(kicad_pcb
	(version 20260206)
	(generator "pcbnew")
	(generator_version "10.0")
	(general
		(thickness 1.6)
		(legacy_teardrops no)
	)
	(paper "A4")
	(layers
		(0 "F.Cu" signal "TOP")
		(4 "In1.Cu" signal "GND")
		(6 "In2.Cu" signal "IN1")
		(8 "In3.Cu" signal "GND1")
		(10 "In4.Cu" signal "IN2")
		(12 "In5.Cu" signal "GND2")
		(14 "In6.Cu" signal "IN3")
		(16 "In7.Cu" signal "GND3")
		(18 "In8.Cu" signal "VCC")
		(20 "In9.Cu" signal "VCC1")
		(22 "In10.Cu" signal "GND4")
		(24 "In11.Cu" signal "IN4")
		(26 "In12.Cu" signal "GND5")
		(28 "In13.Cu" signal "IN5")
		(30 "In14.Cu" signal "GND6")
		(32 "In15.Cu" signal "IN6")
		(34 "In16.Cu" signal "GND7")
		(2 "B.Cu" signal "BOTTOM")
		(9 "F.Adhes" user "F.Adhesive")
		(11 "B.Adhes" user "B.Adhesive")
		(13 "F.Paste" user "Package Geometry/Pastemask Top")
		(15 "B.Paste" user "Package Geometry/Pastemask Bottom")
		(5 "F.SilkS" user "Ref Des/Silkscreen Top")
		(7 "B.SilkS" user "Ref Des/Silkscreen Bottom")
		(1 "F.Mask" user "Board Geometry/Soldermask Top")
		(3 "B.Mask" user "Board Geometry/Soldermask Bottom")
		(17 "Dwgs.User" user "User.Drawings")
		(19 "Cmts.User" user "User.Comments")
		(21 "Eco1.User" user "User.Eco1")
		(23 "Eco2.User" user "User.Eco2")
		(25 "Edge.Cuts" user "Board Geometry/Outline")
		(27 "Margin" user)
		(31 "F.CrtYd" user "Package Geometry/Place Bound Top")
		(29 "B.CrtYd" user "Package Geometry/Place Bound Bottom")
		(35 "F.Fab" user "Ref Des/Assembly Top")
		(33 "B.Fab" user "Ref Des/Assembly Bottom")
	)
	(setup
		(pad_to_mask_clearance 0)
		(allow_soldermask_bridges_in_footprints no)
		(tenting
			(front yes)
			(back yes)
		)
		(covering
			(front no)
			(back no)
		)
		(plugging
			(front no)
			(back no)
		)
		(capping no)
		(filling no)
		(pcbplotparams
			(layerselection 0x00000000_00000000_55555555_5755f5ff)
			(plot_on_all_layers_selection 0x00000000_00000000_00000000_00000000)
			(disableapertmacros no)
			(usegerberextensions no)
			(usegerberattributes yes)
			(usegerberadvancedattributes yes)
			(creategerberjobfile yes)
			(dashed_line_dash_ratio 12)
			(dashed_line_gap_ratio 3)
			(svgprecision 4)
			(plotframeref no)
			(mode 1)
			(useauxorigin no)
			(pdf_front_fp_property_popups yes)
			(pdf_back_fp_property_popups yes)
			(pdf_metadata yes)
			(pdf_single_document no)
			(dxfpolygonmode yes)
			(dxfimperialunits yes)
			(dxfusepcbnewfont yes)
			(psnegative no)
			(psa4output no)
			(plot_black_and_white yes)
			(sketchpadsonfab no)
			(plotpadnumbers no)
			(hidednponfab no)
			(sketchdnponfab yes)
			(crossoutdnponfab yes)
			(subtractmaskfromsilk no)
			(outputformat 1)
			(mirror no)
			(drillshape 1)
			(scaleselection 1)
			(outputdirectory "")
		)
	)
	(segment
		(start 390.515602 -223.120712)
		(end 390.548114 -223.101916)
		(width 0.0889)
		(layer "In4.Cu")
		(net "M_J_CPU0_SA_DQ<3>")
	)
	(segment
		(start 407.813764 -199.991726)
		(end 408.042364 -199.991726)
		(width 0.14478)
		(layer "In4.Cu")
		(net "M_J_CPU0_SA_DQ<3>")
	)
	(segment
		(start 407.61158 -201.121518)
		(end 407.84018 -201.121518)
		(width 0.14478)
		(layer "In4.Cu")
		(net "M_J_CPU0_SA_DQ<3>")
	)
	(segment
		(start 429.915828 -199.450452)
		(end 434.565552 -199.450452)
		(width 0.14478)
		(layer "In4.Cu")
		(net "M_J_CPU0_SA_DQ<3>")
	)
	(segment
		(start 383.393442 -226.33686)
		(end 383.401824 -226.341686)
		(width 0.0889)
		(layer "In4.Cu")
		(net "M_J_CPU0_SA_DQ<3>")
	)
	(segment
		(start 407.221436 -201.740262)
		(end 407.221436 -201.511662)
		(width 0.14478)
		(layer "In4.Cu")
		(net "M_J_CPU0_SA_DQ<3>")
	)
	(segment
		(start 388.667752 -226.341686)
		(end 388.706868 -226.318826)
		(width 0.0889)
		(layer "In4.Cu")
		(net "M_J_CPU0_SA_DQ<3>")
	)
	(segment
		(start 406.441148 -202.65517)
		(end 406.441148 -202.29195)
		(width 0.14478)
		(layer "In4.Cu")
		(net "M_J_CPU0_SA_DQ<3>")
	)
	(segment
		(start 407.033476 -200.772014)
		(end 407.262076 -200.772014)
		(width 0.14478)
		(layer "In4.Cu")
		(net "M_J_CPU0_SA_DQ<3>")
	)
	(segment
		(start 406.091644 -201.942446)
		(end 406.091644 -201.713846)
		(width 0.14478)
		(layer "In4.Cu")
		(net "M_J_CPU0_SA_DQ<3>")
	)
	(segment
		(start 407.65222 -200.15327)
		(end 407.813764 -199.991726)
		(width 0.14478)
		(layer "In4.Cu")
		(net "M_J_CPU0_SA_DQ<3>")
	)
	(segment
		(start 406.091644 -201.713846)
		(end 406.253188 -201.552302)
		(width 0.14478)
		(layer "In4.Cu")
		(net "M_J_CPU0_SA_DQ<3>")
	)
	(segment
		(start 390.045448 -223.930718)
		(end 390.078214 -223.911668)
		(width 0.0889)
		(layer "In4.Cu")
		(net "M_J_CPU0_SA_DQ<3>")
	)
	(segment
		(start 391.301224 -221.537022)
		(end 391.420096 -221.41815)
		(width 0.0889)
		(layer "In4.Cu")
		(net "M_J_CPU0_SA_DQ<3>")
	)
	(segment
		(start 407.262076 -200.772014)
		(end 407.61158 -201.121518)
		(width 0.14478)
		(layer "In4.Cu")
		(net "M_J_CPU0_SA_DQ<3>")
	)
	(segment
		(start 407.221436 -201.511662)
		(end 406.871932 -201.162158)
		(width 0.14478)
		(layer "In4.Cu")
		(net "M_J_CPU0_SA_DQ<3>")
	)
	(segment
		(start 391.420096 -217.676222)
		(end 406.441148 -202.65517)
		(width 0.14478)
		(layer "In4.Cu")
		(net "M_J_CPU0_SA_DQ<3>")
	)
	(segment
		(start 414.30194 -200.014332)
		(end 414.856168 -199.460104)
		(width 0.14478)
		(layer "In4.Cu")
		(net "M_J_CPU0_SA_DQ<3>")
	)
	(segment
		(start 434.565552 -199.450452)
		(end 435.000146 -199.885046)
		(width 0.14478)
		(layer "In4.Cu")
		(net "M_J_CPU0_SA_DQ<3>")
	)
	(segment
		(start 408.042364 -199.991726)
		(end 408.391868 -200.34123)
		(width 0.14478)
		(layer "In4.Cu")
		(net "M_J_CPU0_SA_DQ<3>")
	)
	(segment
		(start 406.871932 -201.162158)
		(end 406.871932 -200.933558)
		(width 0.14478)
		(layer "In4.Cu")
		(net "M_J_CPU0_SA_DQ<3>")
	)
	(segment
		(start 384.333496 -226.33686)
		(end 384.341878 -226.341686)
		(width 0.0889)
		(layer "In4.Cu")
		(net "M_J_CPU0_SA_DQ<3>")
	)
	(segment
		(start 391.018014 -222.29191)
		(end 391.058908 -222.268288)
		(width 0.0889)
		(layer "In4.Cu")
		(net "M_J_CPU0_SA_DQ<3>")
	)
	(segment
		(start 379.63348 -226.33686)
		(end 379.641862 -226.341686)
		(width 0.0889)
		(layer "In4.Cu")
		(net "M_J_CPU0_SA_DQ<3>")
	)
	(segment
		(start 391.301224 -221.80423)
		(end 391.301224 -221.537022)
		(width 0.0889)
		(layer "In4.Cu")
		(net "M_J_CPU0_SA_DQ<3>")
	)
	(segment
		(start 381.147828 -226.341686)
		(end 381.15621 -226.33686)
		(width 0.0889)
		(layer "In4.Cu")
		(net "M_J_CPU0_SA_DQ<3>")
	)
	(segment
		(start 388.093458 -226.33686)
		(end 388.10184 -226.341686)
		(width 0.0889)
		(layer "In4.Cu")
		(net "M_J_CPU0_SA_DQ<3>")
	)
	(segment
		(start 421.346376 -200.300336)
		(end 422.19626 -199.450452)
		(width 0.14478)
		(layer "In4.Cu")
		(net "M_J_CPU0_SA_DQ<3>")
	)
	(segment
		(start 426.914564 -200.30059)
		(end 429.06569 -200.30059)
		(width 0.14478)
		(layer "In4.Cu")
		(net "M_J_CPU0_SA_DQ<3>")
	)
	(segment
		(start 407.059892 -201.901806)
		(end 407.221436 -201.740262)
		(width 0.14478)
		(layer "In4.Cu")
		(net "M_J_CPU0_SA_DQ<3>")
	)
	(segment
		(start 414.856168 -199.460104)
		(end 418.13988 -199.460104)
		(width 0.14478)
		(layer "In4.Cu")
		(net "M_J_CPU0_SA_DQ<3>")
	)
	(segment
		(start 390.078214 -223.911668)
		(end 390.113012 -223.891348)
		(width 0.0889)
		(layer "In4.Cu")
		(net "M_J_CPU0_SA_DQ<3>")
	)
	(segment
		(start 406.441148 -202.29195)
		(end 406.091644 -201.942446)
		(width 0.14478)
		(layer "In4.Cu")
		(net "M_J_CPU0_SA_DQ<3>")
	)
	(segment
		(start 426.064426 -199.450452)
		(end 426.914564 -200.30059)
		(width 0.14478)
		(layer "In4.Cu")
		(net "M_J_CPU0_SA_DQ<3>")
	)
	(segment
		(start 389.137906 -225.53168)
		(end 389.174228 -225.510598)
		(width 0.0889)
		(layer "In4.Cu")
		(net "M_J_CPU0_SA_DQ<3>")
	)
	(segment
		(start 422.19626 -199.450452)
		(end 426.064426 -199.450452)
		(width 0.14478)
		(layer "In4.Cu")
		(net "M_J_CPU0_SA_DQ<3>")
	)
	(segment
		(start 390.987788 -222.309436)
		(end 391.018014 -222.29191)
		(width 0.0889)
		(layer "In4.Cu")
		(net "M_J_CPU0_SA_DQ<3>")
	)
	(segment
		(start 408.391868 -200.34123)
		(end 408.620468 -200.34123)
		(width 0.14478)
		(layer "In4.Cu")
		(net "M_J_CPU0_SA_DQ<3>")
	)
	(segment
		(start 418.980112 -200.300336)
		(end 421.346376 -200.300336)
		(width 0.14478)
		(layer "In4.Cu")
		(net "M_J_CPU0_SA_DQ<3>")
	)
	(segment
		(start 408.001724 -200.731374)
		(end 407.65222 -200.38187)
		(width 0.14478)
		(layer "In4.Cu")
		(net "M_J_CPU0_SA_DQ<3>")
	)
	(segment
		(start 406.871932 -200.933558)
		(end 407.033476 -200.772014)
		(width 0.14478)
		(layer "In4.Cu")
		(net "M_J_CPU0_SA_DQ<3>")
	)
	(segment
		(start 389.106156 -225.549968)
		(end 389.137906 -225.53168)
		(width 0.0889)
		(layer "In4.Cu")
		(net "M_J_CPU0_SA_DQ<3>")
	)
	(segment
		(start 408.620468 -200.34123)
		(end 408.947366 -200.014332)
		(width 0.14478)
		(layer "In4.Cu")
		(net "M_J_CPU0_SA_DQ<3>")
	)
	(segment
		(start 406.253188 -201.552302)
		(end 406.481788 -201.552302)
		(width 0.14478)
		(layer "In4.Cu")
		(net "M_J_CPU0_SA_DQ<3>")
	)
	(segment
		(start 379.454918 -226.664266)
		(end 379.30074 -226.398836)
		(width 0.0889)
		(layer "In4.Cu")
		(net "M_J_CPU0_SA_DQ<3>")
	)
	(segment
		(start 406.481788 -201.552302)
		(end 406.831292 -201.901806)
		(width 0.14478)
		(layer "In4.Cu")
		(net "M_J_CPU0_SA_DQ<3>")
	)
	(segment
		(start 379.30074 -226.398836)
		(end 379.323092 -226.315524)
		(width 0.0889)
		(layer "In4.Cu")
		(net "M_J_CPU0_SA_DQ<3>")
	)
	(segment
		(start 418.13988 -199.460104)
		(end 418.980112 -200.300336)
		(width 0.14478)
		(layer "In4.Cu")
		(net "M_J_CPU0_SA_DQ<3>")
	)
	(segment
		(start 391.420096 -221.23527)
		(end 391.420096 -217.676222)
		(width 0.14478)
		(layer "In4.Cu")
		(net "M_J_CPU0_SA_DQ<3>")
	)
	(segment
		(start 389.576056 -224.739962)
		(end 389.607806 -224.721674)
		(width 0.0889)
		(layer "In4.Cu")
		(net "M_J_CPU0_SA_DQ<3>")
	)
	(segment
		(start 407.84018 -201.121518)
		(end 408.001724 -200.959974)
		(width 0.14478)
		(layer "In4.Cu")
		(net "M_J_CPU0_SA_DQ<3>")
	)
	(segment
		(start 390.548114 -223.101916)
		(end 390.581642 -223.082358)
		(width 0.0889)
		(layer "In4.Cu")
		(net "M_J_CPU0_SA_DQ<3>")
	)
	(segment
		(start 380.207774 -226.341686)
		(end 380.216156 -226.33686)
		(width 0.0889)
		(layer "In4.Cu")
		(net "M_J_CPU0_SA_DQ<3>")
	)
	(segment
		(start 407.65222 -200.38187)
		(end 407.65222 -200.15327)
		(width 0.14478)
		(layer "In4.Cu")
		(net "M_J_CPU0_SA_DQ<3>")
	)
	(segment
		(start 384.90779 -226.341686)
		(end 384.916172 -226.33686)
		(width 0.0889)
		(layer "In4.Cu")
		(net "M_J_CPU0_SA_DQ<3>")
	)
	(segment
		(start 389.607806 -224.721674)
		(end 389.646922 -224.698814)
		(width 0.0889)
		(layer "In4.Cu")
		(net "M_J_CPU0_SA_DQ<3>")
	)
	(segment
		(start 406.831292 -201.901806)
		(end 407.059892 -201.901806)
		(width 0.14478)
		(layer "In4.Cu")
		(net "M_J_CPU0_SA_DQ<3>")
	)
	(segment
		(start 385.847844 -226.341686)
		(end 385.856226 -226.33686)
		(width 0.0889)
		(layer "In4.Cu")
		(net "M_J_CPU0_SA_DQ<3>")
	)
	(segment
		(start 391.420096 -221.41815)
		(end 391.420096 -221.23527)
		(width 0.0889)
		(layer "In4.Cu")
		(net "M_J_CPU0_SA_DQ<3>")
	)
	(arc
		(start 388.9502 -225.85426)
		(mid 388.991455 -225.683289)
		(end 389.106156 -225.549968)
		(width 0.0889)
		(layer "In4.Cu")
		(net "M_J_CPU0_SA_DQ<3>")
	)
	(arc
		(start 386.787898 -226.341686)
		(mid 386.974842 -226.291431)
		(end 387.161786 -226.341686)
		(width 0.0889)
		(layer "In4.Cu")
		(net "M_J_CPU0_SA_DQ<3>")
	)
	(arc
		(start 381.15621 -226.33686)
		(mid 381.339718 -226.291366)
		(end 381.52197 -226.341686)
		(width 0.0889)
		(layer "In4.Cu")
		(net "M_J_CPU0_SA_DQ<3>")
	)
	(arc
		(start 379.641862 -226.341686)
		(mid 379.924818 -226.417863)
		(end 380.207774 -226.341686)
		(width 0.0889)
		(layer "In4.Cu")
		(net "M_J_CPU0_SA_DQ<3>")
	)
	(arc
		(start 380.216156 -226.33686)
		(mid 380.399664 -226.291366)
		(end 380.581916 -226.341686)
		(width 0.0889)
		(layer "In4.Cu")
		(net "M_J_CPU0_SA_DQ<3>")
	)
	(arc
		(start 380.581916 -226.341686)
		(mid 380.864872 -226.417863)
		(end 381.147828 -226.341686)
		(width 0.0889)
		(layer "In4.Cu")
		(net "M_J_CPU0_SA_DQ<3>")
	)
	(arc
		(start 386.221986 -226.341686)
		(mid 386.504942 -226.417863)
		(end 386.787898 -226.341686)
		(width 0.0889)
		(layer "In4.Cu")
		(net "M_J_CPU0_SA_DQ<3>")
	)
	(arc
		(start 390.360408 -223.424242)
		(mid 390.401458 -223.253792)
		(end 390.515602 -223.120712)
		(width 0.0889)
		(layer "In4.Cu")
		(net "M_J_CPU0_SA_DQ<3>")
	)
	(arc
		(start 389.646922 -224.698814)
		(mid 389.825735 -224.496464)
		(end 389.890254 -224.234248)
		(width 0.0889)
		(layer "In4.Cu")
		(net "M_J_CPU0_SA_DQ<3>")
	)
	(arc
		(start 381.52197 -226.341686)
		(mid 381.804926 -226.417863)
		(end 382.087882 -226.341686)
		(width 0.0889)
		(layer "In4.Cu")
		(net "M_J_CPU0_SA_DQ<3>")
	)
	(arc
		(start 382.46177 -226.341686)
		(mid 382.744726 -226.417863)
		(end 383.027682 -226.341686)
		(width 0.0889)
		(layer "In4.Cu")
		(net "M_J_CPU0_SA_DQ<3>")
	)
	(arc
		(start 382.087882 -226.341686)
		(mid 382.274826 -226.291431)
		(end 382.46177 -226.341686)
		(width 0.0889)
		(layer "In4.Cu")
		(net "M_J_CPU0_SA_DQ<3>")
	)
	(arc
		(start 384.341878 -226.341686)
		(mid 384.624834 -226.417863)
		(end 384.90779 -226.341686)
		(width 0.0889)
		(layer "In4.Cu")
		(net "M_J_CPU0_SA_DQ<3>")
	)
	(arc
		(start 390.830562 -222.614236)
		(mid 390.872178 -222.442747)
		(end 390.987788 -222.309436)
		(width 0.0889)
		(layer "In4.Cu")
		(net "M_J_CPU0_SA_DQ<3>")
	)
	(arc
		(start 385.856226 -226.33686)
		(mid 386.039734 -226.291366)
		(end 386.221986 -226.341686)
		(width 0.0889)
		(layer "In4.Cu")
		(net "M_J_CPU0_SA_DQ<3>")
	)
	(arc
		(start 383.967736 -226.341686)
		(mid 384.149987 -226.291336)
		(end 384.333496 -226.33686)
		(width 0.0889)
		(layer "In4.Cu")
		(net "M_J_CPU0_SA_DQ<3>")
	)
	(arc
		(start 388.706868 -226.318826)
		(mid 388.885681 -226.116476)
		(end 388.9502 -225.85426)
		(width 0.0889)
		(layer "In4.Cu")
		(net "M_J_CPU0_SA_DQ<3>")
	)
	(arc
		(start 387.727698 -226.341686)
		(mid 387.909949 -226.291336)
		(end 388.093458 -226.33686)
		(width 0.0889)
		(layer "In4.Cu")
		(net "M_J_CPU0_SA_DQ<3>")
	)
	(arc
		(start 385.281932 -226.341686)
		(mid 385.564888 -226.417863)
		(end 385.847844 -226.341686)
		(width 0.0889)
		(layer "In4.Cu")
		(net "M_J_CPU0_SA_DQ<3>")
	)
	(arc
		(start 391.058908 -222.268288)
		(mid 391.237032 -222.065998)
		(end 391.301224 -221.80423)
		(width 0.0889)
		(layer "In4.Cu")
		(net "M_J_CPU0_SA_DQ<3>")
	)
	(arc
		(start 388.10184 -226.341686)
		(mid 388.384796 -226.417863)
		(end 388.667752 -226.341686)
		(width 0.0889)
		(layer "In4.Cu")
		(net "M_J_CPU0_SA_DQ<3>")
	)
	(arc
		(start 379.323092 -226.315524)
		(mid 379.480602 -226.292326)
		(end 379.63348 -226.33686)
		(width 0.0889)
		(layer "In4.Cu")
		(net "M_J_CPU0_SA_DQ<3>")
	)
	(arc
		(start 390.581642 -223.082358)
		(mid 390.764462 -222.87933)
		(end 390.830562 -222.614236)
		(width 0.0889)
		(layer "In4.Cu")
		(net "M_J_CPU0_SA_DQ<3>")
	)
	(arc
		(start 389.890254 -224.234248)
		(mid 389.931304 -224.063798)
		(end 390.045448 -223.930718)
		(width 0.0889)
		(layer "In4.Cu")
		(net "M_J_CPU0_SA_DQ<3>")
	)
	(arc
		(start 389.174228 -225.510598)
		(mid 389.35488 -225.307853)
		(end 389.4201 -225.044254)
		(width 0.0889)
		(layer "In4.Cu")
		(net "M_J_CPU0_SA_DQ<3>")
	)
	(arc
		(start 390.113012 -223.891348)
		(mid 390.294748 -223.688533)
		(end 390.360408 -223.424242)
		(width 0.0889)
		(layer "In4.Cu")
		(net "M_J_CPU0_SA_DQ<3>")
	)
	(arc
		(start 384.916172 -226.33686)
		(mid 385.09968 -226.291366)
		(end 385.281932 -226.341686)
		(width 0.0889)
		(layer "In4.Cu")
		(net "M_J_CPU0_SA_DQ<3>")
	)
	(arc
		(start 383.401824 -226.341686)
		(mid 383.68478 -226.417863)
		(end 383.967736 -226.341686)
		(width 0.0889)
		(layer "In4.Cu")
		(net "M_J_CPU0_SA_DQ<3>")
	)
	(arc
		(start 383.027682 -226.341686)
		(mid 383.209933 -226.291336)
		(end 383.393442 -226.33686)
		(width 0.0889)
		(layer "In4.Cu")
		(net "M_J_CPU0_SA_DQ<3>")
	)
	(arc
		(start 387.161786 -226.341686)
		(mid 387.444742 -226.417863)
		(end 387.727698 -226.341686)
		(width 0.0889)
		(layer "In4.Cu")
		(net "M_J_CPU0_SA_DQ<3>")
	)
	(arc
		(start 389.4201 -225.044254)
		(mid 389.461355 -224.873283)
		(end 389.576056 -224.739962)
		(width 0.0889)
		(layer "In4.Cu")
		(net "M_J_CPU0_SA_DQ<3>")
	)
	(segment
		(start 378.988066 -244.750082)
		(end 379.454918 -244.484144)
		(width 0.10668)
		(layer "F.Cu")
		(net "M_J_CPU0_SA_DQ<31>")
	)
	(segment
		(start 406.61209 -239.19434)
		(end 406.84069 -239.19434)
		(width 0.14478)
		(layer "In4.Cu")
		(net "M_J_CPU0_SA_DQ<31>")
	)
	(segment
		(start 410.123386 -235.911644)
		(end 410.123386 -235.683044)
		(width 0.14478)
		(layer "In4.Cu")
		(net "M_J_CPU0_SA_DQ<31>")
	)
	(segment
		(start 409.181554 -236.853476)
		(end 409.343098 -236.691932)
		(width 0.14478)
		(layer "In4.Cu")
		(net "M_J_CPU0_SA_DQ<31>")
	)
	(segment
		(start 407.741882 -237.43158)
		(end 407.970482 -237.43158)
		(width 0.14478)
		(layer "In4.Cu")
		(net "M_J_CPU0_SA_DQ<31>")
	)
	(segment
		(start 418.551106 -234.310428)
		(end 421.602662 -234.310428)
		(width 0.14478)
		(layer "In4.Cu")
		(net "M_J_CPU0_SA_DQ<31>")
	)
	(segment
		(start 407.580338 -237.593124)
		(end 407.741882 -237.43158)
		(width 0.14478)
		(layer "In4.Cu")
		(net "M_J_CPU0_SA_DQ<31>")
	)
	(segment
		(start 409.302458 -235.871004)
		(end 409.531058 -235.871004)
		(width 0.14478)
		(layer "In4.Cu")
		(net "M_J_CPU0_SA_DQ<31>")
	)
	(segment
		(start 407.782522 -238.252508)
		(end 407.782522 -238.023908)
		(width 0.14478)
		(layer "In4.Cu")
		(net "M_J_CPU0_SA_DQ<31>")
	)
	(segment
		(start 407.970482 -237.43158)
		(end 408.172666 -237.633764)
		(width 0.14478)
		(layer "In4.Cu")
		(net "M_J_CPU0_SA_DQ<31>")
	)
	(segment
		(start 410.903674 -235.131356)
		(end 410.903674 -234.902756)
		(width 0.14478)
		(layer "In4.Cu")
		(net "M_J_CPU0_SA_DQ<31>")
	)
	(segment
		(start 384.333496 -244.156738)
		(end 384.341878 -244.161564)
		(width 0.0889)
		(layer "In4.Cu")
		(net "M_J_CPU0_SA_DQ<31>")
	)
	(segment
		(start 392.413998 -244.1702)
		(end 392.42873 -244.161564)
		(width 0.0889)
		(layer "In4.Cu")
		(net "M_J_CPU0_SA_DQ<31>")
	)
	(segment
		(start 383.393442 -244.156738)
		(end 383.401824 -244.161564)
		(width 0.0889)
		(layer "In4.Cu")
		(net "M_J_CPU0_SA_DQ<31>")
	)
	(segment
		(start 410.51353 -235.2929)
		(end 410.74213 -235.2929)
		(width 0.14478)
		(layer "In4.Cu")
		(net "M_J_CPU0_SA_DQ<31>")
	)
	(segment
		(start 409.921202 -235.25226)
		(end 410.082746 -235.090716)
		(width 0.14478)
		(layer "In4.Cu")
		(net "M_J_CPU0_SA_DQ<31>")
	)
	(segment
		(start 393.084812 -244.238018)
		(end 394.114528 -244.238018)
		(width 0.0889)
		(layer "In4.Cu")
		(net "M_J_CPU0_SA_DQ<31>")
	)
	(segment
		(start 379.30074 -244.218714)
		(end 379.323092 -244.135402)
		(width 0.0889)
		(layer "In4.Cu")
		(net "M_J_CPU0_SA_DQ<31>")
	)
	(segment
		(start 410.70149 -234.700572)
		(end 410.70149 -234.471972)
		(width 0.14478)
		(layer "In4.Cu")
		(net "M_J_CPU0_SA_DQ<31>")
	)
	(segment
		(start 401.734782 -243.43868)
		(end 406.181306 -238.992156)
		(width 0.14478)
		(layer "In4.Cu")
		(net "M_J_CPU0_SA_DQ<31>")
	)
	(segment
		(start 430.004728 -233.46029)
		(end 434.575458 -233.46029)
		(width 0.14478)
		(layer "In4.Cu")
		(net "M_J_CPU0_SA_DQ<31>")
	)
	(segment
		(start 407.580338 -237.821724)
		(end 407.580338 -237.593124)
		(width 0.14478)
		(layer "In4.Cu")
		(net "M_J_CPU0_SA_DQ<31>")
	)
	(segment
		(start 406.961594 -238.211868)
		(end 407.190194 -238.211868)
		(width 0.14478)
		(layer "In4.Cu")
		(net "M_J_CPU0_SA_DQ<31>")
	)
	(segment
		(start 384.90779 -244.161564)
		(end 384.916172 -244.156738)
		(width 0.0889)
		(layer "In4.Cu")
		(net "M_J_CPU0_SA_DQ<31>")
	)
	(segment
		(start 407.190194 -238.211868)
		(end 407.392378 -238.414052)
		(width 0.14478)
		(layer "In4.Cu")
		(net "M_J_CPU0_SA_DQ<31>")
	)
	(segment
		(start 410.863034 -234.310428)
		(end 414.509204 -234.310428)
		(width 0.14478)
		(layer "In4.Cu")
		(net "M_J_CPU0_SA_DQ<31>")
	)
	(segment
		(start 379.63348 -244.156738)
		(end 379.641862 -244.161564)
		(width 0.0889)
		(layer "In4.Cu")
		(net "M_J_CPU0_SA_DQ<31>")
	)
	(segment
		(start 409.733242 -236.073188)
		(end 409.961842 -236.073188)
		(width 0.14478)
		(layer "In4.Cu")
		(net "M_J_CPU0_SA_DQ<31>")
	)
	(segment
		(start 408.52217 -236.651292)
		(end 408.75077 -236.651292)
		(width 0.14478)
		(layer "In4.Cu")
		(net "M_J_CPU0_SA_DQ<31>")
	)
	(segment
		(start 407.002234 -239.032796)
		(end 407.002234 -238.804196)
		(width 0.14478)
		(layer "In4.Cu")
		(net "M_J_CPU0_SA_DQ<31>")
	)
	(segment
		(start 410.311346 -235.090716)
		(end 410.51353 -235.2929)
		(width 0.14478)
		(layer "In4.Cu")
		(net "M_J_CPU0_SA_DQ<31>")
	)
	(segment
		(start 426.533564 -234.310428)
		(end 429.15459 -234.310428)
		(width 0.14478)
		(layer "In4.Cu")
		(net "M_J_CPU0_SA_DQ<31>")
	)
	(segment
		(start 388.093458 -244.156738)
		(end 388.10184 -244.161564)
		(width 0.0889)
		(layer "In4.Cu")
		(net "M_J_CPU0_SA_DQ<31>")
	)
	(segment
		(start 408.56281 -237.47222)
		(end 408.56281 -237.24362)
		(width 0.14478)
		(layer "In4.Cu")
		(net "M_J_CPU0_SA_DQ<31>")
	)
	(segment
		(start 394.910056 -244.10035)
		(end 395.571726 -243.43868)
		(width 0.0889)
		(layer "In4.Cu")
		(net "M_J_CPU0_SA_DQ<31>")
	)
	(segment
		(start 408.952954 -236.853476)
		(end 409.181554 -236.853476)
		(width 0.14478)
		(layer "In4.Cu")
		(net "M_J_CPU0_SA_DQ<31>")
	)
	(segment
		(start 395.571726 -243.43868)
		(end 395.860778 -243.43868)
		(width 0.0889)
		(layer "In4.Cu")
		(net "M_J_CPU0_SA_DQ<31>")
	)
	(segment
		(start 406.80005 -238.602012)
		(end 406.80005 -238.373412)
		(width 0.14478)
		(layer "In4.Cu")
		(net "M_J_CPU0_SA_DQ<31>")
	)
	(segment
		(start 408.75077 -236.651292)
		(end 408.952954 -236.853476)
		(width 0.14478)
		(layer "In4.Cu")
		(net "M_J_CPU0_SA_DQ<31>")
	)
	(segment
		(start 408.56281 -237.24362)
		(end 408.360626 -237.041436)
		(width 0.14478)
		(layer "In4.Cu")
		(net "M_J_CPU0_SA_DQ<31>")
	)
	(segment
		(start 408.401266 -237.633764)
		(end 408.56281 -237.47222)
		(width 0.14478)
		(layer "In4.Cu")
		(net "M_J_CPU0_SA_DQ<31>")
	)
	(segment
		(start 409.343098 -236.463332)
		(end 409.140914 -236.261148)
		(width 0.14478)
		(layer "In4.Cu")
		(net "M_J_CPU0_SA_DQ<31>")
	)
	(segment
		(start 409.531058 -235.871004)
		(end 409.733242 -236.073188)
		(width 0.14478)
		(layer "In4.Cu")
		(net "M_J_CPU0_SA_DQ<31>")
	)
	(segment
		(start 434.575458 -233.46029)
		(end 435.000146 -233.884978)
		(width 0.14478)
		(layer "In4.Cu")
		(net "M_J_CPU0_SA_DQ<31>")
	)
	(segment
		(start 406.84069 -239.19434)
		(end 407.002234 -239.032796)
		(width 0.14478)
		(layer "In4.Cu")
		(net "M_J_CPU0_SA_DQ<31>")
	)
	(segment
		(start 408.172666 -237.633764)
		(end 408.401266 -237.633764)
		(width 0.14478)
		(layer "In4.Cu")
		(net "M_J_CPU0_SA_DQ<31>")
	)
	(segment
		(start 417.700968 -233.46029)
		(end 418.551106 -234.310428)
		(width 0.14478)
		(layer "In4.Cu")
		(net "M_J_CPU0_SA_DQ<31>")
	)
	(segment
		(start 422.4528 -233.46029)
		(end 425.683426 -233.46029)
		(width 0.14478)
		(layer "In4.Cu")
		(net "M_J_CPU0_SA_DQ<31>")
	)
	(segment
		(start 407.620978 -238.414052)
		(end 407.782522 -238.252508)
		(width 0.14478)
		(layer "In4.Cu")
		(net "M_J_CPU0_SA_DQ<31>")
	)
	(segment
		(start 410.74213 -235.2929)
		(end 410.903674 -235.131356)
		(width 0.14478)
		(layer "In4.Cu")
		(net "M_J_CPU0_SA_DQ<31>")
	)
	(segment
		(start 409.140914 -236.032548)
		(end 409.302458 -235.871004)
		(width 0.14478)
		(layer "In4.Cu")
		(net "M_J_CPU0_SA_DQ<31>")
	)
	(segment
		(start 394.252196 -244.10035)
		(end 394.910056 -244.10035)
		(width 0.0889)
		(layer "In4.Cu")
		(net "M_J_CPU0_SA_DQ<31>")
	)
	(segment
		(start 410.123386 -235.683044)
		(end 409.921202 -235.48086)
		(width 0.14478)
		(layer "In4.Cu")
		(net "M_J_CPU0_SA_DQ<31>")
	)
	(segment
		(start 379.454918 -244.484144)
		(end 379.30074 -244.218714)
		(width 0.0889)
		(layer "In4.Cu")
		(net "M_J_CPU0_SA_DQ<31>")
	)
	(segment
		(start 385.847844 -244.161564)
		(end 385.856226 -244.156738)
		(width 0.0889)
		(layer "In4.Cu")
		(net "M_J_CPU0_SA_DQ<31>")
	)
	(segment
		(start 380.207774 -244.161564)
		(end 380.216156 -244.156738)
		(width 0.0889)
		(layer "In4.Cu")
		(net "M_J_CPU0_SA_DQ<31>")
	)
	(segment
		(start 409.961842 -236.073188)
		(end 410.123386 -235.911644)
		(width 0.14478)
		(layer "In4.Cu")
		(net "M_J_CPU0_SA_DQ<31>")
	)
	(segment
		(start 429.15459 -234.310428)
		(end 430.004728 -233.46029)
		(width 0.14478)
		(layer "In4.Cu")
		(net "M_J_CPU0_SA_DQ<31>")
	)
	(segment
		(start 389.607806 -244.161564)
		(end 389.616188 -244.156738)
		(width 0.0889)
		(layer "In4.Cu")
		(net "M_J_CPU0_SA_DQ<31>")
	)
	(segment
		(start 409.140914 -236.261148)
		(end 409.140914 -236.032548)
		(width 0.14478)
		(layer "In4.Cu")
		(net "M_J_CPU0_SA_DQ<31>")
	)
	(segment
		(start 410.903674 -234.902756)
		(end 410.70149 -234.700572)
		(width 0.14478)
		(layer "In4.Cu")
		(net "M_J_CPU0_SA_DQ<31>")
	)
	(segment
		(start 414.509204 -234.310428)
		(end 415.359342 -233.46029)
		(width 0.14478)
		(layer "In4.Cu")
		(net "M_J_CPU0_SA_DQ<31>")
	)
	(segment
		(start 389.033512 -244.156738)
		(end 389.041894 -244.161564)
		(width 0.0889)
		(layer "In4.Cu")
		(net "M_J_CPU0_SA_DQ<31>")
	)
	(segment
		(start 406.181306 -238.992156)
		(end 406.409906 -238.992156)
		(width 0.14478)
		(layer "In4.Cu")
		(net "M_J_CPU0_SA_DQ<31>")
	)
	(segment
		(start 407.392378 -238.414052)
		(end 407.620978 -238.414052)
		(width 0.14478)
		(layer "In4.Cu")
		(net "M_J_CPU0_SA_DQ<31>")
	)
	(segment
		(start 408.360626 -236.812836)
		(end 408.52217 -236.651292)
		(width 0.14478)
		(layer "In4.Cu")
		(net "M_J_CPU0_SA_DQ<31>")
	)
	(segment
		(start 406.409906 -238.992156)
		(end 406.61209 -239.19434)
		(width 0.14478)
		(layer "In4.Cu")
		(net "M_J_CPU0_SA_DQ<31>")
	)
	(segment
		(start 415.359342 -233.46029)
		(end 417.700968 -233.46029)
		(width 0.14478)
		(layer "In4.Cu")
		(net "M_J_CPU0_SA_DQ<31>")
	)
	(segment
		(start 406.80005 -238.373412)
		(end 406.961594 -238.211868)
		(width 0.14478)
		(layer "In4.Cu")
		(net "M_J_CPU0_SA_DQ<31>")
	)
	(segment
		(start 395.860778 -243.43868)
		(end 401.734782 -243.43868)
		(width 0.14478)
		(layer "In4.Cu")
		(net "M_J_CPU0_SA_DQ<31>")
	)
	(segment
		(start 410.70149 -234.471972)
		(end 410.863034 -234.310428)
		(width 0.14478)
		(layer "In4.Cu")
		(net "M_J_CPU0_SA_DQ<31>")
	)
	(segment
		(start 421.602662 -234.310428)
		(end 422.4528 -233.46029)
		(width 0.14478)
		(layer "In4.Cu")
		(net "M_J_CPU0_SA_DQ<31>")
	)
	(segment
		(start 407.002234 -238.804196)
		(end 406.80005 -238.602012)
		(width 0.14478)
		(layer "In4.Cu")
		(net "M_J_CPU0_SA_DQ<31>")
	)
	(segment
		(start 425.683426 -233.46029)
		(end 426.533564 -234.310428)
		(width 0.14478)
		(layer "In4.Cu")
		(net "M_J_CPU0_SA_DQ<31>")
	)
	(segment
		(start 381.147828 -244.161564)
		(end 381.15621 -244.156738)
		(width 0.0889)
		(layer "In4.Cu")
		(net "M_J_CPU0_SA_DQ<31>")
	)
	(segment
		(start 408.360626 -237.041436)
		(end 408.360626 -236.812836)
		(width 0.14478)
		(layer "In4.Cu")
		(net "M_J_CPU0_SA_DQ<31>")
	)
	(segment
		(start 391.48766 -244.161564)
		(end 391.496042 -244.156738)
		(width 0.0889)
		(layer "In4.Cu")
		(net "M_J_CPU0_SA_DQ<31>")
	)
	(segment
		(start 407.782522 -238.023908)
		(end 407.580338 -237.821724)
		(width 0.14478)
		(layer "In4.Cu")
		(net "M_J_CPU0_SA_DQ<31>")
	)
	(segment
		(start 394.114528 -244.238018)
		(end 394.252196 -244.10035)
		(width 0.0889)
		(layer "In4.Cu")
		(net "M_J_CPU0_SA_DQ<31>")
	)
	(segment
		(start 409.343098 -236.691932)
		(end 409.343098 -236.463332)
		(width 0.14478)
		(layer "In4.Cu")
		(net "M_J_CPU0_SA_DQ<31>")
	)
	(segment
		(start 410.082746 -235.090716)
		(end 410.311346 -235.090716)
		(width 0.14478)
		(layer "In4.Cu")
		(net "M_J_CPU0_SA_DQ<31>")
	)
	(segment
		(start 409.921202 -235.48086)
		(end 409.921202 -235.25226)
		(width 0.14478)
		(layer "In4.Cu")
		(net "M_J_CPU0_SA_DQ<31>")
	)
	(arc
		(start 380.216156 -244.156738)
		(mid 380.399664 -244.111244)
		(end 380.581916 -244.161564)
		(width 0.0889)
		(layer "In4.Cu")
		(net "M_J_CPU0_SA_DQ<31>")
	)
	(arc
		(start 385.856226 -244.156738)
		(mid 386.039734 -244.111244)
		(end 386.221986 -244.161564)
		(width 0.0889)
		(layer "In4.Cu")
		(net "M_J_CPU0_SA_DQ<31>")
	)
	(arc
		(start 382.087882 -244.161564)
		(mid 382.274826 -244.111309)
		(end 382.46177 -244.161564)
		(width 0.0889)
		(layer "In4.Cu")
		(net "M_J_CPU0_SA_DQ<31>")
	)
	(arc
		(start 387.161786 -244.161564)
		(mid 387.444742 -244.237741)
		(end 387.727698 -244.161564)
		(width 0.0889)
		(layer "In4.Cu")
		(net "M_J_CPU0_SA_DQ<31>")
	)
	(arc
		(start 383.967736 -244.161564)
		(mid 384.149987 -244.111214)
		(end 384.333496 -244.156738)
		(width 0.0889)
		(layer "In4.Cu")
		(net "M_J_CPU0_SA_DQ<31>")
	)
	(arc
		(start 389.981948 -244.161564)
		(mid 390.264904 -244.237741)
		(end 390.54786 -244.161564)
		(width 0.0889)
		(layer "In4.Cu")
		(net "M_J_CPU0_SA_DQ<31>")
	)
	(arc
		(start 386.221986 -244.161564)
		(mid 386.504942 -244.237741)
		(end 386.787898 -244.161564)
		(width 0.0889)
		(layer "In4.Cu")
		(net "M_J_CPU0_SA_DQ<31>")
	)
	(arc
		(start 388.10184 -244.161564)
		(mid 388.384796 -244.237741)
		(end 388.667752 -244.161564)
		(width 0.0889)
		(layer "In4.Cu")
		(net "M_J_CPU0_SA_DQ<31>")
	)
	(arc
		(start 384.916172 -244.156738)
		(mid 385.09968 -244.111244)
		(end 385.281932 -244.161564)
		(width 0.0889)
		(layer "In4.Cu")
		(net "M_J_CPU0_SA_DQ<31>")
	)
	(arc
		(start 392.42873 -244.161564)
		(mid 392.607717 -244.111394)
		(end 392.788648 -244.153944)
		(width 0.0889)
		(layer "In4.Cu")
		(net "M_J_CPU0_SA_DQ<31>")
	)
	(arc
		(start 379.323092 -244.135402)
		(mid 379.480602 -244.112204)
		(end 379.63348 -244.156738)
		(width 0.0889)
		(layer "In4.Cu")
		(net "M_J_CPU0_SA_DQ<31>")
	)
	(arc
		(start 383.401824 -244.161564)
		(mid 383.68478 -244.237741)
		(end 383.967736 -244.161564)
		(width 0.0889)
		(layer "In4.Cu")
		(net "M_J_CPU0_SA_DQ<31>")
	)
	(arc
		(start 388.667752 -244.161564)
		(mid 388.850003 -244.111214)
		(end 389.033512 -244.156738)
		(width 0.0889)
		(layer "In4.Cu")
		(net "M_J_CPU0_SA_DQ<31>")
	)
	(arc
		(start 392.788648 -244.153944)
		(mid 392.930878 -244.216598)
		(end 393.084812 -244.238018)
		(width 0.0889)
		(layer "In4.Cu")
		(net "M_J_CPU0_SA_DQ<31>")
	)
	(arc
		(start 385.281932 -244.161564)
		(mid 385.564888 -244.237741)
		(end 385.847844 -244.161564)
		(width 0.0889)
		(layer "In4.Cu")
		(net "M_J_CPU0_SA_DQ<31>")
	)
	(arc
		(start 379.641862 -244.161564)
		(mid 379.924818 -244.237741)
		(end 380.207774 -244.161564)
		(width 0.0889)
		(layer "In4.Cu")
		(net "M_J_CPU0_SA_DQ<31>")
	)
	(arc
		(start 383.027682 -244.161564)
		(mid 383.209933 -244.111214)
		(end 383.393442 -244.156738)
		(width 0.0889)
		(layer "In4.Cu")
		(net "M_J_CPU0_SA_DQ<31>")
	)
	(arc
		(start 389.616188 -244.156738)
		(mid 389.799696 -244.111244)
		(end 389.981948 -244.161564)
		(width 0.0889)
		(layer "In4.Cu")
		(net "M_J_CPU0_SA_DQ<31>")
	)
	(arc
		(start 381.52197 -244.161564)
		(mid 381.804926 -244.237741)
		(end 382.087882 -244.161564)
		(width 0.0889)
		(layer "In4.Cu")
		(net "M_J_CPU0_SA_DQ<31>")
	)
	(arc
		(start 391.86231 -244.161564)
		(mid 392.137016 -244.237928)
		(end 392.413998 -244.1702)
		(width 0.0889)
		(layer "In4.Cu")
		(net "M_J_CPU0_SA_DQ<31>")
	)
	(arc
		(start 384.341878 -244.161564)
		(mid 384.624834 -244.237741)
		(end 384.90779 -244.161564)
		(width 0.0889)
		(layer "In4.Cu")
		(net "M_J_CPU0_SA_DQ<31>")
	)
	(arc
		(start 381.15621 -244.156738)
		(mid 381.339718 -244.111244)
		(end 381.52197 -244.161564)
		(width 0.0889)
		(layer "In4.Cu")
		(net "M_J_CPU0_SA_DQ<31>")
	)
	(arc
		(start 382.46177 -244.161564)
		(mid 382.744726 -244.237741)
		(end 383.027682 -244.161564)
		(width 0.0889)
		(layer "In4.Cu")
		(net "M_J_CPU0_SA_DQ<31>")
	)
	(arc
		(start 390.921748 -244.161564)
		(mid 391.204704 -244.237741)
		(end 391.48766 -244.161564)
		(width 0.0889)
		(layer "In4.Cu")
		(net "M_J_CPU0_SA_DQ<31>")
	)
	(arc
		(start 389.041894 -244.161564)
		(mid 389.32485 -244.237741)
		(end 389.607806 -244.161564)
		(width 0.0889)
		(layer "In4.Cu")
		(net "M_J_CPU0_SA_DQ<31>")
	)
	(arc
		(start 380.581916 -244.161564)
		(mid 380.864872 -244.237741)
		(end 381.147828 -244.161564)
		(width 0.0889)
		(layer "In4.Cu")
		(net "M_J_CPU0_SA_DQ<31>")
	)
	(arc
		(start 387.727698 -244.161564)
		(mid 387.909949 -244.111214)
		(end 388.093458 -244.156738)
		(width 0.0889)
		(layer "In4.Cu")
		(net "M_J_CPU0_SA_DQ<31>")
	)
	(arc
		(start 391.496042 -244.156738)
		(mid 391.679804 -244.111122)
		(end 391.86231 -244.161564)
		(width 0.0889)
		(layer "In4.Cu")
		(net "M_J_CPU0_SA_DQ<31>")
	)
	(arc
		(start 390.54786 -244.161564)
		(mid 390.734804 -244.111309)
		(end 390.921748 -244.161564)
		(width 0.0889)
		(layer "In4.Cu")
		(net "M_J_CPU0_SA_DQ<31>")
	)
	(arc
		(start 386.787898 -244.161564)
		(mid 386.974842 -244.111309)
		(end 387.161786 -244.161564)
		(width 0.0889)
		(layer "In4.Cu")
		(net "M_J_CPU0_SA_DQ<31>")
	)
	(segment
		(start 380.39802 -243.940076)
		(end 380.864872 -243.674138)
		(width 0.10668)
		(layer "F.Cu")
		(net "M_J_CPU0_SA_DQ<30>")
	)
	(segment
		(start 404.543768 -239.357662)
		(end 404.705312 -239.196118)
		(width 0.14478)
		(layer "In4.Cu")
		(net "M_J_CPU0_SA_DQ<30>")
	)
	(segment
		(start 403.10816 -239.93983)
		(end 403.33676 -239.93983)
		(width 0.14478)
		(layer "In4.Cu")
		(net "M_J_CPU0_SA_DQ<30>")
	)
	(segment
		(start 388.197852 -243.351558)
		(end 388.206234 -243.346732)
		(width 0.0889)
		(layer "In4.Cu")
		(net "M_J_CPU0_SA_DQ<30>")
	)
	(segment
		(start 404.705312 -238.967518)
		(end 404.507192 -238.769398)
		(width 0.14478)
		(layer "In4.Cu")
		(net "M_J_CPU0_SA_DQ<30>")
	)
	(segment
		(start 404.705312 -239.196118)
		(end 404.705312 -238.967518)
		(width 0.14478)
		(layer "In4.Cu")
		(net "M_J_CPU0_SA_DQ<30>")
	)
	(segment
		(start 382.557782 -243.351558)
		(end 382.566164 -243.346732)
		(width 0.0889)
		(layer "In4.Cu")
		(net "M_J_CPU0_SA_DQ<30>")
	)
	(segment
		(start 406.884632 -237.016798)
		(end 411.291024 -232.610406)
		(width 0.14478)
		(layer "In4.Cu")
		(net "M_J_CPU0_SA_DQ<30>")
	)
	(segment
		(start 401.58416 -242.08867)
		(end 401.38604 -241.89055)
		(width 0.14478)
		(layer "In4.Cu")
		(net "M_J_CPU0_SA_DQ<30>")
	)
	(segment
		(start 422.287192 -231.760268)
		(end 425.472098 -231.760268)
		(width 0.14478)
		(layer "In4.Cu")
		(net "M_J_CPU0_SA_DQ<30>")
	)
	(segment
		(start 402.364448 -241.536982)
		(end 402.364448 -241.308382)
		(width 0.14478)
		(layer "In4.Cu")
		(net "M_J_CPU0_SA_DQ<30>")
	)
	(segment
		(start 395.166596 -242.892834)
		(end 395.53515 -242.52428)
		(width 0.0889)
		(layer "In4.Cu")
		(net "M_J_CPU0_SA_DQ<30>")
	)
	(segment
		(start 404.507192 -238.769398)
		(end 404.507192 -238.540798)
		(width 0.14478)
		(layer "In4.Cu")
		(net "M_J_CPU0_SA_DQ<30>")
	)
	(segment
		(start 402.983192 -240.918238)
		(end 403.144736 -240.756694)
		(width 0.14478)
		(layer "In4.Cu")
		(net "M_J_CPU0_SA_DQ<30>")
	)
	(segment
		(start 404.117048 -239.159542)
		(end 404.315168 -239.357662)
		(width 0.14478)
		(layer "In4.Cu")
		(net "M_J_CPU0_SA_DQ<30>")
	)
	(segment
		(start 394.152628 -243.300758)
		(end 394.34516 -243.49329)
		(width 0.0889)
		(layer "In4.Cu")
		(net "M_J_CPU0_SA_DQ<30>")
	)
	(segment
		(start 386.683504 -243.346732)
		(end 386.691886 -243.351558)
		(width 0.0889)
		(layer "In4.Cu")
		(net "M_J_CPU0_SA_DQ<30>")
	)
	(segment
		(start 405.324056 -238.577374)
		(end 405.4856 -238.41583)
		(width 0.14478)
		(layer "In4.Cu")
		(net "M_J_CPU0_SA_DQ<30>")
	)
	(segment
		(start 406.265888 -237.635542)
		(end 406.265888 -237.406942)
		(width 0.14478)
		(layer "In4.Cu")
		(net "M_J_CPU0_SA_DQ<30>")
	)
	(segment
		(start 425.472098 -231.760268)
		(end 426.322236 -232.610406)
		(width 0.14478)
		(layer "In4.Cu")
		(net "M_J_CPU0_SA_DQ<30>")
	)
	(segment
		(start 403.925024 -239.747806)
		(end 403.726904 -239.549686)
		(width 0.14478)
		(layer "In4.Cu")
		(net "M_J_CPU0_SA_DQ<30>")
	)
	(segment
		(start 406.656032 -237.016798)
		(end 406.884632 -237.016798)
		(width 0.14478)
		(layer "In4.Cu")
		(net "M_J_CPU0_SA_DQ<30>")
	)
	(segment
		(start 403.925024 -239.976406)
		(end 403.925024 -239.747806)
		(width 0.14478)
		(layer "In4.Cu")
		(net "M_J_CPU0_SA_DQ<30>")
	)
	(segment
		(start 380.864872 -243.674138)
		(end 380.710694 -243.408708)
		(width 0.0889)
		(layer "In4.Cu")
		(net "M_J_CPU0_SA_DQ<30>")
	)
	(segment
		(start 434.575458 -231.760268)
		(end 435.000146 -232.184956)
		(width 0.14478)
		(layer "In4.Cu")
		(net "M_J_CPU0_SA_DQ<30>")
	)
	(segment
		(start 405.28748 -237.98911)
		(end 405.28748 -237.76051)
		(width 0.14478)
		(layer "In4.Cu")
		(net "M_J_CPU0_SA_DQ<30>")
	)
	(segment
		(start 394.34516 -243.49329)
		(end 394.826236 -243.49329)
		(width 0.0889)
		(layer "In4.Cu")
		(net "M_J_CPU0_SA_DQ<30>")
	)
	(segment
		(start 395.166596 -243.15293)
		(end 395.166596 -242.892834)
		(width 0.0889)
		(layer "In4.Cu")
		(net "M_J_CPU0_SA_DQ<30>")
	)
	(segment
		(start 403.144736 -240.528094)
		(end 402.946616 -240.329974)
		(width 0.14478)
		(layer "In4.Cu")
		(net "M_J_CPU0_SA_DQ<30>")
	)
	(segment
		(start 387.257798 -243.351558)
		(end 387.26618 -243.346732)
		(width 0.0889)
		(layer "In4.Cu")
		(net "M_J_CPU0_SA_DQ<30>")
	)
	(segment
		(start 406.104344 -237.797086)
		(end 406.265888 -237.635542)
		(width 0.14478)
		(layer "In4.Cu")
		(net "M_J_CPU0_SA_DQ<30>")
	)
	(segment
		(start 405.875744 -237.797086)
		(end 406.104344 -237.797086)
		(width 0.14478)
		(layer "In4.Cu")
		(net "M_J_CPU0_SA_DQ<30>")
	)
	(segment
		(start 390.443466 -243.346732)
		(end 390.451848 -243.351558)
		(width 0.0889)
		(layer "In4.Cu")
		(net "M_J_CPU0_SA_DQ<30>")
	)
	(segment
		(start 418.379148 -232.610406)
		(end 421.437054 -232.610406)
		(width 0.14478)
		(layer "In4.Cu")
		(net "M_J_CPU0_SA_DQ<30>")
	)
	(segment
		(start 406.067768 -236.980222)
		(end 406.229312 -236.818678)
		(width 0.14478)
		(layer "In4.Cu")
		(net "M_J_CPU0_SA_DQ<30>")
	)
	(segment
		(start 402.946616 -240.101374)
		(end 403.10816 -239.93983)
		(width 0.14478)
		(layer "In4.Cu")
		(net "M_J_CPU0_SA_DQ<30>")
	)
	(segment
		(start 430.183036 -231.760268)
		(end 434.575458 -231.760268)
		(width 0.14478)
		(layer "In4.Cu")
		(net "M_J_CPU0_SA_DQ<30>")
	)
	(segment
		(start 401.547584 -241.500406)
		(end 401.776184 -241.500406)
		(width 0.14478)
		(layer "In4.Cu")
		(net "M_J_CPU0_SA_DQ<30>")
	)
	(segment
		(start 395.53515 -242.52428)
		(end 395.896338 -242.52428)
		(width 0.0889)
		(layer "In4.Cu")
		(net "M_J_CPU0_SA_DQ<30>")
	)
	(segment
		(start 401.38604 -241.66195)
		(end 401.547584 -241.500406)
		(width 0.14478)
		(layer "In4.Cu")
		(net "M_J_CPU0_SA_DQ<30>")
	)
	(segment
		(start 404.507192 -238.540798)
		(end 404.668736 -238.379254)
		(width 0.14478)
		(layer "In4.Cu")
		(net "M_J_CPU0_SA_DQ<30>")
	)
	(segment
		(start 405.4856 -238.18723)
		(end 405.28748 -237.98911)
		(width 0.14478)
		(layer "In4.Cu")
		(net "M_J_CPU0_SA_DQ<30>")
	)
	(segment
		(start 403.726904 -239.549686)
		(end 403.726904 -239.321086)
		(width 0.14478)
		(layer "In4.Cu")
		(net "M_J_CPU0_SA_DQ<30>")
	)
	(segment
		(start 381.983488 -243.346732)
		(end 381.99187 -243.351558)
		(width 0.0889)
		(layer "In4.Cu")
		(net "M_J_CPU0_SA_DQ<30>")
	)
	(segment
		(start 392.324336 -243.346732)
		(end 392.332718 -243.351558)
		(width 0.0889)
		(layer "In4.Cu")
		(net "M_J_CPU0_SA_DQ<30>")
	)
	(segment
		(start 404.668736 -238.379254)
		(end 404.897336 -238.379254)
		(width 0.14478)
		(layer "In4.Cu")
		(net "M_J_CPU0_SA_DQ<30>")
	)
	(segment
		(start 401.776184 -241.500406)
		(end 401.974304 -241.698526)
		(width 0.14478)
		(layer "In4.Cu")
		(net "M_J_CPU0_SA_DQ<30>")
	)
	(segment
		(start 402.754592 -240.918238)
		(end 402.983192 -240.918238)
		(width 0.14478)
		(layer "In4.Cu")
		(net "M_J_CPU0_SA_DQ<30>")
	)
	(segment
		(start 414.922462 -232.610406)
		(end 415.7726 -231.760268)
		(width 0.14478)
		(layer "In4.Cu")
		(net "M_J_CPU0_SA_DQ<30>")
	)
	(segment
		(start 405.4856 -238.41583)
		(end 405.4856 -238.18723)
		(width 0.14478)
		(layer "In4.Cu")
		(net "M_J_CPU0_SA_DQ<30>")
	)
	(segment
		(start 417.52901 -231.760268)
		(end 418.379148 -232.610406)
		(width 0.14478)
		(layer "In4.Cu")
		(net "M_J_CPU0_SA_DQ<30>")
	)
	(segment
		(start 405.677624 -237.598966)
		(end 405.875744 -237.797086)
		(width 0.14478)
		(layer "In4.Cu")
		(net "M_J_CPU0_SA_DQ<30>")
	)
	(segment
		(start 403.888448 -239.159542)
		(end 404.117048 -239.159542)
		(width 0.14478)
		(layer "In4.Cu")
		(net "M_J_CPU0_SA_DQ<30>")
	)
	(segment
		(start 383.497836 -243.351558)
		(end 383.506218 -243.346732)
		(width 0.0889)
		(layer "In4.Cu")
		(net "M_J_CPU0_SA_DQ<30>")
	)
	(segment
		(start 391.01776 -243.351558)
		(end 391.026142 -243.346732)
		(width 0.0889)
		(layer "In4.Cu")
		(net "M_J_CPU0_SA_DQ<30>")
	)
	(segment
		(start 404.315168 -239.357662)
		(end 404.543768 -239.357662)
		(width 0.14478)
		(layer "In4.Cu")
		(net "M_J_CPU0_SA_DQ<30>")
	)
	(segment
		(start 401.38604 -241.89055)
		(end 401.38604 -241.66195)
		(width 0.14478)
		(layer "In4.Cu")
		(net "M_J_CPU0_SA_DQ<30>")
	)
	(segment
		(start 402.364448 -241.308382)
		(end 402.166328 -241.110262)
		(width 0.14478)
		(layer "In4.Cu")
		(net "M_J_CPU0_SA_DQ<30>")
	)
	(segment
		(start 405.28748 -237.76051)
		(end 405.449024 -237.598966)
		(width 0.14478)
		(layer "In4.Cu")
		(net "M_J_CPU0_SA_DQ<30>")
	)
	(segment
		(start 405.449024 -237.598966)
		(end 405.677624 -237.598966)
		(width 0.14478)
		(layer "In4.Cu")
		(net "M_J_CPU0_SA_DQ<30>")
	)
	(segment
		(start 403.76348 -240.13795)
		(end 403.925024 -239.976406)
		(width 0.14478)
		(layer "In4.Cu")
		(net "M_J_CPU0_SA_DQ<30>")
	)
	(segment
		(start 406.457912 -236.818678)
		(end 406.656032 -237.016798)
		(width 0.14478)
		(layer "In4.Cu")
		(net "M_J_CPU0_SA_DQ<30>")
	)
	(segment
		(start 391.391902 -243.351558)
		(end 391.402316 -243.357654)
		(width 0.0889)
		(layer "In4.Cu")
		(net "M_J_CPU0_SA_DQ<30>")
	)
	(segment
		(start 402.327872 -240.720118)
		(end 402.556472 -240.720118)
		(width 0.14478)
		(layer "In4.Cu")
		(net "M_J_CPU0_SA_DQ<30>")
	)
	(segment
		(start 401.58416 -242.31727)
		(end 401.58416 -242.08867)
		(width 0.14478)
		(layer "In4.Cu")
		(net "M_J_CPU0_SA_DQ<30>")
	)
	(segment
		(start 404.897336 -238.379254)
		(end 405.095456 -238.577374)
		(width 0.14478)
		(layer "In4.Cu")
		(net "M_J_CPU0_SA_DQ<30>")
	)
	(segment
		(start 401.37715 -242.52428)
		(end 401.58416 -242.31727)
		(width 0.14478)
		(layer "In4.Cu")
		(net "M_J_CPU0_SA_DQ<30>")
	)
	(segment
		(start 402.946616 -240.329974)
		(end 402.946616 -240.101374)
		(width 0.14478)
		(layer "In4.Cu")
		(net "M_J_CPU0_SA_DQ<30>")
	)
	(segment
		(start 401.974304 -241.698526)
		(end 402.202904 -241.698526)
		(width 0.14478)
		(layer "In4.Cu")
		(net "M_J_CPU0_SA_DQ<30>")
	)
	(segment
		(start 426.322236 -232.610406)
		(end 429.332898 -232.610406)
		(width 0.14478)
		(layer "In4.Cu")
		(net "M_J_CPU0_SA_DQ<30>")
	)
	(segment
		(start 403.33676 -239.93983)
		(end 403.53488 -240.13795)
		(width 0.14478)
		(layer "In4.Cu")
		(net "M_J_CPU0_SA_DQ<30>")
	)
	(segment
		(start 405.095456 -238.577374)
		(end 405.324056 -238.577374)
		(width 0.14478)
		(layer "In4.Cu")
		(net "M_J_CPU0_SA_DQ<30>")
	)
	(segment
		(start 402.166328 -240.881662)
		(end 402.327872 -240.720118)
		(width 0.14478)
		(layer "In4.Cu")
		(net "M_J_CPU0_SA_DQ<30>")
	)
	(segment
		(start 393.084812 -243.300758)
		(end 394.152628 -243.300758)
		(width 0.0889)
		(layer "In4.Cu")
		(net "M_J_CPU0_SA_DQ<30>")
	)
	(segment
		(start 402.166328 -241.110262)
		(end 402.166328 -240.881662)
		(width 0.14478)
		(layer "In4.Cu")
		(net "M_J_CPU0_SA_DQ<30>")
	)
	(segment
		(start 380.710694 -243.408708)
		(end 380.733046 -243.325396)
		(width 0.0889)
		(layer "In4.Cu")
		(net "M_J_CPU0_SA_DQ<30>")
	)
	(segment
		(start 385.74345 -243.346732)
		(end 385.751832 -243.351558)
		(width 0.0889)
		(layer "In4.Cu")
		(net "M_J_CPU0_SA_DQ<30>")
	)
	(segment
		(start 406.229312 -236.818678)
		(end 406.457912 -236.818678)
		(width 0.14478)
		(layer "In4.Cu")
		(net "M_J_CPU0_SA_DQ<30>")
	)
	(segment
		(start 402.556472 -240.720118)
		(end 402.754592 -240.918238)
		(width 0.14478)
		(layer "In4.Cu")
		(net "M_J_CPU0_SA_DQ<30>")
	)
	(segment
		(start 415.7726 -231.760268)
		(end 417.52901 -231.760268)
		(width 0.14478)
		(layer "In4.Cu")
		(net "M_J_CPU0_SA_DQ<30>")
	)
	(segment
		(start 403.144736 -240.756694)
		(end 403.144736 -240.528094)
		(width 0.14478)
		(layer "In4.Cu")
		(net "M_J_CPU0_SA_DQ<30>")
	)
	(segment
		(start 406.067768 -237.208822)
		(end 406.067768 -236.980222)
		(width 0.14478)
		(layer "In4.Cu")
		(net "M_J_CPU0_SA_DQ<30>")
	)
	(segment
		(start 403.726904 -239.321086)
		(end 403.888448 -239.159542)
		(width 0.14478)
		(layer "In4.Cu")
		(net "M_J_CPU0_SA_DQ<30>")
	)
	(segment
		(start 402.202904 -241.698526)
		(end 402.364448 -241.536982)
		(width 0.14478)
		(layer "In4.Cu")
		(net "M_J_CPU0_SA_DQ<30>")
	)
	(segment
		(start 381.043434 -243.346732)
		(end 381.051816 -243.351558)
		(width 0.0889)
		(layer "In4.Cu")
		(net "M_J_CPU0_SA_DQ<30>")
	)
	(segment
		(start 406.265888 -237.406942)
		(end 406.067768 -237.208822)
		(width 0.14478)
		(layer "In4.Cu")
		(net "M_J_CPU0_SA_DQ<30>")
	)
	(segment
		(start 411.291024 -232.610406)
		(end 414.922462 -232.610406)
		(width 0.14478)
		(layer "In4.Cu")
		(net "M_J_CPU0_SA_DQ<30>")
	)
	(segment
		(start 421.437054 -232.610406)
		(end 422.287192 -231.760268)
		(width 0.14478)
		(layer "In4.Cu")
		(net "M_J_CPU0_SA_DQ<30>")
	)
	(segment
		(start 395.896338 -242.52428)
		(end 401.37715 -242.52428)
		(width 0.14478)
		(layer "In4.Cu")
		(net "M_J_CPU0_SA_DQ<30>")
	)
	(segment
		(start 429.332898 -232.610406)
		(end 430.183036 -231.760268)
		(width 0.14478)
		(layer "In4.Cu")
		(net "M_J_CPU0_SA_DQ<30>")
	)
	(segment
		(start 403.53488 -240.13795)
		(end 403.76348 -240.13795)
		(width 0.14478)
		(layer "In4.Cu")
		(net "M_J_CPU0_SA_DQ<30>")
	)
	(segment
		(start 394.826236 -243.49329)
		(end 395.166596 -243.15293)
		(width 0.0889)
		(layer "In4.Cu")
		(net "M_J_CPU0_SA_DQ<30>")
	)
	(arc
		(start 388.571994 -243.351558)
		(mid 388.85495 -243.427735)
		(end 389.137906 -243.351558)
		(width 0.0889)
		(layer "In4.Cu")
		(net "M_J_CPU0_SA_DQ<30>")
	)
	(arc
		(start 387.26618 -243.346732)
		(mid 387.449688 -243.301238)
		(end 387.63194 -243.351558)
		(width 0.0889)
		(layer "In4.Cu")
		(net "M_J_CPU0_SA_DQ<30>")
	)
	(arc
		(start 385.751832 -243.351558)
		(mid 386.034788 -243.427735)
		(end 386.317744 -243.351558)
		(width 0.0889)
		(layer "In4.Cu")
		(net "M_J_CPU0_SA_DQ<30>")
	)
	(arc
		(start 388.206234 -243.346732)
		(mid 388.389742 -243.301238)
		(end 388.571994 -243.351558)
		(width 0.0889)
		(layer "In4.Cu")
		(net "M_J_CPU0_SA_DQ<30>")
	)
	(arc
		(start 391.402316 -243.357654)
		(mid 391.681002 -243.427874)
		(end 391.958068 -243.351558)
		(width 0.0889)
		(layer "In4.Cu")
		(net "M_J_CPU0_SA_DQ<30>")
	)
	(arc
		(start 386.691886 -243.351558)
		(mid 386.974842 -243.427735)
		(end 387.257798 -243.351558)
		(width 0.0889)
		(layer "In4.Cu")
		(net "M_J_CPU0_SA_DQ<30>")
	)
	(arc
		(start 381.051816 -243.351558)
		(mid 381.334772 -243.427735)
		(end 381.617728 -243.351558)
		(width 0.0889)
		(layer "In4.Cu")
		(net "M_J_CPU0_SA_DQ<30>")
	)
	(arc
		(start 385.37769 -243.351558)
		(mid 385.559941 -243.301208)
		(end 385.74345 -243.346732)
		(width 0.0889)
		(layer "In4.Cu")
		(net "M_J_CPU0_SA_DQ<30>")
	)
	(arc
		(start 381.99187 -243.351558)
		(mid 382.274826 -243.427735)
		(end 382.557782 -243.351558)
		(width 0.0889)
		(layer "In4.Cu")
		(net "M_J_CPU0_SA_DQ<30>")
	)
	(arc
		(start 390.451848 -243.351558)
		(mid 390.734804 -243.427735)
		(end 391.01776 -243.351558)
		(width 0.0889)
		(layer "In4.Cu")
		(net "M_J_CPU0_SA_DQ<30>")
	)
	(arc
		(start 383.506218 -243.346732)
		(mid 383.689726 -243.301238)
		(end 383.871978 -243.351558)
		(width 0.0889)
		(layer "In4.Cu")
		(net "M_J_CPU0_SA_DQ<30>")
	)
	(arc
		(start 392.892534 -243.355114)
		(mid 392.984966 -243.314832)
		(end 393.084812 -243.300758)
		(width 0.0889)
		(layer "In4.Cu")
		(net "M_J_CPU0_SA_DQ<30>")
	)
	(arc
		(start 392.332718 -243.351558)
		(mid 392.612146 -243.427724)
		(end 392.892534 -243.355114)
		(width 0.0889)
		(layer "In4.Cu")
		(net "M_J_CPU0_SA_DQ<30>")
	)
	(arc
		(start 381.617728 -243.351558)
		(mid 381.799979 -243.301208)
		(end 381.983488 -243.346732)
		(width 0.0889)
		(layer "In4.Cu")
		(net "M_J_CPU0_SA_DQ<30>")
	)
	(arc
		(start 387.63194 -243.351558)
		(mid 387.914896 -243.427735)
		(end 388.197852 -243.351558)
		(width 0.0889)
		(layer "In4.Cu")
		(net "M_J_CPU0_SA_DQ<30>")
	)
	(arc
		(start 384.43789 -243.351558)
		(mid 384.624834 -243.301303)
		(end 384.811778 -243.351558)
		(width 0.0889)
		(layer "In4.Cu")
		(net "M_J_CPU0_SA_DQ<30>")
	)
	(arc
		(start 382.566164 -243.346732)
		(mid 382.749672 -243.301238)
		(end 382.931924 -243.351558)
		(width 0.0889)
		(layer "In4.Cu")
		(net "M_J_CPU0_SA_DQ<30>")
	)
	(arc
		(start 380.733046 -243.325396)
		(mid 380.890556 -243.302198)
		(end 381.043434 -243.346732)
		(width 0.0889)
		(layer "In4.Cu")
		(net "M_J_CPU0_SA_DQ<30>")
	)
	(arc
		(start 391.958068 -243.351558)
		(mid 392.140573 -243.301081)
		(end 392.324336 -243.346732)
		(width 0.0889)
		(layer "In4.Cu")
		(net "M_J_CPU0_SA_DQ<30>")
	)
	(arc
		(start 391.026142 -243.346732)
		(mid 391.20965 -243.301238)
		(end 391.391902 -243.351558)
		(width 0.0889)
		(layer "In4.Cu")
		(net "M_J_CPU0_SA_DQ<30>")
	)
	(arc
		(start 390.077706 -243.351558)
		(mid 390.259957 -243.301208)
		(end 390.443466 -243.346732)
		(width 0.0889)
		(layer "In4.Cu")
		(net "M_J_CPU0_SA_DQ<30>")
	)
	(arc
		(start 389.137906 -243.351558)
		(mid 389.32485 -243.301303)
		(end 389.511794 -243.351558)
		(width 0.0889)
		(layer "In4.Cu")
		(net "M_J_CPU0_SA_DQ<30>")
	)
	(arc
		(start 384.811778 -243.351558)
		(mid 385.094734 -243.427735)
		(end 385.37769 -243.351558)
		(width 0.0889)
		(layer "In4.Cu")
		(net "M_J_CPU0_SA_DQ<30>")
	)
	(arc
		(start 382.931924 -243.351558)
		(mid 383.21488 -243.427735)
		(end 383.497836 -243.351558)
		(width 0.0889)
		(layer "In4.Cu")
		(net "M_J_CPU0_SA_DQ<30>")
	)
	(arc
		(start 386.317744 -243.351558)
		(mid 386.499995 -243.301208)
		(end 386.683504 -243.346732)
		(width 0.0889)
		(layer "In4.Cu")
		(net "M_J_CPU0_SA_DQ<30>")
	)
	(arc
		(start 389.511794 -243.351558)
		(mid 389.79475 -243.427735)
		(end 390.077706 -243.351558)
		(width 0.0889)
		(layer "In4.Cu")
		(net "M_J_CPU0_SA_DQ<30>")
	)
	(arc
		(start 383.871978 -243.351558)
		(mid 384.154934 -243.427735)
		(end 384.43789 -243.351558)
		(width 0.0889)
		(layer "In4.Cu")
		(net "M_J_CPU0_SA_DQ<30>")
	)
	(segment
		(start 380.39802 -226.120198)
		(end 380.864872 -225.85426)
		(width 0.10668)
		(layer "F.Cu")
		(net "M_J_CPU0_SA_DQ<2>")
	)
	(segment
		(start 381.983488 -225.526854)
		(end 381.99187 -225.53168)
		(width 0.0889)
		(layer "In4.Cu")
		(net "M_J_CPU0_SA_DQ<2>")
	)
	(segment
		(start 434.575204 -197.760082)
		(end 435.000146 -198.185024)
		(width 0.14478)
		(layer "In4.Cu")
		(net "M_J_CPU0_SA_DQ<2>")
	)
	(segment
		(start 410.704538 -198.61022)
		(end 414.168082 -198.61022)
		(width 0.14478)
		(layer "In4.Cu")
		(net "M_J_CPU0_SA_DQ<2>")
	)
	(segment
		(start 403.086062 -203.675996)
		(end 403.086062 -203.447396)
		(width 0.14478)
		(layer "In4.Cu")
		(net "M_J_CPU0_SA_DQ<2>")
	)
	(segment
		(start 407.923238 -198.61022)
		(end 408.773884 -198.61022)
		(width 0.14478)
		(layer "In4.Cu")
		(net "M_J_CPU0_SA_DQ<2>")
	)
	(segment
		(start 404.167086 -203.425044)
		(end 404.167086 -203.196444)
		(width 0.14478)
		(layer "In4.Cu")
		(net "M_J_CPU0_SA_DQ<2>")
	)
	(segment
		(start 386.683504 -225.526854)
		(end 386.691886 -225.53168)
		(width 0.0889)
		(layer "In4.Cu")
		(net "M_J_CPU0_SA_DQ<2>")
	)
	(segment
		(start 422.106344 -197.760082)
		(end 425.92117 -197.760082)
		(width 0.14478)
		(layer "In4.Cu")
		(net "M_J_CPU0_SA_DQ<2>")
	)
	(segment
		(start 390.401556 -217.42273)
		(end 402.60651 -205.217776)
		(width 0.14478)
		(layer "In4.Cu")
		(net "M_J_CPU0_SA_DQ<2>")
	)
	(segment
		(start 404.646638 -202.11542)
		(end 404.646638 -201.88682)
		(width 0.14478)
		(layer "In4.Cu")
		(net "M_J_CPU0_SA_DQ<2>")
	)
	(segment
		(start 403.776942 -203.586588)
		(end 404.005542 -203.586588)
		(width 0.14478)
		(layer "In4.Cu")
		(net "M_J_CPU0_SA_DQ<2>")
	)
	(segment
		(start 409.876752 -198.61022)
		(end 410.153104 -198.886572)
		(width 0.14478)
		(layer "In4.Cu")
		(net "M_J_CPU0_SA_DQ<2>")
	)
	(segment
		(start 409.050236 -198.886572)
		(end 409.325318 -198.886572)
		(width 0.14478)
		(layer "In4.Cu")
		(net "M_J_CPU0_SA_DQ<2>")
	)
	(segment
		(start 419.105588 -198.61022)
		(end 421.256206 -198.61022)
		(width 0.14478)
		(layer "In4.Cu")
		(net "M_J_CPU0_SA_DQ<2>")
	)
	(segment
		(start 403.86635 -202.667108)
		(end 404.027894 -202.505564)
		(width 0.14478)
		(layer "In4.Cu")
		(net "M_J_CPU0_SA_DQ<2>")
	)
	(segment
		(start 404.78583 -202.8063)
		(end 404.947374 -202.644756)
		(width 0.14478)
		(layer "In4.Cu")
		(net "M_J_CPU0_SA_DQ<2>")
	)
	(segment
		(start 403.386798 -203.976732)
		(end 403.086062 -203.675996)
		(width 0.14478)
		(layer "In4.Cu")
		(net "M_J_CPU0_SA_DQ<2>")
	)
	(segment
		(start 404.027894 -202.505564)
		(end 404.256494 -202.505564)
		(width 0.14478)
		(layer "In4.Cu")
		(net "M_J_CPU0_SA_DQ<2>")
	)
	(segment
		(start 403.247606 -203.285852)
		(end 403.476206 -203.285852)
		(width 0.14478)
		(layer "In4.Cu")
		(net "M_J_CPU0_SA_DQ<2>")
	)
	(segment
		(start 404.256494 -202.505564)
		(end 404.55723 -202.8063)
		(width 0.14478)
		(layer "In4.Cu")
		(net "M_J_CPU0_SA_DQ<2>")
	)
	(segment
		(start 410.428186 -198.886572)
		(end 410.704538 -198.61022)
		(width 0.14478)
		(layer "In4.Cu")
		(net "M_J_CPU0_SA_DQ<2>")
	)
	(segment
		(start 409.325318 -198.886572)
		(end 409.60167 -198.61022)
		(width 0.14478)
		(layer "In4.Cu")
		(net "M_J_CPU0_SA_DQ<2>")
	)
	(segment
		(start 410.153104 -198.886572)
		(end 410.428186 -198.886572)
		(width 0.14478)
		(layer "In4.Cu")
		(net "M_J_CPU0_SA_DQ<2>")
	)
	(segment
		(start 404.55723 -202.8063)
		(end 404.78583 -202.8063)
		(width 0.14478)
		(layer "In4.Cu")
		(net "M_J_CPU0_SA_DQ<2>")
	)
	(segment
		(start 389.890508 -222.038672)
		(end 390.401556 -221.527624)
		(width 0.0889)
		(layer "In4.Cu")
		(net "M_J_CPU0_SA_DQ<2>")
	)
	(segment
		(start 390.401556 -221.527624)
		(end 390.401556 -221.30385)
		(width 0.0889)
		(layer "In4.Cu")
		(net "M_J_CPU0_SA_DQ<2>")
	)
	(segment
		(start 403.476206 -203.285852)
		(end 403.776942 -203.586588)
		(width 0.14478)
		(layer "In4.Cu")
		(net "M_J_CPU0_SA_DQ<2>")
	)
	(segment
		(start 402.60651 -205.217776)
		(end 402.60651 -204.75702)
		(width 0.14478)
		(layer "In4.Cu")
		(net "M_J_CPU0_SA_DQ<2>")
	)
	(segment
		(start 403.386798 -204.205332)
		(end 403.386798 -203.976732)
		(width 0.14478)
		(layer "In4.Cu")
		(net "M_J_CPU0_SA_DQ<2>")
	)
	(segment
		(start 418.25545 -197.760082)
		(end 419.105588 -198.61022)
		(width 0.14478)
		(layer "In4.Cu")
		(net "M_J_CPU0_SA_DQ<2>")
	)
	(segment
		(start 402.305774 -204.456284)
		(end 402.305774 -204.227684)
		(width 0.14478)
		(layer "In4.Cu")
		(net "M_J_CPU0_SA_DQ<2>")
	)
	(segment
		(start 389.106156 -223.929956)
		(end 389.137906 -223.911668)
		(width 0.0889)
		(layer "In4.Cu")
		(net "M_J_CPU0_SA_DQ<2>")
	)
	(segment
		(start 383.497836 -225.53168)
		(end 383.506218 -225.526854)
		(width 0.0889)
		(layer "In4.Cu")
		(net "M_J_CPU0_SA_DQ<2>")
	)
	(segment
		(start 404.947374 -202.644756)
		(end 404.947374 -202.416156)
		(width 0.14478)
		(layer "In4.Cu")
		(net "M_J_CPU0_SA_DQ<2>")
	)
	(segment
		(start 402.996654 -204.366876)
		(end 403.225254 -204.366876)
		(width 0.14478)
		(layer "In4.Cu")
		(net "M_J_CPU0_SA_DQ<2>")
	)
	(segment
		(start 409.60167 -198.61022)
		(end 409.876752 -198.61022)
		(width 0.14478)
		(layer "In4.Cu")
		(net "M_J_CPU0_SA_DQ<2>")
	)
	(segment
		(start 388.636256 -224.739962)
		(end 388.668006 -224.721674)
		(width 0.0889)
		(layer "In4.Cu")
		(net "M_J_CPU0_SA_DQ<2>")
	)
	(segment
		(start 421.256206 -198.61022)
		(end 422.106344 -197.760082)
		(width 0.14478)
		(layer "In4.Cu")
		(net "M_J_CPU0_SA_DQ<2>")
	)
	(segment
		(start 402.305774 -204.227684)
		(end 402.467318 -204.06614)
		(width 0.14478)
		(layer "In4.Cu")
		(net "M_J_CPU0_SA_DQ<2>")
	)
	(segment
		(start 388.197852 -225.53168)
		(end 388.236968 -225.50882)
		(width 0.0889)
		(layer "In4.Cu")
		(net "M_J_CPU0_SA_DQ<2>")
	)
	(segment
		(start 402.467318 -204.06614)
		(end 402.695918 -204.06614)
		(width 0.14478)
		(layer "In4.Cu")
		(net "M_J_CPU0_SA_DQ<2>")
	)
	(segment
		(start 387.257798 -225.53168)
		(end 387.26618 -225.526854)
		(width 0.0889)
		(layer "In4.Cu")
		(net "M_J_CPU0_SA_DQ<2>")
	)
	(segment
		(start 403.86635 -202.895708)
		(end 403.86635 -202.667108)
		(width 0.14478)
		(layer "In4.Cu")
		(net "M_J_CPU0_SA_DQ<2>")
	)
	(segment
		(start 381.043434 -225.526854)
		(end 381.051816 -225.53168)
		(width 0.0889)
		(layer "In4.Cu")
		(net "M_J_CPU0_SA_DQ<2>")
	)
	(segment
		(start 380.710694 -225.58883)
		(end 380.733046 -225.505518)
		(width 0.0889)
		(layer "In4.Cu")
		(net "M_J_CPU0_SA_DQ<2>")
	)
	(segment
		(start 385.74345 -225.526854)
		(end 385.751832 -225.53168)
		(width 0.0889)
		(layer "In4.Cu")
		(net "M_J_CPU0_SA_DQ<2>")
	)
	(segment
		(start 382.557782 -225.53168)
		(end 382.566164 -225.526854)
		(width 0.0889)
		(layer "In4.Cu")
		(net "M_J_CPU0_SA_DQ<2>")
	)
	(segment
		(start 429.331882 -198.61022)
		(end 430.18202 -197.760082)
		(width 0.14478)
		(layer "In4.Cu")
		(net "M_J_CPU0_SA_DQ<2>")
	)
	(segment
		(start 415.01822 -197.760082)
		(end 418.25545 -197.760082)
		(width 0.14478)
		(layer "In4.Cu")
		(net "M_J_CPU0_SA_DQ<2>")
	)
	(segment
		(start 390.401556 -221.30385)
		(end 390.401556 -217.42273)
		(width 0.14478)
		(layer "In4.Cu")
		(net "M_J_CPU0_SA_DQ<2>")
	)
	(segment
		(start 402.60651 -204.75702)
		(end 402.305774 -204.456284)
		(width 0.14478)
		(layer "In4.Cu")
		(net "M_J_CPU0_SA_DQ<2>")
	)
	(segment
		(start 404.646638 -201.88682)
		(end 407.923238 -198.61022)
		(width 0.14478)
		(layer "In4.Cu")
		(net "M_J_CPU0_SA_DQ<2>")
	)
	(segment
		(start 389.60806 -223.101662)
		(end 389.648446 -223.07804)
		(width 0.0889)
		(layer "In4.Cu")
		(net "M_J_CPU0_SA_DQ<2>")
	)
	(segment
		(start 408.773884 -198.61022)
		(end 409.050236 -198.886572)
		(width 0.14478)
		(layer "In4.Cu")
		(net "M_J_CPU0_SA_DQ<2>")
	)
	(segment
		(start 388.668006 -224.721674)
		(end 388.704328 -224.700592)
		(width 0.0889)
		(layer "In4.Cu")
		(net "M_J_CPU0_SA_DQ<2>")
	)
	(segment
		(start 403.086062 -203.447396)
		(end 403.247606 -203.285852)
		(width 0.14478)
		(layer "In4.Cu")
		(net "M_J_CPU0_SA_DQ<2>")
	)
	(segment
		(start 425.92117 -197.760082)
		(end 426.771308 -198.61022)
		(width 0.14478)
		(layer "In4.Cu")
		(net "M_J_CPU0_SA_DQ<2>")
	)
	(segment
		(start 389.57758 -223.119442)
		(end 389.60806 -223.101662)
		(width 0.0889)
		(layer "In4.Cu")
		(net "M_J_CPU0_SA_DQ<2>")
	)
	(segment
		(start 402.695918 -204.06614)
		(end 402.996654 -204.366876)
		(width 0.14478)
		(layer "In4.Cu")
		(net "M_J_CPU0_SA_DQ<2>")
	)
	(segment
		(start 426.771308 -198.61022)
		(end 429.331882 -198.61022)
		(width 0.14478)
		(layer "In4.Cu")
		(net "M_J_CPU0_SA_DQ<2>")
	)
	(segment
		(start 404.947374 -202.416156)
		(end 404.646638 -202.11542)
		(width 0.14478)
		(layer "In4.Cu")
		(net "M_J_CPU0_SA_DQ<2>")
	)
	(segment
		(start 430.18202 -197.760082)
		(end 434.575204 -197.760082)
		(width 0.14478)
		(layer "In4.Cu")
		(net "M_J_CPU0_SA_DQ<2>")
	)
	(segment
		(start 404.005542 -203.586588)
		(end 404.167086 -203.425044)
		(width 0.14478)
		(layer "In4.Cu")
		(net "M_J_CPU0_SA_DQ<2>")
	)
	(segment
		(start 414.168082 -198.61022)
		(end 415.01822 -197.760082)
		(width 0.14478)
		(layer "In4.Cu")
		(net "M_J_CPU0_SA_DQ<2>")
	)
	(segment
		(start 380.864872 -225.85426)
		(end 380.710694 -225.58883)
		(width 0.0889)
		(layer "In4.Cu")
		(net "M_J_CPU0_SA_DQ<2>")
	)
	(segment
		(start 389.137906 -223.911668)
		(end 389.178292 -223.888046)
		(width 0.0889)
		(layer "In4.Cu")
		(net "M_J_CPU0_SA_DQ<2>")
	)
	(segment
		(start 404.167086 -203.196444)
		(end 403.86635 -202.895708)
		(width 0.14478)
		(layer "In4.Cu")
		(net "M_J_CPU0_SA_DQ<2>")
	)
	(segment
		(start 389.890508 -222.614236)
		(end 389.890508 -222.038672)
		(width 0.0889)
		(layer "In4.Cu")
		(net "M_J_CPU0_SA_DQ<2>")
	)
	(segment
		(start 403.225254 -204.366876)
		(end 403.386798 -204.205332)
		(width 0.14478)
		(layer "In4.Cu")
		(net "M_J_CPU0_SA_DQ<2>")
	)
	(arc
		(start 389.648446 -223.07804)
		(mid 389.826341 -222.875818)
		(end 389.890508 -222.614236)
		(width 0.0889)
		(layer "In4.Cu")
		(net "M_J_CPU0_SA_DQ<2>")
	)
	(arc
		(start 383.506218 -225.526854)
		(mid 383.689726 -225.48136)
		(end 383.871978 -225.53168)
		(width 0.0889)
		(layer "In4.Cu")
		(net "M_J_CPU0_SA_DQ<2>")
	)
	(arc
		(start 388.236968 -225.50882)
		(mid 388.415781 -225.30647)
		(end 388.4803 -225.044254)
		(width 0.0889)
		(layer "In4.Cu")
		(net "M_J_CPU0_SA_DQ<2>")
	)
	(arc
		(start 382.566164 -225.526854)
		(mid 382.749672 -225.48136)
		(end 382.931924 -225.53168)
		(width 0.0889)
		(layer "In4.Cu")
		(net "M_J_CPU0_SA_DQ<2>")
	)
	(arc
		(start 383.871978 -225.53168)
		(mid 384.154934 -225.607857)
		(end 384.43789 -225.53168)
		(width 0.0889)
		(layer "In4.Cu")
		(net "M_J_CPU0_SA_DQ<2>")
	)
	(arc
		(start 388.9502 -224.234248)
		(mid 388.991455 -224.063277)
		(end 389.106156 -223.929956)
		(width 0.0889)
		(layer "In4.Cu")
		(net "M_J_CPU0_SA_DQ<2>")
	)
	(arc
		(start 388.704328 -224.700592)
		(mid 388.88498 -224.497847)
		(end 388.9502 -224.234248)
		(width 0.0889)
		(layer "In4.Cu")
		(net "M_J_CPU0_SA_DQ<2>")
	)
	(arc
		(start 387.63194 -225.53168)
		(mid 387.914896 -225.607857)
		(end 388.197852 -225.53168)
		(width 0.0889)
		(layer "In4.Cu")
		(net "M_J_CPU0_SA_DQ<2>")
	)
	(arc
		(start 380.733046 -225.505518)
		(mid 380.890556 -225.48232)
		(end 381.043434 -225.526854)
		(width 0.0889)
		(layer "In4.Cu")
		(net "M_J_CPU0_SA_DQ<2>")
	)
	(arc
		(start 384.811778 -225.53168)
		(mid 385.094734 -225.607857)
		(end 385.37769 -225.53168)
		(width 0.0889)
		(layer "In4.Cu")
		(net "M_J_CPU0_SA_DQ<2>")
	)
	(arc
		(start 387.26618 -225.526854)
		(mid 387.449688 -225.48136)
		(end 387.63194 -225.53168)
		(width 0.0889)
		(layer "In4.Cu")
		(net "M_J_CPU0_SA_DQ<2>")
	)
	(arc
		(start 385.751832 -225.53168)
		(mid 386.034788 -225.607857)
		(end 386.317744 -225.53168)
		(width 0.0889)
		(layer "In4.Cu")
		(net "M_J_CPU0_SA_DQ<2>")
	)
	(arc
		(start 385.37769 -225.53168)
		(mid 385.559941 -225.48133)
		(end 385.74345 -225.526854)
		(width 0.0889)
		(layer "In4.Cu")
		(net "M_J_CPU0_SA_DQ<2>")
	)
	(arc
		(start 389.178292 -223.888046)
		(mid 389.356357 -223.685869)
		(end 389.420608 -223.424242)
		(width 0.0889)
		(layer "In4.Cu")
		(net "M_J_CPU0_SA_DQ<2>")
	)
	(arc
		(start 384.43789 -225.53168)
		(mid 384.624834 -225.481425)
		(end 384.811778 -225.53168)
		(width 0.0889)
		(layer "In4.Cu")
		(net "M_J_CPU0_SA_DQ<2>")
	)
	(arc
		(start 389.420608 -223.424242)
		(mid 389.462157 -223.25282)
		(end 389.57758 -223.119442)
		(width 0.0889)
		(layer "In4.Cu")
		(net "M_J_CPU0_SA_DQ<2>")
	)
	(arc
		(start 388.4803 -225.044254)
		(mid 388.521555 -224.873283)
		(end 388.636256 -224.739962)
		(width 0.0889)
		(layer "In4.Cu")
		(net "M_J_CPU0_SA_DQ<2>")
	)
	(arc
		(start 382.931924 -225.53168)
		(mid 383.21488 -225.607857)
		(end 383.497836 -225.53168)
		(width 0.0889)
		(layer "In4.Cu")
		(net "M_J_CPU0_SA_DQ<2>")
	)
	(arc
		(start 381.051816 -225.53168)
		(mid 381.334772 -225.607857)
		(end 381.617728 -225.53168)
		(width 0.0889)
		(layer "In4.Cu")
		(net "M_J_CPU0_SA_DQ<2>")
	)
	(arc
		(start 381.99187 -225.53168)
		(mid 382.274826 -225.607857)
		(end 382.557782 -225.53168)
		(width 0.0889)
		(layer "In4.Cu")
		(net "M_J_CPU0_SA_DQ<2>")
	)
	(arc
		(start 386.317744 -225.53168)
		(mid 386.499995 -225.48133)
		(end 386.683504 -225.526854)
		(width 0.0889)
		(layer "In4.Cu")
		(net "M_J_CPU0_SA_DQ<2>")
	)
	(arc
		(start 381.617728 -225.53168)
		(mid 381.799979 -225.48133)
		(end 381.983488 -225.526854)
		(width 0.0889)
		(layer "In4.Cu")
		(net "M_J_CPU0_SA_DQ<2>")
	)
	(arc
		(start 386.691886 -225.53168)
		(mid 386.974842 -225.607857)
		(end 387.257798 -225.53168)
		(width 0.0889)
		(layer "In4.Cu")
		(net "M_J_CPU0_SA_DQ<2>")
	)
	(segment
		(start 378.517912 -243.940076)
		(end 378.984764 -243.674138)
		(width 0.10668)
		(layer "F.Cu")
		(net "M_J_CPU0_SA_DQ<29>")
	)
	(segment
		(start 415.565844 -232.610406)
		(end 417.619688 -232.610406)
		(width 0.14478)
		(layer "In4.Cu")
		(net "M_J_CPU0_SA_DQ<29>")
	)
	(segment
		(start 387.257798 -243.996718)
		(end 387.26618 -244.001544)
		(width 0.0889)
		(layer "In4.Cu")
		(net "M_J_CPU0_SA_DQ<29>")
	)
	(segment
		(start 378.984764 -243.674138)
		(end 379.138942 -243.939568)
		(width 0.0889)
		(layer "In4.Cu")
		(net "M_J_CPU0_SA_DQ<29>")
	)
	(segment
		(start 401.558506 -242.97894)
		(end 411.077156 -233.46029)
		(width 0.14478)
		(layer "In4.Cu")
		(net "M_J_CPU0_SA_DQ<29>")
	)
	(segment
		(start 379.138942 -243.939568)
		(end 379.235208 -243.964968)
		(width 0.0889)
		(layer "In4.Cu")
		(net "M_J_CPU0_SA_DQ<29>")
	)
	(segment
		(start 381.043434 -244.001544)
		(end 381.051816 -243.996718)
		(width 0.0889)
		(layer "In4.Cu")
		(net "M_J_CPU0_SA_DQ<29>")
	)
	(segment
		(start 391.01776 -243.996718)
		(end 391.026142 -244.001544)
		(width 0.0889)
		(layer "In4.Cu")
		(net "M_J_CPU0_SA_DQ<29>")
	)
	(segment
		(start 395.87805 -242.97894)
		(end 401.558506 -242.97894)
		(width 0.14478)
		(layer "In4.Cu")
		(net "M_J_CPU0_SA_DQ<29>")
	)
	(segment
		(start 385.74345 -244.001544)
		(end 385.751832 -243.996718)
		(width 0.0889)
		(layer "In4.Cu")
		(net "M_J_CPU0_SA_DQ<29>")
	)
	(segment
		(start 392.321034 -244.003576)
		(end 392.332718 -243.996718)
		(width 0.0889)
		(layer "In4.Cu")
		(net "M_J_CPU0_SA_DQ<29>")
	)
	(segment
		(start 393.869672 -244.047518)
		(end 394.12418 -243.79301)
		(width 0.0889)
		(layer "In4.Cu")
		(net "M_J_CPU0_SA_DQ<29>")
	)
	(segment
		(start 430.086262 -232.610406)
		(end 438.675526 -232.610406)
		(width 0.14478)
		(layer "In4.Cu")
		(net "M_J_CPU0_SA_DQ<29>")
	)
	(segment
		(start 386.683504 -244.001544)
		(end 386.691886 -243.996718)
		(width 0.0889)
		(layer "In4.Cu")
		(net "M_J_CPU0_SA_DQ<29>")
	)
	(segment
		(start 393.084812 -244.047518)
		(end 393.869672 -244.047518)
		(width 0.0889)
		(layer "In4.Cu")
		(net "M_J_CPU0_SA_DQ<29>")
	)
	(segment
		(start 418.469572 -233.46029)
		(end 421.731186 -233.46029)
		(width 0.14478)
		(layer "In4.Cu")
		(net "M_J_CPU0_SA_DQ<29>")
	)
	(segment
		(start 425.561506 -232.610406)
		(end 426.41139 -233.46029)
		(width 0.14478)
		(layer "In4.Cu")
		(net "M_J_CPU0_SA_DQ<29>")
	)
	(segment
		(start 421.731186 -233.46029)
		(end 422.58107 -232.610406)
		(width 0.14478)
		(layer "In4.Cu")
		(net "M_J_CPU0_SA_DQ<29>")
	)
	(segment
		(start 388.197852 -243.996718)
		(end 388.206234 -244.001544)
		(width 0.0889)
		(layer "In4.Cu")
		(net "M_J_CPU0_SA_DQ<29>")
	)
	(segment
		(start 381.983488 -244.001544)
		(end 381.99187 -243.996718)
		(width 0.0889)
		(layer "In4.Cu")
		(net "M_J_CPU0_SA_DQ<29>")
	)
	(segment
		(start 417.619688 -232.610406)
		(end 418.469572 -233.46029)
		(width 0.14478)
		(layer "In4.Cu")
		(net "M_J_CPU0_SA_DQ<29>")
	)
	(segment
		(start 422.58107 -232.610406)
		(end 425.561506 -232.610406)
		(width 0.14478)
		(layer "In4.Cu")
		(net "M_J_CPU0_SA_DQ<29>")
	)
	(segment
		(start 414.71596 -233.46029)
		(end 415.565844 -232.610406)
		(width 0.14478)
		(layer "In4.Cu")
		(net "M_J_CPU0_SA_DQ<29>")
	)
	(segment
		(start 411.077156 -233.46029)
		(end 414.71596 -233.46029)
		(width 0.14478)
		(layer "In4.Cu")
		(net "M_J_CPU0_SA_DQ<29>")
	)
	(segment
		(start 395.683486 -242.97894)
		(end 395.87805 -242.97894)
		(width 0.0889)
		(layer "In4.Cu")
		(net "M_J_CPU0_SA_DQ<29>")
	)
	(segment
		(start 383.497836 -243.996718)
		(end 383.506218 -244.001544)
		(width 0.0889)
		(layer "In4.Cu")
		(net "M_J_CPU0_SA_DQ<29>")
	)
	(segment
		(start 394.869416 -243.79301)
		(end 395.683486 -242.97894)
		(width 0.0889)
		(layer "In4.Cu")
		(net "M_J_CPU0_SA_DQ<29>")
	)
	(segment
		(start 426.41139 -233.46029)
		(end 429.236378 -233.46029)
		(width 0.14478)
		(layer "In4.Cu")
		(net "M_J_CPU0_SA_DQ<29>")
	)
	(segment
		(start 438.675526 -232.610406)
		(end 439.100214 -233.035094)
		(width 0.14478)
		(layer "In4.Cu")
		(net "M_J_CPU0_SA_DQ<29>")
	)
	(segment
		(start 391.391902 -243.996718)
		(end 391.406634 -243.988082)
		(width 0.0889)
		(layer "In4.Cu")
		(net "M_J_CPU0_SA_DQ<29>")
	)
	(segment
		(start 429.236378 -233.46029)
		(end 430.086262 -232.610406)
		(width 0.14478)
		(layer "In4.Cu")
		(net "M_J_CPU0_SA_DQ<29>")
	)
	(segment
		(start 394.12418 -243.79301)
		(end 394.869416 -243.79301)
		(width 0.0889)
		(layer "In4.Cu")
		(net "M_J_CPU0_SA_DQ<29>")
	)
	(segment
		(start 382.557782 -243.996718)
		(end 382.566164 -244.001544)
		(width 0.0889)
		(layer "In4.Cu")
		(net "M_J_CPU0_SA_DQ<29>")
	)
	(segment
		(start 390.443466 -244.001544)
		(end 390.451848 -243.996718)
		(width 0.0889)
		(layer "In4.Cu")
		(net "M_J_CPU0_SA_DQ<29>")
	)
	(arc
		(start 387.63194 -243.996718)
		(mid 387.914896 -243.920541)
		(end 388.197852 -243.996718)
		(width 0.0889)
		(layer "In4.Cu")
		(net "M_J_CPU0_SA_DQ<29>")
	)
	(arc
		(start 391.026142 -244.001544)
		(mid 391.20965 -244.047038)
		(end 391.391902 -243.996718)
		(width 0.0889)
		(layer "In4.Cu")
		(net "M_J_CPU0_SA_DQ<29>")
	)
	(arc
		(start 388.571994 -243.996718)
		(mid 388.85495 -243.920541)
		(end 389.137906 -243.996718)
		(width 0.0889)
		(layer "In4.Cu")
		(net "M_J_CPU0_SA_DQ<29>")
	)
	(arc
		(start 384.811778 -243.996718)
		(mid 385.094734 -243.920541)
		(end 385.37769 -243.996718)
		(width 0.0889)
		(layer "In4.Cu")
		(net "M_J_CPU0_SA_DQ<29>")
	)
	(arc
		(start 380.677674 -243.996718)
		(mid 380.859925 -244.047068)
		(end 381.043434 -244.001544)
		(width 0.0889)
		(layer "In4.Cu")
		(net "M_J_CPU0_SA_DQ<29>")
	)
	(arc
		(start 390.451848 -243.996718)
		(mid 390.734804 -243.920541)
		(end 391.01776 -243.996718)
		(width 0.0889)
		(layer "In4.Cu")
		(net "M_J_CPU0_SA_DQ<29>")
	)
	(arc
		(start 380.111762 -243.996718)
		(mid 380.394718 -243.920541)
		(end 380.677674 -243.996718)
		(width 0.0889)
		(layer "In4.Cu")
		(net "M_J_CPU0_SA_DQ<29>")
	)
	(arc
		(start 386.317744 -243.996718)
		(mid 386.499995 -244.047068)
		(end 386.683504 -244.001544)
		(width 0.0889)
		(layer "In4.Cu")
		(net "M_J_CPU0_SA_DQ<29>")
	)
	(arc
		(start 392.892534 -243.993162)
		(mid 392.984966 -244.033444)
		(end 393.084812 -244.047518)
		(width 0.0889)
		(layer "In4.Cu")
		(net "M_J_CPU0_SA_DQ<29>")
	)
	(arc
		(start 381.051816 -243.996718)
		(mid 381.334772 -243.920541)
		(end 381.617728 -243.996718)
		(width 0.0889)
		(layer "In4.Cu")
		(net "M_J_CPU0_SA_DQ<29>")
	)
	(arc
		(start 379.235208 -243.964968)
		(mid 379.490273 -243.921617)
		(end 379.737874 -243.996718)
		(width 0.0889)
		(layer "In4.Cu")
		(net "M_J_CPU0_SA_DQ<29>")
	)
	(arc
		(start 389.511794 -243.996718)
		(mid 389.79475 -243.920541)
		(end 390.077706 -243.996718)
		(width 0.0889)
		(layer "In4.Cu")
		(net "M_J_CPU0_SA_DQ<29>")
	)
	(arc
		(start 383.506218 -244.001544)
		(mid 383.689726 -244.047038)
		(end 383.871978 -243.996718)
		(width 0.0889)
		(layer "In4.Cu")
		(net "M_J_CPU0_SA_DQ<29>")
	)
	(arc
		(start 386.691886 -243.996718)
		(mid 386.974842 -243.920541)
		(end 387.257798 -243.996718)
		(width 0.0889)
		(layer "In4.Cu")
		(net "M_J_CPU0_SA_DQ<29>")
	)
	(arc
		(start 391.406634 -243.988082)
		(mid 391.683617 -243.920278)
		(end 391.958322 -243.996718)
		(width 0.0889)
		(layer "In4.Cu")
		(net "M_J_CPU0_SA_DQ<29>")
	)
	(arc
		(start 389.137906 -243.996718)
		(mid 389.32485 -244.046973)
		(end 389.511794 -243.996718)
		(width 0.0889)
		(layer "In4.Cu")
		(net "M_J_CPU0_SA_DQ<29>")
	)
	(arc
		(start 384.43789 -243.996718)
		(mid 384.624834 -244.046973)
		(end 384.811778 -243.996718)
		(width 0.0889)
		(layer "In4.Cu")
		(net "M_J_CPU0_SA_DQ<29>")
	)
	(arc
		(start 381.99187 -243.996718)
		(mid 382.274826 -243.920541)
		(end 382.557782 -243.996718)
		(width 0.0889)
		(layer "In4.Cu")
		(net "M_J_CPU0_SA_DQ<29>")
	)
	(arc
		(start 390.077706 -243.996718)
		(mid 390.259957 -244.047068)
		(end 390.443466 -244.001544)
		(width 0.0889)
		(layer "In4.Cu")
		(net "M_J_CPU0_SA_DQ<29>")
	)
	(arc
		(start 387.26618 -244.001544)
		(mid 387.449688 -244.047038)
		(end 387.63194 -243.996718)
		(width 0.0889)
		(layer "In4.Cu")
		(net "M_J_CPU0_SA_DQ<29>")
	)
	(arc
		(start 385.751832 -243.996718)
		(mid 386.034788 -243.920541)
		(end 386.317744 -243.996718)
		(width 0.0889)
		(layer "In4.Cu")
		(net "M_J_CPU0_SA_DQ<29>")
	)
	(arc
		(start 382.931924 -243.996718)
		(mid 383.21488 -243.920541)
		(end 383.497836 -243.996718)
		(width 0.0889)
		(layer "In4.Cu")
		(net "M_J_CPU0_SA_DQ<29>")
	)
	(arc
		(start 383.871978 -243.996718)
		(mid 384.154934 -243.920541)
		(end 384.43789 -243.996718)
		(width 0.0889)
		(layer "In4.Cu")
		(net "M_J_CPU0_SA_DQ<29>")
	)
	(arc
		(start 391.958322 -243.996718)
		(mid 392.13878 -244.047162)
		(end 392.321034 -244.003576)
		(width 0.0889)
		(layer "In4.Cu")
		(net "M_J_CPU0_SA_DQ<29>")
	)
	(arc
		(start 392.332718 -243.996718)
		(mid 392.612146 -243.920552)
		(end 392.892534 -243.993162)
		(width 0.0889)
		(layer "In4.Cu")
		(net "M_J_CPU0_SA_DQ<29>")
	)
	(arc
		(start 379.737874 -243.996718)
		(mid 379.924818 -244.046973)
		(end 380.111762 -243.996718)
		(width 0.0889)
		(layer "In4.Cu")
		(net "M_J_CPU0_SA_DQ<29>")
	)
	(arc
		(start 388.206234 -244.001544)
		(mid 388.389742 -244.047038)
		(end 388.571994 -243.996718)
		(width 0.0889)
		(layer "In4.Cu")
		(net "M_J_CPU0_SA_DQ<29>")
	)
	(arc
		(start 381.617728 -243.996718)
		(mid 381.799979 -244.047068)
		(end 381.983488 -244.001544)
		(width 0.0889)
		(layer "In4.Cu")
		(net "M_J_CPU0_SA_DQ<29>")
	)
	(arc
		(start 382.566164 -244.001544)
		(mid 382.749672 -244.047038)
		(end 382.931924 -243.996718)
		(width 0.0889)
		(layer "In4.Cu")
		(net "M_J_CPU0_SA_DQ<29>")
	)
	(arc
		(start 385.37769 -243.996718)
		(mid 385.559941 -244.047068)
		(end 385.74345 -244.001544)
		(width 0.0889)
		(layer "In4.Cu")
		(net "M_J_CPU0_SA_DQ<29>")
	)
	(segment
		(start 379.927866 -243.13007)
		(end 380.394718 -242.864132)
		(width 0.10668)
		(layer "F.Cu")
		(net "M_J_CPU0_SA_DQ<28>")
	)
	(segment
		(start 437.363108 -231.073198)
		(end 437.363108 -231.51084)
		(width 0.14478)
		(layer "In4.Cu")
		(net "M_J_CPU0_SA_DQ<28>")
	)
	(segment
		(start 430.315624 -230.919782)
		(end 434.392578 -230.919782)
		(width 0.14478)
		(layer "In4.Cu")
		(net "M_J_CPU0_SA_DQ<28>")
	)
	(segment
		(start 395.426946 -242.17376)
		(end 395.531086 -242.06962)
		(width 0.14478)
		(layer "In4.Cu")
		(net "M_J_CPU0_SA_DQ<28>")
	)
	(segment
		(start 394.675106 -242.63477)
		(end 394.965936 -242.63477)
		(width 0.0889)
		(layer "In4.Cu")
		(net "M_J_CPU0_SA_DQ<28>")
	)
	(segment
		(start 389.033512 -243.191538)
		(end 389.041894 -243.186712)
		(width 0.0889)
		(layer "In4.Cu")
		(net "M_J_CPU0_SA_DQ<28>")
	)
	(segment
		(start 389.607806 -243.186712)
		(end 389.616188 -243.191538)
		(width 0.0889)
		(layer "In4.Cu")
		(net "M_J_CPU0_SA_DQ<28>")
	)
	(segment
		(start 384.90779 -243.186712)
		(end 384.916172 -243.191538)
		(width 0.0889)
		(layer "In4.Cu")
		(net "M_J_CPU0_SA_DQ<28>")
	)
	(segment
		(start 380.548896 -243.129562)
		(end 380.645162 -243.154962)
		(width 0.0889)
		(layer "In4.Cu")
		(net "M_J_CPU0_SA_DQ<28>")
	)
	(segment
		(start 394.199618 -243.110258)
		(end 394.675106 -242.63477)
		(width 0.0889)
		(layer "In4.Cu")
		(net "M_J_CPU0_SA_DQ<28>")
	)
	(segment
		(start 381.147828 -243.186712)
		(end 381.15621 -243.191538)
		(width 0.0889)
		(layer "In4.Cu")
		(net "M_J_CPU0_SA_DQ<28>")
	)
	(segment
		(start 422.433496 -230.919782)
		(end 425.305982 -230.919782)
		(width 0.14478)
		(layer "In4.Cu")
		(net "M_J_CPU0_SA_DQ<28>")
	)
	(segment
		(start 418.34562 -231.769666)
		(end 421.583612 -231.769666)
		(width 0.14478)
		(layer "In4.Cu")
		(net "M_J_CPU0_SA_DQ<28>")
	)
	(segment
		(start 437.526176 -231.673908)
		(end 437.756554 -231.673908)
		(width 0.14478)
		(layer "In4.Cu")
		(net "M_J_CPU0_SA_DQ<28>")
	)
	(segment
		(start 411.5054 -231.760014)
		(end 414.270444 -231.760014)
		(width 0.14478)
		(layer "In4.Cu")
		(net "M_J_CPU0_SA_DQ<28>")
	)
	(segment
		(start 438.08269 -230.91013)
		(end 438.675272 -230.91013)
		(width 0.14478)
		(layer "In4.Cu")
		(net "M_J_CPU0_SA_DQ<28>")
	)
	(segment
		(start 417.486084 -230.91013)
		(end 418.34562 -231.769666)
		(width 0.14478)
		(layer "In4.Cu")
		(net "M_J_CPU0_SA_DQ<28>")
	)
	(segment
		(start 434.650388 -231.177592)
		(end 435.511448 -231.177592)
		(width 0.14478)
		(layer "In4.Cu")
		(net "M_J_CPU0_SA_DQ<28>")
	)
	(segment
		(start 385.847844 -243.186712)
		(end 385.856226 -243.191538)
		(width 0.0889)
		(layer "In4.Cu")
		(net "M_J_CPU0_SA_DQ<28>")
	)
	(segment
		(start 437.919622 -231.51084)
		(end 437.919622 -231.073198)
		(width 0.14478)
		(layer "In4.Cu")
		(net "M_J_CPU0_SA_DQ<28>")
	)
	(segment
		(start 415.120328 -230.91013)
		(end 417.486084 -230.91013)
		(width 0.14478)
		(layer "In4.Cu")
		(net "M_J_CPU0_SA_DQ<28>")
	)
	(segment
		(start 425.305982 -230.919782)
		(end 426.155866 -231.769666)
		(width 0.14478)
		(layer "In4.Cu")
		(net "M_J_CPU0_SA_DQ<28>")
	)
	(segment
		(start 384.333496 -243.191538)
		(end 384.341878 -243.186712)
		(width 0.0889)
		(layer "In4.Cu")
		(net "M_J_CPU0_SA_DQ<28>")
	)
	(segment
		(start 392.418062 -243.180616)
		(end 392.428476 -243.186712)
		(width 0.0889)
		(layer "In4.Cu")
		(net "M_J_CPU0_SA_DQ<28>")
	)
	(segment
		(start 405.993092 -236.369098)
		(end 406.896316 -236.369098)
		(width 0.14478)
		(layer "In4.Cu")
		(net "M_J_CPU0_SA_DQ<28>")
	)
	(segment
		(start 406.896316 -236.369098)
		(end 411.5054 -231.760014)
		(width 0.14478)
		(layer "In4.Cu")
		(net "M_J_CPU0_SA_DQ<28>")
	)
	(segment
		(start 434.392578 -230.919782)
		(end 434.650388 -231.177592)
		(width 0.14478)
		(layer "In4.Cu")
		(net "M_J_CPU0_SA_DQ<28>")
	)
	(segment
		(start 388.093458 -243.191538)
		(end 388.10184 -243.186712)
		(width 0.0889)
		(layer "In4.Cu")
		(net "M_J_CPU0_SA_DQ<28>")
	)
	(segment
		(start 437.363108 -231.51084)
		(end 437.526176 -231.673908)
		(width 0.14478)
		(layer "In4.Cu")
		(net "M_J_CPU0_SA_DQ<28>")
	)
	(segment
		(start 437.756554 -231.673908)
		(end 437.919622 -231.51084)
		(width 0.14478)
		(layer "In4.Cu")
		(net "M_J_CPU0_SA_DQ<28>")
	)
	(segment
		(start 435.769258 -230.919782)
		(end 437.209692 -230.919782)
		(width 0.14478)
		(layer "In4.Cu")
		(net "M_J_CPU0_SA_DQ<28>")
	)
	(segment
		(start 435.511448 -231.177592)
		(end 435.769258 -230.919782)
		(width 0.14478)
		(layer "In4.Cu")
		(net "M_J_CPU0_SA_DQ<28>")
	)
	(segment
		(start 414.270444 -231.760014)
		(end 415.120328 -230.91013)
		(width 0.14478)
		(layer "In4.Cu")
		(net "M_J_CPU0_SA_DQ<28>")
	)
	(segment
		(start 393.084812 -243.110258)
		(end 394.199618 -243.110258)
		(width 0.0889)
		(layer "In4.Cu")
		(net "M_J_CPU0_SA_DQ<28>")
	)
	(segment
		(start 426.155866 -231.769666)
		(end 429.46574 -231.769666)
		(width 0.14478)
		(layer "In4.Cu")
		(net "M_J_CPU0_SA_DQ<28>")
	)
	(segment
		(start 421.583612 -231.769666)
		(end 422.433496 -230.919782)
		(width 0.14478)
		(layer "In4.Cu")
		(net "M_J_CPU0_SA_DQ<28>")
	)
	(segment
		(start 394.965936 -242.63477)
		(end 395.426946 -242.17376)
		(width 0.0889)
		(layer "In4.Cu")
		(net "M_J_CPU0_SA_DQ<28>")
	)
	(segment
		(start 380.394718 -242.864132)
		(end 380.548896 -243.129562)
		(width 0.0889)
		(layer "In4.Cu")
		(net "M_J_CPU0_SA_DQ<28>")
	)
	(segment
		(start 437.209692 -230.919782)
		(end 437.363108 -231.073198)
		(width 0.14478)
		(layer "In4.Cu")
		(net "M_J_CPU0_SA_DQ<28>")
	)
	(segment
		(start 383.393442 -243.191538)
		(end 383.401824 -243.186712)
		(width 0.0889)
		(layer "In4.Cu")
		(net "M_J_CPU0_SA_DQ<28>")
	)
	(segment
		(start 429.46574 -231.769666)
		(end 430.315624 -230.919782)
		(width 0.14478)
		(layer "In4.Cu")
		(net "M_J_CPU0_SA_DQ<28>")
	)
	(segment
		(start 391.48766 -243.186712)
		(end 391.496042 -243.191538)
		(width 0.0889)
		(layer "In4.Cu")
		(net "M_J_CPU0_SA_DQ<28>")
	)
	(segment
		(start 400.29257 -242.06962)
		(end 405.993092 -236.369098)
		(width 0.14478)
		(layer "In4.Cu")
		(net "M_J_CPU0_SA_DQ<28>")
	)
	(segment
		(start 395.531086 -242.06962)
		(end 400.29257 -242.06962)
		(width 0.14478)
		(layer "In4.Cu")
		(net "M_J_CPU0_SA_DQ<28>")
	)
	(segment
		(start 438.675272 -230.91013)
		(end 439.100214 -231.335072)
		(width 0.14478)
		(layer "In4.Cu")
		(net "M_J_CPU0_SA_DQ<28>")
	)
	(segment
		(start 437.919622 -231.073198)
		(end 438.08269 -230.91013)
		(width 0.14478)
		(layer "In4.Cu")
		(net "M_J_CPU0_SA_DQ<28>")
	)
	(arc
		(start 384.916172 -243.191538)
		(mid 385.09968 -243.237032)
		(end 385.281932 -243.186712)
		(width 0.0889)
		(layer "In4.Cu")
		(net "M_J_CPU0_SA_DQ<28>")
	)
	(arc
		(start 387.727698 -243.186712)
		(mid 387.909949 -243.237062)
		(end 388.093458 -243.191538)
		(width 0.0889)
		(layer "In4.Cu")
		(net "M_J_CPU0_SA_DQ<28>")
	)
	(arc
		(start 381.52197 -243.186712)
		(mid 381.804926 -243.110535)
		(end 382.087882 -243.186712)
		(width 0.0889)
		(layer "In4.Cu")
		(net "M_J_CPU0_SA_DQ<28>")
	)
	(arc
		(start 390.54786 -243.186712)
		(mid 390.734804 -243.236967)
		(end 390.921748 -243.186712)
		(width 0.0889)
		(layer "In4.Cu")
		(net "M_J_CPU0_SA_DQ<28>")
	)
	(arc
		(start 382.46177 -243.186712)
		(mid 382.744726 -243.110535)
		(end 383.027682 -243.186712)
		(width 0.0889)
		(layer "In4.Cu")
		(net "M_J_CPU0_SA_DQ<28>")
	)
	(arc
		(start 389.981948 -243.186712)
		(mid 390.264904 -243.110535)
		(end 390.54786 -243.186712)
		(width 0.0889)
		(layer "In4.Cu")
		(net "M_J_CPU0_SA_DQ<28>")
	)
	(arc
		(start 391.86231 -243.186712)
		(mid 392.139377 -243.110441)
		(end 392.418062 -243.180616)
		(width 0.0889)
		(layer "In4.Cu")
		(net "M_J_CPU0_SA_DQ<28>")
	)
	(arc
		(start 383.401824 -243.186712)
		(mid 383.68478 -243.110535)
		(end 383.967736 -243.186712)
		(width 0.0889)
		(layer "In4.Cu")
		(net "M_J_CPU0_SA_DQ<28>")
	)
	(arc
		(start 380.645162 -243.154962)
		(mid 380.900227 -243.111611)
		(end 381.147828 -243.186712)
		(width 0.0889)
		(layer "In4.Cu")
		(net "M_J_CPU0_SA_DQ<28>")
	)
	(arc
		(start 384.341878 -243.186712)
		(mid 384.624834 -243.110535)
		(end 384.90779 -243.186712)
		(width 0.0889)
		(layer "In4.Cu")
		(net "M_J_CPU0_SA_DQ<28>")
	)
	(arc
		(start 392.786108 -243.195856)
		(mid 392.929447 -243.132069)
		(end 393.084812 -243.110258)
		(width 0.0889)
		(layer "In4.Cu")
		(net "M_J_CPU0_SA_DQ<28>")
	)
	(arc
		(start 392.428476 -243.186712)
		(mid 392.606126 -243.236972)
		(end 392.786108 -243.195856)
		(width 0.0889)
		(layer "In4.Cu")
		(net "M_J_CPU0_SA_DQ<28>")
	)
	(arc
		(start 390.921748 -243.186712)
		(mid 391.204704 -243.110535)
		(end 391.48766 -243.186712)
		(width 0.0889)
		(layer "In4.Cu")
		(net "M_J_CPU0_SA_DQ<28>")
	)
	(arc
		(start 385.281932 -243.186712)
		(mid 385.564888 -243.110535)
		(end 385.847844 -243.186712)
		(width 0.0889)
		(layer "In4.Cu")
		(net "M_J_CPU0_SA_DQ<28>")
	)
	(arc
		(start 382.087882 -243.186712)
		(mid 382.274826 -243.236967)
		(end 382.46177 -243.186712)
		(width 0.0889)
		(layer "In4.Cu")
		(net "M_J_CPU0_SA_DQ<28>")
	)
	(arc
		(start 391.496042 -243.191538)
		(mid 391.679804 -243.237154)
		(end 391.86231 -243.186712)
		(width 0.0889)
		(layer "In4.Cu")
		(net "M_J_CPU0_SA_DQ<28>")
	)
	(arc
		(start 383.967736 -243.186712)
		(mid 384.149987 -243.237062)
		(end 384.333496 -243.191538)
		(width 0.0889)
		(layer "In4.Cu")
		(net "M_J_CPU0_SA_DQ<28>")
	)
	(arc
		(start 385.856226 -243.191538)
		(mid 386.039734 -243.237032)
		(end 386.221986 -243.186712)
		(width 0.0889)
		(layer "In4.Cu")
		(net "M_J_CPU0_SA_DQ<28>")
	)
	(arc
		(start 386.787898 -243.186712)
		(mid 386.974842 -243.236967)
		(end 387.161786 -243.186712)
		(width 0.0889)
		(layer "In4.Cu")
		(net "M_J_CPU0_SA_DQ<28>")
	)
	(arc
		(start 388.667752 -243.186712)
		(mid 388.850003 -243.237062)
		(end 389.033512 -243.191538)
		(width 0.0889)
		(layer "In4.Cu")
		(net "M_J_CPU0_SA_DQ<28>")
	)
	(arc
		(start 387.161786 -243.186712)
		(mid 387.444742 -243.110535)
		(end 387.727698 -243.186712)
		(width 0.0889)
		(layer "In4.Cu")
		(net "M_J_CPU0_SA_DQ<28>")
	)
	(arc
		(start 383.027682 -243.186712)
		(mid 383.209933 -243.237062)
		(end 383.393442 -243.191538)
		(width 0.0889)
		(layer "In4.Cu")
		(net "M_J_CPU0_SA_DQ<28>")
	)
	(arc
		(start 388.10184 -243.186712)
		(mid 388.384796 -243.110535)
		(end 388.667752 -243.186712)
		(width 0.0889)
		(layer "In4.Cu")
		(net "M_J_CPU0_SA_DQ<28>")
	)
	(arc
		(start 386.221986 -243.186712)
		(mid 386.504942 -243.110535)
		(end 386.787898 -243.186712)
		(width 0.0889)
		(layer "In4.Cu")
		(net "M_J_CPU0_SA_DQ<28>")
	)
	(arc
		(start 381.15621 -243.191538)
		(mid 381.339718 -243.237032)
		(end 381.52197 -243.186712)
		(width 0.0889)
		(layer "In4.Cu")
		(net "M_J_CPU0_SA_DQ<28>")
	)
	(arc
		(start 389.616188 -243.191538)
		(mid 389.799696 -243.237032)
		(end 389.981948 -243.186712)
		(width 0.0889)
		(layer "In4.Cu")
		(net "M_J_CPU0_SA_DQ<28>")
	)
	(arc
		(start 389.041894 -243.186712)
		(mid 389.32485 -243.110535)
		(end 389.607806 -243.186712)
		(width 0.0889)
		(layer "In4.Cu")
		(net "M_J_CPU0_SA_DQ<28>")
	)
	(segment
		(start 378.988066 -241.510058)
		(end 379.454918 -241.24412)
		(width 0.10668)
		(layer "F.Cu")
		(net "M_J_CPU0_SA_DQ<27>")
	)
	(segment
		(start 404.937976 -234.096814)
		(end 405.122634 -233.912156)
		(width 0.14478)
		(layer "In4.Cu")
		(net "M_J_CPU0_SA_DQ<27>")
	)
	(segment
		(start 404.157688 -234.877102)
		(end 404.342346 -234.692444)
		(width 0.14478)
		(layer "In4.Cu")
		(net "M_J_CPU0_SA_DQ<27>")
	)
	(segment
		(start 421.346376 -228.350318)
		(end 422.19626 -227.500434)
		(width 0.14478)
		(layer "In4.Cu")
		(net "M_J_CPU0_SA_DQ<27>")
	)
	(segment
		(start 389.607806 -240.92154)
		(end 389.616188 -240.916714)
		(width 0.0889)
		(layer "In4.Cu")
		(net "M_J_CPU0_SA_DQ<27>")
	)
	(segment
		(start 401.221194 -237.402624)
		(end 401.405852 -237.217966)
		(width 0.14478)
		(layer "In4.Cu")
		(net "M_J_CPU0_SA_DQ<27>")
	)
	(segment
		(start 385.847844 -240.92154)
		(end 385.856226 -240.916714)
		(width 0.0889)
		(layer "In4.Cu")
		(net "M_J_CPU0_SA_DQ<27>")
	)
	(segment
		(start 402.966428 -235.65739)
		(end 403.3774 -235.65739)
		(width 0.14478)
		(layer "In4.Cu")
		(net "M_J_CPU0_SA_DQ<27>")
	)
	(segment
		(start 410.263594 -228.360224)
		(end 414.005776 -228.360224)
		(width 0.14478)
		(layer "In4.Cu")
		(net "M_J_CPU0_SA_DQ<27>")
	)
	(segment
		(start 433.814474 -227.271326)
		(end 433.976018 -227.109782)
		(width 0.14478)
		(layer "In4.Cu")
		(net "M_J_CPU0_SA_DQ<27>")
	)
	(segment
		(start 402.001482 -236.622336)
		(end 402.18614 -236.437678)
		(width 0.14478)
		(layer "In4.Cu")
		(net "M_J_CPU0_SA_DQ<27>")
	)
	(segment
		(start 391.48766 -240.92154)
		(end 391.496042 -240.916714)
		(width 0.0889)
		(layer "In4.Cu")
		(net "M_J_CPU0_SA_DQ<27>")
	)
	(segment
		(start 400.256248 -238.778542)
		(end 400.440906 -238.593884)
		(width 0.14478)
		(layer "In4.Cu")
		(net "M_J_CPU0_SA_DQ<27>")
	)
	(segment
		(start 414.005776 -228.360224)
		(end 414.855914 -227.510086)
		(width 0.14478)
		(layer "In4.Cu")
		(net "M_J_CPU0_SA_DQ<27>")
	)
	(segment
		(start 394.168376 -240.67135)
		(end 394.5636 -240.67135)
		(width 0.0889)
		(layer "In4.Cu")
		(net "M_J_CPU0_SA_DQ<27>")
	)
	(segment
		(start 401.816824 -237.217966)
		(end 402.001482 -237.033308)
		(width 0.14478)
		(layer "In4.Cu")
		(net "M_J_CPU0_SA_DQ<27>")
	)
	(segment
		(start 402.597112 -236.437678)
		(end 402.78177 -236.25302)
		(width 0.14478)
		(layer "In4.Cu")
		(net "M_J_CPU0_SA_DQ<27>")
	)
	(segment
		(start 392.925554 -240.983262)
		(end 393.068556 -241.01171)
		(width 0.0889)
		(layer "In4.Cu")
		(net "M_J_CPU0_SA_DQ<27>")
	)
	(segment
		(start 400.625564 -237.998254)
		(end 401.036536 -237.998254)
		(width 0.14478)
		(layer "In4.Cu")
		(net "M_J_CPU0_SA_DQ<27>")
	)
	(segment
		(start 389.033512 -240.916714)
		(end 389.041894 -240.92154)
		(width 0.0889)
		(layer "In4.Cu")
		(net "M_J_CPU0_SA_DQ<27>")
	)
	(segment
		(start 381.147828 -240.92154)
		(end 381.15621 -240.916714)
		(width 0.0889)
		(layer "In4.Cu")
		(net "M_J_CPU0_SA_DQ<27>")
	)
	(segment
		(start 404.342346 -234.692444)
		(end 404.342346 -234.281472)
		(width 0.14478)
		(layer "In4.Cu")
		(net "M_J_CPU0_SA_DQ<27>")
	)
	(segment
		(start 418.13988 -227.510086)
		(end 418.980112 -228.350318)
		(width 0.14478)
		(layer "In4.Cu")
		(net "M_J_CPU0_SA_DQ<27>")
	)
	(segment
		(start 426.736764 -228.350572)
		(end 429.06569 -228.350572)
		(width 0.14478)
		(layer "In4.Cu")
		(net "M_J_CPU0_SA_DQ<27>")
	)
	(segment
		(start 403.562058 -235.472732)
		(end 403.562058 -235.06176)
		(width 0.14478)
		(layer "In4.Cu")
		(net "M_J_CPU0_SA_DQ<27>")
	)
	(segment
		(start 433.26304 -227.769928)
		(end 433.424584 -227.931472)
		(width 0.14478)
		(layer "In4.Cu")
		(net "M_J_CPU0_SA_DQ<27>")
	)
	(segment
		(start 433.424584 -227.931472)
		(end 433.65293 -227.931472)
		(width 0.14478)
		(layer "In4.Cu")
		(net "M_J_CPU0_SA_DQ<27>")
	)
	(segment
		(start 402.78177 -236.25302)
		(end 402.78177 -235.842048)
		(width 0.14478)
		(layer "In4.Cu")
		(net "M_J_CPU0_SA_DQ<27>")
	)
	(segment
		(start 433.101496 -227.109782)
		(end 433.26304 -227.271326)
		(width 0.14478)
		(layer "In4.Cu")
		(net "M_J_CPU0_SA_DQ<27>")
	)
	(segment
		(start 399.47596 -239.55883)
		(end 399.660618 -239.374172)
		(width 0.14478)
		(layer "In4.Cu")
		(net "M_J_CPU0_SA_DQ<27>")
	)
	(segment
		(start 395.52372 -239.71123)
		(end 395.87805 -239.71123)
		(width 0.0889)
		(layer "In4.Cu")
		(net "M_J_CPU0_SA_DQ<27>")
	)
	(segment
		(start 388.093458 -240.916714)
		(end 388.10184 -240.92154)
		(width 0.0889)
		(layer "In4.Cu")
		(net "M_J_CPU0_SA_DQ<27>")
	)
	(segment
		(start 433.814474 -227.769928)
		(end 433.814474 -227.271326)
		(width 0.14478)
		(layer "In4.Cu")
		(net "M_J_CPU0_SA_DQ<27>")
	)
	(segment
		(start 418.980112 -228.350318)
		(end 421.346376 -228.350318)
		(width 0.14478)
		(layer "In4.Cu")
		(net "M_J_CPU0_SA_DQ<27>")
	)
	(segment
		(start 433.976018 -227.109782)
		(end 434.1749 -227.109782)
		(width 0.14478)
		(layer "In4.Cu")
		(net "M_J_CPU0_SA_DQ<27>")
	)
	(segment
		(start 429.06569 -228.350572)
		(end 429.915828 -227.500434)
		(width 0.14478)
		(layer "In4.Cu")
		(net "M_J_CPU0_SA_DQ<27>")
	)
	(segment
		(start 433.65293 -227.931472)
		(end 433.814474 -227.769928)
		(width 0.14478)
		(layer "In4.Cu")
		(net "M_J_CPU0_SA_DQ<27>")
	)
	(segment
		(start 379.30074 -240.97869)
		(end 379.323092 -240.895378)
		(width 0.0889)
		(layer "In4.Cu")
		(net "M_J_CPU0_SA_DQ<27>")
	)
	(segment
		(start 394.5636 -240.67135)
		(end 395.52372 -239.71123)
		(width 0.0889)
		(layer "In4.Cu")
		(net "M_J_CPU0_SA_DQ<27>")
	)
	(segment
		(start 404.342346 -234.281472)
		(end 404.527004 -234.096814)
		(width 0.14478)
		(layer "In4.Cu")
		(net "M_J_CPU0_SA_DQ<27>")
	)
	(segment
		(start 403.746716 -234.877102)
		(end 404.157688 -234.877102)
		(width 0.14478)
		(layer "In4.Cu")
		(net "M_J_CPU0_SA_DQ<27>")
	)
	(segment
		(start 429.915828 -227.500434)
		(end 431.84191 -227.500434)
		(width 0.14478)
		(layer "In4.Cu")
		(net "M_J_CPU0_SA_DQ<27>")
	)
	(segment
		(start 395.87805 -239.71123)
		(end 398.912588 -239.71123)
		(width 0.14478)
		(layer "In4.Cu")
		(net "M_J_CPU0_SA_DQ<27>")
	)
	(segment
		(start 402.18614 -236.437678)
		(end 402.597112 -236.437678)
		(width 0.14478)
		(layer "In4.Cu")
		(net "M_J_CPU0_SA_DQ<27>")
	)
	(segment
		(start 384.90779 -240.92154)
		(end 384.916172 -240.916714)
		(width 0.0889)
		(layer "In4.Cu")
		(net "M_J_CPU0_SA_DQ<27>")
	)
	(segment
		(start 400.440906 -238.593884)
		(end 400.440906 -238.182912)
		(width 0.14478)
		(layer "In4.Cu")
		(net "M_J_CPU0_SA_DQ<27>")
	)
	(segment
		(start 403.562058 -235.06176)
		(end 403.746716 -234.877102)
		(width 0.14478)
		(layer "In4.Cu")
		(net "M_J_CPU0_SA_DQ<27>")
	)
	(segment
		(start 399.660618 -238.9632)
		(end 399.845276 -238.778542)
		(width 0.14478)
		(layer "In4.Cu")
		(net "M_J_CPU0_SA_DQ<27>")
	)
	(segment
		(start 402.001482 -237.033308)
		(end 402.001482 -236.622336)
		(width 0.14478)
		(layer "In4.Cu")
		(net "M_J_CPU0_SA_DQ<27>")
	)
	(segment
		(start 399.845276 -238.778542)
		(end 400.256248 -238.778542)
		(width 0.14478)
		(layer "In4.Cu")
		(net "M_J_CPU0_SA_DQ<27>")
	)
	(segment
		(start 398.912588 -239.71123)
		(end 399.064988 -239.55883)
		(width 0.14478)
		(layer "In4.Cu")
		(net "M_J_CPU0_SA_DQ<27>")
	)
	(segment
		(start 384.333496 -240.916714)
		(end 384.341878 -240.92154)
		(width 0.0889)
		(layer "In4.Cu")
		(net "M_J_CPU0_SA_DQ<27>")
	)
	(segment
		(start 393.828016 -241.01171)
		(end 394.168376 -240.67135)
		(width 0.0889)
		(layer "In4.Cu")
		(net "M_J_CPU0_SA_DQ<27>")
	)
	(segment
		(start 434.1749 -227.109782)
		(end 435.000146 -227.935028)
		(width 0.14478)
		(layer "In4.Cu")
		(net "M_J_CPU0_SA_DQ<27>")
	)
	(segment
		(start 433.26304 -227.271326)
		(end 433.26304 -227.769928)
		(width 0.14478)
		(layer "In4.Cu")
		(net "M_J_CPU0_SA_DQ<27>")
	)
	(segment
		(start 403.3774 -235.65739)
		(end 403.562058 -235.472732)
		(width 0.14478)
		(layer "In4.Cu")
		(net "M_J_CPU0_SA_DQ<27>")
	)
	(segment
		(start 425.886626 -227.500434)
		(end 426.736764 -228.350572)
		(width 0.14478)
		(layer "In4.Cu")
		(net "M_J_CPU0_SA_DQ<27>")
	)
	(segment
		(start 414.855914 -227.510086)
		(end 418.13988 -227.510086)
		(width 0.14478)
		(layer "In4.Cu")
		(net "M_J_CPU0_SA_DQ<27>")
	)
	(segment
		(start 383.393442 -240.916714)
		(end 383.401824 -240.92154)
		(width 0.0889)
		(layer "In4.Cu")
		(net "M_J_CPU0_SA_DQ<27>")
	)
	(segment
		(start 392.810238 -240.93551)
		(end 392.925554 -240.983262)
		(width 0.0889)
		(layer "In4.Cu")
		(net "M_J_CPU0_SA_DQ<27>")
	)
	(segment
		(start 431.84191 -227.500434)
		(end 432.232562 -227.109782)
		(width 0.14478)
		(layer "In4.Cu")
		(net "M_J_CPU0_SA_DQ<27>")
	)
	(segment
		(start 401.221194 -237.813596)
		(end 401.221194 -237.402624)
		(width 0.14478)
		(layer "In4.Cu")
		(net "M_J_CPU0_SA_DQ<27>")
	)
	(segment
		(start 405.122634 -233.912156)
		(end 405.122634 -233.501184)
		(width 0.14478)
		(layer "In4.Cu")
		(net "M_J_CPU0_SA_DQ<27>")
	)
	(segment
		(start 400.440906 -238.182912)
		(end 400.625564 -237.998254)
		(width 0.14478)
		(layer "In4.Cu")
		(net "M_J_CPU0_SA_DQ<27>")
	)
	(segment
		(start 422.19626 -227.500434)
		(end 425.886626 -227.500434)
		(width 0.14478)
		(layer "In4.Cu")
		(net "M_J_CPU0_SA_DQ<27>")
	)
	(segment
		(start 405.122634 -233.501184)
		(end 410.263594 -228.360224)
		(width 0.14478)
		(layer "In4.Cu")
		(net "M_J_CPU0_SA_DQ<27>")
	)
	(segment
		(start 379.63348 -240.916714)
		(end 379.641862 -240.92154)
		(width 0.0889)
		(layer "In4.Cu")
		(net "M_J_CPU0_SA_DQ<27>")
	)
	(segment
		(start 379.454918 -241.24412)
		(end 379.30074 -240.97869)
		(width 0.0889)
		(layer "In4.Cu")
		(net "M_J_CPU0_SA_DQ<27>")
	)
	(segment
		(start 432.232562 -227.109782)
		(end 433.101496 -227.109782)
		(width 0.14478)
		(layer "In4.Cu")
		(net "M_J_CPU0_SA_DQ<27>")
	)
	(segment
		(start 380.207774 -240.92154)
		(end 380.216156 -240.916714)
		(width 0.0889)
		(layer "In4.Cu")
		(net "M_J_CPU0_SA_DQ<27>")
	)
	(segment
		(start 401.036536 -237.998254)
		(end 401.221194 -237.813596)
		(width 0.14478)
		(layer "In4.Cu")
		(net "M_J_CPU0_SA_DQ<27>")
	)
	(segment
		(start 401.405852 -237.217966)
		(end 401.816824 -237.217966)
		(width 0.14478)
		(layer "In4.Cu")
		(net "M_J_CPU0_SA_DQ<27>")
	)
	(segment
		(start 392.788648 -240.91392)
		(end 392.810238 -240.93551)
		(width 0.0889)
		(layer "In4.Cu")
		(net "M_J_CPU0_SA_DQ<27>")
	)
	(segment
		(start 392.413998 -240.930176)
		(end 392.42873 -240.92154)
		(width 0.0889)
		(layer "In4.Cu")
		(net "M_J_CPU0_SA_DQ<27>")
	)
	(segment
		(start 399.660618 -239.374172)
		(end 399.660618 -238.9632)
		(width 0.14478)
		(layer "In4.Cu")
		(net "M_J_CPU0_SA_DQ<27>")
	)
	(segment
		(start 393.068556 -241.01171)
		(end 393.828016 -241.01171)
		(width 0.0889)
		(layer "In4.Cu")
		(net "M_J_CPU0_SA_DQ<27>")
	)
	(segment
		(start 404.527004 -234.096814)
		(end 404.937976 -234.096814)
		(width 0.14478)
		(layer "In4.Cu")
		(net "M_J_CPU0_SA_DQ<27>")
	)
	(segment
		(start 402.78177 -235.842048)
		(end 402.966428 -235.65739)
		(width 0.14478)
		(layer "In4.Cu")
		(net "M_J_CPU0_SA_DQ<27>")
	)
	(segment
		(start 399.064988 -239.55883)
		(end 399.47596 -239.55883)
		(width 0.14478)
		(layer "In4.Cu")
		(net "M_J_CPU0_SA_DQ<27>")
	)
	(arc
		(start 379.323092 -240.895378)
		(mid 379.480602 -240.87218)
		(end 379.63348 -240.916714)
		(width 0.0889)
		(layer "In4.Cu")
		(net "M_J_CPU0_SA_DQ<27>")
	)
	(arc
		(start 380.581916 -240.92154)
		(mid 380.864872 -240.997717)
		(end 381.147828 -240.92154)
		(width 0.0889)
		(layer "In4.Cu")
		(net "M_J_CPU0_SA_DQ<27>")
	)
	(arc
		(start 386.221986 -240.92154)
		(mid 386.504942 -240.997717)
		(end 386.787898 -240.92154)
		(width 0.0889)
		(layer "In4.Cu")
		(net "M_J_CPU0_SA_DQ<27>")
	)
	(arc
		(start 389.616188 -240.916714)
		(mid 389.799696 -240.87122)
		(end 389.981948 -240.92154)
		(width 0.0889)
		(layer "In4.Cu")
		(net "M_J_CPU0_SA_DQ<27>")
	)
	(arc
		(start 382.087882 -240.92154)
		(mid 382.274826 -240.871285)
		(end 382.46177 -240.92154)
		(width 0.0889)
		(layer "In4.Cu")
		(net "M_J_CPU0_SA_DQ<27>")
	)
	(arc
		(start 381.15621 -240.916714)
		(mid 381.339718 -240.87122)
		(end 381.52197 -240.92154)
		(width 0.0889)
		(layer "In4.Cu")
		(net "M_J_CPU0_SA_DQ<27>")
	)
	(arc
		(start 385.281932 -240.92154)
		(mid 385.564888 -240.997717)
		(end 385.847844 -240.92154)
		(width 0.0889)
		(layer "In4.Cu")
		(net "M_J_CPU0_SA_DQ<27>")
	)
	(arc
		(start 390.921748 -240.92154)
		(mid 391.204704 -240.997717)
		(end 391.48766 -240.92154)
		(width 0.0889)
		(layer "In4.Cu")
		(net "M_J_CPU0_SA_DQ<27>")
	)
	(arc
		(start 387.727698 -240.92154)
		(mid 387.909949 -240.87119)
		(end 388.093458 -240.916714)
		(width 0.0889)
		(layer "In4.Cu")
		(net "M_J_CPU0_SA_DQ<27>")
	)
	(arc
		(start 383.967736 -240.92154)
		(mid 384.149987 -240.87119)
		(end 384.333496 -240.916714)
		(width 0.0889)
		(layer "In4.Cu")
		(net "M_J_CPU0_SA_DQ<27>")
	)
	(arc
		(start 391.496042 -240.916714)
		(mid 391.679804 -240.871098)
		(end 391.86231 -240.92154)
		(width 0.0889)
		(layer "In4.Cu")
		(net "M_J_CPU0_SA_DQ<27>")
	)
	(arc
		(start 388.10184 -240.92154)
		(mid 388.384796 -240.997717)
		(end 388.667752 -240.92154)
		(width 0.0889)
		(layer "In4.Cu")
		(net "M_J_CPU0_SA_DQ<27>")
	)
	(arc
		(start 388.667752 -240.92154)
		(mid 388.850003 -240.87119)
		(end 389.033512 -240.916714)
		(width 0.0889)
		(layer "In4.Cu")
		(net "M_J_CPU0_SA_DQ<27>")
	)
	(arc
		(start 390.54786 -240.92154)
		(mid 390.734804 -240.871285)
		(end 390.921748 -240.92154)
		(width 0.0889)
		(layer "In4.Cu")
		(net "M_J_CPU0_SA_DQ<27>")
	)
	(arc
		(start 385.856226 -240.916714)
		(mid 386.039734 -240.87122)
		(end 386.221986 -240.92154)
		(width 0.0889)
		(layer "In4.Cu")
		(net "M_J_CPU0_SA_DQ<27>")
	)
	(arc
		(start 389.981948 -240.92154)
		(mid 390.264904 -240.997717)
		(end 390.54786 -240.92154)
		(width 0.0889)
		(layer "In4.Cu")
		(net "M_J_CPU0_SA_DQ<27>")
	)
	(arc
		(start 386.787898 -240.92154)
		(mid 386.974842 -240.871285)
		(end 387.161786 -240.92154)
		(width 0.0889)
		(layer "In4.Cu")
		(net "M_J_CPU0_SA_DQ<27>")
	)
	(arc
		(start 391.86231 -240.92154)
		(mid 392.137016 -240.997904)
		(end 392.413998 -240.930176)
		(width 0.0889)
		(layer "In4.Cu")
		(net "M_J_CPU0_SA_DQ<27>")
	)
	(arc
		(start 382.46177 -240.92154)
		(mid 382.744726 -240.997717)
		(end 383.027682 -240.92154)
		(width 0.0889)
		(layer "In4.Cu")
		(net "M_J_CPU0_SA_DQ<27>")
	)
	(arc
		(start 383.401824 -240.92154)
		(mid 383.68478 -240.997717)
		(end 383.967736 -240.92154)
		(width 0.0889)
		(layer "In4.Cu")
		(net "M_J_CPU0_SA_DQ<27>")
	)
	(arc
		(start 389.041894 -240.92154)
		(mid 389.32485 -240.997717)
		(end 389.607806 -240.92154)
		(width 0.0889)
		(layer "In4.Cu")
		(net "M_J_CPU0_SA_DQ<27>")
	)
	(arc
		(start 381.52197 -240.92154)
		(mid 381.804926 -240.997717)
		(end 382.087882 -240.92154)
		(width 0.0889)
		(layer "In4.Cu")
		(net "M_J_CPU0_SA_DQ<27>")
	)
	(arc
		(start 379.641862 -240.92154)
		(mid 379.924818 -240.997717)
		(end 380.207774 -240.92154)
		(width 0.0889)
		(layer "In4.Cu")
		(net "M_J_CPU0_SA_DQ<27>")
	)
	(arc
		(start 384.916172 -240.916714)
		(mid 385.09968 -240.87122)
		(end 385.281932 -240.92154)
		(width 0.0889)
		(layer "In4.Cu")
		(net "M_J_CPU0_SA_DQ<27>")
	)
	(arc
		(start 380.216156 -240.916714)
		(mid 380.399664 -240.87122)
		(end 380.581916 -240.92154)
		(width 0.0889)
		(layer "In4.Cu")
		(net "M_J_CPU0_SA_DQ<27>")
	)
	(arc
		(start 384.341878 -240.92154)
		(mid 384.624834 -240.997717)
		(end 384.90779 -240.92154)
		(width 0.0889)
		(layer "In4.Cu")
		(net "M_J_CPU0_SA_DQ<27>")
	)
	(arc
		(start 392.42873 -240.92154)
		(mid 392.607717 -240.87137)
		(end 392.788648 -240.91392)
		(width 0.0889)
		(layer "In4.Cu")
		(net "M_J_CPU0_SA_DQ<27>")
	)
	(arc
		(start 383.027682 -240.92154)
		(mid 383.209933 -240.87119)
		(end 383.393442 -240.916714)
		(width 0.0889)
		(layer "In4.Cu")
		(net "M_J_CPU0_SA_DQ<27>")
	)
	(arc
		(start 387.161786 -240.92154)
		(mid 387.444742 -240.997717)
		(end 387.727698 -240.92154)
		(width 0.0889)
		(layer "In4.Cu")
		(net "M_J_CPU0_SA_DQ<27>")
	)
	(segment
		(start 380.39802 -240.700052)
		(end 380.864872 -240.434114)
		(width 0.10668)
		(layer "F.Cu")
		(net "M_J_CPU0_SA_DQ<26>")
	)
	(segment
		(start 413.315658 -226.349052)
		(end 413.626808 -226.660202)
		(width 0.14478)
		(layer "In4.Cu")
		(net "M_J_CPU0_SA_DQ<26>")
	)
	(segment
		(start 409.544266 -227.133404)
		(end 409.544266 -226.905312)
		(width 0.14478)
		(layer "In4.Cu")
		(net "M_J_CPU0_SA_DQ<26>")
	)
	(segment
		(start 421.580818 -226.660202)
		(end 422.430956 -225.810064)
		(width 0.14478)
		(layer "In4.Cu")
		(net "M_J_CPU0_SA_DQ<26>")
	)
	(segment
		(start 390.443466 -240.106708)
		(end 390.451848 -240.111534)
		(width 0.0889)
		(layer "In4.Cu")
		(net "M_J_CPU0_SA_DQ<26>")
	)
	(segment
		(start 393.689332 -240.060734)
		(end 394.498576 -239.25149)
		(width 0.0889)
		(layer "In4.Cu")
		(net "M_J_CPU0_SA_DQ<26>")
	)
	(segment
		(start 391.01776 -240.111534)
		(end 391.026142 -240.106708)
		(width 0.0889)
		(layer "In4.Cu")
		(net "M_J_CPU0_SA_DQ<26>")
	)
	(segment
		(start 412.21279 -226.349052)
		(end 412.52394 -226.660202)
		(width 0.14478)
		(layer "In4.Cu")
		(net "M_J_CPU0_SA_DQ<26>")
	)
	(segment
		(start 409.544266 -226.905312)
		(end 409.706318 -226.74326)
		(width 0.14478)
		(layer "In4.Cu")
		(net "M_J_CPU0_SA_DQ<26>")
	)
	(segment
		(start 411.972506 -226.349052)
		(end 412.21279 -226.349052)
		(width 0.14478)
		(layer "In4.Cu")
		(net "M_J_CPU0_SA_DQ<26>")
	)
	(segment
		(start 408.817572 -228.519736)
		(end 408.979624 -228.357684)
		(width 0.14478)
		(layer "In4.Cu")
		(net "M_J_CPU0_SA_DQ<26>")
	)
	(segment
		(start 407.419048 -229.690168)
		(end 407.203402 -229.474268)
		(width 0.14478)
		(layer "In4.Cu")
		(net "M_J_CPU0_SA_DQ<26>")
	)
	(segment
		(start 409.706318 -226.74326)
		(end 409.93441 -226.74326)
		(width 0.14478)
		(layer "In4.Cu")
		(net "M_J_CPU0_SA_DQ<26>")
	)
	(segment
		(start 395.105636 -239.25149)
		(end 395.555216 -238.80191)
		(width 0.0889)
		(layer "In4.Cu")
		(net "M_J_CPU0_SA_DQ<26>")
	)
	(segment
		(start 408.199336 -228.90988)
		(end 407.98369 -228.69398)
		(width 0.14478)
		(layer "In4.Cu")
		(net "M_J_CPU0_SA_DQ<26>")
	)
	(segment
		(start 412.52394 -226.660202)
		(end 412.764224 -226.660202)
		(width 0.14478)
		(layer "In4.Cu")
		(net "M_J_CPU0_SA_DQ<26>")
	)
	(segment
		(start 408.145742 -228.303836)
		(end 408.373834 -228.303836)
		(width 0.14478)
		(layer "In4.Cu")
		(net "M_J_CPU0_SA_DQ<26>")
	)
	(segment
		(start 395.885162 -238.80191)
		(end 398.535398 -238.80191)
		(width 0.14478)
		(layer "In4.Cu")
		(net "M_J_CPU0_SA_DQ<26>")
	)
	(segment
		(start 391.391902 -240.111534)
		(end 391.402316 -240.11763)
		(width 0.0889)
		(layer "In4.Cu")
		(net "M_J_CPU0_SA_DQ<26>")
	)
	(segment
		(start 426.712126 -226.660202)
		(end 429.003968 -226.660202)
		(width 0.14478)
		(layer "In4.Cu")
		(net "M_J_CPU0_SA_DQ<26>")
	)
	(segment
		(start 407.593546 -229.084124)
		(end 407.809192 -229.300024)
		(width 0.14478)
		(layer "In4.Cu")
		(net "M_J_CPU0_SA_DQ<26>")
	)
	(segment
		(start 410.677106 -226.660202)
		(end 411.661356 -226.660202)
		(width 0.14478)
		(layer "In4.Cu")
		(net "M_J_CPU0_SA_DQ<26>")
	)
	(segment
		(start 394.498576 -239.25149)
		(end 395.105636 -239.25149)
		(width 0.0889)
		(layer "In4.Cu")
		(net "M_J_CPU0_SA_DQ<26>")
	)
	(segment
		(start 412.764224 -226.660202)
		(end 413.075374 -226.349052)
		(width 0.14478)
		(layer "In4.Cu")
		(net "M_J_CPU0_SA_DQ<26>")
	)
	(segment
		(start 385.74345 -240.106708)
		(end 385.751832 -240.111534)
		(width 0.0889)
		(layer "In4.Cu")
		(net "M_J_CPU0_SA_DQ<26>")
	)
	(segment
		(start 393.084812 -240.060734)
		(end 393.689332 -240.060734)
		(width 0.0889)
		(layer "In4.Cu")
		(net "M_J_CPU0_SA_DQ<26>")
	)
	(segment
		(start 409.59786 -227.739448)
		(end 409.759912 -227.577396)
		(width 0.14478)
		(layer "In4.Cu")
		(net "M_J_CPU0_SA_DQ<26>")
	)
	(segment
		(start 434.575204 -225.810064)
		(end 435.000146 -226.235006)
		(width 0.14478)
		(layer "In4.Cu")
		(net "M_J_CPU0_SA_DQ<26>")
	)
	(segment
		(start 408.199336 -229.137972)
		(end 408.199336 -228.90988)
		(width 0.14478)
		(layer "In4.Cu")
		(net "M_J_CPU0_SA_DQ<26>")
	)
	(segment
		(start 408.979624 -228.357684)
		(end 408.979624 -228.129592)
		(width 0.14478)
		(layer "In4.Cu")
		(net "M_J_CPU0_SA_DQ<26>")
	)
	(segment
		(start 425.861988 -225.810064)
		(end 426.712126 -226.660202)
		(width 0.14478)
		(layer "In4.Cu")
		(net "M_J_CPU0_SA_DQ<26>")
	)
	(segment
		(start 407.203402 -229.246176)
		(end 407.365454 -229.084124)
		(width 0.14478)
		(layer "In4.Cu")
		(net "M_J_CPU0_SA_DQ<26>")
	)
	(segment
		(start 408.979624 -228.129592)
		(end 408.763978 -227.913692)
		(width 0.14478)
		(layer "In4.Cu")
		(net "M_J_CPU0_SA_DQ<26>")
	)
	(segment
		(start 413.075374 -226.349052)
		(end 413.315658 -226.349052)
		(width 0.14478)
		(layer "In4.Cu")
		(net "M_J_CPU0_SA_DQ<26>")
	)
	(segment
		(start 409.369768 -227.739448)
		(end 409.59786 -227.739448)
		(width 0.14478)
		(layer "In4.Cu")
		(net "M_J_CPU0_SA_DQ<26>")
	)
	(segment
		(start 392.324336 -240.106708)
		(end 392.332718 -240.111534)
		(width 0.0889)
		(layer "In4.Cu")
		(net "M_J_CPU0_SA_DQ<26>")
	)
	(segment
		(start 388.197852 -240.111534)
		(end 388.206234 -240.106708)
		(width 0.0889)
		(layer "In4.Cu")
		(net "M_J_CPU0_SA_DQ<26>")
	)
	(segment
		(start 382.557782 -240.111534)
		(end 382.566164 -240.106708)
		(width 0.0889)
		(layer "In4.Cu")
		(net "M_J_CPU0_SA_DQ<26>")
	)
	(segment
		(start 410.378148 -226.95916)
		(end 410.677106 -226.660202)
		(width 0.14478)
		(layer "In4.Cu")
		(net "M_J_CPU0_SA_DQ<26>")
	)
	(segment
		(start 407.809192 -229.300024)
		(end 408.037284 -229.300024)
		(width 0.14478)
		(layer "In4.Cu")
		(net "M_J_CPU0_SA_DQ<26>")
	)
	(segment
		(start 408.58948 -228.519736)
		(end 408.817572 -228.519736)
		(width 0.14478)
		(layer "In4.Cu")
		(net "M_J_CPU0_SA_DQ<26>")
	)
	(segment
		(start 408.373834 -228.303836)
		(end 408.58948 -228.519736)
		(width 0.14478)
		(layer "In4.Cu")
		(net "M_J_CPU0_SA_DQ<26>")
	)
	(segment
		(start 408.037284 -229.300024)
		(end 408.199336 -229.137972)
		(width 0.14478)
		(layer "In4.Cu")
		(net "M_J_CPU0_SA_DQ<26>")
	)
	(segment
		(start 381.983488 -240.106708)
		(end 381.99187 -240.111534)
		(width 0.0889)
		(layer "In4.Cu")
		(net "M_J_CPU0_SA_DQ<26>")
	)
	(segment
		(start 408.763978 -227.6856)
		(end 408.92603 -227.523548)
		(width 0.14478)
		(layer "In4.Cu")
		(net "M_J_CPU0_SA_DQ<26>")
	)
	(segment
		(start 398.535398 -238.80191)
		(end 407.419048 -229.91826)
		(width 0.14478)
		(layer "In4.Cu")
		(net "M_J_CPU0_SA_DQ<26>")
	)
	(segment
		(start 414.239456 -226.660202)
		(end 415.089594 -225.810064)
		(width 0.14478)
		(layer "In4.Cu")
		(net "M_J_CPU0_SA_DQ<26>")
	)
	(segment
		(start 422.430956 -225.810064)
		(end 425.861988 -225.810064)
		(width 0.14478)
		(layer "In4.Cu")
		(net "M_J_CPU0_SA_DQ<26>")
	)
	(segment
		(start 418.732462 -226.660202)
		(end 421.580818 -226.660202)
		(width 0.14478)
		(layer "In4.Cu")
		(net "M_J_CPU0_SA_DQ<26>")
	)
	(segment
		(start 409.759912 -227.349304)
		(end 409.544266 -227.133404)
		(width 0.14478)
		(layer "In4.Cu")
		(net "M_J_CPU0_SA_DQ<26>")
	)
	(segment
		(start 386.683504 -240.106708)
		(end 386.691886 -240.111534)
		(width 0.0889)
		(layer "In4.Cu")
		(net "M_J_CPU0_SA_DQ<26>")
	)
	(segment
		(start 380.864872 -240.434114)
		(end 380.710694 -240.168684)
		(width 0.0889)
		(layer "In4.Cu")
		(net "M_J_CPU0_SA_DQ<26>")
	)
	(segment
		(start 417.882324 -225.810064)
		(end 418.732462 -226.660202)
		(width 0.14478)
		(layer "In4.Cu")
		(net "M_J_CPU0_SA_DQ<26>")
	)
	(segment
		(start 409.93441 -226.74326)
		(end 410.150056 -226.95916)
		(width 0.14478)
		(layer "In4.Cu")
		(net "M_J_CPU0_SA_DQ<26>")
	)
	(segment
		(start 381.043434 -240.106708)
		(end 381.051816 -240.111534)
		(width 0.0889)
		(layer "In4.Cu")
		(net "M_J_CPU0_SA_DQ<26>")
	)
	(segment
		(start 380.710694 -240.168684)
		(end 380.733046 -240.085372)
		(width 0.0889)
		(layer "In4.Cu")
		(net "M_J_CPU0_SA_DQ<26>")
	)
	(segment
		(start 408.92603 -227.523548)
		(end 409.154122 -227.523548)
		(width 0.14478)
		(layer "In4.Cu")
		(net "M_J_CPU0_SA_DQ<26>")
	)
	(segment
		(start 409.759912 -227.577396)
		(end 409.759912 -227.349304)
		(width 0.14478)
		(layer "In4.Cu")
		(net "M_J_CPU0_SA_DQ<26>")
	)
	(segment
		(start 407.98369 -228.465888)
		(end 408.145742 -228.303836)
		(width 0.14478)
		(layer "In4.Cu")
		(net "M_J_CPU0_SA_DQ<26>")
	)
	(segment
		(start 407.203402 -229.474268)
		(end 407.203402 -229.246176)
		(width 0.14478)
		(layer "In4.Cu")
		(net "M_J_CPU0_SA_DQ<26>")
	)
	(segment
		(start 410.150056 -226.95916)
		(end 410.378148 -226.95916)
		(width 0.14478)
		(layer "In4.Cu")
		(net "M_J_CPU0_SA_DQ<26>")
	)
	(segment
		(start 407.365454 -229.084124)
		(end 407.593546 -229.084124)
		(width 0.14478)
		(layer "In4.Cu")
		(net "M_J_CPU0_SA_DQ<26>")
	)
	(segment
		(start 429.003968 -226.660202)
		(end 429.854106 -225.810064)
		(width 0.14478)
		(layer "In4.Cu")
		(net "M_J_CPU0_SA_DQ<26>")
	)
	(segment
		(start 395.555216 -238.80191)
		(end 395.885162 -238.80191)
		(width 0.0889)
		(layer "In4.Cu")
		(net "M_J_CPU0_SA_DQ<26>")
	)
	(segment
		(start 383.497836 -240.111534)
		(end 383.506218 -240.106708)
		(width 0.0889)
		(layer "In4.Cu")
		(net "M_J_CPU0_SA_DQ<26>")
	)
	(segment
		(start 413.626808 -226.660202)
		(end 414.239456 -226.660202)
		(width 0.14478)
		(layer "In4.Cu")
		(net "M_J_CPU0_SA_DQ<26>")
	)
	(segment
		(start 429.854106 -225.810064)
		(end 434.575204 -225.810064)
		(width 0.14478)
		(layer "In4.Cu")
		(net "M_J_CPU0_SA_DQ<26>")
	)
	(segment
		(start 407.98369 -228.69398)
		(end 407.98369 -228.465888)
		(width 0.14478)
		(layer "In4.Cu")
		(net "M_J_CPU0_SA_DQ<26>")
	)
	(segment
		(start 387.257798 -240.111534)
		(end 387.26618 -240.106708)
		(width 0.0889)
		(layer "In4.Cu")
		(net "M_J_CPU0_SA_DQ<26>")
	)
	(segment
		(start 408.763978 -227.913692)
		(end 408.763978 -227.6856)
		(width 0.14478)
		(layer "In4.Cu")
		(net "M_J_CPU0_SA_DQ<26>")
	)
	(segment
		(start 415.089594 -225.810064)
		(end 417.882324 -225.810064)
		(width 0.14478)
		(layer "In4.Cu")
		(net "M_J_CPU0_SA_DQ<26>")
	)
	(segment
		(start 407.419048 -229.91826)
		(end 407.419048 -229.690168)
		(width 0.14478)
		(layer "In4.Cu")
		(net "M_J_CPU0_SA_DQ<26>")
	)
	(segment
		(start 411.661356 -226.660202)
		(end 411.972506 -226.349052)
		(width 0.14478)
		(layer "In4.Cu")
		(net "M_J_CPU0_SA_DQ<26>")
	)
	(segment
		(start 409.154122 -227.523548)
		(end 409.369768 -227.739448)
		(width 0.14478)
		(layer "In4.Cu")
		(net "M_J_CPU0_SA_DQ<26>")
	)
	(arc
		(start 383.506218 -240.106708)
		(mid 383.689726 -240.061214)
		(end 383.871978 -240.111534)
		(width 0.0889)
		(layer "In4.Cu")
		(net "M_J_CPU0_SA_DQ<26>")
	)
	(arc
		(start 389.511794 -240.111534)
		(mid 389.79475 -240.187711)
		(end 390.077706 -240.111534)
		(width 0.0889)
		(layer "In4.Cu")
		(net "M_J_CPU0_SA_DQ<26>")
	)
	(arc
		(start 386.317744 -240.111534)
		(mid 386.499995 -240.061184)
		(end 386.683504 -240.106708)
		(width 0.0889)
		(layer "In4.Cu")
		(net "M_J_CPU0_SA_DQ<26>")
	)
	(arc
		(start 384.43789 -240.111534)
		(mid 384.624834 -240.061279)
		(end 384.811778 -240.111534)
		(width 0.0889)
		(layer "In4.Cu")
		(net "M_J_CPU0_SA_DQ<26>")
	)
	(arc
		(start 381.99187 -240.111534)
		(mid 382.274826 -240.187711)
		(end 382.557782 -240.111534)
		(width 0.0889)
		(layer "In4.Cu")
		(net "M_J_CPU0_SA_DQ<26>")
	)
	(arc
		(start 382.566164 -240.106708)
		(mid 382.749672 -240.061214)
		(end 382.931924 -240.111534)
		(width 0.0889)
		(layer "In4.Cu")
		(net "M_J_CPU0_SA_DQ<26>")
	)
	(arc
		(start 392.332718 -240.111534)
		(mid 392.612146 -240.1877)
		(end 392.892534 -240.11509)
		(width 0.0889)
		(layer "In4.Cu")
		(net "M_J_CPU0_SA_DQ<26>")
	)
	(arc
		(start 385.751832 -240.111534)
		(mid 386.034788 -240.187711)
		(end 386.317744 -240.111534)
		(width 0.0889)
		(layer "In4.Cu")
		(net "M_J_CPU0_SA_DQ<26>")
	)
	(arc
		(start 380.733046 -240.085372)
		(mid 380.890556 -240.062174)
		(end 381.043434 -240.106708)
		(width 0.0889)
		(layer "In4.Cu")
		(net "M_J_CPU0_SA_DQ<26>")
	)
	(arc
		(start 390.077706 -240.111534)
		(mid 390.259957 -240.061184)
		(end 390.443466 -240.106708)
		(width 0.0889)
		(layer "In4.Cu")
		(net "M_J_CPU0_SA_DQ<26>")
	)
	(arc
		(start 381.051816 -240.111534)
		(mid 381.334772 -240.187711)
		(end 381.617728 -240.111534)
		(width 0.0889)
		(layer "In4.Cu")
		(net "M_J_CPU0_SA_DQ<26>")
	)
	(arc
		(start 389.137906 -240.111534)
		(mid 389.32485 -240.061279)
		(end 389.511794 -240.111534)
		(width 0.0889)
		(layer "In4.Cu")
		(net "M_J_CPU0_SA_DQ<26>")
	)
	(arc
		(start 391.402316 -240.11763)
		(mid 391.681002 -240.18785)
		(end 391.958068 -240.111534)
		(width 0.0889)
		(layer "In4.Cu")
		(net "M_J_CPU0_SA_DQ<26>")
	)
	(arc
		(start 383.871978 -240.111534)
		(mid 384.154934 -240.187711)
		(end 384.43789 -240.111534)
		(width 0.0889)
		(layer "In4.Cu")
		(net "M_J_CPU0_SA_DQ<26>")
	)
	(arc
		(start 386.691886 -240.111534)
		(mid 386.974842 -240.187711)
		(end 387.257798 -240.111534)
		(width 0.0889)
		(layer "In4.Cu")
		(net "M_J_CPU0_SA_DQ<26>")
	)
	(arc
		(start 385.37769 -240.111534)
		(mid 385.559941 -240.061184)
		(end 385.74345 -240.106708)
		(width 0.0889)
		(layer "In4.Cu")
		(net "M_J_CPU0_SA_DQ<26>")
	)
	(arc
		(start 392.892534 -240.11509)
		(mid 392.984966 -240.074808)
		(end 393.084812 -240.060734)
		(width 0.0889)
		(layer "In4.Cu")
		(net "M_J_CPU0_SA_DQ<26>")
	)
	(arc
		(start 384.811778 -240.111534)
		(mid 385.094734 -240.187711)
		(end 385.37769 -240.111534)
		(width 0.0889)
		(layer "In4.Cu")
		(net "M_J_CPU0_SA_DQ<26>")
	)
	(arc
		(start 390.451848 -240.111534)
		(mid 390.734804 -240.187711)
		(end 391.01776 -240.111534)
		(width 0.0889)
		(layer "In4.Cu")
		(net "M_J_CPU0_SA_DQ<26>")
	)
	(arc
		(start 391.026142 -240.106708)
		(mid 391.20965 -240.061214)
		(end 391.391902 -240.111534)
		(width 0.0889)
		(layer "In4.Cu")
		(net "M_J_CPU0_SA_DQ<26>")
	)
	(arc
		(start 388.206234 -240.106708)
		(mid 388.389742 -240.061214)
		(end 388.571994 -240.111534)
		(width 0.0889)
		(layer "In4.Cu")
		(net "M_J_CPU0_SA_DQ<26>")
	)
	(arc
		(start 388.571994 -240.111534)
		(mid 388.85495 -240.187711)
		(end 389.137906 -240.111534)
		(width 0.0889)
		(layer "In4.Cu")
		(net "M_J_CPU0_SA_DQ<26>")
	)
	(arc
		(start 391.958068 -240.111534)
		(mid 392.140573 -240.061057)
		(end 392.324336 -240.106708)
		(width 0.0889)
		(layer "In4.Cu")
		(net "M_J_CPU0_SA_DQ<26>")
	)
	(arc
		(start 382.931924 -240.111534)
		(mid 383.21488 -240.187711)
		(end 383.497836 -240.111534)
		(width 0.0889)
		(layer "In4.Cu")
		(net "M_J_CPU0_SA_DQ<26>")
	)
	(arc
		(start 381.617728 -240.111534)
		(mid 381.799979 -240.061184)
		(end 381.983488 -240.106708)
		(width 0.0889)
		(layer "In4.Cu")
		(net "M_J_CPU0_SA_DQ<26>")
	)
	(arc
		(start 387.63194 -240.111534)
		(mid 387.914896 -240.187711)
		(end 388.197852 -240.111534)
		(width 0.0889)
		(layer "In4.Cu")
		(net "M_J_CPU0_SA_DQ<26>")
	)
	(arc
		(start 387.26618 -240.106708)
		(mid 387.449688 -240.061214)
		(end 387.63194 -240.111534)
		(width 0.0889)
		(layer "In4.Cu")
		(net "M_J_CPU0_SA_DQ<26>")
	)
	(segment
		(start 378.517912 -240.700052)
		(end 378.984764 -240.434114)
		(width 0.10668)
		(layer "F.Cu")
		(net "M_J_CPU0_SA_DQ<25>")
	)
	(segment
		(start 379.138942 -240.699544)
		(end 379.235208 -240.724944)
		(width 0.0889)
		(layer "In4.Cu")
		(net "M_J_CPU0_SA_DQ<25>")
	)
	(segment
		(start 382.557782 -240.756694)
		(end 382.566164 -240.76152)
		(width 0.0889)
		(layer "In4.Cu")
		(net "M_J_CPU0_SA_DQ<25>")
	)
	(segment
		(start 378.984764 -240.434114)
		(end 379.138942 -240.699544)
		(width 0.0889)
		(layer "In4.Cu")
		(net "M_J_CPU0_SA_DQ<25>")
	)
	(segment
		(start 425.210478 -226.660202)
		(end 427.262544 -227.510086)
		(width 0.14478)
		(layer "In4.Cu")
		(net "M_J_CPU0_SA_DQ<25>")
	)
	(segment
		(start 420.922958 -227.510086)
		(end 422.97477 -226.660202)
		(width 0.14478)
		(layer "In4.Cu")
		(net "M_J_CPU0_SA_DQ<25>")
	)
	(segment
		(start 422.97477 -226.660202)
		(end 425.210478 -226.660202)
		(width 0.14478)
		(layer "In4.Cu")
		(net "M_J_CPU0_SA_DQ<25>")
	)
	(segment
		(start 427.262544 -227.510086)
		(end 428.57293 -227.510086)
		(width 0.14478)
		(layer "In4.Cu")
		(net "M_J_CPU0_SA_DQ<25>")
	)
	(segment
		(start 413.455104 -227.510086)
		(end 415.506916 -226.660202)
		(width 0.14478)
		(layer "In4.Cu")
		(net "M_J_CPU0_SA_DQ<25>")
	)
	(segment
		(start 395.843506 -239.25657)
		(end 398.72412 -239.25657)
		(width 0.14478)
		(layer "In4.Cu")
		(net "M_J_CPU0_SA_DQ<25>")
	)
	(segment
		(start 393.608052 -240.756694)
		(end 394.325856 -240.03889)
		(width 0.0889)
		(layer "In4.Cu")
		(net "M_J_CPU0_SA_DQ<25>")
	)
	(segment
		(start 381.983488 -240.76152)
		(end 381.99187 -240.756694)
		(width 0.0889)
		(layer "In4.Cu")
		(net "M_J_CPU0_SA_DQ<25>")
	)
	(segment
		(start 394.325856 -240.03889)
		(end 394.325856 -239.73155)
		(width 0.0889)
		(layer "In4.Cu")
		(net "M_J_CPU0_SA_DQ<25>")
	)
	(segment
		(start 415.506916 -226.660202)
		(end 417.452556 -226.660202)
		(width 0.14478)
		(layer "In4.Cu")
		(net "M_J_CPU0_SA_DQ<25>")
	)
	(segment
		(start 436.96382 -226.660202)
		(end 439.100214 -227.085144)
		(width 0.14478)
		(layer "In4.Cu")
		(net "M_J_CPU0_SA_DQ<25>")
	)
	(segment
		(start 395.344396 -239.52073)
		(end 395.608556 -239.25657)
		(width 0.0889)
		(layer "In4.Cu")
		(net "M_J_CPU0_SA_DQ<25>")
	)
	(segment
		(start 410.470604 -227.510086)
		(end 413.455104 -227.510086)
		(width 0.14478)
		(layer "In4.Cu")
		(net "M_J_CPU0_SA_DQ<25>")
	)
	(segment
		(start 390.443466 -240.76152)
		(end 390.451848 -240.756694)
		(width 0.0889)
		(layer "In4.Cu")
		(net "M_J_CPU0_SA_DQ<25>")
	)
	(segment
		(start 387.257798 -240.756694)
		(end 387.26618 -240.76152)
		(width 0.0889)
		(layer "In4.Cu")
		(net "M_J_CPU0_SA_DQ<25>")
	)
	(segment
		(start 394.536676 -239.52073)
		(end 395.344396 -239.52073)
		(width 0.0889)
		(layer "In4.Cu")
		(net "M_J_CPU0_SA_DQ<25>")
	)
	(segment
		(start 388.197852 -240.756694)
		(end 388.206234 -240.76152)
		(width 0.0889)
		(layer "In4.Cu")
		(net "M_J_CPU0_SA_DQ<25>")
	)
	(segment
		(start 385.74345 -240.76152)
		(end 385.751832 -240.756694)
		(width 0.0889)
		(layer "In4.Cu")
		(net "M_J_CPU0_SA_DQ<25>")
	)
	(segment
		(start 392.321034 -240.763552)
		(end 392.332718 -240.756694)
		(width 0.0889)
		(layer "In4.Cu")
		(net "M_J_CPU0_SA_DQ<25>")
	)
	(segment
		(start 386.683504 -240.76152)
		(end 386.691886 -240.756694)
		(width 0.0889)
		(layer "In4.Cu")
		(net "M_J_CPU0_SA_DQ<25>")
	)
	(segment
		(start 428.57293 -227.510086)
		(end 430.624996 -226.660202)
		(width 0.14478)
		(layer "In4.Cu")
		(net "M_J_CPU0_SA_DQ<25>")
	)
	(segment
		(start 430.624996 -226.660202)
		(end 436.96382 -226.660202)
		(width 0.14478)
		(layer "In4.Cu")
		(net "M_J_CPU0_SA_DQ<25>")
	)
	(segment
		(start 419.504368 -227.510086)
		(end 420.922958 -227.510086)
		(width 0.14478)
		(layer "In4.Cu")
		(net "M_J_CPU0_SA_DQ<25>")
	)
	(segment
		(start 395.608556 -239.25657)
		(end 395.843506 -239.25657)
		(width 0.0889)
		(layer "In4.Cu")
		(net "M_J_CPU0_SA_DQ<25>")
	)
	(segment
		(start 393.272264 -240.756694)
		(end 393.608052 -240.756694)
		(width 0.0889)
		(layer "In4.Cu")
		(net "M_J_CPU0_SA_DQ<25>")
	)
	(segment
		(start 417.452556 -226.660202)
		(end 419.504368 -227.510086)
		(width 0.14478)
		(layer "In4.Cu")
		(net "M_J_CPU0_SA_DQ<25>")
	)
	(segment
		(start 392.892534 -240.753138)
		(end 392.898122 -240.75644)
		(width 0.0889)
		(layer "In4.Cu")
		(net "M_J_CPU0_SA_DQ<25>")
	)
	(segment
		(start 392.898122 -240.75644)
		(end 392.91641 -240.766854)
		(width 0.0889)
		(layer "In4.Cu")
		(net "M_J_CPU0_SA_DQ<25>")
	)
	(segment
		(start 391.01776 -240.756694)
		(end 391.026142 -240.76152)
		(width 0.0889)
		(layer "In4.Cu")
		(net "M_J_CPU0_SA_DQ<25>")
	)
	(segment
		(start 391.391902 -240.756694)
		(end 391.406634 -240.748058)
		(width 0.0889)
		(layer "In4.Cu")
		(net "M_J_CPU0_SA_DQ<25>")
	)
	(segment
		(start 394.325856 -239.73155)
		(end 394.536676 -239.52073)
		(width 0.0889)
		(layer "In4.Cu")
		(net "M_J_CPU0_SA_DQ<25>")
	)
	(segment
		(start 383.497836 -240.756694)
		(end 383.506218 -240.76152)
		(width 0.0889)
		(layer "In4.Cu")
		(net "M_J_CPU0_SA_DQ<25>")
	)
	(segment
		(start 381.043434 -240.76152)
		(end 381.051816 -240.756694)
		(width 0.0889)
		(layer "In4.Cu")
		(net "M_J_CPU0_SA_DQ<25>")
	)
	(segment
		(start 398.72412 -239.25657)
		(end 410.470604 -227.510086)
		(width 0.14478)
		(layer "In4.Cu")
		(net "M_J_CPU0_SA_DQ<25>")
	)
	(arc
		(start 391.406634 -240.748058)
		(mid 391.683617 -240.680254)
		(end 391.958322 -240.756694)
		(width 0.0889)
		(layer "In4.Cu")
		(net "M_J_CPU0_SA_DQ<25>")
	)
	(arc
		(start 382.566164 -240.76152)
		(mid 382.749672 -240.807014)
		(end 382.931924 -240.756694)
		(width 0.0889)
		(layer "In4.Cu")
		(net "M_J_CPU0_SA_DQ<25>")
	)
	(arc
		(start 379.737874 -240.756694)
		(mid 379.924818 -240.806949)
		(end 380.111762 -240.756694)
		(width 0.0889)
		(layer "In4.Cu")
		(net "M_J_CPU0_SA_DQ<25>")
	)
	(arc
		(start 391.026142 -240.76152)
		(mid 391.20965 -240.807014)
		(end 391.391902 -240.756694)
		(width 0.0889)
		(layer "In4.Cu")
		(net "M_J_CPU0_SA_DQ<25>")
	)
	(arc
		(start 380.111762 -240.756694)
		(mid 380.394718 -240.680517)
		(end 380.677674 -240.756694)
		(width 0.0889)
		(layer "In4.Cu")
		(net "M_J_CPU0_SA_DQ<25>")
	)
	(arc
		(start 383.871978 -240.756694)
		(mid 384.154934 -240.680517)
		(end 384.43789 -240.756694)
		(width 0.0889)
		(layer "In4.Cu")
		(net "M_J_CPU0_SA_DQ<25>")
	)
	(arc
		(start 391.958322 -240.756694)
		(mid 392.13878 -240.807138)
		(end 392.321034 -240.763552)
		(width 0.0889)
		(layer "In4.Cu")
		(net "M_J_CPU0_SA_DQ<25>")
	)
	(arc
		(start 389.511794 -240.756694)
		(mid 389.79475 -240.680517)
		(end 390.077706 -240.756694)
		(width 0.0889)
		(layer "In4.Cu")
		(net "M_J_CPU0_SA_DQ<25>")
	)
	(arc
		(start 381.617728 -240.756694)
		(mid 381.799979 -240.807044)
		(end 381.983488 -240.76152)
		(width 0.0889)
		(layer "In4.Cu")
		(net "M_J_CPU0_SA_DQ<25>")
	)
	(arc
		(start 386.317744 -240.756694)
		(mid 386.499995 -240.807044)
		(end 386.683504 -240.76152)
		(width 0.0889)
		(layer "In4.Cu")
		(net "M_J_CPU0_SA_DQ<25>")
	)
	(arc
		(start 386.691886 -240.756694)
		(mid 386.974842 -240.680517)
		(end 387.257798 -240.756694)
		(width 0.0889)
		(layer "In4.Cu")
		(net "M_J_CPU0_SA_DQ<25>")
	)
	(arc
		(start 392.91641 -240.766854)
		(mid 393.095639 -240.807007)
		(end 393.272264 -240.756694)
		(width 0.0889)
		(layer "In4.Cu")
		(net "M_J_CPU0_SA_DQ<25>")
	)
	(arc
		(start 387.63194 -240.756694)
		(mid 387.914896 -240.680517)
		(end 388.197852 -240.756694)
		(width 0.0889)
		(layer "In4.Cu")
		(net "M_J_CPU0_SA_DQ<25>")
	)
	(arc
		(start 381.99187 -240.756694)
		(mid 382.274826 -240.680517)
		(end 382.557782 -240.756694)
		(width 0.0889)
		(layer "In4.Cu")
		(net "M_J_CPU0_SA_DQ<25>")
	)
	(arc
		(start 390.451848 -240.756694)
		(mid 390.734804 -240.680517)
		(end 391.01776 -240.756694)
		(width 0.0889)
		(layer "In4.Cu")
		(net "M_J_CPU0_SA_DQ<25>")
	)
	(arc
		(start 382.931924 -240.756694)
		(mid 383.21488 -240.680517)
		(end 383.497836 -240.756694)
		(width 0.0889)
		(layer "In4.Cu")
		(net "M_J_CPU0_SA_DQ<25>")
	)
	(arc
		(start 392.332718 -240.756694)
		(mid 392.612146 -240.680528)
		(end 392.892534 -240.753138)
		(width 0.0889)
		(layer "In4.Cu")
		(net "M_J_CPU0_SA_DQ<25>")
	)
	(arc
		(start 383.506218 -240.76152)
		(mid 383.689726 -240.807014)
		(end 383.871978 -240.756694)
		(width 0.0889)
		(layer "In4.Cu")
		(net "M_J_CPU0_SA_DQ<25>")
	)
	(arc
		(start 388.571994 -240.756694)
		(mid 388.85495 -240.680517)
		(end 389.137906 -240.756694)
		(width 0.0889)
		(layer "In4.Cu")
		(net "M_J_CPU0_SA_DQ<25>")
	)
	(arc
		(start 390.077706 -240.756694)
		(mid 390.259957 -240.807044)
		(end 390.443466 -240.76152)
		(width 0.0889)
		(layer "In4.Cu")
		(net "M_J_CPU0_SA_DQ<25>")
	)
	(arc
		(start 384.811778 -240.756694)
		(mid 385.094734 -240.680517)
		(end 385.37769 -240.756694)
		(width 0.0889)
		(layer "In4.Cu")
		(net "M_J_CPU0_SA_DQ<25>")
	)
	(arc
		(start 387.26618 -240.76152)
		(mid 387.449688 -240.807014)
		(end 387.63194 -240.756694)
		(width 0.0889)
		(layer "In4.Cu")
		(net "M_J_CPU0_SA_DQ<25>")
	)
	(arc
		(start 379.235208 -240.724944)
		(mid 379.490273 -240.681593)
		(end 379.737874 -240.756694)
		(width 0.0889)
		(layer "In4.Cu")
		(net "M_J_CPU0_SA_DQ<25>")
	)
	(arc
		(start 381.051816 -240.756694)
		(mid 381.334772 -240.680517)
		(end 381.617728 -240.756694)
		(width 0.0889)
		(layer "In4.Cu")
		(net "M_J_CPU0_SA_DQ<25>")
	)
	(arc
		(start 385.37769 -240.756694)
		(mid 385.559941 -240.807044)
		(end 385.74345 -240.76152)
		(width 0.0889)
		(layer "In4.Cu")
		(net "M_J_CPU0_SA_DQ<25>")
	)
	(arc
		(start 380.677674 -240.756694)
		(mid 380.859925 -240.807044)
		(end 381.043434 -240.76152)
		(width 0.0889)
		(layer "In4.Cu")
		(net "M_J_CPU0_SA_DQ<25>")
	)
	(arc
		(start 385.751832 -240.756694)
		(mid 386.034788 -240.680517)
		(end 386.317744 -240.756694)
		(width 0.0889)
		(layer "In4.Cu")
		(net "M_J_CPU0_SA_DQ<25>")
	)
	(arc
		(start 389.137906 -240.756694)
		(mid 389.32485 -240.806949)
		(end 389.511794 -240.756694)
		(width 0.0889)
		(layer "In4.Cu")
		(net "M_J_CPU0_SA_DQ<25>")
	)
	(arc
		(start 384.43789 -240.756694)
		(mid 384.624834 -240.806949)
		(end 384.811778 -240.756694)
		(width 0.0889)
		(layer "In4.Cu")
		(net "M_J_CPU0_SA_DQ<25>")
	)
	(arc
		(start 388.206234 -240.76152)
		(mid 388.389742 -240.807014)
		(end 388.571994 -240.756694)
		(width 0.0889)
		(layer "In4.Cu")
		(net "M_J_CPU0_SA_DQ<25>")
	)
	(segment
		(start 379.927866 -239.890046)
		(end 380.394718 -239.624108)
		(width 0.10668)
		(layer "F.Cu")
		(net "M_J_CPU0_SA_DQ<24>")
	)
	(segment
		(start 418.566854 -225.810064)
		(end 421.625014 -225.810064)
		(width 0.14478)
		(layer "In4.Cu")
		(net "M_J_CPU0_SA_DQ<24>")
	)
	(segment
		(start 383.393442 -239.951514)
		(end 383.401824 -239.946688)
		(width 0.0889)
		(layer "In4.Cu")
		(net "M_J_CPU0_SA_DQ<24>")
	)
	(segment
		(start 422.474898 -224.96018)
		(end 425.692062 -224.96018)
		(width 0.14478)
		(layer "In4.Cu")
		(net "M_J_CPU0_SA_DQ<24>")
	)
	(segment
		(start 391.48766 -239.946688)
		(end 391.496042 -239.951514)
		(width 0.0889)
		(layer "In4.Cu")
		(net "M_J_CPU0_SA_DQ<24>")
	)
	(segment
		(start 438.675272 -224.96018)
		(end 439.100214 -225.385122)
		(width 0.14478)
		(layer "In4.Cu")
		(net "M_J_CPU0_SA_DQ<24>")
	)
	(segment
		(start 425.692062 -224.96018)
		(end 426.541946 -225.810064)
		(width 0.14478)
		(layer "In4.Cu")
		(net "M_J_CPU0_SA_DQ<24>")
	)
	(segment
		(start 406.753822 -229.059486)
		(end 410.003244 -225.810064)
		(width 0.14478)
		(layer "In4.Cu")
		(net "M_J_CPU0_SA_DQ<24>")
	)
	(segment
		(start 394.874496 -239.01019)
		(end 395.537436 -238.34725)
		(width 0.0889)
		(layer "In4.Cu")
		(net "M_J_CPU0_SA_DQ<24>")
	)
	(segment
		(start 384.90779 -239.946688)
		(end 384.916172 -239.951514)
		(width 0.0889)
		(layer "In4.Cu")
		(net "M_J_CPU0_SA_DQ<24>")
	)
	(segment
		(start 389.033512 -239.951514)
		(end 389.041894 -239.946688)
		(width 0.0889)
		(layer "In4.Cu")
		(net "M_J_CPU0_SA_DQ<24>")
	)
	(segment
		(start 426.541946 -225.810064)
		(end 429.167544 -225.810064)
		(width 0.14478)
		(layer "In4.Cu")
		(net "M_J_CPU0_SA_DQ<24>")
	)
	(segment
		(start 429.167544 -225.810064)
		(end 430.017428 -224.96018)
		(width 0.14478)
		(layer "In4.Cu")
		(net "M_J_CPU0_SA_DQ<24>")
	)
	(segment
		(start 406.753822 -229.941374)
		(end 406.753822 -229.059486)
		(width 0.14478)
		(layer "In4.Cu")
		(net "M_J_CPU0_SA_DQ<24>")
	)
	(segment
		(start 380.548896 -239.889538)
		(end 380.645162 -239.914938)
		(width 0.0889)
		(layer "In4.Cu")
		(net "M_J_CPU0_SA_DQ<24>")
	)
	(segment
		(start 393.534392 -239.870234)
		(end 394.394436 -239.01019)
		(width 0.0889)
		(layer "In4.Cu")
		(net "M_J_CPU0_SA_DQ<24>")
	)
	(segment
		(start 381.147828 -239.946688)
		(end 381.15621 -239.951514)
		(width 0.0889)
		(layer "In4.Cu")
		(net "M_J_CPU0_SA_DQ<24>")
	)
	(segment
		(start 414.114488 -225.810064)
		(end 414.964372 -224.96018)
		(width 0.14478)
		(layer "In4.Cu")
		(net "M_J_CPU0_SA_DQ<24>")
	)
	(segment
		(start 388.093458 -239.951514)
		(end 388.10184 -239.946688)
		(width 0.0889)
		(layer "In4.Cu")
		(net "M_J_CPU0_SA_DQ<24>")
	)
	(segment
		(start 384.333496 -239.951514)
		(end 384.341878 -239.946688)
		(width 0.0889)
		(layer "In4.Cu")
		(net "M_J_CPU0_SA_DQ<24>")
	)
	(segment
		(start 421.625014 -225.810064)
		(end 422.474898 -224.96018)
		(width 0.14478)
		(layer "In4.Cu")
		(net "M_J_CPU0_SA_DQ<24>")
	)
	(segment
		(start 385.847844 -239.946688)
		(end 385.856226 -239.951514)
		(width 0.0889)
		(layer "In4.Cu")
		(net "M_J_CPU0_SA_DQ<24>")
	)
	(segment
		(start 414.964372 -224.96018)
		(end 417.71697 -224.96018)
		(width 0.14478)
		(layer "In4.Cu")
		(net "M_J_CPU0_SA_DQ<24>")
	)
	(segment
		(start 392.418062 -239.940592)
		(end 392.428476 -239.946688)
		(width 0.0889)
		(layer "In4.Cu")
		(net "M_J_CPU0_SA_DQ<24>")
	)
	(segment
		(start 430.017428 -224.96018)
		(end 438.675272 -224.96018)
		(width 0.14478)
		(layer "In4.Cu")
		(net "M_J_CPU0_SA_DQ<24>")
	)
	(segment
		(start 398.347946 -238.34725)
		(end 406.753822 -229.941374)
		(width 0.14478)
		(layer "In4.Cu")
		(net "M_J_CPU0_SA_DQ<24>")
	)
	(segment
		(start 410.003244 -225.810064)
		(end 414.114488 -225.810064)
		(width 0.14478)
		(layer "In4.Cu")
		(net "M_J_CPU0_SA_DQ<24>")
	)
	(segment
		(start 395.537436 -238.34725)
		(end 395.898878 -238.34725)
		(width 0.0889)
		(layer "In4.Cu")
		(net "M_J_CPU0_SA_DQ<24>")
	)
	(segment
		(start 417.71697 -224.96018)
		(end 418.566854 -225.810064)
		(width 0.14478)
		(layer "In4.Cu")
		(net "M_J_CPU0_SA_DQ<24>")
	)
	(segment
		(start 395.898878 -238.34725)
		(end 398.347946 -238.34725)
		(width 0.14478)
		(layer "In4.Cu")
		(net "M_J_CPU0_SA_DQ<24>")
	)
	(segment
		(start 380.394718 -239.624108)
		(end 380.548896 -239.889538)
		(width 0.0889)
		(layer "In4.Cu")
		(net "M_J_CPU0_SA_DQ<24>")
	)
	(segment
		(start 393.084812 -239.870234)
		(end 393.534392 -239.870234)
		(width 0.0889)
		(layer "In4.Cu")
		(net "M_J_CPU0_SA_DQ<24>")
	)
	(segment
		(start 394.394436 -239.01019)
		(end 394.874496 -239.01019)
		(width 0.0889)
		(layer "In4.Cu")
		(net "M_J_CPU0_SA_DQ<24>")
	)
	(segment
		(start 389.607806 -239.946688)
		(end 389.616188 -239.951514)
		(width 0.0889)
		(layer "In4.Cu")
		(net "M_J_CPU0_SA_DQ<24>")
	)
	(arc
		(start 385.281932 -239.946688)
		(mid 385.564888 -239.870511)
		(end 385.847844 -239.946688)
		(width 0.0889)
		(layer "In4.Cu")
		(net "M_J_CPU0_SA_DQ<24>")
	)
	(arc
		(start 386.221986 -239.946688)
		(mid 386.504942 -239.870511)
		(end 386.787898 -239.946688)
		(width 0.0889)
		(layer "In4.Cu")
		(net "M_J_CPU0_SA_DQ<24>")
	)
	(arc
		(start 385.856226 -239.951514)
		(mid 386.039734 -239.997008)
		(end 386.221986 -239.946688)
		(width 0.0889)
		(layer "In4.Cu")
		(net "M_J_CPU0_SA_DQ<24>")
	)
	(arc
		(start 381.15621 -239.951514)
		(mid 381.339718 -239.997008)
		(end 381.52197 -239.946688)
		(width 0.0889)
		(layer "In4.Cu")
		(net "M_J_CPU0_SA_DQ<24>")
	)
	(arc
		(start 387.727698 -239.946688)
		(mid 387.909949 -239.997038)
		(end 388.093458 -239.951514)
		(width 0.0889)
		(layer "In4.Cu")
		(net "M_J_CPU0_SA_DQ<24>")
	)
	(arc
		(start 386.787898 -239.946688)
		(mid 386.974842 -239.996943)
		(end 387.161786 -239.946688)
		(width 0.0889)
		(layer "In4.Cu")
		(net "M_J_CPU0_SA_DQ<24>")
	)
	(arc
		(start 382.46177 -239.946688)
		(mid 382.744726 -239.870511)
		(end 383.027682 -239.946688)
		(width 0.0889)
		(layer "In4.Cu")
		(net "M_J_CPU0_SA_DQ<24>")
	)
	(arc
		(start 383.401824 -239.946688)
		(mid 383.68478 -239.870511)
		(end 383.967736 -239.946688)
		(width 0.0889)
		(layer "In4.Cu")
		(net "M_J_CPU0_SA_DQ<24>")
	)
	(arc
		(start 383.967736 -239.946688)
		(mid 384.149987 -239.997038)
		(end 384.333496 -239.951514)
		(width 0.0889)
		(layer "In4.Cu")
		(net "M_J_CPU0_SA_DQ<24>")
	)
	(arc
		(start 388.667752 -239.946688)
		(mid 388.850003 -239.997038)
		(end 389.033512 -239.951514)
		(width 0.0889)
		(layer "In4.Cu")
		(net "M_J_CPU0_SA_DQ<24>")
	)
	(arc
		(start 388.10184 -239.946688)
		(mid 388.384796 -239.870511)
		(end 388.667752 -239.946688)
		(width 0.0889)
		(layer "In4.Cu")
		(net "M_J_CPU0_SA_DQ<24>")
	)
	(arc
		(start 390.921748 -239.946688)
		(mid 391.204704 -239.870511)
		(end 391.48766 -239.946688)
		(width 0.0889)
		(layer "In4.Cu")
		(net "M_J_CPU0_SA_DQ<24>")
	)
	(arc
		(start 380.645162 -239.914938)
		(mid 380.900227 -239.871587)
		(end 381.147828 -239.946688)
		(width 0.0889)
		(layer "In4.Cu")
		(net "M_J_CPU0_SA_DQ<24>")
	)
	(arc
		(start 389.041894 -239.946688)
		(mid 389.32485 -239.870511)
		(end 389.607806 -239.946688)
		(width 0.0889)
		(layer "In4.Cu")
		(net "M_J_CPU0_SA_DQ<24>")
	)
	(arc
		(start 392.786108 -239.955832)
		(mid 392.929447 -239.892045)
		(end 393.084812 -239.870234)
		(width 0.0889)
		(layer "In4.Cu")
		(net "M_J_CPU0_SA_DQ<24>")
	)
	(arc
		(start 383.027682 -239.946688)
		(mid 383.209933 -239.997038)
		(end 383.393442 -239.951514)
		(width 0.0889)
		(layer "In4.Cu")
		(net "M_J_CPU0_SA_DQ<24>")
	)
	(arc
		(start 389.616188 -239.951514)
		(mid 389.799696 -239.997008)
		(end 389.981948 -239.946688)
		(width 0.0889)
		(layer "In4.Cu")
		(net "M_J_CPU0_SA_DQ<24>")
	)
	(arc
		(start 391.496042 -239.951514)
		(mid 391.679804 -239.99713)
		(end 391.86231 -239.946688)
		(width 0.0889)
		(layer "In4.Cu")
		(net "M_J_CPU0_SA_DQ<24>")
	)
	(arc
		(start 391.86231 -239.946688)
		(mid 392.139377 -239.870417)
		(end 392.418062 -239.940592)
		(width 0.0889)
		(layer "In4.Cu")
		(net "M_J_CPU0_SA_DQ<24>")
	)
	(arc
		(start 384.916172 -239.951514)
		(mid 385.09968 -239.997008)
		(end 385.281932 -239.946688)
		(width 0.0889)
		(layer "In4.Cu")
		(net "M_J_CPU0_SA_DQ<24>")
	)
	(arc
		(start 387.161786 -239.946688)
		(mid 387.444742 -239.870511)
		(end 387.727698 -239.946688)
		(width 0.0889)
		(layer "In4.Cu")
		(net "M_J_CPU0_SA_DQ<24>")
	)
	(arc
		(start 390.54786 -239.946688)
		(mid 390.734804 -239.996943)
		(end 390.921748 -239.946688)
		(width 0.0889)
		(layer "In4.Cu")
		(net "M_J_CPU0_SA_DQ<24>")
	)
	(arc
		(start 382.087882 -239.946688)
		(mid 382.274826 -239.996943)
		(end 382.46177 -239.946688)
		(width 0.0889)
		(layer "In4.Cu")
		(net "M_J_CPU0_SA_DQ<24>")
	)
	(arc
		(start 381.52197 -239.946688)
		(mid 381.804926 -239.870511)
		(end 382.087882 -239.946688)
		(width 0.0889)
		(layer "In4.Cu")
		(net "M_J_CPU0_SA_DQ<24>")
	)
	(arc
		(start 384.341878 -239.946688)
		(mid 384.624834 -239.870511)
		(end 384.90779 -239.946688)
		(width 0.0889)
		(layer "In4.Cu")
		(net "M_J_CPU0_SA_DQ<24>")
	)
	(arc
		(start 389.981948 -239.946688)
		(mid 390.264904 -239.870511)
		(end 390.54786 -239.946688)
		(width 0.0889)
		(layer "In4.Cu")
		(net "M_J_CPU0_SA_DQ<24>")
	)
	(arc
		(start 392.428476 -239.946688)
		(mid 392.606126 -239.996948)
		(end 392.786108 -239.955832)
		(width 0.0889)
		(layer "In4.Cu")
		(net "M_J_CPU0_SA_DQ<24>")
	)
	(segment
		(start 378.988066 -239.890046)
		(end 379.454918 -239.624108)
		(width 0.10668)
		(layer "F.Cu")
		(net "M_J_CPU0_SA_DQ<23>")
	)
	(segment
		(start 407.472896 -226.809554)
		(end 407.472896 -226.580954)
		(width 0.14478)
		(layer "In4.Cu")
		(net "M_J_CPU0_SA_DQ<23>")
	)
	(segment
		(start 392.811254 -239.316514)
		(end 392.939524 -239.3696)
		(width 0.0889)
		(layer "In4.Cu")
		(net "M_J_CPU0_SA_DQ<23>")
	)
	(segment
		(start 407.082752 -227.199698)
		(end 407.344118 -227.461064)
		(width 0.14478)
		(layer "In4.Cu")
		(net "M_J_CPU0_SA_DQ<23>")
	)
	(segment
		(start 407.86304 -226.41941)
		(end 408.124406 -226.680776)
		(width 0.14478)
		(layer "In4.Cu")
		(net "M_J_CPU0_SA_DQ<23>")
	)
	(segment
		(start 432.566826 -223.783652)
		(end 432.795172 -223.783652)
		(width 0.14478)
		(layer "In4.Cu")
		(net "M_J_CPU0_SA_DQ<23>")
	)
	(segment
		(start 384.90779 -239.301528)
		(end 384.916172 -239.296702)
		(width 0.0889)
		(layer "In4.Cu")
		(net "M_J_CPU0_SA_DQ<23>")
	)
	(segment
		(start 425.683426 -224.110042)
		(end 426.533564 -224.96018)
		(width 0.14478)
		(layer "In4.Cu")
		(net "M_J_CPU0_SA_DQ<23>")
	)
	(segment
		(start 421.602662 -224.96018)
		(end 422.4528 -224.110042)
		(width 0.14478)
		(layer "In4.Cu")
		(net "M_J_CPU0_SA_DQ<23>")
	)
	(segment
		(start 406.202642 -229.692708)
		(end 406.202642 -228.60254)
		(width 0.14478)
		(layer "In4.Cu")
		(net "M_J_CPU0_SA_DQ<23>")
	)
	(segment
		(start 411.699202 -224.96018)
		(end 412.00959 -224.649792)
		(width 0.14478)
		(layer "In4.Cu")
		(net "M_J_CPU0_SA_DQ<23>")
	)
	(segment
		(start 409.195016 -224.858834)
		(end 409.423616 -224.858834)
		(width 0.14478)
		(layer "In4.Cu")
		(net "M_J_CPU0_SA_DQ<23>")
	)
	(segment
		(start 391.48766 -239.301528)
		(end 391.496042 -239.296702)
		(width 0.0889)
		(layer "In4.Cu")
		(net "M_J_CPU0_SA_DQ<23>")
	)
	(segment
		(start 410.906722 -224.649792)
		(end 411.147768 -224.649792)
		(width 0.14478)
		(layer "In4.Cu")
		(net "M_J_CPU0_SA_DQ<23>")
	)
	(segment
		(start 407.734262 -227.29952)
		(end 407.734262 -227.07092)
		(width 0.14478)
		(layer "In4.Cu")
		(net "M_J_CPU0_SA_DQ<23>")
	)
	(segment
		(start 408.253184 -225.800666)
		(end 408.414728 -225.639122)
		(width 0.14478)
		(layer "In4.Cu")
		(net "M_J_CPU0_SA_DQ<23>")
	)
	(segment
		(start 406.202642 -228.60254)
		(end 406.56383 -228.241352)
		(width 0.14478)
		(layer "In4.Cu")
		(net "M_J_CPU0_SA_DQ<23>")
	)
	(segment
		(start 395.668754 -237.78718)
		(end 395.796262 -237.78718)
		(width 0.0889)
		(layer "In4.Cu")
		(net "M_J_CPU0_SA_DQ<23>")
	)
	(segment
		(start 408.353006 -226.680776)
		(end 408.51455 -226.519232)
		(width 0.14478)
		(layer "In4.Cu")
		(net "M_J_CPU0_SA_DQ<23>")
	)
	(segment
		(start 392.788648 -239.293908)
		(end 392.811254 -239.316514)
		(width 0.0889)
		(layer "In4.Cu")
		(net "M_J_CPU0_SA_DQ<23>")
	)
	(segment
		(start 406.692608 -227.589842)
		(end 406.692608 -227.361242)
		(width 0.14478)
		(layer "In4.Cu")
		(net "M_J_CPU0_SA_DQ<23>")
	)
	(segment
		(start 408.124406 -226.680776)
		(end 408.353006 -226.680776)
		(width 0.14478)
		(layer "In4.Cu")
		(net "M_J_CPU0_SA_DQ<23>")
	)
	(segment
		(start 379.454918 -239.624108)
		(end 379.30074 -239.358678)
		(width 0.0889)
		(layer "In4.Cu")
		(net "M_J_CPU0_SA_DQ<23>")
	)
	(segment
		(start 385.847844 -239.301528)
		(end 385.856226 -239.296702)
		(width 0.0889)
		(layer "In4.Cu")
		(net "M_J_CPU0_SA_DQ<23>")
	)
	(segment
		(start 432.405282 -223.948498)
		(end 432.405282 -223.945196)
		(width 0.14478)
		(layer "In4.Cu")
		(net "M_J_CPU0_SA_DQ<23>")
	)
	(segment
		(start 395.796262 -237.78718)
		(end 398.10817 -237.78718)
		(width 0.14478)
		(layer "In4.Cu")
		(net "M_J_CPU0_SA_DQ<23>")
	)
	(segment
		(start 407.472896 -226.580954)
		(end 407.63444 -226.41941)
		(width 0.14478)
		(layer "In4.Cu")
		(net "M_J_CPU0_SA_DQ<23>")
	)
	(segment
		(start 413.663892 -224.96018)
		(end 414.005776 -224.96018)
		(width 0.14478)
		(layer "In4.Cu")
		(net "M_J_CPU0_SA_DQ<23>")
	)
	(segment
		(start 384.333496 -239.296702)
		(end 384.341878 -239.301528)
		(width 0.0889)
		(layer "In4.Cu")
		(net "M_J_CPU0_SA_DQ<23>")
	)
	(segment
		(start 432.405282 -223.945196)
		(end 432.566826 -223.783652)
		(width 0.14478)
		(layer "In4.Cu")
		(net "M_J_CPU0_SA_DQ<23>")
	)
	(segment
		(start 414.855914 -224.110042)
		(end 417.700968 -224.110042)
		(width 0.14478)
		(layer "In4.Cu")
		(net "M_J_CPU0_SA_DQ<23>")
	)
	(segment
		(start 409.294838 -225.738944)
		(end 409.294838 -225.510344)
		(width 0.14478)
		(layer "In4.Cu")
		(net "M_J_CPU0_SA_DQ<23>")
	)
	(segment
		(start 430.004728 -224.110042)
		(end 432.243738 -224.110042)
		(width 0.14478)
		(layer "In4.Cu")
		(net "M_J_CPU0_SA_DQ<23>")
	)
	(segment
		(start 408.904694 -225.900488)
		(end 409.133294 -225.900488)
		(width 0.14478)
		(layer "In4.Cu")
		(net "M_J_CPU0_SA_DQ<23>")
	)
	(segment
		(start 422.4528 -224.110042)
		(end 425.683426 -224.110042)
		(width 0.14478)
		(layer "In4.Cu")
		(net "M_J_CPU0_SA_DQ<23>")
	)
	(segment
		(start 406.854152 -227.199698)
		(end 407.082752 -227.199698)
		(width 0.14478)
		(layer "In4.Cu")
		(net "M_J_CPU0_SA_DQ<23>")
	)
	(segment
		(start 432.956716 -223.948498)
		(end 433.11826 -224.110042)
		(width 0.14478)
		(layer "In4.Cu")
		(net "M_J_CPU0_SA_DQ<23>")
	)
	(segment
		(start 412.250636 -224.649792)
		(end 412.561024 -224.96018)
		(width 0.14478)
		(layer "In4.Cu")
		(net "M_J_CPU0_SA_DQ<23>")
	)
	(segment
		(start 434.059584 -223.945196)
		(end 434.059584 -223.948498)
		(width 0.14478)
		(layer "In4.Cu")
		(net "M_J_CPU0_SA_DQ<23>")
	)
	(segment
		(start 407.344118 -227.461064)
		(end 407.572718 -227.461064)
		(width 0.14478)
		(layer "In4.Cu")
		(net "M_J_CPU0_SA_DQ<23>")
	)
	(segment
		(start 408.643328 -225.639122)
		(end 408.904694 -225.900488)
		(width 0.14478)
		(layer "In4.Cu")
		(net "M_J_CPU0_SA_DQ<23>")
	)
	(segment
		(start 433.89804 -223.783652)
		(end 434.059584 -223.945196)
		(width 0.14478)
		(layer "In4.Cu")
		(net "M_J_CPU0_SA_DQ<23>")
	)
	(segment
		(start 398.10817 -237.78718)
		(end 406.202642 -229.692708)
		(width 0.14478)
		(layer "In4.Cu")
		(net "M_J_CPU0_SA_DQ<23>")
	)
	(segment
		(start 392.413998 -239.310164)
		(end 392.42873 -239.301528)
		(width 0.0889)
		(layer "In4.Cu")
		(net "M_J_CPU0_SA_DQ<23>")
	)
	(segment
		(start 392.939524 -239.3696)
		(end 393.051792 -239.391952)
		(width 0.0889)
		(layer "In4.Cu")
		(net "M_J_CPU0_SA_DQ<23>")
	)
	(segment
		(start 409.684982 -225.1202)
		(end 409.913582 -225.1202)
		(width 0.14478)
		(layer "In4.Cu")
		(net "M_J_CPU0_SA_DQ<23>")
	)
	(segment
		(start 408.51455 -226.519232)
		(end 408.51455 -226.290632)
		(width 0.14478)
		(layer "In4.Cu")
		(net "M_J_CPU0_SA_DQ<23>")
	)
	(segment
		(start 394.781024 -238.67491)
		(end 395.668754 -237.78718)
		(width 0.0889)
		(layer "In4.Cu")
		(net "M_J_CPU0_SA_DQ<23>")
	)
	(segment
		(start 406.56383 -228.241352)
		(end 406.79243 -228.241352)
		(width 0.14478)
		(layer "In4.Cu")
		(net "M_J_CPU0_SA_DQ<23>")
	)
	(segment
		(start 409.033472 -225.020378)
		(end 409.195016 -224.858834)
		(width 0.14478)
		(layer "In4.Cu")
		(net "M_J_CPU0_SA_DQ<23>")
	)
	(segment
		(start 406.79243 -228.241352)
		(end 406.953974 -228.079808)
		(width 0.14478)
		(layer "In4.Cu")
		(net "M_J_CPU0_SA_DQ<23>")
	)
	(segment
		(start 413.112458 -224.649792)
		(end 413.353504 -224.649792)
		(width 0.14478)
		(layer "In4.Cu")
		(net "M_J_CPU0_SA_DQ<23>")
	)
	(segment
		(start 407.734262 -227.07092)
		(end 407.472896 -226.809554)
		(width 0.14478)
		(layer "In4.Cu")
		(net "M_J_CPU0_SA_DQ<23>")
	)
	(segment
		(start 410.596334 -224.96018)
		(end 410.906722 -224.649792)
		(width 0.14478)
		(layer "In4.Cu")
		(net "M_J_CPU0_SA_DQ<23>")
	)
	(segment
		(start 412.561024 -224.96018)
		(end 412.80207 -224.96018)
		(width 0.14478)
		(layer "In4.Cu")
		(net "M_J_CPU0_SA_DQ<23>")
	)
	(segment
		(start 409.294838 -225.510344)
		(end 409.033472 -225.248978)
		(width 0.14478)
		(layer "In4.Cu")
		(net "M_J_CPU0_SA_DQ<23>")
	)
	(segment
		(start 408.51455 -226.290632)
		(end 408.253184 -226.029266)
		(width 0.14478)
		(layer "In4.Cu")
		(net "M_J_CPU0_SA_DQ<23>")
	)
	(segment
		(start 432.795172 -223.783652)
		(end 432.956716 -223.945196)
		(width 0.14478)
		(layer "In4.Cu")
		(net "M_J_CPU0_SA_DQ<23>")
	)
	(segment
		(start 408.253184 -226.029266)
		(end 408.253184 -225.800666)
		(width 0.14478)
		(layer "In4.Cu")
		(net "M_J_CPU0_SA_DQ<23>")
	)
	(segment
		(start 434.221128 -224.110042)
		(end 434.575204 -224.110042)
		(width 0.14478)
		(layer "In4.Cu")
		(net "M_J_CPU0_SA_DQ<23>")
	)
	(segment
		(start 433.50815 -223.948498)
		(end 433.50815 -223.945196)
		(width 0.14478)
		(layer "In4.Cu")
		(net "M_J_CPU0_SA_DQ<23>")
	)
	(segment
		(start 393.051792 -239.391952)
		(end 393.618974 -239.391952)
		(width 0.0889)
		(layer "In4.Cu")
		(net "M_J_CPU0_SA_DQ<23>")
	)
	(segment
		(start 414.005776 -224.96018)
		(end 414.855914 -224.110042)
		(width 0.14478)
		(layer "In4.Cu")
		(net "M_J_CPU0_SA_DQ<23>")
	)
	(segment
		(start 408.414728 -225.639122)
		(end 408.643328 -225.639122)
		(width 0.14478)
		(layer "In4.Cu")
		(net "M_J_CPU0_SA_DQ<23>")
	)
	(segment
		(start 426.533564 -224.96018)
		(end 429.15459 -224.96018)
		(width 0.14478)
		(layer "In4.Cu")
		(net "M_J_CPU0_SA_DQ<23>")
	)
	(segment
		(start 433.669694 -223.783652)
		(end 433.89804 -223.783652)
		(width 0.14478)
		(layer "In4.Cu")
		(net "M_J_CPU0_SA_DQ<23>")
	)
	(segment
		(start 434.059584 -223.948498)
		(end 434.221128 -224.110042)
		(width 0.14478)
		(layer "In4.Cu")
		(net "M_J_CPU0_SA_DQ<23>")
	)
	(segment
		(start 418.551106 -224.96018)
		(end 421.602662 -224.96018)
		(width 0.14478)
		(layer "In4.Cu")
		(net "M_J_CPU0_SA_DQ<23>")
	)
	(segment
		(start 432.243738 -224.110042)
		(end 432.405282 -223.948498)
		(width 0.14478)
		(layer "In4.Cu")
		(net "M_J_CPU0_SA_DQ<23>")
	)
	(segment
		(start 429.15459 -224.96018)
		(end 430.004728 -224.110042)
		(width 0.14478)
		(layer "In4.Cu")
		(net "M_J_CPU0_SA_DQ<23>")
	)
	(segment
		(start 433.346606 -224.110042)
		(end 433.50815 -223.948498)
		(width 0.14478)
		(layer "In4.Cu")
		(net "M_J_CPU0_SA_DQ<23>")
	)
	(segment
		(start 389.607806 -239.301528)
		(end 389.616188 -239.296702)
		(width 0.0889)
		(layer "In4.Cu")
		(net "M_J_CPU0_SA_DQ<23>")
	)
	(segment
		(start 411.147768 -224.649792)
		(end 411.458156 -224.96018)
		(width 0.14478)
		(layer "In4.Cu")
		(net "M_J_CPU0_SA_DQ<23>")
	)
	(segment
		(start 388.093458 -239.296702)
		(end 388.10184 -239.301528)
		(width 0.0889)
		(layer "In4.Cu")
		(net "M_J_CPU0_SA_DQ<23>")
	)
	(segment
		(start 407.63444 -226.41941)
		(end 407.86304 -226.41941)
		(width 0.14478)
		(layer "In4.Cu")
		(net "M_J_CPU0_SA_DQ<23>")
	)
	(segment
		(start 417.700968 -224.110042)
		(end 418.551106 -224.96018)
		(width 0.14478)
		(layer "In4.Cu")
		(net "M_J_CPU0_SA_DQ<23>")
	)
	(segment
		(start 411.458156 -224.96018)
		(end 411.699202 -224.96018)
		(width 0.14478)
		(layer "In4.Cu")
		(net "M_J_CPU0_SA_DQ<23>")
	)
	(segment
		(start 381.147828 -239.301528)
		(end 381.15621 -239.296702)
		(width 0.0889)
		(layer "In4.Cu")
		(net "M_J_CPU0_SA_DQ<23>")
	)
	(segment
		(start 413.353504 -224.649792)
		(end 413.663892 -224.96018)
		(width 0.14478)
		(layer "In4.Cu")
		(net "M_J_CPU0_SA_DQ<23>")
	)
	(segment
		(start 433.50815 -223.945196)
		(end 433.669694 -223.783652)
		(width 0.14478)
		(layer "In4.Cu")
		(net "M_J_CPU0_SA_DQ<23>")
	)
	(segment
		(start 412.80207 -224.96018)
		(end 413.112458 -224.649792)
		(width 0.14478)
		(layer "In4.Cu")
		(net "M_J_CPU0_SA_DQ<23>")
	)
	(segment
		(start 409.133294 -225.900488)
		(end 409.294838 -225.738944)
		(width 0.14478)
		(layer "In4.Cu")
		(net "M_J_CPU0_SA_DQ<23>")
	)
	(segment
		(start 409.423616 -224.858834)
		(end 409.684982 -225.1202)
		(width 0.14478)
		(layer "In4.Cu")
		(net "M_J_CPU0_SA_DQ<23>")
	)
	(segment
		(start 394.336016 -238.67491)
		(end 394.781024 -238.67491)
		(width 0.0889)
		(layer "In4.Cu")
		(net "M_J_CPU0_SA_DQ<23>")
	)
	(segment
		(start 409.913582 -225.1202)
		(end 410.073602 -224.96018)
		(width 0.14478)
		(layer "In4.Cu")
		(net "M_J_CPU0_SA_DQ<23>")
	)
	(segment
		(start 379.30074 -239.358678)
		(end 379.323092 -239.275366)
		(width 0.0889)
		(layer "In4.Cu")
		(net "M_J_CPU0_SA_DQ<23>")
	)
	(segment
		(start 433.11826 -224.110042)
		(end 433.346606 -224.110042)
		(width 0.14478)
		(layer "In4.Cu")
		(net "M_J_CPU0_SA_DQ<23>")
	)
	(segment
		(start 389.033512 -239.296702)
		(end 389.041894 -239.301528)
		(width 0.0889)
		(layer "In4.Cu")
		(net "M_J_CPU0_SA_DQ<23>")
	)
	(segment
		(start 410.073602 -224.96018)
		(end 410.596334 -224.96018)
		(width 0.14478)
		(layer "In4.Cu")
		(net "M_J_CPU0_SA_DQ<23>")
	)
	(segment
		(start 383.393442 -239.296702)
		(end 383.401824 -239.301528)
		(width 0.0889)
		(layer "In4.Cu")
		(net "M_J_CPU0_SA_DQ<23>")
	)
	(segment
		(start 380.207774 -239.301528)
		(end 380.216156 -239.296702)
		(width 0.0889)
		(layer "In4.Cu")
		(net "M_J_CPU0_SA_DQ<23>")
	)
	(segment
		(start 432.956716 -223.945196)
		(end 432.956716 -223.948498)
		(width 0.14478)
		(layer "In4.Cu")
		(net "M_J_CPU0_SA_DQ<23>")
	)
	(segment
		(start 406.953974 -228.079808)
		(end 406.953974 -227.851208)
		(width 0.14478)
		(layer "In4.Cu")
		(net "M_J_CPU0_SA_DQ<23>")
	)
	(segment
		(start 407.572718 -227.461064)
		(end 407.734262 -227.29952)
		(width 0.14478)
		(layer "In4.Cu")
		(net "M_J_CPU0_SA_DQ<23>")
	)
	(segment
		(start 379.63348 -239.296702)
		(end 379.641862 -239.301528)
		(width 0.0889)
		(layer "In4.Cu")
		(net "M_J_CPU0_SA_DQ<23>")
	)
	(segment
		(start 412.00959 -224.649792)
		(end 412.250636 -224.649792)
		(width 0.14478)
		(layer "In4.Cu")
		(net "M_J_CPU0_SA_DQ<23>")
	)
	(segment
		(start 406.692608 -227.361242)
		(end 406.854152 -227.199698)
		(width 0.14478)
		(layer "In4.Cu")
		(net "M_J_CPU0_SA_DQ<23>")
	)
	(segment
		(start 406.953974 -227.851208)
		(end 406.692608 -227.589842)
		(width 0.14478)
		(layer "In4.Cu")
		(net "M_J_CPU0_SA_DQ<23>")
	)
	(segment
		(start 434.575204 -224.110042)
		(end 435.000146 -224.534984)
		(width 0.14478)
		(layer "In4.Cu")
		(net "M_J_CPU0_SA_DQ<23>")
	)
	(segment
		(start 393.618974 -239.391952)
		(end 394.336016 -238.67491)
		(width 0.0889)
		(layer "In4.Cu")
		(net "M_J_CPU0_SA_DQ<23>")
	)
	(segment
		(start 409.033472 -225.248978)
		(end 409.033472 -225.020378)
		(width 0.14478)
		(layer "In4.Cu")
		(net "M_J_CPU0_SA_DQ<23>")
	)
	(arc
		(start 381.15621 -239.296702)
		(mid 381.339718 -239.251208)
		(end 381.52197 -239.301528)
		(width 0.0889)
		(layer "In4.Cu")
		(net "M_J_CPU0_SA_DQ<23>")
	)
	(arc
		(start 379.323092 -239.275366)
		(mid 379.480602 -239.252168)
		(end 379.63348 -239.296702)
		(width 0.0889)
		(layer "In4.Cu")
		(net "M_J_CPU0_SA_DQ<23>")
	)
	(arc
		(start 389.041894 -239.301528)
		(mid 389.32485 -239.377705)
		(end 389.607806 -239.301528)
		(width 0.0889)
		(layer "In4.Cu")
		(net "M_J_CPU0_SA_DQ<23>")
	)
	(arc
		(start 379.641862 -239.301528)
		(mid 379.924818 -239.377705)
		(end 380.207774 -239.301528)
		(width 0.0889)
		(layer "In4.Cu")
		(net "M_J_CPU0_SA_DQ<23>")
	)
	(arc
		(start 391.86231 -239.301528)
		(mid 392.137016 -239.377892)
		(end 392.413998 -239.310164)
		(width 0.0889)
		(layer "In4.Cu")
		(net "M_J_CPU0_SA_DQ<23>")
	)
	(arc
		(start 386.221986 -239.301528)
		(mid 386.504942 -239.377705)
		(end 386.787898 -239.301528)
		(width 0.0889)
		(layer "In4.Cu")
		(net "M_J_CPU0_SA_DQ<23>")
	)
	(arc
		(start 383.401824 -239.301528)
		(mid 383.68478 -239.377705)
		(end 383.967736 -239.301528)
		(width 0.0889)
		(layer "In4.Cu")
		(net "M_J_CPU0_SA_DQ<23>")
	)
	(arc
		(start 383.027682 -239.301528)
		(mid 383.209933 -239.251178)
		(end 383.393442 -239.296702)
		(width 0.0889)
		(layer "In4.Cu")
		(net "M_J_CPU0_SA_DQ<23>")
	)
	(arc
		(start 387.727698 -239.301528)
		(mid 387.909949 -239.251178)
		(end 388.093458 -239.296702)
		(width 0.0889)
		(layer "In4.Cu")
		(net "M_J_CPU0_SA_DQ<23>")
	)
	(arc
		(start 382.087882 -239.301528)
		(mid 382.274826 -239.251273)
		(end 382.46177 -239.301528)
		(width 0.0889)
		(layer "In4.Cu")
		(net "M_J_CPU0_SA_DQ<23>")
	)
	(arc
		(start 385.856226 -239.296702)
		(mid 386.039734 -239.251208)
		(end 386.221986 -239.301528)
		(width 0.0889)
		(layer "In4.Cu")
		(net "M_J_CPU0_SA_DQ<23>")
	)
	(arc
		(start 392.42873 -239.301528)
		(mid 392.607717 -239.251358)
		(end 392.788648 -239.293908)
		(width 0.0889)
		(layer "In4.Cu")
		(net "M_J_CPU0_SA_DQ<23>")
	)
	(arc
		(start 385.281932 -239.301528)
		(mid 385.564888 -239.377705)
		(end 385.847844 -239.301528)
		(width 0.0889)
		(layer "In4.Cu")
		(net "M_J_CPU0_SA_DQ<23>")
	)
	(arc
		(start 381.52197 -239.301528)
		(mid 381.804926 -239.377705)
		(end 382.087882 -239.301528)
		(width 0.0889)
		(layer "In4.Cu")
		(net "M_J_CPU0_SA_DQ<23>")
	)
	(arc
		(start 388.667752 -239.301528)
		(mid 388.850003 -239.251178)
		(end 389.033512 -239.296702)
		(width 0.0889)
		(layer "In4.Cu")
		(net "M_J_CPU0_SA_DQ<23>")
	)
	(arc
		(start 386.787898 -239.301528)
		(mid 386.974842 -239.251273)
		(end 387.161786 -239.301528)
		(width 0.0889)
		(layer "In4.Cu")
		(net "M_J_CPU0_SA_DQ<23>")
	)
	(arc
		(start 389.981948 -239.301528)
		(mid 390.264904 -239.377705)
		(end 390.54786 -239.301528)
		(width 0.0889)
		(layer "In4.Cu")
		(net "M_J_CPU0_SA_DQ<23>")
	)
	(arc
		(start 380.216156 -239.296702)
		(mid 380.399664 -239.251208)
		(end 380.581916 -239.301528)
		(width 0.0889)
		(layer "In4.Cu")
		(net "M_J_CPU0_SA_DQ<23>")
	)
	(arc
		(start 390.54786 -239.301528)
		(mid 390.734804 -239.251273)
		(end 390.921748 -239.301528)
		(width 0.0889)
		(layer "In4.Cu")
		(net "M_J_CPU0_SA_DQ<23>")
	)
	(arc
		(start 388.10184 -239.301528)
		(mid 388.384796 -239.377705)
		(end 388.667752 -239.301528)
		(width 0.0889)
		(layer "In4.Cu")
		(net "M_J_CPU0_SA_DQ<23>")
	)
	(arc
		(start 384.916172 -239.296702)
		(mid 385.09968 -239.251208)
		(end 385.281932 -239.301528)
		(width 0.0889)
		(layer "In4.Cu")
		(net "M_J_CPU0_SA_DQ<23>")
	)
	(arc
		(start 387.161786 -239.301528)
		(mid 387.444742 -239.377705)
		(end 387.727698 -239.301528)
		(width 0.0889)
		(layer "In4.Cu")
		(net "M_J_CPU0_SA_DQ<23>")
	)
	(arc
		(start 389.616188 -239.296702)
		(mid 389.799696 -239.251208)
		(end 389.981948 -239.301528)
		(width 0.0889)
		(layer "In4.Cu")
		(net "M_J_CPU0_SA_DQ<23>")
	)
	(arc
		(start 380.581916 -239.301528)
		(mid 380.864872 -239.377705)
		(end 381.147828 -239.301528)
		(width 0.0889)
		(layer "In4.Cu")
		(net "M_J_CPU0_SA_DQ<23>")
	)
	(arc
		(start 384.341878 -239.301528)
		(mid 384.624834 -239.377705)
		(end 384.90779 -239.301528)
		(width 0.0889)
		(layer "In4.Cu")
		(net "M_J_CPU0_SA_DQ<23>")
	)
	(arc
		(start 390.921748 -239.301528)
		(mid 391.204704 -239.377705)
		(end 391.48766 -239.301528)
		(width 0.0889)
		(layer "In4.Cu")
		(net "M_J_CPU0_SA_DQ<23>")
	)
	(arc
		(start 383.967736 -239.301528)
		(mid 384.149987 -239.251178)
		(end 384.333496 -239.296702)
		(width 0.0889)
		(layer "In4.Cu")
		(net "M_J_CPU0_SA_DQ<23>")
	)
	(arc
		(start 391.496042 -239.296702)
		(mid 391.679804 -239.251086)
		(end 391.86231 -239.301528)
		(width 0.0889)
		(layer "In4.Cu")
		(net "M_J_CPU0_SA_DQ<23>")
	)
	(arc
		(start 382.46177 -239.301528)
		(mid 382.744726 -239.377705)
		(end 383.027682 -239.301528)
		(width 0.0889)
		(layer "In4.Cu")
		(net "M_J_CPU0_SA_DQ<23>")
	)
	(segment
		(start 380.39802 -239.08004)
		(end 380.864872 -238.814102)
		(width 0.10668)
		(layer "F.Cu")
		(net "M_J_CPU0_SA_DQ<22>")
	)
	(segment
		(start 407.533094 -225.020124)
		(end 407.761694 -225.020124)
		(width 0.14478)
		(layer "In4.Cu")
		(net "M_J_CPU0_SA_DQ<22>")
	)
	(segment
		(start 406.362662 -226.190556)
		(end 406.273508 -226.101402)
		(width 0.14478)
		(layer "In4.Cu")
		(net "M_J_CPU0_SA_DQ<22>")
	)
	(segment
		(start 387.257798 -238.491522)
		(end 387.26618 -238.486696)
		(width 0.0889)
		(layer "In4.Cu")
		(net "M_J_CPU0_SA_DQ<22>")
	)
	(segment
		(start 421.437054 -223.260158)
		(end 422.287192 -222.41002)
		(width 0.14478)
		(layer "In4.Cu")
		(net "M_J_CPU0_SA_DQ<22>")
	)
	(segment
		(start 432.817016 -222.184976)
		(end 432.817016 -222.635064)
		(width 0.14478)
		(layer "In4.Cu")
		(net "M_J_CPU0_SA_DQ<22>")
	)
	(segment
		(start 414.168082 -223.260158)
		(end 415.01822 -222.41002)
		(width 0.14478)
		(layer "In4.Cu")
		(net "M_J_CPU0_SA_DQ<22>")
	)
	(segment
		(start 413.070802 -223.260158)
		(end 413.362648 -222.968312)
		(width 0.14478)
		(layer "In4.Cu")
		(net "M_J_CPU0_SA_DQ<22>")
	)
	(segment
		(start 413.914082 -223.260158)
		(end 414.168082 -223.260158)
		(width 0.14478)
		(layer "In4.Cu")
		(net "M_J_CPU0_SA_DQ<22>")
	)
	(segment
		(start 395.27226 -236.87786)
		(end 395.775434 -236.87786)
		(width 0.0889)
		(layer "In4.Cu")
		(net "M_J_CPU0_SA_DQ<22>")
	)
	(segment
		(start 433.529994 -222.023432)
		(end 433.75834 -222.023432)
		(width 0.14478)
		(layer "In4.Cu")
		(net "M_J_CPU0_SA_DQ<22>")
	)
	(segment
		(start 405.972518 -226.5807)
		(end 406.201118 -226.5807)
		(width 0.14478)
		(layer "In4.Cu")
		(net "M_J_CPU0_SA_DQ<22>")
	)
	(segment
		(start 390.443466 -238.486696)
		(end 390.451848 -238.491522)
		(width 0.0889)
		(layer "In4.Cu")
		(net "M_J_CPU0_SA_DQ<22>")
	)
	(segment
		(start 409.252674 -223.618552)
		(end 409.724606 -223.618552)
		(width 0.14478)
		(layer "In4.Cu")
		(net "M_J_CPU0_SA_DQ<22>")
	)
	(segment
		(start 408.703526 -223.849692)
		(end 408.614372 -223.760538)
		(width 0.14478)
		(layer "In4.Cu")
		(net "M_J_CPU0_SA_DQ<22>")
	)
	(segment
		(start 407.053796 -225.321114)
		(end 407.053796 -225.092514)
		(width 0.14478)
		(layer "In4.Cu")
		(net "M_J_CPU0_SA_DQ<22>")
	)
	(segment
		(start 393.084812 -238.440722)
		(end 393.709398 -238.440722)
		(width 0.0889)
		(layer "In4.Cu")
		(net "M_J_CPU0_SA_DQ<22>")
	)
	(segment
		(start 415.01822 -222.41002)
		(end 417.52901 -222.41002)
		(width 0.14478)
		(layer "In4.Cu")
		(net "M_J_CPU0_SA_DQ<22>")
	)
	(segment
		(start 411.967934 -223.260158)
		(end 412.25978 -222.968312)
		(width 0.14478)
		(layer "In4.Cu")
		(net "M_J_CPU0_SA_DQ<22>")
	)
	(segment
		(start 410.972254 -223.023176)
		(end 411.133798 -222.861632)
		(width 0.14478)
		(layer "In4.Cu")
		(net "M_J_CPU0_SA_DQ<22>")
	)
	(segment
		(start 407.44394 -224.93097)
		(end 407.533094 -225.020124)
		(width 0.14478)
		(layer "In4.Cu")
		(net "M_J_CPU0_SA_DQ<22>")
	)
	(segment
		(start 393.709398 -238.440722)
		(end 395.27226 -236.87786)
		(width 0.0889)
		(layer "In4.Cu")
		(net "M_J_CPU0_SA_DQ<22>")
	)
	(segment
		(start 405.883364 -226.491546)
		(end 405.972518 -226.5807)
		(width 0.14478)
		(layer "In4.Cu")
		(net "M_J_CPU0_SA_DQ<22>")
	)
	(segment
		(start 382.557782 -238.491522)
		(end 382.566164 -238.486696)
		(width 0.0889)
		(layer "In4.Cu")
		(net "M_J_CPU0_SA_DQ<22>")
	)
	(segment
		(start 410.81071 -223.658684)
		(end 410.972254 -223.49714)
		(width 0.14478)
		(layer "In4.Cu")
		(net "M_J_CPU0_SA_DQ<22>")
	)
	(segment
		(start 432.265582 -222.184976)
		(end 432.427126 -222.023432)
		(width 0.14478)
		(layer "In4.Cu")
		(net "M_J_CPU0_SA_DQ<22>")
	)
	(segment
		(start 434.575204 -222.41002)
		(end 435.000146 -222.834962)
		(width 0.14478)
		(layer "In4.Cu")
		(net "M_J_CPU0_SA_DQ<22>")
	)
	(segment
		(start 411.523688 -223.023176)
		(end 411.523688 -223.098614)
		(width 0.14478)
		(layer "In4.Cu")
		(net "M_J_CPU0_SA_DQ<22>")
	)
	(segment
		(start 407.923238 -224.85858)
		(end 407.923238 -224.62998)
		(width 0.14478)
		(layer "In4.Cu")
		(net "M_J_CPU0_SA_DQ<22>")
	)
	(segment
		(start 405.303482 -227.478336)
		(end 405.582374 -227.199444)
		(width 0.14478)
		(layer "In4.Cu")
		(net "M_J_CPU0_SA_DQ<22>")
	)
	(segment
		(start 406.752806 -225.800412)
		(end 406.981406 -225.800412)
		(width 0.14478)
		(layer "In4.Cu")
		(net "M_J_CPU0_SA_DQ<22>")
	)
	(segment
		(start 405.49322 -226.65309)
		(end 405.654764 -226.491546)
		(width 0.14478)
		(layer "In4.Cu")
		(net "M_J_CPU0_SA_DQ<22>")
	)
	(segment
		(start 411.523688 -223.098614)
		(end 411.685232 -223.260158)
		(width 0.14478)
		(layer "In4.Cu")
		(net "M_J_CPU0_SA_DQ<22>")
	)
	(segment
		(start 406.273508 -226.101402)
		(end 406.273508 -225.872802)
		(width 0.14478)
		(layer "In4.Cu")
		(net "M_J_CPU0_SA_DQ<22>")
	)
	(segment
		(start 406.981406 -225.800412)
		(end 407.14295 -225.638868)
		(width 0.14478)
		(layer "In4.Cu")
		(net "M_J_CPU0_SA_DQ<22>")
	)
	(segment
		(start 410.03093 -222.861632)
		(end 410.259276 -222.861632)
		(width 0.14478)
		(layer "In4.Cu")
		(net "M_J_CPU0_SA_DQ<22>")
	)
	(segment
		(start 425.472098 -222.41002)
		(end 426.322236 -223.260158)
		(width 0.14478)
		(layer "In4.Cu")
		(net "M_J_CPU0_SA_DQ<22>")
	)
	(segment
		(start 407.923238 -224.62998)
		(end 407.834084 -224.540826)
		(width 0.14478)
		(layer "In4.Cu")
		(net "M_J_CPU0_SA_DQ<22>")
	)
	(segment
		(start 433.36845 -222.184976)
		(end 433.529994 -222.023432)
		(width 0.14478)
		(layer "In4.Cu")
		(net "M_J_CPU0_SA_DQ<22>")
	)
	(segment
		(start 432.655472 -222.023432)
		(end 432.817016 -222.184976)
		(width 0.14478)
		(layer "In4.Cu")
		(net "M_J_CPU0_SA_DQ<22>")
	)
	(segment
		(start 410.972254 -223.49714)
		(end 410.972254 -223.023176)
		(width 0.14478)
		(layer "In4.Cu")
		(net "M_J_CPU0_SA_DQ<22>")
	)
	(segment
		(start 405.303482 -229.245668)
		(end 405.303482 -227.478336)
		(width 0.14478)
		(layer "In4.Cu")
		(net "M_J_CPU0_SA_DQ<22>")
	)
	(segment
		(start 406.435052 -225.711258)
		(end 406.663652 -225.711258)
		(width 0.14478)
		(layer "In4.Cu")
		(net "M_J_CPU0_SA_DQ<22>")
	)
	(segment
		(start 408.224228 -224.150682)
		(end 408.313382 -224.239836)
		(width 0.14478)
		(layer "In4.Cu")
		(net "M_J_CPU0_SA_DQ<22>")
	)
	(segment
		(start 407.14295 -225.638868)
		(end 407.14295 -225.410268)
		(width 0.14478)
		(layer "In4.Cu")
		(net "M_J_CPU0_SA_DQ<22>")
	)
	(segment
		(start 409.869386 -223.473772)
		(end 409.869386 -223.023176)
		(width 0.14478)
		(layer "In4.Cu")
		(net "M_J_CPU0_SA_DQ<22>")
	)
	(segment
		(start 410.582364 -223.658684)
		(end 410.81071 -223.658684)
		(width 0.14478)
		(layer "In4.Cu")
		(net "M_J_CPU0_SA_DQ<22>")
	)
	(segment
		(start 385.74345 -238.486696)
		(end 385.751832 -238.491522)
		(width 0.0889)
		(layer "In4.Cu")
		(net "M_J_CPU0_SA_DQ<22>")
	)
	(segment
		(start 412.811214 -223.260158)
		(end 413.070802 -223.260158)
		(width 0.14478)
		(layer "In4.Cu")
		(net "M_J_CPU0_SA_DQ<22>")
	)
	(segment
		(start 381.983488 -238.486696)
		(end 381.99187 -238.491522)
		(width 0.0889)
		(layer "In4.Cu")
		(net "M_J_CPU0_SA_DQ<22>")
	)
	(segment
		(start 406.663652 -225.711258)
		(end 406.752806 -225.800412)
		(width 0.14478)
		(layer "In4.Cu")
		(net "M_J_CPU0_SA_DQ<22>")
	)
	(segment
		(start 397.67129 -236.87786)
		(end 405.303482 -229.245668)
		(width 0.14478)
		(layer "In4.Cu")
		(net "M_J_CPU0_SA_DQ<22>")
	)
	(segment
		(start 433.919884 -222.248476)
		(end 434.081428 -222.41002)
		(width 0.14478)
		(layer "In4.Cu")
		(net "M_J_CPU0_SA_DQ<22>")
	)
	(segment
		(start 391.01776 -238.491522)
		(end 391.026142 -238.486696)
		(width 0.0889)
		(layer "In4.Cu")
		(net "M_J_CPU0_SA_DQ<22>")
	)
	(segment
		(start 433.36845 -222.635064)
		(end 433.36845 -222.184976)
		(width 0.14478)
		(layer "In4.Cu")
		(net "M_J_CPU0_SA_DQ<22>")
	)
	(segment
		(start 405.582374 -226.970844)
		(end 405.49322 -226.88169)
		(width 0.14478)
		(layer "In4.Cu")
		(net "M_J_CPU0_SA_DQ<22>")
	)
	(segment
		(start 383.497836 -238.491522)
		(end 383.506218 -238.486696)
		(width 0.0889)
		(layer "In4.Cu")
		(net "M_J_CPU0_SA_DQ<22>")
	)
	(segment
		(start 411.685232 -223.260158)
		(end 411.967934 -223.260158)
		(width 0.14478)
		(layer "In4.Cu")
		(net "M_J_CPU0_SA_DQ<22>")
	)
	(segment
		(start 413.362648 -222.968312)
		(end 413.622236 -222.968312)
		(width 0.14478)
		(layer "In4.Cu")
		(net "M_J_CPU0_SA_DQ<22>")
	)
	(segment
		(start 432.265582 -222.248476)
		(end 432.265582 -222.184976)
		(width 0.14478)
		(layer "In4.Cu")
		(net "M_J_CPU0_SA_DQ<22>")
	)
	(segment
		(start 407.21534 -224.93097)
		(end 407.44394 -224.93097)
		(width 0.14478)
		(layer "In4.Cu")
		(net "M_J_CPU0_SA_DQ<22>")
	)
	(segment
		(start 407.834084 -224.540826)
		(end 407.834084 -224.312226)
		(width 0.14478)
		(layer "In4.Cu")
		(net "M_J_CPU0_SA_DQ<22>")
	)
	(segment
		(start 407.834084 -224.312226)
		(end 407.995628 -224.150682)
		(width 0.14478)
		(layer "In4.Cu")
		(net "M_J_CPU0_SA_DQ<22>")
	)
	(segment
		(start 432.817016 -222.635064)
		(end 432.97856 -222.796608)
		(width 0.14478)
		(layer "In4.Cu")
		(net "M_J_CPU0_SA_DQ<22>")
	)
	(segment
		(start 380.710694 -238.548672)
		(end 380.733046 -238.46536)
		(width 0.0889)
		(layer "In4.Cu")
		(net "M_J_CPU0_SA_DQ<22>")
	)
	(segment
		(start 433.919884 -222.184976)
		(end 433.919884 -222.248476)
		(width 0.14478)
		(layer "In4.Cu")
		(net "M_J_CPU0_SA_DQ<22>")
	)
	(segment
		(start 409.869386 -223.023176)
		(end 410.03093 -222.861632)
		(width 0.14478)
		(layer "In4.Cu")
		(net "M_J_CPU0_SA_DQ<22>")
	)
	(segment
		(start 412.25978 -222.968312)
		(end 412.519368 -222.968312)
		(width 0.14478)
		(layer "In4.Cu")
		(net "M_J_CPU0_SA_DQ<22>")
	)
	(segment
		(start 406.362662 -226.419156)
		(end 406.362662 -226.190556)
		(width 0.14478)
		(layer "In4.Cu")
		(net "M_J_CPU0_SA_DQ<22>")
	)
	(segment
		(start 429.331882 -223.260158)
		(end 430.18202 -222.41002)
		(width 0.14478)
		(layer "In4.Cu")
		(net "M_J_CPU0_SA_DQ<22>")
	)
	(segment
		(start 411.133798 -222.861632)
		(end 411.362144 -222.861632)
		(width 0.14478)
		(layer "In4.Cu")
		(net "M_J_CPU0_SA_DQ<22>")
	)
	(segment
		(start 407.14295 -225.410268)
		(end 407.053796 -225.321114)
		(width 0.14478)
		(layer "In4.Cu")
		(net "M_J_CPU0_SA_DQ<22>")
	)
	(segment
		(start 433.206906 -222.796608)
		(end 433.36845 -222.635064)
		(width 0.14478)
		(layer "In4.Cu")
		(net "M_J_CPU0_SA_DQ<22>")
	)
	(segment
		(start 380.864872 -238.814102)
		(end 380.710694 -238.548672)
		(width 0.0889)
		(layer "In4.Cu")
		(net "M_J_CPU0_SA_DQ<22>")
	)
	(segment
		(start 426.322236 -223.260158)
		(end 429.331882 -223.260158)
		(width 0.14478)
		(layer "In4.Cu")
		(net "M_J_CPU0_SA_DQ<22>")
	)
	(segment
		(start 410.259276 -222.861632)
		(end 410.42082 -223.023176)
		(width 0.14478)
		(layer "In4.Cu")
		(net "M_J_CPU0_SA_DQ<22>")
	)
	(segment
		(start 409.004516 -223.370394)
		(end 409.252674 -223.618552)
		(width 0.14478)
		(layer "In4.Cu")
		(net "M_J_CPU0_SA_DQ<22>")
	)
	(segment
		(start 412.519368 -222.968312)
		(end 412.811214 -223.260158)
		(width 0.14478)
		(layer "In4.Cu")
		(net "M_J_CPU0_SA_DQ<22>")
	)
	(segment
		(start 408.703526 -224.078292)
		(end 408.703526 -223.849692)
		(width 0.14478)
		(layer "In4.Cu")
		(net "M_J_CPU0_SA_DQ<22>")
	)
	(segment
		(start 408.614372 -223.531938)
		(end 408.775916 -223.370394)
		(width 0.14478)
		(layer "In4.Cu")
		(net "M_J_CPU0_SA_DQ<22>")
	)
	(segment
		(start 386.683504 -238.486696)
		(end 386.691886 -238.491522)
		(width 0.0889)
		(layer "In4.Cu")
		(net "M_J_CPU0_SA_DQ<22>")
	)
	(segment
		(start 388.197852 -238.491522)
		(end 388.206234 -238.486696)
		(width 0.0889)
		(layer "In4.Cu")
		(net "M_J_CPU0_SA_DQ<22>")
	)
	(segment
		(start 405.654764 -226.491546)
		(end 405.883364 -226.491546)
		(width 0.14478)
		(layer "In4.Cu")
		(net "M_J_CPU0_SA_DQ<22>")
	)
	(segment
		(start 411.362144 -222.861632)
		(end 411.523688 -223.023176)
		(width 0.14478)
		(layer "In4.Cu")
		(net "M_J_CPU0_SA_DQ<22>")
	)
	(segment
		(start 430.18202 -222.41002)
		(end 432.104038 -222.41002)
		(width 0.14478)
		(layer "In4.Cu")
		(net "M_J_CPU0_SA_DQ<22>")
	)
	(segment
		(start 408.541982 -224.239836)
		(end 408.703526 -224.078292)
		(width 0.14478)
		(layer "In4.Cu")
		(net "M_J_CPU0_SA_DQ<22>")
	)
	(segment
		(start 391.391902 -238.491522)
		(end 391.402316 -238.497618)
		(width 0.0889)
		(layer "In4.Cu")
		(net "M_J_CPU0_SA_DQ<22>")
	)
	(segment
		(start 408.614372 -223.760538)
		(end 408.614372 -223.531938)
		(width 0.14478)
		(layer "In4.Cu")
		(net "M_J_CPU0_SA_DQ<22>")
	)
	(segment
		(start 405.49322 -226.88169)
		(end 405.49322 -226.65309)
		(width 0.14478)
		(layer "In4.Cu")
		(net "M_J_CPU0_SA_DQ<22>")
	)
	(segment
		(start 406.273508 -225.872802)
		(end 406.435052 -225.711258)
		(width 0.14478)
		(layer "In4.Cu")
		(net "M_J_CPU0_SA_DQ<22>")
	)
	(segment
		(start 407.053796 -225.092514)
		(end 407.21534 -224.93097)
		(width 0.14478)
		(layer "In4.Cu")
		(net "M_J_CPU0_SA_DQ<22>")
	)
	(segment
		(start 409.724606 -223.618552)
		(end 409.869386 -223.473772)
		(width 0.14478)
		(layer "In4.Cu")
		(net "M_J_CPU0_SA_DQ<22>")
	)
	(segment
		(start 405.582374 -227.199444)
		(end 405.582374 -226.970844)
		(width 0.14478)
		(layer "In4.Cu")
		(net "M_J_CPU0_SA_DQ<22>")
	)
	(segment
		(start 413.622236 -222.968312)
		(end 413.914082 -223.260158)
		(width 0.14478)
		(layer "In4.Cu")
		(net "M_J_CPU0_SA_DQ<22>")
	)
	(segment
		(start 422.287192 -222.41002)
		(end 425.472098 -222.41002)
		(width 0.14478)
		(layer "In4.Cu")
		(net "M_J_CPU0_SA_DQ<22>")
	)
	(segment
		(start 417.52901 -222.41002)
		(end 418.379148 -223.260158)
		(width 0.14478)
		(layer "In4.Cu")
		(net "M_J_CPU0_SA_DQ<22>")
	)
	(segment
		(start 432.97856 -222.796608)
		(end 433.206906 -222.796608)
		(width 0.14478)
		(layer "In4.Cu")
		(net "M_J_CPU0_SA_DQ<22>")
	)
	(segment
		(start 407.761694 -225.020124)
		(end 407.923238 -224.85858)
		(width 0.14478)
		(layer "In4.Cu")
		(net "M_J_CPU0_SA_DQ<22>")
	)
	(segment
		(start 406.201118 -226.5807)
		(end 406.362662 -226.419156)
		(width 0.14478)
		(layer "In4.Cu")
		(net "M_J_CPU0_SA_DQ<22>")
	)
	(segment
		(start 410.42082 -223.023176)
		(end 410.42082 -223.49714)
		(width 0.14478)
		(layer "In4.Cu")
		(net "M_J_CPU0_SA_DQ<22>")
	)
	(segment
		(start 434.081428 -222.41002)
		(end 434.575204 -222.41002)
		(width 0.14478)
		(layer "In4.Cu")
		(net "M_J_CPU0_SA_DQ<22>")
	)
	(segment
		(start 408.313382 -224.239836)
		(end 408.541982 -224.239836)
		(width 0.14478)
		(layer "In4.Cu")
		(net "M_J_CPU0_SA_DQ<22>")
	)
	(segment
		(start 432.427126 -222.023432)
		(end 432.655472 -222.023432)
		(width 0.14478)
		(layer "In4.Cu")
		(net "M_J_CPU0_SA_DQ<22>")
	)
	(segment
		(start 392.324336 -238.486696)
		(end 392.332718 -238.491522)
		(width 0.0889)
		(layer "In4.Cu")
		(net "M_J_CPU0_SA_DQ<22>")
	)
	(segment
		(start 408.775916 -223.370394)
		(end 409.004516 -223.370394)
		(width 0.14478)
		(layer "In4.Cu")
		(net "M_J_CPU0_SA_DQ<22>")
	)
	(segment
		(start 433.75834 -222.023432)
		(end 433.919884 -222.184976)
		(width 0.14478)
		(layer "In4.Cu")
		(net "M_J_CPU0_SA_DQ<22>")
	)
	(segment
		(start 381.043434 -238.486696)
		(end 381.051816 -238.491522)
		(width 0.0889)
		(layer "In4.Cu")
		(net "M_J_CPU0_SA_DQ<22>")
	)
	(segment
		(start 395.775434 -236.87786)
		(end 397.67129 -236.87786)
		(width 0.14478)
		(layer "In4.Cu")
		(net "M_J_CPU0_SA_DQ<22>")
	)
	(segment
		(start 407.995628 -224.150682)
		(end 408.224228 -224.150682)
		(width 0.14478)
		(layer "In4.Cu")
		(net "M_J_CPU0_SA_DQ<22>")
	)
	(segment
		(start 418.379148 -223.260158)
		(end 421.437054 -223.260158)
		(width 0.14478)
		(layer "In4.Cu")
		(net "M_J_CPU0_SA_DQ<22>")
	)
	(segment
		(start 432.104038 -222.41002)
		(end 432.265582 -222.248476)
		(width 0.14478)
		(layer "In4.Cu")
		(net "M_J_CPU0_SA_DQ<22>")
	)
	(segment
		(start 410.42082 -223.49714)
		(end 410.582364 -223.658684)
		(width 0.14478)
		(layer "In4.Cu")
		(net "M_J_CPU0_SA_DQ<22>")
	)
	(arc
		(start 389.137906 -238.491522)
		(mid 389.32485 -238.441267)
		(end 389.511794 -238.491522)
		(width 0.0889)
		(layer "In4.Cu")
		(net "M_J_CPU0_SA_DQ<22>")
	)
	(arc
		(start 388.206234 -238.486696)
		(mid 388.389742 -238.441202)
		(end 388.571994 -238.491522)
		(width 0.0889)
		(layer "In4.Cu")
		(net "M_J_CPU0_SA_DQ<22>")
	)
	(arc
		(start 381.051816 -238.491522)
		(mid 381.334772 -238.567699)
		(end 381.617728 -238.491522)
		(width 0.0889)
		(layer "In4.Cu")
		(net "M_J_CPU0_SA_DQ<22>")
	)
	(arc
		(start 380.733046 -238.46536)
		(mid 380.890556 -238.442162)
		(end 381.043434 -238.486696)
		(width 0.0889)
		(layer "In4.Cu")
		(net "M_J_CPU0_SA_DQ<22>")
	)
	(arc
		(start 386.317744 -238.491522)
		(mid 386.499995 -238.441172)
		(end 386.683504 -238.486696)
		(width 0.0889)
		(layer "In4.Cu")
		(net "M_J_CPU0_SA_DQ<22>")
	)
	(arc
		(start 385.751832 -238.491522)
		(mid 386.034788 -238.567699)
		(end 386.317744 -238.491522)
		(width 0.0889)
		(layer "In4.Cu")
		(net "M_J_CPU0_SA_DQ<22>")
	)
	(arc
		(start 388.571994 -238.491522)
		(mid 388.85495 -238.567699)
		(end 389.137906 -238.491522)
		(width 0.0889)
		(layer "In4.Cu")
		(net "M_J_CPU0_SA_DQ<22>")
	)
	(arc
		(start 382.931924 -238.491522)
		(mid 383.21488 -238.567699)
		(end 383.497836 -238.491522)
		(width 0.0889)
		(layer "In4.Cu")
		(net "M_J_CPU0_SA_DQ<22>")
	)
	(arc
		(start 391.402316 -238.497618)
		(mid 391.681002 -238.567838)
		(end 391.958068 -238.491522)
		(width 0.0889)
		(layer "In4.Cu")
		(net "M_J_CPU0_SA_DQ<22>")
	)
	(arc
		(start 384.811778 -238.491522)
		(mid 385.094734 -238.567699)
		(end 385.37769 -238.491522)
		(width 0.0889)
		(layer "In4.Cu")
		(net "M_J_CPU0_SA_DQ<22>")
	)
	(arc
		(start 387.63194 -238.491522)
		(mid 387.914896 -238.567699)
		(end 388.197852 -238.491522)
		(width 0.0889)
		(layer "In4.Cu")
		(net "M_J_CPU0_SA_DQ<22>")
	)
	(arc
		(start 392.332718 -238.491522)
		(mid 392.612146 -238.567688)
		(end 392.892534 -238.495078)
		(width 0.0889)
		(layer "In4.Cu")
		(net "M_J_CPU0_SA_DQ<22>")
	)
	(arc
		(start 386.691886 -238.491522)
		(mid 386.974842 -238.567699)
		(end 387.257798 -238.491522)
		(width 0.0889)
		(layer "In4.Cu")
		(net "M_J_CPU0_SA_DQ<22>")
	)
	(arc
		(start 389.511794 -238.491522)
		(mid 389.79475 -238.567699)
		(end 390.077706 -238.491522)
		(width 0.0889)
		(layer "In4.Cu")
		(net "M_J_CPU0_SA_DQ<22>")
	)
	(arc
		(start 381.99187 -238.491522)
		(mid 382.274826 -238.567699)
		(end 382.557782 -238.491522)
		(width 0.0889)
		(layer "In4.Cu")
		(net "M_J_CPU0_SA_DQ<22>")
	)
	(arc
		(start 381.617728 -238.491522)
		(mid 381.799979 -238.441172)
		(end 381.983488 -238.486696)
		(width 0.0889)
		(layer "In4.Cu")
		(net "M_J_CPU0_SA_DQ<22>")
	)
	(arc
		(start 384.43789 -238.491522)
		(mid 384.624834 -238.441267)
		(end 384.811778 -238.491522)
		(width 0.0889)
		(layer "In4.Cu")
		(net "M_J_CPU0_SA_DQ<22>")
	)
	(arc
		(start 382.566164 -238.486696)
		(mid 382.749672 -238.441202)
		(end 382.931924 -238.491522)
		(width 0.0889)
		(layer "In4.Cu")
		(net "M_J_CPU0_SA_DQ<22>")
	)
	(arc
		(start 387.26618 -238.486696)
		(mid 387.449688 -238.441202)
		(end 387.63194 -238.491522)
		(width 0.0889)
		(layer "In4.Cu")
		(net "M_J_CPU0_SA_DQ<22>")
	)
	(arc
		(start 391.958068 -238.491522)
		(mid 392.140573 -238.441045)
		(end 392.324336 -238.486696)
		(width 0.0889)
		(layer "In4.Cu")
		(net "M_J_CPU0_SA_DQ<22>")
	)
	(arc
		(start 390.077706 -238.491522)
		(mid 390.259957 -238.441172)
		(end 390.443466 -238.486696)
		(width 0.0889)
		(layer "In4.Cu")
		(net "M_J_CPU0_SA_DQ<22>")
	)
	(arc
		(start 391.026142 -238.486696)
		(mid 391.20965 -238.441202)
		(end 391.391902 -238.491522)
		(width 0.0889)
		(layer "In4.Cu")
		(net "M_J_CPU0_SA_DQ<22>")
	)
	(arc
		(start 383.506218 -238.486696)
		(mid 383.689726 -238.441202)
		(end 383.871978 -238.491522)
		(width 0.0889)
		(layer "In4.Cu")
		(net "M_J_CPU0_SA_DQ<22>")
	)
	(arc
		(start 385.37769 -238.491522)
		(mid 385.559941 -238.441172)
		(end 385.74345 -238.486696)
		(width 0.0889)
		(layer "In4.Cu")
		(net "M_J_CPU0_SA_DQ<22>")
	)
	(arc
		(start 392.892534 -238.495078)
		(mid 392.984966 -238.454796)
		(end 393.084812 -238.440722)
		(width 0.0889)
		(layer "In4.Cu")
		(net "M_J_CPU0_SA_DQ<22>")
	)
	(arc
		(start 383.871978 -238.491522)
		(mid 384.154934 -238.567699)
		(end 384.43789 -238.491522)
		(width 0.0889)
		(layer "In4.Cu")
		(net "M_J_CPU0_SA_DQ<22>")
	)
	(arc
		(start 390.451848 -238.491522)
		(mid 390.734804 -238.567699)
		(end 391.01776 -238.491522)
		(width 0.0889)
		(layer "In4.Cu")
		(net "M_J_CPU0_SA_DQ<22>")
	)
	(segment
		(start 378.517912 -239.08004)
		(end 378.984764 -238.814102)
		(width 0.10668)
		(layer "F.Cu")
		(net "M_J_CPU0_SA_DQ<21>")
	)
	(segment
		(start 391.391902 -239.136682)
		(end 391.406634 -239.128046)
		(width 0.0889)
		(layer "In4.Cu")
		(net "M_J_CPU0_SA_DQ<21>")
	)
	(segment
		(start 386.683504 -239.141508)
		(end 386.691886 -239.136682)
		(width 0.0889)
		(layer "In4.Cu")
		(net "M_J_CPU0_SA_DQ<21>")
	)
	(segment
		(start 426.41139 -224.110042)
		(end 429.236378 -224.110042)
		(width 0.14478)
		(layer "In4.Cu")
		(net "M_J_CPU0_SA_DQ<21>")
	)
	(segment
		(start 430.086262 -223.260158)
		(end 435.402736 -223.260158)
		(width 0.14478)
		(layer "In4.Cu")
		(net "M_J_CPU0_SA_DQ<21>")
	)
	(segment
		(start 415.012124 -223.260158)
		(end 417.619688 -223.260158)
		(width 0.14478)
		(layer "In4.Cu")
		(net "M_J_CPU0_SA_DQ<21>")
	)
	(segment
		(start 381.983488 -239.141508)
		(end 381.99187 -239.136682)
		(width 0.0889)
		(layer "In4.Cu")
		(net "M_J_CPU0_SA_DQ<21>")
	)
	(segment
		(start 378.984764 -238.814102)
		(end 379.138942 -239.079532)
		(width 0.0889)
		(layer "In4.Cu")
		(net "M_J_CPU0_SA_DQ<21>")
	)
	(segment
		(start 435.95417 -223.905572)
		(end 436.115714 -223.744028)
		(width 0.14478)
		(layer "In4.Cu")
		(net "M_J_CPU0_SA_DQ<21>")
	)
	(segment
		(start 435.56428 -223.744028)
		(end 435.725824 -223.905572)
		(width 0.14478)
		(layer "In4.Cu")
		(net "M_J_CPU0_SA_DQ<21>")
	)
	(segment
		(start 436.115714 -223.421702)
		(end 436.277258 -223.260158)
		(width 0.14478)
		(layer "In4.Cu")
		(net "M_J_CPU0_SA_DQ<21>")
	)
	(segment
		(start 405.753062 -229.433628)
		(end 405.753062 -227.664772)
		(width 0.14478)
		(layer "In4.Cu")
		(net "M_J_CPU0_SA_DQ<21>")
	)
	(segment
		(start 390.443466 -239.141508)
		(end 390.451848 -239.136682)
		(width 0.0889)
		(layer "In4.Cu")
		(net "M_J_CPU0_SA_DQ<21>")
	)
	(segment
		(start 382.557782 -239.136682)
		(end 382.566164 -239.141508)
		(width 0.0889)
		(layer "In4.Cu")
		(net "M_J_CPU0_SA_DQ<21>")
	)
	(segment
		(start 381.043434 -239.141508)
		(end 381.051816 -239.136682)
		(width 0.0889)
		(layer "In4.Cu")
		(net "M_J_CPU0_SA_DQ<21>")
	)
	(segment
		(start 422.58107 -223.260158)
		(end 425.561506 -223.260158)
		(width 0.14478)
		(layer "In4.Cu")
		(net "M_J_CPU0_SA_DQ<21>")
	)
	(segment
		(start 409.307792 -224.110042)
		(end 414.16224 -224.110042)
		(width 0.14478)
		(layer "In4.Cu")
		(net "M_J_CPU0_SA_DQ<21>")
	)
	(segment
		(start 395.806676 -237.33252)
		(end 397.85417 -237.33252)
		(width 0.14478)
		(layer "In4.Cu")
		(net "M_J_CPU0_SA_DQ<21>")
	)
	(segment
		(start 435.402736 -223.260158)
		(end 435.56428 -223.421702)
		(width 0.14478)
		(layer "In4.Cu")
		(net "M_J_CPU0_SA_DQ<21>")
	)
	(segment
		(start 418.469572 -224.110042)
		(end 421.731186 -224.110042)
		(width 0.14478)
		(layer "In4.Cu")
		(net "M_J_CPU0_SA_DQ<21>")
	)
	(segment
		(start 425.561506 -223.260158)
		(end 426.41139 -224.110042)
		(width 0.14478)
		(layer "In4.Cu")
		(net "M_J_CPU0_SA_DQ<21>")
	)
	(segment
		(start 388.197852 -239.136682)
		(end 388.206234 -239.141508)
		(width 0.0889)
		(layer "In4.Cu")
		(net "M_J_CPU0_SA_DQ<21>")
	)
	(segment
		(start 387.257798 -239.136682)
		(end 387.26618 -239.141508)
		(width 0.0889)
		(layer "In4.Cu")
		(net "M_J_CPU0_SA_DQ<21>")
	)
	(segment
		(start 436.96382 -223.260158)
		(end 439.100214 -223.6851)
		(width 0.14478)
		(layer "In4.Cu")
		(net "M_J_CPU0_SA_DQ<21>")
	)
	(segment
		(start 379.138942 -239.079532)
		(end 379.235208 -239.104932)
		(width 0.0889)
		(layer "In4.Cu")
		(net "M_J_CPU0_SA_DQ<21>")
	)
	(segment
		(start 417.619688 -223.260158)
		(end 418.469572 -224.110042)
		(width 0.14478)
		(layer "In4.Cu")
		(net "M_J_CPU0_SA_DQ<21>")
	)
	(segment
		(start 435.56428 -223.421702)
		(end 435.56428 -223.744028)
		(width 0.14478)
		(layer "In4.Cu")
		(net "M_J_CPU0_SA_DQ<21>")
	)
	(segment
		(start 393.313412 -239.136682)
		(end 395.117574 -237.33252)
		(width 0.0889)
		(layer "In4.Cu")
		(net "M_J_CPU0_SA_DQ<21>")
	)
	(segment
		(start 435.725824 -223.905572)
		(end 435.95417 -223.905572)
		(width 0.14478)
		(layer "In4.Cu")
		(net "M_J_CPU0_SA_DQ<21>")
	)
	(segment
		(start 392.898122 -239.136428)
		(end 392.91641 -239.146842)
		(width 0.0889)
		(layer "In4.Cu")
		(net "M_J_CPU0_SA_DQ<21>")
	)
	(segment
		(start 392.892534 -239.133126)
		(end 392.898122 -239.136428)
		(width 0.0889)
		(layer "In4.Cu")
		(net "M_J_CPU0_SA_DQ<21>")
	)
	(segment
		(start 392.321034 -239.14354)
		(end 392.332718 -239.136682)
		(width 0.0889)
		(layer "In4.Cu")
		(net "M_J_CPU0_SA_DQ<21>")
	)
	(segment
		(start 395.117574 -237.33252)
		(end 395.806676 -237.33252)
		(width 0.0889)
		(layer "In4.Cu")
		(net "M_J_CPU0_SA_DQ<21>")
	)
	(segment
		(start 436.115714 -223.744028)
		(end 436.115714 -223.421702)
		(width 0.14478)
		(layer "In4.Cu")
		(net "M_J_CPU0_SA_DQ<21>")
	)
	(segment
		(start 436.277258 -223.260158)
		(end 436.96382 -223.260158)
		(width 0.14478)
		(layer "In4.Cu")
		(net "M_J_CPU0_SA_DQ<21>")
	)
	(segment
		(start 391.01776 -239.136682)
		(end 391.026142 -239.141508)
		(width 0.0889)
		(layer "In4.Cu")
		(net "M_J_CPU0_SA_DQ<21>")
	)
	(segment
		(start 397.85417 -237.33252)
		(end 405.753062 -229.433628)
		(width 0.14478)
		(layer "In4.Cu")
		(net "M_J_CPU0_SA_DQ<21>")
	)
	(segment
		(start 393.272264 -239.136682)
		(end 393.313412 -239.136682)
		(width 0.0889)
		(layer "In4.Cu")
		(net "M_J_CPU0_SA_DQ<21>")
	)
	(segment
		(start 405.753062 -227.664772)
		(end 409.307792 -224.110042)
		(width 0.14478)
		(layer "In4.Cu")
		(net "M_J_CPU0_SA_DQ<21>")
	)
	(segment
		(start 383.497836 -239.136682)
		(end 383.506218 -239.141508)
		(width 0.0889)
		(layer "In4.Cu")
		(net "M_J_CPU0_SA_DQ<21>")
	)
	(segment
		(start 421.731186 -224.110042)
		(end 422.58107 -223.260158)
		(width 0.14478)
		(layer "In4.Cu")
		(net "M_J_CPU0_SA_DQ<21>")
	)
	(segment
		(start 429.236378 -224.110042)
		(end 430.086262 -223.260158)
		(width 0.14478)
		(layer "In4.Cu")
		(net "M_J_CPU0_SA_DQ<21>")
	)
	(segment
		(start 414.16224 -224.110042)
		(end 415.012124 -223.260158)
		(width 0.14478)
		(layer "In4.Cu")
		(net "M_J_CPU0_SA_DQ<21>")
	)
	(segment
		(start 385.74345 -239.141508)
		(end 385.751832 -239.136682)
		(width 0.0889)
		(layer "In4.Cu")
		(net "M_J_CPU0_SA_DQ<21>")
	)
	(arc
		(start 390.451848 -239.136682)
		(mid 390.734804 -239.060505)
		(end 391.01776 -239.136682)
		(width 0.0889)
		(layer "In4.Cu")
		(net "M_J_CPU0_SA_DQ<21>")
	)
	(arc
		(start 382.931924 -239.136682)
		(mid 383.21488 -239.060505)
		(end 383.497836 -239.136682)
		(width 0.0889)
		(layer "In4.Cu")
		(net "M_J_CPU0_SA_DQ<21>")
	)
	(arc
		(start 380.111762 -239.136682)
		(mid 380.394718 -239.060505)
		(end 380.677674 -239.136682)
		(width 0.0889)
		(layer "In4.Cu")
		(net "M_J_CPU0_SA_DQ<21>")
	)
	(arc
		(start 381.99187 -239.136682)
		(mid 382.274826 -239.060505)
		(end 382.557782 -239.136682)
		(width 0.0889)
		(layer "In4.Cu")
		(net "M_J_CPU0_SA_DQ<21>")
	)
	(arc
		(start 389.137906 -239.136682)
		(mid 389.32485 -239.186937)
		(end 389.511794 -239.136682)
		(width 0.0889)
		(layer "In4.Cu")
		(net "M_J_CPU0_SA_DQ<21>")
	)
	(arc
		(start 383.871978 -239.136682)
		(mid 384.154934 -239.060505)
		(end 384.43789 -239.136682)
		(width 0.0889)
		(layer "In4.Cu")
		(net "M_J_CPU0_SA_DQ<21>")
	)
	(arc
		(start 391.026142 -239.141508)
		(mid 391.20965 -239.187002)
		(end 391.391902 -239.136682)
		(width 0.0889)
		(layer "In4.Cu")
		(net "M_J_CPU0_SA_DQ<21>")
	)
	(arc
		(start 392.332718 -239.136682)
		(mid 392.612146 -239.060516)
		(end 392.892534 -239.133126)
		(width 0.0889)
		(layer "In4.Cu")
		(net "M_J_CPU0_SA_DQ<21>")
	)
	(arc
		(start 381.617728 -239.136682)
		(mid 381.799979 -239.187032)
		(end 381.983488 -239.141508)
		(width 0.0889)
		(layer "In4.Cu")
		(net "M_J_CPU0_SA_DQ<21>")
	)
	(arc
		(start 381.051816 -239.136682)
		(mid 381.334772 -239.060505)
		(end 381.617728 -239.136682)
		(width 0.0889)
		(layer "In4.Cu")
		(net "M_J_CPU0_SA_DQ<21>")
	)
	(arc
		(start 379.737874 -239.136682)
		(mid 379.924818 -239.186937)
		(end 380.111762 -239.136682)
		(width 0.0889)
		(layer "In4.Cu")
		(net "M_J_CPU0_SA_DQ<21>")
	)
	(arc
		(start 391.406634 -239.128046)
		(mid 391.683617 -239.060242)
		(end 391.958322 -239.136682)
		(width 0.0889)
		(layer "In4.Cu")
		(net "M_J_CPU0_SA_DQ<21>")
	)
	(arc
		(start 387.26618 -239.141508)
		(mid 387.449688 -239.187002)
		(end 387.63194 -239.136682)
		(width 0.0889)
		(layer "In4.Cu")
		(net "M_J_CPU0_SA_DQ<21>")
	)
	(arc
		(start 391.958322 -239.136682)
		(mid 392.13878 -239.187126)
		(end 392.321034 -239.14354)
		(width 0.0889)
		(layer "In4.Cu")
		(net "M_J_CPU0_SA_DQ<21>")
	)
	(arc
		(start 388.571994 -239.136682)
		(mid 388.85495 -239.060505)
		(end 389.137906 -239.136682)
		(width 0.0889)
		(layer "In4.Cu")
		(net "M_J_CPU0_SA_DQ<21>")
	)
	(arc
		(start 382.566164 -239.141508)
		(mid 382.749672 -239.187002)
		(end 382.931924 -239.136682)
		(width 0.0889)
		(layer "In4.Cu")
		(net "M_J_CPU0_SA_DQ<21>")
	)
	(arc
		(start 385.37769 -239.136682)
		(mid 385.559941 -239.187032)
		(end 385.74345 -239.141508)
		(width 0.0889)
		(layer "In4.Cu")
		(net "M_J_CPU0_SA_DQ<21>")
	)
	(arc
		(start 387.63194 -239.136682)
		(mid 387.914896 -239.060505)
		(end 388.197852 -239.136682)
		(width 0.0889)
		(layer "In4.Cu")
		(net "M_J_CPU0_SA_DQ<21>")
	)
	(arc
		(start 383.506218 -239.141508)
		(mid 383.689726 -239.187002)
		(end 383.871978 -239.136682)
		(width 0.0889)
		(layer "In4.Cu")
		(net "M_J_CPU0_SA_DQ<21>")
	)
	(arc
		(start 388.206234 -239.141508)
		(mid 388.389742 -239.187002)
		(end 388.571994 -239.136682)
		(width 0.0889)
		(layer "In4.Cu")
		(net "M_J_CPU0_SA_DQ<21>")
	)
	(arc
		(start 385.751832 -239.136682)
		(mid 386.034788 -239.060505)
		(end 386.317744 -239.136682)
		(width 0.0889)
		(layer "In4.Cu")
		(net "M_J_CPU0_SA_DQ<21>")
	)
	(arc
		(start 384.43789 -239.136682)
		(mid 384.624834 -239.186937)
		(end 384.811778 -239.136682)
		(width 0.0889)
		(layer "In4.Cu")
		(net "M_J_CPU0_SA_DQ<21>")
	)
	(arc
		(start 380.677674 -239.136682)
		(mid 380.859925 -239.187032)
		(end 381.043434 -239.141508)
		(width 0.0889)
		(layer "In4.Cu")
		(net "M_J_CPU0_SA_DQ<21>")
	)
	(arc
		(start 384.811778 -239.136682)
		(mid 385.094734 -239.060505)
		(end 385.37769 -239.136682)
		(width 0.0889)
		(layer "In4.Cu")
		(net "M_J_CPU0_SA_DQ<21>")
	)
	(arc
		(start 389.511794 -239.136682)
		(mid 389.79475 -239.060505)
		(end 390.077706 -239.136682)
		(width 0.0889)
		(layer "In4.Cu")
		(net "M_J_CPU0_SA_DQ<21>")
	)
	(arc
		(start 386.691886 -239.136682)
		(mid 386.974842 -239.060505)
		(end 387.257798 -239.136682)
		(width 0.0889)
		(layer "In4.Cu")
		(net "M_J_CPU0_SA_DQ<21>")
	)
	(arc
		(start 390.077706 -239.136682)
		(mid 390.259957 -239.187032)
		(end 390.443466 -239.141508)
		(width 0.0889)
		(layer "In4.Cu")
		(net "M_J_CPU0_SA_DQ<21>")
	)
	(arc
		(start 386.317744 -239.136682)
		(mid 386.499995 -239.187032)
		(end 386.683504 -239.141508)
		(width 0.0889)
		(layer "In4.Cu")
		(net "M_J_CPU0_SA_DQ<21>")
	)
	(arc
		(start 379.235208 -239.104932)
		(mid 379.490273 -239.061581)
		(end 379.737874 -239.136682)
		(width 0.0889)
		(layer "In4.Cu")
		(net "M_J_CPU0_SA_DQ<21>")
	)
	(arc
		(start 392.91641 -239.146842)
		(mid 393.095639 -239.186995)
		(end 393.272264 -239.136682)
		(width 0.0889)
		(layer "In4.Cu")
		(net "M_J_CPU0_SA_DQ<21>")
	)
	(segment
		(start 379.927866 -238.270034)
		(end 380.394718 -238.004096)
		(width 0.10668)
		(layer "F.Cu")
		(net "M_J_CPU0_SA_DQ<20>")
	)
	(segment
		(start 393.61237 -238.250222)
		(end 395.439392 -236.4232)
		(width 0.0889)
		(layer "In4.Cu")
		(net "M_J_CPU0_SA_DQ<20>")
	)
	(segment
		(start 415.120328 -221.560136)
		(end 417.486084 -221.560136)
		(width 0.14478)
		(layer "In4.Cu")
		(net "M_J_CPU0_SA_DQ<20>")
	)
	(segment
		(start 438.675272 -221.560136)
		(end 439.100214 -221.985078)
		(width 0.14478)
		(layer "In4.Cu")
		(net "M_J_CPU0_SA_DQ<20>")
	)
	(segment
		(start 421.583612 -222.419672)
		(end 422.433496 -221.569788)
		(width 0.14478)
		(layer "In4.Cu")
		(net "M_J_CPU0_SA_DQ<20>")
	)
	(segment
		(start 395.439392 -236.4232)
		(end 395.796262 -236.4232)
		(width 0.0889)
		(layer "In4.Cu")
		(net "M_J_CPU0_SA_DQ<20>")
	)
	(segment
		(start 393.084812 -238.250222)
		(end 393.61237 -238.250222)
		(width 0.0889)
		(layer "In4.Cu")
		(net "M_J_CPU0_SA_DQ<20>")
	)
	(segment
		(start 437.363108 -222.160846)
		(end 437.526176 -222.323914)
		(width 0.14478)
		(layer "In4.Cu")
		(net "M_J_CPU0_SA_DQ<20>")
	)
	(segment
		(start 383.393442 -238.331502)
		(end 383.401824 -238.326676)
		(width 0.0889)
		(layer "In4.Cu")
		(net "M_J_CPU0_SA_DQ<20>")
	)
	(segment
		(start 437.526176 -222.323914)
		(end 437.756554 -222.323914)
		(width 0.14478)
		(layer "In4.Cu")
		(net "M_J_CPU0_SA_DQ<20>")
	)
	(segment
		(start 437.919622 -222.160846)
		(end 437.919622 -221.723204)
		(width 0.14478)
		(layer "In4.Cu")
		(net "M_J_CPU0_SA_DQ<20>")
	)
	(segment
		(start 381.147828 -238.326676)
		(end 381.15621 -238.331502)
		(width 0.0889)
		(layer "In4.Cu")
		(net "M_J_CPU0_SA_DQ<20>")
	)
	(segment
		(start 414.270444 -222.41002)
		(end 415.120328 -221.560136)
		(width 0.14478)
		(layer "In4.Cu")
		(net "M_J_CPU0_SA_DQ<20>")
	)
	(segment
		(start 388.093458 -238.331502)
		(end 388.10184 -238.326676)
		(width 0.0889)
		(layer "In4.Cu")
		(net "M_J_CPU0_SA_DQ<20>")
	)
	(segment
		(start 397.45539 -236.4232)
		(end 404.853902 -229.024688)
		(width 0.14478)
		(layer "In4.Cu")
		(net "M_J_CPU0_SA_DQ<20>")
	)
	(segment
		(start 389.607806 -238.326676)
		(end 389.616188 -238.331502)
		(width 0.0889)
		(layer "In4.Cu")
		(net "M_J_CPU0_SA_DQ<20>")
	)
	(segment
		(start 437.209692 -221.569788)
		(end 437.363108 -221.723204)
		(width 0.14478)
		(layer "In4.Cu")
		(net "M_J_CPU0_SA_DQ<20>")
	)
	(segment
		(start 380.394718 -238.004096)
		(end 380.548896 -238.269526)
		(width 0.0889)
		(layer "In4.Cu")
		(net "M_J_CPU0_SA_DQ<20>")
	)
	(segment
		(start 437.363108 -221.723204)
		(end 437.363108 -222.160846)
		(width 0.14478)
		(layer "In4.Cu")
		(net "M_J_CPU0_SA_DQ<20>")
	)
	(segment
		(start 404.853902 -229.024688)
		(end 404.853902 -226.656392)
		(width 0.14478)
		(layer "In4.Cu")
		(net "M_J_CPU0_SA_DQ<20>")
	)
	(segment
		(start 404.853902 -226.656392)
		(end 409.100274 -222.41002)
		(width 0.14478)
		(layer "In4.Cu")
		(net "M_J_CPU0_SA_DQ<20>")
	)
	(segment
		(start 426.155866 -222.419672)
		(end 429.46574 -222.419672)
		(width 0.14478)
		(layer "In4.Cu")
		(net "M_J_CPU0_SA_DQ<20>")
	)
	(segment
		(start 385.847844 -238.326676)
		(end 385.856226 -238.331502)
		(width 0.0889)
		(layer "In4.Cu")
		(net "M_J_CPU0_SA_DQ<20>")
	)
	(segment
		(start 384.90779 -238.326676)
		(end 384.916172 -238.331502)
		(width 0.0889)
		(layer "In4.Cu")
		(net "M_J_CPU0_SA_DQ<20>")
	)
	(segment
		(start 380.548896 -238.269526)
		(end 380.645162 -238.294926)
		(width 0.0889)
		(layer "In4.Cu")
		(net "M_J_CPU0_SA_DQ<20>")
	)
	(segment
		(start 425.305982 -221.569788)
		(end 426.155866 -222.419672)
		(width 0.14478)
		(layer "In4.Cu")
		(net "M_J_CPU0_SA_DQ<20>")
	)
	(segment
		(start 430.315624 -221.569788)
		(end 437.209692 -221.569788)
		(width 0.14478)
		(layer "In4.Cu")
		(net "M_J_CPU0_SA_DQ<20>")
	)
	(segment
		(start 389.033512 -238.331502)
		(end 389.041894 -238.326676)
		(width 0.0889)
		(layer "In4.Cu")
		(net "M_J_CPU0_SA_DQ<20>")
	)
	(segment
		(start 384.333496 -238.331502)
		(end 384.341878 -238.326676)
		(width 0.0889)
		(layer "In4.Cu")
		(net "M_J_CPU0_SA_DQ<20>")
	)
	(segment
		(start 395.796262 -236.4232)
		(end 397.45539 -236.4232)
		(width 0.14478)
		(layer "In4.Cu")
		(net "M_J_CPU0_SA_DQ<20>")
	)
	(segment
		(start 429.46574 -222.419672)
		(end 430.315624 -221.569788)
		(width 0.14478)
		(layer "In4.Cu")
		(net "M_J_CPU0_SA_DQ<20>")
	)
	(segment
		(start 392.418062 -238.32058)
		(end 392.428476 -238.326676)
		(width 0.0889)
		(layer "In4.Cu")
		(net "M_J_CPU0_SA_DQ<20>")
	)
	(segment
		(start 437.756554 -222.323914)
		(end 437.919622 -222.160846)
		(width 0.14478)
		(layer "In4.Cu")
		(net "M_J_CPU0_SA_DQ<20>")
	)
	(segment
		(start 409.100274 -222.41002)
		(end 414.270444 -222.41002)
		(width 0.14478)
		(layer "In4.Cu")
		(net "M_J_CPU0_SA_DQ<20>")
	)
	(segment
		(start 417.486084 -221.560136)
		(end 418.34562 -222.419672)
		(width 0.14478)
		(layer "In4.Cu")
		(net "M_J_CPU0_SA_DQ<20>")
	)
	(segment
		(start 438.08269 -221.560136)
		(end 438.675272 -221.560136)
		(width 0.14478)
		(layer "In4.Cu")
		(net "M_J_CPU0_SA_DQ<20>")
	)
	(segment
		(start 391.48766 -238.326676)
		(end 391.496042 -238.331502)
		(width 0.0889)
		(layer "In4.Cu")
		(net "M_J_CPU0_SA_DQ<20>")
	)
	(segment
		(start 418.34562 -222.419672)
		(end 421.583612 -222.419672)
		(width 0.14478)
		(layer "In4.Cu")
		(net "M_J_CPU0_SA_DQ<20>")
	)
	(segment
		(start 422.433496 -221.569788)
		(end 425.305982 -221.569788)
		(width 0.14478)
		(layer "In4.Cu")
		(net "M_J_CPU0_SA_DQ<20>")
	)
	(segment
		(start 437.919622 -221.723204)
		(end 438.08269 -221.560136)
		(width 0.14478)
		(layer "In4.Cu")
		(net "M_J_CPU0_SA_DQ<20>")
	)
	(arc
		(start 386.221986 -238.326676)
		(mid 386.504942 -238.250499)
		(end 386.787898 -238.326676)
		(width 0.0889)
		(layer "In4.Cu")
		(net "M_J_CPU0_SA_DQ<20>")
	)
	(arc
		(start 384.916172 -238.331502)
		(mid 385.09968 -238.376996)
		(end 385.281932 -238.326676)
		(width 0.0889)
		(layer "In4.Cu")
		(net "M_J_CPU0_SA_DQ<20>")
	)
	(arc
		(start 391.86231 -238.326676)
		(mid 392.139377 -238.250405)
		(end 392.418062 -238.32058)
		(width 0.0889)
		(layer "In4.Cu")
		(net "M_J_CPU0_SA_DQ<20>")
	)
	(arc
		(start 387.727698 -238.326676)
		(mid 387.909949 -238.377026)
		(end 388.093458 -238.331502)
		(width 0.0889)
		(layer "In4.Cu")
		(net "M_J_CPU0_SA_DQ<20>")
	)
	(arc
		(start 385.856226 -238.331502)
		(mid 386.039734 -238.376996)
		(end 386.221986 -238.326676)
		(width 0.0889)
		(layer "In4.Cu")
		(net "M_J_CPU0_SA_DQ<20>")
	)
	(arc
		(start 386.787898 -238.326676)
		(mid 386.974842 -238.376931)
		(end 387.161786 -238.326676)
		(width 0.0889)
		(layer "In4.Cu")
		(net "M_J_CPU0_SA_DQ<20>")
	)
	(arc
		(start 383.401824 -238.326676)
		(mid 383.68478 -238.250499)
		(end 383.967736 -238.326676)
		(width 0.0889)
		(layer "In4.Cu")
		(net "M_J_CPU0_SA_DQ<20>")
	)
	(arc
		(start 389.616188 -238.331502)
		(mid 389.799696 -238.376996)
		(end 389.981948 -238.326676)
		(width 0.0889)
		(layer "In4.Cu")
		(net "M_J_CPU0_SA_DQ<20>")
	)
	(arc
		(start 392.786108 -238.33582)
		(mid 392.929447 -238.272033)
		(end 393.084812 -238.250222)
		(width 0.0889)
		(layer "In4.Cu")
		(net "M_J_CPU0_SA_DQ<20>")
	)
	(arc
		(start 381.52197 -238.326676)
		(mid 381.804926 -238.250499)
		(end 382.087882 -238.326676)
		(width 0.0889)
		(layer "In4.Cu")
		(net "M_J_CPU0_SA_DQ<20>")
	)
	(arc
		(start 391.496042 -238.331502)
		(mid 391.679804 -238.377118)
		(end 391.86231 -238.326676)
		(width 0.0889)
		(layer "In4.Cu")
		(net "M_J_CPU0_SA_DQ<20>")
	)
	(arc
		(start 382.087882 -238.326676)
		(mid 382.274826 -238.376931)
		(end 382.46177 -238.326676)
		(width 0.0889)
		(layer "In4.Cu")
		(net "M_J_CPU0_SA_DQ<20>")
	)
	(arc
		(start 382.46177 -238.326676)
		(mid 382.744726 -238.250499)
		(end 383.027682 -238.326676)
		(width 0.0889)
		(layer "In4.Cu")
		(net "M_J_CPU0_SA_DQ<20>")
	)
	(arc
		(start 390.54786 -238.326676)
		(mid 390.734804 -238.376931)
		(end 390.921748 -238.326676)
		(width 0.0889)
		(layer "In4.Cu")
		(net "M_J_CPU0_SA_DQ<20>")
	)
	(arc
		(start 389.041894 -238.326676)
		(mid 389.32485 -238.250499)
		(end 389.607806 -238.326676)
		(width 0.0889)
		(layer "In4.Cu")
		(net "M_J_CPU0_SA_DQ<20>")
	)
	(arc
		(start 383.967736 -238.326676)
		(mid 384.149987 -238.377026)
		(end 384.333496 -238.331502)
		(width 0.0889)
		(layer "In4.Cu")
		(net "M_J_CPU0_SA_DQ<20>")
	)
	(arc
		(start 390.921748 -238.326676)
		(mid 391.204704 -238.250499)
		(end 391.48766 -238.326676)
		(width 0.0889)
		(layer "In4.Cu")
		(net "M_J_CPU0_SA_DQ<20>")
	)
	(arc
		(start 381.15621 -238.331502)
		(mid 381.339718 -238.376996)
		(end 381.52197 -238.326676)
		(width 0.0889)
		(layer "In4.Cu")
		(net "M_J_CPU0_SA_DQ<20>")
	)
	(arc
		(start 383.027682 -238.326676)
		(mid 383.209933 -238.377026)
		(end 383.393442 -238.331502)
		(width 0.0889)
		(layer "In4.Cu")
		(net "M_J_CPU0_SA_DQ<20>")
	)
	(arc
		(start 387.161786 -238.326676)
		(mid 387.444742 -238.250499)
		(end 387.727698 -238.326676)
		(width 0.0889)
		(layer "In4.Cu")
		(net "M_J_CPU0_SA_DQ<20>")
	)
	(arc
		(start 388.667752 -238.326676)
		(mid 388.850003 -238.377026)
		(end 389.033512 -238.331502)
		(width 0.0889)
		(layer "In4.Cu")
		(net "M_J_CPU0_SA_DQ<20>")
	)
	(arc
		(start 389.981948 -238.326676)
		(mid 390.264904 -238.250499)
		(end 390.54786 -238.326676)
		(width 0.0889)
		(layer "In4.Cu")
		(net "M_J_CPU0_SA_DQ<20>")
	)
	(arc
		(start 388.10184 -238.326676)
		(mid 388.384796 -238.250499)
		(end 388.667752 -238.326676)
		(width 0.0889)
		(layer "In4.Cu")
		(net "M_J_CPU0_SA_DQ<20>")
	)
	(arc
		(start 392.428476 -238.326676)
		(mid 392.606126 -238.376936)
		(end 392.786108 -238.33582)
		(width 0.0889)
		(layer "In4.Cu")
		(net "M_J_CPU0_SA_DQ<20>")
	)
	(arc
		(start 385.281932 -238.326676)
		(mid 385.564888 -238.250499)
		(end 385.847844 -238.326676)
		(width 0.0889)
		(layer "In4.Cu")
		(net "M_J_CPU0_SA_DQ<20>")
	)
	(arc
		(start 380.645162 -238.294926)
		(mid 380.900227 -238.251575)
		(end 381.147828 -238.326676)
		(width 0.0889)
		(layer "In4.Cu")
		(net "M_J_CPU0_SA_DQ<20>")
	)
	(arc
		(start 384.341878 -238.326676)
		(mid 384.624834 -238.250499)
		(end 384.90779 -238.326676)
		(width 0.0889)
		(layer "In4.Cu")
		(net "M_J_CPU0_SA_DQ<20>")
	)
	(segment
		(start 378.517912 -226.120198)
		(end 378.984764 -225.85426)
		(width 0.10668)
		(layer "F.Cu")
		(net "M_J_CPU0_SA_DQ<1>")
	)
	(segment
		(start 390.962896 -221.39783)
		(end 390.962896 -221.28861)
		(width 0.0889)
		(layer "In4.Cu")
		(net "M_J_CPU0_SA_DQ<1>")
	)
	(segment
		(start 405.642064 -202.818238)
		(end 405.642064 -201.52741)
		(width 0.14478)
		(layer "In4.Cu")
		(net "M_J_CPU0_SA_DQ<1>")
	)
	(segment
		(start 383.497836 -226.17684)
		(end 383.506218 -226.181666)
		(width 0.0889)
		(layer "In4.Cu")
		(net "M_J_CPU0_SA_DQ<1>")
	)
	(segment
		(start 390.962896 -221.28861)
		(end 390.962896 -217.497406)
		(width 0.14478)
		(layer "In4.Cu")
		(net "M_J_CPU0_SA_DQ<1>")
	)
	(segment
		(start 390.418828 -222.95612)
		(end 390.452356 -222.936562)
		(width 0.0889)
		(layer "In4.Cu")
		(net "M_J_CPU0_SA_DQ<1>")
	)
	(segment
		(start 390.887204 -222.146876)
		(end 390.92251 -222.126556)
		(width 0.0889)
		(layer "In4.Cu")
		(net "M_J_CPU0_SA_DQ<1>")
	)
	(segment
		(start 379.138942 -226.11969)
		(end 379.235208 -226.14509)
		(width 0.0889)
		(layer "In4.Cu")
		(net "M_J_CPU0_SA_DQ<1>")
	)
	(segment
		(start 385.74345 -226.181666)
		(end 385.751832 -226.17684)
		(width 0.0889)
		(layer "In4.Cu")
		(net "M_J_CPU0_SA_DQ<1>")
	)
	(segment
		(start 390.452356 -222.936562)
		(end 390.482582 -222.919036)
		(width 0.0889)
		(layer "In4.Cu")
		(net "M_J_CPU0_SA_DQ<1>")
	)
	(segment
		(start 430.674526 -198.61022)
		(end 436.96382 -198.61022)
		(width 0.14478)
		(layer "In4.Cu")
		(net "M_J_CPU0_SA_DQ<1>")
	)
	(segment
		(start 389.475472 -224.57791)
		(end 389.511794 -224.556828)
		(width 0.0889)
		(layer "In4.Cu")
		(net "M_J_CPU0_SA_DQ<1>")
	)
	(segment
		(start 390.92251 -222.126556)
		(end 390.957054 -222.10649)
		(width 0.0889)
		(layer "In4.Cu")
		(net "M_J_CPU0_SA_DQ<1>")
	)
	(segment
		(start 378.984764 -225.85426)
		(end 379.138942 -226.11969)
		(width 0.0889)
		(layer "In4.Cu")
		(net "M_J_CPU0_SA_DQ<1>")
	)
	(segment
		(start 381.983488 -226.181666)
		(end 381.99187 -226.17684)
		(width 0.0889)
		(layer "In4.Cu")
		(net "M_J_CPU0_SA_DQ<1>")
	)
	(segment
		(start 391.11047 -221.80423)
		(end 391.11047 -221.545404)
		(width 0.0889)
		(layer "In4.Cu")
		(net "M_J_CPU0_SA_DQ<1>")
	)
	(segment
		(start 382.557782 -226.17684)
		(end 382.566164 -226.181666)
		(width 0.0889)
		(layer "In4.Cu")
		(net "M_J_CPU0_SA_DQ<1>")
	)
	(segment
		(start 415.595308 -198.61022)
		(end 417.65474 -198.61022)
		(width 0.14478)
		(layer "In4.Cu")
		(net "M_J_CPU0_SA_DQ<1>")
	)
	(segment
		(start 389.041894 -225.366834)
		(end 389.073644 -225.348546)
		(width 0.0889)
		(layer "In4.Cu")
		(net "M_J_CPU0_SA_DQ<1>")
	)
	(segment
		(start 405.642064 -201.52741)
		(end 407.70937 -199.460104)
		(width 0.14478)
		(layer "In4.Cu")
		(net "M_J_CPU0_SA_DQ<1>")
	)
	(segment
		(start 436.96382 -198.61022)
		(end 439.100214 -199.035162)
		(width 0.14478)
		(layer "In4.Cu")
		(net "M_J_CPU0_SA_DQ<1>")
	)
	(segment
		(start 413.543496 -199.460104)
		(end 415.595308 -198.61022)
		(width 0.14478)
		(layer "In4.Cu")
		(net "M_J_CPU0_SA_DQ<1>")
	)
	(segment
		(start 387.257798 -226.17684)
		(end 387.26618 -226.181666)
		(width 0.0889)
		(layer "In4.Cu")
		(net "M_J_CPU0_SA_DQ<1>")
	)
	(segment
		(start 389.982202 -223.746822)
		(end 390.012936 -223.729042)
		(width 0.0889)
		(layer "In4.Cu")
		(net "M_J_CPU0_SA_DQ<1>")
	)
	(segment
		(start 389.511794 -224.556828)
		(end 389.543544 -224.53854)
		(width 0.0889)
		(layer "In4.Cu")
		(net "M_J_CPU0_SA_DQ<1>")
	)
	(segment
		(start 419.706552 -199.460104)
		(end 420.693596 -199.460104)
		(width 0.14478)
		(layer "In4.Cu")
		(net "M_J_CPU0_SA_DQ<1>")
	)
	(segment
		(start 417.65474 -198.61022)
		(end 419.706552 -199.460104)
		(width 0.14478)
		(layer "In4.Cu")
		(net "M_J_CPU0_SA_DQ<1>")
	)
	(segment
		(start 388.197852 -226.17684)
		(end 388.206234 -226.181666)
		(width 0.0889)
		(layer "In4.Cu")
		(net "M_J_CPU0_SA_DQ<1>")
	)
	(segment
		(start 391.11047 -221.545404)
		(end 390.962896 -221.39783)
		(width 0.0889)
		(layer "In4.Cu")
		(net "M_J_CPU0_SA_DQ<1>")
	)
	(segment
		(start 389.941816 -223.770444)
		(end 389.982202 -223.746822)
		(width 0.0889)
		(layer "In4.Cu")
		(net "M_J_CPU0_SA_DQ<1>")
	)
	(segment
		(start 427.353222 -199.460104)
		(end 428.622714 -199.460104)
		(width 0.14478)
		(layer "In4.Cu")
		(net "M_J_CPU0_SA_DQ<1>")
	)
	(segment
		(start 386.683504 -226.181666)
		(end 386.691886 -226.17684)
		(width 0.0889)
		(layer "In4.Cu")
		(net "M_J_CPU0_SA_DQ<1>")
	)
	(segment
		(start 407.70937 -199.460104)
		(end 413.543496 -199.460104)
		(width 0.14478)
		(layer "In4.Cu")
		(net "M_J_CPU0_SA_DQ<1>")
	)
	(segment
		(start 428.622714 -199.460104)
		(end 430.674526 -198.61022)
		(width 0.14478)
		(layer "In4.Cu")
		(net "M_J_CPU0_SA_DQ<1>")
	)
	(segment
		(start 388.571994 -226.17684)
		(end 388.602474 -226.15906)
		(width 0.0889)
		(layer "In4.Cu")
		(net "M_J_CPU0_SA_DQ<1>")
	)
	(segment
		(start 381.043434 -226.181666)
		(end 381.051816 -226.17684)
		(width 0.0889)
		(layer "In4.Cu")
		(net "M_J_CPU0_SA_DQ<1>")
	)
	(segment
		(start 389.002778 -225.389694)
		(end 389.041894 -225.366834)
		(width 0.0889)
		(layer "In4.Cu")
		(net "M_J_CPU0_SA_DQ<1>")
	)
	(segment
		(start 422.745408 -198.61022)
		(end 425.30141 -198.61022)
		(width 0.14478)
		(layer "In4.Cu")
		(net "M_J_CPU0_SA_DQ<1>")
	)
	(segment
		(start 420.693596 -199.460104)
		(end 422.745408 -198.61022)
		(width 0.14478)
		(layer "In4.Cu")
		(net "M_J_CPU0_SA_DQ<1>")
	)
	(segment
		(start 425.30141 -198.61022)
		(end 427.353222 -199.460104)
		(width 0.14478)
		(layer "In4.Cu")
		(net "M_J_CPU0_SA_DQ<1>")
	)
	(segment
		(start 390.962896 -217.497406)
		(end 405.642064 -202.818238)
		(width 0.14478)
		(layer "In4.Cu")
		(net "M_J_CPU0_SA_DQ<1>")
	)
	(arc
		(start 390.012936 -223.729042)
		(mid 390.128363 -223.595666)
		(end 390.169908 -223.424242)
		(width 0.0889)
		(layer "In4.Cu")
		(net "M_J_CPU0_SA_DQ<1>")
	)
	(arc
		(start 384.43789 -226.17684)
		(mid 384.624834 -226.227095)
		(end 384.811778 -226.17684)
		(width 0.0889)
		(layer "In4.Cu")
		(net "M_J_CPU0_SA_DQ<1>")
	)
	(arc
		(start 383.871978 -226.17684)
		(mid 384.154934 -226.100663)
		(end 384.43789 -226.17684)
		(width 0.0889)
		(layer "In4.Cu")
		(net "M_J_CPU0_SA_DQ<1>")
	)
	(arc
		(start 382.931924 -226.17684)
		(mid 383.21488 -226.100663)
		(end 383.497836 -226.17684)
		(width 0.0889)
		(layer "In4.Cu")
		(net "M_J_CPU0_SA_DQ<1>")
	)
	(arc
		(start 380.111762 -226.17684)
		(mid 380.394718 -226.100663)
		(end 380.677674 -226.17684)
		(width 0.0889)
		(layer "In4.Cu")
		(net "M_J_CPU0_SA_DQ<1>")
	)
	(arc
		(start 388.759446 -225.85426)
		(mid 388.823961 -225.592041)
		(end 389.002778 -225.389694)
		(width 0.0889)
		(layer "In4.Cu")
		(net "M_J_CPU0_SA_DQ<1>")
	)
	(arc
		(start 390.169908 -223.424242)
		(mid 390.236007 -223.159148)
		(end 390.418828 -222.95612)
		(width 0.0889)
		(layer "In4.Cu")
		(net "M_J_CPU0_SA_DQ<1>")
	)
	(arc
		(start 381.617728 -226.17684)
		(mid 381.799979 -226.22719)
		(end 381.983488 -226.181666)
		(width 0.0889)
		(layer "In4.Cu")
		(net "M_J_CPU0_SA_DQ<1>")
	)
	(arc
		(start 387.63194 -226.17684)
		(mid 387.914896 -226.100663)
		(end 388.197852 -226.17684)
		(width 0.0889)
		(layer "In4.Cu")
		(net "M_J_CPU0_SA_DQ<1>")
	)
	(arc
		(start 388.206234 -226.181666)
		(mid 388.389742 -226.22716)
		(end 388.571994 -226.17684)
		(width 0.0889)
		(layer "In4.Cu")
		(net "M_J_CPU0_SA_DQ<1>")
	)
	(arc
		(start 379.235208 -226.14509)
		(mid 379.490273 -226.101739)
		(end 379.737874 -226.17684)
		(width 0.0889)
		(layer "In4.Cu")
		(net "M_J_CPU0_SA_DQ<1>")
	)
	(arc
		(start 390.957054 -222.10649)
		(mid 391.06994 -221.973719)
		(end 391.11047 -221.80423)
		(width 0.0889)
		(layer "In4.Cu")
		(net "M_J_CPU0_SA_DQ<1>")
	)
	(arc
		(start 389.2296 -225.044254)
		(mid 389.294836 -224.780663)
		(end 389.475472 -224.57791)
		(width 0.0889)
		(layer "In4.Cu")
		(net "M_J_CPU0_SA_DQ<1>")
	)
	(arc
		(start 382.566164 -226.181666)
		(mid 382.749672 -226.22716)
		(end 382.931924 -226.17684)
		(width 0.0889)
		(layer "In4.Cu")
		(net "M_J_CPU0_SA_DQ<1>")
	)
	(arc
		(start 385.751832 -226.17684)
		(mid 386.034788 -226.100663)
		(end 386.317744 -226.17684)
		(width 0.0889)
		(layer "In4.Cu")
		(net "M_J_CPU0_SA_DQ<1>")
	)
	(arc
		(start 390.482582 -222.919036)
		(mid 390.598161 -222.785709)
		(end 390.639808 -222.614236)
		(width 0.0889)
		(layer "In4.Cu")
		(net "M_J_CPU0_SA_DQ<1>")
	)
	(arc
		(start 379.737874 -226.17684)
		(mid 379.924818 -226.227095)
		(end 380.111762 -226.17684)
		(width 0.0889)
		(layer "In4.Cu")
		(net "M_J_CPU0_SA_DQ<1>")
	)
	(arc
		(start 385.37769 -226.17684)
		(mid 385.559941 -226.22719)
		(end 385.74345 -226.181666)
		(width 0.0889)
		(layer "In4.Cu")
		(net "M_J_CPU0_SA_DQ<1>")
	)
	(arc
		(start 388.602474 -226.15906)
		(mid 388.717901 -226.025684)
		(end 388.759446 -225.85426)
		(width 0.0889)
		(layer "In4.Cu")
		(net "M_J_CPU0_SA_DQ<1>")
	)
	(arc
		(start 381.051816 -226.17684)
		(mid 381.334772 -226.100663)
		(end 381.617728 -226.17684)
		(width 0.0889)
		(layer "In4.Cu")
		(net "M_J_CPU0_SA_DQ<1>")
	)
	(arc
		(start 389.543544 -224.53854)
		(mid 389.65822 -224.405206)
		(end 389.6995 -224.234248)
		(width 0.0889)
		(layer "In4.Cu")
		(net "M_J_CPU0_SA_DQ<1>")
	)
	(arc
		(start 387.26618 -226.181666)
		(mid 387.449688 -226.22716)
		(end 387.63194 -226.17684)
		(width 0.0889)
		(layer "In4.Cu")
		(net "M_J_CPU0_SA_DQ<1>")
	)
	(arc
		(start 389.073644 -225.348546)
		(mid 389.18832 -225.215212)
		(end 389.2296 -225.044254)
		(width 0.0889)
		(layer "In4.Cu")
		(net "M_J_CPU0_SA_DQ<1>")
	)
	(arc
		(start 384.811778 -226.17684)
		(mid 385.094734 -226.100663)
		(end 385.37769 -226.17684)
		(width 0.0889)
		(layer "In4.Cu")
		(net "M_J_CPU0_SA_DQ<1>")
	)
	(arc
		(start 386.691886 -226.17684)
		(mid 386.974842 -226.100663)
		(end 387.257798 -226.17684)
		(width 0.0889)
		(layer "In4.Cu")
		(net "M_J_CPU0_SA_DQ<1>")
	)
	(arc
		(start 386.317744 -226.17684)
		(mid 386.499995 -226.22719)
		(end 386.683504 -226.181666)
		(width 0.0889)
		(layer "In4.Cu")
		(net "M_J_CPU0_SA_DQ<1>")
	)
	(arc
		(start 380.677674 -226.17684)
		(mid 380.859925 -226.22719)
		(end 381.043434 -226.181666)
		(width 0.0889)
		(layer "In4.Cu")
		(net "M_J_CPU0_SA_DQ<1>")
	)
	(arc
		(start 389.6995 -224.234248)
		(mid 389.763793 -223.972643)
		(end 389.941816 -223.770444)
		(width 0.0889)
		(layer "In4.Cu")
		(net "M_J_CPU0_SA_DQ<1>")
	)
	(arc
		(start 381.99187 -226.17684)
		(mid 382.274826 -226.100663)
		(end 382.557782 -226.17684)
		(width 0.0889)
		(layer "In4.Cu")
		(net "M_J_CPU0_SA_DQ<1>")
	)
	(arc
		(start 390.639808 -222.614236)
		(mid 390.705471 -222.349835)
		(end 390.887204 -222.146876)
		(width 0.0889)
		(layer "In4.Cu")
		(net "M_J_CPU0_SA_DQ<1>")
	)
	(arc
		(start 383.506218 -226.181666)
		(mid 383.689726 -226.22716)
		(end 383.871978 -226.17684)
		(width 0.0889)
		(layer "In4.Cu")
		(net "M_J_CPU0_SA_DQ<1>")
	)
	(segment
		(start 378.988066 -236.650022)
		(end 379.454918 -236.384084)
		(width 0.10668)
		(layer "F.Cu")
		(net "M_J_CPU0_SA_DQ<19>")
	)
	(segment
		(start 404.820628 -223.167194)
		(end 405.049228 -223.167194)
		(width 0.14478)
		(layer "In4.Cu")
		(net "M_J_CPU0_SA_DQ<19>")
	)
	(segment
		(start 426.064426 -218.15044)
		(end 426.914564 -219.000578)
		(width 0.14478)
		(layer "In4.Cu")
		(net "M_J_CPU0_SA_DQ<19>")
	)
	(segment
		(start 402.565362 -225.65106)
		(end 402.869908 -225.346514)
		(width 0.14478)
		(layer "In4.Cu")
		(net "M_J_CPU0_SA_DQ<19>")
	)
	(segment
		(start 379.63348 -236.056678)
		(end 379.641862 -236.061504)
		(width 0.0889)
		(layer "In4.Cu")
		(net "M_J_CPU0_SA_DQ<19>")
	)
	(segment
		(start 403.824694 -223.731836)
		(end 404.04034 -223.947482)
		(width 0.14478)
		(layer "In4.Cu")
		(net "M_J_CPU0_SA_DQ<19>")
	)
	(segment
		(start 394.585444 -234.57789)
		(end 394.840968 -234.57789)
		(width 0.0889)
		(layer "In4.Cu")
		(net "M_J_CPU0_SA_DQ<19>")
	)
	(segment
		(start 404.995126 -222.561404)
		(end 404.995126 -222.332804)
		(width 0.14478)
		(layer "In4.Cu")
		(net "M_J_CPU0_SA_DQ<19>")
	)
	(segment
		(start 402.565362 -228.045772)
		(end 402.565362 -225.65106)
		(width 0.14478)
		(layer "In4.Cu")
		(net "M_J_CPU0_SA_DQ<19>")
	)
	(segment
		(start 414.005776 -219.01023)
		(end 414.855914 -218.160092)
		(width 0.14478)
		(layer "In4.Cu")
		(net "M_J_CPU0_SA_DQ<19>")
	)
	(segment
		(start 404.430484 -223.785938)
		(end 404.430484 -223.557338)
		(width 0.14478)
		(layer "In4.Cu")
		(net "M_J_CPU0_SA_DQ<19>")
	)
	(segment
		(start 402.869908 -225.346514)
		(end 402.869908 -225.117914)
		(width 0.14478)
		(layer "In4.Cu")
		(net "M_J_CPU0_SA_DQ<19>")
	)
	(segment
		(start 380.207774 -236.061504)
		(end 380.216156 -236.056678)
		(width 0.0889)
		(layer "In4.Cu")
		(net "M_J_CPU0_SA_DQ<19>")
	)
	(segment
		(start 418.980112 -219.000324)
		(end 421.346376 -219.000324)
		(width 0.14478)
		(layer "In4.Cu")
		(net "M_J_CPU0_SA_DQ<19>")
	)
	(segment
		(start 414.855914 -218.160092)
		(end 418.13988 -218.160092)
		(width 0.14478)
		(layer "In4.Cu")
		(net "M_J_CPU0_SA_DQ<19>")
	)
	(segment
		(start 395.768322 -233.96194)
		(end 396.649194 -233.96194)
		(width 0.14478)
		(layer "In4.Cu")
		(net "M_J_CPU0_SA_DQ<19>")
	)
	(segment
		(start 404.995126 -222.332804)
		(end 405.15667 -222.17126)
		(width 0.14478)
		(layer "In4.Cu")
		(net "M_J_CPU0_SA_DQ<19>")
	)
	(segment
		(start 429.915828 -218.15044)
		(end 434.565552 -218.15044)
		(width 0.14478)
		(layer "In4.Cu")
		(net "M_J_CPU0_SA_DQ<19>")
	)
	(segment
		(start 391.48766 -236.061504)
		(end 391.496042 -236.056678)
		(width 0.0889)
		(layer "In4.Cu")
		(net "M_J_CPU0_SA_DQ<19>")
	)
	(segment
		(start 392.146028 -236.137958)
		(end 393.370816 -236.137958)
		(width 0.0889)
		(layer "In4.Cu")
		(net "M_J_CPU0_SA_DQ<19>")
	)
	(segment
		(start 402.815806 -224.512124)
		(end 403.044406 -224.512124)
		(width 0.14478)
		(layer "In4.Cu")
		(net "M_J_CPU0_SA_DQ<19>")
	)
	(segment
		(start 405.15667 -222.17126)
		(end 405.38527 -222.17126)
		(width 0.14478)
		(layer "In4.Cu")
		(net "M_J_CPU0_SA_DQ<19>")
	)
	(segment
		(start 393.370816 -236.137958)
		(end 394.297916 -235.210858)
		(width 0.0889)
		(layer "In4.Cu")
		(net "M_J_CPU0_SA_DQ<19>")
	)
	(segment
		(start 384.333496 -236.056678)
		(end 384.341878 -236.061504)
		(width 0.0889)
		(layer "In4.Cu")
		(net "M_J_CPU0_SA_DQ<19>")
	)
	(segment
		(start 379.30074 -236.118654)
		(end 379.323092 -236.035342)
		(width 0.0889)
		(layer "In4.Cu")
		(net "M_J_CPU0_SA_DQ<19>")
	)
	(segment
		(start 379.454918 -236.384084)
		(end 379.30074 -236.118654)
		(width 0.0889)
		(layer "In4.Cu")
		(net "M_J_CPU0_SA_DQ<19>")
	)
	(segment
		(start 434.565552 -218.15044)
		(end 435.000146 -218.585034)
		(width 0.14478)
		(layer "In4.Cu")
		(net "M_J_CPU0_SA_DQ<19>")
	)
	(segment
		(start 403.650196 -224.337626)
		(end 403.43455 -224.12198)
		(width 0.14478)
		(layer "In4.Cu")
		(net "M_J_CPU0_SA_DQ<19>")
	)
	(segment
		(start 426.914564 -219.000578)
		(end 429.06569 -219.000578)
		(width 0.14478)
		(layer "In4.Cu")
		(net "M_J_CPU0_SA_DQ<19>")
	)
	(segment
		(start 402.654262 -224.673668)
		(end 402.815806 -224.512124)
		(width 0.14478)
		(layer "In4.Cu")
		(net "M_J_CPU0_SA_DQ<19>")
	)
	(segment
		(start 388.093458 -236.056678)
		(end 388.10184 -236.061504)
		(width 0.0889)
		(layer "In4.Cu")
		(net "M_J_CPU0_SA_DQ<19>")
	)
	(segment
		(start 405.210772 -222.77705)
		(end 404.995126 -222.561404)
		(width 0.14478)
		(layer "In4.Cu")
		(net "M_J_CPU0_SA_DQ<19>")
	)
	(segment
		(start 409.206192 -219.01023)
		(end 414.005776 -219.01023)
		(width 0.14478)
		(layer "In4.Cu")
		(net "M_J_CPU0_SA_DQ<19>")
	)
	(segment
		(start 403.488652 -224.72777)
		(end 403.650196 -224.566226)
		(width 0.14478)
		(layer "In4.Cu")
		(net "M_J_CPU0_SA_DQ<19>")
	)
	(segment
		(start 404.604982 -222.951548)
		(end 404.820628 -223.167194)
		(width 0.14478)
		(layer "In4.Cu")
		(net "M_J_CPU0_SA_DQ<19>")
	)
	(segment
		(start 405.38527 -222.17126)
		(end 405.600916 -222.386906)
		(width 0.14478)
		(layer "In4.Cu")
		(net "M_J_CPU0_SA_DQ<19>")
	)
	(segment
		(start 405.600916 -222.386906)
		(end 405.829516 -222.386906)
		(width 0.14478)
		(layer "In4.Cu")
		(net "M_J_CPU0_SA_DQ<19>")
	)
	(segment
		(start 429.06569 -219.000578)
		(end 429.915828 -218.15044)
		(width 0.14478)
		(layer "In4.Cu")
		(net "M_J_CPU0_SA_DQ<19>")
	)
	(segment
		(start 404.214838 -223.341692)
		(end 404.214838 -223.113092)
		(width 0.14478)
		(layer "In4.Cu")
		(net "M_J_CPU0_SA_DQ<19>")
	)
	(segment
		(start 383.393442 -236.056678)
		(end 383.401824 -236.061504)
		(width 0.0889)
		(layer "In4.Cu")
		(net "M_J_CPU0_SA_DQ<19>")
	)
	(segment
		(start 395.456918 -233.96194)
		(end 395.768322 -233.96194)
		(width 0.0889)
		(layer "In4.Cu")
		(net "M_J_CPU0_SA_DQ<19>")
	)
	(segment
		(start 403.596094 -223.731836)
		(end 403.824694 -223.731836)
		(width 0.14478)
		(layer "In4.Cu")
		(net "M_J_CPU0_SA_DQ<19>")
	)
	(segment
		(start 404.04034 -223.947482)
		(end 404.26894 -223.947482)
		(width 0.14478)
		(layer "In4.Cu")
		(net "M_J_CPU0_SA_DQ<19>")
	)
	(segment
		(start 389.607806 -236.061504)
		(end 389.616188 -236.056678)
		(width 0.0889)
		(layer "In4.Cu")
		(net "M_J_CPU0_SA_DQ<19>")
	)
	(segment
		(start 389.033512 -236.056678)
		(end 389.041894 -236.061504)
		(width 0.0889)
		(layer "In4.Cu")
		(net "M_J_CPU0_SA_DQ<19>")
	)
	(segment
		(start 403.43455 -223.89338)
		(end 403.596094 -223.731836)
		(width 0.14478)
		(layer "In4.Cu")
		(net "M_J_CPU0_SA_DQ<19>")
	)
	(segment
		(start 381.147828 -236.061504)
		(end 381.15621 -236.056678)
		(width 0.0889)
		(layer "In4.Cu")
		(net "M_J_CPU0_SA_DQ<19>")
	)
	(segment
		(start 404.430484 -223.557338)
		(end 404.214838 -223.341692)
		(width 0.14478)
		(layer "In4.Cu")
		(net "M_J_CPU0_SA_DQ<19>")
	)
	(segment
		(start 404.214838 -223.113092)
		(end 404.376382 -222.951548)
		(width 0.14478)
		(layer "In4.Cu")
		(net "M_J_CPU0_SA_DQ<19>")
	)
	(segment
		(start 402.869908 -225.117914)
		(end 402.654262 -224.902268)
		(width 0.14478)
		(layer "In4.Cu")
		(net "M_J_CPU0_SA_DQ<19>")
	)
	(segment
		(start 422.19626 -218.15044)
		(end 426.064426 -218.15044)
		(width 0.14478)
		(layer "In4.Cu")
		(net "M_J_CPU0_SA_DQ<19>")
	)
	(segment
		(start 403.260052 -224.72777)
		(end 403.488652 -224.72777)
		(width 0.14478)
		(layer "In4.Cu")
		(net "M_J_CPU0_SA_DQ<19>")
	)
	(segment
		(start 394.297916 -234.865418)
		(end 394.585444 -234.57789)
		(width 0.0889)
		(layer "In4.Cu")
		(net "M_J_CPU0_SA_DQ<19>")
	)
	(segment
		(start 404.376382 -222.951548)
		(end 404.604982 -222.951548)
		(width 0.14478)
		(layer "In4.Cu")
		(net "M_J_CPU0_SA_DQ<19>")
	)
	(segment
		(start 405.829516 -222.386906)
		(end 409.206192 -219.01023)
		(width 0.14478)
		(layer "In4.Cu")
		(net "M_J_CPU0_SA_DQ<19>")
	)
	(segment
		(start 418.13988 -218.160092)
		(end 418.980112 -219.000324)
		(width 0.14478)
		(layer "In4.Cu")
		(net "M_J_CPU0_SA_DQ<19>")
	)
	(segment
		(start 402.654262 -224.902268)
		(end 402.654262 -224.673668)
		(width 0.14478)
		(layer "In4.Cu")
		(net "M_J_CPU0_SA_DQ<19>")
	)
	(segment
		(start 405.210772 -223.00565)
		(end 405.210772 -222.77705)
		(width 0.14478)
		(layer "In4.Cu")
		(net "M_J_CPU0_SA_DQ<19>")
	)
	(segment
		(start 385.847844 -236.061504)
		(end 385.856226 -236.056678)
		(width 0.0889)
		(layer "In4.Cu")
		(net "M_J_CPU0_SA_DQ<19>")
	)
	(segment
		(start 394.840968 -234.57789)
		(end 395.456918 -233.96194)
		(width 0.0889)
		(layer "In4.Cu")
		(net "M_J_CPU0_SA_DQ<19>")
	)
	(segment
		(start 403.044406 -224.512124)
		(end 403.260052 -224.72777)
		(width 0.14478)
		(layer "In4.Cu")
		(net "M_J_CPU0_SA_DQ<19>")
	)
	(segment
		(start 394.297916 -235.210858)
		(end 394.297916 -234.865418)
		(width 0.0889)
		(layer "In4.Cu")
		(net "M_J_CPU0_SA_DQ<19>")
	)
	(segment
		(start 403.43455 -224.12198)
		(end 403.43455 -223.89338)
		(width 0.14478)
		(layer "In4.Cu")
		(net "M_J_CPU0_SA_DQ<19>")
	)
	(segment
		(start 405.049228 -223.167194)
		(end 405.210772 -223.00565)
		(width 0.14478)
		(layer "In4.Cu")
		(net "M_J_CPU0_SA_DQ<19>")
	)
	(segment
		(start 404.26894 -223.947482)
		(end 404.430484 -223.785938)
		(width 0.14478)
		(layer "In4.Cu")
		(net "M_J_CPU0_SA_DQ<19>")
	)
	(segment
		(start 421.346376 -219.000324)
		(end 422.19626 -218.15044)
		(width 0.14478)
		(layer "In4.Cu")
		(net "M_J_CPU0_SA_DQ<19>")
	)
	(segment
		(start 384.90779 -236.061504)
		(end 384.916172 -236.056678)
		(width 0.0889)
		(layer "In4.Cu")
		(net "M_J_CPU0_SA_DQ<19>")
	)
	(segment
		(start 396.649194 -233.96194)
		(end 402.565362 -228.045772)
		(width 0.14478)
		(layer "In4.Cu")
		(net "M_J_CPU0_SA_DQ<19>")
	)
	(segment
		(start 403.650196 -224.566226)
		(end 403.650196 -224.337626)
		(width 0.14478)
		(layer "In4.Cu")
		(net "M_J_CPU0_SA_DQ<19>")
	)
	(arc
		(start 384.341878 -236.061504)
		(mid 384.624834 -236.137681)
		(end 384.90779 -236.061504)
		(width 0.0889)
		(layer "In4.Cu")
		(net "M_J_CPU0_SA_DQ<19>")
	)
	(arc
		(start 386.221986 -236.061504)
		(mid 386.504942 -236.137681)
		(end 386.787898 -236.061504)
		(width 0.0889)
		(layer "In4.Cu")
		(net "M_J_CPU0_SA_DQ<19>")
	)
	(arc
		(start 381.15621 -236.056678)
		(mid 381.339718 -236.011184)
		(end 381.52197 -236.061504)
		(width 0.0889)
		(layer "In4.Cu")
		(net "M_J_CPU0_SA_DQ<19>")
	)
	(arc
		(start 391.496042 -236.056678)
		(mid 391.679804 -236.011062)
		(end 391.86231 -236.061504)
		(width 0.0889)
		(layer "In4.Cu")
		(net "M_J_CPU0_SA_DQ<19>")
	)
	(arc
		(start 389.981948 -236.061504)
		(mid 390.264904 -236.137681)
		(end 390.54786 -236.061504)
		(width 0.0889)
		(layer "In4.Cu")
		(net "M_J_CPU0_SA_DQ<19>")
	)
	(arc
		(start 379.641862 -236.061504)
		(mid 379.924818 -236.137681)
		(end 380.207774 -236.061504)
		(width 0.0889)
		(layer "In4.Cu")
		(net "M_J_CPU0_SA_DQ<19>")
	)
	(arc
		(start 380.581916 -236.061504)
		(mid 380.864872 -236.137681)
		(end 381.147828 -236.061504)
		(width 0.0889)
		(layer "In4.Cu")
		(net "M_J_CPU0_SA_DQ<19>")
	)
	(arc
		(start 384.916172 -236.056678)
		(mid 385.09968 -236.011184)
		(end 385.281932 -236.061504)
		(width 0.0889)
		(layer "In4.Cu")
		(net "M_J_CPU0_SA_DQ<19>")
	)
	(arc
		(start 389.041894 -236.061504)
		(mid 389.32485 -236.137681)
		(end 389.607806 -236.061504)
		(width 0.0889)
		(layer "In4.Cu")
		(net "M_J_CPU0_SA_DQ<19>")
	)
	(arc
		(start 386.787898 -236.061504)
		(mid 386.974842 -236.011249)
		(end 387.161786 -236.061504)
		(width 0.0889)
		(layer "In4.Cu")
		(net "M_J_CPU0_SA_DQ<19>")
	)
	(arc
		(start 383.401824 -236.061504)
		(mid 383.68478 -236.137681)
		(end 383.967736 -236.061504)
		(width 0.0889)
		(layer "In4.Cu")
		(net "M_J_CPU0_SA_DQ<19>")
	)
	(arc
		(start 383.027682 -236.061504)
		(mid 383.209933 -236.011154)
		(end 383.393442 -236.056678)
		(width 0.0889)
		(layer "In4.Cu")
		(net "M_J_CPU0_SA_DQ<19>")
	)
	(arc
		(start 382.46177 -236.061504)
		(mid 382.744726 -236.137681)
		(end 383.027682 -236.061504)
		(width 0.0889)
		(layer "In4.Cu")
		(net "M_J_CPU0_SA_DQ<19>")
	)
	(arc
		(start 385.856226 -236.056678)
		(mid 386.039734 -236.011184)
		(end 386.221986 -236.061504)
		(width 0.0889)
		(layer "In4.Cu")
		(net "M_J_CPU0_SA_DQ<19>")
	)
	(arc
		(start 381.52197 -236.061504)
		(mid 381.804926 -236.137681)
		(end 382.087882 -236.061504)
		(width 0.0889)
		(layer "In4.Cu")
		(net "M_J_CPU0_SA_DQ<19>")
	)
	(arc
		(start 380.216156 -236.056678)
		(mid 380.399664 -236.011184)
		(end 380.581916 -236.061504)
		(width 0.0889)
		(layer "In4.Cu")
		(net "M_J_CPU0_SA_DQ<19>")
	)
	(arc
		(start 390.921748 -236.061504)
		(mid 391.204704 -236.137681)
		(end 391.48766 -236.061504)
		(width 0.0889)
		(layer "In4.Cu")
		(net "M_J_CPU0_SA_DQ<19>")
	)
	(arc
		(start 389.616188 -236.056678)
		(mid 389.799696 -236.011184)
		(end 389.981948 -236.061504)
		(width 0.0889)
		(layer "In4.Cu")
		(net "M_J_CPU0_SA_DQ<19>")
	)
	(arc
		(start 379.323092 -236.035342)
		(mid 379.480602 -236.012144)
		(end 379.63348 -236.056678)
		(width 0.0889)
		(layer "In4.Cu")
		(net "M_J_CPU0_SA_DQ<19>")
	)
	(arc
		(start 387.727698 -236.061504)
		(mid 387.909949 -236.011154)
		(end 388.093458 -236.056678)
		(width 0.0889)
		(layer "In4.Cu")
		(net "M_J_CPU0_SA_DQ<19>")
	)
	(arc
		(start 387.161786 -236.061504)
		(mid 387.444742 -236.137681)
		(end 387.727698 -236.061504)
		(width 0.0889)
		(layer "In4.Cu")
		(net "M_J_CPU0_SA_DQ<19>")
	)
	(arc
		(start 385.281932 -236.061504)
		(mid 385.564888 -236.137681)
		(end 385.847844 -236.061504)
		(width 0.0889)
		(layer "In4.Cu")
		(net "M_J_CPU0_SA_DQ<19>")
	)
	(arc
		(start 382.087882 -236.061504)
		(mid 382.274826 -236.011249)
		(end 382.46177 -236.061504)
		(width 0.0889)
		(layer "In4.Cu")
		(net "M_J_CPU0_SA_DQ<19>")
	)
	(arc
		(start 391.86231 -236.061504)
		(mid 391.999103 -236.118526)
		(end 392.146028 -236.137958)
		(width 0.0889)
		(layer "In4.Cu")
		(net "M_J_CPU0_SA_DQ<19>")
	)
	(arc
		(start 383.967736 -236.061504)
		(mid 384.149987 -236.011154)
		(end 384.333496 -236.056678)
		(width 0.0889)
		(layer "In4.Cu")
		(net "M_J_CPU0_SA_DQ<19>")
	)
	(arc
		(start 388.10184 -236.061504)
		(mid 388.384796 -236.137681)
		(end 388.667752 -236.061504)
		(width 0.0889)
		(layer "In4.Cu")
		(net "M_J_CPU0_SA_DQ<19>")
	)
	(arc
		(start 388.667752 -236.061504)
		(mid 388.850003 -236.011154)
		(end 389.033512 -236.056678)
		(width 0.0889)
		(layer "In4.Cu")
		(net "M_J_CPU0_SA_DQ<19>")
	)
	(arc
		(start 390.54786 -236.061504)
		(mid 390.734804 -236.011249)
		(end 390.921748 -236.061504)
		(width 0.0889)
		(layer "In4.Cu")
		(net "M_J_CPU0_SA_DQ<19>")
	)
	(segment
		(start 380.39802 -235.840016)
		(end 380.864872 -235.574078)
		(width 0.10668)
		(layer "F.Cu")
		(net "M_J_CPU0_SA_DQ<18>")
	)
	(segment
		(start 414.239456 -217.310208)
		(end 415.089594 -216.46007)
		(width 0.14478)
		(layer "In4.Cu")
		(net "M_J_CPU0_SA_DQ<18>")
	)
	(segment
		(start 407.20518 -219.079318)
		(end 407.20518 -218.850718)
		(width 0.14478)
		(layer "In4.Cu")
		(net "M_J_CPU0_SA_DQ<18>")
	)
	(segment
		(start 429.003968 -217.310208)
		(end 429.854106 -216.46007)
		(width 0.14478)
		(layer "In4.Cu")
		(net "M_J_CPU0_SA_DQ<18>")
	)
	(segment
		(start 407.797 -218.89085)
		(end 408.0256 -218.89085)
		(width 0.14478)
		(layer "In4.Cu")
		(net "M_J_CPU0_SA_DQ<18>")
	)
	(segment
		(start 410.9593 -217.845132)
		(end 411.120844 -217.683588)
		(width 0.14478)
		(layer "In4.Cu")
		(net "M_J_CPU0_SA_DQ<18>")
	)
	(segment
		(start 405.25446 -221.030038)
		(end 405.456136 -221.231714)
		(width 0.14478)
		(layer "In4.Cu")
		(net "M_J_CPU0_SA_DQ<18>")
	)
	(segment
		(start 405.644604 -220.639894)
		(end 405.644604 -220.411294)
		(width 0.14478)
		(layer "In4.Cu")
		(net "M_J_CPU0_SA_DQ<18>")
	)
	(segment
		(start 391.01776 -235.251498)
		(end 391.026142 -235.246672)
		(width 0.0889)
		(layer "In4.Cu")
		(net "M_J_CPU0_SA_DQ<18>")
	)
	(segment
		(start 405.644604 -220.411294)
		(end 405.806148 -220.24975)
		(width 0.14478)
		(layer "In4.Cu")
		(net "M_J_CPU0_SA_DQ<18>")
	)
	(segment
		(start 425.861988 -216.46007)
		(end 426.712126 -217.310208)
		(width 0.14478)
		(layer "In4.Cu")
		(net "M_J_CPU0_SA_DQ<18>")
	)
	(segment
		(start 418.732462 -217.310208)
		(end 421.580818 -217.310208)
		(width 0.14478)
		(layer "In4.Cu")
		(net "M_J_CPU0_SA_DQ<18>")
	)
	(segment
		(start 409.628086 -217.845132)
		(end 409.856432 -217.845132)
		(width 0.14478)
		(layer "In4.Cu")
		(net "M_J_CPU0_SA_DQ<18>")
	)
	(segment
		(start 407.366724 -218.689174)
		(end 407.595324 -218.689174)
		(width 0.14478)
		(layer "In4.Cu")
		(net "M_J_CPU0_SA_DQ<18>")
	)
	(segment
		(start 415.089594 -216.46007)
		(end 417.882324 -216.46007)
		(width 0.14478)
		(layer "In4.Cu")
		(net "M_J_CPU0_SA_DQ<18>")
	)
	(segment
		(start 401.666202 -224.389696)
		(end 405.02586 -221.030038)
		(width 0.14478)
		(layer "In4.Cu")
		(net "M_J_CPU0_SA_DQ<18>")
	)
	(segment
		(start 380.864872 -235.574078)
		(end 380.710694 -235.308648)
		(width 0.0889)
		(layer "In4.Cu")
		(net "M_J_CPU0_SA_DQ<18>")
	)
	(segment
		(start 394.543788 -234.05719)
		(end 395.550898 -233.05008)
		(width 0.0889)
		(layer "In4.Cu")
		(net "M_J_CPU0_SA_DQ<18>")
	)
	(segment
		(start 410.017976 -217.683588)
		(end 410.017976 -217.471752)
		(width 0.14478)
		(layer "In4.Cu")
		(net "M_J_CPU0_SA_DQ<18>")
	)
	(segment
		(start 382.557782 -235.251498)
		(end 382.566164 -235.246672)
		(width 0.0889)
		(layer "In4.Cu")
		(net "M_J_CPU0_SA_DQ<18>")
	)
	(segment
		(start 409.466542 -217.471752)
		(end 409.466542 -217.683588)
		(width 0.14478)
		(layer "In4.Cu")
		(net "M_J_CPU0_SA_DQ<18>")
	)
	(segment
		(start 409.856432 -217.845132)
		(end 410.017976 -217.683588)
		(width 0.14478)
		(layer "In4.Cu")
		(net "M_J_CPU0_SA_DQ<18>")
	)
	(segment
		(start 407.595324 -218.689174)
		(end 407.797 -218.89085)
		(width 0.14478)
		(layer "In4.Cu")
		(net "M_J_CPU0_SA_DQ<18>")
	)
	(segment
		(start 388.197852 -235.251498)
		(end 388.206234 -235.246672)
		(width 0.0889)
		(layer "In4.Cu")
		(net "M_J_CPU0_SA_DQ<18>")
	)
	(segment
		(start 405.684736 -221.231714)
		(end 405.84628 -221.07017)
		(width 0.14478)
		(layer "In4.Cu")
		(net "M_J_CPU0_SA_DQ<18>")
	)
	(segment
		(start 406.586436 -219.469462)
		(end 406.815036 -219.469462)
		(width 0.14478)
		(layer "In4.Cu")
		(net "M_J_CPU0_SA_DQ<18>")
	)
	(segment
		(start 386.683504 -235.246672)
		(end 386.691886 -235.251498)
		(width 0.0889)
		(layer "In4.Cu")
		(net "M_J_CPU0_SA_DQ<18>")
	)
	(segment
		(start 383.497836 -235.251498)
		(end 383.506218 -235.246672)
		(width 0.0889)
		(layer "In4.Cu")
		(net "M_J_CPU0_SA_DQ<18>")
	)
	(segment
		(start 391.391902 -235.251498)
		(end 391.402316 -235.257594)
		(width 0.0889)
		(layer "In4.Cu")
		(net "M_J_CPU0_SA_DQ<18>")
	)
	(segment
		(start 391.89533 -235.287566)
		(end 392.882882 -234.89031)
		(width 0.0889)
		(layer "In4.Cu")
		(net "M_J_CPU0_SA_DQ<18>")
	)
	(segment
		(start 411.282388 -217.310208)
		(end 414.239456 -217.310208)
		(width 0.14478)
		(layer "In4.Cu")
		(net "M_J_CPU0_SA_DQ<18>")
	)
	(segment
		(start 393.266676 -234.89031)
		(end 394.099796 -234.05719)
		(width 0.0889)
		(layer "In4.Cu")
		(net "M_J_CPU0_SA_DQ<18>")
	)
	(segment
		(start 408.187144 -218.729306)
		(end 408.187144 -218.500706)
		(width 0.14478)
		(layer "In4.Cu")
		(net "M_J_CPU0_SA_DQ<18>")
	)
	(segment
		(start 381.983488 -235.246672)
		(end 381.99187 -235.251498)
		(width 0.0889)
		(layer "In4.Cu")
		(net "M_J_CPU0_SA_DQ<18>")
	)
	(segment
		(start 422.430956 -216.46007)
		(end 425.861988 -216.46007)
		(width 0.14478)
		(layer "In4.Cu")
		(net "M_J_CPU0_SA_DQ<18>")
	)
	(segment
		(start 387.257798 -235.251498)
		(end 387.26618 -235.246672)
		(width 0.0889)
		(layer "In4.Cu")
		(net "M_J_CPU0_SA_DQ<18>")
	)
	(segment
		(start 426.712126 -217.310208)
		(end 429.003968 -217.310208)
		(width 0.14478)
		(layer "In4.Cu")
		(net "M_J_CPU0_SA_DQ<18>")
	)
	(segment
		(start 395.782292 -233.05008)
		(end 396.274798 -233.05008)
		(width 0.14478)
		(layer "In4.Cu")
		(net "M_J_CPU0_SA_DQ<18>")
	)
	(segment
		(start 429.854106 -216.46007)
		(end 434.575204 -216.46007)
		(width 0.14478)
		(layer "In4.Cu")
		(net "M_J_CPU0_SA_DQ<18>")
	)
	(segment
		(start 408.187144 -218.500706)
		(end 407.985468 -218.29903)
		(width 0.14478)
		(layer "In4.Cu")
		(net "M_J_CPU0_SA_DQ<18>")
	)
	(segment
		(start 410.730954 -217.845132)
		(end 410.9593 -217.845132)
		(width 0.14478)
		(layer "In4.Cu")
		(net "M_J_CPU0_SA_DQ<18>")
	)
	(segment
		(start 385.74345 -235.246672)
		(end 385.751832 -235.251498)
		(width 0.0889)
		(layer "In4.Cu")
		(net "M_J_CPU0_SA_DQ<18>")
	)
	(segment
		(start 408.0256 -218.89085)
		(end 408.187144 -218.729306)
		(width 0.14478)
		(layer "In4.Cu")
		(net "M_J_CPU0_SA_DQ<18>")
	)
	(segment
		(start 390.443466 -235.246672)
		(end 390.451848 -235.251498)
		(width 0.0889)
		(layer "In4.Cu")
		(net "M_J_CPU0_SA_DQ<18>")
	)
	(segment
		(start 405.84628 -221.07017)
		(end 405.84628 -220.84157)
		(width 0.14478)
		(layer "In4.Cu")
		(net "M_J_CPU0_SA_DQ<18>")
	)
	(segment
		(start 405.456136 -221.231714)
		(end 405.684736 -221.231714)
		(width 0.14478)
		(layer "In4.Cu")
		(net "M_J_CPU0_SA_DQ<18>")
	)
	(segment
		(start 410.56941 -217.683588)
		(end 410.730954 -217.845132)
		(width 0.14478)
		(layer "In4.Cu")
		(net "M_J_CPU0_SA_DQ<18>")
	)
	(segment
		(start 406.034748 -220.24975)
		(end 406.236424 -220.451426)
		(width 0.14478)
		(layer "In4.Cu")
		(net "M_J_CPU0_SA_DQ<18>")
	)
	(segment
		(start 406.424892 -219.631006)
		(end 406.586436 -219.469462)
		(width 0.14478)
		(layer "In4.Cu")
		(net "M_J_CPU0_SA_DQ<18>")
	)
	(segment
		(start 406.424892 -219.859606)
		(end 406.424892 -219.631006)
		(width 0.14478)
		(layer "In4.Cu")
		(net "M_J_CPU0_SA_DQ<18>")
	)
	(segment
		(start 407.406856 -219.280994)
		(end 407.20518 -219.079318)
		(width 0.14478)
		(layer "In4.Cu")
		(net "M_J_CPU0_SA_DQ<18>")
	)
	(segment
		(start 406.815036 -219.469462)
		(end 407.016712 -219.671138)
		(width 0.14478)
		(layer "In4.Cu")
		(net "M_J_CPU0_SA_DQ<18>")
	)
	(segment
		(start 407.016712 -219.671138)
		(end 407.245312 -219.671138)
		(width 0.14478)
		(layer "In4.Cu")
		(net "M_J_CPU0_SA_DQ<18>")
	)
	(segment
		(start 410.56941 -217.471752)
		(end 410.56941 -217.683588)
		(width 0.14478)
		(layer "In4.Cu")
		(net "M_J_CPU0_SA_DQ<18>")
	)
	(segment
		(start 406.626568 -220.061282)
		(end 406.424892 -219.859606)
		(width 0.14478)
		(layer "In4.Cu")
		(net "M_J_CPU0_SA_DQ<18>")
	)
	(segment
		(start 405.806148 -220.24975)
		(end 406.034748 -220.24975)
		(width 0.14478)
		(layer "In4.Cu")
		(net "M_J_CPU0_SA_DQ<18>")
	)
	(segment
		(start 411.120844 -217.471752)
		(end 411.282388 -217.310208)
		(width 0.14478)
		(layer "In4.Cu")
		(net "M_J_CPU0_SA_DQ<18>")
	)
	(segment
		(start 380.710694 -235.308648)
		(end 380.733046 -235.225336)
		(width 0.0889)
		(layer "In4.Cu")
		(net "M_J_CPU0_SA_DQ<18>")
	)
	(segment
		(start 396.274798 -233.05008)
		(end 401.666202 -227.658676)
		(width 0.14478)
		(layer "In4.Cu")
		(net "M_J_CPU0_SA_DQ<18>")
	)
	(segment
		(start 395.550898 -233.05008)
		(end 395.782292 -233.05008)
		(width 0.0889)
		(layer "In4.Cu")
		(net "M_J_CPU0_SA_DQ<18>")
	)
	(segment
		(start 407.985468 -218.29903)
		(end 407.985468 -218.07043)
		(width 0.14478)
		(layer "In4.Cu")
		(net "M_J_CPU0_SA_DQ<18>")
	)
	(segment
		(start 407.245312 -219.671138)
		(end 407.406856 -219.509594)
		(width 0.14478)
		(layer "In4.Cu")
		(net "M_J_CPU0_SA_DQ<18>")
	)
	(segment
		(start 407.406856 -219.509594)
		(end 407.406856 -219.280994)
		(width 0.14478)
		(layer "In4.Cu")
		(net "M_J_CPU0_SA_DQ<18>")
	)
	(segment
		(start 406.626568 -220.289882)
		(end 406.626568 -220.061282)
		(width 0.14478)
		(layer "In4.Cu")
		(net "M_J_CPU0_SA_DQ<18>")
	)
	(segment
		(start 411.120844 -217.683588)
		(end 411.120844 -217.471752)
		(width 0.14478)
		(layer "In4.Cu")
		(net "M_J_CPU0_SA_DQ<18>")
	)
	(segment
		(start 409.304998 -217.310208)
		(end 409.466542 -217.471752)
		(width 0.14478)
		(layer "In4.Cu")
		(net "M_J_CPU0_SA_DQ<18>")
	)
	(segment
		(start 406.236424 -220.451426)
		(end 406.465024 -220.451426)
		(width 0.14478)
		(layer "In4.Cu")
		(net "M_J_CPU0_SA_DQ<18>")
	)
	(segment
		(start 401.666202 -227.658676)
		(end 401.666202 -224.389696)
		(width 0.14478)
		(layer "In4.Cu")
		(net "M_J_CPU0_SA_DQ<18>")
	)
	(segment
		(start 410.017976 -217.471752)
		(end 410.17952 -217.310208)
		(width 0.14478)
		(layer "In4.Cu")
		(net "M_J_CPU0_SA_DQ<18>")
	)
	(segment
		(start 405.02586 -221.030038)
		(end 405.25446 -221.030038)
		(width 0.14478)
		(layer "In4.Cu")
		(net "M_J_CPU0_SA_DQ<18>")
	)
	(segment
		(start 407.20518 -218.850718)
		(end 407.366724 -218.689174)
		(width 0.14478)
		(layer "In4.Cu")
		(net "M_J_CPU0_SA_DQ<18>")
	)
	(segment
		(start 434.575204 -216.46007)
		(end 435.000146 -216.885012)
		(width 0.14478)
		(layer "In4.Cu")
		(net "M_J_CPU0_SA_DQ<18>")
	)
	(segment
		(start 417.882324 -216.46007)
		(end 418.732462 -217.310208)
		(width 0.14478)
		(layer "In4.Cu")
		(net "M_J_CPU0_SA_DQ<18>")
	)
	(segment
		(start 410.407866 -217.310208)
		(end 410.56941 -217.471752)
		(width 0.14478)
		(layer "In4.Cu")
		(net "M_J_CPU0_SA_DQ<18>")
	)
	(segment
		(start 410.17952 -217.310208)
		(end 410.407866 -217.310208)
		(width 0.14478)
		(layer "In4.Cu")
		(net "M_J_CPU0_SA_DQ<18>")
	)
	(segment
		(start 406.465024 -220.451426)
		(end 406.626568 -220.289882)
		(width 0.14478)
		(layer "In4.Cu")
		(net "M_J_CPU0_SA_DQ<18>")
	)
	(segment
		(start 405.84628 -220.84157)
		(end 405.644604 -220.639894)
		(width 0.14478)
		(layer "In4.Cu")
		(net "M_J_CPU0_SA_DQ<18>")
	)
	(segment
		(start 381.043434 -235.246672)
		(end 381.051816 -235.251498)
		(width 0.0889)
		(layer "In4.Cu")
		(net "M_J_CPU0_SA_DQ<18>")
	)
	(segment
		(start 407.985468 -218.07043)
		(end 408.74569 -217.310208)
		(width 0.14478)
		(layer "In4.Cu")
		(net "M_J_CPU0_SA_DQ<18>")
	)
	(segment
		(start 394.099796 -234.05719)
		(end 394.543788 -234.05719)
		(width 0.0889)
		(layer "In4.Cu")
		(net "M_J_CPU0_SA_DQ<18>")
	)
	(segment
		(start 392.882882 -234.89031)
		(end 393.266676 -234.89031)
		(width 0.0889)
		(layer "In4.Cu")
		(net "M_J_CPU0_SA_DQ<18>")
	)
	(segment
		(start 409.466542 -217.683588)
		(end 409.628086 -217.845132)
		(width 0.14478)
		(layer "In4.Cu")
		(net "M_J_CPU0_SA_DQ<18>")
	)
	(segment
		(start 421.580818 -217.310208)
		(end 422.430956 -216.46007)
		(width 0.14478)
		(layer "In4.Cu")
		(net "M_J_CPU0_SA_DQ<18>")
	)
	(segment
		(start 408.74569 -217.310208)
		(end 409.304998 -217.310208)
		(width 0.14478)
		(layer "In4.Cu")
		(net "M_J_CPU0_SA_DQ<18>")
	)
	(arc
		(start 383.871978 -235.251498)
		(mid 384.154934 -235.327675)
		(end 384.43789 -235.251498)
		(width 0.0889)
		(layer "In4.Cu")
		(net "M_J_CPU0_SA_DQ<18>")
	)
	(arc
		(start 387.63194 -235.251498)
		(mid 387.914896 -235.327675)
		(end 388.197852 -235.251498)
		(width 0.0889)
		(layer "In4.Cu")
		(net "M_J_CPU0_SA_DQ<18>")
	)
	(arc
		(start 388.206234 -235.246672)
		(mid 388.389742 -235.201178)
		(end 388.571994 -235.251498)
		(width 0.0889)
		(layer "In4.Cu")
		(net "M_J_CPU0_SA_DQ<18>")
	)
	(arc
		(start 384.43789 -235.251498)
		(mid 384.624834 -235.201243)
		(end 384.811778 -235.251498)
		(width 0.0889)
		(layer "In4.Cu")
		(net "M_J_CPU0_SA_DQ<18>")
	)
	(arc
		(start 390.077706 -235.251498)
		(mid 390.259957 -235.201148)
		(end 390.443466 -235.246672)
		(width 0.0889)
		(layer "In4.Cu")
		(net "M_J_CPU0_SA_DQ<18>")
	)
	(arc
		(start 383.506218 -235.246672)
		(mid 383.689726 -235.201178)
		(end 383.871978 -235.251498)
		(width 0.0889)
		(layer "In4.Cu")
		(net "M_J_CPU0_SA_DQ<18>")
	)
	(arc
		(start 391.026142 -235.246672)
		(mid 391.20965 -235.201178)
		(end 391.391902 -235.251498)
		(width 0.0889)
		(layer "In4.Cu")
		(net "M_J_CPU0_SA_DQ<18>")
	)
	(arc
		(start 388.571994 -235.251498)
		(mid 388.85495 -235.327675)
		(end 389.137906 -235.251498)
		(width 0.0889)
		(layer "In4.Cu")
		(net "M_J_CPU0_SA_DQ<18>")
	)
	(arc
		(start 391.402316 -235.257594)
		(mid 391.645449 -235.328218)
		(end 391.89533 -235.287566)
		(width 0.0889)
		(layer "In4.Cu")
		(net "M_J_CPU0_SA_DQ<18>")
	)
	(arc
		(start 382.566164 -235.246672)
		(mid 382.749672 -235.201178)
		(end 382.931924 -235.251498)
		(width 0.0889)
		(layer "In4.Cu")
		(net "M_J_CPU0_SA_DQ<18>")
	)
	(arc
		(start 384.811778 -235.251498)
		(mid 385.094734 -235.327675)
		(end 385.37769 -235.251498)
		(width 0.0889)
		(layer "In4.Cu")
		(net "M_J_CPU0_SA_DQ<18>")
	)
	(arc
		(start 386.691886 -235.251498)
		(mid 386.974842 -235.327675)
		(end 387.257798 -235.251498)
		(width 0.0889)
		(layer "In4.Cu")
		(net "M_J_CPU0_SA_DQ<18>")
	)
	(arc
		(start 389.511794 -235.251498)
		(mid 389.79475 -235.327675)
		(end 390.077706 -235.251498)
		(width 0.0889)
		(layer "In4.Cu")
		(net "M_J_CPU0_SA_DQ<18>")
	)
	(arc
		(start 390.451848 -235.251498)
		(mid 390.734804 -235.327675)
		(end 391.01776 -235.251498)
		(width 0.0889)
		(layer "In4.Cu")
		(net "M_J_CPU0_SA_DQ<18>")
	)
	(arc
		(start 386.317744 -235.251498)
		(mid 386.499995 -235.201148)
		(end 386.683504 -235.246672)
		(width 0.0889)
		(layer "In4.Cu")
		(net "M_J_CPU0_SA_DQ<18>")
	)
	(arc
		(start 389.137906 -235.251498)
		(mid 389.32485 -235.201243)
		(end 389.511794 -235.251498)
		(width 0.0889)
		(layer "In4.Cu")
		(net "M_J_CPU0_SA_DQ<18>")
	)
	(arc
		(start 387.26618 -235.246672)
		(mid 387.449688 -235.201178)
		(end 387.63194 -235.251498)
		(width 0.0889)
		(layer "In4.Cu")
		(net "M_J_CPU0_SA_DQ<18>")
	)
	(arc
		(start 381.99187 -235.251498)
		(mid 382.274826 -235.327675)
		(end 382.557782 -235.251498)
		(width 0.0889)
		(layer "In4.Cu")
		(net "M_J_CPU0_SA_DQ<18>")
	)
	(arc
		(start 380.733046 -235.225336)
		(mid 380.890556 -235.202138)
		(end 381.043434 -235.246672)
		(width 0.0889)
		(layer "In4.Cu")
		(net "M_J_CPU0_SA_DQ<18>")
	)
	(arc
		(start 382.931924 -235.251498)
		(mid 383.21488 -235.327675)
		(end 383.497836 -235.251498)
		(width 0.0889)
		(layer "In4.Cu")
		(net "M_J_CPU0_SA_DQ<18>")
	)
	(arc
		(start 385.751832 -235.251498)
		(mid 386.034788 -235.327675)
		(end 386.317744 -235.251498)
		(width 0.0889)
		(layer "In4.Cu")
		(net "M_J_CPU0_SA_DQ<18>")
	)
	(arc
		(start 381.617728 -235.251498)
		(mid 381.799979 -235.201148)
		(end 381.983488 -235.246672)
		(width 0.0889)
		(layer "In4.Cu")
		(net "M_J_CPU0_SA_DQ<18>")
	)
	(arc
		(start 381.051816 -235.251498)
		(mid 381.334772 -235.327675)
		(end 381.617728 -235.251498)
		(width 0.0889)
		(layer "In4.Cu")
		(net "M_J_CPU0_SA_DQ<18>")
	)
	(arc
		(start 385.37769 -235.251498)
		(mid 385.559941 -235.201148)
		(end 385.74345 -235.246672)
		(width 0.0889)
		(layer "In4.Cu")
		(net "M_J_CPU0_SA_DQ<18>")
	)
	(segment
		(start 378.517912 -235.840016)
		(end 378.984764 -235.574078)
		(width 0.10668)
		(layer "F.Cu")
		(net "M_J_CPU0_SA_DQ<17>")
	)
	(segment
		(start 387.257798 -235.896658)
		(end 387.26618 -235.901484)
		(width 0.0889)
		(layer "In4.Cu")
		(net "M_J_CPU0_SA_DQ<17>")
	)
	(segment
		(start 436.96382 -217.310208)
		(end 439.100214 -217.73515)
		(width 0.14478)
		(layer "In4.Cu")
		(net "M_J_CPU0_SA_DQ<17>")
	)
	(segment
		(start 405.858726 -221.72168)
		(end 409.285694 -218.294712)
		(width 0.14478)
		(layer "In4.Cu")
		(net "M_J_CPU0_SA_DQ<17>")
	)
	(segment
		(start 381.043434 -235.901484)
		(end 381.051816 -235.896658)
		(width 0.0889)
		(layer "In4.Cu")
		(net "M_J_CPU0_SA_DQ<17>")
	)
	(segment
		(start 391.391902 -235.896658)
		(end 391.406634 -235.888022)
		(width 0.0889)
		(layer "In4.Cu")
		(net "M_J_CPU0_SA_DQ<17>")
	)
	(segment
		(start 394.6398 -234.34167)
		(end 395.47673 -233.50474)
		(width 0.0889)
		(layer "In4.Cu")
		(net "M_J_CPU0_SA_DQ<17>")
	)
	(segment
		(start 402.115782 -227.852224)
		(end 402.115782 -224.576132)
		(width 0.14478)
		(layer "In4.Cu")
		(net "M_J_CPU0_SA_DQ<17>")
	)
	(segment
		(start 404.970234 -221.72168)
		(end 405.858726 -221.72168)
		(width 0.14478)
		(layer "In4.Cu")
		(net "M_J_CPU0_SA_DQ<17>")
	)
	(segment
		(start 386.683504 -235.901484)
		(end 386.691886 -235.896658)
		(width 0.0889)
		(layer "In4.Cu")
		(net "M_J_CPU0_SA_DQ<17>")
	)
	(segment
		(start 393.273788 -235.947458)
		(end 394.094716 -235.12653)
		(width 0.0889)
		(layer "In4.Cu")
		(net "M_J_CPU0_SA_DQ<17>")
	)
	(segment
		(start 392.145774 -235.947458)
		(end 393.273788 -235.947458)
		(width 0.0889)
		(layer "In4.Cu")
		(net "M_J_CPU0_SA_DQ<17>")
	)
	(segment
		(start 385.74345 -235.901484)
		(end 385.751832 -235.896658)
		(width 0.0889)
		(layer "In4.Cu")
		(net "M_J_CPU0_SA_DQ<17>")
	)
	(segment
		(start 413.125412 -218.294712)
		(end 415.50209 -217.310208)
		(width 0.14478)
		(layer "In4.Cu")
		(net "M_J_CPU0_SA_DQ<17>")
	)
	(segment
		(start 394.094716 -235.12653)
		(end 394.094716 -234.64139)
		(width 0.0889)
		(layer "In4.Cu")
		(net "M_J_CPU0_SA_DQ<17>")
	)
	(segment
		(start 391.958322 -235.896658)
		(end 391.958068 -235.896658)
		(width 0.0889)
		(layer "In4.Cu")
		(net "M_J_CPU0_SA_DQ<17>")
	)
	(segment
		(start 396.463266 -233.50474)
		(end 402.115782 -227.852224)
		(width 0.14478)
		(layer "In4.Cu")
		(net "M_J_CPU0_SA_DQ<17>")
	)
	(segment
		(start 420.832026 -218.160092)
		(end 422.883838 -217.310208)
		(width 0.14478)
		(layer "In4.Cu")
		(net "M_J_CPU0_SA_DQ<17>")
	)
	(segment
		(start 422.883838 -217.310208)
		(end 425.318174 -217.310208)
		(width 0.14478)
		(layer "In4.Cu")
		(net "M_J_CPU0_SA_DQ<17>")
	)
	(segment
		(start 419.507924 -218.160092)
		(end 420.832026 -218.160092)
		(width 0.14478)
		(layer "In4.Cu")
		(net "M_J_CPU0_SA_DQ<17>")
	)
	(segment
		(start 381.983488 -235.901484)
		(end 381.99187 -235.896658)
		(width 0.0889)
		(layer "In4.Cu")
		(net "M_J_CPU0_SA_DQ<17>")
	)
	(segment
		(start 388.197852 -235.896658)
		(end 388.206234 -235.901484)
		(width 0.0889)
		(layer "In4.Cu")
		(net "M_J_CPU0_SA_DQ<17>")
	)
	(segment
		(start 382.557782 -235.896658)
		(end 382.566164 -235.901484)
		(width 0.0889)
		(layer "In4.Cu")
		(net "M_J_CPU0_SA_DQ<17>")
	)
	(segment
		(start 395.782292 -233.50474)
		(end 396.463266 -233.50474)
		(width 0.14478)
		(layer "In4.Cu")
		(net "M_J_CPU0_SA_DQ<17>")
	)
	(segment
		(start 409.285694 -218.294712)
		(end 413.125412 -218.294712)
		(width 0.14478)
		(layer "In4.Cu")
		(net "M_J_CPU0_SA_DQ<17>")
	)
	(segment
		(start 415.50209 -217.310208)
		(end 417.456112 -217.310208)
		(width 0.14478)
		(layer "In4.Cu")
		(net "M_J_CPU0_SA_DQ<17>")
	)
	(segment
		(start 395.47673 -233.50474)
		(end 395.782292 -233.50474)
		(width 0.0889)
		(layer "In4.Cu")
		(net "M_J_CPU0_SA_DQ<17>")
	)
	(segment
		(start 427.369986 -218.160092)
		(end 428.541942 -218.160092)
		(width 0.14478)
		(layer "In4.Cu")
		(net "M_J_CPU0_SA_DQ<17>")
	)
	(segment
		(start 430.5935 -217.310208)
		(end 436.96382 -217.310208)
		(width 0.14478)
		(layer "In4.Cu")
		(net "M_J_CPU0_SA_DQ<17>")
	)
	(segment
		(start 428.541942 -218.160092)
		(end 430.5935 -217.310208)
		(width 0.14478)
		(layer "In4.Cu")
		(net "M_J_CPU0_SA_DQ<17>")
	)
	(segment
		(start 390.443466 -235.901484)
		(end 390.451848 -235.896658)
		(width 0.0889)
		(layer "In4.Cu")
		(net "M_J_CPU0_SA_DQ<17>")
	)
	(segment
		(start 394.094716 -234.64139)
		(end 394.394436 -234.34167)
		(width 0.0889)
		(layer "In4.Cu")
		(net "M_J_CPU0_SA_DQ<17>")
	)
	(segment
		(start 417.456112 -217.310208)
		(end 419.507924 -218.160092)
		(width 0.14478)
		(layer "In4.Cu")
		(net "M_J_CPU0_SA_DQ<17>")
	)
	(segment
		(start 378.984764 -235.574078)
		(end 379.138942 -235.839508)
		(width 0.0889)
		(layer "In4.Cu")
		(net "M_J_CPU0_SA_DQ<17>")
	)
	(segment
		(start 391.01776 -235.896658)
		(end 391.026142 -235.901484)
		(width 0.0889)
		(layer "In4.Cu")
		(net "M_J_CPU0_SA_DQ<17>")
	)
	(segment
		(start 425.318174 -217.310208)
		(end 427.369986 -218.160092)
		(width 0.14478)
		(layer "In4.Cu")
		(net "M_J_CPU0_SA_DQ<17>")
	)
	(segment
		(start 402.115782 -224.576132)
		(end 404.970234 -221.72168)
		(width 0.14478)
		(layer "In4.Cu")
		(net "M_J_CPU0_SA_DQ<17>")
	)
	(segment
		(start 394.394436 -234.34167)
		(end 394.6398 -234.34167)
		(width 0.0889)
		(layer "In4.Cu")
		(net "M_J_CPU0_SA_DQ<17>")
	)
	(segment
		(start 379.138942 -235.839508)
		(end 379.235208 -235.864908)
		(width 0.0889)
		(layer "In4.Cu")
		(net "M_J_CPU0_SA_DQ<17>")
	)
	(segment
		(start 383.497836 -235.896658)
		(end 383.506218 -235.901484)
		(width 0.0889)
		(layer "In4.Cu")
		(net "M_J_CPU0_SA_DQ<17>")
	)
	(arc
		(start 385.37769 -235.896658)
		(mid 385.559941 -235.947008)
		(end 385.74345 -235.901484)
		(width 0.0889)
		(layer "In4.Cu")
		(net "M_J_CPU0_SA_DQ<17>")
	)
	(arc
		(start 379.235208 -235.864908)
		(mid 379.490273 -235.821557)
		(end 379.737874 -235.896658)
		(width 0.0889)
		(layer "In4.Cu")
		(net "M_J_CPU0_SA_DQ<17>")
	)
	(arc
		(start 384.811778 -235.896658)
		(mid 385.094734 -235.820481)
		(end 385.37769 -235.896658)
		(width 0.0889)
		(layer "In4.Cu")
		(net "M_J_CPU0_SA_DQ<17>")
	)
	(arc
		(start 380.111762 -235.896658)
		(mid 380.394718 -235.820481)
		(end 380.677674 -235.896658)
		(width 0.0889)
		(layer "In4.Cu")
		(net "M_J_CPU0_SA_DQ<17>")
	)
	(arc
		(start 388.206234 -235.901484)
		(mid 388.389742 -235.946978)
		(end 388.571994 -235.896658)
		(width 0.0889)
		(layer "In4.Cu")
		(net "M_J_CPU0_SA_DQ<17>")
	)
	(arc
		(start 380.677674 -235.896658)
		(mid 380.859925 -235.947008)
		(end 381.043434 -235.901484)
		(width 0.0889)
		(layer "In4.Cu")
		(net "M_J_CPU0_SA_DQ<17>")
	)
	(arc
		(start 387.63194 -235.896658)
		(mid 387.914896 -235.820481)
		(end 388.197852 -235.896658)
		(width 0.0889)
		(layer "In4.Cu")
		(net "M_J_CPU0_SA_DQ<17>")
	)
	(arc
		(start 389.137906 -235.896658)
		(mid 389.32485 -235.946913)
		(end 389.511794 -235.896658)
		(width 0.0889)
		(layer "In4.Cu")
		(net "M_J_CPU0_SA_DQ<17>")
	)
	(arc
		(start 382.931924 -235.896658)
		(mid 383.21488 -235.820481)
		(end 383.497836 -235.896658)
		(width 0.0889)
		(layer "In4.Cu")
		(net "M_J_CPU0_SA_DQ<17>")
	)
	(arc
		(start 381.99187 -235.896658)
		(mid 382.274826 -235.820481)
		(end 382.557782 -235.896658)
		(width 0.0889)
		(layer "In4.Cu")
		(net "M_J_CPU0_SA_DQ<17>")
	)
	(arc
		(start 391.958068 -235.896658)
		(mid 392.048558 -235.934476)
		(end 392.145774 -235.947458)
		(width 0.0889)
		(layer "In4.Cu")
		(net "M_J_CPU0_SA_DQ<17>")
	)
	(arc
		(start 386.691886 -235.896658)
		(mid 386.974842 -235.820481)
		(end 387.257798 -235.896658)
		(width 0.0889)
		(layer "In4.Cu")
		(net "M_J_CPU0_SA_DQ<17>")
	)
	(arc
		(start 391.026142 -235.901484)
		(mid 391.20965 -235.946978)
		(end 391.391902 -235.896658)
		(width 0.0889)
		(layer "In4.Cu")
		(net "M_J_CPU0_SA_DQ<17>")
	)
	(arc
		(start 389.511794 -235.896658)
		(mid 389.79475 -235.820481)
		(end 390.077706 -235.896658)
		(width 0.0889)
		(layer "In4.Cu")
		(net "M_J_CPU0_SA_DQ<17>")
	)
	(arc
		(start 384.43789 -235.896658)
		(mid 384.624834 -235.946913)
		(end 384.811778 -235.896658)
		(width 0.0889)
		(layer "In4.Cu")
		(net "M_J_CPU0_SA_DQ<17>")
	)
	(arc
		(start 388.571994 -235.896658)
		(mid 388.85495 -235.820481)
		(end 389.137906 -235.896658)
		(width 0.0889)
		(layer "In4.Cu")
		(net "M_J_CPU0_SA_DQ<17>")
	)
	(arc
		(start 385.751832 -235.896658)
		(mid 386.034788 -235.820481)
		(end 386.317744 -235.896658)
		(width 0.0889)
		(layer "In4.Cu")
		(net "M_J_CPU0_SA_DQ<17>")
	)
	(arc
		(start 390.077706 -235.896658)
		(mid 390.259957 -235.947008)
		(end 390.443466 -235.901484)
		(width 0.0889)
		(layer "In4.Cu")
		(net "M_J_CPU0_SA_DQ<17>")
	)
	(arc
		(start 383.871978 -235.896658)
		(mid 384.154934 -235.820481)
		(end 384.43789 -235.896658)
		(width 0.0889)
		(layer "In4.Cu")
		(net "M_J_CPU0_SA_DQ<17>")
	)
	(arc
		(start 386.317744 -235.896658)
		(mid 386.499995 -235.947008)
		(end 386.683504 -235.901484)
		(width 0.0889)
		(layer "In4.Cu")
		(net "M_J_CPU0_SA_DQ<17>")
	)
	(arc
		(start 383.506218 -235.901484)
		(mid 383.689726 -235.946978)
		(end 383.871978 -235.896658)
		(width 0.0889)
		(layer "In4.Cu")
		(net "M_J_CPU0_SA_DQ<17>")
	)
	(arc
		(start 381.617728 -235.896658)
		(mid 381.799979 -235.947008)
		(end 381.983488 -235.901484)
		(width 0.0889)
		(layer "In4.Cu")
		(net "M_J_CPU0_SA_DQ<17>")
	)
	(arc
		(start 382.566164 -235.901484)
		(mid 382.749672 -235.946978)
		(end 382.931924 -235.896658)
		(width 0.0889)
		(layer "In4.Cu")
		(net "M_J_CPU0_SA_DQ<17>")
	)
	(arc
		(start 379.737874 -235.896658)
		(mid 379.924818 -235.946913)
		(end 380.111762 -235.896658)
		(width 0.0889)
		(layer "In4.Cu")
		(net "M_J_CPU0_SA_DQ<17>")
	)
	(arc
		(start 391.406634 -235.888022)
		(mid 391.683617 -235.820218)
		(end 391.958322 -235.896658)
		(width 0.0889)
		(layer "In4.Cu")
		(net "M_J_CPU0_SA_DQ<17>")
	)
	(arc
		(start 390.451848 -235.896658)
		(mid 390.734804 -235.820481)
		(end 391.01776 -235.896658)
		(width 0.0889)
		(layer "In4.Cu")
		(net "M_J_CPU0_SA_DQ<17>")
	)
	(arc
		(start 381.051816 -235.896658)
		(mid 381.334772 -235.820481)
		(end 381.617728 -235.896658)
		(width 0.0889)
		(layer "In4.Cu")
		(net "M_J_CPU0_SA_DQ<17>")
	)
	(arc
		(start 387.26618 -235.901484)
		(mid 387.449688 -235.946978)
		(end 387.63194 -235.896658)
		(width 0.0889)
		(layer "In4.Cu")
		(net "M_J_CPU0_SA_DQ<17>")
	)
	(segment
		(start 379.927866 -235.03001)
		(end 380.394718 -234.764072)
		(width 0.10668)
		(layer "F.Cu")
		(net "M_J_CPU0_SA_DQ<16>")
	)
	(segment
		(start 391.48766 -235.086652)
		(end 391.496042 -235.091478)
		(width 0.0889)
		(layer "In4.Cu")
		(net "M_J_CPU0_SA_DQ<16>")
	)
	(segment
		(start 394.313156 -233.276902)
		(end 395.016228 -232.57383)
		(width 0.0889)
		(layer "In4.Cu")
		(net "M_J_CPU0_SA_DQ<16>")
	)
	(segment
		(start 426.541946 -216.46007)
		(end 428.60214 -216.46007)
		(width 0.14478)
		(layer "In4.Cu")
		(net "M_J_CPU0_SA_DQ<16>")
	)
	(segment
		(start 388.093458 -235.091478)
		(end 388.10184 -235.086652)
		(width 0.0889)
		(layer "In4.Cu")
		(net "M_J_CPU0_SA_DQ<16>")
	)
	(segment
		(start 401.216622 -227.371148)
		(end 401.216622 -224.20326)
		(width 0.14478)
		(layer "In4.Cu")
		(net "M_J_CPU0_SA_DQ<16>")
	)
	(segment
		(start 391.86231 -235.086652)
		(end 392.770614 -234.61599)
		(width 0.0889)
		(layer "In4.Cu")
		(net "M_J_CPU0_SA_DQ<16>")
	)
	(segment
		(start 384.90779 -235.086652)
		(end 384.916172 -235.091478)
		(width 0.0889)
		(layer "In4.Cu")
		(net "M_J_CPU0_SA_DQ<16>")
	)
	(segment
		(start 425.692062 -215.610186)
		(end 426.541946 -216.46007)
		(width 0.14478)
		(layer "In4.Cu")
		(net "M_J_CPU0_SA_DQ<16>")
	)
	(segment
		(start 380.548896 -235.029502)
		(end 380.645162 -235.054902)
		(width 0.0889)
		(layer "In4.Cu")
		(net "M_J_CPU0_SA_DQ<16>")
	)
	(segment
		(start 381.147828 -235.086652)
		(end 381.15621 -235.091478)
		(width 0.0889)
		(layer "In4.Cu")
		(net "M_J_CPU0_SA_DQ<16>")
	)
	(segment
		(start 395.886178 -232.57383)
		(end 396.01394 -232.57383)
		(width 0.14478)
		(layer "In4.Cu")
		(net "M_J_CPU0_SA_DQ<16>")
	)
	(segment
		(start 394.313156 -233.42219)
		(end 394.313156 -233.276902)
		(width 0.0889)
		(layer "In4.Cu")
		(net "M_J_CPU0_SA_DQ<16>")
	)
	(segment
		(start 389.033512 -235.091478)
		(end 389.041894 -235.086652)
		(width 0.0889)
		(layer "In4.Cu")
		(net "M_J_CPU0_SA_DQ<16>")
	)
	(segment
		(start 414.114488 -216.46007)
		(end 414.964372 -215.610186)
		(width 0.14478)
		(layer "In4.Cu")
		(net "M_J_CPU0_SA_DQ<16>")
	)
	(segment
		(start 395.016228 -232.57383)
		(end 395.886178 -232.57383)
		(width 0.0889)
		(layer "In4.Cu")
		(net "M_J_CPU0_SA_DQ<16>")
	)
	(segment
		(start 421.625014 -216.46007)
		(end 422.474898 -215.610186)
		(width 0.14478)
		(layer "In4.Cu")
		(net "M_J_CPU0_SA_DQ<16>")
	)
	(segment
		(start 428.60214 -216.46007)
		(end 430.653952 -215.610186)
		(width 0.14478)
		(layer "In4.Cu")
		(net "M_J_CPU0_SA_DQ<16>")
	)
	(segment
		(start 401.216622 -224.20326)
		(end 408.959812 -216.46007)
		(width 0.14478)
		(layer "In4.Cu")
		(net "M_J_CPU0_SA_DQ<16>")
	)
	(segment
		(start 384.333496 -235.091478)
		(end 384.341878 -235.086652)
		(width 0.0889)
		(layer "In4.Cu")
		(net "M_J_CPU0_SA_DQ<16>")
	)
	(segment
		(start 385.847844 -235.086652)
		(end 385.856226 -235.091478)
		(width 0.0889)
		(layer "In4.Cu")
		(net "M_J_CPU0_SA_DQ<16>")
	)
	(segment
		(start 389.607806 -235.086652)
		(end 389.616188 -235.091478)
		(width 0.0889)
		(layer "In4.Cu")
		(net "M_J_CPU0_SA_DQ<16>")
	)
	(segment
		(start 422.474898 -215.610186)
		(end 425.692062 -215.610186)
		(width 0.14478)
		(layer "In4.Cu")
		(net "M_J_CPU0_SA_DQ<16>")
	)
	(segment
		(start 417.71697 -215.610186)
		(end 418.566854 -216.46007)
		(width 0.14478)
		(layer "In4.Cu")
		(net "M_J_CPU0_SA_DQ<16>")
	)
	(segment
		(start 393.119356 -234.61599)
		(end 394.313156 -233.42219)
		(width 0.0889)
		(layer "In4.Cu")
		(net "M_J_CPU0_SA_DQ<16>")
	)
	(segment
		(start 396.01394 -232.57383)
		(end 401.216622 -227.371148)
		(width 0.14478)
		(layer "In4.Cu")
		(net "M_J_CPU0_SA_DQ<16>")
	)
	(segment
		(start 436.96382 -215.610186)
		(end 439.100214 -216.035128)
		(width 0.14478)
		(layer "In4.Cu")
		(net "M_J_CPU0_SA_DQ<16>")
	)
	(segment
		(start 418.566854 -216.46007)
		(end 421.625014 -216.46007)
		(width 0.14478)
		(layer "In4.Cu")
		(net "M_J_CPU0_SA_DQ<16>")
	)
	(segment
		(start 430.653952 -215.610186)
		(end 436.96382 -215.610186)
		(width 0.14478)
		(layer "In4.Cu")
		(net "M_J_CPU0_SA_DQ<16>")
	)
	(segment
		(start 383.393442 -235.091478)
		(end 383.401824 -235.086652)
		(width 0.0889)
		(layer "In4.Cu")
		(net "M_J_CPU0_SA_DQ<16>")
	)
	(segment
		(start 408.959812 -216.46007)
		(end 414.114488 -216.46007)
		(width 0.14478)
		(layer "In4.Cu")
		(net "M_J_CPU0_SA_DQ<16>")
	)
	(segment
		(start 414.964372 -215.610186)
		(end 417.71697 -215.610186)
		(width 0.14478)
		(layer "In4.Cu")
		(net "M_J_CPU0_SA_DQ<16>")
	)
	(segment
		(start 392.770614 -234.61599)
		(end 393.119356 -234.61599)
		(width 0.0889)
		(layer "In4.Cu")
		(net "M_J_CPU0_SA_DQ<16>")
	)
	(segment
		(start 380.394718 -234.764072)
		(end 380.548896 -235.029502)
		(width 0.0889)
		(layer "In4.Cu")
		(net "M_J_CPU0_SA_DQ<16>")
	)
	(arc
		(start 382.087882 -235.086652)
		(mid 382.274826 -235.136907)
		(end 382.46177 -235.086652)
		(width 0.0889)
		(layer "In4.Cu")
		(net "M_J_CPU0_SA_DQ<16>")
	)
	(arc
		(start 385.856226 -235.091478)
		(mid 386.039734 -235.136972)
		(end 386.221986 -235.086652)
		(width 0.0889)
		(layer "In4.Cu")
		(net "M_J_CPU0_SA_DQ<16>")
	)
	(arc
		(start 387.161786 -235.086652)
		(mid 387.444742 -235.010475)
		(end 387.727698 -235.086652)
		(width 0.0889)
		(layer "In4.Cu")
		(net "M_J_CPU0_SA_DQ<16>")
	)
	(arc
		(start 380.645162 -235.054902)
		(mid 380.900227 -235.011551)
		(end 381.147828 -235.086652)
		(width 0.0889)
		(layer "In4.Cu")
		(net "M_J_CPU0_SA_DQ<16>")
	)
	(arc
		(start 390.921748 -235.086652)
		(mid 391.204704 -235.010475)
		(end 391.48766 -235.086652)
		(width 0.0889)
		(layer "In4.Cu")
		(net "M_J_CPU0_SA_DQ<16>")
	)
	(arc
		(start 381.15621 -235.091478)
		(mid 381.339718 -235.136972)
		(end 381.52197 -235.086652)
		(width 0.0889)
		(layer "In4.Cu")
		(net "M_J_CPU0_SA_DQ<16>")
	)
	(arc
		(start 388.667752 -235.086652)
		(mid 388.850003 -235.137002)
		(end 389.033512 -235.091478)
		(width 0.0889)
		(layer "In4.Cu")
		(net "M_J_CPU0_SA_DQ<16>")
	)
	(arc
		(start 381.52197 -235.086652)
		(mid 381.804926 -235.010475)
		(end 382.087882 -235.086652)
		(width 0.0889)
		(layer "In4.Cu")
		(net "M_J_CPU0_SA_DQ<16>")
	)
	(arc
		(start 383.967736 -235.086652)
		(mid 384.149987 -235.137002)
		(end 384.333496 -235.091478)
		(width 0.0889)
		(layer "In4.Cu")
		(net "M_J_CPU0_SA_DQ<16>")
	)
	(arc
		(start 389.616188 -235.091478)
		(mid 389.799696 -235.136972)
		(end 389.981948 -235.086652)
		(width 0.0889)
		(layer "In4.Cu")
		(net "M_J_CPU0_SA_DQ<16>")
	)
	(arc
		(start 389.981948 -235.086652)
		(mid 390.264904 -235.010475)
		(end 390.54786 -235.086652)
		(width 0.0889)
		(layer "In4.Cu")
		(net "M_J_CPU0_SA_DQ<16>")
	)
	(arc
		(start 383.401824 -235.086652)
		(mid 383.68478 -235.010475)
		(end 383.967736 -235.086652)
		(width 0.0889)
		(layer "In4.Cu")
		(net "M_J_CPU0_SA_DQ<16>")
	)
	(arc
		(start 391.496042 -235.091478)
		(mid 391.679804 -235.137094)
		(end 391.86231 -235.086652)
		(width 0.0889)
		(layer "In4.Cu")
		(net "M_J_CPU0_SA_DQ<16>")
	)
	(arc
		(start 388.10184 -235.086652)
		(mid 388.384796 -235.010475)
		(end 388.667752 -235.086652)
		(width 0.0889)
		(layer "In4.Cu")
		(net "M_J_CPU0_SA_DQ<16>")
	)
	(arc
		(start 390.54786 -235.086652)
		(mid 390.734804 -235.136907)
		(end 390.921748 -235.086652)
		(width 0.0889)
		(layer "In4.Cu")
		(net "M_J_CPU0_SA_DQ<16>")
	)
	(arc
		(start 382.46177 -235.086652)
		(mid 382.744726 -235.010475)
		(end 383.027682 -235.086652)
		(width 0.0889)
		(layer "In4.Cu")
		(net "M_J_CPU0_SA_DQ<16>")
	)
	(arc
		(start 383.027682 -235.086652)
		(mid 383.209933 -235.137002)
		(end 383.393442 -235.091478)
		(width 0.0889)
		(layer "In4.Cu")
		(net "M_J_CPU0_SA_DQ<16>")
	)
	(arc
		(start 389.041894 -235.086652)
		(mid 389.32485 -235.010475)
		(end 389.607806 -235.086652)
		(width 0.0889)
		(layer "In4.Cu")
		(net "M_J_CPU0_SA_DQ<16>")
	)
	(arc
		(start 387.727698 -235.086652)
		(mid 387.909949 -235.137002)
		(end 388.093458 -235.091478)
		(width 0.0889)
		(layer "In4.Cu")
		(net "M_J_CPU0_SA_DQ<16>")
	)
	(arc
		(start 386.787898 -235.086652)
		(mid 386.974842 -235.136907)
		(end 387.161786 -235.086652)
		(width 0.0889)
		(layer "In4.Cu")
		(net "M_J_CPU0_SA_DQ<16>")
	)
	(arc
		(start 385.281932 -235.086652)
		(mid 385.564888 -235.010475)
		(end 385.847844 -235.086652)
		(width 0.0889)
		(layer "In4.Cu")
		(net "M_J_CPU0_SA_DQ<16>")
	)
	(arc
		(start 384.916172 -235.091478)
		(mid 385.09968 -235.136972)
		(end 385.281932 -235.086652)
		(width 0.0889)
		(layer "In4.Cu")
		(net "M_J_CPU0_SA_DQ<16>")
	)
	(arc
		(start 386.221986 -235.086652)
		(mid 386.504942 -235.010475)
		(end 386.787898 -235.086652)
		(width 0.0889)
		(layer "In4.Cu")
		(net "M_J_CPU0_SA_DQ<16>")
	)
	(arc
		(start 384.341878 -235.086652)
		(mid 384.624834 -235.010475)
		(end 384.90779 -235.086652)
		(width 0.0889)
		(layer "In4.Cu")
		(net "M_J_CPU0_SA_DQ<16>")
	)
	(segment
		(start 378.988066 -235.03001)
		(end 379.454918 -234.764072)
		(width 0.10668)
		(layer "F.Cu")
		(net "M_J_CPU0_SA_DQ<15>")
	)
	(segment
		(start 417.700968 -214.760048)
		(end 418.551106 -215.610186)
		(width 0.14478)
		(layer "In4.Cu")
		(net "M_J_CPU0_SA_DQ<15>")
	)
	(segment
		(start 430.004728 -214.760048)
		(end 432.430174 -214.760048)
		(width 0.14478)
		(layer "In4.Cu")
		(net "M_J_CPU0_SA_DQ<15>")
	)
	(segment
		(start 425.683426 -214.760048)
		(end 426.533564 -215.610186)
		(width 0.14478)
		(layer "In4.Cu")
		(net "M_J_CPU0_SA_DQ<15>")
	)
	(segment
		(start 393.702794 -233.59491)
		(end 395.277594 -232.02011)
		(width 0.0889)
		(layer "In4.Cu")
		(net "M_J_CPU0_SA_DQ<15>")
	)
	(segment
		(start 401.006818 -223.633538)
		(end 401.006818 -223.404938)
		(width 0.14478)
		(layer "In4.Cu")
		(net "M_J_CPU0_SA_DQ<15>")
	)
	(segment
		(start 402.504148 -221.229428)
		(end 402.732748 -221.229428)
		(width 0.14478)
		(layer "In4.Cu")
		(net "M_J_CPU0_SA_DQ<15>")
	)
	(segment
		(start 401.562316 -222.39986)
		(end 401.562316 -222.17126)
		(width 0.14478)
		(layer "In4.Cu")
		(net "M_J_CPU0_SA_DQ<15>")
	)
	(segment
		(start 429.15459 -215.610186)
		(end 430.004728 -214.760048)
		(width 0.14478)
		(layer "In4.Cu")
		(net "M_J_CPU0_SA_DQ<15>")
	)
	(segment
		(start 401.006818 -223.404938)
		(end 400.782028 -223.180148)
		(width 0.14478)
		(layer "In4.Cu")
		(net "M_J_CPU0_SA_DQ<15>")
	)
	(segment
		(start 381.147828 -234.441492)
		(end 381.15621 -234.436666)
		(width 0.0889)
		(layer "In4.Cu")
		(net "M_J_CPU0_SA_DQ<15>")
	)
	(segment
		(start 379.454918 -234.764072)
		(end 379.30074 -234.498642)
		(width 0.0889)
		(layer "In4.Cu")
		(net "M_J_CPU0_SA_DQ<15>")
	)
	(segment
		(start 395.277594 -232.02011)
		(end 395.701774 -232.02011)
		(width 0.0889)
		(layer "In4.Cu")
		(net "M_J_CPU0_SA_DQ<15>")
	)
	(segment
		(start 434.387752 -214.760048)
		(end 434.575204 -214.760048)
		(width 0.14478)
		(layer "In4.Cu")
		(net "M_J_CPU0_SA_DQ<15>")
	)
	(segment
		(start 384.90779 -234.441492)
		(end 384.916172 -234.436666)
		(width 0.0889)
		(layer "In4.Cu")
		(net "M_J_CPU0_SA_DQ<15>")
	)
	(segment
		(start 401.396962 -223.014794)
		(end 401.625562 -223.014794)
		(width 0.14478)
		(layer "In4.Cu")
		(net "M_J_CPU0_SA_DQ<15>")
	)
	(segment
		(start 400.782028 -223.180148)
		(end 400.782028 -222.951548)
		(width 0.14478)
		(layer "In4.Cu")
		(net "M_J_CPU0_SA_DQ<15>")
	)
	(segment
		(start 402.342604 -221.390972)
		(end 402.504148 -221.229428)
		(width 0.14478)
		(layer "In4.Cu")
		(net "M_J_CPU0_SA_DQ<15>")
	)
	(segment
		(start 379.63348 -234.436666)
		(end 379.641862 -234.441492)
		(width 0.0889)
		(layer "In4.Cu")
		(net "M_J_CPU0_SA_DQ<15>")
	)
	(segment
		(start 401.625562 -223.014794)
		(end 401.787106 -222.85325)
		(width 0.14478)
		(layer "In4.Cu")
		(net "M_J_CPU0_SA_DQ<15>")
	)
	(segment
		(start 404.746714 -219.893642)
		(end 409.03017 -215.610186)
		(width 0.14478)
		(layer "In4.Cu")
		(net "M_J_CPU0_SA_DQ<15>")
	)
	(segment
		(start 402.342604 -221.619572)
		(end 402.342604 -221.390972)
		(width 0.14478)
		(layer "In4.Cu")
		(net "M_J_CPU0_SA_DQ<15>")
	)
	(segment
		(start 403.347682 -221.064074)
		(end 403.122892 -220.839284)
		(width 0.14478)
		(layer "In4.Cu")
		(net "M_J_CPU0_SA_DQ<15>")
	)
	(segment
		(start 404.12797 -220.283786)
		(end 403.90318 -220.058996)
		(width 0.14478)
		(layer "In4.Cu")
		(net "M_J_CPU0_SA_DQ<15>")
	)
	(segment
		(start 432.73345 -214.456772)
		(end 432.981608 -214.456772)
		(width 0.14478)
		(layer "In4.Cu")
		(net "M_J_CPU0_SA_DQ<15>")
	)
	(segment
		(start 404.064724 -219.668852)
		(end 404.293324 -219.668852)
		(width 0.14478)
		(layer "In4.Cu")
		(net "M_J_CPU0_SA_DQ<15>")
	)
	(segment
		(start 402.567394 -222.072962)
		(end 402.567394 -221.844362)
		(width 0.14478)
		(layer "In4.Cu")
		(net "M_J_CPU0_SA_DQ<15>")
	)
	(segment
		(start 403.737826 -220.67393)
		(end 403.966426 -220.67393)
		(width 0.14478)
		(layer "In4.Cu")
		(net "M_J_CPU0_SA_DQ<15>")
	)
	(segment
		(start 400.665442 -223.974914)
		(end 401.006818 -223.633538)
		(width 0.14478)
		(layer "In4.Cu")
		(net "M_J_CPU0_SA_DQ<15>")
	)
	(segment
		(start 395.701774 -232.02011)
		(end 400.665442 -227.056442)
		(width 0.14478)
		(layer "In4.Cu")
		(net "M_J_CPU0_SA_DQ<15>")
	)
	(segment
		(start 433.836318 -214.456772)
		(end 434.084476 -214.456772)
		(width 0.14478)
		(layer "In4.Cu")
		(net "M_J_CPU0_SA_DQ<15>")
	)
	(segment
		(start 434.575204 -214.760048)
		(end 435.000146 -215.18499)
		(width 0.14478)
		(layer "In4.Cu")
		(net "M_J_CPU0_SA_DQ<15>")
	)
	(segment
		(start 402.732748 -221.229428)
		(end 402.957538 -221.454218)
		(width 0.14478)
		(layer "In4.Cu")
		(net "M_J_CPU0_SA_DQ<15>")
	)
	(segment
		(start 392.135106 -234.3912)
		(end 392.931396 -233.59491)
		(width 0.0889)
		(layer "In4.Cu")
		(net "M_J_CPU0_SA_DQ<15>")
	)
	(segment
		(start 400.665442 -227.056442)
		(end 400.665442 -223.974914)
		(width 0.14478)
		(layer "In4.Cu")
		(net "M_J_CPU0_SA_DQ<15>")
	)
	(segment
		(start 404.12797 -220.512386)
		(end 404.12797 -220.283786)
		(width 0.14478)
		(layer "In4.Cu")
		(net "M_J_CPU0_SA_DQ<15>")
	)
	(segment
		(start 402.17725 -222.234506)
		(end 402.40585 -222.234506)
		(width 0.14478)
		(layer "In4.Cu")
		(net "M_J_CPU0_SA_DQ<15>")
	)
	(segment
		(start 432.430174 -214.760048)
		(end 432.73345 -214.456772)
		(width 0.14478)
		(layer "In4.Cu")
		(net "M_J_CPU0_SA_DQ<15>")
	)
	(segment
		(start 402.40585 -222.234506)
		(end 402.567394 -222.072962)
		(width 0.14478)
		(layer "In4.Cu")
		(net "M_J_CPU0_SA_DQ<15>")
	)
	(segment
		(start 402.567394 -221.844362)
		(end 402.342604 -221.619572)
		(width 0.14478)
		(layer "In4.Cu")
		(net "M_J_CPU0_SA_DQ<15>")
	)
	(segment
		(start 403.513036 -220.44914)
		(end 403.737826 -220.67393)
		(width 0.14478)
		(layer "In4.Cu")
		(net "M_J_CPU0_SA_DQ<15>")
	)
	(segment
		(start 403.186138 -221.454218)
		(end 403.347682 -221.292674)
		(width 0.14478)
		(layer "In4.Cu")
		(net "M_J_CPU0_SA_DQ<15>")
	)
	(segment
		(start 401.787106 -222.62465)
		(end 401.562316 -222.39986)
		(width 0.14478)
		(layer "In4.Cu")
		(net "M_J_CPU0_SA_DQ<15>")
	)
	(segment
		(start 389.607806 -234.441492)
		(end 389.616188 -234.436666)
		(width 0.0889)
		(layer "In4.Cu")
		(net "M_J_CPU0_SA_DQ<15>")
	)
	(segment
		(start 414.005776 -215.610186)
		(end 414.855914 -214.760048)
		(width 0.14478)
		(layer "In4.Cu")
		(net "M_J_CPU0_SA_DQ<15>")
	)
	(segment
		(start 404.518114 -219.893642)
		(end 404.746714 -219.893642)
		(width 0.14478)
		(layer "In4.Cu")
		(net "M_J_CPU0_SA_DQ<15>")
	)
	(segment
		(start 385.847844 -234.441492)
		(end 385.856226 -234.436666)
		(width 0.0889)
		(layer "In4.Cu")
		(net "M_J_CPU0_SA_DQ<15>")
	)
	(segment
		(start 403.90318 -219.830396)
		(end 404.064724 -219.668852)
		(width 0.14478)
		(layer "In4.Cu")
		(net "M_J_CPU0_SA_DQ<15>")
	)
	(segment
		(start 421.602662 -215.610186)
		(end 422.4528 -214.760048)
		(width 0.14478)
		(layer "In4.Cu")
		(net "M_J_CPU0_SA_DQ<15>")
	)
	(segment
		(start 422.4528 -214.760048)
		(end 425.683426 -214.760048)
		(width 0.14478)
		(layer "In4.Cu")
		(net "M_J_CPU0_SA_DQ<15>")
	)
	(segment
		(start 400.782028 -222.951548)
		(end 400.943572 -222.790004)
		(width 0.14478)
		(layer "In4.Cu")
		(net "M_J_CPU0_SA_DQ<15>")
	)
	(segment
		(start 404.293324 -219.668852)
		(end 404.518114 -219.893642)
		(width 0.14478)
		(layer "In4.Cu")
		(net "M_J_CPU0_SA_DQ<15>")
	)
	(segment
		(start 432.981608 -214.456772)
		(end 433.284884 -214.760048)
		(width 0.14478)
		(layer "In4.Cu")
		(net "M_J_CPU0_SA_DQ<15>")
	)
	(segment
		(start 418.551106 -215.610186)
		(end 421.602662 -215.610186)
		(width 0.14478)
		(layer "In4.Cu")
		(net "M_J_CPU0_SA_DQ<15>")
	)
	(segment
		(start 401.95246 -222.009716)
		(end 402.17725 -222.234506)
		(width 0.14478)
		(layer "In4.Cu")
		(net "M_J_CPU0_SA_DQ<15>")
	)
	(segment
		(start 426.533564 -215.610186)
		(end 429.15459 -215.610186)
		(width 0.14478)
		(layer "In4.Cu")
		(net "M_J_CPU0_SA_DQ<15>")
	)
	(segment
		(start 403.122892 -220.610684)
		(end 403.284436 -220.44914)
		(width 0.14478)
		(layer "In4.Cu")
		(net "M_J_CPU0_SA_DQ<15>")
	)
	(segment
		(start 409.03017 -215.610186)
		(end 414.005776 -215.610186)
		(width 0.14478)
		(layer "In4.Cu")
		(net "M_J_CPU0_SA_DQ<15>")
	)
	(segment
		(start 388.093458 -234.436666)
		(end 388.10184 -234.441492)
		(width 0.0889)
		(layer "In4.Cu")
		(net "M_J_CPU0_SA_DQ<15>")
	)
	(segment
		(start 433.284884 -214.760048)
		(end 433.533042 -214.760048)
		(width 0.14478)
		(layer "In4.Cu")
		(net "M_J_CPU0_SA_DQ<15>")
	)
	(segment
		(start 401.172172 -222.790004)
		(end 401.396962 -223.014794)
		(width 0.14478)
		(layer "In4.Cu")
		(net "M_J_CPU0_SA_DQ<15>")
	)
	(segment
		(start 403.347682 -221.292674)
		(end 403.347682 -221.064074)
		(width 0.14478)
		(layer "In4.Cu")
		(net "M_J_CPU0_SA_DQ<15>")
	)
	(segment
		(start 401.562316 -222.17126)
		(end 401.72386 -222.009716)
		(width 0.14478)
		(layer "In4.Cu")
		(net "M_J_CPU0_SA_DQ<15>")
	)
	(segment
		(start 400.943572 -222.790004)
		(end 401.172172 -222.790004)
		(width 0.14478)
		(layer "In4.Cu")
		(net "M_J_CPU0_SA_DQ<15>")
	)
	(segment
		(start 403.122892 -220.839284)
		(end 403.122892 -220.610684)
		(width 0.14478)
		(layer "In4.Cu")
		(net "M_J_CPU0_SA_DQ<15>")
	)
	(segment
		(start 379.30074 -234.498642)
		(end 379.323092 -234.41533)
		(width 0.0889)
		(layer "In4.Cu")
		(net "M_J_CPU0_SA_DQ<15>")
	)
	(segment
		(start 383.393442 -234.436666)
		(end 383.401824 -234.441492)
		(width 0.0889)
		(layer "In4.Cu")
		(net "M_J_CPU0_SA_DQ<15>")
	)
	(segment
		(start 403.284436 -220.44914)
		(end 403.513036 -220.44914)
		(width 0.14478)
		(layer "In4.Cu")
		(net "M_J_CPU0_SA_DQ<15>")
	)
	(segment
		(start 403.90318 -220.058996)
		(end 403.90318 -219.830396)
		(width 0.14478)
		(layer "In4.Cu")
		(net "M_J_CPU0_SA_DQ<15>")
	)
	(segment
		(start 403.966426 -220.67393)
		(end 404.12797 -220.512386)
		(width 0.14478)
		(layer "In4.Cu")
		(net "M_J_CPU0_SA_DQ<15>")
	)
	(segment
		(start 401.72386 -222.009716)
		(end 401.95246 -222.009716)
		(width 0.14478)
		(layer "In4.Cu")
		(net "M_J_CPU0_SA_DQ<15>")
	)
	(segment
		(start 434.084476 -214.456772)
		(end 434.387752 -214.760048)
		(width 0.14478)
		(layer "In4.Cu")
		(net "M_J_CPU0_SA_DQ<15>")
	)
	(segment
		(start 392.931396 -233.59491)
		(end 393.702794 -233.59491)
		(width 0.0889)
		(layer "In4.Cu")
		(net "M_J_CPU0_SA_DQ<15>")
	)
	(segment
		(start 389.033512 -234.436666)
		(end 389.041894 -234.441492)
		(width 0.0889)
		(layer "In4.Cu")
		(net "M_J_CPU0_SA_DQ<15>")
	)
	(segment
		(start 433.533042 -214.760048)
		(end 433.836318 -214.456772)
		(width 0.14478)
		(layer "In4.Cu")
		(net "M_J_CPU0_SA_DQ<15>")
	)
	(segment
		(start 391.674858 -234.3912)
		(end 392.135106 -234.3912)
		(width 0.0889)
		(layer "In4.Cu")
		(net "M_J_CPU0_SA_DQ<15>")
	)
	(segment
		(start 414.855914 -214.760048)
		(end 417.700968 -214.760048)
		(width 0.14478)
		(layer "In4.Cu")
		(net "M_J_CPU0_SA_DQ<15>")
	)
	(segment
		(start 401.787106 -222.85325)
		(end 401.787106 -222.62465)
		(width 0.14478)
		(layer "In4.Cu")
		(net "M_J_CPU0_SA_DQ<15>")
	)
	(segment
		(start 402.957538 -221.454218)
		(end 403.186138 -221.454218)
		(width 0.14478)
		(layer "In4.Cu")
		(net "M_J_CPU0_SA_DQ<15>")
	)
	(segment
		(start 380.207774 -234.441492)
		(end 380.216156 -234.436666)
		(width 0.0889)
		(layer "In4.Cu")
		(net "M_J_CPU0_SA_DQ<15>")
	)
	(segment
		(start 384.333496 -234.436666)
		(end 384.341878 -234.441492)
		(width 0.0889)
		(layer "In4.Cu")
		(net "M_J_CPU0_SA_DQ<15>")
	)
	(arc
		(start 386.787898 -234.441492)
		(mid 386.974842 -234.391237)
		(end 387.161786 -234.441492)
		(width 0.0889)
		(layer "In4.Cu")
		(net "M_J_CPU0_SA_DQ<15>")
	)
	(arc
		(start 384.916172 -234.436666)
		(mid 385.09968 -234.391172)
		(end 385.281932 -234.441492)
		(width 0.0889)
		(layer "In4.Cu")
		(net "M_J_CPU0_SA_DQ<15>")
	)
	(arc
		(start 380.581916 -234.441492)
		(mid 380.864872 -234.517669)
		(end 381.147828 -234.441492)
		(width 0.0889)
		(layer "In4.Cu")
		(net "M_J_CPU0_SA_DQ<15>")
	)
	(arc
		(start 388.10184 -234.441492)
		(mid 388.384796 -234.517669)
		(end 388.667752 -234.441492)
		(width 0.0889)
		(layer "In4.Cu")
		(net "M_J_CPU0_SA_DQ<15>")
	)
	(arc
		(start 389.981948 -234.441492)
		(mid 390.264904 -234.517669)
		(end 390.54786 -234.441492)
		(width 0.0889)
		(layer "In4.Cu")
		(net "M_J_CPU0_SA_DQ<15>")
	)
	(arc
		(start 390.921748 -234.441492)
		(mid 391.204704 -234.517669)
		(end 391.48766 -234.441492)
		(width 0.0889)
		(layer "In4.Cu")
		(net "M_J_CPU0_SA_DQ<15>")
	)
	(arc
		(start 389.616188 -234.436666)
		(mid 389.799696 -234.391172)
		(end 389.981948 -234.441492)
		(width 0.0889)
		(layer "In4.Cu")
		(net "M_J_CPU0_SA_DQ<15>")
	)
	(arc
		(start 387.161786 -234.441492)
		(mid 387.444742 -234.517669)
		(end 387.727698 -234.441492)
		(width 0.0889)
		(layer "In4.Cu")
		(net "M_J_CPU0_SA_DQ<15>")
	)
	(arc
		(start 387.727698 -234.441492)
		(mid 387.909949 -234.391142)
		(end 388.093458 -234.436666)
		(width 0.0889)
		(layer "In4.Cu")
		(net "M_J_CPU0_SA_DQ<15>")
	)
	(arc
		(start 380.216156 -234.436666)
		(mid 380.399664 -234.391172)
		(end 380.581916 -234.441492)
		(width 0.0889)
		(layer "In4.Cu")
		(net "M_J_CPU0_SA_DQ<15>")
	)
	(arc
		(start 382.087882 -234.441492)
		(mid 382.274826 -234.391237)
		(end 382.46177 -234.441492)
		(width 0.0889)
		(layer "In4.Cu")
		(net "M_J_CPU0_SA_DQ<15>")
	)
	(arc
		(start 390.54786 -234.441492)
		(mid 390.734804 -234.391237)
		(end 390.921748 -234.441492)
		(width 0.0889)
		(layer "In4.Cu")
		(net "M_J_CPU0_SA_DQ<15>")
	)
	(arc
		(start 386.221986 -234.441492)
		(mid 386.504942 -234.517669)
		(end 386.787898 -234.441492)
		(width 0.0889)
		(layer "In4.Cu")
		(net "M_J_CPU0_SA_DQ<15>")
	)
	(arc
		(start 383.401824 -234.441492)
		(mid 383.68478 -234.517669)
		(end 383.967736 -234.441492)
		(width 0.0889)
		(layer "In4.Cu")
		(net "M_J_CPU0_SA_DQ<15>")
	)
	(arc
		(start 391.48766 -234.441492)
		(mid 391.577936 -234.403987)
		(end 391.674858 -234.3912)
		(width 0.0889)
		(layer "In4.Cu")
		(net "M_J_CPU0_SA_DQ<15>")
	)
	(arc
		(start 381.15621 -234.436666)
		(mid 381.339718 -234.391172)
		(end 381.52197 -234.441492)
		(width 0.0889)
		(layer "In4.Cu")
		(net "M_J_CPU0_SA_DQ<15>")
	)
	(arc
		(start 379.641862 -234.441492)
		(mid 379.924818 -234.517669)
		(end 380.207774 -234.441492)
		(width 0.0889)
		(layer "In4.Cu")
		(net "M_J_CPU0_SA_DQ<15>")
	)
	(arc
		(start 388.667752 -234.441492)
		(mid 388.850003 -234.391142)
		(end 389.033512 -234.436666)
		(width 0.0889)
		(layer "In4.Cu")
		(net "M_J_CPU0_SA_DQ<15>")
	)
	(arc
		(start 381.52197 -234.441492)
		(mid 381.804926 -234.517669)
		(end 382.087882 -234.441492)
		(width 0.0889)
		(layer "In4.Cu")
		(net "M_J_CPU0_SA_DQ<15>")
	)
	(arc
		(start 379.323092 -234.41533)
		(mid 379.480602 -234.392132)
		(end 379.63348 -234.436666)
		(width 0.0889)
		(layer "In4.Cu")
		(net "M_J_CPU0_SA_DQ<15>")
	)
	(arc
		(start 385.281932 -234.441492)
		(mid 385.564888 -234.517669)
		(end 385.847844 -234.441492)
		(width 0.0889)
		(layer "In4.Cu")
		(net "M_J_CPU0_SA_DQ<15>")
	)
	(arc
		(start 382.46177 -234.441492)
		(mid 382.744726 -234.517669)
		(end 383.027682 -234.441492)
		(width 0.0889)
		(layer "In4.Cu")
		(net "M_J_CPU0_SA_DQ<15>")
	)
	(arc
		(start 389.041894 -234.441492)
		(mid 389.32485 -234.517669)
		(end 389.607806 -234.441492)
		(width 0.0889)
		(layer "In4.Cu")
		(net "M_J_CPU0_SA_DQ<15>")
	)
	(arc
		(start 385.856226 -234.436666)
		(mid 386.039734 -234.391172)
		(end 386.221986 -234.441492)
		(width 0.0889)
		(layer "In4.Cu")
		(net "M_J_CPU0_SA_DQ<15>")
	)
	(arc
		(start 384.341878 -234.441492)
		(mid 384.624834 -234.517669)
		(end 384.90779 -234.441492)
		(width 0.0889)
		(layer "In4.Cu")
		(net "M_J_CPU0_SA_DQ<15>")
	)
	(arc
		(start 383.027682 -234.441492)
		(mid 383.209933 -234.391142)
		(end 383.393442 -234.436666)
		(width 0.0889)
		(layer "In4.Cu")
		(net "M_J_CPU0_SA_DQ<15>")
	)
	(arc
		(start 383.967736 -234.441492)
		(mid 384.149987 -234.391142)
		(end 384.333496 -234.436666)
		(width 0.0889)
		(layer "In4.Cu")
		(net "M_J_CPU0_SA_DQ<15>")
	)
	(segment
		(start 380.39802 -234.220004)
		(end 380.864872 -233.954066)
		(width 0.10668)
		(layer "F.Cu")
		(net "M_J_CPU0_SA_DQ<14>")
	)
	(segment
		(start 385.74345 -233.62666)
		(end 385.751832 -233.631486)
		(width 0.0889)
		(layer "In4.Cu")
		(net "M_J_CPU0_SA_DQ<14>")
	)
	(segment
		(start 404.583646 -218.106244)
		(end 404.583646 -217.877644)
		(width 0.14478)
		(layer "In4.Cu")
		(net "M_J_CPU0_SA_DQ<14>")
	)
	(segment
		(start 405.525478 -216.935812)
		(end 405.754078 -216.935812)
		(width 0.14478)
		(layer "In4.Cu")
		(net "M_J_CPU0_SA_DQ<14>")
	)
	(segment
		(start 403.964902 -218.496388)
		(end 404.193502 -218.496388)
		(width 0.14478)
		(layer "In4.Cu")
		(net "M_J_CPU0_SA_DQ<14>")
	)
	(segment
		(start 406.92451 -215.76538)
		(end 406.92451 -215.53678)
		(width 0.14478)
		(layer "In4.Cu")
		(net "M_J_CPU0_SA_DQ<14>")
	)
	(segment
		(start 405.963628 -217.145362)
		(end 406.192228 -217.145362)
		(width 0.14478)
		(layer "In4.Cu")
		(net "M_J_CPU0_SA_DQ<14>")
	)
	(segment
		(start 393.434824 -233.01833)
		(end 394.264896 -232.188258)
		(width 0.0889)
		(layer "In4.Cu")
		(net "M_J_CPU0_SA_DQ<14>")
	)
	(segment
		(start 432.258216 -213.060026)
		(end 432.56073 -212.757512)
		(width 0.14478)
		(layer "In4.Cu")
		(net "M_J_CPU0_SA_DQ<14>")
	)
	(segment
		(start 418.379148 -213.910164)
		(end 421.437054 -213.910164)
		(width 0.14478)
		(layer "In4.Cu")
		(net "M_J_CPU0_SA_DQ<14>")
	)
	(segment
		(start 405.363934 -217.325956)
		(end 405.363934 -217.097356)
		(width 0.14478)
		(layer "In4.Cu")
		(net "M_J_CPU0_SA_DQ<14>")
	)
	(segment
		(start 391.958068 -233.631486)
		(end 392.014964 -233.598466)
		(width 0.0889)
		(layer "In4.Cu")
		(net "M_J_CPU0_SA_DQ<14>")
	)
	(segment
		(start 407.914348 -215.194642)
		(end 407.704798 -214.985092)
		(width 0.14478)
		(layer "In4.Cu")
		(net "M_J_CPU0_SA_DQ<14>")
	)
	(segment
		(start 394.264896 -232.188258)
		(end 394.264896 -231.665018)
		(width 0.0889)
		(layer "In4.Cu")
		(net "M_J_CPU0_SA_DQ<14>")
	)
	(segment
		(start 406.92451 -215.53678)
		(end 407.086054 -215.375236)
		(width 0.14478)
		(layer "In4.Cu")
		(net "M_J_CPU0_SA_DQ<14>")
	)
	(segment
		(start 407.524204 -215.584786)
		(end 407.752804 -215.584786)
		(width 0.14478)
		(layer "In4.Cu")
		(net "M_J_CPU0_SA_DQ<14>")
	)
	(segment
		(start 429.331882 -213.910164)
		(end 430.18202 -213.060026)
		(width 0.14478)
		(layer "In4.Cu")
		(net "M_J_CPU0_SA_DQ<14>")
	)
	(segment
		(start 430.18202 -213.060026)
		(end 432.258216 -213.060026)
		(width 0.14478)
		(layer "In4.Cu")
		(net "M_J_CPU0_SA_DQ<14>")
	)
	(segment
		(start 387.257798 -233.631486)
		(end 387.26618 -233.62666)
		(width 0.0889)
		(layer "In4.Cu")
		(net "M_J_CPU0_SA_DQ<14>")
	)
	(segment
		(start 404.193502 -218.496388)
		(end 404.403052 -218.705938)
		(width 0.14478)
		(layer "In4.Cu")
		(net "M_J_CPU0_SA_DQ<14>")
	)
	(segment
		(start 433.663598 -212.757512)
		(end 433.912518 -212.757512)
		(width 0.14478)
		(layer "In4.Cu")
		(net "M_J_CPU0_SA_DQ<14>")
	)
	(segment
		(start 428.681642 -214.205312)
		(end 428.97679 -213.910164)
		(width 0.14478)
		(layer "In4.Cu")
		(net "M_J_CPU0_SA_DQ<14>")
	)
	(segment
		(start 406.144222 -216.545668)
		(end 406.144222 -216.317068)
		(width 0.14478)
		(layer "In4.Cu")
		(net "M_J_CPU0_SA_DQ<14>")
	)
	(segment
		(start 381.983488 -233.62666)
		(end 381.99187 -233.631486)
		(width 0.0889)
		(layer "In4.Cu")
		(net "M_J_CPU0_SA_DQ<14>")
	)
	(segment
		(start 382.557782 -233.631486)
		(end 382.566164 -233.62666)
		(width 0.0889)
		(layer "In4.Cu")
		(net "M_J_CPU0_SA_DQ<14>")
	)
	(segment
		(start 428.130208 -213.910164)
		(end 428.425356 -214.205312)
		(width 0.14478)
		(layer "In4.Cu")
		(net "M_J_CPU0_SA_DQ<14>")
	)
	(segment
		(start 410.712666 -214.197692)
		(end 410.976572 -214.197692)
		(width 0.14478)
		(layer "In4.Cu")
		(net "M_J_CPU0_SA_DQ<14>")
	)
	(segment
		(start 421.437054 -213.910164)
		(end 422.287192 -213.060026)
		(width 0.14478)
		(layer "In4.Cu")
		(net "M_J_CPU0_SA_DQ<14>")
	)
	(segment
		(start 409.873704 -214.197692)
		(end 410.161232 -213.910164)
		(width 0.14478)
		(layer "In4.Cu")
		(net "M_J_CPU0_SA_DQ<14>")
	)
	(segment
		(start 380.710694 -233.688636)
		(end 380.733046 -233.605324)
		(width 0.0889)
		(layer "In4.Cu")
		(net "M_J_CPU0_SA_DQ<14>")
	)
	(segment
		(start 407.752804 -215.584786)
		(end 407.914348 -215.423242)
		(width 0.14478)
		(layer "In4.Cu")
		(net "M_J_CPU0_SA_DQ<14>")
	)
	(segment
		(start 395.633448 -230.658162)
		(end 399.766282 -226.525328)
		(width 0.14478)
		(layer "In4.Cu")
		(net "M_J_CPU0_SA_DQ<14>")
	)
	(segment
		(start 405.573484 -217.764106)
		(end 405.573484 -217.535506)
		(width 0.14478)
		(layer "In4.Cu")
		(net "M_J_CPU0_SA_DQ<14>")
	)
	(segment
		(start 411.2641 -213.910164)
		(end 414.168082 -213.910164)
		(width 0.14478)
		(layer "In4.Cu")
		(net "M_J_CPU0_SA_DQ<14>")
	)
	(segment
		(start 406.972516 -216.365074)
		(end 407.13406 -216.20353)
		(width 0.14478)
		(layer "In4.Cu")
		(net "M_J_CPU0_SA_DQ<14>")
	)
	(segment
		(start 391.01776 -233.631486)
		(end 391.026142 -233.62666)
		(width 0.0889)
		(layer "In4.Cu")
		(net "M_J_CPU0_SA_DQ<14>")
	)
	(segment
		(start 433.112164 -213.060026)
		(end 433.361084 -213.060026)
		(width 0.14478)
		(layer "In4.Cu")
		(net "M_J_CPU0_SA_DQ<14>")
	)
	(segment
		(start 406.144222 -216.317068)
		(end 406.305766 -216.155524)
		(width 0.14478)
		(layer "In4.Cu")
		(net "M_J_CPU0_SA_DQ<14>")
	)
	(segment
		(start 404.793196 -218.544394)
		(end 404.793196 -218.315794)
		(width 0.14478)
		(layer "In4.Cu")
		(net "M_J_CPU0_SA_DQ<14>")
	)
	(segment
		(start 426.322236 -213.910164)
		(end 428.130208 -213.910164)
		(width 0.14478)
		(layer "In4.Cu")
		(net "M_J_CPU0_SA_DQ<14>")
	)
	(segment
		(start 406.353772 -216.755218)
		(end 406.144222 -216.545668)
		(width 0.14478)
		(layer "In4.Cu")
		(net "M_J_CPU0_SA_DQ<14>")
	)
	(segment
		(start 434.215032 -213.060026)
		(end 434.575204 -213.060026)
		(width 0.14478)
		(layer "In4.Cu")
		(net "M_J_CPU0_SA_DQ<14>")
	)
	(segment
		(start 407.086054 -215.375236)
		(end 407.314654 -215.375236)
		(width 0.14478)
		(layer "In4.Cu")
		(net "M_J_CPU0_SA_DQ<14>")
	)
	(segment
		(start 386.683504 -233.62666)
		(end 386.691886 -233.631486)
		(width 0.0889)
		(layer "In4.Cu")
		(net "M_J_CPU0_SA_DQ<14>")
	)
	(segment
		(start 405.41194 -217.92565)
		(end 405.573484 -217.764106)
		(width 0.14478)
		(layer "In4.Cu")
		(net "M_J_CPU0_SA_DQ<14>")
	)
	(segment
		(start 407.314654 -215.375236)
		(end 407.524204 -215.584786)
		(width 0.14478)
		(layer "In4.Cu")
		(net "M_J_CPU0_SA_DQ<14>")
	)
	(segment
		(start 407.13406 -216.20353)
		(end 407.13406 -215.97493)
		(width 0.14478)
		(layer "In4.Cu")
		(net "M_J_CPU0_SA_DQ<14>")
	)
	(segment
		(start 406.305766 -216.155524)
		(end 406.534366 -216.155524)
		(width 0.14478)
		(layer "In4.Cu")
		(net "M_J_CPU0_SA_DQ<14>")
	)
	(segment
		(start 406.353772 -216.983818)
		(end 406.353772 -216.755218)
		(width 0.14478)
		(layer "In4.Cu")
		(net "M_J_CPU0_SA_DQ<14>")
	)
	(segment
		(start 410.425138 -213.910164)
		(end 410.712666 -214.197692)
		(width 0.14478)
		(layer "In4.Cu")
		(net "M_J_CPU0_SA_DQ<14>")
	)
	(segment
		(start 404.793196 -218.315794)
		(end 404.583646 -218.106244)
		(width 0.14478)
		(layer "In4.Cu")
		(net "M_J_CPU0_SA_DQ<14>")
	)
	(segment
		(start 434.575204 -213.060026)
		(end 435.000146 -213.484968)
		(width 0.14478)
		(layer "In4.Cu")
		(net "M_J_CPU0_SA_DQ<14>")
	)
	(segment
		(start 410.976572 -214.197692)
		(end 411.2641 -213.910164)
		(width 0.14478)
		(layer "In4.Cu")
		(net "M_J_CPU0_SA_DQ<14>")
	)
	(segment
		(start 417.52901 -213.060026)
		(end 418.379148 -213.910164)
		(width 0.14478)
		(layer "In4.Cu")
		(net "M_J_CPU0_SA_DQ<14>")
	)
	(segment
		(start 406.743916 -216.365074)
		(end 406.972516 -216.365074)
		(width 0.14478)
		(layer "In4.Cu")
		(net "M_J_CPU0_SA_DQ<14>")
	)
	(segment
		(start 406.534366 -216.155524)
		(end 406.743916 -216.365074)
		(width 0.14478)
		(layer "In4.Cu")
		(net "M_J_CPU0_SA_DQ<14>")
	)
	(segment
		(start 380.864872 -233.954066)
		(end 380.710694 -233.688636)
		(width 0.0889)
		(layer "In4.Cu")
		(net "M_J_CPU0_SA_DQ<14>")
	)
	(segment
		(start 392.014964 -233.598466)
		(end 392.5951 -233.01833)
		(width 0.0889)
		(layer "In4.Cu")
		(net "M_J_CPU0_SA_DQ<14>")
	)
	(segment
		(start 432.56073 -212.757512)
		(end 432.80965 -212.757512)
		(width 0.14478)
		(layer "In4.Cu")
		(net "M_J_CPU0_SA_DQ<14>")
	)
	(segment
		(start 409.32227 -213.910164)
		(end 409.609798 -214.197692)
		(width 0.14478)
		(layer "In4.Cu")
		(net "M_J_CPU0_SA_DQ<14>")
	)
	(segment
		(start 407.13406 -215.97493)
		(end 406.92451 -215.76538)
		(width 0.14478)
		(layer "In4.Cu")
		(net "M_J_CPU0_SA_DQ<14>")
	)
	(segment
		(start 388.197852 -233.631486)
		(end 388.206234 -233.62666)
		(width 0.0889)
		(layer "In4.Cu")
		(net "M_J_CPU0_SA_DQ<14>")
	)
	(segment
		(start 414.168082 -213.910164)
		(end 415.01822 -213.060026)
		(width 0.14478)
		(layer "In4.Cu")
		(net "M_J_CPU0_SA_DQ<14>")
	)
	(segment
		(start 409.609798 -214.197692)
		(end 409.873704 -214.197692)
		(width 0.14478)
		(layer "In4.Cu")
		(net "M_J_CPU0_SA_DQ<14>")
	)
	(segment
		(start 415.01822 -213.060026)
		(end 417.52901 -213.060026)
		(width 0.14478)
		(layer "In4.Cu")
		(net "M_J_CPU0_SA_DQ<14>")
	)
	(segment
		(start 422.287192 -213.060026)
		(end 425.472098 -213.060026)
		(width 0.14478)
		(layer "In4.Cu")
		(net "M_J_CPU0_SA_DQ<14>")
	)
	(segment
		(start 399.766282 -226.525328)
		(end 399.766282 -222.695008)
		(width 0.14478)
		(layer "In4.Cu")
		(net "M_J_CPU0_SA_DQ<14>")
	)
	(segment
		(start 433.361084 -213.060026)
		(end 433.663598 -212.757512)
		(width 0.14478)
		(layer "In4.Cu")
		(net "M_J_CPU0_SA_DQ<14>")
	)
	(segment
		(start 405.18334 -217.92565)
		(end 405.41194 -217.92565)
		(width 0.14478)
		(layer "In4.Cu")
		(net "M_J_CPU0_SA_DQ<14>")
	)
	(segment
		(start 405.573484 -217.535506)
		(end 405.363934 -217.325956)
		(width 0.14478)
		(layer "In4.Cu")
		(net "M_J_CPU0_SA_DQ<14>")
	)
	(segment
		(start 394.264896 -231.665018)
		(end 394.689584 -231.24033)
		(width 0.0889)
		(layer "In4.Cu")
		(net "M_J_CPU0_SA_DQ<14>")
	)
	(segment
		(start 410.161232 -213.910164)
		(end 410.425138 -213.910164)
		(width 0.14478)
		(layer "In4.Cu")
		(net "M_J_CPU0_SA_DQ<14>")
	)
	(segment
		(start 404.631652 -218.705938)
		(end 404.793196 -218.544394)
		(width 0.14478)
		(layer "In4.Cu")
		(net "M_J_CPU0_SA_DQ<14>")
	)
	(segment
		(start 407.704798 -214.756492)
		(end 408.551126 -213.910164)
		(width 0.14478)
		(layer "In4.Cu")
		(net "M_J_CPU0_SA_DQ<14>")
	)
	(segment
		(start 408.551126 -213.910164)
		(end 409.32227 -213.910164)
		(width 0.14478)
		(layer "In4.Cu")
		(net "M_J_CPU0_SA_DQ<14>")
	)
	(segment
		(start 404.583646 -217.877644)
		(end 404.74519 -217.7161)
		(width 0.14478)
		(layer "In4.Cu")
		(net "M_J_CPU0_SA_DQ<14>")
	)
	(segment
		(start 407.704798 -214.985092)
		(end 407.704798 -214.756492)
		(width 0.14478)
		(layer "In4.Cu")
		(net "M_J_CPU0_SA_DQ<14>")
	)
	(segment
		(start 405.363934 -217.097356)
		(end 405.525478 -216.935812)
		(width 0.14478)
		(layer "In4.Cu")
		(net "M_J_CPU0_SA_DQ<14>")
	)
	(segment
		(start 394.689584 -231.24033)
		(end 395.05128 -231.24033)
		(width 0.0889)
		(layer "In4.Cu")
		(net "M_J_CPU0_SA_DQ<14>")
	)
	(segment
		(start 391.391902 -233.631486)
		(end 391.402316 -233.637582)
		(width 0.0889)
		(layer "In4.Cu")
		(net "M_J_CPU0_SA_DQ<14>")
	)
	(segment
		(start 404.97379 -217.7161)
		(end 405.18334 -217.92565)
		(width 0.14478)
		(layer "In4.Cu")
		(net "M_J_CPU0_SA_DQ<14>")
	)
	(segment
		(start 428.97679 -213.910164)
		(end 429.331882 -213.910164)
		(width 0.14478)
		(layer "In4.Cu")
		(net "M_J_CPU0_SA_DQ<14>")
	)
	(segment
		(start 406.192228 -217.145362)
		(end 406.353772 -216.983818)
		(width 0.14478)
		(layer "In4.Cu")
		(net "M_J_CPU0_SA_DQ<14>")
	)
	(segment
		(start 392.5951 -233.01833)
		(end 393.434824 -233.01833)
		(width 0.0889)
		(layer "In4.Cu")
		(net "M_J_CPU0_SA_DQ<14>")
	)
	(segment
		(start 425.472098 -213.060026)
		(end 426.322236 -213.910164)
		(width 0.14478)
		(layer "In4.Cu")
		(net "M_J_CPU0_SA_DQ<14>")
	)
	(segment
		(start 381.043434 -233.62666)
		(end 381.051816 -233.631486)
		(width 0.0889)
		(layer "In4.Cu")
		(net "M_J_CPU0_SA_DQ<14>")
	)
	(segment
		(start 432.80965 -212.757512)
		(end 433.112164 -213.060026)
		(width 0.14478)
		(layer "In4.Cu")
		(net "M_J_CPU0_SA_DQ<14>")
	)
	(segment
		(start 428.425356 -214.205312)
		(end 428.681642 -214.205312)
		(width 0.14478)
		(layer "In4.Cu")
		(net "M_J_CPU0_SA_DQ<14>")
	)
	(segment
		(start 404.74519 -217.7161)
		(end 404.97379 -217.7161)
		(width 0.14478)
		(layer "In4.Cu")
		(net "M_J_CPU0_SA_DQ<14>")
	)
	(segment
		(start 404.403052 -218.705938)
		(end 404.631652 -218.705938)
		(width 0.14478)
		(layer "In4.Cu")
		(net "M_J_CPU0_SA_DQ<14>")
	)
	(segment
		(start 433.912518 -212.757512)
		(end 434.215032 -213.060026)
		(width 0.14478)
		(layer "In4.Cu")
		(net "M_J_CPU0_SA_DQ<14>")
	)
	(segment
		(start 390.443466 -233.62666)
		(end 390.451848 -233.631486)
		(width 0.0889)
		(layer "In4.Cu")
		(net "M_J_CPU0_SA_DQ<14>")
	)
	(segment
		(start 407.914348 -215.423242)
		(end 407.914348 -215.194642)
		(width 0.14478)
		(layer "In4.Cu")
		(net "M_J_CPU0_SA_DQ<14>")
	)
	(segment
		(start 405.754078 -216.935812)
		(end 405.963628 -217.145362)
		(width 0.14478)
		(layer "In4.Cu")
		(net "M_J_CPU0_SA_DQ<14>")
	)
	(segment
		(start 395.05128 -231.24033)
		(end 395.633448 -230.658162)
		(width 0.0889)
		(layer "In4.Cu")
		(net "M_J_CPU0_SA_DQ<14>")
	)
	(segment
		(start 399.766282 -222.695008)
		(end 403.964902 -218.496388)
		(width 0.14478)
		(layer "In4.Cu")
		(net "M_J_CPU0_SA_DQ<14>")
	)
	(segment
		(start 383.497836 -233.631486)
		(end 383.506218 -233.62666)
		(width 0.0889)
		(layer "In4.Cu")
		(net "M_J_CPU0_SA_DQ<14>")
	)
	(arc
		(start 381.617728 -233.631486)
		(mid 381.799979 -233.581136)
		(end 381.983488 -233.62666)
		(width 0.0889)
		(layer "In4.Cu")
		(net "M_J_CPU0_SA_DQ<14>")
	)
	(arc
		(start 384.811778 -233.631486)
		(mid 385.094734 -233.707663)
		(end 385.37769 -233.631486)
		(width 0.0889)
		(layer "In4.Cu")
		(net "M_J_CPU0_SA_DQ<14>")
	)
	(arc
		(start 386.317744 -233.631486)
		(mid 386.499995 -233.581136)
		(end 386.683504 -233.62666)
		(width 0.0889)
		(layer "In4.Cu")
		(net "M_J_CPU0_SA_DQ<14>")
	)
	(arc
		(start 381.051816 -233.631486)
		(mid 381.334772 -233.707663)
		(end 381.617728 -233.631486)
		(width 0.0889)
		(layer "In4.Cu")
		(net "M_J_CPU0_SA_DQ<14>")
	)
	(arc
		(start 385.751832 -233.631486)
		(mid 386.034788 -233.707663)
		(end 386.317744 -233.631486)
		(width 0.0889)
		(layer "In4.Cu")
		(net "M_J_CPU0_SA_DQ<14>")
	)
	(arc
		(start 385.37769 -233.631486)
		(mid 385.559941 -233.581136)
		(end 385.74345 -233.62666)
		(width 0.0889)
		(layer "In4.Cu")
		(net "M_J_CPU0_SA_DQ<14>")
	)
	(arc
		(start 384.43789 -233.631486)
		(mid 384.624834 -233.581231)
		(end 384.811778 -233.631486)
		(width 0.0889)
		(layer "In4.Cu")
		(net "M_J_CPU0_SA_DQ<14>")
	)
	(arc
		(start 389.137906 -233.631486)
		(mid 389.32485 -233.581231)
		(end 389.511794 -233.631486)
		(width 0.0889)
		(layer "In4.Cu")
		(net "M_J_CPU0_SA_DQ<14>")
	)
	(arc
		(start 388.206234 -233.62666)
		(mid 388.389742 -233.581166)
		(end 388.571994 -233.631486)
		(width 0.0889)
		(layer "In4.Cu")
		(net "M_J_CPU0_SA_DQ<14>")
	)
	(arc
		(start 390.077706 -233.631486)
		(mid 390.259957 -233.581136)
		(end 390.443466 -233.62666)
		(width 0.0889)
		(layer "In4.Cu")
		(net "M_J_CPU0_SA_DQ<14>")
	)
	(arc
		(start 382.931924 -233.631486)
		(mid 383.21488 -233.707663)
		(end 383.497836 -233.631486)
		(width 0.0889)
		(layer "In4.Cu")
		(net "M_J_CPU0_SA_DQ<14>")
	)
	(arc
		(start 383.506218 -233.62666)
		(mid 383.689726 -233.581166)
		(end 383.871978 -233.631486)
		(width 0.0889)
		(layer "In4.Cu")
		(net "M_J_CPU0_SA_DQ<14>")
	)
	(arc
		(start 383.871978 -233.631486)
		(mid 384.154934 -233.707663)
		(end 384.43789 -233.631486)
		(width 0.0889)
		(layer "In4.Cu")
		(net "M_J_CPU0_SA_DQ<14>")
	)
	(arc
		(start 387.26618 -233.62666)
		(mid 387.449688 -233.581166)
		(end 387.63194 -233.631486)
		(width 0.0889)
		(layer "In4.Cu")
		(net "M_J_CPU0_SA_DQ<14>")
	)
	(arc
		(start 391.026142 -233.62666)
		(mid 391.20965 -233.581166)
		(end 391.391902 -233.631486)
		(width 0.0889)
		(layer "In4.Cu")
		(net "M_J_CPU0_SA_DQ<14>")
	)
	(arc
		(start 380.733046 -233.605324)
		(mid 380.890556 -233.582126)
		(end 381.043434 -233.62666)
		(width 0.0889)
		(layer "In4.Cu")
		(net "M_J_CPU0_SA_DQ<14>")
	)
	(arc
		(start 390.451848 -233.631486)
		(mid 390.734804 -233.707663)
		(end 391.01776 -233.631486)
		(width 0.0889)
		(layer "In4.Cu")
		(net "M_J_CPU0_SA_DQ<14>")
	)
	(arc
		(start 381.99187 -233.631486)
		(mid 382.274826 -233.707663)
		(end 382.557782 -233.631486)
		(width 0.0889)
		(layer "In4.Cu")
		(net "M_J_CPU0_SA_DQ<14>")
	)
	(arc
		(start 386.691886 -233.631486)
		(mid 386.974842 -233.707663)
		(end 387.257798 -233.631486)
		(width 0.0889)
		(layer "In4.Cu")
		(net "M_J_CPU0_SA_DQ<14>")
	)
	(arc
		(start 388.571994 -233.631486)
		(mid 388.85495 -233.707663)
		(end 389.137906 -233.631486)
		(width 0.0889)
		(layer "In4.Cu")
		(net "M_J_CPU0_SA_DQ<14>")
	)
	(arc
		(start 389.511794 -233.631486)
		(mid 389.79475 -233.707663)
		(end 390.077706 -233.631486)
		(width 0.0889)
		(layer "In4.Cu")
		(net "M_J_CPU0_SA_DQ<14>")
	)
	(arc
		(start 391.402316 -233.637582)
		(mid 391.681002 -233.707802)
		(end 391.958068 -233.631486)
		(width 0.0889)
		(layer "In4.Cu")
		(net "M_J_CPU0_SA_DQ<14>")
	)
	(arc
		(start 382.566164 -233.62666)
		(mid 382.749672 -233.581166)
		(end 382.931924 -233.631486)
		(width 0.0889)
		(layer "In4.Cu")
		(net "M_J_CPU0_SA_DQ<14>")
	)
	(arc
		(start 387.63194 -233.631486)
		(mid 387.914896 -233.707663)
		(end 388.197852 -233.631486)
		(width 0.0889)
		(layer "In4.Cu")
		(net "M_J_CPU0_SA_DQ<14>")
	)
	(segment
		(start 378.517912 -234.220004)
		(end 378.984764 -233.954066)
		(width 0.10668)
		(layer "F.Cu")
		(net "M_J_CPU0_SA_DQ<13>")
	)
	(segment
		(start 414.16224 -214.760048)
		(end 415.012124 -213.910164)
		(width 0.14478)
		(layer "In4.Cu")
		(net "M_J_CPU0_SA_DQ<13>")
	)
	(segment
		(start 437.513222 -214.657432)
		(end 437.674766 -214.495888)
		(width 0.14478)
		(layer "In4.Cu")
		(net "M_J_CPU0_SA_DQ<13>")
	)
	(segment
		(start 387.257798 -234.276646)
		(end 387.26618 -234.281472)
		(width 0.0889)
		(layer "In4.Cu")
		(net "M_J_CPU0_SA_DQ<13>")
	)
	(segment
		(start 400.215862 -226.794568)
		(end 400.215862 -222.881444)
		(width 0.14478)
		(layer "In4.Cu")
		(net "M_J_CPU0_SA_DQ<13>")
	)
	(segment
		(start 395.329156 -231.675432)
		(end 395.334998 -231.675432)
		(width 0.0889)
		(layer "In4.Cu")
		(net "M_J_CPU0_SA_DQ<13>")
	)
	(segment
		(start 381.043434 -234.281472)
		(end 381.051816 -234.276646)
		(width 0.0889)
		(layer "In4.Cu")
		(net "M_J_CPU0_SA_DQ<13>")
	)
	(segment
		(start 437.284876 -214.657432)
		(end 437.513222 -214.657432)
		(width 0.14478)
		(layer "In4.Cu")
		(net "M_J_CPU0_SA_DQ<13>")
	)
	(segment
		(start 430.086262 -213.910164)
		(end 436.961788 -213.910164)
		(width 0.14478)
		(layer "In4.Cu")
		(net "M_J_CPU0_SA_DQ<13>")
	)
	(segment
		(start 391.01776 -234.276646)
		(end 391.026142 -234.281472)
		(width 0.0889)
		(layer "In4.Cu")
		(net "M_J_CPU0_SA_DQ<13>")
	)
	(segment
		(start 395.334998 -231.675432)
		(end 395.896338 -231.114092)
		(width 0.0889)
		(layer "In4.Cu")
		(net "M_J_CPU0_SA_DQ<13>")
	)
	(segment
		(start 403.878034 -219.219272)
		(end 404.784814 -219.219272)
		(width 0.14478)
		(layer "In4.Cu")
		(net "M_J_CPU0_SA_DQ<13>")
	)
	(segment
		(start 426.41139 -214.760048)
		(end 429.236378 -214.760048)
		(width 0.14478)
		(layer "In4.Cu")
		(net "M_J_CPU0_SA_DQ<13>")
	)
	(segment
		(start 388.197852 -234.276646)
		(end 388.206234 -234.281472)
		(width 0.0889)
		(layer "In4.Cu")
		(net "M_J_CPU0_SA_DQ<13>")
	)
	(segment
		(start 422.58107 -213.910164)
		(end 425.561506 -213.910164)
		(width 0.14478)
		(layer "In4.Cu")
		(net "M_J_CPU0_SA_DQ<13>")
	)
	(segment
		(start 429.236378 -214.760048)
		(end 430.086262 -213.910164)
		(width 0.14478)
		(layer "In4.Cu")
		(net "M_J_CPU0_SA_DQ<13>")
	)
	(segment
		(start 436.961788 -213.910164)
		(end 437.123332 -214.071708)
		(width 0.14478)
		(layer "In4.Cu")
		(net "M_J_CPU0_SA_DQ<13>")
	)
	(segment
		(start 415.012124 -213.910164)
		(end 417.619688 -213.910164)
		(width 0.14478)
		(layer "In4.Cu")
		(net "M_J_CPU0_SA_DQ<13>")
	)
	(segment
		(start 437.123332 -214.071708)
		(end 437.123332 -214.495888)
		(width 0.14478)
		(layer "In4.Cu")
		(net "M_J_CPU0_SA_DQ<13>")
	)
	(segment
		(start 409.244038 -214.760048)
		(end 414.16224 -214.760048)
		(width 0.14478)
		(layer "In4.Cu")
		(net "M_J_CPU0_SA_DQ<13>")
	)
	(segment
		(start 417.619688 -213.910164)
		(end 418.469572 -214.760048)
		(width 0.14478)
		(layer "In4.Cu")
		(net "M_J_CPU0_SA_DQ<13>")
	)
	(segment
		(start 381.983488 -234.281472)
		(end 381.99187 -234.276646)
		(width 0.0889)
		(layer "In4.Cu")
		(net "M_J_CPU0_SA_DQ<13>")
	)
	(segment
		(start 391.98423 -234.200192)
		(end 392.866372 -233.31805)
		(width 0.0889)
		(layer "In4.Cu")
		(net "M_J_CPU0_SA_DQ<13>")
	)
	(segment
		(start 383.497836 -234.276646)
		(end 383.506218 -234.281472)
		(width 0.0889)
		(layer "In4.Cu")
		(net "M_J_CPU0_SA_DQ<13>")
	)
	(segment
		(start 395.896338 -231.114092)
		(end 400.215862 -226.794568)
		(width 0.14478)
		(layer "In4.Cu")
		(net "M_J_CPU0_SA_DQ<13>")
	)
	(segment
		(start 379.138942 -234.219496)
		(end 379.235208 -234.244896)
		(width 0.0889)
		(layer "In4.Cu")
		(net "M_J_CPU0_SA_DQ<13>")
	)
	(segment
		(start 437.83631 -213.910164)
		(end 438.675272 -213.910164)
		(width 0.14478)
		(layer "In4.Cu")
		(net "M_J_CPU0_SA_DQ<13>")
	)
	(segment
		(start 385.74345 -234.281472)
		(end 385.751832 -234.276646)
		(width 0.0889)
		(layer "In4.Cu")
		(net "M_J_CPU0_SA_DQ<13>")
	)
	(segment
		(start 392.866372 -233.31805)
		(end 393.686538 -233.31805)
		(width 0.0889)
		(layer "In4.Cu")
		(net "M_J_CPU0_SA_DQ<13>")
	)
	(segment
		(start 382.557782 -234.276646)
		(end 382.566164 -234.281472)
		(width 0.0889)
		(layer "In4.Cu")
		(net "M_J_CPU0_SA_DQ<13>")
	)
	(segment
		(start 438.675272 -213.910164)
		(end 439.100214 -214.335106)
		(width 0.14478)
		(layer "In4.Cu")
		(net "M_J_CPU0_SA_DQ<13>")
	)
	(segment
		(start 437.123332 -214.495888)
		(end 437.284876 -214.657432)
		(width 0.14478)
		(layer "In4.Cu")
		(net "M_J_CPU0_SA_DQ<13>")
	)
	(segment
		(start 418.469572 -214.760048)
		(end 421.731186 -214.760048)
		(width 0.14478)
		(layer "In4.Cu")
		(net "M_J_CPU0_SA_DQ<13>")
	)
	(segment
		(start 404.784814 -219.219272)
		(end 409.244038 -214.760048)
		(width 0.14478)
		(layer "In4.Cu")
		(net "M_J_CPU0_SA_DQ<13>")
	)
	(segment
		(start 391.674858 -234.200192)
		(end 391.98423 -234.200192)
		(width 0.0889)
		(layer "In4.Cu")
		(net "M_J_CPU0_SA_DQ<13>")
	)
	(segment
		(start 437.674766 -214.071708)
		(end 437.83631 -213.910164)
		(width 0.14478)
		(layer "In4.Cu")
		(net "M_J_CPU0_SA_DQ<13>")
	)
	(segment
		(start 390.443466 -234.281472)
		(end 390.451848 -234.276646)
		(width 0.0889)
		(layer "In4.Cu")
		(net "M_J_CPU0_SA_DQ<13>")
	)
	(segment
		(start 378.984764 -233.954066)
		(end 379.138942 -234.219496)
		(width 0.0889)
		(layer "In4.Cu")
		(net "M_J_CPU0_SA_DQ<13>")
	)
	(segment
		(start 386.683504 -234.281472)
		(end 386.691886 -234.276646)
		(width 0.0889)
		(layer "In4.Cu")
		(net "M_J_CPU0_SA_DQ<13>")
	)
	(segment
		(start 421.731186 -214.760048)
		(end 422.58107 -213.910164)
		(width 0.14478)
		(layer "In4.Cu")
		(net "M_J_CPU0_SA_DQ<13>")
	)
	(segment
		(start 425.561506 -213.910164)
		(end 426.41139 -214.760048)
		(width 0.14478)
		(layer "In4.Cu")
		(net "M_J_CPU0_SA_DQ<13>")
	)
	(segment
		(start 400.215862 -222.881444)
		(end 403.878034 -219.219272)
		(width 0.14478)
		(layer "In4.Cu")
		(net "M_J_CPU0_SA_DQ<13>")
	)
	(segment
		(start 437.674766 -214.495888)
		(end 437.674766 -214.071708)
		(width 0.14478)
		(layer "In4.Cu")
		(net "M_J_CPU0_SA_DQ<13>")
	)
	(segment
		(start 393.686538 -233.31805)
		(end 395.329156 -231.675432)
		(width 0.0889)
		(layer "In4.Cu")
		(net "M_J_CPU0_SA_DQ<13>")
	)
	(segment
		(start 391.391902 -234.276646)
		(end 391.406634 -234.26801)
		(width 0.0889)
		(layer "In4.Cu")
		(net "M_J_CPU0_SA_DQ<13>")
	)
	(arc
		(start 381.99187 -234.276646)
		(mid 382.274826 -234.200469)
		(end 382.557782 -234.276646)
		(width 0.0889)
		(layer "In4.Cu")
		(net "M_J_CPU0_SA_DQ<13>")
	)
	(arc
		(start 382.566164 -234.281472)
		(mid 382.749672 -234.326966)
		(end 382.931924 -234.276646)
		(width 0.0889)
		(layer "In4.Cu")
		(net "M_J_CPU0_SA_DQ<13>")
	)
	(arc
		(start 384.811778 -234.276646)
		(mid 385.094734 -234.200469)
		(end 385.37769 -234.276646)
		(width 0.0889)
		(layer "In4.Cu")
		(net "M_J_CPU0_SA_DQ<13>")
	)
	(arc
		(start 387.26618 -234.281472)
		(mid 387.449688 -234.326966)
		(end 387.63194 -234.276646)
		(width 0.0889)
		(layer "In4.Cu")
		(net "M_J_CPU0_SA_DQ<13>")
	)
	(arc
		(start 385.37769 -234.276646)
		(mid 385.559941 -234.326996)
		(end 385.74345 -234.281472)
		(width 0.0889)
		(layer "In4.Cu")
		(net "M_J_CPU0_SA_DQ<13>")
	)
	(arc
		(start 388.206234 -234.281472)
		(mid 388.389742 -234.326966)
		(end 388.571994 -234.276646)
		(width 0.0889)
		(layer "In4.Cu")
		(net "M_J_CPU0_SA_DQ<13>")
	)
	(arc
		(start 390.451848 -234.276646)
		(mid 390.734804 -234.200469)
		(end 391.01776 -234.276646)
		(width 0.0889)
		(layer "In4.Cu")
		(net "M_J_CPU0_SA_DQ<13>")
	)
	(arc
		(start 388.571994 -234.276646)
		(mid 388.85495 -234.200469)
		(end 389.137906 -234.276646)
		(width 0.0889)
		(layer "In4.Cu")
		(net "M_J_CPU0_SA_DQ<13>")
	)
	(arc
		(start 389.511794 -234.276646)
		(mid 389.79475 -234.200469)
		(end 390.077706 -234.276646)
		(width 0.0889)
		(layer "In4.Cu")
		(net "M_J_CPU0_SA_DQ<13>")
	)
	(arc
		(start 381.051816 -234.276646)
		(mid 381.334772 -234.200469)
		(end 381.617728 -234.276646)
		(width 0.0889)
		(layer "In4.Cu")
		(net "M_J_CPU0_SA_DQ<13>")
	)
	(arc
		(start 386.691886 -234.276646)
		(mid 386.974842 -234.200469)
		(end 387.257798 -234.276646)
		(width 0.0889)
		(layer "In4.Cu")
		(net "M_J_CPU0_SA_DQ<13>")
	)
	(arc
		(start 391.406634 -234.26801)
		(mid 391.536519 -234.217369)
		(end 391.674858 -234.200192)
		(width 0.0889)
		(layer "In4.Cu")
		(net "M_J_CPU0_SA_DQ<13>")
	)
	(arc
		(start 379.235208 -234.244896)
		(mid 379.490273 -234.201545)
		(end 379.737874 -234.276646)
		(width 0.0889)
		(layer "In4.Cu")
		(net "M_J_CPU0_SA_DQ<13>")
	)
	(arc
		(start 383.506218 -234.281472)
		(mid 383.689726 -234.326966)
		(end 383.871978 -234.276646)
		(width 0.0889)
		(layer "In4.Cu")
		(net "M_J_CPU0_SA_DQ<13>")
	)
	(arc
		(start 380.111762 -234.276646)
		(mid 380.394718 -234.200469)
		(end 380.677674 -234.276646)
		(width 0.0889)
		(layer "In4.Cu")
		(net "M_J_CPU0_SA_DQ<13>")
	)
	(arc
		(start 382.931924 -234.276646)
		(mid 383.21488 -234.200469)
		(end 383.497836 -234.276646)
		(width 0.0889)
		(layer "In4.Cu")
		(net "M_J_CPU0_SA_DQ<13>")
	)
	(arc
		(start 380.677674 -234.276646)
		(mid 380.859925 -234.326996)
		(end 381.043434 -234.281472)
		(width 0.0889)
		(layer "In4.Cu")
		(net "M_J_CPU0_SA_DQ<13>")
	)
	(arc
		(start 389.137906 -234.276646)
		(mid 389.32485 -234.326901)
		(end 389.511794 -234.276646)
		(width 0.0889)
		(layer "In4.Cu")
		(net "M_J_CPU0_SA_DQ<13>")
	)
	(arc
		(start 386.317744 -234.276646)
		(mid 386.499995 -234.326996)
		(end 386.683504 -234.281472)
		(width 0.0889)
		(layer "In4.Cu")
		(net "M_J_CPU0_SA_DQ<13>")
	)
	(arc
		(start 383.871978 -234.276646)
		(mid 384.154934 -234.200469)
		(end 384.43789 -234.276646)
		(width 0.0889)
		(layer "In4.Cu")
		(net "M_J_CPU0_SA_DQ<13>")
	)
	(arc
		(start 379.737874 -234.276646)
		(mid 379.924818 -234.326901)
		(end 380.111762 -234.276646)
		(width 0.0889)
		(layer "In4.Cu")
		(net "M_J_CPU0_SA_DQ<13>")
	)
	(arc
		(start 387.63194 -234.276646)
		(mid 387.914896 -234.200469)
		(end 388.197852 -234.276646)
		(width 0.0889)
		(layer "In4.Cu")
		(net "M_J_CPU0_SA_DQ<13>")
	)
	(arc
		(start 390.077706 -234.276646)
		(mid 390.259957 -234.326996)
		(end 390.443466 -234.281472)
		(width 0.0889)
		(layer "In4.Cu")
		(net "M_J_CPU0_SA_DQ<13>")
	)
	(arc
		(start 384.43789 -234.276646)
		(mid 384.624834 -234.326901)
		(end 384.811778 -234.276646)
		(width 0.0889)
		(layer "In4.Cu")
		(net "M_J_CPU0_SA_DQ<13>")
	)
	(arc
		(start 391.026142 -234.281472)
		(mid 391.20965 -234.326966)
		(end 391.391902 -234.276646)
		(width 0.0889)
		(layer "In4.Cu")
		(net "M_J_CPU0_SA_DQ<13>")
	)
	(arc
		(start 385.751832 -234.276646)
		(mid 386.034788 -234.200469)
		(end 386.317744 -234.276646)
		(width 0.0889)
		(layer "In4.Cu")
		(net "M_J_CPU0_SA_DQ<13>")
	)
	(arc
		(start 381.617728 -234.276646)
		(mid 381.799979 -234.326996)
		(end 381.983488 -234.281472)
		(width 0.0889)
		(layer "In4.Cu")
		(net "M_J_CPU0_SA_DQ<13>")
	)
	(segment
		(start 379.927866 -233.409998)
		(end 380.394718 -233.14406)
		(width 0.10668)
		(layer "F.Cu")
		(net "M_J_CPU0_SA_DQ<12>")
	)
	(segment
		(start 380.394718 -233.14406)
		(end 380.548896 -233.40949)
		(width 0.0889)
		(layer "In4.Cu")
		(net "M_J_CPU0_SA_DQ<12>")
	)
	(segment
		(start 393.990576 -231.56291)
		(end 395.185646 -230.36784)
		(width 0.0889)
		(layer "In4.Cu")
		(net "M_J_CPU0_SA_DQ<12>")
	)
	(segment
		(start 438.684924 -212.219794)
		(end 439.100214 -212.635084)
		(width 0.14478)
		(layer "In4.Cu")
		(net "M_J_CPU0_SA_DQ<12>")
	)
	(segment
		(start 399.316702 -222.508572)
		(end 408.541982 -213.283292)
		(width 0.14478)
		(layer "In4.Cu")
		(net "M_J_CPU0_SA_DQ<12>")
	)
	(segment
		(start 438.361074 -212.219794)
		(end 438.684924 -212.219794)
		(width 0.14478)
		(layer "In4.Cu")
		(net "M_J_CPU0_SA_DQ<12>")
	)
	(segment
		(start 417.486084 -212.210142)
		(end 418.34562 -213.069678)
		(width 0.14478)
		(layer "In4.Cu")
		(net "M_J_CPU0_SA_DQ<12>")
	)
	(segment
		(start 393.990576 -232.05313)
		(end 393.990576 -231.56291)
		(width 0.0889)
		(layer "In4.Cu")
		(net "M_J_CPU0_SA_DQ<12>")
	)
	(segment
		(start 391.86231 -233.46664)
		(end 392.59256 -232.73639)
		(width 0.0889)
		(layer "In4.Cu")
		(net "M_J_CPU0_SA_DQ<12>")
	)
	(segment
		(start 438.19953 -212.381338)
		(end 438.361074 -212.219794)
		(width 0.14478)
		(layer "In4.Cu")
		(net "M_J_CPU0_SA_DQ<12>")
	)
	(segment
		(start 414.047178 -213.283292)
		(end 415.120328 -212.210142)
		(width 0.14478)
		(layer "In4.Cu")
		(net "M_J_CPU0_SA_DQ<12>")
	)
	(segment
		(start 438.037986 -212.996272)
		(end 438.19953 -212.834728)
		(width 0.14478)
		(layer "In4.Cu")
		(net "M_J_CPU0_SA_DQ<12>")
	)
	(segment
		(start 392.59256 -232.73639)
		(end 393.307316 -232.73639)
		(width 0.0889)
		(layer "In4.Cu")
		(net "M_J_CPU0_SA_DQ<12>")
	)
	(segment
		(start 421.583612 -213.069678)
		(end 422.433496 -212.219794)
		(width 0.14478)
		(layer "In4.Cu")
		(net "M_J_CPU0_SA_DQ<12>")
	)
	(segment
		(start 408.541982 -213.283292)
		(end 414.047178 -213.283292)
		(width 0.14478)
		(layer "In4.Cu")
		(net "M_J_CPU0_SA_DQ<12>")
	)
	(segment
		(start 395.185646 -230.36784)
		(end 399.316702 -226.236784)
		(width 0.14478)
		(layer "In4.Cu")
		(net "M_J_CPU0_SA_DQ<12>")
	)
	(segment
		(start 391.48766 -233.46664)
		(end 391.496042 -233.471466)
		(width 0.0889)
		(layer "In4.Cu")
		(net "M_J_CPU0_SA_DQ<12>")
	)
	(segment
		(start 438.19953 -212.834728)
		(end 438.19953 -212.381338)
		(width 0.14478)
		(layer "In4.Cu")
		(net "M_J_CPU0_SA_DQ<12>")
	)
	(segment
		(start 437.648096 -212.834728)
		(end 437.80964 -212.996272)
		(width 0.14478)
		(layer "In4.Cu")
		(net "M_J_CPU0_SA_DQ<12>")
	)
	(segment
		(start 437.648096 -212.381338)
		(end 437.648096 -212.834728)
		(width 0.14478)
		(layer "In4.Cu")
		(net "M_J_CPU0_SA_DQ<12>")
	)
	(segment
		(start 393.307316 -232.73639)
		(end 393.990576 -232.05313)
		(width 0.0889)
		(layer "In4.Cu")
		(net "M_J_CPU0_SA_DQ<12>")
	)
	(segment
		(start 389.033512 -233.471466)
		(end 389.041894 -233.46664)
		(width 0.0889)
		(layer "In4.Cu")
		(net "M_J_CPU0_SA_DQ<12>")
	)
	(segment
		(start 389.607806 -233.46664)
		(end 389.616188 -233.471466)
		(width 0.0889)
		(layer "In4.Cu")
		(net "M_J_CPU0_SA_DQ<12>")
	)
	(segment
		(start 385.847844 -233.46664)
		(end 385.856226 -233.471466)
		(width 0.0889)
		(layer "In4.Cu")
		(net "M_J_CPU0_SA_DQ<12>")
	)
	(segment
		(start 429.46574 -213.069678)
		(end 430.315624 -212.219794)
		(width 0.14478)
		(layer "In4.Cu")
		(net "M_J_CPU0_SA_DQ<12>")
	)
	(segment
		(start 425.305982 -212.219794)
		(end 426.155866 -213.069678)
		(width 0.14478)
		(layer "In4.Cu")
		(net "M_J_CPU0_SA_DQ<12>")
	)
	(segment
		(start 437.486552 -212.219794)
		(end 437.648096 -212.381338)
		(width 0.14478)
		(layer "In4.Cu")
		(net "M_J_CPU0_SA_DQ<12>")
	)
	(segment
		(start 437.80964 -212.996272)
		(end 438.037986 -212.996272)
		(width 0.14478)
		(layer "In4.Cu")
		(net "M_J_CPU0_SA_DQ<12>")
	)
	(segment
		(start 384.333496 -233.471466)
		(end 384.341878 -233.46664)
		(width 0.0889)
		(layer "In4.Cu")
		(net "M_J_CPU0_SA_DQ<12>")
	)
	(segment
		(start 418.34562 -213.069678)
		(end 421.583612 -213.069678)
		(width 0.14478)
		(layer "In4.Cu")
		(net "M_J_CPU0_SA_DQ<12>")
	)
	(segment
		(start 426.155866 -213.069678)
		(end 429.46574 -213.069678)
		(width 0.14478)
		(layer "In4.Cu")
		(net "M_J_CPU0_SA_DQ<12>")
	)
	(segment
		(start 380.548896 -233.40949)
		(end 380.645162 -233.43489)
		(width 0.0889)
		(layer "In4.Cu")
		(net "M_J_CPU0_SA_DQ<12>")
	)
	(segment
		(start 381.147828 -233.46664)
		(end 381.15621 -233.471466)
		(width 0.0889)
		(layer "In4.Cu")
		(net "M_J_CPU0_SA_DQ<12>")
	)
	(segment
		(start 384.90779 -233.46664)
		(end 384.916172 -233.471466)
		(width 0.0889)
		(layer "In4.Cu")
		(net "M_J_CPU0_SA_DQ<12>")
	)
	(segment
		(start 383.393442 -233.471466)
		(end 383.401824 -233.46664)
		(width 0.0889)
		(layer "In4.Cu")
		(net "M_J_CPU0_SA_DQ<12>")
	)
	(segment
		(start 422.433496 -212.219794)
		(end 425.305982 -212.219794)
		(width 0.14478)
		(layer "In4.Cu")
		(net "M_J_CPU0_SA_DQ<12>")
	)
	(segment
		(start 399.316702 -226.236784)
		(end 399.316702 -222.508572)
		(width 0.14478)
		(layer "In4.Cu")
		(net "M_J_CPU0_SA_DQ<12>")
	)
	(segment
		(start 388.093458 -233.471466)
		(end 388.10184 -233.46664)
		(width 0.0889)
		(layer "In4.Cu")
		(net "M_J_CPU0_SA_DQ<12>")
	)
	(segment
		(start 415.120328 -212.210142)
		(end 417.486084 -212.210142)
		(width 0.14478)
		(layer "In4.Cu")
		(net "M_J_CPU0_SA_DQ<12>")
	)
	(segment
		(start 430.315624 -212.219794)
		(end 437.486552 -212.219794)
		(width 0.14478)
		(layer "In4.Cu")
		(net "M_J_CPU0_SA_DQ<12>")
	)
	(arc
		(start 385.281932 -233.46664)
		(mid 385.564888 -233.390463)
		(end 385.847844 -233.46664)
		(width 0.0889)
		(layer "In4.Cu")
		(net "M_J_CPU0_SA_DQ<12>")
	)
	(arc
		(start 391.496042 -233.471466)
		(mid 391.679804 -233.517082)
		(end 391.86231 -233.46664)
		(width 0.0889)
		(layer "In4.Cu")
		(net "M_J_CPU0_SA_DQ<12>")
	)
	(arc
		(start 383.027682 -233.46664)
		(mid 383.209933 -233.51699)
		(end 383.393442 -233.471466)
		(width 0.0889)
		(layer "In4.Cu")
		(net "M_J_CPU0_SA_DQ<12>")
	)
	(arc
		(start 383.401824 -233.46664)
		(mid 383.68478 -233.390463)
		(end 383.967736 -233.46664)
		(width 0.0889)
		(layer "In4.Cu")
		(net "M_J_CPU0_SA_DQ<12>")
	)
	(arc
		(start 380.645162 -233.43489)
		(mid 380.900227 -233.391539)
		(end 381.147828 -233.46664)
		(width 0.0889)
		(layer "In4.Cu")
		(net "M_J_CPU0_SA_DQ<12>")
	)
	(arc
		(start 381.15621 -233.471466)
		(mid 381.339718 -233.51696)
		(end 381.52197 -233.46664)
		(width 0.0889)
		(layer "In4.Cu")
		(net "M_J_CPU0_SA_DQ<12>")
	)
	(arc
		(start 388.10184 -233.46664)
		(mid 388.384796 -233.390463)
		(end 388.667752 -233.46664)
		(width 0.0889)
		(layer "In4.Cu")
		(net "M_J_CPU0_SA_DQ<12>")
	)
	(arc
		(start 388.667752 -233.46664)
		(mid 388.850003 -233.51699)
		(end 389.033512 -233.471466)
		(width 0.0889)
		(layer "In4.Cu")
		(net "M_J_CPU0_SA_DQ<12>")
	)
	(arc
		(start 381.52197 -233.46664)
		(mid 381.804926 -233.390463)
		(end 382.087882 -233.46664)
		(width 0.0889)
		(layer "In4.Cu")
		(net "M_J_CPU0_SA_DQ<12>")
	)
	(arc
		(start 389.981948 -233.46664)
		(mid 390.264904 -233.390463)
		(end 390.54786 -233.46664)
		(width 0.0889)
		(layer "In4.Cu")
		(net "M_J_CPU0_SA_DQ<12>")
	)
	(arc
		(start 386.221986 -233.46664)
		(mid 386.504942 -233.390463)
		(end 386.787898 -233.46664)
		(width 0.0889)
		(layer "In4.Cu")
		(net "M_J_CPU0_SA_DQ<12>")
	)
	(arc
		(start 389.616188 -233.471466)
		(mid 389.799696 -233.51696)
		(end 389.981948 -233.46664)
		(width 0.0889)
		(layer "In4.Cu")
		(net "M_J_CPU0_SA_DQ<12>")
	)
	(arc
		(start 390.54786 -233.46664)
		(mid 390.734804 -233.516895)
		(end 390.921748 -233.46664)
		(width 0.0889)
		(layer "In4.Cu")
		(net "M_J_CPU0_SA_DQ<12>")
	)
	(arc
		(start 385.856226 -233.471466)
		(mid 386.039734 -233.51696)
		(end 386.221986 -233.46664)
		(width 0.0889)
		(layer "In4.Cu")
		(net "M_J_CPU0_SA_DQ<12>")
	)
	(arc
		(start 382.087882 -233.46664)
		(mid 382.274826 -233.516895)
		(end 382.46177 -233.46664)
		(width 0.0889)
		(layer "In4.Cu")
		(net "M_J_CPU0_SA_DQ<12>")
	)
	(arc
		(start 390.921748 -233.46664)
		(mid 391.204704 -233.390463)
		(end 391.48766 -233.46664)
		(width 0.0889)
		(layer "In4.Cu")
		(net "M_J_CPU0_SA_DQ<12>")
	)
	(arc
		(start 386.787898 -233.46664)
		(mid 386.974842 -233.516895)
		(end 387.161786 -233.46664)
		(width 0.0889)
		(layer "In4.Cu")
		(net "M_J_CPU0_SA_DQ<12>")
	)
	(arc
		(start 383.967736 -233.46664)
		(mid 384.149987 -233.51699)
		(end 384.333496 -233.471466)
		(width 0.0889)
		(layer "In4.Cu")
		(net "M_J_CPU0_SA_DQ<12>")
	)
	(arc
		(start 384.341878 -233.46664)
		(mid 384.624834 -233.390463)
		(end 384.90779 -233.46664)
		(width 0.0889)
		(layer "In4.Cu")
		(net "M_J_CPU0_SA_DQ<12>")
	)
	(arc
		(start 382.46177 -233.46664)
		(mid 382.744726 -233.390463)
		(end 383.027682 -233.46664)
		(width 0.0889)
		(layer "In4.Cu")
		(net "M_J_CPU0_SA_DQ<12>")
	)
	(arc
		(start 387.161786 -233.46664)
		(mid 387.444742 -233.390463)
		(end 387.727698 -233.46664)
		(width 0.0889)
		(layer "In4.Cu")
		(net "M_J_CPU0_SA_DQ<12>")
	)
	(arc
		(start 384.916172 -233.471466)
		(mid 385.09968 -233.51696)
		(end 385.281932 -233.46664)
		(width 0.0889)
		(layer "In4.Cu")
		(net "M_J_CPU0_SA_DQ<12>")
	)
	(arc
		(start 389.041894 -233.46664)
		(mid 389.32485 -233.390463)
		(end 389.607806 -233.46664)
		(width 0.0889)
		(layer "In4.Cu")
		(net "M_J_CPU0_SA_DQ<12>")
	)
	(arc
		(start 387.727698 -233.46664)
		(mid 387.909949 -233.51699)
		(end 388.093458 -233.471466)
		(width 0.0889)
		(layer "In4.Cu")
		(net "M_J_CPU0_SA_DQ<12>")
	)
	(segment
		(start 378.988066 -231.789986)
		(end 379.454918 -231.524048)
		(width 0.10668)
		(layer "F.Cu")
		(net "M_J_CPU0_SA_DQ<11>")
	)
	(segment
		(start 399.692368 -218.666822)
		(end 399.512028 -218.486482)
		(width 0.14478)
		(layer "In4.Cu")
		(net "M_J_CPU0_SA_DQ<11>")
	)
	(segment
		(start 401.0914 -217.49639)
		(end 408.927554 -209.660236)
		(width 0.14478)
		(layer "In4.Cu")
		(net "M_J_CPU0_SA_DQ<11>")
	)
	(segment
		(start 398.91208 -219.67571)
		(end 398.91208 -219.44711)
		(width 0.14478)
		(layer "In4.Cu")
		(net "M_J_CPU0_SA_DQ<11>")
	)
	(segment
		(start 400.8628 -217.49639)
		(end 401.0914 -217.49639)
		(width 0.14478)
		(layer "In4.Cu")
		(net "M_J_CPU0_SA_DQ<11>")
	)
	(segment
		(start 380.207774 -231.201722)
		(end 380.216156 -231.196896)
		(width 0.0889)
		(layer "In4.Cu")
		(net "M_J_CPU0_SA_DQ<11>")
	)
	(segment
		(start 398.341596 -219.656914)
		(end 398.521936 -219.837254)
		(width 0.14478)
		(layer "In4.Cu")
		(net "M_J_CPU0_SA_DQ<11>")
	)
	(segment
		(start 379.30074 -231.258618)
		(end 379.322838 -231.17556)
		(width 0.0889)
		(layer "In4.Cu")
		(net "M_J_CPU0_SA_DQ<11>")
	)
	(segment
		(start 379.63348 -231.196896)
		(end 379.641862 -231.201722)
		(width 0.0889)
		(layer "In4.Cu")
		(net "M_J_CPU0_SA_DQ<11>")
	)
	(segment
		(start 414.005776 -209.660236)
		(end 414.855914 -208.810098)
		(width 0.14478)
		(layer "In4.Cu")
		(net "M_J_CPU0_SA_DQ<11>")
	)
	(segment
		(start 397.351504 -221.007686)
		(end 397.171164 -220.827346)
		(width 0.14478)
		(layer "In4.Cu")
		(net "M_J_CPU0_SA_DQ<11>")
	)
	(segment
		(start 399.692368 -218.895422)
		(end 399.692368 -218.666822)
		(width 0.14478)
		(layer "In4.Cu")
		(net "M_J_CPU0_SA_DQ<11>")
	)
	(segment
		(start 400.082512 -218.276678)
		(end 400.311112 -218.276678)
		(width 0.14478)
		(layer "In4.Cu")
		(net "M_J_CPU0_SA_DQ<11>")
	)
	(segment
		(start 398.131792 -220.227398)
		(end 397.951452 -220.047058)
		(width 0.14478)
		(layer "In4.Cu")
		(net "M_J_CPU0_SA_DQ<11>")
	)
	(segment
		(start 384.333496 -231.196896)
		(end 384.341878 -231.201722)
		(width 0.0889)
		(layer "In4.Cu")
		(net "M_J_CPU0_SA_DQ<11>")
	)
	(segment
		(start 399.902172 -218.096338)
		(end 400.082512 -218.276678)
		(width 0.14478)
		(layer "In4.Cu")
		(net "M_J_CPU0_SA_DQ<11>")
	)
	(segment
		(start 389.033512 -231.196896)
		(end 389.041894 -231.201722)
		(width 0.0889)
		(layer "In4.Cu")
		(net "M_J_CPU0_SA_DQ<11>")
	)
	(segment
		(start 426.064426 -208.800446)
		(end 426.914564 -209.650584)
		(width 0.14478)
		(layer "In4.Cu")
		(net "M_J_CPU0_SA_DQ<11>")
	)
	(segment
		(start 421.346376 -209.65033)
		(end 422.19626 -208.800446)
		(width 0.14478)
		(layer "In4.Cu")
		(net "M_J_CPU0_SA_DQ<11>")
	)
	(segment
		(start 392.905996 -229.80523)
		(end 393.574778 -229.136448)
		(width 0.0889)
		(layer "In4.Cu")
		(net "M_J_CPU0_SA_DQ<11>")
	)
	(segment
		(start 393.574778 -229.136448)
		(end 393.574778 -228.526086)
		(width 0.0889)
		(layer "In4.Cu")
		(net "M_J_CPU0_SA_DQ<11>")
	)
	(segment
		(start 391.48766 -231.201722)
		(end 391.526776 -231.178862)
		(width 0.0889)
		(layer "In4.Cu")
		(net "M_J_CPU0_SA_DQ<11>")
	)
	(segment
		(start 383.393442 -231.196896)
		(end 383.401824 -231.201722)
		(width 0.0889)
		(layer "In4.Cu")
		(net "M_J_CPU0_SA_DQ<11>")
	)
	(segment
		(start 397.951452 -219.818458)
		(end 398.112996 -219.656914)
		(width 0.14478)
		(layer "In4.Cu")
		(net "M_J_CPU0_SA_DQ<11>")
	)
	(segment
		(start 414.855914 -208.810098)
		(end 418.13988 -208.810098)
		(width 0.14478)
		(layer "In4.Cu")
		(net "M_J_CPU0_SA_DQ<11>")
	)
	(segment
		(start 397.028162 -225.072702)
		(end 397.028162 -221.559628)
		(width 0.14478)
		(layer "In4.Cu")
		(net "M_J_CPU0_SA_DQ<11>")
	)
	(segment
		(start 393.574778 -228.526086)
		(end 395.52626 -226.574604)
		(width 0.0889)
		(layer "In4.Cu")
		(net "M_J_CPU0_SA_DQ<11>")
	)
	(segment
		(start 385.847844 -231.201722)
		(end 385.856226 -231.196896)
		(width 0.0889)
		(layer "In4.Cu")
		(net "M_J_CPU0_SA_DQ<11>")
	)
	(segment
		(start 400.472656 -218.115134)
		(end 400.472656 -217.886534)
		(width 0.14478)
		(layer "In4.Cu")
		(net "M_J_CPU0_SA_DQ<11>")
	)
	(segment
		(start 400.311112 -218.276678)
		(end 400.472656 -218.115134)
		(width 0.14478)
		(layer "In4.Cu")
		(net "M_J_CPU0_SA_DQ<11>")
	)
	(segment
		(start 429.06569 -209.650584)
		(end 429.915828 -208.800446)
		(width 0.14478)
		(layer "In4.Cu")
		(net "M_J_CPU0_SA_DQ<11>")
	)
	(segment
		(start 391.925048 -230.410766)
		(end 392.332718 -230.181912)
		(width 0.0889)
		(layer "In4.Cu")
		(net "M_J_CPU0_SA_DQ<11>")
	)
	(segment
		(start 399.512028 -218.486482)
		(end 399.512028 -218.257882)
		(width 0.14478)
		(layer "In4.Cu")
		(net "M_J_CPU0_SA_DQ<11>")
	)
	(segment
		(start 426.914564 -209.650584)
		(end 429.06569 -209.650584)
		(width 0.14478)
		(layer "In4.Cu")
		(net "M_J_CPU0_SA_DQ<11>")
	)
	(segment
		(start 398.73174 -219.26677)
		(end 398.73174 -219.03817)
		(width 0.14478)
		(layer "In4.Cu")
		(net "M_J_CPU0_SA_DQ<11>")
	)
	(segment
		(start 422.19626 -208.800446)
		(end 426.064426 -208.800446)
		(width 0.14478)
		(layer "In4.Cu")
		(net "M_J_CPU0_SA_DQ<11>")
	)
	(segment
		(start 400.68246 -217.31605)
		(end 400.8628 -217.49639)
		(width 0.14478)
		(layer "In4.Cu")
		(net "M_J_CPU0_SA_DQ<11>")
	)
	(segment
		(start 397.171164 -220.598746)
		(end 397.332708 -220.437202)
		(width 0.14478)
		(layer "In4.Cu")
		(net "M_J_CPU0_SA_DQ<11>")
	)
	(segment
		(start 395.52626 -226.574604)
		(end 397.028162 -225.072702)
		(width 0.14478)
		(layer "In4.Cu")
		(net "M_J_CPU0_SA_DQ<11>")
	)
	(segment
		(start 397.951452 -220.047058)
		(end 397.951452 -219.818458)
		(width 0.14478)
		(layer "In4.Cu")
		(net "M_J_CPU0_SA_DQ<11>")
	)
	(segment
		(start 397.332708 -220.437202)
		(end 397.561308 -220.437202)
		(width 0.14478)
		(layer "In4.Cu")
		(net "M_J_CPU0_SA_DQ<11>")
	)
	(segment
		(start 397.741648 -220.617542)
		(end 397.970248 -220.617542)
		(width 0.14478)
		(layer "In4.Cu")
		(net "M_J_CPU0_SA_DQ<11>")
	)
	(segment
		(start 388.093458 -231.196896)
		(end 388.10184 -231.201722)
		(width 0.0889)
		(layer "In4.Cu")
		(net "M_J_CPU0_SA_DQ<11>")
	)
	(segment
		(start 397.351504 -221.236286)
		(end 397.351504 -221.007686)
		(width 0.14478)
		(layer "In4.Cu")
		(net "M_J_CPU0_SA_DQ<11>")
	)
	(segment
		(start 398.893284 -218.876626)
		(end 399.121884 -218.876626)
		(width 0.14478)
		(layer "In4.Cu")
		(net "M_J_CPU0_SA_DQ<11>")
	)
	(segment
		(start 381.147828 -231.201722)
		(end 381.15621 -231.196896)
		(width 0.0889)
		(layer "In4.Cu")
		(net "M_J_CPU0_SA_DQ<11>")
	)
	(segment
		(start 418.13988 -208.810098)
		(end 418.980112 -209.65033)
		(width 0.14478)
		(layer "In4.Cu")
		(net "M_J_CPU0_SA_DQ<11>")
	)
	(segment
		(start 397.171164 -220.827346)
		(end 397.171164 -220.598746)
		(width 0.14478)
		(layer "In4.Cu")
		(net "M_J_CPU0_SA_DQ<11>")
	)
	(segment
		(start 398.112996 -219.656914)
		(end 398.341596 -219.656914)
		(width 0.14478)
		(layer "In4.Cu")
		(net "M_J_CPU0_SA_DQ<11>")
	)
	(segment
		(start 384.90779 -231.201722)
		(end 384.916172 -231.196896)
		(width 0.0889)
		(layer "In4.Cu")
		(net "M_J_CPU0_SA_DQ<11>")
	)
	(segment
		(start 397.970248 -220.617542)
		(end 398.131792 -220.455998)
		(width 0.14478)
		(layer "In4.Cu")
		(net "M_J_CPU0_SA_DQ<11>")
	)
	(segment
		(start 399.302224 -219.056966)
		(end 399.530824 -219.056966)
		(width 0.14478)
		(layer "In4.Cu")
		(net "M_J_CPU0_SA_DQ<11>")
	)
	(segment
		(start 397.028162 -221.559628)
		(end 397.351504 -221.236286)
		(width 0.14478)
		(layer "In4.Cu")
		(net "M_J_CPU0_SA_DQ<11>")
	)
	(segment
		(start 379.454918 -231.524048)
		(end 379.30074 -231.258618)
		(width 0.0889)
		(layer "In4.Cu")
		(net "M_J_CPU0_SA_DQ<11>")
	)
	(segment
		(start 398.750536 -219.837254)
		(end 398.91208 -219.67571)
		(width 0.14478)
		(layer "In4.Cu")
		(net "M_J_CPU0_SA_DQ<11>")
	)
	(segment
		(start 399.530824 -219.056966)
		(end 399.692368 -218.895422)
		(width 0.14478)
		(layer "In4.Cu")
		(net "M_J_CPU0_SA_DQ<11>")
	)
	(segment
		(start 408.927554 -209.660236)
		(end 414.005776 -209.660236)
		(width 0.14478)
		(layer "In4.Cu")
		(net "M_J_CPU0_SA_DQ<11>")
	)
	(segment
		(start 399.673572 -218.096338)
		(end 399.902172 -218.096338)
		(width 0.14478)
		(layer "In4.Cu")
		(net "M_J_CPU0_SA_DQ<11>")
	)
	(segment
		(start 400.292316 -217.706194)
		(end 400.292316 -217.477594)
		(width 0.14478)
		(layer "In4.Cu")
		(net "M_J_CPU0_SA_DQ<11>")
	)
	(segment
		(start 400.472656 -217.886534)
		(end 400.292316 -217.706194)
		(width 0.14478)
		(layer "In4.Cu")
		(net "M_J_CPU0_SA_DQ<11>")
	)
	(segment
		(start 398.131792 -220.455998)
		(end 398.131792 -220.227398)
		(width 0.14478)
		(layer "In4.Cu")
		(net "M_J_CPU0_SA_DQ<11>")
	)
	(segment
		(start 400.45386 -217.31605)
		(end 400.68246 -217.31605)
		(width 0.14478)
		(layer "In4.Cu")
		(net "M_J_CPU0_SA_DQ<11>")
	)
	(segment
		(start 392.7094 -229.80523)
		(end 392.905996 -229.80523)
		(width 0.0889)
		(layer "In4.Cu")
		(net "M_J_CPU0_SA_DQ<11>")
	)
	(segment
		(start 389.607806 -231.201722)
		(end 389.616188 -231.196896)
		(width 0.0889)
		(layer "In4.Cu")
		(net "M_J_CPU0_SA_DQ<11>")
	)
	(segment
		(start 397.561308 -220.437202)
		(end 397.741648 -220.617542)
		(width 0.14478)
		(layer "In4.Cu")
		(net "M_J_CPU0_SA_DQ<11>")
	)
	(segment
		(start 398.91208 -219.44711)
		(end 398.73174 -219.26677)
		(width 0.14478)
		(layer "In4.Cu")
		(net "M_J_CPU0_SA_DQ<11>")
	)
	(segment
		(start 429.915828 -208.800446)
		(end 434.565552 -208.800446)
		(width 0.14478)
		(layer "In4.Cu")
		(net "M_J_CPU0_SA_DQ<11>")
	)
	(segment
		(start 434.565552 -208.800446)
		(end 435.000146 -209.23504)
		(width 0.14478)
		(layer "In4.Cu")
		(net "M_J_CPU0_SA_DQ<11>")
	)
	(segment
		(start 399.512028 -218.257882)
		(end 399.673572 -218.096338)
		(width 0.14478)
		(layer "In4.Cu")
		(net "M_J_CPU0_SA_DQ<11>")
	)
	(segment
		(start 400.292316 -217.477594)
		(end 400.45386 -217.31605)
		(width 0.14478)
		(layer "In4.Cu")
		(net "M_J_CPU0_SA_DQ<11>")
	)
	(segment
		(start 399.121884 -218.876626)
		(end 399.302224 -219.056966)
		(width 0.14478)
		(layer "In4.Cu")
		(net "M_J_CPU0_SA_DQ<11>")
	)
	(segment
		(start 392.332718 -230.181912)
		(end 392.7094 -229.80523)
		(width 0.0889)
		(layer "In4.Cu")
		(net "M_J_CPU0_SA_DQ<11>")
	)
	(segment
		(start 398.521936 -219.837254)
		(end 398.750536 -219.837254)
		(width 0.14478)
		(layer "In4.Cu")
		(net "M_J_CPU0_SA_DQ<11>")
	)
	(segment
		(start 418.980112 -209.65033)
		(end 421.346376 -209.65033)
		(width 0.14478)
		(layer "In4.Cu")
		(net "M_J_CPU0_SA_DQ<11>")
	)
	(segment
		(start 398.73174 -219.03817)
		(end 398.893284 -218.876626)
		(width 0.14478)
		(layer "In4.Cu")
		(net "M_J_CPU0_SA_DQ<11>")
	)
	(arc
		(start 384.916172 -231.196896)
		(mid 385.09968 -231.151371)
		(end 385.281932 -231.201722)
		(width 0.0889)
		(layer "In4.Cu")
		(net "M_J_CPU0_SA_DQ<11>")
	)
	(arc
		(start 390.921748 -231.201722)
		(mid 391.204704 -231.277899)
		(end 391.48766 -231.201722)
		(width 0.0889)
		(layer "In4.Cu")
		(net "M_J_CPU0_SA_DQ<11>")
	)
	(arc
		(start 381.15621 -231.196896)
		(mid 381.339718 -231.151371)
		(end 381.52197 -231.201722)
		(width 0.0889)
		(layer "In4.Cu")
		(net "M_J_CPU0_SA_DQ<11>")
	)
	(arc
		(start 389.981948 -231.201722)
		(mid 390.264904 -231.277899)
		(end 390.54786 -231.201722)
		(width 0.0889)
		(layer "In4.Cu")
		(net "M_J_CPU0_SA_DQ<11>")
	)
	(arc
		(start 387.161786 -231.201722)
		(mid 387.444742 -231.277899)
		(end 387.727698 -231.201722)
		(width 0.0889)
		(layer "In4.Cu")
		(net "M_J_CPU0_SA_DQ<11>")
	)
	(arc
		(start 386.787898 -231.201722)
		(mid 386.974842 -231.151433)
		(end 387.161786 -231.201722)
		(width 0.0889)
		(layer "In4.Cu")
		(net "M_J_CPU0_SA_DQ<11>")
	)
	(arc
		(start 385.856226 -231.196896)
		(mid 386.039734 -231.151371)
		(end 386.221986 -231.201722)
		(width 0.0889)
		(layer "In4.Cu")
		(net "M_J_CPU0_SA_DQ<11>")
	)
	(arc
		(start 388.10184 -231.201722)
		(mid 388.384796 -231.277899)
		(end 388.667752 -231.201722)
		(width 0.0889)
		(layer "In4.Cu")
		(net "M_J_CPU0_SA_DQ<11>")
	)
	(arc
		(start 388.667752 -231.201722)
		(mid 388.850003 -231.151338)
		(end 389.033512 -231.196896)
		(width 0.0889)
		(layer "In4.Cu")
		(net "M_J_CPU0_SA_DQ<11>")
	)
	(arc
		(start 379.641862 -231.201722)
		(mid 379.924818 -231.277899)
		(end 380.207774 -231.201722)
		(width 0.0889)
		(layer "In4.Cu")
		(net "M_J_CPU0_SA_DQ<11>")
	)
	(arc
		(start 383.401824 -231.201722)
		(mid 383.68478 -231.277899)
		(end 383.967736 -231.201722)
		(width 0.0889)
		(layer "In4.Cu")
		(net "M_J_CPU0_SA_DQ<11>")
	)
	(arc
		(start 384.341878 -231.201722)
		(mid 384.624834 -231.277899)
		(end 384.90779 -231.201722)
		(width 0.0889)
		(layer "In4.Cu")
		(net "M_J_CPU0_SA_DQ<11>")
	)
	(arc
		(start 383.967736 -231.201722)
		(mid 384.149987 -231.151338)
		(end 384.333496 -231.196896)
		(width 0.0889)
		(layer "In4.Cu")
		(net "M_J_CPU0_SA_DQ<11>")
	)
	(arc
		(start 387.727698 -231.201722)
		(mid 387.909949 -231.151338)
		(end 388.093458 -231.196896)
		(width 0.0889)
		(layer "In4.Cu")
		(net "M_J_CPU0_SA_DQ<11>")
	)
	(arc
		(start 389.041894 -231.201722)
		(mid 389.32485 -231.277899)
		(end 389.607806 -231.201722)
		(width 0.0889)
		(layer "In4.Cu")
		(net "M_J_CPU0_SA_DQ<11>")
	)
	(arc
		(start 391.770108 -230.714296)
		(mid 391.811074 -230.54389)
		(end 391.925048 -230.410766)
		(width 0.0889)
		(layer "In4.Cu")
		(net "M_J_CPU0_SA_DQ<11>")
	)
	(arc
		(start 386.221986 -231.201722)
		(mid 386.504942 -231.277899)
		(end 386.787898 -231.201722)
		(width 0.0889)
		(layer "In4.Cu")
		(net "M_J_CPU0_SA_DQ<11>")
	)
	(arc
		(start 380.216156 -231.196896)
		(mid 380.399664 -231.151371)
		(end 380.581916 -231.201722)
		(width 0.0889)
		(layer "In4.Cu")
		(net "M_J_CPU0_SA_DQ<11>")
	)
	(arc
		(start 382.087882 -231.201722)
		(mid 382.274826 -231.151433)
		(end 382.46177 -231.201722)
		(width 0.0889)
		(layer "In4.Cu")
		(net "M_J_CPU0_SA_DQ<11>")
	)
	(arc
		(start 381.52197 -231.201722)
		(mid 381.804926 -231.277899)
		(end 382.087882 -231.201722)
		(width 0.0889)
		(layer "In4.Cu")
		(net "M_J_CPU0_SA_DQ<11>")
	)
	(arc
		(start 382.46177 -231.201722)
		(mid 382.744726 -231.277899)
		(end 383.027682 -231.201722)
		(width 0.0889)
		(layer "In4.Cu")
		(net "M_J_CPU0_SA_DQ<11>")
	)
	(arc
		(start 383.027682 -231.201722)
		(mid 383.209933 -231.151338)
		(end 383.393442 -231.196896)
		(width 0.0889)
		(layer "In4.Cu")
		(net "M_J_CPU0_SA_DQ<11>")
	)
	(arc
		(start 390.54786 -231.201722)
		(mid 390.734804 -231.151433)
		(end 390.921748 -231.201722)
		(width 0.0889)
		(layer "In4.Cu")
		(net "M_J_CPU0_SA_DQ<11>")
	)
	(arc
		(start 389.616188 -231.196896)
		(mid 389.799696 -231.151371)
		(end 389.981948 -231.201722)
		(width 0.0889)
		(layer "In4.Cu")
		(net "M_J_CPU0_SA_DQ<11>")
	)
	(arc
		(start 385.281932 -231.201722)
		(mid 385.564888 -231.277899)
		(end 385.847844 -231.201722)
		(width 0.0889)
		(layer "In4.Cu")
		(net "M_J_CPU0_SA_DQ<11>")
	)
	(arc
		(start 379.322838 -231.17556)
		(mid 379.480489 -231.152248)
		(end 379.63348 -231.196896)
		(width 0.0889)
		(layer "In4.Cu")
		(net "M_J_CPU0_SA_DQ<11>")
	)
	(arc
		(start 391.526776 -231.178862)
		(mid 391.705589 -230.976512)
		(end 391.770108 -230.714296)
		(width 0.0889)
		(layer "In4.Cu")
		(net "M_J_CPU0_SA_DQ<11>")
	)
	(arc
		(start 380.581916 -231.201722)
		(mid 380.864872 -231.277899)
		(end 381.147828 -231.201722)
		(width 0.0889)
		(layer "In4.Cu")
		(net "M_J_CPU0_SA_DQ<11>")
	)
	(segment
		(start 380.39802 -230.97998)
		(end 380.864872 -230.714296)
		(width 0.10668)
		(layer "F.Cu")
		(net "M_J_CPU0_SA_DQ<10>")
	)
	(segment
		(start 404.759922 -212.32114)
		(end 404.988522 -212.32114)
		(width 0.14478)
		(layer "In4.Cu")
		(net "M_J_CPU0_SA_DQ<10>")
	)
	(segment
		(start 405.150066 -212.159596)
		(end 405.150066 -211.930996)
		(width 0.14478)
		(layer "In4.Cu")
		(net "M_J_CPU0_SA_DQ<10>")
	)
	(segment
		(start 421.580818 -207.960214)
		(end 422.430956 -207.110076)
		(width 0.14478)
		(layer "In4.Cu")
		(net "M_J_CPU0_SA_DQ<10>")
	)
	(segment
		(start 400.45259 -216.045288)
		(end 400.68119 -216.045288)
		(width 0.14478)
		(layer "In4.Cu")
		(net "M_J_CPU0_SA_DQ<10>")
	)
	(segment
		(start 404.972774 -211.753704)
		(end 404.972774 -211.525104)
		(width 0.14478)
		(layer "In4.Cu")
		(net "M_J_CPU0_SA_DQ<10>")
	)
	(segment
		(start 392.522456 -228.773736)
		(end 392.522456 -228.57841)
		(width 0.0889)
		(layer "In4.Cu")
		(net "M_J_CPU0_SA_DQ<10>")
	)
	(segment
		(start 380.864872 -230.714296)
		(end 380.710694 -230.448866)
		(width 0.0889)
		(layer "In4.Cu")
		(net "M_J_CPU0_SA_DQ<10>")
	)
	(segment
		(start 401.232878 -215.265)
		(end 401.461478 -215.265)
		(width 0.14478)
		(layer "In4.Cu")
		(net "M_J_CPU0_SA_DQ<10>")
	)
	(segment
		(start 402.647658 -214.662004)
		(end 402.809202 -214.50046)
		(width 0.14478)
		(layer "In4.Cu")
		(net "M_J_CPU0_SA_DQ<10>")
	)
	(segment
		(start 429.003968 -207.960214)
		(end 429.854106 -207.110076)
		(width 0.14478)
		(layer "In4.Cu")
		(net "M_J_CPU0_SA_DQ<10>")
	)
	(segment
		(start 395.693138 -224.787206)
		(end 396.129002 -224.351342)
		(width 0.14478)
		(layer "In4.Cu")
		(net "M_J_CPU0_SA_DQ<10>")
	)
	(segment
		(start 404.35403 -212.143848)
		(end 404.58263 -212.143848)
		(width 0.14478)
		(layer "In4.Cu")
		(net "M_J_CPU0_SA_DQ<10>")
	)
	(segment
		(start 400.68119 -216.045288)
		(end 400.858482 -216.22258)
		(width 0.14478)
		(layer "In4.Cu")
		(net "M_J_CPU0_SA_DQ<10>")
	)
	(segment
		(start 400.858482 -216.22258)
		(end 401.087082 -216.22258)
		(width 0.14478)
		(layer "In4.Cu")
		(net "M_J_CPU0_SA_DQ<10>")
	)
	(segment
		(start 396.129002 -220.368876)
		(end 400.45259 -216.045288)
		(width 0.14478)
		(layer "In4.Cu")
		(net "M_J_CPU0_SA_DQ<10>")
	)
	(segment
		(start 434.575204 -207.110076)
		(end 435.000146 -207.535018)
		(width 0.14478)
		(layer "In4.Cu")
		(net "M_J_CPU0_SA_DQ<10>")
	)
	(segment
		(start 405.150066 -211.930996)
		(end 404.972774 -211.753704)
		(width 0.14478)
		(layer "In4.Cu")
		(net "M_J_CPU0_SA_DQ<10>")
	)
	(segment
		(start 417.882324 -207.110076)
		(end 418.732462 -207.960214)
		(width 0.14478)
		(layer "In4.Cu")
		(net "M_J_CPU0_SA_DQ<10>")
	)
	(segment
		(start 403.199346 -213.881716)
		(end 403.427946 -213.881716)
		(width 0.14478)
		(layer "In4.Cu")
		(net "M_J_CPU0_SA_DQ<10>")
	)
	(segment
		(start 402.028914 -215.052148)
		(end 401.851622 -214.874856)
		(width 0.14478)
		(layer "In4.Cu")
		(net "M_J_CPU0_SA_DQ<10>")
	)
	(segment
		(start 393.844018 -227.256848)
		(end 393.844018 -226.636326)
		(width 0.0889)
		(layer "In4.Cu")
		(net "M_J_CPU0_SA_DQ<10>")
	)
	(segment
		(start 401.86737 -215.442292)
		(end 402.028914 -215.280748)
		(width 0.14478)
		(layer "In4.Cu")
		(net "M_J_CPU0_SA_DQ<10>")
	)
	(segment
		(start 385.74345 -230.38689)
		(end 385.751832 -230.391716)
		(width 0.0889)
		(layer "In4.Cu")
		(net "M_J_CPU0_SA_DQ<10>")
	)
	(segment
		(start 404.192486 -212.305392)
		(end 404.35403 -212.143848)
		(width 0.14478)
		(layer "In4.Cu")
		(net "M_J_CPU0_SA_DQ<10>")
	)
	(segment
		(start 403.412198 -213.31428)
		(end 403.412198 -213.08568)
		(width 0.14478)
		(layer "In4.Cu")
		(net "M_J_CPU0_SA_DQ<10>")
	)
	(segment
		(start 403.802342 -212.924136)
		(end 403.979634 -213.101428)
		(width 0.14478)
		(layer "In4.Cu")
		(net "M_J_CPU0_SA_DQ<10>")
	)
	(segment
		(start 403.412198 -213.08568)
		(end 403.573742 -212.924136)
		(width 0.14478)
		(layer "In4.Cu")
		(net "M_J_CPU0_SA_DQ<10>")
	)
	(segment
		(start 391.01776 -230.391716)
		(end 391.054336 -230.37038)
		(width 0.0889)
		(layer "In4.Cu")
		(net "M_J_CPU0_SA_DQ<10>")
	)
	(segment
		(start 402.809202 -214.27186)
		(end 402.63191 -214.094568)
		(width 0.14478)
		(layer "In4.Cu")
		(net "M_J_CPU0_SA_DQ<10>")
	)
	(segment
		(start 405.134318 -211.36356)
		(end 405.362918 -211.36356)
		(width 0.14478)
		(layer "In4.Cu")
		(net "M_J_CPU0_SA_DQ<10>")
	)
	(segment
		(start 404.988522 -212.32114)
		(end 405.150066 -212.159596)
		(width 0.14478)
		(layer "In4.Cu")
		(net "M_J_CPU0_SA_DQ<10>")
	)
	(segment
		(start 403.58949 -213.720172)
		(end 403.58949 -213.491572)
		(width 0.14478)
		(layer "In4.Cu")
		(net "M_J_CPU0_SA_DQ<10>")
	)
	(segment
		(start 405.362918 -211.36356)
		(end 405.54021 -211.540852)
		(width 0.14478)
		(layer "In4.Cu")
		(net "M_J_CPU0_SA_DQ<10>")
	)
	(segment
		(start 404.192486 -212.533992)
		(end 404.192486 -212.305392)
		(width 0.14478)
		(layer "In4.Cu")
		(net "M_J_CPU0_SA_DQ<10>")
	)
	(segment
		(start 382.557782 -230.391716)
		(end 382.566164 -230.38689)
		(width 0.0889)
		(layer "In4.Cu")
		(net "M_J_CPU0_SA_DQ<10>")
	)
	(segment
		(start 422.430956 -207.110076)
		(end 425.75226 -207.110076)
		(width 0.14478)
		(layer "In4.Cu")
		(net "M_J_CPU0_SA_DQ<10>")
	)
	(segment
		(start 401.071334 -215.426544)
		(end 401.232878 -215.265)
		(width 0.14478)
		(layer "In4.Cu")
		(net "M_J_CPU0_SA_DQ<10>")
	)
	(segment
		(start 409.349448 -207.960214)
		(end 414.239456 -207.960214)
		(width 0.14478)
		(layer "In4.Cu")
		(net "M_J_CPU0_SA_DQ<10>")
	)
	(segment
		(start 404.58263 -212.143848)
		(end 404.759922 -212.32114)
		(width 0.14478)
		(layer "In4.Cu")
		(net "M_J_CPU0_SA_DQ<10>")
	)
	(segment
		(start 401.461478 -215.265)
		(end 401.63877 -215.442292)
		(width 0.14478)
		(layer "In4.Cu")
		(net "M_J_CPU0_SA_DQ<10>")
	)
	(segment
		(start 390.443466 -230.38689)
		(end 390.451848 -230.391716)
		(width 0.0889)
		(layer "In4.Cu")
		(net "M_J_CPU0_SA_DQ<10>")
	)
	(segment
		(start 391.674858 -229.531418)
		(end 391.764774 -229.531418)
		(width 0.0889)
		(layer "In4.Cu")
		(net "M_J_CPU0_SA_DQ<10>")
	)
	(segment
		(start 403.573742 -212.924136)
		(end 403.802342 -212.924136)
		(width 0.14478)
		(layer "In4.Cu")
		(net "M_J_CPU0_SA_DQ<10>")
	)
	(segment
		(start 425.75226 -207.110076)
		(end 426.602398 -207.960214)
		(width 0.14478)
		(layer "In4.Cu")
		(net "M_J_CPU0_SA_DQ<10>")
	)
	(segment
		(start 404.369778 -212.939884)
		(end 404.369778 -212.711284)
		(width 0.14478)
		(layer "In4.Cu")
		(net "M_J_CPU0_SA_DQ<10>")
	)
	(segment
		(start 391.764774 -229.531418)
		(end 392.522456 -228.773736)
		(width 0.0889)
		(layer "In4.Cu")
		(net "M_J_CPU0_SA_DQ<10>")
	)
	(segment
		(start 401.248626 -216.061036)
		(end 401.248626 -215.832436)
		(width 0.14478)
		(layer "In4.Cu")
		(net "M_J_CPU0_SA_DQ<10>")
	)
	(segment
		(start 386.683504 -230.38689)
		(end 386.691886 -230.391716)
		(width 0.0889)
		(layer "In4.Cu")
		(net "M_J_CPU0_SA_DQ<10>")
	)
	(segment
		(start 403.58949 -213.491572)
		(end 403.412198 -213.31428)
		(width 0.14478)
		(layer "In4.Cu")
		(net "M_J_CPU0_SA_DQ<10>")
	)
	(segment
		(start 401.071334 -215.655144)
		(end 401.071334 -215.426544)
		(width 0.14478)
		(layer "In4.Cu")
		(net "M_J_CPU0_SA_DQ<10>")
	)
	(segment
		(start 402.013166 -214.484712)
		(end 402.241766 -214.484712)
		(width 0.14478)
		(layer "In4.Cu")
		(net "M_J_CPU0_SA_DQ<10>")
	)
	(segment
		(start 388.197852 -230.391716)
		(end 388.206234 -230.38689)
		(width 0.0889)
		(layer "In4.Cu")
		(net "M_J_CPU0_SA_DQ<10>")
	)
	(segment
		(start 405.76881 -211.540852)
		(end 409.349448 -207.960214)
		(width 0.14478)
		(layer "In4.Cu")
		(net "M_J_CPU0_SA_DQ<10>")
	)
	(segment
		(start 392.522456 -228.57841)
		(end 393.844018 -227.256848)
		(width 0.0889)
		(layer "In4.Cu")
		(net "M_J_CPU0_SA_DQ<10>")
	)
	(segment
		(start 396.129002 -224.351342)
		(end 396.129002 -220.368876)
		(width 0.14478)
		(layer "In4.Cu")
		(net "M_J_CPU0_SA_DQ<10>")
	)
	(segment
		(start 383.497836 -230.391716)
		(end 383.506218 -230.38689)
		(width 0.0889)
		(layer "In4.Cu")
		(net "M_J_CPU0_SA_DQ<10>")
	)
	(segment
		(start 404.369778 -212.711284)
		(end 404.192486 -212.533992)
		(width 0.14478)
		(layer "In4.Cu")
		(net "M_J_CPU0_SA_DQ<10>")
	)
	(segment
		(start 402.793454 -213.704424)
		(end 403.022054 -213.704424)
		(width 0.14478)
		(layer "In4.Cu")
		(net "M_J_CPU0_SA_DQ<10>")
	)
	(segment
		(start 401.63877 -215.442292)
		(end 401.86737 -215.442292)
		(width 0.14478)
		(layer "In4.Cu")
		(net "M_J_CPU0_SA_DQ<10>")
	)
	(segment
		(start 401.087082 -216.22258)
		(end 401.248626 -216.061036)
		(width 0.14478)
		(layer "In4.Cu")
		(net "M_J_CPU0_SA_DQ<10>")
	)
	(segment
		(start 415.089594 -207.110076)
		(end 417.882324 -207.110076)
		(width 0.14478)
		(layer "In4.Cu")
		(net "M_J_CPU0_SA_DQ<10>")
	)
	(segment
		(start 401.851622 -214.646256)
		(end 402.013166 -214.484712)
		(width 0.14478)
		(layer "In4.Cu")
		(net "M_J_CPU0_SA_DQ<10>")
	)
	(segment
		(start 404.208234 -213.101428)
		(end 404.369778 -212.939884)
		(width 0.14478)
		(layer "In4.Cu")
		(net "M_J_CPU0_SA_DQ<10>")
	)
	(segment
		(start 401.851622 -214.874856)
		(end 401.851622 -214.646256)
		(width 0.14478)
		(layer "In4.Cu")
		(net "M_J_CPU0_SA_DQ<10>")
	)
	(segment
		(start 391.455148 -229.600506)
		(end 391.48766 -229.58171)
		(width 0.0889)
		(layer "In4.Cu")
		(net "M_J_CPU0_SA_DQ<10>")
	)
	(segment
		(start 403.427946 -213.881716)
		(end 403.58949 -213.720172)
		(width 0.14478)
		(layer "In4.Cu")
		(net "M_J_CPU0_SA_DQ<10>")
	)
	(segment
		(start 405.54021 -211.540852)
		(end 405.76881 -211.540852)
		(width 0.14478)
		(layer "In4.Cu")
		(net "M_J_CPU0_SA_DQ<10>")
	)
	(segment
		(start 402.63191 -213.865968)
		(end 402.793454 -213.704424)
		(width 0.14478)
		(layer "In4.Cu")
		(net "M_J_CPU0_SA_DQ<10>")
	)
	(segment
		(start 404.972774 -211.525104)
		(end 405.134318 -211.36356)
		(width 0.14478)
		(layer "In4.Cu")
		(net "M_J_CPU0_SA_DQ<10>")
	)
	(segment
		(start 401.248626 -215.832436)
		(end 401.071334 -215.655144)
		(width 0.14478)
		(layer "In4.Cu")
		(net "M_J_CPU0_SA_DQ<10>")
	)
	(segment
		(start 429.854106 -207.110076)
		(end 434.575204 -207.110076)
		(width 0.14478)
		(layer "In4.Cu")
		(net "M_J_CPU0_SA_DQ<10>")
	)
	(segment
		(start 387.257798 -230.391716)
		(end 387.26618 -230.38689)
		(width 0.0889)
		(layer "In4.Cu")
		(net "M_J_CPU0_SA_DQ<10>")
	)
	(segment
		(start 403.979634 -213.101428)
		(end 404.208234 -213.101428)
		(width 0.14478)
		(layer "In4.Cu")
		(net "M_J_CPU0_SA_DQ<10>")
	)
	(segment
		(start 380.710694 -230.448866)
		(end 380.733046 -230.365554)
		(width 0.0889)
		(layer "In4.Cu")
		(net "M_J_CPU0_SA_DQ<10>")
	)
	(segment
		(start 403.022054 -213.704424)
		(end 403.199346 -213.881716)
		(width 0.14478)
		(layer "In4.Cu")
		(net "M_J_CPU0_SA_DQ<10>")
	)
	(segment
		(start 418.732462 -207.960214)
		(end 421.580818 -207.960214)
		(width 0.14478)
		(layer "In4.Cu")
		(net "M_J_CPU0_SA_DQ<10>")
	)
	(segment
		(start 402.419058 -214.662004)
		(end 402.647658 -214.662004)
		(width 0.14478)
		(layer "In4.Cu")
		(net "M_J_CPU0_SA_DQ<10>")
	)
	(segment
		(start 426.602398 -207.960214)
		(end 429.003968 -207.960214)
		(width 0.14478)
		(layer "In4.Cu")
		(net "M_J_CPU0_SA_DQ<10>")
	)
	(segment
		(start 381.043434 -230.38689)
		(end 381.051816 -230.391716)
		(width 0.0889)
		(layer "In4.Cu")
		(net "M_J_CPU0_SA_DQ<10>")
	)
	(segment
		(start 393.844018 -226.636326)
		(end 395.693138 -224.787206)
		(width 0.0889)
		(layer "In4.Cu")
		(net "M_J_CPU0_SA_DQ<10>")
	)
	(segment
		(start 402.241766 -214.484712)
		(end 402.419058 -214.662004)
		(width 0.14478)
		(layer "In4.Cu")
		(net "M_J_CPU0_SA_DQ<10>")
	)
	(segment
		(start 402.63191 -214.094568)
		(end 402.63191 -213.865968)
		(width 0.14478)
		(layer "In4.Cu")
		(net "M_J_CPU0_SA_DQ<10>")
	)
	(segment
		(start 414.239456 -207.960214)
		(end 415.089594 -207.110076)
		(width 0.14478)
		(layer "In4.Cu")
		(net "M_J_CPU0_SA_DQ<10>")
	)
	(segment
		(start 381.983488 -230.38689)
		(end 381.99187 -230.391716)
		(width 0.0889)
		(layer "In4.Cu")
		(net "M_J_CPU0_SA_DQ<10>")
	)
	(segment
		(start 402.809202 -214.50046)
		(end 402.809202 -214.27186)
		(width 0.14478)
		(layer "In4.Cu")
		(net "M_J_CPU0_SA_DQ<10>")
	)
	(segment
		(start 402.028914 -215.280748)
		(end 402.028914 -215.052148)
		(width 0.14478)
		(layer "In4.Cu")
		(net "M_J_CPU0_SA_DQ<10>")
	)
	(arc
		(start 391.48766 -229.58171)
		(mid 391.577932 -229.54418)
		(end 391.674858 -229.531418)
		(width 0.0889)
		(layer "In4.Cu")
		(net "M_J_CPU0_SA_DQ<10>")
	)
	(arc
		(start 390.451848 -230.391716)
		(mid 390.734804 -230.467859)
		(end 391.01776 -230.391716)
		(width 0.0889)
		(layer "In4.Cu")
		(net "M_J_CPU0_SA_DQ<10>")
	)
	(arc
		(start 388.571994 -230.391716)
		(mid 388.85495 -230.467859)
		(end 389.137906 -230.391716)
		(width 0.0889)
		(layer "In4.Cu")
		(net "M_J_CPU0_SA_DQ<10>")
	)
	(arc
		(start 391.300208 -229.904036)
		(mid 391.341174 -229.73363)
		(end 391.455148 -229.600506)
		(width 0.0889)
		(layer "In4.Cu")
		(net "M_J_CPU0_SA_DQ<10>")
	)
	(arc
		(start 381.617728 -230.391716)
		(mid 381.799979 -230.341366)
		(end 381.983488 -230.38689)
		(width 0.0889)
		(layer "In4.Cu")
		(net "M_J_CPU0_SA_DQ<10>")
	)
	(arc
		(start 385.37769 -230.391716)
		(mid 385.559941 -230.341366)
		(end 385.74345 -230.38689)
		(width 0.0889)
		(layer "In4.Cu")
		(net "M_J_CPU0_SA_DQ<10>")
	)
	(arc
		(start 390.077706 -230.391716)
		(mid 390.259957 -230.341366)
		(end 390.443466 -230.38689)
		(width 0.0889)
		(layer "In4.Cu")
		(net "M_J_CPU0_SA_DQ<10>")
	)
	(arc
		(start 381.051816 -230.391716)
		(mid 381.334772 -230.467859)
		(end 381.617728 -230.391716)
		(width 0.0889)
		(layer "In4.Cu")
		(net "M_J_CPU0_SA_DQ<10>")
	)
	(arc
		(start 381.99187 -230.391716)
		(mid 382.274826 -230.467859)
		(end 382.557782 -230.391716)
		(width 0.0889)
		(layer "In4.Cu")
		(net "M_J_CPU0_SA_DQ<10>")
	)
	(arc
		(start 386.317744 -230.391716)
		(mid 386.499995 -230.341366)
		(end 386.683504 -230.38689)
		(width 0.0889)
		(layer "In4.Cu")
		(net "M_J_CPU0_SA_DQ<10>")
	)
	(arc
		(start 384.811778 -230.391716)
		(mid 385.094734 -230.467859)
		(end 385.37769 -230.391716)
		(width 0.0889)
		(layer "In4.Cu")
		(net "M_J_CPU0_SA_DQ<10>")
	)
	(arc
		(start 388.206234 -230.38689)
		(mid 388.389742 -230.341396)
		(end 388.571994 -230.391716)
		(width 0.0889)
		(layer "In4.Cu")
		(net "M_J_CPU0_SA_DQ<10>")
	)
	(arc
		(start 387.63194 -230.391716)
		(mid 387.914896 -230.467859)
		(end 388.197852 -230.391716)
		(width 0.0889)
		(layer "In4.Cu")
		(net "M_J_CPU0_SA_DQ<10>")
	)
	(arc
		(start 383.506218 -230.38689)
		(mid 383.689726 -230.341396)
		(end 383.871978 -230.391716)
		(width 0.0889)
		(layer "In4.Cu")
		(net "M_J_CPU0_SA_DQ<10>")
	)
	(arc
		(start 389.511794 -230.391716)
		(mid 389.79475 -230.467859)
		(end 390.077706 -230.391716)
		(width 0.0889)
		(layer "In4.Cu")
		(net "M_J_CPU0_SA_DQ<10>")
	)
	(arc
		(start 389.137906 -230.391716)
		(mid 389.32485 -230.341461)
		(end 389.511794 -230.391716)
		(width 0.0889)
		(layer "In4.Cu")
		(net "M_J_CPU0_SA_DQ<10>")
	)
	(arc
		(start 387.26618 -230.38689)
		(mid 387.449688 -230.341396)
		(end 387.63194 -230.391716)
		(width 0.0889)
		(layer "In4.Cu")
		(net "M_J_CPU0_SA_DQ<10>")
	)
	(arc
		(start 384.43789 -230.391716)
		(mid 384.624834 -230.341461)
		(end 384.811778 -230.391716)
		(width 0.0889)
		(layer "In4.Cu")
		(net "M_J_CPU0_SA_DQ<10>")
	)
	(arc
		(start 380.733046 -230.365554)
		(mid 380.890556 -230.342356)
		(end 381.043434 -230.38689)
		(width 0.0889)
		(layer "In4.Cu")
		(net "M_J_CPU0_SA_DQ<10>")
	)
	(arc
		(start 385.751832 -230.391716)
		(mid 386.034788 -230.467859)
		(end 386.317744 -230.391716)
		(width 0.0889)
		(layer "In4.Cu")
		(net "M_J_CPU0_SA_DQ<10>")
	)
	(arc
		(start 382.566164 -230.38689)
		(mid 382.749672 -230.341396)
		(end 382.931924 -230.391716)
		(width 0.0889)
		(layer "In4.Cu")
		(net "M_J_CPU0_SA_DQ<10>")
	)
	(arc
		(start 382.931924 -230.391716)
		(mid 383.21488 -230.467859)
		(end 383.497836 -230.391716)
		(width 0.0889)
		(layer "In4.Cu")
		(net "M_J_CPU0_SA_DQ<10>")
	)
	(arc
		(start 391.054336 -230.37038)
		(mid 391.234988 -230.167635)
		(end 391.300208 -229.904036)
		(width 0.0889)
		(layer "In4.Cu")
		(net "M_J_CPU0_SA_DQ<10>")
	)
	(arc
		(start 386.691886 -230.391716)
		(mid 386.974842 -230.467859)
		(end 387.257798 -230.391716)
		(width 0.0889)
		(layer "In4.Cu")
		(net "M_J_CPU0_SA_DQ<10>")
	)
	(arc
		(start 383.871978 -230.391716)
		(mid 384.154934 -230.467859)
		(end 384.43789 -230.391716)
		(width 0.0889)
		(layer "In4.Cu")
		(net "M_J_CPU0_SA_DQ<10>")
	)
	(segment
		(start 379.927866 -225.310192)
		(end 380.394718 -225.044254)
		(width 0.10668)
		(layer "F.Cu")
		(net "M_J_CPU0_SA_DQ<0>")
	)
	(segment
		(start 389.69315 -221.380812)
		(end 389.69315 -217.49512)
		(width 0.14478)
		(layer "In4.Cu")
		(net "M_J_CPU0_SA_DQ<0>")
	)
	(segment
		(start 436.426864 -197.071742)
		(end 436.588408 -196.910198)
		(width 0.14478)
		(layer "In4.Cu")
		(net "M_J_CPU0_SA_DQ<0>")
	)
	(segment
		(start 384.90779 -225.366834)
		(end 384.916172 -225.37166)
		(width 0.0889)
		(layer "In4.Cu")
		(net "M_J_CPU0_SA_DQ<0>")
	)
	(segment
		(start 435.87543 -197.071742)
		(end 435.87543 -197.335648)
		(width 0.14478)
		(layer "In4.Cu")
		(net "M_J_CPU0_SA_DQ<0>")
	)
	(segment
		(start 389.474456 -222.95866)
		(end 389.512048 -222.936816)
		(width 0.0889)
		(layer "In4.Cu")
		(net "M_J_CPU0_SA_DQ<0>")
	)
	(segment
		(start 389.699754 -222.614236)
		(end 389.69315 -222.607632)
		(width 0.0889)
		(layer "In4.Cu")
		(net "M_J_CPU0_SA_DQ<0>")
	)
	(segment
		(start 380.394718 -225.044254)
		(end 380.548896 -225.309684)
		(width 0.0889)
		(layer "In4.Cu")
		(net "M_J_CPU0_SA_DQ<0>")
	)
	(segment
		(start 436.588408 -196.910198)
		(end 436.96382 -196.910198)
		(width 0.14478)
		(layer "In4.Cu")
		(net "M_J_CPU0_SA_DQ<0>")
	)
	(segment
		(start 436.26532 -197.497192)
		(end 436.426864 -197.335648)
		(width 0.14478)
		(layer "In4.Cu")
		(net "M_J_CPU0_SA_DQ<0>")
	)
	(segment
		(start 384.333496 -225.37166)
		(end 384.341878 -225.366834)
		(width 0.0889)
		(layer "In4.Cu")
		(net "M_J_CPU0_SA_DQ<0>")
	)
	(segment
		(start 401.856194 -204.041248)
		(end 408.13736 -197.760082)
		(width 0.14478)
		(layer "In4.Cu")
		(net "M_J_CPU0_SA_DQ<0>")
	)
	(segment
		(start 383.393442 -225.37166)
		(end 383.401824 -225.366834)
		(width 0.0889)
		(layer "In4.Cu")
		(net "M_J_CPU0_SA_DQ<0>")
	)
	(segment
		(start 427.372526 -197.760082)
		(end 428.620428 -197.760082)
		(width 0.14478)
		(layer "In4.Cu")
		(net "M_J_CPU0_SA_DQ<0>")
	)
	(segment
		(start 413.302196 -197.760082)
		(end 415.354008 -196.910198)
		(width 0.14478)
		(layer "In4.Cu")
		(net "M_J_CPU0_SA_DQ<0>")
	)
	(segment
		(start 408.13736 -197.760082)
		(end 413.302196 -197.760082)
		(width 0.14478)
		(layer "In4.Cu")
		(net "M_J_CPU0_SA_DQ<0>")
	)
	(segment
		(start 388.10184 -225.366834)
		(end 388.13359 -225.348546)
		(width 0.0889)
		(layer "In4.Cu")
		(net "M_J_CPU0_SA_DQ<0>")
	)
	(segment
		(start 435.713886 -196.910198)
		(end 435.87543 -197.071742)
		(width 0.14478)
		(layer "In4.Cu")
		(net "M_J_CPU0_SA_DQ<0>")
	)
	(segment
		(start 420.701724 -197.760082)
		(end 422.753536 -196.910198)
		(width 0.14478)
		(layer "In4.Cu")
		(net "M_J_CPU0_SA_DQ<0>")
	)
	(segment
		(start 415.354008 -196.910198)
		(end 417.695126 -196.910198)
		(width 0.14478)
		(layer "In4.Cu")
		(net "M_J_CPU0_SA_DQ<0>")
	)
	(segment
		(start 389.004302 -223.768666)
		(end 389.042148 -223.746822)
		(width 0.0889)
		(layer "In4.Cu")
		(net "M_J_CPU0_SA_DQ<0>")
	)
	(segment
		(start 389.69315 -222.607632)
		(end 389.69315 -221.380812)
		(width 0.0889)
		(layer "In4.Cu")
		(net "M_J_CPU0_SA_DQ<0>")
	)
	(segment
		(start 388.532878 -224.579688)
		(end 388.571994 -224.556828)
		(width 0.0889)
		(layer "In4.Cu")
		(net "M_J_CPU0_SA_DQ<0>")
	)
	(segment
		(start 419.746938 -197.760082)
		(end 420.701724 -197.760082)
		(width 0.14478)
		(layer "In4.Cu")
		(net "M_J_CPU0_SA_DQ<0>")
	)
	(segment
		(start 436.96382 -196.910198)
		(end 439.100214 -197.33514)
		(width 0.14478)
		(layer "In4.Cu")
		(net "M_J_CPU0_SA_DQ<0>")
	)
	(segment
		(start 436.426864 -197.335648)
		(end 436.426864 -197.071742)
		(width 0.14478)
		(layer "In4.Cu")
		(net "M_J_CPU0_SA_DQ<0>")
	)
	(segment
		(start 422.753536 -196.910198)
		(end 425.320714 -196.910198)
		(width 0.14478)
		(layer "In4.Cu")
		(net "M_J_CPU0_SA_DQ<0>")
	)
	(segment
		(start 380.548896 -225.309684)
		(end 380.645162 -225.335084)
		(width 0.0889)
		(layer "In4.Cu")
		(net "M_J_CPU0_SA_DQ<0>")
	)
	(segment
		(start 430.672494 -196.910198)
		(end 435.713886 -196.910198)
		(width 0.14478)
		(layer "In4.Cu")
		(net "M_J_CPU0_SA_DQ<0>")
	)
	(segment
		(start 425.320714 -196.910198)
		(end 427.372526 -197.760082)
		(width 0.14478)
		(layer "In4.Cu")
		(net "M_J_CPU0_SA_DQ<0>")
	)
	(segment
		(start 417.695126 -196.910198)
		(end 419.746938 -197.760082)
		(width 0.14478)
		(layer "In4.Cu")
		(net "M_J_CPU0_SA_DQ<0>")
	)
	(segment
		(start 435.87543 -197.335648)
		(end 436.036974 -197.497192)
		(width 0.14478)
		(layer "In4.Cu")
		(net "M_J_CPU0_SA_DQ<0>")
	)
	(segment
		(start 389.512048 -222.936816)
		(end 389.544814 -222.917766)
		(width 0.0889)
		(layer "In4.Cu")
		(net "M_J_CPU0_SA_DQ<0>")
	)
	(segment
		(start 436.036974 -197.497192)
		(end 436.26532 -197.497192)
		(width 0.14478)
		(layer "In4.Cu")
		(net "M_J_CPU0_SA_DQ<0>")
	)
	(segment
		(start 388.571994 -224.556828)
		(end 388.603744 -224.53854)
		(width 0.0889)
		(layer "In4.Cu")
		(net "M_J_CPU0_SA_DQ<0>")
	)
	(segment
		(start 388.093458 -225.37166)
		(end 388.10184 -225.366834)
		(width 0.0889)
		(layer "In4.Cu")
		(net "M_J_CPU0_SA_DQ<0>")
	)
	(segment
		(start 401.856194 -205.332076)
		(end 401.856194 -204.041248)
		(width 0.14478)
		(layer "In4.Cu")
		(net "M_J_CPU0_SA_DQ<0>")
	)
	(segment
		(start 381.147828 -225.366834)
		(end 381.15621 -225.37166)
		(width 0.0889)
		(layer "In4.Cu")
		(net "M_J_CPU0_SA_DQ<0>")
	)
	(segment
		(start 385.847844 -225.366834)
		(end 385.856226 -225.37166)
		(width 0.0889)
		(layer "In4.Cu")
		(net "M_J_CPU0_SA_DQ<0>")
	)
	(segment
		(start 389.69315 -217.49512)
		(end 401.856194 -205.332076)
		(width 0.14478)
		(layer "In4.Cu")
		(net "M_J_CPU0_SA_DQ<0>")
	)
	(segment
		(start 428.620428 -197.760082)
		(end 430.672494 -196.910198)
		(width 0.14478)
		(layer "In4.Cu")
		(net "M_J_CPU0_SA_DQ<0>")
	)
	(segment
		(start 389.042148 -223.746822)
		(end 389.073898 -223.728534)
		(width 0.0889)
		(layer "In4.Cu")
		(net "M_J_CPU0_SA_DQ<0>")
	)
	(arc
		(start 386.221986 -225.366834)
		(mid 386.504942 -225.290657)
		(end 386.787898 -225.366834)
		(width 0.0889)
		(layer "In4.Cu")
		(net "M_J_CPU0_SA_DQ<0>")
	)
	(arc
		(start 385.856226 -225.37166)
		(mid 386.039734 -225.417154)
		(end 386.221986 -225.366834)
		(width 0.0889)
		(layer "In4.Cu")
		(net "M_J_CPU0_SA_DQ<0>")
	)
	(arc
		(start 389.073898 -223.728534)
		(mid 389.188574 -223.5952)
		(end 389.229854 -223.424242)
		(width 0.0889)
		(layer "In4.Cu")
		(net "M_J_CPU0_SA_DQ<0>")
	)
	(arc
		(start 383.967736 -225.366834)
		(mid 384.149987 -225.417184)
		(end 384.333496 -225.37166)
		(width 0.0889)
		(layer "In4.Cu")
		(net "M_J_CPU0_SA_DQ<0>")
	)
	(arc
		(start 388.603744 -224.53854)
		(mid 388.71842 -224.405206)
		(end 388.7597 -224.234248)
		(width 0.0889)
		(layer "In4.Cu")
		(net "M_J_CPU0_SA_DQ<0>")
	)
	(arc
		(start 387.161786 -225.366834)
		(mid 387.444742 -225.290657)
		(end 387.727698 -225.366834)
		(width 0.0889)
		(layer "In4.Cu")
		(net "M_J_CPU0_SA_DQ<0>")
	)
	(arc
		(start 382.46177 -225.366834)
		(mid 382.744726 -225.290657)
		(end 383.027682 -225.366834)
		(width 0.0889)
		(layer "In4.Cu")
		(net "M_J_CPU0_SA_DQ<0>")
	)
	(arc
		(start 388.13359 -225.348546)
		(mid 388.248266 -225.215212)
		(end 388.289546 -225.044254)
		(width 0.0889)
		(layer "In4.Cu")
		(net "M_J_CPU0_SA_DQ<0>")
	)
	(arc
		(start 388.7597 -224.234248)
		(mid 388.824572 -223.971285)
		(end 389.004302 -223.768666)
		(width 0.0889)
		(layer "In4.Cu")
		(net "M_J_CPU0_SA_DQ<0>")
	)
	(arc
		(start 389.544814 -222.917766)
		(mid 389.658743 -222.784619)
		(end 389.699754 -222.614236)
		(width 0.0889)
		(layer "In4.Cu")
		(net "M_J_CPU0_SA_DQ<0>")
	)
	(arc
		(start 389.229854 -223.424242)
		(mid 389.294726 -223.161279)
		(end 389.474456 -222.95866)
		(width 0.0889)
		(layer "In4.Cu")
		(net "M_J_CPU0_SA_DQ<0>")
	)
	(arc
		(start 381.52197 -225.366834)
		(mid 381.804926 -225.290657)
		(end 382.087882 -225.366834)
		(width 0.0889)
		(layer "In4.Cu")
		(net "M_J_CPU0_SA_DQ<0>")
	)
	(arc
		(start 385.281932 -225.366834)
		(mid 385.564888 -225.290657)
		(end 385.847844 -225.366834)
		(width 0.0889)
		(layer "In4.Cu")
		(net "M_J_CPU0_SA_DQ<0>")
	)
	(arc
		(start 383.401824 -225.366834)
		(mid 383.68478 -225.290657)
		(end 383.967736 -225.366834)
		(width 0.0889)
		(layer "In4.Cu")
		(net "M_J_CPU0_SA_DQ<0>")
	)
	(arc
		(start 382.087882 -225.366834)
		(mid 382.274826 -225.417089)
		(end 382.46177 -225.366834)
		(width 0.0889)
		(layer "In4.Cu")
		(net "M_J_CPU0_SA_DQ<0>")
	)
	(arc
		(start 380.645162 -225.335084)
		(mid 380.900227 -225.291733)
		(end 381.147828 -225.366834)
		(width 0.0889)
		(layer "In4.Cu")
		(net "M_J_CPU0_SA_DQ<0>")
	)
	(arc
		(start 387.727698 -225.366834)
		(mid 387.909949 -225.417184)
		(end 388.093458 -225.37166)
		(width 0.0889)
		(layer "In4.Cu")
		(net "M_J_CPU0_SA_DQ<0>")
	)
	(arc
		(start 384.341878 -225.366834)
		(mid 384.624834 -225.290657)
		(end 384.90779 -225.366834)
		(width 0.0889)
		(layer "In4.Cu")
		(net "M_J_CPU0_SA_DQ<0>")
	)
	(arc
		(start 388.289546 -225.044254)
		(mid 388.354061 -224.782035)
		(end 388.532878 -224.579688)
		(width 0.0889)
		(layer "In4.Cu")
		(net "M_J_CPU0_SA_DQ<0>")
	)
	(arc
		(start 386.787898 -225.366834)
		(mid 386.974842 -225.417089)
		(end 387.161786 -225.366834)
		(width 0.0889)
		(layer "In4.Cu")
		(net "M_J_CPU0_SA_DQ<0>")
	)
	(arc
		(start 384.916172 -225.37166)
		(mid 385.09968 -225.417154)
		(end 385.281932 -225.366834)
		(width 0.0889)
		(layer "In4.Cu")
		(net "M_J_CPU0_SA_DQ<0>")
	)
	(arc
		(start 381.15621 -225.37166)
		(mid 381.339718 -225.417154)
		(end 381.52197 -225.366834)
		(width 0.0889)
		(layer "In4.Cu")
		(net "M_J_CPU0_SA_DQ<0>")
	)
	(arc
		(start 383.027682 -225.366834)
		(mid 383.209933 -225.417184)
		(end 383.393442 -225.37166)
		(width 0.0889)
		(layer "In4.Cu")
		(net "M_J_CPU0_SA_DQ<0>")
	)
	(segment
		(start 378.517912 -252.040136)
		(end 378.984764 -251.774198)
		(width 0.10668)
		(layer "F.Cu")
		(net "M_J_CPU0_SA_CS_N<1>")
	)
	(segment
		(start 382.557782 -252.096778)
		(end 382.566164 -252.101604)
		(width 0.0889)
		(layer "In4.Cu")
		(net "M_J_CPU0_SA_CS_N<1>")
	)
	(segment
		(start 395.07668 -251.99721)
		(end 395.159738 -251.914152)
		(width 0.0889)
		(layer "In4.Cu")
		(net "M_J_CPU0_SA_CS_N<1>")
	)
	(segment
		(start 392.898122 -252.096524)
		(end 392.91641 -252.106938)
		(width 0.0889)
		(layer "In4.Cu")
		(net "M_J_CPU0_SA_CS_N<1>")
	)
	(segment
		(start 391.01776 -252.096778)
		(end 391.026142 -252.101604)
		(width 0.0889)
		(layer "In4.Cu")
		(net "M_J_CPU0_SA_CS_N<1>")
	)
	(segment
		(start 383.497836 -252.096778)
		(end 383.506218 -252.101604)
		(width 0.0889)
		(layer "In4.Cu")
		(net "M_J_CPU0_SA_CS_N<1>")
	)
	(segment
		(start 381.983488 -252.101604)
		(end 381.99187 -252.096778)
		(width 0.0889)
		(layer "In4.Cu")
		(net "M_J_CPU0_SA_CS_N<1>")
	)
	(segment
		(start 429.23333 -248.760234)
		(end 430.933352 -247.060212)
		(width 0.14478)
		(layer "In4.Cu")
		(net "M_J_CPU0_SA_CS_N<1>")
	)
	(segment
		(start 408.965908 -251.568712)
		(end 411.774386 -248.760234)
		(width 0.14478)
		(layer "In4.Cu")
		(net "M_J_CPU0_SA_CS_N<1>")
	)
	(segment
		(start 397.926814 -251.914152)
		(end 398.272254 -251.568712)
		(width 0.14478)
		(layer "In4.Cu")
		(net "M_J_CPU0_SA_CS_N<1>")
	)
	(segment
		(start 381.043434 -252.101604)
		(end 381.051816 -252.096778)
		(width 0.0889)
		(layer "In4.Cu")
		(net "M_J_CPU0_SA_CS_N<1>")
	)
	(segment
		(start 388.197852 -252.096778)
		(end 388.206234 -252.101604)
		(width 0.0889)
		(layer "In4.Cu")
		(net "M_J_CPU0_SA_CS_N<1>")
	)
	(segment
		(start 386.683504 -252.101604)
		(end 386.691886 -252.096778)
		(width 0.0889)
		(layer "In4.Cu")
		(net "M_J_CPU0_SA_CS_N<1>")
	)
	(segment
		(start 385.74345 -252.101604)
		(end 385.751832 -252.096778)
		(width 0.0889)
		(layer "In4.Cu")
		(net "M_J_CPU0_SA_CS_N<1>")
	)
	(segment
		(start 392.892534 -252.093222)
		(end 392.898122 -252.096524)
		(width 0.0889)
		(layer "In4.Cu")
		(net "M_J_CPU0_SA_CS_N<1>")
	)
	(segment
		(start 393.495784 -251.99721)
		(end 395.07668 -251.99721)
		(width 0.0889)
		(layer "In4.Cu")
		(net "M_J_CPU0_SA_CS_N<1>")
	)
	(segment
		(start 395.159738 -251.914152)
		(end 395.530578 -251.914152)
		(width 0.0889)
		(layer "In4.Cu")
		(net "M_J_CPU0_SA_CS_N<1>")
	)
	(segment
		(start 434.57495 -247.060212)
		(end 435.000146 -246.635016)
		(width 0.14478)
		(layer "In4.Cu")
		(net "M_J_CPU0_SA_CS_N<1>")
	)
	(segment
		(start 390.443466 -252.101604)
		(end 390.451848 -252.096778)
		(width 0.0889)
		(layer "In4.Cu")
		(net "M_J_CPU0_SA_CS_N<1>")
	)
	(segment
		(start 378.984764 -251.774198)
		(end 379.138942 -252.039628)
		(width 0.0889)
		(layer "In4.Cu")
		(net "M_J_CPU0_SA_CS_N<1>")
	)
	(segment
		(start 393.272264 -252.096778)
		(end 393.495784 -251.99721)
		(width 0.0889)
		(layer "In4.Cu")
		(net "M_J_CPU0_SA_CS_N<1>")
	)
	(segment
		(start 395.530578 -251.914152)
		(end 397.926814 -251.914152)
		(width 0.14478)
		(layer "In4.Cu")
		(net "M_J_CPU0_SA_CS_N<1>")
	)
	(segment
		(start 391.391902 -252.096778)
		(end 391.406634 -252.088142)
		(width 0.0889)
		(layer "In4.Cu")
		(net "M_J_CPU0_SA_CS_N<1>")
	)
	(segment
		(start 411.774386 -248.760234)
		(end 429.23333 -248.760234)
		(width 0.14478)
		(layer "In4.Cu")
		(net "M_J_CPU0_SA_CS_N<1>")
	)
	(segment
		(start 387.257798 -252.096778)
		(end 387.26618 -252.101604)
		(width 0.0889)
		(layer "In4.Cu")
		(net "M_J_CPU0_SA_CS_N<1>")
	)
	(segment
		(start 398.272254 -251.568712)
		(end 408.965908 -251.568712)
		(width 0.14478)
		(layer "In4.Cu")
		(net "M_J_CPU0_SA_CS_N<1>")
	)
	(segment
		(start 430.933352 -247.060212)
		(end 434.57495 -247.060212)
		(width 0.14478)
		(layer "In4.Cu")
		(net "M_J_CPU0_SA_CS_N<1>")
	)
	(segment
		(start 392.321034 -252.103636)
		(end 392.332718 -252.096778)
		(width 0.0889)
		(layer "In4.Cu")
		(net "M_J_CPU0_SA_CS_N<1>")
	)
	(segment
		(start 379.138942 -252.039628)
		(end 379.235208 -252.065028)
		(width 0.0889)
		(layer "In4.Cu")
		(net "M_J_CPU0_SA_CS_N<1>")
	)
	(arc
		(start 382.566164 -252.101604)
		(mid 382.749672 -252.147098)
		(end 382.931924 -252.096778)
		(width 0.0889)
		(layer "In4.Cu")
		(net "M_J_CPU0_SA_CS_N<1>")
	)
	(arc
		(start 390.077706 -252.096778)
		(mid 390.259957 -252.147128)
		(end 390.443466 -252.101604)
		(width 0.0889)
		(layer "In4.Cu")
		(net "M_J_CPU0_SA_CS_N<1>")
	)
	(arc
		(start 389.511794 -252.096778)
		(mid 389.79475 -252.020601)
		(end 390.077706 -252.096778)
		(width 0.0889)
		(layer "In4.Cu")
		(net "M_J_CPU0_SA_CS_N<1>")
	)
	(arc
		(start 385.37769 -252.096778)
		(mid 385.559941 -252.147128)
		(end 385.74345 -252.101604)
		(width 0.0889)
		(layer "In4.Cu")
		(net "M_J_CPU0_SA_CS_N<1>")
	)
	(arc
		(start 383.506218 -252.101604)
		(mid 383.689726 -252.147098)
		(end 383.871978 -252.096778)
		(width 0.0889)
		(layer "In4.Cu")
		(net "M_J_CPU0_SA_CS_N<1>")
	)
	(arc
		(start 381.99187 -252.096778)
		(mid 382.274826 -252.020601)
		(end 382.557782 -252.096778)
		(width 0.0889)
		(layer "In4.Cu")
		(net "M_J_CPU0_SA_CS_N<1>")
	)
	(arc
		(start 384.811778 -252.096778)
		(mid 385.094734 -252.020601)
		(end 385.37769 -252.096778)
		(width 0.0889)
		(layer "In4.Cu")
		(net "M_J_CPU0_SA_CS_N<1>")
	)
	(arc
		(start 392.91641 -252.106938)
		(mid 393.095639 -252.147091)
		(end 393.272264 -252.096778)
		(width 0.0889)
		(layer "In4.Cu")
		(net "M_J_CPU0_SA_CS_N<1>")
	)
	(arc
		(start 383.871978 -252.096778)
		(mid 384.154934 -252.020601)
		(end 384.43789 -252.096778)
		(width 0.0889)
		(layer "In4.Cu")
		(net "M_J_CPU0_SA_CS_N<1>")
	)
	(arc
		(start 381.617728 -252.096778)
		(mid 381.799979 -252.147128)
		(end 381.983488 -252.101604)
		(width 0.0889)
		(layer "In4.Cu")
		(net "M_J_CPU0_SA_CS_N<1>")
	)
	(arc
		(start 391.958322 -252.096778)
		(mid 392.13878 -252.147222)
		(end 392.321034 -252.103636)
		(width 0.0889)
		(layer "In4.Cu")
		(net "M_J_CPU0_SA_CS_N<1>")
	)
	(arc
		(start 387.63194 -252.096778)
		(mid 387.914896 -252.020601)
		(end 388.197852 -252.096778)
		(width 0.0889)
		(layer "In4.Cu")
		(net "M_J_CPU0_SA_CS_N<1>")
	)
	(arc
		(start 385.751832 -252.096778)
		(mid 386.034788 -252.020601)
		(end 386.317744 -252.096778)
		(width 0.0889)
		(layer "In4.Cu")
		(net "M_J_CPU0_SA_CS_N<1>")
	)
	(arc
		(start 389.137906 -252.096778)
		(mid 389.32485 -252.147033)
		(end 389.511794 -252.096778)
		(width 0.0889)
		(layer "In4.Cu")
		(net "M_J_CPU0_SA_CS_N<1>")
	)
	(arc
		(start 379.235208 -252.065028)
		(mid 379.490273 -252.021677)
		(end 379.737874 -252.096778)
		(width 0.0889)
		(layer "In4.Cu")
		(net "M_J_CPU0_SA_CS_N<1>")
	)
	(arc
		(start 387.26618 -252.101604)
		(mid 387.449688 -252.147098)
		(end 387.63194 -252.096778)
		(width 0.0889)
		(layer "In4.Cu")
		(net "M_J_CPU0_SA_CS_N<1>")
	)
	(arc
		(start 379.737874 -252.096778)
		(mid 379.924818 -252.147033)
		(end 380.111762 -252.096778)
		(width 0.0889)
		(layer "In4.Cu")
		(net "M_J_CPU0_SA_CS_N<1>")
	)
	(arc
		(start 388.206234 -252.101604)
		(mid 388.389742 -252.147098)
		(end 388.571994 -252.096778)
		(width 0.0889)
		(layer "In4.Cu")
		(net "M_J_CPU0_SA_CS_N<1>")
	)
	(arc
		(start 380.111762 -252.096778)
		(mid 380.394718 -252.020601)
		(end 380.677674 -252.096778)
		(width 0.0889)
		(layer "In4.Cu")
		(net "M_J_CPU0_SA_CS_N<1>")
	)
	(arc
		(start 392.332718 -252.096778)
		(mid 392.612146 -252.020612)
		(end 392.892534 -252.093222)
		(width 0.0889)
		(layer "In4.Cu")
		(net "M_J_CPU0_SA_CS_N<1>")
	)
	(arc
		(start 380.677674 -252.096778)
		(mid 380.859925 -252.147128)
		(end 381.043434 -252.101604)
		(width 0.0889)
		(layer "In4.Cu")
		(net "M_J_CPU0_SA_CS_N<1>")
	)
	(arc
		(start 386.691886 -252.096778)
		(mid 386.974842 -252.020601)
		(end 387.257798 -252.096778)
		(width 0.0889)
		(layer "In4.Cu")
		(net "M_J_CPU0_SA_CS_N<1>")
	)
	(arc
		(start 386.317744 -252.096778)
		(mid 386.499995 -252.147128)
		(end 386.683504 -252.101604)
		(width 0.0889)
		(layer "In4.Cu")
		(net "M_J_CPU0_SA_CS_N<1>")
	)
	(arc
		(start 391.406634 -252.088142)
		(mid 391.683617 -252.020338)
		(end 391.958322 -252.096778)
		(width 0.0889)
		(layer "In4.Cu")
		(net "M_J_CPU0_SA_CS_N<1>")
	)
	(arc
		(start 381.051816 -252.096778)
		(mid 381.334772 -252.020601)
		(end 381.617728 -252.096778)
		(width 0.0889)
		(layer "In4.Cu")
		(net "M_J_CPU0_SA_CS_N<1>")
	)
	(arc
		(start 382.931924 -252.096778)
		(mid 383.21488 -252.020601)
		(end 383.497836 -252.096778)
		(width 0.0889)
		(layer "In4.Cu")
		(net "M_J_CPU0_SA_CS_N<1>")
	)
	(arc
		(start 390.451848 -252.096778)
		(mid 390.734804 -252.020601)
		(end 391.01776 -252.096778)
		(width 0.0889)
		(layer "In4.Cu")
		(net "M_J_CPU0_SA_CS_N<1>")
	)
	(arc
		(start 388.571994 -252.096778)
		(mid 388.85495 -252.020601)
		(end 389.137906 -252.096778)
		(width 0.0889)
		(layer "In4.Cu")
		(net "M_J_CPU0_SA_CS_N<1>")
	)
	(arc
		(start 391.026142 -252.101604)
		(mid 391.20965 -252.147098)
		(end 391.391902 -252.096778)
		(width 0.0889)
		(layer "In4.Cu")
		(net "M_J_CPU0_SA_CS_N<1>")
	)
	(arc
		(start 384.43789 -252.096778)
		(mid 384.624834 -252.147033)
		(end 384.811778 -252.096778)
		(width 0.0889)
		(layer "In4.Cu")
		(net "M_J_CPU0_SA_CS_N<1>")
	)
	(segment
		(start 379.927866 -251.23013)
		(end 380.394718 -250.964192)
		(width 0.10668)
		(layer "F.Cu")
		(net "M_J_CPU0_SA_CS_N<0>")
	)
	(segment
		(start 393.897358 -251.281184)
		(end 394.209524 -251.59335)
		(width 0.0889)
		(layer "In4.Cu")
		(net "M_J_CPU0_SA_CS_N<0>")
	)
	(segment
		(start 389.607806 -251.286772)
		(end 389.616188 -251.291598)
		(width 0.0889)
		(layer "In4.Cu")
		(net "M_J_CPU0_SA_CS_N<0>")
	)
	(segment
		(start 395.148816 -251.45365)
		(end 395.440916 -251.45365)
		(width 0.0889)
		(layer "In4.Cu")
		(net "M_J_CPU0_SA_CS_N<0>")
	)
	(segment
		(start 385.847844 -251.286772)
		(end 385.856226 -251.291598)
		(width 0.0889)
		(layer "In4.Cu")
		(net "M_J_CPU0_SA_CS_N<0>")
	)
	(segment
		(start 384.333496 -251.291598)
		(end 384.341878 -251.286772)
		(width 0.0889)
		(layer "In4.Cu")
		(net "M_J_CPU0_SA_CS_N<0>")
	)
	(segment
		(start 408.779218 -251.119132)
		(end 411.988254 -247.910096)
		(width 0.14478)
		(layer "In4.Cu")
		(net "M_J_CPU0_SA_CS_N<0>")
	)
	(segment
		(start 392.802364 -251.286518)
		(end 392.818112 -251.277374)
		(width 0.0889)
		(layer "In4.Cu")
		(net "M_J_CPU0_SA_CS_N<0>")
	)
	(segment
		(start 411.988254 -247.910096)
		(end 428.9679 -247.910096)
		(width 0.14478)
		(layer "In4.Cu")
		(net "M_J_CPU0_SA_CS_N<0>")
	)
	(segment
		(start 428.9679 -247.910096)
		(end 430.667922 -246.210074)
		(width 0.14478)
		(layer "In4.Cu")
		(net "M_J_CPU0_SA_CS_N<0>")
	)
	(segment
		(start 398.074134 -251.119132)
		(end 408.779218 -251.119132)
		(width 0.14478)
		(layer "In4.Cu")
		(net "M_J_CPU0_SA_CS_N<0>")
	)
	(segment
		(start 395.009116 -251.59335)
		(end 395.148816 -251.45365)
		(width 0.0889)
		(layer "In4.Cu")
		(net "M_J_CPU0_SA_CS_N<0>")
	)
	(segment
		(start 383.393442 -251.291598)
		(end 383.401824 -251.286772)
		(width 0.0889)
		(layer "In4.Cu")
		(net "M_J_CPU0_SA_CS_N<0>")
	)
	(segment
		(start 392.418062 -251.280676)
		(end 392.428476 -251.286772)
		(width 0.0889)
		(layer "In4.Cu")
		(net "M_J_CPU0_SA_CS_N<0>")
	)
	(segment
		(start 389.033512 -251.291598)
		(end 389.041894 -251.286772)
		(width 0.0889)
		(layer "In4.Cu")
		(net "M_J_CPU0_SA_CS_N<0>")
	)
	(segment
		(start 393.368276 -251.286772)
		(end 393.897358 -251.281184)
		(width 0.0889)
		(layer "In4.Cu")
		(net "M_J_CPU0_SA_CS_N<0>")
	)
	(segment
		(start 397.739616 -251.45365)
		(end 398.074134 -251.119132)
		(width 0.14478)
		(layer "In4.Cu")
		(net "M_J_CPU0_SA_CS_N<0>")
	)
	(segment
		(start 395.440916 -251.45365)
		(end 397.739616 -251.45365)
		(width 0.14478)
		(layer "In4.Cu")
		(net "M_J_CPU0_SA_CS_N<0>")
	)
	(segment
		(start 391.48766 -251.286772)
		(end 391.496042 -251.291598)
		(width 0.0889)
		(layer "In4.Cu")
		(net "M_J_CPU0_SA_CS_N<0>")
	)
	(segment
		(start 394.209524 -251.59335)
		(end 395.009116 -251.59335)
		(width 0.0889)
		(layer "In4.Cu")
		(net "M_J_CPU0_SA_CS_N<0>")
	)
	(segment
		(start 380.548896 -251.229622)
		(end 380.645162 -251.255022)
		(width 0.0889)
		(layer "In4.Cu")
		(net "M_J_CPU0_SA_CS_N<0>")
	)
	(segment
		(start 384.90779 -251.286772)
		(end 384.916172 -251.291598)
		(width 0.0889)
		(layer "In4.Cu")
		(net "M_J_CPU0_SA_CS_N<0>")
	)
	(segment
		(start 438.675272 -246.210074)
		(end 439.100214 -245.785132)
		(width 0.14478)
		(layer "In4.Cu")
		(net "M_J_CPU0_SA_CS_N<0>")
	)
	(segment
		(start 392.786108 -251.295916)
		(end 392.802364 -251.286518)
		(width 0.0889)
		(layer "In4.Cu")
		(net "M_J_CPU0_SA_CS_N<0>")
	)
	(segment
		(start 381.147828 -251.286772)
		(end 381.15621 -251.291598)
		(width 0.0889)
		(layer "In4.Cu")
		(net "M_J_CPU0_SA_CS_N<0>")
	)
	(segment
		(start 380.394718 -250.964192)
		(end 380.548896 -251.229622)
		(width 0.0889)
		(layer "In4.Cu")
		(net "M_J_CPU0_SA_CS_N<0>")
	)
	(segment
		(start 430.667922 -246.210074)
		(end 438.675272 -246.210074)
		(width 0.14478)
		(layer "In4.Cu")
		(net "M_J_CPU0_SA_CS_N<0>")
	)
	(segment
		(start 388.093458 -251.291598)
		(end 388.10184 -251.286772)
		(width 0.0889)
		(layer "In4.Cu")
		(net "M_J_CPU0_SA_CS_N<0>")
	)
	(arc
		(start 390.54786 -251.286772)
		(mid 390.734804 -251.337027)
		(end 390.921748 -251.286772)
		(width 0.0889)
		(layer "In4.Cu")
		(net "M_J_CPU0_SA_CS_N<0>")
	)
	(arc
		(start 392.428476 -251.286772)
		(mid 392.606126 -251.337032)
		(end 392.786108 -251.295916)
		(width 0.0889)
		(layer "In4.Cu")
		(net "M_J_CPU0_SA_CS_N<0>")
	)
	(arc
		(start 391.86231 -251.286772)
		(mid 392.139377 -251.210501)
		(end 392.418062 -251.280676)
		(width 0.0889)
		(layer "In4.Cu")
		(net "M_J_CPU0_SA_CS_N<0>")
	)
	(arc
		(start 391.496042 -251.291598)
		(mid 391.679804 -251.337214)
		(end 391.86231 -251.286772)
		(width 0.0889)
		(layer "In4.Cu")
		(net "M_J_CPU0_SA_CS_N<0>")
	)
	(arc
		(start 386.787898 -251.286772)
		(mid 386.974842 -251.337027)
		(end 387.161786 -251.286772)
		(width 0.0889)
		(layer "In4.Cu")
		(net "M_J_CPU0_SA_CS_N<0>")
	)
	(arc
		(start 384.916172 -251.291598)
		(mid 385.09968 -251.337092)
		(end 385.281932 -251.286772)
		(width 0.0889)
		(layer "In4.Cu")
		(net "M_J_CPU0_SA_CS_N<0>")
	)
	(arc
		(start 382.46177 -251.286772)
		(mid 382.744726 -251.210595)
		(end 383.027682 -251.286772)
		(width 0.0889)
		(layer "In4.Cu")
		(net "M_J_CPU0_SA_CS_N<0>")
	)
	(arc
		(start 385.856226 -251.291598)
		(mid 386.039734 -251.337092)
		(end 386.221986 -251.286772)
		(width 0.0889)
		(layer "In4.Cu")
		(net "M_J_CPU0_SA_CS_N<0>")
	)
	(arc
		(start 381.15621 -251.291598)
		(mid 381.339718 -251.337092)
		(end 381.52197 -251.286772)
		(width 0.0889)
		(layer "In4.Cu")
		(net "M_J_CPU0_SA_CS_N<0>")
	)
	(arc
		(start 383.401824 -251.286772)
		(mid 383.68478 -251.210595)
		(end 383.967736 -251.286772)
		(width 0.0889)
		(layer "In4.Cu")
		(net "M_J_CPU0_SA_CS_N<0>")
	)
	(arc
		(start 388.10184 -251.286772)
		(mid 388.384796 -251.210595)
		(end 388.667752 -251.286772)
		(width 0.0889)
		(layer "In4.Cu")
		(net "M_J_CPU0_SA_CS_N<0>")
	)
	(arc
		(start 392.818112 -251.277374)
		(mid 393.094421 -251.210398)
		(end 393.368276 -251.286772)
		(width 0.0889)
		(layer "In4.Cu")
		(net "M_J_CPU0_SA_CS_N<0>")
	)
	(arc
		(start 383.967736 -251.286772)
		(mid 384.149987 -251.337122)
		(end 384.333496 -251.291598)
		(width 0.0889)
		(layer "In4.Cu")
		(net "M_J_CPU0_SA_CS_N<0>")
	)
	(arc
		(start 381.52197 -251.286772)
		(mid 381.804926 -251.210595)
		(end 382.087882 -251.286772)
		(width 0.0889)
		(layer "In4.Cu")
		(net "M_J_CPU0_SA_CS_N<0>")
	)
	(arc
		(start 389.616188 -251.291598)
		(mid 389.799696 -251.337092)
		(end 389.981948 -251.286772)
		(width 0.0889)
		(layer "In4.Cu")
		(net "M_J_CPU0_SA_CS_N<0>")
	)
	(arc
		(start 386.221986 -251.286772)
		(mid 386.504942 -251.210595)
		(end 386.787898 -251.286772)
		(width 0.0889)
		(layer "In4.Cu")
		(net "M_J_CPU0_SA_CS_N<0>")
	)
	(arc
		(start 385.281932 -251.286772)
		(mid 385.564888 -251.210595)
		(end 385.847844 -251.286772)
		(width 0.0889)
		(layer "In4.Cu")
		(net "M_J_CPU0_SA_CS_N<0>")
	)
	(arc
		(start 390.921748 -251.286772)
		(mid 391.204704 -251.210595)
		(end 391.48766 -251.286772)
		(width 0.0889)
		(layer "In4.Cu")
		(net "M_J_CPU0_SA_CS_N<0>")
	)
	(arc
		(start 380.645162 -251.255022)
		(mid 380.900227 -251.211671)
		(end 381.147828 -251.286772)
		(width 0.0889)
		(layer "In4.Cu")
		(net "M_J_CPU0_SA_CS_N<0>")
	)
	(arc
		(start 389.981948 -251.286772)
		(mid 390.264904 -251.210595)
		(end 390.54786 -251.286772)
		(width 0.0889)
		(layer "In4.Cu")
		(net "M_J_CPU0_SA_CS_N<0>")
	)
	(arc
		(start 384.341878 -251.286772)
		(mid 384.624834 -251.210595)
		(end 384.90779 -251.286772)
		(width 0.0889)
		(layer "In4.Cu")
		(net "M_J_CPU0_SA_CS_N<0>")
	)
	(arc
		(start 388.667752 -251.286772)
		(mid 388.850003 -251.337122)
		(end 389.033512 -251.291598)
		(width 0.0889)
		(layer "In4.Cu")
		(net "M_J_CPU0_SA_CS_N<0>")
	)
	(arc
		(start 383.027682 -251.286772)
		(mid 383.209933 -251.337122)
		(end 383.393442 -251.291598)
		(width 0.0889)
		(layer "In4.Cu")
		(net "M_J_CPU0_SA_CS_N<0>")
	)
	(arc
		(start 387.161786 -251.286772)
		(mid 387.444742 -251.210595)
		(end 387.727698 -251.286772)
		(width 0.0889)
		(layer "In4.Cu")
		(net "M_J_CPU0_SA_CS_N<0>")
	)
	(arc
		(start 382.087882 -251.286772)
		(mid 382.274826 -251.337027)
		(end 382.46177 -251.286772)
		(width 0.0889)
		(layer "In4.Cu")
		(net "M_J_CPU0_SA_CS_N<0>")
	)
	(arc
		(start 389.041894 -251.286772)
		(mid 389.32485 -251.210595)
		(end 389.607806 -251.286772)
		(width 0.0889)
		(layer "In4.Cu")
		(net "M_J_CPU0_SA_CS_N<0>")
	)
	(arc
		(start 387.727698 -251.286772)
		(mid 387.909949 -251.337122)
		(end 388.093458 -251.291598)
		(width 0.0889)
		(layer "In4.Cu")
		(net "M_J_CPU0_SA_CS_N<0>")
	)
	(segment
		(start 378.988066 -249.610118)
		(end 379.454918 -249.34418)
		(width 0.10668)
		(layer "F.Cu")
		(net "M_J_CPU0_SA_CB<7>")
	)
	(segment
		(start 407.762456 -249.216672)
		(end 407.990548 -249.216672)
		(width 0.14478)
		(layer "In4.Cu")
		(net "M_J_CPU0_SA_CB<7>")
	)
	(segment
		(start 408.98572 -246.661432)
		(end 409.213812 -246.661432)
		(width 0.14478)
		(layer "In4.Cu")
		(net "M_J_CPU0_SA_CB<7>")
	)
	(segment
		(start 389.033512 -249.016774)
		(end 389.041894 -249.0216)
		(width 0.0889)
		(layer "In4.Cu")
		(net "M_J_CPU0_SA_CB<7>")
	)
	(segment
		(start 406.43048 -249.216672)
		(end 408.98572 -246.661432)
		(width 0.14478)
		(layer "In4.Cu")
		(net "M_J_CPU0_SA_CB<7>")
	)
	(segment
		(start 392.788648 -249.01398)
		(end 392.802364 -249.021854)
		(width 0.0889)
		(layer "In4.Cu")
		(net "M_J_CPU0_SA_CB<7>")
	)
	(segment
		(start 395.062456 -249.45975)
		(end 395.692122 -249.45975)
		(width 0.0889)
		(layer "In4.Cu")
		(net "M_J_CPU0_SA_CB<7>")
	)
	(segment
		(start 383.393442 -249.016774)
		(end 383.401824 -249.0216)
		(width 0.0889)
		(layer "In4.Cu")
		(net "M_J_CPU0_SA_CB<7>")
	)
	(segment
		(start 397.157194 -249.216672)
		(end 406.43048 -249.216672)
		(width 0.14478)
		(layer "In4.Cu")
		(net "M_J_CPU0_SA_CB<7>")
	)
	(segment
		(start 407.600658 -249.054874)
		(end 407.762456 -249.216672)
		(width 0.14478)
		(layer "In4.Cu")
		(net "M_J_CPU0_SA_CB<7>")
	)
	(segment
		(start 428.182786 -245.36019)
		(end 429.882808 -243.660168)
		(width 0.14478)
		(layer "In4.Cu")
		(net "M_J_CPU0_SA_CB<7>")
	)
	(segment
		(start 384.90779 -249.0216)
		(end 384.916172 -249.016774)
		(width 0.0889)
		(layer "In4.Cu")
		(net "M_J_CPU0_SA_CB<7>")
	)
	(segment
		(start 434.57495 -243.660168)
		(end 435.000146 -243.234972)
		(width 0.14478)
		(layer "In4.Cu")
		(net "M_J_CPU0_SA_CB<7>")
	)
	(segment
		(start 393.956286 -249.24385)
		(end 394.846556 -249.24385)
		(width 0.0889)
		(layer "In4.Cu")
		(net "M_J_CPU0_SA_CB<7>")
	)
	(segment
		(start 389.607806 -249.0216)
		(end 389.616188 -249.016774)
		(width 0.0889)
		(layer "In4.Cu")
		(net "M_J_CPU0_SA_CB<7>")
	)
	(segment
		(start 392.802364 -249.021854)
		(end 392.818112 -249.030998)
		(width 0.0889)
		(layer "In4.Cu")
		(net "M_J_CPU0_SA_CB<7>")
	)
	(segment
		(start 379.454918 -249.34418)
		(end 379.30074 -249.07875)
		(width 0.0889)
		(layer "In4.Cu")
		(net "M_J_CPU0_SA_CB<7>")
	)
	(segment
		(start 409.37561 -247.051576)
		(end 407.600658 -248.826528)
		(width 0.14478)
		(layer "In4.Cu")
		(net "M_J_CPU0_SA_CB<7>")
	)
	(segment
		(start 407.600658 -248.826528)
		(end 407.600658 -249.054874)
		(width 0.14478)
		(layer "In4.Cu")
		(net "M_J_CPU0_SA_CB<7>")
	)
	(segment
		(start 429.882808 -243.660168)
		(end 434.57495 -243.660168)
		(width 0.14478)
		(layer "In4.Cu")
		(net "M_J_CPU0_SA_CB<7>")
	)
	(segment
		(start 379.30074 -249.07875)
		(end 379.323092 -248.995438)
		(width 0.0889)
		(layer "In4.Cu")
		(net "M_J_CPU0_SA_CB<7>")
	)
	(segment
		(start 384.333496 -249.016774)
		(end 384.341878 -249.0216)
		(width 0.0889)
		(layer "In4.Cu")
		(net "M_J_CPU0_SA_CB<7>")
	)
	(segment
		(start 407.990548 -249.216672)
		(end 411.84703 -245.36019)
		(width 0.14478)
		(layer "In4.Cu")
		(net "M_J_CPU0_SA_CB<7>")
	)
	(segment
		(start 391.48766 -249.0216)
		(end 391.496042 -249.016774)
		(width 0.0889)
		(layer "In4.Cu")
		(net "M_J_CPU0_SA_CB<7>")
	)
	(segment
		(start 409.213812 -246.661432)
		(end 409.37561 -246.82323)
		(width 0.14478)
		(layer "In4.Cu")
		(net "M_J_CPU0_SA_CB<7>")
	)
	(segment
		(start 396.914116 -249.45975)
		(end 397.157194 -249.216672)
		(width 0.14478)
		(layer "In4.Cu")
		(net "M_J_CPU0_SA_CB<7>")
	)
	(segment
		(start 392.413998 -249.030236)
		(end 392.42873 -249.0216)
		(width 0.0889)
		(layer "In4.Cu")
		(net "M_J_CPU0_SA_CB<7>")
	)
	(segment
		(start 409.37561 -246.82323)
		(end 409.37561 -247.051576)
		(width 0.14478)
		(layer "In4.Cu")
		(net "M_J_CPU0_SA_CB<7>")
	)
	(segment
		(start 411.84703 -245.36019)
		(end 428.182786 -245.36019)
		(width 0.14478)
		(layer "In4.Cu")
		(net "M_J_CPU0_SA_CB<7>")
	)
	(segment
		(start 388.093458 -249.016774)
		(end 388.10184 -249.0216)
		(width 0.0889)
		(layer "In4.Cu")
		(net "M_J_CPU0_SA_CB<7>")
	)
	(segment
		(start 393.734544 -249.016774)
		(end 393.734544 -249.022108)
		(width 0.0889)
		(layer "In4.Cu")
		(net "M_J_CPU0_SA_CB<7>")
	)
	(segment
		(start 381.147828 -249.0216)
		(end 381.15621 -249.016774)
		(width 0.0889)
		(layer "In4.Cu")
		(net "M_J_CPU0_SA_CB<7>")
	)
	(segment
		(start 380.207774 -249.0216)
		(end 380.216156 -249.016774)
		(width 0.0889)
		(layer "In4.Cu")
		(net "M_J_CPU0_SA_CB<7>")
	)
	(segment
		(start 393.734544 -249.022108)
		(end 393.956286 -249.24385)
		(width 0.0889)
		(layer "In4.Cu")
		(net "M_J_CPU0_SA_CB<7>")
	)
	(segment
		(start 394.846556 -249.24385)
		(end 395.062456 -249.45975)
		(width 0.0889)
		(layer "In4.Cu")
		(net "M_J_CPU0_SA_CB<7>")
	)
	(segment
		(start 379.63348 -249.016774)
		(end 379.641862 -249.0216)
		(width 0.0889)
		(layer "In4.Cu")
		(net "M_J_CPU0_SA_CB<7>")
	)
	(segment
		(start 385.847844 -249.0216)
		(end 385.856226 -249.016774)
		(width 0.0889)
		(layer "In4.Cu")
		(net "M_J_CPU0_SA_CB<7>")
	)
	(segment
		(start 395.692122 -249.45975)
		(end 396.914116 -249.45975)
		(width 0.14478)
		(layer "In4.Cu")
		(net "M_J_CPU0_SA_CB<7>")
	)
	(arc
		(start 389.981948 -249.0216)
		(mid 390.264904 -249.097777)
		(end 390.54786 -249.0216)
		(width 0.0889)
		(layer "In4.Cu")
		(net "M_J_CPU0_SA_CB<7>")
	)
	(arc
		(start 382.46177 -249.0216)
		(mid 382.744726 -249.097777)
		(end 383.027682 -249.0216)
		(width 0.0889)
		(layer "In4.Cu")
		(net "M_J_CPU0_SA_CB<7>")
	)
	(arc
		(start 388.667752 -249.0216)
		(mid 388.850003 -248.97125)
		(end 389.033512 -249.016774)
		(width 0.0889)
		(layer "In4.Cu")
		(net "M_J_CPU0_SA_CB<7>")
	)
	(arc
		(start 391.496042 -249.016774)
		(mid 391.679804 -248.971158)
		(end 391.86231 -249.0216)
		(width 0.0889)
		(layer "In4.Cu")
		(net "M_J_CPU0_SA_CB<7>")
	)
	(arc
		(start 383.027682 -249.0216)
		(mid 383.209933 -248.97125)
		(end 383.393442 -249.016774)
		(width 0.0889)
		(layer "In4.Cu")
		(net "M_J_CPU0_SA_CB<7>")
	)
	(arc
		(start 386.221986 -249.0216)
		(mid 386.504942 -249.097777)
		(end 386.787898 -249.0216)
		(width 0.0889)
		(layer "In4.Cu")
		(net "M_J_CPU0_SA_CB<7>")
	)
	(arc
		(start 384.341878 -249.0216)
		(mid 384.624834 -249.097777)
		(end 384.90779 -249.0216)
		(width 0.0889)
		(layer "In4.Cu")
		(net "M_J_CPU0_SA_CB<7>")
	)
	(arc
		(start 382.087882 -249.0216)
		(mid 382.274826 -248.971345)
		(end 382.46177 -249.0216)
		(width 0.0889)
		(layer "In4.Cu")
		(net "M_J_CPU0_SA_CB<7>")
	)
	(arc
		(start 379.641862 -249.0216)
		(mid 379.924818 -249.097777)
		(end 380.207774 -249.0216)
		(width 0.0889)
		(layer "In4.Cu")
		(net "M_J_CPU0_SA_CB<7>")
	)
	(arc
		(start 387.727698 -249.0216)
		(mid 387.909949 -248.97125)
		(end 388.093458 -249.016774)
		(width 0.0889)
		(layer "In4.Cu")
		(net "M_J_CPU0_SA_CB<7>")
	)
	(arc
		(start 391.86231 -249.0216)
		(mid 392.137016 -249.097964)
		(end 392.413998 -249.030236)
		(width 0.0889)
		(layer "In4.Cu")
		(net "M_J_CPU0_SA_CB<7>")
	)
	(arc
		(start 389.041894 -249.0216)
		(mid 389.32485 -249.097777)
		(end 389.607806 -249.0216)
		(width 0.0889)
		(layer "In4.Cu")
		(net "M_J_CPU0_SA_CB<7>")
	)
	(arc
		(start 390.921748 -249.0216)
		(mid 391.204704 -249.097777)
		(end 391.48766 -249.0216)
		(width 0.0889)
		(layer "In4.Cu")
		(net "M_J_CPU0_SA_CB<7>")
	)
	(arc
		(start 385.281932 -249.0216)
		(mid 385.564888 -249.097777)
		(end 385.847844 -249.0216)
		(width 0.0889)
		(layer "In4.Cu")
		(net "M_J_CPU0_SA_CB<7>")
	)
	(arc
		(start 383.401824 -249.0216)
		(mid 383.68478 -249.097777)
		(end 383.967736 -249.0216)
		(width 0.0889)
		(layer "In4.Cu")
		(net "M_J_CPU0_SA_CB<7>")
	)
	(arc
		(start 385.856226 -249.016774)
		(mid 386.039734 -248.97128)
		(end 386.221986 -249.0216)
		(width 0.0889)
		(layer "In4.Cu")
		(net "M_J_CPU0_SA_CB<7>")
	)
	(arc
		(start 389.616188 -249.016774)
		(mid 389.799696 -248.97128)
		(end 389.981948 -249.0216)
		(width 0.0889)
		(layer "In4.Cu")
		(net "M_J_CPU0_SA_CB<7>")
	)
	(arc
		(start 386.787898 -249.0216)
		(mid 386.974842 -248.971345)
		(end 387.161786 -249.0216)
		(width 0.0889)
		(layer "In4.Cu")
		(net "M_J_CPU0_SA_CB<7>")
	)
	(arc
		(start 380.216156 -249.016774)
		(mid 380.399664 -248.97128)
		(end 380.581916 -249.0216)
		(width 0.0889)
		(layer "In4.Cu")
		(net "M_J_CPU0_SA_CB<7>")
	)
	(arc
		(start 383.967736 -249.0216)
		(mid 384.149987 -248.97125)
		(end 384.333496 -249.016774)
		(width 0.0889)
		(layer "In4.Cu")
		(net "M_J_CPU0_SA_CB<7>")
	)
	(arc
		(start 392.818112 -249.030998)
		(mid 393.094421 -249.097974)
		(end 393.368276 -249.0216)
		(width 0.0889)
		(layer "In4.Cu")
		(net "M_J_CPU0_SA_CB<7>")
	)
	(arc
		(start 390.54786 -249.0216)
		(mid 390.734804 -248.971345)
		(end 390.921748 -249.0216)
		(width 0.0889)
		(layer "In4.Cu")
		(net "M_J_CPU0_SA_CB<7>")
	)
	(arc
		(start 392.42873 -249.0216)
		(mid 392.607717 -248.97143)
		(end 392.788648 -249.01398)
		(width 0.0889)
		(layer "In4.Cu")
		(net "M_J_CPU0_SA_CB<7>")
	)
	(arc
		(start 379.323092 -248.995438)
		(mid 379.480602 -248.97224)
		(end 379.63348 -249.016774)
		(width 0.0889)
		(layer "In4.Cu")
		(net "M_J_CPU0_SA_CB<7>")
	)
	(arc
		(start 393.368276 -249.0216)
		(mid 393.550781 -248.971123)
		(end 393.734544 -249.016774)
		(width 0.0889)
		(layer "In4.Cu")
		(net "M_J_CPU0_SA_CB<7>")
	)
	(arc
		(start 381.52197 -249.0216)
		(mid 381.804926 -249.097777)
		(end 382.087882 -249.0216)
		(width 0.0889)
		(layer "In4.Cu")
		(net "M_J_CPU0_SA_CB<7>")
	)
	(arc
		(start 384.916172 -249.016774)
		(mid 385.09968 -248.97128)
		(end 385.281932 -249.0216)
		(width 0.0889)
		(layer "In4.Cu")
		(net "M_J_CPU0_SA_CB<7>")
	)
	(arc
		(start 380.581916 -249.0216)
		(mid 380.864872 -249.097777)
		(end 381.147828 -249.0216)
		(width 0.0889)
		(layer "In4.Cu")
		(net "M_J_CPU0_SA_CB<7>")
	)
	(arc
		(start 388.10184 -249.0216)
		(mid 388.384796 -249.097777)
		(end 388.667752 -249.0216)
		(width 0.0889)
		(layer "In4.Cu")
		(net "M_J_CPU0_SA_CB<7>")
	)
	(arc
		(start 387.161786 -249.0216)
		(mid 387.444742 -249.097777)
		(end 387.727698 -249.0216)
		(width 0.0889)
		(layer "In4.Cu")
		(net "M_J_CPU0_SA_CB<7>")
	)
	(arc
		(start 381.15621 -249.016774)
		(mid 381.339718 -248.97128)
		(end 381.52197 -249.0216)
		(width 0.0889)
		(layer "In4.Cu")
		(net "M_J_CPU0_SA_CB<7>")
	)
	(segment
		(start 380.39802 -248.800112)
		(end 380.864872 -248.534174)
		(width 0.10668)
		(layer "F.Cu")
		(net "M_J_CPU0_SA_CB<6>")
	)
	(segment
		(start 413.055308 -242.81003)
		(end 429.203612 -242.81003)
		(width 0.14478)
		(layer "In4.Cu")
		(net "M_J_CPU0_SA_CB<6>")
	)
	(segment
		(start 392.898122 -248.211848)
		(end 392.91641 -248.201434)
		(width 0.0889)
		(layer "In4.Cu")
		(net "M_J_CPU0_SA_CB<6>")
	)
	(segment
		(start 392.324336 -248.206768)
		(end 392.332718 -248.211594)
		(width 0.0889)
		(layer "In4.Cu")
		(net "M_J_CPU0_SA_CB<6>")
	)
	(segment
		(start 409.874466 -245.762272)
		(end 410.103066 -245.762272)
		(width 0.14478)
		(layer "In4.Cu")
		(net "M_J_CPU0_SA_CB<6>")
	)
	(segment
		(start 395.095476 -248.62663)
		(end 395.179296 -248.54281)
		(width 0.0889)
		(layer "In4.Cu")
		(net "M_J_CPU0_SA_CB<6>")
	)
	(segment
		(start 396.522956 -248.54281)
		(end 396.9004 -248.165366)
		(width 0.14478)
		(layer "In4.Cu")
		(net "M_J_CPU0_SA_CB<6>")
	)
	(segment
		(start 391.391902 -248.211594)
		(end 391.402316 -248.21769)
		(width 0.0889)
		(layer "In4.Cu")
		(net "M_J_CPU0_SA_CB<6>")
	)
	(segment
		(start 411.478984 -242.825778)
		(end 411.707584 -242.825778)
		(width 0.14478)
		(layer "In4.Cu")
		(net "M_J_CPU0_SA_CB<6>")
	)
	(segment
		(start 393.665964 -248.48439)
		(end 393.896596 -248.48439)
		(width 0.0889)
		(layer "In4.Cu")
		(net "M_J_CPU0_SA_CB<6>")
	)
	(segment
		(start 392.892534 -248.21515)
		(end 392.898122 -248.211848)
		(width 0.0889)
		(layer "In4.Cu")
		(net "M_J_CPU0_SA_CB<6>")
	)
	(segment
		(start 385.74345 -248.206768)
		(end 385.751832 -248.211594)
		(width 0.0889)
		(layer "In4.Cu")
		(net "M_J_CPU0_SA_CB<6>")
	)
	(segment
		(start 394.038836 -248.62663)
		(end 395.095476 -248.62663)
		(width 0.0889)
		(layer "In4.Cu")
		(net "M_J_CPU0_SA_CB<6>")
	)
	(segment
		(start 380.864872 -248.534174)
		(end 380.710694 -248.268744)
		(width 0.0889)
		(layer "In4.Cu")
		(net "M_J_CPU0_SA_CB<6>")
	)
	(segment
		(start 395.179296 -248.54281)
		(end 395.733778 -248.54281)
		(width 0.0889)
		(layer "In4.Cu")
		(net "M_J_CPU0_SA_CB<6>")
	)
	(segment
		(start 381.983488 -248.206768)
		(end 381.99187 -248.211594)
		(width 0.0889)
		(layer "In4.Cu")
		(net "M_J_CPU0_SA_CB<6>")
	)
	(segment
		(start 411.707584 -242.825778)
		(end 411.869128 -242.987322)
		(width 0.14478)
		(layer "In4.Cu")
		(net "M_J_CPU0_SA_CB<6>")
	)
	(segment
		(start 382.557782 -248.211594)
		(end 382.566164 -248.206768)
		(width 0.0889)
		(layer "In4.Cu")
		(net "M_J_CPU0_SA_CB<6>")
	)
	(segment
		(start 393.896596 -248.48439)
		(end 394.038836 -248.62663)
		(width 0.0889)
		(layer "In4.Cu")
		(net "M_J_CPU0_SA_CB<6>")
	)
	(segment
		(start 383.497836 -248.211594)
		(end 383.506218 -248.206768)
		(width 0.0889)
		(layer "In4.Cu")
		(net "M_J_CPU0_SA_CB<6>")
	)
	(segment
		(start 409.712922 -245.600728)
		(end 409.874466 -245.762272)
		(width 0.14478)
		(layer "In4.Cu")
		(net "M_J_CPU0_SA_CB<6>")
	)
	(segment
		(start 380.710694 -248.268744)
		(end 380.733046 -248.185432)
		(width 0.0889)
		(layer "In4.Cu")
		(net "M_J_CPU0_SA_CB<6>")
	)
	(segment
		(start 391.01776 -248.211594)
		(end 391.026142 -248.206768)
		(width 0.0889)
		(layer "In4.Cu")
		(net "M_J_CPU0_SA_CB<6>")
	)
	(segment
		(start 388.197852 -248.211594)
		(end 388.206234 -248.206768)
		(width 0.0889)
		(layer "In4.Cu")
		(net "M_J_CPU0_SA_CB<6>")
	)
	(segment
		(start 411.869128 -243.215922)
		(end 409.712922 -245.372128)
		(width 0.14478)
		(layer "In4.Cu")
		(net "M_J_CPU0_SA_CB<6>")
	)
	(segment
		(start 411.869128 -242.987322)
		(end 411.869128 -243.215922)
		(width 0.14478)
		(layer "In4.Cu")
		(net "M_J_CPU0_SA_CB<6>")
	)
	(segment
		(start 390.443466 -248.206768)
		(end 390.451848 -248.211594)
		(width 0.0889)
		(layer "In4.Cu")
		(net "M_J_CPU0_SA_CB<6>")
	)
	(segment
		(start 395.733778 -248.54281)
		(end 396.522956 -248.54281)
		(width 0.14478)
		(layer "In4.Cu")
		(net "M_J_CPU0_SA_CB<6>")
	)
	(segment
		(start 387.257798 -248.211594)
		(end 387.26618 -248.206768)
		(width 0.0889)
		(layer "In4.Cu")
		(net "M_J_CPU0_SA_CB<6>")
	)
	(segment
		(start 434.57495 -241.960146)
		(end 435.000146 -241.53495)
		(width 0.14478)
		(layer "In4.Cu")
		(net "M_J_CPU0_SA_CB<6>")
	)
	(segment
		(start 429.203612 -242.81003)
		(end 430.053496 -241.960146)
		(width 0.14478)
		(layer "In4.Cu")
		(net "M_J_CPU0_SA_CB<6>")
	)
	(segment
		(start 430.053496 -241.960146)
		(end 434.57495 -241.960146)
		(width 0.14478)
		(layer "In4.Cu")
		(net "M_J_CPU0_SA_CB<6>")
	)
	(segment
		(start 410.103066 -245.762272)
		(end 413.055308 -242.81003)
		(width 0.14478)
		(layer "In4.Cu")
		(net "M_J_CPU0_SA_CB<6>")
	)
	(segment
		(start 381.043434 -248.206768)
		(end 381.051816 -248.211594)
		(width 0.0889)
		(layer "In4.Cu")
		(net "M_J_CPU0_SA_CB<6>")
	)
	(segment
		(start 393.461748 -248.280174)
		(end 393.665964 -248.48439)
		(width 0.0889)
		(layer "In4.Cu")
		(net "M_J_CPU0_SA_CB<6>")
	)
	(segment
		(start 396.9004 -248.165366)
		(end 406.139396 -248.165366)
		(width 0.14478)
		(layer "In4.Cu")
		(net "M_J_CPU0_SA_CB<6>")
	)
	(segment
		(start 409.712922 -245.372128)
		(end 409.712922 -245.600728)
		(width 0.14478)
		(layer "In4.Cu")
		(net "M_J_CPU0_SA_CB<6>")
	)
	(segment
		(start 406.139396 -248.165366)
		(end 411.478984 -242.825778)
		(width 0.14478)
		(layer "In4.Cu")
		(net "M_J_CPU0_SA_CB<6>")
	)
	(segment
		(start 386.683504 -248.206768)
		(end 386.691886 -248.211594)
		(width 0.0889)
		(layer "In4.Cu")
		(net "M_J_CPU0_SA_CB<6>")
	)
	(arc
		(start 388.206234 -248.206768)
		(mid 388.389742 -248.161274)
		(end 388.571994 -248.211594)
		(width 0.0889)
		(layer "In4.Cu")
		(net "M_J_CPU0_SA_CB<6>")
	)
	(arc
		(start 391.402316 -248.21769)
		(mid 391.681002 -248.28791)
		(end 391.958068 -248.211594)
		(width 0.0889)
		(layer "In4.Cu")
		(net "M_J_CPU0_SA_CB<6>")
	)
	(arc
		(start 383.506218 -248.206768)
		(mid 383.689726 -248.161274)
		(end 383.871978 -248.211594)
		(width 0.0889)
		(layer "In4.Cu")
		(net "M_J_CPU0_SA_CB<6>")
	)
	(arc
		(start 382.931924 -248.211594)
		(mid 383.21488 -248.287771)
		(end 383.497836 -248.211594)
		(width 0.0889)
		(layer "In4.Cu")
		(net "M_J_CPU0_SA_CB<6>")
	)
	(arc
		(start 384.43789 -248.211594)
		(mid 384.624834 -248.161339)
		(end 384.811778 -248.211594)
		(width 0.0889)
		(layer "In4.Cu")
		(net "M_J_CPU0_SA_CB<6>")
	)
	(arc
		(start 391.958068 -248.211594)
		(mid 392.140573 -248.161117)
		(end 392.324336 -248.206768)
		(width 0.0889)
		(layer "In4.Cu")
		(net "M_J_CPU0_SA_CB<6>")
	)
	(arc
		(start 384.811778 -248.211594)
		(mid 385.094734 -248.287771)
		(end 385.37769 -248.211594)
		(width 0.0889)
		(layer "In4.Cu")
		(net "M_J_CPU0_SA_CB<6>")
	)
	(arc
		(start 385.751832 -248.211594)
		(mid 386.034788 -248.287771)
		(end 386.317744 -248.211594)
		(width 0.0889)
		(layer "In4.Cu")
		(net "M_J_CPU0_SA_CB<6>")
	)
	(arc
		(start 388.571994 -248.211594)
		(mid 388.85495 -248.287771)
		(end 389.137906 -248.211594)
		(width 0.0889)
		(layer "In4.Cu")
		(net "M_J_CPU0_SA_CB<6>")
	)
	(arc
		(start 393.272264 -248.211594)
		(mid 393.363922 -248.2544)
		(end 393.461748 -248.280174)
		(width 0.0889)
		(layer "In4.Cu")
		(net "M_J_CPU0_SA_CB<6>")
	)
	(arc
		(start 387.63194 -248.211594)
		(mid 387.914896 -248.287771)
		(end 388.197852 -248.211594)
		(width 0.0889)
		(layer "In4.Cu")
		(net "M_J_CPU0_SA_CB<6>")
	)
	(arc
		(start 387.26618 -248.206768)
		(mid 387.449688 -248.161274)
		(end 387.63194 -248.211594)
		(width 0.0889)
		(layer "In4.Cu")
		(net "M_J_CPU0_SA_CB<6>")
	)
	(arc
		(start 385.37769 -248.211594)
		(mid 385.559941 -248.161244)
		(end 385.74345 -248.206768)
		(width 0.0889)
		(layer "In4.Cu")
		(net "M_J_CPU0_SA_CB<6>")
	)
	(arc
		(start 391.026142 -248.206768)
		(mid 391.20965 -248.161274)
		(end 391.391902 -248.211594)
		(width 0.0889)
		(layer "In4.Cu")
		(net "M_J_CPU0_SA_CB<6>")
	)
	(arc
		(start 386.691886 -248.211594)
		(mid 386.974842 -248.287771)
		(end 387.257798 -248.211594)
		(width 0.0889)
		(layer "In4.Cu")
		(net "M_J_CPU0_SA_CB<6>")
	)
	(arc
		(start 383.871978 -248.211594)
		(mid 384.154934 -248.287771)
		(end 384.43789 -248.211594)
		(width 0.0889)
		(layer "In4.Cu")
		(net "M_J_CPU0_SA_CB<6>")
	)
	(arc
		(start 381.99187 -248.211594)
		(mid 382.274826 -248.287771)
		(end 382.557782 -248.211594)
		(width 0.0889)
		(layer "In4.Cu")
		(net "M_J_CPU0_SA_CB<6>")
	)
	(arc
		(start 381.617728 -248.211594)
		(mid 381.799979 -248.161244)
		(end 381.983488 -248.206768)
		(width 0.0889)
		(layer "In4.Cu")
		(net "M_J_CPU0_SA_CB<6>")
	)
	(arc
		(start 386.317744 -248.211594)
		(mid 386.499995 -248.161244)
		(end 386.683504 -248.206768)
		(width 0.0889)
		(layer "In4.Cu")
		(net "M_J_CPU0_SA_CB<6>")
	)
	(arc
		(start 392.332718 -248.211594)
		(mid 392.612146 -248.28776)
		(end 392.892534 -248.21515)
		(width 0.0889)
		(layer "In4.Cu")
		(net "M_J_CPU0_SA_CB<6>")
	)
	(arc
		(start 390.451848 -248.211594)
		(mid 390.734804 -248.287771)
		(end 391.01776 -248.211594)
		(width 0.0889)
		(layer "In4.Cu")
		(net "M_J_CPU0_SA_CB<6>")
	)
	(arc
		(start 389.511794 -248.211594)
		(mid 389.79475 -248.287771)
		(end 390.077706 -248.211594)
		(width 0.0889)
		(layer "In4.Cu")
		(net "M_J_CPU0_SA_CB<6>")
	)
	(arc
		(start 392.91641 -248.201434)
		(mid 393.095639 -248.161281)
		(end 393.272264 -248.211594)
		(width 0.0889)
		(layer "In4.Cu")
		(net "M_J_CPU0_SA_CB<6>")
	)
	(arc
		(start 381.051816 -248.211594)
		(mid 381.334772 -248.287771)
		(end 381.617728 -248.211594)
		(width 0.0889)
		(layer "In4.Cu")
		(net "M_J_CPU0_SA_CB<6>")
	)
	(arc
		(start 389.137906 -248.211594)
		(mid 389.32485 -248.161339)
		(end 389.511794 -248.211594)
		(width 0.0889)
		(layer "In4.Cu")
		(net "M_J_CPU0_SA_CB<6>")
	)
	(arc
		(start 382.566164 -248.206768)
		(mid 382.749672 -248.161274)
		(end 382.931924 -248.211594)
		(width 0.0889)
		(layer "In4.Cu")
		(net "M_J_CPU0_SA_CB<6>")
	)
	(arc
		(start 380.733046 -248.185432)
		(mid 380.890556 -248.162234)
		(end 381.043434 -248.206768)
		(width 0.0889)
		(layer "In4.Cu")
		(net "M_J_CPU0_SA_CB<6>")
	)
	(arc
		(start 390.077706 -248.211594)
		(mid 390.259957 -248.161244)
		(end 390.443466 -248.206768)
		(width 0.0889)
		(layer "In4.Cu")
		(net "M_J_CPU0_SA_CB<6>")
	)
	(segment
		(start 378.517912 -248.800112)
		(end 378.984764 -248.534174)
		(width 0.10668)
		(layer "F.Cu")
		(net "M_J_CPU0_SA_CB<5>")
	)
	(segment
		(start 386.683504 -248.86158)
		(end 386.691886 -248.856754)
		(width 0.0889)
		(layer "In4.Cu")
		(net "M_J_CPU0_SA_CB<5>")
	)
	(segment
		(start 437.613552 -242.104164)
		(end 437.84393 -242.104164)
		(width 0.14478)
		(layer "In4.Cu")
		(net "M_J_CPU0_SA_CB<5>")
	)
	(segment
		(start 392.898122 -248.8565)
		(end 392.91641 -248.866914)
		(width 0.0889)
		(layer "In4.Cu")
		(net "M_J_CPU0_SA_CB<5>")
	)
	(segment
		(start 392.321034 -248.863612)
		(end 392.332718 -248.856754)
		(width 0.0889)
		(layer "In4.Cu")
		(net "M_J_CPU0_SA_CB<5>")
	)
	(segment
		(start 406.24379 -248.767092)
		(end 408.79903 -246.211852)
		(width 0.14478)
		(layer "In4.Cu")
		(net "M_J_CPU0_SA_CB<5>")
	)
	(segment
		(start 436.337456 -242.267232)
		(end 436.500524 -242.104164)
		(width 0.14478)
		(layer "In4.Cu")
		(net "M_J_CPU0_SA_CB<5>")
	)
	(segment
		(start 385.74345 -248.86158)
		(end 385.751832 -248.856754)
		(width 0.0889)
		(layer "In4.Cu")
		(net "M_J_CPU0_SA_CB<5>")
	)
	(segment
		(start 438.675272 -242.81003)
		(end 439.100214 -242.385088)
		(width 0.14478)
		(layer "In4.Cu")
		(net "M_J_CPU0_SA_CB<5>")
	)
	(segment
		(start 393.996926 -248.94159)
		(end 395.334236 -248.94159)
		(width 0.0889)
		(layer "In4.Cu")
		(net "M_J_CPU0_SA_CB<5>")
	)
	(segment
		(start 428.276004 -244.510052)
		(end 429.976026 -242.81003)
		(width 0.14478)
		(layer "In4.Cu")
		(net "M_J_CPU0_SA_CB<5>")
	)
	(segment
		(start 438.170066 -242.81003)
		(end 438.675272 -242.81003)
		(width 0.14478)
		(layer "In4.Cu")
		(net "M_J_CPU0_SA_CB<5>")
	)
	(segment
		(start 383.497836 -248.856754)
		(end 383.506218 -248.86158)
		(width 0.0889)
		(layer "In4.Cu")
		(net "M_J_CPU0_SA_CB<5>")
	)
	(segment
		(start 387.257798 -248.856754)
		(end 387.26618 -248.86158)
		(width 0.0889)
		(layer "In4.Cu")
		(net "M_J_CPU0_SA_CB<5>")
	)
	(segment
		(start 392.892534 -248.853198)
		(end 392.898122 -248.8565)
		(width 0.0889)
		(layer "In4.Cu")
		(net "M_J_CPU0_SA_CB<5>")
	)
	(segment
		(start 410.359098 -246.211852)
		(end 412.060898 -244.510052)
		(width 0.14478)
		(layer "In4.Cu")
		(net "M_J_CPU0_SA_CB<5>")
	)
	(segment
		(start 391.391902 -248.856754)
		(end 391.406634 -248.848118)
		(width 0.0889)
		(layer "In4.Cu")
		(net "M_J_CPU0_SA_CB<5>")
	)
	(segment
		(start 436.500524 -242.104164)
		(end 436.730902 -242.104164)
		(width 0.14478)
		(layer "In4.Cu")
		(net "M_J_CPU0_SA_CB<5>")
	)
	(segment
		(start 437.057038 -242.81003)
		(end 437.287416 -242.81003)
		(width 0.14478)
		(layer "In4.Cu")
		(net "M_J_CPU0_SA_CB<5>")
	)
	(segment
		(start 438.006998 -242.267232)
		(end 438.006998 -242.646962)
		(width 0.14478)
		(layer "In4.Cu")
		(net "M_J_CPU0_SA_CB<5>")
	)
	(segment
		(start 381.983488 -248.86158)
		(end 381.99187 -248.856754)
		(width 0.0889)
		(layer "In4.Cu")
		(net "M_J_CPU0_SA_CB<5>")
	)
	(segment
		(start 438.006998 -242.646962)
		(end 438.170066 -242.81003)
		(width 0.14478)
		(layer "In4.Cu")
		(net "M_J_CPU0_SA_CB<5>")
	)
	(segment
		(start 381.043434 -248.86158)
		(end 381.051816 -248.856754)
		(width 0.0889)
		(layer "In4.Cu")
		(net "M_J_CPU0_SA_CB<5>")
	)
	(segment
		(start 396.956534 -248.767092)
		(end 406.24379 -248.767092)
		(width 0.14478)
		(layer "In4.Cu")
		(net "M_J_CPU0_SA_CB<5>")
	)
	(segment
		(start 412.060898 -244.510052)
		(end 428.276004 -244.510052)
		(width 0.14478)
		(layer "In4.Cu")
		(net "M_J_CPU0_SA_CB<5>")
	)
	(segment
		(start 393.823952 -248.848118)
		(end 393.996926 -248.94159)
		(width 0.0889)
		(layer "In4.Cu")
		(net "M_J_CPU0_SA_CB<5>")
	)
	(segment
		(start 395.334236 -248.94159)
		(end 395.395196 -249.00255)
		(width 0.0889)
		(layer "In4.Cu")
		(net "M_J_CPU0_SA_CB<5>")
	)
	(segment
		(start 437.84393 -242.104164)
		(end 438.006998 -242.267232)
		(width 0.14478)
		(layer "In4.Cu")
		(net "M_J_CPU0_SA_CB<5>")
	)
	(segment
		(start 437.450484 -242.646962)
		(end 437.450484 -242.267232)
		(width 0.14478)
		(layer "In4.Cu")
		(net "M_J_CPU0_SA_CB<5>")
	)
	(segment
		(start 437.287416 -242.81003)
		(end 437.450484 -242.646962)
		(width 0.14478)
		(layer "In4.Cu")
		(net "M_J_CPU0_SA_CB<5>")
	)
	(segment
		(start 396.721076 -249.00255)
		(end 396.956534 -248.767092)
		(width 0.14478)
		(layer "In4.Cu")
		(net "M_J_CPU0_SA_CB<5>")
	)
	(segment
		(start 391.01776 -248.856754)
		(end 391.026142 -248.86158)
		(width 0.0889)
		(layer "In4.Cu")
		(net "M_J_CPU0_SA_CB<5>")
	)
	(segment
		(start 436.89397 -242.267232)
		(end 436.89397 -242.646962)
		(width 0.14478)
		(layer "In4.Cu")
		(net "M_J_CPU0_SA_CB<5>")
	)
	(segment
		(start 378.984764 -248.534174)
		(end 379.138942 -248.799604)
		(width 0.0889)
		(layer "In4.Cu")
		(net "M_J_CPU0_SA_CB<5>")
	)
	(segment
		(start 379.138942 -248.799604)
		(end 379.235208 -248.825004)
		(width 0.0889)
		(layer "In4.Cu")
		(net "M_J_CPU0_SA_CB<5>")
	)
	(segment
		(start 436.174388 -242.81003)
		(end 436.337456 -242.646962)
		(width 0.14478)
		(layer "In4.Cu")
		(net "M_J_CPU0_SA_CB<5>")
	)
	(segment
		(start 429.976026 -242.81003)
		(end 436.174388 -242.81003)
		(width 0.14478)
		(layer "In4.Cu")
		(net "M_J_CPU0_SA_CB<5>")
	)
	(segment
		(start 408.79903 -246.211852)
		(end 410.359098 -246.211852)
		(width 0.14478)
		(layer "In4.Cu")
		(net "M_J_CPU0_SA_CB<5>")
	)
	(segment
		(start 437.450484 -242.267232)
		(end 437.613552 -242.104164)
		(width 0.14478)
		(layer "In4.Cu")
		(net "M_J_CPU0_SA_CB<5>")
	)
	(segment
		(start 388.197852 -248.856754)
		(end 388.206234 -248.86158)
		(width 0.0889)
		(layer "In4.Cu")
		(net "M_J_CPU0_SA_CB<5>")
	)
	(segment
		(start 436.337456 -242.646962)
		(end 436.337456 -242.267232)
		(width 0.14478)
		(layer "In4.Cu")
		(net "M_J_CPU0_SA_CB<5>")
	)
	(segment
		(start 395.395196 -249.00255)
		(end 395.768322 -249.00255)
		(width 0.0889)
		(layer "In4.Cu")
		(net "M_J_CPU0_SA_CB<5>")
	)
	(segment
		(start 382.557782 -248.856754)
		(end 382.566164 -248.86158)
		(width 0.0889)
		(layer "In4.Cu")
		(net "M_J_CPU0_SA_CB<5>")
	)
	(segment
		(start 390.443466 -248.86158)
		(end 390.451848 -248.856754)
		(width 0.0889)
		(layer "In4.Cu")
		(net "M_J_CPU0_SA_CB<5>")
	)
	(segment
		(start 436.89397 -242.646962)
		(end 437.057038 -242.81003)
		(width 0.14478)
		(layer "In4.Cu")
		(net "M_J_CPU0_SA_CB<5>")
	)
	(segment
		(start 395.768322 -249.00255)
		(end 396.721076 -249.00255)
		(width 0.14478)
		(layer "In4.Cu")
		(net "M_J_CPU0_SA_CB<5>")
	)
	(segment
		(start 436.730902 -242.104164)
		(end 436.89397 -242.267232)
		(width 0.14478)
		(layer "In4.Cu")
		(net "M_J_CPU0_SA_CB<5>")
	)
	(arc
		(start 387.26618 -248.86158)
		(mid 387.449688 -248.907074)
		(end 387.63194 -248.856754)
		(width 0.0889)
		(layer "In4.Cu")
		(net "M_J_CPU0_SA_CB<5>")
	)
	(arc
		(start 389.137906 -248.856754)
		(mid 389.32485 -248.907009)
		(end 389.511794 -248.856754)
		(width 0.0889)
		(layer "In4.Cu")
		(net "M_J_CPU0_SA_CB<5>")
	)
	(arc
		(start 388.206234 -248.86158)
		(mid 388.389742 -248.907074)
		(end 388.571994 -248.856754)
		(width 0.0889)
		(layer "In4.Cu")
		(net "M_J_CPU0_SA_CB<5>")
	)
	(arc
		(start 391.406634 -248.848118)
		(mid 391.683617 -248.780314)
		(end 391.958322 -248.856754)
		(width 0.0889)
		(layer "In4.Cu")
		(net "M_J_CPU0_SA_CB<5>")
	)
	(arc
		(start 381.051816 -248.856754)
		(mid 381.334772 -248.780577)
		(end 381.617728 -248.856754)
		(width 0.0889)
		(layer "In4.Cu")
		(net "M_J_CPU0_SA_CB<5>")
	)
	(arc
		(start 385.37769 -248.856754)
		(mid 385.559941 -248.907104)
		(end 385.74345 -248.86158)
		(width 0.0889)
		(layer "In4.Cu")
		(net "M_J_CPU0_SA_CB<5>")
	)
	(arc
		(start 380.677674 -248.856754)
		(mid 380.859925 -248.907104)
		(end 381.043434 -248.86158)
		(width 0.0889)
		(layer "In4.Cu")
		(net "M_J_CPU0_SA_CB<5>")
	)
	(arc
		(start 390.077706 -248.856754)
		(mid 390.259957 -248.907104)
		(end 390.443466 -248.86158)
		(width 0.0889)
		(layer "In4.Cu")
		(net "M_J_CPU0_SA_CB<5>")
	)
	(arc
		(start 382.566164 -248.86158)
		(mid 382.749672 -248.907074)
		(end 382.931924 -248.856754)
		(width 0.0889)
		(layer "In4.Cu")
		(net "M_J_CPU0_SA_CB<5>")
	)
	(arc
		(start 386.691886 -248.856754)
		(mid 386.974842 -248.780577)
		(end 387.257798 -248.856754)
		(width 0.0889)
		(layer "In4.Cu")
		(net "M_J_CPU0_SA_CB<5>")
	)
	(arc
		(start 392.332718 -248.856754)
		(mid 392.612146 -248.780588)
		(end 392.892534 -248.853198)
		(width 0.0889)
		(layer "In4.Cu")
		(net "M_J_CPU0_SA_CB<5>")
	)
	(arc
		(start 379.235208 -248.825004)
		(mid 379.490273 -248.781653)
		(end 379.737874 -248.856754)
		(width 0.0889)
		(layer "In4.Cu")
		(net "M_J_CPU0_SA_CB<5>")
	)
	(arc
		(start 389.511794 -248.856754)
		(mid 389.79475 -248.780577)
		(end 390.077706 -248.856754)
		(width 0.0889)
		(layer "In4.Cu")
		(net "M_J_CPU0_SA_CB<5>")
	)
	(arc
		(start 381.617728 -248.856754)
		(mid 381.799979 -248.907104)
		(end 381.983488 -248.86158)
		(width 0.0889)
		(layer "In4.Cu")
		(net "M_J_CPU0_SA_CB<5>")
	)
	(arc
		(start 386.317744 -248.856754)
		(mid 386.499995 -248.907104)
		(end 386.683504 -248.86158)
		(width 0.0889)
		(layer "In4.Cu")
		(net "M_J_CPU0_SA_CB<5>")
	)
	(arc
		(start 383.871978 -248.856754)
		(mid 384.154934 -248.780577)
		(end 384.43789 -248.856754)
		(width 0.0889)
		(layer "In4.Cu")
		(net "M_J_CPU0_SA_CB<5>")
	)
	(arc
		(start 382.931924 -248.856754)
		(mid 383.21488 -248.780577)
		(end 383.497836 -248.856754)
		(width 0.0889)
		(layer "In4.Cu")
		(net "M_J_CPU0_SA_CB<5>")
	)
	(arc
		(start 391.026142 -248.86158)
		(mid 391.20965 -248.907074)
		(end 391.391902 -248.856754)
		(width 0.0889)
		(layer "In4.Cu")
		(net "M_J_CPU0_SA_CB<5>")
	)
	(arc
		(start 393.272264 -248.856754)
		(mid 393.54697 -248.78039)
		(end 393.823952 -248.848118)
		(width 0.0889)
		(layer "In4.Cu")
		(net "M_J_CPU0_SA_CB<5>")
	)
	(arc
		(start 384.811778 -248.856754)
		(mid 385.094734 -248.780577)
		(end 385.37769 -248.856754)
		(width 0.0889)
		(layer "In4.Cu")
		(net "M_J_CPU0_SA_CB<5>")
	)
	(arc
		(start 391.958322 -248.856754)
		(mid 392.13878 -248.907198)
		(end 392.321034 -248.863612)
		(width 0.0889)
		(layer "In4.Cu")
		(net "M_J_CPU0_SA_CB<5>")
	)
	(arc
		(start 380.111762 -248.856754)
		(mid 380.394718 -248.780577)
		(end 380.677674 -248.856754)
		(width 0.0889)
		(layer "In4.Cu")
		(net "M_J_CPU0_SA_CB<5>")
	)
	(arc
		(start 392.91641 -248.866914)
		(mid 393.095639 -248.907067)
		(end 393.272264 -248.856754)
		(width 0.0889)
		(layer "In4.Cu")
		(net "M_J_CPU0_SA_CB<5>")
	)
	(arc
		(start 384.43789 -248.856754)
		(mid 384.624834 -248.907009)
		(end 384.811778 -248.856754)
		(width 0.0889)
		(layer "In4.Cu")
		(net "M_J_CPU0_SA_CB<5>")
	)
	(arc
		(start 385.751832 -248.856754)
		(mid 386.034788 -248.780577)
		(end 386.317744 -248.856754)
		(width 0.0889)
		(layer "In4.Cu")
		(net "M_J_CPU0_SA_CB<5>")
	)
	(arc
		(start 390.451848 -248.856754)
		(mid 390.734804 -248.780577)
		(end 391.01776 -248.856754)
		(width 0.0889)
		(layer "In4.Cu")
		(net "M_J_CPU0_SA_CB<5>")
	)
	(arc
		(start 388.571994 -248.856754)
		(mid 388.85495 -248.780577)
		(end 389.137906 -248.856754)
		(width 0.0889)
		(layer "In4.Cu")
		(net "M_J_CPU0_SA_CB<5>")
	)
	(arc
		(start 387.63194 -248.856754)
		(mid 387.914896 -248.780577)
		(end 388.197852 -248.856754)
		(width 0.0889)
		(layer "In4.Cu")
		(net "M_J_CPU0_SA_CB<5>")
	)
	(arc
		(start 381.99187 -248.856754)
		(mid 382.274826 -248.780577)
		(end 382.557782 -248.856754)
		(width 0.0889)
		(layer "In4.Cu")
		(net "M_J_CPU0_SA_CB<5>")
	)
	(arc
		(start 383.506218 -248.86158)
		(mid 383.689726 -248.907074)
		(end 383.871978 -248.856754)
		(width 0.0889)
		(layer "In4.Cu")
		(net "M_J_CPU0_SA_CB<5>")
	)
	(arc
		(start 379.737874 -248.856754)
		(mid 379.924818 -248.907009)
		(end 380.111762 -248.856754)
		(width 0.0889)
		(layer "In4.Cu")
		(net "M_J_CPU0_SA_CB<5>")
	)
	(segment
		(start 379.927866 -247.990106)
		(end 380.394718 -247.724168)
		(width 0.10668)
		(layer "F.Cu")
		(net "M_J_CPU0_SA_CB<4>")
	)
	(segment
		(start 415.386012 -241.319812)
		(end 415.547556 -241.481356)
		(width 0.14478)
		(layer "In4.Cu")
		(net "M_J_CPU0_SA_CB<4>")
	)
	(segment
		(start 428.554134 -241.960146)
		(end 429.404272 -241.110008)
		(width 0.14478)
		(layer "In4.Cu")
		(net "M_J_CPU0_SA_CB<4>")
	)
	(segment
		(start 412.628842 -241.960146)
		(end 412.790386 -241.798602)
		(width 0.14478)
		(layer "In4.Cu")
		(net "M_J_CPU0_SA_CB<4>")
	)
	(segment
		(start 413.180276 -241.319812)
		(end 413.34182 -241.481356)
		(width 0.14478)
		(layer "In4.Cu")
		(net "M_J_CPU0_SA_CB<4>")
	)
	(segment
		(start 415.547556 -241.798602)
		(end 415.7091 -241.960146)
		(width 0.14478)
		(layer "In4.Cu")
		(net "M_J_CPU0_SA_CB<4>")
	)
	(segment
		(start 391.48766 -248.046748)
		(end 391.496042 -248.051574)
		(width 0.0889)
		(layer "In4.Cu")
		(net "M_J_CPU0_SA_CB<4>")
	)
	(segment
		(start 392.786108 -248.055892)
		(end 392.802364 -248.046494)
		(width 0.0889)
		(layer "In4.Cu")
		(net "M_J_CPU0_SA_CB<4>")
	)
	(segment
		(start 414.606232 -241.960146)
		(end 414.834578 -241.960146)
		(width 0.14478)
		(layer "In4.Cu")
		(net "M_J_CPU0_SA_CB<4>")
	)
	(segment
		(start 413.503364 -241.960146)
		(end 413.73171 -241.960146)
		(width 0.14478)
		(layer "In4.Cu")
		(net "M_J_CPU0_SA_CB<4>")
	)
	(segment
		(start 414.996122 -241.798602)
		(end 414.996122 -241.481356)
		(width 0.14478)
		(layer "In4.Cu")
		(net "M_J_CPU0_SA_CB<4>")
	)
	(segment
		(start 415.7091 -241.960146)
		(end 428.554134 -241.960146)
		(width 0.14478)
		(layer "In4.Cu")
		(net "M_J_CPU0_SA_CB<4>")
	)
	(segment
		(start 389.607806 -248.046748)
		(end 389.616188 -248.051574)
		(width 0.0889)
		(layer "In4.Cu")
		(net "M_J_CPU0_SA_CB<4>")
	)
	(segment
		(start 414.283144 -241.319812)
		(end 414.444688 -241.481356)
		(width 0.14478)
		(layer "In4.Cu")
		(net "M_J_CPU0_SA_CB<4>")
	)
	(segment
		(start 381.147828 -248.046748)
		(end 381.15621 -248.051574)
		(width 0.0889)
		(layer "In4.Cu")
		(net "M_J_CPU0_SA_CB<4>")
	)
	(segment
		(start 388.093458 -248.051574)
		(end 388.10184 -248.046748)
		(width 0.0889)
		(layer "In4.Cu")
		(net "M_J_CPU0_SA_CB<4>")
	)
	(segment
		(start 429.404272 -241.110008)
		(end 438.675272 -241.110008)
		(width 0.14478)
		(layer "In4.Cu")
		(net "M_J_CPU0_SA_CB<4>")
	)
	(segment
		(start 393.685014 -248.23039)
		(end 394.127736 -248.23039)
		(width 0.0889)
		(layer "In4.Cu")
		(net "M_J_CPU0_SA_CB<4>")
	)
	(segment
		(start 412.790386 -241.481356)
		(end 412.95193 -241.319812)
		(width 0.14478)
		(layer "In4.Cu")
		(net "M_J_CPU0_SA_CB<4>")
	)
	(segment
		(start 413.893254 -241.798602)
		(end 413.893254 -241.481356)
		(width 0.14478)
		(layer "In4.Cu")
		(net "M_J_CPU0_SA_CB<4>")
	)
	(segment
		(start 405.436578 -247.715786)
		(end 411.192218 -241.960146)
		(width 0.14478)
		(layer "In4.Cu")
		(net "M_J_CPU0_SA_CB<4>")
	)
	(segment
		(start 414.834578 -241.960146)
		(end 414.996122 -241.798602)
		(width 0.14478)
		(layer "In4.Cu")
		(net "M_J_CPU0_SA_CB<4>")
	)
	(segment
		(start 414.054798 -241.319812)
		(end 414.283144 -241.319812)
		(width 0.14478)
		(layer "In4.Cu")
		(net "M_J_CPU0_SA_CB<4>")
	)
	(segment
		(start 394.127736 -248.23039)
		(end 394.250926 -248.35358)
		(width 0.0889)
		(layer "In4.Cu")
		(net "M_J_CPU0_SA_CB<4>")
	)
	(segment
		(start 392.418062 -248.040652)
		(end 392.428476 -248.046748)
		(width 0.0889)
		(layer "In4.Cu")
		(net "M_J_CPU0_SA_CB<4>")
	)
	(segment
		(start 383.393442 -248.051574)
		(end 383.401824 -248.046748)
		(width 0.0889)
		(layer "In4.Cu")
		(net "M_J_CPU0_SA_CB<4>")
	)
	(segment
		(start 414.444688 -241.798602)
		(end 414.606232 -241.960146)
		(width 0.14478)
		(layer "In4.Cu")
		(net "M_J_CPU0_SA_CB<4>")
	)
	(segment
		(start 393.368276 -248.046748)
		(end 393.368022 -248.046748)
		(width 0.0889)
		(layer "In4.Cu")
		(net "M_J_CPU0_SA_CB<4>")
	)
	(segment
		(start 396.327376 -248.08307)
		(end 396.69466 -247.715786)
		(width 0.14478)
		(layer "In4.Cu")
		(net "M_J_CPU0_SA_CB<4>")
	)
	(segment
		(start 415.157666 -241.319812)
		(end 415.386012 -241.319812)
		(width 0.14478)
		(layer "In4.Cu")
		(net "M_J_CPU0_SA_CB<4>")
	)
	(segment
		(start 412.790386 -241.798602)
		(end 412.790386 -241.481356)
		(width 0.14478)
		(layer "In4.Cu")
		(net "M_J_CPU0_SA_CB<4>")
	)
	(segment
		(start 380.548896 -247.989598)
		(end 380.645162 -248.014998)
		(width 0.0889)
		(layer "In4.Cu")
		(net "M_J_CPU0_SA_CB<4>")
	)
	(segment
		(start 415.547556 -241.481356)
		(end 415.547556 -241.798602)
		(width 0.14478)
		(layer "In4.Cu")
		(net "M_J_CPU0_SA_CB<4>")
	)
	(segment
		(start 396.69466 -247.715786)
		(end 405.436578 -247.715786)
		(width 0.14478)
		(layer "In4.Cu")
		(net "M_J_CPU0_SA_CB<4>")
	)
	(segment
		(start 412.95193 -241.319812)
		(end 413.180276 -241.319812)
		(width 0.14478)
		(layer "In4.Cu")
		(net "M_J_CPU0_SA_CB<4>")
	)
	(segment
		(start 380.394718 -247.724168)
		(end 380.548896 -247.989598)
		(width 0.0889)
		(layer "In4.Cu")
		(net "M_J_CPU0_SA_CB<4>")
	)
	(segment
		(start 384.90779 -248.046748)
		(end 384.916172 -248.051574)
		(width 0.0889)
		(layer "In4.Cu")
		(net "M_J_CPU0_SA_CB<4>")
	)
	(segment
		(start 392.802364 -248.046494)
		(end 392.818112 -248.03735)
		(width 0.0889)
		(layer "In4.Cu")
		(net "M_J_CPU0_SA_CB<4>")
	)
	(segment
		(start 438.675272 -241.110008)
		(end 439.100214 -240.685066)
		(width 0.14478)
		(layer "In4.Cu")
		(net "M_J_CPU0_SA_CB<4>")
	)
	(segment
		(start 393.552172 -248.097548)
		(end 393.685014 -248.23039)
		(width 0.0889)
		(layer "In4.Cu")
		(net "M_J_CPU0_SA_CB<4>")
	)
	(segment
		(start 413.893254 -241.481356)
		(end 414.054798 -241.319812)
		(width 0.14478)
		(layer "In4.Cu")
		(net "M_J_CPU0_SA_CB<4>")
	)
	(segment
		(start 395.733778 -248.08307)
		(end 396.327376 -248.08307)
		(width 0.14478)
		(layer "In4.Cu")
		(net "M_J_CPU0_SA_CB<4>")
	)
	(segment
		(start 414.996122 -241.481356)
		(end 415.157666 -241.319812)
		(width 0.14478)
		(layer "In4.Cu")
		(net "M_J_CPU0_SA_CB<4>")
	)
	(segment
		(start 411.192218 -241.960146)
		(end 412.628842 -241.960146)
		(width 0.14478)
		(layer "In4.Cu")
		(net "M_J_CPU0_SA_CB<4>")
	)
	(segment
		(start 413.73171 -241.960146)
		(end 413.893254 -241.798602)
		(width 0.14478)
		(layer "In4.Cu")
		(net "M_J_CPU0_SA_CB<4>")
	)
	(segment
		(start 385.847844 -248.046748)
		(end 385.856226 -248.051574)
		(width 0.0889)
		(layer "In4.Cu")
		(net "M_J_CPU0_SA_CB<4>")
	)
	(segment
		(start 394.906246 -248.35358)
		(end 395.176756 -248.08307)
		(width 0.0889)
		(layer "In4.Cu")
		(net "M_J_CPU0_SA_CB<4>")
	)
	(segment
		(start 413.34182 -241.798602)
		(end 413.503364 -241.960146)
		(width 0.14478)
		(layer "In4.Cu")
		(net "M_J_CPU0_SA_CB<4>")
	)
	(segment
		(start 395.176756 -248.08307)
		(end 395.733778 -248.08307)
		(width 0.0889)
		(layer "In4.Cu")
		(net "M_J_CPU0_SA_CB<4>")
	)
	(segment
		(start 384.333496 -248.051574)
		(end 384.341878 -248.046748)
		(width 0.0889)
		(layer "In4.Cu")
		(net "M_J_CPU0_SA_CB<4>")
	)
	(segment
		(start 414.444688 -241.481356)
		(end 414.444688 -241.798602)
		(width 0.14478)
		(layer "In4.Cu")
		(net "M_J_CPU0_SA_CB<4>")
	)
	(segment
		(start 394.250926 -248.35358)
		(end 394.906246 -248.35358)
		(width 0.0889)
		(layer "In4.Cu")
		(net "M_J_CPU0_SA_CB<4>")
	)
	(segment
		(start 389.033512 -248.051574)
		(end 389.041894 -248.046748)
		(width 0.0889)
		(layer "In4.Cu")
		(net "M_J_CPU0_SA_CB<4>")
	)
	(segment
		(start 413.34182 -241.481356)
		(end 413.34182 -241.798602)
		(width 0.14478)
		(layer "In4.Cu")
		(net "M_J_CPU0_SA_CB<4>")
	)
	(arc
		(start 390.921748 -248.046748)
		(mid 391.204704 -247.970571)
		(end 391.48766 -248.046748)
		(width 0.0889)
		(layer "In4.Cu")
		(net "M_J_CPU0_SA_CB<4>")
	)
	(arc
		(start 385.856226 -248.051574)
		(mid 386.039734 -248.097068)
		(end 386.221986 -248.046748)
		(width 0.0889)
		(layer "In4.Cu")
		(net "M_J_CPU0_SA_CB<4>")
	)
	(arc
		(start 392.818112 -248.03735)
		(mid 393.094421 -247.970374)
		(end 393.368276 -248.046748)
		(width 0.0889)
		(layer "In4.Cu")
		(net "M_J_CPU0_SA_CB<4>")
	)
	(arc
		(start 384.341878 -248.046748)
		(mid 384.624834 -247.970571)
		(end 384.90779 -248.046748)
		(width 0.0889)
		(layer "In4.Cu")
		(net "M_J_CPU0_SA_CB<4>")
	)
	(arc
		(start 388.667752 -248.046748)
		(mid 388.850003 -248.097098)
		(end 389.033512 -248.051574)
		(width 0.0889)
		(layer "In4.Cu")
		(net "M_J_CPU0_SA_CB<4>")
	)
	(arc
		(start 383.967736 -248.046748)
		(mid 384.149987 -248.097098)
		(end 384.333496 -248.051574)
		(width 0.0889)
		(layer "In4.Cu")
		(net "M_J_CPU0_SA_CB<4>")
	)
	(arc
		(start 382.087882 -248.046748)
		(mid 382.274826 -248.097003)
		(end 382.46177 -248.046748)
		(width 0.0889)
		(layer "In4.Cu")
		(net "M_J_CPU0_SA_CB<4>")
	)
	(arc
		(start 381.15621 -248.051574)
		(mid 381.339718 -248.097068)
		(end 381.52197 -248.046748)
		(width 0.0889)
		(layer "In4.Cu")
		(net "M_J_CPU0_SA_CB<4>")
	)
	(arc
		(start 387.161786 -248.046748)
		(mid 387.444742 -247.970571)
		(end 387.727698 -248.046748)
		(width 0.0889)
		(layer "In4.Cu")
		(net "M_J_CPU0_SA_CB<4>")
	)
	(arc
		(start 390.54786 -248.046748)
		(mid 390.734804 -248.097003)
		(end 390.921748 -248.046748)
		(width 0.0889)
		(layer "In4.Cu")
		(net "M_J_CPU0_SA_CB<4>")
	)
	(arc
		(start 387.727698 -248.046748)
		(mid 387.909949 -248.097098)
		(end 388.093458 -248.051574)
		(width 0.0889)
		(layer "In4.Cu")
		(net "M_J_CPU0_SA_CB<4>")
	)
	(arc
		(start 389.041894 -248.046748)
		(mid 389.32485 -247.970571)
		(end 389.607806 -248.046748)
		(width 0.0889)
		(layer "In4.Cu")
		(net "M_J_CPU0_SA_CB<4>")
	)
	(arc
		(start 389.981948 -248.046748)
		(mid 390.264904 -247.970571)
		(end 390.54786 -248.046748)
		(width 0.0889)
		(layer "In4.Cu")
		(net "M_J_CPU0_SA_CB<4>")
	)
	(arc
		(start 383.401824 -248.046748)
		(mid 383.68478 -247.970571)
		(end 383.967736 -248.046748)
		(width 0.0889)
		(layer "In4.Cu")
		(net "M_J_CPU0_SA_CB<4>")
	)
	(arc
		(start 381.52197 -248.046748)
		(mid 381.804926 -247.970571)
		(end 382.087882 -248.046748)
		(width 0.0889)
		(layer "In4.Cu")
		(net "M_J_CPU0_SA_CB<4>")
	)
	(arc
		(start 383.027682 -248.046748)
		(mid 383.209933 -248.097098)
		(end 383.393442 -248.051574)
		(width 0.0889)
		(layer "In4.Cu")
		(net "M_J_CPU0_SA_CB<4>")
	)
	(arc
		(start 391.86231 -248.046748)
		(mid 392.139377 -247.970477)
		(end 392.418062 -248.040652)
		(width 0.0889)
		(layer "In4.Cu")
		(net "M_J_CPU0_SA_CB<4>")
	)
	(arc
		(start 391.496042 -248.051574)
		(mid 391.679804 -248.09719)
		(end 391.86231 -248.046748)
		(width 0.0889)
		(layer "In4.Cu")
		(net "M_J_CPU0_SA_CB<4>")
	)
	(arc
		(start 385.281932 -248.046748)
		(mid 385.564888 -247.970571)
		(end 385.847844 -248.046748)
		(width 0.0889)
		(layer "In4.Cu")
		(net "M_J_CPU0_SA_CB<4>")
	)
	(arc
		(start 393.368022 -248.046748)
		(mid 393.456797 -248.084097)
		(end 393.552172 -248.097548)
		(width 0.0889)
		(layer "In4.Cu")
		(net "M_J_CPU0_SA_CB<4>")
	)
	(arc
		(start 382.46177 -248.046748)
		(mid 382.744726 -247.970571)
		(end 383.027682 -248.046748)
		(width 0.0889)
		(layer "In4.Cu")
		(net "M_J_CPU0_SA_CB<4>")
	)
	(arc
		(start 386.787898 -248.046748)
		(mid 386.974842 -248.097003)
		(end 387.161786 -248.046748)
		(width 0.0889)
		(layer "In4.Cu")
		(net "M_J_CPU0_SA_CB<4>")
	)
	(arc
		(start 389.616188 -248.051574)
		(mid 389.799696 -248.097068)
		(end 389.981948 -248.046748)
		(width 0.0889)
		(layer "In4.Cu")
		(net "M_J_CPU0_SA_CB<4>")
	)
	(arc
		(start 388.10184 -248.046748)
		(mid 388.384796 -247.970571)
		(end 388.667752 -248.046748)
		(width 0.0889)
		(layer "In4.Cu")
		(net "M_J_CPU0_SA_CB<4>")
	)
	(arc
		(start 386.221986 -248.046748)
		(mid 386.504942 -247.970571)
		(end 386.787898 -248.046748)
		(width 0.0889)
		(layer "In4.Cu")
		(net "M_J_CPU0_SA_CB<4>")
	)
	(arc
		(start 380.645162 -248.014998)
		(mid 380.900227 -247.971647)
		(end 381.147828 -248.046748)
		(width 0.0889)
		(layer "In4.Cu")
		(net "M_J_CPU0_SA_CB<4>")
	)
	(arc
		(start 384.916172 -248.051574)
		(mid 385.09968 -248.097068)
		(end 385.281932 -248.046748)
		(width 0.0889)
		(layer "In4.Cu")
		(net "M_J_CPU0_SA_CB<4>")
	)
	(arc
		(start 392.428476 -248.046748)
		(mid 392.606126 -248.097008)
		(end 392.786108 -248.055892)
		(width 0.0889)
		(layer "In4.Cu")
		(net "M_J_CPU0_SA_CB<4>")
	)
	(segment
		(start 378.988066 -246.370094)
		(end 379.454918 -246.104156)
		(width 0.10668)
		(layer "F.Cu")
		(net "M_J_CPU0_SA_CB<3>")
	)
	(segment
		(start 392.788648 -245.773956)
		(end 392.802364 -245.78183)
		(width 0.0889)
		(layer "In4.Cu")
		(net "M_J_CPU0_SA_CB<3>")
	)
	(segment
		(start 384.90779 -245.781576)
		(end 384.916172 -245.77675)
		(width 0.0889)
		(layer "In4.Cu")
		(net "M_J_CPU0_SA_CB<3>")
	)
	(segment
		(start 379.30074 -245.838726)
		(end 379.323092 -245.755414)
		(width 0.0889)
		(layer "In4.Cu")
		(net "M_J_CPU0_SA_CB<3>")
	)
	(segment
		(start 389.607806 -245.781576)
		(end 389.616188 -245.77675)
		(width 0.0889)
		(layer "In4.Cu")
		(net "M_J_CPU0_SA_CB<3>")
	)
	(segment
		(start 429.06569 -237.700566)
		(end 429.915828 -236.850428)
		(width 0.14478)
		(layer "In4.Cu")
		(net "M_J_CPU0_SA_CB<3>")
	)
	(segment
		(start 410.429202 -239.367568)
		(end 410.590746 -239.206024)
		(width 0.14478)
		(layer "In4.Cu")
		(net "M_J_CPU0_SA_CB<3>")
	)
	(segment
		(start 410.590746 -238.977424)
		(end 410.288486 -238.675164)
		(width 0.14478)
		(layer "In4.Cu")
		(net "M_J_CPU0_SA_CB<3>")
	)
	(segment
		(start 410.590746 -239.206024)
		(end 410.590746 -238.977424)
		(width 0.14478)
		(layer "In4.Cu")
		(net "M_J_CPU0_SA_CB<3>")
	)
	(segment
		(start 383.393442 -245.77675)
		(end 383.401824 -245.781576)
		(width 0.0889)
		(layer "In4.Cu")
		(net "M_J_CPU0_SA_CB<3>")
	)
	(segment
		(start 409.669742 -239.065308)
		(end 409.898342 -239.065308)
		(width 0.14478)
		(layer "In4.Cu")
		(net "M_J_CPU0_SA_CB<3>")
	)
	(segment
		(start 409.898342 -239.065308)
		(end 410.200602 -239.367568)
		(width 0.14478)
		(layer "In4.Cu")
		(net "M_J_CPU0_SA_CB<3>")
	)
	(segment
		(start 422.19626 -236.850428)
		(end 426.064426 -236.850428)
		(width 0.14478)
		(layer "In4.Cu")
		(net "M_J_CPU0_SA_CB<3>")
	)
	(segment
		(start 408.868626 -240.928144)
		(end 409.03017 -240.7666)
		(width 0.14478)
		(layer "In4.Cu")
		(net "M_J_CPU0_SA_CB<3>")
	)
	(segment
		(start 414.855914 -236.86008)
		(end 418.13988 -236.86008)
		(width 0.14478)
		(layer "In4.Cu")
		(net "M_J_CPU0_SA_CB<3>")
	)
	(segment
		(start 410.288486 -238.446564)
		(end 411.024832 -237.710218)
		(width 0.14478)
		(layer "In4.Cu")
		(net "M_J_CPU0_SA_CB<3>")
	)
	(segment
		(start 426.914564 -237.700566)
		(end 429.06569 -237.700566)
		(width 0.14478)
		(layer "In4.Cu")
		(net "M_J_CPU0_SA_CB<3>")
	)
	(segment
		(start 418.980112 -237.700312)
		(end 421.346376 -237.700312)
		(width 0.14478)
		(layer "In4.Cu")
		(net "M_J_CPU0_SA_CB<3>")
	)
	(segment
		(start 414.005776 -237.710218)
		(end 414.855914 -236.86008)
		(width 0.14478)
		(layer "In4.Cu")
		(net "M_J_CPU0_SA_CB<3>")
	)
	(segment
		(start 379.63348 -245.77675)
		(end 379.641862 -245.781576)
		(width 0.0889)
		(layer "In4.Cu")
		(net "M_J_CPU0_SA_CB<3>")
	)
	(segment
		(start 418.13988 -236.86008)
		(end 418.980112 -237.700312)
		(width 0.14478)
		(layer "In4.Cu")
		(net "M_J_CPU0_SA_CB<3>")
	)
	(segment
		(start 409.508198 -239.455452)
		(end 409.508198 -239.226852)
		(width 0.14478)
		(layer "In4.Cu")
		(net "M_J_CPU0_SA_CB<3>")
	)
	(segment
		(start 389.033512 -245.77675)
		(end 389.041894 -245.781576)
		(width 0.0889)
		(layer "In4.Cu")
		(net "M_J_CPU0_SA_CB<3>")
	)
	(segment
		(start 394.88364 -245.98757)
		(end 395.499844 -245.371366)
		(width 0.0889)
		(layer "In4.Cu")
		(net "M_J_CPU0_SA_CB<3>")
	)
	(segment
		(start 395.87805 -245.371366)
		(end 403.363684 -245.371366)
		(width 0.14478)
		(layer "In4.Cu")
		(net "M_J_CPU0_SA_CB<3>")
	)
	(segment
		(start 426.064426 -236.850428)
		(end 426.914564 -237.700566)
		(width 0.14478)
		(layer "In4.Cu")
		(net "M_J_CPU0_SA_CB<3>")
	)
	(segment
		(start 409.118054 -239.845596)
		(end 409.420314 -240.147856)
		(width 0.14478)
		(layer "In4.Cu")
		(net "M_J_CPU0_SA_CB<3>")
	)
	(segment
		(start 409.648914 -240.147856)
		(end 409.810458 -239.986312)
		(width 0.14478)
		(layer "In4.Cu")
		(net "M_J_CPU0_SA_CB<3>")
	)
	(segment
		(start 380.207774 -245.781576)
		(end 380.216156 -245.77675)
		(width 0.0889)
		(layer "In4.Cu")
		(net "M_J_CPU0_SA_CB<3>")
	)
	(segment
		(start 392.413998 -245.790212)
		(end 392.42873 -245.781576)
		(width 0.0889)
		(layer "In4.Cu")
		(net "M_J_CPU0_SA_CB<3>")
	)
	(segment
		(start 408.889454 -239.845596)
		(end 409.118054 -239.845596)
		(width 0.14478)
		(layer "In4.Cu")
		(net "M_J_CPU0_SA_CB<3>")
	)
	(segment
		(start 409.03017 -240.7666)
		(end 409.03017 -240.538)
		(width 0.14478)
		(layer "In4.Cu")
		(net "M_J_CPU0_SA_CB<3>")
	)
	(segment
		(start 411.024832 -237.710218)
		(end 414.005776 -237.710218)
		(width 0.14478)
		(layer "In4.Cu")
		(net "M_J_CPU0_SA_CB<3>")
	)
	(segment
		(start 408.72791 -240.00714)
		(end 408.889454 -239.845596)
		(width 0.14478)
		(layer "In4.Cu")
		(net "M_J_CPU0_SA_CB<3>")
	)
	(segment
		(start 392.802364 -245.78183)
		(end 392.818112 -245.790974)
		(width 0.0889)
		(layer "In4.Cu")
		(net "M_J_CPU0_SA_CB<3>")
	)
	(segment
		(start 403.363684 -245.371366)
		(end 408.109166 -240.625884)
		(width 0.14478)
		(layer "In4.Cu")
		(net "M_J_CPU0_SA_CB<3>")
	)
	(segment
		(start 429.915828 -236.850428)
		(end 434.565552 -236.850428)
		(width 0.14478)
		(layer "In4.Cu")
		(net "M_J_CPU0_SA_CB<3>")
	)
	(segment
		(start 393.734544 -245.77675)
		(end 393.945364 -245.98757)
		(width 0.0889)
		(layer "In4.Cu")
		(net "M_J_CPU0_SA_CB<3>")
	)
	(segment
		(start 393.945364 -245.98757)
		(end 394.88364 -245.98757)
		(width 0.0889)
		(layer "In4.Cu")
		(net "M_J_CPU0_SA_CB<3>")
	)
	(segment
		(start 388.093458 -245.77675)
		(end 388.10184 -245.781576)
		(width 0.0889)
		(layer "In4.Cu")
		(net "M_J_CPU0_SA_CB<3>")
	)
	(segment
		(start 410.288486 -238.675164)
		(end 410.288486 -238.446564)
		(width 0.14478)
		(layer "In4.Cu")
		(net "M_J_CPU0_SA_CB<3>")
	)
	(segment
		(start 408.640026 -240.928144)
		(end 408.868626 -240.928144)
		(width 0.14478)
		(layer "In4.Cu")
		(net "M_J_CPU0_SA_CB<3>")
	)
	(segment
		(start 434.565552 -236.850428)
		(end 435.000146 -237.285022)
		(width 0.14478)
		(layer "In4.Cu")
		(net "M_J_CPU0_SA_CB<3>")
	)
	(segment
		(start 391.48766 -245.781576)
		(end 391.496042 -245.77675)
		(width 0.0889)
		(layer "In4.Cu")
		(net "M_J_CPU0_SA_CB<3>")
	)
	(segment
		(start 409.810458 -239.986312)
		(end 409.810458 -239.757712)
		(width 0.14478)
		(layer "In4.Cu")
		(net "M_J_CPU0_SA_CB<3>")
	)
	(segment
		(start 408.337766 -240.625884)
		(end 408.640026 -240.928144)
		(width 0.14478)
		(layer "In4.Cu")
		(net "M_J_CPU0_SA_CB<3>")
	)
	(segment
		(start 379.454918 -246.104156)
		(end 379.30074 -245.838726)
		(width 0.0889)
		(layer "In4.Cu")
		(net "M_J_CPU0_SA_CB<3>")
	)
	(segment
		(start 408.109166 -240.625884)
		(end 408.337766 -240.625884)
		(width 0.14478)
		(layer "In4.Cu")
		(net "M_J_CPU0_SA_CB<3>")
	)
	(segment
		(start 409.508198 -239.226852)
		(end 409.669742 -239.065308)
		(width 0.14478)
		(layer "In4.Cu")
		(net "M_J_CPU0_SA_CB<3>")
	)
	(segment
		(start 409.810458 -239.757712)
		(end 409.508198 -239.455452)
		(width 0.14478)
		(layer "In4.Cu")
		(net "M_J_CPU0_SA_CB<3>")
	)
	(segment
		(start 409.420314 -240.147856)
		(end 409.648914 -240.147856)
		(width 0.14478)
		(layer "In4.Cu")
		(net "M_J_CPU0_SA_CB<3>")
	)
	(segment
		(start 395.499844 -245.371366)
		(end 395.87805 -245.371366)
		(width 0.0889)
		(layer "In4.Cu")
		(net "M_J_CPU0_SA_CB<3>")
	)
	(segment
		(start 410.200602 -239.367568)
		(end 410.429202 -239.367568)
		(width 0.14478)
		(layer "In4.Cu")
		(net "M_J_CPU0_SA_CB<3>")
	)
	(segment
		(start 421.346376 -237.700312)
		(end 422.19626 -236.850428)
		(width 0.14478)
		(layer "In4.Cu")
		(net "M_J_CPU0_SA_CB<3>")
	)
	(segment
		(start 408.72791 -240.23574)
		(end 408.72791 -240.00714)
		(width 0.14478)
		(layer "In4.Cu")
		(net "M_J_CPU0_SA_CB<3>")
	)
	(segment
		(start 381.147828 -245.781576)
		(end 381.15621 -245.77675)
		(width 0.0889)
		(layer "In4.Cu")
		(net "M_J_CPU0_SA_CB<3>")
	)
	(segment
		(start 385.847844 -245.781576)
		(end 385.856226 -245.77675)
		(width 0.0889)
		(layer "In4.Cu")
		(net "M_J_CPU0_SA_CB<3>")
	)
	(segment
		(start 384.333496 -245.77675)
		(end 384.341878 -245.781576)
		(width 0.0889)
		(layer "In4.Cu")
		(net "M_J_CPU0_SA_CB<3>")
	)
	(segment
		(start 409.03017 -240.538)
		(end 408.72791 -240.23574)
		(width 0.14478)
		(layer "In4.Cu")
		(net "M_J_CPU0_SA_CB<3>")
	)
	(arc
		(start 388.667752 -245.781576)
		(mid 388.850003 -245.731226)
		(end 389.033512 -245.77675)
		(width 0.0889)
		(layer "In4.Cu")
		(net "M_J_CPU0_SA_CB<3>")
	)
	(arc
		(start 392.818112 -245.790974)
		(mid 393.094421 -245.85795)
		(end 393.368276 -245.781576)
		(width 0.0889)
		(layer "In4.Cu")
		(net "M_J_CPU0_SA_CB<3>")
	)
	(arc
		(start 381.52197 -245.781576)
		(mid 381.804926 -245.857753)
		(end 382.087882 -245.781576)
		(width 0.0889)
		(layer "In4.Cu")
		(net "M_J_CPU0_SA_CB<3>")
	)
	(arc
		(start 383.401824 -245.781576)
		(mid 383.68478 -245.857753)
		(end 383.967736 -245.781576)
		(width 0.0889)
		(layer "In4.Cu")
		(net "M_J_CPU0_SA_CB<3>")
	)
	(arc
		(start 392.42873 -245.781576)
		(mid 392.607717 -245.731406)
		(end 392.788648 -245.773956)
		(width 0.0889)
		(layer "In4.Cu")
		(net "M_J_CPU0_SA_CB<3>")
	)
	(arc
		(start 384.916172 -245.77675)
		(mid 385.09968 -245.731256)
		(end 385.281932 -245.781576)
		(width 0.0889)
		(layer "In4.Cu")
		(net "M_J_CPU0_SA_CB<3>")
	)
	(arc
		(start 385.856226 -245.77675)
		(mid 386.039734 -245.731256)
		(end 386.221986 -245.781576)
		(width 0.0889)
		(layer "In4.Cu")
		(net "M_J_CPU0_SA_CB<3>")
	)
	(arc
		(start 391.86231 -245.781576)
		(mid 392.137016 -245.85794)
		(end 392.413998 -245.790212)
		(width 0.0889)
		(layer "In4.Cu")
		(net "M_J_CPU0_SA_CB<3>")
	)
	(arc
		(start 380.581916 -245.781576)
		(mid 380.864872 -245.857753)
		(end 381.147828 -245.781576)
		(width 0.0889)
		(layer "In4.Cu")
		(net "M_J_CPU0_SA_CB<3>")
	)
	(arc
		(start 381.15621 -245.77675)
		(mid 381.339718 -245.731256)
		(end 381.52197 -245.781576)
		(width 0.0889)
		(layer "In4.Cu")
		(net "M_J_CPU0_SA_CB<3>")
	)
	(arc
		(start 382.46177 -245.781576)
		(mid 382.744726 -245.857753)
		(end 383.027682 -245.781576)
		(width 0.0889)
		(layer "In4.Cu")
		(net "M_J_CPU0_SA_CB<3>")
	)
	(arc
		(start 379.641862 -245.781576)
		(mid 379.924818 -245.857753)
		(end 380.207774 -245.781576)
		(width 0.0889)
		(layer "In4.Cu")
		(net "M_J_CPU0_SA_CB<3>")
	)
	(arc
		(start 384.341878 -245.781576)
		(mid 384.624834 -245.857753)
		(end 384.90779 -245.781576)
		(width 0.0889)
		(layer "In4.Cu")
		(net "M_J_CPU0_SA_CB<3>")
	)
	(arc
		(start 388.10184 -245.781576)
		(mid 388.384796 -245.857753)
		(end 388.667752 -245.781576)
		(width 0.0889)
		(layer "In4.Cu")
		(net "M_J_CPU0_SA_CB<3>")
	)
	(arc
		(start 382.087882 -245.781576)
		(mid 382.274826 -245.731321)
		(end 382.46177 -245.781576)
		(width 0.0889)
		(layer "In4.Cu")
		(net "M_J_CPU0_SA_CB<3>")
	)
	(arc
		(start 387.727698 -245.781576)
		(mid 387.909949 -245.731226)
		(end 388.093458 -245.77675)
		(width 0.0889)
		(layer "In4.Cu")
		(net "M_J_CPU0_SA_CB<3>")
	)
	(arc
		(start 391.496042 -245.77675)
		(mid 391.679804 -245.731134)
		(end 391.86231 -245.781576)
		(width 0.0889)
		(layer "In4.Cu")
		(net "M_J_CPU0_SA_CB<3>")
	)
	(arc
		(start 387.161786 -245.781576)
		(mid 387.444742 -245.857753)
		(end 387.727698 -245.781576)
		(width 0.0889)
		(layer "In4.Cu")
		(net "M_J_CPU0_SA_CB<3>")
	)
	(arc
		(start 379.323092 -245.755414)
		(mid 379.480602 -245.732216)
		(end 379.63348 -245.77675)
		(width 0.0889)
		(layer "In4.Cu")
		(net "M_J_CPU0_SA_CB<3>")
	)
	(arc
		(start 389.616188 -245.77675)
		(mid 389.799696 -245.731256)
		(end 389.981948 -245.781576)
		(width 0.0889)
		(layer "In4.Cu")
		(net "M_J_CPU0_SA_CB<3>")
	)
	(arc
		(start 386.221986 -245.781576)
		(mid 386.504942 -245.857753)
		(end 386.787898 -245.781576)
		(width 0.0889)
		(layer "In4.Cu")
		(net "M_J_CPU0_SA_CB<3>")
	)
	(arc
		(start 389.981948 -245.781576)
		(mid 390.264904 -245.857753)
		(end 390.54786 -245.781576)
		(width 0.0889)
		(layer "In4.Cu")
		(net "M_J_CPU0_SA_CB<3>")
	)
	(arc
		(start 380.216156 -245.77675)
		(mid 380.399664 -245.731256)
		(end 380.581916 -245.781576)
		(width 0.0889)
		(layer "In4.Cu")
		(net "M_J_CPU0_SA_CB<3>")
	)
	(arc
		(start 386.787898 -245.781576)
		(mid 386.974842 -245.731321)
		(end 387.161786 -245.781576)
		(width 0.0889)
		(layer "In4.Cu")
		(net "M_J_CPU0_SA_CB<3>")
	)
	(arc
		(start 390.921748 -245.781576)
		(mid 391.204704 -245.857753)
		(end 391.48766 -245.781576)
		(width 0.0889)
		(layer "In4.Cu")
		(net "M_J_CPU0_SA_CB<3>")
	)
	(arc
		(start 389.041894 -245.781576)
		(mid 389.32485 -245.857753)
		(end 389.607806 -245.781576)
		(width 0.0889)
		(layer "In4.Cu")
		(net "M_J_CPU0_SA_CB<3>")
	)
	(arc
		(start 383.967736 -245.781576)
		(mid 384.149987 -245.731226)
		(end 384.333496 -245.77675)
		(width 0.0889)
		(layer "In4.Cu")
		(net "M_J_CPU0_SA_CB<3>")
	)
	(arc
		(start 393.368276 -245.781576)
		(mid 393.550781 -245.731099)
		(end 393.734544 -245.77675)
		(width 0.0889)
		(layer "In4.Cu")
		(net "M_J_CPU0_SA_CB<3>")
	)
	(arc
		(start 383.027682 -245.781576)
		(mid 383.209933 -245.731226)
		(end 383.393442 -245.77675)
		(width 0.0889)
		(layer "In4.Cu")
		(net "M_J_CPU0_SA_CB<3>")
	)
	(arc
		(start 390.54786 -245.781576)
		(mid 390.734804 -245.731321)
		(end 390.921748 -245.781576)
		(width 0.0889)
		(layer "In4.Cu")
		(net "M_J_CPU0_SA_CB<3>")
	)
	(arc
		(start 385.281932 -245.781576)
		(mid 385.564888 -245.857753)
		(end 385.847844 -245.781576)
		(width 0.0889)
		(layer "In4.Cu")
		(net "M_J_CPU0_SA_CB<3>")
	)
	(segment
		(start 380.39802 -245.560088)
		(end 380.864872 -245.29415)
		(width 0.10668)
		(layer "F.Cu")
		(net "M_J_CPU0_SA_CB<2>")
	)
	(segment
		(start 406.419812 -240.81486)
		(end 406.211278 -240.606072)
		(width 0.14478)
		(layer "In4.Cu")
		(net "M_J_CPU0_SA_CB<2>")
	)
	(segment
		(start 426.712126 -236.01045)
		(end 429.003968 -236.01045)
		(width 0.14478)
		(layer "In4.Cu")
		(net "M_J_CPU0_SA_CB<2>")
	)
	(segment
		(start 404.032466 -242.556792)
		(end 404.260558 -242.556792)
		(width 0.14478)
		(layer "In4.Cu")
		(net "M_J_CPU0_SA_CB<2>")
	)
	(segment
		(start 422.430956 -235.160312)
		(end 425.861988 -235.160312)
		(width 0.14478)
		(layer "In4.Cu")
		(net "M_J_CPU0_SA_CB<2>")
	)
	(segment
		(start 418.732462 -236.01045)
		(end 421.580818 -236.01045)
		(width 0.14478)
		(layer "In4.Cu")
		(net "M_J_CPU0_SA_CB<2>")
	)
	(segment
		(start 429.003968 -236.01045)
		(end 429.854106 -235.160312)
		(width 0.14478)
		(layer "In4.Cu")
		(net "M_J_CPU0_SA_CB<2>")
	)
	(segment
		(start 406.601422 -240.215928)
		(end 406.809956 -240.424716)
		(width 0.14478)
		(layer "In4.Cu")
		(net "M_J_CPU0_SA_CB<2>")
	)
	(segment
		(start 403.000718 -244.462046)
		(end 403.29866 -244.164104)
		(width 0.14478)
		(layer "In4.Cu")
		(net "M_J_CPU0_SA_CB<2>")
	)
	(segment
		(start 405.24938 -241.985292)
		(end 405.477472 -241.985292)
		(width 0.14478)
		(layer "In4.Cu")
		(net "M_J_CPU0_SA_CB<2>")
	)
	(segment
		(start 392.324336 -244.966744)
		(end 392.332718 -244.97157)
		(width 0.0889)
		(layer "In4.Cu")
		(net "M_J_CPU0_SA_CB<2>")
	)
	(segment
		(start 403.29866 -244.164104)
		(end 403.29866 -243.936012)
		(width 0.14478)
		(layer "In4.Cu")
		(net "M_J_CPU0_SA_CB<2>")
	)
	(segment
		(start 380.864872 -245.29415)
		(end 380.710694 -245.02872)
		(width 0.0889)
		(layer "In4.Cu")
		(net "M_J_CPU0_SA_CB<2>")
	)
	(segment
		(start 415.089594 -235.160312)
		(end 417.882324 -235.160312)
		(width 0.14478)
		(layer "In4.Cu")
		(net "M_J_CPU0_SA_CB<2>")
	)
	(segment
		(start 380.710694 -245.02872)
		(end 380.733046 -244.945408)
		(width 0.0889)
		(layer "In4.Cu")
		(net "M_J_CPU0_SA_CB<2>")
	)
	(segment
		(start 405.477472 -241.985292)
		(end 405.639524 -241.82324)
		(width 0.14478)
		(layer "In4.Cu")
		(net "M_J_CPU0_SA_CB<2>")
	)
	(segment
		(start 403.29866 -243.936012)
		(end 403.090126 -243.727224)
		(width 0.14478)
		(layer "In4.Cu")
		(net "M_J_CPU0_SA_CB<2>")
	)
	(segment
		(start 390.443466 -244.966744)
		(end 390.451848 -244.97157)
		(width 0.0889)
		(layer "In4.Cu")
		(net "M_J_CPU0_SA_CB<2>")
	)
	(segment
		(start 404.078948 -243.383816)
		(end 404.078948 -243.155724)
		(width 0.14478)
		(layer "In4.Cu")
		(net "M_J_CPU0_SA_CB<2>")
	)
	(segment
		(start 405.593042 -240.996216)
		(end 405.821134 -240.996216)
		(width 0.14478)
		(layer "In4.Cu")
		(net "M_J_CPU0_SA_CB<2>")
	)
	(segment
		(start 391.01776 -244.97157)
		(end 391.026142 -244.966744)
		(width 0.0889)
		(layer "In4.Cu")
		(net "M_J_CPU0_SA_CB<2>")
	)
	(segment
		(start 403.916896 -243.545868)
		(end 404.078948 -243.383816)
		(width 0.14478)
		(layer "In4.Cu")
		(net "M_J_CPU0_SA_CB<2>")
	)
	(segment
		(start 406.211278 -240.606072)
		(end 406.211278 -240.37798)
		(width 0.14478)
		(layer "In4.Cu")
		(net "M_J_CPU0_SA_CB<2>")
	)
	(segment
		(start 405.040846 -241.776504)
		(end 405.24938 -241.985292)
		(width 0.14478)
		(layer "In4.Cu")
		(net "M_J_CPU0_SA_CB<2>")
	)
	(segment
		(start 406.809956 -240.424716)
		(end 407.038048 -240.424716)
		(width 0.14478)
		(layer "In4.Cu")
		(net "M_J_CPU0_SA_CB<2>")
	)
	(segment
		(start 406.211278 -240.37798)
		(end 406.37333 -240.215928)
		(width 0.14478)
		(layer "In4.Cu")
		(net "M_J_CPU0_SA_CB<2>")
	)
	(segment
		(start 414.239456 -236.01045)
		(end 415.089594 -235.160312)
		(width 0.14478)
		(layer "In4.Cu")
		(net "M_J_CPU0_SA_CB<2>")
	)
	(segment
		(start 385.74345 -244.966744)
		(end 385.751832 -244.97157)
		(width 0.0889)
		(layer "In4.Cu")
		(net "M_J_CPU0_SA_CB<2>")
	)
	(segment
		(start 387.257798 -244.97157)
		(end 387.26618 -244.966744)
		(width 0.0889)
		(layer "In4.Cu")
		(net "M_J_CPU0_SA_CB<2>")
	)
	(segment
		(start 405.43099 -241.158268)
		(end 405.593042 -240.996216)
		(width 0.14478)
		(layer "In4.Cu")
		(net "M_J_CPU0_SA_CB<2>")
	)
	(segment
		(start 407.038048 -240.424716)
		(end 411.452314 -236.01045)
		(width 0.14478)
		(layer "In4.Cu")
		(net "M_J_CPU0_SA_CB<2>")
	)
	(segment
		(start 404.469092 -242.76558)
		(end 404.697184 -242.76558)
		(width 0.14478)
		(layer "In4.Cu")
		(net "M_J_CPU0_SA_CB<2>")
	)
	(segment
		(start 382.557782 -244.97157)
		(end 382.566164 -244.966744)
		(width 0.0889)
		(layer "In4.Cu")
		(net "M_J_CPU0_SA_CB<2>")
	)
	(segment
		(start 406.37333 -240.215928)
		(end 406.601422 -240.215928)
		(width 0.14478)
		(layer "In4.Cu")
		(net "M_J_CPU0_SA_CB<2>")
	)
	(segment
		(start 429.854106 -235.160312)
		(end 434.575458 -235.160312)
		(width 0.14478)
		(layer "In4.Cu")
		(net "M_J_CPU0_SA_CB<2>")
	)
	(segment
		(start 386.683504 -244.966744)
		(end 386.691886 -244.97157)
		(width 0.0889)
		(layer "In4.Cu")
		(net "M_J_CPU0_SA_CB<2>")
	)
	(segment
		(start 406.029668 -241.205004)
		(end 406.25776 -241.205004)
		(width 0.14478)
		(layer "In4.Cu")
		(net "M_J_CPU0_SA_CB<2>")
	)
	(segment
		(start 403.870414 -242.946936)
		(end 403.870414 -242.718844)
		(width 0.14478)
		(layer "In4.Cu")
		(net "M_J_CPU0_SA_CB<2>")
	)
	(segment
		(start 393.084812 -244.92077)
		(end 393.954 -244.92077)
		(width 0.0889)
		(layer "In4.Cu")
		(net "M_J_CPU0_SA_CB<2>")
	)
	(segment
		(start 405.639524 -241.595148)
		(end 405.43099 -241.38636)
		(width 0.14478)
		(layer "In4.Cu")
		(net "M_J_CPU0_SA_CB<2>")
	)
	(segment
		(start 421.580818 -236.01045)
		(end 422.430956 -235.160312)
		(width 0.14478)
		(layer "In4.Cu")
		(net "M_J_CPU0_SA_CB<2>")
	)
	(segment
		(start 404.859236 -242.375436)
		(end 404.650702 -242.166648)
		(width 0.14478)
		(layer "In4.Cu")
		(net "M_J_CPU0_SA_CB<2>")
	)
	(segment
		(start 403.688804 -243.545868)
		(end 403.916896 -243.545868)
		(width 0.14478)
		(layer "In4.Cu")
		(net "M_J_CPU0_SA_CB<2>")
	)
	(segment
		(start 404.812754 -241.776504)
		(end 405.040846 -241.776504)
		(width 0.14478)
		(layer "In4.Cu")
		(net "M_J_CPU0_SA_CB<2>")
	)
	(segment
		(start 417.882324 -235.160312)
		(end 418.732462 -236.01045)
		(width 0.14478)
		(layer "In4.Cu")
		(net "M_J_CPU0_SA_CB<2>")
	)
	(segment
		(start 381.043434 -244.966744)
		(end 381.051816 -244.97157)
		(width 0.0889)
		(layer "In4.Cu")
		(net "M_J_CPU0_SA_CB<2>")
	)
	(segment
		(start 405.43099 -241.38636)
		(end 405.43099 -241.158268)
		(width 0.14478)
		(layer "In4.Cu")
		(net "M_J_CPU0_SA_CB<2>")
	)
	(segment
		(start 434.575458 -235.160312)
		(end 435.000146 -235.585)
		(width 0.14478)
		(layer "In4.Cu")
		(net "M_J_CPU0_SA_CB<2>")
	)
	(segment
		(start 404.078948 -243.155724)
		(end 403.870414 -242.946936)
		(width 0.14478)
		(layer "In4.Cu")
		(net "M_J_CPU0_SA_CB<2>")
	)
	(segment
		(start 404.650702 -242.166648)
		(end 404.650702 -241.938556)
		(width 0.14478)
		(layer "In4.Cu")
		(net "M_J_CPU0_SA_CB<2>")
	)
	(segment
		(start 394.24356 -245.21033)
		(end 394.884148 -245.21033)
		(width 0.0889)
		(layer "In4.Cu")
		(net "M_J_CPU0_SA_CB<2>")
	)
	(segment
		(start 403.090126 -243.499132)
		(end 403.252178 -243.33708)
		(width 0.14478)
		(layer "In4.Cu")
		(net "M_J_CPU0_SA_CB<2>")
	)
	(segment
		(start 405.821134 -240.996216)
		(end 406.029668 -241.205004)
		(width 0.14478)
		(layer "In4.Cu")
		(net "M_J_CPU0_SA_CB<2>")
	)
	(segment
		(start 388.197852 -244.97157)
		(end 388.206234 -244.966744)
		(width 0.0889)
		(layer "In4.Cu")
		(net "M_J_CPU0_SA_CB<2>")
	)
	(segment
		(start 404.650702 -241.938556)
		(end 404.812754 -241.776504)
		(width 0.14478)
		(layer "In4.Cu")
		(net "M_J_CPU0_SA_CB<2>")
	)
	(segment
		(start 405.639524 -241.82324)
		(end 405.639524 -241.595148)
		(width 0.14478)
		(layer "In4.Cu")
		(net "M_J_CPU0_SA_CB<2>")
	)
	(segment
		(start 381.983488 -244.966744)
		(end 381.99187 -244.97157)
		(width 0.0889)
		(layer "In4.Cu")
		(net "M_J_CPU0_SA_CB<2>")
	)
	(segment
		(start 394.884148 -245.21033)
		(end 395.632432 -244.462046)
		(width 0.0889)
		(layer "In4.Cu")
		(net "M_J_CPU0_SA_CB<2>")
	)
	(segment
		(start 404.859236 -242.603528)
		(end 404.859236 -242.375436)
		(width 0.14478)
		(layer "In4.Cu")
		(net "M_J_CPU0_SA_CB<2>")
	)
	(segment
		(start 383.497836 -244.97157)
		(end 383.506218 -244.966744)
		(width 0.0889)
		(layer "In4.Cu")
		(net "M_J_CPU0_SA_CB<2>")
	)
	(segment
		(start 406.419812 -241.042952)
		(end 406.419812 -240.81486)
		(width 0.14478)
		(layer "In4.Cu")
		(net "M_J_CPU0_SA_CB<2>")
	)
	(segment
		(start 395.632432 -244.462046)
		(end 395.85392 -244.462046)
		(width 0.0889)
		(layer "In4.Cu")
		(net "M_J_CPU0_SA_CB<2>")
	)
	(segment
		(start 404.260558 -242.556792)
		(end 404.469092 -242.76558)
		(width 0.14478)
		(layer "In4.Cu")
		(net "M_J_CPU0_SA_CB<2>")
	)
	(segment
		(start 411.452314 -236.01045)
		(end 414.239456 -236.01045)
		(width 0.14478)
		(layer "In4.Cu")
		(net "M_J_CPU0_SA_CB<2>")
	)
	(segment
		(start 395.85392 -244.462046)
		(end 403.000718 -244.462046)
		(width 0.14478)
		(layer "In4.Cu")
		(net "M_J_CPU0_SA_CB<2>")
	)
	(segment
		(start 403.870414 -242.718844)
		(end 404.032466 -242.556792)
		(width 0.14478)
		(layer "In4.Cu")
		(net "M_J_CPU0_SA_CB<2>")
	)
	(segment
		(start 403.48027 -243.33708)
		(end 403.688804 -243.545868)
		(width 0.14478)
		(layer "In4.Cu")
		(net "M_J_CPU0_SA_CB<2>")
	)
	(segment
		(start 403.252178 -243.33708)
		(end 403.48027 -243.33708)
		(width 0.14478)
		(layer "In4.Cu")
		(net "M_J_CPU0_SA_CB<2>")
	)
	(segment
		(start 393.954 -244.92077)
		(end 394.24356 -245.21033)
		(width 0.0889)
		(layer "In4.Cu")
		(net "M_J_CPU0_SA_CB<2>")
	)
	(segment
		(start 425.861988 -235.160312)
		(end 426.712126 -236.01045)
		(width 0.14478)
		(layer "In4.Cu")
		(net "M_J_CPU0_SA_CB<2>")
	)
	(segment
		(start 391.391902 -244.97157)
		(end 391.402316 -244.977666)
		(width 0.0889)
		(layer "In4.Cu")
		(net "M_J_CPU0_SA_CB<2>")
	)
	(segment
		(start 404.697184 -242.76558)
		(end 404.859236 -242.603528)
		(width 0.14478)
		(layer "In4.Cu")
		(net "M_J_CPU0_SA_CB<2>")
	)
	(segment
		(start 406.25776 -241.205004)
		(end 406.419812 -241.042952)
		(width 0.14478)
		(layer "In4.Cu")
		(net "M_J_CPU0_SA_CB<2>")
	)
	(segment
		(start 403.090126 -243.727224)
		(end 403.090126 -243.499132)
		(width 0.14478)
		(layer "In4.Cu")
		(net "M_J_CPU0_SA_CB<2>")
	)
	(arc
		(start 392.892534 -244.975126)
		(mid 392.984966 -244.934844)
		(end 393.084812 -244.92077)
		(width 0.0889)
		(layer "In4.Cu")
		(net "M_J_CPU0_SA_CB<2>")
	)
	(arc
		(start 382.566164 -244.966744)
		(mid 382.749672 -244.92125)
		(end 382.931924 -244.97157)
		(width 0.0889)
		(layer "In4.Cu")
		(net "M_J_CPU0_SA_CB<2>")
	)
	(arc
		(start 381.99187 -244.97157)
		(mid 382.274826 -245.047747)
		(end 382.557782 -244.97157)
		(width 0.0889)
		(layer "In4.Cu")
		(net "M_J_CPU0_SA_CB<2>")
	)
	(arc
		(start 383.871978 -244.97157)
		(mid 384.154934 -245.047747)
		(end 384.43789 -244.97157)
		(width 0.0889)
		(layer "In4.Cu")
		(net "M_J_CPU0_SA_CB<2>")
	)
	(arc
		(start 382.931924 -244.97157)
		(mid 383.21488 -245.047747)
		(end 383.497836 -244.97157)
		(width 0.0889)
		(layer "In4.Cu")
		(net "M_J_CPU0_SA_CB<2>")
	)
	(arc
		(start 383.506218 -244.966744)
		(mid 383.689726 -244.92125)
		(end 383.871978 -244.97157)
		(width 0.0889)
		(layer "In4.Cu")
		(net "M_J_CPU0_SA_CB<2>")
	)
	(arc
		(start 385.37769 -244.97157)
		(mid 385.559941 -244.92122)
		(end 385.74345 -244.966744)
		(width 0.0889)
		(layer "In4.Cu")
		(net "M_J_CPU0_SA_CB<2>")
	)
	(arc
		(start 386.317744 -244.97157)
		(mid 386.499995 -244.92122)
		(end 386.683504 -244.966744)
		(width 0.0889)
		(layer "In4.Cu")
		(net "M_J_CPU0_SA_CB<2>")
	)
	(arc
		(start 386.691886 -244.97157)
		(mid 386.974842 -245.047747)
		(end 387.257798 -244.97157)
		(width 0.0889)
		(layer "In4.Cu")
		(net "M_J_CPU0_SA_CB<2>")
	)
	(arc
		(start 381.051816 -244.97157)
		(mid 381.334772 -245.047747)
		(end 381.617728 -244.97157)
		(width 0.0889)
		(layer "In4.Cu")
		(net "M_J_CPU0_SA_CB<2>")
	)
	(arc
		(start 391.026142 -244.966744)
		(mid 391.20965 -244.92125)
		(end 391.391902 -244.97157)
		(width 0.0889)
		(layer "In4.Cu")
		(net "M_J_CPU0_SA_CB<2>")
	)
	(arc
		(start 384.811778 -244.97157)
		(mid 385.094734 -245.047747)
		(end 385.37769 -244.97157)
		(width 0.0889)
		(layer "In4.Cu")
		(net "M_J_CPU0_SA_CB<2>")
	)
	(arc
		(start 384.43789 -244.97157)
		(mid 384.624834 -244.921315)
		(end 384.811778 -244.97157)
		(width 0.0889)
		(layer "In4.Cu")
		(net "M_J_CPU0_SA_CB<2>")
	)
	(arc
		(start 385.751832 -244.97157)
		(mid 386.034788 -245.047747)
		(end 386.317744 -244.97157)
		(width 0.0889)
		(layer "In4.Cu")
		(net "M_J_CPU0_SA_CB<2>")
	)
	(arc
		(start 391.958068 -244.97157)
		(mid 392.140573 -244.921093)
		(end 392.324336 -244.966744)
		(width 0.0889)
		(layer "In4.Cu")
		(net "M_J_CPU0_SA_CB<2>")
	)
	(arc
		(start 388.571994 -244.97157)
		(mid 388.85495 -245.047747)
		(end 389.137906 -244.97157)
		(width 0.0889)
		(layer "In4.Cu")
		(net "M_J_CPU0_SA_CB<2>")
	)
	(arc
		(start 389.511794 -244.97157)
		(mid 389.79475 -245.047747)
		(end 390.077706 -244.97157)
		(width 0.0889)
		(layer "In4.Cu")
		(net "M_J_CPU0_SA_CB<2>")
	)
	(arc
		(start 387.26618 -244.966744)
		(mid 387.449688 -244.92125)
		(end 387.63194 -244.97157)
		(width 0.0889)
		(layer "In4.Cu")
		(net "M_J_CPU0_SA_CB<2>")
	)
	(arc
		(start 380.733046 -244.945408)
		(mid 380.890556 -244.92221)
		(end 381.043434 -244.966744)
		(width 0.0889)
		(layer "In4.Cu")
		(net "M_J_CPU0_SA_CB<2>")
	)
	(arc
		(start 390.451848 -244.97157)
		(mid 390.734804 -245.047747)
		(end 391.01776 -244.97157)
		(width 0.0889)
		(layer "In4.Cu")
		(net "M_J_CPU0_SA_CB<2>")
	)
	(arc
		(start 381.617728 -244.97157)
		(mid 381.799979 -244.92122)
		(end 381.983488 -244.966744)
		(width 0.0889)
		(layer "In4.Cu")
		(net "M_J_CPU0_SA_CB<2>")
	)
	(arc
		(start 389.137906 -244.97157)
		(mid 389.32485 -244.921315)
		(end 389.511794 -244.97157)
		(width 0.0889)
		(layer "In4.Cu")
		(net "M_J_CPU0_SA_CB<2>")
	)
	(arc
		(start 387.63194 -244.97157)
		(mid 387.914896 -245.047747)
		(end 388.197852 -244.97157)
		(width 0.0889)
		(layer "In4.Cu")
		(net "M_J_CPU0_SA_CB<2>")
	)
	(arc
		(start 390.077706 -244.97157)
		(mid 390.259957 -244.92122)
		(end 390.443466 -244.966744)
		(width 0.0889)
		(layer "In4.Cu")
		(net "M_J_CPU0_SA_CB<2>")
	)
	(arc
		(start 391.402316 -244.977666)
		(mid 391.681002 -245.047886)
		(end 391.958068 -244.97157)
		(width 0.0889)
		(layer "In4.Cu")
		(net "M_J_CPU0_SA_CB<2>")
	)
	(arc
		(start 392.332718 -244.97157)
		(mid 392.612146 -245.047736)
		(end 392.892534 -244.975126)
		(width 0.0889)
		(layer "In4.Cu")
		(net "M_J_CPU0_SA_CB<2>")
	)
	(arc
		(start 388.206234 -244.966744)
		(mid 388.389742 -244.92125)
		(end 388.571994 -244.97157)
		(width 0.0889)
		(layer "In4.Cu")
		(net "M_J_CPU0_SA_CB<2>")
	)
	(segment
		(start 378.517912 -245.560088)
		(end 378.984764 -245.29415)
		(width 0.10668)
		(layer "F.Cu")
		(net "M_J_CPU0_SA_CB<1>")
	)
	(segment
		(start 428.44847 -236.860334)
		(end 430.500282 -236.01045)
		(width 0.14478)
		(layer "In4.Cu")
		(net "M_J_CPU0_SA_CB<1>")
	)
	(segment
		(start 379.138942 -245.55958)
		(end 379.235208 -245.58498)
		(width 0.0889)
		(layer "In4.Cu")
		(net "M_J_CPU0_SA_CB<1>")
	)
	(segment
		(start 387.257798 -245.61673)
		(end 387.26618 -245.621556)
		(width 0.0889)
		(layer "In4.Cu")
		(net "M_J_CPU0_SA_CB<1>")
	)
	(segment
		(start 391.01776 -245.61673)
		(end 391.026142 -245.621556)
		(width 0.0889)
		(layer "In4.Cu")
		(net "M_J_CPU0_SA_CB<1>")
	)
	(segment
		(start 427.354492 -236.860334)
		(end 428.44847 -236.860334)
		(width 0.14478)
		(layer "In4.Cu")
		(net "M_J_CPU0_SA_CB<1>")
	)
	(segment
		(start 382.557782 -245.61673)
		(end 382.566164 -245.621556)
		(width 0.0889)
		(layer "In4.Cu")
		(net "M_J_CPU0_SA_CB<1>")
	)
	(segment
		(start 391.391902 -245.61673)
		(end 391.406634 -245.608094)
		(width 0.0889)
		(layer "In4.Cu")
		(net "M_J_CPU0_SA_CB<1>")
	)
	(segment
		(start 417.394644 -236.01045)
		(end 419.446456 -236.860334)
		(width 0.14478)
		(layer "In4.Cu")
		(net "M_J_CPU0_SA_CB<1>")
	)
	(segment
		(start 392.321034 -245.623588)
		(end 392.332718 -245.61673)
		(width 0.0889)
		(layer "In4.Cu")
		(net "M_J_CPU0_SA_CB<1>")
	)
	(segment
		(start 422.962832 -236.01045)
		(end 425.30268 -236.01045)
		(width 0.14478)
		(layer "In4.Cu")
		(net "M_J_CPU0_SA_CB<1>")
	)
	(segment
		(start 383.497836 -245.61673)
		(end 383.506218 -245.621556)
		(width 0.0889)
		(layer "In4.Cu")
		(net "M_J_CPU0_SA_CB<1>")
	)
	(segment
		(start 419.446456 -236.860334)
		(end 420.91102 -236.860334)
		(width 0.14478)
		(layer "In4.Cu")
		(net "M_J_CPU0_SA_CB<1>")
	)
	(segment
		(start 436.964836 -236.01045)
		(end 439.100214 -236.435138)
		(width 0.14478)
		(layer "In4.Cu")
		(net "M_J_CPU0_SA_CB<1>")
	)
	(segment
		(start 395.5923 -244.916706)
		(end 395.850364 -244.916706)
		(width 0.0889)
		(layer "In4.Cu")
		(net "M_J_CPU0_SA_CB<1>")
	)
	(segment
		(start 388.197852 -245.61673)
		(end 388.206234 -245.621556)
		(width 0.0889)
		(layer "In4.Cu")
		(net "M_J_CPU0_SA_CB<1>")
	)
	(segment
		(start 392.898122 -245.616476)
		(end 392.91641 -245.62689)
		(width 0.0889)
		(layer "In4.Cu")
		(net "M_J_CPU0_SA_CB<1>")
	)
	(segment
		(start 393.823952 -245.608094)
		(end 394.900912 -245.608094)
		(width 0.0889)
		(layer "In4.Cu")
		(net "M_J_CPU0_SA_CB<1>")
	)
	(segment
		(start 413.412178 -236.860334)
		(end 415.46399 -236.01045)
		(width 0.14478)
		(layer "In4.Cu")
		(net "M_J_CPU0_SA_CB<1>")
	)
	(segment
		(start 381.043434 -245.621556)
		(end 381.051816 -245.61673)
		(width 0.0889)
		(layer "In4.Cu")
		(net "M_J_CPU0_SA_CB<1>")
	)
	(segment
		(start 390.443466 -245.621556)
		(end 390.451848 -245.61673)
		(width 0.0889)
		(layer "In4.Cu")
		(net "M_J_CPU0_SA_CB<1>")
	)
	(segment
		(start 386.683504 -245.621556)
		(end 386.691886 -245.61673)
		(width 0.0889)
		(layer "In4.Cu")
		(net "M_J_CPU0_SA_CB<1>")
	)
	(segment
		(start 385.74345 -245.621556)
		(end 385.751832 -245.61673)
		(width 0.0889)
		(layer "In4.Cu")
		(net "M_J_CPU0_SA_CB<1>")
	)
	(segment
		(start 403.182328 -244.916706)
		(end 411.2387 -236.860334)
		(width 0.14478)
		(layer "In4.Cu")
		(net "M_J_CPU0_SA_CB<1>")
	)
	(segment
		(start 392.892534 -245.613174)
		(end 392.898122 -245.616476)
		(width 0.0889)
		(layer "In4.Cu")
		(net "M_J_CPU0_SA_CB<1>")
	)
	(segment
		(start 378.984764 -245.29415)
		(end 379.138942 -245.55958)
		(width 0.0889)
		(layer "In4.Cu")
		(net "M_J_CPU0_SA_CB<1>")
	)
	(segment
		(start 395.850364 -244.916706)
		(end 403.182328 -244.916706)
		(width 0.14478)
		(layer "In4.Cu")
		(net "M_J_CPU0_SA_CB<1>")
	)
	(segment
		(start 425.30268 -236.01045)
		(end 427.354492 -236.860334)
		(width 0.14478)
		(layer "In4.Cu")
		(net "M_J_CPU0_SA_CB<1>")
	)
	(segment
		(start 411.2387 -236.860334)
		(end 413.412178 -236.860334)
		(width 0.14478)
		(layer "In4.Cu")
		(net "M_J_CPU0_SA_CB<1>")
	)
	(segment
		(start 381.983488 -245.621556)
		(end 381.99187 -245.61673)
		(width 0.0889)
		(layer "In4.Cu")
		(net "M_J_CPU0_SA_CB<1>")
	)
	(segment
		(start 430.500282 -236.01045)
		(end 436.964836 -236.01045)
		(width 0.14478)
		(layer "In4.Cu")
		(net "M_J_CPU0_SA_CB<1>")
	)
	(segment
		(start 394.900912 -245.608094)
		(end 395.5923 -244.916706)
		(width 0.0889)
		(layer "In4.Cu")
		(net "M_J_CPU0_SA_CB<1>")
	)
	(segment
		(start 415.46399 -236.01045)
		(end 417.394644 -236.01045)
		(width 0.14478)
		(layer "In4.Cu")
		(net "M_J_CPU0_SA_CB<1>")
	)
	(segment
		(start 420.91102 -236.860334)
		(end 422.962832 -236.01045)
		(width 0.14478)
		(layer "In4.Cu")
		(net "M_J_CPU0_SA_CB<1>")
	)
	(arc
		(start 388.206234 -245.621556)
		(mid 388.389742 -245.66705)
		(end 388.571994 -245.61673)
		(width 0.0889)
		(layer "In4.Cu")
		(net "M_J_CPU0_SA_CB<1>")
	)
	(arc
		(start 383.506218 -245.621556)
		(mid 383.689726 -245.66705)
		(end 383.871978 -245.61673)
		(width 0.0889)
		(layer "In4.Cu")
		(net "M_J_CPU0_SA_CB<1>")
	)
	(arc
		(start 387.26618 -245.621556)
		(mid 387.449688 -245.66705)
		(end 387.63194 -245.61673)
		(width 0.0889)
		(layer "In4.Cu")
		(net "M_J_CPU0_SA_CB<1>")
	)
	(arc
		(start 391.958322 -245.61673)
		(mid 392.13878 -245.667174)
		(end 392.321034 -245.623588)
		(width 0.0889)
		(layer "In4.Cu")
		(net "M_J_CPU0_SA_CB<1>")
	)
	(arc
		(start 384.811778 -245.61673)
		(mid 385.094734 -245.540553)
		(end 385.37769 -245.61673)
		(width 0.0889)
		(layer "In4.Cu")
		(net "M_J_CPU0_SA_CB<1>")
	)
	(arc
		(start 380.111762 -245.61673)
		(mid 380.394718 -245.540553)
		(end 380.677674 -245.61673)
		(width 0.0889)
		(layer "In4.Cu")
		(net "M_J_CPU0_SA_CB<1>")
	)
	(arc
		(start 383.871978 -245.61673)
		(mid 384.154934 -245.540553)
		(end 384.43789 -245.61673)
		(width 0.0889)
		(layer "In4.Cu")
		(net "M_J_CPU0_SA_CB<1>")
	)
	(arc
		(start 387.63194 -245.61673)
		(mid 387.914896 -245.540553)
		(end 388.197852 -245.61673)
		(width 0.0889)
		(layer "In4.Cu")
		(net "M_J_CPU0_SA_CB<1>")
	)
	(arc
		(start 379.737874 -245.61673)
		(mid 379.924818 -245.666985)
		(end 380.111762 -245.61673)
		(width 0.0889)
		(layer "In4.Cu")
		(net "M_J_CPU0_SA_CB<1>")
	)
	(arc
		(start 392.91641 -245.62689)
		(mid 393.095639 -245.667043)
		(end 393.272264 -245.61673)
		(width 0.0889)
		(layer "In4.Cu")
		(net "M_J_CPU0_SA_CB<1>")
	)
	(arc
		(start 384.43789 -245.61673)
		(mid 384.624834 -245.666985)
		(end 384.811778 -245.61673)
		(width 0.0889)
		(layer "In4.Cu")
		(net "M_J_CPU0_SA_CB<1>")
	)
	(arc
		(start 390.451848 -245.61673)
		(mid 390.734804 -245.540553)
		(end 391.01776 -245.61673)
		(width 0.0889)
		(layer "In4.Cu")
		(net "M_J_CPU0_SA_CB<1>")
	)
	(arc
		(start 391.406634 -245.608094)
		(mid 391.683617 -245.54029)
		(end 391.958322 -245.61673)
		(width 0.0889)
		(layer "In4.Cu")
		(net "M_J_CPU0_SA_CB<1>")
	)
	(arc
		(start 382.931924 -245.61673)
		(mid 383.21488 -245.540553)
		(end 383.497836 -245.61673)
		(width 0.0889)
		(layer "In4.Cu")
		(net "M_J_CPU0_SA_CB<1>")
	)
	(arc
		(start 391.026142 -245.621556)
		(mid 391.20965 -245.66705)
		(end 391.391902 -245.61673)
		(width 0.0889)
		(layer "In4.Cu")
		(net "M_J_CPU0_SA_CB<1>")
	)
	(arc
		(start 389.511794 -245.61673)
		(mid 389.79475 -245.540553)
		(end 390.077706 -245.61673)
		(width 0.0889)
		(layer "In4.Cu")
		(net "M_J_CPU0_SA_CB<1>")
	)
	(arc
		(start 381.99187 -245.61673)
		(mid 382.274826 -245.540553)
		(end 382.557782 -245.61673)
		(width 0.0889)
		(layer "In4.Cu")
		(net "M_J_CPU0_SA_CB<1>")
	)
	(arc
		(start 381.051816 -245.61673)
		(mid 381.334772 -245.540553)
		(end 381.617728 -245.61673)
		(width 0.0889)
		(layer "In4.Cu")
		(net "M_J_CPU0_SA_CB<1>")
	)
	(arc
		(start 385.37769 -245.61673)
		(mid 385.559941 -245.66708)
		(end 385.74345 -245.621556)
		(width 0.0889)
		(layer "In4.Cu")
		(net "M_J_CPU0_SA_CB<1>")
	)
	(arc
		(start 385.751832 -245.61673)
		(mid 386.034788 -245.540553)
		(end 386.317744 -245.61673)
		(width 0.0889)
		(layer "In4.Cu")
		(net "M_J_CPU0_SA_CB<1>")
	)
	(arc
		(start 386.691886 -245.61673)
		(mid 386.974842 -245.540553)
		(end 387.257798 -245.61673)
		(width 0.0889)
		(layer "In4.Cu")
		(net "M_J_CPU0_SA_CB<1>")
	)
	(arc
		(start 382.566164 -245.621556)
		(mid 382.749672 -245.66705)
		(end 382.931924 -245.61673)
		(width 0.0889)
		(layer "In4.Cu")
		(net "M_J_CPU0_SA_CB<1>")
	)
	(arc
		(start 390.077706 -245.61673)
		(mid 390.259957 -245.66708)
		(end 390.443466 -245.621556)
		(width 0.0889)
		(layer "In4.Cu")
		(net "M_J_CPU0_SA_CB<1>")
	)
	(arc
		(start 381.617728 -245.61673)
		(mid 381.799979 -245.66708)
		(end 381.983488 -245.621556)
		(width 0.0889)
		(layer "In4.Cu")
		(net "M_J_CPU0_SA_CB<1>")
	)
	(arc
		(start 386.317744 -245.61673)
		(mid 386.499995 -245.66708)
		(end 386.683504 -245.621556)
		(width 0.0889)
		(layer "In4.Cu")
		(net "M_J_CPU0_SA_CB<1>")
	)
	(arc
		(start 392.332718 -245.61673)
		(mid 392.612146 -245.540564)
		(end 392.892534 -245.613174)
		(width 0.0889)
		(layer "In4.Cu")
		(net "M_J_CPU0_SA_CB<1>")
	)
	(arc
		(start 379.235208 -245.58498)
		(mid 379.490273 -245.541629)
		(end 379.737874 -245.61673)
		(width 0.0889)
		(layer "In4.Cu")
		(net "M_J_CPU0_SA_CB<1>")
	)
	(arc
		(start 380.677674 -245.61673)
		(mid 380.859925 -245.66708)
		(end 381.043434 -245.621556)
		(width 0.0889)
		(layer "In4.Cu")
		(net "M_J_CPU0_SA_CB<1>")
	)
	(arc
		(start 388.571994 -245.61673)
		(mid 388.85495 -245.540553)
		(end 389.137906 -245.61673)
		(width 0.0889)
		(layer "In4.Cu")
		(net "M_J_CPU0_SA_CB<1>")
	)
	(arc
		(start 393.272264 -245.61673)
		(mid 393.54697 -245.540366)
		(end 393.823952 -245.608094)
		(width 0.0889)
		(layer "In4.Cu")
		(net "M_J_CPU0_SA_CB<1>")
	)
	(arc
		(start 389.137906 -245.61673)
		(mid 389.32485 -245.666985)
		(end 389.511794 -245.61673)
		(width 0.0889)
		(layer "In4.Cu")
		(net "M_J_CPU0_SA_CB<1>")
	)
	(segment
		(start 379.927866 -244.750082)
		(end 380.394718 -244.484144)
		(width 0.10668)
		(layer "F.Cu")
		(net "M_J_CPU0_SA_CB<0>")
	)
	(segment
		(start 380.394718 -244.484144)
		(end 380.548896 -244.749574)
		(width 0.0889)
		(layer "In4.Cu")
		(net "M_J_CPU0_SA_CB<0>")
	)
	(segment
		(start 407.060146 -239.766348)
		(end 411.666182 -235.160312)
		(width 0.14478)
		(layer "In4.Cu")
		(net "M_J_CPU0_SA_CB<0>")
	)
	(segment
		(start 389.033512 -244.81155)
		(end 389.041894 -244.806724)
		(width 0.0889)
		(layer "In4.Cu")
		(net "M_J_CPU0_SA_CB<0>")
	)
	(segment
		(start 384.90779 -244.806724)
		(end 384.916172 -244.81155)
		(width 0.0889)
		(layer "In4.Cu")
		(net "M_J_CPU0_SA_CB<0>")
	)
	(segment
		(start 406.186894 -239.766348)
		(end 407.060146 -239.766348)
		(width 0.14478)
		(layer "In4.Cu")
		(net "M_J_CPU0_SA_CB<0>")
	)
	(segment
		(start 425.692062 -234.310428)
		(end 426.541946 -235.160312)
		(width 0.14478)
		(layer "In4.Cu")
		(net "M_J_CPU0_SA_CB<0>")
	)
	(segment
		(start 417.71697 -234.310428)
		(end 418.566854 -235.160312)
		(width 0.14478)
		(layer "In4.Cu")
		(net "M_J_CPU0_SA_CB<0>")
	)
	(segment
		(start 394.419836 -244.38991)
		(end 395.03858 -244.38991)
		(width 0.0889)
		(layer "In4.Cu")
		(net "M_J_CPU0_SA_CB<0>")
	)
	(segment
		(start 391.48766 -244.806724)
		(end 391.496042 -244.81155)
		(width 0.0889)
		(layer "In4.Cu")
		(net "M_J_CPU0_SA_CB<0>")
	)
	(segment
		(start 380.548896 -244.749574)
		(end 380.645162 -244.774974)
		(width 0.0889)
		(layer "In4.Cu")
		(net "M_J_CPU0_SA_CB<0>")
	)
	(segment
		(start 384.333496 -244.81155)
		(end 384.341878 -244.806724)
		(width 0.0889)
		(layer "In4.Cu")
		(net "M_J_CPU0_SA_CB<0>")
	)
	(segment
		(start 389.607806 -244.806724)
		(end 389.616188 -244.81155)
		(width 0.0889)
		(layer "In4.Cu")
		(net "M_J_CPU0_SA_CB<0>")
	)
	(segment
		(start 421.625014 -235.160312)
		(end 422.474898 -234.310428)
		(width 0.14478)
		(layer "In4.Cu")
		(net "M_J_CPU0_SA_CB<0>")
	)
	(segment
		(start 411.666182 -235.160312)
		(end 414.446212 -235.160312)
		(width 0.14478)
		(layer "In4.Cu")
		(net "M_J_CPU0_SA_CB<0>")
	)
	(segment
		(start 393.084812 -244.73027)
		(end 394.079476 -244.73027)
		(width 0.0889)
		(layer "In4.Cu")
		(net "M_J_CPU0_SA_CB<0>")
	)
	(segment
		(start 392.418062 -244.800628)
		(end 392.428476 -244.806724)
		(width 0.0889)
		(layer "In4.Cu")
		(net "M_J_CPU0_SA_CB<0>")
	)
	(segment
		(start 418.566854 -235.160312)
		(end 421.625014 -235.160312)
		(width 0.14478)
		(layer "In4.Cu")
		(net "M_J_CPU0_SA_CB<0>")
	)
	(segment
		(start 436.964836 -234.310428)
		(end 439.100214 -234.735116)
		(width 0.14478)
		(layer "In4.Cu")
		(net "M_J_CPU0_SA_CB<0>")
	)
	(segment
		(start 401.958302 -243.99494)
		(end 406.186894 -239.766348)
		(width 0.14478)
		(layer "In4.Cu")
		(net "M_J_CPU0_SA_CB<0>")
	)
	(segment
		(start 426.541946 -235.160312)
		(end 429.167544 -235.160312)
		(width 0.14478)
		(layer "In4.Cu")
		(net "M_J_CPU0_SA_CB<0>")
	)
	(segment
		(start 388.093458 -244.81155)
		(end 388.10184 -244.806724)
		(width 0.0889)
		(layer "In4.Cu")
		(net "M_J_CPU0_SA_CB<0>")
	)
	(segment
		(start 385.847844 -244.806724)
		(end 385.856226 -244.81155)
		(width 0.0889)
		(layer "In4.Cu")
		(net "M_J_CPU0_SA_CB<0>")
	)
	(segment
		(start 395.43355 -243.99494)
		(end 395.642846 -243.99494)
		(width 0.0889)
		(layer "In4.Cu")
		(net "M_J_CPU0_SA_CB<0>")
	)
	(segment
		(start 395.642846 -243.99494)
		(end 401.958302 -243.99494)
		(width 0.14478)
		(layer "In4.Cu")
		(net "M_J_CPU0_SA_CB<0>")
	)
	(segment
		(start 395.03858 -244.38991)
		(end 395.43355 -243.99494)
		(width 0.0889)
		(layer "In4.Cu")
		(net "M_J_CPU0_SA_CB<0>")
	)
	(segment
		(start 415.296096 -234.310428)
		(end 417.71697 -234.310428)
		(width 0.14478)
		(layer "In4.Cu")
		(net "M_J_CPU0_SA_CB<0>")
	)
	(segment
		(start 429.167544 -235.160312)
		(end 430.017428 -234.310428)
		(width 0.14478)
		(layer "In4.Cu")
		(net "M_J_CPU0_SA_CB<0>")
	)
	(segment
		(start 394.079476 -244.73027)
		(end 394.419836 -244.38991)
		(width 0.0889)
		(layer "In4.Cu")
		(net "M_J_CPU0_SA_CB<0>")
	)
	(segment
		(start 381.147828 -244.806724)
		(end 381.15621 -244.81155)
		(width 0.0889)
		(layer "In4.Cu")
		(net "M_J_CPU0_SA_CB<0>")
	)
	(segment
		(start 414.446212 -235.160312)
		(end 415.296096 -234.310428)
		(width 0.14478)
		(layer "In4.Cu")
		(net "M_J_CPU0_SA_CB<0>")
	)
	(segment
		(start 383.393442 -244.81155)
		(end 383.401824 -244.806724)
		(width 0.0889)
		(layer "In4.Cu")
		(net "M_J_CPU0_SA_CB<0>")
	)
	(segment
		(start 430.017428 -234.310428)
		(end 436.964836 -234.310428)
		(width 0.14478)
		(layer "In4.Cu")
		(net "M_J_CPU0_SA_CB<0>")
	)
	(segment
		(start 422.474898 -234.310428)
		(end 425.692062 -234.310428)
		(width 0.14478)
		(layer "In4.Cu")
		(net "M_J_CPU0_SA_CB<0>")
	)
	(arc
		(start 389.616188 -244.81155)
		(mid 389.799696 -244.857044)
		(end 389.981948 -244.806724)
		(width 0.0889)
		(layer "In4.Cu")
		(net "M_J_CPU0_SA_CB<0>")
	)
	(arc
		(start 381.52197 -244.806724)
		(mid 381.804926 -244.730547)
		(end 382.087882 -244.806724)
		(width 0.0889)
		(layer "In4.Cu")
		(net "M_J_CPU0_SA_CB<0>")
	)
	(arc
		(start 384.341878 -244.806724)
		(mid 384.624834 -244.730547)
		(end 384.90779 -244.806724)
		(width 0.0889)
		(layer "In4.Cu")
		(net "M_J_CPU0_SA_CB<0>")
	)
	(arc
		(start 383.027682 -244.806724)
		(mid 383.209933 -244.857074)
		(end 383.393442 -244.81155)
		(width 0.0889)
		(layer "In4.Cu")
		(net "M_J_CPU0_SA_CB<0>")
	)
	(arc
		(start 386.787898 -244.806724)
		(mid 386.974842 -244.856979)
		(end 387.161786 -244.806724)
		(width 0.0889)
		(layer "In4.Cu")
		(net "M_J_CPU0_SA_CB<0>")
	)
	(arc
		(start 391.496042 -244.81155)
		(mid 391.679804 -244.857166)
		(end 391.86231 -244.806724)
		(width 0.0889)
		(layer "In4.Cu")
		(net "M_J_CPU0_SA_CB<0>")
	)
	(arc
		(start 380.645162 -244.774974)
		(mid 380.900227 -244.731623)
		(end 381.147828 -244.806724)
		(width 0.0889)
		(layer "In4.Cu")
		(net "M_J_CPU0_SA_CB<0>")
	)
	(arc
		(start 390.921748 -244.806724)
		(mid 391.204704 -244.730547)
		(end 391.48766 -244.806724)
		(width 0.0889)
		(layer "In4.Cu")
		(net "M_J_CPU0_SA_CB<0>")
	)
	(arc
		(start 392.786108 -244.815868)
		(mid 392.929447 -244.752081)
		(end 393.084812 -244.73027)
		(width 0.0889)
		(layer "In4.Cu")
		(net "M_J_CPU0_SA_CB<0>")
	)
	(arc
		(start 389.041894 -244.806724)
		(mid 389.32485 -244.730547)
		(end 389.607806 -244.806724)
		(width 0.0889)
		(layer "In4.Cu")
		(net "M_J_CPU0_SA_CB<0>")
	)
	(arc
		(start 385.856226 -244.81155)
		(mid 386.039734 -244.857044)
		(end 386.221986 -244.806724)
		(width 0.0889)
		(layer "In4.Cu")
		(net "M_J_CPU0_SA_CB<0>")
	)
	(arc
		(start 382.46177 -244.806724)
		(mid 382.744726 -244.730547)
		(end 383.027682 -244.806724)
		(width 0.0889)
		(layer "In4.Cu")
		(net "M_J_CPU0_SA_CB<0>")
	)
	(arc
		(start 383.967736 -244.806724)
		(mid 384.149987 -244.857074)
		(end 384.333496 -244.81155)
		(width 0.0889)
		(layer "In4.Cu")
		(net "M_J_CPU0_SA_CB<0>")
	)
	(arc
		(start 387.727698 -244.806724)
		(mid 387.909949 -244.857074)
		(end 388.093458 -244.81155)
		(width 0.0889)
		(layer "In4.Cu")
		(net "M_J_CPU0_SA_CB<0>")
	)
	(arc
		(start 388.667752 -244.806724)
		(mid 388.850003 -244.857074)
		(end 389.033512 -244.81155)
		(width 0.0889)
		(layer "In4.Cu")
		(net "M_J_CPU0_SA_CB<0>")
	)
	(arc
		(start 391.86231 -244.806724)
		(mid 392.139377 -244.730453)
		(end 392.418062 -244.800628)
		(width 0.0889)
		(layer "In4.Cu")
		(net "M_J_CPU0_SA_CB<0>")
	)
	(arc
		(start 382.087882 -244.806724)
		(mid 382.274826 -244.856979)
		(end 382.46177 -244.806724)
		(width 0.0889)
		(layer "In4.Cu")
		(net "M_J_CPU0_SA_CB<0>")
	)
	(arc
		(start 390.54786 -244.806724)
		(mid 390.734804 -244.856979)
		(end 390.921748 -244.806724)
		(width 0.0889)
		(layer "In4.Cu")
		(net "M_J_CPU0_SA_CB<0>")
	)
	(arc
		(start 387.161786 -244.806724)
		(mid 387.444742 -244.730547)
		(end 387.727698 -244.806724)
		(width 0.0889)
		(layer "In4.Cu")
		(net "M_J_CPU0_SA_CB<0>")
	)
	(arc
		(start 389.981948 -244.806724)
		(mid 390.264904 -244.730547)
		(end 390.54786 -244.806724)
		(width 0.0889)
		(layer "In4.Cu")
		(net "M_J_CPU0_SA_CB<0>")
	)
	(arc
		(start 388.10184 -244.806724)
		(mid 388.384796 -244.730547)
		(end 388.667752 -244.806724)
		(width 0.0889)
		(layer "In4.Cu")
		(net "M_J_CPU0_SA_CB<0>")
	)
	(arc
		(start 381.15621 -244.81155)
		(mid 381.339718 -244.857044)
		(end 381.52197 -244.806724)
		(width 0.0889)
		(layer "In4.Cu")
		(net "M_J_CPU0_SA_CB<0>")
	)
	(arc
		(start 386.221986 -244.806724)
		(mid 386.504942 -244.730547)
		(end 386.787898 -244.806724)
		(width 0.0889)
		(layer "In4.Cu")
		(net "M_J_CPU0_SA_CB<0>")
	)
	(arc
		(start 384.916172 -244.81155)
		(mid 385.09968 -244.857044)
		(end 385.281932 -244.806724)
		(width 0.0889)
		(layer "In4.Cu")
		(net "M_J_CPU0_SA_CB<0>")
	)
	(arc
		(start 383.401824 -244.806724)
		(mid 383.68478 -244.730547)
		(end 383.967736 -244.806724)
		(width 0.0889)
		(layer "In4.Cu")
		(net "M_J_CPU0_SA_CB<0>")
	)
	(arc
		(start 392.428476 -244.806724)
		(mid 392.606126 -244.856984)
		(end 392.786108 -244.815868)
		(width 0.0889)
		(layer "In4.Cu")
		(net "M_J_CPU0_SA_CB<0>")
	)
	(arc
		(start 385.281932 -244.806724)
		(mid 385.564888 -244.730547)
		(end 385.847844 -244.806724)
		(width 0.0889)
		(layer "In4.Cu")
		(net "M_J_CPU0_SA_CB<0>")
	)
	(segment
		(start 378.517912 -255.28016)
		(end 378.984764 -255.014222)
		(width 0.10668)
		(layer "F.Cu")
		(net "M_J_CPU0_SA_CA<6>")
	)
	(segment
		(start 391.391902 -255.336802)
		(end 391.406634 -255.328166)
		(width 0.0889)
		(layer "In4.Cu")
		(net "M_J_CPU0_SA_CA<6>")
	)
	(segment
		(start 394.155676 -255.69799)
		(end 395.494256 -255.69799)
		(width 0.0889)
		(layer "In4.Cu")
		(net "M_J_CPU0_SA_CA<6>")
	)
	(segment
		(start 411.984952 -254.710184)
		(end 431.796444 -254.710184)
		(width 0.14478)
		(layer "In4.Cu")
		(net "M_J_CPU0_SA_CA<6>")
	)
	(segment
		(start 411.434026 -255.26111)
		(end 411.984952 -254.710184)
		(width 0.14478)
		(layer "In4.Cu")
		(net "M_J_CPU0_SA_CA<6>")
	)
	(segment
		(start 383.497836 -255.336802)
		(end 383.506218 -255.341628)
		(width 0.0889)
		(layer "In4.Cu")
		(net "M_J_CPU0_SA_CA<6>")
	)
	(segment
		(start 393.272264 -255.336802)
		(end 393.277852 -255.331214)
		(width 0.0889)
		(layer "In4.Cu")
		(net "M_J_CPU0_SA_CA<6>")
	)
	(segment
		(start 388.197852 -255.336802)
		(end 388.206234 -255.341628)
		(width 0.0889)
		(layer "In4.Cu")
		(net "M_J_CPU0_SA_CA<6>")
	)
	(segment
		(start 393.277852 -255.331214)
		(end 393.7889 -255.331214)
		(width 0.0889)
		(layer "In4.Cu")
		(net "M_J_CPU0_SA_CA<6>")
	)
	(segment
		(start 387.257798 -255.336802)
		(end 387.26618 -255.341628)
		(width 0.0889)
		(layer "In4.Cu")
		(net "M_J_CPU0_SA_CA<6>")
	)
	(segment
		(start 378.984764 -255.014222)
		(end 379.138942 -255.279652)
		(width 0.0889)
		(layer "In4.Cu")
		(net "M_J_CPU0_SA_CA<6>")
	)
	(segment
		(start 381.043434 -255.341628)
		(end 381.051816 -255.336802)
		(width 0.0889)
		(layer "In4.Cu")
		(net "M_J_CPU0_SA_CA<6>")
	)
	(segment
		(start 392.321034 -255.34366)
		(end 392.332718 -255.336802)
		(width 0.0889)
		(layer "In4.Cu")
		(net "M_J_CPU0_SA_CA<6>")
	)
	(segment
		(start 434.763164 -252.217174)
		(end 434.769768 -252.217174)
		(width 0.0889)
		(layer "In4.Cu")
		(net "M_J_CPU0_SA_CA<6>")
	)
	(segment
		(start 382.557782 -255.336802)
		(end 382.566164 -255.341628)
		(width 0.0889)
		(layer "In4.Cu")
		(net "M_J_CPU0_SA_CA<6>")
	)
	(segment
		(start 393.7889 -255.331214)
		(end 394.155676 -255.69799)
		(width 0.0889)
		(layer "In4.Cu")
		(net "M_J_CPU0_SA_CA<6>")
	)
	(segment
		(start 381.983488 -255.341628)
		(end 381.99187 -255.336802)
		(width 0.0889)
		(layer "In4.Cu")
		(net "M_J_CPU0_SA_CA<6>")
	)
	(segment
		(start 435.185566 -252.160024)
		(end 438.675272 -252.160024)
		(width 0.14478)
		(layer "In4.Cu")
		(net "M_J_CPU0_SA_CA<6>")
	)
	(segment
		(start 379.138942 -255.279652)
		(end 379.235208 -255.305052)
		(width 0.0889)
		(layer "In4.Cu")
		(net "M_J_CPU0_SA_CA<6>")
	)
	(segment
		(start 431.796444 -254.710184)
		(end 432.377596 -254.129032)
		(width 0.14478)
		(layer "In4.Cu")
		(net "M_J_CPU0_SA_CA<6>")
	)
	(segment
		(start 403.766528 -254.715772)
		(end 404.311866 -255.26111)
		(width 0.14478)
		(layer "In4.Cu")
		(net "M_J_CPU0_SA_CA<6>")
	)
	(segment
		(start 404.311866 -255.26111)
		(end 411.434026 -255.26111)
		(width 0.14478)
		(layer "In4.Cu")
		(net "M_J_CPU0_SA_CA<6>")
	)
	(segment
		(start 390.443466 -255.341628)
		(end 390.451848 -255.336802)
		(width 0.0889)
		(layer "In4.Cu")
		(net "M_J_CPU0_SA_CA<6>")
	)
	(segment
		(start 386.683504 -255.341628)
		(end 386.691886 -255.336802)
		(width 0.0889)
		(layer "In4.Cu")
		(net "M_J_CPU0_SA_CA<6>")
	)
	(segment
		(start 392.892534 -255.333246)
		(end 392.898122 -255.336548)
		(width 0.0889)
		(layer "In4.Cu")
		(net "M_J_CPU0_SA_CA<6>")
	)
	(segment
		(start 432.377596 -253.611634)
		(end 433.58054 -252.40869)
		(width 0.14478)
		(layer "In4.Cu")
		(net "M_J_CPU0_SA_CA<6>")
	)
	(segment
		(start 399.788634 -254.715772)
		(end 403.766528 -254.715772)
		(width 0.14478)
		(layer "In4.Cu")
		(net "M_J_CPU0_SA_CA<6>")
	)
	(segment
		(start 391.01776 -255.336802)
		(end 391.026142 -255.341628)
		(width 0.0889)
		(layer "In4.Cu")
		(net "M_J_CPU0_SA_CA<6>")
	)
	(segment
		(start 433.58054 -252.40869)
		(end 434.571648 -252.40869)
		(width 0.14478)
		(layer "In4.Cu")
		(net "M_J_CPU0_SA_CA<6>")
	)
	(segment
		(start 398.806416 -255.69799)
		(end 399.788634 -254.715772)
		(width 0.14478)
		(layer "In4.Cu")
		(net "M_J_CPU0_SA_CA<6>")
	)
	(segment
		(start 432.377596 -254.129032)
		(end 432.377596 -253.611634)
		(width 0.14478)
		(layer "In4.Cu")
		(net "M_J_CPU0_SA_CA<6>")
	)
	(segment
		(start 434.826918 -252.160024)
		(end 435.185566 -252.160024)
		(width 0.0889)
		(layer "In4.Cu")
		(net "M_J_CPU0_SA_CA<6>")
	)
	(segment
		(start 392.898122 -255.336548)
		(end 392.91641 -255.346962)
		(width 0.0889)
		(layer "In4.Cu")
		(net "M_J_CPU0_SA_CA<6>")
	)
	(segment
		(start 395.494256 -255.69799)
		(end 398.806416 -255.69799)
		(width 0.14478)
		(layer "In4.Cu")
		(net "M_J_CPU0_SA_CA<6>")
	)
	(segment
		(start 434.769768 -252.217174)
		(end 434.826918 -252.160024)
		(width 0.0889)
		(layer "In4.Cu")
		(net "M_J_CPU0_SA_CA<6>")
	)
	(segment
		(start 385.74345 -255.341628)
		(end 385.751832 -255.336802)
		(width 0.0889)
		(layer "In4.Cu")
		(net "M_J_CPU0_SA_CA<6>")
	)
	(segment
		(start 434.571648 -252.40869)
		(end 434.763164 -252.217174)
		(width 0.14478)
		(layer "In4.Cu")
		(net "M_J_CPU0_SA_CA<6>")
	)
	(segment
		(start 438.675272 -252.160024)
		(end 439.100214 -252.584966)
		(width 0.14478)
		(layer "In4.Cu")
		(net "M_J_CPU0_SA_CA<6>")
	)
	(arc
		(start 388.206234 -255.341628)
		(mid 388.389742 -255.387122)
		(end 388.571994 -255.336802)
		(width 0.0889)
		(layer "In4.Cu")
		(net "M_J_CPU0_SA_CA<6>")
	)
	(arc
		(start 384.43789 -255.336802)
		(mid 384.624834 -255.387057)
		(end 384.811778 -255.336802)
		(width 0.0889)
		(layer "In4.Cu")
		(net "M_J_CPU0_SA_CA<6>")
	)
	(arc
		(start 390.451848 -255.336802)
		(mid 390.734804 -255.260625)
		(end 391.01776 -255.336802)
		(width 0.0889)
		(layer "In4.Cu")
		(net "M_J_CPU0_SA_CA<6>")
	)
	(arc
		(start 379.235208 -255.305052)
		(mid 379.490273 -255.261701)
		(end 379.737874 -255.336802)
		(width 0.0889)
		(layer "In4.Cu")
		(net "M_J_CPU0_SA_CA<6>")
	)
	(arc
		(start 380.677674 -255.336802)
		(mid 380.859925 -255.387152)
		(end 381.043434 -255.341628)
		(width 0.0889)
		(layer "In4.Cu")
		(net "M_J_CPU0_SA_CA<6>")
	)
	(arc
		(start 383.871978 -255.336802)
		(mid 384.154934 -255.260625)
		(end 384.43789 -255.336802)
		(width 0.0889)
		(layer "In4.Cu")
		(net "M_J_CPU0_SA_CA<6>")
	)
	(arc
		(start 381.051816 -255.336802)
		(mid 381.334772 -255.260625)
		(end 381.617728 -255.336802)
		(width 0.0889)
		(layer "In4.Cu")
		(net "M_J_CPU0_SA_CA<6>")
	)
	(arc
		(start 380.111762 -255.336802)
		(mid 380.394718 -255.260625)
		(end 380.677674 -255.336802)
		(width 0.0889)
		(layer "In4.Cu")
		(net "M_J_CPU0_SA_CA<6>")
	)
	(arc
		(start 385.37769 -255.336802)
		(mid 385.559941 -255.387152)
		(end 385.74345 -255.341628)
		(width 0.0889)
		(layer "In4.Cu")
		(net "M_J_CPU0_SA_CA<6>")
	)
	(arc
		(start 391.406634 -255.328166)
		(mid 391.683617 -255.260362)
		(end 391.958322 -255.336802)
		(width 0.0889)
		(layer "In4.Cu")
		(net "M_J_CPU0_SA_CA<6>")
	)
	(arc
		(start 383.506218 -255.341628)
		(mid 383.689726 -255.387122)
		(end 383.871978 -255.336802)
		(width 0.0889)
		(layer "In4.Cu")
		(net "M_J_CPU0_SA_CA<6>")
	)
	(arc
		(start 382.566164 -255.341628)
		(mid 382.749672 -255.387122)
		(end 382.931924 -255.336802)
		(width 0.0889)
		(layer "In4.Cu")
		(net "M_J_CPU0_SA_CA<6>")
	)
	(arc
		(start 382.931924 -255.336802)
		(mid 383.21488 -255.260625)
		(end 383.497836 -255.336802)
		(width 0.0889)
		(layer "In4.Cu")
		(net "M_J_CPU0_SA_CA<6>")
	)
	(arc
		(start 381.617728 -255.336802)
		(mid 381.799979 -255.387152)
		(end 381.983488 -255.341628)
		(width 0.0889)
		(layer "In4.Cu")
		(net "M_J_CPU0_SA_CA<6>")
	)
	(arc
		(start 381.99187 -255.336802)
		(mid 382.274826 -255.260625)
		(end 382.557782 -255.336802)
		(width 0.0889)
		(layer "In4.Cu")
		(net "M_J_CPU0_SA_CA<6>")
	)
	(arc
		(start 391.026142 -255.341628)
		(mid 391.20965 -255.387122)
		(end 391.391902 -255.336802)
		(width 0.0889)
		(layer "In4.Cu")
		(net "M_J_CPU0_SA_CA<6>")
	)
	(arc
		(start 379.737874 -255.336802)
		(mid 379.924818 -255.387057)
		(end 380.111762 -255.336802)
		(width 0.0889)
		(layer "In4.Cu")
		(net "M_J_CPU0_SA_CA<6>")
	)
	(arc
		(start 392.91641 -255.346962)
		(mid 393.095639 -255.387115)
		(end 393.272264 -255.336802)
		(width 0.0889)
		(layer "In4.Cu")
		(net "M_J_CPU0_SA_CA<6>")
	)
	(arc
		(start 387.63194 -255.336802)
		(mid 387.914896 -255.260625)
		(end 388.197852 -255.336802)
		(width 0.0889)
		(layer "In4.Cu")
		(net "M_J_CPU0_SA_CA<6>")
	)
	(arc
		(start 389.511794 -255.336802)
		(mid 389.79475 -255.260625)
		(end 390.077706 -255.336802)
		(width 0.0889)
		(layer "In4.Cu")
		(net "M_J_CPU0_SA_CA<6>")
	)
	(arc
		(start 386.317744 -255.336802)
		(mid 386.499995 -255.387152)
		(end 386.683504 -255.341628)
		(width 0.0889)
		(layer "In4.Cu")
		(net "M_J_CPU0_SA_CA<6>")
	)
	(arc
		(start 392.332718 -255.336802)
		(mid 392.612146 -255.260636)
		(end 392.892534 -255.333246)
		(width 0.0889)
		(layer "In4.Cu")
		(net "M_J_CPU0_SA_CA<6>")
	)
	(arc
		(start 390.077706 -255.336802)
		(mid 390.259957 -255.387152)
		(end 390.443466 -255.341628)
		(width 0.0889)
		(layer "In4.Cu")
		(net "M_J_CPU0_SA_CA<6>")
	)
	(arc
		(start 391.958322 -255.336802)
		(mid 392.13878 -255.387246)
		(end 392.321034 -255.34366)
		(width 0.0889)
		(layer "In4.Cu")
		(net "M_J_CPU0_SA_CA<6>")
	)
	(arc
		(start 384.811778 -255.336802)
		(mid 385.094734 -255.260625)
		(end 385.37769 -255.336802)
		(width 0.0889)
		(layer "In4.Cu")
		(net "M_J_CPU0_SA_CA<6>")
	)
	(arc
		(start 387.26618 -255.341628)
		(mid 387.449688 -255.387122)
		(end 387.63194 -255.336802)
		(width 0.0889)
		(layer "In4.Cu")
		(net "M_J_CPU0_SA_CA<6>")
	)
	(arc
		(start 385.751832 -255.336802)
		(mid 386.034788 -255.260625)
		(end 386.317744 -255.336802)
		(width 0.0889)
		(layer "In4.Cu")
		(net "M_J_CPU0_SA_CA<6>")
	)
	(arc
		(start 389.137906 -255.336802)
		(mid 389.32485 -255.387057)
		(end 389.511794 -255.336802)
		(width 0.0889)
		(layer "In4.Cu")
		(net "M_J_CPU0_SA_CA<6>")
	)
	(arc
		(start 388.571994 -255.336802)
		(mid 388.85495 -255.260625)
		(end 389.137906 -255.336802)
		(width 0.0889)
		(layer "In4.Cu")
		(net "M_J_CPU0_SA_CA<6>")
	)
	(arc
		(start 386.691886 -255.336802)
		(mid 386.974842 -255.260625)
		(end 387.257798 -255.336802)
		(width 0.0889)
		(layer "In4.Cu")
		(net "M_J_CPU0_SA_CA<6>")
	)
	(segment
		(start 380.39802 -255.28016)
		(end 380.864872 -255.014222)
		(width 0.10668)
		(layer "F.Cu")
		(net "M_J_CPU0_SA_CA<5>")
	)
	(segment
		(start 405.892254 -254.427736)
		(end 406.053798 -254.266192)
		(width 0.14478)
		(layer "In4.Cu")
		(net "M_J_CPU0_SA_CA<5>")
	)
	(segment
		(start 432.083718 -253.010162)
		(end 433.358798 -251.735082)
		(width 0.14478)
		(layer "In4.Cu")
		(net "M_J_CPU0_SA_CA<5>")
	)
	(segment
		(start 405.34082 -254.602488)
		(end 405.502364 -254.764032)
		(width 0.14478)
		(layer "In4.Cu")
		(net "M_J_CPU0_SA_CA<5>")
	)
	(segment
		(start 409.362402 -254.266192)
		(end 410.085032 -254.266192)
		(width 0.14478)
		(layer "In4.Cu")
		(net "M_J_CPU0_SA_CA<5>")
	)
	(segment
		(start 410.491178 -253.860046)
		(end 429.492918 -253.860046)
		(width 0.14478)
		(layer "In4.Cu")
		(net "M_J_CPU0_SA_CA<5>")
	)
	(segment
		(start 407.546556 -254.427736)
		(end 407.546556 -254.602488)
		(width 0.14478)
		(layer "In4.Cu")
		(net "M_J_CPU0_SA_CA<5>")
	)
	(segment
		(start 394.429996 -255.24079)
		(end 395.522196 -255.24079)
		(width 0.0889)
		(layer "In4.Cu")
		(net "M_J_CPU0_SA_CA<5>")
	)
	(segment
		(start 407.385012 -254.266192)
		(end 407.546556 -254.427736)
		(width 0.14478)
		(layer "In4.Cu")
		(net "M_J_CPU0_SA_CA<5>")
	)
	(segment
		(start 407.156666 -254.266192)
		(end 407.385012 -254.266192)
		(width 0.14478)
		(layer "In4.Cu")
		(net "M_J_CPU0_SA_CA<5>")
	)
	(segment
		(start 392.898122 -254.691896)
		(end 392.91641 -254.681482)
		(width 0.0889)
		(layer "In4.Cu")
		(net "M_J_CPU0_SA_CA<5>")
	)
	(segment
		(start 406.833578 -254.764032)
		(end 406.995122 -254.602488)
		(width 0.14478)
		(layer "In4.Cu")
		(net "M_J_CPU0_SA_CA<5>")
	)
	(segment
		(start 393.272264 -254.691642)
		(end 393.356338 -254.74041)
		(width 0.0889)
		(layer "In4.Cu")
		(net "M_J_CPU0_SA_CA<5>")
	)
	(segment
		(start 405.502364 -254.764032)
		(end 405.73071 -254.764032)
		(width 0.14478)
		(layer "In4.Cu")
		(net "M_J_CPU0_SA_CA<5>")
	)
	(segment
		(start 429.492918 -253.860046)
		(end 430.342802 -253.010162)
		(width 0.14478)
		(layer "In4.Cu")
		(net "M_J_CPU0_SA_CA<5>")
	)
	(segment
		(start 408.259534 -254.266192)
		(end 408.48788 -254.266192)
		(width 0.14478)
		(layer "In4.Cu")
		(net "M_J_CPU0_SA_CA<5>")
	)
	(segment
		(start 408.810968 -254.764032)
		(end 409.039314 -254.764032)
		(width 0.14478)
		(layer "In4.Cu")
		(net "M_J_CPU0_SA_CA<5>")
	)
	(segment
		(start 398.59077 -255.24079)
		(end 399.565368 -254.266192)
		(width 0.14478)
		(layer "In4.Cu")
		(net "M_J_CPU0_SA_CA<5>")
	)
	(segment
		(start 388.197852 -254.691642)
		(end 388.206234 -254.686816)
		(width 0.0889)
		(layer "In4.Cu")
		(net "M_J_CPU0_SA_CA<5>")
	)
	(segment
		(start 386.683504 -254.686816)
		(end 386.691886 -254.691642)
		(width 0.0889)
		(layer "In4.Cu")
		(net "M_J_CPU0_SA_CA<5>")
	)
	(segment
		(start 392.892534 -254.695198)
		(end 392.898122 -254.691896)
		(width 0.0889)
		(layer "In4.Cu")
		(net "M_J_CPU0_SA_CA<5>")
	)
	(segment
		(start 430.342802 -253.010162)
		(end 432.083718 -253.010162)
		(width 0.14478)
		(layer "In4.Cu")
		(net "M_J_CPU0_SA_CA<5>")
	)
	(segment
		(start 409.200858 -254.602488)
		(end 409.200858 -254.427736)
		(width 0.14478)
		(layer "In4.Cu")
		(net "M_J_CPU0_SA_CA<5>")
	)
	(segment
		(start 393.95019 -254.760984)
		(end 394.429996 -255.24079)
		(width 0.0889)
		(layer "In4.Cu")
		(net "M_J_CPU0_SA_CA<5>")
	)
	(segment
		(start 406.995122 -254.602488)
		(end 406.995122 -254.427736)
		(width 0.14478)
		(layer "In4.Cu")
		(net "M_J_CPU0_SA_CA<5>")
	)
	(segment
		(start 410.085032 -254.266192)
		(end 410.491178 -253.860046)
		(width 0.14478)
		(layer "In4.Cu")
		(net "M_J_CPU0_SA_CA<5>")
	)
	(segment
		(start 391.391902 -254.691642)
		(end 391.402316 -254.697738)
		(width 0.0889)
		(layer "In4.Cu")
		(net "M_J_CPU0_SA_CA<5>")
	)
	(segment
		(start 407.7081 -254.764032)
		(end 407.936446 -254.764032)
		(width 0.14478)
		(layer "In4.Cu")
		(net "M_J_CPU0_SA_CA<5>")
	)
	(segment
		(start 408.09799 -254.427736)
		(end 408.259534 -254.266192)
		(width 0.14478)
		(layer "In4.Cu")
		(net "M_J_CPU0_SA_CA<5>")
	)
	(segment
		(start 381.983488 -254.686816)
		(end 381.99187 -254.691642)
		(width 0.0889)
		(layer "In4.Cu")
		(net "M_J_CPU0_SA_CA<5>")
	)
	(segment
		(start 380.710694 -254.748792)
		(end 380.733046 -254.66548)
		(width 0.0889)
		(layer "In4.Cu")
		(net "M_J_CPU0_SA_CA<5>")
	)
	(segment
		(start 409.200858 -254.427736)
		(end 409.362402 -254.266192)
		(width 0.14478)
		(layer "In4.Cu")
		(net "M_J_CPU0_SA_CA<5>")
	)
	(segment
		(start 407.546556 -254.602488)
		(end 407.7081 -254.764032)
		(width 0.14478)
		(layer "In4.Cu")
		(net "M_J_CPU0_SA_CA<5>")
	)
	(segment
		(start 408.649424 -254.427736)
		(end 408.649424 -254.602488)
		(width 0.14478)
		(layer "In4.Cu")
		(net "M_J_CPU0_SA_CA<5>")
	)
	(segment
		(start 392.324336 -254.686816)
		(end 392.332718 -254.691642)
		(width 0.0889)
		(layer "In4.Cu")
		(net "M_J_CPU0_SA_CA<5>")
	)
	(segment
		(start 407.936446 -254.764032)
		(end 408.09799 -254.602488)
		(width 0.14478)
		(layer "In4.Cu")
		(net "M_J_CPU0_SA_CA<5>")
	)
	(segment
		(start 382.557782 -254.691642)
		(end 382.566164 -254.686816)
		(width 0.0889)
		(layer "In4.Cu")
		(net "M_J_CPU0_SA_CA<5>")
	)
	(segment
		(start 409.039314 -254.764032)
		(end 409.200858 -254.602488)
		(width 0.14478)
		(layer "In4.Cu")
		(net "M_J_CPU0_SA_CA<5>")
	)
	(segment
		(start 406.443688 -254.427736)
		(end 406.443688 -254.602488)
		(width 0.14478)
		(layer "In4.Cu")
		(net "M_J_CPU0_SA_CA<5>")
	)
	(segment
		(start 385.74345 -254.686816)
		(end 385.751832 -254.691642)
		(width 0.0889)
		(layer "In4.Cu")
		(net "M_J_CPU0_SA_CA<5>")
	)
	(segment
		(start 433.358798 -251.735082)
		(end 435.000146 -251.735082)
		(width 0.14478)
		(layer "In4.Cu")
		(net "M_J_CPU0_SA_CA<5>")
	)
	(segment
		(start 405.73071 -254.764032)
		(end 405.892254 -254.602488)
		(width 0.14478)
		(layer "In4.Cu")
		(net "M_J_CPU0_SA_CA<5>")
	)
	(segment
		(start 406.443688 -254.602488)
		(end 406.605232 -254.764032)
		(width 0.14478)
		(layer "In4.Cu")
		(net "M_J_CPU0_SA_CA<5>")
	)
	(segment
		(start 405.179276 -254.266192)
		(end 405.34082 -254.427736)
		(width 0.14478)
		(layer "In4.Cu")
		(net "M_J_CPU0_SA_CA<5>")
	)
	(segment
		(start 399.565368 -254.266192)
		(end 405.179276 -254.266192)
		(width 0.14478)
		(layer "In4.Cu")
		(net "M_J_CPU0_SA_CA<5>")
	)
	(segment
		(start 406.995122 -254.427736)
		(end 407.156666 -254.266192)
		(width 0.14478)
		(layer "In4.Cu")
		(net "M_J_CPU0_SA_CA<5>")
	)
	(segment
		(start 408.48788 -254.266192)
		(end 408.649424 -254.427736)
		(width 0.14478)
		(layer "In4.Cu")
		(net "M_J_CPU0_SA_CA<5>")
	)
	(segment
		(start 395.522196 -255.24079)
		(end 398.59077 -255.24079)
		(width 0.14478)
		(layer "In4.Cu")
		(net "M_J_CPU0_SA_CA<5>")
	)
	(segment
		(start 405.34082 -254.427736)
		(end 405.34082 -254.602488)
		(width 0.14478)
		(layer "In4.Cu")
		(net "M_J_CPU0_SA_CA<5>")
	)
	(segment
		(start 391.01776 -254.691642)
		(end 391.026142 -254.686816)
		(width 0.0889)
		(layer "In4.Cu")
		(net "M_J_CPU0_SA_CA<5>")
	)
	(segment
		(start 406.053798 -254.266192)
		(end 406.282144 -254.266192)
		(width 0.14478)
		(layer "In4.Cu")
		(net "M_J_CPU0_SA_CA<5>")
	)
	(segment
		(start 405.892254 -254.602488)
		(end 405.892254 -254.427736)
		(width 0.14478)
		(layer "In4.Cu")
		(net "M_J_CPU0_SA_CA<5>")
	)
	(segment
		(start 390.443466 -254.686816)
		(end 390.451848 -254.691642)
		(width 0.0889)
		(layer "In4.Cu")
		(net "M_J_CPU0_SA_CA<5>")
	)
	(segment
		(start 393.432792 -254.760984)
		(end 393.95019 -254.760984)
		(width 0.0889)
		(layer "In4.Cu")
		(net "M_J_CPU0_SA_CA<5>")
	)
	(segment
		(start 408.649424 -254.602488)
		(end 408.810968 -254.764032)
		(width 0.14478)
		(layer "In4.Cu")
		(net "M_J_CPU0_SA_CA<5>")
	)
	(segment
		(start 383.497836 -254.691642)
		(end 383.506218 -254.686816)
		(width 0.0889)
		(layer "In4.Cu")
		(net "M_J_CPU0_SA_CA<5>")
	)
	(segment
		(start 406.605232 -254.764032)
		(end 406.833578 -254.764032)
		(width 0.14478)
		(layer "In4.Cu")
		(net "M_J_CPU0_SA_CA<5>")
	)
	(segment
		(start 380.864872 -255.014222)
		(end 380.710694 -254.748792)
		(width 0.0889)
		(layer "In4.Cu")
		(net "M_J_CPU0_SA_CA<5>")
	)
	(segment
		(start 406.282144 -254.266192)
		(end 406.443688 -254.427736)
		(width 0.14478)
		(layer "In4.Cu")
		(net "M_J_CPU0_SA_CA<5>")
	)
	(segment
		(start 387.257798 -254.691642)
		(end 387.26618 -254.686816)
		(width 0.0889)
		(layer "In4.Cu")
		(net "M_J_CPU0_SA_CA<5>")
	)
	(segment
		(start 408.09799 -254.602488)
		(end 408.09799 -254.427736)
		(width 0.14478)
		(layer "In4.Cu")
		(net "M_J_CPU0_SA_CA<5>")
	)
	(segment
		(start 381.043434 -254.686816)
		(end 381.051816 -254.691642)
		(width 0.0889)
		(layer "In4.Cu")
		(net "M_J_CPU0_SA_CA<5>")
	)
	(arc
		(start 382.931924 -254.691642)
		(mid 383.21488 -254.767819)
		(end 383.497836 -254.691642)
		(width 0.0889)
		(layer "In4.Cu")
		(net "M_J_CPU0_SA_CA<5>")
	)
	(arc
		(start 381.051816 -254.691642)
		(mid 381.334772 -254.767819)
		(end 381.617728 -254.691642)
		(width 0.0889)
		(layer "In4.Cu")
		(net "M_J_CPU0_SA_CA<5>")
	)
	(arc
		(start 392.91641 -254.681482)
		(mid 393.095639 -254.641329)
		(end 393.272264 -254.691642)
		(width 0.0889)
		(layer "In4.Cu")
		(net "M_J_CPU0_SA_CA<5>")
	)
	(arc
		(start 385.37769 -254.691642)
		(mid 385.559941 -254.641292)
		(end 385.74345 -254.686816)
		(width 0.0889)
		(layer "In4.Cu")
		(net "M_J_CPU0_SA_CA<5>")
	)
	(arc
		(start 384.811778 -254.691642)
		(mid 385.094734 -254.767819)
		(end 385.37769 -254.691642)
		(width 0.0889)
		(layer "In4.Cu")
		(net "M_J_CPU0_SA_CA<5>")
	)
	(arc
		(start 383.506218 -254.686816)
		(mid 383.689726 -254.641322)
		(end 383.871978 -254.691642)
		(width 0.0889)
		(layer "In4.Cu")
		(net "M_J_CPU0_SA_CA<5>")
	)
	(arc
		(start 389.137906 -254.691642)
		(mid 389.32485 -254.641387)
		(end 389.511794 -254.691642)
		(width 0.0889)
		(layer "In4.Cu")
		(net "M_J_CPU0_SA_CA<5>")
	)
	(arc
		(start 385.751832 -254.691642)
		(mid 386.034788 -254.767819)
		(end 386.317744 -254.691642)
		(width 0.0889)
		(layer "In4.Cu")
		(net "M_J_CPU0_SA_CA<5>")
	)
	(arc
		(start 387.26618 -254.686816)
		(mid 387.449688 -254.641322)
		(end 387.63194 -254.691642)
		(width 0.0889)
		(layer "In4.Cu")
		(net "M_J_CPU0_SA_CA<5>")
	)
	(arc
		(start 390.077706 -254.691642)
		(mid 390.259957 -254.641292)
		(end 390.443466 -254.686816)
		(width 0.0889)
		(layer "In4.Cu")
		(net "M_J_CPU0_SA_CA<5>")
	)
	(arc
		(start 389.511794 -254.691642)
		(mid 389.79475 -254.767819)
		(end 390.077706 -254.691642)
		(width 0.0889)
		(layer "In4.Cu")
		(net "M_J_CPU0_SA_CA<5>")
	)
	(arc
		(start 393.356338 -254.74041)
		(mid 393.393206 -254.755745)
		(end 393.432792 -254.760984)
		(width 0.0889)
		(layer "In4.Cu")
		(net "M_J_CPU0_SA_CA<5>")
	)
	(arc
		(start 392.332718 -254.691642)
		(mid 392.612146 -254.767808)
		(end 392.892534 -254.695198)
		(width 0.0889)
		(layer "In4.Cu")
		(net "M_J_CPU0_SA_CA<5>")
	)
	(arc
		(start 384.43789 -254.691642)
		(mid 384.624834 -254.641387)
		(end 384.811778 -254.691642)
		(width 0.0889)
		(layer "In4.Cu")
		(net "M_J_CPU0_SA_CA<5>")
	)
	(arc
		(start 391.958068 -254.691642)
		(mid 392.140573 -254.641165)
		(end 392.324336 -254.686816)
		(width 0.0889)
		(layer "In4.Cu")
		(net "M_J_CPU0_SA_CA<5>")
	)
	(arc
		(start 382.566164 -254.686816)
		(mid 382.749672 -254.641322)
		(end 382.931924 -254.691642)
		(width 0.0889)
		(layer "In4.Cu")
		(net "M_J_CPU0_SA_CA<5>")
	)
	(arc
		(start 390.451848 -254.691642)
		(mid 390.734804 -254.767819)
		(end 391.01776 -254.691642)
		(width 0.0889)
		(layer "In4.Cu")
		(net "M_J_CPU0_SA_CA<5>")
	)
	(arc
		(start 388.571994 -254.691642)
		(mid 388.85495 -254.767819)
		(end 389.137906 -254.691642)
		(width 0.0889)
		(layer "In4.Cu")
		(net "M_J_CPU0_SA_CA<5>")
	)
	(arc
		(start 381.99187 -254.691642)
		(mid 382.274826 -254.767819)
		(end 382.557782 -254.691642)
		(width 0.0889)
		(layer "In4.Cu")
		(net "M_J_CPU0_SA_CA<5>")
	)
	(arc
		(start 388.206234 -254.686816)
		(mid 388.389742 -254.641322)
		(end 388.571994 -254.691642)
		(width 0.0889)
		(layer "In4.Cu")
		(net "M_J_CPU0_SA_CA<5>")
	)
	(arc
		(start 387.63194 -254.691642)
		(mid 387.914896 -254.767819)
		(end 388.197852 -254.691642)
		(width 0.0889)
		(layer "In4.Cu")
		(net "M_J_CPU0_SA_CA<5>")
	)
	(arc
		(start 380.733046 -254.66548)
		(mid 380.890556 -254.642282)
		(end 381.043434 -254.686816)
		(width 0.0889)
		(layer "In4.Cu")
		(net "M_J_CPU0_SA_CA<5>")
	)
	(arc
		(start 386.317744 -254.691642)
		(mid 386.499995 -254.641292)
		(end 386.683504 -254.686816)
		(width 0.0889)
		(layer "In4.Cu")
		(net "M_J_CPU0_SA_CA<5>")
	)
	(arc
		(start 381.617728 -254.691642)
		(mid 381.799979 -254.641292)
		(end 381.983488 -254.686816)
		(width 0.0889)
		(layer "In4.Cu")
		(net "M_J_CPU0_SA_CA<5>")
	)
	(arc
		(start 391.402316 -254.697738)
		(mid 391.681002 -254.767958)
		(end 391.958068 -254.691642)
		(width 0.0889)
		(layer "In4.Cu")
		(net "M_J_CPU0_SA_CA<5>")
	)
	(arc
		(start 383.871978 -254.691642)
		(mid 384.154934 -254.767819)
		(end 384.43789 -254.691642)
		(width 0.0889)
		(layer "In4.Cu")
		(net "M_J_CPU0_SA_CA<5>")
	)
	(arc
		(start 386.691886 -254.691642)
		(mid 386.974842 -254.767819)
		(end 387.257798 -254.691642)
		(width 0.0889)
		(layer "In4.Cu")
		(net "M_J_CPU0_SA_CA<5>")
	)
	(arc
		(start 391.026142 -254.686816)
		(mid 391.20965 -254.641322)
		(end 391.391902 -254.691642)
		(width 0.0889)
		(layer "In4.Cu")
		(net "M_J_CPU0_SA_CA<5>")
	)
	(segment
		(start 379.927866 -254.470154)
		(end 380.394718 -254.204216)
		(width 0.10668)
		(layer "F.Cu")
		(net "M_J_CPU0_SA_CA<4>")
	)
	(segment
		(start 383.393442 -254.531622)
		(end 383.401824 -254.526796)
		(width 0.0889)
		(layer "In4.Cu")
		(net "M_J_CPU0_SA_CA<4>")
	)
	(segment
		(start 438.675018 -251.31014)
		(end 439.100214 -250.884944)
		(width 0.14478)
		(layer "In4.Cu")
		(net "M_J_CPU0_SA_CA<4>")
	)
	(segment
		(start 391.48766 -254.526796)
		(end 391.496042 -254.531622)
		(width 0.0889)
		(layer "In4.Cu")
		(net "M_J_CPU0_SA_CA<4>")
	)
	(segment
		(start 434.826918 -251.31014)
		(end 435.185566 -251.31014)
		(width 0.0889)
		(layer "In4.Cu")
		(net "M_J_CPU0_SA_CA<4>")
	)
	(segment
		(start 434.763164 -251.25299)
		(end 434.769768 -251.25299)
		(width 0.0889)
		(layer "In4.Cu")
		(net "M_J_CPU0_SA_CA<4>")
	)
	(segment
		(start 435.185566 -251.31014)
		(end 438.675018 -251.31014)
		(width 0.14478)
		(layer "In4.Cu")
		(net "M_J_CPU0_SA_CA<4>")
	)
	(segment
		(start 393.529312 -254.57023)
		(end 394.219176 -254.57023)
		(width 0.0889)
		(layer "In4.Cu")
		(net "M_J_CPU0_SA_CA<4>")
	)
	(segment
		(start 380.548896 -254.469646)
		(end 380.645162 -254.495046)
		(width 0.0889)
		(layer "In4.Cu")
		(net "M_J_CPU0_SA_CA<4>")
	)
	(segment
		(start 434.769768 -251.25299)
		(end 434.826918 -251.31014)
		(width 0.0889)
		(layer "In4.Cu")
		(net "M_J_CPU0_SA_CA<4>")
	)
	(segment
		(start 398.374616 -254.77597)
		(end 399.333974 -253.816612)
		(width 0.14478)
		(layer "In4.Cu")
		(net "M_J_CPU0_SA_CA<4>")
	)
	(segment
		(start 394.526516 -254.87757)
		(end 394.987018 -254.87757)
		(width 0.0889)
		(layer "In4.Cu")
		(net "M_J_CPU0_SA_CA<4>")
	)
	(segment
		(start 384.333496 -254.531622)
		(end 384.341878 -254.526796)
		(width 0.0889)
		(layer "In4.Cu")
		(net "M_J_CPU0_SA_CA<4>")
	)
	(segment
		(start 381.147828 -254.526796)
		(end 381.15621 -254.531622)
		(width 0.0889)
		(layer "In4.Cu")
		(net "M_J_CPU0_SA_CA<4>")
	)
	(segment
		(start 430.192942 -252.160024)
		(end 431.84318 -252.160024)
		(width 0.14478)
		(layer "In4.Cu")
		(net "M_J_CPU0_SA_CA<4>")
	)
	(segment
		(start 385.847844 -254.526796)
		(end 385.856226 -254.531622)
		(width 0.0889)
		(layer "In4.Cu")
		(net "M_J_CPU0_SA_CA<4>")
	)
	(segment
		(start 388.093458 -254.531622)
		(end 388.10184 -254.526796)
		(width 0.0889)
		(layer "In4.Cu")
		(net "M_J_CPU0_SA_CA<4>")
	)
	(segment
		(start 431.84318 -252.160024)
		(end 432.922934 -251.08027)
		(width 0.14478)
		(layer "In4.Cu")
		(net "M_J_CPU0_SA_CA<4>")
	)
	(segment
		(start 432.922934 -251.08027)
		(end 434.590444 -251.08027)
		(width 0.14478)
		(layer "In4.Cu")
		(net "M_J_CPU0_SA_CA<4>")
	)
	(segment
		(start 434.590444 -251.08027)
		(end 434.763164 -251.25299)
		(width 0.14478)
		(layer "In4.Cu")
		(net "M_J_CPU0_SA_CA<4>")
	)
	(segment
		(start 392.418062 -254.5207)
		(end 392.428476 -254.526796)
		(width 0.0889)
		(layer "In4.Cu")
		(net "M_J_CPU0_SA_CA<4>")
	)
	(segment
		(start 380.394718 -254.204216)
		(end 380.548896 -254.469646)
		(width 0.0889)
		(layer "In4.Cu")
		(net "M_J_CPU0_SA_CA<4>")
	)
	(segment
		(start 394.987018 -254.87757)
		(end 395.088618 -254.77597)
		(width 0.0889)
		(layer "In4.Cu")
		(net "M_J_CPU0_SA_CA<4>")
	)
	(segment
		(start 392.786108 -254.53594)
		(end 392.802364 -254.526542)
		(width 0.0889)
		(layer "In4.Cu")
		(net "M_J_CPU0_SA_CA<4>")
	)
	(segment
		(start 409.898342 -253.816612)
		(end 410.704792 -253.010162)
		(width 0.14478)
		(layer "In4.Cu")
		(net "M_J_CPU0_SA_CA<4>")
	)
	(segment
		(start 389.033512 -254.531622)
		(end 389.041894 -254.526796)
		(width 0.0889)
		(layer "In4.Cu")
		(net "M_J_CPU0_SA_CA<4>")
	)
	(segment
		(start 399.333974 -253.816612)
		(end 409.898342 -253.816612)
		(width 0.14478)
		(layer "In4.Cu")
		(net "M_J_CPU0_SA_CA<4>")
	)
	(segment
		(start 394.219176 -254.57023)
		(end 394.526516 -254.87757)
		(width 0.0889)
		(layer "In4.Cu")
		(net "M_J_CPU0_SA_CA<4>")
	)
	(segment
		(start 389.607806 -254.526796)
		(end 389.616188 -254.531622)
		(width 0.0889)
		(layer "In4.Cu")
		(net "M_J_CPU0_SA_CA<4>")
	)
	(segment
		(start 429.342804 -253.010162)
		(end 430.192942 -252.160024)
		(width 0.14478)
		(layer "In4.Cu")
		(net "M_J_CPU0_SA_CA<4>")
	)
	(segment
		(start 384.90779 -254.526796)
		(end 384.916172 -254.531622)
		(width 0.0889)
		(layer "In4.Cu")
		(net "M_J_CPU0_SA_CA<4>")
	)
	(segment
		(start 395.80312 -254.77597)
		(end 398.374616 -254.77597)
		(width 0.14478)
		(layer "In4.Cu")
		(net "M_J_CPU0_SA_CA<4>")
	)
	(segment
		(start 392.802364 -254.526542)
		(end 392.818112 -254.517398)
		(width 0.0889)
		(layer "In4.Cu")
		(net "M_J_CPU0_SA_CA<4>")
	)
	(segment
		(start 410.704792 -253.010162)
		(end 429.342804 -253.010162)
		(width 0.14478)
		(layer "In4.Cu")
		(net "M_J_CPU0_SA_CA<4>")
	)
	(segment
		(start 395.088618 -254.77597)
		(end 395.80312 -254.77597)
		(width 0.0889)
		(layer "In4.Cu")
		(net "M_J_CPU0_SA_CA<4>")
	)
	(arc
		(start 382.46177 -254.526796)
		(mid 382.744726 -254.450619)
		(end 383.027682 -254.526796)
		(width 0.0889)
		(layer "In4.Cu")
		(net "M_J_CPU0_SA_CA<4>")
	)
	(arc
		(start 387.727698 -254.526796)
		(mid 387.909949 -254.577146)
		(end 388.093458 -254.531622)
		(width 0.0889)
		(layer "In4.Cu")
		(net "M_J_CPU0_SA_CA<4>")
	)
	(arc
		(start 384.916172 -254.531622)
		(mid 385.09968 -254.577116)
		(end 385.281932 -254.526796)
		(width 0.0889)
		(layer "In4.Cu")
		(net "M_J_CPU0_SA_CA<4>")
	)
	(arc
		(start 385.281932 -254.526796)
		(mid 385.564888 -254.450619)
		(end 385.847844 -254.526796)
		(width 0.0889)
		(layer "In4.Cu")
		(net "M_J_CPU0_SA_CA<4>")
	)
	(arc
		(start 388.10184 -254.526796)
		(mid 388.384796 -254.450619)
		(end 388.667752 -254.526796)
		(width 0.0889)
		(layer "In4.Cu")
		(net "M_J_CPU0_SA_CA<4>")
	)
	(arc
		(start 383.027682 -254.526796)
		(mid 383.209933 -254.577146)
		(end 383.393442 -254.531622)
		(width 0.0889)
		(layer "In4.Cu")
		(net "M_J_CPU0_SA_CA<4>")
	)
	(arc
		(start 389.041894 -254.526796)
		(mid 389.32485 -254.450619)
		(end 389.607806 -254.526796)
		(width 0.0889)
		(layer "In4.Cu")
		(net "M_J_CPU0_SA_CA<4>")
	)
	(arc
		(start 391.496042 -254.531622)
		(mid 391.679804 -254.577238)
		(end 391.86231 -254.526796)
		(width 0.0889)
		(layer "In4.Cu")
		(net "M_J_CPU0_SA_CA<4>")
	)
	(arc
		(start 381.52197 -254.526796)
		(mid 381.804926 -254.450619)
		(end 382.087882 -254.526796)
		(width 0.0889)
		(layer "In4.Cu")
		(net "M_J_CPU0_SA_CA<4>")
	)
	(arc
		(start 385.856226 -254.531622)
		(mid 386.039734 -254.577116)
		(end 386.221986 -254.526796)
		(width 0.0889)
		(layer "In4.Cu")
		(net "M_J_CPU0_SA_CA<4>")
	)
	(arc
		(start 390.921748 -254.526796)
		(mid 391.204704 -254.450619)
		(end 391.48766 -254.526796)
		(width 0.0889)
		(layer "In4.Cu")
		(net "M_J_CPU0_SA_CA<4>")
	)
	(arc
		(start 388.667752 -254.526796)
		(mid 388.850003 -254.577146)
		(end 389.033512 -254.531622)
		(width 0.0889)
		(layer "In4.Cu")
		(net "M_J_CPU0_SA_CA<4>")
	)
	(arc
		(start 384.341878 -254.526796)
		(mid 384.624834 -254.450619)
		(end 384.90779 -254.526796)
		(width 0.0889)
		(layer "In4.Cu")
		(net "M_J_CPU0_SA_CA<4>")
	)
	(arc
		(start 386.221986 -254.526796)
		(mid 386.504942 -254.450619)
		(end 386.787898 -254.526796)
		(width 0.0889)
		(layer "In4.Cu")
		(net "M_J_CPU0_SA_CA<4>")
	)
	(arc
		(start 393.368276 -254.526796)
		(mid 393.445922 -254.559151)
		(end 393.529312 -254.57023)
		(width 0.0889)
		(layer "In4.Cu")
		(net "M_J_CPU0_SA_CA<4>")
	)
	(arc
		(start 381.15621 -254.531622)
		(mid 381.339718 -254.577116)
		(end 381.52197 -254.526796)
		(width 0.0889)
		(layer "In4.Cu")
		(net "M_J_CPU0_SA_CA<4>")
	)
	(arc
		(start 389.616188 -254.531622)
		(mid 389.799696 -254.577116)
		(end 389.981948 -254.526796)
		(width 0.0889)
		(layer "In4.Cu")
		(net "M_J_CPU0_SA_CA<4>")
	)
	(arc
		(start 392.818112 -254.517398)
		(mid 393.094421 -254.450422)
		(end 393.368276 -254.526796)
		(width 0.0889)
		(layer "In4.Cu")
		(net "M_J_CPU0_SA_CA<4>")
	)
	(arc
		(start 392.428476 -254.526796)
		(mid 392.606126 -254.577056)
		(end 392.786108 -254.53594)
		(width 0.0889)
		(layer "In4.Cu")
		(net "M_J_CPU0_SA_CA<4>")
	)
	(arc
		(start 383.967736 -254.526796)
		(mid 384.149987 -254.577146)
		(end 384.333496 -254.531622)
		(width 0.0889)
		(layer "In4.Cu")
		(net "M_J_CPU0_SA_CA<4>")
	)
	(arc
		(start 389.981948 -254.526796)
		(mid 390.264904 -254.450619)
		(end 390.54786 -254.526796)
		(width 0.0889)
		(layer "In4.Cu")
		(net "M_J_CPU0_SA_CA<4>")
	)
	(arc
		(start 380.645162 -254.495046)
		(mid 380.900227 -254.451695)
		(end 381.147828 -254.526796)
		(width 0.0889)
		(layer "In4.Cu")
		(net "M_J_CPU0_SA_CA<4>")
	)
	(arc
		(start 387.161786 -254.526796)
		(mid 387.444742 -254.450619)
		(end 387.727698 -254.526796)
		(width 0.0889)
		(layer "In4.Cu")
		(net "M_J_CPU0_SA_CA<4>")
	)
	(arc
		(start 390.54786 -254.526796)
		(mid 390.734804 -254.577051)
		(end 390.921748 -254.526796)
		(width 0.0889)
		(layer "In4.Cu")
		(net "M_J_CPU0_SA_CA<4>")
	)
	(arc
		(start 383.401824 -254.526796)
		(mid 383.68478 -254.450619)
		(end 383.967736 -254.526796)
		(width 0.0889)
		(layer "In4.Cu")
		(net "M_J_CPU0_SA_CA<4>")
	)
	(arc
		(start 391.86231 -254.526796)
		(mid 392.139377 -254.450525)
		(end 392.418062 -254.5207)
		(width 0.0889)
		(layer "In4.Cu")
		(net "M_J_CPU0_SA_CA<4>")
	)
	(arc
		(start 386.787898 -254.526796)
		(mid 386.974842 -254.577051)
		(end 387.161786 -254.526796)
		(width 0.0889)
		(layer "In4.Cu")
		(net "M_J_CPU0_SA_CA<4>")
	)
	(arc
		(start 382.087882 -254.526796)
		(mid 382.274826 -254.577051)
		(end 382.46177 -254.526796)
		(width 0.0889)
		(layer "In4.Cu")
		(net "M_J_CPU0_SA_CA<4>")
	)
	(segment
		(start 378.988066 -254.470154)
		(end 379.454918 -254.204216)
		(width 0.10668)
		(layer "F.Cu")
		(net "M_J_CPU0_SA_CA<3>")
	)
	(segment
		(start 392.788648 -253.874016)
		(end 392.802364 -253.88189)
		(width 0.0889)
		(layer "In4.Cu")
		(net "M_J_CPU0_SA_CA<3>")
	)
	(segment
		(start 413.667702 -252.460252)
		(end 413.918908 -252.460252)
		(width 0.14478)
		(layer "In4.Cu")
		(net "M_J_CPU0_SA_CA<3>")
	)
	(segment
		(start 413.918908 -252.460252)
		(end 414.219136 -252.160024)
		(width 0.14478)
		(layer "In4.Cu")
		(net "M_J_CPU0_SA_CA<3>")
	)
	(segment
		(start 384.333496 -253.87681)
		(end 384.341878 -253.881636)
		(width 0.0889)
		(layer "In4.Cu")
		(net "M_J_CPU0_SA_CA<3>")
	)
	(segment
		(start 393.958064 -254.10033)
		(end 394.993876 -254.10033)
		(width 0.0889)
		(layer "In4.Cu")
		(net "M_J_CPU0_SA_CA<3>")
	)
	(segment
		(start 429.292766 -252.160024)
		(end 430.992788 -250.460002)
		(width 0.14478)
		(layer "In4.Cu")
		(net "M_J_CPU0_SA_CA<3>")
	)
	(segment
		(start 384.90779 -253.881636)
		(end 384.916172 -253.87681)
		(width 0.0889)
		(layer "In4.Cu")
		(net "M_J_CPU0_SA_CA<3>")
	)
	(segment
		(start 389.607806 -253.881636)
		(end 389.616188 -253.87681)
		(width 0.0889)
		(layer "In4.Cu")
		(net "M_J_CPU0_SA_CA<3>")
	)
	(segment
		(start 392.802364 -253.88189)
		(end 392.818112 -253.891034)
		(width 0.0889)
		(layer "In4.Cu")
		(net "M_J_CPU0_SA_CA<3>")
	)
	(segment
		(start 393.734544 -253.87681)
		(end 393.958064 -254.10033)
		(width 0.0889)
		(layer "In4.Cu")
		(net "M_J_CPU0_SA_CA<3>")
	)
	(segment
		(start 391.48766 -253.881636)
		(end 391.496042 -253.87681)
		(width 0.0889)
		(layer "In4.Cu")
		(net "M_J_CPU0_SA_CA<3>")
	)
	(segment
		(start 392.413998 -253.890272)
		(end 392.42873 -253.881636)
		(width 0.0889)
		(layer "In4.Cu")
		(net "M_J_CPU0_SA_CA<3>")
	)
	(segment
		(start 416.124644 -252.460252)
		(end 416.424872 -252.160024)
		(width 0.14478)
		(layer "In4.Cu")
		(net "M_J_CPU0_SA_CA<3>")
	)
	(segment
		(start 417.52774 -252.160024)
		(end 429.292766 -252.160024)
		(width 0.14478)
		(layer "In4.Cu")
		(net "M_J_CPU0_SA_CA<3>")
	)
	(segment
		(start 395.69898 -254.31623)
		(end 398.168876 -254.31623)
		(width 0.14478)
		(layer "In4.Cu")
		(net "M_J_CPU0_SA_CA<3>")
	)
	(segment
		(start 415.873438 -252.460252)
		(end 416.124644 -252.460252)
		(width 0.14478)
		(layer "In4.Cu")
		(net "M_J_CPU0_SA_CA<3>")
	)
	(segment
		(start 416.976306 -252.460252)
		(end 417.227512 -252.460252)
		(width 0.14478)
		(layer "In4.Cu")
		(net "M_J_CPU0_SA_CA<3>")
	)
	(segment
		(start 379.454918 -254.204216)
		(end 379.30074 -253.938786)
		(width 0.0889)
		(layer "In4.Cu")
		(net "M_J_CPU0_SA_CA<3>")
	)
	(segment
		(start 395.209776 -254.31623)
		(end 395.69898 -254.31623)
		(width 0.0889)
		(layer "In4.Cu")
		(net "M_J_CPU0_SA_CA<3>")
	)
	(segment
		(start 398.168876 -254.31623)
		(end 399.118074 -253.367032)
		(width 0.14478)
		(layer "In4.Cu")
		(net "M_J_CPU0_SA_CA<3>")
	)
	(segment
		(start 413.367474 -252.160024)
		(end 413.667702 -252.460252)
		(width 0.14478)
		(layer "In4.Cu")
		(net "M_J_CPU0_SA_CA<3>")
	)
	(segment
		(start 379.63348 -253.87681)
		(end 379.641862 -253.881636)
		(width 0.0889)
		(layer "In4.Cu")
		(net "M_J_CPU0_SA_CA<3>")
	)
	(segment
		(start 414.219136 -252.160024)
		(end 414.470342 -252.160024)
		(width 0.14478)
		(layer "In4.Cu")
		(net "M_J_CPU0_SA_CA<3>")
	)
	(segment
		(start 388.093458 -253.87681)
		(end 388.10184 -253.881636)
		(width 0.0889)
		(layer "In4.Cu")
		(net "M_J_CPU0_SA_CA<3>")
	)
	(segment
		(start 409.711906 -253.367032)
		(end 410.918914 -252.160024)
		(width 0.14478)
		(layer "In4.Cu")
		(net "M_J_CPU0_SA_CA<3>")
	)
	(segment
		(start 416.424872 -252.160024)
		(end 416.676078 -252.160024)
		(width 0.14478)
		(layer "In4.Cu")
		(net "M_J_CPU0_SA_CA<3>")
	)
	(segment
		(start 414.470342 -252.160024)
		(end 414.77057 -252.460252)
		(width 0.14478)
		(layer "In4.Cu")
		(net "M_J_CPU0_SA_CA<3>")
	)
	(segment
		(start 417.227512 -252.460252)
		(end 417.52774 -252.160024)
		(width 0.14478)
		(layer "In4.Cu")
		(net "M_J_CPU0_SA_CA<3>")
	)
	(segment
		(start 410.918914 -252.160024)
		(end 413.367474 -252.160024)
		(width 0.14478)
		(layer "In4.Cu")
		(net "M_J_CPU0_SA_CA<3>")
	)
	(segment
		(start 389.033512 -253.87681)
		(end 389.041894 -253.881636)
		(width 0.0889)
		(layer "In4.Cu")
		(net "M_J_CPU0_SA_CA<3>")
	)
	(segment
		(start 415.021776 -252.460252)
		(end 415.322004 -252.160024)
		(width 0.14478)
		(layer "In4.Cu")
		(net "M_J_CPU0_SA_CA<3>")
	)
	(segment
		(start 415.57321 -252.160024)
		(end 415.873438 -252.460252)
		(width 0.14478)
		(layer "In4.Cu")
		(net "M_J_CPU0_SA_CA<3>")
	)
	(segment
		(start 380.207774 -253.881636)
		(end 380.216156 -253.87681)
		(width 0.0889)
		(layer "In4.Cu")
		(net "M_J_CPU0_SA_CA<3>")
	)
	(segment
		(start 399.118074 -253.367032)
		(end 409.711906 -253.367032)
		(width 0.14478)
		(layer "In4.Cu")
		(net "M_J_CPU0_SA_CA<3>")
	)
	(segment
		(start 416.676078 -252.160024)
		(end 416.976306 -252.460252)
		(width 0.14478)
		(layer "In4.Cu")
		(net "M_J_CPU0_SA_CA<3>")
	)
	(segment
		(start 379.30074 -253.938786)
		(end 379.323092 -253.855474)
		(width 0.0889)
		(layer "In4.Cu")
		(net "M_J_CPU0_SA_CA<3>")
	)
	(segment
		(start 430.992788 -250.460002)
		(end 434.575204 -250.460002)
		(width 0.14478)
		(layer "In4.Cu")
		(net "M_J_CPU0_SA_CA<3>")
	)
	(segment
		(start 434.575204 -250.460002)
		(end 435.000146 -250.03506)
		(width 0.14478)
		(layer "In4.Cu")
		(net "M_J_CPU0_SA_CA<3>")
	)
	(segment
		(start 414.77057 -252.460252)
		(end 415.021776 -252.460252)
		(width 0.14478)
		(layer "In4.Cu")
		(net "M_J_CPU0_SA_CA<3>")
	)
	(segment
		(start 381.147828 -253.881636)
		(end 381.15621 -253.87681)
		(width 0.0889)
		(layer "In4.Cu")
		(net "M_J_CPU0_SA_CA<3>")
	)
	(segment
		(start 385.847844 -253.881636)
		(end 385.856226 -253.87681)
		(width 0.0889)
		(layer "In4.Cu")
		(net "M_J_CPU0_SA_CA<3>")
	)
	(segment
		(start 383.393442 -253.87681)
		(end 383.401824 -253.881636)
		(width 0.0889)
		(layer "In4.Cu")
		(net "M_J_CPU0_SA_CA<3>")
	)
	(segment
		(start 394.993876 -254.10033)
		(end 395.209776 -254.31623)
		(width 0.0889)
		(layer "In4.Cu")
		(net "M_J_CPU0_SA_CA<3>")
	)
	(segment
		(start 415.322004 -252.160024)
		(end 415.57321 -252.160024)
		(width 0.14478)
		(layer "In4.Cu")
		(net "M_J_CPU0_SA_CA<3>")
	)
	(arc
		(start 390.921748 -253.881636)
		(mid 391.204704 -253.957813)
		(end 391.48766 -253.881636)
		(width 0.0889)
		(layer "In4.Cu")
		(net "M_J_CPU0_SA_CA<3>")
	)
	(arc
		(start 383.401824 -253.881636)
		(mid 383.68478 -253.957813)
		(end 383.967736 -253.881636)
		(width 0.0889)
		(layer "In4.Cu")
		(net "M_J_CPU0_SA_CA<3>")
	)
	(arc
		(start 389.041894 -253.881636)
		(mid 389.32485 -253.957813)
		(end 389.607806 -253.881636)
		(width 0.0889)
		(layer "In4.Cu")
		(net "M_J_CPU0_SA_CA<3>")
	)
	(arc
		(start 383.967736 -253.881636)
		(mid 384.149987 -253.831286)
		(end 384.333496 -253.87681)
		(width 0.0889)
		(layer "In4.Cu")
		(net "M_J_CPU0_SA_CA<3>")
	)
	(arc
		(start 392.42873 -253.881636)
		(mid 392.607717 -253.831466)
		(end 392.788648 -253.874016)
		(width 0.0889)
		(layer "In4.Cu")
		(net "M_J_CPU0_SA_CA<3>")
	)
	(arc
		(start 384.916172 -253.87681)
		(mid 385.09968 -253.831316)
		(end 385.281932 -253.881636)
		(width 0.0889)
		(layer "In4.Cu")
		(net "M_J_CPU0_SA_CA<3>")
	)
	(arc
		(start 381.15621 -253.87681)
		(mid 381.339718 -253.831316)
		(end 381.52197 -253.881636)
		(width 0.0889)
		(layer "In4.Cu")
		(net "M_J_CPU0_SA_CA<3>")
	)
	(arc
		(start 382.46177 -253.881636)
		(mid 382.744726 -253.957813)
		(end 383.027682 -253.881636)
		(width 0.0889)
		(layer "In4.Cu")
		(net "M_J_CPU0_SA_CA<3>")
	)
	(arc
		(start 379.641862 -253.881636)
		(mid 379.924818 -253.957813)
		(end 380.207774 -253.881636)
		(width 0.0889)
		(layer "In4.Cu")
		(net "M_J_CPU0_SA_CA<3>")
	)
	(arc
		(start 387.727698 -253.881636)
		(mid 387.909949 -253.831286)
		(end 388.093458 -253.87681)
		(width 0.0889)
		(layer "In4.Cu")
		(net "M_J_CPU0_SA_CA<3>")
	)
	(arc
		(start 382.087882 -253.881636)
		(mid 382.274826 -253.831381)
		(end 382.46177 -253.881636)
		(width 0.0889)
		(layer "In4.Cu")
		(net "M_J_CPU0_SA_CA<3>")
	)
	(arc
		(start 380.216156 -253.87681)
		(mid 380.399664 -253.831316)
		(end 380.581916 -253.881636)
		(width 0.0889)
		(layer "In4.Cu")
		(net "M_J_CPU0_SA_CA<3>")
	)
	(arc
		(start 386.787898 -253.881636)
		(mid 386.974842 -253.831381)
		(end 387.161786 -253.881636)
		(width 0.0889)
		(layer "In4.Cu")
		(net "M_J_CPU0_SA_CA<3>")
	)
	(arc
		(start 389.981948 -253.881636)
		(mid 390.264904 -253.957813)
		(end 390.54786 -253.881636)
		(width 0.0889)
		(layer "In4.Cu")
		(net "M_J_CPU0_SA_CA<3>")
	)
	(arc
		(start 385.856226 -253.87681)
		(mid 386.039734 -253.831316)
		(end 386.221986 -253.881636)
		(width 0.0889)
		(layer "In4.Cu")
		(net "M_J_CPU0_SA_CA<3>")
	)
	(arc
		(start 389.616188 -253.87681)
		(mid 389.799696 -253.831316)
		(end 389.981948 -253.881636)
		(width 0.0889)
		(layer "In4.Cu")
		(net "M_J_CPU0_SA_CA<3>")
	)
	(arc
		(start 390.54786 -253.881636)
		(mid 390.734804 -253.831381)
		(end 390.921748 -253.881636)
		(width 0.0889)
		(layer "In4.Cu")
		(net "M_J_CPU0_SA_CA<3>")
	)
	(arc
		(start 381.52197 -253.881636)
		(mid 381.804926 -253.957813)
		(end 382.087882 -253.881636)
		(width 0.0889)
		(layer "In4.Cu")
		(net "M_J_CPU0_SA_CA<3>")
	)
	(arc
		(start 391.496042 -253.87681)
		(mid 391.679804 -253.831194)
		(end 391.86231 -253.881636)
		(width 0.0889)
		(layer "In4.Cu")
		(net "M_J_CPU0_SA_CA<3>")
	)
	(arc
		(start 387.161786 -253.881636)
		(mid 387.444742 -253.957813)
		(end 387.727698 -253.881636)
		(width 0.0889)
		(layer "In4.Cu")
		(net "M_J_CPU0_SA_CA<3>")
	)
	(arc
		(start 380.581916 -253.881636)
		(mid 380.864872 -253.957813)
		(end 381.147828 -253.881636)
		(width 0.0889)
		(layer "In4.Cu")
		(net "M_J_CPU0_SA_CA<3>")
	)
	(arc
		(start 385.281932 -253.881636)
		(mid 385.564888 -253.957813)
		(end 385.847844 -253.881636)
		(width 0.0889)
		(layer "In4.Cu")
		(net "M_J_CPU0_SA_CA<3>")
	)
	(arc
		(start 379.323092 -253.855474)
		(mid 379.480602 -253.832276)
		(end 379.63348 -253.87681)
		(width 0.0889)
		(layer "In4.Cu")
		(net "M_J_CPU0_SA_CA<3>")
	)
	(arc
		(start 393.368276 -253.881636)
		(mid 393.550781 -253.831159)
		(end 393.734544 -253.87681)
		(width 0.0889)
		(layer "In4.Cu")
		(net "M_J_CPU0_SA_CA<3>")
	)
	(arc
		(start 392.818112 -253.891034)
		(mid 393.094421 -253.95801)
		(end 393.368276 -253.881636)
		(width 0.0889)
		(layer "In4.Cu")
		(net "M_J_CPU0_SA_CA<3>")
	)
	(arc
		(start 383.027682 -253.881636)
		(mid 383.209933 -253.831286)
		(end 383.393442 -253.87681)
		(width 0.0889)
		(layer "In4.Cu")
		(net "M_J_CPU0_SA_CA<3>")
	)
	(arc
		(start 386.221986 -253.881636)
		(mid 386.504942 -253.957813)
		(end 386.787898 -253.881636)
		(width 0.0889)
		(layer "In4.Cu")
		(net "M_J_CPU0_SA_CA<3>")
	)
	(arc
		(start 388.667752 -253.881636)
		(mid 388.850003 -253.831286)
		(end 389.033512 -253.87681)
		(width 0.0889)
		(layer "In4.Cu")
		(net "M_J_CPU0_SA_CA<3>")
	)
	(arc
		(start 384.341878 -253.881636)
		(mid 384.624834 -253.957813)
		(end 384.90779 -253.881636)
		(width 0.0889)
		(layer "In4.Cu")
		(net "M_J_CPU0_SA_CA<3>")
	)
	(arc
		(start 391.86231 -253.881636)
		(mid 392.137016 -253.958)
		(end 392.413998 -253.890272)
		(width 0.0889)
		(layer "In4.Cu")
		(net "M_J_CPU0_SA_CA<3>")
	)
	(arc
		(start 388.10184 -253.881636)
		(mid 388.384796 -253.957813)
		(end 388.667752 -253.881636)
		(width 0.0889)
		(layer "In4.Cu")
		(net "M_J_CPU0_SA_CA<3>")
	)
	(segment
		(start 378.517912 -253.660148)
		(end 378.984764 -253.39421)
		(width 0.10668)
		(layer "F.Cu")
		(net "M_J_CPU0_SA_CA<2>")
	)
	(segment
		(start 381.043434 -253.721616)
		(end 381.051816 -253.71679)
		(width 0.0889)
		(layer "In4.Cu")
		(net "M_J_CPU0_SA_CA<2>")
	)
	(segment
		(start 378.984764 -253.39421)
		(end 379.138942 -253.65964)
		(width 0.0889)
		(layer "In4.Cu")
		(net "M_J_CPU0_SA_CA<2>")
	)
	(segment
		(start 395.153896 -253.78537)
		(end 395.227556 -253.85903)
		(width 0.0889)
		(layer "In4.Cu")
		(net "M_J_CPU0_SA_CA<2>")
	)
	(segment
		(start 393.965684 -253.791212)
		(end 393.971526 -253.78537)
		(width 0.0889)
		(layer "In4.Cu")
		(net "M_J_CPU0_SA_CA<2>")
	)
	(segment
		(start 395.664182 -253.85903)
		(end 397.952976 -253.85903)
		(width 0.14478)
		(layer "In4.Cu")
		(net "M_J_CPU0_SA_CA<2>")
	)
	(segment
		(start 438.675272 -249.610118)
		(end 439.100214 -249.185176)
		(width 0.14478)
		(layer "In4.Cu")
		(net "M_J_CPU0_SA_CA<2>")
	)
	(segment
		(start 409.52547 -252.917452)
		(end 411.132782 -251.31014)
		(width 0.14478)
		(layer "In4.Cu")
		(net "M_J_CPU0_SA_CA<2>")
	)
	(segment
		(start 391.01776 -253.71679)
		(end 391.026142 -253.721616)
		(width 0.0889)
		(layer "In4.Cu")
		(net "M_J_CPU0_SA_CA<2>")
	)
	(segment
		(start 388.197852 -253.71679)
		(end 388.206234 -253.721616)
		(width 0.0889)
		(layer "In4.Cu")
		(net "M_J_CPU0_SA_CA<2>")
	)
	(segment
		(start 398.894554 -252.917452)
		(end 409.52547 -252.917452)
		(width 0.14478)
		(layer "In4.Cu")
		(net "M_J_CPU0_SA_CA<2>")
	)
	(segment
		(start 386.683504 -253.721616)
		(end 386.691886 -253.71679)
		(width 0.0889)
		(layer "In4.Cu")
		(net "M_J_CPU0_SA_CA<2>")
	)
	(segment
		(start 382.557782 -253.71679)
		(end 382.566164 -253.721616)
		(width 0.0889)
		(layer "In4.Cu")
		(net "M_J_CPU0_SA_CA<2>")
	)
	(segment
		(start 392.898122 -253.716536)
		(end 392.91641 -253.72695)
		(width 0.0889)
		(layer "In4.Cu")
		(net "M_J_CPU0_SA_CA<2>")
	)
	(segment
		(start 393.823952 -253.708154)
		(end 393.965684 -253.791212)
		(width 0.0889)
		(layer "In4.Cu")
		(net "M_J_CPU0_SA_CA<2>")
	)
	(segment
		(start 397.952976 -253.85903)
		(end 398.894554 -252.917452)
		(width 0.14478)
		(layer "In4.Cu")
		(net "M_J_CPU0_SA_CA<2>")
	)
	(segment
		(start 390.443466 -253.721616)
		(end 390.451848 -253.71679)
		(width 0.0889)
		(layer "In4.Cu")
		(net "M_J_CPU0_SA_CA<2>")
	)
	(segment
		(start 411.132782 -251.31014)
		(end 429.29048 -251.31014)
		(width 0.14478)
		(layer "In4.Cu")
		(net "M_J_CPU0_SA_CA<2>")
	)
	(segment
		(start 381.983488 -253.721616)
		(end 381.99187 -253.71679)
		(width 0.0889)
		(layer "In4.Cu")
		(net "M_J_CPU0_SA_CA<2>")
	)
	(segment
		(start 385.74345 -253.721616)
		(end 385.751832 -253.71679)
		(width 0.0889)
		(layer "In4.Cu")
		(net "M_J_CPU0_SA_CA<2>")
	)
	(segment
		(start 392.321034 -253.723648)
		(end 392.332718 -253.71679)
		(width 0.0889)
		(layer "In4.Cu")
		(net "M_J_CPU0_SA_CA<2>")
	)
	(segment
		(start 429.29048 -251.31014)
		(end 430.990502 -249.610118)
		(width 0.14478)
		(layer "In4.Cu")
		(net "M_J_CPU0_SA_CA<2>")
	)
	(segment
		(start 392.892534 -253.713234)
		(end 392.898122 -253.716536)
		(width 0.0889)
		(layer "In4.Cu")
		(net "M_J_CPU0_SA_CA<2>")
	)
	(segment
		(start 383.497836 -253.71679)
		(end 383.506218 -253.721616)
		(width 0.0889)
		(layer "In4.Cu")
		(net "M_J_CPU0_SA_CA<2>")
	)
	(segment
		(start 379.138942 -253.65964)
		(end 379.235208 -253.68504)
		(width 0.0889)
		(layer "In4.Cu")
		(net "M_J_CPU0_SA_CA<2>")
	)
	(segment
		(start 430.990502 -249.610118)
		(end 438.675272 -249.610118)
		(width 0.14478)
		(layer "In4.Cu")
		(net "M_J_CPU0_SA_CA<2>")
	)
	(segment
		(start 391.391902 -253.71679)
		(end 391.406634 -253.708154)
		(width 0.0889)
		(layer "In4.Cu")
		(net "M_J_CPU0_SA_CA<2>")
	)
	(segment
		(start 395.227556 -253.85903)
		(end 395.664182 -253.85903)
		(width 0.0889)
		(layer "In4.Cu")
		(net "M_J_CPU0_SA_CA<2>")
	)
	(segment
		(start 393.971526 -253.78537)
		(end 395.153896 -253.78537)
		(width 0.0889)
		(layer "In4.Cu")
		(net "M_J_CPU0_SA_CA<2>")
	)
	(segment
		(start 387.257798 -253.71679)
		(end 387.26618 -253.721616)
		(width 0.0889)
		(layer "In4.Cu")
		(net "M_J_CPU0_SA_CA<2>")
	)
	(arc
		(start 386.691886 -253.71679)
		(mid 386.974842 -253.640613)
		(end 387.257798 -253.71679)
		(width 0.0889)
		(layer "In4.Cu")
		(net "M_J_CPU0_SA_CA<2>")
	)
	(arc
		(start 381.617728 -253.71679)
		(mid 381.799979 -253.76714)
		(end 381.983488 -253.721616)
		(width 0.0889)
		(layer "In4.Cu")
		(net "M_J_CPU0_SA_CA<2>")
	)
	(arc
		(start 391.406634 -253.708154)
		(mid 391.683617 -253.64035)
		(end 391.958322 -253.71679)
		(width 0.0889)
		(layer "In4.Cu")
		(net "M_J_CPU0_SA_CA<2>")
	)
	(arc
		(start 388.571994 -253.71679)
		(mid 388.85495 -253.640613)
		(end 389.137906 -253.71679)
		(width 0.0889)
		(layer "In4.Cu")
		(net "M_J_CPU0_SA_CA<2>")
	)
	(arc
		(start 382.931924 -253.71679)
		(mid 383.21488 -253.640613)
		(end 383.497836 -253.71679)
		(width 0.0889)
		(layer "In4.Cu")
		(net "M_J_CPU0_SA_CA<2>")
	)
	(arc
		(start 381.99187 -253.71679)
		(mid 382.274826 -253.640613)
		(end 382.557782 -253.71679)
		(width 0.0889)
		(layer "In4.Cu")
		(net "M_J_CPU0_SA_CA<2>")
	)
	(arc
		(start 393.272264 -253.71679)
		(mid 393.54697 -253.640426)
		(end 393.823952 -253.708154)
		(width 0.0889)
		(layer "In4.Cu")
		(net "M_J_CPU0_SA_CA<2>")
	)
	(arc
		(start 391.958322 -253.71679)
		(mid 392.13878 -253.767234)
		(end 392.321034 -253.723648)
		(width 0.0889)
		(layer "In4.Cu")
		(net "M_J_CPU0_SA_CA<2>")
	)
	(arc
		(start 383.871978 -253.71679)
		(mid 384.154934 -253.640613)
		(end 384.43789 -253.71679)
		(width 0.0889)
		(layer "In4.Cu")
		(net "M_J_CPU0_SA_CA<2>")
	)
	(arc
		(start 384.811778 -253.71679)
		(mid 385.094734 -253.640613)
		(end 385.37769 -253.71679)
		(width 0.0889)
		(layer "In4.Cu")
		(net "M_J_CPU0_SA_CA<2>")
	)
	(arc
		(start 389.511794 -253.71679)
		(mid 389.79475 -253.640613)
		(end 390.077706 -253.71679)
		(width 0.0889)
		(layer "In4.Cu")
		(net "M_J_CPU0_SA_CA<2>")
	)
	(arc
		(start 388.206234 -253.721616)
		(mid 388.389742 -253.76711)
		(end 388.571994 -253.71679)
		(width 0.0889)
		(layer "In4.Cu")
		(net "M_J_CPU0_SA_CA<2>")
	)
	(arc
		(start 383.506218 -253.721616)
		(mid 383.689726 -253.76711)
		(end 383.871978 -253.71679)
		(width 0.0889)
		(layer "In4.Cu")
		(net "M_J_CPU0_SA_CA<2>")
	)
	(arc
		(start 385.751832 -253.71679)
		(mid 386.034788 -253.640613)
		(end 386.317744 -253.71679)
		(width 0.0889)
		(layer "In4.Cu")
		(net "M_J_CPU0_SA_CA<2>")
	)
	(arc
		(start 386.317744 -253.71679)
		(mid 386.499995 -253.76714)
		(end 386.683504 -253.721616)
		(width 0.0889)
		(layer "In4.Cu")
		(net "M_J_CPU0_SA_CA<2>")
	)
	(arc
		(start 384.43789 -253.71679)
		(mid 384.624834 -253.767045)
		(end 384.811778 -253.71679)
		(width 0.0889)
		(layer "In4.Cu")
		(net "M_J_CPU0_SA_CA<2>")
	)
	(arc
		(start 381.051816 -253.71679)
		(mid 381.334772 -253.640613)
		(end 381.617728 -253.71679)
		(width 0.0889)
		(layer "In4.Cu")
		(net "M_J_CPU0_SA_CA<2>")
	)
	(arc
		(start 392.332718 -253.71679)
		(mid 392.612146 -253.640624)
		(end 392.892534 -253.713234)
		(width 0.0889)
		(layer "In4.Cu")
		(net "M_J_CPU0_SA_CA<2>")
	)
	(arc
		(start 387.26618 -253.721616)
		(mid 387.449688 -253.76711)
		(end 387.63194 -253.71679)
		(width 0.0889)
		(layer "In4.Cu")
		(net "M_J_CPU0_SA_CA<2>")
	)
	(arc
		(start 382.566164 -253.721616)
		(mid 382.749672 -253.76711)
		(end 382.931924 -253.71679)
		(width 0.0889)
		(layer "In4.Cu")
		(net "M_J_CPU0_SA_CA<2>")
	)
	(arc
		(start 380.677674 -253.71679)
		(mid 380.859925 -253.76714)
		(end 381.043434 -253.721616)
		(width 0.0889)
		(layer "In4.Cu")
		(net "M_J_CPU0_SA_CA<2>")
	)
	(arc
		(start 385.37769 -253.71679)
		(mid 385.559941 -253.76714)
		(end 385.74345 -253.721616)
		(width 0.0889)
		(layer "In4.Cu")
		(net "M_J_CPU0_SA_CA<2>")
	)
	(arc
		(start 387.63194 -253.71679)
		(mid 387.914896 -253.640613)
		(end 388.197852 -253.71679)
		(width 0.0889)
		(layer "In4.Cu")
		(net "M_J_CPU0_SA_CA<2>")
	)
	(arc
		(start 390.451848 -253.71679)
		(mid 390.734804 -253.640613)
		(end 391.01776 -253.71679)
		(width 0.0889)
		(layer "In4.Cu")
		(net "M_J_CPU0_SA_CA<2>")
	)
	(arc
		(start 390.077706 -253.71679)
		(mid 390.259957 -253.76714)
		(end 390.443466 -253.721616)
		(width 0.0889)
		(layer "In4.Cu")
		(net "M_J_CPU0_SA_CA<2>")
	)
	(arc
		(start 392.91641 -253.72695)
		(mid 393.095639 -253.767103)
		(end 393.272264 -253.71679)
		(width 0.0889)
		(layer "In4.Cu")
		(net "M_J_CPU0_SA_CA<2>")
	)
	(arc
		(start 380.111762 -253.71679)
		(mid 380.394718 -253.640613)
		(end 380.677674 -253.71679)
		(width 0.0889)
		(layer "In4.Cu")
		(net "M_J_CPU0_SA_CA<2>")
	)
	(arc
		(start 379.737874 -253.71679)
		(mid 379.924818 -253.767045)
		(end 380.111762 -253.71679)
		(width 0.0889)
		(layer "In4.Cu")
		(net "M_J_CPU0_SA_CA<2>")
	)
	(arc
		(start 379.235208 -253.68504)
		(mid 379.490273 -253.641689)
		(end 379.737874 -253.71679)
		(width 0.0889)
		(layer "In4.Cu")
		(net "M_J_CPU0_SA_CA<2>")
	)
	(arc
		(start 389.137906 -253.71679)
		(mid 389.32485 -253.767045)
		(end 389.511794 -253.71679)
		(width 0.0889)
		(layer "In4.Cu")
		(net "M_J_CPU0_SA_CA<2>")
	)
	(arc
		(start 391.026142 -253.721616)
		(mid 391.20965 -253.76711)
		(end 391.391902 -253.71679)
		(width 0.0889)
		(layer "In4.Cu")
		(net "M_J_CPU0_SA_CA<2>")
	)
	(segment
		(start 380.39802 -253.660148)
		(end 380.864872 -253.39421)
		(width 0.10668)
		(layer "F.Cu")
		(net "M_J_CPU0_SA_CA<1>")
	)
	(segment
		(start 413.707834 -250.781312)
		(end 414.029144 -250.460002)
		(width 0.14478)
		(layer "In4.Cu")
		(net "M_J_CPU0_SA_CA<1>")
	)
	(segment
		(start 380.710694 -253.12878)
		(end 380.733046 -253.045468)
		(width 0.0889)
		(layer "In4.Cu")
		(net "M_J_CPU0_SA_CA<1>")
	)
	(segment
		(start 394.320522 -253.39675)
		(end 395.070838 -253.39675)
		(width 0.0889)
		(layer "In4.Cu")
		(net "M_J_CPU0_SA_CA<1>")
	)
	(segment
		(start 416.23488 -250.460002)
		(end 416.465004 -250.460002)
		(width 0.14478)
		(layer "In4.Cu")
		(net "M_J_CPU0_SA_CA<1>")
	)
	(segment
		(start 417.337748 -250.460002)
		(end 417.567872 -250.460002)
		(width 0.14478)
		(layer "In4.Cu")
		(net "M_J_CPU0_SA_CA<1>")
	)
	(segment
		(start 387.257798 -253.07163)
		(end 387.26618 -253.066804)
		(width 0.0889)
		(layer "In4.Cu")
		(net "M_J_CPU0_SA_CA<1>")
	)
	(segment
		(start 416.465004 -250.460002)
		(end 416.786314 -250.781312)
		(width 0.14478)
		(layer "In4.Cu")
		(net "M_J_CPU0_SA_CA<1>")
	)
	(segment
		(start 417.889182 -250.781312)
		(end 418.119306 -250.781312)
		(width 0.14478)
		(layer "In4.Cu")
		(net "M_J_CPU0_SA_CA<1>")
	)
	(segment
		(start 381.983488 -253.066804)
		(end 381.99187 -253.07163)
		(width 0.0889)
		(layer "In4.Cu")
		(net "M_J_CPU0_SA_CA<1>")
	)
	(segment
		(start 409.339034 -252.467872)
		(end 411.346904 -250.460002)
		(width 0.14478)
		(layer "In4.Cu")
		(net "M_J_CPU0_SA_CA<1>")
	)
	(segment
		(start 415.91357 -250.781312)
		(end 416.23488 -250.460002)
		(width 0.14478)
		(layer "In4.Cu")
		(net "M_J_CPU0_SA_CA<1>")
	)
	(segment
		(start 415.683446 -250.781312)
		(end 415.91357 -250.781312)
		(width 0.14478)
		(layer "In4.Cu")
		(net "M_J_CPU0_SA_CA<1>")
	)
	(segment
		(start 391.391902 -253.07163)
		(end 391.402316 -253.077726)
		(width 0.0889)
		(layer "In4.Cu")
		(net "M_J_CPU0_SA_CA<1>")
	)
	(segment
		(start 392.892534 -253.075186)
		(end 392.898122 -253.071884)
		(width 0.0889)
		(layer "In4.Cu")
		(net "M_J_CPU0_SA_CA<1>")
	)
	(segment
		(start 414.810702 -250.781312)
		(end 415.132012 -250.460002)
		(width 0.14478)
		(layer "In4.Cu")
		(net "M_J_CPU0_SA_CA<1>")
	)
	(segment
		(start 430.865026 -248.760234)
		(end 434.57495 -248.760234)
		(width 0.14478)
		(layer "In4.Cu")
		(net "M_J_CPU0_SA_CA<1>")
	)
	(segment
		(start 417.567872 -250.460002)
		(end 417.889182 -250.781312)
		(width 0.14478)
		(layer "In4.Cu")
		(net "M_J_CPU0_SA_CA<1>")
	)
	(segment
		(start 385.74345 -253.066804)
		(end 385.751832 -253.07163)
		(width 0.0889)
		(layer "In4.Cu")
		(net "M_J_CPU0_SA_CA<1>")
	)
	(segment
		(start 413.47771 -250.781312)
		(end 413.707834 -250.781312)
		(width 0.14478)
		(layer "In4.Cu")
		(net "M_J_CPU0_SA_CA<1>")
	)
	(segment
		(start 429.165258 -250.460002)
		(end 430.865026 -248.760234)
		(width 0.14478)
		(layer "In4.Cu")
		(net "M_J_CPU0_SA_CA<1>")
	)
	(segment
		(start 434.57495 -248.760234)
		(end 435.000146 -248.335038)
		(width 0.14478)
		(layer "In4.Cu")
		(net "M_J_CPU0_SA_CA<1>")
	)
	(segment
		(start 418.440616 -250.460002)
		(end 429.165258 -250.460002)
		(width 0.14478)
		(layer "In4.Cu")
		(net "M_J_CPU0_SA_CA<1>")
	)
	(segment
		(start 391.01776 -253.07163)
		(end 391.026142 -253.066804)
		(width 0.0889)
		(layer "In4.Cu")
		(net "M_J_CPU0_SA_CA<1>")
	)
	(segment
		(start 414.259268 -250.460002)
		(end 414.580578 -250.781312)
		(width 0.14478)
		(layer "In4.Cu")
		(net "M_J_CPU0_SA_CA<1>")
	)
	(segment
		(start 383.497836 -253.07163)
		(end 383.506218 -253.066804)
		(width 0.0889)
		(layer "In4.Cu")
		(net "M_J_CPU0_SA_CA<1>")
	)
	(segment
		(start 414.029144 -250.460002)
		(end 414.259268 -250.460002)
		(width 0.14478)
		(layer "In4.Cu")
		(net "M_J_CPU0_SA_CA<1>")
	)
	(segment
		(start 392.898122 -253.071884)
		(end 392.91641 -253.06147)
		(width 0.0889)
		(layer "In4.Cu")
		(net "M_J_CPU0_SA_CA<1>")
	)
	(segment
		(start 380.864872 -253.39421)
		(end 380.710694 -253.12878)
		(width 0.0889)
		(layer "In4.Cu")
		(net "M_J_CPU0_SA_CA<1>")
	)
	(segment
		(start 393.555982 -253.148084)
		(end 394.071856 -253.148084)
		(width 0.0889)
		(layer "In4.Cu")
		(net "M_J_CPU0_SA_CA<1>")
	)
	(segment
		(start 415.132012 -250.460002)
		(end 415.362136 -250.460002)
		(width 0.14478)
		(layer "In4.Cu")
		(net "M_J_CPU0_SA_CA<1>")
	)
	(segment
		(start 395.070838 -253.39675)
		(end 395.357096 -253.110492)
		(width 0.14478)
		(layer "In4.Cu")
		(net "M_J_CPU0_SA_CA<1>")
	)
	(segment
		(start 417.016438 -250.781312)
		(end 417.337748 -250.460002)
		(width 0.14478)
		(layer "In4.Cu")
		(net "M_J_CPU0_SA_CA<1>")
	)
	(segment
		(start 415.362136 -250.460002)
		(end 415.683446 -250.781312)
		(width 0.14478)
		(layer "In4.Cu")
		(net "M_J_CPU0_SA_CA<1>")
	)
	(segment
		(start 381.043434 -253.066804)
		(end 381.051816 -253.07163)
		(width 0.0889)
		(layer "In4.Cu")
		(net "M_J_CPU0_SA_CA<1>")
	)
	(segment
		(start 394.071856 -253.148084)
		(end 394.320522 -253.39675)
		(width 0.0889)
		(layer "In4.Cu")
		(net "M_J_CPU0_SA_CA<1>")
	)
	(segment
		(start 382.557782 -253.07163)
		(end 382.566164 -253.066804)
		(width 0.0889)
		(layer "In4.Cu")
		(net "M_J_CPU0_SA_CA<1>")
	)
	(segment
		(start 388.197852 -253.07163)
		(end 388.206234 -253.066804)
		(width 0.0889)
		(layer "In4.Cu")
		(net "M_J_CPU0_SA_CA<1>")
	)
	(segment
		(start 413.1564 -250.460002)
		(end 413.47771 -250.781312)
		(width 0.14478)
		(layer "In4.Cu")
		(net "M_J_CPU0_SA_CA<1>")
	)
	(segment
		(start 411.346904 -250.460002)
		(end 413.1564 -250.460002)
		(width 0.14478)
		(layer "In4.Cu")
		(net "M_J_CPU0_SA_CA<1>")
	)
	(segment
		(start 392.324336 -253.066804)
		(end 392.332718 -253.07163)
		(width 0.0889)
		(layer "In4.Cu")
		(net "M_J_CPU0_SA_CA<1>")
	)
	(segment
		(start 398.683734 -252.467872)
		(end 409.339034 -252.467872)
		(width 0.14478)
		(layer "In4.Cu")
		(net "M_J_CPU0_SA_CA<1>")
	)
	(segment
		(start 414.580578 -250.781312)
		(end 414.810702 -250.781312)
		(width 0.14478)
		(layer "In4.Cu")
		(net "M_J_CPU0_SA_CA<1>")
	)
	(segment
		(start 398.041114 -253.110492)
		(end 398.683734 -252.467872)
		(width 0.14478)
		(layer "In4.Cu")
		(net "M_J_CPU0_SA_CA<1>")
	)
	(segment
		(start 418.119306 -250.781312)
		(end 418.440616 -250.460002)
		(width 0.14478)
		(layer "In4.Cu")
		(net "M_J_CPU0_SA_CA<1>")
	)
	(segment
		(start 386.683504 -253.066804)
		(end 386.691886 -253.07163)
		(width 0.0889)
		(layer "In4.Cu")
		(net "M_J_CPU0_SA_CA<1>")
	)
	(segment
		(start 390.443466 -253.066804)
		(end 390.451848 -253.07163)
		(width 0.0889)
		(layer "In4.Cu")
		(net "M_J_CPU0_SA_CA<1>")
	)
	(segment
		(start 416.786314 -250.781312)
		(end 417.016438 -250.781312)
		(width 0.14478)
		(layer "In4.Cu")
		(net "M_J_CPU0_SA_CA<1>")
	)
	(segment
		(start 395.357096 -253.110492)
		(end 398.041114 -253.110492)
		(width 0.14478)
		(layer "In4.Cu")
		(net "M_J_CPU0_SA_CA<1>")
	)
	(arc
		(start 384.43789 -253.07163)
		(mid 384.624834 -253.021375)
		(end 384.811778 -253.07163)
		(width 0.0889)
		(layer "In4.Cu")
		(net "M_J_CPU0_SA_CA<1>")
	)
	(arc
		(start 385.751832 -253.07163)
		(mid 386.034788 -253.147807)
		(end 386.317744 -253.07163)
		(width 0.0889)
		(layer "In4.Cu")
		(net "M_J_CPU0_SA_CA<1>")
	)
	(arc
		(start 386.317744 -253.07163)
		(mid 386.499995 -253.02128)
		(end 386.683504 -253.066804)
		(width 0.0889)
		(layer "In4.Cu")
		(net "M_J_CPU0_SA_CA<1>")
	)
	(arc
		(start 391.402316 -253.077726)
		(mid 391.681002 -253.147946)
		(end 391.958068 -253.07163)
		(width 0.0889)
		(layer "In4.Cu")
		(net "M_J_CPU0_SA_CA<1>")
	)
	(arc
		(start 380.733046 -253.045468)
		(mid 380.890556 -253.02227)
		(end 381.043434 -253.066804)
		(width 0.0889)
		(layer "In4.Cu")
		(net "M_J_CPU0_SA_CA<1>")
	)
	(arc
		(start 388.206234 -253.066804)
		(mid 388.389742 -253.02131)
		(end 388.571994 -253.07163)
		(width 0.0889)
		(layer "In4.Cu")
		(net "M_J_CPU0_SA_CA<1>")
	)
	(arc
		(start 389.137906 -253.07163)
		(mid 389.32485 -253.021375)
		(end 389.511794 -253.07163)
		(width 0.0889)
		(layer "In4.Cu")
		(net "M_J_CPU0_SA_CA<1>")
	)
	(arc
		(start 390.451848 -253.07163)
		(mid 390.734804 -253.147807)
		(end 391.01776 -253.07163)
		(width 0.0889)
		(layer "In4.Cu")
		(net "M_J_CPU0_SA_CA<1>")
	)
	(arc
		(start 382.931924 -253.07163)
		(mid 383.21488 -253.147807)
		(end 383.497836 -253.07163)
		(width 0.0889)
		(layer "In4.Cu")
		(net "M_J_CPU0_SA_CA<1>")
	)
	(arc
		(start 391.958068 -253.07163)
		(mid 392.140573 -253.021153)
		(end 392.324336 -253.066804)
		(width 0.0889)
		(layer "In4.Cu")
		(net "M_J_CPU0_SA_CA<1>")
	)
	(arc
		(start 384.811778 -253.07163)
		(mid 385.094734 -253.147807)
		(end 385.37769 -253.07163)
		(width 0.0889)
		(layer "In4.Cu")
		(net "M_J_CPU0_SA_CA<1>")
	)
	(arc
		(start 381.617728 -253.07163)
		(mid 381.799979 -253.02128)
		(end 381.983488 -253.066804)
		(width 0.0889)
		(layer "In4.Cu")
		(net "M_J_CPU0_SA_CA<1>")
	)
	(arc
		(start 393.272264 -253.07163)
		(mid 393.409057 -253.128652)
		(end 393.555982 -253.148084)
		(width 0.0889)
		(layer "In4.Cu")
		(net "M_J_CPU0_SA_CA<1>")
	)
	(arc
		(start 387.63194 -253.07163)
		(mid 387.914896 -253.147807)
		(end 388.197852 -253.07163)
		(width 0.0889)
		(layer "In4.Cu")
		(net "M_J_CPU0_SA_CA<1>")
	)
	(arc
		(start 383.871978 -253.07163)
		(mid 384.154934 -253.147807)
		(end 384.43789 -253.07163)
		(width 0.0889)
		(layer "In4.Cu")
		(net "M_J_CPU0_SA_CA<1>")
	)
	(arc
		(start 387.26618 -253.066804)
		(mid 387.449688 -253.02131)
		(end 387.63194 -253.07163)
		(width 0.0889)
		(layer "In4.Cu")
		(net "M_J_CPU0_SA_CA<1>")
	)
	(arc
		(start 386.691886 -253.07163)
		(mid 386.974842 -253.147807)
		(end 387.257798 -253.07163)
		(width 0.0889)
		(layer "In4.Cu")
		(net "M_J_CPU0_SA_CA<1>")
	)
	(arc
		(start 381.99187 -253.07163)
		(mid 382.274826 -253.147807)
		(end 382.557782 -253.07163)
		(width 0.0889)
		(layer "In4.Cu")
		(net "M_J_CPU0_SA_CA<1>")
	)
	(arc
		(start 388.571994 -253.07163)
		(mid 388.85495 -253.147807)
		(end 389.137906 -253.07163)
		(width 0.0889)
		(layer "In4.Cu")
		(net "M_J_CPU0_SA_CA<1>")
	)
	(arc
		(start 392.91641 -253.06147)
		(mid 393.095639 -253.021317)
		(end 393.272264 -253.07163)
		(width 0.0889)
		(layer "In4.Cu")
		(net "M_J_CPU0_SA_CA<1>")
	)
	(arc
		(start 381.051816 -253.07163)
		(mid 381.334772 -253.147807)
		(end 381.617728 -253.07163)
		(width 0.0889)
		(layer "In4.Cu")
		(net "M_J_CPU0_SA_CA<1>")
	)
	(arc
		(start 391.026142 -253.066804)
		(mid 391.20965 -253.02131)
		(end 391.391902 -253.07163)
		(width 0.0889)
		(layer "In4.Cu")
		(net "M_J_CPU0_SA_CA<1>")
	)
	(arc
		(start 389.511794 -253.07163)
		(mid 389.79475 -253.147807)
		(end 390.077706 -253.07163)
		(width 0.0889)
		(layer "In4.Cu")
		(net "M_J_CPU0_SA_CA<1>")
	)
	(arc
		(start 383.506218 -253.066804)
		(mid 383.689726 -253.02131)
		(end 383.871978 -253.07163)
		(width 0.0889)
		(layer "In4.Cu")
		(net "M_J_CPU0_SA_CA<1>")
	)
	(arc
		(start 382.566164 -253.066804)
		(mid 382.749672 -253.02131)
		(end 382.931924 -253.07163)
		(width 0.0889)
		(layer "In4.Cu")
		(net "M_J_CPU0_SA_CA<1>")
	)
	(arc
		(start 385.37769 -253.07163)
		(mid 385.559941 -253.02128)
		(end 385.74345 -253.066804)
		(width 0.0889)
		(layer "In4.Cu")
		(net "M_J_CPU0_SA_CA<1>")
	)
	(arc
		(start 392.332718 -253.07163)
		(mid 392.612146 -253.147796)
		(end 392.892534 -253.075186)
		(width 0.0889)
		(layer "In4.Cu")
		(net "M_J_CPU0_SA_CA<1>")
	)
	(arc
		(start 390.077706 -253.07163)
		(mid 390.259957 -253.02128)
		(end 390.443466 -253.066804)
		(width 0.0889)
		(layer "In4.Cu")
		(net "M_J_CPU0_SA_CA<1>")
	)
	(segment
		(start 379.927866 -252.850142)
		(end 380.394718 -252.584204)
		(width 0.10668)
		(layer "F.Cu")
		(net "M_J_CPU0_SA_CA<0>")
	)
	(segment
		(start 438.675272 -247.910096)
		(end 439.100214 -247.485154)
		(width 0.14478)
		(layer "In4.Cu")
		(net "M_J_CPU0_SA_CA<0>")
	)
	(segment
		(start 381.147828 -252.906784)
		(end 381.15621 -252.91161)
		(width 0.0889)
		(layer "In4.Cu")
		(net "M_J_CPU0_SA_CA<0>")
	)
	(segment
		(start 384.333496 -252.91161)
		(end 384.341878 -252.906784)
		(width 0.0889)
		(layer "In4.Cu")
		(net "M_J_CPU0_SA_CA<0>")
	)
	(segment
		(start 388.093458 -252.91161)
		(end 388.10184 -252.906784)
		(width 0.0889)
		(layer "In4.Cu")
		(net "M_J_CPU0_SA_CA<0>")
	)
	(segment
		(start 385.847844 -252.906784)
		(end 385.856226 -252.91161)
		(width 0.0889)
		(layer "In4.Cu")
		(net "M_J_CPU0_SA_CA<0>")
	)
	(segment
		(start 380.394718 -252.584204)
		(end 380.548896 -252.849634)
		(width 0.0889)
		(layer "In4.Cu")
		(net "M_J_CPU0_SA_CA<0>")
	)
	(segment
		(start 409.152598 -252.018292)
		(end 411.560772 -249.610118)
		(width 0.14478)
		(layer "In4.Cu")
		(net "M_J_CPU0_SA_CA<0>")
	)
	(segment
		(start 389.033512 -252.91161)
		(end 389.041894 -252.906784)
		(width 0.0889)
		(layer "In4.Cu")
		(net "M_J_CPU0_SA_CA<0>")
	)
	(segment
		(start 429.29302 -249.610118)
		(end 430.993042 -247.910096)
		(width 0.14478)
		(layer "In4.Cu")
		(net "M_J_CPU0_SA_CA<0>")
	)
	(segment
		(start 389.607806 -252.906784)
		(end 389.616188 -252.91161)
		(width 0.0889)
		(layer "In4.Cu")
		(net "M_J_CPU0_SA_CA<0>")
	)
	(segment
		(start 392.418062 -252.900688)
		(end 392.428476 -252.906784)
		(width 0.0889)
		(layer "In4.Cu")
		(net "M_J_CPU0_SA_CA<0>")
	)
	(segment
		(start 391.48766 -252.906784)
		(end 391.496042 -252.91161)
		(width 0.0889)
		(layer "In4.Cu")
		(net "M_J_CPU0_SA_CA<0>")
	)
	(segment
		(start 393.982448 -252.957584)
		(end 394.458952 -252.48108)
		(width 0.0889)
		(layer "In4.Cu")
		(net "M_J_CPU0_SA_CA<0>")
	)
	(segment
		(start 393.368276 -252.906784)
		(end 393.368022 -252.906784)
		(width 0.0889)
		(layer "In4.Cu")
		(net "M_J_CPU0_SA_CA<0>")
	)
	(segment
		(start 384.90779 -252.906784)
		(end 384.916172 -252.91161)
		(width 0.0889)
		(layer "In4.Cu")
		(net "M_J_CPU0_SA_CA<0>")
	)
	(segment
		(start 392.802364 -252.90653)
		(end 392.818112 -252.897386)
		(width 0.0889)
		(layer "In4.Cu")
		(net "M_J_CPU0_SA_CA<0>")
	)
	(segment
		(start 411.560772 -249.610118)
		(end 429.29302 -249.610118)
		(width 0.14478)
		(layer "In4.Cu")
		(net "M_J_CPU0_SA_CA<0>")
	)
	(segment
		(start 380.548896 -252.849634)
		(end 380.645162 -252.875034)
		(width 0.0889)
		(layer "In4.Cu")
		(net "M_J_CPU0_SA_CA<0>")
	)
	(segment
		(start 398.020286 -252.48108)
		(end 398.483074 -252.018292)
		(width 0.14478)
		(layer "In4.Cu")
		(net "M_J_CPU0_SA_CA<0>")
	)
	(segment
		(start 393.555728 -252.957584)
		(end 393.982448 -252.957584)
		(width 0.0889)
		(layer "In4.Cu")
		(net "M_J_CPU0_SA_CA<0>")
	)
	(segment
		(start 394.458952 -252.48108)
		(end 395.347698 -252.48108)
		(width 0.0889)
		(layer "In4.Cu")
		(net "M_J_CPU0_SA_CA<0>")
	)
	(segment
		(start 398.483074 -252.018292)
		(end 409.152598 -252.018292)
		(width 0.14478)
		(layer "In4.Cu")
		(net "M_J_CPU0_SA_CA<0>")
	)
	(segment
		(start 395.347698 -252.48108)
		(end 398.020286 -252.48108)
		(width 0.14478)
		(layer "In4.Cu")
		(net "M_J_CPU0_SA_CA<0>")
	)
	(segment
		(start 430.993042 -247.910096)
		(end 438.675272 -247.910096)
		(width 0.14478)
		(layer "In4.Cu")
		(net "M_J_CPU0_SA_CA<0>")
	)
	(segment
		(start 383.393442 -252.91161)
		(end 383.401824 -252.906784)
		(width 0.0889)
		(layer "In4.Cu")
		(net "M_J_CPU0_SA_CA<0>")
	)
	(segment
		(start 392.786108 -252.915928)
		(end 392.802364 -252.90653)
		(width 0.0889)
		(layer "In4.Cu")
		(net "M_J_CPU0_SA_CA<0>")
	)
	(arc
		(start 385.856226 -252.91161)
		(mid 386.039734 -252.957104)
		(end 386.221986 -252.906784)
		(width 0.0889)
		(layer "In4.Cu")
		(net "M_J_CPU0_SA_CA<0>")
	)
	(arc
		(start 386.787898 -252.906784)
		(mid 386.974842 -252.957039)
		(end 387.161786 -252.906784)
		(width 0.0889)
		(layer "In4.Cu")
		(net "M_J_CPU0_SA_CA<0>")
	)
	(arc
		(start 392.428476 -252.906784)
		(mid 392.606126 -252.957044)
		(end 392.786108 -252.915928)
		(width 0.0889)
		(layer "In4.Cu")
		(net "M_J_CPU0_SA_CA<0>")
	)
	(arc
		(start 389.616188 -252.91161)
		(mid 389.799696 -252.957104)
		(end 389.981948 -252.906784)
		(width 0.0889)
		(layer "In4.Cu")
		(net "M_J_CPU0_SA_CA<0>")
	)
	(arc
		(start 383.967736 -252.906784)
		(mid 384.149987 -252.957134)
		(end 384.333496 -252.91161)
		(width 0.0889)
		(layer "In4.Cu")
		(net "M_J_CPU0_SA_CA<0>")
	)
	(arc
		(start 385.281932 -252.906784)
		(mid 385.564888 -252.830607)
		(end 385.847844 -252.906784)
		(width 0.0889)
		(layer "In4.Cu")
		(net "M_J_CPU0_SA_CA<0>")
	)
	(arc
		(start 389.981948 -252.906784)
		(mid 390.264904 -252.830607)
		(end 390.54786 -252.906784)
		(width 0.0889)
		(layer "In4.Cu")
		(net "M_J_CPU0_SA_CA<0>")
	)
	(arc
		(start 393.368022 -252.906784)
		(mid 393.458512 -252.944602)
		(end 393.555728 -252.957584)
		(width 0.0889)
		(layer "In4.Cu")
		(net "M_J_CPU0_SA_CA<0>")
	)
	(arc
		(start 390.54786 -252.906784)
		(mid 390.734804 -252.957039)
		(end 390.921748 -252.906784)
		(width 0.0889)
		(layer "In4.Cu")
		(net "M_J_CPU0_SA_CA<0>")
	)
	(arc
		(start 383.027682 -252.906784)
		(mid 383.209933 -252.957134)
		(end 383.393442 -252.91161)
		(width 0.0889)
		(layer "In4.Cu")
		(net "M_J_CPU0_SA_CA<0>")
	)
	(arc
		(start 387.727698 -252.906784)
		(mid 387.909949 -252.957134)
		(end 388.093458 -252.91161)
		(width 0.0889)
		(layer "In4.Cu")
		(net "M_J_CPU0_SA_CA<0>")
	)
	(arc
		(start 384.916172 -252.91161)
		(mid 385.09968 -252.957104)
		(end 385.281932 -252.906784)
		(width 0.0889)
		(layer "In4.Cu")
		(net "M_J_CPU0_SA_CA<0>")
	)
	(arc
		(start 386.221986 -252.906784)
		(mid 386.504942 -252.830607)
		(end 386.787898 -252.906784)
		(width 0.0889)
		(layer "In4.Cu")
		(net "M_J_CPU0_SA_CA<0>")
	)
	(arc
		(start 390.921748 -252.906784)
		(mid 391.204704 -252.830607)
		(end 391.48766 -252.906784)
		(width 0.0889)
		(layer "In4.Cu")
		(net "M_J_CPU0_SA_CA<0>")
	)
	(arc
		(start 391.496042 -252.91161)
		(mid 391.679804 -252.957226)
		(end 391.86231 -252.906784)
		(width 0.0889)
		(layer "In4.Cu")
		(net "M_J_CPU0_SA_CA<0>")
	)
	(arc
		(start 383.401824 -252.906784)
		(mid 383.68478 -252.830607)
		(end 383.967736 -252.906784)
		(width 0.0889)
		(layer "In4.Cu")
		(net "M_J_CPU0_SA_CA<0>")
	)
	(arc
		(start 382.46177 -252.906784)
		(mid 382.744726 -252.830607)
		(end 383.027682 -252.906784)
		(width 0.0889)
		(layer "In4.Cu")
		(net "M_J_CPU0_SA_CA<0>")
	)
	(arc
		(start 381.52197 -252.906784)
		(mid 381.804926 -252.830607)
		(end 382.087882 -252.906784)
		(width 0.0889)
		(layer "In4.Cu")
		(net "M_J_CPU0_SA_CA<0>")
	)
	(arc
		(start 388.667752 -252.906784)
		(mid 388.850003 -252.957134)
		(end 389.033512 -252.91161)
		(width 0.0889)
		(layer "In4.Cu")
		(net "M_J_CPU0_SA_CA<0>")
	)
	(arc
		(start 381.15621 -252.91161)
		(mid 381.339718 -252.957104)
		(end 381.52197 -252.906784)
		(width 0.0889)
		(layer "In4.Cu")
		(net "M_J_CPU0_SA_CA<0>")
	)
	(arc
		(start 388.10184 -252.906784)
		(mid 388.384796 -252.830607)
		(end 388.667752 -252.906784)
		(width 0.0889)
		(layer "In4.Cu")
		(net "M_J_CPU0_SA_CA<0>")
	)
	(arc
		(start 382.087882 -252.906784)
		(mid 382.274826 -252.957039)
		(end 382.46177 -252.906784)
		(width 0.0889)
		(layer "In4.Cu")
		(net "M_J_CPU0_SA_CA<0>")
	)
	(arc
		(start 380.645162 -252.875034)
		(mid 380.900227 -252.831683)
		(end 381.147828 -252.906784)
		(width 0.0889)
		(layer "In4.Cu")
		(net "M_J_CPU0_SA_CA<0>")
	)
	(arc
		(start 387.161786 -252.906784)
		(mid 387.444742 -252.830607)
		(end 387.727698 -252.906784)
		(width 0.0889)
		(layer "In4.Cu")
		(net "M_J_CPU0_SA_CA<0>")
	)
	(arc
		(start 392.818112 -252.897386)
		(mid 393.094421 -252.83041)
		(end 393.368276 -252.906784)
		(width 0.0889)
		(layer "In4.Cu")
		(net "M_J_CPU0_SA_CA<0>")
	)
	(arc
		(start 389.041894 -252.906784)
		(mid 389.32485 -252.830607)
		(end 389.607806 -252.906784)
		(width 0.0889)
		(layer "In4.Cu")
		(net "M_J_CPU0_SA_CA<0>")
	)
	(arc
		(start 384.341878 -252.906784)
		(mid 384.624834 -252.830607)
		(end 384.90779 -252.906784)
		(width 0.0889)
		(layer "In4.Cu")
		(net "M_J_CPU0_SA_CA<0>")
	)
	(arc
		(start 391.86231 -252.906784)
		(mid 392.139377 -252.830513)
		(end 392.418062 -252.900688)
		(width 0.0889)
		(layer "In4.Cu")
		(net "M_J_CPU0_SA_CA<0>")
	)
	(segment
		(start 378.988066 -251.23013)
		(end 379.454918 -250.964192)
		(width 0.10668)
		(layer "F.Cu")
		(net "M_J_CPU0_RESET_N")
	)
	(segment
		(start 428.674022 -247.060212)
		(end 430.374044 -245.36019)
		(width 0.11684)
		(layer "In4.Cu")
		(net "M_J_CPU0_RESET_N")
	)
	(segment
		(start 392.802364 -250.641866)
		(end 392.818112 -250.65101)
		(width 0.0889)
		(layer "In4.Cu")
		(net "M_J_CPU0_RESET_N")
	)
	(segment
		(start 397.767048 -250.378722)
		(end 408.472132 -250.378722)
		(width 0.11684)
		(layer "In4.Cu")
		(net "M_J_CPU0_RESET_N")
	)
	(segment
		(start 430.374044 -245.36019)
		(end 434.57495 -245.36019)
		(width 0.11684)
		(layer "In4.Cu")
		(net "M_J_CPU0_RESET_N")
	)
	(segment
		(start 379.63348 -250.636786)
		(end 379.641862 -250.641612)
		(width 0.0889)
		(layer "In4.Cu")
		(net "M_J_CPU0_RESET_N")
	)
	(segment
		(start 397.46936 -250.67641)
		(end 397.767048 -250.378722)
		(width 0.11684)
		(layer "In4.Cu")
		(net "M_J_CPU0_RESET_N")
	)
	(segment
		(start 384.333496 -250.636786)
		(end 384.341878 -250.641612)
		(width 0.0889)
		(layer "In4.Cu")
		(net "M_J_CPU0_RESET_N")
	)
	(segment
		(start 391.48766 -250.641612)
		(end 391.496042 -250.636786)
		(width 0.0889)
		(layer "In4.Cu")
		(net "M_J_CPU0_RESET_N")
	)
	(segment
		(start 379.30074 -250.698762)
		(end 379.323092 -250.61545)
		(width 0.0889)
		(layer "In4.Cu")
		(net "M_J_CPU0_RESET_N")
	)
	(segment
		(start 389.607806 -250.641612)
		(end 389.616188 -250.636786)
		(width 0.0889)
		(layer "In4.Cu")
		(net "M_J_CPU0_RESET_N")
	)
	(segment
		(start 379.454918 -250.964192)
		(end 379.30074 -250.698762)
		(width 0.0889)
		(layer "In4.Cu")
		(net "M_J_CPU0_RESET_N")
	)
	(segment
		(start 434.57495 -245.36019)
		(end 435.000146 -244.934994)
		(width 0.11684)
		(layer "In4.Cu")
		(net "M_J_CPU0_RESET_N")
	)
	(segment
		(start 395.293088 -250.724162)
		(end 395.34084 -250.67641)
		(width 0.0889)
		(layer "In4.Cu")
		(net "M_J_CPU0_RESET_N")
	)
	(segment
		(start 411.790642 -247.060212)
		(end 428.674022 -247.060212)
		(width 0.11684)
		(layer "In4.Cu")
		(net "M_J_CPU0_RESET_N")
	)
	(segment
		(start 383.393442 -250.636786)
		(end 383.401824 -250.641612)
		(width 0.0889)
		(layer "In4.Cu")
		(net "M_J_CPU0_RESET_N")
	)
	(segment
		(start 395.576552 -250.67641)
		(end 397.46936 -250.67641)
		(width 0.11684)
		(layer "In4.Cu")
		(net "M_J_CPU0_RESET_N")
	)
	(segment
		(start 408.472132 -250.378722)
		(end 411.790642 -247.060212)
		(width 0.11684)
		(layer "In4.Cu")
		(net "M_J_CPU0_RESET_N")
	)
	(segment
		(start 384.90779 -250.641612)
		(end 384.916172 -250.636786)
		(width 0.0889)
		(layer "In4.Cu")
		(net "M_J_CPU0_RESET_N")
	)
	(segment
		(start 388.093458 -250.636786)
		(end 388.10184 -250.641612)
		(width 0.0889)
		(layer "In4.Cu")
		(net "M_J_CPU0_RESET_N")
	)
	(segment
		(start 389.033512 -250.636786)
		(end 389.041894 -250.641612)
		(width 0.0889)
		(layer "In4.Cu")
		(net "M_J_CPU0_RESET_N")
	)
	(segment
		(start 380.207774 -250.641612)
		(end 380.216156 -250.636786)
		(width 0.0889)
		(layer "In4.Cu")
		(net "M_J_CPU0_RESET_N")
	)
	(segment
		(start 393.107418 -250.724162)
		(end 395.293088 -250.724162)
		(width 0.0889)
		(layer "In4.Cu")
		(net "M_J_CPU0_RESET_N")
	)
	(segment
		(start 395.34084 -250.67641)
		(end 395.576552 -250.67641)
		(width 0.0889)
		(layer "In4.Cu")
		(net "M_J_CPU0_RESET_N")
	)
	(segment
		(start 381.147828 -250.641612)
		(end 381.15621 -250.636786)
		(width 0.0889)
		(layer "In4.Cu")
		(net "M_J_CPU0_RESET_N")
	)
	(segment
		(start 392.413998 -250.650248)
		(end 392.42873 -250.641612)
		(width 0.0889)
		(layer "In4.Cu")
		(net "M_J_CPU0_RESET_N")
	)
	(segment
		(start 392.788648 -250.633992)
		(end 392.802364 -250.641866)
		(width 0.0889)
		(layer "In4.Cu")
		(net "M_J_CPU0_RESET_N")
	)
	(segment
		(start 385.847844 -250.641612)
		(end 385.856226 -250.636786)
		(width 0.0889)
		(layer "In4.Cu")
		(net "M_J_CPU0_RESET_N")
	)
	(arc
		(start 381.52197 -250.641612)
		(mid 381.804926 -250.717789)
		(end 382.087882 -250.641612)
		(width 0.0889)
		(layer "In4.Cu")
		(net "M_J_CPU0_RESET_N")
	)
	(arc
		(start 382.46177 -250.641612)
		(mid 382.744726 -250.717789)
		(end 383.027682 -250.641612)
		(width 0.0889)
		(layer "In4.Cu")
		(net "M_J_CPU0_RESET_N")
	)
	(arc
		(start 389.616188 -250.636786)
		(mid 389.799696 -250.591292)
		(end 389.981948 -250.641612)
		(width 0.0889)
		(layer "In4.Cu")
		(net "M_J_CPU0_RESET_N")
	)
	(arc
		(start 391.496042 -250.636786)
		(mid 391.679804 -250.59117)
		(end 391.86231 -250.641612)
		(width 0.0889)
		(layer "In4.Cu")
		(net "M_J_CPU0_RESET_N")
	)
	(arc
		(start 392.42873 -250.641612)
		(mid 392.607717 -250.591442)
		(end 392.788648 -250.633992)
		(width 0.0889)
		(layer "In4.Cu")
		(net "M_J_CPU0_RESET_N")
	)
	(arc
		(start 382.087882 -250.641612)
		(mid 382.274826 -250.591357)
		(end 382.46177 -250.641612)
		(width 0.0889)
		(layer "In4.Cu")
		(net "M_J_CPU0_RESET_N")
	)
	(arc
		(start 380.216156 -250.636786)
		(mid 380.399664 -250.591292)
		(end 380.581916 -250.641612)
		(width 0.0889)
		(layer "In4.Cu")
		(net "M_J_CPU0_RESET_N")
	)
	(arc
		(start 392.818112 -250.65101)
		(mid 392.957641 -250.707846)
		(end 393.107418 -250.724162)
		(width 0.0889)
		(layer "In4.Cu")
		(net "M_J_CPU0_RESET_N")
	)
	(arc
		(start 389.041894 -250.641612)
		(mid 389.32485 -250.717789)
		(end 389.607806 -250.641612)
		(width 0.0889)
		(layer "In4.Cu")
		(net "M_J_CPU0_RESET_N")
	)
	(arc
		(start 380.581916 -250.641612)
		(mid 380.864872 -250.717789)
		(end 381.147828 -250.641612)
		(width 0.0889)
		(layer "In4.Cu")
		(net "M_J_CPU0_RESET_N")
	)
	(arc
		(start 385.281932 -250.641612)
		(mid 385.564888 -250.717789)
		(end 385.847844 -250.641612)
		(width 0.0889)
		(layer "In4.Cu")
		(net "M_J_CPU0_RESET_N")
	)
	(arc
		(start 383.401824 -250.641612)
		(mid 383.68478 -250.717789)
		(end 383.967736 -250.641612)
		(width 0.0889)
		(layer "In4.Cu")
		(net "M_J_CPU0_RESET_N")
	)
	(arc
		(start 379.323092 -250.61545)
		(mid 379.480602 -250.592252)
		(end 379.63348 -250.636786)
		(width 0.0889)
		(layer "In4.Cu")
		(net "M_J_CPU0_RESET_N")
	)
	(arc
		(start 389.981948 -250.641612)
		(mid 390.264904 -250.717789)
		(end 390.54786 -250.641612)
		(width 0.0889)
		(layer "In4.Cu")
		(net "M_J_CPU0_RESET_N")
	)
	(arc
		(start 387.727698 -250.641612)
		(mid 387.909949 -250.591262)
		(end 388.093458 -250.636786)
		(width 0.0889)
		(layer "In4.Cu")
		(net "M_J_CPU0_RESET_N")
	)
	(arc
		(start 388.10184 -250.641612)
		(mid 388.384796 -250.717789)
		(end 388.667752 -250.641612)
		(width 0.0889)
		(layer "In4.Cu")
		(net "M_J_CPU0_RESET_N")
	)
	(arc
		(start 390.921748 -250.641612)
		(mid 391.204704 -250.717789)
		(end 391.48766 -250.641612)
		(width 0.0889)
		(layer "In4.Cu")
		(net "M_J_CPU0_RESET_N")
	)
	(arc
		(start 391.86231 -250.641612)
		(mid 392.137016 -250.717976)
		(end 392.413998 -250.650248)
		(width 0.0889)
		(layer "In4.Cu")
		(net "M_J_CPU0_RESET_N")
	)
	(arc
		(start 386.787898 -250.641612)
		(mid 386.974842 -250.591357)
		(end 387.161786 -250.641612)
		(width 0.0889)
		(layer "In4.Cu")
		(net "M_J_CPU0_RESET_N")
	)
	(arc
		(start 383.967736 -250.641612)
		(mid 384.149987 -250.591262)
		(end 384.333496 -250.636786)
		(width 0.0889)
		(layer "In4.Cu")
		(net "M_J_CPU0_RESET_N")
	)
	(arc
		(start 388.667752 -250.641612)
		(mid 388.850003 -250.591262)
		(end 389.033512 -250.636786)
		(width 0.0889)
		(layer "In4.Cu")
		(net "M_J_CPU0_RESET_N")
	)
	(arc
		(start 390.54786 -250.641612)
		(mid 390.734804 -250.591357)
		(end 390.921748 -250.641612)
		(width 0.0889)
		(layer "In4.Cu")
		(net "M_J_CPU0_RESET_N")
	)
	(arc
		(start 387.161786 -250.641612)
		(mid 387.444742 -250.717789)
		(end 387.727698 -250.641612)
		(width 0.0889)
		(layer "In4.Cu")
		(net "M_J_CPU0_RESET_N")
	)
	(arc
		(start 386.221986 -250.641612)
		(mid 386.504942 -250.717789)
		(end 386.787898 -250.641612)
		(width 0.0889)
		(layer "In4.Cu")
		(net "M_J_CPU0_RESET_N")
	)
	(arc
		(start 385.856226 -250.636786)
		(mid 386.039734 -250.591292)
		(end 386.221986 -250.641612)
		(width 0.0889)
		(layer "In4.Cu")
		(net "M_J_CPU0_RESET_N")
	)
	(arc
		(start 379.641862 -250.641612)
		(mid 379.924818 -250.717789)
		(end 380.207774 -250.641612)
		(width 0.0889)
		(layer "In4.Cu")
		(net "M_J_CPU0_RESET_N")
	)
	(arc
		(start 383.027682 -250.641612)
		(mid 383.209933 -250.591262)
		(end 383.393442 -250.636786)
		(width 0.0889)
		(layer "In4.Cu")
		(net "M_J_CPU0_RESET_N")
	)
	(arc
		(start 381.15621 -250.636786)
		(mid 381.339718 -250.591292)
		(end 381.52197 -250.641612)
		(width 0.0889)
		(layer "In4.Cu")
		(net "M_J_CPU0_RESET_N")
	)
	(arc
		(start 384.341878 -250.641612)
		(mid 384.624834 -250.717789)
		(end 384.90779 -250.641612)
		(width 0.0889)
		(layer "In4.Cu")
		(net "M_J_CPU0_RESET_N")
	)
	(arc
		(start 384.916172 -250.636786)
		(mid 385.09968 -250.591292)
		(end 385.281932 -250.641612)
		(width 0.0889)
		(layer "In4.Cu")
		(net "M_J_CPU0_RESET_N")
	)
	(segment
		(start 379.927866 -256.090166)
		(end 380.394718 -255.824228)
		(width 0.14732)
		(layer "F.Cu")
		(net "M_J_CPU0_CLK_DP<0>")
	)
	(segment
		(start 395.715236 -257.312922)
		(end 395.738858 -257.312922)
		(width 0.09525)
		(layer "In4.Cu")
		(net "M_J_CPU0_CLK_DP<0>")
	)
	(segment
		(start 381.146304 -256.149348)
		(end 381.154686 -256.154174)
		(width 0.09525)
		(layer "In4.Cu")
		(net "M_J_CPU0_CLK_DP<0>")
	)
	(segment
		(start 393.481306 -256.23774)
		(end 394.61567 -257.372104)
		(width 0.09525)
		(layer "In4.Cu")
		(net "M_J_CPU0_CLK_DP<0>")
	)
	(segment
		(start 424.307508 -256.460752)
		(end 424.710098 -256.863342)
		(width 0.16002)
		(layer "In4.Cu")
		(net "M_J_CPU0_CLK_DP<0>")
	)
	(segment
		(start 425.479972 -256.863342)
		(end 425.882562 -256.460752)
		(width 0.16002)
		(layer "In4.Cu")
		(net "M_J_CPU0_CLK_DP<0>")
	)
	(segment
		(start 426.451776 -256.460752)
		(end 426.854366 -256.863342)
		(width 0.16002)
		(layer "In4.Cu")
		(net "M_J_CPU0_CLK_DP<0>")
	)
	(segment
		(start 384.906266 -256.149348)
		(end 384.914648 -256.154174)
		(width 0.09525)
		(layer "In4.Cu")
		(net "M_J_CPU0_CLK_DP<0>")
	)
	(segment
		(start 425.25442 -257.479292)
		(end 425.479972 -257.25374)
		(width 0.16002)
		(layer "In4.Cu")
		(net "M_J_CPU0_CLK_DP<0>")
	)
	(segment
		(start 383.394966 -256.154174)
		(end 383.403348 -256.149348)
		(width 0.09525)
		(layer "In4.Cu")
		(net "M_J_CPU0_CLK_DP<0>")
	)
	(segment
		(start 424.710098 -257.25374)
		(end 424.93565 -257.479292)
		(width 0.16002)
		(layer "In4.Cu")
		(net "M_J_CPU0_CLK_DP<0>")
	)
	(segment
		(start 434.726334 -253.708916)
		(end 435.000146 -253.435104)
		(width 0.16002)
		(layer "In4.Cu")
		(net "M_J_CPU0_CLK_DP<0>")
	)
	(segment
		(start 391.863326 -256.149348)
		(end 391.878058 -256.140712)
		(width 0.09525)
		(layer "In4.Cu")
		(net "M_J_CPU0_CLK_DP<0>")
	)
	(segment
		(start 392.78941 -256.15773)
		(end 392.803888 -256.149348)
		(width 0.09525)
		(layer "In4.Cu")
		(net "M_J_CPU0_CLK_DP<0>")
	)
	(segment
		(start 403.884638 -256.460752)
		(end 424.307508 -256.460752)
		(width 0.16002)
		(layer "In4.Cu")
		(net "M_J_CPU0_CLK_DP<0>")
	)
	(segment
		(start 380.548642 -256.089658)
		(end 380.64948 -256.116328)
		(width 0.09525)
		(layer "In4.Cu")
		(net "M_J_CPU0_CLK_DP<0>")
	)
	(segment
		(start 427.398688 -257.479292)
		(end 427.62424 -257.25374)
		(width 0.16002)
		(layer "In4.Cu")
		(net "M_J_CPU0_CLK_DP<0>")
	)
	(segment
		(start 426.854366 -256.863342)
		(end 426.854366 -257.25374)
		(width 0.16002)
		(layer "In4.Cu")
		(net "M_J_CPU0_CLK_DP<0>")
	)
	(segment
		(start 425.882562 -256.460752)
		(end 426.451776 -256.460752)
		(width 0.16002)
		(layer "In4.Cu")
		(net "M_J_CPU0_CLK_DP<0>")
	)
	(segment
		(start 392.803888 -256.149348)
		(end 392.824716 -256.137156)
		(width 0.09525)
		(layer "In4.Cu")
		(net "M_J_CPU0_CLK_DP<0>")
	)
	(segment
		(start 427.079918 -257.479292)
		(end 427.398688 -257.479292)
		(width 0.16002)
		(layer "In4.Cu")
		(net "M_J_CPU0_CLK_DP<0>")
	)
	(segment
		(start 432.485038 -256.460752)
		(end 433.772818 -255.172972)
		(width 0.16002)
		(layer "In4.Cu")
		(net "M_J_CPU0_CLK_DP<0>")
	)
	(segment
		(start 403.249638 -255.825752)
		(end 403.884638 -256.460752)
		(width 0.16002)
		(layer "In4.Cu")
		(net "M_J_CPU0_CLK_DP<0>")
	)
	(segment
		(start 428.02683 -256.460752)
		(end 432.485038 -256.460752)
		(width 0.16002)
		(layer "In4.Cu")
		(net "M_J_CPU0_CLK_DP<0>")
	)
	(segment
		(start 398.833848 -257.312922)
		(end 400.321018 -255.825752)
		(width 0.16002)
		(layer "In4.Cu")
		(net "M_J_CPU0_CLK_DP<0>")
	)
	(segment
		(start 389.606282 -256.149348)
		(end 389.614664 -256.154174)
		(width 0.09525)
		(layer "In4.Cu")
		(net "M_J_CPU0_CLK_DP<0>")
	)
	(segment
		(start 391.854944 -256.154174)
		(end 391.863326 -256.149348)
		(width 0.09525)
		(layer "In4.Cu")
		(net "M_J_CPU0_CLK_DP<0>")
	)
	(segment
		(start 433.772818 -255.172972)
		(end 433.772818 -254.045974)
		(width 0.16002)
		(layer "In4.Cu")
		(net "M_J_CPU0_CLK_DP<0>")
	)
	(segment
		(start 395.738858 -257.312922)
		(end 398.833848 -257.312922)
		(width 0.16002)
		(layer "In4.Cu")
		(net "M_J_CPU0_CLK_DP<0>")
	)
	(segment
		(start 426.854366 -257.25374)
		(end 427.079918 -257.479292)
		(width 0.16002)
		(layer "In4.Cu")
		(net "M_J_CPU0_CLK_DP<0>")
	)
	(segment
		(start 388.094982 -256.154174)
		(end 388.103364 -256.149348)
		(width 0.09525)
		(layer "In4.Cu")
		(net "M_J_CPU0_CLK_DP<0>")
	)
	(segment
		(start 425.479972 -257.25374)
		(end 425.479972 -256.863342)
		(width 0.16002)
		(layer "In4.Cu")
		(net "M_J_CPU0_CLK_DP<0>")
	)
	(segment
		(start 427.62424 -256.863342)
		(end 428.02683 -256.460752)
		(width 0.16002)
		(layer "In4.Cu")
		(net "M_J_CPU0_CLK_DP<0>")
	)
	(segment
		(start 400.321018 -255.825752)
		(end 403.249638 -255.825752)
		(width 0.16002)
		(layer "In4.Cu")
		(net "M_J_CPU0_CLK_DP<0>")
	)
	(segment
		(start 434.109876 -253.708916)
		(end 434.726334 -253.708916)
		(width 0.16002)
		(layer "In4.Cu")
		(net "M_J_CPU0_CLK_DP<0>")
	)
	(segment
		(start 384.33502 -256.154174)
		(end 384.343402 -256.149348)
		(width 0.09525)
		(layer "In4.Cu")
		(net "M_J_CPU0_CLK_DP<0>")
	)
	(segment
		(start 394.61567 -257.372104)
		(end 395.656054 -257.372104)
		(width 0.09525)
		(layer "In4.Cu")
		(net "M_J_CPU0_CLK_DP<0>")
	)
	(segment
		(start 427.62424 -257.25374)
		(end 427.62424 -256.863342)
		(width 0.16002)
		(layer "In4.Cu")
		(net "M_J_CPU0_CLK_DP<0>")
	)
	(segment
		(start 424.93565 -257.479292)
		(end 425.25442 -257.479292)
		(width 0.16002)
		(layer "In4.Cu")
		(net "M_J_CPU0_CLK_DP<0>")
	)
	(segment
		(start 433.772818 -254.045974)
		(end 434.109876 -253.708916)
		(width 0.16002)
		(layer "In4.Cu")
		(net "M_J_CPU0_CLK_DP<0>")
	)
	(segment
		(start 389.035036 -256.154174)
		(end 389.043418 -256.149348)
		(width 0.09525)
		(layer "In4.Cu")
		(net "M_J_CPU0_CLK_DP<0>")
	)
	(segment
		(start 385.84632 -256.149348)
		(end 385.854702 -256.154174)
		(width 0.09525)
		(layer "In4.Cu")
		(net "M_J_CPU0_CLK_DP<0>")
	)
	(segment
		(start 424.710098 -256.863342)
		(end 424.710098 -257.25374)
		(width 0.16002)
		(layer "In4.Cu")
		(net "M_J_CPU0_CLK_DP<0>")
	)
	(segment
		(start 395.656054 -257.372104)
		(end 395.715236 -257.312922)
		(width 0.09525)
		(layer "In4.Cu")
		(net "M_J_CPU0_CLK_DP<0>")
	)
	(segment
		(start 380.394718 -255.824228)
		(end 380.548642 -256.089658)
		(width 0.09525)
		(layer "In4.Cu")
		(net "M_J_CPU0_CLK_DP<0>")
	)
	(arc
		(start 385.283456 -256.149348)
		(mid 385.564888 -256.073593)
		(end 385.84632 -256.149348)
		(width 0.09525)
		(layer "In4.Cu")
		(net "M_J_CPU0_CLK_DP<0>")
	)
	(arc
		(start 386.786374 -256.149348)
		(mid 386.974842 -256.200025)
		(end 387.16331 -256.149348)
		(width 0.09525)
		(layer "In4.Cu")
		(net "M_J_CPU0_CLK_DP<0>")
	)
	(arc
		(start 391.486136 -256.149348)
		(mid 391.669911 -256.20012)
		(end 391.854944 -256.154174)
		(width 0.09525)
		(layer "In4.Cu")
		(net "M_J_CPU0_CLK_DP<0>")
	)
	(arc
		(start 387.726174 -256.149348)
		(mid 387.909949 -256.20012)
		(end 388.094982 -256.154174)
		(width 0.09525)
		(layer "In4.Cu")
		(net "M_J_CPU0_CLK_DP<0>")
	)
	(arc
		(start 390.546336 -256.149348)
		(mid 390.734804 -256.200025)
		(end 390.923272 -256.149348)
		(width 0.09525)
		(layer "In4.Cu")
		(net "M_J_CPU0_CLK_DP<0>")
	)
	(arc
		(start 386.22351 -256.149348)
		(mid 386.504942 -256.073593)
		(end 386.786374 -256.149348)
		(width 0.09525)
		(layer "In4.Cu")
		(net "M_J_CPU0_CLK_DP<0>")
	)
	(arc
		(start 389.043418 -256.149348)
		(mid 389.32485 -256.073593)
		(end 389.606282 -256.149348)
		(width 0.09525)
		(layer "In4.Cu")
		(net "M_J_CPU0_CLK_DP<0>")
	)
	(arc
		(start 382.463294 -256.149348)
		(mid 382.744726 -256.073593)
		(end 383.026158 -256.149348)
		(width 0.09525)
		(layer "In4.Cu")
		(net "M_J_CPU0_CLK_DP<0>")
	)
	(arc
		(start 387.16331 -256.149348)
		(mid 387.444742 -256.073593)
		(end 387.726174 -256.149348)
		(width 0.09525)
		(layer "In4.Cu")
		(net "M_J_CPU0_CLK_DP<0>")
	)
	(arc
		(start 383.403348 -256.149348)
		(mid 383.68478 -256.073593)
		(end 383.966212 -256.149348)
		(width 0.09525)
		(layer "In4.Cu")
		(net "M_J_CPU0_CLK_DP<0>")
	)
	(arc
		(start 384.914648 -256.154174)
		(mid 385.09968 -256.200088)
		(end 385.283456 -256.149348)
		(width 0.09525)
		(layer "In4.Cu")
		(net "M_J_CPU0_CLK_DP<0>")
	)
	(arc
		(start 381.523494 -256.149348)
		(mid 381.804926 -256.073593)
		(end 382.086358 -256.149348)
		(width 0.09525)
		(layer "In4.Cu")
		(net "M_J_CPU0_CLK_DP<0>")
	)
	(arc
		(start 388.666228 -256.149348)
		(mid 388.850003 -256.20012)
		(end 389.035036 -256.154174)
		(width 0.09525)
		(layer "In4.Cu")
		(net "M_J_CPU0_CLK_DP<0>")
	)
	(arc
		(start 381.154686 -256.154174)
		(mid 381.339718 -256.200088)
		(end 381.523494 -256.149348)
		(width 0.09525)
		(layer "In4.Cu")
		(net "M_J_CPU0_CLK_DP<0>")
	)
	(arc
		(start 384.343402 -256.149348)
		(mid 384.624834 -256.073593)
		(end 384.906266 -256.149348)
		(width 0.09525)
		(layer "In4.Cu")
		(net "M_J_CPU0_CLK_DP<0>")
	)
	(arc
		(start 383.966212 -256.149348)
		(mid 384.149987 -256.20012)
		(end 384.33502 -256.154174)
		(width 0.09525)
		(layer "In4.Cu")
		(net "M_J_CPU0_CLK_DP<0>")
	)
	(arc
		(start 391.878058 -256.140712)
		(mid 392.153517 -256.073327)
		(end 392.426698 -256.149348)
		(width 0.09525)
		(layer "In4.Cu")
		(net "M_J_CPU0_CLK_DP<0>")
	)
	(arc
		(start 385.854702 -256.154174)
		(mid 386.039734 -256.200088)
		(end 386.22351 -256.149348)
		(width 0.09525)
		(layer "In4.Cu")
		(net "M_J_CPU0_CLK_DP<0>")
	)
	(arc
		(start 383.026158 -256.149348)
		(mid 383.209933 -256.20012)
		(end 383.394966 -256.154174)
		(width 0.09525)
		(layer "In4.Cu")
		(net "M_J_CPU0_CLK_DP<0>")
	)
	(arc
		(start 392.426698 -256.149348)
		(mid 392.606977 -256.200179)
		(end 392.78941 -256.15773)
		(width 0.09525)
		(layer "In4.Cu")
		(net "M_J_CPU0_CLK_DP<0>")
	)
	(arc
		(start 393.366752 -256.149348)
		(mid 393.426887 -256.189839)
		(end 393.481306 -256.23774)
		(width 0.09525)
		(layer "In4.Cu")
		(net "M_J_CPU0_CLK_DP<0>")
	)
	(arc
		(start 389.983472 -256.149348)
		(mid 390.264904 -256.073593)
		(end 390.546336 -256.149348)
		(width 0.09525)
		(layer "In4.Cu")
		(net "M_J_CPU0_CLK_DP<0>")
	)
	(arc
		(start 382.086358 -256.149348)
		(mid 382.274826 -256.200025)
		(end 382.463294 -256.149348)
		(width 0.09525)
		(layer "In4.Cu")
		(net "M_J_CPU0_CLK_DP<0>")
	)
	(arc
		(start 380.64948 -256.116328)
		(mid 380.901764 -256.074634)
		(end 381.146304 -256.149348)
		(width 0.09525)
		(layer "In4.Cu")
		(net "M_J_CPU0_CLK_DP<0>")
	)
	(arc
		(start 392.824716 -256.137156)
		(mid 393.097321 -256.07336)
		(end 393.366752 -256.149348)
		(width 0.09525)
		(layer "In4.Cu")
		(net "M_J_CPU0_CLK_DP<0>")
	)
	(arc
		(start 389.614664 -256.154174)
		(mid 389.799696 -256.200088)
		(end 389.983472 -256.149348)
		(width 0.09525)
		(layer "In4.Cu")
		(net "M_J_CPU0_CLK_DP<0>")
	)
	(arc
		(start 390.923272 -256.149348)
		(mid 391.204704 -256.073593)
		(end 391.486136 -256.149348)
		(width 0.09525)
		(layer "In4.Cu")
		(net "M_J_CPU0_CLK_DP<0>")
	)
	(arc
		(start 388.103364 -256.149348)
		(mid 388.384796 -256.073593)
		(end 388.666228 -256.149348)
		(width 0.09525)
		(layer "In4.Cu")
		(net "M_J_CPU0_CLK_DP<0>")
	)
	(segment
		(start 380.39802 -256.900172)
		(end 380.864872 -256.634234)
		(width 0.14732)
		(layer "F.Cu")
		(net "M_J_CPU0_CLK_DN<0>")
	)
	(segment
		(start 424.407838 -256.988564)
		(end 424.407838 -257.378962)
		(width 0.16002)
		(layer "In4.Cu")
		(net "M_J_CPU0_CLK_DN<0>")
	)
	(segment
		(start 433.735734 -255.637538)
		(end 434.075078 -255.298194)
		(width 0.16002)
		(layer "In4.Cu")
		(net "M_J_CPU0_CLK_DN<0>")
	)
	(segment
		(start 427.9265 -256.988564)
		(end 428.152052 -256.763012)
		(width 0.16002)
		(layer "In4.Cu")
		(net "M_J_CPU0_CLK_DN<0>")
	)
	(segment
		(start 425.782232 -256.988564)
		(end 426.007784 -256.763012)
		(width 0.16002)
		(layer "In4.Cu")
		(net "M_J_CPU0_CLK_DN<0>")
	)
	(segment
		(start 434.075078 -255.298194)
		(end 434.075078 -254.171196)
		(width 0.16002)
		(layer "In4.Cu")
		(net "M_J_CPU0_CLK_DN<0>")
	)
	(segment
		(start 434.726334 -254.011176)
		(end 435.000146 -254.284988)
		(width 0.16002)
		(layer "In4.Cu")
		(net "M_J_CPU0_CLK_DN<0>")
	)
	(segment
		(start 392.87577 -256.321306)
		(end 392.896598 -256.309114)
		(width 0.09525)
		(layer "In4.Cu")
		(net "M_J_CPU0_CLK_DN<0>")
	)
	(segment
		(start 426.552106 -257.378962)
		(end 426.954696 -257.781552)
		(width 0.16002)
		(layer "In4.Cu")
		(net "M_J_CPU0_CLK_DN<0>")
	)
	(segment
		(start 380.710948 -256.368804)
		(end 380.734316 -256.281936)
		(width 0.09525)
		(layer "In4.Cu")
		(net "M_J_CPU0_CLK_DN<0>")
	)
	(segment
		(start 425.782232 -257.378962)
		(end 425.782232 -256.988564)
		(width 0.16002)
		(layer "In4.Cu")
		(net "M_J_CPU0_CLK_DN<0>")
	)
	(segment
		(start 434.075078 -254.171196)
		(end 434.235098 -254.011176)
		(width 0.16002)
		(layer "In4.Cu")
		(net "M_J_CPU0_CLK_DN<0>")
	)
	(segment
		(start 387.256274 -256.309114)
		(end 387.264656 -256.304288)
		(width 0.09525)
		(layer "In4.Cu")
		(net "M_J_CPU0_CLK_DN<0>")
	)
	(segment
		(start 424.182286 -256.763012)
		(end 424.407838 -256.988564)
		(width 0.16002)
		(layer "In4.Cu")
		(net "M_J_CPU0_CLK_DN<0>")
	)
	(segment
		(start 427.52391 -257.781552)
		(end 427.9265 -257.378962)
		(width 0.16002)
		(layer "In4.Cu")
		(net "M_J_CPU0_CLK_DN<0>")
	)
	(segment
		(start 426.552106 -256.988564)
		(end 426.552106 -257.378962)
		(width 0.16002)
		(layer "In4.Cu")
		(net "M_J_CPU0_CLK_DN<0>")
	)
	(segment
		(start 381.985012 -256.304288)
		(end 381.993394 -256.309114)
		(width 0.09525)
		(layer "In4.Cu")
		(net "M_J_CPU0_CLK_DN<0>")
	)
	(segment
		(start 398.95907 -257.615182)
		(end 400.44624 -256.128012)
		(width 0.16002)
		(layer "In4.Cu")
		(net "M_J_CPU0_CLK_DN<0>")
	)
	(segment
		(start 424.407838 -257.378962)
		(end 424.810428 -257.781552)
		(width 0.16002)
		(layer "In4.Cu")
		(net "M_J_CPU0_CLK_DN<0>")
	)
	(segment
		(start 433.735734 -255.802638)
		(end 433.735734 -255.637538)
		(width 0.16002)
		(layer "In4.Cu")
		(net "M_J_CPU0_CLK_DN<0>")
	)
	(segment
		(start 380.864872 -256.634234)
		(end 380.710948 -256.368804)
		(width 0.09525)
		(layer "In4.Cu")
		(net "M_J_CPU0_CLK_DN<0>")
	)
	(segment
		(start 426.007784 -256.763012)
		(end 426.326554 -256.763012)
		(width 0.16002)
		(layer "In4.Cu")
		(net "M_J_CPU0_CLK_DN<0>")
	)
	(segment
		(start 426.326554 -256.763012)
		(end 426.552106 -256.988564)
		(width 0.16002)
		(layer "In4.Cu")
		(net "M_J_CPU0_CLK_DN<0>")
	)
	(segment
		(start 382.556258 -256.309114)
		(end 382.56464 -256.304288)
		(width 0.09525)
		(layer "In4.Cu")
		(net "M_J_CPU0_CLK_DN<0>")
	)
	(segment
		(start 390.44499 -256.304288)
		(end 390.453372 -256.309114)
		(width 0.09525)
		(layer "In4.Cu")
		(net "M_J_CPU0_CLK_DN<0>")
	)
	(segment
		(start 391.016236 -256.309114)
		(end 391.024618 -256.304288)
		(width 0.09525)
		(layer "In4.Cu")
		(net "M_J_CPU0_CLK_DN<0>")
	)
	(segment
		(start 385.744974 -256.304288)
		(end 385.753356 -256.309114)
		(width 0.09525)
		(layer "In4.Cu")
		(net "M_J_CPU0_CLK_DN<0>")
	)
	(segment
		(start 427.9265 -257.378962)
		(end 427.9265 -256.988564)
		(width 0.16002)
		(layer "In4.Cu")
		(net "M_J_CPU0_CLK_DN<0>")
	)
	(segment
		(start 403.759416 -256.763012)
		(end 424.182286 -256.763012)
		(width 0.16002)
		(layer "In4.Cu")
		(net "M_J_CPU0_CLK_DN<0>")
	)
	(segment
		(start 388.196328 -256.309114)
		(end 388.20471 -256.304288)
		(width 0.09525)
		(layer "In4.Cu")
		(net "M_J_CPU0_CLK_DN<0>")
	)
	(segment
		(start 391.95629 -256.309114)
		(end 391.968228 -256.302256)
		(width 0.09525)
		(layer "In4.Cu")
		(net "M_J_CPU0_CLK_DN<0>")
	)
	(segment
		(start 386.685028 -256.304288)
		(end 386.69341 -256.309114)
		(width 0.09525)
		(layer "In4.Cu")
		(net "M_J_CPU0_CLK_DN<0>")
	)
	(segment
		(start 424.810428 -257.781552)
		(end 425.379642 -257.781552)
		(width 0.16002)
		(layer "In4.Cu")
		(net "M_J_CPU0_CLK_DN<0>")
	)
	(segment
		(start 434.235098 -254.011176)
		(end 434.726334 -254.011176)
		(width 0.16002)
		(layer "In4.Cu")
		(net "M_J_CPU0_CLK_DN<0>")
	)
	(segment
		(start 381.044958 -256.304288)
		(end 381.05334 -256.309114)
		(width 0.09525)
		(layer "In4.Cu")
		(net "M_J_CPU0_CLK_DN<0>")
	)
	(segment
		(start 395.656308 -257.556254)
		(end 395.715236 -257.615182)
		(width 0.09525)
		(layer "In4.Cu")
		(net "M_J_CPU0_CLK_DN<0>")
	)
	(segment
		(start 433.230782 -256.14249)
		(end 433.396136 -256.14249)
		(width 0.16002)
		(layer "In4.Cu")
		(net "M_J_CPU0_CLK_DN<0>")
	)
	(segment
		(start 392.896598 -256.309114)
		(end 392.911076 -256.300732)
		(width 0.09525)
		(layer "In4.Cu")
		(net "M_J_CPU0_CLK_DN<0>")
	)
	(segment
		(start 432.61026 -256.763012)
		(end 433.230782 -256.14249)
		(width 0.16002)
		(layer "In4.Cu")
		(net "M_J_CPU0_CLK_DN<0>")
	)
	(segment
		(start 433.396136 -256.14249)
		(end 433.735734 -255.802638)
		(width 0.16002)
		(layer "In4.Cu")
		(net "M_J_CPU0_CLK_DN<0>")
	)
	(segment
		(start 426.954696 -257.781552)
		(end 427.52391 -257.781552)
		(width 0.16002)
		(layer "In4.Cu")
		(net "M_J_CPU0_CLK_DN<0>")
	)
	(segment
		(start 395.738858 -257.615182)
		(end 398.95907 -257.615182)
		(width 0.16002)
		(layer "In4.Cu")
		(net "M_J_CPU0_CLK_DN<0>")
	)
	(segment
		(start 425.379642 -257.781552)
		(end 425.782232 -257.378962)
		(width 0.16002)
		(layer "In4.Cu")
		(net "M_J_CPU0_CLK_DN<0>")
	)
	(segment
		(start 393.351004 -256.368042)
		(end 394.539216 -257.556254)
		(width 0.09525)
		(layer "In4.Cu")
		(net "M_J_CPU0_CLK_DN<0>")
	)
	(segment
		(start 428.152052 -256.763012)
		(end 432.61026 -256.763012)
		(width 0.16002)
		(layer "In4.Cu")
		(net "M_J_CPU0_CLK_DN<0>")
	)
	(segment
		(start 403.124416 -256.128012)
		(end 403.759416 -256.763012)
		(width 0.16002)
		(layer "In4.Cu")
		(net "M_J_CPU0_CLK_DN<0>")
	)
	(segment
		(start 394.539216 -257.556254)
		(end 395.656308 -257.556254)
		(width 0.09525)
		(layer "In4.Cu")
		(net "M_J_CPU0_CLK_DN<0>")
	)
	(segment
		(start 395.715236 -257.615182)
		(end 395.738858 -257.615182)
		(width 0.09525)
		(layer "In4.Cu")
		(net "M_J_CPU0_CLK_DN<0>")
	)
	(segment
		(start 400.44624 -256.128012)
		(end 403.124416 -256.128012)
		(width 0.16002)
		(layer "In4.Cu")
		(net "M_J_CPU0_CLK_DN<0>")
	)
	(segment
		(start 383.496312 -256.309114)
		(end 383.504694 -256.304288)
		(width 0.09525)
		(layer "In4.Cu")
		(net "M_J_CPU0_CLK_DN<0>")
	)
	(arc
		(start 389.513318 -256.309114)
		(mid 389.79475 -256.384869)
		(end 390.076182 -256.309114)
		(width 0.09525)
		(layer "In4.Cu")
		(net "M_J_CPU0_CLK_DN<0>")
	)
	(arc
		(start 382.56464 -256.304288)
		(mid 382.749672 -256.258374)
		(end 382.933448 -256.309114)
		(width 0.09525)
		(layer "In4.Cu")
		(net "M_J_CPU0_CLK_DN<0>")
	)
	(arc
		(start 381.05334 -256.309114)
		(mid 381.334772 -256.384869)
		(end 381.616204 -256.309114)
		(width 0.09525)
		(layer "In4.Cu")
		(net "M_J_CPU0_CLK_DN<0>")
	)
	(arc
		(start 384.436366 -256.309114)
		(mid 384.624834 -256.258437)
		(end 384.813302 -256.309114)
		(width 0.09525)
		(layer "In4.Cu")
		(net "M_J_CPU0_CLK_DN<0>")
	)
	(arc
		(start 383.504694 -256.304288)
		(mid 383.689726 -256.258374)
		(end 383.873502 -256.309114)
		(width 0.09525)
		(layer "In4.Cu")
		(net "M_J_CPU0_CLK_DN<0>")
	)
	(arc
		(start 387.264656 -256.304288)
		(mid 387.449688 -256.258374)
		(end 387.633464 -256.309114)
		(width 0.09525)
		(layer "In4.Cu")
		(net "M_J_CPU0_CLK_DN<0>")
	)
	(arc
		(start 392.333734 -256.309114)
		(mid 392.603167 -256.384985)
		(end 392.87577 -256.321306)
		(width 0.09525)
		(layer "In4.Cu")
		(net "M_J_CPU0_CLK_DN<0>")
	)
	(arc
		(start 391.968228 -256.302256)
		(mid 392.151863 -256.258306)
		(end 392.333734 -256.309114)
		(width 0.09525)
		(layer "In4.Cu")
		(net "M_J_CPU0_CLK_DN<0>")
	)
	(arc
		(start 389.136382 -256.309114)
		(mid 389.32485 -256.258437)
		(end 389.513318 -256.309114)
		(width 0.09525)
		(layer "In4.Cu")
		(net "M_J_CPU0_CLK_DN<0>")
	)
	(arc
		(start 393.273788 -256.309114)
		(mid 393.314312 -256.336069)
		(end 393.351004 -256.368042)
		(width 0.09525)
		(layer "In4.Cu")
		(net "M_J_CPU0_CLK_DN<0>")
	)
	(arc
		(start 388.20471 -256.304288)
		(mid 388.389742 -256.258374)
		(end 388.573518 -256.309114)
		(width 0.09525)
		(layer "In4.Cu")
		(net "M_J_CPU0_CLK_DN<0>")
	)
	(arc
		(start 390.453372 -256.309114)
		(mid 390.734804 -256.384869)
		(end 391.016236 -256.309114)
		(width 0.09525)
		(layer "In4.Cu")
		(net "M_J_CPU0_CLK_DN<0>")
	)
	(arc
		(start 388.573518 -256.309114)
		(mid 388.85495 -256.384869)
		(end 389.136382 -256.309114)
		(width 0.09525)
		(layer "In4.Cu")
		(net "M_J_CPU0_CLK_DN<0>")
	)
	(arc
		(start 385.376166 -256.309114)
		(mid 385.559941 -256.258342)
		(end 385.744974 -256.304288)
		(width 0.09525)
		(layer "In4.Cu")
		(net "M_J_CPU0_CLK_DN<0>")
	)
	(arc
		(start 383.873502 -256.309114)
		(mid 384.154934 -256.384869)
		(end 384.436366 -256.309114)
		(width 0.09525)
		(layer "In4.Cu")
		(net "M_J_CPU0_CLK_DN<0>")
	)
	(arc
		(start 386.69341 -256.309114)
		(mid 386.974842 -256.384869)
		(end 387.256274 -256.309114)
		(width 0.09525)
		(layer "In4.Cu")
		(net "M_J_CPU0_CLK_DN<0>")
	)
	(arc
		(start 390.076182 -256.309114)
		(mid 390.259957 -256.258342)
		(end 390.44499 -256.304288)
		(width 0.09525)
		(layer "In4.Cu")
		(net "M_J_CPU0_CLK_DN<0>")
	)
	(arc
		(start 381.993394 -256.309114)
		(mid 382.274826 -256.384869)
		(end 382.556258 -256.309114)
		(width 0.09525)
		(layer "In4.Cu")
		(net "M_J_CPU0_CLK_DN<0>")
	)
	(arc
		(start 391.024618 -256.304288)
		(mid 391.20965 -256.258374)
		(end 391.393426 -256.309114)
		(width 0.09525)
		(layer "In4.Cu")
		(net "M_J_CPU0_CLK_DN<0>")
	)
	(arc
		(start 386.31622 -256.309114)
		(mid 386.499995 -256.258342)
		(end 386.685028 -256.304288)
		(width 0.09525)
		(layer "In4.Cu")
		(net "M_J_CPU0_CLK_DN<0>")
	)
	(arc
		(start 385.753356 -256.309114)
		(mid 386.034788 -256.384869)
		(end 386.31622 -256.309114)
		(width 0.09525)
		(layer "In4.Cu")
		(net "M_J_CPU0_CLK_DN<0>")
	)
	(arc
		(start 387.633464 -256.309114)
		(mid 387.914896 -256.384869)
		(end 388.196328 -256.309114)
		(width 0.09525)
		(layer "In4.Cu")
		(net "M_J_CPU0_CLK_DN<0>")
	)
	(arc
		(start 391.393426 -256.309114)
		(mid 391.674858 -256.384869)
		(end 391.95629 -256.309114)
		(width 0.09525)
		(layer "In4.Cu")
		(net "M_J_CPU0_CLK_DN<0>")
	)
	(arc
		(start 392.911076 -256.300732)
		(mid 393.093508 -256.258292)
		(end 393.273788 -256.309114)
		(width 0.09525)
		(layer "In4.Cu")
		(net "M_J_CPU0_CLK_DN<0>")
	)
	(arc
		(start 384.813302 -256.309114)
		(mid 385.094734 -256.384869)
		(end 385.376166 -256.309114)
		(width 0.09525)
		(layer "In4.Cu")
		(net "M_J_CPU0_CLK_DN<0>")
	)
	(arc
		(start 381.616204 -256.309114)
		(mid 381.799979 -256.258342)
		(end 381.985012 -256.304288)
		(width 0.09525)
		(layer "In4.Cu")
		(net "M_J_CPU0_CLK_DN<0>")
	)
	(arc
		(start 382.933448 -256.309114)
		(mid 383.21488 -256.384869)
		(end 383.496312 -256.309114)
		(width 0.09525)
		(layer "In4.Cu")
		(net "M_J_CPU0_CLK_DN<0>")
	)
	(arc
		(start 380.734316 -256.281936)
		(mid 380.892066 -256.259417)
		(end 381.044958 -256.304288)
		(width 0.09525)
		(layer "In4.Cu")
		(net "M_J_CPU0_CLK_DN<0>")
	)
	(segment
		(start 378.517912 -250.420124)
		(end 378.984764 -250.154186)
		(width 0.10668)
		(layer "F.Cu")
		(net "M_J_CPU0_ALERT_R_N")
	)
	(segment
		(start 385.74345 -250.481592)
		(end 385.751832 -250.476766)
		(width 0.0889)
		(layer "In4.Cu")
		(net "M_J_CPU0_ALERT_R_N")
	)
	(segment
		(start 393.618974 -250.37669)
		(end 395.097508 -250.37669)
		(width 0.0889)
		(layer "In4.Cu")
		(net "M_J_CPU0_ALERT_R_N")
	)
	(segment
		(start 430.464468 -244.510052)
		(end 437.278272 -244.510052)
		(width 0.11684)
		(layer "In4.Cu")
		(net "M_J_CPU0_ALERT_R_N")
	)
	(segment
		(start 428.764446 -246.210074)
		(end 430.464468 -244.510052)
		(width 0.11684)
		(layer "In4.Cu")
		(net "M_J_CPU0_ALERT_R_N")
	)
	(segment
		(start 392.898122 -250.476512)
		(end 392.91641 -250.486926)
		(width 0.0889)
		(layer "In4.Cu")
		(net "M_J_CPU0_ALERT_R_N")
	)
	(segment
		(start 395.418818 -250.209812)
		(end 397.263874 -250.209812)
		(width 0.11684)
		(layer "In4.Cu")
		(net "M_J_CPU0_ALERT_R_N")
	)
	(segment
		(start 392.892534 -250.47321)
		(end 392.898122 -250.476512)
		(width 0.0889)
		(layer "In4.Cu")
		(net "M_J_CPU0_ALERT_R_N")
	)
	(segment
		(start 381.983488 -250.481592)
		(end 381.99187 -250.476766)
		(width 0.0889)
		(layer "In4.Cu")
		(net "M_J_CPU0_ALERT_R_N")
	)
	(segment
		(start 397.516604 -249.957082)
		(end 408.29738 -249.957082)
		(width 0.11684)
		(layer "In4.Cu")
		(net "M_J_CPU0_ALERT_R_N")
	)
	(segment
		(start 382.557782 -250.476766)
		(end 382.566164 -250.481592)
		(width 0.0889)
		(layer "In4.Cu")
		(net "M_J_CPU0_ALERT_R_N")
	)
	(segment
		(start 378.984764 -250.154186)
		(end 379.138942 -250.419616)
		(width 0.0889)
		(layer "In4.Cu")
		(net "M_J_CPU0_ALERT_R_N")
	)
	(segment
		(start 391.01776 -250.476766)
		(end 391.026142 -250.481592)
		(width 0.0889)
		(layer "In4.Cu")
		(net "M_J_CPU0_ALERT_R_N")
	)
	(segment
		(start 379.138942 -250.419616)
		(end 379.235208 -250.445016)
		(width 0.0889)
		(layer "In4.Cu")
		(net "M_J_CPU0_ALERT_R_N")
	)
	(segment
		(start 390.443466 -250.481592)
		(end 390.451848 -250.476766)
		(width 0.0889)
		(layer "In4.Cu")
		(net "M_J_CPU0_ALERT_R_N")
	)
	(segment
		(start 387.257798 -250.476766)
		(end 387.26618 -250.481592)
		(width 0.0889)
		(layer "In4.Cu")
		(net "M_J_CPU0_ALERT_R_N")
	)
	(segment
		(start 391.391902 -250.476766)
		(end 391.406634 -250.46813)
		(width 0.0889)
		(layer "In4.Cu")
		(net "M_J_CPU0_ALERT_R_N")
	)
	(segment
		(start 388.197852 -250.476766)
		(end 388.206234 -250.481592)
		(width 0.0889)
		(layer "In4.Cu")
		(net "M_J_CPU0_ALERT_R_N")
	)
	(segment
		(start 395.097508 -250.37669)
		(end 395.264386 -250.209812)
		(width 0.0889)
		(layer "In4.Cu")
		(net "M_J_CPU0_ALERT_R_N")
	)
	(segment
		(start 437.278272 -244.510052)
		(end 437.703214 -244.08511)
		(width 0.11684)
		(layer "In4.Cu")
		(net "M_J_CPU0_ALERT_R_N")
	)
	(segment
		(start 397.263874 -250.209812)
		(end 397.516604 -249.957082)
		(width 0.11684)
		(layer "In4.Cu")
		(net "M_J_CPU0_ALERT_R_N")
	)
	(segment
		(start 392.321034 -250.483624)
		(end 392.332718 -250.476766)
		(width 0.0889)
		(layer "In4.Cu")
		(net "M_J_CPU0_ALERT_R_N")
	)
	(segment
		(start 383.497836 -250.476766)
		(end 383.506218 -250.481592)
		(width 0.0889)
		(layer "In4.Cu")
		(net "M_J_CPU0_ALERT_R_N")
	)
	(segment
		(start 395.264386 -250.209812)
		(end 395.418818 -250.209812)
		(width 0.0889)
		(layer "In4.Cu")
		(net "M_J_CPU0_ALERT_R_N")
	)
	(segment
		(start 386.683504 -250.481592)
		(end 386.691886 -250.476766)
		(width 0.0889)
		(layer "In4.Cu")
		(net "M_J_CPU0_ALERT_R_N")
	)
	(segment
		(start 412.044388 -246.210074)
		(end 428.764446 -246.210074)
		(width 0.11684)
		(layer "In4.Cu")
		(net "M_J_CPU0_ALERT_R_N")
	)
	(segment
		(start 408.29738 -249.957082)
		(end 412.044388 -246.210074)
		(width 0.11684)
		(layer "In4.Cu")
		(net "M_J_CPU0_ALERT_R_N")
	)
	(segment
		(start 381.043434 -250.481592)
		(end 381.051816 -250.476766)
		(width 0.0889)
		(layer "In4.Cu")
		(net "M_J_CPU0_ALERT_R_N")
	)
	(arc
		(start 391.026142 -250.481592)
		(mid 391.20965 -250.527086)
		(end 391.391902 -250.476766)
		(width 0.0889)
		(layer "In4.Cu")
		(net "M_J_CPU0_ALERT_R_N")
	)
	(arc
		(start 386.691886 -250.476766)
		(mid 386.974842 -250.400589)
		(end 387.257798 -250.476766)
		(width 0.0889)
		(layer "In4.Cu")
		(net "M_J_CPU0_ALERT_R_N")
	)
	(arc
		(start 382.931924 -250.476766)
		(mid 383.21488 -250.400589)
		(end 383.497836 -250.476766)
		(width 0.0889)
		(layer "In4.Cu")
		(net "M_J_CPU0_ALERT_R_N")
	)
	(arc
		(start 387.63194 -250.476766)
		(mid 387.914896 -250.400589)
		(end 388.197852 -250.476766)
		(width 0.0889)
		(layer "In4.Cu")
		(net "M_J_CPU0_ALERT_R_N")
	)
	(arc
		(start 387.26618 -250.481592)
		(mid 387.449688 -250.527086)
		(end 387.63194 -250.476766)
		(width 0.0889)
		(layer "In4.Cu")
		(net "M_J_CPU0_ALERT_R_N")
	)
	(arc
		(start 383.871978 -250.476766)
		(mid 384.154934 -250.400589)
		(end 384.43789 -250.476766)
		(width 0.0889)
		(layer "In4.Cu")
		(net "M_J_CPU0_ALERT_R_N")
	)
	(arc
		(start 390.077706 -250.476766)
		(mid 390.259957 -250.527116)
		(end 390.443466 -250.481592)
		(width 0.0889)
		(layer "In4.Cu")
		(net "M_J_CPU0_ALERT_R_N")
	)
	(arc
		(start 380.111762 -250.476766)
		(mid 380.394718 -250.400589)
		(end 380.677674 -250.476766)
		(width 0.0889)
		(layer "In4.Cu")
		(net "M_J_CPU0_ALERT_R_N")
	)
	(arc
		(start 392.332718 -250.476766)
		(mid 392.612146 -250.4006)
		(end 392.892534 -250.47321)
		(width 0.0889)
		(layer "In4.Cu")
		(net "M_J_CPU0_ALERT_R_N")
	)
	(arc
		(start 379.235208 -250.445016)
		(mid 379.490273 -250.401665)
		(end 379.737874 -250.476766)
		(width 0.0889)
		(layer "In4.Cu")
		(net "M_J_CPU0_ALERT_R_N")
	)
	(arc
		(start 382.566164 -250.481592)
		(mid 382.749672 -250.527086)
		(end 382.931924 -250.476766)
		(width 0.0889)
		(layer "In4.Cu")
		(net "M_J_CPU0_ALERT_R_N")
	)
	(arc
		(start 391.406634 -250.46813)
		(mid 391.683617 -250.400326)
		(end 391.958322 -250.476766)
		(width 0.0889)
		(layer "In4.Cu")
		(net "M_J_CPU0_ALERT_R_N")
	)
	(arc
		(start 393.272264 -250.476766)
		(mid 393.439464 -250.405407)
		(end 393.618974 -250.37669)
		(width 0.0889)
		(layer "In4.Cu")
		(net "M_J_CPU0_ALERT_R_N")
	)
	(arc
		(start 388.206234 -250.481592)
		(mid 388.389742 -250.527086)
		(end 388.571994 -250.476766)
		(width 0.0889)
		(layer "In4.Cu")
		(net "M_J_CPU0_ALERT_R_N")
	)
	(arc
		(start 390.451848 -250.476766)
		(mid 390.734804 -250.400589)
		(end 391.01776 -250.476766)
		(width 0.0889)
		(layer "In4.Cu")
		(net "M_J_CPU0_ALERT_R_N")
	)
	(arc
		(start 381.99187 -250.476766)
		(mid 382.274826 -250.400589)
		(end 382.557782 -250.476766)
		(width 0.0889)
		(layer "In4.Cu")
		(net "M_J_CPU0_ALERT_R_N")
	)
	(arc
		(start 384.811778 -250.476766)
		(mid 385.094734 -250.400589)
		(end 385.37769 -250.476766)
		(width 0.0889)
		(layer "In4.Cu")
		(net "M_J_CPU0_ALERT_R_N")
	)
	(arc
		(start 380.677674 -250.476766)
		(mid 380.859925 -250.527116)
		(end 381.043434 -250.481592)
		(width 0.0889)
		(layer "In4.Cu")
		(net "M_J_CPU0_ALERT_R_N")
	)
	(arc
		(start 389.137906 -250.476766)
		(mid 389.32485 -250.527021)
		(end 389.511794 -250.476766)
		(width 0.0889)
		(layer "In4.Cu")
		(net "M_J_CPU0_ALERT_R_N")
	)
	(arc
		(start 392.91641 -250.486926)
		(mid 393.095639 -250.527079)
		(end 393.272264 -250.476766)
		(width 0.0889)
		(layer "In4.Cu")
		(net "M_J_CPU0_ALERT_R_N")
	)
	(arc
		(start 386.317744 -250.476766)
		(mid 386.499995 -250.527116)
		(end 386.683504 -250.481592)
		(width 0.0889)
		(layer "In4.Cu")
		(net "M_J_CPU0_ALERT_R_N")
	)
	(arc
		(start 383.506218 -250.481592)
		(mid 383.689726 -250.527086)
		(end 383.871978 -250.476766)
		(width 0.0889)
		(layer "In4.Cu")
		(net "M_J_CPU0_ALERT_R_N")
	)
	(arc
		(start 379.737874 -250.476766)
		(mid 379.924818 -250.527021)
		(end 380.111762 -250.476766)
		(width 0.0889)
		(layer "In4.Cu")
		(net "M_J_CPU0_ALERT_R_N")
	)
	(arc
		(start 381.617728 -250.476766)
		(mid 381.799979 -250.527116)
		(end 381.983488 -250.481592)
		(width 0.0889)
		(layer "In4.Cu")
		(net "M_J_CPU0_ALERT_R_N")
	)
	(arc
		(start 385.37769 -250.476766)
		(mid 385.559941 -250.527116)
		(end 385.74345 -250.481592)
		(width 0.0889)
		(layer "In4.Cu")
		(net "M_J_CPU0_ALERT_R_N")
	)
	(arc
		(start 381.051816 -250.476766)
		(mid 381.334772 -250.400589)
		(end 381.617728 -250.476766)
		(width 0.0889)
		(layer "In4.Cu")
		(net "M_J_CPU0_ALERT_R_N")
	)
	(arc
		(start 388.571994 -250.476766)
		(mid 388.85495 -250.400589)
		(end 389.137906 -250.476766)
		(width 0.0889)
		(layer "In4.Cu")
		(net "M_J_CPU0_ALERT_R_N")
	)
	(arc
		(start 391.958322 -250.476766)
		(mid 392.13878 -250.52721)
		(end 392.321034 -250.483624)
		(width 0.0889)
		(layer "In4.Cu")
		(net "M_J_CPU0_ALERT_R_N")
	)
	(arc
		(start 385.751832 -250.476766)
		(mid 386.034788 -250.400589)
		(end 386.317744 -250.476766)
		(width 0.0889)
		(layer "In4.Cu")
		(net "M_J_CPU0_ALERT_R_N")
	)
	(arc
		(start 384.43789 -250.476766)
		(mid 384.624834 -250.527021)
		(end 384.811778 -250.476766)
		(width 0.0889)
		(layer "In4.Cu")
		(net "M_J_CPU0_ALERT_R_N")
	)
	(arc
		(start 389.511794 -250.476766)
		(mid 389.79475 -250.400589)
		(end 390.077706 -250.476766)
		(width 0.0889)
		(layer "In4.Cu")
		(net "M_J_CPU0_ALERT_R_N")
	)
	(via
		(at 439.100214 -244.08511)
		(size 0.4826)
		(drill 0.254)
		(layers "F.Cu" "B.Cu")
		(net "M_J_CPU0_ALERT_N")
	)
	(segment
		(start 438.503314 -244.08511)
		(end 439.100214 -244.08511)
		(width 0.10668)
		(layer "B.Cu")
		(net "M_J_CPU0_ALERT_N")
	)
	(segment
		(start 128.997964 -267.340334)
		(end 129.464816 -267.606272)
		(width 0.10668)
		(layer "F.Cu")
		(net "M_I_CPU1_SB_RSP<0>")
	)
	(segment
		(start 143.377666 -267.283692)
		(end 143.386048 -267.278866)
		(width 0.0889)
		(layer "In2.Cu")
		(net "M_I_CPU1_SB_RSP<0>")
	)
	(segment
		(start 140.557758 -267.283692)
		(end 140.56614 -267.278866)
		(width 0.0889)
		(layer "In2.Cu")
		(net "M_I_CPU1_SB_RSP<0>")
	)
	(segment
		(start 134.343394 -267.278866)
		(end 134.351776 -267.283692)
		(width 0.0889)
		(layer "In2.Cu")
		(net "M_I_CPU1_SB_RSP<0>")
	)
	(segment
		(start 135.857742 -267.283692)
		(end 135.866124 -267.278866)
		(width 0.0889)
		(layer "In2.Cu")
		(net "M_I_CPU1_SB_RSP<0>")
	)
	(segment
		(start 144.289526 -267.298932)
		(end 144.315688 -267.283946)
		(width 0.0889)
		(layer "In2.Cu")
		(net "M_I_CPU1_SB_RSP<0>")
	)
	(segment
		(start 138.103356 -267.278866)
		(end 138.111738 -267.283692)
		(width 0.0889)
		(layer "In2.Cu")
		(net "M_I_CPU1_SB_RSP<0>")
	)
	(segment
		(start 144.688306 -267.283692)
		(end 144.71777 -267.300964)
		(width 0.0889)
		(layer "In2.Cu")
		(net "M_I_CPU1_SB_RSP<0>")
	)
	(segment
		(start 163.592002 -270.860266)
		(end 183.19115 -270.860266)
		(width 0.11684)
		(layer "In2.Cu")
		(net "M_I_CPU1_SB_RSP<0>")
	)
	(segment
		(start 147.61591 -266.570714)
		(end 157.80766 -266.570714)
		(width 0.11684)
		(layer "In2.Cu")
		(net "M_I_CPU1_SB_RSP<0>")
	)
	(segment
		(start 131.157726 -267.283692)
		(end 131.166108 -267.278866)
		(width 0.0889)
		(layer "In2.Cu")
		(net "M_I_CPU1_SB_RSP<0>")
	)
	(segment
		(start 132.09778 -267.283692)
		(end 132.106162 -267.278866)
		(width 0.0889)
		(layer "In2.Cu")
		(net "M_I_CPU1_SB_RSP<0>")
	)
	(segment
		(start 129.470404 -267.608558)
		(end 130.297174 -267.254228)
		(width 0.0889)
		(layer "In2.Cu")
		(net "M_I_CPU1_SB_RSP<0>")
	)
	(segment
		(start 145.33753 -267.248386)
		(end 146.421348 -266.164568)
		(width 0.0889)
		(layer "In2.Cu")
		(net "M_I_CPU1_SB_RSP<0>")
	)
	(segment
		(start 130.583432 -267.278866)
		(end 130.591814 -267.283692)
		(width 0.0889)
		(layer "In2.Cu")
		(net "M_I_CPU1_SB_RSP<0>")
	)
	(segment
		(start 146.421348 -266.164568)
		(end 147.209764 -266.164568)
		(width 0.0889)
		(layer "In2.Cu")
		(net "M_I_CPU1_SB_RSP<0>")
	)
	(segment
		(start 183.19115 -270.860266)
		(end 183.616092 -270.435324)
		(width 0.11684)
		(layer "In2.Cu")
		(net "M_I_CPU1_SB_RSP<0>")
	)
	(segment
		(start 139.04341 -267.278866)
		(end 139.051792 -267.283692)
		(width 0.0889)
		(layer "In2.Cu")
		(net "M_I_CPU1_SB_RSP<0>")
	)
	(segment
		(start 139.617704 -267.283692)
		(end 139.626086 -267.278866)
		(width 0.0889)
		(layer "In2.Cu")
		(net "M_I_CPU1_SB_RSP<0>")
	)
	(segment
		(start 129.464816 -267.606272)
		(end 129.470404 -267.608558)
		(width 0.0889)
		(layer "In2.Cu")
		(net "M_I_CPU1_SB_RSP<0>")
	)
	(segment
		(start 147.209764 -266.164568)
		(end 147.463764 -266.418568)
		(width 0.0889)
		(layer "In2.Cu")
		(net "M_I_CPU1_SB_RSP<0>")
	)
	(segment
		(start 134.917688 -267.283692)
		(end 134.92607 -267.278866)
		(width 0.0889)
		(layer "In2.Cu")
		(net "M_I_CPU1_SB_RSP<0>")
	)
	(segment
		(start 147.463764 -266.418568)
		(end 147.61591 -266.570714)
		(width 0.11684)
		(layer "In2.Cu")
		(net "M_I_CPU1_SB_RSP<0>")
	)
	(segment
		(start 157.80766 -266.570714)
		(end 163.592002 -270.860266)
		(width 0.11684)
		(layer "In2.Cu")
		(net "M_I_CPU1_SB_RSP<0>")
	)
	(segment
		(start 144.315688 -267.283946)
		(end 144.337532 -267.2715)
		(width 0.0889)
		(layer "In2.Cu")
		(net "M_I_CPU1_SB_RSP<0>")
	)
	(segment
		(start 142.803372 -267.278866)
		(end 142.811754 -267.283692)
		(width 0.0889)
		(layer "In2.Cu")
		(net "M_I_CPU1_SB_RSP<0>")
	)
	(arc
		(start 139.991846 -267.283692)
		(mid 140.274802 -267.359869)
		(end 140.557758 -267.283692)
		(width 0.0889)
		(layer "In2.Cu")
		(net "M_I_CPU1_SB_RSP<0>")
	)
	(arc
		(start 133.977634 -267.283692)
		(mid 134.159885 -267.233342)
		(end 134.343394 -267.278866)
		(width 0.0889)
		(layer "In2.Cu")
		(net "M_I_CPU1_SB_RSP<0>")
	)
	(arc
		(start 133.411722 -267.283692)
		(mid 133.694678 -267.359869)
		(end 133.977634 -267.283692)
		(width 0.0889)
		(layer "In2.Cu")
		(net "M_I_CPU1_SB_RSP<0>")
	)
	(arc
		(start 145.25625 -267.283692)
		(mid 145.295838 -267.263617)
		(end 145.33753 -267.248386)
		(width 0.0889)
		(layer "In2.Cu")
		(net "M_I_CPU1_SB_RSP<0>")
	)
	(arc
		(start 136.797796 -267.283692)
		(mid 136.98474 -267.233437)
		(end 137.171684 -267.283692)
		(width 0.0889)
		(layer "In2.Cu")
		(net "M_I_CPU1_SB_RSP<0>")
	)
	(arc
		(start 139.626086 -267.278866)
		(mid 139.809594 -267.233372)
		(end 139.991846 -267.283692)
		(width 0.0889)
		(layer "In2.Cu")
		(net "M_I_CPU1_SB_RSP<0>")
	)
	(arc
		(start 131.531868 -267.283692)
		(mid 131.814824 -267.359869)
		(end 132.09778 -267.283692)
		(width 0.0889)
		(layer "In2.Cu")
		(net "M_I_CPU1_SB_RSP<0>")
	)
	(arc
		(start 144.337532 -267.2715)
		(mid 144.51446 -267.233672)
		(end 144.688306 -267.283692)
		(width 0.0889)
		(layer "In2.Cu")
		(net "M_I_CPU1_SB_RSP<0>")
	)
	(arc
		(start 135.866124 -267.278866)
		(mid 136.049632 -267.233372)
		(end 136.231884 -267.283692)
		(width 0.0889)
		(layer "In2.Cu")
		(net "M_I_CPU1_SB_RSP<0>")
	)
	(arc
		(start 132.106162 -267.278866)
		(mid 132.28967 -267.233372)
		(end 132.471922 -267.283692)
		(width 0.0889)
		(layer "In2.Cu")
		(net "M_I_CPU1_SB_RSP<0>")
	)
	(arc
		(start 138.111738 -267.283692)
		(mid 138.394694 -267.359869)
		(end 138.67765 -267.283692)
		(width 0.0889)
		(layer "In2.Cu")
		(net "M_I_CPU1_SB_RSP<0>")
	)
	(arc
		(start 130.591814 -267.283692)
		(mid 130.87477 -267.359869)
		(end 131.157726 -267.283692)
		(width 0.0889)
		(layer "In2.Cu")
		(net "M_I_CPU1_SB_RSP<0>")
	)
	(arc
		(start 136.231884 -267.283692)
		(mid 136.51484 -267.359869)
		(end 136.797796 -267.283692)
		(width 0.0889)
		(layer "In2.Cu")
		(net "M_I_CPU1_SB_RSP<0>")
	)
	(arc
		(start 138.67765 -267.283692)
		(mid 138.859901 -267.233342)
		(end 139.04341 -267.278866)
		(width 0.0889)
		(layer "In2.Cu")
		(net "M_I_CPU1_SB_RSP<0>")
	)
	(arc
		(start 139.051792 -267.283692)
		(mid 139.334748 -267.359869)
		(end 139.617704 -267.283692)
		(width 0.0889)
		(layer "In2.Cu")
		(net "M_I_CPU1_SB_RSP<0>")
	)
	(arc
		(start 130.383788 -267.233908)
		(mid 130.486759 -267.242413)
		(end 130.583432 -267.278866)
		(width 0.0889)
		(layer "In2.Cu")
		(net "M_I_CPU1_SB_RSP<0>")
	)
	(arc
		(start 143.386048 -267.278866)
		(mid 143.569556 -267.233372)
		(end 143.751808 -267.283692)
		(width 0.0889)
		(layer "In2.Cu")
		(net "M_I_CPU1_SB_RSP<0>")
	)
	(arc
		(start 135.29183 -267.283692)
		(mid 135.574786 -267.359869)
		(end 135.857742 -267.283692)
		(width 0.0889)
		(layer "In2.Cu")
		(net "M_I_CPU1_SB_RSP<0>")
	)
	(arc
		(start 137.171684 -267.283692)
		(mid 137.45464 -267.359869)
		(end 137.737596 -267.283692)
		(width 0.0889)
		(layer "In2.Cu")
		(net "M_I_CPU1_SB_RSP<0>")
	)
	(arc
		(start 133.037834 -267.283692)
		(mid 133.224778 -267.233437)
		(end 133.411722 -267.283692)
		(width 0.0889)
		(layer "In2.Cu")
		(net "M_I_CPU1_SB_RSP<0>")
	)
	(arc
		(start 143.751808 -267.283692)
		(mid 144.018738 -267.359641)
		(end 144.289526 -267.298932)
		(width 0.0889)
		(layer "In2.Cu")
		(net "M_I_CPU1_SB_RSP<0>")
	)
	(arc
		(start 132.471922 -267.283692)
		(mid 132.754878 -267.359869)
		(end 133.037834 -267.283692)
		(width 0.0889)
		(layer "In2.Cu")
		(net "M_I_CPU1_SB_RSP<0>")
	)
	(arc
		(start 140.9319 -267.283692)
		(mid 141.214856 -267.359869)
		(end 141.497812 -267.283692)
		(width 0.0889)
		(layer "In2.Cu")
		(net "M_I_CPU1_SB_RSP<0>")
	)
	(arc
		(start 137.737596 -267.283692)
		(mid 137.919847 -267.233342)
		(end 138.103356 -267.278866)
		(width 0.0889)
		(layer "In2.Cu")
		(net "M_I_CPU1_SB_RSP<0>")
	)
	(arc
		(start 141.8717 -267.283692)
		(mid 142.154656 -267.359869)
		(end 142.437612 -267.283692)
		(width 0.0889)
		(layer "In2.Cu")
		(net "M_I_CPU1_SB_RSP<0>")
	)
	(arc
		(start 141.497812 -267.283692)
		(mid 141.684756 -267.233437)
		(end 141.8717 -267.283692)
		(width 0.0889)
		(layer "In2.Cu")
		(net "M_I_CPU1_SB_RSP<0>")
	)
	(arc
		(start 140.56614 -267.278866)
		(mid 140.749648 -267.233372)
		(end 140.9319 -267.283692)
		(width 0.0889)
		(layer "In2.Cu")
		(net "M_I_CPU1_SB_RSP<0>")
	)
	(arc
		(start 142.437612 -267.283692)
		(mid 142.619863 -267.233342)
		(end 142.803372 -267.278866)
		(width 0.0889)
		(layer "In2.Cu")
		(net "M_I_CPU1_SB_RSP<0>")
	)
	(arc
		(start 142.811754 -267.283692)
		(mid 143.09471 -267.359869)
		(end 143.377666 -267.283692)
		(width 0.0889)
		(layer "In2.Cu")
		(net "M_I_CPU1_SB_RSP<0>")
	)
	(arc
		(start 134.351776 -267.283692)
		(mid 134.634732 -267.359869)
		(end 134.917688 -267.283692)
		(width 0.0889)
		(layer "In2.Cu")
		(net "M_I_CPU1_SB_RSP<0>")
	)
	(arc
		(start 144.71777 -267.300964)
		(mid 144.98919 -267.360641)
		(end 145.25625 -267.283692)
		(width 0.0889)
		(layer "In2.Cu")
		(net "M_I_CPU1_SB_RSP<0>")
	)
	(arc
		(start 131.166108 -267.278866)
		(mid 131.349616 -267.233372)
		(end 131.531868 -267.283692)
		(width 0.0889)
		(layer "In2.Cu")
		(net "M_I_CPU1_SB_RSP<0>")
	)
	(arc
		(start 134.92607 -267.278866)
		(mid 135.109578 -267.233372)
		(end 135.29183 -267.283692)
		(width 0.0889)
		(layer "In2.Cu")
		(net "M_I_CPU1_SB_RSP<0>")
	)
	(arc
		(start 130.297174 -267.254228)
		(mid 130.339597 -267.240308)
		(end 130.383788 -267.233908)
		(width 0.0889)
		(layer "In2.Cu")
		(net "M_I_CPU1_SB_RSP<0>")
	)
	(segment
		(start 127.58801 -264.910316)
		(end 128.054862 -265.176254)
		(width 0.10668)
		(layer "F.Cu")
		(net "M_I_CPU1_SB_PAR")
	)
	(segment
		(start 144.19707 -265.512042)
		(end 144.220438 -265.49858)
		(width 0.0889)
		(layer "In2.Cu")
		(net "M_I_CPU1_SB_PAR")
	)
	(segment
		(start 140.453364 -265.50366)
		(end 140.461746 -265.498834)
		(width 0.0889)
		(layer "In2.Cu")
		(net "M_I_CPU1_SB_PAR")
	)
	(segment
		(start 135.753348 -265.50366)
		(end 135.76173 -265.498834)
		(width 0.0889)
		(layer "In2.Cu")
		(net "M_I_CPU1_SB_PAR")
	)
	(segment
		(start 175.23714 -267.460476)
		(end 179.090828 -267.460476)
		(width 0.14478)
		(layer "In2.Cu")
		(net "M_I_CPU1_SB_PAR")
	)
	(segment
		(start 138.20775 -265.498834)
		(end 138.216132 -265.50366)
		(width 0.0889)
		(layer "In2.Cu")
		(net "M_I_CPU1_SB_PAR")
	)
	(segment
		(start 136.693402 -265.50366)
		(end 136.701784 -265.498834)
		(width 0.0889)
		(layer "In2.Cu")
		(net "M_I_CPU1_SB_PAR")
	)
	(segment
		(start 158.622238 -264.793984)
		(end 163.610544 -267.460476)
		(width 0.14478)
		(layer "In2.Cu")
		(net "M_I_CPU1_SB_PAR")
	)
	(segment
		(start 128.807718 -265.498834)
		(end 128.8161 -265.50366)
		(width 0.0889)
		(layer "In2.Cu")
		(net "M_I_CPU1_SB_PAR")
	)
	(segment
		(start 174.410116 -267.460476)
		(end 174.685706 -267.184886)
		(width 0.14478)
		(layer "In2.Cu")
		(net "M_I_CPU1_SB_PAR")
	)
	(segment
		(start 129.747772 -265.498834)
		(end 129.756154 -265.50366)
		(width 0.0889)
		(layer "In2.Cu")
		(net "M_I_CPU1_SB_PAR")
	)
	(segment
		(start 179.090828 -267.460476)
		(end 179.516024 -267.03528)
		(width 0.14478)
		(layer "In2.Cu")
		(net "M_I_CPU1_SB_PAR")
	)
	(segment
		(start 128.208786 -265.441684)
		(end 128.304798 -265.467084)
		(width 0.0889)
		(layer "In2.Cu")
		(net "M_I_CPU1_SB_PAR")
	)
	(segment
		(start 174.685706 -267.184886)
		(end 174.96155 -267.184886)
		(width 0.14478)
		(layer "In2.Cu")
		(net "M_I_CPU1_SB_PAR")
	)
	(segment
		(start 128.054862 -265.176254)
		(end 128.208786 -265.441684)
		(width 0.0889)
		(layer "In2.Cu")
		(net "M_I_CPU1_SB_PAR")
	)
	(segment
		(start 137.267696 -265.498834)
		(end 137.276078 -265.50366)
		(width 0.0889)
		(layer "In2.Cu")
		(net "M_I_CPU1_SB_PAR")
	)
	(segment
		(start 131.993386 -265.50366)
		(end 132.001768 -265.498834)
		(width 0.0889)
		(layer "In2.Cu")
		(net "M_I_CPU1_SB_PAR")
	)
	(segment
		(start 141.393418 -265.50366)
		(end 141.4018 -265.498834)
		(width 0.0889)
		(layer "In2.Cu")
		(net "M_I_CPU1_SB_PAR")
	)
	(segment
		(start 144.220438 -265.49858)
		(end 144.2466 -265.483594)
		(width 0.0889)
		(layer "In2.Cu")
		(net "M_I_CPU1_SB_PAR")
	)
	(segment
		(start 147.537932 -264.793984)
		(end 158.622238 -264.793984)
		(width 0.14478)
		(layer "In2.Cu")
		(net "M_I_CPU1_SB_PAR")
	)
	(segment
		(start 163.610544 -267.460476)
		(end 174.410116 -267.460476)
		(width 0.14478)
		(layer "In2.Cu")
		(net "M_I_CPU1_SB_PAR")
	)
	(segment
		(start 146.114008 -264.544556)
		(end 147.288504 -264.544556)
		(width 0.0889)
		(layer "In2.Cu")
		(net "M_I_CPU1_SB_PAR")
	)
	(segment
		(start 144.784318 -265.498834)
		(end 144.804892 -265.510772)
		(width 0.0889)
		(layer "In2.Cu")
		(net "M_I_CPU1_SB_PAR")
	)
	(segment
		(start 141.967712 -265.498834)
		(end 141.976094 -265.50366)
		(width 0.0889)
		(layer "In2.Cu")
		(net "M_I_CPU1_SB_PAR")
	)
	(segment
		(start 147.288504 -264.544556)
		(end 147.537932 -264.793984)
		(width 0.0889)
		(layer "In2.Cu")
		(net "M_I_CPU1_SB_PAR")
	)
	(segment
		(start 132.93344 -265.50366)
		(end 132.941822 -265.498834)
		(width 0.0889)
		(layer "In2.Cu")
		(net "M_I_CPU1_SB_PAR")
	)
	(segment
		(start 145.15973 -265.498834)
		(end 146.114008 -264.544556)
		(width 0.0889)
		(layer "In2.Cu")
		(net "M_I_CPU1_SB_PAR")
	)
	(segment
		(start 174.96155 -267.184886)
		(end 175.23714 -267.460476)
		(width 0.14478)
		(layer "In2.Cu")
		(net "M_I_CPU1_SB_PAR")
	)
	(segment
		(start 133.507734 -265.498834)
		(end 133.516116 -265.50366)
		(width 0.0889)
		(layer "In2.Cu")
		(net "M_I_CPU1_SB_PAR")
	)
	(arc
		(start 128.8161 -265.50366)
		(mid 128.999608 -265.549154)
		(end 129.18186 -265.498834)
		(width 0.0889)
		(layer "In2.Cu")
		(net "M_I_CPU1_SB_PAR")
	)
	(arc
		(start 133.881876 -265.498834)
		(mid 134.164832 -265.422657)
		(end 134.447788 -265.498834)
		(width 0.0889)
		(layer "In2.Cu")
		(net "M_I_CPU1_SB_PAR")
	)
	(arc
		(start 129.756154 -265.50366)
		(mid 129.939662 -265.549154)
		(end 130.121914 -265.498834)
		(width 0.0889)
		(layer "In2.Cu")
		(net "M_I_CPU1_SB_PAR")
	)
	(arc
		(start 141.027658 -265.498834)
		(mid 141.209909 -265.549184)
		(end 141.393418 -265.50366)
		(width 0.0889)
		(layer "In2.Cu")
		(net "M_I_CPU1_SB_PAR")
	)
	(arc
		(start 130.121914 -265.498834)
		(mid 130.40487 -265.422657)
		(end 130.687826 -265.498834)
		(width 0.0889)
		(layer "In2.Cu")
		(net "M_I_CPU1_SB_PAR")
	)
	(arc
		(start 139.147804 -265.498834)
		(mid 139.334748 -265.549089)
		(end 139.521692 -265.498834)
		(width 0.0889)
		(layer "In2.Cu")
		(net "M_I_CPU1_SB_PAR")
	)
	(arc
		(start 138.581892 -265.498834)
		(mid 138.864848 -265.422657)
		(end 139.147804 -265.498834)
		(width 0.0889)
		(layer "In2.Cu")
		(net "M_I_CPU1_SB_PAR")
	)
	(arc
		(start 135.387588 -265.498834)
		(mid 135.569839 -265.549184)
		(end 135.753348 -265.50366)
		(width 0.0889)
		(layer "In2.Cu")
		(net "M_I_CPU1_SB_PAR")
	)
	(arc
		(start 137.276078 -265.50366)
		(mid 137.459586 -265.549154)
		(end 137.641838 -265.498834)
		(width 0.0889)
		(layer "In2.Cu")
		(net "M_I_CPU1_SB_PAR")
	)
	(arc
		(start 142.907766 -265.498834)
		(mid 143.09471 -265.549089)
		(end 143.281654 -265.498834)
		(width 0.0889)
		(layer "In2.Cu")
		(net "M_I_CPU1_SB_PAR")
	)
	(arc
		(start 129.18186 -265.498834)
		(mid 129.464816 -265.422657)
		(end 129.747772 -265.498834)
		(width 0.0889)
		(layer "In2.Cu")
		(net "M_I_CPU1_SB_PAR")
	)
	(arc
		(start 143.281654 -265.498834)
		(mid 143.56461 -265.422657)
		(end 143.847566 -265.498834)
		(width 0.0889)
		(layer "In2.Cu")
		(net "M_I_CPU1_SB_PAR")
	)
	(arc
		(start 136.701784 -265.498834)
		(mid 136.98474 -265.422657)
		(end 137.267696 -265.498834)
		(width 0.0889)
		(layer "In2.Cu")
		(net "M_I_CPU1_SB_PAR")
	)
	(arc
		(start 132.56768 -265.498834)
		(mid 132.749931 -265.549184)
		(end 132.93344 -265.50366)
		(width 0.0889)
		(layer "In2.Cu")
		(net "M_I_CPU1_SB_PAR")
	)
	(arc
		(start 132.941822 -265.498834)
		(mid 133.224778 -265.422657)
		(end 133.507734 -265.498834)
		(width 0.0889)
		(layer "In2.Cu")
		(net "M_I_CPU1_SB_PAR")
	)
	(arc
		(start 139.521692 -265.498834)
		(mid 139.804648 -265.422657)
		(end 140.087604 -265.498834)
		(width 0.0889)
		(layer "In2.Cu")
		(net "M_I_CPU1_SB_PAR")
	)
	(arc
		(start 142.341854 -265.498834)
		(mid 142.62481 -265.422657)
		(end 142.907766 -265.498834)
		(width 0.0889)
		(layer "In2.Cu")
		(net "M_I_CPU1_SB_PAR")
	)
	(arc
		(start 134.821676 -265.498834)
		(mid 135.104632 -265.422657)
		(end 135.387588 -265.498834)
		(width 0.0889)
		(layer "In2.Cu")
		(net "M_I_CPU1_SB_PAR")
	)
	(arc
		(start 140.461746 -265.498834)
		(mid 140.744702 -265.422657)
		(end 141.027658 -265.498834)
		(width 0.0889)
		(layer "In2.Cu")
		(net "M_I_CPU1_SB_PAR")
	)
	(arc
		(start 131.627626 -265.498834)
		(mid 131.809877 -265.549184)
		(end 131.993386 -265.50366)
		(width 0.0889)
		(layer "In2.Cu")
		(net "M_I_CPU1_SB_PAR")
	)
	(arc
		(start 134.447788 -265.498834)
		(mid 134.634732 -265.549089)
		(end 134.821676 -265.498834)
		(width 0.0889)
		(layer "In2.Cu")
		(net "M_I_CPU1_SB_PAR")
	)
	(arc
		(start 144.804892 -265.510772)
		(mid 144.98382 -265.549649)
		(end 145.15973 -265.498834)
		(width 0.0889)
		(layer "In2.Cu")
		(net "M_I_CPU1_SB_PAR")
	)
	(arc
		(start 144.2466 -265.483594)
		(mid 144.517386 -265.422948)
		(end 144.784318 -265.498834)
		(width 0.0889)
		(layer "In2.Cu")
		(net "M_I_CPU1_SB_PAR")
	)
	(arc
		(start 141.976094 -265.50366)
		(mid 142.159602 -265.549154)
		(end 142.341854 -265.498834)
		(width 0.0889)
		(layer "In2.Cu")
		(net "M_I_CPU1_SB_PAR")
	)
	(arc
		(start 133.516116 -265.50366)
		(mid 133.699624 -265.549154)
		(end 133.881876 -265.498834)
		(width 0.0889)
		(layer "In2.Cu")
		(net "M_I_CPU1_SB_PAR")
	)
	(arc
		(start 138.216132 -265.50366)
		(mid 138.39964 -265.549154)
		(end 138.581892 -265.498834)
		(width 0.0889)
		(layer "In2.Cu")
		(net "M_I_CPU1_SB_PAR")
	)
	(arc
		(start 141.4018 -265.498834)
		(mid 141.684756 -265.422657)
		(end 141.967712 -265.498834)
		(width 0.0889)
		(layer "In2.Cu")
		(net "M_I_CPU1_SB_PAR")
	)
	(arc
		(start 131.061714 -265.498834)
		(mid 131.34467 -265.422657)
		(end 131.627626 -265.498834)
		(width 0.0889)
		(layer "In2.Cu")
		(net "M_I_CPU1_SB_PAR")
	)
	(arc
		(start 143.847566 -265.498834)
		(mid 144.020674 -265.54895)
		(end 144.19707 -265.512042)
		(width 0.0889)
		(layer "In2.Cu")
		(net "M_I_CPU1_SB_PAR")
	)
	(arc
		(start 128.304798 -265.467084)
		(mid 128.560006 -265.423607)
		(end 128.807718 -265.498834)
		(width 0.0889)
		(layer "In2.Cu")
		(net "M_I_CPU1_SB_PAR")
	)
	(arc
		(start 135.76173 -265.498834)
		(mid 136.044686 -265.422657)
		(end 136.327642 -265.498834)
		(width 0.0889)
		(layer "In2.Cu")
		(net "M_I_CPU1_SB_PAR")
	)
	(arc
		(start 137.641838 -265.498834)
		(mid 137.924794 -265.422657)
		(end 138.20775 -265.498834)
		(width 0.0889)
		(layer "In2.Cu")
		(net "M_I_CPU1_SB_PAR")
	)
	(arc
		(start 130.687826 -265.498834)
		(mid 130.87477 -265.549089)
		(end 131.061714 -265.498834)
		(width 0.0889)
		(layer "In2.Cu")
		(net "M_I_CPU1_SB_PAR")
	)
	(arc
		(start 132.001768 -265.498834)
		(mid 132.284724 -265.422657)
		(end 132.56768 -265.498834)
		(width 0.0889)
		(layer "In2.Cu")
		(net "M_I_CPU1_SB_PAR")
	)
	(arc
		(start 136.327642 -265.498834)
		(mid 136.509893 -265.549184)
		(end 136.693402 -265.50366)
		(width 0.0889)
		(layer "In2.Cu")
		(net "M_I_CPU1_SB_PAR")
	)
	(arc
		(start 140.087604 -265.498834)
		(mid 140.269855 -265.549184)
		(end 140.453364 -265.50366)
		(width 0.0889)
		(layer "In2.Cu")
		(net "M_I_CPU1_SB_PAR")
	)
	(segment
		(start 128.997964 -270.580358)
		(end 129.464816 -270.846296)
		(width 0.12954)
		(layer "F.Cu")
		(net "M_I_CPU1_SB_DQS_DP<9>")
	)
	(segment
		(start 167.664638 -274.81022)
		(end 169.893742 -274.81022)
		(width 0.16002)
		(layer "In2.Cu")
		(net "M_I_CPU1_SB_DQS_DP<9>")
	)
	(segment
		(start 147.341082 -269.193264)
		(end 147.459954 -269.312136)
		(width 0.09525)
		(layer "In2.Cu")
		(net "M_I_CPU1_SB_DQS_DP<9>")
	)
	(segment
		(start 134.916164 -271.171416)
		(end 134.924546 -271.176242)
		(width 0.09525)
		(layer "In2.Cu")
		(net "M_I_CPU1_SB_DQS_DP<9>")
	)
	(segment
		(start 144.685004 -271.176242)
		(end 144.693386 -271.171416)
		(width 0.09525)
		(layer "In2.Cu")
		(net "M_I_CPU1_SB_DQS_DP<9>")
	)
	(segment
		(start 180.753512 -275.992844)
		(end 181.151276 -275.992844)
		(width 0.16002)
		(layer "In2.Cu")
		(net "M_I_CPU1_SB_DQS_DP<9>")
	)
	(segment
		(start 147.459954 -269.312136)
		(end 147.62099 -269.312136)
		(width 0.09525)
		(layer "In2.Cu")
		(net "M_I_CPU1_SB_DQS_DP<9>")
	)
	(segment
		(start 147.680172 -269.252954)
		(end 147.703794 -269.252954)
		(width 0.09525)
		(layer "In2.Cu")
		(net "M_I_CPU1_SB_DQS_DP<9>")
	)
	(segment
		(start 145.25625 -271.171416)
		(end 145.264632 -271.176242)
		(width 0.09525)
		(layer "In2.Cu")
		(net "M_I_CPU1_SB_DQS_DP<9>")
	)
	(segment
		(start 180.144928 -275.38426)
		(end 180.753512 -275.992844)
		(width 0.16002)
		(layer "In2.Cu")
		(net "M_I_CPU1_SB_DQS_DP<9>")
	)
	(segment
		(start 134.344918 -271.176242)
		(end 134.3533 -271.171416)
		(width 0.09525)
		(layer "In2.Cu")
		(net "M_I_CPU1_SB_DQS_DP<9>")
	)
	(segment
		(start 146.697446 -269.302484)
		(end 146.806666 -269.193264)
		(width 0.09525)
		(layer "In2.Cu")
		(net "M_I_CPU1_SB_DQS_DP<9>")
	)
	(segment
		(start 165.982142 -275.967444)
		(end 166.822882 -275.126704)
		(width 0.16002)
		(layer "In2.Cu")
		(net "M_I_CPU1_SB_DQS_DP<9>")
	)
	(segment
		(start 174.366936 -275.126704)
		(end 174.892208 -275.126704)
		(width 0.16002)
		(layer "In2.Cu")
		(net "M_I_CPU1_SB_DQS_DP<9>")
	)
	(segment
		(start 173.184312 -275.967444)
		(end 173.526196 -275.967444)
		(width 0.16002)
		(layer "In2.Cu")
		(net "M_I_CPU1_SB_DQS_DP<9>")
	)
	(segment
		(start 138.10488 -271.176242)
		(end 138.113262 -271.171416)
		(width 0.09525)
		(layer "In2.Cu")
		(net "M_I_CPU1_SB_DQS_DP<9>")
	)
	(segment
		(start 145.81251 -270.885666)
		(end 145.81251 -270.36014)
		(width 0.09525)
		(layer "In2.Cu")
		(net "M_I_CPU1_SB_DQS_DP<9>")
	)
	(segment
		(start 175.208692 -274.81022)
		(end 177.420524 -274.81022)
		(width 0.16002)
		(layer "In2.Cu")
		(net "M_I_CPU1_SB_DQS_DP<9>")
	)
	(segment
		(start 131.156202 -271.171416)
		(end 131.164584 -271.176242)
		(width 0.09525)
		(layer "In2.Cu")
		(net "M_I_CPU1_SB_DQS_DP<9>")
	)
	(segment
		(start 147.703794 -269.252954)
		(end 156.630116 -269.252954)
		(width 0.16002)
		(layer "In2.Cu")
		(net "M_I_CPU1_SB_DQS_DP<9>")
	)
	(segment
		(start 147.62099 -269.312136)
		(end 147.680172 -269.252954)
		(width 0.09525)
		(layer "In2.Cu")
		(net "M_I_CPU1_SB_DQS_DP<9>")
	)
	(segment
		(start 146.078702 -269.717266)
		(end 146.493484 -269.302484)
		(width 0.09525)
		(layer "In2.Cu")
		(net "M_I_CPU1_SB_DQS_DP<9>")
	)
	(segment
		(start 166.822882 -275.126704)
		(end 167.348154 -275.126704)
		(width 0.16002)
		(layer "In2.Cu")
		(net "M_I_CPU1_SB_DQS_DP<9>")
	)
	(segment
		(start 130.584956 -271.176242)
		(end 130.593338 -271.171416)
		(width 0.09525)
		(layer "In2.Cu")
		(net "M_I_CPU1_SB_DQS_DP<9>")
	)
	(segment
		(start 173.526196 -275.967444)
		(end 174.366936 -275.126704)
		(width 0.16002)
		(layer "In2.Cu")
		(net "M_I_CPU1_SB_DQS_DP<9>")
	)
	(segment
		(start 165.640258 -275.967444)
		(end 165.982142 -275.967444)
		(width 0.16002)
		(layer "In2.Cu")
		(net "M_I_CPU1_SB_DQS_DP<9>")
	)
	(segment
		(start 162.451796 -275.074634)
		(end 163.199064 -275.38426)
		(width 0.16002)
		(layer "In2.Cu")
		(net "M_I_CPU1_SB_DQS_DP<9>")
	)
	(segment
		(start 177.420524 -274.81022)
		(end 178.806602 -275.38426)
		(width 0.16002)
		(layer "In2.Cu")
		(net "M_I_CPU1_SB_DQS_DP<9>")
	)
	(segment
		(start 183.341518 -275.809964)
		(end 183.616092 -275.53539)
		(width 0.16002)
		(layer "In2.Cu")
		(net "M_I_CPU1_SB_DQS_DP<9>")
	)
	(segment
		(start 129.464816 -270.846296)
		(end 129.61874 -271.111726)
		(width 0.09525)
		(layer "In2.Cu")
		(net "M_I_CPU1_SB_DQS_DP<9>")
	)
	(segment
		(start 167.348154 -275.126704)
		(end 167.664638 -274.81022)
		(width 0.16002)
		(layer "In2.Cu")
		(net "M_I_CPU1_SB_DQS_DP<9>")
	)
	(segment
		(start 172.601128 -275.38426)
		(end 173.184312 -275.967444)
		(width 0.16002)
		(layer "In2.Cu")
		(net "M_I_CPU1_SB_DQS_DP<9>")
	)
	(segment
		(start 140.556234 -271.171416)
		(end 140.564616 -271.176242)
		(width 0.09525)
		(layer "In2.Cu")
		(net "M_I_CPU1_SB_DQS_DP<9>")
	)
	(segment
		(start 163.199064 -275.38426)
		(end 165.057074 -275.38426)
		(width 0.16002)
		(layer "In2.Cu")
		(net "M_I_CPU1_SB_DQS_DP<9>")
	)
	(segment
		(start 132.096256 -271.171416)
		(end 132.104638 -271.176242)
		(width 0.09525)
		(layer "In2.Cu")
		(net "M_I_CPU1_SB_DQS_DP<9>")
	)
	(segment
		(start 181.334156 -275.809964)
		(end 183.341518 -275.809964)
		(width 0.16002)
		(layer "In2.Cu")
		(net "M_I_CPU1_SB_DQS_DP<9>")
	)
	(segment
		(start 170.467782 -275.38426)
		(end 172.601128 -275.38426)
		(width 0.16002)
		(layer "In2.Cu")
		(net "M_I_CPU1_SB_DQS_DP<9>")
	)
	(segment
		(start 129.61874 -271.111726)
		(end 129.719578 -271.138396)
		(width 0.09525)
		(layer "In2.Cu")
		(net "M_I_CPU1_SB_DQS_DP<9>")
	)
	(segment
		(start 135.856218 -271.171416)
		(end 135.8646 -271.176242)
		(width 0.09525)
		(layer "In2.Cu")
		(net "M_I_CPU1_SB_DQS_DP<9>")
	)
	(segment
		(start 146.493484 -269.302484)
		(end 146.697446 -269.302484)
		(width 0.09525)
		(layer "In2.Cu")
		(net "M_I_CPU1_SB_DQS_DP<9>")
	)
	(segment
		(start 156.630116 -269.252954)
		(end 162.451796 -275.074634)
		(width 0.16002)
		(layer "In2.Cu")
		(net "M_I_CPU1_SB_DQS_DP<9>")
	)
	(segment
		(start 142.804896 -271.176242)
		(end 142.813278 -271.171416)
		(width 0.09525)
		(layer "In2.Cu")
		(net "M_I_CPU1_SB_DQS_DP<9>")
	)
	(segment
		(start 139.61618 -271.171416)
		(end 139.624562 -271.176242)
		(width 0.09525)
		(layer "In2.Cu")
		(net "M_I_CPU1_SB_DQS_DP<9>")
	)
	(segment
		(start 178.806602 -275.38426)
		(end 180.144928 -275.38426)
		(width 0.16002)
		(layer "In2.Cu")
		(net "M_I_CPU1_SB_DQS_DP<9>")
	)
	(segment
		(start 139.044934 -271.176242)
		(end 139.053316 -271.171416)
		(width 0.09525)
		(layer "In2.Cu")
		(net "M_I_CPU1_SB_DQS_DP<9>")
	)
	(segment
		(start 174.892208 -275.126704)
		(end 175.208692 -274.81022)
		(width 0.16002)
		(layer "In2.Cu")
		(net "M_I_CPU1_SB_DQS_DP<9>")
	)
	(segment
		(start 145.81251 -270.36014)
		(end 146.078702 -269.717266)
		(width 0.09525)
		(layer "In2.Cu")
		(net "M_I_CPU1_SB_DQS_DP<9>")
	)
	(segment
		(start 146.806666 -269.193264)
		(end 147.341082 -269.193264)
		(width 0.09525)
		(layer "In2.Cu")
		(net "M_I_CPU1_SB_DQS_DP<9>")
	)
	(segment
		(start 143.376142 -271.171416)
		(end 143.384524 -271.176242)
		(width 0.09525)
		(layer "In2.Cu")
		(net "M_I_CPU1_SB_DQS_DP<9>")
	)
	(segment
		(start 165.057074 -275.38426)
		(end 165.640258 -275.967444)
		(width 0.16002)
		(layer "In2.Cu")
		(net "M_I_CPU1_SB_DQS_DP<9>")
	)
	(segment
		(start 169.893742 -274.81022)
		(end 170.467782 -275.38426)
		(width 0.16002)
		(layer "In2.Cu")
		(net "M_I_CPU1_SB_DQS_DP<9>")
	)
	(segment
		(start 181.151276 -275.992844)
		(end 181.334156 -275.809964)
		(width 0.16002)
		(layer "In2.Cu")
		(net "M_I_CPU1_SB_DQS_DP<9>")
	)
	(arc
		(start 129.719578 -271.138396)
		(mid 129.971719 -271.096826)
		(end 130.216148 -271.171416)
		(width 0.09525)
		(layer "In2.Cu")
		(net "M_I_CPU1_SB_DQS_DP<9>")
	)
	(arc
		(start 144.316196 -271.171416)
		(mid 144.499971 -271.222188)
		(end 144.685004 -271.176242)
		(width 0.09525)
		(layer "In2.Cu")
		(net "M_I_CPU1_SB_DQS_DP<9>")
	)
	(arc
		(start 144.693386 -271.171416)
		(mid 144.974818 -271.095661)
		(end 145.25625 -271.171416)
		(width 0.09525)
		(layer "In2.Cu")
		(net "M_I_CPU1_SB_DQS_DP<9>")
	)
	(arc
		(start 136.796272 -271.171416)
		(mid 136.98474 -271.222093)
		(end 137.173208 -271.171416)
		(width 0.09525)
		(layer "In2.Cu")
		(net "M_I_CPU1_SB_DQS_DP<9>")
	)
	(arc
		(start 145.63344 -271.171416)
		(mid 145.758358 -271.050709)
		(end 145.81251 -270.885666)
		(width 0.09525)
		(layer "In2.Cu")
		(net "M_I_CPU1_SB_DQS_DP<9>")
	)
	(arc
		(start 138.113262 -271.171416)
		(mid 138.394694 -271.095661)
		(end 138.676126 -271.171416)
		(width 0.09525)
		(layer "In2.Cu")
		(net "M_I_CPU1_SB_DQS_DP<9>")
	)
	(arc
		(start 139.624562 -271.176242)
		(mid 139.809594 -271.222156)
		(end 139.99337 -271.171416)
		(width 0.09525)
		(layer "In2.Cu")
		(net "M_I_CPU1_SB_DQS_DP<9>")
	)
	(arc
		(start 132.473446 -271.171416)
		(mid 132.754878 -271.095661)
		(end 133.03631 -271.171416)
		(width 0.09525)
		(layer "In2.Cu")
		(net "M_I_CPU1_SB_DQS_DP<9>")
	)
	(arc
		(start 130.593338 -271.171416)
		(mid 130.87477 -271.095661)
		(end 131.156202 -271.171416)
		(width 0.09525)
		(layer "In2.Cu")
		(net "M_I_CPU1_SB_DQS_DP<9>")
	)
	(arc
		(start 137.736072 -271.171416)
		(mid 137.919847 -271.222188)
		(end 138.10488 -271.176242)
		(width 0.09525)
		(layer "In2.Cu")
		(net "M_I_CPU1_SB_DQS_DP<9>")
	)
	(arc
		(start 143.384524 -271.176242)
		(mid 143.569556 -271.222156)
		(end 143.753332 -271.171416)
		(width 0.09525)
		(layer "In2.Cu")
		(net "M_I_CPU1_SB_DQS_DP<9>")
	)
	(arc
		(start 134.924546 -271.176242)
		(mid 135.109578 -271.222156)
		(end 135.293354 -271.171416)
		(width 0.09525)
		(layer "In2.Cu")
		(net "M_I_CPU1_SB_DQS_DP<9>")
	)
	(arc
		(start 138.676126 -271.171416)
		(mid 138.859901 -271.222188)
		(end 139.044934 -271.176242)
		(width 0.09525)
		(layer "In2.Cu")
		(net "M_I_CPU1_SB_DQS_DP<9>")
	)
	(arc
		(start 132.104638 -271.176242)
		(mid 132.28967 -271.222156)
		(end 132.473446 -271.171416)
		(width 0.09525)
		(layer "In2.Cu")
		(net "M_I_CPU1_SB_DQS_DP<9>")
	)
	(arc
		(start 137.173208 -271.171416)
		(mid 137.45464 -271.095661)
		(end 137.736072 -271.171416)
		(width 0.09525)
		(layer "In2.Cu")
		(net "M_I_CPU1_SB_DQS_DP<9>")
	)
	(arc
		(start 136.233408 -271.171416)
		(mid 136.51484 -271.095661)
		(end 136.796272 -271.171416)
		(width 0.09525)
		(layer "In2.Cu")
		(net "M_I_CPU1_SB_DQS_DP<9>")
	)
	(arc
		(start 142.813278 -271.171416)
		(mid 143.09471 -271.095661)
		(end 143.376142 -271.171416)
		(width 0.09525)
		(layer "In2.Cu")
		(net "M_I_CPU1_SB_DQS_DP<9>")
	)
	(arc
		(start 135.293354 -271.171416)
		(mid 135.574786 -271.095661)
		(end 135.856218 -271.171416)
		(width 0.09525)
		(layer "In2.Cu")
		(net "M_I_CPU1_SB_DQS_DP<9>")
	)
	(arc
		(start 131.164584 -271.176242)
		(mid 131.349616 -271.222156)
		(end 131.533392 -271.171416)
		(width 0.09525)
		(layer "In2.Cu")
		(net "M_I_CPU1_SB_DQS_DP<9>")
	)
	(arc
		(start 139.053316 -271.171416)
		(mid 139.334748 -271.095661)
		(end 139.61618 -271.171416)
		(width 0.09525)
		(layer "In2.Cu")
		(net "M_I_CPU1_SB_DQS_DP<9>")
	)
	(arc
		(start 141.496288 -271.171416)
		(mid 141.684756 -271.222093)
		(end 141.873224 -271.171416)
		(width 0.09525)
		(layer "In2.Cu")
		(net "M_I_CPU1_SB_DQS_DP<9>")
	)
	(arc
		(start 145.264632 -271.176242)
		(mid 145.449664 -271.222156)
		(end 145.63344 -271.171416)
		(width 0.09525)
		(layer "In2.Cu")
		(net "M_I_CPU1_SB_DQS_DP<9>")
	)
	(arc
		(start 143.753332 -271.171416)
		(mid 144.034764 -271.095661)
		(end 144.316196 -271.171416)
		(width 0.09525)
		(layer "In2.Cu")
		(net "M_I_CPU1_SB_DQS_DP<9>")
	)
	(arc
		(start 141.873224 -271.171416)
		(mid 142.154656 -271.095661)
		(end 142.436088 -271.171416)
		(width 0.09525)
		(layer "In2.Cu")
		(net "M_I_CPU1_SB_DQS_DP<9>")
	)
	(arc
		(start 133.413246 -271.171416)
		(mid 133.694678 -271.095661)
		(end 133.97611 -271.171416)
		(width 0.09525)
		(layer "In2.Cu")
		(net "M_I_CPU1_SB_DQS_DP<9>")
	)
	(arc
		(start 140.564616 -271.176242)
		(mid 140.749648 -271.222156)
		(end 140.933424 -271.171416)
		(width 0.09525)
		(layer "In2.Cu")
		(net "M_I_CPU1_SB_DQS_DP<9>")
	)
	(arc
		(start 130.216148 -271.171416)
		(mid 130.399923 -271.222188)
		(end 130.584956 -271.176242)
		(width 0.09525)
		(layer "In2.Cu")
		(net "M_I_CPU1_SB_DQS_DP<9>")
	)
	(arc
		(start 131.533392 -271.171416)
		(mid 131.814824 -271.095661)
		(end 132.096256 -271.171416)
		(width 0.09525)
		(layer "In2.Cu")
		(net "M_I_CPU1_SB_DQS_DP<9>")
	)
	(arc
		(start 133.97611 -271.171416)
		(mid 134.159885 -271.222188)
		(end 134.344918 -271.176242)
		(width 0.09525)
		(layer "In2.Cu")
		(net "M_I_CPU1_SB_DQS_DP<9>")
	)
	(arc
		(start 134.3533 -271.171416)
		(mid 134.634732 -271.095661)
		(end 134.916164 -271.171416)
		(width 0.09525)
		(layer "In2.Cu")
		(net "M_I_CPU1_SB_DQS_DP<9>")
	)
	(arc
		(start 140.933424 -271.171416)
		(mid 141.214856 -271.095661)
		(end 141.496288 -271.171416)
		(width 0.09525)
		(layer "In2.Cu")
		(net "M_I_CPU1_SB_DQS_DP<9>")
	)
	(arc
		(start 139.99337 -271.171416)
		(mid 140.274802 -271.095661)
		(end 140.556234 -271.171416)
		(width 0.09525)
		(layer "In2.Cu")
		(net "M_I_CPU1_SB_DQS_DP<9>")
	)
	(arc
		(start 142.436088 -271.171416)
		(mid 142.619863 -271.222188)
		(end 142.804896 -271.176242)
		(width 0.09525)
		(layer "In2.Cu")
		(net "M_I_CPU1_SB_DQS_DP<9>")
	)
	(arc
		(start 135.8646 -271.176242)
		(mid 136.049632 -271.222156)
		(end 136.233408 -271.171416)
		(width 0.09525)
		(layer "In2.Cu")
		(net "M_I_CPU1_SB_DQS_DP<9>")
	)
	(arc
		(start 133.03631 -271.171416)
		(mid 133.224778 -271.222093)
		(end 133.413246 -271.171416)
		(width 0.09525)
		(layer "In2.Cu")
		(net "M_I_CPU1_SB_DQS_DP<9>")
	)
	(segment
		(start 128.05791 -291.64026)
		(end 128.524762 -291.906198)
		(width 0.12954)
		(layer "F.Cu")
		(net "M_I_CPU1_SB_DQS_DP<8>")
	)
	(segment
		(start 144.692878 -294.821102)
		(end 144.727676 -294.841168)
		(width 0.09525)
		(layer "In2.Cu")
		(net "M_I_CPU1_SB_DQS_DP<8>")
	)
	(segment
		(start 165.683438 -314.99556)
		(end 166.120318 -314.99556)
		(width 0.16002)
		(layer "In2.Cu")
		(net "M_I_CPU1_SB_DQS_DP<8>")
	)
	(segment
		(start 151.894032 -304.46091)
		(end 151.894032 -305.146202)
		(width 0.16002)
		(layer "In2.Cu")
		(net "M_I_CPU1_SB_DQS_DP<8>")
	)
	(segment
		(start 172.862494 -315.360558)
		(end 173.227492 -314.99556)
		(width 0.16002)
		(layer "In2.Cu")
		(net "M_I_CPU1_SB_DQS_DP<8>")
	)
	(segment
		(start 170.372532 -314.786264)
		(end 170.946826 -315.360558)
		(width 0.16002)
		(layer "In2.Cu")
		(net "M_I_CPU1_SB_DQS_DP<8>")
	)
	(segment
		(start 147.773136 -300.340014)
		(end 147.773136 -301.025306)
		(width 0.16002)
		(layer "In2.Cu")
		(net "M_I_CPU1_SB_DQS_DP<8>")
	)
	(segment
		(start 143.283178 -292.391084)
		(end 143.31569 -292.40988)
		(width 0.09525)
		(layer "In2.Cu")
		(net "M_I_CPU1_SB_DQS_DP<8>")
	)
	(segment
		(start 145.459196 -296.383202)
		(end 145.459196 -296.406824)
		(width 0.09525)
		(layer "In2.Cu")
		(net "M_I_CPU1_SB_DQS_DP<8>")
	)
	(segment
		(start 130.584956 -291.576252)
		(end 130.593338 -291.581078)
		(width 0.09525)
		(layer "In2.Cu")
		(net "M_I_CPU1_SB_DQS_DP<8>")
	)
	(segment
		(start 147.517104 -300.083982)
		(end 147.773136 -300.340014)
		(width 0.16002)
		(layer "In2.Cu")
		(net "M_I_CPU1_SB_DQS_DP<8>")
	)
	(segment
		(start 162.108134 -315.360304)
		(end 165.318694 -315.360304)
		(width 0.16002)
		(layer "In2.Cu")
		(net "M_I_CPU1_SB_DQS_DP<8>")
	)
	(segment
		(start 166.120318 -314.99556)
		(end 166.912798 -314.20308)
		(width 0.16002)
		(layer "In2.Cu")
		(net "M_I_CPU1_SB_DQS_DP<8>")
	)
	(segment
		(start 143.248126 -292.37051)
		(end 143.283178 -292.391084)
		(width 0.09525)
		(layer "In2.Cu")
		(net "M_I_CPU1_SB_DQS_DP<8>")
	)
	(segment
		(start 150.5204 -303.087278)
		(end 150.5204 -303.77257)
		(width 0.16002)
		(layer "In2.Cu")
		(net "M_I_CPU1_SB_DQS_DP<8>")
	)
	(segment
		(start 167.908986 -314.786264)
		(end 170.372532 -314.786264)
		(width 0.16002)
		(layer "In2.Cu")
		(net "M_I_CPU1_SB_DQS_DP<8>")
	)
	(segment
		(start 176.975008 -314.786264)
		(end 177.399188 -314.362084)
		(width 0.16002)
		(layer "In2.Cu")
		(net "M_I_CPU1_SB_DQS_DP<8>")
	)
	(segment
		(start 153.011632 -305.57851)
		(end 153.267664 -305.834542)
		(width 0.16002)
		(layer "In2.Cu")
		(net "M_I_CPU1_SB_DQS_DP<8>")
	)
	(segment
		(start 150.264368 -302.831246)
		(end 150.5204 -303.087278)
		(width 0.16002)
		(layer "In2.Cu")
		(net "M_I_CPU1_SB_DQS_DP<8>")
	)
	(segment
		(start 153.267664 -306.519834)
		(end 162.108134 -315.360304)
		(width 0.16002)
		(layer "In2.Cu")
		(net "M_I_CPU1_SB_DQS_DP<8>")
	)
	(segment
		(start 150.952708 -304.204878)
		(end 151.638 -304.204878)
		(width 0.16002)
		(layer "In2.Cu")
		(net "M_I_CPU1_SB_DQS_DP<8>")
	)
	(segment
		(start 143.753332 -293.20109)
		(end 143.784828 -293.219378)
		(width 0.09525)
		(layer "In2.Cu")
		(net "M_I_CPU1_SB_DQS_DP<8>")
	)
	(segment
		(start 135.856218 -291.581078)
		(end 135.8646 -291.576252)
		(width 0.09525)
		(layer "In2.Cu")
		(net "M_I_CPU1_SB_DQS_DP<8>")
	)
	(segment
		(start 138.10488 -291.576252)
		(end 138.113262 -291.581078)
		(width 0.09525)
		(layer "In2.Cu")
		(net "M_I_CPU1_SB_DQS_DP<8>")
	)
	(segment
		(start 149.146768 -301.713646)
		(end 149.146768 -302.398938)
		(width 0.16002)
		(layer "In2.Cu")
		(net "M_I_CPU1_SB_DQS_DP<8>")
	)
	(segment
		(start 139.61618 -291.581078)
		(end 139.624562 -291.576252)
		(width 0.09525)
		(layer "In2.Cu")
		(net "M_I_CPU1_SB_DQS_DP<8>")
	)
	(segment
		(start 128.370838 -291.640768)
		(end 128.393952 -291.554154)
		(width 0.09525)
		(layer "In2.Cu")
		(net "M_I_CPU1_SB_DQS_DP<8>")
	)
	(segment
		(start 142.804896 -291.576252)
		(end 142.813278 -291.581078)
		(width 0.09525)
		(layer "In2.Cu")
		(net "M_I_CPU1_SB_DQS_DP<8>")
	)
	(segment
		(start 145.163286 -295.631108)
		(end 145.518124 -295.985946)
		(width 0.09525)
		(layer "In2.Cu")
		(net "M_I_CPU1_SB_DQS_DP<8>")
	)
	(segment
		(start 145.459196 -296.406824)
		(end 145.459196 -297.190414)
		(width 0.16002)
		(layer "In2.Cu")
		(net "M_I_CPU1_SB_DQS_DP<8>")
	)
	(segment
		(start 146.534632 -299.786802)
		(end 146.831812 -300.083982)
		(width 0.16002)
		(layer "In2.Cu")
		(net "M_I_CPU1_SB_DQS_DP<8>")
	)
	(segment
		(start 148.205444 -301.457614)
		(end 148.890736 -301.457614)
		(width 0.16002)
		(layer "In2.Cu")
		(net "M_I_CPU1_SB_DQS_DP<8>")
	)
	(segment
		(start 177.399188 -314.362084)
		(end 179.24272 -314.362084)
		(width 0.16002)
		(layer "In2.Cu")
		(net "M_I_CPU1_SB_DQS_DP<8>")
	)
	(segment
		(start 166.912798 -314.20308)
		(end 167.325802 -314.20308)
		(width 0.16002)
		(layer "In2.Cu")
		(net "M_I_CPU1_SB_DQS_DP<8>")
	)
	(segment
		(start 167.325802 -314.20308)
		(end 167.908986 -314.786264)
		(width 0.16002)
		(layer "In2.Cu")
		(net "M_I_CPU1_SB_DQS_DP<8>")
	)
	(segment
		(start 131.156202 -291.581078)
		(end 131.164584 -291.576252)
		(width 0.09525)
		(layer "In2.Cu")
		(net "M_I_CPU1_SB_DQS_DP<8>")
	)
	(segment
		(start 143.715232 -293.178992)
		(end 143.753332 -293.20109)
		(width 0.09525)
		(layer "In2.Cu")
		(net "M_I_CPU1_SB_DQS_DP<8>")
	)
	(segment
		(start 150.5204 -303.77257)
		(end 150.952708 -304.204878)
		(width 0.16002)
		(layer "In2.Cu")
		(net "M_I_CPU1_SB_DQS_DP<8>")
	)
	(segment
		(start 175.45304 -314.786264)
		(end 176.975008 -314.786264)
		(width 0.16002)
		(layer "In2.Cu")
		(net "M_I_CPU1_SB_DQS_DP<8>")
	)
	(segment
		(start 174.869856 -314.20308)
		(end 175.45304 -314.786264)
		(width 0.16002)
		(layer "In2.Cu")
		(net "M_I_CPU1_SB_DQS_DP<8>")
	)
	(segment
		(start 140.556234 -291.581078)
		(end 140.564616 -291.576252)
		(width 0.09525)
		(layer "In2.Cu")
		(net "M_I_CPU1_SB_DQS_DP<8>")
	)
	(segment
		(start 173.664372 -314.99556)
		(end 174.456852 -314.20308)
		(width 0.16002)
		(layer "In2.Cu")
		(net "M_I_CPU1_SB_DQS_DP<8>")
	)
	(segment
		(start 151.894032 -305.146202)
		(end 152.32634 -305.57851)
		(width 0.16002)
		(layer "In2.Cu")
		(net "M_I_CPU1_SB_DQS_DP<8>")
	)
	(segment
		(start 134.916164 -291.581078)
		(end 134.924546 -291.576252)
		(width 0.09525)
		(layer "In2.Cu")
		(net "M_I_CPU1_SB_DQS_DP<8>")
	)
	(segment
		(start 145.125186 -295.60901)
		(end 145.163286 -295.631108)
		(width 0.09525)
		(layer "In2.Cu")
		(net "M_I_CPU1_SB_DQS_DP<8>")
	)
	(segment
		(start 145.459196 -297.190414)
		(end 146.534632 -299.786802)
		(width 0.16002)
		(layer "In2.Cu")
		(net "M_I_CPU1_SB_DQS_DP<8>")
	)
	(segment
		(start 146.831812 -300.083982)
		(end 147.517104 -300.083982)
		(width 0.16002)
		(layer "In2.Cu")
		(net "M_I_CPU1_SB_DQS_DP<8>")
	)
	(segment
		(start 149.146768 -302.398938)
		(end 149.579076 -302.831246)
		(width 0.16002)
		(layer "In2.Cu")
		(net "M_I_CPU1_SB_DQS_DP<8>")
	)
	(segment
		(start 179.24272 -314.362084)
		(end 179.516024 -314.635388)
		(width 0.16002)
		(layer "In2.Cu")
		(net "M_I_CPU1_SB_DQS_DP<8>")
	)
	(segment
		(start 149.579076 -302.831246)
		(end 150.264368 -302.831246)
		(width 0.16002)
		(layer "In2.Cu")
		(net "M_I_CPU1_SB_DQS_DP<8>")
	)
	(segment
		(start 148.890736 -301.457614)
		(end 149.146768 -301.713646)
		(width 0.16002)
		(layer "In2.Cu")
		(net "M_I_CPU1_SB_DQS_DP<8>")
	)
	(segment
		(start 145.518124 -296.324274)
		(end 145.459196 -296.383202)
		(width 0.09525)
		(layer "In2.Cu")
		(net "M_I_CPU1_SB_DQS_DP<8>")
	)
	(segment
		(start 129.644902 -291.576252)
		(end 129.653284 -291.581078)
		(width 0.09525)
		(layer "In2.Cu")
		(net "M_I_CPU1_SB_DQS_DP<8>")
	)
	(segment
		(start 173.227492 -314.99556)
		(end 173.664372 -314.99556)
		(width 0.16002)
		(layer "In2.Cu")
		(net "M_I_CPU1_SB_DQS_DP<8>")
	)
	(segment
		(start 144.657826 -294.800528)
		(end 144.692878 -294.821102)
		(width 0.09525)
		(layer "In2.Cu")
		(net "M_I_CPU1_SB_DQS_DP<8>")
	)
	(segment
		(start 170.946826 -315.360558)
		(end 172.862494 -315.360558)
		(width 0.16002)
		(layer "In2.Cu")
		(net "M_I_CPU1_SB_DQS_DP<8>")
	)
	(segment
		(start 142.813278 -291.581078)
		(end 142.84579 -291.599874)
		(width 0.09525)
		(layer "In2.Cu")
		(net "M_I_CPU1_SB_DQS_DP<8>")
	)
	(segment
		(start 144.223232 -294.011096)
		(end 144.254728 -294.029384)
		(width 0.09525)
		(layer "In2.Cu")
		(net "M_I_CPU1_SB_DQS_DP<8>")
	)
	(segment
		(start 145.518124 -295.985946)
		(end 145.518124 -296.324274)
		(width 0.09525)
		(layer "In2.Cu")
		(net "M_I_CPU1_SB_DQS_DP<8>")
	)
	(segment
		(start 144.185132 -293.988998)
		(end 144.223232 -294.011096)
		(width 0.09525)
		(layer "In2.Cu")
		(net "M_I_CPU1_SB_DQS_DP<8>")
	)
	(segment
		(start 153.267664 -305.834542)
		(end 153.267664 -306.519834)
		(width 0.16002)
		(layer "In2.Cu")
		(net "M_I_CPU1_SB_DQS_DP<8>")
	)
	(segment
		(start 174.456852 -314.20308)
		(end 174.869856 -314.20308)
		(width 0.16002)
		(layer "In2.Cu")
		(net "M_I_CPU1_SB_DQS_DP<8>")
	)
	(segment
		(start 147.773136 -301.025306)
		(end 148.205444 -301.457614)
		(width 0.16002)
		(layer "In2.Cu")
		(net "M_I_CPU1_SB_DQS_DP<8>")
	)
	(segment
		(start 128.524762 -291.906198)
		(end 128.370838 -291.640768)
		(width 0.09525)
		(layer "In2.Cu")
		(net "M_I_CPU1_SB_DQS_DP<8>")
	)
	(segment
		(start 134.344918 -291.576252)
		(end 134.3533 -291.581078)
		(width 0.09525)
		(layer "In2.Cu")
		(net "M_I_CPU1_SB_DQS_DP<8>")
	)
	(segment
		(start 152.32634 -305.57851)
		(end 153.011632 -305.57851)
		(width 0.16002)
		(layer "In2.Cu")
		(net "M_I_CPU1_SB_DQS_DP<8>")
	)
	(segment
		(start 139.044934 -291.576252)
		(end 139.053316 -291.581078)
		(width 0.09525)
		(layer "In2.Cu")
		(net "M_I_CPU1_SB_DQS_DP<8>")
	)
	(segment
		(start 151.638 -304.204878)
		(end 151.894032 -304.46091)
		(width 0.16002)
		(layer "In2.Cu")
		(net "M_I_CPU1_SB_DQS_DP<8>")
	)
	(segment
		(start 165.318694 -315.360304)
		(end 165.683438 -314.99556)
		(width 0.16002)
		(layer "In2.Cu")
		(net "M_I_CPU1_SB_DQS_DP<8>")
	)
	(segment
		(start 132.096256 -291.581078)
		(end 132.104638 -291.576252)
		(width 0.09525)
		(layer "In2.Cu")
		(net "M_I_CPU1_SB_DQS_DP<8>")
	)
	(arc
		(start 143.002508 -291.906198)
		(mid 143.067755 -292.168801)
		(end 143.248126 -292.37051)
		(width 0.09525)
		(layer "In2.Cu")
		(net "M_I_CPU1_SB_DQS_DP<8>")
	)
	(arc
		(start 144.412208 -294.336216)
		(mid 144.477455 -294.598819)
		(end 144.657826 -294.800528)
		(width 0.09525)
		(layer "In2.Cu")
		(net "M_I_CPU1_SB_DQS_DP<8>")
	)
	(arc
		(start 130.593338 -291.581078)
		(mid 130.87477 -291.656833)
		(end 131.156202 -291.581078)
		(width 0.09525)
		(layer "In2.Cu")
		(net "M_I_CPU1_SB_DQS_DP<8>")
	)
	(arc
		(start 144.882362 -295.146222)
		(mid 144.946759 -295.407528)
		(end 145.125186 -295.60901)
		(width 0.09525)
		(layer "In2.Cu")
		(net "M_I_CPU1_SB_DQS_DP<8>")
	)
	(arc
		(start 133.97611 -291.581078)
		(mid 134.159885 -291.530306)
		(end 134.344918 -291.576252)
		(width 0.09525)
		(layer "In2.Cu")
		(net "M_I_CPU1_SB_DQS_DP<8>")
	)
	(arc
		(start 136.233408 -291.581078)
		(mid 136.51484 -291.656833)
		(end 136.796272 -291.581078)
		(width 0.09525)
		(layer "In2.Cu")
		(net "M_I_CPU1_SB_DQS_DP<8>")
	)
	(arc
		(start 140.564616 -291.576252)
		(mid 140.749648 -291.530338)
		(end 140.933424 -291.581078)
		(width 0.09525)
		(layer "In2.Cu")
		(net "M_I_CPU1_SB_DQS_DP<8>")
	)
	(arc
		(start 128.71323 -291.581078)
		(mid 128.994662 -291.656833)
		(end 129.276094 -291.581078)
		(width 0.09525)
		(layer "In2.Cu")
		(net "M_I_CPU1_SB_DQS_DP<8>")
	)
	(arc
		(start 143.784828 -293.219378)
		(mid 143.900626 -293.353772)
		(end 143.942308 -293.52621)
		(width 0.09525)
		(layer "In2.Cu")
		(net "M_I_CPU1_SB_DQS_DP<8>")
	)
	(arc
		(start 143.31569 -292.40988)
		(mid 143.430964 -292.544158)
		(end 143.472408 -292.716204)
		(width 0.09525)
		(layer "In2.Cu")
		(net "M_I_CPU1_SB_DQS_DP<8>")
	)
	(arc
		(start 135.8646 -291.576252)
		(mid 136.049632 -291.530338)
		(end 136.233408 -291.581078)
		(width 0.09525)
		(layer "In2.Cu")
		(net "M_I_CPU1_SB_DQS_DP<8>")
	)
	(arc
		(start 138.113262 -291.581078)
		(mid 138.394694 -291.656833)
		(end 138.676126 -291.581078)
		(width 0.09525)
		(layer "In2.Cu")
		(net "M_I_CPU1_SB_DQS_DP<8>")
	)
	(arc
		(start 129.653284 -291.581078)
		(mid 129.934716 -291.656833)
		(end 130.216148 -291.581078)
		(width 0.09525)
		(layer "In2.Cu")
		(net "M_I_CPU1_SB_DQS_DP<8>")
	)
	(arc
		(start 137.736072 -291.581078)
		(mid 137.919847 -291.530306)
		(end 138.10488 -291.576252)
		(width 0.09525)
		(layer "In2.Cu")
		(net "M_I_CPU1_SB_DQS_DP<8>")
	)
	(arc
		(start 136.796272 -291.581078)
		(mid 136.98474 -291.530401)
		(end 137.173208 -291.581078)
		(width 0.09525)
		(layer "In2.Cu")
		(net "M_I_CPU1_SB_DQS_DP<8>")
	)
	(arc
		(start 135.293354 -291.581078)
		(mid 135.574786 -291.656833)
		(end 135.856218 -291.581078)
		(width 0.09525)
		(layer "In2.Cu")
		(net "M_I_CPU1_SB_DQS_DP<8>")
	)
	(arc
		(start 144.727676 -294.841168)
		(mid 144.841461 -294.975212)
		(end 144.882362 -295.146222)
		(width 0.09525)
		(layer "In2.Cu")
		(net "M_I_CPU1_SB_DQS_DP<8>")
	)
	(arc
		(start 133.03631 -291.581078)
		(mid 133.224778 -291.530401)
		(end 133.413246 -291.581078)
		(width 0.09525)
		(layer "In2.Cu")
		(net "M_I_CPU1_SB_DQS_DP<8>")
	)
	(arc
		(start 139.053316 -291.581078)
		(mid 139.334748 -291.656833)
		(end 139.61618 -291.581078)
		(width 0.09525)
		(layer "In2.Cu")
		(net "M_I_CPU1_SB_DQS_DP<8>")
	)
	(arc
		(start 142.436088 -291.581078)
		(mid 142.619863 -291.530306)
		(end 142.804896 -291.576252)
		(width 0.09525)
		(layer "In2.Cu")
		(net "M_I_CPU1_SB_DQS_DP<8>")
	)
	(arc
		(start 143.942308 -293.52621)
		(mid 144.006705 -293.787516)
		(end 144.185132 -293.988998)
		(width 0.09525)
		(layer "In2.Cu")
		(net "M_I_CPU1_SB_DQS_DP<8>")
	)
	(arc
		(start 132.473446 -291.581078)
		(mid 132.754878 -291.656833)
		(end 133.03631 -291.581078)
		(width 0.09525)
		(layer "In2.Cu")
		(net "M_I_CPU1_SB_DQS_DP<8>")
	)
	(arc
		(start 137.173208 -291.581078)
		(mid 137.45464 -291.656833)
		(end 137.736072 -291.581078)
		(width 0.09525)
		(layer "In2.Cu")
		(net "M_I_CPU1_SB_DQS_DP<8>")
	)
	(arc
		(start 131.533392 -291.581078)
		(mid 131.814824 -291.656833)
		(end 132.096256 -291.581078)
		(width 0.09525)
		(layer "In2.Cu")
		(net "M_I_CPU1_SB_DQS_DP<8>")
	)
	(arc
		(start 144.254728 -294.029384)
		(mid 144.370526 -294.163778)
		(end 144.412208 -294.336216)
		(width 0.09525)
		(layer "In2.Cu")
		(net "M_I_CPU1_SB_DQS_DP<8>")
	)
	(arc
		(start 140.933424 -291.581078)
		(mid 141.214856 -291.656833)
		(end 141.496288 -291.581078)
		(width 0.09525)
		(layer "In2.Cu")
		(net "M_I_CPU1_SB_DQS_DP<8>")
	)
	(arc
		(start 134.924546 -291.576252)
		(mid 135.109578 -291.530338)
		(end 135.293354 -291.581078)
		(width 0.09525)
		(layer "In2.Cu")
		(net "M_I_CPU1_SB_DQS_DP<8>")
	)
	(arc
		(start 143.472408 -292.716204)
		(mid 143.536805 -292.97751)
		(end 143.715232 -293.178992)
		(width 0.09525)
		(layer "In2.Cu")
		(net "M_I_CPU1_SB_DQS_DP<8>")
	)
	(arc
		(start 133.413246 -291.581078)
		(mid 133.694678 -291.656833)
		(end 133.97611 -291.581078)
		(width 0.09525)
		(layer "In2.Cu")
		(net "M_I_CPU1_SB_DQS_DP<8>")
	)
	(arc
		(start 141.496288 -291.581078)
		(mid 141.684756 -291.530401)
		(end 141.873224 -291.581078)
		(width 0.09525)
		(layer "In2.Cu")
		(net "M_I_CPU1_SB_DQS_DP<8>")
	)
	(arc
		(start 132.104638 -291.576252)
		(mid 132.28967 -291.530338)
		(end 132.473446 -291.581078)
		(width 0.09525)
		(layer "In2.Cu")
		(net "M_I_CPU1_SB_DQS_DP<8>")
	)
	(arc
		(start 129.276094 -291.581078)
		(mid 129.459869 -291.530306)
		(end 129.644902 -291.576252)
		(width 0.09525)
		(layer "In2.Cu")
		(net "M_I_CPU1_SB_DQS_DP<8>")
	)
	(arc
		(start 131.164584 -291.576252)
		(mid 131.349616 -291.530338)
		(end 131.533392 -291.581078)
		(width 0.09525)
		(layer "In2.Cu")
		(net "M_I_CPU1_SB_DQS_DP<8>")
	)
	(arc
		(start 130.216148 -291.581078)
		(mid 130.399923 -291.530306)
		(end 130.584956 -291.576252)
		(width 0.09525)
		(layer "In2.Cu")
		(net "M_I_CPU1_SB_DQS_DP<8>")
	)
	(arc
		(start 138.676126 -291.581078)
		(mid 138.859901 -291.530306)
		(end 139.044934 -291.576252)
		(width 0.09525)
		(layer "In2.Cu")
		(net "M_I_CPU1_SB_DQS_DP<8>")
	)
	(arc
		(start 141.873224 -291.581078)
		(mid 142.154656 -291.656833)
		(end 142.436088 -291.581078)
		(width 0.09525)
		(layer "In2.Cu")
		(net "M_I_CPU1_SB_DQS_DP<8>")
	)
	(arc
		(start 128.393952 -291.554154)
		(mid 128.556603 -291.531894)
		(end 128.71323 -291.581078)
		(width 0.09525)
		(layer "In2.Cu")
		(net "M_I_CPU1_SB_DQS_DP<8>")
	)
	(arc
		(start 139.624562 -291.576252)
		(mid 139.809594 -291.530338)
		(end 139.99337 -291.581078)
		(width 0.09525)
		(layer "In2.Cu")
		(net "M_I_CPU1_SB_DQS_DP<8>")
	)
	(arc
		(start 134.3533 -291.581078)
		(mid 134.634732 -291.656833)
		(end 134.916164 -291.581078)
		(width 0.09525)
		(layer "In2.Cu")
		(net "M_I_CPU1_SB_DQS_DP<8>")
	)
	(arc
		(start 139.99337 -291.581078)
		(mid 140.274802 -291.656833)
		(end 140.556234 -291.581078)
		(width 0.09525)
		(layer "In2.Cu")
		(net "M_I_CPU1_SB_DQS_DP<8>")
	)
	(arc
		(start 142.84579 -291.599874)
		(mid 142.961064 -291.734152)
		(end 143.002508 -291.906198)
		(width 0.09525)
		(layer "In2.Cu")
		(net "M_I_CPU1_SB_DQS_DP<8>")
	)
	(segment
		(start 128.05791 -286.780478)
		(end 128.524762 -287.046162)
		(width 0.12954)
		(layer "F.Cu")
		(net "M_I_CPU1_SB_DQS_DP<7>")
	)
	(segment
		(start 158.802832 -302.793908)
		(end 159.184594 -302.412146)
		(width 0.16002)
		(layer "In2.Cu")
		(net "M_I_CPU1_SB_DQS_DP<7>")
	)
	(segment
		(start 147.180808 -288.669476)
		(end 147.197572 -288.68624)
		(width 0.09525)
		(layer "In2.Cu")
		(net "M_I_CPU1_SB_DQS_DP<7>")
	)
	(segment
		(start 159.460946 -302.412146)
		(end 159.657796 -302.608996)
		(width 0.16002)
		(layer "In2.Cu")
		(net "M_I_CPU1_SB_DQS_DP<7>")
	)
	(segment
		(start 157.902656 -302.421036)
		(end 158.275528 -302.793908)
		(width 0.16002)
		(layer "In2.Cu")
		(net "M_I_CPU1_SB_DQS_DP<7>")
	)
	(segment
		(start 166.912798 -304.853086)
		(end 167.325802 -304.853086)
		(width 0.16002)
		(layer "In2.Cu")
		(net "M_I_CPU1_SB_DQS_DP<7>")
	)
	(segment
		(start 158.087314 -301.038514)
		(end 158.284164 -301.235364)
		(width 0.16002)
		(layer "In2.Cu")
		(net "M_I_CPU1_SB_DQS_DP<7>")
	)
	(segment
		(start 165.318694 -306.01031)
		(end 165.683438 -305.645566)
		(width 0.16002)
		(layer "In2.Cu")
		(net "M_I_CPU1_SB_DQS_DP<7>")
	)
	(segment
		(start 144.288256 -286.736282)
		(end 144.314164 -286.721296)
		(width 0.09525)
		(layer "In2.Cu")
		(net "M_I_CPU1_SB_DQS_DP<7>")
	)
	(segment
		(start 143.376142 -286.721042)
		(end 143.384524 -286.716216)
		(width 0.09525)
		(layer "In2.Cu")
		(net "M_I_CPU1_SB_DQS_DP<7>")
	)
	(segment
		(start 165.683438 -305.645566)
		(end 166.120318 -305.645566)
		(width 0.16002)
		(layer "In2.Cu")
		(net "M_I_CPU1_SB_DQS_DP<7>")
	)
	(segment
		(start 131.156202 -286.721042)
		(end 131.164584 -286.716216)
		(width 0.09525)
		(layer "In2.Cu")
		(net "M_I_CPU1_SB_DQS_DP<7>")
	)
	(segment
		(start 140.556234 -286.721042)
		(end 140.564616 -286.716216)
		(width 0.09525)
		(layer "In2.Cu")
		(net "M_I_CPU1_SB_DQS_DP<7>")
	)
	(segment
		(start 158.284164 -301.51197)
		(end 157.902656 -301.893478)
		(width 0.16002)
		(layer "In2.Cu")
		(net "M_I_CPU1_SB_DQS_DP<7>")
	)
	(segment
		(start 156.910532 -300.138338)
		(end 156.529024 -300.519846)
		(width 0.16002)
		(layer "In2.Cu")
		(net "M_I_CPU1_SB_DQS_DP<7>")
	)
	(segment
		(start 159.184594 -302.412146)
		(end 159.460946 -302.412146)
		(width 0.16002)
		(layer "In2.Cu")
		(net "M_I_CPU1_SB_DQS_DP<7>")
	)
	(segment
		(start 156.529024 -300.519846)
		(end 156.529024 -301.047404)
		(width 0.16002)
		(layer "In2.Cu")
		(net "M_I_CPU1_SB_DQS_DP<7>")
	)
	(segment
		(start 157.4292 -301.420276)
		(end 157.810962 -301.038514)
		(width 0.16002)
		(layer "In2.Cu")
		(net "M_I_CPU1_SB_DQS_DP<7>")
	)
	(segment
		(start 156.901896 -301.420276)
		(end 157.4292 -301.420276)
		(width 0.16002)
		(layer "In2.Cu")
		(net "M_I_CPU1_SB_DQS_DP<7>")
	)
	(segment
		(start 159.276288 -303.26711)
		(end 159.276288 -303.794668)
		(width 0.16002)
		(layer "In2.Cu")
		(net "M_I_CPU1_SB_DQS_DP<7>")
	)
	(segment
		(start 179.24272 -305.01209)
		(end 179.516024 -305.285394)
		(width 0.16002)
		(layer "In2.Cu")
		(net "M_I_CPU1_SB_DQS_DP<7>")
	)
	(segment
		(start 158.275528 -302.793908)
		(end 158.802832 -302.793908)
		(width 0.16002)
		(layer "In2.Cu")
		(net "M_I_CPU1_SB_DQS_DP<7>")
	)
	(segment
		(start 134.344918 -286.716216)
		(end 134.3533 -286.721042)
		(width 0.09525)
		(layer "In2.Cu")
		(net "M_I_CPU1_SB_DQS_DP<7>")
	)
	(segment
		(start 144.501616 -286.670496)
		(end 145.67916 -286.670496)
		(width 0.09525)
		(layer "In2.Cu")
		(net "M_I_CPU1_SB_DQS_DP<7>")
	)
	(segment
		(start 132.096256 -286.721042)
		(end 132.104638 -286.716216)
		(width 0.09525)
		(layer "In2.Cu")
		(net "M_I_CPU1_SB_DQS_DP<7>")
	)
	(segment
		(start 135.856218 -286.721042)
		(end 135.8646 -286.716216)
		(width 0.09525)
		(layer "In2.Cu")
		(net "M_I_CPU1_SB_DQS_DP<7>")
	)
	(segment
		(start 166.120318 -305.645566)
		(end 166.912798 -304.853086)
		(width 0.16002)
		(layer "In2.Cu")
		(net "M_I_CPU1_SB_DQS_DP<7>")
	)
	(segment
		(start 158.284164 -301.235364)
		(end 158.284164 -301.51197)
		(width 0.16002)
		(layer "In2.Cu")
		(net "M_I_CPU1_SB_DQS_DP<7>")
	)
	(segment
		(start 149.506432 -292.448996)
		(end 156.910532 -299.853096)
		(width 0.16002)
		(layer "In2.Cu")
		(net "M_I_CPU1_SB_DQS_DP<7>")
	)
	(segment
		(start 167.325802 -304.853086)
		(end 167.633142 -305.160426)
		(width 0.16002)
		(layer "In2.Cu")
		(net "M_I_CPU1_SB_DQS_DP<7>")
	)
	(segment
		(start 159.276288 -303.794668)
		(end 160.321244 -304.839624)
		(width 0.16002)
		(layer "In2.Cu")
		(net "M_I_CPU1_SB_DQS_DP<7>")
	)
	(segment
		(start 145.67916 -286.670496)
		(end 146.19732 -287.188656)
		(width 0.09525)
		(layer "In2.Cu")
		(net "M_I_CPU1_SB_DQS_DP<7>")
	)
	(segment
		(start 177.250852 -305.160426)
		(end 177.399188 -305.01209)
		(width 0.16002)
		(layer "In2.Cu")
		(net "M_I_CPU1_SB_DQS_DP<7>")
	)
	(segment
		(start 174.869856 -304.853086)
		(end 175.177196 -305.160426)
		(width 0.16002)
		(layer "In2.Cu")
		(net "M_I_CPU1_SB_DQS_DP<7>")
	)
	(segment
		(start 173.227492 -305.645566)
		(end 173.664372 -305.645566)
		(width 0.16002)
		(layer "In2.Cu")
		(net "M_I_CPU1_SB_DQS_DP<7>")
	)
	(segment
		(start 142.804896 -286.716216)
		(end 142.813278 -286.721042)
		(width 0.09525)
		(layer "In2.Cu")
		(net "M_I_CPU1_SB_DQS_DP<7>")
	)
	(segment
		(start 146.19732 -287.188656)
		(end 146.19732 -287.60293)
		(width 0.09525)
		(layer "In2.Cu")
		(net "M_I_CPU1_SB_DQS_DP<7>")
	)
	(segment
		(start 128.524762 -287.046162)
		(end 128.370838 -286.780732)
		(width 0.09525)
		(layer "In2.Cu")
		(net "M_I_CPU1_SB_DQS_DP<7>")
	)
	(segment
		(start 129.644902 -286.716216)
		(end 129.653284 -286.721042)
		(width 0.09525)
		(layer "In2.Cu")
		(net "M_I_CPU1_SB_DQS_DP<7>")
	)
	(segment
		(start 138.10488 -286.716216)
		(end 138.113262 -286.721042)
		(width 0.09525)
		(layer "In2.Cu")
		(net "M_I_CPU1_SB_DQS_DP<7>")
	)
	(segment
		(start 157.902656 -301.893478)
		(end 157.902656 -302.421036)
		(width 0.16002)
		(layer "In2.Cu")
		(net "M_I_CPU1_SB_DQS_DP<7>")
	)
	(segment
		(start 148.477732 -289.9664)
		(end 149.506432 -292.448996)
		(width 0.16002)
		(layer "In2.Cu")
		(net "M_I_CPU1_SB_DQS_DP<7>")
	)
	(segment
		(start 173.664372 -305.645566)
		(end 174.456852 -304.853086)
		(width 0.16002)
		(layer "In2.Cu")
		(net "M_I_CPU1_SB_DQS_DP<7>")
	)
	(segment
		(start 139.044934 -286.716216)
		(end 139.053316 -286.721042)
		(width 0.09525)
		(layer "In2.Cu")
		(net "M_I_CPU1_SB_DQS_DP<7>")
	)
	(segment
		(start 177.399188 -305.01209)
		(end 179.24272 -305.01209)
		(width 0.16002)
		(layer "In2.Cu")
		(net "M_I_CPU1_SB_DQS_DP<7>")
	)
	(segment
		(start 170.196256 -305.160426)
		(end 171.046394 -306.010564)
		(width 0.16002)
		(layer "In2.Cu")
		(net "M_I_CPU1_SB_DQS_DP<7>")
	)
	(segment
		(start 174.456852 -304.853086)
		(end 174.869856 -304.853086)
		(width 0.16002)
		(layer "In2.Cu")
		(net "M_I_CPU1_SB_DQS_DP<7>")
	)
	(segment
		(start 159.657796 -302.885602)
		(end 159.276288 -303.26711)
		(width 0.16002)
		(layer "In2.Cu")
		(net "M_I_CPU1_SB_DQS_DP<7>")
	)
	(segment
		(start 128.370838 -286.780732)
		(end 128.393952 -286.694118)
		(width 0.09525)
		(layer "In2.Cu")
		(net "M_I_CPU1_SB_DQS_DP<7>")
	)
	(segment
		(start 139.61618 -286.721042)
		(end 139.624562 -286.716216)
		(width 0.09525)
		(layer "In2.Cu")
		(net "M_I_CPU1_SB_DQS_DP<7>")
	)
	(segment
		(start 156.529024 -301.047404)
		(end 156.901896 -301.420276)
		(width 0.16002)
		(layer "In2.Cu")
		(net "M_I_CPU1_SB_DQS_DP<7>")
	)
	(segment
		(start 163.147502 -306.01031)
		(end 165.318694 -306.01031)
		(width 0.16002)
		(layer "In2.Cu")
		(net "M_I_CPU1_SB_DQS_DP<7>")
	)
	(segment
		(start 156.910532 -299.853096)
		(end 156.910532 -300.138338)
		(width 0.16002)
		(layer "In2.Cu")
		(net "M_I_CPU1_SB_DQS_DP<7>")
	)
	(segment
		(start 175.177196 -305.160426)
		(end 177.250852 -305.160426)
		(width 0.16002)
		(layer "In2.Cu")
		(net "M_I_CPU1_SB_DQS_DP<7>")
	)
	(segment
		(start 147.197572 -288.68624)
		(end 148.477732 -289.9664)
		(width 0.16002)
		(layer "In2.Cu")
		(net "M_I_CPU1_SB_DQS_DP<7>")
	)
	(segment
		(start 167.633142 -305.160426)
		(end 170.196256 -305.160426)
		(width 0.16002)
		(layer "In2.Cu")
		(net "M_I_CPU1_SB_DQS_DP<7>")
	)
	(segment
		(start 134.916164 -286.721042)
		(end 134.924546 -286.716216)
		(width 0.09525)
		(layer "In2.Cu")
		(net "M_I_CPU1_SB_DQS_DP<7>")
	)
	(segment
		(start 159.657796 -302.608996)
		(end 159.657796 -302.885602)
		(width 0.16002)
		(layer "In2.Cu")
		(net "M_I_CPU1_SB_DQS_DP<7>")
	)
	(segment
		(start 147.180808 -288.586672)
		(end 147.180808 -288.669476)
		(width 0.09525)
		(layer "In2.Cu")
		(net "M_I_CPU1_SB_DQS_DP<7>")
	)
	(segment
		(start 157.810962 -301.038514)
		(end 158.087314 -301.038514)
		(width 0.16002)
		(layer "In2.Cu")
		(net "M_I_CPU1_SB_DQS_DP<7>")
	)
	(segment
		(start 146.19732 -287.60293)
		(end 147.180808 -288.586672)
		(width 0.09525)
		(layer "In2.Cu")
		(net "M_I_CPU1_SB_DQS_DP<7>")
	)
	(segment
		(start 160.321244 -304.839624)
		(end 163.147502 -306.01031)
		(width 0.16002)
		(layer "In2.Cu")
		(net "M_I_CPU1_SB_DQS_DP<7>")
	)
	(segment
		(start 172.862494 -306.010564)
		(end 173.227492 -305.645566)
		(width 0.16002)
		(layer "In2.Cu")
		(net "M_I_CPU1_SB_DQS_DP<7>")
	)
	(segment
		(start 171.046394 -306.010564)
		(end 172.862494 -306.010564)
		(width 0.16002)
		(layer "In2.Cu")
		(net "M_I_CPU1_SB_DQS_DP<7>")
	)
	(segment
		(start 130.584956 -286.716216)
		(end 130.593338 -286.721042)
		(width 0.09525)
		(layer "In2.Cu")
		(net "M_I_CPU1_SB_DQS_DP<7>")
	)
	(arc
		(start 137.736072 -286.721042)
		(mid 137.919847 -286.67027)
		(end 138.10488 -286.716216)
		(width 0.09525)
		(layer "In2.Cu")
		(net "M_I_CPU1_SB_DQS_DP<7>")
	)
	(arc
		(start 133.97611 -286.721042)
		(mid 134.159885 -286.67027)
		(end 134.344918 -286.716216)
		(width 0.09525)
		(layer "In2.Cu")
		(net "M_I_CPU1_SB_DQS_DP<7>")
	)
	(arc
		(start 131.533392 -286.721042)
		(mid 131.814824 -286.796831)
		(end 132.096256 -286.721042)
		(width 0.09525)
		(layer "In2.Cu")
		(net "M_I_CPU1_SB_DQS_DP<7>")
	)
	(arc
		(start 136.233408 -286.721042)
		(mid 136.51484 -286.796831)
		(end 136.796272 -286.721042)
		(width 0.09525)
		(layer "In2.Cu")
		(net "M_I_CPU1_SB_DQS_DP<7>")
	)
	(arc
		(start 144.314164 -286.721296)
		(mid 144.404552 -286.683591)
		(end 144.501616 -286.670496)
		(width 0.09525)
		(layer "In2.Cu")
		(net "M_I_CPU1_SB_DQS_DP<7>")
	)
	(arc
		(start 142.813278 -286.721042)
		(mid 143.09471 -286.796831)
		(end 143.376142 -286.721042)
		(width 0.09525)
		(layer "In2.Cu")
		(net "M_I_CPU1_SB_DQS_DP<7>")
	)
	(arc
		(start 135.8646 -286.716216)
		(mid 136.049632 -286.670302)
		(end 136.233408 -286.721042)
		(width 0.09525)
		(layer "In2.Cu")
		(net "M_I_CPU1_SB_DQS_DP<7>")
	)
	(arc
		(start 141.873224 -286.721042)
		(mid 142.154656 -286.796831)
		(end 142.436088 -286.721042)
		(width 0.09525)
		(layer "In2.Cu")
		(net "M_I_CPU1_SB_DQS_DP<7>")
	)
	(arc
		(start 129.276094 -286.721042)
		(mid 129.459869 -286.67027)
		(end 129.644902 -286.716216)
		(width 0.09525)
		(layer "In2.Cu")
		(net "M_I_CPU1_SB_DQS_DP<7>")
	)
	(arc
		(start 140.933424 -286.721042)
		(mid 141.214856 -286.796831)
		(end 141.496288 -286.721042)
		(width 0.09525)
		(layer "In2.Cu")
		(net "M_I_CPU1_SB_DQS_DP<7>")
	)
	(arc
		(start 133.413246 -286.721042)
		(mid 133.694678 -286.796831)
		(end 133.97611 -286.721042)
		(width 0.09525)
		(layer "In2.Cu")
		(net "M_I_CPU1_SB_DQS_DP<7>")
	)
	(arc
		(start 139.99337 -286.721042)
		(mid 140.274802 -286.796831)
		(end 140.556234 -286.721042)
		(width 0.09525)
		(layer "In2.Cu")
		(net "M_I_CPU1_SB_DQS_DP<7>")
	)
	(arc
		(start 138.113262 -286.721042)
		(mid 138.394694 -286.796831)
		(end 138.676126 -286.721042)
		(width 0.09525)
		(layer "In2.Cu")
		(net "M_I_CPU1_SB_DQS_DP<7>")
	)
	(arc
		(start 136.796272 -286.721042)
		(mid 136.98474 -286.670365)
		(end 137.173208 -286.721042)
		(width 0.09525)
		(layer "In2.Cu")
		(net "M_I_CPU1_SB_DQS_DP<7>")
	)
	(arc
		(start 143.384524 -286.716216)
		(mid 143.569556 -286.670302)
		(end 143.753332 -286.721042)
		(width 0.09525)
		(layer "In2.Cu")
		(net "M_I_CPU1_SB_DQS_DP<7>")
	)
	(arc
		(start 133.03631 -286.721042)
		(mid 133.224778 -286.670365)
		(end 133.413246 -286.721042)
		(width 0.09525)
		(layer "In2.Cu")
		(net "M_I_CPU1_SB_DQS_DP<7>")
	)
	(arc
		(start 132.104638 -286.716216)
		(mid 132.28967 -286.670302)
		(end 132.473446 -286.721042)
		(width 0.09525)
		(layer "In2.Cu")
		(net "M_I_CPU1_SB_DQS_DP<7>")
	)
	(arc
		(start 130.593338 -286.721042)
		(mid 130.87477 -286.796831)
		(end 131.156202 -286.721042)
		(width 0.09525)
		(layer "In2.Cu")
		(net "M_I_CPU1_SB_DQS_DP<7>")
	)
	(arc
		(start 142.436088 -286.721042)
		(mid 142.619863 -286.67027)
		(end 142.804896 -286.716216)
		(width 0.09525)
		(layer "In2.Cu")
		(net "M_I_CPU1_SB_DQS_DP<7>")
	)
	(arc
		(start 143.753332 -286.721042)
		(mid 144.018852 -286.796605)
		(end 144.288256 -286.736282)
		(width 0.09525)
		(layer "In2.Cu")
		(net "M_I_CPU1_SB_DQS_DP<7>")
	)
	(arc
		(start 130.216148 -286.721042)
		(mid 130.399923 -286.67027)
		(end 130.584956 -286.716216)
		(width 0.09525)
		(layer "In2.Cu")
		(net "M_I_CPU1_SB_DQS_DP<7>")
	)
	(arc
		(start 134.924546 -286.716216)
		(mid 135.109578 -286.670302)
		(end 135.293354 -286.721042)
		(width 0.09525)
		(layer "In2.Cu")
		(net "M_I_CPU1_SB_DQS_DP<7>")
	)
	(arc
		(start 140.564616 -286.716216)
		(mid 140.749648 -286.670302)
		(end 140.933424 -286.721042)
		(width 0.09525)
		(layer "In2.Cu")
		(net "M_I_CPU1_SB_DQS_DP<7>")
	)
	(arc
		(start 128.71323 -286.721042)
		(mid 128.994662 -286.796831)
		(end 129.276094 -286.721042)
		(width 0.09525)
		(layer "In2.Cu")
		(net "M_I_CPU1_SB_DQS_DP<7>")
	)
	(arc
		(start 129.653284 -286.721042)
		(mid 129.934716 -286.796831)
		(end 130.216148 -286.721042)
		(width 0.09525)
		(layer "In2.Cu")
		(net "M_I_CPU1_SB_DQS_DP<7>")
	)
	(arc
		(start 132.473446 -286.721042)
		(mid 132.754878 -286.796831)
		(end 133.03631 -286.721042)
		(width 0.09525)
		(layer "In2.Cu")
		(net "M_I_CPU1_SB_DQS_DP<7>")
	)
	(arc
		(start 138.676126 -286.721042)
		(mid 138.859901 -286.67027)
		(end 139.044934 -286.716216)
		(width 0.09525)
		(layer "In2.Cu")
		(net "M_I_CPU1_SB_DQS_DP<7>")
	)
	(arc
		(start 139.053316 -286.721042)
		(mid 139.334748 -286.796831)
		(end 139.61618 -286.721042)
		(width 0.09525)
		(layer "In2.Cu")
		(net "M_I_CPU1_SB_DQS_DP<7>")
	)
	(arc
		(start 141.496288 -286.721042)
		(mid 141.684756 -286.670365)
		(end 141.873224 -286.721042)
		(width 0.09525)
		(layer "In2.Cu")
		(net "M_I_CPU1_SB_DQS_DP<7>")
	)
	(arc
		(start 135.293354 -286.721042)
		(mid 135.574786 -286.796831)
		(end 135.856218 -286.721042)
		(width 0.09525)
		(layer "In2.Cu")
		(net "M_I_CPU1_SB_DQS_DP<7>")
	)
	(arc
		(start 134.3533 -286.721042)
		(mid 134.634732 -286.796831)
		(end 134.916164 -286.721042)
		(width 0.09525)
		(layer "In2.Cu")
		(net "M_I_CPU1_SB_DQS_DP<7>")
	)
	(arc
		(start 131.164584 -286.716216)
		(mid 131.349616 -286.670302)
		(end 131.533392 -286.721042)
		(width 0.09525)
		(layer "In2.Cu")
		(net "M_I_CPU1_SB_DQS_DP<7>")
	)
	(arc
		(start 139.624562 -286.716216)
		(mid 139.809594 -286.670302)
		(end 139.99337 -286.721042)
		(width 0.09525)
		(layer "In2.Cu")
		(net "M_I_CPU1_SB_DQS_DP<7>")
	)
	(arc
		(start 137.173208 -286.721042)
		(mid 137.45464 -286.796831)
		(end 137.736072 -286.721042)
		(width 0.09525)
		(layer "In2.Cu")
		(net "M_I_CPU1_SB_DQS_DP<7>")
	)
	(arc
		(start 128.393952 -286.694118)
		(mid 128.556603 -286.671858)
		(end 128.71323 -286.721042)
		(width 0.09525)
		(layer "In2.Cu")
		(net "M_I_CPU1_SB_DQS_DP<7>")
	)
	(segment
		(start 128.05791 -281.920442)
		(end 128.524762 -282.18638)
		(width 0.12954)
		(layer "F.Cu")
		(net "M_I_CPU1_SB_DQS_DP<6>")
	)
	(segment
		(start 154.379676 -286.789114)
		(end 154.614118 -287.023556)
		(width 0.16002)
		(layer "In2.Cu")
		(net "M_I_CPU1_SB_DQS_DP<6>")
	)
	(segment
		(start 132.096256 -281.86126)
		(end 132.104638 -281.856434)
		(width 0.09525)
		(layer "In2.Cu")
		(net "M_I_CPU1_SB_DQS_DP<6>")
	)
	(segment
		(start 166.120318 -296.295572)
		(end 166.912798 -295.503092)
		(width 0.16002)
		(layer "In2.Cu")
		(net "M_I_CPU1_SB_DQS_DP<6>")
	)
	(segment
		(start 145.94332 -282.061666)
		(end 147.836636 -282.061666)
		(width 0.09525)
		(layer "In2.Cu")
		(net "M_I_CPU1_SB_DQS_DP<6>")
	)
	(segment
		(start 155.98775 -288.397188)
		(end 155.98775 -289.12566)
		(width 0.16002)
		(layer "In2.Cu")
		(net "M_I_CPU1_SB_DQS_DP<6>")
	)
	(segment
		(start 139.61618 -281.86126)
		(end 139.624562 -281.856434)
		(width 0.09525)
		(layer "In2.Cu")
		(net "M_I_CPU1_SB_DQS_DP<6>")
	)
	(segment
		(start 154.614118 -287.752028)
		(end 155.024836 -288.162746)
		(width 0.16002)
		(layer "In2.Cu")
		(net "M_I_CPU1_SB_DQS_DP<6>")
	)
	(segment
		(start 178.476148 -295.778936)
		(end 178.592988 -295.662096)
		(width 0.16002)
		(layer "In2.Cu")
		(net "M_I_CPU1_SB_DQS_DP<6>")
	)
	(segment
		(start 155.98775 -289.12566)
		(end 156.398468 -289.536378)
		(width 0.16002)
		(layer "In2.Cu")
		(net "M_I_CPU1_SB_DQS_DP<6>")
	)
	(segment
		(start 144.314164 -281.861514)
		(end 144.336008 -281.849068)
		(width 0.09525)
		(layer "In2.Cu")
		(net "M_I_CPU1_SB_DQS_DP<6>")
	)
	(segment
		(start 134.916164 -281.86126)
		(end 134.924546 -281.856434)
		(width 0.09525)
		(layer "In2.Cu")
		(net "M_I_CPU1_SB_DQS_DP<6>")
	)
	(segment
		(start 128.524762 -282.18638)
		(end 128.370838 -281.92095)
		(width 0.09525)
		(layer "In2.Cu")
		(net "M_I_CPU1_SB_DQS_DP<6>")
	)
	(segment
		(start 157.12694 -289.536378)
		(end 157.361382 -289.77082)
		(width 0.16002)
		(layer "In2.Cu")
		(net "M_I_CPU1_SB_DQS_DP<6>")
	)
	(segment
		(start 155.753308 -288.162746)
		(end 155.98775 -288.397188)
		(width 0.16002)
		(layer "In2.Cu")
		(net "M_I_CPU1_SB_DQS_DP<6>")
	)
	(segment
		(start 163.522406 -296.660316)
		(end 165.318694 -296.660316)
		(width 0.16002)
		(layer "In2.Cu")
		(net "M_I_CPU1_SB_DQS_DP<6>")
	)
	(segment
		(start 174.456852 -295.503092)
		(end 174.869856 -295.503092)
		(width 0.16002)
		(layer "In2.Cu")
		(net "M_I_CPU1_SB_DQS_DP<6>")
	)
	(segment
		(start 167.633142 -295.810432)
		(end 170.096688 -295.810432)
		(width 0.16002)
		(layer "In2.Cu")
		(net "M_I_CPU1_SB_DQS_DP<6>")
	)
	(segment
		(start 142.804896 -281.856434)
		(end 142.813278 -281.86126)
		(width 0.09525)
		(layer "In2.Cu")
		(net "M_I_CPU1_SB_DQS_DP<6>")
	)
	(segment
		(start 134.344918 -281.856434)
		(end 134.3533 -281.86126)
		(width 0.09525)
		(layer "In2.Cu")
		(net "M_I_CPU1_SB_DQS_DP<6>")
	)
	(segment
		(start 128.370838 -281.92095)
		(end 128.393952 -281.834336)
		(width 0.09525)
		(layer "In2.Cu")
		(net "M_I_CPU1_SB_DQS_DP<6>")
	)
	(segment
		(start 173.97349 -295.986454)
		(end 174.456852 -295.503092)
		(width 0.16002)
		(layer "In2.Cu")
		(net "M_I_CPU1_SB_DQS_DP<6>")
	)
	(segment
		(start 145.691352 -281.809698)
		(end 145.94332 -282.061666)
		(width 0.09525)
		(layer "In2.Cu")
		(net "M_I_CPU1_SB_DQS_DP<6>")
	)
	(segment
		(start 178.592988 -295.662096)
		(end 179.24272 -295.662096)
		(width 0.16002)
		(layer "In2.Cu")
		(net "M_I_CPU1_SB_DQS_DP<6>")
	)
	(segment
		(start 167.325802 -295.503092)
		(end 167.633142 -295.810432)
		(width 0.16002)
		(layer "In2.Cu")
		(net "M_I_CPU1_SB_DQS_DP<6>")
	)
	(segment
		(start 129.644902 -281.856434)
		(end 129.653284 -281.86126)
		(width 0.09525)
		(layer "In2.Cu")
		(net "M_I_CPU1_SB_DQS_DP<6>")
	)
	(segment
		(start 140.556234 -281.86126)
		(end 140.564616 -281.856434)
		(width 0.09525)
		(layer "In2.Cu")
		(net "M_I_CPU1_SB_DQS_DP<6>")
	)
	(segment
		(start 165.318694 -296.660316)
		(end 165.683438 -296.295572)
		(width 0.16002)
		(layer "In2.Cu")
		(net "M_I_CPU1_SB_DQS_DP<6>")
	)
	(segment
		(start 138.10488 -281.856434)
		(end 138.113262 -281.86126)
		(width 0.09525)
		(layer "In2.Cu")
		(net "M_I_CPU1_SB_DQS_DP<6>")
	)
	(segment
		(start 139.044934 -281.856434)
		(end 139.053316 -281.86126)
		(width 0.09525)
		(layer "In2.Cu")
		(net "M_I_CPU1_SB_DQS_DP<6>")
	)
	(segment
		(start 148.982684 -282.120594)
		(end 153.651204 -286.789114)
		(width 0.16002)
		(layer "In2.Cu")
		(net "M_I_CPU1_SB_DQS_DP<6>")
	)
	(segment
		(start 170.096688 -295.810432)
		(end 170.946826 -296.66057)
		(width 0.16002)
		(layer "In2.Cu")
		(net "M_I_CPU1_SB_DQS_DP<6>")
	)
	(segment
		(start 147.895564 -282.120594)
		(end 147.919186 -282.120594)
		(width 0.09525)
		(layer "In2.Cu")
		(net "M_I_CPU1_SB_DQS_DP<6>")
	)
	(segment
		(start 160.108646 -292.518084)
		(end 160.108646 -293.246556)
		(width 0.16002)
		(layer "In2.Cu")
		(net "M_I_CPU1_SB_DQS_DP<6>")
	)
	(segment
		(start 157.7721 -290.91001)
		(end 158.500572 -290.91001)
		(width 0.16002)
		(layer "In2.Cu")
		(net "M_I_CPU1_SB_DQS_DP<6>")
	)
	(segment
		(start 158.735014 -291.144452)
		(end 158.735014 -291.872924)
		(width 0.16002)
		(layer "In2.Cu")
		(net "M_I_CPU1_SB_DQS_DP<6>")
	)
	(segment
		(start 130.584956 -281.856434)
		(end 130.593338 -281.86126)
		(width 0.09525)
		(layer "In2.Cu")
		(net "M_I_CPU1_SB_DQS_DP<6>")
	)
	(segment
		(start 158.735014 -291.872924)
		(end 159.145732 -292.283642)
		(width 0.16002)
		(layer "In2.Cu")
		(net "M_I_CPU1_SB_DQS_DP<6>")
	)
	(segment
		(start 155.024836 -288.162746)
		(end 155.753308 -288.162746)
		(width 0.16002)
		(layer "In2.Cu")
		(net "M_I_CPU1_SB_DQS_DP<6>")
	)
	(segment
		(start 153.651204 -286.789114)
		(end 154.379676 -286.789114)
		(width 0.16002)
		(layer "In2.Cu")
		(net "M_I_CPU1_SB_DQS_DP<6>")
	)
	(segment
		(start 157.361382 -289.77082)
		(end 157.361382 -290.499292)
		(width 0.16002)
		(layer "In2.Cu")
		(net "M_I_CPU1_SB_DQS_DP<6>")
	)
	(segment
		(start 154.614118 -287.023556)
		(end 154.614118 -287.752028)
		(width 0.16002)
		(layer "In2.Cu")
		(net "M_I_CPU1_SB_DQS_DP<6>")
	)
	(segment
		(start 177.250852 -295.810432)
		(end 177.399188 -295.662096)
		(width 0.16002)
		(layer "In2.Cu")
		(net "M_I_CPU1_SB_DQS_DP<6>")
	)
	(segment
		(start 177.879248 -295.662096)
		(end 177.996088 -295.778936)
		(width 0.16002)
		(layer "In2.Cu")
		(net "M_I_CPU1_SB_DQS_DP<6>")
	)
	(segment
		(start 173.227492 -296.295572)
		(end 173.97349 -295.986454)
		(width 0.16002)
		(layer "In2.Cu")
		(net "M_I_CPU1_SB_DQS_DP<6>")
	)
	(segment
		(start 161.482278 -294.620188)
		(end 163.522406 -296.660316)
		(width 0.16002)
		(layer "In2.Cu")
		(net "M_I_CPU1_SB_DQS_DP<6>")
	)
	(segment
		(start 170.946826 -296.66057)
		(end 172.862494 -296.66057)
		(width 0.16002)
		(layer "In2.Cu")
		(net "M_I_CPU1_SB_DQS_DP<6>")
	)
	(segment
		(start 131.156202 -281.86126)
		(end 131.164584 -281.856434)
		(width 0.09525)
		(layer "In2.Cu")
		(net "M_I_CPU1_SB_DQS_DP<6>")
	)
	(segment
		(start 166.912798 -295.503092)
		(end 167.325802 -295.503092)
		(width 0.16002)
		(layer "In2.Cu")
		(net "M_I_CPU1_SB_DQS_DP<6>")
	)
	(segment
		(start 159.145732 -292.283642)
		(end 159.874204 -292.283642)
		(width 0.16002)
		(layer "In2.Cu")
		(net "M_I_CPU1_SB_DQS_DP<6>")
	)
	(segment
		(start 161.247836 -293.657274)
		(end 161.482278 -293.891716)
		(width 0.16002)
		(layer "In2.Cu")
		(net "M_I_CPU1_SB_DQS_DP<6>")
	)
	(segment
		(start 179.24272 -295.662096)
		(end 179.516024 -295.9354)
		(width 0.16002)
		(layer "In2.Cu")
		(net "M_I_CPU1_SB_DQS_DP<6>")
	)
	(segment
		(start 158.500572 -290.91001)
		(end 158.735014 -291.144452)
		(width 0.16002)
		(layer "In2.Cu")
		(net "M_I_CPU1_SB_DQS_DP<6>")
	)
	(segment
		(start 175.177196 -295.810432)
		(end 177.250852 -295.810432)
		(width 0.16002)
		(layer "In2.Cu")
		(net "M_I_CPU1_SB_DQS_DP<6>")
	)
	(segment
		(start 145.444718 -281.809698)
		(end 145.691352 -281.809698)
		(width 0.09525)
		(layer "In2.Cu")
		(net "M_I_CPU1_SB_DQS_DP<6>")
	)
	(segment
		(start 160.108646 -293.246556)
		(end 160.519364 -293.657274)
		(width 0.16002)
		(layer "In2.Cu")
		(net "M_I_CPU1_SB_DQS_DP<6>")
	)
	(segment
		(start 156.398468 -289.536378)
		(end 157.12694 -289.536378)
		(width 0.16002)
		(layer "In2.Cu")
		(net "M_I_CPU1_SB_DQS_DP<6>")
	)
	(segment
		(start 135.856218 -281.86126)
		(end 135.8646 -281.856434)
		(width 0.09525)
		(layer "In2.Cu")
		(net "M_I_CPU1_SB_DQS_DP<6>")
	)
	(segment
		(start 157.361382 -290.499292)
		(end 157.7721 -290.91001)
		(width 0.16002)
		(layer "In2.Cu")
		(net "M_I_CPU1_SB_DQS_DP<6>")
	)
	(segment
		(start 165.683438 -296.295572)
		(end 166.120318 -296.295572)
		(width 0.16002)
		(layer "In2.Cu")
		(net "M_I_CPU1_SB_DQS_DP<6>")
	)
	(segment
		(start 177.996088 -295.778936)
		(end 178.476148 -295.778936)
		(width 0.16002)
		(layer "In2.Cu")
		(net "M_I_CPU1_SB_DQS_DP<6>")
	)
	(segment
		(start 177.399188 -295.662096)
		(end 177.879248 -295.662096)
		(width 0.16002)
		(layer "In2.Cu")
		(net "M_I_CPU1_SB_DQS_DP<6>")
	)
	(segment
		(start 161.482278 -293.891716)
		(end 161.482278 -294.620188)
		(width 0.16002)
		(layer "In2.Cu")
		(net "M_I_CPU1_SB_DQS_DP<6>")
	)
	(segment
		(start 144.68983 -281.86126)
		(end 144.715992 -281.8765)
		(width 0.09525)
		(layer "In2.Cu")
		(net "M_I_CPU1_SB_DQS_DP<6>")
	)
	(segment
		(start 159.874204 -292.283642)
		(end 160.108646 -292.518084)
		(width 0.16002)
		(layer "In2.Cu")
		(net "M_I_CPU1_SB_DQS_DP<6>")
	)
	(segment
		(start 147.919186 -282.120594)
		(end 148.982684 -282.120594)
		(width 0.16002)
		(layer "In2.Cu")
		(net "M_I_CPU1_SB_DQS_DP<6>")
	)
	(segment
		(start 174.869856 -295.503092)
		(end 175.177196 -295.810432)
		(width 0.16002)
		(layer "In2.Cu")
		(net "M_I_CPU1_SB_DQS_DP<6>")
	)
	(segment
		(start 172.862494 -296.66057)
		(end 173.227492 -296.295572)
		(width 0.16002)
		(layer "In2.Cu")
		(net "M_I_CPU1_SB_DQS_DP<6>")
	)
	(segment
		(start 144.288256 -281.8765)
		(end 144.314164 -281.861514)
		(width 0.09525)
		(layer "In2.Cu")
		(net "M_I_CPU1_SB_DQS_DP<6>")
	)
	(segment
		(start 147.836636 -282.061666)
		(end 147.895564 -282.120594)
		(width 0.09525)
		(layer "In2.Cu")
		(net "M_I_CPU1_SB_DQS_DP<6>")
	)
	(segment
		(start 143.376142 -281.86126)
		(end 143.384524 -281.856434)
		(width 0.09525)
		(layer "In2.Cu")
		(net "M_I_CPU1_SB_DQS_DP<6>")
	)
	(segment
		(start 160.519364 -293.657274)
		(end 161.247836 -293.657274)
		(width 0.16002)
		(layer "In2.Cu")
		(net "M_I_CPU1_SB_DQS_DP<6>")
	)
	(arc
		(start 136.796272 -281.86126)
		(mid 136.98474 -281.810583)
		(end 137.173208 -281.86126)
		(width 0.09525)
		(layer "In2.Cu")
		(net "M_I_CPU1_SB_DQS_DP<6>")
	)
	(arc
		(start 144.715992 -281.8765)
		(mid 144.987348 -281.937649)
		(end 145.254726 -281.861006)
		(width 0.09525)
		(layer "In2.Cu")
		(net "M_I_CPU1_SB_DQS_DP<6>")
	)
	(arc
		(start 138.676126 -281.86126)
		(mid 138.859901 -281.810488)
		(end 139.044934 -281.856434)
		(width 0.09525)
		(layer "In2.Cu")
		(net "M_I_CPU1_SB_DQS_DP<6>")
	)
	(arc
		(start 128.393952 -281.834336)
		(mid 128.556603 -281.812076)
		(end 128.71323 -281.86126)
		(width 0.09525)
		(layer "In2.Cu")
		(net "M_I_CPU1_SB_DQS_DP<6>")
	)
	(arc
		(start 140.564616 -281.856434)
		(mid 140.749648 -281.81052)
		(end 140.933424 -281.86126)
		(width 0.09525)
		(layer "In2.Cu")
		(net "M_I_CPU1_SB_DQS_DP<6>")
	)
	(arc
		(start 131.164584 -281.856434)
		(mid 131.349616 -281.81052)
		(end 131.533392 -281.86126)
		(width 0.09525)
		(layer "In2.Cu")
		(net "M_I_CPU1_SB_DQS_DP<6>")
	)
	(arc
		(start 139.99337 -281.86126)
		(mid 140.274802 -281.937015)
		(end 140.556234 -281.86126)
		(width 0.09525)
		(layer "In2.Cu")
		(net "M_I_CPU1_SB_DQS_DP<6>")
	)
	(arc
		(start 136.233408 -281.86126)
		(mid 136.51484 -281.937015)
		(end 136.796272 -281.86126)
		(width 0.09525)
		(layer "In2.Cu")
		(net "M_I_CPU1_SB_DQS_DP<6>")
	)
	(arc
		(start 145.254726 -281.861006)
		(mid 145.346314 -281.822738)
		(end 145.444718 -281.809698)
		(width 0.09525)
		(layer "In2.Cu")
		(net "M_I_CPU1_SB_DQS_DP<6>")
	)
	(arc
		(start 141.873224 -281.86126)
		(mid 142.154656 -281.937015)
		(end 142.436088 -281.86126)
		(width 0.09525)
		(layer "In2.Cu")
		(net "M_I_CPU1_SB_DQS_DP<6>")
	)
	(arc
		(start 132.473446 -281.86126)
		(mid 132.754878 -281.937015)
		(end 133.03631 -281.86126)
		(width 0.09525)
		(layer "In2.Cu")
		(net "M_I_CPU1_SB_DQS_DP<6>")
	)
	(arc
		(start 139.053316 -281.86126)
		(mid 139.334748 -281.937015)
		(end 139.61618 -281.86126)
		(width 0.09525)
		(layer "In2.Cu")
		(net "M_I_CPU1_SB_DQS_DP<6>")
	)
	(arc
		(start 142.436088 -281.86126)
		(mid 142.619863 -281.810488)
		(end 142.804896 -281.856434)
		(width 0.09525)
		(layer "In2.Cu")
		(net "M_I_CPU1_SB_DQS_DP<6>")
	)
	(arc
		(start 133.97611 -281.86126)
		(mid 134.159885 -281.810488)
		(end 134.344918 -281.856434)
		(width 0.09525)
		(layer "In2.Cu")
		(net "M_I_CPU1_SB_DQS_DP<6>")
	)
	(arc
		(start 134.3533 -281.86126)
		(mid 134.634732 -281.937015)
		(end 134.916164 -281.86126)
		(width 0.09525)
		(layer "In2.Cu")
		(net "M_I_CPU1_SB_DQS_DP<6>")
	)
	(arc
		(start 128.71323 -281.86126)
		(mid 128.994662 -281.937015)
		(end 129.276094 -281.86126)
		(width 0.09525)
		(layer "In2.Cu")
		(net "M_I_CPU1_SB_DQS_DP<6>")
	)
	(arc
		(start 138.113262 -281.86126)
		(mid 138.394694 -281.937015)
		(end 138.676126 -281.86126)
		(width 0.09525)
		(layer "In2.Cu")
		(net "M_I_CPU1_SB_DQS_DP<6>")
	)
	(arc
		(start 137.173208 -281.86126)
		(mid 137.45464 -281.937015)
		(end 137.736072 -281.86126)
		(width 0.09525)
		(layer "In2.Cu")
		(net "M_I_CPU1_SB_DQS_DP<6>")
	)
	(arc
		(start 135.8646 -281.856434)
		(mid 136.049632 -281.81052)
		(end 136.233408 -281.86126)
		(width 0.09525)
		(layer "In2.Cu")
		(net "M_I_CPU1_SB_DQS_DP<6>")
	)
	(arc
		(start 129.276094 -281.86126)
		(mid 129.459869 -281.810488)
		(end 129.644902 -281.856434)
		(width 0.09525)
		(layer "In2.Cu")
		(net "M_I_CPU1_SB_DQS_DP<6>")
	)
	(arc
		(start 133.03631 -281.86126)
		(mid 133.224778 -281.810583)
		(end 133.413246 -281.86126)
		(width 0.09525)
		(layer "In2.Cu")
		(net "M_I_CPU1_SB_DQS_DP<6>")
	)
	(arc
		(start 144.336008 -281.849068)
		(mid 144.51446 -281.810826)
		(end 144.68983 -281.86126)
		(width 0.09525)
		(layer "In2.Cu")
		(net "M_I_CPU1_SB_DQS_DP<6>")
	)
	(arc
		(start 141.496288 -281.86126)
		(mid 141.684756 -281.810583)
		(end 141.873224 -281.86126)
		(width 0.09525)
		(layer "In2.Cu")
		(net "M_I_CPU1_SB_DQS_DP<6>")
	)
	(arc
		(start 132.104638 -281.856434)
		(mid 132.28967 -281.81052)
		(end 132.473446 -281.86126)
		(width 0.09525)
		(layer "In2.Cu")
		(net "M_I_CPU1_SB_DQS_DP<6>")
	)
	(arc
		(start 142.813278 -281.86126)
		(mid 143.09471 -281.937015)
		(end 143.376142 -281.86126)
		(width 0.09525)
		(layer "In2.Cu")
		(net "M_I_CPU1_SB_DQS_DP<6>")
	)
	(arc
		(start 143.753332 -281.86126)
		(mid 144.018852 -281.936789)
		(end 144.288256 -281.8765)
		(width 0.09525)
		(layer "In2.Cu")
		(net "M_I_CPU1_SB_DQS_DP<6>")
	)
	(arc
		(start 130.593338 -281.86126)
		(mid 130.87477 -281.937015)
		(end 131.156202 -281.86126)
		(width 0.09525)
		(layer "In2.Cu")
		(net "M_I_CPU1_SB_DQS_DP<6>")
	)
	(arc
		(start 137.736072 -281.86126)
		(mid 137.919847 -281.810488)
		(end 138.10488 -281.856434)
		(width 0.09525)
		(layer "In2.Cu")
		(net "M_I_CPU1_SB_DQS_DP<6>")
	)
	(arc
		(start 140.933424 -281.86126)
		(mid 141.214856 -281.937015)
		(end 141.496288 -281.86126)
		(width 0.09525)
		(layer "In2.Cu")
		(net "M_I_CPU1_SB_DQS_DP<6>")
	)
	(arc
		(start 134.924546 -281.856434)
		(mid 135.109578 -281.81052)
		(end 135.293354 -281.86126)
		(width 0.09525)
		(layer "In2.Cu")
		(net "M_I_CPU1_SB_DQS_DP<6>")
	)
	(arc
		(start 129.653284 -281.86126)
		(mid 129.934716 -281.937015)
		(end 130.216148 -281.86126)
		(width 0.09525)
		(layer "In2.Cu")
		(net "M_I_CPU1_SB_DQS_DP<6>")
	)
	(arc
		(start 143.384524 -281.856434)
		(mid 143.569556 -281.81052)
		(end 143.753332 -281.86126)
		(width 0.09525)
		(layer "In2.Cu")
		(net "M_I_CPU1_SB_DQS_DP<6>")
	)
	(arc
		(start 139.624562 -281.856434)
		(mid 139.809594 -281.81052)
		(end 139.99337 -281.86126)
		(width 0.09525)
		(layer "In2.Cu")
		(net "M_I_CPU1_SB_DQS_DP<6>")
	)
	(arc
		(start 131.533392 -281.86126)
		(mid 131.814824 -281.937015)
		(end 132.096256 -281.86126)
		(width 0.09525)
		(layer "In2.Cu")
		(net "M_I_CPU1_SB_DQS_DP<6>")
	)
	(arc
		(start 133.413246 -281.86126)
		(mid 133.694678 -281.937015)
		(end 133.97611 -281.86126)
		(width 0.09525)
		(layer "In2.Cu")
		(net "M_I_CPU1_SB_DQS_DP<6>")
	)
	(arc
		(start 130.216148 -281.86126)
		(mid 130.399923 -281.810488)
		(end 130.584956 -281.856434)
		(width 0.09525)
		(layer "In2.Cu")
		(net "M_I_CPU1_SB_DQS_DP<6>")
	)
	(arc
		(start 135.293354 -281.86126)
		(mid 135.574786 -281.937015)
		(end 135.856218 -281.86126)
		(width 0.09525)
		(layer "In2.Cu")
		(net "M_I_CPU1_SB_DQS_DP<6>")
	)
	(segment
		(start 128.05791 -277.060406)
		(end 128.524762 -277.326344)
		(width 0.12954)
		(layer "F.Cu")
		(net "M_I_CPU1_SB_DQS_DP<5>")
	)
	(segment
		(start 128.370838 -277.060914)
		(end 128.393952 -276.9743)
		(width 0.09525)
		(layer "In2.Cu")
		(net "M_I_CPU1_SB_DQS_DP<5>")
	)
	(segment
		(start 140.556234 -277.001224)
		(end 140.564616 -276.996398)
		(width 0.09525)
		(layer "In2.Cu")
		(net "M_I_CPU1_SB_DQS_DP<5>")
	)
	(segment
		(start 139.61618 -277.001224)
		(end 139.624562 -276.996398)
		(width 0.09525)
		(layer "In2.Cu")
		(net "M_I_CPU1_SB_DQS_DP<5>")
	)
	(segment
		(start 145.2626 -277.00097)
		(end 145.291556 -276.972014)
		(width 0.09525)
		(layer "In2.Cu")
		(net "M_I_CPU1_SB_DQS_DP<5>")
	)
	(segment
		(start 154.065478 -278.48433)
		(end 154.555698 -278.48433)
		(width 0.16002)
		(layer "In2.Cu")
		(net "M_I_CPU1_SB_DQS_DP<5>")
	)
	(segment
		(start 129.644902 -276.996398)
		(end 129.653284 -277.001224)
		(width 0.09525)
		(layer "In2.Cu")
		(net "M_I_CPU1_SB_DQS_DP<5>")
	)
	(segment
		(start 128.524762 -277.326344)
		(end 128.370838 -277.060914)
		(width 0.09525)
		(layer "In2.Cu")
		(net "M_I_CPU1_SB_DQS_DP<5>")
	)
	(segment
		(start 147.836636 -276.059392)
		(end 147.895564 -276.11832)
		(width 0.09525)
		(layer "In2.Cu")
		(net "M_I_CPU1_SB_DQS_DP<5>")
	)
	(segment
		(start 145.254726 -277.00097)
		(end 145.2626 -277.00097)
		(width 0.09525)
		(layer "In2.Cu")
		(net "M_I_CPU1_SB_DQS_DP<5>")
	)
	(segment
		(start 173.664372 -286.945578)
		(end 174.55007 -286.05988)
		(width 0.16002)
		(layer "In2.Cu")
		(net "M_I_CPU1_SB_DQS_DP<5>")
	)
	(segment
		(start 162.356292 -285.637224)
		(end 162.356292 -286.245808)
		(width 0.16002)
		(layer "In2.Cu")
		(net "M_I_CPU1_SB_DQS_DP<5>")
	)
	(segment
		(start 130.584956 -276.996398)
		(end 130.593338 -277.001224)
		(width 0.09525)
		(layer "In2.Cu")
		(net "M_I_CPU1_SB_DQS_DP<5>")
	)
	(segment
		(start 161.424366 -285.313882)
		(end 162.03295 -285.313882)
		(width 0.16002)
		(layer "In2.Cu")
		(net "M_I_CPU1_SB_DQS_DP<5>")
	)
	(segment
		(start 135.856218 -277.001224)
		(end 135.8646 -276.996398)
		(width 0.09525)
		(layer "In2.Cu")
		(net "M_I_CPU1_SB_DQS_DP<5>")
	)
	(segment
		(start 177.250852 -286.460438)
		(end 177.399188 -286.312102)
		(width 0.16002)
		(layer "In2.Cu")
		(net "M_I_CPU1_SB_DQS_DP<5>")
	)
	(segment
		(start 152.08631 -276.505162)
		(end 152.691846 -277.110698)
		(width 0.16002)
		(layer "In2.Cu")
		(net "M_I_CPU1_SB_DQS_DP<5>")
	)
	(segment
		(start 155.43911 -279.857962)
		(end 155.92933 -279.857962)
		(width 0.16002)
		(layer "In2.Cu")
		(net "M_I_CPU1_SB_DQS_DP<5>")
	)
	(segment
		(start 167.006016 -286.05988)
		(end 167.232584 -286.05988)
		(width 0.16002)
		(layer "In2.Cu")
		(net "M_I_CPU1_SB_DQS_DP<5>")
	)
	(segment
		(start 145.917412 -276.804374)
		(end 146.960082 -275.761704)
		(width 0.09525)
		(layer "In2.Cu")
		(net "M_I_CPU1_SB_DQS_DP<5>")
	)
	(segment
		(start 163.420806 -287.310322)
		(end 165.318694 -287.310322)
		(width 0.16002)
		(layer "In2.Cu")
		(net "M_I_CPU1_SB_DQS_DP<5>")
	)
	(segment
		(start 154.927808 -278.85644)
		(end 154.927808 -279.34666)
		(width 0.16002)
		(layer "In2.Cu")
		(net "M_I_CPU1_SB_DQS_DP<5>")
	)
	(segment
		(start 178.476148 -286.428942)
		(end 178.592988 -286.312102)
		(width 0.16002)
		(layer "In2.Cu")
		(net "M_I_CPU1_SB_DQS_DP<5>")
	)
	(segment
		(start 131.156202 -277.001224)
		(end 131.164584 -276.996398)
		(width 0.09525)
		(layer "In2.Cu")
		(net "M_I_CPU1_SB_DQS_DP<5>")
	)
	(segment
		(start 178.592988 -286.312102)
		(end 179.24272 -286.312102)
		(width 0.16002)
		(layer "In2.Cu")
		(net "M_I_CPU1_SB_DQS_DP<5>")
	)
	(segment
		(start 138.10488 -276.996398)
		(end 138.113262 -277.001224)
		(width 0.09525)
		(layer "In2.Cu")
		(net "M_I_CPU1_SB_DQS_DP<5>")
	)
	(segment
		(start 132.096256 -277.001224)
		(end 132.104638 -276.996398)
		(width 0.09525)
		(layer "In2.Cu")
		(net "M_I_CPU1_SB_DQS_DP<5>")
	)
	(segment
		(start 134.344918 -276.996398)
		(end 134.3533 -277.001224)
		(width 0.09525)
		(layer "In2.Cu")
		(net "M_I_CPU1_SB_DQS_DP<5>")
	)
	(segment
		(start 170.096688 -286.460438)
		(end 170.946826 -287.310576)
		(width 0.16002)
		(layer "In2.Cu")
		(net "M_I_CPU1_SB_DQS_DP<5>")
	)
	(segment
		(start 160.970722 -284.860238)
		(end 161.424366 -285.313882)
		(width 0.16002)
		(layer "In2.Cu")
		(net "M_I_CPU1_SB_DQS_DP<5>")
	)
	(segment
		(start 175.177196 -286.460438)
		(end 177.250852 -286.460438)
		(width 0.16002)
		(layer "In2.Cu")
		(net "M_I_CPU1_SB_DQS_DP<5>")
	)
	(segment
		(start 152.691846 -277.110698)
		(end 153.182066 -277.110698)
		(width 0.16002)
		(layer "In2.Cu")
		(net "M_I_CPU1_SB_DQS_DP<5>")
	)
	(segment
		(start 170.946826 -287.310576)
		(end 172.862494 -287.310576)
		(width 0.16002)
		(layer "In2.Cu")
		(net "M_I_CPU1_SB_DQS_DP<5>")
	)
	(segment
		(start 144.288256 -277.016464)
		(end 144.314164 -277.001478)
		(width 0.09525)
		(layer "In2.Cu")
		(net "M_I_CPU1_SB_DQS_DP<5>")
	)
	(segment
		(start 144.314164 -277.001478)
		(end 144.336008 -276.989032)
		(width 0.09525)
		(layer "In2.Cu")
		(net "M_I_CPU1_SB_DQS_DP<5>")
	)
	(segment
		(start 157.23616 -281.125676)
		(end 160.062672 -283.952188)
		(width 0.16002)
		(layer "In2.Cu")
		(net "M_I_CPU1_SB_DQS_DP<5>")
	)
	(segment
		(start 134.916164 -277.001224)
		(end 134.924546 -276.996398)
		(width 0.09525)
		(layer "In2.Cu")
		(net "M_I_CPU1_SB_DQS_DP<5>")
	)
	(segment
		(start 152.08631 -276.278594)
		(end 152.08631 -276.505162)
		(width 0.16002)
		(layer "In2.Cu")
		(net "M_I_CPU1_SB_DQS_DP<5>")
	)
	(segment
		(start 160.062672 -283.952188)
		(end 160.671256 -283.952188)
		(width 0.16002)
		(layer "In2.Cu")
		(net "M_I_CPU1_SB_DQS_DP<5>")
	)
	(segment
		(start 151.926036 -276.11832)
		(end 152.08631 -276.278594)
		(width 0.16002)
		(layer "In2.Cu")
		(net "M_I_CPU1_SB_DQS_DP<5>")
	)
	(segment
		(start 173.227492 -286.945578)
		(end 173.664372 -286.945578)
		(width 0.16002)
		(layer "In2.Cu")
		(net "M_I_CPU1_SB_DQS_DP<5>")
	)
	(segment
		(start 144.68983 -277.001224)
		(end 144.715992 -277.016464)
		(width 0.09525)
		(layer "In2.Cu")
		(net "M_I_CPU1_SB_DQS_DP<5>")
	)
	(segment
		(start 167.232584 -286.05988)
		(end 167.633142 -286.460438)
		(width 0.16002)
		(layer "In2.Cu")
		(net "M_I_CPU1_SB_DQS_DP<5>")
	)
	(segment
		(start 160.671256 -283.952188)
		(end 160.970722 -284.251654)
		(width 0.16002)
		(layer "In2.Cu")
		(net "M_I_CPU1_SB_DQS_DP<5>")
	)
	(segment
		(start 156.30144 -280.230072)
		(end 156.30144 -280.720292)
		(width 0.16002)
		(layer "In2.Cu")
		(net "M_I_CPU1_SB_DQS_DP<5>")
	)
	(segment
		(start 172.862494 -287.310576)
		(end 173.227492 -286.945578)
		(width 0.16002)
		(layer "In2.Cu")
		(net "M_I_CPU1_SB_DQS_DP<5>")
	)
	(segment
		(start 177.879248 -286.312102)
		(end 177.996088 -286.428942)
		(width 0.16002)
		(layer "In2.Cu")
		(net "M_I_CPU1_SB_DQS_DP<5>")
	)
	(segment
		(start 153.554176 -277.482808)
		(end 153.554176 -277.973028)
		(width 0.16002)
		(layer "In2.Cu")
		(net "M_I_CPU1_SB_DQS_DP<5>")
	)
	(segment
		(start 162.03295 -285.313882)
		(end 162.356292 -285.637224)
		(width 0.16002)
		(layer "In2.Cu")
		(net "M_I_CPU1_SB_DQS_DP<5>")
	)
	(segment
		(start 165.318694 -287.310322)
		(end 165.683438 -286.945578)
		(width 0.16002)
		(layer "In2.Cu")
		(net "M_I_CPU1_SB_DQS_DP<5>")
	)
	(segment
		(start 154.555698 -278.48433)
		(end 154.927808 -278.85644)
		(width 0.16002)
		(layer "In2.Cu")
		(net "M_I_CPU1_SB_DQS_DP<5>")
	)
	(segment
		(start 165.683438 -286.945578)
		(end 166.120318 -286.945578)
		(width 0.16002)
		(layer "In2.Cu")
		(net "M_I_CPU1_SB_DQS_DP<5>")
	)
	(segment
		(start 147.919186 -276.11832)
		(end 151.926036 -276.11832)
		(width 0.16002)
		(layer "In2.Cu")
		(net "M_I_CPU1_SB_DQS_DP<5>")
	)
	(segment
		(start 146.960082 -275.761704)
		(end 147.11934 -275.761704)
		(width 0.09525)
		(layer "In2.Cu")
		(net "M_I_CPU1_SB_DQS_DP<5>")
	)
	(segment
		(start 156.706824 -281.125676)
		(end 157.23616 -281.125676)
		(width 0.16002)
		(layer "In2.Cu")
		(net "M_I_CPU1_SB_DQS_DP<5>")
	)
	(segment
		(start 167.633142 -286.460438)
		(end 170.096688 -286.460438)
		(width 0.16002)
		(layer "In2.Cu")
		(net "M_I_CPU1_SB_DQS_DP<5>")
	)
	(segment
		(start 139.044934 -276.996398)
		(end 139.053316 -277.001224)
		(width 0.09525)
		(layer "In2.Cu")
		(net "M_I_CPU1_SB_DQS_DP<5>")
	)
	(segment
		(start 147.417028 -276.059392)
		(end 147.836636 -276.059392)
		(width 0.09525)
		(layer "In2.Cu")
		(net "M_I_CPU1_SB_DQS_DP<5>")
	)
	(segment
		(start 179.24272 -286.312102)
		(end 179.516024 -286.585406)
		(width 0.16002)
		(layer "In2.Cu")
		(net "M_I_CPU1_SB_DQS_DP<5>")
	)
	(segment
		(start 156.30144 -280.720292)
		(end 156.706824 -281.125676)
		(width 0.16002)
		(layer "In2.Cu")
		(net "M_I_CPU1_SB_DQS_DP<5>")
	)
	(segment
		(start 160.970722 -284.251654)
		(end 160.970722 -284.860238)
		(width 0.16002)
		(layer "In2.Cu")
		(net "M_I_CPU1_SB_DQS_DP<5>")
	)
	(segment
		(start 155.92933 -279.857962)
		(end 156.30144 -280.230072)
		(width 0.16002)
		(layer "In2.Cu")
		(net "M_I_CPU1_SB_DQS_DP<5>")
	)
	(segment
		(start 166.120318 -286.945578)
		(end 167.006016 -286.05988)
		(width 0.16002)
		(layer "In2.Cu")
		(net "M_I_CPU1_SB_DQS_DP<5>")
	)
	(segment
		(start 147.11934 -275.761704)
		(end 147.417028 -276.059392)
		(width 0.09525)
		(layer "In2.Cu")
		(net "M_I_CPU1_SB_DQS_DP<5>")
	)
	(segment
		(start 162.356292 -286.245808)
		(end 163.420806 -287.310322)
		(width 0.16002)
		(layer "In2.Cu")
		(net "M_I_CPU1_SB_DQS_DP<5>")
	)
	(segment
		(start 147.895564 -276.11832)
		(end 147.919186 -276.11832)
		(width 0.09525)
		(layer "In2.Cu")
		(net "M_I_CPU1_SB_DQS_DP<5>")
	)
	(segment
		(start 142.804896 -276.996398)
		(end 142.813278 -277.001224)
		(width 0.09525)
		(layer "In2.Cu")
		(net "M_I_CPU1_SB_DQS_DP<5>")
	)
	(segment
		(start 154.927808 -279.34666)
		(end 155.43911 -279.857962)
		(width 0.16002)
		(layer "In2.Cu")
		(net "M_I_CPU1_SB_DQS_DP<5>")
	)
	(segment
		(start 177.399188 -286.312102)
		(end 177.879248 -286.312102)
		(width 0.16002)
		(layer "In2.Cu")
		(net "M_I_CPU1_SB_DQS_DP<5>")
	)
	(segment
		(start 153.554176 -277.973028)
		(end 154.065478 -278.48433)
		(width 0.16002)
		(layer "In2.Cu")
		(net "M_I_CPU1_SB_DQS_DP<5>")
	)
	(segment
		(start 177.996088 -286.428942)
		(end 178.476148 -286.428942)
		(width 0.16002)
		(layer "In2.Cu")
		(net "M_I_CPU1_SB_DQS_DP<5>")
	)
	(segment
		(start 174.776638 -286.05988)
		(end 175.177196 -286.460438)
		(width 0.16002)
		(layer "In2.Cu")
		(net "M_I_CPU1_SB_DQS_DP<5>")
	)
	(segment
		(start 143.376142 -277.001224)
		(end 143.384524 -276.996398)
		(width 0.09525)
		(layer "In2.Cu")
		(net "M_I_CPU1_SB_DQS_DP<5>")
	)
	(segment
		(start 153.182066 -277.110698)
		(end 153.554176 -277.482808)
		(width 0.16002)
		(layer "In2.Cu")
		(net "M_I_CPU1_SB_DQS_DP<5>")
	)
	(segment
		(start 174.55007 -286.05988)
		(end 174.776638 -286.05988)
		(width 0.16002)
		(layer "In2.Cu")
		(net "M_I_CPU1_SB_DQS_DP<5>")
	)
	(segment
		(start 145.696178 -276.804374)
		(end 145.917412 -276.804374)
		(width 0.09525)
		(layer "In2.Cu")
		(net "M_I_CPU1_SB_DQS_DP<5>")
	)
	(arc
		(start 128.71323 -277.001224)
		(mid 128.994662 -277.076979)
		(end 129.276094 -277.001224)
		(width 0.09525)
		(layer "In2.Cu")
		(net "M_I_CPU1_SB_DQS_DP<5>")
	)
	(arc
		(start 141.873224 -277.001224)
		(mid 142.154656 -277.076979)
		(end 142.436088 -277.001224)
		(width 0.09525)
		(layer "In2.Cu")
		(net "M_I_CPU1_SB_DQS_DP<5>")
	)
	(arc
		(start 132.473446 -277.001224)
		(mid 132.754878 -277.076979)
		(end 133.03631 -277.001224)
		(width 0.09525)
		(layer "In2.Cu")
		(net "M_I_CPU1_SB_DQS_DP<5>")
	)
	(arc
		(start 133.413246 -277.001224)
		(mid 133.694678 -277.076979)
		(end 133.97611 -277.001224)
		(width 0.09525)
		(layer "In2.Cu")
		(net "M_I_CPU1_SB_DQS_DP<5>")
	)
	(arc
		(start 129.276094 -277.001224)
		(mid 129.459869 -276.950452)
		(end 129.644902 -276.996398)
		(width 0.09525)
		(layer "In2.Cu")
		(net "M_I_CPU1_SB_DQS_DP<5>")
	)
	(arc
		(start 140.564616 -276.996398)
		(mid 140.749648 -276.950484)
		(end 140.933424 -277.001224)
		(width 0.09525)
		(layer "In2.Cu")
		(net "M_I_CPU1_SB_DQS_DP<5>")
	)
	(arc
		(start 135.8646 -276.996398)
		(mid 136.049632 -276.950484)
		(end 136.233408 -277.001224)
		(width 0.09525)
		(layer "In2.Cu")
		(net "M_I_CPU1_SB_DQS_DP<5>")
	)
	(arc
		(start 140.933424 -277.001224)
		(mid 141.214856 -277.076979)
		(end 141.496288 -277.001224)
		(width 0.09525)
		(layer "In2.Cu")
		(net "M_I_CPU1_SB_DQS_DP<5>")
	)
	(arc
		(start 138.676126 -277.001224)
		(mid 138.859901 -276.950452)
		(end 139.044934 -276.996398)
		(width 0.09525)
		(layer "In2.Cu")
		(net "M_I_CPU1_SB_DQS_DP<5>")
	)
	(arc
		(start 142.436088 -277.001224)
		(mid 142.619863 -276.950452)
		(end 142.804896 -276.996398)
		(width 0.09525)
		(layer "In2.Cu")
		(net "M_I_CPU1_SB_DQS_DP<5>")
	)
	(arc
		(start 131.533392 -277.001224)
		(mid 131.814824 -277.076979)
		(end 132.096256 -277.001224)
		(width 0.09525)
		(layer "In2.Cu")
		(net "M_I_CPU1_SB_DQS_DP<5>")
	)
	(arc
		(start 143.753332 -277.001224)
		(mid 144.018852 -277.076753)
		(end 144.288256 -277.016464)
		(width 0.09525)
		(layer "In2.Cu")
		(net "M_I_CPU1_SB_DQS_DP<5>")
	)
	(arc
		(start 133.03631 -277.001224)
		(mid 133.224778 -276.950547)
		(end 133.413246 -277.001224)
		(width 0.09525)
		(layer "In2.Cu")
		(net "M_I_CPU1_SB_DQS_DP<5>")
	)
	(arc
		(start 145.291556 -276.972014)
		(mid 145.477184 -276.847918)
		(end 145.696178 -276.804374)
		(width 0.09525)
		(layer "In2.Cu")
		(net "M_I_CPU1_SB_DQS_DP<5>")
	)
	(arc
		(start 130.593338 -277.001224)
		(mid 130.87477 -277.076979)
		(end 131.156202 -277.001224)
		(width 0.09525)
		(layer "In2.Cu")
		(net "M_I_CPU1_SB_DQS_DP<5>")
	)
	(arc
		(start 139.99337 -277.001224)
		(mid 140.274802 -277.076979)
		(end 140.556234 -277.001224)
		(width 0.09525)
		(layer "In2.Cu")
		(net "M_I_CPU1_SB_DQS_DP<5>")
	)
	(arc
		(start 130.216148 -277.001224)
		(mid 130.399923 -276.950452)
		(end 130.584956 -276.996398)
		(width 0.09525)
		(layer "In2.Cu")
		(net "M_I_CPU1_SB_DQS_DP<5>")
	)
	(arc
		(start 135.293354 -277.001224)
		(mid 135.574786 -277.076979)
		(end 135.856218 -277.001224)
		(width 0.09525)
		(layer "In2.Cu")
		(net "M_I_CPU1_SB_DQS_DP<5>")
	)
	(arc
		(start 132.104638 -276.996398)
		(mid 132.28967 -276.950484)
		(end 132.473446 -277.001224)
		(width 0.09525)
		(layer "In2.Cu")
		(net "M_I_CPU1_SB_DQS_DP<5>")
	)
	(arc
		(start 138.113262 -277.001224)
		(mid 138.394694 -277.076979)
		(end 138.676126 -277.001224)
		(width 0.09525)
		(layer "In2.Cu")
		(net "M_I_CPU1_SB_DQS_DP<5>")
	)
	(arc
		(start 144.715992 -277.016464)
		(mid 144.987348 -277.077613)
		(end 145.254726 -277.00097)
		(width 0.09525)
		(layer "In2.Cu")
		(net "M_I_CPU1_SB_DQS_DP<5>")
	)
	(arc
		(start 136.233408 -277.001224)
		(mid 136.51484 -277.076979)
		(end 136.796272 -277.001224)
		(width 0.09525)
		(layer "In2.Cu")
		(net "M_I_CPU1_SB_DQS_DP<5>")
	)
	(arc
		(start 144.336008 -276.989032)
		(mid 144.51446 -276.95079)
		(end 144.68983 -277.001224)
		(width 0.09525)
		(layer "In2.Cu")
		(net "M_I_CPU1_SB_DQS_DP<5>")
	)
	(arc
		(start 129.653284 -277.001224)
		(mid 129.934716 -277.076979)
		(end 130.216148 -277.001224)
		(width 0.09525)
		(layer "In2.Cu")
		(net "M_I_CPU1_SB_DQS_DP<5>")
	)
	(arc
		(start 134.3533 -277.001224)
		(mid 134.634732 -277.076979)
		(end 134.916164 -277.001224)
		(width 0.09525)
		(layer "In2.Cu")
		(net "M_I_CPU1_SB_DQS_DP<5>")
	)
	(arc
		(start 137.173208 -277.001224)
		(mid 137.45464 -277.076979)
		(end 137.736072 -277.001224)
		(width 0.09525)
		(layer "In2.Cu")
		(net "M_I_CPU1_SB_DQS_DP<5>")
	)
	(arc
		(start 131.164584 -276.996398)
		(mid 131.349616 -276.950484)
		(end 131.533392 -277.001224)
		(width 0.09525)
		(layer "In2.Cu")
		(net "M_I_CPU1_SB_DQS_DP<5>")
	)
	(arc
		(start 142.813278 -277.001224)
		(mid 143.09471 -277.076979)
		(end 143.376142 -277.001224)
		(width 0.09525)
		(layer "In2.Cu")
		(net "M_I_CPU1_SB_DQS_DP<5>")
	)
	(arc
		(start 139.624562 -276.996398)
		(mid 139.809594 -276.950484)
		(end 139.99337 -277.001224)
		(width 0.09525)
		(layer "In2.Cu")
		(net "M_I_CPU1_SB_DQS_DP<5>")
	)
	(arc
		(start 139.053316 -277.001224)
		(mid 139.334748 -277.076979)
		(end 139.61618 -277.001224)
		(width 0.09525)
		(layer "In2.Cu")
		(net "M_I_CPU1_SB_DQS_DP<5>")
	)
	(arc
		(start 128.393952 -276.9743)
		(mid 128.556603 -276.95204)
		(end 128.71323 -277.001224)
		(width 0.09525)
		(layer "In2.Cu")
		(net "M_I_CPU1_SB_DQS_DP<5>")
	)
	(arc
		(start 134.924546 -276.996398)
		(mid 135.109578 -276.950484)
		(end 135.293354 -277.001224)
		(width 0.09525)
		(layer "In2.Cu")
		(net "M_I_CPU1_SB_DQS_DP<5>")
	)
	(arc
		(start 136.796272 -277.001224)
		(mid 136.98474 -276.950547)
		(end 137.173208 -277.001224)
		(width 0.09525)
		(layer "In2.Cu")
		(net "M_I_CPU1_SB_DQS_DP<5>")
	)
	(arc
		(start 141.496288 -277.001224)
		(mid 141.684756 -276.950547)
		(end 141.873224 -277.001224)
		(width 0.09525)
		(layer "In2.Cu")
		(net "M_I_CPU1_SB_DQS_DP<5>")
	)
	(arc
		(start 133.97611 -277.001224)
		(mid 134.159885 -276.950452)
		(end 134.344918 -276.996398)
		(width 0.09525)
		(layer "In2.Cu")
		(net "M_I_CPU1_SB_DQS_DP<5>")
	)
	(arc
		(start 137.736072 -277.001224)
		(mid 137.919847 -276.950452)
		(end 138.10488 -276.996398)
		(width 0.09525)
		(layer "In2.Cu")
		(net "M_I_CPU1_SB_DQS_DP<5>")
	)
	(arc
		(start 143.384524 -276.996398)
		(mid 143.569556 -276.950484)
		(end 143.753332 -277.001224)
		(width 0.09525)
		(layer "In2.Cu")
		(net "M_I_CPU1_SB_DQS_DP<5>")
	)
	(segment
		(start 128.05791 -272.20037)
		(end 128.524762 -272.466308)
		(width 0.12954)
		(layer "F.Cu")
		(net "M_I_CPU1_SB_DQS_DP<4>")
	)
	(segment
		(start 167.325802 -276.803104)
		(end 167.633142 -277.110444)
		(width 0.16002)
		(layer "In2.Cu")
		(net "M_I_CPU1_SB_DQS_DP<4>")
	)
	(segment
		(start 142.804896 -272.136362)
		(end 142.813278 -272.141188)
		(width 0.09525)
		(layer "In2.Cu")
		(net "M_I_CPU1_SB_DQS_DP<4>")
	)
	(segment
		(start 143.376142 -272.141188)
		(end 143.384524 -272.136362)
		(width 0.09525)
		(layer "In2.Cu")
		(net "M_I_CPU1_SB_DQS_DP<4>")
	)
	(segment
		(start 163.32581 -277.960328)
		(end 165.318694 -277.960328)
		(width 0.16002)
		(layer "In2.Cu")
		(net "M_I_CPU1_SB_DQS_DP<4>")
	)
	(segment
		(start 138.10488 -272.136362)
		(end 138.113262 -272.141188)
		(width 0.09525)
		(layer "In2.Cu")
		(net "M_I_CPU1_SB_DQS_DP<4>")
	)
	(segment
		(start 147.693126 -270.446754)
		(end 156.089096 -270.446754)
		(width 0.16002)
		(layer "In2.Cu")
		(net "M_I_CPU1_SB_DQS_DP<4>")
	)
	(segment
		(start 170.946826 -277.960582)
		(end 172.862494 -277.960582)
		(width 0.16002)
		(layer "In2.Cu")
		(net "M_I_CPU1_SB_DQS_DP<4>")
	)
	(segment
		(start 159.154622 -274.289012)
		(end 159.541972 -274.676362)
		(width 0.16002)
		(layer "In2.Cu")
		(net "M_I_CPU1_SB_DQS_DP<4>")
	)
	(segment
		(start 146.422618 -271.177004)
		(end 146.422618 -270.944848)
		(width 0.09525)
		(layer "In2.Cu")
		(net "M_I_CPU1_SB_DQS_DP<4>")
	)
	(segment
		(start 158.945072 -273.30273)
		(end 159.154622 -273.51228)
		(width 0.16002)
		(layer "In2.Cu")
		(net "M_I_CPU1_SB_DQS_DP<4>")
	)
	(segment
		(start 165.318694 -277.960328)
		(end 165.683438 -277.595584)
		(width 0.16002)
		(layer "In2.Cu")
		(net "M_I_CPU1_SB_DQS_DP<4>")
	)
	(segment
		(start 156.407358 -270.765016)
		(end 156.407358 -271.541748)
		(width 0.16002)
		(layer "In2.Cu")
		(net "M_I_CPU1_SB_DQS_DP<4>")
	)
	(segment
		(start 140.556234 -272.141188)
		(end 140.564616 -272.136362)
		(width 0.09525)
		(layer "In2.Cu")
		(net "M_I_CPU1_SB_DQS_DP<4>")
	)
	(segment
		(start 144.288256 -272.156428)
		(end 144.314164 -272.141442)
		(width 0.09525)
		(layer "In2.Cu")
		(net "M_I_CPU1_SB_DQS_DP<4>")
	)
	(segment
		(start 157.57144 -271.929098)
		(end 157.78099 -272.138648)
		(width 0.16002)
		(layer "In2.Cu")
		(net "M_I_CPU1_SB_DQS_DP<4>")
	)
	(segment
		(start 167.633142 -277.110444)
		(end 170.096688 -277.110444)
		(width 0.16002)
		(layer "In2.Cu")
		(net "M_I_CPU1_SB_DQS_DP<4>")
	)
	(segment
		(start 145.73885 -272.009362)
		(end 146.317716 -271.430496)
		(width 0.09525)
		(layer "In2.Cu")
		(net "M_I_CPU1_SB_DQS_DP<4>")
	)
	(segment
		(start 147.669504 -270.446754)
		(end 147.693126 -270.446754)
		(width 0.09525)
		(layer "In2.Cu")
		(net "M_I_CPU1_SB_DQS_DP<4>")
	)
	(segment
		(start 139.044934 -272.136362)
		(end 139.053316 -272.141188)
		(width 0.09525)
		(layer "In2.Cu")
		(net "M_I_CPU1_SB_DQS_DP<4>")
	)
	(segment
		(start 158.16834 -273.30273)
		(end 158.945072 -273.30273)
		(width 0.16002)
		(layer "In2.Cu")
		(net "M_I_CPU1_SB_DQS_DP<4>")
	)
	(segment
		(start 178.592988 -276.962108)
		(end 179.24272 -276.962108)
		(width 0.16002)
		(layer "In2.Cu")
		(net "M_I_CPU1_SB_DQS_DP<4>")
	)
	(segment
		(start 173.227492 -277.595584)
		(end 173.664372 -277.595584)
		(width 0.16002)
		(layer "In2.Cu")
		(net "M_I_CPU1_SB_DQS_DP<4>")
	)
	(segment
		(start 162.289236 -277.423626)
		(end 162.789108 -277.423626)
		(width 0.16002)
		(layer "In2.Cu")
		(net "M_I_CPU1_SB_DQS_DP<4>")
	)
	(segment
		(start 160.528254 -275.662644)
		(end 160.915604 -276.049994)
		(width 0.16002)
		(layer "In2.Cu")
		(net "M_I_CPU1_SB_DQS_DP<4>")
	)
	(segment
		(start 146.97964 -270.387826)
		(end 147.610576 -270.387826)
		(width 0.09525)
		(layer "In2.Cu")
		(net "M_I_CPU1_SB_DQS_DP<4>")
	)
	(segment
		(start 128.370838 -272.200878)
		(end 128.393952 -272.114264)
		(width 0.09525)
		(layer "In2.Cu")
		(net "M_I_CPU1_SB_DQS_DP<4>")
	)
	(segment
		(start 134.916164 -272.141188)
		(end 134.924546 -272.136362)
		(width 0.09525)
		(layer "In2.Cu")
		(net "M_I_CPU1_SB_DQS_DP<4>")
	)
	(segment
		(start 156.794708 -271.929098)
		(end 157.57144 -271.929098)
		(width 0.16002)
		(layer "In2.Cu")
		(net "M_I_CPU1_SB_DQS_DP<4>")
	)
	(segment
		(start 160.318704 -274.676362)
		(end 160.528254 -274.885912)
		(width 0.16002)
		(layer "In2.Cu")
		(net "M_I_CPU1_SB_DQS_DP<4>")
	)
	(segment
		(start 160.915604 -276.049994)
		(end 161.692336 -276.049994)
		(width 0.16002)
		(layer "In2.Cu")
		(net "M_I_CPU1_SB_DQS_DP<4>")
	)
	(segment
		(start 146.317716 -271.430496)
		(end 146.422618 -271.177004)
		(width 0.09525)
		(layer "In2.Cu")
		(net "M_I_CPU1_SB_DQS_DP<4>")
	)
	(segment
		(start 146.422618 -270.944848)
		(end 146.97964 -270.387826)
		(width 0.09525)
		(layer "In2.Cu")
		(net "M_I_CPU1_SB_DQS_DP<4>")
	)
	(segment
		(start 129.644902 -272.136362)
		(end 129.653284 -272.141188)
		(width 0.09525)
		(layer "In2.Cu")
		(net "M_I_CPU1_SB_DQS_DP<4>")
	)
	(segment
		(start 172.862494 -277.960582)
		(end 173.227492 -277.595584)
		(width 0.16002)
		(layer "In2.Cu")
		(net "M_I_CPU1_SB_DQS_DP<4>")
	)
	(segment
		(start 159.154622 -273.51228)
		(end 159.154622 -274.289012)
		(width 0.16002)
		(layer "In2.Cu")
		(net "M_I_CPU1_SB_DQS_DP<4>")
	)
	(segment
		(start 160.528254 -274.885912)
		(end 160.528254 -275.662644)
		(width 0.16002)
		(layer "In2.Cu")
		(net "M_I_CPU1_SB_DQS_DP<4>")
	)
	(segment
		(start 128.524762 -272.466308)
		(end 128.370838 -272.200878)
		(width 0.09525)
		(layer "In2.Cu")
		(net "M_I_CPU1_SB_DQS_DP<4>")
	)
	(segment
		(start 170.096688 -277.110444)
		(end 170.946826 -277.960582)
		(width 0.16002)
		(layer "In2.Cu")
		(net "M_I_CPU1_SB_DQS_DP<4>")
	)
	(segment
		(start 147.610576 -270.387826)
		(end 147.669504 -270.446754)
		(width 0.09525)
		(layer "In2.Cu")
		(net "M_I_CPU1_SB_DQS_DP<4>")
	)
	(segment
		(start 178.476148 -277.078948)
		(end 178.592988 -276.962108)
		(width 0.16002)
		(layer "In2.Cu")
		(net "M_I_CPU1_SB_DQS_DP<4>")
	)
	(segment
		(start 166.912798 -276.803104)
		(end 167.325802 -276.803104)
		(width 0.16002)
		(layer "In2.Cu")
		(net "M_I_CPU1_SB_DQS_DP<4>")
	)
	(segment
		(start 132.096256 -272.141188)
		(end 132.104638 -272.136362)
		(width 0.09525)
		(layer "In2.Cu")
		(net "M_I_CPU1_SB_DQS_DP<4>")
	)
	(segment
		(start 161.901886 -276.259544)
		(end 161.901886 -277.036276)
		(width 0.16002)
		(layer "In2.Cu")
		(net "M_I_CPU1_SB_DQS_DP<4>")
	)
	(segment
		(start 174.456852 -276.803104)
		(end 174.869856 -276.803104)
		(width 0.16002)
		(layer "In2.Cu")
		(net "M_I_CPU1_SB_DQS_DP<4>")
	)
	(segment
		(start 157.78099 -272.138648)
		(end 157.78099 -272.91538)
		(width 0.16002)
		(layer "In2.Cu")
		(net "M_I_CPU1_SB_DQS_DP<4>")
	)
	(segment
		(start 161.901886 -277.036276)
		(end 162.289236 -277.423626)
		(width 0.16002)
		(layer "In2.Cu")
		(net "M_I_CPU1_SB_DQS_DP<4>")
	)
	(segment
		(start 157.78099 -272.91538)
		(end 158.16834 -273.30273)
		(width 0.16002)
		(layer "In2.Cu")
		(net "M_I_CPU1_SB_DQS_DP<4>")
	)
	(segment
		(start 145.545302 -272.089626)
		(end 145.73885 -272.009362)
		(width 0.09525)
		(layer "In2.Cu")
		(net "M_I_CPU1_SB_DQS_DP<4>")
	)
	(segment
		(start 135.856218 -272.141188)
		(end 135.8646 -272.136362)
		(width 0.09525)
		(layer "In2.Cu")
		(net "M_I_CPU1_SB_DQS_DP<4>")
	)
	(segment
		(start 177.250852 -277.110444)
		(end 177.399188 -276.962108)
		(width 0.16002)
		(layer "In2.Cu")
		(net "M_I_CPU1_SB_DQS_DP<4>")
	)
	(segment
		(start 166.120318 -277.595584)
		(end 166.912798 -276.803104)
		(width 0.16002)
		(layer "In2.Cu")
		(net "M_I_CPU1_SB_DQS_DP<4>")
	)
	(segment
		(start 177.879248 -276.962108)
		(end 177.996088 -277.078948)
		(width 0.16002)
		(layer "In2.Cu")
		(net "M_I_CPU1_SB_DQS_DP<4>")
	)
	(segment
		(start 145.44675 -272.089626)
		(end 145.545302 -272.089626)
		(width 0.09525)
		(layer "In2.Cu")
		(net "M_I_CPU1_SB_DQS_DP<4>")
	)
	(segment
		(start 144.314164 -272.141442)
		(end 144.336008 -272.128996)
		(width 0.09525)
		(layer "In2.Cu")
		(net "M_I_CPU1_SB_DQS_DP<4>")
	)
	(segment
		(start 179.24272 -276.962108)
		(end 179.516024 -277.235412)
		(width 0.16002)
		(layer "In2.Cu")
		(net "M_I_CPU1_SB_DQS_DP<4>")
	)
	(segment
		(start 134.344918 -272.136362)
		(end 134.3533 -272.141188)
		(width 0.09525)
		(layer "In2.Cu")
		(net "M_I_CPU1_SB_DQS_DP<4>")
	)
	(segment
		(start 130.584956 -272.136362)
		(end 130.593338 -272.141188)
		(width 0.09525)
		(layer "In2.Cu")
		(net "M_I_CPU1_SB_DQS_DP<4>")
	)
	(segment
		(start 144.68983 -272.141188)
		(end 144.715992 -272.156428)
		(width 0.09525)
		(layer "In2.Cu")
		(net "M_I_CPU1_SB_DQS_DP<4>")
	)
	(segment
		(start 165.683438 -277.595584)
		(end 166.120318 -277.595584)
		(width 0.16002)
		(layer "In2.Cu")
		(net "M_I_CPU1_SB_DQS_DP<4>")
	)
	(segment
		(start 131.156202 -272.141188)
		(end 131.164584 -272.136362)
		(width 0.09525)
		(layer "In2.Cu")
		(net "M_I_CPU1_SB_DQS_DP<4>")
	)
	(segment
		(start 162.789108 -277.423626)
		(end 163.32581 -277.960328)
		(width 0.16002)
		(layer "In2.Cu")
		(net "M_I_CPU1_SB_DQS_DP<4>")
	)
	(segment
		(start 177.996088 -277.078948)
		(end 178.476148 -277.078948)
		(width 0.16002)
		(layer "In2.Cu")
		(net "M_I_CPU1_SB_DQS_DP<4>")
	)
	(segment
		(start 177.399188 -276.962108)
		(end 177.879248 -276.962108)
		(width 0.16002)
		(layer "In2.Cu")
		(net "M_I_CPU1_SB_DQS_DP<4>")
	)
	(segment
		(start 139.61618 -272.141188)
		(end 139.624562 -272.136362)
		(width 0.09525)
		(layer "In2.Cu")
		(net "M_I_CPU1_SB_DQS_DP<4>")
	)
	(segment
		(start 156.089096 -270.446754)
		(end 156.407358 -270.765016)
		(width 0.16002)
		(layer "In2.Cu")
		(net "M_I_CPU1_SB_DQS_DP<4>")
	)
	(segment
		(start 156.407358 -271.541748)
		(end 156.794708 -271.929098)
		(width 0.16002)
		(layer "In2.Cu")
		(net "M_I_CPU1_SB_DQS_DP<4>")
	)
	(segment
		(start 159.541972 -274.676362)
		(end 160.318704 -274.676362)
		(width 0.16002)
		(layer "In2.Cu")
		(net "M_I_CPU1_SB_DQS_DP<4>")
	)
	(segment
		(start 173.664372 -277.595584)
		(end 174.456852 -276.803104)
		(width 0.16002)
		(layer "In2.Cu")
		(net "M_I_CPU1_SB_DQS_DP<4>")
	)
	(segment
		(start 174.869856 -276.803104)
		(end 175.177196 -277.110444)
		(width 0.16002)
		(layer "In2.Cu")
		(net "M_I_CPU1_SB_DQS_DP<4>")
	)
	(segment
		(start 161.692336 -276.049994)
		(end 161.901886 -276.259544)
		(width 0.16002)
		(layer "In2.Cu")
		(net "M_I_CPU1_SB_DQS_DP<4>")
	)
	(segment
		(start 175.177196 -277.110444)
		(end 177.250852 -277.110444)
		(width 0.16002)
		(layer "In2.Cu")
		(net "M_I_CPU1_SB_DQS_DP<4>")
	)
	(arc
		(start 129.276094 -272.141188)
		(mid 129.459869 -272.090416)
		(end 129.644902 -272.136362)
		(width 0.09525)
		(layer "In2.Cu")
		(net "M_I_CPU1_SB_DQS_DP<4>")
	)
	(arc
		(start 135.293354 -272.141188)
		(mid 135.574786 -272.216943)
		(end 135.856218 -272.141188)
		(width 0.09525)
		(layer "In2.Cu")
		(net "M_I_CPU1_SB_DQS_DP<4>")
	)
	(arc
		(start 136.796272 -272.141188)
		(mid 136.98474 -272.090511)
		(end 137.173208 -272.141188)
		(width 0.09525)
		(layer "In2.Cu")
		(net "M_I_CPU1_SB_DQS_DP<4>")
	)
	(arc
		(start 139.053316 -272.141188)
		(mid 139.334748 -272.216943)
		(end 139.61618 -272.141188)
		(width 0.09525)
		(layer "In2.Cu")
		(net "M_I_CPU1_SB_DQS_DP<4>")
	)
	(arc
		(start 132.473446 -272.141188)
		(mid 132.754878 -272.216943)
		(end 133.03631 -272.141188)
		(width 0.09525)
		(layer "In2.Cu")
		(net "M_I_CPU1_SB_DQS_DP<4>")
	)
	(arc
		(start 140.564616 -272.136362)
		(mid 140.749648 -272.090448)
		(end 140.933424 -272.141188)
		(width 0.09525)
		(layer "In2.Cu")
		(net "M_I_CPU1_SB_DQS_DP<4>")
	)
	(arc
		(start 133.413246 -272.141188)
		(mid 133.694678 -272.216943)
		(end 133.97611 -272.141188)
		(width 0.09525)
		(layer "In2.Cu")
		(net "M_I_CPU1_SB_DQS_DP<4>")
	)
	(arc
		(start 144.336008 -272.128996)
		(mid 144.51446 -272.090754)
		(end 144.68983 -272.141188)
		(width 0.09525)
		(layer "In2.Cu")
		(net "M_I_CPU1_SB_DQS_DP<4>")
	)
	(arc
		(start 138.676126 -272.141188)
		(mid 138.859901 -272.090416)
		(end 139.044934 -272.136362)
		(width 0.09525)
		(layer "In2.Cu")
		(net "M_I_CPU1_SB_DQS_DP<4>")
	)
	(arc
		(start 130.593338 -272.141188)
		(mid 130.87477 -272.216943)
		(end 131.156202 -272.141188)
		(width 0.09525)
		(layer "In2.Cu")
		(net "M_I_CPU1_SB_DQS_DP<4>")
	)
	(arc
		(start 140.933424 -272.141188)
		(mid 141.214856 -272.216943)
		(end 141.496288 -272.141188)
		(width 0.09525)
		(layer "In2.Cu")
		(net "M_I_CPU1_SB_DQS_DP<4>")
	)
	(arc
		(start 137.736072 -272.141188)
		(mid 137.919847 -272.090416)
		(end 138.10488 -272.136362)
		(width 0.09525)
		(layer "In2.Cu")
		(net "M_I_CPU1_SB_DQS_DP<4>")
	)
	(arc
		(start 138.113262 -272.141188)
		(mid 138.394694 -272.216943)
		(end 138.676126 -272.141188)
		(width 0.09525)
		(layer "In2.Cu")
		(net "M_I_CPU1_SB_DQS_DP<4>")
	)
	(arc
		(start 133.03631 -272.141188)
		(mid 133.224778 -272.090511)
		(end 133.413246 -272.141188)
		(width 0.09525)
		(layer "In2.Cu")
		(net "M_I_CPU1_SB_DQS_DP<4>")
	)
	(arc
		(start 139.624562 -272.136362)
		(mid 139.809594 -272.090448)
		(end 139.99337 -272.141188)
		(width 0.09525)
		(layer "In2.Cu")
		(net "M_I_CPU1_SB_DQS_DP<4>")
	)
	(arc
		(start 142.436088 -272.141188)
		(mid 142.619863 -272.090416)
		(end 142.804896 -272.136362)
		(width 0.09525)
		(layer "In2.Cu")
		(net "M_I_CPU1_SB_DQS_DP<4>")
	)
	(arc
		(start 143.384524 -272.136362)
		(mid 143.569556 -272.090448)
		(end 143.753332 -272.141188)
		(width 0.09525)
		(layer "In2.Cu")
		(net "M_I_CPU1_SB_DQS_DP<4>")
	)
	(arc
		(start 139.99337 -272.141188)
		(mid 140.274802 -272.216943)
		(end 140.556234 -272.141188)
		(width 0.09525)
		(layer "In2.Cu")
		(net "M_I_CPU1_SB_DQS_DP<4>")
	)
	(arc
		(start 136.233408 -272.141188)
		(mid 136.51484 -272.216943)
		(end 136.796272 -272.141188)
		(width 0.09525)
		(layer "In2.Cu")
		(net "M_I_CPU1_SB_DQS_DP<4>")
	)
	(arc
		(start 131.533392 -272.141188)
		(mid 131.814824 -272.216943)
		(end 132.096256 -272.141188)
		(width 0.09525)
		(layer "In2.Cu")
		(net "M_I_CPU1_SB_DQS_DP<4>")
	)
	(arc
		(start 144.715992 -272.156428)
		(mid 144.987348 -272.217577)
		(end 145.254726 -272.140934)
		(width 0.09525)
		(layer "In2.Cu")
		(net "M_I_CPU1_SB_DQS_DP<4>")
	)
	(arc
		(start 137.173208 -272.141188)
		(mid 137.45464 -272.216943)
		(end 137.736072 -272.141188)
		(width 0.09525)
		(layer "In2.Cu")
		(net "M_I_CPU1_SB_DQS_DP<4>")
	)
	(arc
		(start 128.393952 -272.114264)
		(mid 128.556603 -272.092004)
		(end 128.71323 -272.141188)
		(width 0.09525)
		(layer "In2.Cu")
		(net "M_I_CPU1_SB_DQS_DP<4>")
	)
	(arc
		(start 134.3533 -272.141188)
		(mid 134.634732 -272.216943)
		(end 134.916164 -272.141188)
		(width 0.09525)
		(layer "In2.Cu")
		(net "M_I_CPU1_SB_DQS_DP<4>")
	)
	(arc
		(start 131.164584 -272.136362)
		(mid 131.349616 -272.090448)
		(end 131.533392 -272.141188)
		(width 0.09525)
		(layer "In2.Cu")
		(net "M_I_CPU1_SB_DQS_DP<4>")
	)
	(arc
		(start 134.924546 -272.136362)
		(mid 135.109578 -272.090448)
		(end 135.293354 -272.141188)
		(width 0.09525)
		(layer "In2.Cu")
		(net "M_I_CPU1_SB_DQS_DP<4>")
	)
	(arc
		(start 142.813278 -272.141188)
		(mid 143.09471 -272.216943)
		(end 143.376142 -272.141188)
		(width 0.09525)
		(layer "In2.Cu")
		(net "M_I_CPU1_SB_DQS_DP<4>")
	)
	(arc
		(start 141.873224 -272.141188)
		(mid 142.154656 -272.216943)
		(end 142.436088 -272.141188)
		(width 0.09525)
		(layer "In2.Cu")
		(net "M_I_CPU1_SB_DQS_DP<4>")
	)
	(arc
		(start 141.496288 -272.141188)
		(mid 141.684756 -272.090511)
		(end 141.873224 -272.141188)
		(width 0.09525)
		(layer "In2.Cu")
		(net "M_I_CPU1_SB_DQS_DP<4>")
	)
	(arc
		(start 132.104638 -272.136362)
		(mid 132.28967 -272.090448)
		(end 132.473446 -272.141188)
		(width 0.09525)
		(layer "In2.Cu")
		(net "M_I_CPU1_SB_DQS_DP<4>")
	)
	(arc
		(start 130.216148 -272.141188)
		(mid 130.399923 -272.090416)
		(end 130.584956 -272.136362)
		(width 0.09525)
		(layer "In2.Cu")
		(net "M_I_CPU1_SB_DQS_DP<4>")
	)
	(arc
		(start 128.71323 -272.141188)
		(mid 128.994662 -272.216943)
		(end 129.276094 -272.141188)
		(width 0.09525)
		(layer "In2.Cu")
		(net "M_I_CPU1_SB_DQS_DP<4>")
	)
	(arc
		(start 129.653284 -272.141188)
		(mid 129.934716 -272.216943)
		(end 130.216148 -272.141188)
		(width 0.09525)
		(layer "In2.Cu")
		(net "M_I_CPU1_SB_DQS_DP<4>")
	)
	(arc
		(start 135.8646 -272.136362)
		(mid 136.049632 -272.090448)
		(end 136.233408 -272.141188)
		(width 0.09525)
		(layer "In2.Cu")
		(net "M_I_CPU1_SB_DQS_DP<4>")
	)
	(arc
		(start 145.254726 -272.140934)
		(mid 145.347295 -272.102403)
		(end 145.44675 -272.089626)
		(width 0.09525)
		(layer "In2.Cu")
		(net "M_I_CPU1_SB_DQS_DP<4>")
	)
	(arc
		(start 143.753332 -272.141188)
		(mid 144.018852 -272.216717)
		(end 144.288256 -272.156428)
		(width 0.09525)
		(layer "In2.Cu")
		(net "M_I_CPU1_SB_DQS_DP<4>")
	)
	(arc
		(start 133.97611 -272.141188)
		(mid 134.159885 -272.090416)
		(end 134.344918 -272.136362)
		(width 0.09525)
		(layer "In2.Cu")
		(net "M_I_CPU1_SB_DQS_DP<4>")
	)
	(segment
		(start 128.997964 -290.020248)
		(end 129.464816 -290.286186)
		(width 0.12954)
		(layer "F.Cu")
		(net "M_I_CPU1_SB_DQS_DP<3>")
	)
	(segment
		(start 182.50408 -313.0931)
		(end 182.62092 -313.20994)
		(width 0.16002)
		(layer "In2.Cu")
		(net "M_I_CPU1_SB_DQS_DP<3>")
	)
	(segment
		(start 182.62092 -313.20994)
		(end 183.341518 -313.20994)
		(width 0.16002)
		(layer "In2.Cu")
		(net "M_I_CPU1_SB_DQS_DP<3>")
	)
	(segment
		(start 145.2245 -293.833042)
		(end 145.255996 -293.85133)
		(width 0.09525)
		(layer "In2.Cu")
		(net "M_I_CPU1_SB_DQS_DP<3>")
	)
	(segment
		(start 166.822882 -312.52668)
		(end 167.348154 -312.52668)
		(width 0.16002)
		(layer "In2.Cu")
		(net "M_I_CPU1_SB_DQS_DP<3>")
	)
	(segment
		(start 146.006566 -295.356788)
		(end 146.624294 -295.974516)
		(width 0.09525)
		(layer "In2.Cu")
		(net "M_I_CPU1_SB_DQS_DP<3>")
	)
	(segment
		(start 144.282414 -292.21176)
		(end 144.316196 -292.231318)
		(width 0.09525)
		(layer "In2.Cu")
		(net "M_I_CPU1_SB_DQS_DP<3>")
	)
	(segment
		(start 129.464816 -290.286186)
		(end 129.61874 -290.551616)
		(width 0.09525)
		(layer "In2.Cu")
		(net "M_I_CPU1_SB_DQS_DP<3>")
	)
	(segment
		(start 131.156202 -290.611306)
		(end 131.164584 -290.616132)
		(width 0.09525)
		(layer "In2.Cu")
		(net "M_I_CPU1_SB_DQS_DP<3>")
	)
	(segment
		(start 177.485548 -312.210196)
		(end 178.059588 -312.784236)
		(width 0.16002)
		(layer "In2.Cu")
		(net "M_I_CPU1_SB_DQS_DP<3>")
	)
	(segment
		(start 130.584956 -290.616132)
		(end 130.593338 -290.611306)
		(width 0.09525)
		(layer "In2.Cu")
		(net "M_I_CPU1_SB_DQS_DP<3>")
	)
	(segment
		(start 170.743626 -313.06008)
		(end 172.876972 -313.06008)
		(width 0.16002)
		(layer "In2.Cu")
		(net "M_I_CPU1_SB_DQS_DP<3>")
	)
	(segment
		(start 180.144928 -312.784236)
		(end 180.753512 -313.39282)
		(width 0.16002)
		(layer "In2.Cu")
		(net "M_I_CPU1_SB_DQS_DP<3>")
	)
	(segment
		(start 132.096256 -290.611306)
		(end 132.104638 -290.616132)
		(width 0.09525)
		(layer "In2.Cu")
		(net "M_I_CPU1_SB_DQS_DP<3>")
	)
	(segment
		(start 172.876972 -313.06008)
		(end 173.184312 -313.36742)
		(width 0.16002)
		(layer "In2.Cu")
		(net "M_I_CPU1_SB_DQS_DP<3>")
	)
	(segment
		(start 174.892208 -312.52668)
		(end 175.208692 -312.210196)
		(width 0.16002)
		(layer "In2.Cu")
		(net "M_I_CPU1_SB_DQS_DP<3>")
	)
	(segment
		(start 139.61618 -290.611306)
		(end 139.624562 -290.616132)
		(width 0.09525)
		(layer "In2.Cu")
		(net "M_I_CPU1_SB_DQS_DP<3>")
	)
	(segment
		(start 167.664638 -312.210196)
		(end 169.893742 -312.210196)
		(width 0.16002)
		(layer "In2.Cu")
		(net "M_I_CPU1_SB_DQS_DP<3>")
	)
	(segment
		(start 143.846042 -291.421312)
		(end 143.881094 -291.441886)
		(width 0.09525)
		(layer "In2.Cu")
		(net "M_I_CPU1_SB_DQS_DP<3>")
	)
	(segment
		(start 147.333462 -298.092368)
		(end 154.694636 -305.453542)
		(width 0.16002)
		(layer "In2.Cu")
		(net "M_I_CPU1_SB_DQS_DP<3>")
	)
	(segment
		(start 134.344918 -290.616132)
		(end 134.3533 -290.611306)
		(width 0.09525)
		(layer "In2.Cu")
		(net "M_I_CPU1_SB_DQS_DP<3>")
	)
	(segment
		(start 161.46399 -313.06008)
		(end 165.332918 -313.06008)
		(width 0.16002)
		(layer "In2.Cu")
		(net "M_I_CPU1_SB_DQS_DP<3>")
	)
	(segment
		(start 173.184312 -313.36742)
		(end 173.526196 -313.36742)
		(width 0.16002)
		(layer "In2.Cu")
		(net "M_I_CPU1_SB_DQS_DP<3>")
	)
	(segment
		(start 146.683476 -296.317924)
		(end 146.683476 -296.522902)
		(width 0.16002)
		(layer "In2.Cu")
		(net "M_I_CPU1_SB_DQS_DP<3>")
	)
	(segment
		(start 144.78635 -293.041324)
		(end 144.822926 -293.06266)
		(width 0.09525)
		(layer "In2.Cu")
		(net "M_I_CPU1_SB_DQS_DP<3>")
	)
	(segment
		(start 139.044934 -290.616132)
		(end 139.053316 -290.611306)
		(width 0.09525)
		(layer "In2.Cu")
		(net "M_I_CPU1_SB_DQS_DP<3>")
	)
	(segment
		(start 140.556234 -290.611306)
		(end 140.564616 -290.616132)
		(width 0.09525)
		(layer "In2.Cu")
		(net "M_I_CPU1_SB_DQS_DP<3>")
	)
	(segment
		(start 154.694636 -306.290726)
		(end 161.46399 -313.06008)
		(width 0.16002)
		(layer "In2.Cu")
		(net "M_I_CPU1_SB_DQS_DP<3>")
	)
	(segment
		(start 181.181756 -313.39282)
		(end 181.364636 -313.20994)
		(width 0.16002)
		(layer "In2.Cu")
		(net "M_I_CPU1_SB_DQS_DP<3>")
	)
	(segment
		(start 146.683476 -296.522902)
		(end 147.333462 -298.092368)
		(width 0.16002)
		(layer "In2.Cu")
		(net "M_I_CPU1_SB_DQS_DP<3>")
	)
	(segment
		(start 143.814546 -291.403024)
		(end 143.846042 -291.421312)
		(width 0.09525)
		(layer "In2.Cu")
		(net "M_I_CPU1_SB_DQS_DP<3>")
	)
	(segment
		(start 144.126712 -291.906198)
		(end 144.126966 -291.906198)
		(width 0.09525)
		(layer "In2.Cu")
		(net "M_I_CPU1_SB_DQS_DP<3>")
	)
	(segment
		(start 181.364636 -313.20994)
		(end 181.90718 -313.20994)
		(width 0.16002)
		(layer "In2.Cu")
		(net "M_I_CPU1_SB_DQS_DP<3>")
	)
	(segment
		(start 135.856218 -290.611306)
		(end 135.8646 -290.616132)
		(width 0.09525)
		(layer "In2.Cu")
		(net "M_I_CPU1_SB_DQS_DP<3>")
	)
	(segment
		(start 165.982142 -313.36742)
		(end 166.822882 -312.52668)
		(width 0.16002)
		(layer "In2.Cu")
		(net "M_I_CPU1_SB_DQS_DP<3>")
	)
	(segment
		(start 182.02402 -313.0931)
		(end 182.50408 -313.0931)
		(width 0.16002)
		(layer "In2.Cu")
		(net "M_I_CPU1_SB_DQS_DP<3>")
	)
	(segment
		(start 174.366936 -312.52668)
		(end 174.892208 -312.52668)
		(width 0.16002)
		(layer "In2.Cu")
		(net "M_I_CPU1_SB_DQS_DP<3>")
	)
	(segment
		(start 165.640258 -313.36742)
		(end 165.982142 -313.36742)
		(width 0.16002)
		(layer "In2.Cu")
		(net "M_I_CPU1_SB_DQS_DP<3>")
	)
	(segment
		(start 145.255996 -293.85133)
		(end 145.294096 -293.873428)
		(width 0.09525)
		(layer "In2.Cu")
		(net "M_I_CPU1_SB_DQS_DP<3>")
	)
	(segment
		(start 146.683476 -296.294302)
		(end 146.683476 -296.317924)
		(width 0.09525)
		(layer "In2.Cu")
		(net "M_I_CPU1_SB_DQS_DP<3>")
	)
	(segment
		(start 180.753512 -313.39282)
		(end 181.181756 -313.39282)
		(width 0.16002)
		(layer "In2.Cu")
		(net "M_I_CPU1_SB_DQS_DP<3>")
	)
	(segment
		(start 145.763234 -294.68318)
		(end 145.765266 -294.68445)
		(width 0.09525)
		(layer "In2.Cu")
		(net "M_I_CPU1_SB_DQS_DP<3>")
	)
	(segment
		(start 129.61874 -290.551616)
		(end 129.719578 -290.578286)
		(width 0.09525)
		(layer "In2.Cu")
		(net "M_I_CPU1_SB_DQS_DP<3>")
	)
	(segment
		(start 134.916164 -290.611306)
		(end 134.924546 -290.616132)
		(width 0.09525)
		(layer "In2.Cu")
		(net "M_I_CPU1_SB_DQS_DP<3>")
	)
	(segment
		(start 173.526196 -313.36742)
		(end 174.366936 -312.52668)
		(width 0.16002)
		(layer "In2.Cu")
		(net "M_I_CPU1_SB_DQS_DP<3>")
	)
	(segment
		(start 169.893742 -312.210196)
		(end 170.743626 -313.06008)
		(width 0.16002)
		(layer "In2.Cu")
		(net "M_I_CPU1_SB_DQS_DP<3>")
	)
	(segment
		(start 138.10488 -290.616132)
		(end 138.113262 -290.611306)
		(width 0.09525)
		(layer "In2.Cu")
		(net "M_I_CPU1_SB_DQS_DP<3>")
	)
	(segment
		(start 144.752568 -293.021766)
		(end 144.78635 -293.041324)
		(width 0.09525)
		(layer "In2.Cu")
		(net "M_I_CPU1_SB_DQS_DP<3>")
	)
	(segment
		(start 167.348154 -312.52668)
		(end 167.664638 -312.210196)
		(width 0.16002)
		(layer "In2.Cu")
		(net "M_I_CPU1_SB_DQS_DP<3>")
	)
	(segment
		(start 144.316196 -292.231318)
		(end 144.354296 -292.253416)
		(width 0.09525)
		(layer "In2.Cu")
		(net "M_I_CPU1_SB_DQS_DP<3>")
	)
	(segment
		(start 178.059588 -312.784236)
		(end 180.144928 -312.784236)
		(width 0.16002)
		(layer "In2.Cu")
		(net "M_I_CPU1_SB_DQS_DP<3>")
	)
	(segment
		(start 175.208692 -312.210196)
		(end 177.485548 -312.210196)
		(width 0.16002)
		(layer "In2.Cu")
		(net "M_I_CPU1_SB_DQS_DP<3>")
	)
	(segment
		(start 146.624294 -296.23512)
		(end 146.683476 -296.294302)
		(width 0.09525)
		(layer "In2.Cu")
		(net "M_I_CPU1_SB_DQS_DP<3>")
	)
	(segment
		(start 146.006566 -295.146222)
		(end 146.006566 -295.356788)
		(width 0.09525)
		(layer "In2.Cu")
		(net "M_I_CPU1_SB_DQS_DP<3>")
	)
	(segment
		(start 146.624294 -295.974516)
		(end 146.624294 -296.23512)
		(width 0.09525)
		(layer "In2.Cu")
		(net "M_I_CPU1_SB_DQS_DP<3>")
	)
	(segment
		(start 165.332918 -313.06008)
		(end 165.640258 -313.36742)
		(width 0.16002)
		(layer "In2.Cu")
		(net "M_I_CPU1_SB_DQS_DP<3>")
	)
	(segment
		(start 154.694636 -305.453542)
		(end 154.694636 -306.290726)
		(width 0.16002)
		(layer "In2.Cu")
		(net "M_I_CPU1_SB_DQS_DP<3>")
	)
	(segment
		(start 181.90718 -313.20994)
		(end 182.02402 -313.0931)
		(width 0.16002)
		(layer "In2.Cu")
		(net "M_I_CPU1_SB_DQS_DP<3>")
	)
	(segment
		(start 142.804896 -290.616132)
		(end 142.813278 -290.611306)
		(width 0.09525)
		(layer "In2.Cu")
		(net "M_I_CPU1_SB_DQS_DP<3>")
	)
	(segment
		(start 143.376142 -290.611306)
		(end 143.414242 -290.633404)
		(width 0.09525)
		(layer "In2.Cu")
		(net "M_I_CPU1_SB_DQS_DP<3>")
	)
	(segment
		(start 183.341518 -313.20994)
		(end 183.616092 -312.935366)
		(width 0.16002)
		(layer "In2.Cu")
		(net "M_I_CPU1_SB_DQS_DP<3>")
	)
	(segment
		(start 145.693638 -294.64254)
		(end 145.761202 -294.68191)
		(width 0.09525)
		(layer "In2.Cu")
		(net "M_I_CPU1_SB_DQS_DP<3>")
	)
	(arc
		(start 130.216148 -290.611306)
		(mid 130.399923 -290.662078)
		(end 130.584956 -290.616132)
		(width 0.09525)
		(layer "In2.Cu")
		(net "M_I_CPU1_SB_DQS_DP<3>")
	)
	(arc
		(start 144.822926 -293.06266)
		(mid 145.002298 -293.264255)
		(end 145.06702 -293.52621)
		(width 0.09525)
		(layer "In2.Cu")
		(net "M_I_CPU1_SB_DQS_DP<3>")
	)
	(arc
		(start 141.873224 -290.611306)
		(mid 142.154656 -290.535551)
		(end 142.436088 -290.611306)
		(width 0.09525)
		(layer "In2.Cu")
		(net "M_I_CPU1_SB_DQS_DP<3>")
	)
	(arc
		(start 139.624562 -290.616132)
		(mid 139.809594 -290.662046)
		(end 139.99337 -290.611306)
		(width 0.09525)
		(layer "In2.Cu")
		(net "M_I_CPU1_SB_DQS_DP<3>")
	)
	(arc
		(start 129.719578 -290.578286)
		(mid 129.7297 -290.574251)
		(end 129.739898 -290.570412)
		(width 0.09525)
		(layer "In2.Cu")
		(net "M_I_CPU1_SB_DQS_DP<3>")
	)
	(arc
		(start 132.473446 -290.611306)
		(mid 132.754878 -290.535551)
		(end 133.03631 -290.611306)
		(width 0.09525)
		(layer "In2.Cu")
		(net "M_I_CPU1_SB_DQS_DP<3>")
	)
	(arc
		(start 136.796272 -290.611306)
		(mid 136.98474 -290.661983)
		(end 137.173208 -290.611306)
		(width 0.09525)
		(layer "In2.Cu")
		(net "M_I_CPU1_SB_DQS_DP<3>")
	)
	(arc
		(start 134.924546 -290.616132)
		(mid 135.109578 -290.662046)
		(end 135.293354 -290.611306)
		(width 0.09525)
		(layer "In2.Cu")
		(net "M_I_CPU1_SB_DQS_DP<3>")
	)
	(arc
		(start 134.3533 -290.611306)
		(mid 134.634732 -290.535551)
		(end 134.916164 -290.611306)
		(width 0.09525)
		(layer "In2.Cu")
		(net "M_I_CPU1_SB_DQS_DP<3>")
	)
	(arc
		(start 144.59712 -292.716204)
		(mid 144.638222 -292.88761)
		(end 144.752568 -293.021766)
		(width 0.09525)
		(layer "In2.Cu")
		(net "M_I_CPU1_SB_DQS_DP<3>")
	)
	(arc
		(start 131.164584 -290.616132)
		(mid 131.349616 -290.662046)
		(end 131.533392 -290.611306)
		(width 0.09525)
		(layer "In2.Cu")
		(net "M_I_CPU1_SB_DQS_DP<3>")
	)
	(arc
		(start 135.293354 -290.611306)
		(mid 135.574786 -290.535551)
		(end 135.856218 -290.611306)
		(width 0.09525)
		(layer "In2.Cu")
		(net "M_I_CPU1_SB_DQS_DP<3>")
	)
	(arc
		(start 143.414242 -290.633404)
		(mid 143.592692 -290.834874)
		(end 143.657066 -291.096192)
		(width 0.09525)
		(layer "In2.Cu")
		(net "M_I_CPU1_SB_DQS_DP<3>")
	)
	(arc
		(start 143.657066 -291.096192)
		(mid 143.698731 -291.268639)
		(end 143.814546 -291.403024)
		(width 0.09525)
		(layer "In2.Cu")
		(net "M_I_CPU1_SB_DQS_DP<3>")
	)
	(arc
		(start 133.413246 -290.611306)
		(mid 133.694678 -290.535551)
		(end 133.97611 -290.611306)
		(width 0.09525)
		(layer "In2.Cu")
		(net "M_I_CPU1_SB_DQS_DP<3>")
	)
	(arc
		(start 133.97611 -290.611306)
		(mid 134.159885 -290.662078)
		(end 134.344918 -290.616132)
		(width 0.09525)
		(layer "In2.Cu")
		(net "M_I_CPU1_SB_DQS_DP<3>")
	)
	(arc
		(start 136.233408 -290.611306)
		(mid 136.51484 -290.535551)
		(end 136.796272 -290.611306)
		(width 0.09525)
		(layer "In2.Cu")
		(net "M_I_CPU1_SB_DQS_DP<3>")
	)
	(arc
		(start 145.765266 -294.68445)
		(mid 145.942631 -294.885694)
		(end 146.006566 -295.146222)
		(width 0.09525)
		(layer "In2.Cu")
		(net "M_I_CPU1_SB_DQS_DP<3>")
	)
	(arc
		(start 145.06702 -293.52621)
		(mid 145.108685 -293.698657)
		(end 145.2245 -293.833042)
		(width 0.09525)
		(layer "In2.Cu")
		(net "M_I_CPU1_SB_DQS_DP<3>")
	)
	(arc
		(start 138.113262 -290.611306)
		(mid 138.394694 -290.535551)
		(end 138.676126 -290.611306)
		(width 0.09525)
		(layer "In2.Cu")
		(net "M_I_CPU1_SB_DQS_DP<3>")
	)
	(arc
		(start 139.99337 -290.611306)
		(mid 140.274802 -290.535551)
		(end 140.556234 -290.611306)
		(width 0.09525)
		(layer "In2.Cu")
		(net "M_I_CPU1_SB_DQS_DP<3>")
	)
	(arc
		(start 145.53692 -294.336216)
		(mid 145.578377 -294.508256)
		(end 145.693638 -294.64254)
		(width 0.09525)
		(layer "In2.Cu")
		(net "M_I_CPU1_SB_DQS_DP<3>")
	)
	(arc
		(start 129.739898 -290.570412)
		(mid 129.98261 -290.537529)
		(end 130.216148 -290.611306)
		(width 0.09525)
		(layer "In2.Cu")
		(net "M_I_CPU1_SB_DQS_DP<3>")
	)
	(arc
		(start 137.736072 -290.611306)
		(mid 137.919847 -290.662078)
		(end 138.10488 -290.616132)
		(width 0.09525)
		(layer "In2.Cu")
		(net "M_I_CPU1_SB_DQS_DP<3>")
	)
	(arc
		(start 140.933424 -290.611306)
		(mid 141.214856 -290.535551)
		(end 141.496288 -290.611306)
		(width 0.09525)
		(layer "In2.Cu")
		(net "M_I_CPU1_SB_DQS_DP<3>")
	)
	(arc
		(start 141.496288 -290.611306)
		(mid 141.684756 -290.661983)
		(end 141.873224 -290.611306)
		(width 0.09525)
		(layer "In2.Cu")
		(net "M_I_CPU1_SB_DQS_DP<3>")
	)
	(arc
		(start 145.761202 -294.68191)
		(mid 145.762219 -294.682544)
		(end 145.763234 -294.68318)
		(width 0.09525)
		(layer "In2.Cu")
		(net "M_I_CPU1_SB_DQS_DP<3>")
	)
	(arc
		(start 145.294096 -293.873428)
		(mid 145.472546 -294.074898)
		(end 145.53692 -294.336216)
		(width 0.09525)
		(layer "In2.Cu")
		(net "M_I_CPU1_SB_DQS_DP<3>")
	)
	(arc
		(start 142.813278 -290.611306)
		(mid 143.09471 -290.535551)
		(end 143.376142 -290.611306)
		(width 0.09525)
		(layer "In2.Cu")
		(net "M_I_CPU1_SB_DQS_DP<3>")
	)
	(arc
		(start 138.676126 -290.611306)
		(mid 138.859901 -290.662078)
		(end 139.044934 -290.616132)
		(width 0.09525)
		(layer "In2.Cu")
		(net "M_I_CPU1_SB_DQS_DP<3>")
	)
	(arc
		(start 143.881094 -291.441886)
		(mid 144.061485 -291.643585)
		(end 144.126712 -291.906198)
		(width 0.09525)
		(layer "In2.Cu")
		(net "M_I_CPU1_SB_DQS_DP<3>")
	)
	(arc
		(start 139.053316 -290.611306)
		(mid 139.334748 -290.535551)
		(end 139.61618 -290.611306)
		(width 0.09525)
		(layer "In2.Cu")
		(net "M_I_CPU1_SB_DQS_DP<3>")
	)
	(arc
		(start 144.126966 -291.906198)
		(mid 144.168068 -292.077604)
		(end 144.282414 -292.21176)
		(width 0.09525)
		(layer "In2.Cu")
		(net "M_I_CPU1_SB_DQS_DP<3>")
	)
	(arc
		(start 137.173208 -290.611306)
		(mid 137.45464 -290.535551)
		(end 137.736072 -290.611306)
		(width 0.09525)
		(layer "In2.Cu")
		(net "M_I_CPU1_SB_DQS_DP<3>")
	)
	(arc
		(start 142.436088 -290.611306)
		(mid 142.619863 -290.662078)
		(end 142.804896 -290.616132)
		(width 0.09525)
		(layer "In2.Cu")
		(net "M_I_CPU1_SB_DQS_DP<3>")
	)
	(arc
		(start 131.533392 -290.611306)
		(mid 131.814824 -290.535551)
		(end 132.096256 -290.611306)
		(width 0.09525)
		(layer "In2.Cu")
		(net "M_I_CPU1_SB_DQS_DP<3>")
	)
	(arc
		(start 130.593338 -290.611306)
		(mid 130.87477 -290.535551)
		(end 131.156202 -290.611306)
		(width 0.09525)
		(layer "In2.Cu")
		(net "M_I_CPU1_SB_DQS_DP<3>")
	)
	(arc
		(start 132.104638 -290.616132)
		(mid 132.28967 -290.662046)
		(end 132.473446 -290.611306)
		(width 0.09525)
		(layer "In2.Cu")
		(net "M_I_CPU1_SB_DQS_DP<3>")
	)
	(arc
		(start 135.8646 -290.616132)
		(mid 136.049632 -290.662046)
		(end 136.233408 -290.611306)
		(width 0.09525)
		(layer "In2.Cu")
		(net "M_I_CPU1_SB_DQS_DP<3>")
	)
	(arc
		(start 140.564616 -290.616132)
		(mid 140.749648 -290.662046)
		(end 140.933424 -290.611306)
		(width 0.09525)
		(layer "In2.Cu")
		(net "M_I_CPU1_SB_DQS_DP<3>")
	)
	(arc
		(start 144.354296 -292.253416)
		(mid 144.532746 -292.454886)
		(end 144.59712 -292.716204)
		(width 0.09525)
		(layer "In2.Cu")
		(net "M_I_CPU1_SB_DQS_DP<3>")
	)
	(arc
		(start 133.03631 -290.611306)
		(mid 133.224778 -290.661983)
		(end 133.413246 -290.611306)
		(width 0.09525)
		(layer "In2.Cu")
		(net "M_I_CPU1_SB_DQS_DP<3>")
	)
	(segment
		(start 128.997964 -285.160466)
		(end 129.464816 -285.426404)
		(width 0.12954)
		(layer "F.Cu")
		(net "M_I_CPU1_SB_DQS_DP<2>")
	)
	(segment
		(start 139.61618 -285.751524)
		(end 139.624562 -285.75635)
		(width 0.09525)
		(layer "In2.Cu")
		(net "M_I_CPU1_SB_DQS_DP<2>")
	)
	(segment
		(start 147.596606 -287.26765)
		(end 147.596606 -287.511744)
		(width 0.09525)
		(layer "In2.Cu")
		(net "M_I_CPU1_SB_DQS_DP<2>")
	)
	(segment
		(start 147.902422 -287.73374)
		(end 147.919186 -287.750504)
		(width 0.09525)
		(layer "In2.Cu")
		(net "M_I_CPU1_SB_DQS_DP<2>")
	)
	(segment
		(start 134.344918 -285.75635)
		(end 134.3533 -285.751524)
		(width 0.09525)
		(layer "In2.Cu")
		(net "M_I_CPU1_SB_DQS_DP<2>")
	)
	(segment
		(start 162.165792 -303.452276)
		(end 162.423602 -303.710086)
		(width 0.16002)
		(layer "In2.Cu")
		(net "M_I_CPU1_SB_DQS_DP<2>")
	)
	(segment
		(start 173.526196 -304.017426)
		(end 174.366936 -303.176686)
		(width 0.16002)
		(layer "In2.Cu")
		(net "M_I_CPU1_SB_DQS_DP<2>")
	)
	(segment
		(start 161.165032 -302.451516)
		(end 161.165032 -302.97882)
		(width 0.16002)
		(layer "In2.Cu")
		(net "M_I_CPU1_SB_DQS_DP<2>")
	)
	(segment
		(start 149.469856 -289.301174)
		(end 150.499826 -291.78631)
		(width 0.16002)
		(layer "In2.Cu")
		(net "M_I_CPU1_SB_DQS_DP<2>")
	)
	(segment
		(start 165.332918 -303.710086)
		(end 165.640258 -304.017426)
		(width 0.16002)
		(layer "In2.Cu")
		(net "M_I_CPU1_SB_DQS_DP<2>")
	)
	(segment
		(start 134.916164 -285.751524)
		(end 134.924546 -285.75635)
		(width 0.09525)
		(layer "In2.Cu")
		(net "M_I_CPU1_SB_DQS_DP<2>")
	)
	(segment
		(start 169.893742 -302.860202)
		(end 170.743626 -303.710086)
		(width 0.16002)
		(layer "In2.Cu")
		(net "M_I_CPU1_SB_DQS_DP<2>")
	)
	(segment
		(start 145.444718 -285.802832)
		(end 145.916396 -285.802832)
		(width 0.09525)
		(layer "In2.Cu")
		(net "M_I_CPU1_SB_DQS_DP<2>")
	)
	(segment
		(start 147.191222 -286.862266)
		(end 147.596606 -287.26765)
		(width 0.09525)
		(layer "In2.Cu")
		(net "M_I_CPU1_SB_DQS_DP<2>")
	)
	(segment
		(start 147.919186 -287.750504)
		(end 149.469856 -289.301174)
		(width 0.16002)
		(layer "In2.Cu")
		(net "M_I_CPU1_SB_DQS_DP<2>")
	)
	(segment
		(start 160.794446 -303.349406)
		(end 160.794446 -303.626012)
		(width 0.16002)
		(layer "In2.Cu")
		(net "M_I_CPU1_SB_DQS_DP<2>")
	)
	(segment
		(start 165.982142 -304.017426)
		(end 166.822882 -303.176686)
		(width 0.16002)
		(layer "In2.Cu")
		(net "M_I_CPU1_SB_DQS_DP<2>")
	)
	(segment
		(start 138.10488 -285.75635)
		(end 138.113262 -285.751524)
		(width 0.09525)
		(layer "In2.Cu")
		(net "M_I_CPU1_SB_DQS_DP<2>")
	)
	(segment
		(start 147.596606 -287.511744)
		(end 147.818602 -287.73374)
		(width 0.09525)
		(layer "In2.Cu")
		(net "M_I_CPU1_SB_DQS_DP<2>")
	)
	(segment
		(start 129.464816 -285.426404)
		(end 129.61874 -285.691834)
		(width 0.09525)
		(layer "In2.Cu")
		(net "M_I_CPU1_SB_DQS_DP<2>")
	)
	(segment
		(start 167.348154 -303.176686)
		(end 167.664638 -302.860202)
		(width 0.16002)
		(layer "In2.Cu")
		(net "M_I_CPU1_SB_DQS_DP<2>")
	)
	(segment
		(start 183.341518 -303.859946)
		(end 183.616092 -303.585372)
		(width 0.16002)
		(layer "In2.Cu")
		(net "M_I_CPU1_SB_DQS_DP<2>")
	)
	(segment
		(start 177.485548 -302.860202)
		(end 178.059588 -303.434242)
		(width 0.16002)
		(layer "In2.Cu")
		(net "M_I_CPU1_SB_DQS_DP<2>")
	)
	(segment
		(start 139.044934 -285.75635)
		(end 139.053316 -285.751524)
		(width 0.09525)
		(layer "In2.Cu")
		(net "M_I_CPU1_SB_DQS_DP<2>")
	)
	(segment
		(start 165.640258 -304.017426)
		(end 165.982142 -304.017426)
		(width 0.16002)
		(layer "In2.Cu")
		(net "M_I_CPU1_SB_DQS_DP<2>")
	)
	(segment
		(start 160.991042 -303.822608)
		(end 161.267902 -303.822608)
		(width 0.16002)
		(layer "In2.Cu")
		(net "M_I_CPU1_SB_DQS_DP<2>")
	)
	(segment
		(start 174.892208 -303.176686)
		(end 175.208692 -302.860202)
		(width 0.16002)
		(layer "In2.Cu")
		(net "M_I_CPU1_SB_DQS_DP<2>")
	)
	(segment
		(start 160.794446 -303.626012)
		(end 160.991042 -303.822608)
		(width 0.16002)
		(layer "In2.Cu")
		(net "M_I_CPU1_SB_DQS_DP<2>")
	)
	(segment
		(start 145.916396 -285.802832)
		(end 146.97583 -286.862266)
		(width 0.09525)
		(layer "In2.Cu")
		(net "M_I_CPU1_SB_DQS_DP<2>")
	)
	(segment
		(start 166.822882 -303.176686)
		(end 167.348154 -303.176686)
		(width 0.16002)
		(layer "In2.Cu")
		(net "M_I_CPU1_SB_DQS_DP<2>")
	)
	(segment
		(start 150.499826 -291.78631)
		(end 161.165032 -302.451516)
		(width 0.16002)
		(layer "In2.Cu")
		(net "M_I_CPU1_SB_DQS_DP<2>")
	)
	(segment
		(start 140.556234 -285.751524)
		(end 140.564616 -285.75635)
		(width 0.09525)
		(layer "In2.Cu")
		(net "M_I_CPU1_SB_DQS_DP<2>")
	)
	(segment
		(start 146.97583 -286.862266)
		(end 147.191222 -286.862266)
		(width 0.09525)
		(layer "In2.Cu")
		(net "M_I_CPU1_SB_DQS_DP<2>")
	)
	(segment
		(start 173.184312 -304.017426)
		(end 173.526196 -304.017426)
		(width 0.16002)
		(layer "In2.Cu")
		(net "M_I_CPU1_SB_DQS_DP<2>")
	)
	(segment
		(start 130.584956 -285.75635)
		(end 130.593338 -285.751524)
		(width 0.09525)
		(layer "In2.Cu")
		(net "M_I_CPU1_SB_DQS_DP<2>")
	)
	(segment
		(start 147.818602 -287.73374)
		(end 147.902422 -287.73374)
		(width 0.09525)
		(layer "In2.Cu")
		(net "M_I_CPU1_SB_DQS_DP<2>")
	)
	(segment
		(start 132.096256 -285.751524)
		(end 132.104638 -285.75635)
		(width 0.09525)
		(layer "In2.Cu")
		(net "M_I_CPU1_SB_DQS_DP<2>")
	)
	(segment
		(start 175.208692 -302.860202)
		(end 177.485548 -302.860202)
		(width 0.16002)
		(layer "In2.Cu")
		(net "M_I_CPU1_SB_DQS_DP<2>")
	)
	(segment
		(start 172.876972 -303.710086)
		(end 173.184312 -304.017426)
		(width 0.16002)
		(layer "In2.Cu")
		(net "M_I_CPU1_SB_DQS_DP<2>")
	)
	(segment
		(start 135.856218 -285.751524)
		(end 135.8646 -285.75635)
		(width 0.09525)
		(layer "In2.Cu")
		(net "M_I_CPU1_SB_DQS_DP<2>")
	)
	(segment
		(start 142.804896 -285.75635)
		(end 142.813278 -285.751524)
		(width 0.09525)
		(layer "In2.Cu")
		(net "M_I_CPU1_SB_DQS_DP<2>")
	)
	(segment
		(start 144.316196 -285.751524)
		(end 144.324578 -285.75635)
		(width 0.09525)
		(layer "In2.Cu")
		(net "M_I_CPU1_SB_DQS_DP<2>")
	)
	(segment
		(start 143.376142 -285.751524)
		(end 143.384524 -285.75635)
		(width 0.09525)
		(layer "In2.Cu")
		(net "M_I_CPU1_SB_DQS_DP<2>")
	)
	(segment
		(start 167.664638 -302.860202)
		(end 169.893742 -302.860202)
		(width 0.16002)
		(layer "In2.Cu")
		(net "M_I_CPU1_SB_DQS_DP<2>")
	)
	(segment
		(start 181.955948 -303.859946)
		(end 183.341518 -303.859946)
		(width 0.16002)
		(layer "In2.Cu")
		(net "M_I_CPU1_SB_DQS_DP<2>")
	)
	(segment
		(start 129.61874 -285.691834)
		(end 129.719578 -285.718504)
		(width 0.09525)
		(layer "In2.Cu")
		(net "M_I_CPU1_SB_DQS_DP<2>")
	)
	(segment
		(start 161.165032 -302.97882)
		(end 160.794446 -303.349406)
		(width 0.16002)
		(layer "In2.Cu")
		(net "M_I_CPU1_SB_DQS_DP<2>")
	)
	(segment
		(start 161.267902 -303.822608)
		(end 161.638234 -303.452276)
		(width 0.16002)
		(layer "In2.Cu")
		(net "M_I_CPU1_SB_DQS_DP<2>")
	)
	(segment
		(start 162.423602 -303.710086)
		(end 165.332918 -303.710086)
		(width 0.16002)
		(layer "In2.Cu")
		(net "M_I_CPU1_SB_DQS_DP<2>")
	)
	(segment
		(start 178.059588 -303.434242)
		(end 180.144928 -303.434242)
		(width 0.16002)
		(layer "In2.Cu")
		(net "M_I_CPU1_SB_DQS_DP<2>")
	)
	(segment
		(start 170.743626 -303.710086)
		(end 172.876972 -303.710086)
		(width 0.16002)
		(layer "In2.Cu")
		(net "M_I_CPU1_SB_DQS_DP<2>")
	)
	(segment
		(start 180.753512 -304.042826)
		(end 181.773068 -304.042826)
		(width 0.16002)
		(layer "In2.Cu")
		(net "M_I_CPU1_SB_DQS_DP<2>")
	)
	(segment
		(start 180.144928 -303.434242)
		(end 180.753512 -304.042826)
		(width 0.16002)
		(layer "In2.Cu")
		(net "M_I_CPU1_SB_DQS_DP<2>")
	)
	(segment
		(start 161.638234 -303.452276)
		(end 162.165792 -303.452276)
		(width 0.16002)
		(layer "In2.Cu")
		(net "M_I_CPU1_SB_DQS_DP<2>")
	)
	(segment
		(start 174.366936 -303.176686)
		(end 174.892208 -303.176686)
		(width 0.16002)
		(layer "In2.Cu")
		(net "M_I_CPU1_SB_DQS_DP<2>")
	)
	(segment
		(start 181.773068 -304.042826)
		(end 181.955948 -303.859946)
		(width 0.16002)
		(layer "In2.Cu")
		(net "M_I_CPU1_SB_DQS_DP<2>")
	)
	(segment
		(start 131.156202 -285.751524)
		(end 131.164584 -285.75635)
		(width 0.09525)
		(layer "In2.Cu")
		(net "M_I_CPU1_SB_DQS_DP<2>")
	)
	(arc
		(start 136.233408 -285.751524)
		(mid 136.51484 -285.675769)
		(end 136.796272 -285.751524)
		(width 0.09525)
		(layer "In2.Cu")
		(net "M_I_CPU1_SB_DQS_DP<2>")
	)
	(arc
		(start 137.173208 -285.751524)
		(mid 137.45464 -285.675769)
		(end 137.736072 -285.751524)
		(width 0.09525)
		(layer "In2.Cu")
		(net "M_I_CPU1_SB_DQS_DP<2>")
	)
	(arc
		(start 143.753332 -285.751524)
		(mid 144.034764 -285.675769)
		(end 144.316196 -285.751524)
		(width 0.09525)
		(layer "In2.Cu")
		(net "M_I_CPU1_SB_DQS_DP<2>")
	)
	(arc
		(start 145.25625 -285.751524)
		(mid 145.347093 -285.789643)
		(end 145.444718 -285.802832)
		(width 0.09525)
		(layer "In2.Cu")
		(net "M_I_CPU1_SB_DQS_DP<2>")
	)
	(arc
		(start 140.933424 -285.751524)
		(mid 141.214856 -285.675769)
		(end 141.496288 -285.751524)
		(width 0.09525)
		(layer "In2.Cu")
		(net "M_I_CPU1_SB_DQS_DP<2>")
	)
	(arc
		(start 136.796272 -285.751524)
		(mid 136.98474 -285.802201)
		(end 137.173208 -285.751524)
		(width 0.09525)
		(layer "In2.Cu")
		(net "M_I_CPU1_SB_DQS_DP<2>")
	)
	(arc
		(start 135.8646 -285.75635)
		(mid 136.049632 -285.802264)
		(end 136.233408 -285.751524)
		(width 0.09525)
		(layer "In2.Cu")
		(net "M_I_CPU1_SB_DQS_DP<2>")
	)
	(arc
		(start 131.533392 -285.751524)
		(mid 131.814824 -285.675769)
		(end 132.096256 -285.751524)
		(width 0.09525)
		(layer "In2.Cu")
		(net "M_I_CPU1_SB_DQS_DP<2>")
	)
	(arc
		(start 144.693386 -285.751524)
		(mid 144.974818 -285.675769)
		(end 145.25625 -285.751524)
		(width 0.09525)
		(layer "In2.Cu")
		(net "M_I_CPU1_SB_DQS_DP<2>")
	)
	(arc
		(start 141.496288 -285.751524)
		(mid 141.684756 -285.802201)
		(end 141.873224 -285.751524)
		(width 0.09525)
		(layer "In2.Cu")
		(net "M_I_CPU1_SB_DQS_DP<2>")
	)
	(arc
		(start 139.624562 -285.75635)
		(mid 139.809594 -285.802264)
		(end 139.99337 -285.751524)
		(width 0.09525)
		(layer "In2.Cu")
		(net "M_I_CPU1_SB_DQS_DP<2>")
	)
	(arc
		(start 140.564616 -285.75635)
		(mid 140.749648 -285.802264)
		(end 140.933424 -285.751524)
		(width 0.09525)
		(layer "In2.Cu")
		(net "M_I_CPU1_SB_DQS_DP<2>")
	)
	(arc
		(start 138.676126 -285.751524)
		(mid 138.859901 -285.802296)
		(end 139.044934 -285.75635)
		(width 0.09525)
		(layer "In2.Cu")
		(net "M_I_CPU1_SB_DQS_DP<2>")
	)
	(arc
		(start 142.813278 -285.751524)
		(mid 143.09471 -285.675769)
		(end 143.376142 -285.751524)
		(width 0.09525)
		(layer "In2.Cu")
		(net "M_I_CPU1_SB_DQS_DP<2>")
	)
	(arc
		(start 143.384524 -285.75635)
		(mid 143.569556 -285.802264)
		(end 143.753332 -285.751524)
		(width 0.09525)
		(layer "In2.Cu")
		(net "M_I_CPU1_SB_DQS_DP<2>")
	)
	(arc
		(start 135.293354 -285.751524)
		(mid 135.574786 -285.675769)
		(end 135.856218 -285.751524)
		(width 0.09525)
		(layer "In2.Cu")
		(net "M_I_CPU1_SB_DQS_DP<2>")
	)
	(arc
		(start 144.324578 -285.75635)
		(mid 144.50961 -285.802264)
		(end 144.693386 -285.751524)
		(width 0.09525)
		(layer "In2.Cu")
		(net "M_I_CPU1_SB_DQS_DP<2>")
	)
	(arc
		(start 131.164584 -285.75635)
		(mid 131.349616 -285.802264)
		(end 131.533392 -285.751524)
		(width 0.09525)
		(layer "In2.Cu")
		(net "M_I_CPU1_SB_DQS_DP<2>")
	)
	(arc
		(start 137.736072 -285.751524)
		(mid 137.919847 -285.802296)
		(end 138.10488 -285.75635)
		(width 0.09525)
		(layer "In2.Cu")
		(net "M_I_CPU1_SB_DQS_DP<2>")
	)
	(arc
		(start 132.473446 -285.751524)
		(mid 132.754878 -285.675769)
		(end 133.03631 -285.751524)
		(width 0.09525)
		(layer "In2.Cu")
		(net "M_I_CPU1_SB_DQS_DP<2>")
	)
	(arc
		(start 133.03631 -285.751524)
		(mid 133.224778 -285.802201)
		(end 133.413246 -285.751524)
		(width 0.09525)
		(layer "In2.Cu")
		(net "M_I_CPU1_SB_DQS_DP<2>")
	)
	(arc
		(start 138.113262 -285.751524)
		(mid 138.394694 -285.675769)
		(end 138.676126 -285.751524)
		(width 0.09525)
		(layer "In2.Cu")
		(net "M_I_CPU1_SB_DQS_DP<2>")
	)
	(arc
		(start 130.593338 -285.751524)
		(mid 130.87477 -285.675769)
		(end 131.156202 -285.751524)
		(width 0.09525)
		(layer "In2.Cu")
		(net "M_I_CPU1_SB_DQS_DP<2>")
	)
	(arc
		(start 130.216148 -285.751524)
		(mid 130.399923 -285.802296)
		(end 130.584956 -285.75635)
		(width 0.09525)
		(layer "In2.Cu")
		(net "M_I_CPU1_SB_DQS_DP<2>")
	)
	(arc
		(start 129.719578 -285.718504)
		(mid 129.971719 -285.676934)
		(end 130.216148 -285.751524)
		(width 0.09525)
		(layer "In2.Cu")
		(net "M_I_CPU1_SB_DQS_DP<2>")
	)
	(arc
		(start 141.873224 -285.751524)
		(mid 142.154656 -285.675769)
		(end 142.436088 -285.751524)
		(width 0.09525)
		(layer "In2.Cu")
		(net "M_I_CPU1_SB_DQS_DP<2>")
	)
	(arc
		(start 139.99337 -285.751524)
		(mid 140.274802 -285.675769)
		(end 140.556234 -285.751524)
		(width 0.09525)
		(layer "In2.Cu")
		(net "M_I_CPU1_SB_DQS_DP<2>")
	)
	(arc
		(start 134.924546 -285.75635)
		(mid 135.109578 -285.802264)
		(end 135.293354 -285.751524)
		(width 0.09525)
		(layer "In2.Cu")
		(net "M_I_CPU1_SB_DQS_DP<2>")
	)
	(arc
		(start 134.3533 -285.751524)
		(mid 134.634732 -285.675769)
		(end 134.916164 -285.751524)
		(width 0.09525)
		(layer "In2.Cu")
		(net "M_I_CPU1_SB_DQS_DP<2>")
	)
	(arc
		(start 132.104638 -285.75635)
		(mid 132.28967 -285.802264)
		(end 132.473446 -285.751524)
		(width 0.09525)
		(layer "In2.Cu")
		(net "M_I_CPU1_SB_DQS_DP<2>")
	)
	(arc
		(start 133.413246 -285.751524)
		(mid 133.694678 -285.675769)
		(end 133.97611 -285.751524)
		(width 0.09525)
		(layer "In2.Cu")
		(net "M_I_CPU1_SB_DQS_DP<2>")
	)
	(arc
		(start 139.053316 -285.751524)
		(mid 139.334748 -285.675769)
		(end 139.61618 -285.751524)
		(width 0.09525)
		(layer "In2.Cu")
		(net "M_I_CPU1_SB_DQS_DP<2>")
	)
	(arc
		(start 142.436088 -285.751524)
		(mid 142.619863 -285.802296)
		(end 142.804896 -285.75635)
		(width 0.09525)
		(layer "In2.Cu")
		(net "M_I_CPU1_SB_DQS_DP<2>")
	)
	(arc
		(start 133.97611 -285.751524)
		(mid 134.159885 -285.802296)
		(end 134.344918 -285.75635)
		(width 0.09525)
		(layer "In2.Cu")
		(net "M_I_CPU1_SB_DQS_DP<2>")
	)
	(segment
		(start 128.997964 -280.30043)
		(end 129.464816 -280.566368)
		(width 0.12954)
		(layer "F.Cu")
		(net "M_I_CPU1_SB_DQS_DP<1>")
	)
	(segment
		(start 154.592782 -285.206948)
		(end 162.89655 -293.510716)
		(width 0.16002)
		(layer "In2.Cu")
		(net "M_I_CPU1_SB_DQS_DP<1>")
	)
	(segment
		(start 163.37915 -294.360092)
		(end 165.332918 -294.360092)
		(width 0.16002)
		(layer "In2.Cu")
		(net "M_I_CPU1_SB_DQS_DP<1>")
	)
	(segment
		(start 145.897346 -280.942796)
		(end 146.305016 -280.535126)
		(width 0.09525)
		(layer "In2.Cu")
		(net "M_I_CPU1_SB_DQS_DP<1>")
	)
	(segment
		(start 147.690078 -280.985976)
		(end 147.836382 -280.985976)
		(width 0.09525)
		(layer "In2.Cu")
		(net "M_I_CPU1_SB_DQS_DP<1>")
	)
	(segment
		(start 166.822882 -293.826692)
		(end 167.348154 -293.826692)
		(width 0.16002)
		(layer "In2.Cu")
		(net "M_I_CPU1_SB_DQS_DP<1>")
	)
	(segment
		(start 149.444964 -280.926794)
		(end 153.725118 -285.206948)
		(width 0.16002)
		(layer "In2.Cu")
		(net "M_I_CPU1_SB_DQS_DP<1>")
	)
	(segment
		(start 165.982142 -294.667432)
		(end 166.822882 -293.826692)
		(width 0.16002)
		(layer "In2.Cu")
		(net "M_I_CPU1_SB_DQS_DP<1>")
	)
	(segment
		(start 147.895564 -280.926794)
		(end 147.919186 -280.926794)
		(width 0.09525)
		(layer "In2.Cu")
		(net "M_I_CPU1_SB_DQS_DP<1>")
	)
	(segment
		(start 138.10488 -280.896314)
		(end 138.113262 -280.891488)
		(width 0.09525)
		(layer "In2.Cu")
		(net "M_I_CPU1_SB_DQS_DP<1>")
	)
	(segment
		(start 183.341518 -294.509952)
		(end 183.616092 -294.235378)
		(width 0.16002)
		(layer "In2.Cu")
		(net "M_I_CPU1_SB_DQS_DP<1>")
	)
	(segment
		(start 180.144928 -294.084248)
		(end 180.753512 -294.692832)
		(width 0.16002)
		(layer "In2.Cu")
		(net "M_I_CPU1_SB_DQS_DP<1>")
	)
	(segment
		(start 145.44167 -280.942288)
		(end 145.536412 -280.942288)
		(width 0.09525)
		(layer "In2.Cu")
		(net "M_I_CPU1_SB_DQS_DP<1>")
	)
	(segment
		(start 139.044934 -280.896314)
		(end 139.053316 -280.891488)
		(width 0.09525)
		(layer "In2.Cu")
		(net "M_I_CPU1_SB_DQS_DP<1>")
	)
	(segment
		(start 134.916164 -280.891488)
		(end 134.924546 -280.896314)
		(width 0.09525)
		(layer "In2.Cu")
		(net "M_I_CPU1_SB_DQS_DP<1>")
	)
	(segment
		(start 146.305016 -280.535126)
		(end 147.239228 -280.535126)
		(width 0.09525)
		(layer "In2.Cu")
		(net "M_I_CPU1_SB_DQS_DP<1>")
	)
	(segment
		(start 153.725118 -285.206948)
		(end 154.592782 -285.206948)
		(width 0.16002)
		(layer "In2.Cu")
		(net "M_I_CPU1_SB_DQS_DP<1>")
	)
	(segment
		(start 145.256504 -280.891488)
		(end 145.270982 -280.89987)
		(width 0.09525)
		(layer "In2.Cu")
		(net "M_I_CPU1_SB_DQS_DP<1>")
	)
	(segment
		(start 143.753332 -280.891488)
		(end 143.768064 -280.882852)
		(width 0.09525)
		(layer "In2.Cu")
		(net "M_I_CPU1_SB_DQS_DP<1>")
	)
	(segment
		(start 181.197504 -294.692832)
		(end 181.380384 -294.509952)
		(width 0.16002)
		(layer "In2.Cu")
		(net "M_I_CPU1_SB_DQS_DP<1>")
	)
	(segment
		(start 147.919186 -280.926794)
		(end 149.444964 -280.926794)
		(width 0.16002)
		(layer "In2.Cu")
		(net "M_I_CPU1_SB_DQS_DP<1>")
	)
	(segment
		(start 132.096256 -280.891488)
		(end 132.104638 -280.896314)
		(width 0.09525)
		(layer "In2.Cu")
		(net "M_I_CPU1_SB_DQS_DP<1>")
	)
	(segment
		(start 144.68221 -280.898346)
		(end 144.694148 -280.891488)
		(width 0.09525)
		(layer "In2.Cu")
		(net "M_I_CPU1_SB_DQS_DP<1>")
	)
	(segment
		(start 129.464816 -280.566368)
		(end 129.61874 -280.831798)
		(width 0.09525)
		(layer "In2.Cu")
		(net "M_I_CPU1_SB_DQS_DP<1>")
	)
	(segment
		(start 170.743626 -294.360092)
		(end 172.876972 -294.360092)
		(width 0.16002)
		(layer "In2.Cu")
		(net "M_I_CPU1_SB_DQS_DP<1>")
	)
	(segment
		(start 145.53692 -280.942796)
		(end 145.897346 -280.942796)
		(width 0.09525)
		(layer "In2.Cu")
		(net "M_I_CPU1_SB_DQS_DP<1>")
	)
	(segment
		(start 180.753512 -294.692832)
		(end 181.197504 -294.692832)
		(width 0.16002)
		(layer "In2.Cu")
		(net "M_I_CPU1_SB_DQS_DP<1>")
	)
	(segment
		(start 162.89655 -293.510716)
		(end 162.89655 -293.877492)
		(width 0.16002)
		(layer "In2.Cu")
		(net "M_I_CPU1_SB_DQS_DP<1>")
	)
	(segment
		(start 129.61874 -280.831798)
		(end 129.719578 -280.858468)
		(width 0.09525)
		(layer "In2.Cu")
		(net "M_I_CPU1_SB_DQS_DP<1>")
	)
	(segment
		(start 134.344918 -280.896314)
		(end 134.3533 -280.891488)
		(width 0.09525)
		(layer "In2.Cu")
		(net "M_I_CPU1_SB_DQS_DP<1>")
	)
	(segment
		(start 142.804896 -280.896314)
		(end 142.813278 -280.891488)
		(width 0.09525)
		(layer "In2.Cu")
		(net "M_I_CPU1_SB_DQS_DP<1>")
	)
	(segment
		(start 173.526196 -294.667432)
		(end 174.366936 -293.826692)
		(width 0.16002)
		(layer "In2.Cu")
		(net "M_I_CPU1_SB_DQS_DP<1>")
	)
	(segment
		(start 139.61618 -280.891488)
		(end 139.624562 -280.896314)
		(width 0.09525)
		(layer "In2.Cu")
		(net "M_I_CPU1_SB_DQS_DP<1>")
	)
	(segment
		(start 130.584956 -280.896314)
		(end 130.593338 -280.891488)
		(width 0.09525)
		(layer "In2.Cu")
		(net "M_I_CPU1_SB_DQS_DP<1>")
	)
	(segment
		(start 145.536412 -280.942288)
		(end 145.53692 -280.942796)
		(width 0.09525)
		(layer "In2.Cu")
		(net "M_I_CPU1_SB_DQS_DP<1>")
	)
	(segment
		(start 145.241772 -280.882852)
		(end 145.256504 -280.891488)
		(width 0.09525)
		(layer "In2.Cu")
		(net "M_I_CPU1_SB_DQS_DP<1>")
	)
	(segment
		(start 140.556234 -280.891488)
		(end 140.564616 -280.896314)
		(width 0.09525)
		(layer "In2.Cu")
		(net "M_I_CPU1_SB_DQS_DP<1>")
	)
	(segment
		(start 165.640258 -294.667432)
		(end 165.982142 -294.667432)
		(width 0.16002)
		(layer "In2.Cu")
		(net "M_I_CPU1_SB_DQS_DP<1>")
	)
	(segment
		(start 135.856218 -280.891488)
		(end 135.8646 -280.896314)
		(width 0.09525)
		(layer "In2.Cu")
		(net "M_I_CPU1_SB_DQS_DP<1>")
	)
	(segment
		(start 165.332918 -294.360092)
		(end 165.640258 -294.667432)
		(width 0.16002)
		(layer "In2.Cu")
		(net "M_I_CPU1_SB_DQS_DP<1>")
	)
	(segment
		(start 172.876972 -294.360092)
		(end 173.184312 -294.667432)
		(width 0.16002)
		(layer "In2.Cu")
		(net "M_I_CPU1_SB_DQS_DP<1>")
	)
	(segment
		(start 147.836382 -280.985976)
		(end 147.895564 -280.926794)
		(width 0.09525)
		(layer "In2.Cu")
		(net "M_I_CPU1_SB_DQS_DP<1>")
	)
	(segment
		(start 169.893742 -293.510208)
		(end 170.743626 -294.360092)
		(width 0.16002)
		(layer "In2.Cu")
		(net "M_I_CPU1_SB_DQS_DP<1>")
	)
	(segment
		(start 167.664638 -293.510208)
		(end 169.893742 -293.510208)
		(width 0.16002)
		(layer "In2.Cu")
		(net "M_I_CPU1_SB_DQS_DP<1>")
	)
	(segment
		(start 162.89655 -293.877492)
		(end 163.37915 -294.360092)
		(width 0.16002)
		(layer "In2.Cu")
		(net "M_I_CPU1_SB_DQS_DP<1>")
	)
	(segment
		(start 177.485548 -293.510208)
		(end 178.059588 -294.084248)
		(width 0.16002)
		(layer "In2.Cu")
		(net "M_I_CPU1_SB_DQS_DP<1>")
	)
	(segment
		(start 175.208692 -293.510208)
		(end 177.485548 -293.510208)
		(width 0.16002)
		(layer "In2.Cu")
		(net "M_I_CPU1_SB_DQS_DP<1>")
	)
	(segment
		(start 174.366936 -293.826692)
		(end 174.892208 -293.826692)
		(width 0.16002)
		(layer "In2.Cu")
		(net "M_I_CPU1_SB_DQS_DP<1>")
	)
	(segment
		(start 147.239228 -280.535126)
		(end 147.690078 -280.985976)
		(width 0.09525)
		(layer "In2.Cu")
		(net "M_I_CPU1_SB_DQS_DP<1>")
	)
	(segment
		(start 167.348154 -293.826692)
		(end 167.664638 -293.510208)
		(width 0.16002)
		(layer "In2.Cu")
		(net "M_I_CPU1_SB_DQS_DP<1>")
	)
	(segment
		(start 174.892208 -293.826692)
		(end 175.208692 -293.510208)
		(width 0.16002)
		(layer "In2.Cu")
		(net "M_I_CPU1_SB_DQS_DP<1>")
	)
	(segment
		(start 131.156202 -280.891488)
		(end 131.164584 -280.896314)
		(width 0.09525)
		(layer "In2.Cu")
		(net "M_I_CPU1_SB_DQS_DP<1>")
	)
	(segment
		(start 181.380384 -294.509952)
		(end 183.341518 -294.509952)
		(width 0.16002)
		(layer "In2.Cu")
		(net "M_I_CPU1_SB_DQS_DP<1>")
	)
	(segment
		(start 178.059588 -294.084248)
		(end 180.144928 -294.084248)
		(width 0.16002)
		(layer "In2.Cu")
		(net "M_I_CPU1_SB_DQS_DP<1>")
	)
	(segment
		(start 173.184312 -294.667432)
		(end 173.526196 -294.667432)
		(width 0.16002)
		(layer "In2.Cu")
		(net "M_I_CPU1_SB_DQS_DP<1>")
	)
	(segment
		(start 143.376142 -280.891488)
		(end 143.384524 -280.896314)
		(width 0.09525)
		(layer "In2.Cu")
		(net "M_I_CPU1_SB_DQS_DP<1>")
	)
	(arc
		(start 137.736072 -280.891488)
		(mid 137.919847 -280.94226)
		(end 138.10488 -280.896314)
		(width 0.09525)
		(layer "In2.Cu")
		(net "M_I_CPU1_SB_DQS_DP<1>")
	)
	(arc
		(start 137.173208 -280.891488)
		(mid 137.45464 -280.815733)
		(end 137.736072 -280.891488)
		(width 0.09525)
		(layer "In2.Cu")
		(net "M_I_CPU1_SB_DQS_DP<1>")
	)
	(arc
		(start 131.533392 -280.891488)
		(mid 131.814824 -280.815733)
		(end 132.096256 -280.891488)
		(width 0.09525)
		(layer "In2.Cu")
		(net "M_I_CPU1_SB_DQS_DP<1>")
	)
	(arc
		(start 141.873224 -280.891488)
		(mid 142.154656 -280.815733)
		(end 142.436088 -280.891488)
		(width 0.09525)
		(layer "In2.Cu")
		(net "M_I_CPU1_SB_DQS_DP<1>")
	)
	(arc
		(start 140.564616 -280.896314)
		(mid 140.749648 -280.942228)
		(end 140.933424 -280.891488)
		(width 0.09525)
		(layer "In2.Cu")
		(net "M_I_CPU1_SB_DQS_DP<1>")
	)
	(arc
		(start 133.97611 -280.891488)
		(mid 134.159885 -280.94226)
		(end 134.344918 -280.896314)
		(width 0.09525)
		(layer "In2.Cu")
		(net "M_I_CPU1_SB_DQS_DP<1>")
	)
	(arc
		(start 135.8646 -280.896314)
		(mid 136.049632 -280.942228)
		(end 136.233408 -280.891488)
		(width 0.09525)
		(layer "In2.Cu")
		(net "M_I_CPU1_SB_DQS_DP<1>")
	)
	(arc
		(start 139.053316 -280.891488)
		(mid 139.334748 -280.815733)
		(end 139.61618 -280.891488)
		(width 0.09525)
		(layer "In2.Cu")
		(net "M_I_CPU1_SB_DQS_DP<1>")
	)
	(arc
		(start 133.413246 -280.891488)
		(mid 133.694678 -280.815733)
		(end 133.97611 -280.891488)
		(width 0.09525)
		(layer "In2.Cu")
		(net "M_I_CPU1_SB_DQS_DP<1>")
	)
	(arc
		(start 143.768064 -280.882852)
		(mid 144.043523 -280.815467)
		(end 144.316704 -280.891488)
		(width 0.09525)
		(layer "In2.Cu")
		(net "M_I_CPU1_SB_DQS_DP<1>")
	)
	(arc
		(start 139.99337 -280.891488)
		(mid 140.274802 -280.815733)
		(end 140.556234 -280.891488)
		(width 0.09525)
		(layer "In2.Cu")
		(net "M_I_CPU1_SB_DQS_DP<1>")
	)
	(arc
		(start 130.593338 -280.891488)
		(mid 130.87477 -280.815733)
		(end 131.156202 -280.891488)
		(width 0.09525)
		(layer "In2.Cu")
		(net "M_I_CPU1_SB_DQS_DP<1>")
	)
	(arc
		(start 134.3533 -280.891488)
		(mid 134.634732 -280.815733)
		(end 134.916164 -280.891488)
		(width 0.09525)
		(layer "In2.Cu")
		(net "M_I_CPU1_SB_DQS_DP<1>")
	)
	(arc
		(start 142.436088 -280.891488)
		(mid 142.619863 -280.94226)
		(end 142.804896 -280.896314)
		(width 0.09525)
		(layer "In2.Cu")
		(net "M_I_CPU1_SB_DQS_DP<1>")
	)
	(arc
		(start 140.933424 -280.891488)
		(mid 141.214856 -280.815733)
		(end 141.496288 -280.891488)
		(width 0.09525)
		(layer "In2.Cu")
		(net "M_I_CPU1_SB_DQS_DP<1>")
	)
	(arc
		(start 132.473446 -280.891488)
		(mid 132.754878 -280.815733)
		(end 133.03631 -280.891488)
		(width 0.09525)
		(layer "In2.Cu")
		(net "M_I_CPU1_SB_DQS_DP<1>")
	)
	(arc
		(start 130.216148 -280.891488)
		(mid 130.399923 -280.94226)
		(end 130.584956 -280.896314)
		(width 0.09525)
		(layer "In2.Cu")
		(net "M_I_CPU1_SB_DQS_DP<1>")
	)
	(arc
		(start 131.164584 -280.896314)
		(mid 131.349616 -280.942228)
		(end 131.533392 -280.891488)
		(width 0.09525)
		(layer "In2.Cu")
		(net "M_I_CPU1_SB_DQS_DP<1>")
	)
	(arc
		(start 133.03631 -280.891488)
		(mid 133.224778 -280.942165)
		(end 133.413246 -280.891488)
		(width 0.09525)
		(layer "In2.Cu")
		(net "M_I_CPU1_SB_DQS_DP<1>")
	)
	(arc
		(start 144.694148 -280.891488)
		(mid 144.966822 -280.815801)
		(end 145.241772 -280.882852)
		(width 0.09525)
		(layer "In2.Cu")
		(net "M_I_CPU1_SB_DQS_DP<1>")
	)
	(arc
		(start 138.676126 -280.891488)
		(mid 138.859901 -280.94226)
		(end 139.044934 -280.896314)
		(width 0.09525)
		(layer "In2.Cu")
		(net "M_I_CPU1_SB_DQS_DP<1>")
	)
	(arc
		(start 144.316704 -280.891488)
		(mid 144.498574 -280.942353)
		(end 144.68221 -280.898346)
		(width 0.09525)
		(layer "In2.Cu")
		(net "M_I_CPU1_SB_DQS_DP<1>")
	)
	(arc
		(start 139.624562 -280.896314)
		(mid 139.809594 -280.942228)
		(end 139.99337 -280.891488)
		(width 0.09525)
		(layer "In2.Cu")
		(net "M_I_CPU1_SB_DQS_DP<1>")
	)
	(arc
		(start 136.796272 -280.891488)
		(mid 136.98474 -280.942165)
		(end 137.173208 -280.891488)
		(width 0.09525)
		(layer "In2.Cu")
		(net "M_I_CPU1_SB_DQS_DP<1>")
	)
	(arc
		(start 136.233408 -280.891488)
		(mid 136.51484 -280.815733)
		(end 136.796272 -280.891488)
		(width 0.09525)
		(layer "In2.Cu")
		(net "M_I_CPU1_SB_DQS_DP<1>")
	)
	(arc
		(start 142.813278 -280.891488)
		(mid 143.09471 -280.815733)
		(end 143.376142 -280.891488)
		(width 0.09525)
		(layer "In2.Cu")
		(net "M_I_CPU1_SB_DQS_DP<1>")
	)
	(arc
		(start 141.496288 -280.891488)
		(mid 141.684756 -280.942165)
		(end 141.873224 -280.891488)
		(width 0.09525)
		(layer "In2.Cu")
		(net "M_I_CPU1_SB_DQS_DP<1>")
	)
	(arc
		(start 138.113262 -280.891488)
		(mid 138.394694 -280.815733)
		(end 138.676126 -280.891488)
		(width 0.09525)
		(layer "In2.Cu")
		(net "M_I_CPU1_SB_DQS_DP<1>")
	)
	(arc
		(start 129.719578 -280.858468)
		(mid 129.971719 -280.816898)
		(end 130.216148 -280.891488)
		(width 0.09525)
		(layer "In2.Cu")
		(net "M_I_CPU1_SB_DQS_DP<1>")
	)
	(arc
		(start 135.293354 -280.891488)
		(mid 135.574786 -280.815733)
		(end 135.856218 -280.891488)
		(width 0.09525)
		(layer "In2.Cu")
		(net "M_I_CPU1_SB_DQS_DP<1>")
	)
	(arc
		(start 132.104638 -280.896314)
		(mid 132.28967 -280.942228)
		(end 132.473446 -280.891488)
		(width 0.09525)
		(layer "In2.Cu")
		(net "M_I_CPU1_SB_DQS_DP<1>")
	)
	(arc
		(start 145.270982 -280.89987)
		(mid 145.353811 -280.931199)
		(end 145.44167 -280.942288)
		(width 0.09525)
		(layer "In2.Cu")
		(net "M_I_CPU1_SB_DQS_DP<1>")
	)
	(arc
		(start 134.924546 -280.896314)
		(mid 135.109578 -280.942228)
		(end 135.293354 -280.891488)
		(width 0.09525)
		(layer "In2.Cu")
		(net "M_I_CPU1_SB_DQS_DP<1>")
	)
	(arc
		(start 143.384524 -280.896314)
		(mid 143.569556 -280.942228)
		(end 143.753332 -280.891488)
		(width 0.09525)
		(layer "In2.Cu")
		(net "M_I_CPU1_SB_DQS_DP<1>")
	)
	(segment
		(start 128.997964 -275.440394)
		(end 129.464816 -275.706332)
		(width 0.12954)
		(layer "F.Cu")
		(net "M_I_CPU1_SB_DQS_DP<0>")
	)
	(segment
		(start 173.184312 -285.317438)
		(end 173.526196 -285.317438)
		(width 0.16002)
		(layer "In2.Cu")
		(net "M_I_CPU1_SB_DQS_DP<0>")
	)
	(segment
		(start 166.822882 -284.476698)
		(end 167.348154 -284.476698)
		(width 0.16002)
		(layer "In2.Cu")
		(net "M_I_CPU1_SB_DQS_DP<0>")
	)
	(segment
		(start 147.20824 -275.019008)
		(end 147.270216 -274.957032)
		(width 0.09525)
		(layer "In2.Cu")
		(net "M_I_CPU1_SB_DQS_DP<0>")
	)
	(segment
		(start 177.485548 -284.160214)
		(end 178.059588 -284.734254)
		(width 0.16002)
		(layer "In2.Cu")
		(net "M_I_CPU1_SB_DQS_DP<0>")
	)
	(segment
		(start 145.256504 -276.031452)
		(end 145.270982 -276.039834)
		(width 0.09525)
		(layer "In2.Cu")
		(net "M_I_CPU1_SB_DQS_DP<0>")
	)
	(segment
		(start 180.753512 -285.342838)
		(end 181.159404 -285.342838)
		(width 0.16002)
		(layer "In2.Cu")
		(net "M_I_CPU1_SB_DQS_DP<0>")
	)
	(segment
		(start 152.664414 -274.89785)
		(end 160.374076 -282.607512)
		(width 0.16002)
		(layer "In2.Cu")
		(net "M_I_CPU1_SB_DQS_DP<0>")
	)
	(segment
		(start 174.366936 -284.476698)
		(end 174.892208 -284.476698)
		(width 0.16002)
		(layer "In2.Cu")
		(net "M_I_CPU1_SB_DQS_DP<0>")
	)
	(segment
		(start 163.385246 -285.010098)
		(end 165.332918 -285.010098)
		(width 0.16002)
		(layer "In2.Cu")
		(net "M_I_CPU1_SB_DQS_DP<0>")
	)
	(segment
		(start 165.982142 -285.317438)
		(end 166.822882 -284.476698)
		(width 0.16002)
		(layer "In2.Cu")
		(net "M_I_CPU1_SB_DQS_DP<0>")
	)
	(segment
		(start 167.664638 -284.160214)
		(end 169.893742 -284.160214)
		(width 0.16002)
		(layer "In2.Cu")
		(net "M_I_CPU1_SB_DQS_DP<0>")
	)
	(segment
		(start 181.159404 -285.342838)
		(end 181.342284 -285.159958)
		(width 0.16002)
		(layer "In2.Cu")
		(net "M_I_CPU1_SB_DQS_DP<0>")
	)
	(segment
		(start 132.096256 -276.031452)
		(end 132.104638 -276.036278)
		(width 0.09525)
		(layer "In2.Cu")
		(net "M_I_CPU1_SB_DQS_DP<0>")
	)
	(segment
		(start 146.664426 -275.019008)
		(end 147.20824 -275.019008)
		(width 0.09525)
		(layer "In2.Cu")
		(net "M_I_CPU1_SB_DQS_DP<0>")
	)
	(segment
		(start 172.876972 -285.010098)
		(end 173.184312 -285.317438)
		(width 0.16002)
		(layer "In2.Cu")
		(net "M_I_CPU1_SB_DQS_DP<0>")
	)
	(segment
		(start 140.556234 -276.031452)
		(end 140.564616 -276.036278)
		(width 0.09525)
		(layer "In2.Cu")
		(net "M_I_CPU1_SB_DQS_DP<0>")
	)
	(segment
		(start 174.892208 -284.476698)
		(end 175.208692 -284.160214)
		(width 0.16002)
		(layer "In2.Cu")
		(net "M_I_CPU1_SB_DQS_DP<0>")
	)
	(segment
		(start 142.804896 -276.036278)
		(end 142.813278 -276.031452)
		(width 0.09525)
		(layer "In2.Cu")
		(net "M_I_CPU1_SB_DQS_DP<0>")
	)
	(segment
		(start 144.68221 -276.03831)
		(end 144.694148 -276.031452)
		(width 0.09525)
		(layer "In2.Cu")
		(net "M_I_CPU1_SB_DQS_DP<0>")
	)
	(segment
		(start 134.344918 -276.036278)
		(end 134.3533 -276.031452)
		(width 0.09525)
		(layer "In2.Cu")
		(net "M_I_CPU1_SB_DQS_DP<0>")
	)
	(segment
		(start 180.144928 -284.734254)
		(end 180.753512 -285.342838)
		(width 0.16002)
		(layer "In2.Cu")
		(net "M_I_CPU1_SB_DQS_DP<0>")
	)
	(segment
		(start 147.919186 -274.89785)
		(end 152.664414 -274.89785)
		(width 0.16002)
		(layer "In2.Cu")
		(net "M_I_CPU1_SB_DQS_DP<0>")
	)
	(segment
		(start 181.342284 -285.159958)
		(end 183.341518 -285.159958)
		(width 0.16002)
		(layer "In2.Cu")
		(net "M_I_CPU1_SB_DQS_DP<0>")
	)
	(segment
		(start 183.341518 -285.159958)
		(end 183.616092 -284.885384)
		(width 0.16002)
		(layer "In2.Cu")
		(net "M_I_CPU1_SB_DQS_DP<0>")
	)
	(segment
		(start 165.332918 -285.010098)
		(end 165.640258 -285.317438)
		(width 0.16002)
		(layer "In2.Cu")
		(net "M_I_CPU1_SB_DQS_DP<0>")
	)
	(segment
		(start 165.640258 -285.317438)
		(end 165.982142 -285.317438)
		(width 0.16002)
		(layer "In2.Cu")
		(net "M_I_CPU1_SB_DQS_DP<0>")
	)
	(segment
		(start 139.61618 -276.031452)
		(end 139.624562 -276.036278)
		(width 0.09525)
		(layer "In2.Cu")
		(net "M_I_CPU1_SB_DQS_DP<0>")
	)
	(segment
		(start 170.743626 -285.010098)
		(end 172.876972 -285.010098)
		(width 0.16002)
		(layer "In2.Cu")
		(net "M_I_CPU1_SB_DQS_DP<0>")
	)
	(segment
		(start 167.348154 -284.476698)
		(end 167.664638 -284.160214)
		(width 0.16002)
		(layer "In2.Cu")
		(net "M_I_CPU1_SB_DQS_DP<0>")
	)
	(segment
		(start 129.464816 -275.706332)
		(end 129.61874 -275.971762)
		(width 0.09525)
		(layer "In2.Cu")
		(net "M_I_CPU1_SB_DQS_DP<0>")
	)
	(segment
		(start 147.895564 -274.89785)
		(end 147.919186 -274.89785)
		(width 0.09525)
		(layer "In2.Cu")
		(net "M_I_CPU1_SB_DQS_DP<0>")
	)
	(segment
		(start 178.059588 -284.734254)
		(end 180.144928 -284.734254)
		(width 0.16002)
		(layer "In2.Cu")
		(net "M_I_CPU1_SB_DQS_DP<0>")
	)
	(segment
		(start 143.376142 -276.031452)
		(end 143.384524 -276.036278)
		(width 0.09525)
		(layer "In2.Cu")
		(net "M_I_CPU1_SB_DQS_DP<0>")
	)
	(segment
		(start 135.856218 -276.031452)
		(end 135.8646 -276.036278)
		(width 0.09525)
		(layer "In2.Cu")
		(net "M_I_CPU1_SB_DQS_DP<0>")
	)
	(segment
		(start 160.374076 -282.607512)
		(end 160.98266 -282.607512)
		(width 0.16002)
		(layer "In2.Cu")
		(net "M_I_CPU1_SB_DQS_DP<0>")
	)
	(segment
		(start 169.893742 -284.160214)
		(end 170.743626 -285.010098)
		(width 0.16002)
		(layer "In2.Cu")
		(net "M_I_CPU1_SB_DQS_DP<0>")
	)
	(segment
		(start 129.61874 -275.971762)
		(end 129.719578 -275.998432)
		(width 0.09525)
		(layer "In2.Cu")
		(net "M_I_CPU1_SB_DQS_DP<0>")
	)
	(segment
		(start 173.526196 -285.317438)
		(end 174.366936 -284.476698)
		(width 0.16002)
		(layer "In2.Cu")
		(net "M_I_CPU1_SB_DQS_DP<0>")
	)
	(segment
		(start 160.98266 -282.607512)
		(end 163.385246 -285.010098)
		(width 0.16002)
		(layer "In2.Cu")
		(net "M_I_CPU1_SB_DQS_DP<0>")
	)
	(segment
		(start 138.10488 -276.036278)
		(end 138.113262 -276.031452)
		(width 0.09525)
		(layer "In2.Cu")
		(net "M_I_CPU1_SB_DQS_DP<0>")
	)
	(segment
		(start 145.71091 -275.972524)
		(end 146.664426 -275.019008)
		(width 0.09525)
		(layer "In2.Cu")
		(net "M_I_CPU1_SB_DQS_DP<0>")
	)
	(segment
		(start 147.270216 -274.957032)
		(end 147.836382 -274.957032)
		(width 0.09525)
		(layer "In2.Cu")
		(net "M_I_CPU1_SB_DQS_DP<0>")
	)
	(segment
		(start 143.753332 -276.031452)
		(end 143.768064 -276.022816)
		(width 0.09525)
		(layer "In2.Cu")
		(net "M_I_CPU1_SB_DQS_DP<0>")
	)
	(segment
		(start 130.584956 -276.036278)
		(end 130.593338 -276.031452)
		(width 0.09525)
		(layer "In2.Cu")
		(net "M_I_CPU1_SB_DQS_DP<0>")
	)
	(segment
		(start 175.208692 -284.160214)
		(end 177.485548 -284.160214)
		(width 0.16002)
		(layer "In2.Cu")
		(net "M_I_CPU1_SB_DQS_DP<0>")
	)
	(segment
		(start 147.836382 -274.957032)
		(end 147.895564 -274.89785)
		(width 0.09525)
		(layer "In2.Cu")
		(net "M_I_CPU1_SB_DQS_DP<0>")
	)
	(segment
		(start 139.044934 -276.036278)
		(end 139.053316 -276.031452)
		(width 0.09525)
		(layer "In2.Cu")
		(net "M_I_CPU1_SB_DQS_DP<0>")
	)
	(segment
		(start 131.156202 -276.031452)
		(end 131.164584 -276.036278)
		(width 0.09525)
		(layer "In2.Cu")
		(net "M_I_CPU1_SB_DQS_DP<0>")
	)
	(segment
		(start 134.916164 -276.031452)
		(end 134.924546 -276.036278)
		(width 0.09525)
		(layer "In2.Cu")
		(net "M_I_CPU1_SB_DQS_DP<0>")
	)
	(segment
		(start 145.241772 -276.022816)
		(end 145.256504 -276.031452)
		(width 0.09525)
		(layer "In2.Cu")
		(net "M_I_CPU1_SB_DQS_DP<0>")
	)
	(arc
		(start 145.270982 -276.039834)
		(mid 145.453414 -276.082274)
		(end 145.633694 -276.031452)
		(width 0.09525)
		(layer "In2.Cu")
		(net "M_I_CPU1_SB_DQS_DP<0>")
	)
	(arc
		(start 136.796272 -276.031452)
		(mid 136.98474 -276.082129)
		(end 137.173208 -276.031452)
		(width 0.09525)
		(layer "In2.Cu")
		(net "M_I_CPU1_SB_DQS_DP<0>")
	)
	(arc
		(start 142.436088 -276.031452)
		(mid 142.619863 -276.082224)
		(end 142.804896 -276.036278)
		(width 0.09525)
		(layer "In2.Cu")
		(net "M_I_CPU1_SB_DQS_DP<0>")
	)
	(arc
		(start 132.473446 -276.031452)
		(mid 132.754878 -275.955697)
		(end 133.03631 -276.031452)
		(width 0.09525)
		(layer "In2.Cu")
		(net "M_I_CPU1_SB_DQS_DP<0>")
	)
	(arc
		(start 144.694148 -276.031452)
		(mid 144.966822 -275.955765)
		(end 145.241772 -276.022816)
		(width 0.09525)
		(layer "In2.Cu")
		(net "M_I_CPU1_SB_DQS_DP<0>")
	)
	(arc
		(start 138.113262 -276.031452)
		(mid 138.394694 -275.955697)
		(end 138.676126 -276.031452)
		(width 0.09525)
		(layer "In2.Cu")
		(net "M_I_CPU1_SB_DQS_DP<0>")
	)
	(arc
		(start 134.3533 -276.031452)
		(mid 134.634732 -275.955697)
		(end 134.916164 -276.031452)
		(width 0.09525)
		(layer "In2.Cu")
		(net "M_I_CPU1_SB_DQS_DP<0>")
	)
	(arc
		(start 132.104638 -276.036278)
		(mid 132.28967 -276.082192)
		(end 132.473446 -276.031452)
		(width 0.09525)
		(layer "In2.Cu")
		(net "M_I_CPU1_SB_DQS_DP<0>")
	)
	(arc
		(start 143.768064 -276.022816)
		(mid 144.043523 -275.955431)
		(end 144.316704 -276.031452)
		(width 0.09525)
		(layer "In2.Cu")
		(net "M_I_CPU1_SB_DQS_DP<0>")
	)
	(arc
		(start 137.173208 -276.031452)
		(mid 137.45464 -275.955697)
		(end 137.736072 -276.031452)
		(width 0.09525)
		(layer "In2.Cu")
		(net "M_I_CPU1_SB_DQS_DP<0>")
	)
	(arc
		(start 133.97611 -276.031452)
		(mid 134.159885 -276.082224)
		(end 134.344918 -276.036278)
		(width 0.09525)
		(layer "In2.Cu")
		(net "M_I_CPU1_SB_DQS_DP<0>")
	)
	(arc
		(start 131.533392 -276.031452)
		(mid 131.814824 -275.955697)
		(end 132.096256 -276.031452)
		(width 0.09525)
		(layer "In2.Cu")
		(net "M_I_CPU1_SB_DQS_DP<0>")
	)
	(arc
		(start 129.719578 -275.998432)
		(mid 129.971719 -275.956862)
		(end 130.216148 -276.031452)
		(width 0.09525)
		(layer "In2.Cu")
		(net "M_I_CPU1_SB_DQS_DP<0>")
	)
	(arc
		(start 138.676126 -276.031452)
		(mid 138.859901 -276.082224)
		(end 139.044934 -276.036278)
		(width 0.09525)
		(layer "In2.Cu")
		(net "M_I_CPU1_SB_DQS_DP<0>")
	)
	(arc
		(start 137.736072 -276.031452)
		(mid 137.919847 -276.082224)
		(end 138.10488 -276.036278)
		(width 0.09525)
		(layer "In2.Cu")
		(net "M_I_CPU1_SB_DQS_DP<0>")
	)
	(arc
		(start 135.293354 -276.031452)
		(mid 135.574786 -275.955697)
		(end 135.856218 -276.031452)
		(width 0.09525)
		(layer "In2.Cu")
		(net "M_I_CPU1_SB_DQS_DP<0>")
	)
	(arc
		(start 130.216148 -276.031452)
		(mid 130.399923 -276.082224)
		(end 130.584956 -276.036278)
		(width 0.09525)
		(layer "In2.Cu")
		(net "M_I_CPU1_SB_DQS_DP<0>")
	)
	(arc
		(start 136.233408 -276.031452)
		(mid 136.51484 -275.955697)
		(end 136.796272 -276.031452)
		(width 0.09525)
		(layer "In2.Cu")
		(net "M_I_CPU1_SB_DQS_DP<0>")
	)
	(arc
		(start 134.924546 -276.036278)
		(mid 135.109578 -276.082192)
		(end 135.293354 -276.031452)
		(width 0.09525)
		(layer "In2.Cu")
		(net "M_I_CPU1_SB_DQS_DP<0>")
	)
	(arc
		(start 131.164584 -276.036278)
		(mid 131.349616 -276.082192)
		(end 131.533392 -276.031452)
		(width 0.09525)
		(layer "In2.Cu")
		(net "M_I_CPU1_SB_DQS_DP<0>")
	)
	(arc
		(start 140.564616 -276.036278)
		(mid 140.749648 -276.082192)
		(end 140.933424 -276.031452)
		(width 0.09525)
		(layer "In2.Cu")
		(net "M_I_CPU1_SB_DQS_DP<0>")
	)
	(arc
		(start 139.053316 -276.031452)
		(mid 139.334748 -275.955697)
		(end 139.61618 -276.031452)
		(width 0.09525)
		(layer "In2.Cu")
		(net "M_I_CPU1_SB_DQS_DP<0>")
	)
	(arc
		(start 142.813278 -276.031452)
		(mid 143.09471 -275.955697)
		(end 143.376142 -276.031452)
		(width 0.09525)
		(layer "In2.Cu")
		(net "M_I_CPU1_SB_DQS_DP<0>")
	)
	(arc
		(start 133.03631 -276.031452)
		(mid 133.224778 -276.082129)
		(end 133.413246 -276.031452)
		(width 0.09525)
		(layer "In2.Cu")
		(net "M_I_CPU1_SB_DQS_DP<0>")
	)
	(arc
		(start 141.873224 -276.031452)
		(mid 142.154656 -275.955697)
		(end 142.436088 -276.031452)
		(width 0.09525)
		(layer "In2.Cu")
		(net "M_I_CPU1_SB_DQS_DP<0>")
	)
	(arc
		(start 130.593338 -276.031452)
		(mid 130.87477 -275.955697)
		(end 131.156202 -276.031452)
		(width 0.09525)
		(layer "In2.Cu")
		(net "M_I_CPU1_SB_DQS_DP<0>")
	)
	(arc
		(start 139.624562 -276.036278)
		(mid 139.809594 -276.082192)
		(end 139.99337 -276.031452)
		(width 0.09525)
		(layer "In2.Cu")
		(net "M_I_CPU1_SB_DQS_DP<0>")
	)
	(arc
		(start 133.413246 -276.031452)
		(mid 133.694678 -275.955697)
		(end 133.97611 -276.031452)
		(width 0.09525)
		(layer "In2.Cu")
		(net "M_I_CPU1_SB_DQS_DP<0>")
	)
	(arc
		(start 135.8646 -276.036278)
		(mid 136.049632 -276.082192)
		(end 136.233408 -276.031452)
		(width 0.09525)
		(layer "In2.Cu")
		(net "M_I_CPU1_SB_DQS_DP<0>")
	)
	(arc
		(start 141.496288 -276.031452)
		(mid 141.684756 -276.082129)
		(end 141.873224 -276.031452)
		(width 0.09525)
		(layer "In2.Cu")
		(net "M_I_CPU1_SB_DQS_DP<0>")
	)
	(arc
		(start 140.933424 -276.031452)
		(mid 141.214856 -275.955697)
		(end 141.496288 -276.031452)
		(width 0.09525)
		(layer "In2.Cu")
		(net "M_I_CPU1_SB_DQS_DP<0>")
	)
	(arc
		(start 143.384524 -276.036278)
		(mid 143.569556 -276.082192)
		(end 143.753332 -276.031452)
		(width 0.09525)
		(layer "In2.Cu")
		(net "M_I_CPU1_SB_DQS_DP<0>")
	)
	(arc
		(start 145.633694 -276.031452)
		(mid 145.674218 -276.004497)
		(end 145.71091 -275.972524)
		(width 0.09525)
		(layer "In2.Cu")
		(net "M_I_CPU1_SB_DQS_DP<0>")
	)
	(arc
		(start 139.99337 -276.031452)
		(mid 140.274802 -275.955697)
		(end 140.556234 -276.031452)
		(width 0.09525)
		(layer "In2.Cu")
		(net "M_I_CPU1_SB_DQS_DP<0>")
	)
	(arc
		(start 144.316704 -276.031452)
		(mid 144.498574 -276.082317)
		(end 144.68221 -276.03831)
		(width 0.09525)
		(layer "In2.Cu")
		(net "M_I_CPU1_SB_DQS_DP<0>")
	)
	(segment
		(start 129.467864 -271.390364)
		(end 129.934716 -271.656302)
		(width 0.12954)
		(layer "F.Cu")
		(net "M_I_CPU1_SB_DQS_DN<9>")
	)
	(segment
		(start 147.3835 -269.496286)
		(end 147.621244 -269.496286)
		(width 0.09525)
		(layer "In2.Cu")
		(net "M_I_CPU1_SB_DQS_DN<9>")
	)
	(segment
		(start 183.343042 -276.112224)
		(end 183.616092 -276.385274)
		(width 0.16002)
		(layer "In2.Cu")
		(net "M_I_CPU1_SB_DQS_DN<9>")
	)
	(segment
		(start 167.473376 -275.428964)
		(end 167.78986 -275.11248)
		(width 0.16002)
		(layer "In2.Cu")
		(net "M_I_CPU1_SB_DQS_DN<9>")
	)
	(segment
		(start 131.99491 -271.326356)
		(end 132.003292 -271.331182)
		(width 0.09525)
		(layer "In2.Cu")
		(net "M_I_CPU1_SB_DQS_DN<9>")
	)
	(segment
		(start 136.694926 -271.326356)
		(end 136.703308 -271.331182)
		(width 0.09525)
		(layer "In2.Cu")
		(net "M_I_CPU1_SB_DQS_DN<9>")
	)
	(segment
		(start 181.276498 -276.295104)
		(end 181.459378 -276.112224)
		(width 0.16002)
		(layer "In2.Cu")
		(net "M_I_CPU1_SB_DQS_DN<9>")
	)
	(segment
		(start 173.05909 -276.269704)
		(end 173.651418 -276.269704)
		(width 0.16002)
		(layer "In2.Cu")
		(net "M_I_CPU1_SB_DQS_DN<9>")
	)
	(segment
		(start 146.88312 -269.377414)
		(end 147.264628 -269.377414)
		(width 0.09525)
		(layer "In2.Cu")
		(net "M_I_CPU1_SB_DQS_DN<9>")
	)
	(segment
		(start 135.754872 -271.326356)
		(end 135.763254 -271.331182)
		(width 0.09525)
		(layer "In2.Cu")
		(net "M_I_CPU1_SB_DQS_DN<9>")
	)
	(segment
		(start 129.780792 -271.390872)
		(end 129.80416 -271.304004)
		(width 0.09525)
		(layer "In2.Cu")
		(net "M_I_CPU1_SB_DQS_DN<9>")
	)
	(segment
		(start 180.62829 -276.295104)
		(end 181.276498 -276.295104)
		(width 0.16002)
		(layer "In2.Cu")
		(net "M_I_CPU1_SB_DQS_DN<9>")
	)
	(segment
		(start 165.515036 -276.269704)
		(end 166.107364 -276.269704)
		(width 0.16002)
		(layer "In2.Cu")
		(net "M_I_CPU1_SB_DQS_DN<9>")
	)
	(segment
		(start 137.266172 -271.331182)
		(end 137.274554 -271.326356)
		(width 0.09525)
		(layer "In2.Cu")
		(net "M_I_CPU1_SB_DQS_DN<9>")
	)
	(segment
		(start 180.019706 -275.68652)
		(end 180.62829 -276.295104)
		(width 0.16002)
		(layer "In2.Cu")
		(net "M_I_CPU1_SB_DQS_DN<9>")
	)
	(segment
		(start 174.492158 -275.428964)
		(end 175.01743 -275.428964)
		(width 0.16002)
		(layer "In2.Cu")
		(net "M_I_CPU1_SB_DQS_DN<9>")
	)
	(segment
		(start 169.76852 -275.11248)
		(end 170.34256 -275.68652)
		(width 0.16002)
		(layer "In2.Cu")
		(net "M_I_CPU1_SB_DQS_DN<9>")
	)
	(segment
		(start 172.475906 -275.68652)
		(end 173.05909 -276.269704)
		(width 0.16002)
		(layer "In2.Cu")
		(net "M_I_CPU1_SB_DQS_DN<9>")
	)
	(segment
		(start 177.360326 -275.11248)
		(end 178.746404 -275.68652)
		(width 0.16002)
		(layer "In2.Cu")
		(net "M_I_CPU1_SB_DQS_DN<9>")
	)
	(segment
		(start 170.34256 -275.68652)
		(end 172.475906 -275.68652)
		(width 0.16002)
		(layer "In2.Cu")
		(net "M_I_CPU1_SB_DQS_DN<9>")
	)
	(segment
		(start 156.504894 -269.555214)
		(end 162.2806 -275.33092)
		(width 0.16002)
		(layer "In2.Cu")
		(net "M_I_CPU1_SB_DQS_DN<9>")
	)
	(segment
		(start 147.621244 -269.496286)
		(end 147.680172 -269.555214)
		(width 0.09525)
		(layer "In2.Cu")
		(net "M_I_CPU1_SB_DQS_DN<9>")
	)
	(segment
		(start 138.206226 -271.331182)
		(end 138.214608 -271.326356)
		(width 0.09525)
		(layer "In2.Cu")
		(net "M_I_CPU1_SB_DQS_DN<9>")
	)
	(segment
		(start 140.454888 -271.326356)
		(end 140.46327 -271.331182)
		(width 0.09525)
		(layer "In2.Cu")
		(net "M_I_CPU1_SB_DQS_DN<9>")
	)
	(segment
		(start 182.056278 -276.229064)
		(end 182.536338 -276.229064)
		(width 0.16002)
		(layer "In2.Cu")
		(net "M_I_CPU1_SB_DQS_DN<9>")
	)
	(segment
		(start 147.264628 -269.377414)
		(end 147.3835 -269.496286)
		(width 0.09525)
		(layer "In2.Cu")
		(net "M_I_CPU1_SB_DQS_DN<9>")
	)
	(segment
		(start 163.138866 -275.68652)
		(end 164.931852 -275.68652)
		(width 0.16002)
		(layer "In2.Cu")
		(net "M_I_CPU1_SB_DQS_DN<9>")
	)
	(segment
		(start 146.234912 -269.82166)
		(end 146.569938 -269.486634)
		(width 0.09525)
		(layer "In2.Cu")
		(net "M_I_CPU1_SB_DQS_DN<9>")
	)
	(segment
		(start 173.651418 -276.269704)
		(end 174.492158 -275.428964)
		(width 0.16002)
		(layer "In2.Cu")
		(net "M_I_CPU1_SB_DQS_DN<9>")
	)
	(segment
		(start 175.333914 -275.11248)
		(end 177.360326 -275.11248)
		(width 0.16002)
		(layer "In2.Cu")
		(net "M_I_CPU1_SB_DQS_DN<9>")
	)
	(segment
		(start 181.939438 -276.112224)
		(end 182.056278 -276.229064)
		(width 0.16002)
		(layer "In2.Cu")
		(net "M_I_CPU1_SB_DQS_DN<9>")
	)
	(segment
		(start 146.7739 -269.486634)
		(end 146.88312 -269.377414)
		(width 0.09525)
		(layer "In2.Cu")
		(net "M_I_CPU1_SB_DQS_DN<9>")
	)
	(segment
		(start 147.703794 -269.555214)
		(end 156.504894 -269.555214)
		(width 0.16002)
		(layer "In2.Cu")
		(net "M_I_CPU1_SB_DQS_DN<9>")
	)
	(segment
		(start 182.536338 -276.229064)
		(end 182.653178 -276.112224)
		(width 0.16002)
		(layer "In2.Cu")
		(net "M_I_CPU1_SB_DQS_DN<9>")
	)
	(segment
		(start 178.746404 -275.68652)
		(end 180.019706 -275.68652)
		(width 0.16002)
		(layer "In2.Cu")
		(net "M_I_CPU1_SB_DQS_DN<9>")
	)
	(segment
		(start 166.107364 -276.269704)
		(end 166.948104 -275.428964)
		(width 0.16002)
		(layer "In2.Cu")
		(net "M_I_CPU1_SB_DQS_DN<9>")
	)
	(segment
		(start 145.99666 -270.39697)
		(end 146.234912 -269.82166)
		(width 0.09525)
		(layer "In2.Cu")
		(net "M_I_CPU1_SB_DQS_DN<9>")
	)
	(segment
		(start 166.948104 -275.428964)
		(end 167.473376 -275.428964)
		(width 0.16002)
		(layer "In2.Cu")
		(net "M_I_CPU1_SB_DQS_DN<9>")
	)
	(segment
		(start 133.50621 -271.331182)
		(end 133.514592 -271.326356)
		(width 0.09525)
		(layer "In2.Cu")
		(net "M_I_CPU1_SB_DQS_DN<9>")
	)
	(segment
		(start 132.934964 -271.326356)
		(end 132.943346 -271.331182)
		(width 0.09525)
		(layer "In2.Cu")
		(net "M_I_CPU1_SB_DQS_DN<9>")
	)
	(segment
		(start 141.966188 -271.331182)
		(end 141.97457 -271.326356)
		(width 0.09525)
		(layer "In2.Cu")
		(net "M_I_CPU1_SB_DQS_DN<9>")
	)
	(segment
		(start 145.725896 -271.331436)
		(end 145.725642 -271.330928)
		(width 0.09525)
		(layer "In2.Cu")
		(net "M_I_CPU1_SB_DQS_DN<9>")
	)
	(segment
		(start 164.931852 -275.68652)
		(end 165.515036 -276.269704)
		(width 0.16002)
		(layer "In2.Cu")
		(net "M_I_CPU1_SB_DQS_DN<9>")
	)
	(segment
		(start 167.78986 -275.11248)
		(end 169.76852 -275.11248)
		(width 0.16002)
		(layer "In2.Cu")
		(net "M_I_CPU1_SB_DQS_DN<9>")
	)
	(segment
		(start 147.680172 -269.555214)
		(end 147.703794 -269.555214)
		(width 0.09525)
		(layer "In2.Cu")
		(net "M_I_CPU1_SB_DQS_DN<9>")
	)
	(segment
		(start 129.934716 -271.656302)
		(end 129.780792 -271.390872)
		(width 0.09525)
		(layer "In2.Cu")
		(net "M_I_CPU1_SB_DQS_DN<9>")
	)
	(segment
		(start 181.459378 -276.112224)
		(end 181.939438 -276.112224)
		(width 0.16002)
		(layer "In2.Cu")
		(net "M_I_CPU1_SB_DQS_DN<9>")
	)
	(segment
		(start 146.569938 -269.486634)
		(end 146.7739 -269.486634)
		(width 0.09525)
		(layer "In2.Cu")
		(net "M_I_CPU1_SB_DQS_DN<9>")
	)
	(segment
		(start 162.2806 -275.33092)
		(end 163.138866 -275.68652)
		(width 0.16002)
		(layer "In2.Cu")
		(net "M_I_CPU1_SB_DQS_DN<9>")
	)
	(segment
		(start 141.394942 -271.326356)
		(end 141.403324 -271.331182)
		(width 0.09525)
		(layer "In2.Cu")
		(net "M_I_CPU1_SB_DQS_DN<9>")
	)
	(segment
		(start 145.99666 -270.892016)
		(end 145.99666 -270.39697)
		(width 0.09525)
		(layer "In2.Cu")
		(net "M_I_CPU1_SB_DQS_DN<9>")
	)
	(segment
		(start 182.653178 -276.112224)
		(end 183.343042 -276.112224)
		(width 0.16002)
		(layer "In2.Cu")
		(net "M_I_CPU1_SB_DQS_DN<9>")
	)
	(segment
		(start 175.01743 -275.428964)
		(end 175.333914 -275.11248)
		(width 0.16002)
		(layer "In2.Cu")
		(net "M_I_CPU1_SB_DQS_DN<9>")
	)
	(arc
		(start 141.97457 -271.326356)
		(mid 142.159602 -271.280442)
		(end 142.343378 -271.331182)
		(width 0.09525)
		(layer "In2.Cu")
		(net "M_I_CPU1_SB_DQS_DN<9>")
	)
	(arc
		(start 136.326118 -271.331182)
		(mid 136.509893 -271.28041)
		(end 136.694926 -271.326356)
		(width 0.09525)
		(layer "In2.Cu")
		(net "M_I_CPU1_SB_DQS_DN<9>")
	)
	(arc
		(start 133.514592 -271.326356)
		(mid 133.699624 -271.280442)
		(end 133.8834 -271.331182)
		(width 0.09525)
		(layer "In2.Cu")
		(net "M_I_CPU1_SB_DQS_DN<9>")
	)
	(arc
		(start 135.763254 -271.331182)
		(mid 136.044686 -271.406937)
		(end 136.326118 -271.331182)
		(width 0.09525)
		(layer "In2.Cu")
		(net "M_I_CPU1_SB_DQS_DN<9>")
	)
	(arc
		(start 145.725642 -271.330928)
		(mid 145.916348 -271.145538)
		(end 145.99666 -270.892016)
		(width 0.09525)
		(layer "In2.Cu")
		(net "M_I_CPU1_SB_DQS_DN<9>")
	)
	(arc
		(start 130.123438 -271.331182)
		(mid 130.40487 -271.406937)
		(end 130.686302 -271.331182)
		(width 0.09525)
		(layer "In2.Cu")
		(net "M_I_CPU1_SB_DQS_DN<9>")
	)
	(arc
		(start 134.446264 -271.331182)
		(mid 134.634732 -271.280505)
		(end 134.8232 -271.331182)
		(width 0.09525)
		(layer "In2.Cu")
		(net "M_I_CPU1_SB_DQS_DN<9>")
	)
	(arc
		(start 137.643362 -271.331182)
		(mid 137.924794 -271.406937)
		(end 138.206226 -271.331182)
		(width 0.09525)
		(layer "In2.Cu")
		(net "M_I_CPU1_SB_DQS_DN<9>")
	)
	(arc
		(start 129.80416 -271.304004)
		(mid 129.966842 -271.281872)
		(end 130.123438 -271.331182)
		(width 0.09525)
		(layer "In2.Cu")
		(net "M_I_CPU1_SB_DQS_DN<9>")
	)
	(arc
		(start 139.14628 -271.331182)
		(mid 139.334748 -271.280505)
		(end 139.523216 -271.331182)
		(width 0.09525)
		(layer "In2.Cu")
		(net "M_I_CPU1_SB_DQS_DN<9>")
	)
	(arc
		(start 137.274554 -271.326356)
		(mid 137.459586 -271.280442)
		(end 137.643362 -271.331182)
		(width 0.09525)
		(layer "In2.Cu")
		(net "M_I_CPU1_SB_DQS_DN<9>")
	)
	(arc
		(start 136.703308 -271.331182)
		(mid 136.98474 -271.406937)
		(end 137.266172 -271.331182)
		(width 0.09525)
		(layer "In2.Cu")
		(net "M_I_CPU1_SB_DQS_DN<9>")
	)
	(arc
		(start 138.214608 -271.326356)
		(mid 138.39964 -271.280442)
		(end 138.583416 -271.331182)
		(width 0.09525)
		(layer "In2.Cu")
		(net "M_I_CPU1_SB_DQS_DN<9>")
	)
	(arc
		(start 143.846042 -271.331182)
		(mid 144.034764 -271.280378)
		(end 144.223486 -271.331182)
		(width 0.09525)
		(layer "In2.Cu")
		(net "M_I_CPU1_SB_DQS_DN<9>")
	)
	(arc
		(start 131.063238 -271.331182)
		(mid 131.34467 -271.406937)
		(end 131.626102 -271.331182)
		(width 0.09525)
		(layer "In2.Cu")
		(net "M_I_CPU1_SB_DQS_DN<9>")
	)
	(arc
		(start 138.583416 -271.331182)
		(mid 138.864848 -271.406937)
		(end 139.14628 -271.331182)
		(width 0.09525)
		(layer "In2.Cu")
		(net "M_I_CPU1_SB_DQS_DN<9>")
	)
	(arc
		(start 141.026134 -271.331182)
		(mid 141.209909 -271.28041)
		(end 141.394942 -271.326356)
		(width 0.09525)
		(layer "In2.Cu")
		(net "M_I_CPU1_SB_DQS_DN<9>")
	)
	(arc
		(start 134.8232 -271.331182)
		(mid 135.104632 -271.406937)
		(end 135.386064 -271.331182)
		(width 0.09525)
		(layer "In2.Cu")
		(net "M_I_CPU1_SB_DQS_DN<9>")
	)
	(arc
		(start 139.523216 -271.331182)
		(mid 139.804648 -271.406937)
		(end 140.08608 -271.331182)
		(width 0.09525)
		(layer "In2.Cu")
		(net "M_I_CPU1_SB_DQS_DN<9>")
	)
	(arc
		(start 135.386064 -271.331182)
		(mid 135.569839 -271.28041)
		(end 135.754872 -271.326356)
		(width 0.09525)
		(layer "In2.Cu")
		(net "M_I_CPU1_SB_DQS_DN<9>")
	)
	(arc
		(start 140.46327 -271.331182)
		(mid 140.744702 -271.406937)
		(end 141.026134 -271.331182)
		(width 0.09525)
		(layer "In2.Cu")
		(net "M_I_CPU1_SB_DQS_DN<9>")
	)
	(arc
		(start 132.003292 -271.331182)
		(mid 132.284724 -271.406937)
		(end 132.566156 -271.331182)
		(width 0.09525)
		(layer "In2.Cu")
		(net "M_I_CPU1_SB_DQS_DN<9>")
	)
	(arc
		(start 142.906242 -271.331182)
		(mid 143.09471 -271.280505)
		(end 143.283178 -271.331182)
		(width 0.09525)
		(layer "In2.Cu")
		(net "M_I_CPU1_SB_DQS_DN<9>")
	)
	(arc
		(start 145.163286 -271.331182)
		(mid 145.444544 -271.406937)
		(end 145.725896 -271.331436)
		(width 0.09525)
		(layer "In2.Cu")
		(net "M_I_CPU1_SB_DQS_DN<9>")
	)
	(arc
		(start 141.403324 -271.331182)
		(mid 141.684756 -271.406937)
		(end 141.966188 -271.331182)
		(width 0.09525)
		(layer "In2.Cu")
		(net "M_I_CPU1_SB_DQS_DN<9>")
	)
	(arc
		(start 142.343378 -271.331182)
		(mid 142.62481 -271.406937)
		(end 142.906242 -271.331182)
		(width 0.09525)
		(layer "In2.Cu")
		(net "M_I_CPU1_SB_DQS_DN<9>")
	)
	(arc
		(start 133.8834 -271.331182)
		(mid 134.164832 -271.406937)
		(end 134.446264 -271.331182)
		(width 0.09525)
		(layer "In2.Cu")
		(net "M_I_CPU1_SB_DQS_DN<9>")
	)
	(arc
		(start 143.283178 -271.331182)
		(mid 143.56461 -271.406937)
		(end 143.846042 -271.331182)
		(width 0.09525)
		(layer "In2.Cu")
		(net "M_I_CPU1_SB_DQS_DN<9>")
	)
	(arc
		(start 131.626102 -271.331182)
		(mid 131.809877 -271.28041)
		(end 131.99491 -271.326356)
		(width 0.09525)
		(layer "In2.Cu")
		(net "M_I_CPU1_SB_DQS_DN<9>")
	)
	(arc
		(start 144.223486 -271.331182)
		(mid 144.504918 -271.406937)
		(end 144.78635 -271.331182)
		(width 0.09525)
		(layer "In2.Cu")
		(net "M_I_CPU1_SB_DQS_DN<9>")
	)
	(arc
		(start 132.943346 -271.331182)
		(mid 133.224778 -271.406937)
		(end 133.50621 -271.331182)
		(width 0.09525)
		(layer "In2.Cu")
		(net "M_I_CPU1_SB_DQS_DN<9>")
	)
	(arc
		(start 132.566156 -271.331182)
		(mid 132.749931 -271.28041)
		(end 132.934964 -271.326356)
		(width 0.09525)
		(layer "In2.Cu")
		(net "M_I_CPU1_SB_DQS_DN<9>")
	)
	(arc
		(start 140.08608 -271.331182)
		(mid 140.269855 -271.28041)
		(end 140.454888 -271.326356)
		(width 0.09525)
		(layer "In2.Cu")
		(net "M_I_CPU1_SB_DQS_DN<9>")
	)
	(arc
		(start 130.686302 -271.331182)
		(mid 130.87477 -271.280505)
		(end 131.063238 -271.331182)
		(width 0.09525)
		(layer "In2.Cu")
		(net "M_I_CPU1_SB_DQS_DN<9>")
	)
	(arc
		(start 144.78635 -271.331182)
		(mid 144.974818 -271.280505)
		(end 145.163286 -271.331182)
		(width 0.09525)
		(layer "In2.Cu")
		(net "M_I_CPU1_SB_DQS_DN<9>")
	)
	(segment
		(start 127.58801 -290.830254)
		(end 128.054862 -291.096192)
		(width 0.12954)
		(layer "F.Cu")
		(net "M_I_CPU1_SB_DQS_DN<8>")
	)
	(segment
		(start 152.196292 -305.02098)
		(end 152.451562 -305.27625)
		(width 0.16002)
		(layer "In2.Cu")
		(net "M_I_CPU1_SB_DQS_DN<8>")
	)
	(segment
		(start 150.82266 -303.647348)
		(end 151.07793 -303.902618)
		(width 0.16002)
		(layer "In2.Cu")
		(net "M_I_CPU1_SB_DQS_DN<8>")
	)
	(segment
		(start 141.394942 -291.426138)
		(end 141.403324 -291.421312)
		(width 0.09525)
		(layer "In2.Cu")
		(net "M_I_CPU1_SB_DQS_DN<8>")
	)
	(segment
		(start 151.07793 -303.902618)
		(end 151.763222 -303.902618)
		(width 0.16002)
		(layer "In2.Cu")
		(net "M_I_CPU1_SB_DQS_DN<8>")
	)
	(segment
		(start 144.75333 -294.64254)
		(end 144.785842 -294.661336)
		(width 0.09525)
		(layer "In2.Cu")
		(net "M_I_CPU1_SB_DQS_DN<8>")
	)
	(segment
		(start 174.33163 -313.90082)
		(end 174.995078 -313.90082)
		(width 0.16002)
		(layer "In2.Cu")
		(net "M_I_CPU1_SB_DQS_DN<8>")
	)
	(segment
		(start 148.330666 -301.155354)
		(end 149.015958 -301.155354)
		(width 0.16002)
		(layer "In2.Cu")
		(net "M_I_CPU1_SB_DQS_DN<8>")
	)
	(segment
		(start 179.24145 -314.059824)
		(end 179.516024 -313.78525)
		(width 0.16002)
		(layer "In2.Cu")
		(net "M_I_CPU1_SB_DQS_DN<8>")
	)
	(segment
		(start 145.761456 -297.130216)
		(end 146.790918 -299.615606)
		(width 0.16002)
		(layer "In2.Cu")
		(net "M_I_CPU1_SB_DQS_DN<8>")
	)
	(segment
		(start 143.814546 -293.023036)
		(end 143.846042 -293.041324)
		(width 0.09525)
		(layer "In2.Cu")
		(net "M_I_CPU1_SB_DQS_DN<8>")
	)
	(segment
		(start 129.746248 -291.421312)
		(end 129.75463 -291.426138)
		(width 0.09525)
		(layer "In2.Cu")
		(net "M_I_CPU1_SB_DQS_DN<8>")
	)
	(segment
		(start 145.761456 -296.383202)
		(end 145.761456 -296.406824)
		(width 0.09525)
		(layer "In2.Cu")
		(net "M_I_CPU1_SB_DQS_DN<8>")
	)
	(segment
		(start 128.208786 -291.361622)
		(end 128.309624 -291.388292)
		(width 0.09525)
		(layer "In2.Cu")
		(net "M_I_CPU1_SB_DQS_DN<8>")
	)
	(segment
		(start 170.497754 -314.484004)
		(end 171.072048 -315.058298)
		(width 0.16002)
		(layer "In2.Cu")
		(net "M_I_CPU1_SB_DQS_DN<8>")
	)
	(segment
		(start 174.995078 -313.90082)
		(end 175.578262 -314.484004)
		(width 0.16002)
		(layer "In2.Cu")
		(net "M_I_CPU1_SB_DQS_DN<8>")
	)
	(segment
		(start 165.193472 -315.058044)
		(end 165.558216 -314.6933)
		(width 0.16002)
		(layer "In2.Cu")
		(net "M_I_CPU1_SB_DQS_DN<8>")
	)
	(segment
		(start 165.995096 -314.6933)
		(end 166.787576 -313.90082)
		(width 0.16002)
		(layer "In2.Cu")
		(net "M_I_CPU1_SB_DQS_DN<8>")
	)
	(segment
		(start 168.034208 -314.484004)
		(end 170.497754 -314.484004)
		(width 0.16002)
		(layer "In2.Cu")
		(net "M_I_CPU1_SB_DQS_DN<8>")
	)
	(segment
		(start 177.870866 -313.942984)
		(end 178.350926 -313.942984)
		(width 0.16002)
		(layer "In2.Cu")
		(net "M_I_CPU1_SB_DQS_DN<8>")
	)
	(segment
		(start 153.569924 -305.70932)
		(end 153.569924 -306.394612)
		(width 0.16002)
		(layer "In2.Cu")
		(net "M_I_CPU1_SB_DQS_DN<8>")
	)
	(segment
		(start 162.233356 -315.058044)
		(end 165.193472 -315.058044)
		(width 0.16002)
		(layer "In2.Cu")
		(net "M_I_CPU1_SB_DQS_DN<8>")
	)
	(segment
		(start 152.196292 -304.335688)
		(end 152.196292 -305.02098)
		(width 0.16002)
		(layer "In2.Cu")
		(net "M_I_CPU1_SB_DQS_DN<8>")
	)
	(segment
		(start 149.449028 -302.273716)
		(end 149.704298 -302.528986)
		(width 0.16002)
		(layer "In2.Cu")
		(net "M_I_CPU1_SB_DQS_DN<8>")
	)
	(segment
		(start 177.273966 -314.059824)
		(end 177.754026 -314.059824)
		(width 0.16002)
		(layer "In2.Cu")
		(net "M_I_CPU1_SB_DQS_DN<8>")
	)
	(segment
		(start 150.38959 -302.528986)
		(end 150.82266 -302.962056)
		(width 0.16002)
		(layer "In2.Cu")
		(net "M_I_CPU1_SB_DQS_DN<8>")
	)
	(segment
		(start 178.350926 -313.942984)
		(end 178.467766 -314.059824)
		(width 0.16002)
		(layer "In2.Cu")
		(net "M_I_CPU1_SB_DQS_DN<8>")
	)
	(segment
		(start 138.206226 -291.421312)
		(end 138.214608 -291.426138)
		(width 0.09525)
		(layer "In2.Cu")
		(net "M_I_CPU1_SB_DQS_DN<8>")
	)
	(segment
		(start 144.785842 -294.661336)
		(end 144.823942 -294.683434)
		(width 0.09525)
		(layer "In2.Cu")
		(net "M_I_CPU1_SB_DQS_DN<8>")
	)
	(segment
		(start 143.376142 -292.231318)
		(end 143.414242 -292.253416)
		(width 0.09525)
		(layer "In2.Cu")
		(net "M_I_CPU1_SB_DQS_DN<8>")
	)
	(segment
		(start 177.754026 -314.059824)
		(end 177.870866 -313.942984)
		(width 0.16002)
		(layer "In2.Cu")
		(net "M_I_CPU1_SB_DQS_DN<8>")
	)
	(segment
		(start 149.015958 -301.155354)
		(end 149.449028 -301.588424)
		(width 0.16002)
		(layer "In2.Cu")
		(net "M_I_CPU1_SB_DQS_DN<8>")
	)
	(segment
		(start 140.454888 -291.426138)
		(end 140.455904 -291.42563)
		(width 0.09525)
		(layer "In2.Cu")
		(net "M_I_CPU1_SB_DQS_DN<8>")
	)
	(segment
		(start 176.849786 -314.484004)
		(end 177.273966 -314.059824)
		(width 0.16002)
		(layer "In2.Cu")
		(net "M_I_CPU1_SB_DQS_DN<8>")
	)
	(segment
		(start 165.558216 -314.6933)
		(end 165.995096 -314.6933)
		(width 0.16002)
		(layer "In2.Cu")
		(net "M_I_CPU1_SB_DQS_DN<8>")
	)
	(segment
		(start 128.054862 -291.096192)
		(end 128.208786 -291.361622)
		(width 0.09525)
		(layer "In2.Cu")
		(net "M_I_CPU1_SB_DQS_DN<8>")
	)
	(segment
		(start 150.82266 -302.962056)
		(end 150.82266 -303.647348)
		(width 0.16002)
		(layer "In2.Cu")
		(net "M_I_CPU1_SB_DQS_DN<8>")
	)
	(segment
		(start 149.704298 -302.528986)
		(end 150.38959 -302.528986)
		(width 0.16002)
		(layer "In2.Cu")
		(net "M_I_CPU1_SB_DQS_DN<8>")
	)
	(segment
		(start 167.451024 -313.90082)
		(end 168.034208 -314.484004)
		(width 0.16002)
		(layer "In2.Cu")
		(net "M_I_CPU1_SB_DQS_DN<8>")
	)
	(segment
		(start 145.27657 -295.483788)
		(end 145.702274 -295.909492)
		(width 0.09525)
		(layer "In2.Cu")
		(net "M_I_CPU1_SB_DQS_DN<8>")
	)
	(segment
		(start 172.737272 -315.058298)
		(end 173.10227 -314.6933)
		(width 0.16002)
		(layer "In2.Cu")
		(net "M_I_CPU1_SB_DQS_DN<8>")
	)
	(segment
		(start 145.761456 -296.406824)
		(end 145.761456 -297.130216)
		(width 0.16002)
		(layer "In2.Cu")
		(net "M_I_CPU1_SB_DQS_DN<8>")
	)
	(segment
		(start 135.754872 -291.426138)
		(end 135.763254 -291.421312)
		(width 0.09525)
		(layer "In2.Cu")
		(net "M_I_CPU1_SB_DQS_DN<8>")
	)
	(segment
		(start 128.806194 -291.421312)
		(end 128.814576 -291.426138)
		(width 0.09525)
		(layer "In2.Cu")
		(net "M_I_CPU1_SB_DQS_DN<8>")
	)
	(segment
		(start 146.957034 -299.781722)
		(end 147.642326 -299.781722)
		(width 0.16002)
		(layer "In2.Cu")
		(net "M_I_CPU1_SB_DQS_DN<8>")
	)
	(segment
		(start 136.694926 -291.426138)
		(end 136.703308 -291.421312)
		(width 0.09525)
		(layer "In2.Cu")
		(net "M_I_CPU1_SB_DQS_DN<8>")
	)
	(segment
		(start 142.906242 -291.421312)
		(end 142.941294 -291.441886)
		(width 0.09525)
		(layer "In2.Cu")
		(net "M_I_CPU1_SB_DQS_DN<8>")
	)
	(segment
		(start 175.578262 -314.484004)
		(end 176.849786 -314.484004)
		(width 0.16002)
		(layer "In2.Cu")
		(net "M_I_CPU1_SB_DQS_DN<8>")
	)
	(segment
		(start 131.99491 -291.426138)
		(end 132.003292 -291.421312)
		(width 0.09525)
		(layer "In2.Cu")
		(net "M_I_CPU1_SB_DQS_DN<8>")
	)
	(segment
		(start 144.315942 -293.85133)
		(end 144.350994 -293.871904)
		(width 0.09525)
		(layer "In2.Cu")
		(net "M_I_CPU1_SB_DQS_DN<8>")
	)
	(segment
		(start 173.10227 -314.6933)
		(end 173.53915 -314.6933)
		(width 0.16002)
		(layer "In2.Cu")
		(net "M_I_CPU1_SB_DQS_DN<8>")
	)
	(segment
		(start 145.702274 -296.32402)
		(end 145.761456 -296.383202)
		(width 0.09525)
		(layer "In2.Cu")
		(net "M_I_CPU1_SB_DQS_DN<8>")
	)
	(segment
		(start 153.569924 -306.394612)
		(end 162.233356 -315.058044)
		(width 0.16002)
		(layer "In2.Cu")
		(net "M_I_CPU1_SB_DQS_DN<8>")
	)
	(segment
		(start 137.266172 -291.421312)
		(end 137.274554 -291.426138)
		(width 0.09525)
		(layer "In2.Cu")
		(net "M_I_CPU1_SB_DQS_DN<8>")
	)
	(segment
		(start 153.136854 -305.27625)
		(end 153.569924 -305.70932)
		(width 0.16002)
		(layer "In2.Cu")
		(net "M_I_CPU1_SB_DQS_DN<8>")
	)
	(segment
		(start 144.284446 -293.833042)
		(end 144.315942 -293.85133)
		(width 0.09525)
		(layer "In2.Cu")
		(net "M_I_CPU1_SB_DQS_DN<8>")
	)
	(segment
		(start 146.790918 -299.615606)
		(end 146.957034 -299.781722)
		(width 0.16002)
		(layer "In2.Cu")
		(net "M_I_CPU1_SB_DQS_DN<8>")
	)
	(segment
		(start 149.449028 -301.588424)
		(end 149.449028 -302.273716)
		(width 0.16002)
		(layer "In2.Cu")
		(net "M_I_CPU1_SB_DQS_DN<8>")
	)
	(segment
		(start 166.787576 -313.90082)
		(end 167.451024 -313.90082)
		(width 0.16002)
		(layer "In2.Cu")
		(net "M_I_CPU1_SB_DQS_DN<8>")
	)
	(segment
		(start 147.642326 -299.781722)
		(end 148.075396 -300.214792)
		(width 0.16002)
		(layer "In2.Cu")
		(net "M_I_CPU1_SB_DQS_DN<8>")
	)
	(segment
		(start 148.075396 -300.900084)
		(end 148.330666 -301.155354)
		(width 0.16002)
		(layer "In2.Cu")
		(net "M_I_CPU1_SB_DQS_DN<8>")
	)
	(segment
		(start 148.075396 -300.214792)
		(end 148.075396 -300.900084)
		(width 0.16002)
		(layer "In2.Cu")
		(net "M_I_CPU1_SB_DQS_DN<8>")
	)
	(segment
		(start 145.221452 -295.451276)
		(end 145.25625 -295.471342)
		(width 0.09525)
		(layer "In2.Cu")
		(net "M_I_CPU1_SB_DQS_DN<8>")
	)
	(segment
		(start 178.467766 -314.059824)
		(end 179.24145 -314.059824)
		(width 0.16002)
		(layer "In2.Cu")
		(net "M_I_CPU1_SB_DQS_DN<8>")
	)
	(segment
		(start 143.34363 -292.212522)
		(end 143.376142 -292.231318)
		(width 0.09525)
		(layer "In2.Cu")
		(net "M_I_CPU1_SB_DQS_DN<8>")
	)
	(segment
		(start 141.966188 -291.421312)
		(end 141.97457 -291.426138)
		(width 0.09525)
		(layer "In2.Cu")
		(net "M_I_CPU1_SB_DQS_DN<8>")
	)
	(segment
		(start 173.53915 -314.6933)
		(end 174.33163 -313.90082)
		(width 0.16002)
		(layer "In2.Cu")
		(net "M_I_CPU1_SB_DQS_DN<8>")
	)
	(segment
		(start 143.846042 -293.041324)
		(end 143.884142 -293.063422)
		(width 0.09525)
		(layer "In2.Cu")
		(net "M_I_CPU1_SB_DQS_DN<8>")
	)
	(segment
		(start 140.455904 -291.42563)
		(end 140.46327 -291.421312)
		(width 0.09525)
		(layer "In2.Cu")
		(net "M_I_CPU1_SB_DQS_DN<8>")
	)
	(segment
		(start 171.072048 -315.058298)
		(end 172.737272 -315.058298)
		(width 0.16002)
		(layer "In2.Cu")
		(net "M_I_CPU1_SB_DQS_DN<8>")
	)
	(segment
		(start 151.763222 -303.902618)
		(end 152.196292 -304.335688)
		(width 0.16002)
		(layer "In2.Cu")
		(net "M_I_CPU1_SB_DQS_DN<8>")
	)
	(segment
		(start 145.702274 -295.909492)
		(end 145.702274 -296.32402)
		(width 0.09525)
		(layer "In2.Cu")
		(net "M_I_CPU1_SB_DQS_DN<8>")
	)
	(segment
		(start 133.50621 -291.421312)
		(end 133.514592 -291.426138)
		(width 0.09525)
		(layer "In2.Cu")
		(net "M_I_CPU1_SB_DQS_DN<8>")
	)
	(segment
		(start 132.934964 -291.426138)
		(end 132.943346 -291.421312)
		(width 0.09525)
		(layer "In2.Cu")
		(net "M_I_CPU1_SB_DQS_DN<8>")
	)
	(segment
		(start 145.25625 -295.471342)
		(end 145.27657 -295.483788)
		(width 0.09525)
		(layer "In2.Cu")
		(net "M_I_CPU1_SB_DQS_DN<8>")
	)
	(segment
		(start 152.451562 -305.27625)
		(end 153.136854 -305.27625)
		(width 0.16002)
		(layer "In2.Cu")
		(net "M_I_CPU1_SB_DQS_DN<8>")
	)
	(arc
		(start 139.14628 -291.421312)
		(mid 139.334748 -291.471989)
		(end 139.523216 -291.421312)
		(width 0.09525)
		(layer "In2.Cu")
		(net "M_I_CPU1_SB_DQS_DN<8>")
	)
	(arc
		(start 143.657066 -292.716204)
		(mid 143.698731 -292.888651)
		(end 143.814546 -293.023036)
		(width 0.09525)
		(layer "In2.Cu")
		(net "M_I_CPU1_SB_DQS_DN<8>")
	)
	(arc
		(start 128.814576 -291.426138)
		(mid 128.999608 -291.472052)
		(end 129.183384 -291.421312)
		(width 0.09525)
		(layer "In2.Cu")
		(net "M_I_CPU1_SB_DQS_DN<8>")
	)
	(arc
		(start 141.026134 -291.421312)
		(mid 141.209909 -291.472084)
		(end 141.394942 -291.426138)
		(width 0.09525)
		(layer "In2.Cu")
		(net "M_I_CPU1_SB_DQS_DN<8>")
	)
	(arc
		(start 132.943346 -291.421312)
		(mid 133.224778 -291.345557)
		(end 133.50621 -291.421312)
		(width 0.09525)
		(layer "In2.Cu")
		(net "M_I_CPU1_SB_DQS_DN<8>")
	)
	(arc
		(start 129.183384 -291.421312)
		(mid 129.464816 -291.345557)
		(end 129.746248 -291.421312)
		(width 0.09525)
		(layer "In2.Cu")
		(net "M_I_CPU1_SB_DQS_DN<8>")
	)
	(arc
		(start 131.063238 -291.421312)
		(mid 131.34467 -291.345557)
		(end 131.626102 -291.421312)
		(width 0.09525)
		(layer "In2.Cu")
		(net "M_I_CPU1_SB_DQS_DN<8>")
	)
	(arc
		(start 132.003292 -291.421312)
		(mid 132.284724 -291.345557)
		(end 132.566156 -291.421312)
		(width 0.09525)
		(layer "In2.Cu")
		(net "M_I_CPU1_SB_DQS_DN<8>")
	)
	(arc
		(start 142.941294 -291.441886)
		(mid 143.121685 -291.643585)
		(end 143.186912 -291.906198)
		(width 0.09525)
		(layer "In2.Cu")
		(net "M_I_CPU1_SB_DQS_DN<8>")
	)
	(arc
		(start 140.46327 -291.421312)
		(mid 140.744702 -291.345557)
		(end 141.026134 -291.421312)
		(width 0.09525)
		(layer "In2.Cu")
		(net "M_I_CPU1_SB_DQS_DN<8>")
	)
	(arc
		(start 142.343378 -291.421312)
		(mid 142.62481 -291.345557)
		(end 142.906242 -291.421312)
		(width 0.09525)
		(layer "In2.Cu")
		(net "M_I_CPU1_SB_DQS_DN<8>")
	)
	(arc
		(start 144.126966 -293.52621)
		(mid 144.168631 -293.698657)
		(end 144.284446 -293.833042)
		(width 0.09525)
		(layer "In2.Cu")
		(net "M_I_CPU1_SB_DQS_DN<8>")
	)
	(arc
		(start 143.884142 -293.063422)
		(mid 144.062592 -293.264892)
		(end 144.126966 -293.52621)
		(width 0.09525)
		(layer "In2.Cu")
		(net "M_I_CPU1_SB_DQS_DN<8>")
	)
	(arc
		(start 138.214608 -291.426138)
		(mid 138.39964 -291.472052)
		(end 138.583416 -291.421312)
		(width 0.09525)
		(layer "In2.Cu")
		(net "M_I_CPU1_SB_DQS_DN<8>")
	)
	(arc
		(start 138.583416 -291.421312)
		(mid 138.864848 -291.345557)
		(end 139.14628 -291.421312)
		(width 0.09525)
		(layer "In2.Cu")
		(net "M_I_CPU1_SB_DQS_DN<8>")
	)
	(arc
		(start 131.626102 -291.421312)
		(mid 131.809877 -291.472084)
		(end 131.99491 -291.426138)
		(width 0.09525)
		(layer "In2.Cu")
		(net "M_I_CPU1_SB_DQS_DN<8>")
	)
	(arc
		(start 136.326118 -291.421312)
		(mid 136.509893 -291.472084)
		(end 136.694926 -291.426138)
		(width 0.09525)
		(layer "In2.Cu")
		(net "M_I_CPU1_SB_DQS_DN<8>")
	)
	(arc
		(start 141.403324 -291.421312)
		(mid 141.684756 -291.345557)
		(end 141.966188 -291.421312)
		(width 0.09525)
		(layer "In2.Cu")
		(net "M_I_CPU1_SB_DQS_DN<8>")
	)
	(arc
		(start 134.446264 -291.421312)
		(mid 134.634732 -291.471989)
		(end 134.8232 -291.421312)
		(width 0.09525)
		(layer "In2.Cu")
		(net "M_I_CPU1_SB_DQS_DN<8>")
	)
	(arc
		(start 135.386064 -291.421312)
		(mid 135.569839 -291.472084)
		(end 135.754872 -291.426138)
		(width 0.09525)
		(layer "In2.Cu")
		(net "M_I_CPU1_SB_DQS_DN<8>")
	)
	(arc
		(start 143.414242 -292.253416)
		(mid 143.592692 -292.454886)
		(end 143.657066 -292.716204)
		(width 0.09525)
		(layer "In2.Cu")
		(net "M_I_CPU1_SB_DQS_DN<8>")
	)
	(arc
		(start 128.309624 -291.388292)
		(mid 128.561765 -291.346722)
		(end 128.806194 -291.421312)
		(width 0.09525)
		(layer "In2.Cu")
		(net "M_I_CPU1_SB_DQS_DN<8>")
	)
	(arc
		(start 134.8232 -291.421312)
		(mid 135.104632 -291.345557)
		(end 135.386064 -291.421312)
		(width 0.09525)
		(layer "In2.Cu")
		(net "M_I_CPU1_SB_DQS_DN<8>")
	)
	(arc
		(start 139.523216 -291.421312)
		(mid 139.804648 -291.345557)
		(end 140.08608 -291.421312)
		(width 0.09525)
		(layer "In2.Cu")
		(net "M_I_CPU1_SB_DQS_DN<8>")
	)
	(arc
		(start 130.123438 -291.421312)
		(mid 130.40487 -291.345557)
		(end 130.686302 -291.421312)
		(width 0.09525)
		(layer "In2.Cu")
		(net "M_I_CPU1_SB_DQS_DN<8>")
	)
	(arc
		(start 136.703308 -291.421312)
		(mid 136.98474 -291.345557)
		(end 137.266172 -291.421312)
		(width 0.09525)
		(layer "In2.Cu")
		(net "M_I_CPU1_SB_DQS_DN<8>")
	)
	(arc
		(start 129.75463 -291.426138)
		(mid 129.939662 -291.472052)
		(end 130.123438 -291.421312)
		(width 0.09525)
		(layer "In2.Cu")
		(net "M_I_CPU1_SB_DQS_DN<8>")
	)
	(arc
		(start 145.066766 -295.146222)
		(mid 145.107642 -295.317244)
		(end 145.221452 -295.451276)
		(width 0.09525)
		(layer "In2.Cu")
		(net "M_I_CPU1_SB_DQS_DN<8>")
	)
	(arc
		(start 141.97457 -291.426138)
		(mid 142.159602 -291.472052)
		(end 142.343378 -291.421312)
		(width 0.09525)
		(layer "In2.Cu")
		(net "M_I_CPU1_SB_DQS_DN<8>")
	)
	(arc
		(start 130.686302 -291.421312)
		(mid 130.87477 -291.471989)
		(end 131.063238 -291.421312)
		(width 0.09525)
		(layer "In2.Cu")
		(net "M_I_CPU1_SB_DQS_DN<8>")
	)
	(arc
		(start 132.566156 -291.421312)
		(mid 132.749931 -291.472084)
		(end 132.934964 -291.426138)
		(width 0.09525)
		(layer "In2.Cu")
		(net "M_I_CPU1_SB_DQS_DN<8>")
	)
	(arc
		(start 144.596612 -294.336216)
		(mid 144.638069 -294.508256)
		(end 144.75333 -294.64254)
		(width 0.09525)
		(layer "In2.Cu")
		(net "M_I_CPU1_SB_DQS_DN<8>")
	)
	(arc
		(start 143.186912 -291.906198)
		(mid 143.228369 -292.078238)
		(end 143.34363 -292.212522)
		(width 0.09525)
		(layer "In2.Cu")
		(net "M_I_CPU1_SB_DQS_DN<8>")
	)
	(arc
		(start 135.763254 -291.421312)
		(mid 136.044686 -291.345557)
		(end 136.326118 -291.421312)
		(width 0.09525)
		(layer "In2.Cu")
		(net "M_I_CPU1_SB_DQS_DN<8>")
	)
	(arc
		(start 137.643362 -291.421312)
		(mid 137.924794 -291.345557)
		(end 138.206226 -291.421312)
		(width 0.09525)
		(layer "In2.Cu")
		(net "M_I_CPU1_SB_DQS_DN<8>")
	)
	(arc
		(start 144.350994 -293.871904)
		(mid 144.531385 -294.073603)
		(end 144.596612 -294.336216)
		(width 0.09525)
		(layer "In2.Cu")
		(net "M_I_CPU1_SB_DQS_DN<8>")
	)
	(arc
		(start 133.8834 -291.421312)
		(mid 134.164832 -291.345557)
		(end 134.446264 -291.421312)
		(width 0.09525)
		(layer "In2.Cu")
		(net "M_I_CPU1_SB_DQS_DN<8>")
	)
	(arc
		(start 133.514592 -291.426138)
		(mid 133.699624 -291.472052)
		(end 133.8834 -291.421312)
		(width 0.09525)
		(layer "In2.Cu")
		(net "M_I_CPU1_SB_DQS_DN<8>")
	)
	(arc
		(start 140.08608 -291.421312)
		(mid 140.269855 -291.472084)
		(end 140.454888 -291.426138)
		(width 0.09525)
		(layer "In2.Cu")
		(net "M_I_CPU1_SB_DQS_DN<8>")
	)
	(arc
		(start 144.823942 -294.683434)
		(mid 145.002392 -294.884904)
		(end 145.066766 -295.146222)
		(width 0.09525)
		(layer "In2.Cu")
		(net "M_I_CPU1_SB_DQS_DN<8>")
	)
	(arc
		(start 137.274554 -291.426138)
		(mid 137.459586 -291.472052)
		(end 137.643362 -291.421312)
		(width 0.09525)
		(layer "In2.Cu")
		(net "M_I_CPU1_SB_DQS_DN<8>")
	)
	(segment
		(start 127.58801 -285.970472)
		(end 128.054862 -286.23641)
		(width 0.12954)
		(layer "F.Cu")
		(net "M_I_CPU1_SB_DQS_DN<7>")
	)
	(segment
		(start 167.451024 -304.550826)
		(end 167.758364 -304.858166)
		(width 0.16002)
		(layer "In2.Cu")
		(net "M_I_CPU1_SB_DQS_DN<7>")
	)
	(segment
		(start 165.558216 -305.343306)
		(end 165.995096 -305.343306)
		(width 0.16002)
		(layer "In2.Cu")
		(net "M_I_CPU1_SB_DQS_DN<7>")
	)
	(segment
		(start 159.578548 -303.669446)
		(end 160.49244 -304.583338)
		(width 0.16002)
		(layer "In2.Cu")
		(net "M_I_CPU1_SB_DQS_DN<7>")
	)
	(segment
		(start 136.694926 -286.566356)
		(end 136.703308 -286.56153)
		(width 0.09525)
		(layer "In2.Cu")
		(net "M_I_CPU1_SB_DQS_DN<7>")
	)
	(segment
		(start 160.49244 -304.583338)
		(end 163.2077 -305.70805)
		(width 0.16002)
		(layer "In2.Cu")
		(net "M_I_CPU1_SB_DQS_DN<7>")
	)
	(segment
		(start 167.758364 -304.858166)
		(end 170.321478 -304.858166)
		(width 0.16002)
		(layer "In2.Cu")
		(net "M_I_CPU1_SB_DQS_DN<7>")
	)
	(segment
		(start 158.212536 -300.736)
		(end 158.586424 -301.109888)
		(width 0.16002)
		(layer "In2.Cu")
		(net "M_I_CPU1_SB_DQS_DN<7>")
	)
	(segment
		(start 158.204916 -302.018954)
		(end 158.204916 -302.295814)
		(width 0.16002)
		(layer "In2.Cu")
		(net "M_I_CPU1_SB_DQS_DN<7>")
	)
	(segment
		(start 166.787576 -304.550826)
		(end 167.451024 -304.550826)
		(width 0.16002)
		(layer "In2.Cu")
		(net "M_I_CPU1_SB_DQS_DN<7>")
	)
	(segment
		(start 147.394676 -288.455862)
		(end 147.41144 -288.472626)
		(width 0.09525)
		(layer "In2.Cu")
		(net "M_I_CPU1_SB_DQS_DN<7>")
	)
	(segment
		(start 157.303978 -301.118016)
		(end 157.68574 -300.736254)
		(width 0.16002)
		(layer "In2.Cu")
		(net "M_I_CPU1_SB_DQS_DN<7>")
	)
	(segment
		(start 177.273966 -304.70983)
		(end 179.24145 -304.70983)
		(width 0.16002)
		(layer "In2.Cu")
		(net "M_I_CPU1_SB_DQS_DN<7>")
	)
	(segment
		(start 159.578548 -303.392586)
		(end 159.578548 -303.669446)
		(width 0.16002)
		(layer "In2.Cu")
		(net "M_I_CPU1_SB_DQS_DN<7>")
	)
	(segment
		(start 159.059372 -302.109886)
		(end 159.586168 -302.109632)
		(width 0.16002)
		(layer "In2.Cu")
		(net "M_I_CPU1_SB_DQS_DN<7>")
	)
	(segment
		(start 158.586424 -301.109888)
		(end 158.586678 -301.637192)
		(width 0.16002)
		(layer "In2.Cu")
		(net "M_I_CPU1_SB_DQS_DN<7>")
	)
	(segment
		(start 145.755614 -286.486346)
		(end 146.38147 -287.112202)
		(width 0.09525)
		(layer "In2.Cu")
		(net "M_I_CPU1_SB_DQS_DN<7>")
	)
	(segment
		(start 141.966188 -286.56153)
		(end 141.97457 -286.566356)
		(width 0.09525)
		(layer "In2.Cu")
		(net "M_I_CPU1_SB_DQS_DN<7>")
	)
	(segment
		(start 144.211802 -286.567626)
		(end 144.212564 -286.567118)
		(width 0.09525)
		(layer "In2.Cu")
		(net "M_I_CPU1_SB_DQS_DN<7>")
	)
	(segment
		(start 174.33163 -304.550826)
		(end 174.995078 -304.550826)
		(width 0.16002)
		(layer "In2.Cu")
		(net "M_I_CPU1_SB_DQS_DN<7>")
	)
	(segment
		(start 137.266172 -286.56153)
		(end 137.274554 -286.566356)
		(width 0.09525)
		(layer "In2.Cu")
		(net "M_I_CPU1_SB_DQS_DN<7>")
	)
	(segment
		(start 165.193472 -305.70805)
		(end 165.558216 -305.343306)
		(width 0.16002)
		(layer "In2.Cu")
		(net "M_I_CPU1_SB_DQS_DN<7>")
	)
	(segment
		(start 147.41144 -288.472626)
		(end 148.734018 -289.795204)
		(width 0.16002)
		(layer "In2.Cu")
		(net "M_I_CPU1_SB_DQS_DN<7>")
	)
	(segment
		(start 156.831284 -300.645068)
		(end 156.831284 -300.922182)
		(width 0.16002)
		(layer "In2.Cu")
		(net "M_I_CPU1_SB_DQS_DN<7>")
	)
	(segment
		(start 146.38147 -287.526476)
		(end 147.310856 -288.455862)
		(width 0.09525)
		(layer "In2.Cu")
		(net "M_I_CPU1_SB_DQS_DN<7>")
	)
	(segment
		(start 158.586678 -301.637192)
		(end 158.204916 -302.018954)
		(width 0.16002)
		(layer "In2.Cu")
		(net "M_I_CPU1_SB_DQS_DN<7>")
	)
	(segment
		(start 131.99491 -286.566356)
		(end 132.003292 -286.56153)
		(width 0.09525)
		(layer "In2.Cu")
		(net "M_I_CPU1_SB_DQS_DN<7>")
	)
	(segment
		(start 135.754872 -286.566356)
		(end 135.763254 -286.56153)
		(width 0.09525)
		(layer "In2.Cu")
		(net "M_I_CPU1_SB_DQS_DN<7>")
	)
	(segment
		(start 159.96031 -303.010824)
		(end 159.578548 -303.392586)
		(width 0.16002)
		(layer "In2.Cu")
		(net "M_I_CPU1_SB_DQS_DN<7>")
	)
	(segment
		(start 144.21358 -286.56661)
		(end 144.22247 -286.56153)
		(width 0.09525)
		(layer "In2.Cu")
		(net "M_I_CPU1_SB_DQS_DN<7>")
	)
	(segment
		(start 128.054862 -286.23641)
		(end 128.208786 -286.50184)
		(width 0.09525)
		(layer "In2.Cu")
		(net "M_I_CPU1_SB_DQS_DN<7>")
	)
	(segment
		(start 141.394942 -286.566356)
		(end 141.403324 -286.56153)
		(width 0.09525)
		(layer "In2.Cu")
		(net "M_I_CPU1_SB_DQS_DN<7>")
	)
	(segment
		(start 144.501362 -286.486346)
		(end 145.755614 -286.486346)
		(width 0.09525)
		(layer "In2.Cu")
		(net "M_I_CPU1_SB_DQS_DN<7>")
	)
	(segment
		(start 179.24145 -304.70983)
		(end 179.516024 -304.435256)
		(width 0.16002)
		(layer "In2.Cu")
		(net "M_I_CPU1_SB_DQS_DN<7>")
	)
	(segment
		(start 158.40075 -302.491648)
		(end 158.67761 -302.491648)
		(width 0.16002)
		(layer "In2.Cu")
		(net "M_I_CPU1_SB_DQS_DN<7>")
	)
	(segment
		(start 157.212792 -300.26356)
		(end 156.831284 -300.645068)
		(width 0.16002)
		(layer "In2.Cu")
		(net "M_I_CPU1_SB_DQS_DN<7>")
	)
	(segment
		(start 159.960056 -302.48352)
		(end 159.96031 -303.010824)
		(width 0.16002)
		(layer "In2.Cu")
		(net "M_I_CPU1_SB_DQS_DN<7>")
	)
	(segment
		(start 157.027118 -301.118016)
		(end 157.303978 -301.118016)
		(width 0.16002)
		(layer "In2.Cu")
		(net "M_I_CPU1_SB_DQS_DN<7>")
	)
	(segment
		(start 172.737272 -305.708304)
		(end 173.10227 -305.343306)
		(width 0.16002)
		(layer "In2.Cu")
		(net "M_I_CPU1_SB_DQS_DN<7>")
	)
	(segment
		(start 173.53915 -305.343306)
		(end 174.33163 -304.550826)
		(width 0.16002)
		(layer "In2.Cu")
		(net "M_I_CPU1_SB_DQS_DN<7>")
	)
	(segment
		(start 159.586168 -302.109632)
		(end 159.960056 -302.48352)
		(width 0.16002)
		(layer "In2.Cu")
		(net "M_I_CPU1_SB_DQS_DN<7>")
	)
	(segment
		(start 144.198594 -286.574738)
		(end 144.211802 -286.567626)
		(width 0.09525)
		(layer "In2.Cu")
		(net "M_I_CPU1_SB_DQS_DN<7>")
	)
	(segment
		(start 173.10227 -305.343306)
		(end 173.53915 -305.343306)
		(width 0.16002)
		(layer "In2.Cu")
		(net "M_I_CPU1_SB_DQS_DN<7>")
	)
	(segment
		(start 175.302418 -304.858166)
		(end 177.12563 -304.858166)
		(width 0.16002)
		(layer "In2.Cu")
		(net "M_I_CPU1_SB_DQS_DN<7>")
	)
	(segment
		(start 170.321478 -304.858166)
		(end 171.171616 -305.708304)
		(width 0.16002)
		(layer "In2.Cu")
		(net "M_I_CPU1_SB_DQS_DN<7>")
	)
	(segment
		(start 147.310856 -288.455862)
		(end 147.394676 -288.455862)
		(width 0.09525)
		(layer "In2.Cu")
		(net "M_I_CPU1_SB_DQS_DN<7>")
	)
	(segment
		(start 149.762718 -292.2778)
		(end 157.212792 -299.727874)
		(width 0.16002)
		(layer "In2.Cu")
		(net "M_I_CPU1_SB_DQS_DN<7>")
	)
	(segment
		(start 148.734018 -289.795204)
		(end 149.762718 -292.2778)
		(width 0.16002)
		(layer "In2.Cu")
		(net "M_I_CPU1_SB_DQS_DN<7>")
	)
	(segment
		(start 132.934964 -286.566356)
		(end 132.943346 -286.56153)
		(width 0.09525)
		(layer "In2.Cu")
		(net "M_I_CPU1_SB_DQS_DN<7>")
	)
	(segment
		(start 156.831284 -300.922182)
		(end 157.027118 -301.118016)
		(width 0.16002)
		(layer "In2.Cu")
		(net "M_I_CPU1_SB_DQS_DN<7>")
	)
	(segment
		(start 158.67761 -302.491648)
		(end 159.059372 -302.109886)
		(width 0.16002)
		(layer "In2.Cu")
		(net "M_I_CPU1_SB_DQS_DN<7>")
	)
	(segment
		(start 177.12563 -304.858166)
		(end 177.273966 -304.70983)
		(width 0.16002)
		(layer "In2.Cu")
		(net "M_I_CPU1_SB_DQS_DN<7>")
	)
	(segment
		(start 133.50621 -286.56153)
		(end 133.514592 -286.566356)
		(width 0.09525)
		(layer "In2.Cu")
		(net "M_I_CPU1_SB_DQS_DN<7>")
	)
	(segment
		(start 138.206226 -286.56153)
		(end 138.214608 -286.566356)
		(width 0.09525)
		(layer "In2.Cu")
		(net "M_I_CPU1_SB_DQS_DN<7>")
	)
	(segment
		(start 171.171616 -305.708304)
		(end 172.737272 -305.708304)
		(width 0.16002)
		(layer "In2.Cu")
		(net "M_I_CPU1_SB_DQS_DN<7>")
	)
	(segment
		(start 129.746248 -286.56153)
		(end 129.75463 -286.566356)
		(width 0.09525)
		(layer "In2.Cu")
		(net "M_I_CPU1_SB_DQS_DN<7>")
	)
	(segment
		(start 157.212792 -299.727874)
		(end 157.212792 -300.26356)
		(width 0.16002)
		(layer "In2.Cu")
		(net "M_I_CPU1_SB_DQS_DN<7>")
	)
	(segment
		(start 165.995096 -305.343306)
		(end 166.787576 -304.550826)
		(width 0.16002)
		(layer "In2.Cu")
		(net "M_I_CPU1_SB_DQS_DN<7>")
	)
	(segment
		(start 146.38147 -287.112202)
		(end 146.38147 -287.526476)
		(width 0.09525)
		(layer "In2.Cu")
		(net "M_I_CPU1_SB_DQS_DN<7>")
	)
	(segment
		(start 144.212564 -286.567118)
		(end 144.21358 -286.56661)
		(width 0.09525)
		(layer "In2.Cu")
		(net "M_I_CPU1_SB_DQS_DN<7>")
	)
	(segment
		(start 163.2077 -305.70805)
		(end 165.193472 -305.70805)
		(width 0.16002)
		(layer "In2.Cu")
		(net "M_I_CPU1_SB_DQS_DN<7>")
	)
	(segment
		(start 128.208786 -286.50184)
		(end 128.309624 -286.52851)
		(width 0.09525)
		(layer "In2.Cu")
		(net "M_I_CPU1_SB_DQS_DN<7>")
	)
	(segment
		(start 157.68574 -300.736254)
		(end 158.212536 -300.736)
		(width 0.16002)
		(layer "In2.Cu")
		(net "M_I_CPU1_SB_DQS_DN<7>")
	)
	(segment
		(start 174.995078 -304.550826)
		(end 175.302418 -304.858166)
		(width 0.16002)
		(layer "In2.Cu")
		(net "M_I_CPU1_SB_DQS_DN<7>")
	)
	(segment
		(start 140.454888 -286.566356)
		(end 140.46327 -286.56153)
		(width 0.09525)
		(layer "In2.Cu")
		(net "M_I_CPU1_SB_DQS_DN<7>")
	)
	(segment
		(start 158.204916 -302.295814)
		(end 158.40075 -302.491648)
		(width 0.16002)
		(layer "In2.Cu")
		(net "M_I_CPU1_SB_DQS_DN<7>")
	)
	(segment
		(start 128.806194 -286.56153)
		(end 128.814576 -286.566356)
		(width 0.09525)
		(layer "In2.Cu")
		(net "M_I_CPU1_SB_DQS_DN<7>")
	)
	(arc
		(start 128.309624 -286.52851)
		(mid 128.561764 -286.486921)
		(end 128.806194 -286.56153)
		(width 0.09525)
		(layer "In2.Cu")
		(net "M_I_CPU1_SB_DQS_DN<7>")
	)
	(arc
		(start 131.626102 -286.56153)
		(mid 131.809877 -286.612302)
		(end 131.99491 -286.566356)
		(width 0.09525)
		(layer "In2.Cu")
		(net "M_I_CPU1_SB_DQS_DN<7>")
	)
	(arc
		(start 132.566156 -286.56153)
		(mid 132.749931 -286.612302)
		(end 132.934964 -286.566356)
		(width 0.09525)
		(layer "In2.Cu")
		(net "M_I_CPU1_SB_DQS_DN<7>")
	)
	(arc
		(start 132.003292 -286.56153)
		(mid 132.284724 -286.485741)
		(end 132.566156 -286.56153)
		(width 0.09525)
		(layer "In2.Cu")
		(net "M_I_CPU1_SB_DQS_DN<7>")
	)
	(arc
		(start 133.8834 -286.56153)
		(mid 134.164832 -286.485741)
		(end 134.446264 -286.56153)
		(width 0.09525)
		(layer "In2.Cu")
		(net "M_I_CPU1_SB_DQS_DN<7>")
	)
	(arc
		(start 143.846042 -286.56153)
		(mid 144.020674 -286.61207)
		(end 144.198594 -286.574738)
		(width 0.09525)
		(layer "In2.Cu")
		(net "M_I_CPU1_SB_DQS_DN<7>")
	)
	(arc
		(start 141.026134 -286.56153)
		(mid 141.209909 -286.612302)
		(end 141.394942 -286.566356)
		(width 0.09525)
		(layer "In2.Cu")
		(net "M_I_CPU1_SB_DQS_DN<7>")
	)
	(arc
		(start 129.183384 -286.56153)
		(mid 129.464816 -286.485741)
		(end 129.746248 -286.56153)
		(width 0.09525)
		(layer "In2.Cu")
		(net "M_I_CPU1_SB_DQS_DN<7>")
	)
	(arc
		(start 138.214608 -286.566356)
		(mid 138.39964 -286.61227)
		(end 138.583416 -286.56153)
		(width 0.09525)
		(layer "In2.Cu")
		(net "M_I_CPU1_SB_DQS_DN<7>")
	)
	(arc
		(start 140.46327 -286.56153)
		(mid 140.744702 -286.485741)
		(end 141.026134 -286.56153)
		(width 0.09525)
		(layer "In2.Cu")
		(net "M_I_CPU1_SB_DQS_DN<7>")
	)
	(arc
		(start 131.063238 -286.56153)
		(mid 131.34467 -286.485741)
		(end 131.626102 -286.56153)
		(width 0.09525)
		(layer "In2.Cu")
		(net "M_I_CPU1_SB_DQS_DN<7>")
	)
	(arc
		(start 129.75463 -286.566356)
		(mid 129.939662 -286.61227)
		(end 130.123438 -286.56153)
		(width 0.09525)
		(layer "In2.Cu")
		(net "M_I_CPU1_SB_DQS_DN<7>")
	)
	(arc
		(start 137.643362 -286.56153)
		(mid 137.924794 -286.485741)
		(end 138.206226 -286.56153)
		(width 0.09525)
		(layer "In2.Cu")
		(net "M_I_CPU1_SB_DQS_DN<7>")
	)
	(arc
		(start 138.583416 -286.56153)
		(mid 138.864848 -286.485741)
		(end 139.14628 -286.56153)
		(width 0.09525)
		(layer "In2.Cu")
		(net "M_I_CPU1_SB_DQS_DN<7>")
	)
	(arc
		(start 139.523216 -286.56153)
		(mid 139.804648 -286.485741)
		(end 140.08608 -286.56153)
		(width 0.09525)
		(layer "In2.Cu")
		(net "M_I_CPU1_SB_DQS_DN<7>")
	)
	(arc
		(start 133.514592 -286.566356)
		(mid 133.699624 -286.61227)
		(end 133.8834 -286.56153)
		(width 0.09525)
		(layer "In2.Cu")
		(net "M_I_CPU1_SB_DQS_DN<7>")
	)
	(arc
		(start 134.8232 -286.56153)
		(mid 135.104632 -286.485741)
		(end 135.386064 -286.56153)
		(width 0.09525)
		(layer "In2.Cu")
		(net "M_I_CPU1_SB_DQS_DN<7>")
	)
	(arc
		(start 140.08608 -286.56153)
		(mid 140.269855 -286.612302)
		(end 140.454888 -286.566356)
		(width 0.09525)
		(layer "In2.Cu")
		(net "M_I_CPU1_SB_DQS_DN<7>")
	)
	(arc
		(start 134.446264 -286.56153)
		(mid 134.634732 -286.612207)
		(end 134.8232 -286.56153)
		(width 0.09525)
		(layer "In2.Cu")
		(net "M_I_CPU1_SB_DQS_DN<7>")
	)
	(arc
		(start 141.403324 -286.56153)
		(mid 141.684756 -286.485741)
		(end 141.966188 -286.56153)
		(width 0.09525)
		(layer "In2.Cu")
		(net "M_I_CPU1_SB_DQS_DN<7>")
	)
	(arc
		(start 135.763254 -286.56153)
		(mid 136.044686 -286.485741)
		(end 136.326118 -286.56153)
		(width 0.09525)
		(layer "In2.Cu")
		(net "M_I_CPU1_SB_DQS_DN<7>")
	)
	(arc
		(start 139.14628 -286.56153)
		(mid 139.334748 -286.612207)
		(end 139.523216 -286.56153)
		(width 0.09525)
		(layer "In2.Cu")
		(net "M_I_CPU1_SB_DQS_DN<7>")
	)
	(arc
		(start 143.283178 -286.56153)
		(mid 143.56461 -286.485741)
		(end 143.846042 -286.56153)
		(width 0.09525)
		(layer "In2.Cu")
		(net "M_I_CPU1_SB_DQS_DN<7>")
	)
	(arc
		(start 136.703308 -286.56153)
		(mid 136.98474 -286.485741)
		(end 137.266172 -286.56153)
		(width 0.09525)
		(layer "In2.Cu")
		(net "M_I_CPU1_SB_DQS_DN<7>")
	)
	(arc
		(start 142.906242 -286.56153)
		(mid 143.09471 -286.612207)
		(end 143.283178 -286.56153)
		(width 0.09525)
		(layer "In2.Cu")
		(net "M_I_CPU1_SB_DQS_DN<7>")
	)
	(arc
		(start 135.386064 -286.56153)
		(mid 135.569839 -286.612302)
		(end 135.754872 -286.566356)
		(width 0.09525)
		(layer "In2.Cu")
		(net "M_I_CPU1_SB_DQS_DN<7>")
	)
	(arc
		(start 142.343378 -286.56153)
		(mid 142.62481 -286.485741)
		(end 142.906242 -286.56153)
		(width 0.09525)
		(layer "In2.Cu")
		(net "M_I_CPU1_SB_DQS_DN<7>")
	)
	(arc
		(start 130.686302 -286.56153)
		(mid 130.87477 -286.612207)
		(end 131.063238 -286.56153)
		(width 0.09525)
		(layer "In2.Cu")
		(net "M_I_CPU1_SB_DQS_DN<7>")
	)
	(arc
		(start 132.943346 -286.56153)
		(mid 133.224778 -286.485741)
		(end 133.50621 -286.56153)
		(width 0.09525)
		(layer "In2.Cu")
		(net "M_I_CPU1_SB_DQS_DN<7>")
	)
	(arc
		(start 137.274554 -286.566356)
		(mid 137.459586 -286.61227)
		(end 137.643362 -286.56153)
		(width 0.09525)
		(layer "In2.Cu")
		(net "M_I_CPU1_SB_DQS_DN<7>")
	)
	(arc
		(start 144.22247 -286.56153)
		(mid 144.356981 -286.505632)
		(end 144.501362 -286.486346)
		(width 0.09525)
		(layer "In2.Cu")
		(net "M_I_CPU1_SB_DQS_DN<7>")
	)
	(arc
		(start 136.326118 -286.56153)
		(mid 136.509893 -286.612302)
		(end 136.694926 -286.566356)
		(width 0.09525)
		(layer "In2.Cu")
		(net "M_I_CPU1_SB_DQS_DN<7>")
	)
	(arc
		(start 141.97457 -286.566356)
		(mid 142.159602 -286.61227)
		(end 142.343378 -286.56153)
		(width 0.09525)
		(layer "In2.Cu")
		(net "M_I_CPU1_SB_DQS_DN<7>")
	)
	(arc
		(start 128.814576 -286.566356)
		(mid 128.999608 -286.61227)
		(end 129.183384 -286.56153)
		(width 0.09525)
		(layer "In2.Cu")
		(net "M_I_CPU1_SB_DQS_DN<7>")
	)
	(arc
		(start 130.123438 -286.56153)
		(mid 130.40487 -286.485741)
		(end 130.686302 -286.56153)
		(width 0.09525)
		(layer "In2.Cu")
		(net "M_I_CPU1_SB_DQS_DN<7>")
	)
	(segment
		(start 127.58801 -281.110436)
		(end 128.054862 -281.376374)
		(width 0.12954)
		(layer "F.Cu")
		(net "M_I_CPU1_SB_DQS_DN<6>")
	)
	(segment
		(start 128.054862 -281.376374)
		(end 128.208786 -281.641804)
		(width 0.09525)
		(layer "In2.Cu")
		(net "M_I_CPU1_SB_DQS_DN<6>")
	)
	(segment
		(start 145.44548 -281.625548)
		(end 145.767806 -281.625548)
		(width 0.09525)
		(layer "In2.Cu")
		(net "M_I_CPU1_SB_DQS_DN<6>")
	)
	(segment
		(start 128.208786 -281.641804)
		(end 128.309624 -281.668474)
		(width 0.09525)
		(layer "In2.Cu")
		(net "M_I_CPU1_SB_DQS_DN<6>")
	)
	(segment
		(start 141.966188 -281.701494)
		(end 141.97457 -281.70632)
		(width 0.09525)
		(layer "In2.Cu")
		(net "M_I_CPU1_SB_DQS_DN<6>")
	)
	(segment
		(start 179.24145 -295.359836)
		(end 179.516024 -295.085262)
		(width 0.16002)
		(layer "In2.Cu")
		(net "M_I_CPU1_SB_DQS_DN<6>")
	)
	(segment
		(start 161.784538 -294.494966)
		(end 163.647628 -296.358056)
		(width 0.16002)
		(layer "In2.Cu")
		(net "M_I_CPU1_SB_DQS_DN<6>")
	)
	(segment
		(start 171.072048 -296.35831)
		(end 172.737272 -296.35831)
		(width 0.16002)
		(layer "In2.Cu")
		(net "M_I_CPU1_SB_DQS_DN<6>")
	)
	(segment
		(start 161.784538 -293.766494)
		(end 161.784538 -294.494966)
		(width 0.16002)
		(layer "In2.Cu")
		(net "M_I_CPU1_SB_DQS_DN<6>")
	)
	(segment
		(start 149.107906 -281.818334)
		(end 153.776426 -286.486854)
		(width 0.16002)
		(layer "In2.Cu")
		(net "M_I_CPU1_SB_DQS_DN<6>")
	)
	(segment
		(start 160.644586 -293.355014)
		(end 161.373058 -293.355014)
		(width 0.16002)
		(layer "In2.Cu")
		(net "M_I_CPU1_SB_DQS_DN<6>")
	)
	(segment
		(start 144.782794 -281.701494)
		(end 144.806162 -281.714956)
		(width 0.09525)
		(layer "In2.Cu")
		(net "M_I_CPU1_SB_DQS_DN<6>")
	)
	(segment
		(start 144.221962 -281.70124)
		(end 144.24787 -281.686254)
		(width 0.09525)
		(layer "In2.Cu")
		(net "M_I_CPU1_SB_DQS_DN<6>")
	)
	(segment
		(start 177.273966 -295.359836)
		(end 179.24145 -295.359836)
		(width 0.16002)
		(layer "In2.Cu")
		(net "M_I_CPU1_SB_DQS_DN<6>")
	)
	(segment
		(start 155.87853 -287.860486)
		(end 156.29001 -288.271966)
		(width 0.16002)
		(layer "In2.Cu")
		(net "M_I_CPU1_SB_DQS_DN<6>")
	)
	(segment
		(start 146.019774 -281.877516)
		(end 147.836382 -281.877516)
		(width 0.09525)
		(layer "In2.Cu")
		(net "M_I_CPU1_SB_DQS_DN<6>")
	)
	(segment
		(start 129.746248 -281.701494)
		(end 129.75463 -281.70632)
		(width 0.09525)
		(layer "In2.Cu")
		(net "M_I_CPU1_SB_DQS_DN<6>")
	)
	(segment
		(start 135.754872 -281.70632)
		(end 135.763254 -281.701494)
		(width 0.09525)
		(layer "In2.Cu")
		(net "M_I_CPU1_SB_DQS_DN<6>")
	)
	(segment
		(start 158.625794 -290.60775)
		(end 159.037274 -291.01923)
		(width 0.16002)
		(layer "In2.Cu")
		(net "M_I_CPU1_SB_DQS_DN<6>")
	)
	(segment
		(start 163.647628 -296.358056)
		(end 165.193472 -296.358056)
		(width 0.16002)
		(layer "In2.Cu")
		(net "M_I_CPU1_SB_DQS_DN<6>")
	)
	(segment
		(start 160.410906 -293.121334)
		(end 160.644586 -293.355014)
		(width 0.16002)
		(layer "In2.Cu")
		(net "M_I_CPU1_SB_DQS_DN<6>")
	)
	(segment
		(start 167.758364 -295.508172)
		(end 170.22191 -295.508172)
		(width 0.16002)
		(layer "In2.Cu")
		(net "M_I_CPU1_SB_DQS_DN<6>")
	)
	(segment
		(start 131.99491 -281.70632)
		(end 132.003292 -281.701494)
		(width 0.09525)
		(layer "In2.Cu")
		(net "M_I_CPU1_SB_DQS_DN<6>")
	)
	(segment
		(start 147.919186 -281.818334)
		(end 149.107906 -281.818334)
		(width 0.16002)
		(layer "In2.Cu")
		(net "M_I_CPU1_SB_DQS_DN<6>")
	)
	(segment
		(start 153.776426 -286.486854)
		(end 154.504898 -286.486854)
		(width 0.16002)
		(layer "In2.Cu")
		(net "M_I_CPU1_SB_DQS_DN<6>")
	)
	(segment
		(start 156.29001 -289.000438)
		(end 156.52369 -289.234118)
		(width 0.16002)
		(layer "In2.Cu")
		(net "M_I_CPU1_SB_DQS_DN<6>")
	)
	(segment
		(start 167.451024 -295.200832)
		(end 167.758364 -295.508172)
		(width 0.16002)
		(layer "In2.Cu")
		(net "M_I_CPU1_SB_DQS_DN<6>")
	)
	(segment
		(start 159.270954 -291.981382)
		(end 159.999426 -291.981382)
		(width 0.16002)
		(layer "In2.Cu")
		(net "M_I_CPU1_SB_DQS_DN<6>")
	)
	(segment
		(start 144.198594 -281.714702)
		(end 144.221962 -281.70124)
		(width 0.09525)
		(layer "In2.Cu")
		(net "M_I_CPU1_SB_DQS_DN<6>")
	)
	(segment
		(start 156.29001 -288.271966)
		(end 156.29001 -289.000438)
		(width 0.16002)
		(layer "In2.Cu")
		(net "M_I_CPU1_SB_DQS_DN<6>")
	)
	(segment
		(start 154.916378 -287.626806)
		(end 155.150058 -287.860486)
		(width 0.16002)
		(layer "In2.Cu")
		(net "M_I_CPU1_SB_DQS_DN<6>")
	)
	(segment
		(start 128.806194 -281.701494)
		(end 128.814576 -281.70632)
		(width 0.09525)
		(layer "In2.Cu")
		(net "M_I_CPU1_SB_DQS_DN<6>")
	)
	(segment
		(start 159.999426 -291.981382)
		(end 160.410906 -292.392862)
		(width 0.16002)
		(layer "In2.Cu")
		(net "M_I_CPU1_SB_DQS_DN<6>")
	)
	(segment
		(start 159.037274 -291.01923)
		(end 159.037274 -291.747702)
		(width 0.16002)
		(layer "In2.Cu")
		(net "M_I_CPU1_SB_DQS_DN<6>")
	)
	(segment
		(start 156.52369 -289.234118)
		(end 157.252162 -289.234118)
		(width 0.16002)
		(layer "In2.Cu")
		(net "M_I_CPU1_SB_DQS_DN<6>")
	)
	(segment
		(start 141.394942 -281.70632)
		(end 141.403324 -281.701494)
		(width 0.09525)
		(layer "In2.Cu")
		(net "M_I_CPU1_SB_DQS_DN<6>")
	)
	(segment
		(start 133.50621 -281.701494)
		(end 133.514592 -281.70632)
		(width 0.09525)
		(layer "In2.Cu")
		(net "M_I_CPU1_SB_DQS_DN<6>")
	)
	(segment
		(start 161.373058 -293.355014)
		(end 161.784538 -293.766494)
		(width 0.16002)
		(layer "In2.Cu")
		(net "M_I_CPU1_SB_DQS_DN<6>")
	)
	(segment
		(start 155.150058 -287.860486)
		(end 155.87853 -287.860486)
		(width 0.16002)
		(layer "In2.Cu")
		(net "M_I_CPU1_SB_DQS_DN<6>")
	)
	(segment
		(start 157.663642 -290.37407)
		(end 157.897322 -290.60775)
		(width 0.16002)
		(layer "In2.Cu")
		(net "M_I_CPU1_SB_DQS_DN<6>")
	)
	(segment
		(start 136.694926 -281.70632)
		(end 136.703308 -281.701494)
		(width 0.09525)
		(layer "In2.Cu")
		(net "M_I_CPU1_SB_DQS_DN<6>")
	)
	(segment
		(start 157.897322 -290.60775)
		(end 158.625794 -290.60775)
		(width 0.16002)
		(layer "In2.Cu")
		(net "M_I_CPU1_SB_DQS_DN<6>")
	)
	(segment
		(start 137.266172 -281.701494)
		(end 137.274554 -281.70632)
		(width 0.09525)
		(layer "In2.Cu")
		(net "M_I_CPU1_SB_DQS_DN<6>")
	)
	(segment
		(start 166.787576 -295.200832)
		(end 167.451024 -295.200832)
		(width 0.16002)
		(layer "In2.Cu")
		(net "M_I_CPU1_SB_DQS_DN<6>")
	)
	(segment
		(start 165.558216 -295.993312)
		(end 165.995096 -295.993312)
		(width 0.16002)
		(layer "In2.Cu")
		(net "M_I_CPU1_SB_DQS_DN<6>")
	)
	(segment
		(start 145.767806 -281.625548)
		(end 146.019774 -281.877516)
		(width 0.09525)
		(layer "In2.Cu")
		(net "M_I_CPU1_SB_DQS_DN<6>")
	)
	(segment
		(start 160.410906 -292.392862)
		(end 160.410906 -293.121334)
		(width 0.16002)
		(layer "In2.Cu")
		(net "M_I_CPU1_SB_DQS_DN<6>")
	)
	(segment
		(start 165.995096 -295.993312)
		(end 166.787576 -295.200832)
		(width 0.16002)
		(layer "In2.Cu")
		(net "M_I_CPU1_SB_DQS_DN<6>")
	)
	(segment
		(start 165.193472 -296.358056)
		(end 165.558216 -295.993312)
		(width 0.16002)
		(layer "In2.Cu")
		(net "M_I_CPU1_SB_DQS_DN<6>")
	)
	(segment
		(start 147.895564 -281.818334)
		(end 147.919186 -281.818334)
		(width 0.09525)
		(layer "In2.Cu")
		(net "M_I_CPU1_SB_DQS_DN<6>")
	)
	(segment
		(start 154.504898 -286.486854)
		(end 154.916378 -286.898334)
		(width 0.16002)
		(layer "In2.Cu")
		(net "M_I_CPU1_SB_DQS_DN<6>")
	)
	(segment
		(start 147.836382 -281.877516)
		(end 147.895564 -281.818334)
		(width 0.09525)
		(layer "In2.Cu")
		(net "M_I_CPU1_SB_DQS_DN<6>")
	)
	(segment
		(start 154.916378 -286.898334)
		(end 154.916378 -287.626806)
		(width 0.16002)
		(layer "In2.Cu")
		(net "M_I_CPU1_SB_DQS_DN<6>")
	)
	(segment
		(start 159.037274 -291.747702)
		(end 159.270954 -291.981382)
		(width 0.16002)
		(layer "In2.Cu")
		(net "M_I_CPU1_SB_DQS_DN<6>")
	)
	(segment
		(start 177.12563 -295.508172)
		(end 177.273966 -295.359836)
		(width 0.16002)
		(layer "In2.Cu")
		(net "M_I_CPU1_SB_DQS_DN<6>")
	)
	(segment
		(start 138.206226 -281.701494)
		(end 138.214608 -281.70632)
		(width 0.09525)
		(layer "In2.Cu")
		(net "M_I_CPU1_SB_DQS_DN<6>")
	)
	(segment
		(start 173.056296 -296.039286)
		(end 173.802294 -295.730168)
		(width 0.16002)
		(layer "In2.Cu")
		(net "M_I_CPU1_SB_DQS_DN<6>")
	)
	(segment
		(start 174.995078 -295.200832)
		(end 175.302418 -295.508172)
		(width 0.16002)
		(layer "In2.Cu")
		(net "M_I_CPU1_SB_DQS_DN<6>")
	)
	(segment
		(start 170.22191 -295.508172)
		(end 171.072048 -296.35831)
		(width 0.16002)
		(layer "In2.Cu")
		(net "M_I_CPU1_SB_DQS_DN<6>")
	)
	(segment
		(start 174.33163 -295.200832)
		(end 174.995078 -295.200832)
		(width 0.16002)
		(layer "In2.Cu")
		(net "M_I_CPU1_SB_DQS_DN<6>")
	)
	(segment
		(start 173.802294 -295.730168)
		(end 174.33163 -295.200832)
		(width 0.16002)
		(layer "In2.Cu")
		(net "M_I_CPU1_SB_DQS_DN<6>")
	)
	(segment
		(start 157.663642 -289.645598)
		(end 157.663642 -290.37407)
		(width 0.16002)
		(layer "In2.Cu")
		(net "M_I_CPU1_SB_DQS_DN<6>")
	)
	(segment
		(start 172.737272 -296.35831)
		(end 173.056296 -296.039286)
		(width 0.16002)
		(layer "In2.Cu")
		(net "M_I_CPU1_SB_DQS_DN<6>")
	)
	(segment
		(start 140.454888 -281.70632)
		(end 140.46327 -281.701494)
		(width 0.09525)
		(layer "In2.Cu")
		(net "M_I_CPU1_SB_DQS_DN<6>")
	)
	(segment
		(start 132.934964 -281.70632)
		(end 132.943346 -281.701494)
		(width 0.09525)
		(layer "In2.Cu")
		(net "M_I_CPU1_SB_DQS_DN<6>")
	)
	(segment
		(start 145.444718 -281.624786)
		(end 145.44548 -281.625548)
		(width 0.09525)
		(layer "In2.Cu")
		(net "M_I_CPU1_SB_DQS_DN<6>")
	)
	(segment
		(start 157.252162 -289.234118)
		(end 157.663642 -289.645598)
		(width 0.16002)
		(layer "In2.Cu")
		(net "M_I_CPU1_SB_DQS_DN<6>")
	)
	(segment
		(start 175.302418 -295.508172)
		(end 177.12563 -295.508172)
		(width 0.16002)
		(layer "In2.Cu")
		(net "M_I_CPU1_SB_DQS_DN<6>")
	)
	(arc
		(start 141.403324 -281.701494)
		(mid 141.684756 -281.625739)
		(end 141.966188 -281.701494)
		(width 0.09525)
		(layer "In2.Cu")
		(net "M_I_CPU1_SB_DQS_DN<6>")
	)
	(arc
		(start 128.814576 -281.70632)
		(mid 128.999608 -281.752234)
		(end 129.183384 -281.701494)
		(width 0.09525)
		(layer "In2.Cu")
		(net "M_I_CPU1_SB_DQS_DN<6>")
	)
	(arc
		(start 142.343378 -281.701494)
		(mid 142.62481 -281.625739)
		(end 142.906242 -281.701494)
		(width 0.09525)
		(layer "In2.Cu")
		(net "M_I_CPU1_SB_DQS_DN<6>")
	)
	(arc
		(start 143.846042 -281.701494)
		(mid 144.020674 -281.752034)
		(end 144.198594 -281.714702)
		(width 0.09525)
		(layer "In2.Cu")
		(net "M_I_CPU1_SB_DQS_DN<6>")
	)
	(arc
		(start 135.763254 -281.701494)
		(mid 136.044686 -281.625739)
		(end 136.326118 -281.701494)
		(width 0.09525)
		(layer "In2.Cu")
		(net "M_I_CPU1_SB_DQS_DN<6>")
	)
	(arc
		(start 140.46327 -281.701494)
		(mid 140.744702 -281.625739)
		(end 141.026134 -281.701494)
		(width 0.09525)
		(layer "In2.Cu")
		(net "M_I_CPU1_SB_DQS_DN<6>")
	)
	(arc
		(start 141.026134 -281.701494)
		(mid 141.209909 -281.752266)
		(end 141.394942 -281.70632)
		(width 0.09525)
		(layer "In2.Cu")
		(net "M_I_CPU1_SB_DQS_DN<6>")
	)
	(arc
		(start 144.24787 -281.686254)
		(mid 144.517276 -281.625906)
		(end 144.782794 -281.701494)
		(width 0.09525)
		(layer "In2.Cu")
		(net "M_I_CPU1_SB_DQS_DN<6>")
	)
	(arc
		(start 130.686302 -281.701494)
		(mid 130.87477 -281.752171)
		(end 131.063238 -281.701494)
		(width 0.09525)
		(layer "In2.Cu")
		(net "M_I_CPU1_SB_DQS_DN<6>")
	)
	(arc
		(start 132.943346 -281.701494)
		(mid 133.224778 -281.625739)
		(end 133.50621 -281.701494)
		(width 0.09525)
		(layer "In2.Cu")
		(net "M_I_CPU1_SB_DQS_DN<6>")
	)
	(arc
		(start 142.906242 -281.701494)
		(mid 143.09471 -281.752171)
		(end 143.283178 -281.701494)
		(width 0.09525)
		(layer "In2.Cu")
		(net "M_I_CPU1_SB_DQS_DN<6>")
	)
	(arc
		(start 139.523216 -281.701494)
		(mid 139.804648 -281.625739)
		(end 140.08608 -281.701494)
		(width 0.09525)
		(layer "In2.Cu")
		(net "M_I_CPU1_SB_DQS_DN<6>")
	)
	(arc
		(start 137.643362 -281.701494)
		(mid 137.924794 -281.625739)
		(end 138.206226 -281.701494)
		(width 0.09525)
		(layer "In2.Cu")
		(net "M_I_CPU1_SB_DQS_DN<6>")
	)
	(arc
		(start 139.14628 -281.701494)
		(mid 139.334748 -281.752171)
		(end 139.523216 -281.701494)
		(width 0.09525)
		(layer "In2.Cu")
		(net "M_I_CPU1_SB_DQS_DN<6>")
	)
	(arc
		(start 135.386064 -281.701494)
		(mid 135.569839 -281.752266)
		(end 135.754872 -281.70632)
		(width 0.09525)
		(layer "In2.Cu")
		(net "M_I_CPU1_SB_DQS_DN<6>")
	)
	(arc
		(start 136.326118 -281.701494)
		(mid 136.509893 -281.752266)
		(end 136.694926 -281.70632)
		(width 0.09525)
		(layer "In2.Cu")
		(net "M_I_CPU1_SB_DQS_DN<6>")
	)
	(arc
		(start 131.063238 -281.701494)
		(mid 131.34467 -281.625739)
		(end 131.626102 -281.701494)
		(width 0.09525)
		(layer "In2.Cu")
		(net "M_I_CPU1_SB_DQS_DN<6>")
	)
	(arc
		(start 137.274554 -281.70632)
		(mid 137.459586 -281.752234)
		(end 137.643362 -281.701494)
		(width 0.09525)
		(layer "In2.Cu")
		(net "M_I_CPU1_SB_DQS_DN<6>")
	)
	(arc
		(start 130.123438 -281.701494)
		(mid 130.40487 -281.625739)
		(end 130.686302 -281.701494)
		(width 0.09525)
		(layer "In2.Cu")
		(net "M_I_CPU1_SB_DQS_DN<6>")
	)
	(arc
		(start 138.583416 -281.701494)
		(mid 138.864848 -281.625739)
		(end 139.14628 -281.701494)
		(width 0.09525)
		(layer "In2.Cu")
		(net "M_I_CPU1_SB_DQS_DN<6>")
	)
	(arc
		(start 133.514592 -281.70632)
		(mid 133.699624 -281.752234)
		(end 133.8834 -281.701494)
		(width 0.09525)
		(layer "In2.Cu")
		(net "M_I_CPU1_SB_DQS_DN<6>")
	)
	(arc
		(start 134.8232 -281.701494)
		(mid 135.104632 -281.625739)
		(end 135.386064 -281.701494)
		(width 0.09525)
		(layer "In2.Cu")
		(net "M_I_CPU1_SB_DQS_DN<6>")
	)
	(arc
		(start 132.003292 -281.701494)
		(mid 132.284724 -281.625739)
		(end 132.566156 -281.701494)
		(width 0.09525)
		(layer "In2.Cu")
		(net "M_I_CPU1_SB_DQS_DN<6>")
	)
	(arc
		(start 129.75463 -281.70632)
		(mid 129.939662 -281.752234)
		(end 130.123438 -281.701494)
		(width 0.09525)
		(layer "In2.Cu")
		(net "M_I_CPU1_SB_DQS_DN<6>")
	)
	(arc
		(start 134.446264 -281.701494)
		(mid 134.634732 -281.752171)
		(end 134.8232 -281.701494)
		(width 0.09525)
		(layer "In2.Cu")
		(net "M_I_CPU1_SB_DQS_DN<6>")
	)
	(arc
		(start 140.08608 -281.701494)
		(mid 140.269855 -281.752266)
		(end 140.454888 -281.70632)
		(width 0.09525)
		(layer "In2.Cu")
		(net "M_I_CPU1_SB_DQS_DN<6>")
	)
	(arc
		(start 136.703308 -281.701494)
		(mid 136.98474 -281.625739)
		(end 137.266172 -281.701494)
		(width 0.09525)
		(layer "In2.Cu")
		(net "M_I_CPU1_SB_DQS_DN<6>")
	)
	(arc
		(start 145.161254 -281.701748)
		(mid 145.297867 -281.644417)
		(end 145.444718 -281.624786)
		(width 0.09525)
		(layer "In2.Cu")
		(net "M_I_CPU1_SB_DQS_DN<6>")
	)
	(arc
		(start 129.183384 -281.701494)
		(mid 129.464816 -281.625739)
		(end 129.746248 -281.701494)
		(width 0.09525)
		(layer "In2.Cu")
		(net "M_I_CPU1_SB_DQS_DN<6>")
	)
	(arc
		(start 132.566156 -281.701494)
		(mid 132.749931 -281.752266)
		(end 132.934964 -281.70632)
		(width 0.09525)
		(layer "In2.Cu")
		(net "M_I_CPU1_SB_DQS_DN<6>")
	)
	(arc
		(start 143.283178 -281.701494)
		(mid 143.56461 -281.625739)
		(end 143.846042 -281.701494)
		(width 0.09525)
		(layer "In2.Cu")
		(net "M_I_CPU1_SB_DQS_DN<6>")
	)
	(arc
		(start 133.8834 -281.701494)
		(mid 134.164832 -281.625739)
		(end 134.446264 -281.701494)
		(width 0.09525)
		(layer "In2.Cu")
		(net "M_I_CPU1_SB_DQS_DN<6>")
	)
	(arc
		(start 138.214608 -281.70632)
		(mid 138.39964 -281.752234)
		(end 138.583416 -281.701494)
		(width 0.09525)
		(layer "In2.Cu")
		(net "M_I_CPU1_SB_DQS_DN<6>")
	)
	(arc
		(start 128.309624 -281.668474)
		(mid 128.561765 -281.626904)
		(end 128.806194 -281.701494)
		(width 0.09525)
		(layer "In2.Cu")
		(net "M_I_CPU1_SB_DQS_DN<6>")
	)
	(arc
		(start 144.806162 -281.714956)
		(mid 144.98535 -281.752801)
		(end 145.161254 -281.701748)
		(width 0.09525)
		(layer "In2.Cu")
		(net "M_I_CPU1_SB_DQS_DN<6>")
	)
	(arc
		(start 131.626102 -281.701494)
		(mid 131.809877 -281.752266)
		(end 131.99491 -281.70632)
		(width 0.09525)
		(layer "In2.Cu")
		(net "M_I_CPU1_SB_DQS_DN<6>")
	)
	(arc
		(start 141.97457 -281.70632)
		(mid 142.159602 -281.752234)
		(end 142.343378 -281.701494)
		(width 0.09525)
		(layer "In2.Cu")
		(net "M_I_CPU1_SB_DQS_DN<6>")
	)
	(segment
		(start 127.58801 -276.2504)
		(end 128.054862 -276.516338)
		(width 0.12954)
		(layer "F.Cu")
		(net "M_I_CPU1_SB_DQS_DN<5>")
	)
	(segment
		(start 153.856436 -277.847806)
		(end 154.1907 -278.18207)
		(width 0.16002)
		(layer "In2.Cu")
		(net "M_I_CPU1_SB_DQS_DN<5>")
	)
	(segment
		(start 172.737272 -287.008316)
		(end 173.10227 -286.643318)
		(width 0.16002)
		(layer "In2.Cu")
		(net "M_I_CPU1_SB_DQS_DN<5>")
	)
	(segment
		(start 170.22191 -286.158178)
		(end 171.072048 -287.008316)
		(width 0.16002)
		(layer "In2.Cu")
		(net "M_I_CPU1_SB_DQS_DN<5>")
	)
	(segment
		(start 162.658552 -286.120586)
		(end 163.546028 -287.008062)
		(width 0.16002)
		(layer "In2.Cu")
		(net "M_I_CPU1_SB_DQS_DN<5>")
	)
	(segment
		(start 171.072048 -287.008316)
		(end 172.737272 -287.008316)
		(width 0.16002)
		(layer "In2.Cu")
		(net "M_I_CPU1_SB_DQS_DN<5>")
	)
	(segment
		(start 177.273966 -286.009842)
		(end 179.24145 -286.009842)
		(width 0.16002)
		(layer "In2.Cu")
		(net "M_I_CPU1_SB_DQS_DN<5>")
	)
	(segment
		(start 131.99491 -276.846284)
		(end 132.003292 -276.841458)
		(width 0.09525)
		(layer "In2.Cu")
		(net "M_I_CPU1_SB_DQS_DN<5>")
	)
	(segment
		(start 156.6037 -280.59507)
		(end 156.832046 -280.823416)
		(width 0.16002)
		(layer "In2.Cu")
		(net "M_I_CPU1_SB_DQS_DN<5>")
	)
	(segment
		(start 145.840958 -276.620224)
		(end 146.883628 -275.577554)
		(width 0.09525)
		(layer "In2.Cu")
		(net "M_I_CPU1_SB_DQS_DN<5>")
	)
	(segment
		(start 128.054862 -276.516338)
		(end 128.208786 -276.781768)
		(width 0.09525)
		(layer "In2.Cu")
		(net "M_I_CPU1_SB_DQS_DN<5>")
	)
	(segment
		(start 141.394942 -276.846284)
		(end 141.403324 -276.841458)
		(width 0.09525)
		(layer "In2.Cu")
		(net "M_I_CPU1_SB_DQS_DN<5>")
	)
	(segment
		(start 147.895564 -275.81606)
		(end 147.919186 -275.81606)
		(width 0.09525)
		(layer "In2.Cu")
		(net "M_I_CPU1_SB_DQS_DN<5>")
	)
	(segment
		(start 174.90186 -285.75762)
		(end 175.302418 -286.158178)
		(width 0.16002)
		(layer "In2.Cu")
		(net "M_I_CPU1_SB_DQS_DN<5>")
	)
	(segment
		(start 152.817068 -276.808438)
		(end 153.307288 -276.808438)
		(width 0.16002)
		(layer "In2.Cu")
		(net "M_I_CPU1_SB_DQS_DN<5>")
	)
	(segment
		(start 153.307288 -276.808438)
		(end 153.856436 -277.357586)
		(width 0.16002)
		(layer "In2.Cu")
		(net "M_I_CPU1_SB_DQS_DN<5>")
	)
	(segment
		(start 167.357806 -285.75762)
		(end 167.758364 -286.158178)
		(width 0.16002)
		(layer "In2.Cu")
		(net "M_I_CPU1_SB_DQS_DN<5>")
	)
	(segment
		(start 155.230068 -279.221438)
		(end 155.564332 -279.555702)
		(width 0.16002)
		(layer "In2.Cu")
		(net "M_I_CPU1_SB_DQS_DN<5>")
	)
	(segment
		(start 155.564332 -279.555702)
		(end 156.054552 -279.555702)
		(width 0.16002)
		(layer "In2.Cu")
		(net "M_I_CPU1_SB_DQS_DN<5>")
	)
	(segment
		(start 161.549588 -285.011622)
		(end 162.158172 -285.011622)
		(width 0.16002)
		(layer "In2.Cu")
		(net "M_I_CPU1_SB_DQS_DN<5>")
	)
	(segment
		(start 129.746248 -276.841458)
		(end 129.75463 -276.846284)
		(width 0.09525)
		(layer "In2.Cu")
		(net "M_I_CPU1_SB_DQS_DN<5>")
	)
	(segment
		(start 160.796478 -283.649928)
		(end 161.272982 -284.126432)
		(width 0.16002)
		(layer "In2.Cu")
		(net "M_I_CPU1_SB_DQS_DN<5>")
	)
	(segment
		(start 173.10227 -286.643318)
		(end 173.53915 -286.643318)
		(width 0.16002)
		(layer "In2.Cu")
		(net "M_I_CPU1_SB_DQS_DN<5>")
	)
	(segment
		(start 166.880794 -285.75762)
		(end 167.357806 -285.75762)
		(width 0.16002)
		(layer "In2.Cu")
		(net "M_I_CPU1_SB_DQS_DN<5>")
	)
	(segment
		(start 147.836382 -275.875242)
		(end 147.895564 -275.81606)
		(width 0.09525)
		(layer "In2.Cu")
		(net "M_I_CPU1_SB_DQS_DN<5>")
	)
	(segment
		(start 167.758364 -286.158178)
		(end 170.22191 -286.158178)
		(width 0.16002)
		(layer "In2.Cu")
		(net "M_I_CPU1_SB_DQS_DN<5>")
	)
	(segment
		(start 156.6037 -280.10485)
		(end 156.6037 -280.59507)
		(width 0.16002)
		(layer "In2.Cu")
		(net "M_I_CPU1_SB_DQS_DN<5>")
	)
	(segment
		(start 153.856436 -277.357586)
		(end 153.856436 -277.847806)
		(width 0.16002)
		(layer "In2.Cu")
		(net "M_I_CPU1_SB_DQS_DN<5>")
	)
	(segment
		(start 156.054552 -279.555702)
		(end 156.6037 -280.10485)
		(width 0.16002)
		(layer "In2.Cu")
		(net "M_I_CPU1_SB_DQS_DN<5>")
	)
	(segment
		(start 155.230068 -278.731218)
		(end 155.230068 -279.221438)
		(width 0.16002)
		(layer "In2.Cu")
		(net "M_I_CPU1_SB_DQS_DN<5>")
	)
	(segment
		(start 144.198594 -276.854666)
		(end 144.221962 -276.841204)
		(width 0.09525)
		(layer "In2.Cu")
		(net "M_I_CPU1_SB_DQS_DN<5>")
	)
	(segment
		(start 177.12563 -286.158178)
		(end 177.273966 -286.009842)
		(width 0.16002)
		(layer "In2.Cu")
		(net "M_I_CPU1_SB_DQS_DN<5>")
	)
	(segment
		(start 154.68092 -278.18207)
		(end 155.230068 -278.731218)
		(width 0.16002)
		(layer "In2.Cu")
		(net "M_I_CPU1_SB_DQS_DN<5>")
	)
	(segment
		(start 144.221962 -276.841204)
		(end 144.24787 -276.826218)
		(width 0.09525)
		(layer "In2.Cu")
		(net "M_I_CPU1_SB_DQS_DN<5>")
	)
	(segment
		(start 156.832046 -280.823416)
		(end 157.361382 -280.823416)
		(width 0.16002)
		(layer "In2.Cu")
		(net "M_I_CPU1_SB_DQS_DN<5>")
	)
	(segment
		(start 152.38857 -276.153372)
		(end 152.38857 -276.37994)
		(width 0.16002)
		(layer "In2.Cu")
		(net "M_I_CPU1_SB_DQS_DN<5>")
	)
	(segment
		(start 133.50621 -276.841458)
		(end 133.514592 -276.846284)
		(width 0.09525)
		(layer "In2.Cu")
		(net "M_I_CPU1_SB_DQS_DN<5>")
	)
	(segment
		(start 157.361382 -280.823416)
		(end 160.187894 -283.649928)
		(width 0.16002)
		(layer "In2.Cu")
		(net "M_I_CPU1_SB_DQS_DN<5>")
	)
	(segment
		(start 128.806194 -276.841458)
		(end 128.814576 -276.846284)
		(width 0.09525)
		(layer "In2.Cu")
		(net "M_I_CPU1_SB_DQS_DN<5>")
	)
	(segment
		(start 128.208786 -276.781768)
		(end 128.309624 -276.808438)
		(width 0.09525)
		(layer "In2.Cu")
		(net "M_I_CPU1_SB_DQS_DN<5>")
	)
	(segment
		(start 140.454888 -276.846284)
		(end 140.46327 -276.841458)
		(width 0.09525)
		(layer "In2.Cu")
		(net "M_I_CPU1_SB_DQS_DN<5>")
	)
	(segment
		(start 165.995096 -286.643318)
		(end 166.880794 -285.75762)
		(width 0.16002)
		(layer "In2.Cu")
		(net "M_I_CPU1_SB_DQS_DN<5>")
	)
	(segment
		(start 141.966188 -276.841458)
		(end 141.97457 -276.846284)
		(width 0.09525)
		(layer "In2.Cu")
		(net "M_I_CPU1_SB_DQS_DN<5>")
	)
	(segment
		(start 162.158172 -285.011622)
		(end 162.658552 -285.512002)
		(width 0.16002)
		(layer "In2.Cu")
		(net "M_I_CPU1_SB_DQS_DN<5>")
	)
	(segment
		(start 161.272982 -284.126432)
		(end 161.272982 -284.735016)
		(width 0.16002)
		(layer "In2.Cu")
		(net "M_I_CPU1_SB_DQS_DN<5>")
	)
	(segment
		(start 152.051258 -275.81606)
		(end 152.38857 -276.153372)
		(width 0.16002)
		(layer "In2.Cu")
		(net "M_I_CPU1_SB_DQS_DN<5>")
	)
	(segment
		(start 154.1907 -278.18207)
		(end 154.68092 -278.18207)
		(width 0.16002)
		(layer "In2.Cu")
		(net "M_I_CPU1_SB_DQS_DN<5>")
	)
	(segment
		(start 146.883628 -275.577554)
		(end 147.195794 -275.577554)
		(width 0.09525)
		(layer "In2.Cu")
		(net "M_I_CPU1_SB_DQS_DN<5>")
	)
	(segment
		(start 174.424848 -285.75762)
		(end 174.90186 -285.75762)
		(width 0.16002)
		(layer "In2.Cu")
		(net "M_I_CPU1_SB_DQS_DN<5>")
	)
	(segment
		(start 144.782794 -276.841458)
		(end 144.806162 -276.85492)
		(width 0.09525)
		(layer "In2.Cu")
		(net "M_I_CPU1_SB_DQS_DN<5>")
	)
	(segment
		(start 147.919186 -275.81606)
		(end 152.051258 -275.81606)
		(width 0.16002)
		(layer "In2.Cu")
		(net "M_I_CPU1_SB_DQS_DN<5>")
	)
	(segment
		(start 132.934964 -276.846284)
		(end 132.943346 -276.841458)
		(width 0.09525)
		(layer "In2.Cu")
		(net "M_I_CPU1_SB_DQS_DN<5>")
	)
	(segment
		(start 165.558216 -286.643318)
		(end 165.995096 -286.643318)
		(width 0.16002)
		(layer "In2.Cu")
		(net "M_I_CPU1_SB_DQS_DN<5>")
	)
	(segment
		(start 135.754872 -276.846284)
		(end 135.763254 -276.841458)
		(width 0.09525)
		(layer "In2.Cu")
		(net "M_I_CPU1_SB_DQS_DN<5>")
	)
	(segment
		(start 161.272982 -284.735016)
		(end 161.549588 -285.011622)
		(width 0.16002)
		(layer "In2.Cu")
		(net "M_I_CPU1_SB_DQS_DN<5>")
	)
	(segment
		(start 175.302418 -286.158178)
		(end 177.12563 -286.158178)
		(width 0.16002)
		(layer "In2.Cu")
		(net "M_I_CPU1_SB_DQS_DN<5>")
	)
	(segment
		(start 145.695924 -276.620224)
		(end 145.840958 -276.620224)
		(width 0.09525)
		(layer "In2.Cu")
		(net "M_I_CPU1_SB_DQS_DN<5>")
	)
	(segment
		(start 136.694926 -276.846284)
		(end 136.703308 -276.841458)
		(width 0.09525)
		(layer "In2.Cu")
		(net "M_I_CPU1_SB_DQS_DN<5>")
	)
	(segment
		(start 147.493482 -275.875242)
		(end 147.836382 -275.875242)
		(width 0.09525)
		(layer "In2.Cu")
		(net "M_I_CPU1_SB_DQS_DN<5>")
	)
	(segment
		(start 162.658552 -285.512002)
		(end 162.658552 -286.120586)
		(width 0.16002)
		(layer "In2.Cu")
		(net "M_I_CPU1_SB_DQS_DN<5>")
	)
	(segment
		(start 173.53915 -286.643318)
		(end 174.424848 -285.75762)
		(width 0.16002)
		(layer "In2.Cu")
		(net "M_I_CPU1_SB_DQS_DN<5>")
	)
	(segment
		(start 165.193472 -287.008062)
		(end 165.558216 -286.643318)
		(width 0.16002)
		(layer "In2.Cu")
		(net "M_I_CPU1_SB_DQS_DN<5>")
	)
	(segment
		(start 179.24145 -286.009842)
		(end 179.516024 -285.735268)
		(width 0.16002)
		(layer "In2.Cu")
		(net "M_I_CPU1_SB_DQS_DN<5>")
	)
	(segment
		(start 138.206226 -276.841458)
		(end 138.214608 -276.846284)
		(width 0.09525)
		(layer "In2.Cu")
		(net "M_I_CPU1_SB_DQS_DN<5>")
	)
	(segment
		(start 137.266172 -276.841458)
		(end 137.274554 -276.846284)
		(width 0.09525)
		(layer "In2.Cu")
		(net "M_I_CPU1_SB_DQS_DN<5>")
	)
	(segment
		(start 152.38857 -276.37994)
		(end 152.817068 -276.808438)
		(width 0.16002)
		(layer "In2.Cu")
		(net "M_I_CPU1_SB_DQS_DN<5>")
	)
	(segment
		(start 147.195794 -275.577554)
		(end 147.493482 -275.875242)
		(width 0.09525)
		(layer "In2.Cu")
		(net "M_I_CPU1_SB_DQS_DN<5>")
	)
	(segment
		(start 160.187894 -283.649928)
		(end 160.796478 -283.649928)
		(width 0.16002)
		(layer "In2.Cu")
		(net "M_I_CPU1_SB_DQS_DN<5>")
	)
	(segment
		(start 163.546028 -287.008062)
		(end 165.193472 -287.008062)
		(width 0.16002)
		(layer "In2.Cu")
		(net "M_I_CPU1_SB_DQS_DN<5>")
	)
	(arc
		(start 139.523216 -276.841458)
		(mid 139.804648 -276.765703)
		(end 140.08608 -276.841458)
		(width 0.09525)
		(layer "In2.Cu")
		(net "M_I_CPU1_SB_DQS_DN<5>")
	)
	(arc
		(start 141.97457 -276.846284)
		(mid 142.159602 -276.892198)
		(end 142.343378 -276.841458)
		(width 0.09525)
		(layer "In2.Cu")
		(net "M_I_CPU1_SB_DQS_DN<5>")
	)
	(arc
		(start 133.8834 -276.841458)
		(mid 134.164832 -276.765703)
		(end 134.446264 -276.841458)
		(width 0.09525)
		(layer "In2.Cu")
		(net "M_I_CPU1_SB_DQS_DN<5>")
	)
	(arc
		(start 141.403324 -276.841458)
		(mid 141.684756 -276.765703)
		(end 141.966188 -276.841458)
		(width 0.09525)
		(layer "In2.Cu")
		(net "M_I_CPU1_SB_DQS_DN<5>")
	)
	(arc
		(start 134.446264 -276.841458)
		(mid 134.634732 -276.892135)
		(end 134.8232 -276.841458)
		(width 0.09525)
		(layer "In2.Cu")
		(net "M_I_CPU1_SB_DQS_DN<5>")
	)
	(arc
		(start 141.026134 -276.841458)
		(mid 141.209909 -276.89223)
		(end 141.394942 -276.846284)
		(width 0.09525)
		(layer "In2.Cu")
		(net "M_I_CPU1_SB_DQS_DN<5>")
	)
	(arc
		(start 140.46327 -276.841458)
		(mid 140.744702 -276.765703)
		(end 141.026134 -276.841458)
		(width 0.09525)
		(layer "In2.Cu")
		(net "M_I_CPU1_SB_DQS_DN<5>")
	)
	(arc
		(start 128.309624 -276.808438)
		(mid 128.319492 -276.804407)
		(end 128.329436 -276.800564)
		(width 0.09525)
		(layer "In2.Cu")
		(net "M_I_CPU1_SB_DQS_DN<5>")
	)
	(arc
		(start 135.763254 -276.841458)
		(mid 136.044686 -276.765703)
		(end 136.326118 -276.841458)
		(width 0.09525)
		(layer "In2.Cu")
		(net "M_I_CPU1_SB_DQS_DN<5>")
	)
	(arc
		(start 131.626102 -276.841458)
		(mid 131.809877 -276.89223)
		(end 131.99491 -276.846284)
		(width 0.09525)
		(layer "In2.Cu")
		(net "M_I_CPU1_SB_DQS_DN<5>")
	)
	(arc
		(start 132.003292 -276.841458)
		(mid 132.284724 -276.765703)
		(end 132.566156 -276.841458)
		(width 0.09525)
		(layer "In2.Cu")
		(net "M_I_CPU1_SB_DQS_DN<5>")
	)
	(arc
		(start 128.814576 -276.846284)
		(mid 128.999608 -276.892198)
		(end 129.183384 -276.841458)
		(width 0.09525)
		(layer "In2.Cu")
		(net "M_I_CPU1_SB_DQS_DN<5>")
	)
	(arc
		(start 132.566156 -276.841458)
		(mid 132.749931 -276.89223)
		(end 132.934964 -276.846284)
		(width 0.09525)
		(layer "In2.Cu")
		(net "M_I_CPU1_SB_DQS_DN<5>")
	)
	(arc
		(start 129.183384 -276.841458)
		(mid 129.464816 -276.765703)
		(end 129.746248 -276.841458)
		(width 0.09525)
		(layer "In2.Cu")
		(net "M_I_CPU1_SB_DQS_DN<5>")
	)
	(arc
		(start 135.386064 -276.841458)
		(mid 135.569839 -276.89223)
		(end 135.754872 -276.846284)
		(width 0.09525)
		(layer "In2.Cu")
		(net "M_I_CPU1_SB_DQS_DN<5>")
	)
	(arc
		(start 134.8232 -276.841458)
		(mid 135.104632 -276.765703)
		(end 135.386064 -276.841458)
		(width 0.09525)
		(layer "In2.Cu")
		(net "M_I_CPU1_SB_DQS_DN<5>")
	)
	(arc
		(start 140.08608 -276.841458)
		(mid 140.269855 -276.89223)
		(end 140.454888 -276.846284)
		(width 0.09525)
		(layer "In2.Cu")
		(net "M_I_CPU1_SB_DQS_DN<5>")
	)
	(arc
		(start 142.906242 -276.841458)
		(mid 143.09471 -276.892135)
		(end 143.283178 -276.841458)
		(width 0.09525)
		(layer "In2.Cu")
		(net "M_I_CPU1_SB_DQS_DN<5>")
	)
	(arc
		(start 130.686302 -276.841458)
		(mid 130.87477 -276.892135)
		(end 131.063238 -276.841458)
		(width 0.09525)
		(layer "In2.Cu")
		(net "M_I_CPU1_SB_DQS_DN<5>")
	)
	(arc
		(start 144.806162 -276.85492)
		(mid 144.98535 -276.892765)
		(end 145.161254 -276.841712)
		(width 0.09525)
		(layer "In2.Cu")
		(net "M_I_CPU1_SB_DQS_DN<5>")
	)
	(arc
		(start 139.14628 -276.841458)
		(mid 139.334748 -276.892135)
		(end 139.523216 -276.841458)
		(width 0.09525)
		(layer "In2.Cu")
		(net "M_I_CPU1_SB_DQS_DN<5>")
	)
	(arc
		(start 132.943346 -276.841458)
		(mid 133.224778 -276.765703)
		(end 133.50621 -276.841458)
		(width 0.09525)
		(layer "In2.Cu")
		(net "M_I_CPU1_SB_DQS_DN<5>")
	)
	(arc
		(start 143.283178 -276.841458)
		(mid 143.56461 -276.765703)
		(end 143.846042 -276.841458)
		(width 0.09525)
		(layer "In2.Cu")
		(net "M_I_CPU1_SB_DQS_DN<5>")
	)
	(arc
		(start 128.329436 -276.800564)
		(mid 128.5724 -276.767577)
		(end 128.806194 -276.841458)
		(width 0.09525)
		(layer "In2.Cu")
		(net "M_I_CPU1_SB_DQS_DN<5>")
	)
	(arc
		(start 145.161254 -276.841712)
		(mid 145.406563 -276.677802)
		(end 145.695924 -276.620224)
		(width 0.09525)
		(layer "In2.Cu")
		(net "M_I_CPU1_SB_DQS_DN<5>")
	)
	(arc
		(start 137.274554 -276.846284)
		(mid 137.459586 -276.892198)
		(end 137.643362 -276.841458)
		(width 0.09525)
		(layer "In2.Cu")
		(net "M_I_CPU1_SB_DQS_DN<5>")
	)
	(arc
		(start 130.123438 -276.841458)
		(mid 130.40487 -276.765703)
		(end 130.686302 -276.841458)
		(width 0.09525)
		(layer "In2.Cu")
		(net "M_I_CPU1_SB_DQS_DN<5>")
	)
	(arc
		(start 133.514592 -276.846284)
		(mid 133.699624 -276.892198)
		(end 133.8834 -276.841458)
		(width 0.09525)
		(layer "In2.Cu")
		(net "M_I_CPU1_SB_DQS_DN<5>")
	)
	(arc
		(start 144.24787 -276.826218)
		(mid 144.517276 -276.76587)
		(end 144.782794 -276.841458)
		(width 0.09525)
		(layer "In2.Cu")
		(net "M_I_CPU1_SB_DQS_DN<5>")
	)
	(arc
		(start 136.326118 -276.841458)
		(mid 136.509893 -276.89223)
		(end 136.694926 -276.846284)
		(width 0.09525)
		(layer "In2.Cu")
		(net "M_I_CPU1_SB_DQS_DN<5>")
	)
	(arc
		(start 129.75463 -276.846284)
		(mid 129.939662 -276.892198)
		(end 130.123438 -276.841458)
		(width 0.09525)
		(layer "In2.Cu")
		(net "M_I_CPU1_SB_DQS_DN<5>")
	)
	(arc
		(start 138.214608 -276.846284)
		(mid 138.39964 -276.892198)
		(end 138.583416 -276.841458)
		(width 0.09525)
		(layer "In2.Cu")
		(net "M_I_CPU1_SB_DQS_DN<5>")
	)
	(arc
		(start 142.343378 -276.841458)
		(mid 142.62481 -276.765703)
		(end 142.906242 -276.841458)
		(width 0.09525)
		(layer "In2.Cu")
		(net "M_I_CPU1_SB_DQS_DN<5>")
	)
	(arc
		(start 138.583416 -276.841458)
		(mid 138.864848 -276.765703)
		(end 139.14628 -276.841458)
		(width 0.09525)
		(layer "In2.Cu")
		(net "M_I_CPU1_SB_DQS_DN<5>")
	)
	(arc
		(start 136.703308 -276.841458)
		(mid 136.98474 -276.765703)
		(end 137.266172 -276.841458)
		(width 0.09525)
		(layer "In2.Cu")
		(net "M_I_CPU1_SB_DQS_DN<5>")
	)
	(arc
		(start 131.063238 -276.841458)
		(mid 131.34467 -276.765703)
		(end 131.626102 -276.841458)
		(width 0.09525)
		(layer "In2.Cu")
		(net "M_I_CPU1_SB_DQS_DN<5>")
	)
	(arc
		(start 143.846042 -276.841458)
		(mid 144.020674 -276.891998)
		(end 144.198594 -276.854666)
		(width 0.09525)
		(layer "In2.Cu")
		(net "M_I_CPU1_SB_DQS_DN<5>")
	)
	(arc
		(start 137.643362 -276.841458)
		(mid 137.924794 -276.765703)
		(end 138.206226 -276.841458)
		(width 0.09525)
		(layer "In2.Cu")
		(net "M_I_CPU1_SB_DQS_DN<5>")
	)
	(segment
		(start 127.58801 -271.390364)
		(end 128.054862 -271.656302)
		(width 0.12954)
		(layer "F.Cu")
		(net "M_I_CPU1_SB_DQS_DN<4>")
	)
	(segment
		(start 158.08325 -272.013426)
		(end 158.08325 -272.790158)
		(width 0.16002)
		(layer "In2.Cu")
		(net "M_I_CPU1_SB_DQS_DN<4>")
	)
	(segment
		(start 167.758364 -276.808184)
		(end 170.22191 -276.808184)
		(width 0.16002)
		(layer "In2.Cu")
		(net "M_I_CPU1_SB_DQS_DN<4>")
	)
	(segment
		(start 165.995096 -277.293324)
		(end 166.787576 -276.500844)
		(width 0.16002)
		(layer "In2.Cu")
		(net "M_I_CPU1_SB_DQS_DN<4>")
	)
	(segment
		(start 128.208786 -271.921732)
		(end 128.309624 -271.948402)
		(width 0.09525)
		(layer "In2.Cu")
		(net "M_I_CPU1_SB_DQS_DN<4>")
	)
	(segment
		(start 174.33163 -276.500844)
		(end 174.995078 -276.500844)
		(width 0.16002)
		(layer "In2.Cu")
		(net "M_I_CPU1_SB_DQS_DN<4>")
	)
	(segment
		(start 172.737272 -277.658322)
		(end 173.10227 -277.293324)
		(width 0.16002)
		(layer "In2.Cu")
		(net "M_I_CPU1_SB_DQS_DN<4>")
	)
	(segment
		(start 162.204146 -276.134322)
		(end 162.204146 -276.911054)
		(width 0.16002)
		(layer "In2.Cu")
		(net "M_I_CPU1_SB_DQS_DN<4>")
	)
	(segment
		(start 159.070294 -273.00047)
		(end 159.456882 -273.387058)
		(width 0.16002)
		(layer "In2.Cu")
		(net "M_I_CPU1_SB_DQS_DN<4>")
	)
	(segment
		(start 166.787576 -276.500844)
		(end 167.451024 -276.500844)
		(width 0.16002)
		(layer "In2.Cu")
		(net "M_I_CPU1_SB_DQS_DN<4>")
	)
	(segment
		(start 144.782794 -271.981422)
		(end 144.806162 -271.994884)
		(width 0.09525)
		(layer "In2.Cu")
		(net "M_I_CPU1_SB_DQS_DN<4>")
	)
	(segment
		(start 145.508472 -271.905476)
		(end 145.634456 -271.853152)
		(width 0.09525)
		(layer "In2.Cu")
		(net "M_I_CPU1_SB_DQS_DN<4>")
	)
	(segment
		(start 174.995078 -276.500844)
		(end 175.302418 -276.808184)
		(width 0.16002)
		(layer "In2.Cu")
		(net "M_I_CPU1_SB_DQS_DN<4>")
	)
	(segment
		(start 177.12563 -276.808184)
		(end 177.273966 -276.659848)
		(width 0.16002)
		(layer "In2.Cu")
		(net "M_I_CPU1_SB_DQS_DN<4>")
	)
	(segment
		(start 129.746248 -271.981422)
		(end 129.75463 -271.986248)
		(width 0.09525)
		(layer "In2.Cu")
		(net "M_I_CPU1_SB_DQS_DN<4>")
	)
	(segment
		(start 144.198594 -271.99463)
		(end 144.221962 -271.981168)
		(width 0.09525)
		(layer "In2.Cu")
		(net "M_I_CPU1_SB_DQS_DN<4>")
	)
	(segment
		(start 146.238468 -271.140174)
		(end 146.238468 -270.868394)
		(width 0.09525)
		(layer "In2.Cu")
		(net "M_I_CPU1_SB_DQS_DN<4>")
	)
	(segment
		(start 138.206226 -271.981422)
		(end 138.214608 -271.986248)
		(width 0.09525)
		(layer "In2.Cu")
		(net "M_I_CPU1_SB_DQS_DN<4>")
	)
	(segment
		(start 159.667194 -274.374102)
		(end 160.443926 -274.374102)
		(width 0.16002)
		(layer "In2.Cu")
		(net "M_I_CPU1_SB_DQS_DN<4>")
	)
	(segment
		(start 167.451024 -276.500844)
		(end 167.758364 -276.808184)
		(width 0.16002)
		(layer "In2.Cu")
		(net "M_I_CPU1_SB_DQS_DN<4>")
	)
	(segment
		(start 160.830514 -274.76069)
		(end 160.830514 -275.537422)
		(width 0.16002)
		(layer "In2.Cu")
		(net "M_I_CPU1_SB_DQS_DN<4>")
	)
	(segment
		(start 162.91433 -277.121366)
		(end 163.451032 -277.658068)
		(width 0.16002)
		(layer "In2.Cu")
		(net "M_I_CPU1_SB_DQS_DN<4>")
	)
	(segment
		(start 128.806194 -271.981422)
		(end 128.814576 -271.986248)
		(width 0.09525)
		(layer "In2.Cu")
		(net "M_I_CPU1_SB_DQS_DN<4>")
	)
	(segment
		(start 159.456882 -274.16379)
		(end 159.667194 -274.374102)
		(width 0.16002)
		(layer "In2.Cu")
		(net "M_I_CPU1_SB_DQS_DN<4>")
	)
	(segment
		(start 161.817558 -275.747734)
		(end 162.204146 -276.134322)
		(width 0.16002)
		(layer "In2.Cu")
		(net "M_I_CPU1_SB_DQS_DN<4>")
	)
	(segment
		(start 147.610322 -270.203676)
		(end 147.669504 -270.144494)
		(width 0.09525)
		(layer "In2.Cu")
		(net "M_I_CPU1_SB_DQS_DN<4>")
	)
	(segment
		(start 171.072048 -277.658322)
		(end 172.737272 -277.658322)
		(width 0.16002)
		(layer "In2.Cu")
		(net "M_I_CPU1_SB_DQS_DN<4>")
	)
	(segment
		(start 158.293562 -273.00047)
		(end 159.070294 -273.00047)
		(width 0.16002)
		(layer "In2.Cu")
		(net "M_I_CPU1_SB_DQS_DN<4>")
	)
	(segment
		(start 128.054862 -271.656302)
		(end 128.208786 -271.921732)
		(width 0.09525)
		(layer "In2.Cu")
		(net "M_I_CPU1_SB_DQS_DN<4>")
	)
	(segment
		(start 156.91993 -271.626838)
		(end 157.696662 -271.626838)
		(width 0.16002)
		(layer "In2.Cu")
		(net "M_I_CPU1_SB_DQS_DN<4>")
	)
	(segment
		(start 141.966188 -271.981422)
		(end 141.97457 -271.986248)
		(width 0.09525)
		(layer "In2.Cu")
		(net "M_I_CPU1_SB_DQS_DN<4>")
	)
	(segment
		(start 163.451032 -277.658068)
		(end 165.193472 -277.658068)
		(width 0.16002)
		(layer "In2.Cu")
		(net "M_I_CPU1_SB_DQS_DN<4>")
	)
	(segment
		(start 158.08325 -272.790158)
		(end 158.293562 -273.00047)
		(width 0.16002)
		(layer "In2.Cu")
		(net "M_I_CPU1_SB_DQS_DN<4>")
	)
	(segment
		(start 162.204146 -276.911054)
		(end 162.414458 -277.121366)
		(width 0.16002)
		(layer "In2.Cu")
		(net "M_I_CPU1_SB_DQS_DN<4>")
	)
	(segment
		(start 156.709618 -271.416526)
		(end 156.91993 -271.626838)
		(width 0.16002)
		(layer "In2.Cu")
		(net "M_I_CPU1_SB_DQS_DN<4>")
	)
	(segment
		(start 135.754872 -271.986248)
		(end 135.763254 -271.981422)
		(width 0.09525)
		(layer "In2.Cu")
		(net "M_I_CPU1_SB_DQS_DN<4>")
	)
	(segment
		(start 179.24145 -276.659848)
		(end 179.516024 -276.385274)
		(width 0.16002)
		(layer "In2.Cu")
		(net "M_I_CPU1_SB_DQS_DN<4>")
	)
	(segment
		(start 160.443926 -274.374102)
		(end 160.830514 -274.76069)
		(width 0.16002)
		(layer "In2.Cu")
		(net "M_I_CPU1_SB_DQS_DN<4>")
	)
	(segment
		(start 144.221962 -271.981168)
		(end 144.24787 -271.966182)
		(width 0.09525)
		(layer "In2.Cu")
		(net "M_I_CPU1_SB_DQS_DN<4>")
	)
	(segment
		(start 165.558216 -277.293324)
		(end 165.995096 -277.293324)
		(width 0.16002)
		(layer "In2.Cu")
		(net "M_I_CPU1_SB_DQS_DN<4>")
	)
	(segment
		(start 157.696662 -271.626838)
		(end 158.08325 -272.013426)
		(width 0.16002)
		(layer "In2.Cu")
		(net "M_I_CPU1_SB_DQS_DN<4>")
	)
	(segment
		(start 159.456882 -273.387058)
		(end 159.456882 -274.16379)
		(width 0.16002)
		(layer "In2.Cu")
		(net "M_I_CPU1_SB_DQS_DN<4>")
	)
	(segment
		(start 160.830514 -275.537422)
		(end 161.040826 -275.747734)
		(width 0.16002)
		(layer "In2.Cu")
		(net "M_I_CPU1_SB_DQS_DN<4>")
	)
	(segment
		(start 145.634456 -271.853152)
		(end 146.161506 -271.326102)
		(width 0.09525)
		(layer "In2.Cu")
		(net "M_I_CPU1_SB_DQS_DN<4>")
	)
	(segment
		(start 161.040826 -275.747734)
		(end 161.817558 -275.747734)
		(width 0.16002)
		(layer "In2.Cu")
		(net "M_I_CPU1_SB_DQS_DN<4>")
	)
	(segment
		(start 165.193472 -277.658068)
		(end 165.558216 -277.293324)
		(width 0.16002)
		(layer "In2.Cu")
		(net "M_I_CPU1_SB_DQS_DN<4>")
	)
	(segment
		(start 146.161506 -271.326102)
		(end 146.238468 -271.140174)
		(width 0.09525)
		(layer "In2.Cu")
		(net "M_I_CPU1_SB_DQS_DN<4>")
	)
	(segment
		(start 170.22191 -276.808184)
		(end 171.072048 -277.658322)
		(width 0.16002)
		(layer "In2.Cu")
		(net "M_I_CPU1_SB_DQS_DN<4>")
	)
	(segment
		(start 132.934964 -271.986248)
		(end 132.943346 -271.981422)
		(width 0.09525)
		(layer "In2.Cu")
		(net "M_I_CPU1_SB_DQS_DN<4>")
	)
	(segment
		(start 131.99491 -271.986248)
		(end 132.003292 -271.981422)
		(width 0.09525)
		(layer "In2.Cu")
		(net "M_I_CPU1_SB_DQS_DN<4>")
	)
	(segment
		(start 147.669504 -270.144494)
		(end 147.693126 -270.144494)
		(width 0.09525)
		(layer "In2.Cu")
		(net "M_I_CPU1_SB_DQS_DN<4>")
	)
	(segment
		(start 173.10227 -277.293324)
		(end 173.53915 -277.293324)
		(width 0.16002)
		(layer "In2.Cu")
		(net "M_I_CPU1_SB_DQS_DN<4>")
	)
	(segment
		(start 146.238468 -270.868394)
		(end 146.903186 -270.203676)
		(width 0.09525)
		(layer "In2.Cu")
		(net "M_I_CPU1_SB_DQS_DN<4>")
	)
	(segment
		(start 177.273966 -276.659848)
		(end 179.24145 -276.659848)
		(width 0.16002)
		(layer "In2.Cu")
		(net "M_I_CPU1_SB_DQS_DN<4>")
	)
	(segment
		(start 133.50621 -271.981422)
		(end 133.514592 -271.986248)
		(width 0.09525)
		(layer "In2.Cu")
		(net "M_I_CPU1_SB_DQS_DN<4>")
	)
	(segment
		(start 140.454888 -271.986248)
		(end 140.46327 -271.981422)
		(width 0.09525)
		(layer "In2.Cu")
		(net "M_I_CPU1_SB_DQS_DN<4>")
	)
	(segment
		(start 145.161254 -271.981676)
		(end 145.161762 -271.98193)
		(width 0.09525)
		(layer "In2.Cu")
		(net "M_I_CPU1_SB_DQS_DN<4>")
	)
	(segment
		(start 173.53915 -277.293324)
		(end 174.33163 -276.500844)
		(width 0.16002)
		(layer "In2.Cu")
		(net "M_I_CPU1_SB_DQS_DN<4>")
	)
	(segment
		(start 136.694926 -271.986248)
		(end 136.703308 -271.981422)
		(width 0.09525)
		(layer "In2.Cu")
		(net "M_I_CPU1_SB_DQS_DN<4>")
	)
	(segment
		(start 146.903186 -270.203676)
		(end 147.610322 -270.203676)
		(width 0.09525)
		(layer "In2.Cu")
		(net "M_I_CPU1_SB_DQS_DN<4>")
	)
	(segment
		(start 156.214318 -270.144494)
		(end 156.709618 -270.639794)
		(width 0.16002)
		(layer "In2.Cu")
		(net "M_I_CPU1_SB_DQS_DN<4>")
	)
	(segment
		(start 141.394942 -271.986248)
		(end 141.403324 -271.981422)
		(width 0.09525)
		(layer "In2.Cu")
		(net "M_I_CPU1_SB_DQS_DN<4>")
	)
	(segment
		(start 156.709618 -270.639794)
		(end 156.709618 -271.416526)
		(width 0.16002)
		(layer "In2.Cu")
		(net "M_I_CPU1_SB_DQS_DN<4>")
	)
	(segment
		(start 147.693126 -270.144494)
		(end 156.214318 -270.144494)
		(width 0.16002)
		(layer "In2.Cu")
		(net "M_I_CPU1_SB_DQS_DN<4>")
	)
	(segment
		(start 137.266172 -271.981422)
		(end 137.274554 -271.986248)
		(width 0.09525)
		(layer "In2.Cu")
		(net "M_I_CPU1_SB_DQS_DN<4>")
	)
	(segment
		(start 175.302418 -276.808184)
		(end 177.12563 -276.808184)
		(width 0.16002)
		(layer "In2.Cu")
		(net "M_I_CPU1_SB_DQS_DN<4>")
	)
	(segment
		(start 145.447258 -271.905476)
		(end 145.508472 -271.905476)
		(width 0.09525)
		(layer "In2.Cu")
		(net "M_I_CPU1_SB_DQS_DN<4>")
	)
	(segment
		(start 162.414458 -277.121366)
		(end 162.91433 -277.121366)
		(width 0.16002)
		(layer "In2.Cu")
		(net "M_I_CPU1_SB_DQS_DN<4>")
	)
	(arc
		(start 136.326118 -271.981422)
		(mid 136.509893 -272.032194)
		(end 136.694926 -271.986248)
		(width 0.09525)
		(layer "In2.Cu")
		(net "M_I_CPU1_SB_DQS_DN<4>")
	)
	(arc
		(start 134.446264 -271.981422)
		(mid 134.634732 -272.032099)
		(end 134.8232 -271.981422)
		(width 0.09525)
		(layer "In2.Cu")
		(net "M_I_CPU1_SB_DQS_DN<4>")
	)
	(arc
		(start 128.309624 -271.948402)
		(mid 128.561765 -271.906832)
		(end 128.806194 -271.981422)
		(width 0.09525)
		(layer "In2.Cu")
		(net "M_I_CPU1_SB_DQS_DN<4>")
	)
	(arc
		(start 141.97457 -271.986248)
		(mid 142.159602 -272.032162)
		(end 142.343378 -271.981422)
		(width 0.09525)
		(layer "In2.Cu")
		(net "M_I_CPU1_SB_DQS_DN<4>")
	)
	(arc
		(start 136.703308 -271.981422)
		(mid 136.98474 -271.905667)
		(end 137.266172 -271.981422)
		(width 0.09525)
		(layer "In2.Cu")
		(net "M_I_CPU1_SB_DQS_DN<4>")
	)
	(arc
		(start 141.026134 -271.981422)
		(mid 141.209909 -272.032194)
		(end 141.394942 -271.986248)
		(width 0.09525)
		(layer "In2.Cu")
		(net "M_I_CPU1_SB_DQS_DN<4>")
	)
	(arc
		(start 139.14628 -271.981422)
		(mid 139.334748 -272.032099)
		(end 139.523216 -271.981422)
		(width 0.09525)
		(layer "In2.Cu")
		(net "M_I_CPU1_SB_DQS_DN<4>")
	)
	(arc
		(start 130.686302 -271.981422)
		(mid 130.87477 -272.032099)
		(end 131.063238 -271.981422)
		(width 0.09525)
		(layer "In2.Cu")
		(net "M_I_CPU1_SB_DQS_DN<4>")
	)
	(arc
		(start 141.403324 -271.981422)
		(mid 141.684756 -271.905667)
		(end 141.966188 -271.981422)
		(width 0.09525)
		(layer "In2.Cu")
		(net "M_I_CPU1_SB_DQS_DN<4>")
	)
	(arc
		(start 129.183384 -271.981422)
		(mid 129.464816 -271.905667)
		(end 129.746248 -271.981422)
		(width 0.09525)
		(layer "In2.Cu")
		(net "M_I_CPU1_SB_DQS_DN<4>")
	)
	(arc
		(start 143.283178 -271.981422)
		(mid 143.56461 -271.905667)
		(end 143.846042 -271.981422)
		(width 0.09525)
		(layer "In2.Cu")
		(net "M_I_CPU1_SB_DQS_DN<4>")
	)
	(arc
		(start 140.46327 -271.981422)
		(mid 140.744702 -271.905667)
		(end 141.026134 -271.981422)
		(width 0.09525)
		(layer "In2.Cu")
		(net "M_I_CPU1_SB_DQS_DN<4>")
	)
	(arc
		(start 132.566156 -271.981422)
		(mid 132.749931 -272.032194)
		(end 132.934964 -271.986248)
		(width 0.09525)
		(layer "In2.Cu")
		(net "M_I_CPU1_SB_DQS_DN<4>")
	)
	(arc
		(start 135.763254 -271.981422)
		(mid 136.044686 -271.905667)
		(end 136.326118 -271.981422)
		(width 0.09525)
		(layer "In2.Cu")
		(net "M_I_CPU1_SB_DQS_DN<4>")
	)
	(arc
		(start 129.75463 -271.986248)
		(mid 129.939662 -272.032162)
		(end 130.123438 -271.981422)
		(width 0.09525)
		(layer "In2.Cu")
		(net "M_I_CPU1_SB_DQS_DN<4>")
	)
	(arc
		(start 143.846042 -271.981422)
		(mid 144.020674 -272.031962)
		(end 144.198594 -271.99463)
		(width 0.09525)
		(layer "In2.Cu")
		(net "M_I_CPU1_SB_DQS_DN<4>")
	)
	(arc
		(start 131.626102 -271.981422)
		(mid 131.809877 -272.032194)
		(end 131.99491 -271.986248)
		(width 0.09525)
		(layer "In2.Cu")
		(net "M_I_CPU1_SB_DQS_DN<4>")
	)
	(arc
		(start 145.161762 -271.98193)
		(mid 145.299383 -271.924557)
		(end 145.447258 -271.905476)
		(width 0.09525)
		(layer "In2.Cu")
		(net "M_I_CPU1_SB_DQS_DN<4>")
	)
	(arc
		(start 128.814576 -271.986248)
		(mid 128.999608 -272.032162)
		(end 129.183384 -271.981422)
		(width 0.09525)
		(layer "In2.Cu")
		(net "M_I_CPU1_SB_DQS_DN<4>")
	)
	(arc
		(start 138.214608 -271.986248)
		(mid 138.39964 -272.032162)
		(end 138.583416 -271.981422)
		(width 0.09525)
		(layer "In2.Cu")
		(net "M_I_CPU1_SB_DQS_DN<4>")
	)
	(arc
		(start 137.643362 -271.981422)
		(mid 137.924794 -271.905667)
		(end 138.206226 -271.981422)
		(width 0.09525)
		(layer "In2.Cu")
		(net "M_I_CPU1_SB_DQS_DN<4>")
	)
	(arc
		(start 138.583416 -271.981422)
		(mid 138.864848 -271.905667)
		(end 139.14628 -271.981422)
		(width 0.09525)
		(layer "In2.Cu")
		(net "M_I_CPU1_SB_DQS_DN<4>")
	)
	(arc
		(start 139.523216 -271.981422)
		(mid 139.804648 -271.905667)
		(end 140.08608 -271.981422)
		(width 0.09525)
		(layer "In2.Cu")
		(net "M_I_CPU1_SB_DQS_DN<4>")
	)
	(arc
		(start 135.386064 -271.981422)
		(mid 135.569839 -272.032194)
		(end 135.754872 -271.986248)
		(width 0.09525)
		(layer "In2.Cu")
		(net "M_I_CPU1_SB_DQS_DN<4>")
	)
	(arc
		(start 132.003292 -271.981422)
		(mid 132.284724 -271.905667)
		(end 132.566156 -271.981422)
		(width 0.09525)
		(layer "In2.Cu")
		(net "M_I_CPU1_SB_DQS_DN<4>")
	)
	(arc
		(start 137.274554 -271.986248)
		(mid 137.459586 -272.032162)
		(end 137.643362 -271.981422)
		(width 0.09525)
		(layer "In2.Cu")
		(net "M_I_CPU1_SB_DQS_DN<4>")
	)
	(arc
		(start 132.943346 -271.981422)
		(mid 133.224778 -271.905667)
		(end 133.50621 -271.981422)
		(width 0.09525)
		(layer "In2.Cu")
		(net "M_I_CPU1_SB_DQS_DN<4>")
	)
	(arc
		(start 142.906242 -271.981422)
		(mid 143.09471 -272.032099)
		(end 143.283178 -271.981422)
		(width 0.09525)
		(layer "In2.Cu")
		(net "M_I_CPU1_SB_DQS_DN<4>")
	)
	(arc
		(start 144.806162 -271.994884)
		(mid 144.98535 -272.032729)
		(end 145.161254 -271.981676)
		(width 0.09525)
		(layer "In2.Cu")
		(net "M_I_CPU1_SB_DQS_DN<4>")
	)
	(arc
		(start 133.514592 -271.986248)
		(mid 133.699624 -272.032162)
		(end 133.8834 -271.981422)
		(width 0.09525)
		(layer "In2.Cu")
		(net "M_I_CPU1_SB_DQS_DN<4>")
	)
	(arc
		(start 142.343378 -271.981422)
		(mid 142.62481 -271.905667)
		(end 142.906242 -271.981422)
		(width 0.09525)
		(layer "In2.Cu")
		(net "M_I_CPU1_SB_DQS_DN<4>")
	)
	(arc
		(start 130.123438 -271.981422)
		(mid 130.40487 -271.905667)
		(end 130.686302 -271.981422)
		(width 0.09525)
		(layer "In2.Cu")
		(net "M_I_CPU1_SB_DQS_DN<4>")
	)
	(arc
		(start 140.08608 -271.981422)
		(mid 140.269855 -272.032194)
		(end 140.454888 -271.986248)
		(width 0.09525)
		(layer "In2.Cu")
		(net "M_I_CPU1_SB_DQS_DN<4>")
	)
	(arc
		(start 133.8834 -271.981422)
		(mid 134.164832 -271.905667)
		(end 134.446264 -271.981422)
		(width 0.09525)
		(layer "In2.Cu")
		(net "M_I_CPU1_SB_DQS_DN<4>")
	)
	(arc
		(start 134.8232 -271.981422)
		(mid 135.104632 -271.905667)
		(end 135.386064 -271.981422)
		(width 0.09525)
		(layer "In2.Cu")
		(net "M_I_CPU1_SB_DQS_DN<4>")
	)
	(arc
		(start 131.063238 -271.981422)
		(mid 131.34467 -271.905667)
		(end 131.626102 -271.981422)
		(width 0.09525)
		(layer "In2.Cu")
		(net "M_I_CPU1_SB_DQS_DN<4>")
	)
	(arc
		(start 144.24787 -271.966182)
		(mid 144.517276 -271.905834)
		(end 144.782794 -271.981422)
		(width 0.09525)
		(layer "In2.Cu")
		(net "M_I_CPU1_SB_DQS_DN<4>")
	)
	(segment
		(start 129.467864 -290.830254)
		(end 129.934716 -291.096192)
		(width 0.12954)
		(layer "F.Cu")
		(net "M_I_CPU1_SB_DQS_DN<3>")
	)
	(segment
		(start 144.65681 -293.179754)
		(end 144.693386 -293.20109)
		(width 0.09525)
		(layer "In2.Cu")
		(net "M_I_CPU1_SB_DQS_DN<3>")
	)
	(segment
		(start 165.207696 -313.36234)
		(end 165.515036 -313.66968)
		(width 0.16002)
		(layer "In2.Cu")
		(net "M_I_CPU1_SB_DQS_DN<3>")
	)
	(segment
		(start 135.754872 -290.766246)
		(end 135.763254 -290.771072)
		(width 0.09525)
		(layer "In2.Cu")
		(net "M_I_CPU1_SB_DQS_DN<3>")
	)
	(segment
		(start 137.266172 -290.771072)
		(end 137.274554 -290.766246)
		(width 0.09525)
		(layer "In2.Cu")
		(net "M_I_CPU1_SB_DQS_DN<3>")
	)
	(segment
		(start 166.948104 -312.82894)
		(end 167.473376 -312.82894)
		(width 0.16002)
		(layer "In2.Cu")
		(net "M_I_CPU1_SB_DQS_DN<3>")
	)
	(segment
		(start 145.822416 -295.146222)
		(end 145.822416 -295.433242)
		(width 0.09525)
		(layer "In2.Cu")
		(net "M_I_CPU1_SB_DQS_DN<3>")
	)
	(segment
		(start 129.780792 -290.830762)
		(end 129.80416 -290.743894)
		(width 0.09525)
		(layer "In2.Cu")
		(net "M_I_CPU1_SB_DQS_DN<3>")
	)
	(segment
		(start 147.077176 -298.263564)
		(end 154.392376 -305.578764)
		(width 0.16002)
		(layer "In2.Cu")
		(net "M_I_CPU1_SB_DQS_DN<3>")
	)
	(segment
		(start 175.333914 -312.512456)
		(end 177.360326 -312.512456)
		(width 0.16002)
		(layer "In2.Cu")
		(net "M_I_CPU1_SB_DQS_DN<3>")
	)
	(segment
		(start 181.489858 -313.5122)
		(end 183.343042 -313.5122)
		(width 0.16002)
		(layer "In2.Cu")
		(net "M_I_CPU1_SB_DQS_DN<3>")
	)
	(segment
		(start 166.107364 -313.66968)
		(end 166.948104 -312.82894)
		(width 0.16002)
		(layer "In2.Cu")
		(net "M_I_CPU1_SB_DQS_DN<3>")
	)
	(segment
		(start 132.934964 -290.766246)
		(end 132.943346 -290.771072)
		(width 0.09525)
		(layer "In2.Cu")
		(net "M_I_CPU1_SB_DQS_DN<3>")
	)
	(segment
		(start 180.019706 -313.086496)
		(end 180.62829 -313.69508)
		(width 0.16002)
		(layer "In2.Cu")
		(net "M_I_CPU1_SB_DQS_DN<3>")
	)
	(segment
		(start 173.651418 -313.66968)
		(end 174.492158 -312.82894)
		(width 0.16002)
		(layer "In2.Cu")
		(net "M_I_CPU1_SB_DQS_DN<3>")
	)
	(segment
		(start 145.633186 -294.821102)
		(end 145.665698 -294.839898)
		(width 0.09525)
		(layer "In2.Cu")
		(net "M_I_CPU1_SB_DQS_DN<3>")
	)
	(segment
		(start 169.76852 -312.512456)
		(end 170.618404 -313.36234)
		(width 0.16002)
		(layer "In2.Cu")
		(net "M_I_CPU1_SB_DQS_DN<3>")
	)
	(segment
		(start 146.440144 -296.05097)
		(end 146.440144 -296.235374)
		(width 0.09525)
		(layer "In2.Cu")
		(net "M_I_CPU1_SB_DQS_DN<3>")
	)
	(segment
		(start 144.693386 -293.20109)
		(end 144.724882 -293.219378)
		(width 0.09525)
		(layer "In2.Cu")
		(net "M_I_CPU1_SB_DQS_DN<3>")
	)
	(segment
		(start 141.966188 -290.771072)
		(end 141.97457 -290.766246)
		(width 0.09525)
		(layer "In2.Cu")
		(net "M_I_CPU1_SB_DQS_DN<3>")
	)
	(segment
		(start 146.381216 -296.5831)
		(end 147.077176 -298.263564)
		(width 0.16002)
		(layer "In2.Cu")
		(net "M_I_CPU1_SB_DQS_DN<3>")
	)
	(segment
		(start 172.75175 -313.36234)
		(end 173.05909 -313.66968)
		(width 0.16002)
		(layer "In2.Cu")
		(net "M_I_CPU1_SB_DQS_DN<3>")
	)
	(segment
		(start 145.822416 -295.433242)
		(end 146.440144 -296.05097)
		(width 0.09525)
		(layer "In2.Cu")
		(net "M_I_CPU1_SB_DQS_DN<3>")
	)
	(segment
		(start 129.934716 -291.096192)
		(end 129.780792 -290.830762)
		(width 0.09525)
		(layer "In2.Cu")
		(net "M_I_CPU1_SB_DQS_DN<3>")
	)
	(segment
		(start 145.125186 -293.988998)
		(end 145.163286 -294.011096)
		(width 0.09525)
		(layer "In2.Cu")
		(net "M_I_CPU1_SB_DQS_DN<3>")
	)
	(segment
		(start 146.381216 -296.317924)
		(end 146.381216 -296.5831)
		(width 0.16002)
		(layer "In2.Cu")
		(net "M_I_CPU1_SB_DQS_DN<3>")
	)
	(segment
		(start 161.338768 -313.36234)
		(end 165.207696 -313.36234)
		(width 0.16002)
		(layer "In2.Cu")
		(net "M_I_CPU1_SB_DQS_DN<3>")
	)
	(segment
		(start 181.306978 -313.69508)
		(end 181.489858 -313.5122)
		(width 0.16002)
		(layer "In2.Cu")
		(net "M_I_CPU1_SB_DQS_DN<3>")
	)
	(segment
		(start 146.440144 -296.235374)
		(end 146.381216 -296.294302)
		(width 0.09525)
		(layer "In2.Cu")
		(net "M_I_CPU1_SB_DQS_DN<3>")
	)
	(segment
		(start 154.392376 -306.415948)
		(end 161.338768 -313.36234)
		(width 0.16002)
		(layer "In2.Cu")
		(net "M_I_CPU1_SB_DQS_DN<3>")
	)
	(segment
		(start 146.381216 -296.294302)
		(end 146.381216 -296.317924)
		(width 0.09525)
		(layer "In2.Cu")
		(net "M_I_CPU1_SB_DQS_DN<3>")
	)
	(segment
		(start 177.934366 -313.086496)
		(end 180.019706 -313.086496)
		(width 0.16002)
		(layer "In2.Cu")
		(net "M_I_CPU1_SB_DQS_DN<3>")
	)
	(segment
		(start 180.62829 -313.69508)
		(end 181.306978 -313.69508)
		(width 0.16002)
		(layer "In2.Cu")
		(net "M_I_CPU1_SB_DQS_DN<3>")
	)
	(segment
		(start 177.360326 -312.512456)
		(end 177.934366 -313.086496)
		(width 0.16002)
		(layer "In2.Cu")
		(net "M_I_CPU1_SB_DQS_DN<3>")
	)
	(segment
		(start 144.223486 -292.391084)
		(end 144.257268 -292.410642)
		(width 0.09525)
		(layer "In2.Cu")
		(net "M_I_CPU1_SB_DQS_DN<3>")
	)
	(segment
		(start 173.05909 -313.66968)
		(end 173.651418 -313.66968)
		(width 0.16002)
		(layer "In2.Cu")
		(net "M_I_CPU1_SB_DQS_DN<3>")
	)
	(segment
		(start 154.392376 -305.578764)
		(end 154.392376 -306.415948)
		(width 0.16002)
		(layer "In2.Cu")
		(net "M_I_CPU1_SB_DQS_DN<3>")
	)
	(segment
		(start 143.283178 -290.771072)
		(end 143.31569 -290.789868)
		(width 0.09525)
		(layer "In2.Cu")
		(net "M_I_CPU1_SB_DQS_DN<3>")
	)
	(segment
		(start 174.492158 -312.82894)
		(end 175.01743 -312.82894)
		(width 0.16002)
		(layer "In2.Cu")
		(net "M_I_CPU1_SB_DQS_DN<3>")
	)
	(segment
		(start 143.753332 -291.581078)
		(end 143.784828 -291.599366)
		(width 0.09525)
		(layer "In2.Cu")
		(net "M_I_CPU1_SB_DQS_DN<3>")
	)
	(segment
		(start 144.185386 -292.368986)
		(end 144.223486 -292.391084)
		(width 0.09525)
		(layer "In2.Cu")
		(net "M_I_CPU1_SB_DQS_DN<3>")
	)
	(segment
		(start 165.515036 -313.66968)
		(end 166.107364 -313.66968)
		(width 0.16002)
		(layer "In2.Cu")
		(net "M_I_CPU1_SB_DQS_DN<3>")
	)
	(segment
		(start 131.99491 -290.766246)
		(end 132.003292 -290.771072)
		(width 0.09525)
		(layer "In2.Cu")
		(net "M_I_CPU1_SB_DQS_DN<3>")
	)
	(segment
		(start 140.454888 -290.766246)
		(end 140.46327 -290.771072)
		(width 0.09525)
		(layer "In2.Cu")
		(net "M_I_CPU1_SB_DQS_DN<3>")
	)
	(segment
		(start 170.618404 -313.36234)
		(end 172.75175 -313.36234)
		(width 0.16002)
		(layer "In2.Cu")
		(net "M_I_CPU1_SB_DQS_DN<3>")
	)
	(segment
		(start 143.942308 -291.906198)
		(end 143.942562 -291.906198)
		(width 0.09525)
		(layer "In2.Cu")
		(net "M_I_CPU1_SB_DQS_DN<3>")
	)
	(segment
		(start 183.343042 -313.5122)
		(end 183.616092 -313.78525)
		(width 0.16002)
		(layer "In2.Cu")
		(net "M_I_CPU1_SB_DQS_DN<3>")
	)
	(segment
		(start 138.206226 -290.771072)
		(end 138.214608 -290.766246)
		(width 0.09525)
		(layer "In2.Cu")
		(net "M_I_CPU1_SB_DQS_DN<3>")
	)
	(segment
		(start 133.50621 -290.771072)
		(end 133.514592 -290.766246)
		(width 0.09525)
		(layer "In2.Cu")
		(net "M_I_CPU1_SB_DQS_DN<3>")
	)
	(segment
		(start 167.473376 -312.82894)
		(end 167.78986 -312.512456)
		(width 0.16002)
		(layer "In2.Cu")
		(net "M_I_CPU1_SB_DQS_DN<3>")
	)
	(segment
		(start 141.394942 -290.766246)
		(end 141.403324 -290.771072)
		(width 0.09525)
		(layer "In2.Cu")
		(net "M_I_CPU1_SB_DQS_DN<3>")
	)
	(segment
		(start 145.163286 -294.011096)
		(end 145.194782 -294.029384)
		(width 0.09525)
		(layer "In2.Cu")
		(net "M_I_CPU1_SB_DQS_DN<3>")
	)
	(segment
		(start 145.595086 -294.799004)
		(end 145.633186 -294.821102)
		(width 0.09525)
		(layer "In2.Cu")
		(net "M_I_CPU1_SB_DQS_DN<3>")
	)
	(segment
		(start 175.01743 -312.82894)
		(end 175.333914 -312.512456)
		(width 0.16002)
		(layer "In2.Cu")
		(net "M_I_CPU1_SB_DQS_DN<3>")
	)
	(segment
		(start 136.694926 -290.766246)
		(end 136.703308 -290.771072)
		(width 0.09525)
		(layer "In2.Cu")
		(net "M_I_CPU1_SB_DQS_DN<3>")
	)
	(segment
		(start 167.78986 -312.512456)
		(end 169.76852 -312.512456)
		(width 0.16002)
		(layer "In2.Cu")
		(net "M_I_CPU1_SB_DQS_DN<3>")
	)
	(segment
		(start 143.715232 -291.55898)
		(end 143.753332 -291.581078)
		(width 0.09525)
		(layer "In2.Cu")
		(net "M_I_CPU1_SB_DQS_DN<3>")
	)
	(arc
		(start 134.8232 -290.771072)
		(mid 135.104632 -290.846827)
		(end 135.386064 -290.771072)
		(width 0.09525)
		(layer "In2.Cu")
		(net "M_I_CPU1_SB_DQS_DN<3>")
	)
	(arc
		(start 138.583416 -290.771072)
		(mid 138.864848 -290.846827)
		(end 139.14628 -290.771072)
		(width 0.09525)
		(layer "In2.Cu")
		(net "M_I_CPU1_SB_DQS_DN<3>")
	)
	(arc
		(start 132.566156 -290.771072)
		(mid 132.749931 -290.7203)
		(end 132.934964 -290.766246)
		(width 0.09525)
		(layer "In2.Cu")
		(net "M_I_CPU1_SB_DQS_DN<3>")
	)
	(arc
		(start 134.446264 -290.771072)
		(mid 134.634732 -290.720395)
		(end 134.8232 -290.771072)
		(width 0.09525)
		(layer "In2.Cu")
		(net "M_I_CPU1_SB_DQS_DN<3>")
	)
	(arc
		(start 143.472408 -291.096192)
		(mid 143.536805 -291.357498)
		(end 143.715232 -291.55898)
		(width 0.09525)
		(layer "In2.Cu")
		(net "M_I_CPU1_SB_DQS_DN<3>")
	)
	(arc
		(start 142.343378 -290.771072)
		(mid 142.62481 -290.846827)
		(end 142.906242 -290.771072)
		(width 0.09525)
		(layer "In2.Cu")
		(net "M_I_CPU1_SB_DQS_DN<3>")
	)
	(arc
		(start 144.724882 -293.219378)
		(mid 144.84068 -293.353772)
		(end 144.882362 -293.52621)
		(width 0.09525)
		(layer "In2.Cu")
		(net "M_I_CPU1_SB_DQS_DN<3>")
	)
	(arc
		(start 145.352262 -294.336216)
		(mid 145.416659 -294.597522)
		(end 145.595086 -294.799004)
		(width 0.09525)
		(layer "In2.Cu")
		(net "M_I_CPU1_SB_DQS_DN<3>")
	)
	(arc
		(start 132.943346 -290.771072)
		(mid 133.224778 -290.846827)
		(end 133.50621 -290.771072)
		(width 0.09525)
		(layer "In2.Cu")
		(net "M_I_CPU1_SB_DQS_DN<3>")
	)
	(arc
		(start 143.784828 -291.599366)
		(mid 143.900626 -291.73376)
		(end 143.942308 -291.906198)
		(width 0.09525)
		(layer "In2.Cu")
		(net "M_I_CPU1_SB_DQS_DN<3>")
	)
	(arc
		(start 145.194782 -294.029384)
		(mid 145.31058 -294.163778)
		(end 145.352262 -294.336216)
		(width 0.09525)
		(layer "In2.Cu")
		(net "M_I_CPU1_SB_DQS_DN<3>")
	)
	(arc
		(start 143.31569 -290.789868)
		(mid 143.430964 -290.924146)
		(end 143.472408 -291.096192)
		(width 0.09525)
		(layer "In2.Cu")
		(net "M_I_CPU1_SB_DQS_DN<3>")
	)
	(arc
		(start 141.97457 -290.766246)
		(mid 142.159602 -290.720332)
		(end 142.343378 -290.771072)
		(width 0.09525)
		(layer "In2.Cu")
		(net "M_I_CPU1_SB_DQS_DN<3>")
	)
	(arc
		(start 140.08608 -290.771072)
		(mid 140.269855 -290.7203)
		(end 140.454888 -290.766246)
		(width 0.09525)
		(layer "In2.Cu")
		(net "M_I_CPU1_SB_DQS_DN<3>")
	)
	(arc
		(start 129.80416 -290.743894)
		(mid 129.966842 -290.721762)
		(end 130.123438 -290.771072)
		(width 0.09525)
		(layer "In2.Cu")
		(net "M_I_CPU1_SB_DQS_DN<3>")
	)
	(arc
		(start 145.665698 -294.839898)
		(mid 145.780972 -294.974176)
		(end 145.822416 -295.146222)
		(width 0.09525)
		(layer "In2.Cu")
		(net "M_I_CPU1_SB_DQS_DN<3>")
	)
	(arc
		(start 132.003292 -290.771072)
		(mid 132.284724 -290.846827)
		(end 132.566156 -290.771072)
		(width 0.09525)
		(layer "In2.Cu")
		(net "M_I_CPU1_SB_DQS_DN<3>")
	)
	(arc
		(start 135.386064 -290.771072)
		(mid 135.569839 -290.7203)
		(end 135.754872 -290.766246)
		(width 0.09525)
		(layer "In2.Cu")
		(net "M_I_CPU1_SB_DQS_DN<3>")
	)
	(arc
		(start 133.514592 -290.766246)
		(mid 133.699624 -290.720332)
		(end 133.8834 -290.771072)
		(width 0.09525)
		(layer "In2.Cu")
		(net "M_I_CPU1_SB_DQS_DN<3>")
	)
	(arc
		(start 139.14628 -290.771072)
		(mid 139.334748 -290.720395)
		(end 139.523216 -290.771072)
		(width 0.09525)
		(layer "In2.Cu")
		(net "M_I_CPU1_SB_DQS_DN<3>")
	)
	(arc
		(start 143.942562 -291.906198)
		(mid 144.006959 -292.167504)
		(end 144.185386 -292.368986)
		(width 0.09525)
		(layer "In2.Cu")
		(net "M_I_CPU1_SB_DQS_DN<3>")
	)
	(arc
		(start 131.063238 -290.771072)
		(mid 131.34467 -290.846827)
		(end 131.626102 -290.771072)
		(width 0.09525)
		(layer "In2.Cu")
		(net "M_I_CPU1_SB_DQS_DN<3>")
	)
	(arc
		(start 140.46327 -290.771072)
		(mid 140.744702 -290.846827)
		(end 141.026134 -290.771072)
		(width 0.09525)
		(layer "In2.Cu")
		(net "M_I_CPU1_SB_DQS_DN<3>")
	)
	(arc
		(start 137.643362 -290.771072)
		(mid 137.924794 -290.846827)
		(end 138.206226 -290.771072)
		(width 0.09525)
		(layer "In2.Cu")
		(net "M_I_CPU1_SB_DQS_DN<3>")
	)
	(arc
		(start 137.274554 -290.766246)
		(mid 137.459586 -290.720332)
		(end 137.643362 -290.771072)
		(width 0.09525)
		(layer "In2.Cu")
		(net "M_I_CPU1_SB_DQS_DN<3>")
	)
	(arc
		(start 136.703308 -290.771072)
		(mid 136.98474 -290.846827)
		(end 137.266172 -290.771072)
		(width 0.09525)
		(layer "In2.Cu")
		(net "M_I_CPU1_SB_DQS_DN<3>")
	)
	(arc
		(start 141.026134 -290.771072)
		(mid 141.209909 -290.7203)
		(end 141.394942 -290.766246)
		(width 0.09525)
		(layer "In2.Cu")
		(net "M_I_CPU1_SB_DQS_DN<3>")
	)
	(arc
		(start 144.412716 -292.716204)
		(mid 144.477476 -292.978139)
		(end 144.65681 -293.179754)
		(width 0.09525)
		(layer "In2.Cu")
		(net "M_I_CPU1_SB_DQS_DN<3>")
	)
	(arc
		(start 138.214608 -290.766246)
		(mid 138.39964 -290.720332)
		(end 138.583416 -290.771072)
		(width 0.09525)
		(layer "In2.Cu")
		(net "M_I_CPU1_SB_DQS_DN<3>")
	)
	(arc
		(start 130.686302 -290.771072)
		(mid 130.87477 -290.720395)
		(end 131.063238 -290.771072)
		(width 0.09525)
		(layer "In2.Cu")
		(net "M_I_CPU1_SB_DQS_DN<3>")
	)
	(arc
		(start 136.326118 -290.771072)
		(mid 136.509893 -290.7203)
		(end 136.694926 -290.766246)
		(width 0.09525)
		(layer "In2.Cu")
		(net "M_I_CPU1_SB_DQS_DN<3>")
	)
	(arc
		(start 142.906242 -290.771072)
		(mid 143.09471 -290.720395)
		(end 143.283178 -290.771072)
		(width 0.09525)
		(layer "In2.Cu")
		(net "M_I_CPU1_SB_DQS_DN<3>")
	)
	(arc
		(start 144.882362 -293.52621)
		(mid 144.946759 -293.787516)
		(end 145.125186 -293.988998)
		(width 0.09525)
		(layer "In2.Cu")
		(net "M_I_CPU1_SB_DQS_DN<3>")
	)
	(arc
		(start 141.403324 -290.771072)
		(mid 141.684756 -290.846827)
		(end 141.966188 -290.771072)
		(width 0.09525)
		(layer "In2.Cu")
		(net "M_I_CPU1_SB_DQS_DN<3>")
	)
	(arc
		(start 144.257268 -292.410642)
		(mid 144.371647 -292.544781)
		(end 144.412716 -292.716204)
		(width 0.09525)
		(layer "In2.Cu")
		(net "M_I_CPU1_SB_DQS_DN<3>")
	)
	(arc
		(start 133.8834 -290.771072)
		(mid 134.164832 -290.846827)
		(end 134.446264 -290.771072)
		(width 0.09525)
		(layer "In2.Cu")
		(net "M_I_CPU1_SB_DQS_DN<3>")
	)
	(arc
		(start 131.626102 -290.771072)
		(mid 131.809877 -290.7203)
		(end 131.99491 -290.766246)
		(width 0.09525)
		(layer "In2.Cu")
		(net "M_I_CPU1_SB_DQS_DN<3>")
	)
	(arc
		(start 135.763254 -290.771072)
		(mid 136.044686 -290.846827)
		(end 136.326118 -290.771072)
		(width 0.09525)
		(layer "In2.Cu")
		(net "M_I_CPU1_SB_DQS_DN<3>")
	)
	(arc
		(start 139.523216 -290.771072)
		(mid 139.804648 -290.846827)
		(end 140.08608 -290.771072)
		(width 0.09525)
		(layer "In2.Cu")
		(net "M_I_CPU1_SB_DQS_DN<3>")
	)
	(arc
		(start 130.123438 -290.771072)
		(mid 130.40487 -290.846827)
		(end 130.686302 -290.771072)
		(width 0.09525)
		(layer "In2.Cu")
		(net "M_I_CPU1_SB_DQS_DN<3>")
	)
	(segment
		(start 129.467864 -285.970472)
		(end 129.934716 -286.23641)
		(width 0.12954)
		(layer "F.Cu")
		(net "M_I_CPU1_SB_DQS_DN<2>")
	)
	(segment
		(start 170.618404 -304.012346)
		(end 172.75175 -304.012346)
		(width 0.16002)
		(layer "In2.Cu")
		(net "M_I_CPU1_SB_DQS_DN<2>")
	)
	(segment
		(start 180.019706 -303.736502)
		(end 180.62829 -304.345086)
		(width 0.16002)
		(layer "In2.Cu")
		(net "M_I_CPU1_SB_DQS_DN<2>")
	)
	(segment
		(start 166.107364 -304.319686)
		(end 166.948104 -303.478946)
		(width 0.16002)
		(layer "In2.Cu")
		(net "M_I_CPU1_SB_DQS_DN<2>")
	)
	(segment
		(start 160.491932 -303.75098)
		(end 160.86582 -304.124868)
		(width 0.16002)
		(layer "In2.Cu")
		(net "M_I_CPU1_SB_DQS_DN<2>")
	)
	(segment
		(start 169.76852 -303.162462)
		(end 170.618404 -304.012346)
		(width 0.16002)
		(layer "In2.Cu")
		(net "M_I_CPU1_SB_DQS_DN<2>")
	)
	(segment
		(start 144.21485 -285.906464)
		(end 144.223232 -285.91129)
		(width 0.09525)
		(layer "In2.Cu")
		(net "M_I_CPU1_SB_DQS_DN<2>")
	)
	(segment
		(start 177.934366 -303.736502)
		(end 180.019706 -303.736502)
		(width 0.16002)
		(layer "In2.Cu")
		(net "M_I_CPU1_SB_DQS_DN<2>")
	)
	(segment
		(start 182.08117 -304.162206)
		(end 183.343042 -304.162206)
		(width 0.16002)
		(layer "In2.Cu")
		(net "M_I_CPU1_SB_DQS_DN<2>")
	)
	(segment
		(start 161.76371 -303.754536)
		(end 162.04057 -303.754536)
		(width 0.16002)
		(layer "In2.Cu")
		(net "M_I_CPU1_SB_DQS_DN<2>")
	)
	(segment
		(start 133.50621 -285.91129)
		(end 133.514592 -285.906464)
		(width 0.09525)
		(layer "In2.Cu")
		(net "M_I_CPU1_SB_DQS_DN<2>")
	)
	(segment
		(start 132.934964 -285.906464)
		(end 132.943346 -285.91129)
		(width 0.09525)
		(layer "In2.Cu")
		(net "M_I_CPU1_SB_DQS_DN<2>")
	)
	(segment
		(start 147.412456 -287.588198)
		(end 147.688808 -287.864804)
		(width 0.09525)
		(layer "In2.Cu")
		(net "M_I_CPU1_SB_DQS_DN<2>")
	)
	(segment
		(start 165.207696 -304.012346)
		(end 165.515036 -304.319686)
		(width 0.16002)
		(layer "In2.Cu")
		(net "M_I_CPU1_SB_DQS_DN<2>")
	)
	(segment
		(start 172.75175 -304.012346)
		(end 173.05909 -304.319686)
		(width 0.16002)
		(layer "In2.Cu")
		(net "M_I_CPU1_SB_DQS_DN<2>")
	)
	(segment
		(start 141.394942 -285.906464)
		(end 141.403324 -285.91129)
		(width 0.09525)
		(layer "In2.Cu")
		(net "M_I_CPU1_SB_DQS_DN<2>")
	)
	(segment
		(start 165.515036 -304.319686)
		(end 166.107364 -304.319686)
		(width 0.16002)
		(layer "In2.Cu")
		(net "M_I_CPU1_SB_DQS_DN<2>")
	)
	(segment
		(start 145.444718 -285.986982)
		(end 145.839942 -285.986982)
		(width 0.09525)
		(layer "In2.Cu")
		(net "M_I_CPU1_SB_DQS_DN<2>")
	)
	(segment
		(start 183.343042 -304.162206)
		(end 183.616092 -304.435256)
		(width 0.16002)
		(layer "In2.Cu")
		(net "M_I_CPU1_SB_DQS_DN<2>")
	)
	(segment
		(start 147.114768 -287.046416)
		(end 147.412456 -287.344104)
		(width 0.09525)
		(layer "In2.Cu")
		(net "M_I_CPU1_SB_DQS_DN<2>")
	)
	(segment
		(start 145.839942 -285.986982)
		(end 146.899376 -287.046416)
		(width 0.09525)
		(layer "In2.Cu")
		(net "M_I_CPU1_SB_DQS_DN<2>")
	)
	(segment
		(start 149.21357 -289.47237)
		(end 150.24354 -291.957506)
		(width 0.16002)
		(layer "In2.Cu")
		(net "M_I_CPU1_SB_DQS_DN<2>")
	)
	(segment
		(start 131.99491 -285.906464)
		(end 132.003292 -285.91129)
		(width 0.09525)
		(layer "In2.Cu")
		(net "M_I_CPU1_SB_DQS_DN<2>")
	)
	(segment
		(start 173.651418 -304.319686)
		(end 174.492158 -303.478946)
		(width 0.16002)
		(layer "In2.Cu")
		(net "M_I_CPU1_SB_DQS_DN<2>")
	)
	(segment
		(start 160.492186 -303.224184)
		(end 160.491932 -303.75098)
		(width 0.16002)
		(layer "In2.Cu")
		(net "M_I_CPU1_SB_DQS_DN<2>")
	)
	(segment
		(start 180.62829 -304.345086)
		(end 181.89829 -304.345086)
		(width 0.16002)
		(layer "In2.Cu")
		(net "M_I_CPU1_SB_DQS_DN<2>")
	)
	(segment
		(start 138.206226 -285.91129)
		(end 138.214608 -285.906464)
		(width 0.09525)
		(layer "In2.Cu")
		(net "M_I_CPU1_SB_DQS_DN<2>")
	)
	(segment
		(start 174.492158 -303.478946)
		(end 175.01743 -303.478946)
		(width 0.16002)
		(layer "In2.Cu")
		(net "M_I_CPU1_SB_DQS_DN<2>")
	)
	(segment
		(start 150.24354 -291.957506)
		(end 160.862772 -302.576738)
		(width 0.16002)
		(layer "In2.Cu")
		(net "M_I_CPU1_SB_DQS_DN<2>")
	)
	(segment
		(start 129.934716 -286.23641)
		(end 129.780792 -285.97098)
		(width 0.09525)
		(layer "In2.Cu")
		(net "M_I_CPU1_SB_DQS_DN<2>")
	)
	(segment
		(start 167.78986 -303.162462)
		(end 169.76852 -303.162462)
		(width 0.16002)
		(layer "In2.Cu")
		(net "M_I_CPU1_SB_DQS_DN<2>")
	)
	(segment
		(start 136.694926 -285.906464)
		(end 136.703308 -285.91129)
		(width 0.09525)
		(layer "In2.Cu")
		(net "M_I_CPU1_SB_DQS_DN<2>")
	)
	(segment
		(start 173.05909 -304.319686)
		(end 173.651418 -304.319686)
		(width 0.16002)
		(layer "In2.Cu")
		(net "M_I_CPU1_SB_DQS_DN<2>")
	)
	(segment
		(start 162.29838 -304.012346)
		(end 165.207696 -304.012346)
		(width 0.16002)
		(layer "In2.Cu")
		(net "M_I_CPU1_SB_DQS_DN<2>")
	)
	(segment
		(start 160.862772 -302.576738)
		(end 160.862772 -302.853598)
		(width 0.16002)
		(layer "In2.Cu")
		(net "M_I_CPU1_SB_DQS_DN<2>")
	)
	(segment
		(start 135.754872 -285.906464)
		(end 135.763254 -285.91129)
		(width 0.09525)
		(layer "In2.Cu")
		(net "M_I_CPU1_SB_DQS_DN<2>")
	)
	(segment
		(start 160.86582 -304.124868)
		(end 161.393124 -304.125122)
		(width 0.16002)
		(layer "In2.Cu")
		(net "M_I_CPU1_SB_DQS_DN<2>")
	)
	(segment
		(start 160.862772 -302.853598)
		(end 160.492186 -303.224184)
		(width 0.16002)
		(layer "In2.Cu")
		(net "M_I_CPU1_SB_DQS_DN<2>")
	)
	(segment
		(start 137.266172 -285.91129)
		(end 137.274554 -285.906464)
		(width 0.09525)
		(layer "In2.Cu")
		(net "M_I_CPU1_SB_DQS_DN<2>")
	)
	(segment
		(start 177.360326 -303.162462)
		(end 177.934366 -303.736502)
		(width 0.16002)
		(layer "In2.Cu")
		(net "M_I_CPU1_SB_DQS_DN<2>")
	)
	(segment
		(start 129.780792 -285.97098)
		(end 129.80416 -285.884112)
		(width 0.09525)
		(layer "In2.Cu")
		(net "M_I_CPU1_SB_DQS_DN<2>")
	)
	(segment
		(start 141.966188 -285.91129)
		(end 141.97457 -285.906464)
		(width 0.09525)
		(layer "In2.Cu")
		(net "M_I_CPU1_SB_DQS_DN<2>")
	)
	(segment
		(start 145.154904 -285.906464)
		(end 145.163286 -285.91129)
		(width 0.09525)
		(layer "In2.Cu")
		(net "M_I_CPU1_SB_DQS_DN<2>")
	)
	(segment
		(start 166.948104 -303.478946)
		(end 167.473376 -303.478946)
		(width 0.16002)
		(layer "In2.Cu")
		(net "M_I_CPU1_SB_DQS_DN<2>")
	)
	(segment
		(start 181.89829 -304.345086)
		(end 182.08117 -304.162206)
		(width 0.16002)
		(layer "In2.Cu")
		(net "M_I_CPU1_SB_DQS_DN<2>")
	)
	(segment
		(start 167.473376 -303.478946)
		(end 167.78986 -303.162462)
		(width 0.16002)
		(layer "In2.Cu")
		(net "M_I_CPU1_SB_DQS_DN<2>")
	)
	(segment
		(start 175.333914 -303.162462)
		(end 177.360326 -303.162462)
		(width 0.16002)
		(layer "In2.Cu")
		(net "M_I_CPU1_SB_DQS_DN<2>")
	)
	(segment
		(start 140.454888 -285.906464)
		(end 140.46327 -285.91129)
		(width 0.09525)
		(layer "In2.Cu")
		(net "M_I_CPU1_SB_DQS_DN<2>")
	)
	(segment
		(start 146.899376 -287.046416)
		(end 147.114768 -287.046416)
		(width 0.09525)
		(layer "In2.Cu")
		(net "M_I_CPU1_SB_DQS_DN<2>")
	)
	(segment
		(start 147.688808 -287.947608)
		(end 147.705572 -287.964372)
		(width 0.09525)
		(layer "In2.Cu")
		(net "M_I_CPU1_SB_DQS_DN<2>")
	)
	(segment
		(start 162.04057 -303.754536)
		(end 162.29838 -304.012346)
		(width 0.16002)
		(layer "In2.Cu")
		(net "M_I_CPU1_SB_DQS_DN<2>")
	)
	(segment
		(start 147.705572 -287.964372)
		(end 149.21357 -289.47237)
		(width 0.16002)
		(layer "In2.Cu")
		(net "M_I_CPU1_SB_DQS_DN<2>")
	)
	(segment
		(start 175.01743 -303.478946)
		(end 175.333914 -303.162462)
		(width 0.16002)
		(layer "In2.Cu")
		(net "M_I_CPU1_SB_DQS_DN<2>")
	)
	(segment
		(start 161.393124 -304.125122)
		(end 161.76371 -303.754536)
		(width 0.16002)
		(layer "In2.Cu")
		(net "M_I_CPU1_SB_DQS_DN<2>")
	)
	(segment
		(start 147.412456 -287.344104)
		(end 147.412456 -287.588198)
		(width 0.09525)
		(layer "In2.Cu")
		(net "M_I_CPU1_SB_DQS_DN<2>")
	)
	(segment
		(start 147.688808 -287.864804)
		(end 147.688808 -287.947608)
		(width 0.09525)
		(layer "In2.Cu")
		(net "M_I_CPU1_SB_DQS_DN<2>")
	)
	(arc
		(start 137.274554 -285.906464)
		(mid 137.459586 -285.86055)
		(end 137.643362 -285.91129)
		(width 0.09525)
		(layer "In2.Cu")
		(net "M_I_CPU1_SB_DQS_DN<2>")
	)
	(arc
		(start 130.123438 -285.91129)
		(mid 130.40487 -285.987045)
		(end 130.686302 -285.91129)
		(width 0.09525)
		(layer "In2.Cu")
		(net "M_I_CPU1_SB_DQS_DN<2>")
	)
	(arc
		(start 141.97457 -285.906464)
		(mid 142.159602 -285.86055)
		(end 142.343378 -285.91129)
		(width 0.09525)
		(layer "In2.Cu")
		(net "M_I_CPU1_SB_DQS_DN<2>")
	)
	(arc
		(start 145.163286 -285.91129)
		(mid 145.298993 -285.967775)
		(end 145.444718 -285.986982)
		(width 0.09525)
		(layer "In2.Cu")
		(net "M_I_CPU1_SB_DQS_DN<2>")
	)
	(arc
		(start 132.943346 -285.91129)
		(mid 133.224778 -285.987045)
		(end 133.50621 -285.91129)
		(width 0.09525)
		(layer "In2.Cu")
		(net "M_I_CPU1_SB_DQS_DN<2>")
	)
	(arc
		(start 134.446264 -285.91129)
		(mid 134.634732 -285.860613)
		(end 134.8232 -285.91129)
		(width 0.09525)
		(layer "In2.Cu")
		(net "M_I_CPU1_SB_DQS_DN<2>")
	)
	(arc
		(start 137.643362 -285.91129)
		(mid 137.924794 -285.987045)
		(end 138.206226 -285.91129)
		(width 0.09525)
		(layer "In2.Cu")
		(net "M_I_CPU1_SB_DQS_DN<2>")
	)
	(arc
		(start 135.763254 -285.91129)
		(mid 136.044686 -285.987045)
		(end 136.326118 -285.91129)
		(width 0.09525)
		(layer "In2.Cu")
		(net "M_I_CPU1_SB_DQS_DN<2>")
	)
	(arc
		(start 133.514592 -285.906464)
		(mid 133.699624 -285.86055)
		(end 133.8834 -285.91129)
		(width 0.09525)
		(layer "In2.Cu")
		(net "M_I_CPU1_SB_DQS_DN<2>")
	)
	(arc
		(start 138.214608 -285.906464)
		(mid 138.39964 -285.86055)
		(end 138.583416 -285.91129)
		(width 0.09525)
		(layer "In2.Cu")
		(net "M_I_CPU1_SB_DQS_DN<2>")
	)
	(arc
		(start 130.686302 -285.91129)
		(mid 130.87477 -285.860613)
		(end 131.063238 -285.91129)
		(width 0.09525)
		(layer "In2.Cu")
		(net "M_I_CPU1_SB_DQS_DN<2>")
	)
	(arc
		(start 141.403324 -285.91129)
		(mid 141.684756 -285.987045)
		(end 141.966188 -285.91129)
		(width 0.09525)
		(layer "In2.Cu")
		(net "M_I_CPU1_SB_DQS_DN<2>")
	)
	(arc
		(start 138.583416 -285.91129)
		(mid 138.864848 -285.987045)
		(end 139.14628 -285.91129)
		(width 0.09525)
		(layer "In2.Cu")
		(net "M_I_CPU1_SB_DQS_DN<2>")
	)
	(arc
		(start 141.026134 -285.91129)
		(mid 141.209909 -285.860518)
		(end 141.394942 -285.906464)
		(width 0.09525)
		(layer "In2.Cu")
		(net "M_I_CPU1_SB_DQS_DN<2>")
	)
	(arc
		(start 136.326118 -285.91129)
		(mid 136.509893 -285.860518)
		(end 136.694926 -285.906464)
		(width 0.09525)
		(layer "In2.Cu")
		(net "M_I_CPU1_SB_DQS_DN<2>")
	)
	(arc
		(start 139.523216 -285.91129)
		(mid 139.804648 -285.987045)
		(end 140.08608 -285.91129)
		(width 0.09525)
		(layer "In2.Cu")
		(net "M_I_CPU1_SB_DQS_DN<2>")
	)
	(arc
		(start 131.626102 -285.91129)
		(mid 131.809877 -285.860518)
		(end 131.99491 -285.906464)
		(width 0.09525)
		(layer "In2.Cu")
		(net "M_I_CPU1_SB_DQS_DN<2>")
	)
	(arc
		(start 135.386064 -285.91129)
		(mid 135.569839 -285.860518)
		(end 135.754872 -285.906464)
		(width 0.09525)
		(layer "In2.Cu")
		(net "M_I_CPU1_SB_DQS_DN<2>")
	)
	(arc
		(start 134.8232 -285.91129)
		(mid 135.104632 -285.987045)
		(end 135.386064 -285.91129)
		(width 0.09525)
		(layer "In2.Cu")
		(net "M_I_CPU1_SB_DQS_DN<2>")
	)
	(arc
		(start 143.283178 -285.91129)
		(mid 143.56461 -285.987045)
		(end 143.846042 -285.91129)
		(width 0.09525)
		(layer "In2.Cu")
		(net "M_I_CPU1_SB_DQS_DN<2>")
	)
	(arc
		(start 144.223232 -285.91129)
		(mid 144.504664 -285.987045)
		(end 144.786096 -285.91129)
		(width 0.09525)
		(layer "In2.Cu")
		(net "M_I_CPU1_SB_DQS_DN<2>")
	)
	(arc
		(start 131.063238 -285.91129)
		(mid 131.34467 -285.987045)
		(end 131.626102 -285.91129)
		(width 0.09525)
		(layer "In2.Cu")
		(net "M_I_CPU1_SB_DQS_DN<2>")
	)
	(arc
		(start 132.003292 -285.91129)
		(mid 132.284724 -285.987045)
		(end 132.566156 -285.91129)
		(width 0.09525)
		(layer "In2.Cu")
		(net "M_I_CPU1_SB_DQS_DN<2>")
	)
	(arc
		(start 132.566156 -285.91129)
		(mid 132.749931 -285.860518)
		(end 132.934964 -285.906464)
		(width 0.09525)
		(layer "In2.Cu")
		(net "M_I_CPU1_SB_DQS_DN<2>")
	)
	(arc
		(start 136.703308 -285.91129)
		(mid 136.98474 -285.987045)
		(end 137.266172 -285.91129)
		(width 0.09525)
		(layer "In2.Cu")
		(net "M_I_CPU1_SB_DQS_DN<2>")
	)
	(arc
		(start 129.80416 -285.884112)
		(mid 129.966842 -285.86198)
		(end 130.123438 -285.91129)
		(width 0.09525)
		(layer "In2.Cu")
		(net "M_I_CPU1_SB_DQS_DN<2>")
	)
	(arc
		(start 143.846042 -285.91129)
		(mid 144.029817 -285.860518)
		(end 144.21485 -285.906464)
		(width 0.09525)
		(layer "In2.Cu")
		(net "M_I_CPU1_SB_DQS_DN<2>")
	)
	(arc
		(start 139.14628 -285.91129)
		(mid 139.334748 -285.860613)
		(end 139.523216 -285.91129)
		(width 0.09525)
		(layer "In2.Cu")
		(net "M_I_CPU1_SB_DQS_DN<2>")
	)
	(arc
		(start 144.786096 -285.91129)
		(mid 144.969871 -285.860518)
		(end 145.154904 -285.906464)
		(width 0.09525)
		(layer "In2.Cu")
		(net "M_I_CPU1_SB_DQS_DN<2>")
	)
	(arc
		(start 133.8834 -285.91129)
		(mid 134.164832 -285.987045)
		(end 134.446264 -285.91129)
		(width 0.09525)
		(layer "In2.Cu")
		(net "M_I_CPU1_SB_DQS_DN<2>")
	)
	(arc
		(start 142.343378 -285.91129)
		(mid 142.62481 -285.987045)
		(end 142.906242 -285.91129)
		(width 0.09525)
		(layer "In2.Cu")
		(net "M_I_CPU1_SB_DQS_DN<2>")
	)
	(arc
		(start 142.906242 -285.91129)
		(mid 143.09471 -285.860613)
		(end 143.283178 -285.91129)
		(width 0.09525)
		(layer "In2.Cu")
		(net "M_I_CPU1_SB_DQS_DN<2>")
	)
	(arc
		(start 140.46327 -285.91129)
		(mid 140.744702 -285.987045)
		(end 141.026134 -285.91129)
		(width 0.09525)
		(layer "In2.Cu")
		(net "M_I_CPU1_SB_DQS_DN<2>")
	)
	(arc
		(start 140.08608 -285.91129)
		(mid 140.269855 -285.860518)
		(end 140.454888 -285.906464)
		(width 0.09525)
		(layer "In2.Cu")
		(net "M_I_CPU1_SB_DQS_DN<2>")
	)
	(segment
		(start 129.467864 -281.110436)
		(end 129.934716 -281.376374)
		(width 0.12954)
		(layer "F.Cu")
		(net "M_I_CPU1_SB_DQS_DN<1>")
	)
	(segment
		(start 165.515036 -294.969692)
		(end 166.107364 -294.969692)
		(width 0.16002)
		(layer "In2.Cu")
		(net "M_I_CPU1_SB_DQS_DN<1>")
	)
	(segment
		(start 173.05909 -294.969692)
		(end 173.651418 -294.969692)
		(width 0.16002)
		(layer "In2.Cu")
		(net "M_I_CPU1_SB_DQS_DN<1>")
	)
	(segment
		(start 137.266172 -281.051254)
		(end 137.274554 -281.046428)
		(width 0.09525)
		(layer "In2.Cu")
		(net "M_I_CPU1_SB_DQS_DN<1>")
	)
	(segment
		(start 167.78986 -293.812468)
		(end 169.76852 -293.812468)
		(width 0.16002)
		(layer "In2.Cu")
		(net "M_I_CPU1_SB_DQS_DN<1>")
	)
	(segment
		(start 174.492158 -294.128952)
		(end 175.01743 -294.128952)
		(width 0.16002)
		(layer "In2.Cu")
		(net "M_I_CPU1_SB_DQS_DN<1>")
	)
	(segment
		(start 145.53692 -281.126946)
		(end 145.9738 -281.126946)
		(width 0.09525)
		(layer "In2.Cu")
		(net "M_I_CPU1_SB_DQS_DN<1>")
	)
	(segment
		(start 175.01743 -294.128952)
		(end 175.333914 -293.812468)
		(width 0.16002)
		(layer "In2.Cu")
		(net "M_I_CPU1_SB_DQS_DN<1>")
	)
	(segment
		(start 145.536666 -281.1272)
		(end 145.53692 -281.126946)
		(width 0.09525)
		(layer "In2.Cu")
		(net "M_I_CPU1_SB_DQS_DN<1>")
	)
	(segment
		(start 143.846042 -281.051254)
		(end 143.854424 -281.046428)
		(width 0.09525)
		(layer "In2.Cu")
		(net "M_I_CPU1_SB_DQS_DN<1>")
	)
	(segment
		(start 147.613624 -281.170126)
		(end 147.836636 -281.170126)
		(width 0.09525)
		(layer "In2.Cu")
		(net "M_I_CPU1_SB_DQS_DN<1>")
	)
	(segment
		(start 162.59429 -294.002714)
		(end 163.253928 -294.662352)
		(width 0.16002)
		(layer "In2.Cu")
		(net "M_I_CPU1_SB_DQS_DN<1>")
	)
	(segment
		(start 177.934366 -294.386508)
		(end 180.019706 -294.386508)
		(width 0.16002)
		(layer "In2.Cu")
		(net "M_I_CPU1_SB_DQS_DN<1>")
	)
	(segment
		(start 163.253928 -294.662352)
		(end 165.207696 -294.662352)
		(width 0.16002)
		(layer "In2.Cu")
		(net "M_I_CPU1_SB_DQS_DN<1>")
	)
	(segment
		(start 135.754872 -281.046428)
		(end 135.763254 -281.051254)
		(width 0.09525)
		(layer "In2.Cu")
		(net "M_I_CPU1_SB_DQS_DN<1>")
	)
	(segment
		(start 147.895564 -281.229054)
		(end 147.919186 -281.229054)
		(width 0.09525)
		(layer "In2.Cu")
		(net "M_I_CPU1_SB_DQS_DN<1>")
	)
	(segment
		(start 162.59429 -293.635938)
		(end 162.59429 -294.002714)
		(width 0.16002)
		(layer "In2.Cu")
		(net "M_I_CPU1_SB_DQS_DN<1>")
	)
	(segment
		(start 129.780792 -281.110944)
		(end 129.80416 -281.024076)
		(width 0.09525)
		(layer "In2.Cu")
		(net "M_I_CPU1_SB_DQS_DN<1>")
	)
	(segment
		(start 149.319742 -281.229054)
		(end 153.599896 -285.509208)
		(width 0.16002)
		(layer "In2.Cu")
		(net "M_I_CPU1_SB_DQS_DN<1>")
	)
	(segment
		(start 180.62829 -294.995092)
		(end 181.322726 -294.995092)
		(width 0.16002)
		(layer "In2.Cu")
		(net "M_I_CPU1_SB_DQS_DN<1>")
	)
	(segment
		(start 165.207696 -294.662352)
		(end 165.515036 -294.969692)
		(width 0.16002)
		(layer "In2.Cu")
		(net "M_I_CPU1_SB_DQS_DN<1>")
	)
	(segment
		(start 147.836636 -281.170126)
		(end 147.895564 -281.229054)
		(width 0.09525)
		(layer "In2.Cu")
		(net "M_I_CPU1_SB_DQS_DN<1>")
	)
	(segment
		(start 141.394942 -281.046428)
		(end 141.403324 -281.051254)
		(width 0.09525)
		(layer "In2.Cu")
		(net "M_I_CPU1_SB_DQS_DN<1>")
	)
	(segment
		(start 145.9738 -281.126946)
		(end 146.38147 -280.719276)
		(width 0.09525)
		(layer "In2.Cu")
		(net "M_I_CPU1_SB_DQS_DN<1>")
	)
	(segment
		(start 133.50621 -281.051254)
		(end 133.514592 -281.046428)
		(width 0.09525)
		(layer "In2.Cu")
		(net "M_I_CPU1_SB_DQS_DN<1>")
	)
	(segment
		(start 181.322726 -294.995092)
		(end 181.505606 -294.812212)
		(width 0.16002)
		(layer "In2.Cu")
		(net "M_I_CPU1_SB_DQS_DN<1>")
	)
	(segment
		(start 181.505606 -294.812212)
		(end 181.985666 -294.812212)
		(width 0.16002)
		(layer "In2.Cu")
		(net "M_I_CPU1_SB_DQS_DN<1>")
	)
	(segment
		(start 167.473376 -294.128952)
		(end 167.78986 -293.812468)
		(width 0.16002)
		(layer "In2.Cu")
		(net "M_I_CPU1_SB_DQS_DN<1>")
	)
	(segment
		(start 182.102506 -294.929052)
		(end 182.582566 -294.929052)
		(width 0.16002)
		(layer "In2.Cu")
		(net "M_I_CPU1_SB_DQS_DN<1>")
	)
	(segment
		(start 147.919186 -281.229054)
		(end 149.319742 -281.229054)
		(width 0.16002)
		(layer "In2.Cu")
		(net "M_I_CPU1_SB_DQS_DN<1>")
	)
	(segment
		(start 146.38147 -280.719276)
		(end 147.162774 -280.719276)
		(width 0.09525)
		(layer "In2.Cu")
		(net "M_I_CPU1_SB_DQS_DN<1>")
	)
	(segment
		(start 145.155412 -281.046428)
		(end 145.163794 -281.051254)
		(width 0.09525)
		(layer "In2.Cu")
		(net "M_I_CPU1_SB_DQS_DN<1>")
	)
	(segment
		(start 147.162774 -280.719276)
		(end 147.613624 -281.170126)
		(width 0.09525)
		(layer "In2.Cu")
		(net "M_I_CPU1_SB_DQS_DN<1>")
	)
	(segment
		(start 132.934964 -281.046428)
		(end 132.943346 -281.051254)
		(width 0.09525)
		(layer "In2.Cu")
		(net "M_I_CPU1_SB_DQS_DN<1>")
	)
	(segment
		(start 138.206226 -281.051254)
		(end 138.214608 -281.046428)
		(width 0.09525)
		(layer "In2.Cu")
		(net "M_I_CPU1_SB_DQS_DN<1>")
	)
	(segment
		(start 136.694926 -281.046428)
		(end 136.703308 -281.051254)
		(width 0.09525)
		(layer "In2.Cu")
		(net "M_I_CPU1_SB_DQS_DN<1>")
	)
	(segment
		(start 129.934716 -281.376374)
		(end 129.780792 -281.110944)
		(width 0.09525)
		(layer "In2.Cu")
		(net "M_I_CPU1_SB_DQS_DN<1>")
	)
	(segment
		(start 131.99491 -281.046428)
		(end 132.003292 -281.051254)
		(width 0.09525)
		(layer "In2.Cu")
		(net "M_I_CPU1_SB_DQS_DN<1>")
	)
	(segment
		(start 170.618404 -294.662352)
		(end 172.75175 -294.662352)
		(width 0.16002)
		(layer "In2.Cu")
		(net "M_I_CPU1_SB_DQS_DN<1>")
	)
	(segment
		(start 140.454888 -281.046428)
		(end 140.46327 -281.051254)
		(width 0.09525)
		(layer "In2.Cu")
		(net "M_I_CPU1_SB_DQS_DN<1>")
	)
	(segment
		(start 145.44167 -281.1272)
		(end 145.536666 -281.1272)
		(width 0.09525)
		(layer "In2.Cu")
		(net "M_I_CPU1_SB_DQS_DN<1>")
	)
	(segment
		(start 145.163794 -281.051254)
		(end 145.184622 -281.063446)
		(width 0.09525)
		(layer "In2.Cu")
		(net "M_I_CPU1_SB_DQS_DN<1>")
	)
	(segment
		(start 154.46756 -285.509208)
		(end 162.59429 -293.635938)
		(width 0.16002)
		(layer "In2.Cu")
		(net "M_I_CPU1_SB_DQS_DN<1>")
	)
	(segment
		(start 153.599896 -285.509208)
		(end 154.46756 -285.509208)
		(width 0.16002)
		(layer "In2.Cu")
		(net "M_I_CPU1_SB_DQS_DN<1>")
	)
	(segment
		(start 182.699406 -294.812212)
		(end 183.343042 -294.812212)
		(width 0.16002)
		(layer "In2.Cu")
		(net "M_I_CPU1_SB_DQS_DN<1>")
	)
	(segment
		(start 175.333914 -293.812468)
		(end 177.360326 -293.812468)
		(width 0.16002)
		(layer "In2.Cu")
		(net "M_I_CPU1_SB_DQS_DN<1>")
	)
	(segment
		(start 181.985666 -294.812212)
		(end 182.102506 -294.929052)
		(width 0.16002)
		(layer "In2.Cu")
		(net "M_I_CPU1_SB_DQS_DN<1>")
	)
	(segment
		(start 180.019706 -294.386508)
		(end 180.62829 -294.995092)
		(width 0.16002)
		(layer "In2.Cu")
		(net "M_I_CPU1_SB_DQS_DN<1>")
	)
	(segment
		(start 166.107364 -294.969692)
		(end 166.948104 -294.128952)
		(width 0.16002)
		(layer "In2.Cu")
		(net "M_I_CPU1_SB_DQS_DN<1>")
	)
	(segment
		(start 166.948104 -294.128952)
		(end 167.473376 -294.128952)
		(width 0.16002)
		(layer "In2.Cu")
		(net "M_I_CPU1_SB_DQS_DN<1>")
	)
	(segment
		(start 169.76852 -293.812468)
		(end 170.618404 -294.662352)
		(width 0.16002)
		(layer "In2.Cu")
		(net "M_I_CPU1_SB_DQS_DN<1>")
	)
	(segment
		(start 173.651418 -294.969692)
		(end 174.492158 -294.128952)
		(width 0.16002)
		(layer "In2.Cu")
		(net "M_I_CPU1_SB_DQS_DN<1>")
	)
	(segment
		(start 182.582566 -294.929052)
		(end 182.699406 -294.812212)
		(width 0.16002)
		(layer "In2.Cu")
		(net "M_I_CPU1_SB_DQS_DN<1>")
	)
	(segment
		(start 141.966188 -281.051254)
		(end 141.97457 -281.046428)
		(width 0.09525)
		(layer "In2.Cu")
		(net "M_I_CPU1_SB_DQS_DN<1>")
	)
	(segment
		(start 144.77238 -281.05989)
		(end 144.787112 -281.051254)
		(width 0.09525)
		(layer "In2.Cu")
		(net "M_I_CPU1_SB_DQS_DN<1>")
	)
	(segment
		(start 172.75175 -294.662352)
		(end 173.05909 -294.969692)
		(width 0.16002)
		(layer "In2.Cu")
		(net "M_I_CPU1_SB_DQS_DN<1>")
	)
	(segment
		(start 177.360326 -293.812468)
		(end 177.934366 -294.386508)
		(width 0.16002)
		(layer "In2.Cu")
		(net "M_I_CPU1_SB_DQS_DN<1>")
	)
	(segment
		(start 183.343042 -294.812212)
		(end 183.616092 -295.085262)
		(width 0.16002)
		(layer "In2.Cu")
		(net "M_I_CPU1_SB_DQS_DN<1>")
	)
	(arc
		(start 144.22374 -281.051254)
		(mid 144.496922 -281.127196)
		(end 144.77238 -281.05989)
		(width 0.09525)
		(layer "In2.Cu")
		(net "M_I_CPU1_SB_DQS_DN<1>")
	)
	(arc
		(start 140.46327 -281.051254)
		(mid 140.744702 -281.127009)
		(end 141.026134 -281.051254)
		(width 0.09525)
		(layer "In2.Cu")
		(net "M_I_CPU1_SB_DQS_DN<1>")
	)
	(arc
		(start 135.386064 -281.051254)
		(mid 135.569839 -281.000482)
		(end 135.754872 -281.046428)
		(width 0.09525)
		(layer "In2.Cu")
		(net "M_I_CPU1_SB_DQS_DN<1>")
	)
	(arc
		(start 141.026134 -281.051254)
		(mid 141.209909 -281.000482)
		(end 141.394942 -281.046428)
		(width 0.09525)
		(layer "In2.Cu")
		(net "M_I_CPU1_SB_DQS_DN<1>")
	)
	(arc
		(start 132.943346 -281.051254)
		(mid 133.224778 -281.127009)
		(end 133.50621 -281.051254)
		(width 0.09525)
		(layer "In2.Cu")
		(net "M_I_CPU1_SB_DQS_DN<1>")
	)
	(arc
		(start 133.514592 -281.046428)
		(mid 133.699624 -281.000514)
		(end 133.8834 -281.051254)
		(width 0.09525)
		(layer "In2.Cu")
		(net "M_I_CPU1_SB_DQS_DN<1>")
	)
	(arc
		(start 136.326118 -281.051254)
		(mid 136.509893 -281.000482)
		(end 136.694926 -281.046428)
		(width 0.09525)
		(layer "In2.Cu")
		(net "M_I_CPU1_SB_DQS_DN<1>")
	)
	(arc
		(start 144.787112 -281.051254)
		(mid 144.970633 -281.00061)
		(end 145.155412 -281.046428)
		(width 0.09525)
		(layer "In2.Cu")
		(net "M_I_CPU1_SB_DQS_DN<1>")
	)
	(arc
		(start 143.854424 -281.046428)
		(mid 144.03971 -281.000392)
		(end 144.22374 -281.051254)
		(width 0.09525)
		(layer "In2.Cu")
		(net "M_I_CPU1_SB_DQS_DN<1>")
	)
	(arc
		(start 130.123438 -281.051254)
		(mid 130.40487 -281.127009)
		(end 130.686302 -281.051254)
		(width 0.09525)
		(layer "In2.Cu")
		(net "M_I_CPU1_SB_DQS_DN<1>")
	)
	(arc
		(start 138.583416 -281.051254)
		(mid 138.864848 -281.127009)
		(end 139.14628 -281.051254)
		(width 0.09525)
		(layer "In2.Cu")
		(net "M_I_CPU1_SB_DQS_DN<1>")
	)
	(arc
		(start 139.523216 -281.051254)
		(mid 139.804648 -281.127009)
		(end 140.08608 -281.051254)
		(width 0.09525)
		(layer "In2.Cu")
		(net "M_I_CPU1_SB_DQS_DN<1>")
	)
	(arc
		(start 134.8232 -281.051254)
		(mid 135.104632 -281.127009)
		(end 135.386064 -281.051254)
		(width 0.09525)
		(layer "In2.Cu")
		(net "M_I_CPU1_SB_DQS_DN<1>")
	)
	(arc
		(start 130.686302 -281.051254)
		(mid 130.87477 -281.000577)
		(end 131.063238 -281.051254)
		(width 0.09525)
		(layer "In2.Cu")
		(net "M_I_CPU1_SB_DQS_DN<1>")
	)
	(arc
		(start 129.80416 -281.024076)
		(mid 129.966842 -281.001944)
		(end 130.123438 -281.051254)
		(width 0.09525)
		(layer "In2.Cu")
		(net "M_I_CPU1_SB_DQS_DN<1>")
	)
	(arc
		(start 137.643362 -281.051254)
		(mid 137.924794 -281.127009)
		(end 138.206226 -281.051254)
		(width 0.09525)
		(layer "In2.Cu")
		(net "M_I_CPU1_SB_DQS_DN<1>")
	)
	(arc
		(start 131.063238 -281.051254)
		(mid 131.34467 -281.127009)
		(end 131.626102 -281.051254)
		(width 0.09525)
		(layer "In2.Cu")
		(net "M_I_CPU1_SB_DQS_DN<1>")
	)
	(arc
		(start 133.8834 -281.051254)
		(mid 134.164832 -281.127009)
		(end 134.446264 -281.051254)
		(width 0.09525)
		(layer "In2.Cu")
		(net "M_I_CPU1_SB_DQS_DN<1>")
	)
	(arc
		(start 136.703308 -281.051254)
		(mid 136.98474 -281.127009)
		(end 137.266172 -281.051254)
		(width 0.09525)
		(layer "In2.Cu")
		(net "M_I_CPU1_SB_DQS_DN<1>")
	)
	(arc
		(start 137.274554 -281.046428)
		(mid 137.459586 -281.000514)
		(end 137.643362 -281.051254)
		(width 0.09525)
		(layer "In2.Cu")
		(net "M_I_CPU1_SB_DQS_DN<1>")
	)
	(arc
		(start 132.003292 -281.051254)
		(mid 132.284724 -281.127009)
		(end 132.566156 -281.051254)
		(width 0.09525)
		(layer "In2.Cu")
		(net "M_I_CPU1_SB_DQS_DN<1>")
	)
	(arc
		(start 142.906242 -281.051254)
		(mid 143.09471 -281.000577)
		(end 143.283178 -281.051254)
		(width 0.09525)
		(layer "In2.Cu")
		(net "M_I_CPU1_SB_DQS_DN<1>")
	)
	(arc
		(start 141.403324 -281.051254)
		(mid 141.684756 -281.127009)
		(end 141.966188 -281.051254)
		(width 0.09525)
		(layer "In2.Cu")
		(net "M_I_CPU1_SB_DQS_DN<1>")
	)
	(arc
		(start 135.763254 -281.051254)
		(mid 136.044686 -281.127009)
		(end 136.326118 -281.051254)
		(width 0.09525)
		(layer "In2.Cu")
		(net "M_I_CPU1_SB_DQS_DN<1>")
	)
	(arc
		(start 139.14628 -281.051254)
		(mid 139.334748 -281.000577)
		(end 139.523216 -281.051254)
		(width 0.09525)
		(layer "In2.Cu")
		(net "M_I_CPU1_SB_DQS_DN<1>")
	)
	(arc
		(start 131.626102 -281.051254)
		(mid 131.809877 -281.000482)
		(end 131.99491 -281.046428)
		(width 0.09525)
		(layer "In2.Cu")
		(net "M_I_CPU1_SB_DQS_DN<1>")
	)
	(arc
		(start 138.214608 -281.046428)
		(mid 138.39964 -281.000514)
		(end 138.583416 -281.051254)
		(width 0.09525)
		(layer "In2.Cu")
		(net "M_I_CPU1_SB_DQS_DN<1>")
	)
	(arc
		(start 132.566156 -281.051254)
		(mid 132.749931 -281.000482)
		(end 132.934964 -281.046428)
		(width 0.09525)
		(layer "In2.Cu")
		(net "M_I_CPU1_SB_DQS_DN<1>")
	)
	(arc
		(start 143.283178 -281.051254)
		(mid 143.56461 -281.127009)
		(end 143.846042 -281.051254)
		(width 0.09525)
		(layer "In2.Cu")
		(net "M_I_CPU1_SB_DQS_DN<1>")
	)
	(arc
		(start 141.97457 -281.046428)
		(mid 142.159602 -281.000514)
		(end 142.343378 -281.051254)
		(width 0.09525)
		(layer "In2.Cu")
		(net "M_I_CPU1_SB_DQS_DN<1>")
	)
	(arc
		(start 145.184622 -281.063446)
		(mid 145.309325 -281.110741)
		(end 145.44167 -281.1272)
		(width 0.09525)
		(layer "In2.Cu")
		(net "M_I_CPU1_SB_DQS_DN<1>")
	)
	(arc
		(start 142.343378 -281.051254)
		(mid 142.62481 -281.127009)
		(end 142.906242 -281.051254)
		(width 0.09525)
		(layer "In2.Cu")
		(net "M_I_CPU1_SB_DQS_DN<1>")
	)
	(arc
		(start 140.08608 -281.051254)
		(mid 140.269855 -281.000482)
		(end 140.454888 -281.046428)
		(width 0.09525)
		(layer "In2.Cu")
		(net "M_I_CPU1_SB_DQS_DN<1>")
	)
	(arc
		(start 134.446264 -281.051254)
		(mid 134.634732 -281.000577)
		(end 134.8232 -281.051254)
		(width 0.09525)
		(layer "In2.Cu")
		(net "M_I_CPU1_SB_DQS_DN<1>")
	)
	(segment
		(start 129.467864 -276.2504)
		(end 129.934716 -276.516338)
		(width 0.12954)
		(layer "F.Cu")
		(net "M_I_CPU1_SB_DQS_DN<0>")
	)
	(segment
		(start 135.754872 -276.186392)
		(end 135.763254 -276.191218)
		(width 0.09525)
		(layer "In2.Cu")
		(net "M_I_CPU1_SB_DQS_DN<0>")
	)
	(segment
		(start 174.492158 -284.778958)
		(end 175.01743 -284.778958)
		(width 0.16002)
		(layer "In2.Cu")
		(net "M_I_CPU1_SB_DQS_DN<0>")
	)
	(segment
		(start 182.544466 -285.579058)
		(end 182.661306 -285.462218)
		(width 0.16002)
		(layer "In2.Cu")
		(net "M_I_CPU1_SB_DQS_DN<0>")
	)
	(segment
		(start 182.064406 -285.579058)
		(end 182.544466 -285.579058)
		(width 0.16002)
		(layer "In2.Cu")
		(net "M_I_CPU1_SB_DQS_DN<0>")
	)
	(segment
		(start 141.394942 -276.186392)
		(end 141.403324 -276.191218)
		(width 0.09525)
		(layer "In2.Cu")
		(net "M_I_CPU1_SB_DQS_DN<0>")
	)
	(segment
		(start 146.74088 -275.203158)
		(end 147.284694 -275.203158)
		(width 0.09525)
		(layer "In2.Cu")
		(net "M_I_CPU1_SB_DQS_DN<0>")
	)
	(segment
		(start 160.857438 -282.909772)
		(end 163.260024 -285.312358)
		(width 0.16002)
		(layer "In2.Cu")
		(net "M_I_CPU1_SB_DQS_DN<0>")
	)
	(segment
		(start 129.780792 -276.250908)
		(end 129.80416 -276.16404)
		(width 0.09525)
		(layer "In2.Cu")
		(net "M_I_CPU1_SB_DQS_DN<0>")
	)
	(segment
		(start 177.934366 -285.036514)
		(end 180.019706 -285.036514)
		(width 0.16002)
		(layer "In2.Cu")
		(net "M_I_CPU1_SB_DQS_DN<0>")
	)
	(segment
		(start 169.76852 -284.462474)
		(end 170.618404 -285.312358)
		(width 0.16002)
		(layer "In2.Cu")
		(net "M_I_CPU1_SB_DQS_DN<0>")
	)
	(segment
		(start 165.207696 -285.312358)
		(end 165.515036 -285.619698)
		(width 0.16002)
		(layer "In2.Cu")
		(net "M_I_CPU1_SB_DQS_DN<0>")
	)
	(segment
		(start 147.284694 -275.203158)
		(end 147.34667 -275.141182)
		(width 0.09525)
		(layer "In2.Cu")
		(net "M_I_CPU1_SB_DQS_DN<0>")
	)
	(segment
		(start 172.75175 -285.312358)
		(end 173.05909 -285.619698)
		(width 0.16002)
		(layer "In2.Cu")
		(net "M_I_CPU1_SB_DQS_DN<0>")
	)
	(segment
		(start 141.966188 -276.191218)
		(end 141.97457 -276.186392)
		(width 0.09525)
		(layer "In2.Cu")
		(net "M_I_CPU1_SB_DQS_DN<0>")
	)
	(segment
		(start 177.360326 -284.462474)
		(end 177.934366 -285.036514)
		(width 0.16002)
		(layer "In2.Cu")
		(net "M_I_CPU1_SB_DQS_DN<0>")
	)
	(segment
		(start 165.515036 -285.619698)
		(end 166.107364 -285.619698)
		(width 0.16002)
		(layer "In2.Cu")
		(net "M_I_CPU1_SB_DQS_DN<0>")
	)
	(segment
		(start 144.77238 -276.199854)
		(end 144.787112 -276.191218)
		(width 0.09525)
		(layer "In2.Cu")
		(net "M_I_CPU1_SB_DQS_DN<0>")
	)
	(segment
		(start 145.155412 -276.186392)
		(end 145.163794 -276.191218)
		(width 0.09525)
		(layer "In2.Cu")
		(net "M_I_CPU1_SB_DQS_DN<0>")
	)
	(segment
		(start 173.05909 -285.619698)
		(end 173.651418 -285.619698)
		(width 0.16002)
		(layer "In2.Cu")
		(net "M_I_CPU1_SB_DQS_DN<0>")
	)
	(segment
		(start 145.163794 -276.191218)
		(end 145.184622 -276.20341)
		(width 0.09525)
		(layer "In2.Cu")
		(net "M_I_CPU1_SB_DQS_DN<0>")
	)
	(segment
		(start 175.333914 -284.462474)
		(end 177.360326 -284.462474)
		(width 0.16002)
		(layer "In2.Cu")
		(net "M_I_CPU1_SB_DQS_DN<0>")
	)
	(segment
		(start 131.99491 -276.186392)
		(end 132.003292 -276.191218)
		(width 0.09525)
		(layer "In2.Cu")
		(net "M_I_CPU1_SB_DQS_DN<0>")
	)
	(segment
		(start 163.260024 -285.312358)
		(end 165.207696 -285.312358)
		(width 0.16002)
		(layer "In2.Cu")
		(net "M_I_CPU1_SB_DQS_DN<0>")
	)
	(segment
		(start 167.78986 -284.462474)
		(end 169.76852 -284.462474)
		(width 0.16002)
		(layer "In2.Cu")
		(net "M_I_CPU1_SB_DQS_DN<0>")
	)
	(segment
		(start 143.846042 -276.191218)
		(end 143.854424 -276.186392)
		(width 0.09525)
		(layer "In2.Cu")
		(net "M_I_CPU1_SB_DQS_DN<0>")
	)
	(segment
		(start 147.836636 -275.141182)
		(end 147.895564 -275.20011)
		(width 0.09525)
		(layer "In2.Cu")
		(net "M_I_CPU1_SB_DQS_DN<0>")
	)
	(segment
		(start 147.919186 -275.20011)
		(end 152.539192 -275.20011)
		(width 0.16002)
		(layer "In2.Cu")
		(net "M_I_CPU1_SB_DQS_DN<0>")
	)
	(segment
		(start 180.019706 -285.036514)
		(end 180.62829 -285.645098)
		(width 0.16002)
		(layer "In2.Cu")
		(net "M_I_CPU1_SB_DQS_DN<0>")
	)
	(segment
		(start 133.50621 -276.191218)
		(end 133.514592 -276.186392)
		(width 0.09525)
		(layer "In2.Cu")
		(net "M_I_CPU1_SB_DQS_DN<0>")
	)
	(segment
		(start 183.343042 -285.462218)
		(end 183.616092 -285.735268)
		(width 0.16002)
		(layer "In2.Cu")
		(net "M_I_CPU1_SB_DQS_DN<0>")
	)
	(segment
		(start 173.651418 -285.619698)
		(end 174.492158 -284.778958)
		(width 0.16002)
		(layer "In2.Cu")
		(net "M_I_CPU1_SB_DQS_DN<0>")
	)
	(segment
		(start 167.473376 -284.778958)
		(end 167.78986 -284.462474)
		(width 0.16002)
		(layer "In2.Cu")
		(net "M_I_CPU1_SB_DQS_DN<0>")
	)
	(segment
		(start 138.206226 -276.191218)
		(end 138.214608 -276.186392)
		(width 0.09525)
		(layer "In2.Cu")
		(net "M_I_CPU1_SB_DQS_DN<0>")
	)
	(segment
		(start 181.947566 -285.462218)
		(end 182.064406 -285.579058)
		(width 0.16002)
		(layer "In2.Cu")
		(net "M_I_CPU1_SB_DQS_DN<0>")
	)
	(segment
		(start 166.948104 -284.778958)
		(end 167.473376 -284.778958)
		(width 0.16002)
		(layer "In2.Cu")
		(net "M_I_CPU1_SB_DQS_DN<0>")
	)
	(segment
		(start 181.284626 -285.645098)
		(end 181.467506 -285.462218)
		(width 0.16002)
		(layer "In2.Cu")
		(net "M_I_CPU1_SB_DQS_DN<0>")
	)
	(segment
		(start 160.248854 -282.909772)
		(end 160.857438 -282.909772)
		(width 0.16002)
		(layer "In2.Cu")
		(net "M_I_CPU1_SB_DQS_DN<0>")
	)
	(segment
		(start 180.62829 -285.645098)
		(end 181.284626 -285.645098)
		(width 0.16002)
		(layer "In2.Cu")
		(net "M_I_CPU1_SB_DQS_DN<0>")
	)
	(segment
		(start 170.618404 -285.312358)
		(end 172.75175 -285.312358)
		(width 0.16002)
		(layer "In2.Cu")
		(net "M_I_CPU1_SB_DQS_DN<0>")
	)
	(segment
		(start 136.694926 -276.186392)
		(end 136.703308 -276.191218)
		(width 0.09525)
		(layer "In2.Cu")
		(net "M_I_CPU1_SB_DQS_DN<0>")
	)
	(segment
		(start 145.841212 -276.102826)
		(end 146.74088 -275.203158)
		(width 0.09525)
		(layer "In2.Cu")
		(net "M_I_CPU1_SB_DQS_DN<0>")
	)
	(segment
		(start 166.107364 -285.619698)
		(end 166.948104 -284.778958)
		(width 0.16002)
		(layer "In2.Cu")
		(net "M_I_CPU1_SB_DQS_DN<0>")
	)
	(segment
		(start 137.266172 -276.191218)
		(end 137.274554 -276.186392)
		(width 0.09525)
		(layer "In2.Cu")
		(net "M_I_CPU1_SB_DQS_DN<0>")
	)
	(segment
		(start 147.34667 -275.141182)
		(end 147.836636 -275.141182)
		(width 0.09525)
		(layer "In2.Cu")
		(net "M_I_CPU1_SB_DQS_DN<0>")
	)
	(segment
		(start 182.661306 -285.462218)
		(end 183.343042 -285.462218)
		(width 0.16002)
		(layer "In2.Cu")
		(net "M_I_CPU1_SB_DQS_DN<0>")
	)
	(segment
		(start 152.539192 -275.20011)
		(end 160.248854 -282.909772)
		(width 0.16002)
		(layer "In2.Cu")
		(net "M_I_CPU1_SB_DQS_DN<0>")
	)
	(segment
		(start 140.454888 -276.186392)
		(end 140.46327 -276.191218)
		(width 0.09525)
		(layer "In2.Cu")
		(net "M_I_CPU1_SB_DQS_DN<0>")
	)
	(segment
		(start 147.895564 -275.20011)
		(end 147.919186 -275.20011)
		(width 0.09525)
		(layer "In2.Cu")
		(net "M_I_CPU1_SB_DQS_DN<0>")
	)
	(segment
		(start 175.01743 -284.778958)
		(end 175.333914 -284.462474)
		(width 0.16002)
		(layer "In2.Cu")
		(net "M_I_CPU1_SB_DQS_DN<0>")
	)
	(segment
		(start 132.934964 -276.186392)
		(end 132.943346 -276.191218)
		(width 0.09525)
		(layer "In2.Cu")
		(net "M_I_CPU1_SB_DQS_DN<0>")
	)
	(segment
		(start 181.467506 -285.462218)
		(end 181.947566 -285.462218)
		(width 0.16002)
		(layer "In2.Cu")
		(net "M_I_CPU1_SB_DQS_DN<0>")
	)
	(segment
		(start 129.934716 -276.516338)
		(end 129.780792 -276.250908)
		(width 0.09525)
		(layer "In2.Cu")
		(net "M_I_CPU1_SB_DQS_DN<0>")
	)
	(arc
		(start 144.787112 -276.191218)
		(mid 144.970633 -276.140574)
		(end 145.155412 -276.186392)
		(width 0.09525)
		(layer "In2.Cu")
		(net "M_I_CPU1_SB_DQS_DN<0>")
	)
	(arc
		(start 136.326118 -276.191218)
		(mid 136.509893 -276.140446)
		(end 136.694926 -276.186392)
		(width 0.09525)
		(layer "In2.Cu")
		(net "M_I_CPU1_SB_DQS_DN<0>")
	)
	(arc
		(start 137.643362 -276.191218)
		(mid 137.924794 -276.266973)
		(end 138.206226 -276.191218)
		(width 0.09525)
		(layer "In2.Cu")
		(net "M_I_CPU1_SB_DQS_DN<0>")
	)
	(arc
		(start 143.283178 -276.191218)
		(mid 143.56461 -276.266973)
		(end 143.846042 -276.191218)
		(width 0.09525)
		(layer "In2.Cu")
		(net "M_I_CPU1_SB_DQS_DN<0>")
	)
	(arc
		(start 130.123438 -276.191218)
		(mid 130.40487 -276.266973)
		(end 130.686302 -276.191218)
		(width 0.09525)
		(layer "In2.Cu")
		(net "M_I_CPU1_SB_DQS_DN<0>")
	)
	(arc
		(start 137.274554 -276.186392)
		(mid 137.459586 -276.140478)
		(end 137.643362 -276.191218)
		(width 0.09525)
		(layer "In2.Cu")
		(net "M_I_CPU1_SB_DQS_DN<0>")
	)
	(arc
		(start 132.003292 -276.191218)
		(mid 132.284724 -276.266973)
		(end 132.566156 -276.191218)
		(width 0.09525)
		(layer "In2.Cu")
		(net "M_I_CPU1_SB_DQS_DN<0>")
	)
	(arc
		(start 134.8232 -276.191218)
		(mid 135.104632 -276.266973)
		(end 135.386064 -276.191218)
		(width 0.09525)
		(layer "In2.Cu")
		(net "M_I_CPU1_SB_DQS_DN<0>")
	)
	(arc
		(start 129.80416 -276.16404)
		(mid 129.966842 -276.141908)
		(end 130.123438 -276.191218)
		(width 0.09525)
		(layer "In2.Cu")
		(net "M_I_CPU1_SB_DQS_DN<0>")
	)
	(arc
		(start 145.726658 -276.191218)
		(mid 145.786793 -276.150727)
		(end 145.841212 -276.102826)
		(width 0.09525)
		(layer "In2.Cu")
		(net "M_I_CPU1_SB_DQS_DN<0>")
	)
	(arc
		(start 132.943346 -276.191218)
		(mid 133.224778 -276.266973)
		(end 133.50621 -276.191218)
		(width 0.09525)
		(layer "In2.Cu")
		(net "M_I_CPU1_SB_DQS_DN<0>")
	)
	(arc
		(start 140.46327 -276.191218)
		(mid 140.744702 -276.266973)
		(end 141.026134 -276.191218)
		(width 0.09525)
		(layer "In2.Cu")
		(net "M_I_CPU1_SB_DQS_DN<0>")
	)
	(arc
		(start 141.026134 -276.191218)
		(mid 141.209909 -276.140446)
		(end 141.394942 -276.186392)
		(width 0.09525)
		(layer "In2.Cu")
		(net "M_I_CPU1_SB_DQS_DN<0>")
	)
	(arc
		(start 135.386064 -276.191218)
		(mid 135.569839 -276.140446)
		(end 135.754872 -276.186392)
		(width 0.09525)
		(layer "In2.Cu")
		(net "M_I_CPU1_SB_DQS_DN<0>")
	)
	(arc
		(start 144.22374 -276.191218)
		(mid 144.496922 -276.26716)
		(end 144.77238 -276.199854)
		(width 0.09525)
		(layer "In2.Cu")
		(net "M_I_CPU1_SB_DQS_DN<0>")
	)
	(arc
		(start 138.583416 -276.191218)
		(mid 138.864848 -276.266973)
		(end 139.14628 -276.191218)
		(width 0.09525)
		(layer "In2.Cu")
		(net "M_I_CPU1_SB_DQS_DN<0>")
	)
	(arc
		(start 139.14628 -276.191218)
		(mid 139.334748 -276.140541)
		(end 139.523216 -276.191218)
		(width 0.09525)
		(layer "In2.Cu")
		(net "M_I_CPU1_SB_DQS_DN<0>")
	)
	(arc
		(start 142.343378 -276.191218)
		(mid 142.62481 -276.266973)
		(end 142.906242 -276.191218)
		(width 0.09525)
		(layer "In2.Cu")
		(net "M_I_CPU1_SB_DQS_DN<0>")
	)
	(arc
		(start 135.763254 -276.191218)
		(mid 136.044686 -276.266973)
		(end 136.326118 -276.191218)
		(width 0.09525)
		(layer "In2.Cu")
		(net "M_I_CPU1_SB_DQS_DN<0>")
	)
	(arc
		(start 145.184622 -276.20341)
		(mid 145.457227 -276.267206)
		(end 145.726658 -276.191218)
		(width 0.09525)
		(layer "In2.Cu")
		(net "M_I_CPU1_SB_DQS_DN<0>")
	)
	(arc
		(start 131.063238 -276.191218)
		(mid 131.34467 -276.266973)
		(end 131.626102 -276.191218)
		(width 0.09525)
		(layer "In2.Cu")
		(net "M_I_CPU1_SB_DQS_DN<0>")
	)
	(arc
		(start 133.8834 -276.191218)
		(mid 134.164832 -276.266973)
		(end 134.446264 -276.191218)
		(width 0.09525)
		(layer "In2.Cu")
		(net "M_I_CPU1_SB_DQS_DN<0>")
	)
	(arc
		(start 134.446264 -276.191218)
		(mid 134.634732 -276.140541)
		(end 134.8232 -276.191218)
		(width 0.09525)
		(layer "In2.Cu")
		(net "M_I_CPU1_SB_DQS_DN<0>")
	)
	(arc
		(start 143.854424 -276.186392)
		(mid 144.03971 -276.140356)
		(end 144.22374 -276.191218)
		(width 0.09525)
		(layer "In2.Cu")
		(net "M_I_CPU1_SB_DQS_DN<0>")
	)
	(arc
		(start 130.686302 -276.191218)
		(mid 130.87477 -276.140541)
		(end 131.063238 -276.191218)
		(width 0.09525)
		(layer "In2.Cu")
		(net "M_I_CPU1_SB_DQS_DN<0>")
	)
	(arc
		(start 140.08608 -276.191218)
		(mid 140.269855 -276.140446)
		(end 140.454888 -276.186392)
		(width 0.09525)
		(layer "In2.Cu")
		(net "M_I_CPU1_SB_DQS_DN<0>")
	)
	(arc
		(start 142.906242 -276.191218)
		(mid 143.09471 -276.140541)
		(end 143.283178 -276.191218)
		(width 0.09525)
		(layer "In2.Cu")
		(net "M_I_CPU1_SB_DQS_DN<0>")
	)
	(arc
		(start 133.514592 -276.186392)
		(mid 133.699624 -276.140478)
		(end 133.8834 -276.191218)
		(width 0.09525)
		(layer "In2.Cu")
		(net "M_I_CPU1_SB_DQS_DN<0>")
	)
	(arc
		(start 136.703308 -276.191218)
		(mid 136.98474 -276.266973)
		(end 137.266172 -276.191218)
		(width 0.09525)
		(layer "In2.Cu")
		(net "M_I_CPU1_SB_DQS_DN<0>")
	)
	(arc
		(start 132.566156 -276.191218)
		(mid 132.749931 -276.140446)
		(end 132.934964 -276.186392)
		(width 0.09525)
		(layer "In2.Cu")
		(net "M_I_CPU1_SB_DQS_DN<0>")
	)
	(arc
		(start 138.214608 -276.186392)
		(mid 138.39964 -276.140478)
		(end 138.583416 -276.191218)
		(width 0.09525)
		(layer "In2.Cu")
		(net "M_I_CPU1_SB_DQS_DN<0>")
	)
	(arc
		(start 139.523216 -276.191218)
		(mid 139.804648 -276.266973)
		(end 140.08608 -276.191218)
		(width 0.09525)
		(layer "In2.Cu")
		(net "M_I_CPU1_SB_DQS_DN<0>")
	)
	(arc
		(start 131.626102 -276.191218)
		(mid 131.809877 -276.140446)
		(end 131.99491 -276.186392)
		(width 0.09525)
		(layer "In2.Cu")
		(net "M_I_CPU1_SB_DQS_DN<0>")
	)
	(arc
		(start 141.403324 -276.191218)
		(mid 141.684756 -276.266973)
		(end 141.966188 -276.191218)
		(width 0.09525)
		(layer "In2.Cu")
		(net "M_I_CPU1_SB_DQS_DN<0>")
	)
	(arc
		(start 141.97457 -276.186392)
		(mid 142.159602 -276.140478)
		(end 142.343378 -276.191218)
		(width 0.09525)
		(layer "In2.Cu")
		(net "M_I_CPU1_SB_DQS_DN<0>")
	)
	(segment
		(start 127.58801 -279.490424)
		(end 128.054862 -279.756362)
		(width 0.10668)
		(layer "F.Cu")
		(net "M_I_CPU1_SB_DQ<9>")
	)
	(segment
		(start 183.19115 -292.110414)
		(end 183.616092 -292.535356)
		(width 0.14478)
		(layer "In2.Cu")
		(net "M_I_CPU1_SB_DQ<9>")
	)
	(segment
		(start 131.993386 -280.083768)
		(end 132.001768 -280.078942)
		(width 0.0889)
		(layer "In2.Cu")
		(net "M_I_CPU1_SB_DQ<9>")
	)
	(segment
		(start 135.753348 -280.083768)
		(end 135.76173 -280.078942)
		(width 0.0889)
		(layer "In2.Cu")
		(net "M_I_CPU1_SB_DQ<9>")
	)
	(segment
		(start 145.357342 -280.009092)
		(end 145.739866 -280.009092)
		(width 0.0889)
		(layer "In2.Cu")
		(net "M_I_CPU1_SB_DQ<9>")
	)
	(segment
		(start 165.212522 -292.960298)
		(end 167.264334 -292.110414)
		(width 0.14478)
		(layer "In2.Cu")
		(net "M_I_CPU1_SB_DQ<9>")
	)
	(segment
		(start 181.515512 -292.271958)
		(end 181.677056 -292.110414)
		(width 0.14478)
		(layer "In2.Cu")
		(net "M_I_CPU1_SB_DQ<9>")
	)
	(segment
		(start 137.267696 -280.078942)
		(end 137.276078 -280.083768)
		(width 0.0889)
		(layer "In2.Cu")
		(net "M_I_CPU1_SB_DQ<9>")
	)
	(segment
		(start 171.759626 -292.960298)
		(end 172.312584 -292.960298)
		(width 0.14478)
		(layer "In2.Cu")
		(net "M_I_CPU1_SB_DQ<9>")
	)
	(segment
		(start 167.264334 -292.110414)
		(end 169.708322 -292.110414)
		(width 0.14478)
		(layer "In2.Cu")
		(net "M_I_CPU1_SB_DQ<9>")
	)
	(segment
		(start 181.353968 -292.790626)
		(end 181.515512 -292.629082)
		(width 0.14478)
		(layer "In2.Cu")
		(net "M_I_CPU1_SB_DQ<9>")
	)
	(segment
		(start 181.677056 -292.110414)
		(end 183.19115 -292.110414)
		(width 0.14478)
		(layer "In2.Cu")
		(net "M_I_CPU1_SB_DQ<9>")
	)
	(segment
		(start 129.747772 -280.078942)
		(end 129.756154 -280.083768)
		(width 0.0889)
		(layer "In2.Cu")
		(net "M_I_CPU1_SB_DQ<9>")
	)
	(segment
		(start 181.515512 -292.629082)
		(end 181.515512 -292.271958)
		(width 0.14478)
		(layer "In2.Cu")
		(net "M_I_CPU1_SB_DQ<9>")
	)
	(segment
		(start 128.208786 -280.021792)
		(end 128.304798 -280.047192)
		(width 0.0889)
		(layer "In2.Cu")
		(net "M_I_CPU1_SB_DQ<9>")
	)
	(segment
		(start 172.312584 -292.960298)
		(end 174.364396 -292.110414)
		(width 0.14478)
		(layer "In2.Cu")
		(net "M_I_CPU1_SB_DQ<9>")
	)
	(segment
		(start 153.033476 -283.088334)
		(end 153.91892 -283.088334)
		(width 0.14478)
		(layer "In2.Cu")
		(net "M_I_CPU1_SB_DQ<9>")
	)
	(segment
		(start 163.790884 -292.960298)
		(end 165.212522 -292.960298)
		(width 0.14478)
		(layer "In2.Cu")
		(net "M_I_CPU1_SB_DQ<9>")
	)
	(segment
		(start 149.844506 -279.899364)
		(end 153.033476 -283.088334)
		(width 0.14478)
		(layer "In2.Cu")
		(net "M_I_CPU1_SB_DQ<9>")
	)
	(segment
		(start 136.693402 -280.083768)
		(end 136.701784 -280.078942)
		(width 0.0889)
		(layer "In2.Cu")
		(net "M_I_CPU1_SB_DQ<9>")
	)
	(segment
		(start 180.964078 -292.629082)
		(end 181.125622 -292.790626)
		(width 0.14478)
		(layer "In2.Cu")
		(net "M_I_CPU1_SB_DQ<9>")
	)
	(segment
		(start 141.393418 -280.083768)
		(end 141.4018 -280.078942)
		(width 0.0889)
		(layer "In2.Cu")
		(net "M_I_CPU1_SB_DQ<9>")
	)
	(segment
		(start 128.054862 -279.756362)
		(end 128.208786 -280.021792)
		(width 0.0889)
		(layer "In2.Cu")
		(net "M_I_CPU1_SB_DQ<9>")
	)
	(segment
		(start 141.967712 -280.078942)
		(end 141.976094 -280.083768)
		(width 0.0889)
		(layer "In2.Cu")
		(net "M_I_CPU1_SB_DQ<9>")
	)
	(segment
		(start 147.855178 -279.899364)
		(end 149.844506 -279.899364)
		(width 0.14478)
		(layer "In2.Cu")
		(net "M_I_CPU1_SB_DQ<9>")
	)
	(segment
		(start 174.364396 -292.110414)
		(end 180.802534 -292.110414)
		(width 0.14478)
		(layer "In2.Cu")
		(net "M_I_CPU1_SB_DQ<9>")
	)
	(segment
		(start 144.784318 -280.078942)
		(end 144.804892 -280.09088)
		(width 0.0889)
		(layer "In2.Cu")
		(net "M_I_CPU1_SB_DQ<9>")
	)
	(segment
		(start 180.964078 -292.271958)
		(end 180.964078 -292.629082)
		(width 0.14478)
		(layer "In2.Cu")
		(net "M_I_CPU1_SB_DQ<9>")
	)
	(segment
		(start 132.93344 -280.083768)
		(end 132.941822 -280.078942)
		(width 0.0889)
		(layer "In2.Cu")
		(net "M_I_CPU1_SB_DQ<9>")
	)
	(segment
		(start 144.220438 -280.078688)
		(end 144.2466 -280.063702)
		(width 0.0889)
		(layer "In2.Cu")
		(net "M_I_CPU1_SB_DQ<9>")
	)
	(segment
		(start 138.20775 -280.078942)
		(end 138.216132 -280.083768)
		(width 0.0889)
		(layer "In2.Cu")
		(net "M_I_CPU1_SB_DQ<9>")
	)
	(segment
		(start 140.453364 -280.083768)
		(end 140.461746 -280.078942)
		(width 0.0889)
		(layer "In2.Cu")
		(net "M_I_CPU1_SB_DQ<9>")
	)
	(segment
		(start 144.19707 -280.09215)
		(end 144.220438 -280.078688)
		(width 0.0889)
		(layer "In2.Cu")
		(net "M_I_CPU1_SB_DQ<9>")
	)
	(segment
		(start 128.807718 -280.078942)
		(end 128.8161 -280.083768)
		(width 0.0889)
		(layer "In2.Cu")
		(net "M_I_CPU1_SB_DQ<9>")
	)
	(segment
		(start 180.802534 -292.110414)
		(end 180.964078 -292.271958)
		(width 0.14478)
		(layer "In2.Cu")
		(net "M_I_CPU1_SB_DQ<9>")
	)
	(segment
		(start 145.15973 -280.078942)
		(end 145.159984 -280.079196)
		(width 0.0889)
		(layer "In2.Cu")
		(net "M_I_CPU1_SB_DQ<9>")
	)
	(segment
		(start 133.507734 -280.078942)
		(end 133.516116 -280.083768)
		(width 0.0889)
		(layer "In2.Cu")
		(net "M_I_CPU1_SB_DQ<9>")
	)
	(segment
		(start 145.739866 -280.009092)
		(end 145.849594 -279.899364)
		(width 0.0889)
		(layer "In2.Cu")
		(net "M_I_CPU1_SB_DQ<9>")
	)
	(segment
		(start 153.91892 -283.088334)
		(end 163.790884 -292.960298)
		(width 0.14478)
		(layer "In2.Cu")
		(net "M_I_CPU1_SB_DQ<9>")
	)
	(segment
		(start 169.708322 -292.110414)
		(end 171.759626 -292.960298)
		(width 0.14478)
		(layer "In2.Cu")
		(net "M_I_CPU1_SB_DQ<9>")
	)
	(segment
		(start 145.849594 -279.899364)
		(end 147.855178 -279.899364)
		(width 0.0889)
		(layer "In2.Cu")
		(net "M_I_CPU1_SB_DQ<9>")
	)
	(segment
		(start 181.125622 -292.790626)
		(end 181.353968 -292.790626)
		(width 0.14478)
		(layer "In2.Cu")
		(net "M_I_CPU1_SB_DQ<9>")
	)
	(arc
		(start 129.756154 -280.083768)
		(mid 129.939662 -280.129262)
		(end 130.121914 -280.078942)
		(width 0.0889)
		(layer "In2.Cu")
		(net "M_I_CPU1_SB_DQ<9>")
	)
	(arc
		(start 143.281654 -280.078942)
		(mid 143.56461 -280.002765)
		(end 143.847566 -280.078942)
		(width 0.0889)
		(layer "In2.Cu")
		(net "M_I_CPU1_SB_DQ<9>")
	)
	(arc
		(start 128.304798 -280.047192)
		(mid 128.560006 -280.003715)
		(end 128.807718 -280.078942)
		(width 0.0889)
		(layer "In2.Cu")
		(net "M_I_CPU1_SB_DQ<9>")
	)
	(arc
		(start 144.804892 -280.09088)
		(mid 144.98382 -280.129757)
		(end 145.15973 -280.078942)
		(width 0.0889)
		(layer "In2.Cu")
		(net "M_I_CPU1_SB_DQ<9>")
	)
	(arc
		(start 140.087604 -280.078942)
		(mid 140.269855 -280.129292)
		(end 140.453364 -280.083768)
		(width 0.0889)
		(layer "In2.Cu")
		(net "M_I_CPU1_SB_DQ<9>")
	)
	(arc
		(start 132.941822 -280.078942)
		(mid 133.224778 -280.002765)
		(end 133.507734 -280.078942)
		(width 0.0889)
		(layer "In2.Cu")
		(net "M_I_CPU1_SB_DQ<9>")
	)
	(arc
		(start 141.4018 -280.078942)
		(mid 141.684756 -280.002765)
		(end 141.967712 -280.078942)
		(width 0.0889)
		(layer "In2.Cu")
		(net "M_I_CPU1_SB_DQ<9>")
	)
	(arc
		(start 133.881876 -280.078942)
		(mid 134.164832 -280.002765)
		(end 134.447788 -280.078942)
		(width 0.0889)
		(layer "In2.Cu")
		(net "M_I_CPU1_SB_DQ<9>")
	)
	(arc
		(start 135.76173 -280.078942)
		(mid 136.044686 -280.002765)
		(end 136.327642 -280.078942)
		(width 0.0889)
		(layer "In2.Cu")
		(net "M_I_CPU1_SB_DQ<9>")
	)
	(arc
		(start 145.159984 -280.079196)
		(mid 145.255384 -280.034914)
		(end 145.357342 -280.009092)
		(width 0.0889)
		(layer "In2.Cu")
		(net "M_I_CPU1_SB_DQ<9>")
	)
	(arc
		(start 139.147804 -280.078942)
		(mid 139.334748 -280.129197)
		(end 139.521692 -280.078942)
		(width 0.0889)
		(layer "In2.Cu")
		(net "M_I_CPU1_SB_DQ<9>")
	)
	(arc
		(start 128.8161 -280.083768)
		(mid 128.999608 -280.129262)
		(end 129.18186 -280.078942)
		(width 0.0889)
		(layer "In2.Cu")
		(net "M_I_CPU1_SB_DQ<9>")
	)
	(arc
		(start 143.847566 -280.078942)
		(mid 144.020674 -280.129058)
		(end 144.19707 -280.09215)
		(width 0.0889)
		(layer "In2.Cu")
		(net "M_I_CPU1_SB_DQ<9>")
	)
	(arc
		(start 131.061714 -280.078942)
		(mid 131.34467 -280.002765)
		(end 131.627626 -280.078942)
		(width 0.0889)
		(layer "In2.Cu")
		(net "M_I_CPU1_SB_DQ<9>")
	)
	(arc
		(start 142.341854 -280.078942)
		(mid 142.62481 -280.002765)
		(end 142.907766 -280.078942)
		(width 0.0889)
		(layer "In2.Cu")
		(net "M_I_CPU1_SB_DQ<9>")
	)
	(arc
		(start 140.461746 -280.078942)
		(mid 140.744702 -280.002765)
		(end 141.027658 -280.078942)
		(width 0.0889)
		(layer "In2.Cu")
		(net "M_I_CPU1_SB_DQ<9>")
	)
	(arc
		(start 130.687826 -280.078942)
		(mid 130.87477 -280.129197)
		(end 131.061714 -280.078942)
		(width 0.0889)
		(layer "In2.Cu")
		(net "M_I_CPU1_SB_DQ<9>")
	)
	(arc
		(start 133.516116 -280.083768)
		(mid 133.699624 -280.129262)
		(end 133.881876 -280.078942)
		(width 0.0889)
		(layer "In2.Cu")
		(net "M_I_CPU1_SB_DQ<9>")
	)
	(arc
		(start 132.56768 -280.078942)
		(mid 132.749931 -280.129292)
		(end 132.93344 -280.083768)
		(width 0.0889)
		(layer "In2.Cu")
		(net "M_I_CPU1_SB_DQ<9>")
	)
	(arc
		(start 130.121914 -280.078942)
		(mid 130.40487 -280.002765)
		(end 130.687826 -280.078942)
		(width 0.0889)
		(layer "In2.Cu")
		(net "M_I_CPU1_SB_DQ<9>")
	)
	(arc
		(start 144.2466 -280.063702)
		(mid 144.517386 -280.003056)
		(end 144.784318 -280.078942)
		(width 0.0889)
		(layer "In2.Cu")
		(net "M_I_CPU1_SB_DQ<9>")
	)
	(arc
		(start 134.821676 -280.078942)
		(mid 135.104632 -280.002765)
		(end 135.387588 -280.078942)
		(width 0.0889)
		(layer "In2.Cu")
		(net "M_I_CPU1_SB_DQ<9>")
	)
	(arc
		(start 135.387588 -280.078942)
		(mid 135.569839 -280.129292)
		(end 135.753348 -280.083768)
		(width 0.0889)
		(layer "In2.Cu")
		(net "M_I_CPU1_SB_DQ<9>")
	)
	(arc
		(start 142.907766 -280.078942)
		(mid 143.09471 -280.129197)
		(end 143.281654 -280.078942)
		(width 0.0889)
		(layer "In2.Cu")
		(net "M_I_CPU1_SB_DQ<9>")
	)
	(arc
		(start 131.627626 -280.078942)
		(mid 131.809877 -280.129292)
		(end 131.993386 -280.083768)
		(width 0.0889)
		(layer "In2.Cu")
		(net "M_I_CPU1_SB_DQ<9>")
	)
	(arc
		(start 136.327642 -280.078942)
		(mid 136.509893 -280.129292)
		(end 136.693402 -280.083768)
		(width 0.0889)
		(layer "In2.Cu")
		(net "M_I_CPU1_SB_DQ<9>")
	)
	(arc
		(start 132.001768 -280.078942)
		(mid 132.284724 -280.002765)
		(end 132.56768 -280.078942)
		(width 0.0889)
		(layer "In2.Cu")
		(net "M_I_CPU1_SB_DQ<9>")
	)
	(arc
		(start 137.276078 -280.083768)
		(mid 137.459586 -280.129262)
		(end 137.641838 -280.078942)
		(width 0.0889)
		(layer "In2.Cu")
		(net "M_I_CPU1_SB_DQ<9>")
	)
	(arc
		(start 137.641838 -280.078942)
		(mid 137.924794 -280.002765)
		(end 138.20775 -280.078942)
		(width 0.0889)
		(layer "In2.Cu")
		(net "M_I_CPU1_SB_DQ<9>")
	)
	(arc
		(start 141.976094 -280.083768)
		(mid 142.159602 -280.129262)
		(end 142.341854 -280.078942)
		(width 0.0889)
		(layer "In2.Cu")
		(net "M_I_CPU1_SB_DQ<9>")
	)
	(arc
		(start 129.18186 -280.078942)
		(mid 129.464816 -280.002765)
		(end 129.747772 -280.078942)
		(width 0.0889)
		(layer "In2.Cu")
		(net "M_I_CPU1_SB_DQ<9>")
	)
	(arc
		(start 138.581892 -280.078942)
		(mid 138.864848 -280.002765)
		(end 139.147804 -280.078942)
		(width 0.0889)
		(layer "In2.Cu")
		(net "M_I_CPU1_SB_DQ<9>")
	)
	(arc
		(start 134.447788 -280.078942)
		(mid 134.634732 -280.129197)
		(end 134.821676 -280.078942)
		(width 0.0889)
		(layer "In2.Cu")
		(net "M_I_CPU1_SB_DQ<9>")
	)
	(arc
		(start 139.521692 -280.078942)
		(mid 139.804648 -280.002765)
		(end 140.087604 -280.078942)
		(width 0.0889)
		(layer "In2.Cu")
		(net "M_I_CPU1_SB_DQ<9>")
	)
	(arc
		(start 138.216132 -280.083768)
		(mid 138.39964 -280.129262)
		(end 138.581892 -280.078942)
		(width 0.0889)
		(layer "In2.Cu")
		(net "M_I_CPU1_SB_DQ<9>")
	)
	(arc
		(start 141.027658 -280.078942)
		(mid 141.209909 -280.129292)
		(end 141.393418 -280.083768)
		(width 0.0889)
		(layer "In2.Cu")
		(net "M_I_CPU1_SB_DQ<9>")
	)
	(arc
		(start 136.701784 -280.078942)
		(mid 136.98474 -280.002765)
		(end 137.267696 -280.078942)
		(width 0.0889)
		(layer "In2.Cu")
		(net "M_I_CPU1_SB_DQ<9>")
	)
	(segment
		(start 128.997964 -278.680418)
		(end 129.464816 -278.946356)
		(width 0.10668)
		(layer "F.Cu")
		(net "M_I_CPU1_SB_DQ<8>")
	)
	(segment
		(start 173.807882 -290.706556)
		(end 175.297338 -290.410392)
		(width 0.14478)
		(layer "In2.Cu")
		(net "M_I_CPU1_SB_DQ<8>")
	)
	(segment
		(start 180.751988 -290.410392)
		(end 180.901848 -290.260532)
		(width 0.14478)
		(layer "In2.Cu")
		(net "M_I_CPU1_SB_DQ<8>")
	)
	(segment
		(start 164.31006 -291.260276)
		(end 164.81806 -291.260276)
		(width 0.14478)
		(layer "In2.Cu")
		(net "M_I_CPU1_SB_DQ<8>")
	)
	(segment
		(start 146.47164 -278.54275)
		(end 147.41906 -278.54275)
		(width 0.0889)
		(layer "In2.Cu")
		(net "M_I_CPU1_SB_DQ<8>")
	)
	(segment
		(start 140.557758 -279.268936)
		(end 140.56614 -279.273762)
		(width 0.0889)
		(layer "In2.Cu")
		(net "M_I_CPU1_SB_DQ<8>")
	)
	(segment
		(start 129.464816 -278.946356)
		(end 129.61874 -279.211786)
		(width 0.0889)
		(layer "In2.Cu")
		(net "M_I_CPU1_SB_DQ<8>")
	)
	(segment
		(start 138.103356 -279.273762)
		(end 138.111738 -279.268936)
		(width 0.0889)
		(layer "In2.Cu")
		(net "M_I_CPU1_SB_DQ<8>")
	)
	(segment
		(start 148.01342 -278.61133)
		(end 150.713948 -278.61133)
		(width 0.14478)
		(layer "In2.Cu")
		(net "M_I_CPU1_SB_DQ<8>")
	)
	(segment
		(start 135.857742 -279.268936)
		(end 135.866124 -279.273762)
		(width 0.0889)
		(layer "In2.Cu")
		(net "M_I_CPU1_SB_DQ<8>")
	)
	(segment
		(start 181.310788 -289.736784)
		(end 181.460648 -289.886644)
		(width 0.14478)
		(layer "In2.Cu")
		(net "M_I_CPU1_SB_DQ<8>")
	)
	(segment
		(start 145.695162 -279.319228)
		(end 146.47164 -278.54275)
		(width 0.0889)
		(layer "In2.Cu")
		(net "M_I_CPU1_SB_DQ<8>")
	)
	(segment
		(start 131.157726 -279.268936)
		(end 131.166108 -279.273762)
		(width 0.0889)
		(layer "In2.Cu")
		(net "M_I_CPU1_SB_DQ<8>")
	)
	(segment
		(start 181.460648 -289.886644)
		(end 181.460648 -290.897564)
		(width 0.14478)
		(layer "In2.Cu")
		(net "M_I_CPU1_SB_DQ<8>")
	)
	(segment
		(start 167.617902 -290.410392)
		(end 169.283634 -290.410392)
		(width 0.14478)
		(layer "In2.Cu")
		(net "M_I_CPU1_SB_DQ<8>")
	)
	(segment
		(start 139.617704 -279.268936)
		(end 139.626086 -279.273762)
		(width 0.0889)
		(layer "In2.Cu")
		(net "M_I_CPU1_SB_DQ<8>")
	)
	(segment
		(start 150.713948 -278.61133)
		(end 162.693858 -290.59124)
		(width 0.14478)
		(layer "In2.Cu")
		(net "M_I_CPU1_SB_DQ<8>")
	)
	(segment
		(start 172.471334 -291.260276)
		(end 173.807882 -290.706556)
		(width 0.14478)
		(layer "In2.Cu")
		(net "M_I_CPU1_SB_DQ<8>")
	)
	(segment
		(start 182.019448 -290.897564)
		(end 182.019448 -290.560252)
		(width 0.14478)
		(layer "In2.Cu")
		(net "M_I_CPU1_SB_DQ<8>")
	)
	(segment
		(start 145.24228 -279.259538)
		(end 145.258028 -279.268682)
		(width 0.0889)
		(layer "In2.Cu")
		(net "M_I_CPU1_SB_DQ<8>")
	)
	(segment
		(start 183.19115 -290.410392)
		(end 183.616092 -290.835334)
		(width 0.14478)
		(layer "In2.Cu")
		(net "M_I_CPU1_SB_DQ<8>")
	)
	(segment
		(start 132.09778 -279.268936)
		(end 132.106162 -279.273762)
		(width 0.0889)
		(layer "In2.Cu")
		(net "M_I_CPU1_SB_DQ<8>")
	)
	(segment
		(start 181.610508 -291.047424)
		(end 181.869588 -291.047424)
		(width 0.14478)
		(layer "In2.Cu")
		(net "M_I_CPU1_SB_DQ<8>")
	)
	(segment
		(start 145.43659 -279.319228)
		(end 145.695162 -279.319228)
		(width 0.0889)
		(layer "In2.Cu")
		(net "M_I_CPU1_SB_DQ<8>")
	)
	(segment
		(start 147.48764 -278.61133)
		(end 148.01342 -278.61133)
		(width 0.0889)
		(layer "In2.Cu")
		(net "M_I_CPU1_SB_DQ<8>")
	)
	(segment
		(start 181.869588 -291.047424)
		(end 182.019448 -290.897564)
		(width 0.14478)
		(layer "In2.Cu")
		(net "M_I_CPU1_SB_DQ<8>")
	)
	(segment
		(start 162.693858 -290.59124)
		(end 164.31006 -291.260276)
		(width 0.14478)
		(layer "In2.Cu")
		(net "M_I_CPU1_SB_DQ<8>")
	)
	(segment
		(start 143.377666 -279.268936)
		(end 143.386048 -279.273762)
		(width 0.0889)
		(layer "In2.Cu")
		(net "M_I_CPU1_SB_DQ<8>")
	)
	(segment
		(start 139.04341 -279.273762)
		(end 139.051792 -279.268936)
		(width 0.0889)
		(layer "In2.Cu")
		(net "M_I_CPU1_SB_DQ<8>")
	)
	(segment
		(start 175.297338 -290.410392)
		(end 180.751988 -290.410392)
		(width 0.14478)
		(layer "In2.Cu")
		(net "M_I_CPU1_SB_DQ<8>")
	)
	(segment
		(start 180.901848 -289.886644)
		(end 181.051708 -289.736784)
		(width 0.14478)
		(layer "In2.Cu")
		(net "M_I_CPU1_SB_DQ<8>")
	)
	(segment
		(start 164.81806 -291.260276)
		(end 167.617902 -290.410392)
		(width 0.14478)
		(layer "In2.Cu")
		(net "M_I_CPU1_SB_DQ<8>")
	)
	(segment
		(start 142.803372 -279.273762)
		(end 142.811754 -279.268936)
		(width 0.0889)
		(layer "In2.Cu")
		(net "M_I_CPU1_SB_DQ<8>")
	)
	(segment
		(start 144.31772 -279.268936)
		(end 144.329404 -279.275794)
		(width 0.0889)
		(layer "In2.Cu")
		(net "M_I_CPU1_SB_DQ<8>")
	)
	(segment
		(start 134.343394 -279.273762)
		(end 134.351776 -279.268936)
		(width 0.0889)
		(layer "In2.Cu")
		(net "M_I_CPU1_SB_DQ<8>")
	)
	(segment
		(start 171.78147 -291.260276)
		(end 172.471334 -291.260276)
		(width 0.14478)
		(layer "In2.Cu")
		(net "M_I_CPU1_SB_DQ<8>")
	)
	(segment
		(start 180.901848 -290.260532)
		(end 180.901848 -289.886644)
		(width 0.14478)
		(layer "In2.Cu")
		(net "M_I_CPU1_SB_DQ<8>")
	)
	(segment
		(start 129.61874 -279.211786)
		(end 129.714752 -279.237186)
		(width 0.0889)
		(layer "In2.Cu")
		(net "M_I_CPU1_SB_DQ<8>")
	)
	(segment
		(start 147.41906 -278.54275)
		(end 147.48764 -278.61133)
		(width 0.0889)
		(layer "In2.Cu")
		(net "M_I_CPU1_SB_DQ<8>")
	)
	(segment
		(start 181.051708 -289.736784)
		(end 181.310788 -289.736784)
		(width 0.14478)
		(layer "In2.Cu")
		(net "M_I_CPU1_SB_DQ<8>")
	)
	(segment
		(start 130.583432 -279.273762)
		(end 130.591814 -279.268936)
		(width 0.0889)
		(layer "In2.Cu")
		(net "M_I_CPU1_SB_DQ<8>")
	)
	(segment
		(start 181.460648 -290.897564)
		(end 181.610508 -291.047424)
		(width 0.14478)
		(layer "In2.Cu")
		(net "M_I_CPU1_SB_DQ<8>")
	)
	(segment
		(start 134.917688 -279.268936)
		(end 134.92607 -279.273762)
		(width 0.0889)
		(layer "In2.Cu")
		(net "M_I_CPU1_SB_DQ<8>")
	)
	(segment
		(start 169.283634 -290.410392)
		(end 170.1419 -290.58108)
		(width 0.14478)
		(layer "In2.Cu")
		(net "M_I_CPU1_SB_DQ<8>")
	)
	(segment
		(start 182.169308 -290.410392)
		(end 183.19115 -290.410392)
		(width 0.14478)
		(layer "In2.Cu")
		(net "M_I_CPU1_SB_DQ<8>")
	)
	(segment
		(start 182.019448 -290.560252)
		(end 182.169308 -290.410392)
		(width 0.14478)
		(layer "In2.Cu")
		(net "M_I_CPU1_SB_DQ<8>")
	)
	(segment
		(start 145.258028 -279.268682)
		(end 145.276316 -279.279096)
		(width 0.0889)
		(layer "In2.Cu")
		(net "M_I_CPU1_SB_DQ<8>")
	)
	(segment
		(start 170.1419 -290.58108)
		(end 171.78147 -291.260276)
		(width 0.14478)
		(layer "In2.Cu")
		(net "M_I_CPU1_SB_DQ<8>")
	)
	(arc
		(start 134.351776 -279.268936)
		(mid 134.634732 -279.192759)
		(end 134.917688 -279.268936)
		(width 0.0889)
		(layer "In2.Cu")
		(net "M_I_CPU1_SB_DQ<8>")
	)
	(arc
		(start 137.171684 -279.268936)
		(mid 137.45464 -279.192759)
		(end 137.737596 -279.268936)
		(width 0.0889)
		(layer "In2.Cu")
		(net "M_I_CPU1_SB_DQ<8>")
	)
	(arc
		(start 138.111738 -279.268936)
		(mid 138.394694 -279.192759)
		(end 138.67765 -279.268936)
		(width 0.0889)
		(layer "In2.Cu")
		(net "M_I_CPU1_SB_DQ<8>")
	)
	(arc
		(start 136.231884 -279.268936)
		(mid 136.51484 -279.192759)
		(end 136.797796 -279.268936)
		(width 0.0889)
		(layer "In2.Cu")
		(net "M_I_CPU1_SB_DQ<8>")
	)
	(arc
		(start 136.797796 -279.268936)
		(mid 136.98474 -279.319191)
		(end 137.171684 -279.268936)
		(width 0.0889)
		(layer "In2.Cu")
		(net "M_I_CPU1_SB_DQ<8>")
	)
	(arc
		(start 130.591814 -279.268936)
		(mid 130.87477 -279.192759)
		(end 131.157726 -279.268936)
		(width 0.0889)
		(layer "In2.Cu")
		(net "M_I_CPU1_SB_DQ<8>")
	)
	(arc
		(start 137.737596 -279.268936)
		(mid 137.919847 -279.319286)
		(end 138.103356 -279.273762)
		(width 0.0889)
		(layer "In2.Cu")
		(net "M_I_CPU1_SB_DQ<8>")
	)
	(arc
		(start 139.051792 -279.268936)
		(mid 139.334748 -279.192759)
		(end 139.617704 -279.268936)
		(width 0.0889)
		(layer "In2.Cu")
		(net "M_I_CPU1_SB_DQ<8>")
	)
	(arc
		(start 139.626086 -279.273762)
		(mid 139.809594 -279.319256)
		(end 139.991846 -279.268936)
		(width 0.0889)
		(layer "In2.Cu")
		(net "M_I_CPU1_SB_DQ<8>")
	)
	(arc
		(start 138.67765 -279.268936)
		(mid 138.859901 -279.319286)
		(end 139.04341 -279.273762)
		(width 0.0889)
		(layer "In2.Cu")
		(net "M_I_CPU1_SB_DQ<8>")
	)
	(arc
		(start 144.329404 -279.275794)
		(mid 144.511659 -279.319447)
		(end 144.692116 -279.268936)
		(width 0.0889)
		(layer "In2.Cu")
		(net "M_I_CPU1_SB_DQ<8>")
	)
	(arc
		(start 133.411722 -279.268936)
		(mid 133.694678 -279.192759)
		(end 133.977634 -279.268936)
		(width 0.0889)
		(layer "In2.Cu")
		(net "M_I_CPU1_SB_DQ<8>")
	)
	(arc
		(start 143.386048 -279.273762)
		(mid 143.569556 -279.319256)
		(end 143.751808 -279.268936)
		(width 0.0889)
		(layer "In2.Cu")
		(net "M_I_CPU1_SB_DQ<8>")
	)
	(arc
		(start 129.714752 -279.237186)
		(mid 129.96996 -279.193709)
		(end 130.217672 -279.268936)
		(width 0.0889)
		(layer "In2.Cu")
		(net "M_I_CPU1_SB_DQ<8>")
	)
	(arc
		(start 133.037834 -279.268936)
		(mid 133.224778 -279.319191)
		(end 133.411722 -279.268936)
		(width 0.0889)
		(layer "In2.Cu")
		(net "M_I_CPU1_SB_DQ<8>")
	)
	(arc
		(start 131.531868 -279.268936)
		(mid 131.814824 -279.192759)
		(end 132.09778 -279.268936)
		(width 0.0889)
		(layer "In2.Cu")
		(net "M_I_CPU1_SB_DQ<8>")
	)
	(arc
		(start 134.92607 -279.273762)
		(mid 135.109578 -279.319256)
		(end 135.29183 -279.268936)
		(width 0.0889)
		(layer "In2.Cu")
		(net "M_I_CPU1_SB_DQ<8>")
	)
	(arc
		(start 144.692116 -279.268936)
		(mid 144.965971 -279.192586)
		(end 145.24228 -279.259538)
		(width 0.0889)
		(layer "In2.Cu")
		(net "M_I_CPU1_SB_DQ<8>")
	)
	(arc
		(start 141.497812 -279.268936)
		(mid 141.684756 -279.319191)
		(end 141.8717 -279.268936)
		(width 0.0889)
		(layer "In2.Cu")
		(net "M_I_CPU1_SB_DQ<8>")
	)
	(arc
		(start 141.8717 -279.268936)
		(mid 142.154656 -279.192759)
		(end 142.437612 -279.268936)
		(width 0.0889)
		(layer "In2.Cu")
		(net "M_I_CPU1_SB_DQ<8>")
	)
	(arc
		(start 142.437612 -279.268936)
		(mid 142.619863 -279.319286)
		(end 142.803372 -279.273762)
		(width 0.0889)
		(layer "In2.Cu")
		(net "M_I_CPU1_SB_DQ<8>")
	)
	(arc
		(start 132.106162 -279.273762)
		(mid 132.28967 -279.319256)
		(end 132.471922 -279.268936)
		(width 0.0889)
		(layer "In2.Cu")
		(net "M_I_CPU1_SB_DQ<8>")
	)
	(arc
		(start 143.751808 -279.268936)
		(mid 144.034764 -279.192759)
		(end 144.31772 -279.268936)
		(width 0.0889)
		(layer "In2.Cu")
		(net "M_I_CPU1_SB_DQ<8>")
	)
	(arc
		(start 142.811754 -279.268936)
		(mid 143.09471 -279.192759)
		(end 143.377666 -279.268936)
		(width 0.0889)
		(layer "In2.Cu")
		(net "M_I_CPU1_SB_DQ<8>")
	)
	(arc
		(start 140.9319 -279.268936)
		(mid 141.214856 -279.192759)
		(end 141.497812 -279.268936)
		(width 0.0889)
		(layer "In2.Cu")
		(net "M_I_CPU1_SB_DQ<8>")
	)
	(arc
		(start 140.56614 -279.273762)
		(mid 140.749648 -279.319256)
		(end 140.9319 -279.268936)
		(width 0.0889)
		(layer "In2.Cu")
		(net "M_I_CPU1_SB_DQ<8>")
	)
	(arc
		(start 135.29183 -279.268936)
		(mid 135.574786 -279.192759)
		(end 135.857742 -279.268936)
		(width 0.0889)
		(layer "In2.Cu")
		(net "M_I_CPU1_SB_DQ<8>")
	)
	(arc
		(start 139.991846 -279.268936)
		(mid 140.274802 -279.192759)
		(end 140.557758 -279.268936)
		(width 0.0889)
		(layer "In2.Cu")
		(net "M_I_CPU1_SB_DQ<8>")
	)
	(arc
		(start 133.977634 -279.268936)
		(mid 134.159885 -279.319286)
		(end 134.343394 -279.273762)
		(width 0.0889)
		(layer "In2.Cu")
		(net "M_I_CPU1_SB_DQ<8>")
	)
	(arc
		(start 145.276316 -279.279096)
		(mid 145.354205 -279.308133)
		(end 145.43659 -279.319228)
		(width 0.0889)
		(layer "In2.Cu")
		(net "M_I_CPU1_SB_DQ<8>")
	)
	(arc
		(start 132.471922 -279.268936)
		(mid 132.754878 -279.192759)
		(end 133.037834 -279.268936)
		(width 0.0889)
		(layer "In2.Cu")
		(net "M_I_CPU1_SB_DQ<8>")
	)
	(arc
		(start 131.166108 -279.273762)
		(mid 131.349616 -279.319256)
		(end 131.531868 -279.268936)
		(width 0.0889)
		(layer "In2.Cu")
		(net "M_I_CPU1_SB_DQ<8>")
	)
	(arc
		(start 135.866124 -279.273762)
		(mid 136.049632 -279.319256)
		(end 136.231884 -279.268936)
		(width 0.0889)
		(layer "In2.Cu")
		(net "M_I_CPU1_SB_DQ<8>")
	)
	(arc
		(start 130.217672 -279.268936)
		(mid 130.399923 -279.319286)
		(end 130.583432 -279.273762)
		(width 0.0889)
		(layer "In2.Cu")
		(net "M_I_CPU1_SB_DQ<8>")
	)
	(segment
		(start 128.05791 -278.680418)
		(end 128.524762 -278.946356)
		(width 0.10668)
		(layer "F.Cu")
		(net "M_I_CPU1_SB_DQ<7>")
	)
	(segment
		(start 162.996372 -290.114228)
		(end 163.712906 -290.410646)
		(width 0.14478)
		(layer "In2.Cu")
		(net "M_I_CPU1_SB_DQ<7>")
	)
	(segment
		(start 166.594536 -290.038282)
		(end 166.845996 -289.975036)
		(width 0.14478)
		(layer "In2.Cu")
		(net "M_I_CPU1_SB_DQ<7>")
	)
	(segment
		(start 177.199798 -289.19297)
		(end 177.412142 -289.19297)
		(width 0.14478)
		(layer "In2.Cu")
		(net "M_I_CPU1_SB_DQ<7>")
	)
	(segment
		(start 130.583432 -278.61895)
		(end 130.591814 -278.623776)
		(width 0.0889)
		(layer "In2.Cu")
		(net "M_I_CPU1_SB_DQ<7>")
	)
	(segment
		(start 179.091082 -289.560508)
		(end 179.516024 -289.98545)
		(width 0.14478)
		(layer "In2.Cu")
		(net "M_I_CPU1_SB_DQ<7>")
	)
	(segment
		(start 145.673826 -278.580342)
		(end 146.076162 -278.580342)
		(width 0.0889)
		(layer "In2.Cu")
		(net "M_I_CPU1_SB_DQ<7>")
	)
	(segment
		(start 129.643378 -278.61895)
		(end 129.65176 -278.623776)
		(width 0.0889)
		(layer "In2.Cu")
		(net "M_I_CPU1_SB_DQ<7>")
	)
	(segment
		(start 173.165516 -290.33724)
		(end 173.386496 -289.801046)
		(width 0.14478)
		(layer "In2.Cu")
		(net "M_I_CPU1_SB_DQ<7>")
	)
	(segment
		(start 178.941222 -289.175444)
		(end 179.091082 -289.325304)
		(width 0.14478)
		(layer "In2.Cu")
		(net "M_I_CPU1_SB_DQ<7>")
	)
	(segment
		(start 171.192444 -290.410646)
		(end 172.988224 -290.410646)
		(width 0.14478)
		(layer "In2.Cu")
		(net "M_I_CPU1_SB_DQ<7>")
	)
	(segment
		(start 178.270662 -289.175444)
		(end 178.941222 -289.175444)
		(width 0.14478)
		(layer "In2.Cu")
		(net "M_I_CPU1_SB_DQ<7>")
	)
	(segment
		(start 134.917688 -278.623776)
		(end 134.92607 -278.61895)
		(width 0.0889)
		(layer "In2.Cu")
		(net "M_I_CPU1_SB_DQ<7>")
	)
	(segment
		(start 138.103356 -278.61895)
		(end 138.111738 -278.623776)
		(width 0.0889)
		(layer "In2.Cu")
		(net "M_I_CPU1_SB_DQ<7>")
	)
	(segment
		(start 178.120802 -289.698684)
		(end 178.120802 -289.325304)
		(width 0.14478)
		(layer "In2.Cu")
		(net "M_I_CPU1_SB_DQ<7>")
	)
	(segment
		(start 170.284648 -290.034726)
		(end 171.192444 -290.410646)
		(width 0.14478)
		(layer "In2.Cu")
		(net "M_I_CPU1_SB_DQ<7>")
	)
	(segment
		(start 169.655998 -289.54984)
		(end 169.730674 -289.369754)
		(width 0.14478)
		(layer "In2.Cu")
		(net "M_I_CPU1_SB_DQ<7>")
	)
	(segment
		(start 174.018194 -289.8648)
		(end 174.752254 -289.560508)
		(width 0.14478)
		(layer "In2.Cu")
		(net "M_I_CPU1_SB_DQ<7>")
	)
	(segment
		(start 167.266112 -289.352228)
		(end 167.447722 -289.461194)
		(width 0.14478)
		(layer "In2.Cu")
		(net "M_I_CPU1_SB_DQ<7>")
	)
	(segment
		(start 165.87089 -290.065206)
		(end 165.821614 -289.868864)
		(width 0.14478)
		(layer "In2.Cu")
		(net "M_I_CPU1_SB_DQ<7>")
	)
	(segment
		(start 177.562002 -289.34283)
		(end 177.562002 -289.698684)
		(width 0.14478)
		(layer "In2.Cu")
		(net "M_I_CPU1_SB_DQ<7>")
	)
	(segment
		(start 147.22856 -278.236172)
		(end 147.409662 -278.05507)
		(width 0.0889)
		(layer "In2.Cu")
		(net "M_I_CPU1_SB_DQ<7>")
	)
	(segment
		(start 146.076162 -278.580342)
		(end 146.420332 -278.236172)
		(width 0.0889)
		(layer "In2.Cu")
		(net "M_I_CPU1_SB_DQ<7>")
	)
	(segment
		(start 139.617704 -278.623776)
		(end 139.626086 -278.61895)
		(width 0.0889)
		(layer "In2.Cu")
		(net "M_I_CPU1_SB_DQ<7>")
	)
	(segment
		(start 177.970942 -289.848544)
		(end 178.120802 -289.698684)
		(width 0.14478)
		(layer "In2.Cu")
		(net "M_I_CPU1_SB_DQ<7>")
	)
	(segment
		(start 163.712906 -290.410646)
		(end 165.269164 -290.410646)
		(width 0.14478)
		(layer "In2.Cu")
		(net "M_I_CPU1_SB_DQ<7>")
	)
	(segment
		(start 128.370838 -278.680926)
		(end 128.39319 -278.597614)
		(width 0.0889)
		(layer "In2.Cu")
		(net "M_I_CPU1_SB_DQ<7>")
	)
	(segment
		(start 177.412142 -289.19297)
		(end 177.562002 -289.34283)
		(width 0.14478)
		(layer "In2.Cu")
		(net "M_I_CPU1_SB_DQ<7>")
	)
	(segment
		(start 166.36365 -289.732974)
		(end 166.412926 -289.929316)
		(width 0.14478)
		(layer "In2.Cu")
		(net "M_I_CPU1_SB_DQ<7>")
	)
	(segment
		(start 144.688306 -278.623776)
		(end 144.71777 -278.641048)
		(width 0.0889)
		(layer "In2.Cu")
		(net "M_I_CPU1_SB_DQ<7>")
	)
	(segment
		(start 176.83226 -289.560508)
		(end 177.199798 -289.19297)
		(width 0.14478)
		(layer "In2.Cu")
		(net "M_I_CPU1_SB_DQ<7>")
	)
	(segment
		(start 177.711862 -289.848544)
		(end 177.970942 -289.848544)
		(width 0.14478)
		(layer "In2.Cu")
		(net "M_I_CPU1_SB_DQ<7>")
	)
	(segment
		(start 170.17238 -289.763962)
		(end 170.284648 -290.034726)
		(width 0.14478)
		(layer "In2.Cu")
		(net "M_I_CPU1_SB_DQ<7>")
	)
	(segment
		(start 177.562002 -289.698684)
		(end 177.711862 -289.848544)
		(width 0.14478)
		(layer "In2.Cu")
		(net "M_I_CPU1_SB_DQ<7>")
	)
	(segment
		(start 169.460418 -289.63112)
		(end 169.655998 -289.54984)
		(width 0.14478)
		(layer "In2.Cu")
		(net "M_I_CPU1_SB_DQ<7>")
	)
	(segment
		(start 165.733476 -290.29406)
		(end 165.87089 -290.065206)
		(width 0.14478)
		(layer "In2.Cu")
		(net "M_I_CPU1_SB_DQ<7>")
	)
	(segment
		(start 167.496998 -289.657536)
		(end 167.678608 -289.766502)
		(width 0.14478)
		(layer "In2.Cu")
		(net "M_I_CPU1_SB_DQ<7>")
	)
	(segment
		(start 173.626272 -289.701478)
		(end 174.018194 -289.8648)
		(width 0.14478)
		(layer "In2.Cu")
		(net "M_I_CPU1_SB_DQ<7>")
	)
	(segment
		(start 167.447722 -289.461194)
		(end 167.496998 -289.657536)
		(width 0.14478)
		(layer "In2.Cu")
		(net "M_I_CPU1_SB_DQ<7>")
	)
	(segment
		(start 173.386496 -289.801046)
		(end 173.626272 -289.701478)
		(width 0.14478)
		(layer "In2.Cu")
		(net "M_I_CPU1_SB_DQ<7>")
	)
	(segment
		(start 166.412926 -289.929316)
		(end 166.594536 -290.038282)
		(width 0.14478)
		(layer "In2.Cu")
		(net "M_I_CPU1_SB_DQ<7>")
	)
	(segment
		(start 131.157726 -278.623776)
		(end 131.166108 -278.61895)
		(width 0.0889)
		(layer "In2.Cu")
		(net "M_I_CPU1_SB_DQ<7>")
	)
	(segment
		(start 169.957242 -289.275774)
		(end 170.15333 -289.357054)
		(width 0.14478)
		(layer "In2.Cu")
		(net "M_I_CPU1_SB_DQ<7>")
	)
	(segment
		(start 165.93058 -289.687254)
		(end 166.18204 -289.624008)
		(width 0.14478)
		(layer "In2.Cu")
		(net "M_I_CPU1_SB_DQ<7>")
	)
	(segment
		(start 166.18204 -289.624008)
		(end 166.36365 -289.732974)
		(width 0.14478)
		(layer "In2.Cu")
		(net "M_I_CPU1_SB_DQ<7>")
	)
	(segment
		(start 167.014652 -289.415474)
		(end 167.266112 -289.352228)
		(width 0.14478)
		(layer "In2.Cu")
		(net "M_I_CPU1_SB_DQ<7>")
	)
	(segment
		(start 142.803372 -278.61895)
		(end 142.811754 -278.623776)
		(width 0.0889)
		(layer "In2.Cu")
		(net "M_I_CPU1_SB_DQ<7>")
	)
	(segment
		(start 167.678608 -289.766502)
		(end 168.500806 -289.560508)
		(width 0.14478)
		(layer "In2.Cu")
		(net "M_I_CPU1_SB_DQ<7>")
	)
	(segment
		(start 166.954962 -289.793426)
		(end 166.905686 -289.597084)
		(width 0.14478)
		(layer "In2.Cu")
		(net "M_I_CPU1_SB_DQ<7>")
	)
	(segment
		(start 174.752254 -289.560508)
		(end 176.83226 -289.560508)
		(width 0.14478)
		(layer "In2.Cu")
		(net "M_I_CPU1_SB_DQ<7>")
	)
	(segment
		(start 165.269164 -290.410646)
		(end 165.733476 -290.29406)
		(width 0.14478)
		(layer "In2.Cu")
		(net "M_I_CPU1_SB_DQ<7>")
	)
	(segment
		(start 146.420332 -278.236172)
		(end 147.22856 -278.236172)
		(width 0.0889)
		(layer "In2.Cu")
		(net "M_I_CPU1_SB_DQ<7>")
	)
	(segment
		(start 150.937214 -278.05507)
		(end 162.996372 -290.114228)
		(width 0.14478)
		(layer "In2.Cu")
		(net "M_I_CPU1_SB_DQ<7>")
	)
	(segment
		(start 128.524762 -278.946356)
		(end 128.370838 -278.680926)
		(width 0.0889)
		(layer "In2.Cu")
		(net "M_I_CPU1_SB_DQ<7>")
	)
	(segment
		(start 145.673064 -278.57958)
		(end 145.673826 -278.580342)
		(width 0.0889)
		(layer "In2.Cu")
		(net "M_I_CPU1_SB_DQ<7>")
	)
	(segment
		(start 144.315688 -278.62403)
		(end 144.337532 -278.611584)
		(width 0.0889)
		(layer "In2.Cu")
		(net "M_I_CPU1_SB_DQ<7>")
	)
	(segment
		(start 166.845996 -289.975036)
		(end 166.954962 -289.793426)
		(width 0.14478)
		(layer "In2.Cu")
		(net "M_I_CPU1_SB_DQ<7>")
	)
	(segment
		(start 140.557758 -278.623776)
		(end 140.56614 -278.61895)
		(width 0.0889)
		(layer "In2.Cu")
		(net "M_I_CPU1_SB_DQ<7>")
	)
	(segment
		(start 179.091082 -289.325304)
		(end 179.091082 -289.560508)
		(width 0.14478)
		(layer "In2.Cu")
		(net "M_I_CPU1_SB_DQ<7>")
	)
	(segment
		(start 168.500806 -289.560508)
		(end 169.290492 -289.560508)
		(width 0.14478)
		(layer "In2.Cu")
		(net "M_I_CPU1_SB_DQ<7>")
	)
	(segment
		(start 178.120802 -289.325304)
		(end 178.270662 -289.175444)
		(width 0.14478)
		(layer "In2.Cu")
		(net "M_I_CPU1_SB_DQ<7>")
	)
	(segment
		(start 139.04341 -278.61895)
		(end 139.051792 -278.623776)
		(width 0.0889)
		(layer "In2.Cu")
		(net "M_I_CPU1_SB_DQ<7>")
	)
	(segment
		(start 143.377666 -278.623776)
		(end 143.386048 -278.61895)
		(width 0.0889)
		(layer "In2.Cu")
		(net "M_I_CPU1_SB_DQ<7>")
	)
	(segment
		(start 172.988224 -290.410646)
		(end 173.165516 -290.33724)
		(width 0.14478)
		(layer "In2.Cu")
		(net "M_I_CPU1_SB_DQ<7>")
	)
	(segment
		(start 169.730674 -289.369754)
		(end 169.957242 -289.275774)
		(width 0.14478)
		(layer "In2.Cu")
		(net "M_I_CPU1_SB_DQ<7>")
	)
	(segment
		(start 165.821614 -289.868864)
		(end 165.93058 -289.687254)
		(width 0.14478)
		(layer "In2.Cu")
		(net "M_I_CPU1_SB_DQ<7>")
	)
	(segment
		(start 166.905686 -289.597084)
		(end 167.014652 -289.415474)
		(width 0.14478)
		(layer "In2.Cu")
		(net "M_I_CPU1_SB_DQ<7>")
	)
	(segment
		(start 135.857742 -278.623776)
		(end 135.866124 -278.61895)
		(width 0.0889)
		(layer "In2.Cu")
		(net "M_I_CPU1_SB_DQ<7>")
	)
	(segment
		(start 170.24731 -289.583622)
		(end 170.17238 -289.763962)
		(width 0.14478)
		(layer "In2.Cu")
		(net "M_I_CPU1_SB_DQ<7>")
	)
	(segment
		(start 144.289526 -278.639016)
		(end 144.315688 -278.62403)
		(width 0.0889)
		(layer "In2.Cu")
		(net "M_I_CPU1_SB_DQ<7>")
	)
	(segment
		(start 145.373852 -278.57958)
		(end 145.673064 -278.57958)
		(width 0.0889)
		(layer "In2.Cu")
		(net "M_I_CPU1_SB_DQ<7>")
	)
	(segment
		(start 134.343394 -278.61895)
		(end 134.351776 -278.623776)
		(width 0.0889)
		(layer "In2.Cu")
		(net "M_I_CPU1_SB_DQ<7>")
	)
	(segment
		(start 169.290492 -289.560508)
		(end 169.460418 -289.63112)
		(width 0.14478)
		(layer "In2.Cu")
		(net "M_I_CPU1_SB_DQ<7>")
	)
	(segment
		(start 148.019262 -278.05507)
		(end 150.937214 -278.05507)
		(width 0.14478)
		(layer "In2.Cu")
		(net "M_I_CPU1_SB_DQ<7>")
	)
	(segment
		(start 132.09778 -278.623776)
		(end 132.106162 -278.61895)
		(width 0.0889)
		(layer "In2.Cu")
		(net "M_I_CPU1_SB_DQ<7>")
	)
	(segment
		(start 147.409662 -278.05507)
		(end 148.019262 -278.05507)
		(width 0.0889)
		(layer "In2.Cu")
		(net "M_I_CPU1_SB_DQ<7>")
	)
	(segment
		(start 170.15333 -289.357054)
		(end 170.24731 -289.583622)
		(width 0.14478)
		(layer "In2.Cu")
		(net "M_I_CPU1_SB_DQ<7>")
	)
	(arc
		(start 129.65176 -278.623776)
		(mid 129.934716 -278.699953)
		(end 130.217672 -278.623776)
		(width 0.0889)
		(layer "In2.Cu")
		(net "M_I_CPU1_SB_DQ<7>")
	)
	(arc
		(start 143.751808 -278.623776)
		(mid 144.018738 -278.699725)
		(end 144.289526 -278.639016)
		(width 0.0889)
		(layer "In2.Cu")
		(net "M_I_CPU1_SB_DQ<7>")
	)
	(arc
		(start 133.037834 -278.623776)
		(mid 133.224778 -278.573521)
		(end 133.411722 -278.623776)
		(width 0.0889)
		(layer "In2.Cu")
		(net "M_I_CPU1_SB_DQ<7>")
	)
	(arc
		(start 140.9319 -278.623776)
		(mid 141.214856 -278.699953)
		(end 141.497812 -278.623776)
		(width 0.0889)
		(layer "In2.Cu")
		(net "M_I_CPU1_SB_DQ<7>")
	)
	(arc
		(start 129.277618 -278.623776)
		(mid 129.459869 -278.573426)
		(end 129.643378 -278.61895)
		(width 0.0889)
		(layer "In2.Cu")
		(net "M_I_CPU1_SB_DQ<7>")
	)
	(arc
		(start 128.711706 -278.623776)
		(mid 128.994662 -278.699953)
		(end 129.277618 -278.623776)
		(width 0.0889)
		(layer "In2.Cu")
		(net "M_I_CPU1_SB_DQ<7>")
	)
	(arc
		(start 137.737596 -278.623776)
		(mid 137.919847 -278.573426)
		(end 138.103356 -278.61895)
		(width 0.0889)
		(layer "In2.Cu")
		(net "M_I_CPU1_SB_DQ<7>")
	)
	(arc
		(start 143.386048 -278.61895)
		(mid 143.569556 -278.573456)
		(end 143.751808 -278.623776)
		(width 0.0889)
		(layer "In2.Cu")
		(net "M_I_CPU1_SB_DQ<7>")
	)
	(arc
		(start 131.166108 -278.61895)
		(mid 131.349616 -278.573456)
		(end 131.531868 -278.623776)
		(width 0.0889)
		(layer "In2.Cu")
		(net "M_I_CPU1_SB_DQ<7>")
	)
	(arc
		(start 128.39319 -278.597614)
		(mid 128.555379 -278.574879)
		(end 128.711706 -278.623776)
		(width 0.0889)
		(layer "In2.Cu")
		(net "M_I_CPU1_SB_DQ<7>")
	)
	(arc
		(start 144.337532 -278.611584)
		(mid 144.51446 -278.573756)
		(end 144.688306 -278.623776)
		(width 0.0889)
		(layer "In2.Cu")
		(net "M_I_CPU1_SB_DQ<7>")
	)
	(arc
		(start 135.29183 -278.623776)
		(mid 135.574786 -278.699953)
		(end 135.857742 -278.623776)
		(width 0.0889)
		(layer "In2.Cu")
		(net "M_I_CPU1_SB_DQ<7>")
	)
	(arc
		(start 139.626086 -278.61895)
		(mid 139.809594 -278.573456)
		(end 139.991846 -278.623776)
		(width 0.0889)
		(layer "In2.Cu")
		(net "M_I_CPU1_SB_DQ<7>")
	)
	(arc
		(start 139.051792 -278.623776)
		(mid 139.334748 -278.699953)
		(end 139.617704 -278.623776)
		(width 0.0889)
		(layer "In2.Cu")
		(net "M_I_CPU1_SB_DQ<7>")
	)
	(arc
		(start 138.111738 -278.623776)
		(mid 138.394694 -278.699953)
		(end 138.67765 -278.623776)
		(width 0.0889)
		(layer "In2.Cu")
		(net "M_I_CPU1_SB_DQ<7>")
	)
	(arc
		(start 130.591814 -278.623776)
		(mid 130.87477 -278.699953)
		(end 131.157726 -278.623776)
		(width 0.0889)
		(layer "In2.Cu")
		(net "M_I_CPU1_SB_DQ<7>")
	)
	(arc
		(start 135.866124 -278.61895)
		(mid 136.049632 -278.573456)
		(end 136.231884 -278.623776)
		(width 0.0889)
		(layer "In2.Cu")
		(net "M_I_CPU1_SB_DQ<7>")
	)
	(arc
		(start 136.231884 -278.623776)
		(mid 136.51484 -278.699953)
		(end 136.797796 -278.623776)
		(width 0.0889)
		(layer "In2.Cu")
		(net "M_I_CPU1_SB_DQ<7>")
	)
	(arc
		(start 141.8717 -278.623776)
		(mid 142.154656 -278.699953)
		(end 142.437612 -278.623776)
		(width 0.0889)
		(layer "In2.Cu")
		(net "M_I_CPU1_SB_DQ<7>")
	)
	(arc
		(start 133.411722 -278.623776)
		(mid 133.694678 -278.699953)
		(end 133.977634 -278.623776)
		(width 0.0889)
		(layer "In2.Cu")
		(net "M_I_CPU1_SB_DQ<7>")
	)
	(arc
		(start 136.797796 -278.623776)
		(mid 136.98474 -278.573521)
		(end 137.171684 -278.623776)
		(width 0.0889)
		(layer "In2.Cu")
		(net "M_I_CPU1_SB_DQ<7>")
	)
	(arc
		(start 144.71777 -278.641048)
		(mid 144.98919 -278.700725)
		(end 145.25625 -278.623776)
		(width 0.0889)
		(layer "In2.Cu")
		(net "M_I_CPU1_SB_DQ<7>")
	)
	(arc
		(start 141.497812 -278.623776)
		(mid 141.684756 -278.573521)
		(end 141.8717 -278.623776)
		(width 0.0889)
		(layer "In2.Cu")
		(net "M_I_CPU1_SB_DQ<7>")
	)
	(arc
		(start 132.471922 -278.623776)
		(mid 132.754878 -278.699953)
		(end 133.037834 -278.623776)
		(width 0.0889)
		(layer "In2.Cu")
		(net "M_I_CPU1_SB_DQ<7>")
	)
	(arc
		(start 140.56614 -278.61895)
		(mid 140.749648 -278.573456)
		(end 140.9319 -278.623776)
		(width 0.0889)
		(layer "In2.Cu")
		(net "M_I_CPU1_SB_DQ<7>")
	)
	(arc
		(start 139.991846 -278.623776)
		(mid 140.274802 -278.699953)
		(end 140.557758 -278.623776)
		(width 0.0889)
		(layer "In2.Cu")
		(net "M_I_CPU1_SB_DQ<7>")
	)
	(arc
		(start 142.437612 -278.623776)
		(mid 142.619863 -278.573426)
		(end 142.803372 -278.61895)
		(width 0.0889)
		(layer "In2.Cu")
		(net "M_I_CPU1_SB_DQ<7>")
	)
	(arc
		(start 138.67765 -278.623776)
		(mid 138.859901 -278.573426)
		(end 139.04341 -278.61895)
		(width 0.0889)
		(layer "In2.Cu")
		(net "M_I_CPU1_SB_DQ<7>")
	)
	(arc
		(start 145.25625 -278.623776)
		(mid 145.313174 -278.596679)
		(end 145.373852 -278.57958)
		(width 0.0889)
		(layer "In2.Cu")
		(net "M_I_CPU1_SB_DQ<7>")
	)
	(arc
		(start 131.531868 -278.623776)
		(mid 131.814824 -278.699953)
		(end 132.09778 -278.623776)
		(width 0.0889)
		(layer "In2.Cu")
		(net "M_I_CPU1_SB_DQ<7>")
	)
	(arc
		(start 134.351776 -278.623776)
		(mid 134.634732 -278.699953)
		(end 134.917688 -278.623776)
		(width 0.0889)
		(layer "In2.Cu")
		(net "M_I_CPU1_SB_DQ<7>")
	)
	(arc
		(start 132.106162 -278.61895)
		(mid 132.28967 -278.573456)
		(end 132.471922 -278.623776)
		(width 0.0889)
		(layer "In2.Cu")
		(net "M_I_CPU1_SB_DQ<7>")
	)
	(arc
		(start 134.92607 -278.61895)
		(mid 135.109578 -278.573456)
		(end 135.29183 -278.623776)
		(width 0.0889)
		(layer "In2.Cu")
		(net "M_I_CPU1_SB_DQ<7>")
	)
	(arc
		(start 142.811754 -278.623776)
		(mid 143.09471 -278.699953)
		(end 143.377666 -278.623776)
		(width 0.0889)
		(layer "In2.Cu")
		(net "M_I_CPU1_SB_DQ<7>")
	)
	(arc
		(start 133.977634 -278.623776)
		(mid 134.159885 -278.573426)
		(end 134.343394 -278.61895)
		(width 0.0889)
		(layer "In2.Cu")
		(net "M_I_CPU1_SB_DQ<7>")
	)
	(arc
		(start 130.217672 -278.623776)
		(mid 130.399923 -278.573426)
		(end 130.583432 -278.61895)
		(width 0.0889)
		(layer "In2.Cu")
		(net "M_I_CPU1_SB_DQ<7>")
	)
	(arc
		(start 137.171684 -278.623776)
		(mid 137.45464 -278.699953)
		(end 137.737596 -278.623776)
		(width 0.0889)
		(layer "In2.Cu")
		(net "M_I_CPU1_SB_DQ<7>")
	)
	(segment
		(start 129.467864 -277.870412)
		(end 129.934716 -278.13635)
		(width 0.10668)
		(layer "F.Cu")
		(net "M_I_CPU1_SB_DQ<6>")
	)
	(segment
		(start 157.002226 -282.619704)
		(end 157.002226 -282.847796)
		(width 0.14478)
		(layer "In2.Cu")
		(net "M_I_CPU1_SB_DQ<6>")
	)
	(segment
		(start 141.967712 -277.81377)
		(end 141.976094 -277.808944)
		(width 0.0889)
		(layer "In2.Cu")
		(net "M_I_CPU1_SB_DQ<6>")
	)
	(segment
		(start 157.164278 -283.009848)
		(end 157.392624 -283.009848)
		(width 0.14478)
		(layer "In2.Cu")
		(net "M_I_CPU1_SB_DQ<6>")
	)
	(segment
		(start 166.538656 -288.55289)
		(end 166.730172 -288.090356)
		(width 0.14478)
		(layer "In2.Cu")
		(net "M_I_CPU1_SB_DQ<6>")
	)
	(segment
		(start 160.916874 -286.280098)
		(end 160.916874 -286.50819)
		(width 0.14478)
		(layer "In2.Cu")
		(net "M_I_CPU1_SB_DQ<6>")
	)
	(segment
		(start 133.507734 -277.81377)
		(end 133.516116 -277.808944)
		(width 0.0889)
		(layer "In2.Cu")
		(net "M_I_CPU1_SB_DQ<6>")
	)
	(segment
		(start 157.782514 -283.628084)
		(end 157.944566 -283.790136)
		(width 0.14478)
		(layer "In2.Cu")
		(net "M_I_CPU1_SB_DQ<6>")
	)
	(segment
		(start 165.829488 -288.468562)
		(end 166.285672 -288.658046)
		(width 0.14478)
		(layer "In2.Cu")
		(net "M_I_CPU1_SB_DQ<6>")
	)
	(segment
		(start 156.625036 -282.21686)
		(end 156.853636 -282.21686)
		(width 0.14478)
		(layer "In2.Cu")
		(net "M_I_CPU1_SB_DQ<6>")
	)
	(segment
		(start 162.464242 -288.309812)
		(end 162.832034 -288.677604)
		(width 0.14478)
		(layer "In2.Cu")
		(net "M_I_CPU1_SB_DQ<6>")
	)
	(segment
		(start 141.393418 -277.808944)
		(end 141.4018 -277.81377)
		(width 0.0889)
		(layer "In2.Cu")
		(net "M_I_CPU1_SB_DQ<6>")
	)
	(segment
		(start 135.753348 -277.808944)
		(end 135.76173 -277.81377)
		(width 0.0889)
		(layer "In2.Cu")
		(net "M_I_CPU1_SB_DQ<6>")
	)
	(segment
		(start 173.518068 -288.39287)
		(end 174.001684 -288.59353)
		(width 0.14478)
		(layer "In2.Cu")
		(net "M_I_CPU1_SB_DQ<6>")
	)
	(segment
		(start 169.522902 -288.000948)
		(end 171.234354 -288.710624)
		(width 0.14478)
		(layer "In2.Cu")
		(net "M_I_CPU1_SB_DQ<6>")
	)
	(segment
		(start 159.746188 -285.338012)
		(end 159.974788 -285.338012)
		(width 0.14478)
		(layer "In2.Cu")
		(net "M_I_CPU1_SB_DQ<6>")
	)
	(segment
		(start 131.993386 -277.808944)
		(end 132.001768 -277.81377)
		(width 0.0889)
		(layer "In2.Cu")
		(net "M_I_CPU1_SB_DQ<6>")
	)
	(segment
		(start 160.903666 -286.521144)
		(end 160.903666 -286.749236)
		(width 0.14478)
		(layer "In2.Cu")
		(net "M_I_CPU1_SB_DQ<6>")
	)
	(segment
		(start 159.974788 -285.338012)
		(end 160.136586 -285.49981)
		(width 0.14478)
		(layer "In2.Cu")
		(net "M_I_CPU1_SB_DQ<6>")
	)
	(segment
		(start 176.6316 -288.253932)
		(end 176.911762 -288.253932)
		(width 0.14478)
		(layer "In2.Cu")
		(net "M_I_CPU1_SB_DQ<6>")
	)
	(segment
		(start 174.001684 -288.59353)
		(end 174.257208 -288.487612)
		(width 0.14478)
		(layer "In2.Cu")
		(net "M_I_CPU1_SB_DQ<6>")
	)
	(segment
		(start 136.693402 -277.808944)
		(end 136.701784 -277.81377)
		(width 0.0889)
		(layer "In2.Cu")
		(net "M_I_CPU1_SB_DQ<6>")
	)
	(segment
		(start 172.751242 -288.710624)
		(end 173.518068 -288.39287)
		(width 0.14478)
		(layer "In2.Cu")
		(net "M_I_CPU1_SB_DQ<6>")
	)
	(segment
		(start 177.67046 -287.482026)
		(end 177.863246 -287.674812)
		(width 0.14478)
		(layer "In2.Cu")
		(net "M_I_CPU1_SB_DQ<6>")
	)
	(segment
		(start 158.172912 -283.790136)
		(end 158.185612 -283.777436)
		(width 0.14478)
		(layer "In2.Cu")
		(net "M_I_CPU1_SB_DQ<6>")
	)
	(segment
		(start 161.697162 -287.288478)
		(end 161.683954 -287.301432)
		(width 0.14478)
		(layer "In2.Cu")
		(net "M_I_CPU1_SB_DQ<6>")
	)
	(segment
		(start 160.903666 -286.749236)
		(end 161.065718 -286.911288)
		(width 0.14478)
		(layer "In2.Cu")
		(net "M_I_CPU1_SB_DQ<6>")
	)
	(segment
		(start 146.489928 -277.14575)
		(end 147.998434 -277.14575)
		(width 0.0889)
		(layer "In2.Cu")
		(net "M_I_CPU1_SB_DQ<6>")
	)
	(segment
		(start 177.863246 -288.045398)
		(end 178.056032 -288.238184)
		(width 0.14478)
		(layer "In2.Cu")
		(net "M_I_CPU1_SB_DQ<6>")
	)
	(segment
		(start 144.221708 -277.81377)
		(end 144.23644 -277.822406)
		(width 0.0889)
		(layer "In2.Cu")
		(net "M_I_CPU1_SB_DQ<6>")
	)
	(segment
		(start 161.535364 -286.898588)
		(end 161.697162 -287.060386)
		(width 0.14478)
		(layer "In2.Cu")
		(net "M_I_CPU1_SB_DQ<6>")
	)
	(segment
		(start 166.285672 -288.658046)
		(end 166.538656 -288.55289)
		(width 0.14478)
		(layer "In2.Cu")
		(net "M_I_CPU1_SB_DQ<6>")
	)
	(segment
		(start 159.733488 -285.350712)
		(end 159.746188 -285.338012)
		(width 0.14478)
		(layer "In2.Cu")
		(net "M_I_CPU1_SB_DQ<6>")
	)
	(segment
		(start 129.934716 -278.13635)
		(end 129.780792 -277.87092)
		(width 0.0889)
		(layer "In2.Cu")
		(net "M_I_CPU1_SB_DQ<6>")
	)
	(segment
		(start 161.697162 -287.060386)
		(end 161.697162 -287.288478)
		(width 0.14478)
		(layer "In2.Cu")
		(net "M_I_CPU1_SB_DQ<6>")
	)
	(segment
		(start 177.315114 -287.482026)
		(end 177.67046 -287.482026)
		(width 0.14478)
		(layer "In2.Cu")
		(net "M_I_CPU1_SB_DQ<6>")
	)
	(segment
		(start 161.065718 -286.911288)
		(end 161.294064 -286.911288)
		(width 0.14478)
		(layer "In2.Cu")
		(net "M_I_CPU1_SB_DQ<6>")
	)
	(segment
		(start 156.853636 -282.21686)
		(end 157.015434 -282.378658)
		(width 0.14478)
		(layer "In2.Cu")
		(net "M_I_CPU1_SB_DQ<6>")
	)
	(segment
		(start 162.464242 -288.08172)
		(end 162.464242 -288.309812)
		(width 0.14478)
		(layer "In2.Cu")
		(net "M_I_CPU1_SB_DQ<6>")
	)
	(segment
		(start 156.612336 -282.22956)
		(end 156.625036 -282.21686)
		(width 0.14478)
		(layer "In2.Cu")
		(net "M_I_CPU1_SB_DQ<6>")
	)
	(segment
		(start 137.267696 -277.81377)
		(end 137.276078 -277.808944)
		(width 0.0889)
		(layer "In2.Cu")
		(net "M_I_CPU1_SB_DQ<6>")
	)
	(segment
		(start 158.9659 -284.557724)
		(end 159.1945 -284.557724)
		(width 0.14478)
		(layer "In2.Cu")
		(net "M_I_CPU1_SB_DQ<6>")
	)
	(segment
		(start 176.911762 -288.253932)
		(end 177.136552 -288.029142)
		(width 0.14478)
		(layer "In2.Cu")
		(net "M_I_CPU1_SB_DQ<6>")
	)
	(segment
		(start 160.136586 -285.727902)
		(end 160.123378 -285.740856)
		(width 0.14478)
		(layer "In2.Cu")
		(net "M_I_CPU1_SB_DQ<6>")
	)
	(segment
		(start 157.944566 -283.790136)
		(end 158.172912 -283.790136)
		(width 0.14478)
		(layer "In2.Cu")
		(net "M_I_CPU1_SB_DQ<6>")
	)
	(segment
		(start 162.47745 -287.840674)
		(end 162.47745 -288.068766)
		(width 0.14478)
		(layer "In2.Cu")
		(net "M_I_CPU1_SB_DQ<6>")
	)
	(segment
		(start 158.562802 -284.408372)
		(end 158.724854 -284.570424)
		(width 0.14478)
		(layer "In2.Cu")
		(net "M_I_CPU1_SB_DQ<6>")
	)
	(segment
		(start 161.306764 -286.898588)
		(end 161.535364 -286.898588)
		(width 0.14478)
		(layer "In2.Cu")
		(net "M_I_CPU1_SB_DQ<6>")
	)
	(segment
		(start 161.683954 -287.301432)
		(end 161.683954 -287.529524)
		(width 0.14478)
		(layer "In2.Cu")
		(net "M_I_CPU1_SB_DQ<6>")
	)
	(segment
		(start 160.123378 -285.740856)
		(end 160.123378 -285.968948)
		(width 0.14478)
		(layer "In2.Cu")
		(net "M_I_CPU1_SB_DQ<6>")
	)
	(segment
		(start 156.38399 -282.22956)
		(end 156.612336 -282.22956)
		(width 0.14478)
		(layer "In2.Cu")
		(net "M_I_CPU1_SB_DQ<6>")
	)
	(segment
		(start 166.730172 -288.090356)
		(end 167.066976 -287.950656)
		(width 0.14478)
		(layer "In2.Cu")
		(net "M_I_CPU1_SB_DQ<6>")
	)
	(segment
		(start 167.843454 -288.228024)
		(end 168.210992 -287.860486)
		(width 0.14478)
		(layer "In2.Cu")
		(net "M_I_CPU1_SB_DQ<6>")
	)
	(segment
		(start 140.453364 -277.808944)
		(end 140.461746 -277.81377)
		(width 0.0889)
		(layer "In2.Cu")
		(net "M_I_CPU1_SB_DQ<6>")
	)
	(segment
		(start 145.44421 -277.890478)
		(end 145.450052 -277.89632)
		(width 0.0889)
		(layer "In2.Cu")
		(net "M_I_CPU1_SB_DQ<6>")
	)
	(segment
		(start 160.136586 -285.49981)
		(end 160.136586 -285.727902)
		(width 0.14478)
		(layer "In2.Cu")
		(net "M_I_CPU1_SB_DQ<6>")
	)
	(segment
		(start 132.93344 -277.808944)
		(end 132.941822 -277.81377)
		(width 0.0889)
		(layer "In2.Cu")
		(net "M_I_CPU1_SB_DQ<6>")
	)
	(segment
		(start 159.505142 -285.350712)
		(end 159.733488 -285.350712)
		(width 0.14478)
		(layer "In2.Cu")
		(net "M_I_CPU1_SB_DQ<6>")
	)
	(segment
		(start 162.47745 -288.068766)
		(end 162.464242 -288.08172)
		(width 0.14478)
		(layer "In2.Cu")
		(net "M_I_CPU1_SB_DQ<6>")
	)
	(segment
		(start 174.457106 -288.003488)
		(end 174.801784 -287.860486)
		(width 0.14478)
		(layer "In2.Cu")
		(net "M_I_CPU1_SB_DQ<6>")
	)
	(segment
		(start 165.245542 -288.710624)
		(end 165.829488 -288.468562)
		(width 0.14478)
		(layer "In2.Cu")
		(net "M_I_CPU1_SB_DQ<6>")
	)
	(segment
		(start 151.30018 -277.14575)
		(end 156.38399 -282.22956)
		(width 0.14478)
		(layer "In2.Cu")
		(net "M_I_CPU1_SB_DQ<6>")
	)
	(segment
		(start 167.066976 -287.950656)
		(end 167.366442 -288.010092)
		(width 0.14478)
		(layer "In2.Cu")
		(net "M_I_CPU1_SB_DQ<6>")
	)
	(segment
		(start 160.526476 -286.1183)
		(end 160.755076 -286.1183)
		(width 0.14478)
		(layer "In2.Cu")
		(net "M_I_CPU1_SB_DQ<6>")
	)
	(segment
		(start 160.916874 -286.50819)
		(end 160.903666 -286.521144)
		(width 0.14478)
		(layer "In2.Cu")
		(net "M_I_CPU1_SB_DQ<6>")
	)
	(segment
		(start 176.238154 -287.860486)
		(end 176.6316 -288.253932)
		(width 0.14478)
		(layer "In2.Cu")
		(net "M_I_CPU1_SB_DQ<6>")
	)
	(segment
		(start 147.998434 -277.14575)
		(end 151.30018 -277.14575)
		(width 0.14478)
		(layer "In2.Cu")
		(net "M_I_CPU1_SB_DQ<6>")
	)
	(segment
		(start 174.257208 -288.487612)
		(end 174.457106 -288.003488)
		(width 0.14478)
		(layer "In2.Cu")
		(net "M_I_CPU1_SB_DQ<6>")
	)
	(segment
		(start 159.34309 -285.18866)
		(end 159.505142 -285.350712)
		(width 0.14478)
		(layer "In2.Cu")
		(net "M_I_CPU1_SB_DQ<6>")
	)
	(segment
		(start 158.57601 -283.939234)
		(end 158.57601 -284.167326)
		(width 0.14478)
		(layer "In2.Cu")
		(net "M_I_CPU1_SB_DQ<6>")
	)
	(segment
		(start 159.356298 -284.947614)
		(end 159.34309 -284.960568)
		(width 0.14478)
		(layer "In2.Cu")
		(net "M_I_CPU1_SB_DQ<6>")
	)
	(segment
		(start 157.015434 -282.60675)
		(end 157.002226 -282.619704)
		(width 0.14478)
		(layer "In2.Cu")
		(net "M_I_CPU1_SB_DQ<6>")
	)
	(segment
		(start 178.521106 -288.045398)
		(end 178.521106 -287.672272)
		(width 0.14478)
		(layer "In2.Cu")
		(net "M_I_CPU1_SB_DQ<6>")
	)
	(segment
		(start 162.087052 -287.678876)
		(end 162.315652 -287.678876)
		(width 0.14478)
		(layer "In2.Cu")
		(net "M_I_CPU1_SB_DQ<6>")
	)
	(segment
		(start 158.562802 -284.18028)
		(end 158.562802 -284.408372)
		(width 0.14478)
		(layer "In2.Cu")
		(net "M_I_CPU1_SB_DQ<6>")
	)
	(segment
		(start 160.755076 -286.1183)
		(end 160.916874 -286.280098)
		(width 0.14478)
		(layer "In2.Cu")
		(net "M_I_CPU1_SB_DQ<6>")
	)
	(segment
		(start 162.91179 -288.710624)
		(end 165.245542 -288.710624)
		(width 0.14478)
		(layer "In2.Cu")
		(net "M_I_CPU1_SB_DQ<6>")
	)
	(segment
		(start 167.584374 -288.228024)
		(end 167.843454 -288.228024)
		(width 0.14478)
		(layer "In2.Cu")
		(net "M_I_CPU1_SB_DQ<6>")
	)
	(segment
		(start 162.315652 -287.678876)
		(end 162.47745 -287.840674)
		(width 0.14478)
		(layer "In2.Cu")
		(net "M_I_CPU1_SB_DQ<6>")
	)
	(segment
		(start 160.513776 -286.131)
		(end 160.526476 -286.1183)
		(width 0.14478)
		(layer "In2.Cu")
		(net "M_I_CPU1_SB_DQ<6>")
	)
	(segment
		(start 158.414212 -283.777436)
		(end 158.57601 -283.939234)
		(width 0.14478)
		(layer "In2.Cu")
		(net "M_I_CPU1_SB_DQ<6>")
	)
	(segment
		(start 157.633924 -282.997148)
		(end 157.795722 -283.158946)
		(width 0.14478)
		(layer "In2.Cu")
		(net "M_I_CPU1_SB_DQ<6>")
	)
	(segment
		(start 158.724854 -284.570424)
		(end 158.9532 -284.570424)
		(width 0.14478)
		(layer "In2.Cu")
		(net "M_I_CPU1_SB_DQ<6>")
	)
	(segment
		(start 145.450052 -277.89632)
		(end 145.739358 -277.89632)
		(width 0.0889)
		(layer "In2.Cu")
		(net "M_I_CPU1_SB_DQ<6>")
	)
	(segment
		(start 179.516024 -287.63087)
		(end 179.516024 -288.285428)
		(width 0.14478)
		(layer "In2.Cu")
		(net "M_I_CPU1_SB_DQ<6>")
	)
	(segment
		(start 160.123378 -285.968948)
		(end 160.28543 -286.131)
		(width 0.14478)
		(layer "In2.Cu")
		(net "M_I_CPU1_SB_DQ<6>")
	)
	(segment
		(start 161.294064 -286.911288)
		(end 161.306764 -286.898588)
		(width 0.14478)
		(layer "In2.Cu")
		(net "M_I_CPU1_SB_DQ<6>")
	)
	(segment
		(start 177.136552 -288.029142)
		(end 177.136552 -287.660588)
		(width 0.14478)
		(layer "In2.Cu")
		(net "M_I_CPU1_SB_DQ<6>")
	)
	(segment
		(start 158.57601 -284.167326)
		(end 158.562802 -284.18028)
		(width 0.14478)
		(layer "In2.Cu")
		(net "M_I_CPU1_SB_DQ<6>")
	)
	(segment
		(start 179.36464 -287.479486)
		(end 179.516024 -287.63087)
		(width 0.14478)
		(layer "In2.Cu")
		(net "M_I_CPU1_SB_DQ<6>")
	)
	(segment
		(start 158.185612 -283.777436)
		(end 158.414212 -283.777436)
		(width 0.14478)
		(layer "In2.Cu")
		(net "M_I_CPU1_SB_DQ<6>")
	)
	(segment
		(start 159.34309 -284.960568)
		(end 159.34309 -285.18866)
		(width 0.14478)
		(layer "In2.Cu")
		(net "M_I_CPU1_SB_DQ<6>")
	)
	(segment
		(start 174.801784 -287.860486)
		(end 176.238154 -287.860486)
		(width 0.14478)
		(layer "In2.Cu")
		(net "M_I_CPU1_SB_DQ<6>")
	)
	(segment
		(start 157.795722 -283.158946)
		(end 157.795722 -283.387038)
		(width 0.14478)
		(layer "In2.Cu")
		(net "M_I_CPU1_SB_DQ<6>")
	)
	(segment
		(start 178.056032 -288.238184)
		(end 178.32832 -288.238184)
		(width 0.14478)
		(layer "In2.Cu")
		(net "M_I_CPU1_SB_DQ<6>")
	)
	(segment
		(start 178.32832 -288.238184)
		(end 178.521106 -288.045398)
		(width 0.14478)
		(layer "In2.Cu")
		(net "M_I_CPU1_SB_DQ<6>")
	)
	(segment
		(start 159.1945 -284.557724)
		(end 159.356298 -284.719522)
		(width 0.14478)
		(layer "In2.Cu")
		(net "M_I_CPU1_SB_DQ<6>")
	)
	(segment
		(start 168.210992 -287.860486)
		(end 169.182542 -287.860486)
		(width 0.14478)
		(layer "In2.Cu")
		(net "M_I_CPU1_SB_DQ<6>")
	)
	(segment
		(start 178.521106 -287.672272)
		(end 178.713892 -287.479486)
		(width 0.14478)
		(layer "In2.Cu")
		(net "M_I_CPU1_SB_DQ<6>")
	)
	(segment
		(start 144.213326 -277.808944)
		(end 144.221708 -277.81377)
		(width 0.0889)
		(layer "In2.Cu")
		(net "M_I_CPU1_SB_DQ<6>")
	)
	(segment
		(start 162.832034 -288.677604)
		(end 162.91179 -288.710624)
		(width 0.14478)
		(layer "In2.Cu")
		(net "M_I_CPU1_SB_DQ<6>")
	)
	(segment
		(start 177.863246 -287.674812)
		(end 177.863246 -288.045398)
		(width 0.14478)
		(layer "In2.Cu")
		(net "M_I_CPU1_SB_DQ<6>")
	)
	(segment
		(start 161.683954 -287.529524)
		(end 161.846006 -287.691576)
		(width 0.14478)
		(layer "In2.Cu")
		(net "M_I_CPU1_SB_DQ<6>")
	)
	(segment
		(start 145.739358 -277.89632)
		(end 146.489928 -277.14575)
		(width 0.0889)
		(layer "In2.Cu")
		(net "M_I_CPU1_SB_DQ<6>")
	)
	(segment
		(start 161.846006 -287.691576)
		(end 162.074352 -287.691576)
		(width 0.14478)
		(layer "In2.Cu")
		(net "M_I_CPU1_SB_DQ<6>")
	)
	(segment
		(start 157.015434 -282.378658)
		(end 157.015434 -282.60675)
		(width 0.14478)
		(layer "In2.Cu")
		(net "M_I_CPU1_SB_DQ<6>")
	)
	(segment
		(start 159.356298 -284.719522)
		(end 159.356298 -284.947614)
		(width 0.14478)
		(layer "In2.Cu")
		(net "M_I_CPU1_SB_DQ<6>")
	)
	(segment
		(start 169.182542 -287.860486)
		(end 169.52214 -288.001202)
		(width 0.14478)
		(layer "In2.Cu")
		(net "M_I_CPU1_SB_DQ<6>")
	)
	(segment
		(start 178.713892 -287.479486)
		(end 179.36464 -287.479486)
		(width 0.14478)
		(layer "In2.Cu")
		(net "M_I_CPU1_SB_DQ<6>")
	)
	(segment
		(start 138.20775 -277.81377)
		(end 138.216132 -277.808944)
		(width 0.0889)
		(layer "In2.Cu")
		(net "M_I_CPU1_SB_DQ<6>")
	)
	(segment
		(start 169.52214 -288.001202)
		(end 169.522902 -288.000948)
		(width 0.14478)
		(layer "In2.Cu")
		(net "M_I_CPU1_SB_DQ<6>")
	)
	(segment
		(start 129.780792 -277.87092)
		(end 129.803144 -277.787608)
		(width 0.0889)
		(layer "In2.Cu")
		(net "M_I_CPU1_SB_DQ<6>")
	)
	(segment
		(start 157.405324 -282.997148)
		(end 157.633924 -282.997148)
		(width 0.14478)
		(layer "In2.Cu")
		(net "M_I_CPU1_SB_DQ<6>")
	)
	(segment
		(start 160.28543 -286.131)
		(end 160.513776 -286.131)
		(width 0.14478)
		(layer "In2.Cu")
		(net "M_I_CPU1_SB_DQ<6>")
	)
	(segment
		(start 171.234354 -288.710624)
		(end 172.751242 -288.710624)
		(width 0.14478)
		(layer "In2.Cu")
		(net "M_I_CPU1_SB_DQ<6>")
	)
	(segment
		(start 177.136552 -287.660588)
		(end 177.315114 -287.482026)
		(width 0.14478)
		(layer "In2.Cu")
		(net "M_I_CPU1_SB_DQ<6>")
	)
	(segment
		(start 157.782514 -283.399992)
		(end 157.782514 -283.628084)
		(width 0.14478)
		(layer "In2.Cu")
		(net "M_I_CPU1_SB_DQ<6>")
	)
	(segment
		(start 157.392624 -283.009848)
		(end 157.405324 -282.997148)
		(width 0.14478)
		(layer "In2.Cu")
		(net "M_I_CPU1_SB_DQ<6>")
	)
	(segment
		(start 157.795722 -283.387038)
		(end 157.782514 -283.399992)
		(width 0.14478)
		(layer "In2.Cu")
		(net "M_I_CPU1_SB_DQ<6>")
	)
	(segment
		(start 162.074352 -287.691576)
		(end 162.087052 -287.678876)
		(width 0.14478)
		(layer "In2.Cu")
		(net "M_I_CPU1_SB_DQ<6>")
	)
	(segment
		(start 167.366442 -288.010092)
		(end 167.584374 -288.228024)
		(width 0.14478)
		(layer "In2.Cu")
		(net "M_I_CPU1_SB_DQ<6>")
	)
	(segment
		(start 157.002226 -282.847796)
		(end 157.164278 -283.009848)
		(width 0.14478)
		(layer "In2.Cu")
		(net "M_I_CPU1_SB_DQ<6>")
	)
	(segment
		(start 158.9532 -284.570424)
		(end 158.9659 -284.557724)
		(width 0.14478)
		(layer "In2.Cu")
		(net "M_I_CPU1_SB_DQ<6>")
	)
	(arc
		(start 138.216132 -277.808944)
		(mid 138.39964 -277.76345)
		(end 138.581892 -277.81377)
		(width 0.0889)
		(layer "In2.Cu")
		(net "M_I_CPU1_SB_DQ<6>")
	)
	(arc
		(start 132.56768 -277.81377)
		(mid 132.749931 -277.76342)
		(end 132.93344 -277.808944)
		(width 0.0889)
		(layer "In2.Cu")
		(net "M_I_CPU1_SB_DQ<6>")
	)
	(arc
		(start 140.461746 -277.81377)
		(mid 140.744702 -277.889947)
		(end 141.027658 -277.81377)
		(width 0.0889)
		(layer "In2.Cu")
		(net "M_I_CPU1_SB_DQ<6>")
	)
	(arc
		(start 144.788128 -277.81377)
		(mid 144.964756 -277.763537)
		(end 145.143982 -277.80361)
		(width 0.0889)
		(layer "In2.Cu")
		(net "M_I_CPU1_SB_DQ<6>")
	)
	(arc
		(start 137.641838 -277.81377)
		(mid 137.924794 -277.889947)
		(end 138.20775 -277.81377)
		(width 0.0889)
		(layer "In2.Cu")
		(net "M_I_CPU1_SB_DQ<6>")
	)
	(arc
		(start 135.76173 -277.81377)
		(mid 136.044686 -277.889947)
		(end 136.327642 -277.81377)
		(width 0.0889)
		(layer "In2.Cu")
		(net "M_I_CPU1_SB_DQ<6>")
	)
	(arc
		(start 134.821676 -277.81377)
		(mid 135.104632 -277.889947)
		(end 135.387588 -277.81377)
		(width 0.0889)
		(layer "In2.Cu")
		(net "M_I_CPU1_SB_DQ<6>")
	)
	(arc
		(start 133.881876 -277.81377)
		(mid 134.164832 -277.889947)
		(end 134.447788 -277.81377)
		(width 0.0889)
		(layer "In2.Cu")
		(net "M_I_CPU1_SB_DQ<6>")
	)
	(arc
		(start 130.121914 -277.81377)
		(mid 130.40487 -277.889947)
		(end 130.687826 -277.81377)
		(width 0.0889)
		(layer "In2.Cu")
		(net "M_I_CPU1_SB_DQ<6>")
	)
	(arc
		(start 129.803144 -277.787608)
		(mid 129.965476 -277.76479)
		(end 130.121914 -277.81377)
		(width 0.0889)
		(layer "In2.Cu")
		(net "M_I_CPU1_SB_DQ<6>")
	)
	(arc
		(start 131.627626 -277.81377)
		(mid 131.809877 -277.76342)
		(end 131.993386 -277.808944)
		(width 0.0889)
		(layer "In2.Cu")
		(net "M_I_CPU1_SB_DQ<6>")
	)
	(arc
		(start 141.4018 -277.81377)
		(mid 141.684756 -277.889947)
		(end 141.967712 -277.81377)
		(width 0.0889)
		(layer "In2.Cu")
		(net "M_I_CPU1_SB_DQ<6>")
	)
	(arc
		(start 132.941822 -277.81377)
		(mid 133.224778 -277.889947)
		(end 133.507734 -277.81377)
		(width 0.0889)
		(layer "In2.Cu")
		(net "M_I_CPU1_SB_DQ<6>")
	)
	(arc
		(start 140.087604 -277.81377)
		(mid 140.269855 -277.76342)
		(end 140.453364 -277.808944)
		(width 0.0889)
		(layer "In2.Cu")
		(net "M_I_CPU1_SB_DQ<6>")
	)
	(arc
		(start 137.276078 -277.808944)
		(mid 137.459586 -277.76345)
		(end 137.641838 -277.81377)
		(width 0.0889)
		(layer "In2.Cu")
		(net "M_I_CPU1_SB_DQ<6>")
	)
	(arc
		(start 143.847566 -277.81377)
		(mid 144.029817 -277.76342)
		(end 144.213326 -277.808944)
		(width 0.0889)
		(layer "In2.Cu")
		(net "M_I_CPU1_SB_DQ<6>")
	)
	(arc
		(start 132.001768 -277.81377)
		(mid 132.284724 -277.889947)
		(end 132.56768 -277.81377)
		(width 0.0889)
		(layer "In2.Cu")
		(net "M_I_CPU1_SB_DQ<6>")
	)
	(arc
		(start 136.701784 -277.81377)
		(mid 136.98474 -277.889947)
		(end 137.267696 -277.81377)
		(width 0.0889)
		(layer "In2.Cu")
		(net "M_I_CPU1_SB_DQ<6>")
	)
	(arc
		(start 136.327642 -277.81377)
		(mid 136.509893 -277.76342)
		(end 136.693402 -277.808944)
		(width 0.0889)
		(layer "In2.Cu")
		(net "M_I_CPU1_SB_DQ<6>")
	)
	(arc
		(start 133.516116 -277.808944)
		(mid 133.699624 -277.76345)
		(end 133.881876 -277.81377)
		(width 0.0889)
		(layer "In2.Cu")
		(net "M_I_CPU1_SB_DQ<6>")
	)
	(arc
		(start 145.143982 -277.80361)
		(mid 145.287961 -277.868241)
		(end 145.44421 -277.890478)
		(width 0.0889)
		(layer "In2.Cu")
		(net "M_I_CPU1_SB_DQ<6>")
	)
	(arc
		(start 142.341854 -277.81377)
		(mid 142.62481 -277.889947)
		(end 142.907766 -277.81377)
		(width 0.0889)
		(layer "In2.Cu")
		(net "M_I_CPU1_SB_DQ<6>")
	)
	(arc
		(start 134.447788 -277.81377)
		(mid 134.634732 -277.763515)
		(end 134.821676 -277.81377)
		(width 0.0889)
		(layer "In2.Cu")
		(net "M_I_CPU1_SB_DQ<6>")
	)
	(arc
		(start 139.147804 -277.81377)
		(mid 139.334748 -277.763515)
		(end 139.521692 -277.81377)
		(width 0.0889)
		(layer "In2.Cu")
		(net "M_I_CPU1_SB_DQ<6>")
	)
	(arc
		(start 138.581892 -277.81377)
		(mid 138.864848 -277.889947)
		(end 139.147804 -277.81377)
		(width 0.0889)
		(layer "In2.Cu")
		(net "M_I_CPU1_SB_DQ<6>")
	)
	(arc
		(start 143.281654 -277.81377)
		(mid 143.56461 -277.889947)
		(end 143.847566 -277.81377)
		(width 0.0889)
		(layer "In2.Cu")
		(net "M_I_CPU1_SB_DQ<6>")
	)
	(arc
		(start 139.521692 -277.81377)
		(mid 139.804648 -277.889947)
		(end 140.087604 -277.81377)
		(width 0.0889)
		(layer "In2.Cu")
		(net "M_I_CPU1_SB_DQ<6>")
	)
	(arc
		(start 142.907766 -277.81377)
		(mid 143.09471 -277.763515)
		(end 143.281654 -277.81377)
		(width 0.0889)
		(layer "In2.Cu")
		(net "M_I_CPU1_SB_DQ<6>")
	)
	(arc
		(start 141.976094 -277.808944)
		(mid 142.159602 -277.76345)
		(end 142.341854 -277.81377)
		(width 0.0889)
		(layer "In2.Cu")
		(net "M_I_CPU1_SB_DQ<6>")
	)
	(arc
		(start 141.027658 -277.81377)
		(mid 141.209909 -277.76342)
		(end 141.393418 -277.808944)
		(width 0.0889)
		(layer "In2.Cu")
		(net "M_I_CPU1_SB_DQ<6>")
	)
	(arc
		(start 144.23644 -277.822406)
		(mid 144.513423 -277.89021)
		(end 144.788128 -277.81377)
		(width 0.0889)
		(layer "In2.Cu")
		(net "M_I_CPU1_SB_DQ<6>")
	)
	(arc
		(start 135.387588 -277.81377)
		(mid 135.569839 -277.76342)
		(end 135.753348 -277.808944)
		(width 0.0889)
		(layer "In2.Cu")
		(net "M_I_CPU1_SB_DQ<6>")
	)
	(arc
		(start 131.061714 -277.81377)
		(mid 131.34467 -277.889947)
		(end 131.627626 -277.81377)
		(width 0.0889)
		(layer "In2.Cu")
		(net "M_I_CPU1_SB_DQ<6>")
	)
	(arc
		(start 130.687826 -277.81377)
		(mid 130.87477 -277.763515)
		(end 131.061714 -277.81377)
		(width 0.0889)
		(layer "In2.Cu")
		(net "M_I_CPU1_SB_DQ<6>")
	)
	(segment
		(start 127.58801 -277.870412)
		(end 128.054862 -278.13635)
		(width 0.10668)
		(layer "F.Cu")
		(net "M_I_CPU1_SB_DQ<5>")
	)
	(segment
		(start 145.357342 -278.38908)
		(end 145.814288 -278.38908)
		(width 0.0889)
		(layer "In2.Cu")
		(net "M_I_CPU1_SB_DQ<5>")
	)
	(segment
		(start 145.814288 -278.38908)
		(end 146.699224 -277.504144)
		(width 0.0889)
		(layer "In2.Cu")
		(net "M_I_CPU1_SB_DQ<5>")
	)
	(segment
		(start 128.054862 -278.13635)
		(end 128.208786 -278.40178)
		(width 0.0889)
		(layer "In2.Cu")
		(net "M_I_CPU1_SB_DQ<5>")
	)
	(segment
		(start 128.208786 -278.40178)
		(end 128.304798 -278.42718)
		(width 0.0889)
		(layer "In2.Cu")
		(net "M_I_CPU1_SB_DQ<5>")
	)
	(segment
		(start 164.432742 -289.560508)
		(end 165.031674 -289.441382)
		(width 0.14478)
		(layer "In2.Cu")
		(net "M_I_CPU1_SB_DQ<5>")
	)
	(segment
		(start 136.693402 -278.463756)
		(end 136.701784 -278.45893)
		(width 0.0889)
		(layer "In2.Cu")
		(net "M_I_CPU1_SB_DQ<5>")
	)
	(segment
		(start 131.993386 -278.463756)
		(end 132.001768 -278.45893)
		(width 0.0889)
		(layer "In2.Cu")
		(net "M_I_CPU1_SB_DQ<5>")
	)
	(segment
		(start 170.078654 -288.82975)
		(end 171.842684 -289.560508)
		(width 0.14478)
		(layer "In2.Cu")
		(net "M_I_CPU1_SB_DQ<5>")
	)
	(segment
		(start 141.393418 -278.463756)
		(end 141.4018 -278.45893)
		(width 0.0889)
		(layer "In2.Cu")
		(net "M_I_CPU1_SB_DQ<5>")
	)
	(segment
		(start 144.784318 -278.45893)
		(end 144.804892 -278.470868)
		(width 0.0889)
		(layer "In2.Cu")
		(net "M_I_CPU1_SB_DQ<5>")
	)
	(segment
		(start 128.807718 -278.45893)
		(end 128.8161 -278.463756)
		(width 0.0889)
		(layer "In2.Cu")
		(net "M_I_CPU1_SB_DQ<5>")
	)
	(segment
		(start 129.747772 -278.45893)
		(end 129.756154 -278.463756)
		(width 0.0889)
		(layer "In2.Cu")
		(net "M_I_CPU1_SB_DQ<5>")
	)
	(segment
		(start 164.18814 -289.560508)
		(end 164.432742 -289.560508)
		(width 0.14478)
		(layer "In2.Cu")
		(net "M_I_CPU1_SB_DQ<5>")
	)
	(segment
		(start 144.19707 -278.472138)
		(end 144.220438 -278.458676)
		(width 0.0889)
		(layer "In2.Cu")
		(net "M_I_CPU1_SB_DQ<5>")
	)
	(segment
		(start 171.842684 -289.560508)
		(end 172.122084 -289.560508)
		(width 0.14478)
		(layer "In2.Cu")
		(net "M_I_CPU1_SB_DQ<5>")
	)
	(segment
		(start 137.267696 -278.45893)
		(end 137.276078 -278.463756)
		(width 0.0889)
		(layer "In2.Cu")
		(net "M_I_CPU1_SB_DQ<5>")
	)
	(segment
		(start 162.57778 -289.059366)
		(end 162.949128 -289.213036)
		(width 0.14478)
		(layer "In2.Cu")
		(net "M_I_CPU1_SB_DQ<5>")
	)
	(segment
		(start 172.122084 -289.560508)
		(end 175.514508 -288.710624)
		(width 0.14478)
		(layer "In2.Cu")
		(net "M_I_CPU1_SB_DQ<5>")
	)
	(segment
		(start 145.15973 -278.45893)
		(end 145.159984 -278.459184)
		(width 0.0889)
		(layer "In2.Cu")
		(net "M_I_CPU1_SB_DQ<5>")
	)
	(segment
		(start 147.657566 -277.504144)
		(end 147.753832 -277.60041)
		(width 0.0889)
		(layer "In2.Cu")
		(net "M_I_CPU1_SB_DQ<5>")
	)
	(segment
		(start 140.453364 -278.463756)
		(end 140.461746 -278.45893)
		(width 0.0889)
		(layer "In2.Cu")
		(net "M_I_CPU1_SB_DQ<5>")
	)
	(segment
		(start 133.507734 -278.45893)
		(end 133.516116 -278.463756)
		(width 0.0889)
		(layer "In2.Cu")
		(net "M_I_CPU1_SB_DQ<5>")
	)
	(segment
		(start 175.514508 -288.710624)
		(end 183.191404 -288.710624)
		(width 0.14478)
		(layer "In2.Cu")
		(net "M_I_CPU1_SB_DQ<5>")
	)
	(segment
		(start 151.118824 -277.60041)
		(end 162.57778 -289.059366)
		(width 0.14478)
		(layer "In2.Cu")
		(net "M_I_CPU1_SB_DQ<5>")
	)
	(segment
		(start 163.657788 -289.42792)
		(end 164.18814 -289.560508)
		(width 0.14478)
		(layer "In2.Cu")
		(net "M_I_CPU1_SB_DQ<5>")
	)
	(segment
		(start 169.479976 -288.710624)
		(end 170.078654 -288.82975)
		(width 0.14478)
		(layer "In2.Cu")
		(net "M_I_CPU1_SB_DQ<5>")
	)
	(segment
		(start 147.753832 -277.60041)
		(end 151.118824 -277.60041)
		(width 0.14478)
		(layer "In2.Cu")
		(net "M_I_CPU1_SB_DQ<5>")
	)
	(segment
		(start 141.967712 -278.45893)
		(end 141.976094 -278.463756)
		(width 0.0889)
		(layer "In2.Cu")
		(net "M_I_CPU1_SB_DQ<5>")
	)
	(segment
		(start 138.20775 -278.45893)
		(end 138.216132 -278.463756)
		(width 0.0889)
		(layer "In2.Cu")
		(net "M_I_CPU1_SB_DQ<5>")
	)
	(segment
		(start 165.031674 -289.441382)
		(end 167.945816 -288.710624)
		(width 0.14478)
		(layer "In2.Cu")
		(net "M_I_CPU1_SB_DQ<5>")
	)
	(segment
		(start 183.191404 -288.710624)
		(end 183.616092 -289.135312)
		(width 0.14478)
		(layer "In2.Cu")
		(net "M_I_CPU1_SB_DQ<5>")
	)
	(segment
		(start 146.699224 -277.504144)
		(end 147.657566 -277.504144)
		(width 0.0889)
		(layer "In2.Cu")
		(net "M_I_CPU1_SB_DQ<5>")
	)
	(segment
		(start 132.93344 -278.463756)
		(end 132.941822 -278.45893)
		(width 0.0889)
		(layer "In2.Cu")
		(net "M_I_CPU1_SB_DQ<5>")
	)
	(segment
		(start 135.753348 -278.463756)
		(end 135.76173 -278.45893)
		(width 0.0889)
		(layer "In2.Cu")
		(net "M_I_CPU1_SB_DQ<5>")
	)
	(segment
		(start 144.220438 -278.458676)
		(end 144.2466 -278.44369)
		(width 0.0889)
		(layer "In2.Cu")
		(net "M_I_CPU1_SB_DQ<5>")
	)
	(segment
		(start 167.945816 -288.710624)
		(end 169.479976 -288.710624)
		(width 0.14478)
		(layer "In2.Cu")
		(net "M_I_CPU1_SB_DQ<5>")
	)
	(segment
		(start 162.949128 -289.213036)
		(end 163.657788 -289.42792)
		(width 0.14478)
		(layer "In2.Cu")
		(net "M_I_CPU1_SB_DQ<5>")
	)
	(arc
		(start 135.387588 -278.45893)
		(mid 135.569839 -278.50928)
		(end 135.753348 -278.463756)
		(width 0.0889)
		(layer "In2.Cu")
		(net "M_I_CPU1_SB_DQ<5>")
	)
	(arc
		(start 128.304798 -278.42718)
		(mid 128.560006 -278.383703)
		(end 128.807718 -278.45893)
		(width 0.0889)
		(layer "In2.Cu")
		(net "M_I_CPU1_SB_DQ<5>")
	)
	(arc
		(start 144.2466 -278.44369)
		(mid 144.517386 -278.383044)
		(end 144.784318 -278.45893)
		(width 0.0889)
		(layer "In2.Cu")
		(net "M_I_CPU1_SB_DQ<5>")
	)
	(arc
		(start 141.027658 -278.45893)
		(mid 141.209909 -278.50928)
		(end 141.393418 -278.463756)
		(width 0.0889)
		(layer "In2.Cu")
		(net "M_I_CPU1_SB_DQ<5>")
	)
	(arc
		(start 131.061714 -278.45893)
		(mid 131.34467 -278.382753)
		(end 131.627626 -278.45893)
		(width 0.0889)
		(layer "In2.Cu")
		(net "M_I_CPU1_SB_DQ<5>")
	)
	(arc
		(start 140.087604 -278.45893)
		(mid 140.269855 -278.50928)
		(end 140.453364 -278.463756)
		(width 0.0889)
		(layer "In2.Cu")
		(net "M_I_CPU1_SB_DQ<5>")
	)
	(arc
		(start 138.216132 -278.463756)
		(mid 138.39964 -278.50925)
		(end 138.581892 -278.45893)
		(width 0.0889)
		(layer "In2.Cu")
		(net "M_I_CPU1_SB_DQ<5>")
	)
	(arc
		(start 128.8161 -278.463756)
		(mid 128.999608 -278.50925)
		(end 129.18186 -278.45893)
		(width 0.0889)
		(layer "In2.Cu")
		(net "M_I_CPU1_SB_DQ<5>")
	)
	(arc
		(start 139.147804 -278.45893)
		(mid 139.334748 -278.509185)
		(end 139.521692 -278.45893)
		(width 0.0889)
		(layer "In2.Cu")
		(net "M_I_CPU1_SB_DQ<5>")
	)
	(arc
		(start 145.159984 -278.459184)
		(mid 145.255384 -278.414902)
		(end 145.357342 -278.38908)
		(width 0.0889)
		(layer "In2.Cu")
		(net "M_I_CPU1_SB_DQ<5>")
	)
	(arc
		(start 132.941822 -278.45893)
		(mid 133.224778 -278.382753)
		(end 133.507734 -278.45893)
		(width 0.0889)
		(layer "In2.Cu")
		(net "M_I_CPU1_SB_DQ<5>")
	)
	(arc
		(start 134.821676 -278.45893)
		(mid 135.104632 -278.382753)
		(end 135.387588 -278.45893)
		(width 0.0889)
		(layer "In2.Cu")
		(net "M_I_CPU1_SB_DQ<5>")
	)
	(arc
		(start 130.121914 -278.45893)
		(mid 130.40487 -278.382753)
		(end 130.687826 -278.45893)
		(width 0.0889)
		(layer "In2.Cu")
		(net "M_I_CPU1_SB_DQ<5>")
	)
	(arc
		(start 135.76173 -278.45893)
		(mid 136.044686 -278.382753)
		(end 136.327642 -278.45893)
		(width 0.0889)
		(layer "In2.Cu")
		(net "M_I_CPU1_SB_DQ<5>")
	)
	(arc
		(start 129.18186 -278.45893)
		(mid 129.464816 -278.382753)
		(end 129.747772 -278.45893)
		(width 0.0889)
		(layer "In2.Cu")
		(net "M_I_CPU1_SB_DQ<5>")
	)
	(arc
		(start 141.976094 -278.463756)
		(mid 142.159602 -278.50925)
		(end 142.341854 -278.45893)
		(width 0.0889)
		(layer "In2.Cu")
		(net "M_I_CPU1_SB_DQ<5>")
	)
	(arc
		(start 134.447788 -278.45893)
		(mid 134.634732 -278.509185)
		(end 134.821676 -278.45893)
		(width 0.0889)
		(layer "In2.Cu")
		(net "M_I_CPU1_SB_DQ<5>")
	)
	(arc
		(start 130.687826 -278.45893)
		(mid 130.87477 -278.509185)
		(end 131.061714 -278.45893)
		(width 0.0889)
		(layer "In2.Cu")
		(net "M_I_CPU1_SB_DQ<5>")
	)
	(arc
		(start 136.701784 -278.45893)
		(mid 136.98474 -278.382753)
		(end 137.267696 -278.45893)
		(width 0.0889)
		(layer "In2.Cu")
		(net "M_I_CPU1_SB_DQ<5>")
	)
	(arc
		(start 132.56768 -278.45893)
		(mid 132.749931 -278.50928)
		(end 132.93344 -278.463756)
		(width 0.0889)
		(layer "In2.Cu")
		(net "M_I_CPU1_SB_DQ<5>")
	)
	(arc
		(start 131.627626 -278.45893)
		(mid 131.809877 -278.50928)
		(end 131.993386 -278.463756)
		(width 0.0889)
		(layer "In2.Cu")
		(net "M_I_CPU1_SB_DQ<5>")
	)
	(arc
		(start 144.804892 -278.470868)
		(mid 144.98382 -278.509745)
		(end 145.15973 -278.45893)
		(width 0.0889)
		(layer "In2.Cu")
		(net "M_I_CPU1_SB_DQ<5>")
	)
	(arc
		(start 132.001768 -278.45893)
		(mid 132.284724 -278.382753)
		(end 132.56768 -278.45893)
		(width 0.0889)
		(layer "In2.Cu")
		(net "M_I_CPU1_SB_DQ<5>")
	)
	(arc
		(start 143.281654 -278.45893)
		(mid 143.56461 -278.382753)
		(end 143.847566 -278.45893)
		(width 0.0889)
		(layer "In2.Cu")
		(net "M_I_CPU1_SB_DQ<5>")
	)
	(arc
		(start 133.881876 -278.45893)
		(mid 134.164832 -278.382753)
		(end 134.447788 -278.45893)
		(width 0.0889)
		(layer "In2.Cu")
		(net "M_I_CPU1_SB_DQ<5>")
	)
	(arc
		(start 143.847566 -278.45893)
		(mid 144.020674 -278.509046)
		(end 144.19707 -278.472138)
		(width 0.0889)
		(layer "In2.Cu")
		(net "M_I_CPU1_SB_DQ<5>")
	)
	(arc
		(start 133.516116 -278.463756)
		(mid 133.699624 -278.50925)
		(end 133.881876 -278.45893)
		(width 0.0889)
		(layer "In2.Cu")
		(net "M_I_CPU1_SB_DQ<5>")
	)
	(arc
		(start 138.581892 -278.45893)
		(mid 138.864848 -278.382753)
		(end 139.147804 -278.45893)
		(width 0.0889)
		(layer "In2.Cu")
		(net "M_I_CPU1_SB_DQ<5>")
	)
	(arc
		(start 142.907766 -278.45893)
		(mid 143.09471 -278.509185)
		(end 143.281654 -278.45893)
		(width 0.0889)
		(layer "In2.Cu")
		(net "M_I_CPU1_SB_DQ<5>")
	)
	(arc
		(start 141.4018 -278.45893)
		(mid 141.684756 -278.382753)
		(end 141.967712 -278.45893)
		(width 0.0889)
		(layer "In2.Cu")
		(net "M_I_CPU1_SB_DQ<5>")
	)
	(arc
		(start 137.641838 -278.45893)
		(mid 137.924794 -278.382753)
		(end 138.20775 -278.45893)
		(width 0.0889)
		(layer "In2.Cu")
		(net "M_I_CPU1_SB_DQ<5>")
	)
	(arc
		(start 139.521692 -278.45893)
		(mid 139.804648 -278.382753)
		(end 140.087604 -278.45893)
		(width 0.0889)
		(layer "In2.Cu")
		(net "M_I_CPU1_SB_DQ<5>")
	)
	(arc
		(start 129.756154 -278.463756)
		(mid 129.939662 -278.50925)
		(end 130.121914 -278.45893)
		(width 0.0889)
		(layer "In2.Cu")
		(net "M_I_CPU1_SB_DQ<5>")
	)
	(arc
		(start 136.327642 -278.45893)
		(mid 136.509893 -278.50928)
		(end 136.693402 -278.463756)
		(width 0.0889)
		(layer "In2.Cu")
		(net "M_I_CPU1_SB_DQ<5>")
	)
	(arc
		(start 142.341854 -278.45893)
		(mid 142.62481 -278.382753)
		(end 142.907766 -278.45893)
		(width 0.0889)
		(layer "In2.Cu")
		(net "M_I_CPU1_SB_DQ<5>")
	)
	(arc
		(start 140.461746 -278.45893)
		(mid 140.744702 -278.382753)
		(end 141.027658 -278.45893)
		(width 0.0889)
		(layer "In2.Cu")
		(net "M_I_CPU1_SB_DQ<5>")
	)
	(arc
		(start 137.276078 -278.463756)
		(mid 137.459586 -278.50925)
		(end 137.641838 -278.45893)
		(width 0.0889)
		(layer "In2.Cu")
		(net "M_I_CPU1_SB_DQ<5>")
	)
	(segment
		(start 128.997964 -277.060406)
		(end 129.464816 -277.326344)
		(width 0.10668)
		(layer "F.Cu")
		(net "M_I_CPU1_SB_DQ<4>")
	)
	(segment
		(start 169.808144 -287.02)
		(end 170.658282 -287.870138)
		(width 0.14478)
		(layer "In2.Cu")
		(net "M_I_CPU1_SB_DQ<4>")
	)
	(segment
		(start 146.65706 -276.69109)
		(end 148.0312 -276.69109)
		(width 0.0889)
		(layer "In2.Cu")
		(net "M_I_CPU1_SB_DQ<4>")
	)
	(segment
		(start 174.738792 -287.02)
		(end 183.200802 -287.02)
		(width 0.14478)
		(layer "In2.Cu")
		(net "M_I_CPU1_SB_DQ<4>")
	)
	(segment
		(start 140.557758 -277.648924)
		(end 140.56614 -277.65375)
		(width 0.0889)
		(layer "In2.Cu")
		(net "M_I_CPU1_SB_DQ<4>")
	)
	(segment
		(start 144.31772 -277.648924)
		(end 144.329404 -277.655782)
		(width 0.0889)
		(layer "In2.Cu")
		(net "M_I_CPU1_SB_DQ<4>")
	)
	(segment
		(start 129.61874 -277.591774)
		(end 129.714752 -277.617174)
		(width 0.0889)
		(layer "In2.Cu")
		(net "M_I_CPU1_SB_DQ<4>")
	)
	(segment
		(start 151.481536 -276.69109)
		(end 156.486606 -281.69616)
		(width 0.14478)
		(layer "In2.Cu")
		(net "M_I_CPU1_SB_DQ<4>")
	)
	(segment
		(start 139.04341 -277.65375)
		(end 139.051792 -277.648924)
		(width 0.0889)
		(layer "In2.Cu")
		(net "M_I_CPU1_SB_DQ<4>")
	)
	(segment
		(start 163.18992 -287.870138)
		(end 165.885368 -287.870138)
		(width 0.14478)
		(layer "In2.Cu")
		(net "M_I_CPU1_SB_DQ<4>")
	)
	(segment
		(start 167.083232 -287.02)
		(end 169.808144 -287.02)
		(width 0.14478)
		(layer "In2.Cu")
		(net "M_I_CPU1_SB_DQ<4>")
	)
	(segment
		(start 130.583432 -277.65375)
		(end 130.591814 -277.648924)
		(width 0.0889)
		(layer "In2.Cu")
		(net "M_I_CPU1_SB_DQ<4>")
	)
	(segment
		(start 132.09778 -277.648924)
		(end 132.106162 -277.65375)
		(width 0.0889)
		(layer "In2.Cu")
		(net "M_I_CPU1_SB_DQ<4>")
	)
	(segment
		(start 134.917688 -277.648924)
		(end 134.92607 -277.65375)
		(width 0.0889)
		(layer "In2.Cu")
		(net "M_I_CPU1_SB_DQ<4>")
	)
	(segment
		(start 129.464816 -277.326344)
		(end 129.61874 -277.591774)
		(width 0.0889)
		(layer "In2.Cu")
		(net "M_I_CPU1_SB_DQ<4>")
	)
	(segment
		(start 157.015942 -281.69616)
		(end 163.18992 -287.870138)
		(width 0.14478)
		(layer "In2.Cu")
		(net "M_I_CPU1_SB_DQ<4>")
	)
	(segment
		(start 145.444718 -277.699978)
		(end 145.648172 -277.699978)
		(width 0.0889)
		(layer "In2.Cu")
		(net "M_I_CPU1_SB_DQ<4>")
	)
	(segment
		(start 134.343394 -277.65375)
		(end 134.351776 -277.648924)
		(width 0.0889)
		(layer "In2.Cu")
		(net "M_I_CPU1_SB_DQ<4>")
	)
	(segment
		(start 142.803372 -277.65375)
		(end 142.811754 -277.648924)
		(width 0.0889)
		(layer "In2.Cu")
		(net "M_I_CPU1_SB_DQ<4>")
	)
	(segment
		(start 148.0312 -276.69109)
		(end 151.481536 -276.69109)
		(width 0.14478)
		(layer "In2.Cu")
		(net "M_I_CPU1_SB_DQ<4>")
	)
	(segment
		(start 138.103356 -277.65375)
		(end 138.111738 -277.648924)
		(width 0.0889)
		(layer "In2.Cu")
		(net "M_I_CPU1_SB_DQ<4>")
	)
	(segment
		(start 143.377666 -277.648924)
		(end 143.386048 -277.65375)
		(width 0.0889)
		(layer "In2.Cu")
		(net "M_I_CPU1_SB_DQ<4>")
	)
	(segment
		(start 165.885368 -287.870138)
		(end 166.478966 -287.624266)
		(width 0.14478)
		(layer "In2.Cu")
		(net "M_I_CPU1_SB_DQ<4>")
	)
	(segment
		(start 139.617704 -277.648924)
		(end 139.626086 -277.65375)
		(width 0.0889)
		(layer "In2.Cu")
		(net "M_I_CPU1_SB_DQ<4>")
	)
	(segment
		(start 145.648172 -277.699978)
		(end 146.65706 -276.69109)
		(width 0.0889)
		(layer "In2.Cu")
		(net "M_I_CPU1_SB_DQ<4>")
	)
	(segment
		(start 166.478966 -287.624266)
		(end 167.083232 -287.02)
		(width 0.14478)
		(layer "In2.Cu")
		(net "M_I_CPU1_SB_DQ<4>")
	)
	(segment
		(start 156.486606 -281.69616)
		(end 157.015942 -281.69616)
		(width 0.14478)
		(layer "In2.Cu")
		(net "M_I_CPU1_SB_DQ<4>")
	)
	(segment
		(start 173.465998 -287.870138)
		(end 174.738792 -287.02)
		(width 0.14478)
		(layer "In2.Cu")
		(net "M_I_CPU1_SB_DQ<4>")
	)
	(segment
		(start 183.200802 -287.02)
		(end 183.616092 -287.43529)
		(width 0.14478)
		(layer "In2.Cu")
		(net "M_I_CPU1_SB_DQ<4>")
	)
	(segment
		(start 170.658282 -287.870138)
		(end 173.465998 -287.870138)
		(width 0.14478)
		(layer "In2.Cu")
		(net "M_I_CPU1_SB_DQ<4>")
	)
	(segment
		(start 131.157726 -277.648924)
		(end 131.166108 -277.65375)
		(width 0.0889)
		(layer "In2.Cu")
		(net "M_I_CPU1_SB_DQ<4>")
	)
	(segment
		(start 135.857742 -277.648924)
		(end 135.866124 -277.65375)
		(width 0.0889)
		(layer "In2.Cu")
		(net "M_I_CPU1_SB_DQ<4>")
	)
	(arc
		(start 142.811754 -277.648924)
		(mid 143.09471 -277.572747)
		(end 143.377666 -277.648924)
		(width 0.0889)
		(layer "In2.Cu")
		(net "M_I_CPU1_SB_DQ<4>")
	)
	(arc
		(start 139.051792 -277.648924)
		(mid 139.334748 -277.572747)
		(end 139.617704 -277.648924)
		(width 0.0889)
		(layer "In2.Cu")
		(net "M_I_CPU1_SB_DQ<4>")
	)
	(arc
		(start 140.9319 -277.648924)
		(mid 141.214856 -277.572747)
		(end 141.497812 -277.648924)
		(width 0.0889)
		(layer "In2.Cu")
		(net "M_I_CPU1_SB_DQ<4>")
	)
	(arc
		(start 130.591814 -277.648924)
		(mid 130.87477 -277.572747)
		(end 131.157726 -277.648924)
		(width 0.0889)
		(layer "In2.Cu")
		(net "M_I_CPU1_SB_DQ<4>")
	)
	(arc
		(start 133.411722 -277.648924)
		(mid 133.694678 -277.572747)
		(end 133.977634 -277.648924)
		(width 0.0889)
		(layer "In2.Cu")
		(net "M_I_CPU1_SB_DQ<4>")
	)
	(arc
		(start 135.29183 -277.648924)
		(mid 135.574786 -277.572747)
		(end 135.857742 -277.648924)
		(width 0.0889)
		(layer "In2.Cu")
		(net "M_I_CPU1_SB_DQ<4>")
	)
	(arc
		(start 136.797796 -277.648924)
		(mid 136.98474 -277.699179)
		(end 137.171684 -277.648924)
		(width 0.0889)
		(layer "In2.Cu")
		(net "M_I_CPU1_SB_DQ<4>")
	)
	(arc
		(start 140.56614 -277.65375)
		(mid 140.749648 -277.699244)
		(end 140.9319 -277.648924)
		(width 0.0889)
		(layer "In2.Cu")
		(net "M_I_CPU1_SB_DQ<4>")
	)
	(arc
		(start 138.67765 -277.648924)
		(mid 138.859901 -277.699274)
		(end 139.04341 -277.65375)
		(width 0.0889)
		(layer "In2.Cu")
		(net "M_I_CPU1_SB_DQ<4>")
	)
	(arc
		(start 143.386048 -277.65375)
		(mid 143.569556 -277.699244)
		(end 143.751808 -277.648924)
		(width 0.0889)
		(layer "In2.Cu")
		(net "M_I_CPU1_SB_DQ<4>")
	)
	(arc
		(start 129.714752 -277.617174)
		(mid 129.96996 -277.573697)
		(end 130.217672 -277.648924)
		(width 0.0889)
		(layer "In2.Cu")
		(net "M_I_CPU1_SB_DQ<4>")
	)
	(arc
		(start 134.92607 -277.65375)
		(mid 135.109578 -277.699244)
		(end 135.29183 -277.648924)
		(width 0.0889)
		(layer "In2.Cu")
		(net "M_I_CPU1_SB_DQ<4>")
	)
	(arc
		(start 133.037834 -277.648924)
		(mid 133.224778 -277.699179)
		(end 133.411722 -277.648924)
		(width 0.0889)
		(layer "In2.Cu")
		(net "M_I_CPU1_SB_DQ<4>")
	)
	(arc
		(start 134.351776 -277.648924)
		(mid 134.634732 -277.572747)
		(end 134.917688 -277.648924)
		(width 0.0889)
		(layer "In2.Cu")
		(net "M_I_CPU1_SB_DQ<4>")
	)
	(arc
		(start 139.626086 -277.65375)
		(mid 139.809594 -277.699244)
		(end 139.991846 -277.648924)
		(width 0.0889)
		(layer "In2.Cu")
		(net "M_I_CPU1_SB_DQ<4>")
	)
	(arc
		(start 144.329404 -277.655782)
		(mid 144.511659 -277.699435)
		(end 144.692116 -277.648924)
		(width 0.0889)
		(layer "In2.Cu")
		(net "M_I_CPU1_SB_DQ<4>")
	)
	(arc
		(start 136.231884 -277.648924)
		(mid 136.51484 -277.572747)
		(end 136.797796 -277.648924)
		(width 0.0889)
		(layer "In2.Cu")
		(net "M_I_CPU1_SB_DQ<4>")
	)
	(arc
		(start 135.866124 -277.65375)
		(mid 136.049632 -277.699244)
		(end 136.231884 -277.648924)
		(width 0.0889)
		(layer "In2.Cu")
		(net "M_I_CPU1_SB_DQ<4>")
	)
	(arc
		(start 141.8717 -277.648924)
		(mid 142.154656 -277.572747)
		(end 142.437612 -277.648924)
		(width 0.0889)
		(layer "In2.Cu")
		(net "M_I_CPU1_SB_DQ<4>")
	)
	(arc
		(start 143.751808 -277.648924)
		(mid 144.034764 -277.572747)
		(end 144.31772 -277.648924)
		(width 0.0889)
		(layer "In2.Cu")
		(net "M_I_CPU1_SB_DQ<4>")
	)
	(arc
		(start 142.437612 -277.648924)
		(mid 142.619863 -277.699274)
		(end 142.803372 -277.65375)
		(width 0.0889)
		(layer "In2.Cu")
		(net "M_I_CPU1_SB_DQ<4>")
	)
	(arc
		(start 137.737596 -277.648924)
		(mid 137.919847 -277.699274)
		(end 138.103356 -277.65375)
		(width 0.0889)
		(layer "In2.Cu")
		(net "M_I_CPU1_SB_DQ<4>")
	)
	(arc
		(start 141.497812 -277.648924)
		(mid 141.684756 -277.699179)
		(end 141.8717 -277.648924)
		(width 0.0889)
		(layer "In2.Cu")
		(net "M_I_CPU1_SB_DQ<4>")
	)
	(arc
		(start 139.991846 -277.648924)
		(mid 140.274802 -277.572747)
		(end 140.557758 -277.648924)
		(width 0.0889)
		(layer "In2.Cu")
		(net "M_I_CPU1_SB_DQ<4>")
	)
	(arc
		(start 138.111738 -277.648924)
		(mid 138.394694 -277.572747)
		(end 138.67765 -277.648924)
		(width 0.0889)
		(layer "In2.Cu")
		(net "M_I_CPU1_SB_DQ<4>")
	)
	(arc
		(start 144.692116 -277.648924)
		(mid 144.965971 -277.572574)
		(end 145.24228 -277.639526)
		(width 0.0889)
		(layer "In2.Cu")
		(net "M_I_CPU1_SB_DQ<4>")
	)
	(arc
		(start 137.171684 -277.648924)
		(mid 137.45464 -277.572747)
		(end 137.737596 -277.648924)
		(width 0.0889)
		(layer "In2.Cu")
		(net "M_I_CPU1_SB_DQ<4>")
	)
	(arc
		(start 132.471922 -277.648924)
		(mid 132.754878 -277.572747)
		(end 133.037834 -277.648924)
		(width 0.0889)
		(layer "In2.Cu")
		(net "M_I_CPU1_SB_DQ<4>")
	)
	(arc
		(start 145.24228 -277.639526)
		(mid 145.339134 -277.684373)
		(end 145.444718 -277.699978)
		(width 0.0889)
		(layer "In2.Cu")
		(net "M_I_CPU1_SB_DQ<4>")
	)
	(arc
		(start 130.217672 -277.648924)
		(mid 130.399923 -277.699274)
		(end 130.583432 -277.65375)
		(width 0.0889)
		(layer "In2.Cu")
		(net "M_I_CPU1_SB_DQ<4>")
	)
	(arc
		(start 133.977634 -277.648924)
		(mid 134.159885 -277.699274)
		(end 134.343394 -277.65375)
		(width 0.0889)
		(layer "In2.Cu")
		(net "M_I_CPU1_SB_DQ<4>")
	)
	(arc
		(start 131.531868 -277.648924)
		(mid 131.814824 -277.572747)
		(end 132.09778 -277.648924)
		(width 0.0889)
		(layer "In2.Cu")
		(net "M_I_CPU1_SB_DQ<4>")
	)
	(arc
		(start 132.106162 -277.65375)
		(mid 132.28967 -277.699244)
		(end 132.471922 -277.648924)
		(width 0.0889)
		(layer "In2.Cu")
		(net "M_I_CPU1_SB_DQ<4>")
	)
	(arc
		(start 131.166108 -277.65375)
		(mid 131.349616 -277.699244)
		(end 131.531868 -277.648924)
		(width 0.0889)
		(layer "In2.Cu")
		(net "M_I_CPU1_SB_DQ<4>")
	)
	(segment
		(start 128.05791 -275.440394)
		(end 128.524762 -275.706332)
		(width 0.10668)
		(layer "F.Cu")
		(net "M_I_CPU1_SB_DQ<3>")
	)
	(segment
		(start 145.25625 -275.383752)
		(end 145.81505 -275.08073)
		(width 0.0889)
		(layer "In2.Cu")
		(net "M_I_CPU1_SB_DQ<3>")
	)
	(segment
		(start 160.44418 -281.887168)
		(end 160.605724 -282.048712)
		(width 0.14478)
		(layer "In2.Cu")
		(net "M_I_CPU1_SB_DQ<3>")
	)
	(segment
		(start 146.188938 -274.903692)
		(end 146.834606 -274.258024)
		(width 0.0889)
		(layer "In2.Cu")
		(net "M_I_CPU1_SB_DQ<3>")
	)
	(segment
		(start 177.926238 -283.678884)
		(end 178.073558 -283.826204)
		(width 0.14478)
		(layer "In2.Cu")
		(net "M_I_CPU1_SB_DQ<3>")
	)
	(segment
		(start 178.632358 -283.610304)
		(end 179.091082 -283.610304)
		(width 0.14478)
		(layer "In2.Cu")
		(net "M_I_CPU1_SB_DQ<3>")
	)
	(segment
		(start 132.09778 -275.383752)
		(end 132.106162 -275.378926)
		(width 0.0889)
		(layer "In2.Cu")
		(net "M_I_CPU1_SB_DQ<3>")
	)
	(segment
		(start 158.883604 -280.097992)
		(end 158.883604 -280.326592)
		(width 0.14478)
		(layer "In2.Cu")
		(net "M_I_CPU1_SB_DQ<3>")
	)
	(segment
		(start 178.416458 -283.826204)
		(end 178.632358 -283.610304)
		(width 0.14478)
		(layer "In2.Cu")
		(net "M_I_CPU1_SB_DQ<3>")
	)
	(segment
		(start 148.078698 -274.303744)
		(end 152.860756 -274.303744)
		(width 0.14478)
		(layer "In2.Cu")
		(net "M_I_CPU1_SB_DQ<3>")
	)
	(segment
		(start 152.860756 -274.303744)
		(end 158.26486 -279.707848)
		(width 0.14478)
		(layer "In2.Cu")
		(net "M_I_CPU1_SB_DQ<3>")
	)
	(segment
		(start 159.452564 -280.30932)
		(end 159.681164 -280.30932)
		(width 0.14478)
		(layer "In2.Cu")
		(net "M_I_CPU1_SB_DQ<3>")
	)
	(segment
		(start 167.66032 -283.600652)
		(end 170.137836 -283.600652)
		(width 0.14478)
		(layer "In2.Cu")
		(net "M_I_CPU1_SB_DQ<3>")
	)
	(segment
		(start 170.98772 -284.450536)
		(end 172.886624 -284.450536)
		(width 0.14478)
		(layer "In2.Cu")
		(net "M_I_CPU1_SB_DQ<3>")
	)
	(segment
		(start 159.842708 -280.699464)
		(end 159.663892 -280.87828)
		(width 0.14478)
		(layer "In2.Cu")
		(net "M_I_CPU1_SB_DQ<3>")
	)
	(segment
		(start 147.442174 -274.258024)
		(end 147.487894 -274.303744)
		(width 0.0889)
		(layer "In2.Cu")
		(net "M_I_CPU1_SB_DQ<3>")
	)
	(segment
		(start 159.842708 -280.470864)
		(end 159.842708 -280.699464)
		(width 0.14478)
		(layer "In2.Cu")
		(net "M_I_CPU1_SB_DQ<3>")
	)
	(segment
		(start 163.616132 -284.450536)
		(end 165.212522 -284.450536)
		(width 0.14478)
		(layer "In2.Cu")
		(net "M_I_CPU1_SB_DQ<3>")
	)
	(segment
		(start 159.06242 -279.690576)
		(end 159.06242 -279.919176)
		(width 0.14478)
		(layer "In2.Cu")
		(net "M_I_CPU1_SB_DQ<3>")
	)
	(segment
		(start 135.857742 -275.383752)
		(end 135.866124 -275.378926)
		(width 0.0889)
		(layer "In2.Cu")
		(net "M_I_CPU1_SB_DQ<3>")
	)
	(segment
		(start 161.01314 -281.869896)
		(end 161.24174 -281.869896)
		(width 0.14478)
		(layer "In2.Cu")
		(net "M_I_CPU1_SB_DQ<3>")
	)
	(segment
		(start 159.663892 -280.87828)
		(end 159.663892 -281.10688)
		(width 0.14478)
		(layer "In2.Cu")
		(net "M_I_CPU1_SB_DQ<3>")
	)
	(segment
		(start 167.509952 -283.450284)
		(end 167.66032 -283.600652)
		(width 0.14478)
		(layer "In2.Cu")
		(net "M_I_CPU1_SB_DQ<3>")
	)
	(segment
		(start 128.524762 -275.706332)
		(end 128.370838 -275.440902)
		(width 0.0889)
		(layer "In2.Cu")
		(net "M_I_CPU1_SB_DQ<3>")
	)
	(segment
		(start 167.357298 -283.450284)
		(end 167.509952 -283.450284)
		(width 0.14478)
		(layer "In2.Cu")
		(net "M_I_CPU1_SB_DQ<3>")
	)
	(segment
		(start 139.617704 -275.383752)
		(end 139.626086 -275.378926)
		(width 0.0889)
		(layer "In2.Cu")
		(net "M_I_CPU1_SB_DQ<3>")
	)
	(segment
		(start 177.514758 -283.315664)
		(end 177.778918 -283.315664)
		(width 0.14478)
		(layer "In2.Cu")
		(net "M_I_CPU1_SB_DQ<3>")
	)
	(segment
		(start 160.461452 -281.089608)
		(end 160.622996 -281.251152)
		(width 0.14478)
		(layer "In2.Cu")
		(net "M_I_CPU1_SB_DQ<3>")
	)
	(segment
		(start 178.073558 -283.826204)
		(end 178.416458 -283.826204)
		(width 0.14478)
		(layer "In2.Cu")
		(net "M_I_CPU1_SB_DQ<3>")
	)
	(segment
		(start 143.377666 -275.383752)
		(end 143.386048 -275.378926)
		(width 0.0889)
		(layer "In2.Cu")
		(net "M_I_CPU1_SB_DQ<3>")
	)
	(segment
		(start 159.06242 -279.919176)
		(end 158.883604 -280.097992)
		(width 0.14478)
		(layer "In2.Cu")
		(net "M_I_CPU1_SB_DQ<3>")
	)
	(segment
		(start 159.273748 -280.488136)
		(end 159.452564 -280.30932)
		(width 0.14478)
		(layer "In2.Cu")
		(net "M_I_CPU1_SB_DQ<3>")
	)
	(segment
		(start 144.688306 -275.383752)
		(end 144.71777 -275.401024)
		(width 0.0889)
		(layer "In2.Cu")
		(net "M_I_CPU1_SB_DQ<3>")
	)
	(segment
		(start 146.834606 -274.258024)
		(end 147.442174 -274.258024)
		(width 0.0889)
		(layer "In2.Cu")
		(net "M_I_CPU1_SB_DQ<3>")
	)
	(segment
		(start 165.754558 -284.226)
		(end 166.01186 -284.332934)
		(width 0.14478)
		(layer "In2.Cu")
		(net "M_I_CPU1_SB_DQ<3>")
	)
	(segment
		(start 177.778918 -283.315664)
		(end 177.926238 -283.462984)
		(width 0.14478)
		(layer "In2.Cu")
		(net "M_I_CPU1_SB_DQ<3>")
	)
	(segment
		(start 160.44418 -281.658568)
		(end 160.44418 -281.887168)
		(width 0.14478)
		(layer "In2.Cu")
		(net "M_I_CPU1_SB_DQ<3>")
	)
	(segment
		(start 160.622996 -281.251152)
		(end 160.622996 -281.479752)
		(width 0.14478)
		(layer "In2.Cu")
		(net "M_I_CPU1_SB_DQ<3>")
	)
	(segment
		(start 142.803372 -275.378926)
		(end 142.811754 -275.383752)
		(width 0.0889)
		(layer "In2.Cu")
		(net "M_I_CPU1_SB_DQ<3>")
	)
	(segment
		(start 159.825436 -281.268424)
		(end 160.054036 -281.268424)
		(width 0.14478)
		(layer "In2.Cu")
		(net "M_I_CPU1_SB_DQ<3>")
	)
	(segment
		(start 166.452042 -283.825188)
		(end 167.357298 -283.450284)
		(width 0.14478)
		(layer "In2.Cu")
		(net "M_I_CPU1_SB_DQ<3>")
	)
	(segment
		(start 166.01186 -284.332934)
		(end 166.289482 -284.217872)
		(width 0.14478)
		(layer "In2.Cu")
		(net "M_I_CPU1_SB_DQ<3>")
	)
	(segment
		(start 165.212522 -284.450536)
		(end 165.754558 -284.226)
		(width 0.14478)
		(layer "In2.Cu")
		(net "M_I_CPU1_SB_DQ<3>")
	)
	(segment
		(start 134.917688 -275.383752)
		(end 134.92607 -275.378926)
		(width 0.0889)
		(layer "In2.Cu")
		(net "M_I_CPU1_SB_DQ<3>")
	)
	(segment
		(start 160.605724 -282.048712)
		(end 160.834324 -282.048712)
		(width 0.14478)
		(layer "In2.Cu")
		(net "M_I_CPU1_SB_DQ<3>")
	)
	(segment
		(start 160.232852 -281.089608)
		(end 160.461452 -281.089608)
		(width 0.14478)
		(layer "In2.Cu")
		(net "M_I_CPU1_SB_DQ<3>")
	)
	(segment
		(start 144.315688 -275.384006)
		(end 144.337532 -275.37156)
		(width 0.0889)
		(layer "In2.Cu")
		(net "M_I_CPU1_SB_DQ<3>")
	)
	(segment
		(start 160.834324 -282.048712)
		(end 161.01314 -281.869896)
		(width 0.14478)
		(layer "In2.Cu")
		(net "M_I_CPU1_SB_DQ<3>")
	)
	(segment
		(start 159.663892 -281.10688)
		(end 159.825436 -281.268424)
		(width 0.14478)
		(layer "In2.Cu")
		(net "M_I_CPU1_SB_DQ<3>")
	)
	(segment
		(start 145.81505 -275.08073)
		(end 146.188938 -274.903692)
		(width 0.0889)
		(layer "In2.Cu")
		(net "M_I_CPU1_SB_DQ<3>")
	)
	(segment
		(start 131.157726 -275.383752)
		(end 131.166108 -275.378926)
		(width 0.0889)
		(layer "In2.Cu")
		(net "M_I_CPU1_SB_DQ<3>")
	)
	(segment
		(start 179.091082 -283.610304)
		(end 179.516024 -284.035246)
		(width 0.14478)
		(layer "In2.Cu")
		(net "M_I_CPU1_SB_DQ<3>")
	)
	(segment
		(start 158.49346 -279.707848)
		(end 158.672276 -279.529032)
		(width 0.14478)
		(layer "In2.Cu")
		(net "M_I_CPU1_SB_DQ<3>")
	)
	(segment
		(start 174.475394 -283.600652)
		(end 177.22977 -283.600652)
		(width 0.14478)
		(layer "In2.Cu")
		(net "M_I_CPU1_SB_DQ<3>")
	)
	(segment
		(start 172.886624 -284.450536)
		(end 174.475394 -283.600652)
		(width 0.14478)
		(layer "In2.Cu")
		(net "M_I_CPU1_SB_DQ<3>")
	)
	(segment
		(start 129.643378 -275.378926)
		(end 129.65176 -275.383752)
		(width 0.0889)
		(layer "In2.Cu")
		(net "M_I_CPU1_SB_DQ<3>")
	)
	(segment
		(start 158.26486 -279.707848)
		(end 158.49346 -279.707848)
		(width 0.14478)
		(layer "In2.Cu")
		(net "M_I_CPU1_SB_DQ<3>")
	)
	(segment
		(start 140.557758 -275.383752)
		(end 140.56614 -275.378926)
		(width 0.0889)
		(layer "In2.Cu")
		(net "M_I_CPU1_SB_DQ<3>")
	)
	(segment
		(start 166.289482 -284.217872)
		(end 166.452042 -283.825188)
		(width 0.14478)
		(layer "In2.Cu")
		(net "M_I_CPU1_SB_DQ<3>")
	)
	(segment
		(start 177.22977 -283.600652)
		(end 177.514758 -283.315664)
		(width 0.14478)
		(layer "In2.Cu")
		(net "M_I_CPU1_SB_DQ<3>")
	)
	(segment
		(start 159.681164 -280.30932)
		(end 159.842708 -280.470864)
		(width 0.14478)
		(layer "In2.Cu")
		(net "M_I_CPU1_SB_DQ<3>")
	)
	(segment
		(start 139.04341 -275.378926)
		(end 139.051792 -275.383752)
		(width 0.0889)
		(layer "In2.Cu")
		(net "M_I_CPU1_SB_DQ<3>")
	)
	(segment
		(start 158.883604 -280.326592)
		(end 159.045148 -280.488136)
		(width 0.14478)
		(layer "In2.Cu")
		(net "M_I_CPU1_SB_DQ<3>")
	)
	(segment
		(start 158.672276 -279.529032)
		(end 158.900876 -279.529032)
		(width 0.14478)
		(layer "In2.Cu")
		(net "M_I_CPU1_SB_DQ<3>")
	)
	(segment
		(start 147.487894 -274.303744)
		(end 148.078698 -274.303744)
		(width 0.0889)
		(layer "In2.Cu")
		(net "M_I_CPU1_SB_DQ<3>")
	)
	(segment
		(start 158.900876 -279.529032)
		(end 159.06242 -279.690576)
		(width 0.14478)
		(layer "In2.Cu")
		(net "M_I_CPU1_SB_DQ<3>")
	)
	(segment
		(start 177.926238 -283.462984)
		(end 177.926238 -283.678884)
		(width 0.14478)
		(layer "In2.Cu")
		(net "M_I_CPU1_SB_DQ<3>")
	)
	(segment
		(start 160.054036 -281.268424)
		(end 160.232852 -281.089608)
		(width 0.14478)
		(layer "In2.Cu")
		(net "M_I_CPU1_SB_DQ<3>")
	)
	(segment
		(start 170.137836 -283.600652)
		(end 170.98772 -284.450536)
		(width 0.14478)
		(layer "In2.Cu")
		(net "M_I_CPU1_SB_DQ<3>")
	)
	(segment
		(start 128.370838 -275.440902)
		(end 128.39319 -275.35759)
		(width 0.0889)
		(layer "In2.Cu")
		(net "M_I_CPU1_SB_DQ<3>")
	)
	(segment
		(start 138.103356 -275.378926)
		(end 138.111738 -275.383752)
		(width 0.0889)
		(layer "In2.Cu")
		(net "M_I_CPU1_SB_DQ<3>")
	)
	(segment
		(start 130.583432 -275.378926)
		(end 130.591814 -275.383752)
		(width 0.0889)
		(layer "In2.Cu")
		(net "M_I_CPU1_SB_DQ<3>")
	)
	(segment
		(start 134.343394 -275.378926)
		(end 134.351776 -275.383752)
		(width 0.0889)
		(layer "In2.Cu")
		(net "M_I_CPU1_SB_DQ<3>")
	)
	(segment
		(start 161.403284 -282.03144)
		(end 161.403284 -282.237688)
		(width 0.14478)
		(layer "In2.Cu")
		(net "M_I_CPU1_SB_DQ<3>")
	)
	(segment
		(start 160.622996 -281.479752)
		(end 160.44418 -281.658568)
		(width 0.14478)
		(layer "In2.Cu")
		(net "M_I_CPU1_SB_DQ<3>")
	)
	(segment
		(start 144.289526 -275.398992)
		(end 144.315688 -275.384006)
		(width 0.0889)
		(layer "In2.Cu")
		(net "M_I_CPU1_SB_DQ<3>")
	)
	(segment
		(start 161.24174 -281.869896)
		(end 161.403284 -282.03144)
		(width 0.14478)
		(layer "In2.Cu")
		(net "M_I_CPU1_SB_DQ<3>")
	)
	(segment
		(start 159.045148 -280.488136)
		(end 159.273748 -280.488136)
		(width 0.14478)
		(layer "In2.Cu")
		(net "M_I_CPU1_SB_DQ<3>")
	)
	(segment
		(start 161.403284 -282.237688)
		(end 163.616132 -284.450536)
		(width 0.14478)
		(layer "In2.Cu")
		(net "M_I_CPU1_SB_DQ<3>")
	)
	(arc
		(start 137.737596 -275.383752)
		(mid 137.919847 -275.333402)
		(end 138.103356 -275.378926)
		(width 0.0889)
		(layer "In2.Cu")
		(net "M_I_CPU1_SB_DQ<3>")
	)
	(arc
		(start 128.39319 -275.35759)
		(mid 128.555379 -275.334855)
		(end 128.711706 -275.383752)
		(width 0.0889)
		(layer "In2.Cu")
		(net "M_I_CPU1_SB_DQ<3>")
	)
	(arc
		(start 133.977634 -275.383752)
		(mid 134.159885 -275.333402)
		(end 134.343394 -275.378926)
		(width 0.0889)
		(layer "In2.Cu")
		(net "M_I_CPU1_SB_DQ<3>")
	)
	(arc
		(start 144.337532 -275.37156)
		(mid 144.51446 -275.333732)
		(end 144.688306 -275.383752)
		(width 0.0889)
		(layer "In2.Cu")
		(net "M_I_CPU1_SB_DQ<3>")
	)
	(arc
		(start 130.591814 -275.383752)
		(mid 130.87477 -275.459929)
		(end 131.157726 -275.383752)
		(width 0.0889)
		(layer "In2.Cu")
		(net "M_I_CPU1_SB_DQ<3>")
	)
	(arc
		(start 133.037834 -275.383752)
		(mid 133.224778 -275.333497)
		(end 133.411722 -275.383752)
		(width 0.0889)
		(layer "In2.Cu")
		(net "M_I_CPU1_SB_DQ<3>")
	)
	(arc
		(start 139.991846 -275.383752)
		(mid 140.274802 -275.459929)
		(end 140.557758 -275.383752)
		(width 0.0889)
		(layer "In2.Cu")
		(net "M_I_CPU1_SB_DQ<3>")
	)
	(arc
		(start 142.811754 -275.383752)
		(mid 143.09471 -275.459929)
		(end 143.377666 -275.383752)
		(width 0.0889)
		(layer "In2.Cu")
		(net "M_I_CPU1_SB_DQ<3>")
	)
	(arc
		(start 136.797796 -275.383752)
		(mid 136.98474 -275.333497)
		(end 137.171684 -275.383752)
		(width 0.0889)
		(layer "In2.Cu")
		(net "M_I_CPU1_SB_DQ<3>")
	)
	(arc
		(start 139.626086 -275.378926)
		(mid 139.809594 -275.333432)
		(end 139.991846 -275.383752)
		(width 0.0889)
		(layer "In2.Cu")
		(net "M_I_CPU1_SB_DQ<3>")
	)
	(arc
		(start 141.497812 -275.383752)
		(mid 141.684756 -275.333497)
		(end 141.8717 -275.383752)
		(width 0.0889)
		(layer "In2.Cu")
		(net "M_I_CPU1_SB_DQ<3>")
	)
	(arc
		(start 143.386048 -275.378926)
		(mid 143.569556 -275.333432)
		(end 143.751808 -275.383752)
		(width 0.0889)
		(layer "In2.Cu")
		(net "M_I_CPU1_SB_DQ<3>")
	)
	(arc
		(start 136.231884 -275.383752)
		(mid 136.51484 -275.459929)
		(end 136.797796 -275.383752)
		(width 0.0889)
		(layer "In2.Cu")
		(net "M_I_CPU1_SB_DQ<3>")
	)
	(arc
		(start 129.277618 -275.383752)
		(mid 129.459869 -275.333402)
		(end 129.643378 -275.378926)
		(width 0.0889)
		(layer "In2.Cu")
		(net "M_I_CPU1_SB_DQ<3>")
	)
	(arc
		(start 137.171684 -275.383752)
		(mid 137.45464 -275.459929)
		(end 137.737596 -275.383752)
		(width 0.0889)
		(layer "In2.Cu")
		(net "M_I_CPU1_SB_DQ<3>")
	)
	(arc
		(start 129.65176 -275.383752)
		(mid 129.934716 -275.459929)
		(end 130.217672 -275.383752)
		(width 0.0889)
		(layer "In2.Cu")
		(net "M_I_CPU1_SB_DQ<3>")
	)
	(arc
		(start 134.351776 -275.383752)
		(mid 134.634732 -275.459929)
		(end 134.917688 -275.383752)
		(width 0.0889)
		(layer "In2.Cu")
		(net "M_I_CPU1_SB_DQ<3>")
	)
	(arc
		(start 135.866124 -275.378926)
		(mid 136.049632 -275.333432)
		(end 136.231884 -275.383752)
		(width 0.0889)
		(layer "In2.Cu")
		(net "M_I_CPU1_SB_DQ<3>")
	)
	(arc
		(start 132.106162 -275.378926)
		(mid 132.28967 -275.333432)
		(end 132.471922 -275.383752)
		(width 0.0889)
		(layer "In2.Cu")
		(net "M_I_CPU1_SB_DQ<3>")
	)
	(arc
		(start 144.71777 -275.401024)
		(mid 144.98919 -275.460701)
		(end 145.25625 -275.383752)
		(width 0.0889)
		(layer "In2.Cu")
		(net "M_I_CPU1_SB_DQ<3>")
	)
	(arc
		(start 143.751808 -275.383752)
		(mid 144.018738 -275.459701)
		(end 144.289526 -275.398992)
		(width 0.0889)
		(layer "In2.Cu")
		(net "M_I_CPU1_SB_DQ<3>")
	)
	(arc
		(start 139.051792 -275.383752)
		(mid 139.334748 -275.459929)
		(end 139.617704 -275.383752)
		(width 0.0889)
		(layer "In2.Cu")
		(net "M_I_CPU1_SB_DQ<3>")
	)
	(arc
		(start 140.56614 -275.378926)
		(mid 140.749648 -275.333432)
		(end 140.9319 -275.383752)
		(width 0.0889)
		(layer "In2.Cu")
		(net "M_I_CPU1_SB_DQ<3>")
	)
	(arc
		(start 130.217672 -275.383752)
		(mid 130.399923 -275.333402)
		(end 130.583432 -275.378926)
		(width 0.0889)
		(layer "In2.Cu")
		(net "M_I_CPU1_SB_DQ<3>")
	)
	(arc
		(start 140.9319 -275.383752)
		(mid 141.214856 -275.459929)
		(end 141.497812 -275.383752)
		(width 0.0889)
		(layer "In2.Cu")
		(net "M_I_CPU1_SB_DQ<3>")
	)
	(arc
		(start 134.92607 -275.378926)
		(mid 135.109578 -275.333432)
		(end 135.29183 -275.383752)
		(width 0.0889)
		(layer "In2.Cu")
		(net "M_I_CPU1_SB_DQ<3>")
	)
	(arc
		(start 142.437612 -275.383752)
		(mid 142.619863 -275.333402)
		(end 142.803372 -275.378926)
		(width 0.0889)
		(layer "In2.Cu")
		(net "M_I_CPU1_SB_DQ<3>")
	)
	(arc
		(start 132.471922 -275.383752)
		(mid 132.754878 -275.459929)
		(end 133.037834 -275.383752)
		(width 0.0889)
		(layer "In2.Cu")
		(net "M_I_CPU1_SB_DQ<3>")
	)
	(arc
		(start 141.8717 -275.383752)
		(mid 142.154656 -275.459929)
		(end 142.437612 -275.383752)
		(width 0.0889)
		(layer "In2.Cu")
		(net "M_I_CPU1_SB_DQ<3>")
	)
	(arc
		(start 128.711706 -275.383752)
		(mid 128.994662 -275.459929)
		(end 129.277618 -275.383752)
		(width 0.0889)
		(layer "In2.Cu")
		(net "M_I_CPU1_SB_DQ<3>")
	)
	(arc
		(start 131.166108 -275.378926)
		(mid 131.349616 -275.333432)
		(end 131.531868 -275.383752)
		(width 0.0889)
		(layer "In2.Cu")
		(net "M_I_CPU1_SB_DQ<3>")
	)
	(arc
		(start 133.411722 -275.383752)
		(mid 133.694678 -275.459929)
		(end 133.977634 -275.383752)
		(width 0.0889)
		(layer "In2.Cu")
		(net "M_I_CPU1_SB_DQ<3>")
	)
	(arc
		(start 138.111738 -275.383752)
		(mid 138.394694 -275.459929)
		(end 138.67765 -275.383752)
		(width 0.0889)
		(layer "In2.Cu")
		(net "M_I_CPU1_SB_DQ<3>")
	)
	(arc
		(start 138.67765 -275.383752)
		(mid 138.859901 -275.333402)
		(end 139.04341 -275.378926)
		(width 0.0889)
		(layer "In2.Cu")
		(net "M_I_CPU1_SB_DQ<3>")
	)
	(arc
		(start 131.531868 -275.383752)
		(mid 131.814824 -275.459929)
		(end 132.09778 -275.383752)
		(width 0.0889)
		(layer "In2.Cu")
		(net "M_I_CPU1_SB_DQ<3>")
	)
	(arc
		(start 135.29183 -275.383752)
		(mid 135.574786 -275.459929)
		(end 135.857742 -275.383752)
		(width 0.0889)
		(layer "In2.Cu")
		(net "M_I_CPU1_SB_DQ<3>")
	)
	(segment
		(start 128.05791 -293.260272)
		(end 128.524762 -293.52621)
		(width 0.10668)
		(layer "F.Cu")
		(net "M_I_CPU1_SB_DQ<31>")
	)
	(segment
		(start 138.103356 -293.198804)
		(end 138.111738 -293.20363)
		(width 0.0889)
		(layer "In2.Cu")
		(net "M_I_CPU1_SB_DQ<31>")
	)
	(segment
		(start 154.138122 -310.834024)
		(end 154.300174 -310.996076)
		(width 0.14478)
		(layer "In2.Cu")
		(net "M_I_CPU1_SB_DQ<31>")
	)
	(segment
		(start 155.86075 -312.556652)
		(end 156.089096 -312.556652)
		(width 0.14478)
		(layer "In2.Cu")
		(net "M_I_CPU1_SB_DQ<31>")
	)
	(segment
		(start 153.748232 -310.215788)
		(end 153.868882 -310.095138)
		(width 0.14478)
		(layer "In2.Cu")
		(net "M_I_CPU1_SB_DQ<31>")
	)
	(segment
		(start 140.557758 -293.20363)
		(end 140.56614 -293.198804)
		(width 0.0889)
		(layer "In2.Cu")
		(net "M_I_CPU1_SB_DQ<31>")
	)
	(segment
		(start 139.617704 -293.20363)
		(end 139.626086 -293.198804)
		(width 0.0889)
		(layer "In2.Cu")
		(net "M_I_CPU1_SB_DQ<31>")
	)
	(segment
		(start 152.69845 -308.696614)
		(end 152.69845 -308.924706)
		(width 0.14478)
		(layer "In2.Cu")
		(net "M_I_CPU1_SB_DQ<31>")
	)
	(segment
		(start 155.039314 -311.037478)
		(end 155.039314 -311.26557)
		(width 0.14478)
		(layer "In2.Cu")
		(net "M_I_CPU1_SB_DQ<31>")
	)
	(segment
		(start 134.343394 -293.198804)
		(end 134.351776 -293.20363)
		(width 0.0889)
		(layer "In2.Cu")
		(net "M_I_CPU1_SB_DQ<31>")
	)
	(segment
		(start 135.857742 -293.20363)
		(end 135.866124 -293.198804)
		(width 0.0889)
		(layer "In2.Cu")
		(net "M_I_CPU1_SB_DQ<31>")
	)
	(segment
		(start 153.478738 -309.704994)
		(end 153.357834 -309.825644)
		(width 0.14478)
		(layer "In2.Cu")
		(net "M_I_CPU1_SB_DQ<31>")
	)
	(segment
		(start 152.577546 -309.273448)
		(end 152.739598 -309.4355)
		(width 0.14478)
		(layer "In2.Cu")
		(net "M_I_CPU1_SB_DQ<31>")
	)
	(segment
		(start 156.59989 -312.826146)
		(end 156.478986 -312.946796)
		(width 0.14478)
		(layer "In2.Cu")
		(net "M_I_CPU1_SB_DQ<31>")
	)
	(segment
		(start 163.595304 -318.460374)
		(end 179.091082 -318.460374)
		(width 0.14478)
		(layer "In2.Cu")
		(net "M_I_CPU1_SB_DQ<31>")
	)
	(segment
		(start 154.096974 -310.095138)
		(end 154.259026 -310.25719)
		(width 0.14478)
		(layer "In2.Cu")
		(net "M_I_CPU1_SB_DQ<31>")
	)
	(segment
		(start 143.319246 -296.620438)
		(end 143.319246 -297.173396)
		(width 0.14478)
		(layer "In2.Cu")
		(net "M_I_CPU1_SB_DQ<31>")
	)
	(segment
		(start 128.524762 -293.52621)
		(end 128.370838 -293.26078)
		(width 0.0889)
		(layer "In2.Cu")
		(net "M_I_CPU1_SB_DQ<31>")
	)
	(segment
		(start 153.519886 -310.215788)
		(end 153.748232 -310.215788)
		(width 0.14478)
		(layer "In2.Cu")
		(net "M_I_CPU1_SB_DQ<31>")
	)
	(segment
		(start 155.819602 -311.817766)
		(end 155.819602 -312.045858)
		(width 0.14478)
		(layer "In2.Cu")
		(net "M_I_CPU1_SB_DQ<31>")
	)
	(segment
		(start 145.328894 -302.024796)
		(end 151.95931 -308.655212)
		(width 0.14478)
		(layer "In2.Cu")
		(net "M_I_CPU1_SB_DQ<31>")
	)
	(segment
		(start 152.69845 -308.924706)
		(end 152.577546 -309.045356)
		(width 0.14478)
		(layer "In2.Cu")
		(net "M_I_CPU1_SB_DQ<31>")
	)
	(segment
		(start 143.46936 -296.470324)
		(end 143.319246 -296.620438)
		(width 0.0889)
		(layer "In2.Cu")
		(net "M_I_CPU1_SB_DQ<31>")
	)
	(segment
		(start 156.089096 -312.556652)
		(end 156.209746 -312.436002)
		(width 0.14478)
		(layer "In2.Cu")
		(net "M_I_CPU1_SB_DQ<31>")
	)
	(segment
		(start 154.52852 -310.996076)
		(end 154.64917 -310.875426)
		(width 0.14478)
		(layer "In2.Cu")
		(net "M_I_CPU1_SB_DQ<31>")
	)
	(segment
		(start 143.281654 -295.633648)
		(end 143.313404 -295.651936)
		(width 0.0889)
		(layer "In2.Cu")
		(net "M_I_CPU1_SB_DQ<31>")
	)
	(segment
		(start 134.917688 -293.20363)
		(end 134.92607 -293.198804)
		(width 0.0889)
		(layer "In2.Cu")
		(net "M_I_CPU1_SB_DQ<31>")
	)
	(segment
		(start 153.316686 -309.31485)
		(end 153.478738 -309.476902)
		(width 0.14478)
		(layer "In2.Cu")
		(net "M_I_CPU1_SB_DQ<31>")
	)
	(segment
		(start 154.259026 -310.485282)
		(end 154.138122 -310.605932)
		(width 0.14478)
		(layer "In2.Cu")
		(net "M_I_CPU1_SB_DQ<31>")
	)
	(segment
		(start 143.46936 -295.956228)
		(end 143.46936 -296.470324)
		(width 0.0889)
		(layer "In2.Cu")
		(net "M_I_CPU1_SB_DQ<31>")
	)
	(segment
		(start 155.819602 -312.045858)
		(end 155.698698 -312.166508)
		(width 0.14478)
		(layer "In2.Cu")
		(net "M_I_CPU1_SB_DQ<31>")
	)
	(segment
		(start 152.308306 -308.534562)
		(end 152.536398 -308.534562)
		(width 0.14478)
		(layer "In2.Cu")
		(net "M_I_CPU1_SB_DQ<31>")
	)
	(segment
		(start 143.245332 -295.612566)
		(end 143.281654 -295.633648)
		(width 0.0889)
		(layer "In2.Cu")
		(net "M_I_CPU1_SB_DQ<31>")
	)
	(segment
		(start 131.157726 -293.20363)
		(end 131.166108 -293.198804)
		(width 0.0889)
		(layer "In2.Cu")
		(net "M_I_CPU1_SB_DQ<31>")
	)
	(segment
		(start 142.341854 -294.013636)
		(end 142.372334 -294.031416)
		(width 0.0889)
		(layer "In2.Cu")
		(net "M_I_CPU1_SB_DQ<31>")
	)
	(segment
		(start 153.478738 -309.476902)
		(end 153.478738 -309.704994)
		(width 0.14478)
		(layer "In2.Cu")
		(net "M_I_CPU1_SB_DQ<31>")
	)
	(segment
		(start 156.209746 -312.436002)
		(end 156.437838 -312.436002)
		(width 0.14478)
		(layer "In2.Cu")
		(net "M_I_CPU1_SB_DQ<31>")
	)
	(segment
		(start 155.698698 -312.3946)
		(end 155.86075 -312.556652)
		(width 0.14478)
		(layer "In2.Cu")
		(net "M_I_CPU1_SB_DQ<31>")
	)
	(segment
		(start 154.300174 -310.996076)
		(end 154.52852 -310.996076)
		(width 0.14478)
		(layer "In2.Cu")
		(net "M_I_CPU1_SB_DQ<31>")
	)
	(segment
		(start 156.478986 -312.946796)
		(end 156.478986 -313.174888)
		(width 0.14478)
		(layer "In2.Cu")
		(net "M_I_CPU1_SB_DQ<31>")
	)
	(segment
		(start 128.370838 -293.26078)
		(end 128.39319 -293.177468)
		(width 0.0889)
		(layer "In2.Cu")
		(net "M_I_CPU1_SB_DQ<31>")
	)
	(segment
		(start 151.95931 -308.655212)
		(end 152.187656 -308.655212)
		(width 0.14478)
		(layer "In2.Cu")
		(net "M_I_CPU1_SB_DQ<31>")
	)
	(segment
		(start 155.308808 -311.776364)
		(end 155.429458 -311.655714)
		(width 0.14478)
		(layer "In2.Cu")
		(net "M_I_CPU1_SB_DQ<31>")
	)
	(segment
		(start 152.536398 -308.534562)
		(end 152.69845 -308.696614)
		(width 0.14478)
		(layer "In2.Cu")
		(net "M_I_CPU1_SB_DQ<31>")
	)
	(segment
		(start 154.259026 -310.25719)
		(end 154.259026 -310.485282)
		(width 0.14478)
		(layer "In2.Cu")
		(net "M_I_CPU1_SB_DQ<31>")
	)
	(segment
		(start 156.478986 -313.174888)
		(end 160.470088 -317.16599)
		(width 0.14478)
		(layer "In2.Cu")
		(net "M_I_CPU1_SB_DQ<31>")
	)
	(segment
		(start 156.437838 -312.436002)
		(end 156.59989 -312.598054)
		(width 0.14478)
		(layer "In2.Cu")
		(net "M_I_CPU1_SB_DQ<31>")
	)
	(segment
		(start 129.643378 -293.198804)
		(end 129.65176 -293.20363)
		(width 0.0889)
		(layer "In2.Cu")
		(net "M_I_CPU1_SB_DQ<31>")
	)
	(segment
		(start 154.64917 -310.875426)
		(end 154.877262 -310.875426)
		(width 0.14478)
		(layer "In2.Cu")
		(net "M_I_CPU1_SB_DQ<31>")
	)
	(segment
		(start 154.877262 -310.875426)
		(end 155.039314 -311.037478)
		(width 0.14478)
		(layer "In2.Cu")
		(net "M_I_CPU1_SB_DQ<31>")
	)
	(segment
		(start 156.59989 -312.598054)
		(end 156.59989 -312.826146)
		(width 0.14478)
		(layer "In2.Cu")
		(net "M_I_CPU1_SB_DQ<31>")
	)
	(segment
		(start 153.357834 -309.825644)
		(end 153.357834 -310.053736)
		(width 0.14478)
		(layer "In2.Cu")
		(net "M_I_CPU1_SB_DQ<31>")
	)
	(segment
		(start 139.04341 -293.198804)
		(end 139.051792 -293.20363)
		(width 0.0889)
		(layer "In2.Cu")
		(net "M_I_CPU1_SB_DQ<31>")
	)
	(segment
		(start 142.772638 -294.800782)
		(end 142.811754 -294.823642)
		(width 0.0889)
		(layer "In2.Cu")
		(net "M_I_CPU1_SB_DQ<31>")
	)
	(segment
		(start 152.577546 -309.045356)
		(end 152.577546 -309.273448)
		(width 0.14478)
		(layer "In2.Cu")
		(net "M_I_CPU1_SB_DQ<31>")
	)
	(segment
		(start 154.138122 -310.605932)
		(end 154.138122 -310.834024)
		(width 0.14478)
		(layer "In2.Cu")
		(net "M_I_CPU1_SB_DQ<31>")
	)
	(segment
		(start 143.319246 -297.173396)
		(end 145.328894 -302.024796)
		(width 0.14478)
		(layer "In2.Cu")
		(net "M_I_CPU1_SB_DQ<31>")
	)
	(segment
		(start 141.8717 -293.20363)
		(end 141.90345 -293.221918)
		(width 0.0889)
		(layer "In2.Cu")
		(net "M_I_CPU1_SB_DQ<31>")
	)
	(segment
		(start 153.088594 -309.31485)
		(end 153.316686 -309.31485)
		(width 0.14478)
		(layer "In2.Cu")
		(net "M_I_CPU1_SB_DQ<31>")
	)
	(segment
		(start 152.187656 -308.655212)
		(end 152.308306 -308.534562)
		(width 0.14478)
		(layer "In2.Cu")
		(net "M_I_CPU1_SB_DQ<31>")
	)
	(segment
		(start 179.091082 -318.460374)
		(end 179.516024 -318.035432)
		(width 0.14478)
		(layer "In2.Cu")
		(net "M_I_CPU1_SB_DQ<31>")
	)
	(segment
		(start 153.357834 -310.053736)
		(end 153.519886 -310.215788)
		(width 0.14478)
		(layer "In2.Cu")
		(net "M_I_CPU1_SB_DQ<31>")
	)
	(segment
		(start 142.811754 -294.823642)
		(end 142.843504 -294.84193)
		(width 0.0889)
		(layer "In2.Cu")
		(net "M_I_CPU1_SB_DQ<31>")
	)
	(segment
		(start 154.91841 -311.614312)
		(end 155.080462 -311.776364)
		(width 0.14478)
		(layer "In2.Cu")
		(net "M_I_CPU1_SB_DQ<31>")
	)
	(segment
		(start 152.739598 -309.4355)
		(end 152.967944 -309.4355)
		(width 0.14478)
		(layer "In2.Cu")
		(net "M_I_CPU1_SB_DQ<31>")
	)
	(segment
		(start 160.470088 -317.16599)
		(end 163.595304 -318.460374)
		(width 0.14478)
		(layer "In2.Cu")
		(net "M_I_CPU1_SB_DQ<31>")
	)
	(segment
		(start 142.302738 -293.990776)
		(end 142.341854 -294.013636)
		(width 0.0889)
		(layer "In2.Cu")
		(net "M_I_CPU1_SB_DQ<31>")
	)
	(segment
		(start 153.868882 -310.095138)
		(end 154.096974 -310.095138)
		(width 0.14478)
		(layer "In2.Cu")
		(net "M_I_CPU1_SB_DQ<31>")
	)
	(segment
		(start 130.583432 -293.198804)
		(end 130.591814 -293.20363)
		(width 0.0889)
		(layer "In2.Cu")
		(net "M_I_CPU1_SB_DQ<31>")
	)
	(segment
		(start 155.039314 -311.26557)
		(end 154.91841 -311.38622)
		(width 0.14478)
		(layer "In2.Cu")
		(net "M_I_CPU1_SB_DQ<31>")
	)
	(segment
		(start 155.429458 -311.655714)
		(end 155.65755 -311.655714)
		(width 0.14478)
		(layer "In2.Cu")
		(net "M_I_CPU1_SB_DQ<31>")
	)
	(segment
		(start 152.967944 -309.4355)
		(end 153.088594 -309.31485)
		(width 0.14478)
		(layer "In2.Cu")
		(net "M_I_CPU1_SB_DQ<31>")
	)
	(segment
		(start 155.698698 -312.166508)
		(end 155.698698 -312.3946)
		(width 0.14478)
		(layer "In2.Cu")
		(net "M_I_CPU1_SB_DQ<31>")
	)
	(segment
		(start 155.080462 -311.776364)
		(end 155.308808 -311.776364)
		(width 0.14478)
		(layer "In2.Cu")
		(net "M_I_CPU1_SB_DQ<31>")
	)
	(segment
		(start 132.09778 -293.20363)
		(end 132.106162 -293.198804)
		(width 0.0889)
		(layer "In2.Cu")
		(net "M_I_CPU1_SB_DQ<31>")
	)
	(segment
		(start 155.65755 -311.655714)
		(end 155.819602 -311.817766)
		(width 0.14478)
		(layer "In2.Cu")
		(net "M_I_CPU1_SB_DQ<31>")
	)
	(segment
		(start 154.91841 -311.38622)
		(end 154.91841 -311.614312)
		(width 0.14478)
		(layer "In2.Cu")
		(net "M_I_CPU1_SB_DQ<31>")
	)
	(arc
		(start 130.217672 -293.20363)
		(mid 130.399923 -293.15328)
		(end 130.583432 -293.198804)
		(width 0.0889)
		(layer "In2.Cu")
		(net "M_I_CPU1_SB_DQ<31>")
	)
	(arc
		(start 141.90345 -293.221918)
		(mid 142.018126 -293.355252)
		(end 142.059406 -293.52621)
		(width 0.0889)
		(layer "In2.Cu")
		(net "M_I_CPU1_SB_DQ<31>")
	)
	(arc
		(start 134.351776 -293.20363)
		(mid 134.634732 -293.279807)
		(end 134.917688 -293.20363)
		(width 0.0889)
		(layer "In2.Cu")
		(net "M_I_CPU1_SB_DQ<31>")
	)
	(arc
		(start 130.591814 -293.20363)
		(mid 130.87477 -293.279807)
		(end 131.157726 -293.20363)
		(width 0.0889)
		(layer "In2.Cu")
		(net "M_I_CPU1_SB_DQ<31>")
	)
	(arc
		(start 135.29183 -293.20363)
		(mid 135.574786 -293.279807)
		(end 135.857742 -293.20363)
		(width 0.0889)
		(layer "In2.Cu")
		(net "M_I_CPU1_SB_DQ<31>")
	)
	(arc
		(start 137.171684 -293.20363)
		(mid 137.45464 -293.279807)
		(end 137.737596 -293.20363)
		(width 0.0889)
		(layer "In2.Cu")
		(net "M_I_CPU1_SB_DQ<31>")
	)
	(arc
		(start 138.67765 -293.20363)
		(mid 138.859901 -293.15328)
		(end 139.04341 -293.198804)
		(width 0.0889)
		(layer "In2.Cu")
		(net "M_I_CPU1_SB_DQ<31>")
	)
	(arc
		(start 132.106162 -293.198804)
		(mid 132.28967 -293.15331)
		(end 132.471922 -293.20363)
		(width 0.0889)
		(layer "In2.Cu")
		(net "M_I_CPU1_SB_DQ<31>")
	)
	(arc
		(start 133.037834 -293.20363)
		(mid 133.224778 -293.153375)
		(end 133.411722 -293.20363)
		(width 0.0889)
		(layer "In2.Cu")
		(net "M_I_CPU1_SB_DQ<31>")
	)
	(arc
		(start 139.051792 -293.20363)
		(mid 139.334748 -293.279807)
		(end 139.617704 -293.20363)
		(width 0.0889)
		(layer "In2.Cu")
		(net "M_I_CPU1_SB_DQ<31>")
	)
	(arc
		(start 133.977634 -293.20363)
		(mid 134.159885 -293.15328)
		(end 134.343394 -293.198804)
		(width 0.0889)
		(layer "In2.Cu")
		(net "M_I_CPU1_SB_DQ<31>")
	)
	(arc
		(start 136.797796 -293.20363)
		(mid 136.98474 -293.153375)
		(end 137.171684 -293.20363)
		(width 0.0889)
		(layer "In2.Cu")
		(net "M_I_CPU1_SB_DQ<31>")
	)
	(arc
		(start 140.56614 -293.198804)
		(mid 140.749648 -293.15331)
		(end 140.9319 -293.20363)
		(width 0.0889)
		(layer "In2.Cu")
		(net "M_I_CPU1_SB_DQ<31>")
	)
	(arc
		(start 142.372334 -294.031416)
		(mid 142.487761 -294.164792)
		(end 142.529306 -294.336216)
		(width 0.0889)
		(layer "In2.Cu")
		(net "M_I_CPU1_SB_DQ<31>")
	)
	(arc
		(start 142.99946 -295.146222)
		(mid 143.064696 -295.409813)
		(end 143.245332 -295.612566)
		(width 0.0889)
		(layer "In2.Cu")
		(net "M_I_CPU1_SB_DQ<31>")
	)
	(arc
		(start 136.231884 -293.20363)
		(mid 136.51484 -293.279807)
		(end 136.797796 -293.20363)
		(width 0.0889)
		(layer "In2.Cu")
		(net "M_I_CPU1_SB_DQ<31>")
	)
	(arc
		(start 131.166108 -293.198804)
		(mid 131.349616 -293.15331)
		(end 131.531868 -293.20363)
		(width 0.0889)
		(layer "In2.Cu")
		(net "M_I_CPU1_SB_DQ<31>")
	)
	(arc
		(start 134.92607 -293.198804)
		(mid 135.109578 -293.15331)
		(end 135.29183 -293.20363)
		(width 0.0889)
		(layer "In2.Cu")
		(net "M_I_CPU1_SB_DQ<31>")
	)
	(arc
		(start 139.626086 -293.198804)
		(mid 139.809594 -293.15331)
		(end 139.991846 -293.20363)
		(width 0.0889)
		(layer "In2.Cu")
		(net "M_I_CPU1_SB_DQ<31>")
	)
	(arc
		(start 128.39319 -293.177468)
		(mid 128.555379 -293.154733)
		(end 128.711706 -293.20363)
		(width 0.0889)
		(layer "In2.Cu")
		(net "M_I_CPU1_SB_DQ<31>")
	)
	(arc
		(start 139.991846 -293.20363)
		(mid 140.274802 -293.279807)
		(end 140.557758 -293.20363)
		(width 0.0889)
		(layer "In2.Cu")
		(net "M_I_CPU1_SB_DQ<31>")
	)
	(arc
		(start 128.711706 -293.20363)
		(mid 128.994662 -293.279807)
		(end 129.277618 -293.20363)
		(width 0.0889)
		(layer "In2.Cu")
		(net "M_I_CPU1_SB_DQ<31>")
	)
	(arc
		(start 143.313404 -295.651936)
		(mid 143.42808 -295.78527)
		(end 143.46936 -295.956228)
		(width 0.0889)
		(layer "In2.Cu")
		(net "M_I_CPU1_SB_DQ<31>")
	)
	(arc
		(start 140.9319 -293.20363)
		(mid 141.214856 -293.279807)
		(end 141.497812 -293.20363)
		(width 0.0889)
		(layer "In2.Cu")
		(net "M_I_CPU1_SB_DQ<31>")
	)
	(arc
		(start 138.111738 -293.20363)
		(mid 138.394694 -293.279807)
		(end 138.67765 -293.20363)
		(width 0.0889)
		(layer "In2.Cu")
		(net "M_I_CPU1_SB_DQ<31>")
	)
	(arc
		(start 135.866124 -293.198804)
		(mid 136.049632 -293.15331)
		(end 136.231884 -293.20363)
		(width 0.0889)
		(layer "In2.Cu")
		(net "M_I_CPU1_SB_DQ<31>")
	)
	(arc
		(start 129.65176 -293.20363)
		(mid 129.934716 -293.279807)
		(end 130.217672 -293.20363)
		(width 0.0889)
		(layer "In2.Cu")
		(net "M_I_CPU1_SB_DQ<31>")
	)
	(arc
		(start 137.737596 -293.20363)
		(mid 137.919847 -293.15328)
		(end 138.103356 -293.198804)
		(width 0.0889)
		(layer "In2.Cu")
		(net "M_I_CPU1_SB_DQ<31>")
	)
	(arc
		(start 142.059406 -293.52621)
		(mid 142.123921 -293.788429)
		(end 142.302738 -293.990776)
		(width 0.0889)
		(layer "In2.Cu")
		(net "M_I_CPU1_SB_DQ<31>")
	)
	(arc
		(start 141.497812 -293.20363)
		(mid 141.684756 -293.153375)
		(end 141.8717 -293.20363)
		(width 0.0889)
		(layer "In2.Cu")
		(net "M_I_CPU1_SB_DQ<31>")
	)
	(arc
		(start 131.531868 -293.20363)
		(mid 131.814824 -293.279807)
		(end 132.09778 -293.20363)
		(width 0.0889)
		(layer "In2.Cu")
		(net "M_I_CPU1_SB_DQ<31>")
	)
	(arc
		(start 133.411722 -293.20363)
		(mid 133.694678 -293.279807)
		(end 133.977634 -293.20363)
		(width 0.0889)
		(layer "In2.Cu")
		(net "M_I_CPU1_SB_DQ<31>")
	)
	(arc
		(start 142.529306 -294.336216)
		(mid 142.593821 -294.598435)
		(end 142.772638 -294.800782)
		(width 0.0889)
		(layer "In2.Cu")
		(net "M_I_CPU1_SB_DQ<31>")
	)
	(arc
		(start 129.277618 -293.20363)
		(mid 129.459869 -293.15328)
		(end 129.643378 -293.198804)
		(width 0.0889)
		(layer "In2.Cu")
		(net "M_I_CPU1_SB_DQ<31>")
	)
	(arc
		(start 132.471922 -293.20363)
		(mid 132.754878 -293.279807)
		(end 133.037834 -293.20363)
		(width 0.0889)
		(layer "In2.Cu")
		(net "M_I_CPU1_SB_DQ<31>")
	)
	(arc
		(start 142.843504 -294.84193)
		(mid 142.95818 -294.975264)
		(end 142.99946 -295.146222)
		(width 0.0889)
		(layer "In2.Cu")
		(net "M_I_CPU1_SB_DQ<31>")
	)
	(segment
		(start 129.467864 -292.450266)
		(end 129.934716 -292.716204)
		(width 0.10668)
		(layer "F.Cu")
		(net "M_I_CPU1_SB_DQ<30>")
	)
	(segment
		(start 170.395138 -316.457584)
		(end 170.65117 -316.457584)
		(width 0.14478)
		(layer "In2.Cu")
		(net "M_I_CPU1_SB_DQ<30>")
	)
	(segment
		(start 166.549832 -316.760352)
		(end 166.84498 -316.465204)
		(width 0.14478)
		(layer "In2.Cu")
		(net "M_I_CPU1_SB_DQ<30>")
	)
	(segment
		(start 132.93344 -292.388798)
		(end 132.941822 -292.393624)
		(width 0.0889)
		(layer "In2.Cu")
		(net "M_I_CPU1_SB_DQ<30>")
	)
	(segment
		(start 175.014382 -316.760352)
		(end 177.211736 -316.760352)
		(width 0.14478)
		(layer "In2.Cu")
		(net "M_I_CPU1_SB_DQ<30>")
	)
	(segment
		(start 161.778696 -316.457584)
		(end 162.141662 -316.457584)
		(width 0.14478)
		(layer "In2.Cu")
		(net "M_I_CPU1_SB_DQ<30>")
	)
	(segment
		(start 159.710882 -314.61837)
		(end 159.939482 -314.61837)
		(width 0.14478)
		(layer "In2.Cu")
		(net "M_I_CPU1_SB_DQ<30>")
	)
	(segment
		(start 169.53357 -316.457584)
		(end 169.836338 -316.760352)
		(width 0.14478)
		(layer "In2.Cu")
		(net "M_I_CPU1_SB_DQ<30>")
	)
	(segment
		(start 158.78683 -313.981846)
		(end 158.930594 -313.838082)
		(width 0.14478)
		(layer "In2.Cu")
		(net "M_I_CPU1_SB_DQ<30>")
	)
	(segment
		(start 160.73755 -316.161166)
		(end 160.899094 -316.32271)
		(width 0.14478)
		(layer "In2.Cu")
		(net "M_I_CPU1_SB_DQ<30>")
	)
	(segment
		(start 162.700462 -316.760352)
		(end 162.942524 -316.51829)
		(width 0.14478)
		(layer "In2.Cu")
		(net "M_I_CPU1_SB_DQ<30>")
	)
	(segment
		(start 160.71977 -315.398658)
		(end 160.881314 -315.560202)
		(width 0.14478)
		(layer "In2.Cu")
		(net "M_I_CPU1_SB_DQ<30>")
	)
	(segment
		(start 142.341854 -292.393624)
		(end 142.372334 -292.411404)
		(width 0.0889)
		(layer "In2.Cu")
		(net "M_I_CPU1_SB_DQ<30>")
	)
	(segment
		(start 163.207192 -316.51829)
		(end 163.449254 -316.760352)
		(width 0.14478)
		(layer "In2.Cu")
		(net "M_I_CPU1_SB_DQ<30>")
	)
	(segment
		(start 157.777942 -313.201558)
		(end 158.006542 -313.201558)
		(width 0.14478)
		(layer "In2.Cu")
		(net "M_I_CPU1_SB_DQ<30>")
	)
	(segment
		(start 173.576234 -316.439804)
		(end 173.896782 -316.760352)
		(width 0.14478)
		(layer "In2.Cu")
		(net "M_I_CPU1_SB_DQ<30>")
	)
	(segment
		(start 145.629376 -300.308264)
		(end 157.760162 -312.43905)
		(width 0.14478)
		(layer "In2.Cu")
		(net "M_I_CPU1_SB_DQ<30>")
	)
	(segment
		(start 160.49117 -315.398658)
		(end 160.71977 -315.398658)
		(width 0.14478)
		(layer "In2.Cu")
		(net "M_I_CPU1_SB_DQ<30>")
	)
	(segment
		(start 166.28618 -316.760352)
		(end 166.549832 -316.760352)
		(width 0.14478)
		(layer "In2.Cu")
		(net "M_I_CPU1_SB_DQ<30>")
	)
	(segment
		(start 170.953938 -316.760352)
		(end 173.017434 -316.760352)
		(width 0.14478)
		(layer "In2.Cu")
		(net "M_I_CPU1_SB_DQ<30>")
	)
	(segment
		(start 179.091082 -316.760352)
		(end 179.516024 -316.33541)
		(width 0.14478)
		(layer "In2.Cu")
		(net "M_I_CPU1_SB_DQ<30>")
	)
	(segment
		(start 158.54045 -313.219338)
		(end 158.54045 -313.447938)
		(width 0.14478)
		(layer "In2.Cu")
		(net "M_I_CPU1_SB_DQ<30>")
	)
	(segment
		(start 129.934716 -292.716204)
		(end 129.780792 -292.450774)
		(width 0.0889)
		(layer "In2.Cu")
		(net "M_I_CPU1_SB_DQ<30>")
	)
	(segment
		(start 135.753348 -292.388798)
		(end 135.76173 -292.393624)
		(width 0.0889)
		(layer "In2.Cu")
		(net "M_I_CPU1_SB_DQ<30>")
	)
	(segment
		(start 162.942524 -316.51829)
		(end 163.207192 -316.51829)
		(width 0.14478)
		(layer "In2.Cu")
		(net "M_I_CPU1_SB_DQ<30>")
	)
	(segment
		(start 160.881314 -315.788802)
		(end 160.73755 -315.932566)
		(width 0.14478)
		(layer "In2.Cu")
		(net "M_I_CPU1_SB_DQ<30>")
	)
	(segment
		(start 160.101026 -315.008514)
		(end 159.957262 -315.152278)
		(width 0.14478)
		(layer "In2.Cu")
		(net "M_I_CPU1_SB_DQ<30>")
	)
	(segment
		(start 159.176974 -314.60059)
		(end 159.338518 -314.762134)
		(width 0.14478)
		(layer "In2.Cu")
		(net "M_I_CPU1_SB_DQ<30>")
	)
	(segment
		(start 162.44443 -316.760352)
		(end 162.700462 -316.760352)
		(width 0.14478)
		(layer "In2.Cu")
		(net "M_I_CPU1_SB_DQ<30>")
	)
	(segment
		(start 174.455582 -316.439804)
		(end 174.693834 -316.439804)
		(width 0.14478)
		(layer "In2.Cu")
		(net "M_I_CPU1_SB_DQ<30>")
	)
	(segment
		(start 177.770536 -316.457584)
		(end 178.073304 -316.760352)
		(width 0.14478)
		(layer "In2.Cu")
		(net "M_I_CPU1_SB_DQ<30>")
	)
	(segment
		(start 131.993386 -292.388798)
		(end 132.001768 -292.393624)
		(width 0.0889)
		(layer "In2.Cu")
		(net "M_I_CPU1_SB_DQ<30>")
	)
	(segment
		(start 143.715232 -294.80256)
		(end 143.751554 -294.823642)
		(width 0.0889)
		(layer "In2.Cu")
		(net "M_I_CPU1_SB_DQ<30>")
	)
	(segment
		(start 159.957262 -315.152278)
		(end 159.957262 -315.380878)
		(width 0.14478)
		(layer "In2.Cu")
		(net "M_I_CPU1_SB_DQ<30>")
	)
	(segment
		(start 136.693402 -292.388798)
		(end 136.701784 -292.393624)
		(width 0.0889)
		(layer "In2.Cu")
		(net "M_I_CPU1_SB_DQ<30>")
	)
	(segment
		(start 159.957262 -315.380878)
		(end 160.118806 -315.542422)
		(width 0.14478)
		(layer "In2.Cu")
		(net "M_I_CPU1_SB_DQ<30>")
	)
	(segment
		(start 159.338518 -314.762134)
		(end 159.567118 -314.762134)
		(width 0.14478)
		(layer "In2.Cu")
		(net "M_I_CPU1_SB_DQ<30>")
	)
	(segment
		(start 174.135034 -316.760352)
		(end 174.455582 -316.439804)
		(width 0.14478)
		(layer "In2.Cu")
		(net "M_I_CPU1_SB_DQ<30>")
	)
	(segment
		(start 143.245332 -293.992554)
		(end 143.281654 -294.013636)
		(width 0.0889)
		(layer "In2.Cu")
		(net "M_I_CPU1_SB_DQ<30>")
	)
	(segment
		(start 165.432232 -316.760352)
		(end 165.72738 -316.465204)
		(width 0.14478)
		(layer "In2.Cu")
		(net "M_I_CPU1_SB_DQ<30>")
	)
	(segment
		(start 166.84498 -316.465204)
		(end 167.108632 -316.465204)
		(width 0.14478)
		(layer "In2.Cu")
		(net "M_I_CPU1_SB_DQ<30>")
	)
	(segment
		(start 142.772638 -293.18077)
		(end 142.811754 -293.20363)
		(width 0.0889)
		(layer "In2.Cu")
		(net "M_I_CPU1_SB_DQ<30>")
	)
	(segment
		(start 141.967712 -292.393624)
		(end 141.976094 -292.388798)
		(width 0.0889)
		(layer "In2.Cu")
		(net "M_I_CPU1_SB_DQ<30>")
	)
	(segment
		(start 144.40916 -296.282618)
		(end 144.269206 -296.422572)
		(width 0.0889)
		(layer "In2.Cu")
		(net "M_I_CPU1_SB_DQ<30>")
	)
	(segment
		(start 173.017434 -316.760352)
		(end 173.337982 -316.439804)
		(width 0.14478)
		(layer "In2.Cu")
		(net "M_I_CPU1_SB_DQ<30>")
	)
	(segment
		(start 159.939482 -314.61837)
		(end 160.101026 -314.779914)
		(width 0.14478)
		(layer "In2.Cu")
		(net "M_I_CPU1_SB_DQ<30>")
	)
	(segment
		(start 137.267696 -292.393624)
		(end 137.276078 -292.388798)
		(width 0.0889)
		(layer "In2.Cu")
		(net "M_I_CPU1_SB_DQ<30>")
	)
	(segment
		(start 159.567118 -314.762134)
		(end 159.710882 -314.61837)
		(width 0.14478)
		(layer "In2.Cu")
		(net "M_I_CPU1_SB_DQ<30>")
	)
	(segment
		(start 158.396686 -313.591702)
		(end 158.396686 -313.820302)
		(width 0.14478)
		(layer "In2.Cu")
		(net "M_I_CPU1_SB_DQ<30>")
	)
	(segment
		(start 144.40916 -295.956228)
		(end 144.40916 -296.282618)
		(width 0.0889)
		(layer "In2.Cu")
		(net "M_I_CPU1_SB_DQ<30>")
	)
	(segment
		(start 170.09237 -316.760352)
		(end 170.395138 -316.457584)
		(width 0.14478)
		(layer "In2.Cu")
		(net "M_I_CPU1_SB_DQ<30>")
	)
	(segment
		(start 178.073304 -316.760352)
		(end 179.091082 -316.760352)
		(width 0.14478)
		(layer "In2.Cu")
		(net "M_I_CPU1_SB_DQ<30>")
	)
	(segment
		(start 177.514504 -316.457584)
		(end 177.770536 -316.457584)
		(width 0.14478)
		(layer "In2.Cu")
		(net "M_I_CPU1_SB_DQ<30>")
	)
	(segment
		(start 141.393418 -292.388798)
		(end 141.4018 -292.393624)
		(width 0.0889)
		(layer "In2.Cu")
		(net "M_I_CPU1_SB_DQ<30>")
	)
	(segment
		(start 165.72738 -316.465204)
		(end 165.991032 -316.465204)
		(width 0.14478)
		(layer "In2.Cu")
		(net "M_I_CPU1_SB_DQ<30>")
	)
	(segment
		(start 163.449254 -316.760352)
		(end 165.432232 -316.760352)
		(width 0.14478)
		(layer "In2.Cu")
		(net "M_I_CPU1_SB_DQ<30>")
	)
	(segment
		(start 144.221454 -295.633648)
		(end 144.25422 -295.652698)
		(width 0.0889)
		(layer "In2.Cu")
		(net "M_I_CPU1_SB_DQ<30>")
	)
	(segment
		(start 159.176974 -314.37199)
		(end 159.176974 -314.60059)
		(width 0.14478)
		(layer "In2.Cu")
		(net "M_I_CPU1_SB_DQ<30>")
	)
	(segment
		(start 133.507734 -292.393624)
		(end 133.516116 -292.388798)
		(width 0.0889)
		(layer "In2.Cu")
		(net "M_I_CPU1_SB_DQ<30>")
	)
	(segment
		(start 158.006542 -313.201558)
		(end 158.150306 -313.057794)
		(width 0.14478)
		(layer "In2.Cu")
		(net "M_I_CPU1_SB_DQ<30>")
	)
	(segment
		(start 167.108632 -316.465204)
		(end 167.40378 -316.760352)
		(width 0.14478)
		(layer "In2.Cu")
		(net "M_I_CPU1_SB_DQ<30>")
	)
	(segment
		(start 158.150306 -313.057794)
		(end 158.378906 -313.057794)
		(width 0.14478)
		(layer "In2.Cu")
		(net "M_I_CPU1_SB_DQ<30>")
	)
	(segment
		(start 157.760162 -312.66765)
		(end 157.616398 -312.811414)
		(width 0.14478)
		(layer "In2.Cu")
		(net "M_I_CPU1_SB_DQ<30>")
	)
	(segment
		(start 174.693834 -316.439804)
		(end 175.014382 -316.760352)
		(width 0.14478)
		(layer "In2.Cu")
		(net "M_I_CPU1_SB_DQ<30>")
	)
	(segment
		(start 160.101026 -314.779914)
		(end 160.101026 -315.008514)
		(width 0.14478)
		(layer "In2.Cu")
		(net "M_I_CPU1_SB_DQ<30>")
	)
	(segment
		(start 140.453364 -292.388798)
		(end 140.45438 -292.389306)
		(width 0.0889)
		(layer "In2.Cu")
		(net "M_I_CPU1_SB_DQ<30>")
	)
	(segment
		(start 129.780792 -292.450774)
		(end 129.803144 -292.367462)
		(width 0.0889)
		(layer "In2.Cu")
		(net "M_I_CPU1_SB_DQ<30>")
	)
	(segment
		(start 157.616398 -313.040014)
		(end 157.777942 -313.201558)
		(width 0.14478)
		(layer "In2.Cu")
		(net "M_I_CPU1_SB_DQ<30>")
	)
	(segment
		(start 158.378906 -313.057794)
		(end 158.54045 -313.219338)
		(width 0.14478)
		(layer "In2.Cu")
		(net "M_I_CPU1_SB_DQ<30>")
	)
	(segment
		(start 161.127694 -316.32271)
		(end 161.271458 -316.178946)
		(width 0.14478)
		(layer "In2.Cu")
		(net "M_I_CPU1_SB_DQ<30>")
	)
	(segment
		(start 143.281654 -294.013636)
		(end 143.313404 -294.031924)
		(width 0.0889)
		(layer "In2.Cu")
		(net "M_I_CPU1_SB_DQ<30>")
	)
	(segment
		(start 165.991032 -316.465204)
		(end 166.28618 -316.760352)
		(width 0.14478)
		(layer "In2.Cu")
		(net "M_I_CPU1_SB_DQ<30>")
	)
	(segment
		(start 160.73755 -315.932566)
		(end 160.73755 -316.161166)
		(width 0.14478)
		(layer "In2.Cu")
		(net "M_I_CPU1_SB_DQ<30>")
	)
	(segment
		(start 168.97477 -316.760352)
		(end 169.277538 -316.457584)
		(width 0.14478)
		(layer "In2.Cu")
		(net "M_I_CPU1_SB_DQ<30>")
	)
	(segment
		(start 157.616398 -312.811414)
		(end 157.616398 -313.040014)
		(width 0.14478)
		(layer "In2.Cu")
		(net "M_I_CPU1_SB_DQ<30>")
	)
	(segment
		(start 173.337982 -316.439804)
		(end 173.576234 -316.439804)
		(width 0.14478)
		(layer "In2.Cu")
		(net "M_I_CPU1_SB_DQ<30>")
	)
	(segment
		(start 138.20775 -292.393624)
		(end 138.216132 -292.388798)
		(width 0.0889)
		(layer "In2.Cu")
		(net "M_I_CPU1_SB_DQ<30>")
	)
	(segment
		(start 159.320738 -314.228226)
		(end 159.176974 -314.37199)
		(width 0.14478)
		(layer "In2.Cu")
		(net "M_I_CPU1_SB_DQ<30>")
	)
	(segment
		(start 159.320738 -313.999626)
		(end 159.320738 -314.228226)
		(width 0.14478)
		(layer "In2.Cu")
		(net "M_I_CPU1_SB_DQ<30>")
	)
	(segment
		(start 142.811754 -293.20363)
		(end 142.843504 -293.221918)
		(width 0.0889)
		(layer "In2.Cu")
		(net "M_I_CPU1_SB_DQ<30>")
	)
	(segment
		(start 162.141662 -316.457584)
		(end 162.44443 -316.760352)
		(width 0.14478)
		(layer "In2.Cu")
		(net "M_I_CPU1_SB_DQ<30>")
	)
	(segment
		(start 160.118806 -315.542422)
		(end 160.347406 -315.542422)
		(width 0.14478)
		(layer "In2.Cu")
		(net "M_I_CPU1_SB_DQ<30>")
	)
	(segment
		(start 157.760162 -312.43905)
		(end 157.760162 -312.66765)
		(width 0.14478)
		(layer "In2.Cu")
		(net "M_I_CPU1_SB_DQ<30>")
	)
	(segment
		(start 144.269206 -296.422572)
		(end 144.269206 -297.024806)
		(width 0.14478)
		(layer "In2.Cu")
		(net "M_I_CPU1_SB_DQ<30>")
	)
	(segment
		(start 161.500058 -316.178946)
		(end 161.778696 -316.457584)
		(width 0.14478)
		(layer "In2.Cu")
		(net "M_I_CPU1_SB_DQ<30>")
	)
	(segment
		(start 158.396686 -313.820302)
		(end 158.55823 -313.981846)
		(width 0.14478)
		(layer "In2.Cu")
		(net "M_I_CPU1_SB_DQ<30>")
	)
	(segment
		(start 158.55823 -313.981846)
		(end 158.78683 -313.981846)
		(width 0.14478)
		(layer "In2.Cu")
		(net "M_I_CPU1_SB_DQ<30>")
	)
	(segment
		(start 144.269206 -297.024806)
		(end 145.629376 -300.308264)
		(width 0.14478)
		(layer "In2.Cu")
		(net "M_I_CPU1_SB_DQ<30>")
	)
	(segment
		(start 169.836338 -316.760352)
		(end 170.09237 -316.760352)
		(width 0.14478)
		(layer "In2.Cu")
		(net "M_I_CPU1_SB_DQ<30>")
	)
	(segment
		(start 160.881314 -315.560202)
		(end 160.881314 -315.788802)
		(width 0.14478)
		(layer "In2.Cu")
		(net "M_I_CPU1_SB_DQ<30>")
	)
	(segment
		(start 140.45438 -292.389306)
		(end 140.461746 -292.393624)
		(width 0.0889)
		(layer "In2.Cu")
		(net "M_I_CPU1_SB_DQ<30>")
	)
	(segment
		(start 160.347406 -315.542422)
		(end 160.49117 -315.398658)
		(width 0.14478)
		(layer "In2.Cu")
		(net "M_I_CPU1_SB_DQ<30>")
	)
	(segment
		(start 144.185132 -295.612566)
		(end 144.221454 -295.633648)
		(width 0.0889)
		(layer "In2.Cu")
		(net "M_I_CPU1_SB_DQ<30>")
	)
	(segment
		(start 158.930594 -313.838082)
		(end 159.159194 -313.838082)
		(width 0.14478)
		(layer "In2.Cu")
		(net "M_I_CPU1_SB_DQ<30>")
	)
	(segment
		(start 158.54045 -313.447938)
		(end 158.396686 -313.591702)
		(width 0.14478)
		(layer "In2.Cu")
		(net "M_I_CPU1_SB_DQ<30>")
	)
	(segment
		(start 159.159194 -313.838082)
		(end 159.320738 -313.999626)
		(width 0.14478)
		(layer "In2.Cu")
		(net "M_I_CPU1_SB_DQ<30>")
	)
	(segment
		(start 160.899094 -316.32271)
		(end 161.127694 -316.32271)
		(width 0.14478)
		(layer "In2.Cu")
		(net "M_I_CPU1_SB_DQ<30>")
	)
	(segment
		(start 169.277538 -316.457584)
		(end 169.53357 -316.457584)
		(width 0.14478)
		(layer "In2.Cu")
		(net "M_I_CPU1_SB_DQ<30>")
	)
	(segment
		(start 161.271458 -316.178946)
		(end 161.500058 -316.178946)
		(width 0.14478)
		(layer "In2.Cu")
		(net "M_I_CPU1_SB_DQ<30>")
	)
	(segment
		(start 177.211736 -316.760352)
		(end 177.514504 -316.457584)
		(width 0.14478)
		(layer "In2.Cu")
		(net "M_I_CPU1_SB_DQ<30>")
	)
	(segment
		(start 143.751554 -294.823642)
		(end 143.783304 -294.84193)
		(width 0.0889)
		(layer "In2.Cu")
		(net "M_I_CPU1_SB_DQ<30>")
	)
	(segment
		(start 170.65117 -316.457584)
		(end 170.953938 -316.760352)
		(width 0.14478)
		(layer "In2.Cu")
		(net "M_I_CPU1_SB_DQ<30>")
	)
	(segment
		(start 167.40378 -316.760352)
		(end 168.97477 -316.760352)
		(width 0.14478)
		(layer "In2.Cu")
		(net "M_I_CPU1_SB_DQ<30>")
	)
	(segment
		(start 173.896782 -316.760352)
		(end 174.135034 -316.760352)
		(width 0.14478)
		(layer "In2.Cu")
		(net "M_I_CPU1_SB_DQ<30>")
	)
	(arc
		(start 143.783304 -294.84193)
		(mid 143.89798 -294.975264)
		(end 143.93926 -295.146222)
		(width 0.0889)
		(layer "In2.Cu")
		(net "M_I_CPU1_SB_DQ<30>")
	)
	(arc
		(start 137.276078 -292.388798)
		(mid 137.459586 -292.343304)
		(end 137.641838 -292.393624)
		(width 0.0889)
		(layer "In2.Cu")
		(net "M_I_CPU1_SB_DQ<30>")
	)
	(arc
		(start 130.687826 -292.393624)
		(mid 130.87477 -292.343369)
		(end 131.061714 -292.393624)
		(width 0.0889)
		(layer "In2.Cu")
		(net "M_I_CPU1_SB_DQ<30>")
	)
	(arc
		(start 142.99946 -293.52621)
		(mid 143.064696 -293.789801)
		(end 143.245332 -293.992554)
		(width 0.0889)
		(layer "In2.Cu")
		(net "M_I_CPU1_SB_DQ<30>")
	)
	(arc
		(start 142.843504 -293.221918)
		(mid 142.95818 -293.355252)
		(end 142.99946 -293.52621)
		(width 0.0889)
		(layer "In2.Cu")
		(net "M_I_CPU1_SB_DQ<30>")
	)
	(arc
		(start 141.4018 -292.393624)
		(mid 141.684756 -292.469801)
		(end 141.967712 -292.393624)
		(width 0.0889)
		(layer "In2.Cu")
		(net "M_I_CPU1_SB_DQ<30>")
	)
	(arc
		(start 131.627626 -292.393624)
		(mid 131.809877 -292.343274)
		(end 131.993386 -292.388798)
		(width 0.0889)
		(layer "In2.Cu")
		(net "M_I_CPU1_SB_DQ<30>")
	)
	(arc
		(start 133.516116 -292.388798)
		(mid 133.699624 -292.343304)
		(end 133.881876 -292.393624)
		(width 0.0889)
		(layer "In2.Cu")
		(net "M_I_CPU1_SB_DQ<30>")
	)
	(arc
		(start 133.881876 -292.393624)
		(mid 134.164832 -292.469801)
		(end 134.447788 -292.393624)
		(width 0.0889)
		(layer "In2.Cu")
		(net "M_I_CPU1_SB_DQ<30>")
	)
	(arc
		(start 144.25422 -295.652698)
		(mid 144.368149 -295.785845)
		(end 144.40916 -295.956228)
		(width 0.0889)
		(layer "In2.Cu")
		(net "M_I_CPU1_SB_DQ<30>")
	)
	(arc
		(start 136.701784 -292.393624)
		(mid 136.98474 -292.469801)
		(end 137.267696 -292.393624)
		(width 0.0889)
		(layer "In2.Cu")
		(net "M_I_CPU1_SB_DQ<30>")
	)
	(arc
		(start 132.001768 -292.393624)
		(mid 132.284724 -292.469801)
		(end 132.56768 -292.393624)
		(width 0.0889)
		(layer "In2.Cu")
		(net "M_I_CPU1_SB_DQ<30>")
	)
	(arc
		(start 140.087604 -292.393624)
		(mid 140.269855 -292.343274)
		(end 140.453364 -292.388798)
		(width 0.0889)
		(layer "In2.Cu")
		(net "M_I_CPU1_SB_DQ<30>")
	)
	(arc
		(start 137.641838 -292.393624)
		(mid 137.924794 -292.469801)
		(end 138.20775 -292.393624)
		(width 0.0889)
		(layer "In2.Cu")
		(net "M_I_CPU1_SB_DQ<30>")
	)
	(arc
		(start 143.93926 -295.146222)
		(mid 144.004496 -295.409813)
		(end 144.185132 -295.612566)
		(width 0.0889)
		(layer "In2.Cu")
		(net "M_I_CPU1_SB_DQ<30>")
	)
	(arc
		(start 139.147804 -292.393624)
		(mid 139.334748 -292.343369)
		(end 139.521692 -292.393624)
		(width 0.0889)
		(layer "In2.Cu")
		(net "M_I_CPU1_SB_DQ<30>")
	)
	(arc
		(start 132.56768 -292.393624)
		(mid 132.749931 -292.343274)
		(end 132.93344 -292.388798)
		(width 0.0889)
		(layer "In2.Cu")
		(net "M_I_CPU1_SB_DQ<30>")
	)
	(arc
		(start 135.76173 -292.393624)
		(mid 136.044686 -292.469801)
		(end 136.327642 -292.393624)
		(width 0.0889)
		(layer "In2.Cu")
		(net "M_I_CPU1_SB_DQ<30>")
	)
	(arc
		(start 143.313404 -294.031924)
		(mid 143.42808 -294.165258)
		(end 143.46936 -294.336216)
		(width 0.0889)
		(layer "In2.Cu")
		(net "M_I_CPU1_SB_DQ<30>")
	)
	(arc
		(start 142.372334 -292.411404)
		(mid 142.487761 -292.54478)
		(end 142.529306 -292.716204)
		(width 0.0889)
		(layer "In2.Cu")
		(net "M_I_CPU1_SB_DQ<30>")
	)
	(arc
		(start 138.581892 -292.393624)
		(mid 138.864848 -292.469801)
		(end 139.147804 -292.393624)
		(width 0.0889)
		(layer "In2.Cu")
		(net "M_I_CPU1_SB_DQ<30>")
	)
	(arc
		(start 142.529306 -292.716204)
		(mid 142.593821 -292.978423)
		(end 142.772638 -293.18077)
		(width 0.0889)
		(layer "In2.Cu")
		(net "M_I_CPU1_SB_DQ<30>")
	)
	(arc
		(start 138.216132 -292.388798)
		(mid 138.39964 -292.343304)
		(end 138.581892 -292.393624)
		(width 0.0889)
		(layer "In2.Cu")
		(net "M_I_CPU1_SB_DQ<30>")
	)
	(arc
		(start 139.521692 -292.393624)
		(mid 139.804648 -292.469801)
		(end 140.087604 -292.393624)
		(width 0.0889)
		(layer "In2.Cu")
		(net "M_I_CPU1_SB_DQ<30>")
	)
	(arc
		(start 141.027658 -292.393624)
		(mid 141.209909 -292.343274)
		(end 141.393418 -292.388798)
		(width 0.0889)
		(layer "In2.Cu")
		(net "M_I_CPU1_SB_DQ<30>")
	)
	(arc
		(start 135.387588 -292.393624)
		(mid 135.569839 -292.343274)
		(end 135.753348 -292.388798)
		(width 0.0889)
		(layer "In2.Cu")
		(net "M_I_CPU1_SB_DQ<30>")
	)
	(arc
		(start 132.941822 -292.393624)
		(mid 133.224778 -292.469801)
		(end 133.507734 -292.393624)
		(width 0.0889)
		(layer "In2.Cu")
		(net "M_I_CPU1_SB_DQ<30>")
	)
	(arc
		(start 130.121914 -292.393624)
		(mid 130.40487 -292.469801)
		(end 130.687826 -292.393624)
		(width 0.0889)
		(layer "In2.Cu")
		(net "M_I_CPU1_SB_DQ<30>")
	)
	(arc
		(start 136.327642 -292.393624)
		(mid 136.509893 -292.343274)
		(end 136.693402 -292.388798)
		(width 0.0889)
		(layer "In2.Cu")
		(net "M_I_CPU1_SB_DQ<30>")
	)
	(arc
		(start 134.447788 -292.393624)
		(mid 134.634732 -292.343369)
		(end 134.821676 -292.393624)
		(width 0.0889)
		(layer "In2.Cu")
		(net "M_I_CPU1_SB_DQ<30>")
	)
	(arc
		(start 129.803144 -292.367462)
		(mid 129.965476 -292.344644)
		(end 130.121914 -292.393624)
		(width 0.0889)
		(layer "In2.Cu")
		(net "M_I_CPU1_SB_DQ<30>")
	)
	(arc
		(start 140.461746 -292.393624)
		(mid 140.744702 -292.469801)
		(end 141.027658 -292.393624)
		(width 0.0889)
		(layer "In2.Cu")
		(net "M_I_CPU1_SB_DQ<30>")
	)
	(arc
		(start 143.46936 -294.336216)
		(mid 143.534596 -294.599807)
		(end 143.715232 -294.80256)
		(width 0.0889)
		(layer "In2.Cu")
		(net "M_I_CPU1_SB_DQ<30>")
	)
	(arc
		(start 131.061714 -292.393624)
		(mid 131.34467 -292.469801)
		(end 131.627626 -292.393624)
		(width 0.0889)
		(layer "In2.Cu")
		(net "M_I_CPU1_SB_DQ<30>")
	)
	(arc
		(start 134.821676 -292.393624)
		(mid 135.104632 -292.469801)
		(end 135.387588 -292.393624)
		(width 0.0889)
		(layer "In2.Cu")
		(net "M_I_CPU1_SB_DQ<30>")
	)
	(arc
		(start 141.976094 -292.388798)
		(mid 142.159602 -292.343304)
		(end 142.341854 -292.393624)
		(width 0.0889)
		(layer "In2.Cu")
		(net "M_I_CPU1_SB_DQ<30>")
	)
	(segment
		(start 129.467864 -274.630388)
		(end 129.934716 -274.896326)
		(width 0.10668)
		(layer "F.Cu")
		(net "M_I_CPU1_SB_DQ<2>")
	)
	(segment
		(start 178.15179 -282.2829)
		(end 178.30165 -282.13304)
		(width 0.14478)
		(layer "In2.Cu")
		(net "M_I_CPU1_SB_DQ<2>")
	)
	(segment
		(start 135.753348 -274.56892)
		(end 135.76173 -274.573746)
		(width 0.0889)
		(layer "In2.Cu")
		(net "M_I_CPU1_SB_DQ<2>")
	)
	(segment
		(start 166.327074 -282.724352)
		(end 166.247064 -282.531566)
		(width 0.14478)
		(layer "In2.Cu")
		(net "M_I_CPU1_SB_DQ<2>")
	)
	(segment
		(start 166.578026 -282.070302)
		(end 166.49192 -281.862784)
		(width 0.14478)
		(layer "In2.Cu")
		(net "M_I_CPU1_SB_DQ<2>")
	)
	(segment
		(start 175.162972 -281.910282)
		(end 176.961292 -281.910282)
		(width 0.14478)
		(layer "In2.Cu")
		(net "M_I_CPU1_SB_DQ<2>")
	)
	(segment
		(start 166.496746 -282.265882)
		(end 166.578026 -282.070302)
		(width 0.14478)
		(layer "In2.Cu")
		(net "M_I_CPU1_SB_DQ<2>")
	)
	(segment
		(start 173.880272 -282.748736)
		(end 174.06366 -282.565348)
		(width 0.14478)
		(layer "In2.Cu")
		(net "M_I_CPU1_SB_DQ<2>")
	)
	(segment
		(start 159.253428 -278.579834)
		(end 163.434014 -282.76042)
		(width 0.14478)
		(layer "In2.Cu")
		(net "M_I_CPU1_SB_DQ<2>")
	)
	(segment
		(start 140.453364 -274.56892)
		(end 140.461746 -274.573746)
		(width 0.0889)
		(layer "In2.Cu")
		(net "M_I_CPU1_SB_DQ<2>")
	)
	(segment
		(start 178.45151 -281.537664)
		(end 178.71059 -281.537664)
		(width 0.14478)
		(layer "In2.Cu")
		(net "M_I_CPU1_SB_DQ<2>")
	)
	(segment
		(start 138.20775 -274.573746)
		(end 138.216132 -274.56892)
		(width 0.0889)
		(layer "In2.Cu")
		(net "M_I_CPU1_SB_DQ<2>")
	)
	(segment
		(start 177.33391 -281.537664)
		(end 177.59299 -281.537664)
		(width 0.14478)
		(layer "In2.Cu")
		(net "M_I_CPU1_SB_DQ<2>")
	)
	(segment
		(start 174.860712 -281.174444)
		(end 175.010572 -281.324304)
		(width 0.14478)
		(layer "In2.Cu")
		(net "M_I_CPU1_SB_DQ<2>")
	)
	(segment
		(start 173.10227 -282.39466)
		(end 173.314106 -282.39466)
		(width 0.14478)
		(layer "In2.Cu")
		(net "M_I_CPU1_SB_DQ<2>")
	)
	(segment
		(start 177.74285 -281.687524)
		(end 177.74285 -282.13304)
		(width 0.14478)
		(layer "In2.Cu")
		(net "M_I_CPU1_SB_DQ<2>")
	)
	(segment
		(start 145.143982 -274.563586)
		(end 145.16227 -274.574)
		(width 0.0889)
		(layer "In2.Cu")
		(net "M_I_CPU1_SB_DQ<2>")
	)
	(segment
		(start 129.934716 -274.896326)
		(end 129.780792 -274.630896)
		(width 0.0889)
		(layer "In2.Cu")
		(net "M_I_CPU1_SB_DQ<2>")
	)
	(segment
		(start 166.245794 -282.920186)
		(end 166.327074 -282.724352)
		(width 0.14478)
		(layer "In2.Cu")
		(net "M_I_CPU1_SB_DQ<2>")
	)
	(segment
		(start 178.30165 -281.687524)
		(end 178.45151 -281.537664)
		(width 0.14478)
		(layer "In2.Cu")
		(net "M_I_CPU1_SB_DQ<2>")
	)
	(segment
		(start 166.006272 -283.0195)
		(end 166.245794 -282.920186)
		(width 0.14478)
		(layer "In2.Cu")
		(net "M_I_CPU1_SB_DQ<2>")
	)
	(segment
		(start 165.730682 -282.745434)
		(end 165.810692 -282.93822)
		(width 0.14478)
		(layer "In2.Cu")
		(net "M_I_CPU1_SB_DQ<2>")
	)
	(segment
		(start 170.838368 -282.76042)
		(end 172.73651 -282.76042)
		(width 0.14478)
		(layer "In2.Cu")
		(net "M_I_CPU1_SB_DQ<2>")
	)
	(segment
		(start 167.083232 -281.82951)
		(end 167.279066 -281.910282)
		(width 0.14478)
		(layer "In2.Cu")
		(net "M_I_CPU1_SB_DQ<2>")
	)
	(segment
		(start 174.06366 -282.353512)
		(end 173.70933 -281.999436)
		(width 0.14478)
		(layer "In2.Cu")
		(net "M_I_CPU1_SB_DQ<2>")
	)
	(segment
		(start 136.693402 -274.56892)
		(end 136.701784 -274.573746)
		(width 0.0889)
		(layer "In2.Cu")
		(net "M_I_CPU1_SB_DQ<2>")
	)
	(segment
		(start 131.993386 -274.56892)
		(end 132.001768 -274.573746)
		(width 0.0889)
		(layer "In2.Cu")
		(net "M_I_CPU1_SB_DQ<2>")
	)
	(segment
		(start 178.71059 -281.537664)
		(end 179.083208 -281.910282)
		(width 0.14478)
		(layer "In2.Cu")
		(net "M_I_CPU1_SB_DQ<2>")
	)
	(segment
		(start 166.49192 -281.862784)
		(end 166.5732 -281.667458)
		(width 0.14478)
		(layer "In2.Cu")
		(net "M_I_CPU1_SB_DQ<2>")
	)
	(segment
		(start 174.322486 -281.174444)
		(end 174.860712 -281.174444)
		(width 0.14478)
		(layer "In2.Cu")
		(net "M_I_CPU1_SB_DQ<2>")
	)
	(segment
		(start 144.221708 -274.573746)
		(end 144.23644 -274.582382)
		(width 0.0889)
		(layer "In2.Cu")
		(net "M_I_CPU1_SB_DQ<2>")
	)
	(segment
		(start 174.06366 -282.565348)
		(end 174.06366 -282.353512)
		(width 0.14478)
		(layer "In2.Cu")
		(net "M_I_CPU1_SB_DQ<2>")
	)
	(segment
		(start 147.243038 -273.645884)
		(end 147.494498 -273.394424)
		(width 0.0889)
		(layer "In2.Cu")
		(net "M_I_CPU1_SB_DQ<2>")
	)
	(segment
		(start 179.083208 -281.910282)
		(end 179.091082 -281.910282)
		(width 0.14478)
		(layer "In2.Cu")
		(net "M_I_CPU1_SB_DQ<2>")
	)
	(segment
		(start 167.008302 -281.648916)
		(end 167.083232 -281.82951)
		(width 0.14478)
		(layer "In2.Cu")
		(net "M_I_CPU1_SB_DQ<2>")
	)
	(segment
		(start 177.59299 -281.537664)
		(end 177.74285 -281.687524)
		(width 0.14478)
		(layer "In2.Cu")
		(net "M_I_CPU1_SB_DQ<2>")
	)
	(segment
		(start 141.967712 -274.573746)
		(end 141.976094 -274.56892)
		(width 0.0889)
		(layer "In2.Cu")
		(net "M_I_CPU1_SB_DQ<2>")
	)
	(segment
		(start 158.409132 -278.579834)
		(end 159.253428 -278.579834)
		(width 0.14478)
		(layer "In2.Cu")
		(net "M_I_CPU1_SB_DQ<2>")
	)
	(segment
		(start 132.93344 -274.56892)
		(end 132.941822 -274.573746)
		(width 0.0889)
		(layer "In2.Cu")
		(net "M_I_CPU1_SB_DQ<2>")
	)
	(segment
		(start 147.494498 -273.394424)
		(end 148.048218 -273.394424)
		(width 0.0889)
		(layer "In2.Cu")
		(net "M_I_CPU1_SB_DQ<2>")
	)
	(segment
		(start 175.010572 -281.324304)
		(end 175.010572 -281.757882)
		(width 0.14478)
		(layer "In2.Cu")
		(net "M_I_CPU1_SB_DQ<2>")
	)
	(segment
		(start 175.010572 -281.757882)
		(end 175.162972 -281.910282)
		(width 0.14478)
		(layer "In2.Cu")
		(net "M_I_CPU1_SB_DQ<2>")
	)
	(segment
		(start 176.961292 -281.910282)
		(end 177.33391 -281.537664)
		(width 0.14478)
		(layer "In2.Cu")
		(net "M_I_CPU1_SB_DQ<2>")
	)
	(segment
		(start 166.328344 -282.335732)
		(end 166.496746 -282.265882)
		(width 0.14478)
		(layer "In2.Cu")
		(net "M_I_CPU1_SB_DQ<2>")
	)
	(segment
		(start 165.535102 -282.664154)
		(end 165.730682 -282.745434)
		(width 0.14478)
		(layer "In2.Cu")
		(net "M_I_CPU1_SB_DQ<2>")
	)
	(segment
		(start 179.091082 -281.910282)
		(end 179.516024 -282.335224)
		(width 0.14478)
		(layer "In2.Cu")
		(net "M_I_CPU1_SB_DQ<2>")
	)
	(segment
		(start 146.755866 -273.645884)
		(end 147.243038 -273.645884)
		(width 0.0889)
		(layer "In2.Cu")
		(net "M_I_CPU1_SB_DQ<2>")
	)
	(segment
		(start 166.247064 -282.531566)
		(end 166.328344 -282.335732)
		(width 0.14478)
		(layer "In2.Cu")
		(net "M_I_CPU1_SB_DQ<2>")
	)
	(segment
		(start 145.8341 -274.56765)
		(end 146.755866 -273.645884)
		(width 0.0889)
		(layer "In2.Cu")
		(net "M_I_CPU1_SB_DQ<2>")
	)
	(segment
		(start 137.267696 -274.573746)
		(end 137.276078 -274.56892)
		(width 0.0889)
		(layer "In2.Cu")
		(net "M_I_CPU1_SB_DQ<2>")
	)
	(segment
		(start 177.89271 -282.2829)
		(end 178.15179 -282.2829)
		(width 0.14478)
		(layer "In2.Cu")
		(net "M_I_CPU1_SB_DQ<2>")
	)
	(segment
		(start 163.434014 -282.76042)
		(end 165.302946 -282.76042)
		(width 0.14478)
		(layer "In2.Cu")
		(net "M_I_CPU1_SB_DQ<2>")
	)
	(segment
		(start 177.74285 -282.13304)
		(end 177.89271 -282.2829)
		(width 0.14478)
		(layer "In2.Cu")
		(net "M_I_CPU1_SB_DQ<2>")
	)
	(segment
		(start 173.70933 -281.7876)
		(end 174.322486 -281.174444)
		(width 0.14478)
		(layer "In2.Cu")
		(net "M_I_CPU1_SB_DQ<2>")
	)
	(segment
		(start 144.213326 -274.56892)
		(end 144.221708 -274.573746)
		(width 0.0889)
		(layer "In2.Cu")
		(net "M_I_CPU1_SB_DQ<2>")
	)
	(segment
		(start 141.393418 -274.56892)
		(end 141.4018 -274.573746)
		(width 0.0889)
		(layer "In2.Cu")
		(net "M_I_CPU1_SB_DQ<2>")
	)
	(segment
		(start 166.5732 -281.667458)
		(end 166.812976 -281.56789)
		(width 0.14478)
		(layer "In2.Cu")
		(net "M_I_CPU1_SB_DQ<2>")
	)
	(segment
		(start 173.314106 -282.39466)
		(end 173.668436 -282.748736)
		(width 0.14478)
		(layer "In2.Cu")
		(net "M_I_CPU1_SB_DQ<2>")
	)
	(segment
		(start 173.70933 -281.999436)
		(end 173.70933 -281.7876)
		(width 0.14478)
		(layer "In2.Cu")
		(net "M_I_CPU1_SB_DQ<2>")
	)
	(segment
		(start 169.98823 -281.910282)
		(end 170.838368 -282.76042)
		(width 0.14478)
		(layer "In2.Cu")
		(net "M_I_CPU1_SB_DQ<2>")
	)
	(segment
		(start 153.223722 -273.394424)
		(end 158.409132 -278.579834)
		(width 0.14478)
		(layer "In2.Cu")
		(net "M_I_CPU1_SB_DQ<2>")
	)
	(segment
		(start 133.507734 -274.573746)
		(end 133.516116 -274.56892)
		(width 0.0889)
		(layer "In2.Cu")
		(net "M_I_CPU1_SB_DQ<2>")
	)
	(segment
		(start 166.812976 -281.56789)
		(end 167.008302 -281.648916)
		(width 0.14478)
		(layer "In2.Cu")
		(net "M_I_CPU1_SB_DQ<2>")
	)
	(segment
		(start 165.810692 -282.93822)
		(end 166.006272 -283.0195)
		(width 0.14478)
		(layer "In2.Cu")
		(net "M_I_CPU1_SB_DQ<2>")
	)
	(segment
		(start 167.279066 -281.910282)
		(end 169.98823 -281.910282)
		(width 0.14478)
		(layer "In2.Cu")
		(net "M_I_CPU1_SB_DQ<2>")
	)
	(segment
		(start 148.048218 -273.394424)
		(end 153.223722 -273.394424)
		(width 0.14478)
		(layer "In2.Cu")
		(net "M_I_CPU1_SB_DQ<2>")
	)
	(segment
		(start 178.30165 -282.13304)
		(end 178.30165 -281.687524)
		(width 0.14478)
		(layer "In2.Cu")
		(net "M_I_CPU1_SB_DQ<2>")
	)
	(segment
		(start 172.73651 -282.76042)
		(end 173.10227 -282.39466)
		(width 0.14478)
		(layer "In2.Cu")
		(net "M_I_CPU1_SB_DQ<2>")
	)
	(segment
		(start 145.730214 -274.61083)
		(end 145.8341 -274.56765)
		(width 0.0889)
		(layer "In2.Cu")
		(net "M_I_CPU1_SB_DQ<2>")
	)
	(segment
		(start 165.302946 -282.76042)
		(end 165.535102 -282.664154)
		(width 0.14478)
		(layer "In2.Cu")
		(net "M_I_CPU1_SB_DQ<2>")
	)
	(segment
		(start 129.780792 -274.630896)
		(end 129.803144 -274.547584)
		(width 0.0889)
		(layer "In2.Cu")
		(net "M_I_CPU1_SB_DQ<2>")
	)
	(segment
		(start 145.16227 -274.574)
		(end 145.178018 -274.583144)
		(width 0.0889)
		(layer "In2.Cu")
		(net "M_I_CPU1_SB_DQ<2>")
	)
	(segment
		(start 173.668436 -282.748736)
		(end 173.880272 -282.748736)
		(width 0.14478)
		(layer "In2.Cu")
		(net "M_I_CPU1_SB_DQ<2>")
	)
	(arc
		(start 134.447788 -274.573746)
		(mid 134.634732 -274.523491)
		(end 134.821676 -274.573746)
		(width 0.0889)
		(layer "In2.Cu")
		(net "M_I_CPU1_SB_DQ<2>")
	)
	(arc
		(start 136.327642 -274.573746)
		(mid 136.509893 -274.523396)
		(end 136.693402 -274.56892)
		(width 0.0889)
		(layer "In2.Cu")
		(net "M_I_CPU1_SB_DQ<2>")
	)
	(arc
		(start 142.907766 -274.573746)
		(mid 143.09471 -274.523491)
		(end 143.281654 -274.573746)
		(width 0.0889)
		(layer "In2.Cu")
		(net "M_I_CPU1_SB_DQ<2>")
	)
	(arc
		(start 132.001768 -274.573746)
		(mid 132.284724 -274.649923)
		(end 132.56768 -274.573746)
		(width 0.0889)
		(layer "In2.Cu")
		(net "M_I_CPU1_SB_DQ<2>")
	)
	(arc
		(start 144.23644 -274.582382)
		(mid 144.513423 -274.650186)
		(end 144.788128 -274.573746)
		(width 0.0889)
		(layer "In2.Cu")
		(net "M_I_CPU1_SB_DQ<2>")
	)
	(arc
		(start 134.821676 -274.573746)
		(mid 135.104632 -274.649923)
		(end 135.387588 -274.573746)
		(width 0.0889)
		(layer "In2.Cu")
		(net "M_I_CPU1_SB_DQ<2>")
	)
	(arc
		(start 138.581892 -274.573746)
		(mid 138.864848 -274.649923)
		(end 139.147804 -274.573746)
		(width 0.0889)
		(layer "In2.Cu")
		(net "M_I_CPU1_SB_DQ<2>")
	)
	(arc
		(start 141.4018 -274.573746)
		(mid 141.684756 -274.649923)
		(end 141.967712 -274.573746)
		(width 0.0889)
		(layer "In2.Cu")
		(net "M_I_CPU1_SB_DQ<2>")
	)
	(arc
		(start 136.701784 -274.573746)
		(mid 136.98474 -274.649923)
		(end 137.267696 -274.573746)
		(width 0.0889)
		(layer "In2.Cu")
		(net "M_I_CPU1_SB_DQ<2>")
	)
	(arc
		(start 141.027658 -274.573746)
		(mid 141.209909 -274.523396)
		(end 141.393418 -274.56892)
		(width 0.0889)
		(layer "In2.Cu")
		(net "M_I_CPU1_SB_DQ<2>")
	)
	(arc
		(start 137.641838 -274.573746)
		(mid 137.924794 -274.649923)
		(end 138.20775 -274.573746)
		(width 0.0889)
		(layer "In2.Cu")
		(net "M_I_CPU1_SB_DQ<2>")
	)
	(arc
		(start 130.687826 -274.573746)
		(mid 130.87477 -274.523491)
		(end 131.061714 -274.573746)
		(width 0.0889)
		(layer "In2.Cu")
		(net "M_I_CPU1_SB_DQ<2>")
	)
	(arc
		(start 143.281654 -274.573746)
		(mid 143.56461 -274.649923)
		(end 143.847566 -274.573746)
		(width 0.0889)
		(layer "In2.Cu")
		(net "M_I_CPU1_SB_DQ<2>")
	)
	(arc
		(start 137.276078 -274.56892)
		(mid 137.459586 -274.523426)
		(end 137.641838 -274.573746)
		(width 0.0889)
		(layer "In2.Cu")
		(net "M_I_CPU1_SB_DQ<2>")
	)
	(arc
		(start 139.147804 -274.573746)
		(mid 139.334748 -274.523491)
		(end 139.521692 -274.573746)
		(width 0.0889)
		(layer "In2.Cu")
		(net "M_I_CPU1_SB_DQ<2>")
	)
	(arc
		(start 140.461746 -274.573746)
		(mid 140.744702 -274.649923)
		(end 141.027658 -274.573746)
		(width 0.0889)
		(layer "In2.Cu")
		(net "M_I_CPU1_SB_DQ<2>")
	)
	(arc
		(start 140.087604 -274.573746)
		(mid 140.269855 -274.523396)
		(end 140.453364 -274.56892)
		(width 0.0889)
		(layer "In2.Cu")
		(net "M_I_CPU1_SB_DQ<2>")
	)
	(arc
		(start 132.941822 -274.573746)
		(mid 133.224778 -274.649923)
		(end 133.507734 -274.573746)
		(width 0.0889)
		(layer "In2.Cu")
		(net "M_I_CPU1_SB_DQ<2>")
	)
	(arc
		(start 131.061714 -274.573746)
		(mid 131.34467 -274.649923)
		(end 131.627626 -274.573746)
		(width 0.0889)
		(layer "In2.Cu")
		(net "M_I_CPU1_SB_DQ<2>")
	)
	(arc
		(start 131.627626 -274.573746)
		(mid 131.809877 -274.523396)
		(end 131.993386 -274.56892)
		(width 0.0889)
		(layer "In2.Cu")
		(net "M_I_CPU1_SB_DQ<2>")
	)
	(arc
		(start 142.341854 -274.573746)
		(mid 142.62481 -274.649923)
		(end 142.907766 -274.573746)
		(width 0.0889)
		(layer "In2.Cu")
		(net "M_I_CPU1_SB_DQ<2>")
	)
	(arc
		(start 130.121914 -274.573746)
		(mid 130.40487 -274.649923)
		(end 130.687826 -274.573746)
		(width 0.0889)
		(layer "In2.Cu")
		(net "M_I_CPU1_SB_DQ<2>")
	)
	(arc
		(start 143.847566 -274.573746)
		(mid 144.029817 -274.523396)
		(end 144.213326 -274.56892)
		(width 0.0889)
		(layer "In2.Cu")
		(net "M_I_CPU1_SB_DQ<2>")
	)
	(arc
		(start 133.881876 -274.573746)
		(mid 134.164832 -274.649923)
		(end 134.447788 -274.573746)
		(width 0.0889)
		(layer "In2.Cu")
		(net "M_I_CPU1_SB_DQ<2>")
	)
	(arc
		(start 145.178018 -274.583144)
		(mid 145.451001 -274.659164)
		(end 145.730214 -274.61083)
		(width 0.0889)
		(layer "In2.Cu")
		(net "M_I_CPU1_SB_DQ<2>")
	)
	(arc
		(start 139.521692 -274.573746)
		(mid 139.804648 -274.649923)
		(end 140.087604 -274.573746)
		(width 0.0889)
		(layer "In2.Cu")
		(net "M_I_CPU1_SB_DQ<2>")
	)
	(arc
		(start 144.788128 -274.573746)
		(mid 144.964756 -274.523513)
		(end 145.143982 -274.563586)
		(width 0.0889)
		(layer "In2.Cu")
		(net "M_I_CPU1_SB_DQ<2>")
	)
	(arc
		(start 138.216132 -274.56892)
		(mid 138.39964 -274.523426)
		(end 138.581892 -274.573746)
		(width 0.0889)
		(layer "In2.Cu")
		(net "M_I_CPU1_SB_DQ<2>")
	)
	(arc
		(start 132.56768 -274.573746)
		(mid 132.749931 -274.523396)
		(end 132.93344 -274.56892)
		(width 0.0889)
		(layer "In2.Cu")
		(net "M_I_CPU1_SB_DQ<2>")
	)
	(arc
		(start 129.803144 -274.547584)
		(mid 129.965476 -274.524766)
		(end 130.121914 -274.573746)
		(width 0.0889)
		(layer "In2.Cu")
		(net "M_I_CPU1_SB_DQ<2>")
	)
	(arc
		(start 141.976094 -274.56892)
		(mid 142.159602 -274.523426)
		(end 142.341854 -274.573746)
		(width 0.0889)
		(layer "In2.Cu")
		(net "M_I_CPU1_SB_DQ<2>")
	)
	(arc
		(start 133.516116 -274.56892)
		(mid 133.699624 -274.523426)
		(end 133.881876 -274.573746)
		(width 0.0889)
		(layer "In2.Cu")
		(net "M_I_CPU1_SB_DQ<2>")
	)
	(arc
		(start 135.76173 -274.573746)
		(mid 136.044686 -274.649923)
		(end 136.327642 -274.573746)
		(width 0.0889)
		(layer "In2.Cu")
		(net "M_I_CPU1_SB_DQ<2>")
	)
	(arc
		(start 135.387588 -274.573746)
		(mid 135.569839 -274.523396)
		(end 135.753348 -274.56892)
		(width 0.0889)
		(layer "In2.Cu")
		(net "M_I_CPU1_SB_DQ<2>")
	)
	(segment
		(start 127.58801 -292.450266)
		(end 128.054862 -292.716204)
		(width 0.10668)
		(layer "F.Cu")
		(net "M_I_CPU1_SB_DQ<29>")
	)
	(segment
		(start 160.643824 -316.70371)
		(end 162.83305 -317.61049)
		(width 0.14478)
		(layer "In2.Cu")
		(net "M_I_CPU1_SB_DQ<29>")
	)
	(segment
		(start 142.407132 -293.83101)
		(end 142.437612 -293.84879)
		(width 0.0889)
		(layer "In2.Cu")
		(net "M_I_CPU1_SB_DQ<29>")
	)
	(segment
		(start 132.93344 -293.04361)
		(end 132.941822 -293.038784)
		(width 0.0889)
		(layer "In2.Cu")
		(net "M_I_CPU1_SB_DQ<29>")
	)
	(segment
		(start 143.814546 -296.624756)
		(end 143.814546 -297.12031)
		(width 0.14478)
		(layer "In2.Cu")
		(net "M_I_CPU1_SB_DQ<29>")
	)
	(segment
		(start 128.208786 -292.981634)
		(end 128.304798 -293.007034)
		(width 0.0889)
		(layer "In2.Cu")
		(net "M_I_CPU1_SB_DQ<29>")
	)
	(segment
		(start 157.166818 -313.226704)
		(end 160.643824 -316.70371)
		(width 0.14478)
		(layer "In2.Cu")
		(net "M_I_CPU1_SB_DQ<29>")
	)
	(segment
		(start 143.65986 -295.956228)
		(end 143.65986 -296.47007)
		(width 0.0889)
		(layer "In2.Cu")
		(net "M_I_CPU1_SB_DQ<29>")
	)
	(segment
		(start 128.054862 -292.716204)
		(end 128.208786 -292.981634)
		(width 0.0889)
		(layer "In2.Cu")
		(net "M_I_CPU1_SB_DQ<29>")
	)
	(segment
		(start 138.20775 -293.038784)
		(end 138.216132 -293.04361)
		(width 0.0889)
		(layer "In2.Cu")
		(net "M_I_CPU1_SB_DQ<29>")
	)
	(segment
		(start 136.693402 -293.04361)
		(end 136.701784 -293.038784)
		(width 0.0889)
		(layer "In2.Cu")
		(net "M_I_CPU1_SB_DQ<29>")
	)
	(segment
		(start 162.83305 -317.61049)
		(end 183.190896 -317.61049)
		(width 0.14478)
		(layer "In2.Cu")
		(net "M_I_CPU1_SB_DQ<29>")
	)
	(segment
		(start 128.807718 -293.038784)
		(end 128.8161 -293.04361)
		(width 0.0889)
		(layer "In2.Cu")
		(net "M_I_CPU1_SB_DQ<29>")
	)
	(segment
		(start 135.753348 -293.04361)
		(end 135.76173 -293.038784)
		(width 0.0889)
		(layer "In2.Cu")
		(net "M_I_CPU1_SB_DQ<29>")
	)
	(segment
		(start 137.267696 -293.038784)
		(end 137.276078 -293.04361)
		(width 0.0889)
		(layer "In2.Cu")
		(net "M_I_CPU1_SB_DQ<29>")
	)
	(segment
		(start 141.393418 -293.04361)
		(end 141.4018 -293.038784)
		(width 0.0889)
		(layer "In2.Cu")
		(net "M_I_CPU1_SB_DQ<29>")
	)
	(segment
		(start 141.967712 -293.038784)
		(end 142.006828 -293.061644)
		(width 0.0889)
		(layer "In2.Cu")
		(net "M_I_CPU1_SB_DQ<29>")
	)
	(segment
		(start 131.993386 -293.04361)
		(end 132.001768 -293.038784)
		(width 0.0889)
		(layer "In2.Cu")
		(net "M_I_CPU1_SB_DQ<29>")
	)
	(segment
		(start 142.907766 -294.658796)
		(end 142.944088 -294.679878)
		(width 0.0889)
		(layer "In2.Cu")
		(net "M_I_CPU1_SB_DQ<29>")
	)
	(segment
		(start 142.437612 -293.84879)
		(end 142.476728 -293.87165)
		(width 0.0889)
		(layer "In2.Cu")
		(net "M_I_CPU1_SB_DQ<29>")
	)
	(segment
		(start 143.65986 -296.47007)
		(end 143.814546 -296.624756)
		(width 0.0889)
		(layer "In2.Cu")
		(net "M_I_CPU1_SB_DQ<29>")
	)
	(segment
		(start 133.507734 -293.038784)
		(end 133.516116 -293.04361)
		(width 0.0889)
		(layer "In2.Cu")
		(net "M_I_CPU1_SB_DQ<29>")
	)
	(segment
		(start 145.235168 -300.550326)
		(end 157.166818 -312.481976)
		(width 0.14478)
		(layer "In2.Cu")
		(net "M_I_CPU1_SB_DQ<29>")
	)
	(segment
		(start 143.814546 -297.12031)
		(end 145.235168 -300.550326)
		(width 0.14478)
		(layer "In2.Cu")
		(net "M_I_CPU1_SB_DQ<29>")
	)
	(segment
		(start 142.876016 -294.640508)
		(end 142.907766 -294.658796)
		(width 0.0889)
		(layer "In2.Cu")
		(net "M_I_CPU1_SB_DQ<29>")
	)
	(segment
		(start 143.345916 -295.450514)
		(end 143.377666 -295.468802)
		(width 0.0889)
		(layer "In2.Cu")
		(net "M_I_CPU1_SB_DQ<29>")
	)
	(segment
		(start 157.166818 -312.481976)
		(end 157.166818 -313.226704)
		(width 0.14478)
		(layer "In2.Cu")
		(net "M_I_CPU1_SB_DQ<29>")
	)
	(segment
		(start 129.747772 -293.038784)
		(end 129.756154 -293.04361)
		(width 0.0889)
		(layer "In2.Cu")
		(net "M_I_CPU1_SB_DQ<29>")
	)
	(segment
		(start 143.377666 -295.468802)
		(end 143.413988 -295.489884)
		(width 0.0889)
		(layer "In2.Cu")
		(net "M_I_CPU1_SB_DQ<29>")
	)
	(segment
		(start 183.190896 -317.61049)
		(end 183.616092 -317.185294)
		(width 0.14478)
		(layer "In2.Cu")
		(net "M_I_CPU1_SB_DQ<29>")
	)
	(segment
		(start 140.453364 -293.04361)
		(end 140.45438 -293.043102)
		(width 0.0889)
		(layer "In2.Cu")
		(net "M_I_CPU1_SB_DQ<29>")
	)
	(segment
		(start 140.45438 -293.043102)
		(end 140.461746 -293.038784)
		(width 0.0889)
		(layer "In2.Cu")
		(net "M_I_CPU1_SB_DQ<29>")
	)
	(arc
		(start 140.461746 -293.038784)
		(mid 140.744702 -292.962607)
		(end 141.027658 -293.038784)
		(width 0.0889)
		(layer "In2.Cu")
		(net "M_I_CPU1_SB_DQ<29>")
	)
	(arc
		(start 132.001768 -293.038784)
		(mid 132.284724 -292.962607)
		(end 132.56768 -293.038784)
		(width 0.0889)
		(layer "In2.Cu")
		(net "M_I_CPU1_SB_DQ<29>")
	)
	(arc
		(start 131.627626 -293.038784)
		(mid 131.809877 -293.089134)
		(end 131.993386 -293.04361)
		(width 0.0889)
		(layer "In2.Cu")
		(net "M_I_CPU1_SB_DQ<29>")
	)
	(arc
		(start 133.516116 -293.04361)
		(mid 133.699624 -293.089104)
		(end 133.881876 -293.038784)
		(width 0.0889)
		(layer "In2.Cu")
		(net "M_I_CPU1_SB_DQ<29>")
	)
	(arc
		(start 139.147804 -293.038784)
		(mid 139.334748 -293.089039)
		(end 139.521692 -293.038784)
		(width 0.0889)
		(layer "In2.Cu")
		(net "M_I_CPU1_SB_DQ<29>")
	)
	(arc
		(start 137.276078 -293.04361)
		(mid 137.459586 -293.089104)
		(end 137.641838 -293.038784)
		(width 0.0889)
		(layer "In2.Cu")
		(net "M_I_CPU1_SB_DQ<29>")
	)
	(arc
		(start 135.387588 -293.038784)
		(mid 135.569839 -293.089134)
		(end 135.753348 -293.04361)
		(width 0.0889)
		(layer "In2.Cu")
		(net "M_I_CPU1_SB_DQ<29>")
	)
	(arc
		(start 131.061714 -293.038784)
		(mid 131.34467 -292.962607)
		(end 131.627626 -293.038784)
		(width 0.0889)
		(layer "In2.Cu")
		(net "M_I_CPU1_SB_DQ<29>")
	)
	(arc
		(start 137.641838 -293.038784)
		(mid 137.924794 -292.962607)
		(end 138.20775 -293.038784)
		(width 0.0889)
		(layer "In2.Cu")
		(net "M_I_CPU1_SB_DQ<29>")
	)
	(arc
		(start 140.087604 -293.038784)
		(mid 140.269855 -293.089134)
		(end 140.453364 -293.04361)
		(width 0.0889)
		(layer "In2.Cu")
		(net "M_I_CPU1_SB_DQ<29>")
	)
	(arc
		(start 142.944088 -294.679878)
		(mid 143.12474 -294.882623)
		(end 143.18996 -295.146222)
		(width 0.0889)
		(layer "In2.Cu")
		(net "M_I_CPU1_SB_DQ<29>")
	)
	(arc
		(start 128.304798 -293.007034)
		(mid 128.560006 -292.963557)
		(end 128.807718 -293.038784)
		(width 0.0889)
		(layer "In2.Cu")
		(net "M_I_CPU1_SB_DQ<29>")
	)
	(arc
		(start 142.72006 -294.336216)
		(mid 142.761315 -294.507187)
		(end 142.876016 -294.640508)
		(width 0.0889)
		(layer "In2.Cu")
		(net "M_I_CPU1_SB_DQ<29>")
	)
	(arc
		(start 139.521692 -293.038784)
		(mid 139.804648 -292.962607)
		(end 140.087604 -293.038784)
		(width 0.0889)
		(layer "In2.Cu")
		(net "M_I_CPU1_SB_DQ<29>")
	)
	(arc
		(start 132.941822 -293.038784)
		(mid 133.224778 -292.962607)
		(end 133.507734 -293.038784)
		(width 0.0889)
		(layer "In2.Cu")
		(net "M_I_CPU1_SB_DQ<29>")
	)
	(arc
		(start 136.701784 -293.038784)
		(mid 136.98474 -292.962607)
		(end 137.267696 -293.038784)
		(width 0.0889)
		(layer "In2.Cu")
		(net "M_I_CPU1_SB_DQ<29>")
	)
	(arc
		(start 129.756154 -293.04361)
		(mid 129.939662 -293.089104)
		(end 130.121914 -293.038784)
		(width 0.0889)
		(layer "In2.Cu")
		(net "M_I_CPU1_SB_DQ<29>")
	)
	(arc
		(start 143.413988 -295.489884)
		(mid 143.59464 -295.692629)
		(end 143.65986 -295.956228)
		(width 0.0889)
		(layer "In2.Cu")
		(net "M_I_CPU1_SB_DQ<29>")
	)
	(arc
		(start 136.327642 -293.038784)
		(mid 136.509893 -293.089134)
		(end 136.693402 -293.04361)
		(width 0.0889)
		(layer "In2.Cu")
		(net "M_I_CPU1_SB_DQ<29>")
	)
	(arc
		(start 134.821676 -293.038784)
		(mid 135.104632 -292.962607)
		(end 135.387588 -293.038784)
		(width 0.0889)
		(layer "In2.Cu")
		(net "M_I_CPU1_SB_DQ<29>")
	)
	(arc
		(start 130.687826 -293.038784)
		(mid 130.87477 -293.089039)
		(end 131.061714 -293.038784)
		(width 0.0889)
		(layer "In2.Cu")
		(net "M_I_CPU1_SB_DQ<29>")
	)
	(arc
		(start 141.027658 -293.038784)
		(mid 141.209909 -293.089134)
		(end 141.393418 -293.04361)
		(width 0.0889)
		(layer "In2.Cu")
		(net "M_I_CPU1_SB_DQ<29>")
	)
	(arc
		(start 130.121914 -293.038784)
		(mid 130.40487 -292.962607)
		(end 130.687826 -293.038784)
		(width 0.0889)
		(layer "In2.Cu")
		(net "M_I_CPU1_SB_DQ<29>")
	)
	(arc
		(start 138.216132 -293.04361)
		(mid 138.39964 -293.089104)
		(end 138.581892 -293.038784)
		(width 0.0889)
		(layer "In2.Cu")
		(net "M_I_CPU1_SB_DQ<29>")
	)
	(arc
		(start 142.476728 -293.87165)
		(mid 142.655541 -294.074)
		(end 142.72006 -294.336216)
		(width 0.0889)
		(layer "In2.Cu")
		(net "M_I_CPU1_SB_DQ<29>")
	)
	(arc
		(start 134.447788 -293.038784)
		(mid 134.634732 -293.089039)
		(end 134.821676 -293.038784)
		(width 0.0889)
		(layer "In2.Cu")
		(net "M_I_CPU1_SB_DQ<29>")
	)
	(arc
		(start 129.18186 -293.038784)
		(mid 129.464816 -292.962607)
		(end 129.747772 -293.038784)
		(width 0.0889)
		(layer "In2.Cu")
		(net "M_I_CPU1_SB_DQ<29>")
	)
	(arc
		(start 138.581892 -293.038784)
		(mid 138.864848 -292.962607)
		(end 139.147804 -293.038784)
		(width 0.0889)
		(layer "In2.Cu")
		(net "M_I_CPU1_SB_DQ<29>")
	)
	(arc
		(start 128.8161 -293.04361)
		(mid 128.999608 -293.089104)
		(end 129.18186 -293.038784)
		(width 0.0889)
		(layer "In2.Cu")
		(net "M_I_CPU1_SB_DQ<29>")
	)
	(arc
		(start 142.006828 -293.061644)
		(mid 142.185641 -293.263994)
		(end 142.25016 -293.52621)
		(width 0.0889)
		(layer "In2.Cu")
		(net "M_I_CPU1_SB_DQ<29>")
	)
	(arc
		(start 133.881876 -293.038784)
		(mid 134.164832 -292.962607)
		(end 134.447788 -293.038784)
		(width 0.0889)
		(layer "In2.Cu")
		(net "M_I_CPU1_SB_DQ<29>")
	)
	(arc
		(start 143.18996 -295.146222)
		(mid 143.231215 -295.317193)
		(end 143.345916 -295.450514)
		(width 0.0889)
		(layer "In2.Cu")
		(net "M_I_CPU1_SB_DQ<29>")
	)
	(arc
		(start 135.76173 -293.038784)
		(mid 136.044686 -292.962607)
		(end 136.327642 -293.038784)
		(width 0.0889)
		(layer "In2.Cu")
		(net "M_I_CPU1_SB_DQ<29>")
	)
	(arc
		(start 141.4018 -293.038784)
		(mid 141.684756 -292.962607)
		(end 141.967712 -293.038784)
		(width 0.0889)
		(layer "In2.Cu")
		(net "M_I_CPU1_SB_DQ<29>")
	)
	(arc
		(start 142.25016 -293.52621)
		(mid 142.291709 -293.697632)
		(end 142.407132 -293.83101)
		(width 0.0889)
		(layer "In2.Cu")
		(net "M_I_CPU1_SB_DQ<29>")
	)
	(arc
		(start 132.56768 -293.038784)
		(mid 132.749931 -293.089134)
		(end 132.93344 -293.04361)
		(width 0.0889)
		(layer "In2.Cu")
		(net "M_I_CPU1_SB_DQ<29>")
	)
	(segment
		(start 128.997964 -291.64026)
		(end 129.464816 -291.906198)
		(width 0.10668)
		(layer "F.Cu")
		(net "M_I_CPU1_SB_DQ<28>")
	)
	(segment
		(start 144.731994 -296.41419)
		(end 144.731994 -296.90822)
		(width 0.14478)
		(layer "In2.Cu")
		(net "M_I_CPU1_SB_DQ<28>")
	)
	(segment
		(start 134.343394 -292.233604)
		(end 134.351776 -292.228778)
		(width 0.0889)
		(layer "In2.Cu")
		(net "M_I_CPU1_SB_DQ<28>")
	)
	(segment
		(start 183.181244 -315.92012)
		(end 183.616092 -315.485272)
		(width 0.14478)
		(layer "In2.Cu")
		(net "M_I_CPU1_SB_DQ<28>")
	)
	(segment
		(start 130.583432 -292.233604)
		(end 130.591814 -292.228778)
		(width 0.0889)
		(layer "In2.Cu")
		(net "M_I_CPU1_SB_DQ<28>")
	)
	(segment
		(start 182.090314 -316.081664)
		(end 182.090314 -316.433962)
		(width 0.14478)
		(layer "In2.Cu")
		(net "M_I_CPU1_SB_DQ<28>")
	)
	(segment
		(start 182.803292 -315.92012)
		(end 183.181244 -315.92012)
		(width 0.14478)
		(layer "In2.Cu")
		(net "M_I_CPU1_SB_DQ<28>")
	)
	(segment
		(start 144.599914 -296.28211)
		(end 144.731994 -296.41419)
		(width 0.0889)
		(layer "In2.Cu")
		(net "M_I_CPU1_SB_DQ<28>")
	)
	(segment
		(start 144.731994 -296.90822)
		(end 146.051524 -300.094142)
		(width 0.14478)
		(layer "In2.Cu")
		(net "M_I_CPU1_SB_DQ<28>")
	)
	(segment
		(start 144.599914 -295.956228)
		(end 144.599914 -296.28211)
		(width 0.0889)
		(layer "In2.Cu")
		(net "M_I_CPU1_SB_DQ<28>")
	)
	(segment
		(start 180.825902 -315.92012)
		(end 180.987446 -316.081664)
		(width 0.14478)
		(layer "In2.Cu")
		(net "M_I_CPU1_SB_DQ<28>")
	)
	(segment
		(start 143.345916 -293.830502)
		(end 143.377666 -293.84879)
		(width 0.0889)
		(layer "In2.Cu")
		(net "M_I_CPU1_SB_DQ<28>")
	)
	(segment
		(start 181.14899 -316.595506)
		(end 181.377336 -316.595506)
		(width 0.14478)
		(layer "In2.Cu")
		(net "M_I_CPU1_SB_DQ<28>")
	)
	(segment
		(start 143.377666 -293.84879)
		(end 143.413988 -293.869872)
		(width 0.0889)
		(layer "In2.Cu")
		(net "M_I_CPU1_SB_DQ<28>")
	)
	(segment
		(start 132.09778 -292.228778)
		(end 132.106162 -292.233604)
		(width 0.0889)
		(layer "In2.Cu")
		(net "M_I_CPU1_SB_DQ<28>")
	)
	(segment
		(start 144.286732 -295.451022)
		(end 144.317212 -295.468802)
		(width 0.0889)
		(layer "In2.Cu")
		(net "M_I_CPU1_SB_DQ<28>")
	)
	(segment
		(start 181.92877 -315.92012)
		(end 182.090314 -316.081664)
		(width 0.14478)
		(layer "In2.Cu")
		(net "M_I_CPU1_SB_DQ<28>")
	)
	(segment
		(start 182.090314 -316.433962)
		(end 182.251858 -316.595506)
		(width 0.14478)
		(layer "In2.Cu")
		(net "M_I_CPU1_SB_DQ<28>")
	)
	(segment
		(start 139.617704 -292.228778)
		(end 139.626086 -292.233604)
		(width 0.0889)
		(layer "In2.Cu")
		(net "M_I_CPU1_SB_DQ<28>")
	)
	(segment
		(start 134.917688 -292.228778)
		(end 134.92607 -292.233604)
		(width 0.0889)
		(layer "In2.Cu")
		(net "M_I_CPU1_SB_DQ<28>")
	)
	(segment
		(start 182.641748 -316.433962)
		(end 182.641748 -316.081664)
		(width 0.14478)
		(layer "In2.Cu")
		(net "M_I_CPU1_SB_DQ<28>")
	)
	(segment
		(start 181.53888 -316.433962)
		(end 181.53888 -316.081664)
		(width 0.14478)
		(layer "In2.Cu")
		(net "M_I_CPU1_SB_DQ<28>")
	)
	(segment
		(start 182.251858 -316.595506)
		(end 182.480204 -316.595506)
		(width 0.14478)
		(layer "In2.Cu")
		(net "M_I_CPU1_SB_DQ<28>")
	)
	(segment
		(start 142.907766 -293.038784)
		(end 142.944088 -293.059866)
		(width 0.0889)
		(layer "In2.Cu")
		(net "M_I_CPU1_SB_DQ<28>")
	)
	(segment
		(start 161.877502 -315.92012)
		(end 180.825902 -315.92012)
		(width 0.14478)
		(layer "In2.Cu")
		(net "M_I_CPU1_SB_DQ<28>")
	)
	(segment
		(start 181.53888 -316.081664)
		(end 181.700424 -315.92012)
		(width 0.14478)
		(layer "In2.Cu")
		(net "M_I_CPU1_SB_DQ<28>")
	)
	(segment
		(start 129.464816 -291.906198)
		(end 129.61874 -292.171628)
		(width 0.0889)
		(layer "In2.Cu")
		(net "M_I_CPU1_SB_DQ<28>")
	)
	(segment
		(start 135.857742 -292.228778)
		(end 135.866124 -292.233604)
		(width 0.0889)
		(layer "In2.Cu")
		(net "M_I_CPU1_SB_DQ<28>")
	)
	(segment
		(start 181.377336 -316.595506)
		(end 181.53888 -316.433962)
		(width 0.14478)
		(layer "In2.Cu")
		(net "M_I_CPU1_SB_DQ<28>")
	)
	(segment
		(start 131.157726 -292.228778)
		(end 131.166108 -292.233604)
		(width 0.0889)
		(layer "In2.Cu")
		(net "M_I_CPU1_SB_DQ<28>")
	)
	(segment
		(start 142.437612 -292.228778)
		(end 142.476728 -292.251638)
		(width 0.0889)
		(layer "In2.Cu")
		(net "M_I_CPU1_SB_DQ<28>")
	)
	(segment
		(start 129.61874 -292.171628)
		(end 129.714752 -292.197028)
		(width 0.0889)
		(layer "In2.Cu")
		(net "M_I_CPU1_SB_DQ<28>")
	)
	(segment
		(start 180.987446 -316.081664)
		(end 180.987446 -316.433962)
		(width 0.14478)
		(layer "In2.Cu")
		(net "M_I_CPU1_SB_DQ<28>")
	)
	(segment
		(start 182.480204 -316.595506)
		(end 182.641748 -316.433962)
		(width 0.14478)
		(layer "In2.Cu")
		(net "M_I_CPU1_SB_DQ<28>")
	)
	(segment
		(start 138.103356 -292.233604)
		(end 138.111738 -292.228778)
		(width 0.0889)
		(layer "In2.Cu")
		(net "M_I_CPU1_SB_DQ<28>")
	)
	(segment
		(start 180.987446 -316.433962)
		(end 181.14899 -316.595506)
		(width 0.14478)
		(layer "In2.Cu")
		(net "M_I_CPU1_SB_DQ<28>")
	)
	(segment
		(start 182.641748 -316.081664)
		(end 182.803292 -315.92012)
		(width 0.14478)
		(layer "In2.Cu")
		(net "M_I_CPU1_SB_DQ<28>")
	)
	(segment
		(start 140.557758 -292.228778)
		(end 140.56614 -292.233604)
		(width 0.0889)
		(layer "In2.Cu")
		(net "M_I_CPU1_SB_DQ<28>")
	)
	(segment
		(start 142.876016 -293.020496)
		(end 142.907766 -293.038784)
		(width 0.0889)
		(layer "In2.Cu")
		(net "M_I_CPU1_SB_DQ<28>")
	)
	(segment
		(start 144.317212 -295.468802)
		(end 144.359122 -295.493186)
		(width 0.0889)
		(layer "In2.Cu")
		(net "M_I_CPU1_SB_DQ<28>")
	)
	(segment
		(start 181.700424 -315.92012)
		(end 181.92877 -315.92012)
		(width 0.14478)
		(layer "In2.Cu")
		(net "M_I_CPU1_SB_DQ<28>")
	)
	(segment
		(start 143.847566 -294.658796)
		(end 143.883888 -294.679878)
		(width 0.0889)
		(layer "In2.Cu")
		(net "M_I_CPU1_SB_DQ<28>")
	)
	(segment
		(start 143.815816 -294.640508)
		(end 143.847566 -294.658796)
		(width 0.0889)
		(layer "In2.Cu")
		(net "M_I_CPU1_SB_DQ<28>")
	)
	(segment
		(start 146.051524 -300.094142)
		(end 161.877502 -315.92012)
		(width 0.14478)
		(layer "In2.Cu")
		(net "M_I_CPU1_SB_DQ<28>")
	)
	(segment
		(start 139.04341 -292.233604)
		(end 139.051792 -292.228778)
		(width 0.0889)
		(layer "In2.Cu")
		(net "M_I_CPU1_SB_DQ<28>")
	)
	(arc
		(start 136.797796 -292.228778)
		(mid 136.98474 -292.279033)
		(end 137.171684 -292.228778)
		(width 0.0889)
		(layer "In2.Cu")
		(net "M_I_CPU1_SB_DQ<28>")
	)
	(arc
		(start 143.65986 -294.336216)
		(mid 143.701115 -294.507187)
		(end 143.815816 -294.640508)
		(width 0.0889)
		(layer "In2.Cu")
		(net "M_I_CPU1_SB_DQ<28>")
	)
	(arc
		(start 129.714752 -292.197028)
		(mid 129.96996 -292.153551)
		(end 130.217672 -292.228778)
		(width 0.0889)
		(layer "In2.Cu")
		(net "M_I_CPU1_SB_DQ<28>")
	)
	(arc
		(start 143.883888 -294.679878)
		(mid 144.06454 -294.882623)
		(end 144.12976 -295.146222)
		(width 0.0889)
		(layer "In2.Cu")
		(net "M_I_CPU1_SB_DQ<28>")
	)
	(arc
		(start 135.866124 -292.233604)
		(mid 136.049632 -292.279098)
		(end 136.231884 -292.228778)
		(width 0.0889)
		(layer "In2.Cu")
		(net "M_I_CPU1_SB_DQ<28>")
	)
	(arc
		(start 131.166108 -292.233604)
		(mid 131.349616 -292.279098)
		(end 131.531868 -292.228778)
		(width 0.0889)
		(layer "In2.Cu")
		(net "M_I_CPU1_SB_DQ<28>")
	)
	(arc
		(start 133.037834 -292.228778)
		(mid 133.224778 -292.279033)
		(end 133.411722 -292.228778)
		(width 0.0889)
		(layer "In2.Cu")
		(net "M_I_CPU1_SB_DQ<28>")
	)
	(arc
		(start 143.413988 -293.869872)
		(mid 143.59464 -294.072617)
		(end 143.65986 -294.336216)
		(width 0.0889)
		(layer "In2.Cu")
		(net "M_I_CPU1_SB_DQ<28>")
	)
	(arc
		(start 138.111738 -292.228778)
		(mid 138.394694 -292.152601)
		(end 138.67765 -292.228778)
		(width 0.0889)
		(layer "In2.Cu")
		(net "M_I_CPU1_SB_DQ<28>")
	)
	(arc
		(start 141.497812 -292.228778)
		(mid 141.684756 -292.279033)
		(end 141.8717 -292.228778)
		(width 0.0889)
		(layer "In2.Cu")
		(net "M_I_CPU1_SB_DQ<28>")
	)
	(arc
		(start 139.051792 -292.228778)
		(mid 139.334748 -292.152601)
		(end 139.617704 -292.228778)
		(width 0.0889)
		(layer "In2.Cu")
		(net "M_I_CPU1_SB_DQ<28>")
	)
	(arc
		(start 138.67765 -292.228778)
		(mid 138.859901 -292.279128)
		(end 139.04341 -292.233604)
		(width 0.0889)
		(layer "In2.Cu")
		(net "M_I_CPU1_SB_DQ<28>")
	)
	(arc
		(start 144.12976 -295.146222)
		(mid 144.171309 -295.317644)
		(end 144.286732 -295.451022)
		(width 0.0889)
		(layer "In2.Cu")
		(net "M_I_CPU1_SB_DQ<28>")
	)
	(arc
		(start 132.471922 -292.228778)
		(mid 132.754878 -292.152601)
		(end 133.037834 -292.228778)
		(width 0.0889)
		(layer "In2.Cu")
		(net "M_I_CPU1_SB_DQ<28>")
	)
	(arc
		(start 134.351776 -292.228778)
		(mid 134.634732 -292.152601)
		(end 134.917688 -292.228778)
		(width 0.0889)
		(layer "In2.Cu")
		(net "M_I_CPU1_SB_DQ<28>")
	)
	(arc
		(start 139.626086 -292.233604)
		(mid 139.809594 -292.279098)
		(end 139.991846 -292.228778)
		(width 0.0889)
		(layer "In2.Cu")
		(net "M_I_CPU1_SB_DQ<28>")
	)
	(arc
		(start 141.8717 -292.228778)
		(mid 142.154656 -292.152601)
		(end 142.437612 -292.228778)
		(width 0.0889)
		(layer "In2.Cu")
		(net "M_I_CPU1_SB_DQ<28>")
	)
	(arc
		(start 130.217672 -292.228778)
		(mid 130.399923 -292.279128)
		(end 130.583432 -292.233604)
		(width 0.0889)
		(layer "In2.Cu")
		(net "M_I_CPU1_SB_DQ<28>")
	)
	(arc
		(start 133.411722 -292.228778)
		(mid 133.694678 -292.152601)
		(end 133.977634 -292.228778)
		(width 0.0889)
		(layer "In2.Cu")
		(net "M_I_CPU1_SB_DQ<28>")
	)
	(arc
		(start 142.476728 -292.251638)
		(mid 142.655541 -292.453988)
		(end 142.72006 -292.716204)
		(width 0.0889)
		(layer "In2.Cu")
		(net "M_I_CPU1_SB_DQ<28>")
	)
	(arc
		(start 133.977634 -292.228778)
		(mid 134.159885 -292.279128)
		(end 134.343394 -292.233604)
		(width 0.0889)
		(layer "In2.Cu")
		(net "M_I_CPU1_SB_DQ<28>")
	)
	(arc
		(start 132.106162 -292.233604)
		(mid 132.28967 -292.279098)
		(end 132.471922 -292.228778)
		(width 0.0889)
		(layer "In2.Cu")
		(net "M_I_CPU1_SB_DQ<28>")
	)
	(arc
		(start 142.72006 -292.716204)
		(mid 142.761315 -292.887175)
		(end 142.876016 -293.020496)
		(width 0.0889)
		(layer "In2.Cu")
		(net "M_I_CPU1_SB_DQ<28>")
	)
	(arc
		(start 140.9319 -292.228778)
		(mid 141.214856 -292.152601)
		(end 141.497812 -292.228778)
		(width 0.0889)
		(layer "In2.Cu")
		(net "M_I_CPU1_SB_DQ<28>")
	)
	(arc
		(start 139.991846 -292.228778)
		(mid 140.274802 -292.152601)
		(end 140.557758 -292.228778)
		(width 0.0889)
		(layer "In2.Cu")
		(net "M_I_CPU1_SB_DQ<28>")
	)
	(arc
		(start 137.171684 -292.228778)
		(mid 137.45464 -292.152601)
		(end 137.737596 -292.228778)
		(width 0.0889)
		(layer "In2.Cu")
		(net "M_I_CPU1_SB_DQ<28>")
	)
	(arc
		(start 134.92607 -292.233604)
		(mid 135.109578 -292.279098)
		(end 135.29183 -292.228778)
		(width 0.0889)
		(layer "In2.Cu")
		(net "M_I_CPU1_SB_DQ<28>")
	)
	(arc
		(start 140.56614 -292.233604)
		(mid 140.749648 -292.279098)
		(end 140.9319 -292.228778)
		(width 0.0889)
		(layer "In2.Cu")
		(net "M_I_CPU1_SB_DQ<28>")
	)
	(arc
		(start 137.737596 -292.228778)
		(mid 137.919847 -292.279128)
		(end 138.103356 -292.233604)
		(width 0.0889)
		(layer "In2.Cu")
		(net "M_I_CPU1_SB_DQ<28>")
	)
	(arc
		(start 142.944088 -293.059866)
		(mid 143.12474 -293.262611)
		(end 143.18996 -293.52621)
		(width 0.0889)
		(layer "In2.Cu")
		(net "M_I_CPU1_SB_DQ<28>")
	)
	(arc
		(start 136.231884 -292.228778)
		(mid 136.51484 -292.152601)
		(end 136.797796 -292.228778)
		(width 0.0889)
		(layer "In2.Cu")
		(net "M_I_CPU1_SB_DQ<28>")
	)
	(arc
		(start 131.531868 -292.228778)
		(mid 131.814824 -292.152601)
		(end 132.09778 -292.228778)
		(width 0.0889)
		(layer "In2.Cu")
		(net "M_I_CPU1_SB_DQ<28>")
	)
	(arc
		(start 143.18996 -293.52621)
		(mid 143.231215 -293.697181)
		(end 143.345916 -293.830502)
		(width 0.0889)
		(layer "In2.Cu")
		(net "M_I_CPU1_SB_DQ<28>")
	)
	(arc
		(start 130.591814 -292.228778)
		(mid 130.87477 -292.152601)
		(end 131.157726 -292.228778)
		(width 0.0889)
		(layer "In2.Cu")
		(net "M_I_CPU1_SB_DQ<28>")
	)
	(arc
		(start 144.359122 -295.493186)
		(mid 144.536104 -295.695278)
		(end 144.599914 -295.956228)
		(width 0.0889)
		(layer "In2.Cu")
		(net "M_I_CPU1_SB_DQ<28>")
	)
	(arc
		(start 135.29183 -292.228778)
		(mid 135.574786 -292.152601)
		(end 135.857742 -292.228778)
		(width 0.0889)
		(layer "In2.Cu")
		(net "M_I_CPU1_SB_DQ<28>")
	)
	(segment
		(start 128.05791 -290.020248)
		(end 128.524762 -290.286186)
		(width 0.10668)
		(layer "F.Cu")
		(net "M_I_CPU1_SB_DQ<27>")
	)
	(segment
		(start 131.157726 -289.963606)
		(end 131.166108 -289.95878)
		(width 0.0889)
		(layer "In2.Cu")
		(net "M_I_CPU1_SB_DQ<27>")
	)
	(segment
		(start 156.814012 -307.619654)
		(end 156.976064 -307.781706)
		(width 0.14478)
		(layer "In2.Cu")
		(net "M_I_CPU1_SB_DQ<27>")
	)
	(segment
		(start 155.44419 -305.640486)
		(end 155.253436 -305.830986)
		(width 0.14478)
		(layer "In2.Cu")
		(net "M_I_CPU1_SB_DQ<27>")
	)
	(segment
		(start 165.265862 -312.500518)
		(end 166.334694 -312.057796)
		(width 0.14478)
		(layer "In2.Cu")
		(net "M_I_CPU1_SB_DQ<27>")
	)
	(segment
		(start 134.917688 -289.963606)
		(end 134.92607 -289.95878)
		(width 0.0889)
		(layer "In2.Cu")
		(net "M_I_CPU1_SB_DQ<27>")
	)
	(segment
		(start 156.976064 -307.781706)
		(end 157.20441 -307.781706)
		(width 0.14478)
		(layer "In2.Cu")
		(net "M_I_CPU1_SB_DQ<27>")
	)
	(segment
		(start 173.635162 -311.708546)
		(end 174.055786 -311.79262)
		(width 0.14478)
		(layer "In2.Cu")
		(net "M_I_CPU1_SB_DQ<27>")
	)
	(segment
		(start 147.773644 -296.443654)
		(end 148.691854 -298.660058)
		(width 0.14478)
		(layer "In2.Cu")
		(net "M_I_CPU1_SB_DQ<27>")
	)
	(segment
		(start 142.803372 -289.95878)
		(end 142.811754 -289.963606)
		(width 0.0889)
		(layer "In2.Cu")
		(net "M_I_CPU1_SB_DQ<27>")
	)
	(segment
		(start 157.004766 -307.201062)
		(end 156.814012 -307.391562)
		(width 0.14478)
		(layer "In2.Cu")
		(net "M_I_CPU1_SB_DQ<27>")
	)
	(segment
		(start 143.751808 -289.963606)
		(end 143.782288 -289.981386)
		(width 0.0889)
		(layer "In2.Cu")
		(net "M_I_CPU1_SB_DQ<27>")
	)
	(segment
		(start 166.741856 -311.650634)
		(end 170.143678 -311.650634)
		(width 0.14478)
		(layer "In2.Cu")
		(net "M_I_CPU1_SB_DQ<27>")
	)
	(segment
		(start 134.343394 -289.95878)
		(end 134.351776 -289.963606)
		(width 0.0889)
		(layer "In2.Cu")
		(net "M_I_CPU1_SB_DQ<27>")
	)
	(segment
		(start 179.091082 -311.660286)
		(end 179.516024 -312.085228)
		(width 0.14478)
		(layer "In2.Cu")
		(net "M_I_CPU1_SB_DQ<27>")
	)
	(segment
		(start 155.44419 -305.412394)
		(end 155.44419 -305.640486)
		(width 0.14478)
		(layer "In2.Cu")
		(net "M_I_CPU1_SB_DQ<27>")
	)
	(segment
		(start 157.785054 -307.98135)
		(end 157.5943 -308.17185)
		(width 0.14478)
		(layer "In2.Cu")
		(net "M_I_CPU1_SB_DQ<27>")
	)
	(segment
		(start 146.36369 -295.0337)
		(end 146.585686 -295.255696)
		(width 0.0889)
		(layer "In2.Cu")
		(net "M_I_CPU1_SB_DQ<27>")
	)
	(segment
		(start 156.224478 -306.420774)
		(end 156.033724 -306.611274)
		(width 0.14478)
		(layer "In2.Cu")
		(net "M_I_CPU1_SB_DQ<27>")
	)
	(segment
		(start 138.103356 -289.95878)
		(end 138.111738 -289.963606)
		(width 0.0889)
		(layer "In2.Cu")
		(net "M_I_CPU1_SB_DQ<27>")
	)
	(segment
		(start 148.691854 -298.660058)
		(end 155.44419 -305.412394)
		(width 0.14478)
		(layer "In2.Cu")
		(net "M_I_CPU1_SB_DQ<27>")
	)
	(segment
		(start 146.32178 -294.720518)
		(end 146.36369 -294.82161)
		(width 0.0889)
		(layer "In2.Cu")
		(net "M_I_CPU1_SB_DQ<27>")
	)
	(segment
		(start 177.66284 -311.385204)
		(end 177.937922 -311.660286)
		(width 0.14478)
		(layer "In2.Cu")
		(net "M_I_CPU1_SB_DQ<27>")
	)
	(segment
		(start 173.338744 -312.271664)
		(end 173.422564 -311.850786)
		(width 0.14478)
		(layer "In2.Cu")
		(net "M_I_CPU1_SB_DQ<27>")
	)
	(segment
		(start 156.424122 -307.001418)
		(end 156.614622 -306.810918)
		(width 0.14478)
		(layer "In2.Cu")
		(net "M_I_CPU1_SB_DQ<27>")
	)
	(segment
		(start 170.993562 -312.500518)
		(end 172.996352 -312.500518)
		(width 0.14478)
		(layer "In2.Cu")
		(net "M_I_CPU1_SB_DQ<27>")
	)
	(segment
		(start 163.535868 -312.500518)
		(end 165.265862 -312.500518)
		(width 0.14478)
		(layer "In2.Cu")
		(net "M_I_CPU1_SB_DQ<27>")
	)
	(segment
		(start 174.268384 -311.650634)
		(end 177.113692 -311.650634)
		(width 0.14478)
		(layer "In2.Cu")
		(net "M_I_CPU1_SB_DQ<27>")
	)
	(segment
		(start 157.5943 -308.399942)
		(end 161.620962 -312.426604)
		(width 0.14478)
		(layer "In2.Cu")
		(net "M_I_CPU1_SB_DQ<27>")
	)
	(segment
		(start 156.814012 -307.391562)
		(end 156.814012 -307.619654)
		(width 0.14478)
		(layer "In2.Cu")
		(net "M_I_CPU1_SB_DQ<27>")
	)
	(segment
		(start 146.36369 -294.82161)
		(end 146.36369 -295.0337)
		(width 0.0889)
		(layer "In2.Cu")
		(net "M_I_CPU1_SB_DQ<27>")
	)
	(segment
		(start 156.195776 -307.001418)
		(end 156.424122 -307.001418)
		(width 0.14478)
		(layer "In2.Cu")
		(net "M_I_CPU1_SB_DQ<27>")
	)
	(segment
		(start 144.221708 -290.773612)
		(end 144.253458 -290.7919)
		(width 0.0889)
		(layer "In2.Cu")
		(net "M_I_CPU1_SB_DQ<27>")
	)
	(segment
		(start 163.329366 -312.294016)
		(end 163.535868 -312.500518)
		(width 0.14478)
		(layer "In2.Cu")
		(net "M_I_CPU1_SB_DQ<27>")
	)
	(segment
		(start 144.182592 -290.750752)
		(end 144.221708 -290.773612)
		(width 0.0889)
		(layer "In2.Cu")
		(net "M_I_CPU1_SB_DQ<27>")
	)
	(segment
		(start 155.253436 -305.830986)
		(end 155.253436 -306.059078)
		(width 0.14478)
		(layer "In2.Cu")
		(net "M_I_CPU1_SB_DQ<27>")
	)
	(segment
		(start 162.82416 -312.294016)
		(end 163.329366 -312.294016)
		(width 0.14478)
		(layer "In2.Cu")
		(net "M_I_CPU1_SB_DQ<27>")
	)
	(segment
		(start 177.113692 -311.650634)
		(end 177.379122 -311.385204)
		(width 0.14478)
		(layer "In2.Cu")
		(net "M_I_CPU1_SB_DQ<27>")
	)
	(segment
		(start 129.643378 -289.95878)
		(end 129.65176 -289.963606)
		(width 0.0889)
		(layer "In2.Cu")
		(net "M_I_CPU1_SB_DQ<27>")
	)
	(segment
		(start 173.422564 -311.850786)
		(end 173.635162 -311.708546)
		(width 0.14478)
		(layer "In2.Cu")
		(net "M_I_CPU1_SB_DQ<27>")
	)
	(segment
		(start 128.370838 -290.020756)
		(end 128.39319 -289.937444)
		(width 0.0889)
		(layer "In2.Cu")
		(net "M_I_CPU1_SB_DQ<27>")
	)
	(segment
		(start 174.055786 -311.79262)
		(end 174.268384 -311.650634)
		(width 0.14478)
		(layer "In2.Cu")
		(net "M_I_CPU1_SB_DQ<27>")
	)
	(segment
		(start 155.834334 -306.03063)
		(end 156.062426 -306.03063)
		(width 0.14478)
		(layer "In2.Cu")
		(net "M_I_CPU1_SB_DQ<27>")
	)
	(segment
		(start 177.379122 -311.385204)
		(end 177.66284 -311.385204)
		(width 0.14478)
		(layer "In2.Cu")
		(net "M_I_CPU1_SB_DQ<27>")
	)
	(segment
		(start 132.09778 -289.963606)
		(end 132.106162 -289.95878)
		(width 0.0889)
		(layer "In2.Cu")
		(net "M_I_CPU1_SB_DQ<27>")
	)
	(segment
		(start 157.623002 -307.591206)
		(end 157.785054 -307.753258)
		(width 0.14478)
		(layer "In2.Cu")
		(net "M_I_CPU1_SB_DQ<27>")
	)
	(segment
		(start 156.614622 -306.810918)
		(end 156.842714 -306.810918)
		(width 0.14478)
		(layer "In2.Cu")
		(net "M_I_CPU1_SB_DQ<27>")
	)
	(segment
		(start 166.334694 -312.057796)
		(end 166.741856 -311.650634)
		(width 0.14478)
		(layer "In2.Cu")
		(net "M_I_CPU1_SB_DQ<27>")
	)
	(segment
		(start 128.524762 -290.286186)
		(end 128.370838 -290.020756)
		(width 0.0889)
		(layer "In2.Cu")
		(net "M_I_CPU1_SB_DQ<27>")
	)
	(segment
		(start 135.857742 -289.963606)
		(end 135.866124 -289.95878)
		(width 0.0889)
		(layer "In2.Cu")
		(net "M_I_CPU1_SB_DQ<27>")
	)
	(segment
		(start 144.76857 -292.069266)
		(end 144.892522 -292.2143)
		(width 0.0889)
		(layer "In2.Cu")
		(net "M_I_CPU1_SB_DQ<27>")
	)
	(segment
		(start 139.04341 -289.95878)
		(end 139.051792 -289.963606)
		(width 0.0889)
		(layer "In2.Cu")
		(net "M_I_CPU1_SB_DQ<27>")
	)
	(segment
		(start 157.004766 -306.97297)
		(end 157.004766 -307.201062)
		(width 0.14478)
		(layer "In2.Cu")
		(net "M_I_CPU1_SB_DQ<27>")
	)
	(segment
		(start 172.996352 -312.500518)
		(end 173.338744 -312.271664)
		(width 0.14478)
		(layer "In2.Cu")
		(net "M_I_CPU1_SB_DQ<27>")
	)
	(segment
		(start 161.620962 -312.426604)
		(end 162.691572 -312.426604)
		(width 0.14478)
		(layer "In2.Cu")
		(net "M_I_CPU1_SB_DQ<27>")
	)
	(segment
		(start 146.27987 -293.883334)
		(end 146.27987 -294.509444)
		(width 0.0889)
		(layer "In2.Cu")
		(net "M_I_CPU1_SB_DQ<27>")
	)
	(segment
		(start 139.617704 -289.963606)
		(end 139.626086 -289.95878)
		(width 0.0889)
		(layer "In2.Cu")
		(net "M_I_CPU1_SB_DQ<27>")
	)
	(segment
		(start 146.27987 -294.509444)
		(end 146.32178 -294.720518)
		(width 0.0889)
		(layer "In2.Cu")
		(net "M_I_CPU1_SB_DQ<27>")
	)
	(segment
		(start 156.033724 -306.839366)
		(end 156.195776 -307.001418)
		(width 0.14478)
		(layer "In2.Cu")
		(net "M_I_CPU1_SB_DQ<27>")
	)
	(segment
		(start 155.415488 -306.22113)
		(end 155.643834 -306.22113)
		(width 0.14478)
		(layer "In2.Cu")
		(net "M_I_CPU1_SB_DQ<27>")
	)
	(segment
		(start 157.20441 -307.781706)
		(end 157.39491 -307.591206)
		(width 0.14478)
		(layer "In2.Cu")
		(net "M_I_CPU1_SB_DQ<27>")
	)
	(segment
		(start 170.143678 -311.650634)
		(end 170.993562 -312.500518)
		(width 0.14478)
		(layer "In2.Cu")
		(net "M_I_CPU1_SB_DQ<27>")
	)
	(segment
		(start 156.224478 -306.192682)
		(end 156.224478 -306.420774)
		(width 0.14478)
		(layer "In2.Cu")
		(net "M_I_CPU1_SB_DQ<27>")
	)
	(segment
		(start 130.583432 -289.95878)
		(end 130.591814 -289.963606)
		(width 0.0889)
		(layer "In2.Cu")
		(net "M_I_CPU1_SB_DQ<27>")
	)
	(segment
		(start 140.557758 -289.963606)
		(end 140.56614 -289.95878)
		(width 0.0889)
		(layer "In2.Cu")
		(net "M_I_CPU1_SB_DQ<27>")
	)
	(segment
		(start 146.585686 -295.255696)
		(end 147.773644 -296.443654)
		(width 0.14478)
		(layer "In2.Cu")
		(net "M_I_CPU1_SB_DQ<27>")
	)
	(segment
		(start 155.253436 -306.059078)
		(end 155.415488 -306.22113)
		(width 0.14478)
		(layer "In2.Cu")
		(net "M_I_CPU1_SB_DQ<27>")
	)
	(segment
		(start 155.643834 -306.22113)
		(end 155.834334 -306.03063)
		(width 0.14478)
		(layer "In2.Cu")
		(net "M_I_CPU1_SB_DQ<27>")
	)
	(segment
		(start 144.892522 -292.2143)
		(end 146.00936 -293.323772)
		(width 0.0889)
		(layer "In2.Cu")
		(net "M_I_CPU1_SB_DQ<27>")
	)
	(segment
		(start 156.033724 -306.611274)
		(end 156.033724 -306.839366)
		(width 0.14478)
		(layer "In2.Cu")
		(net "M_I_CPU1_SB_DQ<27>")
	)
	(segment
		(start 157.39491 -307.591206)
		(end 157.623002 -307.591206)
		(width 0.14478)
		(layer "In2.Cu")
		(net "M_I_CPU1_SB_DQ<27>")
	)
	(segment
		(start 157.5943 -308.17185)
		(end 157.5943 -308.399942)
		(width 0.14478)
		(layer "In2.Cu")
		(net "M_I_CPU1_SB_DQ<27>")
	)
	(segment
		(start 162.691572 -312.426604)
		(end 162.82416 -312.294016)
		(width 0.14478)
		(layer "In2.Cu")
		(net "M_I_CPU1_SB_DQ<27>")
	)
	(segment
		(start 143.377666 -289.963606)
		(end 143.386048 -289.95878)
		(width 0.0889)
		(layer "In2.Cu")
		(net "M_I_CPU1_SB_DQ<27>")
	)
	(segment
		(start 156.062426 -306.03063)
		(end 156.224478 -306.192682)
		(width 0.14478)
		(layer "In2.Cu")
		(net "M_I_CPU1_SB_DQ<27>")
	)
	(segment
		(start 157.785054 -307.753258)
		(end 157.785054 -307.98135)
		(width 0.14478)
		(layer "In2.Cu")
		(net "M_I_CPU1_SB_DQ<27>")
	)
	(segment
		(start 177.937922 -311.660286)
		(end 179.091082 -311.660286)
		(width 0.14478)
		(layer "In2.Cu")
		(net "M_I_CPU1_SB_DQ<27>")
	)
	(segment
		(start 156.842714 -306.810918)
		(end 157.004766 -306.97297)
		(width 0.14478)
		(layer "In2.Cu")
		(net "M_I_CPU1_SB_DQ<27>")
	)
	(arc
		(start 136.797796 -289.963606)
		(mid 136.98474 -289.913351)
		(end 137.171684 -289.963606)
		(width 0.0889)
		(layer "In2.Cu")
		(net "M_I_CPU1_SB_DQ<27>")
	)
	(arc
		(start 143.93926 -290.286186)
		(mid 144.003775 -290.548405)
		(end 144.182592 -290.750752)
		(width 0.0889)
		(layer "In2.Cu")
		(net "M_I_CPU1_SB_DQ<27>")
	)
	(arc
		(start 142.811754 -289.963606)
		(mid 143.09471 -290.039783)
		(end 143.377666 -289.963606)
		(width 0.0889)
		(layer "In2.Cu")
		(net "M_I_CPU1_SB_DQ<27>")
	)
	(arc
		(start 138.67765 -289.963606)
		(mid 138.859901 -289.913256)
		(end 139.04341 -289.95878)
		(width 0.0889)
		(layer "In2.Cu")
		(net "M_I_CPU1_SB_DQ<27>")
	)
	(arc
		(start 140.56614 -289.95878)
		(mid 140.749648 -289.913286)
		(end 140.9319 -289.963606)
		(width 0.0889)
		(layer "In2.Cu")
		(net "M_I_CPU1_SB_DQ<27>")
	)
	(arc
		(start 139.991846 -289.963606)
		(mid 140.274802 -290.039783)
		(end 140.557758 -289.963606)
		(width 0.0889)
		(layer "In2.Cu")
		(net "M_I_CPU1_SB_DQ<27>")
	)
	(arc
		(start 144.409414 -291.096192)
		(mid 144.502065 -291.614815)
		(end 144.76857 -292.069266)
		(width 0.0889)
		(layer "In2.Cu")
		(net "M_I_CPU1_SB_DQ<27>")
	)
	(arc
		(start 130.217672 -289.963606)
		(mid 130.399923 -289.913256)
		(end 130.583432 -289.95878)
		(width 0.0889)
		(layer "In2.Cu")
		(net "M_I_CPU1_SB_DQ<27>")
	)
	(arc
		(start 130.591814 -289.963606)
		(mid 130.87477 -290.039783)
		(end 131.157726 -289.963606)
		(width 0.0889)
		(layer "In2.Cu")
		(net "M_I_CPU1_SB_DQ<27>")
	)
	(arc
		(start 134.92607 -289.95878)
		(mid 135.109578 -289.913286)
		(end 135.29183 -289.963606)
		(width 0.0889)
		(layer "In2.Cu")
		(net "M_I_CPU1_SB_DQ<27>")
	)
	(arc
		(start 128.39319 -289.937444)
		(mid 128.555379 -289.914709)
		(end 128.711706 -289.963606)
		(width 0.0889)
		(layer "In2.Cu")
		(net "M_I_CPU1_SB_DQ<27>")
	)
	(arc
		(start 132.106162 -289.95878)
		(mid 132.28967 -289.913286)
		(end 132.471922 -289.963606)
		(width 0.0889)
		(layer "In2.Cu")
		(net "M_I_CPU1_SB_DQ<27>")
	)
	(arc
		(start 141.8717 -289.963606)
		(mid 142.154656 -290.039783)
		(end 142.437612 -289.963606)
		(width 0.0889)
		(layer "In2.Cu")
		(net "M_I_CPU1_SB_DQ<27>")
	)
	(arc
		(start 139.626086 -289.95878)
		(mid 139.809594 -289.913286)
		(end 139.991846 -289.963606)
		(width 0.0889)
		(layer "In2.Cu")
		(net "M_I_CPU1_SB_DQ<27>")
	)
	(arc
		(start 133.037834 -289.963606)
		(mid 133.224778 -289.913351)
		(end 133.411722 -289.963606)
		(width 0.0889)
		(layer "In2.Cu")
		(net "M_I_CPU1_SB_DQ<27>")
	)
	(arc
		(start 141.497812 -289.963606)
		(mid 141.684756 -289.913351)
		(end 141.8717 -289.963606)
		(width 0.0889)
		(layer "In2.Cu")
		(net "M_I_CPU1_SB_DQ<27>")
	)
	(arc
		(start 143.386048 -289.95878)
		(mid 143.569556 -289.913286)
		(end 143.751808 -289.963606)
		(width 0.0889)
		(layer "In2.Cu")
		(net "M_I_CPU1_SB_DQ<27>")
	)
	(arc
		(start 133.977634 -289.963606)
		(mid 134.159885 -289.913256)
		(end 134.343394 -289.95878)
		(width 0.0889)
		(layer "In2.Cu")
		(net "M_I_CPU1_SB_DQ<27>")
	)
	(arc
		(start 131.531868 -289.963606)
		(mid 131.814824 -290.039783)
		(end 132.09778 -289.963606)
		(width 0.0889)
		(layer "In2.Cu")
		(net "M_I_CPU1_SB_DQ<27>")
	)
	(arc
		(start 134.351776 -289.963606)
		(mid 134.634732 -290.039783)
		(end 134.917688 -289.963606)
		(width 0.0889)
		(layer "In2.Cu")
		(net "M_I_CPU1_SB_DQ<27>")
	)
	(arc
		(start 146.00936 -293.323772)
		(mid 146.191942 -293.580676)
		(end 146.27987 -293.883334)
		(width 0.0889)
		(layer "In2.Cu")
		(net "M_I_CPU1_SB_DQ<27>")
	)
	(arc
		(start 133.411722 -289.963606)
		(mid 133.694678 -290.039783)
		(end 133.977634 -289.963606)
		(width 0.0889)
		(layer "In2.Cu")
		(net "M_I_CPU1_SB_DQ<27>")
	)
	(arc
		(start 131.166108 -289.95878)
		(mid 131.349616 -289.913286)
		(end 131.531868 -289.963606)
		(width 0.0889)
		(layer "In2.Cu")
		(net "M_I_CPU1_SB_DQ<27>")
	)
	(arc
		(start 136.231884 -289.963606)
		(mid 136.51484 -290.039783)
		(end 136.797796 -289.963606)
		(width 0.0889)
		(layer "In2.Cu")
		(net "M_I_CPU1_SB_DQ<27>")
	)
	(arc
		(start 140.9319 -289.963606)
		(mid 141.214856 -290.039783)
		(end 141.497812 -289.963606)
		(width 0.0889)
		(layer "In2.Cu")
		(net "M_I_CPU1_SB_DQ<27>")
	)
	(arc
		(start 129.65176 -289.963606)
		(mid 129.934716 -290.039783)
		(end 130.217672 -289.963606)
		(width 0.0889)
		(layer "In2.Cu")
		(net "M_I_CPU1_SB_DQ<27>")
	)
	(arc
		(start 139.051792 -289.963606)
		(mid 139.334748 -290.039783)
		(end 139.617704 -289.963606)
		(width 0.0889)
		(layer "In2.Cu")
		(net "M_I_CPU1_SB_DQ<27>")
	)
	(arc
		(start 137.737596 -289.963606)
		(mid 137.919847 -289.913256)
		(end 138.103356 -289.95878)
		(width 0.0889)
		(layer "In2.Cu")
		(net "M_I_CPU1_SB_DQ<27>")
	)
	(arc
		(start 132.471922 -289.963606)
		(mid 132.754878 -290.039783)
		(end 133.037834 -289.963606)
		(width 0.0889)
		(layer "In2.Cu")
		(net "M_I_CPU1_SB_DQ<27>")
	)
	(arc
		(start 135.866124 -289.95878)
		(mid 136.049632 -289.913286)
		(end 136.231884 -289.963606)
		(width 0.0889)
		(layer "In2.Cu")
		(net "M_I_CPU1_SB_DQ<27>")
	)
	(arc
		(start 144.253458 -290.7919)
		(mid 144.368134 -290.925234)
		(end 144.409414 -291.096192)
		(width 0.0889)
		(layer "In2.Cu")
		(net "M_I_CPU1_SB_DQ<27>")
	)
	(arc
		(start 138.111738 -289.963606)
		(mid 138.394694 -290.039783)
		(end 138.67765 -289.963606)
		(width 0.0889)
		(layer "In2.Cu")
		(net "M_I_CPU1_SB_DQ<27>")
	)
	(arc
		(start 137.171684 -289.963606)
		(mid 137.45464 -290.039783)
		(end 137.737596 -289.963606)
		(width 0.0889)
		(layer "In2.Cu")
		(net "M_I_CPU1_SB_DQ<27>")
	)
	(arc
		(start 143.782288 -289.981386)
		(mid 143.897715 -290.114762)
		(end 143.93926 -290.286186)
		(width 0.0889)
		(layer "In2.Cu")
		(net "M_I_CPU1_SB_DQ<27>")
	)
	(arc
		(start 135.29183 -289.963606)
		(mid 135.574786 -290.039783)
		(end 135.857742 -289.963606)
		(width 0.0889)
		(layer "In2.Cu")
		(net "M_I_CPU1_SB_DQ<27>")
	)
	(arc
		(start 142.437612 -289.963606)
		(mid 142.619863 -289.913256)
		(end 142.803372 -289.95878)
		(width 0.0889)
		(layer "In2.Cu")
		(net "M_I_CPU1_SB_DQ<27>")
	)
	(arc
		(start 129.277618 -289.963606)
		(mid 129.459869 -289.913256)
		(end 129.643378 -289.95878)
		(width 0.0889)
		(layer "In2.Cu")
		(net "M_I_CPU1_SB_DQ<27>")
	)
	(arc
		(start 128.711706 -289.963606)
		(mid 128.994662 -290.039783)
		(end 129.277618 -289.963606)
		(width 0.0889)
		(layer "In2.Cu")
		(net "M_I_CPU1_SB_DQ<27>")
	)
	(segment
		(start 129.467864 -289.210242)
		(end 129.934716 -289.47618)
		(width 0.10668)
		(layer "F.Cu")
		(net "M_I_CPU1_SB_DQ<26>")
	)
	(segment
		(start 146.458686 -292.597078)
		(end 146.458686 -293.005002)
		(width 0.0889)
		(layer "In2.Cu")
		(net "M_I_CPU1_SB_DQ<26>")
	)
	(segment
		(start 177.454052 -309.429404)
		(end 177.617628 -309.59298)
		(width 0.14478)
		(layer "In2.Cu")
		(net "M_I_CPU1_SB_DQ<26>")
	)
	(segment
		(start 177.222404 -309.429404)
		(end 177.454052 -309.429404)
		(width 0.14478)
		(layer "In2.Cu")
		(net "M_I_CPU1_SB_DQ<26>")
	)
	(segment
		(start 159.722312 -308.614064)
		(end 159.51581 -308.820566)
		(width 0.14478)
		(layer "In2.Cu")
		(net "M_I_CPU1_SB_DQ<26>")
	)
	(segment
		(start 160.457642 -309.990998)
		(end 160.686242 -309.990998)
		(width 0.14478)
		(layer "In2.Cu")
		(net "M_I_CPU1_SB_DQ<26>")
	)
	(segment
		(start 159.722312 -308.385464)
		(end 159.722312 -308.614064)
		(width 0.14478)
		(layer "In2.Cu")
		(net "M_I_CPU1_SB_DQ<26>")
	)
	(segment
		(start 147.444714 -294.779446)
		(end 148.51634 -295.850818)
		(width 0.14478)
		(layer "In2.Cu")
		(net "M_I_CPU1_SB_DQ<26>")
	)
	(segment
		(start 165.899846 -310.385206)
		(end 166.012876 -310.111394)
		(width 0.14478)
		(layer "In2.Cu")
		(net "M_I_CPU1_SB_DQ<26>")
	)
	(segment
		(start 168.158922 -309.960264)
		(end 169.297096 -309.960264)
		(width 0.14478)
		(layer "In2.Cu")
		(net "M_I_CPU1_SB_DQ<26>")
	)
	(segment
		(start 145.071846 -289.482784)
		(end 145.071846 -290.350702)
		(width 0.0889)
		(layer "In2.Cu")
		(net "M_I_CPU1_SB_DQ<26>")
	)
	(segment
		(start 161.282888 -309.94604)
		(end 161.282888 -310.17464)
		(width 0.14478)
		(layer "In2.Cu")
		(net "M_I_CPU1_SB_DQ<26>")
	)
	(segment
		(start 175.642524 -309.960264)
		(end 176.895252 -309.960264)
		(width 0.14478)
		(layer "In2.Cu")
		(net "M_I_CPU1_SB_DQ<26>")
	)
	(segment
		(start 173.380654 -310.15178)
		(end 173.616112 -310.054244)
		(width 0.14478)
		(layer "In2.Cu")
		(net "M_I_CPU1_SB_DQ<26>")
	)
	(segment
		(start 170.537378 -310.731916)
		(end 170.726608 -310.810402)
		(width 0.14478)
		(layer "In2.Cu")
		(net "M_I_CPU1_SB_DQ<26>")
	)
	(segment
		(start 158.735522 -308.268878)
		(end 158.897066 -308.430422)
		(width 0.14478)
		(layer "In2.Cu")
		(net "M_I_CPU1_SB_DQ<26>")
	)
	(segment
		(start 170.726608 -310.810402)
		(end 172.875702 -310.810402)
		(width 0.14478)
		(layer "In2.Cu")
		(net "M_I_CPU1_SB_DQ<26>")
	)
	(segment
		(start 177.617628 -309.796688)
		(end 177.781204 -309.960264)
		(width 0.14478)
		(layer "In2.Cu")
		(net "M_I_CPU1_SB_DQ<26>")
	)
	(segment
		(start 161.121344 -309.784496)
		(end 161.282888 -309.94604)
		(width 0.14478)
		(layer "In2.Cu")
		(net "M_I_CPU1_SB_DQ<26>")
	)
	(segment
		(start 145.124424 -290.477702)
		(end 145.903188 -291.256466)
		(width 0.0889)
		(layer "In2.Cu")
		(net "M_I_CPU1_SB_DQ<26>")
	)
	(segment
		(start 158.942024 -307.605176)
		(end 158.942024 -307.833776)
		(width 0.14478)
		(layer "In2.Cu")
		(net "M_I_CPU1_SB_DQ<26>")
	)
	(segment
		(start 159.51581 -308.820566)
		(end 159.51581 -309.049166)
		(width 0.14478)
		(layer "In2.Cu")
		(net "M_I_CPU1_SB_DQ<26>")
	)
	(segment
		(start 144.034764 -289.103308)
		(end 144.69237 -289.103308)
		(width 0.0889)
		(layer "In2.Cu")
		(net "M_I_CPU1_SB_DQ<26>")
	)
	(segment
		(start 136.693402 -289.148774)
		(end 136.701784 -289.1536)
		(width 0.0889)
		(layer "In2.Cu")
		(net "M_I_CPU1_SB_DQ<26>")
	)
	(segment
		(start 159.677354 -309.21071)
		(end 159.905954 -309.21071)
		(width 0.14478)
		(layer "In2.Cu")
		(net "M_I_CPU1_SB_DQ<26>")
	)
	(segment
		(start 161.076386 -310.381142)
		(end 161.076386 -310.609742)
		(width 0.14478)
		(layer "In2.Cu")
		(net "M_I_CPU1_SB_DQ<26>")
	)
	(segment
		(start 160.5026 -309.165752)
		(end 160.5026 -309.394352)
		(width 0.14478)
		(layer "In2.Cu")
		(net "M_I_CPU1_SB_DQ<26>")
	)
	(segment
		(start 173.156626 -310.69407)
		(end 173.284134 -310.385206)
		(width 0.14478)
		(layer "In2.Cu")
		(net "M_I_CPU1_SB_DQ<26>")
	)
	(segment
		(start 175.083724 -310.239664)
		(end 175.363124 -310.239664)
		(width 0.14478)
		(layer "In2.Cu")
		(net "M_I_CPU1_SB_DQ<26>")
	)
	(segment
		(start 165.086792 -310.810402)
		(end 165.85565 -310.491886)
		(width 0.14478)
		(layer "In2.Cu")
		(net "M_I_CPU1_SB_DQ<26>")
	)
	(segment
		(start 161.076386 -310.609742)
		(end 161.23793 -310.771286)
		(width 0.14478)
		(layer "In2.Cu")
		(net "M_I_CPU1_SB_DQ<26>")
	)
	(segment
		(start 174.804324 -309.960264)
		(end 175.083724 -310.239664)
		(width 0.14478)
		(layer "In2.Cu")
		(net "M_I_CPU1_SB_DQ<26>")
	)
	(segment
		(start 129.934716 -289.47618)
		(end 129.780792 -289.21075)
		(width 0.0889)
		(layer "In2.Cu")
		(net "M_I_CPU1_SB_DQ<26>")
	)
	(segment
		(start 160.112456 -309.004208)
		(end 160.341056 -309.004208)
		(width 0.14478)
		(layer "In2.Cu")
		(net "M_I_CPU1_SB_DQ<26>")
	)
	(segment
		(start 161.901632 -310.564784)
		(end 162.14725 -310.810402)
		(width 0.14478)
		(layer "In2.Cu")
		(net "M_I_CPU1_SB_DQ<26>")
	)
	(segment
		(start 159.332168 -308.22392)
		(end 159.560768 -308.22392)
		(width 0.14478)
		(layer "In2.Cu")
		(net "M_I_CPU1_SB_DQ<26>")
	)
	(segment
		(start 166.260526 -310.008778)
		(end 166.641018 -310.166766)
		(width 0.14478)
		(layer "In2.Cu")
		(net "M_I_CPU1_SB_DQ<26>")
	)
	(segment
		(start 170.022266 -309.901336)
		(end 170.236642 -309.990236)
		(width 0.14478)
		(layer "In2.Cu")
		(net "M_I_CPU1_SB_DQ<26>")
	)
	(segment
		(start 169.297096 -309.960264)
		(end 169.593514 -310.0832)
		(width 0.14478)
		(layer "In2.Cu")
		(net "M_I_CPU1_SB_DQ<26>")
	)
	(segment
		(start 178.012852 -309.960264)
		(end 178.302412 -309.670704)
		(width 0.14478)
		(layer "In2.Cu")
		(net "M_I_CPU1_SB_DQ<26>")
	)
	(segment
		(start 159.905954 -309.21071)
		(end 160.112456 -309.004208)
		(width 0.14478)
		(layer "In2.Cu")
		(net "M_I_CPU1_SB_DQ<26>")
	)
	(segment
		(start 160.5026 -309.394352)
		(end 160.296098 -309.600854)
		(width 0.14478)
		(layer "In2.Cu")
		(net "M_I_CPU1_SB_DQ<26>")
	)
	(segment
		(start 135.753348 -289.148774)
		(end 135.76173 -289.1536)
		(width 0.0889)
		(layer "In2.Cu")
		(net "M_I_CPU1_SB_DQ<26>")
	)
	(segment
		(start 178.898804 -309.960264)
		(end 179.091082 -309.960264)
		(width 0.14478)
		(layer "In2.Cu")
		(net "M_I_CPU1_SB_DQ<26>")
	)
	(segment
		(start 159.51581 -309.049166)
		(end 159.677354 -309.21071)
		(width 0.14478)
		(layer "In2.Cu")
		(net "M_I_CPU1_SB_DQ<26>")
	)
	(segment
		(start 146.458686 -293.005002)
		(end 147.268946 -293.815262)
		(width 0.0889)
		(layer "In2.Cu")
		(net "M_I_CPU1_SB_DQ<26>")
	)
	(segment
		(start 174.013876 -310.219344)
		(end 174.639478 -309.960264)
		(width 0.14478)
		(layer "In2.Cu")
		(net "M_I_CPU1_SB_DQ<26>")
	)
	(segment
		(start 137.267696 -289.1536)
		(end 137.276078 -289.148774)
		(width 0.0889)
		(layer "In2.Cu")
		(net "M_I_CPU1_SB_DQ<26>")
	)
	(segment
		(start 177.058828 -309.59298)
		(end 177.222404 -309.429404)
		(width 0.14478)
		(layer "In2.Cu")
		(net "M_I_CPU1_SB_DQ<26>")
	)
	(segment
		(start 169.593514 -310.0832)
		(end 170.022266 -309.901336)
		(width 0.14478)
		(layer "In2.Cu")
		(net "M_I_CPU1_SB_DQ<26>")
	)
	(segment
		(start 148.51634 -295.850818)
		(end 149.455886 -298.119038)
		(width 0.14478)
		(layer "In2.Cu")
		(net "M_I_CPU1_SB_DQ<26>")
	)
	(segment
		(start 167.313102 -309.960264)
		(end 167.600122 -310.247284)
		(width 0.14478)
		(layer "In2.Cu")
		(net "M_I_CPU1_SB_DQ<26>")
	)
	(segment
		(start 158.735522 -308.040278)
		(end 158.735522 -308.268878)
		(width 0.14478)
		(layer "In2.Cu")
		(net "M_I_CPU1_SB_DQ<26>")
	)
	(segment
		(start 177.058828 -309.796688)
		(end 177.058828 -309.59298)
		(width 0.14478)
		(layer "In2.Cu")
		(net "M_I_CPU1_SB_DQ<26>")
	)
	(segment
		(start 179.091082 -309.960264)
		(end 179.516024 -310.385206)
		(width 0.14478)
		(layer "In2.Cu")
		(net "M_I_CPU1_SB_DQ<26>")
	)
	(segment
		(start 160.686242 -309.990998)
		(end 160.892744 -309.784496)
		(width 0.14478)
		(layer "In2.Cu")
		(net "M_I_CPU1_SB_DQ<26>")
	)
	(segment
		(start 132.93344 -289.148774)
		(end 132.941822 -289.1536)
		(width 0.0889)
		(layer "In2.Cu")
		(net "M_I_CPU1_SB_DQ<26>")
	)
	(segment
		(start 161.46653 -310.771286)
		(end 161.673032 -310.564784)
		(width 0.14478)
		(layer "In2.Cu")
		(net "M_I_CPU1_SB_DQ<26>")
	)
	(segment
		(start 167.600122 -310.247284)
		(end 167.871902 -310.247284)
		(width 0.14478)
		(layer "In2.Cu")
		(net "M_I_CPU1_SB_DQ<26>")
	)
	(segment
		(start 165.85565 -310.491886)
		(end 165.899846 -310.385206)
		(width 0.14478)
		(layer "In2.Cu")
		(net "M_I_CPU1_SB_DQ<26>")
	)
	(segment
		(start 147.268946 -293.815262)
		(end 147.268946 -294.603678)
		(width 0.0889)
		(layer "In2.Cu")
		(net "M_I_CPU1_SB_DQ<26>")
	)
	(segment
		(start 161.673032 -310.564784)
		(end 161.901632 -310.564784)
		(width 0.14478)
		(layer "In2.Cu")
		(net "M_I_CPU1_SB_DQ<26>")
	)
	(segment
		(start 144.69237 -289.103308)
		(end 145.071846 -289.482784)
		(width 0.0889)
		(layer "In2.Cu")
		(net "M_I_CPU1_SB_DQ<26>")
	)
	(segment
		(start 178.302412 -309.670704)
		(end 178.609244 -309.670704)
		(width 0.14478)
		(layer "In2.Cu")
		(net "M_I_CPU1_SB_DQ<26>")
	)
	(segment
		(start 160.892744 -309.784496)
		(end 161.121344 -309.784496)
		(width 0.14478)
		(layer "In2.Cu")
		(net "M_I_CPU1_SB_DQ<26>")
	)
	(segment
		(start 138.20775 -289.1536)
		(end 138.216132 -289.148774)
		(width 0.0889)
		(layer "In2.Cu")
		(net "M_I_CPU1_SB_DQ<26>")
	)
	(segment
		(start 147.268946 -294.603678)
		(end 147.444714 -294.779446)
		(width 0.0889)
		(layer "In2.Cu")
		(net "M_I_CPU1_SB_DQ<26>")
	)
	(segment
		(start 170.396916 -310.385206)
		(end 170.537378 -310.731916)
		(width 0.14478)
		(layer "In2.Cu")
		(net "M_I_CPU1_SB_DQ<26>")
	)
	(segment
		(start 160.341056 -309.004208)
		(end 160.5026 -309.165752)
		(width 0.14478)
		(layer "In2.Cu")
		(net "M_I_CPU1_SB_DQ<26>")
	)
	(segment
		(start 167.871902 -310.247284)
		(end 168.158922 -309.960264)
		(width 0.14478)
		(layer "In2.Cu")
		(net "M_I_CPU1_SB_DQ<26>")
	)
	(segment
		(start 140.453364 -289.148774)
		(end 140.461746 -289.1536)
		(width 0.0889)
		(layer "In2.Cu")
		(net "M_I_CPU1_SB_DQ<26>")
	)
	(segment
		(start 172.875702 -310.810402)
		(end 173.156626 -310.69407)
		(width 0.14478)
		(layer "In2.Cu")
		(net "M_I_CPU1_SB_DQ<26>")
	)
	(segment
		(start 160.296098 -309.829454)
		(end 160.457642 -309.990998)
		(width 0.14478)
		(layer "In2.Cu")
		(net "M_I_CPU1_SB_DQ<26>")
	)
	(segment
		(start 166.012876 -310.111394)
		(end 166.260526 -310.008778)
		(width 0.14478)
		(layer "In2.Cu")
		(net "M_I_CPU1_SB_DQ<26>")
	)
	(segment
		(start 161.282888 -310.17464)
		(end 161.076386 -310.381142)
		(width 0.14478)
		(layer "In2.Cu")
		(net "M_I_CPU1_SB_DQ<26>")
	)
	(segment
		(start 173.284134 -310.385206)
		(end 173.380654 -310.15178)
		(width 0.14478)
		(layer "In2.Cu")
		(net "M_I_CPU1_SB_DQ<26>")
	)
	(segment
		(start 167.139366 -309.960264)
		(end 167.313102 -309.960264)
		(width 0.14478)
		(layer "In2.Cu")
		(net "M_I_CPU1_SB_DQ<26>")
	)
	(segment
		(start 166.641018 -310.166766)
		(end 167.139366 -309.960264)
		(width 0.14478)
		(layer "In2.Cu")
		(net "M_I_CPU1_SB_DQ<26>")
	)
	(segment
		(start 177.781204 -309.960264)
		(end 178.012852 -309.960264)
		(width 0.14478)
		(layer "In2.Cu")
		(net "M_I_CPU1_SB_DQ<26>")
	)
	(segment
		(start 159.560768 -308.22392)
		(end 159.722312 -308.385464)
		(width 0.14478)
		(layer "In2.Cu")
		(net "M_I_CPU1_SB_DQ<26>")
	)
	(segment
		(start 149.455886 -298.119038)
		(end 158.942024 -307.605176)
		(width 0.14478)
		(layer "In2.Cu")
		(net "M_I_CPU1_SB_DQ<26>")
	)
	(segment
		(start 177.617628 -309.59298)
		(end 177.617628 -309.796688)
		(width 0.14478)
		(layer "In2.Cu")
		(net "M_I_CPU1_SB_DQ<26>")
	)
	(segment
		(start 161.23793 -310.771286)
		(end 161.46653 -310.771286)
		(width 0.14478)
		(layer "In2.Cu")
		(net "M_I_CPU1_SB_DQ<26>")
	)
	(segment
		(start 159.125666 -308.430422)
		(end 159.332168 -308.22392)
		(width 0.14478)
		(layer "In2.Cu")
		(net "M_I_CPU1_SB_DQ<26>")
	)
	(segment
		(start 133.507734 -289.1536)
		(end 133.516116 -289.148774)
		(width 0.0889)
		(layer "In2.Cu")
		(net "M_I_CPU1_SB_DQ<26>")
	)
	(segment
		(start 176.895252 -309.960264)
		(end 177.058828 -309.796688)
		(width 0.14478)
		(layer "In2.Cu")
		(net "M_I_CPU1_SB_DQ<26>")
	)
	(segment
		(start 158.897066 -308.430422)
		(end 159.125666 -308.430422)
		(width 0.14478)
		(layer "In2.Cu")
		(net "M_I_CPU1_SB_DQ<26>")
	)
	(segment
		(start 175.363124 -310.239664)
		(end 175.642524 -309.960264)
		(width 0.14478)
		(layer "In2.Cu")
		(net "M_I_CPU1_SB_DQ<26>")
	)
	(segment
		(start 160.296098 -309.600854)
		(end 160.296098 -309.829454)
		(width 0.14478)
		(layer "In2.Cu")
		(net "M_I_CPU1_SB_DQ<26>")
	)
	(segment
		(start 131.993386 -289.148774)
		(end 132.001768 -289.1536)
		(width 0.0889)
		(layer "In2.Cu")
		(net "M_I_CPU1_SB_DQ<26>")
	)
	(segment
		(start 170.236642 -309.990236)
		(end 170.396916 -310.385206)
		(width 0.14478)
		(layer "In2.Cu")
		(net "M_I_CPU1_SB_DQ<26>")
	)
	(segment
		(start 129.780792 -289.21075)
		(end 129.803144 -289.127438)
		(width 0.0889)
		(layer "In2.Cu")
		(net "M_I_CPU1_SB_DQ<26>")
	)
	(segment
		(start 173.616112 -310.054244)
		(end 174.013876 -310.219344)
		(width 0.14478)
		(layer "In2.Cu")
		(net "M_I_CPU1_SB_DQ<26>")
	)
	(segment
		(start 141.967712 -289.1536)
		(end 141.976094 -289.148774)
		(width 0.0889)
		(layer "In2.Cu")
		(net "M_I_CPU1_SB_DQ<26>")
	)
	(segment
		(start 158.942024 -307.833776)
		(end 158.735522 -308.040278)
		(width 0.14478)
		(layer "In2.Cu")
		(net "M_I_CPU1_SB_DQ<26>")
	)
	(segment
		(start 178.609244 -309.670704)
		(end 178.898804 -309.960264)
		(width 0.14478)
		(layer "In2.Cu")
		(net "M_I_CPU1_SB_DQ<26>")
	)
	(segment
		(start 145.071846 -290.350702)
		(end 145.124424 -290.477702)
		(width 0.0889)
		(layer "In2.Cu")
		(net "M_I_CPU1_SB_DQ<26>")
	)
	(segment
		(start 174.639478 -309.960264)
		(end 174.804324 -309.960264)
		(width 0.14478)
		(layer "In2.Cu")
		(net "M_I_CPU1_SB_DQ<26>")
	)
	(segment
		(start 162.14725 -310.810402)
		(end 165.086792 -310.810402)
		(width 0.14478)
		(layer "In2.Cu")
		(net "M_I_CPU1_SB_DQ<26>")
	)
	(segment
		(start 141.393418 -289.148774)
		(end 141.4018 -289.1536)
		(width 0.0889)
		(layer "In2.Cu")
		(net "M_I_CPU1_SB_DQ<26>")
	)
	(segment
		(start 145.903188 -291.256466)
		(end 146.458686 -292.597078)
		(width 0.0889)
		(layer "In2.Cu")
		(net "M_I_CPU1_SB_DQ<26>")
	)
	(arc
		(start 130.121914 -289.1536)
		(mid 130.40487 -289.229777)
		(end 130.687826 -289.1536)
		(width 0.0889)
		(layer "In2.Cu")
		(net "M_I_CPU1_SB_DQ<26>")
	)
	(arc
		(start 139.147804 -289.1536)
		(mid 139.334748 -289.103345)
		(end 139.521692 -289.1536)
		(width 0.0889)
		(layer "In2.Cu")
		(net "M_I_CPU1_SB_DQ<26>")
	)
	(arc
		(start 142.907766 -289.1536)
		(mid 143.09471 -289.103345)
		(end 143.281654 -289.1536)
		(width 0.0889)
		(layer "In2.Cu")
		(net "M_I_CPU1_SB_DQ<26>")
	)
	(arc
		(start 130.687826 -289.1536)
		(mid 130.87477 -289.103345)
		(end 131.061714 -289.1536)
		(width 0.0889)
		(layer "In2.Cu")
		(net "M_I_CPU1_SB_DQ<26>")
	)
	(arc
		(start 135.387588 -289.1536)
		(mid 135.569839 -289.10325)
		(end 135.753348 -289.148774)
		(width 0.0889)
		(layer "In2.Cu")
		(net "M_I_CPU1_SB_DQ<26>")
	)
	(arc
		(start 131.627626 -289.1536)
		(mid 131.809877 -289.10325)
		(end 131.993386 -289.148774)
		(width 0.0889)
		(layer "In2.Cu")
		(net "M_I_CPU1_SB_DQ<26>")
	)
	(arc
		(start 138.216132 -289.148774)
		(mid 138.39964 -289.10328)
		(end 138.581892 -289.1536)
		(width 0.0889)
		(layer "In2.Cu")
		(net "M_I_CPU1_SB_DQ<26>")
	)
	(arc
		(start 140.461746 -289.1536)
		(mid 140.744702 -289.229777)
		(end 141.027658 -289.1536)
		(width 0.0889)
		(layer "In2.Cu")
		(net "M_I_CPU1_SB_DQ<26>")
	)
	(arc
		(start 140.087604 -289.1536)
		(mid 140.269855 -289.10325)
		(end 140.453364 -289.148774)
		(width 0.0889)
		(layer "In2.Cu")
		(net "M_I_CPU1_SB_DQ<26>")
	)
	(arc
		(start 141.4018 -289.1536)
		(mid 141.684756 -289.229777)
		(end 141.967712 -289.1536)
		(width 0.0889)
		(layer "In2.Cu")
		(net "M_I_CPU1_SB_DQ<26>")
	)
	(arc
		(start 141.976094 -289.148774)
		(mid 142.159602 -289.10328)
		(end 142.341854 -289.1536)
		(width 0.0889)
		(layer "In2.Cu")
		(net "M_I_CPU1_SB_DQ<26>")
	)
	(arc
		(start 137.276078 -289.148774)
		(mid 137.459586 -289.10328)
		(end 137.641838 -289.1536)
		(width 0.0889)
		(layer "In2.Cu")
		(net "M_I_CPU1_SB_DQ<26>")
	)
	(arc
		(start 132.941822 -289.1536)
		(mid 133.224778 -289.229777)
		(end 133.507734 -289.1536)
		(width 0.0889)
		(layer "In2.Cu")
		(net "M_I_CPU1_SB_DQ<26>")
	)
	(arc
		(start 135.76173 -289.1536)
		(mid 136.044686 -289.229777)
		(end 136.327642 -289.1536)
		(width 0.0889)
		(layer "In2.Cu")
		(net "M_I_CPU1_SB_DQ<26>")
	)
	(arc
		(start 137.641838 -289.1536)
		(mid 137.924794 -289.229777)
		(end 138.20775 -289.1536)
		(width 0.0889)
		(layer "In2.Cu")
		(net "M_I_CPU1_SB_DQ<26>")
	)
	(arc
		(start 132.56768 -289.1536)
		(mid 132.749931 -289.10325)
		(end 132.93344 -289.148774)
		(width 0.0889)
		(layer "In2.Cu")
		(net "M_I_CPU1_SB_DQ<26>")
	)
	(arc
		(start 136.327642 -289.1536)
		(mid 136.509893 -289.10325)
		(end 136.693402 -289.148774)
		(width 0.0889)
		(layer "In2.Cu")
		(net "M_I_CPU1_SB_DQ<26>")
	)
	(arc
		(start 141.027658 -289.1536)
		(mid 141.209909 -289.10325)
		(end 141.393418 -289.148774)
		(width 0.0889)
		(layer "In2.Cu")
		(net "M_I_CPU1_SB_DQ<26>")
	)
	(arc
		(start 134.447788 -289.1536)
		(mid 134.634732 -289.103345)
		(end 134.821676 -289.1536)
		(width 0.0889)
		(layer "In2.Cu")
		(net "M_I_CPU1_SB_DQ<26>")
	)
	(arc
		(start 136.701784 -289.1536)
		(mid 136.98474 -289.229777)
		(end 137.267696 -289.1536)
		(width 0.0889)
		(layer "In2.Cu")
		(net "M_I_CPU1_SB_DQ<26>")
	)
	(arc
		(start 139.521692 -289.1536)
		(mid 139.804648 -289.229777)
		(end 140.087604 -289.1536)
		(width 0.0889)
		(layer "In2.Cu")
		(net "M_I_CPU1_SB_DQ<26>")
	)
	(arc
		(start 143.847566 -289.1536)
		(mid 143.937842 -289.116095)
		(end 144.034764 -289.103308)
		(width 0.0889)
		(layer "In2.Cu")
		(net "M_I_CPU1_SB_DQ<26>")
	)
	(arc
		(start 143.281654 -289.1536)
		(mid 143.56461 -289.229777)
		(end 143.847566 -289.1536)
		(width 0.0889)
		(layer "In2.Cu")
		(net "M_I_CPU1_SB_DQ<26>")
	)
	(arc
		(start 129.803144 -289.127438)
		(mid 129.965476 -289.10462)
		(end 130.121914 -289.1536)
		(width 0.0889)
		(layer "In2.Cu")
		(net "M_I_CPU1_SB_DQ<26>")
	)
	(arc
		(start 138.581892 -289.1536)
		(mid 138.864848 -289.229777)
		(end 139.147804 -289.1536)
		(width 0.0889)
		(layer "In2.Cu")
		(net "M_I_CPU1_SB_DQ<26>")
	)
	(arc
		(start 131.061714 -289.1536)
		(mid 131.34467 -289.229777)
		(end 131.627626 -289.1536)
		(width 0.0889)
		(layer "In2.Cu")
		(net "M_I_CPU1_SB_DQ<26>")
	)
	(arc
		(start 132.001768 -289.1536)
		(mid 132.284724 -289.229777)
		(end 132.56768 -289.1536)
		(width 0.0889)
		(layer "In2.Cu")
		(net "M_I_CPU1_SB_DQ<26>")
	)
	(arc
		(start 133.516116 -289.148774)
		(mid 133.699624 -289.10328)
		(end 133.881876 -289.1536)
		(width 0.0889)
		(layer "In2.Cu")
		(net "M_I_CPU1_SB_DQ<26>")
	)
	(arc
		(start 134.821676 -289.1536)
		(mid 135.104632 -289.229777)
		(end 135.387588 -289.1536)
		(width 0.0889)
		(layer "In2.Cu")
		(net "M_I_CPU1_SB_DQ<26>")
	)
	(arc
		(start 142.341854 -289.1536)
		(mid 142.62481 -289.229777)
		(end 142.907766 -289.1536)
		(width 0.0889)
		(layer "In2.Cu")
		(net "M_I_CPU1_SB_DQ<26>")
	)
	(arc
		(start 133.881876 -289.1536)
		(mid 134.164832 -289.229777)
		(end 134.447788 -289.1536)
		(width 0.0889)
		(layer "In2.Cu")
		(net "M_I_CPU1_SB_DQ<26>")
	)
	(segment
		(start 127.58801 -289.210242)
		(end 128.054862 -289.47618)
		(width 0.10668)
		(layer "F.Cu")
		(net "M_I_CPU1_SB_DQ<25>")
	)
	(segment
		(start 144.28597 -290.590478)
		(end 144.356836 -290.631626)
		(width 0.0889)
		(layer "In2.Cu")
		(net "M_I_CPU1_SB_DQ<25>")
	)
	(segment
		(start 144.913604 -291.945314)
		(end 145.032222 -292.084506)
		(width 0.0889)
		(layer "In2.Cu")
		(net "M_I_CPU1_SB_DQ<25>")
	)
	(segment
		(start 146.47037 -294.389302)
		(end 146.537426 -294.5511)
		(width 0.0889)
		(layer "In2.Cu")
		(net "M_I_CPU1_SB_DQ<25>")
	)
	(segment
		(start 177.66284 -310.506364)
		(end 177.966878 -310.810402)
		(width 0.14478)
		(layer "In2.Cu")
		(net "M_I_CPU1_SB_DQ<25>")
	)
	(segment
		(start 143.847566 -289.79876)
		(end 143.886682 -289.82162)
		(width 0.0889)
		(layer "In2.Cu")
		(net "M_I_CPU1_SB_DQ<25>")
	)
	(segment
		(start 166.885874 -310.810402)
		(end 169.372534 -310.810402)
		(width 0.14478)
		(layer "In2.Cu")
		(net "M_I_CPU1_SB_DQ<25>")
	)
	(segment
		(start 141.967712 -289.79876)
		(end 141.976094 -289.803586)
		(width 0.0889)
		(layer "In2.Cu")
		(net "M_I_CPU1_SB_DQ<25>")
	)
	(segment
		(start 172.27042 -311.660286)
		(end 174.322232 -310.810402)
		(width 0.14478)
		(layer "In2.Cu")
		(net "M_I_CPU1_SB_DQ<25>")
	)
	(segment
		(start 146.855688 -294.869362)
		(end 148.140674 -296.154348)
		(width 0.14478)
		(layer "In2.Cu")
		(net "M_I_CPU1_SB_DQ<25>")
	)
	(segment
		(start 140.453364 -289.803586)
		(end 140.461746 -289.79876)
		(width 0.0889)
		(layer "In2.Cu")
		(net "M_I_CPU1_SB_DQ<25>")
	)
	(segment
		(start 146.47037 -293.872666)
		(end 146.47037 -294.389302)
		(width 0.0889)
		(layer "In2.Cu")
		(net "M_I_CPU1_SB_DQ<25>")
	)
	(segment
		(start 158.285942 -308.455568)
		(end 161.49066 -311.660286)
		(width 0.14478)
		(layer "In2.Cu")
		(net "M_I_CPU1_SB_DQ<25>")
	)
	(segment
		(start 131.993386 -289.803586)
		(end 132.001768 -289.79876)
		(width 0.0889)
		(layer "In2.Cu")
		(net "M_I_CPU1_SB_DQ<25>")
	)
	(segment
		(start 128.208786 -289.74161)
		(end 128.304798 -289.76701)
		(width 0.0889)
		(layer "In2.Cu")
		(net "M_I_CPU1_SB_DQ<25>")
	)
	(segment
		(start 182.02529 -310.511444)
		(end 182.285132 -310.511444)
		(width 0.14478)
		(layer "In2.Cu")
		(net "M_I_CPU1_SB_DQ<25>")
	)
	(segment
		(start 149.049994 -298.349416)
		(end 158.285942 -307.585364)
		(width 0.14478)
		(layer "In2.Cu")
		(net "M_I_CPU1_SB_DQ<25>")
	)
	(segment
		(start 181.726332 -310.810402)
		(end 182.02529 -310.511444)
		(width 0.14478)
		(layer "In2.Cu")
		(net "M_I_CPU1_SB_DQ<25>")
	)
	(segment
		(start 182.58409 -310.810402)
		(end 183.19115 -310.810402)
		(width 0.14478)
		(layer "In2.Cu")
		(net "M_I_CPU1_SB_DQ<25>")
	)
	(segment
		(start 128.807718 -289.79876)
		(end 128.8161 -289.803586)
		(width 0.0889)
		(layer "In2.Cu")
		(net "M_I_CPU1_SB_DQ<25>")
	)
	(segment
		(start 177.966878 -310.810402)
		(end 180.608732 -310.810402)
		(width 0.14478)
		(layer "In2.Cu")
		(net "M_I_CPU1_SB_DQ<25>")
	)
	(segment
		(start 180.608732 -310.810402)
		(end 180.90769 -310.511444)
		(width 0.14478)
		(layer "In2.Cu")
		(net "M_I_CPU1_SB_DQ<25>")
	)
	(segment
		(start 183.19115 -310.810402)
		(end 183.616092 -311.235344)
		(width 0.14478)
		(layer "In2.Cu")
		(net "M_I_CPU1_SB_DQ<25>")
	)
	(segment
		(start 171.424346 -311.660286)
		(end 172.27042 -311.660286)
		(width 0.14478)
		(layer "In2.Cu")
		(net "M_I_CPU1_SB_DQ<25>")
	)
	(segment
		(start 161.49066 -311.660286)
		(end 164.834062 -311.660286)
		(width 0.14478)
		(layer "In2.Cu")
		(net "M_I_CPU1_SB_DQ<25>")
	)
	(segment
		(start 145.032222 -292.084506)
		(end 146.14398 -293.188644)
		(width 0.0889)
		(layer "In2.Cu")
		(net "M_I_CPU1_SB_DQ<25>")
	)
	(segment
		(start 141.393418 -289.803586)
		(end 141.4018 -289.79876)
		(width 0.0889)
		(layer "In2.Cu")
		(net "M_I_CPU1_SB_DQ<25>")
	)
	(segment
		(start 146.537426 -294.5511)
		(end 146.855688 -294.869362)
		(width 0.0889)
		(layer "In2.Cu")
		(net "M_I_CPU1_SB_DQ<25>")
	)
	(segment
		(start 158.285942 -307.585364)
		(end 158.285942 -308.455568)
		(width 0.14478)
		(layer "In2.Cu")
		(net "M_I_CPU1_SB_DQ<25>")
	)
	(segment
		(start 164.834062 -311.660286)
		(end 166.885874 -310.810402)
		(width 0.14478)
		(layer "In2.Cu")
		(net "M_I_CPU1_SB_DQ<25>")
	)
	(segment
		(start 169.372534 -310.810402)
		(end 171.424346 -311.660286)
		(width 0.14478)
		(layer "In2.Cu")
		(net "M_I_CPU1_SB_DQ<25>")
	)
	(segment
		(start 181.46649 -310.810402)
		(end 181.726332 -310.810402)
		(width 0.14478)
		(layer "In2.Cu")
		(net "M_I_CPU1_SB_DQ<25>")
	)
	(segment
		(start 137.267696 -289.79876)
		(end 137.276078 -289.803586)
		(width 0.0889)
		(layer "In2.Cu")
		(net "M_I_CPU1_SB_DQ<25>")
	)
	(segment
		(start 133.507734 -289.79876)
		(end 133.516116 -289.803586)
		(width 0.0889)
		(layer "In2.Cu")
		(net "M_I_CPU1_SB_DQ<25>")
	)
	(segment
		(start 148.140674 -296.154348)
		(end 149.049994 -298.349416)
		(width 0.14478)
		(layer "In2.Cu")
		(net "M_I_CPU1_SB_DQ<25>")
	)
	(segment
		(start 174.322232 -310.810402)
		(end 177.10404 -310.810402)
		(width 0.14478)
		(layer "In2.Cu")
		(net "M_I_CPU1_SB_DQ<25>")
	)
	(segment
		(start 135.753348 -289.803586)
		(end 135.76173 -289.79876)
		(width 0.0889)
		(layer "In2.Cu")
		(net "M_I_CPU1_SB_DQ<25>")
	)
	(segment
		(start 132.93344 -289.803586)
		(end 132.941822 -289.79876)
		(width 0.0889)
		(layer "In2.Cu")
		(net "M_I_CPU1_SB_DQ<25>")
	)
	(segment
		(start 182.285132 -310.511444)
		(end 182.58409 -310.810402)
		(width 0.14478)
		(layer "In2.Cu")
		(net "M_I_CPU1_SB_DQ<25>")
	)
	(segment
		(start 129.747772 -289.79876)
		(end 129.756154 -289.803586)
		(width 0.0889)
		(layer "In2.Cu")
		(net "M_I_CPU1_SB_DQ<25>")
	)
	(segment
		(start 181.167532 -310.511444)
		(end 181.46649 -310.810402)
		(width 0.14478)
		(layer "In2.Cu")
		(net "M_I_CPU1_SB_DQ<25>")
	)
	(segment
		(start 180.90769 -310.511444)
		(end 181.167532 -310.511444)
		(width 0.14478)
		(layer "In2.Cu")
		(net "M_I_CPU1_SB_DQ<25>")
	)
	(segment
		(start 177.408078 -310.506364)
		(end 177.66284 -310.506364)
		(width 0.14478)
		(layer "In2.Cu")
		(net "M_I_CPU1_SB_DQ<25>")
	)
	(segment
		(start 177.10404 -310.810402)
		(end 177.408078 -310.506364)
		(width 0.14478)
		(layer "In2.Cu")
		(net "M_I_CPU1_SB_DQ<25>")
	)
	(segment
		(start 138.20775 -289.79876)
		(end 138.216132 -289.803586)
		(width 0.0889)
		(layer "In2.Cu")
		(net "M_I_CPU1_SB_DQ<25>")
	)
	(segment
		(start 136.693402 -289.803586)
		(end 136.701784 -289.79876)
		(width 0.0889)
		(layer "In2.Cu")
		(net "M_I_CPU1_SB_DQ<25>")
	)
	(segment
		(start 128.054862 -289.47618)
		(end 128.208786 -289.74161)
		(width 0.0889)
		(layer "In2.Cu")
		(net "M_I_CPU1_SB_DQ<25>")
	)
	(arc
		(start 135.76173 -289.79876)
		(mid 136.044686 -289.722583)
		(end 136.327642 -289.79876)
		(width 0.0889)
		(layer "In2.Cu")
		(net "M_I_CPU1_SB_DQ<25>")
	)
	(arc
		(start 143.886682 -289.82162)
		(mid 144.065495 -290.02397)
		(end 144.130014 -290.286186)
		(width 0.0889)
		(layer "In2.Cu")
		(net "M_I_CPU1_SB_DQ<25>")
	)
	(arc
		(start 139.147804 -289.79876)
		(mid 139.334748 -289.849015)
		(end 139.521692 -289.79876)
		(width 0.0889)
		(layer "In2.Cu")
		(net "M_I_CPU1_SB_DQ<25>")
	)
	(arc
		(start 146.14398 -293.188644)
		(mid 146.365922 -293.502625)
		(end 146.47037 -293.872666)
		(width 0.0889)
		(layer "In2.Cu")
		(net "M_I_CPU1_SB_DQ<25>")
	)
	(arc
		(start 130.121914 -289.79876)
		(mid 130.40487 -289.722583)
		(end 130.687826 -289.79876)
		(width 0.0889)
		(layer "In2.Cu")
		(net "M_I_CPU1_SB_DQ<25>")
	)
	(arc
		(start 131.627626 -289.79876)
		(mid 131.809877 -289.84911)
		(end 131.993386 -289.803586)
		(width 0.0889)
		(layer "In2.Cu")
		(net "M_I_CPU1_SB_DQ<25>")
	)
	(arc
		(start 140.087604 -289.79876)
		(mid 140.269855 -289.84911)
		(end 140.453364 -289.803586)
		(width 0.0889)
		(layer "In2.Cu")
		(net "M_I_CPU1_SB_DQ<25>")
	)
	(arc
		(start 136.327642 -289.79876)
		(mid 136.509893 -289.84911)
		(end 136.693402 -289.803586)
		(width 0.0889)
		(layer "In2.Cu")
		(net "M_I_CPU1_SB_DQ<25>")
	)
	(arc
		(start 139.521692 -289.79876)
		(mid 139.804648 -289.722583)
		(end 140.087604 -289.79876)
		(width 0.0889)
		(layer "In2.Cu")
		(net "M_I_CPU1_SB_DQ<25>")
	)
	(arc
		(start 131.061714 -289.79876)
		(mid 131.34467 -289.722583)
		(end 131.627626 -289.79876)
		(width 0.0889)
		(layer "In2.Cu")
		(net "M_I_CPU1_SB_DQ<25>")
	)
	(arc
		(start 138.216132 -289.803586)
		(mid 138.39964 -289.84908)
		(end 138.581892 -289.79876)
		(width 0.0889)
		(layer "In2.Cu")
		(net "M_I_CPU1_SB_DQ<25>")
	)
	(arc
		(start 130.687826 -289.79876)
		(mid 130.87477 -289.849015)
		(end 131.061714 -289.79876)
		(width 0.0889)
		(layer "In2.Cu")
		(net "M_I_CPU1_SB_DQ<25>")
	)
	(arc
		(start 140.461746 -289.79876)
		(mid 140.744702 -289.722583)
		(end 141.027658 -289.79876)
		(width 0.0889)
		(layer "In2.Cu")
		(net "M_I_CPU1_SB_DQ<25>")
	)
	(arc
		(start 144.356836 -290.631626)
		(mid 144.535649 -290.833976)
		(end 144.600168 -291.096192)
		(width 0.0889)
		(layer "In2.Cu")
		(net "M_I_CPU1_SB_DQ<25>")
	)
	(arc
		(start 143.281654 -289.79876)
		(mid 143.56461 -289.722583)
		(end 143.847566 -289.79876)
		(width 0.0889)
		(layer "In2.Cu")
		(net "M_I_CPU1_SB_DQ<25>")
	)
	(arc
		(start 129.756154 -289.803586)
		(mid 129.939662 -289.84908)
		(end 130.121914 -289.79876)
		(width 0.0889)
		(layer "In2.Cu")
		(net "M_I_CPU1_SB_DQ<25>")
	)
	(arc
		(start 133.516116 -289.803586)
		(mid 133.699624 -289.84908)
		(end 133.881876 -289.79876)
		(width 0.0889)
		(layer "In2.Cu")
		(net "M_I_CPU1_SB_DQ<25>")
	)
	(arc
		(start 144.600168 -291.096192)
		(mid 144.681031 -291.548752)
		(end 144.913604 -291.945314)
		(width 0.0889)
		(layer "In2.Cu")
		(net "M_I_CPU1_SB_DQ<25>")
	)
	(arc
		(start 134.821676 -289.79876)
		(mid 135.104632 -289.722583)
		(end 135.387588 -289.79876)
		(width 0.0889)
		(layer "In2.Cu")
		(net "M_I_CPU1_SB_DQ<25>")
	)
	(arc
		(start 142.907766 -289.79876)
		(mid 143.09471 -289.849015)
		(end 143.281654 -289.79876)
		(width 0.0889)
		(layer "In2.Cu")
		(net "M_I_CPU1_SB_DQ<25>")
	)
	(arc
		(start 137.276078 -289.803586)
		(mid 137.459586 -289.84908)
		(end 137.641838 -289.79876)
		(width 0.0889)
		(layer "In2.Cu")
		(net "M_I_CPU1_SB_DQ<25>")
	)
	(arc
		(start 142.341854 -289.79876)
		(mid 142.62481 -289.722583)
		(end 142.907766 -289.79876)
		(width 0.0889)
		(layer "In2.Cu")
		(net "M_I_CPU1_SB_DQ<25>")
	)
	(arc
		(start 132.56768 -289.79876)
		(mid 132.749931 -289.84911)
		(end 132.93344 -289.803586)
		(width 0.0889)
		(layer "In2.Cu")
		(net "M_I_CPU1_SB_DQ<25>")
	)
	(arc
		(start 132.941822 -289.79876)
		(mid 133.224778 -289.722583)
		(end 133.507734 -289.79876)
		(width 0.0889)
		(layer "In2.Cu")
		(net "M_I_CPU1_SB_DQ<25>")
	)
	(arc
		(start 133.881876 -289.79876)
		(mid 134.164832 -289.722583)
		(end 134.447788 -289.79876)
		(width 0.0889)
		(layer "In2.Cu")
		(net "M_I_CPU1_SB_DQ<25>")
	)
	(arc
		(start 128.8161 -289.803586)
		(mid 128.999608 -289.84908)
		(end 129.18186 -289.79876)
		(width 0.0889)
		(layer "In2.Cu")
		(net "M_I_CPU1_SB_DQ<25>")
	)
	(arc
		(start 134.447788 -289.79876)
		(mid 134.634732 -289.849015)
		(end 134.821676 -289.79876)
		(width 0.0889)
		(layer "In2.Cu")
		(net "M_I_CPU1_SB_DQ<25>")
	)
	(arc
		(start 141.027658 -289.79876)
		(mid 141.209909 -289.84911)
		(end 141.393418 -289.803586)
		(width 0.0889)
		(layer "In2.Cu")
		(net "M_I_CPU1_SB_DQ<25>")
	)
	(arc
		(start 144.130014 -290.286186)
		(mid 144.171269 -290.457157)
		(end 144.28597 -290.590478)
		(width 0.0889)
		(layer "In2.Cu")
		(net "M_I_CPU1_SB_DQ<25>")
	)
	(arc
		(start 128.304798 -289.76701)
		(mid 128.560006 -289.723533)
		(end 128.807718 -289.79876)
		(width 0.0889)
		(layer "In2.Cu")
		(net "M_I_CPU1_SB_DQ<25>")
	)
	(arc
		(start 129.18186 -289.79876)
		(mid 129.464816 -289.722583)
		(end 129.747772 -289.79876)
		(width 0.0889)
		(layer "In2.Cu")
		(net "M_I_CPU1_SB_DQ<25>")
	)
	(arc
		(start 138.581892 -289.79876)
		(mid 138.864848 -289.722583)
		(end 139.147804 -289.79876)
		(width 0.0889)
		(layer "In2.Cu")
		(net "M_I_CPU1_SB_DQ<25>")
	)
	(arc
		(start 141.4018 -289.79876)
		(mid 141.684756 -289.722583)
		(end 141.967712 -289.79876)
		(width 0.0889)
		(layer "In2.Cu")
		(net "M_I_CPU1_SB_DQ<25>")
	)
	(arc
		(start 141.976094 -289.803586)
		(mid 142.159602 -289.84908)
		(end 142.341854 -289.79876)
		(width 0.0889)
		(layer "In2.Cu")
		(net "M_I_CPU1_SB_DQ<25>")
	)
	(arc
		(start 136.701784 -289.79876)
		(mid 136.98474 -289.722583)
		(end 137.267696 -289.79876)
		(width 0.0889)
		(layer "In2.Cu")
		(net "M_I_CPU1_SB_DQ<25>")
	)
	(arc
		(start 135.387588 -289.79876)
		(mid 135.569839 -289.84911)
		(end 135.753348 -289.803586)
		(width 0.0889)
		(layer "In2.Cu")
		(net "M_I_CPU1_SB_DQ<25>")
	)
	(arc
		(start 137.641838 -289.79876)
		(mid 137.924794 -289.722583)
		(end 138.20775 -289.79876)
		(width 0.0889)
		(layer "In2.Cu")
		(net "M_I_CPU1_SB_DQ<25>")
	)
	(arc
		(start 132.001768 -289.79876)
		(mid 132.284724 -289.722583)
		(end 132.56768 -289.79876)
		(width 0.0889)
		(layer "In2.Cu")
		(net "M_I_CPU1_SB_DQ<25>")
	)
	(segment
		(start 128.997964 -288.400236)
		(end 129.464816 -288.666174)
		(width 0.10668)
		(layer "F.Cu")
		(net "M_I_CPU1_SB_DQ<24>")
	)
	(segment
		(start 148.998178 -295.594278)
		(end 149.989286 -297.986704)
		(width 0.14478)
		(layer "In2.Cu")
		(net "M_I_CPU1_SB_DQ<24>")
	)
	(segment
		(start 181.471062 -309.11038)
		(end 181.70271 -309.11038)
		(width 0.14478)
		(layer "In2.Cu")
		(net "M_I_CPU1_SB_DQ<24>")
	)
	(segment
		(start 172.470064 -309.960264)
		(end 174.521876 -309.11038)
		(width 0.14478)
		(layer "In2.Cu")
		(net "M_I_CPU1_SB_DQ<24>")
	)
	(segment
		(start 182.588662 -309.11038)
		(end 183.19115 -309.11038)
		(width 0.14478)
		(layer "In2.Cu")
		(net "M_I_CPU1_SB_DQ<24>")
	)
	(segment
		(start 138.103356 -288.99358)
		(end 138.111738 -288.988754)
		(width 0.0889)
		(layer "In2.Cu")
		(net "M_I_CPU1_SB_DQ<24>")
	)
	(segment
		(start 167.09263 -309.11038)
		(end 169.333926 -309.11038)
		(width 0.14478)
		(layer "In2.Cu")
		(net "M_I_CPU1_SB_DQ<24>")
	)
	(segment
		(start 149.989286 -297.986704)
		(end 161.962846 -309.960264)
		(width 0.14478)
		(layer "In2.Cu")
		(net "M_I_CPU1_SB_DQ<24>")
	)
	(segment
		(start 140.557758 -288.988754)
		(end 140.56614 -288.99358)
		(width 0.0889)
		(layer "In2.Cu")
		(net "M_I_CPU1_SB_DQ<24>")
	)
	(segment
		(start 129.61874 -288.931604)
		(end 129.714752 -288.957004)
		(width 0.0889)
		(layer "In2.Cu")
		(net "M_I_CPU1_SB_DQ<24>")
	)
	(segment
		(start 177.170588 -308.835044)
		(end 178.390296 -308.835044)
		(width 0.14478)
		(layer "In2.Cu")
		(net "M_I_CPU1_SB_DQ<24>")
	)
	(segment
		(start 134.343394 -288.99358)
		(end 134.351776 -288.988754)
		(width 0.0889)
		(layer "In2.Cu")
		(net "M_I_CPU1_SB_DQ<24>")
	)
	(segment
		(start 146.677126 -292.55339)
		(end 146.677126 -292.914324)
		(width 0.0889)
		(layer "In2.Cu")
		(net "M_I_CPU1_SB_DQ<24>")
	)
	(segment
		(start 144.92732 -288.912554)
		(end 145.577306 -289.56254)
		(width 0.0889)
		(layer "In2.Cu")
		(net "M_I_CPU1_SB_DQ<24>")
	)
	(segment
		(start 176.895252 -309.11038)
		(end 177.170588 -308.835044)
		(width 0.14478)
		(layer "In2.Cu")
		(net "M_I_CPU1_SB_DQ<24>")
	)
	(segment
		(start 139.617704 -288.988754)
		(end 139.626086 -288.99358)
		(width 0.0889)
		(layer "In2.Cu")
		(net "M_I_CPU1_SB_DQ<24>")
	)
	(segment
		(start 145.577306 -289.56254)
		(end 145.999708 -290.581842)
		(width 0.0889)
		(layer "In2.Cu")
		(net "M_I_CPU1_SB_DQ<24>")
	)
	(segment
		(start 181.866286 -308.946804)
		(end 181.866286 -308.60746)
		(width 0.14478)
		(layer "In2.Cu")
		(net "M_I_CPU1_SB_DQ<24>")
	)
	(segment
		(start 146.128486 -291.22878)
		(end 146.677126 -292.55339)
		(width 0.0889)
		(layer "In2.Cu")
		(net "M_I_CPU1_SB_DQ<24>")
	)
	(segment
		(start 147.535646 -294.131746)
		(end 147.832064 -294.428164)
		(width 0.0889)
		(layer "In2.Cu")
		(net "M_I_CPU1_SB_DQ<24>")
	)
	(segment
		(start 134.917688 -288.988754)
		(end 134.92607 -288.99358)
		(width 0.0889)
		(layer "In2.Cu")
		(net "M_I_CPU1_SB_DQ<24>")
	)
	(segment
		(start 165.040818 -309.960264)
		(end 167.09263 -309.11038)
		(width 0.14478)
		(layer "In2.Cu")
		(net "M_I_CPU1_SB_DQ<24>")
	)
	(segment
		(start 169.333926 -309.11038)
		(end 171.385738 -309.960264)
		(width 0.14478)
		(layer "In2.Cu")
		(net "M_I_CPU1_SB_DQ<24>")
	)
	(segment
		(start 135.857742 -288.988754)
		(end 135.866124 -288.99358)
		(width 0.0889)
		(layer "In2.Cu")
		(net "M_I_CPU1_SB_DQ<24>")
	)
	(segment
		(start 130.583432 -288.99358)
		(end 130.591814 -288.988754)
		(width 0.0889)
		(layer "In2.Cu")
		(net "M_I_CPU1_SB_DQ<24>")
	)
	(segment
		(start 181.307486 -308.60746)
		(end 181.307486 -308.946804)
		(width 0.14478)
		(layer "In2.Cu")
		(net "M_I_CPU1_SB_DQ<24>")
	)
	(segment
		(start 142.803372 -288.99358)
		(end 142.811754 -288.988754)
		(width 0.0889)
		(layer "In2.Cu")
		(net "M_I_CPU1_SB_DQ<24>")
	)
	(segment
		(start 183.19115 -309.11038)
		(end 183.616092 -309.535322)
		(width 0.14478)
		(layer "In2.Cu")
		(net "M_I_CPU1_SB_DQ<24>")
	)
	(segment
		(start 139.04341 -288.99358)
		(end 139.051792 -288.988754)
		(width 0.0889)
		(layer "In2.Cu")
		(net "M_I_CPU1_SB_DQ<24>")
	)
	(segment
		(start 147.535646 -293.772844)
		(end 147.535646 -294.131746)
		(width 0.0889)
		(layer "In2.Cu")
		(net "M_I_CPU1_SB_DQ<24>")
	)
	(segment
		(start 181.866286 -308.60746)
		(end 182.029862 -308.443884)
		(width 0.14478)
		(layer "In2.Cu")
		(net "M_I_CPU1_SB_DQ<24>")
	)
	(segment
		(start 180.58511 -309.11038)
		(end 180.748686 -308.946804)
		(width 0.14478)
		(layer "In2.Cu")
		(net "M_I_CPU1_SB_DQ<24>")
	)
	(segment
		(start 131.157726 -288.988754)
		(end 131.166108 -288.99358)
		(width 0.0889)
		(layer "In2.Cu")
		(net "M_I_CPU1_SB_DQ<24>")
	)
	(segment
		(start 181.14391 -308.443884)
		(end 181.307486 -308.60746)
		(width 0.14478)
		(layer "In2.Cu")
		(net "M_I_CPU1_SB_DQ<24>")
	)
	(segment
		(start 178.665632 -309.11038)
		(end 180.58511 -309.11038)
		(width 0.14478)
		(layer "In2.Cu")
		(net "M_I_CPU1_SB_DQ<24>")
	)
	(segment
		(start 180.912262 -308.443884)
		(end 181.14391 -308.443884)
		(width 0.14478)
		(layer "In2.Cu")
		(net "M_I_CPU1_SB_DQ<24>")
	)
	(segment
		(start 174.521876 -309.11038)
		(end 176.895252 -309.11038)
		(width 0.14478)
		(layer "In2.Cu")
		(net "M_I_CPU1_SB_DQ<24>")
	)
	(segment
		(start 171.385738 -309.960264)
		(end 172.470064 -309.960264)
		(width 0.14478)
		(layer "In2.Cu")
		(net "M_I_CPU1_SB_DQ<24>")
	)
	(segment
		(start 182.425086 -308.946804)
		(end 182.588662 -309.11038)
		(width 0.14478)
		(layer "In2.Cu")
		(net "M_I_CPU1_SB_DQ<24>")
	)
	(segment
		(start 178.390296 -308.835044)
		(end 178.665632 -309.11038)
		(width 0.14478)
		(layer "In2.Cu")
		(net "M_I_CPU1_SB_DQ<24>")
	)
	(segment
		(start 181.307486 -308.946804)
		(end 181.471062 -309.11038)
		(width 0.14478)
		(layer "In2.Cu")
		(net "M_I_CPU1_SB_DQ<24>")
	)
	(segment
		(start 143.377666 -288.988754)
		(end 143.386048 -288.99358)
		(width 0.0889)
		(layer "In2.Cu")
		(net "M_I_CPU1_SB_DQ<24>")
	)
	(segment
		(start 161.962846 -309.960264)
		(end 165.040818 -309.960264)
		(width 0.14478)
		(layer "In2.Cu")
		(net "M_I_CPU1_SB_DQ<24>")
	)
	(segment
		(start 182.425086 -308.60746)
		(end 182.425086 -308.946804)
		(width 0.14478)
		(layer "In2.Cu")
		(net "M_I_CPU1_SB_DQ<24>")
	)
	(segment
		(start 146.677126 -292.914324)
		(end 147.535646 -293.772844)
		(width 0.0889)
		(layer "In2.Cu")
		(net "M_I_CPU1_SB_DQ<24>")
	)
	(segment
		(start 182.029862 -308.443884)
		(end 182.26151 -308.443884)
		(width 0.14478)
		(layer "In2.Cu")
		(net "M_I_CPU1_SB_DQ<24>")
	)
	(segment
		(start 144.034764 -288.912554)
		(end 144.92732 -288.912554)
		(width 0.0889)
		(layer "In2.Cu")
		(net "M_I_CPU1_SB_DQ<24>")
	)
	(segment
		(start 129.464816 -288.666174)
		(end 129.61874 -288.931604)
		(width 0.0889)
		(layer "In2.Cu")
		(net "M_I_CPU1_SB_DQ<24>")
	)
	(segment
		(start 132.09778 -288.988754)
		(end 132.106162 -288.99358)
		(width 0.0889)
		(layer "In2.Cu")
		(net "M_I_CPU1_SB_DQ<24>")
	)
	(segment
		(start 181.70271 -309.11038)
		(end 181.866286 -308.946804)
		(width 0.14478)
		(layer "In2.Cu")
		(net "M_I_CPU1_SB_DQ<24>")
	)
	(segment
		(start 180.748686 -308.60746)
		(end 180.912262 -308.443884)
		(width 0.14478)
		(layer "In2.Cu")
		(net "M_I_CPU1_SB_DQ<24>")
	)
	(segment
		(start 147.832064 -294.428164)
		(end 148.998178 -295.594278)
		(width 0.14478)
		(layer "In2.Cu")
		(net "M_I_CPU1_SB_DQ<24>")
	)
	(segment
		(start 145.999708 -290.581842)
		(end 146.128486 -291.22878)
		(width 0.0889)
		(layer "In2.Cu")
		(net "M_I_CPU1_SB_DQ<24>")
	)
	(segment
		(start 180.748686 -308.946804)
		(end 180.748686 -308.60746)
		(width 0.14478)
		(layer "In2.Cu")
		(net "M_I_CPU1_SB_DQ<24>")
	)
	(segment
		(start 182.26151 -308.443884)
		(end 182.425086 -308.60746)
		(width 0.14478)
		(layer "In2.Cu")
		(net "M_I_CPU1_SB_DQ<24>")
	)
	(arc
		(start 131.531868 -288.988754)
		(mid 131.814824 -288.912577)
		(end 132.09778 -288.988754)
		(width 0.0889)
		(layer "In2.Cu")
		(net "M_I_CPU1_SB_DQ<24>")
	)
	(arc
		(start 137.171684 -288.988754)
		(mid 137.45464 -288.912577)
		(end 137.737596 -288.988754)
		(width 0.0889)
		(layer "In2.Cu")
		(net "M_I_CPU1_SB_DQ<24>")
	)
	(arc
		(start 130.217672 -288.988754)
		(mid 130.399923 -289.039104)
		(end 130.583432 -288.99358)
		(width 0.0889)
		(layer "In2.Cu")
		(net "M_I_CPU1_SB_DQ<24>")
	)
	(arc
		(start 136.231884 -288.988754)
		(mid 136.51484 -288.912577)
		(end 136.797796 -288.988754)
		(width 0.0889)
		(layer "In2.Cu")
		(net "M_I_CPU1_SB_DQ<24>")
	)
	(arc
		(start 132.106162 -288.99358)
		(mid 132.28967 -289.039074)
		(end 132.471922 -288.988754)
		(width 0.0889)
		(layer "In2.Cu")
		(net "M_I_CPU1_SB_DQ<24>")
	)
	(arc
		(start 133.037834 -288.988754)
		(mid 133.224778 -289.039009)
		(end 133.411722 -288.988754)
		(width 0.0889)
		(layer "In2.Cu")
		(net "M_I_CPU1_SB_DQ<24>")
	)
	(arc
		(start 131.166108 -288.99358)
		(mid 131.349616 -289.039074)
		(end 131.531868 -288.988754)
		(width 0.0889)
		(layer "In2.Cu")
		(net "M_I_CPU1_SB_DQ<24>")
	)
	(arc
		(start 137.737596 -288.988754)
		(mid 137.919847 -289.039104)
		(end 138.103356 -288.99358)
		(width 0.0889)
		(layer "In2.Cu")
		(net "M_I_CPU1_SB_DQ<24>")
	)
	(arc
		(start 135.29183 -288.988754)
		(mid 135.574786 -288.912577)
		(end 135.857742 -288.988754)
		(width 0.0889)
		(layer "In2.Cu")
		(net "M_I_CPU1_SB_DQ<24>")
	)
	(arc
		(start 141.497812 -288.988754)
		(mid 141.684756 -289.039009)
		(end 141.8717 -288.988754)
		(width 0.0889)
		(layer "In2.Cu")
		(net "M_I_CPU1_SB_DQ<24>")
	)
	(arc
		(start 143.386048 -288.99358)
		(mid 143.569556 -289.039074)
		(end 143.751808 -288.988754)
		(width 0.0889)
		(layer "In2.Cu")
		(net "M_I_CPU1_SB_DQ<24>")
	)
	(arc
		(start 140.56614 -288.99358)
		(mid 140.749648 -289.039074)
		(end 140.9319 -288.988754)
		(width 0.0889)
		(layer "In2.Cu")
		(net "M_I_CPU1_SB_DQ<24>")
	)
	(arc
		(start 142.437612 -288.988754)
		(mid 142.619863 -289.039104)
		(end 142.803372 -288.99358)
		(width 0.0889)
		(layer "In2.Cu")
		(net "M_I_CPU1_SB_DQ<24>")
	)
	(arc
		(start 138.67765 -288.988754)
		(mid 138.859901 -289.039104)
		(end 139.04341 -288.99358)
		(width 0.0889)
		(layer "In2.Cu")
		(net "M_I_CPU1_SB_DQ<24>")
	)
	(arc
		(start 132.471922 -288.988754)
		(mid 132.754878 -288.912577)
		(end 133.037834 -288.988754)
		(width 0.0889)
		(layer "In2.Cu")
		(net "M_I_CPU1_SB_DQ<24>")
	)
	(arc
		(start 136.797796 -288.988754)
		(mid 136.98474 -289.039009)
		(end 137.171684 -288.988754)
		(width 0.0889)
		(layer "In2.Cu")
		(net "M_I_CPU1_SB_DQ<24>")
	)
	(arc
		(start 135.866124 -288.99358)
		(mid 136.049632 -289.039074)
		(end 136.231884 -288.988754)
		(width 0.0889)
		(layer "In2.Cu")
		(net "M_I_CPU1_SB_DQ<24>")
	)
	(arc
		(start 134.351776 -288.988754)
		(mid 134.634732 -288.912577)
		(end 134.917688 -288.988754)
		(width 0.0889)
		(layer "In2.Cu")
		(net "M_I_CPU1_SB_DQ<24>")
	)
	(arc
		(start 133.977634 -288.988754)
		(mid 134.159885 -289.039104)
		(end 134.343394 -288.99358)
		(width 0.0889)
		(layer "In2.Cu")
		(net "M_I_CPU1_SB_DQ<24>")
	)
	(arc
		(start 133.411722 -288.988754)
		(mid 133.694678 -288.912577)
		(end 133.977634 -288.988754)
		(width 0.0889)
		(layer "In2.Cu")
		(net "M_I_CPU1_SB_DQ<24>")
	)
	(arc
		(start 140.9319 -288.988754)
		(mid 141.214856 -288.912577)
		(end 141.497812 -288.988754)
		(width 0.0889)
		(layer "In2.Cu")
		(net "M_I_CPU1_SB_DQ<24>")
	)
	(arc
		(start 129.714752 -288.957004)
		(mid 129.96996 -288.913527)
		(end 130.217672 -288.988754)
		(width 0.0889)
		(layer "In2.Cu")
		(net "M_I_CPU1_SB_DQ<24>")
	)
	(arc
		(start 142.811754 -288.988754)
		(mid 143.09471 -288.912577)
		(end 143.377666 -288.988754)
		(width 0.0889)
		(layer "In2.Cu")
		(net "M_I_CPU1_SB_DQ<24>")
	)
	(arc
		(start 139.051792 -288.988754)
		(mid 139.334748 -288.912577)
		(end 139.617704 -288.988754)
		(width 0.0889)
		(layer "In2.Cu")
		(net "M_I_CPU1_SB_DQ<24>")
	)
	(arc
		(start 134.92607 -288.99358)
		(mid 135.109578 -289.039074)
		(end 135.29183 -288.988754)
		(width 0.0889)
		(layer "In2.Cu")
		(net "M_I_CPU1_SB_DQ<24>")
	)
	(arc
		(start 139.991846 -288.988754)
		(mid 140.274802 -288.912577)
		(end 140.557758 -288.988754)
		(width 0.0889)
		(layer "In2.Cu")
		(net "M_I_CPU1_SB_DQ<24>")
	)
	(arc
		(start 130.591814 -288.988754)
		(mid 130.87477 -288.912577)
		(end 131.157726 -288.988754)
		(width 0.0889)
		(layer "In2.Cu")
		(net "M_I_CPU1_SB_DQ<24>")
	)
	(arc
		(start 143.751808 -288.988754)
		(mid 143.888244 -288.931929)
		(end 144.034764 -288.912554)
		(width 0.0889)
		(layer "In2.Cu")
		(net "M_I_CPU1_SB_DQ<24>")
	)
	(arc
		(start 138.111738 -288.988754)
		(mid 138.394694 -288.912577)
		(end 138.67765 -288.988754)
		(width 0.0889)
		(layer "In2.Cu")
		(net "M_I_CPU1_SB_DQ<24>")
	)
	(arc
		(start 139.626086 -288.99358)
		(mid 139.809594 -289.039074)
		(end 139.991846 -288.988754)
		(width 0.0889)
		(layer "In2.Cu")
		(net "M_I_CPU1_SB_DQ<24>")
	)
	(arc
		(start 141.8717 -288.988754)
		(mid 142.154656 -288.912577)
		(end 142.437612 -288.988754)
		(width 0.0889)
		(layer "In2.Cu")
		(net "M_I_CPU1_SB_DQ<24>")
	)
	(segment
		(start 128.05791 -288.400236)
		(end 128.524762 -288.666174)
		(width 0.10668)
		(layer "F.Cu")
		(net "M_I_CPU1_SB_DQ<23>")
	)
	(segment
		(start 151.594566 -298.438062)
		(end 152.075642 -297.956986)
		(width 0.14478)
		(layer "In2.Cu")
		(net "M_I_CPU1_SB_DQ<23>")
	)
	(segment
		(start 145.595086 -288.263584)
		(end 145.907506 -288.576004)
		(width 0.0889)
		(layer "In2.Cu")
		(net "M_I_CPU1_SB_DQ<23>")
	)
	(segment
		(start 153.323798 -300.54169)
		(end 160.647126 -307.865018)
		(width 0.14478)
		(layer "In2.Cu")
		(net "M_I_CPU1_SB_DQ<23>")
	)
	(segment
		(start 175.05553 -308.260496)
		(end 179.091082 -308.260496)
		(width 0.14478)
		(layer "In2.Cu")
		(net "M_I_CPU1_SB_DQ<23>")
	)
	(segment
		(start 173.002956 -309.110634)
		(end 175.05553 -308.260496)
		(width 0.14478)
		(layer "In2.Cu")
		(net "M_I_CPU1_SB_DQ<23>")
	)
	(segment
		(start 134.343394 -288.339022)
		(end 134.351776 -288.343848)
		(width 0.0889)
		(layer "In2.Cu")
		(net "M_I_CPU1_SB_DQ<23>")
	)
	(segment
		(start 153.08453 -298.737274)
		(end 153.323798 -298.976542)
		(width 0.14478)
		(layer "In2.Cu")
		(net "M_I_CPU1_SB_DQ<23>")
	)
	(segment
		(start 146.925538 -291.755576)
		(end 147.345654 -292.175692)
		(width 0.14478)
		(layer "In2.Cu")
		(net "M_I_CPU1_SB_DQ<23>")
	)
	(segment
		(start 152.465786 -298.34713)
		(end 151.98471 -298.828206)
		(width 0.14478)
		(layer "In2.Cu")
		(net "M_I_CPU1_SB_DQ<23>")
	)
	(segment
		(start 160.647126 -307.865018)
		(end 163.654232 -309.110634)
		(width 0.14478)
		(layer "In2.Cu")
		(net "M_I_CPU1_SB_DQ<23>")
	)
	(segment
		(start 128.370838 -288.400744)
		(end 128.392936 -288.317686)
		(width 0.0889)
		(layer "In2.Cu")
		(net "M_I_CPU1_SB_DQ<23>")
	)
	(segment
		(start 168.97985 -308.260496)
		(end 171.032424 -309.110634)
		(width 0.14478)
		(layer "In2.Cu")
		(net "M_I_CPU1_SB_DQ<23>")
	)
	(segment
		(start 151.204422 -298.047918)
		(end 151.204422 -298.276518)
		(width 0.14478)
		(layer "In2.Cu")
		(net "M_I_CPU1_SB_DQ<23>")
	)
	(segment
		(start 142.803372 -288.339022)
		(end 142.811754 -288.343848)
		(width 0.0889)
		(layer "In2.Cu")
		(net "M_I_CPU1_SB_DQ<23>")
	)
	(segment
		(start 140.557758 -288.343848)
		(end 140.56614 -288.339022)
		(width 0.0889)
		(layer "In2.Cu")
		(net "M_I_CPU1_SB_DQ<23>")
	)
	(segment
		(start 151.685498 -297.338242)
		(end 151.685498 -297.566842)
		(width 0.14478)
		(layer "In2.Cu")
		(net "M_I_CPU1_SB_DQ<23>")
	)
	(segment
		(start 147.345654 -292.175692)
		(end 147.926806 -293.57955)
		(width 0.14478)
		(layer "In2.Cu")
		(net "M_I_CPU1_SB_DQ<23>")
	)
	(segment
		(start 129.643378 -288.339022)
		(end 129.65176 -288.343848)
		(width 0.0889)
		(layer "In2.Cu")
		(net "M_I_CPU1_SB_DQ<23>")
	)
	(segment
		(start 132.09778 -288.343848)
		(end 132.106162 -288.339022)
		(width 0.0889)
		(layer "In2.Cu")
		(net "M_I_CPU1_SB_DQ<23>")
	)
	(segment
		(start 139.617704 -288.343848)
		(end 139.626086 -288.339022)
		(width 0.0889)
		(layer "In2.Cu")
		(net "M_I_CPU1_SB_DQ<23>")
	)
	(segment
		(start 144.286224 -288.360866)
		(end 144.315688 -288.343848)
		(width 0.0889)
		(layer "In2.Cu")
		(net "M_I_CPU1_SB_DQ<23>")
	)
	(segment
		(start 152.075642 -297.956986)
		(end 152.304242 -297.956986)
		(width 0.14478)
		(layer "In2.Cu")
		(net "M_I_CPU1_SB_DQ<23>")
	)
	(segment
		(start 152.146254 -299.21835)
		(end 152.374854 -299.21835)
		(width 0.14478)
		(layer "In2.Cu")
		(net "M_I_CPU1_SB_DQ<23>")
	)
	(segment
		(start 151.98471 -298.828206)
		(end 151.98471 -299.056806)
		(width 0.14478)
		(layer "In2.Cu")
		(net "M_I_CPU1_SB_DQ<23>")
	)
	(segment
		(start 163.654232 -309.110634)
		(end 165.232842 -309.110634)
		(width 0.14478)
		(layer "In2.Cu")
		(net "M_I_CPU1_SB_DQ<23>")
	)
	(segment
		(start 145.907506 -289.721544)
		(end 146.625818 -291.455856)
		(width 0.0889)
		(layer "In2.Cu")
		(net "M_I_CPU1_SB_DQ<23>")
	)
	(segment
		(start 151.204422 -298.276518)
		(end 151.365966 -298.438062)
		(width 0.14478)
		(layer "In2.Cu")
		(net "M_I_CPU1_SB_DQ<23>")
	)
	(segment
		(start 131.157726 -288.343848)
		(end 131.166108 -288.339022)
		(width 0.0889)
		(layer "In2.Cu")
		(net "M_I_CPU1_SB_DQ<23>")
	)
	(segment
		(start 138.103356 -288.339022)
		(end 138.111738 -288.343848)
		(width 0.0889)
		(layer "In2.Cu")
		(net "M_I_CPU1_SB_DQ<23>")
	)
	(segment
		(start 144.615408 -288.263584)
		(end 145.595086 -288.263584)
		(width 0.0889)
		(layer "In2.Cu")
		(net "M_I_CPU1_SB_DQ<23>")
	)
	(segment
		(start 171.032424 -309.110634)
		(end 173.002956 -309.110634)
		(width 0.14478)
		(layer "In2.Cu")
		(net "M_I_CPU1_SB_DQ<23>")
	)
	(segment
		(start 139.04341 -288.339022)
		(end 139.051792 -288.343848)
		(width 0.0889)
		(layer "In2.Cu")
		(net "M_I_CPU1_SB_DQ<23>")
	)
	(segment
		(start 152.374854 -299.21835)
		(end 152.85593 -298.737274)
		(width 0.14478)
		(layer "In2.Cu")
		(net "M_I_CPU1_SB_DQ<23>")
	)
	(segment
		(start 147.926806 -293.57955)
		(end 151.685498 -297.338242)
		(width 0.14478)
		(layer "In2.Cu")
		(net "M_I_CPU1_SB_DQ<23>")
	)
	(segment
		(start 134.917688 -288.343848)
		(end 134.92607 -288.339022)
		(width 0.0889)
		(layer "In2.Cu")
		(net "M_I_CPU1_SB_DQ<23>")
	)
	(segment
		(start 135.857742 -288.343848)
		(end 135.866124 -288.339022)
		(width 0.0889)
		(layer "In2.Cu")
		(net "M_I_CPU1_SB_DQ<23>")
	)
	(segment
		(start 151.98471 -299.056806)
		(end 152.146254 -299.21835)
		(width 0.14478)
		(layer "In2.Cu")
		(net "M_I_CPU1_SB_DQ<23>")
	)
	(segment
		(start 151.365966 -298.438062)
		(end 151.594566 -298.438062)
		(width 0.14478)
		(layer "In2.Cu")
		(net "M_I_CPU1_SB_DQ<23>")
	)
	(segment
		(start 146.625818 -291.455856)
		(end 146.925538 -291.755576)
		(width 0.0889)
		(layer "In2.Cu")
		(net "M_I_CPU1_SB_DQ<23>")
	)
	(segment
		(start 152.304242 -297.956986)
		(end 152.465786 -298.11853)
		(width 0.14478)
		(layer "In2.Cu")
		(net "M_I_CPU1_SB_DQ<23>")
	)
	(segment
		(start 152.85593 -298.737274)
		(end 153.08453 -298.737274)
		(width 0.14478)
		(layer "In2.Cu")
		(net "M_I_CPU1_SB_DQ<23>")
	)
	(segment
		(start 151.685498 -297.566842)
		(end 151.204422 -298.047918)
		(width 0.14478)
		(layer "In2.Cu")
		(net "M_I_CPU1_SB_DQ<23>")
	)
	(segment
		(start 143.377666 -288.343848)
		(end 143.386048 -288.339022)
		(width 0.0889)
		(layer "In2.Cu")
		(net "M_I_CPU1_SB_DQ<23>")
	)
	(segment
		(start 145.907506 -288.576004)
		(end 145.907506 -289.721544)
		(width 0.0889)
		(layer "In2.Cu")
		(net "M_I_CPU1_SB_DQ<23>")
	)
	(segment
		(start 179.091082 -308.260496)
		(end 179.516024 -308.685438)
		(width 0.14478)
		(layer "In2.Cu")
		(net "M_I_CPU1_SB_DQ<23>")
	)
	(segment
		(start 130.583432 -288.339022)
		(end 130.591814 -288.343848)
		(width 0.0889)
		(layer "In2.Cu")
		(net "M_I_CPU1_SB_DQ<23>")
	)
	(segment
		(start 152.465786 -298.11853)
		(end 152.465786 -298.34713)
		(width 0.14478)
		(layer "In2.Cu")
		(net "M_I_CPU1_SB_DQ<23>")
	)
	(segment
		(start 153.323798 -298.976542)
		(end 153.323798 -300.54169)
		(width 0.14478)
		(layer "In2.Cu")
		(net "M_I_CPU1_SB_DQ<23>")
	)
	(segment
		(start 167.285416 -308.260496)
		(end 168.97985 -308.260496)
		(width 0.14478)
		(layer "In2.Cu")
		(net "M_I_CPU1_SB_DQ<23>")
	)
	(segment
		(start 165.232842 -309.110634)
		(end 167.285416 -308.260496)
		(width 0.14478)
		(layer "In2.Cu")
		(net "M_I_CPU1_SB_DQ<23>")
	)
	(segment
		(start 128.524762 -288.666174)
		(end 128.370838 -288.400744)
		(width 0.0889)
		(layer "In2.Cu")
		(net "M_I_CPU1_SB_DQ<23>")
	)
	(arc
		(start 134.351776 -288.343848)
		(mid 134.634732 -288.420025)
		(end 134.917688 -288.343848)
		(width 0.0889)
		(layer "In2.Cu")
		(net "M_I_CPU1_SB_DQ<23>")
	)
	(arc
		(start 142.811754 -288.343848)
		(mid 143.09471 -288.420025)
		(end 143.377666 -288.343848)
		(width 0.0889)
		(layer "In2.Cu")
		(net "M_I_CPU1_SB_DQ<23>")
	)
	(arc
		(start 130.217672 -288.343848)
		(mid 130.399923 -288.293464)
		(end 130.583432 -288.339022)
		(width 0.0889)
		(layer "In2.Cu")
		(net "M_I_CPU1_SB_DQ<23>")
	)
	(arc
		(start 128.711706 -288.343848)
		(mid 128.994662 -288.420025)
		(end 129.277618 -288.343848)
		(width 0.0889)
		(layer "In2.Cu")
		(net "M_I_CPU1_SB_DQ<23>")
	)
	(arc
		(start 144.315688 -288.343848)
		(mid 144.460271 -288.284018)
		(end 144.615408 -288.263584)
		(width 0.0889)
		(layer "In2.Cu")
		(net "M_I_CPU1_SB_DQ<23>")
	)
	(arc
		(start 138.111738 -288.343848)
		(mid 138.394694 -288.420025)
		(end 138.67765 -288.343848)
		(width 0.0889)
		(layer "In2.Cu")
		(net "M_I_CPU1_SB_DQ<23>")
	)
	(arc
		(start 135.29183 -288.343848)
		(mid 135.574786 -288.420025)
		(end 135.857742 -288.343848)
		(width 0.0889)
		(layer "In2.Cu")
		(net "M_I_CPU1_SB_DQ<23>")
	)
	(arc
		(start 131.531868 -288.343848)
		(mid 131.814824 -288.420025)
		(end 132.09778 -288.343848)
		(width 0.0889)
		(layer "In2.Cu")
		(net "M_I_CPU1_SB_DQ<23>")
	)
	(arc
		(start 129.277618 -288.343848)
		(mid 129.459869 -288.293464)
		(end 129.643378 -288.339022)
		(width 0.0889)
		(layer "In2.Cu")
		(net "M_I_CPU1_SB_DQ<23>")
	)
	(arc
		(start 141.8717 -288.343848)
		(mid 142.154656 -288.420025)
		(end 142.437612 -288.343848)
		(width 0.0889)
		(layer "In2.Cu")
		(net "M_I_CPU1_SB_DQ<23>")
	)
	(arc
		(start 133.411722 -288.343848)
		(mid 133.694678 -288.420025)
		(end 133.977634 -288.343848)
		(width 0.0889)
		(layer "In2.Cu")
		(net "M_I_CPU1_SB_DQ<23>")
	)
	(arc
		(start 143.386048 -288.339022)
		(mid 143.569556 -288.293497)
		(end 143.751808 -288.343848)
		(width 0.0889)
		(layer "In2.Cu")
		(net "M_I_CPU1_SB_DQ<23>")
	)
	(arc
		(start 140.56614 -288.339022)
		(mid 140.749648 -288.293497)
		(end 140.9319 -288.343848)
		(width 0.0889)
		(layer "In2.Cu")
		(net "M_I_CPU1_SB_DQ<23>")
	)
	(arc
		(start 132.471922 -288.343848)
		(mid 132.754878 -288.420025)
		(end 133.037834 -288.343848)
		(width 0.0889)
		(layer "In2.Cu")
		(net "M_I_CPU1_SB_DQ<23>")
	)
	(arc
		(start 136.797796 -288.343848)
		(mid 136.98474 -288.293559)
		(end 137.171684 -288.343848)
		(width 0.0889)
		(layer "In2.Cu")
		(net "M_I_CPU1_SB_DQ<23>")
	)
	(arc
		(start 128.392936 -288.317686)
		(mid 128.555267 -288.294837)
		(end 128.711706 -288.343848)
		(width 0.0889)
		(layer "In2.Cu")
		(net "M_I_CPU1_SB_DQ<23>")
	)
	(arc
		(start 141.497812 -288.343848)
		(mid 141.684756 -288.293559)
		(end 141.8717 -288.343848)
		(width 0.0889)
		(layer "In2.Cu")
		(net "M_I_CPU1_SB_DQ<23>")
	)
	(arc
		(start 134.92607 -288.339022)
		(mid 135.109578 -288.293497)
		(end 135.29183 -288.343848)
		(width 0.0889)
		(layer "In2.Cu")
		(net "M_I_CPU1_SB_DQ<23>")
	)
	(arc
		(start 135.866124 -288.339022)
		(mid 136.049632 -288.293497)
		(end 136.231884 -288.343848)
		(width 0.0889)
		(layer "In2.Cu")
		(net "M_I_CPU1_SB_DQ<23>")
	)
	(arc
		(start 139.991846 -288.343848)
		(mid 140.274802 -288.420025)
		(end 140.557758 -288.343848)
		(width 0.0889)
		(layer "In2.Cu")
		(net "M_I_CPU1_SB_DQ<23>")
	)
	(arc
		(start 140.9319 -288.343848)
		(mid 141.214856 -288.420025)
		(end 141.497812 -288.343848)
		(width 0.0889)
		(layer "In2.Cu")
		(net "M_I_CPU1_SB_DQ<23>")
	)
	(arc
		(start 132.106162 -288.339022)
		(mid 132.28967 -288.293497)
		(end 132.471922 -288.343848)
		(width 0.0889)
		(layer "In2.Cu")
		(net "M_I_CPU1_SB_DQ<23>")
	)
	(arc
		(start 142.437612 -288.343848)
		(mid 142.619863 -288.293464)
		(end 142.803372 -288.339022)
		(width 0.0889)
		(layer "In2.Cu")
		(net "M_I_CPU1_SB_DQ<23>")
	)
	(arc
		(start 143.751808 -288.343848)
		(mid 144.016865 -288.419741)
		(end 144.286224 -288.360866)
		(width 0.0889)
		(layer "In2.Cu")
		(net "M_I_CPU1_SB_DQ<23>")
	)
	(arc
		(start 136.231884 -288.343848)
		(mid 136.51484 -288.420025)
		(end 136.797796 -288.343848)
		(width 0.0889)
		(layer "In2.Cu")
		(net "M_I_CPU1_SB_DQ<23>")
	)
	(arc
		(start 138.67765 -288.343848)
		(mid 138.859901 -288.293464)
		(end 139.04341 -288.339022)
		(width 0.0889)
		(layer "In2.Cu")
		(net "M_I_CPU1_SB_DQ<23>")
	)
	(arc
		(start 137.171684 -288.343848)
		(mid 137.45464 -288.420025)
		(end 137.737596 -288.343848)
		(width 0.0889)
		(layer "In2.Cu")
		(net "M_I_CPU1_SB_DQ<23>")
	)
	(arc
		(start 139.626086 -288.339022)
		(mid 139.809594 -288.293497)
		(end 139.991846 -288.343848)
		(width 0.0889)
		(layer "In2.Cu")
		(net "M_I_CPU1_SB_DQ<23>")
	)
	(arc
		(start 133.037834 -288.343848)
		(mid 133.224778 -288.293559)
		(end 133.411722 -288.343848)
		(width 0.0889)
		(layer "In2.Cu")
		(net "M_I_CPU1_SB_DQ<23>")
	)
	(arc
		(start 139.051792 -288.343848)
		(mid 139.334748 -288.420025)
		(end 139.617704 -288.343848)
		(width 0.0889)
		(layer "In2.Cu")
		(net "M_I_CPU1_SB_DQ<23>")
	)
	(arc
		(start 133.977634 -288.343848)
		(mid 134.159885 -288.293464)
		(end 134.343394 -288.339022)
		(width 0.0889)
		(layer "In2.Cu")
		(net "M_I_CPU1_SB_DQ<23>")
	)
	(arc
		(start 130.591814 -288.343848)
		(mid 130.87477 -288.420025)
		(end 131.157726 -288.343848)
		(width 0.0889)
		(layer "In2.Cu")
		(net "M_I_CPU1_SB_DQ<23>")
	)
	(arc
		(start 131.166108 -288.339022)
		(mid 131.349616 -288.293497)
		(end 131.531868 -288.343848)
		(width 0.0889)
		(layer "In2.Cu")
		(net "M_I_CPU1_SB_DQ<23>")
	)
	(arc
		(start 137.737596 -288.343848)
		(mid 137.919847 -288.293464)
		(end 138.103356 -288.339022)
		(width 0.0889)
		(layer "In2.Cu")
		(net "M_I_CPU1_SB_DQ<23>")
	)
	(arc
		(start 129.65176 -288.343848)
		(mid 129.934716 -288.420025)
		(end 130.217672 -288.343848)
		(width 0.0889)
		(layer "In2.Cu")
		(net "M_I_CPU1_SB_DQ<23>")
	)
	(segment
		(start 129.467864 -287.590484)
		(end 129.934716 -287.856422)
		(width 0.10668)
		(layer "F.Cu")
		(net "M_I_CPU1_SB_DQ<22>")
	)
	(segment
		(start 138.20775 -287.533842)
		(end 138.216132 -287.529016)
		(width 0.0889)
		(layer "In2.Cu")
		(net "M_I_CPU1_SB_DQ<22>")
	)
	(segment
		(start 175.825658 -306.560474)
		(end 176.787556 -306.560474)
		(width 0.14478)
		(layer "In2.Cu")
		(net "M_I_CPU1_SB_DQ<22>")
	)
	(segment
		(start 173.463712 -307.234336)
		(end 173.873922 -307.404516)
		(width 0.14478)
		(layer "In2.Cu")
		(net "M_I_CPU1_SB_DQ<22>")
	)
	(segment
		(start 144.723612 -287.66897)
		(end 145.578322 -287.66897)
		(width 0.0889)
		(layer "In2.Cu")
		(net "M_I_CPU1_SB_DQ<22>")
	)
	(segment
		(start 147.631404 -290.659566)
		(end 148.579332 -292.948868)
		(width 0.14478)
		(layer "In2.Cu")
		(net "M_I_CPU1_SB_DQ<22>")
	)
	(segment
		(start 146.382486 -289.410648)
		(end 147.024598 -290.05276)
		(width 0.0889)
		(layer "In2.Cu")
		(net "M_I_CPU1_SB_DQ<22>")
	)
	(segment
		(start 155.502864 -299.99178)
		(end 155.502864 -300.22038)
		(width 0.14478)
		(layer "In2.Cu")
		(net "M_I_CPU1_SB_DQ<22>")
	)
	(segment
		(start 163.62934 -307.410612)
		(end 165.220142 -307.410612)
		(width 0.14478)
		(layer "In2.Cu")
		(net "M_I_CPU1_SB_DQ<22>")
	)
	(segment
		(start 178.033934 -306.400962)
		(end 178.193192 -306.241704)
		(width 0.14478)
		(layer "In2.Cu")
		(net "M_I_CPU1_SB_DQ<22>")
	)
	(segment
		(start 154.782266 -299.151802)
		(end 154.782266 -299.380402)
		(width 0.14478)
		(layer "In2.Cu")
		(net "M_I_CPU1_SB_DQ<22>")
	)
	(segment
		(start 179.516024 -306.391818)
		(end 179.516024 -306.985416)
		(width 0.14478)
		(layer "In2.Cu")
		(net "M_I_CPU1_SB_DQ<22>")
	)
	(segment
		(start 173.873922 -307.404516)
		(end 174.099982 -307.31079)
		(width 0.14478)
		(layer "In2.Cu")
		(net "M_I_CPU1_SB_DQ<22>")
	)
	(segment
		(start 148.579332 -292.948868)
		(end 154.782266 -299.151802)
		(width 0.14478)
		(layer "In2.Cu")
		(net "M_I_CPU1_SB_DQ<22>")
	)
	(segment
		(start 174.35449 -306.69611)
		(end 174.68215 -306.560474)
		(width 0.14478)
		(layer "In2.Cu")
		(net "M_I_CPU1_SB_DQ<22>")
	)
	(segment
		(start 174.958248 -306.560474)
		(end 175.266858 -306.869084)
		(width 0.14478)
		(layer "In2.Cu")
		(net "M_I_CPU1_SB_DQ<22>")
	)
	(segment
		(start 177.634392 -306.879244)
		(end 177.874676 -306.879244)
		(width 0.14478)
		(layer "In2.Cu")
		(net "M_I_CPU1_SB_DQ<22>")
	)
	(segment
		(start 169.0878 -306.560474)
		(end 169.41419 -306.886864)
		(width 0.14478)
		(layer "In2.Cu")
		(net "M_I_CPU1_SB_DQ<22>")
	)
	(segment
		(start 154.222958 -300.16831)
		(end 154.384502 -300.329854)
		(width 0.14478)
		(layer "In2.Cu")
		(net "M_I_CPU1_SB_DQ<22>")
	)
	(segment
		(start 155.11272 -299.830236)
		(end 155.34132 -299.830236)
		(width 0.14478)
		(layer "In2.Cu")
		(net "M_I_CPU1_SB_DQ<22>")
	)
	(segment
		(start 167.172894 -306.560474)
		(end 167.405558 -306.560474)
		(width 0.14478)
		(layer "In2.Cu")
		(net "M_I_CPU1_SB_DQ<22>")
	)
	(segment
		(start 165.220142 -307.410612)
		(end 165.759892 -307.186838)
		(width 0.14478)
		(layer "In2.Cu")
		(net "M_I_CPU1_SB_DQ<22>")
	)
	(segment
		(start 154.613102 -300.329854)
		(end 155.11272 -299.830236)
		(width 0.14478)
		(layer "In2.Cu")
		(net "M_I_CPU1_SB_DQ<22>")
	)
	(segment
		(start 154.782266 -299.380402)
		(end 154.222958 -299.93971)
		(width 0.14478)
		(layer "In2.Cu")
		(net "M_I_CPU1_SB_DQ<22>")
	)
	(segment
		(start 169.767758 -306.886864)
		(end 171.032424 -307.410612)
		(width 0.14478)
		(layer "In2.Cu")
		(net "M_I_CPU1_SB_DQ<22>")
	)
	(segment
		(start 129.780792 -287.590992)
		(end 129.803144 -287.50768)
		(width 0.0889)
		(layer "In2.Cu")
		(net "M_I_CPU1_SB_DQ<22>")
	)
	(segment
		(start 177.105056 -306.242974)
		(end 177.317146 -306.242974)
		(width 0.14478)
		(layer "In2.Cu")
		(net "M_I_CPU1_SB_DQ<22>")
	)
	(segment
		(start 166.58209 -306.805076)
		(end 167.172894 -306.560474)
		(width 0.14478)
		(layer "In2.Cu")
		(net "M_I_CPU1_SB_DQ<22>")
	)
	(segment
		(start 154.384502 -300.329854)
		(end 154.613102 -300.329854)
		(width 0.14478)
		(layer "In2.Cu")
		(net "M_I_CPU1_SB_DQ<22>")
	)
	(segment
		(start 171.032424 -307.410612)
		(end 173.038008 -307.410612)
		(width 0.14478)
		(layer "In2.Cu")
		(net "M_I_CPU1_SB_DQ<22>")
	)
	(segment
		(start 169.41419 -306.886864)
		(end 169.767758 -306.886864)
		(width 0.14478)
		(layer "In2.Cu")
		(net "M_I_CPU1_SB_DQ<22>")
	)
	(segment
		(start 176.787556 -306.560474)
		(end 177.105056 -306.242974)
		(width 0.14478)
		(layer "In2.Cu")
		(net "M_I_CPU1_SB_DQ<22>")
	)
	(segment
		(start 173.038008 -307.410612)
		(end 173.463712 -307.234336)
		(width 0.14478)
		(layer "In2.Cu")
		(net "M_I_CPU1_SB_DQ<22>")
	)
	(segment
		(start 133.507734 -287.533842)
		(end 133.516116 -287.529016)
		(width 0.0889)
		(layer "In2.Cu")
		(net "M_I_CPU1_SB_DQ<22>")
	)
	(segment
		(start 129.934716 -287.856422)
		(end 129.780792 -287.590992)
		(width 0.0889)
		(layer "In2.Cu")
		(net "M_I_CPU1_SB_DQ<22>")
	)
	(segment
		(start 137.267696 -287.533842)
		(end 137.276078 -287.529016)
		(width 0.0889)
		(layer "In2.Cu")
		(net "M_I_CPU1_SB_DQ<22>")
	)
	(segment
		(start 177.874676 -306.879244)
		(end 178.033934 -306.719986)
		(width 0.14478)
		(layer "In2.Cu")
		(net "M_I_CPU1_SB_DQ<22>")
	)
	(segment
		(start 147.024598 -290.05276)
		(end 147.631404 -290.659566)
		(width 0.14478)
		(layer "In2.Cu")
		(net "M_I_CPU1_SB_DQ<22>")
	)
	(segment
		(start 178.033934 -306.719986)
		(end 178.033934 -306.400962)
		(width 0.14478)
		(layer "In2.Cu")
		(net "M_I_CPU1_SB_DQ<22>")
	)
	(segment
		(start 166.163752 -307.354224)
		(end 166.394638 -307.258466)
		(width 0.14478)
		(layer "In2.Cu")
		(net "M_I_CPU1_SB_DQ<22>")
	)
	(segment
		(start 146.382486 -288.426144)
		(end 146.382486 -289.410648)
		(width 0.0889)
		(layer "In2.Cu")
		(net "M_I_CPU1_SB_DQ<22>")
	)
	(segment
		(start 179.36591 -306.241704)
		(end 179.516024 -306.391818)
		(width 0.14478)
		(layer "In2.Cu")
		(net "M_I_CPU1_SB_DQ<22>")
	)
	(segment
		(start 143.847566 -287.533842)
		(end 143.855948 -287.529016)
		(width 0.0889)
		(layer "In2.Cu")
		(net "M_I_CPU1_SB_DQ<22>")
	)
	(segment
		(start 141.967712 -287.533842)
		(end 141.976094 -287.529016)
		(width 0.0889)
		(layer "In2.Cu")
		(net "M_I_CPU1_SB_DQ<22>")
	)
	(segment
		(start 167.405558 -306.560474)
		(end 167.693848 -306.848764)
		(width 0.14478)
		(layer "In2.Cu")
		(net "M_I_CPU1_SB_DQ<22>")
	)
	(segment
		(start 175.266858 -306.869084)
		(end 175.517048 -306.869084)
		(width 0.14478)
		(layer "In2.Cu")
		(net "M_I_CPU1_SB_DQ<22>")
	)
	(segment
		(start 177.475134 -306.400962)
		(end 177.475134 -306.719986)
		(width 0.14478)
		(layer "In2.Cu")
		(net "M_I_CPU1_SB_DQ<22>")
	)
	(segment
		(start 155.003246 -300.948598)
		(end 159.93491 -305.880262)
		(width 0.14478)
		(layer "In2.Cu")
		(net "M_I_CPU1_SB_DQ<22>")
	)
	(segment
		(start 175.517048 -306.869084)
		(end 175.825658 -306.560474)
		(width 0.14478)
		(layer "In2.Cu")
		(net "M_I_CPU1_SB_DQ<22>")
	)
	(segment
		(start 177.317146 -306.242974)
		(end 177.475134 -306.400962)
		(width 0.14478)
		(layer "In2.Cu")
		(net "M_I_CPU1_SB_DQ<22>")
	)
	(segment
		(start 165.759892 -307.186838)
		(end 166.163752 -307.354224)
		(width 0.14478)
		(layer "In2.Cu")
		(net "M_I_CPU1_SB_DQ<22>")
	)
	(segment
		(start 132.93344 -287.529016)
		(end 132.941822 -287.533842)
		(width 0.0889)
		(layer "In2.Cu")
		(net "M_I_CPU1_SB_DQ<22>")
	)
	(segment
		(start 155.502864 -300.22038)
		(end 155.003246 -300.719998)
		(width 0.14478)
		(layer "In2.Cu")
		(net "M_I_CPU1_SB_DQ<22>")
	)
	(segment
		(start 159.93491 -305.880262)
		(end 163.62934 -307.410612)
		(width 0.14478)
		(layer "In2.Cu")
		(net "M_I_CPU1_SB_DQ<22>")
	)
	(segment
		(start 131.993386 -287.529016)
		(end 132.001768 -287.533842)
		(width 0.0889)
		(layer "In2.Cu")
		(net "M_I_CPU1_SB_DQ<22>")
	)
	(segment
		(start 154.222958 -299.93971)
		(end 154.222958 -300.16831)
		(width 0.14478)
		(layer "In2.Cu")
		(net "M_I_CPU1_SB_DQ<22>")
	)
	(segment
		(start 178.193192 -306.241704)
		(end 179.36591 -306.241704)
		(width 0.14478)
		(layer "In2.Cu")
		(net "M_I_CPU1_SB_DQ<22>")
	)
	(segment
		(start 145.658586 -287.702244)
		(end 146.382486 -288.426144)
		(width 0.0889)
		(layer "In2.Cu")
		(net "M_I_CPU1_SB_DQ<22>")
	)
	(segment
		(start 174.68215 -306.560474)
		(end 174.958248 -306.560474)
		(width 0.14478)
		(layer "In2.Cu")
		(net "M_I_CPU1_SB_DQ<22>")
	)
	(segment
		(start 166.394638 -307.258466)
		(end 166.58209 -306.805076)
		(width 0.14478)
		(layer "In2.Cu")
		(net "M_I_CPU1_SB_DQ<22>")
	)
	(segment
		(start 168.252648 -306.560474)
		(end 169.0878 -306.560474)
		(width 0.14478)
		(layer "In2.Cu")
		(net "M_I_CPU1_SB_DQ<22>")
	)
	(segment
		(start 155.34132 -299.830236)
		(end 155.502864 -299.99178)
		(width 0.14478)
		(layer "In2.Cu")
		(net "M_I_CPU1_SB_DQ<22>")
	)
	(segment
		(start 141.393418 -287.529016)
		(end 141.4018 -287.533842)
		(width 0.0889)
		(layer "In2.Cu")
		(net "M_I_CPU1_SB_DQ<22>")
	)
	(segment
		(start 140.453364 -287.529016)
		(end 140.461746 -287.533842)
		(width 0.0889)
		(layer "In2.Cu")
		(net "M_I_CPU1_SB_DQ<22>")
	)
	(segment
		(start 155.003246 -300.719998)
		(end 155.003246 -300.948598)
		(width 0.14478)
		(layer "In2.Cu")
		(net "M_I_CPU1_SB_DQ<22>")
	)
	(segment
		(start 177.475134 -306.719986)
		(end 177.634392 -306.879244)
		(width 0.14478)
		(layer "In2.Cu")
		(net "M_I_CPU1_SB_DQ<22>")
	)
	(segment
		(start 167.693848 -306.848764)
		(end 167.964358 -306.848764)
		(width 0.14478)
		(layer "In2.Cu")
		(net "M_I_CPU1_SB_DQ<22>")
	)
	(segment
		(start 167.964358 -306.848764)
		(end 168.252648 -306.560474)
		(width 0.14478)
		(layer "In2.Cu")
		(net "M_I_CPU1_SB_DQ<22>")
	)
	(segment
		(start 136.693402 -287.529016)
		(end 136.701784 -287.533842)
		(width 0.0889)
		(layer "In2.Cu")
		(net "M_I_CPU1_SB_DQ<22>")
	)
	(segment
		(start 174.099982 -307.31079)
		(end 174.35449 -306.69611)
		(width 0.14478)
		(layer "In2.Cu")
		(net "M_I_CPU1_SB_DQ<22>")
	)
	(segment
		(start 135.753348 -287.529016)
		(end 135.76173 -287.533842)
		(width 0.0889)
		(layer "In2.Cu")
		(net "M_I_CPU1_SB_DQ<22>")
	)
	(arc
		(start 134.821676 -287.533842)
		(mid 135.104632 -287.609985)
		(end 135.387588 -287.533842)
		(width 0.0889)
		(layer "In2.Cu")
		(net "M_I_CPU1_SB_DQ<22>")
	)
	(arc
		(start 143.855948 -287.529016)
		(mid 144.03971 -287.4834)
		(end 144.222216 -287.533842)
		(width 0.0889)
		(layer "In2.Cu")
		(net "M_I_CPU1_SB_DQ<22>")
	)
	(arc
		(start 132.941822 -287.533842)
		(mid 133.224778 -287.609985)
		(end 133.507734 -287.533842)
		(width 0.0889)
		(layer "In2.Cu")
		(net "M_I_CPU1_SB_DQ<22>")
	)
	(arc
		(start 139.147804 -287.533842)
		(mid 139.334748 -287.483587)
		(end 139.521692 -287.533842)
		(width 0.0889)
		(layer "In2.Cu")
		(net "M_I_CPU1_SB_DQ<22>")
	)
	(arc
		(start 144.222216 -287.533842)
		(mid 144.463963 -287.634629)
		(end 144.723612 -287.66897)
		(width 0.0889)
		(layer "In2.Cu")
		(net "M_I_CPU1_SB_DQ<22>")
	)
	(arc
		(start 138.216132 -287.529016)
		(mid 138.39964 -287.483522)
		(end 138.581892 -287.533842)
		(width 0.0889)
		(layer "In2.Cu")
		(net "M_I_CPU1_SB_DQ<22>")
	)
	(arc
		(start 140.461746 -287.533842)
		(mid 140.744702 -287.609985)
		(end 141.027658 -287.533842)
		(width 0.0889)
		(layer "In2.Cu")
		(net "M_I_CPU1_SB_DQ<22>")
	)
	(arc
		(start 133.881876 -287.533842)
		(mid 134.164832 -287.609985)
		(end 134.447788 -287.533842)
		(width 0.0889)
		(layer "In2.Cu")
		(net "M_I_CPU1_SB_DQ<22>")
	)
	(arc
		(start 137.276078 -287.529016)
		(mid 137.459586 -287.483522)
		(end 137.641838 -287.533842)
		(width 0.0889)
		(layer "In2.Cu")
		(net "M_I_CPU1_SB_DQ<22>")
	)
	(arc
		(start 129.803144 -287.50768)
		(mid 129.965476 -287.484862)
		(end 130.121914 -287.533842)
		(width 0.0889)
		(layer "In2.Cu")
		(net "M_I_CPU1_SB_DQ<22>")
	)
	(arc
		(start 137.641838 -287.533842)
		(mid 137.924794 -287.609985)
		(end 138.20775 -287.533842)
		(width 0.0889)
		(layer "In2.Cu")
		(net "M_I_CPU1_SB_DQ<22>")
	)
	(arc
		(start 131.627626 -287.533842)
		(mid 131.809877 -287.483492)
		(end 131.993386 -287.529016)
		(width 0.0889)
		(layer "In2.Cu")
		(net "M_I_CPU1_SB_DQ<22>")
	)
	(arc
		(start 132.001768 -287.533842)
		(mid 132.284724 -287.609985)
		(end 132.56768 -287.533842)
		(width 0.0889)
		(layer "In2.Cu")
		(net "M_I_CPU1_SB_DQ<22>")
	)
	(arc
		(start 132.56768 -287.533842)
		(mid 132.749931 -287.483492)
		(end 132.93344 -287.529016)
		(width 0.0889)
		(layer "In2.Cu")
		(net "M_I_CPU1_SB_DQ<22>")
	)
	(arc
		(start 135.387588 -287.533842)
		(mid 135.569839 -287.483492)
		(end 135.753348 -287.529016)
		(width 0.0889)
		(layer "In2.Cu")
		(net "M_I_CPU1_SB_DQ<22>")
	)
	(arc
		(start 138.581892 -287.533842)
		(mid 138.864848 -287.609985)
		(end 139.147804 -287.533842)
		(width 0.0889)
		(layer "In2.Cu")
		(net "M_I_CPU1_SB_DQ<22>")
	)
	(arc
		(start 135.76173 -287.533842)
		(mid 136.044686 -287.609985)
		(end 136.327642 -287.533842)
		(width 0.0889)
		(layer "In2.Cu")
		(net "M_I_CPU1_SB_DQ<22>")
	)
	(arc
		(start 139.521692 -287.533842)
		(mid 139.804648 -287.609985)
		(end 140.087604 -287.533842)
		(width 0.0889)
		(layer "In2.Cu")
		(net "M_I_CPU1_SB_DQ<22>")
	)
	(arc
		(start 136.701784 -287.533842)
		(mid 136.98474 -287.609985)
		(end 137.267696 -287.533842)
		(width 0.0889)
		(layer "In2.Cu")
		(net "M_I_CPU1_SB_DQ<22>")
	)
	(arc
		(start 134.447788 -287.533842)
		(mid 134.634732 -287.483587)
		(end 134.821676 -287.533842)
		(width 0.0889)
		(layer "In2.Cu")
		(net "M_I_CPU1_SB_DQ<22>")
	)
	(arc
		(start 130.121914 -287.533842)
		(mid 130.40487 -287.609985)
		(end 130.687826 -287.533842)
		(width 0.0889)
		(layer "In2.Cu")
		(net "M_I_CPU1_SB_DQ<22>")
	)
	(arc
		(start 140.087604 -287.533842)
		(mid 140.269855 -287.483492)
		(end 140.453364 -287.529016)
		(width 0.0889)
		(layer "In2.Cu")
		(net "M_I_CPU1_SB_DQ<22>")
	)
	(arc
		(start 143.281654 -287.533842)
		(mid 143.56461 -287.609985)
		(end 143.847566 -287.533842)
		(width 0.0889)
		(layer "In2.Cu")
		(net "M_I_CPU1_SB_DQ<22>")
	)
	(arc
		(start 141.976094 -287.529016)
		(mid 142.159602 -287.483522)
		(end 142.341854 -287.533842)
		(width 0.0889)
		(layer "In2.Cu")
		(net "M_I_CPU1_SB_DQ<22>")
	)
	(arc
		(start 145.578322 -287.66897)
		(mid 145.621757 -287.677628)
		(end 145.658586 -287.702244)
		(width 0.0889)
		(layer "In2.Cu")
		(net "M_I_CPU1_SB_DQ<22>")
	)
	(arc
		(start 136.327642 -287.533842)
		(mid 136.509893 -287.483492)
		(end 136.693402 -287.529016)
		(width 0.0889)
		(layer "In2.Cu")
		(net "M_I_CPU1_SB_DQ<22>")
	)
	(arc
		(start 142.341854 -287.533842)
		(mid 142.62481 -287.609985)
		(end 142.907766 -287.533842)
		(width 0.0889)
		(layer "In2.Cu")
		(net "M_I_CPU1_SB_DQ<22>")
	)
	(arc
		(start 130.687826 -287.533842)
		(mid 130.87477 -287.483587)
		(end 131.061714 -287.533842)
		(width 0.0889)
		(layer "In2.Cu")
		(net "M_I_CPU1_SB_DQ<22>")
	)
	(arc
		(start 141.4018 -287.533842)
		(mid 141.684756 -287.609985)
		(end 141.967712 -287.533842)
		(width 0.0889)
		(layer "In2.Cu")
		(net "M_I_CPU1_SB_DQ<22>")
	)
	(arc
		(start 131.061714 -287.533842)
		(mid 131.34467 -287.609985)
		(end 131.627626 -287.533842)
		(width 0.0889)
		(layer "In2.Cu")
		(net "M_I_CPU1_SB_DQ<22>")
	)
	(arc
		(start 142.907766 -287.533842)
		(mid 143.09471 -287.483587)
		(end 143.281654 -287.533842)
		(width 0.0889)
		(layer "In2.Cu")
		(net "M_I_CPU1_SB_DQ<22>")
	)
	(arc
		(start 141.027658 -287.533842)
		(mid 141.209909 -287.483492)
		(end 141.393418 -287.529016)
		(width 0.0889)
		(layer "In2.Cu")
		(net "M_I_CPU1_SB_DQ<22>")
	)
	(arc
		(start 133.516116 -287.529016)
		(mid 133.699624 -287.483522)
		(end 133.881876 -287.533842)
		(width 0.0889)
		(layer "In2.Cu")
		(net "M_I_CPU1_SB_DQ<22>")
	)
	(segment
		(start 127.58801 -287.590484)
		(end 128.054862 -287.856422)
		(width 0.10668)
		(layer "F.Cu")
		(net "M_I_CPU1_SB_DQ<21>")
	)
	(segment
		(start 141.967712 -288.178748)
		(end 141.976094 -288.183574)
		(width 0.0889)
		(layer "In2.Cu")
		(net "M_I_CPU1_SB_DQ<21>")
	)
	(segment
		(start 136.693402 -288.183574)
		(end 136.701784 -288.178748)
		(width 0.0889)
		(layer "In2.Cu")
		(net "M_I_CPU1_SB_DQ<21>")
	)
	(segment
		(start 135.753348 -288.183574)
		(end 135.76173 -288.178748)
		(width 0.0889)
		(layer "In2.Cu")
		(net "M_I_CPU1_SB_DQ<21>")
	)
	(segment
		(start 146.156426 -288.512504)
		(end 146.156426 -289.74415)
		(width 0.0889)
		(layer "In2.Cu")
		(net "M_I_CPU1_SB_DQ<21>")
	)
	(segment
		(start 164.20719 -308.260496)
		(end 164.452046 -308.260496)
		(width 0.14478)
		(layer "In2.Cu")
		(net "M_I_CPU1_SB_DQ<21>")
	)
	(segment
		(start 171.823634 -308.260496)
		(end 172.030898 -308.260496)
		(width 0.14478)
		(layer "In2.Cu")
		(net "M_I_CPU1_SB_DQ<21>")
	)
	(segment
		(start 146.156426 -289.74415)
		(end 146.67738 -291.001958)
		(width 0.0889)
		(layer "In2.Cu")
		(net "M_I_CPU1_SB_DQ<21>")
	)
	(segment
		(start 141.393418 -288.183574)
		(end 141.4018 -288.178748)
		(width 0.0889)
		(layer "In2.Cu")
		(net "M_I_CPU1_SB_DQ<21>")
	)
	(segment
		(start 167.84574 -307.410612)
		(end 169.257726 -307.410612)
		(width 0.14478)
		(layer "In2.Cu")
		(net "M_I_CPU1_SB_DQ<21>")
	)
	(segment
		(start 128.807718 -288.178748)
		(end 128.8161 -288.183574)
		(width 0.0889)
		(layer "In2.Cu")
		(net "M_I_CPU1_SB_DQ<21>")
	)
	(segment
		(start 128.054862 -287.856422)
		(end 128.208786 -288.121852)
		(width 0.0889)
		(layer "In2.Cu")
		(net "M_I_CPU1_SB_DQ<21>")
	)
	(segment
		(start 147.112736 -291.299646)
		(end 147.610322 -291.797232)
		(width 0.14478)
		(layer "In2.Cu")
		(net "M_I_CPU1_SB_DQ<21>")
	)
	(segment
		(start 172.030898 -308.260496)
		(end 174.337726 -307.801518)
		(width 0.14478)
		(layer "In2.Cu")
		(net "M_I_CPU1_SB_DQ<21>")
	)
	(segment
		(start 145.696686 -288.052764)
		(end 146.156426 -288.512504)
		(width 0.0889)
		(layer "In2.Cu")
		(net "M_I_CPU1_SB_DQ<21>")
	)
	(segment
		(start 169.528998 -307.464714)
		(end 170.92295 -307.887624)
		(width 0.14478)
		(layer "In2.Cu")
		(net "M_I_CPU1_SB_DQ<21>")
	)
	(segment
		(start 129.747772 -288.178748)
		(end 129.756154 -288.183574)
		(width 0.0889)
		(layer "In2.Cu")
		(net "M_I_CPU1_SB_DQ<21>")
	)
	(segment
		(start 148.189696 -293.195502)
		(end 153.773378 -298.779184)
		(width 0.14478)
		(layer "In2.Cu")
		(net "M_I_CPU1_SB_DQ<21>")
	)
	(segment
		(start 153.773378 -300.355)
		(end 160.129982 -306.711604)
		(width 0.14478)
		(layer "In2.Cu")
		(net "M_I_CPU1_SB_DQ<21>")
	)
	(segment
		(start 137.267696 -288.178748)
		(end 137.276078 -288.183574)
		(width 0.0889)
		(layer "In2.Cu")
		(net "M_I_CPU1_SB_DQ<21>")
	)
	(segment
		(start 175.281844 -307.410612)
		(end 183.191404 -307.410612)
		(width 0.14478)
		(layer "In2.Cu")
		(net "M_I_CPU1_SB_DQ<21>")
	)
	(segment
		(start 163.556188 -308.130956)
		(end 164.20719 -308.260496)
		(width 0.14478)
		(layer "In2.Cu")
		(net "M_I_CPU1_SB_DQ<21>")
	)
	(segment
		(start 138.20775 -288.178748)
		(end 138.216132 -288.183574)
		(width 0.0889)
		(layer "In2.Cu")
		(net "M_I_CPU1_SB_DQ<21>")
	)
	(segment
		(start 128.208786 -288.121852)
		(end 128.304544 -288.147252)
		(width 0.0889)
		(layer "In2.Cu")
		(net "M_I_CPU1_SB_DQ<21>")
	)
	(segment
		(start 131.993386 -288.183574)
		(end 132.001768 -288.178748)
		(width 0.0889)
		(layer "In2.Cu")
		(net "M_I_CPU1_SB_DQ<21>")
	)
	(segment
		(start 146.877532 -291.20211)
		(end 147.112736 -291.299646)
		(width 0.0889)
		(layer "In2.Cu")
		(net "M_I_CPU1_SB_DQ<21>")
	)
	(segment
		(start 164.452046 -308.260496)
		(end 167.84574 -307.410612)
		(width 0.14478)
		(layer "In2.Cu")
		(net "M_I_CPU1_SB_DQ<21>")
	)
	(segment
		(start 132.93344 -288.183574)
		(end 132.941822 -288.178748)
		(width 0.0889)
		(layer "In2.Cu")
		(net "M_I_CPU1_SB_DQ<21>")
	)
	(segment
		(start 146.67738 -291.001958)
		(end 146.877532 -291.20211)
		(width 0.0889)
		(layer "In2.Cu")
		(net "M_I_CPU1_SB_DQ<21>")
	)
	(segment
		(start 144.691354 -288.052764)
		(end 145.696686 -288.052764)
		(width 0.0889)
		(layer "In2.Cu")
		(net "M_I_CPU1_SB_DQ<21>")
	)
	(segment
		(start 170.92295 -307.887624)
		(end 171.823634 -308.260496)
		(width 0.14478)
		(layer "In2.Cu")
		(net "M_I_CPU1_SB_DQ<21>")
	)
	(segment
		(start 147.610322 -291.797232)
		(end 148.189696 -293.195502)
		(width 0.14478)
		(layer "In2.Cu")
		(net "M_I_CPU1_SB_DQ<21>")
	)
	(segment
		(start 153.773378 -298.779184)
		(end 153.773378 -300.355)
		(width 0.14478)
		(layer "In2.Cu")
		(net "M_I_CPU1_SB_DQ<21>")
	)
	(segment
		(start 174.337726 -307.801518)
		(end 175.281844 -307.410612)
		(width 0.14478)
		(layer "In2.Cu")
		(net "M_I_CPU1_SB_DQ<21>")
	)
	(segment
		(start 183.191404 -307.410612)
		(end 183.616092 -307.8353)
		(width 0.14478)
		(layer "In2.Cu")
		(net "M_I_CPU1_SB_DQ<21>")
	)
	(segment
		(start 160.129982 -306.711604)
		(end 163.556188 -308.130956)
		(width 0.14478)
		(layer "In2.Cu")
		(net "M_I_CPU1_SB_DQ<21>")
	)
	(segment
		(start 133.507734 -288.178748)
		(end 133.516116 -288.183574)
		(width 0.0889)
		(layer "In2.Cu")
		(net "M_I_CPU1_SB_DQ<21>")
	)
	(segment
		(start 169.257726 -307.410612)
		(end 169.528998 -307.464714)
		(width 0.14478)
		(layer "In2.Cu")
		(net "M_I_CPU1_SB_DQ<21>")
	)
	(segment
		(start 144.199864 -288.190432)
		(end 144.220438 -288.178748)
		(width 0.0889)
		(layer "In2.Cu")
		(net "M_I_CPU1_SB_DQ<21>")
	)
	(segment
		(start 140.453364 -288.183574)
		(end 140.461746 -288.178748)
		(width 0.0889)
		(layer "In2.Cu")
		(net "M_I_CPU1_SB_DQ<21>")
	)
	(arc
		(start 133.881876 -288.178748)
		(mid 134.164832 -288.102571)
		(end 134.447788 -288.178748)
		(width 0.0889)
		(layer "In2.Cu")
		(net "M_I_CPU1_SB_DQ<21>")
	)
	(arc
		(start 129.18186 -288.178748)
		(mid 129.464816 -288.102571)
		(end 129.747772 -288.178748)
		(width 0.0889)
		(layer "In2.Cu")
		(net "M_I_CPU1_SB_DQ<21>")
	)
	(arc
		(start 140.461746 -288.178748)
		(mid 140.744702 -288.102571)
		(end 141.027658 -288.178748)
		(width 0.0889)
		(layer "In2.Cu")
		(net "M_I_CPU1_SB_DQ<21>")
	)
	(arc
		(start 141.027658 -288.178748)
		(mid 141.209909 -288.229132)
		(end 141.393418 -288.183574)
		(width 0.0889)
		(layer "In2.Cu")
		(net "M_I_CPU1_SB_DQ<21>")
	)
	(arc
		(start 133.516116 -288.183574)
		(mid 133.699624 -288.229099)
		(end 133.881876 -288.178748)
		(width 0.0889)
		(layer "In2.Cu")
		(net "M_I_CPU1_SB_DQ<21>")
	)
	(arc
		(start 138.581892 -288.178748)
		(mid 138.864848 -288.102571)
		(end 139.147804 -288.178748)
		(width 0.0889)
		(layer "In2.Cu")
		(net "M_I_CPU1_SB_DQ<21>")
	)
	(arc
		(start 131.627626 -288.178748)
		(mid 131.809877 -288.229132)
		(end 131.993386 -288.183574)
		(width 0.0889)
		(layer "In2.Cu")
		(net "M_I_CPU1_SB_DQ<21>")
	)
	(arc
		(start 135.387588 -288.178748)
		(mid 135.569839 -288.229132)
		(end 135.753348 -288.183574)
		(width 0.0889)
		(layer "In2.Cu")
		(net "M_I_CPU1_SB_DQ<21>")
	)
	(arc
		(start 141.4018 -288.178748)
		(mid 141.684756 -288.102571)
		(end 141.967712 -288.178748)
		(width 0.0889)
		(layer "In2.Cu")
		(net "M_I_CPU1_SB_DQ<21>")
	)
	(arc
		(start 138.216132 -288.183574)
		(mid 138.39964 -288.229099)
		(end 138.581892 -288.178748)
		(width 0.0889)
		(layer "In2.Cu")
		(net "M_I_CPU1_SB_DQ<21>")
	)
	(arc
		(start 132.941822 -288.178748)
		(mid 133.224778 -288.102571)
		(end 133.507734 -288.178748)
		(width 0.0889)
		(layer "In2.Cu")
		(net "M_I_CPU1_SB_DQ<21>")
	)
	(arc
		(start 135.76173 -288.178748)
		(mid 136.044686 -288.102571)
		(end 136.327642 -288.178748)
		(width 0.0889)
		(layer "In2.Cu")
		(net "M_I_CPU1_SB_DQ<21>")
	)
	(arc
		(start 132.56768 -288.178748)
		(mid 132.749931 -288.229132)
		(end 132.93344 -288.183574)
		(width 0.0889)
		(layer "In2.Cu")
		(net "M_I_CPU1_SB_DQ<21>")
	)
	(arc
		(start 139.147804 -288.178748)
		(mid 139.334748 -288.229037)
		(end 139.521692 -288.178748)
		(width 0.0889)
		(layer "In2.Cu")
		(net "M_I_CPU1_SB_DQ<21>")
	)
	(arc
		(start 129.756154 -288.183574)
		(mid 129.939662 -288.229099)
		(end 130.121914 -288.178748)
		(width 0.0889)
		(layer "In2.Cu")
		(net "M_I_CPU1_SB_DQ<21>")
	)
	(arc
		(start 142.341854 -288.178748)
		(mid 142.62481 -288.102571)
		(end 142.907766 -288.178748)
		(width 0.0889)
		(layer "In2.Cu")
		(net "M_I_CPU1_SB_DQ<21>")
	)
	(arc
		(start 136.327642 -288.178748)
		(mid 136.509893 -288.229132)
		(end 136.693402 -288.183574)
		(width 0.0889)
		(layer "In2.Cu")
		(net "M_I_CPU1_SB_DQ<21>")
	)
	(arc
		(start 137.641838 -288.178748)
		(mid 137.924794 -288.102571)
		(end 138.20775 -288.178748)
		(width 0.0889)
		(layer "In2.Cu")
		(net "M_I_CPU1_SB_DQ<21>")
	)
	(arc
		(start 139.521692 -288.178748)
		(mid 139.804648 -288.102571)
		(end 140.087604 -288.178748)
		(width 0.0889)
		(layer "In2.Cu")
		(net "M_I_CPU1_SB_DQ<21>")
	)
	(arc
		(start 131.061714 -288.178748)
		(mid 131.34467 -288.102571)
		(end 131.627626 -288.178748)
		(width 0.0889)
		(layer "In2.Cu")
		(net "M_I_CPU1_SB_DQ<21>")
	)
	(arc
		(start 137.276078 -288.183574)
		(mid 137.459586 -288.229099)
		(end 137.641838 -288.178748)
		(width 0.0889)
		(layer "In2.Cu")
		(net "M_I_CPU1_SB_DQ<21>")
	)
	(arc
		(start 144.220438 -288.178748)
		(mid 144.447611 -288.084778)
		(end 144.691354 -288.052764)
		(width 0.0889)
		(layer "In2.Cu")
		(net "M_I_CPU1_SB_DQ<21>")
	)
	(arc
		(start 128.304544 -288.147252)
		(mid 128.559866 -288.103552)
		(end 128.807718 -288.178748)
		(width 0.0889)
		(layer "In2.Cu")
		(net "M_I_CPU1_SB_DQ<21>")
	)
	(arc
		(start 140.087604 -288.178748)
		(mid 140.269855 -288.229132)
		(end 140.453364 -288.183574)
		(width 0.0889)
		(layer "In2.Cu")
		(net "M_I_CPU1_SB_DQ<21>")
	)
	(arc
		(start 141.976094 -288.183574)
		(mid 142.159602 -288.229099)
		(end 142.341854 -288.178748)
		(width 0.0889)
		(layer "In2.Cu")
		(net "M_I_CPU1_SB_DQ<21>")
	)
	(arc
		(start 136.701784 -288.178748)
		(mid 136.98474 -288.102571)
		(end 137.267696 -288.178748)
		(width 0.0889)
		(layer "In2.Cu")
		(net "M_I_CPU1_SB_DQ<21>")
	)
	(arc
		(start 142.907766 -288.178748)
		(mid 143.09471 -288.229037)
		(end 143.281654 -288.178748)
		(width 0.0889)
		(layer "In2.Cu")
		(net "M_I_CPU1_SB_DQ<21>")
	)
	(arc
		(start 130.687826 -288.178748)
		(mid 130.87477 -288.229037)
		(end 131.061714 -288.178748)
		(width 0.0889)
		(layer "In2.Cu")
		(net "M_I_CPU1_SB_DQ<21>")
	)
	(arc
		(start 143.281654 -288.178748)
		(mid 143.56461 -288.102571)
		(end 143.847566 -288.178748)
		(width 0.0889)
		(layer "In2.Cu")
		(net "M_I_CPU1_SB_DQ<21>")
	)
	(arc
		(start 130.121914 -288.178748)
		(mid 130.40487 -288.102571)
		(end 130.687826 -288.178748)
		(width 0.0889)
		(layer "In2.Cu")
		(net "M_I_CPU1_SB_DQ<21>")
	)
	(arc
		(start 143.847566 -288.178748)
		(mid 144.022237 -288.228835)
		(end 144.199864 -288.190432)
		(width 0.0889)
		(layer "In2.Cu")
		(net "M_I_CPU1_SB_DQ<21>")
	)
	(arc
		(start 134.821676 -288.178748)
		(mid 135.104632 -288.102571)
		(end 135.387588 -288.178748)
		(width 0.0889)
		(layer "In2.Cu")
		(net "M_I_CPU1_SB_DQ<21>")
	)
	(arc
		(start 132.001768 -288.178748)
		(mid 132.284724 -288.102571)
		(end 132.56768 -288.178748)
		(width 0.0889)
		(layer "In2.Cu")
		(net "M_I_CPU1_SB_DQ<21>")
	)
	(arc
		(start 134.447788 -288.178748)
		(mid 134.634732 -288.229037)
		(end 134.821676 -288.178748)
		(width 0.0889)
		(layer "In2.Cu")
		(net "M_I_CPU1_SB_DQ<21>")
	)
	(arc
		(start 128.8161 -288.183574)
		(mid 128.999608 -288.229099)
		(end 129.18186 -288.178748)
		(width 0.0889)
		(layer "In2.Cu")
		(net "M_I_CPU1_SB_DQ<21>")
	)
	(segment
		(start 128.997964 -286.780478)
		(end 129.464816 -287.046162)
		(width 0.10668)
		(layer "F.Cu")
		(net "M_I_CPU1_SB_DQ<20>")
	)
	(segment
		(start 174.627286 -305.719988)
		(end 181.575456 -305.719988)
		(width 0.14478)
		(layer "In2.Cu")
		(net "M_I_CPU1_SB_DQ<20>")
	)
	(segment
		(start 181.737 -305.881532)
		(end 181.737 -306.332382)
		(width 0.14478)
		(layer "In2.Cu")
		(net "M_I_CPU1_SB_DQ<20>")
	)
	(segment
		(start 181.737 -306.332382)
		(end 181.898544 -306.493926)
		(width 0.14478)
		(layer "In2.Cu")
		(net "M_I_CPU1_SB_DQ<20>")
	)
	(segment
		(start 142.803372 -287.373568)
		(end 142.811754 -287.368742)
		(width 0.0889)
		(layer "In2.Cu")
		(net "M_I_CPU1_SB_DQ<20>")
	)
	(segment
		(start 147.461732 -289.79241)
		(end 147.987766 -290.318444)
		(width 0.14478)
		(layer "In2.Cu")
		(net "M_I_CPU1_SB_DQ<20>")
	)
	(segment
		(start 130.583432 -287.373568)
		(end 130.591814 -287.368742)
		(width 0.0889)
		(layer "In2.Cu")
		(net "M_I_CPU1_SB_DQ<20>")
	)
	(segment
		(start 134.917688 -287.368742)
		(end 134.92607 -287.373568)
		(width 0.0889)
		(layer "In2.Cu")
		(net "M_I_CPU1_SB_DQ<20>")
	)
	(segment
		(start 166.14521 -306.570126)
		(end 166.995348 -305.719988)
		(width 0.14478)
		(layer "In2.Cu")
		(net "M_I_CPU1_SB_DQ<20>")
	)
	(segment
		(start 173.777148 -306.570126)
		(end 174.627286 -305.719988)
		(width 0.14478)
		(layer "In2.Cu")
		(net "M_I_CPU1_SB_DQ<20>")
	)
	(segment
		(start 139.617704 -287.368742)
		(end 139.626086 -287.373568)
		(width 0.0889)
		(layer "In2.Cu")
		(net "M_I_CPU1_SB_DQ<20>")
	)
	(segment
		(start 169.918126 -305.720242)
		(end 170.76801 -306.570126)
		(width 0.14478)
		(layer "In2.Cu")
		(net "M_I_CPU1_SB_DQ<20>")
	)
	(segment
		(start 166.995348 -305.719988)
		(end 169.917364 -305.719988)
		(width 0.14478)
		(layer "In2.Cu")
		(net "M_I_CPU1_SB_DQ<20>")
	)
	(segment
		(start 182.449978 -305.719988)
		(end 183.200802 -305.719988)
		(width 0.14478)
		(layer "In2.Cu")
		(net "M_I_CPU1_SB_DQ<20>")
	)
	(segment
		(start 146.585686 -289.282378)
		(end 146.874992 -289.571684)
		(width 0.0889)
		(layer "In2.Cu")
		(net "M_I_CPU1_SB_DQ<20>")
	)
	(segment
		(start 129.61874 -287.311592)
		(end 129.714752 -287.336992)
		(width 0.0889)
		(layer "In2.Cu")
		(net "M_I_CPU1_SB_DQ<20>")
	)
	(segment
		(start 134.343394 -287.373568)
		(end 134.351776 -287.368742)
		(width 0.0889)
		(layer "In2.Cu")
		(net "M_I_CPU1_SB_DQ<20>")
	)
	(segment
		(start 147.241006 -289.571684)
		(end 147.461732 -289.79241)
		(width 0.0889)
		(layer "In2.Cu")
		(net "M_I_CPU1_SB_DQ<20>")
	)
	(segment
		(start 140.557758 -287.368742)
		(end 140.56614 -287.373568)
		(width 0.0889)
		(layer "In2.Cu")
		(net "M_I_CPU1_SB_DQ<20>")
	)
	(segment
		(start 183.200802 -305.719988)
		(end 183.616092 -306.135278)
		(width 0.14478)
		(layer "In2.Cu")
		(net "M_I_CPU1_SB_DQ<20>")
	)
	(segment
		(start 169.917364 -305.719988)
		(end 169.918126 -305.720242)
		(width 0.14478)
		(layer "In2.Cu")
		(net "M_I_CPU1_SB_DQ<20>")
	)
	(segment
		(start 163.03879 -306.570126)
		(end 166.14521 -306.570126)
		(width 0.14478)
		(layer "In2.Cu")
		(net "M_I_CPU1_SB_DQ<20>")
	)
	(segment
		(start 147.987766 -290.318444)
		(end 148.97989 -292.713156)
		(width 0.14478)
		(layer "In2.Cu")
		(net "M_I_CPU1_SB_DQ<20>")
	)
	(segment
		(start 181.575456 -305.719988)
		(end 181.737 -305.881532)
		(width 0.14478)
		(layer "In2.Cu")
		(net "M_I_CPU1_SB_DQ<20>")
	)
	(segment
		(start 155.970224 -299.70349)
		(end 155.970224 -301.279306)
		(width 0.14478)
		(layer "In2.Cu")
		(net "M_I_CPU1_SB_DQ<20>")
	)
	(segment
		(start 131.157726 -287.368742)
		(end 131.166108 -287.373568)
		(width 0.0889)
		(layer "In2.Cu")
		(net "M_I_CPU1_SB_DQ<20>")
	)
	(segment
		(start 138.103356 -287.373568)
		(end 138.111738 -287.368742)
		(width 0.0889)
		(layer "In2.Cu")
		(net "M_I_CPU1_SB_DQ<20>")
	)
	(segment
		(start 160.003998 -305.31308)
		(end 163.03879 -306.570126)
		(width 0.14478)
		(layer "In2.Cu")
		(net "M_I_CPU1_SB_DQ<20>")
	)
	(segment
		(start 139.04341 -287.373568)
		(end 139.051792 -287.368742)
		(width 0.0889)
		(layer "In2.Cu")
		(net "M_I_CPU1_SB_DQ<20>")
	)
	(segment
		(start 143.377666 -287.368742)
		(end 143.386048 -287.373568)
		(width 0.0889)
		(layer "In2.Cu")
		(net "M_I_CPU1_SB_DQ<20>")
	)
	(segment
		(start 182.12689 -306.493926)
		(end 182.288434 -306.332382)
		(width 0.14478)
		(layer "In2.Cu")
		(net "M_I_CPU1_SB_DQ<20>")
	)
	(segment
		(start 182.288434 -306.332382)
		(end 182.288434 -305.881532)
		(width 0.14478)
		(layer "In2.Cu")
		(net "M_I_CPU1_SB_DQ<20>")
	)
	(segment
		(start 148.97989 -292.713156)
		(end 155.970224 -299.70349)
		(width 0.14478)
		(layer "In2.Cu")
		(net "M_I_CPU1_SB_DQ<20>")
	)
	(segment
		(start 132.09778 -287.368742)
		(end 132.106162 -287.373568)
		(width 0.0889)
		(layer "In2.Cu")
		(net "M_I_CPU1_SB_DQ<20>")
	)
	(segment
		(start 182.288434 -305.881532)
		(end 182.449978 -305.719988)
		(width 0.14478)
		(layer "In2.Cu")
		(net "M_I_CPU1_SB_DQ<20>")
	)
	(segment
		(start 144.64919 -287.458404)
		(end 145.662396 -287.458404)
		(width 0.0889)
		(layer "In2.Cu")
		(net "M_I_CPU1_SB_DQ<20>")
	)
	(segment
		(start 143.751808 -287.368742)
		(end 143.76654 -287.360106)
		(width 0.0889)
		(layer "In2.Cu")
		(net "M_I_CPU1_SB_DQ<20>")
	)
	(segment
		(start 181.898544 -306.493926)
		(end 182.12689 -306.493926)
		(width 0.14478)
		(layer "In2.Cu")
		(net "M_I_CPU1_SB_DQ<20>")
	)
	(segment
		(start 146.874992 -289.571684)
		(end 147.241006 -289.571684)
		(width 0.0889)
		(layer "In2.Cu")
		(net "M_I_CPU1_SB_DQ<20>")
	)
	(segment
		(start 135.857742 -287.368742)
		(end 135.866124 -287.373568)
		(width 0.0889)
		(layer "In2.Cu")
		(net "M_I_CPU1_SB_DQ<20>")
	)
	(segment
		(start 155.970224 -301.279306)
		(end 160.003998 -305.31308)
		(width 0.14478)
		(layer "In2.Cu")
		(net "M_I_CPU1_SB_DQ<20>")
	)
	(segment
		(start 170.76801 -306.570126)
		(end 173.777148 -306.570126)
		(width 0.14478)
		(layer "In2.Cu")
		(net "M_I_CPU1_SB_DQ<20>")
	)
	(segment
		(start 145.74266 -287.491678)
		(end 146.585686 -288.334704)
		(width 0.0889)
		(layer "In2.Cu")
		(net "M_I_CPU1_SB_DQ<20>")
	)
	(segment
		(start 129.464816 -287.046162)
		(end 129.61874 -287.311592)
		(width 0.0889)
		(layer "In2.Cu")
		(net "M_I_CPU1_SB_DQ<20>")
	)
	(segment
		(start 146.585686 -288.334704)
		(end 146.585686 -289.282378)
		(width 0.0889)
		(layer "In2.Cu")
		(net "M_I_CPU1_SB_DQ<20>")
	)
	(arc
		(start 129.714752 -287.336992)
		(mid 129.96996 -287.293535)
		(end 130.217672 -287.368742)
		(width 0.0889)
		(layer "In2.Cu")
		(net "M_I_CPU1_SB_DQ<20>")
	)
	(arc
		(start 137.737596 -287.368742)
		(mid 137.919847 -287.419092)
		(end 138.103356 -287.373568)
		(width 0.0889)
		(layer "In2.Cu")
		(net "M_I_CPU1_SB_DQ<20>")
	)
	(arc
		(start 141.497812 -287.368742)
		(mid 141.684756 -287.418997)
		(end 141.8717 -287.368742)
		(width 0.0889)
		(layer "In2.Cu")
		(net "M_I_CPU1_SB_DQ<20>")
	)
	(arc
		(start 135.866124 -287.373568)
		(mid 136.049632 -287.419062)
		(end 136.231884 -287.368742)
		(width 0.0889)
		(layer "In2.Cu")
		(net "M_I_CPU1_SB_DQ<20>")
	)
	(arc
		(start 138.111738 -287.368742)
		(mid 138.394694 -287.292599)
		(end 138.67765 -287.368742)
		(width 0.0889)
		(layer "In2.Cu")
		(net "M_I_CPU1_SB_DQ<20>")
	)
	(arc
		(start 134.92607 -287.373568)
		(mid 135.109578 -287.419062)
		(end 135.29183 -287.368742)
		(width 0.0889)
		(layer "In2.Cu")
		(net "M_I_CPU1_SB_DQ<20>")
	)
	(arc
		(start 136.231884 -287.368742)
		(mid 136.51484 -287.292599)
		(end 136.797796 -287.368742)
		(width 0.0889)
		(layer "In2.Cu")
		(net "M_I_CPU1_SB_DQ<20>")
	)
	(arc
		(start 142.811754 -287.368742)
		(mid 143.09471 -287.292599)
		(end 143.377666 -287.368742)
		(width 0.0889)
		(layer "In2.Cu")
		(net "M_I_CPU1_SB_DQ<20>")
	)
	(arc
		(start 135.29183 -287.368742)
		(mid 135.574786 -287.292599)
		(end 135.857742 -287.368742)
		(width 0.0889)
		(layer "In2.Cu")
		(net "M_I_CPU1_SB_DQ<20>")
	)
	(arc
		(start 145.662396 -287.458404)
		(mid 145.705831 -287.467062)
		(end 145.74266 -287.491678)
		(width 0.0889)
		(layer "In2.Cu")
		(net "M_I_CPU1_SB_DQ<20>")
	)
	(arc
		(start 139.626086 -287.373568)
		(mid 139.809594 -287.419062)
		(end 139.991846 -287.368742)
		(width 0.0889)
		(layer "In2.Cu")
		(net "M_I_CPU1_SB_DQ<20>")
	)
	(arc
		(start 134.351776 -287.368742)
		(mid 134.634732 -287.292599)
		(end 134.917688 -287.368742)
		(width 0.0889)
		(layer "In2.Cu")
		(net "M_I_CPU1_SB_DQ<20>")
	)
	(arc
		(start 130.217672 -287.368742)
		(mid 130.399923 -287.419092)
		(end 130.583432 -287.373568)
		(width 0.0889)
		(layer "In2.Cu")
		(net "M_I_CPU1_SB_DQ<20>")
	)
	(arc
		(start 137.171684 -287.368742)
		(mid 137.45464 -287.292599)
		(end 137.737596 -287.368742)
		(width 0.0889)
		(layer "In2.Cu")
		(net "M_I_CPU1_SB_DQ<20>")
	)
	(arc
		(start 142.437612 -287.368742)
		(mid 142.619863 -287.419092)
		(end 142.803372 -287.373568)
		(width 0.0889)
		(layer "In2.Cu")
		(net "M_I_CPU1_SB_DQ<20>")
	)
	(arc
		(start 131.166108 -287.373568)
		(mid 131.349616 -287.419062)
		(end 131.531868 -287.368742)
		(width 0.0889)
		(layer "In2.Cu")
		(net "M_I_CPU1_SB_DQ<20>")
	)
	(arc
		(start 130.591814 -287.368742)
		(mid 130.87477 -287.292599)
		(end 131.157726 -287.368742)
		(width 0.0889)
		(layer "In2.Cu")
		(net "M_I_CPU1_SB_DQ<20>")
	)
	(arc
		(start 132.471922 -287.368742)
		(mid 132.754878 -287.292599)
		(end 133.037834 -287.368742)
		(width 0.0889)
		(layer "In2.Cu")
		(net "M_I_CPU1_SB_DQ<20>")
	)
	(arc
		(start 133.977634 -287.368742)
		(mid 134.159885 -287.419092)
		(end 134.343394 -287.373568)
		(width 0.0889)
		(layer "In2.Cu")
		(net "M_I_CPU1_SB_DQ<20>")
	)
	(arc
		(start 139.051792 -287.368742)
		(mid 139.334748 -287.292599)
		(end 139.617704 -287.368742)
		(width 0.0889)
		(layer "In2.Cu")
		(net "M_I_CPU1_SB_DQ<20>")
	)
	(arc
		(start 143.76654 -287.360106)
		(mid 144.043523 -287.292332)
		(end 144.318228 -287.368742)
		(width 0.0889)
		(layer "In2.Cu")
		(net "M_I_CPU1_SB_DQ<20>")
	)
	(arc
		(start 136.797796 -287.368742)
		(mid 136.98474 -287.418997)
		(end 137.171684 -287.368742)
		(width 0.0889)
		(layer "In2.Cu")
		(net "M_I_CPU1_SB_DQ<20>")
	)
	(arc
		(start 140.56614 -287.373568)
		(mid 140.749648 -287.419062)
		(end 140.9319 -287.368742)
		(width 0.0889)
		(layer "In2.Cu")
		(net "M_I_CPU1_SB_DQ<20>")
	)
	(arc
		(start 132.106162 -287.373568)
		(mid 132.28967 -287.419062)
		(end 132.471922 -287.368742)
		(width 0.0889)
		(layer "In2.Cu")
		(net "M_I_CPU1_SB_DQ<20>")
	)
	(arc
		(start 139.991846 -287.368742)
		(mid 140.274802 -287.292599)
		(end 140.557758 -287.368742)
		(width 0.0889)
		(layer "In2.Cu")
		(net "M_I_CPU1_SB_DQ<20>")
	)
	(arc
		(start 140.9319 -287.368742)
		(mid 141.214856 -287.292599)
		(end 141.497812 -287.368742)
		(width 0.0889)
		(layer "In2.Cu")
		(net "M_I_CPU1_SB_DQ<20>")
	)
	(arc
		(start 131.531868 -287.368742)
		(mid 131.814824 -287.292599)
		(end 132.09778 -287.368742)
		(width 0.0889)
		(layer "In2.Cu")
		(net "M_I_CPU1_SB_DQ<20>")
	)
	(arc
		(start 144.318228 -287.368742)
		(mid 144.477751 -287.435549)
		(end 144.64919 -287.458404)
		(width 0.0889)
		(layer "In2.Cu")
		(net "M_I_CPU1_SB_DQ<20>")
	)
	(arc
		(start 133.037834 -287.368742)
		(mid 133.224778 -287.418997)
		(end 133.411722 -287.368742)
		(width 0.0889)
		(layer "In2.Cu")
		(net "M_I_CPU1_SB_DQ<20>")
	)
	(arc
		(start 133.411722 -287.368742)
		(mid 133.694678 -287.292599)
		(end 133.977634 -287.368742)
		(width 0.0889)
		(layer "In2.Cu")
		(net "M_I_CPU1_SB_DQ<20>")
	)
	(arc
		(start 138.67765 -287.368742)
		(mid 138.859901 -287.419092)
		(end 139.04341 -287.373568)
		(width 0.0889)
		(layer "In2.Cu")
		(net "M_I_CPU1_SB_DQ<20>")
	)
	(arc
		(start 143.386048 -287.373568)
		(mid 143.569556 -287.419062)
		(end 143.751808 -287.368742)
		(width 0.0889)
		(layer "In2.Cu")
		(net "M_I_CPU1_SB_DQ<20>")
	)
	(arc
		(start 141.8717 -287.368742)
		(mid 142.154656 -287.292599)
		(end 142.437612 -287.368742)
		(width 0.0889)
		(layer "In2.Cu")
		(net "M_I_CPU1_SB_DQ<20>")
	)
	(segment
		(start 127.58801 -274.630388)
		(end 128.054862 -274.896326)
		(width 0.10668)
		(layer "F.Cu")
		(net "M_I_CPU1_SB_DQ<1>")
	)
	(segment
		(start 170.921172 -283.610304)
		(end 172.988478 -283.610304)
		(width 0.14478)
		(layer "In2.Cu")
		(net "M_I_CPU1_SB_DQ<1>")
	)
	(segment
		(start 153.042112 -273.849084)
		(end 158.222442 -279.029414)
		(width 0.14478)
		(layer "In2.Cu")
		(net "M_I_CPU1_SB_DQ<1>")
	)
	(segment
		(start 145.15973 -275.218906)
		(end 145.754598 -274.859496)
		(width 0.0889)
		(layer "In2.Cu")
		(net "M_I_CPU1_SB_DQ<1>")
	)
	(segment
		(start 128.208786 -275.161756)
		(end 128.304798 -275.187156)
		(width 0.0889)
		(layer "In2.Cu")
		(net "M_I_CPU1_SB_DQ<1>")
	)
	(segment
		(start 148.060918 -273.849084)
		(end 153.042112 -273.849084)
		(width 0.14478)
		(layer "In2.Cu")
		(net "M_I_CPU1_SB_DQ<1>")
	)
	(segment
		(start 170.071288 -282.76042)
		(end 170.921172 -283.610304)
		(width 0.14478)
		(layer "In2.Cu")
		(net "M_I_CPU1_SB_DQ<1>")
	)
	(segment
		(start 146.7485 -274.009104)
		(end 147.266152 -274.009104)
		(width 0.0889)
		(layer "In2.Cu")
		(net "M_I_CPU1_SB_DQ<1>")
	)
	(segment
		(start 144.220438 -275.218652)
		(end 144.2466 -275.203666)
		(width 0.0889)
		(layer "In2.Cu")
		(net "M_I_CPU1_SB_DQ<1>")
	)
	(segment
		(start 167.82288 -282.76042)
		(end 170.071288 -282.76042)
		(width 0.14478)
		(layer "In2.Cu")
		(net "M_I_CPU1_SB_DQ<1>")
	)
	(segment
		(start 133.507734 -275.218906)
		(end 133.516116 -275.223732)
		(width 0.0889)
		(layer "In2.Cu")
		(net "M_I_CPU1_SB_DQ<1>")
	)
	(segment
		(start 175.040798 -282.76042)
		(end 183.19115 -282.76042)
		(width 0.14478)
		(layer "In2.Cu")
		(net "M_I_CPU1_SB_DQ<1>")
	)
	(segment
		(start 147.426172 -273.849084)
		(end 148.060918 -273.849084)
		(width 0.0889)
		(layer "In2.Cu")
		(net "M_I_CPU1_SB_DQ<1>")
	)
	(segment
		(start 158.222442 -279.029414)
		(end 159.066738 -279.029414)
		(width 0.14478)
		(layer "In2.Cu")
		(net "M_I_CPU1_SB_DQ<1>")
	)
	(segment
		(start 145.754598 -274.859496)
		(end 146.037554 -274.72005)
		(width 0.0889)
		(layer "In2.Cu")
		(net "M_I_CPU1_SB_DQ<1>")
	)
	(segment
		(start 163.647628 -283.610304)
		(end 165.771576 -283.610304)
		(width 0.14478)
		(layer "In2.Cu")
		(net "M_I_CPU1_SB_DQ<1>")
	)
	(segment
		(start 135.753348 -275.223732)
		(end 135.76173 -275.218906)
		(width 0.0889)
		(layer "In2.Cu")
		(net "M_I_CPU1_SB_DQ<1>")
	)
	(segment
		(start 183.19115 -282.76042)
		(end 183.616092 -283.185362)
		(width 0.14478)
		(layer "In2.Cu")
		(net "M_I_CPU1_SB_DQ<1>")
	)
	(segment
		(start 136.693402 -275.223732)
		(end 136.701784 -275.218906)
		(width 0.0889)
		(layer "In2.Cu")
		(net "M_I_CPU1_SB_DQ<1>")
	)
	(segment
		(start 132.93344 -275.223732)
		(end 132.941822 -275.218906)
		(width 0.0889)
		(layer "In2.Cu")
		(net "M_I_CPU1_SB_DQ<1>")
	)
	(segment
		(start 140.453364 -275.223732)
		(end 140.461746 -275.218906)
		(width 0.0889)
		(layer "In2.Cu")
		(net "M_I_CPU1_SB_DQ<1>")
	)
	(segment
		(start 172.988478 -283.610304)
		(end 175.040798 -282.76042)
		(width 0.14478)
		(layer "In2.Cu")
		(net "M_I_CPU1_SB_DQ<1>")
	)
	(segment
		(start 137.267696 -275.218906)
		(end 137.276078 -275.223732)
		(width 0.0889)
		(layer "In2.Cu")
		(net "M_I_CPU1_SB_DQ<1>")
	)
	(segment
		(start 128.054862 -274.896326)
		(end 128.208786 -275.161756)
		(width 0.0889)
		(layer "In2.Cu")
		(net "M_I_CPU1_SB_DQ<1>")
	)
	(segment
		(start 159.066738 -279.029414)
		(end 163.647628 -283.610304)
		(width 0.14478)
		(layer "In2.Cu")
		(net "M_I_CPU1_SB_DQ<1>")
	)
	(segment
		(start 165.771576 -283.610304)
		(end 167.82288 -282.76042)
		(width 0.14478)
		(layer "In2.Cu")
		(net "M_I_CPU1_SB_DQ<1>")
	)
	(segment
		(start 144.784318 -275.218906)
		(end 144.804892 -275.230844)
		(width 0.0889)
		(layer "In2.Cu")
		(net "M_I_CPU1_SB_DQ<1>")
	)
	(segment
		(start 146.037554 -274.72005)
		(end 146.7485 -274.009104)
		(width 0.0889)
		(layer "In2.Cu")
		(net "M_I_CPU1_SB_DQ<1>")
	)
	(segment
		(start 141.967712 -275.218906)
		(end 141.976094 -275.223732)
		(width 0.0889)
		(layer "In2.Cu")
		(net "M_I_CPU1_SB_DQ<1>")
	)
	(segment
		(start 147.266152 -274.009104)
		(end 147.426172 -273.849084)
		(width 0.0889)
		(layer "In2.Cu")
		(net "M_I_CPU1_SB_DQ<1>")
	)
	(segment
		(start 138.20775 -275.218906)
		(end 138.216132 -275.223732)
		(width 0.0889)
		(layer "In2.Cu")
		(net "M_I_CPU1_SB_DQ<1>")
	)
	(segment
		(start 128.807718 -275.218906)
		(end 128.8161 -275.223732)
		(width 0.0889)
		(layer "In2.Cu")
		(net "M_I_CPU1_SB_DQ<1>")
	)
	(segment
		(start 129.747772 -275.218906)
		(end 129.756154 -275.223732)
		(width 0.0889)
		(layer "In2.Cu")
		(net "M_I_CPU1_SB_DQ<1>")
	)
	(segment
		(start 131.993386 -275.223732)
		(end 132.001768 -275.218906)
		(width 0.0889)
		(layer "In2.Cu")
		(net "M_I_CPU1_SB_DQ<1>")
	)
	(segment
		(start 144.19707 -275.232114)
		(end 144.220438 -275.218652)
		(width 0.0889)
		(layer "In2.Cu")
		(net "M_I_CPU1_SB_DQ<1>")
	)
	(segment
		(start 141.393418 -275.223732)
		(end 141.4018 -275.218906)
		(width 0.0889)
		(layer "In2.Cu")
		(net "M_I_CPU1_SB_DQ<1>")
	)
	(arc
		(start 138.581892 -275.218906)
		(mid 138.864848 -275.142729)
		(end 139.147804 -275.218906)
		(width 0.0889)
		(layer "In2.Cu")
		(net "M_I_CPU1_SB_DQ<1>")
	)
	(arc
		(start 143.281654 -275.218906)
		(mid 143.56461 -275.142729)
		(end 143.847566 -275.218906)
		(width 0.0889)
		(layer "In2.Cu")
		(net "M_I_CPU1_SB_DQ<1>")
	)
	(arc
		(start 128.8161 -275.223732)
		(mid 128.999608 -275.269226)
		(end 129.18186 -275.218906)
		(width 0.0889)
		(layer "In2.Cu")
		(net "M_I_CPU1_SB_DQ<1>")
	)
	(arc
		(start 139.147804 -275.218906)
		(mid 139.334748 -275.269161)
		(end 139.521692 -275.218906)
		(width 0.0889)
		(layer "In2.Cu")
		(net "M_I_CPU1_SB_DQ<1>")
	)
	(arc
		(start 141.976094 -275.223732)
		(mid 142.159602 -275.269226)
		(end 142.341854 -275.218906)
		(width 0.0889)
		(layer "In2.Cu")
		(net "M_I_CPU1_SB_DQ<1>")
	)
	(arc
		(start 132.001768 -275.218906)
		(mid 132.284724 -275.142729)
		(end 132.56768 -275.218906)
		(width 0.0889)
		(layer "In2.Cu")
		(net "M_I_CPU1_SB_DQ<1>")
	)
	(arc
		(start 130.121914 -275.218906)
		(mid 130.40487 -275.142729)
		(end 130.687826 -275.218906)
		(width 0.0889)
		(layer "In2.Cu")
		(net "M_I_CPU1_SB_DQ<1>")
	)
	(arc
		(start 133.516116 -275.223732)
		(mid 133.699624 -275.269226)
		(end 133.881876 -275.218906)
		(width 0.0889)
		(layer "In2.Cu")
		(net "M_I_CPU1_SB_DQ<1>")
	)
	(arc
		(start 138.216132 -275.223732)
		(mid 138.39964 -275.269226)
		(end 138.581892 -275.218906)
		(width 0.0889)
		(layer "In2.Cu")
		(net "M_I_CPU1_SB_DQ<1>")
	)
	(arc
		(start 139.521692 -275.218906)
		(mid 139.804648 -275.142729)
		(end 140.087604 -275.218906)
		(width 0.0889)
		(layer "In2.Cu")
		(net "M_I_CPU1_SB_DQ<1>")
	)
	(arc
		(start 144.2466 -275.203666)
		(mid 144.517386 -275.14302)
		(end 144.784318 -275.218906)
		(width 0.0889)
		(layer "In2.Cu")
		(net "M_I_CPU1_SB_DQ<1>")
	)
	(arc
		(start 135.76173 -275.218906)
		(mid 136.044686 -275.142729)
		(end 136.327642 -275.218906)
		(width 0.0889)
		(layer "In2.Cu")
		(net "M_I_CPU1_SB_DQ<1>")
	)
	(arc
		(start 134.447788 -275.218906)
		(mid 134.634732 -275.269161)
		(end 134.821676 -275.218906)
		(width 0.0889)
		(layer "In2.Cu")
		(net "M_I_CPU1_SB_DQ<1>")
	)
	(arc
		(start 129.756154 -275.223732)
		(mid 129.939662 -275.269226)
		(end 130.121914 -275.218906)
		(width 0.0889)
		(layer "In2.Cu")
		(net "M_I_CPU1_SB_DQ<1>")
	)
	(arc
		(start 129.18186 -275.218906)
		(mid 129.464816 -275.142729)
		(end 129.747772 -275.218906)
		(width 0.0889)
		(layer "In2.Cu")
		(net "M_I_CPU1_SB_DQ<1>")
	)
	(arc
		(start 140.461746 -275.218906)
		(mid 140.744702 -275.142729)
		(end 141.027658 -275.218906)
		(width 0.0889)
		(layer "In2.Cu")
		(net "M_I_CPU1_SB_DQ<1>")
	)
	(arc
		(start 142.341854 -275.218906)
		(mid 142.62481 -275.142729)
		(end 142.907766 -275.218906)
		(width 0.0889)
		(layer "In2.Cu")
		(net "M_I_CPU1_SB_DQ<1>")
	)
	(arc
		(start 132.56768 -275.218906)
		(mid 132.749931 -275.269256)
		(end 132.93344 -275.223732)
		(width 0.0889)
		(layer "In2.Cu")
		(net "M_I_CPU1_SB_DQ<1>")
	)
	(arc
		(start 128.304798 -275.187156)
		(mid 128.560006 -275.143679)
		(end 128.807718 -275.218906)
		(width 0.0889)
		(layer "In2.Cu")
		(net "M_I_CPU1_SB_DQ<1>")
	)
	(arc
		(start 142.907766 -275.218906)
		(mid 143.09471 -275.269161)
		(end 143.281654 -275.218906)
		(width 0.0889)
		(layer "In2.Cu")
		(net "M_I_CPU1_SB_DQ<1>")
	)
	(arc
		(start 144.804892 -275.230844)
		(mid 144.98382 -275.269721)
		(end 145.15973 -275.218906)
		(width 0.0889)
		(layer "In2.Cu")
		(net "M_I_CPU1_SB_DQ<1>")
	)
	(arc
		(start 134.821676 -275.218906)
		(mid 135.104632 -275.142729)
		(end 135.387588 -275.218906)
		(width 0.0889)
		(layer "In2.Cu")
		(net "M_I_CPU1_SB_DQ<1>")
	)
	(arc
		(start 130.687826 -275.218906)
		(mid 130.87477 -275.269161)
		(end 131.061714 -275.218906)
		(width 0.0889)
		(layer "In2.Cu")
		(net "M_I_CPU1_SB_DQ<1>")
	)
	(arc
		(start 131.627626 -275.218906)
		(mid 131.809877 -275.269256)
		(end 131.993386 -275.223732)
		(width 0.0889)
		(layer "In2.Cu")
		(net "M_I_CPU1_SB_DQ<1>")
	)
	(arc
		(start 133.881876 -275.218906)
		(mid 134.164832 -275.142729)
		(end 134.447788 -275.218906)
		(width 0.0889)
		(layer "In2.Cu")
		(net "M_I_CPU1_SB_DQ<1>")
	)
	(arc
		(start 136.701784 -275.218906)
		(mid 136.98474 -275.142729)
		(end 137.267696 -275.218906)
		(width 0.0889)
		(layer "In2.Cu")
		(net "M_I_CPU1_SB_DQ<1>")
	)
	(arc
		(start 137.641838 -275.218906)
		(mid 137.924794 -275.142729)
		(end 138.20775 -275.218906)
		(width 0.0889)
		(layer "In2.Cu")
		(net "M_I_CPU1_SB_DQ<1>")
	)
	(arc
		(start 131.061714 -275.218906)
		(mid 131.34467 -275.142729)
		(end 131.627626 -275.218906)
		(width 0.0889)
		(layer "In2.Cu")
		(net "M_I_CPU1_SB_DQ<1>")
	)
	(arc
		(start 135.387588 -275.218906)
		(mid 135.569839 -275.269256)
		(end 135.753348 -275.223732)
		(width 0.0889)
		(layer "In2.Cu")
		(net "M_I_CPU1_SB_DQ<1>")
	)
	(arc
		(start 137.276078 -275.223732)
		(mid 137.459586 -275.269226)
		(end 137.641838 -275.218906)
		(width 0.0889)
		(layer "In2.Cu")
		(net "M_I_CPU1_SB_DQ<1>")
	)
	(arc
		(start 132.941822 -275.218906)
		(mid 133.224778 -275.142729)
		(end 133.507734 -275.218906)
		(width 0.0889)
		(layer "In2.Cu")
		(net "M_I_CPU1_SB_DQ<1>")
	)
	(arc
		(start 140.087604 -275.218906)
		(mid 140.269855 -275.269256)
		(end 140.453364 -275.223732)
		(width 0.0889)
		(layer "In2.Cu")
		(net "M_I_CPU1_SB_DQ<1>")
	)
	(arc
		(start 136.327642 -275.218906)
		(mid 136.509893 -275.269256)
		(end 136.693402 -275.223732)
		(width 0.0889)
		(layer "In2.Cu")
		(net "M_I_CPU1_SB_DQ<1>")
	)
	(arc
		(start 141.4018 -275.218906)
		(mid 141.684756 -275.142729)
		(end 141.967712 -275.218906)
		(width 0.0889)
		(layer "In2.Cu")
		(net "M_I_CPU1_SB_DQ<1>")
	)
	(arc
		(start 143.847566 -275.218906)
		(mid 144.020674 -275.269022)
		(end 144.19707 -275.232114)
		(width 0.0889)
		(layer "In2.Cu")
		(net "M_I_CPU1_SB_DQ<1>")
	)
	(arc
		(start 141.027658 -275.218906)
		(mid 141.209909 -275.269256)
		(end 141.393418 -275.223732)
		(width 0.0889)
		(layer "In2.Cu")
		(net "M_I_CPU1_SB_DQ<1>")
	)
	(segment
		(start 128.05791 -285.160466)
		(end 128.524762 -285.426404)
		(width 0.10668)
		(layer "F.Cu")
		(net "M_I_CPU1_SB_DQ<19>")
	)
	(segment
		(start 162.4203 -302.09363)
		(end 162.581844 -302.255174)
		(width 0.14478)
		(layer "In2.Cu")
		(net "M_I_CPU1_SB_DQ<19>")
	)
	(segment
		(start 162.399218 -302.6664)
		(end 162.399218 -302.895)
		(width 0.14478)
		(layer "In2.Cu")
		(net "M_I_CPU1_SB_DQ<19>")
	)
	(segment
		(start 173.550072 -302.87468)
		(end 173.700948 -302.511206)
		(width 0.14478)
		(layer "In2.Cu")
		(net "M_I_CPU1_SB_DQ<19>")
	)
	(segment
		(start 143.377666 -285.103824)
		(end 143.386048 -285.098998)
		(width 0.0889)
		(layer "In2.Cu")
		(net "M_I_CPU1_SB_DQ<19>")
	)
	(segment
		(start 161.801556 -301.703486)
		(end 161.61893 -301.886112)
		(width 0.14478)
		(layer "In2.Cu")
		(net "M_I_CPU1_SB_DQ<19>")
	)
	(segment
		(start 160.24098 -300.14291)
		(end 160.058354 -300.325536)
		(width 0.14478)
		(layer "In2.Cu")
		(net "M_I_CPU1_SB_DQ<19>")
	)
	(segment
		(start 151.322532 -291.818314)
		(end 157.098746 -297.594528)
		(width 0.14478)
		(layer "In2.Cu")
		(net "M_I_CPU1_SB_DQ<19>")
	)
	(segment
		(start 166.834058 -302.30064)
		(end 170.022774 -302.30064)
		(width 0.14478)
		(layer "In2.Cu")
		(net "M_I_CPU1_SB_DQ<19>")
	)
	(segment
		(start 157.738572 -297.411902)
		(end 157.900116 -297.573446)
		(width 0.14478)
		(layer "In2.Cu")
		(net "M_I_CPU1_SB_DQ<19>")
	)
	(segment
		(start 160.859724 -300.533054)
		(end 161.021268 -300.694598)
		(width 0.14478)
		(layer "In2.Cu")
		(net "M_I_CPU1_SB_DQ<19>")
	)
	(segment
		(start 158.497778 -298.76496)
		(end 158.497778 -298.99356)
		(width 0.14478)
		(layer "In2.Cu")
		(net "M_I_CPU1_SB_DQ<19>")
	)
	(segment
		(start 145.673826 -285.104332)
		(end 146.895566 -286.326072)
		(width 0.0889)
		(layer "In2.Cu")
		(net "M_I_CPU1_SB_DQ<19>")
	)
	(segment
		(start 158.29026 -298.19219)
		(end 158.51886 -298.19219)
		(width 0.14478)
		(layer "In2.Cu")
		(net "M_I_CPU1_SB_DQ<19>")
	)
	(segment
		(start 159.460692 -299.134022)
		(end 159.460692 -299.362622)
		(width 0.14478)
		(layer "In2.Cu")
		(net "M_I_CPU1_SB_DQ<19>")
	)
	(segment
		(start 160.631124 -300.533054)
		(end 160.859724 -300.533054)
		(width 0.14478)
		(layer "In2.Cu")
		(net "M_I_CPU1_SB_DQ<19>")
	)
	(segment
		(start 157.098746 -297.594528)
		(end 157.327346 -297.594528)
		(width 0.14478)
		(layer "In2.Cu")
		(net "M_I_CPU1_SB_DQ<19>")
	)
	(segment
		(start 160.24098 -299.91431)
		(end 160.24098 -300.14291)
		(width 0.14478)
		(layer "In2.Cu")
		(net "M_I_CPU1_SB_DQ<19>")
	)
	(segment
		(start 147.93722 -286.938212)
		(end 150.26513 -289.266122)
		(width 0.14478)
		(layer "In2.Cu")
		(net "M_I_CPU1_SB_DQ<19>")
	)
	(segment
		(start 146.895566 -286.326072)
		(end 147.32508 -286.326072)
		(width 0.0889)
		(layer "In2.Cu")
		(net "M_I_CPU1_SB_DQ<19>")
	)
	(segment
		(start 162.009074 -302.276256)
		(end 162.1917 -302.09363)
		(width 0.14478)
		(layer "In2.Cu")
		(net "M_I_CPU1_SB_DQ<19>")
	)
	(segment
		(start 158.107634 -298.374816)
		(end 158.29026 -298.19219)
		(width 0.14478)
		(layer "In2.Cu")
		(net "M_I_CPU1_SB_DQ<19>")
	)
	(segment
		(start 157.327346 -297.594528)
		(end 157.509972 -297.411902)
		(width 0.14478)
		(layer "In2.Cu")
		(net "M_I_CPU1_SB_DQ<19>")
	)
	(segment
		(start 140.557758 -285.103824)
		(end 140.56614 -285.098998)
		(width 0.0889)
		(layer "In2.Cu")
		(net "M_I_CPU1_SB_DQ<19>")
	)
	(segment
		(start 139.04341 -285.098998)
		(end 139.051792 -285.103824)
		(width 0.0889)
		(layer "In2.Cu")
		(net "M_I_CPU1_SB_DQ<19>")
	)
	(segment
		(start 157.879034 -298.374816)
		(end 158.107634 -298.374816)
		(width 0.14478)
		(layer "In2.Cu")
		(net "M_I_CPU1_SB_DQ<19>")
	)
	(segment
		(start 170.71721 -302.588422)
		(end 170.905424 -303.042574)
		(width 0.14478)
		(layer "In2.Cu")
		(net "M_I_CPU1_SB_DQ<19>")
	)
	(segment
		(start 159.299148 -298.972478)
		(end 159.460692 -299.134022)
		(width 0.14478)
		(layer "In2.Cu")
		(net "M_I_CPU1_SB_DQ<19>")
	)
	(segment
		(start 131.157726 -285.103824)
		(end 131.166108 -285.098998)
		(width 0.0889)
		(layer "In2.Cu")
		(net "M_I_CPU1_SB_DQ<19>")
	)
	(segment
		(start 162.654742 -303.150524)
		(end 165.457632 -303.150524)
		(width 0.14478)
		(layer "In2.Cu")
		(net "M_I_CPU1_SB_DQ<19>")
	)
	(segment
		(start 160.838642 -301.334424)
		(end 161.000186 -301.495968)
		(width 0.14478)
		(layer "In2.Cu")
		(net "M_I_CPU1_SB_DQ<19>")
	)
	(segment
		(start 160.079436 -299.752766)
		(end 160.24098 -299.91431)
		(width 0.14478)
		(layer "In2.Cu")
		(net "M_I_CPU1_SB_DQ<19>")
	)
	(segment
		(start 160.219898 -300.71568)
		(end 160.448498 -300.71568)
		(width 0.14478)
		(layer "In2.Cu")
		(net "M_I_CPU1_SB_DQ<19>")
	)
	(segment
		(start 128.370838 -285.160974)
		(end 128.39319 -285.077662)
		(width 0.0889)
		(layer "In2.Cu")
		(net "M_I_CPU1_SB_DQ<19>")
	)
	(segment
		(start 147.32508 -286.326072)
		(end 147.93722 -286.938212)
		(width 0.0889)
		(layer "In2.Cu")
		(net "M_I_CPU1_SB_DQ<19>")
	)
	(segment
		(start 138.103356 -285.098998)
		(end 138.111738 -285.103824)
		(width 0.0889)
		(layer "In2.Cu")
		(net "M_I_CPU1_SB_DQ<19>")
	)
	(segment
		(start 170.022774 -302.30064)
		(end 170.71721 -302.588422)
		(width 0.14478)
		(layer "In2.Cu")
		(net "M_I_CPU1_SB_DQ<19>")
	)
	(segment
		(start 159.278066 -299.773848)
		(end 159.43961 -299.935392)
		(width 0.14478)
		(layer "In2.Cu")
		(net "M_I_CPU1_SB_DQ<19>")
	)
	(segment
		(start 161.780474 -302.276256)
		(end 162.009074 -302.276256)
		(width 0.14478)
		(layer "In2.Cu")
		(net "M_I_CPU1_SB_DQ<19>")
	)
	(segment
		(start 128.524762 -285.426404)
		(end 128.370838 -285.160974)
		(width 0.0889)
		(layer "In2.Cu")
		(net "M_I_CPU1_SB_DQ<19>")
	)
	(segment
		(start 145.373852 -285.059628)
		(end 145.565876 -285.059628)
		(width 0.0889)
		(layer "In2.Cu")
		(net "M_I_CPU1_SB_DQ<19>")
	)
	(segment
		(start 165.457632 -303.150524)
		(end 165.935152 -302.673004)
		(width 0.14478)
		(layer "In2.Cu")
		(net "M_I_CPU1_SB_DQ<19>")
	)
	(segment
		(start 161.640012 -301.313342)
		(end 161.801556 -301.474886)
		(width 0.14478)
		(layer "In2.Cu")
		(net "M_I_CPU1_SB_DQ<19>")
	)
	(segment
		(start 144.289526 -285.119064)
		(end 144.315688 -285.104078)
		(width 0.0889)
		(layer "In2.Cu")
		(net "M_I_CPU1_SB_DQ<19>")
	)
	(segment
		(start 172.884846 -303.150524)
		(end 173.550072 -302.87468)
		(width 0.14478)
		(layer "In2.Cu")
		(net "M_I_CPU1_SB_DQ<19>")
	)
	(segment
		(start 179.08143 -302.30064)
		(end 179.516024 -302.735234)
		(width 0.14478)
		(layer "In2.Cu")
		(net "M_I_CPU1_SB_DQ<19>")
	)
	(segment
		(start 159.070548 -298.972478)
		(end 159.299148 -298.972478)
		(width 0.14478)
		(layer "In2.Cu")
		(net "M_I_CPU1_SB_DQ<19>")
	)
	(segment
		(start 145.565876 -285.059628)
		(end 145.673826 -285.104332)
		(width 0.0889)
		(layer "In2.Cu")
		(net "M_I_CPU1_SB_DQ<19>")
	)
	(segment
		(start 157.71749 -297.984672)
		(end 157.71749 -298.213272)
		(width 0.14478)
		(layer "In2.Cu")
		(net "M_I_CPU1_SB_DQ<19>")
	)
	(segment
		(start 173.700948 -302.511206)
		(end 174.209202 -302.30064)
		(width 0.14478)
		(layer "In2.Cu")
		(net "M_I_CPU1_SB_DQ<19>")
	)
	(segment
		(start 142.803372 -285.098998)
		(end 142.811754 -285.103824)
		(width 0.0889)
		(layer "In2.Cu")
		(net "M_I_CPU1_SB_DQ<19>")
	)
	(segment
		(start 144.315688 -285.104078)
		(end 144.337532 -285.091632)
		(width 0.0889)
		(layer "In2.Cu")
		(net "M_I_CPU1_SB_DQ<19>")
	)
	(segment
		(start 161.801556 -301.474886)
		(end 161.801556 -301.703486)
		(width 0.14478)
		(layer "In2.Cu")
		(net "M_I_CPU1_SB_DQ<19>")
	)
	(segment
		(start 159.850836 -299.752766)
		(end 160.079436 -299.752766)
		(width 0.14478)
		(layer "In2.Cu")
		(net "M_I_CPU1_SB_DQ<19>")
	)
	(segment
		(start 158.680404 -298.582334)
		(end 158.497778 -298.76496)
		(width 0.14478)
		(layer "In2.Cu")
		(net "M_I_CPU1_SB_DQ<19>")
	)
	(segment
		(start 158.497778 -298.99356)
		(end 158.659322 -299.155104)
		(width 0.14478)
		(layer "In2.Cu")
		(net "M_I_CPU1_SB_DQ<19>")
	)
	(segment
		(start 165.935152 -302.673004)
		(end 166.834058 -302.30064)
		(width 0.14478)
		(layer "In2.Cu")
		(net "M_I_CPU1_SB_DQ<19>")
	)
	(segment
		(start 157.71749 -298.213272)
		(end 157.879034 -298.374816)
		(width 0.14478)
		(layer "In2.Cu")
		(net "M_I_CPU1_SB_DQ<19>")
	)
	(segment
		(start 130.583432 -285.098998)
		(end 130.591814 -285.103824)
		(width 0.0889)
		(layer "In2.Cu")
		(net "M_I_CPU1_SB_DQ<19>")
	)
	(segment
		(start 161.61893 -301.886112)
		(end 161.61893 -302.114712)
		(width 0.14478)
		(layer "In2.Cu")
		(net "M_I_CPU1_SB_DQ<19>")
	)
	(segment
		(start 157.509972 -297.411902)
		(end 157.738572 -297.411902)
		(width 0.14478)
		(layer "In2.Cu")
		(net "M_I_CPU1_SB_DQ<19>")
	)
	(segment
		(start 134.917688 -285.103824)
		(end 134.92607 -285.098998)
		(width 0.0889)
		(layer "In2.Cu")
		(net "M_I_CPU1_SB_DQ<19>")
	)
	(segment
		(start 161.000186 -301.495968)
		(end 161.228786 -301.495968)
		(width 0.14478)
		(layer "In2.Cu")
		(net "M_I_CPU1_SB_DQ<19>")
	)
	(segment
		(start 159.278066 -299.545248)
		(end 159.278066 -299.773848)
		(width 0.14478)
		(layer "In2.Cu")
		(net "M_I_CPU1_SB_DQ<19>")
	)
	(segment
		(start 161.411412 -301.313342)
		(end 161.640012 -301.313342)
		(width 0.14478)
		(layer "In2.Cu")
		(net "M_I_CPU1_SB_DQ<19>")
	)
	(segment
		(start 144.688306 -285.103824)
		(end 144.71777 -285.121096)
		(width 0.0889)
		(layer "In2.Cu")
		(net "M_I_CPU1_SB_DQ<19>")
	)
	(segment
		(start 132.09778 -285.103824)
		(end 132.106162 -285.098998)
		(width 0.0889)
		(layer "In2.Cu")
		(net "M_I_CPU1_SB_DQ<19>")
	)
	(segment
		(start 171.166536 -303.150524)
		(end 172.884846 -303.150524)
		(width 0.14478)
		(layer "In2.Cu")
		(net "M_I_CPU1_SB_DQ<19>")
	)
	(segment
		(start 139.617704 -285.103824)
		(end 139.626086 -285.098998)
		(width 0.0889)
		(layer "In2.Cu")
		(net "M_I_CPU1_SB_DQ<19>")
	)
	(segment
		(start 162.399218 -302.895)
		(end 162.654742 -303.150524)
		(width 0.14478)
		(layer "In2.Cu")
		(net "M_I_CPU1_SB_DQ<19>")
	)
	(segment
		(start 157.900116 -297.802046)
		(end 157.71749 -297.984672)
		(width 0.14478)
		(layer "In2.Cu")
		(net "M_I_CPU1_SB_DQ<19>")
	)
	(segment
		(start 160.448498 -300.71568)
		(end 160.631124 -300.533054)
		(width 0.14478)
		(layer "In2.Cu")
		(net "M_I_CPU1_SB_DQ<19>")
	)
	(segment
		(start 158.659322 -299.155104)
		(end 158.887922 -299.155104)
		(width 0.14478)
		(layer "In2.Cu")
		(net "M_I_CPU1_SB_DQ<19>")
	)
	(segment
		(start 161.021268 -300.694598)
		(end 161.021268 -300.923198)
		(width 0.14478)
		(layer "In2.Cu")
		(net "M_I_CPU1_SB_DQ<19>")
	)
	(segment
		(start 159.460692 -299.362622)
		(end 159.278066 -299.545248)
		(width 0.14478)
		(layer "In2.Cu")
		(net "M_I_CPU1_SB_DQ<19>")
	)
	(segment
		(start 135.857742 -285.103824)
		(end 135.866124 -285.098998)
		(width 0.0889)
		(layer "In2.Cu")
		(net "M_I_CPU1_SB_DQ<19>")
	)
	(segment
		(start 129.643378 -285.098998)
		(end 129.65176 -285.103824)
		(width 0.0889)
		(layer "In2.Cu")
		(net "M_I_CPU1_SB_DQ<19>")
	)
	(segment
		(start 158.51886 -298.19219)
		(end 158.680404 -298.353734)
		(width 0.14478)
		(layer "In2.Cu")
		(net "M_I_CPU1_SB_DQ<19>")
	)
	(segment
		(start 174.209202 -302.30064)
		(end 179.08143 -302.30064)
		(width 0.14478)
		(layer "In2.Cu")
		(net "M_I_CPU1_SB_DQ<19>")
	)
	(segment
		(start 170.905424 -303.042574)
		(end 171.166536 -303.150524)
		(width 0.14478)
		(layer "In2.Cu")
		(net "M_I_CPU1_SB_DQ<19>")
	)
	(segment
		(start 158.680404 -298.353734)
		(end 158.680404 -298.582334)
		(width 0.14478)
		(layer "In2.Cu")
		(net "M_I_CPU1_SB_DQ<19>")
	)
	(segment
		(start 162.1917 -302.09363)
		(end 162.4203 -302.09363)
		(width 0.14478)
		(layer "In2.Cu")
		(net "M_I_CPU1_SB_DQ<19>")
	)
	(segment
		(start 159.43961 -299.935392)
		(end 159.66821 -299.935392)
		(width 0.14478)
		(layer "In2.Cu")
		(net "M_I_CPU1_SB_DQ<19>")
	)
	(segment
		(start 162.581844 -302.255174)
		(end 162.581844 -302.483774)
		(width 0.14478)
		(layer "In2.Cu")
		(net "M_I_CPU1_SB_DQ<19>")
	)
	(segment
		(start 159.66821 -299.935392)
		(end 159.850836 -299.752766)
		(width 0.14478)
		(layer "In2.Cu")
		(net "M_I_CPU1_SB_DQ<19>")
	)
	(segment
		(start 160.058354 -300.325536)
		(end 160.058354 -300.554136)
		(width 0.14478)
		(layer "In2.Cu")
		(net "M_I_CPU1_SB_DQ<19>")
	)
	(segment
		(start 160.838642 -301.105824)
		(end 160.838642 -301.334424)
		(width 0.14478)
		(layer "In2.Cu")
		(net "M_I_CPU1_SB_DQ<19>")
	)
	(segment
		(start 161.021268 -300.923198)
		(end 160.838642 -301.105824)
		(width 0.14478)
		(layer "In2.Cu")
		(net "M_I_CPU1_SB_DQ<19>")
	)
	(segment
		(start 161.228786 -301.495968)
		(end 161.411412 -301.313342)
		(width 0.14478)
		(layer "In2.Cu")
		(net "M_I_CPU1_SB_DQ<19>")
	)
	(segment
		(start 158.887922 -299.155104)
		(end 159.070548 -298.972478)
		(width 0.14478)
		(layer "In2.Cu")
		(net "M_I_CPU1_SB_DQ<19>")
	)
	(segment
		(start 161.61893 -302.114712)
		(end 161.780474 -302.276256)
		(width 0.14478)
		(layer "In2.Cu")
		(net "M_I_CPU1_SB_DQ<19>")
	)
	(segment
		(start 162.581844 -302.483774)
		(end 162.399218 -302.6664)
		(width 0.14478)
		(layer "In2.Cu")
		(net "M_I_CPU1_SB_DQ<19>")
	)
	(segment
		(start 160.058354 -300.554136)
		(end 160.219898 -300.71568)
		(width 0.14478)
		(layer "In2.Cu")
		(net "M_I_CPU1_SB_DQ<19>")
	)
	(segment
		(start 150.26513 -289.266122)
		(end 151.322532 -291.818314)
		(width 0.14478)
		(layer "In2.Cu")
		(net "M_I_CPU1_SB_DQ<19>")
	)
	(segment
		(start 157.900116 -297.573446)
		(end 157.900116 -297.802046)
		(width 0.14478)
		(layer "In2.Cu")
		(net "M_I_CPU1_SB_DQ<19>")
	)
	(segment
		(start 134.343394 -285.098998)
		(end 134.351776 -285.103824)
		(width 0.0889)
		(layer "In2.Cu")
		(net "M_I_CPU1_SB_DQ<19>")
	)
	(arc
		(start 140.9319 -285.103824)
		(mid 141.214856 -285.180001)
		(end 141.497812 -285.103824)
		(width 0.0889)
		(layer "In2.Cu")
		(net "M_I_CPU1_SB_DQ<19>")
	)
	(arc
		(start 144.71777 -285.121096)
		(mid 144.98919 -285.180773)
		(end 145.25625 -285.103824)
		(width 0.0889)
		(layer "In2.Cu")
		(net "M_I_CPU1_SB_DQ<19>")
	)
	(arc
		(start 130.591814 -285.103824)
		(mid 130.87477 -285.180001)
		(end 131.157726 -285.103824)
		(width 0.0889)
		(layer "In2.Cu")
		(net "M_I_CPU1_SB_DQ<19>")
	)
	(arc
		(start 133.411722 -285.103824)
		(mid 133.694678 -285.180001)
		(end 133.977634 -285.103824)
		(width 0.0889)
		(layer "In2.Cu")
		(net "M_I_CPU1_SB_DQ<19>")
	)
	(arc
		(start 137.737596 -285.103824)
		(mid 137.919847 -285.053474)
		(end 138.103356 -285.098998)
		(width 0.0889)
		(layer "In2.Cu")
		(net "M_I_CPU1_SB_DQ<19>")
	)
	(arc
		(start 138.111738 -285.103824)
		(mid 138.394694 -285.180001)
		(end 138.67765 -285.103824)
		(width 0.0889)
		(layer "In2.Cu")
		(net "M_I_CPU1_SB_DQ<19>")
	)
	(arc
		(start 131.166108 -285.098998)
		(mid 131.349616 -285.053504)
		(end 131.531868 -285.103824)
		(width 0.0889)
		(layer "In2.Cu")
		(net "M_I_CPU1_SB_DQ<19>")
	)
	(arc
		(start 131.531868 -285.103824)
		(mid 131.814824 -285.180001)
		(end 132.09778 -285.103824)
		(width 0.0889)
		(layer "In2.Cu")
		(net "M_I_CPU1_SB_DQ<19>")
	)
	(arc
		(start 139.051792 -285.103824)
		(mid 139.334748 -285.180001)
		(end 139.617704 -285.103824)
		(width 0.0889)
		(layer "In2.Cu")
		(net "M_I_CPU1_SB_DQ<19>")
	)
	(arc
		(start 139.626086 -285.098998)
		(mid 139.809594 -285.053504)
		(end 139.991846 -285.103824)
		(width 0.0889)
		(layer "In2.Cu")
		(net "M_I_CPU1_SB_DQ<19>")
	)
	(arc
		(start 133.037834 -285.103824)
		(mid 133.224778 -285.053569)
		(end 133.411722 -285.103824)
		(width 0.0889)
		(layer "In2.Cu")
		(net "M_I_CPU1_SB_DQ<19>")
	)
	(arc
		(start 133.977634 -285.103824)
		(mid 134.159885 -285.053474)
		(end 134.343394 -285.098998)
		(width 0.0889)
		(layer "In2.Cu")
		(net "M_I_CPU1_SB_DQ<19>")
	)
	(arc
		(start 142.811754 -285.103824)
		(mid 143.09471 -285.180001)
		(end 143.377666 -285.103824)
		(width 0.0889)
		(layer "In2.Cu")
		(net "M_I_CPU1_SB_DQ<19>")
	)
	(arc
		(start 129.277618 -285.103824)
		(mid 129.459869 -285.053474)
		(end 129.643378 -285.098998)
		(width 0.0889)
		(layer "In2.Cu")
		(net "M_I_CPU1_SB_DQ<19>")
	)
	(arc
		(start 141.497812 -285.103824)
		(mid 141.684756 -285.053569)
		(end 141.8717 -285.103824)
		(width 0.0889)
		(layer "In2.Cu")
		(net "M_I_CPU1_SB_DQ<19>")
	)
	(arc
		(start 130.217672 -285.103824)
		(mid 130.399923 -285.053474)
		(end 130.583432 -285.098998)
		(width 0.0889)
		(layer "In2.Cu")
		(net "M_I_CPU1_SB_DQ<19>")
	)
	(arc
		(start 140.56614 -285.098998)
		(mid 140.749648 -285.053504)
		(end 140.9319 -285.103824)
		(width 0.0889)
		(layer "In2.Cu")
		(net "M_I_CPU1_SB_DQ<19>")
	)
	(arc
		(start 136.231884 -285.103824)
		(mid 136.51484 -285.180001)
		(end 136.797796 -285.103824)
		(width 0.0889)
		(layer "In2.Cu")
		(net "M_I_CPU1_SB_DQ<19>")
	)
	(arc
		(start 145.25625 -285.103824)
		(mid 145.313174 -285.076727)
		(end 145.373852 -285.059628)
		(width 0.0889)
		(layer "In2.Cu")
		(net "M_I_CPU1_SB_DQ<19>")
	)
	(arc
		(start 135.866124 -285.098998)
		(mid 136.049632 -285.053504)
		(end 136.231884 -285.103824)
		(width 0.0889)
		(layer "In2.Cu")
		(net "M_I_CPU1_SB_DQ<19>")
	)
	(arc
		(start 129.65176 -285.103824)
		(mid 129.934716 -285.180001)
		(end 130.217672 -285.103824)
		(width 0.0889)
		(layer "In2.Cu")
		(net "M_I_CPU1_SB_DQ<19>")
	)
	(arc
		(start 143.751808 -285.103824)
		(mid 144.018738 -285.179773)
		(end 144.289526 -285.119064)
		(width 0.0889)
		(layer "In2.Cu")
		(net "M_I_CPU1_SB_DQ<19>")
	)
	(arc
		(start 138.67765 -285.103824)
		(mid 138.859901 -285.053474)
		(end 139.04341 -285.098998)
		(width 0.0889)
		(layer "In2.Cu")
		(net "M_I_CPU1_SB_DQ<19>")
	)
	(arc
		(start 134.351776 -285.103824)
		(mid 134.634732 -285.180001)
		(end 134.917688 -285.103824)
		(width 0.0889)
		(layer "In2.Cu")
		(net "M_I_CPU1_SB_DQ<19>")
	)
	(arc
		(start 135.29183 -285.103824)
		(mid 135.574786 -285.180001)
		(end 135.857742 -285.103824)
		(width 0.0889)
		(layer "In2.Cu")
		(net "M_I_CPU1_SB_DQ<19>")
	)
	(arc
		(start 142.437612 -285.103824)
		(mid 142.619863 -285.053474)
		(end 142.803372 -285.098998)
		(width 0.0889)
		(layer "In2.Cu")
		(net "M_I_CPU1_SB_DQ<19>")
	)
	(arc
		(start 143.386048 -285.098998)
		(mid 143.569556 -285.053504)
		(end 143.751808 -285.103824)
		(width 0.0889)
		(layer "In2.Cu")
		(net "M_I_CPU1_SB_DQ<19>")
	)
	(arc
		(start 132.471922 -285.103824)
		(mid 132.754878 -285.180001)
		(end 133.037834 -285.103824)
		(width 0.0889)
		(layer "In2.Cu")
		(net "M_I_CPU1_SB_DQ<19>")
	)
	(arc
		(start 139.991846 -285.103824)
		(mid 140.274802 -285.180001)
		(end 140.557758 -285.103824)
		(width 0.0889)
		(layer "In2.Cu")
		(net "M_I_CPU1_SB_DQ<19>")
	)
	(arc
		(start 141.8717 -285.103824)
		(mid 142.154656 -285.180001)
		(end 142.437612 -285.103824)
		(width 0.0889)
		(layer "In2.Cu")
		(net "M_I_CPU1_SB_DQ<19>")
	)
	(arc
		(start 128.711706 -285.103824)
		(mid 128.994662 -285.180001)
		(end 129.277618 -285.103824)
		(width 0.0889)
		(layer "In2.Cu")
		(net "M_I_CPU1_SB_DQ<19>")
	)
	(arc
		(start 128.39319 -285.077662)
		(mid 128.555379 -285.054927)
		(end 128.711706 -285.103824)
		(width 0.0889)
		(layer "In2.Cu")
		(net "M_I_CPU1_SB_DQ<19>")
	)
	(arc
		(start 134.92607 -285.098998)
		(mid 135.109578 -285.053504)
		(end 135.29183 -285.103824)
		(width 0.0889)
		(layer "In2.Cu")
		(net "M_I_CPU1_SB_DQ<19>")
	)
	(arc
		(start 132.106162 -285.098998)
		(mid 132.28967 -285.053504)
		(end 132.471922 -285.103824)
		(width 0.0889)
		(layer "In2.Cu")
		(net "M_I_CPU1_SB_DQ<19>")
	)
	(arc
		(start 137.171684 -285.103824)
		(mid 137.45464 -285.180001)
		(end 137.737596 -285.103824)
		(width 0.0889)
		(layer "In2.Cu")
		(net "M_I_CPU1_SB_DQ<19>")
	)
	(arc
		(start 144.337532 -285.091632)
		(mid 144.51446 -285.053804)
		(end 144.688306 -285.103824)
		(width 0.0889)
		(layer "In2.Cu")
		(net "M_I_CPU1_SB_DQ<19>")
	)
	(arc
		(start 136.797796 -285.103824)
		(mid 136.98474 -285.053569)
		(end 137.171684 -285.103824)
		(width 0.0889)
		(layer "In2.Cu")
		(net "M_I_CPU1_SB_DQ<19>")
	)
	(segment
		(start 129.467864 -284.35046)
		(end 129.934716 -284.616398)
		(width 0.10668)
		(layer "F.Cu")
		(net "M_I_CPU1_SB_DQ<18>")
	)
	(segment
		(start 144.221708 -284.293818)
		(end 144.23644 -284.302454)
		(width 0.0889)
		(layer "In2.Cu")
		(net "M_I_CPU1_SB_DQ<18>")
	)
	(segment
		(start 152.652984 -291.209984)
		(end 152.881076 -291.208968)
		(width 0.14478)
		(layer "In2.Cu")
		(net "M_I_CPU1_SB_DQ<18>")
	)
	(segment
		(start 141.967712 -284.293818)
		(end 141.976094 -284.288992)
		(width 0.0889)
		(layer "In2.Cu")
		(net "M_I_CPU1_SB_DQ<18>")
	)
	(segment
		(start 169.522648 -300.912784)
		(end 169.825162 -300.61027)
		(width 0.14478)
		(layer "In2.Cu")
		(net "M_I_CPU1_SB_DQ<18>")
	)
	(segment
		(start 169.266362 -300.912784)
		(end 169.522648 -300.912784)
		(width 0.14478)
		(layer "In2.Cu")
		(net "M_I_CPU1_SB_DQ<18>")
	)
	(segment
		(start 178.210464 -301.194216)
		(end 178.37404 -301.03064)
		(width 0.14478)
		(layer "In2.Cu")
		(net "M_I_CPU1_SB_DQ<18>")
	)
	(segment
		(start 136.693402 -284.288992)
		(end 136.701784 -284.293818)
		(width 0.0889)
		(layer "In2.Cu")
		(net "M_I_CPU1_SB_DQ<18>")
	)
	(segment
		(start 156.016452 -294.313864)
		(end 163.2331 -301.460408)
		(width 0.14478)
		(layer "In2.Cu")
		(net "M_I_CPU1_SB_DQ<18>")
	)
	(segment
		(start 153.231596 -292.193472)
		(end 153.436828 -291.986208)
		(width 0.14478)
		(layer "In2.Cu")
		(net "M_I_CPU1_SB_DQ<18>")
	)
	(segment
		(start 168.963848 -300.61027)
		(end 169.266362 -300.912784)
		(width 0.14478)
		(layer "In2.Cu")
		(net "M_I_CPU1_SB_DQ<18>")
	)
	(segment
		(start 152.260046 -290.59378)
		(end 152.261062 -290.821872)
		(width 0.14478)
		(layer "In2.Cu")
		(net "M_I_CPU1_SB_DQ<18>")
	)
	(segment
		(start 145.444718 -284.370272)
		(end 145.791174 -284.370272)
		(width 0.0889)
		(layer "In2.Cu")
		(net "M_I_CPU1_SB_DQ<18>")
	)
	(segment
		(start 155.78836 -294.31488)
		(end 156.016452 -294.313864)
		(width 0.14478)
		(layer "In2.Cu")
		(net "M_I_CPU1_SB_DQ<18>")
	)
	(segment
		(start 155.004516 -293.538656)
		(end 155.232608 -293.53764)
		(width 0.14478)
		(layer "In2.Cu")
		(net "M_I_CPU1_SB_DQ<18>")
	)
	(segment
		(start 177.651664 -300.026324)
		(end 177.81524 -300.1899)
		(width 0.14478)
		(layer "In2.Cu")
		(net "M_I_CPU1_SB_DQ<18>")
	)
	(segment
		(start 175.795686 -300.61027)
		(end 177.092864 -300.61027)
		(width 0.14478)
		(layer "In2.Cu")
		(net "M_I_CPU1_SB_DQ<18>")
	)
	(segment
		(start 152.133046 -291.18052)
		(end 152.295606 -291.341556)
		(width 0.14478)
		(layer "In2.Cu")
		(net "M_I_CPU1_SB_DQ<18>")
	)
	(segment
		(start 152.13203 -290.952174)
		(end 152.133046 -291.18052)
		(width 0.14478)
		(layer "In2.Cu")
		(net "M_I_CPU1_SB_DQ<18>")
	)
	(segment
		(start 129.934716 -284.616398)
		(end 129.780792 -284.350968)
		(width 0.0889)
		(layer "In2.Cu")
		(net "M_I_CPU1_SB_DQ<18>")
	)
	(segment
		(start 154.799284 -293.74592)
		(end 155.004516 -293.538656)
		(width 0.14478)
		(layer "In2.Cu")
		(net "M_I_CPU1_SB_DQ<18>")
	)
	(segment
		(start 145.16227 -284.294072)
		(end 145.178018 -284.303216)
		(width 0.0889)
		(layer "In2.Cu")
		(net "M_I_CPU1_SB_DQ<18>")
	)
	(segment
		(start 153.044906 -291.598096)
		(end 152.839674 -291.80536)
		(width 0.14478)
		(layer "In2.Cu")
		(net "M_I_CPU1_SB_DQ<18>")
	)
	(segment
		(start 146.504914 -285.084012)
		(end 147.414234 -285.084012)
		(width 0.0889)
		(layer "In2.Cu")
		(net "M_I_CPU1_SB_DQ<18>")
	)
	(segment
		(start 153.624534 -292.809676)
		(end 153.787094 -292.970712)
		(width 0.14478)
		(layer "In2.Cu")
		(net "M_I_CPU1_SB_DQ<18>")
	)
	(segment
		(start 163.2331 -301.460408)
		(end 165.352476 -301.460408)
		(width 0.14478)
		(layer "In2.Cu")
		(net "M_I_CPU1_SB_DQ<18>")
	)
	(segment
		(start 155.395422 -293.698676)
		(end 155.396438 -293.926768)
		(width 0.14478)
		(layer "In2.Cu")
		(net "M_I_CPU1_SB_DQ<18>")
	)
	(segment
		(start 153.827734 -292.146228)
		(end 153.82875 -292.37432)
		(width 0.14478)
		(layer "In2.Cu")
		(net "M_I_CPU1_SB_DQ<18>")
	)
	(segment
		(start 167.268906 -300.61027)
		(end 167.5765 -300.917864)
		(width 0.14478)
		(layer "In2.Cu")
		(net "M_I_CPU1_SB_DQ<18>")
	)
	(segment
		(start 169.825162 -300.61027)
		(end 170.120564 -300.61027)
		(width 0.14478)
		(layer "In2.Cu")
		(net "M_I_CPU1_SB_DQ<18>")
	)
	(segment
		(start 165.63848 -301.34179)
		(end 165.781736 -300.996858)
		(width 0.14478)
		(layer "In2.Cu")
		(net "M_I_CPU1_SB_DQ<18>")
	)
	(segment
		(start 154.611578 -292.922452)
		(end 154.612594 -293.150544)
		(width 0.14478)
		(layer "In2.Cu")
		(net "M_I_CPU1_SB_DQ<18>")
	)
	(segment
		(start 153.82875 -292.37432)
		(end 153.623518 -292.581584)
		(width 0.14478)
		(layer "In2.Cu")
		(net "M_I_CPU1_SB_DQ<18>")
	)
	(segment
		(start 175.523652 -300.882304)
		(end 175.795686 -300.61027)
		(width 0.14478)
		(layer "In2.Cu")
		(net "M_I_CPU1_SB_DQ<18>")
	)
	(segment
		(start 147.414234 -285.084012)
		(end 147.888198 -285.557976)
		(width 0.0889)
		(layer "In2.Cu")
		(net "M_I_CPU1_SB_DQ<18>")
	)
	(segment
		(start 151.746204 -289.415982)
		(end 151.746204 -290.085018)
		(width 0.14478)
		(layer "In2.Cu")
		(net "M_I_CPU1_SB_DQ<18>")
	)
	(segment
		(start 178.537616 -300.61027)
		(end 179.091082 -300.61027)
		(width 0.14478)
		(layer "In2.Cu")
		(net "M_I_CPU1_SB_DQ<18>")
	)
	(segment
		(start 152.839674 -291.80536)
		(end 152.84069 -292.033452)
		(width 0.14478)
		(layer "In2.Cu")
		(net "M_I_CPU1_SB_DQ<18>")
	)
	(segment
		(start 135.753348 -284.288992)
		(end 135.76173 -284.293818)
		(width 0.0889)
		(layer "In2.Cu")
		(net "M_I_CPU1_SB_DQ<18>")
	)
	(segment
		(start 129.780792 -284.350968)
		(end 129.803144 -284.267656)
		(width 0.0889)
		(layer "In2.Cu")
		(net "M_I_CPU1_SB_DQ<18>")
	)
	(segment
		(start 152.295606 -291.341556)
		(end 152.523698 -291.34054)
		(width 0.14478)
		(layer "In2.Cu")
		(net "M_I_CPU1_SB_DQ<18>")
	)
	(segment
		(start 154.612594 -293.150544)
		(end 154.407362 -293.357808)
		(width 0.14478)
		(layer "In2.Cu")
		(net "M_I_CPU1_SB_DQ<18>")
	)
	(segment
		(start 168.1353 -300.61027)
		(end 168.963848 -300.61027)
		(width 0.14478)
		(layer "In2.Cu")
		(net "M_I_CPU1_SB_DQ<18>")
	)
	(segment
		(start 165.781736 -300.996858)
		(end 165.71087 -300.825916)
		(width 0.14478)
		(layer "In2.Cu")
		(net "M_I_CPU1_SB_DQ<18>")
	)
	(segment
		(start 153.623518 -292.581584)
		(end 153.624534 -292.809676)
		(width 0.14478)
		(layer "In2.Cu")
		(net "M_I_CPU1_SB_DQ<18>")
	)
	(segment
		(start 165.71087 -300.825916)
		(end 165.799516 -300.612302)
		(width 0.14478)
		(layer "In2.Cu")
		(net "M_I_CPU1_SB_DQ<18>")
	)
	(segment
		(start 141.393418 -284.288992)
		(end 141.4018 -284.293818)
		(width 0.0889)
		(layer "In2.Cu")
		(net "M_I_CPU1_SB_DQ<18>")
	)
	(segment
		(start 170.120564 -300.61027)
		(end 170.819318 -300.891448)
		(width 0.14478)
		(layer "In2.Cu")
		(net "M_I_CPU1_SB_DQ<18>")
	)
	(segment
		(start 165.799516 -300.612302)
		(end 166.013892 -300.523402)
		(width 0.14478)
		(layer "In2.Cu")
		(net "M_I_CPU1_SB_DQ<18>")
	)
	(segment
		(start 177.81524 -300.1899)
		(end 177.81524 -301.03064)
		(width 0.14478)
		(layer "In2.Cu")
		(net "M_I_CPU1_SB_DQ<18>")
	)
	(segment
		(start 144.213326 -284.288992)
		(end 144.221708 -284.293818)
		(width 0.0889)
		(layer "In2.Cu")
		(net "M_I_CPU1_SB_DQ<18>")
	)
	(segment
		(start 155.396438 -293.926768)
		(end 155.191206 -294.134032)
		(width 0.14478)
		(layer "In2.Cu")
		(net "M_I_CPU1_SB_DQ<18>")
	)
	(segment
		(start 177.25644 -300.446694)
		(end 177.25644 -300.1899)
		(width 0.14478)
		(layer "In2.Cu")
		(net "M_I_CPU1_SB_DQ<18>")
	)
	(segment
		(start 155.583128 -294.522144)
		(end 155.78836 -294.31488)
		(width 0.14478)
		(layer "In2.Cu")
		(net "M_I_CPU1_SB_DQ<18>")
	)
	(segment
		(start 154.448764 -292.761416)
		(end 154.611578 -292.922452)
		(width 0.14478)
		(layer "In2.Cu")
		(net "M_I_CPU1_SB_DQ<18>")
	)
	(segment
		(start 155.192222 -294.362124)
		(end 155.354782 -294.52316)
		(width 0.14478)
		(layer "In2.Cu")
		(net "M_I_CPU1_SB_DQ<18>")
	)
	(segment
		(start 171.033694 -301.394368)
		(end 171.198032 -301.460408)
		(width 0.14478)
		(layer "In2.Cu")
		(net "M_I_CPU1_SB_DQ<18>")
	)
	(segment
		(start 154.01544 -292.969696)
		(end 154.220672 -292.762432)
		(width 0.14478)
		(layer "In2.Cu")
		(net "M_I_CPU1_SB_DQ<18>")
	)
	(segment
		(start 173.615604 -300.731936)
		(end 174.04334 -300.911514)
		(width 0.14478)
		(layer "In2.Cu")
		(net "M_I_CPU1_SB_DQ<18>")
	)
	(segment
		(start 166.227252 -300.611794)
		(end 166.298118 -300.78299)
		(width 0.14478)
		(layer "In2.Cu")
		(net "M_I_CPU1_SB_DQ<18>")
	)
	(segment
		(start 177.420016 -300.026324)
		(end 177.651664 -300.026324)
		(width 0.14478)
		(layer "In2.Cu")
		(net "M_I_CPU1_SB_DQ<18>")
	)
	(segment
		(start 137.267696 -284.293818)
		(end 137.276078 -284.288992)
		(width 0.0889)
		(layer "In2.Cu")
		(net "M_I_CPU1_SB_DQ<18>")
	)
	(segment
		(start 177.25644 -300.1899)
		(end 177.420016 -300.026324)
		(width 0.14478)
		(layer "In2.Cu")
		(net "M_I_CPU1_SB_DQ<18>")
	)
	(segment
		(start 177.092864 -300.61027)
		(end 177.25644 -300.446694)
		(width 0.14478)
		(layer "In2.Cu")
		(net "M_I_CPU1_SB_DQ<18>")
	)
	(segment
		(start 155.232608 -293.53764)
		(end 155.395422 -293.698676)
		(width 0.14478)
		(layer "In2.Cu")
		(net "M_I_CPU1_SB_DQ<18>")
	)
	(segment
		(start 173.401228 -300.820836)
		(end 173.615604 -300.731936)
		(width 0.14478)
		(layer "In2.Cu")
		(net "M_I_CPU1_SB_DQ<18>")
	)
	(segment
		(start 132.93344 -284.288992)
		(end 132.941822 -284.293818)
		(width 0.0889)
		(layer "In2.Cu")
		(net "M_I_CPU1_SB_DQ<18>")
	)
	(segment
		(start 166.511478 -300.871636)
		(end 167.142922 -300.61027)
		(width 0.14478)
		(layer "In2.Cu")
		(net "M_I_CPU1_SB_DQ<18>")
	)
	(segment
		(start 174.04334 -300.911514)
		(end 174.77105 -300.61027)
		(width 0.14478)
		(layer "In2.Cu")
		(net "M_I_CPU1_SB_DQ<18>")
	)
	(segment
		(start 152.261062 -290.821872)
		(end 152.13203 -290.952174)
		(width 0.14478)
		(layer "In2.Cu")
		(net "M_I_CPU1_SB_DQ<18>")
	)
	(segment
		(start 167.142922 -300.61027)
		(end 167.268906 -300.61027)
		(width 0.14478)
		(layer "In2.Cu")
		(net "M_I_CPU1_SB_DQ<18>")
	)
	(segment
		(start 153.787094 -292.970712)
		(end 154.01544 -292.969696)
		(width 0.14478)
		(layer "In2.Cu")
		(net "M_I_CPU1_SB_DQ<18>")
	)
	(segment
		(start 131.993386 -284.288992)
		(end 132.001768 -284.293818)
		(width 0.0889)
		(layer "In2.Cu")
		(net "M_I_CPU1_SB_DQ<18>")
	)
	(segment
		(start 152.881076 -291.208968)
		(end 153.04389 -291.370004)
		(width 0.14478)
		(layer "In2.Cu")
		(net "M_I_CPU1_SB_DQ<18>")
	)
	(segment
		(start 155.191206 -294.134032)
		(end 155.192222 -294.362124)
		(width 0.14478)
		(layer "In2.Cu")
		(net "M_I_CPU1_SB_DQ<18>")
	)
	(segment
		(start 172.78096 -301.460408)
		(end 173.211998 -301.281846)
		(width 0.14478)
		(layer "In2.Cu")
		(net "M_I_CPU1_SB_DQ<18>")
	)
	(segment
		(start 140.453364 -284.288992)
		(end 140.461746 -284.293818)
		(width 0.0889)
		(layer "In2.Cu")
		(net "M_I_CPU1_SB_DQ<18>")
	)
	(segment
		(start 145.143982 -284.283658)
		(end 145.16227 -284.294072)
		(width 0.0889)
		(layer "In2.Cu")
		(net "M_I_CPU1_SB_DQ<18>")
	)
	(segment
		(start 167.827706 -300.917864)
		(end 168.1353 -300.61027)
		(width 0.14478)
		(layer "In2.Cu")
		(net "M_I_CPU1_SB_DQ<18>")
	)
	(segment
		(start 179.091082 -300.61027)
		(end 179.516024 -301.035212)
		(width 0.14478)
		(layer "In2.Cu")
		(net "M_I_CPU1_SB_DQ<18>")
	)
	(segment
		(start 177.978816 -301.194216)
		(end 178.210464 -301.194216)
		(width 0.14478)
		(layer "In2.Cu")
		(net "M_I_CPU1_SB_DQ<18>")
	)
	(segment
		(start 175.236886 -300.882304)
		(end 175.523652 -300.882304)
		(width 0.14478)
		(layer "In2.Cu")
		(net "M_I_CPU1_SB_DQ<18>")
	)
	(segment
		(start 165.352476 -301.460408)
		(end 165.63848 -301.34179)
		(width 0.14478)
		(layer "In2.Cu")
		(net "M_I_CPU1_SB_DQ<18>")
	)
	(segment
		(start 153.04389 -291.370004)
		(end 153.044906 -291.598096)
		(width 0.14478)
		(layer "In2.Cu")
		(net "M_I_CPU1_SB_DQ<18>")
	)
	(segment
		(start 145.791174 -284.370272)
		(end 146.504914 -285.084012)
		(width 0.0889)
		(layer "In2.Cu")
		(net "M_I_CPU1_SB_DQ<18>")
	)
	(segment
		(start 154.408378 -293.5859)
		(end 154.570938 -293.746936)
		(width 0.14478)
		(layer "In2.Cu")
		(net "M_I_CPU1_SB_DQ<18>")
	)
	(segment
		(start 133.507734 -284.293818)
		(end 133.516116 -284.288992)
		(width 0.0889)
		(layer "In2.Cu")
		(net "M_I_CPU1_SB_DQ<18>")
	)
	(segment
		(start 154.570938 -293.746936)
		(end 154.799284 -293.74592)
		(width 0.14478)
		(layer "In2.Cu")
		(net "M_I_CPU1_SB_DQ<18>")
	)
	(segment
		(start 173.211998 -301.281846)
		(end 173.401228 -300.820836)
		(width 0.14478)
		(layer "In2.Cu")
		(net "M_I_CPU1_SB_DQ<18>")
	)
	(segment
		(start 153.00325 -292.194488)
		(end 153.231596 -292.193472)
		(width 0.14478)
		(layer "In2.Cu")
		(net "M_I_CPU1_SB_DQ<18>")
	)
	(segment
		(start 170.819318 -300.891448)
		(end 171.033694 -301.394368)
		(width 0.14478)
		(layer "In2.Cu")
		(net "M_I_CPU1_SB_DQ<18>")
	)
	(segment
		(start 154.220672 -292.762432)
		(end 154.448764 -292.761416)
		(width 0.14478)
		(layer "In2.Cu")
		(net "M_I_CPU1_SB_DQ<18>")
	)
	(segment
		(start 151.746204 -290.085018)
		(end 152.260046 -290.59378)
		(width 0.14478)
		(layer "In2.Cu")
		(net "M_I_CPU1_SB_DQ<18>")
	)
	(segment
		(start 174.964852 -300.61027)
		(end 175.236886 -300.882304)
		(width 0.14478)
		(layer "In2.Cu")
		(net "M_I_CPU1_SB_DQ<18>")
	)
	(segment
		(start 174.77105 -300.61027)
		(end 174.964852 -300.61027)
		(width 0.14478)
		(layer "In2.Cu")
		(net "M_I_CPU1_SB_DQ<18>")
	)
	(segment
		(start 147.888198 -285.557976)
		(end 151.746204 -289.415982)
		(width 0.14478)
		(layer "In2.Cu")
		(net "M_I_CPU1_SB_DQ<18>")
	)
	(segment
		(start 152.84069 -292.033452)
		(end 153.00325 -292.194488)
		(width 0.14478)
		(layer "In2.Cu")
		(net "M_I_CPU1_SB_DQ<18>")
	)
	(segment
		(start 153.436828 -291.986208)
		(end 153.66492 -291.985192)
		(width 0.14478)
		(layer "In2.Cu")
		(net "M_I_CPU1_SB_DQ<18>")
	)
	(segment
		(start 178.37404 -301.03064)
		(end 178.37404 -300.773846)
		(width 0.14478)
		(layer "In2.Cu")
		(net "M_I_CPU1_SB_DQ<18>")
	)
	(segment
		(start 166.298118 -300.78299)
		(end 166.511478 -300.871636)
		(width 0.14478)
		(layer "In2.Cu")
		(net "M_I_CPU1_SB_DQ<18>")
	)
	(segment
		(start 178.37404 -300.773846)
		(end 178.537616 -300.61027)
		(width 0.14478)
		(layer "In2.Cu")
		(net "M_I_CPU1_SB_DQ<18>")
	)
	(segment
		(start 167.5765 -300.917864)
		(end 167.827706 -300.917864)
		(width 0.14478)
		(layer "In2.Cu")
		(net "M_I_CPU1_SB_DQ<18>")
	)
	(segment
		(start 152.523698 -291.34054)
		(end 152.652984 -291.209984)
		(width 0.14478)
		(layer "In2.Cu")
		(net "M_I_CPU1_SB_DQ<18>")
	)
	(segment
		(start 177.81524 -301.03064)
		(end 177.978816 -301.194216)
		(width 0.14478)
		(layer "In2.Cu")
		(net "M_I_CPU1_SB_DQ<18>")
	)
	(segment
		(start 154.407362 -293.357808)
		(end 154.408378 -293.5859)
		(width 0.14478)
		(layer "In2.Cu")
		(net "M_I_CPU1_SB_DQ<18>")
	)
	(segment
		(start 171.198032 -301.460408)
		(end 172.78096 -301.460408)
		(width 0.14478)
		(layer "In2.Cu")
		(net "M_I_CPU1_SB_DQ<18>")
	)
	(segment
		(start 155.354782 -294.52316)
		(end 155.583128 -294.522144)
		(width 0.14478)
		(layer "In2.Cu")
		(net "M_I_CPU1_SB_DQ<18>")
	)
	(segment
		(start 153.66492 -291.985192)
		(end 153.827734 -292.146228)
		(width 0.14478)
		(layer "In2.Cu")
		(net "M_I_CPU1_SB_DQ<18>")
	)
	(segment
		(start 166.013892 -300.523402)
		(end 166.227252 -300.611794)
		(width 0.14478)
		(layer "In2.Cu")
		(net "M_I_CPU1_SB_DQ<18>")
	)
	(segment
		(start 138.20775 -284.293818)
		(end 138.216132 -284.288992)
		(width 0.0889)
		(layer "In2.Cu")
		(net "M_I_CPU1_SB_DQ<18>")
	)
	(arc
		(start 130.687826 -284.293818)
		(mid 130.87477 -284.243563)
		(end 131.061714 -284.293818)
		(width 0.0889)
		(layer "In2.Cu")
		(net "M_I_CPU1_SB_DQ<18>")
	)
	(arc
		(start 134.447788 -284.293818)
		(mid 134.634732 -284.243563)
		(end 134.821676 -284.293818)
		(width 0.0889)
		(layer "In2.Cu")
		(net "M_I_CPU1_SB_DQ<18>")
	)
	(arc
		(start 138.581892 -284.293818)
		(mid 138.864848 -284.369995)
		(end 139.147804 -284.293818)
		(width 0.0889)
		(layer "In2.Cu")
		(net "M_I_CPU1_SB_DQ<18>")
	)
	(arc
		(start 143.281654 -284.293818)
		(mid 143.56461 -284.369995)
		(end 143.847566 -284.293818)
		(width 0.0889)
		(layer "In2.Cu")
		(net "M_I_CPU1_SB_DQ<18>")
	)
	(arc
		(start 129.803144 -284.267656)
		(mid 129.965476 -284.244838)
		(end 130.121914 -284.293818)
		(width 0.0889)
		(layer "In2.Cu")
		(net "M_I_CPU1_SB_DQ<18>")
	)
	(arc
		(start 137.641838 -284.293818)
		(mid 137.924794 -284.369995)
		(end 138.20775 -284.293818)
		(width 0.0889)
		(layer "In2.Cu")
		(net "M_I_CPU1_SB_DQ<18>")
	)
	(arc
		(start 130.121914 -284.293818)
		(mid 130.40487 -284.369995)
		(end 130.687826 -284.293818)
		(width 0.0889)
		(layer "In2.Cu")
		(net "M_I_CPU1_SB_DQ<18>")
	)
	(arc
		(start 139.521692 -284.293818)
		(mid 139.804648 -284.369995)
		(end 140.087604 -284.293818)
		(width 0.0889)
		(layer "In2.Cu")
		(net "M_I_CPU1_SB_DQ<18>")
	)
	(arc
		(start 140.461746 -284.293818)
		(mid 140.744702 -284.369995)
		(end 141.027658 -284.293818)
		(width 0.0889)
		(layer "In2.Cu")
		(net "M_I_CPU1_SB_DQ<18>")
	)
	(arc
		(start 137.276078 -284.288992)
		(mid 137.459586 -284.243498)
		(end 137.641838 -284.293818)
		(width 0.0889)
		(layer "In2.Cu")
		(net "M_I_CPU1_SB_DQ<18>")
	)
	(arc
		(start 141.027658 -284.293818)
		(mid 141.209909 -284.243468)
		(end 141.393418 -284.288992)
		(width 0.0889)
		(layer "In2.Cu")
		(net "M_I_CPU1_SB_DQ<18>")
	)
	(arc
		(start 138.216132 -284.288992)
		(mid 138.39964 -284.243498)
		(end 138.581892 -284.293818)
		(width 0.0889)
		(layer "In2.Cu")
		(net "M_I_CPU1_SB_DQ<18>")
	)
	(arc
		(start 134.821676 -284.293818)
		(mid 135.104632 -284.369995)
		(end 135.387588 -284.293818)
		(width 0.0889)
		(layer "In2.Cu")
		(net "M_I_CPU1_SB_DQ<18>")
	)
	(arc
		(start 136.701784 -284.293818)
		(mid 136.98474 -284.369995)
		(end 137.267696 -284.293818)
		(width 0.0889)
		(layer "In2.Cu")
		(net "M_I_CPU1_SB_DQ<18>")
	)
	(arc
		(start 144.23644 -284.302454)
		(mid 144.513423 -284.370258)
		(end 144.788128 -284.293818)
		(width 0.0889)
		(layer "In2.Cu")
		(net "M_I_CPU1_SB_DQ<18>")
	)
	(arc
		(start 132.56768 -284.293818)
		(mid 132.749931 -284.243468)
		(end 132.93344 -284.288992)
		(width 0.0889)
		(layer "In2.Cu")
		(net "M_I_CPU1_SB_DQ<18>")
	)
	(arc
		(start 131.061714 -284.293818)
		(mid 131.34467 -284.369995)
		(end 131.627626 -284.293818)
		(width 0.0889)
		(layer "In2.Cu")
		(net "M_I_CPU1_SB_DQ<18>")
	)
	(arc
		(start 144.788128 -284.293818)
		(mid 144.964756 -284.243585)
		(end 145.143982 -284.283658)
		(width 0.0889)
		(layer "In2.Cu")
		(net "M_I_CPU1_SB_DQ<18>")
	)
	(arc
		(start 145.178018 -284.303216)
		(mid 145.307217 -284.353253)
		(end 145.444718 -284.370272)
		(width 0.0889)
		(layer "In2.Cu")
		(net "M_I_CPU1_SB_DQ<18>")
	)
	(arc
		(start 142.907766 -284.293818)
		(mid 143.09471 -284.243563)
		(end 143.281654 -284.293818)
		(width 0.0889)
		(layer "In2.Cu")
		(net "M_I_CPU1_SB_DQ<18>")
	)
	(arc
		(start 141.976094 -284.288992)
		(mid 142.159602 -284.243498)
		(end 142.341854 -284.293818)
		(width 0.0889)
		(layer "In2.Cu")
		(net "M_I_CPU1_SB_DQ<18>")
	)
	(arc
		(start 135.76173 -284.293818)
		(mid 136.044686 -284.369995)
		(end 136.327642 -284.293818)
		(width 0.0889)
		(layer "In2.Cu")
		(net "M_I_CPU1_SB_DQ<18>")
	)
	(arc
		(start 132.001768 -284.293818)
		(mid 132.284724 -284.369995)
		(end 132.56768 -284.293818)
		(width 0.0889)
		(layer "In2.Cu")
		(net "M_I_CPU1_SB_DQ<18>")
	)
	(arc
		(start 140.087604 -284.293818)
		(mid 140.269855 -284.243468)
		(end 140.453364 -284.288992)
		(width 0.0889)
		(layer "In2.Cu")
		(net "M_I_CPU1_SB_DQ<18>")
	)
	(arc
		(start 132.941822 -284.293818)
		(mid 133.224778 -284.369995)
		(end 133.507734 -284.293818)
		(width 0.0889)
		(layer "In2.Cu")
		(net "M_I_CPU1_SB_DQ<18>")
	)
	(arc
		(start 136.327642 -284.293818)
		(mid 136.509893 -284.243468)
		(end 136.693402 -284.288992)
		(width 0.0889)
		(layer "In2.Cu")
		(net "M_I_CPU1_SB_DQ<18>")
	)
	(arc
		(start 139.147804 -284.293818)
		(mid 139.334748 -284.243563)
		(end 139.521692 -284.293818)
		(width 0.0889)
		(layer "In2.Cu")
		(net "M_I_CPU1_SB_DQ<18>")
	)
	(arc
		(start 133.516116 -284.288992)
		(mid 133.699624 -284.243498)
		(end 133.881876 -284.293818)
		(width 0.0889)
		(layer "In2.Cu")
		(net "M_I_CPU1_SB_DQ<18>")
	)
	(arc
		(start 135.387588 -284.293818)
		(mid 135.569839 -284.243468)
		(end 135.753348 -284.288992)
		(width 0.0889)
		(layer "In2.Cu")
		(net "M_I_CPU1_SB_DQ<18>")
	)
	(arc
		(start 143.847566 -284.293818)
		(mid 144.029817 -284.243468)
		(end 144.213326 -284.288992)
		(width 0.0889)
		(layer "In2.Cu")
		(net "M_I_CPU1_SB_DQ<18>")
	)
	(arc
		(start 133.881876 -284.293818)
		(mid 134.164832 -284.369995)
		(end 134.447788 -284.293818)
		(width 0.0889)
		(layer "In2.Cu")
		(net "M_I_CPU1_SB_DQ<18>")
	)
	(arc
		(start 142.341854 -284.293818)
		(mid 142.62481 -284.369995)
		(end 142.907766 -284.293818)
		(width 0.0889)
		(layer "In2.Cu")
		(net "M_I_CPU1_SB_DQ<18>")
	)
	(arc
		(start 131.627626 -284.293818)
		(mid 131.809877 -284.243468)
		(end 131.993386 -284.288992)
		(width 0.0889)
		(layer "In2.Cu")
		(net "M_I_CPU1_SB_DQ<18>")
	)
	(arc
		(start 141.4018 -284.293818)
		(mid 141.684756 -284.369995)
		(end 141.967712 -284.293818)
		(width 0.0889)
		(layer "In2.Cu")
		(net "M_I_CPU1_SB_DQ<18>")
	)
	(segment
		(start 127.58801 -284.35046)
		(end 128.054862 -284.616398)
		(width 0.10668)
		(layer "F.Cu")
		(net "M_I_CPU1_SB_DQ<17>")
	)
	(segment
		(start 156.165042 -296.024554)
		(end 156.393642 -296.024554)
		(width 0.14478)
		(layer "In2.Cu")
		(net "M_I_CPU1_SB_DQ<17>")
	)
	(segment
		(start 156.003498 -295.86301)
		(end 156.165042 -296.024554)
		(width 0.14478)
		(layer "In2.Cu")
		(net "M_I_CPU1_SB_DQ<17>")
	)
	(segment
		(start 178.359816 -301.647606)
		(end 179.301394 -301.460408)
		(width 0.14478)
		(layer "In2.Cu")
		(net "M_I_CPU1_SB_DQ<17>")
	)
	(segment
		(start 156.94533 -296.804842)
		(end 157.17393 -296.804842)
		(width 0.14478)
		(layer "In2.Cu")
		(net "M_I_CPU1_SB_DQ<17>")
	)
	(segment
		(start 131.993386 -284.943804)
		(end 132.001768 -284.938978)
		(width 0.0889)
		(layer "In2.Cu")
		(net "M_I_CPU1_SB_DQ<17>")
	)
	(segment
		(start 173.392846 -301.78883)
		(end 175.043592 -301.460408)
		(width 0.14478)
		(layer "In2.Cu")
		(net "M_I_CPU1_SB_DQ<17>")
	)
	(segment
		(start 156.8577 -295.789096)
		(end 157.019244 -295.95064)
		(width 0.14478)
		(layer "In2.Cu")
		(net "M_I_CPU1_SB_DQ<17>")
	)
	(segment
		(start 163.378896 -302.310292)
		(end 165.040818 -302.310292)
		(width 0.14478)
		(layer "In2.Cu")
		(net "M_I_CPU1_SB_DQ<17>")
	)
	(segment
		(start 156.6291 -295.789096)
		(end 156.8577 -295.789096)
		(width 0.14478)
		(layer "In2.Cu")
		(net "M_I_CPU1_SB_DQ<17>")
	)
	(segment
		(start 150.79345 -289.121342)
		(end 151.876506 -291.736018)
		(width 0.14478)
		(layer "In2.Cu")
		(net "M_I_CPU1_SB_DQ<17>")
	)
	(segment
		(start 171.720002 -302.310292)
		(end 172.133768 -302.310292)
		(width 0.14478)
		(layer "In2.Cu")
		(net "M_I_CPU1_SB_DQ<17>")
	)
	(segment
		(start 138.20775 -284.938978)
		(end 138.216132 -284.943804)
		(width 0.0889)
		(layer "In2.Cu")
		(net "M_I_CPU1_SB_DQ<17>")
	)
	(segment
		(start 135.753348 -284.943804)
		(end 135.76173 -284.938978)
		(width 0.0889)
		(layer "In2.Cu")
		(net "M_I_CPU1_SB_DQ<17>")
	)
	(segment
		(start 176.804066 -301.460408)
		(end 177.745644 -301.647606)
		(width 0.14478)
		(layer "In2.Cu")
		(net "M_I_CPU1_SB_DQ<17>")
	)
	(segment
		(start 140.453364 -284.943804)
		(end 140.461746 -284.938978)
		(width 0.0889)
		(layer "In2.Cu")
		(net "M_I_CPU1_SB_DQ<17>")
	)
	(segment
		(start 157.409388 -296.569384)
		(end 157.637988 -296.569384)
		(width 0.14478)
		(layer "In2.Cu")
		(net "M_I_CPU1_SB_DQ<17>")
	)
	(segment
		(start 145.854928 -284.959298)
		(end 146.213322 -285.317692)
		(width 0.0889)
		(layer "In2.Cu")
		(net "M_I_CPU1_SB_DQ<17>")
	)
	(segment
		(start 144.784318 -284.938978)
		(end 144.804892 -284.950916)
		(width 0.0889)
		(layer "In2.Cu")
		(net "M_I_CPU1_SB_DQ<17>")
	)
	(segment
		(start 172.133768 -302.310292)
		(end 173.392846 -301.78883)
		(width 0.14478)
		(layer "In2.Cu")
		(net "M_I_CPU1_SB_DQ<17>")
	)
	(segment
		(start 128.208786 -284.881828)
		(end 128.304798 -284.907228)
		(width 0.0889)
		(layer "In2.Cu")
		(net "M_I_CPU1_SB_DQ<17>")
	)
	(segment
		(start 156.783786 -296.414698)
		(end 156.783786 -296.643298)
		(width 0.14478)
		(layer "In2.Cu")
		(net "M_I_CPU1_SB_DQ<17>")
	)
	(segment
		(start 156.238956 -295.170352)
		(end 156.238956 -295.398952)
		(width 0.14478)
		(layer "In2.Cu")
		(net "M_I_CPU1_SB_DQ<17>")
	)
	(segment
		(start 155.384754 -295.244266)
		(end 155.613354 -295.244266)
		(width 0.14478)
		(layer "In2.Cu")
		(net "M_I_CPU1_SB_DQ<17>")
	)
	(segment
		(start 141.967712 -284.938978)
		(end 141.976094 -284.943804)
		(width 0.0889)
		(layer "In2.Cu")
		(net "M_I_CPU1_SB_DQ<17>")
	)
	(segment
		(start 175.043592 -301.460408)
		(end 176.804066 -301.460408)
		(width 0.14478)
		(layer "In2.Cu")
		(net "M_I_CPU1_SB_DQ<17>")
	)
	(segment
		(start 156.238956 -295.398952)
		(end 156.003498 -295.63441)
		(width 0.14478)
		(layer "In2.Cu")
		(net "M_I_CPU1_SB_DQ<17>")
	)
	(segment
		(start 156.077412 -295.008808)
		(end 156.238956 -295.170352)
		(width 0.14478)
		(layer "In2.Cu")
		(net "M_I_CPU1_SB_DQ<17>")
	)
	(segment
		(start 157.17393 -296.804842)
		(end 157.409388 -296.569384)
		(width 0.14478)
		(layer "In2.Cu")
		(net "M_I_CPU1_SB_DQ<17>")
	)
	(segment
		(start 157.637988 -296.569384)
		(end 163.378896 -302.310292)
		(width 0.14478)
		(layer "In2.Cu")
		(net "M_I_CPU1_SB_DQ<17>")
	)
	(segment
		(start 145.63725 -284.869128)
		(end 145.854928 -284.959298)
		(width 0.0889)
		(layer "In2.Cu")
		(net "M_I_CPU1_SB_DQ<17>")
	)
	(segment
		(start 183.19115 -301.460408)
		(end 183.616092 -301.88535)
		(width 0.14478)
		(layer "In2.Cu")
		(net "M_I_CPU1_SB_DQ<17>")
	)
	(segment
		(start 169.668444 -301.460408)
		(end 171.720002 -302.310292)
		(width 0.14478)
		(layer "In2.Cu")
		(net "M_I_CPU1_SB_DQ<17>")
	)
	(segment
		(start 129.747772 -284.938978)
		(end 129.756154 -284.943804)
		(width 0.0889)
		(layer "In2.Cu")
		(net "M_I_CPU1_SB_DQ<17>")
	)
	(segment
		(start 155.613354 -295.244266)
		(end 155.848812 -295.008808)
		(width 0.14478)
		(layer "In2.Cu")
		(net "M_I_CPU1_SB_DQ<17>")
	)
	(segment
		(start 128.807718 -284.938978)
		(end 128.8161 -284.943804)
		(width 0.0889)
		(layer "In2.Cu")
		(net "M_I_CPU1_SB_DQ<17>")
	)
	(segment
		(start 165.040818 -302.310292)
		(end 167.09263 -301.460408)
		(width 0.14478)
		(layer "In2.Cu")
		(net "M_I_CPU1_SB_DQ<17>")
	)
	(segment
		(start 146.213322 -285.317692)
		(end 146.9898 -285.317692)
		(width 0.0889)
		(layer "In2.Cu")
		(net "M_I_CPU1_SB_DQ<17>")
	)
	(segment
		(start 156.003498 -295.63441)
		(end 156.003498 -295.86301)
		(width 0.14478)
		(layer "In2.Cu")
		(net "M_I_CPU1_SB_DQ<17>")
	)
	(segment
		(start 179.301394 -301.460408)
		(end 183.19115 -301.460408)
		(width 0.14478)
		(layer "In2.Cu")
		(net "M_I_CPU1_SB_DQ<17>")
	)
	(segment
		(start 147.90674 -286.234632)
		(end 150.79345 -289.121342)
		(width 0.14478)
		(layer "In2.Cu")
		(net "M_I_CPU1_SB_DQ<17>")
	)
	(segment
		(start 141.393418 -284.943804)
		(end 141.4018 -284.938978)
		(width 0.0889)
		(layer "In2.Cu")
		(net "M_I_CPU1_SB_DQ<17>")
	)
	(segment
		(start 146.9898 -285.317692)
		(end 147.90674 -286.234632)
		(width 0.0889)
		(layer "In2.Cu")
		(net "M_I_CPU1_SB_DQ<17>")
	)
	(segment
		(start 132.93344 -284.943804)
		(end 132.941822 -284.938978)
		(width 0.0889)
		(layer "In2.Cu")
		(net "M_I_CPU1_SB_DQ<17>")
	)
	(segment
		(start 155.848812 -295.008808)
		(end 156.077412 -295.008808)
		(width 0.14478)
		(layer "In2.Cu")
		(net "M_I_CPU1_SB_DQ<17>")
	)
	(segment
		(start 167.09263 -301.460408)
		(end 169.668444 -301.460408)
		(width 0.14478)
		(layer "In2.Cu")
		(net "M_I_CPU1_SB_DQ<17>")
	)
	(segment
		(start 137.267696 -284.938978)
		(end 137.276078 -284.943804)
		(width 0.0889)
		(layer "In2.Cu")
		(net "M_I_CPU1_SB_DQ<17>")
	)
	(segment
		(start 156.393642 -296.024554)
		(end 156.6291 -295.789096)
		(width 0.14478)
		(layer "In2.Cu")
		(net "M_I_CPU1_SB_DQ<17>")
	)
	(segment
		(start 157.019244 -296.17924)
		(end 156.783786 -296.414698)
		(width 0.14478)
		(layer "In2.Cu")
		(net "M_I_CPU1_SB_DQ<17>")
	)
	(segment
		(start 145.15973 -284.938978)
		(end 145.159984 -284.939232)
		(width 0.0889)
		(layer "In2.Cu")
		(net "M_I_CPU1_SB_DQ<17>")
	)
	(segment
		(start 136.693402 -284.943804)
		(end 136.701784 -284.938978)
		(width 0.0889)
		(layer "In2.Cu")
		(net "M_I_CPU1_SB_DQ<17>")
	)
	(segment
		(start 177.745644 -301.647606)
		(end 178.359816 -301.647606)
		(width 0.14478)
		(layer "In2.Cu")
		(net "M_I_CPU1_SB_DQ<17>")
	)
	(segment
		(start 133.507734 -284.938978)
		(end 133.516116 -284.943804)
		(width 0.0889)
		(layer "In2.Cu")
		(net "M_I_CPU1_SB_DQ<17>")
	)
	(segment
		(start 156.783786 -296.643298)
		(end 156.94533 -296.804842)
		(width 0.14478)
		(layer "In2.Cu")
		(net "M_I_CPU1_SB_DQ<17>")
	)
	(segment
		(start 157.019244 -295.95064)
		(end 157.019244 -296.17924)
		(width 0.14478)
		(layer "In2.Cu")
		(net "M_I_CPU1_SB_DQ<17>")
	)
	(segment
		(start 145.357342 -284.869128)
		(end 145.63725 -284.869128)
		(width 0.0889)
		(layer "In2.Cu")
		(net "M_I_CPU1_SB_DQ<17>")
	)
	(segment
		(start 144.220438 -284.938724)
		(end 144.2466 -284.923738)
		(width 0.0889)
		(layer "In2.Cu")
		(net "M_I_CPU1_SB_DQ<17>")
	)
	(segment
		(start 151.876506 -291.736018)
		(end 155.384754 -295.244266)
		(width 0.14478)
		(layer "In2.Cu")
		(net "M_I_CPU1_SB_DQ<17>")
	)
	(segment
		(start 128.054862 -284.616398)
		(end 128.208786 -284.881828)
		(width 0.0889)
		(layer "In2.Cu")
		(net "M_I_CPU1_SB_DQ<17>")
	)
	(segment
		(start 144.19707 -284.952186)
		(end 144.220438 -284.938724)
		(width 0.0889)
		(layer "In2.Cu")
		(net "M_I_CPU1_SB_DQ<17>")
	)
	(arc
		(start 137.276078 -284.943804)
		(mid 137.459586 -284.989298)
		(end 137.641838 -284.938978)
		(width 0.0889)
		(layer "In2.Cu")
		(net "M_I_CPU1_SB_DQ<17>")
	)
	(arc
		(start 139.147804 -284.938978)
		(mid 139.334748 -284.989233)
		(end 139.521692 -284.938978)
		(width 0.0889)
		(layer "In2.Cu")
		(net "M_I_CPU1_SB_DQ<17>")
	)
	(arc
		(start 128.8161 -284.943804)
		(mid 128.999608 -284.989298)
		(end 129.18186 -284.938978)
		(width 0.0889)
		(layer "In2.Cu")
		(net "M_I_CPU1_SB_DQ<17>")
	)
	(arc
		(start 141.4018 -284.938978)
		(mid 141.684756 -284.862801)
		(end 141.967712 -284.938978)
		(width 0.0889)
		(layer "In2.Cu")
		(net "M_I_CPU1_SB_DQ<17>")
	)
	(arc
		(start 133.516116 -284.943804)
		(mid 133.699624 -284.989298)
		(end 133.881876 -284.938978)
		(width 0.0889)
		(layer "In2.Cu")
		(net "M_I_CPU1_SB_DQ<17>")
	)
	(arc
		(start 128.304798 -284.907228)
		(mid 128.560006 -284.863751)
		(end 128.807718 -284.938978)
		(width 0.0889)
		(layer "In2.Cu")
		(net "M_I_CPU1_SB_DQ<17>")
	)
	(arc
		(start 140.087604 -284.938978)
		(mid 140.269855 -284.989328)
		(end 140.453364 -284.943804)
		(width 0.0889)
		(layer "In2.Cu")
		(net "M_I_CPU1_SB_DQ<17>")
	)
	(arc
		(start 137.641838 -284.938978)
		(mid 137.924794 -284.862801)
		(end 138.20775 -284.938978)
		(width 0.0889)
		(layer "In2.Cu")
		(net "M_I_CPU1_SB_DQ<17>")
	)
	(arc
		(start 143.847566 -284.938978)
		(mid 144.020674 -284.989094)
		(end 144.19707 -284.952186)
		(width 0.0889)
		(layer "In2.Cu")
		(net "M_I_CPU1_SB_DQ<17>")
	)
	(arc
		(start 144.2466 -284.923738)
		(mid 144.517386 -284.863092)
		(end 144.784318 -284.938978)
		(width 0.0889)
		(layer "In2.Cu")
		(net "M_I_CPU1_SB_DQ<17>")
	)
	(arc
		(start 133.881876 -284.938978)
		(mid 134.164832 -284.862801)
		(end 134.447788 -284.938978)
		(width 0.0889)
		(layer "In2.Cu")
		(net "M_I_CPU1_SB_DQ<17>")
	)
	(arc
		(start 129.756154 -284.943804)
		(mid 129.939662 -284.989298)
		(end 130.121914 -284.938978)
		(width 0.0889)
		(layer "In2.Cu")
		(net "M_I_CPU1_SB_DQ<17>")
	)
	(arc
		(start 129.18186 -284.938978)
		(mid 129.464816 -284.862801)
		(end 129.747772 -284.938978)
		(width 0.0889)
		(layer "In2.Cu")
		(net "M_I_CPU1_SB_DQ<17>")
	)
	(arc
		(start 138.581892 -284.938978)
		(mid 138.864848 -284.862801)
		(end 139.147804 -284.938978)
		(width 0.0889)
		(layer "In2.Cu")
		(net "M_I_CPU1_SB_DQ<17>")
	)
	(arc
		(start 130.121914 -284.938978)
		(mid 130.40487 -284.862801)
		(end 130.687826 -284.938978)
		(width 0.0889)
		(layer "In2.Cu")
		(net "M_I_CPU1_SB_DQ<17>")
	)
	(arc
		(start 145.159984 -284.939232)
		(mid 145.255384 -284.89495)
		(end 145.357342 -284.869128)
		(width 0.0889)
		(layer "In2.Cu")
		(net "M_I_CPU1_SB_DQ<17>")
	)
	(arc
		(start 141.027658 -284.938978)
		(mid 141.209909 -284.989328)
		(end 141.393418 -284.943804)
		(width 0.0889)
		(layer "In2.Cu")
		(net "M_I_CPU1_SB_DQ<17>")
	)
	(arc
		(start 132.56768 -284.938978)
		(mid 132.749931 -284.989328)
		(end 132.93344 -284.943804)
		(width 0.0889)
		(layer "In2.Cu")
		(net "M_I_CPU1_SB_DQ<17>")
	)
	(arc
		(start 130.687826 -284.938978)
		(mid 130.87477 -284.989233)
		(end 131.061714 -284.938978)
		(width 0.0889)
		(layer "In2.Cu")
		(net "M_I_CPU1_SB_DQ<17>")
	)
	(arc
		(start 135.76173 -284.938978)
		(mid 136.044686 -284.862801)
		(end 136.327642 -284.938978)
		(width 0.0889)
		(layer "In2.Cu")
		(net "M_I_CPU1_SB_DQ<17>")
	)
	(arc
		(start 140.461746 -284.938978)
		(mid 140.744702 -284.862801)
		(end 141.027658 -284.938978)
		(width 0.0889)
		(layer "In2.Cu")
		(net "M_I_CPU1_SB_DQ<17>")
	)
	(arc
		(start 144.804892 -284.950916)
		(mid 144.98382 -284.989793)
		(end 145.15973 -284.938978)
		(width 0.0889)
		(layer "In2.Cu")
		(net "M_I_CPU1_SB_DQ<17>")
	)
	(arc
		(start 135.387588 -284.938978)
		(mid 135.569839 -284.989328)
		(end 135.753348 -284.943804)
		(width 0.0889)
		(layer "In2.Cu")
		(net "M_I_CPU1_SB_DQ<17>")
	)
	(arc
		(start 139.521692 -284.938978)
		(mid 139.804648 -284.862801)
		(end 140.087604 -284.938978)
		(width 0.0889)
		(layer "In2.Cu")
		(net "M_I_CPU1_SB_DQ<17>")
	)
	(arc
		(start 138.216132 -284.943804)
		(mid 138.39964 -284.989298)
		(end 138.581892 -284.938978)
		(width 0.0889)
		(layer "In2.Cu")
		(net "M_I_CPU1_SB_DQ<17>")
	)
	(arc
		(start 142.341854 -284.938978)
		(mid 142.62481 -284.862801)
		(end 142.907766 -284.938978)
		(width 0.0889)
		(layer "In2.Cu")
		(net "M_I_CPU1_SB_DQ<17>")
	)
	(arc
		(start 143.281654 -284.938978)
		(mid 143.56461 -284.862801)
		(end 143.847566 -284.938978)
		(width 0.0889)
		(layer "In2.Cu")
		(net "M_I_CPU1_SB_DQ<17>")
	)
	(arc
		(start 131.061714 -284.938978)
		(mid 131.34467 -284.862801)
		(end 131.627626 -284.938978)
		(width 0.0889)
		(layer "In2.Cu")
		(net "M_I_CPU1_SB_DQ<17>")
	)
	(arc
		(start 134.821676 -284.938978)
		(mid 135.104632 -284.862801)
		(end 135.387588 -284.938978)
		(width 0.0889)
		(layer "In2.Cu")
		(net "M_I_CPU1_SB_DQ<17>")
	)
	(arc
		(start 136.701784 -284.938978)
		(mid 136.98474 -284.862801)
		(end 137.267696 -284.938978)
		(width 0.0889)
		(layer "In2.Cu")
		(net "M_I_CPU1_SB_DQ<17>")
	)
	(arc
		(start 142.907766 -284.938978)
		(mid 143.09471 -284.989233)
		(end 143.281654 -284.938978)
		(width 0.0889)
		(layer "In2.Cu")
		(net "M_I_CPU1_SB_DQ<17>")
	)
	(arc
		(start 136.327642 -284.938978)
		(mid 136.509893 -284.989328)
		(end 136.693402 -284.943804)
		(width 0.0889)
		(layer "In2.Cu")
		(net "M_I_CPU1_SB_DQ<17>")
	)
	(arc
		(start 134.447788 -284.938978)
		(mid 134.634732 -284.989233)
		(end 134.821676 -284.938978)
		(width 0.0889)
		(layer "In2.Cu")
		(net "M_I_CPU1_SB_DQ<17>")
	)
	(arc
		(start 141.976094 -284.943804)
		(mid 142.159602 -284.989298)
		(end 142.341854 -284.938978)
		(width 0.0889)
		(layer "In2.Cu")
		(net "M_I_CPU1_SB_DQ<17>")
	)
	(arc
		(start 132.001768 -284.938978)
		(mid 132.284724 -284.862801)
		(end 132.56768 -284.938978)
		(width 0.0889)
		(layer "In2.Cu")
		(net "M_I_CPU1_SB_DQ<17>")
	)
	(arc
		(start 132.941822 -284.938978)
		(mid 133.224778 -284.862801)
		(end 133.507734 -284.938978)
		(width 0.0889)
		(layer "In2.Cu")
		(net "M_I_CPU1_SB_DQ<17>")
	)
	(arc
		(start 131.627626 -284.938978)
		(mid 131.809877 -284.989328)
		(end 131.993386 -284.943804)
		(width 0.0889)
		(layer "In2.Cu")
		(net "M_I_CPU1_SB_DQ<17>")
	)
	(segment
		(start 128.997964 -283.540454)
		(end 129.464816 -283.806392)
		(width 0.10668)
		(layer "F.Cu")
		(net "M_I_CPU1_SB_DQ<16>")
	)
	(segment
		(start 143.377666 -284.128972)
		(end 143.386048 -284.133798)
		(width 0.0889)
		(layer "In2.Cu")
		(net "M_I_CPU1_SB_DQ<16>")
	)
	(segment
		(start 154.935682 -291.775896)
		(end 154.935682 -292.532308)
		(width 0.14478)
		(layer "In2.Cu")
		(net "M_I_CPU1_SB_DQ<16>")
	)
	(segment
		(start 145.887948 -284.179518)
		(end 146.449034 -284.740604)
		(width 0.0889)
		(layer "In2.Cu")
		(net "M_I_CPU1_SB_DQ<16>")
	)
	(segment
		(start 152.389586 -289.809682)
		(end 152.389586 -290.037774)
		(width 0.14478)
		(layer "In2.Cu")
		(net "M_I_CPU1_SB_DQ<16>")
	)
	(segment
		(start 153.345896 -290.414202)
		(end 153.169874 -290.58997)
		(width 0.14478)
		(layer "In2.Cu")
		(net "M_I_CPU1_SB_DQ<16>")
	)
	(segment
		(start 181.854094 -300.383702)
		(end 181.854094 -299.92193)
		(width 0.14478)
		(layer "In2.Cu")
		(net "M_I_CPU1_SB_DQ<16>")
	)
	(segment
		(start 181.69255 -300.545246)
		(end 181.854094 -300.383702)
		(width 0.14478)
		(layer "In2.Cu")
		(net "M_I_CPU1_SB_DQ<16>")
	)
	(segment
		(start 139.04341 -284.133798)
		(end 139.051792 -284.128972)
		(width 0.0889)
		(layer "In2.Cu")
		(net "M_I_CPU1_SB_DQ<16>")
	)
	(segment
		(start 153.169874 -290.818062)
		(end 153.331926 -290.980114)
		(width 0.14478)
		(layer "In2.Cu")
		(net "M_I_CPU1_SB_DQ<16>")
	)
	(segment
		(start 153.331926 -290.980114)
		(end 153.560272 -290.980114)
		(width 0.14478)
		(layer "In2.Cu")
		(net "M_I_CPU1_SB_DQ<16>")
	)
	(segment
		(start 183.19115 -299.760386)
		(end 183.616092 -300.185328)
		(width 0.14478)
		(layer "In2.Cu")
		(net "M_I_CPU1_SB_DQ<16>")
	)
	(segment
		(start 153.950162 -291.59835)
		(end 154.112214 -291.760402)
		(width 0.14478)
		(layer "In2.Cu")
		(net "M_I_CPU1_SB_DQ<16>")
	)
	(segment
		(start 147.90039 -284.740604)
		(end 152.565608 -289.405822)
		(width 0.14478)
		(layer "In2.Cu")
		(net "M_I_CPU1_SB_DQ<16>")
	)
	(segment
		(start 145.24228 -284.119574)
		(end 145.258028 -284.128718)
		(width 0.0889)
		(layer "In2.Cu")
		(net "M_I_CPU1_SB_DQ<16>")
	)
	(segment
		(start 140.557758 -284.128972)
		(end 140.56614 -284.133798)
		(width 0.0889)
		(layer "In2.Cu")
		(net "M_I_CPU1_SB_DQ<16>")
	)
	(segment
		(start 145.258028 -284.128718)
		(end 145.276316 -284.139132)
		(width 0.0889)
		(layer "In2.Cu")
		(net "M_I_CPU1_SB_DQ<16>")
	)
	(segment
		(start 178.056032 -299.760386)
		(end 181.141116 -299.760386)
		(width 0.14478)
		(layer "In2.Cu")
		(net "M_I_CPU1_SB_DQ<16>")
	)
	(segment
		(start 169.562018 -299.760386)
		(end 171.61383 -300.61027)
		(width 0.14478)
		(layer "In2.Cu")
		(net "M_I_CPU1_SB_DQ<16>")
	)
	(segment
		(start 142.803372 -284.133798)
		(end 142.811754 -284.128972)
		(width 0.0889)
		(layer "In2.Cu")
		(net "M_I_CPU1_SB_DQ<16>")
	)
	(segment
		(start 144.31772 -284.128972)
		(end 144.329404 -284.13583)
		(width 0.0889)
		(layer "In2.Cu")
		(net "M_I_CPU1_SB_DQ<16>")
	)
	(segment
		(start 154.74442 -291.584634)
		(end 154.935682 -291.775896)
		(width 0.14478)
		(layer "In2.Cu")
		(net "M_I_CPU1_SB_DQ<16>")
	)
	(segment
		(start 181.464204 -300.545246)
		(end 181.69255 -300.545246)
		(width 0.14478)
		(layer "In2.Cu")
		(net "M_I_CPU1_SB_DQ<16>")
	)
	(segment
		(start 134.917688 -284.128972)
		(end 134.92607 -284.133798)
		(width 0.0889)
		(layer "In2.Cu")
		(net "M_I_CPU1_SB_DQ<16>")
	)
	(segment
		(start 145.444718 -284.179518)
		(end 145.887948 -284.179518)
		(width 0.0889)
		(layer "In2.Cu")
		(net "M_I_CPU1_SB_DQ<16>")
	)
	(segment
		(start 134.343394 -284.133798)
		(end 134.351776 -284.128972)
		(width 0.0889)
		(layer "In2.Cu")
		(net "M_I_CPU1_SB_DQ<16>")
	)
	(segment
		(start 181.30266 -300.383702)
		(end 181.464204 -300.545246)
		(width 0.14478)
		(layer "In2.Cu")
		(net "M_I_CPU1_SB_DQ<16>")
	)
	(segment
		(start 132.09778 -284.128972)
		(end 132.106162 -284.133798)
		(width 0.0889)
		(layer "In2.Cu")
		(net "M_I_CPU1_SB_DQ<16>")
	)
	(segment
		(start 135.857742 -284.128972)
		(end 135.866124 -284.133798)
		(width 0.0889)
		(layer "In2.Cu")
		(net "M_I_CPU1_SB_DQ<16>")
	)
	(segment
		(start 163.013644 -300.61027)
		(end 164.615622 -300.61027)
		(width 0.14478)
		(layer "In2.Cu")
		(net "M_I_CPU1_SB_DQ<16>")
	)
	(segment
		(start 146.449034 -284.740604)
		(end 147.90039 -284.740604)
		(width 0.0889)
		(layer "In2.Cu")
		(net "M_I_CPU1_SB_DQ<16>")
	)
	(segment
		(start 172.443394 -300.61027)
		(end 174.495206 -299.760386)
		(width 0.14478)
		(layer "In2.Cu")
		(net "M_I_CPU1_SB_DQ<16>")
	)
	(segment
		(start 177.001932 -299.760386)
		(end 177.233834 -299.528484)
		(width 0.14478)
		(layer "In2.Cu")
		(net "M_I_CPU1_SB_DQ<16>")
	)
	(segment
		(start 154.34056 -291.760402)
		(end 154.516328 -291.584634)
		(width 0.14478)
		(layer "In2.Cu")
		(net "M_I_CPU1_SB_DQ<16>")
	)
	(segment
		(start 181.854094 -299.92193)
		(end 182.015638 -299.760386)
		(width 0.14478)
		(layer "In2.Cu")
		(net "M_I_CPU1_SB_DQ<16>")
	)
	(segment
		(start 177.82413 -299.528484)
		(end 178.056032 -299.760386)
		(width 0.14478)
		(layer "In2.Cu")
		(net "M_I_CPU1_SB_DQ<16>")
	)
	(segment
		(start 130.583432 -284.133798)
		(end 130.591814 -284.128972)
		(width 0.0889)
		(layer "In2.Cu")
		(net "M_I_CPU1_SB_DQ<16>")
	)
	(segment
		(start 182.015638 -299.760386)
		(end 183.19115 -299.760386)
		(width 0.14478)
		(layer "In2.Cu")
		(net "M_I_CPU1_SB_DQ<16>")
	)
	(segment
		(start 154.516328 -291.584634)
		(end 154.74442 -291.584634)
		(width 0.14478)
		(layer "In2.Cu")
		(net "M_I_CPU1_SB_DQ<16>")
	)
	(segment
		(start 152.565608 -289.405822)
		(end 152.565608 -289.633914)
		(width 0.14478)
		(layer "In2.Cu")
		(net "M_I_CPU1_SB_DQ<16>")
	)
	(segment
		(start 154.935682 -292.532308)
		(end 163.013644 -300.61027)
		(width 0.14478)
		(layer "In2.Cu")
		(net "M_I_CPU1_SB_DQ<16>")
	)
	(segment
		(start 153.345896 -290.18611)
		(end 153.345896 -290.414202)
		(width 0.14478)
		(layer "In2.Cu")
		(net "M_I_CPU1_SB_DQ<16>")
	)
	(segment
		(start 171.61383 -300.61027)
		(end 172.443394 -300.61027)
		(width 0.14478)
		(layer "In2.Cu")
		(net "M_I_CPU1_SB_DQ<16>")
	)
	(segment
		(start 139.617704 -284.128972)
		(end 139.626086 -284.133798)
		(width 0.0889)
		(layer "In2.Cu")
		(net "M_I_CPU1_SB_DQ<16>")
	)
	(segment
		(start 166.667434 -299.760386)
		(end 169.562018 -299.760386)
		(width 0.14478)
		(layer "In2.Cu")
		(net "M_I_CPU1_SB_DQ<16>")
	)
	(segment
		(start 129.464816 -283.806392)
		(end 129.61874 -284.071822)
		(width 0.0889)
		(layer "In2.Cu")
		(net "M_I_CPU1_SB_DQ<16>")
	)
	(segment
		(start 152.551638 -290.199826)
		(end 152.779984 -290.199826)
		(width 0.14478)
		(layer "In2.Cu")
		(net "M_I_CPU1_SB_DQ<16>")
	)
	(segment
		(start 181.141116 -299.760386)
		(end 181.30266 -299.92193)
		(width 0.14478)
		(layer "In2.Cu")
		(net "M_I_CPU1_SB_DQ<16>")
	)
	(segment
		(start 152.389586 -290.037774)
		(end 152.551638 -290.199826)
		(width 0.14478)
		(layer "In2.Cu")
		(net "M_I_CPU1_SB_DQ<16>")
	)
	(segment
		(start 177.233834 -299.528484)
		(end 177.82413 -299.528484)
		(width 0.14478)
		(layer "In2.Cu")
		(net "M_I_CPU1_SB_DQ<16>")
	)
	(segment
		(start 131.157726 -284.128972)
		(end 131.166108 -284.133798)
		(width 0.0889)
		(layer "In2.Cu")
		(net "M_I_CPU1_SB_DQ<16>")
	)
	(segment
		(start 154.126184 -290.966398)
		(end 154.126184 -291.19449)
		(width 0.14478)
		(layer "In2.Cu")
		(net "M_I_CPU1_SB_DQ<16>")
	)
	(segment
		(start 153.964132 -290.804346)
		(end 154.126184 -290.966398)
		(width 0.14478)
		(layer "In2.Cu")
		(net "M_I_CPU1_SB_DQ<16>")
	)
	(segment
		(start 164.615622 -300.61027)
		(end 166.667434 -299.760386)
		(width 0.14478)
		(layer "In2.Cu")
		(net "M_I_CPU1_SB_DQ<16>")
	)
	(segment
		(start 181.30266 -299.92193)
		(end 181.30266 -300.383702)
		(width 0.14478)
		(layer "In2.Cu")
		(net "M_I_CPU1_SB_DQ<16>")
	)
	(segment
		(start 152.565608 -289.633914)
		(end 152.389586 -289.809682)
		(width 0.14478)
		(layer "In2.Cu")
		(net "M_I_CPU1_SB_DQ<16>")
	)
	(segment
		(start 152.955752 -290.024058)
		(end 153.183844 -290.024058)
		(width 0.14478)
		(layer "In2.Cu")
		(net "M_I_CPU1_SB_DQ<16>")
	)
	(segment
		(start 153.169874 -290.58997)
		(end 153.169874 -290.818062)
		(width 0.14478)
		(layer "In2.Cu")
		(net "M_I_CPU1_SB_DQ<16>")
	)
	(segment
		(start 153.950162 -291.370258)
		(end 153.950162 -291.59835)
		(width 0.14478)
		(layer "In2.Cu")
		(net "M_I_CPU1_SB_DQ<16>")
	)
	(segment
		(start 174.495206 -299.760386)
		(end 177.001932 -299.760386)
		(width 0.14478)
		(layer "In2.Cu")
		(net "M_I_CPU1_SB_DQ<16>")
	)
	(segment
		(start 138.103356 -284.133798)
		(end 138.111738 -284.128972)
		(width 0.0889)
		(layer "In2.Cu")
		(net "M_I_CPU1_SB_DQ<16>")
	)
	(segment
		(start 153.183844 -290.024058)
		(end 153.345896 -290.18611)
		(width 0.14478)
		(layer "In2.Cu")
		(net "M_I_CPU1_SB_DQ<16>")
	)
	(segment
		(start 154.112214 -291.760402)
		(end 154.34056 -291.760402)
		(width 0.14478)
		(layer "In2.Cu")
		(net "M_I_CPU1_SB_DQ<16>")
	)
	(segment
		(start 154.126184 -291.19449)
		(end 153.950162 -291.370258)
		(width 0.14478)
		(layer "In2.Cu")
		(net "M_I_CPU1_SB_DQ<16>")
	)
	(segment
		(start 153.73604 -290.804346)
		(end 153.964132 -290.804346)
		(width 0.14478)
		(layer "In2.Cu")
		(net "M_I_CPU1_SB_DQ<16>")
	)
	(segment
		(start 152.779984 -290.199826)
		(end 152.955752 -290.024058)
		(width 0.14478)
		(layer "In2.Cu")
		(net "M_I_CPU1_SB_DQ<16>")
	)
	(segment
		(start 153.560272 -290.980114)
		(end 153.73604 -290.804346)
		(width 0.14478)
		(layer "In2.Cu")
		(net "M_I_CPU1_SB_DQ<16>")
	)
	(segment
		(start 129.61874 -284.071822)
		(end 129.714752 -284.097222)
		(width 0.0889)
		(layer "In2.Cu")
		(net "M_I_CPU1_SB_DQ<16>")
	)
	(arc
		(start 141.8717 -284.128972)
		(mid 142.154656 -284.052795)
		(end 142.437612 -284.128972)
		(width 0.0889)
		(layer "In2.Cu")
		(net "M_I_CPU1_SB_DQ<16>")
	)
	(arc
		(start 140.9319 -284.128972)
		(mid 141.214856 -284.052795)
		(end 141.497812 -284.128972)
		(width 0.0889)
		(layer "In2.Cu")
		(net "M_I_CPU1_SB_DQ<16>")
	)
	(arc
		(start 130.217672 -284.128972)
		(mid 130.399923 -284.179322)
		(end 130.583432 -284.133798)
		(width 0.0889)
		(layer "In2.Cu")
		(net "M_I_CPU1_SB_DQ<16>")
	)
	(arc
		(start 134.92607 -284.133798)
		(mid 135.109578 -284.179292)
		(end 135.29183 -284.128972)
		(width 0.0889)
		(layer "In2.Cu")
		(net "M_I_CPU1_SB_DQ<16>")
	)
	(arc
		(start 132.106162 -284.133798)
		(mid 132.28967 -284.179292)
		(end 132.471922 -284.128972)
		(width 0.0889)
		(layer "In2.Cu")
		(net "M_I_CPU1_SB_DQ<16>")
	)
	(arc
		(start 143.751808 -284.128972)
		(mid 144.034764 -284.052795)
		(end 144.31772 -284.128972)
		(width 0.0889)
		(layer "In2.Cu")
		(net "M_I_CPU1_SB_DQ<16>")
	)
	(arc
		(start 138.67765 -284.128972)
		(mid 138.859901 -284.179322)
		(end 139.04341 -284.133798)
		(width 0.0889)
		(layer "In2.Cu")
		(net "M_I_CPU1_SB_DQ<16>")
	)
	(arc
		(start 140.56614 -284.133798)
		(mid 140.749648 -284.179292)
		(end 140.9319 -284.128972)
		(width 0.0889)
		(layer "In2.Cu")
		(net "M_I_CPU1_SB_DQ<16>")
	)
	(arc
		(start 138.111738 -284.128972)
		(mid 138.394694 -284.052795)
		(end 138.67765 -284.128972)
		(width 0.0889)
		(layer "In2.Cu")
		(net "M_I_CPU1_SB_DQ<16>")
	)
	(arc
		(start 143.386048 -284.133798)
		(mid 143.569556 -284.179292)
		(end 143.751808 -284.128972)
		(width 0.0889)
		(layer "In2.Cu")
		(net "M_I_CPU1_SB_DQ<16>")
	)
	(arc
		(start 130.591814 -284.128972)
		(mid 130.87477 -284.052795)
		(end 131.157726 -284.128972)
		(width 0.0889)
		(layer "In2.Cu")
		(net "M_I_CPU1_SB_DQ<16>")
	)
	(arc
		(start 131.166108 -284.133798)
		(mid 131.349616 -284.179292)
		(end 131.531868 -284.128972)
		(width 0.0889)
		(layer "In2.Cu")
		(net "M_I_CPU1_SB_DQ<16>")
	)
	(arc
		(start 133.037834 -284.128972)
		(mid 133.224778 -284.179227)
		(end 133.411722 -284.128972)
		(width 0.0889)
		(layer "In2.Cu")
		(net "M_I_CPU1_SB_DQ<16>")
	)
	(arc
		(start 133.977634 -284.128972)
		(mid 134.159885 -284.179322)
		(end 134.343394 -284.133798)
		(width 0.0889)
		(layer "In2.Cu")
		(net "M_I_CPU1_SB_DQ<16>")
	)
	(arc
		(start 144.692116 -284.128972)
		(mid 144.965971 -284.052622)
		(end 145.24228 -284.119574)
		(width 0.0889)
		(layer "In2.Cu")
		(net "M_I_CPU1_SB_DQ<16>")
	)
	(arc
		(start 139.991846 -284.128972)
		(mid 140.274802 -284.052795)
		(end 140.557758 -284.128972)
		(width 0.0889)
		(layer "In2.Cu")
		(net "M_I_CPU1_SB_DQ<16>")
	)
	(arc
		(start 145.276316 -284.139132)
		(mid 145.35814 -284.169245)
		(end 145.444718 -284.179518)
		(width 0.0889)
		(layer "In2.Cu")
		(net "M_I_CPU1_SB_DQ<16>")
	)
	(arc
		(start 139.051792 -284.128972)
		(mid 139.334748 -284.052795)
		(end 139.617704 -284.128972)
		(width 0.0889)
		(layer "In2.Cu")
		(net "M_I_CPU1_SB_DQ<16>")
	)
	(arc
		(start 136.797796 -284.128972)
		(mid 136.98474 -284.179227)
		(end 137.171684 -284.128972)
		(width 0.0889)
		(layer "In2.Cu")
		(net "M_I_CPU1_SB_DQ<16>")
	)
	(arc
		(start 133.411722 -284.128972)
		(mid 133.694678 -284.052795)
		(end 133.977634 -284.128972)
		(width 0.0889)
		(layer "In2.Cu")
		(net "M_I_CPU1_SB_DQ<16>")
	)
	(arc
		(start 134.351776 -284.128972)
		(mid 134.634732 -284.052795)
		(end 134.917688 -284.128972)
		(width 0.0889)
		(layer "In2.Cu")
		(net "M_I_CPU1_SB_DQ<16>")
	)
	(arc
		(start 136.231884 -284.128972)
		(mid 136.51484 -284.052795)
		(end 136.797796 -284.128972)
		(width 0.0889)
		(layer "In2.Cu")
		(net "M_I_CPU1_SB_DQ<16>")
	)
	(arc
		(start 137.171684 -284.128972)
		(mid 137.45464 -284.052795)
		(end 137.737596 -284.128972)
		(width 0.0889)
		(layer "In2.Cu")
		(net "M_I_CPU1_SB_DQ<16>")
	)
	(arc
		(start 131.531868 -284.128972)
		(mid 131.814824 -284.052795)
		(end 132.09778 -284.128972)
		(width 0.0889)
		(layer "In2.Cu")
		(net "M_I_CPU1_SB_DQ<16>")
	)
	(arc
		(start 135.866124 -284.133798)
		(mid 136.049632 -284.179292)
		(end 136.231884 -284.128972)
		(width 0.0889)
		(layer "In2.Cu")
		(net "M_I_CPU1_SB_DQ<16>")
	)
	(arc
		(start 132.471922 -284.128972)
		(mid 132.754878 -284.052795)
		(end 133.037834 -284.128972)
		(width 0.0889)
		(layer "In2.Cu")
		(net "M_I_CPU1_SB_DQ<16>")
	)
	(arc
		(start 129.714752 -284.097222)
		(mid 129.96996 -284.053745)
		(end 130.217672 -284.128972)
		(width 0.0889)
		(layer "In2.Cu")
		(net "M_I_CPU1_SB_DQ<16>")
	)
	(arc
		(start 139.626086 -284.133798)
		(mid 139.809594 -284.179292)
		(end 139.991846 -284.128972)
		(width 0.0889)
		(layer "In2.Cu")
		(net "M_I_CPU1_SB_DQ<16>")
	)
	(arc
		(start 142.811754 -284.128972)
		(mid 143.09471 -284.052795)
		(end 143.377666 -284.128972)
		(width 0.0889)
		(layer "In2.Cu")
		(net "M_I_CPU1_SB_DQ<16>")
	)
	(arc
		(start 142.437612 -284.128972)
		(mid 142.619863 -284.179322)
		(end 142.803372 -284.133798)
		(width 0.0889)
		(layer "In2.Cu")
		(net "M_I_CPU1_SB_DQ<16>")
	)
	(arc
		(start 141.497812 -284.128972)
		(mid 141.684756 -284.179227)
		(end 141.8717 -284.128972)
		(width 0.0889)
		(layer "In2.Cu")
		(net "M_I_CPU1_SB_DQ<16>")
	)
	(arc
		(start 137.737596 -284.128972)
		(mid 137.919847 -284.179322)
		(end 138.103356 -284.133798)
		(width 0.0889)
		(layer "In2.Cu")
		(net "M_I_CPU1_SB_DQ<16>")
	)
	(arc
		(start 135.29183 -284.128972)
		(mid 135.574786 -284.052795)
		(end 135.857742 -284.128972)
		(width 0.0889)
		(layer "In2.Cu")
		(net "M_I_CPU1_SB_DQ<16>")
	)
	(arc
		(start 144.329404 -284.13583)
		(mid 144.511659 -284.179483)
		(end 144.692116 -284.128972)
		(width 0.0889)
		(layer "In2.Cu")
		(net "M_I_CPU1_SB_DQ<16>")
	)
	(segment
		(start 128.05791 -283.540454)
		(end 128.524762 -283.806392)
		(width 0.10668)
		(layer "F.Cu")
		(net "M_I_CPU1_SB_DQ<15>")
	)
	(segment
		(start 147.489164 -283.99486)
		(end 147.70227 -284.207966)
		(width 0.0889)
		(layer "In2.Cu")
		(net "M_I_CPU1_SB_DQ<15>")
	)
	(segment
		(start 179.091082 -298.910502)
		(end 179.516024 -299.335444)
		(width 0.14478)
		(layer "In2.Cu")
		(net "M_I_CPU1_SB_DQ<15>")
	)
	(segment
		(start 155.641294 -291.69233)
		(end 155.641294 -291.92093)
		(width 0.14478)
		(layer "In2.Cu")
		(net "M_I_CPU1_SB_DQ<15>")
	)
	(segment
		(start 134.917688 -283.483812)
		(end 134.92607 -283.478986)
		(width 0.0889)
		(layer "In2.Cu")
		(net "M_I_CPU1_SB_DQ<15>")
	)
	(segment
		(start 134.343394 -283.478986)
		(end 134.351776 -283.483812)
		(width 0.0889)
		(layer "In2.Cu")
		(net "M_I_CPU1_SB_DQ<15>")
	)
	(segment
		(start 148.15693 -284.207966)
		(end 155.641294 -291.69233)
		(width 0.14478)
		(layer "In2.Cu")
		(net "M_I_CPU1_SB_DQ<15>")
	)
	(segment
		(start 145.373852 -283.439616)
		(end 145.774918 -283.439616)
		(width 0.0889)
		(layer "In2.Cu")
		(net "M_I_CPU1_SB_DQ<15>")
	)
	(segment
		(start 131.157726 -283.483812)
		(end 131.166108 -283.478986)
		(width 0.0889)
		(layer "In2.Cu")
		(net "M_I_CPU1_SB_DQ<15>")
	)
	(segment
		(start 167.22344 -298.910502)
		(end 167.51554 -298.910502)
		(width 0.14478)
		(layer "In2.Cu")
		(net "M_I_CPU1_SB_DQ<15>")
	)
	(segment
		(start 170.288966 -299.064934)
		(end 170.212004 -299.250608)
		(width 0.14478)
		(layer "In2.Cu")
		(net "M_I_CPU1_SB_DQ<15>")
	)
	(segment
		(start 157.20187 -293.481506)
		(end 157.047438 -293.635938)
		(width 0.14478)
		(layer "In2.Cu")
		(net "M_I_CPU1_SB_DQ<15>")
	)
	(segment
		(start 174.906178 -298.910502)
		(end 175.14062 -299.144944)
		(width 0.14478)
		(layer "In2.Cu")
		(net "M_I_CPU1_SB_DQ<15>")
	)
	(segment
		(start 175.464978 -299.144944)
		(end 175.69942 -298.910502)
		(width 0.14478)
		(layer "In2.Cu")
		(net "M_I_CPU1_SB_DQ<15>")
	)
	(segment
		(start 173.23308 -299.619162)
		(end 173.426374 -299.151548)
		(width 0.14478)
		(layer "In2.Cu")
		(net "M_I_CPU1_SB_DQ<15>")
	)
	(segment
		(start 156.26715 -293.08425)
		(end 156.428694 -293.245794)
		(width 0.14478)
		(layer "In2.Cu")
		(net "M_I_CPU1_SB_DQ<15>")
	)
	(segment
		(start 156.811726 -293.091362)
		(end 157.040326 -293.091362)
		(width 0.14478)
		(layer "In2.Cu")
		(net "M_I_CPU1_SB_DQ<15>")
	)
	(segment
		(start 138.103356 -283.478986)
		(end 138.111738 -283.483812)
		(width 0.0889)
		(layer "In2.Cu")
		(net "M_I_CPU1_SB_DQ<15>")
	)
	(segment
		(start 140.557758 -283.483812)
		(end 140.56614 -283.478986)
		(width 0.0889)
		(layer "In2.Cu")
		(net "M_I_CPU1_SB_DQ<15>")
	)
	(segment
		(start 166.106856 -299.061378)
		(end 166.482522 -299.217334)
		(width 0.14478)
		(layer "In2.Cu")
		(net "M_I_CPU1_SB_DQ<15>")
	)
	(segment
		(start 165.691566 -299.562012)
		(end 165.855904 -299.165518)
		(width 0.14478)
		(layer "In2.Cu")
		(net "M_I_CPU1_SB_DQ<15>")
	)
	(segment
		(start 173.9392 -299.18279)
		(end 174.596552 -298.910502)
		(width 0.14478)
		(layer "In2.Cu")
		(net "M_I_CPU1_SB_DQ<15>")
	)
	(segment
		(start 167.719502 -299.114464)
		(end 168.07434 -299.114464)
		(width 0.14478)
		(layer "In2.Cu")
		(net "M_I_CPU1_SB_DQ<15>")
	)
	(segment
		(start 170.20032 -298.85132)
		(end 170.288966 -299.064934)
		(width 0.14478)
		(layer "In2.Cu")
		(net "M_I_CPU1_SB_DQ<15>")
	)
	(segment
		(start 128.524762 -283.806392)
		(end 128.370838 -283.540962)
		(width 0.0889)
		(layer "In2.Cu")
		(net "M_I_CPU1_SB_DQ<15>")
	)
	(segment
		(start 155.648406 -292.465506)
		(end 155.877006 -292.465506)
		(width 0.14478)
		(layer "In2.Cu")
		(net "M_I_CPU1_SB_DQ<15>")
	)
	(segment
		(start 130.583432 -283.478986)
		(end 130.591814 -283.483812)
		(width 0.0889)
		(layer "In2.Cu")
		(net "M_I_CPU1_SB_DQ<15>")
	)
	(segment
		(start 135.857742 -283.483812)
		(end 135.866124 -283.478986)
		(width 0.0889)
		(layer "In2.Cu")
		(net "M_I_CPU1_SB_DQ<15>")
	)
	(segment
		(start 145.774918 -283.439616)
		(end 146.330162 -283.99486)
		(width 0.0889)
		(layer "In2.Cu")
		(net "M_I_CPU1_SB_DQ<15>")
	)
	(segment
		(start 129.643378 -283.478986)
		(end 129.65176 -283.483812)
		(width 0.0889)
		(layer "In2.Cu")
		(net "M_I_CPU1_SB_DQ<15>")
	)
	(segment
		(start 147.83943 -284.207966)
		(end 148.15693 -284.207966)
		(width 0.14478)
		(layer "In2.Cu")
		(net "M_I_CPU1_SB_DQ<15>")
	)
	(segment
		(start 139.617704 -283.483812)
		(end 139.626086 -283.478986)
		(width 0.0889)
		(layer "In2.Cu")
		(net "M_I_CPU1_SB_DQ<15>")
	)
	(segment
		(start 157.047438 -293.635938)
		(end 157.047438 -293.864538)
		(width 0.14478)
		(layer "In2.Cu")
		(net "M_I_CPU1_SB_DQ<15>")
	)
	(segment
		(start 156.260038 -292.311074)
		(end 156.421582 -292.472618)
		(width 0.14478)
		(layer "In2.Cu")
		(net "M_I_CPU1_SB_DQ<15>")
	)
	(segment
		(start 175.14062 -299.144944)
		(end 175.464978 -299.144944)
		(width 0.14478)
		(layer "In2.Cu")
		(net "M_I_CPU1_SB_DQ<15>")
	)
	(segment
		(start 177.393854 -298.616624)
		(end 177.658776 -298.616624)
		(width 0.14478)
		(layer "In2.Cu")
		(net "M_I_CPU1_SB_DQ<15>")
	)
	(segment
		(start 155.641294 -291.92093)
		(end 155.486862 -292.075362)
		(width 0.14478)
		(layer "In2.Cu")
		(net "M_I_CPU1_SB_DQ<15>")
	)
	(segment
		(start 142.803372 -283.478986)
		(end 142.811754 -283.483812)
		(width 0.0889)
		(layer "In2.Cu")
		(net "M_I_CPU1_SB_DQ<15>")
	)
	(segment
		(start 157.047438 -293.864538)
		(end 162.94354 -299.76064)
		(width 0.14478)
		(layer "In2.Cu")
		(net "M_I_CPU1_SB_DQ<15>")
	)
	(segment
		(start 144.289526 -283.499052)
		(end 144.315688 -283.484066)
		(width 0.0889)
		(layer "In2.Cu")
		(net "M_I_CPU1_SB_DQ<15>")
	)
	(segment
		(start 177.099976 -298.910502)
		(end 177.393854 -298.616624)
		(width 0.14478)
		(layer "In2.Cu")
		(net "M_I_CPU1_SB_DQ<15>")
	)
	(segment
		(start 156.031438 -292.311074)
		(end 156.260038 -292.311074)
		(width 0.14478)
		(layer "In2.Cu")
		(net "M_I_CPU1_SB_DQ<15>")
	)
	(segment
		(start 157.20187 -293.252906)
		(end 157.20187 -293.481506)
		(width 0.14478)
		(layer "In2.Cu")
		(net "M_I_CPU1_SB_DQ<15>")
	)
	(segment
		(start 156.428694 -293.245794)
		(end 156.657294 -293.245794)
		(width 0.14478)
		(layer "In2.Cu")
		(net "M_I_CPU1_SB_DQ<15>")
	)
	(segment
		(start 144.315688 -283.484066)
		(end 144.337532 -283.47162)
		(width 0.0889)
		(layer "In2.Cu")
		(net "M_I_CPU1_SB_DQ<15>")
	)
	(segment
		(start 168.963848 -298.910502)
		(end 169.482262 -299.125386)
		(width 0.14478)
		(layer "In2.Cu")
		(net "M_I_CPU1_SB_DQ<15>")
	)
	(segment
		(start 156.421582 -292.472618)
		(end 156.421582 -292.701218)
		(width 0.14478)
		(layer "In2.Cu")
		(net "M_I_CPU1_SB_DQ<15>")
	)
	(segment
		(start 170.30065 -299.464222)
		(end 171.016422 -299.76064)
		(width 0.14478)
		(layer "In2.Cu")
		(net "M_I_CPU1_SB_DQ<15>")
	)
	(segment
		(start 147.70227 -284.207966)
		(end 147.83943 -284.207966)
		(width 0.0889)
		(layer "In2.Cu")
		(net "M_I_CPU1_SB_DQ<15>")
	)
	(segment
		(start 172.891704 -299.76064)
		(end 173.23308 -299.619162)
		(width 0.14478)
		(layer "In2.Cu")
		(net "M_I_CPU1_SB_DQ<15>")
	)
	(segment
		(start 132.09778 -283.483812)
		(end 132.106162 -283.478986)
		(width 0.0889)
		(layer "In2.Cu")
		(net "M_I_CPU1_SB_DQ<15>")
	)
	(segment
		(start 167.51554 -298.910502)
		(end 167.719502 -299.114464)
		(width 0.14478)
		(layer "In2.Cu")
		(net "M_I_CPU1_SB_DQ<15>")
	)
	(segment
		(start 177.658776 -298.616624)
		(end 177.952654 -298.910502)
		(width 0.14478)
		(layer "In2.Cu")
		(net "M_I_CPU1_SB_DQ<15>")
	)
	(segment
		(start 171.016422 -299.76064)
		(end 172.891704 -299.76064)
		(width 0.14478)
		(layer "In2.Cu")
		(net "M_I_CPU1_SB_DQ<15>")
	)
	(segment
		(start 156.657294 -293.245794)
		(end 156.811726 -293.091362)
		(width 0.14478)
		(layer "In2.Cu")
		(net "M_I_CPU1_SB_DQ<15>")
	)
	(segment
		(start 155.486862 -292.075362)
		(end 155.486862 -292.303962)
		(width 0.14478)
		(layer "In2.Cu")
		(net "M_I_CPU1_SB_DQ<15>")
	)
	(segment
		(start 165.855904 -299.165518)
		(end 166.106856 -299.061378)
		(width 0.14478)
		(layer "In2.Cu")
		(net "M_I_CPU1_SB_DQ<15>")
	)
	(segment
		(start 144.688306 -283.483812)
		(end 144.71777 -283.501084)
		(width 0.0889)
		(layer "In2.Cu")
		(net "M_I_CPU1_SB_DQ<15>")
	)
	(segment
		(start 162.94354 -299.76064)
		(end 165.212522 -299.76064)
		(width 0.14478)
		(layer "In2.Cu")
		(net "M_I_CPU1_SB_DQ<15>")
	)
	(segment
		(start 169.695622 -299.036994)
		(end 169.772584 -298.850812)
		(width 0.14478)
		(layer "In2.Cu")
		(net "M_I_CPU1_SB_DQ<15>")
	)
	(segment
		(start 155.877006 -292.465506)
		(end 156.031438 -292.311074)
		(width 0.14478)
		(layer "In2.Cu")
		(net "M_I_CPU1_SB_DQ<15>")
	)
	(segment
		(start 169.482262 -299.125386)
		(end 169.695622 -299.036994)
		(width 0.14478)
		(layer "In2.Cu")
		(net "M_I_CPU1_SB_DQ<15>")
	)
	(segment
		(start 170.212004 -299.250608)
		(end 170.30065 -299.464222)
		(width 0.14478)
		(layer "In2.Cu")
		(net "M_I_CPU1_SB_DQ<15>")
	)
	(segment
		(start 156.421582 -292.701218)
		(end 156.26715 -292.85565)
		(width 0.14478)
		(layer "In2.Cu")
		(net "M_I_CPU1_SB_DQ<15>")
	)
	(segment
		(start 139.04341 -283.478986)
		(end 139.051792 -283.483812)
		(width 0.0889)
		(layer "In2.Cu")
		(net "M_I_CPU1_SB_DQ<15>")
	)
	(segment
		(start 166.482522 -299.217334)
		(end 167.22344 -298.910502)
		(width 0.14478)
		(layer "In2.Cu")
		(net "M_I_CPU1_SB_DQ<15>")
	)
	(segment
		(start 168.278302 -298.910502)
		(end 168.963848 -298.910502)
		(width 0.14478)
		(layer "In2.Cu")
		(net "M_I_CPU1_SB_DQ<15>")
	)
	(segment
		(start 175.69942 -298.910502)
		(end 177.099976 -298.910502)
		(width 0.14478)
		(layer "In2.Cu")
		(net "M_I_CPU1_SB_DQ<15>")
	)
	(segment
		(start 155.486862 -292.303962)
		(end 155.648406 -292.465506)
		(width 0.14478)
		(layer "In2.Cu")
		(net "M_I_CPU1_SB_DQ<15>")
	)
	(segment
		(start 173.426374 -299.151548)
		(end 173.645068 -299.06087)
		(width 0.14478)
		(layer "In2.Cu")
		(net "M_I_CPU1_SB_DQ<15>")
	)
	(segment
		(start 168.07434 -299.114464)
		(end 168.278302 -298.910502)
		(width 0.14478)
		(layer "In2.Cu")
		(net "M_I_CPU1_SB_DQ<15>")
	)
	(segment
		(start 165.212522 -299.76064)
		(end 165.691566 -299.562012)
		(width 0.14478)
		(layer "In2.Cu")
		(net "M_I_CPU1_SB_DQ<15>")
	)
	(segment
		(start 156.26715 -292.85565)
		(end 156.26715 -293.08425)
		(width 0.14478)
		(layer "In2.Cu")
		(net "M_I_CPU1_SB_DQ<15>")
	)
	(segment
		(start 169.985944 -298.76242)
		(end 170.20032 -298.85132)
		(width 0.14478)
		(layer "In2.Cu")
		(net "M_I_CPU1_SB_DQ<15>")
	)
	(segment
		(start 173.645068 -299.06087)
		(end 173.9392 -299.18279)
		(width 0.14478)
		(layer "In2.Cu")
		(net "M_I_CPU1_SB_DQ<15>")
	)
	(segment
		(start 177.952654 -298.910502)
		(end 179.091082 -298.910502)
		(width 0.14478)
		(layer "In2.Cu")
		(net "M_I_CPU1_SB_DQ<15>")
	)
	(segment
		(start 146.330162 -283.99486)
		(end 147.489164 -283.99486)
		(width 0.0889)
		(layer "In2.Cu")
		(net "M_I_CPU1_SB_DQ<15>")
	)
	(segment
		(start 143.377666 -283.483812)
		(end 143.386048 -283.478986)
		(width 0.0889)
		(layer "In2.Cu")
		(net "M_I_CPU1_SB_DQ<15>")
	)
	(segment
		(start 157.040326 -293.091362)
		(end 157.20187 -293.252906)
		(width 0.14478)
		(layer "In2.Cu")
		(net "M_I_CPU1_SB_DQ<15>")
	)
	(segment
		(start 174.596552 -298.910502)
		(end 174.906178 -298.910502)
		(width 0.14478)
		(layer "In2.Cu")
		(net "M_I_CPU1_SB_DQ<15>")
	)
	(segment
		(start 169.772584 -298.850812)
		(end 169.985944 -298.76242)
		(width 0.14478)
		(layer "In2.Cu")
		(net "M_I_CPU1_SB_DQ<15>")
	)
	(segment
		(start 128.370838 -283.540962)
		(end 128.39319 -283.45765)
		(width 0.0889)
		(layer "In2.Cu")
		(net "M_I_CPU1_SB_DQ<15>")
	)
	(arc
		(start 137.171684 -283.483812)
		(mid 137.45464 -283.559989)
		(end 137.737596 -283.483812)
		(width 0.0889)
		(layer "In2.Cu")
		(net "M_I_CPU1_SB_DQ<15>")
	)
	(arc
		(start 132.106162 -283.478986)
		(mid 132.28967 -283.433492)
		(end 132.471922 -283.483812)
		(width 0.0889)
		(layer "In2.Cu")
		(net "M_I_CPU1_SB_DQ<15>")
	)
	(arc
		(start 130.591814 -283.483812)
		(mid 130.87477 -283.559989)
		(end 131.157726 -283.483812)
		(width 0.0889)
		(layer "In2.Cu")
		(net "M_I_CPU1_SB_DQ<15>")
	)
	(arc
		(start 145.25625 -283.483812)
		(mid 145.313174 -283.456715)
		(end 145.373852 -283.439616)
		(width 0.0889)
		(layer "In2.Cu")
		(net "M_I_CPU1_SB_DQ<15>")
	)
	(arc
		(start 138.67765 -283.483812)
		(mid 138.859901 -283.433462)
		(end 139.04341 -283.478986)
		(width 0.0889)
		(layer "In2.Cu")
		(net "M_I_CPU1_SB_DQ<15>")
	)
	(arc
		(start 133.977634 -283.483812)
		(mid 134.159885 -283.433462)
		(end 134.343394 -283.478986)
		(width 0.0889)
		(layer "In2.Cu")
		(net "M_I_CPU1_SB_DQ<15>")
	)
	(arc
		(start 143.386048 -283.478986)
		(mid 143.569556 -283.433492)
		(end 143.751808 -283.483812)
		(width 0.0889)
		(layer "In2.Cu")
		(net "M_I_CPU1_SB_DQ<15>")
	)
	(arc
		(start 133.037834 -283.483812)
		(mid 133.224778 -283.433557)
		(end 133.411722 -283.483812)
		(width 0.0889)
		(layer "In2.Cu")
		(net "M_I_CPU1_SB_DQ<15>")
	)
	(arc
		(start 141.497812 -283.483812)
		(mid 141.684756 -283.433557)
		(end 141.8717 -283.483812)
		(width 0.0889)
		(layer "In2.Cu")
		(net "M_I_CPU1_SB_DQ<15>")
	)
	(arc
		(start 129.277618 -283.483812)
		(mid 129.459869 -283.433462)
		(end 129.643378 -283.478986)
		(width 0.0889)
		(layer "In2.Cu")
		(net "M_I_CPU1_SB_DQ<15>")
	)
	(arc
		(start 130.217672 -283.483812)
		(mid 130.399923 -283.433462)
		(end 130.583432 -283.478986)
		(width 0.0889)
		(layer "In2.Cu")
		(net "M_I_CPU1_SB_DQ<15>")
	)
	(arc
		(start 131.166108 -283.478986)
		(mid 131.349616 -283.433492)
		(end 131.531868 -283.483812)
		(width 0.0889)
		(layer "In2.Cu")
		(net "M_I_CPU1_SB_DQ<15>")
	)
	(arc
		(start 142.811754 -283.483812)
		(mid 143.09471 -283.559989)
		(end 143.377666 -283.483812)
		(width 0.0889)
		(layer "In2.Cu")
		(net "M_I_CPU1_SB_DQ<15>")
	)
	(arc
		(start 137.737596 -283.483812)
		(mid 137.919847 -283.433462)
		(end 138.103356 -283.478986)
		(width 0.0889)
		(layer "In2.Cu")
		(net "M_I_CPU1_SB_DQ<15>")
	)
	(arc
		(start 138.111738 -283.483812)
		(mid 138.394694 -283.559989)
		(end 138.67765 -283.483812)
		(width 0.0889)
		(layer "In2.Cu")
		(net "M_I_CPU1_SB_DQ<15>")
	)
	(arc
		(start 141.8717 -283.483812)
		(mid 142.154656 -283.559989)
		(end 142.437612 -283.483812)
		(width 0.0889)
		(layer "In2.Cu")
		(net "M_I_CPU1_SB_DQ<15>")
	)
	(arc
		(start 136.797796 -283.483812)
		(mid 136.98474 -283.433557)
		(end 137.171684 -283.483812)
		(width 0.0889)
		(layer "In2.Cu")
		(net "M_I_CPU1_SB_DQ<15>")
	)
	(arc
		(start 140.9319 -283.483812)
		(mid 141.214856 -283.559989)
		(end 141.497812 -283.483812)
		(width 0.0889)
		(layer "In2.Cu")
		(net "M_I_CPU1_SB_DQ<15>")
	)
	(arc
		(start 136.231884 -283.483812)
		(mid 136.51484 -283.559989)
		(end 136.797796 -283.483812)
		(width 0.0889)
		(layer "In2.Cu")
		(net "M_I_CPU1_SB_DQ<15>")
	)
	(arc
		(start 143.751808 -283.483812)
		(mid 144.018738 -283.559761)
		(end 144.289526 -283.499052)
		(width 0.0889)
		(layer "In2.Cu")
		(net "M_I_CPU1_SB_DQ<15>")
	)
	(arc
		(start 133.411722 -283.483812)
		(mid 133.694678 -283.559989)
		(end 133.977634 -283.483812)
		(width 0.0889)
		(layer "In2.Cu")
		(net "M_I_CPU1_SB_DQ<15>")
	)
	(arc
		(start 139.991846 -283.483812)
		(mid 140.274802 -283.559989)
		(end 140.557758 -283.483812)
		(width 0.0889)
		(layer "In2.Cu")
		(net "M_I_CPU1_SB_DQ<15>")
	)
	(arc
		(start 139.051792 -283.483812)
		(mid 139.334748 -283.559989)
		(end 139.617704 -283.483812)
		(width 0.0889)
		(layer "In2.Cu")
		(net "M_I_CPU1_SB_DQ<15>")
	)
	(arc
		(start 129.65176 -283.483812)
		(mid 129.934716 -283.559989)
		(end 130.217672 -283.483812)
		(width 0.0889)
		(layer "In2.Cu")
		(net "M_I_CPU1_SB_DQ<15>")
	)
	(arc
		(start 134.92607 -283.478986)
		(mid 135.109578 -283.433492)
		(end 135.29183 -283.483812)
		(width 0.0889)
		(layer "In2.Cu")
		(net "M_I_CPU1_SB_DQ<15>")
	)
	(arc
		(start 142.437612 -283.483812)
		(mid 142.619863 -283.433462)
		(end 142.803372 -283.478986)
		(width 0.0889)
		(layer "In2.Cu")
		(net "M_I_CPU1_SB_DQ<15>")
	)
	(arc
		(start 144.71777 -283.501084)
		(mid 144.98919 -283.560761)
		(end 145.25625 -283.483812)
		(width 0.0889)
		(layer "In2.Cu")
		(net "M_I_CPU1_SB_DQ<15>")
	)
	(arc
		(start 135.29183 -283.483812)
		(mid 135.574786 -283.559989)
		(end 135.857742 -283.483812)
		(width 0.0889)
		(layer "In2.Cu")
		(net "M_I_CPU1_SB_DQ<15>")
	)
	(arc
		(start 134.351776 -283.483812)
		(mid 134.634732 -283.559989)
		(end 134.917688 -283.483812)
		(width 0.0889)
		(layer "In2.Cu")
		(net "M_I_CPU1_SB_DQ<15>")
	)
	(arc
		(start 144.337532 -283.47162)
		(mid 144.51446 -283.433792)
		(end 144.688306 -283.483812)
		(width 0.0889)
		(layer "In2.Cu")
		(net "M_I_CPU1_SB_DQ<15>")
	)
	(arc
		(start 135.866124 -283.478986)
		(mid 136.049632 -283.433492)
		(end 136.231884 -283.483812)
		(width 0.0889)
		(layer "In2.Cu")
		(net "M_I_CPU1_SB_DQ<15>")
	)
	(arc
		(start 128.39319 -283.45765)
		(mid 128.555379 -283.434915)
		(end 128.711706 -283.483812)
		(width 0.0889)
		(layer "In2.Cu")
		(net "M_I_CPU1_SB_DQ<15>")
	)
	(arc
		(start 132.471922 -283.483812)
		(mid 132.754878 -283.559989)
		(end 133.037834 -283.483812)
		(width 0.0889)
		(layer "In2.Cu")
		(net "M_I_CPU1_SB_DQ<15>")
	)
	(arc
		(start 139.626086 -283.478986)
		(mid 139.809594 -283.433492)
		(end 139.991846 -283.483812)
		(width 0.0889)
		(layer "In2.Cu")
		(net "M_I_CPU1_SB_DQ<15>")
	)
	(arc
		(start 140.56614 -283.478986)
		(mid 140.749648 -283.433492)
		(end 140.9319 -283.483812)
		(width 0.0889)
		(layer "In2.Cu")
		(net "M_I_CPU1_SB_DQ<15>")
	)
	(arc
		(start 131.531868 -283.483812)
		(mid 131.814824 -283.559989)
		(end 132.09778 -283.483812)
		(width 0.0889)
		(layer "In2.Cu")
		(net "M_I_CPU1_SB_DQ<15>")
	)
	(arc
		(start 128.711706 -283.483812)
		(mid 128.994662 -283.559989)
		(end 129.277618 -283.483812)
		(width 0.0889)
		(layer "In2.Cu")
		(net "M_I_CPU1_SB_DQ<15>")
	)
	(segment
		(start 129.467864 -282.730448)
		(end 129.934716 -282.996386)
		(width 0.10668)
		(layer "F.Cu")
		(net "M_I_CPU1_SB_DQ<14>")
	)
	(segment
		(start 173.37151 -297.7896)
		(end 173.676818 -297.9166)
		(width 0.14478)
		(layer "In2.Cu")
		(net "M_I_CPU1_SB_DQ<14>")
	)
	(segment
		(start 135.753348 -282.66898)
		(end 135.76173 -282.673806)
		(width 0.0889)
		(layer "In2.Cu")
		(net "M_I_CPU1_SB_DQ<14>")
	)
	(segment
		(start 159.893 -294.65397)
		(end 159.893 -294.882316)
		(width 0.14478)
		(layer "In2.Cu")
		(net "M_I_CPU1_SB_DQ<14>")
	)
	(segment
		(start 173.9773 -297.791886)
		(end 174.103792 -297.486578)
		(width 0.14478)
		(layer "In2.Cu")
		(net "M_I_CPU1_SB_DQ<14>")
	)
	(segment
		(start 160.283144 -295.272206)
		(end 160.511236 -295.272206)
		(width 0.14478)
		(layer "In2.Cu")
		(net "M_I_CPU1_SB_DQ<14>")
	)
	(segment
		(start 158.948882 -294.265858)
		(end 158.948882 -294.49395)
		(width 0.14478)
		(layer "In2.Cu")
		(net "M_I_CPU1_SB_DQ<14>")
	)
	(segment
		(start 171.137072 -298.060618)
		(end 172.909992 -298.060618)
		(width 0.14478)
		(layer "In2.Cu")
		(net "M_I_CPU1_SB_DQ<14>")
	)
	(segment
		(start 161.67989 -296.996866)
		(end 161.84372 -296.832782)
		(width 0.14478)
		(layer "In2.Cu")
		(net "M_I_CPU1_SB_DQ<14>")
	)
	(segment
		(start 145.143982 -282.663646)
		(end 145.16227 -282.67406)
		(width 0.0889)
		(layer "In2.Cu")
		(net "M_I_CPU1_SB_DQ<14>")
	)
	(segment
		(start 161.289746 -296.834814)
		(end 161.451798 -296.996866)
		(width 0.14478)
		(layer "In2.Cu")
		(net "M_I_CPU1_SB_DQ<14>")
	)
	(segment
		(start 169.80662 -297.204638)
		(end 170.212766 -297.37304)
		(width 0.14478)
		(layer "In2.Cu")
		(net "M_I_CPU1_SB_DQ<14>")
	)
	(segment
		(start 170.324018 -297.641518)
		(end 170.99661 -297.920156)
		(width 0.14478)
		(layer "In2.Cu")
		(net "M_I_CPU1_SB_DQ<14>")
	)
	(segment
		(start 163.106608 -297.867578)
		(end 163.573714 -298.060618)
		(width 0.14478)
		(layer "In2.Cu")
		(net "M_I_CPU1_SB_DQ<14>")
	)
	(segment
		(start 129.780792 -282.730956)
		(end 129.803144 -282.647644)
		(width 0.0889)
		(layer "In2.Cu")
		(net "M_I_CPU1_SB_DQ<14>")
	)
	(segment
		(start 173.676818 -297.9166)
		(end 173.9773 -297.791886)
		(width 0.14478)
		(layer "In2.Cu")
		(net "M_I_CPU1_SB_DQ<14>")
	)
	(segment
		(start 159.112712 -294.102028)
		(end 158.948882 -294.265858)
		(width 0.14478)
		(layer "In2.Cu")
		(net "M_I_CPU1_SB_DQ<14>")
	)
	(segment
		(start 178.387248 -297.21048)
		(end 179.091082 -297.21048)
		(width 0.14478)
		(layer "In2.Cu")
		(net "M_I_CPU1_SB_DQ<14>")
	)
	(segment
		(start 161.291524 -296.052494)
		(end 161.453576 -296.214546)
		(width 0.14478)
		(layer "In2.Cu")
		(net "M_I_CPU1_SB_DQ<14>")
	)
	(segment
		(start 165.58006 -297.93819)
		(end 165.877748 -298.062142)
		(width 0.14478)
		(layer "In2.Cu")
		(net "M_I_CPU1_SB_DQ<14>")
	)
	(segment
		(start 176.442624 -297.21048)
		(end 176.710848 -297.478704)
		(width 0.14478)
		(layer "In2.Cu")
		(net "M_I_CPU1_SB_DQ<14>")
	)
	(segment
		(start 160.509458 -295.826434)
		(end 160.509458 -296.054526)
		(width 0.14478)
		(layer "In2.Cu")
		(net "M_I_CPU1_SB_DQ<14>")
	)
	(segment
		(start 160.673288 -295.434258)
		(end 160.673288 -295.662604)
		(width 0.14478)
		(layer "In2.Cu")
		(net "M_I_CPU1_SB_DQ<14>")
	)
	(segment
		(start 159.110934 -294.656002)
		(end 159.339026 -294.656002)
		(width 0.14478)
		(layer "In2.Cu")
		(net "M_I_CPU1_SB_DQ<14>")
	)
	(segment
		(start 177.269648 -297.21048)
		(end 177.560224 -297.21048)
		(width 0.14478)
		(layer "In2.Cu")
		(net "M_I_CPU1_SB_DQ<14>")
	)
	(segment
		(start 160.511236 -295.272206)
		(end 160.673288 -295.434258)
		(width 0.14478)
		(layer "In2.Cu")
		(net "M_I_CPU1_SB_DQ<14>")
	)
	(segment
		(start 158.168594 -293.48557)
		(end 158.168594 -293.713662)
		(width 0.14478)
		(layer "In2.Cu")
		(net "M_I_CPU1_SB_DQ<14>")
	)
	(segment
		(start 159.730948 -294.491918)
		(end 159.893 -294.65397)
		(width 0.14478)
		(layer "In2.Cu")
		(net "M_I_CPU1_SB_DQ<14>")
	)
	(segment
		(start 162.233864 -296.994834)
		(end 162.233864 -297.22318)
		(width 0.14478)
		(layer "In2.Cu")
		(net "M_I_CPU1_SB_DQ<14>")
	)
	(segment
		(start 178.119024 -297.478704)
		(end 178.387248 -297.21048)
		(width 0.14478)
		(layer "In2.Cu")
		(net "M_I_CPU1_SB_DQ<14>")
	)
	(segment
		(start 137.267696 -282.673806)
		(end 137.276078 -282.66898)
		(width 0.0889)
		(layer "In2.Cu")
		(net "M_I_CPU1_SB_DQ<14>")
	)
	(segment
		(start 162.624008 -297.61307)
		(end 162.8521 -297.61307)
		(width 0.14478)
		(layer "In2.Cu")
		(net "M_I_CPU1_SB_DQ<14>")
	)
	(segment
		(start 173.046136 -297.924474)
		(end 173.37151 -297.7896)
		(width 0.14478)
		(layer "In2.Cu")
		(net "M_I_CPU1_SB_DQ<14>")
	)
	(segment
		(start 174.770034 -297.21048)
		(end 176.442624 -297.21048)
		(width 0.14478)
		(layer "In2.Cu")
		(net "M_I_CPU1_SB_DQ<14>")
	)
	(segment
		(start 159.72917 -295.274238)
		(end 159.891222 -295.43629)
		(width 0.14478)
		(layer "In2.Cu")
		(net "M_I_CPU1_SB_DQ<14>")
	)
	(segment
		(start 160.67151 -296.216578)
		(end 160.899602 -296.216578)
		(width 0.14478)
		(layer "In2.Cu")
		(net "M_I_CPU1_SB_DQ<14>")
	)
	(segment
		(start 160.509458 -296.054526)
		(end 160.67151 -296.216578)
		(width 0.14478)
		(layer "In2.Cu")
		(net "M_I_CPU1_SB_DQ<14>")
	)
	(segment
		(start 179.091082 -297.21048)
		(end 179.516024 -297.635422)
		(width 0.14478)
		(layer "In2.Cu")
		(net "M_I_CPU1_SB_DQ<14>")
	)
	(segment
		(start 140.453364 -282.66898)
		(end 140.461746 -282.673806)
		(width 0.0889)
		(layer "In2.Cu")
		(net "M_I_CPU1_SB_DQ<14>")
	)
	(segment
		(start 158.722568 -293.71163)
		(end 158.95066 -293.71163)
		(width 0.14478)
		(layer "In2.Cu")
		(net "M_I_CPU1_SB_DQ<14>")
	)
	(segment
		(start 158.558738 -293.875714)
		(end 158.722568 -293.71163)
		(width 0.14478)
		(layer "In2.Cu")
		(net "M_I_CPU1_SB_DQ<14>")
	)
	(segment
		(start 159.893 -294.882316)
		(end 159.72917 -295.046146)
		(width 0.14478)
		(layer "In2.Cu")
		(net "M_I_CPU1_SB_DQ<14>")
	)
	(segment
		(start 158.330646 -293.875714)
		(end 158.558738 -293.875714)
		(width 0.14478)
		(layer "In2.Cu")
		(net "M_I_CPU1_SB_DQ<14>")
	)
	(segment
		(start 158.168594 -293.713662)
		(end 158.330646 -293.875714)
		(width 0.14478)
		(layer "In2.Cu")
		(net "M_I_CPU1_SB_DQ<14>")
	)
	(segment
		(start 148.387054 -283.148024)
		(end 158.332424 -293.093394)
		(width 0.14478)
		(layer "In2.Cu")
		(net "M_I_CPU1_SB_DQ<14>")
	)
	(segment
		(start 160.119314 -295.43629)
		(end 160.283144 -295.272206)
		(width 0.14478)
		(layer "In2.Cu")
		(net "M_I_CPU1_SB_DQ<14>")
	)
	(segment
		(start 145.444718 -282.75026)
		(end 145.923762 -282.75026)
		(width 0.0889)
		(layer "In2.Cu")
		(net "M_I_CPU1_SB_DQ<14>")
	)
	(segment
		(start 133.507734 -282.673806)
		(end 133.516116 -282.66898)
		(width 0.0889)
		(layer "In2.Cu")
		(net "M_I_CPU1_SB_DQ<14>")
	)
	(segment
		(start 162.071812 -296.832782)
		(end 162.233864 -296.994834)
		(width 0.14478)
		(layer "In2.Cu")
		(net "M_I_CPU1_SB_DQ<14>")
	)
	(segment
		(start 158.948882 -294.49395)
		(end 159.110934 -294.656002)
		(width 0.14478)
		(layer "In2.Cu")
		(net "M_I_CPU1_SB_DQ<14>")
	)
	(segment
		(start 147.352766 -283.381704)
		(end 147.586446 -283.148024)
		(width 0.0889)
		(layer "In2.Cu")
		(net "M_I_CPU1_SB_DQ<14>")
	)
	(segment
		(start 147.586446 -283.148024)
		(end 147.93849 -283.148024)
		(width 0.0889)
		(layer "In2.Cu")
		(net "M_I_CPU1_SB_DQ<14>")
	)
	(segment
		(start 158.332424 -293.093394)
		(end 158.332424 -293.32174)
		(width 0.14478)
		(layer "In2.Cu")
		(net "M_I_CPU1_SB_DQ<14>")
	)
	(segment
		(start 144.213326 -282.66898)
		(end 144.221708 -282.673806)
		(width 0.0889)
		(layer "In2.Cu")
		(net "M_I_CPU1_SB_DQ<14>")
	)
	(segment
		(start 177.001424 -297.478704)
		(end 177.269648 -297.21048)
		(width 0.14478)
		(layer "In2.Cu")
		(net "M_I_CPU1_SB_DQ<14>")
	)
	(segment
		(start 131.993386 -282.66898)
		(end 132.001768 -282.673806)
		(width 0.0889)
		(layer "In2.Cu")
		(net "M_I_CPU1_SB_DQ<14>")
	)
	(segment
		(start 138.20775 -282.673806)
		(end 138.216132 -282.66898)
		(width 0.0889)
		(layer "In2.Cu")
		(net "M_I_CPU1_SB_DQ<14>")
	)
	(segment
		(start 162.070034 -297.615102)
		(end 162.232086 -297.777154)
		(width 0.14478)
		(layer "In2.Cu")
		(net "M_I_CPU1_SB_DQ<14>")
	)
	(segment
		(start 160.673288 -295.662604)
		(end 160.509458 -295.826434)
		(width 0.14478)
		(layer "In2.Cu")
		(net "M_I_CPU1_SB_DQ<14>")
	)
	(segment
		(start 174.103792 -297.486578)
		(end 174.770034 -297.21048)
		(width 0.14478)
		(layer "In2.Cu")
		(net "M_I_CPU1_SB_DQ<14>")
	)
	(segment
		(start 141.967712 -282.673806)
		(end 141.976094 -282.66898)
		(width 0.0889)
		(layer "In2.Cu")
		(net "M_I_CPU1_SB_DQ<14>")
	)
	(segment
		(start 170.212766 -297.37304)
		(end 170.324018 -297.641518)
		(width 0.14478)
		(layer "In2.Cu")
		(net "M_I_CPU1_SB_DQ<14>")
	)
	(segment
		(start 165.284404 -298.060618)
		(end 165.58006 -297.93819)
		(width 0.14478)
		(layer "In2.Cu")
		(net "M_I_CPU1_SB_DQ<14>")
	)
	(segment
		(start 166.29126 -297.5991)
		(end 167.229028 -297.21048)
		(width 0.14478)
		(layer "In2.Cu")
		(net "M_I_CPU1_SB_DQ<14>")
	)
	(segment
		(start 162.460178 -297.777154)
		(end 162.624008 -297.61307)
		(width 0.14478)
		(layer "In2.Cu")
		(net "M_I_CPU1_SB_DQ<14>")
	)
	(segment
		(start 172.909992 -298.060618)
		(end 173.046136 -297.924474)
		(width 0.14478)
		(layer "In2.Cu")
		(net "M_I_CPU1_SB_DQ<14>")
	)
	(segment
		(start 169.537888 -297.316144)
		(end 169.80662 -297.204638)
		(width 0.14478)
		(layer "In2.Cu")
		(net "M_I_CPU1_SB_DQ<14>")
	)
	(segment
		(start 147.93849 -283.148024)
		(end 148.387054 -283.148024)
		(width 0.14478)
		(layer "In2.Cu")
		(net "M_I_CPU1_SB_DQ<14>")
	)
	(segment
		(start 158.332424 -293.32174)
		(end 158.168594 -293.48557)
		(width 0.14478)
		(layer "In2.Cu")
		(net "M_I_CPU1_SB_DQ<14>")
	)
	(segment
		(start 162.232086 -297.777154)
		(end 162.460178 -297.777154)
		(width 0.14478)
		(layer "In2.Cu")
		(net "M_I_CPU1_SB_DQ<14>")
	)
	(segment
		(start 146.555206 -283.381704)
		(end 147.352766 -283.381704)
		(width 0.0889)
		(layer "In2.Cu")
		(net "M_I_CPU1_SB_DQ<14>")
	)
	(segment
		(start 158.95066 -293.71163)
		(end 159.112712 -293.873682)
		(width 0.14478)
		(layer "In2.Cu")
		(net "M_I_CPU1_SB_DQ<14>")
	)
	(segment
		(start 159.72917 -295.046146)
		(end 159.72917 -295.274238)
		(width 0.14478)
		(layer "In2.Cu")
		(net "M_I_CPU1_SB_DQ<14>")
	)
	(segment
		(start 162.233864 -297.22318)
		(end 162.070034 -297.38701)
		(width 0.14478)
		(layer "In2.Cu")
		(net "M_I_CPU1_SB_DQ<14>")
	)
	(segment
		(start 145.923762 -282.75026)
		(end 146.555206 -283.381704)
		(width 0.0889)
		(layer "In2.Cu")
		(net "M_I_CPU1_SB_DQ<14>")
	)
	(segment
		(start 162.070034 -297.38701)
		(end 162.070034 -297.615102)
		(width 0.14478)
		(layer "In2.Cu")
		(net "M_I_CPU1_SB_DQ<14>")
	)
	(segment
		(start 161.84372 -296.832782)
		(end 162.071812 -296.832782)
		(width 0.14478)
		(layer "In2.Cu")
		(net "M_I_CPU1_SB_DQ<14>")
	)
	(segment
		(start 141.393418 -282.66898)
		(end 141.4018 -282.673806)
		(width 0.0889)
		(layer "In2.Cu")
		(net "M_I_CPU1_SB_DQ<14>")
	)
	(segment
		(start 176.710848 -297.478704)
		(end 177.001424 -297.478704)
		(width 0.14478)
		(layer "In2.Cu")
		(net "M_I_CPU1_SB_DQ<14>")
	)
	(segment
		(start 159.339026 -294.656002)
		(end 159.502856 -294.491918)
		(width 0.14478)
		(layer "In2.Cu")
		(net "M_I_CPU1_SB_DQ<14>")
	)
	(segment
		(start 144.221708 -282.673806)
		(end 144.23644 -282.682442)
		(width 0.0889)
		(layer "In2.Cu")
		(net "M_I_CPU1_SB_DQ<14>")
	)
	(segment
		(start 161.289746 -296.606722)
		(end 161.289746 -296.834814)
		(width 0.14478)
		(layer "In2.Cu")
		(net "M_I_CPU1_SB_DQ<14>")
	)
	(segment
		(start 159.891222 -295.43629)
		(end 160.119314 -295.43629)
		(width 0.14478)
		(layer "In2.Cu")
		(net "M_I_CPU1_SB_DQ<14>")
	)
	(segment
		(start 132.93344 -282.66898)
		(end 132.941822 -282.673806)
		(width 0.0889)
		(layer "In2.Cu")
		(net "M_I_CPU1_SB_DQ<14>")
	)
	(segment
		(start 136.693402 -282.66898)
		(end 136.701784 -282.673806)
		(width 0.0889)
		(layer "In2.Cu")
		(net "M_I_CPU1_SB_DQ<14>")
	)
	(segment
		(start 161.063432 -296.052494)
		(end 161.291524 -296.052494)
		(width 0.14478)
		(layer "In2.Cu")
		(net "M_I_CPU1_SB_DQ<14>")
	)
	(segment
		(start 165.877748 -298.062142)
		(end 166.145464 -297.951144)
		(width 0.14478)
		(layer "In2.Cu")
		(net "M_I_CPU1_SB_DQ<14>")
	)
	(segment
		(start 166.145464 -297.951144)
		(end 166.29126 -297.5991)
		(width 0.14478)
		(layer "In2.Cu")
		(net "M_I_CPU1_SB_DQ<14>")
	)
	(segment
		(start 170.99661 -297.920156)
		(end 171.137072 -298.060618)
		(width 0.14478)
		(layer "In2.Cu")
		(net "M_I_CPU1_SB_DQ<14>")
	)
	(segment
		(start 161.451798 -296.996866)
		(end 161.67989 -296.996866)
		(width 0.14478)
		(layer "In2.Cu")
		(net "M_I_CPU1_SB_DQ<14>")
	)
	(segment
		(start 177.560224 -297.21048)
		(end 177.828448 -297.478704)
		(width 0.14478)
		(layer "In2.Cu")
		(net "M_I_CPU1_SB_DQ<14>")
	)
	(segment
		(start 163.573714 -298.060618)
		(end 165.284404 -298.060618)
		(width 0.14478)
		(layer "In2.Cu")
		(net "M_I_CPU1_SB_DQ<14>")
	)
	(segment
		(start 162.8521 -297.61307)
		(end 163.106608 -297.867578)
		(width 0.14478)
		(layer "In2.Cu")
		(net "M_I_CPU1_SB_DQ<14>")
	)
	(segment
		(start 161.453576 -296.442892)
		(end 161.289746 -296.606722)
		(width 0.14478)
		(layer "In2.Cu")
		(net "M_I_CPU1_SB_DQ<14>")
	)
	(segment
		(start 169.283126 -297.21048)
		(end 169.537888 -297.316144)
		(width 0.14478)
		(layer "In2.Cu")
		(net "M_I_CPU1_SB_DQ<14>")
	)
	(segment
		(start 159.112712 -293.873682)
		(end 159.112712 -294.102028)
		(width 0.14478)
		(layer "In2.Cu")
		(net "M_I_CPU1_SB_DQ<14>")
	)
	(segment
		(start 145.16227 -282.67406)
		(end 145.178018 -282.683204)
		(width 0.0889)
		(layer "In2.Cu")
		(net "M_I_CPU1_SB_DQ<14>")
	)
	(segment
		(start 160.899602 -296.216578)
		(end 161.063432 -296.052494)
		(width 0.14478)
		(layer "In2.Cu")
		(net "M_I_CPU1_SB_DQ<14>")
	)
	(segment
		(start 129.934716 -282.996386)
		(end 129.780792 -282.730956)
		(width 0.0889)
		(layer "In2.Cu")
		(net "M_I_CPU1_SB_DQ<14>")
	)
	(segment
		(start 177.828448 -297.478704)
		(end 178.119024 -297.478704)
		(width 0.14478)
		(layer "In2.Cu")
		(net "M_I_CPU1_SB_DQ<14>")
	)
	(segment
		(start 167.229028 -297.21048)
		(end 169.283126 -297.21048)
		(width 0.14478)
		(layer "In2.Cu")
		(net "M_I_CPU1_SB_DQ<14>")
	)
	(segment
		(start 159.502856 -294.491918)
		(end 159.730948 -294.491918)
		(width 0.14478)
		(layer "In2.Cu")
		(net "M_I_CPU1_SB_DQ<14>")
	)
	(segment
		(start 161.453576 -296.214546)
		(end 161.453576 -296.442892)
		(width 0.14478)
		(layer "In2.Cu")
		(net "M_I_CPU1_SB_DQ<14>")
	)
	(arc
		(start 141.976094 -282.66898)
		(mid 142.159602 -282.623486)
		(end 142.341854 -282.673806)
		(width 0.0889)
		(layer "In2.Cu")
		(net "M_I_CPU1_SB_DQ<14>")
	)
	(arc
		(start 130.121914 -282.673806)
		(mid 130.40487 -282.749983)
		(end 130.687826 -282.673806)
		(width 0.0889)
		(layer "In2.Cu")
		(net "M_I_CPU1_SB_DQ<14>")
	)
	(arc
		(start 141.027658 -282.673806)
		(mid 141.209909 -282.623456)
		(end 141.393418 -282.66898)
		(width 0.0889)
		(layer "In2.Cu")
		(net "M_I_CPU1_SB_DQ<14>")
	)
	(arc
		(start 137.276078 -282.66898)
		(mid 137.459586 -282.623486)
		(end 137.641838 -282.673806)
		(width 0.0889)
		(layer "In2.Cu")
		(net "M_I_CPU1_SB_DQ<14>")
	)
	(arc
		(start 142.341854 -282.673806)
		(mid 142.62481 -282.749983)
		(end 142.907766 -282.673806)
		(width 0.0889)
		(layer "In2.Cu")
		(net "M_I_CPU1_SB_DQ<14>")
	)
	(arc
		(start 130.687826 -282.673806)
		(mid 130.87477 -282.623551)
		(end 131.061714 -282.673806)
		(width 0.0889)
		(layer "In2.Cu")
		(net "M_I_CPU1_SB_DQ<14>")
	)
	(arc
		(start 136.327642 -282.673806)
		(mid 136.509893 -282.623456)
		(end 136.693402 -282.66898)
		(width 0.0889)
		(layer "In2.Cu")
		(net "M_I_CPU1_SB_DQ<14>")
	)
	(arc
		(start 144.788128 -282.673806)
		(mid 144.964756 -282.623573)
		(end 145.143982 -282.663646)
		(width 0.0889)
		(layer "In2.Cu")
		(net "M_I_CPU1_SB_DQ<14>")
	)
	(arc
		(start 139.521692 -282.673806)
		(mid 139.804648 -282.749983)
		(end 140.087604 -282.673806)
		(width 0.0889)
		(layer "In2.Cu")
		(net "M_I_CPU1_SB_DQ<14>")
	)
	(arc
		(start 140.087604 -282.673806)
		(mid 140.269855 -282.623456)
		(end 140.453364 -282.66898)
		(width 0.0889)
		(layer "In2.Cu")
		(net "M_I_CPU1_SB_DQ<14>")
	)
	(arc
		(start 132.56768 -282.673806)
		(mid 132.749931 -282.623456)
		(end 132.93344 -282.66898)
		(width 0.0889)
		(layer "In2.Cu")
		(net "M_I_CPU1_SB_DQ<14>")
	)
	(arc
		(start 141.4018 -282.673806)
		(mid 141.684756 -282.749983)
		(end 141.967712 -282.673806)
		(width 0.0889)
		(layer "In2.Cu")
		(net "M_I_CPU1_SB_DQ<14>")
	)
	(arc
		(start 142.907766 -282.673806)
		(mid 143.09471 -282.623551)
		(end 143.281654 -282.673806)
		(width 0.0889)
		(layer "In2.Cu")
		(net "M_I_CPU1_SB_DQ<14>")
	)
	(arc
		(start 131.627626 -282.673806)
		(mid 131.809877 -282.623456)
		(end 131.993386 -282.66898)
		(width 0.0889)
		(layer "In2.Cu")
		(net "M_I_CPU1_SB_DQ<14>")
	)
	(arc
		(start 144.23644 -282.682442)
		(mid 144.513423 -282.750246)
		(end 144.788128 -282.673806)
		(width 0.0889)
		(layer "In2.Cu")
		(net "M_I_CPU1_SB_DQ<14>")
	)
	(arc
		(start 137.641838 -282.673806)
		(mid 137.924794 -282.749983)
		(end 138.20775 -282.673806)
		(width 0.0889)
		(layer "In2.Cu")
		(net "M_I_CPU1_SB_DQ<14>")
	)
	(arc
		(start 143.847566 -282.673806)
		(mid 144.029817 -282.623456)
		(end 144.213326 -282.66898)
		(width 0.0889)
		(layer "In2.Cu")
		(net "M_I_CPU1_SB_DQ<14>")
	)
	(arc
		(start 143.281654 -282.673806)
		(mid 143.56461 -282.749983)
		(end 143.847566 -282.673806)
		(width 0.0889)
		(layer "In2.Cu")
		(net "M_I_CPU1_SB_DQ<14>")
	)
	(arc
		(start 132.941822 -282.673806)
		(mid 133.224778 -282.749983)
		(end 133.507734 -282.673806)
		(width 0.0889)
		(layer "In2.Cu")
		(net "M_I_CPU1_SB_DQ<14>")
	)
	(arc
		(start 135.76173 -282.673806)
		(mid 136.044686 -282.749983)
		(end 136.327642 -282.673806)
		(width 0.0889)
		(layer "In2.Cu")
		(net "M_I_CPU1_SB_DQ<14>")
	)
	(arc
		(start 138.581892 -282.673806)
		(mid 138.864848 -282.749983)
		(end 139.147804 -282.673806)
		(width 0.0889)
		(layer "In2.Cu")
		(net "M_I_CPU1_SB_DQ<14>")
	)
	(arc
		(start 133.516116 -282.66898)
		(mid 133.699624 -282.623486)
		(end 133.881876 -282.673806)
		(width 0.0889)
		(layer "In2.Cu")
		(net "M_I_CPU1_SB_DQ<14>")
	)
	(arc
		(start 136.701784 -282.673806)
		(mid 136.98474 -282.749983)
		(end 137.267696 -282.673806)
		(width 0.0889)
		(layer "In2.Cu")
		(net "M_I_CPU1_SB_DQ<14>")
	)
	(arc
		(start 134.821676 -282.673806)
		(mid 135.104632 -282.749983)
		(end 135.387588 -282.673806)
		(width 0.0889)
		(layer "In2.Cu")
		(net "M_I_CPU1_SB_DQ<14>")
	)
	(arc
		(start 139.147804 -282.673806)
		(mid 139.334748 -282.623551)
		(end 139.521692 -282.673806)
		(width 0.0889)
		(layer "In2.Cu")
		(net "M_I_CPU1_SB_DQ<14>")
	)
	(arc
		(start 129.803144 -282.647644)
		(mid 129.965476 -282.624826)
		(end 130.121914 -282.673806)
		(width 0.0889)
		(layer "In2.Cu")
		(net "M_I_CPU1_SB_DQ<14>")
	)
	(arc
		(start 145.178018 -282.683204)
		(mid 145.307217 -282.733241)
		(end 145.444718 -282.75026)
		(width 0.0889)
		(layer "In2.Cu")
		(net "M_I_CPU1_SB_DQ<14>")
	)
	(arc
		(start 131.061714 -282.673806)
		(mid 131.34467 -282.749983)
		(end 131.627626 -282.673806)
		(width 0.0889)
		(layer "In2.Cu")
		(net "M_I_CPU1_SB_DQ<14>")
	)
	(arc
		(start 138.216132 -282.66898)
		(mid 138.39964 -282.623486)
		(end 138.581892 -282.673806)
		(width 0.0889)
		(layer "In2.Cu")
		(net "M_I_CPU1_SB_DQ<14>")
	)
	(arc
		(start 132.001768 -282.673806)
		(mid 132.284724 -282.749983)
		(end 132.56768 -282.673806)
		(width 0.0889)
		(layer "In2.Cu")
		(net "M_I_CPU1_SB_DQ<14>")
	)
	(arc
		(start 135.387588 -282.673806)
		(mid 135.569839 -282.623456)
		(end 135.753348 -282.66898)
		(width 0.0889)
		(layer "In2.Cu")
		(net "M_I_CPU1_SB_DQ<14>")
	)
	(arc
		(start 133.881876 -282.673806)
		(mid 134.164832 -282.749983)
		(end 134.447788 -282.673806)
		(width 0.0889)
		(layer "In2.Cu")
		(net "M_I_CPU1_SB_DQ<14>")
	)
	(arc
		(start 134.447788 -282.673806)
		(mid 134.634732 -282.623551)
		(end 134.821676 -282.673806)
		(width 0.0889)
		(layer "In2.Cu")
		(net "M_I_CPU1_SB_DQ<14>")
	)
	(arc
		(start 140.461746 -282.673806)
		(mid 140.744702 -282.749983)
		(end 141.027658 -282.673806)
		(width 0.0889)
		(layer "In2.Cu")
		(net "M_I_CPU1_SB_DQ<14>")
	)
	(segment
		(start 127.58801 -282.730448)
		(end 128.054862 -282.996386)
		(width 0.10668)
		(layer "F.Cu")
		(net "M_I_CPU1_SB_DQ<13>")
	)
	(segment
		(start 135.753348 -283.323792)
		(end 135.76173 -283.318966)
		(width 0.0889)
		(layer "In2.Cu")
		(net "M_I_CPU1_SB_DQ<13>")
	)
	(segment
		(start 141.393418 -283.323792)
		(end 141.4018 -283.318966)
		(width 0.0889)
		(layer "In2.Cu")
		(net "M_I_CPU1_SB_DQ<13>")
	)
	(segment
		(start 136.693402 -283.323792)
		(end 136.701784 -283.318966)
		(width 0.0889)
		(layer "In2.Cu")
		(net "M_I_CPU1_SB_DQ<13>")
	)
	(segment
		(start 132.93344 -283.323792)
		(end 132.941822 -283.318966)
		(width 0.0889)
		(layer "In2.Cu")
		(net "M_I_CPU1_SB_DQ<13>")
	)
	(segment
		(start 146.582384 -283.704284)
		(end 147.959318 -283.704284)
		(width 0.0889)
		(layer "In2.Cu")
		(net "M_I_CPU1_SB_DQ<13>")
	)
	(segment
		(start 146.14652 -283.52369)
		(end 146.582384 -283.704284)
		(width 0.0889)
		(layer "In2.Cu")
		(net "M_I_CPU1_SB_DQ<13>")
	)
	(segment
		(start 171.751498 -298.910502)
		(end 172.141388 -298.910502)
		(width 0.14478)
		(layer "In2.Cu")
		(net "M_I_CPU1_SB_DQ<13>")
	)
	(segment
		(start 148.43506 -283.8323)
		(end 157.57525 -292.97249)
		(width 0.14478)
		(layer "In2.Cu")
		(net "M_I_CPU1_SB_DQ<13>")
	)
	(segment
		(start 128.208786 -283.261816)
		(end 128.304798 -283.287216)
		(width 0.0889)
		(layer "In2.Cu")
		(net "M_I_CPU1_SB_DQ<13>")
	)
	(segment
		(start 172.141388 -298.910502)
		(end 173.03623 -298.539916)
		(width 0.14478)
		(layer "In2.Cu")
		(net "M_I_CPU1_SB_DQ<13>")
	)
	(segment
		(start 173.03623 -298.539916)
		(end 175.446182 -298.060618)
		(width 0.14478)
		(layer "In2.Cu")
		(net "M_I_CPU1_SB_DQ<13>")
	)
	(segment
		(start 145.871946 -283.249116)
		(end 146.14652 -283.52369)
		(width 0.0889)
		(layer "In2.Cu")
		(net "M_I_CPU1_SB_DQ<13>")
	)
	(segment
		(start 167.4495 -298.060618)
		(end 169.699686 -298.060618)
		(width 0.14478)
		(layer "In2.Cu")
		(net "M_I_CPU1_SB_DQ<13>")
	)
	(segment
		(start 157.719014 -293.803832)
		(end 157.787086 -293.96817)
		(width 0.14478)
		(layer "In2.Cu")
		(net "M_I_CPU1_SB_DQ<13>")
	)
	(segment
		(start 144.220438 -283.318712)
		(end 144.2466 -283.303726)
		(width 0.0889)
		(layer "In2.Cu")
		(net "M_I_CPU1_SB_DQ<13>")
	)
	(segment
		(start 164.648134 -298.910502)
		(end 167.4495 -298.060618)
		(width 0.14478)
		(layer "In2.Cu")
		(net "M_I_CPU1_SB_DQ<13>")
	)
	(segment
		(start 148.12645 -283.704284)
		(end 148.43506 -283.8323)
		(width 0.14478)
		(layer "In2.Cu")
		(net "M_I_CPU1_SB_DQ<13>")
	)
	(segment
		(start 145.15973 -283.318966)
		(end 145.159984 -283.31922)
		(width 0.0889)
		(layer "In2.Cu")
		(net "M_I_CPU1_SB_DQ<13>")
	)
	(segment
		(start 145.357342 -283.249116)
		(end 145.871946 -283.249116)
		(width 0.0889)
		(layer "In2.Cu")
		(net "M_I_CPU1_SB_DQ<13>")
	)
	(segment
		(start 144.19707 -283.332174)
		(end 144.220438 -283.318712)
		(width 0.0889)
		(layer "In2.Cu")
		(net "M_I_CPU1_SB_DQ<13>")
	)
	(segment
		(start 164.421058 -298.910502)
		(end 164.648134 -298.910502)
		(width 0.14478)
		(layer "In2.Cu")
		(net "M_I_CPU1_SB_DQ<13>")
	)
	(segment
		(start 157.719014 -293.319708)
		(end 157.719014 -293.803832)
		(width 0.14478)
		(layer "In2.Cu")
		(net "M_I_CPU1_SB_DQ<13>")
	)
	(segment
		(start 144.784318 -283.318966)
		(end 144.804892 -283.330904)
		(width 0.0889)
		(layer "In2.Cu")
		(net "M_I_CPU1_SB_DQ<13>")
	)
	(segment
		(start 128.807718 -283.318966)
		(end 128.8161 -283.323792)
		(width 0.0889)
		(layer "In2.Cu")
		(net "M_I_CPU1_SB_DQ<13>")
	)
	(segment
		(start 169.699686 -298.060618)
		(end 171.751498 -298.910502)
		(width 0.14478)
		(layer "In2.Cu")
		(net "M_I_CPU1_SB_DQ<13>")
	)
	(segment
		(start 162.541204 -298.392088)
		(end 163.924742 -298.811696)
		(width 0.14478)
		(layer "In2.Cu")
		(net "M_I_CPU1_SB_DQ<13>")
	)
	(segment
		(start 175.446182 -298.060618)
		(end 183.191404 -298.060618)
		(width 0.14478)
		(layer "In2.Cu")
		(net "M_I_CPU1_SB_DQ<13>")
	)
	(segment
		(start 137.267696 -283.318966)
		(end 137.276078 -283.323792)
		(width 0.0889)
		(layer "In2.Cu")
		(net "M_I_CPU1_SB_DQ<13>")
	)
	(segment
		(start 140.453364 -283.323792)
		(end 140.461746 -283.318966)
		(width 0.0889)
		(layer "In2.Cu")
		(net "M_I_CPU1_SB_DQ<13>")
	)
	(segment
		(start 161.977324 -298.158408)
		(end 162.541204 -298.392088)
		(width 0.14478)
		(layer "In2.Cu")
		(net "M_I_CPU1_SB_DQ<13>")
	)
	(segment
		(start 128.054862 -282.996386)
		(end 128.208786 -283.261816)
		(width 0.0889)
		(layer "In2.Cu")
		(net "M_I_CPU1_SB_DQ<13>")
	)
	(segment
		(start 141.967712 -283.318966)
		(end 141.976094 -283.323792)
		(width 0.0889)
		(layer "In2.Cu")
		(net "M_I_CPU1_SB_DQ<13>")
	)
	(segment
		(start 183.191404 -298.060618)
		(end 183.616092 -298.485306)
		(width 0.14478)
		(layer "In2.Cu")
		(net "M_I_CPU1_SB_DQ<13>")
	)
	(segment
		(start 157.787086 -293.96817)
		(end 161.977324 -298.158408)
		(width 0.14478)
		(layer "In2.Cu")
		(net "M_I_CPU1_SB_DQ<13>")
	)
	(segment
		(start 129.747772 -283.318966)
		(end 129.756154 -283.323792)
		(width 0.0889)
		(layer "In2.Cu")
		(net "M_I_CPU1_SB_DQ<13>")
	)
	(segment
		(start 147.959318 -283.704284)
		(end 148.12645 -283.704284)
		(width 0.14478)
		(layer "In2.Cu")
		(net "M_I_CPU1_SB_DQ<13>")
	)
	(segment
		(start 163.924742 -298.811696)
		(end 164.421058 -298.910502)
		(width 0.14478)
		(layer "In2.Cu")
		(net "M_I_CPU1_SB_DQ<13>")
	)
	(segment
		(start 133.507734 -283.318966)
		(end 133.516116 -283.323792)
		(width 0.0889)
		(layer "In2.Cu")
		(net "M_I_CPU1_SB_DQ<13>")
	)
	(segment
		(start 157.57525 -292.97249)
		(end 157.719014 -293.319708)
		(width 0.14478)
		(layer "In2.Cu")
		(net "M_I_CPU1_SB_DQ<13>")
	)
	(segment
		(start 131.993386 -283.323792)
		(end 132.001768 -283.318966)
		(width 0.0889)
		(layer "In2.Cu")
		(net "M_I_CPU1_SB_DQ<13>")
	)
	(segment
		(start 138.20775 -283.318966)
		(end 138.216132 -283.323792)
		(width 0.0889)
		(layer "In2.Cu")
		(net "M_I_CPU1_SB_DQ<13>")
	)
	(arc
		(start 141.4018 -283.318966)
		(mid 141.684756 -283.242789)
		(end 141.967712 -283.318966)
		(width 0.0889)
		(layer "In2.Cu")
		(net "M_I_CPU1_SB_DQ<13>")
	)
	(arc
		(start 142.907766 -283.318966)
		(mid 143.09471 -283.369221)
		(end 143.281654 -283.318966)
		(width 0.0889)
		(layer "In2.Cu")
		(net "M_I_CPU1_SB_DQ<13>")
	)
	(arc
		(start 131.627626 -283.318966)
		(mid 131.809877 -283.369316)
		(end 131.993386 -283.323792)
		(width 0.0889)
		(layer "In2.Cu")
		(net "M_I_CPU1_SB_DQ<13>")
	)
	(arc
		(start 144.2466 -283.303726)
		(mid 144.517386 -283.24308)
		(end 144.784318 -283.318966)
		(width 0.0889)
		(layer "In2.Cu")
		(net "M_I_CPU1_SB_DQ<13>")
	)
	(arc
		(start 141.976094 -283.323792)
		(mid 142.159602 -283.369286)
		(end 142.341854 -283.318966)
		(width 0.0889)
		(layer "In2.Cu")
		(net "M_I_CPU1_SB_DQ<13>")
	)
	(arc
		(start 133.516116 -283.323792)
		(mid 133.699624 -283.369286)
		(end 133.881876 -283.318966)
		(width 0.0889)
		(layer "In2.Cu")
		(net "M_I_CPU1_SB_DQ<13>")
	)
	(arc
		(start 139.521692 -283.318966)
		(mid 139.804648 -283.242789)
		(end 140.087604 -283.318966)
		(width 0.0889)
		(layer "In2.Cu")
		(net "M_I_CPU1_SB_DQ<13>")
	)
	(arc
		(start 130.121914 -283.318966)
		(mid 130.40487 -283.242789)
		(end 130.687826 -283.318966)
		(width 0.0889)
		(layer "In2.Cu")
		(net "M_I_CPU1_SB_DQ<13>")
	)
	(arc
		(start 137.276078 -283.323792)
		(mid 137.459586 -283.369286)
		(end 137.641838 -283.318966)
		(width 0.0889)
		(layer "In2.Cu")
		(net "M_I_CPU1_SB_DQ<13>")
	)
	(arc
		(start 142.341854 -283.318966)
		(mid 142.62481 -283.242789)
		(end 142.907766 -283.318966)
		(width 0.0889)
		(layer "In2.Cu")
		(net "M_I_CPU1_SB_DQ<13>")
	)
	(arc
		(start 135.76173 -283.318966)
		(mid 136.044686 -283.242789)
		(end 136.327642 -283.318966)
		(width 0.0889)
		(layer "In2.Cu")
		(net "M_I_CPU1_SB_DQ<13>")
	)
	(arc
		(start 134.447788 -283.318966)
		(mid 134.634732 -283.369221)
		(end 134.821676 -283.318966)
		(width 0.0889)
		(layer "In2.Cu")
		(net "M_I_CPU1_SB_DQ<13>")
	)
	(arc
		(start 134.821676 -283.318966)
		(mid 135.104632 -283.242789)
		(end 135.387588 -283.318966)
		(width 0.0889)
		(layer "In2.Cu")
		(net "M_I_CPU1_SB_DQ<13>")
	)
	(arc
		(start 128.304798 -283.287216)
		(mid 128.560006 -283.243739)
		(end 128.807718 -283.318966)
		(width 0.0889)
		(layer "In2.Cu")
		(net "M_I_CPU1_SB_DQ<13>")
	)
	(arc
		(start 130.687826 -283.318966)
		(mid 130.87477 -283.369221)
		(end 131.061714 -283.318966)
		(width 0.0889)
		(layer "In2.Cu")
		(net "M_I_CPU1_SB_DQ<13>")
	)
	(arc
		(start 143.281654 -283.318966)
		(mid 143.56461 -283.242789)
		(end 143.847566 -283.318966)
		(width 0.0889)
		(layer "In2.Cu")
		(net "M_I_CPU1_SB_DQ<13>")
	)
	(arc
		(start 131.061714 -283.318966)
		(mid 131.34467 -283.242789)
		(end 131.627626 -283.318966)
		(width 0.0889)
		(layer "In2.Cu")
		(net "M_I_CPU1_SB_DQ<13>")
	)
	(arc
		(start 140.461746 -283.318966)
		(mid 140.744702 -283.242789)
		(end 141.027658 -283.318966)
		(width 0.0889)
		(layer "In2.Cu")
		(net "M_I_CPU1_SB_DQ<13>")
	)
	(arc
		(start 132.001768 -283.318966)
		(mid 132.284724 -283.242789)
		(end 132.56768 -283.318966)
		(width 0.0889)
		(layer "In2.Cu")
		(net "M_I_CPU1_SB_DQ<13>")
	)
	(arc
		(start 143.847566 -283.318966)
		(mid 144.020674 -283.369082)
		(end 144.19707 -283.332174)
		(width 0.0889)
		(layer "In2.Cu")
		(net "M_I_CPU1_SB_DQ<13>")
	)
	(arc
		(start 132.941822 -283.318966)
		(mid 133.224778 -283.242789)
		(end 133.507734 -283.318966)
		(width 0.0889)
		(layer "In2.Cu")
		(net "M_I_CPU1_SB_DQ<13>")
	)
	(arc
		(start 137.641838 -283.318966)
		(mid 137.924794 -283.242789)
		(end 138.20775 -283.318966)
		(width 0.0889)
		(layer "In2.Cu")
		(net "M_I_CPU1_SB_DQ<13>")
	)
	(arc
		(start 135.387588 -283.318966)
		(mid 135.569839 -283.369316)
		(end 135.753348 -283.323792)
		(width 0.0889)
		(layer "In2.Cu")
		(net "M_I_CPU1_SB_DQ<13>")
	)
	(arc
		(start 141.027658 -283.318966)
		(mid 141.209909 -283.369316)
		(end 141.393418 -283.323792)
		(width 0.0889)
		(layer "In2.Cu")
		(net "M_I_CPU1_SB_DQ<13>")
	)
	(arc
		(start 144.804892 -283.330904)
		(mid 144.98382 -283.369781)
		(end 145.15973 -283.318966)
		(width 0.0889)
		(layer "In2.Cu")
		(net "M_I_CPU1_SB_DQ<13>")
	)
	(arc
		(start 128.8161 -283.323792)
		(mid 128.999608 -283.369286)
		(end 129.18186 -283.318966)
		(width 0.0889)
		(layer "In2.Cu")
		(net "M_I_CPU1_SB_DQ<13>")
	)
	(arc
		(start 132.56768 -283.318966)
		(mid 132.749931 -283.369316)
		(end 132.93344 -283.323792)
		(width 0.0889)
		(layer "In2.Cu")
		(net "M_I_CPU1_SB_DQ<13>")
	)
	(arc
		(start 138.216132 -283.323792)
		(mid 138.39964 -283.369286)
		(end 138.581892 -283.318966)
		(width 0.0889)
		(layer "In2.Cu")
		(net "M_I_CPU1_SB_DQ<13>")
	)
	(arc
		(start 140.087604 -283.318966)
		(mid 140.269855 -283.369316)
		(end 140.453364 -283.323792)
		(width 0.0889)
		(layer "In2.Cu")
		(net "M_I_CPU1_SB_DQ<13>")
	)
	(arc
		(start 133.881876 -283.318966)
		(mid 134.164832 -283.242789)
		(end 134.447788 -283.318966)
		(width 0.0889)
		(layer "In2.Cu")
		(net "M_I_CPU1_SB_DQ<13>")
	)
	(arc
		(start 136.327642 -283.318966)
		(mid 136.509893 -283.369316)
		(end 136.693402 -283.323792)
		(width 0.0889)
		(layer "In2.Cu")
		(net "M_I_CPU1_SB_DQ<13>")
	)
	(arc
		(start 138.581892 -283.318966)
		(mid 138.864848 -283.242789)
		(end 139.147804 -283.318966)
		(width 0.0889)
		(layer "In2.Cu")
		(net "M_I_CPU1_SB_DQ<13>")
	)
	(arc
		(start 136.701784 -283.318966)
		(mid 136.98474 -283.242789)
		(end 137.267696 -283.318966)
		(width 0.0889)
		(layer "In2.Cu")
		(net "M_I_CPU1_SB_DQ<13>")
	)
	(arc
		(start 129.18186 -283.318966)
		(mid 129.464816 -283.242789)
		(end 129.747772 -283.318966)
		(width 0.0889)
		(layer "In2.Cu")
		(net "M_I_CPU1_SB_DQ<13>")
	)
	(arc
		(start 129.756154 -283.323792)
		(mid 129.939662 -283.369286)
		(end 130.121914 -283.318966)
		(width 0.0889)
		(layer "In2.Cu")
		(net "M_I_CPU1_SB_DQ<13>")
	)
	(arc
		(start 145.159984 -283.31922)
		(mid 145.255384 -283.274938)
		(end 145.357342 -283.249116)
		(width 0.0889)
		(layer "In2.Cu")
		(net "M_I_CPU1_SB_DQ<13>")
	)
	(arc
		(start 139.147804 -283.318966)
		(mid 139.334748 -283.369221)
		(end 139.521692 -283.318966)
		(width 0.0889)
		(layer "In2.Cu")
		(net "M_I_CPU1_SB_DQ<13>")
	)
	(segment
		(start 128.997964 -281.920442)
		(end 129.464816 -282.18638)
		(width 0.10668)
		(layer "F.Cu")
		(net "M_I_CPU1_SB_DQ<12>")
	)
	(segment
		(start 174.437548 -296.369994)
		(end 177.49393 -296.369994)
		(width 0.14478)
		(layer "In2.Cu")
		(net "M_I_CPU1_SB_DQ<12>")
	)
	(segment
		(start 129.61874 -282.45181)
		(end 129.714752 -282.47721)
		(width 0.0889)
		(layer "In2.Cu")
		(net "M_I_CPU1_SB_DQ<12>")
	)
	(segment
		(start 173.58741 -297.220132)
		(end 174.437548 -296.369994)
		(width 0.14478)
		(layer "In2.Cu")
		(net "M_I_CPU1_SB_DQ<12>")
	)
	(segment
		(start 131.157726 -282.50896)
		(end 131.166108 -282.513786)
		(width 0.0889)
		(layer "In2.Cu")
		(net "M_I_CPU1_SB_DQ<12>")
	)
	(segment
		(start 143.377666 -282.50896)
		(end 143.386048 -282.513786)
		(width 0.0889)
		(layer "In2.Cu")
		(net "M_I_CPU1_SB_DQ<12>")
	)
	(segment
		(start 145.258028 -282.508706)
		(end 145.276316 -282.51912)
		(width 0.0889)
		(layer "In2.Cu")
		(net "M_I_CPU1_SB_DQ<12>")
	)
	(segment
		(start 169.863516 -296.369994)
		(end 170.713654 -297.220132)
		(width 0.14478)
		(layer "In2.Cu")
		(net "M_I_CPU1_SB_DQ<12>")
	)
	(segment
		(start 148.56841 -282.693364)
		(end 163.095178 -297.220132)
		(width 0.14478)
		(layer "In2.Cu")
		(net "M_I_CPU1_SB_DQ<12>")
	)
	(segment
		(start 178.327812 -296.698924)
		(end 178.66614 -296.360596)
		(width 0.14478)
		(layer "In2.Cu")
		(net "M_I_CPU1_SB_DQ<12>")
	)
	(segment
		(start 132.09778 -282.50896)
		(end 132.106162 -282.513786)
		(width 0.0889)
		(layer "In2.Cu")
		(net "M_I_CPU1_SB_DQ<12>")
	)
	(segment
		(start 177.49393 -296.369994)
		(end 177.82286 -296.698924)
		(width 0.14478)
		(layer "In2.Cu")
		(net "M_I_CPU1_SB_DQ<12>")
	)
	(segment
		(start 130.583432 -282.513786)
		(end 130.591814 -282.50896)
		(width 0.0889)
		(layer "In2.Cu")
		(net "M_I_CPU1_SB_DQ<12>")
	)
	(segment
		(start 147.218146 -283.102304)
		(end 147.627086 -282.693364)
		(width 0.0889)
		(layer "In2.Cu")
		(net "M_I_CPU1_SB_DQ<12>")
	)
	(segment
		(start 140.557758 -282.50896)
		(end 140.56614 -282.513786)
		(width 0.0889)
		(layer "In2.Cu")
		(net "M_I_CPU1_SB_DQ<12>")
	)
	(segment
		(start 139.617704 -282.50896)
		(end 139.626086 -282.513786)
		(width 0.0889)
		(layer "In2.Cu")
		(net "M_I_CPU1_SB_DQ<12>")
	)
	(segment
		(start 144.31772 -282.50896)
		(end 144.329404 -282.515818)
		(width 0.0889)
		(layer "In2.Cu")
		(net "M_I_CPU1_SB_DQ<12>")
	)
	(segment
		(start 138.103356 -282.513786)
		(end 138.111738 -282.50896)
		(width 0.0889)
		(layer "In2.Cu")
		(net "M_I_CPU1_SB_DQ<12>")
	)
	(segment
		(start 146.563334 -283.102304)
		(end 147.218146 -283.102304)
		(width 0.0889)
		(layer "In2.Cu")
		(net "M_I_CPU1_SB_DQ<12>")
	)
	(segment
		(start 134.917688 -282.50896)
		(end 134.92607 -282.513786)
		(width 0.0889)
		(layer "In2.Cu")
		(net "M_I_CPU1_SB_DQ<12>")
	)
	(segment
		(start 170.713654 -297.220132)
		(end 173.58741 -297.220132)
		(width 0.14478)
		(layer "In2.Cu")
		(net "M_I_CPU1_SB_DQ<12>")
	)
	(segment
		(start 129.464816 -282.18638)
		(end 129.61874 -282.45181)
		(width 0.0889)
		(layer "In2.Cu")
		(net "M_I_CPU1_SB_DQ<12>")
	)
	(segment
		(start 177.82286 -296.698924)
		(end 178.327812 -296.698924)
		(width 0.14478)
		(layer "In2.Cu")
		(net "M_I_CPU1_SB_DQ<12>")
	)
	(segment
		(start 167.083232 -296.369994)
		(end 169.863516 -296.369994)
		(width 0.14478)
		(layer "In2.Cu")
		(net "M_I_CPU1_SB_DQ<12>")
	)
	(segment
		(start 165.882574 -297.220132)
		(end 166.480998 -296.972228)
		(width 0.14478)
		(layer "In2.Cu")
		(net "M_I_CPU1_SB_DQ<12>")
	)
	(segment
		(start 163.095178 -297.220132)
		(end 165.882574 -297.220132)
		(width 0.14478)
		(layer "In2.Cu")
		(net "M_I_CPU1_SB_DQ<12>")
	)
	(segment
		(start 145.24228 -282.499562)
		(end 145.258028 -282.508706)
		(width 0.0889)
		(layer "In2.Cu")
		(net "M_I_CPU1_SB_DQ<12>")
	)
	(segment
		(start 145.444718 -282.559506)
		(end 146.020536 -282.559506)
		(width 0.0889)
		(layer "In2.Cu")
		(net "M_I_CPU1_SB_DQ<12>")
	)
	(segment
		(start 134.343394 -282.513786)
		(end 134.351776 -282.50896)
		(width 0.0889)
		(layer "In2.Cu")
		(net "M_I_CPU1_SB_DQ<12>")
	)
	(segment
		(start 147.890992 -282.693364)
		(end 148.56841 -282.693364)
		(width 0.14478)
		(layer "In2.Cu")
		(net "M_I_CPU1_SB_DQ<12>")
	)
	(segment
		(start 166.480998 -296.972228)
		(end 167.083232 -296.369994)
		(width 0.14478)
		(layer "In2.Cu")
		(net "M_I_CPU1_SB_DQ<12>")
	)
	(segment
		(start 178.66614 -296.360596)
		(end 183.191404 -296.360596)
		(width 0.14478)
		(layer "In2.Cu")
		(net "M_I_CPU1_SB_DQ<12>")
	)
	(segment
		(start 183.191404 -296.360596)
		(end 183.616092 -296.785284)
		(width 0.14478)
		(layer "In2.Cu")
		(net "M_I_CPU1_SB_DQ<12>")
	)
	(segment
		(start 135.857742 -282.50896)
		(end 135.866124 -282.513786)
		(width 0.0889)
		(layer "In2.Cu")
		(net "M_I_CPU1_SB_DQ<12>")
	)
	(segment
		(start 139.04341 -282.513786)
		(end 139.051792 -282.50896)
		(width 0.0889)
		(layer "In2.Cu")
		(net "M_I_CPU1_SB_DQ<12>")
	)
	(segment
		(start 147.627086 -282.693364)
		(end 147.890992 -282.693364)
		(width 0.0889)
		(layer "In2.Cu")
		(net "M_I_CPU1_SB_DQ<12>")
	)
	(segment
		(start 146.020536 -282.559506)
		(end 146.563334 -283.102304)
		(width 0.0889)
		(layer "In2.Cu")
		(net "M_I_CPU1_SB_DQ<12>")
	)
	(segment
		(start 142.803372 -282.513786)
		(end 142.811754 -282.50896)
		(width 0.0889)
		(layer "In2.Cu")
		(net "M_I_CPU1_SB_DQ<12>")
	)
	(arc
		(start 140.56614 -282.513786)
		(mid 140.749648 -282.55928)
		(end 140.9319 -282.50896)
		(width 0.0889)
		(layer "In2.Cu")
		(net "M_I_CPU1_SB_DQ<12>")
	)
	(arc
		(start 142.437612 -282.50896)
		(mid 142.619863 -282.55931)
		(end 142.803372 -282.513786)
		(width 0.0889)
		(layer "In2.Cu")
		(net "M_I_CPU1_SB_DQ<12>")
	)
	(arc
		(start 135.866124 -282.513786)
		(mid 136.049632 -282.55928)
		(end 136.231884 -282.50896)
		(width 0.0889)
		(layer "In2.Cu")
		(net "M_I_CPU1_SB_DQ<12>")
	)
	(arc
		(start 134.92607 -282.513786)
		(mid 135.109578 -282.55928)
		(end 135.29183 -282.50896)
		(width 0.0889)
		(layer "In2.Cu")
		(net "M_I_CPU1_SB_DQ<12>")
	)
	(arc
		(start 140.9319 -282.50896)
		(mid 141.214856 -282.432783)
		(end 141.497812 -282.50896)
		(width 0.0889)
		(layer "In2.Cu")
		(net "M_I_CPU1_SB_DQ<12>")
	)
	(arc
		(start 130.591814 -282.50896)
		(mid 130.87477 -282.432783)
		(end 131.157726 -282.50896)
		(width 0.0889)
		(layer "In2.Cu")
		(net "M_I_CPU1_SB_DQ<12>")
	)
	(arc
		(start 131.166108 -282.513786)
		(mid 131.349616 -282.55928)
		(end 131.531868 -282.50896)
		(width 0.0889)
		(layer "In2.Cu")
		(net "M_I_CPU1_SB_DQ<12>")
	)
	(arc
		(start 138.67765 -282.50896)
		(mid 138.859901 -282.55931)
		(end 139.04341 -282.513786)
		(width 0.0889)
		(layer "In2.Cu")
		(net "M_I_CPU1_SB_DQ<12>")
	)
	(arc
		(start 133.411722 -282.50896)
		(mid 133.694678 -282.432783)
		(end 133.977634 -282.50896)
		(width 0.0889)
		(layer "In2.Cu")
		(net "M_I_CPU1_SB_DQ<12>")
	)
	(arc
		(start 142.811754 -282.50896)
		(mid 143.09471 -282.432783)
		(end 143.377666 -282.50896)
		(width 0.0889)
		(layer "In2.Cu")
		(net "M_I_CPU1_SB_DQ<12>")
	)
	(arc
		(start 143.386048 -282.513786)
		(mid 143.569556 -282.55928)
		(end 143.751808 -282.50896)
		(width 0.0889)
		(layer "In2.Cu")
		(net "M_I_CPU1_SB_DQ<12>")
	)
	(arc
		(start 129.714752 -282.47721)
		(mid 129.96996 -282.433733)
		(end 130.217672 -282.50896)
		(width 0.0889)
		(layer "In2.Cu")
		(net "M_I_CPU1_SB_DQ<12>")
	)
	(arc
		(start 144.692116 -282.50896)
		(mid 144.965971 -282.43261)
		(end 145.24228 -282.499562)
		(width 0.0889)
		(layer "In2.Cu")
		(net "M_I_CPU1_SB_DQ<12>")
	)
	(arc
		(start 143.751808 -282.50896)
		(mid 144.034764 -282.432783)
		(end 144.31772 -282.50896)
		(width 0.0889)
		(layer "In2.Cu")
		(net "M_I_CPU1_SB_DQ<12>")
	)
	(arc
		(start 132.106162 -282.513786)
		(mid 132.28967 -282.55928)
		(end 132.471922 -282.50896)
		(width 0.0889)
		(layer "In2.Cu")
		(net "M_I_CPU1_SB_DQ<12>")
	)
	(arc
		(start 130.217672 -282.50896)
		(mid 130.399923 -282.55931)
		(end 130.583432 -282.513786)
		(width 0.0889)
		(layer "In2.Cu")
		(net "M_I_CPU1_SB_DQ<12>")
	)
	(arc
		(start 135.29183 -282.50896)
		(mid 135.574786 -282.432783)
		(end 135.857742 -282.50896)
		(width 0.0889)
		(layer "In2.Cu")
		(net "M_I_CPU1_SB_DQ<12>")
	)
	(arc
		(start 139.626086 -282.513786)
		(mid 139.809594 -282.55928)
		(end 139.991846 -282.50896)
		(width 0.0889)
		(layer "In2.Cu")
		(net "M_I_CPU1_SB_DQ<12>")
	)
	(arc
		(start 137.737596 -282.50896)
		(mid 137.919847 -282.55931)
		(end 138.103356 -282.513786)
		(width 0.0889)
		(layer "In2.Cu")
		(net "M_I_CPU1_SB_DQ<12>")
	)
	(arc
		(start 138.111738 -282.50896)
		(mid 138.394694 -282.432783)
		(end 138.67765 -282.50896)
		(width 0.0889)
		(layer "In2.Cu")
		(net "M_I_CPU1_SB_DQ<12>")
	)
	(arc
		(start 139.051792 -282.50896)
		(mid 139.334748 -282.432783)
		(end 139.617704 -282.50896)
		(width 0.0889)
		(layer "In2.Cu")
		(net "M_I_CPU1_SB_DQ<12>")
	)
	(arc
		(start 133.977634 -282.50896)
		(mid 134.159885 -282.55931)
		(end 134.343394 -282.513786)
		(width 0.0889)
		(layer "In2.Cu")
		(net "M_I_CPU1_SB_DQ<12>")
	)
	(arc
		(start 137.171684 -282.50896)
		(mid 137.45464 -282.432783)
		(end 137.737596 -282.50896)
		(width 0.0889)
		(layer "In2.Cu")
		(net "M_I_CPU1_SB_DQ<12>")
	)
	(arc
		(start 144.329404 -282.515818)
		(mid 144.511659 -282.559471)
		(end 144.692116 -282.50896)
		(width 0.0889)
		(layer "In2.Cu")
		(net "M_I_CPU1_SB_DQ<12>")
	)
	(arc
		(start 134.351776 -282.50896)
		(mid 134.634732 -282.432783)
		(end 134.917688 -282.50896)
		(width 0.0889)
		(layer "In2.Cu")
		(net "M_I_CPU1_SB_DQ<12>")
	)
	(arc
		(start 132.471922 -282.50896)
		(mid 132.754878 -282.432783)
		(end 133.037834 -282.50896)
		(width 0.0889)
		(layer "In2.Cu")
		(net "M_I_CPU1_SB_DQ<12>")
	)
	(arc
		(start 133.037834 -282.50896)
		(mid 133.224778 -282.559215)
		(end 133.411722 -282.50896)
		(width 0.0889)
		(layer "In2.Cu")
		(net "M_I_CPU1_SB_DQ<12>")
	)
	(arc
		(start 145.276316 -282.51912)
		(mid 145.35814 -282.549233)
		(end 145.444718 -282.559506)
		(width 0.0889)
		(layer "In2.Cu")
		(net "M_I_CPU1_SB_DQ<12>")
	)
	(arc
		(start 139.991846 -282.50896)
		(mid 140.274802 -282.432783)
		(end 140.557758 -282.50896)
		(width 0.0889)
		(layer "In2.Cu")
		(net "M_I_CPU1_SB_DQ<12>")
	)
	(arc
		(start 131.531868 -282.50896)
		(mid 131.814824 -282.432783)
		(end 132.09778 -282.50896)
		(width 0.0889)
		(layer "In2.Cu")
		(net "M_I_CPU1_SB_DQ<12>")
	)
	(arc
		(start 136.797796 -282.50896)
		(mid 136.98474 -282.559215)
		(end 137.171684 -282.50896)
		(width 0.0889)
		(layer "In2.Cu")
		(net "M_I_CPU1_SB_DQ<12>")
	)
	(arc
		(start 141.8717 -282.50896)
		(mid 142.154656 -282.432783)
		(end 142.437612 -282.50896)
		(width 0.0889)
		(layer "In2.Cu")
		(net "M_I_CPU1_SB_DQ<12>")
	)
	(arc
		(start 136.231884 -282.50896)
		(mid 136.51484 -282.432783)
		(end 136.797796 -282.50896)
		(width 0.0889)
		(layer "In2.Cu")
		(net "M_I_CPU1_SB_DQ<12>")
	)
	(arc
		(start 141.497812 -282.50896)
		(mid 141.684756 -282.559215)
		(end 141.8717 -282.50896)
		(width 0.0889)
		(layer "In2.Cu")
		(net "M_I_CPU1_SB_DQ<12>")
	)
	(segment
		(start 128.05791 -280.30043)
		(end 128.524762 -280.566368)
		(width 0.10668)
		(layer "F.Cu")
		(net "M_I_CPU1_SB_DQ<11>")
	)
	(segment
		(start 170.004232 -292.736524)
		(end 170.502072 -292.943026)
		(width 0.14478)
		(layer "In2.Cu")
		(net "M_I_CPU1_SB_DQ<11>")
	)
	(segment
		(start 140.557758 -280.243788)
		(end 140.56614 -280.238962)
		(width 0.0889)
		(layer "In2.Cu")
		(net "M_I_CPU1_SB_DQ<11>")
	)
	(segment
		(start 128.370838 -280.300938)
		(end 128.39319 -280.217626)
		(width 0.0889)
		(layer "In2.Cu")
		(net "M_I_CPU1_SB_DQ<11>")
	)
	(segment
		(start 175.233838 -292.950646)
		(end 177.333402 -292.950646)
		(width 0.14478)
		(layer "In2.Cu")
		(net "M_I_CPU1_SB_DQ<11>")
	)
	(segment
		(start 153.79573 -284.486604)
		(end 153.957274 -284.648148)
		(width 0.14478)
		(layer "In2.Cu")
		(net "M_I_CPU1_SB_DQ<11>")
	)
	(segment
		(start 171.202858 -293.80053)
		(end 172.954696 -293.80053)
		(width 0.14478)
		(layer "In2.Cu")
		(net "M_I_CPU1_SB_DQ<11>")
	)
	(segment
		(start 178.18227 -293.412418)
		(end 178.44135 -293.412418)
		(width 0.14478)
		(layer "In2.Cu")
		(net "M_I_CPU1_SB_DQ<11>")
	)
	(segment
		(start 174.211996 -292.960298)
		(end 174.58563 -292.586664)
		(width 0.14478)
		(layer "In2.Cu")
		(net "M_I_CPU1_SB_DQ<11>")
	)
	(segment
		(start 179.150772 -293.019988)
		(end 179.516024 -293.38524)
		(width 0.14478)
		(layer "In2.Cu")
		(net "M_I_CPU1_SB_DQ<11>")
	)
	(segment
		(start 154.000708 -283.824426)
		(end 154.000708 -284.053026)
		(width 0.14478)
		(layer "In2.Cu")
		(net "M_I_CPU1_SB_DQ<11>")
	)
	(segment
		(start 147.550886 -280.354024)
		(end 147.896834 -280.354024)
		(width 0.0889)
		(layer "In2.Cu")
		(net "M_I_CPU1_SB_DQ<11>")
	)
	(segment
		(start 166.617396 -293.255446)
		(end 166.922196 -292.950646)
		(width 0.14478)
		(layer "In2.Cu")
		(net "M_I_CPU1_SB_DQ<11>")
	)
	(segment
		(start 178.03241 -292.815264)
		(end 178.03241 -293.262558)
		(width 0.14478)
		(layer "In2.Cu")
		(net "M_I_CPU1_SB_DQ<11>")
	)
	(segment
		(start 128.524762 -280.566368)
		(end 128.370838 -280.300938)
		(width 0.0889)
		(layer "In2.Cu")
		(net "M_I_CPU1_SB_DQ<11>")
	)
	(segment
		(start 170.502072 -292.943026)
		(end 170.613324 -293.210996)
		(width 0.14478)
		(layer "In2.Cu")
		(net "M_I_CPU1_SB_DQ<11>")
	)
	(segment
		(start 178.74107 -292.622224)
		(end 179.000912 -292.622224)
		(width 0.14478)
		(layer "In2.Cu")
		(net "M_I_CPU1_SB_DQ<11>")
	)
	(segment
		(start 166.922196 -292.950646)
		(end 169.488612 -292.950646)
		(width 0.14478)
		(layer "In2.Cu")
		(net "M_I_CPU1_SB_DQ<11>")
	)
	(segment
		(start 178.44135 -293.412418)
		(end 178.59121 -293.262558)
		(width 0.14478)
		(layer "In2.Cu")
		(net "M_I_CPU1_SB_DQ<11>")
	)
	(segment
		(start 174.58563 -292.586664)
		(end 174.869856 -292.586664)
		(width 0.14478)
		(layer "In2.Cu")
		(net "M_I_CPU1_SB_DQ<11>")
	)
	(segment
		(start 135.857742 -280.243788)
		(end 135.866124 -280.238962)
		(width 0.0889)
		(layer "In2.Cu")
		(net "M_I_CPU1_SB_DQ<11>")
	)
	(segment
		(start 134.343394 -280.238962)
		(end 134.351776 -280.243788)
		(width 0.0889)
		(layer "In2.Cu")
		(net "M_I_CPU1_SB_DQ<11>")
	)
	(segment
		(start 153.79573 -284.258004)
		(end 153.79573 -284.486604)
		(width 0.14478)
		(layer "In2.Cu")
		(net "M_I_CPU1_SB_DQ<11>")
	)
	(segment
		(start 153.610564 -283.662882)
		(end 153.839164 -283.662882)
		(width 0.14478)
		(layer "In2.Cu")
		(net "M_I_CPU1_SB_DQ<11>")
	)
	(segment
		(start 177.333402 -292.950646)
		(end 177.618644 -292.665404)
		(width 0.14478)
		(layer "In2.Cu")
		(net "M_I_CPU1_SB_DQ<11>")
	)
	(segment
		(start 153.17724 -283.868114)
		(end 153.405332 -283.868114)
		(width 0.14478)
		(layer "In2.Cu")
		(net "M_I_CPU1_SB_DQ<11>")
	)
	(segment
		(start 138.103356 -280.238962)
		(end 138.111738 -280.243788)
		(width 0.0889)
		(layer "In2.Cu")
		(net "M_I_CPU1_SB_DQ<11>")
	)
	(segment
		(start 153.957274 -284.648148)
		(end 154.185874 -284.648148)
		(width 0.14478)
		(layer "In2.Cu")
		(net "M_I_CPU1_SB_DQ<11>")
	)
	(segment
		(start 165.301168 -293.80053)
		(end 165.695122 -293.637208)
		(width 0.14478)
		(layer "In2.Cu")
		(net "M_I_CPU1_SB_DQ<11>")
	)
	(segment
		(start 131.157726 -280.243788)
		(end 131.166108 -280.238962)
		(width 0.0889)
		(layer "In2.Cu")
		(net "M_I_CPU1_SB_DQ<11>")
	)
	(segment
		(start 166.468044 -293.317168)
		(end 166.617396 -293.255446)
		(width 0.14478)
		(layer "In2.Cu")
		(net "M_I_CPU1_SB_DQ<11>")
	)
	(segment
		(start 154.185874 -284.648148)
		(end 154.390852 -284.44317)
		(width 0.14478)
		(layer "In2.Cu")
		(net "M_I_CPU1_SB_DQ<11>")
	)
	(segment
		(start 166.105078 -293.166292)
		(end 166.468044 -293.317168)
		(width 0.14478)
		(layer "In2.Cu")
		(net "M_I_CPU1_SB_DQ<11>")
	)
	(segment
		(start 142.803372 -280.238962)
		(end 142.811754 -280.243788)
		(width 0.0889)
		(layer "In2.Cu")
		(net "M_I_CPU1_SB_DQ<11>")
	)
	(segment
		(start 178.59121 -292.772084)
		(end 178.74107 -292.622224)
		(width 0.14478)
		(layer "In2.Cu")
		(net "M_I_CPU1_SB_DQ<11>")
	)
	(segment
		(start 169.488612 -292.950646)
		(end 170.004232 -292.736524)
		(width 0.14478)
		(layer "In2.Cu")
		(net "M_I_CPU1_SB_DQ<11>")
	)
	(segment
		(start 163.45535 -293.64559)
		(end 163.61029 -293.80053)
		(width 0.14478)
		(layer "In2.Cu")
		(net "M_I_CPU1_SB_DQ<11>")
	)
	(segment
		(start 173.99 -293.108888)
		(end 174.211996 -292.960298)
		(width 0.14478)
		(layer "In2.Cu")
		(net "M_I_CPU1_SB_DQ<11>")
	)
	(segment
		(start 153.839164 -283.662882)
		(end 154.000708 -283.824426)
		(width 0.14478)
		(layer "In2.Cu")
		(net "M_I_CPU1_SB_DQ<11>")
	)
	(segment
		(start 173.315884 -293.55923)
		(end 173.665134 -293.62908)
		(width 0.14478)
		(layer "In2.Cu")
		(net "M_I_CPU1_SB_DQ<11>")
	)
	(segment
		(start 179.150772 -292.772084)
		(end 179.150772 -293.019988)
		(width 0.14478)
		(layer "In2.Cu")
		(net "M_I_CPU1_SB_DQ<11>")
	)
	(segment
		(start 143.377666 -280.243788)
		(end 143.386048 -280.238962)
		(width 0.0889)
		(layer "In2.Cu")
		(net "M_I_CPU1_SB_DQ<11>")
	)
	(segment
		(start 144.315688 -280.244042)
		(end 144.337532 -280.231596)
		(width 0.0889)
		(layer "In2.Cu")
		(net "M_I_CPU1_SB_DQ<11>")
	)
	(segment
		(start 144.289526 -280.259028)
		(end 144.315688 -280.244042)
		(width 0.0889)
		(layer "In2.Cu")
		(net "M_I_CPU1_SB_DQ<11>")
	)
	(segment
		(start 139.04341 -280.238962)
		(end 139.051792 -280.243788)
		(width 0.0889)
		(layer "In2.Cu")
		(net "M_I_CPU1_SB_DQ<11>")
	)
	(segment
		(start 178.59121 -293.262558)
		(end 178.59121 -292.772084)
		(width 0.14478)
		(layer "In2.Cu")
		(net "M_I_CPU1_SB_DQ<11>")
	)
	(segment
		(start 144.688306 -280.243788)
		(end 144.71777 -280.26106)
		(width 0.0889)
		(layer "In2.Cu")
		(net "M_I_CPU1_SB_DQ<11>")
	)
	(segment
		(start 154.619452 -284.44317)
		(end 163.45535 -293.278052)
		(width 0.14478)
		(layer "In2.Cu")
		(net "M_I_CPU1_SB_DQ<11>")
	)
	(segment
		(start 177.618644 -292.665404)
		(end 177.88255 -292.665404)
		(width 0.14478)
		(layer "In2.Cu")
		(net "M_I_CPU1_SB_DQ<11>")
	)
	(segment
		(start 173.665134 -293.62908)
		(end 173.920658 -293.458138)
		(width 0.14478)
		(layer "In2.Cu")
		(net "M_I_CPU1_SB_DQ<11>")
	)
	(segment
		(start 177.88255 -292.665404)
		(end 178.03241 -292.815264)
		(width 0.14478)
		(layer "In2.Cu")
		(net "M_I_CPU1_SB_DQ<11>")
	)
	(segment
		(start 179.000912 -292.622224)
		(end 179.150772 -292.772084)
		(width 0.14478)
		(layer "In2.Cu")
		(net "M_I_CPU1_SB_DQ<11>")
	)
	(segment
		(start 165.695122 -293.637208)
		(end 165.845236 -293.273988)
		(width 0.14478)
		(layer "In2.Cu")
		(net "M_I_CPU1_SB_DQ<11>")
	)
	(segment
		(start 178.03241 -293.262558)
		(end 178.18227 -293.412418)
		(width 0.14478)
		(layer "In2.Cu")
		(net "M_I_CPU1_SB_DQ<11>")
	)
	(segment
		(start 139.617704 -280.243788)
		(end 139.626086 -280.238962)
		(width 0.0889)
		(layer "In2.Cu")
		(net "M_I_CPU1_SB_DQ<11>")
	)
	(segment
		(start 154.000708 -284.053026)
		(end 153.79573 -284.258004)
		(width 0.14478)
		(layer "In2.Cu")
		(net "M_I_CPU1_SB_DQ<11>")
	)
	(segment
		(start 130.583432 -280.238962)
		(end 130.591814 -280.243788)
		(width 0.0889)
		(layer "In2.Cu")
		(net "M_I_CPU1_SB_DQ<11>")
	)
	(segment
		(start 147.396454 -280.199592)
		(end 147.550886 -280.354024)
		(width 0.0889)
		(layer "In2.Cu")
		(net "M_I_CPU1_SB_DQ<11>")
	)
	(segment
		(start 163.61029 -293.80053)
		(end 165.301168 -293.80053)
		(width 0.14478)
		(layer "In2.Cu")
		(net "M_I_CPU1_SB_DQ<11>")
	)
	(segment
		(start 173.920658 -293.458138)
		(end 173.99 -293.108888)
		(width 0.14478)
		(layer "In2.Cu")
		(net "M_I_CPU1_SB_DQ<11>")
	)
	(segment
		(start 172.954696 -293.80053)
		(end 173.315884 -293.55923)
		(width 0.14478)
		(layer "In2.Cu")
		(net "M_I_CPU1_SB_DQ<11>")
	)
	(segment
		(start 153.405332 -283.868114)
		(end 153.610564 -283.662882)
		(width 0.14478)
		(layer "In2.Cu")
		(net "M_I_CPU1_SB_DQ<11>")
	)
	(segment
		(start 163.45535 -293.278052)
		(end 163.45535 -293.64559)
		(width 0.14478)
		(layer "In2.Cu")
		(net "M_I_CPU1_SB_DQ<11>")
	)
	(segment
		(start 132.09778 -280.243788)
		(end 132.106162 -280.238962)
		(width 0.0889)
		(layer "In2.Cu")
		(net "M_I_CPU1_SB_DQ<11>")
	)
	(segment
		(start 165.845236 -293.273988)
		(end 166.105078 -293.166292)
		(width 0.14478)
		(layer "In2.Cu")
		(net "M_I_CPU1_SB_DQ<11>")
	)
	(segment
		(start 147.896834 -280.354024)
		(end 149.662896 -280.354024)
		(width 0.14478)
		(layer "In2.Cu")
		(net "M_I_CPU1_SB_DQ<11>")
	)
	(segment
		(start 174.869856 -292.586664)
		(end 175.233838 -292.950646)
		(width 0.14478)
		(layer "In2.Cu")
		(net "M_I_CPU1_SB_DQ<11>")
	)
	(segment
		(start 129.643378 -280.238962)
		(end 129.65176 -280.243788)
		(width 0.0889)
		(layer "In2.Cu")
		(net "M_I_CPU1_SB_DQ<11>")
	)
	(segment
		(start 149.662896 -280.354024)
		(end 153.17724 -283.868114)
		(width 0.14478)
		(layer "In2.Cu")
		(net "M_I_CPU1_SB_DQ<11>")
	)
	(segment
		(start 154.390852 -284.44317)
		(end 154.619452 -284.44317)
		(width 0.14478)
		(layer "In2.Cu")
		(net "M_I_CPU1_SB_DQ<11>")
	)
	(segment
		(start 145.373852 -280.199592)
		(end 147.396454 -280.199592)
		(width 0.0889)
		(layer "In2.Cu")
		(net "M_I_CPU1_SB_DQ<11>")
	)
	(segment
		(start 134.917688 -280.243788)
		(end 134.92607 -280.238962)
		(width 0.0889)
		(layer "In2.Cu")
		(net "M_I_CPU1_SB_DQ<11>")
	)
	(segment
		(start 170.613324 -293.210996)
		(end 171.202858 -293.80053)
		(width 0.14478)
		(layer "In2.Cu")
		(net "M_I_CPU1_SB_DQ<11>")
	)
	(arc
		(start 138.111738 -280.243788)
		(mid 138.394694 -280.319965)
		(end 138.67765 -280.243788)
		(width 0.0889)
		(layer "In2.Cu")
		(net "M_I_CPU1_SB_DQ<11>")
	)
	(arc
		(start 142.437612 -280.243788)
		(mid 142.619863 -280.193438)
		(end 142.803372 -280.238962)
		(width 0.0889)
		(layer "In2.Cu")
		(net "M_I_CPU1_SB_DQ<11>")
	)
	(arc
		(start 131.166108 -280.238962)
		(mid 131.349616 -280.193468)
		(end 131.531868 -280.243788)
		(width 0.0889)
		(layer "In2.Cu")
		(net "M_I_CPU1_SB_DQ<11>")
	)
	(arc
		(start 128.711706 -280.243788)
		(mid 128.994662 -280.319965)
		(end 129.277618 -280.243788)
		(width 0.0889)
		(layer "In2.Cu")
		(net "M_I_CPU1_SB_DQ<11>")
	)
	(arc
		(start 136.231884 -280.243788)
		(mid 136.51484 -280.319965)
		(end 136.797796 -280.243788)
		(width 0.0889)
		(layer "In2.Cu")
		(net "M_I_CPU1_SB_DQ<11>")
	)
	(arc
		(start 130.217672 -280.243788)
		(mid 130.399923 -280.193438)
		(end 130.583432 -280.238962)
		(width 0.0889)
		(layer "In2.Cu")
		(net "M_I_CPU1_SB_DQ<11>")
	)
	(arc
		(start 144.71777 -280.26106)
		(mid 144.98919 -280.320737)
		(end 145.25625 -280.243788)
		(width 0.0889)
		(layer "In2.Cu")
		(net "M_I_CPU1_SB_DQ<11>")
	)
	(arc
		(start 130.591814 -280.243788)
		(mid 130.87477 -280.319965)
		(end 131.157726 -280.243788)
		(width 0.0889)
		(layer "In2.Cu")
		(net "M_I_CPU1_SB_DQ<11>")
	)
	(arc
		(start 135.29183 -280.243788)
		(mid 135.574786 -280.319965)
		(end 135.857742 -280.243788)
		(width 0.0889)
		(layer "In2.Cu")
		(net "M_I_CPU1_SB_DQ<11>")
	)
	(arc
		(start 137.737596 -280.243788)
		(mid 137.919847 -280.193438)
		(end 138.103356 -280.238962)
		(width 0.0889)
		(layer "In2.Cu")
		(net "M_I_CPU1_SB_DQ<11>")
	)
	(arc
		(start 139.051792 -280.243788)
		(mid 139.334748 -280.319965)
		(end 139.617704 -280.243788)
		(width 0.0889)
		(layer "In2.Cu")
		(net "M_I_CPU1_SB_DQ<11>")
	)
	(arc
		(start 132.471922 -280.243788)
		(mid 132.754878 -280.319965)
		(end 133.037834 -280.243788)
		(width 0.0889)
		(layer "In2.Cu")
		(net "M_I_CPU1_SB_DQ<11>")
	)
	(arc
		(start 141.497812 -280.243788)
		(mid 141.684756 -280.193533)
		(end 141.8717 -280.243788)
		(width 0.0889)
		(layer "In2.Cu")
		(net "M_I_CPU1_SB_DQ<11>")
	)
	(arc
		(start 133.411722 -280.243788)
		(mid 133.694678 -280.319965)
		(end 133.977634 -280.243788)
		(width 0.0889)
		(layer "In2.Cu")
		(net "M_I_CPU1_SB_DQ<11>")
	)
	(arc
		(start 144.337532 -280.231596)
		(mid 144.51446 -280.193768)
		(end 144.688306 -280.243788)
		(width 0.0889)
		(layer "In2.Cu")
		(net "M_I_CPU1_SB_DQ<11>")
	)
	(arc
		(start 133.037834 -280.243788)
		(mid 133.224778 -280.193533)
		(end 133.411722 -280.243788)
		(width 0.0889)
		(layer "In2.Cu")
		(net "M_I_CPU1_SB_DQ<11>")
	)
	(arc
		(start 133.977634 -280.243788)
		(mid 134.159885 -280.193438)
		(end 134.343394 -280.238962)
		(width 0.0889)
		(layer "In2.Cu")
		(net "M_I_CPU1_SB_DQ<11>")
	)
	(arc
		(start 128.39319 -280.217626)
		(mid 128.555379 -280.194891)
		(end 128.711706 -280.243788)
		(width 0.0889)
		(layer "In2.Cu")
		(net "M_I_CPU1_SB_DQ<11>")
	)
	(arc
		(start 134.351776 -280.243788)
		(mid 134.634732 -280.319965)
		(end 134.917688 -280.243788)
		(width 0.0889)
		(layer "In2.Cu")
		(net "M_I_CPU1_SB_DQ<11>")
	)
	(arc
		(start 129.277618 -280.243788)
		(mid 129.459869 -280.193438)
		(end 129.643378 -280.238962)
		(width 0.0889)
		(layer "In2.Cu")
		(net "M_I_CPU1_SB_DQ<11>")
	)
	(arc
		(start 141.8717 -280.243788)
		(mid 142.154656 -280.319965)
		(end 142.437612 -280.243788)
		(width 0.0889)
		(layer "In2.Cu")
		(net "M_I_CPU1_SB_DQ<11>")
	)
	(arc
		(start 143.386048 -280.238962)
		(mid 143.569556 -280.193468)
		(end 143.751808 -280.243788)
		(width 0.0889)
		(layer "In2.Cu")
		(net "M_I_CPU1_SB_DQ<11>")
	)
	(arc
		(start 131.531868 -280.243788)
		(mid 131.814824 -280.319965)
		(end 132.09778 -280.243788)
		(width 0.0889)
		(layer "In2.Cu")
		(net "M_I_CPU1_SB_DQ<11>")
	)
	(arc
		(start 138.67765 -280.243788)
		(mid 138.859901 -280.193438)
		(end 139.04341 -280.238962)
		(width 0.0889)
		(layer "In2.Cu")
		(net "M_I_CPU1_SB_DQ<11>")
	)
	(arc
		(start 136.797796 -280.243788)
		(mid 136.98474 -280.193533)
		(end 137.171684 -280.243788)
		(width 0.0889)
		(layer "In2.Cu")
		(net "M_I_CPU1_SB_DQ<11>")
	)
	(arc
		(start 135.866124 -280.238962)
		(mid 136.049632 -280.193468)
		(end 136.231884 -280.243788)
		(width 0.0889)
		(layer "In2.Cu")
		(net "M_I_CPU1_SB_DQ<11>")
	)
	(arc
		(start 140.56614 -280.238962)
		(mid 140.749648 -280.193468)
		(end 140.9319 -280.243788)
		(width 0.0889)
		(layer "In2.Cu")
		(net "M_I_CPU1_SB_DQ<11>")
	)
	(arc
		(start 145.25625 -280.243788)
		(mid 145.313174 -280.216691)
		(end 145.373852 -280.199592)
		(width 0.0889)
		(layer "In2.Cu")
		(net "M_I_CPU1_SB_DQ<11>")
	)
	(arc
		(start 139.991846 -280.243788)
		(mid 140.274802 -280.319965)
		(end 140.557758 -280.243788)
		(width 0.0889)
		(layer "In2.Cu")
		(net "M_I_CPU1_SB_DQ<11>")
	)
	(arc
		(start 139.626086 -280.238962)
		(mid 139.809594 -280.193468)
		(end 139.991846 -280.243788)
		(width 0.0889)
		(layer "In2.Cu")
		(net "M_I_CPU1_SB_DQ<11>")
	)
	(arc
		(start 134.92607 -280.238962)
		(mid 135.109578 -280.193468)
		(end 135.29183 -280.243788)
		(width 0.0889)
		(layer "In2.Cu")
		(net "M_I_CPU1_SB_DQ<11>")
	)
	(arc
		(start 137.171684 -280.243788)
		(mid 137.45464 -280.319965)
		(end 137.737596 -280.243788)
		(width 0.0889)
		(layer "In2.Cu")
		(net "M_I_CPU1_SB_DQ<11>")
	)
	(arc
		(start 143.751808 -280.243788)
		(mid 144.018738 -280.319737)
		(end 144.289526 -280.259028)
		(width 0.0889)
		(layer "In2.Cu")
		(net "M_I_CPU1_SB_DQ<11>")
	)
	(arc
		(start 132.106162 -280.238962)
		(mid 132.28967 -280.193468)
		(end 132.471922 -280.243788)
		(width 0.0889)
		(layer "In2.Cu")
		(net "M_I_CPU1_SB_DQ<11>")
	)
	(arc
		(start 129.65176 -280.243788)
		(mid 129.934716 -280.319965)
		(end 130.217672 -280.243788)
		(width 0.0889)
		(layer "In2.Cu")
		(net "M_I_CPU1_SB_DQ<11>")
	)
	(arc
		(start 142.811754 -280.243788)
		(mid 143.09471 -280.319965)
		(end 143.377666 -280.243788)
		(width 0.0889)
		(layer "In2.Cu")
		(net "M_I_CPU1_SB_DQ<11>")
	)
	(arc
		(start 140.9319 -280.243788)
		(mid 141.214856 -280.319965)
		(end 141.497812 -280.243788)
		(width 0.0889)
		(layer "In2.Cu")
		(net "M_I_CPU1_SB_DQ<11>")
	)
	(segment
		(start 129.467864 -279.490424)
		(end 129.934716 -279.756362)
		(width 0.10668)
		(layer "F.Cu")
		(net "M_I_CPU1_SB_DQ<10>")
	)
	(segment
		(start 173.73219 -291.235384)
		(end 174.253398 -291.451792)
		(width 0.14478)
		(layer "In2.Cu")
		(net "M_I_CPU1_SB_DQ<10>")
	)
	(segment
		(start 153.89098 -282.424378)
		(end 163.577016 -292.110414)
		(width 0.14478)
		(layer "In2.Cu")
		(net "M_I_CPU1_SB_DQ<10>")
	)
	(segment
		(start 153.272744 -281.806142)
		(end 153.272744 -282.034234)
		(width 0.14478)
		(layer "In2.Cu")
		(net "M_I_CPU1_SB_DQ<10>")
	)
	(segment
		(start 152.8826 -281.64409)
		(end 153.110692 -281.64409)
		(width 0.14478)
		(layer "In2.Cu")
		(net "M_I_CPU1_SB_DQ<10>")
	)
	(segment
		(start 147.403566 -278.913844)
		(end 147.632166 -279.142444)
		(width 0.0889)
		(layer "In2.Cu")
		(net "M_I_CPU1_SB_DQ<10>")
	)
	(segment
		(start 151.712168 -280.473658)
		(end 151.497538 -280.688034)
		(width 0.14478)
		(layer "In2.Cu")
		(net "M_I_CPU1_SB_DQ<10>")
	)
	(segment
		(start 141.393418 -279.428956)
		(end 141.4018 -279.433782)
		(width 0.0889)
		(layer "In2.Cu")
		(net "M_I_CPU1_SB_DQ<10>")
	)
	(segment
		(start 169.554652 -291.380418)
		(end 169.750232 -291.299138)
		(width 0.14478)
		(layer "In2.Cu")
		(net "M_I_CPU1_SB_DQ<10>")
	)
	(segment
		(start 153.448258 -282.638754)
		(end 153.662888 -282.424378)
		(width 0.14478)
		(layer "In2.Cu")
		(net "M_I_CPU1_SB_DQ<10>")
	)
	(segment
		(start 178.600862 -291.260276)
		(end 179.091082 -291.260276)
		(width 0.14478)
		(layer "In2.Cu")
		(net "M_I_CPU1_SB_DQ<10>")
	)
	(segment
		(start 166.379652 -291.856414)
		(end 166.23792 -291.513006)
		(width 0.14478)
		(layer "In2.Cu")
		(net "M_I_CPU1_SB_DQ<10>")
	)
	(segment
		(start 150.71725 -280.135838)
		(end 150.879302 -280.29789)
		(width 0.14478)
		(layer "In2.Cu")
		(net "M_I_CPU1_SB_DQ<10>")
	)
	(segment
		(start 135.753348 -279.428956)
		(end 135.76173 -279.433782)
		(width 0.0889)
		(layer "In2.Cu")
		(net "M_I_CPU1_SB_DQ<10>")
	)
	(segment
		(start 167.281352 -291.260276)
		(end 167.64 -291.618924)
		(width 0.14478)
		(layer "In2.Cu")
		(net "M_I_CPU1_SB_DQ<10>")
	)
	(segment
		(start 179.091082 -291.260276)
		(end 179.516024 -291.685218)
		(width 0.14478)
		(layer "In2.Cu")
		(net "M_I_CPU1_SB_DQ<10>")
	)
	(segment
		(start 168.29786 -291.260276)
		(end 169.265092 -291.260276)
		(width 0.14478)
		(layer "In2.Cu")
		(net "M_I_CPU1_SB_DQ<10>")
	)
	(segment
		(start 151.497538 -280.916126)
		(end 151.65959 -281.078178)
		(width 0.14478)
		(layer "In2.Cu")
		(net "M_I_CPU1_SB_DQ<10>")
	)
	(segment
		(start 136.693402 -279.428956)
		(end 136.701784 -279.433782)
		(width 0.0889)
		(layer "In2.Cu")
		(net "M_I_CPU1_SB_DQ<10>")
	)
	(segment
		(start 129.780792 -279.490932)
		(end 129.803144 -279.40762)
		(width 0.0889)
		(layer "In2.Cu")
		(net "M_I_CPU1_SB_DQ<10>")
	)
	(segment
		(start 174.71517 -291.260276)
		(end 176.276254 -291.260276)
		(width 0.14478)
		(layer "In2.Cu")
		(net "M_I_CPU1_SB_DQ<10>")
	)
	(segment
		(start 150.609046 -279.142444)
		(end 150.93188 -279.465278)
		(width 0.14478)
		(layer "In2.Cu")
		(net "M_I_CPU1_SB_DQ<10>")
	)
	(segment
		(start 171.138342 -292.110414)
		(end 172.809916 -292.110414)
		(width 0.14478)
		(layer "In2.Cu")
		(net "M_I_CPU1_SB_DQ<10>")
	)
	(segment
		(start 129.934716 -279.756362)
		(end 129.780792 -279.490932)
		(width 0.0889)
		(layer "In2.Cu")
		(net "M_I_CPU1_SB_DQ<10>")
	)
	(segment
		(start 177.285142 -291.260276)
		(end 177.591974 -291.260276)
		(width 0.14478)
		(layer "In2.Cu")
		(net "M_I_CPU1_SB_DQ<10>")
	)
	(segment
		(start 145.43659 -279.510236)
		(end 145.880074 -279.510236)
		(width 0.0889)
		(layer "In2.Cu")
		(net "M_I_CPU1_SB_DQ<10>")
	)
	(segment
		(start 146.476466 -278.913844)
		(end 147.403566 -278.913844)
		(width 0.0889)
		(layer "In2.Cu")
		(net "M_I_CPU1_SB_DQ<10>")
	)
	(segment
		(start 173.492414 -291.334952)
		(end 173.73219 -291.235384)
		(width 0.14478)
		(layer "In2.Cu")
		(net "M_I_CPU1_SB_DQ<10>")
	)
	(segment
		(start 166.908734 -291.3634)
		(end 167.158162 -291.260276)
		(width 0.14478)
		(layer "In2.Cu")
		(net "M_I_CPU1_SB_DQ<10>")
	)
	(segment
		(start 165.323012 -292.110414)
		(end 165.642036 -291.978334)
		(width 0.14478)
		(layer "In2.Cu")
		(net "M_I_CPU1_SB_DQ<10>")
	)
	(segment
		(start 166.017956 -292.13429)
		(end 166.315644 -292.0111)
		(width 0.14478)
		(layer "In2.Cu")
		(net "M_I_CPU1_SB_DQ<10>")
	)
	(segment
		(start 153.058114 -282.24861)
		(end 153.058114 -282.476702)
		(width 0.14478)
		(layer "In2.Cu")
		(net "M_I_CPU1_SB_DQ<10>")
	)
	(segment
		(start 167.64 -291.618924)
		(end 167.939212 -291.618924)
		(width 0.14478)
		(layer "In2.Cu")
		(net "M_I_CPU1_SB_DQ<10>")
	)
	(segment
		(start 153.272744 -282.034234)
		(end 153.058114 -282.24861)
		(width 0.14478)
		(layer "In2.Cu")
		(net "M_I_CPU1_SB_DQ<10>")
	)
	(segment
		(start 170.346624 -291.320474)
		(end 170.266614 -291.51326)
		(width 0.14478)
		(layer "In2.Cu")
		(net "M_I_CPU1_SB_DQ<10>")
	)
	(segment
		(start 147.632166 -279.142444)
		(end 147.99437 -279.142444)
		(width 0.0889)
		(layer "In2.Cu")
		(net "M_I_CPU1_SB_DQ<10>")
	)
	(segment
		(start 152.330404 -280.863802)
		(end 152.492456 -281.025854)
		(width 0.14478)
		(layer "In2.Cu")
		(net "M_I_CPU1_SB_DQ<10>")
	)
	(segment
		(start 165.642036 -291.978334)
		(end 166.017956 -292.13429)
		(width 0.14478)
		(layer "In2.Cu")
		(net "M_I_CPU1_SB_DQ<10>")
	)
	(segment
		(start 145.16227 -279.434036)
		(end 145.178018 -279.44318)
		(width 0.0889)
		(layer "In2.Cu")
		(net "M_I_CPU1_SB_DQ<10>")
	)
	(segment
		(start 176.627282 -291.611304)
		(end 176.934114 -291.611304)
		(width 0.14478)
		(layer "In2.Cu")
		(net "M_I_CPU1_SB_DQ<10>")
	)
	(segment
		(start 170.385232 -291.798502)
		(end 171.138342 -292.110414)
		(width 0.14478)
		(layer "In2.Cu")
		(net "M_I_CPU1_SB_DQ<10>")
	)
	(segment
		(start 167.158162 -291.260276)
		(end 167.281352 -291.260276)
		(width 0.14478)
		(layer "In2.Cu")
		(net "M_I_CPU1_SB_DQ<10>")
	)
	(segment
		(start 177.943002 -291.611304)
		(end 178.249834 -291.611304)
		(width 0.14478)
		(layer "In2.Cu")
		(net "M_I_CPU1_SB_DQ<10>")
	)
	(segment
		(start 176.934114 -291.611304)
		(end 177.285142 -291.260276)
		(width 0.14478)
		(layer "In2.Cu")
		(net "M_I_CPU1_SB_DQ<10>")
	)
	(segment
		(start 150.71725 -279.907746)
		(end 150.71725 -280.135838)
		(width 0.14478)
		(layer "In2.Cu")
		(net "M_I_CPU1_SB_DQ<10>")
	)
	(segment
		(start 145.143982 -279.423622)
		(end 145.16227 -279.434036)
		(width 0.0889)
		(layer "In2.Cu")
		(net "M_I_CPU1_SB_DQ<10>")
	)
	(segment
		(start 152.102312 -280.863802)
		(end 152.330404 -280.863802)
		(width 0.14478)
		(layer "In2.Cu")
		(net "M_I_CPU1_SB_DQ<10>")
	)
	(segment
		(start 174.253398 -291.451792)
		(end 174.71517 -291.260276)
		(width 0.14478)
		(layer "In2.Cu")
		(net "M_I_CPU1_SB_DQ<10>")
	)
	(segment
		(start 151.887682 -281.078178)
		(end 152.102312 -280.863802)
		(width 0.14478)
		(layer "In2.Cu")
		(net "M_I_CPU1_SB_DQ<10>")
	)
	(segment
		(start 166.315644 -292.0111)
		(end 166.379652 -291.856414)
		(width 0.14478)
		(layer "In2.Cu")
		(net "M_I_CPU1_SB_DQ<10>")
	)
	(segment
		(start 153.110692 -281.64409)
		(end 153.272744 -281.806142)
		(width 0.14478)
		(layer "In2.Cu")
		(net "M_I_CPU1_SB_DQ<10>")
	)
	(segment
		(start 151.550116 -280.083514)
		(end 151.712168 -280.245566)
		(width 0.14478)
		(layer "In2.Cu")
		(net "M_I_CPU1_SB_DQ<10>")
	)
	(segment
		(start 178.249834 -291.611304)
		(end 178.600862 -291.260276)
		(width 0.14478)
		(layer "In2.Cu")
		(net "M_I_CPU1_SB_DQ<10>")
	)
	(segment
		(start 150.879302 -280.29789)
		(end 151.107394 -280.29789)
		(width 0.14478)
		(layer "In2.Cu")
		(net "M_I_CPU1_SB_DQ<10>")
	)
	(segment
		(start 173.244764 -291.930074)
		(end 173.492414 -291.334952)
		(width 0.14478)
		(layer "In2.Cu")
		(net "M_I_CPU1_SB_DQ<10>")
	)
	(segment
		(start 138.20775 -279.433782)
		(end 138.216132 -279.428956)
		(width 0.0889)
		(layer "In2.Cu")
		(net "M_I_CPU1_SB_DQ<10>")
	)
	(segment
		(start 152.277826 -281.696414)
		(end 152.439878 -281.858466)
		(width 0.14478)
		(layer "In2.Cu")
		(net "M_I_CPU1_SB_DQ<10>")
	)
	(segment
		(start 151.712168 -280.245566)
		(end 151.712168 -280.473658)
		(width 0.14478)
		(layer "In2.Cu")
		(net "M_I_CPU1_SB_DQ<10>")
	)
	(segment
		(start 170.265344 -291.12464)
		(end 170.346624 -291.320474)
		(width 0.14478)
		(layer "In2.Cu")
		(net "M_I_CPU1_SB_DQ<10>")
	)
	(segment
		(start 167.939212 -291.618924)
		(end 168.29786 -291.260276)
		(width 0.14478)
		(layer "In2.Cu")
		(net "M_I_CPU1_SB_DQ<10>")
	)
	(segment
		(start 140.453364 -279.428956)
		(end 140.461746 -279.433782)
		(width 0.0889)
		(layer "In2.Cu")
		(net "M_I_CPU1_SB_DQ<10>")
	)
	(segment
		(start 131.993386 -279.428956)
		(end 132.001768 -279.433782)
		(width 0.0889)
		(layer "In2.Cu")
		(net "M_I_CPU1_SB_DQ<10>")
	)
	(segment
		(start 153.662888 -282.424378)
		(end 153.89098 -282.424378)
		(width 0.14478)
		(layer "In2.Cu")
		(net "M_I_CPU1_SB_DQ<10>")
	)
	(segment
		(start 153.058114 -282.476702)
		(end 153.220166 -282.638754)
		(width 0.14478)
		(layer "In2.Cu")
		(net "M_I_CPU1_SB_DQ<10>")
	)
	(segment
		(start 132.93344 -279.428956)
		(end 132.941822 -279.433782)
		(width 0.0889)
		(layer "In2.Cu")
		(net "M_I_CPU1_SB_DQ<10>")
	)
	(segment
		(start 169.265092 -291.260276)
		(end 169.554652 -291.380418)
		(width 0.14478)
		(layer "In2.Cu")
		(net "M_I_CPU1_SB_DQ<10>")
	)
	(segment
		(start 166.59987 -291.23513)
		(end 166.908734 -291.3634)
		(width 0.14478)
		(layer "In2.Cu")
		(net "M_I_CPU1_SB_DQ<10>")
	)
	(segment
		(start 169.750232 -291.299138)
		(end 169.830242 -291.106606)
		(width 0.14478)
		(layer "In2.Cu")
		(net "M_I_CPU1_SB_DQ<10>")
	)
	(segment
		(start 152.492456 -281.025854)
		(end 152.492456 -281.253946)
		(width 0.14478)
		(layer "In2.Cu")
		(net "M_I_CPU1_SB_DQ<10>")
	)
	(segment
		(start 151.107394 -280.29789)
		(end 151.322024 -280.083514)
		(width 0.14478)
		(layer "In2.Cu")
		(net "M_I_CPU1_SB_DQ<10>")
	)
	(segment
		(start 152.66797 -281.858466)
		(end 152.8826 -281.64409)
		(width 0.14478)
		(layer "In2.Cu")
		(net "M_I_CPU1_SB_DQ<10>")
	)
	(segment
		(start 133.507734 -279.433782)
		(end 133.516116 -279.428956)
		(width 0.0889)
		(layer "In2.Cu")
		(net "M_I_CPU1_SB_DQ<10>")
	)
	(segment
		(start 151.65959 -281.078178)
		(end 151.887682 -281.078178)
		(width 0.14478)
		(layer "In2.Cu")
		(net "M_I_CPU1_SB_DQ<10>")
	)
	(segment
		(start 166.23792 -291.513006)
		(end 166.301928 -291.358574)
		(width 0.14478)
		(layer "In2.Cu")
		(net "M_I_CPU1_SB_DQ<10>")
	)
	(segment
		(start 145.880074 -279.510236)
		(end 146.476466 -278.913844)
		(width 0.0889)
		(layer "In2.Cu")
		(net "M_I_CPU1_SB_DQ<10>")
	)
	(segment
		(start 153.220166 -282.638754)
		(end 153.448258 -282.638754)
		(width 0.14478)
		(layer "In2.Cu")
		(net "M_I_CPU1_SB_DQ<10>")
	)
	(segment
		(start 170.266614 -291.51326)
		(end 170.385232 -291.798502)
		(width 0.14478)
		(layer "In2.Cu")
		(net "M_I_CPU1_SB_DQ<10>")
	)
	(segment
		(start 144.221708 -279.433782)
		(end 144.23644 -279.442418)
		(width 0.0889)
		(layer "In2.Cu")
		(net "M_I_CPU1_SB_DQ<10>")
	)
	(segment
		(start 144.213326 -279.428956)
		(end 144.221708 -279.433782)
		(width 0.0889)
		(layer "In2.Cu")
		(net "M_I_CPU1_SB_DQ<10>")
	)
	(segment
		(start 137.267696 -279.433782)
		(end 137.276078 -279.428956)
		(width 0.0889)
		(layer "In2.Cu")
		(net "M_I_CPU1_SB_DQ<10>")
	)
	(segment
		(start 150.93188 -279.465278)
		(end 150.93188 -279.69337)
		(width 0.14478)
		(layer "In2.Cu")
		(net "M_I_CPU1_SB_DQ<10>")
	)
	(segment
		(start 163.577016 -292.110414)
		(end 165.323012 -292.110414)
		(width 0.14478)
		(layer "In2.Cu")
		(net "M_I_CPU1_SB_DQ<10>")
	)
	(segment
		(start 169.830242 -291.106606)
		(end 170.025822 -291.025326)
		(width 0.14478)
		(layer "In2.Cu")
		(net "M_I_CPU1_SB_DQ<10>")
	)
	(segment
		(start 177.591974 -291.260276)
		(end 177.943002 -291.611304)
		(width 0.14478)
		(layer "In2.Cu")
		(net "M_I_CPU1_SB_DQ<10>")
	)
	(segment
		(start 166.301928 -291.358574)
		(end 166.59987 -291.23513)
		(width 0.14478)
		(layer "In2.Cu")
		(net "M_I_CPU1_SB_DQ<10>")
	)
	(segment
		(start 151.322024 -280.083514)
		(end 151.550116 -280.083514)
		(width 0.14478)
		(layer "In2.Cu")
		(net "M_I_CPU1_SB_DQ<10>")
	)
	(segment
		(start 172.809916 -292.110414)
		(end 173.244764 -291.930074)
		(width 0.14478)
		(layer "In2.Cu")
		(net "M_I_CPU1_SB_DQ<10>")
	)
	(segment
		(start 147.99437 -279.142444)
		(end 150.609046 -279.142444)
		(width 0.14478)
		(layer "In2.Cu")
		(net "M_I_CPU1_SB_DQ<10>")
	)
	(segment
		(start 150.93188 -279.69337)
		(end 150.71725 -279.907746)
		(width 0.14478)
		(layer "In2.Cu")
		(net "M_I_CPU1_SB_DQ<10>")
	)
	(segment
		(start 152.439878 -281.858466)
		(end 152.66797 -281.858466)
		(width 0.14478)
		(layer "In2.Cu")
		(net "M_I_CPU1_SB_DQ<10>")
	)
	(segment
		(start 176.276254 -291.260276)
		(end 176.627282 -291.611304)
		(width 0.14478)
		(layer "In2.Cu")
		(net "M_I_CPU1_SB_DQ<10>")
	)
	(segment
		(start 151.497538 -280.688034)
		(end 151.497538 -280.916126)
		(width 0.14478)
		(layer "In2.Cu")
		(net "M_I_CPU1_SB_DQ<10>")
	)
	(segment
		(start 141.967712 -279.433782)
		(end 141.976094 -279.428956)
		(width 0.0889)
		(layer "In2.Cu")
		(net "M_I_CPU1_SB_DQ<10>")
	)
	(segment
		(start 152.492456 -281.253946)
		(end 152.277826 -281.468322)
		(width 0.14478)
		(layer "In2.Cu")
		(net "M_I_CPU1_SB_DQ<10>")
	)
	(segment
		(start 152.277826 -281.468322)
		(end 152.277826 -281.696414)
		(width 0.14478)
		(layer "In2.Cu")
		(net "M_I_CPU1_SB_DQ<10>")
	)
	(segment
		(start 170.025822 -291.025326)
		(end 170.265344 -291.12464)
		(width 0.14478)
		(layer "In2.Cu")
		(net "M_I_CPU1_SB_DQ<10>")
	)
	(arc
		(start 141.976094 -279.428956)
		(mid 142.159602 -279.383462)
		(end 142.341854 -279.433782)
		(width 0.0889)
		(layer "In2.Cu")
		(net "M_I_CPU1_SB_DQ<10>")
	)
	(arc
		(start 142.341854 -279.433782)
		(mid 142.62481 -279.509959)
		(end 142.907766 -279.433782)
		(width 0.0889)
		(layer "In2.Cu")
		(net "M_I_CPU1_SB_DQ<10>")
	)
	(arc
		(start 134.821676 -279.433782)
		(mid 135.104632 -279.509959)
		(end 135.387588 -279.433782)
		(width 0.0889)
		(layer "In2.Cu")
		(net "M_I_CPU1_SB_DQ<10>")
	)
	(arc
		(start 136.327642 -279.433782)
		(mid 136.509893 -279.383432)
		(end 136.693402 -279.428956)
		(width 0.0889)
		(layer "In2.Cu")
		(net "M_I_CPU1_SB_DQ<10>")
	)
	(arc
		(start 135.76173 -279.433782)
		(mid 136.044686 -279.509959)
		(end 136.327642 -279.433782)
		(width 0.0889)
		(layer "In2.Cu")
		(net "M_I_CPU1_SB_DQ<10>")
	)
	(arc
		(start 141.4018 -279.433782)
		(mid 141.684756 -279.509959)
		(end 141.967712 -279.433782)
		(width 0.0889)
		(layer "In2.Cu")
		(net "M_I_CPU1_SB_DQ<10>")
	)
	(arc
		(start 141.027658 -279.433782)
		(mid 141.209909 -279.383432)
		(end 141.393418 -279.428956)
		(width 0.0889)
		(layer "In2.Cu")
		(net "M_I_CPU1_SB_DQ<10>")
	)
	(arc
		(start 136.701784 -279.433782)
		(mid 136.98474 -279.509959)
		(end 137.267696 -279.433782)
		(width 0.0889)
		(layer "In2.Cu")
		(net "M_I_CPU1_SB_DQ<10>")
	)
	(arc
		(start 131.627626 -279.433782)
		(mid 131.809877 -279.383432)
		(end 131.993386 -279.428956)
		(width 0.0889)
		(layer "In2.Cu")
		(net "M_I_CPU1_SB_DQ<10>")
	)
	(arc
		(start 144.23644 -279.442418)
		(mid 144.513423 -279.510222)
		(end 144.788128 -279.433782)
		(width 0.0889)
		(layer "In2.Cu")
		(net "M_I_CPU1_SB_DQ<10>")
	)
	(arc
		(start 132.941822 -279.433782)
		(mid 133.224778 -279.509959)
		(end 133.507734 -279.433782)
		(width 0.0889)
		(layer "In2.Cu")
		(net "M_I_CPU1_SB_DQ<10>")
	)
	(arc
		(start 139.521692 -279.433782)
		(mid 139.804648 -279.509959)
		(end 140.087604 -279.433782)
		(width 0.0889)
		(layer "In2.Cu")
		(net "M_I_CPU1_SB_DQ<10>")
	)
	(arc
		(start 143.281654 -279.433782)
		(mid 143.56461 -279.509959)
		(end 143.847566 -279.433782)
		(width 0.0889)
		(layer "In2.Cu")
		(net "M_I_CPU1_SB_DQ<10>")
	)
	(arc
		(start 133.881876 -279.433782)
		(mid 134.164832 -279.509959)
		(end 134.447788 -279.433782)
		(width 0.0889)
		(layer "In2.Cu")
		(net "M_I_CPU1_SB_DQ<10>")
	)
	(arc
		(start 133.516116 -279.428956)
		(mid 133.699624 -279.383462)
		(end 133.881876 -279.433782)
		(width 0.0889)
		(layer "In2.Cu")
		(net "M_I_CPU1_SB_DQ<10>")
	)
	(arc
		(start 139.147804 -279.433782)
		(mid 139.334748 -279.383527)
		(end 139.521692 -279.433782)
		(width 0.0889)
		(layer "In2.Cu")
		(net "M_I_CPU1_SB_DQ<10>")
	)
	(arc
		(start 137.276078 -279.428956)
		(mid 137.459586 -279.383462)
		(end 137.641838 -279.433782)
		(width 0.0889)
		(layer "In2.Cu")
		(net "M_I_CPU1_SB_DQ<10>")
	)
	(arc
		(start 132.001768 -279.433782)
		(mid 132.284724 -279.509959)
		(end 132.56768 -279.433782)
		(width 0.0889)
		(layer "In2.Cu")
		(net "M_I_CPU1_SB_DQ<10>")
	)
	(arc
		(start 130.687826 -279.433782)
		(mid 130.87477 -279.383527)
		(end 131.061714 -279.433782)
		(width 0.0889)
		(layer "In2.Cu")
		(net "M_I_CPU1_SB_DQ<10>")
	)
	(arc
		(start 129.803144 -279.40762)
		(mid 129.965476 -279.384802)
		(end 130.121914 -279.433782)
		(width 0.0889)
		(layer "In2.Cu")
		(net "M_I_CPU1_SB_DQ<10>")
	)
	(arc
		(start 144.788128 -279.433782)
		(mid 144.964756 -279.383549)
		(end 145.143982 -279.423622)
		(width 0.0889)
		(layer "In2.Cu")
		(net "M_I_CPU1_SB_DQ<10>")
	)
	(arc
		(start 132.56768 -279.433782)
		(mid 132.749931 -279.383432)
		(end 132.93344 -279.428956)
		(width 0.0889)
		(layer "In2.Cu")
		(net "M_I_CPU1_SB_DQ<10>")
	)
	(arc
		(start 131.061714 -279.433782)
		(mid 131.34467 -279.509959)
		(end 131.627626 -279.433782)
		(width 0.0889)
		(layer "In2.Cu")
		(net "M_I_CPU1_SB_DQ<10>")
	)
	(arc
		(start 130.121914 -279.433782)
		(mid 130.40487 -279.509959)
		(end 130.687826 -279.433782)
		(width 0.0889)
		(layer "In2.Cu")
		(net "M_I_CPU1_SB_DQ<10>")
	)
	(arc
		(start 138.581892 -279.433782)
		(mid 138.864848 -279.509959)
		(end 139.147804 -279.433782)
		(width 0.0889)
		(layer "In2.Cu")
		(net "M_I_CPU1_SB_DQ<10>")
	)
	(arc
		(start 134.447788 -279.433782)
		(mid 134.634732 -279.383527)
		(end 134.821676 -279.433782)
		(width 0.0889)
		(layer "In2.Cu")
		(net "M_I_CPU1_SB_DQ<10>")
	)
	(arc
		(start 142.907766 -279.433782)
		(mid 143.09471 -279.383527)
		(end 143.281654 -279.433782)
		(width 0.0889)
		(layer "In2.Cu")
		(net "M_I_CPU1_SB_DQ<10>")
	)
	(arc
		(start 143.847566 -279.433782)
		(mid 144.029817 -279.383432)
		(end 144.213326 -279.428956)
		(width 0.0889)
		(layer "In2.Cu")
		(net "M_I_CPU1_SB_DQ<10>")
	)
	(arc
		(start 138.216132 -279.428956)
		(mid 138.39964 -279.383462)
		(end 138.581892 -279.433782)
		(width 0.0889)
		(layer "In2.Cu")
		(net "M_I_CPU1_SB_DQ<10>")
	)
	(arc
		(start 135.387588 -279.433782)
		(mid 135.569839 -279.383432)
		(end 135.753348 -279.428956)
		(width 0.0889)
		(layer "In2.Cu")
		(net "M_I_CPU1_SB_DQ<10>")
	)
	(arc
		(start 140.087604 -279.433782)
		(mid 140.269855 -279.383432)
		(end 140.453364 -279.428956)
		(width 0.0889)
		(layer "In2.Cu")
		(net "M_I_CPU1_SB_DQ<10>")
	)
	(arc
		(start 140.461746 -279.433782)
		(mid 140.744702 -279.509959)
		(end 141.027658 -279.433782)
		(width 0.0889)
		(layer "In2.Cu")
		(net "M_I_CPU1_SB_DQ<10>")
	)
	(arc
		(start 145.178018 -279.44318)
		(mid 145.30328 -279.492212)
		(end 145.43659 -279.510236)
		(width 0.0889)
		(layer "In2.Cu")
		(net "M_I_CPU1_SB_DQ<10>")
	)
	(arc
		(start 137.641838 -279.433782)
		(mid 137.924794 -279.509959)
		(end 138.20775 -279.433782)
		(width 0.0889)
		(layer "In2.Cu")
		(net "M_I_CPU1_SB_DQ<10>")
	)
	(segment
		(start 128.997964 -273.820382)
		(end 129.464816 -274.08632)
		(width 0.10668)
		(layer "F.Cu")
		(net "M_I_CPU1_SB_DQ<0>")
	)
	(segment
		(start 158.595822 -278.130254)
		(end 159.440118 -278.130254)
		(width 0.14478)
		(layer "In2.Cu")
		(net "M_I_CPU1_SB_DQ<0>")
	)
	(segment
		(start 146.666458 -273.394424)
		(end 147.164806 -273.394424)
		(width 0.0889)
		(layer "In2.Cu")
		(net "M_I_CPU1_SB_DQ<0>")
	)
	(segment
		(start 147.619466 -272.939764)
		(end 148.052028 -272.939764)
		(width 0.0889)
		(layer "In2.Cu")
		(net "M_I_CPU1_SB_DQ<0>")
	)
	(segment
		(start 173.867572 -280.6573)
		(end 174.846996 -280.6573)
		(width 0.14478)
		(layer "In2.Cu")
		(net "M_I_CPU1_SB_DQ<0>")
	)
	(segment
		(start 144.31772 -274.4089)
		(end 144.329404 -274.415758)
		(width 0.0889)
		(layer "In2.Cu")
		(net "M_I_CPU1_SB_DQ<0>")
	)
	(segment
		(start 165.607746 -282.133294)
		(end 165.847268 -282.03398)
		(width 0.14478)
		(layer "In2.Cu")
		(net "M_I_CPU1_SB_DQ<0>")
	)
	(segment
		(start 134.917688 -274.4089)
		(end 134.92607 -274.413726)
		(width 0.0889)
		(layer "In2.Cu")
		(net "M_I_CPU1_SB_DQ<0>")
	)
	(segment
		(start 165.125146 -281.7495)
		(end 165.320472 -281.83078)
		(width 0.14478)
		(layer "In2.Cu")
		(net "M_I_CPU1_SB_DQ<0>")
	)
	(segment
		(start 171.361354 -281.910282)
		(end 172.24375 -281.910282)
		(width 0.14478)
		(layer "In2.Cu")
		(net "M_I_CPU1_SB_DQ<0>")
	)
	(segment
		(start 164.737288 -281.910282)
		(end 165.125146 -281.7495)
		(width 0.14478)
		(layer "In2.Cu")
		(net "M_I_CPU1_SB_DQ<0>")
	)
	(segment
		(start 170.57497 -281.584654)
		(end 171.361354 -281.910282)
		(width 0.14478)
		(layer "In2.Cu")
		(net "M_I_CPU1_SB_DQ<0>")
	)
	(segment
		(start 145.24228 -274.399502)
		(end 145.258028 -274.408646)
		(width 0.0889)
		(layer "In2.Cu")
		(net "M_I_CPU1_SB_DQ<0>")
	)
	(segment
		(start 165.836854 -281.616912)
		(end 165.918134 -281.421332)
		(width 0.14478)
		(layer "In2.Cu")
		(net "M_I_CPU1_SB_DQ<0>")
	)
	(segment
		(start 129.464816 -274.08632)
		(end 129.61874 -274.35175)
		(width 0.0889)
		(layer "In2.Cu")
		(net "M_I_CPU1_SB_DQ<0>")
	)
	(segment
		(start 165.928548 -281.838146)
		(end 165.836854 -281.616912)
		(width 0.14478)
		(layer "In2.Cu")
		(net "M_I_CPU1_SB_DQ<0>")
	)
	(segment
		(start 153.405332 -272.939764)
		(end 158.595822 -278.130254)
		(width 0.14478)
		(layer "In2.Cu")
		(net "M_I_CPU1_SB_DQ<0>")
	)
	(segment
		(start 174.846996 -280.6573)
		(end 175.820832 -281.060398)
		(width 0.14478)
		(layer "In2.Cu")
		(net "M_I_CPU1_SB_DQ<0>")
	)
	(segment
		(start 131.157726 -274.4089)
		(end 131.166108 -274.413726)
		(width 0.0889)
		(layer "In2.Cu")
		(net "M_I_CPU1_SB_DQ<0>")
	)
	(segment
		(start 139.617704 -274.4089)
		(end 139.626086 -274.413726)
		(width 0.0889)
		(layer "In2.Cu")
		(net "M_I_CPU1_SB_DQ<0>")
	)
	(segment
		(start 142.803372 -274.413726)
		(end 142.811754 -274.4089)
		(width 0.0889)
		(layer "In2.Cu")
		(net "M_I_CPU1_SB_DQ<0>")
	)
	(segment
		(start 138.103356 -274.413726)
		(end 138.111738 -274.4089)
		(width 0.0889)
		(layer "In2.Cu")
		(net "M_I_CPU1_SB_DQ<0>")
	)
	(segment
		(start 134.343394 -274.413726)
		(end 134.351776 -274.4089)
		(width 0.0889)
		(layer "In2.Cu")
		(net "M_I_CPU1_SB_DQ<0>")
	)
	(segment
		(start 173.707552 -281.133296)
		(end 173.707552 -280.81732)
		(width 0.14478)
		(layer "In2.Cu")
		(net "M_I_CPU1_SB_DQ<0>")
	)
	(segment
		(start 129.61874 -274.35175)
		(end 129.714752 -274.37715)
		(width 0.0889)
		(layer "In2.Cu")
		(net "M_I_CPU1_SB_DQ<0>")
	)
	(segment
		(start 165.320472 -281.83078)
		(end 165.412166 -282.052014)
		(width 0.14478)
		(layer "In2.Cu")
		(net "M_I_CPU1_SB_DQ<0>")
	)
	(segment
		(start 183.19115 -281.060398)
		(end 183.616092 -281.48534)
		(width 0.14478)
		(layer "In2.Cu")
		(net "M_I_CPU1_SB_DQ<0>")
	)
	(segment
		(start 139.04341 -274.413726)
		(end 139.051792 -274.4089)
		(width 0.0889)
		(layer "In2.Cu")
		(net "M_I_CPU1_SB_DQ<0>")
	)
	(segment
		(start 169.718482 -281.060398)
		(end 170.490388 -281.380184)
		(width 0.14478)
		(layer "In2.Cu")
		(net "M_I_CPU1_SB_DQ<0>")
	)
	(segment
		(start 132.09778 -274.4089)
		(end 132.106162 -274.413726)
		(width 0.0889)
		(layer "In2.Cu")
		(net "M_I_CPU1_SB_DQ<0>")
	)
	(segment
		(start 165.918134 -281.421332)
		(end 166.7891 -281.060398)
		(width 0.14478)
		(layer "In2.Cu")
		(net "M_I_CPU1_SB_DQ<0>")
	)
	(segment
		(start 143.377666 -274.4089)
		(end 143.386048 -274.413726)
		(width 0.0889)
		(layer "In2.Cu")
		(net "M_I_CPU1_SB_DQ<0>")
	)
	(segment
		(start 130.583432 -274.413726)
		(end 130.591814 -274.4089)
		(width 0.0889)
		(layer "In2.Cu")
		(net "M_I_CPU1_SB_DQ<0>")
	)
	(segment
		(start 148.052028 -272.939764)
		(end 153.405332 -272.939764)
		(width 0.14478)
		(layer "In2.Cu")
		(net "M_I_CPU1_SB_DQ<0>")
	)
	(segment
		(start 135.857742 -274.4089)
		(end 135.866124 -274.413726)
		(width 0.0889)
		(layer "In2.Cu")
		(net "M_I_CPU1_SB_DQ<0>")
	)
	(segment
		(start 145.63217 -274.4089)
		(end 146.666458 -273.394424)
		(width 0.0889)
		(layer "In2.Cu")
		(net "M_I_CPU1_SB_DQ<0>")
	)
	(segment
		(start 166.7891 -281.060398)
		(end 169.718482 -281.060398)
		(width 0.14478)
		(layer "In2.Cu")
		(net "M_I_CPU1_SB_DQ<0>")
	)
	(segment
		(start 175.820832 -281.060398)
		(end 183.19115 -281.060398)
		(width 0.14478)
		(layer "In2.Cu")
		(net "M_I_CPU1_SB_DQ<0>")
	)
	(segment
		(start 163.220146 -281.910282)
		(end 164.737288 -281.910282)
		(width 0.14478)
		(layer "In2.Cu")
		(net "M_I_CPU1_SB_DQ<0>")
	)
	(segment
		(start 147.164806 -273.394424)
		(end 147.619466 -272.939764)
		(width 0.0889)
		(layer "In2.Cu")
		(net "M_I_CPU1_SB_DQ<0>")
	)
	(segment
		(start 165.412166 -282.052014)
		(end 165.607746 -282.133294)
		(width 0.14478)
		(layer "In2.Cu")
		(net "M_I_CPU1_SB_DQ<0>")
	)
	(segment
		(start 173.416214 -281.424634)
		(end 173.707552 -281.133296)
		(width 0.14478)
		(layer "In2.Cu")
		(net "M_I_CPU1_SB_DQ<0>")
	)
	(segment
		(start 145.258028 -274.408646)
		(end 145.276316 -274.41906)
		(width 0.0889)
		(layer "In2.Cu")
		(net "M_I_CPU1_SB_DQ<0>")
	)
	(segment
		(start 165.847268 -282.03398)
		(end 165.928548 -281.838146)
		(width 0.14478)
		(layer "In2.Cu")
		(net "M_I_CPU1_SB_DQ<0>")
	)
	(segment
		(start 170.490388 -281.380184)
		(end 170.57497 -281.584654)
		(width 0.14478)
		(layer "In2.Cu")
		(net "M_I_CPU1_SB_DQ<0>")
	)
	(segment
		(start 140.557758 -274.4089)
		(end 140.56614 -274.413726)
		(width 0.0889)
		(layer "In2.Cu")
		(net "M_I_CPU1_SB_DQ<0>")
	)
	(segment
		(start 173.707552 -280.81732)
		(end 173.867572 -280.6573)
		(width 0.14478)
		(layer "In2.Cu")
		(net "M_I_CPU1_SB_DQ<0>")
	)
	(segment
		(start 172.24375 -281.910282)
		(end 173.416214 -281.424634)
		(width 0.14478)
		(layer "In2.Cu")
		(net "M_I_CPU1_SB_DQ<0>")
	)
	(segment
		(start 159.440118 -278.130254)
		(end 163.220146 -281.910282)
		(width 0.14478)
		(layer "In2.Cu")
		(net "M_I_CPU1_SB_DQ<0>")
	)
	(arc
		(start 136.797796 -274.4089)
		(mid 136.98474 -274.459155)
		(end 137.171684 -274.4089)
		(width 0.0889)
		(layer "In2.Cu")
		(net "M_I_CPU1_SB_DQ<0>")
	)
	(arc
		(start 136.231884 -274.4089)
		(mid 136.51484 -274.332723)
		(end 136.797796 -274.4089)
		(width 0.0889)
		(layer "In2.Cu")
		(net "M_I_CPU1_SB_DQ<0>")
	)
	(arc
		(start 130.217672 -274.4089)
		(mid 130.399923 -274.45925)
		(end 130.583432 -274.413726)
		(width 0.0889)
		(layer "In2.Cu")
		(net "M_I_CPU1_SB_DQ<0>")
	)
	(arc
		(start 134.92607 -274.413726)
		(mid 135.109578 -274.45922)
		(end 135.29183 -274.4089)
		(width 0.0889)
		(layer "In2.Cu")
		(net "M_I_CPU1_SB_DQ<0>")
	)
	(arc
		(start 145.276316 -274.41906)
		(mid 145.455545 -274.459213)
		(end 145.63217 -274.4089)
		(width 0.0889)
		(layer "In2.Cu")
		(net "M_I_CPU1_SB_DQ<0>")
	)
	(arc
		(start 132.106162 -274.413726)
		(mid 132.28967 -274.45922)
		(end 132.471922 -274.4089)
		(width 0.0889)
		(layer "In2.Cu")
		(net "M_I_CPU1_SB_DQ<0>")
	)
	(arc
		(start 135.29183 -274.4089)
		(mid 135.574786 -274.332723)
		(end 135.857742 -274.4089)
		(width 0.0889)
		(layer "In2.Cu")
		(net "M_I_CPU1_SB_DQ<0>")
	)
	(arc
		(start 137.737596 -274.4089)
		(mid 137.919847 -274.45925)
		(end 138.103356 -274.413726)
		(width 0.0889)
		(layer "In2.Cu")
		(net "M_I_CPU1_SB_DQ<0>")
	)
	(arc
		(start 144.329404 -274.415758)
		(mid 144.511659 -274.459411)
		(end 144.692116 -274.4089)
		(width 0.0889)
		(layer "In2.Cu")
		(net "M_I_CPU1_SB_DQ<0>")
	)
	(arc
		(start 131.166108 -274.413726)
		(mid 131.349616 -274.45922)
		(end 131.531868 -274.4089)
		(width 0.0889)
		(layer "In2.Cu")
		(net "M_I_CPU1_SB_DQ<0>")
	)
	(arc
		(start 129.714752 -274.37715)
		(mid 129.96996 -274.333673)
		(end 130.217672 -274.4089)
		(width 0.0889)
		(layer "In2.Cu")
		(net "M_I_CPU1_SB_DQ<0>")
	)
	(arc
		(start 143.386048 -274.413726)
		(mid 143.569556 -274.45922)
		(end 143.751808 -274.4089)
		(width 0.0889)
		(layer "In2.Cu")
		(net "M_I_CPU1_SB_DQ<0>")
	)
	(arc
		(start 143.751808 -274.4089)
		(mid 144.034764 -274.332723)
		(end 144.31772 -274.4089)
		(width 0.0889)
		(layer "In2.Cu")
		(net "M_I_CPU1_SB_DQ<0>")
	)
	(arc
		(start 138.67765 -274.4089)
		(mid 138.859901 -274.45925)
		(end 139.04341 -274.413726)
		(width 0.0889)
		(layer "In2.Cu")
		(net "M_I_CPU1_SB_DQ<0>")
	)
	(arc
		(start 140.9319 -274.4089)
		(mid 141.214856 -274.332723)
		(end 141.497812 -274.4089)
		(width 0.0889)
		(layer "In2.Cu")
		(net "M_I_CPU1_SB_DQ<0>")
	)
	(arc
		(start 133.977634 -274.4089)
		(mid 134.159885 -274.45925)
		(end 134.343394 -274.413726)
		(width 0.0889)
		(layer "In2.Cu")
		(net "M_I_CPU1_SB_DQ<0>")
	)
	(arc
		(start 131.531868 -274.4089)
		(mid 131.814824 -274.332723)
		(end 132.09778 -274.4089)
		(width 0.0889)
		(layer "In2.Cu")
		(net "M_I_CPU1_SB_DQ<0>")
	)
	(arc
		(start 141.497812 -274.4089)
		(mid 141.684756 -274.459155)
		(end 141.8717 -274.4089)
		(width 0.0889)
		(layer "In2.Cu")
		(net "M_I_CPU1_SB_DQ<0>")
	)
	(arc
		(start 144.692116 -274.4089)
		(mid 144.965971 -274.33255)
		(end 145.24228 -274.399502)
		(width 0.0889)
		(layer "In2.Cu")
		(net "M_I_CPU1_SB_DQ<0>")
	)
	(arc
		(start 134.351776 -274.4089)
		(mid 134.634732 -274.332723)
		(end 134.917688 -274.4089)
		(width 0.0889)
		(layer "In2.Cu")
		(net "M_I_CPU1_SB_DQ<0>")
	)
	(arc
		(start 130.591814 -274.4089)
		(mid 130.87477 -274.332723)
		(end 131.157726 -274.4089)
		(width 0.0889)
		(layer "In2.Cu")
		(net "M_I_CPU1_SB_DQ<0>")
	)
	(arc
		(start 139.626086 -274.413726)
		(mid 139.809594 -274.45922)
		(end 139.991846 -274.4089)
		(width 0.0889)
		(layer "In2.Cu")
		(net "M_I_CPU1_SB_DQ<0>")
	)
	(arc
		(start 140.56614 -274.413726)
		(mid 140.749648 -274.45922)
		(end 140.9319 -274.4089)
		(width 0.0889)
		(layer "In2.Cu")
		(net "M_I_CPU1_SB_DQ<0>")
	)
	(arc
		(start 139.051792 -274.4089)
		(mid 139.334748 -274.332723)
		(end 139.617704 -274.4089)
		(width 0.0889)
		(layer "In2.Cu")
		(net "M_I_CPU1_SB_DQ<0>")
	)
	(arc
		(start 135.866124 -274.413726)
		(mid 136.049632 -274.45922)
		(end 136.231884 -274.4089)
		(width 0.0889)
		(layer "In2.Cu")
		(net "M_I_CPU1_SB_DQ<0>")
	)
	(arc
		(start 133.037834 -274.4089)
		(mid 133.224778 -274.459155)
		(end 133.411722 -274.4089)
		(width 0.0889)
		(layer "In2.Cu")
		(net "M_I_CPU1_SB_DQ<0>")
	)
	(arc
		(start 132.471922 -274.4089)
		(mid 132.754878 -274.332723)
		(end 133.037834 -274.4089)
		(width 0.0889)
		(layer "In2.Cu")
		(net "M_I_CPU1_SB_DQ<0>")
	)
	(arc
		(start 138.111738 -274.4089)
		(mid 138.394694 -274.332723)
		(end 138.67765 -274.4089)
		(width 0.0889)
		(layer "In2.Cu")
		(net "M_I_CPU1_SB_DQ<0>")
	)
	(arc
		(start 141.8717 -274.4089)
		(mid 142.154656 -274.332723)
		(end 142.437612 -274.4089)
		(width 0.0889)
		(layer "In2.Cu")
		(net "M_I_CPU1_SB_DQ<0>")
	)
	(arc
		(start 142.811754 -274.4089)
		(mid 143.09471 -274.332723)
		(end 143.377666 -274.4089)
		(width 0.0889)
		(layer "In2.Cu")
		(net "M_I_CPU1_SB_DQ<0>")
	)
	(arc
		(start 133.411722 -274.4089)
		(mid 133.694678 -274.332723)
		(end 133.977634 -274.4089)
		(width 0.0889)
		(layer "In2.Cu")
		(net "M_I_CPU1_SB_DQ<0>")
	)
	(arc
		(start 137.171684 -274.4089)
		(mid 137.45464 -274.332723)
		(end 137.737596 -274.4089)
		(width 0.0889)
		(layer "In2.Cu")
		(net "M_I_CPU1_SB_DQ<0>")
	)
	(arc
		(start 142.437612 -274.4089)
		(mid 142.619863 -274.45925)
		(end 142.803372 -274.413726)
		(width 0.0889)
		(layer "In2.Cu")
		(net "M_I_CPU1_SB_DQ<0>")
	)
	(arc
		(start 139.991846 -274.4089)
		(mid 140.274802 -274.332723)
		(end 140.557758 -274.4089)
		(width 0.0889)
		(layer "In2.Cu")
		(net "M_I_CPU1_SB_DQ<0>")
	)
	(segment
		(start 129.467864 -266.530328)
		(end 129.934716 -266.796266)
		(width 0.10668)
		(layer "F.Cu")
		(net "M_I_CPU1_SB_CS_N<1>")
	)
	(segment
		(start 129.780792 -266.530836)
		(end 129.803144 -266.447524)
		(width 0.0889)
		(layer "In2.Cu")
		(net "M_I_CPU1_SB_CS_N<1>")
	)
	(segment
		(start 179.090828 -269.160498)
		(end 179.516024 -268.735302)
		(width 0.14478)
		(layer "In2.Cu")
		(net "M_I_CPU1_SB_CS_N<1>")
	)
	(segment
		(start 174.599854 -268.845284)
		(end 174.84344 -268.845284)
		(width 0.14478)
		(layer "In2.Cu")
		(net "M_I_CPU1_SB_CS_N<1>")
	)
	(segment
		(start 167.648636 -269.160498)
		(end 169.58437 -269.160498)
		(width 0.14478)
		(layer "In2.Cu")
		(net "M_I_CPU1_SB_CS_N<1>")
	)
	(segment
		(start 132.93344 -266.46886)
		(end 132.941822 -266.473686)
		(width 0.0889)
		(layer "In2.Cu")
		(net "M_I_CPU1_SB_CS_N<1>")
	)
	(segment
		(start 133.507734 -266.473686)
		(end 133.516116 -266.46886)
		(width 0.0889)
		(layer "In2.Cu")
		(net "M_I_CPU1_SB_CS_N<1>")
	)
	(segment
		(start 174.041054 -269.160498)
		(end 174.28464 -269.160498)
		(width 0.14478)
		(layer "In2.Cu")
		(net "M_I_CPU1_SB_CS_N<1>")
	)
	(segment
		(start 144.221708 -266.473686)
		(end 144.23644 -266.482322)
		(width 0.0889)
		(layer "In2.Cu")
		(net "M_I_CPU1_SB_CS_N<1>")
	)
	(segment
		(start 158.147512 -265.703304)
		(end 163.321238 -269.160498)
		(width 0.14478)
		(layer "In2.Cu")
		(net "M_I_CPU1_SB_CS_N<1>")
	)
	(segment
		(start 169.858944 -268.885924)
		(end 170.14317 -268.885924)
		(width 0.14478)
		(layer "In2.Cu")
		(net "M_I_CPU1_SB_CS_N<1>")
	)
	(segment
		(start 166.531036 -269.160498)
		(end 166.772082 -269.160498)
		(width 0.14478)
		(layer "In2.Cu")
		(net "M_I_CPU1_SB_CS_N<1>")
	)
	(segment
		(start 145.513044 -266.435586)
		(end 146.311366 -265.637264)
		(width 0.0889)
		(layer "In2.Cu")
		(net "M_I_CPU1_SB_CS_N<1>")
	)
	(segment
		(start 174.28464 -269.160498)
		(end 174.599854 -268.845284)
		(width 0.14478)
		(layer "In2.Cu")
		(net "M_I_CPU1_SB_CS_N<1>")
	)
	(segment
		(start 144.213326 -266.46886)
		(end 144.221708 -266.473686)
		(width 0.0889)
		(layer "In2.Cu")
		(net "M_I_CPU1_SB_CS_N<1>")
	)
	(segment
		(start 136.693402 -266.46886)
		(end 136.701784 -266.473686)
		(width 0.0889)
		(layer "In2.Cu")
		(net "M_I_CPU1_SB_CS_N<1>")
	)
	(segment
		(start 166.213282 -268.842744)
		(end 166.531036 -269.160498)
		(width 0.14478)
		(layer "In2.Cu")
		(net "M_I_CPU1_SB_CS_N<1>")
	)
	(segment
		(start 137.267696 -266.473686)
		(end 137.276078 -266.46886)
		(width 0.0889)
		(layer "In2.Cu")
		(net "M_I_CPU1_SB_CS_N<1>")
	)
	(segment
		(start 166.772082 -269.160498)
		(end 167.089836 -268.842744)
		(width 0.14478)
		(layer "In2.Cu")
		(net "M_I_CPU1_SB_CS_N<1>")
	)
	(segment
		(start 169.58437 -269.160498)
		(end 169.858944 -268.885924)
		(width 0.14478)
		(layer "In2.Cu")
		(net "M_I_CPU1_SB_CS_N<1>")
	)
	(segment
		(start 146.311366 -265.637264)
		(end 147.662646 -265.637264)
		(width 0.0889)
		(layer "In2.Cu")
		(net "M_I_CPU1_SB_CS_N<1>")
	)
	(segment
		(start 165.654482 -269.160498)
		(end 165.972236 -268.842744)
		(width 0.14478)
		(layer "In2.Cu")
		(net "M_I_CPU1_SB_CS_N<1>")
	)
	(segment
		(start 135.753348 -266.46886)
		(end 135.76173 -266.473686)
		(width 0.0889)
		(layer "In2.Cu")
		(net "M_I_CPU1_SB_CS_N<1>")
	)
	(segment
		(start 167.330882 -268.842744)
		(end 167.648636 -269.160498)
		(width 0.14478)
		(layer "In2.Cu")
		(net "M_I_CPU1_SB_CS_N<1>")
	)
	(segment
		(start 138.20775 -266.473686)
		(end 138.216132 -266.46886)
		(width 0.0889)
		(layer "In2.Cu")
		(net "M_I_CPU1_SB_CS_N<1>")
	)
	(segment
		(start 165.972236 -268.842744)
		(end 166.213282 -268.842744)
		(width 0.14478)
		(layer "In2.Cu")
		(net "M_I_CPU1_SB_CS_N<1>")
	)
	(segment
		(start 147.662646 -265.637264)
		(end 147.728686 -265.703304)
		(width 0.0889)
		(layer "In2.Cu")
		(net "M_I_CPU1_SB_CS_N<1>")
	)
	(segment
		(start 173.16704 -269.160498)
		(end 173.482254 -268.845284)
		(width 0.14478)
		(layer "In2.Cu")
		(net "M_I_CPU1_SB_CS_N<1>")
	)
	(segment
		(start 170.14317 -268.885924)
		(end 170.417744 -269.160498)
		(width 0.14478)
		(layer "In2.Cu")
		(net "M_I_CPU1_SB_CS_N<1>")
	)
	(segment
		(start 173.482254 -268.845284)
		(end 173.72584 -268.845284)
		(width 0.14478)
		(layer "In2.Cu")
		(net "M_I_CPU1_SB_CS_N<1>")
	)
	(segment
		(start 163.321238 -269.160498)
		(end 165.654482 -269.160498)
		(width 0.14478)
		(layer "In2.Cu")
		(net "M_I_CPU1_SB_CS_N<1>")
	)
	(segment
		(start 140.453364 -266.46886)
		(end 140.461746 -266.473686)
		(width 0.0889)
		(layer "In2.Cu")
		(net "M_I_CPU1_SB_CS_N<1>")
	)
	(segment
		(start 174.84344 -268.845284)
		(end 175.158654 -269.160498)
		(width 0.14478)
		(layer "In2.Cu")
		(net "M_I_CPU1_SB_CS_N<1>")
	)
	(segment
		(start 129.934716 -266.796266)
		(end 129.780792 -266.530836)
		(width 0.0889)
		(layer "In2.Cu")
		(net "M_I_CPU1_SB_CS_N<1>")
	)
	(segment
		(start 177.50282 -268.860524)
		(end 177.761646 -268.860524)
		(width 0.14478)
		(layer "In2.Cu")
		(net "M_I_CPU1_SB_CS_N<1>")
	)
	(segment
		(start 177.202846 -269.160498)
		(end 177.50282 -268.860524)
		(width 0.14478)
		(layer "In2.Cu")
		(net "M_I_CPU1_SB_CS_N<1>")
	)
	(segment
		(start 173.72584 -268.845284)
		(end 174.041054 -269.160498)
		(width 0.14478)
		(layer "In2.Cu")
		(net "M_I_CPU1_SB_CS_N<1>")
	)
	(segment
		(start 177.761646 -268.860524)
		(end 178.06162 -269.160498)
		(width 0.14478)
		(layer "In2.Cu")
		(net "M_I_CPU1_SB_CS_N<1>")
	)
	(segment
		(start 141.967712 -266.473686)
		(end 141.976094 -266.46886)
		(width 0.0889)
		(layer "In2.Cu")
		(net "M_I_CPU1_SB_CS_N<1>")
	)
	(segment
		(start 167.089836 -268.842744)
		(end 167.330882 -268.842744)
		(width 0.14478)
		(layer "In2.Cu")
		(net "M_I_CPU1_SB_CS_N<1>")
	)
	(segment
		(start 147.728686 -265.703304)
		(end 158.147512 -265.703304)
		(width 0.14478)
		(layer "In2.Cu")
		(net "M_I_CPU1_SB_CS_N<1>")
	)
	(segment
		(start 141.393418 -266.46886)
		(end 141.4018 -266.473686)
		(width 0.0889)
		(layer "In2.Cu")
		(net "M_I_CPU1_SB_CS_N<1>")
	)
	(segment
		(start 175.158654 -269.160498)
		(end 177.202846 -269.160498)
		(width 0.14478)
		(layer "In2.Cu")
		(net "M_I_CPU1_SB_CS_N<1>")
	)
	(segment
		(start 170.417744 -269.160498)
		(end 173.16704 -269.160498)
		(width 0.14478)
		(layer "In2.Cu")
		(net "M_I_CPU1_SB_CS_N<1>")
	)
	(segment
		(start 178.06162 -269.160498)
		(end 179.090828 -269.160498)
		(width 0.14478)
		(layer "In2.Cu")
		(net "M_I_CPU1_SB_CS_N<1>")
	)
	(segment
		(start 131.993386 -266.46886)
		(end 132.001768 -266.473686)
		(width 0.0889)
		(layer "In2.Cu")
		(net "M_I_CPU1_SB_CS_N<1>")
	)
	(segment
		(start 145.070068 -266.435586)
		(end 145.513044 -266.435586)
		(width 0.0889)
		(layer "In2.Cu")
		(net "M_I_CPU1_SB_CS_N<1>")
	)
	(arc
		(start 143.281654 -266.473686)
		(mid 143.56461 -266.549863)
		(end 143.847566 -266.473686)
		(width 0.0889)
		(layer "In2.Cu")
		(net "M_I_CPU1_SB_CS_N<1>")
	)
	(arc
		(start 130.687826 -266.473686)
		(mid 130.87477 -266.423431)
		(end 131.061714 -266.473686)
		(width 0.0889)
		(layer "In2.Cu")
		(net "M_I_CPU1_SB_CS_N<1>")
	)
	(arc
		(start 144.788128 -266.473686)
		(mid 144.925324 -266.426671)
		(end 145.070068 -266.435586)
		(width 0.0889)
		(layer "In2.Cu")
		(net "M_I_CPU1_SB_CS_N<1>")
	)
	(arc
		(start 131.061714 -266.473686)
		(mid 131.34467 -266.549863)
		(end 131.627626 -266.473686)
		(width 0.0889)
		(layer "In2.Cu")
		(net "M_I_CPU1_SB_CS_N<1>")
	)
	(arc
		(start 134.447788 -266.473686)
		(mid 134.634732 -266.423431)
		(end 134.821676 -266.473686)
		(width 0.0889)
		(layer "In2.Cu")
		(net "M_I_CPU1_SB_CS_N<1>")
	)
	(arc
		(start 129.803144 -266.447524)
		(mid 129.965476 -266.424706)
		(end 130.121914 -266.473686)
		(width 0.0889)
		(layer "In2.Cu")
		(net "M_I_CPU1_SB_CS_N<1>")
	)
	(arc
		(start 142.341854 -266.473686)
		(mid 142.62481 -266.549863)
		(end 142.907766 -266.473686)
		(width 0.0889)
		(layer "In2.Cu")
		(net "M_I_CPU1_SB_CS_N<1>")
	)
	(arc
		(start 135.387588 -266.473686)
		(mid 135.569839 -266.423336)
		(end 135.753348 -266.46886)
		(width 0.0889)
		(layer "In2.Cu")
		(net "M_I_CPU1_SB_CS_N<1>")
	)
	(arc
		(start 134.821676 -266.473686)
		(mid 135.104632 -266.549863)
		(end 135.387588 -266.473686)
		(width 0.0889)
		(layer "In2.Cu")
		(net "M_I_CPU1_SB_CS_N<1>")
	)
	(arc
		(start 135.76173 -266.473686)
		(mid 136.044686 -266.549863)
		(end 136.327642 -266.473686)
		(width 0.0889)
		(layer "In2.Cu")
		(net "M_I_CPU1_SB_CS_N<1>")
	)
	(arc
		(start 142.907766 -266.473686)
		(mid 143.09471 -266.423431)
		(end 143.281654 -266.473686)
		(width 0.0889)
		(layer "In2.Cu")
		(net "M_I_CPU1_SB_CS_N<1>")
	)
	(arc
		(start 133.881876 -266.473686)
		(mid 134.164832 -266.549863)
		(end 134.447788 -266.473686)
		(width 0.0889)
		(layer "In2.Cu")
		(net "M_I_CPU1_SB_CS_N<1>")
	)
	(arc
		(start 132.56768 -266.473686)
		(mid 132.749931 -266.423336)
		(end 132.93344 -266.46886)
		(width 0.0889)
		(layer "In2.Cu")
		(net "M_I_CPU1_SB_CS_N<1>")
	)
	(arc
		(start 140.461746 -266.473686)
		(mid 140.744702 -266.549863)
		(end 141.027658 -266.473686)
		(width 0.0889)
		(layer "In2.Cu")
		(net "M_I_CPU1_SB_CS_N<1>")
	)
	(arc
		(start 131.627626 -266.473686)
		(mid 131.809877 -266.423336)
		(end 131.993386 -266.46886)
		(width 0.0889)
		(layer "In2.Cu")
		(net "M_I_CPU1_SB_CS_N<1>")
	)
	(arc
		(start 133.516116 -266.46886)
		(mid 133.699624 -266.423366)
		(end 133.881876 -266.473686)
		(width 0.0889)
		(layer "In2.Cu")
		(net "M_I_CPU1_SB_CS_N<1>")
	)
	(arc
		(start 138.216132 -266.46886)
		(mid 138.39964 -266.423366)
		(end 138.581892 -266.473686)
		(width 0.0889)
		(layer "In2.Cu")
		(net "M_I_CPU1_SB_CS_N<1>")
	)
	(arc
		(start 141.976094 -266.46886)
		(mid 142.159602 -266.423366)
		(end 142.341854 -266.473686)
		(width 0.0889)
		(layer "In2.Cu")
		(net "M_I_CPU1_SB_CS_N<1>")
	)
	(arc
		(start 139.521692 -266.473686)
		(mid 139.804648 -266.549863)
		(end 140.087604 -266.473686)
		(width 0.0889)
		(layer "In2.Cu")
		(net "M_I_CPU1_SB_CS_N<1>")
	)
	(arc
		(start 143.847566 -266.473686)
		(mid 144.029817 -266.423336)
		(end 144.213326 -266.46886)
		(width 0.0889)
		(layer "In2.Cu")
		(net "M_I_CPU1_SB_CS_N<1>")
	)
	(arc
		(start 136.327642 -266.473686)
		(mid 136.509893 -266.423336)
		(end 136.693402 -266.46886)
		(width 0.0889)
		(layer "In2.Cu")
		(net "M_I_CPU1_SB_CS_N<1>")
	)
	(arc
		(start 140.087604 -266.473686)
		(mid 140.269855 -266.423336)
		(end 140.453364 -266.46886)
		(width 0.0889)
		(layer "In2.Cu")
		(net "M_I_CPU1_SB_CS_N<1>")
	)
	(arc
		(start 137.276078 -266.46886)
		(mid 137.459586 -266.423366)
		(end 137.641838 -266.473686)
		(width 0.0889)
		(layer "In2.Cu")
		(net "M_I_CPU1_SB_CS_N<1>")
	)
	(arc
		(start 132.001768 -266.473686)
		(mid 132.284724 -266.549863)
		(end 132.56768 -266.473686)
		(width 0.0889)
		(layer "In2.Cu")
		(net "M_I_CPU1_SB_CS_N<1>")
	)
	(arc
		(start 141.027658 -266.473686)
		(mid 141.209909 -266.423336)
		(end 141.393418 -266.46886)
		(width 0.0889)
		(layer "In2.Cu")
		(net "M_I_CPU1_SB_CS_N<1>")
	)
	(arc
		(start 144.23644 -266.482322)
		(mid 144.513423 -266.550126)
		(end 144.788128 -266.473686)
		(width 0.0889)
		(layer "In2.Cu")
		(net "M_I_CPU1_SB_CS_N<1>")
	)
	(arc
		(start 130.121914 -266.473686)
		(mid 130.40487 -266.549863)
		(end 130.687826 -266.473686)
		(width 0.0889)
		(layer "In2.Cu")
		(net "M_I_CPU1_SB_CS_N<1>")
	)
	(arc
		(start 139.147804 -266.473686)
		(mid 139.334748 -266.423431)
		(end 139.521692 -266.473686)
		(width 0.0889)
		(layer "In2.Cu")
		(net "M_I_CPU1_SB_CS_N<1>")
	)
	(arc
		(start 136.701784 -266.473686)
		(mid 136.98474 -266.549863)
		(end 137.267696 -266.473686)
		(width 0.0889)
		(layer "In2.Cu")
		(net "M_I_CPU1_SB_CS_N<1>")
	)
	(arc
		(start 132.941822 -266.473686)
		(mid 133.224778 -266.549863)
		(end 133.507734 -266.473686)
		(width 0.0889)
		(layer "In2.Cu")
		(net "M_I_CPU1_SB_CS_N<1>")
	)
	(arc
		(start 141.4018 -266.473686)
		(mid 141.684756 -266.549863)
		(end 141.967712 -266.473686)
		(width 0.0889)
		(layer "In2.Cu")
		(net "M_I_CPU1_SB_CS_N<1>")
	)
	(arc
		(start 138.581892 -266.473686)
		(mid 138.864848 -266.549863)
		(end 139.147804 -266.473686)
		(width 0.0889)
		(layer "In2.Cu")
		(net "M_I_CPU1_SB_CS_N<1>")
	)
	(arc
		(start 137.641838 -266.473686)
		(mid 137.924794 -266.549863)
		(end 138.20775 -266.473686)
		(width 0.0889)
		(layer "In2.Cu")
		(net "M_I_CPU1_SB_CS_N<1>")
	)
	(segment
		(start 128.05791 -265.720322)
		(end 128.524762 -265.98626)
		(width 0.10668)
		(layer "F.Cu")
		(net "M_I_CPU1_SB_CS_N<0>")
	)
	(segment
		(start 145.373852 -265.619484)
		(end 145.684494 -265.308842)
		(width 0.0889)
		(layer "In2.Cu")
		(net "M_I_CPU1_SB_CS_N<0>")
	)
	(segment
		(start 130.583432 -265.658854)
		(end 130.591814 -265.66368)
		(width 0.0889)
		(layer "In2.Cu")
		(net "M_I_CPU1_SB_CS_N<0>")
	)
	(segment
		(start 131.157726 -265.66368)
		(end 131.166108 -265.658854)
		(width 0.0889)
		(layer "In2.Cu")
		(net "M_I_CPU1_SB_CS_N<0>")
	)
	(segment
		(start 144.315688 -265.663934)
		(end 144.337532 -265.651488)
		(width 0.0889)
		(layer "In2.Cu")
		(net "M_I_CPU1_SB_CS_N<0>")
	)
	(segment
		(start 143.377666 -265.66368)
		(end 143.386048 -265.658854)
		(width 0.0889)
		(layer "In2.Cu")
		(net "M_I_CPU1_SB_CS_N<0>")
	)
	(segment
		(start 183.19115 -268.31036)
		(end 183.616092 -267.885418)
		(width 0.14478)
		(layer "In2.Cu")
		(net "M_I_CPU1_SB_CS_N<0>")
	)
	(segment
		(start 144.289526 -265.67892)
		(end 144.315688 -265.663934)
		(width 0.0889)
		(layer "In2.Cu")
		(net "M_I_CPU1_SB_CS_N<0>")
	)
	(segment
		(start 144.688306 -265.66368)
		(end 144.71777 -265.680952)
		(width 0.0889)
		(layer "In2.Cu")
		(net "M_I_CPU1_SB_CS_N<0>")
	)
	(segment
		(start 158.357824 -265.248644)
		(end 163.762182 -268.31036)
		(width 0.14478)
		(layer "In2.Cu")
		(net "M_I_CPU1_SB_CS_N<0>")
	)
	(segment
		(start 129.643378 -265.658854)
		(end 129.65176 -265.66368)
		(width 0.0889)
		(layer "In2.Cu")
		(net "M_I_CPU1_SB_CS_N<0>")
	)
	(segment
		(start 128.370838 -265.72083)
		(end 128.39319 -265.637518)
		(width 0.0889)
		(layer "In2.Cu")
		(net "M_I_CPU1_SB_CS_N<0>")
	)
	(segment
		(start 139.617704 -265.66368)
		(end 139.626086 -265.658854)
		(width 0.0889)
		(layer "In2.Cu")
		(net "M_I_CPU1_SB_CS_N<0>")
	)
	(segment
		(start 135.857742 -265.66368)
		(end 135.866124 -265.658854)
		(width 0.0889)
		(layer "In2.Cu")
		(net "M_I_CPU1_SB_CS_N<0>")
	)
	(segment
		(start 145.684494 -265.308842)
		(end 147.176998 -265.308842)
		(width 0.0889)
		(layer "In2.Cu")
		(net "M_I_CPU1_SB_CS_N<0>")
	)
	(segment
		(start 128.524762 -265.98626)
		(end 128.370838 -265.72083)
		(width 0.0889)
		(layer "In2.Cu")
		(net "M_I_CPU1_SB_CS_N<0>")
	)
	(segment
		(start 138.103356 -265.658854)
		(end 138.111738 -265.66368)
		(width 0.0889)
		(layer "In2.Cu")
		(net "M_I_CPU1_SB_CS_N<0>")
	)
	(segment
		(start 134.917688 -265.66368)
		(end 134.92607 -265.658854)
		(width 0.0889)
		(layer "In2.Cu")
		(net "M_I_CPU1_SB_CS_N<0>")
	)
	(segment
		(start 163.762182 -268.31036)
		(end 183.19115 -268.31036)
		(width 0.14478)
		(layer "In2.Cu")
		(net "M_I_CPU1_SB_CS_N<0>")
	)
	(segment
		(start 147.754086 -265.248644)
		(end 158.357824 -265.248644)
		(width 0.14478)
		(layer "In2.Cu")
		(net "M_I_CPU1_SB_CS_N<0>")
	)
	(segment
		(start 134.343394 -265.658854)
		(end 134.351776 -265.66368)
		(width 0.0889)
		(layer "In2.Cu")
		(net "M_I_CPU1_SB_CS_N<0>")
	)
	(segment
		(start 147.176998 -265.308842)
		(end 147.237196 -265.248644)
		(width 0.0889)
		(layer "In2.Cu")
		(net "M_I_CPU1_SB_CS_N<0>")
	)
	(segment
		(start 140.557758 -265.66368)
		(end 140.56614 -265.658854)
		(width 0.0889)
		(layer "In2.Cu")
		(net "M_I_CPU1_SB_CS_N<0>")
	)
	(segment
		(start 142.803372 -265.658854)
		(end 142.811754 -265.66368)
		(width 0.0889)
		(layer "In2.Cu")
		(net "M_I_CPU1_SB_CS_N<0>")
	)
	(segment
		(start 147.237196 -265.248644)
		(end 147.754086 -265.248644)
		(width 0.0889)
		(layer "In2.Cu")
		(net "M_I_CPU1_SB_CS_N<0>")
	)
	(segment
		(start 132.09778 -265.66368)
		(end 132.106162 -265.658854)
		(width 0.0889)
		(layer "In2.Cu")
		(net "M_I_CPU1_SB_CS_N<0>")
	)
	(segment
		(start 139.04341 -265.658854)
		(end 139.051792 -265.66368)
		(width 0.0889)
		(layer "In2.Cu")
		(net "M_I_CPU1_SB_CS_N<0>")
	)
	(arc
		(start 139.051792 -265.66368)
		(mid 139.334748 -265.739857)
		(end 139.617704 -265.66368)
		(width 0.0889)
		(layer "In2.Cu")
		(net "M_I_CPU1_SB_CS_N<0>")
	)
	(arc
		(start 139.626086 -265.658854)
		(mid 139.809594 -265.61336)
		(end 139.991846 -265.66368)
		(width 0.0889)
		(layer "In2.Cu")
		(net "M_I_CPU1_SB_CS_N<0>")
	)
	(arc
		(start 136.797796 -265.66368)
		(mid 136.98474 -265.613425)
		(end 137.171684 -265.66368)
		(width 0.0889)
		(layer "In2.Cu")
		(net "M_I_CPU1_SB_CS_N<0>")
	)
	(arc
		(start 134.92607 -265.658854)
		(mid 135.109578 -265.61336)
		(end 135.29183 -265.66368)
		(width 0.0889)
		(layer "In2.Cu")
		(net "M_I_CPU1_SB_CS_N<0>")
	)
	(arc
		(start 137.171684 -265.66368)
		(mid 137.45464 -265.739857)
		(end 137.737596 -265.66368)
		(width 0.0889)
		(layer "In2.Cu")
		(net "M_I_CPU1_SB_CS_N<0>")
	)
	(arc
		(start 134.351776 -265.66368)
		(mid 134.634732 -265.739857)
		(end 134.917688 -265.66368)
		(width 0.0889)
		(layer "In2.Cu")
		(net "M_I_CPU1_SB_CS_N<0>")
	)
	(arc
		(start 137.737596 -265.66368)
		(mid 137.919847 -265.61333)
		(end 138.103356 -265.658854)
		(width 0.0889)
		(layer "In2.Cu")
		(net "M_I_CPU1_SB_CS_N<0>")
	)
	(arc
		(start 140.56614 -265.658854)
		(mid 140.749648 -265.61336)
		(end 140.9319 -265.66368)
		(width 0.0889)
		(layer "In2.Cu")
		(net "M_I_CPU1_SB_CS_N<0>")
	)
	(arc
		(start 145.25625 -265.66368)
		(mid 145.313174 -265.636583)
		(end 145.373852 -265.619484)
		(width 0.0889)
		(layer "In2.Cu")
		(net "M_I_CPU1_SB_CS_N<0>")
	)
	(arc
		(start 130.591814 -265.66368)
		(mid 130.87477 -265.739857)
		(end 131.157726 -265.66368)
		(width 0.0889)
		(layer "In2.Cu")
		(net "M_I_CPU1_SB_CS_N<0>")
	)
	(arc
		(start 141.8717 -265.66368)
		(mid 142.154656 -265.739857)
		(end 142.437612 -265.66368)
		(width 0.0889)
		(layer "In2.Cu")
		(net "M_I_CPU1_SB_CS_N<0>")
	)
	(arc
		(start 142.437612 -265.66368)
		(mid 142.619863 -265.61333)
		(end 142.803372 -265.658854)
		(width 0.0889)
		(layer "In2.Cu")
		(net "M_I_CPU1_SB_CS_N<0>")
	)
	(arc
		(start 132.106162 -265.658854)
		(mid 132.28967 -265.61336)
		(end 132.471922 -265.66368)
		(width 0.0889)
		(layer "In2.Cu")
		(net "M_I_CPU1_SB_CS_N<0>")
	)
	(arc
		(start 143.751808 -265.66368)
		(mid 144.018738 -265.739629)
		(end 144.289526 -265.67892)
		(width 0.0889)
		(layer "In2.Cu")
		(net "M_I_CPU1_SB_CS_N<0>")
	)
	(arc
		(start 135.866124 -265.658854)
		(mid 136.049632 -265.61336)
		(end 136.231884 -265.66368)
		(width 0.0889)
		(layer "In2.Cu")
		(net "M_I_CPU1_SB_CS_N<0>")
	)
	(arc
		(start 138.67765 -265.66368)
		(mid 138.859901 -265.61333)
		(end 139.04341 -265.658854)
		(width 0.0889)
		(layer "In2.Cu")
		(net "M_I_CPU1_SB_CS_N<0>")
	)
	(arc
		(start 128.39319 -265.637518)
		(mid 128.555379 -265.614783)
		(end 128.711706 -265.66368)
		(width 0.0889)
		(layer "In2.Cu")
		(net "M_I_CPU1_SB_CS_N<0>")
	)
	(arc
		(start 141.497812 -265.66368)
		(mid 141.684756 -265.613425)
		(end 141.8717 -265.66368)
		(width 0.0889)
		(layer "In2.Cu")
		(net "M_I_CPU1_SB_CS_N<0>")
	)
	(arc
		(start 131.166108 -265.658854)
		(mid 131.349616 -265.61336)
		(end 131.531868 -265.66368)
		(width 0.0889)
		(layer "In2.Cu")
		(net "M_I_CPU1_SB_CS_N<0>")
	)
	(arc
		(start 132.471922 -265.66368)
		(mid 132.754878 -265.739857)
		(end 133.037834 -265.66368)
		(width 0.0889)
		(layer "In2.Cu")
		(net "M_I_CPU1_SB_CS_N<0>")
	)
	(arc
		(start 143.386048 -265.658854)
		(mid 143.569556 -265.61336)
		(end 143.751808 -265.66368)
		(width 0.0889)
		(layer "In2.Cu")
		(net "M_I_CPU1_SB_CS_N<0>")
	)
	(arc
		(start 144.337532 -265.651488)
		(mid 144.51446 -265.61366)
		(end 144.688306 -265.66368)
		(width 0.0889)
		(layer "In2.Cu")
		(net "M_I_CPU1_SB_CS_N<0>")
	)
	(arc
		(start 140.9319 -265.66368)
		(mid 141.214856 -265.739857)
		(end 141.497812 -265.66368)
		(width 0.0889)
		(layer "In2.Cu")
		(net "M_I_CPU1_SB_CS_N<0>")
	)
	(arc
		(start 136.231884 -265.66368)
		(mid 136.51484 -265.739857)
		(end 136.797796 -265.66368)
		(width 0.0889)
		(layer "In2.Cu")
		(net "M_I_CPU1_SB_CS_N<0>")
	)
	(arc
		(start 129.65176 -265.66368)
		(mid 129.934716 -265.739857)
		(end 130.217672 -265.66368)
		(width 0.0889)
		(layer "In2.Cu")
		(net "M_I_CPU1_SB_CS_N<0>")
	)
	(arc
		(start 142.811754 -265.66368)
		(mid 143.09471 -265.739857)
		(end 143.377666 -265.66368)
		(width 0.0889)
		(layer "In2.Cu")
		(net "M_I_CPU1_SB_CS_N<0>")
	)
	(arc
		(start 144.71777 -265.680952)
		(mid 144.98919 -265.740629)
		(end 145.25625 -265.66368)
		(width 0.0889)
		(layer "In2.Cu")
		(net "M_I_CPU1_SB_CS_N<0>")
	)
	(arc
		(start 131.531868 -265.66368)
		(mid 131.814824 -265.739857)
		(end 132.09778 -265.66368)
		(width 0.0889)
		(layer "In2.Cu")
		(net "M_I_CPU1_SB_CS_N<0>")
	)
	(arc
		(start 138.111738 -265.66368)
		(mid 138.394694 -265.739857)
		(end 138.67765 -265.66368)
		(width 0.0889)
		(layer "In2.Cu")
		(net "M_I_CPU1_SB_CS_N<0>")
	)
	(arc
		(start 133.411722 -265.66368)
		(mid 133.694678 -265.739857)
		(end 133.977634 -265.66368)
		(width 0.0889)
		(layer "In2.Cu")
		(net "M_I_CPU1_SB_CS_N<0>")
	)
	(arc
		(start 128.711706 -265.66368)
		(mid 128.994662 -265.739857)
		(end 129.277618 -265.66368)
		(width 0.0889)
		(layer "In2.Cu")
		(net "M_I_CPU1_SB_CS_N<0>")
	)
	(arc
		(start 135.29183 -265.66368)
		(mid 135.574786 -265.739857)
		(end 135.857742 -265.66368)
		(width 0.0889)
		(layer "In2.Cu")
		(net "M_I_CPU1_SB_CS_N<0>")
	)
	(arc
		(start 133.037834 -265.66368)
		(mid 133.224778 -265.613425)
		(end 133.411722 -265.66368)
		(width 0.0889)
		(layer "In2.Cu")
		(net "M_I_CPU1_SB_CS_N<0>")
	)
	(arc
		(start 133.977634 -265.66368)
		(mid 134.159885 -265.61333)
		(end 134.343394 -265.658854)
		(width 0.0889)
		(layer "In2.Cu")
		(net "M_I_CPU1_SB_CS_N<0>")
	)
	(arc
		(start 130.217672 -265.66368)
		(mid 130.399923 -265.61333)
		(end 130.583432 -265.658854)
		(width 0.0889)
		(layer "In2.Cu")
		(net "M_I_CPU1_SB_CS_N<0>")
	)
	(arc
		(start 129.277618 -265.66368)
		(mid 129.459869 -265.61333)
		(end 129.643378 -265.658854)
		(width 0.0889)
		(layer "In2.Cu")
		(net "M_I_CPU1_SB_CS_N<0>")
	)
	(arc
		(start 139.991846 -265.66368)
		(mid 140.274802 -265.739857)
		(end 140.557758 -265.66368)
		(width 0.0889)
		(layer "In2.Cu")
		(net "M_I_CPU1_SB_CS_N<0>")
	)
	(segment
		(start 128.05791 -270.580358)
		(end 128.524762 -270.846296)
		(width 0.10668)
		(layer "F.Cu")
		(net "M_I_CPU1_SB_CB<7>")
	)
	(segment
		(start 166.86403 -274.03171)
		(end 166.86403 -274.089114)
		(width 0.14478)
		(layer "In2.Cu")
		(net "M_I_CPU1_SB_CB<7>")
	)
	(segment
		(start 173.851824 -274.03171)
		(end 174.013368 -273.870166)
		(width 0.14478)
		(layer "In2.Cu")
		(net "M_I_CPU1_SB_CB<7>")
	)
	(segment
		(start 167.025574 -274.250658)
		(end 169.495978 -274.250658)
		(width 0.14478)
		(layer "In2.Cu")
		(net "M_I_CPU1_SB_CB<7>")
	)
	(segment
		(start 145.821654 -269.655544)
		(end 146.639534 -268.837664)
		(width 0.0889)
		(layer "In2.Cu")
		(net "M_I_CPU1_SB_CB<7>")
	)
	(segment
		(start 173.461934 -274.63115)
		(end 173.69028 -274.63115)
		(width 0.14478)
		(layer "In2.Cu")
		(net "M_I_CPU1_SB_CB<7>")
	)
	(segment
		(start 165.209728 -274.03171)
		(end 165.371272 -273.870166)
		(width 0.14478)
		(layer "In2.Cu")
		(net "M_I_CPU1_SB_CB<7>")
	)
	(segment
		(start 178.886358 -274.250658)
		(end 179.08143 -274.250658)
		(width 0.14478)
		(layer "In2.Cu")
		(net "M_I_CPU1_SB_CB<7>")
	)
	(segment
		(start 146.639534 -268.837664)
		(end 147.431506 -268.837664)
		(width 0.0889)
		(layer "In2.Cu")
		(net "M_I_CPU1_SB_CB<7>")
	)
	(segment
		(start 140.557758 -270.523716)
		(end 140.56614 -270.51889)
		(width 0.0889)
		(layer "In2.Cu")
		(net "M_I_CPU1_SB_CB<7>")
	)
	(segment
		(start 169.81805 -273.928586)
		(end 170.047412 -273.928586)
		(width 0.14478)
		(layer "In2.Cu")
		(net "M_I_CPU1_SB_CB<7>")
	)
	(segment
		(start 163.921186 -274.250658)
		(end 165.048184 -274.250658)
		(width 0.14478)
		(layer "In2.Cu")
		(net "M_I_CPU1_SB_CB<7>")
	)
	(segment
		(start 171.15028 -273.928586)
		(end 171.472352 -274.250658)
		(width 0.14478)
		(layer "In2.Cu")
		(net "M_I_CPU1_SB_CB<7>")
	)
	(segment
		(start 174.013368 -273.870166)
		(end 174.241714 -273.870166)
		(width 0.14478)
		(layer "In2.Cu")
		(net "M_I_CPU1_SB_CB<7>")
	)
	(segment
		(start 170.369484 -274.250658)
		(end 170.598846 -274.250658)
		(width 0.14478)
		(layer "In2.Cu")
		(net "M_I_CPU1_SB_CB<7>")
	)
	(segment
		(start 179.08143 -274.250658)
		(end 179.516024 -274.685252)
		(width 0.14478)
		(layer "In2.Cu")
		(net "M_I_CPU1_SB_CB<7>")
	)
	(segment
		(start 166.312596 -274.469606)
		(end 166.312596 -274.03171)
		(width 0.14478)
		(layer "In2.Cu")
		(net "M_I_CPU1_SB_CB<7>")
	)
	(segment
		(start 165.209728 -274.089114)
		(end 165.209728 -274.03171)
		(width 0.14478)
		(layer "In2.Cu")
		(net "M_I_CPU1_SB_CB<7>")
	)
	(segment
		(start 132.09778 -270.523716)
		(end 132.106162 -270.51889)
		(width 0.0889)
		(layer "In2.Cu")
		(net "M_I_CPU1_SB_CB<7>")
	)
	(segment
		(start 139.04341 -270.51889)
		(end 139.051792 -270.523716)
		(width 0.0889)
		(layer "In2.Cu")
		(net "M_I_CPU1_SB_CB<7>")
	)
	(segment
		(start 174.564802 -274.250658)
		(end 176.917604 -274.250658)
		(width 0.14478)
		(layer "In2.Cu")
		(net "M_I_CPU1_SB_CB<7>")
	)
	(segment
		(start 178.020472 -274.250658)
		(end 178.334924 -273.936206)
		(width 0.14478)
		(layer "In2.Cu")
		(net "M_I_CPU1_SB_CB<7>")
	)
	(segment
		(start 166.86403 -274.089114)
		(end 167.025574 -274.250658)
		(width 0.14478)
		(layer "In2.Cu")
		(net "M_I_CPU1_SB_CB<7>")
	)
	(segment
		(start 173.851824 -274.469606)
		(end 173.851824 -274.03171)
		(width 0.14478)
		(layer "In2.Cu")
		(net "M_I_CPU1_SB_CB<7>")
	)
	(segment
		(start 170.047412 -273.928586)
		(end 170.369484 -274.250658)
		(width 0.14478)
		(layer "In2.Cu")
		(net "M_I_CPU1_SB_CB<7>")
	)
	(segment
		(start 173.138846 -274.250658)
		(end 173.30039 -274.412202)
		(width 0.14478)
		(layer "In2.Cu")
		(net "M_I_CPU1_SB_CB<7>")
	)
	(segment
		(start 143.377666 -270.523716)
		(end 143.386048 -270.51889)
		(width 0.0889)
		(layer "In2.Cu")
		(net "M_I_CPU1_SB_CB<7>")
	)
	(segment
		(start 174.241714 -273.870166)
		(end 174.403258 -274.03171)
		(width 0.14478)
		(layer "In2.Cu")
		(net "M_I_CPU1_SB_CB<7>")
	)
	(segment
		(start 178.334924 -273.936206)
		(end 178.571906 -273.936206)
		(width 0.14478)
		(layer "In2.Cu")
		(net "M_I_CPU1_SB_CB<7>")
	)
	(segment
		(start 170.598846 -274.250658)
		(end 170.920918 -273.928586)
		(width 0.14478)
		(layer "In2.Cu")
		(net "M_I_CPU1_SB_CB<7>")
	)
	(segment
		(start 173.69028 -274.63115)
		(end 173.851824 -274.469606)
		(width 0.14478)
		(layer "In2.Cu")
		(net "M_I_CPU1_SB_CB<7>")
	)
	(segment
		(start 144.307052 -270.529812)
		(end 144.317466 -270.523716)
		(width 0.0889)
		(layer "In2.Cu")
		(net "M_I_CPU1_SB_CB<7>")
	)
	(segment
		(start 165.761162 -274.469606)
		(end 165.922706 -274.63115)
		(width 0.14478)
		(layer "In2.Cu")
		(net "M_I_CPU1_SB_CB<7>")
	)
	(segment
		(start 163.22548 -274.615402)
		(end 163.394644 -274.20697)
		(width 0.14478)
		(layer "In2.Cu")
		(net "M_I_CPU1_SB_CB<7>")
	)
	(segment
		(start 171.472352 -274.250658)
		(end 173.138846 -274.250658)
		(width 0.14478)
		(layer "In2.Cu")
		(net "M_I_CPU1_SB_CB<7>")
	)
	(segment
		(start 161.35604 -273.188176)
		(end 162.797744 -273.785076)
		(width 0.14478)
		(layer "In2.Cu")
		(net "M_I_CPU1_SB_CB<7>")
	)
	(segment
		(start 147.588986 -268.680184)
		(end 156.848048 -268.680184)
		(width 0.14478)
		(layer "In2.Cu")
		(net "M_I_CPU1_SB_CB<7>")
	)
	(segment
		(start 165.922706 -274.63115)
		(end 166.151052 -274.63115)
		(width 0.14478)
		(layer "In2.Cu")
		(net "M_I_CPU1_SB_CB<7>")
	)
	(segment
		(start 163.01466 -274.702778)
		(end 163.22548 -274.615402)
		(width 0.14478)
		(layer "In2.Cu")
		(net "M_I_CPU1_SB_CB<7>")
	)
	(segment
		(start 162.797744 -273.785076)
		(end 162.88512 -273.995896)
		(width 0.14478)
		(layer "In2.Cu")
		(net "M_I_CPU1_SB_CB<7>")
	)
	(segment
		(start 165.371272 -273.870166)
		(end 165.599618 -273.870166)
		(width 0.14478)
		(layer "In2.Cu")
		(net "M_I_CPU1_SB_CB<7>")
	)
	(segment
		(start 162.803332 -274.615148)
		(end 163.01466 -274.702778)
		(width 0.14478)
		(layer "In2.Cu")
		(net "M_I_CPU1_SB_CB<7>")
	)
	(segment
		(start 166.312596 -274.03171)
		(end 166.47414 -273.870166)
		(width 0.14478)
		(layer "In2.Cu")
		(net "M_I_CPU1_SB_CB<7>")
	)
	(segment
		(start 163.605464 -274.119594)
		(end 163.921186 -274.250658)
		(width 0.14478)
		(layer "In2.Cu")
		(net "M_I_CPU1_SB_CB<7>")
	)
	(segment
		(start 166.702486 -273.870166)
		(end 166.86403 -274.03171)
		(width 0.14478)
		(layer "In2.Cu")
		(net "M_I_CPU1_SB_CB<7>")
	)
	(segment
		(start 156.848048 -268.680184)
		(end 161.35604 -273.188176)
		(width 0.14478)
		(layer "In2.Cu")
		(net "M_I_CPU1_SB_CB<7>")
	)
	(segment
		(start 174.403258 -274.03171)
		(end 174.403258 -274.089114)
		(width 0.14478)
		(layer "In2.Cu")
		(net "M_I_CPU1_SB_CB<7>")
	)
	(segment
		(start 173.30039 -274.469606)
		(end 173.461934 -274.63115)
		(width 0.14478)
		(layer "In2.Cu")
		(net "M_I_CPU1_SB_CB<7>")
	)
	(segment
		(start 176.917604 -274.250658)
		(end 177.232056 -273.936206)
		(width 0.14478)
		(layer "In2.Cu")
		(net "M_I_CPU1_SB_CB<7>")
	)
	(segment
		(start 174.403258 -274.089114)
		(end 174.564802 -274.250658)
		(width 0.14478)
		(layer "In2.Cu")
		(net "M_I_CPU1_SB_CB<7>")
	)
	(segment
		(start 131.157726 -270.523716)
		(end 131.166108 -270.51889)
		(width 0.0889)
		(layer "In2.Cu")
		(net "M_I_CPU1_SB_CB<7>")
	)
	(segment
		(start 128.370838 -270.580866)
		(end 128.39319 -270.497554)
		(width 0.0889)
		(layer "In2.Cu")
		(net "M_I_CPU1_SB_CB<7>")
	)
	(segment
		(start 162.88512 -273.995896)
		(end 162.715956 -274.404328)
		(width 0.14478)
		(layer "In2.Cu")
		(net "M_I_CPU1_SB_CB<7>")
	)
	(segment
		(start 147.431506 -268.837664)
		(end 147.588986 -268.680184)
		(width 0.0889)
		(layer "In2.Cu")
		(net "M_I_CPU1_SB_CB<7>")
	)
	(segment
		(start 173.30039 -274.412202)
		(end 173.30039 -274.469606)
		(width 0.14478)
		(layer "In2.Cu")
		(net "M_I_CPU1_SB_CB<7>")
	)
	(segment
		(start 165.048184 -274.250658)
		(end 165.209728 -274.089114)
		(width 0.14478)
		(layer "In2.Cu")
		(net "M_I_CPU1_SB_CB<7>")
	)
	(segment
		(start 139.617704 -270.523716)
		(end 139.626086 -270.51889)
		(width 0.0889)
		(layer "In2.Cu")
		(net "M_I_CPU1_SB_CB<7>")
	)
	(segment
		(start 165.761162 -274.03171)
		(end 165.761162 -274.469606)
		(width 0.14478)
		(layer "In2.Cu")
		(net "M_I_CPU1_SB_CB<7>")
	)
	(segment
		(start 177.232056 -273.936206)
		(end 177.469038 -273.936206)
		(width 0.14478)
		(layer "In2.Cu")
		(net "M_I_CPU1_SB_CB<7>")
	)
	(segment
		(start 145.25752 -270.524224)
		(end 145.302224 -270.498062)
		(width 0.0889)
		(layer "In2.Cu")
		(net "M_I_CPU1_SB_CB<7>")
	)
	(segment
		(start 144.67586 -270.515334)
		(end 144.691354 -270.524224)
		(width 0.0889)
		(layer "In2.Cu")
		(net "M_I_CPU1_SB_CB<7>")
	)
	(segment
		(start 163.394644 -274.20697)
		(end 163.605464 -274.119594)
		(width 0.14478)
		(layer "In2.Cu")
		(net "M_I_CPU1_SB_CB<7>")
	)
	(segment
		(start 177.78349 -274.250658)
		(end 178.020472 -274.250658)
		(width 0.14478)
		(layer "In2.Cu")
		(net "M_I_CPU1_SB_CB<7>")
	)
	(segment
		(start 130.583432 -270.51889)
		(end 130.591814 -270.523716)
		(width 0.0889)
		(layer "In2.Cu")
		(net "M_I_CPU1_SB_CB<7>")
	)
	(segment
		(start 144.691354 -270.524224)
		(end 144.701768 -270.53032)
		(width 0.0889)
		(layer "In2.Cu")
		(net "M_I_CPU1_SB_CB<7>")
	)
	(segment
		(start 134.917688 -270.523716)
		(end 134.92607 -270.51889)
		(width 0.0889)
		(layer "In2.Cu")
		(net "M_I_CPU1_SB_CB<7>")
	)
	(segment
		(start 177.469038 -273.936206)
		(end 177.78349 -274.250658)
		(width 0.14478)
		(layer "In2.Cu")
		(net "M_I_CPU1_SB_CB<7>")
	)
	(segment
		(start 145.792698 -269.675864)
		(end 145.821654 -269.655544)
		(width 0.0889)
		(layer "In2.Cu")
		(net "M_I_CPU1_SB_CB<7>")
	)
	(segment
		(start 162.715956 -274.404328)
		(end 162.803332 -274.615148)
		(width 0.14478)
		(layer "In2.Cu")
		(net "M_I_CPU1_SB_CB<7>")
	)
	(segment
		(start 129.643378 -270.51889)
		(end 129.65176 -270.523716)
		(width 0.0889)
		(layer "In2.Cu")
		(net "M_I_CPU1_SB_CB<7>")
	)
	(segment
		(start 135.857742 -270.523716)
		(end 135.866124 -270.51889)
		(width 0.0889)
		(layer "In2.Cu")
		(net "M_I_CPU1_SB_CB<7>")
	)
	(segment
		(start 128.524762 -270.846296)
		(end 128.370838 -270.580866)
		(width 0.0889)
		(layer "In2.Cu")
		(net "M_I_CPU1_SB_CB<7>")
	)
	(segment
		(start 165.599618 -273.870166)
		(end 165.761162 -274.03171)
		(width 0.14478)
		(layer "In2.Cu")
		(net "M_I_CPU1_SB_CB<7>")
	)
	(segment
		(start 170.920918 -273.928586)
		(end 171.15028 -273.928586)
		(width 0.14478)
		(layer "In2.Cu")
		(net "M_I_CPU1_SB_CB<7>")
	)
	(segment
		(start 138.103356 -270.51889)
		(end 138.111738 -270.523716)
		(width 0.0889)
		(layer "In2.Cu")
		(net "M_I_CPU1_SB_CB<7>")
	)
	(segment
		(start 134.343394 -270.51889)
		(end 134.351776 -270.523716)
		(width 0.0889)
		(layer "In2.Cu")
		(net "M_I_CPU1_SB_CB<7>")
	)
	(segment
		(start 142.803372 -270.51889)
		(end 142.811754 -270.523716)
		(width 0.0889)
		(layer "In2.Cu")
		(net "M_I_CPU1_SB_CB<7>")
	)
	(segment
		(start 145.694908 -269.73276)
		(end 145.792698 -269.675864)
		(width 0.0889)
		(layer "In2.Cu")
		(net "M_I_CPU1_SB_CB<7>")
	)
	(segment
		(start 166.47414 -273.870166)
		(end 166.702486 -273.870166)
		(width 0.14478)
		(layer "In2.Cu")
		(net "M_I_CPU1_SB_CB<7>")
	)
	(segment
		(start 166.151052 -274.63115)
		(end 166.312596 -274.469606)
		(width 0.14478)
		(layer "In2.Cu")
		(net "M_I_CPU1_SB_CB<7>")
	)
	(segment
		(start 178.571906 -273.936206)
		(end 178.886358 -274.250658)
		(width 0.14478)
		(layer "In2.Cu")
		(net "M_I_CPU1_SB_CB<7>")
	)
	(segment
		(start 169.495978 -274.250658)
		(end 169.81805 -273.928586)
		(width 0.14478)
		(layer "In2.Cu")
		(net "M_I_CPU1_SB_CB<7>")
	)
	(arc
		(start 138.67765 -270.523716)
		(mid 138.859901 -270.473366)
		(end 139.04341 -270.51889)
		(width 0.0889)
		(layer "In2.Cu")
		(net "M_I_CPU1_SB_CB<7>")
	)
	(arc
		(start 139.991846 -270.523716)
		(mid 140.274802 -270.599893)
		(end 140.557758 -270.523716)
		(width 0.0889)
		(layer "In2.Cu")
		(net "M_I_CPU1_SB_CB<7>")
	)
	(arc
		(start 131.531868 -270.523716)
		(mid 131.814824 -270.599893)
		(end 132.09778 -270.523716)
		(width 0.0889)
		(layer "In2.Cu")
		(net "M_I_CPU1_SB_CB<7>")
	)
	(arc
		(start 131.166108 -270.51889)
		(mid 131.349616 -270.473396)
		(end 131.531868 -270.523716)
		(width 0.0889)
		(layer "In2.Cu")
		(net "M_I_CPU1_SB_CB<7>")
	)
	(arc
		(start 144.317466 -270.523716)
		(mid 144.495601 -270.473565)
		(end 144.67586 -270.515334)
		(width 0.0889)
		(layer "In2.Cu")
		(net "M_I_CPU1_SB_CB<7>")
	)
	(arc
		(start 142.811754 -270.523716)
		(mid 143.09471 -270.599893)
		(end 143.377666 -270.523716)
		(width 0.0889)
		(layer "In2.Cu")
		(net "M_I_CPU1_SB_CB<7>")
	)
	(arc
		(start 132.471922 -270.523716)
		(mid 132.754878 -270.599893)
		(end 133.037834 -270.523716)
		(width 0.0889)
		(layer "In2.Cu")
		(net "M_I_CPU1_SB_CB<7>")
	)
	(arc
		(start 142.437612 -270.523716)
		(mid 142.619863 -270.473366)
		(end 142.803372 -270.51889)
		(width 0.0889)
		(layer "In2.Cu")
		(net "M_I_CPU1_SB_CB<7>")
	)
	(arc
		(start 141.8717 -270.523716)
		(mid 142.154656 -270.599893)
		(end 142.437612 -270.523716)
		(width 0.0889)
		(layer "In2.Cu")
		(net "M_I_CPU1_SB_CB<7>")
	)
	(arc
		(start 145.302224 -270.498062)
		(mid 145.477204 -270.296196)
		(end 145.539968 -270.036544)
		(width 0.0889)
		(layer "In2.Cu")
		(net "M_I_CPU1_SB_CB<7>")
	)
	(arc
		(start 137.171684 -270.523716)
		(mid 137.45464 -270.599893)
		(end 137.737596 -270.523716)
		(width 0.0889)
		(layer "In2.Cu")
		(net "M_I_CPU1_SB_CB<7>")
	)
	(arc
		(start 134.92607 -270.51889)
		(mid 135.109578 -270.473396)
		(end 135.29183 -270.523716)
		(width 0.0889)
		(layer "In2.Cu")
		(net "M_I_CPU1_SB_CB<7>")
	)
	(arc
		(start 137.737596 -270.523716)
		(mid 137.919847 -270.473366)
		(end 138.103356 -270.51889)
		(width 0.0889)
		(layer "In2.Cu")
		(net "M_I_CPU1_SB_CB<7>")
	)
	(arc
		(start 140.9319 -270.523716)
		(mid 141.214856 -270.599893)
		(end 141.497812 -270.523716)
		(width 0.0889)
		(layer "In2.Cu")
		(net "M_I_CPU1_SB_CB<7>")
	)
	(arc
		(start 141.497812 -270.523716)
		(mid 141.684756 -270.473461)
		(end 141.8717 -270.523716)
		(width 0.0889)
		(layer "In2.Cu")
		(net "M_I_CPU1_SB_CB<7>")
	)
	(arc
		(start 143.386048 -270.51889)
		(mid 143.569556 -270.473396)
		(end 143.751808 -270.523716)
		(width 0.0889)
		(layer "In2.Cu")
		(net "M_I_CPU1_SB_CB<7>")
	)
	(arc
		(start 134.351776 -270.523716)
		(mid 134.634732 -270.599893)
		(end 134.917688 -270.523716)
		(width 0.0889)
		(layer "In2.Cu")
		(net "M_I_CPU1_SB_CB<7>")
	)
	(arc
		(start 128.39319 -270.497554)
		(mid 128.555379 -270.474819)
		(end 128.711706 -270.523716)
		(width 0.0889)
		(layer "In2.Cu")
		(net "M_I_CPU1_SB_CB<7>")
	)
	(arc
		(start 135.866124 -270.51889)
		(mid 136.049632 -270.473396)
		(end 136.231884 -270.523716)
		(width 0.0889)
		(layer "In2.Cu")
		(net "M_I_CPU1_SB_CB<7>")
	)
	(arc
		(start 139.051792 -270.523716)
		(mid 139.334748 -270.599893)
		(end 139.617704 -270.523716)
		(width 0.0889)
		(layer "In2.Cu")
		(net "M_I_CPU1_SB_CB<7>")
	)
	(arc
		(start 130.591814 -270.523716)
		(mid 130.87477 -270.599893)
		(end 131.157726 -270.523716)
		(width 0.0889)
		(layer "In2.Cu")
		(net "M_I_CPU1_SB_CB<7>")
	)
	(arc
		(start 133.411722 -270.523716)
		(mid 133.694678 -270.599893)
		(end 133.977634 -270.523716)
		(width 0.0889)
		(layer "In2.Cu")
		(net "M_I_CPU1_SB_CB<7>")
	)
	(arc
		(start 130.217672 -270.523716)
		(mid 130.399923 -270.473366)
		(end 130.583432 -270.51889)
		(width 0.0889)
		(layer "In2.Cu")
		(net "M_I_CPU1_SB_CB<7>")
	)
	(arc
		(start 129.277618 -270.523716)
		(mid 129.459869 -270.473366)
		(end 129.643378 -270.51889)
		(width 0.0889)
		(layer "In2.Cu")
		(net "M_I_CPU1_SB_CB<7>")
	)
	(arc
		(start 128.711706 -270.523716)
		(mid 128.994662 -270.599893)
		(end 129.277618 -270.523716)
		(width 0.0889)
		(layer "In2.Cu")
		(net "M_I_CPU1_SB_CB<7>")
	)
	(arc
		(start 132.106162 -270.51889)
		(mid 132.28967 -270.473396)
		(end 132.471922 -270.523716)
		(width 0.0889)
		(layer "In2.Cu")
		(net "M_I_CPU1_SB_CB<7>")
	)
	(arc
		(start 133.977634 -270.523716)
		(mid 134.159885 -270.473366)
		(end 134.343394 -270.51889)
		(width 0.0889)
		(layer "In2.Cu")
		(net "M_I_CPU1_SB_CB<7>")
	)
	(arc
		(start 143.751808 -270.523716)
		(mid 144.028621 -270.599859)
		(end 144.307052 -270.529812)
		(width 0.0889)
		(layer "In2.Cu")
		(net "M_I_CPU1_SB_CB<7>")
	)
	(arc
		(start 135.29183 -270.523716)
		(mid 135.574786 -270.599893)
		(end 135.857742 -270.523716)
		(width 0.0889)
		(layer "In2.Cu")
		(net "M_I_CPU1_SB_CB<7>")
	)
	(arc
		(start 136.797796 -270.523716)
		(mid 136.98474 -270.473461)
		(end 137.171684 -270.523716)
		(width 0.0889)
		(layer "In2.Cu")
		(net "M_I_CPU1_SB_CB<7>")
	)
	(arc
		(start 138.111738 -270.523716)
		(mid 138.394694 -270.599893)
		(end 138.67765 -270.523716)
		(width 0.0889)
		(layer "In2.Cu")
		(net "M_I_CPU1_SB_CB<7>")
	)
	(arc
		(start 133.037834 -270.523716)
		(mid 133.224778 -270.473461)
		(end 133.411722 -270.523716)
		(width 0.0889)
		(layer "In2.Cu")
		(net "M_I_CPU1_SB_CB<7>")
	)
	(arc
		(start 139.626086 -270.51889)
		(mid 139.809594 -270.473396)
		(end 139.991846 -270.523716)
		(width 0.0889)
		(layer "In2.Cu")
		(net "M_I_CPU1_SB_CB<7>")
	)
	(arc
		(start 144.701768 -270.53032)
		(mid 144.980454 -270.600604)
		(end 145.25752 -270.524224)
		(width 0.0889)
		(layer "In2.Cu")
		(net "M_I_CPU1_SB_CB<7>")
	)
	(arc
		(start 140.56614 -270.51889)
		(mid 140.749648 -270.473396)
		(end 140.9319 -270.523716)
		(width 0.0889)
		(layer "In2.Cu")
		(net "M_I_CPU1_SB_CB<7>")
	)
	(arc
		(start 129.65176 -270.523716)
		(mid 129.934716 -270.599893)
		(end 130.217672 -270.523716)
		(width 0.0889)
		(layer "In2.Cu")
		(net "M_I_CPU1_SB_CB<7>")
	)
	(arc
		(start 136.231884 -270.523716)
		(mid 136.51484 -270.599893)
		(end 136.797796 -270.523716)
		(width 0.0889)
		(layer "In2.Cu")
		(net "M_I_CPU1_SB_CB<7>")
	)
	(arc
		(start 145.539968 -270.036544)
		(mid 145.580876 -269.865997)
		(end 145.694908 -269.73276)
		(width 0.0889)
		(layer "In2.Cu")
		(net "M_I_CPU1_SB_CB<7>")
	)
	(segment
		(start 129.467864 -269.770352)
		(end 129.934716 -270.03629)
		(width 0.10668)
		(layer "F.Cu")
		(net "M_I_CPU1_SB_CB<6>")
	)
	(segment
		(start 173.659292 -272.37563)
		(end 173.84395 -272.190972)
		(width 0.14478)
		(layer "In2.Cu")
		(net "M_I_CPU1_SB_CB<6>")
	)
	(segment
		(start 178.822858 -272.292064)
		(end 179.516024 -272.98523)
		(width 0.14478)
		(layer "In2.Cu")
		(net "M_I_CPU1_SB_CB<6>")
	)
	(segment
		(start 141.393418 -269.708884)
		(end 141.4018 -269.71371)
		(width 0.0889)
		(layer "In2.Cu")
		(net "M_I_CPU1_SB_CB<6>")
	)
	(segment
		(start 162.60445 -272.1102)
		(end 163.054538 -272.560288)
		(width 0.14478)
		(layer "In2.Cu")
		(net "M_I_CPU1_SB_CB<6>")
	)
	(segment
		(start 174.317152 -272.37563)
		(end 174.317152 -272.744946)
		(width 0.14478)
		(layer "In2.Cu")
		(net "M_I_CPU1_SB_CB<6>")
	)
	(segment
		(start 140.453364 -269.708884)
		(end 140.461746 -269.71371)
		(width 0.0889)
		(layer "In2.Cu")
		(net "M_I_CPU1_SB_CB<6>")
	)
	(segment
		(start 162.392868 -272.1102)
		(end 162.60445 -272.1102)
		(width 0.14478)
		(layer "In2.Cu")
		(net "M_I_CPU1_SB_CB<6>")
	)
	(segment
		(start 159.493966 -270.05407)
		(end 159.706056 -270.05407)
		(width 0.14478)
		(layer "In2.Cu")
		(net "M_I_CPU1_SB_CB<6>")
	)
	(segment
		(start 162.15995 -271.340834)
		(end 162.15995 -271.552416)
		(width 0.14478)
		(layer "In2.Cu")
		(net "M_I_CPU1_SB_CB<6>")
	)
	(segment
		(start 160.85693 -270.484346)
		(end 161.06902 -270.484346)
		(width 0.14478)
		(layer "In2.Cu")
		(net "M_I_CPU1_SB_CB<6>")
	)
	(segment
		(start 166.332662 -272.428208)
		(end 166.628318 -272.428208)
		(width 0.14478)
		(layer "In2.Cu")
		(net "M_I_CPU1_SB_CB<6>")
	)
	(segment
		(start 159.436816 -269.321026)
		(end 159.436816 -269.532862)
		(width 0.14478)
		(layer "In2.Cu")
		(net "M_I_CPU1_SB_CB<6>")
	)
	(segment
		(start 175.15967 -272.560288)
		(end 177.056034 -272.560288)
		(width 0.14478)
		(layer "In2.Cu")
		(net "M_I_CPU1_SB_CB<6>")
	)
	(segment
		(start 158.703518 -269.263622)
		(end 158.915608 -269.263622)
		(width 0.14478)
		(layer "In2.Cu")
		(net "M_I_CPU1_SB_CB<6>")
	)
	(segment
		(start 173.474634 -272.929604)
		(end 173.659292 -272.744946)
		(width 0.14478)
		(layer "In2.Cu")
		(net "M_I_CPU1_SB_CB<6>")
	)
	(segment
		(start 144.213326 -269.708884)
		(end 144.221708 -269.71371)
		(width 0.0889)
		(layer "In2.Cu")
		(net "M_I_CPU1_SB_CB<6>")
	)
	(segment
		(start 165.773862 -272.165064)
		(end 166.069518 -272.165064)
		(width 0.14478)
		(layer "In2.Cu")
		(net "M_I_CPU1_SB_CB<6>")
	)
	(segment
		(start 173.659292 -272.744946)
		(end 173.659292 -272.37563)
		(width 0.14478)
		(layer "In2.Cu")
		(net "M_I_CPU1_SB_CB<6>")
	)
	(segment
		(start 166.891462 -272.165064)
		(end 167.187118 -272.165064)
		(width 0.14478)
		(layer "In2.Cu")
		(net "M_I_CPU1_SB_CB<6>")
	)
	(segment
		(start 167.582342 -272.560288)
		(end 172.816774 -272.560288)
		(width 0.14478)
		(layer "In2.Cu")
		(net "M_I_CPU1_SB_CB<6>")
	)
	(segment
		(start 135.753348 -269.708884)
		(end 135.76173 -269.71371)
		(width 0.0889)
		(layer "In2.Cu")
		(net "M_I_CPU1_SB_CB<6>")
	)
	(segment
		(start 173.84395 -272.190972)
		(end 174.132494 -272.190972)
		(width 0.14478)
		(layer "In2.Cu")
		(net "M_I_CPU1_SB_CB<6>")
	)
	(segment
		(start 131.993386 -269.708884)
		(end 132.001768 -269.71371)
		(width 0.0889)
		(layer "In2.Cu")
		(net "M_I_CPU1_SB_CB<6>")
	)
	(segment
		(start 161.06902 -270.484346)
		(end 161.252154 -270.66748)
		(width 0.14478)
		(layer "In2.Cu")
		(net "M_I_CPU1_SB_CB<6>")
	)
	(segment
		(start 163.054538 -272.560288)
		(end 165.378638 -272.560288)
		(width 0.14478)
		(layer "In2.Cu")
		(net "M_I_CPU1_SB_CB<6>")
	)
	(segment
		(start 174.50181 -272.929604)
		(end 174.790354 -272.929604)
		(width 0.14478)
		(layer "In2.Cu")
		(net "M_I_CPU1_SB_CB<6>")
	)
	(segment
		(start 174.132494 -272.190972)
		(end 174.317152 -272.37563)
		(width 0.14478)
		(layer "In2.Cu")
		(net "M_I_CPU1_SB_CB<6>")
	)
	(segment
		(start 157.2006 -267.760704)
		(end 158.703518 -269.263622)
		(width 0.14478)
		(layer "In2.Cu")
		(net "M_I_CPU1_SB_CB<6>")
	)
	(segment
		(start 161.074862 -271.634966)
		(end 161.286698 -271.634966)
		(width 0.14478)
		(layer "In2.Cu")
		(net "M_I_CPU1_SB_CB<6>")
	)
	(segment
		(start 144.776952 -269.719806)
		(end 144.787366 -269.71371)
		(width 0.0889)
		(layer "In2.Cu")
		(net "M_I_CPU1_SB_CB<6>")
	)
	(segment
		(start 162.077146 -272.425414)
		(end 162.392868 -272.1102)
		(width 0.14478)
		(layer "In2.Cu")
		(net "M_I_CPU1_SB_CB<6>")
	)
	(segment
		(start 166.628318 -272.428208)
		(end 166.891462 -272.165064)
		(width 0.14478)
		(layer "In2.Cu")
		(net "M_I_CPU1_SB_CB<6>")
	)
	(segment
		(start 133.507734 -269.71371)
		(end 133.516116 -269.708884)
		(width 0.0889)
		(layer "In2.Cu")
		(net "M_I_CPU1_SB_CB<6>")
	)
	(segment
		(start 146.226276 -268.348714)
		(end 146.814286 -267.760704)
		(width 0.0889)
		(layer "In2.Cu")
		(net "M_I_CPU1_SB_CB<6>")
	)
	(segment
		(start 137.267696 -269.71371)
		(end 137.276078 -269.708884)
		(width 0.0889)
		(layer "In2.Cu")
		(net "M_I_CPU1_SB_CB<6>")
	)
	(segment
		(start 159.310578 -269.6591)
		(end 159.310578 -269.870682)
		(width 0.14478)
		(layer "In2.Cu")
		(net "M_I_CPU1_SB_CB<6>")
	)
	(segment
		(start 136.693402 -269.708884)
		(end 136.701784 -269.71371)
		(width 0.0889)
		(layer "In2.Cu")
		(net "M_I_CPU1_SB_CB<6>")
	)
	(segment
		(start 146.814286 -267.760704)
		(end 147.487386 -267.760704)
		(width 0.0889)
		(layer "In2.Cu")
		(net "M_I_CPU1_SB_CB<6>")
	)
	(segment
		(start 144.787366 -269.71371)
		(end 144.78762 -269.71371)
		(width 0.0889)
		(layer "In2.Cu")
		(net "M_I_CPU1_SB_CB<6>")
	)
	(segment
		(start 132.93344 -269.708884)
		(end 132.941822 -269.71371)
		(width 0.0889)
		(layer "In2.Cu")
		(net "M_I_CPU1_SB_CB<6>")
	)
	(segment
		(start 178.173634 -272.560288)
		(end 178.441858 -272.292064)
		(width 0.14478)
		(layer "In2.Cu")
		(net "M_I_CPU1_SB_CB<6>")
	)
	(segment
		(start 144.78762 -269.71371)
		(end 144.826736 -269.69085)
		(width 0.0889)
		(layer "In2.Cu")
		(net "M_I_CPU1_SB_CB<6>")
	)
	(segment
		(start 177.883058 -272.560288)
		(end 178.173634 -272.560288)
		(width 0.14478)
		(layer "In2.Cu")
		(net "M_I_CPU1_SB_CB<6>")
	)
	(segment
		(start 161.252154 -270.879316)
		(end 160.891474 -271.239996)
		(width 0.14478)
		(layer "In2.Cu")
		(net "M_I_CPU1_SB_CB<6>")
	)
	(segment
		(start 159.706056 -270.05407)
		(end 159.949134 -269.810992)
		(width 0.14478)
		(layer "In2.Cu")
		(net "M_I_CPU1_SB_CB<6>")
	)
	(segment
		(start 160.891474 -271.451578)
		(end 161.074862 -271.634966)
		(width 0.14478)
		(layer "In2.Cu")
		(net "M_I_CPU1_SB_CB<6>")
	)
	(segment
		(start 159.310578 -269.870682)
		(end 159.493966 -270.05407)
		(width 0.14478)
		(layer "In2.Cu")
		(net "M_I_CPU1_SB_CB<6>")
	)
	(segment
		(start 160.344358 -269.99438)
		(end 160.344358 -270.206216)
		(width 0.14478)
		(layer "In2.Cu")
		(net "M_I_CPU1_SB_CB<6>")
	)
	(segment
		(start 178.441858 -272.292064)
		(end 178.822858 -272.292064)
		(width 0.14478)
		(layer "In2.Cu")
		(net "M_I_CPU1_SB_CB<6>")
	)
	(segment
		(start 141.967712 -269.71371)
		(end 141.976094 -269.708884)
		(width 0.0889)
		(layer "In2.Cu")
		(net "M_I_CPU1_SB_CB<6>")
	)
	(segment
		(start 145.226024 -268.921992)
		(end 145.257774 -268.903704)
		(width 0.0889)
		(layer "In2.Cu")
		(net "M_I_CPU1_SB_CB<6>")
	)
	(segment
		(start 160.284414 -270.844518)
		(end 160.49625 -270.844518)
		(width 0.14478)
		(layer "In2.Cu")
		(net "M_I_CPU1_SB_CB<6>")
	)
	(segment
		(start 160.101026 -270.449548)
		(end 160.101026 -270.66113)
		(width 0.14478)
		(layer "In2.Cu")
		(net "M_I_CPU1_SB_CB<6>")
	)
	(segment
		(start 161.76498 -271.157446)
		(end 161.976562 -271.157446)
		(width 0.14478)
		(layer "In2.Cu")
		(net "M_I_CPU1_SB_CB<6>")
	)
	(segment
		(start 177.324258 -272.292064)
		(end 177.614834 -272.292064)
		(width 0.14478)
		(layer "In2.Cu")
		(net "M_I_CPU1_SB_CB<6>")
	)
	(segment
		(start 160.891474 -271.239996)
		(end 160.891474 -271.451578)
		(width 0.14478)
		(layer "In2.Cu")
		(net "M_I_CPU1_SB_CB<6>")
	)
	(segment
		(start 129.934716 -270.03629)
		(end 129.780792 -269.77086)
		(width 0.0889)
		(layer "In2.Cu")
		(net "M_I_CPU1_SB_CB<6>")
	)
	(segment
		(start 160.16097 -269.810992)
		(end 160.344358 -269.99438)
		(width 0.14478)
		(layer "In2.Cu")
		(net "M_I_CPU1_SB_CB<6>")
	)
	(segment
		(start 174.790354 -272.929604)
		(end 175.15967 -272.560288)
		(width 0.14478)
		(layer "In2.Cu")
		(net "M_I_CPU1_SB_CB<6>")
	)
	(segment
		(start 174.317152 -272.744946)
		(end 174.50181 -272.929604)
		(width 0.14478)
		(layer "In2.Cu")
		(net "M_I_CPU1_SB_CB<6>")
	)
	(segment
		(start 159.253428 -269.137638)
		(end 159.436816 -269.321026)
		(width 0.14478)
		(layer "In2.Cu")
		(net "M_I_CPU1_SB_CB<6>")
	)
	(segment
		(start 177.056034 -272.560288)
		(end 177.324258 -272.292064)
		(width 0.14478)
		(layer "In2.Cu")
		(net "M_I_CPU1_SB_CB<6>")
	)
	(segment
		(start 159.436816 -269.532862)
		(end 159.310578 -269.6591)
		(width 0.14478)
		(layer "In2.Cu")
		(net "M_I_CPU1_SB_CB<6>")
	)
	(segment
		(start 161.681922 -272.242026)
		(end 161.86531 -272.425414)
		(width 0.14478)
		(layer "In2.Cu")
		(net "M_I_CPU1_SB_CB<6>")
	)
	(segment
		(start 161.252154 -270.66748)
		(end 161.252154 -270.879316)
		(width 0.14478)
		(layer "In2.Cu")
		(net "M_I_CPU1_SB_CB<6>")
	)
	(segment
		(start 145.257774 -268.903704)
		(end 146.226276 -268.348714)
		(width 0.0889)
		(layer "In2.Cu")
		(net "M_I_CPU1_SB_CB<6>")
	)
	(segment
		(start 165.378638 -272.560288)
		(end 165.773862 -272.165064)
		(width 0.14478)
		(layer "In2.Cu")
		(net "M_I_CPU1_SB_CB<6>")
	)
	(segment
		(start 158.915608 -269.263622)
		(end 159.041592 -269.137638)
		(width 0.14478)
		(layer "In2.Cu")
		(net "M_I_CPU1_SB_CB<6>")
	)
	(segment
		(start 177.614834 -272.292064)
		(end 177.883058 -272.560288)
		(width 0.14478)
		(layer "In2.Cu")
		(net "M_I_CPU1_SB_CB<6>")
	)
	(segment
		(start 161.976562 -271.157446)
		(end 162.15995 -271.340834)
		(width 0.14478)
		(layer "In2.Cu")
		(net "M_I_CPU1_SB_CB<6>")
	)
	(segment
		(start 160.101026 -270.66113)
		(end 160.284414 -270.844518)
		(width 0.14478)
		(layer "In2.Cu")
		(net "M_I_CPU1_SB_CB<6>")
	)
	(segment
		(start 160.344358 -270.206216)
		(end 160.101026 -270.449548)
		(width 0.14478)
		(layer "In2.Cu")
		(net "M_I_CPU1_SB_CB<6>")
	)
	(segment
		(start 161.286698 -271.634966)
		(end 161.76498 -271.157446)
		(width 0.14478)
		(layer "In2.Cu")
		(net "M_I_CPU1_SB_CB<6>")
	)
	(segment
		(start 160.49625 -270.844518)
		(end 160.85693 -270.484346)
		(width 0.14478)
		(layer "In2.Cu")
		(net "M_I_CPU1_SB_CB<6>")
	)
	(segment
		(start 166.069518 -272.165064)
		(end 166.332662 -272.428208)
		(width 0.14478)
		(layer "In2.Cu")
		(net "M_I_CPU1_SB_CB<6>")
	)
	(segment
		(start 161.681922 -272.030444)
		(end 161.681922 -272.242026)
		(width 0.14478)
		(layer "In2.Cu")
		(net "M_I_CPU1_SB_CB<6>")
	)
	(segment
		(start 147.487386 -267.760704)
		(end 157.2006 -267.760704)
		(width 0.14478)
		(layer "In2.Cu")
		(net "M_I_CPU1_SB_CB<6>")
	)
	(segment
		(start 162.15995 -271.552416)
		(end 161.681922 -272.030444)
		(width 0.14478)
		(layer "In2.Cu")
		(net "M_I_CPU1_SB_CB<6>")
	)
	(segment
		(start 159.041592 -269.137638)
		(end 159.253428 -269.137638)
		(width 0.14478)
		(layer "In2.Cu")
		(net "M_I_CPU1_SB_CB<6>")
	)
	(segment
		(start 138.20775 -269.71371)
		(end 138.216132 -269.708884)
		(width 0.0889)
		(layer "In2.Cu")
		(net "M_I_CPU1_SB_CB<6>")
	)
	(segment
		(start 167.187118 -272.165064)
		(end 167.582342 -272.560288)
		(width 0.14478)
		(layer "In2.Cu")
		(net "M_I_CPU1_SB_CB<6>")
	)
	(segment
		(start 173.18609 -272.929604)
		(end 173.474634 -272.929604)
		(width 0.14478)
		(layer "In2.Cu")
		(net "M_I_CPU1_SB_CB<6>")
	)
	(segment
		(start 129.780792 -269.77086)
		(end 129.803144 -269.687548)
		(width 0.0889)
		(layer "In2.Cu")
		(net "M_I_CPU1_SB_CB<6>")
	)
	(segment
		(start 159.949134 -269.810992)
		(end 160.16097 -269.810992)
		(width 0.14478)
		(layer "In2.Cu")
		(net "M_I_CPU1_SB_CB<6>")
	)
	(segment
		(start 172.816774 -272.560288)
		(end 173.18609 -272.929604)
		(width 0.14478)
		(layer "In2.Cu")
		(net "M_I_CPU1_SB_CB<6>")
	)
	(segment
		(start 161.86531 -272.425414)
		(end 162.077146 -272.425414)
		(width 0.14478)
		(layer "In2.Cu")
		(net "M_I_CPU1_SB_CB<6>")
	)
	(arc
		(start 145.070068 -269.226284)
		(mid 145.111323 -269.055313)
		(end 145.226024 -268.921992)
		(width 0.0889)
		(layer "In2.Cu")
		(net "M_I_CPU1_SB_CB<6>")
	)
	(arc
		(start 140.461746 -269.71371)
		(mid 140.744702 -269.789887)
		(end 141.027658 -269.71371)
		(width 0.0889)
		(layer "In2.Cu")
		(net "M_I_CPU1_SB_CB<6>")
	)
	(arc
		(start 133.516116 -269.708884)
		(mid 133.699624 -269.66339)
		(end 133.881876 -269.71371)
		(width 0.0889)
		(layer "In2.Cu")
		(net "M_I_CPU1_SB_CB<6>")
	)
	(arc
		(start 130.687826 -269.71371)
		(mid 130.87477 -269.663455)
		(end 131.061714 -269.71371)
		(width 0.0889)
		(layer "In2.Cu")
		(net "M_I_CPU1_SB_CB<6>")
	)
	(arc
		(start 143.281654 -269.71371)
		(mid 143.56461 -269.789887)
		(end 143.847566 -269.71371)
		(width 0.0889)
		(layer "In2.Cu")
		(net "M_I_CPU1_SB_CB<6>")
	)
	(arc
		(start 137.276078 -269.708884)
		(mid 137.459586 -269.66339)
		(end 137.641838 -269.71371)
		(width 0.0889)
		(layer "In2.Cu")
		(net "M_I_CPU1_SB_CB<6>")
	)
	(arc
		(start 144.826736 -269.69085)
		(mid 145.005549 -269.4885)
		(end 145.070068 -269.226284)
		(width 0.0889)
		(layer "In2.Cu")
		(net "M_I_CPU1_SB_CB<6>")
	)
	(arc
		(start 138.216132 -269.708884)
		(mid 138.39964 -269.66339)
		(end 138.581892 -269.71371)
		(width 0.0889)
		(layer "In2.Cu")
		(net "M_I_CPU1_SB_CB<6>")
	)
	(arc
		(start 130.121914 -269.71371)
		(mid 130.40487 -269.789887)
		(end 130.687826 -269.71371)
		(width 0.0889)
		(layer "In2.Cu")
		(net "M_I_CPU1_SB_CB<6>")
	)
	(arc
		(start 134.447788 -269.71371)
		(mid 134.634732 -269.663455)
		(end 134.821676 -269.71371)
		(width 0.0889)
		(layer "In2.Cu")
		(net "M_I_CPU1_SB_CB<6>")
	)
	(arc
		(start 132.001768 -269.71371)
		(mid 132.284724 -269.789887)
		(end 132.56768 -269.71371)
		(width 0.0889)
		(layer "In2.Cu")
		(net "M_I_CPU1_SB_CB<6>")
	)
	(arc
		(start 137.641838 -269.71371)
		(mid 137.924794 -269.789887)
		(end 138.20775 -269.71371)
		(width 0.0889)
		(layer "In2.Cu")
		(net "M_I_CPU1_SB_CB<6>")
	)
	(arc
		(start 134.821676 -269.71371)
		(mid 135.104632 -269.789887)
		(end 135.387588 -269.71371)
		(width 0.0889)
		(layer "In2.Cu")
		(net "M_I_CPU1_SB_CB<6>")
	)
	(arc
		(start 141.027658 -269.71371)
		(mid 141.209909 -269.66336)
		(end 141.393418 -269.708884)
		(width 0.0889)
		(layer "In2.Cu")
		(net "M_I_CPU1_SB_CB<6>")
	)
	(arc
		(start 132.56768 -269.71371)
		(mid 132.749931 -269.66336)
		(end 132.93344 -269.708884)
		(width 0.0889)
		(layer "In2.Cu")
		(net "M_I_CPU1_SB_CB<6>")
	)
	(arc
		(start 141.976094 -269.708884)
		(mid 142.159602 -269.66339)
		(end 142.341854 -269.71371)
		(width 0.0889)
		(layer "In2.Cu")
		(net "M_I_CPU1_SB_CB<6>")
	)
	(arc
		(start 140.087604 -269.71371)
		(mid 140.269855 -269.66336)
		(end 140.453364 -269.708884)
		(width 0.0889)
		(layer "In2.Cu")
		(net "M_I_CPU1_SB_CB<6>")
	)
	(arc
		(start 132.941822 -269.71371)
		(mid 133.224778 -269.789887)
		(end 133.507734 -269.71371)
		(width 0.0889)
		(layer "In2.Cu")
		(net "M_I_CPU1_SB_CB<6>")
	)
	(arc
		(start 136.327642 -269.71371)
		(mid 136.509893 -269.66336)
		(end 136.693402 -269.708884)
		(width 0.0889)
		(layer "In2.Cu")
		(net "M_I_CPU1_SB_CB<6>")
	)
	(arc
		(start 135.387588 -269.71371)
		(mid 135.569839 -269.66336)
		(end 135.753348 -269.708884)
		(width 0.0889)
		(layer "In2.Cu")
		(net "M_I_CPU1_SB_CB<6>")
	)
	(arc
		(start 138.581892 -269.71371)
		(mid 138.864848 -269.789887)
		(end 139.147804 -269.71371)
		(width 0.0889)
		(layer "In2.Cu")
		(net "M_I_CPU1_SB_CB<6>")
	)
	(arc
		(start 144.221708 -269.71371)
		(mid 144.498521 -269.789853)
		(end 144.776952 -269.719806)
		(width 0.0889)
		(layer "In2.Cu")
		(net "M_I_CPU1_SB_CB<6>")
	)
	(arc
		(start 136.701784 -269.71371)
		(mid 136.98474 -269.789887)
		(end 137.267696 -269.71371)
		(width 0.0889)
		(layer "In2.Cu")
		(net "M_I_CPU1_SB_CB<6>")
	)
	(arc
		(start 141.4018 -269.71371)
		(mid 141.684756 -269.789887)
		(end 141.967712 -269.71371)
		(width 0.0889)
		(layer "In2.Cu")
		(net "M_I_CPU1_SB_CB<6>")
	)
	(arc
		(start 139.521692 -269.71371)
		(mid 139.804648 -269.789887)
		(end 140.087604 -269.71371)
		(width 0.0889)
		(layer "In2.Cu")
		(net "M_I_CPU1_SB_CB<6>")
	)
	(arc
		(start 142.907766 -269.71371)
		(mid 143.09471 -269.663455)
		(end 143.281654 -269.71371)
		(width 0.0889)
		(layer "In2.Cu")
		(net "M_I_CPU1_SB_CB<6>")
	)
	(arc
		(start 129.803144 -269.687548)
		(mid 129.965476 -269.66473)
		(end 130.121914 -269.71371)
		(width 0.0889)
		(layer "In2.Cu")
		(net "M_I_CPU1_SB_CB<6>")
	)
	(arc
		(start 142.341854 -269.71371)
		(mid 142.62481 -269.789887)
		(end 142.907766 -269.71371)
		(width 0.0889)
		(layer "In2.Cu")
		(net "M_I_CPU1_SB_CB<6>")
	)
	(arc
		(start 133.881876 -269.71371)
		(mid 134.164832 -269.789887)
		(end 134.447788 -269.71371)
		(width 0.0889)
		(layer "In2.Cu")
		(net "M_I_CPU1_SB_CB<6>")
	)
	(arc
		(start 143.847566 -269.71371)
		(mid 144.029817 -269.66336)
		(end 144.213326 -269.708884)
		(width 0.0889)
		(layer "In2.Cu")
		(net "M_I_CPU1_SB_CB<6>")
	)
	(arc
		(start 131.061714 -269.71371)
		(mid 131.34467 -269.789887)
		(end 131.627626 -269.71371)
		(width 0.0889)
		(layer "In2.Cu")
		(net "M_I_CPU1_SB_CB<6>")
	)
	(arc
		(start 131.627626 -269.71371)
		(mid 131.809877 -269.66336)
		(end 131.993386 -269.708884)
		(width 0.0889)
		(layer "In2.Cu")
		(net "M_I_CPU1_SB_CB<6>")
	)
	(arc
		(start 135.76173 -269.71371)
		(mid 136.044686 -269.789887)
		(end 136.327642 -269.71371)
		(width 0.0889)
		(layer "In2.Cu")
		(net "M_I_CPU1_SB_CB<6>")
	)
	(arc
		(start 139.147804 -269.71371)
		(mid 139.334748 -269.663455)
		(end 139.521692 -269.71371)
		(width 0.0889)
		(layer "In2.Cu")
		(net "M_I_CPU1_SB_CB<6>")
	)
	(segment
		(start 127.58801 -269.770352)
		(end 128.054862 -270.03629)
		(width 0.10668)
		(layer "F.Cu")
		(net "M_I_CPU1_SB_CB<5>")
	)
	(segment
		(start 135.753348 -270.363696)
		(end 135.76173 -270.35887)
		(width 0.0889)
		(layer "In2.Cu")
		(net "M_I_CPU1_SB_CB<5>")
	)
	(segment
		(start 132.93344 -270.363696)
		(end 132.941822 -270.35887)
		(width 0.0889)
		(layer "In2.Cu")
		(net "M_I_CPU1_SB_CB<5>")
	)
	(segment
		(start 157.014164 -268.210284)
		(end 161.610802 -272.806922)
		(width 0.14478)
		(layer "In2.Cu")
		(net "M_I_CPU1_SB_CB<5>")
	)
	(segment
		(start 181.78018 -273.410426)
		(end 183.19115 -273.410426)
		(width 0.14478)
		(layer "In2.Cu")
		(net "M_I_CPU1_SB_CB<5>")
	)
	(segment
		(start 131.993386 -270.363696)
		(end 132.001768 -270.35887)
		(width 0.0889)
		(layer "In2.Cu")
		(net "M_I_CPU1_SB_CB<5>")
	)
	(segment
		(start 181.228746 -274.149566)
		(end 181.457092 -274.149566)
		(width 0.14478)
		(layer "In2.Cu")
		(net "M_I_CPU1_SB_CB<5>")
	)
	(segment
		(start 181.618636 -273.988022)
		(end 181.618636 -273.57197)
		(width 0.14478)
		(layer "In2.Cu")
		(net "M_I_CPU1_SB_CB<5>")
	)
	(segment
		(start 141.393418 -270.363696)
		(end 141.4018 -270.35887)
		(width 0.0889)
		(layer "In2.Cu")
		(net "M_I_CPU1_SB_CB<5>")
	)
	(segment
		(start 140.453364 -270.363696)
		(end 140.461746 -270.35887)
		(width 0.0889)
		(layer "In2.Cu")
		(net "M_I_CPU1_SB_CB<5>")
	)
	(segment
		(start 128.208786 -270.30172)
		(end 128.304798 -270.32712)
		(width 0.0889)
		(layer "In2.Cu")
		(net "M_I_CPU1_SB_CB<5>")
	)
	(segment
		(start 145.631916 -269.548864)
		(end 146.600672 -268.588744)
		(width 0.0889)
		(layer "In2.Cu")
		(net "M_I_CPU1_SB_CB<5>")
	)
	(segment
		(start 145.590006 -269.573248)
		(end 145.631916 -269.548864)
		(width 0.0889)
		(layer "In2.Cu")
		(net "M_I_CPU1_SB_CB<5>")
	)
	(segment
		(start 181.618636 -273.57197)
		(end 181.78018 -273.410426)
		(width 0.14478)
		(layer "In2.Cu")
		(net "M_I_CPU1_SB_CB<5>")
	)
	(segment
		(start 145.161508 -270.359378)
		(end 145.19783 -270.338296)
		(width 0.0889)
		(layer "In2.Cu")
		(net "M_I_CPU1_SB_CB<5>")
	)
	(segment
		(start 141.967712 -270.35887)
		(end 141.976094 -270.363696)
		(width 0.0889)
		(layer "In2.Cu")
		(net "M_I_CPU1_SB_CB<5>")
	)
	(segment
		(start 129.747772 -270.35887)
		(end 129.756154 -270.363696)
		(width 0.0889)
		(layer "In2.Cu")
		(net "M_I_CPU1_SB_CB<5>")
	)
	(segment
		(start 181.067202 -273.988022)
		(end 181.228746 -274.149566)
		(width 0.14478)
		(layer "In2.Cu")
		(net "M_I_CPU1_SB_CB<5>")
	)
	(segment
		(start 181.067202 -273.57197)
		(end 181.067202 -273.988022)
		(width 0.14478)
		(layer "In2.Cu")
		(net "M_I_CPU1_SB_CB<5>")
	)
	(segment
		(start 181.457092 -274.149566)
		(end 181.618636 -273.988022)
		(width 0.14478)
		(layer "In2.Cu")
		(net "M_I_CPU1_SB_CB<5>")
	)
	(segment
		(start 144.213326 -270.363696)
		(end 144.221708 -270.35887)
		(width 0.0889)
		(layer "In2.Cu")
		(net "M_I_CPU1_SB_CB<5>")
	)
	(segment
		(start 147.114006 -268.588744)
		(end 147.492466 -268.210284)
		(width 0.0889)
		(layer "In2.Cu")
		(net "M_I_CPU1_SB_CB<5>")
	)
	(segment
		(start 183.19115 -273.410426)
		(end 183.616092 -273.835368)
		(width 0.14478)
		(layer "In2.Cu")
		(net "M_I_CPU1_SB_CB<5>")
	)
	(segment
		(start 146.600672 -268.588744)
		(end 147.114006 -268.588744)
		(width 0.0889)
		(layer "In2.Cu")
		(net "M_I_CPU1_SB_CB<5>")
	)
	(segment
		(start 136.693402 -270.363696)
		(end 136.701784 -270.35887)
		(width 0.0889)
		(layer "In2.Cu")
		(net "M_I_CPU1_SB_CB<5>")
	)
	(segment
		(start 180.905658 -273.410426)
		(end 181.067202 -273.57197)
		(width 0.14478)
		(layer "In2.Cu")
		(net "M_I_CPU1_SB_CB<5>")
	)
	(segment
		(start 128.054862 -270.03629)
		(end 128.208786 -270.30172)
		(width 0.0889)
		(layer "In2.Cu")
		(net "M_I_CPU1_SB_CB<5>")
	)
	(segment
		(start 128.807718 -270.35887)
		(end 128.8161 -270.363696)
		(width 0.0889)
		(layer "In2.Cu")
		(net "M_I_CPU1_SB_CB<5>")
	)
	(segment
		(start 133.507734 -270.35887)
		(end 133.516116 -270.363696)
		(width 0.0889)
		(layer "In2.Cu")
		(net "M_I_CPU1_SB_CB<5>")
	)
	(segment
		(start 161.610802 -272.806922)
		(end 163.068254 -273.410426)
		(width 0.14478)
		(layer "In2.Cu")
		(net "M_I_CPU1_SB_CB<5>")
	)
	(segment
		(start 144.787366 -270.359378)
		(end 144.795748 -270.364204)
		(width 0.0889)
		(layer "In2.Cu")
		(net "M_I_CPU1_SB_CB<5>")
	)
	(segment
		(start 163.068254 -273.410426)
		(end 180.905658 -273.410426)
		(width 0.14478)
		(layer "In2.Cu")
		(net "M_I_CPU1_SB_CB<5>")
	)
	(segment
		(start 144.77111 -270.349726)
		(end 144.787366 -270.359378)
		(width 0.0889)
		(layer "In2.Cu")
		(net "M_I_CPU1_SB_CB<5>")
	)
	(segment
		(start 137.267696 -270.35887)
		(end 137.276078 -270.363696)
		(width 0.0889)
		(layer "In2.Cu")
		(net "M_I_CPU1_SB_CB<5>")
	)
	(segment
		(start 138.20775 -270.35887)
		(end 138.216132 -270.363696)
		(width 0.0889)
		(layer "In2.Cu")
		(net "M_I_CPU1_SB_CB<5>")
	)
	(segment
		(start 147.492466 -268.210284)
		(end 157.014164 -268.210284)
		(width 0.14478)
		(layer "In2.Cu")
		(net "M_I_CPU1_SB_CB<5>")
	)
	(arc
		(start 138.581892 -270.35887)
		(mid 138.864848 -270.282693)
		(end 139.147804 -270.35887)
		(width 0.0889)
		(layer "In2.Cu")
		(net "M_I_CPU1_SB_CB<5>")
	)
	(arc
		(start 128.8161 -270.363696)
		(mid 128.999608 -270.40919)
		(end 129.18186 -270.35887)
		(width 0.0889)
		(layer "In2.Cu")
		(net "M_I_CPU1_SB_CB<5>")
	)
	(arc
		(start 135.76173 -270.35887)
		(mid 136.044686 -270.282693)
		(end 136.327642 -270.35887)
		(width 0.0889)
		(layer "In2.Cu")
		(net "M_I_CPU1_SB_CB<5>")
	)
	(arc
		(start 130.687826 -270.35887)
		(mid 130.87477 -270.409125)
		(end 131.061714 -270.35887)
		(width 0.0889)
		(layer "In2.Cu")
		(net "M_I_CPU1_SB_CB<5>")
	)
	(arc
		(start 137.276078 -270.363696)
		(mid 137.459586 -270.40919)
		(end 137.641838 -270.35887)
		(width 0.0889)
		(layer "In2.Cu")
		(net "M_I_CPU1_SB_CB<5>")
	)
	(arc
		(start 136.327642 -270.35887)
		(mid 136.509893 -270.40922)
		(end 136.693402 -270.363696)
		(width 0.0889)
		(layer "In2.Cu")
		(net "M_I_CPU1_SB_CB<5>")
	)
	(arc
		(start 142.907766 -270.35887)
		(mid 143.09471 -270.409125)
		(end 143.281654 -270.35887)
		(width 0.0889)
		(layer "In2.Cu")
		(net "M_I_CPU1_SB_CB<5>")
	)
	(arc
		(start 140.087604 -270.35887)
		(mid 140.269855 -270.40922)
		(end 140.453364 -270.363696)
		(width 0.0889)
		(layer "In2.Cu")
		(net "M_I_CPU1_SB_CB<5>")
	)
	(arc
		(start 142.341854 -270.35887)
		(mid 142.62481 -270.282693)
		(end 142.907766 -270.35887)
		(width 0.0889)
		(layer "In2.Cu")
		(net "M_I_CPU1_SB_CB<5>")
	)
	(arc
		(start 143.281654 -270.35887)
		(mid 143.56461 -270.282693)
		(end 143.847566 -270.35887)
		(width 0.0889)
		(layer "In2.Cu")
		(net "M_I_CPU1_SB_CB<5>")
	)
	(arc
		(start 131.627626 -270.35887)
		(mid 131.809877 -270.40922)
		(end 131.993386 -270.363696)
		(width 0.0889)
		(layer "In2.Cu")
		(net "M_I_CPU1_SB_CB<5>")
	)
	(arc
		(start 137.641838 -270.35887)
		(mid 137.924794 -270.282693)
		(end 138.20775 -270.35887)
		(width 0.0889)
		(layer "In2.Cu")
		(net "M_I_CPU1_SB_CB<5>")
	)
	(arc
		(start 128.304798 -270.32712)
		(mid 128.560006 -270.283643)
		(end 128.807718 -270.35887)
		(width 0.0889)
		(layer "In2.Cu")
		(net "M_I_CPU1_SB_CB<5>")
	)
	(arc
		(start 140.461746 -270.35887)
		(mid 140.744702 -270.282693)
		(end 141.027658 -270.35887)
		(width 0.0889)
		(layer "In2.Cu")
		(net "M_I_CPU1_SB_CB<5>")
	)
	(arc
		(start 134.447788 -270.35887)
		(mid 134.634732 -270.409125)
		(end 134.821676 -270.35887)
		(width 0.0889)
		(layer "In2.Cu")
		(net "M_I_CPU1_SB_CB<5>")
	)
	(arc
		(start 129.18186 -270.35887)
		(mid 129.464816 -270.282693)
		(end 129.747772 -270.35887)
		(width 0.0889)
		(layer "In2.Cu")
		(net "M_I_CPU1_SB_CB<5>")
	)
	(arc
		(start 132.001768 -270.35887)
		(mid 132.284724 -270.282693)
		(end 132.56768 -270.35887)
		(width 0.0889)
		(layer "In2.Cu")
		(net "M_I_CPU1_SB_CB<5>")
	)
	(arc
		(start 129.756154 -270.363696)
		(mid 129.939662 -270.40919)
		(end 130.121914 -270.35887)
		(width 0.0889)
		(layer "In2.Cu")
		(net "M_I_CPU1_SB_CB<5>")
	)
	(arc
		(start 130.121914 -270.35887)
		(mid 130.40487 -270.282693)
		(end 130.687826 -270.35887)
		(width 0.0889)
		(layer "In2.Cu")
		(net "M_I_CPU1_SB_CB<5>")
	)
	(arc
		(start 132.56768 -270.35887)
		(mid 132.749931 -270.40922)
		(end 132.93344 -270.363696)
		(width 0.0889)
		(layer "In2.Cu")
		(net "M_I_CPU1_SB_CB<5>")
	)
	(arc
		(start 133.881876 -270.35887)
		(mid 134.164832 -270.282693)
		(end 134.447788 -270.35887)
		(width 0.0889)
		(layer "In2.Cu")
		(net "M_I_CPU1_SB_CB<5>")
	)
	(arc
		(start 144.795748 -270.364204)
		(mid 144.979256 -270.40976)
		(end 145.161508 -270.359378)
		(width 0.0889)
		(layer "In2.Cu")
		(net "M_I_CPU1_SB_CB<5>")
	)
	(arc
		(start 139.521692 -270.35887)
		(mid 139.804648 -270.282693)
		(end 140.087604 -270.35887)
		(width 0.0889)
		(layer "In2.Cu")
		(net "M_I_CPU1_SB_CB<5>")
	)
	(arc
		(start 145.19783 -270.338296)
		(mid 145.309297 -270.205651)
		(end 145.349214 -270.037052)
		(width 0.0889)
		(layer "In2.Cu")
		(net "M_I_CPU1_SB_CB<5>")
	)
	(arc
		(start 139.147804 -270.35887)
		(mid 139.334748 -270.409125)
		(end 139.521692 -270.35887)
		(width 0.0889)
		(layer "In2.Cu")
		(net "M_I_CPU1_SB_CB<5>")
	)
	(arc
		(start 134.821676 -270.35887)
		(mid 135.104632 -270.282693)
		(end 135.387588 -270.35887)
		(width 0.0889)
		(layer "In2.Cu")
		(net "M_I_CPU1_SB_CB<5>")
	)
	(arc
		(start 144.221708 -270.35887)
		(mid 144.495227 -270.282772)
		(end 144.77111 -270.349726)
		(width 0.0889)
		(layer "In2.Cu")
		(net "M_I_CPU1_SB_CB<5>")
	)
	(arc
		(start 136.701784 -270.35887)
		(mid 136.98474 -270.282693)
		(end 137.267696 -270.35887)
		(width 0.0889)
		(layer "In2.Cu")
		(net "M_I_CPU1_SB_CB<5>")
	)
	(arc
		(start 131.061714 -270.35887)
		(mid 131.34467 -270.282693)
		(end 131.627626 -270.35887)
		(width 0.0889)
		(layer "In2.Cu")
		(net "M_I_CPU1_SB_CB<5>")
	)
	(arc
		(start 143.847566 -270.35887)
		(mid 144.029817 -270.40922)
		(end 144.213326 -270.363696)
		(width 0.0889)
		(layer "In2.Cu")
		(net "M_I_CPU1_SB_CB<5>")
	)
	(arc
		(start 133.516116 -270.363696)
		(mid 133.699624 -270.40919)
		(end 133.881876 -270.35887)
		(width 0.0889)
		(layer "In2.Cu")
		(net "M_I_CPU1_SB_CB<5>")
	)
	(arc
		(start 132.941822 -270.35887)
		(mid 133.224778 -270.282693)
		(end 133.507734 -270.35887)
		(width 0.0889)
		(layer "In2.Cu")
		(net "M_I_CPU1_SB_CB<5>")
	)
	(arc
		(start 141.027658 -270.35887)
		(mid 141.209909 -270.40922)
		(end 141.393418 -270.363696)
		(width 0.0889)
		(layer "In2.Cu")
		(net "M_I_CPU1_SB_CB<5>")
	)
	(arc
		(start 141.976094 -270.363696)
		(mid 142.159602 -270.40919)
		(end 142.341854 -270.35887)
		(width 0.0889)
		(layer "In2.Cu")
		(net "M_I_CPU1_SB_CB<5>")
	)
	(arc
		(start 138.216132 -270.363696)
		(mid 138.39964 -270.40919)
		(end 138.581892 -270.35887)
		(width 0.0889)
		(layer "In2.Cu")
		(net "M_I_CPU1_SB_CB<5>")
	)
	(arc
		(start 145.349214 -270.037052)
		(mid 145.41283 -269.775669)
		(end 145.590006 -269.573248)
		(width 0.0889)
		(layer "In2.Cu")
		(net "M_I_CPU1_SB_CB<5>")
	)
	(arc
		(start 141.4018 -270.35887)
		(mid 141.684756 -270.282693)
		(end 141.967712 -270.35887)
		(width 0.0889)
		(layer "In2.Cu")
		(net "M_I_CPU1_SB_CB<5>")
	)
	(arc
		(start 135.387588 -270.35887)
		(mid 135.569839 -270.40922)
		(end 135.753348 -270.363696)
		(width 0.0889)
		(layer "In2.Cu")
		(net "M_I_CPU1_SB_CB<5>")
	)
	(segment
		(start 128.997964 -268.960346)
		(end 129.464816 -269.226284)
		(width 0.10668)
		(layer "F.Cu")
		(net "M_I_CPU1_SB_CB<4>")
	)
	(segment
		(start 140.557758 -269.548864)
		(end 140.56614 -269.55369)
		(width 0.0889)
		(layer "In2.Cu")
		(net "M_I_CPU1_SB_CB<4>")
	)
	(segment
		(start 131.157726 -269.548864)
		(end 131.166108 -269.55369)
		(width 0.0889)
		(layer "In2.Cu")
		(net "M_I_CPU1_SB_CB<4>")
	)
	(segment
		(start 129.464816 -269.226284)
		(end 129.61874 -269.491714)
		(width 0.0889)
		(layer "In2.Cu")
		(net "M_I_CPU1_SB_CB<4>")
	)
	(segment
		(start 181.69255 -272.610326)
		(end 181.920896 -272.610326)
		(width 0.14478)
		(layer "In2.Cu")
		(net "M_I_CPU1_SB_CB<4>")
	)
	(segment
		(start 180.818028 -272.610326)
		(end 180.979572 -272.448782)
		(width 0.14478)
		(layer "In2.Cu")
		(net "M_I_CPU1_SB_CB<4>")
	)
	(segment
		(start 134.343394 -269.55369)
		(end 134.351776 -269.548864)
		(width 0.0889)
		(layer "In2.Cu")
		(net "M_I_CPU1_SB_CB<4>")
	)
	(segment
		(start 129.61874 -269.491714)
		(end 129.714752 -269.517114)
		(width 0.0889)
		(layer "In2.Cu")
		(net "M_I_CPU1_SB_CB<4>")
	)
	(segment
		(start 181.141116 -271.710404)
		(end 181.369462 -271.710404)
		(width 0.14478)
		(layer "In2.Cu")
		(net "M_I_CPU1_SB_CB<4>")
	)
	(segment
		(start 181.920896 -272.610326)
		(end 182.08244 -272.448782)
		(width 0.14478)
		(layer "In2.Cu")
		(net "M_I_CPU1_SB_CB<4>")
	)
	(segment
		(start 132.09778 -269.548864)
		(end 132.106162 -269.55369)
		(width 0.0889)
		(layer "In2.Cu")
		(net "M_I_CPU1_SB_CB<4>")
	)
	(segment
		(start 130.583432 -269.55369)
		(end 130.591814 -269.548864)
		(width 0.0889)
		(layer "In2.Cu")
		(net "M_I_CPU1_SB_CB<4>")
	)
	(segment
		(start 163.771834 -271.710404)
		(end 180.266594 -271.710404)
		(width 0.14478)
		(layer "In2.Cu")
		(net "M_I_CPU1_SB_CB<4>")
	)
	(segment
		(start 180.428138 -272.448782)
		(end 180.589682 -272.610326)
		(width 0.14478)
		(layer "In2.Cu")
		(net "M_I_CPU1_SB_CB<4>")
	)
	(segment
		(start 135.857742 -269.548864)
		(end 135.866124 -269.55369)
		(width 0.0889)
		(layer "In2.Cu")
		(net "M_I_CPU1_SB_CB<4>")
	)
	(segment
		(start 181.369462 -271.710404)
		(end 181.531006 -271.871948)
		(width 0.14478)
		(layer "In2.Cu")
		(net "M_I_CPU1_SB_CB<4>")
	)
	(segment
		(start 146.051016 -268.211808)
		(end 146.9517 -267.311124)
		(width 0.0889)
		(layer "In2.Cu")
		(net "M_I_CPU1_SB_CB<4>")
	)
	(segment
		(start 144.691608 -269.548864)
		(end 144.691862 -269.548864)
		(width 0.0889)
		(layer "In2.Cu")
		(net "M_I_CPU1_SB_CB<4>")
	)
	(segment
		(start 157.554422 -267.311124)
		(end 163.255198 -271.539716)
		(width 0.14478)
		(layer "In2.Cu")
		(net "M_I_CPU1_SB_CB<4>")
	)
	(segment
		(start 183.19115 -271.710404)
		(end 183.616092 -272.135346)
		(width 0.14478)
		(layer "In2.Cu")
		(net "M_I_CPU1_SB_CB<4>")
	)
	(segment
		(start 180.428138 -271.871948)
		(end 180.428138 -272.448782)
		(width 0.14478)
		(layer "In2.Cu")
		(net "M_I_CPU1_SB_CB<4>")
	)
	(segment
		(start 182.243984 -271.710404)
		(end 183.19115 -271.710404)
		(width 0.14478)
		(layer "In2.Cu")
		(net "M_I_CPU1_SB_CB<4>")
	)
	(segment
		(start 180.266594 -271.710404)
		(end 180.428138 -271.871948)
		(width 0.14478)
		(layer "In2.Cu")
		(net "M_I_CPU1_SB_CB<4>")
	)
	(segment
		(start 145.161762 -268.738858)
		(end 146.051016 -268.211808)
		(width 0.0889)
		(layer "In2.Cu")
		(net "M_I_CPU1_SB_CB<4>")
	)
	(segment
		(start 181.531006 -271.871948)
		(end 181.531006 -272.448782)
		(width 0.14478)
		(layer "In2.Cu")
		(net "M_I_CPU1_SB_CB<4>")
	)
	(segment
		(start 180.979572 -271.871948)
		(end 181.141116 -271.710404)
		(width 0.14478)
		(layer "In2.Cu")
		(net "M_I_CPU1_SB_CB<4>")
	)
	(segment
		(start 139.617704 -269.548864)
		(end 139.626086 -269.55369)
		(width 0.0889)
		(layer "In2.Cu")
		(net "M_I_CPU1_SB_CB<4>")
	)
	(segment
		(start 181.531006 -272.448782)
		(end 181.69255 -272.610326)
		(width 0.14478)
		(layer "In2.Cu")
		(net "M_I_CPU1_SB_CB<4>")
	)
	(segment
		(start 147.708366 -267.311124)
		(end 157.554422 -267.311124)
		(width 0.14478)
		(layer "In2.Cu")
		(net "M_I_CPU1_SB_CB<4>")
	)
	(segment
		(start 139.04341 -269.55369)
		(end 139.051792 -269.548864)
		(width 0.0889)
		(layer "In2.Cu")
		(net "M_I_CPU1_SB_CB<4>")
	)
	(segment
		(start 163.255198 -271.539716)
		(end 163.771834 -271.710404)
		(width 0.14478)
		(layer "In2.Cu")
		(net "M_I_CPU1_SB_CB<4>")
	)
	(segment
		(start 145.122646 -268.761718)
		(end 145.161762 -268.738858)
		(width 0.0889)
		(layer "In2.Cu")
		(net "M_I_CPU1_SB_CB<4>")
	)
	(segment
		(start 182.08244 -271.871948)
		(end 182.243984 -271.710404)
		(width 0.14478)
		(layer "In2.Cu")
		(net "M_I_CPU1_SB_CB<4>")
	)
	(segment
		(start 138.103356 -269.55369)
		(end 138.111738 -269.548864)
		(width 0.0889)
		(layer "In2.Cu")
		(net "M_I_CPU1_SB_CB<4>")
	)
	(segment
		(start 180.979572 -272.448782)
		(end 180.979572 -271.871948)
		(width 0.14478)
		(layer "In2.Cu")
		(net "M_I_CPU1_SB_CB<4>")
	)
	(segment
		(start 144.691862 -269.548864)
		(end 144.722342 -269.531084)
		(width 0.0889)
		(layer "In2.Cu")
		(net "M_I_CPU1_SB_CB<4>")
	)
	(segment
		(start 134.917688 -269.548864)
		(end 134.92607 -269.55369)
		(width 0.0889)
		(layer "In2.Cu")
		(net "M_I_CPU1_SB_CB<4>")
	)
	(segment
		(start 143.377666 -269.548864)
		(end 143.386048 -269.55369)
		(width 0.0889)
		(layer "In2.Cu")
		(net "M_I_CPU1_SB_CB<4>")
	)
	(segment
		(start 180.589682 -272.610326)
		(end 180.818028 -272.610326)
		(width 0.14478)
		(layer "In2.Cu")
		(net "M_I_CPU1_SB_CB<4>")
	)
	(segment
		(start 182.08244 -272.448782)
		(end 182.08244 -271.871948)
		(width 0.14478)
		(layer "In2.Cu")
		(net "M_I_CPU1_SB_CB<4>")
	)
	(segment
		(start 142.803372 -269.55369)
		(end 142.811754 -269.548864)
		(width 0.0889)
		(layer "In2.Cu")
		(net "M_I_CPU1_SB_CB<4>")
	)
	(segment
		(start 146.9517 -267.311124)
		(end 147.708366 -267.311124)
		(width 0.0889)
		(layer "In2.Cu")
		(net "M_I_CPU1_SB_CB<4>")
	)
	(arc
		(start 132.471922 -269.548864)
		(mid 132.754878 -269.472687)
		(end 133.037834 -269.548864)
		(width 0.0889)
		(layer "In2.Cu")
		(net "M_I_CPU1_SB_CB<4>")
	)
	(arc
		(start 137.737596 -269.548864)
		(mid 137.919847 -269.599214)
		(end 138.103356 -269.55369)
		(width 0.0889)
		(layer "In2.Cu")
		(net "M_I_CPU1_SB_CB<4>")
	)
	(arc
		(start 135.29183 -269.548864)
		(mid 135.574786 -269.472687)
		(end 135.857742 -269.548864)
		(width 0.0889)
		(layer "In2.Cu")
		(net "M_I_CPU1_SB_CB<4>")
	)
	(arc
		(start 138.67765 -269.548864)
		(mid 138.859901 -269.599214)
		(end 139.04341 -269.55369)
		(width 0.0889)
		(layer "In2.Cu")
		(net "M_I_CPU1_SB_CB<4>")
	)
	(arc
		(start 141.8717 -269.548864)
		(mid 142.154656 -269.472687)
		(end 142.437612 -269.548864)
		(width 0.0889)
		(layer "In2.Cu")
		(net "M_I_CPU1_SB_CB<4>")
	)
	(arc
		(start 142.811754 -269.548864)
		(mid 143.09471 -269.472687)
		(end 143.377666 -269.548864)
		(width 0.0889)
		(layer "In2.Cu")
		(net "M_I_CPU1_SB_CB<4>")
	)
	(arc
		(start 144.879314 -269.226284)
		(mid 144.943829 -268.964065)
		(end 145.122646 -268.761718)
		(width 0.0889)
		(layer "In2.Cu")
		(net "M_I_CPU1_SB_CB<4>")
	)
	(arc
		(start 135.866124 -269.55369)
		(mid 136.049632 -269.599184)
		(end 136.231884 -269.548864)
		(width 0.0889)
		(layer "In2.Cu")
		(net "M_I_CPU1_SB_CB<4>")
	)
	(arc
		(start 139.626086 -269.55369)
		(mid 139.809594 -269.599184)
		(end 139.991846 -269.548864)
		(width 0.0889)
		(layer "In2.Cu")
		(net "M_I_CPU1_SB_CB<4>")
	)
	(arc
		(start 136.797796 -269.548864)
		(mid 136.98474 -269.599119)
		(end 137.171684 -269.548864)
		(width 0.0889)
		(layer "In2.Cu")
		(net "M_I_CPU1_SB_CB<4>")
	)
	(arc
		(start 144.31772 -269.548864)
		(mid 144.504664 -269.599119)
		(end 144.691608 -269.548864)
		(width 0.0889)
		(layer "In2.Cu")
		(net "M_I_CPU1_SB_CB<4>")
	)
	(arc
		(start 138.111738 -269.548864)
		(mid 138.394694 -269.472687)
		(end 138.67765 -269.548864)
		(width 0.0889)
		(layer "In2.Cu")
		(net "M_I_CPU1_SB_CB<4>")
	)
	(arc
		(start 131.166108 -269.55369)
		(mid 131.349616 -269.599184)
		(end 131.531868 -269.548864)
		(width 0.0889)
		(layer "In2.Cu")
		(net "M_I_CPU1_SB_CB<4>")
	)
	(arc
		(start 136.231884 -269.548864)
		(mid 136.51484 -269.472687)
		(end 136.797796 -269.548864)
		(width 0.0889)
		(layer "In2.Cu")
		(net "M_I_CPU1_SB_CB<4>")
	)
	(arc
		(start 139.991846 -269.548864)
		(mid 140.274802 -269.472687)
		(end 140.557758 -269.548864)
		(width 0.0889)
		(layer "In2.Cu")
		(net "M_I_CPU1_SB_CB<4>")
	)
	(arc
		(start 142.437612 -269.548864)
		(mid 142.619863 -269.599214)
		(end 142.803372 -269.55369)
		(width 0.0889)
		(layer "In2.Cu")
		(net "M_I_CPU1_SB_CB<4>")
	)
	(arc
		(start 141.497812 -269.548864)
		(mid 141.684756 -269.599119)
		(end 141.8717 -269.548864)
		(width 0.0889)
		(layer "In2.Cu")
		(net "M_I_CPU1_SB_CB<4>")
	)
	(arc
		(start 144.722342 -269.531084)
		(mid 144.837769 -269.397708)
		(end 144.879314 -269.226284)
		(width 0.0889)
		(layer "In2.Cu")
		(net "M_I_CPU1_SB_CB<4>")
	)
	(arc
		(start 133.037834 -269.548864)
		(mid 133.224778 -269.599119)
		(end 133.411722 -269.548864)
		(width 0.0889)
		(layer "In2.Cu")
		(net "M_I_CPU1_SB_CB<4>")
	)
	(arc
		(start 130.591814 -269.548864)
		(mid 130.87477 -269.472687)
		(end 131.157726 -269.548864)
		(width 0.0889)
		(layer "In2.Cu")
		(net "M_I_CPU1_SB_CB<4>")
	)
	(arc
		(start 143.386048 -269.55369)
		(mid 143.569556 -269.599184)
		(end 143.751808 -269.548864)
		(width 0.0889)
		(layer "In2.Cu")
		(net "M_I_CPU1_SB_CB<4>")
	)
	(arc
		(start 132.106162 -269.55369)
		(mid 132.28967 -269.599184)
		(end 132.471922 -269.548864)
		(width 0.0889)
		(layer "In2.Cu")
		(net "M_I_CPU1_SB_CB<4>")
	)
	(arc
		(start 143.751808 -269.548864)
		(mid 144.034764 -269.472687)
		(end 144.31772 -269.548864)
		(width 0.0889)
		(layer "In2.Cu")
		(net "M_I_CPU1_SB_CB<4>")
	)
	(arc
		(start 133.977634 -269.548864)
		(mid 134.159885 -269.599214)
		(end 134.343394 -269.55369)
		(width 0.0889)
		(layer "In2.Cu")
		(net "M_I_CPU1_SB_CB<4>")
	)
	(arc
		(start 129.714752 -269.517114)
		(mid 129.96996 -269.473637)
		(end 130.217672 -269.548864)
		(width 0.0889)
		(layer "In2.Cu")
		(net "M_I_CPU1_SB_CB<4>")
	)
	(arc
		(start 139.051792 -269.548864)
		(mid 139.334748 -269.472687)
		(end 139.617704 -269.548864)
		(width 0.0889)
		(layer "In2.Cu")
		(net "M_I_CPU1_SB_CB<4>")
	)
	(arc
		(start 131.531868 -269.548864)
		(mid 131.814824 -269.472687)
		(end 132.09778 -269.548864)
		(width 0.0889)
		(layer "In2.Cu")
		(net "M_I_CPU1_SB_CB<4>")
	)
	(arc
		(start 134.92607 -269.55369)
		(mid 135.109578 -269.599184)
		(end 135.29183 -269.548864)
		(width 0.0889)
		(layer "In2.Cu")
		(net "M_I_CPU1_SB_CB<4>")
	)
	(arc
		(start 133.411722 -269.548864)
		(mid 133.694678 -269.472687)
		(end 133.977634 -269.548864)
		(width 0.0889)
		(layer "In2.Cu")
		(net "M_I_CPU1_SB_CB<4>")
	)
	(arc
		(start 130.217672 -269.548864)
		(mid 130.399923 -269.599214)
		(end 130.583432 -269.55369)
		(width 0.0889)
		(layer "In2.Cu")
		(net "M_I_CPU1_SB_CB<4>")
	)
	(arc
		(start 140.9319 -269.548864)
		(mid 141.214856 -269.472687)
		(end 141.497812 -269.548864)
		(width 0.0889)
		(layer "In2.Cu")
		(net "M_I_CPU1_SB_CB<4>")
	)
	(arc
		(start 137.171684 -269.548864)
		(mid 137.45464 -269.472687)
		(end 137.737596 -269.548864)
		(width 0.0889)
		(layer "In2.Cu")
		(net "M_I_CPU1_SB_CB<4>")
	)
	(arc
		(start 140.56614 -269.55369)
		(mid 140.749648 -269.599184)
		(end 140.9319 -269.548864)
		(width 0.0889)
		(layer "In2.Cu")
		(net "M_I_CPU1_SB_CB<4>")
	)
	(arc
		(start 134.351776 -269.548864)
		(mid 134.634732 -269.472687)
		(end 134.917688 -269.548864)
		(width 0.0889)
		(layer "In2.Cu")
		(net "M_I_CPU1_SB_CB<4>")
	)
	(segment
		(start 128.05791 -273.820382)
		(end 128.524762 -274.08632)
		(width 0.10668)
		(layer "F.Cu")
		(net "M_I_CPU1_SB_CB<3>")
	)
	(segment
		(start 132.09778 -273.76374)
		(end 132.106162 -273.758914)
		(width 0.0889)
		(layer "In2.Cu")
		(net "M_I_CPU1_SB_CB<3>")
	)
	(segment
		(start 159.486346 -277.396702)
		(end 163.150042 -281.060398)
		(width 0.14478)
		(layer "In2.Cu")
		(net "M_I_CPU1_SB_CB<3>")
	)
	(segment
		(start 142.803372 -273.758914)
		(end 142.811754 -273.76374)
		(width 0.0889)
		(layer "In2.Cu")
		(net "M_I_CPU1_SB_CB<3>")
	)
	(segment
		(start 170.51401 -280.764996)
		(end 170.88231 -280.917396)
		(width 0.14478)
		(layer "In2.Cu")
		(net "M_I_CPU1_SB_CB<3>")
	)
	(segment
		(start 166.033958 -280.46934)
		(end 166.114984 -280.274014)
		(width 0.14478)
		(layer "In2.Cu")
		(net "M_I_CPU1_SB_CB<3>")
	)
	(segment
		(start 166.55034 -280.255726)
		(end 166.59733 -280.36901)
		(width 0.14478)
		(layer "In2.Cu")
		(net "M_I_CPU1_SB_CB<3>")
	)
	(segment
		(start 158.846774 -277.579074)
		(end 159.075374 -277.579074)
		(width 0.14478)
		(layer "In2.Cu")
		(net "M_I_CPU1_SB_CB<3>")
	)
	(segment
		(start 158.867602 -276.777958)
		(end 158.867602 -277.006558)
		(width 0.14478)
		(layer "In2.Cu")
		(net "M_I_CPU1_SB_CB<3>")
	)
	(segment
		(start 178.717956 -279.823164)
		(end 178.941222 -279.823164)
		(width 0.14478)
		(layer "In2.Cu")
		(net "M_I_CPU1_SB_CB<3>")
	)
	(segment
		(start 170.88231 -280.917396)
		(end 171.025312 -281.060398)
		(width 0.14478)
		(layer "In2.Cu")
		(net "M_I_CPU1_SB_CB<3>")
	)
	(segment
		(start 134.343394 -273.758914)
		(end 134.351776 -273.76374)
		(width 0.0889)
		(layer "In2.Cu")
		(net "M_I_CPU1_SB_CB<3>")
	)
	(segment
		(start 166.114984 -280.274014)
		(end 166.355014 -280.174446)
		(width 0.14478)
		(layer "In2.Cu")
		(net "M_I_CPU1_SB_CB<3>")
	)
	(segment
		(start 131.157726 -273.76374)
		(end 131.166108 -273.758914)
		(width 0.0889)
		(layer "In2.Cu")
		(net "M_I_CPU1_SB_CB<3>")
	)
	(segment
		(start 147.352258 -272.383504)
		(end 148.06676 -272.383504)
		(width 0.0889)
		(layer "In2.Cu")
		(net "M_I_CPU1_SB_CB<3>")
	)
	(segment
		(start 167.372284 -280.21026)
		(end 169.17416 -280.21026)
		(width 0.14478)
		(layer "In2.Cu")
		(net "M_I_CPU1_SB_CB<3>")
	)
	(segment
		(start 145.444718 -273.719798)
		(end 145.961354 -273.505676)
		(width 0.0889)
		(layer "In2.Cu")
		(net "M_I_CPU1_SB_CB<3>")
	)
	(segment
		(start 166.793164 -280.45029)
		(end 167.372284 -280.21026)
		(width 0.14478)
		(layer "In2.Cu")
		(net "M_I_CPU1_SB_CB<3>")
	)
	(segment
		(start 159.075374 -277.579074)
		(end 159.257746 -277.396702)
		(width 0.14478)
		(layer "In2.Cu")
		(net "M_I_CPU1_SB_CB<3>")
	)
	(segment
		(start 172.750988 -281.060398)
		(end 173.008544 -280.982166)
		(width 0.14478)
		(layer "In2.Cu")
		(net "M_I_CPU1_SB_CB<3>")
	)
	(segment
		(start 144.688306 -273.76374)
		(end 144.71777 -273.781012)
		(width 0.0889)
		(layer "In2.Cu")
		(net "M_I_CPU1_SB_CB<3>")
	)
	(segment
		(start 163.150042 -281.060398)
		(end 165.31971 -281.060398)
		(width 0.14478)
		(layer "In2.Cu")
		(net "M_I_CPU1_SB_CB<3>")
	)
	(segment
		(start 158.477458 -276.616414)
		(end 158.706058 -276.616414)
		(width 0.14478)
		(layer "In2.Cu")
		(net "M_I_CPU1_SB_CB<3>")
	)
	(segment
		(start 144.289526 -273.77898)
		(end 144.315688 -273.763994)
		(width 0.0889)
		(layer "In2.Cu")
		(net "M_I_CPU1_SB_CB<3>")
	)
	(segment
		(start 147.243038 -272.492724)
		(end 147.352258 -272.383504)
		(width 0.0889)
		(layer "In2.Cu")
		(net "M_I_CPU1_SB_CB<3>")
	)
	(segment
		(start 148.06676 -272.383504)
		(end 153.651204 -272.383504)
		(width 0.14478)
		(layer "In2.Cu")
		(net "M_I_CPU1_SB_CB<3>")
	)
	(segment
		(start 173.227238 -280.217118)
		(end 174.823882 -279.90038)
		(width 0.14478)
		(layer "In2.Cu")
		(net "M_I_CPU1_SB_CB<3>")
	)
	(segment
		(start 135.857742 -273.76374)
		(end 135.866124 -273.758914)
		(width 0.0889)
		(layer "In2.Cu")
		(net "M_I_CPU1_SB_CB<3>")
	)
	(segment
		(start 140.557758 -273.76374)
		(end 140.56614 -273.758914)
		(width 0.0889)
		(layer "In2.Cu")
		(net "M_I_CPU1_SB_CB<3>")
	)
	(segment
		(start 165.999922 -280.778458)
		(end 166.081202 -280.582878)
		(width 0.14478)
		(layer "In2.Cu")
		(net "M_I_CPU1_SB_CB<3>")
	)
	(segment
		(start 179.091082 -279.973024)
		(end 179.091082 -280.21026)
		(width 0.14478)
		(layer "In2.Cu")
		(net "M_I_CPU1_SB_CB<3>")
	)
	(segment
		(start 177.447956 -279.913588)
		(end 177.931572 -280.397204)
		(width 0.14478)
		(layer "In2.Cu")
		(net "M_I_CPU1_SB_CB<3>")
	)
	(segment
		(start 128.524762 -274.08632)
		(end 128.370838 -273.82089)
		(width 0.0889)
		(layer "In2.Cu")
		(net "M_I_CPU1_SB_CB<3>")
	)
	(segment
		(start 178.143916 -280.397204)
		(end 178.717956 -279.823164)
		(width 0.14478)
		(layer "In2.Cu")
		(net "M_I_CPU1_SB_CB<3>")
	)
	(segment
		(start 169.916602 -280.355548)
		(end 169.991786 -280.174446)
		(width 0.14478)
		(layer "In2.Cu")
		(net "M_I_CPU1_SB_CB<3>")
	)
	(segment
		(start 146.974306 -272.492724)
		(end 147.243038 -272.492724)
		(width 0.0889)
		(layer "In2.Cu")
		(net "M_I_CPU1_SB_CB<3>")
	)
	(segment
		(start 170.427142 -280.19248)
		(end 170.508422 -280.388314)
		(width 0.14478)
		(layer "In2.Cu")
		(net "M_I_CPU1_SB_CB<3>")
	)
	(segment
		(start 158.68523 -277.18893)
		(end 158.68523 -277.41753)
		(width 0.14478)
		(layer "In2.Cu")
		(net "M_I_CPU1_SB_CB<3>")
	)
	(segment
		(start 144.315688 -273.763994)
		(end 144.337532 -273.751548)
		(width 0.0889)
		(layer "In2.Cu")
		(net "M_I_CPU1_SB_CB<3>")
	)
	(segment
		(start 158.295086 -276.798786)
		(end 158.477458 -276.616414)
		(width 0.14478)
		(layer "In2.Cu")
		(net "M_I_CPU1_SB_CB<3>")
	)
	(segment
		(start 169.721022 -280.436828)
		(end 169.916602 -280.355548)
		(width 0.14478)
		(layer "In2.Cu")
		(net "M_I_CPU1_SB_CB<3>")
	)
	(segment
		(start 158.68523 -277.41753)
		(end 158.846774 -277.579074)
		(width 0.14478)
		(layer "In2.Cu")
		(net "M_I_CPU1_SB_CB<3>")
	)
	(segment
		(start 158.066486 -276.798786)
		(end 158.295086 -276.798786)
		(width 0.14478)
		(layer "In2.Cu")
		(net "M_I_CPU1_SB_CB<3>")
	)
	(segment
		(start 128.370838 -273.82089)
		(end 128.39319 -273.737578)
		(width 0.0889)
		(layer "In2.Cu")
		(net "M_I_CPU1_SB_CB<3>")
	)
	(segment
		(start 134.917688 -273.76374)
		(end 134.92607 -273.758914)
		(width 0.0889)
		(layer "In2.Cu")
		(net "M_I_CPU1_SB_CB<3>")
	)
	(segment
		(start 173.117764 -280.800302)
		(end 173.05401 -280.475944)
		(width 0.14478)
		(layer "In2.Cu")
		(net "M_I_CPU1_SB_CB<3>")
	)
	(segment
		(start 139.04341 -273.758914)
		(end 139.051792 -273.76374)
		(width 0.0889)
		(layer "In2.Cu")
		(net "M_I_CPU1_SB_CB<3>")
	)
	(segment
		(start 173.008544 -280.982166)
		(end 173.117764 -280.800302)
		(width 0.14478)
		(layer "In2.Cu")
		(net "M_I_CPU1_SB_CB<3>")
	)
	(segment
		(start 158.706058 -276.616414)
		(end 158.867602 -276.777958)
		(width 0.14478)
		(layer "In2.Cu")
		(net "M_I_CPU1_SB_CB<3>")
	)
	(segment
		(start 170.508422 -280.388314)
		(end 170.433238 -280.56967)
		(width 0.14478)
		(layer "In2.Cu")
		(net "M_I_CPU1_SB_CB<3>")
	)
	(segment
		(start 145.961354 -273.505676)
		(end 146.974306 -272.492724)
		(width 0.0889)
		(layer "In2.Cu")
		(net "M_I_CPU1_SB_CB<3>")
	)
	(segment
		(start 138.103356 -273.758914)
		(end 138.111738 -273.76374)
		(width 0.0889)
		(layer "In2.Cu")
		(net "M_I_CPU1_SB_CB<3>")
	)
	(segment
		(start 159.257746 -277.396702)
		(end 159.486346 -277.396702)
		(width 0.14478)
		(layer "In2.Cu")
		(net "M_I_CPU1_SB_CB<3>")
	)
	(segment
		(start 158.867602 -277.006558)
		(end 158.68523 -277.18893)
		(width 0.14478)
		(layer "In2.Cu")
		(net "M_I_CPU1_SB_CB<3>")
	)
	(segment
		(start 179.091082 -280.21026)
		(end 179.516024 -280.635202)
		(width 0.14478)
		(layer "In2.Cu")
		(net "M_I_CPU1_SB_CB<3>")
	)
	(segment
		(start 177.235612 -279.913588)
		(end 177.447956 -279.913588)
		(width 0.14478)
		(layer "In2.Cu")
		(net "M_I_CPU1_SB_CB<3>")
	)
	(segment
		(start 166.355014 -280.174446)
		(end 166.55034 -280.255726)
		(width 0.14478)
		(layer "In2.Cu")
		(net "M_I_CPU1_SB_CB<3>")
	)
	(segment
		(start 173.05401 -280.475944)
		(end 173.227238 -280.217118)
		(width 0.14478)
		(layer "In2.Cu")
		(net "M_I_CPU1_SB_CB<3>")
	)
	(segment
		(start 130.583432 -273.758914)
		(end 130.591814 -273.76374)
		(width 0.0889)
		(layer "In2.Cu")
		(net "M_I_CPU1_SB_CB<3>")
	)
	(segment
		(start 153.651204 -272.383504)
		(end 158.066486 -276.798786)
		(width 0.14478)
		(layer "In2.Cu")
		(net "M_I_CPU1_SB_CB<3>")
	)
	(segment
		(start 169.17416 -280.21026)
		(end 169.721022 -280.436828)
		(width 0.14478)
		(layer "In2.Cu")
		(net "M_I_CPU1_SB_CB<3>")
	)
	(segment
		(start 165.31971 -281.060398)
		(end 165.999922 -280.778458)
		(width 0.14478)
		(layer "In2.Cu")
		(net "M_I_CPU1_SB_CB<3>")
	)
	(segment
		(start 143.377666 -273.76374)
		(end 143.386048 -273.758914)
		(width 0.0889)
		(layer "In2.Cu")
		(net "M_I_CPU1_SB_CB<3>")
	)
	(segment
		(start 166.59733 -280.36901)
		(end 166.793164 -280.45029)
		(width 0.14478)
		(layer "In2.Cu")
		(net "M_I_CPU1_SB_CB<3>")
	)
	(segment
		(start 178.941222 -279.823164)
		(end 179.091082 -279.973024)
		(width 0.14478)
		(layer "In2.Cu")
		(net "M_I_CPU1_SB_CB<3>")
	)
	(segment
		(start 174.823882 -279.90038)
		(end 175.287432 -280.21026)
		(width 0.14478)
		(layer "In2.Cu")
		(net "M_I_CPU1_SB_CB<3>")
	)
	(segment
		(start 139.617704 -273.76374)
		(end 139.626086 -273.758914)
		(width 0.0889)
		(layer "In2.Cu")
		(net "M_I_CPU1_SB_CB<3>")
	)
	(segment
		(start 175.287432 -280.21026)
		(end 176.93894 -280.21026)
		(width 0.14478)
		(layer "In2.Cu")
		(net "M_I_CPU1_SB_CB<3>")
	)
	(segment
		(start 177.931572 -280.397204)
		(end 178.143916 -280.397204)
		(width 0.14478)
		(layer "In2.Cu")
		(net "M_I_CPU1_SB_CB<3>")
	)
	(segment
		(start 170.433238 -280.56967)
		(end 170.51401 -280.764996)
		(width 0.14478)
		(layer "In2.Cu")
		(net "M_I_CPU1_SB_CB<3>")
	)
	(segment
		(start 129.643378 -273.758914)
		(end 129.65176 -273.76374)
		(width 0.0889)
		(layer "In2.Cu")
		(net "M_I_CPU1_SB_CB<3>")
	)
	(segment
		(start 170.18762 -280.093166)
		(end 170.427142 -280.19248)
		(width 0.14478)
		(layer "In2.Cu")
		(net "M_I_CPU1_SB_CB<3>")
	)
	(segment
		(start 176.93894 -280.21026)
		(end 177.235612 -279.913588)
		(width 0.14478)
		(layer "In2.Cu")
		(net "M_I_CPU1_SB_CB<3>")
	)
	(segment
		(start 166.081202 -280.582878)
		(end 166.033958 -280.46934)
		(width 0.14478)
		(layer "In2.Cu")
		(net "M_I_CPU1_SB_CB<3>")
	)
	(segment
		(start 169.991786 -280.174446)
		(end 170.18762 -280.093166)
		(width 0.14478)
		(layer "In2.Cu")
		(net "M_I_CPU1_SB_CB<3>")
	)
	(segment
		(start 145.373852 -273.719544)
		(end 145.444718 -273.719798)
		(width 0.0889)
		(layer "In2.Cu")
		(net "M_I_CPU1_SB_CB<3>")
	)
	(segment
		(start 171.025312 -281.060398)
		(end 172.750988 -281.060398)
		(width 0.14478)
		(layer "In2.Cu")
		(net "M_I_CPU1_SB_CB<3>")
	)
	(arc
		(start 134.92607 -273.758914)
		(mid 135.109578 -273.71342)
		(end 135.29183 -273.76374)
		(width 0.0889)
		(layer "In2.Cu")
		(net "M_I_CPU1_SB_CB<3>")
	)
	(arc
		(start 135.29183 -273.76374)
		(mid 135.574786 -273.839917)
		(end 135.857742 -273.76374)
		(width 0.0889)
		(layer "In2.Cu")
		(net "M_I_CPU1_SB_CB<3>")
	)
	(arc
		(start 134.351776 -273.76374)
		(mid 134.634732 -273.839917)
		(end 134.917688 -273.76374)
		(width 0.0889)
		(layer "In2.Cu")
		(net "M_I_CPU1_SB_CB<3>")
	)
	(arc
		(start 133.977634 -273.76374)
		(mid 134.159885 -273.71339)
		(end 134.343394 -273.758914)
		(width 0.0889)
		(layer "In2.Cu")
		(net "M_I_CPU1_SB_CB<3>")
	)
	(arc
		(start 142.437612 -273.76374)
		(mid 142.619863 -273.71339)
		(end 142.803372 -273.758914)
		(width 0.0889)
		(layer "In2.Cu")
		(net "M_I_CPU1_SB_CB<3>")
	)
	(arc
		(start 143.386048 -273.758914)
		(mid 143.569556 -273.71342)
		(end 143.751808 -273.76374)
		(width 0.0889)
		(layer "In2.Cu")
		(net "M_I_CPU1_SB_CB<3>")
	)
	(arc
		(start 131.531868 -273.76374)
		(mid 131.814824 -273.839917)
		(end 132.09778 -273.76374)
		(width 0.0889)
		(layer "In2.Cu")
		(net "M_I_CPU1_SB_CB<3>")
	)
	(arc
		(start 140.56614 -273.758914)
		(mid 140.749648 -273.71342)
		(end 140.9319 -273.76374)
		(width 0.0889)
		(layer "In2.Cu")
		(net "M_I_CPU1_SB_CB<3>")
	)
	(arc
		(start 128.39319 -273.737578)
		(mid 128.555379 -273.714843)
		(end 128.711706 -273.76374)
		(width 0.0889)
		(layer "In2.Cu")
		(net "M_I_CPU1_SB_CB<3>")
	)
	(arc
		(start 133.037834 -273.76374)
		(mid 133.224778 -273.713485)
		(end 133.411722 -273.76374)
		(width 0.0889)
		(layer "In2.Cu")
		(net "M_I_CPU1_SB_CB<3>")
	)
	(arc
		(start 133.411722 -273.76374)
		(mid 133.694678 -273.839917)
		(end 133.977634 -273.76374)
		(width 0.0889)
		(layer "In2.Cu")
		(net "M_I_CPU1_SB_CB<3>")
	)
	(arc
		(start 132.471922 -273.76374)
		(mid 132.754878 -273.839917)
		(end 133.037834 -273.76374)
		(width 0.0889)
		(layer "In2.Cu")
		(net "M_I_CPU1_SB_CB<3>")
	)
	(arc
		(start 139.991846 -273.76374)
		(mid 140.274802 -273.839917)
		(end 140.557758 -273.76374)
		(width 0.0889)
		(layer "In2.Cu")
		(net "M_I_CPU1_SB_CB<3>")
	)
	(arc
		(start 142.811754 -273.76374)
		(mid 143.09471 -273.839917)
		(end 143.377666 -273.76374)
		(width 0.0889)
		(layer "In2.Cu")
		(net "M_I_CPU1_SB_CB<3>")
	)
	(arc
		(start 141.497812 -273.76374)
		(mid 141.684756 -273.713485)
		(end 141.8717 -273.76374)
		(width 0.0889)
		(layer "In2.Cu")
		(net "M_I_CPU1_SB_CB<3>")
	)
	(arc
		(start 141.8717 -273.76374)
		(mid 142.154656 -273.839917)
		(end 142.437612 -273.76374)
		(width 0.0889)
		(layer "In2.Cu")
		(net "M_I_CPU1_SB_CB<3>")
	)
	(arc
		(start 130.217672 -273.76374)
		(mid 130.399923 -273.71339)
		(end 130.583432 -273.758914)
		(width 0.0889)
		(layer "In2.Cu")
		(net "M_I_CPU1_SB_CB<3>")
	)
	(arc
		(start 144.337532 -273.751548)
		(mid 144.51446 -273.71372)
		(end 144.688306 -273.76374)
		(width 0.0889)
		(layer "In2.Cu")
		(net "M_I_CPU1_SB_CB<3>")
	)
	(arc
		(start 138.111738 -273.76374)
		(mid 138.394694 -273.839917)
		(end 138.67765 -273.76374)
		(width 0.0889)
		(layer "In2.Cu")
		(net "M_I_CPU1_SB_CB<3>")
	)
	(arc
		(start 143.751808 -273.76374)
		(mid 144.018738 -273.839689)
		(end 144.289526 -273.77898)
		(width 0.0889)
		(layer "In2.Cu")
		(net "M_I_CPU1_SB_CB<3>")
	)
	(arc
		(start 137.737596 -273.76374)
		(mid 137.919847 -273.71339)
		(end 138.103356 -273.758914)
		(width 0.0889)
		(layer "In2.Cu")
		(net "M_I_CPU1_SB_CB<3>")
	)
	(arc
		(start 137.171684 -273.76374)
		(mid 137.45464 -273.839917)
		(end 137.737596 -273.76374)
		(width 0.0889)
		(layer "In2.Cu")
		(net "M_I_CPU1_SB_CB<3>")
	)
	(arc
		(start 139.626086 -273.758914)
		(mid 139.809594 -273.71342)
		(end 139.991846 -273.76374)
		(width 0.0889)
		(layer "In2.Cu")
		(net "M_I_CPU1_SB_CB<3>")
	)
	(arc
		(start 128.711706 -273.76374)
		(mid 128.994662 -273.839917)
		(end 129.277618 -273.76374)
		(width 0.0889)
		(layer "In2.Cu")
		(net "M_I_CPU1_SB_CB<3>")
	)
	(arc
		(start 140.9319 -273.76374)
		(mid 141.214856 -273.839917)
		(end 141.497812 -273.76374)
		(width 0.0889)
		(layer "In2.Cu")
		(net "M_I_CPU1_SB_CB<3>")
	)
	(arc
		(start 138.67765 -273.76374)
		(mid 138.859901 -273.71339)
		(end 139.04341 -273.758914)
		(width 0.0889)
		(layer "In2.Cu")
		(net "M_I_CPU1_SB_CB<3>")
	)
	(arc
		(start 130.591814 -273.76374)
		(mid 130.87477 -273.839917)
		(end 131.157726 -273.76374)
		(width 0.0889)
		(layer "In2.Cu")
		(net "M_I_CPU1_SB_CB<3>")
	)
	(arc
		(start 136.797796 -273.76374)
		(mid 136.98474 -273.713485)
		(end 137.171684 -273.76374)
		(width 0.0889)
		(layer "In2.Cu")
		(net "M_I_CPU1_SB_CB<3>")
	)
	(arc
		(start 131.166108 -273.758914)
		(mid 131.349616 -273.71342)
		(end 131.531868 -273.76374)
		(width 0.0889)
		(layer "In2.Cu")
		(net "M_I_CPU1_SB_CB<3>")
	)
	(arc
		(start 135.866124 -273.758914)
		(mid 136.049632 -273.71342)
		(end 136.231884 -273.76374)
		(width 0.0889)
		(layer "In2.Cu")
		(net "M_I_CPU1_SB_CB<3>")
	)
	(arc
		(start 144.71777 -273.781012)
		(mid 144.98919 -273.840689)
		(end 145.25625 -273.76374)
		(width 0.0889)
		(layer "In2.Cu")
		(net "M_I_CPU1_SB_CB<3>")
	)
	(arc
		(start 129.277618 -273.76374)
		(mid 129.459869 -273.71339)
		(end 129.643378 -273.758914)
		(width 0.0889)
		(layer "In2.Cu")
		(net "M_I_CPU1_SB_CB<3>")
	)
	(arc
		(start 139.051792 -273.76374)
		(mid 139.334748 -273.839917)
		(end 139.617704 -273.76374)
		(width 0.0889)
		(layer "In2.Cu")
		(net "M_I_CPU1_SB_CB<3>")
	)
	(arc
		(start 132.106162 -273.758914)
		(mid 132.28967 -273.71342)
		(end 132.471922 -273.76374)
		(width 0.0889)
		(layer "In2.Cu")
		(net "M_I_CPU1_SB_CB<3>")
	)
	(arc
		(start 136.231884 -273.76374)
		(mid 136.51484 -273.839917)
		(end 136.797796 -273.76374)
		(width 0.0889)
		(layer "In2.Cu")
		(net "M_I_CPU1_SB_CB<3>")
	)
	(arc
		(start 129.65176 -273.76374)
		(mid 129.934716 -273.839917)
		(end 130.217672 -273.76374)
		(width 0.0889)
		(layer "In2.Cu")
		(net "M_I_CPU1_SB_CB<3>")
	)
	(arc
		(start 145.25625 -273.76374)
		(mid 145.313174 -273.736643)
		(end 145.373852 -273.719544)
		(width 0.0889)
		(layer "In2.Cu")
		(net "M_I_CPU1_SB_CB<3>")
	)
	(segment
		(start 129.467864 -273.010376)
		(end 129.934716 -273.276314)
		(width 0.10668)
		(layer "F.Cu")
		(net "M_I_CPU1_SB_CB<2>")
	)
	(segment
		(start 167.456358 -278.510238)
		(end 169.708322 -278.510238)
		(width 0.14478)
		(layer "In2.Cu")
		(net "M_I_CPU1_SB_CB<2>")
	)
	(segment
		(start 158.094934 -275.32711)
		(end 158.094934 -275.555202)
		(width 0.14478)
		(layer "In2.Cu")
		(net "M_I_CPU1_SB_CB<2>")
	)
	(segment
		(start 155.916122 -273.37639)
		(end 156.144214 -273.37639)
		(width 0.14478)
		(layer "In2.Cu")
		(net "M_I_CPU1_SB_CB<2>")
	)
	(segment
		(start 138.20775 -272.953734)
		(end 138.216132 -272.948908)
		(width 0.0889)
		(layer "In2.Cu")
		(net "M_I_CPU1_SB_CB<2>")
	)
	(segment
		(start 145.16227 -272.953988)
		(end 145.178018 -272.963132)
		(width 0.0889)
		(layer "In2.Cu")
		(net "M_I_CPU1_SB_CB<2>")
	)
	(segment
		(start 141.967712 -272.953734)
		(end 141.976094 -272.948908)
		(width 0.0889)
		(layer "In2.Cu")
		(net "M_I_CPU1_SB_CB<2>")
	)
	(segment
		(start 136.693402 -272.948908)
		(end 136.701784 -272.953734)
		(width 0.0889)
		(layer "In2.Cu")
		(net "M_I_CPU1_SB_CB<2>")
	)
	(segment
		(start 157.70479 -274.936966)
		(end 157.926024 -274.715478)
		(width 0.14478)
		(layer "In2.Cu")
		(net "M_I_CPU1_SB_CB<2>")
	)
	(segment
		(start 155.975304 -272.536666)
		(end 155.975304 -272.764758)
		(width 0.14478)
		(layer "In2.Cu")
		(net "M_I_CPU1_SB_CB<2>")
	)
	(segment
		(start 147.009358 -271.756124)
		(end 147.194778 -271.756124)
		(width 0.0889)
		(layer "In2.Cu")
		(net "M_I_CPU1_SB_CB<2>")
	)
	(segment
		(start 156.59354 -273.154902)
		(end 156.755592 -273.316954)
		(width 0.14478)
		(layer "In2.Cu")
		(net "M_I_CPU1_SB_CB<2>")
	)
	(segment
		(start 145.44167 -273.030188)
		(end 145.635218 -273.030188)
		(width 0.0889)
		(layer "In2.Cu")
		(net "M_I_CPU1_SB_CB<2>")
	)
	(segment
		(start 129.934716 -273.276314)
		(end 129.780792 -273.010884)
		(width 0.0889)
		(layer "In2.Cu")
		(net "M_I_CPU1_SB_CB<2>")
	)
	(segment
		(start 135.753348 -272.948908)
		(end 135.76173 -272.953734)
		(width 0.0889)
		(layer "In2.Cu")
		(net "M_I_CPU1_SB_CB<2>")
	)
	(segment
		(start 155.975304 -272.764758)
		(end 155.75407 -272.986246)
		(width 0.14478)
		(layer "In2.Cu")
		(net "M_I_CPU1_SB_CB<2>")
	)
	(segment
		(start 155.75407 -273.214338)
		(end 155.916122 -273.37639)
		(width 0.14478)
		(layer "In2.Cu")
		(net "M_I_CPU1_SB_CB<2>")
	)
	(segment
		(start 169.708322 -278.510238)
		(end 170.093386 -278.895302)
		(width 0.14478)
		(layer "In2.Cu")
		(net "M_I_CPU1_SB_CB<2>")
	)
	(segment
		(start 156.534358 -273.766534)
		(end 156.534358 -273.994626)
		(width 0.14478)
		(layer "In2.Cu")
		(net "M_I_CPU1_SB_CB<2>")
	)
	(segment
		(start 156.69641 -274.156678)
		(end 156.924502 -274.156678)
		(width 0.14478)
		(layer "In2.Cu")
		(net "M_I_CPU1_SB_CB<2>")
	)
	(segment
		(start 170.093386 -278.895302)
		(end 171.21632 -279.360376)
		(width 0.14478)
		(layer "In2.Cu")
		(net "M_I_CPU1_SB_CB<2>")
	)
	(segment
		(start 158.485078 -275.717254)
		(end 158.706312 -275.495766)
		(width 0.14478)
		(layer "In2.Cu")
		(net "M_I_CPU1_SB_CB<2>")
	)
	(segment
		(start 177.415698 -278.238204)
		(end 177.702464 -278.238204)
		(width 0.14478)
		(layer "In2.Cu")
		(net "M_I_CPU1_SB_CB<2>")
	)
	(segment
		(start 178.533298 -278.238204)
		(end 178.818794 -278.238204)
		(width 0.14478)
		(layer "In2.Cu")
		(net "M_I_CPU1_SB_CB<2>")
	)
	(segment
		(start 158.154116 -274.715478)
		(end 158.316168 -274.87753)
		(width 0.14478)
		(layer "In2.Cu")
		(net "M_I_CPU1_SB_CB<2>")
	)
	(segment
		(start 158.316168 -274.87753)
		(end 158.316168 -275.105622)
		(width 0.14478)
		(layer "In2.Cu")
		(net "M_I_CPU1_SB_CB<2>")
	)
	(segment
		(start 145.934684 -272.830798)
		(end 147.009358 -271.756124)
		(width 0.0889)
		(layer "In2.Cu")
		(net "M_I_CPU1_SB_CB<2>")
	)
	(segment
		(start 133.507734 -272.953734)
		(end 133.516116 -272.948908)
		(width 0.0889)
		(layer "In2.Cu")
		(net "M_I_CPU1_SB_CB<2>")
	)
	(segment
		(start 155.75407 -272.986246)
		(end 155.75407 -273.214338)
		(width 0.14478)
		(layer "In2.Cu")
		(net "M_I_CPU1_SB_CB<2>")
	)
	(segment
		(start 177.974498 -278.510238)
		(end 178.261264 -278.510238)
		(width 0.14478)
		(layer "In2.Cu")
		(net "M_I_CPU1_SB_CB<2>")
	)
	(segment
		(start 171.21632 -279.360376)
		(end 172.911008 -279.360376)
		(width 0.14478)
		(layer "In2.Cu")
		(net "M_I_CPU1_SB_CB<2>")
	)
	(segment
		(start 177.702464 -278.238204)
		(end 177.974498 -278.510238)
		(width 0.14478)
		(layer "In2.Cu")
		(net "M_I_CPU1_SB_CB<2>")
	)
	(segment
		(start 144.213326 -272.948908)
		(end 144.221708 -272.953734)
		(width 0.0889)
		(layer "In2.Cu")
		(net "M_I_CPU1_SB_CB<2>")
	)
	(segment
		(start 174.963328 -278.510238)
		(end 177.143664 -278.510238)
		(width 0.14478)
		(layer "In2.Cu")
		(net "M_I_CPU1_SB_CB<2>")
	)
	(segment
		(start 157.145736 -273.93519)
		(end 157.373828 -273.93519)
		(width 0.14478)
		(layer "In2.Cu")
		(net "M_I_CPU1_SB_CB<2>")
	)
	(segment
		(start 178.818794 -278.238204)
		(end 179.516024 -278.935434)
		(width 0.14478)
		(layer "In2.Cu")
		(net "M_I_CPU1_SB_CB<2>")
	)
	(segment
		(start 140.453364 -272.948908)
		(end 140.461746 -272.953734)
		(width 0.0889)
		(layer "In2.Cu")
		(net "M_I_CPU1_SB_CB<2>")
	)
	(segment
		(start 157.53588 -274.097242)
		(end 157.53588 -274.325334)
		(width 0.14478)
		(layer "In2.Cu")
		(net "M_I_CPU1_SB_CB<2>")
	)
	(segment
		(start 177.143664 -278.510238)
		(end 177.415698 -278.238204)
		(width 0.14478)
		(layer "In2.Cu")
		(net "M_I_CPU1_SB_CB<2>")
	)
	(segment
		(start 158.316168 -275.105622)
		(end 158.094934 -275.32711)
		(width 0.14478)
		(layer "In2.Cu")
		(net "M_I_CPU1_SB_CB<2>")
	)
	(segment
		(start 145.143982 -272.943574)
		(end 145.16227 -272.953988)
		(width 0.0889)
		(layer "In2.Cu")
		(net "M_I_CPU1_SB_CB<2>")
	)
	(segment
		(start 178.261264 -278.510238)
		(end 178.533298 -278.238204)
		(width 0.14478)
		(layer "In2.Cu")
		(net "M_I_CPU1_SB_CB<2>")
	)
	(segment
		(start 156.365448 -273.154902)
		(end 156.59354 -273.154902)
		(width 0.14478)
		(layer "In2.Cu")
		(net "M_I_CPU1_SB_CB<2>")
	)
	(segment
		(start 157.53588 -274.325334)
		(end 157.314646 -274.546822)
		(width 0.14478)
		(layer "In2.Cu")
		(net "M_I_CPU1_SB_CB<2>")
	)
	(segment
		(start 156.924502 -274.156678)
		(end 157.145736 -273.93519)
		(width 0.14478)
		(layer "In2.Cu")
		(net "M_I_CPU1_SB_CB<2>")
	)
	(segment
		(start 131.993386 -272.948908)
		(end 132.001768 -272.953734)
		(width 0.0889)
		(layer "In2.Cu")
		(net "M_I_CPU1_SB_CB<2>")
	)
	(segment
		(start 172.911008 -279.360376)
		(end 174.963328 -278.510238)
		(width 0.14478)
		(layer "In2.Cu")
		(net "M_I_CPU1_SB_CB<2>")
	)
	(segment
		(start 145.735802 -272.99412)
		(end 145.934684 -272.830798)
		(width 0.0889)
		(layer "In2.Cu")
		(net "M_I_CPU1_SB_CB<2>")
	)
	(segment
		(start 147.194778 -271.756124)
		(end 147.476718 -271.474184)
		(width 0.0889)
		(layer "In2.Cu")
		(net "M_I_CPU1_SB_CB<2>")
	)
	(segment
		(start 155.135834 -272.596102)
		(end 155.363926 -272.596102)
		(width 0.14478)
		(layer "In2.Cu")
		(net "M_I_CPU1_SB_CB<2>")
	)
	(segment
		(start 157.926024 -274.715478)
		(end 158.154116 -274.715478)
		(width 0.14478)
		(layer "In2.Cu")
		(net "M_I_CPU1_SB_CB<2>")
	)
	(segment
		(start 154.912822 -271.474184)
		(end 155.195016 -271.756378)
		(width 0.14478)
		(layer "In2.Cu")
		(net "M_I_CPU1_SB_CB<2>")
	)
	(segment
		(start 132.93344 -272.948908)
		(end 132.941822 -272.953734)
		(width 0.0889)
		(layer "In2.Cu")
		(net "M_I_CPU1_SB_CB<2>")
	)
	(segment
		(start 147.476718 -271.474184)
		(end 148.06676 -271.474184)
		(width 0.0889)
		(layer "In2.Cu")
		(net "M_I_CPU1_SB_CB<2>")
	)
	(segment
		(start 145.635218 -273.030188)
		(end 145.735802 -272.99412)
		(width 0.0889)
		(layer "In2.Cu")
		(net "M_I_CPU1_SB_CB<2>")
	)
	(segment
		(start 156.534358 -273.994626)
		(end 156.69641 -274.156678)
		(width 0.14478)
		(layer "In2.Cu")
		(net "M_I_CPU1_SB_CB<2>")
	)
	(segment
		(start 148.06676 -271.474184)
		(end 154.912822 -271.474184)
		(width 0.14478)
		(layer "In2.Cu")
		(net "M_I_CPU1_SB_CB<2>")
	)
	(segment
		(start 129.780792 -273.010884)
		(end 129.803144 -272.927572)
		(width 0.0889)
		(layer "In2.Cu")
		(net "M_I_CPU1_SB_CB<2>")
	)
	(segment
		(start 155.58516 -272.374614)
		(end 155.813252 -272.374614)
		(width 0.14478)
		(layer "In2.Cu")
		(net "M_I_CPU1_SB_CB<2>")
	)
	(segment
		(start 137.267696 -272.953734)
		(end 137.276078 -272.948908)
		(width 0.0889)
		(layer "In2.Cu")
		(net "M_I_CPU1_SB_CB<2>")
	)
	(segment
		(start 157.314646 -274.546822)
		(end 157.314646 -274.774914)
		(width 0.14478)
		(layer "In2.Cu")
		(net "M_I_CPU1_SB_CB<2>")
	)
	(segment
		(start 156.755592 -273.316954)
		(end 156.755592 -273.545046)
		(width 0.14478)
		(layer "In2.Cu")
		(net "M_I_CPU1_SB_CB<2>")
	)
	(segment
		(start 158.094934 -275.555202)
		(end 158.256986 -275.717254)
		(width 0.14478)
		(layer "In2.Cu")
		(net "M_I_CPU1_SB_CB<2>")
	)
	(segment
		(start 157.373828 -273.93519)
		(end 157.53588 -274.097242)
		(width 0.14478)
		(layer "In2.Cu")
		(net "M_I_CPU1_SB_CB<2>")
	)
	(segment
		(start 154.973782 -272.43405)
		(end 155.135834 -272.596102)
		(width 0.14478)
		(layer "In2.Cu")
		(net "M_I_CPU1_SB_CB<2>")
	)
	(segment
		(start 157.476698 -274.936966)
		(end 157.70479 -274.936966)
		(width 0.14478)
		(layer "In2.Cu")
		(net "M_I_CPU1_SB_CB<2>")
	)
	(segment
		(start 157.314646 -274.774914)
		(end 157.476698 -274.936966)
		(width 0.14478)
		(layer "In2.Cu")
		(net "M_I_CPU1_SB_CB<2>")
	)
	(segment
		(start 155.363926 -272.596102)
		(end 155.58516 -272.374614)
		(width 0.14478)
		(layer "In2.Cu")
		(net "M_I_CPU1_SB_CB<2>")
	)
	(segment
		(start 155.195016 -271.756378)
		(end 155.195016 -271.98447)
		(width 0.14478)
		(layer "In2.Cu")
		(net "M_I_CPU1_SB_CB<2>")
	)
	(segment
		(start 156.144214 -273.37639)
		(end 156.365448 -273.154902)
		(width 0.14478)
		(layer "In2.Cu")
		(net "M_I_CPU1_SB_CB<2>")
	)
	(segment
		(start 158.706312 -275.495766)
		(end 158.934404 -275.495766)
		(width 0.14478)
		(layer "In2.Cu")
		(net "M_I_CPU1_SB_CB<2>")
	)
	(segment
		(start 141.393418 -272.948908)
		(end 141.4018 -272.953734)
		(width 0.0889)
		(layer "In2.Cu")
		(net "M_I_CPU1_SB_CB<2>")
	)
	(segment
		(start 165.40353 -279.360376)
		(end 167.456358 -278.510238)
		(width 0.14478)
		(layer "In2.Cu")
		(net "M_I_CPU1_SB_CB<2>")
	)
	(segment
		(start 162.799014 -279.360376)
		(end 165.40353 -279.360376)
		(width 0.14478)
		(layer "In2.Cu")
		(net "M_I_CPU1_SB_CB<2>")
	)
	(segment
		(start 155.195016 -271.98447)
		(end 154.973782 -272.205958)
		(width 0.14478)
		(layer "In2.Cu")
		(net "M_I_CPU1_SB_CB<2>")
	)
	(segment
		(start 158.934404 -275.495766)
		(end 162.799014 -279.360376)
		(width 0.14478)
		(layer "In2.Cu")
		(net "M_I_CPU1_SB_CB<2>")
	)
	(segment
		(start 155.813252 -272.374614)
		(end 155.975304 -272.536666)
		(width 0.14478)
		(layer "In2.Cu")
		(net "M_I_CPU1_SB_CB<2>")
	)
	(segment
		(start 156.755592 -273.545046)
		(end 156.534358 -273.766534)
		(width 0.14478)
		(layer "In2.Cu")
		(net "M_I_CPU1_SB_CB<2>")
	)
	(segment
		(start 154.973782 -272.205958)
		(end 154.973782 -272.43405)
		(width 0.14478)
		(layer "In2.Cu")
		(net "M_I_CPU1_SB_CB<2>")
	)
	(segment
		(start 158.256986 -275.717254)
		(end 158.485078 -275.717254)
		(width 0.14478)
		(layer "In2.Cu")
		(net "M_I_CPU1_SB_CB<2>")
	)
	(segment
		(start 144.221708 -272.953734)
		(end 144.23644 -272.96237)
		(width 0.0889)
		(layer "In2.Cu")
		(net "M_I_CPU1_SB_CB<2>")
	)
	(arc
		(start 129.803144 -272.927572)
		(mid 129.965476 -272.904754)
		(end 130.121914 -272.953734)
		(width 0.0889)
		(layer "In2.Cu")
		(net "M_I_CPU1_SB_CB<2>")
	)
	(arc
		(start 133.881876 -272.953734)
		(mid 134.164832 -273.029911)
		(end 134.447788 -272.953734)
		(width 0.0889)
		(layer "In2.Cu")
		(net "M_I_CPU1_SB_CB<2>")
	)
	(arc
		(start 140.461746 -272.953734)
		(mid 140.744702 -273.029911)
		(end 141.027658 -272.953734)
		(width 0.0889)
		(layer "In2.Cu")
		(net "M_I_CPU1_SB_CB<2>")
	)
	(arc
		(start 142.907766 -272.953734)
		(mid 143.09471 -272.903479)
		(end 143.281654 -272.953734)
		(width 0.0889)
		(layer "In2.Cu")
		(net "M_I_CPU1_SB_CB<2>")
	)
	(arc
		(start 140.087604 -272.953734)
		(mid 140.269855 -272.903384)
		(end 140.453364 -272.948908)
		(width 0.0889)
		(layer "In2.Cu")
		(net "M_I_CPU1_SB_CB<2>")
	)
	(arc
		(start 138.581892 -272.953734)
		(mid 138.864848 -273.029911)
		(end 139.147804 -272.953734)
		(width 0.0889)
		(layer "In2.Cu")
		(net "M_I_CPU1_SB_CB<2>")
	)
	(arc
		(start 131.061714 -272.953734)
		(mid 131.34467 -273.029911)
		(end 131.627626 -272.953734)
		(width 0.0889)
		(layer "In2.Cu")
		(net "M_I_CPU1_SB_CB<2>")
	)
	(arc
		(start 132.001768 -272.953734)
		(mid 132.284724 -273.029911)
		(end 132.56768 -272.953734)
		(width 0.0889)
		(layer "In2.Cu")
		(net "M_I_CPU1_SB_CB<2>")
	)
	(arc
		(start 135.387588 -272.953734)
		(mid 135.569839 -272.903384)
		(end 135.753348 -272.948908)
		(width 0.0889)
		(layer "In2.Cu")
		(net "M_I_CPU1_SB_CB<2>")
	)
	(arc
		(start 137.276078 -272.948908)
		(mid 137.459586 -272.903414)
		(end 137.641838 -272.953734)
		(width 0.0889)
		(layer "In2.Cu")
		(net "M_I_CPU1_SB_CB<2>")
	)
	(arc
		(start 141.976094 -272.948908)
		(mid 142.159602 -272.903414)
		(end 142.341854 -272.953734)
		(width 0.0889)
		(layer "In2.Cu")
		(net "M_I_CPU1_SB_CB<2>")
	)
	(arc
		(start 137.641838 -272.953734)
		(mid 137.924794 -273.029911)
		(end 138.20775 -272.953734)
		(width 0.0889)
		(layer "In2.Cu")
		(net "M_I_CPU1_SB_CB<2>")
	)
	(arc
		(start 133.516116 -272.948908)
		(mid 133.699624 -272.903414)
		(end 133.881876 -272.953734)
		(width 0.0889)
		(layer "In2.Cu")
		(net "M_I_CPU1_SB_CB<2>")
	)
	(arc
		(start 131.627626 -272.953734)
		(mid 131.809877 -272.903384)
		(end 131.993386 -272.948908)
		(width 0.0889)
		(layer "In2.Cu")
		(net "M_I_CPU1_SB_CB<2>")
	)
	(arc
		(start 134.447788 -272.953734)
		(mid 134.634732 -272.903479)
		(end 134.821676 -272.953734)
		(width 0.0889)
		(layer "In2.Cu")
		(net "M_I_CPU1_SB_CB<2>")
	)
	(arc
		(start 139.147804 -272.953734)
		(mid 139.334748 -272.903479)
		(end 139.521692 -272.953734)
		(width 0.0889)
		(layer "In2.Cu")
		(net "M_I_CPU1_SB_CB<2>")
	)
	(arc
		(start 136.701784 -272.953734)
		(mid 136.98474 -273.029911)
		(end 137.267696 -272.953734)
		(width 0.0889)
		(layer "In2.Cu")
		(net "M_I_CPU1_SB_CB<2>")
	)
	(arc
		(start 141.4018 -272.953734)
		(mid 141.684756 -273.029911)
		(end 141.967712 -272.953734)
		(width 0.0889)
		(layer "In2.Cu")
		(net "M_I_CPU1_SB_CB<2>")
	)
	(arc
		(start 143.281654 -272.953734)
		(mid 143.56461 -273.029911)
		(end 143.847566 -272.953734)
		(width 0.0889)
		(layer "In2.Cu")
		(net "M_I_CPU1_SB_CB<2>")
	)
	(arc
		(start 144.788128 -272.953734)
		(mid 144.964756 -272.903501)
		(end 145.143982 -272.943574)
		(width 0.0889)
		(layer "In2.Cu")
		(net "M_I_CPU1_SB_CB<2>")
	)
	(arc
		(start 144.23644 -272.96237)
		(mid 144.513423 -273.030174)
		(end 144.788128 -272.953734)
		(width 0.0889)
		(layer "In2.Cu")
		(net "M_I_CPU1_SB_CB<2>")
	)
	(arc
		(start 134.821676 -272.953734)
		(mid 135.104632 -273.029911)
		(end 135.387588 -272.953734)
		(width 0.0889)
		(layer "In2.Cu")
		(net "M_I_CPU1_SB_CB<2>")
	)
	(arc
		(start 142.341854 -272.953734)
		(mid 142.62481 -273.029911)
		(end 142.907766 -272.953734)
		(width 0.0889)
		(layer "In2.Cu")
		(net "M_I_CPU1_SB_CB<2>")
	)
	(arc
		(start 130.687826 -272.953734)
		(mid 130.87477 -272.903479)
		(end 131.061714 -272.953734)
		(width 0.0889)
		(layer "In2.Cu")
		(net "M_I_CPU1_SB_CB<2>")
	)
	(arc
		(start 136.327642 -272.953734)
		(mid 136.509893 -272.903384)
		(end 136.693402 -272.948908)
		(width 0.0889)
		(layer "In2.Cu")
		(net "M_I_CPU1_SB_CB<2>")
	)
	(arc
		(start 139.521692 -272.953734)
		(mid 139.804648 -273.029911)
		(end 140.087604 -272.953734)
		(width 0.0889)
		(layer "In2.Cu")
		(net "M_I_CPU1_SB_CB<2>")
	)
	(arc
		(start 141.027658 -272.953734)
		(mid 141.209909 -272.903384)
		(end 141.393418 -272.948908)
		(width 0.0889)
		(layer "In2.Cu")
		(net "M_I_CPU1_SB_CB<2>")
	)
	(arc
		(start 132.941822 -272.953734)
		(mid 133.224778 -273.029911)
		(end 133.507734 -272.953734)
		(width 0.0889)
		(layer "In2.Cu")
		(net "M_I_CPU1_SB_CB<2>")
	)
	(arc
		(start 138.216132 -272.948908)
		(mid 138.39964 -272.903414)
		(end 138.581892 -272.953734)
		(width 0.0889)
		(layer "In2.Cu")
		(net "M_I_CPU1_SB_CB<2>")
	)
	(arc
		(start 135.76173 -272.953734)
		(mid 136.044686 -273.029911)
		(end 136.327642 -272.953734)
		(width 0.0889)
		(layer "In2.Cu")
		(net "M_I_CPU1_SB_CB<2>")
	)
	(arc
		(start 145.178018 -272.963132)
		(mid 145.30574 -273.012795)
		(end 145.44167 -273.030188)
		(width 0.0889)
		(layer "In2.Cu")
		(net "M_I_CPU1_SB_CB<2>")
	)
	(arc
		(start 143.847566 -272.953734)
		(mid 144.029817 -272.903384)
		(end 144.213326 -272.948908)
		(width 0.0889)
		(layer "In2.Cu")
		(net "M_I_CPU1_SB_CB<2>")
	)
	(arc
		(start 132.56768 -272.953734)
		(mid 132.749931 -272.903384)
		(end 132.93344 -272.948908)
		(width 0.0889)
		(layer "In2.Cu")
		(net "M_I_CPU1_SB_CB<2>")
	)
	(arc
		(start 130.121914 -272.953734)
		(mid 130.40487 -273.029911)
		(end 130.687826 -272.953734)
		(width 0.0889)
		(layer "In2.Cu")
		(net "M_I_CPU1_SB_CB<2>")
	)
	(segment
		(start 127.58801 -273.010376)
		(end 128.054862 -273.276314)
		(width 0.10668)
		(layer "F.Cu")
		(net "M_I_CPU1_SB_CB<1>")
	)
	(segment
		(start 137.267696 -273.598894)
		(end 137.276078 -273.60372)
		(width 0.0889)
		(layer "In2.Cu")
		(net "M_I_CPU1_SB_CB<1>")
	)
	(segment
		(start 132.93344 -273.60372)
		(end 132.941822 -273.598894)
		(width 0.0889)
		(layer "In2.Cu")
		(net "M_I_CPU1_SB_CB<1>")
	)
	(segment
		(start 135.753348 -273.60372)
		(end 135.76173 -273.598894)
		(width 0.0889)
		(layer "In2.Cu")
		(net "M_I_CPU1_SB_CB<1>")
	)
	(segment
		(start 145.15973 -273.598894)
		(end 145.159984 -273.599148)
		(width 0.0889)
		(layer "In2.Cu")
		(net "M_I_CPU1_SB_CB<1>")
	)
	(segment
		(start 128.054862 -273.276314)
		(end 128.208786 -273.541744)
		(width 0.0889)
		(layer "In2.Cu")
		(net "M_I_CPU1_SB_CB<1>")
	)
	(segment
		(start 173.521878 -279.599898)
		(end 174.7266 -279.360376)
		(width 0.14478)
		(layer "In2.Cu")
		(net "M_I_CPU1_SB_CB<1>")
	)
	(segment
		(start 147.420838 -271.928844)
		(end 148.04898 -271.928844)
		(width 0.0889)
		(layer "In2.Cu")
		(net "M_I_CPU1_SB_CB<1>")
	)
	(segment
		(start 144.220438 -273.59864)
		(end 144.2466 -273.583654)
		(width 0.0889)
		(layer "In2.Cu")
		(net "M_I_CPU1_SB_CB<1>")
	)
	(segment
		(start 141.967712 -273.598894)
		(end 141.976094 -273.60372)
		(width 0.0889)
		(layer "In2.Cu")
		(net "M_I_CPU1_SB_CB<1>")
	)
	(segment
		(start 145.884138 -273.295364)
		(end 147.029678 -272.149824)
		(width 0.0889)
		(layer "In2.Cu")
		(net "M_I_CPU1_SB_CB<1>")
	)
	(segment
		(start 145.357342 -273.529044)
		(end 145.884138 -273.295364)
		(width 0.0889)
		(layer "In2.Cu")
		(net "M_I_CPU1_SB_CB<1>")
	)
	(segment
		(start 153.83256 -271.928844)
		(end 158.07055 -276.166834)
		(width 0.14478)
		(layer "In2.Cu")
		(net "M_I_CPU1_SB_CB<1>")
	)
	(segment
		(start 174.7266 -279.360376)
		(end 183.19115 -279.360376)
		(width 0.14478)
		(layer "In2.Cu")
		(net "M_I_CPU1_SB_CB<1>")
	)
	(segment
		(start 158.969202 -276.166834)
		(end 163.012628 -280.21026)
		(width 0.14478)
		(layer "In2.Cu")
		(net "M_I_CPU1_SB_CB<1>")
	)
	(segment
		(start 144.784318 -273.598894)
		(end 144.804892 -273.610832)
		(width 0.0889)
		(layer "In2.Cu")
		(net "M_I_CPU1_SB_CB<1>")
	)
	(segment
		(start 138.20775 -273.598894)
		(end 138.216132 -273.60372)
		(width 0.0889)
		(layer "In2.Cu")
		(net "M_I_CPU1_SB_CB<1>")
	)
	(segment
		(start 163.012628 -280.21026)
		(end 165.040818 -280.21026)
		(width 0.14478)
		(layer "In2.Cu")
		(net "M_I_CPU1_SB_CB<1>")
	)
	(segment
		(start 167.09263 -279.360376)
		(end 169.66438 -279.360376)
		(width 0.14478)
		(layer "In2.Cu")
		(net "M_I_CPU1_SB_CB<1>")
	)
	(segment
		(start 129.747772 -273.598894)
		(end 129.756154 -273.60372)
		(width 0.0889)
		(layer "In2.Cu")
		(net "M_I_CPU1_SB_CB<1>")
	)
	(segment
		(start 148.04898 -271.928844)
		(end 153.83256 -271.928844)
		(width 0.14478)
		(layer "In2.Cu")
		(net "M_I_CPU1_SB_CB<1>")
	)
	(segment
		(start 183.19115 -279.360376)
		(end 183.616092 -279.785318)
		(width 0.14478)
		(layer "In2.Cu")
		(net "M_I_CPU1_SB_CB<1>")
	)
	(segment
		(start 147.199858 -272.149824)
		(end 147.420838 -271.928844)
		(width 0.0889)
		(layer "In2.Cu")
		(net "M_I_CPU1_SB_CB<1>")
	)
	(segment
		(start 147.029678 -272.149824)
		(end 147.199858 -272.149824)
		(width 0.0889)
		(layer "In2.Cu")
		(net "M_I_CPU1_SB_CB<1>")
	)
	(segment
		(start 171.715938 -280.21026)
		(end 172.048678 -280.21026)
		(width 0.14478)
		(layer "In2.Cu")
		(net "M_I_CPU1_SB_CB<1>")
	)
	(segment
		(start 140.453364 -273.60372)
		(end 140.461746 -273.598894)
		(width 0.0889)
		(layer "In2.Cu")
		(net "M_I_CPU1_SB_CB<1>")
	)
	(segment
		(start 141.393418 -273.60372)
		(end 141.4018 -273.598894)
		(width 0.0889)
		(layer "In2.Cu")
		(net "M_I_CPU1_SB_CB<1>")
	)
	(segment
		(start 144.19707 -273.612102)
		(end 144.220438 -273.59864)
		(width 0.0889)
		(layer "In2.Cu")
		(net "M_I_CPU1_SB_CB<1>")
	)
	(segment
		(start 172.048678 -280.21026)
		(end 173.521878 -279.599898)
		(width 0.14478)
		(layer "In2.Cu")
		(net "M_I_CPU1_SB_CB<1>")
	)
	(segment
		(start 128.807718 -273.598894)
		(end 128.8161 -273.60372)
		(width 0.0889)
		(layer "In2.Cu")
		(net "M_I_CPU1_SB_CB<1>")
	)
	(segment
		(start 133.507734 -273.598894)
		(end 133.516116 -273.60372)
		(width 0.0889)
		(layer "In2.Cu")
		(net "M_I_CPU1_SB_CB<1>")
	)
	(segment
		(start 169.66438 -279.360376)
		(end 171.715938 -280.21026)
		(width 0.14478)
		(layer "In2.Cu")
		(net "M_I_CPU1_SB_CB<1>")
	)
	(segment
		(start 128.208786 -273.541744)
		(end 128.304798 -273.567144)
		(width 0.0889)
		(layer "In2.Cu")
		(net "M_I_CPU1_SB_CB<1>")
	)
	(segment
		(start 131.993386 -273.60372)
		(end 132.001768 -273.598894)
		(width 0.0889)
		(layer "In2.Cu")
		(net "M_I_CPU1_SB_CB<1>")
	)
	(segment
		(start 158.07055 -276.166834)
		(end 158.969202 -276.166834)
		(width 0.14478)
		(layer "In2.Cu")
		(net "M_I_CPU1_SB_CB<1>")
	)
	(segment
		(start 136.693402 -273.60372)
		(end 136.701784 -273.598894)
		(width 0.0889)
		(layer "In2.Cu")
		(net "M_I_CPU1_SB_CB<1>")
	)
	(segment
		(start 165.040818 -280.21026)
		(end 167.09263 -279.360376)
		(width 0.14478)
		(layer "In2.Cu")
		(net "M_I_CPU1_SB_CB<1>")
	)
	(arc
		(start 141.976094 -273.60372)
		(mid 142.159602 -273.649214)
		(end 142.341854 -273.598894)
		(width 0.0889)
		(layer "In2.Cu")
		(net "M_I_CPU1_SB_CB<1>")
	)
	(arc
		(start 143.847566 -273.598894)
		(mid 144.020674 -273.64901)
		(end 144.19707 -273.612102)
		(width 0.0889)
		(layer "In2.Cu")
		(net "M_I_CPU1_SB_CB<1>")
	)
	(arc
		(start 145.159984 -273.599148)
		(mid 145.255384 -273.554866)
		(end 145.357342 -273.529044)
		(width 0.0889)
		(layer "In2.Cu")
		(net "M_I_CPU1_SB_CB<1>")
	)
	(arc
		(start 130.687826 -273.598894)
		(mid 130.87477 -273.649149)
		(end 131.061714 -273.598894)
		(width 0.0889)
		(layer "In2.Cu")
		(net "M_I_CPU1_SB_CB<1>")
	)
	(arc
		(start 143.281654 -273.598894)
		(mid 143.56461 -273.522717)
		(end 143.847566 -273.598894)
		(width 0.0889)
		(layer "In2.Cu")
		(net "M_I_CPU1_SB_CB<1>")
	)
	(arc
		(start 138.216132 -273.60372)
		(mid 138.39964 -273.649214)
		(end 138.581892 -273.598894)
		(width 0.0889)
		(layer "In2.Cu")
		(net "M_I_CPU1_SB_CB<1>")
	)
	(arc
		(start 132.56768 -273.598894)
		(mid 132.749931 -273.649244)
		(end 132.93344 -273.60372)
		(width 0.0889)
		(layer "In2.Cu")
		(net "M_I_CPU1_SB_CB<1>")
	)
	(arc
		(start 134.821676 -273.598894)
		(mid 135.104632 -273.522717)
		(end 135.387588 -273.598894)
		(width 0.0889)
		(layer "In2.Cu")
		(net "M_I_CPU1_SB_CB<1>")
	)
	(arc
		(start 135.387588 -273.598894)
		(mid 135.569839 -273.649244)
		(end 135.753348 -273.60372)
		(width 0.0889)
		(layer "In2.Cu")
		(net "M_I_CPU1_SB_CB<1>")
	)
	(arc
		(start 133.516116 -273.60372)
		(mid 133.699624 -273.649214)
		(end 133.881876 -273.598894)
		(width 0.0889)
		(layer "In2.Cu")
		(net "M_I_CPU1_SB_CB<1>")
	)
	(arc
		(start 128.304798 -273.567144)
		(mid 128.560006 -273.523667)
		(end 128.807718 -273.598894)
		(width 0.0889)
		(layer "In2.Cu")
		(net "M_I_CPU1_SB_CB<1>")
	)
	(arc
		(start 133.881876 -273.598894)
		(mid 134.164832 -273.522717)
		(end 134.447788 -273.598894)
		(width 0.0889)
		(layer "In2.Cu")
		(net "M_I_CPU1_SB_CB<1>")
	)
	(arc
		(start 144.2466 -273.583654)
		(mid 144.517386 -273.523008)
		(end 144.784318 -273.598894)
		(width 0.0889)
		(layer "In2.Cu")
		(net "M_I_CPU1_SB_CB<1>")
	)
	(arc
		(start 144.804892 -273.610832)
		(mid 144.98382 -273.649709)
		(end 145.15973 -273.598894)
		(width 0.0889)
		(layer "In2.Cu")
		(net "M_I_CPU1_SB_CB<1>")
	)
	(arc
		(start 137.641838 -273.598894)
		(mid 137.924794 -273.522717)
		(end 138.20775 -273.598894)
		(width 0.0889)
		(layer "In2.Cu")
		(net "M_I_CPU1_SB_CB<1>")
	)
	(arc
		(start 142.341854 -273.598894)
		(mid 142.62481 -273.522717)
		(end 142.907766 -273.598894)
		(width 0.0889)
		(layer "In2.Cu")
		(net "M_I_CPU1_SB_CB<1>")
	)
	(arc
		(start 142.907766 -273.598894)
		(mid 143.09471 -273.649149)
		(end 143.281654 -273.598894)
		(width 0.0889)
		(layer "In2.Cu")
		(net "M_I_CPU1_SB_CB<1>")
	)
	(arc
		(start 131.627626 -273.598894)
		(mid 131.809877 -273.649244)
		(end 131.993386 -273.60372)
		(width 0.0889)
		(layer "In2.Cu")
		(net "M_I_CPU1_SB_CB<1>")
	)
	(arc
		(start 132.941822 -273.598894)
		(mid 133.224778 -273.522717)
		(end 133.507734 -273.598894)
		(width 0.0889)
		(layer "In2.Cu")
		(net "M_I_CPU1_SB_CB<1>")
	)
	(arc
		(start 137.276078 -273.60372)
		(mid 137.459586 -273.649214)
		(end 137.641838 -273.598894)
		(width 0.0889)
		(layer "In2.Cu")
		(net "M_I_CPU1_SB_CB<1>")
	)
	(arc
		(start 130.121914 -273.598894)
		(mid 130.40487 -273.522717)
		(end 130.687826 -273.598894)
		(width 0.0889)
		(layer "In2.Cu")
		(net "M_I_CPU1_SB_CB<1>")
	)
	(arc
		(start 128.8161 -273.60372)
		(mid 128.999608 -273.649214)
		(end 129.18186 -273.598894)
		(width 0.0889)
		(layer "In2.Cu")
		(net "M_I_CPU1_SB_CB<1>")
	)
	(arc
		(start 129.756154 -273.60372)
		(mid 129.939662 -273.649214)
		(end 130.121914 -273.598894)
		(width 0.0889)
		(layer "In2.Cu")
		(net "M_I_CPU1_SB_CB<1>")
	)
	(arc
		(start 140.087604 -273.598894)
		(mid 140.269855 -273.649244)
		(end 140.453364 -273.60372)
		(width 0.0889)
		(layer "In2.Cu")
		(net "M_I_CPU1_SB_CB<1>")
	)
	(arc
		(start 136.327642 -273.598894)
		(mid 136.509893 -273.649244)
		(end 136.693402 -273.60372)
		(width 0.0889)
		(layer "In2.Cu")
		(net "M_I_CPU1_SB_CB<1>")
	)
	(arc
		(start 140.461746 -273.598894)
		(mid 140.744702 -273.522717)
		(end 141.027658 -273.598894)
		(width 0.0889)
		(layer "In2.Cu")
		(net "M_I_CPU1_SB_CB<1>")
	)
	(arc
		(start 139.147804 -273.598894)
		(mid 139.334748 -273.649149)
		(end 139.521692 -273.598894)
		(width 0.0889)
		(layer "In2.Cu")
		(net "M_I_CPU1_SB_CB<1>")
	)
	(arc
		(start 134.447788 -273.598894)
		(mid 134.634732 -273.649149)
		(end 134.821676 -273.598894)
		(width 0.0889)
		(layer "In2.Cu")
		(net "M_I_CPU1_SB_CB<1>")
	)
	(arc
		(start 141.027658 -273.598894)
		(mid 141.209909 -273.649244)
		(end 141.393418 -273.60372)
		(width 0.0889)
		(layer "In2.Cu")
		(net "M_I_CPU1_SB_CB<1>")
	)
	(arc
		(start 132.001768 -273.598894)
		(mid 132.284724 -273.522717)
		(end 132.56768 -273.598894)
		(width 0.0889)
		(layer "In2.Cu")
		(net "M_I_CPU1_SB_CB<1>")
	)
	(arc
		(start 138.581892 -273.598894)
		(mid 138.864848 -273.522717)
		(end 139.147804 -273.598894)
		(width 0.0889)
		(layer "In2.Cu")
		(net "M_I_CPU1_SB_CB<1>")
	)
	(arc
		(start 136.701784 -273.598894)
		(mid 136.98474 -273.522717)
		(end 137.267696 -273.598894)
		(width 0.0889)
		(layer "In2.Cu")
		(net "M_I_CPU1_SB_CB<1>")
	)
	(arc
		(start 141.4018 -273.598894)
		(mid 141.684756 -273.522717)
		(end 141.967712 -273.598894)
		(width 0.0889)
		(layer "In2.Cu")
		(net "M_I_CPU1_SB_CB<1>")
	)
	(arc
		(start 131.061714 -273.598894)
		(mid 131.34467 -273.522717)
		(end 131.627626 -273.598894)
		(width 0.0889)
		(layer "In2.Cu")
		(net "M_I_CPU1_SB_CB<1>")
	)
	(arc
		(start 129.18186 -273.598894)
		(mid 129.464816 -273.522717)
		(end 129.747772 -273.598894)
		(width 0.0889)
		(layer "In2.Cu")
		(net "M_I_CPU1_SB_CB<1>")
	)
	(arc
		(start 139.521692 -273.598894)
		(mid 139.804648 -273.522717)
		(end 140.087604 -273.598894)
		(width 0.0889)
		(layer "In2.Cu")
		(net "M_I_CPU1_SB_CB<1>")
	)
	(arc
		(start 135.76173 -273.598894)
		(mid 136.044686 -273.522717)
		(end 136.327642 -273.598894)
		(width 0.0889)
		(layer "In2.Cu")
		(net "M_I_CPU1_SB_CB<1>")
	)
	(segment
		(start 128.997964 -272.20037)
		(end 129.464816 -272.466308)
		(width 0.10668)
		(layer "F.Cu")
		(net "M_I_CPU1_SB_CB<0>")
	)
	(segment
		(start 148.001482 -271.019524)
		(end 155.094432 -271.019524)
		(width 0.14478)
		(layer "In2.Cu")
		(net "M_I_CPU1_SB_CB<0>")
	)
	(segment
		(start 181.924706 -278.035004)
		(end 182.074566 -278.184864)
		(width 0.14478)
		(layer "In2.Cu")
		(net "M_I_CPU1_SB_CB<0>")
	)
	(segment
		(start 131.157726 -272.788888)
		(end 131.166108 -272.793714)
		(width 0.0889)
		(layer "In2.Cu")
		(net "M_I_CPU1_SB_CB<0>")
	)
	(segment
		(start 144.31772 -272.788888)
		(end 144.329404 -272.795746)
		(width 0.0889)
		(layer "In2.Cu")
		(net "M_I_CPU1_SB_CB<0>")
	)
	(segment
		(start 167.082978 -277.670006)
		(end 169.73423 -277.670006)
		(width 0.14478)
		(layer "In2.Cu")
		(net "M_I_CPU1_SB_CB<0>")
	)
	(segment
		(start 182.483506 -277.810214)
		(end 182.633366 -277.660354)
		(width 0.14478)
		(layer "In2.Cu")
		(net "M_I_CPU1_SB_CB<0>")
	)
	(segment
		(start 130.583432 -272.793714)
		(end 130.591814 -272.788888)
		(width 0.0889)
		(layer "In2.Cu")
		(net "M_I_CPU1_SB_CB<0>")
	)
	(segment
		(start 181.924706 -277.814786)
		(end 181.924706 -278.035004)
		(width 0.14478)
		(layer "In2.Cu")
		(net "M_I_CPU1_SB_CB<0>")
	)
	(segment
		(start 182.483506 -278.035004)
		(end 182.483506 -277.810214)
		(width 0.14478)
		(layer "In2.Cu")
		(net "M_I_CPU1_SB_CB<0>")
	)
	(segment
		(start 129.464816 -272.466308)
		(end 129.61874 -272.731738)
		(width 0.0889)
		(layer "In2.Cu")
		(net "M_I_CPU1_SB_CB<0>")
	)
	(segment
		(start 145.258028 -272.788634)
		(end 145.276316 -272.799048)
		(width 0.0889)
		(layer "In2.Cu")
		(net "M_I_CPU1_SB_CB<0>")
	)
	(segment
		(start 139.617704 -272.788888)
		(end 139.626086 -272.793714)
		(width 0.0889)
		(layer "In2.Cu")
		(net "M_I_CPU1_SB_CB<0>")
	)
	(segment
		(start 139.04341 -272.793714)
		(end 139.051792 -272.788888)
		(width 0.0889)
		(layer "In2.Cu")
		(net "M_I_CPU1_SB_CB<0>")
	)
	(segment
		(start 142.803372 -272.793714)
		(end 142.811754 -272.788888)
		(width 0.0889)
		(layer "In2.Cu")
		(net "M_I_CPU1_SB_CB<0>")
	)
	(segment
		(start 169.73423 -277.670006)
		(end 170.584368 -278.520144)
		(width 0.14478)
		(layer "In2.Cu")
		(net "M_I_CPU1_SB_CB<0>")
	)
	(segment
		(start 134.343394 -272.793714)
		(end 134.351776 -272.788888)
		(width 0.0889)
		(layer "In2.Cu")
		(net "M_I_CPU1_SB_CB<0>")
	)
	(segment
		(start 183.19115 -277.660354)
		(end 183.616092 -278.085296)
		(width 0.14478)
		(layer "In2.Cu")
		(net "M_I_CPU1_SB_CB<0>")
	)
	(segment
		(start 182.633366 -277.660354)
		(end 183.19115 -277.660354)
		(width 0.14478)
		(layer "In2.Cu")
		(net "M_I_CPU1_SB_CB<0>")
	)
	(segment
		(start 145.63217 -272.788888)
		(end 145.788126 -272.68424)
		(width 0.0889)
		(layer "In2.Cu")
		(net "M_I_CPU1_SB_CB<0>")
	)
	(segment
		(start 129.61874 -272.731738)
		(end 129.714752 -272.757138)
		(width 0.0889)
		(layer "In2.Cu")
		(net "M_I_CPU1_SB_CB<0>")
	)
	(segment
		(start 134.917688 -272.788888)
		(end 134.92607 -272.793714)
		(width 0.0889)
		(layer "In2.Cu")
		(net "M_I_CPU1_SB_CB<0>")
	)
	(segment
		(start 182.333646 -278.184864)
		(end 182.483506 -278.035004)
		(width 0.14478)
		(layer "In2.Cu")
		(net "M_I_CPU1_SB_CB<0>")
	)
	(segment
		(start 145.788126 -272.68424)
		(end 146.472148 -271.66062)
		(width 0.0889)
		(layer "In2.Cu")
		(net "M_I_CPU1_SB_CB<0>")
	)
	(segment
		(start 135.857742 -272.788888)
		(end 135.866124 -272.793714)
		(width 0.0889)
		(layer "In2.Cu")
		(net "M_I_CPU1_SB_CB<0>")
	)
	(segment
		(start 146.644106 -271.245584)
		(end 146.870166 -271.019524)
		(width 0.0889)
		(layer "In2.Cu")
		(net "M_I_CPU1_SB_CB<0>")
	)
	(segment
		(start 155.094432 -271.019524)
		(end 162.595052 -278.520144)
		(width 0.14478)
		(layer "In2.Cu")
		(net "M_I_CPU1_SB_CB<0>")
	)
	(segment
		(start 132.09778 -272.788888)
		(end 132.106162 -272.793714)
		(width 0.0889)
		(layer "In2.Cu")
		(net "M_I_CPU1_SB_CB<0>")
	)
	(segment
		(start 145.24228 -272.77949)
		(end 145.258028 -272.788634)
		(width 0.0889)
		(layer "In2.Cu")
		(net "M_I_CPU1_SB_CB<0>")
	)
	(segment
		(start 138.103356 -272.793714)
		(end 138.111738 -272.788888)
		(width 0.0889)
		(layer "In2.Cu")
		(net "M_I_CPU1_SB_CB<0>")
	)
	(segment
		(start 146.870166 -271.019524)
		(end 148.001482 -271.019524)
		(width 0.0889)
		(layer "In2.Cu")
		(net "M_I_CPU1_SB_CB<0>")
	)
	(segment
		(start 170.584368 -278.520144)
		(end 173.575726 -278.520144)
		(width 0.14478)
		(layer "In2.Cu")
		(net "M_I_CPU1_SB_CB<0>")
	)
	(segment
		(start 140.557758 -272.788888)
		(end 140.56614 -272.793714)
		(width 0.0889)
		(layer "In2.Cu")
		(net "M_I_CPU1_SB_CB<0>")
	)
	(segment
		(start 174.425864 -277.670006)
		(end 181.779926 -277.670006)
		(width 0.14478)
		(layer "In2.Cu")
		(net "M_I_CPU1_SB_CB<0>")
	)
	(segment
		(start 166.23284 -278.520144)
		(end 167.082978 -277.670006)
		(width 0.14478)
		(layer "In2.Cu")
		(net "M_I_CPU1_SB_CB<0>")
	)
	(segment
		(start 173.575726 -278.520144)
		(end 174.425864 -277.670006)
		(width 0.14478)
		(layer "In2.Cu")
		(net "M_I_CPU1_SB_CB<0>")
	)
	(segment
		(start 162.595052 -278.520144)
		(end 166.23284 -278.520144)
		(width 0.14478)
		(layer "In2.Cu")
		(net "M_I_CPU1_SB_CB<0>")
	)
	(segment
		(start 143.377666 -272.788888)
		(end 143.386048 -272.793714)
		(width 0.0889)
		(layer "In2.Cu")
		(net "M_I_CPU1_SB_CB<0>")
	)
	(segment
		(start 181.779926 -277.670006)
		(end 181.924706 -277.814786)
		(width 0.14478)
		(layer "In2.Cu")
		(net "M_I_CPU1_SB_CB<0>")
	)
	(segment
		(start 182.074566 -278.184864)
		(end 182.333646 -278.184864)
		(width 0.14478)
		(layer "In2.Cu")
		(net "M_I_CPU1_SB_CB<0>")
	)
	(segment
		(start 146.472148 -271.66062)
		(end 146.644106 -271.245584)
		(width 0.0889)
		(layer "In2.Cu")
		(net "M_I_CPU1_SB_CB<0>")
	)
	(arc
		(start 130.591814 -272.788888)
		(mid 130.87477 -272.712711)
		(end 131.157726 -272.788888)
		(width 0.0889)
		(layer "In2.Cu")
		(net "M_I_CPU1_SB_CB<0>")
	)
	(arc
		(start 144.692116 -272.788888)
		(mid 144.965971 -272.712538)
		(end 145.24228 -272.77949)
		(width 0.0889)
		(layer "In2.Cu")
		(net "M_I_CPU1_SB_CB<0>")
	)
	(arc
		(start 131.531868 -272.788888)
		(mid 131.814824 -272.712711)
		(end 132.09778 -272.788888)
		(width 0.0889)
		(layer "In2.Cu")
		(net "M_I_CPU1_SB_CB<0>")
	)
	(arc
		(start 137.737596 -272.788888)
		(mid 137.919847 -272.839238)
		(end 138.103356 -272.793714)
		(width 0.0889)
		(layer "In2.Cu")
		(net "M_I_CPU1_SB_CB<0>")
	)
	(arc
		(start 135.866124 -272.793714)
		(mid 136.049632 -272.839208)
		(end 136.231884 -272.788888)
		(width 0.0889)
		(layer "In2.Cu")
		(net "M_I_CPU1_SB_CB<0>")
	)
	(arc
		(start 142.811754 -272.788888)
		(mid 143.09471 -272.712711)
		(end 143.377666 -272.788888)
		(width 0.0889)
		(layer "In2.Cu")
		(net "M_I_CPU1_SB_CB<0>")
	)
	(arc
		(start 136.231884 -272.788888)
		(mid 136.51484 -272.712711)
		(end 136.797796 -272.788888)
		(width 0.0889)
		(layer "In2.Cu")
		(net "M_I_CPU1_SB_CB<0>")
	)
	(arc
		(start 130.217672 -272.788888)
		(mid 130.399923 -272.839238)
		(end 130.583432 -272.793714)
		(width 0.0889)
		(layer "In2.Cu")
		(net "M_I_CPU1_SB_CB<0>")
	)
	(arc
		(start 139.991846 -272.788888)
		(mid 140.274802 -272.712711)
		(end 140.557758 -272.788888)
		(width 0.0889)
		(layer "In2.Cu")
		(net "M_I_CPU1_SB_CB<0>")
	)
	(arc
		(start 143.751808 -272.788888)
		(mid 144.034764 -272.712711)
		(end 144.31772 -272.788888)
		(width 0.0889)
		(layer "In2.Cu")
		(net "M_I_CPU1_SB_CB<0>")
	)
	(arc
		(start 142.437612 -272.788888)
		(mid 142.619863 -272.839238)
		(end 142.803372 -272.793714)
		(width 0.0889)
		(layer "In2.Cu")
		(net "M_I_CPU1_SB_CB<0>")
	)
	(arc
		(start 132.471922 -272.788888)
		(mid 132.754878 -272.712711)
		(end 133.037834 -272.788888)
		(width 0.0889)
		(layer "In2.Cu")
		(net "M_I_CPU1_SB_CB<0>")
	)
	(arc
		(start 129.714752 -272.757138)
		(mid 129.96996 -272.713661)
		(end 130.217672 -272.788888)
		(width 0.0889)
		(layer "In2.Cu")
		(net "M_I_CPU1_SB_CB<0>")
	)
	(arc
		(start 135.29183 -272.788888)
		(mid 135.574786 -272.712711)
		(end 135.857742 -272.788888)
		(width 0.0889)
		(layer "In2.Cu")
		(net "M_I_CPU1_SB_CB<0>")
	)
	(arc
		(start 132.106162 -272.793714)
		(mid 132.28967 -272.839208)
		(end 132.471922 -272.788888)
		(width 0.0889)
		(layer "In2.Cu")
		(net "M_I_CPU1_SB_CB<0>")
	)
	(arc
		(start 141.497812 -272.788888)
		(mid 141.684756 -272.839143)
		(end 141.8717 -272.788888)
		(width 0.0889)
		(layer "In2.Cu")
		(net "M_I_CPU1_SB_CB<0>")
	)
	(arc
		(start 140.9319 -272.788888)
		(mid 141.214856 -272.712711)
		(end 141.497812 -272.788888)
		(width 0.0889)
		(layer "In2.Cu")
		(net "M_I_CPU1_SB_CB<0>")
	)
	(arc
		(start 134.351776 -272.788888)
		(mid 134.634732 -272.712711)
		(end 134.917688 -272.788888)
		(width 0.0889)
		(layer "In2.Cu")
		(net "M_I_CPU1_SB_CB<0>")
	)
	(arc
		(start 141.8717 -272.788888)
		(mid 142.154656 -272.712711)
		(end 142.437612 -272.788888)
		(width 0.0889)
		(layer "In2.Cu")
		(net "M_I_CPU1_SB_CB<0>")
	)
	(arc
		(start 145.276316 -272.799048)
		(mid 145.455545 -272.839201)
		(end 145.63217 -272.788888)
		(width 0.0889)
		(layer "In2.Cu")
		(net "M_I_CPU1_SB_CB<0>")
	)
	(arc
		(start 140.56614 -272.793714)
		(mid 140.749648 -272.839208)
		(end 140.9319 -272.788888)
		(width 0.0889)
		(layer "In2.Cu")
		(net "M_I_CPU1_SB_CB<0>")
	)
	(arc
		(start 143.386048 -272.793714)
		(mid 143.569556 -272.839208)
		(end 143.751808 -272.788888)
		(width 0.0889)
		(layer "In2.Cu")
		(net "M_I_CPU1_SB_CB<0>")
	)
	(arc
		(start 134.92607 -272.793714)
		(mid 135.109578 -272.839208)
		(end 135.29183 -272.788888)
		(width 0.0889)
		(layer "In2.Cu")
		(net "M_I_CPU1_SB_CB<0>")
	)
	(arc
		(start 138.67765 -272.788888)
		(mid 138.859901 -272.839238)
		(end 139.04341 -272.793714)
		(width 0.0889)
		(layer "In2.Cu")
		(net "M_I_CPU1_SB_CB<0>")
	)
	(arc
		(start 133.037834 -272.788888)
		(mid 133.224778 -272.839143)
		(end 133.411722 -272.788888)
		(width 0.0889)
		(layer "In2.Cu")
		(net "M_I_CPU1_SB_CB<0>")
	)
	(arc
		(start 137.171684 -272.788888)
		(mid 137.45464 -272.712711)
		(end 137.737596 -272.788888)
		(width 0.0889)
		(layer "In2.Cu")
		(net "M_I_CPU1_SB_CB<0>")
	)
	(arc
		(start 139.051792 -272.788888)
		(mid 139.334748 -272.712711)
		(end 139.617704 -272.788888)
		(width 0.0889)
		(layer "In2.Cu")
		(net "M_I_CPU1_SB_CB<0>")
	)
	(arc
		(start 138.111738 -272.788888)
		(mid 138.394694 -272.712711)
		(end 138.67765 -272.788888)
		(width 0.0889)
		(layer "In2.Cu")
		(net "M_I_CPU1_SB_CB<0>")
	)
	(arc
		(start 144.329404 -272.795746)
		(mid 144.511659 -272.839399)
		(end 144.692116 -272.788888)
		(width 0.0889)
		(layer "In2.Cu")
		(net "M_I_CPU1_SB_CB<0>")
	)
	(arc
		(start 136.797796 -272.788888)
		(mid 136.98474 -272.839143)
		(end 137.171684 -272.788888)
		(width 0.0889)
		(layer "In2.Cu")
		(net "M_I_CPU1_SB_CB<0>")
	)
	(arc
		(start 139.626086 -272.793714)
		(mid 139.809594 -272.839208)
		(end 139.991846 -272.788888)
		(width 0.0889)
		(layer "In2.Cu")
		(net "M_I_CPU1_SB_CB<0>")
	)
	(arc
		(start 131.166108 -272.793714)
		(mid 131.349616 -272.839208)
		(end 131.531868 -272.788888)
		(width 0.0889)
		(layer "In2.Cu")
		(net "M_I_CPU1_SB_CB<0>")
	)
	(arc
		(start 133.411722 -272.788888)
		(mid 133.694678 -272.712711)
		(end 133.977634 -272.788888)
		(width 0.0889)
		(layer "In2.Cu")
		(net "M_I_CPU1_SB_CB<0>")
	)
	(arc
		(start 133.977634 -272.788888)
		(mid 134.159885 -272.839238)
		(end 134.343394 -272.793714)
		(width 0.0889)
		(layer "In2.Cu")
		(net "M_I_CPU1_SB_CB<0>")
	)
	(segment
		(start 128.997964 -264.10031)
		(end 129.464816 -264.366248)
		(width 0.10668)
		(layer "F.Cu")
		(net "M_I_CPU1_SB_CA<6>")
	)
	(segment
		(start 144.31772 -264.688828)
		(end 144.329404 -264.695686)
		(width 0.0889)
		(layer "In2.Cu")
		(net "M_I_CPU1_SB_CA<6>")
	)
	(segment
		(start 135.857742 -264.688828)
		(end 135.866124 -264.693654)
		(width 0.0889)
		(layer "In2.Cu")
		(net "M_I_CPU1_SB_CA<6>")
	)
	(segment
		(start 142.803372 -264.693654)
		(end 142.811754 -264.688828)
		(width 0.0889)
		(layer "In2.Cu")
		(net "M_I_CPU1_SB_CA<6>")
	)
	(segment
		(start 129.464816 -264.366248)
		(end 129.61874 -264.631678)
		(width 0.0889)
		(layer "In2.Cu")
		(net "M_I_CPU1_SB_CA<6>")
	)
	(segment
		(start 145.936462 -264.384536)
		(end 146.045682 -264.339324)
		(width 0.0889)
		(layer "In2.Cu")
		(net "M_I_CPU1_SB_CA<6>")
	)
	(segment
		(start 139.617704 -264.688828)
		(end 139.626086 -264.693654)
		(width 0.0889)
		(layer "In2.Cu")
		(net "M_I_CPU1_SB_CA<6>")
	)
	(segment
		(start 132.09778 -264.688828)
		(end 132.106162 -264.693654)
		(width 0.0889)
		(layer "In2.Cu")
		(net "M_I_CPU1_SB_CA<6>")
	)
	(segment
		(start 139.04341 -264.693654)
		(end 139.051792 -264.688828)
		(width 0.0889)
		(layer "In2.Cu")
		(net "M_I_CPU1_SB_CA<6>")
	)
	(segment
		(start 183.19115 -266.610338)
		(end 183.616092 -266.185396)
		(width 0.14478)
		(layer "In2.Cu")
		(net "M_I_CPU1_SB_CA<6>")
	)
	(segment
		(start 131.157726 -264.688828)
		(end 131.166108 -264.693654)
		(width 0.0889)
		(layer "In2.Cu")
		(net "M_I_CPU1_SB_CA<6>")
	)
	(segment
		(start 163.708334 -266.610338)
		(end 183.19115 -266.610338)
		(width 0.14478)
		(layer "In2.Cu")
		(net "M_I_CPU1_SB_CA<6>")
	)
	(segment
		(start 134.343394 -264.693654)
		(end 134.351776 -264.688828)
		(width 0.0889)
		(layer "In2.Cu")
		(net "M_I_CPU1_SB_CA<6>")
	)
	(segment
		(start 138.103356 -264.693654)
		(end 138.111738 -264.688828)
		(width 0.0889)
		(layer "In2.Cu")
		(net "M_I_CPU1_SB_CA<6>")
	)
	(segment
		(start 147.509992 -264.339324)
		(end 158.907988 -264.339324)
		(width 0.14478)
		(layer "In2.Cu")
		(net "M_I_CPU1_SB_CA<6>")
	)
	(segment
		(start 145.63217 -264.688828)
		(end 145.936462 -264.384536)
		(width 0.0889)
		(layer "In2.Cu")
		(net "M_I_CPU1_SB_CA<6>")
	)
	(segment
		(start 140.557758 -264.688828)
		(end 140.56614 -264.693654)
		(width 0.0889)
		(layer "In2.Cu")
		(net "M_I_CPU1_SB_CA<6>")
	)
	(segment
		(start 145.24228 -264.67943)
		(end 145.258028 -264.688574)
		(width 0.0889)
		(layer "In2.Cu")
		(net "M_I_CPU1_SB_CA<6>")
	)
	(segment
		(start 143.377666 -264.688828)
		(end 143.386048 -264.693654)
		(width 0.0889)
		(layer "In2.Cu")
		(net "M_I_CPU1_SB_CA<6>")
	)
	(segment
		(start 146.045682 -264.339324)
		(end 147.509992 -264.339324)
		(width 0.0889)
		(layer "In2.Cu")
		(net "M_I_CPU1_SB_CA<6>")
	)
	(segment
		(start 145.258028 -264.688574)
		(end 145.276316 -264.698988)
		(width 0.0889)
		(layer "In2.Cu")
		(net "M_I_CPU1_SB_CA<6>")
	)
	(segment
		(start 130.583432 -264.693654)
		(end 130.591814 -264.688828)
		(width 0.0889)
		(layer "In2.Cu")
		(net "M_I_CPU1_SB_CA<6>")
	)
	(segment
		(start 158.907988 -264.339324)
		(end 163.708334 -266.610338)
		(width 0.14478)
		(layer "In2.Cu")
		(net "M_I_CPU1_SB_CA<6>")
	)
	(segment
		(start 129.61874 -264.631678)
		(end 129.714752 -264.657078)
		(width 0.0889)
		(layer "In2.Cu")
		(net "M_I_CPU1_SB_CA<6>")
	)
	(segment
		(start 134.917688 -264.688828)
		(end 134.92607 -264.693654)
		(width 0.0889)
		(layer "In2.Cu")
		(net "M_I_CPU1_SB_CA<6>")
	)
	(arc
		(start 138.67765 -264.688828)
		(mid 138.859901 -264.739178)
		(end 139.04341 -264.693654)
		(width 0.0889)
		(layer "In2.Cu")
		(net "M_I_CPU1_SB_CA<6>")
	)
	(arc
		(start 140.9319 -264.688828)
		(mid 141.214856 -264.612651)
		(end 141.497812 -264.688828)
		(width 0.0889)
		(layer "In2.Cu")
		(net "M_I_CPU1_SB_CA<6>")
	)
	(arc
		(start 132.106162 -264.693654)
		(mid 132.28967 -264.739148)
		(end 132.471922 -264.688828)
		(width 0.0889)
		(layer "In2.Cu")
		(net "M_I_CPU1_SB_CA<6>")
	)
	(arc
		(start 137.171684 -264.688828)
		(mid 137.45464 -264.612651)
		(end 137.737596 -264.688828)
		(width 0.0889)
		(layer "In2.Cu")
		(net "M_I_CPU1_SB_CA<6>")
	)
	(arc
		(start 133.411722 -264.688828)
		(mid 133.694678 -264.612651)
		(end 133.977634 -264.688828)
		(width 0.0889)
		(layer "In2.Cu")
		(net "M_I_CPU1_SB_CA<6>")
	)
	(arc
		(start 134.92607 -264.693654)
		(mid 135.109578 -264.739148)
		(end 135.29183 -264.688828)
		(width 0.0889)
		(layer "In2.Cu")
		(net "M_I_CPU1_SB_CA<6>")
	)
	(arc
		(start 133.977634 -264.688828)
		(mid 134.159885 -264.739178)
		(end 134.343394 -264.693654)
		(width 0.0889)
		(layer "In2.Cu")
		(net "M_I_CPU1_SB_CA<6>")
	)
	(arc
		(start 141.497812 -264.688828)
		(mid 141.684756 -264.739083)
		(end 141.8717 -264.688828)
		(width 0.0889)
		(layer "In2.Cu")
		(net "M_I_CPU1_SB_CA<6>")
	)
	(arc
		(start 129.714752 -264.657078)
		(mid 129.96996 -264.613601)
		(end 130.217672 -264.688828)
		(width 0.0889)
		(layer "In2.Cu")
		(net "M_I_CPU1_SB_CA<6>")
	)
	(arc
		(start 135.29183 -264.688828)
		(mid 135.574786 -264.612651)
		(end 135.857742 -264.688828)
		(width 0.0889)
		(layer "In2.Cu")
		(net "M_I_CPU1_SB_CA<6>")
	)
	(arc
		(start 136.797796 -264.688828)
		(mid 136.98474 -264.739083)
		(end 137.171684 -264.688828)
		(width 0.0889)
		(layer "In2.Cu")
		(net "M_I_CPU1_SB_CA<6>")
	)
	(arc
		(start 139.991846 -264.688828)
		(mid 140.274802 -264.612651)
		(end 140.557758 -264.688828)
		(width 0.0889)
		(layer "In2.Cu")
		(net "M_I_CPU1_SB_CA<6>")
	)
	(arc
		(start 130.217672 -264.688828)
		(mid 130.399923 -264.739178)
		(end 130.583432 -264.693654)
		(width 0.0889)
		(layer "In2.Cu")
		(net "M_I_CPU1_SB_CA<6>")
	)
	(arc
		(start 131.166108 -264.693654)
		(mid 131.349616 -264.739148)
		(end 131.531868 -264.688828)
		(width 0.0889)
		(layer "In2.Cu")
		(net "M_I_CPU1_SB_CA<6>")
	)
	(arc
		(start 132.471922 -264.688828)
		(mid 132.754878 -264.612651)
		(end 133.037834 -264.688828)
		(width 0.0889)
		(layer "In2.Cu")
		(net "M_I_CPU1_SB_CA<6>")
	)
	(arc
		(start 145.276316 -264.698988)
		(mid 145.455545 -264.739141)
		(end 145.63217 -264.688828)
		(width 0.0889)
		(layer "In2.Cu")
		(net "M_I_CPU1_SB_CA<6>")
	)
	(arc
		(start 141.8717 -264.688828)
		(mid 142.154656 -264.612651)
		(end 142.437612 -264.688828)
		(width 0.0889)
		(layer "In2.Cu")
		(net "M_I_CPU1_SB_CA<6>")
	)
	(arc
		(start 143.751808 -264.688828)
		(mid 144.034764 -264.612651)
		(end 144.31772 -264.688828)
		(width 0.0889)
		(layer "In2.Cu")
		(net "M_I_CPU1_SB_CA<6>")
	)
	(arc
		(start 131.531868 -264.688828)
		(mid 131.814824 -264.612651)
		(end 132.09778 -264.688828)
		(width 0.0889)
		(layer "In2.Cu")
		(net "M_I_CPU1_SB_CA<6>")
	)
	(arc
		(start 130.591814 -264.688828)
		(mid 130.87477 -264.612651)
		(end 131.157726 -264.688828)
		(width 0.0889)
		(layer "In2.Cu")
		(net "M_I_CPU1_SB_CA<6>")
	)
	(arc
		(start 144.692116 -264.688828)
		(mid 144.965971 -264.612478)
		(end 145.24228 -264.67943)
		(width 0.0889)
		(layer "In2.Cu")
		(net "M_I_CPU1_SB_CA<6>")
	)
	(arc
		(start 137.737596 -264.688828)
		(mid 137.919847 -264.739178)
		(end 138.103356 -264.693654)
		(width 0.0889)
		(layer "In2.Cu")
		(net "M_I_CPU1_SB_CA<6>")
	)
	(arc
		(start 136.231884 -264.688828)
		(mid 136.51484 -264.612651)
		(end 136.797796 -264.688828)
		(width 0.0889)
		(layer "In2.Cu")
		(net "M_I_CPU1_SB_CA<6>")
	)
	(arc
		(start 142.811754 -264.688828)
		(mid 143.09471 -264.612651)
		(end 143.377666 -264.688828)
		(width 0.0889)
		(layer "In2.Cu")
		(net "M_I_CPU1_SB_CA<6>")
	)
	(arc
		(start 139.051792 -264.688828)
		(mid 139.334748 -264.612651)
		(end 139.617704 -264.688828)
		(width 0.0889)
		(layer "In2.Cu")
		(net "M_I_CPU1_SB_CA<6>")
	)
	(arc
		(start 138.111738 -264.688828)
		(mid 138.394694 -264.612651)
		(end 138.67765 -264.688828)
		(width 0.0889)
		(layer "In2.Cu")
		(net "M_I_CPU1_SB_CA<6>")
	)
	(arc
		(start 144.329404 -264.695686)
		(mid 144.511659 -264.739339)
		(end 144.692116 -264.688828)
		(width 0.0889)
		(layer "In2.Cu")
		(net "M_I_CPU1_SB_CA<6>")
	)
	(arc
		(start 135.866124 -264.693654)
		(mid 136.049632 -264.739148)
		(end 136.231884 -264.688828)
		(width 0.0889)
		(layer "In2.Cu")
		(net "M_I_CPU1_SB_CA<6>")
	)
	(arc
		(start 142.437612 -264.688828)
		(mid 142.619863 -264.739178)
		(end 142.803372 -264.693654)
		(width 0.0889)
		(layer "In2.Cu")
		(net "M_I_CPU1_SB_CA<6>")
	)
	(arc
		(start 140.56614 -264.693654)
		(mid 140.749648 -264.739148)
		(end 140.9319 -264.688828)
		(width 0.0889)
		(layer "In2.Cu")
		(net "M_I_CPU1_SB_CA<6>")
	)
	(arc
		(start 139.626086 -264.693654)
		(mid 139.809594 -264.739148)
		(end 139.991846 -264.688828)
		(width 0.0889)
		(layer "In2.Cu")
		(net "M_I_CPU1_SB_CA<6>")
	)
	(arc
		(start 134.351776 -264.688828)
		(mid 134.634732 -264.612651)
		(end 134.917688 -264.688828)
		(width 0.0889)
		(layer "In2.Cu")
		(net "M_I_CPU1_SB_CA<6>")
	)
	(arc
		(start 133.037834 -264.688828)
		(mid 133.224778 -264.739083)
		(end 133.411722 -264.688828)
		(width 0.0889)
		(layer "In2.Cu")
		(net "M_I_CPU1_SB_CA<6>")
	)
	(arc
		(start 143.386048 -264.693654)
		(mid 143.569556 -264.739148)
		(end 143.751808 -264.688828)
		(width 0.0889)
		(layer "In2.Cu")
		(net "M_I_CPU1_SB_CA<6>")
	)
	(segment
		(start 128.05791 -264.10031)
		(end 128.524762 -264.366248)
		(width 0.10668)
		(layer "F.Cu")
		(net "M_I_CPU1_SB_CA<5>")
	)
	(segment
		(start 145.373852 -263.999472)
		(end 147.422362 -263.999472)
		(width 0.0889)
		(layer "In2.Cu")
		(net "M_I_CPU1_SB_CA<5>")
	)
	(segment
		(start 167.226996 -265.464544)
		(end 167.522906 -265.760454)
		(width 0.14478)
		(layer "In2.Cu")
		(net "M_I_CPU1_SB_CA<5>")
	)
	(segment
		(start 134.343394 -264.038842)
		(end 134.351776 -264.043668)
		(width 0.0889)
		(layer "In2.Cu")
		(net "M_I_CPU1_SB_CA<5>")
	)
	(segment
		(start 160.894268 -264.594848)
		(end 161.264854 -264.440924)
		(width 0.14478)
		(layer "In2.Cu")
		(net "M_I_CPU1_SB_CA<5>")
	)
	(segment
		(start 128.524762 -264.366248)
		(end 128.370838 -264.100818)
		(width 0.0889)
		(layer "In2.Cu")
		(net "M_I_CPU1_SB_CA<5>")
	)
	(segment
		(start 140.557758 -264.043668)
		(end 140.56614 -264.038842)
		(width 0.0889)
		(layer "In2.Cu")
		(net "M_I_CPU1_SB_CA<5>")
	)
	(segment
		(start 165.846506 -265.464544)
		(end 166.109396 -265.464544)
		(width 0.14478)
		(layer "In2.Cu")
		(net "M_I_CPU1_SB_CA<5>")
	)
	(segment
		(start 160.23209 -264.013188)
		(end 160.48609 -264.118598)
		(width 0.14478)
		(layer "In2.Cu")
		(net "M_I_CPU1_SB_CA<5>")
	)
	(segment
		(start 128.370838 -264.100818)
		(end 128.39319 -264.017506)
		(width 0.0889)
		(layer "In2.Cu")
		(net "M_I_CPU1_SB_CA<5>")
	)
	(segment
		(start 139.617704 -264.043668)
		(end 139.626086 -264.038842)
		(width 0.0889)
		(layer "In2.Cu")
		(net "M_I_CPU1_SB_CA<5>")
	)
	(segment
		(start 138.103356 -264.038842)
		(end 138.111738 -264.043668)
		(width 0.0889)
		(layer "In2.Cu")
		(net "M_I_CPU1_SB_CA<5>")
	)
	(segment
		(start 161.518854 -264.546334)
		(end 161.672524 -264.917174)
		(width 0.14478)
		(layer "In2.Cu")
		(net "M_I_CPU1_SB_CA<5>")
	)
	(segment
		(start 162.705288 -265.34491)
		(end 163.120832 -265.760454)
		(width 0.14478)
		(layer "In2.Cu")
		(net "M_I_CPU1_SB_CA<5>")
	)
	(segment
		(start 144.289526 -264.058908)
		(end 144.315688 -264.043922)
		(width 0.0889)
		(layer "In2.Cu")
		(net "M_I_CPU1_SB_CA<5>")
	)
	(segment
		(start 161.927032 -265.022584)
		(end 162.297618 -264.86866)
		(width 0.14478)
		(layer "In2.Cu")
		(net "M_I_CPU1_SB_CA<5>")
	)
	(segment
		(start 162.297618 -264.86866)
		(end 162.551618 -264.97407)
		(width 0.14478)
		(layer "In2.Cu")
		(net "M_I_CPU1_SB_CA<5>")
	)
	(segment
		(start 147.53717 -263.884664)
		(end 159.179514 -263.884664)
		(width 0.14478)
		(layer "In2.Cu")
		(net "M_I_CPU1_SB_CA<5>")
	)
	(segment
		(start 159.179514 -263.884664)
		(end 159.861504 -264.167112)
		(width 0.14478)
		(layer "In2.Cu")
		(net "M_I_CPU1_SB_CA<5>")
	)
	(segment
		(start 160.63976 -264.489438)
		(end 160.894268 -264.594848)
		(width 0.14478)
		(layer "In2.Cu")
		(net "M_I_CPU1_SB_CA<5>")
	)
	(segment
		(start 160.48609 -264.118598)
		(end 160.63976 -264.489438)
		(width 0.14478)
		(layer "In2.Cu")
		(net "M_I_CPU1_SB_CA<5>")
	)
	(segment
		(start 129.643378 -264.038842)
		(end 129.65176 -264.043668)
		(width 0.0889)
		(layer "In2.Cu")
		(net "M_I_CPU1_SB_CA<5>")
	)
	(segment
		(start 161.264854 -264.440924)
		(end 161.518854 -264.546334)
		(width 0.14478)
		(layer "In2.Cu")
		(net "M_I_CPU1_SB_CA<5>")
	)
	(segment
		(start 131.157726 -264.043668)
		(end 131.166108 -264.038842)
		(width 0.0889)
		(layer "In2.Cu")
		(net "M_I_CPU1_SB_CA<5>")
	)
	(segment
		(start 179.090828 -265.760454)
		(end 179.516024 -265.335258)
		(width 0.14478)
		(layer "In2.Cu")
		(net "M_I_CPU1_SB_CA<5>")
	)
	(segment
		(start 166.668196 -265.760454)
		(end 166.964106 -265.464544)
		(width 0.14478)
		(layer "In2.Cu")
		(net "M_I_CPU1_SB_CA<5>")
	)
	(segment
		(start 143.377666 -264.043668)
		(end 143.386048 -264.038842)
		(width 0.0889)
		(layer "In2.Cu")
		(net "M_I_CPU1_SB_CA<5>")
	)
	(segment
		(start 161.672524 -264.917174)
		(end 161.927032 -265.022584)
		(width 0.14478)
		(layer "In2.Cu")
		(net "M_I_CPU1_SB_CA<5>")
	)
	(segment
		(start 166.109396 -265.464544)
		(end 166.405306 -265.760454)
		(width 0.14478)
		(layer "In2.Cu")
		(net "M_I_CPU1_SB_CA<5>")
	)
	(segment
		(start 130.583432 -264.038842)
		(end 130.591814 -264.043668)
		(width 0.0889)
		(layer "In2.Cu")
		(net "M_I_CPU1_SB_CA<5>")
	)
	(segment
		(start 159.861504 -264.167112)
		(end 160.23209 -264.013188)
		(width 0.14478)
		(layer "In2.Cu")
		(net "M_I_CPU1_SB_CA<5>")
	)
	(segment
		(start 135.857742 -264.043668)
		(end 135.866124 -264.038842)
		(width 0.0889)
		(layer "In2.Cu")
		(net "M_I_CPU1_SB_CA<5>")
	)
	(segment
		(start 166.405306 -265.760454)
		(end 166.668196 -265.760454)
		(width 0.14478)
		(layer "In2.Cu")
		(net "M_I_CPU1_SB_CA<5>")
	)
	(segment
		(start 166.964106 -265.464544)
		(end 167.226996 -265.464544)
		(width 0.14478)
		(layer "In2.Cu")
		(net "M_I_CPU1_SB_CA<5>")
	)
	(segment
		(start 132.09778 -264.043668)
		(end 132.106162 -264.038842)
		(width 0.0889)
		(layer "In2.Cu")
		(net "M_I_CPU1_SB_CA<5>")
	)
	(segment
		(start 163.120832 -265.760454)
		(end 165.550596 -265.760454)
		(width 0.14478)
		(layer "In2.Cu")
		(net "M_I_CPU1_SB_CA<5>")
	)
	(segment
		(start 134.917688 -264.043668)
		(end 134.92607 -264.038842)
		(width 0.0889)
		(layer "In2.Cu")
		(net "M_I_CPU1_SB_CA<5>")
	)
	(segment
		(start 167.522906 -265.760454)
		(end 179.090828 -265.760454)
		(width 0.14478)
		(layer "In2.Cu")
		(net "M_I_CPU1_SB_CA<5>")
	)
	(segment
		(start 165.550596 -265.760454)
		(end 165.846506 -265.464544)
		(width 0.14478)
		(layer "In2.Cu")
		(net "M_I_CPU1_SB_CA<5>")
	)
	(segment
		(start 139.04341 -264.038842)
		(end 139.051792 -264.043668)
		(width 0.0889)
		(layer "In2.Cu")
		(net "M_I_CPU1_SB_CA<5>")
	)
	(segment
		(start 147.422362 -263.999472)
		(end 147.53717 -263.884664)
		(width 0.0889)
		(layer "In2.Cu")
		(net "M_I_CPU1_SB_CA<5>")
	)
	(segment
		(start 142.803372 -264.038842)
		(end 142.811754 -264.043668)
		(width 0.0889)
		(layer "In2.Cu")
		(net "M_I_CPU1_SB_CA<5>")
	)
	(segment
		(start 144.315688 -264.043922)
		(end 144.337532 -264.031476)
		(width 0.0889)
		(layer "In2.Cu")
		(net "M_I_CPU1_SB_CA<5>")
	)
	(segment
		(start 144.688306 -264.043668)
		(end 144.71777 -264.06094)
		(width 0.0889)
		(layer "In2.Cu")
		(net "M_I_CPU1_SB_CA<5>")
	)
	(segment
		(start 162.551618 -264.97407)
		(end 162.705288 -265.34491)
		(width 0.14478)
		(layer "In2.Cu")
		(net "M_I_CPU1_SB_CA<5>")
	)
	(arc
		(start 139.991846 -264.043668)
		(mid 140.274802 -264.119845)
		(end 140.557758 -264.043668)
		(width 0.0889)
		(layer "In2.Cu")
		(net "M_I_CPU1_SB_CA<5>")
	)
	(arc
		(start 142.811754 -264.043668)
		(mid 143.09471 -264.119845)
		(end 143.377666 -264.043668)
		(width 0.0889)
		(layer "In2.Cu")
		(net "M_I_CPU1_SB_CA<5>")
	)
	(arc
		(start 130.591814 -264.043668)
		(mid 130.87477 -264.119845)
		(end 131.157726 -264.043668)
		(width 0.0889)
		(layer "In2.Cu")
		(net "M_I_CPU1_SB_CA<5>")
	)
	(arc
		(start 135.866124 -264.038842)
		(mid 136.049632 -263.993348)
		(end 136.231884 -264.043668)
		(width 0.0889)
		(layer "In2.Cu")
		(net "M_I_CPU1_SB_CA<5>")
	)
	(arc
		(start 134.92607 -264.038842)
		(mid 135.109578 -263.993348)
		(end 135.29183 -264.043668)
		(width 0.0889)
		(layer "In2.Cu")
		(net "M_I_CPU1_SB_CA<5>")
	)
	(arc
		(start 142.437612 -264.043668)
		(mid 142.619863 -263.993318)
		(end 142.803372 -264.038842)
		(width 0.0889)
		(layer "In2.Cu")
		(net "M_I_CPU1_SB_CA<5>")
	)
	(arc
		(start 134.351776 -264.043668)
		(mid 134.634732 -264.119845)
		(end 134.917688 -264.043668)
		(width 0.0889)
		(layer "In2.Cu")
		(net "M_I_CPU1_SB_CA<5>")
	)
	(arc
		(start 144.71777 -264.06094)
		(mid 144.98919 -264.120617)
		(end 145.25625 -264.043668)
		(width 0.0889)
		(layer "In2.Cu")
		(net "M_I_CPU1_SB_CA<5>")
	)
	(arc
		(start 143.386048 -264.038842)
		(mid 143.569556 -263.993348)
		(end 143.751808 -264.043668)
		(width 0.0889)
		(layer "In2.Cu")
		(net "M_I_CPU1_SB_CA<5>")
	)
	(arc
		(start 139.051792 -264.043668)
		(mid 139.334748 -264.119845)
		(end 139.617704 -264.043668)
		(width 0.0889)
		(layer "In2.Cu")
		(net "M_I_CPU1_SB_CA<5>")
	)
	(arc
		(start 138.111738 -264.043668)
		(mid 138.394694 -264.119845)
		(end 138.67765 -264.043668)
		(width 0.0889)
		(layer "In2.Cu")
		(net "M_I_CPU1_SB_CA<5>")
	)
	(arc
		(start 131.531868 -264.043668)
		(mid 131.814824 -264.119845)
		(end 132.09778 -264.043668)
		(width 0.0889)
		(layer "In2.Cu")
		(net "M_I_CPU1_SB_CA<5>")
	)
	(arc
		(start 141.8717 -264.043668)
		(mid 142.154656 -264.119845)
		(end 142.437612 -264.043668)
		(width 0.0889)
		(layer "In2.Cu")
		(net "M_I_CPU1_SB_CA<5>")
	)
	(arc
		(start 133.411722 -264.043668)
		(mid 133.694678 -264.119845)
		(end 133.977634 -264.043668)
		(width 0.0889)
		(layer "In2.Cu")
		(net "M_I_CPU1_SB_CA<5>")
	)
	(arc
		(start 129.277618 -264.043668)
		(mid 129.459869 -263.993318)
		(end 129.643378 -264.038842)
		(width 0.0889)
		(layer "In2.Cu")
		(net "M_I_CPU1_SB_CA<5>")
	)
	(arc
		(start 136.231884 -264.043668)
		(mid 136.51484 -264.119845)
		(end 136.797796 -264.043668)
		(width 0.0889)
		(layer "In2.Cu")
		(net "M_I_CPU1_SB_CA<5>")
	)
	(arc
		(start 140.9319 -264.043668)
		(mid 141.214856 -264.119845)
		(end 141.497812 -264.043668)
		(width 0.0889)
		(layer "In2.Cu")
		(net "M_I_CPU1_SB_CA<5>")
	)
	(arc
		(start 140.56614 -264.038842)
		(mid 140.749648 -263.993348)
		(end 140.9319 -264.043668)
		(width 0.0889)
		(layer "In2.Cu")
		(net "M_I_CPU1_SB_CA<5>")
	)
	(arc
		(start 136.797796 -264.043668)
		(mid 136.98474 -263.993413)
		(end 137.171684 -264.043668)
		(width 0.0889)
		(layer "In2.Cu")
		(net "M_I_CPU1_SB_CA<5>")
	)
	(arc
		(start 135.29183 -264.043668)
		(mid 135.574786 -264.119845)
		(end 135.857742 -264.043668)
		(width 0.0889)
		(layer "In2.Cu")
		(net "M_I_CPU1_SB_CA<5>")
	)
	(arc
		(start 141.497812 -264.043668)
		(mid 141.684756 -263.993413)
		(end 141.8717 -264.043668)
		(width 0.0889)
		(layer "In2.Cu")
		(net "M_I_CPU1_SB_CA<5>")
	)
	(arc
		(start 131.166108 -264.038842)
		(mid 131.349616 -263.993348)
		(end 131.531868 -264.043668)
		(width 0.0889)
		(layer "In2.Cu")
		(net "M_I_CPU1_SB_CA<5>")
	)
	(arc
		(start 129.65176 -264.043668)
		(mid 129.934716 -264.119845)
		(end 130.217672 -264.043668)
		(width 0.0889)
		(layer "In2.Cu")
		(net "M_I_CPU1_SB_CA<5>")
	)
	(arc
		(start 143.751808 -264.043668)
		(mid 144.018738 -264.119617)
		(end 144.289526 -264.058908)
		(width 0.0889)
		(layer "In2.Cu")
		(net "M_I_CPU1_SB_CA<5>")
	)
	(arc
		(start 145.25625 -264.043668)
		(mid 145.313174 -264.016571)
		(end 145.373852 -263.999472)
		(width 0.0889)
		(layer "In2.Cu")
		(net "M_I_CPU1_SB_CA<5>")
	)
	(arc
		(start 132.106162 -264.038842)
		(mid 132.28967 -263.993348)
		(end 132.471922 -264.043668)
		(width 0.0889)
		(layer "In2.Cu")
		(net "M_I_CPU1_SB_CA<5>")
	)
	(arc
		(start 128.711706 -264.043668)
		(mid 128.994662 -264.119845)
		(end 129.277618 -264.043668)
		(width 0.0889)
		(layer "In2.Cu")
		(net "M_I_CPU1_SB_CA<5>")
	)
	(arc
		(start 133.977634 -264.043668)
		(mid 134.159885 -263.993318)
		(end 134.343394 -264.038842)
		(width 0.0889)
		(layer "In2.Cu")
		(net "M_I_CPU1_SB_CA<5>")
	)
	(arc
		(start 139.626086 -264.038842)
		(mid 139.809594 -263.993348)
		(end 139.991846 -264.043668)
		(width 0.0889)
		(layer "In2.Cu")
		(net "M_I_CPU1_SB_CA<5>")
	)
	(arc
		(start 128.39319 -264.017506)
		(mid 128.555379 -263.994771)
		(end 128.711706 -264.043668)
		(width 0.0889)
		(layer "In2.Cu")
		(net "M_I_CPU1_SB_CA<5>")
	)
	(arc
		(start 137.737596 -264.043668)
		(mid 137.919847 -263.993318)
		(end 138.103356 -264.038842)
		(width 0.0889)
		(layer "In2.Cu")
		(net "M_I_CPU1_SB_CA<5>")
	)
	(arc
		(start 144.337532 -264.031476)
		(mid 144.51446 -263.993648)
		(end 144.688306 -264.043668)
		(width 0.0889)
		(layer "In2.Cu")
		(net "M_I_CPU1_SB_CA<5>")
	)
	(arc
		(start 130.217672 -264.043668)
		(mid 130.399923 -263.993318)
		(end 130.583432 -264.038842)
		(width 0.0889)
		(layer "In2.Cu")
		(net "M_I_CPU1_SB_CA<5>")
	)
	(arc
		(start 137.171684 -264.043668)
		(mid 137.45464 -264.119845)
		(end 137.737596 -264.043668)
		(width 0.0889)
		(layer "In2.Cu")
		(net "M_I_CPU1_SB_CA<5>")
	)
	(arc
		(start 132.471922 -264.043668)
		(mid 132.754878 -264.119845)
		(end 133.037834 -264.043668)
		(width 0.0889)
		(layer "In2.Cu")
		(net "M_I_CPU1_SB_CA<5>")
	)
	(arc
		(start 138.67765 -264.043668)
		(mid 138.859901 -263.993318)
		(end 139.04341 -264.038842)
		(width 0.0889)
		(layer "In2.Cu")
		(net "M_I_CPU1_SB_CA<5>")
	)
	(arc
		(start 133.037834 -264.043668)
		(mid 133.224778 -263.993413)
		(end 133.411722 -264.043668)
		(width 0.0889)
		(layer "In2.Cu")
		(net "M_I_CPU1_SB_CA<5>")
	)
	(segment
		(start 127.58801 -263.290304)
		(end 128.054862 -263.556242)
		(width 0.10668)
		(layer "F.Cu")
		(net "M_I_CPU1_SB_CA<4>")
	)
	(segment
		(start 128.208786 -263.821672)
		(end 128.304798 -263.847072)
		(width 0.0889)
		(layer "In2.Cu")
		(net "M_I_CPU1_SB_CA<4>")
	)
	(segment
		(start 135.753348 -263.883648)
		(end 135.76173 -263.878822)
		(width 0.0889)
		(layer "In2.Cu")
		(net "M_I_CPU1_SB_CA<4>")
	)
	(segment
		(start 128.054862 -263.556242)
		(end 128.208786 -263.821672)
		(width 0.0889)
		(layer "In2.Cu")
		(net "M_I_CPU1_SB_CA<4>")
	)
	(segment
		(start 147.143978 -263.808972)
		(end 147.522946 -263.430004)
		(width 0.0889)
		(layer "In2.Cu")
		(net "M_I_CPU1_SB_CA<4>")
	)
	(segment
		(start 144.784318 -263.878822)
		(end 144.804892 -263.89076)
		(width 0.0889)
		(layer "In2.Cu")
		(net "M_I_CPU1_SB_CA<4>")
	)
	(segment
		(start 141.967712 -263.878822)
		(end 141.976094 -263.883648)
		(width 0.0889)
		(layer "In2.Cu")
		(net "M_I_CPU1_SB_CA<4>")
	)
	(segment
		(start 141.393418 -263.883648)
		(end 141.4018 -263.878822)
		(width 0.0889)
		(layer "In2.Cu")
		(net "M_I_CPU1_SB_CA<4>")
	)
	(segment
		(start 145.15973 -263.878822)
		(end 145.159984 -263.879076)
		(width 0.0889)
		(layer "In2.Cu")
		(net "M_I_CPU1_SB_CA<4>")
	)
	(segment
		(start 147.522946 -263.430004)
		(end 160.176464 -263.430004)
		(width 0.14478)
		(layer "In2.Cu")
		(net "M_I_CPU1_SB_CA<4>")
	)
	(segment
		(start 138.20775 -263.878822)
		(end 138.216132 -263.883648)
		(width 0.0889)
		(layer "In2.Cu")
		(net "M_I_CPU1_SB_CA<4>")
	)
	(segment
		(start 131.993386 -263.883648)
		(end 132.001768 -263.878822)
		(width 0.0889)
		(layer "In2.Cu")
		(net "M_I_CPU1_SB_CA<4>")
	)
	(segment
		(start 128.807718 -263.878822)
		(end 128.8161 -263.883648)
		(width 0.0889)
		(layer "In2.Cu")
		(net "M_I_CPU1_SB_CA<4>")
	)
	(segment
		(start 129.747772 -263.878822)
		(end 129.756154 -263.883648)
		(width 0.0889)
		(layer "In2.Cu")
		(net "M_I_CPU1_SB_CA<4>")
	)
	(segment
		(start 144.19707 -263.89203)
		(end 144.220438 -263.878568)
		(width 0.0889)
		(layer "In2.Cu")
		(net "M_I_CPU1_SB_CA<4>")
	)
	(segment
		(start 145.357342 -263.808972)
		(end 147.143978 -263.808972)
		(width 0.0889)
		(layer "In2.Cu")
		(net "M_I_CPU1_SB_CA<4>")
	)
	(segment
		(start 144.220438 -263.878568)
		(end 144.2466 -263.863582)
		(width 0.0889)
		(layer "In2.Cu")
		(net "M_I_CPU1_SB_CA<4>")
	)
	(segment
		(start 140.453364 -263.883648)
		(end 140.461746 -263.878822)
		(width 0.0889)
		(layer "In2.Cu")
		(net "M_I_CPU1_SB_CA<4>")
	)
	(segment
		(start 163.751006 -264.910316)
		(end 183.19115 -264.910316)
		(width 0.14478)
		(layer "In2.Cu")
		(net "M_I_CPU1_SB_CA<4>")
	)
	(segment
		(start 132.93344 -263.883648)
		(end 132.941822 -263.878822)
		(width 0.0889)
		(layer "In2.Cu")
		(net "M_I_CPU1_SB_CA<4>")
	)
	(segment
		(start 137.267696 -263.878822)
		(end 137.276078 -263.883648)
		(width 0.0889)
		(layer "In2.Cu")
		(net "M_I_CPU1_SB_CA<4>")
	)
	(segment
		(start 136.693402 -263.883648)
		(end 136.701784 -263.878822)
		(width 0.0889)
		(layer "In2.Cu")
		(net "M_I_CPU1_SB_CA<4>")
	)
	(segment
		(start 183.19115 -264.910316)
		(end 183.616092 -264.485374)
		(width 0.14478)
		(layer "In2.Cu")
		(net "M_I_CPU1_SB_CA<4>")
	)
	(segment
		(start 160.176464 -263.430004)
		(end 163.751006 -264.910316)
		(width 0.14478)
		(layer "In2.Cu")
		(net "M_I_CPU1_SB_CA<4>")
	)
	(segment
		(start 133.507734 -263.878822)
		(end 133.516116 -263.883648)
		(width 0.0889)
		(layer "In2.Cu")
		(net "M_I_CPU1_SB_CA<4>")
	)
	(arc
		(start 132.001768 -263.878822)
		(mid 132.284724 -263.802645)
		(end 132.56768 -263.878822)
		(width 0.0889)
		(layer "In2.Cu")
		(net "M_I_CPU1_SB_CA<4>")
	)
	(arc
		(start 137.641838 -263.878822)
		(mid 137.924794 -263.802645)
		(end 138.20775 -263.878822)
		(width 0.0889)
		(layer "In2.Cu")
		(net "M_I_CPU1_SB_CA<4>")
	)
	(arc
		(start 139.147804 -263.878822)
		(mid 139.334748 -263.929077)
		(end 139.521692 -263.878822)
		(width 0.0889)
		(layer "In2.Cu")
		(net "M_I_CPU1_SB_CA<4>")
	)
	(arc
		(start 128.304798 -263.847072)
		(mid 128.560006 -263.803595)
		(end 128.807718 -263.878822)
		(width 0.0889)
		(layer "In2.Cu")
		(net "M_I_CPU1_SB_CA<4>")
	)
	(arc
		(start 129.756154 -263.883648)
		(mid 129.939662 -263.929142)
		(end 130.121914 -263.878822)
		(width 0.0889)
		(layer "In2.Cu")
		(net "M_I_CPU1_SB_CA<4>")
	)
	(arc
		(start 142.907766 -263.878822)
		(mid 143.09471 -263.929077)
		(end 143.281654 -263.878822)
		(width 0.0889)
		(layer "In2.Cu")
		(net "M_I_CPU1_SB_CA<4>")
	)
	(arc
		(start 141.4018 -263.878822)
		(mid 141.684756 -263.802645)
		(end 141.967712 -263.878822)
		(width 0.0889)
		(layer "In2.Cu")
		(net "M_I_CPU1_SB_CA<4>")
	)
	(arc
		(start 128.8161 -263.883648)
		(mid 128.999608 -263.929142)
		(end 129.18186 -263.878822)
		(width 0.0889)
		(layer "In2.Cu")
		(net "M_I_CPU1_SB_CA<4>")
	)
	(arc
		(start 129.18186 -263.878822)
		(mid 129.464816 -263.802645)
		(end 129.747772 -263.878822)
		(width 0.0889)
		(layer "In2.Cu")
		(net "M_I_CPU1_SB_CA<4>")
	)
	(arc
		(start 130.687826 -263.878822)
		(mid 130.87477 -263.929077)
		(end 131.061714 -263.878822)
		(width 0.0889)
		(layer "In2.Cu")
		(net "M_I_CPU1_SB_CA<4>")
	)
	(arc
		(start 133.881876 -263.878822)
		(mid 134.164832 -263.802645)
		(end 134.447788 -263.878822)
		(width 0.0889)
		(layer "In2.Cu")
		(net "M_I_CPU1_SB_CA<4>")
	)
	(arc
		(start 135.387588 -263.878822)
		(mid 135.569839 -263.929172)
		(end 135.753348 -263.883648)
		(width 0.0889)
		(layer "In2.Cu")
		(net "M_I_CPU1_SB_CA<4>")
	)
	(arc
		(start 143.281654 -263.878822)
		(mid 143.56461 -263.802645)
		(end 143.847566 -263.878822)
		(width 0.0889)
		(layer "In2.Cu")
		(net "M_I_CPU1_SB_CA<4>")
	)
	(arc
		(start 136.701784 -263.878822)
		(mid 136.98474 -263.802645)
		(end 137.267696 -263.878822)
		(width 0.0889)
		(layer "In2.Cu")
		(net "M_I_CPU1_SB_CA<4>")
	)
	(arc
		(start 145.159984 -263.879076)
		(mid 145.255384 -263.834794)
		(end 145.357342 -263.808972)
		(width 0.0889)
		(layer "In2.Cu")
		(net "M_I_CPU1_SB_CA<4>")
	)
	(arc
		(start 134.821676 -263.878822)
		(mid 135.104632 -263.802645)
		(end 135.387588 -263.878822)
		(width 0.0889)
		(layer "In2.Cu")
		(net "M_I_CPU1_SB_CA<4>")
	)
	(arc
		(start 131.061714 -263.878822)
		(mid 131.34467 -263.802645)
		(end 131.627626 -263.878822)
		(width 0.0889)
		(layer "In2.Cu")
		(net "M_I_CPU1_SB_CA<4>")
	)
	(arc
		(start 140.461746 -263.878822)
		(mid 140.744702 -263.802645)
		(end 141.027658 -263.878822)
		(width 0.0889)
		(layer "In2.Cu")
		(net "M_I_CPU1_SB_CA<4>")
	)
	(arc
		(start 141.027658 -263.878822)
		(mid 141.209909 -263.929172)
		(end 141.393418 -263.883648)
		(width 0.0889)
		(layer "In2.Cu")
		(net "M_I_CPU1_SB_CA<4>")
	)
	(arc
		(start 141.976094 -263.883648)
		(mid 142.159602 -263.929142)
		(end 142.341854 -263.878822)
		(width 0.0889)
		(layer "In2.Cu")
		(net "M_I_CPU1_SB_CA<4>")
	)
	(arc
		(start 134.447788 -263.878822)
		(mid 134.634732 -263.929077)
		(end 134.821676 -263.878822)
		(width 0.0889)
		(layer "In2.Cu")
		(net "M_I_CPU1_SB_CA<4>")
	)
	(arc
		(start 142.341854 -263.878822)
		(mid 142.62481 -263.802645)
		(end 142.907766 -263.878822)
		(width 0.0889)
		(layer "In2.Cu")
		(net "M_I_CPU1_SB_CA<4>")
	)
	(arc
		(start 143.847566 -263.878822)
		(mid 144.020674 -263.928938)
		(end 144.19707 -263.89203)
		(width 0.0889)
		(layer "In2.Cu")
		(net "M_I_CPU1_SB_CA<4>")
	)
	(arc
		(start 133.516116 -263.883648)
		(mid 133.699624 -263.929142)
		(end 133.881876 -263.878822)
		(width 0.0889)
		(layer "In2.Cu")
		(net "M_I_CPU1_SB_CA<4>")
	)
	(arc
		(start 144.2466 -263.863582)
		(mid 144.517386 -263.802936)
		(end 144.784318 -263.878822)
		(width 0.0889)
		(layer "In2.Cu")
		(net "M_I_CPU1_SB_CA<4>")
	)
	(arc
		(start 137.276078 -263.883648)
		(mid 137.459586 -263.929142)
		(end 137.641838 -263.878822)
		(width 0.0889)
		(layer "In2.Cu")
		(net "M_I_CPU1_SB_CA<4>")
	)
	(arc
		(start 138.216132 -263.883648)
		(mid 138.39964 -263.929142)
		(end 138.581892 -263.878822)
		(width 0.0889)
		(layer "In2.Cu")
		(net "M_I_CPU1_SB_CA<4>")
	)
	(arc
		(start 132.941822 -263.878822)
		(mid 133.224778 -263.802645)
		(end 133.507734 -263.878822)
		(width 0.0889)
		(layer "In2.Cu")
		(net "M_I_CPU1_SB_CA<4>")
	)
	(arc
		(start 130.121914 -263.878822)
		(mid 130.40487 -263.802645)
		(end 130.687826 -263.878822)
		(width 0.0889)
		(layer "In2.Cu")
		(net "M_I_CPU1_SB_CA<4>")
	)
	(arc
		(start 144.804892 -263.89076)
		(mid 144.98382 -263.929637)
		(end 145.15973 -263.878822)
		(width 0.0889)
		(layer "In2.Cu")
		(net "M_I_CPU1_SB_CA<4>")
	)
	(arc
		(start 136.327642 -263.878822)
		(mid 136.509893 -263.929172)
		(end 136.693402 -263.883648)
		(width 0.0889)
		(layer "In2.Cu")
		(net "M_I_CPU1_SB_CA<4>")
	)
	(arc
		(start 132.56768 -263.878822)
		(mid 132.749931 -263.929172)
		(end 132.93344 -263.883648)
		(width 0.0889)
		(layer "In2.Cu")
		(net "M_I_CPU1_SB_CA<4>")
	)
	(arc
		(start 131.627626 -263.878822)
		(mid 131.809877 -263.929172)
		(end 131.993386 -263.883648)
		(width 0.0889)
		(layer "In2.Cu")
		(net "M_I_CPU1_SB_CA<4>")
	)
	(arc
		(start 135.76173 -263.878822)
		(mid 136.044686 -263.802645)
		(end 136.327642 -263.878822)
		(width 0.0889)
		(layer "In2.Cu")
		(net "M_I_CPU1_SB_CA<4>")
	)
	(arc
		(start 140.087604 -263.878822)
		(mid 140.269855 -263.929172)
		(end 140.453364 -263.883648)
		(width 0.0889)
		(layer "In2.Cu")
		(net "M_I_CPU1_SB_CA<4>")
	)
	(arc
		(start 138.581892 -263.878822)
		(mid 138.864848 -263.802645)
		(end 139.147804 -263.878822)
		(width 0.0889)
		(layer "In2.Cu")
		(net "M_I_CPU1_SB_CA<4>")
	)
	(arc
		(start 139.521692 -263.878822)
		(mid 139.804648 -263.802645)
		(end 140.087604 -263.878822)
		(width 0.0889)
		(layer "In2.Cu")
		(net "M_I_CPU1_SB_CA<4>")
	)
	(segment
		(start 129.467864 -263.290304)
		(end 129.934716 -263.556242)
		(width 0.10668)
		(layer "F.Cu")
		(net "M_I_CPU1_SB_CA<3>")
	)
	(segment
		(start 167.065706 -264.060432)
		(end 167.371014 -264.060432)
		(width 0.14478)
		(layer "In2.Cu")
		(net "M_I_CPU1_SB_CA<3>")
	)
	(segment
		(start 175.508412 -263.755886)
		(end 175.812958 -264.060432)
		(width 0.14478)
		(layer "In2.Cu")
		(net "M_I_CPU1_SB_CA<3>")
	)
	(segment
		(start 133.507734 -263.233662)
		(end 133.516116 -263.228836)
		(width 0.0889)
		(layer "In2.Cu")
		(net "M_I_CPU1_SB_CA<3>")
	)
	(segment
		(start 166.81958 -263.814306)
		(end 167.065706 -264.060432)
		(width 0.14478)
		(layer "In2.Cu")
		(net "M_I_CPU1_SB_CA<3>")
	)
	(segment
		(start 169.740834 -264.060432)
		(end 169.980102 -264.060432)
		(width 0.14478)
		(layer "In2.Cu")
		(net "M_I_CPU1_SB_CA<3>")
	)
	(segment
		(start 175.261524 -263.755886)
		(end 175.508412 -263.755886)
		(width 0.14478)
		(layer "In2.Cu")
		(net "M_I_CPU1_SB_CA<3>")
	)
	(segment
		(start 136.693402 -263.228836)
		(end 136.701784 -263.233662)
		(width 0.0889)
		(layer "In2.Cu")
		(net "M_I_CPU1_SB_CA<3>")
	)
	(segment
		(start 173.85411 -264.060432)
		(end 174.158656 -263.755886)
		(width 0.14478)
		(layer "In2.Cu")
		(net "M_I_CPU1_SB_CA<3>")
	)
	(segment
		(start 165.962838 -264.060432)
		(end 166.268146 -264.060432)
		(width 0.14478)
		(layer "In2.Cu")
		(net "M_I_CPU1_SB_CA<3>")
	)
	(segment
		(start 173.302676 -263.755886)
		(end 173.607222 -264.060432)
		(width 0.14478)
		(layer "In2.Cu")
		(net "M_I_CPU1_SB_CA<3>")
	)
	(segment
		(start 137.267696 -263.233662)
		(end 137.276078 -263.228836)
		(width 0.0889)
		(layer "In2.Cu")
		(net "M_I_CPU1_SB_CA<3>")
	)
	(segment
		(start 144.773904 -263.242298)
		(end 144.788636 -263.233662)
		(width 0.0889)
		(layer "In2.Cu")
		(net "M_I_CPU1_SB_CA<3>")
	)
	(segment
		(start 161.753042 -263.548622)
		(end 162.183064 -263.37006)
		(width 0.14478)
		(layer "In2.Cu")
		(net "M_I_CPU1_SB_CA<3>")
	)
	(segment
		(start 173.055788 -263.755886)
		(end 173.302676 -263.755886)
		(width 0.14478)
		(layer "In2.Cu")
		(net "M_I_CPU1_SB_CA<3>")
	)
	(segment
		(start 147.583906 -262.924544)
		(end 147.634706 -262.975344)
		(width 0.14478)
		(layer "In2.Cu")
		(net "M_I_CPU1_SB_CA<3>")
	)
	(segment
		(start 168.877234 -264.060432)
		(end 169.1894 -263.748266)
		(width 0.14478)
		(layer "In2.Cu")
		(net "M_I_CPU1_SB_CA<3>")
	)
	(segment
		(start 135.753348 -263.228836)
		(end 135.76173 -263.233662)
		(width 0.0889)
		(layer "In2.Cu")
		(net "M_I_CPU1_SB_CA<3>")
	)
	(segment
		(start 165.165278 -264.060432)
		(end 165.411404 -263.814306)
		(width 0.14478)
		(layer "In2.Cu")
		(net "M_I_CPU1_SB_CA<3>")
	)
	(segment
		(start 169.428668 -263.748266)
		(end 169.740834 -264.060432)
		(width 0.14478)
		(layer "In2.Cu")
		(net "M_I_CPU1_SB_CA<3>")
	)
	(segment
		(start 146.523964 -262.924544)
		(end 147.583906 -262.924544)
		(width 0.0889)
		(layer "In2.Cu")
		(net "M_I_CPU1_SB_CA<3>")
	)
	(segment
		(start 170.531536 -263.748266)
		(end 170.843702 -264.060432)
		(width 0.14478)
		(layer "In2.Cu")
		(net "M_I_CPU1_SB_CA<3>")
	)
	(segment
		(start 167.922448 -263.814306)
		(end 168.168574 -264.060432)
		(width 0.14478)
		(layer "In2.Cu")
		(net "M_I_CPU1_SB_CA<3>")
	)
	(segment
		(start 138.20775 -263.233662)
		(end 138.216132 -263.228836)
		(width 0.0889)
		(layer "In2.Cu")
		(net "M_I_CPU1_SB_CA<3>")
	)
	(segment
		(start 169.1894 -263.748266)
		(end 169.428668 -263.748266)
		(width 0.14478)
		(layer "In2.Cu")
		(net "M_I_CPU1_SB_CA<3>")
	)
	(segment
		(start 173.607222 -264.060432)
		(end 173.85411 -264.060432)
		(width 0.14478)
		(layer "In2.Cu")
		(net "M_I_CPU1_SB_CA<3>")
	)
	(segment
		(start 172.751242 -264.060432)
		(end 173.055788 -263.755886)
		(width 0.14478)
		(layer "In2.Cu")
		(net "M_I_CPU1_SB_CA<3>")
	)
	(segment
		(start 145.148554 -263.226042)
		(end 145.16227 -263.233916)
		(width 0.0889)
		(layer "In2.Cu")
		(net "M_I_CPU1_SB_CA<3>")
	)
	(segment
		(start 162.989006 -264.060432)
		(end 165.165278 -264.060432)
		(width 0.14478)
		(layer "In2.Cu")
		(net "M_I_CPU1_SB_CA<3>")
	)
	(segment
		(start 174.956978 -264.060432)
		(end 175.261524 -263.755886)
		(width 0.14478)
		(layer "In2.Cu")
		(net "M_I_CPU1_SB_CA<3>")
	)
	(segment
		(start 174.158656 -263.755886)
		(end 174.405544 -263.755886)
		(width 0.14478)
		(layer "In2.Cu")
		(net "M_I_CPU1_SB_CA<3>")
	)
	(segment
		(start 177.099214 -264.060432)
		(end 177.396902 -263.762744)
		(width 0.14478)
		(layer "In2.Cu")
		(net "M_I_CPU1_SB_CA<3>")
	)
	(segment
		(start 147.634706 -262.975344)
		(end 160.36925 -262.975344)
		(width 0.14478)
		(layer "In2.Cu")
		(net "M_I_CPU1_SB_CA<3>")
	)
	(segment
		(start 145.670778 -263.26973)
		(end 146.523964 -262.924544)
		(width 0.0889)
		(layer "In2.Cu")
		(net "M_I_CPU1_SB_CA<3>")
	)
	(segment
		(start 162.183064 -263.37006)
		(end 162.379152 -263.451086)
		(width 0.14478)
		(layer "In2.Cu")
		(net "M_I_CPU1_SB_CA<3>")
	)
	(segment
		(start 174.405544 -263.755886)
		(end 174.71009 -264.060432)
		(width 0.14478)
		(layer "In2.Cu")
		(net "M_I_CPU1_SB_CA<3>")
	)
	(segment
		(start 174.71009 -264.060432)
		(end 174.956978 -264.060432)
		(width 0.14478)
		(layer "In2.Cu")
		(net "M_I_CPU1_SB_CA<3>")
	)
	(segment
		(start 140.453364 -263.228836)
		(end 140.461746 -263.233662)
		(width 0.0889)
		(layer "In2.Cu")
		(net "M_I_CPU1_SB_CA<3>")
	)
	(segment
		(start 177.658014 -263.762744)
		(end 177.955702 -264.060432)
		(width 0.14478)
		(layer "In2.Cu")
		(net "M_I_CPU1_SB_CA<3>")
	)
	(segment
		(start 141.967712 -263.233662)
		(end 141.976094 -263.228836)
		(width 0.0889)
		(layer "In2.Cu")
		(net "M_I_CPU1_SB_CA<3>")
	)
	(segment
		(start 160.36925 -262.975344)
		(end 160.720278 -263.120886)
		(width 0.14478)
		(layer "In2.Cu")
		(net "M_I_CPU1_SB_CA<3>")
	)
	(segment
		(start 166.514272 -263.814306)
		(end 166.81958 -263.814306)
		(width 0.14478)
		(layer "In2.Cu")
		(net "M_I_CPU1_SB_CA<3>")
	)
	(segment
		(start 166.268146 -264.060432)
		(end 166.514272 -263.814306)
		(width 0.14478)
		(layer "In2.Cu")
		(net "M_I_CPU1_SB_CA<3>")
	)
	(segment
		(start 165.411404 -263.814306)
		(end 165.716712 -263.814306)
		(width 0.14478)
		(layer "In2.Cu")
		(net "M_I_CPU1_SB_CA<3>")
	)
	(segment
		(start 170.843702 -264.060432)
		(end 172.751242 -264.060432)
		(width 0.14478)
		(layer "In2.Cu")
		(net "M_I_CPU1_SB_CA<3>")
	)
	(segment
		(start 167.61714 -263.814306)
		(end 167.922448 -263.814306)
		(width 0.14478)
		(layer "In2.Cu")
		(net "M_I_CPU1_SB_CA<3>")
	)
	(segment
		(start 129.934716 -263.556242)
		(end 129.780792 -263.290812)
		(width 0.0889)
		(layer "In2.Cu")
		(net "M_I_CPU1_SB_CA<3>")
	)
	(segment
		(start 145.16227 -263.233916)
		(end 145.178018 -263.24306)
		(width 0.0889)
		(layer "In2.Cu")
		(net "M_I_CPU1_SB_CA<3>")
	)
	(segment
		(start 179.090828 -264.060432)
		(end 179.516024 -263.635236)
		(width 0.14478)
		(layer "In2.Cu")
		(net "M_I_CPU1_SB_CA<3>")
	)
	(segment
		(start 129.780792 -263.290812)
		(end 129.803144 -263.2075)
		(width 0.0889)
		(layer "In2.Cu")
		(net "M_I_CPU1_SB_CA<3>")
	)
	(segment
		(start 141.393418 -263.228836)
		(end 141.4018 -263.233662)
		(width 0.0889)
		(layer "In2.Cu")
		(net "M_I_CPU1_SB_CA<3>")
	)
	(segment
		(start 162.379152 -263.451086)
		(end 162.55746 -263.881616)
		(width 0.14478)
		(layer "In2.Cu")
		(net "M_I_CPU1_SB_CA<3>")
	)
	(segment
		(start 169.980102 -264.060432)
		(end 170.292268 -263.748266)
		(width 0.14478)
		(layer "In2.Cu")
		(net "M_I_CPU1_SB_CA<3>")
	)
	(segment
		(start 167.371014 -264.060432)
		(end 167.61714 -263.814306)
		(width 0.14478)
		(layer "In2.Cu")
		(net "M_I_CPU1_SB_CA<3>")
	)
	(segment
		(start 175.812958 -264.060432)
		(end 177.099214 -264.060432)
		(width 0.14478)
		(layer "In2.Cu")
		(net "M_I_CPU1_SB_CA<3>")
	)
	(segment
		(start 165.716712 -263.814306)
		(end 165.962838 -264.060432)
		(width 0.14478)
		(layer "In2.Cu")
		(net "M_I_CPU1_SB_CA<3>")
	)
	(segment
		(start 143.847566 -263.233662)
		(end 143.855948 -263.228836)
		(width 0.0889)
		(layer "In2.Cu")
		(net "M_I_CPU1_SB_CA<3>")
	)
	(segment
		(start 177.955702 -264.060432)
		(end 179.090828 -264.060432)
		(width 0.14478)
		(layer "In2.Cu")
		(net "M_I_CPU1_SB_CA<3>")
	)
	(segment
		(start 170.292268 -263.748266)
		(end 170.531536 -263.748266)
		(width 0.14478)
		(layer "In2.Cu")
		(net "M_I_CPU1_SB_CA<3>")
	)
	(segment
		(start 168.168574 -264.060432)
		(end 168.877234 -264.060432)
		(width 0.14478)
		(layer "In2.Cu")
		(net "M_I_CPU1_SB_CA<3>")
	)
	(segment
		(start 177.396902 -263.762744)
		(end 177.658014 -263.762744)
		(width 0.14478)
		(layer "In2.Cu")
		(net "M_I_CPU1_SB_CA<3>")
	)
	(segment
		(start 161.524696 -263.454134)
		(end 161.753042 -263.548622)
		(width 0.14478)
		(layer "In2.Cu")
		(net "M_I_CPU1_SB_CA<3>")
	)
	(segment
		(start 161.393632 -263.137396)
		(end 161.524696 -263.454134)
		(width 0.14478)
		(layer "In2.Cu")
		(net "M_I_CPU1_SB_CA<3>")
	)
	(segment
		(start 131.993386 -263.228836)
		(end 132.001768 -263.233662)
		(width 0.0889)
		(layer "In2.Cu")
		(net "M_I_CPU1_SB_CA<3>")
	)
	(segment
		(start 160.720278 -263.120886)
		(end 161.036762 -262.989568)
		(width 0.14478)
		(layer "In2.Cu")
		(net "M_I_CPU1_SB_CA<3>")
	)
	(segment
		(start 162.55746 -263.881616)
		(end 162.989006 -264.060432)
		(width 0.14478)
		(layer "In2.Cu")
		(net "M_I_CPU1_SB_CA<3>")
	)
	(segment
		(start 132.93344 -263.228836)
		(end 132.941822 -263.233662)
		(width 0.0889)
		(layer "In2.Cu")
		(net "M_I_CPU1_SB_CA<3>")
	)
	(segment
		(start 161.036762 -262.989568)
		(end 161.393632 -263.137396)
		(width 0.14478)
		(layer "In2.Cu")
		(net "M_I_CPU1_SB_CA<3>")
	)
	(arc
		(start 131.627626 -263.233662)
		(mid 131.809877 -263.183312)
		(end 131.993386 -263.228836)
		(width 0.0889)
		(layer "In2.Cu")
		(net "M_I_CPU1_SB_CA<3>")
	)
	(arc
		(start 134.447788 -263.233662)
		(mid 134.634732 -263.183407)
		(end 134.821676 -263.233662)
		(width 0.0889)
		(layer "In2.Cu")
		(net "M_I_CPU1_SB_CA<3>")
	)
	(arc
		(start 130.121914 -263.233662)
		(mid 130.40487 -263.309839)
		(end 130.687826 -263.233662)
		(width 0.0889)
		(layer "In2.Cu")
		(net "M_I_CPU1_SB_CA<3>")
	)
	(arc
		(start 142.341854 -263.233662)
		(mid 142.62481 -263.309839)
		(end 142.907766 -263.233662)
		(width 0.0889)
		(layer "In2.Cu")
		(net "M_I_CPU1_SB_CA<3>")
	)
	(arc
		(start 140.461746 -263.233662)
		(mid 140.744702 -263.309839)
		(end 141.027658 -263.233662)
		(width 0.0889)
		(layer "In2.Cu")
		(net "M_I_CPU1_SB_CA<3>")
	)
	(arc
		(start 144.222216 -263.233662)
		(mid 144.496922 -263.310026)
		(end 144.773904 -263.242298)
		(width 0.0889)
		(layer "In2.Cu")
		(net "M_I_CPU1_SB_CA<3>")
	)
	(arc
		(start 137.276078 -263.228836)
		(mid 137.459586 -263.183342)
		(end 137.641838 -263.233662)
		(width 0.0889)
		(layer "In2.Cu")
		(net "M_I_CPU1_SB_CA<3>")
	)
	(arc
		(start 144.788636 -263.233662)
		(mid 144.967623 -263.183492)
		(end 145.148554 -263.226042)
		(width 0.0889)
		(layer "In2.Cu")
		(net "M_I_CPU1_SB_CA<3>")
	)
	(arc
		(start 141.4018 -263.233662)
		(mid 141.684756 -263.309839)
		(end 141.967712 -263.233662)
		(width 0.0889)
		(layer "In2.Cu")
		(net "M_I_CPU1_SB_CA<3>")
	)
	(arc
		(start 129.803144 -263.2075)
		(mid 129.965476 -263.184682)
		(end 130.121914 -263.233662)
		(width 0.0889)
		(layer "In2.Cu")
		(net "M_I_CPU1_SB_CA<3>")
	)
	(arc
		(start 139.147804 -263.233662)
		(mid 139.334748 -263.183407)
		(end 139.521692 -263.233662)
		(width 0.0889)
		(layer "In2.Cu")
		(net "M_I_CPU1_SB_CA<3>")
	)
	(arc
		(start 137.641838 -263.233662)
		(mid 137.924794 -263.309839)
		(end 138.20775 -263.233662)
		(width 0.0889)
		(layer "In2.Cu")
		(net "M_I_CPU1_SB_CA<3>")
	)
	(arc
		(start 131.061714 -263.233662)
		(mid 131.34467 -263.309839)
		(end 131.627626 -263.233662)
		(width 0.0889)
		(layer "In2.Cu")
		(net "M_I_CPU1_SB_CA<3>")
	)
	(arc
		(start 132.56768 -263.233662)
		(mid 132.749931 -263.183312)
		(end 132.93344 -263.228836)
		(width 0.0889)
		(layer "In2.Cu")
		(net "M_I_CPU1_SB_CA<3>")
	)
	(arc
		(start 145.178018 -263.24306)
		(mid 145.421427 -263.3113)
		(end 145.670778 -263.26973)
		(width 0.0889)
		(layer "In2.Cu")
		(net "M_I_CPU1_SB_CA<3>")
	)
	(arc
		(start 142.907766 -263.233662)
		(mid 143.09471 -263.183407)
		(end 143.281654 -263.233662)
		(width 0.0889)
		(layer "In2.Cu")
		(net "M_I_CPU1_SB_CA<3>")
	)
	(arc
		(start 138.581892 -263.233662)
		(mid 138.864848 -263.309839)
		(end 139.147804 -263.233662)
		(width 0.0889)
		(layer "In2.Cu")
		(net "M_I_CPU1_SB_CA<3>")
	)
	(arc
		(start 132.001768 -263.233662)
		(mid 132.284724 -263.309839)
		(end 132.56768 -263.233662)
		(width 0.0889)
		(layer "In2.Cu")
		(net "M_I_CPU1_SB_CA<3>")
	)
	(arc
		(start 134.821676 -263.233662)
		(mid 135.104632 -263.309839)
		(end 135.387588 -263.233662)
		(width 0.0889)
		(layer "In2.Cu")
		(net "M_I_CPU1_SB_CA<3>")
	)
	(arc
		(start 133.516116 -263.228836)
		(mid 133.699624 -263.183342)
		(end 133.881876 -263.233662)
		(width 0.0889)
		(layer "In2.Cu")
		(net "M_I_CPU1_SB_CA<3>")
	)
	(arc
		(start 140.087604 -263.233662)
		(mid 140.269855 -263.183312)
		(end 140.453364 -263.228836)
		(width 0.0889)
		(layer "In2.Cu")
		(net "M_I_CPU1_SB_CA<3>")
	)
	(arc
		(start 132.941822 -263.233662)
		(mid 133.224778 -263.309839)
		(end 133.507734 -263.233662)
		(width 0.0889)
		(layer "In2.Cu")
		(net "M_I_CPU1_SB_CA<3>")
	)
	(arc
		(start 143.855948 -263.228836)
		(mid 144.03971 -263.18322)
		(end 144.222216 -263.233662)
		(width 0.0889)
		(layer "In2.Cu")
		(net "M_I_CPU1_SB_CA<3>")
	)
	(arc
		(start 135.76173 -263.233662)
		(mid 136.044686 -263.309839)
		(end 136.327642 -263.233662)
		(width 0.0889)
		(layer "In2.Cu")
		(net "M_I_CPU1_SB_CA<3>")
	)
	(arc
		(start 135.387588 -263.233662)
		(mid 135.569839 -263.183312)
		(end 135.753348 -263.228836)
		(width 0.0889)
		(layer "In2.Cu")
		(net "M_I_CPU1_SB_CA<3>")
	)
	(arc
		(start 136.701784 -263.233662)
		(mid 136.98474 -263.309839)
		(end 137.267696 -263.233662)
		(width 0.0889)
		(layer "In2.Cu")
		(net "M_I_CPU1_SB_CA<3>")
	)
	(arc
		(start 133.881876 -263.233662)
		(mid 134.164832 -263.309839)
		(end 134.447788 -263.233662)
		(width 0.0889)
		(layer "In2.Cu")
		(net "M_I_CPU1_SB_CA<3>")
	)
	(arc
		(start 141.027658 -263.233662)
		(mid 141.209909 -263.183312)
		(end 141.393418 -263.228836)
		(width 0.0889)
		(layer "In2.Cu")
		(net "M_I_CPU1_SB_CA<3>")
	)
	(arc
		(start 136.327642 -263.233662)
		(mid 136.509893 -263.183312)
		(end 136.693402 -263.228836)
		(width 0.0889)
		(layer "In2.Cu")
		(net "M_I_CPU1_SB_CA<3>")
	)
	(arc
		(start 143.281654 -263.233662)
		(mid 143.56461 -263.309839)
		(end 143.847566 -263.233662)
		(width 0.0889)
		(layer "In2.Cu")
		(net "M_I_CPU1_SB_CA<3>")
	)
	(arc
		(start 139.521692 -263.233662)
		(mid 139.804648 -263.309839)
		(end 140.087604 -263.233662)
		(width 0.0889)
		(layer "In2.Cu")
		(net "M_I_CPU1_SB_CA<3>")
	)
	(arc
		(start 130.687826 -263.233662)
		(mid 130.87477 -263.183407)
		(end 131.061714 -263.233662)
		(width 0.0889)
		(layer "In2.Cu")
		(net "M_I_CPU1_SB_CA<3>")
	)
	(arc
		(start 138.216132 -263.228836)
		(mid 138.39964 -263.183342)
		(end 138.581892 -263.233662)
		(width 0.0889)
		(layer "In2.Cu")
		(net "M_I_CPU1_SB_CA<3>")
	)
	(arc
		(start 141.976094 -263.228836)
		(mid 142.159602 -263.183342)
		(end 142.341854 -263.233662)
		(width 0.0889)
		(layer "In2.Cu")
		(net "M_I_CPU1_SB_CA<3>")
	)
	(segment
		(start 128.997964 -262.480298)
		(end 129.464816 -262.746236)
		(width 0.10668)
		(layer "F.Cu")
		(net "M_I_CPU1_SB_CA<2>")
	)
	(segment
		(start 129.464816 -262.746236)
		(end 129.61874 -263.011666)
		(width 0.0889)
		(layer "In2.Cu")
		(net "M_I_CPU1_SB_CA<2>")
	)
	(segment
		(start 183.19115 -263.210294)
		(end 183.616092 -262.785352)
		(width 0.14478)
		(layer "In2.Cu")
		(net "M_I_CPU1_SB_CA<2>")
	)
	(segment
		(start 131.157726 -263.068816)
		(end 131.166108 -263.073642)
		(width 0.0889)
		(layer "In2.Cu")
		(net "M_I_CPU1_SB_CA<2>")
	)
	(segment
		(start 130.583432 -263.073642)
		(end 130.591814 -263.068816)
		(width 0.0889)
		(layer "In2.Cu")
		(net "M_I_CPU1_SB_CA<2>")
	)
	(segment
		(start 132.09778 -263.068816)
		(end 132.106162 -263.073642)
		(width 0.0889)
		(layer "In2.Cu")
		(net "M_I_CPU1_SB_CA<2>")
	)
	(segment
		(start 143.751808 -263.068816)
		(end 143.76654 -263.06018)
		(width 0.0889)
		(layer "In2.Cu")
		(net "M_I_CPU1_SB_CA<2>")
	)
	(segment
		(start 147.33016 -262.721344)
		(end 147.53082 -262.520684)
		(width 0.0889)
		(layer "In2.Cu")
		(net "M_I_CPU1_SB_CA<2>")
	)
	(segment
		(start 145.25244 -263.06526)
		(end 145.258028 -263.068562)
		(width 0.0889)
		(layer "In2.Cu")
		(net "M_I_CPU1_SB_CA<2>")
	)
	(segment
		(start 134.917688 -263.068816)
		(end 134.92607 -263.073642)
		(width 0.0889)
		(layer "In2.Cu")
		(net "M_I_CPU1_SB_CA<2>")
	)
	(segment
		(start 134.343394 -263.073642)
		(end 134.351776 -263.068816)
		(width 0.0889)
		(layer "In2.Cu")
		(net "M_I_CPU1_SB_CA<2>")
	)
	(segment
		(start 139.617704 -263.068816)
		(end 139.626086 -263.073642)
		(width 0.0889)
		(layer "In2.Cu")
		(net "M_I_CPU1_SB_CA<2>")
	)
	(segment
		(start 147.53082 -262.520684)
		(end 161.79927 -262.520684)
		(width 0.14478)
		(layer "In2.Cu")
		(net "M_I_CPU1_SB_CA<2>")
	)
	(segment
		(start 146.440652 -262.721344)
		(end 147.33016 -262.721344)
		(width 0.0889)
		(layer "In2.Cu")
		(net "M_I_CPU1_SB_CA<2>")
	)
	(segment
		(start 129.61874 -263.011666)
		(end 129.714752 -263.037066)
		(width 0.0889)
		(layer "In2.Cu")
		(net "M_I_CPU1_SB_CA<2>")
	)
	(segment
		(start 139.04341 -263.073642)
		(end 139.051792 -263.068816)
		(width 0.0889)
		(layer "In2.Cu")
		(net "M_I_CPU1_SB_CA<2>")
	)
	(segment
		(start 145.258028 -263.068562)
		(end 145.276316 -263.078976)
		(width 0.0889)
		(layer "In2.Cu")
		(net "M_I_CPU1_SB_CA<2>")
	)
	(segment
		(start 140.557758 -263.068816)
		(end 140.56614 -263.073642)
		(width 0.0889)
		(layer "In2.Cu")
		(net "M_I_CPU1_SB_CA<2>")
	)
	(segment
		(start 145.63217 -263.068816)
		(end 146.440652 -262.721344)
		(width 0.0889)
		(layer "In2.Cu")
		(net "M_I_CPU1_SB_CA<2>")
	)
	(segment
		(start 138.103356 -263.073642)
		(end 138.111738 -263.068816)
		(width 0.0889)
		(layer "In2.Cu")
		(net "M_I_CPU1_SB_CA<2>")
	)
	(segment
		(start 143.377666 -263.068816)
		(end 143.386048 -263.073642)
		(width 0.0889)
		(layer "In2.Cu")
		(net "M_I_CPU1_SB_CA<2>")
	)
	(segment
		(start 163.464494 -263.210294)
		(end 183.19115 -263.210294)
		(width 0.14478)
		(layer "In2.Cu")
		(net "M_I_CPU1_SB_CA<2>")
	)
	(segment
		(start 135.857742 -263.068816)
		(end 135.866124 -263.073642)
		(width 0.0889)
		(layer "In2.Cu")
		(net "M_I_CPU1_SB_CA<2>")
	)
	(segment
		(start 144.68094 -263.075674)
		(end 144.692624 -263.068816)
		(width 0.0889)
		(layer "In2.Cu")
		(net "M_I_CPU1_SB_CA<2>")
	)
	(segment
		(start 161.79927 -262.520684)
		(end 163.464494 -263.210294)
		(width 0.14478)
		(layer "In2.Cu")
		(net "M_I_CPU1_SB_CA<2>")
	)
	(segment
		(start 142.803372 -263.073642)
		(end 142.811754 -263.068816)
		(width 0.0889)
		(layer "In2.Cu")
		(net "M_I_CPU1_SB_CA<2>")
	)
	(arc
		(start 139.051792 -263.068816)
		(mid 139.334748 -262.992639)
		(end 139.617704 -263.068816)
		(width 0.0889)
		(layer "In2.Cu")
		(net "M_I_CPU1_SB_CA<2>")
	)
	(arc
		(start 132.106162 -263.073642)
		(mid 132.28967 -263.119136)
		(end 132.471922 -263.068816)
		(width 0.0889)
		(layer "In2.Cu")
		(net "M_I_CPU1_SB_CA<2>")
	)
	(arc
		(start 143.386048 -263.073642)
		(mid 143.569556 -263.119136)
		(end 143.751808 -263.068816)
		(width 0.0889)
		(layer "In2.Cu")
		(net "M_I_CPU1_SB_CA<2>")
	)
	(arc
		(start 138.111738 -263.068816)
		(mid 138.394694 -262.992639)
		(end 138.67765 -263.068816)
		(width 0.0889)
		(layer "In2.Cu")
		(net "M_I_CPU1_SB_CA<2>")
	)
	(arc
		(start 142.811754 -263.068816)
		(mid 143.09471 -262.992639)
		(end 143.377666 -263.068816)
		(width 0.0889)
		(layer "In2.Cu")
		(net "M_I_CPU1_SB_CA<2>")
	)
	(arc
		(start 143.76654 -263.06018)
		(mid 144.043523 -262.992376)
		(end 144.318228 -263.068816)
		(width 0.0889)
		(layer "In2.Cu")
		(net "M_I_CPU1_SB_CA<2>")
	)
	(arc
		(start 131.166108 -263.073642)
		(mid 131.349616 -263.119136)
		(end 131.531868 -263.068816)
		(width 0.0889)
		(layer "In2.Cu")
		(net "M_I_CPU1_SB_CA<2>")
	)
	(arc
		(start 129.714752 -263.037066)
		(mid 129.96996 -262.993589)
		(end 130.217672 -263.068816)
		(width 0.0889)
		(layer "In2.Cu")
		(net "M_I_CPU1_SB_CA<2>")
	)
	(arc
		(start 141.8717 -263.068816)
		(mid 142.154656 -262.992639)
		(end 142.437612 -263.068816)
		(width 0.0889)
		(layer "In2.Cu")
		(net "M_I_CPU1_SB_CA<2>")
	)
	(arc
		(start 137.737596 -263.068816)
		(mid 137.919847 -263.119166)
		(end 138.103356 -263.073642)
		(width 0.0889)
		(layer "In2.Cu")
		(net "M_I_CPU1_SB_CA<2>")
	)
	(arc
		(start 139.991846 -263.068816)
		(mid 140.274802 -262.992639)
		(end 140.557758 -263.068816)
		(width 0.0889)
		(layer "In2.Cu")
		(net "M_I_CPU1_SB_CA<2>")
	)
	(arc
		(start 132.471922 -263.068816)
		(mid 132.754878 -262.992639)
		(end 133.037834 -263.068816)
		(width 0.0889)
		(layer "In2.Cu")
		(net "M_I_CPU1_SB_CA<2>")
	)
	(arc
		(start 142.437612 -263.068816)
		(mid 142.619863 -263.119166)
		(end 142.803372 -263.073642)
		(width 0.0889)
		(layer "In2.Cu")
		(net "M_I_CPU1_SB_CA<2>")
	)
	(arc
		(start 144.318228 -263.068816)
		(mid 144.498686 -263.11926)
		(end 144.68094 -263.075674)
		(width 0.0889)
		(layer "In2.Cu")
		(net "M_I_CPU1_SB_CA<2>")
	)
	(arc
		(start 133.411722 -263.068816)
		(mid 133.694678 -262.992639)
		(end 133.977634 -263.068816)
		(width 0.0889)
		(layer "In2.Cu")
		(net "M_I_CPU1_SB_CA<2>")
	)
	(arc
		(start 133.977634 -263.068816)
		(mid 134.159885 -263.119166)
		(end 134.343394 -263.073642)
		(width 0.0889)
		(layer "In2.Cu")
		(net "M_I_CPU1_SB_CA<2>")
	)
	(arc
		(start 135.866124 -263.073642)
		(mid 136.049632 -263.119136)
		(end 136.231884 -263.068816)
		(width 0.0889)
		(layer "In2.Cu")
		(net "M_I_CPU1_SB_CA<2>")
	)
	(arc
		(start 144.692624 -263.068816)
		(mid 144.972052 -262.99265)
		(end 145.25244 -263.06526)
		(width 0.0889)
		(layer "In2.Cu")
		(net "M_I_CPU1_SB_CA<2>")
	)
	(arc
		(start 131.531868 -263.068816)
		(mid 131.814824 -262.992639)
		(end 132.09778 -263.068816)
		(width 0.0889)
		(layer "In2.Cu")
		(net "M_I_CPU1_SB_CA<2>")
	)
	(arc
		(start 134.92607 -263.073642)
		(mid 135.109578 -263.119136)
		(end 135.29183 -263.068816)
		(width 0.0889)
		(layer "In2.Cu")
		(net "M_I_CPU1_SB_CA<2>")
	)
	(arc
		(start 138.67765 -263.068816)
		(mid 138.859901 -263.119166)
		(end 139.04341 -263.073642)
		(width 0.0889)
		(layer "In2.Cu")
		(net "M_I_CPU1_SB_CA<2>")
	)
	(arc
		(start 140.9319 -263.068816)
		(mid 141.214856 -262.992639)
		(end 141.497812 -263.068816)
		(width 0.0889)
		(layer "In2.Cu")
		(net "M_I_CPU1_SB_CA<2>")
	)
	(arc
		(start 134.351776 -263.068816)
		(mid 134.634732 -262.992639)
		(end 134.917688 -263.068816)
		(width 0.0889)
		(layer "In2.Cu")
		(net "M_I_CPU1_SB_CA<2>")
	)
	(arc
		(start 139.626086 -263.073642)
		(mid 139.809594 -263.119136)
		(end 139.991846 -263.068816)
		(width 0.0889)
		(layer "In2.Cu")
		(net "M_I_CPU1_SB_CA<2>")
	)
	(arc
		(start 136.797796 -263.068816)
		(mid 136.98474 -263.119071)
		(end 137.171684 -263.068816)
		(width 0.0889)
		(layer "In2.Cu")
		(net "M_I_CPU1_SB_CA<2>")
	)
	(arc
		(start 137.171684 -263.068816)
		(mid 137.45464 -262.992639)
		(end 137.737596 -263.068816)
		(width 0.0889)
		(layer "In2.Cu")
		(net "M_I_CPU1_SB_CA<2>")
	)
	(arc
		(start 145.276316 -263.078976)
		(mid 145.455545 -263.119129)
		(end 145.63217 -263.068816)
		(width 0.0889)
		(layer "In2.Cu")
		(net "M_I_CPU1_SB_CA<2>")
	)
	(arc
		(start 130.591814 -263.068816)
		(mid 130.87477 -262.992639)
		(end 131.157726 -263.068816)
		(width 0.0889)
		(layer "In2.Cu")
		(net "M_I_CPU1_SB_CA<2>")
	)
	(arc
		(start 130.217672 -263.068816)
		(mid 130.399923 -263.119166)
		(end 130.583432 -263.073642)
		(width 0.0889)
		(layer "In2.Cu")
		(net "M_I_CPU1_SB_CA<2>")
	)
	(arc
		(start 141.497812 -263.068816)
		(mid 141.684756 -263.119071)
		(end 141.8717 -263.068816)
		(width 0.0889)
		(layer "In2.Cu")
		(net "M_I_CPU1_SB_CA<2>")
	)
	(arc
		(start 135.29183 -263.068816)
		(mid 135.574786 -262.992639)
		(end 135.857742 -263.068816)
		(width 0.0889)
		(layer "In2.Cu")
		(net "M_I_CPU1_SB_CA<2>")
	)
	(arc
		(start 140.56614 -263.073642)
		(mid 140.749648 -263.119136)
		(end 140.9319 -263.068816)
		(width 0.0889)
		(layer "In2.Cu")
		(net "M_I_CPU1_SB_CA<2>")
	)
	(arc
		(start 133.037834 -263.068816)
		(mid 133.224778 -263.119071)
		(end 133.411722 -263.068816)
		(width 0.0889)
		(layer "In2.Cu")
		(net "M_I_CPU1_SB_CA<2>")
	)
	(arc
		(start 136.231884 -263.068816)
		(mid 136.51484 -262.992639)
		(end 136.797796 -263.068816)
		(width 0.0889)
		(layer "In2.Cu")
		(net "M_I_CPU1_SB_CA<2>")
	)
	(segment
		(start 128.05791 -262.480298)
		(end 128.524762 -262.746236)
		(width 0.10668)
		(layer "F.Cu")
		(net "M_I_CPU1_SB_CA<1>")
	)
	(segment
		(start 177.830988 -262.068564)
		(end 178.097942 -262.068564)
		(width 0.14478)
		(layer "In2.Cu")
		(net "M_I_CPU1_SB_CA<1>")
	)
	(segment
		(start 134.343394 -262.41883)
		(end 134.351776 -262.423656)
		(width 0.0889)
		(layer "In2.Cu")
		(net "M_I_CPU1_SB_CA<1>")
	)
	(segment
		(start 166.08933 -262.038084)
		(end 166.411656 -262.36041)
		(width 0.14478)
		(layer "In2.Cu")
		(net "M_I_CPU1_SB_CA<1>")
	)
	(segment
		(start 163.063428 -262.36041)
		(end 165.53053 -262.36041)
		(width 0.14478)
		(layer "In2.Cu")
		(net "M_I_CPU1_SB_CA<1>")
	)
	(segment
		(start 128.524762 -262.746236)
		(end 128.370838 -262.480806)
		(width 0.0889)
		(layer "In2.Cu")
		(net "M_I_CPU1_SB_CA<1>")
	)
	(segment
		(start 133.40334 -262.41883)
		(end 133.411722 -262.423656)
		(width 0.0889)
		(layer "In2.Cu")
		(net "M_I_CPU1_SB_CA<1>")
	)
	(segment
		(start 162.352228 -262.066024)
		(end 163.063428 -262.36041)
		(width 0.14478)
		(layer "In2.Cu")
		(net "M_I_CPU1_SB_CA<1>")
	)
	(segment
		(start 173.824138 -262.36041)
		(end 174.103792 -262.36041)
		(width 0.14478)
		(layer "In2.Cu")
		(net "M_I_CPU1_SB_CA<1>")
	)
	(segment
		(start 138.103356 -262.41883)
		(end 138.111738 -262.423656)
		(width 0.0889)
		(layer "In2.Cu")
		(net "M_I_CPU1_SB_CA<1>")
	)
	(segment
		(start 166.64813 -262.36041)
		(end 166.970456 -262.038084)
		(width 0.14478)
		(layer "In2.Cu")
		(net "M_I_CPU1_SB_CA<1>")
	)
	(segment
		(start 166.411656 -262.36041)
		(end 166.64813 -262.36041)
		(width 0.14478)
		(layer "In2.Cu")
		(net "M_I_CPU1_SB_CA<1>")
	)
	(segment
		(start 135.857742 -262.423656)
		(end 135.866124 -262.41883)
		(width 0.0889)
		(layer "In2.Cu")
		(net "M_I_CPU1_SB_CA<1>")
	)
	(segment
		(start 174.382938 -262.081264)
		(end 174.662592 -262.081264)
		(width 0.14478)
		(layer "In2.Cu")
		(net "M_I_CPU1_SB_CA<1>")
	)
	(segment
		(start 178.389788 -262.36041)
		(end 179.090828 -262.36041)
		(width 0.14478)
		(layer "In2.Cu")
		(net "M_I_CPU1_SB_CA<1>")
	)
	(segment
		(start 130.583432 -262.41883)
		(end 130.591814 -262.423656)
		(width 0.0889)
		(layer "In2.Cu")
		(net "M_I_CPU1_SB_CA<1>")
	)
	(segment
		(start 167.529256 -262.36041)
		(end 172.986192 -262.36041)
		(width 0.14478)
		(layer "In2.Cu")
		(net "M_I_CPU1_SB_CA<1>")
	)
	(segment
		(start 166.970456 -262.038084)
		(end 167.20693 -262.038084)
		(width 0.14478)
		(layer "In2.Cu")
		(net "M_I_CPU1_SB_CA<1>")
	)
	(segment
		(start 173.265338 -262.081264)
		(end 173.544992 -262.081264)
		(width 0.14478)
		(layer "In2.Cu")
		(net "M_I_CPU1_SB_CA<1>")
	)
	(segment
		(start 174.103792 -262.36041)
		(end 174.382938 -262.081264)
		(width 0.14478)
		(layer "In2.Cu")
		(net "M_I_CPU1_SB_CA<1>")
	)
	(segment
		(start 165.852856 -262.038084)
		(end 166.08933 -262.038084)
		(width 0.14478)
		(layer "In2.Cu")
		(net "M_I_CPU1_SB_CA<1>")
	)
	(segment
		(start 144.315688 -262.42391)
		(end 144.337532 -262.411464)
		(width 0.0889)
		(layer "In2.Cu")
		(net "M_I_CPU1_SB_CA<1>")
	)
	(segment
		(start 128.370838 -262.480806)
		(end 128.39319 -262.397494)
		(width 0.0889)
		(layer "In2.Cu")
		(net "M_I_CPU1_SB_CA<1>")
	)
	(segment
		(start 147.305776 -262.372094)
		(end 147.611846 -262.066024)
		(width 0.0889)
		(layer "In2.Cu")
		(net "M_I_CPU1_SB_CA<1>")
	)
	(segment
		(start 172.986192 -262.36041)
		(end 173.265338 -262.081264)
		(width 0.14478)
		(layer "In2.Cu")
		(net "M_I_CPU1_SB_CA<1>")
	)
	(segment
		(start 173.544992 -262.081264)
		(end 173.824138 -262.36041)
		(width 0.14478)
		(layer "In2.Cu")
		(net "M_I_CPU1_SB_CA<1>")
	)
	(segment
		(start 142.803372 -262.41883)
		(end 142.811754 -262.423656)
		(width 0.0889)
		(layer "In2.Cu")
		(net "M_I_CPU1_SB_CA<1>")
	)
	(segment
		(start 143.377666 -262.423656)
		(end 143.386048 -262.41883)
		(width 0.0889)
		(layer "In2.Cu")
		(net "M_I_CPU1_SB_CA<1>")
	)
	(segment
		(start 177.539142 -262.36041)
		(end 177.830988 -262.068564)
		(width 0.14478)
		(layer "In2.Cu")
		(net "M_I_CPU1_SB_CA<1>")
	)
	(segment
		(start 147.611846 -262.066024)
		(end 162.352228 -262.066024)
		(width 0.14478)
		(layer "In2.Cu")
		(net "M_I_CPU1_SB_CA<1>")
	)
	(segment
		(start 179.090828 -262.36041)
		(end 179.516024 -261.935214)
		(width 0.14478)
		(layer "In2.Cu")
		(net "M_I_CPU1_SB_CA<1>")
	)
	(segment
		(start 134.917688 -262.423656)
		(end 134.92607 -262.41883)
		(width 0.0889)
		(layer "In2.Cu")
		(net "M_I_CPU1_SB_CA<1>")
	)
	(segment
		(start 165.53053 -262.36041)
		(end 165.852856 -262.038084)
		(width 0.14478)
		(layer "In2.Cu")
		(net "M_I_CPU1_SB_CA<1>")
	)
	(segment
		(start 145.444718 -262.372094)
		(end 147.305776 -262.372094)
		(width 0.0889)
		(layer "In2.Cu")
		(net "M_I_CPU1_SB_CA<1>")
	)
	(segment
		(start 129.643378 -262.41883)
		(end 129.65176 -262.423656)
		(width 0.0889)
		(layer "In2.Cu")
		(net "M_I_CPU1_SB_CA<1>")
	)
	(segment
		(start 131.157726 -262.423656)
		(end 131.166108 -262.41883)
		(width 0.0889)
		(layer "In2.Cu")
		(net "M_I_CPU1_SB_CA<1>")
	)
	(segment
		(start 144.289526 -262.438896)
		(end 144.315688 -262.42391)
		(width 0.0889)
		(layer "In2.Cu")
		(net "M_I_CPU1_SB_CA<1>")
	)
	(segment
		(start 144.688306 -262.423656)
		(end 144.71777 -262.440928)
		(width 0.0889)
		(layer "In2.Cu")
		(net "M_I_CPU1_SB_CA<1>")
	)
	(segment
		(start 140.557758 -262.423656)
		(end 140.56614 -262.41883)
		(width 0.0889)
		(layer "In2.Cu")
		(net "M_I_CPU1_SB_CA<1>")
	)
	(segment
		(start 174.941738 -262.36041)
		(end 177.539142 -262.36041)
		(width 0.14478)
		(layer "In2.Cu")
		(net "M_I_CPU1_SB_CA<1>")
	)
	(segment
		(start 167.20693 -262.038084)
		(end 167.529256 -262.36041)
		(width 0.14478)
		(layer "In2.Cu")
		(net "M_I_CPU1_SB_CA<1>")
	)
	(segment
		(start 178.097942 -262.068564)
		(end 178.389788 -262.36041)
		(width 0.14478)
		(layer "In2.Cu")
		(net "M_I_CPU1_SB_CA<1>")
	)
	(segment
		(start 139.04341 -262.41883)
		(end 139.051792 -262.423656)
		(width 0.0889)
		(layer "In2.Cu")
		(net "M_I_CPU1_SB_CA<1>")
	)
	(segment
		(start 139.617704 -262.423656)
		(end 139.626086 -262.41883)
		(width 0.0889)
		(layer "In2.Cu")
		(net "M_I_CPU1_SB_CA<1>")
	)
	(segment
		(start 174.662592 -262.081264)
		(end 174.941738 -262.36041)
		(width 0.14478)
		(layer "In2.Cu")
		(net "M_I_CPU1_SB_CA<1>")
	)
	(arc
		(start 144.337532 -262.411464)
		(mid 144.51446 -262.373636)
		(end 144.688306 -262.423656)
		(width 0.0889)
		(layer "In2.Cu")
		(net "M_I_CPU1_SB_CA<1>")
	)
	(arc
		(start 131.166108 -262.41883)
		(mid 131.349616 -262.373336)
		(end 131.531868 -262.423656)
		(width 0.0889)
		(layer "In2.Cu")
		(net "M_I_CPU1_SB_CA<1>")
	)
	(arc
		(start 139.626086 -262.41883)
		(mid 139.809594 -262.373336)
		(end 139.991846 -262.423656)
		(width 0.0889)
		(layer "In2.Cu")
		(net "M_I_CPU1_SB_CA<1>")
	)
	(arc
		(start 144.71777 -262.440928)
		(mid 144.98919 -262.500605)
		(end 145.25625 -262.423656)
		(width 0.0889)
		(layer "In2.Cu")
		(net "M_I_CPU1_SB_CA<1>")
	)
	(arc
		(start 139.051792 -262.423656)
		(mid 139.334748 -262.499833)
		(end 139.617704 -262.423656)
		(width 0.0889)
		(layer "In2.Cu")
		(net "M_I_CPU1_SB_CA<1>")
	)
	(arc
		(start 143.751808 -262.423656)
		(mid 144.018738 -262.499605)
		(end 144.289526 -262.438896)
		(width 0.0889)
		(layer "In2.Cu")
		(net "M_I_CPU1_SB_CA<1>")
	)
	(arc
		(start 129.277618 -262.423656)
		(mid 129.459869 -262.373306)
		(end 129.643378 -262.41883)
		(width 0.0889)
		(layer "In2.Cu")
		(net "M_I_CPU1_SB_CA<1>")
	)
	(arc
		(start 128.711706 -262.423656)
		(mid 128.994662 -262.499833)
		(end 129.277618 -262.423656)
		(width 0.0889)
		(layer "In2.Cu")
		(net "M_I_CPU1_SB_CA<1>")
	)
	(arc
		(start 141.8717 -262.423656)
		(mid 142.154656 -262.499833)
		(end 142.437612 -262.423656)
		(width 0.0889)
		(layer "In2.Cu")
		(net "M_I_CPU1_SB_CA<1>")
	)
	(arc
		(start 137.171684 -262.423656)
		(mid 137.45464 -262.499833)
		(end 137.737596 -262.423656)
		(width 0.0889)
		(layer "In2.Cu")
		(net "M_I_CPU1_SB_CA<1>")
	)
	(arc
		(start 145.25625 -262.423656)
		(mid 145.347056 -262.385343)
		(end 145.444718 -262.372094)
		(width 0.0889)
		(layer "In2.Cu")
		(net "M_I_CPU1_SB_CA<1>")
	)
	(arc
		(start 136.797796 -262.423656)
		(mid 136.98474 -262.373401)
		(end 137.171684 -262.423656)
		(width 0.0889)
		(layer "In2.Cu")
		(net "M_I_CPU1_SB_CA<1>")
	)
	(arc
		(start 139.991846 -262.423656)
		(mid 140.274802 -262.499833)
		(end 140.557758 -262.423656)
		(width 0.0889)
		(layer "In2.Cu")
		(net "M_I_CPU1_SB_CA<1>")
	)
	(arc
		(start 133.977634 -262.423656)
		(mid 134.159885 -262.373306)
		(end 134.343394 -262.41883)
		(width 0.0889)
		(layer "In2.Cu")
		(net "M_I_CPU1_SB_CA<1>")
	)
	(arc
		(start 135.29183 -262.423656)
		(mid 135.574786 -262.499833)
		(end 135.857742 -262.423656)
		(width 0.0889)
		(layer "In2.Cu")
		(net "M_I_CPU1_SB_CA<1>")
	)
	(arc
		(start 137.737596 -262.423656)
		(mid 137.919847 -262.373306)
		(end 138.103356 -262.41883)
		(width 0.0889)
		(layer "In2.Cu")
		(net "M_I_CPU1_SB_CA<1>")
	)
	(arc
		(start 142.437612 -262.423656)
		(mid 142.619863 -262.373306)
		(end 142.803372 -262.41883)
		(width 0.0889)
		(layer "In2.Cu")
		(net "M_I_CPU1_SB_CA<1>")
	)
	(arc
		(start 135.866124 -262.41883)
		(mid 136.049632 -262.373336)
		(end 136.231884 -262.423656)
		(width 0.0889)
		(layer "In2.Cu")
		(net "M_I_CPU1_SB_CA<1>")
	)
	(arc
		(start 129.65176 -262.423656)
		(mid 129.934716 -262.499833)
		(end 130.217672 -262.423656)
		(width 0.0889)
		(layer "In2.Cu")
		(net "M_I_CPU1_SB_CA<1>")
	)
	(arc
		(start 130.217672 -262.423656)
		(mid 130.399923 -262.373306)
		(end 130.583432 -262.41883)
		(width 0.0889)
		(layer "In2.Cu")
		(net "M_I_CPU1_SB_CA<1>")
	)
	(arc
		(start 143.386048 -262.41883)
		(mid 143.569556 -262.373336)
		(end 143.751808 -262.423656)
		(width 0.0889)
		(layer "In2.Cu")
		(net "M_I_CPU1_SB_CA<1>")
	)
	(arc
		(start 138.67765 -262.423656)
		(mid 138.859901 -262.373306)
		(end 139.04341 -262.41883)
		(width 0.0889)
		(layer "In2.Cu")
		(net "M_I_CPU1_SB_CA<1>")
	)
	(arc
		(start 134.92607 -262.41883)
		(mid 135.109578 -262.373336)
		(end 135.29183 -262.423656)
		(width 0.0889)
		(layer "In2.Cu")
		(net "M_I_CPU1_SB_CA<1>")
	)
	(arc
		(start 132.09778 -262.423656)
		(mid 132.284724 -262.373401)
		(end 132.471668 -262.423656)
		(width 0.0889)
		(layer "In2.Cu")
		(net "M_I_CPU1_SB_CA<1>")
	)
	(arc
		(start 128.39319 -262.397494)
		(mid 128.555379 -262.374759)
		(end 128.711706 -262.423656)
		(width 0.0889)
		(layer "In2.Cu")
		(net "M_I_CPU1_SB_CA<1>")
	)
	(arc
		(start 133.03758 -262.423656)
		(mid 133.219831 -262.373306)
		(end 133.40334 -262.41883)
		(width 0.0889)
		(layer "In2.Cu")
		(net "M_I_CPU1_SB_CA<1>")
	)
	(arc
		(start 131.531868 -262.423656)
		(mid 131.814824 -262.499833)
		(end 132.09778 -262.423656)
		(width 0.0889)
		(layer "In2.Cu")
		(net "M_I_CPU1_SB_CA<1>")
	)
	(arc
		(start 134.351776 -262.423656)
		(mid 134.634732 -262.499833)
		(end 134.917688 -262.423656)
		(width 0.0889)
		(layer "In2.Cu")
		(net "M_I_CPU1_SB_CA<1>")
	)
	(arc
		(start 138.111738 -262.423656)
		(mid 138.394694 -262.499833)
		(end 138.67765 -262.423656)
		(width 0.0889)
		(layer "In2.Cu")
		(net "M_I_CPU1_SB_CA<1>")
	)
	(arc
		(start 132.471668 -262.423656)
		(mid 132.754624 -262.499833)
		(end 133.03758 -262.423656)
		(width 0.0889)
		(layer "In2.Cu")
		(net "M_I_CPU1_SB_CA<1>")
	)
	(arc
		(start 130.591814 -262.423656)
		(mid 130.87477 -262.499833)
		(end 131.157726 -262.423656)
		(width 0.0889)
		(layer "In2.Cu")
		(net "M_I_CPU1_SB_CA<1>")
	)
	(arc
		(start 136.231884 -262.423656)
		(mid 136.51484 -262.499833)
		(end 136.797796 -262.423656)
		(width 0.0889)
		(layer "In2.Cu")
		(net "M_I_CPU1_SB_CA<1>")
	)
	(arc
		(start 141.497812 -262.423656)
		(mid 141.684756 -262.373401)
		(end 141.8717 -262.423656)
		(width 0.0889)
		(layer "In2.Cu")
		(net "M_I_CPU1_SB_CA<1>")
	)
	(arc
		(start 133.411722 -262.423656)
		(mid 133.694678 -262.499833)
		(end 133.977634 -262.423656)
		(width 0.0889)
		(layer "In2.Cu")
		(net "M_I_CPU1_SB_CA<1>")
	)
	(arc
		(start 142.811754 -262.423656)
		(mid 143.09471 -262.499833)
		(end 143.377666 -262.423656)
		(width 0.0889)
		(layer "In2.Cu")
		(net "M_I_CPU1_SB_CA<1>")
	)
	(arc
		(start 140.56614 -262.41883)
		(mid 140.749648 -262.373336)
		(end 140.9319 -262.423656)
		(width 0.0889)
		(layer "In2.Cu")
		(net "M_I_CPU1_SB_CA<1>")
	)
	(arc
		(start 140.9319 -262.423656)
		(mid 141.214856 -262.499833)
		(end 141.497812 -262.423656)
		(width 0.0889)
		(layer "In2.Cu")
		(net "M_I_CPU1_SB_CA<1>")
	)
	(segment
		(start 127.58801 -261.670292)
		(end 128.054862 -261.93623)
		(width 0.10668)
		(layer "F.Cu")
		(net "M_I_CPU1_SB_CA<0>")
	)
	(segment
		(start 138.20775 -262.25881)
		(end 138.216132 -262.263636)
		(width 0.0889)
		(layer "In2.Cu")
		(net "M_I_CPU1_SB_CA<0>")
	)
	(segment
		(start 128.054862 -261.93623)
		(end 128.208786 -262.20166)
		(width 0.0889)
		(layer "In2.Cu")
		(net "M_I_CPU1_SB_CA<0>")
	)
	(segment
		(start 147.049236 -262.181594)
		(end 147.720558 -261.510272)
		(width 0.0889)
		(layer "In2.Cu")
		(net "M_I_CPU1_SB_CA<0>")
	)
	(segment
		(start 145.444464 -262.181594)
		(end 147.049236 -262.181594)
		(width 0.0889)
		(layer "In2.Cu")
		(net "M_I_CPU1_SB_CA<0>")
	)
	(segment
		(start 136.693402 -262.263636)
		(end 136.701784 -262.25881)
		(width 0.0889)
		(layer "In2.Cu")
		(net "M_I_CPU1_SB_CA<0>")
	)
	(segment
		(start 129.747772 -262.25881)
		(end 129.756154 -262.263636)
		(width 0.0889)
		(layer "In2.Cu")
		(net "M_I_CPU1_SB_CA<0>")
	)
	(segment
		(start 141.967712 -262.25881)
		(end 141.976094 -262.263636)
		(width 0.0889)
		(layer "In2.Cu")
		(net "M_I_CPU1_SB_CA<0>")
	)
	(segment
		(start 132.56768 -262.25881)
		(end 132.576062 -262.263636)
		(width 0.0889)
		(layer "In2.Cu")
		(net "M_I_CPU1_SB_CA<0>")
	)
	(segment
		(start 141.393418 -262.263636)
		(end 141.4018 -262.25881)
		(width 0.0889)
		(layer "In2.Cu")
		(net "M_I_CPU1_SB_CA<0>")
	)
	(segment
		(start 144.19707 -262.272018)
		(end 144.220438 -262.258556)
		(width 0.0889)
		(layer "In2.Cu")
		(net "M_I_CPU1_SB_CA<0>")
	)
	(segment
		(start 140.453364 -262.263636)
		(end 140.461746 -262.25881)
		(width 0.0889)
		(layer "In2.Cu")
		(net "M_I_CPU1_SB_CA<0>")
	)
	(segment
		(start 144.784318 -262.25881)
		(end 144.804892 -262.270748)
		(width 0.0889)
		(layer "In2.Cu")
		(net "M_I_CPU1_SB_CA<0>")
	)
	(segment
		(start 128.807718 -262.25881)
		(end 128.8161 -262.263636)
		(width 0.0889)
		(layer "In2.Cu")
		(net "M_I_CPU1_SB_CA<0>")
	)
	(segment
		(start 183.19115 -261.510272)
		(end 183.616092 -261.08533)
		(width 0.14478)
		(layer "In2.Cu")
		(net "M_I_CPU1_SB_CA<0>")
	)
	(segment
		(start 133.507734 -262.25881)
		(end 133.516116 -262.263636)
		(width 0.0889)
		(layer "In2.Cu")
		(net "M_I_CPU1_SB_CA<0>")
	)
	(segment
		(start 131.993386 -262.263636)
		(end 132.001768 -262.25881)
		(width 0.0889)
		(layer "In2.Cu")
		(net "M_I_CPU1_SB_CA<0>")
	)
	(segment
		(start 128.208786 -262.20166)
		(end 128.304798 -262.22706)
		(width 0.0889)
		(layer "In2.Cu")
		(net "M_I_CPU1_SB_CA<0>")
	)
	(segment
		(start 147.720558 -261.510272)
		(end 183.19115 -261.510272)
		(width 0.14478)
		(layer "In2.Cu")
		(net "M_I_CPU1_SB_CA<0>")
	)
	(segment
		(start 144.220438 -262.258556)
		(end 144.2466 -262.24357)
		(width 0.0889)
		(layer "In2.Cu")
		(net "M_I_CPU1_SB_CA<0>")
	)
	(segment
		(start 137.267696 -262.25881)
		(end 137.276078 -262.263636)
		(width 0.0889)
		(layer "In2.Cu")
		(net "M_I_CPU1_SB_CA<0>")
	)
	(segment
		(start 135.753348 -262.263636)
		(end 135.76173 -262.25881)
		(width 0.0889)
		(layer "In2.Cu")
		(net "M_I_CPU1_SB_CA<0>")
	)
	(arc
		(start 138.581892 -262.25881)
		(mid 138.864848 -262.182633)
		(end 139.147804 -262.25881)
		(width 0.0889)
		(layer "In2.Cu")
		(net "M_I_CPU1_SB_CA<0>")
	)
	(arc
		(start 145.15973 -262.25881)
		(mid 145.28681 -262.204081)
		(end 145.423382 -262.181848)
		(width 0.0889)
		(layer "In2.Cu")
		(net "M_I_CPU1_SB_CA<0>")
	)
	(arc
		(start 134.447788 -262.25881)
		(mid 134.634732 -262.309065)
		(end 134.821676 -262.25881)
		(width 0.0889)
		(layer "In2.Cu")
		(net "M_I_CPU1_SB_CA<0>")
	)
	(arc
		(start 136.327642 -262.25881)
		(mid 136.509893 -262.30916)
		(end 136.693402 -262.263636)
		(width 0.0889)
		(layer "In2.Cu")
		(net "M_I_CPU1_SB_CA<0>")
	)
	(arc
		(start 133.516116 -262.263636)
		(mid 133.699624 -262.30913)
		(end 133.881876 -262.25881)
		(width 0.0889)
		(layer "In2.Cu")
		(net "M_I_CPU1_SB_CA<0>")
	)
	(arc
		(start 141.976094 -262.263636)
		(mid 142.159602 -262.30913)
		(end 142.341854 -262.25881)
		(width 0.0889)
		(layer "In2.Cu")
		(net "M_I_CPU1_SB_CA<0>")
	)
	(arc
		(start 142.907766 -262.25881)
		(mid 143.09471 -262.309065)
		(end 143.281654 -262.25881)
		(width 0.0889)
		(layer "In2.Cu")
		(net "M_I_CPU1_SB_CA<0>")
	)
	(arc
		(start 135.387588 -262.25881)
		(mid 135.569839 -262.30916)
		(end 135.753348 -262.263636)
		(width 0.0889)
		(layer "In2.Cu")
		(net "M_I_CPU1_SB_CA<0>")
	)
	(arc
		(start 139.147804 -262.25881)
		(mid 139.334748 -262.309065)
		(end 139.521692 -262.25881)
		(width 0.0889)
		(layer "In2.Cu")
		(net "M_I_CPU1_SB_CA<0>")
	)
	(arc
		(start 143.847566 -262.25881)
		(mid 144.020674 -262.308926)
		(end 144.19707 -262.272018)
		(width 0.0889)
		(layer "In2.Cu")
		(net "M_I_CPU1_SB_CA<0>")
	)
	(arc
		(start 130.121914 -262.25881)
		(mid 130.40487 -262.182633)
		(end 130.687826 -262.25881)
		(width 0.0889)
		(layer "In2.Cu")
		(net "M_I_CPU1_SB_CA<0>")
	)
	(arc
		(start 132.941822 -262.25881)
		(mid 133.224778 -262.182633)
		(end 133.507734 -262.25881)
		(width 0.0889)
		(layer "In2.Cu")
		(net "M_I_CPU1_SB_CA<0>")
	)
	(arc
		(start 132.576062 -262.263636)
		(mid 132.75957 -262.30913)
		(end 132.941822 -262.25881)
		(width 0.0889)
		(layer "In2.Cu")
		(net "M_I_CPU1_SB_CA<0>")
	)
	(arc
		(start 132.001768 -262.25881)
		(mid 132.284724 -262.182633)
		(end 132.56768 -262.25881)
		(width 0.0889)
		(layer "In2.Cu")
		(net "M_I_CPU1_SB_CA<0>")
	)
	(arc
		(start 137.276078 -262.263636)
		(mid 137.459586 -262.30913)
		(end 137.641838 -262.25881)
		(width 0.0889)
		(layer "In2.Cu")
		(net "M_I_CPU1_SB_CA<0>")
	)
	(arc
		(start 130.687826 -262.25881)
		(mid 130.87477 -262.309065)
		(end 131.061714 -262.25881)
		(width 0.0889)
		(layer "In2.Cu")
		(net "M_I_CPU1_SB_CA<0>")
	)
	(arc
		(start 143.281654 -262.25881)
		(mid 143.56461 -262.182633)
		(end 143.847566 -262.25881)
		(width 0.0889)
		(layer "In2.Cu")
		(net "M_I_CPU1_SB_CA<0>")
	)
	(arc
		(start 128.8161 -262.263636)
		(mid 128.999608 -262.30913)
		(end 129.18186 -262.25881)
		(width 0.0889)
		(layer "In2.Cu")
		(net "M_I_CPU1_SB_CA<0>")
	)
	(arc
		(start 137.641838 -262.25881)
		(mid 137.924794 -262.182633)
		(end 138.20775 -262.25881)
		(width 0.0889)
		(layer "In2.Cu")
		(net "M_I_CPU1_SB_CA<0>")
	)
	(arc
		(start 129.756154 -262.263636)
		(mid 129.939662 -262.30913)
		(end 130.121914 -262.25881)
		(width 0.0889)
		(layer "In2.Cu")
		(net "M_I_CPU1_SB_CA<0>")
	)
	(arc
		(start 144.804892 -262.270748)
		(mid 144.98382 -262.309625)
		(end 145.15973 -262.25881)
		(width 0.0889)
		(layer "In2.Cu")
		(net "M_I_CPU1_SB_CA<0>")
	)
	(arc
		(start 134.821676 -262.25881)
		(mid 135.104632 -262.182633)
		(end 135.387588 -262.25881)
		(width 0.0889)
		(layer "In2.Cu")
		(net "M_I_CPU1_SB_CA<0>")
	)
	(arc
		(start 141.4018 -262.25881)
		(mid 141.684756 -262.182633)
		(end 141.967712 -262.25881)
		(width 0.0889)
		(layer "In2.Cu")
		(net "M_I_CPU1_SB_CA<0>")
	)
	(arc
		(start 140.461746 -262.25881)
		(mid 140.744702 -262.182633)
		(end 141.027658 -262.25881)
		(width 0.0889)
		(layer "In2.Cu")
		(net "M_I_CPU1_SB_CA<0>")
	)
	(arc
		(start 131.627626 -262.25881)
		(mid 131.809877 -262.30916)
		(end 131.993386 -262.263636)
		(width 0.0889)
		(layer "In2.Cu")
		(net "M_I_CPU1_SB_CA<0>")
	)
	(arc
		(start 145.423382 -262.181848)
		(mid 145.433922 -262.181624)
		(end 145.444464 -262.181594)
		(width 0.0889)
		(layer "In2.Cu")
		(net "M_I_CPU1_SB_CA<0>")
	)
	(arc
		(start 128.304798 -262.22706)
		(mid 128.560006 -262.183583)
		(end 128.807718 -262.25881)
		(width 0.0889)
		(layer "In2.Cu")
		(net "M_I_CPU1_SB_CA<0>")
	)
	(arc
		(start 129.18186 -262.25881)
		(mid 129.464816 -262.182633)
		(end 129.747772 -262.25881)
		(width 0.0889)
		(layer "In2.Cu")
		(net "M_I_CPU1_SB_CA<0>")
	)
	(arc
		(start 135.76173 -262.25881)
		(mid 136.044686 -262.182633)
		(end 136.327642 -262.25881)
		(width 0.0889)
		(layer "In2.Cu")
		(net "M_I_CPU1_SB_CA<0>")
	)
	(arc
		(start 131.061714 -262.25881)
		(mid 131.34467 -262.182633)
		(end 131.627626 -262.25881)
		(width 0.0889)
		(layer "In2.Cu")
		(net "M_I_CPU1_SB_CA<0>")
	)
	(arc
		(start 139.521692 -262.25881)
		(mid 139.804648 -262.182633)
		(end 140.087604 -262.25881)
		(width 0.0889)
		(layer "In2.Cu")
		(net "M_I_CPU1_SB_CA<0>")
	)
	(arc
		(start 136.701784 -262.25881)
		(mid 136.98474 -262.182633)
		(end 137.267696 -262.25881)
		(width 0.0889)
		(layer "In2.Cu")
		(net "M_I_CPU1_SB_CA<0>")
	)
	(arc
		(start 133.881876 -262.25881)
		(mid 134.164832 -262.182633)
		(end 134.447788 -262.25881)
		(width 0.0889)
		(layer "In2.Cu")
		(net "M_I_CPU1_SB_CA<0>")
	)
	(arc
		(start 144.2466 -262.24357)
		(mid 144.517386 -262.182924)
		(end 144.784318 -262.25881)
		(width 0.0889)
		(layer "In2.Cu")
		(net "M_I_CPU1_SB_CA<0>")
	)
	(arc
		(start 142.341854 -262.25881)
		(mid 142.62481 -262.182633)
		(end 142.907766 -262.25881)
		(width 0.0889)
		(layer "In2.Cu")
		(net "M_I_CPU1_SB_CA<0>")
	)
	(arc
		(start 140.087604 -262.25881)
		(mid 140.269855 -262.30916)
		(end 140.453364 -262.263636)
		(width 0.0889)
		(layer "In2.Cu")
		(net "M_I_CPU1_SB_CA<0>")
	)
	(arc
		(start 141.027658 -262.25881)
		(mid 141.209909 -262.30916)
		(end 141.393418 -262.263636)
		(width 0.0889)
		(layer "In2.Cu")
		(net "M_I_CPU1_SB_CA<0>")
	)
	(arc
		(start 138.216132 -262.263636)
		(mid 138.39964 -262.30913)
		(end 138.581892 -262.25881)
		(width 0.0889)
		(layer "In2.Cu")
		(net "M_I_CPU1_SB_CA<0>")
	)
	(segment
		(start 127.58801 -266.530328)
		(end 128.054862 -266.796266)
		(width 0.10668)
		(layer "F.Cu")
		(net "M_I_CPU1_SA_RSP<0>")
	)
	(segment
		(start 135.753348 -267.123672)
		(end 135.76173 -267.118846)
		(width 0.0889)
		(layer "In2.Cu")
		(net "M_I_CPU1_SA_RSP<0>")
	)
	(segment
		(start 128.807718 -267.118846)
		(end 128.8161 -267.123672)
		(width 0.0889)
		(layer "In2.Cu")
		(net "M_I_CPU1_SA_RSP<0>")
	)
	(segment
		(start 136.693402 -267.123672)
		(end 136.701784 -267.118846)
		(width 0.0889)
		(layer "In2.Cu")
		(net "M_I_CPU1_SA_RSP<0>")
	)
	(segment
		(start 141.393418 -267.123672)
		(end 141.4018 -267.118846)
		(width 0.0889)
		(layer "In2.Cu")
		(net "M_I_CPU1_SA_RSP<0>")
	)
	(segment
		(start 146.339052 -265.939524)
		(end 147.473162 -265.939524)
		(width 0.0889)
		(layer "In2.Cu")
		(net "M_I_CPU1_SA_RSP<0>")
	)
	(segment
		(start 145.15973 -267.118846)
		(end 146.339052 -265.939524)
		(width 0.0889)
		(layer "In2.Cu")
		(net "M_I_CPU1_SA_RSP<0>")
	)
	(segment
		(start 144.220438 -267.118592)
		(end 144.2466 -267.103606)
		(width 0.0889)
		(layer "In2.Cu")
		(net "M_I_CPU1_SA_RSP<0>")
	)
	(segment
		(start 163.76015 -270.010636)
		(end 183.190896 -270.010636)
		(width 0.11684)
		(layer "In2.Cu")
		(net "M_I_CPU1_SA_RSP<0>")
	)
	(segment
		(start 147.677632 -266.143994)
		(end 157.973268 -266.143994)
		(width 0.11684)
		(layer "In2.Cu")
		(net "M_I_CPU1_SA_RSP<0>")
	)
	(segment
		(start 138.20775 -267.118846)
		(end 138.216132 -267.123672)
		(width 0.0889)
		(layer "In2.Cu")
		(net "M_I_CPU1_SA_RSP<0>")
	)
	(segment
		(start 144.19707 -267.132054)
		(end 144.220438 -267.118592)
		(width 0.0889)
		(layer "In2.Cu")
		(net "M_I_CPU1_SA_RSP<0>")
	)
	(segment
		(start 147.473162 -265.939524)
		(end 147.677632 -266.143994)
		(width 0.0889)
		(layer "In2.Cu")
		(net "M_I_CPU1_SA_RSP<0>")
	)
	(segment
		(start 128.054862 -266.796266)
		(end 128.208786 -267.061696)
		(width 0.0889)
		(layer "In2.Cu")
		(net "M_I_CPU1_SA_RSP<0>")
	)
	(segment
		(start 140.453364 -267.123672)
		(end 140.461746 -267.118846)
		(width 0.0889)
		(layer "In2.Cu")
		(net "M_I_CPU1_SA_RSP<0>")
	)
	(segment
		(start 144.784318 -267.118846)
		(end 144.804892 -267.130784)
		(width 0.0889)
		(layer "In2.Cu")
		(net "M_I_CPU1_SA_RSP<0>")
	)
	(segment
		(start 131.993386 -267.123672)
		(end 132.001768 -267.118846)
		(width 0.0889)
		(layer "In2.Cu")
		(net "M_I_CPU1_SA_RSP<0>")
	)
	(segment
		(start 183.190896 -270.010636)
		(end 183.616092 -269.58544)
		(width 0.11684)
		(layer "In2.Cu")
		(net "M_I_CPU1_SA_RSP<0>")
	)
	(segment
		(start 132.93344 -267.123672)
		(end 132.941822 -267.118846)
		(width 0.0889)
		(layer "In2.Cu")
		(net "M_I_CPU1_SA_RSP<0>")
	)
	(segment
		(start 128.208786 -267.061696)
		(end 128.304798 -267.087096)
		(width 0.0889)
		(layer "In2.Cu")
		(net "M_I_CPU1_SA_RSP<0>")
	)
	(segment
		(start 137.267696 -267.118846)
		(end 137.276078 -267.123672)
		(width 0.0889)
		(layer "In2.Cu")
		(net "M_I_CPU1_SA_RSP<0>")
	)
	(segment
		(start 133.507734 -267.118846)
		(end 133.516116 -267.123672)
		(width 0.0889)
		(layer "In2.Cu")
		(net "M_I_CPU1_SA_RSP<0>")
	)
	(segment
		(start 157.973268 -266.143994)
		(end 163.76015 -270.010636)
		(width 0.11684)
		(layer "In2.Cu")
		(net "M_I_CPU1_SA_RSP<0>")
	)
	(segment
		(start 129.747772 -267.118846)
		(end 129.756154 -267.123672)
		(width 0.0889)
		(layer "In2.Cu")
		(net "M_I_CPU1_SA_RSP<0>")
	)
	(segment
		(start 141.967712 -267.118846)
		(end 141.976094 -267.123672)
		(width 0.0889)
		(layer "In2.Cu")
		(net "M_I_CPU1_SA_RSP<0>")
	)
	(arc
		(start 132.56768 -267.118846)
		(mid 132.749931 -267.169196)
		(end 132.93344 -267.123672)
		(width 0.0889)
		(layer "In2.Cu")
		(net "M_I_CPU1_SA_RSP<0>")
	)
	(arc
		(start 128.304798 -267.087096)
		(mid 128.560006 -267.043619)
		(end 128.807718 -267.118846)
		(width 0.0889)
		(layer "In2.Cu")
		(net "M_I_CPU1_SA_RSP<0>")
	)
	(arc
		(start 133.881876 -267.118846)
		(mid 134.164832 -267.042669)
		(end 134.447788 -267.118846)
		(width 0.0889)
		(layer "In2.Cu")
		(net "M_I_CPU1_SA_RSP<0>")
	)
	(arc
		(start 143.847566 -267.118846)
		(mid 144.020674 -267.168962)
		(end 144.19707 -267.132054)
		(width 0.0889)
		(layer "In2.Cu")
		(net "M_I_CPU1_SA_RSP<0>")
	)
	(arc
		(start 134.447788 -267.118846)
		(mid 134.634732 -267.169101)
		(end 134.821676 -267.118846)
		(width 0.0889)
		(layer "In2.Cu")
		(net "M_I_CPU1_SA_RSP<0>")
	)
	(arc
		(start 131.061714 -267.118846)
		(mid 131.34467 -267.042669)
		(end 131.627626 -267.118846)
		(width 0.0889)
		(layer "In2.Cu")
		(net "M_I_CPU1_SA_RSP<0>")
	)
	(arc
		(start 137.276078 -267.123672)
		(mid 137.459586 -267.169166)
		(end 137.641838 -267.118846)
		(width 0.0889)
		(layer "In2.Cu")
		(net "M_I_CPU1_SA_RSP<0>")
	)
	(arc
		(start 135.387588 -267.118846)
		(mid 135.569839 -267.169196)
		(end 135.753348 -267.123672)
		(width 0.0889)
		(layer "In2.Cu")
		(net "M_I_CPU1_SA_RSP<0>")
	)
	(arc
		(start 133.516116 -267.123672)
		(mid 133.699624 -267.169166)
		(end 133.881876 -267.118846)
		(width 0.0889)
		(layer "In2.Cu")
		(net "M_I_CPU1_SA_RSP<0>")
	)
	(arc
		(start 128.8161 -267.123672)
		(mid 128.999608 -267.169166)
		(end 129.18186 -267.118846)
		(width 0.0889)
		(layer "In2.Cu")
		(net "M_I_CPU1_SA_RSP<0>")
	)
	(arc
		(start 135.76173 -267.118846)
		(mid 136.044686 -267.042669)
		(end 136.327642 -267.118846)
		(width 0.0889)
		(layer "In2.Cu")
		(net "M_I_CPU1_SA_RSP<0>")
	)
	(arc
		(start 139.521692 -267.118846)
		(mid 139.804648 -267.042669)
		(end 140.087604 -267.118846)
		(width 0.0889)
		(layer "In2.Cu")
		(net "M_I_CPU1_SA_RSP<0>")
	)
	(arc
		(start 136.701784 -267.118846)
		(mid 136.98474 -267.042669)
		(end 137.267696 -267.118846)
		(width 0.0889)
		(layer "In2.Cu")
		(net "M_I_CPU1_SA_RSP<0>")
	)
	(arc
		(start 141.027658 -267.118846)
		(mid 141.209909 -267.169196)
		(end 141.393418 -267.123672)
		(width 0.0889)
		(layer "In2.Cu")
		(net "M_I_CPU1_SA_RSP<0>")
	)
	(arc
		(start 144.804892 -267.130784)
		(mid 144.98382 -267.169661)
		(end 145.15973 -267.118846)
		(width 0.0889)
		(layer "In2.Cu")
		(net "M_I_CPU1_SA_RSP<0>")
	)
	(arc
		(start 138.216132 -267.123672)
		(mid 138.39964 -267.169166)
		(end 138.581892 -267.118846)
		(width 0.0889)
		(layer "In2.Cu")
		(net "M_I_CPU1_SA_RSP<0>")
	)
	(arc
		(start 141.4018 -267.118846)
		(mid 141.684756 -267.042669)
		(end 141.967712 -267.118846)
		(width 0.0889)
		(layer "In2.Cu")
		(net "M_I_CPU1_SA_RSP<0>")
	)
	(arc
		(start 143.281654 -267.118846)
		(mid 143.56461 -267.042669)
		(end 143.847566 -267.118846)
		(width 0.0889)
		(layer "In2.Cu")
		(net "M_I_CPU1_SA_RSP<0>")
	)
	(arc
		(start 131.627626 -267.118846)
		(mid 131.809877 -267.169196)
		(end 131.993386 -267.123672)
		(width 0.0889)
		(layer "In2.Cu")
		(net "M_I_CPU1_SA_RSP<0>")
	)
	(arc
		(start 132.001768 -267.118846)
		(mid 132.284724 -267.042669)
		(end 132.56768 -267.118846)
		(width 0.0889)
		(layer "In2.Cu")
		(net "M_I_CPU1_SA_RSP<0>")
	)
	(arc
		(start 138.581892 -267.118846)
		(mid 138.864848 -267.042669)
		(end 139.147804 -267.118846)
		(width 0.0889)
		(layer "In2.Cu")
		(net "M_I_CPU1_SA_RSP<0>")
	)
	(arc
		(start 130.121914 -267.118846)
		(mid 130.40487 -267.042669)
		(end 130.687826 -267.118846)
		(width 0.0889)
		(layer "In2.Cu")
		(net "M_I_CPU1_SA_RSP<0>")
	)
	(arc
		(start 129.18186 -267.118846)
		(mid 129.464816 -267.042669)
		(end 129.747772 -267.118846)
		(width 0.0889)
		(layer "In2.Cu")
		(net "M_I_CPU1_SA_RSP<0>")
	)
	(arc
		(start 129.756154 -267.123672)
		(mid 129.939662 -267.169166)
		(end 130.121914 -267.118846)
		(width 0.0889)
		(layer "In2.Cu")
		(net "M_I_CPU1_SA_RSP<0>")
	)
	(arc
		(start 142.907766 -267.118846)
		(mid 143.09471 -267.169101)
		(end 143.281654 -267.118846)
		(width 0.0889)
		(layer "In2.Cu")
		(net "M_I_CPU1_SA_RSP<0>")
	)
	(arc
		(start 141.976094 -267.123672)
		(mid 142.159602 -267.169166)
		(end 142.341854 -267.118846)
		(width 0.0889)
		(layer "In2.Cu")
		(net "M_I_CPU1_SA_RSP<0>")
	)
	(arc
		(start 144.2466 -267.103606)
		(mid 144.517386 -267.04296)
		(end 144.784318 -267.118846)
		(width 0.0889)
		(layer "In2.Cu")
		(net "M_I_CPU1_SA_RSP<0>")
	)
	(arc
		(start 130.687826 -267.118846)
		(mid 130.87477 -267.169101)
		(end 131.061714 -267.118846)
		(width 0.0889)
		(layer "In2.Cu")
		(net "M_I_CPU1_SA_RSP<0>")
	)
	(arc
		(start 139.147804 -267.118846)
		(mid 139.334748 -267.169101)
		(end 139.521692 -267.118846)
		(width 0.0889)
		(layer "In2.Cu")
		(net "M_I_CPU1_SA_RSP<0>")
	)
	(arc
		(start 132.941822 -267.118846)
		(mid 133.224778 -267.042669)
		(end 133.507734 -267.118846)
		(width 0.0889)
		(layer "In2.Cu")
		(net "M_I_CPU1_SA_RSP<0>")
	)
	(arc
		(start 142.341854 -267.118846)
		(mid 142.62481 -267.042669)
		(end 142.907766 -267.118846)
		(width 0.0889)
		(layer "In2.Cu")
		(net "M_I_CPU1_SA_RSP<0>")
	)
	(arc
		(start 140.087604 -267.118846)
		(mid 140.269855 -267.169196)
		(end 140.453364 -267.123672)
		(width 0.0889)
		(layer "In2.Cu")
		(net "M_I_CPU1_SA_RSP<0>")
	)
	(arc
		(start 134.821676 -267.118846)
		(mid 135.104632 -267.042669)
		(end 135.387588 -267.118846)
		(width 0.0889)
		(layer "In2.Cu")
		(net "M_I_CPU1_SA_RSP<0>")
	)
	(arc
		(start 140.461746 -267.118846)
		(mid 140.744702 -267.042669)
		(end 141.027658 -267.118846)
		(width 0.0889)
		(layer "In2.Cu")
		(net "M_I_CPU1_SA_RSP<0>")
	)
	(arc
		(start 137.641838 -267.118846)
		(mid 137.924794 -267.042669)
		(end 138.20775 -267.118846)
		(width 0.0889)
		(layer "In2.Cu")
		(net "M_I_CPU1_SA_RSP<0>")
	)
	(arc
		(start 136.327642 -267.118846)
		(mid 136.509893 -267.169196)
		(end 136.693402 -267.123672)
		(width 0.0889)
		(layer "In2.Cu")
		(net "M_I_CPU1_SA_RSP<0>")
	)
	(segment
		(start 127.287782 -256.09042)
		(end 127.754634 -255.824482)
		(width 0.10668)
		(layer "F.Cu")
		(net "M_I_CPU1_SA_PAR")
	)
	(segment
		(start 145.452846 -255.660906)
		(end 145.629122 -255.660906)
		(width 0.0889)
		(layer "In2.Cu")
		(net "M_I_CPU1_SA_PAR")
	)
	(segment
		(start 146.859498 -256.503678)
		(end 146.98853 -256.374646)
		(width 0.0889)
		(layer "In2.Cu")
		(net "M_I_CPU1_SA_PAR")
	)
	(segment
		(start 177.033936 -254.710438)
		(end 177.250344 -254.49403)
		(width 0.14478)
		(layer "In2.Cu")
		(net "M_I_CPU1_SA_PAR")
	)
	(segment
		(start 156.099002 -255.56591)
		(end 172.188886 -255.56591)
		(width 0.14478)
		(layer "In2.Cu")
		(net "M_I_CPU1_SA_PAR")
	)
	(segment
		(start 175.476154 -254.710438)
		(end 177.033936 -254.710438)
		(width 0.14478)
		(layer "In2.Cu")
		(net "M_I_CPU1_SA_PAR")
	)
	(segment
		(start 136.393428 -255.497076)
		(end 136.40181 -255.501902)
		(width 0.0889)
		(layer "In2.Cu")
		(net "M_I_CPU1_SA_PAR")
	)
	(segment
		(start 174.537878 -255.098804)
		(end 175.476154 -254.710438)
		(width 0.14478)
		(layer "In2.Cu")
		(net "M_I_CPU1_SA_PAR")
	)
	(segment
		(start 141.667738 -255.501902)
		(end 141.67612 -255.497076)
		(width 0.0889)
		(layer "In2.Cu")
		(net "M_I_CPU1_SA_PAR")
	)
	(segment
		(start 183.175656 -253.844806)
		(end 183.616092 -254.285242)
		(width 0.14478)
		(layer "In2.Cu")
		(net "M_I_CPU1_SA_PAR")
	)
	(segment
		(start 151.179276 -256.374646)
		(end 152.459436 -255.094486)
		(width 0.14478)
		(layer "In2.Cu")
		(net "M_I_CPU1_SA_PAR")
	)
	(segment
		(start 135.453374 -255.497076)
		(end 135.461756 -255.501902)
		(width 0.0889)
		(layer "In2.Cu")
		(net "M_I_CPU1_SA_PAR")
	)
	(segment
		(start 178.495706 -253.010416)
		(end 180.261768 -253.010416)
		(width 0.14478)
		(layer "In2.Cu")
		(net "M_I_CPU1_SA_PAR")
	)
	(segment
		(start 180.261768 -253.010416)
		(end 180.737764 -253.105158)
		(width 0.14478)
		(layer "In2.Cu")
		(net "M_I_CPU1_SA_PAR")
	)
	(segment
		(start 144.84858 -255.494282)
		(end 144.862296 -255.502156)
		(width 0.0889)
		(layer "In2.Cu")
		(net "M_I_CPU1_SA_PAR")
	)
	(segment
		(start 145.629122 -255.660906)
		(end 146.471894 -256.503678)
		(width 0.0889)
		(layer "In2.Cu")
		(net "M_I_CPU1_SA_PAR")
	)
	(segment
		(start 146.98853 -256.374646)
		(end 147.29079 -256.374646)
		(width 0.0889)
		(layer "In2.Cu")
		(net "M_I_CPU1_SA_PAR")
	)
	(segment
		(start 178.157632 -253.15037)
		(end 178.495706 -253.010416)
		(width 0.14478)
		(layer "In2.Cu")
		(net "M_I_CPU1_SA_PAR")
	)
	(segment
		(start 133.20776 -255.501902)
		(end 133.216142 -255.497076)
		(width 0.0889)
		(layer "In2.Cu")
		(net "M_I_CPU1_SA_PAR")
	)
	(segment
		(start 152.459436 -255.094486)
		(end 155.627578 -255.094486)
		(width 0.14478)
		(layer "In2.Cu")
		(net "M_I_CPU1_SA_PAR")
	)
	(segment
		(start 155.627578 -255.094486)
		(end 156.099002 -255.56591)
		(width 0.14478)
		(layer "In2.Cu")
		(net "M_I_CPU1_SA_PAR")
	)
	(segment
		(start 144.47393 -255.510538)
		(end 144.488662 -255.501902)
		(width 0.0889)
		(layer "In2.Cu")
		(net "M_I_CPU1_SA_PAR")
	)
	(segment
		(start 177.250344 -254.49403)
		(end 177.558954 -253.749048)
		(width 0.14478)
		(layer "In2.Cu")
		(net "M_I_CPU1_SA_PAR")
	)
	(segment
		(start 143.547592 -255.501902)
		(end 143.555974 -255.497076)
		(width 0.0889)
		(layer "In2.Cu")
		(net "M_I_CPU1_SA_PAR")
	)
	(segment
		(start 141.093444 -255.497076)
		(end 141.101826 -255.501902)
		(width 0.0889)
		(layer "In2.Cu")
		(net "M_I_CPU1_SA_PAR")
	)
	(segment
		(start 127.754634 -255.824482)
		(end 127.908812 -255.559052)
		(width 0.0889)
		(layer "In2.Cu")
		(net "M_I_CPU1_SA_PAR")
	)
	(segment
		(start 136.967722 -255.501902)
		(end 136.976104 -255.497076)
		(width 0.0889)
		(layer "In2.Cu")
		(net "M_I_CPU1_SA_PAR")
	)
	(segment
		(start 130.753358 -255.497076)
		(end 130.76174 -255.501902)
		(width 0.0889)
		(layer "In2.Cu")
		(net "M_I_CPU1_SA_PAR")
	)
	(segment
		(start 180.737764 -253.105158)
		(end 183.175656 -253.844806)
		(width 0.14478)
		(layer "In2.Cu")
		(net "M_I_CPU1_SA_PAR")
	)
	(segment
		(start 127.908812 -255.559052)
		(end 128.005078 -255.533652)
		(width 0.0889)
		(layer "In2.Cu")
		(net "M_I_CPU1_SA_PAR")
	)
	(segment
		(start 132.267706 -255.501902)
		(end 132.276088 -255.497076)
		(width 0.0889)
		(layer "In2.Cu")
		(net "M_I_CPU1_SA_PAR")
	)
	(segment
		(start 177.558954 -253.749048)
		(end 178.157632 -253.15037)
		(width 0.14478)
		(layer "In2.Cu")
		(net "M_I_CPU1_SA_PAR")
	)
	(segment
		(start 128.507744 -255.501902)
		(end 128.516126 -255.497076)
		(width 0.0889)
		(layer "In2.Cu")
		(net "M_I_CPU1_SA_PAR")
	)
	(segment
		(start 172.188886 -255.56591)
		(end 174.537878 -255.098804)
		(width 0.14478)
		(layer "In2.Cu")
		(net "M_I_CPU1_SA_PAR")
	)
	(segment
		(start 147.29079 -256.374646)
		(end 151.179276 -256.374646)
		(width 0.14478)
		(layer "In2.Cu")
		(net "M_I_CPU1_SA_PAR")
	)
	(segment
		(start 140.15339 -255.497076)
		(end 140.161772 -255.501902)
		(width 0.0889)
		(layer "In2.Cu")
		(net "M_I_CPU1_SA_PAR")
	)
	(segment
		(start 137.907776 -255.501902)
		(end 137.916158 -255.497076)
		(width 0.0889)
		(layer "In2.Cu")
		(net "M_I_CPU1_SA_PAR")
	)
	(segment
		(start 146.471894 -256.503678)
		(end 146.859498 -256.503678)
		(width 0.0889)
		(layer "In2.Cu")
		(net "M_I_CPU1_SA_PAR")
	)
	(segment
		(start 131.693412 -255.497076)
		(end 131.701794 -255.501902)
		(width 0.0889)
		(layer "In2.Cu")
		(net "M_I_CPU1_SA_PAR")
	)
	(arc
		(start 140.161772 -255.501902)
		(mid 140.444728 -255.578079)
		(end 140.727684 -255.501902)
		(width 0.0889)
		(layer "In2.Cu")
		(net "M_I_CPU1_SA_PAR")
	)
	(arc
		(start 136.976104 -255.497076)
		(mid 137.159612 -255.451582)
		(end 137.341864 -255.501902)
		(width 0.0889)
		(layer "In2.Cu")
		(net "M_I_CPU1_SA_PAR")
	)
	(arc
		(start 129.821686 -255.501902)
		(mid 130.104642 -255.578079)
		(end 130.387598 -255.501902)
		(width 0.0889)
		(layer "In2.Cu")
		(net "M_I_CPU1_SA_PAR")
	)
	(arc
		(start 128.881886 -255.501902)
		(mid 129.164842 -255.578079)
		(end 129.447798 -255.501902)
		(width 0.0889)
		(layer "In2.Cu")
		(net "M_I_CPU1_SA_PAR")
	)
	(arc
		(start 134.147814 -255.501902)
		(mid 134.334758 -255.451647)
		(end 134.521702 -255.501902)
		(width 0.0889)
		(layer "In2.Cu")
		(net "M_I_CPU1_SA_PAR")
	)
	(arc
		(start 140.727684 -255.501902)
		(mid 140.909935 -255.451552)
		(end 141.093444 -255.497076)
		(width 0.0889)
		(layer "In2.Cu")
		(net "M_I_CPU1_SA_PAR")
	)
	(arc
		(start 133.216142 -255.497076)
		(mid 133.39965 -255.451582)
		(end 133.581902 -255.501902)
		(width 0.0889)
		(layer "In2.Cu")
		(net "M_I_CPU1_SA_PAR")
	)
	(arc
		(start 142.607792 -255.501902)
		(mid 142.794736 -255.451647)
		(end 142.98168 -255.501902)
		(width 0.0889)
		(layer "In2.Cu")
		(net "M_I_CPU1_SA_PAR")
	)
	(arc
		(start 132.276088 -255.497076)
		(mid 132.459596 -255.451582)
		(end 132.641848 -255.501902)
		(width 0.0889)
		(layer "In2.Cu")
		(net "M_I_CPU1_SA_PAR")
	)
	(arc
		(start 132.641848 -255.501902)
		(mid 132.924804 -255.578079)
		(end 133.20776 -255.501902)
		(width 0.0889)
		(layer "In2.Cu")
		(net "M_I_CPU1_SA_PAR")
	)
	(arc
		(start 142.98168 -255.501902)
		(mid 143.264636 -255.578079)
		(end 143.547592 -255.501902)
		(width 0.0889)
		(layer "In2.Cu")
		(net "M_I_CPU1_SA_PAR")
	)
	(arc
		(start 134.521702 -255.501902)
		(mid 134.804658 -255.578079)
		(end 135.087614 -255.501902)
		(width 0.0889)
		(layer "In2.Cu")
		(net "M_I_CPU1_SA_PAR")
	)
	(arc
		(start 139.221718 -255.501902)
		(mid 139.504674 -255.578079)
		(end 139.78763 -255.501902)
		(width 0.0889)
		(layer "In2.Cu")
		(net "M_I_CPU1_SA_PAR")
	)
	(arc
		(start 137.916158 -255.497076)
		(mid 138.099666 -255.451582)
		(end 138.281918 -255.501902)
		(width 0.0889)
		(layer "In2.Cu")
		(net "M_I_CPU1_SA_PAR")
	)
	(arc
		(start 129.447798 -255.501902)
		(mid 129.634742 -255.451647)
		(end 129.821686 -255.501902)
		(width 0.0889)
		(layer "In2.Cu")
		(net "M_I_CPU1_SA_PAR")
	)
	(arc
		(start 143.555974 -255.497076)
		(mid 143.739736 -255.45146)
		(end 143.922242 -255.501902)
		(width 0.0889)
		(layer "In2.Cu")
		(net "M_I_CPU1_SA_PAR")
	)
	(arc
		(start 128.005078 -255.533652)
		(mid 128.260143 -255.577003)
		(end 128.507744 -255.501902)
		(width 0.0889)
		(layer "In2.Cu")
		(net "M_I_CPU1_SA_PAR")
	)
	(arc
		(start 144.862296 -255.502156)
		(mid 145.147093 -255.620501)
		(end 145.452846 -255.660906)
		(width 0.0889)
		(layer "In2.Cu")
		(net "M_I_CPU1_SA_PAR")
	)
	(arc
		(start 136.40181 -255.501902)
		(mid 136.684766 -255.578079)
		(end 136.967722 -255.501902)
		(width 0.0889)
		(layer "In2.Cu")
		(net "M_I_CPU1_SA_PAR")
	)
	(arc
		(start 141.67612 -255.497076)
		(mid 141.859628 -255.451582)
		(end 142.04188 -255.501902)
		(width 0.0889)
		(layer "In2.Cu")
		(net "M_I_CPU1_SA_PAR")
	)
	(arc
		(start 141.101826 -255.501902)
		(mid 141.384782 -255.578079)
		(end 141.667738 -255.501902)
		(width 0.0889)
		(layer "In2.Cu")
		(net "M_I_CPU1_SA_PAR")
	)
	(arc
		(start 138.281918 -255.501902)
		(mid 138.564874 -255.578079)
		(end 138.84783 -255.501902)
		(width 0.0889)
		(layer "In2.Cu")
		(net "M_I_CPU1_SA_PAR")
	)
	(arc
		(start 137.341864 -255.501902)
		(mid 137.62482 -255.578079)
		(end 137.907776 -255.501902)
		(width 0.0889)
		(layer "In2.Cu")
		(net "M_I_CPU1_SA_PAR")
	)
	(arc
		(start 130.76174 -255.501902)
		(mid 131.044696 -255.578079)
		(end 131.327652 -255.501902)
		(width 0.0889)
		(layer "In2.Cu")
		(net "M_I_CPU1_SA_PAR")
	)
	(arc
		(start 133.581902 -255.501902)
		(mid 133.864858 -255.578079)
		(end 134.147814 -255.501902)
		(width 0.0889)
		(layer "In2.Cu")
		(net "M_I_CPU1_SA_PAR")
	)
	(arc
		(start 139.78763 -255.501902)
		(mid 139.969881 -255.451552)
		(end 140.15339 -255.497076)
		(width 0.0889)
		(layer "In2.Cu")
		(net "M_I_CPU1_SA_PAR")
	)
	(arc
		(start 128.516126 -255.497076)
		(mid 128.699634 -255.451582)
		(end 128.881886 -255.501902)
		(width 0.0889)
		(layer "In2.Cu")
		(net "M_I_CPU1_SA_PAR")
	)
	(arc
		(start 142.04188 -255.501902)
		(mid 142.324836 -255.578079)
		(end 142.607792 -255.501902)
		(width 0.0889)
		(layer "In2.Cu")
		(net "M_I_CPU1_SA_PAR")
	)
	(arc
		(start 130.387598 -255.501902)
		(mid 130.569849 -255.451552)
		(end 130.753358 -255.497076)
		(width 0.0889)
		(layer "In2.Cu")
		(net "M_I_CPU1_SA_PAR")
	)
	(arc
		(start 143.922242 -255.501902)
		(mid 144.196948 -255.578266)
		(end 144.47393 -255.510538)
		(width 0.0889)
		(layer "In2.Cu")
		(net "M_I_CPU1_SA_PAR")
	)
	(arc
		(start 136.027668 -255.501902)
		(mid 136.209919 -255.451552)
		(end 136.393428 -255.497076)
		(width 0.0889)
		(layer "In2.Cu")
		(net "M_I_CPU1_SA_PAR")
	)
	(arc
		(start 135.087614 -255.501902)
		(mid 135.269865 -255.451552)
		(end 135.453374 -255.497076)
		(width 0.0889)
		(layer "In2.Cu")
		(net "M_I_CPU1_SA_PAR")
	)
	(arc
		(start 144.488662 -255.501902)
		(mid 144.667649 -255.451732)
		(end 144.84858 -255.494282)
		(width 0.0889)
		(layer "In2.Cu")
		(net "M_I_CPU1_SA_PAR")
	)
	(arc
		(start 135.461756 -255.501902)
		(mid 135.744712 -255.578079)
		(end 136.027668 -255.501902)
		(width 0.0889)
		(layer "In2.Cu")
		(net "M_I_CPU1_SA_PAR")
	)
	(arc
		(start 131.701794 -255.501902)
		(mid 131.98475 -255.578079)
		(end 132.267706 -255.501902)
		(width 0.0889)
		(layer "In2.Cu")
		(net "M_I_CPU1_SA_PAR")
	)
	(arc
		(start 138.84783 -255.501902)
		(mid 139.034774 -255.451647)
		(end 139.221718 -255.501902)
		(width 0.0889)
		(layer "In2.Cu")
		(net "M_I_CPU1_SA_PAR")
	)
	(arc
		(start 131.327652 -255.501902)
		(mid 131.509903 -255.451552)
		(end 131.693412 -255.497076)
		(width 0.0889)
		(layer "In2.Cu")
		(net "M_I_CPU1_SA_PAR")
	)
	(segment
		(start 127.287782 -247.99036)
		(end 127.754634 -247.724422)
		(width 0.12954)
		(layer "F.Cu")
		(net "M_I_CPU1_SA_DQS_DP<9>")
	)
	(segment
		(start 144.855438 -247.394476)
		(end 144.86382 -247.399302)
		(width 0.09525)
		(layer "In2.Cu")
		(net "M_I_CPU1_SA_DQS_DP<9>")
	)
	(segment
		(start 160.61944 -243.874036)
		(end 160.815274 -243.678202)
		(width 0.16002)
		(layer "In2.Cu")
		(net "M_I_CPU1_SA_DQS_DP<9>")
	)
	(segment
		(start 163.657026 -240.83645)
		(end 165.042596 -240.83645)
		(width 0.16002)
		(layer "In2.Cu")
		(net "M_I_CPU1_SA_DQS_DP<9>")
	)
	(segment
		(start 133.206236 -247.399302)
		(end 133.214618 -247.394476)
		(width 0.09525)
		(layer "In2.Cu")
		(net "M_I_CPU1_SA_DQS_DP<9>")
	)
	(segment
		(start 167.325802 -239.403128)
		(end 167.90924 -239.986566)
		(width 0.16002)
		(layer "In2.Cu")
		(net "M_I_CPU1_SA_DQS_DP<9>")
	)
	(segment
		(start 160.61944 -244.150896)
		(end 160.61944 -243.874036)
		(width 0.16002)
		(layer "In2.Cu")
		(net "M_I_CPU1_SA_DQS_DP<9>")
	)
	(segment
		(start 161.993072 -242.777264)
		(end 161.993072 -242.500404)
		(width 0.16002)
		(layer "In2.Cu")
		(net "M_I_CPU1_SA_DQS_DP<9>")
	)
	(segment
		(start 160.946338 -245.005098)
		(end 160.946338 -244.477794)
		(width 0.16002)
		(layer "In2.Cu")
		(net "M_I_CPU1_SA_DQS_DP<9>")
	)
	(segment
		(start 145.796 -247.394476)
		(end 145.804382 -247.399302)
		(width 0.09525)
		(layer "In2.Cu")
		(net "M_I_CPU1_SA_DQS_DP<9>")
	)
	(segment
		(start 171.22267 -240.83645)
		(end 172.58665 -240.83645)
		(width 0.16002)
		(layer "In2.Cu")
		(net "M_I_CPU1_SA_DQS_DP<9>")
	)
	(segment
		(start 161.419032 -244.0051)
		(end 161.946336 -244.0051)
		(width 0.16002)
		(layer "In2.Cu")
		(net "M_I_CPU1_SA_DQS_DP<9>")
	)
	(segment
		(start 130.754882 -247.394476)
		(end 130.763264 -247.399302)
		(width 0.09525)
		(layer "In2.Cu")
		(net "M_I_CPU1_SA_DQS_DP<9>")
	)
	(segment
		(start 147.657566 -247.474994)
		(end 147.716494 -247.533922)
		(width 0.09525)
		(layer "In2.Cu")
		(net "M_I_CPU1_SA_DQS_DP<9>")
	)
	(segment
		(start 144.86382 -247.399302)
		(end 144.884648 -247.411494)
		(width 0.09525)
		(layer "In2.Cu")
		(net "M_I_CPU1_SA_DQS_DP<9>")
	)
	(segment
		(start 159.572706 -246.37873)
		(end 159.572706 -245.851426)
		(width 0.16002)
		(layer "In2.Cu")
		(net "M_I_CPU1_SA_DQS_DP<9>")
	)
	(segment
		(start 175.177196 -239.710468)
		(end 177.250852 -239.710468)
		(width 0.16002)
		(layer "In2.Cu")
		(net "M_I_CPU1_SA_DQS_DP<9>")
	)
	(segment
		(start 132.266182 -247.399302)
		(end 132.274564 -247.394476)
		(width 0.09525)
		(layer "In2.Cu")
		(net "M_I_CPU1_SA_DQS_DP<9>")
	)
	(segment
		(start 165.042596 -240.83645)
		(end 165.683438 -240.195608)
		(width 0.16002)
		(layer "In2.Cu")
		(net "M_I_CPU1_SA_DQS_DP<9>")
	)
	(segment
		(start 162.31997 -243.104162)
		(end 161.993072 -242.777264)
		(width 0.16002)
		(layer "In2.Cu")
		(net "M_I_CPU1_SA_DQS_DP<9>")
	)
	(segment
		(start 159.572706 -245.851426)
		(end 159.245808 -245.524528)
		(width 0.16002)
		(layer "In2.Cu")
		(net "M_I_CPU1_SA_DQS_DP<9>")
	)
	(segment
		(start 141.666214 -247.399302)
		(end 141.674596 -247.394476)
		(width 0.09525)
		(layer "In2.Cu")
		(net "M_I_CPU1_SA_DQS_DP<9>")
	)
	(segment
		(start 159.199072 -246.752364)
		(end 159.572706 -246.37873)
		(width 0.16002)
		(layer "In2.Cu")
		(net "M_I_CPU1_SA_DQS_DP<9>")
	)
	(segment
		(start 135.454898 -247.394476)
		(end 135.46328 -247.399302)
		(width 0.09525)
		(layer "In2.Cu")
		(net "M_I_CPU1_SA_DQS_DP<9>")
	)
	(segment
		(start 165.683438 -240.195608)
		(end 166.120318 -240.195608)
		(width 0.16002)
		(layer "In2.Cu")
		(net "M_I_CPU1_SA_DQS_DP<9>")
	)
	(segment
		(start 127.908558 -247.458992)
		(end 128.009396 -247.432322)
		(width 0.09525)
		(layer "In2.Cu")
		(net "M_I_CPU1_SA_DQS_DP<9>")
	)
	(segment
		(start 127.754634 -247.724422)
		(end 127.908558 -247.458992)
		(width 0.09525)
		(layer "In2.Cu")
		(net "M_I_CPU1_SA_DQS_DP<9>")
	)
	(segment
		(start 179.24272 -239.562132)
		(end 179.516024 -239.835436)
		(width 0.16002)
		(layer "In2.Cu")
		(net "M_I_CPU1_SA_DQS_DP<9>")
	)
	(segment
		(start 160.815274 -243.678202)
		(end 161.092134 -243.678202)
		(width 0.16002)
		(layer "In2.Cu")
		(net "M_I_CPU1_SA_DQS_DP<9>")
	)
	(segment
		(start 174.869856 -239.403128)
		(end 175.177196 -239.710468)
		(width 0.16002)
		(layer "In2.Cu")
		(net "M_I_CPU1_SA_DQS_DP<9>")
	)
	(segment
		(start 136.966198 -247.399302)
		(end 136.97458 -247.394476)
		(width 0.09525)
		(layer "In2.Cu")
		(net "M_I_CPU1_SA_DQS_DP<9>")
	)
	(segment
		(start 147.716494 -247.533922)
		(end 147.740116 -247.533922)
		(width 0.09525)
		(layer "In2.Cu")
		(net "M_I_CPU1_SA_DQS_DP<9>")
	)
	(segment
		(start 141.094968 -247.394476)
		(end 141.10335 -247.399302)
		(width 0.09525)
		(layer "In2.Cu")
		(net "M_I_CPU1_SA_DQS_DP<9>")
	)
	(segment
		(start 173.227492 -240.195608)
		(end 173.664372 -240.195608)
		(width 0.16002)
		(layer "In2.Cu")
		(net "M_I_CPU1_SA_DQS_DP<9>")
	)
	(segment
		(start 159.441642 -245.051834)
		(end 159.718502 -245.051834)
		(width 0.16002)
		(layer "In2.Cu")
		(net "M_I_CPU1_SA_DQS_DP<9>")
	)
	(segment
		(start 136.394952 -247.394476)
		(end 136.403334 -247.399302)
		(width 0.09525)
		(layer "In2.Cu")
		(net "M_I_CPU1_SA_DQS_DP<9>")
	)
	(segment
		(start 157.55747 -246.936006)
		(end 158.06801 -246.425466)
		(width 0.16002)
		(layer "In2.Cu")
		(net "M_I_CPU1_SA_DQS_DP<9>")
	)
	(segment
		(start 167.90924 -239.986566)
		(end 170.372786 -239.986566)
		(width 0.16002)
		(layer "In2.Cu")
		(net "M_I_CPU1_SA_DQS_DP<9>")
	)
	(segment
		(start 166.912798 -239.403128)
		(end 167.325802 -239.403128)
		(width 0.16002)
		(layer "In2.Cu")
		(net "M_I_CPU1_SA_DQS_DP<9>")
	)
	(segment
		(start 159.245808 -245.247668)
		(end 159.441642 -245.051834)
		(width 0.16002)
		(layer "In2.Cu")
		(net "M_I_CPU1_SA_DQS_DP<9>")
	)
	(segment
		(start 161.092134 -243.678202)
		(end 161.419032 -244.0051)
		(width 0.16002)
		(layer "In2.Cu")
		(net "M_I_CPU1_SA_DQS_DP<9>")
	)
	(segment
		(start 144.472406 -247.407938)
		(end 144.487138 -247.399302)
		(width 0.09525)
		(layer "In2.Cu")
		(net "M_I_CPU1_SA_DQS_DP<9>")
	)
	(segment
		(start 148.354796 -247.533922)
		(end 148.952712 -246.936006)
		(width 0.16002)
		(layer "In2.Cu")
		(net "M_I_CPU1_SA_DQS_DP<9>")
	)
	(segment
		(start 173.664372 -240.195608)
		(end 174.456852 -239.403128)
		(width 0.16002)
		(layer "In2.Cu")
		(net "M_I_CPU1_SA_DQS_DP<9>")
	)
	(segment
		(start 159.718502 -245.051834)
		(end 160.0454 -245.378732)
		(width 0.16002)
		(layer "In2.Cu")
		(net "M_I_CPU1_SA_DQS_DP<9>")
	)
	(segment
		(start 140.154914 -247.394476)
		(end 140.163296 -247.399302)
		(width 0.09525)
		(layer "In2.Cu")
		(net "M_I_CPU1_SA_DQS_DP<9>")
	)
	(segment
		(start 158.06801 -246.425466)
		(end 158.34487 -246.425466)
		(width 0.16002)
		(layer "In2.Cu")
		(net "M_I_CPU1_SA_DQS_DP<9>")
	)
	(segment
		(start 174.456852 -239.403128)
		(end 174.869856 -239.403128)
		(width 0.16002)
		(layer "In2.Cu")
		(net "M_I_CPU1_SA_DQS_DP<9>")
	)
	(segment
		(start 158.671768 -246.752364)
		(end 159.199072 -246.752364)
		(width 0.16002)
		(layer "In2.Cu")
		(net "M_I_CPU1_SA_DQS_DP<9>")
	)
	(segment
		(start 158.34487 -246.425466)
		(end 158.671768 -246.752364)
		(width 0.16002)
		(layer "In2.Cu")
		(net "M_I_CPU1_SA_DQS_DP<9>")
	)
	(segment
		(start 172.58665 -240.83645)
		(end 173.227492 -240.195608)
		(width 0.16002)
		(layer "In2.Cu")
		(net "M_I_CPU1_SA_DQS_DP<9>")
	)
	(segment
		(start 170.372786 -239.986566)
		(end 171.22267 -240.83645)
		(width 0.16002)
		(layer "In2.Cu")
		(net "M_I_CPU1_SA_DQS_DP<9>")
	)
	(segment
		(start 161.946336 -244.0051)
		(end 162.31997 -243.631466)
		(width 0.16002)
		(layer "In2.Cu")
		(net "M_I_CPU1_SA_DQS_DP<9>")
	)
	(segment
		(start 160.572704 -245.378732)
		(end 160.946338 -245.005098)
		(width 0.16002)
		(layer "In2.Cu")
		(net "M_I_CPU1_SA_DQS_DP<9>")
	)
	(segment
		(start 143.546068 -247.399302)
		(end 143.55445 -247.394476)
		(width 0.09525)
		(layer "In2.Cu")
		(net "M_I_CPU1_SA_DQS_DP<9>")
	)
	(segment
		(start 162.31997 -243.631466)
		(end 162.31997 -243.104162)
		(width 0.16002)
		(layer "In2.Cu")
		(net "M_I_CPU1_SA_DQS_DP<9>")
	)
	(segment
		(start 147.740116 -247.533922)
		(end 148.354796 -247.533922)
		(width 0.16002)
		(layer "In2.Cu")
		(net "M_I_CPU1_SA_DQS_DP<9>")
	)
	(segment
		(start 160.946338 -244.477794)
		(end 160.61944 -244.150896)
		(width 0.16002)
		(layer "In2.Cu")
		(net "M_I_CPU1_SA_DQS_DP<9>")
	)
	(segment
		(start 159.245808 -245.524528)
		(end 159.245808 -245.247668)
		(width 0.16002)
		(layer "In2.Cu")
		(net "M_I_CPU1_SA_DQS_DP<9>")
	)
	(segment
		(start 177.399188 -239.562132)
		(end 179.24272 -239.562132)
		(width 0.16002)
		(layer "In2.Cu")
		(net "M_I_CPU1_SA_DQS_DP<9>")
	)
	(segment
		(start 177.250852 -239.710468)
		(end 177.399188 -239.562132)
		(width 0.16002)
		(layer "In2.Cu")
		(net "M_I_CPU1_SA_DQS_DP<9>")
	)
	(segment
		(start 148.952712 -246.936006)
		(end 157.55747 -246.936006)
		(width 0.16002)
		(layer "In2.Cu")
		(net "M_I_CPU1_SA_DQS_DP<9>")
	)
	(segment
		(start 131.694936 -247.394476)
		(end 131.703318 -247.399302)
		(width 0.09525)
		(layer "In2.Cu")
		(net "M_I_CPU1_SA_DQS_DP<9>")
	)
	(segment
		(start 137.906252 -247.399302)
		(end 137.914634 -247.394476)
		(width 0.09525)
		(layer "In2.Cu")
		(net "M_I_CPU1_SA_DQS_DP<9>")
	)
	(segment
		(start 161.993072 -242.500404)
		(end 163.657026 -240.83645)
		(width 0.16002)
		(layer "In2.Cu")
		(net "M_I_CPU1_SA_DQS_DP<9>")
	)
	(segment
		(start 146.085814 -247.474994)
		(end 147.657566 -247.474994)
		(width 0.09525)
		(layer "In2.Cu")
		(net "M_I_CPU1_SA_DQS_DP<9>")
	)
	(segment
		(start 160.0454 -245.378732)
		(end 160.572704 -245.378732)
		(width 0.16002)
		(layer "In2.Cu")
		(net "M_I_CPU1_SA_DQS_DP<9>")
	)
	(segment
		(start 166.120318 -240.195608)
		(end 166.912798 -239.403128)
		(width 0.16002)
		(layer "In2.Cu")
		(net "M_I_CPU1_SA_DQS_DP<9>")
	)
	(segment
		(start 128.50622 -247.399302)
		(end 128.514602 -247.394476)
		(width 0.09525)
		(layer "In2.Cu")
		(net "M_I_CPU1_SA_DQS_DP<9>")
	)
	(arc
		(start 144.884648 -247.411494)
		(mid 145.157253 -247.47529)
		(end 145.426684 -247.399302)
		(width 0.09525)
		(layer "In2.Cu")
		(net "M_I_CPU1_SA_DQS_DP<9>")
	)
	(arc
		(start 129.82321 -247.399302)
		(mid 130.104642 -247.475057)
		(end 130.386074 -247.399302)
		(width 0.09525)
		(layer "In2.Cu")
		(net "M_I_CPU1_SA_DQS_DP<9>")
	)
	(arc
		(start 132.643372 -247.399302)
		(mid 132.924804 -247.475057)
		(end 133.206236 -247.399302)
		(width 0.09525)
		(layer "In2.Cu")
		(net "M_I_CPU1_SA_DQS_DP<9>")
	)
	(arc
		(start 141.674596 -247.394476)
		(mid 141.859628 -247.348562)
		(end 142.043404 -247.399302)
		(width 0.09525)
		(layer "In2.Cu")
		(net "M_I_CPU1_SA_DQS_DP<9>")
	)
	(arc
		(start 130.763264 -247.399302)
		(mid 131.044696 -247.475057)
		(end 131.326128 -247.399302)
		(width 0.09525)
		(layer "In2.Cu")
		(net "M_I_CPU1_SA_DQS_DP<9>")
	)
	(arc
		(start 133.583426 -247.399302)
		(mid 133.864858 -247.475057)
		(end 134.14629 -247.399302)
		(width 0.09525)
		(layer "In2.Cu")
		(net "M_I_CPU1_SA_DQS_DP<9>")
	)
	(arc
		(start 134.523226 -247.399302)
		(mid 134.804658 -247.475057)
		(end 135.08609 -247.399302)
		(width 0.09525)
		(layer "In2.Cu")
		(net "M_I_CPU1_SA_DQS_DP<9>")
	)
	(arc
		(start 142.983204 -247.399302)
		(mid 143.264636 -247.475057)
		(end 143.546068 -247.399302)
		(width 0.09525)
		(layer "In2.Cu")
		(net "M_I_CPU1_SA_DQS_DP<9>")
	)
	(arc
		(start 128.009396 -247.432322)
		(mid 128.019644 -247.436485)
		(end 128.02997 -247.44045)
		(width 0.09525)
		(layer "In2.Cu")
		(net "M_I_CPU1_SA_DQS_DP<9>")
	)
	(arc
		(start 142.606268 -247.399302)
		(mid 142.794736 -247.348625)
		(end 142.983204 -247.399302)
		(width 0.09525)
		(layer "In2.Cu")
		(net "M_I_CPU1_SA_DQS_DP<9>")
	)
	(arc
		(start 136.97458 -247.394476)
		(mid 137.159612 -247.348562)
		(end 137.343388 -247.399302)
		(width 0.09525)
		(layer "In2.Cu")
		(net "M_I_CPU1_SA_DQS_DP<9>")
	)
	(arc
		(start 135.08609 -247.399302)
		(mid 135.269865 -247.34853)
		(end 135.454898 -247.394476)
		(width 0.09525)
		(layer "In2.Cu")
		(net "M_I_CPU1_SA_DQS_DP<9>")
	)
	(arc
		(start 130.386074 -247.399302)
		(mid 130.569849 -247.34853)
		(end 130.754882 -247.394476)
		(width 0.09525)
		(layer "In2.Cu")
		(net "M_I_CPU1_SA_DQS_DP<9>")
	)
	(arc
		(start 128.514602 -247.394476)
		(mid 128.699634 -247.348562)
		(end 128.88341 -247.399302)
		(width 0.09525)
		(layer "In2.Cu")
		(net "M_I_CPU1_SA_DQS_DP<9>")
	)
	(arc
		(start 141.10335 -247.399302)
		(mid 141.384782 -247.475057)
		(end 141.666214 -247.399302)
		(width 0.09525)
		(layer "In2.Cu")
		(net "M_I_CPU1_SA_DQS_DP<9>")
	)
	(arc
		(start 140.163296 -247.399302)
		(mid 140.444728 -247.475057)
		(end 140.72616 -247.399302)
		(width 0.09525)
		(layer "In2.Cu")
		(net "M_I_CPU1_SA_DQS_DP<9>")
	)
	(arc
		(start 138.283442 -247.399302)
		(mid 138.564874 -247.475057)
		(end 138.846306 -247.399302)
		(width 0.09525)
		(layer "In2.Cu")
		(net "M_I_CPU1_SA_DQS_DP<9>")
	)
	(arc
		(start 129.446274 -247.399302)
		(mid 129.634742 -247.348625)
		(end 129.82321 -247.399302)
		(width 0.09525)
		(layer "In2.Cu")
		(net "M_I_CPU1_SA_DQS_DP<9>")
	)
	(arc
		(start 134.14629 -247.399302)
		(mid 134.334758 -247.348625)
		(end 134.523226 -247.399302)
		(width 0.09525)
		(layer "In2.Cu")
		(net "M_I_CPU1_SA_DQS_DP<9>")
	)
	(arc
		(start 137.343388 -247.399302)
		(mid 137.62482 -247.475057)
		(end 137.906252 -247.399302)
		(width 0.09525)
		(layer "In2.Cu")
		(net "M_I_CPU1_SA_DQS_DP<9>")
	)
	(arc
		(start 132.274564 -247.394476)
		(mid 132.459596 -247.348562)
		(end 132.643372 -247.399302)
		(width 0.09525)
		(layer "In2.Cu")
		(net "M_I_CPU1_SA_DQS_DP<9>")
	)
	(arc
		(start 133.214618 -247.394476)
		(mid 133.39965 -247.348562)
		(end 133.583426 -247.399302)
		(width 0.09525)
		(layer "In2.Cu")
		(net "M_I_CPU1_SA_DQS_DP<9>")
	)
	(arc
		(start 128.02997 -247.44045)
		(mid 128.272712 -247.47322)
		(end 128.50622 -247.399302)
		(width 0.09525)
		(layer "In2.Cu")
		(net "M_I_CPU1_SA_DQS_DP<9>")
	)
	(arc
		(start 145.804382 -247.399302)
		(mid 145.940089 -247.455787)
		(end 146.085814 -247.474994)
		(width 0.09525)
		(layer "In2.Cu")
		(net "M_I_CPU1_SA_DQS_DP<9>")
	)
	(arc
		(start 139.223242 -247.399302)
		(mid 139.504674 -247.475057)
		(end 139.786106 -247.399302)
		(width 0.09525)
		(layer "In2.Cu")
		(net "M_I_CPU1_SA_DQS_DP<9>")
	)
	(arc
		(start 136.026144 -247.399302)
		(mid 136.209919 -247.34853)
		(end 136.394952 -247.394476)
		(width 0.09525)
		(layer "In2.Cu")
		(net "M_I_CPU1_SA_DQS_DP<9>")
	)
	(arc
		(start 143.55445 -247.394476)
		(mid 143.739736 -247.34844)
		(end 143.923766 -247.399302)
		(width 0.09525)
		(layer "In2.Cu")
		(net "M_I_CPU1_SA_DQS_DP<9>")
	)
	(arc
		(start 128.88341 -247.399302)
		(mid 129.164842 -247.475057)
		(end 129.446274 -247.399302)
		(width 0.09525)
		(layer "In2.Cu")
		(net "M_I_CPU1_SA_DQS_DP<9>")
	)
	(arc
		(start 137.914634 -247.394476)
		(mid 138.099666 -247.348562)
		(end 138.283442 -247.399302)
		(width 0.09525)
		(layer "In2.Cu")
		(net "M_I_CPU1_SA_DQS_DP<9>")
	)
	(arc
		(start 135.46328 -247.399302)
		(mid 135.744712 -247.475057)
		(end 136.026144 -247.399302)
		(width 0.09525)
		(layer "In2.Cu")
		(net "M_I_CPU1_SA_DQS_DP<9>")
	)
	(arc
		(start 144.487138 -247.399302)
		(mid 144.670659 -247.348658)
		(end 144.855438 -247.394476)
		(width 0.09525)
		(layer "In2.Cu")
		(net "M_I_CPU1_SA_DQS_DP<9>")
	)
	(arc
		(start 143.923766 -247.399302)
		(mid 144.196948 -247.475244)
		(end 144.472406 -247.407938)
		(width 0.09525)
		(layer "In2.Cu")
		(net "M_I_CPU1_SA_DQS_DP<9>")
	)
	(arc
		(start 138.846306 -247.399302)
		(mid 139.034774 -247.348625)
		(end 139.223242 -247.399302)
		(width 0.09525)
		(layer "In2.Cu")
		(net "M_I_CPU1_SA_DQS_DP<9>")
	)
	(arc
		(start 140.72616 -247.399302)
		(mid 140.909935 -247.34853)
		(end 141.094968 -247.394476)
		(width 0.09525)
		(layer "In2.Cu")
		(net "M_I_CPU1_SA_DQS_DP<9>")
	)
	(arc
		(start 136.403334 -247.399302)
		(mid 136.684766 -247.475057)
		(end 136.966198 -247.399302)
		(width 0.09525)
		(layer "In2.Cu")
		(net "M_I_CPU1_SA_DQS_DP<9>")
	)
	(arc
		(start 142.043404 -247.399302)
		(mid 142.324836 -247.475057)
		(end 142.606268 -247.399302)
		(width 0.09525)
		(layer "In2.Cu")
		(net "M_I_CPU1_SA_DQS_DP<9>")
	)
	(arc
		(start 131.326128 -247.399302)
		(mid 131.509903 -247.34853)
		(end 131.694936 -247.394476)
		(width 0.09525)
		(layer "In2.Cu")
		(net "M_I_CPU1_SA_DQS_DP<9>")
	)
	(arc
		(start 139.786106 -247.399302)
		(mid 139.969881 -247.34853)
		(end 140.154914 -247.394476)
		(width 0.09525)
		(layer "In2.Cu")
		(net "M_I_CPU1_SA_DQS_DP<9>")
	)
	(arc
		(start 131.703318 -247.399302)
		(mid 131.98475 -247.475057)
		(end 132.266182 -247.399302)
		(width 0.09525)
		(layer "In2.Cu")
		(net "M_I_CPU1_SA_DQS_DP<9>")
	)
	(arc
		(start 145.426684 -247.399302)
		(mid 145.610713 -247.348403)
		(end 145.796 -247.394476)
		(width 0.09525)
		(layer "In2.Cu")
		(net "M_I_CPU1_SA_DQS_DP<9>")
	)
	(segment
		(start 127.287782 -243.130324)
		(end 127.754634 -242.864386)
		(width 0.12954)
		(layer "F.Cu")
		(net "M_I_CPU1_SA_DQS_DP<8>")
	)
	(segment
		(start 156.00172 -236.854746)
		(end 156.198316 -236.65815)
		(width 0.16002)
		(layer "In2.Cu")
		(net "M_I_CPU1_SA_DQS_DP<8>")
	)
	(segment
		(start 156.00172 -237.131606)
		(end 156.00172 -236.854746)
		(width 0.16002)
		(layer "In2.Cu")
		(net "M_I_CPU1_SA_DQS_DP<8>")
	)
	(segment
		(start 154.824684 -238.031782)
		(end 155.10129 -238.031782)
		(width 0.16002)
		(layer "In2.Cu")
		(net "M_I_CPU1_SA_DQS_DP<8>")
	)
	(segment
		(start 147.2946 -241.3)
		(end 147.397724 -241.196876)
		(width 0.09525)
		(layer "In2.Cu")
		(net "M_I_CPU1_SA_DQS_DP<8>")
	)
	(segment
		(start 153.254456 -239.87887)
		(end 153.254456 -239.60201)
		(width 0.16002)
		(layer "In2.Cu")
		(net "M_I_CPU1_SA_DQS_DP<8>")
	)
	(segment
		(start 136.966198 -242.539266)
		(end 136.97458 -242.53444)
		(width 0.09525)
		(layer "In2.Cu")
		(net "M_I_CPU1_SA_DQS_DP<8>")
	)
	(segment
		(start 146.170142 -242.262914)
		(end 146.304762 -242.128294)
		(width 0.09525)
		(layer "In2.Cu")
		(net "M_I_CPU1_SA_DQS_DP<8>")
	)
	(segment
		(start 152.956768 -241.255804)
		(end 153.5303 -240.682272)
		(width 0.16002)
		(layer "In2.Cu")
		(net "M_I_CPU1_SA_DQS_DP<8>")
	)
	(segment
		(start 155.904692 -238.30788)
		(end 156.277564 -237.935008)
		(width 0.16002)
		(layer "In2.Cu")
		(net "M_I_CPU1_SA_DQS_DP<8>")
	)
	(segment
		(start 165.683438 -230.845614)
		(end 166.120318 -230.845614)
		(width 0.16002)
		(layer "In2.Cu")
		(net "M_I_CPU1_SA_DQS_DP<8>")
	)
	(segment
		(start 177.399188 -230.212138)
		(end 179.24272 -230.212138)
		(width 0.16002)
		(layer "In2.Cu")
		(net "M_I_CPU1_SA_DQS_DP<8>")
	)
	(segment
		(start 153.727658 -239.405414)
		(end 154.003756 -239.681512)
		(width 0.16002)
		(layer "In2.Cu")
		(net "M_I_CPU1_SA_DQS_DP<8>")
	)
	(segment
		(start 127.754634 -242.864386)
		(end 127.908558 -242.598956)
		(width 0.09525)
		(layer "In2.Cu")
		(net "M_I_CPU1_SA_DQS_DP<8>")
	)
	(segment
		(start 172.862494 -231.210612)
		(end 173.227492 -230.845614)
		(width 0.16002)
		(layer "In2.Cu")
		(net "M_I_CPU1_SA_DQS_DP<8>")
	)
	(segment
		(start 165.318694 -231.210358)
		(end 165.683438 -230.845614)
		(width 0.16002)
		(layer "In2.Cu")
		(net "M_I_CPU1_SA_DQS_DP<8>")
	)
	(segment
		(start 157.278324 -236.934248)
		(end 163.002214 -231.210358)
		(width 0.16002)
		(layer "In2.Cu")
		(net "M_I_CPU1_SA_DQS_DP<8>")
	)
	(segment
		(start 147.722336 -241.255804)
		(end 147.745958 -241.255804)
		(width 0.09525)
		(layer "In2.Cu")
		(net "M_I_CPU1_SA_DQS_DP<8>")
	)
	(segment
		(start 147.2946 -241.739928)
		(end 147.2946 -241.3)
		(width 0.09525)
		(layer "In2.Cu")
		(net "M_I_CPU1_SA_DQS_DP<8>")
	)
	(segment
		(start 145.541492 -242.451128)
		(end 145.729706 -242.262914)
		(width 0.09525)
		(layer "In2.Cu")
		(net "M_I_CPU1_SA_DQS_DP<8>")
	)
	(segment
		(start 155.377388 -238.30788)
		(end 155.904692 -238.30788)
		(width 0.16002)
		(layer "In2.Cu")
		(net "M_I_CPU1_SA_DQS_DP<8>")
	)
	(segment
		(start 131.694936 -242.53444)
		(end 131.703318 -242.539266)
		(width 0.09525)
		(layer "In2.Cu")
		(net "M_I_CPU1_SA_DQS_DP<8>")
	)
	(segment
		(start 166.120318 -230.845614)
		(end 166.912798 -230.053134)
		(width 0.16002)
		(layer "In2.Cu")
		(net "M_I_CPU1_SA_DQS_DP<8>")
	)
	(segment
		(start 156.75102 -236.934248)
		(end 157.278324 -236.934248)
		(width 0.16002)
		(layer "In2.Cu")
		(net "M_I_CPU1_SA_DQS_DP<8>")
	)
	(segment
		(start 137.906252 -242.539266)
		(end 137.914634 -242.53444)
		(width 0.09525)
		(layer "In2.Cu")
		(net "M_I_CPU1_SA_DQS_DP<8>")
	)
	(segment
		(start 141.666214 -242.539266)
		(end 141.674596 -242.53444)
		(width 0.09525)
		(layer "In2.Cu")
		(net "M_I_CPU1_SA_DQS_DP<8>")
	)
	(segment
		(start 156.474922 -236.65815)
		(end 156.75102 -236.934248)
		(width 0.16002)
		(layer "In2.Cu")
		(net "M_I_CPU1_SA_DQS_DP<8>")
	)
	(segment
		(start 144.851882 -242.532408)
		(end 144.86382 -242.539266)
		(width 0.09525)
		(layer "In2.Cu")
		(net "M_I_CPU1_SA_DQS_DP<8>")
	)
	(segment
		(start 144.47647 -242.545362)
		(end 144.486884 -242.539266)
		(width 0.09525)
		(layer "In2.Cu")
		(net "M_I_CPU1_SA_DQS_DP<8>")
	)
	(segment
		(start 135.454898 -242.53444)
		(end 135.46328 -242.539266)
		(width 0.09525)
		(layer "In2.Cu")
		(net "M_I_CPU1_SA_DQS_DP<8>")
	)
	(segment
		(start 141.094968 -242.53444)
		(end 141.10335 -242.539266)
		(width 0.09525)
		(layer "In2.Cu")
		(net "M_I_CPU1_SA_DQS_DP<8>")
	)
	(segment
		(start 153.254456 -239.60201)
		(end 153.451052 -239.405414)
		(width 0.16002)
		(layer "In2.Cu")
		(net "M_I_CPU1_SA_DQS_DP<8>")
	)
	(segment
		(start 170.946826 -231.210612)
		(end 172.862494 -231.210612)
		(width 0.16002)
		(layer "In2.Cu")
		(net "M_I_CPU1_SA_DQS_DP<8>")
	)
	(segment
		(start 154.003756 -239.681512)
		(end 154.53106 -239.681512)
		(width 0.16002)
		(layer "In2.Cu")
		(net "M_I_CPU1_SA_DQS_DP<8>")
	)
	(segment
		(start 143.546068 -242.539266)
		(end 143.55445 -242.53444)
		(width 0.09525)
		(layer "In2.Cu")
		(net "M_I_CPU1_SA_DQS_DP<8>")
	)
	(segment
		(start 154.53106 -239.681512)
		(end 154.903932 -239.30864)
		(width 0.16002)
		(layer "In2.Cu")
		(net "M_I_CPU1_SA_DQS_DP<8>")
	)
	(segment
		(start 144.86382 -242.539266)
		(end 144.887188 -242.552728)
		(width 0.09525)
		(layer "In2.Cu")
		(net "M_I_CPU1_SA_DQS_DP<8>")
	)
	(segment
		(start 130.754882 -242.53444)
		(end 130.763264 -242.539266)
		(width 0.09525)
		(layer "In2.Cu")
		(net "M_I_CPU1_SA_DQS_DP<8>")
	)
	(segment
		(start 146.304762 -242.128294)
		(end 146.906234 -242.128294)
		(width 0.09525)
		(layer "In2.Cu")
		(net "M_I_CPU1_SA_DQS_DP<8>")
	)
	(segment
		(start 170.096688 -230.360474)
		(end 170.946826 -231.210612)
		(width 0.16002)
		(layer "In2.Cu")
		(net "M_I_CPU1_SA_DQS_DP<8>")
	)
	(segment
		(start 156.277564 -237.935008)
		(end 156.277564 -237.40745)
		(width 0.16002)
		(layer "In2.Cu")
		(net "M_I_CPU1_SA_DQS_DP<8>")
	)
	(segment
		(start 127.908558 -242.598956)
		(end 128.009396 -242.572286)
		(width 0.09525)
		(layer "In2.Cu")
		(net "M_I_CPU1_SA_DQS_DP<8>")
	)
	(segment
		(start 173.227492 -230.845614)
		(end 173.664372 -230.845614)
		(width 0.16002)
		(layer "In2.Cu")
		(net "M_I_CPU1_SA_DQS_DP<8>")
	)
	(segment
		(start 128.50622 -242.539266)
		(end 128.514602 -242.53444)
		(width 0.09525)
		(layer "In2.Cu")
		(net "M_I_CPU1_SA_DQS_DP<8>")
	)
	(segment
		(start 177.250852 -230.360474)
		(end 177.399188 -230.212138)
		(width 0.16002)
		(layer "In2.Cu")
		(net "M_I_CPU1_SA_DQS_DP<8>")
	)
	(segment
		(start 145.729706 -242.262914)
		(end 146.170142 -242.262914)
		(width 0.09525)
		(layer "In2.Cu")
		(net "M_I_CPU1_SA_DQS_DP<8>")
	)
	(segment
		(start 173.664372 -230.845614)
		(end 174.456852 -230.053134)
		(width 0.16002)
		(layer "In2.Cu")
		(net "M_I_CPU1_SA_DQS_DP<8>")
	)
	(segment
		(start 153.5303 -240.154714)
		(end 153.254456 -239.87887)
		(width 0.16002)
		(layer "In2.Cu")
		(net "M_I_CPU1_SA_DQS_DP<8>")
	)
	(segment
		(start 154.903932 -239.30864)
		(end 154.903932 -238.781082)
		(width 0.16002)
		(layer "In2.Cu")
		(net "M_I_CPU1_SA_DQS_DP<8>")
	)
	(segment
		(start 146.906234 -242.128294)
		(end 147.2946 -241.739928)
		(width 0.09525)
		(layer "In2.Cu")
		(net "M_I_CPU1_SA_DQS_DP<8>")
	)
	(segment
		(start 147.397724 -241.196876)
		(end 147.663408 -241.196876)
		(width 0.09525)
		(layer "In2.Cu")
		(net "M_I_CPU1_SA_DQS_DP<8>")
	)
	(segment
		(start 166.912798 -230.053134)
		(end 167.325802 -230.053134)
		(width 0.16002)
		(layer "In2.Cu")
		(net "M_I_CPU1_SA_DQS_DP<8>")
	)
	(segment
		(start 154.903932 -238.781082)
		(end 154.628088 -238.505238)
		(width 0.16002)
		(layer "In2.Cu")
		(net "M_I_CPU1_SA_DQS_DP<8>")
	)
	(segment
		(start 174.456852 -230.053134)
		(end 174.869856 -230.053134)
		(width 0.16002)
		(layer "In2.Cu")
		(net "M_I_CPU1_SA_DQS_DP<8>")
	)
	(segment
		(start 155.10129 -238.031782)
		(end 155.377388 -238.30788)
		(width 0.16002)
		(layer "In2.Cu")
		(net "M_I_CPU1_SA_DQS_DP<8>")
	)
	(segment
		(start 163.002214 -231.210358)
		(end 165.318694 -231.210358)
		(width 0.16002)
		(layer "In2.Cu")
		(net "M_I_CPU1_SA_DQS_DP<8>")
	)
	(segment
		(start 156.198316 -236.65815)
		(end 156.474922 -236.65815)
		(width 0.16002)
		(layer "In2.Cu")
		(net "M_I_CPU1_SA_DQS_DP<8>")
	)
	(segment
		(start 175.177196 -230.360474)
		(end 177.250852 -230.360474)
		(width 0.16002)
		(layer "In2.Cu")
		(net "M_I_CPU1_SA_DQS_DP<8>")
	)
	(segment
		(start 153.451052 -239.405414)
		(end 153.727658 -239.405414)
		(width 0.16002)
		(layer "In2.Cu")
		(net "M_I_CPU1_SA_DQS_DP<8>")
	)
	(segment
		(start 147.663408 -241.196876)
		(end 147.722336 -241.255804)
		(width 0.09525)
		(layer "In2.Cu")
		(net "M_I_CPU1_SA_DQS_DP<8>")
	)
	(segment
		(start 179.24272 -230.212138)
		(end 179.516024 -230.485442)
		(width 0.16002)
		(layer "In2.Cu")
		(net "M_I_CPU1_SA_DQS_DP<8>")
	)
	(segment
		(start 153.5303 -240.682272)
		(end 153.5303 -240.154714)
		(width 0.16002)
		(layer "In2.Cu")
		(net "M_I_CPU1_SA_DQS_DP<8>")
	)
	(segment
		(start 167.325802 -230.053134)
		(end 167.633142 -230.360474)
		(width 0.16002)
		(layer "In2.Cu")
		(net "M_I_CPU1_SA_DQS_DP<8>")
	)
	(segment
		(start 154.628088 -238.505238)
		(end 154.628088 -238.228378)
		(width 0.16002)
		(layer "In2.Cu")
		(net "M_I_CPU1_SA_DQS_DP<8>")
	)
	(segment
		(start 140.154914 -242.53444)
		(end 140.163296 -242.539266)
		(width 0.09525)
		(layer "In2.Cu")
		(net "M_I_CPU1_SA_DQS_DP<8>")
	)
	(segment
		(start 132.266182 -242.539266)
		(end 132.274564 -242.53444)
		(width 0.09525)
		(layer "In2.Cu")
		(net "M_I_CPU1_SA_DQS_DP<8>")
	)
	(segment
		(start 136.394952 -242.53444)
		(end 136.403334 -242.539266)
		(width 0.09525)
		(layer "In2.Cu")
		(net "M_I_CPU1_SA_DQS_DP<8>")
	)
	(segment
		(start 156.277564 -237.40745)
		(end 156.00172 -237.131606)
		(width 0.16002)
		(layer "In2.Cu")
		(net "M_I_CPU1_SA_DQS_DP<8>")
	)
	(segment
		(start 167.633142 -230.360474)
		(end 170.096688 -230.360474)
		(width 0.16002)
		(layer "In2.Cu")
		(net "M_I_CPU1_SA_DQS_DP<8>")
	)
	(segment
		(start 174.869856 -230.053134)
		(end 175.177196 -230.360474)
		(width 0.16002)
		(layer "In2.Cu")
		(net "M_I_CPU1_SA_DQS_DP<8>")
	)
	(segment
		(start 133.206236 -242.539266)
		(end 133.214618 -242.53444)
		(width 0.09525)
		(layer "In2.Cu")
		(net "M_I_CPU1_SA_DQS_DP<8>")
	)
	(segment
		(start 147.745958 -241.255804)
		(end 152.956768 -241.255804)
		(width 0.16002)
		(layer "In2.Cu")
		(net "M_I_CPU1_SA_DQS_DP<8>")
	)
	(segment
		(start 154.628088 -238.228378)
		(end 154.824684 -238.031782)
		(width 0.16002)
		(layer "In2.Cu")
		(net "M_I_CPU1_SA_DQS_DP<8>")
	)
	(arc
		(start 133.583426 -242.539266)
		(mid 133.864858 -242.615021)
		(end 134.14629 -242.539266)
		(width 0.09525)
		(layer "In2.Cu")
		(net "M_I_CPU1_SA_DQS_DP<8>")
	)
	(arc
		(start 135.46328 -242.539266)
		(mid 135.744712 -242.615021)
		(end 136.026144 -242.539266)
		(width 0.09525)
		(layer "In2.Cu")
		(net "M_I_CPU1_SA_DQS_DP<8>")
	)
	(arc
		(start 140.72616 -242.539266)
		(mid 140.909935 -242.488494)
		(end 141.094968 -242.53444)
		(width 0.09525)
		(layer "In2.Cu")
		(net "M_I_CPU1_SA_DQS_DP<8>")
	)
	(arc
		(start 142.983204 -242.539266)
		(mid 143.264636 -242.615021)
		(end 143.546068 -242.539266)
		(width 0.09525)
		(layer "In2.Cu")
		(net "M_I_CPU1_SA_DQS_DP<8>")
	)
	(arc
		(start 129.446274 -242.539266)
		(mid 129.634742 -242.488589)
		(end 129.82321 -242.539266)
		(width 0.09525)
		(layer "In2.Cu")
		(net "M_I_CPU1_SA_DQS_DP<8>")
	)
	(arc
		(start 128.02997 -242.580414)
		(mid 128.272712 -242.613184)
		(end 128.50622 -242.539266)
		(width 0.09525)
		(layer "In2.Cu")
		(net "M_I_CPU1_SA_DQS_DP<8>")
	)
	(arc
		(start 133.214618 -242.53444)
		(mid 133.39965 -242.488526)
		(end 133.583426 -242.539266)
		(width 0.09525)
		(layer "In2.Cu")
		(net "M_I_CPU1_SA_DQS_DP<8>")
	)
	(arc
		(start 136.026144 -242.539266)
		(mid 136.209919 -242.488494)
		(end 136.394952 -242.53444)
		(width 0.09525)
		(layer "In2.Cu")
		(net "M_I_CPU1_SA_DQS_DP<8>")
	)
	(arc
		(start 130.386074 -242.539266)
		(mid 130.569849 -242.488494)
		(end 130.754882 -242.53444)
		(width 0.09525)
		(layer "In2.Cu")
		(net "M_I_CPU1_SA_DQS_DP<8>")
	)
	(arc
		(start 137.914634 -242.53444)
		(mid 138.099666 -242.488526)
		(end 138.283442 -242.539266)
		(width 0.09525)
		(layer "In2.Cu")
		(net "M_I_CPU1_SA_DQS_DP<8>")
	)
	(arc
		(start 129.82321 -242.539266)
		(mid 130.104642 -242.615021)
		(end 130.386074 -242.539266)
		(width 0.09525)
		(layer "In2.Cu")
		(net "M_I_CPU1_SA_DQS_DP<8>")
	)
	(arc
		(start 143.55445 -242.53444)
		(mid 143.739736 -242.488404)
		(end 143.923766 -242.539266)
		(width 0.09525)
		(layer "In2.Cu")
		(net "M_I_CPU1_SA_DQS_DP<8>")
	)
	(arc
		(start 141.10335 -242.539266)
		(mid 141.384782 -242.615021)
		(end 141.666214 -242.539266)
		(width 0.09525)
		(layer "In2.Cu")
		(net "M_I_CPU1_SA_DQS_DP<8>")
	)
	(arc
		(start 128.514602 -242.53444)
		(mid 128.699634 -242.488526)
		(end 128.88341 -242.539266)
		(width 0.09525)
		(layer "In2.Cu")
		(net "M_I_CPU1_SA_DQS_DP<8>")
	)
	(arc
		(start 144.486884 -242.539266)
		(mid 144.6685 -242.488529)
		(end 144.851882 -242.532408)
		(width 0.09525)
		(layer "In2.Cu")
		(net "M_I_CPU1_SA_DQS_DP<8>")
	)
	(arc
		(start 137.343388 -242.539266)
		(mid 137.62482 -242.615021)
		(end 137.906252 -242.539266)
		(width 0.09525)
		(layer "In2.Cu")
		(net "M_I_CPU1_SA_DQS_DP<8>")
	)
	(arc
		(start 131.326128 -242.539266)
		(mid 131.509903 -242.488494)
		(end 131.694936 -242.53444)
		(width 0.09525)
		(layer "In2.Cu")
		(net "M_I_CPU1_SA_DQS_DP<8>")
	)
	(arc
		(start 145.426938 -242.539266)
		(mid 145.487075 -242.498912)
		(end 145.541492 -242.451128)
		(width 0.09525)
		(layer "In2.Cu")
		(net "M_I_CPU1_SA_DQS_DP<8>")
	)
	(arc
		(start 128.88341 -242.539266)
		(mid 129.164842 -242.615021)
		(end 129.446274 -242.539266)
		(width 0.09525)
		(layer "In2.Cu")
		(net "M_I_CPU1_SA_DQS_DP<8>")
	)
	(arc
		(start 136.403334 -242.539266)
		(mid 136.684766 -242.615021)
		(end 136.966198 -242.539266)
		(width 0.09525)
		(layer "In2.Cu")
		(net "M_I_CPU1_SA_DQS_DP<8>")
	)
	(arc
		(start 142.606268 -242.539266)
		(mid 142.794736 -242.488589)
		(end 142.983204 -242.539266)
		(width 0.09525)
		(layer "In2.Cu")
		(net "M_I_CPU1_SA_DQS_DP<8>")
	)
	(arc
		(start 135.08609 -242.539266)
		(mid 135.269865 -242.488494)
		(end 135.454898 -242.53444)
		(width 0.09525)
		(layer "In2.Cu")
		(net "M_I_CPU1_SA_DQS_DP<8>")
	)
	(arc
		(start 140.163296 -242.539266)
		(mid 140.444728 -242.615021)
		(end 140.72616 -242.539266)
		(width 0.09525)
		(layer "In2.Cu")
		(net "M_I_CPU1_SA_DQS_DP<8>")
	)
	(arc
		(start 144.887188 -242.552728)
		(mid 145.158781 -242.615173)
		(end 145.426938 -242.539266)
		(width 0.09525)
		(layer "In2.Cu")
		(net "M_I_CPU1_SA_DQS_DP<8>")
	)
	(arc
		(start 128.009396 -242.572286)
		(mid 128.019644 -242.576449)
		(end 128.02997 -242.580414)
		(width 0.09525)
		(layer "In2.Cu")
		(net "M_I_CPU1_SA_DQS_DP<8>")
	)
	(arc
		(start 142.043404 -242.539266)
		(mid 142.324836 -242.615021)
		(end 142.606268 -242.539266)
		(width 0.09525)
		(layer "In2.Cu")
		(net "M_I_CPU1_SA_DQS_DP<8>")
	)
	(arc
		(start 132.643372 -242.539266)
		(mid 132.924804 -242.615021)
		(end 133.206236 -242.539266)
		(width 0.09525)
		(layer "In2.Cu")
		(net "M_I_CPU1_SA_DQS_DP<8>")
	)
	(arc
		(start 130.763264 -242.539266)
		(mid 131.044696 -242.615021)
		(end 131.326128 -242.539266)
		(width 0.09525)
		(layer "In2.Cu")
		(net "M_I_CPU1_SA_DQS_DP<8>")
	)
	(arc
		(start 141.674596 -242.53444)
		(mid 141.859628 -242.488526)
		(end 142.043404 -242.539266)
		(width 0.09525)
		(layer "In2.Cu")
		(net "M_I_CPU1_SA_DQS_DP<8>")
	)
	(arc
		(start 138.283442 -242.539266)
		(mid 138.564874 -242.615021)
		(end 138.846306 -242.539266)
		(width 0.09525)
		(layer "In2.Cu")
		(net "M_I_CPU1_SA_DQS_DP<8>")
	)
	(arc
		(start 132.274564 -242.53444)
		(mid 132.459596 -242.488526)
		(end 132.643372 -242.539266)
		(width 0.09525)
		(layer "In2.Cu")
		(net "M_I_CPU1_SA_DQS_DP<8>")
	)
	(arc
		(start 143.923766 -242.539266)
		(mid 144.199309 -242.615115)
		(end 144.47647 -242.545362)
		(width 0.09525)
		(layer "In2.Cu")
		(net "M_I_CPU1_SA_DQS_DP<8>")
	)
	(arc
		(start 131.703318 -242.539266)
		(mid 131.98475 -242.615021)
		(end 132.266182 -242.539266)
		(width 0.09525)
		(layer "In2.Cu")
		(net "M_I_CPU1_SA_DQS_DP<8>")
	)
	(arc
		(start 139.786106 -242.539266)
		(mid 139.969881 -242.488494)
		(end 140.154914 -242.53444)
		(width 0.09525)
		(layer "In2.Cu")
		(net "M_I_CPU1_SA_DQS_DP<8>")
	)
	(arc
		(start 134.14629 -242.539266)
		(mid 134.334758 -242.488589)
		(end 134.523226 -242.539266)
		(width 0.09525)
		(layer "In2.Cu")
		(net "M_I_CPU1_SA_DQS_DP<8>")
	)
	(arc
		(start 134.523226 -242.539266)
		(mid 134.804658 -242.615021)
		(end 135.08609 -242.539266)
		(width 0.09525)
		(layer "In2.Cu")
		(net "M_I_CPU1_SA_DQS_DP<8>")
	)
	(arc
		(start 136.97458 -242.53444)
		(mid 137.159612 -242.488526)
		(end 137.343388 -242.539266)
		(width 0.09525)
		(layer "In2.Cu")
		(net "M_I_CPU1_SA_DQS_DP<8>")
	)
	(arc
		(start 139.223242 -242.539266)
		(mid 139.504674 -242.615021)
		(end 139.786106 -242.539266)
		(width 0.09525)
		(layer "In2.Cu")
		(net "M_I_CPU1_SA_DQS_DP<8>")
	)
	(arc
		(start 138.846306 -242.539266)
		(mid 139.034774 -242.488589)
		(end 139.223242 -242.539266)
		(width 0.09525)
		(layer "In2.Cu")
		(net "M_I_CPU1_SA_DQS_DP<8>")
	)
	(segment
		(start 127.287782 -238.270288)
		(end 127.754634 -238.00435)
		(width 0.12954)
		(layer "F.Cu")
		(net "M_I_CPU1_SA_DQS_DP<7>")
	)
	(segment
		(start 167.633142 -221.01048)
		(end 170.096688 -221.01048)
		(width 0.16002)
		(layer "In2.Cu")
		(net "M_I_CPU1_SA_DQS_DP<7>")
	)
	(segment
		(start 143.73479 -237.627922)
		(end 143.914114 -237.627922)
		(width 0.09525)
		(layer "In2.Cu")
		(net "M_I_CPU1_SA_DQS_DP<7>")
	)
	(segment
		(start 165.318694 -221.860364)
		(end 165.683438 -221.49562)
		(width 0.16002)
		(layer "In2.Cu")
		(net "M_I_CPU1_SA_DQS_DP<7>")
	)
	(segment
		(start 149.795484 -233.789474)
		(end 149.99208 -233.592878)
		(width 0.16002)
		(layer "In2.Cu")
		(net "M_I_CPU1_SA_DQS_DP<7>")
	)
	(segment
		(start 135.454898 -237.674404)
		(end 135.46328 -237.67923)
		(width 0.09525)
		(layer "In2.Cu")
		(net "M_I_CPU1_SA_DQS_DP<7>")
	)
	(segment
		(start 170.096688 -221.01048)
		(end 170.946572 -221.860364)
		(width 0.16002)
		(layer "In2.Cu")
		(net "M_I_CPU1_SA_DQS_DP<7>")
	)
	(segment
		(start 144.937734 -236.850174)
		(end 145.11528 -236.776514)
		(width 0.09525)
		(layer "In2.Cu")
		(net "M_I_CPU1_SA_DQS_DP<7>")
	)
	(segment
		(start 153.288238 -231.117648)
		(end 153.815542 -231.117648)
		(width 0.16002)
		(layer "In2.Cu")
		(net "M_I_CPU1_SA_DQS_DP<7>")
	)
	(segment
		(start 177.399188 -220.862144)
		(end 179.242974 -220.862144)
		(width 0.16002)
		(layer "In2.Cu")
		(net "M_I_CPU1_SA_DQS_DP<7>")
	)
	(segment
		(start 172.862748 -221.860364)
		(end 173.227492 -221.49562)
		(width 0.16002)
		(layer "In2.Cu")
		(net "M_I_CPU1_SA_DQS_DP<7>")
	)
	(segment
		(start 174.869856 -220.70314)
		(end 175.177196 -221.01048)
		(width 0.16002)
		(layer "In2.Cu")
		(net "M_I_CPU1_SA_DQS_DP<7>")
	)
	(segment
		(start 153.91638 -229.668578)
		(end 161.724594 -221.860364)
		(width 0.16002)
		(layer "In2.Cu")
		(net "M_I_CPU1_SA_DQS_DP<7>")
	)
	(segment
		(start 166.120318 -221.49562)
		(end 166.912798 -220.70314)
		(width 0.16002)
		(layer "In2.Cu")
		(net "M_I_CPU1_SA_DQS_DP<7>")
	)
	(segment
		(start 150.26894 -233.592878)
		(end 150.540974 -233.864912)
		(width 0.16002)
		(layer "In2.Cu")
		(net "M_I_CPU1_SA_DQS_DP<7>")
	)
	(segment
		(start 144.21866 -237.5281)
		(end 144.37487 -237.413292)
		(width 0.09525)
		(layer "In2.Cu")
		(net "M_I_CPU1_SA_DQS_DP<7>")
	)
	(segment
		(start 140.154914 -237.674404)
		(end 140.163296 -237.67923)
		(width 0.09525)
		(layer "In2.Cu")
		(net "M_I_CPU1_SA_DQS_DP<7>")
	)
	(segment
		(start 136.394952 -237.674404)
		(end 136.403334 -237.67923)
		(width 0.09525)
		(layer "In2.Cu")
		(net "M_I_CPU1_SA_DQS_DP<7>")
	)
	(segment
		(start 141.666214 -237.67923)
		(end 141.674596 -237.674404)
		(width 0.09525)
		(layer "In2.Cu")
		(net "M_I_CPU1_SA_DQS_DP<7>")
	)
	(segment
		(start 127.754634 -238.00435)
		(end 127.908558 -237.73892)
		(width 0.09525)
		(layer "In2.Cu")
		(net "M_I_CPU1_SA_DQS_DP<7>")
	)
	(segment
		(start 142.983204 -237.67923)
		(end 142.983458 -237.67923)
		(width 0.09525)
		(layer "In2.Cu")
		(net "M_I_CPU1_SA_DQS_DP<7>")
	)
	(segment
		(start 145.11528 -236.776514)
		(end 145.791174 -236.776514)
		(width 0.09525)
		(layer "In2.Cu")
		(net "M_I_CPU1_SA_DQS_DP<7>")
	)
	(segment
		(start 136.966198 -237.67923)
		(end 136.97458 -237.674404)
		(width 0.09525)
		(layer "In2.Cu")
		(net "M_I_CPU1_SA_DQS_DP<7>")
	)
	(segment
		(start 151.914606 -232.49128)
		(end 152.44191 -232.49128)
		(width 0.16002)
		(layer "In2.Cu")
		(net "M_I_CPU1_SA_DQS_DP<7>")
	)
	(segment
		(start 131.694936 -237.674404)
		(end 131.703318 -237.67923)
		(width 0.09525)
		(layer "In2.Cu")
		(net "M_I_CPU1_SA_DQS_DP<7>")
	)
	(segment
		(start 151.068278 -233.864912)
		(end 151.44115 -233.49204)
		(width 0.16002)
		(layer "In2.Cu")
		(net "M_I_CPU1_SA_DQS_DP<7>")
	)
	(segment
		(start 152.542748 -231.04221)
		(end 152.739344 -230.845614)
		(width 0.16002)
		(layer "In2.Cu")
		(net "M_I_CPU1_SA_DQS_DP<7>")
	)
	(segment
		(start 147.693634 -235.373164)
		(end 147.717256 -235.373164)
		(width 0.09525)
		(layer "In2.Cu")
		(net "M_I_CPU1_SA_DQS_DP<7>")
	)
	(segment
		(start 133.206236 -237.67923)
		(end 133.214618 -237.674404)
		(width 0.09525)
		(layer "In2.Cu")
		(net "M_I_CPU1_SA_DQS_DP<7>")
	)
	(segment
		(start 173.664372 -221.49562)
		(end 174.456852 -220.70314)
		(width 0.16002)
		(layer "In2.Cu")
		(net "M_I_CPU1_SA_DQS_DP<7>")
	)
	(segment
		(start 152.542748 -231.31907)
		(end 152.542748 -231.04221)
		(width 0.16002)
		(layer "In2.Cu")
		(net "M_I_CPU1_SA_DQS_DP<7>")
	)
	(segment
		(start 150.067518 -234.338368)
		(end 149.795484 -234.066334)
		(width 0.16002)
		(layer "In2.Cu")
		(net "M_I_CPU1_SA_DQS_DP<7>")
	)
	(segment
		(start 150.067518 -234.865672)
		(end 150.067518 -234.338368)
		(width 0.16002)
		(layer "In2.Cu")
		(net "M_I_CPU1_SA_DQS_DP<7>")
	)
	(segment
		(start 151.642572 -232.219246)
		(end 151.914606 -232.49128)
		(width 0.16002)
		(layer "In2.Cu")
		(net "M_I_CPU1_SA_DQS_DP<7>")
	)
	(segment
		(start 145.791174 -236.776514)
		(end 147.253452 -235.314236)
		(width 0.09525)
		(layer "In2.Cu")
		(net "M_I_CPU1_SA_DQS_DP<7>")
	)
	(segment
		(start 153.016204 -230.845614)
		(end 153.288238 -231.117648)
		(width 0.16002)
		(layer "In2.Cu")
		(net "M_I_CPU1_SA_DQS_DP<7>")
	)
	(segment
		(start 175.177196 -221.01048)
		(end 177.250852 -221.01048)
		(width 0.16002)
		(layer "In2.Cu")
		(net "M_I_CPU1_SA_DQS_DP<7>")
	)
	(segment
		(start 166.912798 -220.70314)
		(end 167.325802 -220.70314)
		(width 0.16002)
		(layer "In2.Cu")
		(net "M_I_CPU1_SA_DQS_DP<7>")
	)
	(segment
		(start 179.242974 -220.862144)
		(end 179.516024 -221.135194)
		(width 0.16002)
		(layer "In2.Cu")
		(net "M_I_CPU1_SA_DQS_DP<7>")
	)
	(segment
		(start 161.724594 -221.860364)
		(end 165.318694 -221.860364)
		(width 0.16002)
		(layer "In2.Cu")
		(net "M_I_CPU1_SA_DQS_DP<7>")
	)
	(segment
		(start 151.44115 -232.964736)
		(end 151.169116 -232.692702)
		(width 0.16002)
		(layer "In2.Cu")
		(net "M_I_CPU1_SA_DQS_DP<7>")
	)
	(segment
		(start 141.094968 -237.674404)
		(end 141.10335 -237.67923)
		(width 0.09525)
		(layer "In2.Cu")
		(net "M_I_CPU1_SA_DQS_DP<7>")
	)
	(segment
		(start 152.44191 -232.49128)
		(end 152.814782 -232.118408)
		(width 0.16002)
		(layer "In2.Cu")
		(net "M_I_CPU1_SA_DQS_DP<7>")
	)
	(segment
		(start 147.634706 -235.314236)
		(end 147.693634 -235.373164)
		(width 0.09525)
		(layer "In2.Cu")
		(net "M_I_CPU1_SA_DQS_DP<7>")
	)
	(segment
		(start 152.739344 -230.845614)
		(end 153.016204 -230.845614)
		(width 0.16002)
		(layer "In2.Cu")
		(net "M_I_CPU1_SA_DQS_DP<7>")
	)
	(segment
		(start 147.253452 -235.314236)
		(end 147.634706 -235.314236)
		(width 0.09525)
		(layer "In2.Cu")
		(net "M_I_CPU1_SA_DQS_DP<7>")
	)
	(segment
		(start 165.683438 -221.49562)
		(end 166.120318 -221.49562)
		(width 0.16002)
		(layer "In2.Cu")
		(net "M_I_CPU1_SA_DQS_DP<7>")
	)
	(segment
		(start 173.227492 -221.49562)
		(end 173.664372 -221.49562)
		(width 0.16002)
		(layer "In2.Cu")
		(net "M_I_CPU1_SA_DQS_DP<7>")
	)
	(segment
		(start 137.906252 -237.67923)
		(end 137.914634 -237.674404)
		(width 0.09525)
		(layer "In2.Cu")
		(net "M_I_CPU1_SA_DQS_DP<7>")
	)
	(segment
		(start 127.908558 -237.73892)
		(end 128.009396 -237.71225)
		(width 0.09525)
		(layer "In2.Cu")
		(net "M_I_CPU1_SA_DQS_DP<7>")
	)
	(segment
		(start 174.456852 -220.70314)
		(end 174.869856 -220.70314)
		(width 0.16002)
		(layer "In2.Cu")
		(net "M_I_CPU1_SA_DQS_DP<7>")
	)
	(segment
		(start 151.44115 -233.49204)
		(end 151.44115 -232.964736)
		(width 0.16002)
		(layer "In2.Cu")
		(net "M_I_CPU1_SA_DQS_DP<7>")
	)
	(segment
		(start 154.188414 -230.217472)
		(end 153.91638 -229.945438)
		(width 0.16002)
		(layer "In2.Cu")
		(net "M_I_CPU1_SA_DQS_DP<7>")
	)
	(segment
		(start 147.717256 -235.373164)
		(end 149.560026 -235.373164)
		(width 0.16002)
		(layer "In2.Cu")
		(net "M_I_CPU1_SA_DQS_DP<7>")
	)
	(segment
		(start 128.50622 -237.67923)
		(end 128.514602 -237.674404)
		(width 0.09525)
		(layer "In2.Cu")
		(net "M_I_CPU1_SA_DQS_DP<7>")
	)
	(segment
		(start 153.815542 -231.117648)
		(end 154.188414 -230.744776)
		(width 0.16002)
		(layer "In2.Cu")
		(net "M_I_CPU1_SA_DQS_DP<7>")
	)
	(segment
		(start 142.983458 -237.67923)
		(end 142.994126 -237.685072)
		(width 0.09525)
		(layer "In2.Cu")
		(net "M_I_CPU1_SA_DQS_DP<7>")
	)
	(segment
		(start 152.814782 -231.591104)
		(end 152.542748 -231.31907)
		(width 0.16002)
		(layer "In2.Cu")
		(net "M_I_CPU1_SA_DQS_DP<7>")
	)
	(segment
		(start 130.754882 -237.674404)
		(end 130.763264 -237.67923)
		(width 0.09525)
		(layer "In2.Cu")
		(net "M_I_CPU1_SA_DQS_DP<7>")
	)
	(segment
		(start 154.188414 -230.744776)
		(end 154.188414 -230.217472)
		(width 0.16002)
		(layer "In2.Cu")
		(net "M_I_CPU1_SA_DQS_DP<7>")
	)
	(segment
		(start 149.99208 -233.592878)
		(end 150.26894 -233.592878)
		(width 0.16002)
		(layer "In2.Cu")
		(net "M_I_CPU1_SA_DQS_DP<7>")
	)
	(segment
		(start 132.266182 -237.67923)
		(end 132.274564 -237.674404)
		(width 0.09525)
		(layer "In2.Cu")
		(net "M_I_CPU1_SA_DQS_DP<7>")
	)
	(segment
		(start 150.540974 -233.864912)
		(end 151.068278 -233.864912)
		(width 0.16002)
		(layer "In2.Cu")
		(net "M_I_CPU1_SA_DQS_DP<7>")
	)
	(segment
		(start 149.560026 -235.373164)
		(end 150.067518 -234.865672)
		(width 0.16002)
		(layer "In2.Cu")
		(net "M_I_CPU1_SA_DQS_DP<7>")
	)
	(segment
		(start 153.91638 -229.945438)
		(end 153.91638 -229.668578)
		(width 0.16002)
		(layer "In2.Cu")
		(net "M_I_CPU1_SA_DQS_DP<7>")
	)
	(segment
		(start 151.169116 -232.415842)
		(end 151.365712 -232.219246)
		(width 0.16002)
		(layer "In2.Cu")
		(net "M_I_CPU1_SA_DQS_DP<7>")
	)
	(segment
		(start 151.169116 -232.692702)
		(end 151.169116 -232.415842)
		(width 0.16002)
		(layer "In2.Cu")
		(net "M_I_CPU1_SA_DQS_DP<7>")
	)
	(segment
		(start 152.814782 -232.118408)
		(end 152.814782 -231.591104)
		(width 0.16002)
		(layer "In2.Cu")
		(net "M_I_CPU1_SA_DQS_DP<7>")
	)
	(segment
		(start 170.946572 -221.860364)
		(end 172.862748 -221.860364)
		(width 0.16002)
		(layer "In2.Cu")
		(net "M_I_CPU1_SA_DQS_DP<7>")
	)
	(segment
		(start 177.250852 -221.01048)
		(end 177.399188 -220.862144)
		(width 0.16002)
		(layer "In2.Cu")
		(net "M_I_CPU1_SA_DQS_DP<7>")
	)
	(segment
		(start 151.365712 -232.219246)
		(end 151.642572 -232.219246)
		(width 0.16002)
		(layer "In2.Cu")
		(net "M_I_CPU1_SA_DQS_DP<7>")
	)
	(segment
		(start 144.37487 -237.413292)
		(end 144.937734 -236.850174)
		(width 0.09525)
		(layer "In2.Cu")
		(net "M_I_CPU1_SA_DQS_DP<7>")
	)
	(segment
		(start 149.795484 -234.066334)
		(end 149.795484 -233.789474)
		(width 0.16002)
		(layer "In2.Cu")
		(net "M_I_CPU1_SA_DQS_DP<7>")
	)
	(segment
		(start 167.325802 -220.70314)
		(end 167.633142 -221.01048)
		(width 0.16002)
		(layer "In2.Cu")
		(net "M_I_CPU1_SA_DQS_DP<7>")
	)
	(arc
		(start 132.643372 -237.67923)
		(mid 132.924804 -237.754985)
		(end 133.206236 -237.67923)
		(width 0.09525)
		(layer "In2.Cu")
		(net "M_I_CPU1_SA_DQS_DP<7>")
	)
	(arc
		(start 135.46328 -237.67923)
		(mid 135.744712 -237.754985)
		(end 136.026144 -237.67923)
		(width 0.09525)
		(layer "In2.Cu")
		(net "M_I_CPU1_SA_DQS_DP<7>")
	)
	(arc
		(start 130.763264 -237.67923)
		(mid 131.044696 -237.754985)
		(end 131.326128 -237.67923)
		(width 0.09525)
		(layer "In2.Cu")
		(net "M_I_CPU1_SA_DQS_DP<7>")
	)
	(arc
		(start 139.223242 -237.67923)
		(mid 139.504674 -237.754985)
		(end 139.786106 -237.67923)
		(width 0.09525)
		(layer "In2.Cu")
		(net "M_I_CPU1_SA_DQS_DP<7>")
	)
	(arc
		(start 138.846306 -237.67923)
		(mid 139.034774 -237.628553)
		(end 139.223242 -237.67923)
		(width 0.09525)
		(layer "In2.Cu")
		(net "M_I_CPU1_SA_DQS_DP<7>")
	)
	(arc
		(start 131.326128 -237.67923)
		(mid 131.509903 -237.628458)
		(end 131.694936 -237.674404)
		(width 0.09525)
		(layer "In2.Cu")
		(net "M_I_CPU1_SA_DQS_DP<7>")
	)
	(arc
		(start 141.10335 -237.67923)
		(mid 141.384782 -237.754985)
		(end 141.666214 -237.67923)
		(width 0.09525)
		(layer "In2.Cu")
		(net "M_I_CPU1_SA_DQS_DP<7>")
	)
	(arc
		(start 137.343388 -237.67923)
		(mid 137.62482 -237.754985)
		(end 137.906252 -237.67923)
		(width 0.09525)
		(layer "In2.Cu")
		(net "M_I_CPU1_SA_DQS_DP<7>")
	)
	(arc
		(start 143.914114 -237.627922)
		(mid 144.074388 -237.602414)
		(end 144.21866 -237.5281)
		(width 0.09525)
		(layer "In2.Cu")
		(net "M_I_CPU1_SA_DQS_DP<7>")
	)
	(arc
		(start 139.786106 -237.67923)
		(mid 139.969881 -237.628458)
		(end 140.154914 -237.674404)
		(width 0.09525)
		(layer "In2.Cu")
		(net "M_I_CPU1_SA_DQS_DP<7>")
	)
	(arc
		(start 136.026144 -237.67923)
		(mid 136.209919 -237.628458)
		(end 136.394952 -237.674404)
		(width 0.09525)
		(layer "In2.Cu")
		(net "M_I_CPU1_SA_DQS_DP<7>")
	)
	(arc
		(start 136.403334 -237.67923)
		(mid 136.684766 -237.754985)
		(end 136.966198 -237.67923)
		(width 0.09525)
		(layer "In2.Cu")
		(net "M_I_CPU1_SA_DQS_DP<7>")
	)
	(arc
		(start 138.283442 -237.67923)
		(mid 138.564874 -237.754985)
		(end 138.846306 -237.67923)
		(width 0.09525)
		(layer "In2.Cu")
		(net "M_I_CPU1_SA_DQS_DP<7>")
	)
	(arc
		(start 142.043404 -237.67923)
		(mid 142.324836 -237.754985)
		(end 142.606268 -237.67923)
		(width 0.09525)
		(layer "In2.Cu")
		(net "M_I_CPU1_SA_DQS_DP<7>")
	)
	(arc
		(start 141.674596 -237.674404)
		(mid 141.859628 -237.62849)
		(end 142.043404 -237.67923)
		(width 0.09525)
		(layer "In2.Cu")
		(net "M_I_CPU1_SA_DQS_DP<7>")
	)
	(arc
		(start 133.583426 -237.67923)
		(mid 133.864858 -237.754985)
		(end 134.14629 -237.67923)
		(width 0.09525)
		(layer "In2.Cu")
		(net "M_I_CPU1_SA_DQS_DP<7>")
	)
	(arc
		(start 132.274564 -237.674404)
		(mid 132.459596 -237.62849)
		(end 132.643372 -237.67923)
		(width 0.09525)
		(layer "In2.Cu")
		(net "M_I_CPU1_SA_DQS_DP<7>")
	)
	(arc
		(start 133.214618 -237.674404)
		(mid 133.39965 -237.62849)
		(end 133.583426 -237.67923)
		(width 0.09525)
		(layer "In2.Cu")
		(net "M_I_CPU1_SA_DQS_DP<7>")
	)
	(arc
		(start 134.14629 -237.67923)
		(mid 134.334758 -237.628553)
		(end 134.523226 -237.67923)
		(width 0.09525)
		(layer "In2.Cu")
		(net "M_I_CPU1_SA_DQS_DP<7>")
	)
	(arc
		(start 128.02997 -237.720378)
		(mid 128.272712 -237.753148)
		(end 128.50622 -237.67923)
		(width 0.09525)
		(layer "In2.Cu")
		(net "M_I_CPU1_SA_DQS_DP<7>")
	)
	(arc
		(start 142.606268 -237.67923)
		(mid 142.794736 -237.628553)
		(end 142.983204 -237.67923)
		(width 0.09525)
		(layer "In2.Cu")
		(net "M_I_CPU1_SA_DQS_DP<7>")
	)
	(arc
		(start 130.386074 -237.67923)
		(mid 130.569849 -237.628458)
		(end 130.754882 -237.674404)
		(width 0.09525)
		(layer "In2.Cu")
		(net "M_I_CPU1_SA_DQS_DP<7>")
	)
	(arc
		(start 136.97458 -237.674404)
		(mid 137.159612 -237.62849)
		(end 137.343388 -237.67923)
		(width 0.09525)
		(layer "In2.Cu")
		(net "M_I_CPU1_SA_DQS_DP<7>")
	)
	(arc
		(start 134.523226 -237.67923)
		(mid 134.804658 -237.754985)
		(end 135.08609 -237.67923)
		(width 0.09525)
		(layer "In2.Cu")
		(net "M_I_CPU1_SA_DQS_DP<7>")
	)
	(arc
		(start 135.08609 -237.67923)
		(mid 135.269865 -237.628458)
		(end 135.454898 -237.674404)
		(width 0.09525)
		(layer "In2.Cu")
		(net "M_I_CPU1_SA_DQS_DP<7>")
	)
	(arc
		(start 140.72616 -237.67923)
		(mid 140.909935 -237.628458)
		(end 141.094968 -237.674404)
		(width 0.09525)
		(layer "In2.Cu")
		(net "M_I_CPU1_SA_DQS_DP<7>")
	)
	(arc
		(start 137.914634 -237.674404)
		(mid 138.099666 -237.62849)
		(end 138.283442 -237.67923)
		(width 0.09525)
		(layer "In2.Cu")
		(net "M_I_CPU1_SA_DQS_DP<7>")
	)
	(arc
		(start 128.88341 -237.67923)
		(mid 129.164842 -237.754985)
		(end 129.446274 -237.67923)
		(width 0.09525)
		(layer "In2.Cu")
		(net "M_I_CPU1_SA_DQS_DP<7>")
	)
	(arc
		(start 140.163296 -237.67923)
		(mid 140.444728 -237.754985)
		(end 140.72616 -237.67923)
		(width 0.09525)
		(layer "In2.Cu")
		(net "M_I_CPU1_SA_DQS_DP<7>")
	)
	(arc
		(start 129.446274 -237.67923)
		(mid 129.634742 -237.628553)
		(end 129.82321 -237.67923)
		(width 0.09525)
		(layer "In2.Cu")
		(net "M_I_CPU1_SA_DQS_DP<7>")
	)
	(arc
		(start 131.703318 -237.67923)
		(mid 131.98475 -237.754985)
		(end 132.266182 -237.67923)
		(width 0.09525)
		(layer "In2.Cu")
		(net "M_I_CPU1_SA_DQS_DP<7>")
	)
	(arc
		(start 128.009396 -237.71225)
		(mid 128.019644 -237.716413)
		(end 128.02997 -237.720378)
		(width 0.09525)
		(layer "In2.Cu")
		(net "M_I_CPU1_SA_DQS_DP<7>")
	)
	(arc
		(start 129.82321 -237.67923)
		(mid 130.104642 -237.754985)
		(end 130.386074 -237.67923)
		(width 0.09525)
		(layer "In2.Cu")
		(net "M_I_CPU1_SA_DQS_DP<7>")
	)
	(arc
		(start 128.514602 -237.674404)
		(mid 128.699634 -237.62849)
		(end 128.88341 -237.67923)
		(width 0.09525)
		(layer "In2.Cu")
		(net "M_I_CPU1_SA_DQS_DP<7>")
	)
	(arc
		(start 142.994126 -237.685072)
		(mid 143.27078 -237.754658)
		(end 143.545814 -237.678976)
		(width 0.09525)
		(layer "In2.Cu")
		(net "M_I_CPU1_SA_DQS_DP<7>")
	)
	(arc
		(start 143.545814 -237.678976)
		(mid 143.636927 -237.640964)
		(end 143.73479 -237.627922)
		(width 0.09525)
		(layer "In2.Cu")
		(net "M_I_CPU1_SA_DQS_DP<7>")
	)
	(segment
		(start 127.287782 -233.410252)
		(end 127.754634 -233.144314)
		(width 0.12954)
		(layer "F.Cu")
		(net "M_I_CPU1_SA_DQS_DP<6>")
	)
	(segment
		(start 127.908558 -232.878884)
		(end 128.009396 -232.852214)
		(width 0.09525)
		(layer "In2.Cu")
		(net "M_I_CPU1_SA_DQS_DP<6>")
	)
	(segment
		(start 146.643598 -227.80752)
		(end 148.46681 -225.984308)
		(width 0.16002)
		(layer "In2.Cu")
		(net "M_I_CPU1_SA_DQS_DP<6>")
	)
	(segment
		(start 127.754634 -233.144314)
		(end 127.908558 -232.878884)
		(width 0.09525)
		(layer "In2.Cu")
		(net "M_I_CPU1_SA_DQS_DP<6>")
	)
	(segment
		(start 140.154914 -232.814368)
		(end 140.163296 -232.819194)
		(width 0.09525)
		(layer "In2.Cu")
		(net "M_I_CPU1_SA_DQS_DP<6>")
	)
	(segment
		(start 157.209744 -216.576402)
		(end 157.209744 -216.049098)
		(width 0.16002)
		(layer "In2.Cu")
		(net "M_I_CPU1_SA_DQS_DP<6>")
	)
	(segment
		(start 156.866082 -215.428576)
		(end 157.062678 -215.23198)
		(width 0.16002)
		(layer "In2.Cu")
		(net "M_I_CPU1_SA_DQS_DP<6>")
	)
	(segment
		(start 158.583376 -214.675466)
		(end 158.239714 -214.331804)
		(width 0.16002)
		(layer "In2.Cu")
		(net "M_I_CPU1_SA_DQS_DP<6>")
	)
	(segment
		(start 136.394952 -232.814368)
		(end 136.403334 -232.819194)
		(width 0.09525)
		(layer "In2.Cu")
		(net "M_I_CPU1_SA_DQS_DP<6>")
	)
	(segment
		(start 146.048476 -228.617018)
		(end 146.17192 -228.493574)
		(width 0.09525)
		(layer "In2.Cu")
		(net "M_I_CPU1_SA_DQS_DP<6>")
	)
	(segment
		(start 148.46681 -225.984308)
		(end 148.46681 -225.319336)
		(width 0.16002)
		(layer "In2.Cu")
		(net "M_I_CPU1_SA_DQS_DP<6>")
	)
	(segment
		(start 156.866082 -215.705436)
		(end 156.866082 -215.428576)
		(width 0.16002)
		(layer "In2.Cu")
		(net "M_I_CPU1_SA_DQS_DP<6>")
	)
	(segment
		(start 145.863818 -228.788214)
		(end 145.884138 -228.776022)
		(width 0.09525)
		(layer "In2.Cu")
		(net "M_I_CPU1_SA_DQS_DP<6>")
	)
	(segment
		(start 143.546068 -232.819194)
		(end 143.584168 -232.797096)
		(width 0.09525)
		(layer "In2.Cu")
		(net "M_I_CPU1_SA_DQS_DP<6>")
	)
	(segment
		(start 174.869856 -211.353146)
		(end 175.177196 -211.660486)
		(width 0.16002)
		(layer "In2.Cu")
		(net "M_I_CPU1_SA_DQS_DP<6>")
	)
	(segment
		(start 145.39468 -229.597458)
		(end 145.426176 -229.57917)
		(width 0.09525)
		(layer "In2.Cu")
		(net "M_I_CPU1_SA_DQS_DP<6>")
	)
	(segment
		(start 141.094968 -232.814368)
		(end 141.10335 -232.819194)
		(width 0.09525)
		(layer "In2.Cu")
		(net "M_I_CPU1_SA_DQS_DP<6>")
	)
	(segment
		(start 159.957008 -213.301834)
		(end 159.613346 -212.958172)
		(width 0.16002)
		(layer "In2.Cu")
		(net "M_I_CPU1_SA_DQS_DP<6>")
	)
	(segment
		(start 173.227492 -212.145626)
		(end 173.664372 -212.145626)
		(width 0.16002)
		(layer "In2.Cu")
		(net "M_I_CPU1_SA_DQS_DP<6>")
	)
	(segment
		(start 137.906252 -232.819194)
		(end 137.914634 -232.814368)
		(width 0.09525)
		(layer "In2.Cu")
		(net "M_I_CPU1_SA_DQS_DP<6>")
	)
	(segment
		(start 165.683438 -212.145626)
		(end 166.120318 -212.145626)
		(width 0.16002)
		(layer "In2.Cu")
		(net "M_I_CPU1_SA_DQS_DP<6>")
	)
	(segment
		(start 157.339538 -215.23198)
		(end 157.6832 -215.575642)
		(width 0.16002)
		(layer "In2.Cu")
		(net "M_I_CPU1_SA_DQS_DP<6>")
	)
	(segment
		(start 158.239714 -214.054944)
		(end 158.43631 -213.858348)
		(width 0.16002)
		(layer "In2.Cu")
		(net "M_I_CPU1_SA_DQS_DP<6>")
	)
	(segment
		(start 159.613346 -212.958172)
		(end 159.613346 -212.681312)
		(width 0.16002)
		(layer "In2.Cu")
		(net "M_I_CPU1_SA_DQS_DP<6>")
	)
	(segment
		(start 172.862748 -212.51037)
		(end 173.227492 -212.145626)
		(width 0.16002)
		(layer "In2.Cu")
		(net "M_I_CPU1_SA_DQS_DP<6>")
	)
	(segment
		(start 146.543776 -227.824284)
		(end 146.626834 -227.824284)
		(width 0.09525)
		(layer "In2.Cu")
		(net "M_I_CPU1_SA_DQS_DP<6>")
	)
	(segment
		(start 146.17192 -228.493574)
		(end 146.17192 -228.09708)
		(width 0.09525)
		(layer "In2.Cu")
		(net "M_I_CPU1_SA_DQS_DP<6>")
	)
	(segment
		(start 144.016222 -232.009188)
		(end 144.054322 -231.98709)
		(width 0.09525)
		(layer "In2.Cu")
		(net "M_I_CPU1_SA_DQS_DP<6>")
	)
	(segment
		(start 145.897092 -228.768656)
		(end 146.04873 -228.617018)
		(width 0.09525)
		(layer "In2.Cu")
		(net "M_I_CPU1_SA_DQS_DP<6>")
	)
	(segment
		(start 165.318694 -212.51037)
		(end 165.683438 -212.145626)
		(width 0.16002)
		(layer "In2.Cu")
		(net "M_I_CPU1_SA_DQS_DP<6>")
	)
	(segment
		(start 174.456852 -211.353146)
		(end 174.869856 -211.353146)
		(width 0.16002)
		(layer "In2.Cu")
		(net "M_I_CPU1_SA_DQS_DP<6>")
	)
	(segment
		(start 159.957008 -213.829138)
		(end 159.957008 -213.301834)
		(width 0.16002)
		(layer "In2.Cu")
		(net "M_I_CPU1_SA_DQS_DP<6>")
	)
	(segment
		(start 170.096688 -211.660486)
		(end 170.946572 -212.51037)
		(width 0.16002)
		(layer "In2.Cu")
		(net "M_I_CPU1_SA_DQS_DP<6>")
	)
	(segment
		(start 146.342354 -227.926646)
		(end 146.441414 -227.926646)
		(width 0.09525)
		(layer "In2.Cu")
		(net "M_I_CPU1_SA_DQS_DP<6>")
	)
	(segment
		(start 157.209744 -216.049098)
		(end 156.866082 -215.705436)
		(width 0.16002)
		(layer "In2.Cu")
		(net "M_I_CPU1_SA_DQS_DP<6>")
	)
	(segment
		(start 158.43631 -213.858348)
		(end 158.71317 -213.858348)
		(width 0.16002)
		(layer "In2.Cu")
		(net "M_I_CPU1_SA_DQS_DP<6>")
	)
	(segment
		(start 146.17192 -228.09708)
		(end 146.342354 -227.926646)
		(width 0.09525)
		(layer "In2.Cu")
		(net "M_I_CPU1_SA_DQS_DP<6>")
	)
	(segment
		(start 161.275776 -212.51037)
		(end 165.318694 -212.51037)
		(width 0.16002)
		(layer "In2.Cu")
		(net "M_I_CPU1_SA_DQS_DP<6>")
	)
	(segment
		(start 130.754882 -232.814368)
		(end 130.763264 -232.819194)
		(width 0.09525)
		(layer "In2.Cu")
		(net "M_I_CPU1_SA_DQS_DP<6>")
	)
	(segment
		(start 132.266182 -232.819194)
		(end 132.274564 -232.814368)
		(width 0.09525)
		(layer "In2.Cu")
		(net "M_I_CPU1_SA_DQS_DP<6>")
	)
	(segment
		(start 143.98371 -232.027984)
		(end 144.016222 -232.009188)
		(width 0.09525)
		(layer "In2.Cu")
		(net "M_I_CPU1_SA_DQS_DP<6>")
	)
	(segment
		(start 144.956276 -230.38943)
		(end 144.991836 -230.368856)
		(width 0.09525)
		(layer "In2.Cu")
		(net "M_I_CPU1_SA_DQS_DP<6>")
	)
	(segment
		(start 144.486122 -231.199182)
		(end 144.526508 -231.17556)
		(width 0.09525)
		(layer "In2.Cu")
		(net "M_I_CPU1_SA_DQS_DP<6>")
	)
	(segment
		(start 166.912798 -211.353146)
		(end 167.325802 -211.353146)
		(width 0.16002)
		(layer "In2.Cu")
		(net "M_I_CPU1_SA_DQS_DP<6>")
	)
	(segment
		(start 128.50622 -232.819194)
		(end 128.514602 -232.814368)
		(width 0.09525)
		(layer "In2.Cu")
		(net "M_I_CPU1_SA_DQS_DP<6>")
	)
	(segment
		(start 175.177196 -211.660486)
		(end 177.250852 -211.660486)
		(width 0.16002)
		(layer "In2.Cu")
		(net "M_I_CPU1_SA_DQS_DP<6>")
	)
	(segment
		(start 159.584136 -214.20201)
		(end 159.957008 -213.829138)
		(width 0.16002)
		(layer "In2.Cu")
		(net "M_I_CPU1_SA_DQS_DP<6>")
	)
	(segment
		(start 160.957768 -212.828378)
		(end 161.275776 -212.51037)
		(width 0.16002)
		(layer "In2.Cu")
		(net "M_I_CPU1_SA_DQS_DP<6>")
	)
	(segment
		(start 173.664372 -212.145626)
		(end 174.456852 -211.353146)
		(width 0.16002)
		(layer "In2.Cu")
		(net "M_I_CPU1_SA_DQS_DP<6>")
	)
	(segment
		(start 177.250852 -211.660486)
		(end 177.399188 -211.51215)
		(width 0.16002)
		(layer "In2.Cu")
		(net "M_I_CPU1_SA_DQS_DP<6>")
	)
	(segment
		(start 148.46681 -225.319336)
		(end 157.209744 -216.576402)
		(width 0.16002)
		(layer "In2.Cu")
		(net "M_I_CPU1_SA_DQS_DP<6>")
	)
	(segment
		(start 136.966198 -232.819194)
		(end 136.97458 -232.814368)
		(width 0.09525)
		(layer "In2.Cu")
		(net "M_I_CPU1_SA_DQS_DP<6>")
	)
	(segment
		(start 158.210504 -215.575642)
		(end 158.583376 -215.20277)
		(width 0.16002)
		(layer "In2.Cu")
		(net "M_I_CPU1_SA_DQS_DP<6>")
	)
	(segment
		(start 157.6832 -215.575642)
		(end 158.210504 -215.575642)
		(width 0.16002)
		(layer "In2.Cu")
		(net "M_I_CPU1_SA_DQS_DP<6>")
	)
	(segment
		(start 159.613346 -212.681312)
		(end 159.809942 -212.484716)
		(width 0.16002)
		(layer "In2.Cu")
		(net "M_I_CPU1_SA_DQS_DP<6>")
	)
	(segment
		(start 167.325802 -211.353146)
		(end 167.633142 -211.660486)
		(width 0.16002)
		(layer "In2.Cu")
		(net "M_I_CPU1_SA_DQS_DP<6>")
	)
	(segment
		(start 144.454626 -231.21747)
		(end 144.486122 -231.199182)
		(width 0.09525)
		(layer "In2.Cu")
		(net "M_I_CPU1_SA_DQS_DP<6>")
	)
	(segment
		(start 146.626834 -227.824284)
		(end 146.643598 -227.80752)
		(width 0.09525)
		(layer "In2.Cu")
		(net "M_I_CPU1_SA_DQS_DP<6>")
	)
	(segment
		(start 141.666214 -232.819194)
		(end 141.674596 -232.814368)
		(width 0.09525)
		(layer "In2.Cu")
		(net "M_I_CPU1_SA_DQS_DP<6>")
	)
	(segment
		(start 158.71317 -213.858348)
		(end 159.056832 -214.20201)
		(width 0.16002)
		(layer "In2.Cu")
		(net "M_I_CPU1_SA_DQS_DP<6>")
	)
	(segment
		(start 177.399188 -211.51215)
		(end 179.242974 -211.51215)
		(width 0.16002)
		(layer "In2.Cu")
		(net "M_I_CPU1_SA_DQS_DP<6>")
	)
	(segment
		(start 159.809942 -212.484716)
		(end 160.086802 -212.484716)
		(width 0.16002)
		(layer "In2.Cu")
		(net "M_I_CPU1_SA_DQS_DP<6>")
	)
	(segment
		(start 167.633142 -211.660486)
		(end 170.096688 -211.660486)
		(width 0.16002)
		(layer "In2.Cu")
		(net "M_I_CPU1_SA_DQS_DP<6>")
	)
	(segment
		(start 160.430464 -212.828378)
		(end 160.957768 -212.828378)
		(width 0.16002)
		(layer "In2.Cu")
		(net "M_I_CPU1_SA_DQS_DP<6>")
	)
	(segment
		(start 158.583376 -215.20277)
		(end 158.583376 -214.675466)
		(width 0.16002)
		(layer "In2.Cu")
		(net "M_I_CPU1_SA_DQS_DP<6>")
	)
	(segment
		(start 157.062678 -215.23198)
		(end 157.339538 -215.23198)
		(width 0.16002)
		(layer "In2.Cu")
		(net "M_I_CPU1_SA_DQS_DP<6>")
	)
	(segment
		(start 158.239714 -214.331804)
		(end 158.239714 -214.054944)
		(width 0.16002)
		(layer "In2.Cu")
		(net "M_I_CPU1_SA_DQS_DP<6>")
	)
	(segment
		(start 170.946572 -212.51037)
		(end 172.862748 -212.51037)
		(width 0.16002)
		(layer "In2.Cu")
		(net "M_I_CPU1_SA_DQS_DP<6>")
	)
	(segment
		(start 131.694936 -232.814368)
		(end 131.703318 -232.819194)
		(width 0.09525)
		(layer "In2.Cu")
		(net "M_I_CPU1_SA_DQS_DP<6>")
	)
	(segment
		(start 144.923764 -230.408226)
		(end 144.956276 -230.38943)
		(width 0.09525)
		(layer "In2.Cu")
		(net "M_I_CPU1_SA_DQS_DP<6>")
	)
	(segment
		(start 133.206236 -232.819194)
		(end 133.214618 -232.814368)
		(width 0.09525)
		(layer "In2.Cu")
		(net "M_I_CPU1_SA_DQS_DP<6>")
	)
	(segment
		(start 160.086802 -212.484716)
		(end 160.430464 -212.828378)
		(width 0.16002)
		(layer "In2.Cu")
		(net "M_I_CPU1_SA_DQS_DP<6>")
	)
	(segment
		(start 146.441414 -227.926646)
		(end 146.543776 -227.824284)
		(width 0.09525)
		(layer "In2.Cu")
		(net "M_I_CPU1_SA_DQS_DP<6>")
	)
	(segment
		(start 159.056832 -214.20201)
		(end 159.584136 -214.20201)
		(width 0.16002)
		(layer "In2.Cu")
		(net "M_I_CPU1_SA_DQS_DP<6>")
	)
	(segment
		(start 146.04873 -228.617018)
		(end 146.048476 -228.617018)
		(width 0.09525)
		(layer "In2.Cu")
		(net "M_I_CPU1_SA_DQS_DP<6>")
	)
	(segment
		(start 135.454898 -232.814368)
		(end 135.46328 -232.819194)
		(width 0.09525)
		(layer "In2.Cu")
		(net "M_I_CPU1_SA_DQS_DP<6>")
	)
	(segment
		(start 145.884138 -228.776022)
		(end 145.897092 -228.768656)
		(width 0.09525)
		(layer "In2.Cu")
		(net "M_I_CPU1_SA_DQS_DP<6>")
	)
	(segment
		(start 145.426176 -229.57917)
		(end 145.466562 -229.555548)
		(width 0.09525)
		(layer "In2.Cu")
		(net "M_I_CPU1_SA_DQS_DP<6>")
	)
	(segment
		(start 166.120318 -212.145626)
		(end 166.912798 -211.353146)
		(width 0.16002)
		(layer "In2.Cu")
		(net "M_I_CPU1_SA_DQS_DP<6>")
	)
	(segment
		(start 179.242974 -211.51215)
		(end 179.516024 -211.7852)
		(width 0.16002)
		(layer "In2.Cu")
		(net "M_I_CPU1_SA_DQS_DP<6>")
	)
	(arc
		(start 128.009396 -232.852214)
		(mid 128.019644 -232.856377)
		(end 128.02997 -232.860342)
		(width 0.09525)
		(layer "In2.Cu")
		(net "M_I_CPU1_SA_DQS_DP<6>")
	)
	(arc
		(start 137.343388 -232.819194)
		(mid 137.62482 -232.894949)
		(end 137.906252 -232.819194)
		(width 0.09525)
		(layer "In2.Cu")
		(net "M_I_CPU1_SA_DQS_DP<6>")
	)
	(arc
		(start 131.703318 -232.819194)
		(mid 131.98475 -232.894949)
		(end 132.266182 -232.819194)
		(width 0.09525)
		(layer "In2.Cu")
		(net "M_I_CPU1_SA_DQS_DP<6>")
	)
	(arc
		(start 143.584168 -232.797096)
		(mid 143.762618 -232.595626)
		(end 143.826992 -232.334308)
		(width 0.09525)
		(layer "In2.Cu")
		(net "M_I_CPU1_SA_DQS_DP<6>")
	)
	(arc
		(start 140.72616 -232.819194)
		(mid 140.909935 -232.768422)
		(end 141.094968 -232.814368)
		(width 0.09525)
		(layer "In2.Cu")
		(net "M_I_CPU1_SA_DQS_DP<6>")
	)
	(arc
		(start 142.043404 -232.819194)
		(mid 142.324836 -232.894949)
		(end 142.606268 -232.819194)
		(width 0.09525)
		(layer "In2.Cu")
		(net "M_I_CPU1_SA_DQS_DP<6>")
	)
	(arc
		(start 130.386074 -232.819194)
		(mid 130.569849 -232.768422)
		(end 130.754882 -232.814368)
		(width 0.09525)
		(layer "In2.Cu")
		(net "M_I_CPU1_SA_DQS_DP<6>")
	)
	(arc
		(start 144.297146 -231.524302)
		(mid 144.338811 -231.351855)
		(end 144.454626 -231.21747)
		(width 0.09525)
		(layer "In2.Cu")
		(net "M_I_CPU1_SA_DQS_DP<6>")
	)
	(arc
		(start 130.763264 -232.819194)
		(mid 131.044696 -232.894949)
		(end 131.326128 -232.819194)
		(width 0.09525)
		(layer "In2.Cu")
		(net "M_I_CPU1_SA_DQS_DP<6>")
	)
	(arc
		(start 129.82321 -232.819194)
		(mid 130.104642 -232.894949)
		(end 130.386074 -232.819194)
		(width 0.09525)
		(layer "In2.Cu")
		(net "M_I_CPU1_SA_DQS_DP<6>")
	)
	(arc
		(start 138.846306 -232.819194)
		(mid 139.034774 -232.768517)
		(end 139.223242 -232.819194)
		(width 0.09525)
		(layer "In2.Cu")
		(net "M_I_CPU1_SA_DQS_DP<6>")
	)
	(arc
		(start 129.446274 -232.819194)
		(mid 129.634742 -232.768517)
		(end 129.82321 -232.819194)
		(width 0.09525)
		(layer "In2.Cu")
		(net "M_I_CPU1_SA_DQS_DP<6>")
	)
	(arc
		(start 137.914634 -232.814368)
		(mid 138.099666 -232.768454)
		(end 138.283442 -232.819194)
		(width 0.09525)
		(layer "In2.Cu")
		(net "M_I_CPU1_SA_DQS_DP<6>")
	)
	(arc
		(start 133.583426 -232.819194)
		(mid 133.864858 -232.894949)
		(end 134.14629 -232.819194)
		(width 0.09525)
		(layer "In2.Cu")
		(net "M_I_CPU1_SA_DQS_DP<6>")
	)
	(arc
		(start 135.46328 -232.819194)
		(mid 135.744712 -232.894949)
		(end 136.026144 -232.819194)
		(width 0.09525)
		(layer "In2.Cu")
		(net "M_I_CPU1_SA_DQS_DP<6>")
	)
	(arc
		(start 135.08609 -232.819194)
		(mid 135.269865 -232.768422)
		(end 135.454898 -232.814368)
		(width 0.09525)
		(layer "In2.Cu")
		(net "M_I_CPU1_SA_DQS_DP<6>")
	)
	(arc
		(start 142.606268 -232.819194)
		(mid 142.794736 -232.768517)
		(end 142.983204 -232.819194)
		(width 0.09525)
		(layer "In2.Cu")
		(net "M_I_CPU1_SA_DQS_DP<6>")
	)
	(arc
		(start 128.02997 -232.860342)
		(mid 128.272712 -232.893112)
		(end 128.50622 -232.819194)
		(width 0.09525)
		(layer "In2.Cu")
		(net "M_I_CPU1_SA_DQS_DP<6>")
	)
	(arc
		(start 145.2372 -229.90429)
		(mid 145.278865 -229.731843)
		(end 145.39468 -229.597458)
		(width 0.09525)
		(layer "In2.Cu")
		(net "M_I_CPU1_SA_DQS_DP<6>")
	)
	(arc
		(start 138.283442 -232.819194)
		(mid 138.564874 -232.894949)
		(end 138.846306 -232.819194)
		(width 0.09525)
		(layer "In2.Cu")
		(net "M_I_CPU1_SA_DQS_DP<6>")
	)
	(arc
		(start 136.026144 -232.819194)
		(mid 136.209919 -232.768422)
		(end 136.394952 -232.814368)
		(width 0.09525)
		(layer "In2.Cu")
		(net "M_I_CPU1_SA_DQS_DP<6>")
	)
	(arc
		(start 140.163296 -232.819194)
		(mid 140.444728 -232.894949)
		(end 140.72616 -232.819194)
		(width 0.09525)
		(layer "In2.Cu")
		(net "M_I_CPU1_SA_DQS_DP<6>")
	)
	(arc
		(start 144.054322 -231.98709)
		(mid 144.232772 -231.78562)
		(end 144.297146 -231.524302)
		(width 0.09525)
		(layer "In2.Cu")
		(net "M_I_CPU1_SA_DQS_DP<6>")
	)
	(arc
		(start 142.983204 -232.819194)
		(mid 143.264636 -232.894949)
		(end 143.546068 -232.819194)
		(width 0.09525)
		(layer "In2.Cu")
		(net "M_I_CPU1_SA_DQS_DP<6>")
	)
	(arc
		(start 136.97458 -232.814368)
		(mid 137.159612 -232.768454)
		(end 137.343388 -232.819194)
		(width 0.09525)
		(layer "In2.Cu")
		(net "M_I_CPU1_SA_DQS_DP<6>")
	)
	(arc
		(start 141.10335 -232.819194)
		(mid 141.384782 -232.894949)
		(end 141.666214 -232.819194)
		(width 0.09525)
		(layer "In2.Cu")
		(net "M_I_CPU1_SA_DQS_DP<6>")
	)
	(arc
		(start 139.786106 -232.819194)
		(mid 139.969881 -232.768422)
		(end 140.154914 -232.814368)
		(width 0.09525)
		(layer "In2.Cu")
		(net "M_I_CPU1_SA_DQS_DP<6>")
	)
	(arc
		(start 131.326128 -232.819194)
		(mid 131.509903 -232.768422)
		(end 131.694936 -232.814368)
		(width 0.09525)
		(layer "In2.Cu")
		(net "M_I_CPU1_SA_DQS_DP<6>")
	)
	(arc
		(start 143.826992 -232.334308)
		(mid 143.868449 -232.162268)
		(end 143.98371 -232.027984)
		(width 0.09525)
		(layer "In2.Cu")
		(net "M_I_CPU1_SA_DQS_DP<6>")
	)
	(arc
		(start 144.991836 -230.368856)
		(mid 145.172129 -230.166993)
		(end 145.2372 -229.90429)
		(width 0.09525)
		(layer "In2.Cu")
		(net "M_I_CPU1_SA_DQS_DP<6>")
	)
	(arc
		(start 141.674596 -232.814368)
		(mid 141.859628 -232.768454)
		(end 142.043404 -232.819194)
		(width 0.09525)
		(layer "In2.Cu")
		(net "M_I_CPU1_SA_DQS_DP<6>")
	)
	(arc
		(start 132.274564 -232.814368)
		(mid 132.459596 -232.768454)
		(end 132.643372 -232.819194)
		(width 0.09525)
		(layer "In2.Cu")
		(net "M_I_CPU1_SA_DQS_DP<6>")
	)
	(arc
		(start 145.7071 -229.094538)
		(mid 145.748557 -228.922498)
		(end 145.863818 -228.788214)
		(width 0.09525)
		(layer "In2.Cu")
		(net "M_I_CPU1_SA_DQS_DP<6>")
	)
	(arc
		(start 136.403334 -232.819194)
		(mid 136.684766 -232.894949)
		(end 136.966198 -232.819194)
		(width 0.09525)
		(layer "In2.Cu")
		(net "M_I_CPU1_SA_DQS_DP<6>")
	)
	(arc
		(start 144.767046 -230.71455)
		(mid 144.808503 -230.54251)
		(end 144.923764 -230.408226)
		(width 0.09525)
		(layer "In2.Cu")
		(net "M_I_CPU1_SA_DQS_DP<6>")
	)
	(arc
		(start 132.643372 -232.819194)
		(mid 132.924804 -232.894949)
		(end 133.206236 -232.819194)
		(width 0.09525)
		(layer "In2.Cu")
		(net "M_I_CPU1_SA_DQS_DP<6>")
	)
	(arc
		(start 134.523226 -232.819194)
		(mid 134.804658 -232.894949)
		(end 135.08609 -232.819194)
		(width 0.09525)
		(layer "In2.Cu")
		(net "M_I_CPU1_SA_DQS_DP<6>")
	)
	(arc
		(start 128.88341 -232.819194)
		(mid 129.164842 -232.894949)
		(end 129.446274 -232.819194)
		(width 0.09525)
		(layer "In2.Cu")
		(net "M_I_CPU1_SA_DQS_DP<6>")
	)
	(arc
		(start 128.514602 -232.814368)
		(mid 128.699634 -232.768454)
		(end 128.88341 -232.819194)
		(width 0.09525)
		(layer "In2.Cu")
		(net "M_I_CPU1_SA_DQS_DP<6>")
	)
	(arc
		(start 144.526508 -231.17556)
		(mid 144.70328 -230.974539)
		(end 144.767046 -230.71455)
		(width 0.09525)
		(layer "In2.Cu")
		(net "M_I_CPU1_SA_DQS_DP<6>")
	)
	(arc
		(start 134.14629 -232.819194)
		(mid 134.334758 -232.768517)
		(end 134.523226 -232.819194)
		(width 0.09525)
		(layer "In2.Cu")
		(net "M_I_CPU1_SA_DQS_DP<6>")
	)
	(arc
		(start 139.223242 -232.819194)
		(mid 139.504674 -232.894949)
		(end 139.786106 -232.819194)
		(width 0.09525)
		(layer "In2.Cu")
		(net "M_I_CPU1_SA_DQS_DP<6>")
	)
	(arc
		(start 133.214618 -232.814368)
		(mid 133.39965 -232.768454)
		(end 133.583426 -232.819194)
		(width 0.09525)
		(layer "In2.Cu")
		(net "M_I_CPU1_SA_DQS_DP<6>")
	)
	(arc
		(start 145.466562 -229.555548)
		(mid 145.643334 -229.354527)
		(end 145.7071 -229.094538)
		(width 0.09525)
		(layer "In2.Cu")
		(net "M_I_CPU1_SA_DQS_DP<6>")
	)
	(segment
		(start 127.287782 -228.55047)
		(end 127.754634 -228.284532)
		(width 0.12954)
		(layer "F.Cu")
		(net "M_I_CPU1_SA_DQS_DP<5>")
	)
	(segment
		(start 144.356074 -221.174564)
		(end 144.356074 -220.105478)
		(width 0.16002)
		(layer "In2.Cu")
		(net "M_I_CPU1_SA_DQS_DP<5>")
	)
	(segment
		(start 143.987012 -222.30588)
		(end 144.056862 -222.26524)
		(width 0.09525)
		(layer "In2.Cu")
		(net "M_I_CPU1_SA_DQS_DP<5>")
	)
	(segment
		(start 156.045916 -207.447896)
		(end 160.333436 -203.160376)
		(width 0.16002)
		(layer "In2.Cu")
		(net "M_I_CPU1_SA_DQS_DP<5>")
	)
	(segment
		(start 174.869856 -202.003152)
		(end 175.177196 -202.310492)
		(width 0.16002)
		(layer "In2.Cu")
		(net "M_I_CPU1_SA_DQS_DP<5>")
	)
	(segment
		(start 143.546068 -223.099376)
		(end 143.584168 -223.077278)
		(width 0.09525)
		(layer "In2.Cu")
		(net "M_I_CPU1_SA_DQS_DP<5>")
	)
	(segment
		(start 151.836882 -212.097366)
		(end 151.572214 -211.832698)
		(width 0.16002)
		(layer "In2.Cu")
		(net "M_I_CPU1_SA_DQS_DP<5>")
	)
	(segment
		(start 154.211274 -210.250278)
		(end 154.584146 -209.877406)
		(width 0.16002)
		(layer "In2.Cu")
		(net "M_I_CPU1_SA_DQS_DP<5>")
	)
	(segment
		(start 154.319478 -208.808828)
		(end 154.516074 -208.612232)
		(width 0.16002)
		(layer "In2.Cu")
		(net "M_I_CPU1_SA_DQS_DP<5>")
	)
	(segment
		(start 156.045916 -208.268316)
		(end 156.045916 -207.447896)
		(width 0.16002)
		(layer "In2.Cu")
		(net "M_I_CPU1_SA_DQS_DP<5>")
	)
	(segment
		(start 151.572214 -211.556346)
		(end 151.769064 -211.359496)
		(width 0.16002)
		(layer "In2.Cu")
		(net "M_I_CPU1_SA_DQS_DP<5>")
	)
	(segment
		(start 151.769064 -211.359496)
		(end 152.04567 -211.359496)
		(width 0.16002)
		(layer "In2.Cu")
		(net "M_I_CPU1_SA_DQS_DP<5>")
	)
	(segment
		(start 150.936452 -212.997542)
		(end 151.46401 -212.997542)
		(width 0.16002)
		(layer "In2.Cu")
		(net "M_I_CPU1_SA_DQS_DP<5>")
	)
	(segment
		(start 142.573756 -224.738184)
		(end 142.606268 -224.719388)
		(width 0.09525)
		(layer "In2.Cu")
		(net "M_I_CPU1_SA_DQS_DP<5>")
	)
	(segment
		(start 172.862748 -203.160376)
		(end 173.227492 -202.795632)
		(width 0.16002)
		(layer "In2.Cu")
		(net "M_I_CPU1_SA_DQS_DP<5>")
	)
	(segment
		(start 152.04567 -211.359496)
		(end 152.310084 -211.62391)
		(width 0.16002)
		(layer "In2.Cu")
		(net "M_I_CPU1_SA_DQS_DP<5>")
	)
	(segment
		(start 153.210514 -211.251038)
		(end 153.210514 -210.723734)
		(width 0.16002)
		(layer "In2.Cu")
		(net "M_I_CPU1_SA_DQS_DP<5>")
	)
	(segment
		(start 165.318694 -203.160376)
		(end 165.683438 -202.795632)
		(width 0.16002)
		(layer "In2.Cu")
		(net "M_I_CPU1_SA_DQS_DP<5>")
	)
	(segment
		(start 174.456852 -202.003152)
		(end 174.869856 -202.003152)
		(width 0.16002)
		(layer "In2.Cu")
		(net "M_I_CPU1_SA_DQS_DP<5>")
	)
	(segment
		(start 128.50622 -227.959412)
		(end 128.514602 -227.954586)
		(width 0.09525)
		(layer "In2.Cu")
		(net "M_I_CPU1_SA_DQS_DP<5>")
	)
	(segment
		(start 143.076168 -223.909382)
		(end 143.114268 -223.887284)
		(width 0.09525)
		(layer "In2.Cu")
		(net "M_I_CPU1_SA_DQS_DP<5>")
	)
	(segment
		(start 142.606268 -224.719388)
		(end 142.64132 -224.698814)
		(width 0.09525)
		(layer "In2.Cu")
		(net "M_I_CPU1_SA_DQS_DP<5>")
	)
	(segment
		(start 177.813208 -202.278996)
		(end 178.293268 -202.278996)
		(width 0.16002)
		(layer "In2.Cu")
		(net "M_I_CPU1_SA_DQS_DP<5>")
	)
	(segment
		(start 178.293268 -202.278996)
		(end 178.410108 -202.162156)
		(width 0.16002)
		(layer "In2.Cu")
		(net "M_I_CPU1_SA_DQS_DP<5>")
	)
	(segment
		(start 132.266182 -227.959412)
		(end 132.274564 -227.954586)
		(width 0.09525)
		(layer "In2.Cu")
		(net "M_I_CPU1_SA_DQS_DP<5>")
	)
	(segment
		(start 141.163802 -227.168202)
		(end 141.196314 -227.149406)
		(width 0.09525)
		(layer "In2.Cu")
		(net "M_I_CPU1_SA_DQS_DP<5>")
	)
	(segment
		(start 152.945846 -210.459066)
		(end 152.945846 -210.182714)
		(width 0.16002)
		(layer "In2.Cu")
		(net "M_I_CPU1_SA_DQS_DP<5>")
	)
	(segment
		(start 150.672038 -212.733128)
		(end 150.936452 -212.997542)
		(width 0.16002)
		(layer "In2.Cu")
		(net "M_I_CPU1_SA_DQS_DP<5>")
	)
	(segment
		(start 150.395432 -212.733128)
		(end 150.672038 -212.733128)
		(width 0.16002)
		(layer "In2.Cu")
		(net "M_I_CPU1_SA_DQS_DP<5>")
	)
	(segment
		(start 143.984472 -222.307658)
		(end 143.987012 -222.30588)
		(width 0.09525)
		(layer "In2.Cu")
		(net "M_I_CPU1_SA_DQS_DP<5>")
	)
	(segment
		(start 140.154914 -227.954586)
		(end 140.163296 -227.959412)
		(width 0.09525)
		(layer "In2.Cu")
		(net "M_I_CPU1_SA_DQS_DP<5>")
	)
	(segment
		(start 150.198582 -212.929978)
		(end 150.395432 -212.733128)
		(width 0.16002)
		(layer "In2.Cu")
		(net "M_I_CPU1_SA_DQS_DP<5>")
	)
	(segment
		(start 127.908558 -228.019102)
		(end 128.009396 -227.992432)
		(width 0.09525)
		(layer "In2.Cu")
		(net "M_I_CPU1_SA_DQS_DP<5>")
	)
	(segment
		(start 144.356074 -220.105478)
		(end 150.46325 -213.998302)
		(width 0.16002)
		(layer "In2.Cu")
		(net "M_I_CPU1_SA_DQS_DP<5>")
	)
	(segment
		(start 154.584146 -209.350102)
		(end 154.319478 -209.085434)
		(width 0.16002)
		(layer "In2.Cu")
		(net "M_I_CPU1_SA_DQS_DP<5>")
	)
	(segment
		(start 136.394952 -227.954586)
		(end 136.403334 -227.959412)
		(width 0.09525)
		(layer "In2.Cu")
		(net "M_I_CPU1_SA_DQS_DP<5>")
	)
	(segment
		(start 177.067972 -202.310492)
		(end 177.216308 -202.162156)
		(width 0.16002)
		(layer "In2.Cu")
		(net "M_I_CPU1_SA_DQS_DP<5>")
	)
	(segment
		(start 152.837642 -211.62391)
		(end 153.210514 -211.251038)
		(width 0.16002)
		(layer "In2.Cu")
		(net "M_I_CPU1_SA_DQS_DP<5>")
	)
	(segment
		(start 177.216308 -202.162156)
		(end 177.696368 -202.162156)
		(width 0.16002)
		(layer "In2.Cu")
		(net "M_I_CPU1_SA_DQS_DP<5>")
	)
	(segment
		(start 155.4861 -208.828132)
		(end 156.045916 -208.268316)
		(width 0.16002)
		(layer "In2.Cu")
		(net "M_I_CPU1_SA_DQS_DP<5>")
	)
	(segment
		(start 151.46401 -212.997542)
		(end 151.836882 -212.62467)
		(width 0.16002)
		(layer "In2.Cu")
		(net "M_I_CPU1_SA_DQS_DP<5>")
	)
	(segment
		(start 141.666214 -226.3394)
		(end 141.704314 -226.317302)
		(width 0.09525)
		(layer "In2.Cu")
		(net "M_I_CPU1_SA_DQS_DP<5>")
	)
	(segment
		(start 160.333436 -203.160376)
		(end 165.318694 -203.160376)
		(width 0.16002)
		(layer "In2.Cu")
		(net "M_I_CPU1_SA_DQS_DP<5>")
	)
	(segment
		(start 154.516074 -208.612232)
		(end 154.792934 -208.612232)
		(width 0.16002)
		(layer "In2.Cu")
		(net "M_I_CPU1_SA_DQS_DP<5>")
	)
	(segment
		(start 133.206236 -227.959412)
		(end 133.214618 -227.954586)
		(width 0.09525)
		(layer "In2.Cu")
		(net "M_I_CPU1_SA_DQS_DP<5>")
	)
	(segment
		(start 154.584146 -209.877406)
		(end 154.584146 -209.350102)
		(width 0.16002)
		(layer "In2.Cu")
		(net "M_I_CPU1_SA_DQS_DP<5>")
	)
	(segment
		(start 144.297146 -221.257114)
		(end 144.356074 -221.198186)
		(width 0.09525)
		(layer "In2.Cu")
		(net "M_I_CPU1_SA_DQS_DP<5>")
	)
	(segment
		(start 141.633702 -226.358196)
		(end 141.666214 -226.3394)
		(width 0.09525)
		(layer "In2.Cu")
		(net "M_I_CPU1_SA_DQS_DP<5>")
	)
	(segment
		(start 178.410108 -202.162156)
		(end 179.242974 -202.162156)
		(width 0.16002)
		(layer "In2.Cu")
		(net "M_I_CPU1_SA_DQS_DP<5>")
	)
	(segment
		(start 130.754882 -227.954586)
		(end 130.763264 -227.959412)
		(width 0.09525)
		(layer "In2.Cu")
		(net "M_I_CPU1_SA_DQS_DP<5>")
	)
	(segment
		(start 173.664372 -202.795632)
		(end 174.456852 -202.003152)
		(width 0.16002)
		(layer "In2.Cu")
		(net "M_I_CPU1_SA_DQS_DP<5>")
	)
	(segment
		(start 170.946572 -203.160376)
		(end 172.862748 -203.160376)
		(width 0.16002)
		(layer "In2.Cu")
		(net "M_I_CPU1_SA_DQS_DP<5>")
	)
	(segment
		(start 140.72616 -227.959412)
		(end 140.76426 -227.937314)
		(width 0.09525)
		(layer "In2.Cu")
		(net "M_I_CPU1_SA_DQS_DP<5>")
	)
	(segment
		(start 165.683438 -202.795632)
		(end 166.120318 -202.795632)
		(width 0.16002)
		(layer "In2.Cu")
		(net "M_I_CPU1_SA_DQS_DP<5>")
	)
	(segment
		(start 143.043656 -223.928178)
		(end 143.076168 -223.909382)
		(width 0.09525)
		(layer "In2.Cu")
		(net "M_I_CPU1_SA_DQS_DP<5>")
	)
	(segment
		(start 137.906252 -227.959412)
		(end 137.914634 -227.954586)
		(width 0.09525)
		(layer "In2.Cu")
		(net "M_I_CPU1_SA_DQS_DP<5>")
	)
	(segment
		(start 150.46325 -213.998302)
		(end 150.46325 -213.470998)
		(width 0.16002)
		(layer "In2.Cu")
		(net "M_I_CPU1_SA_DQS_DP<5>")
	)
	(segment
		(start 154.792934 -208.612232)
		(end 155.008834 -208.828132)
		(width 0.16002)
		(layer "In2.Cu")
		(net "M_I_CPU1_SA_DQS_DP<5>")
	)
	(segment
		(start 144.297146 -221.803722)
		(end 144.297146 -221.257114)
		(width 0.09525)
		(layer "In2.Cu")
		(net "M_I_CPU1_SA_DQS_DP<5>")
	)
	(segment
		(start 167.325802 -202.003152)
		(end 167.633142 -202.310492)
		(width 0.16002)
		(layer "In2.Cu")
		(net "M_I_CPU1_SA_DQS_DP<5>")
	)
	(segment
		(start 151.572214 -211.832698)
		(end 151.572214 -211.556346)
		(width 0.16002)
		(layer "In2.Cu")
		(net "M_I_CPU1_SA_DQS_DP<5>")
	)
	(segment
		(start 150.198582 -213.20633)
		(end 150.198582 -212.929978)
		(width 0.16002)
		(layer "In2.Cu")
		(net "M_I_CPU1_SA_DQS_DP<5>")
	)
	(segment
		(start 177.696368 -202.162156)
		(end 177.813208 -202.278996)
		(width 0.16002)
		(layer "In2.Cu")
		(net "M_I_CPU1_SA_DQS_DP<5>")
	)
	(segment
		(start 155.008834 -208.828132)
		(end 155.4861 -208.828132)
		(width 0.16002)
		(layer "In2.Cu")
		(net "M_I_CPU1_SA_DQS_DP<5>")
	)
	(segment
		(start 173.227492 -202.795632)
		(end 173.664372 -202.795632)
		(width 0.16002)
		(layer "In2.Cu")
		(net "M_I_CPU1_SA_DQS_DP<5>")
	)
	(segment
		(start 131.694936 -227.954586)
		(end 131.703318 -227.959412)
		(width 0.09525)
		(layer "In2.Cu")
		(net "M_I_CPU1_SA_DQS_DP<5>")
	)
	(segment
		(start 127.754634 -228.284532)
		(end 127.908558 -228.019102)
		(width 0.09525)
		(layer "In2.Cu")
		(net "M_I_CPU1_SA_DQS_DP<5>")
	)
	(segment
		(start 175.177196 -202.310492)
		(end 177.067972 -202.310492)
		(width 0.16002)
		(layer "In2.Cu")
		(net "M_I_CPU1_SA_DQS_DP<5>")
	)
	(segment
		(start 142.104618 -225.547682)
		(end 142.136114 -225.529394)
		(width 0.09525)
		(layer "In2.Cu")
		(net "M_I_CPU1_SA_DQS_DP<5>")
	)
	(segment
		(start 153.142696 -209.985864)
		(end 153.419302 -209.985864)
		(width 0.16002)
		(layer "In2.Cu")
		(net "M_I_CPU1_SA_DQS_DP<5>")
	)
	(segment
		(start 179.242974 -202.162156)
		(end 179.516024 -202.435206)
		(width 0.16002)
		(layer "In2.Cu")
		(net "M_I_CPU1_SA_DQS_DP<5>")
	)
	(segment
		(start 141.196314 -227.149406)
		(end 141.231366 -227.128832)
		(width 0.09525)
		(layer "In2.Cu")
		(net "M_I_CPU1_SA_DQS_DP<5>")
	)
	(segment
		(start 143.514572 -223.117664)
		(end 143.546068 -223.099376)
		(width 0.09525)
		(layer "In2.Cu")
		(net "M_I_CPU1_SA_DQS_DP<5>")
	)
	(segment
		(start 167.633142 -202.310492)
		(end 170.096688 -202.310492)
		(width 0.16002)
		(layer "In2.Cu")
		(net "M_I_CPU1_SA_DQS_DP<5>")
	)
	(segment
		(start 142.136114 -225.529394)
		(end 142.174214 -225.507296)
		(width 0.09525)
		(layer "In2.Cu")
		(net "M_I_CPU1_SA_DQS_DP<5>")
	)
	(segment
		(start 151.836882 -212.62467)
		(end 151.836882 -212.097366)
		(width 0.16002)
		(layer "In2.Cu")
		(net "M_I_CPU1_SA_DQS_DP<5>")
	)
	(segment
		(start 154.319478 -209.085434)
		(end 154.319478 -208.808828)
		(width 0.16002)
		(layer "In2.Cu")
		(net "M_I_CPU1_SA_DQS_DP<5>")
	)
	(segment
		(start 136.966198 -227.959412)
		(end 136.97458 -227.954586)
		(width 0.09525)
		(layer "In2.Cu")
		(net "M_I_CPU1_SA_DQS_DP<5>")
	)
	(segment
		(start 166.120318 -202.795632)
		(end 166.912798 -202.003152)
		(width 0.16002)
		(layer "In2.Cu")
		(net "M_I_CPU1_SA_DQS_DP<5>")
	)
	(segment
		(start 166.912798 -202.003152)
		(end 167.325802 -202.003152)
		(width 0.16002)
		(layer "In2.Cu")
		(net "M_I_CPU1_SA_DQS_DP<5>")
	)
	(segment
		(start 153.210514 -210.723734)
		(end 152.945846 -210.459066)
		(width 0.16002)
		(layer "In2.Cu")
		(net "M_I_CPU1_SA_DQS_DP<5>")
	)
	(segment
		(start 150.46325 -213.470998)
		(end 150.198582 -213.20633)
		(width 0.16002)
		(layer "In2.Cu")
		(net "M_I_CPU1_SA_DQS_DP<5>")
	)
	(segment
		(start 170.096688 -202.310492)
		(end 170.946572 -203.160376)
		(width 0.16002)
		(layer "In2.Cu")
		(net "M_I_CPU1_SA_DQS_DP<5>")
	)
	(segment
		(start 135.454898 -227.954586)
		(end 135.46328 -227.959412)
		(width 0.09525)
		(layer "In2.Cu")
		(net "M_I_CPU1_SA_DQS_DP<5>")
	)
	(segment
		(start 144.356074 -221.198186)
		(end 144.356074 -221.174564)
		(width 0.09525)
		(layer "In2.Cu")
		(net "M_I_CPU1_SA_DQS_DP<5>")
	)
	(segment
		(start 153.419302 -209.985864)
		(end 153.683716 -210.250278)
		(width 0.16002)
		(layer "In2.Cu")
		(net "M_I_CPU1_SA_DQS_DP<5>")
	)
	(segment
		(start 153.683716 -210.250278)
		(end 154.211274 -210.250278)
		(width 0.16002)
		(layer "In2.Cu")
		(net "M_I_CPU1_SA_DQS_DP<5>")
	)
	(segment
		(start 152.310084 -211.62391)
		(end 152.837642 -211.62391)
		(width 0.16002)
		(layer "In2.Cu")
		(net "M_I_CPU1_SA_DQS_DP<5>")
	)
	(segment
		(start 152.945846 -210.182714)
		(end 153.142696 -209.985864)
		(width 0.16002)
		(layer "In2.Cu")
		(net "M_I_CPU1_SA_DQS_DP<5>")
	)
	(arc
		(start 140.163296 -227.959412)
		(mid 140.444728 -228.035167)
		(end 140.72616 -227.959412)
		(width 0.09525)
		(layer "In2.Cu")
		(net "M_I_CPU1_SA_DQS_DP<5>")
	)
	(arc
		(start 128.88341 -227.959412)
		(mid 129.164842 -228.035167)
		(end 129.446274 -227.959412)
		(width 0.09525)
		(layer "In2.Cu")
		(net "M_I_CPU1_SA_DQS_DP<5>")
	)
	(arc
		(start 136.026144 -227.959412)
		(mid 136.209919 -227.90864)
		(end 136.394952 -227.954586)
		(width 0.09525)
		(layer "In2.Cu")
		(net "M_I_CPU1_SA_DQS_DP<5>")
	)
	(arc
		(start 143.357092 -223.424496)
		(mid 143.398757 -223.252049)
		(end 143.514572 -223.117664)
		(width 0.09525)
		(layer "In2.Cu")
		(net "M_I_CPU1_SA_DQS_DP<5>")
	)
	(arc
		(start 129.82321 -227.959412)
		(mid 130.104642 -228.035167)
		(end 130.386074 -227.959412)
		(width 0.09525)
		(layer "In2.Cu")
		(net "M_I_CPU1_SA_DQS_DP<5>")
	)
	(arc
		(start 133.214618 -227.954586)
		(mid 133.39965 -227.908672)
		(end 133.583426 -227.959412)
		(width 0.09525)
		(layer "In2.Cu")
		(net "M_I_CPU1_SA_DQS_DP<5>")
	)
	(arc
		(start 140.76426 -227.937314)
		(mid 140.94271 -227.735844)
		(end 141.007084 -227.474526)
		(width 0.09525)
		(layer "In2.Cu")
		(net "M_I_CPU1_SA_DQS_DP<5>")
	)
	(arc
		(start 132.643372 -227.959412)
		(mid 132.924804 -228.035167)
		(end 133.206236 -227.959412)
		(width 0.09525)
		(layer "In2.Cu")
		(net "M_I_CPU1_SA_DQS_DP<5>")
	)
	(arc
		(start 131.326128 -227.959412)
		(mid 131.509903 -227.90864)
		(end 131.694936 -227.954586)
		(width 0.09525)
		(layer "In2.Cu")
		(net "M_I_CPU1_SA_DQS_DP<5>")
	)
	(arc
		(start 141.476984 -226.66452)
		(mid 141.518441 -226.49248)
		(end 141.633702 -226.358196)
		(width 0.09525)
		(layer "In2.Cu")
		(net "M_I_CPU1_SA_DQS_DP<5>")
	)
	(arc
		(start 139.223242 -227.959412)
		(mid 139.504674 -228.035167)
		(end 139.786106 -227.959412)
		(width 0.09525)
		(layer "In2.Cu")
		(net "M_I_CPU1_SA_DQS_DP<5>")
	)
	(arc
		(start 135.46328 -227.959412)
		(mid 135.744712 -228.035167)
		(end 136.026144 -227.959412)
		(width 0.09525)
		(layer "In2.Cu")
		(net "M_I_CPU1_SA_DQS_DP<5>")
	)
	(arc
		(start 131.703318 -227.959412)
		(mid 131.98475 -228.035167)
		(end 132.266182 -227.959412)
		(width 0.09525)
		(layer "In2.Cu")
		(net "M_I_CPU1_SA_DQS_DP<5>")
	)
	(arc
		(start 132.274564 -227.954586)
		(mid 132.459596 -227.908672)
		(end 132.643372 -227.959412)
		(width 0.09525)
		(layer "In2.Cu")
		(net "M_I_CPU1_SA_DQS_DP<5>")
	)
	(arc
		(start 143.584168 -223.077278)
		(mid 143.762618 -222.875808)
		(end 143.826992 -222.61449)
		(width 0.09525)
		(layer "In2.Cu")
		(net "M_I_CPU1_SA_DQS_DP<5>")
	)
	(arc
		(start 130.386074 -227.959412)
		(mid 130.569849 -227.90864)
		(end 130.754882 -227.954586)
		(width 0.09525)
		(layer "In2.Cu")
		(net "M_I_CPU1_SA_DQS_DP<5>")
	)
	(arc
		(start 141.007084 -227.474526)
		(mid 141.048541 -227.302486)
		(end 141.163802 -227.168202)
		(width 0.09525)
		(layer "In2.Cu")
		(net "M_I_CPU1_SA_DQS_DP<5>")
	)
	(arc
		(start 142.886938 -224.234502)
		(mid 142.928395 -224.062462)
		(end 143.043656 -223.928178)
		(width 0.09525)
		(layer "In2.Cu")
		(net "M_I_CPU1_SA_DQS_DP<5>")
	)
	(arc
		(start 142.417038 -225.044508)
		(mid 142.458495 -224.872468)
		(end 142.573756 -224.738184)
		(width 0.09525)
		(layer "In2.Cu")
		(net "M_I_CPU1_SA_DQS_DP<5>")
	)
	(arc
		(start 129.446274 -227.959412)
		(mid 129.634742 -227.908735)
		(end 129.82321 -227.959412)
		(width 0.09525)
		(layer "In2.Cu")
		(net "M_I_CPU1_SA_DQS_DP<5>")
	)
	(arc
		(start 134.14629 -227.959412)
		(mid 134.334758 -227.908735)
		(end 134.523226 -227.959412)
		(width 0.09525)
		(layer "In2.Cu")
		(net "M_I_CPU1_SA_DQS_DP<5>")
	)
	(arc
		(start 144.056862 -222.26524)
		(mid 144.233536 -222.063913)
		(end 144.297146 -221.803722)
		(width 0.09525)
		(layer "In2.Cu")
		(net "M_I_CPU1_SA_DQS_DP<5>")
	)
	(arc
		(start 128.02997 -228.00056)
		(mid 128.272712 -228.03333)
		(end 128.50622 -227.959412)
		(width 0.09525)
		(layer "In2.Cu")
		(net "M_I_CPU1_SA_DQS_DP<5>")
	)
	(arc
		(start 141.231366 -227.128832)
		(mid 141.411757 -226.927133)
		(end 141.476984 -226.66452)
		(width 0.09525)
		(layer "In2.Cu")
		(net "M_I_CPU1_SA_DQS_DP<5>")
	)
	(arc
		(start 136.97458 -227.954586)
		(mid 137.159612 -227.908672)
		(end 137.343388 -227.959412)
		(width 0.09525)
		(layer "In2.Cu")
		(net "M_I_CPU1_SA_DQS_DP<5>")
	)
	(arc
		(start 130.763264 -227.959412)
		(mid 131.044696 -228.035167)
		(end 131.326128 -227.959412)
		(width 0.09525)
		(layer "In2.Cu")
		(net "M_I_CPU1_SA_DQS_DP<5>")
	)
	(arc
		(start 143.826992 -222.61449)
		(mid 143.868657 -222.442043)
		(end 143.984472 -222.307658)
		(width 0.09525)
		(layer "In2.Cu")
		(net "M_I_CPU1_SA_DQS_DP<5>")
	)
	(arc
		(start 141.947138 -225.854514)
		(mid 141.988803 -225.682067)
		(end 142.104618 -225.547682)
		(width 0.09525)
		(layer "In2.Cu")
		(net "M_I_CPU1_SA_DQS_DP<5>")
	)
	(arc
		(start 142.174214 -225.507296)
		(mid 142.352664 -225.305826)
		(end 142.417038 -225.044508)
		(width 0.09525)
		(layer "In2.Cu")
		(net "M_I_CPU1_SA_DQS_DP<5>")
	)
	(arc
		(start 128.514602 -227.954586)
		(mid 128.699634 -227.908672)
		(end 128.88341 -227.959412)
		(width 0.09525)
		(layer "In2.Cu")
		(net "M_I_CPU1_SA_DQS_DP<5>")
	)
	(arc
		(start 142.64132 -224.698814)
		(mid 142.821711 -224.497115)
		(end 142.886938 -224.234502)
		(width 0.09525)
		(layer "In2.Cu")
		(net "M_I_CPU1_SA_DQS_DP<5>")
	)
	(arc
		(start 138.283442 -227.959412)
		(mid 138.564874 -228.035167)
		(end 138.846306 -227.959412)
		(width 0.09525)
		(layer "In2.Cu")
		(net "M_I_CPU1_SA_DQS_DP<5>")
	)
	(arc
		(start 141.704314 -226.317302)
		(mid 141.882764 -226.115832)
		(end 141.947138 -225.854514)
		(width 0.09525)
		(layer "In2.Cu")
		(net "M_I_CPU1_SA_DQS_DP<5>")
	)
	(arc
		(start 135.08609 -227.959412)
		(mid 135.269865 -227.90864)
		(end 135.454898 -227.954586)
		(width 0.09525)
		(layer "In2.Cu")
		(net "M_I_CPU1_SA_DQS_DP<5>")
	)
	(arc
		(start 137.914634 -227.954586)
		(mid 138.099666 -227.908672)
		(end 138.283442 -227.959412)
		(width 0.09525)
		(layer "In2.Cu")
		(net "M_I_CPU1_SA_DQS_DP<5>")
	)
	(arc
		(start 139.786106 -227.959412)
		(mid 139.969881 -227.90864)
		(end 140.154914 -227.954586)
		(width 0.09525)
		(layer "In2.Cu")
		(net "M_I_CPU1_SA_DQS_DP<5>")
	)
	(arc
		(start 137.343388 -227.959412)
		(mid 137.62482 -228.035167)
		(end 137.906252 -227.959412)
		(width 0.09525)
		(layer "In2.Cu")
		(net "M_I_CPU1_SA_DQS_DP<5>")
	)
	(arc
		(start 134.523226 -227.959412)
		(mid 134.804658 -228.035167)
		(end 135.08609 -227.959412)
		(width 0.09525)
		(layer "In2.Cu")
		(net "M_I_CPU1_SA_DQS_DP<5>")
	)
	(arc
		(start 128.009396 -227.992432)
		(mid 128.019644 -227.996595)
		(end 128.02997 -228.00056)
		(width 0.09525)
		(layer "In2.Cu")
		(net "M_I_CPU1_SA_DQS_DP<5>")
	)
	(arc
		(start 138.846306 -227.959412)
		(mid 139.034774 -227.908735)
		(end 139.223242 -227.959412)
		(width 0.09525)
		(layer "In2.Cu")
		(net "M_I_CPU1_SA_DQS_DP<5>")
	)
	(arc
		(start 143.114268 -223.887284)
		(mid 143.292718 -223.685814)
		(end 143.357092 -223.424496)
		(width 0.09525)
		(layer "In2.Cu")
		(net "M_I_CPU1_SA_DQS_DP<5>")
	)
	(arc
		(start 136.403334 -227.959412)
		(mid 136.684766 -228.035167)
		(end 136.966198 -227.959412)
		(width 0.09525)
		(layer "In2.Cu")
		(net "M_I_CPU1_SA_DQS_DP<5>")
	)
	(arc
		(start 133.583426 -227.959412)
		(mid 133.864858 -228.035167)
		(end 134.14629 -227.959412)
		(width 0.09525)
		(layer "In2.Cu")
		(net "M_I_CPU1_SA_DQS_DP<5>")
	)
	(segment
		(start 129.16789 -246.370348)
		(end 129.634742 -246.10441)
		(width 0.12954)
		(layer "F.Cu")
		(net "M_I_CPU1_SA_DQS_DP<4>")
	)
	(segment
		(start 144.483074 -246.42953)
		(end 144.506442 -246.442992)
		(width 0.09525)
		(layer "In2.Cu")
		(net "M_I_CPU1_SA_DQS_DP<4>")
	)
	(segment
		(start 140.154914 -246.434356)
		(end 140.163296 -246.42953)
		(width 0.09525)
		(layer "In2.Cu")
		(net "M_I_CPU1_SA_DQS_DP<4>")
	)
	(segment
		(start 141.666214 -246.42953)
		(end 141.674596 -246.434356)
		(width 0.09525)
		(layer "In2.Cu")
		(net "M_I_CPU1_SA_DQS_DP<4>")
	)
	(segment
		(start 181.394608 -238.409988)
		(end 181.874668 -238.409988)
		(width 0.16002)
		(layer "In2.Cu")
		(net "M_I_CPU1_SA_DQS_DP<4>")
	)
	(segment
		(start 133.206236 -246.42953)
		(end 133.214618 -246.434356)
		(width 0.09525)
		(layer "In2.Cu")
		(net "M_I_CPU1_SA_DQS_DP<4>")
	)
	(segment
		(start 147.745958 -246.339614)
		(end 147.87626 -246.339614)
		(width 0.16002)
		(layer "In2.Cu")
		(net "M_I_CPU1_SA_DQS_DP<4>")
	)
	(segment
		(start 169.893742 -237.410244)
		(end 170.743626 -238.260128)
		(width 0.16002)
		(layer "In2.Cu")
		(net "M_I_CPU1_SA_DQS_DP<4>")
	)
	(segment
		(start 132.266182 -246.42953)
		(end 132.274564 -246.434356)
		(width 0.09525)
		(layer "In2.Cu")
		(net "M_I_CPU1_SA_DQS_DP<4>")
	)
	(segment
		(start 147.87626 -246.339614)
		(end 148.455888 -245.759986)
		(width 0.16002)
		(layer "In2.Cu")
		(net "M_I_CPU1_SA_DQS_DP<4>")
	)
	(segment
		(start 180.753512 -238.592868)
		(end 181.211728 -238.592868)
		(width 0.16002)
		(layer "In2.Cu")
		(net "M_I_CPU1_SA_DQS_DP<4>")
	)
	(segment
		(start 167.664638 -237.410244)
		(end 169.893742 -237.410244)
		(width 0.16002)
		(layer "In2.Cu")
		(net "M_I_CPU1_SA_DQS_DP<4>")
	)
	(segment
		(start 174.366936 -237.726728)
		(end 174.892208 -237.726728)
		(width 0.16002)
		(layer "In2.Cu")
		(net "M_I_CPU1_SA_DQS_DP<4>")
	)
	(segment
		(start 147.663154 -246.398796)
		(end 147.722336 -246.339614)
		(width 0.09525)
		(layer "In2.Cu")
		(net "M_I_CPU1_SA_DQS_DP<4>")
	)
	(segment
		(start 136.966198 -246.42953)
		(end 136.97458 -246.434356)
		(width 0.09525)
		(layer "In2.Cu")
		(net "M_I_CPU1_SA_DQS_DP<4>")
	)
	(segment
		(start 131.694936 -246.434356)
		(end 131.703318 -246.42953)
		(width 0.09525)
		(layer "In2.Cu")
		(net "M_I_CPU1_SA_DQS_DP<4>")
	)
	(segment
		(start 135.454898 -246.434356)
		(end 135.46328 -246.42953)
		(width 0.09525)
		(layer "In2.Cu")
		(net "M_I_CPU1_SA_DQS_DP<4>")
	)
	(segment
		(start 162.95243 -238.755682)
		(end 163.447984 -238.260128)
		(width 0.16002)
		(layer "In2.Cu")
		(net "M_I_CPU1_SA_DQS_DP<4>")
	)
	(segment
		(start 145.388838 -246.408956)
		(end 145.424144 -246.429276)
		(width 0.09525)
		(layer "In2.Cu")
		(net "M_I_CPU1_SA_DQS_DP<4>")
	)
	(segment
		(start 174.892208 -237.726728)
		(end 175.208692 -237.410244)
		(width 0.16002)
		(layer "In2.Cu")
		(net "M_I_CPU1_SA_DQS_DP<4>")
	)
	(segment
		(start 129.480818 -246.36984)
		(end 129.503932 -246.456454)
		(width 0.09525)
		(layer "In2.Cu")
		(net "M_I_CPU1_SA_DQS_DP<4>")
	)
	(segment
		(start 147.30349 -246.398796)
		(end 147.663154 -246.398796)
		(width 0.09525)
		(layer "In2.Cu")
		(net "M_I_CPU1_SA_DQS_DP<4>")
	)
	(segment
		(start 181.874668 -238.409988)
		(end 181.991508 -238.293148)
		(width 0.16002)
		(layer "In2.Cu")
		(net "M_I_CPU1_SA_DQS_DP<4>")
	)
	(segment
		(start 178.059588 -237.984284)
		(end 180.144928 -237.984284)
		(width 0.16002)
		(layer "In2.Cu")
		(net "M_I_CPU1_SA_DQS_DP<4>")
	)
	(segment
		(start 167.348154 -237.726728)
		(end 167.664638 -237.410244)
		(width 0.16002)
		(layer "In2.Cu")
		(net "M_I_CPU1_SA_DQS_DP<4>")
	)
	(segment
		(start 148.455888 -245.759986)
		(end 157.07741 -245.759986)
		(width 0.16002)
		(layer "In2.Cu")
		(net "M_I_CPU1_SA_DQS_DP<4>")
	)
	(segment
		(start 129.634742 -246.10441)
		(end 129.480818 -246.36984)
		(width 0.09525)
		(layer "In2.Cu")
		(net "M_I_CPU1_SA_DQS_DP<4>")
	)
	(segment
		(start 181.991508 -238.293148)
		(end 182.471568 -238.293148)
		(width 0.16002)
		(layer "In2.Cu")
		(net "M_I_CPU1_SA_DQS_DP<4>")
	)
	(segment
		(start 177.485548 -237.410244)
		(end 178.059588 -237.984284)
		(width 0.16002)
		(layer "In2.Cu")
		(net "M_I_CPU1_SA_DQS_DP<4>")
	)
	(segment
		(start 137.906252 -246.42953)
		(end 137.914634 -246.434356)
		(width 0.09525)
		(layer "In2.Cu")
		(net "M_I_CPU1_SA_DQS_DP<4>")
	)
	(segment
		(start 147.722336 -246.339614)
		(end 147.745958 -246.339614)
		(width 0.09525)
		(layer "In2.Cu")
		(net "M_I_CPU1_SA_DQS_DP<4>")
	)
	(segment
		(start 165.640258 -238.567468)
		(end 165.982142 -238.567468)
		(width 0.16002)
		(layer "In2.Cu")
		(net "M_I_CPU1_SA_DQS_DP<4>")
	)
	(segment
		(start 172.876972 -238.260128)
		(end 173.184312 -238.567468)
		(width 0.16002)
		(layer "In2.Cu")
		(net "M_I_CPU1_SA_DQS_DP<4>")
	)
	(segment
		(start 145.611342 -246.480076)
		(end 145.746724 -246.480076)
		(width 0.09525)
		(layer "In2.Cu")
		(net "M_I_CPU1_SA_DQS_DP<4>")
	)
	(segment
		(start 181.211728 -238.592868)
		(end 181.394608 -238.409988)
		(width 0.16002)
		(layer "In2.Cu")
		(net "M_I_CPU1_SA_DQS_DP<4>")
	)
	(segment
		(start 170.743626 -238.260128)
		(end 172.876972 -238.260128)
		(width 0.16002)
		(layer "In2.Cu")
		(net "M_I_CPU1_SA_DQS_DP<4>")
	)
	(segment
		(start 143.89862 -246.442738)
		(end 143.921988 -246.429276)
		(width 0.09525)
		(layer "In2.Cu")
		(net "M_I_CPU1_SA_DQS_DP<4>")
	)
	(segment
		(start 182.471568 -238.293148)
		(end 182.588408 -238.409988)
		(width 0.16002)
		(layer "In2.Cu")
		(net "M_I_CPU1_SA_DQS_DP<4>")
	)
	(segment
		(start 146.031712 -246.765064)
		(end 146.937222 -246.765064)
		(width 0.09525)
		(layer "In2.Cu")
		(net "M_I_CPU1_SA_DQS_DP<4>")
	)
	(segment
		(start 182.588408 -238.409988)
		(end 183.341518 -238.409988)
		(width 0.16002)
		(layer "In2.Cu")
		(net "M_I_CPU1_SA_DQS_DP<4>")
	)
	(segment
		(start 130.754882 -246.434356)
		(end 130.763264 -246.42953)
		(width 0.09525)
		(layer "In2.Cu")
		(net "M_I_CPU1_SA_DQS_DP<4>")
	)
	(segment
		(start 183.341518 -238.409988)
		(end 183.616092 -238.135414)
		(width 0.16002)
		(layer "In2.Cu")
		(net "M_I_CPU1_SA_DQS_DP<4>")
	)
	(segment
		(start 166.822882 -237.726728)
		(end 167.348154 -237.726728)
		(width 0.16002)
		(layer "In2.Cu")
		(net "M_I_CPU1_SA_DQS_DP<4>")
	)
	(segment
		(start 165.332918 -238.260128)
		(end 165.640258 -238.567468)
		(width 0.16002)
		(layer "In2.Cu")
		(net "M_I_CPU1_SA_DQS_DP<4>")
	)
	(segment
		(start 162.95243 -239.884966)
		(end 162.95243 -238.755682)
		(width 0.16002)
		(layer "In2.Cu")
		(net "M_I_CPU1_SA_DQS_DP<4>")
	)
	(segment
		(start 145.746724 -246.480076)
		(end 146.031712 -246.765064)
		(width 0.09525)
		(layer "In2.Cu")
		(net "M_I_CPU1_SA_DQS_DP<4>")
	)
	(segment
		(start 157.07741 -245.759986)
		(end 162.95243 -239.884966)
		(width 0.16002)
		(layer "In2.Cu")
		(net "M_I_CPU1_SA_DQS_DP<4>")
	)
	(segment
		(start 180.144928 -237.984284)
		(end 180.753512 -238.592868)
		(width 0.16002)
		(layer "In2.Cu")
		(net "M_I_CPU1_SA_DQS_DP<4>")
	)
	(segment
		(start 136.394952 -246.434356)
		(end 136.403334 -246.42953)
		(width 0.09525)
		(layer "In2.Cu")
		(net "M_I_CPU1_SA_DQS_DP<4>")
	)
	(segment
		(start 146.937222 -246.765064)
		(end 147.30349 -246.398796)
		(width 0.09525)
		(layer "In2.Cu")
		(net "M_I_CPU1_SA_DQS_DP<4>")
	)
	(segment
		(start 173.184312 -238.567468)
		(end 173.526196 -238.567468)
		(width 0.16002)
		(layer "In2.Cu")
		(net "M_I_CPU1_SA_DQS_DP<4>")
	)
	(segment
		(start 175.208692 -237.410244)
		(end 177.485548 -237.410244)
		(width 0.16002)
		(layer "In2.Cu")
		(net "M_I_CPU1_SA_DQS_DP<4>")
	)
	(segment
		(start 143.921988 -246.429276)
		(end 143.945864 -246.41556)
		(width 0.09525)
		(layer "In2.Cu")
		(net "M_I_CPU1_SA_DQS_DP<4>")
	)
	(segment
		(start 141.094968 -246.434356)
		(end 141.10335 -246.42953)
		(width 0.09525)
		(layer "In2.Cu")
		(net "M_I_CPU1_SA_DQS_DP<4>")
	)
	(segment
		(start 163.447984 -238.260128)
		(end 165.332918 -238.260128)
		(width 0.16002)
		(layer "In2.Cu")
		(net "M_I_CPU1_SA_DQS_DP<4>")
	)
	(segment
		(start 165.982142 -238.567468)
		(end 166.822882 -237.726728)
		(width 0.16002)
		(layer "In2.Cu")
		(net "M_I_CPU1_SA_DQS_DP<4>")
	)
	(segment
		(start 173.526196 -238.567468)
		(end 174.366936 -237.726728)
		(width 0.16002)
		(layer "In2.Cu")
		(net "M_I_CPU1_SA_DQS_DP<4>")
	)
	(arc
		(start 136.403334 -246.42953)
		(mid 136.684766 -246.353775)
		(end 136.966198 -246.42953)
		(width 0.09525)
		(layer "In2.Cu")
		(net "M_I_CPU1_SA_DQS_DP<4>")
	)
	(arc
		(start 129.82321 -246.42953)
		(mid 130.104642 -246.353775)
		(end 130.386074 -246.42953)
		(width 0.09525)
		(layer "In2.Cu")
		(net "M_I_CPU1_SA_DQS_DP<4>")
	)
	(arc
		(start 141.10335 -246.42953)
		(mid 141.384782 -246.353775)
		(end 141.666214 -246.42953)
		(width 0.09525)
		(layer "In2.Cu")
		(net "M_I_CPU1_SA_DQS_DP<4>")
	)
	(arc
		(start 141.674596 -246.434356)
		(mid 141.859628 -246.48027)
		(end 142.043404 -246.42953)
		(width 0.09525)
		(layer "In2.Cu")
		(net "M_I_CPU1_SA_DQS_DP<4>")
	)
	(arc
		(start 130.386074 -246.42953)
		(mid 130.569849 -246.480302)
		(end 130.754882 -246.434356)
		(width 0.09525)
		(layer "In2.Cu")
		(net "M_I_CPU1_SA_DQS_DP<4>")
	)
	(arc
		(start 133.214618 -246.434356)
		(mid 133.39965 -246.48027)
		(end 133.583426 -246.42953)
		(width 0.09525)
		(layer "In2.Cu")
		(net "M_I_CPU1_SA_DQS_DP<4>")
	)
	(arc
		(start 129.503932 -246.456454)
		(mid 129.666583 -246.478714)
		(end 129.82321 -246.42953)
		(width 0.09525)
		(layer "In2.Cu")
		(net "M_I_CPU1_SA_DQS_DP<4>")
	)
	(arc
		(start 143.945864 -246.41556)
		(mid 144.216247 -246.354)
		(end 144.483074 -246.42953)
		(width 0.09525)
		(layer "In2.Cu")
		(net "M_I_CPU1_SA_DQS_DP<4>")
	)
	(arc
		(start 136.97458 -246.434356)
		(mid 137.159612 -246.48027)
		(end 137.343388 -246.42953)
		(width 0.09525)
		(layer "In2.Cu")
		(net "M_I_CPU1_SA_DQS_DP<4>")
	)
	(arc
		(start 142.606268 -246.42953)
		(mid 142.794736 -246.480207)
		(end 142.983204 -246.42953)
		(width 0.09525)
		(layer "In2.Cu")
		(net "M_I_CPU1_SA_DQS_DP<4>")
	)
	(arc
		(start 138.283442 -246.42953)
		(mid 138.564874 -246.353775)
		(end 138.846306 -246.42953)
		(width 0.09525)
		(layer "In2.Cu")
		(net "M_I_CPU1_SA_DQS_DP<4>")
	)
	(arc
		(start 143.546068 -246.42953)
		(mid 143.7207 -246.48007)
		(end 143.89862 -246.442738)
		(width 0.09525)
		(layer "In2.Cu")
		(net "M_I_CPU1_SA_DQS_DP<4>")
	)
	(arc
		(start 144.506442 -246.442992)
		(mid 144.68563 -246.480837)
		(end 144.861534 -246.429784)
		(width 0.09525)
		(layer "In2.Cu")
		(net "M_I_CPU1_SA_DQS_DP<4>")
	)
	(arc
		(start 137.343388 -246.42953)
		(mid 137.62482 -246.353775)
		(end 137.906252 -246.42953)
		(width 0.09525)
		(layer "In2.Cu")
		(net "M_I_CPU1_SA_DQS_DP<4>")
	)
	(arc
		(start 135.08609 -246.42953)
		(mid 135.269865 -246.480302)
		(end 135.454898 -246.434356)
		(width 0.09525)
		(layer "In2.Cu")
		(net "M_I_CPU1_SA_DQS_DP<4>")
	)
	(arc
		(start 130.763264 -246.42953)
		(mid 131.044696 -246.353775)
		(end 131.326128 -246.42953)
		(width 0.09525)
		(layer "In2.Cu")
		(net "M_I_CPU1_SA_DQS_DP<4>")
	)
	(arc
		(start 133.583426 -246.42953)
		(mid 133.864858 -246.353775)
		(end 134.14629 -246.42953)
		(width 0.09525)
		(layer "In2.Cu")
		(net "M_I_CPU1_SA_DQS_DP<4>")
	)
	(arc
		(start 131.703318 -246.42953)
		(mid 131.98475 -246.353775)
		(end 132.266182 -246.42953)
		(width 0.09525)
		(layer "In2.Cu")
		(net "M_I_CPU1_SA_DQS_DP<4>")
	)
	(arc
		(start 142.983204 -246.42953)
		(mid 143.264636 -246.353775)
		(end 143.546068 -246.42953)
		(width 0.09525)
		(layer "In2.Cu")
		(net "M_I_CPU1_SA_DQS_DP<4>")
	)
	(arc
		(start 134.14629 -246.42953)
		(mid 134.334758 -246.480207)
		(end 134.523226 -246.42953)
		(width 0.09525)
		(layer "In2.Cu")
		(net "M_I_CPU1_SA_DQS_DP<4>")
	)
	(arc
		(start 137.914634 -246.434356)
		(mid 138.099666 -246.48027)
		(end 138.283442 -246.42953)
		(width 0.09525)
		(layer "In2.Cu")
		(net "M_I_CPU1_SA_DQS_DP<4>")
	)
	(arc
		(start 142.043404 -246.42953)
		(mid 142.324836 -246.353775)
		(end 142.606268 -246.42953)
		(width 0.09525)
		(layer "In2.Cu")
		(net "M_I_CPU1_SA_DQS_DP<4>")
	)
	(arc
		(start 136.026144 -246.42953)
		(mid 136.209919 -246.480302)
		(end 136.394952 -246.434356)
		(width 0.09525)
		(layer "In2.Cu")
		(net "M_I_CPU1_SA_DQS_DP<4>")
	)
	(arc
		(start 144.861534 -246.429784)
		(mid 145.122586 -246.353537)
		(end 145.388838 -246.408956)
		(width 0.09525)
		(layer "In2.Cu")
		(net "M_I_CPU1_SA_DQS_DP<4>")
	)
	(arc
		(start 132.274564 -246.434356)
		(mid 132.459596 -246.48027)
		(end 132.643372 -246.42953)
		(width 0.09525)
		(layer "In2.Cu")
		(net "M_I_CPU1_SA_DQS_DP<4>")
	)
	(arc
		(start 139.786106 -246.42953)
		(mid 139.969881 -246.480302)
		(end 140.154914 -246.434356)
		(width 0.09525)
		(layer "In2.Cu")
		(net "M_I_CPU1_SA_DQS_DP<4>")
	)
	(arc
		(start 132.643372 -246.42953)
		(mid 132.924804 -246.353775)
		(end 133.206236 -246.42953)
		(width 0.09525)
		(layer "In2.Cu")
		(net "M_I_CPU1_SA_DQS_DP<4>")
	)
	(arc
		(start 138.846306 -246.42953)
		(mid 139.034774 -246.480207)
		(end 139.223242 -246.42953)
		(width 0.09525)
		(layer "In2.Cu")
		(net "M_I_CPU1_SA_DQS_DP<4>")
	)
	(arc
		(start 140.163296 -246.42953)
		(mid 140.444728 -246.353775)
		(end 140.72616 -246.42953)
		(width 0.09525)
		(layer "In2.Cu")
		(net "M_I_CPU1_SA_DQS_DP<4>")
	)
	(arc
		(start 140.72616 -246.42953)
		(mid 140.909935 -246.480302)
		(end 141.094968 -246.434356)
		(width 0.09525)
		(layer "In2.Cu")
		(net "M_I_CPU1_SA_DQS_DP<4>")
	)
	(arc
		(start 139.223242 -246.42953)
		(mid 139.504674 -246.353775)
		(end 139.786106 -246.42953)
		(width 0.09525)
		(layer "In2.Cu")
		(net "M_I_CPU1_SA_DQS_DP<4>")
	)
	(arc
		(start 145.424144 -246.429276)
		(mid 145.514401 -246.467009)
		(end 145.611342 -246.480076)
		(width 0.09525)
		(layer "In2.Cu")
		(net "M_I_CPU1_SA_DQS_DP<4>")
	)
	(arc
		(start 134.523226 -246.42953)
		(mid 134.804658 -246.353775)
		(end 135.08609 -246.42953)
		(width 0.09525)
		(layer "In2.Cu")
		(net "M_I_CPU1_SA_DQS_DP<4>")
	)
	(arc
		(start 135.46328 -246.42953)
		(mid 135.744712 -246.353775)
		(end 136.026144 -246.42953)
		(width 0.09525)
		(layer "In2.Cu")
		(net "M_I_CPU1_SA_DQS_DP<4>")
	)
	(arc
		(start 131.326128 -246.42953)
		(mid 131.509903 -246.480302)
		(end 131.694936 -246.434356)
		(width 0.09525)
		(layer "In2.Cu")
		(net "M_I_CPU1_SA_DQS_DP<4>")
	)
	(segment
		(start 129.16789 -241.510312)
		(end 129.634742 -241.244374)
		(width 0.12954)
		(layer "F.Cu")
		(net "M_I_CPU1_SA_DQS_DP<3>")
	)
	(segment
		(start 147.201128 -240.114582)
		(end 147.663154 -240.114582)
		(width 0.09525)
		(layer "In2.Cu")
		(net "M_I_CPU1_SA_DQS_DP<3>")
	)
	(segment
		(start 181.486556 -229.059994)
		(end 181.966616 -229.059994)
		(width 0.16002)
		(layer "In2.Cu")
		(net "M_I_CPU1_SA_DQS_DP<3>")
	)
	(segment
		(start 161.613088 -230.900224)
		(end 161.613088 -230.634032)
		(width 0.16002)
		(layer "In2.Cu")
		(net "M_I_CPU1_SA_DQS_DP<3>")
	)
	(segment
		(start 145.845784 -241.125248)
		(end 146.190462 -241.125248)
		(width 0.09525)
		(layer "In2.Cu")
		(net "M_I_CPU1_SA_DQS_DP<3>")
	)
	(segment
		(start 129.634742 -241.244374)
		(end 129.480818 -241.509804)
		(width 0.09525)
		(layer "In2.Cu")
		(net "M_I_CPU1_SA_DQS_DP<3>")
	)
	(segment
		(start 155.645104 -235.486956)
		(end 157.026356 -235.486956)
		(width 0.16002)
		(layer "In2.Cu")
		(net "M_I_CPU1_SA_DQS_DP<3>")
	)
	(segment
		(start 178.059588 -228.63429)
		(end 180.144928 -228.63429)
		(width 0.16002)
		(layer "In2.Cu")
		(net "M_I_CPU1_SA_DQS_DP<3>")
	)
	(segment
		(start 177.485548 -228.06025)
		(end 178.059588 -228.63429)
		(width 0.16002)
		(layer "In2.Cu")
		(net "M_I_CPU1_SA_DQS_DP<3>")
	)
	(segment
		(start 145.144744 -241.493548)
		(end 145.477484 -241.493548)
		(width 0.09525)
		(layer "In2.Cu")
		(net "M_I_CPU1_SA_DQS_DP<3>")
	)
	(segment
		(start 147.722336 -240.0554)
		(end 147.745958 -240.0554)
		(width 0.09525)
		(layer "In2.Cu")
		(net "M_I_CPU1_SA_DQS_DP<3>")
	)
	(segment
		(start 143.914876 -241.57432)
		(end 143.923258 -241.569494)
		(width 0.09525)
		(layer "In2.Cu")
		(net "M_I_CPU1_SA_DQS_DP<3>")
	)
	(segment
		(start 136.394952 -241.57432)
		(end 136.403334 -241.569494)
		(width 0.09525)
		(layer "In2.Cu")
		(net "M_I_CPU1_SA_DQS_DP<3>")
	)
	(segment
		(start 146.190462 -241.125248)
		(end 147.201128 -240.114582)
		(width 0.09525)
		(layer "In2.Cu")
		(net "M_I_CPU1_SA_DQS_DP<3>")
	)
	(segment
		(start 145.477484 -241.493548)
		(end 145.845784 -241.125248)
		(width 0.09525)
		(layer "In2.Cu")
		(net "M_I_CPU1_SA_DQS_DP<3>")
	)
	(segment
		(start 182.083456 -228.943154)
		(end 182.563516 -228.943154)
		(width 0.16002)
		(layer "In2.Cu")
		(net "M_I_CPU1_SA_DQS_DP<3>")
	)
	(segment
		(start 181.966616 -229.059994)
		(end 182.083456 -228.943154)
		(width 0.16002)
		(layer "In2.Cu")
		(net "M_I_CPU1_SA_DQS_DP<3>")
	)
	(segment
		(start 131.694936 -241.57432)
		(end 131.703318 -241.569494)
		(width 0.09525)
		(layer "In2.Cu")
		(net "M_I_CPU1_SA_DQS_DP<3>")
	)
	(segment
		(start 170.743626 -228.910134)
		(end 172.876972 -228.910134)
		(width 0.16002)
		(layer "In2.Cu")
		(net "M_I_CPU1_SA_DQS_DP<3>")
	)
	(segment
		(start 174.892208 -228.376734)
		(end 175.208692 -228.06025)
		(width 0.16002)
		(layer "In2.Cu")
		(net "M_I_CPU1_SA_DQS_DP<3>")
	)
	(segment
		(start 140.154914 -241.57432)
		(end 140.163296 -241.569494)
		(width 0.09525)
		(layer "In2.Cu")
		(net "M_I_CPU1_SA_DQS_DP<3>")
	)
	(segment
		(start 163.336986 -228.910134)
		(end 165.332918 -228.910134)
		(width 0.16002)
		(layer "In2.Cu")
		(net "M_I_CPU1_SA_DQS_DP<3>")
	)
	(segment
		(start 144.485868 -241.569494)
		(end 144.49425 -241.57432)
		(width 0.09525)
		(layer "In2.Cu")
		(net "M_I_CPU1_SA_DQS_DP<3>")
	)
	(segment
		(start 151.07666 -240.0554)
		(end 155.645104 -235.486956)
		(width 0.16002)
		(layer "In2.Cu")
		(net "M_I_CPU1_SA_DQS_DP<3>")
	)
	(segment
		(start 180.144928 -228.63429)
		(end 180.753512 -229.242874)
		(width 0.16002)
		(layer "In2.Cu")
		(net "M_I_CPU1_SA_DQS_DP<3>")
	)
	(segment
		(start 147.663154 -240.114582)
		(end 147.722336 -240.0554)
		(width 0.09525)
		(layer "In2.Cu")
		(net "M_I_CPU1_SA_DQS_DP<3>")
	)
	(segment
		(start 137.906252 -241.569494)
		(end 137.914634 -241.57432)
		(width 0.09525)
		(layer "In2.Cu")
		(net "M_I_CPU1_SA_DQS_DP<3>")
	)
	(segment
		(start 147.745958 -240.0554)
		(end 151.07666 -240.0554)
		(width 0.16002)
		(layer "In2.Cu")
		(net "M_I_CPU1_SA_DQS_DP<3>")
	)
	(segment
		(start 180.753512 -229.242874)
		(end 181.303676 -229.242874)
		(width 0.16002)
		(layer "In2.Cu")
		(net "M_I_CPU1_SA_DQS_DP<3>")
	)
	(segment
		(start 161.613088 -230.634032)
		(end 163.336986 -228.910134)
		(width 0.16002)
		(layer "In2.Cu")
		(net "M_I_CPU1_SA_DQS_DP<3>")
	)
	(segment
		(start 135.454898 -241.57432)
		(end 135.46328 -241.569494)
		(width 0.09525)
		(layer "In2.Cu")
		(net "M_I_CPU1_SA_DQS_DP<3>")
	)
	(segment
		(start 165.332918 -228.910134)
		(end 165.640258 -229.217474)
		(width 0.16002)
		(layer "In2.Cu")
		(net "M_I_CPU1_SA_DQS_DP<3>")
	)
	(segment
		(start 182.563516 -228.943154)
		(end 182.680356 -229.059994)
		(width 0.16002)
		(layer "In2.Cu")
		(net "M_I_CPU1_SA_DQS_DP<3>")
	)
	(segment
		(start 133.206236 -241.569494)
		(end 133.214618 -241.57432)
		(width 0.09525)
		(layer "In2.Cu")
		(net "M_I_CPU1_SA_DQS_DP<3>")
	)
	(segment
		(start 173.184312 -229.217474)
		(end 173.526196 -229.217474)
		(width 0.16002)
		(layer "In2.Cu")
		(net "M_I_CPU1_SA_DQS_DP<3>")
	)
	(segment
		(start 136.966198 -241.569494)
		(end 136.97458 -241.57432)
		(width 0.09525)
		(layer "In2.Cu")
		(net "M_I_CPU1_SA_DQS_DP<3>")
	)
	(segment
		(start 129.480818 -241.509804)
		(end 129.503932 -241.596418)
		(width 0.09525)
		(layer "In2.Cu")
		(net "M_I_CPU1_SA_DQS_DP<3>")
	)
	(segment
		(start 172.876972 -228.910134)
		(end 173.184312 -229.217474)
		(width 0.16002)
		(layer "In2.Cu")
		(net "M_I_CPU1_SA_DQS_DP<3>")
	)
	(segment
		(start 181.303676 -229.242874)
		(end 181.486556 -229.059994)
		(width 0.16002)
		(layer "In2.Cu")
		(net "M_I_CPU1_SA_DQS_DP<3>")
	)
	(segment
		(start 132.266182 -241.569494)
		(end 132.274564 -241.57432)
		(width 0.09525)
		(layer "In2.Cu")
		(net "M_I_CPU1_SA_DQS_DP<3>")
	)
	(segment
		(start 166.822882 -228.376734)
		(end 167.348154 -228.376734)
		(width 0.16002)
		(layer "In2.Cu")
		(net "M_I_CPU1_SA_DQS_DP<3>")
	)
	(segment
		(start 175.208692 -228.06025)
		(end 177.485548 -228.06025)
		(width 0.16002)
		(layer "In2.Cu")
		(net "M_I_CPU1_SA_DQS_DP<3>")
	)
	(segment
		(start 157.026356 -235.486956)
		(end 161.613088 -230.900224)
		(width 0.16002)
		(layer "In2.Cu")
		(net "M_I_CPU1_SA_DQS_DP<3>")
	)
	(segment
		(start 174.366936 -228.376734)
		(end 174.892208 -228.376734)
		(width 0.16002)
		(layer "In2.Cu")
		(net "M_I_CPU1_SA_DQS_DP<3>")
	)
	(segment
		(start 141.666214 -241.569494)
		(end 141.674596 -241.57432)
		(width 0.09525)
		(layer "In2.Cu")
		(net "M_I_CPU1_SA_DQS_DP<3>")
	)
	(segment
		(start 182.680356 -229.059994)
		(end 183.341518 -229.059994)
		(width 0.16002)
		(layer "In2.Cu")
		(net "M_I_CPU1_SA_DQS_DP<3>")
	)
	(segment
		(start 167.664638 -228.06025)
		(end 169.893742 -228.06025)
		(width 0.16002)
		(layer "In2.Cu")
		(net "M_I_CPU1_SA_DQS_DP<3>")
	)
	(segment
		(start 167.348154 -228.376734)
		(end 167.664638 -228.06025)
		(width 0.16002)
		(layer "In2.Cu")
		(net "M_I_CPU1_SA_DQS_DP<3>")
	)
	(segment
		(start 130.754882 -241.57432)
		(end 130.763264 -241.569494)
		(width 0.09525)
		(layer "In2.Cu")
		(net "M_I_CPU1_SA_DQS_DP<3>")
	)
	(segment
		(start 165.640258 -229.217474)
		(end 165.982142 -229.217474)
		(width 0.16002)
		(layer "In2.Cu")
		(net "M_I_CPU1_SA_DQS_DP<3>")
	)
	(segment
		(start 169.893742 -228.06025)
		(end 170.743626 -228.910134)
		(width 0.16002)
		(layer "In2.Cu")
		(net "M_I_CPU1_SA_DQS_DP<3>")
	)
	(segment
		(start 173.526196 -229.217474)
		(end 174.366936 -228.376734)
		(width 0.16002)
		(layer "In2.Cu")
		(net "M_I_CPU1_SA_DQS_DP<3>")
	)
	(segment
		(start 183.341518 -229.059994)
		(end 183.616092 -228.78542)
		(width 0.16002)
		(layer "In2.Cu")
		(net "M_I_CPU1_SA_DQS_DP<3>")
	)
	(segment
		(start 143.923258 -241.569494)
		(end 143.933672 -241.563398)
		(width 0.09525)
		(layer "In2.Cu")
		(net "M_I_CPU1_SA_DQS_DP<3>")
	)
	(segment
		(start 165.982142 -229.217474)
		(end 166.822882 -228.376734)
		(width 0.16002)
		(layer "In2.Cu")
		(net "M_I_CPU1_SA_DQS_DP<3>")
	)
	(segment
		(start 141.094968 -241.57432)
		(end 141.10335 -241.569494)
		(width 0.09525)
		(layer "In2.Cu")
		(net "M_I_CPU1_SA_DQS_DP<3>")
	)
	(arc
		(start 140.163296 -241.569494)
		(mid 140.444728 -241.493739)
		(end 140.72616 -241.569494)
		(width 0.09525)
		(layer "In2.Cu")
		(net "M_I_CPU1_SA_DQS_DP<3>")
	)
	(arc
		(start 140.72616 -241.569494)
		(mid 140.909935 -241.620266)
		(end 141.094968 -241.57432)
		(width 0.09525)
		(layer "In2.Cu")
		(net "M_I_CPU1_SA_DQS_DP<3>")
	)
	(arc
		(start 131.703318 -241.569494)
		(mid 131.98475 -241.493739)
		(end 132.266182 -241.569494)
		(width 0.09525)
		(layer "In2.Cu")
		(net "M_I_CPU1_SA_DQS_DP<3>")
	)
	(arc
		(start 136.403334 -241.569494)
		(mid 136.684766 -241.493739)
		(end 136.966198 -241.569494)
		(width 0.09525)
		(layer "In2.Cu")
		(net "M_I_CPU1_SA_DQS_DP<3>")
	)
	(arc
		(start 138.283442 -241.569494)
		(mid 138.564874 -241.493739)
		(end 138.846306 -241.569494)
		(width 0.09525)
		(layer "In2.Cu")
		(net "M_I_CPU1_SA_DQS_DP<3>")
	)
	(arc
		(start 136.97458 -241.57432)
		(mid 137.159612 -241.620234)
		(end 137.343388 -241.569494)
		(width 0.09525)
		(layer "In2.Cu")
		(net "M_I_CPU1_SA_DQS_DP<3>")
	)
	(arc
		(start 135.08609 -241.569494)
		(mid 135.269865 -241.620266)
		(end 135.454898 -241.57432)
		(width 0.09525)
		(layer "In2.Cu")
		(net "M_I_CPU1_SA_DQS_DP<3>")
	)
	(arc
		(start 132.643372 -241.569494)
		(mid 132.924804 -241.493739)
		(end 133.206236 -241.569494)
		(width 0.09525)
		(layer "In2.Cu")
		(net "M_I_CPU1_SA_DQS_DP<3>")
	)
	(arc
		(start 135.46328 -241.569494)
		(mid 135.744712 -241.493739)
		(end 136.026144 -241.569494)
		(width 0.09525)
		(layer "In2.Cu")
		(net "M_I_CPU1_SA_DQS_DP<3>")
	)
	(arc
		(start 136.026144 -241.569494)
		(mid 136.209919 -241.620266)
		(end 136.394952 -241.57432)
		(width 0.09525)
		(layer "In2.Cu")
		(net "M_I_CPU1_SA_DQS_DP<3>")
	)
	(arc
		(start 139.223242 -241.569494)
		(mid 139.504674 -241.493739)
		(end 139.786106 -241.569494)
		(width 0.09525)
		(layer "In2.Cu")
		(net "M_I_CPU1_SA_DQS_DP<3>")
	)
	(arc
		(start 138.846306 -241.569494)
		(mid 139.034774 -241.620171)
		(end 139.223242 -241.569494)
		(width 0.09525)
		(layer "In2.Cu")
		(net "M_I_CPU1_SA_DQS_DP<3>")
	)
	(arc
		(start 134.14629 -241.569494)
		(mid 134.334758 -241.620171)
		(end 134.523226 -241.569494)
		(width 0.09525)
		(layer "In2.Cu")
		(net "M_I_CPU1_SA_DQS_DP<3>")
	)
	(arc
		(start 142.606268 -241.569494)
		(mid 142.794736 -241.620171)
		(end 142.983204 -241.569494)
		(width 0.09525)
		(layer "In2.Cu")
		(net "M_I_CPU1_SA_DQS_DP<3>")
	)
	(arc
		(start 137.343388 -241.569494)
		(mid 137.62482 -241.493739)
		(end 137.906252 -241.569494)
		(width 0.09525)
		(layer "In2.Cu")
		(net "M_I_CPU1_SA_DQS_DP<3>")
	)
	(arc
		(start 133.583426 -241.569494)
		(mid 133.864858 -241.493739)
		(end 134.14629 -241.569494)
		(width 0.09525)
		(layer "In2.Cu")
		(net "M_I_CPU1_SA_DQS_DP<3>")
	)
	(arc
		(start 142.983204 -241.569494)
		(mid 143.264636 -241.493739)
		(end 143.546068 -241.569494)
		(width 0.09525)
		(layer "In2.Cu")
		(net "M_I_CPU1_SA_DQS_DP<3>")
	)
	(arc
		(start 141.674596 -241.57432)
		(mid 141.859628 -241.620234)
		(end 142.043404 -241.569494)
		(width 0.09525)
		(layer "In2.Cu")
		(net "M_I_CPU1_SA_DQS_DP<3>")
	)
	(arc
		(start 143.933672 -241.563398)
		(mid 144.21058 -241.493721)
		(end 144.485868 -241.569494)
		(width 0.09525)
		(layer "In2.Cu")
		(net "M_I_CPU1_SA_DQS_DP<3>")
	)
	(arc
		(start 141.10335 -241.569494)
		(mid 141.384782 -241.493739)
		(end 141.666214 -241.569494)
		(width 0.09525)
		(layer "In2.Cu")
		(net "M_I_CPU1_SA_DQS_DP<3>")
	)
	(arc
		(start 131.326128 -241.569494)
		(mid 131.509903 -241.620266)
		(end 131.694936 -241.57432)
		(width 0.09525)
		(layer "In2.Cu")
		(net "M_I_CPU1_SA_DQS_DP<3>")
	)
	(arc
		(start 132.274564 -241.57432)
		(mid 132.459596 -241.620234)
		(end 132.643372 -241.569494)
		(width 0.09525)
		(layer "In2.Cu")
		(net "M_I_CPU1_SA_DQS_DP<3>")
	)
	(arc
		(start 143.546068 -241.569494)
		(mid 143.729843 -241.620266)
		(end 143.914876 -241.57432)
		(width 0.09525)
		(layer "In2.Cu")
		(net "M_I_CPU1_SA_DQS_DP<3>")
	)
	(arc
		(start 133.214618 -241.57432)
		(mid 133.39965 -241.620234)
		(end 133.583426 -241.569494)
		(width 0.09525)
		(layer "In2.Cu")
		(net "M_I_CPU1_SA_DQS_DP<3>")
	)
	(arc
		(start 134.523226 -241.569494)
		(mid 134.804658 -241.493739)
		(end 135.08609 -241.569494)
		(width 0.09525)
		(layer "In2.Cu")
		(net "M_I_CPU1_SA_DQS_DP<3>")
	)
	(arc
		(start 130.763264 -241.569494)
		(mid 131.044696 -241.493739)
		(end 131.326128 -241.569494)
		(width 0.09525)
		(layer "In2.Cu")
		(net "M_I_CPU1_SA_DQS_DP<3>")
	)
	(arc
		(start 139.786106 -241.569494)
		(mid 139.969881 -241.620266)
		(end 140.154914 -241.57432)
		(width 0.09525)
		(layer "In2.Cu")
		(net "M_I_CPU1_SA_DQS_DP<3>")
	)
	(arc
		(start 144.49425 -241.57432)
		(mid 144.679282 -241.620234)
		(end 144.863058 -241.569494)
		(width 0.09525)
		(layer "In2.Cu")
		(net "M_I_CPU1_SA_DQS_DP<3>")
	)
	(arc
		(start 129.503932 -241.596418)
		(mid 129.666583 -241.618678)
		(end 129.82321 -241.569494)
		(width 0.09525)
		(layer "In2.Cu")
		(net "M_I_CPU1_SA_DQS_DP<3>")
	)
	(arc
		(start 137.914634 -241.57432)
		(mid 138.099666 -241.620234)
		(end 138.283442 -241.569494)
		(width 0.09525)
		(layer "In2.Cu")
		(net "M_I_CPU1_SA_DQS_DP<3>")
	)
	(arc
		(start 129.82321 -241.569494)
		(mid 130.104642 -241.493739)
		(end 130.386074 -241.569494)
		(width 0.09525)
		(layer "In2.Cu")
		(net "M_I_CPU1_SA_DQS_DP<3>")
	)
	(arc
		(start 144.863058 -241.569494)
		(mid 144.99888 -241.512914)
		(end 145.144744 -241.493548)
		(width 0.09525)
		(layer "In2.Cu")
		(net "M_I_CPU1_SA_DQS_DP<3>")
	)
	(arc
		(start 130.386074 -241.569494)
		(mid 130.569849 -241.620266)
		(end 130.754882 -241.57432)
		(width 0.09525)
		(layer "In2.Cu")
		(net "M_I_CPU1_SA_DQS_DP<3>")
	)
	(arc
		(start 142.043404 -241.569494)
		(mid 142.324836 -241.493739)
		(end 142.606268 -241.569494)
		(width 0.09525)
		(layer "In2.Cu")
		(net "M_I_CPU1_SA_DQS_DP<3>")
	)
	(segment
		(start 129.16789 -236.650276)
		(end 129.634742 -236.384338)
		(width 0.12954)
		(layer "F.Cu")
		(net "M_I_CPU1_SA_DQS_DP<2>")
	)
	(segment
		(start 165.982142 -219.86748)
		(end 166.822882 -219.02674)
		(width 0.16002)
		(layer "In2.Cu")
		(net "M_I_CPU1_SA_DQS_DP<2>")
	)
	(segment
		(start 181.955948 -219.71)
		(end 183.341518 -219.71)
		(width 0.16002)
		(layer "In2.Cu")
		(net "M_I_CPU1_SA_DQS_DP<2>")
	)
	(segment
		(start 145.60804 -236.031024)
		(end 146.093688 -235.545376)
		(width 0.09525)
		(layer "In2.Cu")
		(net "M_I_CPU1_SA_DQS_DP<2>")
	)
	(segment
		(start 162.330892 -219.56014)
		(end 165.332918 -219.56014)
		(width 0.16002)
		(layer "In2.Cu")
		(net "M_I_CPU1_SA_DQS_DP<2>")
	)
	(segment
		(start 174.366936 -219.02674)
		(end 174.892208 -219.02674)
		(width 0.16002)
		(layer "In2.Cu")
		(net "M_I_CPU1_SA_DQS_DP<2>")
	)
	(segment
		(start 180.144928 -219.284296)
		(end 180.753512 -219.89288)
		(width 0.16002)
		(layer "In2.Cu")
		(net "M_I_CPU1_SA_DQS_DP<2>")
	)
	(segment
		(start 140.154914 -236.714284)
		(end 140.163296 -236.709458)
		(width 0.09525)
		(layer "In2.Cu")
		(net "M_I_CPU1_SA_DQS_DP<2>")
	)
	(segment
		(start 173.526196 -219.86748)
		(end 174.366936 -219.02674)
		(width 0.16002)
		(layer "In2.Cu")
		(net "M_I_CPU1_SA_DQS_DP<2>")
	)
	(segment
		(start 177.485548 -218.710256)
		(end 178.059588 -219.284296)
		(width 0.16002)
		(layer "In2.Cu")
		(net "M_I_CPU1_SA_DQS_DP<2>")
	)
	(segment
		(start 178.059588 -219.284296)
		(end 180.144928 -219.284296)
		(width 0.16002)
		(layer "In2.Cu")
		(net "M_I_CPU1_SA_DQS_DP<2>")
	)
	(segment
		(start 170.743626 -219.56014)
		(end 172.876972 -219.56014)
		(width 0.16002)
		(layer "In2.Cu")
		(net "M_I_CPU1_SA_DQS_DP<2>")
	)
	(segment
		(start 129.634742 -236.384338)
		(end 129.480818 -236.649768)
		(width 0.09525)
		(layer "In2.Cu")
		(net "M_I_CPU1_SA_DQS_DP<2>")
	)
	(segment
		(start 144.61998 -236.031024)
		(end 145.60804 -236.031024)
		(width 0.09525)
		(layer "In2.Cu")
		(net "M_I_CPU1_SA_DQS_DP<2>")
	)
	(segment
		(start 129.480818 -236.649768)
		(end 129.503932 -236.736382)
		(width 0.09525)
		(layer "In2.Cu")
		(net "M_I_CPU1_SA_DQS_DP<2>")
	)
	(segment
		(start 172.876972 -219.56014)
		(end 173.184312 -219.86748)
		(width 0.16002)
		(layer "In2.Cu")
		(net "M_I_CPU1_SA_DQS_DP<2>")
	)
	(segment
		(start 131.694936 -236.714284)
		(end 131.703318 -236.709458)
		(width 0.09525)
		(layer "In2.Cu")
		(net "M_I_CPU1_SA_DQS_DP<2>")
	)
	(segment
		(start 136.394952 -236.714284)
		(end 136.403334 -236.709458)
		(width 0.09525)
		(layer "In2.Cu")
		(net "M_I_CPU1_SA_DQS_DP<2>")
	)
	(segment
		(start 180.753512 -219.89288)
		(end 181.773068 -219.89288)
		(width 0.16002)
		(layer "In2.Cu")
		(net "M_I_CPU1_SA_DQS_DP<2>")
	)
	(segment
		(start 167.348154 -219.02674)
		(end 167.664638 -218.710256)
		(width 0.16002)
		(layer "In2.Cu")
		(net "M_I_CPU1_SA_DQS_DP<2>")
	)
	(segment
		(start 165.640258 -219.86748)
		(end 165.982142 -219.86748)
		(width 0.16002)
		(layer "In2.Cu")
		(net "M_I_CPU1_SA_DQS_DP<2>")
	)
	(segment
		(start 144.000474 -236.650022)
		(end 144.000474 -236.650276)
		(width 0.09525)
		(layer "In2.Cu")
		(net "M_I_CPU1_SA_DQS_DP<2>")
	)
	(segment
		(start 132.266182 -236.709458)
		(end 132.274564 -236.714284)
		(width 0.09525)
		(layer "In2.Cu")
		(net "M_I_CPU1_SA_DQS_DP<2>")
	)
	(segment
		(start 169.893742 -218.710256)
		(end 170.743626 -219.56014)
		(width 0.16002)
		(layer "In2.Cu")
		(net "M_I_CPU1_SA_DQS_DP<2>")
	)
	(segment
		(start 183.341518 -219.71)
		(end 183.616092 -219.435426)
		(width 0.16002)
		(layer "In2.Cu")
		(net "M_I_CPU1_SA_DQS_DP<2>")
	)
	(segment
		(start 146.093688 -234.816396)
		(end 146.463512 -234.446572)
		(width 0.09525)
		(layer "In2.Cu")
		(net "M_I_CPU1_SA_DQS_DP<2>")
	)
	(segment
		(start 167.664638 -218.710256)
		(end 169.893742 -218.710256)
		(width 0.16002)
		(layer "In2.Cu")
		(net "M_I_CPU1_SA_DQS_DP<2>")
	)
	(segment
		(start 141.666214 -236.709458)
		(end 141.674596 -236.714284)
		(width 0.09525)
		(layer "In2.Cu")
		(net "M_I_CPU1_SA_DQS_DP<2>")
	)
	(segment
		(start 135.454898 -236.714284)
		(end 135.46328 -236.709458)
		(width 0.09525)
		(layer "In2.Cu")
		(net "M_I_CPU1_SA_DQS_DP<2>")
	)
	(segment
		(start 130.754882 -236.714284)
		(end 130.763264 -236.709458)
		(width 0.09525)
		(layer "In2.Cu")
		(net "M_I_CPU1_SA_DQS_DP<2>")
	)
	(segment
		(start 147.705318 -234.185714)
		(end 162.330892 -219.56014)
		(width 0.16002)
		(layer "In2.Cu")
		(net "M_I_CPU1_SA_DQS_DP<2>")
	)
	(segment
		(start 144.438624 -236.21238)
		(end 144.61998 -236.031024)
		(width 0.09525)
		(layer "In2.Cu")
		(net "M_I_CPU1_SA_DQS_DP<2>")
	)
	(segment
		(start 137.906252 -236.709458)
		(end 137.914634 -236.714284)
		(width 0.09525)
		(layer "In2.Cu")
		(net "M_I_CPU1_SA_DQS_DP<2>")
	)
	(segment
		(start 136.966198 -236.709458)
		(end 136.97458 -236.714284)
		(width 0.09525)
		(layer "In2.Cu")
		(net "M_I_CPU1_SA_DQS_DP<2>")
	)
	(segment
		(start 133.206236 -236.709458)
		(end 133.214618 -236.714284)
		(width 0.09525)
		(layer "In2.Cu")
		(net "M_I_CPU1_SA_DQS_DP<2>")
	)
	(segment
		(start 146.463512 -234.446572)
		(end 147.52828 -234.446572)
		(width 0.09525)
		(layer "In2.Cu")
		(net "M_I_CPU1_SA_DQS_DP<2>")
	)
	(segment
		(start 147.688554 -234.286298)
		(end 147.688554 -234.202478)
		(width 0.09525)
		(layer "In2.Cu")
		(net "M_I_CPU1_SA_DQS_DP<2>")
	)
	(segment
		(start 147.688554 -234.202478)
		(end 147.705318 -234.185714)
		(width 0.09525)
		(layer "In2.Cu")
		(net "M_I_CPU1_SA_DQS_DP<2>")
	)
	(segment
		(start 144.000474 -236.650276)
		(end 144.438624 -236.21238)
		(width 0.09525)
		(layer "In2.Cu")
		(net "M_I_CPU1_SA_DQS_DP<2>")
	)
	(segment
		(start 146.093688 -235.545376)
		(end 146.093688 -234.816396)
		(width 0.09525)
		(layer "In2.Cu")
		(net "M_I_CPU1_SA_DQS_DP<2>")
	)
	(segment
		(start 147.52828 -234.446572)
		(end 147.688554 -234.286298)
		(width 0.09525)
		(layer "In2.Cu")
		(net "M_I_CPU1_SA_DQS_DP<2>")
	)
	(segment
		(start 141.094968 -236.714284)
		(end 141.10335 -236.709458)
		(width 0.09525)
		(layer "In2.Cu")
		(net "M_I_CPU1_SA_DQS_DP<2>")
	)
	(segment
		(start 173.184312 -219.86748)
		(end 173.526196 -219.86748)
		(width 0.16002)
		(layer "In2.Cu")
		(net "M_I_CPU1_SA_DQS_DP<2>")
	)
	(segment
		(start 166.822882 -219.02674)
		(end 167.348154 -219.02674)
		(width 0.16002)
		(layer "In2.Cu")
		(net "M_I_CPU1_SA_DQS_DP<2>")
	)
	(segment
		(start 181.773068 -219.89288)
		(end 181.955948 -219.71)
		(width 0.16002)
		(layer "In2.Cu")
		(net "M_I_CPU1_SA_DQS_DP<2>")
	)
	(segment
		(start 174.892208 -219.02674)
		(end 175.208692 -218.710256)
		(width 0.16002)
		(layer "In2.Cu")
		(net "M_I_CPU1_SA_DQS_DP<2>")
	)
	(segment
		(start 175.208692 -218.710256)
		(end 177.485548 -218.710256)
		(width 0.16002)
		(layer "In2.Cu")
		(net "M_I_CPU1_SA_DQS_DP<2>")
	)
	(segment
		(start 165.332918 -219.56014)
		(end 165.640258 -219.86748)
		(width 0.16002)
		(layer "In2.Cu")
		(net "M_I_CPU1_SA_DQS_DP<2>")
	)
	(arc
		(start 135.08609 -236.709458)
		(mid 135.269865 -236.76023)
		(end 135.454898 -236.714284)
		(width 0.09525)
		(layer "In2.Cu")
		(net "M_I_CPU1_SA_DQS_DP<2>")
	)
	(arc
		(start 142.043404 -236.709458)
		(mid 142.324836 -236.633703)
		(end 142.606268 -236.709458)
		(width 0.09525)
		(layer "In2.Cu")
		(net "M_I_CPU1_SA_DQS_DP<2>")
	)
	(arc
		(start 131.703318 -236.709458)
		(mid 131.98475 -236.633703)
		(end 132.266182 -236.709458)
		(width 0.09525)
		(layer "In2.Cu")
		(net "M_I_CPU1_SA_DQS_DP<2>")
	)
	(arc
		(start 140.72616 -236.709458)
		(mid 140.909935 -236.76023)
		(end 141.094968 -236.714284)
		(width 0.09525)
		(layer "In2.Cu")
		(net "M_I_CPU1_SA_DQS_DP<2>")
	)
	(arc
		(start 137.914634 -236.714284)
		(mid 138.099666 -236.760198)
		(end 138.283442 -236.709458)
		(width 0.09525)
		(layer "In2.Cu")
		(net "M_I_CPU1_SA_DQS_DP<2>")
	)
	(arc
		(start 141.10335 -236.709458)
		(mid 141.384782 -236.633703)
		(end 141.666214 -236.709458)
		(width 0.09525)
		(layer "In2.Cu")
		(net "M_I_CPU1_SA_DQS_DP<2>")
	)
	(arc
		(start 134.523226 -236.709458)
		(mid 134.804658 -236.633703)
		(end 135.08609 -236.709458)
		(width 0.09525)
		(layer "In2.Cu")
		(net "M_I_CPU1_SA_DQS_DP<2>")
	)
	(arc
		(start 138.846306 -236.709458)
		(mid 139.034774 -236.760135)
		(end 139.223242 -236.709458)
		(width 0.09525)
		(layer "In2.Cu")
		(net "M_I_CPU1_SA_DQS_DP<2>")
	)
	(arc
		(start 142.606268 -236.709458)
		(mid 142.794736 -236.760135)
		(end 142.983204 -236.709458)
		(width 0.09525)
		(layer "In2.Cu")
		(net "M_I_CPU1_SA_DQS_DP<2>")
	)
	(arc
		(start 143.546068 -236.709458)
		(mid 143.78335 -236.756951)
		(end 144.000474 -236.650022)
		(width 0.09525)
		(layer "In2.Cu")
		(net "M_I_CPU1_SA_DQS_DP<2>")
	)
	(arc
		(start 133.583426 -236.709458)
		(mid 133.864858 -236.633703)
		(end 134.14629 -236.709458)
		(width 0.09525)
		(layer "In2.Cu")
		(net "M_I_CPU1_SA_DQS_DP<2>")
	)
	(arc
		(start 129.82321 -236.709458)
		(mid 130.104642 -236.633703)
		(end 130.386074 -236.709458)
		(width 0.09525)
		(layer "In2.Cu")
		(net "M_I_CPU1_SA_DQS_DP<2>")
	)
	(arc
		(start 133.214618 -236.714284)
		(mid 133.39965 -236.760198)
		(end 133.583426 -236.709458)
		(width 0.09525)
		(layer "In2.Cu")
		(net "M_I_CPU1_SA_DQS_DP<2>")
	)
	(arc
		(start 129.503932 -236.736382)
		(mid 129.666583 -236.758642)
		(end 129.82321 -236.709458)
		(width 0.09525)
		(layer "In2.Cu")
		(net "M_I_CPU1_SA_DQS_DP<2>")
	)
	(arc
		(start 130.386074 -236.709458)
		(mid 130.569849 -236.76023)
		(end 130.754882 -236.714284)
		(width 0.09525)
		(layer "In2.Cu")
		(net "M_I_CPU1_SA_DQS_DP<2>")
	)
	(arc
		(start 142.983204 -236.709458)
		(mid 143.264636 -236.633703)
		(end 143.546068 -236.709458)
		(width 0.09525)
		(layer "In2.Cu")
		(net "M_I_CPU1_SA_DQS_DP<2>")
	)
	(arc
		(start 139.223242 -236.709458)
		(mid 139.504674 -236.633703)
		(end 139.786106 -236.709458)
		(width 0.09525)
		(layer "In2.Cu")
		(net "M_I_CPU1_SA_DQS_DP<2>")
	)
	(arc
		(start 141.674596 -236.714284)
		(mid 141.859628 -236.760198)
		(end 142.043404 -236.709458)
		(width 0.09525)
		(layer "In2.Cu")
		(net "M_I_CPU1_SA_DQS_DP<2>")
	)
	(arc
		(start 135.46328 -236.709458)
		(mid 135.744712 -236.633703)
		(end 136.026144 -236.709458)
		(width 0.09525)
		(layer "In2.Cu")
		(net "M_I_CPU1_SA_DQS_DP<2>")
	)
	(arc
		(start 136.026144 -236.709458)
		(mid 136.209919 -236.76023)
		(end 136.394952 -236.714284)
		(width 0.09525)
		(layer "In2.Cu")
		(net "M_I_CPU1_SA_DQS_DP<2>")
	)
	(arc
		(start 136.97458 -236.714284)
		(mid 137.159612 -236.760198)
		(end 137.343388 -236.709458)
		(width 0.09525)
		(layer "In2.Cu")
		(net "M_I_CPU1_SA_DQS_DP<2>")
	)
	(arc
		(start 130.763264 -236.709458)
		(mid 131.044696 -236.633703)
		(end 131.326128 -236.709458)
		(width 0.09525)
		(layer "In2.Cu")
		(net "M_I_CPU1_SA_DQS_DP<2>")
	)
	(arc
		(start 140.163296 -236.709458)
		(mid 140.444728 -236.633703)
		(end 140.72616 -236.709458)
		(width 0.09525)
		(layer "In2.Cu")
		(net "M_I_CPU1_SA_DQS_DP<2>")
	)
	(arc
		(start 136.403334 -236.709458)
		(mid 136.684766 -236.633703)
		(end 136.966198 -236.709458)
		(width 0.09525)
		(layer "In2.Cu")
		(net "M_I_CPU1_SA_DQS_DP<2>")
	)
	(arc
		(start 138.283442 -236.709458)
		(mid 138.564874 -236.633703)
		(end 138.846306 -236.709458)
		(width 0.09525)
		(layer "In2.Cu")
		(net "M_I_CPU1_SA_DQS_DP<2>")
	)
	(arc
		(start 139.786106 -236.709458)
		(mid 139.969881 -236.76023)
		(end 140.154914 -236.714284)
		(width 0.09525)
		(layer "In2.Cu")
		(net "M_I_CPU1_SA_DQS_DP<2>")
	)
	(arc
		(start 132.643372 -236.709458)
		(mid 132.924804 -236.633703)
		(end 133.206236 -236.709458)
		(width 0.09525)
		(layer "In2.Cu")
		(net "M_I_CPU1_SA_DQS_DP<2>")
	)
	(arc
		(start 132.274564 -236.714284)
		(mid 132.459596 -236.760198)
		(end 132.643372 -236.709458)
		(width 0.09525)
		(layer "In2.Cu")
		(net "M_I_CPU1_SA_DQS_DP<2>")
	)
	(arc
		(start 137.343388 -236.709458)
		(mid 137.62482 -236.633703)
		(end 137.906252 -236.709458)
		(width 0.09525)
		(layer "In2.Cu")
		(net "M_I_CPU1_SA_DQS_DP<2>")
	)
	(arc
		(start 134.14629 -236.709458)
		(mid 134.334758 -236.760135)
		(end 134.523226 -236.709458)
		(width 0.09525)
		(layer "In2.Cu")
		(net "M_I_CPU1_SA_DQS_DP<2>")
	)
	(arc
		(start 131.326128 -236.709458)
		(mid 131.509903 -236.76023)
		(end 131.694936 -236.714284)
		(width 0.09525)
		(layer "In2.Cu")
		(net "M_I_CPU1_SA_DQS_DP<2>")
	)
	(segment
		(start 129.16789 -231.79024)
		(end 129.634742 -231.524302)
		(width 0.12954)
		(layer "F.Cu")
		(net "M_I_CPU1_SA_DQS_DP<1>")
	)
	(segment
		(start 143.923258 -230.22941)
		(end 143.95577 -230.210614)
		(width 0.09525)
		(layer "In2.Cu")
		(net "M_I_CPU1_SA_DQS_DP<1>")
	)
	(segment
		(start 142.983204 -231.849422)
		(end 143.015716 -231.830626)
		(width 0.09525)
		(layer "In2.Cu")
		(net "M_I_CPU1_SA_DQS_DP<1>")
	)
	(segment
		(start 143.412972 -231.063292)
		(end 143.453358 -231.03967)
		(width 0.09525)
		(layer "In2.Cu")
		(net "M_I_CPU1_SA_DQS_DP<1>")
	)
	(segment
		(start 175.208692 -209.360262)
		(end 177.513488 -209.360262)
		(width 0.16002)
		(layer "In2.Cu")
		(net "M_I_CPU1_SA_DQS_DP<1>")
	)
	(segment
		(start 165.332918 -210.210146)
		(end 165.640258 -210.517486)
		(width 0.16002)
		(layer "In2.Cu")
		(net "M_I_CPU1_SA_DQS_DP<1>")
	)
	(segment
		(start 155.695142 -214.943436)
		(end 160.428432 -210.210146)
		(width 0.16002)
		(layer "In2.Cu")
		(net "M_I_CPU1_SA_DQS_DP<1>")
	)
	(segment
		(start 144.825212 -228.63175)
		(end 144.863312 -228.609652)
		(width 0.09525)
		(layer "In2.Cu")
		(net "M_I_CPU1_SA_DQS_DP<1>")
	)
	(segment
		(start 141.094968 -231.854248)
		(end 141.10335 -231.849422)
		(width 0.09525)
		(layer "In2.Cu")
		(net "M_I_CPU1_SA_DQS_DP<1>")
	)
	(segment
		(start 146.934682 -225.793046)
		(end 146.934682 -225.709226)
		(width 0.09525)
		(layer "In2.Cu")
		(net "M_I_CPU1_SA_DQS_DP<1>")
	)
	(segment
		(start 145.96999 -226.458526)
		(end 146.32432 -226.104196)
		(width 0.09525)
		(layer "In2.Cu")
		(net "M_I_CPU1_SA_DQS_DP<1>")
	)
	(segment
		(start 135.454898 -231.854248)
		(end 135.46328 -231.849422)
		(width 0.09525)
		(layer "In2.Cu")
		(net "M_I_CPU1_SA_DQS_DP<1>")
	)
	(segment
		(start 131.694936 -231.854248)
		(end 131.703318 -231.849422)
		(width 0.09525)
		(layer "In2.Cu")
		(net "M_I_CPU1_SA_DQS_DP<1>")
	)
	(segment
		(start 177.513488 -209.360262)
		(end 178.087528 -209.934302)
		(width 0.16002)
		(layer "In2.Cu")
		(net "M_I_CPU1_SA_DQS_DP<1>")
	)
	(segment
		(start 167.664638 -209.360262)
		(end 169.893742 -209.360262)
		(width 0.16002)
		(layer "In2.Cu")
		(net "M_I_CPU1_SA_DQS_DP<1>")
	)
	(segment
		(start 144.393412 -229.419658)
		(end 144.424908 -229.40137)
		(width 0.09525)
		(layer "In2.Cu")
		(net "M_I_CPU1_SA_DQS_DP<1>")
	)
	(segment
		(start 144.353026 -229.44328)
		(end 144.393412 -229.419658)
		(width 0.09525)
		(layer "In2.Cu")
		(net "M_I_CPU1_SA_DQS_DP<1>")
	)
	(segment
		(start 155.695142 -216.434924)
		(end 155.695142 -214.943436)
		(width 0.16002)
		(layer "In2.Cu")
		(net "M_I_CPU1_SA_DQS_DP<1>")
	)
	(segment
		(start 145.803112 -226.989386)
		(end 145.885662 -226.941634)
		(width 0.09525)
		(layer "In2.Cu")
		(net "M_I_CPU1_SA_DQS_DP<1>")
	)
	(segment
		(start 130.754882 -231.854248)
		(end 130.763264 -231.849422)
		(width 0.09525)
		(layer "In2.Cu")
		(net "M_I_CPU1_SA_DQS_DP<1>")
	)
	(segment
		(start 147.36445 -225.279204)
		(end 147.36445 -224.765616)
		(width 0.16002)
		(layer "In2.Cu")
		(net "M_I_CPU1_SA_DQS_DP<1>")
	)
	(segment
		(start 173.184312 -210.517486)
		(end 173.526196 -210.517486)
		(width 0.16002)
		(layer "In2.Cu")
		(net "M_I_CPU1_SA_DQS_DP<1>")
	)
	(segment
		(start 178.087528 -209.934302)
		(end 180.144928 -209.934302)
		(width 0.16002)
		(layer "In2.Cu")
		(net "M_I_CPU1_SA_DQS_DP<1>")
	)
	(segment
		(start 145.96999 -226.857306)
		(end 145.96999 -226.458526)
		(width 0.09525)
		(layer "In2.Cu")
		(net "M_I_CPU1_SA_DQS_DP<1>")
	)
	(segment
		(start 137.906252 -231.849422)
		(end 137.914634 -231.854248)
		(width 0.09525)
		(layer "In2.Cu")
		(net "M_I_CPU1_SA_DQS_DP<1>")
	)
	(segment
		(start 173.526196 -210.517486)
		(end 174.366936 -209.676746)
		(width 0.16002)
		(layer "In2.Cu")
		(net "M_I_CPU1_SA_DQS_DP<1>")
	)
	(segment
		(start 146.951446 -225.692462)
		(end 147.36445 -225.279204)
		(width 0.16002)
		(layer "In2.Cu")
		(net "M_I_CPU1_SA_DQS_DP<1>")
	)
	(segment
		(start 147.36445 -224.765616)
		(end 155.695142 -216.434924)
		(width 0.16002)
		(layer "In2.Cu")
		(net "M_I_CPU1_SA_DQS_DP<1>")
	)
	(segment
		(start 146.934682 -225.709226)
		(end 146.951446 -225.692462)
		(width 0.09525)
		(layer "In2.Cu")
		(net "M_I_CPU1_SA_DQS_DP<1>")
	)
	(segment
		(start 132.266182 -231.849422)
		(end 132.274564 -231.854248)
		(width 0.09525)
		(layer "In2.Cu")
		(net "M_I_CPU1_SA_DQS_DP<1>")
	)
	(segment
		(start 141.666214 -231.849422)
		(end 141.674596 -231.854248)
		(width 0.09525)
		(layer "In2.Cu")
		(net "M_I_CPU1_SA_DQS_DP<1>")
	)
	(segment
		(start 146.32432 -226.104196)
		(end 146.623532 -226.104196)
		(width 0.09525)
		(layer "In2.Cu")
		(net "M_I_CPU1_SA_DQS_DP<1>")
	)
	(segment
		(start 174.366936 -209.676746)
		(end 174.892208 -209.676746)
		(width 0.16002)
		(layer "In2.Cu")
		(net "M_I_CPU1_SA_DQS_DP<1>")
	)
	(segment
		(start 145.333466 -227.799646)
		(end 145.362676 -227.782882)
		(width 0.09525)
		(layer "In2.Cu")
		(net "M_I_CPU1_SA_DQS_DP<1>")
	)
	(segment
		(start 165.640258 -210.517486)
		(end 165.982142 -210.517486)
		(width 0.16002)
		(layer "In2.Cu")
		(net "M_I_CPU1_SA_DQS_DP<1>")
	)
	(segment
		(start 167.348154 -209.676746)
		(end 167.664638 -209.360262)
		(width 0.16002)
		(layer "In2.Cu")
		(net "M_I_CPU1_SA_DQS_DP<1>")
	)
	(segment
		(start 165.982142 -210.517486)
		(end 166.822882 -209.676746)
		(width 0.16002)
		(layer "In2.Cu")
		(net "M_I_CPU1_SA_DQS_DP<1>")
	)
	(segment
		(start 169.893742 -209.360262)
		(end 170.743626 -210.210146)
		(width 0.16002)
		(layer "In2.Cu")
		(net "M_I_CPU1_SA_DQS_DP<1>")
	)
	(segment
		(start 174.892208 -209.676746)
		(end 175.208692 -209.360262)
		(width 0.16002)
		(layer "In2.Cu")
		(net "M_I_CPU1_SA_DQS_DP<1>")
	)
	(segment
		(start 129.634742 -231.524302)
		(end 129.480818 -231.789732)
		(width 0.09525)
		(layer "In2.Cu")
		(net "M_I_CPU1_SA_DQS_DP<1>")
	)
	(segment
		(start 143.887698 -230.249984)
		(end 143.923258 -230.22941)
		(width 0.09525)
		(layer "In2.Cu")
		(net "M_I_CPU1_SA_DQS_DP<1>")
	)
	(segment
		(start 136.966198 -231.849422)
		(end 136.97458 -231.854248)
		(width 0.09525)
		(layer "In2.Cu")
		(net "M_I_CPU1_SA_DQS_DP<1>")
	)
	(segment
		(start 181.955948 -210.360006)
		(end 183.341518 -210.360006)
		(width 0.16002)
		(layer "In2.Cu")
		(net "M_I_CPU1_SA_DQS_DP<1>")
	)
	(segment
		(start 143.453358 -231.03967)
		(end 143.484854 -231.021382)
		(width 0.09525)
		(layer "In2.Cu")
		(net "M_I_CPU1_SA_DQS_DP<1>")
	)
	(segment
		(start 160.428432 -210.210146)
		(end 165.332918 -210.210146)
		(width 0.16002)
		(layer "In2.Cu")
		(net "M_I_CPU1_SA_DQS_DP<1>")
	)
	(segment
		(start 129.480818 -231.789732)
		(end 129.503932 -231.876346)
		(width 0.09525)
		(layer "In2.Cu")
		(net "M_I_CPU1_SA_DQS_DP<1>")
	)
	(segment
		(start 145.885662 -226.941634)
		(end 145.96999 -226.857306)
		(width 0.09525)
		(layer "In2.Cu")
		(net "M_I_CPU1_SA_DQS_DP<1>")
	)
	(segment
		(start 140.154914 -231.854248)
		(end 140.163296 -231.849422)
		(width 0.09525)
		(layer "In2.Cu")
		(net "M_I_CPU1_SA_DQS_DP<1>")
	)
	(segment
		(start 166.822882 -209.676746)
		(end 167.348154 -209.676746)
		(width 0.16002)
		(layer "In2.Cu")
		(net "M_I_CPU1_SA_DQS_DP<1>")
	)
	(segment
		(start 133.206236 -231.849422)
		(end 133.214618 -231.854248)
		(width 0.09525)
		(layer "In2.Cu")
		(net "M_I_CPU1_SA_DQS_DP<1>")
	)
	(segment
		(start 136.394952 -231.854248)
		(end 136.403334 -231.849422)
		(width 0.09525)
		(layer "In2.Cu")
		(net "M_I_CPU1_SA_DQS_DP<1>")
	)
	(segment
		(start 146.623532 -226.104196)
		(end 146.934682 -225.793046)
		(width 0.09525)
		(layer "In2.Cu")
		(net "M_I_CPU1_SA_DQS_DP<1>")
	)
	(segment
		(start 145.76806 -227.009706)
		(end 145.803112 -226.989386)
		(width 0.09525)
		(layer "In2.Cu")
		(net "M_I_CPU1_SA_DQS_DP<1>")
	)
	(segment
		(start 144.863312 -228.609652)
		(end 144.895824 -228.590856)
		(width 0.09525)
		(layer "In2.Cu")
		(net "M_I_CPU1_SA_DQS_DP<1>")
	)
	(segment
		(start 170.743626 -210.210146)
		(end 172.876972 -210.210146)
		(width 0.16002)
		(layer "In2.Cu")
		(net "M_I_CPU1_SA_DQS_DP<1>")
	)
	(segment
		(start 180.753512 -210.542886)
		(end 181.773068 -210.542886)
		(width 0.16002)
		(layer "In2.Cu")
		(net "M_I_CPU1_SA_DQS_DP<1>")
	)
	(segment
		(start 172.876972 -210.210146)
		(end 173.184312 -210.517486)
		(width 0.16002)
		(layer "In2.Cu")
		(net "M_I_CPU1_SA_DQS_DP<1>")
	)
	(segment
		(start 181.773068 -210.542886)
		(end 181.955948 -210.360006)
		(width 0.16002)
		(layer "In2.Cu")
		(net "M_I_CPU1_SA_DQS_DP<1>")
	)
	(segment
		(start 183.341518 -210.360006)
		(end 183.616092 -210.085432)
		(width 0.16002)
		(layer "In2.Cu")
		(net "M_I_CPU1_SA_DQS_DP<1>")
	)
	(segment
		(start 180.144928 -209.934302)
		(end 180.753512 -210.542886)
		(width 0.16002)
		(layer "In2.Cu")
		(net "M_I_CPU1_SA_DQS_DP<1>")
	)
	(segment
		(start 145.295366 -227.821744)
		(end 145.333466 -227.799646)
		(width 0.09525)
		(layer "In2.Cu")
		(net "M_I_CPU1_SA_DQS_DP<1>")
	)
	(arc
		(start 143.95577 -230.210614)
		(mid 144.071044 -230.076336)
		(end 144.112488 -229.90429)
		(width 0.09525)
		(layer "In2.Cu")
		(net "M_I_CPU1_SA_DQS_DP<1>")
	)
	(arc
		(start 129.503932 -231.876346)
		(mid 129.666583 -231.898606)
		(end 129.82321 -231.849422)
		(width 0.09525)
		(layer "In2.Cu")
		(net "M_I_CPU1_SA_DQS_DP<1>")
	)
	(arc
		(start 139.223242 -231.849422)
		(mid 139.504674 -231.773667)
		(end 139.786106 -231.849422)
		(width 0.09525)
		(layer "In2.Cu")
		(net "M_I_CPU1_SA_DQS_DP<1>")
	)
	(arc
		(start 137.343388 -231.849422)
		(mid 137.62482 -231.773667)
		(end 137.906252 -231.849422)
		(width 0.09525)
		(layer "In2.Cu")
		(net "M_I_CPU1_SA_DQS_DP<1>")
	)
	(arc
		(start 145.522188 -227.474526)
		(mid 145.587385 -227.211573)
		(end 145.76806 -227.009706)
		(width 0.09525)
		(layer "In2.Cu")
		(net "M_I_CPU1_SA_DQS_DP<1>")
	)
	(arc
		(start 142.043404 -231.849422)
		(mid 142.324836 -231.773667)
		(end 142.606268 -231.849422)
		(width 0.09525)
		(layer "In2.Cu")
		(net "M_I_CPU1_SA_DQS_DP<1>")
	)
	(arc
		(start 131.326128 -231.849422)
		(mid 131.509903 -231.900194)
		(end 131.694936 -231.854248)
		(width 0.09525)
		(layer "In2.Cu")
		(net "M_I_CPU1_SA_DQS_DP<1>")
	)
	(arc
		(start 145.362676 -227.782882)
		(mid 145.47998 -227.648121)
		(end 145.522188 -227.474526)
		(width 0.09525)
		(layer "In2.Cu")
		(net "M_I_CPU1_SA_DQS_DP<1>")
	)
	(arc
		(start 141.10335 -231.849422)
		(mid 141.384782 -231.773667)
		(end 141.666214 -231.849422)
		(width 0.09525)
		(layer "In2.Cu")
		(net "M_I_CPU1_SA_DQS_DP<1>")
	)
	(arc
		(start 138.846306 -231.849422)
		(mid 139.034774 -231.900099)
		(end 139.223242 -231.849422)
		(width 0.09525)
		(layer "In2.Cu")
		(net "M_I_CPU1_SA_DQS_DP<1>")
	)
	(arc
		(start 136.97458 -231.854248)
		(mid 137.159612 -231.900162)
		(end 137.343388 -231.849422)
		(width 0.09525)
		(layer "In2.Cu")
		(net "M_I_CPU1_SA_DQS_DP<1>")
	)
	(arc
		(start 129.82321 -231.849422)
		(mid 130.104642 -231.773667)
		(end 130.386074 -231.849422)
		(width 0.09525)
		(layer "In2.Cu")
		(net "M_I_CPU1_SA_DQS_DP<1>")
	)
	(arc
		(start 133.583426 -231.849422)
		(mid 133.864858 -231.773667)
		(end 134.14629 -231.849422)
		(width 0.09525)
		(layer "In2.Cu")
		(net "M_I_CPU1_SA_DQS_DP<1>")
	)
	(arc
		(start 135.08609 -231.849422)
		(mid 135.269865 -231.900194)
		(end 135.454898 -231.854248)
		(width 0.09525)
		(layer "In2.Cu")
		(net "M_I_CPU1_SA_DQS_DP<1>")
	)
	(arc
		(start 137.914634 -231.854248)
		(mid 138.099666 -231.900162)
		(end 138.283442 -231.849422)
		(width 0.09525)
		(layer "In2.Cu")
		(net "M_I_CPU1_SA_DQS_DP<1>")
	)
	(arc
		(start 132.643372 -231.849422)
		(mid 132.924804 -231.773667)
		(end 133.206236 -231.849422)
		(width 0.09525)
		(layer "In2.Cu")
		(net "M_I_CPU1_SA_DQS_DP<1>")
	)
	(arc
		(start 136.026144 -231.849422)
		(mid 136.209919 -231.900194)
		(end 136.394952 -231.854248)
		(width 0.09525)
		(layer "In2.Cu")
		(net "M_I_CPU1_SA_DQS_DP<1>")
	)
	(arc
		(start 133.214618 -231.854248)
		(mid 133.39965 -231.900162)
		(end 133.583426 -231.849422)
		(width 0.09525)
		(layer "In2.Cu")
		(net "M_I_CPU1_SA_DQS_DP<1>")
	)
	(arc
		(start 140.163296 -231.849422)
		(mid 140.444728 -231.773667)
		(end 140.72616 -231.849422)
		(width 0.09525)
		(layer "In2.Cu")
		(net "M_I_CPU1_SA_DQS_DP<1>")
	)
	(arc
		(start 141.674596 -231.854248)
		(mid 141.859628 -231.900162)
		(end 142.043404 -231.849422)
		(width 0.09525)
		(layer "In2.Cu")
		(net "M_I_CPU1_SA_DQS_DP<1>")
	)
	(arc
		(start 131.703318 -231.849422)
		(mid 131.98475 -231.773667)
		(end 132.266182 -231.849422)
		(width 0.09525)
		(layer "In2.Cu")
		(net "M_I_CPU1_SA_DQS_DP<1>")
	)
	(arc
		(start 130.386074 -231.849422)
		(mid 130.569849 -231.900194)
		(end 130.754882 -231.854248)
		(width 0.09525)
		(layer "In2.Cu")
		(net "M_I_CPU1_SA_DQS_DP<1>")
	)
	(arc
		(start 135.46328 -231.849422)
		(mid 135.744712 -231.773667)
		(end 136.026144 -231.849422)
		(width 0.09525)
		(layer "In2.Cu")
		(net "M_I_CPU1_SA_DQS_DP<1>")
	)
	(arc
		(start 143.172434 -231.524302)
		(mid 143.23618 -231.264302)
		(end 143.412972 -231.063292)
		(width 0.09525)
		(layer "In2.Cu")
		(net "M_I_CPU1_SA_DQS_DP<1>")
	)
	(arc
		(start 143.484854 -231.021382)
		(mid 143.600652 -230.886988)
		(end 143.642334 -230.71455)
		(width 0.09525)
		(layer "In2.Cu")
		(net "M_I_CPU1_SA_DQS_DP<1>")
	)
	(arc
		(start 144.112488 -229.90429)
		(mid 144.176234 -229.64429)
		(end 144.353026 -229.44328)
		(width 0.09525)
		(layer "In2.Cu")
		(net "M_I_CPU1_SA_DQS_DP<1>")
	)
	(arc
		(start 130.763264 -231.849422)
		(mid 131.044696 -231.773667)
		(end 131.326128 -231.849422)
		(width 0.09525)
		(layer "In2.Cu")
		(net "M_I_CPU1_SA_DQS_DP<1>")
	)
	(arc
		(start 140.72616 -231.849422)
		(mid 140.909935 -231.900194)
		(end 141.094968 -231.854248)
		(width 0.09525)
		(layer "In2.Cu")
		(net "M_I_CPU1_SA_DQS_DP<1>")
	)
	(arc
		(start 144.895824 -228.590856)
		(mid 145.011098 -228.456578)
		(end 145.052542 -228.284532)
		(width 0.09525)
		(layer "In2.Cu")
		(net "M_I_CPU1_SA_DQS_DP<1>")
	)
	(arc
		(start 143.015716 -231.830626)
		(mid 143.13099 -231.696348)
		(end 143.172434 -231.524302)
		(width 0.09525)
		(layer "In2.Cu")
		(net "M_I_CPU1_SA_DQS_DP<1>")
	)
	(arc
		(start 139.786106 -231.849422)
		(mid 139.969881 -231.900194)
		(end 140.154914 -231.854248)
		(width 0.09525)
		(layer "In2.Cu")
		(net "M_I_CPU1_SA_DQS_DP<1>")
	)
	(arc
		(start 145.052542 -228.284532)
		(mid 145.116939 -228.023226)
		(end 145.295366 -227.821744)
		(width 0.09525)
		(layer "In2.Cu")
		(net "M_I_CPU1_SA_DQS_DP<1>")
	)
	(arc
		(start 143.642334 -230.71455)
		(mid 143.707453 -230.451872)
		(end 143.887698 -230.249984)
		(width 0.09525)
		(layer "In2.Cu")
		(net "M_I_CPU1_SA_DQS_DP<1>")
	)
	(arc
		(start 144.582388 -229.094538)
		(mid 144.646785 -228.833232)
		(end 144.825212 -228.63175)
		(width 0.09525)
		(layer "In2.Cu")
		(net "M_I_CPU1_SA_DQS_DP<1>")
	)
	(arc
		(start 134.523226 -231.849422)
		(mid 134.804658 -231.773667)
		(end 135.08609 -231.849422)
		(width 0.09525)
		(layer "In2.Cu")
		(net "M_I_CPU1_SA_DQS_DP<1>")
	)
	(arc
		(start 144.424908 -229.40137)
		(mid 144.540706 -229.266976)
		(end 144.582388 -229.094538)
		(width 0.09525)
		(layer "In2.Cu")
		(net "M_I_CPU1_SA_DQS_DP<1>")
	)
	(arc
		(start 134.14629 -231.849422)
		(mid 134.334758 -231.900099)
		(end 134.523226 -231.849422)
		(width 0.09525)
		(layer "In2.Cu")
		(net "M_I_CPU1_SA_DQS_DP<1>")
	)
	(arc
		(start 142.606268 -231.849422)
		(mid 142.794736 -231.900099)
		(end 142.983204 -231.849422)
		(width 0.09525)
		(layer "In2.Cu")
		(net "M_I_CPU1_SA_DQS_DP<1>")
	)
	(arc
		(start 132.274564 -231.854248)
		(mid 132.459596 -231.900162)
		(end 132.643372 -231.849422)
		(width 0.09525)
		(layer "In2.Cu")
		(net "M_I_CPU1_SA_DQS_DP<1>")
	)
	(arc
		(start 138.283442 -231.849422)
		(mid 138.564874 -231.773667)
		(end 138.846306 -231.849422)
		(width 0.09525)
		(layer "In2.Cu")
		(net "M_I_CPU1_SA_DQS_DP<1>")
	)
	(arc
		(start 136.403334 -231.849422)
		(mid 136.684766 -231.773667)
		(end 136.966198 -231.849422)
		(width 0.09525)
		(layer "In2.Cu")
		(net "M_I_CPU1_SA_DQS_DP<1>")
	)
	(segment
		(start 129.16789 -226.930458)
		(end 129.634742 -226.66452)
		(width 0.12954)
		(layer "F.Cu")
		(net "M_I_CPU1_SA_DQS_DP<0>")
	)
	(segment
		(start 132.266182 -226.98964)
		(end 132.274564 -226.994466)
		(width 0.09525)
		(layer "In2.Cu")
		(net "M_I_CPU1_SA_DQS_DP<0>")
	)
	(segment
		(start 173.526196 -201.167492)
		(end 174.366936 -200.326752)
		(width 0.16002)
		(layer "In2.Cu")
		(net "M_I_CPU1_SA_DQS_DP<0>")
	)
	(segment
		(start 143.172688 -221.803722)
		(end 143.172688 -221.257114)
		(width 0.09525)
		(layer "In2.Cu")
		(net "M_I_CPU1_SA_DQS_DP<0>")
	)
	(segment
		(start 165.982142 -201.167492)
		(end 166.822882 -200.326752)
		(width 0.16002)
		(layer "In2.Cu")
		(net "M_I_CPU1_SA_DQS_DP<0>")
	)
	(segment
		(start 181.159404 -201.192892)
		(end 181.342284 -201.010012)
		(width 0.16002)
		(layer "In2.Cu")
		(net "M_I_CPU1_SA_DQS_DP<0>")
	)
	(segment
		(start 169.893742 -200.010268)
		(end 170.743626 -200.860152)
		(width 0.16002)
		(layer "In2.Cu")
		(net "M_I_CPU1_SA_DQS_DP<0>")
	)
	(segment
		(start 142.945104 -222.151702)
		(end 143.0147 -222.111316)
		(width 0.09525)
		(layer "In2.Cu")
		(net "M_I_CPU1_SA_DQS_DP<0>")
	)
	(segment
		(start 141.10335 -225.369628)
		(end 141.135862 -225.350832)
		(width 0.09525)
		(layer "In2.Cu")
		(net "M_I_CPU1_SA_DQS_DP<0>")
	)
	(segment
		(start 172.876972 -200.860152)
		(end 173.184312 -201.167492)
		(width 0.16002)
		(layer "In2.Cu")
		(net "M_I_CPU1_SA_DQS_DP<0>")
	)
	(segment
		(start 141.06525 -225.391726)
		(end 141.10335 -225.369628)
		(width 0.09525)
		(layer "In2.Cu")
		(net "M_I_CPU1_SA_DQS_DP<0>")
	)
	(segment
		(start 131.694936 -226.994466)
		(end 131.703318 -226.98964)
		(width 0.09525)
		(layer "In2.Cu")
		(net "M_I_CPU1_SA_DQS_DP<0>")
	)
	(segment
		(start 142.475204 -222.961708)
		(end 142.513304 -222.93961)
		(width 0.09525)
		(layer "In2.Cu")
		(net "M_I_CPU1_SA_DQS_DP<0>")
	)
	(segment
		(start 165.640258 -201.167492)
		(end 165.982142 -201.167492)
		(width 0.16002)
		(layer "In2.Cu")
		(net "M_I_CPU1_SA_DQS_DP<0>")
	)
	(segment
		(start 167.664638 -200.010268)
		(end 169.893742 -200.010268)
		(width 0.16002)
		(layer "In2.Cu")
		(net "M_I_CPU1_SA_DQS_DP<0>")
	)
	(segment
		(start 130.754882 -226.994466)
		(end 130.763264 -226.98964)
		(width 0.09525)
		(layer "In2.Cu")
		(net "M_I_CPU1_SA_DQS_DP<0>")
	)
	(segment
		(start 129.480818 -226.92995)
		(end 129.503932 -227.016564)
		(width 0.09525)
		(layer "In2.Cu")
		(net "M_I_CPU1_SA_DQS_DP<0>")
	)
	(segment
		(start 149.027388 -213.778084)
		(end 149.027388 -212.444584)
		(width 0.16002)
		(layer "In2.Cu")
		(net "M_I_CPU1_SA_DQS_DP<0>")
	)
	(segment
		(start 160.61182 -200.860152)
		(end 165.332918 -200.860152)
		(width 0.16002)
		(layer "In2.Cu")
		(net "M_I_CPU1_SA_DQS_DP<0>")
	)
	(segment
		(start 143.172688 -221.257114)
		(end 143.11376 -221.198186)
		(width 0.09525)
		(layer "In2.Cu")
		(net "M_I_CPU1_SA_DQS_DP<0>")
	)
	(segment
		(start 181.342284 -201.010012)
		(end 183.341518 -201.010012)
		(width 0.16002)
		(layer "In2.Cu")
		(net "M_I_CPU1_SA_DQS_DP<0>")
	)
	(segment
		(start 136.966198 -226.98964)
		(end 136.97458 -226.994466)
		(width 0.09525)
		(layer "In2.Cu")
		(net "M_I_CPU1_SA_DQS_DP<0>")
	)
	(segment
		(start 141.57325 -224.559622)
		(end 141.605762 -224.540826)
		(width 0.09525)
		(layer "In2.Cu")
		(net "M_I_CPU1_SA_DQS_DP<0>")
	)
	(segment
		(start 140.63345 -226.179634)
		(end 140.664946 -226.161346)
		(width 0.09525)
		(layer "In2.Cu")
		(net "M_I_CPU1_SA_DQS_DP<0>")
	)
	(segment
		(start 180.144928 -200.584308)
		(end 180.753512 -201.192892)
		(width 0.16002)
		(layer "In2.Cu")
		(net "M_I_CPU1_SA_DQS_DP<0>")
	)
	(segment
		(start 129.634742 -226.66452)
		(end 129.480818 -226.92995)
		(width 0.09525)
		(layer "In2.Cu")
		(net "M_I_CPU1_SA_DQS_DP<0>")
	)
	(segment
		(start 143.11376 -219.691712)
		(end 149.027388 -213.778084)
		(width 0.16002)
		(layer "In2.Cu")
		(net "M_I_CPU1_SA_DQS_DP<0>")
	)
	(segment
		(start 140.59535 -226.201732)
		(end 140.63345 -226.179634)
		(width 0.09525)
		(layer "In2.Cu")
		(net "M_I_CPU1_SA_DQS_DP<0>")
	)
	(segment
		(start 137.906252 -226.98964)
		(end 137.914634 -226.994466)
		(width 0.09525)
		(layer "In2.Cu")
		(net "M_I_CPU1_SA_DQS_DP<0>")
	)
	(segment
		(start 142.513304 -222.93961)
		(end 142.5448 -222.921322)
		(width 0.09525)
		(layer "In2.Cu")
		(net "M_I_CPU1_SA_DQS_DP<0>")
	)
	(segment
		(start 149.027388 -212.444584)
		(end 160.61182 -200.860152)
		(width 0.16002)
		(layer "In2.Cu")
		(net "M_I_CPU1_SA_DQS_DP<0>")
	)
	(segment
		(start 143.11376 -221.198186)
		(end 143.11376 -221.174564)
		(width 0.09525)
		(layer "In2.Cu")
		(net "M_I_CPU1_SA_DQS_DP<0>")
	)
	(segment
		(start 141.538198 -224.580196)
		(end 141.57325 -224.559622)
		(width 0.09525)
		(layer "In2.Cu")
		(net "M_I_CPU1_SA_DQS_DP<0>")
	)
	(segment
		(start 140.154914 -226.994466)
		(end 140.163296 -226.98964)
		(width 0.09525)
		(layer "In2.Cu")
		(net "M_I_CPU1_SA_DQS_DP<0>")
	)
	(segment
		(start 167.348154 -200.326752)
		(end 167.664638 -200.010268)
		(width 0.16002)
		(layer "In2.Cu")
		(net "M_I_CPU1_SA_DQS_DP<0>")
	)
	(segment
		(start 133.206236 -226.98964)
		(end 133.214618 -226.994466)
		(width 0.09525)
		(layer "In2.Cu")
		(net "M_I_CPU1_SA_DQS_DP<0>")
	)
	(segment
		(start 135.454898 -226.994466)
		(end 135.46328 -226.98964)
		(width 0.09525)
		(layer "In2.Cu")
		(net "M_I_CPU1_SA_DQS_DP<0>")
	)
	(segment
		(start 136.394952 -226.994466)
		(end 136.403334 -226.98964)
		(width 0.09525)
		(layer "In2.Cu")
		(net "M_I_CPU1_SA_DQS_DP<0>")
	)
	(segment
		(start 183.341518 -201.010012)
		(end 183.616092 -200.735438)
		(width 0.16002)
		(layer "In2.Cu")
		(net "M_I_CPU1_SA_DQS_DP<0>")
	)
	(segment
		(start 174.892208 -200.326752)
		(end 175.208692 -200.010268)
		(width 0.16002)
		(layer "In2.Cu")
		(net "M_I_CPU1_SA_DQS_DP<0>")
	)
	(segment
		(start 142.005304 -223.771714)
		(end 142.043404 -223.749616)
		(width 0.09525)
		(layer "In2.Cu")
		(net "M_I_CPU1_SA_DQS_DP<0>")
	)
	(segment
		(start 174.366936 -200.326752)
		(end 174.892208 -200.326752)
		(width 0.16002)
		(layer "In2.Cu")
		(net "M_I_CPU1_SA_DQS_DP<0>")
	)
	(segment
		(start 142.043404 -223.749616)
		(end 142.0749 -223.731328)
		(width 0.09525)
		(layer "In2.Cu")
		(net "M_I_CPU1_SA_DQS_DP<0>")
	)
	(segment
		(start 177.485548 -200.010268)
		(end 178.059588 -200.584308)
		(width 0.16002)
		(layer "In2.Cu")
		(net "M_I_CPU1_SA_DQS_DP<0>")
	)
	(segment
		(start 170.743626 -200.860152)
		(end 172.876972 -200.860152)
		(width 0.16002)
		(layer "In2.Cu")
		(net "M_I_CPU1_SA_DQS_DP<0>")
	)
	(segment
		(start 180.753512 -201.192892)
		(end 181.159404 -201.192892)
		(width 0.16002)
		(layer "In2.Cu")
		(net "M_I_CPU1_SA_DQS_DP<0>")
	)
	(segment
		(start 165.332918 -200.860152)
		(end 165.640258 -201.167492)
		(width 0.16002)
		(layer "In2.Cu")
		(net "M_I_CPU1_SA_DQS_DP<0>")
	)
	(segment
		(start 143.11376 -221.174564)
		(end 143.11376 -219.691712)
		(width 0.16002)
		(layer "In2.Cu")
		(net "M_I_CPU1_SA_DQS_DP<0>")
	)
	(segment
		(start 140.163296 -226.98964)
		(end 140.195808 -226.970844)
		(width 0.09525)
		(layer "In2.Cu")
		(net "M_I_CPU1_SA_DQS_DP<0>")
	)
	(segment
		(start 178.059588 -200.584308)
		(end 180.144928 -200.584308)
		(width 0.16002)
		(layer "In2.Cu")
		(net "M_I_CPU1_SA_DQS_DP<0>")
	)
	(segment
		(start 173.184312 -201.167492)
		(end 173.526196 -201.167492)
		(width 0.16002)
		(layer "In2.Cu")
		(net "M_I_CPU1_SA_DQS_DP<0>")
	)
	(segment
		(start 175.208692 -200.010268)
		(end 177.485548 -200.010268)
		(width 0.16002)
		(layer "In2.Cu")
		(net "M_I_CPU1_SA_DQS_DP<0>")
	)
	(segment
		(start 166.822882 -200.326752)
		(end 167.348154 -200.326752)
		(width 0.16002)
		(layer "In2.Cu")
		(net "M_I_CPU1_SA_DQS_DP<0>")
	)
	(arc
		(start 131.703318 -226.98964)
		(mid 131.98475 -226.913885)
		(end 132.266182 -226.98964)
		(width 0.09525)
		(layer "In2.Cu")
		(net "M_I_CPU1_SA_DQS_DP<0>")
	)
	(arc
		(start 139.786106 -226.98964)
		(mid 139.969881 -227.040412)
		(end 140.154914 -226.994466)
		(width 0.09525)
		(layer "In2.Cu")
		(net "M_I_CPU1_SA_DQS_DP<0>")
	)
	(arc
		(start 140.822426 -225.854514)
		(mid 140.886823 -225.593208)
		(end 141.06525 -225.391726)
		(width 0.09525)
		(layer "In2.Cu")
		(net "M_I_CPU1_SA_DQS_DP<0>")
	)
	(arc
		(start 136.97458 -226.994466)
		(mid 137.159612 -227.04038)
		(end 137.343388 -226.98964)
		(width 0.09525)
		(layer "In2.Cu")
		(net "M_I_CPU1_SA_DQS_DP<0>")
	)
	(arc
		(start 142.5448 -222.921322)
		(mid 142.660598 -222.786928)
		(end 142.70228 -222.61449)
		(width 0.09525)
		(layer "In2.Cu")
		(net "M_I_CPU1_SA_DQS_DP<0>")
	)
	(arc
		(start 134.523226 -226.98964)
		(mid 134.804658 -226.913885)
		(end 135.08609 -226.98964)
		(width 0.09525)
		(layer "In2.Cu")
		(net "M_I_CPU1_SA_DQS_DP<0>")
	)
	(arc
		(start 142.23238 -223.424496)
		(mid 142.296777 -223.16319)
		(end 142.475204 -222.961708)
		(width 0.09525)
		(layer "In2.Cu")
		(net "M_I_CPU1_SA_DQS_DP<0>")
	)
	(arc
		(start 129.503932 -227.016564)
		(mid 129.666583 -227.038824)
		(end 129.82321 -226.98964)
		(width 0.09525)
		(layer "In2.Cu")
		(net "M_I_CPU1_SA_DQS_DP<0>")
	)
	(arc
		(start 130.386074 -226.98964)
		(mid 130.569849 -227.040412)
		(end 130.754882 -226.994466)
		(width 0.09525)
		(layer "In2.Cu")
		(net "M_I_CPU1_SA_DQS_DP<0>")
	)
	(arc
		(start 134.14629 -226.98964)
		(mid 134.334758 -227.040317)
		(end 134.523226 -226.98964)
		(width 0.09525)
		(layer "In2.Cu")
		(net "M_I_CPU1_SA_DQS_DP<0>")
	)
	(arc
		(start 143.0147 -222.111316)
		(mid 143.130872 -221.976617)
		(end 143.172688 -221.803722)
		(width 0.09525)
		(layer "In2.Cu")
		(net "M_I_CPU1_SA_DQS_DP<0>")
	)
	(arc
		(start 141.135862 -225.350832)
		(mid 141.251136 -225.216554)
		(end 141.29258 -225.044508)
		(width 0.09525)
		(layer "In2.Cu")
		(net "M_I_CPU1_SA_DQS_DP<0>")
	)
	(arc
		(start 142.0749 -223.731328)
		(mid 142.190698 -223.596934)
		(end 142.23238 -223.424496)
		(width 0.09525)
		(layer "In2.Cu")
		(net "M_I_CPU1_SA_DQS_DP<0>")
	)
	(arc
		(start 133.214618 -226.994466)
		(mid 133.39965 -227.04038)
		(end 133.583426 -226.98964)
		(width 0.09525)
		(layer "In2.Cu")
		(net "M_I_CPU1_SA_DQS_DP<0>")
	)
	(arc
		(start 136.026144 -226.98964)
		(mid 136.209919 -227.040412)
		(end 136.394952 -226.994466)
		(width 0.09525)
		(layer "In2.Cu")
		(net "M_I_CPU1_SA_DQS_DP<0>")
	)
	(arc
		(start 141.29258 -225.044508)
		(mid 141.357827 -224.781905)
		(end 141.538198 -224.580196)
		(width 0.09525)
		(layer "In2.Cu")
		(net "M_I_CPU1_SA_DQS_DP<0>")
	)
	(arc
		(start 142.70228 -222.61449)
		(mid 142.766677 -222.353184)
		(end 142.945104 -222.151702)
		(width 0.09525)
		(layer "In2.Cu")
		(net "M_I_CPU1_SA_DQS_DP<0>")
	)
	(arc
		(start 137.914634 -226.994466)
		(mid 138.099666 -227.04038)
		(end 138.283442 -226.98964)
		(width 0.09525)
		(layer "In2.Cu")
		(net "M_I_CPU1_SA_DQS_DP<0>")
	)
	(arc
		(start 132.274564 -226.994466)
		(mid 132.459596 -227.04038)
		(end 132.643372 -226.98964)
		(width 0.09525)
		(layer "In2.Cu")
		(net "M_I_CPU1_SA_DQS_DP<0>")
	)
	(arc
		(start 141.605762 -224.540826)
		(mid 141.721036 -224.406548)
		(end 141.76248 -224.234502)
		(width 0.09525)
		(layer "In2.Cu")
		(net "M_I_CPU1_SA_DQS_DP<0>")
	)
	(arc
		(start 130.763264 -226.98964)
		(mid 131.044696 -226.913885)
		(end 131.326128 -226.98964)
		(width 0.09525)
		(layer "In2.Cu")
		(net "M_I_CPU1_SA_DQS_DP<0>")
	)
	(arc
		(start 140.195808 -226.970844)
		(mid 140.311082 -226.836566)
		(end 140.352526 -226.66452)
		(width 0.09525)
		(layer "In2.Cu")
		(net "M_I_CPU1_SA_DQS_DP<0>")
	)
	(arc
		(start 129.82321 -226.98964)
		(mid 130.104642 -226.913885)
		(end 130.386074 -226.98964)
		(width 0.09525)
		(layer "In2.Cu")
		(net "M_I_CPU1_SA_DQS_DP<0>")
	)
	(arc
		(start 137.343388 -226.98964)
		(mid 137.62482 -226.913885)
		(end 137.906252 -226.98964)
		(width 0.09525)
		(layer "In2.Cu")
		(net "M_I_CPU1_SA_DQS_DP<0>")
	)
	(arc
		(start 139.223242 -226.98964)
		(mid 139.504674 -226.913885)
		(end 139.786106 -226.98964)
		(width 0.09525)
		(layer "In2.Cu")
		(net "M_I_CPU1_SA_DQS_DP<0>")
	)
	(arc
		(start 135.46328 -226.98964)
		(mid 135.744712 -226.913885)
		(end 136.026144 -226.98964)
		(width 0.09525)
		(layer "In2.Cu")
		(net "M_I_CPU1_SA_DQS_DP<0>")
	)
	(arc
		(start 136.403334 -226.98964)
		(mid 136.684766 -226.913885)
		(end 136.966198 -226.98964)
		(width 0.09525)
		(layer "In2.Cu")
		(net "M_I_CPU1_SA_DQS_DP<0>")
	)
	(arc
		(start 140.664946 -226.161346)
		(mid 140.780744 -226.026952)
		(end 140.822426 -225.854514)
		(width 0.09525)
		(layer "In2.Cu")
		(net "M_I_CPU1_SA_DQS_DP<0>")
	)
	(arc
		(start 135.08609 -226.98964)
		(mid 135.269865 -227.040412)
		(end 135.454898 -226.994466)
		(width 0.09525)
		(layer "In2.Cu")
		(net "M_I_CPU1_SA_DQS_DP<0>")
	)
	(arc
		(start 132.643372 -226.98964)
		(mid 132.924804 -226.913885)
		(end 133.206236 -226.98964)
		(width 0.09525)
		(layer "In2.Cu")
		(net "M_I_CPU1_SA_DQS_DP<0>")
	)
	(arc
		(start 138.283442 -226.98964)
		(mid 138.564874 -226.913885)
		(end 138.846306 -226.98964)
		(width 0.09525)
		(layer "In2.Cu")
		(net "M_I_CPU1_SA_DQS_DP<0>")
	)
	(arc
		(start 141.76248 -224.234502)
		(mid 141.826877 -223.973196)
		(end 142.005304 -223.771714)
		(width 0.09525)
		(layer "In2.Cu")
		(net "M_I_CPU1_SA_DQS_DP<0>")
	)
	(arc
		(start 133.583426 -226.98964)
		(mid 133.864858 -226.913885)
		(end 134.14629 -226.98964)
		(width 0.09525)
		(layer "In2.Cu")
		(net "M_I_CPU1_SA_DQS_DP<0>")
	)
	(arc
		(start 140.352526 -226.66452)
		(mid 140.416923 -226.403214)
		(end 140.59535 -226.201732)
		(width 0.09525)
		(layer "In2.Cu")
		(net "M_I_CPU1_SA_DQS_DP<0>")
	)
	(arc
		(start 131.326128 -226.98964)
		(mid 131.509903 -227.040412)
		(end 131.694936 -226.994466)
		(width 0.09525)
		(layer "In2.Cu")
		(net "M_I_CPU1_SA_DQS_DP<0>")
	)
	(arc
		(start 138.846306 -226.98964)
		(mid 139.034774 -227.040317)
		(end 139.223242 -226.98964)
		(width 0.09525)
		(layer "In2.Cu")
		(net "M_I_CPU1_SA_DQS_DP<0>")
	)
	(segment
		(start 127.757936 -247.180354)
		(end 128.224788 -246.914416)
		(width 0.12954)
		(layer "F.Cu")
		(net "M_I_CPU1_SA_DQS_DN<9>")
	)
	(segment
		(start 159.270446 -246.253508)
		(end 159.270446 -245.976648)
		(width 0.16002)
		(layer "In2.Cu")
		(net "M_I_CPU1_SA_DQS_DN<9>")
	)
	(segment
		(start 161.690812 -242.902486)
		(end 161.690812 -242.375182)
		(width 0.16002)
		(layer "In2.Cu")
		(net "M_I_CPU1_SA_DQS_DN<9>")
	)
	(segment
		(start 157.942788 -246.123206)
		(end 158.470092 -246.123206)
		(width 0.16002)
		(layer "In2.Cu")
		(net "M_I_CPU1_SA_DQS_DN<9>")
	)
	(segment
		(start 128.224788 -246.914416)
		(end 128.070864 -247.179846)
		(width 0.09525)
		(layer "In2.Cu")
		(net "M_I_CPU1_SA_DQS_DN<9>")
	)
	(segment
		(start 162.01771 -243.506244)
		(end 162.01771 -243.229384)
		(width 0.16002)
		(layer "In2.Cu")
		(net "M_I_CPU1_SA_DQS_DN<9>")
	)
	(segment
		(start 161.821114 -243.70284)
		(end 162.01771 -243.506244)
		(width 0.16002)
		(layer "In2.Cu")
		(net "M_I_CPU1_SA_DQS_DN<9>")
	)
	(segment
		(start 143.453358 -247.239536)
		(end 143.46809 -247.2309)
		(width 0.09525)
		(layer "In2.Cu")
		(net "M_I_CPU1_SA_DQS_DN<9>")
	)
	(segment
		(start 134.61619 -247.239536)
		(end 134.624572 -247.244362)
		(width 0.09525)
		(layer "In2.Cu")
		(net "M_I_CPU1_SA_DQS_DN<9>")
	)
	(segment
		(start 143.076168 -247.239536)
		(end 143.08455 -247.244362)
		(width 0.09525)
		(layer "In2.Cu")
		(net "M_I_CPU1_SA_DQS_DN<9>")
	)
	(segment
		(start 165.558216 -239.893348)
		(end 165.995096 -239.893348)
		(width 0.16002)
		(layer "In2.Cu")
		(net "M_I_CPU1_SA_DQS_DN<9>")
	)
	(segment
		(start 144.382236 -247.246394)
		(end 144.394174 -247.239536)
		(width 0.09525)
		(layer "In2.Cu")
		(net "M_I_CPU1_SA_DQS_DN<9>")
	)
	(segment
		(start 142.504922 -247.244362)
		(end 142.513304 -247.239536)
		(width 0.09525)
		(layer "In2.Cu")
		(net "M_I_CPU1_SA_DQS_DN<9>")
	)
	(segment
		(start 162.01771 -243.229384)
		(end 161.690812 -242.902486)
		(width 0.16002)
		(layer "In2.Cu")
		(net "M_I_CPU1_SA_DQS_DN<9>")
	)
	(segment
		(start 163.531804 -240.53419)
		(end 164.917374 -240.53419)
		(width 0.16002)
		(layer "In2.Cu")
		(net "M_I_CPU1_SA_DQS_DN<9>")
	)
	(segment
		(start 177.754026 -239.259872)
		(end 177.870866 -239.143032)
		(width 0.16002)
		(layer "In2.Cu")
		(net "M_I_CPU1_SA_DQS_DN<9>")
	)
	(segment
		(start 158.470092 -246.123206)
		(end 158.79699 -246.450104)
		(width 0.16002)
		(layer "In2.Cu")
		(net "M_I_CPU1_SA_DQS_DN<9>")
	)
	(segment
		(start 129.344928 -247.244362)
		(end 129.35331 -247.239536)
		(width 0.09525)
		(layer "In2.Cu")
		(net "M_I_CPU1_SA_DQS_DN<9>")
	)
	(segment
		(start 159.843724 -244.749574)
		(end 160.170622 -245.076472)
		(width 0.16002)
		(layer "In2.Cu")
		(net "M_I_CPU1_SA_DQS_DN<9>")
	)
	(segment
		(start 147.716494 -247.231662)
		(end 147.740116 -247.231662)
		(width 0.09525)
		(layer "In2.Cu")
		(net "M_I_CPU1_SA_DQS_DN<9>")
	)
	(segment
		(start 134.044944 -247.244362)
		(end 134.053326 -247.239536)
		(width 0.09525)
		(layer "In2.Cu")
		(net "M_I_CPU1_SA_DQS_DN<9>")
	)
	(segment
		(start 128.070864 -247.179846)
		(end 128.094232 -247.266714)
		(width 0.09525)
		(layer "In2.Cu")
		(net "M_I_CPU1_SA_DQS_DN<9>")
	)
	(segment
		(start 165.995096 -239.893348)
		(end 166.787576 -239.100868)
		(width 0.16002)
		(layer "In2.Cu")
		(net "M_I_CPU1_SA_DQS_DN<9>")
	)
	(segment
		(start 158.943548 -245.122446)
		(end 159.31642 -244.749574)
		(width 0.16002)
		(layer "In2.Cu")
		(net "M_I_CPU1_SA_DQS_DN<9>")
	)
	(segment
		(start 159.07385 -246.450104)
		(end 159.270446 -246.253508)
		(width 0.16002)
		(layer "In2.Cu")
		(net "M_I_CPU1_SA_DQS_DN<9>")
	)
	(segment
		(start 157.432248 -246.633746)
		(end 157.942788 -246.123206)
		(width 0.16002)
		(layer "In2.Cu")
		(net "M_I_CPU1_SA_DQS_DN<9>")
	)
	(segment
		(start 160.170622 -245.076472)
		(end 160.447482 -245.076472)
		(width 0.16002)
		(layer "In2.Cu")
		(net "M_I_CPU1_SA_DQS_DN<9>")
	)
	(segment
		(start 161.217356 -243.375942)
		(end 161.544254 -243.70284)
		(width 0.16002)
		(layer "In2.Cu")
		(net "M_I_CPU1_SA_DQS_DN<9>")
	)
	(segment
		(start 130.856228 -247.239536)
		(end 130.86461 -247.244362)
		(width 0.09525)
		(layer "In2.Cu")
		(net "M_I_CPU1_SA_DQS_DN<9>")
	)
	(segment
		(start 174.995078 -239.100868)
		(end 175.302418 -239.408208)
		(width 0.16002)
		(layer "In2.Cu")
		(net "M_I_CPU1_SA_DQS_DN<9>")
	)
	(segment
		(start 138.74496 -247.244362)
		(end 138.753342 -247.239536)
		(width 0.09525)
		(layer "In2.Cu")
		(net "M_I_CPU1_SA_DQS_DN<9>")
	)
	(segment
		(start 178.350926 -239.143032)
		(end 178.467766 -239.259872)
		(width 0.16002)
		(layer "In2.Cu")
		(net "M_I_CPU1_SA_DQS_DN<9>")
	)
	(segment
		(start 161.544254 -243.70284)
		(end 161.821114 -243.70284)
		(width 0.16002)
		(layer "In2.Cu")
		(net "M_I_CPU1_SA_DQS_DN<9>")
	)
	(segment
		(start 133.10489 -247.244362)
		(end 133.113272 -247.239536)
		(width 0.09525)
		(layer "In2.Cu")
		(net "M_I_CPU1_SA_DQS_DN<9>")
	)
	(segment
		(start 161.690812 -242.375182)
		(end 163.531804 -240.53419)
		(width 0.16002)
		(layer "In2.Cu")
		(net "M_I_CPU1_SA_DQS_DN<9>")
	)
	(segment
		(start 173.53915 -239.893348)
		(end 174.33163 -239.100868)
		(width 0.16002)
		(layer "In2.Cu")
		(net "M_I_CPU1_SA_DQS_DN<9>")
	)
	(segment
		(start 159.31642 -244.749574)
		(end 159.843724 -244.749574)
		(width 0.16002)
		(layer "In2.Cu")
		(net "M_I_CPU1_SA_DQS_DN<9>")
	)
	(segment
		(start 173.10227 -239.893348)
		(end 173.53915 -239.893348)
		(width 0.16002)
		(layer "In2.Cu")
		(net "M_I_CPU1_SA_DQS_DN<9>")
	)
	(segment
		(start 174.33163 -239.100868)
		(end 174.995078 -239.100868)
		(width 0.16002)
		(layer "In2.Cu")
		(net "M_I_CPU1_SA_DQS_DN<9>")
	)
	(segment
		(start 148.229574 -247.231662)
		(end 148.82749 -246.633746)
		(width 0.16002)
		(layer "In2.Cu")
		(net "M_I_CPU1_SA_DQS_DN<9>")
	)
	(segment
		(start 164.917374 -240.53419)
		(end 165.558216 -239.893348)
		(width 0.16002)
		(layer "In2.Cu")
		(net "M_I_CPU1_SA_DQS_DN<9>")
	)
	(segment
		(start 140.25626 -247.239536)
		(end 140.264642 -247.244362)
		(width 0.09525)
		(layer "In2.Cu")
		(net "M_I_CPU1_SA_DQS_DN<9>")
	)
	(segment
		(start 166.787576 -239.100868)
		(end 167.451024 -239.100868)
		(width 0.16002)
		(layer "In2.Cu")
		(net "M_I_CPU1_SA_DQS_DN<9>")
	)
	(segment
		(start 168.034462 -239.684306)
		(end 170.498008 -239.684306)
		(width 0.16002)
		(layer "In2.Cu")
		(net "M_I_CPU1_SA_DQS_DN<9>")
	)
	(segment
		(start 159.270446 -245.976648)
		(end 158.943548 -245.64975)
		(width 0.16002)
		(layer "In2.Cu")
		(net "M_I_CPU1_SA_DQS_DN<9>")
	)
	(segment
		(start 160.31718 -243.748814)
		(end 160.690052 -243.375942)
		(width 0.16002)
		(layer "In2.Cu")
		(net "M_I_CPU1_SA_DQS_DN<9>")
	)
	(segment
		(start 160.690052 -243.375942)
		(end 161.217356 -243.375942)
		(width 0.16002)
		(layer "In2.Cu")
		(net "M_I_CPU1_SA_DQS_DN<9>")
	)
	(segment
		(start 177.870866 -239.143032)
		(end 178.350926 -239.143032)
		(width 0.16002)
		(layer "In2.Cu")
		(net "M_I_CPU1_SA_DQS_DN<9>")
	)
	(segment
		(start 146.085814 -247.290844)
		(end 147.657312 -247.290844)
		(width 0.09525)
		(layer "In2.Cu")
		(net "M_I_CPU1_SA_DQS_DN<9>")
	)
	(segment
		(start 129.916174 -247.239536)
		(end 129.924556 -247.244362)
		(width 0.09525)
		(layer "In2.Cu")
		(net "M_I_CPU1_SA_DQS_DN<9>")
	)
	(segment
		(start 137.804906 -247.244362)
		(end 137.813288 -247.239536)
		(width 0.09525)
		(layer "In2.Cu")
		(net "M_I_CPU1_SA_DQS_DN<9>")
	)
	(segment
		(start 147.740116 -247.231662)
		(end 148.229574 -247.231662)
		(width 0.16002)
		(layer "In2.Cu")
		(net "M_I_CPU1_SA_DQS_DN<9>")
	)
	(segment
		(start 171.347892 -240.53419)
		(end 172.461428 -240.53419)
		(width 0.16002)
		(layer "In2.Cu")
		(net "M_I_CPU1_SA_DQS_DN<9>")
	)
	(segment
		(start 160.447482 -245.076472)
		(end 160.644078 -244.879876)
		(width 0.16002)
		(layer "In2.Cu")
		(net "M_I_CPU1_SA_DQS_DN<9>")
	)
	(segment
		(start 147.657312 -247.290844)
		(end 147.716494 -247.231662)
		(width 0.09525)
		(layer "In2.Cu")
		(net "M_I_CPU1_SA_DQS_DN<9>")
	)
	(segment
		(start 128.404874 -247.244362)
		(end 128.413256 -247.239536)
		(width 0.09525)
		(layer "In2.Cu")
		(net "M_I_CPU1_SA_DQS_DN<9>")
	)
	(segment
		(start 177.12563 -239.408208)
		(end 177.273966 -239.259872)
		(width 0.16002)
		(layer "In2.Cu")
		(net "M_I_CPU1_SA_DQS_DN<9>")
	)
	(segment
		(start 144.941798 -247.2309)
		(end 144.95653 -247.239536)
		(width 0.09525)
		(layer "In2.Cu")
		(net "M_I_CPU1_SA_DQS_DN<9>")
	)
	(segment
		(start 148.82749 -246.633746)
		(end 157.432248 -246.633746)
		(width 0.16002)
		(layer "In2.Cu")
		(net "M_I_CPU1_SA_DQS_DN<9>")
	)
	(segment
		(start 160.644078 -244.603016)
		(end 160.31718 -244.276118)
		(width 0.16002)
		(layer "In2.Cu")
		(net "M_I_CPU1_SA_DQS_DN<9>")
	)
	(segment
		(start 139.316206 -247.239536)
		(end 139.324588 -247.244362)
		(width 0.09525)
		(layer "In2.Cu")
		(net "M_I_CPU1_SA_DQS_DN<9>")
	)
	(segment
		(start 160.31718 -244.276118)
		(end 160.31718 -243.748814)
		(width 0.16002)
		(layer "In2.Cu")
		(net "M_I_CPU1_SA_DQS_DN<9>")
	)
	(segment
		(start 158.943548 -245.64975)
		(end 158.943548 -245.122446)
		(width 0.16002)
		(layer "In2.Cu")
		(net "M_I_CPU1_SA_DQS_DN<9>")
	)
	(segment
		(start 170.498008 -239.684306)
		(end 171.347892 -240.53419)
		(width 0.16002)
		(layer "In2.Cu")
		(net "M_I_CPU1_SA_DQS_DN<9>")
	)
	(segment
		(start 135.556244 -247.239536)
		(end 135.564626 -247.244362)
		(width 0.09525)
		(layer "In2.Cu")
		(net "M_I_CPU1_SA_DQS_DN<9>")
	)
	(segment
		(start 175.302418 -239.408208)
		(end 177.12563 -239.408208)
		(width 0.16002)
		(layer "In2.Cu")
		(net "M_I_CPU1_SA_DQS_DN<9>")
	)
	(segment
		(start 144.95653 -247.239536)
		(end 144.971008 -247.247918)
		(width 0.09525)
		(layer "In2.Cu")
		(net "M_I_CPU1_SA_DQS_DN<9>")
	)
	(segment
		(start 177.273966 -239.259872)
		(end 177.754026 -239.259872)
		(width 0.16002)
		(layer "In2.Cu")
		(net "M_I_CPU1_SA_DQS_DN<9>")
	)
	(segment
		(start 158.79699 -246.450104)
		(end 159.07385 -246.450104)
		(width 0.16002)
		(layer "In2.Cu")
		(net "M_I_CPU1_SA_DQS_DN<9>")
	)
	(segment
		(start 145.88236 -247.2309)
		(end 145.897092 -247.239536)
		(width 0.09525)
		(layer "In2.Cu")
		(net "M_I_CPU1_SA_DQS_DN<9>")
	)
	(segment
		(start 160.644078 -244.879876)
		(end 160.644078 -244.603016)
		(width 0.16002)
		(layer "In2.Cu")
		(net "M_I_CPU1_SA_DQS_DN<9>")
	)
	(segment
		(start 167.451024 -239.100868)
		(end 168.034462 -239.684306)
		(width 0.16002)
		(layer "In2.Cu")
		(net "M_I_CPU1_SA_DQS_DN<9>")
	)
	(segment
		(start 172.461428 -240.53419)
		(end 173.10227 -239.893348)
		(width 0.16002)
		(layer "In2.Cu")
		(net "M_I_CPU1_SA_DQS_DN<9>")
	)
	(segment
		(start 178.467766 -239.259872)
		(end 179.24145 -239.259872)
		(width 0.16002)
		(layer "In2.Cu")
		(net "M_I_CPU1_SA_DQS_DN<9>")
	)
	(segment
		(start 179.24145 -239.259872)
		(end 179.516024 -238.985298)
		(width 0.16002)
		(layer "In2.Cu")
		(net "M_I_CPU1_SA_DQS_DN<9>")
	)
	(arc
		(start 138.753342 -247.239536)
		(mid 139.034774 -247.163781)
		(end 139.316206 -247.239536)
		(width 0.09525)
		(layer "In2.Cu")
		(net "M_I_CPU1_SA_DQS_DN<9>")
	)
	(arc
		(start 137.436098 -247.239536)
		(mid 137.619873 -247.290308)
		(end 137.804906 -247.244362)
		(width 0.09525)
		(layer "In2.Cu")
		(net "M_I_CPU1_SA_DQS_DN<9>")
	)
	(arc
		(start 141.196314 -247.239536)
		(mid 141.384782 -247.290213)
		(end 141.57325 -247.239536)
		(width 0.09525)
		(layer "In2.Cu")
		(net "M_I_CPU1_SA_DQS_DN<9>")
	)
	(arc
		(start 145.897092 -247.239536)
		(mid 145.988058 -247.277689)
		(end 146.085814 -247.290844)
		(width 0.09525)
		(layer "In2.Cu")
		(net "M_I_CPU1_SA_DQS_DN<9>")
	)
	(arc
		(start 144.971008 -247.247918)
		(mid 145.15344 -247.290358)
		(end 145.33372 -247.239536)
		(width 0.09525)
		(layer "In2.Cu")
		(net "M_I_CPU1_SA_DQS_DN<9>")
	)
	(arc
		(start 129.35331 -247.239536)
		(mid 129.634742 -247.163781)
		(end 129.916174 -247.239536)
		(width 0.09525)
		(layer "In2.Cu")
		(net "M_I_CPU1_SA_DQS_DN<9>")
	)
	(arc
		(start 141.57325 -247.239536)
		(mid 141.854682 -247.163781)
		(end 142.136114 -247.239536)
		(width 0.09525)
		(layer "In2.Cu")
		(net "M_I_CPU1_SA_DQS_DN<9>")
	)
	(arc
		(start 132.173218 -247.239536)
		(mid 132.45465 -247.163781)
		(end 132.736082 -247.239536)
		(width 0.09525)
		(layer "In2.Cu")
		(net "M_I_CPU1_SA_DQS_DN<9>")
	)
	(arc
		(start 133.676136 -247.239536)
		(mid 133.859911 -247.290308)
		(end 134.044944 -247.244362)
		(width 0.09525)
		(layer "In2.Cu")
		(net "M_I_CPU1_SA_DQS_DN<9>")
	)
	(arc
		(start 144.01673 -247.239536)
		(mid 144.1986 -247.290401)
		(end 144.382236 -247.246394)
		(width 0.09525)
		(layer "In2.Cu")
		(net "M_I_CPU1_SA_DQS_DN<9>")
	)
	(arc
		(start 134.99338 -247.239536)
		(mid 135.274812 -247.163781)
		(end 135.556244 -247.239536)
		(width 0.09525)
		(layer "In2.Cu")
		(net "M_I_CPU1_SA_DQS_DN<9>")
	)
	(arc
		(start 133.113272 -247.239536)
		(mid 133.394704 -247.163781)
		(end 133.676136 -247.239536)
		(width 0.09525)
		(layer "In2.Cu")
		(net "M_I_CPU1_SA_DQS_DN<9>")
	)
	(arc
		(start 130.86461 -247.244362)
		(mid 131.049642 -247.290276)
		(end 131.233418 -247.239536)
		(width 0.09525)
		(layer "In2.Cu")
		(net "M_I_CPU1_SA_DQS_DN<9>")
	)
	(arc
		(start 139.324588 -247.244362)
		(mid 139.50962 -247.290276)
		(end 139.693396 -247.239536)
		(width 0.09525)
		(layer "In2.Cu")
		(net "M_I_CPU1_SA_DQS_DN<9>")
	)
	(arc
		(start 136.496298 -247.239536)
		(mid 136.684766 -247.290213)
		(end 136.873234 -247.239536)
		(width 0.09525)
		(layer "In2.Cu")
		(net "M_I_CPU1_SA_DQS_DN<9>")
	)
	(arc
		(start 135.933434 -247.239536)
		(mid 136.214866 -247.163781)
		(end 136.496298 -247.239536)
		(width 0.09525)
		(layer "In2.Cu")
		(net "M_I_CPU1_SA_DQS_DN<9>")
	)
	(arc
		(start 132.736082 -247.239536)
		(mid 132.919857 -247.290308)
		(end 133.10489 -247.244362)
		(width 0.09525)
		(layer "In2.Cu")
		(net "M_I_CPU1_SA_DQS_DN<9>")
	)
	(arc
		(start 136.873234 -247.239536)
		(mid 137.154666 -247.163781)
		(end 137.436098 -247.239536)
		(width 0.09525)
		(layer "In2.Cu")
		(net "M_I_CPU1_SA_DQS_DN<9>")
	)
	(arc
		(start 134.053326 -247.239536)
		(mid 134.334758 -247.163781)
		(end 134.61619 -247.239536)
		(width 0.09525)
		(layer "In2.Cu")
		(net "M_I_CPU1_SA_DQS_DN<9>")
	)
	(arc
		(start 131.796282 -247.239536)
		(mid 131.98475 -247.290213)
		(end 132.173218 -247.239536)
		(width 0.09525)
		(layer "In2.Cu")
		(net "M_I_CPU1_SA_DQS_DN<9>")
	)
	(arc
		(start 128.413256 -247.239536)
		(mid 128.694688 -247.163781)
		(end 128.97612 -247.239536)
		(width 0.09525)
		(layer "In2.Cu")
		(net "M_I_CPU1_SA_DQS_DN<9>")
	)
	(arc
		(start 128.094232 -247.266714)
		(mid 128.251982 -247.289233)
		(end 128.404874 -247.244362)
		(width 0.09525)
		(layer "In2.Cu")
		(net "M_I_CPU1_SA_DQS_DN<9>")
	)
	(arc
		(start 143.08455 -247.244362)
		(mid 143.269582 -247.290276)
		(end 143.453358 -247.239536)
		(width 0.09525)
		(layer "In2.Cu")
		(net "M_I_CPU1_SA_DQS_DN<9>")
	)
	(arc
		(start 145.33372 -247.239536)
		(mid 145.606902 -247.163594)
		(end 145.88236 -247.2309)
		(width 0.09525)
		(layer "In2.Cu")
		(net "M_I_CPU1_SA_DQS_DN<9>")
	)
	(arc
		(start 128.97612 -247.239536)
		(mid 129.159895 -247.290308)
		(end 129.344928 -247.244362)
		(width 0.09525)
		(layer "In2.Cu")
		(net "M_I_CPU1_SA_DQS_DN<9>")
	)
	(arc
		(start 140.63345 -247.239536)
		(mid 140.914882 -247.163781)
		(end 141.196314 -247.239536)
		(width 0.09525)
		(layer "In2.Cu")
		(net "M_I_CPU1_SA_DQS_DN<9>")
	)
	(arc
		(start 135.564626 -247.244362)
		(mid 135.749658 -247.290276)
		(end 135.933434 -247.239536)
		(width 0.09525)
		(layer "In2.Cu")
		(net "M_I_CPU1_SA_DQS_DN<9>")
	)
	(arc
		(start 131.233418 -247.239536)
		(mid 131.51485 -247.163781)
		(end 131.796282 -247.239536)
		(width 0.09525)
		(layer "In2.Cu")
		(net "M_I_CPU1_SA_DQS_DN<9>")
	)
	(arc
		(start 140.264642 -247.244362)
		(mid 140.449674 -247.290276)
		(end 140.63345 -247.239536)
		(width 0.09525)
		(layer "In2.Cu")
		(net "M_I_CPU1_SA_DQS_DN<9>")
	)
	(arc
		(start 130.293364 -247.239536)
		(mid 130.574796 -247.163781)
		(end 130.856228 -247.239536)
		(width 0.09525)
		(layer "In2.Cu")
		(net "M_I_CPU1_SA_DQS_DN<9>")
	)
	(arc
		(start 137.813288 -247.239536)
		(mid 138.09472 -247.163781)
		(end 138.376152 -247.239536)
		(width 0.09525)
		(layer "In2.Cu")
		(net "M_I_CPU1_SA_DQS_DN<9>")
	)
	(arc
		(start 138.376152 -247.239536)
		(mid 138.559927 -247.290308)
		(end 138.74496 -247.244362)
		(width 0.09525)
		(layer "In2.Cu")
		(net "M_I_CPU1_SA_DQS_DN<9>")
	)
	(arc
		(start 134.624572 -247.244362)
		(mid 134.809604 -247.290276)
		(end 134.99338 -247.239536)
		(width 0.09525)
		(layer "In2.Cu")
		(net "M_I_CPU1_SA_DQS_DN<9>")
	)
	(arc
		(start 144.394174 -247.239536)
		(mid 144.666848 -247.163849)
		(end 144.941798 -247.2309)
		(width 0.09525)
		(layer "In2.Cu")
		(net "M_I_CPU1_SA_DQS_DN<9>")
	)
	(arc
		(start 139.693396 -247.239536)
		(mid 139.974828 -247.163781)
		(end 140.25626 -247.239536)
		(width 0.09525)
		(layer "In2.Cu")
		(net "M_I_CPU1_SA_DQS_DN<9>")
	)
	(arc
		(start 129.924556 -247.244362)
		(mid 130.109588 -247.290276)
		(end 130.293364 -247.239536)
		(width 0.09525)
		(layer "In2.Cu")
		(net "M_I_CPU1_SA_DQS_DN<9>")
	)
	(arc
		(start 142.513304 -247.239536)
		(mid 142.794736 -247.163781)
		(end 143.076168 -247.239536)
		(width 0.09525)
		(layer "In2.Cu")
		(net "M_I_CPU1_SA_DQS_DN<9>")
	)
	(arc
		(start 143.46809 -247.2309)
		(mid 143.743549 -247.163515)
		(end 144.01673 -247.239536)
		(width 0.09525)
		(layer "In2.Cu")
		(net "M_I_CPU1_SA_DQS_DN<9>")
	)
	(arc
		(start 142.136114 -247.239536)
		(mid 142.319889 -247.290308)
		(end 142.504922 -247.244362)
		(width 0.09525)
		(layer "In2.Cu")
		(net "M_I_CPU1_SA_DQS_DN<9>")
	)
	(segment
		(start 127.757936 -242.320318)
		(end 128.224788 -242.05438)
		(width 0.12954)
		(layer "F.Cu")
		(net "M_I_CPU1_SA_DQS_DN<8>")
	)
	(segment
		(start 177.273966 -229.909878)
		(end 177.87366 -229.909878)
		(width 0.16002)
		(layer "In2.Cu")
		(net "M_I_CPU1_SA_DQS_DN<8>")
	)
	(segment
		(start 153.326084 -239.1029)
		(end 153.85288 -239.103154)
		(width 0.16002)
		(layer "In2.Cu")
		(net "M_I_CPU1_SA_DQS_DN<8>")
	)
	(segment
		(start 179.24145 -229.909878)
		(end 179.516024 -229.635304)
		(width 0.16002)
		(layer "In2.Cu")
		(net "M_I_CPU1_SA_DQS_DN<8>")
	)
	(segment
		(start 177.12563 -230.058214)
		(end 177.273966 -229.909878)
		(width 0.16002)
		(layer "In2.Cu")
		(net "M_I_CPU1_SA_DQS_DN<8>")
	)
	(segment
		(start 129.344928 -242.384326)
		(end 129.35331 -242.3795)
		(width 0.09525)
		(layer "In2.Cu")
		(net "M_I_CPU1_SA_DQS_DN<8>")
	)
	(segment
		(start 172.737272 -230.908352)
		(end 173.10227 -230.543354)
		(width 0.16002)
		(layer "In2.Cu")
		(net "M_I_CPU1_SA_DQS_DN<8>")
	)
	(segment
		(start 140.25626 -242.3795)
		(end 140.264642 -242.384326)
		(width 0.09525)
		(layer "In2.Cu")
		(net "M_I_CPU1_SA_DQS_DN<8>")
	)
	(segment
		(start 155.975304 -237.809786)
		(end 155.975304 -237.532926)
		(width 0.16002)
		(layer "In2.Cu")
		(net "M_I_CPU1_SA_DQS_DN<8>")
	)
	(segment
		(start 154.325828 -238.103156)
		(end 154.699716 -237.729268)
		(width 0.16002)
		(layer "In2.Cu")
		(net "M_I_CPU1_SA_DQS_DN<8>")
	)
	(segment
		(start 147.11045 -241.663474)
		(end 147.11045 -241.223546)
		(width 0.09525)
		(layer "In2.Cu")
		(net "M_I_CPU1_SA_DQS_DN<8>")
	)
	(segment
		(start 143.453358 -242.3795)
		(end 143.463772 -242.373404)
		(width 0.09525)
		(layer "In2.Cu")
		(net "M_I_CPU1_SA_DQS_DN<8>")
	)
	(segment
		(start 177.87366 -229.909878)
		(end 177.9905 -229.793038)
		(width 0.16002)
		(layer "In2.Cu")
		(net "M_I_CPU1_SA_DQS_DN<8>")
	)
	(segment
		(start 153.22804 -240.55705)
		(end 153.22804 -240.28019)
		(width 0.16002)
		(layer "In2.Cu")
		(net "M_I_CPU1_SA_DQS_DN<8>")
	)
	(segment
		(start 147.722336 -240.953544)
		(end 147.745958 -240.953544)
		(width 0.09525)
		(layer "In2.Cu")
		(net "M_I_CPU1_SA_DQS_DN<8>")
	)
	(segment
		(start 130.856228 -242.3795)
		(end 130.86461 -242.384326)
		(width 0.09525)
		(layer "In2.Cu")
		(net "M_I_CPU1_SA_DQS_DN<8>")
	)
	(segment
		(start 154.405838 -239.379252)
		(end 154.601672 -239.183418)
		(width 0.16002)
		(layer "In2.Cu")
		(net "M_I_CPU1_SA_DQS_DN<8>")
	)
	(segment
		(start 152.951942 -240.004092)
		(end 152.952196 -239.476788)
		(width 0.16002)
		(layer "In2.Cu")
		(net "M_I_CPU1_SA_DQS_DN<8>")
	)
	(segment
		(start 178.5874 -229.909878)
		(end 179.24145 -229.909878)
		(width 0.16002)
		(layer "In2.Cu")
		(net "M_I_CPU1_SA_DQS_DN<8>")
	)
	(segment
		(start 154.601672 -238.906558)
		(end 154.325574 -238.63046)
		(width 0.16002)
		(layer "In2.Cu")
		(net "M_I_CPU1_SA_DQS_DN<8>")
	)
	(segment
		(start 143.076168 -242.3795)
		(end 143.08455 -242.384326)
		(width 0.09525)
		(layer "In2.Cu")
		(net "M_I_CPU1_SA_DQS_DN<8>")
	)
	(segment
		(start 128.070864 -242.31981)
		(end 128.094232 -242.406678)
		(width 0.09525)
		(layer "In2.Cu")
		(net "M_I_CPU1_SA_DQS_DN<8>")
	)
	(segment
		(start 175.302418 -230.058214)
		(end 177.12563 -230.058214)
		(width 0.16002)
		(layer "In2.Cu")
		(net "M_I_CPU1_SA_DQS_DN<8>")
	)
	(segment
		(start 157.153102 -236.631988)
		(end 162.876992 -230.908098)
		(width 0.16002)
		(layer "In2.Cu")
		(net "M_I_CPU1_SA_DQS_DN<8>")
	)
	(segment
		(start 142.504922 -242.384326)
		(end 142.513304 -242.3795)
		(width 0.09525)
		(layer "In2.Cu")
		(net "M_I_CPU1_SA_DQS_DN<8>")
	)
	(segment
		(start 144.385792 -242.384326)
		(end 144.394174 -242.3795)
		(width 0.09525)
		(layer "In2.Cu")
		(net "M_I_CPU1_SA_DQS_DN<8>")
	)
	(segment
		(start 147.11045 -241.223546)
		(end 147.32127 -241.012726)
		(width 0.09525)
		(layer "In2.Cu")
		(net "M_I_CPU1_SA_DQS_DN<8>")
	)
	(segment
		(start 128.404874 -242.384326)
		(end 128.413256 -242.3795)
		(width 0.09525)
		(layer "In2.Cu")
		(net "M_I_CPU1_SA_DQS_DN<8>")
	)
	(segment
		(start 167.451024 -229.750874)
		(end 167.758364 -230.058214)
		(width 0.16002)
		(layer "In2.Cu")
		(net "M_I_CPU1_SA_DQS_DN<8>")
	)
	(segment
		(start 155.69946 -236.729524)
		(end 156.073348 -236.355636)
		(width 0.16002)
		(layer "In2.Cu")
		(net "M_I_CPU1_SA_DQS_DN<8>")
	)
	(segment
		(start 153.22804 -240.28019)
		(end 152.951942 -240.004092)
		(width 0.16002)
		(layer "In2.Cu")
		(net "M_I_CPU1_SA_DQS_DN<8>")
	)
	(segment
		(start 155.226512 -237.729522)
		(end 155.50261 -238.00562)
		(width 0.16002)
		(layer "In2.Cu")
		(net "M_I_CPU1_SA_DQS_DN<8>")
	)
	(segment
		(start 154.128978 -239.379252)
		(end 154.405838 -239.379252)
		(width 0.16002)
		(layer "In2.Cu")
		(net "M_I_CPU1_SA_DQS_DN<8>")
	)
	(segment
		(start 174.995078 -229.750874)
		(end 175.302418 -230.058214)
		(width 0.16002)
		(layer "In2.Cu")
		(net "M_I_CPU1_SA_DQS_DN<8>")
	)
	(segment
		(start 137.804906 -242.384326)
		(end 137.813288 -242.3795)
		(width 0.09525)
		(layer "In2.Cu")
		(net "M_I_CPU1_SA_DQS_DN<8>")
	)
	(segment
		(start 165.193472 -230.908098)
		(end 165.558216 -230.543354)
		(width 0.16002)
		(layer "In2.Cu")
		(net "M_I_CPU1_SA_DQS_DN<8>")
	)
	(segment
		(start 135.556244 -242.3795)
		(end 135.564626 -242.384326)
		(width 0.09525)
		(layer "In2.Cu")
		(net "M_I_CPU1_SA_DQS_DN<8>")
	)
	(segment
		(start 155.699206 -237.256828)
		(end 155.69946 -236.729524)
		(width 0.16002)
		(layer "In2.Cu")
		(net "M_I_CPU1_SA_DQS_DN<8>")
	)
	(segment
		(start 146.093688 -242.078764)
		(end 146.228308 -241.944144)
		(width 0.09525)
		(layer "In2.Cu")
		(net "M_I_CPU1_SA_DQS_DN<8>")
	)
	(segment
		(start 162.876992 -230.908098)
		(end 165.193472 -230.908098)
		(width 0.16002)
		(layer "In2.Cu")
		(net "M_I_CPU1_SA_DQS_DN<8>")
	)
	(segment
		(start 173.10227 -230.543354)
		(end 173.53915 -230.543354)
		(width 0.16002)
		(layer "In2.Cu")
		(net "M_I_CPU1_SA_DQS_DN<8>")
	)
	(segment
		(start 133.10489 -242.384326)
		(end 133.113272 -242.3795)
		(width 0.09525)
		(layer "In2.Cu")
		(net "M_I_CPU1_SA_DQS_DN<8>")
	)
	(segment
		(start 139.316206 -242.3795)
		(end 139.324588 -242.384326)
		(width 0.09525)
		(layer "In2.Cu")
		(net "M_I_CPU1_SA_DQS_DN<8>")
	)
	(segment
		(start 153.85288 -239.103154)
		(end 154.128978 -239.379252)
		(width 0.16002)
		(layer "In2.Cu")
		(net "M_I_CPU1_SA_DQS_DN<8>")
	)
	(segment
		(start 174.33163 -229.750874)
		(end 174.995078 -229.750874)
		(width 0.16002)
		(layer "In2.Cu")
		(net "M_I_CPU1_SA_DQS_DN<8>")
	)
	(segment
		(start 177.9905 -229.793038)
		(end 178.47056 -229.793038)
		(width 0.16002)
		(layer "In2.Cu")
		(net "M_I_CPU1_SA_DQS_DN<8>")
	)
	(segment
		(start 145.41119 -242.320826)
		(end 145.653252 -242.078764)
		(width 0.09525)
		(layer "In2.Cu")
		(net "M_I_CPU1_SA_DQS_DN<8>")
	)
	(segment
		(start 134.044944 -242.384326)
		(end 134.053326 -242.3795)
		(width 0.09525)
		(layer "In2.Cu")
		(net "M_I_CPU1_SA_DQS_DN<8>")
	)
	(segment
		(start 152.952196 -239.476788)
		(end 153.326084 -239.1029)
		(width 0.16002)
		(layer "In2.Cu")
		(net "M_I_CPU1_SA_DQS_DN<8>")
	)
	(segment
		(start 155.975304 -237.532926)
		(end 155.699206 -237.256828)
		(width 0.16002)
		(layer "In2.Cu")
		(net "M_I_CPU1_SA_DQS_DN<8>")
	)
	(segment
		(start 146.228308 -241.944144)
		(end 146.82978 -241.944144)
		(width 0.09525)
		(layer "In2.Cu")
		(net "M_I_CPU1_SA_DQS_DN<8>")
	)
	(segment
		(start 171.072048 -230.908352)
		(end 172.737272 -230.908352)
		(width 0.16002)
		(layer "In2.Cu")
		(net "M_I_CPU1_SA_DQS_DN<8>")
	)
	(segment
		(start 166.787576 -229.750874)
		(end 167.451024 -229.750874)
		(width 0.16002)
		(layer "In2.Cu")
		(net "M_I_CPU1_SA_DQS_DN<8>")
	)
	(segment
		(start 144.95653 -242.3795)
		(end 144.971008 -242.387882)
		(width 0.09525)
		(layer "In2.Cu")
		(net "M_I_CPU1_SA_DQS_DN<8>")
	)
	(segment
		(start 154.325574 -238.63046)
		(end 154.325828 -238.103156)
		(width 0.16002)
		(layer "In2.Cu")
		(net "M_I_CPU1_SA_DQS_DN<8>")
	)
	(segment
		(start 170.22191 -230.058214)
		(end 171.072048 -230.908352)
		(width 0.16002)
		(layer "In2.Cu")
		(net "M_I_CPU1_SA_DQS_DN<8>")
	)
	(segment
		(start 154.601672 -239.183418)
		(end 154.601672 -238.906558)
		(width 0.16002)
		(layer "In2.Cu")
		(net "M_I_CPU1_SA_DQS_DN<8>")
	)
	(segment
		(start 165.995096 -230.543354)
		(end 166.787576 -229.750874)
		(width 0.16002)
		(layer "In2.Cu")
		(net "M_I_CPU1_SA_DQS_DN<8>")
	)
	(segment
		(start 156.600144 -236.35589)
		(end 156.876242 -236.631988)
		(width 0.16002)
		(layer "In2.Cu")
		(net "M_I_CPU1_SA_DQS_DN<8>")
	)
	(segment
		(start 156.876242 -236.631988)
		(end 157.153102 -236.631988)
		(width 0.16002)
		(layer "In2.Cu")
		(net "M_I_CPU1_SA_DQS_DN<8>")
	)
	(segment
		(start 146.82978 -241.944144)
		(end 147.11045 -241.663474)
		(width 0.09525)
		(layer "In2.Cu")
		(net "M_I_CPU1_SA_DQS_DN<8>")
	)
	(segment
		(start 138.74496 -242.384326)
		(end 138.753342 -242.3795)
		(width 0.09525)
		(layer "In2.Cu")
		(net "M_I_CPU1_SA_DQS_DN<8>")
	)
	(segment
		(start 147.745958 -240.953544)
		(end 152.831546 -240.953544)
		(width 0.16002)
		(layer "In2.Cu")
		(net "M_I_CPU1_SA_DQS_DN<8>")
	)
	(segment
		(start 128.224788 -242.05438)
		(end 128.070864 -242.31981)
		(width 0.09525)
		(layer "In2.Cu")
		(net "M_I_CPU1_SA_DQS_DN<8>")
	)
	(segment
		(start 155.77947 -238.00562)
		(end 155.975304 -237.809786)
		(width 0.16002)
		(layer "In2.Cu")
		(net "M_I_CPU1_SA_DQS_DN<8>")
	)
	(segment
		(start 144.941798 -242.370864)
		(end 144.95653 -242.3795)
		(width 0.09525)
		(layer "In2.Cu")
		(net "M_I_CPU1_SA_DQS_DN<8>")
	)
	(segment
		(start 156.073348 -236.355636)
		(end 156.600144 -236.35589)
		(width 0.16002)
		(layer "In2.Cu")
		(net "M_I_CPU1_SA_DQS_DN<8>")
	)
	(segment
		(start 165.558216 -230.543354)
		(end 165.995096 -230.543354)
		(width 0.16002)
		(layer "In2.Cu")
		(net "M_I_CPU1_SA_DQS_DN<8>")
	)
	(segment
		(start 134.61619 -242.3795)
		(end 134.624572 -242.384326)
		(width 0.09525)
		(layer "In2.Cu")
		(net "M_I_CPU1_SA_DQS_DN<8>")
	)
	(segment
		(start 173.53915 -230.543354)
		(end 174.33163 -229.750874)
		(width 0.16002)
		(layer "In2.Cu")
		(net "M_I_CPU1_SA_DQS_DN<8>")
	)
	(segment
		(start 147.663154 -241.012726)
		(end 147.722336 -240.953544)
		(width 0.09525)
		(layer "In2.Cu")
		(net "M_I_CPU1_SA_DQS_DN<8>")
	)
	(segment
		(start 152.831546 -240.953544)
		(end 153.22804 -240.55705)
		(width 0.16002)
		(layer "In2.Cu")
		(net "M_I_CPU1_SA_DQS_DN<8>")
	)
	(segment
		(start 154.699716 -237.729268)
		(end 155.226512 -237.729522)
		(width 0.16002)
		(layer "In2.Cu")
		(net "M_I_CPU1_SA_DQS_DN<8>")
	)
	(segment
		(start 155.50261 -238.00562)
		(end 155.77947 -238.00562)
		(width 0.16002)
		(layer "In2.Cu")
		(net "M_I_CPU1_SA_DQS_DN<8>")
	)
	(segment
		(start 178.47056 -229.793038)
		(end 178.5874 -229.909878)
		(width 0.16002)
		(layer "In2.Cu")
		(net "M_I_CPU1_SA_DQS_DN<8>")
	)
	(segment
		(start 145.653252 -242.078764)
		(end 146.093688 -242.078764)
		(width 0.09525)
		(layer "In2.Cu")
		(net "M_I_CPU1_SA_DQS_DN<8>")
	)
	(segment
		(start 129.916174 -242.3795)
		(end 129.924556 -242.384326)
		(width 0.09525)
		(layer "In2.Cu")
		(net "M_I_CPU1_SA_DQS_DN<8>")
	)
	(segment
		(start 147.32127 -241.012726)
		(end 147.663154 -241.012726)
		(width 0.09525)
		(layer "In2.Cu")
		(net "M_I_CPU1_SA_DQS_DN<8>")
	)
	(segment
		(start 167.758364 -230.058214)
		(end 170.22191 -230.058214)
		(width 0.16002)
		(layer "In2.Cu")
		(net "M_I_CPU1_SA_DQS_DN<8>")
	)
	(arc
		(start 144.971008 -242.387882)
		(mid 145.15344 -242.430322)
		(end 145.33372 -242.3795)
		(width 0.09525)
		(layer "In2.Cu")
		(net "M_I_CPU1_SA_DQS_DN<8>")
	)
	(arc
		(start 128.97612 -242.3795)
		(mid 129.159895 -242.430272)
		(end 129.344928 -242.384326)
		(width 0.09525)
		(layer "In2.Cu")
		(net "M_I_CPU1_SA_DQS_DN<8>")
	)
	(arc
		(start 134.053326 -242.3795)
		(mid 134.334758 -242.303745)
		(end 134.61619 -242.3795)
		(width 0.09525)
		(layer "In2.Cu")
		(net "M_I_CPU1_SA_DQS_DN<8>")
	)
	(arc
		(start 140.264642 -242.384326)
		(mid 140.449674 -242.43024)
		(end 140.63345 -242.3795)
		(width 0.09525)
		(layer "In2.Cu")
		(net "M_I_CPU1_SA_DQS_DN<8>")
	)
	(arc
		(start 138.376152 -242.3795)
		(mid 138.559927 -242.430272)
		(end 138.74496 -242.384326)
		(width 0.09525)
		(layer "In2.Cu")
		(net "M_I_CPU1_SA_DQS_DN<8>")
	)
	(arc
		(start 145.33372 -242.3795)
		(mid 145.374352 -242.352669)
		(end 145.41119 -242.320826)
		(width 0.09525)
		(layer "In2.Cu")
		(net "M_I_CPU1_SA_DQS_DN<8>")
	)
	(arc
		(start 143.08455 -242.384326)
		(mid 143.269582 -242.43024)
		(end 143.453358 -242.3795)
		(width 0.09525)
		(layer "In2.Cu")
		(net "M_I_CPU1_SA_DQS_DN<8>")
	)
	(arc
		(start 142.513304 -242.3795)
		(mid 142.794736 -242.303745)
		(end 143.076168 -242.3795)
		(width 0.09525)
		(layer "In2.Cu")
		(net "M_I_CPU1_SA_DQS_DN<8>")
	)
	(arc
		(start 132.736082 -242.3795)
		(mid 132.919857 -242.430272)
		(end 133.10489 -242.384326)
		(width 0.09525)
		(layer "In2.Cu")
		(net "M_I_CPU1_SA_DQS_DN<8>")
	)
	(arc
		(start 130.293364 -242.3795)
		(mid 130.574796 -242.303745)
		(end 130.856228 -242.3795)
		(width 0.09525)
		(layer "In2.Cu")
		(net "M_I_CPU1_SA_DQS_DN<8>")
	)
	(arc
		(start 137.436098 -242.3795)
		(mid 137.619873 -242.430272)
		(end 137.804906 -242.384326)
		(width 0.09525)
		(layer "In2.Cu")
		(net "M_I_CPU1_SA_DQS_DN<8>")
	)
	(arc
		(start 133.113272 -242.3795)
		(mid 133.394704 -242.303745)
		(end 133.676136 -242.3795)
		(width 0.09525)
		(layer "In2.Cu")
		(net "M_I_CPU1_SA_DQS_DN<8>")
	)
	(arc
		(start 134.624572 -242.384326)
		(mid 134.809604 -242.43024)
		(end 134.99338 -242.3795)
		(width 0.09525)
		(layer "In2.Cu")
		(net "M_I_CPU1_SA_DQS_DN<8>")
	)
	(arc
		(start 132.173218 -242.3795)
		(mid 132.45465 -242.303745)
		(end 132.736082 -242.3795)
		(width 0.09525)
		(layer "In2.Cu")
		(net "M_I_CPU1_SA_DQS_DN<8>")
	)
	(arc
		(start 129.35331 -242.3795)
		(mid 129.634742 -242.303745)
		(end 129.916174 -242.3795)
		(width 0.09525)
		(layer "In2.Cu")
		(net "M_I_CPU1_SA_DQS_DN<8>")
	)
	(arc
		(start 133.676136 -242.3795)
		(mid 133.859911 -242.430272)
		(end 134.044944 -242.384326)
		(width 0.09525)
		(layer "In2.Cu")
		(net "M_I_CPU1_SA_DQS_DN<8>")
	)
	(arc
		(start 134.99338 -242.3795)
		(mid 135.274812 -242.303745)
		(end 135.556244 -242.3795)
		(width 0.09525)
		(layer "In2.Cu")
		(net "M_I_CPU1_SA_DQS_DN<8>")
	)
	(arc
		(start 135.564626 -242.384326)
		(mid 135.749658 -242.43024)
		(end 135.933434 -242.3795)
		(width 0.09525)
		(layer "In2.Cu")
		(net "M_I_CPU1_SA_DQS_DN<8>")
	)
	(arc
		(start 128.413256 -242.3795)
		(mid 128.694688 -242.303745)
		(end 128.97612 -242.3795)
		(width 0.09525)
		(layer "In2.Cu")
		(net "M_I_CPU1_SA_DQS_DN<8>")
	)
	(arc
		(start 138.753342 -242.3795)
		(mid 139.034774 -242.303745)
		(end 139.316206 -242.3795)
		(width 0.09525)
		(layer "In2.Cu")
		(net "M_I_CPU1_SA_DQS_DN<8>")
	)
	(arc
		(start 137.813288 -242.3795)
		(mid 138.09472 -242.303745)
		(end 138.376152 -242.3795)
		(width 0.09525)
		(layer "In2.Cu")
		(net "M_I_CPU1_SA_DQS_DN<8>")
	)
	(arc
		(start 142.136114 -242.3795)
		(mid 142.319889 -242.430272)
		(end 142.504922 -242.384326)
		(width 0.09525)
		(layer "In2.Cu")
		(net "M_I_CPU1_SA_DQS_DN<8>")
	)
	(arc
		(start 130.86461 -242.384326)
		(mid 131.049642 -242.43024)
		(end 131.233418 -242.3795)
		(width 0.09525)
		(layer "In2.Cu")
		(net "M_I_CPU1_SA_DQS_DN<8>")
	)
	(arc
		(start 128.094232 -242.406678)
		(mid 128.251982 -242.429197)
		(end 128.404874 -242.384326)
		(width 0.09525)
		(layer "In2.Cu")
		(net "M_I_CPU1_SA_DQS_DN<8>")
	)
	(arc
		(start 129.924556 -242.384326)
		(mid 130.109588 -242.43024)
		(end 130.293364 -242.3795)
		(width 0.09525)
		(layer "In2.Cu")
		(net "M_I_CPU1_SA_DQS_DN<8>")
	)
	(arc
		(start 139.324588 -242.384326)
		(mid 139.50962 -242.43024)
		(end 139.693396 -242.3795)
		(width 0.09525)
		(layer "In2.Cu")
		(net "M_I_CPU1_SA_DQS_DN<8>")
	)
	(arc
		(start 139.693396 -242.3795)
		(mid 139.974828 -242.303745)
		(end 140.25626 -242.3795)
		(width 0.09525)
		(layer "In2.Cu")
		(net "M_I_CPU1_SA_DQS_DN<8>")
	)
	(arc
		(start 131.233418 -242.3795)
		(mid 131.51485 -242.303745)
		(end 131.796282 -242.3795)
		(width 0.09525)
		(layer "In2.Cu")
		(net "M_I_CPU1_SA_DQS_DN<8>")
	)
	(arc
		(start 144.394174 -242.3795)
		(mid 144.666848 -242.303813)
		(end 144.941798 -242.370864)
		(width 0.09525)
		(layer "In2.Cu")
		(net "M_I_CPU1_SA_DQS_DN<8>")
	)
	(arc
		(start 136.873234 -242.3795)
		(mid 137.154666 -242.303745)
		(end 137.436098 -242.3795)
		(width 0.09525)
		(layer "In2.Cu")
		(net "M_I_CPU1_SA_DQS_DN<8>")
	)
	(arc
		(start 140.63345 -242.3795)
		(mid 140.914882 -242.303745)
		(end 141.196314 -242.3795)
		(width 0.09525)
		(layer "In2.Cu")
		(net "M_I_CPU1_SA_DQS_DN<8>")
	)
	(arc
		(start 141.196314 -242.3795)
		(mid 141.384782 -242.430177)
		(end 141.57325 -242.3795)
		(width 0.09525)
		(layer "In2.Cu")
		(net "M_I_CPU1_SA_DQS_DN<8>")
	)
	(arc
		(start 135.933434 -242.3795)
		(mid 136.214866 -242.303745)
		(end 136.496298 -242.3795)
		(width 0.09525)
		(layer "In2.Cu")
		(net "M_I_CPU1_SA_DQS_DN<8>")
	)
	(arc
		(start 131.796282 -242.3795)
		(mid 131.98475 -242.430177)
		(end 132.173218 -242.3795)
		(width 0.09525)
		(layer "In2.Cu")
		(net "M_I_CPU1_SA_DQS_DN<8>")
	)
	(arc
		(start 143.463772 -242.373404)
		(mid 143.740934 -242.303604)
		(end 144.016476 -242.3795)
		(width 0.09525)
		(layer "In2.Cu")
		(net "M_I_CPU1_SA_DQS_DN<8>")
	)
	(arc
		(start 144.016476 -242.3795)
		(mid 144.200505 -242.430399)
		(end 144.385792 -242.384326)
		(width 0.09525)
		(layer "In2.Cu")
		(net "M_I_CPU1_SA_DQS_DN<8>")
	)
	(arc
		(start 136.496298 -242.3795)
		(mid 136.684766 -242.430177)
		(end 136.873234 -242.3795)
		(width 0.09525)
		(layer "In2.Cu")
		(net "M_I_CPU1_SA_DQS_DN<8>")
	)
	(arc
		(start 141.57325 -242.3795)
		(mid 141.854682 -242.303745)
		(end 142.136114 -242.3795)
		(width 0.09525)
		(layer "In2.Cu")
		(net "M_I_CPU1_SA_DQS_DN<8>")
	)
	(segment
		(start 127.757936 -237.460282)
		(end 128.224788 -237.194344)
		(width 0.12954)
		(layer "F.Cu")
		(net "M_I_CPU1_SA_DQS_DN<7>")
	)
	(segment
		(start 153.61412 -230.07066)
		(end 153.61412 -229.543356)
		(width 0.16002)
		(layer "In2.Cu")
		(net "M_I_CPU1_SA_DQS_DN<7>")
	)
	(segment
		(start 147.693634 -235.070904)
		(end 147.717256 -235.070904)
		(width 0.09525)
		(layer "In2.Cu")
		(net "M_I_CPU1_SA_DQS_DN<7>")
	)
	(segment
		(start 144.83334 -236.693964)
		(end 145.07845 -236.592364)
		(width 0.09525)
		(layer "In2.Cu")
		(net "M_I_CPU1_SA_DQS_DN<7>")
	)
	(segment
		(start 152.039828 -232.18902)
		(end 152.316688 -232.18902)
		(width 0.16002)
		(layer "In2.Cu")
		(net "M_I_CPU1_SA_DQS_DN<7>")
	)
	(segment
		(start 177.79492 -220.559884)
		(end 177.91176 -220.443044)
		(width 0.16002)
		(layer "In2.Cu")
		(net "M_I_CPU1_SA_DQS_DN<7>")
	)
	(segment
		(start 138.74496 -237.52429)
		(end 138.753342 -237.519464)
		(width 0.09525)
		(layer "In2.Cu")
		(net "M_I_CPU1_SA_DQS_DN<7>")
	)
	(segment
		(start 150.666196 -233.562652)
		(end 150.943056 -233.562652)
		(width 0.16002)
		(layer "In2.Cu")
		(net "M_I_CPU1_SA_DQS_DN<7>")
	)
	(segment
		(start 139.316206 -237.519464)
		(end 139.324588 -237.52429)
		(width 0.09525)
		(layer "In2.Cu")
		(net "M_I_CPU1_SA_DQS_DN<7>")
	)
	(segment
		(start 177.12563 -220.70822)
		(end 177.273966 -220.559884)
		(width 0.16002)
		(layer "In2.Cu")
		(net "M_I_CPU1_SA_DQS_DN<7>")
	)
	(segment
		(start 143.73479 -237.443772)
		(end 143.914368 -237.443772)
		(width 0.09525)
		(layer "In2.Cu")
		(net "M_I_CPU1_SA_DQS_DN<7>")
	)
	(segment
		(start 147.176998 -235.130086)
		(end 147.634452 -235.130086)
		(width 0.09525)
		(layer "In2.Cu")
		(net "M_I_CPU1_SA_DQS_DN<7>")
	)
	(segment
		(start 177.273966 -220.559884)
		(end 177.79492 -220.559884)
		(width 0.16002)
		(layer "In2.Cu")
		(net "M_I_CPU1_SA_DQS_DN<7>")
	)
	(segment
		(start 134.61619 -237.519464)
		(end 134.624572 -237.52429)
		(width 0.09525)
		(layer "In2.Cu")
		(net "M_I_CPU1_SA_DQS_DN<7>")
	)
	(segment
		(start 143.076168 -237.519464)
		(end 143.08455 -237.52429)
		(width 0.09525)
		(layer "In2.Cu")
		(net "M_I_CPU1_SA_DQS_DN<7>")
	)
	(segment
		(start 152.614122 -230.543354)
		(end 153.141426 -230.543354)
		(width 0.16002)
		(layer "In2.Cu")
		(net "M_I_CPU1_SA_DQS_DN<7>")
	)
	(segment
		(start 130.856228 -237.519464)
		(end 130.86461 -237.52429)
		(width 0.09525)
		(layer "In2.Cu")
		(net "M_I_CPU1_SA_DQS_DN<7>")
	)
	(segment
		(start 178.39182 -220.443044)
		(end 178.50866 -220.559884)
		(width 0.16002)
		(layer "In2.Cu")
		(net "M_I_CPU1_SA_DQS_DN<7>")
	)
	(segment
		(start 152.316688 -232.18902)
		(end 152.512522 -231.993186)
		(width 0.16002)
		(layer "In2.Cu")
		(net "M_I_CPU1_SA_DQS_DN<7>")
	)
	(segment
		(start 149.765258 -234.74045)
		(end 149.765258 -234.46359)
		(width 0.16002)
		(layer "In2.Cu")
		(net "M_I_CPU1_SA_DQS_DN<7>")
	)
	(segment
		(start 149.493224 -233.664252)
		(end 149.866858 -233.290618)
		(width 0.16002)
		(layer "In2.Cu")
		(net "M_I_CPU1_SA_DQS_DN<7>")
	)
	(segment
		(start 167.451024 -220.40088)
		(end 167.758364 -220.70822)
		(width 0.16002)
		(layer "In2.Cu")
		(net "M_I_CPU1_SA_DQS_DN<7>")
	)
	(segment
		(start 153.886154 -230.342694)
		(end 153.61412 -230.07066)
		(width 0.16002)
		(layer "In2.Cu")
		(net "M_I_CPU1_SA_DQS_DN<7>")
	)
	(segment
		(start 170.22191 -220.70822)
		(end 171.071794 -221.558104)
		(width 0.16002)
		(layer "In2.Cu")
		(net "M_I_CPU1_SA_DQS_DN<7>")
	)
	(segment
		(start 151.767794 -231.916986)
		(end 152.039828 -232.18902)
		(width 0.16002)
		(layer "In2.Cu")
		(net "M_I_CPU1_SA_DQS_DN<7>")
	)
	(segment
		(start 171.071794 -221.558104)
		(end 172.737526 -221.558104)
		(width 0.16002)
		(layer "In2.Cu")
		(net "M_I_CPU1_SA_DQS_DN<7>")
	)
	(segment
		(start 179.24145 -220.559884)
		(end 179.516024 -220.28531)
		(width 0.16002)
		(layer "In2.Cu")
		(net "M_I_CPU1_SA_DQS_DN<7>")
	)
	(segment
		(start 147.717256 -235.070904)
		(end 149.434804 -235.070904)
		(width 0.16002)
		(layer "In2.Cu")
		(net "M_I_CPU1_SA_DQS_DN<7>")
	)
	(segment
		(start 153.41346 -230.815388)
		(end 153.69032 -230.815388)
		(width 0.16002)
		(layer "In2.Cu")
		(net "M_I_CPU1_SA_DQS_DN<7>")
	)
	(segment
		(start 165.995096 -221.19336)
		(end 166.787576 -220.40088)
		(width 0.16002)
		(layer "In2.Cu")
		(net "M_I_CPU1_SA_DQS_DN<7>")
	)
	(segment
		(start 149.434804 -235.070904)
		(end 149.765258 -234.74045)
		(width 0.16002)
		(layer "In2.Cu")
		(net "M_I_CPU1_SA_DQS_DN<7>")
	)
	(segment
		(start 145.07845 -236.592364)
		(end 145.71472 -236.592364)
		(width 0.09525)
		(layer "In2.Cu")
		(net "M_I_CPU1_SA_DQS_DN<7>")
	)
	(segment
		(start 140.25626 -237.519464)
		(end 140.264642 -237.52429)
		(width 0.09525)
		(layer "In2.Cu")
		(net "M_I_CPU1_SA_DQS_DN<7>")
	)
	(segment
		(start 149.866858 -233.290618)
		(end 150.394162 -233.290618)
		(width 0.16002)
		(layer "In2.Cu")
		(net "M_I_CPU1_SA_DQS_DN<7>")
	)
	(segment
		(start 153.886154 -230.619554)
		(end 153.886154 -230.342694)
		(width 0.16002)
		(layer "In2.Cu")
		(net "M_I_CPU1_SA_DQS_DN<7>")
	)
	(segment
		(start 152.512522 -231.716326)
		(end 152.240488 -231.444292)
		(width 0.16002)
		(layer "In2.Cu")
		(net "M_I_CPU1_SA_DQS_DN<7>")
	)
	(segment
		(start 145.71472 -236.592364)
		(end 147.176998 -235.130086)
		(width 0.09525)
		(layer "In2.Cu")
		(net "M_I_CPU1_SA_DQS_DN<7>")
	)
	(segment
		(start 153.61412 -229.543356)
		(end 161.599372 -221.558104)
		(width 0.16002)
		(layer "In2.Cu")
		(net "M_I_CPU1_SA_DQS_DN<7>")
	)
	(segment
		(start 165.558216 -221.19336)
		(end 165.995096 -221.19336)
		(width 0.16002)
		(layer "In2.Cu")
		(net "M_I_CPU1_SA_DQS_DN<7>")
	)
	(segment
		(start 144.25422 -237.273084)
		(end 144.83334 -236.693964)
		(width 0.09525)
		(layer "In2.Cu")
		(net "M_I_CPU1_SA_DQS_DN<7>")
	)
	(segment
		(start 150.394162 -233.290618)
		(end 150.666196 -233.562652)
		(width 0.16002)
		(layer "In2.Cu")
		(net "M_I_CPU1_SA_DQS_DN<7>")
	)
	(segment
		(start 147.634452 -235.130086)
		(end 147.693634 -235.070904)
		(width 0.09525)
		(layer "In2.Cu")
		(net "M_I_CPU1_SA_DQS_DN<7>")
	)
	(segment
		(start 152.512522 -231.993186)
		(end 152.512522 -231.716326)
		(width 0.16002)
		(layer "In2.Cu")
		(net "M_I_CPU1_SA_DQS_DN<7>")
	)
	(segment
		(start 152.240488 -230.916988)
		(end 152.614122 -230.543354)
		(width 0.16002)
		(layer "In2.Cu")
		(net "M_I_CPU1_SA_DQS_DN<7>")
	)
	(segment
		(start 150.866856 -232.29062)
		(end 151.24049 -231.916986)
		(width 0.16002)
		(layer "In2.Cu")
		(net "M_I_CPU1_SA_DQS_DN<7>")
	)
	(segment
		(start 167.758364 -220.70822)
		(end 170.22191 -220.70822)
		(width 0.16002)
		(layer "In2.Cu")
		(net "M_I_CPU1_SA_DQS_DN<7>")
	)
	(segment
		(start 149.493224 -234.191556)
		(end 149.493224 -233.664252)
		(width 0.16002)
		(layer "In2.Cu")
		(net "M_I_CPU1_SA_DQS_DN<7>")
	)
	(segment
		(start 151.24049 -231.916986)
		(end 151.767794 -231.916986)
		(width 0.16002)
		(layer "In2.Cu")
		(net "M_I_CPU1_SA_DQS_DN<7>")
	)
	(segment
		(start 129.344928 -237.52429)
		(end 129.35331 -237.519464)
		(width 0.09525)
		(layer "In2.Cu")
		(net "M_I_CPU1_SA_DQS_DN<7>")
	)
	(segment
		(start 172.737526 -221.558104)
		(end 173.10227 -221.19336)
		(width 0.16002)
		(layer "In2.Cu")
		(net "M_I_CPU1_SA_DQS_DN<7>")
	)
	(segment
		(start 150.943056 -233.562652)
		(end 151.13889 -233.366818)
		(width 0.16002)
		(layer "In2.Cu")
		(net "M_I_CPU1_SA_DQS_DN<7>")
	)
	(segment
		(start 161.599372 -221.558104)
		(end 165.193472 -221.558104)
		(width 0.16002)
		(layer "In2.Cu")
		(net "M_I_CPU1_SA_DQS_DN<7>")
	)
	(segment
		(start 153.141426 -230.543354)
		(end 153.41346 -230.815388)
		(width 0.16002)
		(layer "In2.Cu")
		(net "M_I_CPU1_SA_DQS_DN<7>")
	)
	(segment
		(start 135.556244 -237.519464)
		(end 135.564626 -237.52429)
		(width 0.09525)
		(layer "In2.Cu")
		(net "M_I_CPU1_SA_DQS_DN<7>")
	)
	(segment
		(start 153.69032 -230.815388)
		(end 153.886154 -230.619554)
		(width 0.16002)
		(layer "In2.Cu")
		(net "M_I_CPU1_SA_DQS_DN<7>")
	)
	(segment
		(start 173.53915 -221.19336)
		(end 174.33163 -220.40088)
		(width 0.16002)
		(layer "In2.Cu")
		(net "M_I_CPU1_SA_DQS_DN<7>")
	)
	(segment
		(start 128.224788 -237.194344)
		(end 128.070864 -237.459774)
		(width 0.09525)
		(layer "In2.Cu")
		(net "M_I_CPU1_SA_DQS_DN<7>")
	)
	(segment
		(start 178.50866 -220.559884)
		(end 179.24145 -220.559884)
		(width 0.16002)
		(layer "In2.Cu")
		(net "M_I_CPU1_SA_DQS_DN<7>")
	)
	(segment
		(start 165.193472 -221.558104)
		(end 165.558216 -221.19336)
		(width 0.16002)
		(layer "In2.Cu")
		(net "M_I_CPU1_SA_DQS_DN<7>")
	)
	(segment
		(start 128.070864 -237.459774)
		(end 128.094232 -237.546642)
		(width 0.09525)
		(layer "In2.Cu")
		(net "M_I_CPU1_SA_DQS_DN<7>")
	)
	(segment
		(start 166.787576 -220.40088)
		(end 167.451024 -220.40088)
		(width 0.16002)
		(layer "In2.Cu")
		(net "M_I_CPU1_SA_DQS_DN<7>")
	)
	(segment
		(start 151.13889 -233.366818)
		(end 151.13889 -233.089958)
		(width 0.16002)
		(layer "In2.Cu")
		(net "M_I_CPU1_SA_DQS_DN<7>")
	)
	(segment
		(start 142.504922 -237.52429)
		(end 142.513304 -237.519464)
		(width 0.09525)
		(layer "In2.Cu")
		(net "M_I_CPU1_SA_DQS_DN<7>")
	)
	(segment
		(start 149.765258 -234.46359)
		(end 149.493224 -234.191556)
		(width 0.16002)
		(layer "In2.Cu")
		(net "M_I_CPU1_SA_DQS_DN<7>")
	)
	(segment
		(start 151.13889 -233.089958)
		(end 150.866856 -232.817924)
		(width 0.16002)
		(layer "In2.Cu")
		(net "M_I_CPU1_SA_DQS_DN<7>")
	)
	(segment
		(start 152.240488 -231.444292)
		(end 152.240488 -230.916988)
		(width 0.16002)
		(layer "In2.Cu")
		(net "M_I_CPU1_SA_DQS_DN<7>")
	)
	(segment
		(start 133.10489 -237.52429)
		(end 133.113272 -237.519464)
		(width 0.09525)
		(layer "In2.Cu")
		(net "M_I_CPU1_SA_DQS_DN<7>")
	)
	(segment
		(start 144.10944 -237.379764)
		(end 144.25422 -237.273084)
		(width 0.09525)
		(layer "In2.Cu")
		(net "M_I_CPU1_SA_DQS_DN<7>")
	)
	(segment
		(start 128.404874 -237.52429)
		(end 128.413256 -237.519464)
		(width 0.09525)
		(layer "In2.Cu")
		(net "M_I_CPU1_SA_DQS_DN<7>")
	)
	(segment
		(start 134.044944 -237.52429)
		(end 134.053326 -237.519464)
		(width 0.09525)
		(layer "In2.Cu")
		(net "M_I_CPU1_SA_DQS_DN<7>")
	)
	(segment
		(start 175.302418 -220.70822)
		(end 177.12563 -220.70822)
		(width 0.16002)
		(layer "In2.Cu")
		(net "M_I_CPU1_SA_DQS_DN<7>")
	)
	(segment
		(start 129.916174 -237.519464)
		(end 129.924556 -237.52429)
		(width 0.09525)
		(layer "In2.Cu")
		(net "M_I_CPU1_SA_DQS_DN<7>")
	)
	(segment
		(start 174.995078 -220.40088)
		(end 175.302418 -220.70822)
		(width 0.16002)
		(layer "In2.Cu")
		(net "M_I_CPU1_SA_DQS_DN<7>")
	)
	(segment
		(start 174.33163 -220.40088)
		(end 174.995078 -220.40088)
		(width 0.16002)
		(layer "In2.Cu")
		(net "M_I_CPU1_SA_DQS_DN<7>")
	)
	(segment
		(start 150.866856 -232.817924)
		(end 150.866856 -232.29062)
		(width 0.16002)
		(layer "In2.Cu")
		(net "M_I_CPU1_SA_DQS_DN<7>")
	)
	(segment
		(start 173.10227 -221.19336)
		(end 173.53915 -221.19336)
		(width 0.16002)
		(layer "In2.Cu")
		(net "M_I_CPU1_SA_DQS_DN<7>")
	)
	(segment
		(start 137.804906 -237.52429)
		(end 137.813288 -237.519464)
		(width 0.09525)
		(layer "In2.Cu")
		(net "M_I_CPU1_SA_DQS_DN<7>")
	)
	(segment
		(start 177.91176 -220.443044)
		(end 178.39182 -220.443044)
		(width 0.16002)
		(layer "In2.Cu")
		(net "M_I_CPU1_SA_DQS_DN<7>")
	)
	(arc
		(start 133.676136 -237.519464)
		(mid 133.859911 -237.570236)
		(end 134.044944 -237.52429)
		(width 0.09525)
		(layer "In2.Cu")
		(net "M_I_CPU1_SA_DQS_DN<7>")
	)
	(arc
		(start 131.796282 -237.519464)
		(mid 131.98475 -237.570141)
		(end 132.173218 -237.519464)
		(width 0.09525)
		(layer "In2.Cu")
		(net "M_I_CPU1_SA_DQS_DN<7>")
	)
	(arc
		(start 133.113272 -237.519464)
		(mid 133.394704 -237.443709)
		(end 133.676136 -237.519464)
		(width 0.09525)
		(layer "In2.Cu")
		(net "M_I_CPU1_SA_DQS_DN<7>")
	)
	(arc
		(start 138.376152 -237.519464)
		(mid 138.559927 -237.570236)
		(end 138.74496 -237.52429)
		(width 0.09525)
		(layer "In2.Cu")
		(net "M_I_CPU1_SA_DQS_DN<7>")
	)
	(arc
		(start 134.624572 -237.52429)
		(mid 134.809604 -237.570204)
		(end 134.99338 -237.519464)
		(width 0.09525)
		(layer "In2.Cu")
		(net "M_I_CPU1_SA_DQS_DN<7>")
	)
	(arc
		(start 139.693396 -237.519464)
		(mid 139.974828 -237.443709)
		(end 140.25626 -237.519464)
		(width 0.09525)
		(layer "In2.Cu")
		(net "M_I_CPU1_SA_DQS_DN<7>")
	)
	(arc
		(start 142.136114 -237.519464)
		(mid 142.319889 -237.570236)
		(end 142.504922 -237.52429)
		(width 0.09525)
		(layer "In2.Cu")
		(net "M_I_CPU1_SA_DQS_DN<7>")
	)
	(arc
		(start 143.08455 -237.52429)
		(mid 143.269582 -237.570204)
		(end 143.453358 -237.519464)
		(width 0.09525)
		(layer "In2.Cu")
		(net "M_I_CPU1_SA_DQS_DN<7>")
	)
	(arc
		(start 128.97612 -237.519464)
		(mid 129.159895 -237.570236)
		(end 129.344928 -237.52429)
		(width 0.09525)
		(layer "In2.Cu")
		(net "M_I_CPU1_SA_DQS_DN<7>")
	)
	(arc
		(start 130.86461 -237.52429)
		(mid 131.049642 -237.570204)
		(end 131.233418 -237.519464)
		(width 0.09525)
		(layer "In2.Cu")
		(net "M_I_CPU1_SA_DQS_DN<7>")
	)
	(arc
		(start 137.813288 -237.519464)
		(mid 138.09472 -237.443709)
		(end 138.376152 -237.519464)
		(width 0.09525)
		(layer "In2.Cu")
		(net "M_I_CPU1_SA_DQS_DN<7>")
	)
	(arc
		(start 139.324588 -237.52429)
		(mid 139.50962 -237.570204)
		(end 139.693396 -237.519464)
		(width 0.09525)
		(layer "In2.Cu")
		(net "M_I_CPU1_SA_DQS_DN<7>")
	)
	(arc
		(start 132.173218 -237.519464)
		(mid 132.45465 -237.443709)
		(end 132.736082 -237.519464)
		(width 0.09525)
		(layer "In2.Cu")
		(net "M_I_CPU1_SA_DQS_DN<7>")
	)
	(arc
		(start 136.873234 -237.519464)
		(mid 137.154666 -237.443709)
		(end 137.436098 -237.519464)
		(width 0.09525)
		(layer "In2.Cu")
		(net "M_I_CPU1_SA_DQS_DN<7>")
	)
	(arc
		(start 132.736082 -237.519464)
		(mid 132.919857 -237.570236)
		(end 133.10489 -237.52429)
		(width 0.09525)
		(layer "In2.Cu")
		(net "M_I_CPU1_SA_DQS_DN<7>")
	)
	(arc
		(start 142.513304 -237.519464)
		(mid 142.794736 -237.443709)
		(end 143.076168 -237.519464)
		(width 0.09525)
		(layer "In2.Cu")
		(net "M_I_CPU1_SA_DQS_DN<7>")
	)
	(arc
		(start 129.35331 -237.519464)
		(mid 129.634742 -237.443709)
		(end 129.916174 -237.519464)
		(width 0.09525)
		(layer "In2.Cu")
		(net "M_I_CPU1_SA_DQS_DN<7>")
	)
	(arc
		(start 140.63345 -237.519464)
		(mid 140.914882 -237.443709)
		(end 141.196314 -237.519464)
		(width 0.09525)
		(layer "In2.Cu")
		(net "M_I_CPU1_SA_DQS_DN<7>")
	)
	(arc
		(start 136.496298 -237.519464)
		(mid 136.684766 -237.570141)
		(end 136.873234 -237.519464)
		(width 0.09525)
		(layer "In2.Cu")
		(net "M_I_CPU1_SA_DQS_DN<7>")
	)
	(arc
		(start 130.293364 -237.519464)
		(mid 130.574796 -237.443709)
		(end 130.856228 -237.519464)
		(width 0.09525)
		(layer "In2.Cu")
		(net "M_I_CPU1_SA_DQS_DN<7>")
	)
	(arc
		(start 135.564626 -237.52429)
		(mid 135.749658 -237.570204)
		(end 135.933434 -237.519464)
		(width 0.09525)
		(layer "In2.Cu")
		(net "M_I_CPU1_SA_DQS_DN<7>")
	)
	(arc
		(start 135.933434 -237.519464)
		(mid 136.214866 -237.443709)
		(end 136.496298 -237.519464)
		(width 0.09525)
		(layer "In2.Cu")
		(net "M_I_CPU1_SA_DQS_DN<7>")
	)
	(arc
		(start 143.914368 -237.443772)
		(mid 144.017047 -237.427419)
		(end 144.10944 -237.379764)
		(width 0.09525)
		(layer "In2.Cu")
		(net "M_I_CPU1_SA_DQS_DN<7>")
	)
	(arc
		(start 131.233418 -237.519464)
		(mid 131.51485 -237.443709)
		(end 131.796282 -237.519464)
		(width 0.09525)
		(layer "In2.Cu")
		(net "M_I_CPU1_SA_DQS_DN<7>")
	)
	(arc
		(start 137.436098 -237.519464)
		(mid 137.619873 -237.570236)
		(end 137.804906 -237.52429)
		(width 0.09525)
		(layer "In2.Cu")
		(net "M_I_CPU1_SA_DQS_DN<7>")
	)
	(arc
		(start 128.094232 -237.546642)
		(mid 128.251982 -237.569161)
		(end 128.404874 -237.52429)
		(width 0.09525)
		(layer "In2.Cu")
		(net "M_I_CPU1_SA_DQS_DN<7>")
	)
	(arc
		(start 134.99338 -237.519464)
		(mid 135.274812 -237.443709)
		(end 135.556244 -237.519464)
		(width 0.09525)
		(layer "In2.Cu")
		(net "M_I_CPU1_SA_DQS_DN<7>")
	)
	(arc
		(start 129.924556 -237.52429)
		(mid 130.109588 -237.570204)
		(end 130.293364 -237.519464)
		(width 0.09525)
		(layer "In2.Cu")
		(net "M_I_CPU1_SA_DQS_DN<7>")
	)
	(arc
		(start 138.753342 -237.519464)
		(mid 139.034774 -237.443709)
		(end 139.316206 -237.519464)
		(width 0.09525)
		(layer "In2.Cu")
		(net "M_I_CPU1_SA_DQS_DN<7>")
	)
	(arc
		(start 134.053326 -237.519464)
		(mid 134.334758 -237.443709)
		(end 134.61619 -237.519464)
		(width 0.09525)
		(layer "In2.Cu")
		(net "M_I_CPU1_SA_DQS_DN<7>")
	)
	(arc
		(start 141.57325 -237.519464)
		(mid 141.854682 -237.443709)
		(end 142.136114 -237.519464)
		(width 0.09525)
		(layer "In2.Cu")
		(net "M_I_CPU1_SA_DQS_DN<7>")
	)
	(arc
		(start 140.264642 -237.52429)
		(mid 140.449674 -237.570204)
		(end 140.63345 -237.519464)
		(width 0.09525)
		(layer "In2.Cu")
		(net "M_I_CPU1_SA_DQS_DN<7>")
	)
	(arc
		(start 143.453358 -237.519464)
		(mid 143.589065 -237.462979)
		(end 143.73479 -237.443772)
		(width 0.09525)
		(layer "In2.Cu")
		(net "M_I_CPU1_SA_DQS_DN<7>")
	)
	(arc
		(start 128.413256 -237.519464)
		(mid 128.694688 -237.443709)
		(end 128.97612 -237.519464)
		(width 0.09525)
		(layer "In2.Cu")
		(net "M_I_CPU1_SA_DQS_DN<7>")
	)
	(arc
		(start 141.196314 -237.519464)
		(mid 141.384782 -237.570141)
		(end 141.57325 -237.519464)
		(width 0.09525)
		(layer "In2.Cu")
		(net "M_I_CPU1_SA_DQS_DN<7>")
	)
	(segment
		(start 127.757936 -232.600246)
		(end 128.224788 -232.334308)
		(width 0.12954)
		(layer "F.Cu")
		(net "M_I_CPU1_SA_DQS_DN<6>")
	)
	(segment
		(start 134.61619 -232.659428)
		(end 134.624572 -232.664254)
		(width 0.09525)
		(layer "In2.Cu")
		(net "M_I_CPU1_SA_DQS_DN<6>")
	)
	(segment
		(start 159.458914 -213.89975)
		(end 159.654748 -213.703916)
		(width 0.16002)
		(layer "In2.Cu")
		(net "M_I_CPU1_SA_DQS_DN<6>")
	)
	(segment
		(start 130.856228 -232.659428)
		(end 130.86461 -232.664254)
		(width 0.09525)
		(layer "In2.Cu")
		(net "M_I_CPU1_SA_DQS_DN<6>")
	)
	(segment
		(start 158.838392 -213.556088)
		(end 159.182054 -213.89975)
		(width 0.16002)
		(layer "In2.Cu")
		(net "M_I_CPU1_SA_DQS_DN<6>")
	)
	(segment
		(start 148.16455 -225.194114)
		(end 156.907484 -216.45118)
		(width 0.16002)
		(layer "In2.Cu")
		(net "M_I_CPU1_SA_DQS_DN<6>")
	)
	(segment
		(start 177.273966 -211.20989)
		(end 179.24145 -211.20989)
		(width 0.16002)
		(layer "In2.Cu")
		(net "M_I_CPU1_SA_DQS_DN<6>")
	)
	(segment
		(start 129.344928 -232.664254)
		(end 129.35331 -232.659428)
		(width 0.09525)
		(layer "In2.Cu")
		(net "M_I_CPU1_SA_DQS_DN<6>")
	)
	(segment
		(start 143.076168 -232.659428)
		(end 143.08455 -232.664254)
		(width 0.09525)
		(layer "In2.Cu")
		(net "M_I_CPU1_SA_DQS_DN<6>")
	)
	(segment
		(start 140.25626 -232.659428)
		(end 140.264642 -232.664254)
		(width 0.09525)
		(layer "In2.Cu")
		(net "M_I_CPU1_SA_DQS_DN<6>")
	)
	(segment
		(start 146.42973 -227.593906)
		(end 148.16455 -225.859086)
		(width 0.16002)
		(layer "In2.Cu")
		(net "M_I_CPU1_SA_DQS_DN<6>")
	)
	(segment
		(start 145.784062 -228.620828)
		(end 145.98777 -228.41712)
		(width 0.09525)
		(layer "In2.Cu")
		(net "M_I_CPU1_SA_DQS_DN<6>")
	)
	(segment
		(start 173.53915 -211.843366)
		(end 174.33163 -211.050886)
		(width 0.16002)
		(layer "In2.Cu")
		(net "M_I_CPU1_SA_DQS_DN<6>")
	)
	(segment
		(start 156.907484 -216.45118)
		(end 156.907484 -216.17432)
		(width 0.16002)
		(layer "In2.Cu")
		(net "M_I_CPU1_SA_DQS_DN<6>")
	)
	(segment
		(start 128.404874 -232.664254)
		(end 128.413256 -232.659428)
		(width 0.09525)
		(layer "In2.Cu")
		(net "M_I_CPU1_SA_DQS_DN<6>")
	)
	(segment
		(start 157.808422 -215.273382)
		(end 158.085282 -215.273382)
		(width 0.16002)
		(layer "In2.Cu")
		(net "M_I_CPU1_SA_DQS_DN<6>")
	)
	(segment
		(start 146.412966 -227.69449)
		(end 146.412966 -227.61067)
		(width 0.09525)
		(layer "In2.Cu")
		(net "M_I_CPU1_SA_DQS_DN<6>")
	)
	(segment
		(start 143.923258 -231.849422)
		(end 143.95577 -231.830626)
		(width 0.09525)
		(layer "In2.Cu")
		(net "M_I_CPU1_SA_DQS_DN<6>")
	)
	(segment
		(start 156.907484 -216.17432)
		(end 156.563822 -215.830658)
		(width 0.16002)
		(layer "In2.Cu")
		(net "M_I_CPU1_SA_DQS_DN<6>")
	)
	(segment
		(start 179.24145 -211.20989)
		(end 179.516024 -210.935316)
		(width 0.16002)
		(layer "In2.Cu")
		(net "M_I_CPU1_SA_DQS_DN<6>")
	)
	(segment
		(start 145.98777 -228.41712)
		(end 145.98777 -228.020626)
		(width 0.09525)
		(layer "In2.Cu")
		(net "M_I_CPU1_SA_DQS_DN<6>")
	)
	(segment
		(start 146.412966 -227.61067)
		(end 146.42973 -227.593906)
		(width 0.09525)
		(layer "In2.Cu")
		(net "M_I_CPU1_SA_DQS_DN<6>")
	)
	(segment
		(start 165.558216 -211.843366)
		(end 165.995096 -211.843366)
		(width 0.16002)
		(layer "In2.Cu")
		(net "M_I_CPU1_SA_DQS_DN<6>")
	)
	(segment
		(start 158.311088 -213.556088)
		(end 158.838392 -213.556088)
		(width 0.16002)
		(layer "In2.Cu")
		(net "M_I_CPU1_SA_DQS_DN<6>")
	)
	(segment
		(start 159.68472 -212.182456)
		(end 160.212024 -212.182456)
		(width 0.16002)
		(layer "In2.Cu")
		(net "M_I_CPU1_SA_DQS_DN<6>")
	)
	(segment
		(start 165.193472 -212.20811)
		(end 165.558216 -211.843366)
		(width 0.16002)
		(layer "In2.Cu")
		(net "M_I_CPU1_SA_DQS_DN<6>")
	)
	(segment
		(start 158.281116 -214.800688)
		(end 157.937454 -214.457026)
		(width 0.16002)
		(layer "In2.Cu")
		(net "M_I_CPU1_SA_DQS_DN<6>")
	)
	(segment
		(start 144.393412 -231.03967)
		(end 144.424908 -231.021382)
		(width 0.09525)
		(layer "In2.Cu")
		(net "M_I_CPU1_SA_DQS_DN<6>")
	)
	(segment
		(start 177.12563 -211.358226)
		(end 177.273966 -211.20989)
		(width 0.16002)
		(layer "In2.Cu")
		(net "M_I_CPU1_SA_DQS_DN<6>")
	)
	(segment
		(start 144.353026 -231.063292)
		(end 144.393412 -231.03967)
		(width 0.09525)
		(layer "In2.Cu")
		(net "M_I_CPU1_SA_DQS_DN<6>")
	)
	(segment
		(start 144.863312 -230.22941)
		(end 144.895824 -230.210614)
		(width 0.09525)
		(layer "In2.Cu")
		(net "M_I_CPU1_SA_DQS_DN<6>")
	)
	(segment
		(start 161.150554 -212.20811)
		(end 165.193472 -212.20811)
		(width 0.16002)
		(layer "In2.Cu")
		(net "M_I_CPU1_SA_DQS_DN<6>")
	)
	(segment
		(start 156.563822 -215.830658)
		(end 156.563822 -215.303354)
		(width 0.16002)
		(layer "In2.Cu")
		(net "M_I_CPU1_SA_DQS_DN<6>")
	)
	(segment
		(start 166.787576 -211.050886)
		(end 167.451024 -211.050886)
		(width 0.16002)
		(layer "In2.Cu")
		(net "M_I_CPU1_SA_DQS_DN<6>")
	)
	(segment
		(start 173.10227 -211.843366)
		(end 173.53915 -211.843366)
		(width 0.16002)
		(layer "In2.Cu")
		(net "M_I_CPU1_SA_DQS_DN<6>")
	)
	(segment
		(start 145.765266 -228.63175)
		(end 145.784062 -228.620828)
		(width 0.09525)
		(layer "In2.Cu")
		(net "M_I_CPU1_SA_DQS_DN<6>")
	)
	(segment
		(start 160.832546 -212.526118)
		(end 161.150554 -212.20811)
		(width 0.16002)
		(layer "In2.Cu")
		(net "M_I_CPU1_SA_DQS_DN<6>")
	)
	(segment
		(start 129.916174 -232.659428)
		(end 129.924556 -232.664254)
		(width 0.09525)
		(layer "In2.Cu")
		(net "M_I_CPU1_SA_DQS_DN<6>")
	)
	(segment
		(start 159.311086 -213.083394)
		(end 159.311086 -212.55609)
		(width 0.16002)
		(layer "In2.Cu")
		(net "M_I_CPU1_SA_DQS_DN<6>")
	)
	(segment
		(start 146.36496 -227.742496)
		(end 146.412966 -227.69449)
		(width 0.09525)
		(layer "In2.Cu")
		(net "M_I_CPU1_SA_DQS_DN<6>")
	)
	(segment
		(start 158.281116 -215.077548)
		(end 158.281116 -214.800688)
		(width 0.16002)
		(layer "In2.Cu")
		(net "M_I_CPU1_SA_DQS_DN<6>")
	)
	(segment
		(start 170.22191 -211.358226)
		(end 171.071794 -212.20811)
		(width 0.16002)
		(layer "In2.Cu")
		(net "M_I_CPU1_SA_DQS_DN<6>")
	)
	(segment
		(start 156.563822 -215.303354)
		(end 156.937456 -214.92972)
		(width 0.16002)
		(layer "In2.Cu")
		(net "M_I_CPU1_SA_DQS_DN<6>")
	)
	(segment
		(start 175.302418 -211.358226)
		(end 177.12563 -211.358226)
		(width 0.16002)
		(layer "In2.Cu")
		(net "M_I_CPU1_SA_DQS_DN<6>")
	)
	(segment
		(start 158.085282 -215.273382)
		(end 158.281116 -215.077548)
		(width 0.16002)
		(layer "In2.Cu")
		(net "M_I_CPU1_SA_DQS_DN<6>")
	)
	(segment
		(start 146.2659 -227.742496)
		(end 146.36496 -227.742496)
		(width 0.09525)
		(layer "In2.Cu")
		(net "M_I_CPU1_SA_DQS_DN<6>")
	)
	(segment
		(start 174.33163 -211.050886)
		(end 174.995078 -211.050886)
		(width 0.16002)
		(layer "In2.Cu")
		(net "M_I_CPU1_SA_DQS_DN<6>")
	)
	(segment
		(start 172.737526 -212.20811)
		(end 173.10227 -211.843366)
		(width 0.16002)
		(layer "In2.Cu")
		(net "M_I_CPU1_SA_DQS_DN<6>")
	)
	(segment
		(start 174.995078 -211.050886)
		(end 175.302418 -211.358226)
		(width 0.16002)
		(layer "In2.Cu")
		(net "M_I_CPU1_SA_DQS_DN<6>")
	)
	(segment
		(start 157.937454 -214.457026)
		(end 157.937454 -213.929722)
		(width 0.16002)
		(layer "In2.Cu")
		(net "M_I_CPU1_SA_DQS_DN<6>")
	)
	(segment
		(start 145.29308 -229.44328)
		(end 145.333466 -229.419658)
		(width 0.09525)
		(layer "In2.Cu")
		(net "M_I_CPU1_SA_DQS_DN<6>")
	)
	(segment
		(start 160.212024 -212.182456)
		(end 160.555686 -212.526118)
		(width 0.16002)
		(layer "In2.Cu")
		(net "M_I_CPU1_SA_DQS_DN<6>")
	)
	(segment
		(start 142.504922 -232.664254)
		(end 142.513304 -232.659428)
		(width 0.09525)
		(layer "In2.Cu")
		(net "M_I_CPU1_SA_DQS_DN<6>")
	)
	(segment
		(start 171.071794 -212.20811)
		(end 172.737526 -212.20811)
		(width 0.16002)
		(layer "In2.Cu")
		(net "M_I_CPU1_SA_DQS_DN<6>")
	)
	(segment
		(start 148.16455 -225.859086)
		(end 148.16455 -225.194114)
		(width 0.16002)
		(layer "In2.Cu")
		(net "M_I_CPU1_SA_DQS_DN<6>")
	)
	(segment
		(start 144.827752 -230.249984)
		(end 144.863312 -230.22941)
		(width 0.09525)
		(layer "In2.Cu")
		(net "M_I_CPU1_SA_DQS_DN<6>")
	)
	(segment
		(start 159.654748 -213.703916)
		(end 159.654748 -213.427056)
		(width 0.16002)
		(layer "In2.Cu")
		(net "M_I_CPU1_SA_DQS_DN<6>")
	)
	(segment
		(start 157.46476 -214.92972)
		(end 157.808422 -215.273382)
		(width 0.16002)
		(layer "In2.Cu")
		(net "M_I_CPU1_SA_DQS_DN<6>")
	)
	(segment
		(start 133.10489 -232.664254)
		(end 133.113272 -232.659428)
		(width 0.09525)
		(layer "In2.Cu")
		(net "M_I_CPU1_SA_DQS_DN<6>")
	)
	(segment
		(start 157.937454 -213.929722)
		(end 158.311088 -213.556088)
		(width 0.16002)
		(layer "In2.Cu")
		(net "M_I_CPU1_SA_DQS_DN<6>")
	)
	(segment
		(start 167.451024 -211.050886)
		(end 167.758364 -211.358226)
		(width 0.16002)
		(layer "In2.Cu")
		(net "M_I_CPU1_SA_DQS_DN<6>")
	)
	(segment
		(start 159.654748 -213.427056)
		(end 159.311086 -213.083394)
		(width 0.16002)
		(layer "In2.Cu")
		(net "M_I_CPU1_SA_DQS_DN<6>")
	)
	(segment
		(start 137.804906 -232.664254)
		(end 137.813288 -232.659428)
		(width 0.09525)
		(layer "In2.Cu")
		(net "M_I_CPU1_SA_DQS_DN<6>")
	)
	(segment
		(start 156.937456 -214.92972)
		(end 157.46476 -214.92972)
		(width 0.16002)
		(layer "In2.Cu")
		(net "M_I_CPU1_SA_DQS_DN<6>")
	)
	(segment
		(start 145.98777 -228.020626)
		(end 146.2659 -227.742496)
		(width 0.09525)
		(layer "In2.Cu")
		(net "M_I_CPU1_SA_DQS_DN<6>")
	)
	(segment
		(start 139.316206 -232.659428)
		(end 139.324588 -232.664254)
		(width 0.09525)
		(layer "In2.Cu")
		(net "M_I_CPU1_SA_DQS_DN<6>")
	)
	(segment
		(start 165.995096 -211.843366)
		(end 166.787576 -211.050886)
		(width 0.16002)
		(layer "In2.Cu")
		(net "M_I_CPU1_SA_DQS_DN<6>")
	)
	(segment
		(start 128.070864 -232.599738)
		(end 128.094232 -232.686606)
		(width 0.09525)
		(layer "In2.Cu")
		(net "M_I_CPU1_SA_DQS_DN<6>")
	)
	(segment
		(start 159.311086 -212.55609)
		(end 159.68472 -212.182456)
		(width 0.16002)
		(layer "In2.Cu")
		(net "M_I_CPU1_SA_DQS_DN<6>")
	)
	(segment
		(start 160.555686 -212.526118)
		(end 160.832546 -212.526118)
		(width 0.16002)
		(layer "In2.Cu")
		(net "M_I_CPU1_SA_DQS_DN<6>")
	)
	(segment
		(start 143.453358 -232.659428)
		(end 143.484854 -232.64114)
		(width 0.09525)
		(layer "In2.Cu")
		(net "M_I_CPU1_SA_DQS_DN<6>")
	)
	(segment
		(start 135.556244 -232.659428)
		(end 135.564626 -232.664254)
		(width 0.09525)
		(layer "In2.Cu")
		(net "M_I_CPU1_SA_DQS_DN<6>")
	)
	(segment
		(start 143.885158 -231.87152)
		(end 143.923258 -231.849422)
		(width 0.09525)
		(layer "In2.Cu")
		(net "M_I_CPU1_SA_DQS_DN<6>")
	)
	(segment
		(start 159.182054 -213.89975)
		(end 159.458914 -213.89975)
		(width 0.16002)
		(layer "In2.Cu")
		(net "M_I_CPU1_SA_DQS_DN<6>")
	)
	(segment
		(start 145.333466 -229.419658)
		(end 145.364962 -229.40137)
		(width 0.09525)
		(layer "In2.Cu")
		(net "M_I_CPU1_SA_DQS_DN<6>")
	)
	(segment
		(start 128.224788 -232.334308)
		(end 128.070864 -232.599738)
		(width 0.09525)
		(layer "In2.Cu")
		(net "M_I_CPU1_SA_DQS_DN<6>")
	)
	(segment
		(start 138.74496 -232.664254)
		(end 138.753342 -232.659428)
		(width 0.09525)
		(layer "In2.Cu")
		(net "M_I_CPU1_SA_DQS_DN<6>")
	)
	(segment
		(start 134.044944 -232.664254)
		(end 134.053326 -232.659428)
		(width 0.09525)
		(layer "In2.Cu")
		(net "M_I_CPU1_SA_DQS_DN<6>")
	)
	(segment
		(start 167.758364 -211.358226)
		(end 170.22191 -211.358226)
		(width 0.16002)
		(layer "In2.Cu")
		(net "M_I_CPU1_SA_DQS_DN<6>")
	)
	(arc
		(start 145.052542 -229.90429)
		(mid 145.116288 -229.64429)
		(end 145.29308 -229.44328)
		(width 0.09525)
		(layer "In2.Cu")
		(net "M_I_CPU1_SA_DQS_DN<6>")
	)
	(arc
		(start 136.496298 -232.659428)
		(mid 136.684766 -232.710105)
		(end 136.873234 -232.659428)
		(width 0.09525)
		(layer "In2.Cu")
		(net "M_I_CPU1_SA_DQS_DN<6>")
	)
	(arc
		(start 128.97612 -232.659428)
		(mid 129.159895 -232.7102)
		(end 129.344928 -232.664254)
		(width 0.09525)
		(layer "In2.Cu")
		(net "M_I_CPU1_SA_DQS_DN<6>")
	)
	(arc
		(start 129.924556 -232.664254)
		(mid 130.109588 -232.710168)
		(end 130.293364 -232.659428)
		(width 0.09525)
		(layer "In2.Cu")
		(net "M_I_CPU1_SA_DQS_DN<6>")
	)
	(arc
		(start 141.57325 -232.659428)
		(mid 141.854682 -232.583673)
		(end 142.136114 -232.659428)
		(width 0.09525)
		(layer "In2.Cu")
		(net "M_I_CPU1_SA_DQS_DN<6>")
	)
	(arc
		(start 142.136114 -232.659428)
		(mid 142.319889 -232.7102)
		(end 142.504922 -232.664254)
		(width 0.09525)
		(layer "In2.Cu")
		(net "M_I_CPU1_SA_DQS_DN<6>")
	)
	(arc
		(start 143.484854 -232.64114)
		(mid 143.600652 -232.506746)
		(end 143.642334 -232.334308)
		(width 0.09525)
		(layer "In2.Cu")
		(net "M_I_CPU1_SA_DQS_DN<6>")
	)
	(arc
		(start 131.233418 -232.659428)
		(mid 131.51485 -232.583673)
		(end 131.796282 -232.659428)
		(width 0.09525)
		(layer "In2.Cu")
		(net "M_I_CPU1_SA_DQS_DN<6>")
	)
	(arc
		(start 134.053326 -232.659428)
		(mid 134.334758 -232.583673)
		(end 134.61619 -232.659428)
		(width 0.09525)
		(layer "In2.Cu")
		(net "M_I_CPU1_SA_DQS_DN<6>")
	)
	(arc
		(start 144.895824 -230.210614)
		(mid 145.011098 -230.076336)
		(end 145.052542 -229.90429)
		(width 0.09525)
		(layer "In2.Cu")
		(net "M_I_CPU1_SA_DQS_DN<6>")
	)
	(arc
		(start 138.753342 -232.659428)
		(mid 139.034774 -232.583673)
		(end 139.316206 -232.659428)
		(width 0.09525)
		(layer "In2.Cu")
		(net "M_I_CPU1_SA_DQS_DN<6>")
	)
	(arc
		(start 130.86461 -232.664254)
		(mid 131.049642 -232.710168)
		(end 131.233418 -232.659428)
		(width 0.09525)
		(layer "In2.Cu")
		(net "M_I_CPU1_SA_DQS_DN<6>")
	)
	(arc
		(start 139.693396 -232.659428)
		(mid 139.974828 -232.583673)
		(end 140.25626 -232.659428)
		(width 0.09525)
		(layer "In2.Cu")
		(net "M_I_CPU1_SA_DQS_DN<6>")
	)
	(arc
		(start 128.094232 -232.686606)
		(mid 128.251982 -232.709125)
		(end 128.404874 -232.664254)
		(width 0.09525)
		(layer "In2.Cu")
		(net "M_I_CPU1_SA_DQS_DN<6>")
	)
	(arc
		(start 139.324588 -232.664254)
		(mid 139.50962 -232.710168)
		(end 139.693396 -232.659428)
		(width 0.09525)
		(layer "In2.Cu")
		(net "M_I_CPU1_SA_DQS_DN<6>")
	)
	(arc
		(start 143.95577 -231.830626)
		(mid 144.071044 -231.696348)
		(end 144.112488 -231.524302)
		(width 0.09525)
		(layer "In2.Cu")
		(net "M_I_CPU1_SA_DQS_DN<6>")
	)
	(arc
		(start 137.436098 -232.659428)
		(mid 137.619873 -232.7102)
		(end 137.804906 -232.664254)
		(width 0.09525)
		(layer "In2.Cu")
		(net "M_I_CPU1_SA_DQS_DN<6>")
	)
	(arc
		(start 135.933434 -232.659428)
		(mid 136.214866 -232.583673)
		(end 136.496298 -232.659428)
		(width 0.09525)
		(layer "In2.Cu")
		(net "M_I_CPU1_SA_DQS_DN<6>")
	)
	(arc
		(start 140.264642 -232.664254)
		(mid 140.449674 -232.710168)
		(end 140.63345 -232.659428)
		(width 0.09525)
		(layer "In2.Cu")
		(net "M_I_CPU1_SA_DQS_DN<6>")
	)
	(arc
		(start 145.522442 -229.094538)
		(mid 145.586839 -228.833232)
		(end 145.765266 -228.63175)
		(width 0.09525)
		(layer "In2.Cu")
		(net "M_I_CPU1_SA_DQS_DN<6>")
	)
	(arc
		(start 141.196314 -232.659428)
		(mid 141.384782 -232.710105)
		(end 141.57325 -232.659428)
		(width 0.09525)
		(layer "In2.Cu")
		(net "M_I_CPU1_SA_DQS_DN<6>")
	)
	(arc
		(start 129.35331 -232.659428)
		(mid 129.634742 -232.583673)
		(end 129.916174 -232.659428)
		(width 0.09525)
		(layer "In2.Cu")
		(net "M_I_CPU1_SA_DQS_DN<6>")
	)
	(arc
		(start 143.08455 -232.664254)
		(mid 143.269582 -232.710168)
		(end 143.453358 -232.659428)
		(width 0.09525)
		(layer "In2.Cu")
		(net "M_I_CPU1_SA_DQS_DN<6>")
	)
	(arc
		(start 128.413256 -232.659428)
		(mid 128.694688 -232.583673)
		(end 128.97612 -232.659428)
		(width 0.09525)
		(layer "In2.Cu")
		(net "M_I_CPU1_SA_DQS_DN<6>")
	)
	(arc
		(start 138.376152 -232.659428)
		(mid 138.559927 -232.7102)
		(end 138.74496 -232.664254)
		(width 0.09525)
		(layer "In2.Cu")
		(net "M_I_CPU1_SA_DQS_DN<6>")
	)
	(arc
		(start 132.173218 -232.659428)
		(mid 132.45465 -232.583673)
		(end 132.736082 -232.659428)
		(width 0.09525)
		(layer "In2.Cu")
		(net "M_I_CPU1_SA_DQS_DN<6>")
	)
	(arc
		(start 133.113272 -232.659428)
		(mid 133.394704 -232.583673)
		(end 133.676136 -232.659428)
		(width 0.09525)
		(layer "In2.Cu")
		(net "M_I_CPU1_SA_DQS_DN<6>")
	)
	(arc
		(start 137.813288 -232.659428)
		(mid 138.09472 -232.583673)
		(end 138.376152 -232.659428)
		(width 0.09525)
		(layer "In2.Cu")
		(net "M_I_CPU1_SA_DQS_DN<6>")
	)
	(arc
		(start 143.642334 -232.334308)
		(mid 143.706731 -232.073002)
		(end 143.885158 -231.87152)
		(width 0.09525)
		(layer "In2.Cu")
		(net "M_I_CPU1_SA_DQS_DN<6>")
	)
	(arc
		(start 132.736082 -232.659428)
		(mid 132.919857 -232.7102)
		(end 133.10489 -232.664254)
		(width 0.09525)
		(layer "In2.Cu")
		(net "M_I_CPU1_SA_DQS_DN<6>")
	)
	(arc
		(start 134.624572 -232.664254)
		(mid 134.809604 -232.710168)
		(end 134.99338 -232.659428)
		(width 0.09525)
		(layer "In2.Cu")
		(net "M_I_CPU1_SA_DQS_DN<6>")
	)
	(arc
		(start 144.112488 -231.524302)
		(mid 144.176234 -231.264302)
		(end 144.353026 -231.063292)
		(width 0.09525)
		(layer "In2.Cu")
		(net "M_I_CPU1_SA_DQS_DN<6>")
	)
	(arc
		(start 131.796282 -232.659428)
		(mid 131.98475 -232.710105)
		(end 132.173218 -232.659428)
		(width 0.09525)
		(layer "In2.Cu")
		(net "M_I_CPU1_SA_DQS_DN<6>")
	)
	(arc
		(start 144.582388 -230.71455)
		(mid 144.647507 -230.451872)
		(end 144.827752 -230.249984)
		(width 0.09525)
		(layer "In2.Cu")
		(net "M_I_CPU1_SA_DQS_DN<6>")
	)
	(arc
		(start 140.63345 -232.659428)
		(mid 140.914882 -232.583673)
		(end 141.196314 -232.659428)
		(width 0.09525)
		(layer "In2.Cu")
		(net "M_I_CPU1_SA_DQS_DN<6>")
	)
	(arc
		(start 135.564626 -232.664254)
		(mid 135.749658 -232.710168)
		(end 135.933434 -232.659428)
		(width 0.09525)
		(layer "In2.Cu")
		(net "M_I_CPU1_SA_DQS_DN<6>")
	)
	(arc
		(start 136.873234 -232.659428)
		(mid 137.154666 -232.583673)
		(end 137.436098 -232.659428)
		(width 0.09525)
		(layer "In2.Cu")
		(net "M_I_CPU1_SA_DQS_DN<6>")
	)
	(arc
		(start 144.424908 -231.021382)
		(mid 144.540706 -230.886988)
		(end 144.582388 -230.71455)
		(width 0.09525)
		(layer "In2.Cu")
		(net "M_I_CPU1_SA_DQS_DN<6>")
	)
	(arc
		(start 142.513304 -232.659428)
		(mid 142.794736 -232.583673)
		(end 143.076168 -232.659428)
		(width 0.09525)
		(layer "In2.Cu")
		(net "M_I_CPU1_SA_DQS_DN<6>")
	)
	(arc
		(start 133.676136 -232.659428)
		(mid 133.859911 -232.7102)
		(end 134.044944 -232.664254)
		(width 0.09525)
		(layer "In2.Cu")
		(net "M_I_CPU1_SA_DQS_DN<6>")
	)
	(arc
		(start 130.293364 -232.659428)
		(mid 130.574796 -232.583673)
		(end 130.856228 -232.659428)
		(width 0.09525)
		(layer "In2.Cu")
		(net "M_I_CPU1_SA_DQS_DN<6>")
	)
	(arc
		(start 145.364962 -229.40137)
		(mid 145.48076 -229.266976)
		(end 145.522442 -229.094538)
		(width 0.09525)
		(layer "In2.Cu")
		(net "M_I_CPU1_SA_DQS_DN<6>")
	)
	(arc
		(start 134.99338 -232.659428)
		(mid 135.274812 -232.583673)
		(end 135.556244 -232.659428)
		(width 0.09525)
		(layer "In2.Cu")
		(net "M_I_CPU1_SA_DQS_DN<6>")
	)
	(segment
		(start 127.757936 -227.740464)
		(end 128.224788 -227.474526)
		(width 0.12954)
		(layer "F.Cu")
		(net "M_I_CPU1_SA_DQS_DN<5>")
	)
	(segment
		(start 174.995078 -201.700892)
		(end 175.302418 -202.008232)
		(width 0.16002)
		(layer "In2.Cu")
		(net "M_I_CPU1_SA_DQS_DN<5>")
	)
	(segment
		(start 165.995096 -202.493372)
		(end 166.787576 -201.700892)
		(width 0.16002)
		(layer "In2.Cu")
		(net "M_I_CPU1_SA_DQS_DN<5>")
	)
	(segment
		(start 151.338788 -212.695282)
		(end 151.534622 -212.499448)
		(width 0.16002)
		(layer "In2.Cu")
		(net "M_I_CPU1_SA_DQS_DN<5>")
	)
	(segment
		(start 135.556244 -227.799646)
		(end 135.564626 -227.804472)
		(width 0.09525)
		(layer "In2.Cu")
		(net "M_I_CPU1_SA_DQS_DN<5>")
	)
	(segment
		(start 154.016964 -208.68386)
		(end 154.390852 -208.309972)
		(width 0.16002)
		(layer "In2.Cu")
		(net "M_I_CPU1_SA_DQS_DN<5>")
	)
	(segment
		(start 150.79726 -212.430614)
		(end 151.061928 -212.695282)
		(width 0.16002)
		(layer "In2.Cu")
		(net "M_I_CPU1_SA_DQS_DN<5>")
	)
	(segment
		(start 154.017218 -209.210656)
		(end 154.016964 -208.68386)
		(width 0.16002)
		(layer "In2.Cu")
		(net "M_I_CPU1_SA_DQS_DN<5>")
	)
	(segment
		(start 152.908254 -210.848956)
		(end 152.643586 -210.584288)
		(width 0.16002)
		(layer "In2.Cu")
		(net "M_I_CPU1_SA_DQS_DN<5>")
	)
	(segment
		(start 128.070864 -227.739956)
		(end 128.094232 -227.826824)
		(width 0.09525)
		(layer "In2.Cu")
		(net "M_I_CPU1_SA_DQS_DN<5>")
	)
	(segment
		(start 150.16099 -213.59622)
		(end 149.896322 -213.331552)
		(width 0.16002)
		(layer "In2.Cu")
		(net "M_I_CPU1_SA_DQS_DN<5>")
	)
	(segment
		(start 144.112996 -221.803722)
		(end 144.112996 -221.257368)
		(width 0.09525)
		(layer "In2.Cu")
		(net "M_I_CPU1_SA_DQS_DN<5>")
	)
	(segment
		(start 179.24145 -201.859896)
		(end 179.516024 -201.585322)
		(width 0.16002)
		(layer "In2.Cu")
		(net "M_I_CPU1_SA_DQS_DN<5>")
	)
	(segment
		(start 138.74496 -227.804472)
		(end 138.753342 -227.799646)
		(width 0.09525)
		(layer "In2.Cu")
		(net "M_I_CPU1_SA_DQS_DN<5>")
	)
	(segment
		(start 155.743656 -207.322674)
		(end 160.208214 -202.858116)
		(width 0.16002)
		(layer "In2.Cu")
		(net "M_I_CPU1_SA_DQS_DN<5>")
	)
	(segment
		(start 153.544524 -209.68335)
		(end 153.809192 -209.948018)
		(width 0.16002)
		(layer "In2.Cu")
		(net "M_I_CPU1_SA_DQS_DN<5>")
	)
	(segment
		(start 149.896068 -212.804756)
		(end 150.269956 -212.430868)
		(width 0.16002)
		(layer "In2.Cu")
		(net "M_I_CPU1_SA_DQS_DN<5>")
	)
	(segment
		(start 152.643332 -210.057492)
		(end 153.01722 -209.683604)
		(width 0.16002)
		(layer "In2.Cu")
		(net "M_I_CPU1_SA_DQS_DN<5>")
	)
	(segment
		(start 151.534622 -212.499448)
		(end 151.534622 -212.222588)
		(width 0.16002)
		(layer "In2.Cu")
		(net "M_I_CPU1_SA_DQS_DN<5>")
	)
	(segment
		(start 143.415258 -222.961708)
		(end 143.453358 -222.93961)
		(width 0.09525)
		(layer "In2.Cu")
		(net "M_I_CPU1_SA_DQS_DN<5>")
	)
	(segment
		(start 173.53915 -202.493372)
		(end 174.33163 -201.700892)
		(width 0.16002)
		(layer "In2.Cu")
		(net "M_I_CPU1_SA_DQS_DN<5>")
	)
	(segment
		(start 174.33163 -201.700892)
		(end 174.995078 -201.700892)
		(width 0.16002)
		(layer "In2.Cu")
		(net "M_I_CPU1_SA_DQS_DN<5>")
	)
	(segment
		(start 150.269956 -212.430868)
		(end 150.79726 -212.430614)
		(width 0.16002)
		(layer "In2.Cu")
		(net "M_I_CPU1_SA_DQS_DN<5>")
	)
	(segment
		(start 151.269954 -211.95792)
		(end 151.2697 -211.431124)
		(width 0.16002)
		(layer "In2.Cu")
		(net "M_I_CPU1_SA_DQS_DN<5>")
	)
	(segment
		(start 151.061928 -212.695282)
		(end 151.338788 -212.695282)
		(width 0.16002)
		(layer "In2.Cu")
		(net "M_I_CPU1_SA_DQS_DN<5>")
	)
	(segment
		(start 167.451024 -201.700892)
		(end 167.758364 -202.008232)
		(width 0.16002)
		(layer "In2.Cu")
		(net "M_I_CPU1_SA_DQS_DN<5>")
	)
	(segment
		(start 142.043404 -225.369628)
		(end 142.0749 -225.35134)
		(width 0.09525)
		(layer "In2.Cu")
		(net "M_I_CPU1_SA_DQS_DN<5>")
	)
	(segment
		(start 150.16099 -213.87308)
		(end 150.16099 -213.59622)
		(width 0.16002)
		(layer "In2.Cu")
		(net "M_I_CPU1_SA_DQS_DN<5>")
	)
	(segment
		(start 175.302418 -202.008232)
		(end 176.94275 -202.008232)
		(width 0.16002)
		(layer "In2.Cu")
		(net "M_I_CPU1_SA_DQS_DN<5>")
	)
	(segment
		(start 152.643586 -210.584288)
		(end 152.643332 -210.057492)
		(width 0.16002)
		(layer "In2.Cu")
		(net "M_I_CPU1_SA_DQS_DN<5>")
	)
	(segment
		(start 142.475204 -224.58172)
		(end 142.513304 -224.559622)
		(width 0.09525)
		(layer "In2.Cu")
		(net "M_I_CPU1_SA_DQS_DN<5>")
	)
	(segment
		(start 137.805922 -227.803964)
		(end 137.813288 -227.799646)
		(width 0.09525)
		(layer "In2.Cu")
		(net "M_I_CPU1_SA_DQS_DN<5>")
	)
	(segment
		(start 154.281886 -209.475324)
		(end 154.017218 -209.210656)
		(width 0.16002)
		(layer "In2.Cu")
		(net "M_I_CPU1_SA_DQS_DN<5>")
	)
	(segment
		(start 151.534622 -212.222588)
		(end 151.269954 -211.95792)
		(width 0.16002)
		(layer "In2.Cu")
		(net "M_I_CPU1_SA_DQS_DN<5>")
	)
	(segment
		(start 154.281886 -209.752184)
		(end 154.281886 -209.475324)
		(width 0.16002)
		(layer "In2.Cu")
		(net "M_I_CPU1_SA_DQS_DN<5>")
	)
	(segment
		(start 177.091086 -201.859896)
		(end 179.24145 -201.859896)
		(width 0.16002)
		(layer "In2.Cu")
		(net "M_I_CPU1_SA_DQS_DN<5>")
	)
	(segment
		(start 142.513304 -224.559622)
		(end 142.545816 -224.540826)
		(width 0.09525)
		(layer "In2.Cu")
		(net "M_I_CPU1_SA_DQS_DN<5>")
	)
	(segment
		(start 173.10227 -202.493372)
		(end 173.53915 -202.493372)
		(width 0.16002)
		(layer "In2.Cu")
		(net "M_I_CPU1_SA_DQS_DN<5>")
	)
	(segment
		(start 152.43556 -211.32165)
		(end 152.71242 -211.32165)
		(width 0.16002)
		(layer "In2.Cu")
		(net "M_I_CPU1_SA_DQS_DN<5>")
	)
	(segment
		(start 134.044944 -227.804472)
		(end 134.053326 -227.799646)
		(width 0.09525)
		(layer "In2.Cu")
		(net "M_I_CPU1_SA_DQS_DN<5>")
	)
	(segment
		(start 137.804906 -227.804472)
		(end 137.805922 -227.803964)
		(width 0.09525)
		(layer "In2.Cu")
		(net "M_I_CPU1_SA_DQS_DN<5>")
	)
	(segment
		(start 128.404874 -227.804472)
		(end 128.413256 -227.799646)
		(width 0.09525)
		(layer "In2.Cu")
		(net "M_I_CPU1_SA_DQS_DN<5>")
	)
	(segment
		(start 144.053814 -219.980256)
		(end 150.16099 -213.87308)
		(width 0.16002)
		(layer "In2.Cu")
		(net "M_I_CPU1_SA_DQS_DN<5>")
	)
	(segment
		(start 142.983204 -223.749616)
		(end 143.015716 -223.73082)
		(width 0.09525)
		(layer "In2.Cu")
		(net "M_I_CPU1_SA_DQS_DN<5>")
	)
	(segment
		(start 155.743656 -208.143094)
		(end 155.743656 -207.322674)
		(width 0.16002)
		(layer "In2.Cu")
		(net "M_I_CPU1_SA_DQS_DN<5>")
	)
	(segment
		(start 172.737526 -202.858116)
		(end 173.10227 -202.493372)
		(width 0.16002)
		(layer "In2.Cu")
		(net "M_I_CPU1_SA_DQS_DN<5>")
	)
	(segment
		(start 152.71242 -211.32165)
		(end 152.908254 -211.125816)
		(width 0.16002)
		(layer "In2.Cu")
		(net "M_I_CPU1_SA_DQS_DN<5>")
	)
	(segment
		(start 141.57325 -226.179634)
		(end 141.605762 -226.160838)
		(width 0.09525)
		(layer "In2.Cu")
		(net "M_I_CPU1_SA_DQS_DN<5>")
	)
	(segment
		(start 153.809192 -209.948018)
		(end 154.086052 -209.948018)
		(width 0.16002)
		(layer "In2.Cu")
		(net "M_I_CPU1_SA_DQS_DN<5>")
	)
	(segment
		(start 151.2697 -211.431124)
		(end 151.643588 -211.057236)
		(width 0.16002)
		(layer "In2.Cu")
		(net "M_I_CPU1_SA_DQS_DN<5>")
	)
	(segment
		(start 160.208214 -202.858116)
		(end 165.193472 -202.858116)
		(width 0.16002)
		(layer "In2.Cu")
		(net "M_I_CPU1_SA_DQS_DN<5>")
	)
	(segment
		(start 154.086052 -209.948018)
		(end 154.281886 -209.752184)
		(width 0.16002)
		(layer "In2.Cu")
		(net "M_I_CPU1_SA_DQS_DN<5>")
	)
	(segment
		(start 167.758364 -202.008232)
		(end 170.22191 -202.008232)
		(width 0.16002)
		(layer "In2.Cu")
		(net "M_I_CPU1_SA_DQS_DN<5>")
	)
	(segment
		(start 144.053814 -221.174564)
		(end 144.053814 -219.980256)
		(width 0.16002)
		(layer "In2.Cu")
		(net "M_I_CPU1_SA_DQS_DN<5>")
	)
	(segment
		(start 176.94275 -202.008232)
		(end 177.091086 -201.859896)
		(width 0.16002)
		(layer "In2.Cu")
		(net "M_I_CPU1_SA_DQS_DN<5>")
	)
	(segment
		(start 165.558216 -202.493372)
		(end 165.995096 -202.493372)
		(width 0.16002)
		(layer "In2.Cu")
		(net "M_I_CPU1_SA_DQS_DN<5>")
	)
	(segment
		(start 128.224788 -227.474526)
		(end 128.070864 -227.739956)
		(width 0.09525)
		(layer "In2.Cu")
		(net "M_I_CPU1_SA_DQS_DN<5>")
	)
	(segment
		(start 143.453358 -222.93961)
		(end 143.484854 -222.921322)
		(width 0.09525)
		(layer "In2.Cu")
		(net "M_I_CPU1_SA_DQS_DN<5>")
	)
	(segment
		(start 129.344928 -227.804472)
		(end 129.35331 -227.799646)
		(width 0.09525)
		(layer "In2.Cu")
		(net "M_I_CPU1_SA_DQS_DN<5>")
	)
	(segment
		(start 154.390852 -208.309972)
		(end 154.918156 -208.309718)
		(width 0.16002)
		(layer "In2.Cu")
		(net "M_I_CPU1_SA_DQS_DN<5>")
	)
	(segment
		(start 151.643588 -211.057236)
		(end 152.170892 -211.056982)
		(width 0.16002)
		(layer "In2.Cu")
		(net "M_I_CPU1_SA_DQS_DN<5>")
	)
	(segment
		(start 129.916174 -227.799646)
		(end 129.924556 -227.804472)
		(width 0.09525)
		(layer "In2.Cu")
		(net "M_I_CPU1_SA_DQS_DN<5>")
	)
	(segment
		(start 144.053814 -221.198186)
		(end 144.053814 -221.174564)
		(width 0.09525)
		(layer "In2.Cu")
		(net "M_I_CPU1_SA_DQS_DN<5>")
	)
	(segment
		(start 139.316206 -227.799646)
		(end 139.324588 -227.804472)
		(width 0.09525)
		(layer "In2.Cu")
		(net "M_I_CPU1_SA_DQS_DN<5>")
	)
	(segment
		(start 133.10489 -227.804472)
		(end 133.113272 -227.799646)
		(width 0.09525)
		(layer "In2.Cu")
		(net "M_I_CPU1_SA_DQS_DN<5>")
	)
	(segment
		(start 141.538198 -226.200208)
		(end 141.57325 -226.179634)
		(width 0.09525)
		(layer "In2.Cu")
		(net "M_I_CPU1_SA_DQS_DN<5>")
	)
	(segment
		(start 130.856228 -227.799646)
		(end 130.86461 -227.804472)
		(width 0.09525)
		(layer "In2.Cu")
		(net "M_I_CPU1_SA_DQS_DN<5>")
	)
	(segment
		(start 152.908254 -211.125816)
		(end 152.908254 -210.848956)
		(width 0.16002)
		(layer "In2.Cu")
		(net "M_I_CPU1_SA_DQS_DN<5>")
	)
	(segment
		(start 171.071794 -202.858116)
		(end 172.737526 -202.858116)
		(width 0.16002)
		(layer "In2.Cu")
		(net "M_I_CPU1_SA_DQS_DN<5>")
	)
	(segment
		(start 140.25626 -227.799646)
		(end 140.264642 -227.804472)
		(width 0.09525)
		(layer "In2.Cu")
		(net "M_I_CPU1_SA_DQS_DN<5>")
	)
	(segment
		(start 170.22191 -202.008232)
		(end 171.071794 -202.858116)
		(width 0.16002)
		(layer "In2.Cu")
		(net "M_I_CPU1_SA_DQS_DN<5>")
	)
	(segment
		(start 142.005304 -225.391726)
		(end 142.043404 -225.369628)
		(width 0.09525)
		(layer "In2.Cu")
		(net "M_I_CPU1_SA_DQS_DN<5>")
	)
	(segment
		(start 141.06525 -227.011738)
		(end 141.10335 -226.98964)
		(width 0.09525)
		(layer "In2.Cu")
		(net "M_I_CPU1_SA_DQS_DN<5>")
	)
	(segment
		(start 141.10335 -226.98964)
		(end 141.135862 -226.970844)
		(width 0.09525)
		(layer "In2.Cu")
		(net "M_I_CPU1_SA_DQS_DN<5>")
	)
	(segment
		(start 166.787576 -201.700892)
		(end 167.451024 -201.700892)
		(width 0.16002)
		(layer "In2.Cu")
		(net "M_I_CPU1_SA_DQS_DN<5>")
	)
	(segment
		(start 142.948152 -223.77019)
		(end 142.983204 -223.749616)
		(width 0.09525)
		(layer "In2.Cu")
		(net "M_I_CPU1_SA_DQS_DN<5>")
	)
	(segment
		(start 144.112996 -221.257368)
		(end 144.053814 -221.198186)
		(width 0.09525)
		(layer "In2.Cu")
		(net "M_I_CPU1_SA_DQS_DN<5>")
	)
	(segment
		(start 143.885158 -222.151702)
		(end 143.95704 -222.110046)
		(width 0.09525)
		(layer "In2.Cu")
		(net "M_I_CPU1_SA_DQS_DN<5>")
	)
	(segment
		(start 155.360878 -208.525872)
		(end 155.743656 -208.143094)
		(width 0.16002)
		(layer "In2.Cu")
		(net "M_I_CPU1_SA_DQS_DN<5>")
	)
	(segment
		(start 140.63345 -227.799646)
		(end 140.664946 -227.781358)
		(width 0.09525)
		(layer "In2.Cu")
		(net "M_I_CPU1_SA_DQS_DN<5>")
	)
	(segment
		(start 155.13431 -208.525872)
		(end 155.360878 -208.525872)
		(width 0.16002)
		(layer "In2.Cu")
		(net "M_I_CPU1_SA_DQS_DN<5>")
	)
	(segment
		(start 149.896322 -213.331552)
		(end 149.896068 -212.804756)
		(width 0.16002)
		(layer "In2.Cu")
		(net "M_I_CPU1_SA_DQS_DN<5>")
	)
	(segment
		(start 153.01722 -209.683604)
		(end 153.544524 -209.68335)
		(width 0.16002)
		(layer "In2.Cu")
		(net "M_I_CPU1_SA_DQS_DN<5>")
	)
	(segment
		(start 134.61619 -227.799646)
		(end 134.624572 -227.804472)
		(width 0.09525)
		(layer "In2.Cu")
		(net "M_I_CPU1_SA_DQS_DN<5>")
	)
	(segment
		(start 154.918156 -208.309718)
		(end 155.13431 -208.525872)
		(width 0.16002)
		(layer "In2.Cu")
		(net "M_I_CPU1_SA_DQS_DN<5>")
	)
	(segment
		(start 165.193472 -202.858116)
		(end 165.558216 -202.493372)
		(width 0.16002)
		(layer "In2.Cu")
		(net "M_I_CPU1_SA_DQS_DN<5>")
	)
	(segment
		(start 152.170892 -211.056982)
		(end 152.43556 -211.32165)
		(width 0.16002)
		(layer "In2.Cu")
		(net "M_I_CPU1_SA_DQS_DN<5>")
	)
	(arc
		(start 143.172434 -223.424496)
		(mid 143.236831 -223.16319)
		(end 143.415258 -222.961708)
		(width 0.09525)
		(layer "In2.Cu")
		(net "M_I_CPU1_SA_DQS_DN<5>")
	)
	(arc
		(start 137.436098 -227.799646)
		(mid 137.619873 -227.850418)
		(end 137.804906 -227.804472)
		(width 0.09525)
		(layer "In2.Cu")
		(net "M_I_CPU1_SA_DQS_DN<5>")
	)
	(arc
		(start 142.702534 -224.234502)
		(mid 142.767781 -223.971899)
		(end 142.948152 -223.77019)
		(width 0.09525)
		(layer "In2.Cu")
		(net "M_I_CPU1_SA_DQS_DN<5>")
	)
	(arc
		(start 140.664946 -227.781358)
		(mid 140.780744 -227.646964)
		(end 140.822426 -227.474526)
		(width 0.09525)
		(layer "In2.Cu")
		(net "M_I_CPU1_SA_DQS_DN<5>")
	)
	(arc
		(start 141.605762 -226.160838)
		(mid 141.721036 -226.02656)
		(end 141.76248 -225.854514)
		(width 0.09525)
		(layer "In2.Cu")
		(net "M_I_CPU1_SA_DQS_DN<5>")
	)
	(arc
		(start 138.376152 -227.799646)
		(mid 138.559927 -227.850418)
		(end 138.74496 -227.804472)
		(width 0.09525)
		(layer "In2.Cu")
		(net "M_I_CPU1_SA_DQS_DN<5>")
	)
	(arc
		(start 130.293364 -227.799646)
		(mid 130.574796 -227.723891)
		(end 130.856228 -227.799646)
		(width 0.09525)
		(layer "In2.Cu")
		(net "M_I_CPU1_SA_DQS_DN<5>")
	)
	(arc
		(start 128.97612 -227.799646)
		(mid 129.159895 -227.850418)
		(end 129.344928 -227.804472)
		(width 0.09525)
		(layer "In2.Cu")
		(net "M_I_CPU1_SA_DQS_DN<5>")
	)
	(arc
		(start 139.693396 -227.799646)
		(mid 139.974828 -227.723891)
		(end 140.25626 -227.799646)
		(width 0.09525)
		(layer "In2.Cu")
		(net "M_I_CPU1_SA_DQS_DN<5>")
	)
	(arc
		(start 143.95704 -222.110046)
		(mid 144.071792 -221.975601)
		(end 144.112996 -221.803722)
		(width 0.09525)
		(layer "In2.Cu")
		(net "M_I_CPU1_SA_DQS_DN<5>")
	)
	(arc
		(start 142.545816 -224.540826)
		(mid 142.66109 -224.406548)
		(end 142.702534 -224.234502)
		(width 0.09525)
		(layer "In2.Cu")
		(net "M_I_CPU1_SA_DQS_DN<5>")
	)
	(arc
		(start 129.924556 -227.804472)
		(mid 130.109588 -227.850386)
		(end 130.293364 -227.799646)
		(width 0.09525)
		(layer "In2.Cu")
		(net "M_I_CPU1_SA_DQS_DN<5>")
	)
	(arc
		(start 132.173218 -227.799646)
		(mid 132.45465 -227.723891)
		(end 132.736082 -227.799646)
		(width 0.09525)
		(layer "In2.Cu")
		(net "M_I_CPU1_SA_DQS_DN<5>")
	)
	(arc
		(start 139.324588 -227.804472)
		(mid 139.50962 -227.850386)
		(end 139.693396 -227.799646)
		(width 0.09525)
		(layer "In2.Cu")
		(net "M_I_CPU1_SA_DQS_DN<5>")
	)
	(arc
		(start 137.813288 -227.799646)
		(mid 138.09472 -227.723891)
		(end 138.376152 -227.799646)
		(width 0.09525)
		(layer "In2.Cu")
		(net "M_I_CPU1_SA_DQS_DN<5>")
	)
	(arc
		(start 140.264642 -227.804472)
		(mid 140.449674 -227.850386)
		(end 140.63345 -227.799646)
		(width 0.09525)
		(layer "In2.Cu")
		(net "M_I_CPU1_SA_DQS_DN<5>")
	)
	(arc
		(start 130.86461 -227.804472)
		(mid 131.049642 -227.850386)
		(end 131.233418 -227.799646)
		(width 0.09525)
		(layer "In2.Cu")
		(net "M_I_CPU1_SA_DQS_DN<5>")
	)
	(arc
		(start 141.76248 -225.854514)
		(mid 141.826877 -225.593208)
		(end 142.005304 -225.391726)
		(width 0.09525)
		(layer "In2.Cu")
		(net "M_I_CPU1_SA_DQS_DN<5>")
	)
	(arc
		(start 128.413256 -227.799646)
		(mid 128.694688 -227.723891)
		(end 128.97612 -227.799646)
		(width 0.09525)
		(layer "In2.Cu")
		(net "M_I_CPU1_SA_DQS_DN<5>")
	)
	(arc
		(start 143.484854 -222.921322)
		(mid 143.600652 -222.786928)
		(end 143.642334 -222.61449)
		(width 0.09525)
		(layer "In2.Cu")
		(net "M_I_CPU1_SA_DQS_DN<5>")
	)
	(arc
		(start 133.676136 -227.799646)
		(mid 133.859911 -227.850418)
		(end 134.044944 -227.804472)
		(width 0.09525)
		(layer "In2.Cu")
		(net "M_I_CPU1_SA_DQS_DN<5>")
	)
	(arc
		(start 141.135862 -226.970844)
		(mid 141.251136 -226.836566)
		(end 141.29258 -226.66452)
		(width 0.09525)
		(layer "In2.Cu")
		(net "M_I_CPU1_SA_DQS_DN<5>")
	)
	(arc
		(start 128.094232 -227.826824)
		(mid 128.251982 -227.849343)
		(end 128.404874 -227.804472)
		(width 0.09525)
		(layer "In2.Cu")
		(net "M_I_CPU1_SA_DQS_DN<5>")
	)
	(arc
		(start 140.822426 -227.474526)
		(mid 140.886823 -227.21322)
		(end 141.06525 -227.011738)
		(width 0.09525)
		(layer "In2.Cu")
		(net "M_I_CPU1_SA_DQS_DN<5>")
	)
	(arc
		(start 133.113272 -227.799646)
		(mid 133.394704 -227.723891)
		(end 133.676136 -227.799646)
		(width 0.09525)
		(layer "In2.Cu")
		(net "M_I_CPU1_SA_DQS_DN<5>")
	)
	(arc
		(start 138.753342 -227.799646)
		(mid 139.034774 -227.723891)
		(end 139.316206 -227.799646)
		(width 0.09525)
		(layer "In2.Cu")
		(net "M_I_CPU1_SA_DQS_DN<5>")
	)
	(arc
		(start 136.496298 -227.799646)
		(mid 136.684766 -227.850323)
		(end 136.873234 -227.799646)
		(width 0.09525)
		(layer "In2.Cu")
		(net "M_I_CPU1_SA_DQS_DN<5>")
	)
	(arc
		(start 135.564626 -227.804472)
		(mid 135.749658 -227.850386)
		(end 135.933434 -227.799646)
		(width 0.09525)
		(layer "In2.Cu")
		(net "M_I_CPU1_SA_DQS_DN<5>")
	)
	(arc
		(start 131.796282 -227.799646)
		(mid 131.98475 -227.850323)
		(end 132.173218 -227.799646)
		(width 0.09525)
		(layer "In2.Cu")
		(net "M_I_CPU1_SA_DQS_DN<5>")
	)
	(arc
		(start 134.99338 -227.799646)
		(mid 135.274812 -227.723891)
		(end 135.556244 -227.799646)
		(width 0.09525)
		(layer "In2.Cu")
		(net "M_I_CPU1_SA_DQS_DN<5>")
	)
	(arc
		(start 135.933434 -227.799646)
		(mid 136.214866 -227.723891)
		(end 136.496298 -227.799646)
		(width 0.09525)
		(layer "In2.Cu")
		(net "M_I_CPU1_SA_DQS_DN<5>")
	)
	(arc
		(start 134.053326 -227.799646)
		(mid 134.334758 -227.723891)
		(end 134.61619 -227.799646)
		(width 0.09525)
		(layer "In2.Cu")
		(net "M_I_CPU1_SA_DQS_DN<5>")
	)
	(arc
		(start 143.642334 -222.61449)
		(mid 143.706731 -222.353184)
		(end 143.885158 -222.151702)
		(width 0.09525)
		(layer "In2.Cu")
		(net "M_I_CPU1_SA_DQS_DN<5>")
	)
	(arc
		(start 142.23238 -225.044508)
		(mid 142.296777 -224.783202)
		(end 142.475204 -224.58172)
		(width 0.09525)
		(layer "In2.Cu")
		(net "M_I_CPU1_SA_DQS_DN<5>")
	)
	(arc
		(start 132.736082 -227.799646)
		(mid 132.919857 -227.850418)
		(end 133.10489 -227.804472)
		(width 0.09525)
		(layer "In2.Cu")
		(net "M_I_CPU1_SA_DQS_DN<5>")
	)
	(arc
		(start 134.624572 -227.804472)
		(mid 134.809604 -227.850386)
		(end 134.99338 -227.799646)
		(width 0.09525)
		(layer "In2.Cu")
		(net "M_I_CPU1_SA_DQS_DN<5>")
	)
	(arc
		(start 129.35331 -227.799646)
		(mid 129.634742 -227.723891)
		(end 129.916174 -227.799646)
		(width 0.09525)
		(layer "In2.Cu")
		(net "M_I_CPU1_SA_DQS_DN<5>")
	)
	(arc
		(start 136.873234 -227.799646)
		(mid 137.154666 -227.723891)
		(end 137.436098 -227.799646)
		(width 0.09525)
		(layer "In2.Cu")
		(net "M_I_CPU1_SA_DQS_DN<5>")
	)
	(arc
		(start 142.0749 -225.35134)
		(mid 142.190698 -225.216946)
		(end 142.23238 -225.044508)
		(width 0.09525)
		(layer "In2.Cu")
		(net "M_I_CPU1_SA_DQS_DN<5>")
	)
	(arc
		(start 131.233418 -227.799646)
		(mid 131.51485 -227.723891)
		(end 131.796282 -227.799646)
		(width 0.09525)
		(layer "In2.Cu")
		(net "M_I_CPU1_SA_DQS_DN<5>")
	)
	(arc
		(start 143.015716 -223.73082)
		(mid 143.13099 -223.596542)
		(end 143.172434 -223.424496)
		(width 0.09525)
		(layer "In2.Cu")
		(net "M_I_CPU1_SA_DQS_DN<5>")
	)
	(arc
		(start 141.29258 -226.66452)
		(mid 141.357827 -226.401917)
		(end 141.538198 -226.200208)
		(width 0.09525)
		(layer "In2.Cu")
		(net "M_I_CPU1_SA_DQS_DN<5>")
	)
	(segment
		(start 128.69799 -247.180354)
		(end 129.164842 -246.914416)
		(width 0.12954)
		(layer "F.Cu")
		(net "M_I_CPU1_SA_DQS_DN<4>")
	)
	(segment
		(start 172.75175 -238.562388)
		(end 173.05909 -238.869728)
		(width 0.16002)
		(layer "In2.Cu")
		(net "M_I_CPU1_SA_DQS_DN<4>")
	)
	(segment
		(start 181.33695 -238.895128)
		(end 181.51983 -238.712248)
		(width 0.16002)
		(layer "In2.Cu")
		(net "M_I_CPU1_SA_DQS_DN<4>")
	)
	(segment
		(start 134.044944 -246.58447)
		(end 134.053326 -246.589296)
		(width 0.09525)
		(layer "In2.Cu")
		(net "M_I_CPU1_SA_DQS_DN<4>")
	)
	(segment
		(start 167.78986 -237.712504)
		(end 169.76852 -237.712504)
		(width 0.16002)
		(layer "In2.Cu")
		(net "M_I_CPU1_SA_DQS_DN<4>")
	)
	(segment
		(start 170.618404 -238.562388)
		(end 172.75175 -238.562388)
		(width 0.16002)
		(layer "In2.Cu")
		(net "M_I_CPU1_SA_DQS_DN<4>")
	)
	(segment
		(start 177.360326 -237.712504)
		(end 177.934366 -238.286544)
		(width 0.16002)
		(layer "In2.Cu")
		(net "M_I_CPU1_SA_DQS_DN<4>")
	)
	(segment
		(start 144.39011 -246.589296)
		(end 144.413986 -246.603266)
		(width 0.09525)
		(layer "In2.Cu")
		(net "M_I_CPU1_SA_DQS_DN<4>")
	)
	(segment
		(start 180.019706 -238.286544)
		(end 180.62829 -238.895128)
		(width 0.16002)
		(layer "In2.Cu")
		(net "M_I_CPU1_SA_DQS_DN<4>")
	)
	(segment
		(start 163.573206 -238.562388)
		(end 165.207696 -238.562388)
		(width 0.16002)
		(layer "In2.Cu")
		(net "M_I_CPU1_SA_DQS_DN<4>")
	)
	(segment
		(start 147.379944 -246.582946)
		(end 147.663408 -246.582946)
		(width 0.09525)
		(layer "In2.Cu")
		(net "M_I_CPU1_SA_DQS_DN<4>")
	)
	(segment
		(start 130.856228 -246.589296)
		(end 130.86461 -246.58447)
		(width 0.09525)
		(layer "In2.Cu")
		(net "M_I_CPU1_SA_DQS_DN<4>")
	)
	(segment
		(start 134.61619 -246.589296)
		(end 134.624572 -246.58447)
		(width 0.09525)
		(layer "In2.Cu")
		(net "M_I_CPU1_SA_DQS_DN<4>")
	)
	(segment
		(start 142.504922 -246.58447)
		(end 142.513304 -246.589296)
		(width 0.09525)
		(layer "In2.Cu")
		(net "M_I_CPU1_SA_DQS_DN<4>")
	)
	(segment
		(start 148.001482 -246.641874)
		(end 148.58111 -246.062246)
		(width 0.16002)
		(layer "In2.Cu")
		(net "M_I_CPU1_SA_DQS_DN<4>")
	)
	(segment
		(start 129.164842 -246.914416)
		(end 129.318766 -246.648986)
		(width 0.09525)
		(layer "In2.Cu")
		(net "M_I_CPU1_SA_DQS_DN<4>")
	)
	(segment
		(start 143.076168 -246.589296)
		(end 143.08455 -246.58447)
		(width 0.09525)
		(layer "In2.Cu")
		(net "M_I_CPU1_SA_DQS_DN<4>")
	)
	(segment
		(start 166.948104 -238.028988)
		(end 167.473376 -238.028988)
		(width 0.16002)
		(layer "In2.Cu")
		(net "M_I_CPU1_SA_DQS_DN<4>")
	)
	(segment
		(start 165.515036 -238.869728)
		(end 166.107364 -238.869728)
		(width 0.16002)
		(layer "In2.Cu")
		(net "M_I_CPU1_SA_DQS_DN<4>")
	)
	(segment
		(start 147.663408 -246.582946)
		(end 147.722336 -246.641874)
		(width 0.09525)
		(layer "In2.Cu")
		(net "M_I_CPU1_SA_DQS_DN<4>")
	)
	(segment
		(start 129.916174 -246.589296)
		(end 129.924556 -246.58447)
		(width 0.09525)
		(layer "In2.Cu")
		(net "M_I_CPU1_SA_DQS_DN<4>")
	)
	(segment
		(start 144.014444 -246.58955)
		(end 144.036288 -246.577104)
		(width 0.09525)
		(layer "In2.Cu")
		(net "M_I_CPU1_SA_DQS_DN<4>")
	)
	(segment
		(start 167.473376 -238.028988)
		(end 167.78986 -237.712504)
		(width 0.16002)
		(layer "In2.Cu")
		(net "M_I_CPU1_SA_DQS_DN<4>")
	)
	(segment
		(start 157.202632 -246.062246)
		(end 163.25469 -240.010188)
		(width 0.16002)
		(layer "In2.Cu")
		(net "M_I_CPU1_SA_DQS_DN<4>")
	)
	(segment
		(start 163.25469 -238.880904)
		(end 163.573206 -238.562388)
		(width 0.16002)
		(layer "In2.Cu")
		(net "M_I_CPU1_SA_DQS_DN<4>")
	)
	(segment
		(start 147.013676 -246.949214)
		(end 147.379944 -246.582946)
		(width 0.09525)
		(layer "In2.Cu")
		(net "M_I_CPU1_SA_DQS_DN<4>")
	)
	(segment
		(start 129.318766 -246.648986)
		(end 129.419604 -246.622316)
		(width 0.09525)
		(layer "In2.Cu")
		(net "M_I_CPU1_SA_DQS_DN<4>")
	)
	(segment
		(start 180.62829 -238.895128)
		(end 181.33695 -238.895128)
		(width 0.16002)
		(layer "In2.Cu")
		(net "M_I_CPU1_SA_DQS_DN<4>")
	)
	(segment
		(start 145.67027 -246.664226)
		(end 145.955258 -246.949214)
		(width 0.09525)
		(layer "In2.Cu")
		(net "M_I_CPU1_SA_DQS_DN<4>")
	)
	(segment
		(start 135.556244 -246.589296)
		(end 135.564626 -246.58447)
		(width 0.09525)
		(layer "In2.Cu")
		(net "M_I_CPU1_SA_DQS_DN<4>")
	)
	(segment
		(start 140.25626 -246.589296)
		(end 140.264642 -246.58447)
		(width 0.09525)
		(layer "In2.Cu")
		(net "M_I_CPU1_SA_DQS_DN<4>")
	)
	(segment
		(start 183.343042 -238.712248)
		(end 183.616092 -238.985298)
		(width 0.16002)
		(layer "In2.Cu")
		(net "M_I_CPU1_SA_DQS_DN<4>")
	)
	(segment
		(start 173.05909 -238.869728)
		(end 173.651418 -238.869728)
		(width 0.16002)
		(layer "In2.Cu")
		(net "M_I_CPU1_SA_DQS_DN<4>")
	)
	(segment
		(start 137.804906 -246.58447)
		(end 137.813288 -246.589296)
		(width 0.09525)
		(layer "In2.Cu")
		(net "M_I_CPU1_SA_DQS_DN<4>")
	)
	(segment
		(start 145.955258 -246.949214)
		(end 147.013676 -246.949214)
		(width 0.09525)
		(layer "In2.Cu")
		(net "M_I_CPU1_SA_DQS_DN<4>")
	)
	(segment
		(start 143.990568 -246.603266)
		(end 144.014444 -246.58955)
		(width 0.09525)
		(layer "In2.Cu")
		(net "M_I_CPU1_SA_DQS_DN<4>")
	)
	(segment
		(start 133.10489 -246.58447)
		(end 133.113272 -246.589296)
		(width 0.09525)
		(layer "In2.Cu")
		(net "M_I_CPU1_SA_DQS_DN<4>")
	)
	(segment
		(start 139.316206 -246.589296)
		(end 139.324588 -246.58447)
		(width 0.09525)
		(layer "In2.Cu")
		(net "M_I_CPU1_SA_DQS_DN<4>")
	)
	(segment
		(start 175.333914 -237.712504)
		(end 177.360326 -237.712504)
		(width 0.16002)
		(layer "In2.Cu")
		(net "M_I_CPU1_SA_DQS_DN<4>")
	)
	(segment
		(start 165.207696 -238.562388)
		(end 165.515036 -238.869728)
		(width 0.16002)
		(layer "In2.Cu")
		(net "M_I_CPU1_SA_DQS_DN<4>")
	)
	(segment
		(start 175.01743 -238.028988)
		(end 175.333914 -237.712504)
		(width 0.16002)
		(layer "In2.Cu")
		(net "M_I_CPU1_SA_DQS_DN<4>")
	)
	(segment
		(start 145.610834 -246.664226)
		(end 145.67027 -246.664226)
		(width 0.09525)
		(layer "In2.Cu")
		(net "M_I_CPU1_SA_DQS_DN<4>")
	)
	(segment
		(start 166.107364 -238.869728)
		(end 166.948104 -238.028988)
		(width 0.16002)
		(layer "In2.Cu")
		(net "M_I_CPU1_SA_DQS_DN<4>")
	)
	(segment
		(start 163.25469 -240.010188)
		(end 163.25469 -238.880904)
		(width 0.16002)
		(layer "In2.Cu")
		(net "M_I_CPU1_SA_DQS_DN<4>")
	)
	(segment
		(start 145.299938 -246.571008)
		(end 145.331942 -246.58955)
		(width 0.09525)
		(layer "In2.Cu")
		(net "M_I_CPU1_SA_DQS_DN<4>")
	)
	(segment
		(start 138.74496 -246.58447)
		(end 138.753342 -246.589296)
		(width 0.09525)
		(layer "In2.Cu")
		(net "M_I_CPU1_SA_DQS_DN<4>")
	)
	(segment
		(start 174.492158 -238.028988)
		(end 175.01743 -238.028988)
		(width 0.16002)
		(layer "In2.Cu")
		(net "M_I_CPU1_SA_DQS_DN<4>")
	)
	(segment
		(start 181.51983 -238.712248)
		(end 183.343042 -238.712248)
		(width 0.16002)
		(layer "In2.Cu")
		(net "M_I_CPU1_SA_DQS_DN<4>")
	)
	(segment
		(start 177.934366 -238.286544)
		(end 180.019706 -238.286544)
		(width 0.16002)
		(layer "In2.Cu")
		(net "M_I_CPU1_SA_DQS_DN<4>")
	)
	(segment
		(start 147.745958 -246.641874)
		(end 148.001482 -246.641874)
		(width 0.16002)
		(layer "In2.Cu")
		(net "M_I_CPU1_SA_DQS_DN<4>")
	)
	(segment
		(start 173.651418 -238.869728)
		(end 174.492158 -238.028988)
		(width 0.16002)
		(layer "In2.Cu")
		(net "M_I_CPU1_SA_DQS_DN<4>")
	)
	(segment
		(start 148.58111 -246.062246)
		(end 157.202632 -246.062246)
		(width 0.16002)
		(layer "In2.Cu")
		(net "M_I_CPU1_SA_DQS_DN<4>")
	)
	(segment
		(start 147.722336 -246.641874)
		(end 147.745958 -246.641874)
		(width 0.09525)
		(layer "In2.Cu")
		(net "M_I_CPU1_SA_DQS_DN<4>")
	)
	(segment
		(start 169.76852 -237.712504)
		(end 170.618404 -238.562388)
		(width 0.16002)
		(layer "In2.Cu")
		(net "M_I_CPU1_SA_DQS_DN<4>")
	)
	(arc
		(start 139.693396 -246.589296)
		(mid 139.974828 -246.665051)
		(end 140.25626 -246.589296)
		(width 0.09525)
		(layer "In2.Cu")
		(net "M_I_CPU1_SA_DQS_DN<4>")
	)
	(arc
		(start 144.413986 -246.603266)
		(mid 144.68621 -246.665638)
		(end 144.954752 -246.589042)
		(width 0.09525)
		(layer "In2.Cu")
		(net "M_I_CPU1_SA_DQS_DN<4>")
	)
	(arc
		(start 134.99338 -246.589296)
		(mid 135.274812 -246.665051)
		(end 135.556244 -246.589296)
		(width 0.09525)
		(layer "In2.Cu")
		(net "M_I_CPU1_SA_DQS_DN<4>")
	)
	(arc
		(start 142.136114 -246.589296)
		(mid 142.319889 -246.538524)
		(end 142.504922 -246.58447)
		(width 0.09525)
		(layer "In2.Cu")
		(net "M_I_CPU1_SA_DQS_DN<4>")
	)
	(arc
		(start 140.264642 -246.58447)
		(mid 140.449674 -246.538556)
		(end 140.63345 -246.589296)
		(width 0.09525)
		(layer "In2.Cu")
		(net "M_I_CPU1_SA_DQS_DN<4>")
	)
	(arc
		(start 132.736082 -246.589296)
		(mid 132.919857 -246.538524)
		(end 133.10489 -246.58447)
		(width 0.09525)
		(layer "In2.Cu")
		(net "M_I_CPU1_SA_DQS_DN<4>")
	)
	(arc
		(start 136.496298 -246.589296)
		(mid 136.684766 -246.538619)
		(end 136.873234 -246.589296)
		(width 0.09525)
		(layer "In2.Cu")
		(net "M_I_CPU1_SA_DQS_DN<4>")
	)
	(arc
		(start 131.796282 -246.589296)
		(mid 131.98475 -246.538619)
		(end 132.173218 -246.589296)
		(width 0.09525)
		(layer "In2.Cu")
		(net "M_I_CPU1_SA_DQS_DN<4>")
	)
	(arc
		(start 136.873234 -246.589296)
		(mid 137.154666 -246.665051)
		(end 137.436098 -246.589296)
		(width 0.09525)
		(layer "In2.Cu")
		(net "M_I_CPU1_SA_DQS_DN<4>")
	)
	(arc
		(start 138.376152 -246.589296)
		(mid 138.559927 -246.538524)
		(end 138.74496 -246.58447)
		(width 0.09525)
		(layer "In2.Cu")
		(net "M_I_CPU1_SA_DQS_DN<4>")
	)
	(arc
		(start 140.63345 -246.589296)
		(mid 140.914882 -246.665051)
		(end 141.196314 -246.589296)
		(width 0.09525)
		(layer "In2.Cu")
		(net "M_I_CPU1_SA_DQS_DN<4>")
	)
	(arc
		(start 142.513304 -246.589296)
		(mid 142.794736 -246.665051)
		(end 143.076168 -246.589296)
		(width 0.09525)
		(layer "In2.Cu")
		(net "M_I_CPU1_SA_DQS_DN<4>")
	)
	(arc
		(start 134.053326 -246.589296)
		(mid 134.334758 -246.665051)
		(end 134.61619 -246.589296)
		(width 0.09525)
		(layer "In2.Cu")
		(net "M_I_CPU1_SA_DQS_DN<4>")
	)
	(arc
		(start 135.933434 -246.589296)
		(mid 136.214866 -246.665051)
		(end 136.496298 -246.589296)
		(width 0.09525)
		(layer "In2.Cu")
		(net "M_I_CPU1_SA_DQS_DN<4>")
	)
	(arc
		(start 137.436098 -246.589296)
		(mid 137.619873 -246.538524)
		(end 137.804906 -246.58447)
		(width 0.09525)
		(layer "In2.Cu")
		(net "M_I_CPU1_SA_DQS_DN<4>")
	)
	(arc
		(start 138.753342 -246.589296)
		(mid 139.034774 -246.665051)
		(end 139.316206 -246.589296)
		(width 0.09525)
		(layer "In2.Cu")
		(net "M_I_CPU1_SA_DQS_DN<4>")
	)
	(arc
		(start 139.324588 -246.58447)
		(mid 139.50962 -246.538556)
		(end 139.693396 -246.589296)
		(width 0.09525)
		(layer "In2.Cu")
		(net "M_I_CPU1_SA_DQS_DN<4>")
	)
	(arc
		(start 145.60804 -246.664226)
		(mid 145.609437 -246.664228)
		(end 145.610834 -246.664226)
		(width 0.09525)
		(layer "In2.Cu")
		(net "M_I_CPU1_SA_DQS_DN<4>")
	)
	(arc
		(start 145.331942 -246.58955)
		(mid 145.465145 -246.644802)
		(end 145.60804 -246.664226)
		(width 0.09525)
		(layer "In2.Cu")
		(net "M_I_CPU1_SA_DQS_DN<4>")
	)
	(arc
		(start 129.419604 -246.622316)
		(mid 129.429472 -246.626347)
		(end 129.439416 -246.63019)
		(width 0.09525)
		(layer "In2.Cu")
		(net "M_I_CPU1_SA_DQS_DN<4>")
	)
	(arc
		(start 130.86461 -246.58447)
		(mid 131.049642 -246.538556)
		(end 131.233418 -246.589296)
		(width 0.09525)
		(layer "In2.Cu")
		(net "M_I_CPU1_SA_DQS_DN<4>")
	)
	(arc
		(start 134.624572 -246.58447)
		(mid 134.809604 -246.538556)
		(end 134.99338 -246.589296)
		(width 0.09525)
		(layer "In2.Cu")
		(net "M_I_CPU1_SA_DQS_DN<4>")
	)
	(arc
		(start 133.676136 -246.589296)
		(mid 133.859911 -246.538524)
		(end 134.044944 -246.58447)
		(width 0.09525)
		(layer "In2.Cu")
		(net "M_I_CPU1_SA_DQS_DN<4>")
	)
	(arc
		(start 135.564626 -246.58447)
		(mid 135.749658 -246.538556)
		(end 135.933434 -246.589296)
		(width 0.09525)
		(layer "In2.Cu")
		(net "M_I_CPU1_SA_DQS_DN<4>")
	)
	(arc
		(start 141.57325 -246.589296)
		(mid 141.854682 -246.665051)
		(end 142.136114 -246.589296)
		(width 0.09525)
		(layer "In2.Cu")
		(net "M_I_CPU1_SA_DQS_DN<4>")
	)
	(arc
		(start 129.439416 -246.63019)
		(mid 129.68238 -246.663177)
		(end 129.916174 -246.589296)
		(width 0.09525)
		(layer "In2.Cu")
		(net "M_I_CPU1_SA_DQS_DN<4>")
	)
	(arc
		(start 143.08455 -246.58447)
		(mid 143.269582 -246.538556)
		(end 143.453358 -246.589296)
		(width 0.09525)
		(layer "In2.Cu")
		(net "M_I_CPU1_SA_DQS_DN<4>")
	)
	(arc
		(start 131.233418 -246.589296)
		(mid 131.51485 -246.665051)
		(end 131.796282 -246.589296)
		(width 0.09525)
		(layer "In2.Cu")
		(net "M_I_CPU1_SA_DQS_DN<4>")
	)
	(arc
		(start 141.196314 -246.589296)
		(mid 141.384782 -246.538619)
		(end 141.57325 -246.589296)
		(width 0.09525)
		(layer "In2.Cu")
		(net "M_I_CPU1_SA_DQS_DN<4>")
	)
	(arc
		(start 137.813288 -246.589296)
		(mid 138.09472 -246.665051)
		(end 138.376152 -246.589296)
		(width 0.09525)
		(layer "In2.Cu")
		(net "M_I_CPU1_SA_DQS_DN<4>")
	)
	(arc
		(start 133.113272 -246.589296)
		(mid 133.394704 -246.665051)
		(end 133.676136 -246.589296)
		(width 0.09525)
		(layer "In2.Cu")
		(net "M_I_CPU1_SA_DQS_DN<4>")
	)
	(arc
		(start 144.036288 -246.577104)
		(mid 144.21474 -246.538862)
		(end 144.39011 -246.589296)
		(width 0.09525)
		(layer "In2.Cu")
		(net "M_I_CPU1_SA_DQS_DN<4>")
	)
	(arc
		(start 144.954752 -246.589042)
		(mid 145.125149 -246.538143)
		(end 145.299938 -246.571008)
		(width 0.09525)
		(layer "In2.Cu")
		(net "M_I_CPU1_SA_DQS_DN<4>")
	)
	(arc
		(start 132.173218 -246.589296)
		(mid 132.45465 -246.665051)
		(end 132.736082 -246.589296)
		(width 0.09525)
		(layer "In2.Cu")
		(net "M_I_CPU1_SA_DQS_DN<4>")
	)
	(arc
		(start 143.453358 -246.589296)
		(mid 143.720184 -246.664861)
		(end 143.990568 -246.603266)
		(width 0.09525)
		(layer "In2.Cu")
		(net "M_I_CPU1_SA_DQS_DN<4>")
	)
	(arc
		(start 129.924556 -246.58447)
		(mid 130.109588 -246.538556)
		(end 130.293364 -246.589296)
		(width 0.09525)
		(layer "In2.Cu")
		(net "M_I_CPU1_SA_DQS_DN<4>")
	)
	(arc
		(start 130.293364 -246.589296)
		(mid 130.574796 -246.665051)
		(end 130.856228 -246.589296)
		(width 0.09525)
		(layer "In2.Cu")
		(net "M_I_CPU1_SA_DQS_DN<4>")
	)
	(segment
		(start 128.69799 -242.320318)
		(end 129.164842 -242.05438)
		(width 0.12954)
		(layer "F.Cu")
		(net "M_I_CPU1_SA_DQS_DN<3>")
	)
	(segment
		(start 137.804906 -241.724434)
		(end 137.813288 -241.72926)
		(width 0.09525)
		(layer "In2.Cu")
		(net "M_I_CPU1_SA_DQS_DN<3>")
	)
	(segment
		(start 177.934366 -228.93655)
		(end 180.019706 -228.93655)
		(width 0.16002)
		(layer "In2.Cu")
		(net "M_I_CPU1_SA_DQS_DN<3>")
	)
	(segment
		(start 166.948104 -228.678994)
		(end 167.473376 -228.678994)
		(width 0.16002)
		(layer "In2.Cu")
		(net "M_I_CPU1_SA_DQS_DN<3>")
	)
	(segment
		(start 163.462208 -229.212394)
		(end 165.207696 -229.212394)
		(width 0.16002)
		(layer "In2.Cu")
		(net "M_I_CPU1_SA_DQS_DN<3>")
	)
	(segment
		(start 173.05909 -229.519734)
		(end 173.651418 -229.519734)
		(width 0.16002)
		(layer "In2.Cu")
		(net "M_I_CPU1_SA_DQS_DN<3>")
	)
	(segment
		(start 146.266916 -241.309398)
		(end 147.277582 -240.298732)
		(width 0.09525)
		(layer "In2.Cu")
		(net "M_I_CPU1_SA_DQS_DN<3>")
	)
	(segment
		(start 147.663408 -240.298732)
		(end 147.722336 -240.35766)
		(width 0.09525)
		(layer "In2.Cu")
		(net "M_I_CPU1_SA_DQS_DN<3>")
	)
	(segment
		(start 145.144744 -241.677698)
		(end 145.553938 -241.677698)
		(width 0.09525)
		(layer "In2.Cu")
		(net "M_I_CPU1_SA_DQS_DN<3>")
	)
	(segment
		(start 130.856228 -241.72926)
		(end 130.86461 -241.724434)
		(width 0.09525)
		(layer "In2.Cu")
		(net "M_I_CPU1_SA_DQS_DN<3>")
	)
	(segment
		(start 147.722336 -240.35766)
		(end 147.745958 -240.35766)
		(width 0.09525)
		(layer "In2.Cu")
		(net "M_I_CPU1_SA_DQS_DN<3>")
	)
	(segment
		(start 138.74496 -241.724434)
		(end 138.753342 -241.72926)
		(width 0.09525)
		(layer "In2.Cu")
		(net "M_I_CPU1_SA_DQS_DN<3>")
	)
	(segment
		(start 180.62829 -229.545134)
		(end 181.428898 -229.545134)
		(width 0.16002)
		(layer "In2.Cu")
		(net "M_I_CPU1_SA_DQS_DN<3>")
	)
	(segment
		(start 144.005554 -241.735356)
		(end 144.015968 -241.72926)
		(width 0.09525)
		(layer "In2.Cu")
		(net "M_I_CPU1_SA_DQS_DN<3>")
	)
	(segment
		(start 140.25626 -241.72926)
		(end 140.264642 -241.724434)
		(width 0.09525)
		(layer "In2.Cu")
		(net "M_I_CPU1_SA_DQS_DN<3>")
	)
	(segment
		(start 180.019706 -228.93655)
		(end 180.62829 -229.545134)
		(width 0.16002)
		(layer "In2.Cu")
		(net "M_I_CPU1_SA_DQS_DN<3>")
	)
	(segment
		(start 129.164842 -242.05438)
		(end 129.318766 -241.78895)
		(width 0.09525)
		(layer "In2.Cu")
		(net "M_I_CPU1_SA_DQS_DN<3>")
	)
	(segment
		(start 161.915348 -230.759254)
		(end 163.462208 -229.212394)
		(width 0.16002)
		(layer "In2.Cu")
		(net "M_I_CPU1_SA_DQS_DN<3>")
	)
	(segment
		(start 151.201882 -240.35766)
		(end 155.770326 -235.789216)
		(width 0.16002)
		(layer "In2.Cu")
		(net "M_I_CPU1_SA_DQS_DN<3>")
	)
	(segment
		(start 181.611778 -229.362254)
		(end 183.343042 -229.362254)
		(width 0.16002)
		(layer "In2.Cu")
		(net "M_I_CPU1_SA_DQS_DN<3>")
	)
	(segment
		(start 183.343042 -229.362254)
		(end 183.616092 -229.635304)
		(width 0.16002)
		(layer "In2.Cu")
		(net "M_I_CPU1_SA_DQS_DN<3>")
	)
	(segment
		(start 177.360326 -228.36251)
		(end 177.934366 -228.93655)
		(width 0.16002)
		(layer "In2.Cu")
		(net "M_I_CPU1_SA_DQS_DN<3>")
	)
	(segment
		(start 165.515036 -229.519734)
		(end 166.107364 -229.519734)
		(width 0.16002)
		(layer "In2.Cu")
		(net "M_I_CPU1_SA_DQS_DN<3>")
	)
	(segment
		(start 175.333914 -228.36251)
		(end 177.360326 -228.36251)
		(width 0.16002)
		(layer "In2.Cu")
		(net "M_I_CPU1_SA_DQS_DN<3>")
	)
	(segment
		(start 143.076168 -241.72926)
		(end 143.08455 -241.724434)
		(width 0.09525)
		(layer "In2.Cu")
		(net "M_I_CPU1_SA_DQS_DN<3>")
	)
	(segment
		(start 145.922238 -241.309398)
		(end 146.266916 -241.309398)
		(width 0.09525)
		(layer "In2.Cu")
		(net "M_I_CPU1_SA_DQS_DN<3>")
	)
	(segment
		(start 129.916174 -241.72926)
		(end 129.924556 -241.724434)
		(width 0.09525)
		(layer "In2.Cu")
		(net "M_I_CPU1_SA_DQS_DN<3>")
	)
	(segment
		(start 135.556244 -241.72926)
		(end 135.564626 -241.724434)
		(width 0.09525)
		(layer "In2.Cu")
		(net "M_I_CPU1_SA_DQS_DN<3>")
	)
	(segment
		(start 147.745958 -240.35766)
		(end 151.201882 -240.35766)
		(width 0.16002)
		(layer "In2.Cu")
		(net "M_I_CPU1_SA_DQS_DN<3>")
	)
	(segment
		(start 133.10489 -241.724434)
		(end 133.113272 -241.72926)
		(width 0.09525)
		(layer "In2.Cu")
		(net "M_I_CPU1_SA_DQS_DN<3>")
	)
	(segment
		(start 145.553938 -241.677698)
		(end 145.922238 -241.309398)
		(width 0.09525)
		(layer "In2.Cu")
		(net "M_I_CPU1_SA_DQS_DN<3>")
	)
	(segment
		(start 170.618404 -229.212394)
		(end 172.75175 -229.212394)
		(width 0.16002)
		(layer "In2.Cu")
		(net "M_I_CPU1_SA_DQS_DN<3>")
	)
	(segment
		(start 134.61619 -241.72926)
		(end 134.624572 -241.724434)
		(width 0.09525)
		(layer "In2.Cu")
		(net "M_I_CPU1_SA_DQS_DN<3>")
	)
	(segment
		(start 147.277582 -240.298732)
		(end 147.663408 -240.298732)
		(width 0.09525)
		(layer "In2.Cu")
		(net "M_I_CPU1_SA_DQS_DN<3>")
	)
	(segment
		(start 167.78986 -228.36251)
		(end 169.76852 -228.36251)
		(width 0.16002)
		(layer "In2.Cu")
		(net "M_I_CPU1_SA_DQS_DN<3>")
	)
	(segment
		(start 169.76852 -228.36251)
		(end 170.618404 -229.212394)
		(width 0.16002)
		(layer "In2.Cu")
		(net "M_I_CPU1_SA_DQS_DN<3>")
	)
	(segment
		(start 181.428898 -229.545134)
		(end 181.611778 -229.362254)
		(width 0.16002)
		(layer "In2.Cu")
		(net "M_I_CPU1_SA_DQS_DN<3>")
	)
	(segment
		(start 129.318766 -241.78895)
		(end 129.419604 -241.76228)
		(width 0.09525)
		(layer "In2.Cu")
		(net "M_I_CPU1_SA_DQS_DN<3>")
	)
	(segment
		(start 157.151578 -235.789216)
		(end 161.915348 -231.025446)
		(width 0.16002)
		(layer "In2.Cu")
		(net "M_I_CPU1_SA_DQS_DN<3>")
	)
	(segment
		(start 165.207696 -229.212394)
		(end 165.515036 -229.519734)
		(width 0.16002)
		(layer "In2.Cu")
		(net "M_I_CPU1_SA_DQS_DN<3>")
	)
	(segment
		(start 139.316206 -241.72926)
		(end 139.324588 -241.724434)
		(width 0.09525)
		(layer "In2.Cu")
		(net "M_I_CPU1_SA_DQS_DN<3>")
	)
	(segment
		(start 166.107364 -229.519734)
		(end 166.948104 -228.678994)
		(width 0.16002)
		(layer "In2.Cu")
		(net "M_I_CPU1_SA_DQS_DN<3>")
	)
	(segment
		(start 173.651418 -229.519734)
		(end 174.492158 -228.678994)
		(width 0.16002)
		(layer "In2.Cu")
		(net "M_I_CPU1_SA_DQS_DN<3>")
	)
	(segment
		(start 172.75175 -229.212394)
		(end 173.05909 -229.519734)
		(width 0.16002)
		(layer "In2.Cu")
		(net "M_I_CPU1_SA_DQS_DN<3>")
	)
	(segment
		(start 144.392904 -241.72926)
		(end 144.403318 -241.735356)
		(width 0.09525)
		(layer "In2.Cu")
		(net "M_I_CPU1_SA_DQS_DN<3>")
	)
	(segment
		(start 142.504922 -241.724434)
		(end 142.513304 -241.72926)
		(width 0.09525)
		(layer "In2.Cu")
		(net "M_I_CPU1_SA_DQS_DN<3>")
	)
	(segment
		(start 155.770326 -235.789216)
		(end 157.151578 -235.789216)
		(width 0.16002)
		(layer "In2.Cu")
		(net "M_I_CPU1_SA_DQS_DN<3>")
	)
	(segment
		(start 167.473376 -228.678994)
		(end 167.78986 -228.36251)
		(width 0.16002)
		(layer "In2.Cu")
		(net "M_I_CPU1_SA_DQS_DN<3>")
	)
	(segment
		(start 174.492158 -228.678994)
		(end 175.01743 -228.678994)
		(width 0.16002)
		(layer "In2.Cu")
		(net "M_I_CPU1_SA_DQS_DN<3>")
	)
	(segment
		(start 175.01743 -228.678994)
		(end 175.333914 -228.36251)
		(width 0.16002)
		(layer "In2.Cu")
		(net "M_I_CPU1_SA_DQS_DN<3>")
	)
	(segment
		(start 161.915348 -231.025446)
		(end 161.915348 -230.759254)
		(width 0.16002)
		(layer "In2.Cu")
		(net "M_I_CPU1_SA_DQS_DN<3>")
	)
	(segment
		(start 134.044944 -241.724434)
		(end 134.053326 -241.72926)
		(width 0.09525)
		(layer "In2.Cu")
		(net "M_I_CPU1_SA_DQS_DN<3>")
	)
	(arc
		(start 136.496298 -241.72926)
		(mid 136.684766 -241.678583)
		(end 136.873234 -241.72926)
		(width 0.09525)
		(layer "In2.Cu")
		(net "M_I_CPU1_SA_DQS_DN<3>")
	)
	(arc
		(start 139.324588 -241.724434)
		(mid 139.50962 -241.67852)
		(end 139.693396 -241.72926)
		(width 0.09525)
		(layer "In2.Cu")
		(net "M_I_CPU1_SA_DQS_DN<3>")
	)
	(arc
		(start 132.173218 -241.72926)
		(mid 132.45465 -241.805015)
		(end 132.736082 -241.72926)
		(width 0.09525)
		(layer "In2.Cu")
		(net "M_I_CPU1_SA_DQS_DN<3>")
	)
	(arc
		(start 139.693396 -241.72926)
		(mid 139.974828 -241.805015)
		(end 140.25626 -241.72926)
		(width 0.09525)
		(layer "In2.Cu")
		(net "M_I_CPU1_SA_DQS_DN<3>")
	)
	(arc
		(start 136.873234 -241.72926)
		(mid 137.154666 -241.805015)
		(end 137.436098 -241.72926)
		(width 0.09525)
		(layer "In2.Cu")
		(net "M_I_CPU1_SA_DQS_DN<3>")
	)
	(arc
		(start 138.376152 -241.72926)
		(mid 138.559927 -241.678488)
		(end 138.74496 -241.724434)
		(width 0.09525)
		(layer "In2.Cu")
		(net "M_I_CPU1_SA_DQS_DN<3>")
	)
	(arc
		(start 135.564626 -241.724434)
		(mid 135.749658 -241.67852)
		(end 135.933434 -241.72926)
		(width 0.09525)
		(layer "In2.Cu")
		(net "M_I_CPU1_SA_DQS_DN<3>")
	)
	(arc
		(start 142.136114 -241.72926)
		(mid 142.319889 -241.678488)
		(end 142.504922 -241.724434)
		(width 0.09525)
		(layer "In2.Cu")
		(net "M_I_CPU1_SA_DQS_DN<3>")
	)
	(arc
		(start 134.053326 -241.72926)
		(mid 134.334758 -241.805015)
		(end 134.61619 -241.72926)
		(width 0.09525)
		(layer "In2.Cu")
		(net "M_I_CPU1_SA_DQS_DN<3>")
	)
	(arc
		(start 141.196314 -241.72926)
		(mid 141.384782 -241.678583)
		(end 141.57325 -241.72926)
		(width 0.09525)
		(layer "In2.Cu")
		(net "M_I_CPU1_SA_DQS_DN<3>")
	)
	(arc
		(start 129.419604 -241.76228)
		(mid 129.429472 -241.766311)
		(end 129.439416 -241.770154)
		(width 0.09525)
		(layer "In2.Cu")
		(net "M_I_CPU1_SA_DQS_DN<3>")
	)
	(arc
		(start 135.933434 -241.72926)
		(mid 136.214866 -241.805015)
		(end 136.496298 -241.72926)
		(width 0.09525)
		(layer "In2.Cu")
		(net "M_I_CPU1_SA_DQS_DN<3>")
	)
	(arc
		(start 134.624572 -241.724434)
		(mid 134.809604 -241.67852)
		(end 134.99338 -241.72926)
		(width 0.09525)
		(layer "In2.Cu")
		(net "M_I_CPU1_SA_DQS_DN<3>")
	)
	(arc
		(start 143.453358 -241.72926)
		(mid 143.728647 -241.804981)
		(end 144.005554 -241.735356)
		(width 0.09525)
		(layer "In2.Cu")
		(net "M_I_CPU1_SA_DQS_DN<3>")
	)
	(arc
		(start 129.924556 -241.724434)
		(mid 130.109588 -241.67852)
		(end 130.293364 -241.72926)
		(width 0.09525)
		(layer "In2.Cu")
		(net "M_I_CPU1_SA_DQS_DN<3>")
	)
	(arc
		(start 129.439416 -241.770154)
		(mid 129.68238 -241.803141)
		(end 129.916174 -241.72926)
		(width 0.09525)
		(layer "In2.Cu")
		(net "M_I_CPU1_SA_DQS_DN<3>")
	)
	(arc
		(start 133.676136 -241.72926)
		(mid 133.859911 -241.678488)
		(end 134.044944 -241.724434)
		(width 0.09525)
		(layer "In2.Cu")
		(net "M_I_CPU1_SA_DQS_DN<3>")
	)
	(arc
		(start 144.403318 -241.735356)
		(mid 144.68048 -241.805156)
		(end 144.956022 -241.72926)
		(width 0.09525)
		(layer "In2.Cu")
		(net "M_I_CPU1_SA_DQS_DN<3>")
	)
	(arc
		(start 144.015968 -241.72926)
		(mid 144.204436 -241.678583)
		(end 144.392904 -241.72926)
		(width 0.09525)
		(layer "In2.Cu")
		(net "M_I_CPU1_SA_DQS_DN<3>")
	)
	(arc
		(start 134.99338 -241.72926)
		(mid 135.274812 -241.805015)
		(end 135.556244 -241.72926)
		(width 0.09525)
		(layer "In2.Cu")
		(net "M_I_CPU1_SA_DQS_DN<3>")
	)
	(arc
		(start 130.293364 -241.72926)
		(mid 130.574796 -241.805015)
		(end 130.856228 -241.72926)
		(width 0.09525)
		(layer "In2.Cu")
		(net "M_I_CPU1_SA_DQS_DN<3>")
	)
	(arc
		(start 137.436098 -241.72926)
		(mid 137.619873 -241.678488)
		(end 137.804906 -241.724434)
		(width 0.09525)
		(layer "In2.Cu")
		(net "M_I_CPU1_SA_DQS_DN<3>")
	)
	(arc
		(start 144.956022 -241.72926)
		(mid 145.046968 -241.690959)
		(end 145.144744 -241.677698)
		(width 0.09525)
		(layer "In2.Cu")
		(net "M_I_CPU1_SA_DQS_DN<3>")
	)
	(arc
		(start 131.233418 -241.72926)
		(mid 131.51485 -241.805015)
		(end 131.796282 -241.72926)
		(width 0.09525)
		(layer "In2.Cu")
		(net "M_I_CPU1_SA_DQS_DN<3>")
	)
	(arc
		(start 138.753342 -241.72926)
		(mid 139.034774 -241.805015)
		(end 139.316206 -241.72926)
		(width 0.09525)
		(layer "In2.Cu")
		(net "M_I_CPU1_SA_DQS_DN<3>")
	)
	(arc
		(start 130.86461 -241.724434)
		(mid 131.049642 -241.67852)
		(end 131.233418 -241.72926)
		(width 0.09525)
		(layer "In2.Cu")
		(net "M_I_CPU1_SA_DQS_DN<3>")
	)
	(arc
		(start 131.796282 -241.72926)
		(mid 131.98475 -241.678583)
		(end 132.173218 -241.72926)
		(width 0.09525)
		(layer "In2.Cu")
		(net "M_I_CPU1_SA_DQS_DN<3>")
	)
	(arc
		(start 132.736082 -241.72926)
		(mid 132.919857 -241.678488)
		(end 133.10489 -241.724434)
		(width 0.09525)
		(layer "In2.Cu")
		(net "M_I_CPU1_SA_DQS_DN<3>")
	)
	(arc
		(start 133.113272 -241.72926)
		(mid 133.394704 -241.805015)
		(end 133.676136 -241.72926)
		(width 0.09525)
		(layer "In2.Cu")
		(net "M_I_CPU1_SA_DQS_DN<3>")
	)
	(arc
		(start 141.57325 -241.72926)
		(mid 141.854682 -241.805015)
		(end 142.136114 -241.72926)
		(width 0.09525)
		(layer "In2.Cu")
		(net "M_I_CPU1_SA_DQS_DN<3>")
	)
	(arc
		(start 137.813288 -241.72926)
		(mid 138.09472 -241.805015)
		(end 138.376152 -241.72926)
		(width 0.09525)
		(layer "In2.Cu")
		(net "M_I_CPU1_SA_DQS_DN<3>")
	)
	(arc
		(start 142.513304 -241.72926)
		(mid 142.794736 -241.805015)
		(end 143.076168 -241.72926)
		(width 0.09525)
		(layer "In2.Cu")
		(net "M_I_CPU1_SA_DQS_DN<3>")
	)
	(arc
		(start 140.63345 -241.72926)
		(mid 140.914882 -241.805015)
		(end 141.196314 -241.72926)
		(width 0.09525)
		(layer "In2.Cu")
		(net "M_I_CPU1_SA_DQS_DN<3>")
	)
	(arc
		(start 140.264642 -241.724434)
		(mid 140.449674 -241.67852)
		(end 140.63345 -241.72926)
		(width 0.09525)
		(layer "In2.Cu")
		(net "M_I_CPU1_SA_DQS_DN<3>")
	)
	(arc
		(start 143.08455 -241.724434)
		(mid 143.269582 -241.67852)
		(end 143.453358 -241.72926)
		(width 0.09525)
		(layer "In2.Cu")
		(net "M_I_CPU1_SA_DQS_DN<3>")
	)
	(segment
		(start 128.69799 -237.460282)
		(end 129.164842 -237.194344)
		(width 0.12954)
		(layer "F.Cu")
		(net "M_I_CPU1_SA_DQS_DN<2>")
	)
	(segment
		(start 166.948104 -219.329)
		(end 167.473376 -219.329)
		(width 0.16002)
		(layer "In2.Cu")
		(net "M_I_CPU1_SA_DQS_DN<2>")
	)
	(segment
		(start 173.05909 -220.16974)
		(end 173.651418 -220.16974)
		(width 0.16002)
		(layer "In2.Cu")
		(net "M_I_CPU1_SA_DQS_DN<2>")
	)
	(segment
		(start 129.164842 -237.194344)
		(end 129.318766 -236.928914)
		(width 0.09525)
		(layer "In2.Cu")
		(net "M_I_CPU1_SA_DQS_DN<2>")
	)
	(segment
		(start 169.76852 -219.012516)
		(end 170.618404 -219.8624)
		(width 0.16002)
		(layer "In2.Cu")
		(net "M_I_CPU1_SA_DQS_DN<2>")
	)
	(segment
		(start 144.13103 -236.780578)
		(end 144.696434 -236.215174)
		(width 0.09525)
		(layer "In2.Cu")
		(net "M_I_CPU1_SA_DQS_DN<2>")
	)
	(segment
		(start 135.556244 -236.869224)
		(end 135.564626 -236.864398)
		(width 0.09525)
		(layer "In2.Cu")
		(net "M_I_CPU1_SA_DQS_DN<2>")
	)
	(segment
		(start 144.696434 -236.215174)
		(end 145.684494 -236.215174)
		(width 0.09525)
		(layer "In2.Cu")
		(net "M_I_CPU1_SA_DQS_DN<2>")
	)
	(segment
		(start 147.902422 -234.416092)
		(end 147.919186 -234.399328)
		(width 0.09525)
		(layer "In2.Cu")
		(net "M_I_CPU1_SA_DQS_DN<2>")
	)
	(segment
		(start 147.819364 -234.416092)
		(end 147.902422 -234.416092)
		(width 0.09525)
		(layer "In2.Cu")
		(net "M_I_CPU1_SA_DQS_DN<2>")
	)
	(segment
		(start 140.25626 -236.869224)
		(end 140.264642 -236.864398)
		(width 0.09525)
		(layer "In2.Cu")
		(net "M_I_CPU1_SA_DQS_DN<2>")
	)
	(segment
		(start 173.651418 -220.16974)
		(end 174.492158 -219.329)
		(width 0.16002)
		(layer "In2.Cu")
		(net "M_I_CPU1_SA_DQS_DN<2>")
	)
	(segment
		(start 183.343042 -220.01226)
		(end 183.616092 -220.28531)
		(width 0.16002)
		(layer "In2.Cu")
		(net "M_I_CPU1_SA_DQS_DN<2>")
	)
	(segment
		(start 174.492158 -219.329)
		(end 175.01743 -219.329)
		(width 0.16002)
		(layer "In2.Cu")
		(net "M_I_CPU1_SA_DQS_DN<2>")
	)
	(segment
		(start 144.005554 -236.87532)
		(end 144.015968 -236.869224)
		(width 0.09525)
		(layer "In2.Cu")
		(net "M_I_CPU1_SA_DQS_DN<2>")
	)
	(segment
		(start 167.78986 -219.012516)
		(end 169.76852 -219.012516)
		(width 0.16002)
		(layer "In2.Cu")
		(net "M_I_CPU1_SA_DQS_DN<2>")
	)
	(segment
		(start 146.539966 -234.630722)
		(end 147.604734 -234.630722)
		(width 0.09525)
		(layer "In2.Cu")
		(net "M_I_CPU1_SA_DQS_DN<2>")
	)
	(segment
		(start 130.856228 -236.869224)
		(end 130.86461 -236.864398)
		(width 0.09525)
		(layer "In2.Cu")
		(net "M_I_CPU1_SA_DQS_DN<2>")
	)
	(segment
		(start 146.277838 -234.89285)
		(end 146.539966 -234.630722)
		(width 0.09525)
		(layer "In2.Cu")
		(net "M_I_CPU1_SA_DQS_DN<2>")
	)
	(segment
		(start 137.804906 -236.864398)
		(end 137.813288 -236.869224)
		(width 0.09525)
		(layer "In2.Cu")
		(net "M_I_CPU1_SA_DQS_DN<2>")
	)
	(segment
		(start 134.044944 -236.864398)
		(end 134.053326 -236.869224)
		(width 0.09525)
		(layer "In2.Cu")
		(net "M_I_CPU1_SA_DQS_DN<2>")
	)
	(segment
		(start 145.684494 -236.215174)
		(end 146.277838 -235.62183)
		(width 0.09525)
		(layer "In2.Cu")
		(net "M_I_CPU1_SA_DQS_DN<2>")
	)
	(segment
		(start 167.473376 -219.329)
		(end 167.78986 -219.012516)
		(width 0.16002)
		(layer "In2.Cu")
		(net "M_I_CPU1_SA_DQS_DN<2>")
	)
	(segment
		(start 139.316206 -236.869224)
		(end 139.324588 -236.864398)
		(width 0.09525)
		(layer "In2.Cu")
		(net "M_I_CPU1_SA_DQS_DN<2>")
	)
	(segment
		(start 129.318766 -236.928914)
		(end 129.419604 -236.902244)
		(width 0.09525)
		(layer "In2.Cu")
		(net "M_I_CPU1_SA_DQS_DN<2>")
	)
	(segment
		(start 175.333914 -219.012516)
		(end 177.360326 -219.012516)
		(width 0.16002)
		(layer "In2.Cu")
		(net "M_I_CPU1_SA_DQS_DN<2>")
	)
	(segment
		(start 175.01743 -219.329)
		(end 175.333914 -219.012516)
		(width 0.16002)
		(layer "In2.Cu")
		(net "M_I_CPU1_SA_DQS_DN<2>")
	)
	(segment
		(start 181.89829 -220.19514)
		(end 182.08117 -220.01226)
		(width 0.16002)
		(layer "In2.Cu")
		(net "M_I_CPU1_SA_DQS_DN<2>")
	)
	(segment
		(start 133.10489 -236.864398)
		(end 133.113272 -236.869224)
		(width 0.09525)
		(layer "In2.Cu")
		(net "M_I_CPU1_SA_DQS_DN<2>")
	)
	(segment
		(start 165.515036 -220.16974)
		(end 166.107364 -220.16974)
		(width 0.16002)
		(layer "In2.Cu")
		(net "M_I_CPU1_SA_DQS_DN<2>")
	)
	(segment
		(start 170.618404 -219.8624)
		(end 172.75175 -219.8624)
		(width 0.16002)
		(layer "In2.Cu")
		(net "M_I_CPU1_SA_DQS_DN<2>")
	)
	(segment
		(start 182.08117 -220.01226)
		(end 183.343042 -220.01226)
		(width 0.16002)
		(layer "In2.Cu")
		(net "M_I_CPU1_SA_DQS_DN<2>")
	)
	(segment
		(start 146.277838 -235.62183)
		(end 146.277838 -234.89285)
		(width 0.09525)
		(layer "In2.Cu")
		(net "M_I_CPU1_SA_DQS_DN<2>")
	)
	(segment
		(start 162.456114 -219.8624)
		(end 165.207696 -219.8624)
		(width 0.16002)
		(layer "In2.Cu")
		(net "M_I_CPU1_SA_DQS_DN<2>")
	)
	(segment
		(start 147.604734 -234.630722)
		(end 147.819364 -234.416092)
		(width 0.09525)
		(layer "In2.Cu")
		(net "M_I_CPU1_SA_DQS_DN<2>")
	)
	(segment
		(start 180.019706 -219.586556)
		(end 180.62829 -220.19514)
		(width 0.16002)
		(layer "In2.Cu")
		(net "M_I_CPU1_SA_DQS_DN<2>")
	)
	(segment
		(start 165.207696 -219.8624)
		(end 165.515036 -220.16974)
		(width 0.16002)
		(layer "In2.Cu")
		(net "M_I_CPU1_SA_DQS_DN<2>")
	)
	(segment
		(start 172.75175 -219.8624)
		(end 173.05909 -220.16974)
		(width 0.16002)
		(layer "In2.Cu")
		(net "M_I_CPU1_SA_DQS_DN<2>")
	)
	(segment
		(start 129.916174 -236.869224)
		(end 129.924556 -236.864398)
		(width 0.09525)
		(layer "In2.Cu")
		(net "M_I_CPU1_SA_DQS_DN<2>")
	)
	(segment
		(start 177.934366 -219.586556)
		(end 180.019706 -219.586556)
		(width 0.16002)
		(layer "In2.Cu")
		(net "M_I_CPU1_SA_DQS_DN<2>")
	)
	(segment
		(start 180.62829 -220.19514)
		(end 181.89829 -220.19514)
		(width 0.16002)
		(layer "In2.Cu")
		(net "M_I_CPU1_SA_DQS_DN<2>")
	)
	(segment
		(start 166.107364 -220.16974)
		(end 166.948104 -219.329)
		(width 0.16002)
		(layer "In2.Cu")
		(net "M_I_CPU1_SA_DQS_DN<2>")
	)
	(segment
		(start 147.919186 -234.399328)
		(end 162.456114 -219.8624)
		(width 0.16002)
		(layer "In2.Cu")
		(net "M_I_CPU1_SA_DQS_DN<2>")
	)
	(segment
		(start 177.360326 -219.012516)
		(end 177.934366 -219.586556)
		(width 0.16002)
		(layer "In2.Cu")
		(net "M_I_CPU1_SA_DQS_DN<2>")
	)
	(segment
		(start 138.74496 -236.864398)
		(end 138.753342 -236.869224)
		(width 0.09525)
		(layer "In2.Cu")
		(net "M_I_CPU1_SA_DQS_DN<2>")
	)
	(segment
		(start 143.076168 -236.869224)
		(end 143.08455 -236.864398)
		(width 0.09525)
		(layer "In2.Cu")
		(net "M_I_CPU1_SA_DQS_DN<2>")
	)
	(segment
		(start 134.61619 -236.869224)
		(end 134.624572 -236.864398)
		(width 0.09525)
		(layer "In2.Cu")
		(net "M_I_CPU1_SA_DQS_DN<2>")
	)
	(segment
		(start 142.504922 -236.864398)
		(end 142.513304 -236.869224)
		(width 0.09525)
		(layer "In2.Cu")
		(net "M_I_CPU1_SA_DQS_DN<2>")
	)
	(arc
		(start 135.933434 -236.869224)
		(mid 136.214866 -236.944979)
		(end 136.496298 -236.869224)
		(width 0.09525)
		(layer "In2.Cu")
		(net "M_I_CPU1_SA_DQS_DN<2>")
	)
	(arc
		(start 134.624572 -236.864398)
		(mid 134.809604 -236.818484)
		(end 134.99338 -236.869224)
		(width 0.09525)
		(layer "In2.Cu")
		(net "M_I_CPU1_SA_DQS_DN<2>")
	)
	(arc
		(start 139.693396 -236.869224)
		(mid 139.974828 -236.944979)
		(end 140.25626 -236.869224)
		(width 0.09525)
		(layer "In2.Cu")
		(net "M_I_CPU1_SA_DQS_DN<2>")
	)
	(arc
		(start 140.63345 -236.869224)
		(mid 140.914882 -236.944979)
		(end 141.196314 -236.869224)
		(width 0.09525)
		(layer "In2.Cu")
		(net "M_I_CPU1_SA_DQS_DN<2>")
	)
	(arc
		(start 129.439416 -236.910118)
		(mid 129.68238 -236.943105)
		(end 129.916174 -236.869224)
		(width 0.09525)
		(layer "In2.Cu")
		(net "M_I_CPU1_SA_DQS_DN<2>")
	)
	(arc
		(start 134.99338 -236.869224)
		(mid 135.274812 -236.944979)
		(end 135.556244 -236.869224)
		(width 0.09525)
		(layer "In2.Cu")
		(net "M_I_CPU1_SA_DQS_DN<2>")
	)
	(arc
		(start 134.053326 -236.869224)
		(mid 134.334758 -236.944979)
		(end 134.61619 -236.869224)
		(width 0.09525)
		(layer "In2.Cu")
		(net "M_I_CPU1_SA_DQS_DN<2>")
	)
	(arc
		(start 143.453358 -236.869224)
		(mid 143.728647 -236.944945)
		(end 144.005554 -236.87532)
		(width 0.09525)
		(layer "In2.Cu")
		(net "M_I_CPU1_SA_DQS_DN<2>")
	)
	(arc
		(start 139.324588 -236.864398)
		(mid 139.50962 -236.818484)
		(end 139.693396 -236.869224)
		(width 0.09525)
		(layer "In2.Cu")
		(net "M_I_CPU1_SA_DQS_DN<2>")
	)
	(arc
		(start 138.753342 -236.869224)
		(mid 139.034774 -236.944979)
		(end 139.316206 -236.869224)
		(width 0.09525)
		(layer "In2.Cu")
		(net "M_I_CPU1_SA_DQS_DN<2>")
	)
	(arc
		(start 142.136114 -236.869224)
		(mid 142.319889 -236.818452)
		(end 142.504922 -236.864398)
		(width 0.09525)
		(layer "In2.Cu")
		(net "M_I_CPU1_SA_DQS_DN<2>")
	)
	(arc
		(start 141.196314 -236.869224)
		(mid 141.384782 -236.818547)
		(end 141.57325 -236.869224)
		(width 0.09525)
		(layer "In2.Cu")
		(net "M_I_CPU1_SA_DQS_DN<2>")
	)
	(arc
		(start 131.233418 -236.869224)
		(mid 131.51485 -236.944979)
		(end 131.796282 -236.869224)
		(width 0.09525)
		(layer "In2.Cu")
		(net "M_I_CPU1_SA_DQS_DN<2>")
	)
	(arc
		(start 133.676136 -236.869224)
		(mid 133.859911 -236.818452)
		(end 134.044944 -236.864398)
		(width 0.09525)
		(layer "In2.Cu")
		(net "M_I_CPU1_SA_DQS_DN<2>")
	)
	(arc
		(start 129.924556 -236.864398)
		(mid 130.109588 -236.818484)
		(end 130.293364 -236.869224)
		(width 0.09525)
		(layer "In2.Cu")
		(net "M_I_CPU1_SA_DQS_DN<2>")
	)
	(arc
		(start 132.736082 -236.869224)
		(mid 132.919857 -236.818452)
		(end 133.10489 -236.864398)
		(width 0.09525)
		(layer "In2.Cu")
		(net "M_I_CPU1_SA_DQS_DN<2>")
	)
	(arc
		(start 132.173218 -236.869224)
		(mid 132.45465 -236.944979)
		(end 132.736082 -236.869224)
		(width 0.09525)
		(layer "In2.Cu")
		(net "M_I_CPU1_SA_DQS_DN<2>")
	)
	(arc
		(start 141.57325 -236.869224)
		(mid 141.854682 -236.944979)
		(end 142.136114 -236.869224)
		(width 0.09525)
		(layer "In2.Cu")
		(net "M_I_CPU1_SA_DQS_DN<2>")
	)
	(arc
		(start 129.419604 -236.902244)
		(mid 129.429472 -236.906275)
		(end 129.439416 -236.910118)
		(width 0.09525)
		(layer "In2.Cu")
		(net "M_I_CPU1_SA_DQS_DN<2>")
	)
	(arc
		(start 137.813288 -236.869224)
		(mid 138.09472 -236.944979)
		(end 138.376152 -236.869224)
		(width 0.09525)
		(layer "In2.Cu")
		(net "M_I_CPU1_SA_DQS_DN<2>")
	)
	(arc
		(start 136.496298 -236.869224)
		(mid 136.684766 -236.818547)
		(end 136.873234 -236.869224)
		(width 0.09525)
		(layer "In2.Cu")
		(net "M_I_CPU1_SA_DQS_DN<2>")
	)
	(arc
		(start 138.376152 -236.869224)
		(mid 138.559927 -236.818452)
		(end 138.74496 -236.864398)
		(width 0.09525)
		(layer "In2.Cu")
		(net "M_I_CPU1_SA_DQS_DN<2>")
	)
	(arc
		(start 143.08455 -236.864398)
		(mid 143.269582 -236.818484)
		(end 143.453358 -236.869224)
		(width 0.09525)
		(layer "In2.Cu")
		(net "M_I_CPU1_SA_DQS_DN<2>")
	)
	(arc
		(start 136.873234 -236.869224)
		(mid 137.154666 -236.944979)
		(end 137.436098 -236.869224)
		(width 0.09525)
		(layer "In2.Cu")
		(net "M_I_CPU1_SA_DQS_DN<2>")
	)
	(arc
		(start 130.293364 -236.869224)
		(mid 130.574796 -236.944979)
		(end 130.856228 -236.869224)
		(width 0.09525)
		(layer "In2.Cu")
		(net "M_I_CPU1_SA_DQS_DN<2>")
	)
	(arc
		(start 142.513304 -236.869224)
		(mid 142.794736 -236.944979)
		(end 143.076168 -236.869224)
		(width 0.09525)
		(layer "In2.Cu")
		(net "M_I_CPU1_SA_DQS_DN<2>")
	)
	(arc
		(start 130.86461 -236.864398)
		(mid 131.049642 -236.818484)
		(end 131.233418 -236.869224)
		(width 0.09525)
		(layer "In2.Cu")
		(net "M_I_CPU1_SA_DQS_DN<2>")
	)
	(arc
		(start 140.264642 -236.864398)
		(mid 140.449674 -236.818484)
		(end 140.63345 -236.869224)
		(width 0.09525)
		(layer "In2.Cu")
		(net "M_I_CPU1_SA_DQS_DN<2>")
	)
	(arc
		(start 131.796282 -236.869224)
		(mid 131.98475 -236.818547)
		(end 132.173218 -236.869224)
		(width 0.09525)
		(layer "In2.Cu")
		(net "M_I_CPU1_SA_DQS_DN<2>")
	)
	(arc
		(start 144.015968 -236.869224)
		(mid 144.076383 -236.828644)
		(end 144.13103 -236.780578)
		(width 0.09525)
		(layer "In2.Cu")
		(net "M_I_CPU1_SA_DQS_DN<2>")
	)
	(arc
		(start 137.436098 -236.869224)
		(mid 137.619873 -236.818452)
		(end 137.804906 -236.864398)
		(width 0.09525)
		(layer "In2.Cu")
		(net "M_I_CPU1_SA_DQS_DN<2>")
	)
	(arc
		(start 133.113272 -236.869224)
		(mid 133.394704 -236.944979)
		(end 133.676136 -236.869224)
		(width 0.09525)
		(layer "In2.Cu")
		(net "M_I_CPU1_SA_DQS_DN<2>")
	)
	(arc
		(start 135.564626 -236.864398)
		(mid 135.749658 -236.818484)
		(end 135.933434 -236.869224)
		(width 0.09525)
		(layer "In2.Cu")
		(net "M_I_CPU1_SA_DQS_DN<2>")
	)
	(segment
		(start 128.69799 -232.600246)
		(end 129.164842 -232.334308)
		(width 0.12954)
		(layer "F.Cu")
		(net "M_I_CPU1_SA_DQS_DN<1>")
	)
	(segment
		(start 143.546068 -231.199182)
		(end 143.586454 -231.17556)
		(width 0.09525)
		(layer "In2.Cu")
		(net "M_I_CPU1_SA_DQS_DN<1>")
	)
	(segment
		(start 170.618404 -210.512406)
		(end 172.75175 -210.512406)
		(width 0.16002)
		(layer "In2.Cu")
		(net "M_I_CPU1_SA_DQS_DN<1>")
	)
	(segment
		(start 146.699986 -226.288346)
		(end 147.065492 -225.92284)
		(width 0.09525)
		(layer "In2.Cu")
		(net "M_I_CPU1_SA_DQS_DN<1>")
	)
	(segment
		(start 134.044944 -232.004362)
		(end 134.053326 -232.009188)
		(width 0.09525)
		(layer "In2.Cu")
		(net "M_I_CPU1_SA_DQS_DN<1>")
	)
	(segment
		(start 169.76852 -209.662522)
		(end 170.618404 -210.512406)
		(width 0.16002)
		(layer "In2.Cu")
		(net "M_I_CPU1_SA_DQS_DN<1>")
	)
	(segment
		(start 180.62829 -210.845146)
		(end 181.89829 -210.845146)
		(width 0.16002)
		(layer "In2.Cu")
		(net "M_I_CPU1_SA_DQS_DN<1>")
	)
	(segment
		(start 147.16506 -225.90633)
		(end 147.66671 -225.404426)
		(width 0.16002)
		(layer "In2.Cu")
		(net "M_I_CPU1_SA_DQS_DN<1>")
	)
	(segment
		(start 138.74496 -232.004362)
		(end 138.753342 -232.009188)
		(width 0.09525)
		(layer "In2.Cu")
		(net "M_I_CPU1_SA_DQS_DN<1>")
	)
	(segment
		(start 147.66671 -224.890838)
		(end 155.997402 -216.560146)
		(width 0.16002)
		(layer "In2.Cu")
		(net "M_I_CPU1_SA_DQS_DN<1>")
	)
	(segment
		(start 134.61619 -232.009188)
		(end 134.624572 -232.004362)
		(width 0.09525)
		(layer "In2.Cu")
		(net "M_I_CPU1_SA_DQS_DN<1>")
	)
	(segment
		(start 144.454626 -229.597458)
		(end 144.486122 -229.57917)
		(width 0.09525)
		(layer "In2.Cu")
		(net "M_I_CPU1_SA_DQS_DN<1>")
	)
	(segment
		(start 165.515036 -210.819746)
		(end 166.107364 -210.819746)
		(width 0.16002)
		(layer "In2.Cu")
		(net "M_I_CPU1_SA_DQS_DN<1>")
	)
	(segment
		(start 173.651418 -210.819746)
		(end 174.492158 -209.979006)
		(width 0.16002)
		(layer "In2.Cu")
		(net "M_I_CPU1_SA_DQS_DN<1>")
	)
	(segment
		(start 167.78986 -209.662522)
		(end 169.76852 -209.662522)
		(width 0.16002)
		(layer "In2.Cu")
		(net "M_I_CPU1_SA_DQS_DN<1>")
	)
	(segment
		(start 181.89829 -210.845146)
		(end 182.08117 -210.662266)
		(width 0.16002)
		(layer "In2.Cu")
		(net "M_I_CPU1_SA_DQS_DN<1>")
	)
	(segment
		(start 145.862294 -227.16871)
		(end 145.998946 -227.089208)
		(width 0.09525)
		(layer "In2.Cu")
		(net "M_I_CPU1_SA_DQS_DN<1>")
	)
	(segment
		(start 175.01743 -209.979006)
		(end 175.333914 -209.662522)
		(width 0.16002)
		(layer "In2.Cu")
		(net "M_I_CPU1_SA_DQS_DN<1>")
	)
	(segment
		(start 147.065492 -225.92284)
		(end 147.148296 -225.923094)
		(width 0.09525)
		(layer "In2.Cu")
		(net "M_I_CPU1_SA_DQS_DN<1>")
	)
	(segment
		(start 155.997402 -216.560146)
		(end 155.997402 -215.068658)
		(width 0.16002)
		(layer "In2.Cu")
		(net "M_I_CPU1_SA_DQS_DN<1>")
	)
	(segment
		(start 146.15414 -226.53498)
		(end 146.400774 -226.288346)
		(width 0.09525)
		(layer "In2.Cu")
		(net "M_I_CPU1_SA_DQS_DN<1>")
	)
	(segment
		(start 129.164842 -232.334308)
		(end 129.318766 -232.068878)
		(width 0.09525)
		(layer "In2.Cu")
		(net "M_I_CPU1_SA_DQS_DN<1>")
	)
	(segment
		(start 145.39468 -227.9777)
		(end 145.426176 -227.959412)
		(width 0.09525)
		(layer "In2.Cu")
		(net "M_I_CPU1_SA_DQS_DN<1>")
	)
	(segment
		(start 139.316206 -232.009188)
		(end 139.324588 -232.004362)
		(width 0.09525)
		(layer "In2.Cu")
		(net "M_I_CPU1_SA_DQS_DN<1>")
	)
	(segment
		(start 133.10489 -232.004362)
		(end 133.113272 -232.009188)
		(width 0.09525)
		(layer "In2.Cu")
		(net "M_I_CPU1_SA_DQS_DN<1>")
	)
	(segment
		(start 174.492158 -209.979006)
		(end 175.01743 -209.979006)
		(width 0.16002)
		(layer "In2.Cu")
		(net "M_I_CPU1_SA_DQS_DN<1>")
	)
	(segment
		(start 143.076168 -232.009188)
		(end 143.114268 -231.98709)
		(width 0.09525)
		(layer "In2.Cu")
		(net "M_I_CPU1_SA_DQS_DN<1>")
	)
	(segment
		(start 177.962306 -210.236562)
		(end 180.019706 -210.236562)
		(width 0.16002)
		(layer "In2.Cu")
		(net "M_I_CPU1_SA_DQS_DN<1>")
	)
	(segment
		(start 147.148296 -225.923094)
		(end 147.16506 -225.90633)
		(width 0.09525)
		(layer "In2.Cu")
		(net "M_I_CPU1_SA_DQS_DN<1>")
	)
	(segment
		(start 172.75175 -210.512406)
		(end 173.05909 -210.819746)
		(width 0.16002)
		(layer "In2.Cu")
		(net "M_I_CPU1_SA_DQS_DN<1>")
	)
	(segment
		(start 145.998946 -227.089208)
		(end 146.15414 -226.93376)
		(width 0.09525)
		(layer "In2.Cu")
		(net "M_I_CPU1_SA_DQS_DN<1>")
	)
	(segment
		(start 182.08117 -210.662266)
		(end 183.343042 -210.662266)
		(width 0.16002)
		(layer "In2.Cu")
		(net "M_I_CPU1_SA_DQS_DN<1>")
	)
	(segment
		(start 147.66671 -225.404426)
		(end 147.66671 -224.890838)
		(width 0.16002)
		(layer "In2.Cu")
		(net "M_I_CPU1_SA_DQS_DN<1>")
	)
	(segment
		(start 137.804906 -232.004362)
		(end 137.813288 -232.009188)
		(width 0.09525)
		(layer "In2.Cu")
		(net "M_I_CPU1_SA_DQS_DN<1>")
	)
	(segment
		(start 144.956276 -228.769418)
		(end 144.994376 -228.74732)
		(width 0.09525)
		(layer "In2.Cu")
		(net "M_I_CPU1_SA_DQS_DN<1>")
	)
	(segment
		(start 180.019706 -210.236562)
		(end 180.62829 -210.845146)
		(width 0.16002)
		(layer "In2.Cu")
		(net "M_I_CPU1_SA_DQS_DN<1>")
	)
	(segment
		(start 140.25626 -232.009188)
		(end 140.264642 -232.004362)
		(width 0.09525)
		(layer "In2.Cu")
		(net "M_I_CPU1_SA_DQS_DN<1>")
	)
	(segment
		(start 146.400774 -226.288346)
		(end 146.699986 -226.288346)
		(width 0.09525)
		(layer "In2.Cu")
		(net "M_I_CPU1_SA_DQS_DN<1>")
	)
	(segment
		(start 135.556244 -232.009188)
		(end 135.564626 -232.004362)
		(width 0.09525)
		(layer "In2.Cu")
		(net "M_I_CPU1_SA_DQS_DN<1>")
	)
	(segment
		(start 143.514572 -231.21747)
		(end 143.546068 -231.199182)
		(width 0.09525)
		(layer "In2.Cu")
		(net "M_I_CPU1_SA_DQS_DN<1>")
	)
	(segment
		(start 155.997402 -215.068658)
		(end 160.553654 -210.512406)
		(width 0.16002)
		(layer "In2.Cu")
		(net "M_I_CPU1_SA_DQS_DN<1>")
	)
	(segment
		(start 144.923764 -228.788214)
		(end 144.956276 -228.769418)
		(width 0.09525)
		(layer "In2.Cu")
		(net "M_I_CPU1_SA_DQS_DN<1>")
	)
	(segment
		(start 166.107364 -210.819746)
		(end 166.948104 -209.979006)
		(width 0.16002)
		(layer "In2.Cu")
		(net "M_I_CPU1_SA_DQS_DN<1>")
	)
	(segment
		(start 145.426176 -227.959412)
		(end 145.45818 -227.94087)
		(width 0.09525)
		(layer "In2.Cu")
		(net "M_I_CPU1_SA_DQS_DN<1>")
	)
	(segment
		(start 146.15414 -226.93376)
		(end 146.15414 -226.53498)
		(width 0.09525)
		(layer "In2.Cu")
		(net "M_I_CPU1_SA_DQS_DN<1>")
	)
	(segment
		(start 175.333914 -209.662522)
		(end 177.388266 -209.662522)
		(width 0.16002)
		(layer "In2.Cu")
		(net "M_I_CPU1_SA_DQS_DN<1>")
	)
	(segment
		(start 129.916174 -232.009188)
		(end 129.924556 -232.004362)
		(width 0.09525)
		(layer "In2.Cu")
		(net "M_I_CPU1_SA_DQS_DN<1>")
	)
	(segment
		(start 129.318766 -232.068878)
		(end 129.419604 -232.042208)
		(width 0.09525)
		(layer "In2.Cu")
		(net "M_I_CPU1_SA_DQS_DN<1>")
	)
	(segment
		(start 165.207696 -210.512406)
		(end 165.515036 -210.819746)
		(width 0.16002)
		(layer "In2.Cu")
		(net "M_I_CPU1_SA_DQS_DN<1>")
	)
	(segment
		(start 177.388266 -209.662522)
		(end 177.962306 -210.236562)
		(width 0.16002)
		(layer "In2.Cu")
		(net "M_I_CPU1_SA_DQS_DN<1>")
	)
	(segment
		(start 142.504922 -232.004362)
		(end 142.513304 -232.009188)
		(width 0.09525)
		(layer "In2.Cu")
		(net "M_I_CPU1_SA_DQS_DN<1>")
	)
	(segment
		(start 143.98371 -230.408226)
		(end 144.016222 -230.38943)
		(width 0.09525)
		(layer "In2.Cu")
		(net "M_I_CPU1_SA_DQS_DN<1>")
	)
	(segment
		(start 130.856228 -232.009188)
		(end 130.86461 -232.004362)
		(width 0.09525)
		(layer "In2.Cu")
		(net "M_I_CPU1_SA_DQS_DN<1>")
	)
	(segment
		(start 167.473376 -209.979006)
		(end 167.78986 -209.662522)
		(width 0.16002)
		(layer "In2.Cu")
		(net "M_I_CPU1_SA_DQS_DN<1>")
	)
	(segment
		(start 144.016222 -230.38943)
		(end 144.051782 -230.368856)
		(width 0.09525)
		(layer "In2.Cu")
		(net "M_I_CPU1_SA_DQS_DN<1>")
	)
	(segment
		(start 183.343042 -210.662266)
		(end 183.616092 -210.935316)
		(width 0.16002)
		(layer "In2.Cu")
		(net "M_I_CPU1_SA_DQS_DN<1>")
	)
	(segment
		(start 160.553654 -210.512406)
		(end 165.207696 -210.512406)
		(width 0.16002)
		(layer "In2.Cu")
		(net "M_I_CPU1_SA_DQS_DN<1>")
	)
	(segment
		(start 144.486122 -229.57917)
		(end 144.526508 -229.555548)
		(width 0.09525)
		(layer "In2.Cu")
		(net "M_I_CPU1_SA_DQS_DN<1>")
	)
	(segment
		(start 173.05909 -210.819746)
		(end 173.651418 -210.819746)
		(width 0.16002)
		(layer "In2.Cu")
		(net "M_I_CPU1_SA_DQS_DN<1>")
	)
	(segment
		(start 166.948104 -209.979006)
		(end 167.473376 -209.979006)
		(width 0.16002)
		(layer "In2.Cu")
		(net "M_I_CPU1_SA_DQS_DN<1>")
	)
	(arc
		(start 143.114268 -231.98709)
		(mid 143.292718 -231.78562)
		(end 143.357092 -231.524302)
		(width 0.09525)
		(layer "In2.Cu")
		(net "M_I_CPU1_SA_DQS_DN<1>")
	)
	(arc
		(start 145.2372 -228.284532)
		(mid 145.278865 -228.112085)
		(end 145.39468 -227.9777)
		(width 0.09525)
		(layer "In2.Cu")
		(net "M_I_CPU1_SA_DQS_DN<1>")
	)
	(arc
		(start 141.57325 -232.009188)
		(mid 141.854682 -232.084943)
		(end 142.136114 -232.009188)
		(width 0.09525)
		(layer "In2.Cu")
		(net "M_I_CPU1_SA_DQS_DN<1>")
	)
	(arc
		(start 144.297146 -229.90429)
		(mid 144.338811 -229.731843)
		(end 144.454626 -229.597458)
		(width 0.09525)
		(layer "In2.Cu")
		(net "M_I_CPU1_SA_DQS_DN<1>")
	)
	(arc
		(start 130.293364 -232.009188)
		(mid 130.574796 -232.084943)
		(end 130.856228 -232.009188)
		(width 0.09525)
		(layer "In2.Cu")
		(net "M_I_CPU1_SA_DQS_DN<1>")
	)
	(arc
		(start 142.136114 -232.009188)
		(mid 142.319889 -231.958416)
		(end 142.504922 -232.004362)
		(width 0.09525)
		(layer "In2.Cu")
		(net "M_I_CPU1_SA_DQS_DN<1>")
	)
	(arc
		(start 144.526508 -229.555548)
		(mid 144.70328 -229.354527)
		(end 144.767046 -229.094538)
		(width 0.09525)
		(layer "In2.Cu")
		(net "M_I_CPU1_SA_DQS_DN<1>")
	)
	(arc
		(start 138.376152 -232.009188)
		(mid 138.559927 -231.958416)
		(end 138.74496 -232.004362)
		(width 0.09525)
		(layer "In2.Cu")
		(net "M_I_CPU1_SA_DQS_DN<1>")
	)
	(arc
		(start 129.924556 -232.004362)
		(mid 130.109588 -231.958448)
		(end 130.293364 -232.009188)
		(width 0.09525)
		(layer "In2.Cu")
		(net "M_I_CPU1_SA_DQS_DN<1>")
	)
	(arc
		(start 134.99338 -232.009188)
		(mid 135.274812 -232.084943)
		(end 135.556244 -232.009188)
		(width 0.09525)
		(layer "In2.Cu")
		(net "M_I_CPU1_SA_DQS_DN<1>")
	)
	(arc
		(start 132.736082 -232.009188)
		(mid 132.919857 -231.958416)
		(end 133.10489 -232.004362)
		(width 0.09525)
		(layer "In2.Cu")
		(net "M_I_CPU1_SA_DQS_DN<1>")
	)
	(arc
		(start 136.496298 -232.009188)
		(mid 136.684766 -231.958511)
		(end 136.873234 -232.009188)
		(width 0.09525)
		(layer "In2.Cu")
		(net "M_I_CPU1_SA_DQS_DN<1>")
	)
	(arc
		(start 145.706592 -227.474272)
		(mid 145.74776 -227.302798)
		(end 145.862294 -227.16871)
		(width 0.09525)
		(layer "In2.Cu")
		(net "M_I_CPU1_SA_DQS_DN<1>")
	)
	(arc
		(start 140.63345 -232.009188)
		(mid 140.914882 -232.084943)
		(end 141.196314 -232.009188)
		(width 0.09525)
		(layer "In2.Cu")
		(net "M_I_CPU1_SA_DQS_DN<1>")
	)
	(arc
		(start 139.324588 -232.004362)
		(mid 139.50962 -231.958448)
		(end 139.693396 -232.009188)
		(width 0.09525)
		(layer "In2.Cu")
		(net "M_I_CPU1_SA_DQS_DN<1>")
	)
	(arc
		(start 131.796282 -232.009188)
		(mid 131.98475 -231.958511)
		(end 132.173218 -232.009188)
		(width 0.09525)
		(layer "In2.Cu")
		(net "M_I_CPU1_SA_DQS_DN<1>")
	)
	(arc
		(start 144.051782 -230.368856)
		(mid 144.232075 -230.166993)
		(end 144.297146 -229.90429)
		(width 0.09525)
		(layer "In2.Cu")
		(net "M_I_CPU1_SA_DQS_DN<1>")
	)
	(arc
		(start 133.113272 -232.009188)
		(mid 133.394704 -232.084943)
		(end 133.676136 -232.009188)
		(width 0.09525)
		(layer "In2.Cu")
		(net "M_I_CPU1_SA_DQS_DN<1>")
	)
	(arc
		(start 144.994376 -228.74732)
		(mid 145.172826 -228.54585)
		(end 145.2372 -228.284532)
		(width 0.09525)
		(layer "In2.Cu")
		(net "M_I_CPU1_SA_DQS_DN<1>")
	)
	(arc
		(start 132.173218 -232.009188)
		(mid 132.45465 -232.084943)
		(end 132.736082 -232.009188)
		(width 0.09525)
		(layer "In2.Cu")
		(net "M_I_CPU1_SA_DQS_DN<1>")
	)
	(arc
		(start 142.513304 -232.009188)
		(mid 142.794736 -232.084943)
		(end 143.076168 -232.009188)
		(width 0.09525)
		(layer "In2.Cu")
		(net "M_I_CPU1_SA_DQS_DN<1>")
	)
	(arc
		(start 143.357092 -231.524302)
		(mid 143.398757 -231.351855)
		(end 143.514572 -231.21747)
		(width 0.09525)
		(layer "In2.Cu")
		(net "M_I_CPU1_SA_DQS_DN<1>")
	)
	(arc
		(start 139.693396 -232.009188)
		(mid 139.974828 -232.084943)
		(end 140.25626 -232.009188)
		(width 0.09525)
		(layer "In2.Cu")
		(net "M_I_CPU1_SA_DQS_DN<1>")
	)
	(arc
		(start 135.933434 -232.009188)
		(mid 136.214866 -232.084943)
		(end 136.496298 -232.009188)
		(width 0.09525)
		(layer "In2.Cu")
		(net "M_I_CPU1_SA_DQS_DN<1>")
	)
	(arc
		(start 135.564626 -232.004362)
		(mid 135.749658 -231.958448)
		(end 135.933434 -232.009188)
		(width 0.09525)
		(layer "In2.Cu")
		(net "M_I_CPU1_SA_DQS_DN<1>")
	)
	(arc
		(start 133.676136 -232.009188)
		(mid 133.859911 -231.958416)
		(end 134.044944 -232.004362)
		(width 0.09525)
		(layer "In2.Cu")
		(net "M_I_CPU1_SA_DQS_DN<1>")
	)
	(arc
		(start 129.439416 -232.050082)
		(mid 129.68238 -232.083069)
		(end 129.916174 -232.009188)
		(width 0.09525)
		(layer "In2.Cu")
		(net "M_I_CPU1_SA_DQS_DN<1>")
	)
	(arc
		(start 134.624572 -232.004362)
		(mid 134.809604 -231.958448)
		(end 134.99338 -232.009188)
		(width 0.09525)
		(layer "In2.Cu")
		(net "M_I_CPU1_SA_DQS_DN<1>")
	)
	(arc
		(start 136.873234 -232.009188)
		(mid 137.154666 -232.084943)
		(end 137.436098 -232.009188)
		(width 0.09525)
		(layer "In2.Cu")
		(net "M_I_CPU1_SA_DQS_DN<1>")
	)
	(arc
		(start 145.45818 -227.94087)
		(mid 145.640704 -227.738613)
		(end 145.706592 -227.474272)
		(width 0.09525)
		(layer "In2.Cu")
		(net "M_I_CPU1_SA_DQS_DN<1>")
	)
	(arc
		(start 143.586454 -231.17556)
		(mid 143.763226 -230.974539)
		(end 143.826992 -230.71455)
		(width 0.09525)
		(layer "In2.Cu")
		(net "M_I_CPU1_SA_DQS_DN<1>")
	)
	(arc
		(start 141.196314 -232.009188)
		(mid 141.384782 -231.958511)
		(end 141.57325 -232.009188)
		(width 0.09525)
		(layer "In2.Cu")
		(net "M_I_CPU1_SA_DQS_DN<1>")
	)
	(arc
		(start 131.233418 -232.009188)
		(mid 131.51485 -232.084943)
		(end 131.796282 -232.009188)
		(width 0.09525)
		(layer "In2.Cu")
		(net "M_I_CPU1_SA_DQS_DN<1>")
	)
	(arc
		(start 130.86461 -232.004362)
		(mid 131.049642 -231.958448)
		(end 131.233418 -232.009188)
		(width 0.09525)
		(layer "In2.Cu")
		(net "M_I_CPU1_SA_DQS_DN<1>")
	)
	(arc
		(start 144.767046 -229.094538)
		(mid 144.808503 -228.922498)
		(end 144.923764 -228.788214)
		(width 0.09525)
		(layer "In2.Cu")
		(net "M_I_CPU1_SA_DQS_DN<1>")
	)
	(arc
		(start 137.436098 -232.009188)
		(mid 137.619873 -231.958416)
		(end 137.804906 -232.004362)
		(width 0.09525)
		(layer "In2.Cu")
		(net "M_I_CPU1_SA_DQS_DN<1>")
	)
	(arc
		(start 138.753342 -232.009188)
		(mid 139.034774 -232.084943)
		(end 139.316206 -232.009188)
		(width 0.09525)
		(layer "In2.Cu")
		(net "M_I_CPU1_SA_DQS_DN<1>")
	)
	(arc
		(start 137.813288 -232.009188)
		(mid 138.09472 -232.084943)
		(end 138.376152 -232.009188)
		(width 0.09525)
		(layer "In2.Cu")
		(net "M_I_CPU1_SA_DQS_DN<1>")
	)
	(arc
		(start 143.826992 -230.71455)
		(mid 143.868449 -230.54251)
		(end 143.98371 -230.408226)
		(width 0.09525)
		(layer "In2.Cu")
		(net "M_I_CPU1_SA_DQS_DN<1>")
	)
	(arc
		(start 140.264642 -232.004362)
		(mid 140.449674 -231.958448)
		(end 140.63345 -232.009188)
		(width 0.09525)
		(layer "In2.Cu")
		(net "M_I_CPU1_SA_DQS_DN<1>")
	)
	(arc
		(start 134.053326 -232.009188)
		(mid 134.334758 -232.084943)
		(end 134.61619 -232.009188)
		(width 0.09525)
		(layer "In2.Cu")
		(net "M_I_CPU1_SA_DQS_DN<1>")
	)
	(arc
		(start 129.419604 -232.042208)
		(mid 129.429472 -232.046239)
		(end 129.439416 -232.050082)
		(width 0.09525)
		(layer "In2.Cu")
		(net "M_I_CPU1_SA_DQS_DN<1>")
	)
	(segment
		(start 128.69799 -227.740464)
		(end 129.164842 -227.474526)
		(width 0.12954)
		(layer "F.Cu")
		(net "M_I_CPU1_SA_DQS_DN<0>")
	)
	(segment
		(start 179.128166 -200.886568)
		(end 180.019706 -200.886568)
		(width 0.16002)
		(layer "In2.Cu")
		(net "M_I_CPU1_SA_DQS_DN<0>")
	)
	(segment
		(start 177.360326 -200.312528)
		(end 177.934366 -200.886568)
		(width 0.16002)
		(layer "In2.Cu")
		(net "M_I_CPU1_SA_DQS_DN<0>")
	)
	(segment
		(start 165.207696 -201.162412)
		(end 165.515036 -201.469752)
		(width 0.16002)
		(layer "In2.Cu")
		(net "M_I_CPU1_SA_DQS_DN<0>")
	)
	(segment
		(start 129.916174 -227.149406)
		(end 129.924556 -227.14458)
		(width 0.09525)
		(layer "In2.Cu")
		(net "M_I_CPU1_SA_DQS_DN<0>")
	)
	(segment
		(start 178.414426 -200.886568)
		(end 178.531266 -201.003408)
		(width 0.16002)
		(layer "In2.Cu")
		(net "M_I_CPU1_SA_DQS_DN<0>")
	)
	(segment
		(start 129.318766 -227.209096)
		(end 129.419604 -227.182426)
		(width 0.09525)
		(layer "In2.Cu")
		(net "M_I_CPU1_SA_DQS_DN<0>")
	)
	(segment
		(start 175.333914 -200.312528)
		(end 177.360326 -200.312528)
		(width 0.16002)
		(layer "In2.Cu")
		(net "M_I_CPU1_SA_DQS_DN<0>")
	)
	(segment
		(start 173.651418 -201.469752)
		(end 174.492158 -200.629012)
		(width 0.16002)
		(layer "In2.Cu")
		(net "M_I_CPU1_SA_DQS_DN<0>")
	)
	(segment
		(start 143.41602 -221.198186)
		(end 143.41602 -221.174564)
		(width 0.09525)
		(layer "In2.Cu")
		(net "M_I_CPU1_SA_DQS_DN<0>")
	)
	(segment
		(start 140.72616 -226.3394)
		(end 140.76426 -226.317302)
		(width 0.09525)
		(layer "In2.Cu")
		(net "M_I_CPU1_SA_DQS_DN<0>")
	)
	(segment
		(start 160.737042 -201.162412)
		(end 165.207696 -201.162412)
		(width 0.16002)
		(layer "In2.Cu")
		(net "M_I_CPU1_SA_DQS_DN<0>")
	)
	(segment
		(start 135.556244 -227.149406)
		(end 135.564626 -227.14458)
		(width 0.09525)
		(layer "In2.Cu")
		(net "M_I_CPU1_SA_DQS_DN<0>")
	)
	(segment
		(start 165.515036 -201.469752)
		(end 166.107364 -201.469752)
		(width 0.16002)
		(layer "In2.Cu")
		(net "M_I_CPU1_SA_DQS_DN<0>")
	)
	(segment
		(start 139.316206 -227.149406)
		(end 139.324588 -227.14458)
		(width 0.09525)
		(layer "In2.Cu")
		(net "M_I_CPU1_SA_DQS_DN<0>")
	)
	(segment
		(start 129.164842 -227.474526)
		(end 129.318766 -227.209096)
		(width 0.09525)
		(layer "In2.Cu")
		(net "M_I_CPU1_SA_DQS_DN<0>")
	)
	(segment
		(start 143.046958 -222.30588)
		(end 143.114268 -222.266764)
		(width 0.09525)
		(layer "In2.Cu")
		(net "M_I_CPU1_SA_DQS_DN<0>")
	)
	(segment
		(start 181.467506 -201.312272)
		(end 183.343042 -201.312272)
		(width 0.16002)
		(layer "In2.Cu")
		(net "M_I_CPU1_SA_DQS_DN<0>")
	)
	(segment
		(start 167.78986 -200.312528)
		(end 169.76852 -200.312528)
		(width 0.16002)
		(layer "In2.Cu")
		(net "M_I_CPU1_SA_DQS_DN<0>")
	)
	(segment
		(start 140.694664 -226.357688)
		(end 140.72616 -226.3394)
		(width 0.09525)
		(layer "In2.Cu")
		(net "M_I_CPU1_SA_DQS_DN<0>")
	)
	(segment
		(start 166.107364 -201.469752)
		(end 166.948104 -200.629012)
		(width 0.16002)
		(layer "In2.Cu")
		(net "M_I_CPU1_SA_DQS_DN<0>")
	)
	(segment
		(start 172.75175 -201.162412)
		(end 173.05909 -201.469752)
		(width 0.16002)
		(layer "In2.Cu")
		(net "M_I_CPU1_SA_DQS_DN<0>")
	)
	(segment
		(start 178.531266 -201.003408)
		(end 179.011326 -201.003408)
		(width 0.16002)
		(layer "In2.Cu")
		(net "M_I_CPU1_SA_DQS_DN<0>")
	)
	(segment
		(start 170.618404 -201.162412)
		(end 172.75175 -201.162412)
		(width 0.16002)
		(layer "In2.Cu")
		(net "M_I_CPU1_SA_DQS_DN<0>")
	)
	(segment
		(start 137.805922 -227.145088)
		(end 137.813288 -227.149406)
		(width 0.09525)
		(layer "In2.Cu")
		(net "M_I_CPU1_SA_DQS_DN<0>")
	)
	(segment
		(start 141.163802 -225.54819)
		(end 141.196314 -225.529394)
		(width 0.09525)
		(layer "In2.Cu")
		(net "M_I_CPU1_SA_DQS_DN<0>")
	)
	(segment
		(start 138.74496 -227.14458)
		(end 138.753342 -227.149406)
		(width 0.09525)
		(layer "In2.Cu")
		(net "M_I_CPU1_SA_DQS_DN<0>")
	)
	(segment
		(start 142.574518 -223.117664)
		(end 142.606014 -223.099376)
		(width 0.09525)
		(layer "In2.Cu")
		(net "M_I_CPU1_SA_DQS_DN<0>")
	)
	(segment
		(start 181.284626 -201.495152)
		(end 181.467506 -201.312272)
		(width 0.16002)
		(layer "In2.Cu")
		(net "M_I_CPU1_SA_DQS_DN<0>")
	)
	(segment
		(start 169.76852 -200.312528)
		(end 170.618404 -201.162412)
		(width 0.16002)
		(layer "In2.Cu")
		(net "M_I_CPU1_SA_DQS_DN<0>")
	)
	(segment
		(start 140.25626 -227.149406)
		(end 140.29436 -227.127308)
		(width 0.09525)
		(layer "In2.Cu")
		(net "M_I_CPU1_SA_DQS_DN<0>")
	)
	(segment
		(start 173.05909 -201.469752)
		(end 173.651418 -201.469752)
		(width 0.16002)
		(layer "In2.Cu")
		(net "M_I_CPU1_SA_DQS_DN<0>")
	)
	(segment
		(start 149.329648 -212.569806)
		(end 160.737042 -201.162412)
		(width 0.16002)
		(layer "In2.Cu")
		(net "M_I_CPU1_SA_DQS_DN<0>")
	)
	(segment
		(start 143.044418 -222.307658)
		(end 143.046958 -222.30588)
		(width 0.09525)
		(layer "In2.Cu")
		(net "M_I_CPU1_SA_DQS_DN<0>")
	)
	(segment
		(start 142.606014 -223.099376)
		(end 142.644114 -223.077278)
		(width 0.09525)
		(layer "In2.Cu")
		(net "M_I_CPU1_SA_DQS_DN<0>")
	)
	(segment
		(start 143.41602 -219.816934)
		(end 149.329648 -213.903306)
		(width 0.16002)
		(layer "In2.Cu")
		(net "M_I_CPU1_SA_DQS_DN<0>")
	)
	(segment
		(start 179.011326 -201.003408)
		(end 179.128166 -200.886568)
		(width 0.16002)
		(layer "In2.Cu")
		(net "M_I_CPU1_SA_DQS_DN<0>")
	)
	(segment
		(start 180.62829 -201.495152)
		(end 181.284626 -201.495152)
		(width 0.16002)
		(layer "In2.Cu")
		(net "M_I_CPU1_SA_DQS_DN<0>")
	)
	(segment
		(start 183.343042 -201.312272)
		(end 183.616092 -201.585322)
		(width 0.16002)
		(layer "In2.Cu")
		(net "M_I_CPU1_SA_DQS_DN<0>")
	)
	(segment
		(start 143.356838 -221.803976)
		(end 143.356838 -221.257368)
		(width 0.09525)
		(layer "In2.Cu")
		(net "M_I_CPU1_SA_DQS_DN<0>")
	)
	(segment
		(start 133.10489 -227.14458)
		(end 133.113272 -227.149406)
		(width 0.09525)
		(layer "In2.Cu")
		(net "M_I_CPU1_SA_DQS_DN<0>")
	)
	(segment
		(start 180.019706 -200.886568)
		(end 180.62829 -201.495152)
		(width 0.16002)
		(layer "In2.Cu")
		(net "M_I_CPU1_SA_DQS_DN<0>")
	)
	(segment
		(start 149.329648 -213.903306)
		(end 149.329648 -212.569806)
		(width 0.16002)
		(layer "In2.Cu")
		(net "M_I_CPU1_SA_DQS_DN<0>")
	)
	(segment
		(start 142.136114 -223.909382)
		(end 142.174214 -223.887284)
		(width 0.09525)
		(layer "In2.Cu")
		(net "M_I_CPU1_SA_DQS_DN<0>")
	)
	(segment
		(start 174.492158 -200.629012)
		(end 175.01743 -200.629012)
		(width 0.16002)
		(layer "In2.Cu")
		(net "M_I_CPU1_SA_DQS_DN<0>")
	)
	(segment
		(start 175.01743 -200.629012)
		(end 175.333914 -200.312528)
		(width 0.16002)
		(layer "In2.Cu")
		(net "M_I_CPU1_SA_DQS_DN<0>")
	)
	(segment
		(start 143.41602 -221.174564)
		(end 143.41602 -219.816934)
		(width 0.16002)
		(layer "In2.Cu")
		(net "M_I_CPU1_SA_DQS_DN<0>")
	)
	(segment
		(start 141.666214 -224.719388)
		(end 141.704314 -224.69729)
		(width 0.09525)
		(layer "In2.Cu")
		(net "M_I_CPU1_SA_DQS_DN<0>")
	)
	(segment
		(start 141.633702 -224.738184)
		(end 141.666214 -224.719388)
		(width 0.09525)
		(layer "In2.Cu")
		(net "M_I_CPU1_SA_DQS_DN<0>")
	)
	(segment
		(start 166.948104 -200.629012)
		(end 167.473376 -200.629012)
		(width 0.16002)
		(layer "In2.Cu")
		(net "M_I_CPU1_SA_DQS_DN<0>")
	)
	(segment
		(start 134.61619 -227.149406)
		(end 134.624572 -227.14458)
		(width 0.09525)
		(layer "In2.Cu")
		(net "M_I_CPU1_SA_DQS_DN<0>")
	)
	(segment
		(start 143.356838 -221.257368)
		(end 143.41602 -221.198186)
		(width 0.09525)
		(layer "In2.Cu")
		(net "M_I_CPU1_SA_DQS_DN<0>")
	)
	(segment
		(start 134.044944 -227.14458)
		(end 134.053326 -227.149406)
		(width 0.09525)
		(layer "In2.Cu")
		(net "M_I_CPU1_SA_DQS_DN<0>")
	)
	(segment
		(start 130.856228 -227.149406)
		(end 130.86461 -227.14458)
		(width 0.09525)
		(layer "In2.Cu")
		(net "M_I_CPU1_SA_DQS_DN<0>")
	)
	(segment
		(start 167.473376 -200.629012)
		(end 167.78986 -200.312528)
		(width 0.16002)
		(layer "In2.Cu")
		(net "M_I_CPU1_SA_DQS_DN<0>")
	)
	(segment
		(start 177.934366 -200.886568)
		(end 178.414426 -200.886568)
		(width 0.16002)
		(layer "In2.Cu")
		(net "M_I_CPU1_SA_DQS_DN<0>")
	)
	(segment
		(start 142.104618 -223.92767)
		(end 142.136114 -223.909382)
		(width 0.09525)
		(layer "In2.Cu")
		(net "M_I_CPU1_SA_DQS_DN<0>")
	)
	(segment
		(start 141.196314 -225.529394)
		(end 141.231366 -225.50882)
		(width 0.09525)
		(layer "In2.Cu")
		(net "M_I_CPU1_SA_DQS_DN<0>")
	)
	(segment
		(start 137.804906 -227.14458)
		(end 137.805922 -227.145088)
		(width 0.09525)
		(layer "In2.Cu")
		(net "M_I_CPU1_SA_DQS_DN<0>")
	)
	(arc
		(start 140.537184 -226.66452)
		(mid 140.578849 -226.492073)
		(end 140.694664 -226.357688)
		(width 0.09525)
		(layer "In2.Cu")
		(net "M_I_CPU1_SA_DQS_DN<0>")
	)
	(arc
		(start 133.113272 -227.149406)
		(mid 133.394704 -227.225161)
		(end 133.676136 -227.149406)
		(width 0.09525)
		(layer "In2.Cu")
		(net "M_I_CPU1_SA_DQS_DN<0>")
	)
	(arc
		(start 134.99338 -227.149406)
		(mid 135.274812 -227.225161)
		(end 135.556244 -227.149406)
		(width 0.09525)
		(layer "In2.Cu")
		(net "M_I_CPU1_SA_DQS_DN<0>")
	)
	(arc
		(start 142.886938 -222.61449)
		(mid 142.928603 -222.442043)
		(end 143.044418 -222.307658)
		(width 0.09525)
		(layer "In2.Cu")
		(net "M_I_CPU1_SA_DQS_DN<0>")
	)
	(arc
		(start 143.114268 -222.266764)
		(mid 143.292563 -222.065243)
		(end 143.356838 -221.803976)
		(width 0.09525)
		(layer "In2.Cu")
		(net "M_I_CPU1_SA_DQS_DN<0>")
	)
	(arc
		(start 137.813288 -227.149406)
		(mid 138.09472 -227.225161)
		(end 138.376152 -227.149406)
		(width 0.09525)
		(layer "In2.Cu")
		(net "M_I_CPU1_SA_DQS_DN<0>")
	)
	(arc
		(start 131.796282 -227.149406)
		(mid 131.98475 -227.098729)
		(end 132.173218 -227.149406)
		(width 0.09525)
		(layer "In2.Cu")
		(net "M_I_CPU1_SA_DQS_DN<0>")
	)
	(arc
		(start 138.753342 -227.149406)
		(mid 139.034774 -227.225161)
		(end 139.316206 -227.149406)
		(width 0.09525)
		(layer "In2.Cu")
		(net "M_I_CPU1_SA_DQS_DN<0>")
	)
	(arc
		(start 133.676136 -227.149406)
		(mid 133.859911 -227.098634)
		(end 134.044944 -227.14458)
		(width 0.09525)
		(layer "In2.Cu")
		(net "M_I_CPU1_SA_DQS_DN<0>")
	)
	(arc
		(start 135.933434 -227.149406)
		(mid 136.214866 -227.225161)
		(end 136.496298 -227.149406)
		(width 0.09525)
		(layer "In2.Cu")
		(net "M_I_CPU1_SA_DQS_DN<0>")
	)
	(arc
		(start 129.419604 -227.182426)
		(mid 129.429472 -227.186457)
		(end 129.439416 -227.1903)
		(width 0.09525)
		(layer "In2.Cu")
		(net "M_I_CPU1_SA_DQS_DN<0>")
	)
	(arc
		(start 142.644114 -223.077278)
		(mid 142.822564 -222.875808)
		(end 142.886938 -222.61449)
		(width 0.09525)
		(layer "In2.Cu")
		(net "M_I_CPU1_SA_DQS_DN<0>")
	)
	(arc
		(start 129.924556 -227.14458)
		(mid 130.109588 -227.098666)
		(end 130.293364 -227.149406)
		(width 0.09525)
		(layer "In2.Cu")
		(net "M_I_CPU1_SA_DQS_DN<0>")
	)
	(arc
		(start 132.173218 -227.149406)
		(mid 132.45465 -227.225161)
		(end 132.736082 -227.149406)
		(width 0.09525)
		(layer "In2.Cu")
		(net "M_I_CPU1_SA_DQS_DN<0>")
	)
	(arc
		(start 139.324588 -227.14458)
		(mid 139.50962 -227.098666)
		(end 139.693396 -227.149406)
		(width 0.09525)
		(layer "In2.Cu")
		(net "M_I_CPU1_SA_DQS_DN<0>")
	)
	(arc
		(start 130.293364 -227.149406)
		(mid 130.574796 -227.225161)
		(end 130.856228 -227.149406)
		(width 0.09525)
		(layer "In2.Cu")
		(net "M_I_CPU1_SA_DQS_DN<0>")
	)
	(arc
		(start 141.947138 -224.234502)
		(mid 141.988803 -224.062055)
		(end 142.104618 -223.92767)
		(width 0.09525)
		(layer "In2.Cu")
		(net "M_I_CPU1_SA_DQS_DN<0>")
	)
	(arc
		(start 142.417038 -223.424496)
		(mid 142.458703 -223.252049)
		(end 142.574518 -223.117664)
		(width 0.09525)
		(layer "In2.Cu")
		(net "M_I_CPU1_SA_DQS_DN<0>")
	)
	(arc
		(start 137.436098 -227.149406)
		(mid 137.619873 -227.098634)
		(end 137.804906 -227.14458)
		(width 0.09525)
		(layer "In2.Cu")
		(net "M_I_CPU1_SA_DQS_DN<0>")
	)
	(arc
		(start 132.736082 -227.149406)
		(mid 132.919857 -227.098634)
		(end 133.10489 -227.14458)
		(width 0.09525)
		(layer "In2.Cu")
		(net "M_I_CPU1_SA_DQS_DN<0>")
	)
	(arc
		(start 135.564626 -227.14458)
		(mid 135.749658 -227.098666)
		(end 135.933434 -227.149406)
		(width 0.09525)
		(layer "In2.Cu")
		(net "M_I_CPU1_SA_DQS_DN<0>")
	)
	(arc
		(start 131.233418 -227.149406)
		(mid 131.51485 -227.225161)
		(end 131.796282 -227.149406)
		(width 0.09525)
		(layer "In2.Cu")
		(net "M_I_CPU1_SA_DQS_DN<0>")
	)
	(arc
		(start 134.053326 -227.149406)
		(mid 134.334758 -227.225161)
		(end 134.61619 -227.149406)
		(width 0.09525)
		(layer "In2.Cu")
		(net "M_I_CPU1_SA_DQS_DN<0>")
	)
	(arc
		(start 129.439416 -227.1903)
		(mid 129.68238 -227.223287)
		(end 129.916174 -227.149406)
		(width 0.09525)
		(layer "In2.Cu")
		(net "M_I_CPU1_SA_DQS_DN<0>")
	)
	(arc
		(start 141.476984 -225.044508)
		(mid 141.518441 -224.872468)
		(end 141.633702 -224.738184)
		(width 0.09525)
		(layer "In2.Cu")
		(net "M_I_CPU1_SA_DQS_DN<0>")
	)
	(arc
		(start 141.231366 -225.50882)
		(mid 141.411757 -225.307121)
		(end 141.476984 -225.044508)
		(width 0.09525)
		(layer "In2.Cu")
		(net "M_I_CPU1_SA_DQS_DN<0>")
	)
	(arc
		(start 136.496298 -227.149406)
		(mid 136.684766 -227.098729)
		(end 136.873234 -227.149406)
		(width 0.09525)
		(layer "In2.Cu")
		(net "M_I_CPU1_SA_DQS_DN<0>")
	)
	(arc
		(start 140.76426 -226.317302)
		(mid 140.94271 -226.115832)
		(end 141.007084 -225.854514)
		(width 0.09525)
		(layer "In2.Cu")
		(net "M_I_CPU1_SA_DQS_DN<0>")
	)
	(arc
		(start 139.693396 -227.149406)
		(mid 139.974828 -227.225161)
		(end 140.25626 -227.149406)
		(width 0.09525)
		(layer "In2.Cu")
		(net "M_I_CPU1_SA_DQS_DN<0>")
	)
	(arc
		(start 138.376152 -227.149406)
		(mid 138.559927 -227.098634)
		(end 138.74496 -227.14458)
		(width 0.09525)
		(layer "In2.Cu")
		(net "M_I_CPU1_SA_DQS_DN<0>")
	)
	(arc
		(start 130.86461 -227.14458)
		(mid 131.049642 -227.098666)
		(end 131.233418 -227.149406)
		(width 0.09525)
		(layer "In2.Cu")
		(net "M_I_CPU1_SA_DQS_DN<0>")
	)
	(arc
		(start 134.624572 -227.14458)
		(mid 134.809604 -227.098666)
		(end 134.99338 -227.149406)
		(width 0.09525)
		(layer "In2.Cu")
		(net "M_I_CPU1_SA_DQS_DN<0>")
	)
	(arc
		(start 142.174214 -223.887284)
		(mid 142.352664 -223.685814)
		(end 142.417038 -223.424496)
		(width 0.09525)
		(layer "In2.Cu")
		(net "M_I_CPU1_SA_DQS_DN<0>")
	)
	(arc
		(start 140.29436 -227.127308)
		(mid 140.47281 -226.925838)
		(end 140.537184 -226.66452)
		(width 0.09525)
		(layer "In2.Cu")
		(net "M_I_CPU1_SA_DQS_DN<0>")
	)
	(arc
		(start 136.873234 -227.149406)
		(mid 137.154666 -227.225161)
		(end 137.436098 -227.149406)
		(width 0.09525)
		(layer "In2.Cu")
		(net "M_I_CPU1_SA_DQS_DN<0>")
	)
	(arc
		(start 141.704314 -224.69729)
		(mid 141.882764 -224.49582)
		(end 141.947138 -224.234502)
		(width 0.09525)
		(layer "In2.Cu")
		(net "M_I_CPU1_SA_DQS_DN<0>")
	)
	(arc
		(start 141.007084 -225.854514)
		(mid 141.048541 -225.682474)
		(end 141.163802 -225.54819)
		(width 0.09525)
		(layer "In2.Cu")
		(net "M_I_CPU1_SA_DQS_DN<0>")
	)
	(segment
		(start 127.757936 -230.980234)
		(end 128.224788 -230.71455)
		(width 0.10668)
		(layer "F.Cu")
		(net "M_I_CPU1_SA_DQ<9>")
	)
	(segment
		(start 128.07061 -230.97998)
		(end 128.092708 -231.063038)
		(width 0.0889)
		(layer "In2.Cu")
		(net "M_I_CPU1_SA_DQ<9>")
	)
	(segment
		(start 144.352772 -227.819966)
		(end 144.391888 -227.797106)
		(width 0.0889)
		(layer "In2.Cu")
		(net "M_I_CPU1_SA_DQ<9>")
	)
	(segment
		(start 145.472912 -226.0219)
		(end 145.759932 -225.553524)
		(width 0.0889)
		(layer "In2.Cu")
		(net "M_I_CPU1_SA_DQ<9>")
	)
	(segment
		(start 166.180262 -208.810352)
		(end 167.030146 -207.960468)
		(width 0.14478)
		(layer "In2.Cu")
		(net "M_I_CPU1_SA_DQ<9>")
	)
	(segment
		(start 142.503398 -231.041702)
		(end 142.51178 -231.036876)
		(width 0.0889)
		(layer "In2.Cu")
		(net "M_I_CPU1_SA_DQ<9>")
	)
	(segment
		(start 139.31773 -231.036876)
		(end 139.326112 -231.041702)
		(width 0.0889)
		(layer "In2.Cu")
		(net "M_I_CPU1_SA_DQ<9>")
	)
	(segment
		(start 160.401508 -208.810352)
		(end 166.180262 -208.810352)
		(width 0.14478)
		(layer "In2.Cu")
		(net "M_I_CPU1_SA_DQ<9>")
	)
	(segment
		(start 153.44013 -215.77173)
		(end 160.401508 -208.810352)
		(width 0.14478)
		(layer "In2.Cu")
		(net "M_I_CPU1_SA_DQ<9>")
	)
	(segment
		(start 134.04342 -231.041702)
		(end 134.051802 -231.036876)
		(width 0.0889)
		(layer "In2.Cu")
		(net "M_I_CPU1_SA_DQ<9>")
	)
	(segment
		(start 144.861788 -226.9871)
		(end 144.893538 -226.968812)
		(width 0.0889)
		(layer "In2.Cu")
		(net "M_I_CPU1_SA_DQ<9>")
	)
	(segment
		(start 174.34433 -207.960468)
		(end 183.19115 -207.960468)
		(width 0.14478)
		(layer "In2.Cu")
		(net "M_I_CPU1_SA_DQ<9>")
	)
	(segment
		(start 173.494446 -208.810352)
		(end 174.34433 -207.960468)
		(width 0.14478)
		(layer "In2.Cu")
		(net "M_I_CPU1_SA_DQ<9>")
	)
	(segment
		(start 143.451834 -229.416864)
		(end 143.484346 -229.398068)
		(width 0.0889)
		(layer "In2.Cu")
		(net "M_I_CPU1_SA_DQ<9>")
	)
	(segment
		(start 145.759932 -225.553524)
		(end 145.759932 -225.06813)
		(width 0.0889)
		(layer "In2.Cu")
		(net "M_I_CPU1_SA_DQ<9>")
	)
	(segment
		(start 143.882618 -228.629972)
		(end 143.921734 -228.607112)
		(width 0.0889)
		(layer "In2.Cu")
		(net "M_I_CPU1_SA_DQ<9>")
	)
	(segment
		(start 134.617714 -231.036876)
		(end 134.626096 -231.041702)
		(width 0.0889)
		(layer "In2.Cu")
		(net "M_I_CPU1_SA_DQ<9>")
	)
	(segment
		(start 144.822672 -227.00996)
		(end 144.861788 -226.9871)
		(width 0.0889)
		(layer "In2.Cu")
		(net "M_I_CPU1_SA_DQ<9>")
	)
	(segment
		(start 143.921734 -228.607112)
		(end 143.953484 -228.588824)
		(width 0.0889)
		(layer "In2.Cu")
		(net "M_I_CPU1_SA_DQ<9>")
	)
	(segment
		(start 128.40335 -231.041702)
		(end 128.411732 -231.036876)
		(width 0.0889)
		(layer "In2.Cu")
		(net "M_I_CPU1_SA_DQ<9>")
	)
	(segment
		(start 146.84629 -223.664272)
		(end 153.44013 -217.070432)
		(width 0.14478)
		(layer "In2.Cu")
		(net "M_I_CPU1_SA_DQ<9>")
	)
	(segment
		(start 128.224788 -230.71455)
		(end 128.07061 -230.97998)
		(width 0.0889)
		(layer "In2.Cu")
		(net "M_I_CPU1_SA_DQ<9>")
	)
	(segment
		(start 143.412718 -229.439724)
		(end 143.451834 -229.416864)
		(width 0.0889)
		(layer "In2.Cu")
		(net "M_I_CPU1_SA_DQ<9>")
	)
	(segment
		(start 142.948152 -230.246428)
		(end 142.98168 -230.22687)
		(width 0.0889)
		(layer "In2.Cu")
		(net "M_I_CPU1_SA_DQ<9>")
	)
	(segment
		(start 153.44013 -217.070432)
		(end 153.44013 -215.77173)
		(width 0.14478)
		(layer "In2.Cu")
		(net "M_I_CPU1_SA_DQ<9>")
	)
	(segment
		(start 167.030146 -207.960468)
		(end 170.10761 -207.960468)
		(width 0.14478)
		(layer "In2.Cu")
		(net "M_I_CPU1_SA_DQ<9>")
	)
	(segment
		(start 146.512026 -223.998536)
		(end 146.84629 -223.664272)
		(width 0.0889)
		(layer "In2.Cu")
		(net "M_I_CPU1_SA_DQ<9>")
	)
	(segment
		(start 142.98168 -230.22687)
		(end 143.01343 -230.208582)
		(width 0.0889)
		(layer "In2.Cu")
		(net "M_I_CPU1_SA_DQ<9>")
	)
	(segment
		(start 135.557768 -231.036876)
		(end 135.56615 -231.041702)
		(width 0.0889)
		(layer "In2.Cu")
		(net "M_I_CPU1_SA_DQ<9>")
	)
	(segment
		(start 129.917698 -231.036876)
		(end 129.92608 -231.041702)
		(width 0.0889)
		(layer "In2.Cu")
		(net "M_I_CPU1_SA_DQ<9>")
	)
	(segment
		(start 129.343404 -231.041702)
		(end 129.351786 -231.036876)
		(width 0.0889)
		(layer "In2.Cu")
		(net "M_I_CPU1_SA_DQ<9>")
	)
	(segment
		(start 183.19115 -207.960468)
		(end 183.616092 -208.38541)
		(width 0.14478)
		(layer "In2.Cu")
		(net "M_I_CPU1_SA_DQ<9>")
	)
	(segment
		(start 138.743436 -231.041702)
		(end 138.751818 -231.036876)
		(width 0.0889)
		(layer "In2.Cu")
		(net "M_I_CPU1_SA_DQ<9>")
	)
	(segment
		(start 145.292826 -226.199954)
		(end 145.331942 -226.177094)
		(width 0.0889)
		(layer "In2.Cu")
		(net "M_I_CPU1_SA_DQ<9>")
	)
	(segment
		(start 137.803382 -231.041702)
		(end 137.811764 -231.036876)
		(width 0.0889)
		(layer "In2.Cu")
		(net "M_I_CPU1_SA_DQ<9>")
	)
	(segment
		(start 170.957494 -208.810352)
		(end 173.494446 -208.810352)
		(width 0.14478)
		(layer "In2.Cu")
		(net "M_I_CPU1_SA_DQ<9>")
	)
	(segment
		(start 142.51178 -231.036876)
		(end 142.545308 -231.017318)
		(width 0.0889)
		(layer "In2.Cu")
		(net "M_I_CPU1_SA_DQ<9>")
	)
	(segment
		(start 146.512026 -224.316036)
		(end 146.512026 -223.998536)
		(width 0.0889)
		(layer "In2.Cu")
		(net "M_I_CPU1_SA_DQ<9>")
	)
	(segment
		(start 170.10761 -207.960468)
		(end 170.957494 -208.810352)
		(width 0.14478)
		(layer "In2.Cu")
		(net "M_I_CPU1_SA_DQ<9>")
	)
	(segment
		(start 145.759932 -225.06813)
		(end 146.512026 -224.316036)
		(width 0.0889)
		(layer "In2.Cu")
		(net "M_I_CPU1_SA_DQ<9>")
	)
	(segment
		(start 133.103366 -231.041702)
		(end 133.111748 -231.036876)
		(width 0.0889)
		(layer "In2.Cu")
		(net "M_I_CPU1_SA_DQ<9>")
	)
	(segment
		(start 130.857752 -231.036876)
		(end 130.866134 -231.041702)
		(width 0.0889)
		(layer "In2.Cu")
		(net "M_I_CPU1_SA_DQ<9>")
	)
	(segment
		(start 140.257784 -231.036876)
		(end 140.266166 -231.041702)
		(width 0.0889)
		(layer "In2.Cu")
		(net "M_I_CPU1_SA_DQ<9>")
	)
	(segment
		(start 144.391888 -227.797106)
		(end 144.422368 -227.779326)
		(width 0.0889)
		(layer "In2.Cu")
		(net "M_I_CPU1_SA_DQ<9>")
	)
	(arc
		(start 129.351786 -231.036876)
		(mid 129.634742 -230.960699)
		(end 129.917698 -231.036876)
		(width 0.0889)
		(layer "In2.Cu")
		(net "M_I_CPU1_SA_DQ<9>")
	)
	(arc
		(start 144.893538 -226.968812)
		(mid 145.008214 -226.835478)
		(end 145.049494 -226.66452)
		(width 0.0889)
		(layer "In2.Cu")
		(net "M_I_CPU1_SA_DQ<9>")
	)
	(arc
		(start 130.866134 -231.041702)
		(mid 131.049642 -231.087227)
		(end 131.231894 -231.036876)
		(width 0.0889)
		(layer "In2.Cu")
		(net "M_I_CPU1_SA_DQ<9>")
	)
	(arc
		(start 140.631926 -231.036876)
		(mid 140.914882 -230.960699)
		(end 141.197838 -231.036876)
		(width 0.0889)
		(layer "In2.Cu")
		(net "M_I_CPU1_SA_DQ<9>")
	)
	(arc
		(start 139.691872 -231.036876)
		(mid 139.974828 -230.960699)
		(end 140.257784 -231.036876)
		(width 0.0889)
		(layer "In2.Cu")
		(net "M_I_CPU1_SA_DQ<9>")
	)
	(arc
		(start 130.29184 -231.036876)
		(mid 130.574796 -230.960699)
		(end 130.857752 -231.036876)
		(width 0.0889)
		(layer "In2.Cu")
		(net "M_I_CPU1_SA_DQ<9>")
	)
	(arc
		(start 141.571726 -231.036876)
		(mid 141.854682 -230.960699)
		(end 142.137638 -231.036876)
		(width 0.0889)
		(layer "In2.Cu")
		(net "M_I_CPU1_SA_DQ<9>")
	)
	(arc
		(start 137.811764 -231.036876)
		(mid 138.09472 -230.960699)
		(end 138.377676 -231.036876)
		(width 0.0889)
		(layer "In2.Cu")
		(net "M_I_CPU1_SA_DQ<9>")
	)
	(arc
		(start 131.231894 -231.036876)
		(mid 131.51485 -230.960699)
		(end 131.797806 -231.036876)
		(width 0.0889)
		(layer "In2.Cu")
		(net "M_I_CPU1_SA_DQ<9>")
	)
	(arc
		(start 128.977644 -231.036876)
		(mid 129.159895 -231.08726)
		(end 129.343404 -231.041702)
		(width 0.0889)
		(layer "In2.Cu")
		(net "M_I_CPU1_SA_DQ<9>")
	)
	(arc
		(start 136.497822 -231.036876)
		(mid 136.684766 -231.087165)
		(end 136.87171 -231.036876)
		(width 0.0889)
		(layer "In2.Cu")
		(net "M_I_CPU1_SA_DQ<9>")
	)
	(arc
		(start 131.797806 -231.036876)
		(mid 131.98475 -231.087165)
		(end 132.171694 -231.036876)
		(width 0.0889)
		(layer "In2.Cu")
		(net "M_I_CPU1_SA_DQ<9>")
	)
	(arc
		(start 143.639286 -229.094538)
		(mid 143.703801 -228.832319)
		(end 143.882618 -228.629972)
		(width 0.0889)
		(layer "In2.Cu")
		(net "M_I_CPU1_SA_DQ<9>")
	)
	(arc
		(start 128.411732 -231.036876)
		(mid 128.694688 -230.960699)
		(end 128.977644 -231.036876)
		(width 0.0889)
		(layer "In2.Cu")
		(net "M_I_CPU1_SA_DQ<9>")
	)
	(arc
		(start 133.111748 -231.036876)
		(mid 133.394704 -230.960699)
		(end 133.67766 -231.036876)
		(width 0.0889)
		(layer "In2.Cu")
		(net "M_I_CPU1_SA_DQ<9>")
	)
	(arc
		(start 137.437622 -231.036876)
		(mid 137.619873 -231.08726)
		(end 137.803382 -231.041702)
		(width 0.0889)
		(layer "In2.Cu")
		(net "M_I_CPU1_SA_DQ<9>")
	)
	(arc
		(start 129.92608 -231.041702)
		(mid 130.109588 -231.087227)
		(end 130.29184 -231.036876)
		(width 0.0889)
		(layer "In2.Cu")
		(net "M_I_CPU1_SA_DQ<9>")
	)
	(arc
		(start 135.56615 -231.041702)
		(mid 135.749658 -231.087227)
		(end 135.93191 -231.036876)
		(width 0.0889)
		(layer "In2.Cu")
		(net "M_I_CPU1_SA_DQ<9>")
	)
	(arc
		(start 139.326112 -231.041702)
		(mid 139.50962 -231.087227)
		(end 139.691872 -231.036876)
		(width 0.0889)
		(layer "In2.Cu")
		(net "M_I_CPU1_SA_DQ<9>")
	)
	(arc
		(start 144.57934 -227.474526)
		(mid 144.643855 -227.212307)
		(end 144.822672 -227.00996)
		(width 0.0889)
		(layer "In2.Cu")
		(net "M_I_CPU1_SA_DQ<9>")
	)
	(arc
		(start 144.422368 -227.779326)
		(mid 144.537795 -227.64595)
		(end 144.57934 -227.474526)
		(width 0.0889)
		(layer "In2.Cu")
		(net "M_I_CPU1_SA_DQ<9>")
	)
	(arc
		(start 138.377676 -231.036876)
		(mid 138.559927 -231.08726)
		(end 138.743436 -231.041702)
		(width 0.0889)
		(layer "In2.Cu")
		(net "M_I_CPU1_SA_DQ<9>")
	)
	(arc
		(start 143.01343 -230.208582)
		(mid 143.128106 -230.075248)
		(end 143.169386 -229.90429)
		(width 0.0889)
		(layer "In2.Cu")
		(net "M_I_CPU1_SA_DQ<9>")
	)
	(arc
		(start 145.331942 -226.177094)
		(mid 145.409714 -226.106118)
		(end 145.472912 -226.0219)
		(width 0.0889)
		(layer "In2.Cu")
		(net "M_I_CPU1_SA_DQ<9>")
	)
	(arc
		(start 145.049494 -226.66452)
		(mid 145.114009 -226.402301)
		(end 145.292826 -226.199954)
		(width 0.0889)
		(layer "In2.Cu")
		(net "M_I_CPU1_SA_DQ<9>")
	)
	(arc
		(start 138.751818 -231.036876)
		(mid 139.034774 -230.960699)
		(end 139.31773 -231.036876)
		(width 0.0889)
		(layer "In2.Cu")
		(net "M_I_CPU1_SA_DQ<9>")
	)
	(arc
		(start 133.67766 -231.036876)
		(mid 133.859911 -231.08726)
		(end 134.04342 -231.041702)
		(width 0.0889)
		(layer "In2.Cu")
		(net "M_I_CPU1_SA_DQ<9>")
	)
	(arc
		(start 136.87171 -231.036876)
		(mid 137.154666 -230.960699)
		(end 137.437622 -231.036876)
		(width 0.0889)
		(layer "In2.Cu")
		(net "M_I_CPU1_SA_DQ<9>")
	)
	(arc
		(start 142.699486 -230.71455)
		(mid 142.765516 -230.449522)
		(end 142.948152 -230.246428)
		(width 0.0889)
		(layer "In2.Cu")
		(net "M_I_CPU1_SA_DQ<9>")
	)
	(arc
		(start 132.171694 -231.036876)
		(mid 132.45465 -230.960699)
		(end 132.737606 -231.036876)
		(width 0.0889)
		(layer "In2.Cu")
		(net "M_I_CPU1_SA_DQ<9>")
	)
	(arc
		(start 134.626096 -231.041702)
		(mid 134.809604 -231.087227)
		(end 134.991856 -231.036876)
		(width 0.0889)
		(layer "In2.Cu")
		(net "M_I_CPU1_SA_DQ<9>")
	)
	(arc
		(start 142.137638 -231.036876)
		(mid 142.319889 -231.08726)
		(end 142.503398 -231.041702)
		(width 0.0889)
		(layer "In2.Cu")
		(net "M_I_CPU1_SA_DQ<9>")
	)
	(arc
		(start 132.737606 -231.036876)
		(mid 132.919857 -231.08726)
		(end 133.103366 -231.041702)
		(width 0.0889)
		(layer "In2.Cu")
		(net "M_I_CPU1_SA_DQ<9>")
	)
	(arc
		(start 143.953484 -228.588824)
		(mid 144.06816 -228.45549)
		(end 144.10944 -228.284532)
		(width 0.0889)
		(layer "In2.Cu")
		(net "M_I_CPU1_SA_DQ<9>")
	)
	(arc
		(start 128.092708 -231.063038)
		(mid 128.250359 -231.08635)
		(end 128.40335 -231.041702)
		(width 0.0889)
		(layer "In2.Cu")
		(net "M_I_CPU1_SA_DQ<9>")
	)
	(arc
		(start 142.545308 -231.017318)
		(mid 142.658715 -230.884429)
		(end 142.699486 -230.71455)
		(width 0.0889)
		(layer "In2.Cu")
		(net "M_I_CPU1_SA_DQ<9>")
	)
	(arc
		(start 135.93191 -231.036876)
		(mid 136.214866 -230.960699)
		(end 136.497822 -231.036876)
		(width 0.0889)
		(layer "In2.Cu")
		(net "M_I_CPU1_SA_DQ<9>")
	)
	(arc
		(start 143.484346 -229.398068)
		(mid 143.598275 -229.264921)
		(end 143.639286 -229.094538)
		(width 0.0889)
		(layer "In2.Cu")
		(net "M_I_CPU1_SA_DQ<9>")
	)
	(arc
		(start 134.991856 -231.036876)
		(mid 135.274812 -230.960699)
		(end 135.557768 -231.036876)
		(width 0.0889)
		(layer "In2.Cu")
		(net "M_I_CPU1_SA_DQ<9>")
	)
	(arc
		(start 134.051802 -231.036876)
		(mid 134.334758 -230.960699)
		(end 134.617714 -231.036876)
		(width 0.0889)
		(layer "In2.Cu")
		(net "M_I_CPU1_SA_DQ<9>")
	)
	(arc
		(start 140.266166 -231.041702)
		(mid 140.449674 -231.087227)
		(end 140.631926 -231.036876)
		(width 0.0889)
		(layer "In2.Cu")
		(net "M_I_CPU1_SA_DQ<9>")
	)
	(arc
		(start 141.197838 -231.036876)
		(mid 141.384782 -231.087165)
		(end 141.571726 -231.036876)
		(width 0.0889)
		(layer "In2.Cu")
		(net "M_I_CPU1_SA_DQ<9>")
	)
	(arc
		(start 143.169386 -229.90429)
		(mid 143.233901 -229.642071)
		(end 143.412718 -229.439724)
		(width 0.0889)
		(layer "In2.Cu")
		(net "M_I_CPU1_SA_DQ<9>")
	)
	(arc
		(start 144.10944 -228.284532)
		(mid 144.173955 -228.022313)
		(end 144.352772 -227.819966)
		(width 0.0889)
		(layer "In2.Cu")
		(net "M_I_CPU1_SA_DQ<9>")
	)
	(segment
		(start 129.16789 -230.170228)
		(end 129.634742 -229.90429)
		(width 0.10668)
		(layer "F.Cu")
		(net "M_I_CPU1_SA_DQ<8>")
	)
	(segment
		(start 146.741388 -222.352108)
		(end 147.023074 -222.215202)
		(width 0.0889)
		(layer "In2.Cu")
		(net "M_I_CPU1_SA_DQ<8>")
	)
	(segment
		(start 173.684692 -207.11033)
		(end 174.534576 -206.260446)
		(width 0.14478)
		(layer "In2.Cu")
		(net "M_I_CPU1_SA_DQ<8>")
	)
	(segment
		(start 143.921734 -226.9871)
		(end 143.953484 -226.968812)
		(width 0.0889)
		(layer "In2.Cu")
		(net "M_I_CPU1_SA_DQ<8>")
	)
	(segment
		(start 142.945358 -228.628194)
		(end 142.98168 -228.607112)
		(width 0.0889)
		(layer "In2.Cu")
		(net "M_I_CPU1_SA_DQ<8>")
	)
	(segment
		(start 150.5712 -218.667076)
		(end 150.5712 -217.368628)
		(width 0.14478)
		(layer "In2.Cu")
		(net "M_I_CPU1_SA_DQ<8>")
	)
	(segment
		(start 143.412718 -227.819966)
		(end 143.451834 -227.797106)
		(width 0.0889)
		(layer "In2.Cu")
		(net "M_I_CPU1_SA_DQ<8>")
	)
	(segment
		(start 141.093444 -230.231696)
		(end 141.101826 -230.22687)
		(width 0.0889)
		(layer "In2.Cu")
		(net "M_I_CPU1_SA_DQ<8>")
	)
	(segment
		(start 145.283428 -224.584768)
		(end 145.332196 -224.55632)
		(width 0.0889)
		(layer "In2.Cu")
		(net "M_I_CPU1_SA_DQ<8>")
	)
	(segment
		(start 142.98168 -228.607112)
		(end 143.01343 -228.588824)
		(width 0.0889)
		(layer "In2.Cu")
		(net "M_I_CPU1_SA_DQ<8>")
	)
	(segment
		(start 137.907776 -230.22687)
		(end 137.916158 -230.231696)
		(width 0.0889)
		(layer "In2.Cu")
		(net "M_I_CPU1_SA_DQ<8>")
	)
	(segment
		(start 142.04188 -230.22687)
		(end 142.07236 -230.20909)
		(width 0.0889)
		(layer "In2.Cu")
		(net "M_I_CPU1_SA_DQ<8>")
	)
	(segment
		(start 145.332196 -224.55632)
		(end 145.367248 -224.536)
		(width 0.0889)
		(layer "In2.Cu")
		(net "M_I_CPU1_SA_DQ<8>")
	)
	(segment
		(start 136.967722 -230.22687)
		(end 136.976104 -230.231696)
		(width 0.0889)
		(layer "In2.Cu")
		(net "M_I_CPU1_SA_DQ<8>")
	)
	(segment
		(start 142.472664 -229.439724)
		(end 142.51178 -229.416864)
		(width 0.0889)
		(layer "In2.Cu")
		(net "M_I_CPU1_SA_DQ<8>")
	)
	(segment
		(start 133.20776 -230.22687)
		(end 133.216142 -230.231696)
		(width 0.0889)
		(layer "In2.Cu")
		(net "M_I_CPU1_SA_DQ<8>")
	)
	(segment
		(start 135.453374 -230.231696)
		(end 135.461756 -230.22687)
		(width 0.0889)
		(layer "In2.Cu")
		(net "M_I_CPU1_SA_DQ<8>")
	)
	(segment
		(start 170.626532 -207.11033)
		(end 173.684692 -207.11033)
		(width 0.14478)
		(layer "In2.Cu")
		(net "M_I_CPU1_SA_DQ<8>")
	)
	(segment
		(start 145.762726 -223.769936)
		(end 145.801842 -223.747076)
		(width 0.0889)
		(layer "In2.Cu")
		(net "M_I_CPU1_SA_DQ<8>")
	)
	(segment
		(start 160.829498 -207.11033)
		(end 166.174166 -207.11033)
		(width 0.14478)
		(layer "In2.Cu")
		(net "M_I_CPU1_SA_DQ<8>")
	)
	(segment
		(start 131.693412 -230.231696)
		(end 131.701794 -230.22687)
		(width 0.0889)
		(layer "In2.Cu")
		(net "M_I_CPU1_SA_DQ<8>")
	)
	(segment
		(start 144.822672 -225.389948)
		(end 144.861788 -225.367088)
		(width 0.0889)
		(layer "In2.Cu")
		(net "M_I_CPU1_SA_DQ<8>")
	)
	(segment
		(start 174.534576 -206.260446)
		(end 183.19115 -206.260446)
		(width 0.14478)
		(layer "In2.Cu")
		(net "M_I_CPU1_SA_DQ<8>")
	)
	(segment
		(start 183.19115 -206.260446)
		(end 183.616092 -206.685388)
		(width 0.14478)
		(layer "In2.Cu")
		(net "M_I_CPU1_SA_DQ<8>")
	)
	(segment
		(start 147.023074 -222.215202)
		(end 150.5712 -218.667076)
		(width 0.14478)
		(layer "In2.Cu")
		(net "M_I_CPU1_SA_DQ<8>")
	)
	(segment
		(start 144.861788 -225.367088)
		(end 144.897856 -225.34626)
		(width 0.0889)
		(layer "In2.Cu")
		(net "M_I_CPU1_SA_DQ<8>")
	)
	(segment
		(start 167.02405 -206.260446)
		(end 169.776648 -206.260446)
		(width 0.14478)
		(layer "In2.Cu")
		(net "M_I_CPU1_SA_DQ<8>")
	)
	(segment
		(start 146.272758 -222.935546)
		(end 146.741388 -222.352108)
		(width 0.0889)
		(layer "In2.Cu")
		(net "M_I_CPU1_SA_DQ<8>")
	)
	(segment
		(start 132.267706 -230.22687)
		(end 132.276088 -230.231696)
		(width 0.0889)
		(layer "In2.Cu")
		(net "M_I_CPU1_SA_DQ<8>")
	)
	(segment
		(start 169.776648 -206.260446)
		(end 170.626532 -207.11033)
		(width 0.14478)
		(layer "In2.Cu")
		(net "M_I_CPU1_SA_DQ<8>")
	)
	(segment
		(start 136.393428 -230.231696)
		(end 136.40181 -230.22687)
		(width 0.0889)
		(layer "In2.Cu")
		(net "M_I_CPU1_SA_DQ<8>")
	)
	(segment
		(start 130.753358 -230.231696)
		(end 130.76174 -230.22687)
		(width 0.0889)
		(layer "In2.Cu")
		(net "M_I_CPU1_SA_DQ<8>")
	)
	(segment
		(start 145.801842 -223.747076)
		(end 145.832322 -223.729296)
		(width 0.0889)
		(layer "In2.Cu")
		(net "M_I_CPU1_SA_DQ<8>")
	)
	(segment
		(start 142.51178 -229.416864)
		(end 142.545308 -229.397306)
		(width 0.0889)
		(layer "In2.Cu")
		(net "M_I_CPU1_SA_DQ<8>")
	)
	(segment
		(start 141.667738 -230.22687)
		(end 141.67612 -230.231696)
		(width 0.0889)
		(layer "In2.Cu")
		(net "M_I_CPU1_SA_DQ<8>")
	)
	(segment
		(start 144.352772 -226.199954)
		(end 144.391888 -226.177094)
		(width 0.0889)
		(layer "In2.Cu")
		(net "M_I_CPU1_SA_DQ<8>")
	)
	(segment
		(start 143.882618 -227.00996)
		(end 143.921734 -226.9871)
		(width 0.0889)
		(layer "In2.Cu")
		(net "M_I_CPU1_SA_DQ<8>")
	)
	(segment
		(start 150.5712 -217.368628)
		(end 160.829498 -207.11033)
		(width 0.14478)
		(layer "In2.Cu")
		(net "M_I_CPU1_SA_DQ<8>")
	)
	(segment
		(start 144.391888 -226.177094)
		(end 144.422368 -226.159314)
		(width 0.0889)
		(layer "In2.Cu")
		(net "M_I_CPU1_SA_DQ<8>")
	)
	(segment
		(start 143.451834 -227.797106)
		(end 143.482314 -227.779326)
		(width 0.0889)
		(layer "In2.Cu")
		(net "M_I_CPU1_SA_DQ<8>")
	)
	(segment
		(start 129.480818 -230.16972)
		(end 129.50317 -230.253032)
		(width 0.0889)
		(layer "In2.Cu")
		(net "M_I_CPU1_SA_DQ<8>")
	)
	(segment
		(start 129.634742 -229.90429)
		(end 129.480818 -230.16972)
		(width 0.0889)
		(layer "In2.Cu")
		(net "M_I_CPU1_SA_DQ<8>")
	)
	(segment
		(start 140.15339 -230.231696)
		(end 140.161772 -230.22687)
		(width 0.0889)
		(layer "In2.Cu")
		(net "M_I_CPU1_SA_DQ<8>")
	)
	(segment
		(start 146.243548 -222.95231)
		(end 146.272758 -222.935546)
		(width 0.0889)
		(layer "In2.Cu")
		(net "M_I_CPU1_SA_DQ<8>")
	)
	(segment
		(start 166.174166 -207.11033)
		(end 167.02405 -206.260446)
		(width 0.14478)
		(layer "In2.Cu")
		(net "M_I_CPU1_SA_DQ<8>")
	)
	(arc
		(start 144.57934 -225.854514)
		(mid 144.643855 -225.592295)
		(end 144.822672 -225.389948)
		(width 0.0889)
		(layer "In2.Cu")
		(net "M_I_CPU1_SA_DQ<8>")
	)
	(arc
		(start 130.76174 -230.22687)
		(mid 131.044696 -230.150727)
		(end 131.327652 -230.22687)
		(width 0.0889)
		(layer "In2.Cu")
		(net "M_I_CPU1_SA_DQ<8>")
	)
	(arc
		(start 143.482314 -227.779326)
		(mid 143.597741 -227.64595)
		(end 143.639286 -227.474526)
		(width 0.0889)
		(layer "In2.Cu")
		(net "M_I_CPU1_SA_DQ<8>")
	)
	(arc
		(start 138.281918 -230.22687)
		(mid 138.564874 -230.150727)
		(end 138.84783 -230.22687)
		(width 0.0889)
		(layer "In2.Cu")
		(net "M_I_CPU1_SA_DQ<8>")
	)
	(arc
		(start 142.699486 -229.094538)
		(mid 142.764722 -228.830947)
		(end 142.945358 -228.628194)
		(width 0.0889)
		(layer "In2.Cu")
		(net "M_I_CPU1_SA_DQ<8>")
	)
	(arc
		(start 145.519394 -224.234502)
		(mid 145.583909 -223.972283)
		(end 145.762726 -223.769936)
		(width 0.0889)
		(layer "In2.Cu")
		(net "M_I_CPU1_SA_DQ<8>")
	)
	(arc
		(start 132.641848 -230.22687)
		(mid 132.924804 -230.150727)
		(end 133.20776 -230.22687)
		(width 0.0889)
		(layer "In2.Cu")
		(net "M_I_CPU1_SA_DQ<8>")
	)
	(arc
		(start 134.147814 -230.22687)
		(mid 134.334758 -230.277125)
		(end 134.521702 -230.22687)
		(width 0.0889)
		(layer "In2.Cu")
		(net "M_I_CPU1_SA_DQ<8>")
	)
	(arc
		(start 136.976104 -230.231696)
		(mid 137.159612 -230.27719)
		(end 137.341864 -230.22687)
		(width 0.0889)
		(layer "In2.Cu")
		(net "M_I_CPU1_SA_DQ<8>")
	)
	(arc
		(start 129.50317 -230.253032)
		(mid 129.665359 -230.275767)
		(end 129.821686 -230.22687)
		(width 0.0889)
		(layer "In2.Cu")
		(net "M_I_CPU1_SA_DQ<8>")
	)
	(arc
		(start 141.101826 -230.22687)
		(mid 141.384782 -230.150727)
		(end 141.667738 -230.22687)
		(width 0.0889)
		(layer "In2.Cu")
		(net "M_I_CPU1_SA_DQ<8>")
	)
	(arc
		(start 140.161772 -230.22687)
		(mid 140.444728 -230.150727)
		(end 140.727684 -230.22687)
		(width 0.0889)
		(layer "In2.Cu")
		(net "M_I_CPU1_SA_DQ<8>")
	)
	(arc
		(start 131.701794 -230.22687)
		(mid 131.98475 -230.150727)
		(end 132.267706 -230.22687)
		(width 0.0889)
		(layer "In2.Cu")
		(net "M_I_CPU1_SA_DQ<8>")
	)
	(arc
		(start 141.67612 -230.231696)
		(mid 141.859628 -230.27719)
		(end 142.04188 -230.22687)
		(width 0.0889)
		(layer "In2.Cu")
		(net "M_I_CPU1_SA_DQ<8>")
	)
	(arc
		(start 138.84783 -230.22687)
		(mid 139.034774 -230.277125)
		(end 139.221718 -230.22687)
		(width 0.0889)
		(layer "In2.Cu")
		(net "M_I_CPU1_SA_DQ<8>")
	)
	(arc
		(start 144.10944 -226.66452)
		(mid 144.173955 -226.402301)
		(end 144.352772 -226.199954)
		(width 0.0889)
		(layer "In2.Cu")
		(net "M_I_CPU1_SA_DQ<8>")
	)
	(arc
		(start 145.832322 -223.729296)
		(mid 145.947749 -223.59592)
		(end 145.989294 -223.424496)
		(width 0.0889)
		(layer "In2.Cu")
		(net "M_I_CPU1_SA_DQ<8>")
	)
	(arc
		(start 139.221718 -230.22687)
		(mid 139.504674 -230.150727)
		(end 139.78763 -230.22687)
		(width 0.0889)
		(layer "In2.Cu")
		(net "M_I_CPU1_SA_DQ<8>")
	)
	(arc
		(start 145.050002 -225.044)
		(mid 145.111438 -224.786289)
		(end 145.283428 -224.584768)
		(width 0.0889)
		(layer "In2.Cu")
		(net "M_I_CPU1_SA_DQ<8>")
	)
	(arc
		(start 136.027668 -230.22687)
		(mid 136.209919 -230.27722)
		(end 136.393428 -230.231696)
		(width 0.0889)
		(layer "In2.Cu")
		(net "M_I_CPU1_SA_DQ<8>")
	)
	(arc
		(start 143.169386 -228.284532)
		(mid 143.233901 -228.022313)
		(end 143.412718 -227.819966)
		(width 0.0889)
		(layer "In2.Cu")
		(net "M_I_CPU1_SA_DQ<8>")
	)
	(arc
		(start 130.387598 -230.22687)
		(mid 130.569849 -230.27722)
		(end 130.753358 -230.231696)
		(width 0.0889)
		(layer "In2.Cu")
		(net "M_I_CPU1_SA_DQ<8>")
	)
	(arc
		(start 143.639286 -227.474526)
		(mid 143.703801 -227.212307)
		(end 143.882618 -227.00996)
		(width 0.0889)
		(layer "In2.Cu")
		(net "M_I_CPU1_SA_DQ<8>")
	)
	(arc
		(start 142.229332 -229.90429)
		(mid 142.293847 -229.642071)
		(end 142.472664 -229.439724)
		(width 0.0889)
		(layer "In2.Cu")
		(net "M_I_CPU1_SA_DQ<8>")
	)
	(arc
		(start 131.327652 -230.22687)
		(mid 131.509903 -230.27722)
		(end 131.693412 -230.231696)
		(width 0.0889)
		(layer "In2.Cu")
		(net "M_I_CPU1_SA_DQ<8>")
	)
	(arc
		(start 136.40181 -230.22687)
		(mid 136.684766 -230.150727)
		(end 136.967722 -230.22687)
		(width 0.0889)
		(layer "In2.Cu")
		(net "M_I_CPU1_SA_DQ<8>")
	)
	(arc
		(start 139.78763 -230.22687)
		(mid 139.969881 -230.27722)
		(end 140.15339 -230.231696)
		(width 0.0889)
		(layer "In2.Cu")
		(net "M_I_CPU1_SA_DQ<8>")
	)
	(arc
		(start 142.545308 -229.397306)
		(mid 142.658715 -229.264417)
		(end 142.699486 -229.094538)
		(width 0.0889)
		(layer "In2.Cu")
		(net "M_I_CPU1_SA_DQ<8>")
	)
	(arc
		(start 145.989294 -223.424496)
		(mid 146.056892 -223.156344)
		(end 146.243548 -222.95231)
		(width 0.0889)
		(layer "In2.Cu")
		(net "M_I_CPU1_SA_DQ<8>")
	)
	(arc
		(start 144.422368 -226.159314)
		(mid 144.537795 -226.025938)
		(end 144.57934 -225.854514)
		(width 0.0889)
		(layer "In2.Cu")
		(net "M_I_CPU1_SA_DQ<8>")
	)
	(arc
		(start 129.821686 -230.22687)
		(mid 130.104642 -230.150727)
		(end 130.387598 -230.22687)
		(width 0.0889)
		(layer "In2.Cu")
		(net "M_I_CPU1_SA_DQ<8>")
	)
	(arc
		(start 133.581902 -230.22687)
		(mid 133.864858 -230.150727)
		(end 134.147814 -230.22687)
		(width 0.0889)
		(layer "In2.Cu")
		(net "M_I_CPU1_SA_DQ<8>")
	)
	(arc
		(start 135.087614 -230.22687)
		(mid 135.269865 -230.27722)
		(end 135.453374 -230.231696)
		(width 0.0889)
		(layer "In2.Cu")
		(net "M_I_CPU1_SA_DQ<8>")
	)
	(arc
		(start 145.367248 -224.536)
		(mid 145.479173 -224.403349)
		(end 145.519394 -224.234502)
		(width 0.0889)
		(layer "In2.Cu")
		(net "M_I_CPU1_SA_DQ<8>")
	)
	(arc
		(start 144.897856 -225.34626)
		(mid 145.009971 -225.213264)
		(end 145.050002 -225.044)
		(width 0.0889)
		(layer "In2.Cu")
		(net "M_I_CPU1_SA_DQ<8>")
	)
	(arc
		(start 143.01343 -228.588824)
		(mid 143.128106 -228.45549)
		(end 143.169386 -228.284532)
		(width 0.0889)
		(layer "In2.Cu")
		(net "M_I_CPU1_SA_DQ<8>")
	)
	(arc
		(start 142.07236 -230.20909)
		(mid 142.187787 -230.075714)
		(end 142.229332 -229.90429)
		(width 0.0889)
		(layer "In2.Cu")
		(net "M_I_CPU1_SA_DQ<8>")
	)
	(arc
		(start 137.916158 -230.231696)
		(mid 138.099666 -230.27719)
		(end 138.281918 -230.22687)
		(width 0.0889)
		(layer "In2.Cu")
		(net "M_I_CPU1_SA_DQ<8>")
	)
	(arc
		(start 140.727684 -230.22687)
		(mid 140.909935 -230.27722)
		(end 141.093444 -230.231696)
		(width 0.0889)
		(layer "In2.Cu")
		(net "M_I_CPU1_SA_DQ<8>")
	)
	(arc
		(start 132.276088 -230.231696)
		(mid 132.459596 -230.27719)
		(end 132.641848 -230.22687)
		(width 0.0889)
		(layer "In2.Cu")
		(net "M_I_CPU1_SA_DQ<8>")
	)
	(arc
		(start 134.521702 -230.22687)
		(mid 134.804658 -230.150727)
		(end 135.087614 -230.22687)
		(width 0.0889)
		(layer "In2.Cu")
		(net "M_I_CPU1_SA_DQ<8>")
	)
	(arc
		(start 133.216142 -230.231696)
		(mid 133.39965 -230.27719)
		(end 133.581902 -230.22687)
		(width 0.0889)
		(layer "In2.Cu")
		(net "M_I_CPU1_SA_DQ<8>")
	)
	(arc
		(start 137.341864 -230.22687)
		(mid 137.62482 -230.150727)
		(end 137.907776 -230.22687)
		(width 0.0889)
		(layer "In2.Cu")
		(net "M_I_CPU1_SA_DQ<8>")
	)
	(arc
		(start 135.461756 -230.22687)
		(mid 135.744712 -230.150727)
		(end 136.027668 -230.22687)
		(width 0.0889)
		(layer "In2.Cu")
		(net "M_I_CPU1_SA_DQ<8>")
	)
	(arc
		(start 143.953484 -226.968812)
		(mid 144.06816 -226.835478)
		(end 144.10944 -226.66452)
		(width 0.0889)
		(layer "In2.Cu")
		(net "M_I_CPU1_SA_DQ<8>")
	)
	(segment
		(start 127.287782 -230.170228)
		(end 127.754634 -229.90429)
		(width 0.10668)
		(layer "F.Cu")
		(net "M_I_CPU1_SA_DQ<7>")
	)
	(segment
		(start 177.362104 -205.024482)
		(end 177.592736 -205.024482)
		(width 0.14478)
		(layer "In2.Cu")
		(net "M_I_CPU1_SA_DQ<7>")
	)
	(segment
		(start 146.900138 -220.666818)
		(end 147.231862 -220.998796)
		(width 0.14478)
		(layer "In2.Cu")
		(net "M_I_CPU1_SA_DQ<7>")
	)
	(segment
		(start 177.75555 -205.187296)
		(end 177.75555 -205.541372)
		(width 0.14478)
		(layer "In2.Cu")
		(net "M_I_CPU1_SA_DQ<7>")
	)
	(segment
		(start 166.915592 -205.410308)
		(end 169.760646 -205.410308)
		(width 0.14478)
		(layer "In2.Cu")
		(net "M_I_CPU1_SA_DQ<7>")
	)
	(segment
		(start 148.07057 -219.496386)
		(end 148.07057 -219.268294)
		(width 0.14478)
		(layer "In2.Cu")
		(net "M_I_CPU1_SA_DQ<7>")
	)
	(segment
		(start 149.01291 -218.325954)
		(end 149.241002 -218.325954)
		(width 0.14478)
		(layer "In2.Cu")
		(net "M_I_CPU1_SA_DQ<7>")
	)
	(segment
		(start 145.499582 -223.062292)
		(end 145.514314 -223.051624)
		(width 0.0889)
		(layer "In2.Cu")
		(net "M_I_CPU1_SA_DQ<7>")
	)
	(segment
		(start 131.693412 -229.577138)
		(end 131.701794 -229.581964)
		(width 0.0889)
		(layer "In2.Cu")
		(net "M_I_CPU1_SA_DQ<7>")
	)
	(segment
		(start 178.474624 -205.024482)
		(end 178.705256 -205.024482)
		(width 0.14478)
		(layer "In2.Cu")
		(net "M_I_CPU1_SA_DQ<7>")
	)
	(segment
		(start 146.672046 -220.666818)
		(end 146.900138 -220.666818)
		(width 0.14478)
		(layer "In2.Cu")
		(net "M_I_CPU1_SA_DQ<7>")
	)
	(segment
		(start 149.182582 -219.276168)
		(end 149.182582 -219.048076)
		(width 0.14478)
		(layer "In2.Cu")
		(net "M_I_CPU1_SA_DQ<7>")
	)
	(segment
		(start 177.19929 -205.541372)
		(end 177.19929 -205.187296)
		(width 0.14478)
		(layer "In2.Cu")
		(net "M_I_CPU1_SA_DQ<7>")
	)
	(segment
		(start 147.290282 -220.048582)
		(end 147.452334 -219.88653)
		(width 0.14478)
		(layer "In2.Cu")
		(net "M_I_CPU1_SA_DQ<7>")
	)
	(segment
		(start 148.402294 -220.056456)
		(end 148.402294 -219.828364)
		(width 0.14478)
		(layer "In2.Cu")
		(net "M_I_CPU1_SA_DQ<7>")
	)
	(segment
		(start 169.760646 -205.410308)
		(end 170.610784 -206.260446)
		(width 0.14478)
		(layer "In2.Cu")
		(net "M_I_CPU1_SA_DQ<7>")
	)
	(segment
		(start 146.509994 -220.82887)
		(end 146.672046 -220.666818)
		(width 0.14478)
		(layer "In2.Cu")
		(net "M_I_CPU1_SA_DQ<7>")
	)
	(segment
		(start 148.850858 -218.488006)
		(end 149.01291 -218.325954)
		(width 0.14478)
		(layer "In2.Cu")
		(net "M_I_CPU1_SA_DQ<7>")
	)
	(segment
		(start 148.402294 -219.828364)
		(end 148.07057 -219.496386)
		(width 0.14478)
		(layer "In2.Cu")
		(net "M_I_CPU1_SA_DQ<7>")
	)
	(segment
		(start 141.667738 -229.581964)
		(end 141.706854 -229.559104)
		(width 0.0889)
		(layer "In2.Cu")
		(net "M_I_CPU1_SA_DQ<7>")
	)
	(segment
		(start 143.517112 -226.35972)
		(end 143.547592 -226.34194)
		(width 0.0889)
		(layer "In2.Cu")
		(net "M_I_CPU1_SA_DQ<7>")
	)
	(segment
		(start 144.9578 -223.911922)
		(end 144.994122 -223.89084)
		(width 0.0889)
		(layer "In2.Cu")
		(net "M_I_CPU1_SA_DQ<7>")
	)
	(segment
		(start 127.908812 -229.63886)
		(end 128.00457 -229.61346)
		(width 0.0889)
		(layer "In2.Cu")
		(net "M_I_CPU1_SA_DQ<7>")
	)
	(segment
		(start 176.511966 -205.410308)
		(end 176.805844 -205.704186)
		(width 0.14478)
		(layer "In2.Cu")
		(net "M_I_CPU1_SA_DQ<7>")
	)
	(segment
		(start 149.02053 -219.43822)
		(end 149.182582 -219.276168)
		(width 0.14478)
		(layer "In2.Cu")
		(net "M_I_CPU1_SA_DQ<7>")
	)
	(segment
		(start 143.547592 -226.34194)
		(end 143.586708 -226.31908)
		(width 0.0889)
		(layer "In2.Cu")
		(net "M_I_CPU1_SA_DQ<7>")
	)
	(segment
		(start 145.56486 -223.001078)
		(end 145.945352 -222.513398)
		(width 0.0889)
		(layer "In2.Cu")
		(net "M_I_CPU1_SA_DQ<7>")
	)
	(segment
		(start 166.065454 -206.260446)
		(end 166.915592 -205.410308)
		(width 0.14478)
		(layer "In2.Cu")
		(net "M_I_CPU1_SA_DQ<7>")
	)
	(segment
		(start 147.680426 -219.88653)
		(end 148.01215 -220.218508)
		(width 0.14478)
		(layer "In2.Cu")
		(net "M_I_CPU1_SA_DQ<7>")
	)
	(segment
		(start 173.66234 -206.260446)
		(end 174.512478 -205.410308)
		(width 0.14478)
		(layer "In2.Cu")
		(net "M_I_CPU1_SA_DQ<7>")
	)
	(segment
		(start 177.19929 -205.187296)
		(end 177.362104 -205.024482)
		(width 0.14478)
		(layer "In2.Cu")
		(net "M_I_CPU1_SA_DQ<7>")
	)
	(segment
		(start 177.592736 -205.024482)
		(end 177.75555 -205.187296)
		(width 0.14478)
		(layer "In2.Cu")
		(net "M_I_CPU1_SA_DQ<7>")
	)
	(segment
		(start 147.459954 -220.998796)
		(end 147.622006 -220.836744)
		(width 0.14478)
		(layer "In2.Cu")
		(net "M_I_CPU1_SA_DQ<7>")
	)
	(segment
		(start 140.15339 -229.577138)
		(end 140.161772 -229.581964)
		(width 0.0889)
		(layer "In2.Cu")
		(net "M_I_CPU1_SA_DQ<7>")
	)
	(segment
		(start 170.610784 -206.260446)
		(end 173.66234 -206.260446)
		(width 0.14478)
		(layer "In2.Cu")
		(net "M_I_CPU1_SA_DQ<7>")
	)
	(segment
		(start 146.841718 -221.617032)
		(end 146.841718 -221.38894)
		(width 0.14478)
		(layer "In2.Cu")
		(net "M_I_CPU1_SA_DQ<7>")
	)
	(segment
		(start 128.507744 -229.581964)
		(end 128.516126 -229.577138)
		(width 0.0889)
		(layer "In2.Cu")
		(net "M_I_CPU1_SA_DQ<7>")
	)
	(segment
		(start 144.92605 -223.93021)
		(end 144.9578 -223.911922)
		(width 0.0889)
		(layer "In2.Cu")
		(net "M_I_CPU1_SA_DQ<7>")
	)
	(segment
		(start 145.421604 -223.108012)
		(end 145.499582 -223.062292)
		(width 0.0889)
		(layer "In2.Cu")
		(net "M_I_CPU1_SA_DQ<7>")
	)
	(segment
		(start 149.800818 -218.657932)
		(end 150.02002 -218.43873)
		(width 0.14478)
		(layer "In2.Cu")
		(net "M_I_CPU1_SA_DQ<7>")
	)
	(segment
		(start 141.093444 -229.577138)
		(end 141.101826 -229.581964)
		(width 0.0889)
		(layer "In2.Cu")
		(net "M_I_CPU1_SA_DQ<7>")
	)
	(segment
		(start 127.754634 -229.90429)
		(end 127.908812 -229.63886)
		(width 0.0889)
		(layer "In2.Cu")
		(net "M_I_CPU1_SA_DQ<7>")
	)
	(segment
		(start 149.182582 -219.048076)
		(end 148.850858 -218.716098)
		(width 0.14478)
		(layer "In2.Cu")
		(net "M_I_CPU1_SA_DQ<7>")
	)
	(segment
		(start 148.460714 -219.106242)
		(end 148.792438 -219.43822)
		(width 0.14478)
		(layer "In2.Cu")
		(net "M_I_CPU1_SA_DQ<7>")
	)
	(segment
		(start 135.453374 -229.577138)
		(end 135.461756 -229.581964)
		(width 0.0889)
		(layer "In2.Cu")
		(net "M_I_CPU1_SA_DQ<7>")
	)
	(segment
		(start 147.290282 -220.276674)
		(end 147.290282 -220.048582)
		(width 0.14478)
		(layer "In2.Cu")
		(net "M_I_CPU1_SA_DQ<7>")
	)
	(segment
		(start 142.607792 -227.961952)
		(end 142.644114 -227.94087)
		(width 0.0889)
		(layer "In2.Cu")
		(net "M_I_CPU1_SA_DQ<7>")
	)
	(segment
		(start 137.907776 -229.581964)
		(end 137.916158 -229.577138)
		(width 0.0889)
		(layer "In2.Cu")
		(net "M_I_CPU1_SA_DQ<7>")
	)
	(segment
		(start 144.017746 -225.531934)
		(end 144.056862 -225.509074)
		(width 0.0889)
		(layer "In2.Cu")
		(net "M_I_CPU1_SA_DQ<7>")
	)
	(segment
		(start 149.572726 -218.657932)
		(end 149.800818 -218.657932)
		(width 0.14478)
		(layer "In2.Cu")
		(net "M_I_CPU1_SA_DQ<7>")
	)
	(segment
		(start 144.487646 -224.721928)
		(end 144.526762 -224.699068)
		(width 0.0889)
		(layer "In2.Cu")
		(net "M_I_CPU1_SA_DQ<7>")
	)
	(segment
		(start 142.576042 -227.98024)
		(end 142.607792 -227.961952)
		(width 0.0889)
		(layer "In2.Cu")
		(net "M_I_CPU1_SA_DQ<7>")
	)
	(segment
		(start 147.231862 -220.998796)
		(end 147.459954 -220.998796)
		(width 0.14478)
		(layer "In2.Cu")
		(net "M_I_CPU1_SA_DQ<7>")
	)
	(segment
		(start 147.452334 -219.88653)
		(end 147.680426 -219.88653)
		(width 0.14478)
		(layer "In2.Cu")
		(net "M_I_CPU1_SA_DQ<7>")
	)
	(segment
		(start 148.07057 -219.268294)
		(end 148.232622 -219.106242)
		(width 0.14478)
		(layer "In2.Cu")
		(net "M_I_CPU1_SA_DQ<7>")
	)
	(segment
		(start 178.31181 -205.187296)
		(end 178.474624 -205.024482)
		(width 0.14478)
		(layer "In2.Cu")
		(net "M_I_CPU1_SA_DQ<7>")
	)
	(segment
		(start 133.20776 -229.581964)
		(end 133.216142 -229.577138)
		(width 0.0889)
		(layer "In2.Cu")
		(net "M_I_CPU1_SA_DQ<7>")
	)
	(segment
		(start 178.705256 -205.024482)
		(end 179.516024 -205.83525)
		(width 0.14478)
		(layer "In2.Cu")
		(net "M_I_CPU1_SA_DQ<7>")
	)
	(segment
		(start 148.232622 -219.106242)
		(end 148.460714 -219.106242)
		(width 0.14478)
		(layer "In2.Cu")
		(net "M_I_CPU1_SA_DQ<7>")
	)
	(segment
		(start 177.918364 -205.704186)
		(end 178.148996 -205.704186)
		(width 0.14478)
		(layer "In2.Cu")
		(net "M_I_CPU1_SA_DQ<7>")
	)
	(segment
		(start 148.792438 -219.43822)
		(end 149.02053 -219.43822)
		(width 0.14478)
		(layer "In2.Cu")
		(net "M_I_CPU1_SA_DQ<7>")
	)
	(segment
		(start 142.137638 -228.771958)
		(end 142.176754 -228.749098)
		(width 0.0889)
		(layer "In2.Cu")
		(net "M_I_CPU1_SA_DQ<7>")
	)
	(segment
		(start 142.107158 -228.789738)
		(end 142.137638 -228.771958)
		(width 0.0889)
		(layer "In2.Cu")
		(net "M_I_CPU1_SA_DQ<7>")
	)
	(segment
		(start 146.841718 -221.38894)
		(end 146.509994 -221.056962)
		(width 0.14478)
		(layer "In2.Cu")
		(net "M_I_CPU1_SA_DQ<7>")
	)
	(segment
		(start 149.241002 -218.325954)
		(end 149.572726 -218.657932)
		(width 0.14478)
		(layer "In2.Cu")
		(net "M_I_CPU1_SA_DQ<7>")
	)
	(segment
		(start 143.985996 -225.550222)
		(end 144.017746 -225.531934)
		(width 0.0889)
		(layer "In2.Cu")
		(net "M_I_CPU1_SA_DQ<7>")
	)
	(segment
		(start 177.036476 -205.704186)
		(end 177.19929 -205.541372)
		(width 0.14478)
		(layer "In2.Cu")
		(net "M_I_CPU1_SA_DQ<7>")
	)
	(segment
		(start 148.850858 -218.716098)
		(end 148.850858 -218.488006)
		(width 0.14478)
		(layer "In2.Cu")
		(net "M_I_CPU1_SA_DQ<7>")
	)
	(segment
		(start 144.457166 -224.739708)
		(end 144.487646 -224.721928)
		(width 0.0889)
		(layer "In2.Cu")
		(net "M_I_CPU1_SA_DQ<7>")
	)
	(segment
		(start 136.967722 -229.581964)
		(end 136.976104 -229.577138)
		(width 0.0889)
		(layer "In2.Cu")
		(net "M_I_CPU1_SA_DQ<7>")
	)
	(segment
		(start 132.267706 -229.581964)
		(end 132.276088 -229.577138)
		(width 0.0889)
		(layer "In2.Cu")
		(net "M_I_CPU1_SA_DQ<7>")
	)
	(segment
		(start 145.945352 -222.513398)
		(end 146.841718 -221.617032)
		(width 0.14478)
		(layer "In2.Cu")
		(net "M_I_CPU1_SA_DQ<7>")
	)
	(segment
		(start 148.01215 -220.218508)
		(end 148.240242 -220.218508)
		(width 0.14478)
		(layer "In2.Cu")
		(net "M_I_CPU1_SA_DQ<7>")
	)
	(segment
		(start 178.31181 -205.541372)
		(end 178.31181 -205.187296)
		(width 0.14478)
		(layer "In2.Cu")
		(net "M_I_CPU1_SA_DQ<7>")
	)
	(segment
		(start 176.805844 -205.704186)
		(end 177.036476 -205.704186)
		(width 0.14478)
		(layer "In2.Cu")
		(net "M_I_CPU1_SA_DQ<7>")
	)
	(segment
		(start 177.75555 -205.541372)
		(end 177.918364 -205.704186)
		(width 0.14478)
		(layer "In2.Cu")
		(net "M_I_CPU1_SA_DQ<7>")
	)
	(segment
		(start 148.240242 -220.218508)
		(end 148.402294 -220.056456)
		(width 0.14478)
		(layer "In2.Cu")
		(net "M_I_CPU1_SA_DQ<7>")
	)
	(segment
		(start 178.148996 -205.704186)
		(end 178.31181 -205.541372)
		(width 0.14478)
		(layer "In2.Cu")
		(net "M_I_CPU1_SA_DQ<7>")
	)
	(segment
		(start 146.509994 -221.056962)
		(end 146.509994 -220.82887)
		(width 0.14478)
		(layer "In2.Cu")
		(net "M_I_CPU1_SA_DQ<7>")
	)
	(segment
		(start 150.02002 -218.43873)
		(end 150.02002 -217.140282)
		(width 0.14478)
		(layer "In2.Cu")
		(net "M_I_CPU1_SA_DQ<7>")
	)
	(segment
		(start 174.512478 -205.410308)
		(end 176.511966 -205.410308)
		(width 0.14478)
		(layer "In2.Cu")
		(net "M_I_CPU1_SA_DQ<7>")
	)
	(segment
		(start 160.899856 -206.260446)
		(end 166.065454 -206.260446)
		(width 0.14478)
		(layer "In2.Cu")
		(net "M_I_CPU1_SA_DQ<7>")
	)
	(segment
		(start 143.045942 -227.170234)
		(end 143.077692 -227.151946)
		(width 0.0889)
		(layer "In2.Cu")
		(net "M_I_CPU1_SA_DQ<7>")
	)
	(segment
		(start 130.753358 -229.577138)
		(end 130.76174 -229.581964)
		(width 0.0889)
		(layer "In2.Cu")
		(net "M_I_CPU1_SA_DQ<7>")
	)
	(segment
		(start 147.622006 -220.608652)
		(end 147.290282 -220.276674)
		(width 0.14478)
		(layer "In2.Cu")
		(net "M_I_CPU1_SA_DQ<7>")
	)
	(segment
		(start 136.393428 -229.577138)
		(end 136.40181 -229.581964)
		(width 0.0889)
		(layer "In2.Cu")
		(net "M_I_CPU1_SA_DQ<7>")
	)
	(segment
		(start 143.077692 -227.151946)
		(end 143.116808 -227.129086)
		(width 0.0889)
		(layer "In2.Cu")
		(net "M_I_CPU1_SA_DQ<7>")
	)
	(segment
		(start 150.02002 -217.140282)
		(end 160.899856 -206.260446)
		(width 0.14478)
		(layer "In2.Cu")
		(net "M_I_CPU1_SA_DQ<7>")
	)
	(segment
		(start 147.622006 -220.836744)
		(end 147.622006 -220.608652)
		(width 0.14478)
		(layer "In2.Cu")
		(net "M_I_CPU1_SA_DQ<7>")
	)
	(arc
		(start 136.027668 -229.581964)
		(mid 136.209919 -229.53158)
		(end 136.393428 -229.577138)
		(width 0.0889)
		(layer "In2.Cu")
		(net "M_I_CPU1_SA_DQ<7>")
	)
	(arc
		(start 138.84783 -229.581964)
		(mid 139.034774 -229.531675)
		(end 139.221718 -229.581964)
		(width 0.0889)
		(layer "In2.Cu")
		(net "M_I_CPU1_SA_DQ<7>")
	)
	(arc
		(start 141.950186 -229.094538)
		(mid 141.991735 -228.923116)
		(end 142.107158 -228.789738)
		(width 0.0889)
		(layer "In2.Cu")
		(net "M_I_CPU1_SA_DQ<7>")
	)
	(arc
		(start 144.056862 -225.509074)
		(mid 144.235675 -225.306724)
		(end 144.300194 -225.044508)
		(width 0.0889)
		(layer "In2.Cu")
		(net "M_I_CPU1_SA_DQ<7>")
	)
	(arc
		(start 133.216142 -229.577138)
		(mid 133.39965 -229.531613)
		(end 133.581902 -229.581964)
		(width 0.0889)
		(layer "In2.Cu")
		(net "M_I_CPU1_SA_DQ<7>")
	)
	(arc
		(start 142.644114 -227.94087)
		(mid 142.824766 -227.738125)
		(end 142.889986 -227.474526)
		(width 0.0889)
		(layer "In2.Cu")
		(net "M_I_CPU1_SA_DQ<7>")
	)
	(arc
		(start 139.221718 -229.581964)
		(mid 139.504674 -229.658141)
		(end 139.78763 -229.581964)
		(width 0.0889)
		(layer "In2.Cu")
		(net "M_I_CPU1_SA_DQ<7>")
	)
	(arc
		(start 132.641848 -229.581964)
		(mid 132.924804 -229.658141)
		(end 133.20776 -229.581964)
		(width 0.0889)
		(layer "In2.Cu")
		(net "M_I_CPU1_SA_DQ<7>")
	)
	(arc
		(start 129.821686 -229.581964)
		(mid 130.104642 -229.658141)
		(end 130.387598 -229.581964)
		(width 0.0889)
		(layer "In2.Cu")
		(net "M_I_CPU1_SA_DQ<7>")
	)
	(arc
		(start 128.881886 -229.581964)
		(mid 129.164842 -229.658141)
		(end 129.447798 -229.581964)
		(width 0.0889)
		(layer "In2.Cu")
		(net "M_I_CPU1_SA_DQ<7>")
	)
	(arc
		(start 143.116808 -227.129086)
		(mid 143.295621 -226.926736)
		(end 143.36014 -226.66452)
		(width 0.0889)
		(layer "In2.Cu")
		(net "M_I_CPU1_SA_DQ<7>")
	)
	(arc
		(start 132.276088 -229.577138)
		(mid 132.459596 -229.531613)
		(end 132.641848 -229.581964)
		(width 0.0889)
		(layer "In2.Cu")
		(net "M_I_CPU1_SA_DQ<7>")
	)
	(arc
		(start 143.586708 -226.31908)
		(mid 143.765521 -226.11673)
		(end 143.83004 -225.854514)
		(width 0.0889)
		(layer "In2.Cu")
		(net "M_I_CPU1_SA_DQ<7>")
	)
	(arc
		(start 138.281918 -229.581964)
		(mid 138.564874 -229.658141)
		(end 138.84783 -229.581964)
		(width 0.0889)
		(layer "In2.Cu")
		(net "M_I_CPU1_SA_DQ<7>")
	)
	(arc
		(start 145.514314 -223.051624)
		(mid 145.541179 -223.027943)
		(end 145.56486 -223.001078)
		(width 0.0889)
		(layer "In2.Cu")
		(net "M_I_CPU1_SA_DQ<7>")
	)
	(arc
		(start 145.239994 -223.424496)
		(mid 145.288626 -223.242057)
		(end 145.421604 -223.108012)
		(width 0.0889)
		(layer "In2.Cu")
		(net "M_I_CPU1_SA_DQ<7>")
	)
	(arc
		(start 144.770094 -224.234502)
		(mid 144.811349 -224.063531)
		(end 144.92605 -223.93021)
		(width 0.0889)
		(layer "In2.Cu")
		(net "M_I_CPU1_SA_DQ<7>")
	)
	(arc
		(start 136.40181 -229.581964)
		(mid 136.684766 -229.658141)
		(end 136.967722 -229.581964)
		(width 0.0889)
		(layer "In2.Cu")
		(net "M_I_CPU1_SA_DQ<7>")
	)
	(arc
		(start 141.101826 -229.581964)
		(mid 141.384782 -229.658141)
		(end 141.667738 -229.581964)
		(width 0.0889)
		(layer "In2.Cu")
		(net "M_I_CPU1_SA_DQ<7>")
	)
	(arc
		(start 128.516126 -229.577138)
		(mid 128.699634 -229.531613)
		(end 128.881886 -229.581964)
		(width 0.0889)
		(layer "In2.Cu")
		(net "M_I_CPU1_SA_DQ<7>")
	)
	(arc
		(start 142.420086 -228.284532)
		(mid 142.461341 -228.113561)
		(end 142.576042 -227.98024)
		(width 0.0889)
		(layer "In2.Cu")
		(net "M_I_CPU1_SA_DQ<7>")
	)
	(arc
		(start 144.994122 -223.89084)
		(mid 145.174774 -223.688095)
		(end 145.239994 -223.424496)
		(width 0.0889)
		(layer "In2.Cu")
		(net "M_I_CPU1_SA_DQ<7>")
	)
	(arc
		(start 144.300194 -225.044508)
		(mid 144.341743 -224.873086)
		(end 144.457166 -224.739708)
		(width 0.0889)
		(layer "In2.Cu")
		(net "M_I_CPU1_SA_DQ<7>")
	)
	(arc
		(start 131.701794 -229.581964)
		(mid 131.98475 -229.658141)
		(end 132.267706 -229.581964)
		(width 0.0889)
		(layer "In2.Cu")
		(net "M_I_CPU1_SA_DQ<7>")
	)
	(arc
		(start 134.147814 -229.581964)
		(mid 134.334758 -229.531675)
		(end 134.521702 -229.581964)
		(width 0.0889)
		(layer "In2.Cu")
		(net "M_I_CPU1_SA_DQ<7>")
	)
	(arc
		(start 130.76174 -229.581964)
		(mid 131.044696 -229.658141)
		(end 131.327652 -229.581964)
		(width 0.0889)
		(layer "In2.Cu")
		(net "M_I_CPU1_SA_DQ<7>")
	)
	(arc
		(start 131.327652 -229.581964)
		(mid 131.509903 -229.53158)
		(end 131.693412 -229.577138)
		(width 0.0889)
		(layer "In2.Cu")
		(net "M_I_CPU1_SA_DQ<7>")
	)
	(arc
		(start 130.387598 -229.581964)
		(mid 130.569849 -229.53158)
		(end 130.753358 -229.577138)
		(width 0.0889)
		(layer "In2.Cu")
		(net "M_I_CPU1_SA_DQ<7>")
	)
	(arc
		(start 135.087614 -229.581964)
		(mid 135.269865 -229.53158)
		(end 135.453374 -229.577138)
		(width 0.0889)
		(layer "In2.Cu")
		(net "M_I_CPU1_SA_DQ<7>")
	)
	(arc
		(start 137.341864 -229.581964)
		(mid 137.62482 -229.658141)
		(end 137.907776 -229.581964)
		(width 0.0889)
		(layer "In2.Cu")
		(net "M_I_CPU1_SA_DQ<7>")
	)
	(arc
		(start 140.727684 -229.581964)
		(mid 140.909935 -229.53158)
		(end 141.093444 -229.577138)
		(width 0.0889)
		(layer "In2.Cu")
		(net "M_I_CPU1_SA_DQ<7>")
	)
	(arc
		(start 144.526762 -224.699068)
		(mid 144.705575 -224.496718)
		(end 144.770094 -224.234502)
		(width 0.0889)
		(layer "In2.Cu")
		(net "M_I_CPU1_SA_DQ<7>")
	)
	(arc
		(start 137.916158 -229.577138)
		(mid 138.099666 -229.531613)
		(end 138.281918 -229.581964)
		(width 0.0889)
		(layer "In2.Cu")
		(net "M_I_CPU1_SA_DQ<7>")
	)
	(arc
		(start 129.447798 -229.581964)
		(mid 129.634742 -229.531675)
		(end 129.821686 -229.581964)
		(width 0.0889)
		(layer "In2.Cu")
		(net "M_I_CPU1_SA_DQ<7>")
	)
	(arc
		(start 136.976104 -229.577138)
		(mid 137.159612 -229.531613)
		(end 137.341864 -229.581964)
		(width 0.0889)
		(layer "In2.Cu")
		(net "M_I_CPU1_SA_DQ<7>")
	)
	(arc
		(start 134.521702 -229.581964)
		(mid 134.804658 -229.658141)
		(end 135.087614 -229.581964)
		(width 0.0889)
		(layer "In2.Cu")
		(net "M_I_CPU1_SA_DQ<7>")
	)
	(arc
		(start 139.78763 -229.581964)
		(mid 139.969881 -229.53158)
		(end 140.15339 -229.577138)
		(width 0.0889)
		(layer "In2.Cu")
		(net "M_I_CPU1_SA_DQ<7>")
	)
	(arc
		(start 140.161772 -229.581964)
		(mid 140.444728 -229.658141)
		(end 140.727684 -229.581964)
		(width 0.0889)
		(layer "In2.Cu")
		(net "M_I_CPU1_SA_DQ<7>")
	)
	(arc
		(start 142.889986 -227.474526)
		(mid 142.931241 -227.303555)
		(end 143.045942 -227.170234)
		(width 0.0889)
		(layer "In2.Cu")
		(net "M_I_CPU1_SA_DQ<7>")
	)
	(arc
		(start 141.706854 -229.559104)
		(mid 141.885667 -229.356754)
		(end 141.950186 -229.094538)
		(width 0.0889)
		(layer "In2.Cu")
		(net "M_I_CPU1_SA_DQ<7>")
	)
	(arc
		(start 142.176754 -228.749098)
		(mid 142.355567 -228.546748)
		(end 142.420086 -228.284532)
		(width 0.0889)
		(layer "In2.Cu")
		(net "M_I_CPU1_SA_DQ<7>")
	)
	(arc
		(start 128.00457 -229.61346)
		(mid 128.259892 -229.65716)
		(end 128.507744 -229.581964)
		(width 0.0889)
		(layer "In2.Cu")
		(net "M_I_CPU1_SA_DQ<7>")
	)
	(arc
		(start 143.36014 -226.66452)
		(mid 143.401689 -226.493098)
		(end 143.517112 -226.35972)
		(width 0.0889)
		(layer "In2.Cu")
		(net "M_I_CPU1_SA_DQ<7>")
	)
	(arc
		(start 143.83004 -225.854514)
		(mid 143.871295 -225.683543)
		(end 143.985996 -225.550222)
		(width 0.0889)
		(layer "In2.Cu")
		(net "M_I_CPU1_SA_DQ<7>")
	)
	(arc
		(start 133.581902 -229.581964)
		(mid 133.864858 -229.658141)
		(end 134.147814 -229.581964)
		(width 0.0889)
		(layer "In2.Cu")
		(net "M_I_CPU1_SA_DQ<7>")
	)
	(arc
		(start 135.461756 -229.581964)
		(mid 135.744712 -229.658141)
		(end 136.027668 -229.581964)
		(width 0.0889)
		(layer "In2.Cu")
		(net "M_I_CPU1_SA_DQ<7>")
	)
	(segment
		(start 128.69799 -229.360476)
		(end 129.164842 -229.094538)
		(width 0.10668)
		(layer "F.Cu")
		(net "M_I_CPU1_SA_DQ<6>")
	)
	(segment
		(start 157.834584 -207.314292)
		(end 157.834584 -207.085692)
		(width 0.14478)
		(layer "In2.Cu")
		(net "M_I_CPU1_SA_DQ<6>")
	)
	(segment
		(start 144.487646 -223.101916)
		(end 144.52092 -223.082612)
		(width 0.0889)
		(layer "In2.Cu")
		(net "M_I_CPU1_SA_DQ<6>")
	)
	(segment
		(start 159.556704 -205.363572)
		(end 159.785304 -205.363572)
		(width 0.14478)
		(layer "In2.Cu")
		(net "M_I_CPU1_SA_DQ<6>")
	)
	(segment
		(start 157.309566 -208.34985)
		(end 157.054296 -208.09458)
		(width 0.14478)
		(layer "In2.Cu")
		(net "M_I_CPU1_SA_DQ<6>")
	)
	(segment
		(start 129.164842 -229.094538)
		(end 129.318766 -228.829108)
		(width 0.0889)
		(layer "In2.Cu")
		(net "M_I_CPU1_SA_DQ<6>")
	)
	(segment
		(start 158.776416 -206.14386)
		(end 159.005016 -206.14386)
		(width 0.14478)
		(layer "In2.Cu")
		(net "M_I_CPU1_SA_DQ<6>")
	)
	(segment
		(start 157.054296 -207.86598)
		(end 157.21584 -207.704436)
		(width 0.14478)
		(layer "In2.Cu")
		(net "M_I_CPU1_SA_DQ<6>")
	)
	(segment
		(start 176.410366 -203.710286)
		(end 176.805844 -204.105764)
		(width 0.14478)
		(layer "In2.Cu")
		(net "M_I_CPU1_SA_DQ<6>")
	)
	(segment
		(start 158.089854 -207.798162)
		(end 158.089854 -207.569562)
		(width 0.14478)
		(layer "In2.Cu")
		(net "M_I_CPU1_SA_DQ<6>")
	)
	(segment
		(start 142.607792 -226.34194)
		(end 142.644114 -226.320858)
		(width 0.0889)
		(layer "In2.Cu")
		(net "M_I_CPU1_SA_DQ<6>")
	)
	(segment
		(start 157.69971 -207.959706)
		(end 157.92831 -207.959706)
		(width 0.14478)
		(layer "In2.Cu")
		(net "M_I_CPU1_SA_DQ<6>")
	)
	(segment
		(start 160.565592 -204.583284)
		(end 160.820862 -204.838554)
		(width 0.14478)
		(layer "In2.Cu")
		(net "M_I_CPU1_SA_DQ<6>")
	)
	(segment
		(start 177.918364 -204.105764)
		(end 178.148996 -204.105764)
		(width 0.14478)
		(layer "In2.Cu")
		(net "M_I_CPU1_SA_DQ<6>")
	)
	(segment
		(start 137.804398 -228.76764)
		(end 137.811764 -228.771958)
		(width 0.0889)
		(layer "In2.Cu")
		(net "M_I_CPU1_SA_DQ<6>")
	)
	(segment
		(start 177.19929 -203.94295)
		(end 177.19929 -203.52512)
		(width 0.14478)
		(layer "In2.Cu")
		(net "M_I_CPU1_SA_DQ<6>")
	)
	(segment
		(start 160.336992 -204.583284)
		(end 160.565592 -204.583284)
		(width 0.14478)
		(layer "In2.Cu")
		(net "M_I_CPU1_SA_DQ<6>")
	)
	(segment
		(start 133.103366 -228.767132)
		(end 133.111748 -228.771958)
		(width 0.0889)
		(layer "In2.Cu")
		(net "M_I_CPU1_SA_DQ<6>")
	)
	(segment
		(start 143.547592 -224.721928)
		(end 143.586708 -224.699068)
		(width 0.0889)
		(layer "In2.Cu")
		(net "M_I_CPU1_SA_DQ<6>")
	)
	(segment
		(start 158.870142 -207.017874)
		(end 158.870142 -206.789274)
		(width 0.14478)
		(layer "In2.Cu")
		(net "M_I_CPU1_SA_DQ<6>")
	)
	(segment
		(start 134.617714 -228.771958)
		(end 134.626096 -228.767132)
		(width 0.0889)
		(layer "In2.Cu")
		(net "M_I_CPU1_SA_DQ<6>")
	)
	(segment
		(start 145.126456 -222.17126)
		(end 145.177256 -222.12681)
		(width 0.0889)
		(layer "In2.Cu")
		(net "M_I_CPU1_SA_DQ<6>")
	)
	(segment
		(start 158.224728 -206.924148)
		(end 158.479998 -207.179418)
		(width 0.14478)
		(layer "In2.Cu")
		(net "M_I_CPU1_SA_DQ<6>")
	)
	(segment
		(start 160.820862 -204.838554)
		(end 161.049462 -204.838554)
		(width 0.14478)
		(layer "In2.Cu")
		(net "M_I_CPU1_SA_DQ<6>")
	)
	(segment
		(start 159.785304 -205.363572)
		(end 160.040574 -205.618842)
		(width 0.14478)
		(layer "In2.Cu")
		(net "M_I_CPU1_SA_DQ<6>")
	)
	(segment
		(start 129.917698 -228.771958)
		(end 129.92608 -228.767132)
		(width 0.0889)
		(layer "In2.Cu")
		(net "M_I_CPU1_SA_DQ<6>")
	)
	(segment
		(start 137.803382 -228.767132)
		(end 137.804398 -228.76764)
		(width 0.0889)
		(layer "In2.Cu")
		(net "M_I_CPU1_SA_DQ<6>")
	)
	(segment
		(start 135.557768 -228.771958)
		(end 135.56615 -228.767132)
		(width 0.0889)
		(layer "In2.Cu")
		(net "M_I_CPU1_SA_DQ<6>")
	)
	(segment
		(start 178.148996 -204.105764)
		(end 178.31181 -203.94295)
		(width 0.14478)
		(layer "In2.Cu")
		(net "M_I_CPU1_SA_DQ<6>")
	)
	(segment
		(start 178.705256 -203.32446)
		(end 179.516024 -204.135228)
		(width 0.14478)
		(layer "In2.Cu")
		(net "M_I_CPU1_SA_DQ<6>")
	)
	(segment
		(start 157.92831 -207.959706)
		(end 158.089854 -207.798162)
		(width 0.14478)
		(layer "In2.Cu")
		(net "M_I_CPU1_SA_DQ<6>")
	)
	(segment
		(start 138.743436 -228.767132)
		(end 138.751818 -228.771958)
		(width 0.0889)
		(layer "In2.Cu")
		(net "M_I_CPU1_SA_DQ<6>")
	)
	(segment
		(start 158.708598 -207.179418)
		(end 158.870142 -207.017874)
		(width 0.14478)
		(layer "In2.Cu")
		(net "M_I_CPU1_SA_DQ<6>")
	)
	(segment
		(start 139.31773 -228.771958)
		(end 139.326112 -228.767132)
		(width 0.0889)
		(layer "In2.Cu")
		(net "M_I_CPU1_SA_DQ<6>")
	)
	(segment
		(start 145.509234 -221.703646)
		(end 145.509234 -221.185486)
		(width 0.0889)
		(layer "In2.Cu")
		(net "M_I_CPU1_SA_DQ<6>")
	)
	(segment
		(start 177.362104 -203.362306)
		(end 177.592736 -203.362306)
		(width 0.14478)
		(layer "In2.Cu")
		(net "M_I_CPU1_SA_DQ<6>")
	)
	(segment
		(start 174.34687 -203.710286)
		(end 176.410366 -203.710286)
		(width 0.14478)
		(layer "In2.Cu")
		(net "M_I_CPU1_SA_DQ<6>")
	)
	(segment
		(start 160.430718 -205.457298)
		(end 160.430718 -205.228698)
		(width 0.14478)
		(layer "In2.Cu")
		(net "M_I_CPU1_SA_DQ<6>")
	)
	(segment
		(start 177.036476 -204.105764)
		(end 177.19929 -203.94295)
		(width 0.14478)
		(layer "In2.Cu")
		(net "M_I_CPU1_SA_DQ<6>")
	)
	(segment
		(start 142.137638 -227.151946)
		(end 142.176754 -227.129086)
		(width 0.0889)
		(layer "In2.Cu")
		(net "M_I_CPU1_SA_DQ<6>")
	)
	(segment
		(start 144.912842 -222.329756)
		(end 145.126456 -222.17126)
		(width 0.0889)
		(layer "In2.Cu")
		(net "M_I_CPU1_SA_DQ<6>")
	)
	(segment
		(start 160.040574 -205.618842)
		(end 160.269174 -205.618842)
		(width 0.14478)
		(layer "In2.Cu")
		(net "M_I_CPU1_SA_DQ<6>")
	)
	(segment
		(start 161.327592 -204.560424)
		(end 166.22776 -204.560424)
		(width 0.14478)
		(layer "In2.Cu")
		(net "M_I_CPU1_SA_DQ<6>")
	)
	(segment
		(start 159.65043 -206.237586)
		(end 159.65043 -206.008986)
		(width 0.14478)
		(layer "In2.Cu")
		(net "M_I_CPU1_SA_DQ<6>")
	)
	(segment
		(start 142.107158 -227.169726)
		(end 142.137638 -227.151946)
		(width 0.0889)
		(layer "In2.Cu")
		(net "M_I_CPU1_SA_DQ<6>")
	)
	(segment
		(start 143.985996 -223.93021)
		(end 144.017746 -223.911922)
		(width 0.0889)
		(layer "In2.Cu")
		(net "M_I_CPU1_SA_DQ<6>")
	)
	(segment
		(start 158.479998 -207.179418)
		(end 158.708598 -207.179418)
		(width 0.14478)
		(layer "In2.Cu")
		(net "M_I_CPU1_SA_DQ<6>")
	)
	(segment
		(start 144.457166 -223.119696)
		(end 144.487646 -223.101916)
		(width 0.0889)
		(layer "In2.Cu")
		(net "M_I_CPU1_SA_DQ<6>")
	)
	(segment
		(start 129.318766 -228.829108)
		(end 129.414778 -228.803708)
		(width 0.0889)
		(layer "In2.Cu")
		(net "M_I_CPU1_SA_DQ<6>")
	)
	(segment
		(start 140.257784 -228.771958)
		(end 140.266166 -228.767132)
		(width 0.0889)
		(layer "In2.Cu")
		(net "M_I_CPU1_SA_DQ<6>")
	)
	(segment
		(start 159.65043 -206.008986)
		(end 159.39516 -205.753716)
		(width 0.14478)
		(layer "In2.Cu")
		(net "M_I_CPU1_SA_DQ<6>")
	)
	(segment
		(start 145.509234 -220.378782)
		(end 157.309566 -208.57845)
		(width 0.14478)
		(layer "In2.Cu")
		(net "M_I_CPU1_SA_DQ<6>")
	)
	(segment
		(start 160.430718 -205.228698)
		(end 160.175448 -204.973428)
		(width 0.14478)
		(layer "In2.Cu")
		(net "M_I_CPU1_SA_DQ<6>")
	)
	(segment
		(start 167.077898 -203.710286)
		(end 169.588688 -203.710286)
		(width 0.14478)
		(layer "In2.Cu")
		(net "M_I_CPU1_SA_DQ<6>")
	)
	(segment
		(start 157.309566 -208.57845)
		(end 157.309566 -208.34985)
		(width 0.14478)
		(layer "In2.Cu")
		(net "M_I_CPU1_SA_DQ<6>")
	)
	(segment
		(start 157.44444 -207.704436)
		(end 157.69971 -207.959706)
		(width 0.14478)
		(layer "In2.Cu")
		(net "M_I_CPU1_SA_DQ<6>")
	)
	(segment
		(start 157.834584 -207.085692)
		(end 157.996128 -206.924148)
		(width 0.14478)
		(layer "In2.Cu")
		(net "M_I_CPU1_SA_DQ<6>")
	)
	(segment
		(start 160.175448 -204.973428)
		(end 160.175448 -204.744828)
		(width 0.14478)
		(layer "In2.Cu")
		(net "M_I_CPU1_SA_DQ<6>")
	)
	(segment
		(start 177.592736 -203.362306)
		(end 177.75555 -203.52512)
		(width 0.14478)
		(layer "In2.Cu")
		(net "M_I_CPU1_SA_DQ<6>")
	)
	(segment
		(start 144.017746 -223.911922)
		(end 144.056862 -223.889062)
		(width 0.0889)
		(layer "In2.Cu")
		(net "M_I_CPU1_SA_DQ<6>")
	)
	(segment
		(start 143.517112 -224.739708)
		(end 143.547592 -224.721928)
		(width 0.0889)
		(layer "In2.Cu")
		(net "M_I_CPU1_SA_DQ<6>")
	)
	(segment
		(start 157.054296 -208.09458)
		(end 157.054296 -207.86598)
		(width 0.14478)
		(layer "In2.Cu")
		(net "M_I_CPU1_SA_DQ<6>")
	)
	(segment
		(start 159.005016 -206.14386)
		(end 159.260286 -206.39913)
		(width 0.14478)
		(layer "In2.Cu")
		(net "M_I_CPU1_SA_DQ<6>")
	)
	(segment
		(start 159.488886 -206.39913)
		(end 159.65043 -206.237586)
		(width 0.14478)
		(layer "In2.Cu")
		(net "M_I_CPU1_SA_DQ<6>")
	)
	(segment
		(start 143.045942 -225.550222)
		(end 143.077692 -225.531934)
		(width 0.0889)
		(layer "In2.Cu")
		(net "M_I_CPU1_SA_DQ<6>")
	)
	(segment
		(start 159.260286 -206.39913)
		(end 159.488886 -206.39913)
		(width 0.14478)
		(layer "In2.Cu")
		(net "M_I_CPU1_SA_DQ<6>")
	)
	(segment
		(start 169.588688 -203.710286)
		(end 170.438826 -204.560424)
		(width 0.14478)
		(layer "In2.Cu")
		(net "M_I_CPU1_SA_DQ<6>")
	)
	(segment
		(start 178.31181 -203.94295)
		(end 178.31181 -203.487274)
		(width 0.14478)
		(layer "In2.Cu")
		(net "M_I_CPU1_SA_DQ<6>")
	)
	(segment
		(start 176.805844 -204.105764)
		(end 177.036476 -204.105764)
		(width 0.14478)
		(layer "In2.Cu")
		(net "M_I_CPU1_SA_DQ<6>")
	)
	(segment
		(start 141.197838 -228.771958)
		(end 141.23416 -228.750876)
		(width 0.0889)
		(layer "In2.Cu")
		(net "M_I_CPU1_SA_DQ<6>")
	)
	(segment
		(start 173.496732 -204.560424)
		(end 174.34687 -203.710286)
		(width 0.14478)
		(layer "In2.Cu")
		(net "M_I_CPU1_SA_DQ<6>")
	)
	(segment
		(start 158.614872 -206.534004)
		(end 158.614872 -206.305404)
		(width 0.14478)
		(layer "In2.Cu")
		(net "M_I_CPU1_SA_DQ<6>")
	)
	(segment
		(start 157.996128 -206.924148)
		(end 158.224728 -206.924148)
		(width 0.14478)
		(layer "In2.Cu")
		(net "M_I_CPU1_SA_DQ<6>")
	)
	(segment
		(start 177.75555 -203.94295)
		(end 177.918364 -204.105764)
		(width 0.14478)
		(layer "In2.Cu")
		(net "M_I_CPU1_SA_DQ<6>")
	)
	(segment
		(start 143.077692 -225.531934)
		(end 143.116808 -225.509074)
		(width 0.0889)
		(layer "In2.Cu")
		(net "M_I_CPU1_SA_DQ<6>")
	)
	(segment
		(start 177.19929 -203.52512)
		(end 177.362104 -203.362306)
		(width 0.14478)
		(layer "In2.Cu")
		(net "M_I_CPU1_SA_DQ<6>")
	)
	(segment
		(start 130.857752 -228.771958)
		(end 130.866134 -228.767132)
		(width 0.0889)
		(layer "In2.Cu")
		(net "M_I_CPU1_SA_DQ<6>")
	)
	(segment
		(start 145.177256 -222.12681)
		(end 145.509234 -221.703646)
		(width 0.0889)
		(layer "In2.Cu")
		(net "M_I_CPU1_SA_DQ<6>")
	)
	(segment
		(start 141.667738 -227.961952)
		(end 141.706854 -227.939092)
		(width 0.0889)
		(layer "In2.Cu")
		(net "M_I_CPU1_SA_DQ<6>")
	)
	(segment
		(start 166.22776 -204.560424)
		(end 167.077898 -203.710286)
		(width 0.14478)
		(layer "In2.Cu")
		(net "M_I_CPU1_SA_DQ<6>")
	)
	(segment
		(start 177.75555 -203.52512)
		(end 177.75555 -203.94295)
		(width 0.14478)
		(layer "In2.Cu")
		(net "M_I_CPU1_SA_DQ<6>")
	)
	(segment
		(start 141.635988 -227.98024)
		(end 141.667738 -227.961952)
		(width 0.0889)
		(layer "In2.Cu")
		(net "M_I_CPU1_SA_DQ<6>")
	)
	(segment
		(start 158.614872 -206.305404)
		(end 158.776416 -206.14386)
		(width 0.14478)
		(layer "In2.Cu")
		(net "M_I_CPU1_SA_DQ<6>")
	)
	(segment
		(start 158.870142 -206.789274)
		(end 158.614872 -206.534004)
		(width 0.14478)
		(layer "In2.Cu")
		(net "M_I_CPU1_SA_DQ<6>")
	)
	(segment
		(start 142.576042 -226.360228)
		(end 142.607792 -226.34194)
		(width 0.0889)
		(layer "In2.Cu")
		(net "M_I_CPU1_SA_DQ<6>")
	)
	(segment
		(start 178.474624 -203.32446)
		(end 178.705256 -203.32446)
		(width 0.14478)
		(layer "In2.Cu")
		(net "M_I_CPU1_SA_DQ<6>")
	)
	(segment
		(start 157.21584 -207.704436)
		(end 157.44444 -207.704436)
		(width 0.14478)
		(layer "In2.Cu")
		(net "M_I_CPU1_SA_DQ<6>")
	)
	(segment
		(start 159.39516 -205.525116)
		(end 159.556704 -205.363572)
		(width 0.14478)
		(layer "In2.Cu")
		(net "M_I_CPU1_SA_DQ<6>")
	)
	(segment
		(start 158.089854 -207.569562)
		(end 157.834584 -207.314292)
		(width 0.14478)
		(layer "In2.Cu")
		(net "M_I_CPU1_SA_DQ<6>")
	)
	(segment
		(start 170.438826 -204.560424)
		(end 173.496732 -204.560424)
		(width 0.14478)
		(layer "In2.Cu")
		(net "M_I_CPU1_SA_DQ<6>")
	)
	(segment
		(start 178.31181 -203.487274)
		(end 178.474624 -203.32446)
		(width 0.14478)
		(layer "In2.Cu")
		(net "M_I_CPU1_SA_DQ<6>")
	)
	(segment
		(start 160.175448 -204.744828)
		(end 160.336992 -204.583284)
		(width 0.14478)
		(layer "In2.Cu")
		(net "M_I_CPU1_SA_DQ<6>")
	)
	(segment
		(start 160.269174 -205.618842)
		(end 160.430718 -205.457298)
		(width 0.14478)
		(layer "In2.Cu")
		(net "M_I_CPU1_SA_DQ<6>")
	)
	(segment
		(start 159.39516 -205.753716)
		(end 159.39516 -205.525116)
		(width 0.14478)
		(layer "In2.Cu")
		(net "M_I_CPU1_SA_DQ<6>")
	)
	(segment
		(start 145.509234 -221.185486)
		(end 145.509234 -220.378782)
		(width 0.14478)
		(layer "In2.Cu")
		(net "M_I_CPU1_SA_DQ<6>")
	)
	(segment
		(start 161.049462 -204.838554)
		(end 161.327592 -204.560424)
		(width 0.14478)
		(layer "In2.Cu")
		(net "M_I_CPU1_SA_DQ<6>")
	)
	(segment
		(start 134.04342 -228.767132)
		(end 134.051802 -228.771958)
		(width 0.0889)
		(layer "In2.Cu")
		(net "M_I_CPU1_SA_DQ<6>")
	)
	(arc
		(start 130.866134 -228.767132)
		(mid 131.049642 -228.721638)
		(end 131.231894 -228.771958)
		(width 0.0889)
		(layer "In2.Cu")
		(net "M_I_CPU1_SA_DQ<6>")
	)
	(arc
		(start 143.83004 -224.234502)
		(mid 143.871295 -224.063531)
		(end 143.985996 -223.93021)
		(width 0.0889)
		(layer "In2.Cu")
		(net "M_I_CPU1_SA_DQ<6>")
	)
	(arc
		(start 144.056862 -223.889062)
		(mid 144.235675 -223.686712)
		(end 144.300194 -223.424496)
		(width 0.0889)
		(layer "In2.Cu")
		(net "M_I_CPU1_SA_DQ<6>")
	)
	(arc
		(start 133.111748 -228.771958)
		(mid 133.394704 -228.848135)
		(end 133.67766 -228.771958)
		(width 0.0889)
		(layer "In2.Cu")
		(net "M_I_CPU1_SA_DQ<6>")
	)
	(arc
		(start 141.480032 -228.284532)
		(mid 141.521287 -228.113561)
		(end 141.635988 -227.98024)
		(width 0.0889)
		(layer "In2.Cu")
		(net "M_I_CPU1_SA_DQ<6>")
	)
	(arc
		(start 143.36014 -225.044508)
		(mid 143.401689 -224.873086)
		(end 143.517112 -224.739708)
		(width 0.0889)
		(layer "In2.Cu")
		(net "M_I_CPU1_SA_DQ<6>")
	)
	(arc
		(start 141.23416 -228.750876)
		(mid 141.414812 -228.548131)
		(end 141.480032 -228.284532)
		(width 0.0889)
		(layer "In2.Cu")
		(net "M_I_CPU1_SA_DQ<6>")
	)
	(arc
		(start 143.586708 -224.699068)
		(mid 143.765521 -224.496718)
		(end 143.83004 -224.234502)
		(width 0.0889)
		(layer "In2.Cu")
		(net "M_I_CPU1_SA_DQ<6>")
	)
	(arc
		(start 134.626096 -228.767132)
		(mid 134.809604 -228.721638)
		(end 134.991856 -228.771958)
		(width 0.0889)
		(layer "In2.Cu")
		(net "M_I_CPU1_SA_DQ<6>")
	)
	(arc
		(start 131.231894 -228.771958)
		(mid 131.51485 -228.848135)
		(end 131.797806 -228.771958)
		(width 0.0889)
		(layer "In2.Cu")
		(net "M_I_CPU1_SA_DQ<6>")
	)
	(arc
		(start 129.414778 -228.803708)
		(mid 129.669986 -228.847185)
		(end 129.917698 -228.771958)
		(width 0.0889)
		(layer "In2.Cu")
		(net "M_I_CPU1_SA_DQ<6>")
	)
	(arc
		(start 133.67766 -228.771958)
		(mid 133.859911 -228.721608)
		(end 134.04342 -228.767132)
		(width 0.0889)
		(layer "In2.Cu")
		(net "M_I_CPU1_SA_DQ<6>")
	)
	(arc
		(start 134.991856 -228.771958)
		(mid 135.274812 -228.848135)
		(end 135.557768 -228.771958)
		(width 0.0889)
		(layer "In2.Cu")
		(net "M_I_CPU1_SA_DQ<6>")
	)
	(arc
		(start 141.950186 -227.474526)
		(mid 141.991735 -227.303104)
		(end 142.107158 -227.169726)
		(width 0.0889)
		(layer "In2.Cu")
		(net "M_I_CPU1_SA_DQ<6>")
	)
	(arc
		(start 135.56615 -228.767132)
		(mid 135.749658 -228.721638)
		(end 135.93191 -228.771958)
		(width 0.0889)
		(layer "In2.Cu")
		(net "M_I_CPU1_SA_DQ<6>")
	)
	(arc
		(start 136.87171 -228.771958)
		(mid 137.154666 -228.848135)
		(end 137.437622 -228.771958)
		(width 0.0889)
		(layer "In2.Cu")
		(net "M_I_CPU1_SA_DQ<6>")
	)
	(arc
		(start 140.266166 -228.767132)
		(mid 140.449674 -228.721638)
		(end 140.631926 -228.771958)
		(width 0.0889)
		(layer "In2.Cu")
		(net "M_I_CPU1_SA_DQ<6>")
	)
	(arc
		(start 129.92608 -228.767132)
		(mid 130.109588 -228.721638)
		(end 130.29184 -228.771958)
		(width 0.0889)
		(layer "In2.Cu")
		(net "M_I_CPU1_SA_DQ<6>")
	)
	(arc
		(start 138.377676 -228.771958)
		(mid 138.559927 -228.721608)
		(end 138.743436 -228.767132)
		(width 0.0889)
		(layer "In2.Cu")
		(net "M_I_CPU1_SA_DQ<6>")
	)
	(arc
		(start 135.93191 -228.771958)
		(mid 136.214866 -228.848135)
		(end 136.497822 -228.771958)
		(width 0.0889)
		(layer "In2.Cu")
		(net "M_I_CPU1_SA_DQ<6>")
	)
	(arc
		(start 139.326112 -228.767132)
		(mid 139.50962 -228.721638)
		(end 139.691872 -228.771958)
		(width 0.0889)
		(layer "In2.Cu")
		(net "M_I_CPU1_SA_DQ<6>")
	)
	(arc
		(start 132.737606 -228.771958)
		(mid 132.919857 -228.721608)
		(end 133.103366 -228.767132)
		(width 0.0889)
		(layer "In2.Cu")
		(net "M_I_CPU1_SA_DQ<6>")
	)
	(arc
		(start 142.420086 -226.66452)
		(mid 142.461341 -226.493549)
		(end 142.576042 -226.360228)
		(width 0.0889)
		(layer "In2.Cu")
		(net "M_I_CPU1_SA_DQ<6>")
	)
	(arc
		(start 142.889986 -225.854514)
		(mid 142.931241 -225.683543)
		(end 143.045942 -225.550222)
		(width 0.0889)
		(layer "In2.Cu")
		(net "M_I_CPU1_SA_DQ<6>")
	)
	(arc
		(start 140.631926 -228.771958)
		(mid 140.914882 -228.848135)
		(end 141.197838 -228.771958)
		(width 0.0889)
		(layer "In2.Cu")
		(net "M_I_CPU1_SA_DQ<6>")
	)
	(arc
		(start 142.644114 -226.320858)
		(mid 142.824766 -226.118113)
		(end 142.889986 -225.854514)
		(width 0.0889)
		(layer "In2.Cu")
		(net "M_I_CPU1_SA_DQ<6>")
	)
	(arc
		(start 141.706854 -227.939092)
		(mid 141.885667 -227.736742)
		(end 141.950186 -227.474526)
		(width 0.0889)
		(layer "In2.Cu")
		(net "M_I_CPU1_SA_DQ<6>")
	)
	(arc
		(start 144.300194 -223.424496)
		(mid 144.341743 -223.253074)
		(end 144.457166 -223.119696)
		(width 0.0889)
		(layer "In2.Cu")
		(net "M_I_CPU1_SA_DQ<6>")
	)
	(arc
		(start 142.176754 -227.129086)
		(mid 142.355567 -226.926736)
		(end 142.420086 -226.66452)
		(width 0.0889)
		(layer "In2.Cu")
		(net "M_I_CPU1_SA_DQ<6>")
	)
	(arc
		(start 137.811764 -228.771958)
		(mid 138.09472 -228.848135)
		(end 138.377676 -228.771958)
		(width 0.0889)
		(layer "In2.Cu")
		(net "M_I_CPU1_SA_DQ<6>")
	)
	(arc
		(start 130.29184 -228.771958)
		(mid 130.574796 -228.848135)
		(end 130.857752 -228.771958)
		(width 0.0889)
		(layer "In2.Cu")
		(net "M_I_CPU1_SA_DQ<6>")
	)
	(arc
		(start 131.797806 -228.771958)
		(mid 131.98475 -228.721703)
		(end 132.171694 -228.771958)
		(width 0.0889)
		(layer "In2.Cu")
		(net "M_I_CPU1_SA_DQ<6>")
	)
	(arc
		(start 136.497822 -228.771958)
		(mid 136.684766 -228.721703)
		(end 136.87171 -228.771958)
		(width 0.0889)
		(layer "In2.Cu")
		(net "M_I_CPU1_SA_DQ<6>")
	)
	(arc
		(start 143.116808 -225.509074)
		(mid 143.295621 -225.306724)
		(end 143.36014 -225.044508)
		(width 0.0889)
		(layer "In2.Cu")
		(net "M_I_CPU1_SA_DQ<6>")
	)
	(arc
		(start 138.751818 -228.771958)
		(mid 139.034774 -228.848135)
		(end 139.31773 -228.771958)
		(width 0.0889)
		(layer "In2.Cu")
		(net "M_I_CPU1_SA_DQ<6>")
	)
	(arc
		(start 144.769586 -222.61449)
		(mid 144.807419 -222.455121)
		(end 144.912842 -222.329756)
		(width 0.0889)
		(layer "In2.Cu")
		(net "M_I_CPU1_SA_DQ<6>")
	)
	(arc
		(start 139.691872 -228.771958)
		(mid 139.974828 -228.848135)
		(end 140.257784 -228.771958)
		(width 0.0889)
		(layer "In2.Cu")
		(net "M_I_CPU1_SA_DQ<6>")
	)
	(arc
		(start 132.171694 -228.771958)
		(mid 132.45465 -228.848135)
		(end 132.737606 -228.771958)
		(width 0.0889)
		(layer "In2.Cu")
		(net "M_I_CPU1_SA_DQ<6>")
	)
	(arc
		(start 144.52092 -223.082612)
		(mid 144.703582 -222.879531)
		(end 144.769586 -222.61449)
		(width 0.0889)
		(layer "In2.Cu")
		(net "M_I_CPU1_SA_DQ<6>")
	)
	(arc
		(start 134.051802 -228.771958)
		(mid 134.334758 -228.848135)
		(end 134.617714 -228.771958)
		(width 0.0889)
		(layer "In2.Cu")
		(net "M_I_CPU1_SA_DQ<6>")
	)
	(arc
		(start 137.437622 -228.771958)
		(mid 137.619873 -228.721608)
		(end 137.803382 -228.767132)
		(width 0.0889)
		(layer "In2.Cu")
		(net "M_I_CPU1_SA_DQ<6>")
	)
	(segment
		(start 127.757936 -229.360476)
		(end 128.224788 -229.094538)
		(width 0.10668)
		(layer "F.Cu")
		(net "M_I_CPU1_SA_DQ<5>")
	)
	(segment
		(start 135.557768 -229.416864)
		(end 135.56615 -229.42169)
		(width 0.0889)
		(layer "In2.Cu")
		(net "M_I_CPU1_SA_DQ<5>")
	)
	(segment
		(start 182.17896 -204.721968)
		(end 182.340504 -204.560424)
		(width 0.14478)
		(layer "In2.Cu")
		(net "M_I_CPU1_SA_DQ<5>")
	)
	(segment
		(start 145.288254 -222.963232)
		(end 145.33118 -222.938086)
		(width 0.0889)
		(layer "In2.Cu")
		(net "M_I_CPU1_SA_DQ<5>")
	)
	(segment
		(start 182.017416 -205.658466)
		(end 182.17896 -205.496922)
		(width 0.14478)
		(layer "In2.Cu")
		(net "M_I_CPU1_SA_DQ<5>")
	)
	(segment
		(start 142.945358 -227.008182)
		(end 142.98168 -226.9871)
		(width 0.0889)
		(layer "In2.Cu")
		(net "M_I_CPU1_SA_DQ<5>")
	)
	(segment
		(start 181.627526 -204.721968)
		(end 181.627526 -205.496922)
		(width 0.14478)
		(layer "In2.Cu")
		(net "M_I_CPU1_SA_DQ<5>")
	)
	(segment
		(start 142.002764 -228.629972)
		(end 142.04188 -228.607112)
		(width 0.0889)
		(layer "In2.Cu")
		(net "M_I_CPU1_SA_DQ<5>")
	)
	(segment
		(start 134.04342 -229.42169)
		(end 134.051802 -229.416864)
		(width 0.0889)
		(layer "In2.Cu")
		(net "M_I_CPU1_SA_DQ<5>")
	)
	(segment
		(start 143.882618 -225.389948)
		(end 143.921734 -225.367088)
		(width 0.0889)
		(layer "In2.Cu")
		(net "M_I_CPU1_SA_DQ<5>")
	)
	(segment
		(start 145.904204 -221.91853)
		(end 145.97761 -221.845124)
		(width 0.0889)
		(layer "In2.Cu")
		(net "M_I_CPU1_SA_DQ<5>")
	)
	(segment
		(start 142.51178 -227.797106)
		(end 142.54353 -227.778818)
		(width 0.0889)
		(layer "In2.Cu")
		(net "M_I_CPU1_SA_DQ<5>")
	)
	(segment
		(start 143.921734 -225.367088)
		(end 143.953484 -225.3488)
		(width 0.0889)
		(layer "In2.Cu")
		(net "M_I_CPU1_SA_DQ<5>")
	)
	(segment
		(start 133.103366 -229.42169)
		(end 133.111748 -229.416864)
		(width 0.0889)
		(layer "In2.Cu")
		(net "M_I_CPU1_SA_DQ<5>")
	)
	(segment
		(start 142.472664 -227.819966)
		(end 142.51178 -227.797106)
		(width 0.0889)
		(layer "In2.Cu")
		(net "M_I_CPU1_SA_DQ<5>")
	)
	(segment
		(start 145.97761 -221.315026)
		(end 145.97761 -220.546676)
		(width 0.14478)
		(layer "In2.Cu")
		(net "M_I_CPU1_SA_DQ<5>")
	)
	(segment
		(start 182.17896 -205.496922)
		(end 182.17896 -204.721968)
		(width 0.14478)
		(layer "In2.Cu")
		(net "M_I_CPU1_SA_DQ<5>")
	)
	(segment
		(start 167.071802 -204.560424)
		(end 169.679366 -204.560424)
		(width 0.14478)
		(layer "In2.Cu")
		(net "M_I_CPU1_SA_DQ<5>")
	)
	(segment
		(start 169.679366 -204.560424)
		(end 170.52925 -205.410308)
		(width 0.14478)
		(layer "In2.Cu")
		(net "M_I_CPU1_SA_DQ<5>")
	)
	(segment
		(start 129.343404 -229.42169)
		(end 129.351786 -229.416864)
		(width 0.0889)
		(layer "In2.Cu")
		(net "M_I_CPU1_SA_DQ<5>")
	)
	(segment
		(start 183.19115 -204.560424)
		(end 183.616092 -204.985366)
		(width 0.14478)
		(layer "In2.Cu")
		(net "M_I_CPU1_SA_DQ<5>")
	)
	(segment
		(start 142.98168 -226.9871)
		(end 143.01343 -226.968812)
		(width 0.0889)
		(layer "In2.Cu")
		(net "M_I_CPU1_SA_DQ<5>")
	)
	(segment
		(start 128.07061 -229.359968)
		(end 128.092708 -229.443026)
		(width 0.0889)
		(layer "In2.Cu")
		(net "M_I_CPU1_SA_DQ<5>")
	)
	(segment
		(start 134.617714 -229.416864)
		(end 134.626096 -229.42169)
		(width 0.0889)
		(layer "In2.Cu")
		(net "M_I_CPU1_SA_DQ<5>")
	)
	(segment
		(start 138.743436 -229.42169)
		(end 138.751818 -229.416864)
		(width 0.0889)
		(layer "In2.Cu")
		(net "M_I_CPU1_SA_DQ<5>")
	)
	(segment
		(start 142.04188 -228.607112)
		(end 142.07236 -228.589332)
		(width 0.0889)
		(layer "In2.Cu")
		(net "M_I_CPU1_SA_DQ<5>")
	)
	(segment
		(start 130.857752 -229.416864)
		(end 130.866134 -229.42169)
		(width 0.0889)
		(layer "In2.Cu")
		(net "M_I_CPU1_SA_DQ<5>")
	)
	(segment
		(start 181.627526 -205.496922)
		(end 181.78907 -205.658466)
		(width 0.14478)
		(layer "In2.Cu")
		(net "M_I_CPU1_SA_DQ<5>")
	)
	(segment
		(start 145.97761 -221.845124)
		(end 145.97761 -221.315026)
		(width 0.0889)
		(layer "In2.Cu")
		(net "M_I_CPU1_SA_DQ<5>")
	)
	(segment
		(start 140.257784 -229.416864)
		(end 140.266166 -229.42169)
		(width 0.0889)
		(layer "In2.Cu")
		(net "M_I_CPU1_SA_DQ<5>")
	)
	(segment
		(start 173.790864 -205.410308)
		(end 174.640748 -204.560424)
		(width 0.14478)
		(layer "In2.Cu")
		(net "M_I_CPU1_SA_DQ<5>")
	)
	(segment
		(start 174.640748 -204.560424)
		(end 181.465982 -204.560424)
		(width 0.14478)
		(layer "In2.Cu")
		(net "M_I_CPU1_SA_DQ<5>")
	)
	(segment
		(start 137.803382 -229.42169)
		(end 137.811764 -229.416864)
		(width 0.0889)
		(layer "In2.Cu")
		(net "M_I_CPU1_SA_DQ<5>")
	)
	(segment
		(start 144.861788 -223.747076)
		(end 144.893538 -223.728788)
		(width 0.0889)
		(layer "In2.Cu")
		(net "M_I_CPU1_SA_DQ<5>")
	)
	(segment
		(start 182.340504 -204.560424)
		(end 183.19115 -204.560424)
		(width 0.14478)
		(layer "In2.Cu")
		(net "M_I_CPU1_SA_DQ<5>")
	)
	(segment
		(start 144.822672 -223.769936)
		(end 144.861788 -223.747076)
		(width 0.0889)
		(layer "In2.Cu")
		(net "M_I_CPU1_SA_DQ<5>")
	)
	(segment
		(start 166.221918 -205.410308)
		(end 167.071802 -204.560424)
		(width 0.14478)
		(layer "In2.Cu")
		(net "M_I_CPU1_SA_DQ<5>")
	)
	(segment
		(start 139.31773 -229.416864)
		(end 139.326112 -229.42169)
		(width 0.0889)
		(layer "In2.Cu")
		(net "M_I_CPU1_SA_DQ<5>")
	)
	(segment
		(start 170.52925 -205.410308)
		(end 173.790864 -205.410308)
		(width 0.14478)
		(layer "In2.Cu")
		(net "M_I_CPU1_SA_DQ<5>")
	)
	(segment
		(start 144.352772 -224.579942)
		(end 144.391888 -224.557082)
		(width 0.0889)
		(layer "In2.Cu")
		(net "M_I_CPU1_SA_DQ<5>")
	)
	(segment
		(start 144.391888 -224.557082)
		(end 144.422368 -224.539302)
		(width 0.0889)
		(layer "In2.Cu")
		(net "M_I_CPU1_SA_DQ<5>")
	)
	(segment
		(start 143.451834 -226.177094)
		(end 143.482314 -226.159314)
		(width 0.0889)
		(layer "In2.Cu")
		(net "M_I_CPU1_SA_DQ<5>")
	)
	(segment
		(start 145.587974 -222.331534)
		(end 145.904204 -221.91853)
		(width 0.0889)
		(layer "In2.Cu")
		(net "M_I_CPU1_SA_DQ<5>")
	)
	(segment
		(start 161.113978 -205.410308)
		(end 166.221918 -205.410308)
		(width 0.14478)
		(layer "In2.Cu")
		(net "M_I_CPU1_SA_DQ<5>")
	)
	(segment
		(start 181.78907 -205.658466)
		(end 182.017416 -205.658466)
		(width 0.14478)
		(layer "In2.Cu")
		(net "M_I_CPU1_SA_DQ<5>")
	)
	(segment
		(start 129.917698 -229.416864)
		(end 129.92608 -229.42169)
		(width 0.0889)
		(layer "In2.Cu")
		(net "M_I_CPU1_SA_DQ<5>")
	)
	(segment
		(start 128.224788 -229.094538)
		(end 128.07061 -229.359968)
		(width 0.0889)
		(layer "In2.Cu")
		(net "M_I_CPU1_SA_DQ<5>")
	)
	(segment
		(start 145.97761 -220.546676)
		(end 161.113978 -205.410308)
		(width 0.14478)
		(layer "In2.Cu")
		(net "M_I_CPU1_SA_DQ<5>")
	)
	(segment
		(start 128.40335 -229.42169)
		(end 128.411732 -229.416864)
		(width 0.0889)
		(layer "In2.Cu")
		(net "M_I_CPU1_SA_DQ<5>")
	)
	(segment
		(start 143.412718 -226.199954)
		(end 143.451834 -226.177094)
		(width 0.0889)
		(layer "In2.Cu")
		(net "M_I_CPU1_SA_DQ<5>")
	)
	(segment
		(start 145.33118 -222.938086)
		(end 145.368772 -222.916242)
		(width 0.0889)
		(layer "In2.Cu")
		(net "M_I_CPU1_SA_DQ<5>")
	)
	(segment
		(start 141.571726 -229.416864)
		(end 141.605254 -229.397306)
		(width 0.0889)
		(layer "In2.Cu")
		(net "M_I_CPU1_SA_DQ<5>")
	)
	(segment
		(start 181.465982 -204.560424)
		(end 181.627526 -204.721968)
		(width 0.14478)
		(layer "In2.Cu")
		(net "M_I_CPU1_SA_DQ<5>")
	)
	(arc
		(start 143.169386 -226.66452)
		(mid 143.233901 -226.402301)
		(end 143.412718 -226.199954)
		(width 0.0889)
		(layer "In2.Cu")
		(net "M_I_CPU1_SA_DQ<5>")
	)
	(arc
		(start 145.368772 -222.916242)
		(mid 145.479079 -222.784071)
		(end 145.518632 -222.616522)
		(width 0.0889)
		(layer "In2.Cu")
		(net "M_I_CPU1_SA_DQ<5>")
	)
	(arc
		(start 142.54353 -227.778818)
		(mid 142.658206 -227.645484)
		(end 142.699486 -227.474526)
		(width 0.0889)
		(layer "In2.Cu")
		(net "M_I_CPU1_SA_DQ<5>")
	)
	(arc
		(start 132.171694 -229.416864)
		(mid 132.45465 -229.340687)
		(end 132.737606 -229.416864)
		(width 0.0889)
		(layer "In2.Cu")
		(net "M_I_CPU1_SA_DQ<5>")
	)
	(arc
		(start 133.67766 -229.416864)
		(mid 133.859911 -229.467248)
		(end 134.04342 -229.42169)
		(width 0.0889)
		(layer "In2.Cu")
		(net "M_I_CPU1_SA_DQ<5>")
	)
	(arc
		(start 142.229332 -228.284532)
		(mid 142.293847 -228.022313)
		(end 142.472664 -227.819966)
		(width 0.0889)
		(layer "In2.Cu")
		(net "M_I_CPU1_SA_DQ<5>")
	)
	(arc
		(start 138.751818 -229.416864)
		(mid 139.034774 -229.340687)
		(end 139.31773 -229.416864)
		(width 0.0889)
		(layer "In2.Cu")
		(net "M_I_CPU1_SA_DQ<5>")
	)
	(arc
		(start 128.977644 -229.416864)
		(mid 129.159895 -229.467248)
		(end 129.343404 -229.42169)
		(width 0.0889)
		(layer "In2.Cu")
		(net "M_I_CPU1_SA_DQ<5>")
	)
	(arc
		(start 137.437622 -229.416864)
		(mid 137.619873 -229.467248)
		(end 137.803382 -229.42169)
		(width 0.0889)
		(layer "In2.Cu")
		(net "M_I_CPU1_SA_DQ<5>")
	)
	(arc
		(start 143.482314 -226.159314)
		(mid 143.597741 -226.025938)
		(end 143.639286 -225.854514)
		(width 0.0889)
		(layer "In2.Cu")
		(net "M_I_CPU1_SA_DQ<5>")
	)
	(arc
		(start 134.991856 -229.416864)
		(mid 135.274812 -229.340687)
		(end 135.557768 -229.416864)
		(width 0.0889)
		(layer "In2.Cu")
		(net "M_I_CPU1_SA_DQ<5>")
	)
	(arc
		(start 143.953484 -225.3488)
		(mid 144.06816 -225.215466)
		(end 144.10944 -225.044508)
		(width 0.0889)
		(layer "In2.Cu")
		(net "M_I_CPU1_SA_DQ<5>")
	)
	(arc
		(start 130.866134 -229.42169)
		(mid 131.049642 -229.467215)
		(end 131.231894 -229.416864)
		(width 0.0889)
		(layer "In2.Cu")
		(net "M_I_CPU1_SA_DQ<5>")
	)
	(arc
		(start 145.518632 -222.616522)
		(mid 145.523319 -222.46673)
		(end 145.587974 -222.331534)
		(width 0.0889)
		(layer "In2.Cu")
		(net "M_I_CPU1_SA_DQ<5>")
	)
	(arc
		(start 129.351786 -229.416864)
		(mid 129.634742 -229.340687)
		(end 129.917698 -229.416864)
		(width 0.0889)
		(layer "In2.Cu")
		(net "M_I_CPU1_SA_DQ<5>")
	)
	(arc
		(start 131.797806 -229.416864)
		(mid 131.98475 -229.467153)
		(end 132.171694 -229.416864)
		(width 0.0889)
		(layer "In2.Cu")
		(net "M_I_CPU1_SA_DQ<5>")
	)
	(arc
		(start 136.497822 -229.416864)
		(mid 136.684766 -229.467153)
		(end 136.87171 -229.416864)
		(width 0.0889)
		(layer "In2.Cu")
		(net "M_I_CPU1_SA_DQ<5>")
	)
	(arc
		(start 132.737606 -229.416864)
		(mid 132.919857 -229.467248)
		(end 133.103366 -229.42169)
		(width 0.0889)
		(layer "In2.Cu")
		(net "M_I_CPU1_SA_DQ<5>")
	)
	(arc
		(start 142.699486 -227.474526)
		(mid 142.764722 -227.210935)
		(end 142.945358 -227.008182)
		(width 0.0889)
		(layer "In2.Cu")
		(net "M_I_CPU1_SA_DQ<5>")
	)
	(arc
		(start 142.07236 -228.589332)
		(mid 142.187787 -228.455956)
		(end 142.229332 -228.284532)
		(width 0.0889)
		(layer "In2.Cu")
		(net "M_I_CPU1_SA_DQ<5>")
	)
	(arc
		(start 138.377676 -229.416864)
		(mid 138.559927 -229.467248)
		(end 138.743436 -229.42169)
		(width 0.0889)
		(layer "In2.Cu")
		(net "M_I_CPU1_SA_DQ<5>")
	)
	(arc
		(start 140.266166 -229.42169)
		(mid 140.449674 -229.467215)
		(end 140.631926 -229.416864)
		(width 0.0889)
		(layer "In2.Cu")
		(net "M_I_CPU1_SA_DQ<5>")
	)
	(arc
		(start 141.197838 -229.416864)
		(mid 141.384782 -229.467153)
		(end 141.571726 -229.416864)
		(width 0.0889)
		(layer "In2.Cu")
		(net "M_I_CPU1_SA_DQ<5>")
	)
	(arc
		(start 141.759432 -229.094538)
		(mid 141.823947 -228.832319)
		(end 142.002764 -228.629972)
		(width 0.0889)
		(layer "In2.Cu")
		(net "M_I_CPU1_SA_DQ<5>")
	)
	(arc
		(start 135.56615 -229.42169)
		(mid 135.749658 -229.467215)
		(end 135.93191 -229.416864)
		(width 0.0889)
		(layer "In2.Cu")
		(net "M_I_CPU1_SA_DQ<5>")
	)
	(arc
		(start 133.111748 -229.416864)
		(mid 133.394704 -229.340687)
		(end 133.67766 -229.416864)
		(width 0.0889)
		(layer "In2.Cu")
		(net "M_I_CPU1_SA_DQ<5>")
	)
	(arc
		(start 134.626096 -229.42169)
		(mid 134.809604 -229.467215)
		(end 134.991856 -229.416864)
		(width 0.0889)
		(layer "In2.Cu")
		(net "M_I_CPU1_SA_DQ<5>")
	)
	(arc
		(start 130.29184 -229.416864)
		(mid 130.574796 -229.340687)
		(end 130.857752 -229.416864)
		(width 0.0889)
		(layer "In2.Cu")
		(net "M_I_CPU1_SA_DQ<5>")
	)
	(arc
		(start 131.231894 -229.416864)
		(mid 131.51485 -229.340687)
		(end 131.797806 -229.416864)
		(width 0.0889)
		(layer "In2.Cu")
		(net "M_I_CPU1_SA_DQ<5>")
	)
	(arc
		(start 141.605254 -229.397306)
		(mid 141.718661 -229.264417)
		(end 141.759432 -229.094538)
		(width 0.0889)
		(layer "In2.Cu")
		(net "M_I_CPU1_SA_DQ<5>")
	)
	(arc
		(start 144.57934 -224.234502)
		(mid 144.643855 -223.972283)
		(end 144.822672 -223.769936)
		(width 0.0889)
		(layer "In2.Cu")
		(net "M_I_CPU1_SA_DQ<5>")
	)
	(arc
		(start 136.87171 -229.416864)
		(mid 137.154666 -229.340687)
		(end 137.437622 -229.416864)
		(width 0.0889)
		(layer "In2.Cu")
		(net "M_I_CPU1_SA_DQ<5>")
	)
	(arc
		(start 128.411732 -229.416864)
		(mid 128.694688 -229.340687)
		(end 128.977644 -229.416864)
		(width 0.0889)
		(layer "In2.Cu")
		(net "M_I_CPU1_SA_DQ<5>")
	)
	(arc
		(start 128.092708 -229.443026)
		(mid 128.250359 -229.466338)
		(end 128.40335 -229.42169)
		(width 0.0889)
		(layer "In2.Cu")
		(net "M_I_CPU1_SA_DQ<5>")
	)
	(arc
		(start 134.051802 -229.416864)
		(mid 134.334758 -229.340687)
		(end 134.617714 -229.416864)
		(width 0.0889)
		(layer "In2.Cu")
		(net "M_I_CPU1_SA_DQ<5>")
	)
	(arc
		(start 135.93191 -229.416864)
		(mid 136.214866 -229.340687)
		(end 136.497822 -229.416864)
		(width 0.0889)
		(layer "In2.Cu")
		(net "M_I_CPU1_SA_DQ<5>")
	)
	(arc
		(start 129.92608 -229.42169)
		(mid 130.109588 -229.467215)
		(end 130.29184 -229.416864)
		(width 0.0889)
		(layer "In2.Cu")
		(net "M_I_CPU1_SA_DQ<5>")
	)
	(arc
		(start 144.893538 -223.728788)
		(mid 145.008214 -223.595454)
		(end 145.049494 -223.424496)
		(width 0.0889)
		(layer "In2.Cu")
		(net "M_I_CPU1_SA_DQ<5>")
	)
	(arc
		(start 140.631926 -229.416864)
		(mid 140.914882 -229.340687)
		(end 141.197838 -229.416864)
		(width 0.0889)
		(layer "In2.Cu")
		(net "M_I_CPU1_SA_DQ<5>")
	)
	(arc
		(start 137.811764 -229.416864)
		(mid 138.09472 -229.340687)
		(end 138.377676 -229.416864)
		(width 0.0889)
		(layer "In2.Cu")
		(net "M_I_CPU1_SA_DQ<5>")
	)
	(arc
		(start 145.049494 -223.424496)
		(mid 145.112726 -223.164803)
		(end 145.288254 -222.963232)
		(width 0.0889)
		(layer "In2.Cu")
		(net "M_I_CPU1_SA_DQ<5>")
	)
	(arc
		(start 139.691872 -229.416864)
		(mid 139.974828 -229.340687)
		(end 140.257784 -229.416864)
		(width 0.0889)
		(layer "In2.Cu")
		(net "M_I_CPU1_SA_DQ<5>")
	)
	(arc
		(start 144.422368 -224.539302)
		(mid 144.537795 -224.405926)
		(end 144.57934 -224.234502)
		(width 0.0889)
		(layer "In2.Cu")
		(net "M_I_CPU1_SA_DQ<5>")
	)
	(arc
		(start 144.10944 -225.044508)
		(mid 144.173955 -224.782289)
		(end 144.352772 -224.579942)
		(width 0.0889)
		(layer "In2.Cu")
		(net "M_I_CPU1_SA_DQ<5>")
	)
	(arc
		(start 139.326112 -229.42169)
		(mid 139.50962 -229.467215)
		(end 139.691872 -229.416864)
		(width 0.0889)
		(layer "In2.Cu")
		(net "M_I_CPU1_SA_DQ<5>")
	)
	(arc
		(start 143.01343 -226.968812)
		(mid 143.128106 -226.835478)
		(end 143.169386 -226.66452)
		(width 0.0889)
		(layer "In2.Cu")
		(net "M_I_CPU1_SA_DQ<5>")
	)
	(arc
		(start 143.639286 -225.854514)
		(mid 143.703801 -225.592295)
		(end 143.882618 -225.389948)
		(width 0.0889)
		(layer "In2.Cu")
		(net "M_I_CPU1_SA_DQ<5>")
	)
	(segment
		(start 129.16789 -228.55047)
		(end 129.634742 -228.284532)
		(width 0.10668)
		(layer "F.Cu")
		(net "M_I_CPU1_SA_DQ<4>")
	)
	(segment
		(start 141.571726 -227.797106)
		(end 141.603476 -227.778818)
		(width 0.0889)
		(layer "In2.Cu")
		(net "M_I_CPU1_SA_DQ<4>")
	)
	(segment
		(start 181.770274 -203.804012)
		(end 181.933088 -203.966826)
		(width 0.14478)
		(layer "In2.Cu")
		(net "M_I_CPU1_SA_DQ<4>")
	)
	(segment
		(start 156.604716 -207.679544)
		(end 160.564322 -203.719938)
		(width 0.14478)
		(layer "In2.Cu")
		(net "M_I_CPU1_SA_DQ<4>")
	)
	(segment
		(start 142.98168 -225.367088)
		(end 143.01343 -225.3488)
		(width 0.0889)
		(layer "In2.Cu")
		(net "M_I_CPU1_SA_DQ<4>")
	)
	(segment
		(start 144.391888 -222.93707)
		(end 144.420082 -222.920814)
		(width 0.0889)
		(layer "In2.Cu")
		(net "M_I_CPU1_SA_DQ<4>")
	)
	(segment
		(start 129.634742 -228.284532)
		(end 129.480818 -228.549962)
		(width 0.0889)
		(layer "In2.Cu")
		(net "M_I_CPU1_SA_DQ<4>")
	)
	(segment
		(start 142.945358 -225.38817)
		(end 142.98168 -225.367088)
		(width 0.0889)
		(layer "In2.Cu")
		(net "M_I_CPU1_SA_DQ<4>")
	)
	(segment
		(start 141.101826 -228.607112)
		(end 141.133576 -228.588824)
		(width 0.0889)
		(layer "In2.Cu")
		(net "M_I_CPU1_SA_DQ<4>")
	)
	(segment
		(start 170.629834 -203.719938)
		(end 173.64329 -203.719938)
		(width 0.14478)
		(layer "In2.Cu")
		(net "M_I_CPU1_SA_DQ<4>")
	)
	(segment
		(start 145.054574 -221.85757)
		(end 145.054574 -221.276926)
		(width 0.0889)
		(layer "In2.Cu")
		(net "M_I_CPU1_SA_DQ<4>")
	)
	(segment
		(start 167.170354 -202.870054)
		(end 169.77995 -202.870054)
		(width 0.14478)
		(layer "In2.Cu")
		(net "M_I_CPU1_SA_DQ<4>")
	)
	(segment
		(start 141.093444 -228.611938)
		(end 141.101826 -228.607112)
		(width 0.0889)
		(layer "In2.Cu")
		(net "M_I_CPU1_SA_DQ<4>")
	)
	(segment
		(start 181.617112 -202.870054)
		(end 181.770274 -203.023216)
		(width 0.14478)
		(layer "In2.Cu")
		(net "M_I_CPU1_SA_DQ<4>")
	)
	(segment
		(start 136.393428 -228.611938)
		(end 136.40181 -228.607112)
		(width 0.0889)
		(layer "In2.Cu")
		(net "M_I_CPU1_SA_DQ<4>")
	)
	(segment
		(start 166.32047 -203.719938)
		(end 167.170354 -202.870054)
		(width 0.14478)
		(layer "In2.Cu")
		(net "M_I_CPU1_SA_DQ<4>")
	)
	(segment
		(start 174.493174 -202.870054)
		(end 181.617112 -202.870054)
		(width 0.14478)
		(layer "In2.Cu")
		(net "M_I_CPU1_SA_DQ<4>")
	)
	(segment
		(start 181.770274 -203.023216)
		(end 181.770274 -203.804012)
		(width 0.14478)
		(layer "In2.Cu")
		(net "M_I_CPU1_SA_DQ<4>")
	)
	(segment
		(start 143.412718 -224.579942)
		(end 143.451834 -224.557082)
		(width 0.0889)
		(layer "In2.Cu")
		(net "M_I_CPU1_SA_DQ<4>")
	)
	(segment
		(start 143.921734 -223.747076)
		(end 143.953484 -223.728788)
		(width 0.0889)
		(layer "In2.Cu")
		(net "M_I_CPU1_SA_DQ<4>")
	)
	(segment
		(start 182.16372 -203.966826)
		(end 182.326534 -203.804012)
		(width 0.14478)
		(layer "In2.Cu")
		(net "M_I_CPU1_SA_DQ<4>")
	)
	(segment
		(start 136.967722 -228.607112)
		(end 136.976104 -228.611938)
		(width 0.0889)
		(layer "In2.Cu")
		(net "M_I_CPU1_SA_DQ<4>")
	)
	(segment
		(start 145.054574 -220.197426)
		(end 156.604716 -208.647284)
		(width 0.14478)
		(layer "In2.Cu")
		(net "M_I_CPU1_SA_DQ<4>")
	)
	(segment
		(start 173.64329 -203.719938)
		(end 174.493174 -202.870054)
		(width 0.14478)
		(layer "In2.Cu")
		(net "M_I_CPU1_SA_DQ<4>")
	)
	(segment
		(start 182.326534 -203.804012)
		(end 182.326534 -203.023216)
		(width 0.14478)
		(layer "In2.Cu")
		(net "M_I_CPU1_SA_DQ<4>")
	)
	(segment
		(start 142.472664 -226.199954)
		(end 142.51178 -226.177094)
		(width 0.0889)
		(layer "In2.Cu")
		(net "M_I_CPU1_SA_DQ<4>")
	)
	(segment
		(start 142.51178 -226.177094)
		(end 142.54353 -226.158806)
		(width 0.0889)
		(layer "In2.Cu")
		(net "M_I_CPU1_SA_DQ<4>")
	)
	(segment
		(start 135.453374 -228.611938)
		(end 135.461756 -228.607112)
		(width 0.0889)
		(layer "In2.Cu")
		(net "M_I_CPU1_SA_DQ<4>")
	)
	(segment
		(start 169.77995 -202.870054)
		(end 170.629834 -203.719938)
		(width 0.14478)
		(layer "In2.Cu")
		(net "M_I_CPU1_SA_DQ<4>")
	)
	(segment
		(start 144.352772 -222.95993)
		(end 144.391888 -222.93707)
		(width 0.0889)
		(layer "In2.Cu")
		(net "M_I_CPU1_SA_DQ<4>")
	)
	(segment
		(start 131.693412 -228.611938)
		(end 131.701794 -228.607112)
		(width 0.0889)
		(layer "In2.Cu")
		(net "M_I_CPU1_SA_DQ<4>")
	)
	(segment
		(start 143.451834 -224.557082)
		(end 143.482314 -224.539302)
		(width 0.0889)
		(layer "In2.Cu")
		(net "M_I_CPU1_SA_DQ<4>")
	)
	(segment
		(start 140.15339 -228.611938)
		(end 140.161772 -228.607112)
		(width 0.0889)
		(layer "In2.Cu")
		(net "M_I_CPU1_SA_DQ<4>")
	)
	(segment
		(start 129.480818 -228.549962)
		(end 129.50317 -228.633274)
		(width 0.0889)
		(layer "In2.Cu")
		(net "M_I_CPU1_SA_DQ<4>")
	)
	(segment
		(start 144.873218 -222.119952)
		(end 144.997424 -221.995746)
		(width 0.0889)
		(layer "In2.Cu")
		(net "M_I_CPU1_SA_DQ<4>")
	)
	(segment
		(start 182.326534 -203.023216)
		(end 182.489348 -202.860402)
		(width 0.14478)
		(layer "In2.Cu")
		(net "M_I_CPU1_SA_DQ<4>")
	)
	(segment
		(start 133.20776 -228.607112)
		(end 133.216142 -228.611938)
		(width 0.0889)
		(layer "In2.Cu")
		(net "M_I_CPU1_SA_DQ<4>")
	)
	(segment
		(start 182.489348 -202.860402)
		(end 183.19115 -202.860402)
		(width 0.14478)
		(layer "In2.Cu")
		(net "M_I_CPU1_SA_DQ<4>")
	)
	(segment
		(start 130.753358 -228.611938)
		(end 130.76174 -228.607112)
		(width 0.0889)
		(layer "In2.Cu")
		(net "M_I_CPU1_SA_DQ<4>")
	)
	(segment
		(start 160.564322 -203.719938)
		(end 166.32047 -203.719938)
		(width 0.14478)
		(layer "In2.Cu")
		(net "M_I_CPU1_SA_DQ<4>")
	)
	(segment
		(start 143.882618 -223.769936)
		(end 143.921734 -223.747076)
		(width 0.0889)
		(layer "In2.Cu")
		(net "M_I_CPU1_SA_DQ<4>")
	)
	(segment
		(start 144.828006 -222.146368)
		(end 144.873218 -222.119952)
		(width 0.0889)
		(layer "In2.Cu")
		(net "M_I_CPU1_SA_DQ<4>")
	)
	(segment
		(start 132.267706 -228.607112)
		(end 132.276088 -228.611938)
		(width 0.0889)
		(layer "In2.Cu")
		(net "M_I_CPU1_SA_DQ<4>")
	)
	(segment
		(start 144.997424 -221.995746)
		(end 145.054574 -221.85757)
		(width 0.0889)
		(layer "In2.Cu")
		(net "M_I_CPU1_SA_DQ<4>")
	)
	(segment
		(start 141.535404 -227.818188)
		(end 141.571726 -227.797106)
		(width 0.0889)
		(layer "In2.Cu")
		(net "M_I_CPU1_SA_DQ<4>")
	)
	(segment
		(start 145.054574 -221.276926)
		(end 145.054574 -220.197426)
		(width 0.14478)
		(layer "In2.Cu")
		(net "M_I_CPU1_SA_DQ<4>")
	)
	(segment
		(start 183.19115 -202.860402)
		(end 183.616092 -203.285344)
		(width 0.14478)
		(layer "In2.Cu")
		(net "M_I_CPU1_SA_DQ<4>")
	)
	(segment
		(start 142.04188 -226.9871)
		(end 142.07236 -226.96932)
		(width 0.0889)
		(layer "In2.Cu")
		(net "M_I_CPU1_SA_DQ<4>")
	)
	(segment
		(start 142.002764 -227.00996)
		(end 142.04188 -226.9871)
		(width 0.0889)
		(layer "In2.Cu")
		(net "M_I_CPU1_SA_DQ<4>")
	)
	(segment
		(start 156.604716 -208.647284)
		(end 156.604716 -207.679544)
		(width 0.14478)
		(layer "In2.Cu")
		(net "M_I_CPU1_SA_DQ<4>")
	)
	(segment
		(start 137.907776 -228.607112)
		(end 137.916158 -228.611938)
		(width 0.0889)
		(layer "In2.Cu")
		(net "M_I_CPU1_SA_DQ<4>")
	)
	(segment
		(start 181.933088 -203.966826)
		(end 182.16372 -203.966826)
		(width 0.14478)
		(layer "In2.Cu")
		(net "M_I_CPU1_SA_DQ<4>")
	)
	(arc
		(start 136.40181 -228.607112)
		(mid 136.684766 -228.530935)
		(end 136.967722 -228.607112)
		(width 0.0889)
		(layer "In2.Cu")
		(net "M_I_CPU1_SA_DQ<4>")
	)
	(arc
		(start 132.641848 -228.607112)
		(mid 132.924804 -228.530935)
		(end 133.20776 -228.607112)
		(width 0.0889)
		(layer "In2.Cu")
		(net "M_I_CPU1_SA_DQ<4>")
	)
	(arc
		(start 142.54353 -226.158806)
		(mid 142.658206 -226.025472)
		(end 142.699486 -225.854514)
		(width 0.0889)
		(layer "In2.Cu")
		(net "M_I_CPU1_SA_DQ<4>")
	)
	(arc
		(start 136.027668 -228.607112)
		(mid 136.209919 -228.657462)
		(end 136.393428 -228.611938)
		(width 0.0889)
		(layer "In2.Cu")
		(net "M_I_CPU1_SA_DQ<4>")
	)
	(arc
		(start 138.84783 -228.607112)
		(mid 139.034774 -228.657367)
		(end 139.221718 -228.607112)
		(width 0.0889)
		(layer "In2.Cu")
		(net "M_I_CPU1_SA_DQ<4>")
	)
	(arc
		(start 144.579086 -222.61449)
		(mid 144.645185 -222.349396)
		(end 144.828006 -222.146368)
		(width 0.0889)
		(layer "In2.Cu")
		(net "M_I_CPU1_SA_DQ<4>")
	)
	(arc
		(start 131.327652 -228.607112)
		(mid 131.509903 -228.657462)
		(end 131.693412 -228.611938)
		(width 0.0889)
		(layer "In2.Cu")
		(net "M_I_CPU1_SA_DQ<4>")
	)
	(arc
		(start 132.276088 -228.611938)
		(mid 132.459596 -228.657432)
		(end 132.641848 -228.607112)
		(width 0.0889)
		(layer "In2.Cu")
		(net "M_I_CPU1_SA_DQ<4>")
	)
	(arc
		(start 141.133576 -228.588824)
		(mid 141.248252 -228.45549)
		(end 141.289532 -228.284532)
		(width 0.0889)
		(layer "In2.Cu")
		(net "M_I_CPU1_SA_DQ<4>")
	)
	(arc
		(start 135.087614 -228.607112)
		(mid 135.269865 -228.657462)
		(end 135.453374 -228.611938)
		(width 0.0889)
		(layer "In2.Cu")
		(net "M_I_CPU1_SA_DQ<4>")
	)
	(arc
		(start 135.461756 -228.607112)
		(mid 135.744712 -228.530935)
		(end 136.027668 -228.607112)
		(width 0.0889)
		(layer "In2.Cu")
		(net "M_I_CPU1_SA_DQ<4>")
	)
	(arc
		(start 141.759432 -227.474526)
		(mid 141.823947 -227.212307)
		(end 142.002764 -227.00996)
		(width 0.0889)
		(layer "In2.Cu")
		(net "M_I_CPU1_SA_DQ<4>")
	)
	(arc
		(start 143.169386 -225.044508)
		(mid 143.233901 -224.782289)
		(end 143.412718 -224.579942)
		(width 0.0889)
		(layer "In2.Cu")
		(net "M_I_CPU1_SA_DQ<4>")
	)
	(arc
		(start 138.281918 -228.607112)
		(mid 138.564874 -228.530935)
		(end 138.84783 -228.607112)
		(width 0.0889)
		(layer "In2.Cu")
		(net "M_I_CPU1_SA_DQ<4>")
	)
	(arc
		(start 129.50317 -228.633274)
		(mid 129.665359 -228.656009)
		(end 129.821686 -228.607112)
		(width 0.0889)
		(layer "In2.Cu")
		(net "M_I_CPU1_SA_DQ<4>")
	)
	(arc
		(start 141.289532 -228.284532)
		(mid 141.354768 -228.020941)
		(end 141.535404 -227.818188)
		(width 0.0889)
		(layer "In2.Cu")
		(net "M_I_CPU1_SA_DQ<4>")
	)
	(arc
		(start 139.78763 -228.607112)
		(mid 139.969881 -228.657462)
		(end 140.15339 -228.611938)
		(width 0.0889)
		(layer "In2.Cu")
		(net "M_I_CPU1_SA_DQ<4>")
	)
	(arc
		(start 143.482314 -224.539302)
		(mid 143.597741 -224.405926)
		(end 143.639286 -224.234502)
		(width 0.0889)
		(layer "In2.Cu")
		(net "M_I_CPU1_SA_DQ<4>")
	)
	(arc
		(start 130.387598 -228.607112)
		(mid 130.569849 -228.657462)
		(end 130.753358 -228.611938)
		(width 0.0889)
		(layer "In2.Cu")
		(net "M_I_CPU1_SA_DQ<4>")
	)
	(arc
		(start 131.701794 -228.607112)
		(mid 131.98475 -228.530935)
		(end 132.267706 -228.607112)
		(width 0.0889)
		(layer "In2.Cu")
		(net "M_I_CPU1_SA_DQ<4>")
	)
	(arc
		(start 136.976104 -228.611938)
		(mid 137.159612 -228.657432)
		(end 137.341864 -228.607112)
		(width 0.0889)
		(layer "In2.Cu")
		(net "M_I_CPU1_SA_DQ<4>")
	)
	(arc
		(start 142.699486 -225.854514)
		(mid 142.764722 -225.590923)
		(end 142.945358 -225.38817)
		(width 0.0889)
		(layer "In2.Cu")
		(net "M_I_CPU1_SA_DQ<4>")
	)
	(arc
		(start 143.953484 -223.728788)
		(mid 144.06816 -223.595454)
		(end 144.10944 -223.424496)
		(width 0.0889)
		(layer "In2.Cu")
		(net "M_I_CPU1_SA_DQ<4>")
	)
	(arc
		(start 141.603476 -227.778818)
		(mid 141.718152 -227.645484)
		(end 141.759432 -227.474526)
		(width 0.0889)
		(layer "In2.Cu")
		(net "M_I_CPU1_SA_DQ<4>")
	)
	(arc
		(start 144.10944 -223.424496)
		(mid 144.173955 -223.162277)
		(end 144.352772 -222.95993)
		(width 0.0889)
		(layer "In2.Cu")
		(net "M_I_CPU1_SA_DQ<4>")
	)
	(arc
		(start 129.821686 -228.607112)
		(mid 130.104642 -228.530935)
		(end 130.387598 -228.607112)
		(width 0.0889)
		(layer "In2.Cu")
		(net "M_I_CPU1_SA_DQ<4>")
	)
	(arc
		(start 137.916158 -228.611938)
		(mid 138.099666 -228.657432)
		(end 138.281918 -228.607112)
		(width 0.0889)
		(layer "In2.Cu")
		(net "M_I_CPU1_SA_DQ<4>")
	)
	(arc
		(start 143.01343 -225.3488)
		(mid 143.128106 -225.215466)
		(end 143.169386 -225.044508)
		(width 0.0889)
		(layer "In2.Cu")
		(net "M_I_CPU1_SA_DQ<4>")
	)
	(arc
		(start 140.727684 -228.607112)
		(mid 140.909935 -228.657462)
		(end 141.093444 -228.611938)
		(width 0.0889)
		(layer "In2.Cu")
		(net "M_I_CPU1_SA_DQ<4>")
	)
	(arc
		(start 133.216142 -228.611938)
		(mid 133.39965 -228.657432)
		(end 133.581902 -228.607112)
		(width 0.0889)
		(layer "In2.Cu")
		(net "M_I_CPU1_SA_DQ<4>")
	)
	(arc
		(start 133.581902 -228.607112)
		(mid 133.864858 -228.530935)
		(end 134.147814 -228.607112)
		(width 0.0889)
		(layer "In2.Cu")
		(net "M_I_CPU1_SA_DQ<4>")
	)
	(arc
		(start 139.221718 -228.607112)
		(mid 139.504674 -228.530935)
		(end 139.78763 -228.607112)
		(width 0.0889)
		(layer "In2.Cu")
		(net "M_I_CPU1_SA_DQ<4>")
	)
	(arc
		(start 137.341864 -228.607112)
		(mid 137.62482 -228.530935)
		(end 137.907776 -228.607112)
		(width 0.0889)
		(layer "In2.Cu")
		(net "M_I_CPU1_SA_DQ<4>")
	)
	(arc
		(start 134.147814 -228.607112)
		(mid 134.334758 -228.657367)
		(end 134.521702 -228.607112)
		(width 0.0889)
		(layer "In2.Cu")
		(net "M_I_CPU1_SA_DQ<4>")
	)
	(arc
		(start 134.521702 -228.607112)
		(mid 134.804658 -228.530935)
		(end 135.087614 -228.607112)
		(width 0.0889)
		(layer "In2.Cu")
		(net "M_I_CPU1_SA_DQ<4>")
	)
	(arc
		(start 140.161772 -228.607112)
		(mid 140.444728 -228.530935)
		(end 140.727684 -228.607112)
		(width 0.0889)
		(layer "In2.Cu")
		(net "M_I_CPU1_SA_DQ<4>")
	)
	(arc
		(start 142.07236 -226.96932)
		(mid 142.187787 -226.835944)
		(end 142.229332 -226.66452)
		(width 0.0889)
		(layer "In2.Cu")
		(net "M_I_CPU1_SA_DQ<4>")
	)
	(arc
		(start 144.420082 -222.920814)
		(mid 144.536943 -222.787049)
		(end 144.579086 -222.61449)
		(width 0.0889)
		(layer "In2.Cu")
		(net "M_I_CPU1_SA_DQ<4>")
	)
	(arc
		(start 142.229332 -226.66452)
		(mid 142.293847 -226.402301)
		(end 142.472664 -226.199954)
		(width 0.0889)
		(layer "In2.Cu")
		(net "M_I_CPU1_SA_DQ<4>")
	)
	(arc
		(start 143.639286 -224.234502)
		(mid 143.703801 -223.972283)
		(end 143.882618 -223.769936)
		(width 0.0889)
		(layer "In2.Cu")
		(net "M_I_CPU1_SA_DQ<4>")
	)
	(arc
		(start 130.76174 -228.607112)
		(mid 131.044696 -228.530935)
		(end 131.327652 -228.607112)
		(width 0.0889)
		(layer "In2.Cu")
		(net "M_I_CPU1_SA_DQ<4>")
	)
	(segment
		(start 127.287782 -226.930458)
		(end 127.754634 -226.66452)
		(width 0.10668)
		(layer "F.Cu")
		(net "M_I_CPU1_SA_DQ<3>")
	)
	(segment
		(start 136.967722 -226.34194)
		(end 136.976104 -226.337114)
		(width 0.0889)
		(layer "In2.Cu")
		(net "M_I_CPU1_SA_DQ<3>")
	)
	(segment
		(start 157.135322 -203.545948)
		(end 157.135322 -203.317602)
		(width 0.14478)
		(layer "In2.Cu")
		(net "M_I_CPU1_SA_DQ<3>")
	)
	(segment
		(start 159.324802 -200.825354)
		(end 159.324802 -200.597262)
		(width 0.14478)
		(layer "In2.Cu")
		(net "M_I_CPU1_SA_DQ<3>")
	)
	(segment
		(start 127.754634 -226.66452)
		(end 127.908812 -226.39909)
		(width 0.0889)
		(layer "In2.Cu")
		(net "M_I_CPU1_SA_DQ<3>")
	)
	(segment
		(start 141.95044 -222.506286)
		(end 142.54099 -221.17685)
		(width 0.0889)
		(layer "In2.Cu")
		(net "M_I_CPU1_SA_DQ<3>")
	)
	(segment
		(start 158.305754 -202.147424)
		(end 158.533846 -202.147424)
		(width 0.14478)
		(layer "In2.Cu")
		(net "M_I_CPU1_SA_DQ<3>")
	)
	(segment
		(start 142.54099 -221.17685)
		(end 142.54099 -219.47378)
		(width 0.14478)
		(layer "In2.Cu")
		(net "M_I_CPU1_SA_DQ<3>")
	)
	(segment
		(start 157.926278 -201.995786)
		(end 158.15437 -201.995786)
		(width 0.14478)
		(layer "In2.Cu")
		(net "M_I_CPU1_SA_DQ<3>")
	)
	(segment
		(start 157.764226 -202.157838)
		(end 157.926278 -201.995786)
		(width 0.14478)
		(layer "In2.Cu")
		(net "M_I_CPU1_SA_DQ<3>")
	)
	(segment
		(start 137.907776 -226.34194)
		(end 137.916158 -226.337114)
		(width 0.0889)
		(layer "In2.Cu")
		(net "M_I_CPU1_SA_DQ<3>")
	)
	(segment
		(start 156.97327 -203.708)
		(end 157.135322 -203.545948)
		(width 0.14478)
		(layer "In2.Cu")
		(net "M_I_CPU1_SA_DQ<3>")
	)
	(segment
		(start 165.987222 -200.30059)
		(end 166.837106 -199.450706)
		(width 0.14478)
		(layer "In2.Cu")
		(net "M_I_CPU1_SA_DQ<3>")
	)
	(segment
		(start 159.714946 -200.43521)
		(end 159.86633 -200.586848)
		(width 0.14478)
		(layer "In2.Cu")
		(net "M_I_CPU1_SA_DQ<3>")
	)
	(segment
		(start 158.533846 -202.147424)
		(end 158.695898 -201.985372)
		(width 0.14478)
		(layer "In2.Cu")
		(net "M_I_CPU1_SA_DQ<3>")
	)
	(segment
		(start 136.393428 -226.337114)
		(end 136.40181 -226.34194)
		(width 0.0889)
		(layer "In2.Cu")
		(net "M_I_CPU1_SA_DQ<3>")
	)
	(segment
		(start 170.2308 -199.450706)
		(end 171.080684 -200.30059)
		(width 0.14478)
		(layer "In2.Cu")
		(net "M_I_CPU1_SA_DQ<3>")
	)
	(segment
		(start 159.314134 -201.367136)
		(end 159.476186 -201.205084)
		(width 0.14478)
		(layer "In2.Cu")
		(net "M_I_CPU1_SA_DQ<3>")
	)
	(segment
		(start 155.423362 -204.498702)
		(end 155.585414 -204.33665)
		(width 0.14478)
		(layer "In2.Cu")
		(net "M_I_CPU1_SA_DQ<3>")
	)
	(segment
		(start 140.696188 -224.740216)
		(end 140.727938 -224.721928)
		(width 0.0889)
		(layer "In2.Cu")
		(net "M_I_CPU1_SA_DQ<3>")
	)
	(segment
		(start 166.837106 -199.450706)
		(end 170.2308 -199.450706)
		(width 0.14478)
		(layer "In2.Cu")
		(net "M_I_CPU1_SA_DQ<3>")
	)
	(segment
		(start 141.638528 -223.118934)
		(end 141.667992 -223.101916)
		(width 0.0889)
		(layer "In2.Cu")
		(net "M_I_CPU1_SA_DQ<3>")
	)
	(segment
		(start 174.375572 -199.450706)
		(end 177.12436 -199.450706)
		(width 0.14478)
		(layer "In2.Cu")
		(net "M_I_CPU1_SA_DQ<3>")
	)
	(segment
		(start 141.198092 -223.911922)
		(end 141.238478 -223.8883)
		(width 0.0889)
		(layer "In2.Cu")
		(net "M_I_CPU1_SA_DQ<3>")
	)
	(segment
		(start 159.476186 -200.976738)
		(end 159.324802 -200.825354)
		(width 0.14478)
		(layer "In2.Cu")
		(net "M_I_CPU1_SA_DQ<3>")
	)
	(segment
		(start 155.813506 -204.33665)
		(end 155.96489 -204.488288)
		(width 0.14478)
		(layer "In2.Cu")
		(net "M_I_CPU1_SA_DQ<3>")
	)
	(segment
		(start 158.934658 -201.215498)
		(end 159.086042 -201.367136)
		(width 0.14478)
		(layer "In2.Cu")
		(net "M_I_CPU1_SA_DQ<3>")
	)
	(segment
		(start 141.95044 -222.61449)
		(end 141.95044 -222.506286)
		(width 0.0889)
		(layer "In2.Cu")
		(net "M_I_CPU1_SA_DQ<3>")
	)
	(segment
		(start 160.094422 -200.586848)
		(end 160.38068 -200.30059)
		(width 0.14478)
		(layer "In2.Cu")
		(net "M_I_CPU1_SA_DQ<3>")
	)
	(segment
		(start 142.54099 -219.47378)
		(end 148.468588 -213.546182)
		(width 0.14478)
		(layer "In2.Cu")
		(net "M_I_CPU1_SA_DQ<3>")
	)
	(segment
		(start 148.468588 -212.212682)
		(end 155.574746 -205.106524)
		(width 0.14478)
		(layer "In2.Cu")
		(net "M_I_CPU1_SA_DQ<3>")
	)
	(segment
		(start 155.96489 -204.488288)
		(end 156.192982 -204.488288)
		(width 0.14478)
		(layer "In2.Cu")
		(net "M_I_CPU1_SA_DQ<3>")
	)
	(segment
		(start 173.525688 -200.30059)
		(end 174.375572 -199.450706)
		(width 0.14478)
		(layer "In2.Cu")
		(net "M_I_CPU1_SA_DQ<3>")
	)
	(segment
		(start 155.585414 -204.33665)
		(end 155.813506 -204.33665)
		(width 0.14478)
		(layer "In2.Cu")
		(net "M_I_CPU1_SA_DQ<3>")
	)
	(segment
		(start 178.534822 -199.152764)
		(end 178.783488 -199.152764)
		(width 0.14478)
		(layer "In2.Cu")
		(net "M_I_CPU1_SA_DQ<3>")
	)
	(segment
		(start 156.745178 -203.708)
		(end 156.97327 -203.708)
		(width 0.14478)
		(layer "In2.Cu")
		(net "M_I_CPU1_SA_DQ<3>")
	)
	(segment
		(start 158.706566 -201.215498)
		(end 158.934658 -201.215498)
		(width 0.14478)
		(layer "In2.Cu")
		(net "M_I_CPU1_SA_DQ<3>")
	)
	(segment
		(start 141.167358 -223.929702)
		(end 141.198092 -223.911922)
		(width 0.0889)
		(layer "In2.Cu")
		(net "M_I_CPU1_SA_DQ<3>")
	)
	(segment
		(start 177.978562 -199.460358)
		(end 178.227228 -199.460358)
		(width 0.14478)
		(layer "In2.Cu")
		(net "M_I_CPU1_SA_DQ<3>")
	)
	(segment
		(start 159.476186 -201.205084)
		(end 159.476186 -200.976738)
		(width 0.14478)
		(layer "In2.Cu")
		(net "M_I_CPU1_SA_DQ<3>")
	)
	(segment
		(start 139.78763 -226.34194)
		(end 139.826746 -226.31908)
		(width 0.0889)
		(layer "In2.Cu")
		(net "M_I_CPU1_SA_DQ<3>")
	)
	(segment
		(start 157.374082 -202.776074)
		(end 157.525466 -202.927712)
		(width 0.14478)
		(layer "In2.Cu")
		(net "M_I_CPU1_SA_DQ<3>")
	)
	(segment
		(start 159.86633 -200.586848)
		(end 160.094422 -200.586848)
		(width 0.14478)
		(layer "In2.Cu")
		(net "M_I_CPU1_SA_DQ<3>")
	)
	(segment
		(start 156.365702 -203.556362)
		(end 156.593794 -203.556362)
		(width 0.14478)
		(layer "In2.Cu")
		(net "M_I_CPU1_SA_DQ<3>")
	)
	(segment
		(start 160.38068 -200.30059)
		(end 165.987222 -200.30059)
		(width 0.14478)
		(layer "In2.Cu")
		(net "M_I_CPU1_SA_DQ<3>")
	)
	(segment
		(start 158.695898 -201.757026)
		(end 158.544514 -201.605642)
		(width 0.14478)
		(layer "In2.Cu")
		(net "M_I_CPU1_SA_DQ<3>")
	)
	(segment
		(start 156.20365 -203.718414)
		(end 156.365702 -203.556362)
		(width 0.14478)
		(layer "In2.Cu")
		(net "M_I_CPU1_SA_DQ<3>")
	)
	(segment
		(start 157.14599 -202.776074)
		(end 157.374082 -202.776074)
		(width 0.14478)
		(layer "In2.Cu")
		(net "M_I_CPU1_SA_DQ<3>")
	)
	(segment
		(start 148.468588 -213.546182)
		(end 148.468588 -212.212682)
		(width 0.14478)
		(layer "In2.Cu")
		(net "M_I_CPU1_SA_DQ<3>")
	)
	(segment
		(start 177.12436 -199.450706)
		(end 177.422302 -199.152764)
		(width 0.14478)
		(layer "In2.Cu")
		(net "M_I_CPU1_SA_DQ<3>")
	)
	(segment
		(start 157.764226 -202.38593)
		(end 157.764226 -202.157838)
		(width 0.14478)
		(layer "In2.Cu")
		(net "M_I_CPU1_SA_DQ<3>")
	)
	(segment
		(start 157.91561 -202.537314)
		(end 157.764226 -202.38593)
		(width 0.14478)
		(layer "In2.Cu")
		(net "M_I_CPU1_SA_DQ<3>")
	)
	(segment
		(start 157.525466 -202.927712)
		(end 157.753558 -202.927712)
		(width 0.14478)
		(layer "In2.Cu")
		(net "M_I_CPU1_SA_DQ<3>")
	)
	(segment
		(start 158.695898 -201.985372)
		(end 158.695898 -201.757026)
		(width 0.14478)
		(layer "In2.Cu")
		(net "M_I_CPU1_SA_DQ<3>")
	)
	(segment
		(start 155.423362 -204.726794)
		(end 155.423362 -204.498702)
		(width 0.14478)
		(layer "In2.Cu")
		(net "M_I_CPU1_SA_DQ<3>")
	)
	(segment
		(start 156.983938 -203.166218)
		(end 156.983938 -202.938126)
		(width 0.14478)
		(layer "In2.Cu")
		(net "M_I_CPU1_SA_DQ<3>")
	)
	(segment
		(start 171.080684 -200.30059)
		(end 173.525688 -200.30059)
		(width 0.14478)
		(layer "In2.Cu")
		(net "M_I_CPU1_SA_DQ<3>")
	)
	(segment
		(start 156.192982 -204.488288)
		(end 156.355034 -204.326236)
		(width 0.14478)
		(layer "In2.Cu")
		(net "M_I_CPU1_SA_DQ<3>")
	)
	(segment
		(start 156.355034 -204.326236)
		(end 156.355034 -204.09789)
		(width 0.14478)
		(layer "In2.Cu")
		(net "M_I_CPU1_SA_DQ<3>")
	)
	(segment
		(start 157.135322 -203.317602)
		(end 156.983938 -203.166218)
		(width 0.14478)
		(layer "In2.Cu")
		(net "M_I_CPU1_SA_DQ<3>")
	)
	(segment
		(start 158.15437 -201.995786)
		(end 158.305754 -202.147424)
		(width 0.14478)
		(layer "In2.Cu")
		(net "M_I_CPU1_SA_DQ<3>")
	)
	(segment
		(start 155.574746 -205.106524)
		(end 155.574746 -204.878178)
		(width 0.14478)
		(layer "In2.Cu")
		(net "M_I_CPU1_SA_DQ<3>")
	)
	(segment
		(start 132.267706 -226.34194)
		(end 132.276088 -226.337114)
		(width 0.0889)
		(layer "In2.Cu")
		(net "M_I_CPU1_SA_DQ<3>")
	)
	(segment
		(start 177.422302 -199.152764)
		(end 177.670968 -199.152764)
		(width 0.14478)
		(layer "In2.Cu")
		(net "M_I_CPU1_SA_DQ<3>")
	)
	(segment
		(start 158.544514 -201.37755)
		(end 158.706566 -201.215498)
		(width 0.14478)
		(layer "In2.Cu")
		(net "M_I_CPU1_SA_DQ<3>")
	)
	(segment
		(start 159.324802 -200.597262)
		(end 159.486854 -200.43521)
		(width 0.14478)
		(layer "In2.Cu")
		(net "M_I_CPU1_SA_DQ<3>")
	)
	(segment
		(start 157.753558 -202.927712)
		(end 157.91561 -202.76566)
		(width 0.14478)
		(layer "In2.Cu")
		(net "M_I_CPU1_SA_DQ<3>")
	)
	(segment
		(start 178.783488 -199.152764)
		(end 179.516024 -199.8853)
		(width 0.14478)
		(layer "In2.Cu")
		(net "M_I_CPU1_SA_DQ<3>")
	)
	(segment
		(start 159.086042 -201.367136)
		(end 159.314134 -201.367136)
		(width 0.14478)
		(layer "In2.Cu")
		(net "M_I_CPU1_SA_DQ<3>")
	)
	(segment
		(start 155.574746 -204.878178)
		(end 155.423362 -204.726794)
		(width 0.14478)
		(layer "In2.Cu")
		(net "M_I_CPU1_SA_DQ<3>")
	)
	(segment
		(start 128.507744 -226.34194)
		(end 128.516126 -226.337114)
		(width 0.0889)
		(layer "In2.Cu")
		(net "M_I_CPU1_SA_DQ<3>")
	)
	(segment
		(start 157.91561 -202.76566)
		(end 157.91561 -202.537314)
		(width 0.14478)
		(layer "In2.Cu")
		(net "M_I_CPU1_SA_DQ<3>")
	)
	(segment
		(start 178.227228 -199.460358)
		(end 178.534822 -199.152764)
		(width 0.14478)
		(layer "In2.Cu")
		(net "M_I_CPU1_SA_DQ<3>")
	)
	(segment
		(start 127.908812 -226.39909)
		(end 128.005078 -226.37369)
		(width 0.0889)
		(layer "In2.Cu")
		(net "M_I_CPU1_SA_DQ<3>")
	)
	(segment
		(start 130.753358 -226.337114)
		(end 130.76174 -226.34194)
		(width 0.0889)
		(layer "In2.Cu")
		(net "M_I_CPU1_SA_DQ<3>")
	)
	(segment
		(start 177.670968 -199.152764)
		(end 177.978562 -199.460358)
		(width 0.14478)
		(layer "In2.Cu")
		(net "M_I_CPU1_SA_DQ<3>")
	)
	(segment
		(start 156.355034 -204.09789)
		(end 156.20365 -203.946506)
		(width 0.14478)
		(layer "In2.Cu")
		(net "M_I_CPU1_SA_DQ<3>")
	)
	(segment
		(start 133.20776 -226.34194)
		(end 133.216142 -226.337114)
		(width 0.0889)
		(layer "In2.Cu")
		(net "M_I_CPU1_SA_DQ<3>")
	)
	(segment
		(start 140.257784 -225.531934)
		(end 140.2969 -225.509074)
		(width 0.0889)
		(layer "In2.Cu")
		(net "M_I_CPU1_SA_DQ<3>")
	)
	(segment
		(start 131.693412 -226.337114)
		(end 131.701794 -226.34194)
		(width 0.0889)
		(layer "In2.Cu")
		(net "M_I_CPU1_SA_DQ<3>")
	)
	(segment
		(start 140.226034 -225.550222)
		(end 140.257784 -225.531934)
		(width 0.0889)
		(layer "In2.Cu")
		(net "M_I_CPU1_SA_DQ<3>")
	)
	(segment
		(start 158.544514 -201.605642)
		(end 158.544514 -201.37755)
		(width 0.14478)
		(layer "In2.Cu")
		(net "M_I_CPU1_SA_DQ<3>")
	)
	(segment
		(start 135.453374 -226.337114)
		(end 135.461756 -226.34194)
		(width 0.0889)
		(layer "In2.Cu")
		(net "M_I_CPU1_SA_DQ<3>")
	)
	(segment
		(start 141.667992 -223.101916)
		(end 141.708378 -223.078294)
		(width 0.0889)
		(layer "In2.Cu")
		(net "M_I_CPU1_SA_DQ<3>")
	)
	(segment
		(start 156.983938 -202.938126)
		(end 157.14599 -202.776074)
		(width 0.14478)
		(layer "In2.Cu")
		(net "M_I_CPU1_SA_DQ<3>")
	)
	(segment
		(start 156.20365 -203.946506)
		(end 156.20365 -203.718414)
		(width 0.14478)
		(layer "In2.Cu")
		(net "M_I_CPU1_SA_DQ<3>")
	)
	(segment
		(start 140.727938 -224.721928)
		(end 140.765784 -224.700084)
		(width 0.0889)
		(layer "In2.Cu")
		(net "M_I_CPU1_SA_DQ<3>")
	)
	(segment
		(start 156.593794 -203.556362)
		(end 156.745178 -203.708)
		(width 0.14478)
		(layer "In2.Cu")
		(net "M_I_CPU1_SA_DQ<3>")
	)
	(segment
		(start 159.486854 -200.43521)
		(end 159.714946 -200.43521)
		(width 0.14478)
		(layer "In2.Cu")
		(net "M_I_CPU1_SA_DQ<3>")
	)
	(arc
		(start 133.216142 -226.337114)
		(mid 133.39965 -226.29162)
		(end 133.581902 -226.34194)
		(width 0.0889)
		(layer "In2.Cu")
		(net "M_I_CPU1_SA_DQ<3>")
	)
	(arc
		(start 128.516126 -226.337114)
		(mid 128.699634 -226.29162)
		(end 128.881886 -226.34194)
		(width 0.0889)
		(layer "In2.Cu")
		(net "M_I_CPU1_SA_DQ<3>")
	)
	(arc
		(start 129.821686 -226.34194)
		(mid 130.104642 -226.418117)
		(end 130.387598 -226.34194)
		(width 0.0889)
		(layer "In2.Cu")
		(net "M_I_CPU1_SA_DQ<3>")
	)
	(arc
		(start 140.2969 -225.509074)
		(mid 140.475713 -225.306724)
		(end 140.540232 -225.044508)
		(width 0.0889)
		(layer "In2.Cu")
		(net "M_I_CPU1_SA_DQ<3>")
	)
	(arc
		(start 128.881886 -226.34194)
		(mid 129.164842 -226.418117)
		(end 129.447798 -226.34194)
		(width 0.0889)
		(layer "In2.Cu")
		(net "M_I_CPU1_SA_DQ<3>")
	)
	(arc
		(start 141.480794 -223.424496)
		(mid 141.522548 -223.252553)
		(end 141.638528 -223.118934)
		(width 0.0889)
		(layer "In2.Cu")
		(net "M_I_CPU1_SA_DQ<3>")
	)
	(arc
		(start 141.010386 -224.234502)
		(mid 141.051935 -224.06308)
		(end 141.167358 -223.929702)
		(width 0.0889)
		(layer "In2.Cu")
		(net "M_I_CPU1_SA_DQ<3>")
	)
	(arc
		(start 132.641848 -226.34194)
		(mid 132.924804 -226.418117)
		(end 133.20776 -226.34194)
		(width 0.0889)
		(layer "In2.Cu")
		(net "M_I_CPU1_SA_DQ<3>")
	)
	(arc
		(start 131.701794 -226.34194)
		(mid 131.98475 -226.418117)
		(end 132.267706 -226.34194)
		(width 0.0889)
		(layer "In2.Cu")
		(net "M_I_CPU1_SA_DQ<3>")
	)
	(arc
		(start 140.765784 -224.700084)
		(mid 140.945513 -224.497464)
		(end 141.010386 -224.234502)
		(width 0.0889)
		(layer "In2.Cu")
		(net "M_I_CPU1_SA_DQ<3>")
	)
	(arc
		(start 130.76174 -226.34194)
		(mid 131.044696 -226.418117)
		(end 131.327652 -226.34194)
		(width 0.0889)
		(layer "In2.Cu")
		(net "M_I_CPU1_SA_DQ<3>")
	)
	(arc
		(start 134.521702 -226.34194)
		(mid 134.804658 -226.418117)
		(end 135.087614 -226.34194)
		(width 0.0889)
		(layer "In2.Cu")
		(net "M_I_CPU1_SA_DQ<3>")
	)
	(arc
		(start 136.027668 -226.34194)
		(mid 136.209919 -226.29159)
		(end 136.393428 -226.337114)
		(width 0.0889)
		(layer "In2.Cu")
		(net "M_I_CPU1_SA_DQ<3>")
	)
	(arc
		(start 140.070078 -225.854514)
		(mid 140.111333 -225.683543)
		(end 140.226034 -225.550222)
		(width 0.0889)
		(layer "In2.Cu")
		(net "M_I_CPU1_SA_DQ<3>")
	)
	(arc
		(start 135.461756 -226.34194)
		(mid 135.744712 -226.418117)
		(end 136.027668 -226.34194)
		(width 0.0889)
		(layer "In2.Cu")
		(net "M_I_CPU1_SA_DQ<3>")
	)
	(arc
		(start 141.238478 -223.8883)
		(mid 141.416543 -223.686123)
		(end 141.480794 -223.424496)
		(width 0.0889)
		(layer "In2.Cu")
		(net "M_I_CPU1_SA_DQ<3>")
	)
	(arc
		(start 134.147814 -226.34194)
		(mid 134.334758 -226.291685)
		(end 134.521702 -226.34194)
		(width 0.0889)
		(layer "In2.Cu")
		(net "M_I_CPU1_SA_DQ<3>")
	)
	(arc
		(start 137.916158 -226.337114)
		(mid 138.099666 -226.29162)
		(end 138.281918 -226.34194)
		(width 0.0889)
		(layer "In2.Cu")
		(net "M_I_CPU1_SA_DQ<3>")
	)
	(arc
		(start 138.84783 -226.34194)
		(mid 139.034774 -226.291685)
		(end 139.221718 -226.34194)
		(width 0.0889)
		(layer "In2.Cu")
		(net "M_I_CPU1_SA_DQ<3>")
	)
	(arc
		(start 135.087614 -226.34194)
		(mid 135.269865 -226.29159)
		(end 135.453374 -226.337114)
		(width 0.0889)
		(layer "In2.Cu")
		(net "M_I_CPU1_SA_DQ<3>")
	)
	(arc
		(start 139.826746 -226.31908)
		(mid 140.005559 -226.11673)
		(end 140.070078 -225.854514)
		(width 0.0889)
		(layer "In2.Cu")
		(net "M_I_CPU1_SA_DQ<3>")
	)
	(arc
		(start 138.281918 -226.34194)
		(mid 138.564874 -226.418117)
		(end 138.84783 -226.34194)
		(width 0.0889)
		(layer "In2.Cu")
		(net "M_I_CPU1_SA_DQ<3>")
	)
	(arc
		(start 128.005078 -226.37369)
		(mid 128.260143 -226.417041)
		(end 128.507744 -226.34194)
		(width 0.0889)
		(layer "In2.Cu")
		(net "M_I_CPU1_SA_DQ<3>")
	)
	(arc
		(start 141.708378 -223.078294)
		(mid 141.886273 -222.876072)
		(end 141.95044 -222.61449)
		(width 0.0889)
		(layer "In2.Cu")
		(net "M_I_CPU1_SA_DQ<3>")
	)
	(arc
		(start 131.327652 -226.34194)
		(mid 131.509903 -226.29159)
		(end 131.693412 -226.337114)
		(width 0.0889)
		(layer "In2.Cu")
		(net "M_I_CPU1_SA_DQ<3>")
	)
	(arc
		(start 139.221718 -226.34194)
		(mid 139.504674 -226.418117)
		(end 139.78763 -226.34194)
		(width 0.0889)
		(layer "In2.Cu")
		(net "M_I_CPU1_SA_DQ<3>")
	)
	(arc
		(start 130.387598 -226.34194)
		(mid 130.569849 -226.29159)
		(end 130.753358 -226.337114)
		(width 0.0889)
		(layer "In2.Cu")
		(net "M_I_CPU1_SA_DQ<3>")
	)
	(arc
		(start 129.447798 -226.34194)
		(mid 129.634742 -226.291685)
		(end 129.821686 -226.34194)
		(width 0.0889)
		(layer "In2.Cu")
		(net "M_I_CPU1_SA_DQ<3>")
	)
	(arc
		(start 133.581902 -226.34194)
		(mid 133.864858 -226.418117)
		(end 134.147814 -226.34194)
		(width 0.0889)
		(layer "In2.Cu")
		(net "M_I_CPU1_SA_DQ<3>")
	)
	(arc
		(start 136.976104 -226.337114)
		(mid 137.159612 -226.29162)
		(end 137.341864 -226.34194)
		(width 0.0889)
		(layer "In2.Cu")
		(net "M_I_CPU1_SA_DQ<3>")
	)
	(arc
		(start 137.341864 -226.34194)
		(mid 137.62482 -226.418117)
		(end 137.907776 -226.34194)
		(width 0.0889)
		(layer "In2.Cu")
		(net "M_I_CPU1_SA_DQ<3>")
	)
	(arc
		(start 140.540232 -225.044508)
		(mid 140.581487 -224.873537)
		(end 140.696188 -224.740216)
		(width 0.0889)
		(layer "In2.Cu")
		(net "M_I_CPU1_SA_DQ<3>")
	)
	(arc
		(start 136.40181 -226.34194)
		(mid 136.684766 -226.418117)
		(end 136.967722 -226.34194)
		(width 0.0889)
		(layer "In2.Cu")
		(net "M_I_CPU1_SA_DQ<3>")
	)
	(arc
		(start 132.276088 -226.337114)
		(mid 132.459596 -226.29162)
		(end 132.641848 -226.34194)
		(width 0.0889)
		(layer "In2.Cu")
		(net "M_I_CPU1_SA_DQ<3>")
	)
	(segment
		(start 127.287782 -244.750336)
		(end 127.754634 -244.484398)
		(width 0.10668)
		(layer "F.Cu")
		(net "M_I_CPU1_SA_DQ<31>")
	)
	(segment
		(start 165.429184 -234.17149)
		(end 165.642544 -234.259882)
		(width 0.14478)
		(layer "In2.Cu")
		(net "M_I_CPU1_SA_DQ<31>")
	)
	(segment
		(start 167.440102 -233.724704)
		(end 167.734488 -233.724704)
		(width 0.14478)
		(layer "In2.Cu")
		(net "M_I_CPU1_SA_DQ<31>")
	)
	(segment
		(start 141.093444 -244.156992)
		(end 141.101826 -244.161818)
		(width 0.0889)
		(layer "In2.Cu")
		(net "M_I_CPU1_SA_DQ<31>")
	)
	(segment
		(start 178.189382 -233.732324)
		(end 178.461416 -233.46029)
		(width 0.14478)
		(layer "In2.Cu")
		(net "M_I_CPU1_SA_DQ<31>")
	)
	(segment
		(start 161.629598 -236.186218)
		(end 161.858198 -236.186218)
		(width 0.14478)
		(layer "In2.Cu")
		(net "M_I_CPU1_SA_DQ<31>")
	)
	(segment
		(start 162.019742 -235.796074)
		(end 161.681922 -235.458254)
		(width 0.14478)
		(layer "In2.Cu")
		(net "M_I_CPU1_SA_DQ<31>")
	)
	(segment
		(start 163.106608 -234.542076)
		(end 163.31184 -234.542076)
		(width 0.14478)
		(layer "In2.Cu")
		(net "M_I_CPU1_SA_DQ<31>")
	)
	(segment
		(start 136.393428 -244.156992)
		(end 136.40181 -244.161818)
		(width 0.0889)
		(layer "In2.Cu")
		(net "M_I_CPU1_SA_DQ<31>")
	)
	(segment
		(start 176.785016 -233.732324)
		(end 177.071782 -233.732324)
		(width 0.14478)
		(layer "In2.Cu")
		(net "M_I_CPU1_SA_DQ<31>")
	)
	(segment
		(start 161.681922 -235.458254)
		(end 161.681922 -235.229654)
		(width 0.14478)
		(layer "In2.Cu")
		(net "M_I_CPU1_SA_DQ<31>")
	)
	(segment
		(start 173.223428 -234.310428)
		(end 175.276002 -233.46029)
		(width 0.14478)
		(layer "In2.Cu")
		(net "M_I_CPU1_SA_DQ<31>")
	)
	(segment
		(start 128.507744 -244.161818)
		(end 128.516126 -244.156992)
		(width 0.0889)
		(layer "In2.Cu")
		(net "M_I_CPU1_SA_DQ<31>")
	)
	(segment
		(start 175.276002 -233.46029)
		(end 176.512982 -233.46029)
		(width 0.14478)
		(layer "In2.Cu")
		(net "M_I_CPU1_SA_DQ<31>")
	)
	(segment
		(start 161.239454 -236.804962)
		(end 161.239454 -236.576362)
		(width 0.14478)
		(layer "In2.Cu")
		(net "M_I_CPU1_SA_DQ<31>")
	)
	(segment
		(start 154.820112 -243.224304)
		(end 161.239454 -236.804962)
		(width 0.14478)
		(layer "In2.Cu")
		(net "M_I_CPU1_SA_DQ<31>")
	)
	(segment
		(start 130.753358 -244.156992)
		(end 130.76174 -244.161818)
		(width 0.0889)
		(layer "In2.Cu")
		(net "M_I_CPU1_SA_DQ<31>")
	)
	(segment
		(start 163.31184 -234.542076)
		(end 163.543488 -234.310428)
		(width 0.14478)
		(layer "In2.Cu")
		(net "M_I_CPU1_SA_DQ<31>")
	)
	(segment
		(start 161.681922 -235.229654)
		(end 161.843466 -235.06811)
		(width 0.14478)
		(layer "In2.Cu")
		(net "M_I_CPU1_SA_DQ<31>")
	)
	(segment
		(start 162.46221 -234.449366)
		(end 162.623754 -234.287822)
		(width 0.14478)
		(layer "In2.Cu")
		(net "M_I_CPU1_SA_DQ<31>")
	)
	(segment
		(start 165.713156 -234.43057)
		(end 165.909244 -234.511596)
		(width 0.14478)
		(layer "In2.Cu")
		(net "M_I_CPU1_SA_DQ<31>")
	)
	(segment
		(start 165.094158 -234.310428)
		(end 165.429184 -234.17149)
		(width 0.14478)
		(layer "In2.Cu")
		(net "M_I_CPU1_SA_DQ<31>")
	)
	(segment
		(start 160.901634 -236.238542)
		(end 160.901634 -236.009942)
		(width 0.14478)
		(layer "In2.Cu")
		(net "M_I_CPU1_SA_DQ<31>")
	)
	(segment
		(start 162.80003 -235.244386)
		(end 162.80003 -235.015786)
		(width 0.14478)
		(layer "In2.Cu")
		(net "M_I_CPU1_SA_DQ<31>")
	)
	(segment
		(start 177.902616 -233.732324)
		(end 178.189382 -233.732324)
		(width 0.14478)
		(layer "In2.Cu")
		(net "M_I_CPU1_SA_DQ<31>")
	)
	(segment
		(start 127.908812 -244.218968)
		(end 128.005078 -244.193568)
		(width 0.0889)
		(layer "In2.Cu")
		(net "M_I_CPU1_SA_DQ<31>")
	)
	(segment
		(start 165.909244 -234.511596)
		(end 166.148512 -234.412536)
		(width 0.14478)
		(layer "In2.Cu")
		(net "M_I_CPU1_SA_DQ<31>")
	)
	(segment
		(start 161.858198 -236.186218)
		(end 162.019742 -236.024674)
		(width 0.14478)
		(layer "In2.Cu")
		(net "M_I_CPU1_SA_DQ<31>")
	)
	(segment
		(start 147.995386 -243.224304)
		(end 154.820112 -243.224304)
		(width 0.14478)
		(layer "In2.Cu")
		(net "M_I_CPU1_SA_DQ<31>")
	)
	(segment
		(start 160.901634 -236.009942)
		(end 161.063178 -235.848398)
		(width 0.14478)
		(layer "In2.Cu")
		(net "M_I_CPU1_SA_DQ<31>")
	)
	(segment
		(start 132.267706 -244.161818)
		(end 132.276088 -244.156992)
		(width 0.0889)
		(layer "In2.Cu")
		(net "M_I_CPU1_SA_DQ<31>")
	)
	(segment
		(start 161.063178 -235.848398)
		(end 161.291778 -235.848398)
		(width 0.14478)
		(layer "In2.Cu")
		(net "M_I_CPU1_SA_DQ<31>")
	)
	(segment
		(start 178.461416 -233.46029)
		(end 179.091082 -233.46029)
		(width 0.14478)
		(layer "In2.Cu")
		(net "M_I_CPU1_SA_DQ<31>")
	)
	(segment
		(start 146.708368 -244.111272)
		(end 147.595336 -243.224304)
		(width 0.0889)
		(layer "In2.Cu")
		(net "M_I_CPU1_SA_DQ<31>")
	)
	(segment
		(start 177.071782 -233.732324)
		(end 177.343816 -233.46029)
		(width 0.14478)
		(layer "In2.Cu")
		(net "M_I_CPU1_SA_DQ<31>")
	)
	(segment
		(start 162.80003 -235.015786)
		(end 162.46221 -234.677966)
		(width 0.14478)
		(layer "In2.Cu")
		(net "M_I_CPU1_SA_DQ<31>")
	)
	(segment
		(start 137.907776 -244.161818)
		(end 137.916158 -244.156992)
		(width 0.0889)
		(layer "In2.Cu")
		(net "M_I_CPU1_SA_DQ<31>")
	)
	(segment
		(start 171.062396 -234.310428)
		(end 173.223428 -234.310428)
		(width 0.14478)
		(layer "In2.Cu")
		(net "M_I_CPU1_SA_DQ<31>")
	)
	(segment
		(start 140.15339 -244.156992)
		(end 140.161772 -244.161818)
		(width 0.0889)
		(layer "In2.Cu")
		(net "M_I_CPU1_SA_DQ<31>")
	)
	(segment
		(start 161.843466 -235.06811)
		(end 162.072066 -235.06811)
		(width 0.14478)
		(layer "In2.Cu")
		(net "M_I_CPU1_SA_DQ<31>")
	)
	(segment
		(start 166.229538 -234.216448)
		(end 166.158926 -234.046014)
		(width 0.14478)
		(layer "In2.Cu")
		(net "M_I_CPU1_SA_DQ<31>")
	)
	(segment
		(start 131.693412 -244.156992)
		(end 131.701794 -244.161818)
		(width 0.0889)
		(layer "In2.Cu")
		(net "M_I_CPU1_SA_DQ<31>")
	)
	(segment
		(start 162.072066 -235.06811)
		(end 162.409886 -235.40593)
		(width 0.14478)
		(layer "In2.Cu")
		(net "M_I_CPU1_SA_DQ<31>")
	)
	(segment
		(start 135.453374 -244.156992)
		(end 135.461756 -244.161818)
		(width 0.0889)
		(layer "In2.Cu")
		(net "M_I_CPU1_SA_DQ<31>")
	)
	(segment
		(start 167.998902 -233.46029)
		(end 169.658284 -233.46029)
		(width 0.14478)
		(layer "In2.Cu")
		(net "M_I_CPU1_SA_DQ<31>")
	)
	(segment
		(start 170.603926 -233.851958)
		(end 171.062396 -234.310428)
		(width 0.14478)
		(layer "In2.Cu")
		(net "M_I_CPU1_SA_DQ<31>")
	)
	(segment
		(start 166.158926 -234.046014)
		(end 166.32682 -233.640884)
		(width 0.14478)
		(layer "In2.Cu")
		(net "M_I_CPU1_SA_DQ<31>")
	)
	(segment
		(start 169.658284 -233.46029)
		(end 170.603926 -233.851958)
		(width 0.14478)
		(layer "In2.Cu")
		(net "M_I_CPU1_SA_DQ<31>")
	)
	(segment
		(start 165.642544 -234.259882)
		(end 165.713156 -234.43057)
		(width 0.14478)
		(layer "In2.Cu")
		(net "M_I_CPU1_SA_DQ<31>")
	)
	(segment
		(start 162.019742 -236.024674)
		(end 162.019742 -235.796074)
		(width 0.14478)
		(layer "In2.Cu")
		(net "M_I_CPU1_SA_DQ<31>")
	)
	(segment
		(start 162.409886 -235.40593)
		(end 162.638486 -235.40593)
		(width 0.14478)
		(layer "In2.Cu")
		(net "M_I_CPU1_SA_DQ<31>")
	)
	(segment
		(start 162.623754 -234.287822)
		(end 162.852354 -234.287822)
		(width 0.14478)
		(layer "In2.Cu")
		(net "M_I_CPU1_SA_DQ<31>")
	)
	(segment
		(start 162.638486 -235.40593)
		(end 162.80003 -235.244386)
		(width 0.14478)
		(layer "In2.Cu")
		(net "M_I_CPU1_SA_DQ<31>")
	)
	(segment
		(start 161.239454 -236.576362)
		(end 160.901634 -236.238542)
		(width 0.14478)
		(layer "In2.Cu")
		(net "M_I_CPU1_SA_DQ<31>")
	)
	(segment
		(start 162.46221 -234.677966)
		(end 162.46221 -234.449366)
		(width 0.14478)
		(layer "In2.Cu")
		(net "M_I_CPU1_SA_DQ<31>")
	)
	(segment
		(start 133.20776 -244.161818)
		(end 133.216142 -244.156992)
		(width 0.0889)
		(layer "In2.Cu")
		(net "M_I_CPU1_SA_DQ<31>")
	)
	(segment
		(start 147.595336 -243.224304)
		(end 147.995386 -243.224304)
		(width 0.0889)
		(layer "In2.Cu")
		(net "M_I_CPU1_SA_DQ<31>")
	)
	(segment
		(start 166.762938 -233.46029)
		(end 167.175688 -233.46029)
		(width 0.14478)
		(layer "In2.Cu")
		(net "M_I_CPU1_SA_DQ<31>")
	)
	(segment
		(start 161.291778 -235.848398)
		(end 161.629598 -236.186218)
		(width 0.14478)
		(layer "In2.Cu")
		(net "M_I_CPU1_SA_DQ<31>")
	)
	(segment
		(start 141.667738 -244.161818)
		(end 141.67612 -244.156992)
		(width 0.0889)
		(layer "In2.Cu")
		(net "M_I_CPU1_SA_DQ<31>")
	)
	(segment
		(start 177.630582 -233.46029)
		(end 177.902616 -233.732324)
		(width 0.14478)
		(layer "In2.Cu")
		(net "M_I_CPU1_SA_DQ<31>")
	)
	(segment
		(start 127.754634 -244.484398)
		(end 127.908812 -244.218968)
		(width 0.0889)
		(layer "In2.Cu")
		(net "M_I_CPU1_SA_DQ<31>")
	)
	(segment
		(start 176.512982 -233.46029)
		(end 176.785016 -233.732324)
		(width 0.14478)
		(layer "In2.Cu")
		(net "M_I_CPU1_SA_DQ<31>")
	)
	(segment
		(start 166.32682 -233.640884)
		(end 166.762938 -233.46029)
		(width 0.14478)
		(layer "In2.Cu")
		(net "M_I_CPU1_SA_DQ<31>")
	)
	(segment
		(start 136.967722 -244.161818)
		(end 136.976104 -244.156992)
		(width 0.0889)
		(layer "In2.Cu")
		(net "M_I_CPU1_SA_DQ<31>")
	)
	(segment
		(start 167.734488 -233.724704)
		(end 167.998902 -233.46029)
		(width 0.14478)
		(layer "In2.Cu")
		(net "M_I_CPU1_SA_DQ<31>")
	)
	(segment
		(start 177.343816 -233.46029)
		(end 177.630582 -233.46029)
		(width 0.14478)
		(layer "In2.Cu")
		(net "M_I_CPU1_SA_DQ<31>")
	)
	(segment
		(start 166.148512 -234.412536)
		(end 166.229538 -234.216448)
		(width 0.14478)
		(layer "In2.Cu")
		(net "M_I_CPU1_SA_DQ<31>")
	)
	(segment
		(start 179.091082 -233.46029)
		(end 179.516024 -233.885232)
		(width 0.14478)
		(layer "In2.Cu")
		(net "M_I_CPU1_SA_DQ<31>")
	)
	(segment
		(start 163.543488 -234.310428)
		(end 165.094158 -234.310428)
		(width 0.14478)
		(layer "In2.Cu")
		(net "M_I_CPU1_SA_DQ<31>")
	)
	(segment
		(start 162.852354 -234.287822)
		(end 163.106608 -234.542076)
		(width 0.14478)
		(layer "In2.Cu")
		(net "M_I_CPU1_SA_DQ<31>")
	)
	(segment
		(start 167.175688 -233.46029)
		(end 167.440102 -233.724704)
		(width 0.14478)
		(layer "In2.Cu")
		(net "M_I_CPU1_SA_DQ<31>")
	)
	(segment
		(start 145.614898 -244.111272)
		(end 146.708368 -244.111272)
		(width 0.0889)
		(layer "In2.Cu")
		(net "M_I_CPU1_SA_DQ<31>")
	)
	(arc
		(start 141.67612 -244.156992)
		(mid 141.859628 -244.111498)
		(end 142.04188 -244.161818)
		(width 0.0889)
		(layer "In2.Cu")
		(net "M_I_CPU1_SA_DQ<31>")
	)
	(arc
		(start 144.4879 -244.161818)
		(mid 144.674844 -244.111563)
		(end 144.861788 -244.161818)
		(width 0.0889)
		(layer "In2.Cu")
		(net "M_I_CPU1_SA_DQ<31>")
	)
	(arc
		(start 128.881886 -244.161818)
		(mid 129.164842 -244.237995)
		(end 129.447798 -244.161818)
		(width 0.0889)
		(layer "In2.Cu")
		(net "M_I_CPU1_SA_DQ<31>")
	)
	(arc
		(start 130.76174 -244.161818)
		(mid 131.044696 -244.237995)
		(end 131.327652 -244.161818)
		(width 0.0889)
		(layer "In2.Cu")
		(net "M_I_CPU1_SA_DQ<31>")
	)
	(arc
		(start 132.641848 -244.161818)
		(mid 132.924804 -244.237995)
		(end 133.20776 -244.161818)
		(width 0.0889)
		(layer "In2.Cu")
		(net "M_I_CPU1_SA_DQ<31>")
	)
	(arc
		(start 135.087614 -244.161818)
		(mid 135.269865 -244.111468)
		(end 135.453374 -244.156992)
		(width 0.0889)
		(layer "In2.Cu")
		(net "M_I_CPU1_SA_DQ<31>")
	)
	(arc
		(start 142.04188 -244.161818)
		(mid 142.324836 -244.237995)
		(end 142.607792 -244.161818)
		(width 0.0889)
		(layer "In2.Cu")
		(net "M_I_CPU1_SA_DQ<31>")
	)
	(arc
		(start 134.147814 -244.161818)
		(mid 134.334758 -244.111563)
		(end 134.521702 -244.161818)
		(width 0.0889)
		(layer "In2.Cu")
		(net "M_I_CPU1_SA_DQ<31>")
	)
	(arc
		(start 140.727684 -244.161818)
		(mid 140.909935 -244.111468)
		(end 141.093444 -244.156992)
		(width 0.0889)
		(layer "In2.Cu")
		(net "M_I_CPU1_SA_DQ<31>")
	)
	(arc
		(start 140.161772 -244.161818)
		(mid 140.444728 -244.237995)
		(end 140.727684 -244.161818)
		(width 0.0889)
		(layer "In2.Cu")
		(net "M_I_CPU1_SA_DQ<31>")
	)
	(arc
		(start 142.98168 -244.161818)
		(mid 143.264636 -244.237995)
		(end 143.547592 -244.161818)
		(width 0.0889)
		(layer "In2.Cu")
		(net "M_I_CPU1_SA_DQ<31>")
	)
	(arc
		(start 128.516126 -244.156992)
		(mid 128.699634 -244.111498)
		(end 128.881886 -244.161818)
		(width 0.0889)
		(layer "In2.Cu")
		(net "M_I_CPU1_SA_DQ<31>")
	)
	(arc
		(start 139.221718 -244.161818)
		(mid 139.504674 -244.237995)
		(end 139.78763 -244.161818)
		(width 0.0889)
		(layer "In2.Cu")
		(net "M_I_CPU1_SA_DQ<31>")
	)
	(arc
		(start 139.78763 -244.161818)
		(mid 139.969881 -244.111468)
		(end 140.15339 -244.156992)
		(width 0.0889)
		(layer "In2.Cu")
		(net "M_I_CPU1_SA_DQ<31>")
	)
	(arc
		(start 142.607792 -244.161818)
		(mid 142.794736 -244.111563)
		(end 142.98168 -244.161818)
		(width 0.0889)
		(layer "In2.Cu")
		(net "M_I_CPU1_SA_DQ<31>")
	)
	(arc
		(start 137.916158 -244.156992)
		(mid 138.099666 -244.111498)
		(end 138.281918 -244.161818)
		(width 0.0889)
		(layer "In2.Cu")
		(net "M_I_CPU1_SA_DQ<31>")
	)
	(arc
		(start 143.921988 -244.161818)
		(mid 144.204944 -244.237995)
		(end 144.4879 -244.161818)
		(width 0.0889)
		(layer "In2.Cu")
		(net "M_I_CPU1_SA_DQ<31>")
	)
	(arc
		(start 137.341864 -244.161818)
		(mid 137.62482 -244.237995)
		(end 137.907776 -244.161818)
		(width 0.0889)
		(layer "In2.Cu")
		(net "M_I_CPU1_SA_DQ<31>")
	)
	(arc
		(start 138.84783 -244.161818)
		(mid 139.034774 -244.111563)
		(end 139.221718 -244.161818)
		(width 0.0889)
		(layer "In2.Cu")
		(net "M_I_CPU1_SA_DQ<31>")
	)
	(arc
		(start 144.861788 -244.161818)
		(mid 145.144744 -244.237995)
		(end 145.4277 -244.161818)
		(width 0.0889)
		(layer "In2.Cu")
		(net "M_I_CPU1_SA_DQ<31>")
	)
	(arc
		(start 129.447798 -244.161818)
		(mid 129.634742 -244.111563)
		(end 129.821686 -244.161818)
		(width 0.0889)
		(layer "In2.Cu")
		(net "M_I_CPU1_SA_DQ<31>")
	)
	(arc
		(start 138.281918 -244.161818)
		(mid 138.564874 -244.237995)
		(end 138.84783 -244.161818)
		(width 0.0889)
		(layer "In2.Cu")
		(net "M_I_CPU1_SA_DQ<31>")
	)
	(arc
		(start 134.521702 -244.161818)
		(mid 134.804658 -244.237995)
		(end 135.087614 -244.161818)
		(width 0.0889)
		(layer "In2.Cu")
		(net "M_I_CPU1_SA_DQ<31>")
	)
	(arc
		(start 133.581902 -244.161818)
		(mid 133.864858 -244.237995)
		(end 134.147814 -244.161818)
		(width 0.0889)
		(layer "In2.Cu")
		(net "M_I_CPU1_SA_DQ<31>")
	)
	(arc
		(start 132.276088 -244.156992)
		(mid 132.459596 -244.111498)
		(end 132.641848 -244.161818)
		(width 0.0889)
		(layer "In2.Cu")
		(net "M_I_CPU1_SA_DQ<31>")
	)
	(arc
		(start 129.821686 -244.161818)
		(mid 130.104642 -244.237995)
		(end 130.387598 -244.161818)
		(width 0.0889)
		(layer "In2.Cu")
		(net "M_I_CPU1_SA_DQ<31>")
	)
	(arc
		(start 133.216142 -244.156992)
		(mid 133.39965 -244.111498)
		(end 133.581902 -244.161818)
		(width 0.0889)
		(layer "In2.Cu")
		(net "M_I_CPU1_SA_DQ<31>")
	)
	(arc
		(start 145.4277 -244.161818)
		(mid 145.517965 -244.124215)
		(end 145.614898 -244.111272)
		(width 0.0889)
		(layer "In2.Cu")
		(net "M_I_CPU1_SA_DQ<31>")
	)
	(arc
		(start 128.005078 -244.193568)
		(mid 128.260143 -244.236919)
		(end 128.507744 -244.161818)
		(width 0.0889)
		(layer "In2.Cu")
		(net "M_I_CPU1_SA_DQ<31>")
	)
	(arc
		(start 136.976104 -244.156992)
		(mid 137.159612 -244.111498)
		(end 137.341864 -244.161818)
		(width 0.0889)
		(layer "In2.Cu")
		(net "M_I_CPU1_SA_DQ<31>")
	)
	(arc
		(start 136.027668 -244.161818)
		(mid 136.209919 -244.111468)
		(end 136.393428 -244.156992)
		(width 0.0889)
		(layer "In2.Cu")
		(net "M_I_CPU1_SA_DQ<31>")
	)
	(arc
		(start 136.40181 -244.161818)
		(mid 136.684766 -244.237995)
		(end 136.967722 -244.161818)
		(width 0.0889)
		(layer "In2.Cu")
		(net "M_I_CPU1_SA_DQ<31>")
	)
	(arc
		(start 130.387598 -244.161818)
		(mid 130.569849 -244.111468)
		(end 130.753358 -244.156992)
		(width 0.0889)
		(layer "In2.Cu")
		(net "M_I_CPU1_SA_DQ<31>")
	)
	(arc
		(start 141.101826 -244.161818)
		(mid 141.384782 -244.237995)
		(end 141.667738 -244.161818)
		(width 0.0889)
		(layer "In2.Cu")
		(net "M_I_CPU1_SA_DQ<31>")
	)
	(arc
		(start 131.701794 -244.161818)
		(mid 131.98475 -244.237995)
		(end 132.267706 -244.161818)
		(width 0.0889)
		(layer "In2.Cu")
		(net "M_I_CPU1_SA_DQ<31>")
	)
	(arc
		(start 143.547592 -244.161818)
		(mid 143.73479 -244.111436)
		(end 143.921988 -244.161818)
		(width 0.0889)
		(layer "In2.Cu")
		(net "M_I_CPU1_SA_DQ<31>")
	)
	(arc
		(start 135.461756 -244.161818)
		(mid 135.744712 -244.237995)
		(end 136.027668 -244.161818)
		(width 0.0889)
		(layer "In2.Cu")
		(net "M_I_CPU1_SA_DQ<31>")
	)
	(arc
		(start 131.327652 -244.161818)
		(mid 131.509903 -244.111468)
		(end 131.693412 -244.156992)
		(width 0.0889)
		(layer "In2.Cu")
		(net "M_I_CPU1_SA_DQ<31>")
	)
	(segment
		(start 128.69799 -243.94033)
		(end 129.164842 -243.674392)
		(width 0.10668)
		(layer "F.Cu")
		(net "M_I_CPU1_SA_DQ<30>")
	)
	(segment
		(start 158.811468 -237.056422)
		(end 158.811468 -236.827822)
		(width 0.14478)
		(layer "In2.Cu")
		(net "M_I_CPU1_SA_DQ<30>")
	)
	(segment
		(start 133.103366 -243.346986)
		(end 133.111748 -243.351812)
		(width 0.0889)
		(layer "In2.Cu")
		(net "M_I_CPU1_SA_DQ<30>")
	)
	(segment
		(start 158.421324 -237.446566)
		(end 158.751524 -237.776766)
		(width 0.14478)
		(layer "In2.Cu")
		(net "M_I_CPU1_SA_DQ<30>")
	)
	(segment
		(start 147.597368 -242.307364)
		(end 147.969986 -242.307364)
		(width 0.0889)
		(layer "In2.Cu")
		(net "M_I_CPU1_SA_DQ<30>")
	)
	(segment
		(start 157.190948 -239.337342)
		(end 157.419548 -239.337342)
		(width 0.14478)
		(layer "In2.Cu")
		(net "M_I_CPU1_SA_DQ<30>")
	)
	(segment
		(start 158.199836 -238.557054)
		(end 158.36138 -238.39551)
		(width 0.14478)
		(layer "In2.Cu")
		(net "M_I_CPU1_SA_DQ<30>")
	)
	(segment
		(start 177.844704 -231.436164)
		(end 178.077114 -231.436164)
		(width 0.14478)
		(layer "In2.Cu")
		(net "M_I_CPU1_SA_DQ<30>")
	)
	(segment
		(start 157.250892 -238.388398)
		(end 157.412436 -238.226854)
		(width 0.14478)
		(layer "In2.Cu")
		(net "M_I_CPU1_SA_DQ<30>")
	)
	(segment
		(start 158.03118 -237.60811)
		(end 158.192724 -237.446566)
		(width 0.14478)
		(layer "In2.Cu")
		(net "M_I_CPU1_SA_DQ<30>")
	)
	(segment
		(start 174.952152 -232.007664)
		(end 175.549306 -231.760268)
		(width 0.14478)
		(layer "In2.Cu")
		(net "M_I_CPU1_SA_DQ<30>")
	)
	(segment
		(start 157.581092 -239.175798)
		(end 157.581092 -238.947198)
		(width 0.14478)
		(layer "In2.Cu")
		(net "M_I_CPU1_SA_DQ<30>")
	)
	(segment
		(start 169.914316 -231.760268)
		(end 170.764454 -232.610406)
		(width 0.14478)
		(layer "In2.Cu")
		(net "M_I_CPU1_SA_DQ<30>")
	)
	(segment
		(start 159.531812 -236.996478)
		(end 159.760412 -236.996478)
		(width 0.14478)
		(layer "In2.Cu")
		(net "M_I_CPU1_SA_DQ<30>")
	)
	(segment
		(start 157.971236 -238.557054)
		(end 158.199836 -238.557054)
		(width 0.14478)
		(layer "In2.Cu")
		(net "M_I_CPU1_SA_DQ<30>")
	)
	(segment
		(start 179.091082 -231.760268)
		(end 179.516024 -232.18521)
		(width 0.14478)
		(layer "In2.Cu")
		(net "M_I_CPU1_SA_DQ<30>")
	)
	(segment
		(start 156.860748 -239.007142)
		(end 157.190948 -239.337342)
		(width 0.14478)
		(layer "In2.Cu")
		(net "M_I_CPU1_SA_DQ<30>")
	)
	(segment
		(start 147.132548 -242.772184)
		(end 147.597368 -242.307364)
		(width 0.0889)
		(layer "In2.Cu")
		(net "M_I_CPU1_SA_DQ<30>")
	)
	(segment
		(start 156.800804 -239.956086)
		(end 156.800804 -239.727486)
		(width 0.14478)
		(layer "In2.Cu")
		(net "M_I_CPU1_SA_DQ<30>")
	)
	(segment
		(start 129.318766 -243.408962)
		(end 129.414778 -243.383562)
		(width 0.0889)
		(layer "In2.Cu")
		(net "M_I_CPU1_SA_DQ<30>")
	)
	(segment
		(start 156.632148 -239.007142)
		(end 156.860748 -239.007142)
		(width 0.14478)
		(layer "In2.Cu")
		(net "M_I_CPU1_SA_DQ<30>")
	)
	(segment
		(start 146.596608 -242.772184)
		(end 147.132548 -242.772184)
		(width 0.0889)
		(layer "In2.Cu")
		(net "M_I_CPU1_SA_DQ<30>")
	)
	(segment
		(start 173.496732 -232.610406)
		(end 174.136558 -232.34523)
		(width 0.14478)
		(layer "In2.Cu")
		(net "M_I_CPU1_SA_DQ<30>")
	)
	(segment
		(start 158.811468 -236.827822)
		(end 158.973012 -236.666278)
		(width 0.14478)
		(layer "In2.Cu")
		(net "M_I_CPU1_SA_DQ<30>")
	)
	(segment
		(start 156.470604 -239.168686)
		(end 156.632148 -239.007142)
		(width 0.14478)
		(layer "In2.Cu")
		(net "M_I_CPU1_SA_DQ<30>")
	)
	(segment
		(start 156.470604 -239.397286)
		(end 156.470604 -239.168686)
		(width 0.14478)
		(layer "In2.Cu")
		(net "M_I_CPU1_SA_DQ<30>")
	)
	(segment
		(start 177.5206 -231.760268)
		(end 177.844704 -231.436164)
		(width 0.14478)
		(layer "In2.Cu")
		(net "M_I_CPU1_SA_DQ<30>")
	)
	(segment
		(start 163.028884 -232.610406)
		(end 165.753796 -232.610406)
		(width 0.14478)
		(layer "In2.Cu")
		(net "M_I_CPU1_SA_DQ<30>")
	)
	(segment
		(start 140.257784 -243.351812)
		(end 140.266166 -243.346986)
		(width 0.0889)
		(layer "In2.Cu")
		(net "M_I_CPU1_SA_DQ<30>")
	)
	(segment
		(start 159.921956 -236.834934)
		(end 159.921956 -236.606334)
		(width 0.14478)
		(layer "In2.Cu")
		(net "M_I_CPU1_SA_DQ<30>")
	)
	(segment
		(start 158.751524 -237.776766)
		(end 158.980124 -237.776766)
		(width 0.14478)
		(layer "In2.Cu")
		(net "M_I_CPU1_SA_DQ<30>")
	)
	(segment
		(start 174.524416 -231.8258)
		(end 174.952152 -232.007664)
		(width 0.14478)
		(layer "In2.Cu")
		(net "M_I_CPU1_SA_DQ<30>")
	)
	(segment
		(start 158.36138 -238.39551)
		(end 158.36138 -238.16691)
		(width 0.14478)
		(layer "In2.Cu")
		(net "M_I_CPU1_SA_DQ<30>")
	)
	(segment
		(start 143.077692 -243.351812)
		(end 143.086074 -243.346986)
		(width 0.0889)
		(layer "In2.Cu")
		(net "M_I_CPU1_SA_DQ<30>")
	)
	(segment
		(start 159.921956 -236.606334)
		(end 159.591756 -236.276134)
		(width 0.14478)
		(layer "In2.Cu")
		(net "M_I_CPU1_SA_DQ<30>")
	)
	(segment
		(start 167.806878 -231.760268)
		(end 169.914316 -231.760268)
		(width 0.14478)
		(layer "In2.Cu")
		(net "M_I_CPU1_SA_DQ<30>")
	)
	(segment
		(start 158.03118 -237.83671)
		(end 158.03118 -237.60811)
		(width 0.14478)
		(layer "In2.Cu")
		(net "M_I_CPU1_SA_DQ<30>")
	)
	(segment
		(start 156.800804 -239.727486)
		(end 156.470604 -239.397286)
		(width 0.14478)
		(layer "In2.Cu")
		(net "M_I_CPU1_SA_DQ<30>")
	)
	(segment
		(start 147.969986 -242.307364)
		(end 154.449526 -242.307364)
		(width 0.14478)
		(layer "In2.Cu")
		(net "M_I_CPU1_SA_DQ<30>")
	)
	(segment
		(start 170.764454 -232.610406)
		(end 173.496732 -232.610406)
		(width 0.14478)
		(layer "In2.Cu")
		(net "M_I_CPU1_SA_DQ<30>")
	)
	(segment
		(start 157.581092 -238.947198)
		(end 157.250892 -238.616998)
		(width 0.14478)
		(layer "In2.Cu")
		(net "M_I_CPU1_SA_DQ<30>")
	)
	(segment
		(start 129.917698 -243.351812)
		(end 129.92608 -243.346986)
		(width 0.0889)
		(layer "In2.Cu")
		(net "M_I_CPU1_SA_DQ<30>")
	)
	(segment
		(start 137.803382 -243.346986)
		(end 137.811764 -243.351812)
		(width 0.0889)
		(layer "In2.Cu")
		(net "M_I_CPU1_SA_DQ<30>")
	)
	(segment
		(start 157.250892 -238.616998)
		(end 157.250892 -238.388398)
		(width 0.14478)
		(layer "In2.Cu")
		(net "M_I_CPU1_SA_DQ<30>")
	)
	(segment
		(start 157.419548 -239.337342)
		(end 157.581092 -239.175798)
		(width 0.14478)
		(layer "In2.Cu")
		(net "M_I_CPU1_SA_DQ<30>")
	)
	(segment
		(start 159.760412 -236.996478)
		(end 159.921956 -236.834934)
		(width 0.14478)
		(layer "In2.Cu")
		(net "M_I_CPU1_SA_DQ<30>")
	)
	(segment
		(start 158.973012 -236.666278)
		(end 159.201612 -236.666278)
		(width 0.14478)
		(layer "In2.Cu")
		(net "M_I_CPU1_SA_DQ<30>")
	)
	(segment
		(start 142.503398 -243.346986)
		(end 142.51178 -243.351812)
		(width 0.0889)
		(layer "In2.Cu")
		(net "M_I_CPU1_SA_DQ<30>")
	)
	(segment
		(start 135.557768 -243.351812)
		(end 135.56615 -243.346986)
		(width 0.0889)
		(layer "In2.Cu")
		(net "M_I_CPU1_SA_DQ<30>")
	)
	(segment
		(start 144.39138 -243.351812)
		(end 144.401794 -243.357908)
		(width 0.0889)
		(layer "In2.Cu")
		(net "M_I_CPU1_SA_DQ<30>")
	)
	(segment
		(start 175.549306 -231.760268)
		(end 177.5206 -231.760268)
		(width 0.14478)
		(layer "In2.Cu")
		(net "M_I_CPU1_SA_DQ<30>")
	)
	(segment
		(start 139.31773 -243.351812)
		(end 139.326112 -243.346986)
		(width 0.0889)
		(layer "In2.Cu")
		(net "M_I_CPU1_SA_DQ<30>")
	)
	(segment
		(start 146.067526 -243.301266)
		(end 146.596608 -242.772184)
		(width 0.0889)
		(layer "In2.Cu")
		(net "M_I_CPU1_SA_DQ<30>")
	)
	(segment
		(start 157.641036 -238.226854)
		(end 157.971236 -238.557054)
		(width 0.14478)
		(layer "In2.Cu")
		(net "M_I_CPU1_SA_DQ<30>")
	)
	(segment
		(start 154.449526 -242.307364)
		(end 156.800804 -239.956086)
		(width 0.14478)
		(layer "In2.Cu")
		(net "M_I_CPU1_SA_DQ<30>")
	)
	(segment
		(start 158.192724 -237.446566)
		(end 158.421324 -237.446566)
		(width 0.14478)
		(layer "In2.Cu")
		(net "M_I_CPU1_SA_DQ<30>")
	)
	(segment
		(start 144.007078 -243.357908)
		(end 144.017492 -243.351812)
		(width 0.0889)
		(layer "In2.Cu")
		(net "M_I_CPU1_SA_DQ<30>")
	)
	(segment
		(start 138.743436 -243.346986)
		(end 138.751818 -243.351812)
		(width 0.0889)
		(layer "In2.Cu")
		(net "M_I_CPU1_SA_DQ<30>")
	)
	(segment
		(start 134.04342 -243.346986)
		(end 134.051802 -243.351812)
		(width 0.0889)
		(layer "In2.Cu")
		(net "M_I_CPU1_SA_DQ<30>")
	)
	(segment
		(start 159.201612 -236.666278)
		(end 159.531812 -236.996478)
		(width 0.14478)
		(layer "In2.Cu")
		(net "M_I_CPU1_SA_DQ<30>")
	)
	(segment
		(start 178.401218 -231.760268)
		(end 179.091082 -231.760268)
		(width 0.14478)
		(layer "In2.Cu")
		(net "M_I_CPU1_SA_DQ<30>")
	)
	(segment
		(start 130.857752 -243.351812)
		(end 130.866134 -243.346986)
		(width 0.0889)
		(layer "In2.Cu")
		(net "M_I_CPU1_SA_DQ<30>")
	)
	(segment
		(start 174.136558 -232.34523)
		(end 174.311056 -231.914446)
		(width 0.14478)
		(layer "In2.Cu")
		(net "M_I_CPU1_SA_DQ<30>")
	)
	(segment
		(start 145.144744 -243.301266)
		(end 146.067526 -243.301266)
		(width 0.0889)
		(layer "In2.Cu")
		(net "M_I_CPU1_SA_DQ<30>")
	)
	(segment
		(start 159.141668 -237.386622)
		(end 158.811468 -237.056422)
		(width 0.14478)
		(layer "In2.Cu")
		(net "M_I_CPU1_SA_DQ<30>")
	)
	(segment
		(start 159.591756 -236.047534)
		(end 163.028884 -232.610406)
		(width 0.14478)
		(layer "In2.Cu")
		(net "M_I_CPU1_SA_DQ<30>")
	)
	(segment
		(start 178.077114 -231.436164)
		(end 178.401218 -231.760268)
		(width 0.14478)
		(layer "In2.Cu")
		(net "M_I_CPU1_SA_DQ<30>")
	)
	(segment
		(start 165.753796 -232.610406)
		(end 167.806878 -231.760268)
		(width 0.14478)
		(layer "In2.Cu")
		(net "M_I_CPU1_SA_DQ<30>")
	)
	(segment
		(start 134.617714 -243.351812)
		(end 134.626096 -243.346986)
		(width 0.0889)
		(layer "In2.Cu")
		(net "M_I_CPU1_SA_DQ<30>")
	)
	(segment
		(start 158.36138 -238.16691)
		(end 158.03118 -237.83671)
		(width 0.14478)
		(layer "In2.Cu")
		(net "M_I_CPU1_SA_DQ<30>")
	)
	(segment
		(start 157.412436 -238.226854)
		(end 157.641036 -238.226854)
		(width 0.14478)
		(layer "In2.Cu")
		(net "M_I_CPU1_SA_DQ<30>")
	)
	(segment
		(start 159.591756 -236.276134)
		(end 159.591756 -236.047534)
		(width 0.14478)
		(layer "In2.Cu")
		(net "M_I_CPU1_SA_DQ<30>")
	)
	(segment
		(start 129.164842 -243.674392)
		(end 129.318766 -243.408962)
		(width 0.0889)
		(layer "In2.Cu")
		(net "M_I_CPU1_SA_DQ<30>")
	)
	(segment
		(start 158.980124 -237.776766)
		(end 159.141668 -237.615222)
		(width 0.14478)
		(layer "In2.Cu")
		(net "M_I_CPU1_SA_DQ<30>")
	)
	(segment
		(start 159.141668 -237.615222)
		(end 159.141668 -237.386622)
		(width 0.14478)
		(layer "In2.Cu")
		(net "M_I_CPU1_SA_DQ<30>")
	)
	(segment
		(start 174.311056 -231.914446)
		(end 174.524416 -231.8258)
		(width 0.14478)
		(layer "In2.Cu")
		(net "M_I_CPU1_SA_DQ<30>")
	)
	(arc
		(start 137.811764 -243.351812)
		(mid 138.09472 -243.427989)
		(end 138.377676 -243.351812)
		(width 0.0889)
		(layer "In2.Cu")
		(net "M_I_CPU1_SA_DQ<30>")
	)
	(arc
		(start 132.737606 -243.351812)
		(mid 132.919857 -243.301462)
		(end 133.103366 -243.346986)
		(width 0.0889)
		(layer "In2.Cu")
		(net "M_I_CPU1_SA_DQ<30>")
	)
	(arc
		(start 142.51178 -243.351812)
		(mid 142.794736 -243.427989)
		(end 143.077692 -243.351812)
		(width 0.0889)
		(layer "In2.Cu")
		(net "M_I_CPU1_SA_DQ<30>")
	)
	(arc
		(start 143.086074 -243.346986)
		(mid 143.269582 -243.301492)
		(end 143.451834 -243.351812)
		(width 0.0889)
		(layer "In2.Cu")
		(net "M_I_CPU1_SA_DQ<30>")
	)
	(arc
		(start 139.691872 -243.351812)
		(mid 139.974828 -243.427989)
		(end 140.257784 -243.351812)
		(width 0.0889)
		(layer "In2.Cu")
		(net "M_I_CPU1_SA_DQ<30>")
	)
	(arc
		(start 134.991856 -243.351812)
		(mid 135.274812 -243.427989)
		(end 135.557768 -243.351812)
		(width 0.0889)
		(layer "In2.Cu")
		(net "M_I_CPU1_SA_DQ<30>")
	)
	(arc
		(start 131.231894 -243.351812)
		(mid 131.51485 -243.427989)
		(end 131.797806 -243.351812)
		(width 0.0889)
		(layer "In2.Cu")
		(net "M_I_CPU1_SA_DQ<30>")
	)
	(arc
		(start 130.29184 -243.351812)
		(mid 130.574796 -243.427989)
		(end 130.857752 -243.351812)
		(width 0.0889)
		(layer "In2.Cu")
		(net "M_I_CPU1_SA_DQ<30>")
	)
	(arc
		(start 132.171694 -243.351812)
		(mid 132.45465 -243.427989)
		(end 132.737606 -243.351812)
		(width 0.0889)
		(layer "In2.Cu")
		(net "M_I_CPU1_SA_DQ<30>")
	)
	(arc
		(start 144.957546 -243.351812)
		(mid 145.047806 -243.314184)
		(end 145.144744 -243.301266)
		(width 0.0889)
		(layer "In2.Cu")
		(net "M_I_CPU1_SA_DQ<30>")
	)
	(arc
		(start 141.197838 -243.351812)
		(mid 141.384782 -243.301557)
		(end 141.571726 -243.351812)
		(width 0.0889)
		(layer "In2.Cu")
		(net "M_I_CPU1_SA_DQ<30>")
	)
	(arc
		(start 139.326112 -243.346986)
		(mid 139.50962 -243.301492)
		(end 139.691872 -243.351812)
		(width 0.0889)
		(layer "In2.Cu")
		(net "M_I_CPU1_SA_DQ<30>")
	)
	(arc
		(start 134.051802 -243.351812)
		(mid 134.334758 -243.427989)
		(end 134.617714 -243.351812)
		(width 0.0889)
		(layer "In2.Cu")
		(net "M_I_CPU1_SA_DQ<30>")
	)
	(arc
		(start 138.751818 -243.351812)
		(mid 139.034774 -243.427989)
		(end 139.31773 -243.351812)
		(width 0.0889)
		(layer "In2.Cu")
		(net "M_I_CPU1_SA_DQ<30>")
	)
	(arc
		(start 142.137638 -243.351812)
		(mid 142.319889 -243.301462)
		(end 142.503398 -243.346986)
		(width 0.0889)
		(layer "In2.Cu")
		(net "M_I_CPU1_SA_DQ<30>")
	)
	(arc
		(start 133.111748 -243.351812)
		(mid 133.394704 -243.427989)
		(end 133.67766 -243.351812)
		(width 0.0889)
		(layer "In2.Cu")
		(net "M_I_CPU1_SA_DQ<30>")
	)
	(arc
		(start 131.797806 -243.351812)
		(mid 131.98475 -243.301557)
		(end 132.171694 -243.351812)
		(width 0.0889)
		(layer "In2.Cu")
		(net "M_I_CPU1_SA_DQ<30>")
	)
	(arc
		(start 140.266166 -243.346986)
		(mid 140.449674 -243.301492)
		(end 140.631926 -243.351812)
		(width 0.0889)
		(layer "In2.Cu")
		(net "M_I_CPU1_SA_DQ<30>")
	)
	(arc
		(start 144.401794 -243.357908)
		(mid 144.68048 -243.428128)
		(end 144.957546 -243.351812)
		(width 0.0889)
		(layer "In2.Cu")
		(net "M_I_CPU1_SA_DQ<30>")
	)
	(arc
		(start 134.626096 -243.346986)
		(mid 134.809604 -243.301492)
		(end 134.991856 -243.351812)
		(width 0.0889)
		(layer "In2.Cu")
		(net "M_I_CPU1_SA_DQ<30>")
	)
	(arc
		(start 136.497822 -243.351812)
		(mid 136.684766 -243.301557)
		(end 136.87171 -243.351812)
		(width 0.0889)
		(layer "In2.Cu")
		(net "M_I_CPU1_SA_DQ<30>")
	)
	(arc
		(start 133.67766 -243.351812)
		(mid 133.859911 -243.301462)
		(end 134.04342 -243.346986)
		(width 0.0889)
		(layer "In2.Cu")
		(net "M_I_CPU1_SA_DQ<30>")
	)
	(arc
		(start 143.451834 -243.351812)
		(mid 143.728647 -243.427955)
		(end 144.007078 -243.357908)
		(width 0.0889)
		(layer "In2.Cu")
		(net "M_I_CPU1_SA_DQ<30>")
	)
	(arc
		(start 129.92608 -243.346986)
		(mid 130.109588 -243.301492)
		(end 130.29184 -243.351812)
		(width 0.0889)
		(layer "In2.Cu")
		(net "M_I_CPU1_SA_DQ<30>")
	)
	(arc
		(start 130.866134 -243.346986)
		(mid 131.049642 -243.301492)
		(end 131.231894 -243.351812)
		(width 0.0889)
		(layer "In2.Cu")
		(net "M_I_CPU1_SA_DQ<30>")
	)
	(arc
		(start 135.93191 -243.351812)
		(mid 136.214866 -243.427989)
		(end 136.497822 -243.351812)
		(width 0.0889)
		(layer "In2.Cu")
		(net "M_I_CPU1_SA_DQ<30>")
	)
	(arc
		(start 136.87171 -243.351812)
		(mid 137.154666 -243.427989)
		(end 137.437622 -243.351812)
		(width 0.0889)
		(layer "In2.Cu")
		(net "M_I_CPU1_SA_DQ<30>")
	)
	(arc
		(start 135.56615 -243.346986)
		(mid 135.749658 -243.301492)
		(end 135.93191 -243.351812)
		(width 0.0889)
		(layer "In2.Cu")
		(net "M_I_CPU1_SA_DQ<30>")
	)
	(arc
		(start 138.377676 -243.351812)
		(mid 138.559927 -243.301462)
		(end 138.743436 -243.346986)
		(width 0.0889)
		(layer "In2.Cu")
		(net "M_I_CPU1_SA_DQ<30>")
	)
	(arc
		(start 137.437622 -243.351812)
		(mid 137.619873 -243.301462)
		(end 137.803382 -243.346986)
		(width 0.0889)
		(layer "In2.Cu")
		(net "M_I_CPU1_SA_DQ<30>")
	)
	(arc
		(start 140.631926 -243.351812)
		(mid 140.914882 -243.427989)
		(end 141.197838 -243.351812)
		(width 0.0889)
		(layer "In2.Cu")
		(net "M_I_CPU1_SA_DQ<30>")
	)
	(arc
		(start 129.414778 -243.383562)
		(mid 129.669986 -243.427039)
		(end 129.917698 -243.351812)
		(width 0.0889)
		(layer "In2.Cu")
		(net "M_I_CPU1_SA_DQ<30>")
	)
	(arc
		(start 144.017492 -243.351812)
		(mid 144.204436 -243.301557)
		(end 144.39138 -243.351812)
		(width 0.0889)
		(layer "In2.Cu")
		(net "M_I_CPU1_SA_DQ<30>")
	)
	(arc
		(start 141.571726 -243.351812)
		(mid 141.854682 -243.427989)
		(end 142.137638 -243.351812)
		(width 0.0889)
		(layer "In2.Cu")
		(net "M_I_CPU1_SA_DQ<30>")
	)
	(segment
		(start 128.69799 -226.120452)
		(end 129.164842 -225.854514)
		(width 0.10668)
		(layer "F.Cu")
		(net "M_I_CPU1_SA_DQ<2>")
	)
	(segment
		(start 139.75715 -224.739708)
		(end 139.78763 -224.721928)
		(width 0.0889)
		(layer "In2.Cu")
		(net "M_I_CPU1_SA_DQ<2>")
	)
	(segment
		(start 177.760376 -197.527926)
		(end 177.760376 -197.993)
		(width 0.14478)
		(layer "In2.Cu")
		(net "M_I_CPU1_SA_DQ<2>")
	)
	(segment
		(start 178.710082 -197.379336)
		(end 179.516024 -198.185278)
		(width 0.14478)
		(layer "In2.Cu")
		(net "M_I_CPU1_SA_DQ<2>")
	)
	(segment
		(start 140.22578 -223.93021)
		(end 140.25753 -223.911922)
		(width 0.0889)
		(layer "In2.Cu")
		(net "M_I_CPU1_SA_DQ<2>")
	)
	(segment
		(start 137.804398 -225.527616)
		(end 137.811764 -225.531934)
		(width 0.0889)
		(layer "In2.Cu")
		(net "M_I_CPU1_SA_DQ<2>")
	)
	(segment
		(start 178.316636 -197.993)
		(end 178.316636 -197.54215)
		(width 0.14478)
		(layer "In2.Cu")
		(net "M_I_CPU1_SA_DQ<2>")
	)
	(segment
		(start 145.351246 -215.16213)
		(end 145.579846 -215.16213)
		(width 0.14478)
		(layer "In2.Cu")
		(net "M_I_CPU1_SA_DQ<2>")
	)
	(segment
		(start 160.03905 -198.610474)
		(end 166.299134 -198.610474)
		(width 0.14478)
		(layer "In2.Cu")
		(net "M_I_CPU1_SA_DQ<2>")
	)
	(segment
		(start 144.450816 -215.822276)
		(end 144.570958 -215.942418)
		(width 0.14478)
		(layer "In2.Cu")
		(net "M_I_CPU1_SA_DQ<2>")
	)
	(segment
		(start 141.63167 -221.174564)
		(end 141.63167 -218.412822)
		(width 0.14478)
		(layer "In2.Cu")
		(net "M_I_CPU1_SA_DQ<2>")
	)
	(segment
		(start 144.961102 -215.552274)
		(end 144.84096 -215.432132)
		(width 0.14478)
		(layer "In2.Cu")
		(net "M_I_CPU1_SA_DQ<2>")
	)
	(segment
		(start 176.81067 -198.155814)
		(end 177.041302 -198.155814)
		(width 0.14478)
		(layer "In2.Cu")
		(net "M_I_CPU1_SA_DQ<2>")
	)
	(segment
		(start 177.041302 -198.155814)
		(end 177.204116 -197.993)
		(width 0.14478)
		(layer "In2.Cu")
		(net "M_I_CPU1_SA_DQ<2>")
	)
	(segment
		(start 142.109952 -218.16314)
		(end 142.230094 -218.283282)
		(width 0.14478)
		(layer "In2.Cu")
		(net "M_I_CPU1_SA_DQ<2>")
	)
	(segment
		(start 139.78763 -224.721928)
		(end 139.823952 -224.700846)
		(width 0.0889)
		(layer "In2.Cu")
		(net "M_I_CPU1_SA_DQ<2>")
	)
	(segment
		(start 144.060672 -215.98382)
		(end 144.222216 -215.822276)
		(width 0.14478)
		(layer "In2.Cu")
		(net "M_I_CPU1_SA_DQ<2>")
	)
	(segment
		(start 145.621248 -214.651844)
		(end 145.621248 -214.423244)
		(width 0.14478)
		(layer "In2.Cu")
		(net "M_I_CPU1_SA_DQ<2>")
	)
	(segment
		(start 142.500096 -217.544396)
		(end 142.66164 -217.382852)
		(width 0.14478)
		(layer "In2.Cu")
		(net "M_I_CPU1_SA_DQ<2>")
	)
	(segment
		(start 143.400526 -217.34145)
		(end 143.400526 -217.11285)
		(width 0.14478)
		(layer "In2.Cu")
		(net "M_I_CPU1_SA_DQ<2>")
	)
	(segment
		(start 141.63167 -218.412822)
		(end 141.881352 -218.16314)
		(width 0.14478)
		(layer "In2.Cu")
		(net "M_I_CPU1_SA_DQ<2>")
	)
	(segment
		(start 138.743436 -225.527108)
		(end 138.751818 -225.531934)
		(width 0.0889)
		(layer "In2.Cu")
		(net "M_I_CPU1_SA_DQ<2>")
	)
	(segment
		(start 177.92319 -198.155814)
		(end 178.153822 -198.155814)
		(width 0.14478)
		(layer "In2.Cu")
		(net "M_I_CPU1_SA_DQ<2>")
	)
	(segment
		(start 174.490634 -197.760336)
		(end 176.415192 -197.760336)
		(width 0.14478)
		(layer "In2.Cu")
		(net "M_I_CPU1_SA_DQ<2>")
	)
	(segment
		(start 144.180814 -216.561162)
		(end 144.180814 -216.332562)
		(width 0.14478)
		(layer "In2.Cu")
		(net "M_I_CPU1_SA_DQ<2>")
	)
	(segment
		(start 145.74139 -215.000586)
		(end 145.74139 -214.771986)
		(width 0.14478)
		(layer "In2.Cu")
		(net "M_I_CPU1_SA_DQ<2>")
	)
	(segment
		(start 129.917698 -225.531934)
		(end 129.92608 -225.527108)
		(width 0.0889)
		(layer "In2.Cu")
		(net "M_I_CPU1_SA_DQ<2>")
	)
	(segment
		(start 177.36693 -197.365112)
		(end 177.597562 -197.365112)
		(width 0.14478)
		(layer "In2.Cu")
		(net "M_I_CPU1_SA_DQ<2>")
	)
	(segment
		(start 143.280384 -216.764108)
		(end 143.441928 -216.602564)
		(width 0.14478)
		(layer "In2.Cu")
		(net "M_I_CPU1_SA_DQ<2>")
	)
	(segment
		(start 142.230094 -218.283282)
		(end 142.458694 -218.283282)
		(width 0.14478)
		(layer "In2.Cu")
		(net "M_I_CPU1_SA_DQ<2>")
	)
	(segment
		(start 177.597562 -197.365112)
		(end 177.760376 -197.527926)
		(width 0.14478)
		(layer "In2.Cu")
		(net "M_I_CPU1_SA_DQ<2>")
	)
	(segment
		(start 144.060672 -216.21242)
		(end 144.060672 -215.98382)
		(width 0.14478)
		(layer "In2.Cu")
		(net "M_I_CPU1_SA_DQ<2>")
	)
	(segment
		(start 140.72743 -223.101916)
		(end 140.767816 -223.078294)
		(width 0.0889)
		(layer "In2.Cu")
		(net "M_I_CPU1_SA_DQ<2>")
	)
	(segment
		(start 144.84096 -215.203532)
		(end 145.002504 -215.041988)
		(width 0.14478)
		(layer "In2.Cu")
		(net "M_I_CPU1_SA_DQ<2>")
	)
	(segment
		(start 173.640496 -198.610474)
		(end 174.490634 -197.760336)
		(width 0.14478)
		(layer "In2.Cu")
		(net "M_I_CPU1_SA_DQ<2>")
	)
	(segment
		(start 143.010382 -217.502994)
		(end 143.238982 -217.502994)
		(width 0.14478)
		(layer "In2.Cu")
		(net "M_I_CPU1_SA_DQ<2>")
	)
	(segment
		(start 144.799558 -215.942418)
		(end 144.961102 -215.780874)
		(width 0.14478)
		(layer "In2.Cu")
		(net "M_I_CPU1_SA_DQ<2>")
	)
	(segment
		(start 144.180814 -216.332562)
		(end 144.060672 -216.21242)
		(width 0.14478)
		(layer "In2.Cu")
		(net "M_I_CPU1_SA_DQ<2>")
	)
	(segment
		(start 129.318766 -225.589084)
		(end 129.414778 -225.563684)
		(width 0.0889)
		(layer "In2.Cu")
		(net "M_I_CPU1_SA_DQ<2>")
	)
	(segment
		(start 177.760376 -197.993)
		(end 177.92319 -198.155814)
		(width 0.14478)
		(layer "In2.Cu")
		(net "M_I_CPU1_SA_DQ<2>")
	)
	(segment
		(start 145.002504 -215.041988)
		(end 145.231104 -215.041988)
		(width 0.14478)
		(layer "In2.Cu")
		(net "M_I_CPU1_SA_DQ<2>")
	)
	(segment
		(start 143.441928 -216.602564)
		(end 143.670528 -216.602564)
		(width 0.14478)
		(layer "In2.Cu")
		(net "M_I_CPU1_SA_DQ<2>")
	)
	(segment
		(start 143.670528 -216.602564)
		(end 143.79067 -216.722706)
		(width 0.14478)
		(layer "In2.Cu")
		(net "M_I_CPU1_SA_DQ<2>")
	)
	(segment
		(start 144.570958 -215.942418)
		(end 144.799558 -215.942418)
		(width 0.14478)
		(layer "In2.Cu")
		(net "M_I_CPU1_SA_DQ<2>")
	)
	(segment
		(start 139.31773 -225.531934)
		(end 139.356846 -225.509074)
		(width 0.0889)
		(layer "In2.Cu")
		(net "M_I_CPU1_SA_DQ<2>")
	)
	(segment
		(start 178.316636 -197.54215)
		(end 178.47945 -197.379336)
		(width 0.14478)
		(layer "In2.Cu")
		(net "M_I_CPU1_SA_DQ<2>")
	)
	(segment
		(start 178.47945 -197.379336)
		(end 178.710082 -197.379336)
		(width 0.14478)
		(layer "In2.Cu")
		(net "M_I_CPU1_SA_DQ<2>")
	)
	(segment
		(start 143.280384 -216.992708)
		(end 143.280384 -216.764108)
		(width 0.14478)
		(layer "In2.Cu")
		(net "M_I_CPU1_SA_DQ<2>")
	)
	(segment
		(start 129.164842 -225.854514)
		(end 129.318766 -225.589084)
		(width 0.0889)
		(layer "In2.Cu")
		(net "M_I_CPU1_SA_DQ<2>")
	)
	(segment
		(start 145.579846 -215.16213)
		(end 145.74139 -215.000586)
		(width 0.14478)
		(layer "In2.Cu")
		(net "M_I_CPU1_SA_DQ<2>")
	)
	(segment
		(start 137.803382 -225.527108)
		(end 137.804398 -225.527616)
		(width 0.0889)
		(layer "In2.Cu")
		(net "M_I_CPU1_SA_DQ<2>")
	)
	(segment
		(start 141.479524 -221.804484)
		(end 141.63167 -221.174564)
		(width 0.0889)
		(layer "In2.Cu")
		(net "M_I_CPU1_SA_DQ<2>")
	)
	(segment
		(start 142.66164 -217.382852)
		(end 142.89024 -217.382852)
		(width 0.14478)
		(layer "In2.Cu")
		(net "M_I_CPU1_SA_DQ<2>")
	)
	(segment
		(start 144.222216 -215.822276)
		(end 144.450816 -215.822276)
		(width 0.14478)
		(layer "In2.Cu")
		(net "M_I_CPU1_SA_DQ<2>")
	)
	(segment
		(start 177.204116 -197.527926)
		(end 177.36693 -197.365112)
		(width 0.14478)
		(layer "In2.Cu")
		(net "M_I_CPU1_SA_DQ<2>")
	)
	(segment
		(start 142.620238 -218.121738)
		(end 142.620238 -217.893138)
		(width 0.14478)
		(layer "In2.Cu")
		(net "M_I_CPU1_SA_DQ<2>")
	)
	(segment
		(start 143.400526 -217.11285)
		(end 143.280384 -216.992708)
		(width 0.14478)
		(layer "In2.Cu")
		(net "M_I_CPU1_SA_DQ<2>")
	)
	(segment
		(start 142.458694 -218.283282)
		(end 142.620238 -218.121738)
		(width 0.14478)
		(layer "In2.Cu")
		(net "M_I_CPU1_SA_DQ<2>")
	)
	(segment
		(start 142.620238 -217.893138)
		(end 142.500096 -217.772996)
		(width 0.14478)
		(layer "In2.Cu")
		(net "M_I_CPU1_SA_DQ<2>")
	)
	(segment
		(start 147.569428 -212.475064)
		(end 147.569428 -211.080096)
		(width 0.14478)
		(layer "In2.Cu")
		(net "M_I_CPU1_SA_DQ<2>")
	)
	(segment
		(start 141.167104 -222.30969)
		(end 141.197584 -222.29191)
		(width 0.0889)
		(layer "In2.Cu")
		(net "M_I_CPU1_SA_DQ<2>")
	)
	(segment
		(start 142.89024 -217.382852)
		(end 143.010382 -217.502994)
		(width 0.14478)
		(layer "In2.Cu")
		(net "M_I_CPU1_SA_DQ<2>")
	)
	(segment
		(start 143.79067 -216.722706)
		(end 144.01927 -216.722706)
		(width 0.14478)
		(layer "In2.Cu")
		(net "M_I_CPU1_SA_DQ<2>")
	)
	(segment
		(start 130.857752 -225.531934)
		(end 130.866134 -225.527108)
		(width 0.0889)
		(layer "In2.Cu")
		(net "M_I_CPU1_SA_DQ<2>")
	)
	(segment
		(start 144.84096 -215.432132)
		(end 144.84096 -215.203532)
		(width 0.14478)
		(layer "In2.Cu")
		(net "M_I_CPU1_SA_DQ<2>")
	)
	(segment
		(start 134.04342 -225.527108)
		(end 134.051802 -225.531934)
		(width 0.0889)
		(layer "In2.Cu")
		(net "M_I_CPU1_SA_DQ<2>")
	)
	(segment
		(start 178.153822 -198.155814)
		(end 178.316636 -197.993)
		(width 0.14478)
		(layer "In2.Cu")
		(net "M_I_CPU1_SA_DQ<2>")
	)
	(segment
		(start 166.299134 -198.610474)
		(end 167.149272 -197.760336)
		(width 0.14478)
		(layer "In2.Cu")
		(net "M_I_CPU1_SA_DQ<2>")
	)
	(segment
		(start 141.197584 -222.29191)
		(end 141.232382 -222.27159)
		(width 0.0889)
		(layer "In2.Cu")
		(net "M_I_CPU1_SA_DQ<2>")
	)
	(segment
		(start 144.961102 -215.780874)
		(end 144.961102 -215.552274)
		(width 0.14478)
		(layer "In2.Cu")
		(net "M_I_CPU1_SA_DQ<2>")
	)
	(segment
		(start 145.621248 -214.423244)
		(end 147.569428 -212.475064)
		(width 0.14478)
		(layer "In2.Cu")
		(net "M_I_CPU1_SA_DQ<2>")
	)
	(segment
		(start 141.881352 -218.16314)
		(end 142.109952 -218.16314)
		(width 0.14478)
		(layer "In2.Cu")
		(net "M_I_CPU1_SA_DQ<2>")
	)
	(segment
		(start 145.231104 -215.041988)
		(end 145.351246 -215.16213)
		(width 0.14478)
		(layer "In2.Cu")
		(net "M_I_CPU1_SA_DQ<2>")
	)
	(segment
		(start 167.149272 -197.760336)
		(end 169.942002 -197.760336)
		(width 0.14478)
		(layer "In2.Cu")
		(net "M_I_CPU1_SA_DQ<2>")
	)
	(segment
		(start 169.942002 -197.760336)
		(end 170.79214 -198.610474)
		(width 0.14478)
		(layer "In2.Cu")
		(net "M_I_CPU1_SA_DQ<2>")
	)
	(segment
		(start 170.79214 -198.610474)
		(end 173.640496 -198.610474)
		(width 0.14478)
		(layer "In2.Cu")
		(net "M_I_CPU1_SA_DQ<2>")
	)
	(segment
		(start 144.01927 -216.722706)
		(end 144.180814 -216.561162)
		(width 0.14478)
		(layer "In2.Cu")
		(net "M_I_CPU1_SA_DQ<2>")
	)
	(segment
		(start 143.238982 -217.502994)
		(end 143.400526 -217.34145)
		(width 0.14478)
		(layer "In2.Cu")
		(net "M_I_CPU1_SA_DQ<2>")
	)
	(segment
		(start 147.569428 -211.080096)
		(end 160.03905 -198.610474)
		(width 0.14478)
		(layer "In2.Cu")
		(net "M_I_CPU1_SA_DQ<2>")
	)
	(segment
		(start 176.415192 -197.760336)
		(end 176.81067 -198.155814)
		(width 0.14478)
		(layer "In2.Cu")
		(net "M_I_CPU1_SA_DQ<2>")
	)
	(segment
		(start 145.74139 -214.771986)
		(end 145.621248 -214.651844)
		(width 0.14478)
		(layer "In2.Cu")
		(net "M_I_CPU1_SA_DQ<2>")
	)
	(segment
		(start 133.103366 -225.527108)
		(end 133.111748 -225.531934)
		(width 0.0889)
		(layer "In2.Cu")
		(net "M_I_CPU1_SA_DQ<2>")
	)
	(segment
		(start 177.204116 -197.993)
		(end 177.204116 -197.527926)
		(width 0.14478)
		(layer "In2.Cu")
		(net "M_I_CPU1_SA_DQ<2>")
	)
	(segment
		(start 142.500096 -217.772996)
		(end 142.500096 -217.544396)
		(width 0.14478)
		(layer "In2.Cu")
		(net "M_I_CPU1_SA_DQ<2>")
	)
	(segment
		(start 135.557768 -225.531934)
		(end 135.56615 -225.527108)
		(width 0.0889)
		(layer "In2.Cu")
		(net "M_I_CPU1_SA_DQ<2>")
	)
	(segment
		(start 140.25753 -223.911922)
		(end 140.295376 -223.890078)
		(width 0.0889)
		(layer "In2.Cu")
		(net "M_I_CPU1_SA_DQ<2>")
	)
	(segment
		(start 140.697966 -223.118934)
		(end 140.72743 -223.101916)
		(width 0.0889)
		(layer "In2.Cu")
		(net "M_I_CPU1_SA_DQ<2>")
	)
	(segment
		(start 134.617714 -225.531934)
		(end 134.626096 -225.527108)
		(width 0.0889)
		(layer "In2.Cu")
		(net "M_I_CPU1_SA_DQ<2>")
	)
	(arc
		(start 134.626096 -225.527108)
		(mid 134.809604 -225.481614)
		(end 134.991856 -225.531934)
		(width 0.0889)
		(layer "In2.Cu")
		(net "M_I_CPU1_SA_DQ<2>")
	)
	(arc
		(start 138.377676 -225.531934)
		(mid 138.559927 -225.481584)
		(end 138.743436 -225.527108)
		(width 0.0889)
		(layer "In2.Cu")
		(net "M_I_CPU1_SA_DQ<2>")
	)
	(arc
		(start 136.497822 -225.531934)
		(mid 136.684766 -225.481679)
		(end 136.87171 -225.531934)
		(width 0.0889)
		(layer "In2.Cu")
		(net "M_I_CPU1_SA_DQ<2>")
	)
	(arc
		(start 135.93191 -225.531934)
		(mid 136.214866 -225.608111)
		(end 136.497822 -225.531934)
		(width 0.0889)
		(layer "In2.Cu")
		(net "M_I_CPU1_SA_DQ<2>")
	)
	(arc
		(start 139.823952 -224.700846)
		(mid 140.004604 -224.498101)
		(end 140.069824 -224.234502)
		(width 0.0889)
		(layer "In2.Cu")
		(net "M_I_CPU1_SA_DQ<2>")
	)
	(arc
		(start 132.171694 -225.531934)
		(mid 132.45465 -225.608111)
		(end 132.737606 -225.531934)
		(width 0.0889)
		(layer "In2.Cu")
		(net "M_I_CPU1_SA_DQ<2>")
	)
	(arc
		(start 139.600178 -225.044508)
		(mid 139.641727 -224.873086)
		(end 139.75715 -224.739708)
		(width 0.0889)
		(layer "In2.Cu")
		(net "M_I_CPU1_SA_DQ<2>")
	)
	(arc
		(start 133.111748 -225.531934)
		(mid 133.394704 -225.608111)
		(end 133.67766 -225.531934)
		(width 0.0889)
		(layer "In2.Cu")
		(net "M_I_CPU1_SA_DQ<2>")
	)
	(arc
		(start 135.56615 -225.527108)
		(mid 135.749658 -225.481614)
		(end 135.93191 -225.531934)
		(width 0.0889)
		(layer "In2.Cu")
		(net "M_I_CPU1_SA_DQ<2>")
	)
	(arc
		(start 141.010132 -222.61449)
		(mid 141.051681 -222.443068)
		(end 141.167104 -222.30969)
		(width 0.0889)
		(layer "In2.Cu")
		(net "M_I_CPU1_SA_DQ<2>")
	)
	(arc
		(start 139.356846 -225.509074)
		(mid 139.535659 -225.306724)
		(end 139.600178 -225.044508)
		(width 0.0889)
		(layer "In2.Cu")
		(net "M_I_CPU1_SA_DQ<2>")
	)
	(arc
		(start 141.232382 -222.27159)
		(mid 141.413961 -222.068723)
		(end 141.479524 -221.804484)
		(width 0.0889)
		(layer "In2.Cu")
		(net "M_I_CPU1_SA_DQ<2>")
	)
	(arc
		(start 129.414778 -225.563684)
		(mid 129.669986 -225.607161)
		(end 129.917698 -225.531934)
		(width 0.0889)
		(layer "In2.Cu")
		(net "M_I_CPU1_SA_DQ<2>")
	)
	(arc
		(start 133.67766 -225.531934)
		(mid 133.859911 -225.481584)
		(end 134.04342 -225.527108)
		(width 0.0889)
		(layer "In2.Cu")
		(net "M_I_CPU1_SA_DQ<2>")
	)
	(arc
		(start 129.92608 -225.527108)
		(mid 130.109588 -225.481614)
		(end 130.29184 -225.531934)
		(width 0.0889)
		(layer "In2.Cu")
		(net "M_I_CPU1_SA_DQ<2>")
	)
	(arc
		(start 130.29184 -225.531934)
		(mid 130.574796 -225.608111)
		(end 130.857752 -225.531934)
		(width 0.0889)
		(layer "In2.Cu")
		(net "M_I_CPU1_SA_DQ<2>")
	)
	(arc
		(start 132.737606 -225.531934)
		(mid 132.919857 -225.481584)
		(end 133.103366 -225.527108)
		(width 0.0889)
		(layer "In2.Cu")
		(net "M_I_CPU1_SA_DQ<2>")
	)
	(arc
		(start 140.069824 -224.234502)
		(mid 140.111079 -224.063531)
		(end 140.22578 -223.93021)
		(width 0.0889)
		(layer "In2.Cu")
		(net "M_I_CPU1_SA_DQ<2>")
	)
	(arc
		(start 140.539978 -223.424496)
		(mid 140.581818 -223.25251)
		(end 140.697966 -223.118934)
		(width 0.0889)
		(layer "In2.Cu")
		(net "M_I_CPU1_SA_DQ<2>")
	)
	(arc
		(start 140.767816 -223.078294)
		(mid 140.945881 -222.876117)
		(end 141.010132 -222.61449)
		(width 0.0889)
		(layer "In2.Cu")
		(net "M_I_CPU1_SA_DQ<2>")
	)
	(arc
		(start 137.437622 -225.531934)
		(mid 137.619873 -225.481584)
		(end 137.803382 -225.527108)
		(width 0.0889)
		(layer "In2.Cu")
		(net "M_I_CPU1_SA_DQ<2>")
	)
	(arc
		(start 131.231894 -225.531934)
		(mid 131.51485 -225.608111)
		(end 131.797806 -225.531934)
		(width 0.0889)
		(layer "In2.Cu")
		(net "M_I_CPU1_SA_DQ<2>")
	)
	(arc
		(start 136.87171 -225.531934)
		(mid 137.154666 -225.608111)
		(end 137.437622 -225.531934)
		(width 0.0889)
		(layer "In2.Cu")
		(net "M_I_CPU1_SA_DQ<2>")
	)
	(arc
		(start 138.751818 -225.531934)
		(mid 139.034774 -225.608111)
		(end 139.31773 -225.531934)
		(width 0.0889)
		(layer "In2.Cu")
		(net "M_I_CPU1_SA_DQ<2>")
	)
	(arc
		(start 140.295376 -223.890078)
		(mid 140.475105 -223.687458)
		(end 140.539978 -223.424496)
		(width 0.0889)
		(layer "In2.Cu")
		(net "M_I_CPU1_SA_DQ<2>")
	)
	(arc
		(start 134.991856 -225.531934)
		(mid 135.274812 -225.608111)
		(end 135.557768 -225.531934)
		(width 0.0889)
		(layer "In2.Cu")
		(net "M_I_CPU1_SA_DQ<2>")
	)
	(arc
		(start 134.051802 -225.531934)
		(mid 134.334758 -225.608111)
		(end 134.617714 -225.531934)
		(width 0.0889)
		(layer "In2.Cu")
		(net "M_I_CPU1_SA_DQ<2>")
	)
	(arc
		(start 130.866134 -225.527108)
		(mid 131.049642 -225.481614)
		(end 131.231894 -225.531934)
		(width 0.0889)
		(layer "In2.Cu")
		(net "M_I_CPU1_SA_DQ<2>")
	)
	(arc
		(start 131.797806 -225.531934)
		(mid 131.98475 -225.481679)
		(end 132.171694 -225.531934)
		(width 0.0889)
		(layer "In2.Cu")
		(net "M_I_CPU1_SA_DQ<2>")
	)
	(arc
		(start 137.811764 -225.531934)
		(mid 138.09472 -225.608111)
		(end 138.377676 -225.531934)
		(width 0.0889)
		(layer "In2.Cu")
		(net "M_I_CPU1_SA_DQ<2>")
	)
	(segment
		(start 127.757936 -243.94033)
		(end 128.224788 -243.674392)
		(width 0.10668)
		(layer "F.Cu")
		(net "M_I_CPU1_SA_DQ<29>")
	)
	(segment
		(start 128.224788 -243.674392)
		(end 128.07061 -243.939822)
		(width 0.0889)
		(layer "In2.Cu")
		(net "M_I_CPU1_SA_DQ<29>")
	)
	(segment
		(start 144.9578 -243.996972)
		(end 144.966182 -244.001798)
		(width 0.0889)
		(layer "In2.Cu")
		(net "M_I_CPU1_SA_DQ<29>")
	)
	(segment
		(start 140.257784 -243.996972)
		(end 140.266166 -244.001798)
		(width 0.0889)
		(layer "In2.Cu")
		(net "M_I_CPU1_SA_DQ<29>")
	)
	(segment
		(start 183.19115 -232.610406)
		(end 183.616092 -233.035348)
		(width 0.14478)
		(layer "In2.Cu")
		(net "M_I_CPU1_SA_DQ<29>")
	)
	(segment
		(start 133.103366 -244.001798)
		(end 133.111748 -243.996972)
		(width 0.0889)
		(layer "In2.Cu")
		(net "M_I_CPU1_SA_DQ<29>")
	)
	(segment
		(start 128.40335 -244.001798)
		(end 128.411732 -243.996972)
		(width 0.0889)
		(layer "In2.Cu")
		(net "M_I_CPU1_SA_DQ<29>")
	)
	(segment
		(start 129.343404 -244.001798)
		(end 129.351786 -243.996972)
		(width 0.0889)
		(layer "In2.Cu")
		(net "M_I_CPU1_SA_DQ<29>")
	)
	(segment
		(start 142.503398 -244.001798)
		(end 142.51178 -243.996972)
		(width 0.0889)
		(layer "In2.Cu")
		(net "M_I_CPU1_SA_DQ<29>")
	)
	(segment
		(start 160.452054 -236.956092)
		(end 160.452054 -235.823252)
		(width 0.14478)
		(layer "In2.Cu")
		(net "M_I_CPU1_SA_DQ<29>")
	)
	(segment
		(start 139.31773 -243.996972)
		(end 139.326112 -244.001798)
		(width 0.0889)
		(layer "In2.Cu")
		(net "M_I_CPU1_SA_DQ<29>")
	)
	(segment
		(start 129.917698 -243.996972)
		(end 129.92608 -244.001798)
		(width 0.0889)
		(layer "In2.Cu")
		(net "M_I_CPU1_SA_DQ<29>")
	)
	(segment
		(start 162.815016 -233.46029)
		(end 165.01999 -233.46029)
		(width 0.14478)
		(layer "In2.Cu")
		(net "M_I_CPU1_SA_DQ<29>")
	)
	(segment
		(start 135.557768 -243.996972)
		(end 135.56615 -244.001798)
		(width 0.0889)
		(layer "In2.Cu")
		(net "M_I_CPU1_SA_DQ<29>")
	)
	(segment
		(start 130.857752 -243.996972)
		(end 130.866134 -244.001798)
		(width 0.0889)
		(layer "In2.Cu")
		(net "M_I_CPU1_SA_DQ<29>")
	)
	(segment
		(start 134.617714 -243.996972)
		(end 134.626096 -244.001798)
		(width 0.0889)
		(layer "In2.Cu")
		(net "M_I_CPU1_SA_DQ<29>")
	)
	(segment
		(start 147.646136 -242.767104)
		(end 147.969986 -242.767104)
		(width 0.0889)
		(layer "In2.Cu")
		(net "M_I_CPU1_SA_DQ<29>")
	)
	(segment
		(start 128.07061 -243.939822)
		(end 128.092962 -244.023134)
		(width 0.0889)
		(layer "In2.Cu")
		(net "M_I_CPU1_SA_DQ<29>")
	)
	(segment
		(start 175.386492 -232.610406)
		(end 183.19115 -232.610406)
		(width 0.14478)
		(layer "In2.Cu")
		(net "M_I_CPU1_SA_DQ<29>")
	)
	(segment
		(start 134.04342 -244.001798)
		(end 134.051802 -243.996972)
		(width 0.0889)
		(layer "In2.Cu")
		(net "M_I_CPU1_SA_DQ<29>")
	)
	(segment
		(start 154.641042 -242.767104)
		(end 160.452054 -236.956092)
		(width 0.14478)
		(layer "In2.Cu")
		(net "M_I_CPU1_SA_DQ<29>")
	)
	(segment
		(start 138.743436 -244.001798)
		(end 138.751818 -243.996972)
		(width 0.0889)
		(layer "In2.Cu")
		(net "M_I_CPU1_SA_DQ<29>")
	)
	(segment
		(start 173.33468 -233.46029)
		(end 175.386492 -232.610406)
		(width 0.14478)
		(layer "In2.Cu")
		(net "M_I_CPU1_SA_DQ<29>")
	)
	(segment
		(start 169.232072 -232.610406)
		(end 171.283884 -233.46029)
		(width 0.14478)
		(layer "In2.Cu")
		(net "M_I_CPU1_SA_DQ<29>")
	)
	(segment
		(start 160.452054 -235.823252)
		(end 162.815016 -233.46029)
		(width 0.14478)
		(layer "In2.Cu")
		(net "M_I_CPU1_SA_DQ<29>")
	)
	(segment
		(start 144.383506 -244.001798)
		(end 144.391888 -243.996972)
		(width 0.0889)
		(layer "In2.Cu")
		(net "M_I_CPU1_SA_DQ<29>")
	)
	(segment
		(start 143.077692 -243.996972)
		(end 143.086074 -244.001798)
		(width 0.0889)
		(layer "In2.Cu")
		(net "M_I_CPU1_SA_DQ<29>")
	)
	(segment
		(start 137.803382 -244.001798)
		(end 137.811764 -243.996972)
		(width 0.0889)
		(layer "In2.Cu")
		(net "M_I_CPU1_SA_DQ<29>")
	)
	(segment
		(start 146.492468 -243.920772)
		(end 147.646136 -242.767104)
		(width 0.0889)
		(layer "In2.Cu")
		(net "M_I_CPU1_SA_DQ<29>")
	)
	(segment
		(start 147.969986 -242.767104)
		(end 154.641042 -242.767104)
		(width 0.14478)
		(layer "In2.Cu")
		(net "M_I_CPU1_SA_DQ<29>")
	)
	(segment
		(start 171.283884 -233.46029)
		(end 173.33468 -233.46029)
		(width 0.14478)
		(layer "In2.Cu")
		(net "M_I_CPU1_SA_DQ<29>")
	)
	(segment
		(start 167.071802 -232.610406)
		(end 169.232072 -232.610406)
		(width 0.14478)
		(layer "In2.Cu")
		(net "M_I_CPU1_SA_DQ<29>")
	)
	(segment
		(start 165.01999 -233.46029)
		(end 167.071802 -232.610406)
		(width 0.14478)
		(layer "In2.Cu")
		(net "M_I_CPU1_SA_DQ<29>")
	)
	(segment
		(start 145.614644 -243.920772)
		(end 146.492468 -243.920772)
		(width 0.0889)
		(layer "In2.Cu")
		(net "M_I_CPU1_SA_DQ<29>")
	)
	(arc
		(start 136.497822 -243.996972)
		(mid 136.684766 -244.047227)
		(end 136.87171 -243.996972)
		(width 0.0889)
		(layer "In2.Cu")
		(net "M_I_CPU1_SA_DQ<29>")
	)
	(arc
		(start 140.266166 -244.001798)
		(mid 140.449674 -244.047292)
		(end 140.631926 -243.996972)
		(width 0.0889)
		(layer "In2.Cu")
		(net "M_I_CPU1_SA_DQ<29>")
	)
	(arc
		(start 131.231894 -243.996972)
		(mid 131.51485 -243.920795)
		(end 131.797806 -243.996972)
		(width 0.0889)
		(layer "In2.Cu")
		(net "M_I_CPU1_SA_DQ<29>")
	)
	(arc
		(start 135.56615 -244.001798)
		(mid 135.749658 -244.047292)
		(end 135.93191 -243.996972)
		(width 0.0889)
		(layer "In2.Cu")
		(net "M_I_CPU1_SA_DQ<29>")
	)
	(arc
		(start 129.351786 -243.996972)
		(mid 129.634742 -243.920795)
		(end 129.917698 -243.996972)
		(width 0.0889)
		(layer "In2.Cu")
		(net "M_I_CPU1_SA_DQ<29>")
	)
	(arc
		(start 130.866134 -244.001798)
		(mid 131.049642 -244.047292)
		(end 131.231894 -243.996972)
		(width 0.0889)
		(layer "In2.Cu")
		(net "M_I_CPU1_SA_DQ<29>")
	)
	(arc
		(start 132.737606 -243.996972)
		(mid 132.919857 -244.047322)
		(end 133.103366 -244.001798)
		(width 0.0889)
		(layer "In2.Cu")
		(net "M_I_CPU1_SA_DQ<29>")
	)
	(arc
		(start 141.197838 -243.996972)
		(mid 141.384782 -244.047227)
		(end 141.571726 -243.996972)
		(width 0.0889)
		(layer "In2.Cu")
		(net "M_I_CPU1_SA_DQ<29>")
	)
	(arc
		(start 137.811764 -243.996972)
		(mid 138.09472 -243.920795)
		(end 138.377676 -243.996972)
		(width 0.0889)
		(layer "In2.Cu")
		(net "M_I_CPU1_SA_DQ<29>")
	)
	(arc
		(start 144.017746 -243.996972)
		(mid 144.199997 -244.047322)
		(end 144.383506 -244.001798)
		(width 0.0889)
		(layer "In2.Cu")
		(net "M_I_CPU1_SA_DQ<29>")
	)
	(arc
		(start 133.67766 -243.996972)
		(mid 133.859911 -244.047322)
		(end 134.04342 -244.001798)
		(width 0.0889)
		(layer "In2.Cu")
		(net "M_I_CPU1_SA_DQ<29>")
	)
	(arc
		(start 143.086074 -244.001798)
		(mid 143.269582 -244.047292)
		(end 143.451834 -243.996972)
		(width 0.0889)
		(layer "In2.Cu")
		(net "M_I_CPU1_SA_DQ<29>")
	)
	(arc
		(start 141.571726 -243.996972)
		(mid 141.854682 -243.920795)
		(end 142.137638 -243.996972)
		(width 0.0889)
		(layer "In2.Cu")
		(net "M_I_CPU1_SA_DQ<29>")
	)
	(arc
		(start 140.631926 -243.996972)
		(mid 140.914882 -243.920795)
		(end 141.197838 -243.996972)
		(width 0.0889)
		(layer "In2.Cu")
		(net "M_I_CPU1_SA_DQ<29>")
	)
	(arc
		(start 144.966182 -244.001798)
		(mid 145.14969 -244.047292)
		(end 145.331942 -243.996972)
		(width 0.0889)
		(layer "In2.Cu")
		(net "M_I_CPU1_SA_DQ<29>")
	)
	(arc
		(start 128.411732 -243.996972)
		(mid 128.694688 -243.920795)
		(end 128.977644 -243.996972)
		(width 0.0889)
		(layer "In2.Cu")
		(net "M_I_CPU1_SA_DQ<29>")
	)
	(arc
		(start 143.451834 -243.996972)
		(mid 143.73479 -243.920795)
		(end 144.017746 -243.996972)
		(width 0.0889)
		(layer "In2.Cu")
		(net "M_I_CPU1_SA_DQ<29>")
	)
	(arc
		(start 134.051802 -243.996972)
		(mid 134.334758 -243.920795)
		(end 134.617714 -243.996972)
		(width 0.0889)
		(layer "In2.Cu")
		(net "M_I_CPU1_SA_DQ<29>")
	)
	(arc
		(start 128.977644 -243.996972)
		(mid 129.159895 -244.047322)
		(end 129.343404 -244.001798)
		(width 0.0889)
		(layer "In2.Cu")
		(net "M_I_CPU1_SA_DQ<29>")
	)
	(arc
		(start 128.092962 -244.023134)
		(mid 128.250472 -244.046332)
		(end 128.40335 -244.001798)
		(width 0.0889)
		(layer "In2.Cu")
		(net "M_I_CPU1_SA_DQ<29>")
	)
	(arc
		(start 129.92608 -244.001798)
		(mid 130.109588 -244.047292)
		(end 130.29184 -243.996972)
		(width 0.0889)
		(layer "In2.Cu")
		(net "M_I_CPU1_SA_DQ<29>")
	)
	(arc
		(start 144.391888 -243.996972)
		(mid 144.674844 -243.920795)
		(end 144.9578 -243.996972)
		(width 0.0889)
		(layer "In2.Cu")
		(net "M_I_CPU1_SA_DQ<29>")
	)
	(arc
		(start 145.331942 -243.996972)
		(mid 145.468264 -243.940231)
		(end 145.614644 -243.920772)
		(width 0.0889)
		(layer "In2.Cu")
		(net "M_I_CPU1_SA_DQ<29>")
	)
	(arc
		(start 138.377676 -243.996972)
		(mid 138.559927 -244.047322)
		(end 138.743436 -244.001798)
		(width 0.0889)
		(layer "In2.Cu")
		(net "M_I_CPU1_SA_DQ<29>")
	)
	(arc
		(start 138.751818 -243.996972)
		(mid 139.034774 -243.920795)
		(end 139.31773 -243.996972)
		(width 0.0889)
		(layer "In2.Cu")
		(net "M_I_CPU1_SA_DQ<29>")
	)
	(arc
		(start 131.797806 -243.996972)
		(mid 131.98475 -244.047227)
		(end 132.171694 -243.996972)
		(width 0.0889)
		(layer "In2.Cu")
		(net "M_I_CPU1_SA_DQ<29>")
	)
	(arc
		(start 134.991856 -243.996972)
		(mid 135.274812 -243.920795)
		(end 135.557768 -243.996972)
		(width 0.0889)
		(layer "In2.Cu")
		(net "M_I_CPU1_SA_DQ<29>")
	)
	(arc
		(start 135.93191 -243.996972)
		(mid 136.214866 -243.920795)
		(end 136.497822 -243.996972)
		(width 0.0889)
		(layer "In2.Cu")
		(net "M_I_CPU1_SA_DQ<29>")
	)
	(arc
		(start 142.137638 -243.996972)
		(mid 142.319889 -244.047322)
		(end 142.503398 -244.001798)
		(width 0.0889)
		(layer "In2.Cu")
		(net "M_I_CPU1_SA_DQ<29>")
	)
	(arc
		(start 132.171694 -243.996972)
		(mid 132.45465 -243.920795)
		(end 132.737606 -243.996972)
		(width 0.0889)
		(layer "In2.Cu")
		(net "M_I_CPU1_SA_DQ<29>")
	)
	(arc
		(start 137.437622 -243.996972)
		(mid 137.619873 -244.047322)
		(end 137.803382 -244.001798)
		(width 0.0889)
		(layer "In2.Cu")
		(net "M_I_CPU1_SA_DQ<29>")
	)
	(arc
		(start 134.626096 -244.001798)
		(mid 134.809604 -244.047292)
		(end 134.991856 -243.996972)
		(width 0.0889)
		(layer "In2.Cu")
		(net "M_I_CPU1_SA_DQ<29>")
	)
	(arc
		(start 130.29184 -243.996972)
		(mid 130.574796 -243.920795)
		(end 130.857752 -243.996972)
		(width 0.0889)
		(layer "In2.Cu")
		(net "M_I_CPU1_SA_DQ<29>")
	)
	(arc
		(start 139.326112 -244.001798)
		(mid 139.50962 -244.047292)
		(end 139.691872 -243.996972)
		(width 0.0889)
		(layer "In2.Cu")
		(net "M_I_CPU1_SA_DQ<29>")
	)
	(arc
		(start 136.87171 -243.996972)
		(mid 137.154666 -243.920795)
		(end 137.437622 -243.996972)
		(width 0.0889)
		(layer "In2.Cu")
		(net "M_I_CPU1_SA_DQ<29>")
	)
	(arc
		(start 139.691872 -243.996972)
		(mid 139.974828 -243.920795)
		(end 140.257784 -243.996972)
		(width 0.0889)
		(layer "In2.Cu")
		(net "M_I_CPU1_SA_DQ<29>")
	)
	(arc
		(start 142.51178 -243.996972)
		(mid 142.794736 -243.920795)
		(end 143.077692 -243.996972)
		(width 0.0889)
		(layer "In2.Cu")
		(net "M_I_CPU1_SA_DQ<29>")
	)
	(arc
		(start 133.111748 -243.996972)
		(mid 133.394704 -243.920795)
		(end 133.67766 -243.996972)
		(width 0.0889)
		(layer "In2.Cu")
		(net "M_I_CPU1_SA_DQ<29>")
	)
	(segment
		(start 129.16789 -243.130324)
		(end 129.634742 -242.864386)
		(width 0.10668)
		(layer "F.Cu")
		(net "M_I_CPU1_SA_DQ<28>")
	)
	(segment
		(start 144.487392 -243.186966)
		(end 144.495774 -243.191792)
		(width 0.0889)
		(layer "In2.Cu")
		(net "M_I_CPU1_SA_DQ<28>")
	)
	(segment
		(start 181.683152 -231.07396)
		(end 181.683152 -231.722168)
		(width 0.14478)
		(layer "In2.Cu")
		(net "M_I_CPU1_SA_DQ<28>")
	)
	(segment
		(start 141.667738 -243.186966)
		(end 141.67612 -243.191792)
		(width 0.0889)
		(layer "In2.Cu")
		(net "M_I_CPU1_SA_DQ<28>")
	)
	(segment
		(start 147.944586 -241.829844)
		(end 153.17343 -241.829844)
		(width 0.14478)
		(layer "In2.Cu")
		(net "M_I_CPU1_SA_DQ<28>")
	)
	(segment
		(start 129.634742 -242.864386)
		(end 129.480818 -243.129816)
		(width 0.0889)
		(layer "In2.Cu")
		(net "M_I_CPU1_SA_DQ<28>")
	)
	(segment
		(start 131.693412 -243.191792)
		(end 131.701794 -243.186966)
		(width 0.0889)
		(layer "In2.Cu")
		(net "M_I_CPU1_SA_DQ<28>")
	)
	(segment
		(start 145.343626 -243.110766)
		(end 145.466308 -242.988084)
		(width 0.0889)
		(layer "In2.Cu")
		(net "M_I_CPU1_SA_DQ<28>")
	)
	(segment
		(start 141.093444 -243.191792)
		(end 141.101826 -243.186966)
		(width 0.0889)
		(layer "In2.Cu")
		(net "M_I_CPU1_SA_DQ<28>")
	)
	(segment
		(start 163.233354 -231.76992)
		(end 165.993826 -231.76992)
		(width 0.14478)
		(layer "In2.Cu")
		(net "M_I_CPU1_SA_DQ<28>")
	)
	(segment
		(start 181.683152 -231.722168)
		(end 181.846728 -231.885744)
		(width 0.14478)
		(layer "In2.Cu")
		(net "M_I_CPU1_SA_DQ<28>")
	)
	(segment
		(start 169.777918 -230.920036)
		(end 170.627802 -231.76992)
		(width 0.14478)
		(layer "In2.Cu")
		(net "M_I_CPU1_SA_DQ<28>")
	)
	(segment
		(start 166.84371 -230.920036)
		(end 169.777918 -230.920036)
		(width 0.14478)
		(layer "In2.Cu")
		(net "M_I_CPU1_SA_DQ<28>")
	)
	(segment
		(start 146.530568 -242.467384)
		(end 146.962368 -242.467384)
		(width 0.0889)
		(layer "In2.Cu")
		(net "M_I_CPU1_SA_DQ<28>")
	)
	(segment
		(start 140.15339 -243.191792)
		(end 140.161772 -243.186966)
		(width 0.0889)
		(layer "In2.Cu")
		(net "M_I_CPU1_SA_DQ<28>")
	)
	(segment
		(start 132.267706 -243.186966)
		(end 132.276088 -243.191792)
		(width 0.0889)
		(layer "In2.Cu")
		(net "M_I_CPU1_SA_DQ<28>")
	)
	(segment
		(start 147.599908 -241.829844)
		(end 147.944586 -241.829844)
		(width 0.0889)
		(layer "In2.Cu")
		(net "M_I_CPU1_SA_DQ<28>")
	)
	(segment
		(start 137.907776 -243.186966)
		(end 137.916158 -243.191792)
		(width 0.0889)
		(layer "In2.Cu")
		(net "M_I_CPU1_SA_DQ<28>")
	)
	(segment
		(start 182.241952 -231.722168)
		(end 182.241952 -231.07396)
		(width 0.14478)
		(layer "In2.Cu")
		(net "M_I_CPU1_SA_DQ<28>")
	)
	(segment
		(start 165.993826 -231.76992)
		(end 166.84371 -230.920036)
		(width 0.14478)
		(layer "In2.Cu")
		(net "M_I_CPU1_SA_DQ<28>")
	)
	(segment
		(start 143.921734 -243.186966)
		(end 143.932148 -243.18087)
		(width 0.0889)
		(layer "In2.Cu")
		(net "M_I_CPU1_SA_DQ<28>")
	)
	(segment
		(start 173.64329 -231.76992)
		(end 174.493174 -230.920036)
		(width 0.14478)
		(layer "In2.Cu")
		(net "M_I_CPU1_SA_DQ<28>")
	)
	(segment
		(start 170.627802 -231.76992)
		(end 173.64329 -231.76992)
		(width 0.14478)
		(layer "In2.Cu")
		(net "M_I_CPU1_SA_DQ<28>")
	)
	(segment
		(start 174.493174 -230.920036)
		(end 181.529228 -230.920036)
		(width 0.14478)
		(layer "In2.Cu")
		(net "M_I_CPU1_SA_DQ<28>")
	)
	(segment
		(start 181.529228 -230.920036)
		(end 181.683152 -231.07396)
		(width 0.14478)
		(layer "In2.Cu")
		(net "M_I_CPU1_SA_DQ<28>")
	)
	(segment
		(start 146.009868 -242.988084)
		(end 146.530568 -242.467384)
		(width 0.0889)
		(layer "In2.Cu")
		(net "M_I_CPU1_SA_DQ<28>")
	)
	(segment
		(start 182.241952 -231.07396)
		(end 182.405528 -230.910384)
		(width 0.14478)
		(layer "In2.Cu")
		(net "M_I_CPU1_SA_DQ<28>")
	)
	(segment
		(start 133.20776 -243.186966)
		(end 133.216142 -243.191792)
		(width 0.0889)
		(layer "In2.Cu")
		(net "M_I_CPU1_SA_DQ<28>")
	)
	(segment
		(start 153.17343 -241.829844)
		(end 163.233354 -231.76992)
		(width 0.14478)
		(layer "In2.Cu")
		(net "M_I_CPU1_SA_DQ<28>")
	)
	(segment
		(start 182.405528 -230.910384)
		(end 183.19115 -230.910384)
		(width 0.14478)
		(layer "In2.Cu")
		(net "M_I_CPU1_SA_DQ<28>")
	)
	(segment
		(start 129.480818 -243.129816)
		(end 129.50317 -243.213128)
		(width 0.0889)
		(layer "In2.Cu")
		(net "M_I_CPU1_SA_DQ<28>")
	)
	(segment
		(start 136.967722 -243.186966)
		(end 136.976104 -243.191792)
		(width 0.0889)
		(layer "In2.Cu")
		(net "M_I_CPU1_SA_DQ<28>")
	)
	(segment
		(start 146.962368 -242.467384)
		(end 147.599908 -241.829844)
		(width 0.0889)
		(layer "In2.Cu")
		(net "M_I_CPU1_SA_DQ<28>")
	)
	(segment
		(start 183.19115 -230.910384)
		(end 183.616092 -231.335326)
		(width 0.14478)
		(layer "In2.Cu")
		(net "M_I_CPU1_SA_DQ<28>")
	)
	(segment
		(start 145.466308 -242.988084)
		(end 146.009868 -242.988084)
		(width 0.0889)
		(layer "In2.Cu")
		(net "M_I_CPU1_SA_DQ<28>")
	)
	(segment
		(start 136.393428 -243.191792)
		(end 136.40181 -243.186966)
		(width 0.0889)
		(layer "In2.Cu")
		(net "M_I_CPU1_SA_DQ<28>")
	)
	(segment
		(start 143.913352 -243.191792)
		(end 143.921734 -243.186966)
		(width 0.0889)
		(layer "In2.Cu")
		(net "M_I_CPU1_SA_DQ<28>")
	)
	(segment
		(start 182.078376 -231.885744)
		(end 182.241952 -231.722168)
		(width 0.14478)
		(layer "In2.Cu")
		(net "M_I_CPU1_SA_DQ<28>")
	)
	(segment
		(start 130.753358 -243.191792)
		(end 130.76174 -243.186966)
		(width 0.0889)
		(layer "In2.Cu")
		(net "M_I_CPU1_SA_DQ<28>")
	)
	(segment
		(start 135.453374 -243.191792)
		(end 135.461756 -243.186966)
		(width 0.0889)
		(layer "In2.Cu")
		(net "M_I_CPU1_SA_DQ<28>")
	)
	(segment
		(start 181.846728 -231.885744)
		(end 182.078376 -231.885744)
		(width 0.14478)
		(layer "In2.Cu")
		(net "M_I_CPU1_SA_DQ<28>")
	)
	(segment
		(start 145.144744 -243.110766)
		(end 145.343626 -243.110766)
		(width 0.0889)
		(layer "In2.Cu")
		(net "M_I_CPU1_SA_DQ<28>")
	)
	(arc
		(start 136.40181 -243.186966)
		(mid 136.684766 -243.110789)
		(end 136.967722 -243.186966)
		(width 0.0889)
		(layer "In2.Cu")
		(net "M_I_CPU1_SA_DQ<28>")
	)
	(arc
		(start 133.216142 -243.191792)
		(mid 133.39965 -243.237286)
		(end 133.581902 -243.186966)
		(width 0.0889)
		(layer "In2.Cu")
		(net "M_I_CPU1_SA_DQ<28>")
	)
	(arc
		(start 141.67612 -243.191792)
		(mid 141.859628 -243.237286)
		(end 142.04188 -243.186966)
		(width 0.0889)
		(layer "In2.Cu")
		(net "M_I_CPU1_SA_DQ<28>")
	)
	(arc
		(start 131.327652 -243.186966)
		(mid 131.509903 -243.237316)
		(end 131.693412 -243.191792)
		(width 0.0889)
		(layer "In2.Cu")
		(net "M_I_CPU1_SA_DQ<28>")
	)
	(arc
		(start 136.976104 -243.191792)
		(mid 137.159612 -243.237286)
		(end 137.341864 -243.186966)
		(width 0.0889)
		(layer "In2.Cu")
		(net "M_I_CPU1_SA_DQ<28>")
	)
	(arc
		(start 139.78763 -243.186966)
		(mid 139.969881 -243.237316)
		(end 140.15339 -243.191792)
		(width 0.0889)
		(layer "In2.Cu")
		(net "M_I_CPU1_SA_DQ<28>")
	)
	(arc
		(start 133.581902 -243.186966)
		(mid 133.864858 -243.110789)
		(end 134.147814 -243.186966)
		(width 0.0889)
		(layer "In2.Cu")
		(net "M_I_CPU1_SA_DQ<28>")
	)
	(arc
		(start 130.387598 -243.186966)
		(mid 130.569849 -243.237316)
		(end 130.753358 -243.191792)
		(width 0.0889)
		(layer "In2.Cu")
		(net "M_I_CPU1_SA_DQ<28>")
	)
	(arc
		(start 132.641848 -243.186966)
		(mid 132.924804 -243.110789)
		(end 133.20776 -243.186966)
		(width 0.0889)
		(layer "In2.Cu")
		(net "M_I_CPU1_SA_DQ<28>")
	)
	(arc
		(start 137.916158 -243.191792)
		(mid 138.099666 -243.237286)
		(end 138.281918 -243.186966)
		(width 0.0889)
		(layer "In2.Cu")
		(net "M_I_CPU1_SA_DQ<28>")
	)
	(arc
		(start 138.281918 -243.186966)
		(mid 138.564874 -243.110789)
		(end 138.84783 -243.186966)
		(width 0.0889)
		(layer "In2.Cu")
		(net "M_I_CPU1_SA_DQ<28>")
	)
	(arc
		(start 134.147814 -243.186966)
		(mid 134.334758 -243.237221)
		(end 134.521702 -243.186966)
		(width 0.0889)
		(layer "In2.Cu")
		(net "M_I_CPU1_SA_DQ<28>")
	)
	(arc
		(start 142.98168 -243.186966)
		(mid 143.264636 -243.110789)
		(end 143.547592 -243.186966)
		(width 0.0889)
		(layer "In2.Cu")
		(net "M_I_CPU1_SA_DQ<28>")
	)
	(arc
		(start 132.276088 -243.191792)
		(mid 132.459596 -243.237286)
		(end 132.641848 -243.186966)
		(width 0.0889)
		(layer "In2.Cu")
		(net "M_I_CPU1_SA_DQ<28>")
	)
	(arc
		(start 140.161772 -243.186966)
		(mid 140.444728 -243.110789)
		(end 140.727684 -243.186966)
		(width 0.0889)
		(layer "In2.Cu")
		(net "M_I_CPU1_SA_DQ<28>")
	)
	(arc
		(start 140.727684 -243.186966)
		(mid 140.909935 -243.237316)
		(end 141.093444 -243.191792)
		(width 0.0889)
		(layer "In2.Cu")
		(net "M_I_CPU1_SA_DQ<28>")
	)
	(arc
		(start 131.701794 -243.186966)
		(mid 131.98475 -243.110789)
		(end 132.267706 -243.186966)
		(width 0.0889)
		(layer "In2.Cu")
		(net "M_I_CPU1_SA_DQ<28>")
	)
	(arc
		(start 129.50317 -243.213128)
		(mid 129.665359 -243.235863)
		(end 129.821686 -243.186966)
		(width 0.0889)
		(layer "In2.Cu")
		(net "M_I_CPU1_SA_DQ<28>")
	)
	(arc
		(start 142.607792 -243.186966)
		(mid 142.794736 -243.237221)
		(end 142.98168 -243.186966)
		(width 0.0889)
		(layer "In2.Cu")
		(net "M_I_CPU1_SA_DQ<28>")
	)
	(arc
		(start 143.547592 -243.186966)
		(mid 143.729843 -243.237316)
		(end 143.913352 -243.191792)
		(width 0.0889)
		(layer "In2.Cu")
		(net "M_I_CPU1_SA_DQ<28>")
	)
	(arc
		(start 137.341864 -243.186966)
		(mid 137.62482 -243.110789)
		(end 137.907776 -243.186966)
		(width 0.0889)
		(layer "In2.Cu")
		(net "M_I_CPU1_SA_DQ<28>")
	)
	(arc
		(start 136.027668 -243.186966)
		(mid 136.209919 -243.237316)
		(end 136.393428 -243.191792)
		(width 0.0889)
		(layer "In2.Cu")
		(net "M_I_CPU1_SA_DQ<28>")
	)
	(arc
		(start 143.932148 -243.18087)
		(mid 144.21058 -243.110772)
		(end 144.487392 -243.186966)
		(width 0.0889)
		(layer "In2.Cu")
		(net "M_I_CPU1_SA_DQ<28>")
	)
	(arc
		(start 134.521702 -243.186966)
		(mid 134.804658 -243.110789)
		(end 135.087614 -243.186966)
		(width 0.0889)
		(layer "In2.Cu")
		(net "M_I_CPU1_SA_DQ<28>")
	)
	(arc
		(start 130.76174 -243.186966)
		(mid 131.044696 -243.110789)
		(end 131.327652 -243.186966)
		(width 0.0889)
		(layer "In2.Cu")
		(net "M_I_CPU1_SA_DQ<28>")
	)
	(arc
		(start 139.221718 -243.186966)
		(mid 139.504674 -243.110789)
		(end 139.78763 -243.186966)
		(width 0.0889)
		(layer "In2.Cu")
		(net "M_I_CPU1_SA_DQ<28>")
	)
	(arc
		(start 141.101826 -243.186966)
		(mid 141.384782 -243.110789)
		(end 141.667738 -243.186966)
		(width 0.0889)
		(layer "In2.Cu")
		(net "M_I_CPU1_SA_DQ<28>")
	)
	(arc
		(start 144.861534 -243.186966)
		(mid 144.998097 -243.130133)
		(end 145.144744 -243.110766)
		(width 0.0889)
		(layer "In2.Cu")
		(net "M_I_CPU1_SA_DQ<28>")
	)
	(arc
		(start 144.495774 -243.191792)
		(mid 144.679282 -243.237286)
		(end 144.861534 -243.186966)
		(width 0.0889)
		(layer "In2.Cu")
		(net "M_I_CPU1_SA_DQ<28>")
	)
	(arc
		(start 129.821686 -243.186966)
		(mid 130.104642 -243.110789)
		(end 130.387598 -243.186966)
		(width 0.0889)
		(layer "In2.Cu")
		(net "M_I_CPU1_SA_DQ<28>")
	)
	(arc
		(start 135.461756 -243.186966)
		(mid 135.744712 -243.110789)
		(end 136.027668 -243.186966)
		(width 0.0889)
		(layer "In2.Cu")
		(net "M_I_CPU1_SA_DQ<28>")
	)
	(arc
		(start 135.087614 -243.186966)
		(mid 135.269865 -243.237316)
		(end 135.453374 -243.191792)
		(width 0.0889)
		(layer "In2.Cu")
		(net "M_I_CPU1_SA_DQ<28>")
	)
	(arc
		(start 142.04188 -243.186966)
		(mid 142.324836 -243.110789)
		(end 142.607792 -243.186966)
		(width 0.0889)
		(layer "In2.Cu")
		(net "M_I_CPU1_SA_DQ<28>")
	)
	(arc
		(start 138.84783 -243.186966)
		(mid 139.034774 -243.237221)
		(end 139.221718 -243.186966)
		(width 0.0889)
		(layer "In2.Cu")
		(net "M_I_CPU1_SA_DQ<28>")
	)
	(segment
		(start 127.287782 -241.510312)
		(end 127.754634 -241.244374)
		(width 0.10668)
		(layer "F.Cu")
		(net "M_I_CPU1_SA_DQ<27>")
	)
	(segment
		(start 157.600142 -234.122722)
		(end 157.761686 -233.961178)
		(width 0.14478)
		(layer "In2.Cu")
		(net "M_I_CPU1_SA_DQ<27>")
	)
	(segment
		(start 140.15339 -240.916968)
		(end 140.161772 -240.921794)
		(width 0.0889)
		(layer "In2.Cu")
		(net "M_I_CPU1_SA_DQ<27>")
	)
	(segment
		(start 136.393428 -240.916968)
		(end 136.40181 -240.921794)
		(width 0.0889)
		(layer "In2.Cu")
		(net "M_I_CPU1_SA_DQ<27>")
	)
	(segment
		(start 166.837106 -227.500688)
		(end 170.2308 -227.500688)
		(width 0.14478)
		(layer "In2.Cu")
		(net "M_I_CPU1_SA_DQ<27>")
	)
	(segment
		(start 141.093444 -240.916968)
		(end 141.101826 -240.921794)
		(width 0.0889)
		(layer "In2.Cu")
		(net "M_I_CPU1_SA_DQ<27>")
	)
	(segment
		(start 127.908812 -240.978944)
		(end 128.005078 -240.953544)
		(width 0.0889)
		(layer "In2.Cu")
		(net "M_I_CPU1_SA_DQ<27>")
	)
	(segment
		(start 171.080684 -228.350572)
		(end 173.525688 -228.350572)
		(width 0.14478)
		(layer "In2.Cu")
		(net "M_I_CPU1_SA_DQ<27>")
	)
	(segment
		(start 146.365468 -240.010696)
		(end 146.365468 -239.719104)
		(width 0.0889)
		(layer "In2.Cu")
		(net "M_I_CPU1_SA_DQ<27>")
	)
	(segment
		(start 156.518864 -233.821732)
		(end 156.680408 -233.660188)
		(width 0.14478)
		(layer "In2.Cu")
		(net "M_I_CPU1_SA_DQ<27>")
	)
	(segment
		(start 157.371542 -234.122722)
		(end 157.600142 -234.122722)
		(width 0.14478)
		(layer "In2.Cu")
		(net "M_I_CPU1_SA_DQ<27>")
	)
	(segment
		(start 174.375572 -227.500688)
		(end 179.08143 -227.500688)
		(width 0.14478)
		(layer "In2.Cu")
		(net "M_I_CPU1_SA_DQ<27>")
	)
	(segment
		(start 157.299152 -233.270044)
		(end 157.299152 -233.041444)
		(width 0.14478)
		(layer "In2.Cu")
		(net "M_I_CPU1_SA_DQ<27>")
	)
	(segment
		(start 160.99155 -230.731314)
		(end 160.99155 -230.212646)
		(width 0.14478)
		(layer "In2.Cu")
		(net "M_I_CPU1_SA_DQ<27>")
	)
	(segment
		(start 155.398724 -234.928156)
		(end 156.794708 -234.928156)
		(width 0.14478)
		(layer "In2.Cu")
		(net "M_I_CPU1_SA_DQ<27>")
	)
	(segment
		(start 156.518864 -234.050332)
		(end 156.518864 -233.821732)
		(width 0.14478)
		(layer "In2.Cu")
		(net "M_I_CPU1_SA_DQ<27>")
	)
	(segment
		(start 146.553428 -239.531144)
		(end 147.526248 -239.531144)
		(width 0.0889)
		(layer "In2.Cu")
		(net "M_I_CPU1_SA_DQ<27>")
	)
	(segment
		(start 145.54327 -240.832894)
		(end 146.365468 -240.010696)
		(width 0.0889)
		(layer "In2.Cu")
		(net "M_I_CPU1_SA_DQ<27>")
	)
	(segment
		(start 137.907776 -240.921794)
		(end 137.916158 -240.916968)
		(width 0.0889)
		(layer "In2.Cu")
		(net "M_I_CPU1_SA_DQ<27>")
	)
	(segment
		(start 156.981398 -234.741466)
		(end 156.981398 -234.512866)
		(width 0.14478)
		(layer "In2.Cu")
		(net "M_I_CPU1_SA_DQ<27>")
	)
	(segment
		(start 145.412714 -240.93043)
		(end 145.427446 -240.921794)
		(width 0.0889)
		(layer "In2.Cu")
		(net "M_I_CPU1_SA_DQ<27>")
	)
	(segment
		(start 157.761686 -233.961178)
		(end 157.761686 -233.732578)
		(width 0.14478)
		(layer "In2.Cu")
		(net "M_I_CPU1_SA_DQ<27>")
	)
	(segment
		(start 160.99155 -230.212646)
		(end 162.853624 -228.350572)
		(width 0.14478)
		(layer "In2.Cu")
		(net "M_I_CPU1_SA_DQ<27>")
	)
	(segment
		(start 136.967722 -240.921794)
		(end 136.976104 -240.916968)
		(width 0.0889)
		(layer "In2.Cu")
		(net "M_I_CPU1_SA_DQ<27>")
	)
	(segment
		(start 158.38043 -233.342434)
		(end 160.99155 -230.731314)
		(width 0.14478)
		(layer "In2.Cu")
		(net "M_I_CPU1_SA_DQ<27>")
	)
	(segment
		(start 156.680408 -233.660188)
		(end 156.909008 -233.660188)
		(width 0.14478)
		(layer "In2.Cu")
		(net "M_I_CPU1_SA_DQ<27>")
	)
	(segment
		(start 157.460696 -232.8799)
		(end 157.689296 -232.8799)
		(width 0.14478)
		(layer "In2.Cu")
		(net "M_I_CPU1_SA_DQ<27>")
	)
	(segment
		(start 143.913352 -240.916968)
		(end 143.921734 -240.921794)
		(width 0.0889)
		(layer "In2.Cu")
		(net "M_I_CPU1_SA_DQ<27>")
	)
	(segment
		(start 162.853624 -228.350572)
		(end 165.987222 -228.350572)
		(width 0.14478)
		(layer "In2.Cu")
		(net "M_I_CPU1_SA_DQ<27>")
	)
	(segment
		(start 143.921734 -240.921794)
		(end 143.932148 -240.92789)
		(width 0.0889)
		(layer "In2.Cu")
		(net "M_I_CPU1_SA_DQ<27>")
	)
	(segment
		(start 173.525688 -228.350572)
		(end 174.375572 -227.500688)
		(width 0.14478)
		(layer "In2.Cu")
		(net "M_I_CPU1_SA_DQ<27>")
	)
	(segment
		(start 133.20776 -240.921794)
		(end 133.216142 -240.916968)
		(width 0.0889)
		(layer "In2.Cu")
		(net "M_I_CPU1_SA_DQ<27>")
	)
	(segment
		(start 130.753358 -240.916968)
		(end 130.76174 -240.921794)
		(width 0.0889)
		(layer "In2.Cu")
		(net "M_I_CPU1_SA_DQ<27>")
	)
	(segment
		(start 144.487392 -240.921794)
		(end 144.495774 -240.916968)
		(width 0.0889)
		(layer "In2.Cu")
		(net "M_I_CPU1_SA_DQ<27>")
	)
	(segment
		(start 147.526248 -239.531144)
		(end 147.579588 -239.477804)
		(width 0.0889)
		(layer "In2.Cu")
		(net "M_I_CPU1_SA_DQ<27>")
	)
	(segment
		(start 150.849076 -239.477804)
		(end 155.398724 -234.928156)
		(width 0.14478)
		(layer "In2.Cu")
		(net "M_I_CPU1_SA_DQ<27>")
	)
	(segment
		(start 165.987222 -228.350572)
		(end 166.837106 -227.500688)
		(width 0.14478)
		(layer "In2.Cu")
		(net "M_I_CPU1_SA_DQ<27>")
	)
	(segment
		(start 179.08143 -227.500688)
		(end 179.516024 -227.935282)
		(width 0.14478)
		(layer "In2.Cu")
		(net "M_I_CPU1_SA_DQ<27>")
	)
	(segment
		(start 128.507744 -240.921794)
		(end 128.516126 -240.916968)
		(width 0.0889)
		(layer "In2.Cu")
		(net "M_I_CPU1_SA_DQ<27>")
	)
	(segment
		(start 141.667738 -240.921794)
		(end 141.67612 -240.916968)
		(width 0.0889)
		(layer "In2.Cu")
		(net "M_I_CPU1_SA_DQ<27>")
	)
	(segment
		(start 156.909008 -233.660188)
		(end 157.371542 -234.122722)
		(width 0.14478)
		(layer "In2.Cu")
		(net "M_I_CPU1_SA_DQ<27>")
	)
	(segment
		(start 147.579588 -239.477804)
		(end 147.944586 -239.477804)
		(width 0.0889)
		(layer "In2.Cu")
		(net "M_I_CPU1_SA_DQ<27>")
	)
	(segment
		(start 147.944586 -239.477804)
		(end 150.849076 -239.477804)
		(width 0.14478)
		(layer "In2.Cu")
		(net "M_I_CPU1_SA_DQ<27>")
	)
	(segment
		(start 135.453374 -240.916968)
		(end 135.461756 -240.921794)
		(width 0.0889)
		(layer "In2.Cu")
		(net "M_I_CPU1_SA_DQ<27>")
	)
	(segment
		(start 158.15183 -233.342434)
		(end 158.38043 -233.342434)
		(width 0.14478)
		(layer "In2.Cu")
		(net "M_I_CPU1_SA_DQ<27>")
	)
	(segment
		(start 132.267706 -240.921794)
		(end 132.276088 -240.916968)
		(width 0.0889)
		(layer "In2.Cu")
		(net "M_I_CPU1_SA_DQ<27>")
	)
	(segment
		(start 157.689296 -232.8799)
		(end 158.15183 -233.342434)
		(width 0.14478)
		(layer "In2.Cu")
		(net "M_I_CPU1_SA_DQ<27>")
	)
	(segment
		(start 156.794708 -234.928156)
		(end 156.981398 -234.741466)
		(width 0.14478)
		(layer "In2.Cu")
		(net "M_I_CPU1_SA_DQ<27>")
	)
	(segment
		(start 157.299152 -233.041444)
		(end 157.460696 -232.8799)
		(width 0.14478)
		(layer "In2.Cu")
		(net "M_I_CPU1_SA_DQ<27>")
	)
	(segment
		(start 146.365468 -239.719104)
		(end 146.553428 -239.531144)
		(width 0.0889)
		(layer "In2.Cu")
		(net "M_I_CPU1_SA_DQ<27>")
	)
	(segment
		(start 157.761686 -233.732578)
		(end 157.299152 -233.270044)
		(width 0.14478)
		(layer "In2.Cu")
		(net "M_I_CPU1_SA_DQ<27>")
	)
	(segment
		(start 156.981398 -234.512866)
		(end 156.518864 -234.050332)
		(width 0.14478)
		(layer "In2.Cu")
		(net "M_I_CPU1_SA_DQ<27>")
	)
	(segment
		(start 127.754634 -241.244374)
		(end 127.908812 -240.978944)
		(width 0.0889)
		(layer "In2.Cu")
		(net "M_I_CPU1_SA_DQ<27>")
	)
	(segment
		(start 170.2308 -227.500688)
		(end 171.080684 -228.350572)
		(width 0.14478)
		(layer "In2.Cu")
		(net "M_I_CPU1_SA_DQ<27>")
	)
	(segment
		(start 131.693412 -240.916968)
		(end 131.701794 -240.921794)
		(width 0.0889)
		(layer "In2.Cu")
		(net "M_I_CPU1_SA_DQ<27>")
	)
	(arc
		(start 144.861534 -240.921794)
		(mid 145.135986 -240.99803)
		(end 145.412714 -240.93043)
		(width 0.0889)
		(layer "In2.Cu")
		(net "M_I_CPU1_SA_DQ<27>")
	)
	(arc
		(start 141.101826 -240.921794)
		(mid 141.384782 -240.997971)
		(end 141.667738 -240.921794)
		(width 0.0889)
		(layer "In2.Cu")
		(net "M_I_CPU1_SA_DQ<27>")
	)
	(arc
		(start 142.607792 -240.921794)
		(mid 142.794736 -240.871539)
		(end 142.98168 -240.921794)
		(width 0.0889)
		(layer "In2.Cu")
		(net "M_I_CPU1_SA_DQ<27>")
	)
	(arc
		(start 143.547592 -240.921794)
		(mid 143.729843 -240.871444)
		(end 143.913352 -240.916968)
		(width 0.0889)
		(layer "In2.Cu")
		(net "M_I_CPU1_SA_DQ<27>")
	)
	(arc
		(start 140.161772 -240.921794)
		(mid 140.444728 -240.997971)
		(end 140.727684 -240.921794)
		(width 0.0889)
		(layer "In2.Cu")
		(net "M_I_CPU1_SA_DQ<27>")
	)
	(arc
		(start 139.221718 -240.921794)
		(mid 139.504674 -240.997971)
		(end 139.78763 -240.921794)
		(width 0.0889)
		(layer "In2.Cu")
		(net "M_I_CPU1_SA_DQ<27>")
	)
	(arc
		(start 134.147814 -240.921794)
		(mid 134.334758 -240.871539)
		(end 134.521702 -240.921794)
		(width 0.0889)
		(layer "In2.Cu")
		(net "M_I_CPU1_SA_DQ<27>")
	)
	(arc
		(start 141.67612 -240.916968)
		(mid 141.859628 -240.871474)
		(end 142.04188 -240.921794)
		(width 0.0889)
		(layer "In2.Cu")
		(net "M_I_CPU1_SA_DQ<27>")
	)
	(arc
		(start 130.76174 -240.921794)
		(mid 131.044696 -240.997971)
		(end 131.327652 -240.921794)
		(width 0.0889)
		(layer "In2.Cu")
		(net "M_I_CPU1_SA_DQ<27>")
	)
	(arc
		(start 136.027668 -240.921794)
		(mid 136.209919 -240.871444)
		(end 136.393428 -240.916968)
		(width 0.0889)
		(layer "In2.Cu")
		(net "M_I_CPU1_SA_DQ<27>")
	)
	(arc
		(start 138.84783 -240.921794)
		(mid 139.034774 -240.871539)
		(end 139.221718 -240.921794)
		(width 0.0889)
		(layer "In2.Cu")
		(net "M_I_CPU1_SA_DQ<27>")
	)
	(arc
		(start 137.916158 -240.916968)
		(mid 138.099666 -240.871474)
		(end 138.281918 -240.921794)
		(width 0.0889)
		(layer "In2.Cu")
		(net "M_I_CPU1_SA_DQ<27>")
	)
	(arc
		(start 136.976104 -240.916968)
		(mid 137.159612 -240.871474)
		(end 137.341864 -240.921794)
		(width 0.0889)
		(layer "In2.Cu")
		(net "M_I_CPU1_SA_DQ<27>")
	)
	(arc
		(start 128.516126 -240.916968)
		(mid 128.699634 -240.871474)
		(end 128.881886 -240.921794)
		(width 0.0889)
		(layer "In2.Cu")
		(net "M_I_CPU1_SA_DQ<27>")
	)
	(arc
		(start 131.701794 -240.921794)
		(mid 131.98475 -240.997971)
		(end 132.267706 -240.921794)
		(width 0.0889)
		(layer "In2.Cu")
		(net "M_I_CPU1_SA_DQ<27>")
	)
	(arc
		(start 128.881886 -240.921794)
		(mid 129.164842 -240.997971)
		(end 129.447798 -240.921794)
		(width 0.0889)
		(layer "In2.Cu")
		(net "M_I_CPU1_SA_DQ<27>")
	)
	(arc
		(start 139.78763 -240.921794)
		(mid 139.969881 -240.871444)
		(end 140.15339 -240.916968)
		(width 0.0889)
		(layer "In2.Cu")
		(net "M_I_CPU1_SA_DQ<27>")
	)
	(arc
		(start 137.341864 -240.921794)
		(mid 137.62482 -240.997971)
		(end 137.907776 -240.921794)
		(width 0.0889)
		(layer "In2.Cu")
		(net "M_I_CPU1_SA_DQ<27>")
	)
	(arc
		(start 136.40181 -240.921794)
		(mid 136.684766 -240.997971)
		(end 136.967722 -240.921794)
		(width 0.0889)
		(layer "In2.Cu")
		(net "M_I_CPU1_SA_DQ<27>")
	)
	(arc
		(start 133.216142 -240.916968)
		(mid 133.39965 -240.871474)
		(end 133.581902 -240.921794)
		(width 0.0889)
		(layer "In2.Cu")
		(net "M_I_CPU1_SA_DQ<27>")
	)
	(arc
		(start 142.04188 -240.921794)
		(mid 142.324836 -240.997971)
		(end 142.607792 -240.921794)
		(width 0.0889)
		(layer "In2.Cu")
		(net "M_I_CPU1_SA_DQ<27>")
	)
	(arc
		(start 143.932148 -240.92789)
		(mid 144.21058 -240.997988)
		(end 144.487392 -240.921794)
		(width 0.0889)
		(layer "In2.Cu")
		(net "M_I_CPU1_SA_DQ<27>")
	)
	(arc
		(start 132.641848 -240.921794)
		(mid 132.924804 -240.997971)
		(end 133.20776 -240.921794)
		(width 0.0889)
		(layer "In2.Cu")
		(net "M_I_CPU1_SA_DQ<27>")
	)
	(arc
		(start 135.087614 -240.921794)
		(mid 135.269865 -240.871444)
		(end 135.453374 -240.916968)
		(width 0.0889)
		(layer "In2.Cu")
		(net "M_I_CPU1_SA_DQ<27>")
	)
	(arc
		(start 142.98168 -240.921794)
		(mid 143.264636 -240.997971)
		(end 143.547592 -240.921794)
		(width 0.0889)
		(layer "In2.Cu")
		(net "M_I_CPU1_SA_DQ<27>")
	)
	(arc
		(start 135.461756 -240.921794)
		(mid 135.744712 -240.997971)
		(end 136.027668 -240.921794)
		(width 0.0889)
		(layer "In2.Cu")
		(net "M_I_CPU1_SA_DQ<27>")
	)
	(arc
		(start 140.727684 -240.921794)
		(mid 140.909935 -240.871444)
		(end 141.093444 -240.916968)
		(width 0.0889)
		(layer "In2.Cu")
		(net "M_I_CPU1_SA_DQ<27>")
	)
	(arc
		(start 144.495774 -240.916968)
		(mid 144.679282 -240.871474)
		(end 144.861534 -240.921794)
		(width 0.0889)
		(layer "In2.Cu")
		(net "M_I_CPU1_SA_DQ<27>")
	)
	(arc
		(start 129.447798 -240.921794)
		(mid 129.634742 -240.871539)
		(end 129.821686 -240.921794)
		(width 0.0889)
		(layer "In2.Cu")
		(net "M_I_CPU1_SA_DQ<27>")
	)
	(arc
		(start 133.581902 -240.921794)
		(mid 133.864858 -240.997971)
		(end 134.147814 -240.921794)
		(width 0.0889)
		(layer "In2.Cu")
		(net "M_I_CPU1_SA_DQ<27>")
	)
	(arc
		(start 130.387598 -240.921794)
		(mid 130.569849 -240.871444)
		(end 130.753358 -240.916968)
		(width 0.0889)
		(layer "In2.Cu")
		(net "M_I_CPU1_SA_DQ<27>")
	)
	(arc
		(start 132.276088 -240.916968)
		(mid 132.459596 -240.871474)
		(end 132.641848 -240.921794)
		(width 0.0889)
		(layer "In2.Cu")
		(net "M_I_CPU1_SA_DQ<27>")
	)
	(arc
		(start 128.005078 -240.953544)
		(mid 128.260143 -240.996895)
		(end 128.507744 -240.921794)
		(width 0.0889)
		(layer "In2.Cu")
		(net "M_I_CPU1_SA_DQ<27>")
	)
	(arc
		(start 129.821686 -240.921794)
		(mid 130.104642 -240.997971)
		(end 130.387598 -240.921794)
		(width 0.0889)
		(layer "In2.Cu")
		(net "M_I_CPU1_SA_DQ<27>")
	)
	(arc
		(start 138.281918 -240.921794)
		(mid 138.564874 -240.997971)
		(end 138.84783 -240.921794)
		(width 0.0889)
		(layer "In2.Cu")
		(net "M_I_CPU1_SA_DQ<27>")
	)
	(arc
		(start 145.427446 -240.921794)
		(mid 145.488256 -240.881119)
		(end 145.54327 -240.832894)
		(width 0.0889)
		(layer "In2.Cu")
		(net "M_I_CPU1_SA_DQ<27>")
	)
	(arc
		(start 131.327652 -240.921794)
		(mid 131.509903 -240.871444)
		(end 131.693412 -240.916968)
		(width 0.0889)
		(layer "In2.Cu")
		(net "M_I_CPU1_SA_DQ<27>")
	)
	(arc
		(start 134.521702 -240.921794)
		(mid 134.804658 -240.997971)
		(end 135.087614 -240.921794)
		(width 0.0889)
		(layer "In2.Cu")
		(net "M_I_CPU1_SA_DQ<27>")
	)
	(segment
		(start 128.69799 -240.700306)
		(end 129.164842 -240.434368)
		(width 0.10668)
		(layer "F.Cu")
		(net "M_I_CPU1_SA_DQ<26>")
	)
	(segment
		(start 166.541704 -225.810318)
		(end 170.055032 -225.810318)
		(width 0.14478)
		(layer "In2.Cu")
		(net "M_I_CPU1_SA_DQ<26>")
	)
	(segment
		(start 145.811748 -239.508284)
		(end 146.345148 -238.974884)
		(width 0.0889)
		(layer "In2.Cu")
		(net "M_I_CPU1_SA_DQ<26>")
	)
	(segment
		(start 133.103366 -240.106962)
		(end 133.111748 -240.111788)
		(width 0.0889)
		(layer "In2.Cu")
		(net "M_I_CPU1_SA_DQ<26>")
	)
	(segment
		(start 159.577024 -229.699312)
		(end 159.577024 -229.470712)
		(width 0.14478)
		(layer "In2.Cu")
		(net "M_I_CPU1_SA_DQ<26>")
	)
	(segment
		(start 165.691566 -226.660456)
		(end 166.541704 -225.810318)
		(width 0.14478)
		(layer "In2.Cu")
		(net "M_I_CPU1_SA_DQ<26>")
	)
	(segment
		(start 170.055032 -225.810318)
		(end 170.90517 -226.660456)
		(width 0.14478)
		(layer "In2.Cu")
		(net "M_I_CPU1_SA_DQ<26>")
	)
	(segment
		(start 147.622768 -238.553244)
		(end 147.919186 -238.553244)
		(width 0.0889)
		(layer "In2.Cu")
		(net "M_I_CPU1_SA_DQ<26>")
	)
	(segment
		(start 146.345148 -238.974884)
		(end 147.201128 -238.974884)
		(width 0.0889)
		(layer "In2.Cu")
		(net "M_I_CPU1_SA_DQ<26>")
	)
	(segment
		(start 159.8676 -230.541576)
		(end 160.029144 -230.380032)
		(width 0.14478)
		(layer "In2.Cu")
		(net "M_I_CPU1_SA_DQ<26>")
	)
	(segment
		(start 145.56867 -240.061242)
		(end 145.811748 -239.818164)
		(width 0.0889)
		(layer "In2.Cu")
		(net "M_I_CPU1_SA_DQ<26>")
	)
	(segment
		(start 138.743436 -240.106962)
		(end 138.751818 -240.111788)
		(width 0.0889)
		(layer "In2.Cu")
		(net "M_I_CPU1_SA_DQ<26>")
	)
	(segment
		(start 158.347156 -231.819196)
		(end 158.347156 -231.590596)
		(width 0.14478)
		(layer "In2.Cu")
		(net "M_I_CPU1_SA_DQ<26>")
	)
	(segment
		(start 157.626304 -231.650032)
		(end 157.957012 -231.98074)
		(width 0.14478)
		(layer "In2.Cu")
		(net "M_I_CPU1_SA_DQ<26>")
	)
	(segment
		(start 158.796736 -230.251)
		(end 158.95828 -230.089456)
		(width 0.14478)
		(layer "In2.Cu")
		(net "M_I_CPU1_SA_DQ<26>")
	)
	(segment
		(start 137.803382 -240.106962)
		(end 137.811764 -240.111788)
		(width 0.0889)
		(layer "In2.Cu")
		(net "M_I_CPU1_SA_DQ<26>")
	)
	(segment
		(start 158.185612 -231.98074)
		(end 158.347156 -231.819196)
		(width 0.14478)
		(layer "In2.Cu")
		(net "M_I_CPU1_SA_DQ<26>")
	)
	(segment
		(start 158.016448 -231.031288)
		(end 158.177992 -230.869744)
		(width 0.14478)
		(layer "In2.Cu")
		(net "M_I_CPU1_SA_DQ<26>")
	)
	(segment
		(start 173.62424 -226.660456)
		(end 174.474378 -225.810318)
		(width 0.14478)
		(layer "In2.Cu")
		(net "M_I_CPU1_SA_DQ<26>")
	)
	(segment
		(start 159.248856 -230.93172)
		(end 158.796736 -230.4796)
		(width 0.14478)
		(layer "In2.Cu")
		(net "M_I_CPU1_SA_DQ<26>")
	)
	(segment
		(start 129.917698 -240.111788)
		(end 129.92608 -240.106962)
		(width 0.0889)
		(layer "In2.Cu")
		(net "M_I_CPU1_SA_DQ<26>")
	)
	(segment
		(start 147.919186 -238.553244)
		(end 150.494492 -238.553244)
		(width 0.14478)
		(layer "In2.Cu")
		(net "M_I_CPU1_SA_DQ<26>")
	)
	(segment
		(start 158.796736 -230.4796)
		(end 158.796736 -230.251)
		(width 0.14478)
		(layer "In2.Cu")
		(net "M_I_CPU1_SA_DQ<26>")
	)
	(segment
		(start 144.39138 -240.111788)
		(end 144.401794 -240.117884)
		(width 0.0889)
		(layer "In2.Cu")
		(net "M_I_CPU1_SA_DQ<26>")
	)
	(segment
		(start 150.494492 -238.553244)
		(end 157.397704 -231.650032)
		(width 0.14478)
		(layer "In2.Cu")
		(net "M_I_CPU1_SA_DQ<26>")
	)
	(segment
		(start 145.144744 -240.061242)
		(end 145.56867 -240.061242)
		(width 0.0889)
		(layer "In2.Cu")
		(net "M_I_CPU1_SA_DQ<26>")
	)
	(segment
		(start 145.811748 -239.818164)
		(end 145.811748 -239.508284)
		(width 0.0889)
		(layer "In2.Cu")
		(net "M_I_CPU1_SA_DQ<26>")
	)
	(segment
		(start 179.091082 -225.810318)
		(end 179.516024 -226.23526)
		(width 0.14478)
		(layer "In2.Cu")
		(net "M_I_CPU1_SA_DQ<26>")
	)
	(segment
		(start 158.95828 -230.089456)
		(end 159.18688 -230.089456)
		(width 0.14478)
		(layer "In2.Cu")
		(net "M_I_CPU1_SA_DQ<26>")
	)
	(segment
		(start 130.857752 -240.111788)
		(end 130.866134 -240.106962)
		(width 0.0889)
		(layer "In2.Cu")
		(net "M_I_CPU1_SA_DQ<26>")
	)
	(segment
		(start 158.016448 -231.259888)
		(end 158.016448 -231.031288)
		(width 0.14478)
		(layer "In2.Cu")
		(net "M_I_CPU1_SA_DQ<26>")
	)
	(segment
		(start 158.858712 -231.321864)
		(end 159.087312 -231.321864)
		(width 0.14478)
		(layer "In2.Cu")
		(net "M_I_CPU1_SA_DQ<26>")
	)
	(segment
		(start 170.90517 -226.660456)
		(end 173.62424 -226.660456)
		(width 0.14478)
		(layer "In2.Cu")
		(net "M_I_CPU1_SA_DQ<26>")
	)
	(segment
		(start 129.164842 -240.434368)
		(end 129.318766 -240.168938)
		(width 0.0889)
		(layer "In2.Cu")
		(net "M_I_CPU1_SA_DQ<26>")
	)
	(segment
		(start 134.617714 -240.111788)
		(end 134.626096 -240.106962)
		(width 0.0889)
		(layer "In2.Cu")
		(net "M_I_CPU1_SA_DQ<26>")
	)
	(segment
		(start 129.318766 -240.168938)
		(end 129.414778 -240.143538)
		(width 0.0889)
		(layer "In2.Cu")
		(net "M_I_CPU1_SA_DQ<26>")
	)
	(segment
		(start 160.165542 -229.507542)
		(end 160.370774 -229.507542)
		(width 0.14478)
		(layer "In2.Cu")
		(net "M_I_CPU1_SA_DQ<26>")
	)
	(segment
		(start 142.503398 -240.106962)
		(end 142.51178 -240.111788)
		(width 0.0889)
		(layer "In2.Cu")
		(net "M_I_CPU1_SA_DQ<26>")
	)
	(segment
		(start 159.577024 -229.470712)
		(end 159.738568 -229.309168)
		(width 0.14478)
		(layer "In2.Cu")
		(net "M_I_CPU1_SA_DQ<26>")
	)
	(segment
		(start 160.029144 -230.151432)
		(end 159.577024 -229.699312)
		(width 0.14478)
		(layer "In2.Cu")
		(net "M_I_CPU1_SA_DQ<26>")
	)
	(segment
		(start 134.04342 -240.106962)
		(end 134.051802 -240.111788)
		(width 0.0889)
		(layer "In2.Cu")
		(net "M_I_CPU1_SA_DQ<26>")
	)
	(segment
		(start 174.474378 -225.810318)
		(end 179.091082 -225.810318)
		(width 0.14478)
		(layer "In2.Cu")
		(net "M_I_CPU1_SA_DQ<26>")
	)
	(segment
		(start 144.007078 -240.117884)
		(end 144.017492 -240.111788)
		(width 0.0889)
		(layer "In2.Cu")
		(net "M_I_CPU1_SA_DQ<26>")
	)
	(segment
		(start 160.029144 -230.380032)
		(end 160.029144 -230.151432)
		(width 0.14478)
		(layer "In2.Cu")
		(net "M_I_CPU1_SA_DQ<26>")
	)
	(segment
		(start 139.31773 -240.111788)
		(end 139.326112 -240.106962)
		(width 0.0889)
		(layer "In2.Cu")
		(net "M_I_CPU1_SA_DQ<26>")
	)
	(segment
		(start 159.967168 -229.309168)
		(end 160.165542 -229.507542)
		(width 0.14478)
		(layer "In2.Cu")
		(net "M_I_CPU1_SA_DQ<26>")
	)
	(segment
		(start 147.201128 -238.974884)
		(end 147.622768 -238.553244)
		(width 0.0889)
		(layer "In2.Cu")
		(net "M_I_CPU1_SA_DQ<26>")
	)
	(segment
		(start 159.639 -230.541576)
		(end 159.8676 -230.541576)
		(width 0.14478)
		(layer "In2.Cu")
		(net "M_I_CPU1_SA_DQ<26>")
	)
	(segment
		(start 157.957012 -231.98074)
		(end 158.185612 -231.98074)
		(width 0.14478)
		(layer "In2.Cu")
		(net "M_I_CPU1_SA_DQ<26>")
	)
	(segment
		(start 157.397704 -231.650032)
		(end 157.626304 -231.650032)
		(width 0.14478)
		(layer "In2.Cu")
		(net "M_I_CPU1_SA_DQ<26>")
	)
	(segment
		(start 158.347156 -231.590596)
		(end 158.016448 -231.259888)
		(width 0.14478)
		(layer "In2.Cu")
		(net "M_I_CPU1_SA_DQ<26>")
	)
	(segment
		(start 143.077692 -240.111788)
		(end 143.086074 -240.106962)
		(width 0.0889)
		(layer "In2.Cu")
		(net "M_I_CPU1_SA_DQ<26>")
	)
	(segment
		(start 159.738568 -229.309168)
		(end 159.967168 -229.309168)
		(width 0.14478)
		(layer "In2.Cu")
		(net "M_I_CPU1_SA_DQ<26>")
	)
	(segment
		(start 159.087312 -231.321864)
		(end 159.248856 -231.16032)
		(width 0.14478)
		(layer "In2.Cu")
		(net "M_I_CPU1_SA_DQ<26>")
	)
	(segment
		(start 135.557768 -240.111788)
		(end 135.56615 -240.106962)
		(width 0.0889)
		(layer "In2.Cu")
		(net "M_I_CPU1_SA_DQ<26>")
	)
	(segment
		(start 163.21786 -226.660456)
		(end 165.691566 -226.660456)
		(width 0.14478)
		(layer "In2.Cu")
		(net "M_I_CPU1_SA_DQ<26>")
	)
	(segment
		(start 158.177992 -230.869744)
		(end 158.406592 -230.869744)
		(width 0.14478)
		(layer "In2.Cu")
		(net "M_I_CPU1_SA_DQ<26>")
	)
	(segment
		(start 140.257784 -240.111788)
		(end 140.266166 -240.106962)
		(width 0.0889)
		(layer "In2.Cu")
		(net "M_I_CPU1_SA_DQ<26>")
	)
	(segment
		(start 160.370774 -229.507542)
		(end 163.21786 -226.660456)
		(width 0.14478)
		(layer "In2.Cu")
		(net "M_I_CPU1_SA_DQ<26>")
	)
	(segment
		(start 159.18688 -230.089456)
		(end 159.639 -230.541576)
		(width 0.14478)
		(layer "In2.Cu")
		(net "M_I_CPU1_SA_DQ<26>")
	)
	(segment
		(start 158.406592 -230.869744)
		(end 158.858712 -231.321864)
		(width 0.14478)
		(layer "In2.Cu")
		(net "M_I_CPU1_SA_DQ<26>")
	)
	(segment
		(start 159.248856 -231.16032)
		(end 159.248856 -230.93172)
		(width 0.14478)
		(layer "In2.Cu")
		(net "M_I_CPU1_SA_DQ<26>")
	)
	(arc
		(start 140.266166 -240.106962)
		(mid 140.449674 -240.061468)
		(end 140.631926 -240.111788)
		(width 0.0889)
		(layer "In2.Cu")
		(net "M_I_CPU1_SA_DQ<26>")
	)
	(arc
		(start 136.87171 -240.111788)
		(mid 137.154666 -240.187965)
		(end 137.437622 -240.111788)
		(width 0.0889)
		(layer "In2.Cu")
		(net "M_I_CPU1_SA_DQ<26>")
	)
	(arc
		(start 133.67766 -240.111788)
		(mid 133.859911 -240.061438)
		(end 134.04342 -240.106962)
		(width 0.0889)
		(layer "In2.Cu")
		(net "M_I_CPU1_SA_DQ<26>")
	)
	(arc
		(start 135.93191 -240.111788)
		(mid 136.214866 -240.187965)
		(end 136.497822 -240.111788)
		(width 0.0889)
		(layer "In2.Cu")
		(net "M_I_CPU1_SA_DQ<26>")
	)
	(arc
		(start 141.571726 -240.111788)
		(mid 141.854682 -240.187965)
		(end 142.137638 -240.111788)
		(width 0.0889)
		(layer "In2.Cu")
		(net "M_I_CPU1_SA_DQ<26>")
	)
	(arc
		(start 130.29184 -240.111788)
		(mid 130.574796 -240.187965)
		(end 130.857752 -240.111788)
		(width 0.0889)
		(layer "In2.Cu")
		(net "M_I_CPU1_SA_DQ<26>")
	)
	(arc
		(start 129.414778 -240.143538)
		(mid 129.669986 -240.187015)
		(end 129.917698 -240.111788)
		(width 0.0889)
		(layer "In2.Cu")
		(net "M_I_CPU1_SA_DQ<26>")
	)
	(arc
		(start 141.197838 -240.111788)
		(mid 141.384782 -240.061533)
		(end 141.571726 -240.111788)
		(width 0.0889)
		(layer "In2.Cu")
		(net "M_I_CPU1_SA_DQ<26>")
	)
	(arc
		(start 142.51178 -240.111788)
		(mid 142.794736 -240.187965)
		(end 143.077692 -240.111788)
		(width 0.0889)
		(layer "In2.Cu")
		(net "M_I_CPU1_SA_DQ<26>")
	)
	(arc
		(start 134.051802 -240.111788)
		(mid 134.334758 -240.187965)
		(end 134.617714 -240.111788)
		(width 0.0889)
		(layer "In2.Cu")
		(net "M_I_CPU1_SA_DQ<26>")
	)
	(arc
		(start 142.137638 -240.111788)
		(mid 142.319889 -240.061438)
		(end 142.503398 -240.106962)
		(width 0.0889)
		(layer "In2.Cu")
		(net "M_I_CPU1_SA_DQ<26>")
	)
	(arc
		(start 131.797806 -240.111788)
		(mid 131.98475 -240.061533)
		(end 132.171694 -240.111788)
		(width 0.0889)
		(layer "In2.Cu")
		(net "M_I_CPU1_SA_DQ<26>")
	)
	(arc
		(start 143.086074 -240.106962)
		(mid 143.269582 -240.061468)
		(end 143.451834 -240.111788)
		(width 0.0889)
		(layer "In2.Cu")
		(net "M_I_CPU1_SA_DQ<26>")
	)
	(arc
		(start 144.017492 -240.111788)
		(mid 144.204436 -240.061533)
		(end 144.39138 -240.111788)
		(width 0.0889)
		(layer "In2.Cu")
		(net "M_I_CPU1_SA_DQ<26>")
	)
	(arc
		(start 140.631926 -240.111788)
		(mid 140.914882 -240.187965)
		(end 141.197838 -240.111788)
		(width 0.0889)
		(layer "In2.Cu")
		(net "M_I_CPU1_SA_DQ<26>")
	)
	(arc
		(start 129.92608 -240.106962)
		(mid 130.109588 -240.061468)
		(end 130.29184 -240.111788)
		(width 0.0889)
		(layer "In2.Cu")
		(net "M_I_CPU1_SA_DQ<26>")
	)
	(arc
		(start 132.171694 -240.111788)
		(mid 132.45465 -240.187965)
		(end 132.737606 -240.111788)
		(width 0.0889)
		(layer "In2.Cu")
		(net "M_I_CPU1_SA_DQ<26>")
	)
	(arc
		(start 138.751818 -240.111788)
		(mid 139.034774 -240.187965)
		(end 139.31773 -240.111788)
		(width 0.0889)
		(layer "In2.Cu")
		(net "M_I_CPU1_SA_DQ<26>")
	)
	(arc
		(start 130.866134 -240.106962)
		(mid 131.049642 -240.061468)
		(end 131.231894 -240.111788)
		(width 0.0889)
		(layer "In2.Cu")
		(net "M_I_CPU1_SA_DQ<26>")
	)
	(arc
		(start 134.626096 -240.106962)
		(mid 134.809604 -240.061468)
		(end 134.991856 -240.111788)
		(width 0.0889)
		(layer "In2.Cu")
		(net "M_I_CPU1_SA_DQ<26>")
	)
	(arc
		(start 139.326112 -240.106962)
		(mid 139.50962 -240.061468)
		(end 139.691872 -240.111788)
		(width 0.0889)
		(layer "In2.Cu")
		(net "M_I_CPU1_SA_DQ<26>")
	)
	(arc
		(start 138.377676 -240.111788)
		(mid 138.559927 -240.061438)
		(end 138.743436 -240.106962)
		(width 0.0889)
		(layer "In2.Cu")
		(net "M_I_CPU1_SA_DQ<26>")
	)
	(arc
		(start 144.957546 -240.111788)
		(mid 145.047806 -240.07416)
		(end 145.144744 -240.061242)
		(width 0.0889)
		(layer "In2.Cu")
		(net "M_I_CPU1_SA_DQ<26>")
	)
	(arc
		(start 137.811764 -240.111788)
		(mid 138.09472 -240.187965)
		(end 138.377676 -240.111788)
		(width 0.0889)
		(layer "In2.Cu")
		(net "M_I_CPU1_SA_DQ<26>")
	)
	(arc
		(start 134.991856 -240.111788)
		(mid 135.274812 -240.187965)
		(end 135.557768 -240.111788)
		(width 0.0889)
		(layer "In2.Cu")
		(net "M_I_CPU1_SA_DQ<26>")
	)
	(arc
		(start 137.437622 -240.111788)
		(mid 137.619873 -240.061438)
		(end 137.803382 -240.106962)
		(width 0.0889)
		(layer "In2.Cu")
		(net "M_I_CPU1_SA_DQ<26>")
	)
	(arc
		(start 132.737606 -240.111788)
		(mid 132.919857 -240.061438)
		(end 133.103366 -240.106962)
		(width 0.0889)
		(layer "In2.Cu")
		(net "M_I_CPU1_SA_DQ<26>")
	)
	(arc
		(start 143.451834 -240.111788)
		(mid 143.728647 -240.187931)
		(end 144.007078 -240.117884)
		(width 0.0889)
		(layer "In2.Cu")
		(net "M_I_CPU1_SA_DQ<26>")
	)
	(arc
		(start 131.231894 -240.111788)
		(mid 131.51485 -240.187965)
		(end 131.797806 -240.111788)
		(width 0.0889)
		(layer "In2.Cu")
		(net "M_I_CPU1_SA_DQ<26>")
	)
	(arc
		(start 133.111748 -240.111788)
		(mid 133.394704 -240.187965)
		(end 133.67766 -240.111788)
		(width 0.0889)
		(layer "In2.Cu")
		(net "M_I_CPU1_SA_DQ<26>")
	)
	(arc
		(start 144.401794 -240.117884)
		(mid 144.68048 -240.188104)
		(end 144.957546 -240.111788)
		(width 0.0889)
		(layer "In2.Cu")
		(net "M_I_CPU1_SA_DQ<26>")
	)
	(arc
		(start 135.56615 -240.106962)
		(mid 135.749658 -240.061468)
		(end 135.93191 -240.111788)
		(width 0.0889)
		(layer "In2.Cu")
		(net "M_I_CPU1_SA_DQ<26>")
	)
	(arc
		(start 136.497822 -240.111788)
		(mid 136.684766 -240.061533)
		(end 136.87171 -240.111788)
		(width 0.0889)
		(layer "In2.Cu")
		(net "M_I_CPU1_SA_DQ<26>")
	)
	(arc
		(start 139.691872 -240.111788)
		(mid 139.974828 -240.187965)
		(end 140.257784 -240.111788)
		(width 0.0889)
		(layer "In2.Cu")
		(net "M_I_CPU1_SA_DQ<26>")
	)
	(segment
		(start 127.757936 -240.700306)
		(end 128.224788 -240.434368)
		(width 0.10668)
		(layer "F.Cu")
		(net "M_I_CPU1_SA_DQ<25>")
	)
	(segment
		(start 146.111468 -239.995202)
		(end 146.111468 -239.576864)
		(width 0.0889)
		(layer "In2.Cu")
		(net "M_I_CPU1_SA_DQ<25>")
	)
	(segment
		(start 163.035996 -227.51034)
		(end 164.45484 -227.51034)
		(width 0.14478)
		(layer "In2.Cu")
		(net "M_I_CPU1_SA_DQ<25>")
	)
	(segment
		(start 134.617714 -240.756948)
		(end 134.626096 -240.761774)
		(width 0.0889)
		(layer "In2.Cu")
		(net "M_I_CPU1_SA_DQ<25>")
	)
	(segment
		(start 145.40865 -240.69802)
		(end 146.111468 -239.995202)
		(width 0.0889)
		(layer "In2.Cu")
		(net "M_I_CPU1_SA_DQ<25>")
	)
	(segment
		(start 168.087294 -226.660456)
		(end 169.39768 -226.660456)
		(width 0.14478)
		(layer "In2.Cu")
		(net "M_I_CPU1_SA_DQ<25>")
	)
	(segment
		(start 129.343404 -240.761774)
		(end 129.351786 -240.756948)
		(width 0.0889)
		(layer "In2.Cu")
		(net "M_I_CPU1_SA_DQ<25>")
	)
	(segment
		(start 143.077692 -240.756948)
		(end 143.086074 -240.761774)
		(width 0.0889)
		(layer "In2.Cu")
		(net "M_I_CPU1_SA_DQ<25>")
	)
	(segment
		(start 135.557768 -240.756948)
		(end 135.56615 -240.761774)
		(width 0.0889)
		(layer "In2.Cu")
		(net "M_I_CPU1_SA_DQ<25>")
	)
	(segment
		(start 128.07061 -240.699798)
		(end 128.092962 -240.78311)
		(width 0.0889)
		(layer "In2.Cu")
		(net "M_I_CPU1_SA_DQ<25>")
	)
	(segment
		(start 157.253432 -232.43032)
		(end 158.656528 -232.43032)
		(width 0.14478)
		(layer "In2.Cu")
		(net "M_I_CPU1_SA_DQ<25>")
	)
	(segment
		(start 146.111468 -239.576864)
		(end 146.390868 -239.297464)
		(width 0.0889)
		(layer "In2.Cu")
		(net "M_I_CPU1_SA_DQ<25>")
	)
	(segment
		(start 139.31773 -240.756948)
		(end 139.326112 -240.761774)
		(width 0.0889)
		(layer "In2.Cu")
		(net "M_I_CPU1_SA_DQ<25>")
	)
	(segment
		(start 144.007078 -240.750852)
		(end 144.017492 -240.756948)
		(width 0.0889)
		(layer "In2.Cu")
		(net "M_I_CPU1_SA_DQ<25>")
	)
	(segment
		(start 174.024798 -227.13315)
		(end 175.165766 -226.660456)
		(width 0.14478)
		(layer "In2.Cu")
		(net "M_I_CPU1_SA_DQ<25>")
	)
	(segment
		(start 167.195246 -226.838002)
		(end 168.087294 -226.660456)
		(width 0.14478)
		(layer "In2.Cu")
		(net "M_I_CPU1_SA_DQ<25>")
	)
	(segment
		(start 147.919186 -239.010444)
		(end 150.673308 -239.010444)
		(width 0.14478)
		(layer "In2.Cu")
		(net "M_I_CPU1_SA_DQ<25>")
	)
	(segment
		(start 133.103366 -240.761774)
		(end 133.111748 -240.756948)
		(width 0.0889)
		(layer "In2.Cu")
		(net "M_I_CPU1_SA_DQ<25>")
	)
	(segment
		(start 147.325588 -239.297464)
		(end 147.612608 -239.010444)
		(width 0.0889)
		(layer "In2.Cu")
		(net "M_I_CPU1_SA_DQ<25>")
	)
	(segment
		(start 145.408396 -240.69802)
		(end 145.40865 -240.69802)
		(width 0.0889)
		(layer "In2.Cu")
		(net "M_I_CPU1_SA_DQ<25>")
	)
	(segment
		(start 164.45484 -227.51034)
		(end 165.479222 -227.358448)
		(width 0.14478)
		(layer "In2.Cu")
		(net "M_I_CPU1_SA_DQ<25>")
	)
	(segment
		(start 158.656528 -232.43032)
		(end 160.49117 -230.595678)
		(width 0.14478)
		(layer "In2.Cu")
		(net "M_I_CPU1_SA_DQ<25>")
	)
	(segment
		(start 150.673308 -239.010444)
		(end 157.253432 -232.43032)
		(width 0.14478)
		(layer "In2.Cu")
		(net "M_I_CPU1_SA_DQ<25>")
	)
	(segment
		(start 147.612608 -239.010444)
		(end 147.919186 -239.010444)
		(width 0.0889)
		(layer "In2.Cu")
		(net "M_I_CPU1_SA_DQ<25>")
	)
	(segment
		(start 171.449746 -227.51034)
		(end 172.128434 -227.51034)
		(width 0.14478)
		(layer "In2.Cu")
		(net "M_I_CPU1_SA_DQ<25>")
	)
	(segment
		(start 175.165766 -226.660456)
		(end 183.19115 -226.660456)
		(width 0.14478)
		(layer "In2.Cu")
		(net "M_I_CPU1_SA_DQ<25>")
	)
	(segment
		(start 140.257784 -240.756948)
		(end 140.266166 -240.761774)
		(width 0.0889)
		(layer "In2.Cu")
		(net "M_I_CPU1_SA_DQ<25>")
	)
	(segment
		(start 144.39138 -240.756948)
		(end 144.401794 -240.750852)
		(width 0.0889)
		(layer "In2.Cu")
		(net "M_I_CPU1_SA_DQ<25>")
	)
	(segment
		(start 160.49117 -230.055166)
		(end 163.035996 -227.51034)
		(width 0.14478)
		(layer "In2.Cu")
		(net "M_I_CPU1_SA_DQ<25>")
	)
	(segment
		(start 145.31975 -240.763806)
		(end 145.331434 -240.756948)
		(width 0.0889)
		(layer "In2.Cu")
		(net "M_I_CPU1_SA_DQ<25>")
	)
	(segment
		(start 137.803382 -240.761774)
		(end 137.811764 -240.756948)
		(width 0.0889)
		(layer "In2.Cu")
		(net "M_I_CPU1_SA_DQ<25>")
	)
	(segment
		(start 142.503398 -240.761774)
		(end 142.51178 -240.756948)
		(width 0.0889)
		(layer "In2.Cu")
		(net "M_I_CPU1_SA_DQ<25>")
	)
	(segment
		(start 129.917698 -240.756948)
		(end 129.92608 -240.761774)
		(width 0.0889)
		(layer "In2.Cu")
		(net "M_I_CPU1_SA_DQ<25>")
	)
	(segment
		(start 172.128434 -227.51034)
		(end 174.024798 -227.13315)
		(width 0.14478)
		(layer "In2.Cu")
		(net "M_I_CPU1_SA_DQ<25>")
	)
	(segment
		(start 128.40335 -240.761774)
		(end 128.411732 -240.756948)
		(width 0.0889)
		(layer "In2.Cu")
		(net "M_I_CPU1_SA_DQ<25>")
	)
	(segment
		(start 160.49117 -230.595678)
		(end 160.49117 -230.055166)
		(width 0.14478)
		(layer "In2.Cu")
		(net "M_I_CPU1_SA_DQ<25>")
	)
	(segment
		(start 169.39768 -226.660456)
		(end 171.449746 -227.51034)
		(width 0.14478)
		(layer "In2.Cu")
		(net "M_I_CPU1_SA_DQ<25>")
	)
	(segment
		(start 183.19115 -226.660456)
		(end 183.616092 -227.085398)
		(width 0.14478)
		(layer "In2.Cu")
		(net "M_I_CPU1_SA_DQ<25>")
	)
	(segment
		(start 134.04342 -240.761774)
		(end 134.051802 -240.756948)
		(width 0.0889)
		(layer "In2.Cu")
		(net "M_I_CPU1_SA_DQ<25>")
	)
	(segment
		(start 138.743436 -240.761774)
		(end 138.751818 -240.756948)
		(width 0.0889)
		(layer "In2.Cu")
		(net "M_I_CPU1_SA_DQ<25>")
	)
	(segment
		(start 130.857752 -240.756948)
		(end 130.866134 -240.761774)
		(width 0.0889)
		(layer "In2.Cu")
		(net "M_I_CPU1_SA_DQ<25>")
	)
	(segment
		(start 128.224788 -240.434368)
		(end 128.07061 -240.699798)
		(width 0.0889)
		(layer "In2.Cu")
		(net "M_I_CPU1_SA_DQ<25>")
	)
	(segment
		(start 146.390868 -239.297464)
		(end 147.325588 -239.297464)
		(width 0.0889)
		(layer "In2.Cu")
		(net "M_I_CPU1_SA_DQ<25>")
	)
	(segment
		(start 165.479222 -227.358448)
		(end 167.195246 -226.838002)
		(width 0.14478)
		(layer "In2.Cu")
		(net "M_I_CPU1_SA_DQ<25>")
	)
	(arc
		(start 129.351786 -240.756948)
		(mid 129.634742 -240.680771)
		(end 129.917698 -240.756948)
		(width 0.0889)
		(layer "In2.Cu")
		(net "M_I_CPU1_SA_DQ<25>")
	)
	(arc
		(start 137.437622 -240.756948)
		(mid 137.619873 -240.807298)
		(end 137.803382 -240.761774)
		(width 0.0889)
		(layer "In2.Cu")
		(net "M_I_CPU1_SA_DQ<25>")
	)
	(arc
		(start 138.751818 -240.756948)
		(mid 139.034774 -240.680771)
		(end 139.31773 -240.756948)
		(width 0.0889)
		(layer "In2.Cu")
		(net "M_I_CPU1_SA_DQ<25>")
	)
	(arc
		(start 144.401794 -240.750852)
		(mid 144.68048 -240.680632)
		(end 144.957546 -240.756948)
		(width 0.0889)
		(layer "In2.Cu")
		(net "M_I_CPU1_SA_DQ<25>")
	)
	(arc
		(start 141.571726 -240.756948)
		(mid 141.854682 -240.680771)
		(end 142.137638 -240.756948)
		(width 0.0889)
		(layer "In2.Cu")
		(net "M_I_CPU1_SA_DQ<25>")
	)
	(arc
		(start 131.797806 -240.756948)
		(mid 131.98475 -240.807203)
		(end 132.171694 -240.756948)
		(width 0.0889)
		(layer "In2.Cu")
		(net "M_I_CPU1_SA_DQ<25>")
	)
	(arc
		(start 142.137638 -240.756948)
		(mid 142.319889 -240.807298)
		(end 142.503398 -240.761774)
		(width 0.0889)
		(layer "In2.Cu")
		(net "M_I_CPU1_SA_DQ<25>")
	)
	(arc
		(start 134.051802 -240.756948)
		(mid 134.334758 -240.680771)
		(end 134.617714 -240.756948)
		(width 0.0889)
		(layer "In2.Cu")
		(net "M_I_CPU1_SA_DQ<25>")
	)
	(arc
		(start 145.331434 -240.756948)
		(mid 145.371837 -240.729994)
		(end 145.408396 -240.69802)
		(width 0.0889)
		(layer "In2.Cu")
		(net "M_I_CPU1_SA_DQ<25>")
	)
	(arc
		(start 135.93191 -240.756948)
		(mid 136.214866 -240.680771)
		(end 136.497822 -240.756948)
		(width 0.0889)
		(layer "In2.Cu")
		(net "M_I_CPU1_SA_DQ<25>")
	)
	(arc
		(start 136.87171 -240.756948)
		(mid 137.154666 -240.680771)
		(end 137.437622 -240.756948)
		(width 0.0889)
		(layer "In2.Cu")
		(net "M_I_CPU1_SA_DQ<25>")
	)
	(arc
		(start 128.092962 -240.78311)
		(mid 128.250472 -240.806308)
		(end 128.40335 -240.761774)
		(width 0.0889)
		(layer "In2.Cu")
		(net "M_I_CPU1_SA_DQ<25>")
	)
	(arc
		(start 129.92608 -240.761774)
		(mid 130.109588 -240.807268)
		(end 130.29184 -240.756948)
		(width 0.0889)
		(layer "In2.Cu")
		(net "M_I_CPU1_SA_DQ<25>")
	)
	(arc
		(start 131.231894 -240.756948)
		(mid 131.51485 -240.680771)
		(end 131.797806 -240.756948)
		(width 0.0889)
		(layer "In2.Cu")
		(net "M_I_CPU1_SA_DQ<25>")
	)
	(arc
		(start 130.29184 -240.756948)
		(mid 130.574796 -240.680771)
		(end 130.857752 -240.756948)
		(width 0.0889)
		(layer "In2.Cu")
		(net "M_I_CPU1_SA_DQ<25>")
	)
	(arc
		(start 135.56615 -240.761774)
		(mid 135.749658 -240.807268)
		(end 135.93191 -240.756948)
		(width 0.0889)
		(layer "In2.Cu")
		(net "M_I_CPU1_SA_DQ<25>")
	)
	(arc
		(start 134.991856 -240.756948)
		(mid 135.274812 -240.680771)
		(end 135.557768 -240.756948)
		(width 0.0889)
		(layer "In2.Cu")
		(net "M_I_CPU1_SA_DQ<25>")
	)
	(arc
		(start 138.377676 -240.756948)
		(mid 138.559927 -240.807298)
		(end 138.743436 -240.761774)
		(width 0.0889)
		(layer "In2.Cu")
		(net "M_I_CPU1_SA_DQ<25>")
	)
	(arc
		(start 130.866134 -240.761774)
		(mid 131.049642 -240.807268)
		(end 131.231894 -240.756948)
		(width 0.0889)
		(layer "In2.Cu")
		(net "M_I_CPU1_SA_DQ<25>")
	)
	(arc
		(start 128.977644 -240.756948)
		(mid 129.159895 -240.807298)
		(end 129.343404 -240.761774)
		(width 0.0889)
		(layer "In2.Cu")
		(net "M_I_CPU1_SA_DQ<25>")
	)
	(arc
		(start 143.086074 -240.761774)
		(mid 143.269582 -240.807268)
		(end 143.451834 -240.756948)
		(width 0.0889)
		(layer "In2.Cu")
		(net "M_I_CPU1_SA_DQ<25>")
	)
	(arc
		(start 144.957546 -240.756948)
		(mid 145.137751 -240.807265)
		(end 145.31975 -240.763806)
		(width 0.0889)
		(layer "In2.Cu")
		(net "M_I_CPU1_SA_DQ<25>")
	)
	(arc
		(start 139.691872 -240.756948)
		(mid 139.974828 -240.680771)
		(end 140.257784 -240.756948)
		(width 0.0889)
		(layer "In2.Cu")
		(net "M_I_CPU1_SA_DQ<25>")
	)
	(arc
		(start 140.266166 -240.761774)
		(mid 140.449674 -240.807268)
		(end 140.631926 -240.756948)
		(width 0.0889)
		(layer "In2.Cu")
		(net "M_I_CPU1_SA_DQ<25>")
	)
	(arc
		(start 133.111748 -240.756948)
		(mid 133.394704 -240.680771)
		(end 133.67766 -240.756948)
		(width 0.0889)
		(layer "In2.Cu")
		(net "M_I_CPU1_SA_DQ<25>")
	)
	(arc
		(start 133.67766 -240.756948)
		(mid 133.859911 -240.807298)
		(end 134.04342 -240.761774)
		(width 0.0889)
		(layer "In2.Cu")
		(net "M_I_CPU1_SA_DQ<25>")
	)
	(arc
		(start 132.171694 -240.756948)
		(mid 132.45465 -240.680771)
		(end 132.737606 -240.756948)
		(width 0.0889)
		(layer "In2.Cu")
		(net "M_I_CPU1_SA_DQ<25>")
	)
	(arc
		(start 139.326112 -240.761774)
		(mid 139.50962 -240.807268)
		(end 139.691872 -240.756948)
		(width 0.0889)
		(layer "In2.Cu")
		(net "M_I_CPU1_SA_DQ<25>")
	)
	(arc
		(start 141.197838 -240.756948)
		(mid 141.384782 -240.807203)
		(end 141.571726 -240.756948)
		(width 0.0889)
		(layer "In2.Cu")
		(net "M_I_CPU1_SA_DQ<25>")
	)
	(arc
		(start 134.626096 -240.761774)
		(mid 134.809604 -240.807268)
		(end 134.991856 -240.756948)
		(width 0.0889)
		(layer "In2.Cu")
		(net "M_I_CPU1_SA_DQ<25>")
	)
	(arc
		(start 144.017492 -240.756948)
		(mid 144.204436 -240.807203)
		(end 144.39138 -240.756948)
		(width 0.0889)
		(layer "In2.Cu")
		(net "M_I_CPU1_SA_DQ<25>")
	)
	(arc
		(start 136.497822 -240.756948)
		(mid 136.684766 -240.807203)
		(end 136.87171 -240.756948)
		(width 0.0889)
		(layer "In2.Cu")
		(net "M_I_CPU1_SA_DQ<25>")
	)
	(arc
		(start 140.631926 -240.756948)
		(mid 140.914882 -240.680771)
		(end 141.197838 -240.756948)
		(width 0.0889)
		(layer "In2.Cu")
		(net "M_I_CPU1_SA_DQ<25>")
	)
	(arc
		(start 142.51178 -240.756948)
		(mid 142.794736 -240.680771)
		(end 143.077692 -240.756948)
		(width 0.0889)
		(layer "In2.Cu")
		(net "M_I_CPU1_SA_DQ<25>")
	)
	(arc
		(start 137.811764 -240.756948)
		(mid 138.09472 -240.680771)
		(end 138.377676 -240.756948)
		(width 0.0889)
		(layer "In2.Cu")
		(net "M_I_CPU1_SA_DQ<25>")
	)
	(arc
		(start 132.737606 -240.756948)
		(mid 132.919857 -240.807298)
		(end 133.103366 -240.761774)
		(width 0.0889)
		(layer "In2.Cu")
		(net "M_I_CPU1_SA_DQ<25>")
	)
	(arc
		(start 143.451834 -240.756948)
		(mid 143.728647 -240.680805)
		(end 144.007078 -240.750852)
		(width 0.0889)
		(layer "In2.Cu")
		(net "M_I_CPU1_SA_DQ<25>")
	)
	(arc
		(start 128.411732 -240.756948)
		(mid 128.694688 -240.680771)
		(end 128.977644 -240.756948)
		(width 0.0889)
		(layer "In2.Cu")
		(net "M_I_CPU1_SA_DQ<25>")
	)
	(segment
		(start 129.16789 -239.8903)
		(end 129.634742 -239.624362)
		(width 0.10668)
		(layer "F.Cu")
		(net "M_I_CPU1_SA_DQ<24>")
	)
	(segment
		(start 145.547588 -239.359948)
		(end 146.222212 -238.685324)
		(width 0.0889)
		(layer "In2.Cu")
		(net "M_I_CPU1_SA_DQ<24>")
	)
	(segment
		(start 133.20776 -239.946942)
		(end 133.216142 -239.951768)
		(width 0.0889)
		(layer "In2.Cu")
		(net "M_I_CPU1_SA_DQ<24>")
	)
	(segment
		(start 181.93258 -225.441764)
		(end 182.163212 -225.441764)
		(width 0.14478)
		(layer "In2.Cu")
		(net "M_I_CPU1_SA_DQ<24>")
	)
	(segment
		(start 132.267706 -239.946942)
		(end 132.276088 -239.951768)
		(width 0.0889)
		(layer "In2.Cu")
		(net "M_I_CPU1_SA_DQ<24>")
	)
	(segment
		(start 181.769766 -225.27895)
		(end 181.93258 -225.441764)
		(width 0.14478)
		(layer "In2.Cu")
		(net "M_I_CPU1_SA_DQ<24>")
	)
	(segment
		(start 137.907776 -239.946942)
		(end 137.916158 -239.951768)
		(width 0.0889)
		(layer "In2.Cu")
		(net "M_I_CPU1_SA_DQ<24>")
	)
	(segment
		(start 140.15339 -239.951768)
		(end 140.161772 -239.946942)
		(width 0.0889)
		(layer "In2.Cu")
		(net "M_I_CPU1_SA_DQ<24>")
	)
	(segment
		(start 144.487392 -239.946942)
		(end 144.495774 -239.951768)
		(width 0.0889)
		(layer "In2.Cu")
		(net "M_I_CPU1_SA_DQ<24>")
	)
	(segment
		(start 146.995388 -238.685324)
		(end 147.582128 -238.098584)
		(width 0.0889)
		(layer "In2.Cu")
		(net "M_I_CPU1_SA_DQ<24>")
	)
	(segment
		(start 135.453374 -239.951768)
		(end 135.461756 -239.946942)
		(width 0.0889)
		(layer "In2.Cu")
		(net "M_I_CPU1_SA_DQ<24>")
	)
	(segment
		(start 160.376108 -228.859588)
		(end 163.425378 -225.810318)
		(width 0.14478)
		(layer "In2.Cu")
		(net "M_I_CPU1_SA_DQ<24>")
	)
	(segment
		(start 147.944586 -238.098584)
		(end 150.313136 -238.098584)
		(width 0.14478)
		(layer "In2.Cu")
		(net "M_I_CPU1_SA_DQ<24>")
	)
	(segment
		(start 131.693412 -239.951768)
		(end 131.701794 -239.946942)
		(width 0.0889)
		(layer "In2.Cu")
		(net "M_I_CPU1_SA_DQ<24>")
	)
	(segment
		(start 163.425378 -225.810318)
		(end 165.845998 -225.810318)
		(width 0.14478)
		(layer "In2.Cu")
		(net "M_I_CPU1_SA_DQ<24>")
	)
	(segment
		(start 171.232068 -225.810318)
		(end 173.686724 -225.810318)
		(width 0.14478)
		(layer "In2.Cu")
		(net "M_I_CPU1_SA_DQ<24>")
	)
	(segment
		(start 165.845998 -225.810318)
		(end 166.695882 -224.960434)
		(width 0.14478)
		(layer "In2.Cu")
		(net "M_I_CPU1_SA_DQ<24>")
	)
	(segment
		(start 145.144744 -239.870742)
		(end 145.547588 -239.467898)
		(width 0.0889)
		(layer "In2.Cu")
		(net "M_I_CPU1_SA_DQ<24>")
	)
	(segment
		(start 182.48884 -224.960434)
		(end 183.19115 -224.960434)
		(width 0.14478)
		(layer "In2.Cu")
		(net "M_I_CPU1_SA_DQ<24>")
	)
	(segment
		(start 182.326026 -225.123248)
		(end 182.48884 -224.960434)
		(width 0.14478)
		(layer "In2.Cu")
		(net "M_I_CPU1_SA_DQ<24>")
	)
	(segment
		(start 141.093444 -239.951768)
		(end 141.101826 -239.946942)
		(width 0.0889)
		(layer "In2.Cu")
		(net "M_I_CPU1_SA_DQ<24>")
	)
	(segment
		(start 143.921734 -239.946942)
		(end 143.932148 -239.940846)
		(width 0.0889)
		(layer "In2.Cu")
		(net "M_I_CPU1_SA_DQ<24>")
	)
	(segment
		(start 174.536608 -224.960434)
		(end 181.606952 -224.960434)
		(width 0.14478)
		(layer "In2.Cu")
		(net "M_I_CPU1_SA_DQ<24>")
	)
	(segment
		(start 166.695882 -224.960434)
		(end 170.382184 -224.960434)
		(width 0.14478)
		(layer "In2.Cu")
		(net "M_I_CPU1_SA_DQ<24>")
	)
	(segment
		(start 129.480818 -239.889792)
		(end 129.50317 -239.973104)
		(width 0.0889)
		(layer "In2.Cu")
		(net "M_I_CPU1_SA_DQ<24>")
	)
	(segment
		(start 181.769766 -225.123248)
		(end 181.769766 -225.27895)
		(width 0.14478)
		(layer "In2.Cu")
		(net "M_I_CPU1_SA_DQ<24>")
	)
	(segment
		(start 181.606952 -224.960434)
		(end 181.769766 -225.123248)
		(width 0.14478)
		(layer "In2.Cu")
		(net "M_I_CPU1_SA_DQ<24>")
	)
	(segment
		(start 136.967722 -239.946942)
		(end 136.976104 -239.951768)
		(width 0.0889)
		(layer "In2.Cu")
		(net "M_I_CPU1_SA_DQ<24>")
	)
	(segment
		(start 183.19115 -224.960434)
		(end 183.616092 -225.385376)
		(width 0.14478)
		(layer "In2.Cu")
		(net "M_I_CPU1_SA_DQ<24>")
	)
	(segment
		(start 141.667738 -239.946942)
		(end 141.67612 -239.951768)
		(width 0.0889)
		(layer "In2.Cu")
		(net "M_I_CPU1_SA_DQ<24>")
	)
	(segment
		(start 147.582128 -238.098584)
		(end 147.944586 -238.098584)
		(width 0.0889)
		(layer "In2.Cu")
		(net "M_I_CPU1_SA_DQ<24>")
	)
	(segment
		(start 145.547588 -239.467898)
		(end 145.547588 -239.359948)
		(width 0.0889)
		(layer "In2.Cu")
		(net "M_I_CPU1_SA_DQ<24>")
	)
	(segment
		(start 182.326026 -225.27895)
		(end 182.326026 -225.123248)
		(width 0.14478)
		(layer "In2.Cu")
		(net "M_I_CPU1_SA_DQ<24>")
	)
	(segment
		(start 130.753358 -239.951768)
		(end 130.76174 -239.946942)
		(width 0.0889)
		(layer "In2.Cu")
		(net "M_I_CPU1_SA_DQ<24>")
	)
	(segment
		(start 170.382184 -224.960434)
		(end 171.232068 -225.810318)
		(width 0.14478)
		(layer "In2.Cu")
		(net "M_I_CPU1_SA_DQ<24>")
	)
	(segment
		(start 182.163212 -225.441764)
		(end 182.326026 -225.27895)
		(width 0.14478)
		(layer "In2.Cu")
		(net "M_I_CPU1_SA_DQ<24>")
	)
	(segment
		(start 136.393428 -239.951768)
		(end 136.40181 -239.946942)
		(width 0.0889)
		(layer "In2.Cu")
		(net "M_I_CPU1_SA_DQ<24>")
	)
	(segment
		(start 159.552132 -228.859588)
		(end 160.376108 -228.859588)
		(width 0.14478)
		(layer "In2.Cu")
		(net "M_I_CPU1_SA_DQ<24>")
	)
	(segment
		(start 146.222212 -238.685324)
		(end 146.995388 -238.685324)
		(width 0.0889)
		(layer "In2.Cu")
		(net "M_I_CPU1_SA_DQ<24>")
	)
	(segment
		(start 173.686724 -225.810318)
		(end 174.536608 -224.960434)
		(width 0.14478)
		(layer "In2.Cu")
		(net "M_I_CPU1_SA_DQ<24>")
	)
	(segment
		(start 143.913352 -239.951768)
		(end 143.921734 -239.946942)
		(width 0.0889)
		(layer "In2.Cu")
		(net "M_I_CPU1_SA_DQ<24>")
	)
	(segment
		(start 129.634742 -239.624362)
		(end 129.480818 -239.889792)
		(width 0.0889)
		(layer "In2.Cu")
		(net "M_I_CPU1_SA_DQ<24>")
	)
	(segment
		(start 150.313136 -238.098584)
		(end 159.552132 -228.859588)
		(width 0.14478)
		(layer "In2.Cu")
		(net "M_I_CPU1_SA_DQ<24>")
	)
	(arc
		(start 138.281918 -239.946942)
		(mid 138.564874 -239.870765)
		(end 138.84783 -239.946942)
		(width 0.0889)
		(layer "In2.Cu")
		(net "M_I_CPU1_SA_DQ<24>")
	)
	(arc
		(start 129.821686 -239.946942)
		(mid 130.104642 -239.870765)
		(end 130.387598 -239.946942)
		(width 0.0889)
		(layer "In2.Cu")
		(net "M_I_CPU1_SA_DQ<24>")
	)
	(arc
		(start 144.495774 -239.951768)
		(mid 144.679282 -239.997262)
		(end 144.861534 -239.946942)
		(width 0.0889)
		(layer "In2.Cu")
		(net "M_I_CPU1_SA_DQ<24>")
	)
	(arc
		(start 134.147814 -239.946942)
		(mid 134.334758 -239.997197)
		(end 134.521702 -239.946942)
		(width 0.0889)
		(layer "In2.Cu")
		(net "M_I_CPU1_SA_DQ<24>")
	)
	(arc
		(start 143.932148 -239.940846)
		(mid 144.21058 -239.870748)
		(end 144.487392 -239.946942)
		(width 0.0889)
		(layer "In2.Cu")
		(net "M_I_CPU1_SA_DQ<24>")
	)
	(arc
		(start 136.40181 -239.946942)
		(mid 136.684766 -239.870765)
		(end 136.967722 -239.946942)
		(width 0.0889)
		(layer "In2.Cu")
		(net "M_I_CPU1_SA_DQ<24>")
	)
	(arc
		(start 130.387598 -239.946942)
		(mid 130.569849 -239.997292)
		(end 130.753358 -239.951768)
		(width 0.0889)
		(layer "In2.Cu")
		(net "M_I_CPU1_SA_DQ<24>")
	)
	(arc
		(start 140.727684 -239.946942)
		(mid 140.909935 -239.997292)
		(end 141.093444 -239.951768)
		(width 0.0889)
		(layer "In2.Cu")
		(net "M_I_CPU1_SA_DQ<24>")
	)
	(arc
		(start 136.027668 -239.946942)
		(mid 136.209919 -239.997292)
		(end 136.393428 -239.951768)
		(width 0.0889)
		(layer "In2.Cu")
		(net "M_I_CPU1_SA_DQ<24>")
	)
	(arc
		(start 142.98168 -239.946942)
		(mid 143.264636 -239.870765)
		(end 143.547592 -239.946942)
		(width 0.0889)
		(layer "In2.Cu")
		(net "M_I_CPU1_SA_DQ<24>")
	)
	(arc
		(start 142.04188 -239.946942)
		(mid 142.324836 -239.870765)
		(end 142.607792 -239.946942)
		(width 0.0889)
		(layer "In2.Cu")
		(net "M_I_CPU1_SA_DQ<24>")
	)
	(arc
		(start 129.50317 -239.973104)
		(mid 129.665359 -239.995839)
		(end 129.821686 -239.946942)
		(width 0.0889)
		(layer "In2.Cu")
		(net "M_I_CPU1_SA_DQ<24>")
	)
	(arc
		(start 144.861534 -239.946942)
		(mid 144.998097 -239.890109)
		(end 145.144744 -239.870742)
		(width 0.0889)
		(layer "In2.Cu")
		(net "M_I_CPU1_SA_DQ<24>")
	)
	(arc
		(start 139.221718 -239.946942)
		(mid 139.504674 -239.870765)
		(end 139.78763 -239.946942)
		(width 0.0889)
		(layer "In2.Cu")
		(net "M_I_CPU1_SA_DQ<24>")
	)
	(arc
		(start 138.84783 -239.946942)
		(mid 139.034774 -239.997197)
		(end 139.221718 -239.946942)
		(width 0.0889)
		(layer "In2.Cu")
		(net "M_I_CPU1_SA_DQ<24>")
	)
	(arc
		(start 143.547592 -239.946942)
		(mid 143.729843 -239.997292)
		(end 143.913352 -239.951768)
		(width 0.0889)
		(layer "In2.Cu")
		(net "M_I_CPU1_SA_DQ<24>")
	)
	(arc
		(start 141.101826 -239.946942)
		(mid 141.384782 -239.870765)
		(end 141.667738 -239.946942)
		(width 0.0889)
		(layer "In2.Cu")
		(net "M_I_CPU1_SA_DQ<24>")
	)
	(arc
		(start 139.78763 -239.946942)
		(mid 139.969881 -239.997292)
		(end 140.15339 -239.951768)
		(width 0.0889)
		(layer "In2.Cu")
		(net "M_I_CPU1_SA_DQ<24>")
	)
	(arc
		(start 140.161772 -239.946942)
		(mid 140.444728 -239.870765)
		(end 140.727684 -239.946942)
		(width 0.0889)
		(layer "In2.Cu")
		(net "M_I_CPU1_SA_DQ<24>")
	)
	(arc
		(start 135.461756 -239.946942)
		(mid 135.744712 -239.870765)
		(end 136.027668 -239.946942)
		(width 0.0889)
		(layer "In2.Cu")
		(net "M_I_CPU1_SA_DQ<24>")
	)
	(arc
		(start 133.581902 -239.946942)
		(mid 133.864858 -239.870765)
		(end 134.147814 -239.946942)
		(width 0.0889)
		(layer "In2.Cu")
		(net "M_I_CPU1_SA_DQ<24>")
	)
	(arc
		(start 130.76174 -239.946942)
		(mid 131.044696 -239.870765)
		(end 131.327652 -239.946942)
		(width 0.0889)
		(layer "In2.Cu")
		(net "M_I_CPU1_SA_DQ<24>")
	)
	(arc
		(start 142.607792 -239.946942)
		(mid 142.794736 -239.997197)
		(end 142.98168 -239.946942)
		(width 0.0889)
		(layer "In2.Cu")
		(net "M_I_CPU1_SA_DQ<24>")
	)
	(arc
		(start 135.087614 -239.946942)
		(mid 135.269865 -239.997292)
		(end 135.453374 -239.951768)
		(width 0.0889)
		(layer "In2.Cu")
		(net "M_I_CPU1_SA_DQ<24>")
	)
	(arc
		(start 133.216142 -239.951768)
		(mid 133.39965 -239.997262)
		(end 133.581902 -239.946942)
		(width 0.0889)
		(layer "In2.Cu")
		(net "M_I_CPU1_SA_DQ<24>")
	)
	(arc
		(start 137.916158 -239.951768)
		(mid 138.099666 -239.997262)
		(end 138.281918 -239.946942)
		(width 0.0889)
		(layer "In2.Cu")
		(net "M_I_CPU1_SA_DQ<24>")
	)
	(arc
		(start 131.327652 -239.946942)
		(mid 131.509903 -239.997292)
		(end 131.693412 -239.951768)
		(width 0.0889)
		(layer "In2.Cu")
		(net "M_I_CPU1_SA_DQ<24>")
	)
	(arc
		(start 132.276088 -239.951768)
		(mid 132.459596 -239.997262)
		(end 132.641848 -239.946942)
		(width 0.0889)
		(layer "In2.Cu")
		(net "M_I_CPU1_SA_DQ<24>")
	)
	(arc
		(start 141.67612 -239.951768)
		(mid 141.859628 -239.997262)
		(end 142.04188 -239.946942)
		(width 0.0889)
		(layer "In2.Cu")
		(net "M_I_CPU1_SA_DQ<24>")
	)
	(arc
		(start 137.341864 -239.946942)
		(mid 137.62482 -239.870765)
		(end 137.907776 -239.946942)
		(width 0.0889)
		(layer "In2.Cu")
		(net "M_I_CPU1_SA_DQ<24>")
	)
	(arc
		(start 131.701794 -239.946942)
		(mid 131.98475 -239.870765)
		(end 132.267706 -239.946942)
		(width 0.0889)
		(layer "In2.Cu")
		(net "M_I_CPU1_SA_DQ<24>")
	)
	(arc
		(start 136.976104 -239.951768)
		(mid 137.159612 -239.997262)
		(end 137.341864 -239.946942)
		(width 0.0889)
		(layer "In2.Cu")
		(net "M_I_CPU1_SA_DQ<24>")
	)
	(arc
		(start 134.521702 -239.946942)
		(mid 134.804658 -239.870765)
		(end 135.087614 -239.946942)
		(width 0.0889)
		(layer "In2.Cu")
		(net "M_I_CPU1_SA_DQ<24>")
	)
	(arc
		(start 132.641848 -239.946942)
		(mid 132.924804 -239.870765)
		(end 133.20776 -239.946942)
		(width 0.0889)
		(layer "In2.Cu")
		(net "M_I_CPU1_SA_DQ<24>")
	)
	(segment
		(start 127.287782 -239.8903)
		(end 127.754634 -239.624362)
		(width 0.10668)
		(layer "F.Cu")
		(net "M_I_CPU1_SA_DQ<23>")
	)
	(segment
		(start 162.596068 -225.816922)
		(end 162.757612 -225.655378)
		(width 0.14478)
		(layer "In2.Cu")
		(net "M_I_CPU1_SA_DQ<23>")
	)
	(segment
		(start 162.313112 -224.982278)
		(end 162.313112 -224.753678)
		(width 0.14478)
		(layer "In2.Cu")
		(net "M_I_CPU1_SA_DQ<23>")
	)
	(segment
		(start 150.09241 -237.539784)
		(end 159.53105 -228.101144)
		(width 0.14478)
		(layer "In2.Cu")
		(net "M_I_CPU1_SA_DQ<23>")
	)
	(segment
		(start 160.255966 -228.101144)
		(end 160.388808 -227.968302)
		(width 0.14478)
		(layer "In2.Cu")
		(net "M_I_CPU1_SA_DQ<23>")
	)
	(segment
		(start 128.507744 -239.301782)
		(end 128.516126 -239.296956)
		(width 0.0889)
		(layer "In2.Cu")
		(net "M_I_CPU1_SA_DQ<23>")
	)
	(segment
		(start 163.32708 -225.215958)
		(end 163.55568 -225.215958)
		(width 0.14478)
		(layer "In2.Cu")
		(net "M_I_CPU1_SA_DQ<23>")
	)
	(segment
		(start 160.650428 -227.221034)
		(end 160.822132 -227.392738)
		(width 0.14478)
		(layer "In2.Cu")
		(net "M_I_CPU1_SA_DQ<23>")
	)
	(segment
		(start 170.32859 -224.110296)
		(end 171.178728 -224.960434)
		(width 0.14478)
		(layer "In2.Cu")
		(net "M_I_CPU1_SA_DQ<23>")
	)
	(segment
		(start 137.907776 -239.301782)
		(end 137.916158 -239.296956)
		(width 0.0889)
		(layer "In2.Cu")
		(net "M_I_CPU1_SA_DQ<23>")
	)
	(segment
		(start 174.512478 -224.110296)
		(end 179.091082 -224.110296)
		(width 0.14478)
		(layer "In2.Cu")
		(net "M_I_CPU1_SA_DQ<23>")
	)
	(segment
		(start 173.66234 -224.960434)
		(end 174.512478 -224.110296)
		(width 0.14478)
		(layer "In2.Cu")
		(net "M_I_CPU1_SA_DQ<23>")
	)
	(segment
		(start 160.421828 -227.221034)
		(end 160.650428 -227.221034)
		(width 0.14478)
		(layer "In2.Cu")
		(net "M_I_CPU1_SA_DQ<23>")
	)
	(segment
		(start 161.992564 -226.222306)
		(end 161.47034 -225.700082)
		(width 0.14478)
		(layer "In2.Cu")
		(net "M_I_CPU1_SA_DQ<23>")
	)
	(segment
		(start 179.091082 -224.110296)
		(end 179.516024 -224.535238)
		(width 0.14478)
		(layer "In2.Cu")
		(net "M_I_CPU1_SA_DQ<23>")
	)
	(segment
		(start 162.757612 -225.426778)
		(end 162.313112 -224.982278)
		(width 0.14478)
		(layer "In2.Cu")
		(net "M_I_CPU1_SA_DQ<23>")
	)
	(segment
		(start 163.55568 -225.215958)
		(end 163.811204 -224.960434)
		(width 0.14478)
		(layer "In2.Cu")
		(net "M_I_CPU1_SA_DQ<23>")
	)
	(segment
		(start 127.908812 -239.358932)
		(end 128.005078 -239.333532)
		(width 0.0889)
		(layer "In2.Cu")
		(net "M_I_CPU1_SA_DQ<23>")
	)
	(segment
		(start 127.754634 -239.624362)
		(end 127.908812 -239.358932)
		(width 0.0889)
		(layer "In2.Cu")
		(net "M_I_CPU1_SA_DQ<23>")
	)
	(segment
		(start 160.822132 -227.392738)
		(end 161.050732 -227.392738)
		(width 0.14478)
		(layer "In2.Cu")
		(net "M_I_CPU1_SA_DQ<23>")
	)
	(segment
		(start 165.870382 -224.960434)
		(end 166.72052 -224.110296)
		(width 0.14478)
		(layer "In2.Cu")
		(net "M_I_CPU1_SA_DQ<23>")
	)
	(segment
		(start 131.693412 -239.296956)
		(end 131.701794 -239.301782)
		(width 0.0889)
		(layer "In2.Cu")
		(net "M_I_CPU1_SA_DQ<23>")
	)
	(segment
		(start 141.093444 -239.296956)
		(end 141.101826 -239.301782)
		(width 0.0889)
		(layer "In2.Cu")
		(net "M_I_CPU1_SA_DQ<23>")
	)
	(segment
		(start 160.945576 -226.184206)
		(end 161.174176 -226.184206)
		(width 0.14478)
		(layer "In2.Cu")
		(net "M_I_CPU1_SA_DQ<23>")
	)
	(segment
		(start 135.453374 -239.296956)
		(end 135.461756 -239.301782)
		(width 0.0889)
		(layer "In2.Cu")
		(net "M_I_CPU1_SA_DQ<23>")
	)
	(segment
		(start 163.811204 -224.960434)
		(end 165.870382 -224.960434)
		(width 0.14478)
		(layer "In2.Cu")
		(net "M_I_CPU1_SA_DQ<23>")
	)
	(segment
		(start 162.474656 -224.592134)
		(end 162.703256 -224.592134)
		(width 0.14478)
		(layer "In2.Cu")
		(net "M_I_CPU1_SA_DQ<23>")
	)
	(segment
		(start 130.753358 -239.296956)
		(end 130.76174 -239.301782)
		(width 0.0889)
		(layer "In2.Cu")
		(net "M_I_CPU1_SA_DQ<23>")
	)
	(segment
		(start 145.18767 -239.301782)
		(end 146.578828 -237.910624)
		(width 0.0889)
		(layer "In2.Cu")
		(net "M_I_CPU1_SA_DQ<23>")
	)
	(segment
		(start 146.578828 -237.910624)
		(end 147.218908 -237.910624)
		(width 0.0889)
		(layer "In2.Cu")
		(net "M_I_CPU1_SA_DQ<23>")
	)
	(segment
		(start 147.969986 -237.539784)
		(end 150.09241 -237.539784)
		(width 0.14478)
		(layer "In2.Cu")
		(net "M_I_CPU1_SA_DQ<23>")
	)
	(segment
		(start 159.53105 -228.101144)
		(end 160.255966 -228.101144)
		(width 0.14478)
		(layer "In2.Cu")
		(net "M_I_CPU1_SA_DQ<23>")
	)
	(segment
		(start 141.667738 -239.301782)
		(end 141.67612 -239.296956)
		(width 0.0889)
		(layer "In2.Cu")
		(net "M_I_CPU1_SA_DQ<23>")
	)
	(segment
		(start 160.388808 -227.739702)
		(end 160.260284 -227.611178)
		(width 0.14478)
		(layer "In2.Cu")
		(net "M_I_CPU1_SA_DQ<23>")
	)
	(segment
		(start 161.860484 -225.309938)
		(end 162.367468 -225.816922)
		(width 0.14478)
		(layer "In2.Cu")
		(net "M_I_CPU1_SA_DQ<23>")
	)
	(segment
		(start 143.921988 -239.301782)
		(end 145.18767 -239.301782)
		(width 0.0889)
		(layer "In2.Cu")
		(net "M_I_CPU1_SA_DQ<23>")
	)
	(segment
		(start 161.60242 -226.61245)
		(end 161.83102 -226.61245)
		(width 0.14478)
		(layer "In2.Cu")
		(net "M_I_CPU1_SA_DQ<23>")
	)
	(segment
		(start 162.313112 -224.753678)
		(end 162.474656 -224.592134)
		(width 0.14478)
		(layer "In2.Cu")
		(net "M_I_CPU1_SA_DQ<23>")
	)
	(segment
		(start 162.757612 -225.655378)
		(end 162.757612 -225.426778)
		(width 0.14478)
		(layer "In2.Cu")
		(net "M_I_CPU1_SA_DQ<23>")
	)
	(segment
		(start 160.260284 -227.382578)
		(end 160.421828 -227.221034)
		(width 0.14478)
		(layer "In2.Cu")
		(net "M_I_CPU1_SA_DQ<23>")
	)
	(segment
		(start 133.20776 -239.301782)
		(end 133.216142 -239.296956)
		(width 0.0889)
		(layer "In2.Cu")
		(net "M_I_CPU1_SA_DQ<23>")
	)
	(segment
		(start 171.178728 -224.960434)
		(end 173.66234 -224.960434)
		(width 0.14478)
		(layer "In2.Cu")
		(net "M_I_CPU1_SA_DQ<23>")
	)
	(segment
		(start 161.174176 -226.184206)
		(end 161.60242 -226.61245)
		(width 0.14478)
		(layer "In2.Cu")
		(net "M_I_CPU1_SA_DQ<23>")
	)
	(segment
		(start 147.589748 -237.539784)
		(end 147.969986 -237.539784)
		(width 0.0889)
		(layer "In2.Cu")
		(net "M_I_CPU1_SA_DQ<23>")
	)
	(segment
		(start 140.15339 -239.296956)
		(end 140.161772 -239.301782)
		(width 0.0889)
		(layer "In2.Cu")
		(net "M_I_CPU1_SA_DQ<23>")
	)
	(segment
		(start 160.260284 -227.611178)
		(end 160.260284 -227.382578)
		(width 0.14478)
		(layer "In2.Cu")
		(net "M_I_CPU1_SA_DQ<23>")
	)
	(segment
		(start 160.784032 -226.57435)
		(end 160.784032 -226.34575)
		(width 0.14478)
		(layer "In2.Cu")
		(net "M_I_CPU1_SA_DQ<23>")
	)
	(segment
		(start 161.47034 -225.700082)
		(end 161.47034 -225.471482)
		(width 0.14478)
		(layer "In2.Cu")
		(net "M_I_CPU1_SA_DQ<23>")
	)
	(segment
		(start 132.267706 -239.301782)
		(end 132.276088 -239.296956)
		(width 0.0889)
		(layer "In2.Cu")
		(net "M_I_CPU1_SA_DQ<23>")
	)
	(segment
		(start 161.83102 -226.61245)
		(end 161.992564 -226.450906)
		(width 0.14478)
		(layer "In2.Cu")
		(net "M_I_CPU1_SA_DQ<23>")
	)
	(segment
		(start 160.784032 -226.34575)
		(end 160.945576 -226.184206)
		(width 0.14478)
		(layer "In2.Cu")
		(net "M_I_CPU1_SA_DQ<23>")
	)
	(segment
		(start 161.992564 -226.450906)
		(end 161.992564 -226.222306)
		(width 0.14478)
		(layer "In2.Cu")
		(net "M_I_CPU1_SA_DQ<23>")
	)
	(segment
		(start 161.47034 -225.471482)
		(end 161.631884 -225.309938)
		(width 0.14478)
		(layer "In2.Cu")
		(net "M_I_CPU1_SA_DQ<23>")
	)
	(segment
		(start 160.388808 -227.968302)
		(end 160.388808 -227.739702)
		(width 0.14478)
		(layer "In2.Cu")
		(net "M_I_CPU1_SA_DQ<23>")
	)
	(segment
		(start 161.050732 -227.392738)
		(end 161.212276 -227.231194)
		(width 0.14478)
		(layer "In2.Cu")
		(net "M_I_CPU1_SA_DQ<23>")
	)
	(segment
		(start 161.212276 -227.002594)
		(end 160.784032 -226.57435)
		(width 0.14478)
		(layer "In2.Cu")
		(net "M_I_CPU1_SA_DQ<23>")
	)
	(segment
		(start 162.703256 -224.592134)
		(end 163.32708 -225.215958)
		(width 0.14478)
		(layer "In2.Cu")
		(net "M_I_CPU1_SA_DQ<23>")
	)
	(segment
		(start 162.367468 -225.816922)
		(end 162.596068 -225.816922)
		(width 0.14478)
		(layer "In2.Cu")
		(net "M_I_CPU1_SA_DQ<23>")
	)
	(segment
		(start 147.218908 -237.910624)
		(end 147.589748 -237.539784)
		(width 0.0889)
		(layer "In2.Cu")
		(net "M_I_CPU1_SA_DQ<23>")
	)
	(segment
		(start 161.631884 -225.309938)
		(end 161.860484 -225.309938)
		(width 0.14478)
		(layer "In2.Cu")
		(net "M_I_CPU1_SA_DQ<23>")
	)
	(segment
		(start 136.967722 -239.301782)
		(end 136.976104 -239.296956)
		(width 0.0889)
		(layer "In2.Cu")
		(net "M_I_CPU1_SA_DQ<23>")
	)
	(segment
		(start 166.72052 -224.110296)
		(end 170.32859 -224.110296)
		(width 0.14478)
		(layer "In2.Cu")
		(net "M_I_CPU1_SA_DQ<23>")
	)
	(segment
		(start 136.393428 -239.296956)
		(end 136.40181 -239.301782)
		(width 0.0889)
		(layer "In2.Cu")
		(net "M_I_CPU1_SA_DQ<23>")
	)
	(segment
		(start 161.212276 -227.231194)
		(end 161.212276 -227.002594)
		(width 0.14478)
		(layer "In2.Cu")
		(net "M_I_CPU1_SA_DQ<23>")
	)
	(arc
		(start 140.161772 -239.301782)
		(mid 140.444728 -239.377959)
		(end 140.727684 -239.301782)
		(width 0.0889)
		(layer "In2.Cu")
		(net "M_I_CPU1_SA_DQ<23>")
	)
	(arc
		(start 137.916158 -239.296956)
		(mid 138.099666 -239.251462)
		(end 138.281918 -239.301782)
		(width 0.0889)
		(layer "In2.Cu")
		(net "M_I_CPU1_SA_DQ<23>")
	)
	(arc
		(start 139.221718 -239.301782)
		(mid 139.504674 -239.377959)
		(end 139.78763 -239.301782)
		(width 0.0889)
		(layer "In2.Cu")
		(net "M_I_CPU1_SA_DQ<23>")
	)
	(arc
		(start 135.087614 -239.301782)
		(mid 135.269865 -239.251432)
		(end 135.453374 -239.296956)
		(width 0.0889)
		(layer "In2.Cu")
		(net "M_I_CPU1_SA_DQ<23>")
	)
	(arc
		(start 142.98168 -239.301782)
		(mid 143.264636 -239.377959)
		(end 143.547592 -239.301782)
		(width 0.0889)
		(layer "In2.Cu")
		(net "M_I_CPU1_SA_DQ<23>")
	)
	(arc
		(start 131.701794 -239.301782)
		(mid 131.98475 -239.377959)
		(end 132.267706 -239.301782)
		(width 0.0889)
		(layer "In2.Cu")
		(net "M_I_CPU1_SA_DQ<23>")
	)
	(arc
		(start 134.521702 -239.301782)
		(mid 134.804658 -239.377959)
		(end 135.087614 -239.301782)
		(width 0.0889)
		(layer "In2.Cu")
		(net "M_I_CPU1_SA_DQ<23>")
	)
	(arc
		(start 132.276088 -239.296956)
		(mid 132.459596 -239.251462)
		(end 132.641848 -239.301782)
		(width 0.0889)
		(layer "In2.Cu")
		(net "M_I_CPU1_SA_DQ<23>")
	)
	(arc
		(start 129.447798 -239.301782)
		(mid 129.634742 -239.251527)
		(end 129.821686 -239.301782)
		(width 0.0889)
		(layer "In2.Cu")
		(net "M_I_CPU1_SA_DQ<23>")
	)
	(arc
		(start 128.516126 -239.296956)
		(mid 128.699634 -239.251462)
		(end 128.881886 -239.301782)
		(width 0.0889)
		(layer "In2.Cu")
		(net "M_I_CPU1_SA_DQ<23>")
	)
	(arc
		(start 135.461756 -239.301782)
		(mid 135.744712 -239.377959)
		(end 136.027668 -239.301782)
		(width 0.0889)
		(layer "In2.Cu")
		(net "M_I_CPU1_SA_DQ<23>")
	)
	(arc
		(start 128.005078 -239.333532)
		(mid 128.260143 -239.376883)
		(end 128.507744 -239.301782)
		(width 0.0889)
		(layer "In2.Cu")
		(net "M_I_CPU1_SA_DQ<23>")
	)
	(arc
		(start 130.76174 -239.301782)
		(mid 131.044696 -239.377959)
		(end 131.327652 -239.301782)
		(width 0.0889)
		(layer "In2.Cu")
		(net "M_I_CPU1_SA_DQ<23>")
	)
	(arc
		(start 138.281918 -239.301782)
		(mid 138.564874 -239.377959)
		(end 138.84783 -239.301782)
		(width 0.0889)
		(layer "In2.Cu")
		(net "M_I_CPU1_SA_DQ<23>")
	)
	(arc
		(start 133.216142 -239.296956)
		(mid 133.39965 -239.251462)
		(end 133.581902 -239.301782)
		(width 0.0889)
		(layer "In2.Cu")
		(net "M_I_CPU1_SA_DQ<23>")
	)
	(arc
		(start 136.40181 -239.301782)
		(mid 136.684766 -239.377959)
		(end 136.967722 -239.301782)
		(width 0.0889)
		(layer "In2.Cu")
		(net "M_I_CPU1_SA_DQ<23>")
	)
	(arc
		(start 130.387598 -239.301782)
		(mid 130.569849 -239.251432)
		(end 130.753358 -239.296956)
		(width 0.0889)
		(layer "In2.Cu")
		(net "M_I_CPU1_SA_DQ<23>")
	)
	(arc
		(start 129.821686 -239.301782)
		(mid 130.104642 -239.377959)
		(end 130.387598 -239.301782)
		(width 0.0889)
		(layer "In2.Cu")
		(net "M_I_CPU1_SA_DQ<23>")
	)
	(arc
		(start 139.78763 -239.301782)
		(mid 139.969881 -239.251432)
		(end 140.15339 -239.296956)
		(width 0.0889)
		(layer "In2.Cu")
		(net "M_I_CPU1_SA_DQ<23>")
	)
	(arc
		(start 128.881886 -239.301782)
		(mid 129.164842 -239.377959)
		(end 129.447798 -239.301782)
		(width 0.0889)
		(layer "In2.Cu")
		(net "M_I_CPU1_SA_DQ<23>")
	)
	(arc
		(start 141.101826 -239.301782)
		(mid 141.384782 -239.377959)
		(end 141.667738 -239.301782)
		(width 0.0889)
		(layer "In2.Cu")
		(net "M_I_CPU1_SA_DQ<23>")
	)
	(arc
		(start 134.147814 -239.301782)
		(mid 134.334758 -239.251527)
		(end 134.521702 -239.301782)
		(width 0.0889)
		(layer "In2.Cu")
		(net "M_I_CPU1_SA_DQ<23>")
	)
	(arc
		(start 141.67612 -239.296956)
		(mid 141.859628 -239.251462)
		(end 142.04188 -239.301782)
		(width 0.0889)
		(layer "In2.Cu")
		(net "M_I_CPU1_SA_DQ<23>")
	)
	(arc
		(start 133.581902 -239.301782)
		(mid 133.864858 -239.377959)
		(end 134.147814 -239.301782)
		(width 0.0889)
		(layer "In2.Cu")
		(net "M_I_CPU1_SA_DQ<23>")
	)
	(arc
		(start 136.027668 -239.301782)
		(mid 136.209919 -239.251432)
		(end 136.393428 -239.296956)
		(width 0.0889)
		(layer "In2.Cu")
		(net "M_I_CPU1_SA_DQ<23>")
	)
	(arc
		(start 131.327652 -239.301782)
		(mid 131.509903 -239.251432)
		(end 131.693412 -239.296956)
		(width 0.0889)
		(layer "In2.Cu")
		(net "M_I_CPU1_SA_DQ<23>")
	)
	(arc
		(start 142.04188 -239.301782)
		(mid 142.324836 -239.377959)
		(end 142.607792 -239.301782)
		(width 0.0889)
		(layer "In2.Cu")
		(net "M_I_CPU1_SA_DQ<23>")
	)
	(arc
		(start 137.341864 -239.301782)
		(mid 137.62482 -239.377959)
		(end 137.907776 -239.301782)
		(width 0.0889)
		(layer "In2.Cu")
		(net "M_I_CPU1_SA_DQ<23>")
	)
	(arc
		(start 143.547592 -239.301782)
		(mid 143.73479 -239.2514)
		(end 143.921988 -239.301782)
		(width 0.0889)
		(layer "In2.Cu")
		(net "M_I_CPU1_SA_DQ<23>")
	)
	(arc
		(start 132.641848 -239.301782)
		(mid 132.924804 -239.377959)
		(end 133.20776 -239.301782)
		(width 0.0889)
		(layer "In2.Cu")
		(net "M_I_CPU1_SA_DQ<23>")
	)
	(arc
		(start 140.727684 -239.301782)
		(mid 140.909935 -239.251432)
		(end 141.093444 -239.296956)
		(width 0.0889)
		(layer "In2.Cu")
		(net "M_I_CPU1_SA_DQ<23>")
	)
	(arc
		(start 138.84783 -239.301782)
		(mid 139.034774 -239.251527)
		(end 139.221718 -239.301782)
		(width 0.0889)
		(layer "In2.Cu")
		(net "M_I_CPU1_SA_DQ<23>")
	)
	(arc
		(start 142.607792 -239.301782)
		(mid 142.794736 -239.251527)
		(end 142.98168 -239.301782)
		(width 0.0889)
		(layer "In2.Cu")
		(net "M_I_CPU1_SA_DQ<23>")
	)
	(arc
		(start 136.976104 -239.296956)
		(mid 137.159612 -239.251462)
		(end 137.341864 -239.301782)
		(width 0.0889)
		(layer "In2.Cu")
		(net "M_I_CPU1_SA_DQ<23>")
	)
	(segment
		(start 128.69799 -239.080294)
		(end 129.164842 -238.814356)
		(width 0.10668)
		(layer "F.Cu")
		(net "M_I_CPU1_SA_DQ<22>")
	)
	(segment
		(start 149.739604 -236.620304)
		(end 155.565602 -230.794306)
		(width 0.14478)
		(layer "In2.Cu")
		(net "M_I_CPU1_SA_DQ<22>")
	)
	(segment
		(start 156.964634 -229.395274)
		(end 157.126178 -229.23373)
		(width 0.14478)
		(layer "In2.Cu")
		(net "M_I_CPU1_SA_DQ<22>")
	)
	(segment
		(start 156.012134 -229.451662)
		(end 156.012134 -229.223062)
		(width 0.14478)
		(layer "In2.Cu")
		(net "M_I_CPU1_SA_DQ<22>")
	)
	(segment
		(start 155.955746 -230.175562)
		(end 156.184346 -230.175562)
		(width 0.14478)
		(layer "In2.Cu")
		(net "M_I_CPU1_SA_DQ<22>")
	)
	(segment
		(start 159.305498 -227.05441)
		(end 159.467042 -226.892866)
		(width 0.14478)
		(layer "In2.Cu")
		(net "M_I_CPU1_SA_DQ<22>")
	)
	(segment
		(start 159.133286 -226.33051)
		(end 159.133286 -226.10191)
		(width 0.14478)
		(layer "In2.Cu")
		(net "M_I_CPU1_SA_DQ<22>")
	)
	(segment
		(start 158.686754 -227.444554)
		(end 158.352998 -227.110798)
		(width 0.14478)
		(layer "In2.Cu")
		(net "M_I_CPU1_SA_DQ<22>")
	)
	(segment
		(start 173.496732 -223.260412)
		(end 174.34687 -222.410274)
		(width 0.14478)
		(layer "In2.Cu")
		(net "M_I_CPU1_SA_DQ<22>")
	)
	(segment
		(start 140.257784 -238.491776)
		(end 140.266166 -238.48695)
		(width 0.0889)
		(layer "In2.Cu")
		(net "M_I_CPU1_SA_DQ<22>")
	)
	(segment
		(start 170.819826 -223.260412)
		(end 173.496732 -223.260412)
		(width 0.14478)
		(layer "In2.Cu")
		(net "M_I_CPU1_SA_DQ<22>")
	)
	(segment
		(start 155.565602 -230.565706)
		(end 155.231846 -230.23195)
		(width 0.14478)
		(layer "In2.Cu")
		(net "M_I_CPU1_SA_DQ<22>")
	)
	(segment
		(start 143.75257 -238.567722)
		(end 144.51965 -238.567722)
		(width 0.0889)
		(layer "In2.Cu")
		(net "M_I_CPU1_SA_DQ<22>")
	)
	(segment
		(start 157.182566 -228.28123)
		(end 157.516322 -228.614986)
		(width 0.14478)
		(layer "In2.Cu")
		(net "M_I_CPU1_SA_DQ<22>")
	)
	(segment
		(start 157.906466 -228.453442)
		(end 157.906466 -228.224842)
		(width 0.14478)
		(layer "In2.Cu")
		(net "M_I_CPU1_SA_DQ<22>")
	)
	(segment
		(start 157.126178 -229.23373)
		(end 157.126178 -229.00513)
		(width 0.14478)
		(layer "In2.Cu")
		(net "M_I_CPU1_SA_DQ<22>")
	)
	(segment
		(start 179.091082 -222.410274)
		(end 179.516024 -222.835216)
		(width 0.14478)
		(layer "In2.Cu")
		(net "M_I_CPU1_SA_DQ<22>")
	)
	(segment
		(start 133.103366 -238.48695)
		(end 133.111748 -238.491776)
		(width 0.0889)
		(layer "In2.Cu")
		(net "M_I_CPU1_SA_DQ<22>")
	)
	(segment
		(start 146.845528 -237.369604)
		(end 147.594828 -236.620304)
		(width 0.0889)
		(layer "In2.Cu")
		(net "M_I_CPU1_SA_DQ<22>")
	)
	(segment
		(start 139.31773 -238.491776)
		(end 139.326112 -238.48695)
		(width 0.0889)
		(layer "In2.Cu")
		(net "M_I_CPU1_SA_DQ<22>")
	)
	(segment
		(start 135.557768 -238.491776)
		(end 135.56615 -238.48695)
		(width 0.0889)
		(layer "In2.Cu")
		(net "M_I_CPU1_SA_DQ<22>")
	)
	(segment
		(start 156.012134 -229.223062)
		(end 156.173678 -229.061518)
		(width 0.14478)
		(layer "In2.Cu")
		(net "M_I_CPU1_SA_DQ<22>")
	)
	(segment
		(start 155.62199 -229.841806)
		(end 155.955746 -230.175562)
		(width 0.14478)
		(layer "In2.Cu")
		(net "M_I_CPU1_SA_DQ<22>")
	)
	(segment
		(start 156.792422 -228.442774)
		(end 156.953966 -228.28123)
		(width 0.14478)
		(layer "In2.Cu")
		(net "M_I_CPU1_SA_DQ<22>")
	)
	(segment
		(start 134.617714 -238.491776)
		(end 134.626096 -238.48695)
		(width 0.0889)
		(layer "In2.Cu")
		(net "M_I_CPU1_SA_DQ<22>")
	)
	(segment
		(start 156.34589 -229.785418)
		(end 156.012134 -229.451662)
		(width 0.14478)
		(layer "In2.Cu")
		(net "M_I_CPU1_SA_DQ<22>")
	)
	(segment
		(start 142.503398 -238.48695)
		(end 142.51178 -238.491776)
		(width 0.0889)
		(layer "In2.Cu")
		(net "M_I_CPU1_SA_DQ<22>")
	)
	(segment
		(start 157.516322 -228.614986)
		(end 157.744922 -228.614986)
		(width 0.14478)
		(layer "In2.Cu")
		(net "M_I_CPU1_SA_DQ<22>")
	)
	(segment
		(start 147.594828 -236.620304)
		(end 147.919186 -236.620304)
		(width 0.0889)
		(layer "In2.Cu")
		(net "M_I_CPU1_SA_DQ<22>")
	)
	(segment
		(start 157.906466 -228.224842)
		(end 157.57271 -227.891086)
		(width 0.14478)
		(layer "In2.Cu")
		(net "M_I_CPU1_SA_DQ<22>")
	)
	(segment
		(start 159.076898 -227.05441)
		(end 159.305498 -227.05441)
		(width 0.14478)
		(layer "In2.Cu")
		(net "M_I_CPU1_SA_DQ<22>")
	)
	(segment
		(start 159.467042 -226.892866)
		(end 159.467042 -226.664266)
		(width 0.14478)
		(layer "In2.Cu")
		(net "M_I_CPU1_SA_DQ<22>")
	)
	(segment
		(start 157.126178 -229.00513)
		(end 156.792422 -228.671374)
		(width 0.14478)
		(layer "In2.Cu")
		(net "M_I_CPU1_SA_DQ<22>")
	)
	(segment
		(start 147.919186 -236.620304)
		(end 149.739604 -236.620304)
		(width 0.14478)
		(layer "In2.Cu")
		(net "M_I_CPU1_SA_DQ<22>")
	)
	(segment
		(start 156.736034 -229.395274)
		(end 156.964634 -229.395274)
		(width 0.14478)
		(layer "In2.Cu")
		(net "M_I_CPU1_SA_DQ<22>")
	)
	(segment
		(start 129.164842 -238.814356)
		(end 129.318766 -238.548926)
		(width 0.0889)
		(layer "In2.Cu")
		(net "M_I_CPU1_SA_DQ<22>")
	)
	(segment
		(start 156.792422 -228.671374)
		(end 156.792422 -228.442774)
		(width 0.14478)
		(layer "In2.Cu")
		(net "M_I_CPU1_SA_DQ<22>")
	)
	(segment
		(start 155.231846 -230.23195)
		(end 155.231846 -230.00335)
		(width 0.14478)
		(layer "In2.Cu")
		(net "M_I_CPU1_SA_DQ<22>")
	)
	(segment
		(start 129.917698 -238.491776)
		(end 129.92608 -238.48695)
		(width 0.0889)
		(layer "In2.Cu")
		(net "M_I_CPU1_SA_DQ<22>")
	)
	(segment
		(start 156.953966 -228.28123)
		(end 157.182566 -228.28123)
		(width 0.14478)
		(layer "In2.Cu")
		(net "M_I_CPU1_SA_DQ<22>")
	)
	(segment
		(start 143.077692 -238.491776)
		(end 143.086074 -238.48695)
		(width 0.0889)
		(layer "In2.Cu")
		(net "M_I_CPU1_SA_DQ<22>")
	)
	(segment
		(start 156.34589 -230.014018)
		(end 156.34589 -229.785418)
		(width 0.14478)
		(layer "In2.Cu")
		(net "M_I_CPU1_SA_DQ<22>")
	)
	(segment
		(start 157.57271 -227.662486)
		(end 157.734254 -227.500942)
		(width 0.14478)
		(layer "In2.Cu")
		(net "M_I_CPU1_SA_DQ<22>")
	)
	(segment
		(start 157.744922 -228.614986)
		(end 157.906466 -228.453442)
		(width 0.14478)
		(layer "In2.Cu")
		(net "M_I_CPU1_SA_DQ<22>")
	)
	(segment
		(start 158.352998 -226.882198)
		(end 158.514542 -226.720654)
		(width 0.14478)
		(layer "In2.Cu")
		(net "M_I_CPU1_SA_DQ<22>")
	)
	(segment
		(start 158.29661 -227.834698)
		(end 158.52521 -227.834698)
		(width 0.14478)
		(layer "In2.Cu")
		(net "M_I_CPU1_SA_DQ<22>")
	)
	(segment
		(start 157.57271 -227.891086)
		(end 157.57271 -227.662486)
		(width 0.14478)
		(layer "In2.Cu")
		(net "M_I_CPU1_SA_DQ<22>")
	)
	(segment
		(start 144.882108 -238.205264)
		(end 145.326608 -238.205264)
		(width 0.0889)
		(layer "In2.Cu")
		(net "M_I_CPU1_SA_DQ<22>")
	)
	(segment
		(start 156.402278 -229.061518)
		(end 156.736034 -229.395274)
		(width 0.14478)
		(layer "In2.Cu")
		(net "M_I_CPU1_SA_DQ<22>")
	)
	(segment
		(start 130.857752 -238.491776)
		(end 130.866134 -238.48695)
		(width 0.0889)
		(layer "In2.Cu")
		(net "M_I_CPU1_SA_DQ<22>")
	)
	(segment
		(start 161.974784 -223.260412)
		(end 166.22776 -223.260412)
		(width 0.14478)
		(layer "In2.Cu")
		(net "M_I_CPU1_SA_DQ<22>")
	)
	(segment
		(start 157.734254 -227.500942)
		(end 157.962854 -227.500942)
		(width 0.14478)
		(layer "In2.Cu")
		(net "M_I_CPU1_SA_DQ<22>")
	)
	(segment
		(start 156.184346 -230.175562)
		(end 156.34589 -230.014018)
		(width 0.14478)
		(layer "In2.Cu")
		(net "M_I_CPU1_SA_DQ<22>")
	)
	(segment
		(start 158.743142 -226.720654)
		(end 159.076898 -227.05441)
		(width 0.14478)
		(layer "In2.Cu")
		(net "M_I_CPU1_SA_DQ<22>")
	)
	(segment
		(start 129.318766 -238.548926)
		(end 129.414778 -238.523526)
		(width 0.0889)
		(layer "In2.Cu")
		(net "M_I_CPU1_SA_DQ<22>")
	)
	(segment
		(start 134.04342 -238.48695)
		(end 134.051802 -238.491776)
		(width 0.0889)
		(layer "In2.Cu")
		(net "M_I_CPU1_SA_DQ<22>")
	)
	(segment
		(start 144.51965 -238.567722)
		(end 144.882108 -238.205264)
		(width 0.0889)
		(layer "In2.Cu")
		(net "M_I_CPU1_SA_DQ<22>")
	)
	(segment
		(start 167.077898 -222.410274)
		(end 169.969688 -222.410274)
		(width 0.14478)
		(layer "In2.Cu")
		(net "M_I_CPU1_SA_DQ<22>")
	)
	(segment
		(start 155.39339 -229.841806)
		(end 155.62199 -229.841806)
		(width 0.14478)
		(layer "In2.Cu")
		(net "M_I_CPU1_SA_DQ<22>")
	)
	(segment
		(start 155.231846 -230.00335)
		(end 155.39339 -229.841806)
		(width 0.14478)
		(layer "In2.Cu")
		(net "M_I_CPU1_SA_DQ<22>")
	)
	(segment
		(start 166.22776 -223.260412)
		(end 167.077898 -222.410274)
		(width 0.14478)
		(layer "In2.Cu")
		(net "M_I_CPU1_SA_DQ<22>")
	)
	(segment
		(start 146.162268 -237.369604)
		(end 146.845528 -237.369604)
		(width 0.0889)
		(layer "In2.Cu")
		(net "M_I_CPU1_SA_DQ<22>")
	)
	(segment
		(start 158.352998 -227.110798)
		(end 158.352998 -226.882198)
		(width 0.14478)
		(layer "In2.Cu")
		(net "M_I_CPU1_SA_DQ<22>")
	)
	(segment
		(start 156.173678 -229.061518)
		(end 156.402278 -229.061518)
		(width 0.14478)
		(layer "In2.Cu")
		(net "M_I_CPU1_SA_DQ<22>")
	)
	(segment
		(start 158.686754 -227.673154)
		(end 158.686754 -227.444554)
		(width 0.14478)
		(layer "In2.Cu")
		(net "M_I_CPU1_SA_DQ<22>")
	)
	(segment
		(start 159.133286 -226.10191)
		(end 161.974784 -223.260412)
		(width 0.14478)
		(layer "In2.Cu")
		(net "M_I_CPU1_SA_DQ<22>")
	)
	(segment
		(start 145.326608 -238.205264)
		(end 146.162268 -237.369604)
		(width 0.0889)
		(layer "In2.Cu")
		(net "M_I_CPU1_SA_DQ<22>")
	)
	(segment
		(start 155.565602 -230.794306)
		(end 155.565602 -230.565706)
		(width 0.14478)
		(layer "In2.Cu")
		(net "M_I_CPU1_SA_DQ<22>")
	)
	(segment
		(start 157.962854 -227.500942)
		(end 158.29661 -227.834698)
		(width 0.14478)
		(layer "In2.Cu")
		(net "M_I_CPU1_SA_DQ<22>")
	)
	(segment
		(start 169.969688 -222.410274)
		(end 170.819826 -223.260412)
		(width 0.14478)
		(layer "In2.Cu")
		(net "M_I_CPU1_SA_DQ<22>")
	)
	(segment
		(start 138.743436 -238.48695)
		(end 138.751818 -238.491776)
		(width 0.0889)
		(layer "In2.Cu")
		(net "M_I_CPU1_SA_DQ<22>")
	)
	(segment
		(start 137.803382 -238.48695)
		(end 137.811764 -238.491776)
		(width 0.0889)
		(layer "In2.Cu")
		(net "M_I_CPU1_SA_DQ<22>")
	)
	(segment
		(start 158.52521 -227.834698)
		(end 158.686754 -227.673154)
		(width 0.14478)
		(layer "In2.Cu")
		(net "M_I_CPU1_SA_DQ<22>")
	)
	(segment
		(start 159.467042 -226.664266)
		(end 159.133286 -226.33051)
		(width 0.14478)
		(layer "In2.Cu")
		(net "M_I_CPU1_SA_DQ<22>")
	)
	(segment
		(start 158.514542 -226.720654)
		(end 158.743142 -226.720654)
		(width 0.14478)
		(layer "In2.Cu")
		(net "M_I_CPU1_SA_DQ<22>")
	)
	(segment
		(start 174.34687 -222.410274)
		(end 179.091082 -222.410274)
		(width 0.14478)
		(layer "In2.Cu")
		(net "M_I_CPU1_SA_DQ<22>")
	)
	(arc
		(start 131.231894 -238.491776)
		(mid 131.51485 -238.567953)
		(end 131.797806 -238.491776)
		(width 0.0889)
		(layer "In2.Cu")
		(net "M_I_CPU1_SA_DQ<22>")
	)
	(arc
		(start 133.111748 -238.491776)
		(mid 133.394704 -238.567953)
		(end 133.67766 -238.491776)
		(width 0.0889)
		(layer "In2.Cu")
		(net "M_I_CPU1_SA_DQ<22>")
	)
	(arc
		(start 142.51178 -238.491776)
		(mid 142.794736 -238.567953)
		(end 143.077692 -238.491776)
		(width 0.0889)
		(layer "In2.Cu")
		(net "M_I_CPU1_SA_DQ<22>")
	)
	(arc
		(start 132.171694 -238.491776)
		(mid 132.45465 -238.567953)
		(end 132.737606 -238.491776)
		(width 0.0889)
		(layer "In2.Cu")
		(net "M_I_CPU1_SA_DQ<22>")
	)
	(arc
		(start 140.631926 -238.491776)
		(mid 140.914882 -238.567953)
		(end 141.197838 -238.491776)
		(width 0.0889)
		(layer "In2.Cu")
		(net "M_I_CPU1_SA_DQ<22>")
	)
	(arc
		(start 135.93191 -238.491776)
		(mid 136.214866 -238.567953)
		(end 136.497822 -238.491776)
		(width 0.0889)
		(layer "In2.Cu")
		(net "M_I_CPU1_SA_DQ<22>")
	)
	(arc
		(start 134.626096 -238.48695)
		(mid 134.809604 -238.441456)
		(end 134.991856 -238.491776)
		(width 0.0889)
		(layer "In2.Cu")
		(net "M_I_CPU1_SA_DQ<22>")
	)
	(arc
		(start 132.737606 -238.491776)
		(mid 132.919857 -238.441426)
		(end 133.103366 -238.48695)
		(width 0.0889)
		(layer "In2.Cu")
		(net "M_I_CPU1_SA_DQ<22>")
	)
	(arc
		(start 133.67766 -238.491776)
		(mid 133.859911 -238.441426)
		(end 134.04342 -238.48695)
		(width 0.0889)
		(layer "In2.Cu")
		(net "M_I_CPU1_SA_DQ<22>")
	)
	(arc
		(start 136.87171 -238.491776)
		(mid 137.154666 -238.567953)
		(end 137.437622 -238.491776)
		(width 0.0889)
		(layer "In2.Cu")
		(net "M_I_CPU1_SA_DQ<22>")
	)
	(arc
		(start 129.92608 -238.48695)
		(mid 130.109588 -238.441456)
		(end 130.29184 -238.491776)
		(width 0.0889)
		(layer "In2.Cu")
		(net "M_I_CPU1_SA_DQ<22>")
	)
	(arc
		(start 141.197838 -238.491776)
		(mid 141.384782 -238.441521)
		(end 141.571726 -238.491776)
		(width 0.0889)
		(layer "In2.Cu")
		(net "M_I_CPU1_SA_DQ<22>")
	)
	(arc
		(start 142.137638 -238.491776)
		(mid 142.319889 -238.441426)
		(end 142.503398 -238.48695)
		(width 0.0889)
		(layer "In2.Cu")
		(net "M_I_CPU1_SA_DQ<22>")
	)
	(arc
		(start 139.691872 -238.491776)
		(mid 139.974828 -238.567953)
		(end 140.257784 -238.491776)
		(width 0.0889)
		(layer "In2.Cu")
		(net "M_I_CPU1_SA_DQ<22>")
	)
	(arc
		(start 134.051802 -238.491776)
		(mid 134.334758 -238.567953)
		(end 134.617714 -238.491776)
		(width 0.0889)
		(layer "In2.Cu")
		(net "M_I_CPU1_SA_DQ<22>")
	)
	(arc
		(start 141.571726 -238.491776)
		(mid 141.854682 -238.567953)
		(end 142.137638 -238.491776)
		(width 0.0889)
		(layer "In2.Cu")
		(net "M_I_CPU1_SA_DQ<22>")
	)
	(arc
		(start 143.086074 -238.48695)
		(mid 143.269582 -238.441456)
		(end 143.451834 -238.491776)
		(width 0.0889)
		(layer "In2.Cu")
		(net "M_I_CPU1_SA_DQ<22>")
	)
	(arc
		(start 136.497822 -238.491776)
		(mid 136.684766 -238.441521)
		(end 136.87171 -238.491776)
		(width 0.0889)
		(layer "In2.Cu")
		(net "M_I_CPU1_SA_DQ<22>")
	)
	(arc
		(start 139.326112 -238.48695)
		(mid 139.50962 -238.441456)
		(end 139.691872 -238.491776)
		(width 0.0889)
		(layer "In2.Cu")
		(net "M_I_CPU1_SA_DQ<22>")
	)
	(arc
		(start 135.56615 -238.48695)
		(mid 135.749658 -238.441456)
		(end 135.93191 -238.491776)
		(width 0.0889)
		(layer "In2.Cu")
		(net "M_I_CPU1_SA_DQ<22>")
	)
	(arc
		(start 129.414778 -238.523526)
		(mid 129.669986 -238.567003)
		(end 129.917698 -238.491776)
		(width 0.0889)
		(layer "In2.Cu")
		(net "M_I_CPU1_SA_DQ<22>")
	)
	(arc
		(start 143.451834 -238.491776)
		(mid 143.596878 -238.550819)
		(end 143.75257 -238.567722)
		(width 0.0889)
		(layer "In2.Cu")
		(net "M_I_CPU1_SA_DQ<22>")
	)
	(arc
		(start 130.866134 -238.48695)
		(mid 131.049642 -238.441456)
		(end 131.231894 -238.491776)
		(width 0.0889)
		(layer "In2.Cu")
		(net "M_I_CPU1_SA_DQ<22>")
	)
	(arc
		(start 137.811764 -238.491776)
		(mid 138.09472 -238.567953)
		(end 138.377676 -238.491776)
		(width 0.0889)
		(layer "In2.Cu")
		(net "M_I_CPU1_SA_DQ<22>")
	)
	(arc
		(start 140.266166 -238.48695)
		(mid 140.449674 -238.441456)
		(end 140.631926 -238.491776)
		(width 0.0889)
		(layer "In2.Cu")
		(net "M_I_CPU1_SA_DQ<22>")
	)
	(arc
		(start 134.991856 -238.491776)
		(mid 135.274812 -238.567953)
		(end 135.557768 -238.491776)
		(width 0.0889)
		(layer "In2.Cu")
		(net "M_I_CPU1_SA_DQ<22>")
	)
	(arc
		(start 130.29184 -238.491776)
		(mid 130.574796 -238.567953)
		(end 130.857752 -238.491776)
		(width 0.0889)
		(layer "In2.Cu")
		(net "M_I_CPU1_SA_DQ<22>")
	)
	(arc
		(start 137.437622 -238.491776)
		(mid 137.619873 -238.441426)
		(end 137.803382 -238.48695)
		(width 0.0889)
		(layer "In2.Cu")
		(net "M_I_CPU1_SA_DQ<22>")
	)
	(arc
		(start 138.377676 -238.491776)
		(mid 138.559927 -238.441426)
		(end 138.743436 -238.48695)
		(width 0.0889)
		(layer "In2.Cu")
		(net "M_I_CPU1_SA_DQ<22>")
	)
	(arc
		(start 138.751818 -238.491776)
		(mid 139.034774 -238.567953)
		(end 139.31773 -238.491776)
		(width 0.0889)
		(layer "In2.Cu")
		(net "M_I_CPU1_SA_DQ<22>")
	)
	(arc
		(start 131.797806 -238.491776)
		(mid 131.98475 -238.441521)
		(end 132.171694 -238.491776)
		(width 0.0889)
		(layer "In2.Cu")
		(net "M_I_CPU1_SA_DQ<22>")
	)
	(segment
		(start 127.757936 -239.080294)
		(end 128.224788 -238.814356)
		(width 0.10668)
		(layer "F.Cu")
		(net "M_I_CPU1_SA_DQ<21>")
	)
	(segment
		(start 174.640748 -223.260412)
		(end 181.391306 -223.260412)
		(width 0.14478)
		(layer "In2.Cu")
		(net "M_I_CPU1_SA_DQ<21>")
	)
	(segment
		(start 128.40335 -239.141762)
		(end 128.411732 -239.136936)
		(width 0.0889)
		(layer "In2.Cu")
		(net "M_I_CPU1_SA_DQ<21>")
	)
	(segment
		(start 142.503398 -239.141762)
		(end 142.51178 -239.136936)
		(width 0.0889)
		(layer "In2.Cu")
		(net "M_I_CPU1_SA_DQ<21>")
	)
	(segment
		(start 182.11038 -223.423226)
		(end 182.273194 -223.260412)
		(width 0.14478)
		(layer "In2.Cu")
		(net "M_I_CPU1_SA_DQ<21>")
	)
	(segment
		(start 147.944586 -237.074964)
		(end 149.92096 -237.074964)
		(width 0.14478)
		(layer "In2.Cu")
		(net "M_I_CPU1_SA_DQ<21>")
	)
	(segment
		(start 170.999658 -224.110296)
		(end 173.790864 -224.110296)
		(width 0.14478)
		(layer "In2.Cu")
		(net "M_I_CPU1_SA_DQ<21>")
	)
	(segment
		(start 149.92096 -237.074964)
		(end 159.96031 -227.035614)
		(width 0.14478)
		(layer "In2.Cu")
		(net "M_I_CPU1_SA_DQ<21>")
	)
	(segment
		(start 129.917698 -239.136936)
		(end 129.92608 -239.141762)
		(width 0.0889)
		(layer "In2.Cu")
		(net "M_I_CPU1_SA_DQ<21>")
	)
	(segment
		(start 161.77768 -224.110296)
		(end 166.024814 -224.110296)
		(width 0.14478)
		(layer "In2.Cu")
		(net "M_I_CPU1_SA_DQ<21>")
	)
	(segment
		(start 181.716934 -223.860106)
		(end 181.947566 -223.860106)
		(width 0.14478)
		(layer "In2.Cu")
		(net "M_I_CPU1_SA_DQ<21>")
	)
	(segment
		(start 159.96031 -227.035614)
		(end 159.96031 -225.927666)
		(width 0.14478)
		(layer "In2.Cu")
		(net "M_I_CPU1_SA_DQ<21>")
	)
	(segment
		(start 181.391306 -223.260412)
		(end 181.55412 -223.423226)
		(width 0.14478)
		(layer "In2.Cu")
		(net "M_I_CPU1_SA_DQ<21>")
	)
	(segment
		(start 139.31773 -239.136936)
		(end 139.326112 -239.141762)
		(width 0.0889)
		(layer "In2.Cu")
		(net "M_I_CPU1_SA_DQ<21>")
	)
	(segment
		(start 140.257784 -239.136936)
		(end 140.266166 -239.141762)
		(width 0.0889)
		(layer "In2.Cu")
		(net "M_I_CPU1_SA_DQ<21>")
	)
	(segment
		(start 145.517108 -238.454184)
		(end 146.332448 -237.638844)
		(width 0.0889)
		(layer "In2.Cu")
		(net "M_I_CPU1_SA_DQ<21>")
	)
	(segment
		(start 129.343404 -239.141762)
		(end 129.351786 -239.136936)
		(width 0.0889)
		(layer "In2.Cu")
		(net "M_I_CPU1_SA_DQ<21>")
	)
	(segment
		(start 166.024814 -224.110296)
		(end 166.874698 -223.260412)
		(width 0.14478)
		(layer "In2.Cu")
		(net "M_I_CPU1_SA_DQ<21>")
	)
	(segment
		(start 130.857752 -239.136936)
		(end 130.866134 -239.141762)
		(width 0.0889)
		(layer "In2.Cu")
		(net "M_I_CPU1_SA_DQ<21>")
	)
	(segment
		(start 173.790864 -224.110296)
		(end 174.640748 -223.260412)
		(width 0.14478)
		(layer "In2.Cu")
		(net "M_I_CPU1_SA_DQ<21>")
	)
	(segment
		(start 144.392142 -239.06099)
		(end 144.998948 -238.454184)
		(width 0.0889)
		(layer "In2.Cu")
		(net "M_I_CPU1_SA_DQ<21>")
	)
	(segment
		(start 166.874698 -223.260412)
		(end 170.149774 -223.260412)
		(width 0.14478)
		(layer "In2.Cu")
		(net "M_I_CPU1_SA_DQ<21>")
	)
	(segment
		(start 137.803382 -239.141762)
		(end 137.811764 -239.136936)
		(width 0.0889)
		(layer "In2.Cu")
		(net "M_I_CPU1_SA_DQ<21>")
	)
	(segment
		(start 133.103366 -239.141762)
		(end 133.111748 -239.136936)
		(width 0.0889)
		(layer "In2.Cu")
		(net "M_I_CPU1_SA_DQ<21>")
	)
	(segment
		(start 159.96031 -225.927666)
		(end 161.77768 -224.110296)
		(width 0.14478)
		(layer "In2.Cu")
		(net "M_I_CPU1_SA_DQ<21>")
	)
	(segment
		(start 181.55412 -223.697292)
		(end 181.716934 -223.860106)
		(width 0.14478)
		(layer "In2.Cu")
		(net "M_I_CPU1_SA_DQ<21>")
	)
	(segment
		(start 146.332448 -237.638844)
		(end 147.046188 -237.638844)
		(width 0.0889)
		(layer "In2.Cu")
		(net "M_I_CPU1_SA_DQ<21>")
	)
	(segment
		(start 128.224788 -238.814356)
		(end 128.07061 -239.079786)
		(width 0.0889)
		(layer "In2.Cu")
		(net "M_I_CPU1_SA_DQ<21>")
	)
	(segment
		(start 144.998948 -238.454184)
		(end 145.517108 -238.454184)
		(width 0.0889)
		(layer "In2.Cu")
		(net "M_I_CPU1_SA_DQ<21>")
	)
	(segment
		(start 181.947566 -223.860106)
		(end 182.11038 -223.697292)
		(width 0.14478)
		(layer "In2.Cu")
		(net "M_I_CPU1_SA_DQ<21>")
	)
	(segment
		(start 143.75257 -239.06099)
		(end 144.392142 -239.06099)
		(width 0.0889)
		(layer "In2.Cu")
		(net "M_I_CPU1_SA_DQ<21>")
	)
	(segment
		(start 128.07061 -239.079786)
		(end 128.092962 -239.163098)
		(width 0.0889)
		(layer "In2.Cu")
		(net "M_I_CPU1_SA_DQ<21>")
	)
	(segment
		(start 135.557768 -239.136936)
		(end 135.56615 -239.141762)
		(width 0.0889)
		(layer "In2.Cu")
		(net "M_I_CPU1_SA_DQ<21>")
	)
	(segment
		(start 182.273194 -223.260412)
		(end 183.19115 -223.260412)
		(width 0.14478)
		(layer "In2.Cu")
		(net "M_I_CPU1_SA_DQ<21>")
	)
	(segment
		(start 147.610068 -237.074964)
		(end 147.944586 -237.074964)
		(width 0.0889)
		(layer "In2.Cu")
		(net "M_I_CPU1_SA_DQ<21>")
	)
	(segment
		(start 183.19115 -223.260412)
		(end 183.616092 -223.685354)
		(width 0.14478)
		(layer "In2.Cu")
		(net "M_I_CPU1_SA_DQ<21>")
	)
	(segment
		(start 181.55412 -223.423226)
		(end 181.55412 -223.697292)
		(width 0.14478)
		(layer "In2.Cu")
		(net "M_I_CPU1_SA_DQ<21>")
	)
	(segment
		(start 134.617714 -239.136936)
		(end 134.626096 -239.141762)
		(width 0.0889)
		(layer "In2.Cu")
		(net "M_I_CPU1_SA_DQ<21>")
	)
	(segment
		(start 134.04342 -239.141762)
		(end 134.051802 -239.136936)
		(width 0.0889)
		(layer "In2.Cu")
		(net "M_I_CPU1_SA_DQ<21>")
	)
	(segment
		(start 182.11038 -223.697292)
		(end 182.11038 -223.423226)
		(width 0.14478)
		(layer "In2.Cu")
		(net "M_I_CPU1_SA_DQ<21>")
	)
	(segment
		(start 143.077692 -239.136936)
		(end 143.086074 -239.141762)
		(width 0.0889)
		(layer "In2.Cu")
		(net "M_I_CPU1_SA_DQ<21>")
	)
	(segment
		(start 147.046188 -237.638844)
		(end 147.610068 -237.074964)
		(width 0.0889)
		(layer "In2.Cu")
		(net "M_I_CPU1_SA_DQ<21>")
	)
	(segment
		(start 138.743436 -239.141762)
		(end 138.751818 -239.136936)
		(width 0.0889)
		(layer "In2.Cu")
		(net "M_I_CPU1_SA_DQ<21>")
	)
	(segment
		(start 170.149774 -223.260412)
		(end 170.999658 -224.110296)
		(width 0.14478)
		(layer "In2.Cu")
		(net "M_I_CPU1_SA_DQ<21>")
	)
	(arc
		(start 131.231894 -239.136936)
		(mid 131.51485 -239.060759)
		(end 131.797806 -239.136936)
		(width 0.0889)
		(layer "In2.Cu")
		(net "M_I_CPU1_SA_DQ<21>")
	)
	(arc
		(start 130.866134 -239.141762)
		(mid 131.049642 -239.187256)
		(end 131.231894 -239.136936)
		(width 0.0889)
		(layer "In2.Cu")
		(net "M_I_CPU1_SA_DQ<21>")
	)
	(arc
		(start 128.092962 -239.163098)
		(mid 128.250472 -239.186296)
		(end 128.40335 -239.141762)
		(width 0.0889)
		(layer "In2.Cu")
		(net "M_I_CPU1_SA_DQ<21>")
	)
	(arc
		(start 138.377676 -239.136936)
		(mid 138.559927 -239.187286)
		(end 138.743436 -239.141762)
		(width 0.0889)
		(layer "In2.Cu")
		(net "M_I_CPU1_SA_DQ<21>")
	)
	(arc
		(start 142.51178 -239.136936)
		(mid 142.794736 -239.060759)
		(end 143.077692 -239.136936)
		(width 0.0889)
		(layer "In2.Cu")
		(net "M_I_CPU1_SA_DQ<21>")
	)
	(arc
		(start 136.87171 -239.136936)
		(mid 137.154666 -239.060759)
		(end 137.437622 -239.136936)
		(width 0.0889)
		(layer "In2.Cu")
		(net "M_I_CPU1_SA_DQ<21>")
	)
	(arc
		(start 141.571726 -239.136936)
		(mid 141.854682 -239.060759)
		(end 142.137638 -239.136936)
		(width 0.0889)
		(layer "In2.Cu")
		(net "M_I_CPU1_SA_DQ<21>")
	)
	(arc
		(start 134.991856 -239.136936)
		(mid 135.274812 -239.060759)
		(end 135.557768 -239.136936)
		(width 0.0889)
		(layer "In2.Cu")
		(net "M_I_CPU1_SA_DQ<21>")
	)
	(arc
		(start 138.751818 -239.136936)
		(mid 139.034774 -239.060759)
		(end 139.31773 -239.136936)
		(width 0.0889)
		(layer "In2.Cu")
		(net "M_I_CPU1_SA_DQ<21>")
	)
	(arc
		(start 133.67766 -239.136936)
		(mid 133.859911 -239.187286)
		(end 134.04342 -239.141762)
		(width 0.0889)
		(layer "In2.Cu")
		(net "M_I_CPU1_SA_DQ<21>")
	)
	(arc
		(start 135.93191 -239.136936)
		(mid 136.214866 -239.060759)
		(end 136.497822 -239.136936)
		(width 0.0889)
		(layer "In2.Cu")
		(net "M_I_CPU1_SA_DQ<21>")
	)
	(arc
		(start 132.737606 -239.136936)
		(mid 132.919857 -239.187286)
		(end 133.103366 -239.141762)
		(width 0.0889)
		(layer "In2.Cu")
		(net "M_I_CPU1_SA_DQ<21>")
	)
	(arc
		(start 140.631926 -239.136936)
		(mid 140.914882 -239.060759)
		(end 141.197838 -239.136936)
		(width 0.0889)
		(layer "In2.Cu")
		(net "M_I_CPU1_SA_DQ<21>")
	)
	(arc
		(start 143.086074 -239.141762)
		(mid 143.269582 -239.187256)
		(end 143.451834 -239.136936)
		(width 0.0889)
		(layer "In2.Cu")
		(net "M_I_CPU1_SA_DQ<21>")
	)
	(arc
		(start 140.266166 -239.141762)
		(mid 140.449674 -239.187256)
		(end 140.631926 -239.136936)
		(width 0.0889)
		(layer "In2.Cu")
		(net "M_I_CPU1_SA_DQ<21>")
	)
	(arc
		(start 137.811764 -239.136936)
		(mid 138.09472 -239.060759)
		(end 138.377676 -239.136936)
		(width 0.0889)
		(layer "In2.Cu")
		(net "M_I_CPU1_SA_DQ<21>")
	)
	(arc
		(start 132.171694 -239.136936)
		(mid 132.45465 -239.060759)
		(end 132.737606 -239.136936)
		(width 0.0889)
		(layer "In2.Cu")
		(net "M_I_CPU1_SA_DQ<21>")
	)
	(arc
		(start 137.437622 -239.136936)
		(mid 137.619873 -239.187286)
		(end 137.803382 -239.141762)
		(width 0.0889)
		(layer "In2.Cu")
		(net "M_I_CPU1_SA_DQ<21>")
	)
	(arc
		(start 142.137638 -239.136936)
		(mid 142.319889 -239.187286)
		(end 142.503398 -239.141762)
		(width 0.0889)
		(layer "In2.Cu")
		(net "M_I_CPU1_SA_DQ<21>")
	)
	(arc
		(start 128.977644 -239.136936)
		(mid 129.159895 -239.187286)
		(end 129.343404 -239.141762)
		(width 0.0889)
		(layer "In2.Cu")
		(net "M_I_CPU1_SA_DQ<21>")
	)
	(arc
		(start 139.691872 -239.136936)
		(mid 139.974828 -239.060759)
		(end 140.257784 -239.136936)
		(width 0.0889)
		(layer "In2.Cu")
		(net "M_I_CPU1_SA_DQ<21>")
	)
	(arc
		(start 129.92608 -239.141762)
		(mid 130.109588 -239.187256)
		(end 130.29184 -239.136936)
		(width 0.0889)
		(layer "In2.Cu")
		(net "M_I_CPU1_SA_DQ<21>")
	)
	(arc
		(start 130.29184 -239.136936)
		(mid 130.574796 -239.060759)
		(end 130.857752 -239.136936)
		(width 0.0889)
		(layer "In2.Cu")
		(net "M_I_CPU1_SA_DQ<21>")
	)
	(arc
		(start 129.351786 -239.136936)
		(mid 129.634742 -239.060759)
		(end 129.917698 -239.136936)
		(width 0.0889)
		(layer "In2.Cu")
		(net "M_I_CPU1_SA_DQ<21>")
	)
	(arc
		(start 136.497822 -239.136936)
		(mid 136.684766 -239.187191)
		(end 136.87171 -239.136936)
		(width 0.0889)
		(layer "In2.Cu")
		(net "M_I_CPU1_SA_DQ<21>")
	)
	(arc
		(start 128.411732 -239.136936)
		(mid 128.694688 -239.060759)
		(end 128.977644 -239.136936)
		(width 0.0889)
		(layer "In2.Cu")
		(net "M_I_CPU1_SA_DQ<21>")
	)
	(arc
		(start 139.326112 -239.141762)
		(mid 139.50962 -239.187256)
		(end 139.691872 -239.136936)
		(width 0.0889)
		(layer "In2.Cu")
		(net "M_I_CPU1_SA_DQ<21>")
	)
	(arc
		(start 131.797806 -239.136936)
		(mid 131.98475 -239.187191)
		(end 132.171694 -239.136936)
		(width 0.0889)
		(layer "In2.Cu")
		(net "M_I_CPU1_SA_DQ<21>")
	)
	(arc
		(start 133.111748 -239.136936)
		(mid 133.394704 -239.060759)
		(end 133.67766 -239.136936)
		(width 0.0889)
		(layer "In2.Cu")
		(net "M_I_CPU1_SA_DQ<21>")
	)
	(arc
		(start 134.051802 -239.136936)
		(mid 134.334758 -239.060759)
		(end 134.617714 -239.136936)
		(width 0.0889)
		(layer "In2.Cu")
		(net "M_I_CPU1_SA_DQ<21>")
	)
	(arc
		(start 135.56615 -239.141762)
		(mid 135.749658 -239.187256)
		(end 135.93191 -239.136936)
		(width 0.0889)
		(layer "In2.Cu")
		(net "M_I_CPU1_SA_DQ<21>")
	)
	(arc
		(start 143.451834 -239.136936)
		(mid 143.596878 -239.077893)
		(end 143.75257 -239.06099)
		(width 0.0889)
		(layer "In2.Cu")
		(net "M_I_CPU1_SA_DQ<21>")
	)
	(arc
		(start 141.197838 -239.136936)
		(mid 141.384782 -239.187191)
		(end 141.571726 -239.136936)
		(width 0.0889)
		(layer "In2.Cu")
		(net "M_I_CPU1_SA_DQ<21>")
	)
	(arc
		(start 134.626096 -239.141762)
		(mid 134.809604 -239.187256)
		(end 134.991856 -239.136936)
		(width 0.0889)
		(layer "In2.Cu")
		(net "M_I_CPU1_SA_DQ<21>")
	)
	(segment
		(start 129.16789 -238.270288)
		(end 129.634742 -238.00435)
		(width 0.10668)
		(layer "F.Cu")
		(net "M_I_CPU1_SA_DQ<20>")
	)
	(segment
		(start 182.374794 -221.56039)
		(end 183.19115 -221.56039)
		(width 0.14478)
		(layer "In2.Cu")
		(net "M_I_CPU1_SA_DQ<20>")
	)
	(segment
		(start 147.366228 -236.406944)
		(end 147.610068 -236.163104)
		(width 0.0889)
		(layer "In2.Cu")
		(net "M_I_CPU1_SA_DQ<20>")
	)
	(segment
		(start 145.887948 -237.105444)
		(end 146.797268 -237.105444)
		(width 0.0889)
		(layer "In2.Cu")
		(net "M_I_CPU1_SA_DQ<20>")
	)
	(segment
		(start 147.610068 -236.163104)
		(end 147.919186 -236.163104)
		(width 0.0889)
		(layer "In2.Cu")
		(net "M_I_CPU1_SA_DQ<20>")
	)
	(segment
		(start 149.560534 -236.163104)
		(end 154.747214 -230.976424)
		(width 0.14478)
		(layer "In2.Cu")
		(net "M_I_CPU1_SA_DQ<20>")
	)
	(segment
		(start 174.493174 -221.570042)
		(end 181.502558 -221.570042)
		(width 0.14478)
		(layer "In2.Cu")
		(net "M_I_CPU1_SA_DQ<20>")
	)
	(segment
		(start 136.393428 -238.331756)
		(end 136.40181 -238.32693)
		(width 0.0889)
		(layer "In2.Cu")
		(net "M_I_CPU1_SA_DQ<20>")
	)
	(segment
		(start 170.684698 -222.419926)
		(end 173.64329 -222.419926)
		(width 0.14478)
		(layer "In2.Cu")
		(net "M_I_CPU1_SA_DQ<20>")
	)
	(segment
		(start 129.634742 -238.00435)
		(end 129.480818 -238.26978)
		(width 0.0889)
		(layer "In2.Cu")
		(net "M_I_CPU1_SA_DQ<20>")
	)
	(segment
		(start 144.362424 -238.326168)
		(end 144.724628 -237.963964)
		(width 0.0889)
		(layer "In2.Cu")
		(net "M_I_CPU1_SA_DQ<20>")
	)
	(segment
		(start 181.65572 -222.45955)
		(end 181.818534 -222.622364)
		(width 0.14478)
		(layer "In2.Cu")
		(net "M_I_CPU1_SA_DQ<20>")
	)
	(segment
		(start 166.32047 -222.419926)
		(end 167.170354 -221.570042)
		(width 0.14478)
		(layer "In2.Cu")
		(net "M_I_CPU1_SA_DQ<20>")
	)
	(segment
		(start 182.21198 -222.45955)
		(end 182.21198 -221.723204)
		(width 0.14478)
		(layer "In2.Cu")
		(net "M_I_CPU1_SA_DQ<20>")
	)
	(segment
		(start 182.049166 -222.622364)
		(end 182.21198 -222.45955)
		(width 0.14478)
		(layer "In2.Cu")
		(net "M_I_CPU1_SA_DQ<20>")
	)
	(segment
		(start 181.502558 -221.570042)
		(end 181.65572 -221.723204)
		(width 0.14478)
		(layer "In2.Cu")
		(net "M_I_CPU1_SA_DQ<20>")
	)
	(segment
		(start 133.20776 -238.32693)
		(end 133.216142 -238.331756)
		(width 0.0889)
		(layer "In2.Cu")
		(net "M_I_CPU1_SA_DQ<20>")
	)
	(segment
		(start 136.967722 -238.32693)
		(end 136.976104 -238.331756)
		(width 0.0889)
		(layer "In2.Cu")
		(net "M_I_CPU1_SA_DQ<20>")
	)
	(segment
		(start 181.65572 -221.723204)
		(end 181.65572 -222.45955)
		(width 0.14478)
		(layer "In2.Cu")
		(net "M_I_CPU1_SA_DQ<20>")
	)
	(segment
		(start 173.64329 -222.419926)
		(end 174.493174 -221.570042)
		(width 0.14478)
		(layer "In2.Cu")
		(net "M_I_CPU1_SA_DQ<20>")
	)
	(segment
		(start 144.724628 -237.963964)
		(end 145.029428 -237.963964)
		(width 0.0889)
		(layer "In2.Cu")
		(net "M_I_CPU1_SA_DQ<20>")
	)
	(segment
		(start 141.667738 -238.32693)
		(end 141.67612 -238.331756)
		(width 0.0889)
		(layer "In2.Cu")
		(net "M_I_CPU1_SA_DQ<20>")
	)
	(segment
		(start 132.267706 -238.32693)
		(end 132.276088 -238.331756)
		(width 0.0889)
		(layer "In2.Cu")
		(net "M_I_CPU1_SA_DQ<20>")
	)
	(segment
		(start 182.21198 -221.723204)
		(end 182.374794 -221.56039)
		(width 0.14478)
		(layer "In2.Cu")
		(net "M_I_CPU1_SA_DQ<20>")
	)
	(segment
		(start 129.480818 -238.26978)
		(end 129.50317 -238.353092)
		(width 0.0889)
		(layer "In2.Cu")
		(net "M_I_CPU1_SA_DQ<20>")
	)
	(segment
		(start 137.907776 -238.32693)
		(end 137.916158 -238.331756)
		(width 0.0889)
		(layer "In2.Cu")
		(net "M_I_CPU1_SA_DQ<20>")
	)
	(segment
		(start 154.747214 -229.839012)
		(end 162.1663 -222.419926)
		(width 0.14478)
		(layer "In2.Cu")
		(net "M_I_CPU1_SA_DQ<20>")
	)
	(segment
		(start 169.834814 -221.570042)
		(end 170.684698 -222.419926)
		(width 0.14478)
		(layer "In2.Cu")
		(net "M_I_CPU1_SA_DQ<20>")
	)
	(segment
		(start 135.453374 -238.331756)
		(end 135.461756 -238.32693)
		(width 0.0889)
		(layer "In2.Cu")
		(net "M_I_CPU1_SA_DQ<20>")
	)
	(segment
		(start 181.818534 -222.622364)
		(end 182.049166 -222.622364)
		(width 0.14478)
		(layer "In2.Cu")
		(net "M_I_CPU1_SA_DQ<20>")
	)
	(segment
		(start 146.797268 -237.105444)
		(end 147.366228 -236.536484)
		(width 0.0889)
		(layer "In2.Cu")
		(net "M_I_CPU1_SA_DQ<20>")
	)
	(segment
		(start 145.029428 -237.963964)
		(end 145.887948 -237.105444)
		(width 0.0889)
		(layer "In2.Cu")
		(net "M_I_CPU1_SA_DQ<20>")
	)
	(segment
		(start 143.921734 -238.32693)
		(end 144.362424 -238.326168)
		(width 0.0889)
		(layer "In2.Cu")
		(net "M_I_CPU1_SA_DQ<20>")
	)
	(segment
		(start 143.913352 -238.331756)
		(end 143.921734 -238.32693)
		(width 0.0889)
		(layer "In2.Cu")
		(net "M_I_CPU1_SA_DQ<20>")
	)
	(segment
		(start 131.693412 -238.331756)
		(end 131.701794 -238.32693)
		(width 0.0889)
		(layer "In2.Cu")
		(net "M_I_CPU1_SA_DQ<20>")
	)
	(segment
		(start 140.15339 -238.331756)
		(end 140.161772 -238.32693)
		(width 0.0889)
		(layer "In2.Cu")
		(net "M_I_CPU1_SA_DQ<20>")
	)
	(segment
		(start 183.19115 -221.56039)
		(end 183.616092 -221.985332)
		(width 0.14478)
		(layer "In2.Cu")
		(net "M_I_CPU1_SA_DQ<20>")
	)
	(segment
		(start 141.093444 -238.331756)
		(end 141.101826 -238.32693)
		(width 0.0889)
		(layer "In2.Cu")
		(net "M_I_CPU1_SA_DQ<20>")
	)
	(segment
		(start 130.753358 -238.331756)
		(end 130.76174 -238.32693)
		(width 0.0889)
		(layer "In2.Cu")
		(net "M_I_CPU1_SA_DQ<20>")
	)
	(segment
		(start 162.1663 -222.419926)
		(end 166.32047 -222.419926)
		(width 0.14478)
		(layer "In2.Cu")
		(net "M_I_CPU1_SA_DQ<20>")
	)
	(segment
		(start 154.747214 -230.976424)
		(end 154.747214 -229.839012)
		(width 0.14478)
		(layer "In2.Cu")
		(net "M_I_CPU1_SA_DQ<20>")
	)
	(segment
		(start 167.170354 -221.570042)
		(end 169.834814 -221.570042)
		(width 0.14478)
		(layer "In2.Cu")
		(net "M_I_CPU1_SA_DQ<20>")
	)
	(segment
		(start 147.919186 -236.163104)
		(end 149.560534 -236.163104)
		(width 0.14478)
		(layer "In2.Cu")
		(net "M_I_CPU1_SA_DQ<20>")
	)
	(segment
		(start 147.366228 -236.536484)
		(end 147.366228 -236.406944)
		(width 0.0889)
		(layer "In2.Cu")
		(net "M_I_CPU1_SA_DQ<20>")
	)
	(arc
		(start 142.607792 -238.32693)
		(mid 142.794736 -238.377185)
		(end 142.98168 -238.32693)
		(width 0.0889)
		(layer "In2.Cu")
		(net "M_I_CPU1_SA_DQ<20>")
	)
	(arc
		(start 141.101826 -238.32693)
		(mid 141.384782 -238.250753)
		(end 141.667738 -238.32693)
		(width 0.0889)
		(layer "In2.Cu")
		(net "M_I_CPU1_SA_DQ<20>")
	)
	(arc
		(start 130.387598 -238.32693)
		(mid 130.569849 -238.37728)
		(end 130.753358 -238.331756)
		(width 0.0889)
		(layer "In2.Cu")
		(net "M_I_CPU1_SA_DQ<20>")
	)
	(arc
		(start 140.161772 -238.32693)
		(mid 140.444728 -238.250753)
		(end 140.727684 -238.32693)
		(width 0.0889)
		(layer "In2.Cu")
		(net "M_I_CPU1_SA_DQ<20>")
	)
	(arc
		(start 132.641848 -238.32693)
		(mid 132.924804 -238.250753)
		(end 133.20776 -238.32693)
		(width 0.0889)
		(layer "In2.Cu")
		(net "M_I_CPU1_SA_DQ<20>")
	)
	(arc
		(start 136.976104 -238.331756)
		(mid 137.159612 -238.37725)
		(end 137.341864 -238.32693)
		(width 0.0889)
		(layer "In2.Cu")
		(net "M_I_CPU1_SA_DQ<20>")
	)
	(arc
		(start 130.76174 -238.32693)
		(mid 131.044696 -238.250753)
		(end 131.327652 -238.32693)
		(width 0.0889)
		(layer "In2.Cu")
		(net "M_I_CPU1_SA_DQ<20>")
	)
	(arc
		(start 139.221718 -238.32693)
		(mid 139.504674 -238.250753)
		(end 139.78763 -238.32693)
		(width 0.0889)
		(layer "In2.Cu")
		(net "M_I_CPU1_SA_DQ<20>")
	)
	(arc
		(start 139.78763 -238.32693)
		(mid 139.969881 -238.37728)
		(end 140.15339 -238.331756)
		(width 0.0889)
		(layer "In2.Cu")
		(net "M_I_CPU1_SA_DQ<20>")
	)
	(arc
		(start 135.461756 -238.32693)
		(mid 135.744712 -238.250753)
		(end 136.027668 -238.32693)
		(width 0.0889)
		(layer "In2.Cu")
		(net "M_I_CPU1_SA_DQ<20>")
	)
	(arc
		(start 141.67612 -238.331756)
		(mid 141.859628 -238.37725)
		(end 142.04188 -238.32693)
		(width 0.0889)
		(layer "In2.Cu")
		(net "M_I_CPU1_SA_DQ<20>")
	)
	(arc
		(start 131.327652 -238.32693)
		(mid 131.509903 -238.37728)
		(end 131.693412 -238.331756)
		(width 0.0889)
		(layer "In2.Cu")
		(net "M_I_CPU1_SA_DQ<20>")
	)
	(arc
		(start 133.216142 -238.331756)
		(mid 133.39965 -238.37725)
		(end 133.581902 -238.32693)
		(width 0.0889)
		(layer "In2.Cu")
		(net "M_I_CPU1_SA_DQ<20>")
	)
	(arc
		(start 136.027668 -238.32693)
		(mid 136.209919 -238.37728)
		(end 136.393428 -238.331756)
		(width 0.0889)
		(layer "In2.Cu")
		(net "M_I_CPU1_SA_DQ<20>")
	)
	(arc
		(start 132.276088 -238.331756)
		(mid 132.459596 -238.37725)
		(end 132.641848 -238.32693)
		(width 0.0889)
		(layer "In2.Cu")
		(net "M_I_CPU1_SA_DQ<20>")
	)
	(arc
		(start 142.04188 -238.32693)
		(mid 142.324836 -238.250753)
		(end 142.607792 -238.32693)
		(width 0.0889)
		(layer "In2.Cu")
		(net "M_I_CPU1_SA_DQ<20>")
	)
	(arc
		(start 129.50317 -238.353092)
		(mid 129.665359 -238.375827)
		(end 129.821686 -238.32693)
		(width 0.0889)
		(layer "In2.Cu")
		(net "M_I_CPU1_SA_DQ<20>")
	)
	(arc
		(start 134.147814 -238.32693)
		(mid 134.334758 -238.377185)
		(end 134.521702 -238.32693)
		(width 0.0889)
		(layer "In2.Cu")
		(net "M_I_CPU1_SA_DQ<20>")
	)
	(arc
		(start 133.581902 -238.32693)
		(mid 133.864858 -238.250753)
		(end 134.147814 -238.32693)
		(width 0.0889)
		(layer "In2.Cu")
		(net "M_I_CPU1_SA_DQ<20>")
	)
	(arc
		(start 135.087614 -238.32693)
		(mid 135.269865 -238.37728)
		(end 135.453374 -238.331756)
		(width 0.0889)
		(layer "In2.Cu")
		(net "M_I_CPU1_SA_DQ<20>")
	)
	(arc
		(start 143.547592 -238.32693)
		(mid 143.729843 -238.37728)
		(end 143.913352 -238.331756)
		(width 0.0889)
		(layer "In2.Cu")
		(net "M_I_CPU1_SA_DQ<20>")
	)
	(arc
		(start 137.341864 -238.32693)
		(mid 137.62482 -238.250753)
		(end 137.907776 -238.32693)
		(width 0.0889)
		(layer "In2.Cu")
		(net "M_I_CPU1_SA_DQ<20>")
	)
	(arc
		(start 137.916158 -238.331756)
		(mid 138.099666 -238.37725)
		(end 138.281918 -238.32693)
		(width 0.0889)
		(layer "In2.Cu")
		(net "M_I_CPU1_SA_DQ<20>")
	)
	(arc
		(start 138.281918 -238.32693)
		(mid 138.564874 -238.250753)
		(end 138.84783 -238.32693)
		(width 0.0889)
		(layer "In2.Cu")
		(net "M_I_CPU1_SA_DQ<20>")
	)
	(arc
		(start 136.40181 -238.32693)
		(mid 136.684766 -238.250753)
		(end 136.967722 -238.32693)
		(width 0.0889)
		(layer "In2.Cu")
		(net "M_I_CPU1_SA_DQ<20>")
	)
	(arc
		(start 131.701794 -238.32693)
		(mid 131.98475 -238.250753)
		(end 132.267706 -238.32693)
		(width 0.0889)
		(layer "In2.Cu")
		(net "M_I_CPU1_SA_DQ<20>")
	)
	(arc
		(start 138.84783 -238.32693)
		(mid 139.034774 -238.377185)
		(end 139.221718 -238.32693)
		(width 0.0889)
		(layer "In2.Cu")
		(net "M_I_CPU1_SA_DQ<20>")
	)
	(arc
		(start 142.98168 -238.32693)
		(mid 143.264636 -238.250753)
		(end 143.547592 -238.32693)
		(width 0.0889)
		(layer "In2.Cu")
		(net "M_I_CPU1_SA_DQ<20>")
	)
	(arc
		(start 129.821686 -238.32693)
		(mid 130.104642 -238.250753)
		(end 130.387598 -238.32693)
		(width 0.0889)
		(layer "In2.Cu")
		(net "M_I_CPU1_SA_DQ<20>")
	)
	(arc
		(start 140.727684 -238.32693)
		(mid 140.909935 -238.37728)
		(end 141.093444 -238.331756)
		(width 0.0889)
		(layer "In2.Cu")
		(net "M_I_CPU1_SA_DQ<20>")
	)
	(arc
		(start 134.521702 -238.32693)
		(mid 134.804658 -238.250753)
		(end 135.087614 -238.32693)
		(width 0.0889)
		(layer "In2.Cu")
		(net "M_I_CPU1_SA_DQ<20>")
	)
	(segment
		(start 127.757936 -226.120452)
		(end 128.224788 -225.854514)
		(width 0.10668)
		(layer "F.Cu")
		(net "M_I_CPU1_SA_DQ<1>")
	)
	(segment
		(start 165.899846 -199.460358)
		(end 167.171624 -198.610474)
		(width 0.14478)
		(layer "In2.Cu")
		(net "M_I_CPU1_SA_DQ<1>")
	)
	(segment
		(start 169.865548 -198.610474)
		(end 171.13758 -199.460358)
		(width 0.14478)
		(layer "In2.Cu")
		(net "M_I_CPU1_SA_DQ<1>")
	)
	(segment
		(start 159.825436 -199.460358)
		(end 165.899846 -199.460358)
		(width 0.14478)
		(layer "In2.Cu")
		(net "M_I_CPU1_SA_DQ<1>")
	)
	(segment
		(start 141.75994 -222.416116)
		(end 142.08633 -221.196662)
		(width 0.0889)
		(layer "In2.Cu")
		(net "M_I_CPU1_SA_DQ<1>")
	)
	(segment
		(start 139.31773 -226.177094)
		(end 139.326112 -226.18192)
		(width 0.0889)
		(layer "In2.Cu")
		(net "M_I_CPU1_SA_DQ<1>")
	)
	(segment
		(start 141.064234 -223.76892)
		(end 141.10208 -223.747076)
		(width 0.0889)
		(layer "In2.Cu")
		(net "M_I_CPU1_SA_DQ<1>")
	)
	(segment
		(start 128.40335 -226.18192)
		(end 128.411732 -226.177094)
		(width 0.0889)
		(layer "In2.Cu")
		(net "M_I_CPU1_SA_DQ<1>")
	)
	(segment
		(start 142.08633 -219.292424)
		(end 148.019008 -213.359746)
		(width 0.14478)
		(layer "In2.Cu")
		(net "M_I_CPU1_SA_DQ<1>")
	)
	(segment
		(start 173.392338 -199.460358)
		(end 174.66437 -198.610474)
		(width 0.14478)
		(layer "In2.Cu")
		(net "M_I_CPU1_SA_DQ<1>")
	)
	(segment
		(start 174.66437 -198.610474)
		(end 183.19115 -198.610474)
		(width 0.14478)
		(layer "In2.Cu")
		(net "M_I_CPU1_SA_DQ<1>")
	)
	(segment
		(start 183.19115 -198.610474)
		(end 183.616092 -199.035416)
		(width 0.14478)
		(layer "In2.Cu")
		(net "M_I_CPU1_SA_DQ<1>")
	)
	(segment
		(start 139.691872 -226.177094)
		(end 139.722352 -226.159314)
		(width 0.0889)
		(layer "In2.Cu")
		(net "M_I_CPU1_SA_DQ<1>")
	)
	(segment
		(start 138.743436 -226.18192)
		(end 138.751818 -226.177094)
		(width 0.0889)
		(layer "In2.Cu")
		(net "M_I_CPU1_SA_DQ<1>")
	)
	(segment
		(start 154.973782 -205.071472)
		(end 154.973782 -204.312012)
		(width 0.14478)
		(layer "In2.Cu")
		(net "M_I_CPU1_SA_DQ<1>")
	)
	(segment
		(start 141.10208 -223.747076)
		(end 141.134846 -223.728026)
		(width 0.0889)
		(layer "In2.Cu")
		(net "M_I_CPU1_SA_DQ<1>")
	)
	(segment
		(start 140.161772 -225.367088)
		(end 140.193522 -225.3488)
		(width 0.0889)
		(layer "In2.Cu")
		(net "M_I_CPU1_SA_DQ<1>")
	)
	(segment
		(start 141.534642 -222.958914)
		(end 141.572234 -222.93707)
		(width 0.0889)
		(layer "In2.Cu")
		(net "M_I_CPU1_SA_DQ<1>")
	)
	(segment
		(start 167.171624 -198.610474)
		(end 169.865548 -198.610474)
		(width 0.14478)
		(layer "In2.Cu")
		(net "M_I_CPU1_SA_DQ<1>")
	)
	(segment
		(start 129.917698 -226.177094)
		(end 129.92608 -226.18192)
		(width 0.0889)
		(layer "In2.Cu")
		(net "M_I_CPU1_SA_DQ<1>")
	)
	(segment
		(start 140.122656 -225.389948)
		(end 140.161772 -225.367088)
		(width 0.0889)
		(layer "In2.Cu")
		(net "M_I_CPU1_SA_DQ<1>")
	)
	(segment
		(start 133.103366 -226.18192)
		(end 133.111748 -226.177094)
		(width 0.0889)
		(layer "In2.Cu")
		(net "M_I_CPU1_SA_DQ<1>")
	)
	(segment
		(start 142.08633 -221.196662)
		(end 142.08633 -219.292424)
		(width 0.14478)
		(layer "In2.Cu")
		(net "M_I_CPU1_SA_DQ<1>")
	)
	(segment
		(start 134.617714 -226.177094)
		(end 134.626096 -226.18192)
		(width 0.0889)
		(layer "In2.Cu")
		(net "M_I_CPU1_SA_DQ<1>")
	)
	(segment
		(start 137.803382 -226.18192)
		(end 137.804398 -226.181412)
		(width 0.0889)
		(layer "In2.Cu")
		(net "M_I_CPU1_SA_DQ<1>")
	)
	(segment
		(start 128.07061 -226.119944)
		(end 128.092962 -226.203256)
		(width 0.0889)
		(layer "In2.Cu")
		(net "M_I_CPU1_SA_DQ<1>")
	)
	(segment
		(start 171.13758 -199.460358)
		(end 173.392338 -199.460358)
		(width 0.14478)
		(layer "In2.Cu")
		(net "M_I_CPU1_SA_DQ<1>")
	)
	(segment
		(start 134.04342 -226.18192)
		(end 134.051802 -226.177094)
		(width 0.0889)
		(layer "In2.Cu")
		(net "M_I_CPU1_SA_DQ<1>")
	)
	(segment
		(start 140.63218 -224.557082)
		(end 140.661644 -224.540064)
		(width 0.0889)
		(layer "In2.Cu")
		(net "M_I_CPU1_SA_DQ<1>")
	)
	(segment
		(start 141.75994 -222.61449)
		(end 141.75994 -222.416116)
		(width 0.0889)
		(layer "In2.Cu")
		(net "M_I_CPU1_SA_DQ<1>")
	)
	(segment
		(start 128.224788 -225.854514)
		(end 128.07061 -226.119944)
		(width 0.0889)
		(layer "In2.Cu")
		(net "M_I_CPU1_SA_DQ<1>")
	)
	(segment
		(start 148.019008 -212.026246)
		(end 154.973782 -205.071472)
		(width 0.14478)
		(layer "In2.Cu")
		(net "M_I_CPU1_SA_DQ<1>")
	)
	(segment
		(start 141.572234 -222.93707)
		(end 141.606016 -222.917512)
		(width 0.0889)
		(layer "In2.Cu")
		(net "M_I_CPU1_SA_DQ<1>")
	)
	(segment
		(start 130.857752 -226.177094)
		(end 130.866134 -226.18192)
		(width 0.0889)
		(layer "In2.Cu")
		(net "M_I_CPU1_SA_DQ<1>")
	)
	(segment
		(start 140.591794 -224.580704)
		(end 140.63218 -224.557082)
		(width 0.0889)
		(layer "In2.Cu")
		(net "M_I_CPU1_SA_DQ<1>")
	)
	(segment
		(start 129.343404 -226.18192)
		(end 129.351786 -226.177094)
		(width 0.0889)
		(layer "In2.Cu")
		(net "M_I_CPU1_SA_DQ<1>")
	)
	(segment
		(start 135.557768 -226.177094)
		(end 135.56615 -226.18192)
		(width 0.0889)
		(layer "In2.Cu")
		(net "M_I_CPU1_SA_DQ<1>")
	)
	(segment
		(start 137.804398 -226.181412)
		(end 137.811764 -226.177094)
		(width 0.0889)
		(layer "In2.Cu")
		(net "M_I_CPU1_SA_DQ<1>")
	)
	(segment
		(start 148.019008 -213.359746)
		(end 148.019008 -212.026246)
		(width 0.14478)
		(layer "In2.Cu")
		(net "M_I_CPU1_SA_DQ<1>")
	)
	(segment
		(start 154.973782 -204.312012)
		(end 159.825436 -199.460358)
		(width 0.14478)
		(layer "In2.Cu")
		(net "M_I_CPU1_SA_DQ<1>")
	)
	(arc
		(start 139.722352 -226.159314)
		(mid 139.837779 -226.025938)
		(end 139.879324 -225.854514)
		(width 0.0889)
		(layer "In2.Cu")
		(net "M_I_CPU1_SA_DQ<1>")
	)
	(arc
		(start 129.92608 -226.18192)
		(mid 130.109588 -226.227414)
		(end 130.29184 -226.177094)
		(width 0.0889)
		(layer "In2.Cu")
		(net "M_I_CPU1_SA_DQ<1>")
	)
	(arc
		(start 133.67766 -226.177094)
		(mid 133.859911 -226.227444)
		(end 134.04342 -226.18192)
		(width 0.0889)
		(layer "In2.Cu")
		(net "M_I_CPU1_SA_DQ<1>")
	)
	(arc
		(start 131.231894 -226.177094)
		(mid 131.51485 -226.100917)
		(end 131.797806 -226.177094)
		(width 0.0889)
		(layer "In2.Cu")
		(net "M_I_CPU1_SA_DQ<1>")
	)
	(arc
		(start 128.092962 -226.203256)
		(mid 128.250472 -226.226454)
		(end 128.40335 -226.18192)
		(width 0.0889)
		(layer "In2.Cu")
		(net "M_I_CPU1_SA_DQ<1>")
	)
	(arc
		(start 136.87171 -226.177094)
		(mid 137.154666 -226.100917)
		(end 137.437622 -226.177094)
		(width 0.0889)
		(layer "In2.Cu")
		(net "M_I_CPU1_SA_DQ<1>")
	)
	(arc
		(start 128.411732 -226.177094)
		(mid 128.694688 -226.100917)
		(end 128.977644 -226.177094)
		(width 0.0889)
		(layer "In2.Cu")
		(net "M_I_CPU1_SA_DQ<1>")
	)
	(arc
		(start 141.606016 -222.917512)
		(mid 141.719275 -222.784434)
		(end 141.75994 -222.61449)
		(width 0.0889)
		(layer "In2.Cu")
		(net "M_I_CPU1_SA_DQ<1>")
	)
	(arc
		(start 141.134846 -223.728026)
		(mid 141.248999 -223.59495)
		(end 141.29004 -223.424496)
		(width 0.0889)
		(layer "In2.Cu")
		(net "M_I_CPU1_SA_DQ<1>")
	)
	(arc
		(start 140.661644 -224.540064)
		(mid 140.777825 -224.406505)
		(end 140.819632 -224.234502)
		(width 0.0889)
		(layer "In2.Cu")
		(net "M_I_CPU1_SA_DQ<1>")
	)
	(arc
		(start 140.819632 -224.234502)
		(mid 140.884504 -223.971539)
		(end 141.064234 -223.76892)
		(width 0.0889)
		(layer "In2.Cu")
		(net "M_I_CPU1_SA_DQ<1>")
	)
	(arc
		(start 141.29004 -223.424496)
		(mid 141.354912 -223.161533)
		(end 141.534642 -222.958914)
		(width 0.0889)
		(layer "In2.Cu")
		(net "M_I_CPU1_SA_DQ<1>")
	)
	(arc
		(start 137.437622 -226.177094)
		(mid 137.619873 -226.227444)
		(end 137.803382 -226.18192)
		(width 0.0889)
		(layer "In2.Cu")
		(net "M_I_CPU1_SA_DQ<1>")
	)
	(arc
		(start 140.193522 -225.3488)
		(mid 140.308198 -225.215466)
		(end 140.349478 -225.044508)
		(width 0.0889)
		(layer "In2.Cu")
		(net "M_I_CPU1_SA_DQ<1>")
	)
	(arc
		(start 140.349478 -225.044508)
		(mid 140.413771 -224.782903)
		(end 140.591794 -224.580704)
		(width 0.0889)
		(layer "In2.Cu")
		(net "M_I_CPU1_SA_DQ<1>")
	)
	(arc
		(start 132.737606 -226.177094)
		(mid 132.919857 -226.227444)
		(end 133.103366 -226.18192)
		(width 0.0889)
		(layer "In2.Cu")
		(net "M_I_CPU1_SA_DQ<1>")
	)
	(arc
		(start 134.991856 -226.177094)
		(mid 135.274812 -226.100917)
		(end 135.557768 -226.177094)
		(width 0.0889)
		(layer "In2.Cu")
		(net "M_I_CPU1_SA_DQ<1>")
	)
	(arc
		(start 129.351786 -226.177094)
		(mid 129.634742 -226.100917)
		(end 129.917698 -226.177094)
		(width 0.0889)
		(layer "In2.Cu")
		(net "M_I_CPU1_SA_DQ<1>")
	)
	(arc
		(start 130.866134 -226.18192)
		(mid 131.049642 -226.227414)
		(end 131.231894 -226.177094)
		(width 0.0889)
		(layer "In2.Cu")
		(net "M_I_CPU1_SA_DQ<1>")
	)
	(arc
		(start 128.977644 -226.177094)
		(mid 129.159895 -226.227444)
		(end 129.343404 -226.18192)
		(width 0.0889)
		(layer "In2.Cu")
		(net "M_I_CPU1_SA_DQ<1>")
	)
	(arc
		(start 132.171694 -226.177094)
		(mid 132.45465 -226.100917)
		(end 132.737606 -226.177094)
		(width 0.0889)
		(layer "In2.Cu")
		(net "M_I_CPU1_SA_DQ<1>")
	)
	(arc
		(start 139.879324 -225.854514)
		(mid 139.943839 -225.592295)
		(end 140.122656 -225.389948)
		(width 0.0889)
		(layer "In2.Cu")
		(net "M_I_CPU1_SA_DQ<1>")
	)
	(arc
		(start 134.626096 -226.18192)
		(mid 134.809604 -226.227414)
		(end 134.991856 -226.177094)
		(width 0.0889)
		(layer "In2.Cu")
		(net "M_I_CPU1_SA_DQ<1>")
	)
	(arc
		(start 137.811764 -226.177094)
		(mid 138.09472 -226.100917)
		(end 138.377676 -226.177094)
		(width 0.0889)
		(layer "In2.Cu")
		(net "M_I_CPU1_SA_DQ<1>")
	)
	(arc
		(start 135.56615 -226.18192)
		(mid 135.749658 -226.227414)
		(end 135.93191 -226.177094)
		(width 0.0889)
		(layer "In2.Cu")
		(net "M_I_CPU1_SA_DQ<1>")
	)
	(arc
		(start 131.797806 -226.177094)
		(mid 131.98475 -226.227349)
		(end 132.171694 -226.177094)
		(width 0.0889)
		(layer "In2.Cu")
		(net "M_I_CPU1_SA_DQ<1>")
	)
	(arc
		(start 134.051802 -226.177094)
		(mid 134.334758 -226.100917)
		(end 134.617714 -226.177094)
		(width 0.0889)
		(layer "In2.Cu")
		(net "M_I_CPU1_SA_DQ<1>")
	)
	(arc
		(start 138.751818 -226.177094)
		(mid 139.034774 -226.100917)
		(end 139.31773 -226.177094)
		(width 0.0889)
		(layer "In2.Cu")
		(net "M_I_CPU1_SA_DQ<1>")
	)
	(arc
		(start 139.326112 -226.18192)
		(mid 139.50962 -226.227414)
		(end 139.691872 -226.177094)
		(width 0.0889)
		(layer "In2.Cu")
		(net "M_I_CPU1_SA_DQ<1>")
	)
	(arc
		(start 135.93191 -226.177094)
		(mid 136.214866 -226.100917)
		(end 136.497822 -226.177094)
		(width 0.0889)
		(layer "In2.Cu")
		(net "M_I_CPU1_SA_DQ<1>")
	)
	(arc
		(start 133.111748 -226.177094)
		(mid 133.394704 -226.100917)
		(end 133.67766 -226.177094)
		(width 0.0889)
		(layer "In2.Cu")
		(net "M_I_CPU1_SA_DQ<1>")
	)
	(arc
		(start 130.29184 -226.177094)
		(mid 130.574796 -226.100917)
		(end 130.857752 -226.177094)
		(width 0.0889)
		(layer "In2.Cu")
		(net "M_I_CPU1_SA_DQ<1>")
	)
	(arc
		(start 138.377676 -226.177094)
		(mid 138.559927 -226.227444)
		(end 138.743436 -226.18192)
		(width 0.0889)
		(layer "In2.Cu")
		(net "M_I_CPU1_SA_DQ<1>")
	)
	(arc
		(start 136.497822 -226.177094)
		(mid 136.684766 -226.227349)
		(end 136.87171 -226.177094)
		(width 0.0889)
		(layer "In2.Cu")
		(net "M_I_CPU1_SA_DQ<1>")
	)
	(segment
		(start 127.287782 -236.650276)
		(end 127.754634 -236.384338)
		(width 0.10668)
		(layer "F.Cu")
		(net "M_I_CPU1_SA_DQ<19>")
	)
	(segment
		(start 133.20776 -236.061758)
		(end 133.216142 -236.056932)
		(width 0.0889)
		(layer "In2.Cu")
		(net "M_I_CPU1_SA_DQ<19>")
	)
	(segment
		(start 159.390842 -221.275402)
		(end 159.141668 -221.026228)
		(width 0.14478)
		(layer "In2.Cu")
		(net "M_I_CPU1_SA_DQ<19>")
	)
	(segment
		(start 136.393428 -236.056932)
		(end 136.40181 -236.061758)
		(width 0.0889)
		(layer "In2.Cu")
		(net "M_I_CPU1_SA_DQ<19>")
	)
	(segment
		(start 158.36138 -221.577916)
		(end 158.522924 -221.416372)
		(width 0.14478)
		(layer "In2.Cu")
		(net "M_I_CPU1_SA_DQ<19>")
	)
	(segment
		(start 132.267706 -236.061758)
		(end 132.276088 -236.056932)
		(width 0.0889)
		(layer "In2.Cu")
		(net "M_I_CPU1_SA_DQ<19>")
	)
	(segment
		(start 159.141668 -221.026228)
		(end 159.141668 -220.797628)
		(width 0.14478)
		(layer "In2.Cu")
		(net "M_I_CPU1_SA_DQ<19>")
	)
	(segment
		(start 159.531812 -220.636084)
		(end 159.780986 -220.885258)
		(width 0.14478)
		(layer "In2.Cu")
		(net "M_I_CPU1_SA_DQ<19>")
	)
	(segment
		(start 160.702244 -219.237052)
		(end 160.863788 -219.075508)
		(width 0.14478)
		(layer "In2.Cu")
		(net "M_I_CPU1_SA_DQ<19>")
	)
	(segment
		(start 140.15339 -236.056932)
		(end 140.161772 -236.061758)
		(width 0.0889)
		(layer "In2.Cu")
		(net "M_I_CPU1_SA_DQ<19>")
	)
	(segment
		(start 160.009586 -220.885258)
		(end 160.17113 -220.723714)
		(width 0.14478)
		(layer "In2.Cu")
		(net "M_I_CPU1_SA_DQ<19>")
	)
	(segment
		(start 177.283872 -217.872564)
		(end 177.55235 -217.872564)
		(width 0.14478)
		(layer "In2.Cu")
		(net "M_I_CPU1_SA_DQ<19>")
	)
	(segment
		(start 159.000698 -221.665546)
		(end 159.229298 -221.665546)
		(width 0.14478)
		(layer "In2.Cu")
		(net "M_I_CPU1_SA_DQ<19>")
	)
	(segment
		(start 141.667738 -236.061758)
		(end 141.67612 -236.056932)
		(width 0.0889)
		(layer "In2.Cu")
		(net "M_I_CPU1_SA_DQ<19>")
	)
	(segment
		(start 160.702244 -219.465652)
		(end 160.702244 -219.237052)
		(width 0.14478)
		(layer "In2.Cu")
		(net "M_I_CPU1_SA_DQ<19>")
	)
	(segment
		(start 137.907776 -236.061758)
		(end 137.916158 -236.056932)
		(width 0.0889)
		(layer "In2.Cu")
		(net "M_I_CPU1_SA_DQ<19>")
	)
	(segment
		(start 160.951418 -219.714826)
		(end 160.702244 -219.465652)
		(width 0.14478)
		(layer "In2.Cu")
		(net "M_I_CPU1_SA_DQ<19>")
	)
	(segment
		(start 158.522924 -221.416372)
		(end 158.751524 -221.416372)
		(width 0.14478)
		(layer "In2.Cu")
		(net "M_I_CPU1_SA_DQ<19>")
	)
	(segment
		(start 147.07108 -233.823764)
		(end 147.914106 -232.980738)
		(width 0.0889)
		(layer "In2.Cu")
		(net "M_I_CPU1_SA_DQ<19>")
	)
	(segment
		(start 161.570162 -219.324682)
		(end 161.894266 -219.000578)
		(width 0.14478)
		(layer "In2.Cu")
		(net "M_I_CPU1_SA_DQ<19>")
	)
	(segment
		(start 147.914106 -232.980738)
		(end 158.610554 -222.28429)
		(width 0.14478)
		(layer "In2.Cu")
		(net "M_I_CPU1_SA_DQ<19>")
	)
	(segment
		(start 159.921956 -220.24594)
		(end 159.921956 -220.01734)
		(width 0.14478)
		(layer "In2.Cu")
		(net "M_I_CPU1_SA_DQ<19>")
	)
	(segment
		(start 161.341562 -219.324682)
		(end 161.570162 -219.324682)
		(width 0.14478)
		(layer "In2.Cu")
		(net "M_I_CPU1_SA_DQ<19>")
	)
	(segment
		(start 128.507744 -236.061758)
		(end 128.516126 -236.056932)
		(width 0.0889)
		(layer "In2.Cu")
		(net "M_I_CPU1_SA_DQ<19>")
	)
	(segment
		(start 159.390842 -221.504002)
		(end 159.390842 -221.275402)
		(width 0.14478)
		(layer "In2.Cu")
		(net "M_I_CPU1_SA_DQ<19>")
	)
	(segment
		(start 145.698464 -234.793028)
		(end 146.667728 -233.823764)
		(width 0.0889)
		(layer "In2.Cu")
		(net "M_I_CPU1_SA_DQ<19>")
	)
	(segment
		(start 131.693412 -236.056932)
		(end 131.701794 -236.061758)
		(width 0.0889)
		(layer "In2.Cu")
		(net "M_I_CPU1_SA_DQ<19>")
	)
	(segment
		(start 158.610554 -222.05569)
		(end 158.36138 -221.806516)
		(width 0.14478)
		(layer "In2.Cu")
		(net "M_I_CPU1_SA_DQ<19>")
	)
	(segment
		(start 177.005742 -218.150694)
		(end 177.283872 -217.872564)
		(width 0.14478)
		(layer "In2.Cu")
		(net "M_I_CPU1_SA_DQ<19>")
	)
	(segment
		(start 174.375572 -218.150694)
		(end 177.005742 -218.150694)
		(width 0.14478)
		(layer "In2.Cu")
		(net "M_I_CPU1_SA_DQ<19>")
	)
	(segment
		(start 135.453374 -236.056932)
		(end 135.461756 -236.061758)
		(width 0.0889)
		(layer "In2.Cu")
		(net "M_I_CPU1_SA_DQ<19>")
	)
	(segment
		(start 161.092388 -219.075508)
		(end 161.341562 -219.324682)
		(width 0.14478)
		(layer "In2.Cu")
		(net "M_I_CPU1_SA_DQ<19>")
	)
	(segment
		(start 158.36138 -221.806516)
		(end 158.36138 -221.577916)
		(width 0.14478)
		(layer "In2.Cu")
		(net "M_I_CPU1_SA_DQ<19>")
	)
	(segment
		(start 177.55235 -217.872564)
		(end 177.74539 -218.065604)
		(width 0.14478)
		(layer "In2.Cu")
		(net "M_I_CPU1_SA_DQ<19>")
	)
	(segment
		(start 159.303212 -220.636084)
		(end 159.531812 -220.636084)
		(width 0.14478)
		(layer "In2.Cu")
		(net "M_I_CPU1_SA_DQ<19>")
	)
	(segment
		(start 159.921956 -220.01734)
		(end 160.0835 -219.855796)
		(width 0.14478)
		(layer "In2.Cu")
		(net "M_I_CPU1_SA_DQ<19>")
	)
	(segment
		(start 171.080684 -219.000578)
		(end 173.525688 -219.000578)
		(width 0.14478)
		(layer "In2.Cu")
		(net "M_I_CPU1_SA_DQ<19>")
	)
	(segment
		(start 158.610554 -222.28429)
		(end 158.610554 -222.05569)
		(width 0.14478)
		(layer "In2.Cu")
		(net "M_I_CPU1_SA_DQ<19>")
	)
	(segment
		(start 130.753358 -236.056932)
		(end 130.76174 -236.061758)
		(width 0.0889)
		(layer "In2.Cu")
		(net "M_I_CPU1_SA_DQ<19>")
	)
	(segment
		(start 177.74539 -218.065604)
		(end 178.203352 -218.065604)
		(width 0.14478)
		(layer "In2.Cu")
		(net "M_I_CPU1_SA_DQ<19>")
	)
	(segment
		(start 141.093444 -236.056932)
		(end 141.101826 -236.061758)
		(width 0.0889)
		(layer "In2.Cu")
		(net "M_I_CPU1_SA_DQ<19>")
	)
	(segment
		(start 160.561274 -220.10497)
		(end 160.789874 -220.10497)
		(width 0.14478)
		(layer "In2.Cu")
		(net "M_I_CPU1_SA_DQ<19>")
	)
	(segment
		(start 160.789874 -220.10497)
		(end 160.951418 -219.943426)
		(width 0.14478)
		(layer "In2.Cu")
		(net "M_I_CPU1_SA_DQ<19>")
	)
	(segment
		(start 160.17113 -220.495114)
		(end 159.921956 -220.24594)
		(width 0.14478)
		(layer "In2.Cu")
		(net "M_I_CPU1_SA_DQ<19>")
	)
	(segment
		(start 165.987222 -219.000578)
		(end 166.837106 -218.150694)
		(width 0.14478)
		(layer "In2.Cu")
		(net "M_I_CPU1_SA_DQ<19>")
	)
	(segment
		(start 170.2308 -218.150694)
		(end 171.080684 -219.000578)
		(width 0.14478)
		(layer "In2.Cu")
		(net "M_I_CPU1_SA_DQ<19>")
	)
	(segment
		(start 159.229298 -221.665546)
		(end 159.390842 -221.504002)
		(width 0.14478)
		(layer "In2.Cu")
		(net "M_I_CPU1_SA_DQ<19>")
	)
	(segment
		(start 127.754634 -236.384338)
		(end 127.908812 -236.118908)
		(width 0.0889)
		(layer "In2.Cu")
		(net "M_I_CPU1_SA_DQ<19>")
	)
	(segment
		(start 178.8033 -217.872564)
		(end 179.516024 -218.585288)
		(width 0.14478)
		(layer "In2.Cu")
		(net "M_I_CPU1_SA_DQ<19>")
	)
	(segment
		(start 160.3121 -219.855796)
		(end 160.561274 -220.10497)
		(width 0.14478)
		(layer "In2.Cu")
		(net "M_I_CPU1_SA_DQ<19>")
	)
	(segment
		(start 127.908812 -236.118908)
		(end 128.005078 -236.093508)
		(width 0.0889)
		(layer "In2.Cu")
		(net "M_I_CPU1_SA_DQ<19>")
	)
	(segment
		(start 159.141668 -220.797628)
		(end 159.303212 -220.636084)
		(width 0.14478)
		(layer "In2.Cu")
		(net "M_I_CPU1_SA_DQ<19>")
	)
	(segment
		(start 173.525688 -219.000578)
		(end 174.375572 -218.150694)
		(width 0.14478)
		(layer "In2.Cu")
		(net "M_I_CPU1_SA_DQ<19>")
	)
	(segment
		(start 159.780986 -220.885258)
		(end 160.009586 -220.885258)
		(width 0.14478)
		(layer "In2.Cu")
		(net "M_I_CPU1_SA_DQ<19>")
	)
	(segment
		(start 161.894266 -219.000578)
		(end 165.987222 -219.000578)
		(width 0.14478)
		(layer "In2.Cu")
		(net "M_I_CPU1_SA_DQ<19>")
	)
	(segment
		(start 160.17113 -220.723714)
		(end 160.17113 -220.495114)
		(width 0.14478)
		(layer "In2.Cu")
		(net "M_I_CPU1_SA_DQ<19>")
	)
	(segment
		(start 178.396392 -217.872564)
		(end 178.8033 -217.872564)
		(width 0.14478)
		(layer "In2.Cu")
		(net "M_I_CPU1_SA_DQ<19>")
	)
	(segment
		(start 178.203352 -218.065604)
		(end 178.396392 -217.872564)
		(width 0.14478)
		(layer "In2.Cu")
		(net "M_I_CPU1_SA_DQ<19>")
	)
	(segment
		(start 146.667728 -233.823764)
		(end 147.07108 -233.823764)
		(width 0.0889)
		(layer "In2.Cu")
		(net "M_I_CPU1_SA_DQ<19>")
	)
	(segment
		(start 160.863788 -219.075508)
		(end 161.092388 -219.075508)
		(width 0.14478)
		(layer "In2.Cu")
		(net "M_I_CPU1_SA_DQ<19>")
	)
	(segment
		(start 143.547592 -236.061758)
		(end 145.698464 -234.793028)
		(width 0.0889)
		(layer "In2.Cu")
		(net "M_I_CPU1_SA_DQ<19>")
	)
	(segment
		(start 160.951418 -219.943426)
		(end 160.951418 -219.714826)
		(width 0.14478)
		(layer "In2.Cu")
		(net "M_I_CPU1_SA_DQ<19>")
	)
	(segment
		(start 160.0835 -219.855796)
		(end 160.3121 -219.855796)
		(width 0.14478)
		(layer "In2.Cu")
		(net "M_I_CPU1_SA_DQ<19>")
	)
	(segment
		(start 136.967722 -236.061758)
		(end 136.976104 -236.056932)
		(width 0.0889)
		(layer "In2.Cu")
		(net "M_I_CPU1_SA_DQ<19>")
	)
	(segment
		(start 166.837106 -218.150694)
		(end 170.2308 -218.150694)
		(width 0.14478)
		(layer "In2.Cu")
		(net "M_I_CPU1_SA_DQ<19>")
	)
	(segment
		(start 158.751524 -221.416372)
		(end 159.000698 -221.665546)
		(width 0.14478)
		(layer "In2.Cu")
		(net "M_I_CPU1_SA_DQ<19>")
	)
	(arc
		(start 134.147814 -236.061758)
		(mid 134.334758 -236.011503)
		(end 134.521702 -236.061758)
		(width 0.0889)
		(layer "In2.Cu")
		(net "M_I_CPU1_SA_DQ<19>")
	)
	(arc
		(start 128.881886 -236.061758)
		(mid 129.164842 -236.137935)
		(end 129.447798 -236.061758)
		(width 0.0889)
		(layer "In2.Cu")
		(net "M_I_CPU1_SA_DQ<19>")
	)
	(arc
		(start 132.641848 -236.061758)
		(mid 132.924804 -236.137935)
		(end 133.20776 -236.061758)
		(width 0.0889)
		(layer "In2.Cu")
		(net "M_I_CPU1_SA_DQ<19>")
	)
	(arc
		(start 138.84783 -236.061758)
		(mid 139.034774 -236.011503)
		(end 139.221718 -236.061758)
		(width 0.0889)
		(layer "In2.Cu")
		(net "M_I_CPU1_SA_DQ<19>")
	)
	(arc
		(start 134.521702 -236.061758)
		(mid 134.804658 -236.137935)
		(end 135.087614 -236.061758)
		(width 0.0889)
		(layer "In2.Cu")
		(net "M_I_CPU1_SA_DQ<19>")
	)
	(arc
		(start 141.101826 -236.061758)
		(mid 141.384782 -236.137935)
		(end 141.667738 -236.061758)
		(width 0.0889)
		(layer "In2.Cu")
		(net "M_I_CPU1_SA_DQ<19>")
	)
	(arc
		(start 142.98168 -236.061758)
		(mid 143.264636 -236.137935)
		(end 143.547592 -236.061758)
		(width 0.0889)
		(layer "In2.Cu")
		(net "M_I_CPU1_SA_DQ<19>")
	)
	(arc
		(start 136.976104 -236.056932)
		(mid 137.159612 -236.011438)
		(end 137.341864 -236.061758)
		(width 0.0889)
		(layer "In2.Cu")
		(net "M_I_CPU1_SA_DQ<19>")
	)
	(arc
		(start 142.04188 -236.061758)
		(mid 142.324836 -236.137935)
		(end 142.607792 -236.061758)
		(width 0.0889)
		(layer "In2.Cu")
		(net "M_I_CPU1_SA_DQ<19>")
	)
	(arc
		(start 135.461756 -236.061758)
		(mid 135.744712 -236.137935)
		(end 136.027668 -236.061758)
		(width 0.0889)
		(layer "In2.Cu")
		(net "M_I_CPU1_SA_DQ<19>")
	)
	(arc
		(start 129.821686 -236.061758)
		(mid 130.104642 -236.137935)
		(end 130.387598 -236.061758)
		(width 0.0889)
		(layer "In2.Cu")
		(net "M_I_CPU1_SA_DQ<19>")
	)
	(arc
		(start 133.216142 -236.056932)
		(mid 133.39965 -236.011438)
		(end 133.581902 -236.061758)
		(width 0.0889)
		(layer "In2.Cu")
		(net "M_I_CPU1_SA_DQ<19>")
	)
	(arc
		(start 130.387598 -236.061758)
		(mid 130.569849 -236.011408)
		(end 130.753358 -236.056932)
		(width 0.0889)
		(layer "In2.Cu")
		(net "M_I_CPU1_SA_DQ<19>")
	)
	(arc
		(start 128.005078 -236.093508)
		(mid 128.260143 -236.136859)
		(end 128.507744 -236.061758)
		(width 0.0889)
		(layer "In2.Cu")
		(net "M_I_CPU1_SA_DQ<19>")
	)
	(arc
		(start 137.916158 -236.056932)
		(mid 138.099666 -236.011438)
		(end 138.281918 -236.061758)
		(width 0.0889)
		(layer "In2.Cu")
		(net "M_I_CPU1_SA_DQ<19>")
	)
	(arc
		(start 139.221718 -236.061758)
		(mid 139.504674 -236.137935)
		(end 139.78763 -236.061758)
		(width 0.0889)
		(layer "In2.Cu")
		(net "M_I_CPU1_SA_DQ<19>")
	)
	(arc
		(start 132.276088 -236.056932)
		(mid 132.459596 -236.011438)
		(end 132.641848 -236.061758)
		(width 0.0889)
		(layer "In2.Cu")
		(net "M_I_CPU1_SA_DQ<19>")
	)
	(arc
		(start 137.341864 -236.061758)
		(mid 137.62482 -236.137935)
		(end 137.907776 -236.061758)
		(width 0.0889)
		(layer "In2.Cu")
		(net "M_I_CPU1_SA_DQ<19>")
	)
	(arc
		(start 131.327652 -236.061758)
		(mid 131.509903 -236.011408)
		(end 131.693412 -236.056932)
		(width 0.0889)
		(layer "In2.Cu")
		(net "M_I_CPU1_SA_DQ<19>")
	)
	(arc
		(start 140.161772 -236.061758)
		(mid 140.444728 -236.137935)
		(end 140.727684 -236.061758)
		(width 0.0889)
		(layer "In2.Cu")
		(net "M_I_CPU1_SA_DQ<19>")
	)
	(arc
		(start 128.516126 -236.056932)
		(mid 128.699634 -236.011438)
		(end 128.881886 -236.061758)
		(width 0.0889)
		(layer "In2.Cu")
		(net "M_I_CPU1_SA_DQ<19>")
	)
	(arc
		(start 142.607792 -236.061758)
		(mid 142.794736 -236.011503)
		(end 142.98168 -236.061758)
		(width 0.0889)
		(layer "In2.Cu")
		(net "M_I_CPU1_SA_DQ<19>")
	)
	(arc
		(start 131.701794 -236.061758)
		(mid 131.98475 -236.137935)
		(end 132.267706 -236.061758)
		(width 0.0889)
		(layer "In2.Cu")
		(net "M_I_CPU1_SA_DQ<19>")
	)
	(arc
		(start 139.78763 -236.061758)
		(mid 139.969881 -236.011408)
		(end 140.15339 -236.056932)
		(width 0.0889)
		(layer "In2.Cu")
		(net "M_I_CPU1_SA_DQ<19>")
	)
	(arc
		(start 141.67612 -236.056932)
		(mid 141.859628 -236.011438)
		(end 142.04188 -236.061758)
		(width 0.0889)
		(layer "In2.Cu")
		(net "M_I_CPU1_SA_DQ<19>")
	)
	(arc
		(start 133.581902 -236.061758)
		(mid 133.864858 -236.137935)
		(end 134.147814 -236.061758)
		(width 0.0889)
		(layer "In2.Cu")
		(net "M_I_CPU1_SA_DQ<19>")
	)
	(arc
		(start 135.087614 -236.061758)
		(mid 135.269865 -236.011408)
		(end 135.453374 -236.056932)
		(width 0.0889)
		(layer "In2.Cu")
		(net "M_I_CPU1_SA_DQ<19>")
	)
	(arc
		(start 136.40181 -236.061758)
		(mid 136.684766 -236.137935)
		(end 136.967722 -236.061758)
		(width 0.0889)
		(layer "In2.Cu")
		(net "M_I_CPU1_SA_DQ<19>")
	)
	(arc
		(start 129.447798 -236.061758)
		(mid 129.634742 -236.011503)
		(end 129.821686 -236.061758)
		(width 0.0889)
		(layer "In2.Cu")
		(net "M_I_CPU1_SA_DQ<19>")
	)
	(arc
		(start 136.027668 -236.061758)
		(mid 136.209919 -236.011408)
		(end 136.393428 -236.056932)
		(width 0.0889)
		(layer "In2.Cu")
		(net "M_I_CPU1_SA_DQ<19>")
	)
	(arc
		(start 140.727684 -236.061758)
		(mid 140.909935 -236.011408)
		(end 141.093444 -236.056932)
		(width 0.0889)
		(layer "In2.Cu")
		(net "M_I_CPU1_SA_DQ<19>")
	)
	(arc
		(start 130.76174 -236.061758)
		(mid 131.044696 -236.137935)
		(end 131.327652 -236.061758)
		(width 0.0889)
		(layer "In2.Cu")
		(net "M_I_CPU1_SA_DQ<19>")
	)
	(arc
		(start 138.281918 -236.061758)
		(mid 138.564874 -236.137935)
		(end 138.84783 -236.061758)
		(width 0.0889)
		(layer "In2.Cu")
		(net "M_I_CPU1_SA_DQ<19>")
	)
	(segment
		(start 128.69799 -235.84027)
		(end 129.164842 -235.574332)
		(width 0.10668)
		(layer "F.Cu")
		(net "M_I_CPU1_SA_DQ<18>")
	)
	(segment
		(start 155.794456 -223.5708)
		(end 155.521914 -223.298258)
		(width 0.14478)
		(layer "In2.Cu")
		(net "M_I_CPU1_SA_DQ<18>")
	)
	(segment
		(start 157.08249 -221.737682)
		(end 157.08249 -221.509082)
		(width 0.14478)
		(layer "In2.Cu")
		(net "M_I_CPU1_SA_DQ<18>")
	)
	(segment
		(start 154.741626 -224.078546)
		(end 154.741626 -223.849946)
		(width 0.14478)
		(layer "In2.Cu")
		(net "M_I_CPU1_SA_DQ<18>")
	)
	(segment
		(start 154.90317 -223.688402)
		(end 155.13177 -223.688402)
		(width 0.14478)
		(layer "In2.Cu")
		(net "M_I_CPU1_SA_DQ<18>")
	)
	(segment
		(start 173.640496 -217.310462)
		(end 174.490634 -216.460324)
		(width 0.14478)
		(layer "In2.Cu")
		(net "M_I_CPU1_SA_DQ<18>")
	)
	(segment
		(start 154.741626 -223.849946)
		(end 154.90317 -223.688402)
		(width 0.14478)
		(layer "In2.Cu")
		(net "M_I_CPU1_SA_DQ<18>")
	)
	(segment
		(start 133.103366 -235.246926)
		(end 133.111748 -235.251752)
		(width 0.0889)
		(layer "In2.Cu")
		(net "M_I_CPU1_SA_DQ<18>")
	)
	(segment
		(start 153.961338 -224.630234)
		(end 154.122882 -224.46869)
		(width 0.14478)
		(layer "In2.Cu")
		(net "M_I_CPU1_SA_DQ<18>")
	)
	(segment
		(start 129.164842 -235.574332)
		(end 129.318766 -235.308902)
		(width 0.0889)
		(layer "In2.Cu")
		(net "M_I_CPU1_SA_DQ<18>")
	)
	(segment
		(start 155.794456 -223.7994)
		(end 155.794456 -223.5708)
		(width 0.14478)
		(layer "In2.Cu")
		(net "M_I_CPU1_SA_DQ<18>")
	)
	(segment
		(start 156.574744 -223.019112)
		(end 156.574744 -222.790512)
		(width 0.14478)
		(layer "In2.Cu")
		(net "M_I_CPU1_SA_DQ<18>")
	)
	(segment
		(start 174.490634 -216.460324)
		(end 179.091082 -216.460324)
		(width 0.14478)
		(layer "In2.Cu")
		(net "M_I_CPU1_SA_DQ<18>")
	)
	(segment
		(start 156.302202 -222.51797)
		(end 156.302202 -222.28937)
		(width 0.14478)
		(layer "In2.Cu")
		(net "M_I_CPU1_SA_DQ<18>")
	)
	(segment
		(start 156.692346 -222.127826)
		(end 156.964888 -222.400368)
		(width 0.14478)
		(layer "In2.Cu")
		(net "M_I_CPU1_SA_DQ<18>")
	)
	(segment
		(start 155.632912 -223.960944)
		(end 155.794456 -223.7994)
		(width 0.14478)
		(layer "In2.Cu")
		(net "M_I_CPU1_SA_DQ<18>")
	)
	(segment
		(start 139.31773 -235.251752)
		(end 139.326112 -235.246926)
		(width 0.0889)
		(layer "In2.Cu")
		(net "M_I_CPU1_SA_DQ<18>")
	)
	(segment
		(start 155.521914 -223.069658)
		(end 155.683458 -222.908114)
		(width 0.14478)
		(layer "In2.Cu")
		(net "M_I_CPU1_SA_DQ<18>")
	)
	(segment
		(start 144.007078 -235.257848)
		(end 144.223232 -235.131356)
		(width 0.0889)
		(layer "In2.Cu")
		(net "M_I_CPU1_SA_DQ<18>")
	)
	(segment
		(start 156.302202 -222.28937)
		(end 156.463746 -222.127826)
		(width 0.14478)
		(layer "In2.Cu")
		(net "M_I_CPU1_SA_DQ<18>")
	)
	(segment
		(start 154.852624 -224.741232)
		(end 155.014168 -224.579688)
		(width 0.14478)
		(layer "In2.Cu")
		(net "M_I_CPU1_SA_DQ<18>")
	)
	(segment
		(start 167.149272 -216.460324)
		(end 169.942002 -216.460324)
		(width 0.14478)
		(layer "In2.Cu")
		(net "M_I_CPU1_SA_DQ<18>")
	)
	(segment
		(start 138.743436 -235.246926)
		(end 138.751818 -235.251752)
		(width 0.0889)
		(layer "In2.Cu")
		(net "M_I_CPU1_SA_DQ<18>")
	)
	(segment
		(start 154.122882 -224.46869)
		(end 154.351482 -224.46869)
		(width 0.14478)
		(layer "In2.Cu")
		(net "M_I_CPU1_SA_DQ<18>")
	)
	(segment
		(start 157.08249 -221.509082)
		(end 161.28111 -217.310462)
		(width 0.14478)
		(layer "In2.Cu")
		(net "M_I_CPU1_SA_DQ<18>")
	)
	(segment
		(start 154.23388 -225.359976)
		(end 154.23388 -225.131376)
		(width 0.14478)
		(layer "In2.Cu")
		(net "M_I_CPU1_SA_DQ<18>")
	)
	(segment
		(start 155.404312 -223.960944)
		(end 155.632912 -223.960944)
		(width 0.14478)
		(layer "In2.Cu")
		(net "M_I_CPU1_SA_DQ<18>")
	)
	(segment
		(start 153.961338 -224.858834)
		(end 153.961338 -224.630234)
		(width 0.14478)
		(layer "In2.Cu")
		(net "M_I_CPU1_SA_DQ<18>")
	)
	(segment
		(start 134.617714 -235.251752)
		(end 134.626096 -235.246926)
		(width 0.0889)
		(layer "In2.Cu")
		(net "M_I_CPU1_SA_DQ<18>")
	)
	(segment
		(start 155.13177 -223.688402)
		(end 155.404312 -223.960944)
		(width 0.14478)
		(layer "In2.Cu")
		(net "M_I_CPU1_SA_DQ<18>")
	)
	(segment
		(start 129.318766 -235.308902)
		(end 129.414778 -235.283502)
		(width 0.0889)
		(layer "In2.Cu")
		(net "M_I_CPU1_SA_DQ<18>")
	)
	(segment
		(start 147.817586 -231.77627)
		(end 154.23388 -225.359976)
		(width 0.14478)
		(layer "In2.Cu")
		(net "M_I_CPU1_SA_DQ<18>")
	)
	(segment
		(start 155.683458 -222.908114)
		(end 155.912058 -222.908114)
		(width 0.14478)
		(layer "In2.Cu")
		(net "M_I_CPU1_SA_DQ<18>")
	)
	(segment
		(start 156.1846 -223.180656)
		(end 156.4132 -223.180656)
		(width 0.14478)
		(layer "In2.Cu")
		(net "M_I_CPU1_SA_DQ<18>")
	)
	(segment
		(start 157.193488 -222.400368)
		(end 157.355032 -222.238824)
		(width 0.14478)
		(layer "In2.Cu")
		(net "M_I_CPU1_SA_DQ<18>")
	)
	(segment
		(start 155.014168 -224.579688)
		(end 155.014168 -224.351088)
		(width 0.14478)
		(layer "In2.Cu")
		(net "M_I_CPU1_SA_DQ<18>")
	)
	(segment
		(start 145.633186 -233.417364)
		(end 147.094194 -231.956356)
		(width 0.0889)
		(layer "In2.Cu")
		(net "M_I_CPU1_SA_DQ<18>")
	)
	(segment
		(start 166.299134 -217.310462)
		(end 167.149272 -216.460324)
		(width 0.14478)
		(layer "In2.Cu")
		(net "M_I_CPU1_SA_DQ<18>")
	)
	(segment
		(start 154.624024 -224.741232)
		(end 154.852624 -224.741232)
		(width 0.14478)
		(layer "In2.Cu")
		(net "M_I_CPU1_SA_DQ<18>")
	)
	(segment
		(start 155.014168 -224.351088)
		(end 154.741626 -224.078546)
		(width 0.14478)
		(layer "In2.Cu")
		(net "M_I_CPU1_SA_DQ<18>")
	)
	(segment
		(start 169.942002 -216.460324)
		(end 170.79214 -217.310462)
		(width 0.14478)
		(layer "In2.Cu")
		(net "M_I_CPU1_SA_DQ<18>")
	)
	(segment
		(start 155.521914 -223.298258)
		(end 155.521914 -223.069658)
		(width 0.14478)
		(layer "In2.Cu")
		(net "M_I_CPU1_SA_DQ<18>")
	)
	(segment
		(start 156.463746 -222.127826)
		(end 156.692346 -222.127826)
		(width 0.14478)
		(layer "In2.Cu")
		(net "M_I_CPU1_SA_DQ<18>")
	)
	(segment
		(start 170.79214 -217.310462)
		(end 173.640496 -217.310462)
		(width 0.14478)
		(layer "In2.Cu")
		(net "M_I_CPU1_SA_DQ<18>")
	)
	(segment
		(start 147.6375 -231.956356)
		(end 147.817586 -231.77627)
		(width 0.0889)
		(layer "In2.Cu")
		(net "M_I_CPU1_SA_DQ<18>")
	)
	(segment
		(start 157.355032 -222.010224)
		(end 157.08249 -221.737682)
		(width 0.14478)
		(layer "In2.Cu")
		(net "M_I_CPU1_SA_DQ<18>")
	)
	(segment
		(start 179.091082 -216.460324)
		(end 179.516024 -216.885266)
		(width 0.14478)
		(layer "In2.Cu")
		(net "M_I_CPU1_SA_DQ<18>")
	)
	(segment
		(start 154.23388 -225.131376)
		(end 153.961338 -224.858834)
		(width 0.14478)
		(layer "In2.Cu")
		(net "M_I_CPU1_SA_DQ<18>")
	)
	(segment
		(start 156.964888 -222.400368)
		(end 157.193488 -222.400368)
		(width 0.14478)
		(layer "In2.Cu")
		(net "M_I_CPU1_SA_DQ<18>")
	)
	(segment
		(start 147.094194 -231.956356)
		(end 147.6375 -231.956356)
		(width 0.0889)
		(layer "In2.Cu")
		(net "M_I_CPU1_SA_DQ<18>")
	)
	(segment
		(start 144.223232 -235.131356)
		(end 144.977866 -234.644692)
		(width 0.0889)
		(layer "In2.Cu")
		(net "M_I_CPU1_SA_DQ<18>")
	)
	(segment
		(start 129.917698 -235.251752)
		(end 129.92608 -235.246926)
		(width 0.0889)
		(layer "In2.Cu")
		(net "M_I_CPU1_SA_DQ<18>")
	)
	(segment
		(start 143.077692 -235.251752)
		(end 143.086074 -235.246926)
		(width 0.0889)
		(layer "In2.Cu")
		(net "M_I_CPU1_SA_DQ<18>")
	)
	(segment
		(start 145.633186 -233.975148)
		(end 145.633186 -233.417364)
		(width 0.0889)
		(layer "In2.Cu")
		(net "M_I_CPU1_SA_DQ<18>")
	)
	(segment
		(start 142.503398 -235.246926)
		(end 142.51178 -235.251752)
		(width 0.0889)
		(layer "In2.Cu")
		(net "M_I_CPU1_SA_DQ<18>")
	)
	(segment
		(start 154.351482 -224.46869)
		(end 154.624024 -224.741232)
		(width 0.14478)
		(layer "In2.Cu")
		(net "M_I_CPU1_SA_DQ<18>")
	)
	(segment
		(start 135.557768 -235.251752)
		(end 135.56615 -235.246926)
		(width 0.0889)
		(layer "In2.Cu")
		(net "M_I_CPU1_SA_DQ<18>")
	)
	(segment
		(start 140.257784 -235.251752)
		(end 140.266166 -235.246926)
		(width 0.0889)
		(layer "In2.Cu")
		(net "M_I_CPU1_SA_DQ<18>")
	)
	(segment
		(start 155.912058 -222.908114)
		(end 156.1846 -223.180656)
		(width 0.14478)
		(layer "In2.Cu")
		(net "M_I_CPU1_SA_DQ<18>")
	)
	(segment
		(start 130.857752 -235.251752)
		(end 130.866134 -235.246926)
		(width 0.0889)
		(layer "In2.Cu")
		(net "M_I_CPU1_SA_DQ<18>")
	)
	(segment
		(start 156.4132 -223.180656)
		(end 156.574744 -223.019112)
		(width 0.14478)
		(layer "In2.Cu")
		(net "M_I_CPU1_SA_DQ<18>")
	)
	(segment
		(start 156.574744 -222.790512)
		(end 156.302202 -222.51797)
		(width 0.14478)
		(layer "In2.Cu")
		(net "M_I_CPU1_SA_DQ<18>")
	)
	(segment
		(start 144.977866 -234.644692)
		(end 145.633186 -233.975148)
		(width 0.0889)
		(layer "In2.Cu")
		(net "M_I_CPU1_SA_DQ<18>")
	)
	(segment
		(start 137.803382 -235.246926)
		(end 137.811764 -235.251752)
		(width 0.0889)
		(layer "In2.Cu")
		(net "M_I_CPU1_SA_DQ<18>")
	)
	(segment
		(start 157.355032 -222.238824)
		(end 157.355032 -222.010224)
		(width 0.14478)
		(layer "In2.Cu")
		(net "M_I_CPU1_SA_DQ<18>")
	)
	(segment
		(start 161.28111 -217.310462)
		(end 166.299134 -217.310462)
		(width 0.14478)
		(layer "In2.Cu")
		(net "M_I_CPU1_SA_DQ<18>")
	)
	(segment
		(start 134.04342 -235.246926)
		(end 134.051802 -235.251752)
		(width 0.0889)
		(layer "In2.Cu")
		(net "M_I_CPU1_SA_DQ<18>")
	)
	(arc
		(start 137.811764 -235.251752)
		(mid 138.09472 -235.327929)
		(end 138.377676 -235.251752)
		(width 0.0889)
		(layer "In2.Cu")
		(net "M_I_CPU1_SA_DQ<18>")
	)
	(arc
		(start 135.56615 -235.246926)
		(mid 135.749658 -235.201432)
		(end 135.93191 -235.251752)
		(width 0.0889)
		(layer "In2.Cu")
		(net "M_I_CPU1_SA_DQ<18>")
	)
	(arc
		(start 136.497822 -235.251752)
		(mid 136.684766 -235.201497)
		(end 136.87171 -235.251752)
		(width 0.0889)
		(layer "In2.Cu")
		(net "M_I_CPU1_SA_DQ<18>")
	)
	(arc
		(start 138.751818 -235.251752)
		(mid 139.034774 -235.327929)
		(end 139.31773 -235.251752)
		(width 0.0889)
		(layer "In2.Cu")
		(net "M_I_CPU1_SA_DQ<18>")
	)
	(arc
		(start 140.266166 -235.246926)
		(mid 140.449674 -235.201432)
		(end 140.631926 -235.251752)
		(width 0.0889)
		(layer "In2.Cu")
		(net "M_I_CPU1_SA_DQ<18>")
	)
	(arc
		(start 136.87171 -235.251752)
		(mid 137.154666 -235.327929)
		(end 137.437622 -235.251752)
		(width 0.0889)
		(layer "In2.Cu")
		(net "M_I_CPU1_SA_DQ<18>")
	)
	(arc
		(start 142.51178 -235.251752)
		(mid 142.794736 -235.327929)
		(end 143.077692 -235.251752)
		(width 0.0889)
		(layer "In2.Cu")
		(net "M_I_CPU1_SA_DQ<18>")
	)
	(arc
		(start 137.437622 -235.251752)
		(mid 137.619873 -235.201402)
		(end 137.803382 -235.246926)
		(width 0.0889)
		(layer "In2.Cu")
		(net "M_I_CPU1_SA_DQ<18>")
	)
	(arc
		(start 132.171694 -235.251752)
		(mid 132.45465 -235.327929)
		(end 132.737606 -235.251752)
		(width 0.0889)
		(layer "In2.Cu")
		(net "M_I_CPU1_SA_DQ<18>")
	)
	(arc
		(start 131.797806 -235.251752)
		(mid 131.98475 -235.201497)
		(end 132.171694 -235.251752)
		(width 0.0889)
		(layer "In2.Cu")
		(net "M_I_CPU1_SA_DQ<18>")
	)
	(arc
		(start 142.137638 -235.251752)
		(mid 142.319889 -235.201402)
		(end 142.503398 -235.246926)
		(width 0.0889)
		(layer "In2.Cu")
		(net "M_I_CPU1_SA_DQ<18>")
	)
	(arc
		(start 139.326112 -235.246926)
		(mid 139.50962 -235.201432)
		(end 139.691872 -235.251752)
		(width 0.0889)
		(layer "In2.Cu")
		(net "M_I_CPU1_SA_DQ<18>")
	)
	(arc
		(start 135.93191 -235.251752)
		(mid 136.214866 -235.327929)
		(end 136.497822 -235.251752)
		(width 0.0889)
		(layer "In2.Cu")
		(net "M_I_CPU1_SA_DQ<18>")
	)
	(arc
		(start 134.991856 -235.251752)
		(mid 135.274812 -235.327929)
		(end 135.557768 -235.251752)
		(width 0.0889)
		(layer "In2.Cu")
		(net "M_I_CPU1_SA_DQ<18>")
	)
	(arc
		(start 133.111748 -235.251752)
		(mid 133.394704 -235.327929)
		(end 133.67766 -235.251752)
		(width 0.0889)
		(layer "In2.Cu")
		(net "M_I_CPU1_SA_DQ<18>")
	)
	(arc
		(start 139.691872 -235.251752)
		(mid 139.974828 -235.327929)
		(end 140.257784 -235.251752)
		(width 0.0889)
		(layer "In2.Cu")
		(net "M_I_CPU1_SA_DQ<18>")
	)
	(arc
		(start 141.571726 -235.251752)
		(mid 141.854682 -235.327929)
		(end 142.137638 -235.251752)
		(width 0.0889)
		(layer "In2.Cu")
		(net "M_I_CPU1_SA_DQ<18>")
	)
	(arc
		(start 143.451834 -235.251752)
		(mid 143.728647 -235.327895)
		(end 144.007078 -235.257848)
		(width 0.0889)
		(layer "In2.Cu")
		(net "M_I_CPU1_SA_DQ<18>")
	)
	(arc
		(start 132.737606 -235.251752)
		(mid 132.919857 -235.201402)
		(end 133.103366 -235.246926)
		(width 0.0889)
		(layer "In2.Cu")
		(net "M_I_CPU1_SA_DQ<18>")
	)
	(arc
		(start 138.377676 -235.251752)
		(mid 138.559927 -235.201402)
		(end 138.743436 -235.246926)
		(width 0.0889)
		(layer "In2.Cu")
		(net "M_I_CPU1_SA_DQ<18>")
	)
	(arc
		(start 129.92608 -235.246926)
		(mid 130.109588 -235.201432)
		(end 130.29184 -235.251752)
		(width 0.0889)
		(layer "In2.Cu")
		(net "M_I_CPU1_SA_DQ<18>")
	)
	(arc
		(start 129.414778 -235.283502)
		(mid 129.669986 -235.326979)
		(end 129.917698 -235.251752)
		(width 0.0889)
		(layer "In2.Cu")
		(net "M_I_CPU1_SA_DQ<18>")
	)
	(arc
		(start 134.051802 -235.251752)
		(mid 134.334758 -235.327929)
		(end 134.617714 -235.251752)
		(width 0.0889)
		(layer "In2.Cu")
		(net "M_I_CPU1_SA_DQ<18>")
	)
	(arc
		(start 143.086074 -235.246926)
		(mid 143.269582 -235.201432)
		(end 143.451834 -235.251752)
		(width 0.0889)
		(layer "In2.Cu")
		(net "M_I_CPU1_SA_DQ<18>")
	)
	(arc
		(start 130.29184 -235.251752)
		(mid 130.574796 -235.327929)
		(end 130.857752 -235.251752)
		(width 0.0889)
		(layer "In2.Cu")
		(net "M_I_CPU1_SA_DQ<18>")
	)
	(arc
		(start 131.231894 -235.251752)
		(mid 131.51485 -235.327929)
		(end 131.797806 -235.251752)
		(width 0.0889)
		(layer "In2.Cu")
		(net "M_I_CPU1_SA_DQ<18>")
	)
	(arc
		(start 141.197838 -235.251752)
		(mid 141.384782 -235.201497)
		(end 141.571726 -235.251752)
		(width 0.0889)
		(layer "In2.Cu")
		(net "M_I_CPU1_SA_DQ<18>")
	)
	(arc
		(start 134.626096 -235.246926)
		(mid 134.809604 -235.201432)
		(end 134.991856 -235.251752)
		(width 0.0889)
		(layer "In2.Cu")
		(net "M_I_CPU1_SA_DQ<18>")
	)
	(arc
		(start 133.67766 -235.251752)
		(mid 133.859911 -235.201402)
		(end 134.04342 -235.246926)
		(width 0.0889)
		(layer "In2.Cu")
		(net "M_I_CPU1_SA_DQ<18>")
	)
	(arc
		(start 130.866134 -235.246926)
		(mid 131.049642 -235.201432)
		(end 131.231894 -235.251752)
		(width 0.0889)
		(layer "In2.Cu")
		(net "M_I_CPU1_SA_DQ<18>")
	)
	(arc
		(start 140.631926 -235.251752)
		(mid 140.914882 -235.327929)
		(end 141.197838 -235.251752)
		(width 0.0889)
		(layer "In2.Cu")
		(net "M_I_CPU1_SA_DQ<18>")
	)
	(segment
		(start 127.757936 -235.84027)
		(end 128.224788 -235.574332)
		(width 0.10668)
		(layer "F.Cu")
		(net "M_I_CPU1_SA_DQ<17>")
	)
	(segment
		(start 137.803382 -235.901738)
		(end 137.811764 -235.896912)
		(width 0.0889)
		(layer "In2.Cu")
		(net "M_I_CPU1_SA_DQ<17>")
	)
	(segment
		(start 146.727926 -232.95991)
		(end 147.690078 -232.561384)
		(width 0.0889)
		(layer "In2.Cu")
		(net "M_I_CPU1_SA_DQ<17>")
	)
	(segment
		(start 183.19115 -217.310462)
		(end 183.616092 -217.735404)
		(width 0.14478)
		(layer "In2.Cu")
		(net "M_I_CPU1_SA_DQ<17>")
	)
	(segment
		(start 134.04342 -235.901738)
		(end 134.051802 -235.896912)
		(width 0.0889)
		(layer "In2.Cu")
		(net "M_I_CPU1_SA_DQ<17>")
	)
	(segment
		(start 134.617714 -235.896912)
		(end 134.626096 -235.901738)
		(width 0.0889)
		(layer "In2.Cu")
		(net "M_I_CPU1_SA_DQ<17>")
	)
	(segment
		(start 174.34433 -217.310462)
		(end 183.19115 -217.310462)
		(width 0.14478)
		(layer "In2.Cu")
		(net "M_I_CPU1_SA_DQ<17>")
	)
	(segment
		(start 146.4437 -233.193336)
		(end 146.727926 -232.95991)
		(width 0.0889)
		(layer "In2.Cu")
		(net "M_I_CPU1_SA_DQ<17>")
	)
	(segment
		(start 128.224788 -235.574332)
		(end 128.07061 -235.839762)
		(width 0.0889)
		(layer "In2.Cu")
		(net "M_I_CPU1_SA_DQ<17>")
	)
	(segment
		(start 129.917698 -235.896912)
		(end 129.92608 -235.901738)
		(width 0.0889)
		(layer "In2.Cu")
		(net "M_I_CPU1_SA_DQ<17>")
	)
	(segment
		(start 140.257784 -235.896912)
		(end 140.266166 -235.901738)
		(width 0.0889)
		(layer "In2.Cu")
		(net "M_I_CPU1_SA_DQ<17>")
	)
	(segment
		(start 143.528288 -235.837984)
		(end 145.163032 -234.772962)
		(width 0.0889)
		(layer "In2.Cu")
		(net "M_I_CPU1_SA_DQ<17>")
	)
	(segment
		(start 166.180262 -218.160346)
		(end 167.030146 -217.310462)
		(width 0.14478)
		(layer "In2.Cu")
		(net "M_I_CPU1_SA_DQ<17>")
	)
	(segment
		(start 139.31773 -235.896912)
		(end 139.326112 -235.901738)
		(width 0.0889)
		(layer "In2.Cu")
		(net "M_I_CPU1_SA_DQ<17>")
	)
	(segment
		(start 129.343404 -235.901738)
		(end 129.351786 -235.896912)
		(width 0.0889)
		(layer "In2.Cu")
		(net "M_I_CPU1_SA_DQ<17>")
	)
	(segment
		(start 167.030146 -217.310462)
		(end 170.10761 -217.310462)
		(width 0.14478)
		(layer "In2.Cu")
		(net "M_I_CPU1_SA_DQ<17>")
	)
	(segment
		(start 133.103366 -235.901738)
		(end 133.111748 -235.896912)
		(width 0.0889)
		(layer "In2.Cu")
		(net "M_I_CPU1_SA_DQ<17>")
	)
	(segment
		(start 157.9118 -221.316042)
		(end 161.067496 -218.160346)
		(width 0.14478)
		(layer "In2.Cu")
		(net "M_I_CPU1_SA_DQ<17>")
	)
	(segment
		(start 145.826226 -234.117134)
		(end 146.4437 -233.193336)
		(width 0.0889)
		(layer "In2.Cu")
		(net "M_I_CPU1_SA_DQ<17>")
	)
	(segment
		(start 145.163032 -234.772962)
		(end 145.826226 -234.117134)
		(width 0.0889)
		(layer "In2.Cu")
		(net "M_I_CPU1_SA_DQ<17>")
	)
	(segment
		(start 142.503398 -235.901738)
		(end 142.51178 -235.896912)
		(width 0.0889)
		(layer "In2.Cu")
		(net "M_I_CPU1_SA_DQ<17>")
	)
	(segment
		(start 138.743436 -235.901738)
		(end 138.751818 -235.896912)
		(width 0.0889)
		(layer "In2.Cu")
		(net "M_I_CPU1_SA_DQ<17>")
	)
	(segment
		(start 157.9118 -222.339662)
		(end 157.9118 -221.316042)
		(width 0.14478)
		(layer "In2.Cu")
		(net "M_I_CPU1_SA_DQ<17>")
	)
	(segment
		(start 147.922742 -232.32872)
		(end 157.9118 -222.339662)
		(width 0.14478)
		(layer "In2.Cu")
		(net "M_I_CPU1_SA_DQ<17>")
	)
	(segment
		(start 170.957494 -218.160346)
		(end 173.494446 -218.160346)
		(width 0.14478)
		(layer "In2.Cu")
		(net "M_I_CPU1_SA_DQ<17>")
	)
	(segment
		(start 130.857752 -235.896912)
		(end 130.866134 -235.901738)
		(width 0.0889)
		(layer "In2.Cu")
		(net "M_I_CPU1_SA_DQ<17>")
	)
	(segment
		(start 135.557768 -235.896912)
		(end 135.56615 -235.901738)
		(width 0.0889)
		(layer "In2.Cu")
		(net "M_I_CPU1_SA_DQ<17>")
	)
	(segment
		(start 147.690078 -232.561384)
		(end 147.922742 -232.32872)
		(width 0.0889)
		(layer "In2.Cu")
		(net "M_I_CPU1_SA_DQ<17>")
	)
	(segment
		(start 128.40335 -235.901738)
		(end 128.411732 -235.896912)
		(width 0.0889)
		(layer "In2.Cu")
		(net "M_I_CPU1_SA_DQ<17>")
	)
	(segment
		(start 161.067496 -218.160346)
		(end 166.180262 -218.160346)
		(width 0.14478)
		(layer "In2.Cu")
		(net "M_I_CPU1_SA_DQ<17>")
	)
	(segment
		(start 128.07061 -235.839762)
		(end 128.092962 -235.923074)
		(width 0.0889)
		(layer "In2.Cu")
		(net "M_I_CPU1_SA_DQ<17>")
	)
	(segment
		(start 170.10761 -217.310462)
		(end 170.957494 -218.160346)
		(width 0.14478)
		(layer "In2.Cu")
		(net "M_I_CPU1_SA_DQ<17>")
	)
	(segment
		(start 143.077692 -235.896912)
		(end 143.086074 -235.901738)
		(width 0.0889)
		(layer "In2.Cu")
		(net "M_I_CPU1_SA_DQ<17>")
	)
	(segment
		(start 173.494446 -218.160346)
		(end 174.34433 -217.310462)
		(width 0.14478)
		(layer "In2.Cu")
		(net "M_I_CPU1_SA_DQ<17>")
	)
	(arc
		(start 142.51178 -235.896912)
		(mid 142.794736 -235.820735)
		(end 143.077692 -235.896912)
		(width 0.0889)
		(layer "In2.Cu")
		(net "M_I_CPU1_SA_DQ<17>")
	)
	(arc
		(start 141.197838 -235.896912)
		(mid 141.384782 -235.947167)
		(end 141.571726 -235.896912)
		(width 0.0889)
		(layer "In2.Cu")
		(net "M_I_CPU1_SA_DQ<17>")
	)
	(arc
		(start 133.67766 -235.896912)
		(mid 133.859911 -235.947262)
		(end 134.04342 -235.901738)
		(width 0.0889)
		(layer "In2.Cu")
		(net "M_I_CPU1_SA_DQ<17>")
	)
	(arc
		(start 128.092962 -235.923074)
		(mid 128.250472 -235.946272)
		(end 128.40335 -235.901738)
		(width 0.0889)
		(layer "In2.Cu")
		(net "M_I_CPU1_SA_DQ<17>")
	)
	(arc
		(start 143.451834 -235.896912)
		(mid 143.491979 -235.869936)
		(end 143.528288 -235.837984)
		(width 0.0889)
		(layer "In2.Cu")
		(net "M_I_CPU1_SA_DQ<17>")
	)
	(arc
		(start 132.737606 -235.896912)
		(mid 132.919857 -235.947262)
		(end 133.103366 -235.901738)
		(width 0.0889)
		(layer "In2.Cu")
		(net "M_I_CPU1_SA_DQ<17>")
	)
	(arc
		(start 136.497822 -235.896912)
		(mid 136.684766 -235.947167)
		(end 136.87171 -235.896912)
		(width 0.0889)
		(layer "In2.Cu")
		(net "M_I_CPU1_SA_DQ<17>")
	)
	(arc
		(start 134.051802 -235.896912)
		(mid 134.334758 -235.820735)
		(end 134.617714 -235.896912)
		(width 0.0889)
		(layer "In2.Cu")
		(net "M_I_CPU1_SA_DQ<17>")
	)
	(arc
		(start 139.326112 -235.901738)
		(mid 139.50962 -235.947232)
		(end 139.691872 -235.896912)
		(width 0.0889)
		(layer "In2.Cu")
		(net "M_I_CPU1_SA_DQ<17>")
	)
	(arc
		(start 134.991856 -235.896912)
		(mid 135.274812 -235.820735)
		(end 135.557768 -235.896912)
		(width 0.0889)
		(layer "In2.Cu")
		(net "M_I_CPU1_SA_DQ<17>")
	)
	(arc
		(start 129.92608 -235.901738)
		(mid 130.109588 -235.947232)
		(end 130.29184 -235.896912)
		(width 0.0889)
		(layer "In2.Cu")
		(net "M_I_CPU1_SA_DQ<17>")
	)
	(arc
		(start 137.437622 -235.896912)
		(mid 137.619873 -235.947262)
		(end 137.803382 -235.901738)
		(width 0.0889)
		(layer "In2.Cu")
		(net "M_I_CPU1_SA_DQ<17>")
	)
	(arc
		(start 131.231894 -235.896912)
		(mid 131.51485 -235.820735)
		(end 131.797806 -235.896912)
		(width 0.0889)
		(layer "In2.Cu")
		(net "M_I_CPU1_SA_DQ<17>")
	)
	(arc
		(start 140.631926 -235.896912)
		(mid 140.914882 -235.820735)
		(end 141.197838 -235.896912)
		(width 0.0889)
		(layer "In2.Cu")
		(net "M_I_CPU1_SA_DQ<17>")
	)
	(arc
		(start 135.56615 -235.901738)
		(mid 135.749658 -235.947232)
		(end 135.93191 -235.896912)
		(width 0.0889)
		(layer "In2.Cu")
		(net "M_I_CPU1_SA_DQ<17>")
	)
	(arc
		(start 137.811764 -235.896912)
		(mid 138.09472 -235.820735)
		(end 138.377676 -235.896912)
		(width 0.0889)
		(layer "In2.Cu")
		(net "M_I_CPU1_SA_DQ<17>")
	)
	(arc
		(start 132.171694 -235.896912)
		(mid 132.45465 -235.820735)
		(end 132.737606 -235.896912)
		(width 0.0889)
		(layer "In2.Cu")
		(net "M_I_CPU1_SA_DQ<17>")
	)
	(arc
		(start 138.377676 -235.896912)
		(mid 138.559927 -235.947262)
		(end 138.743436 -235.901738)
		(width 0.0889)
		(layer "In2.Cu")
		(net "M_I_CPU1_SA_DQ<17>")
	)
	(arc
		(start 128.977644 -235.896912)
		(mid 129.159895 -235.947262)
		(end 129.343404 -235.901738)
		(width 0.0889)
		(layer "In2.Cu")
		(net "M_I_CPU1_SA_DQ<17>")
	)
	(arc
		(start 143.086074 -235.901738)
		(mid 143.269582 -235.947232)
		(end 143.451834 -235.896912)
		(width 0.0889)
		(layer "In2.Cu")
		(net "M_I_CPU1_SA_DQ<17>")
	)
	(arc
		(start 134.626096 -235.901738)
		(mid 134.809604 -235.947232)
		(end 134.991856 -235.896912)
		(width 0.0889)
		(layer "In2.Cu")
		(net "M_I_CPU1_SA_DQ<17>")
	)
	(arc
		(start 139.691872 -235.896912)
		(mid 139.974828 -235.820735)
		(end 140.257784 -235.896912)
		(width 0.0889)
		(layer "In2.Cu")
		(net "M_I_CPU1_SA_DQ<17>")
	)
	(arc
		(start 141.571726 -235.896912)
		(mid 141.854682 -235.820735)
		(end 142.137638 -235.896912)
		(width 0.0889)
		(layer "In2.Cu")
		(net "M_I_CPU1_SA_DQ<17>")
	)
	(arc
		(start 128.411732 -235.896912)
		(mid 128.694688 -235.820735)
		(end 128.977644 -235.896912)
		(width 0.0889)
		(layer "In2.Cu")
		(net "M_I_CPU1_SA_DQ<17>")
	)
	(arc
		(start 140.266166 -235.901738)
		(mid 140.449674 -235.947232)
		(end 140.631926 -235.896912)
		(width 0.0889)
		(layer "In2.Cu")
		(net "M_I_CPU1_SA_DQ<17>")
	)
	(arc
		(start 135.93191 -235.896912)
		(mid 136.214866 -235.820735)
		(end 136.497822 -235.896912)
		(width 0.0889)
		(layer "In2.Cu")
		(net "M_I_CPU1_SA_DQ<17>")
	)
	(arc
		(start 131.797806 -235.896912)
		(mid 131.98475 -235.947167)
		(end 132.171694 -235.896912)
		(width 0.0889)
		(layer "In2.Cu")
		(net "M_I_CPU1_SA_DQ<17>")
	)
	(arc
		(start 133.111748 -235.896912)
		(mid 133.394704 -235.820735)
		(end 133.67766 -235.896912)
		(width 0.0889)
		(layer "In2.Cu")
		(net "M_I_CPU1_SA_DQ<17>")
	)
	(arc
		(start 129.351786 -235.896912)
		(mid 129.634742 -235.820735)
		(end 129.917698 -235.896912)
		(width 0.0889)
		(layer "In2.Cu")
		(net "M_I_CPU1_SA_DQ<17>")
	)
	(arc
		(start 130.29184 -235.896912)
		(mid 130.574796 -235.820735)
		(end 130.857752 -235.896912)
		(width 0.0889)
		(layer "In2.Cu")
		(net "M_I_CPU1_SA_DQ<17>")
	)
	(arc
		(start 142.137638 -235.896912)
		(mid 142.319889 -235.947262)
		(end 142.503398 -235.901738)
		(width 0.0889)
		(layer "In2.Cu")
		(net "M_I_CPU1_SA_DQ<17>")
	)
	(arc
		(start 130.866134 -235.901738)
		(mid 131.049642 -235.947232)
		(end 131.231894 -235.896912)
		(width 0.0889)
		(layer "In2.Cu")
		(net "M_I_CPU1_SA_DQ<17>")
	)
	(arc
		(start 138.751818 -235.896912)
		(mid 139.034774 -235.820735)
		(end 139.31773 -235.896912)
		(width 0.0889)
		(layer "In2.Cu")
		(net "M_I_CPU1_SA_DQ<17>")
	)
	(arc
		(start 136.87171 -235.896912)
		(mid 137.154666 -235.820735)
		(end 137.437622 -235.896912)
		(width 0.0889)
		(layer "In2.Cu")
		(net "M_I_CPU1_SA_DQ<17>")
	)
	(segment
		(start 129.16789 -235.030264)
		(end 129.634742 -234.764326)
		(width 0.10668)
		(layer "F.Cu")
		(net "M_I_CPU1_SA_DQ<16>")
	)
	(segment
		(start 167.02405 -215.61044)
		(end 169.776648 -215.61044)
		(width 0.14478)
		(layer "In2.Cu")
		(net "M_I_CPU1_SA_DQ<16>")
	)
	(segment
		(start 146.96059 -231.43464)
		(end 147.514056 -231.43464)
		(width 0.14478)
		(layer "In2.Cu")
		(net "M_I_CPU1_SA_DQ<16>")
	)
	(segment
		(start 131.693412 -235.091732)
		(end 131.701794 -235.086906)
		(width 0.0889)
		(layer "In2.Cu")
		(net "M_I_CPU1_SA_DQ<16>")
	)
	(segment
		(start 141.093444 -235.091732)
		(end 141.101826 -235.086906)
		(width 0.0889)
		(layer "In2.Cu")
		(net "M_I_CPU1_SA_DQ<16>")
	)
	(segment
		(start 146.114008 -231.894888)
		(end 146.574256 -231.43464)
		(width 0.0889)
		(layer "In2.Cu")
		(net "M_I_CPU1_SA_DQ<16>")
	)
	(segment
		(start 170.626532 -216.460324)
		(end 173.684692 -216.460324)
		(width 0.14478)
		(layer "In2.Cu")
		(net "M_I_CPU1_SA_DQ<16>")
	)
	(segment
		(start 147.514056 -231.43464)
		(end 153.511758 -225.436938)
		(width 0.14478)
		(layer "In2.Cu")
		(net "M_I_CPU1_SA_DQ<16>")
	)
	(segment
		(start 137.907776 -235.086906)
		(end 137.916158 -235.091732)
		(width 0.0889)
		(layer "In2.Cu")
		(net "M_I_CPU1_SA_DQ<16>")
	)
	(segment
		(start 130.753358 -235.091732)
		(end 130.76174 -235.086906)
		(width 0.0889)
		(layer "In2.Cu")
		(net "M_I_CPU1_SA_DQ<16>")
	)
	(segment
		(start 173.684692 -216.460324)
		(end 174.534576 -215.61044)
		(width 0.14478)
		(layer "In2.Cu")
		(net "M_I_CPU1_SA_DQ<16>")
	)
	(segment
		(start 140.15339 -235.091732)
		(end 140.161772 -235.086906)
		(width 0.0889)
		(layer "In2.Cu")
		(net "M_I_CPU1_SA_DQ<16>")
	)
	(segment
		(start 143.913352 -235.091732)
		(end 143.921734 -235.086906)
		(width 0.0889)
		(layer "In2.Cu")
		(net "M_I_CPU1_SA_DQ<16>")
	)
	(segment
		(start 166.174166 -216.460324)
		(end 167.02405 -215.61044)
		(width 0.14478)
		(layer "In2.Cu")
		(net "M_I_CPU1_SA_DQ<16>")
	)
	(segment
		(start 136.393428 -235.091732)
		(end 136.40181 -235.086906)
		(width 0.0889)
		(layer "In2.Cu")
		(net "M_I_CPU1_SA_DQ<16>")
	)
	(segment
		(start 129.634742 -234.764326)
		(end 129.480818 -235.029756)
		(width 0.0889)
		(layer "In2.Cu")
		(net "M_I_CPU1_SA_DQ<16>")
	)
	(segment
		(start 135.453374 -235.091732)
		(end 135.461756 -235.086906)
		(width 0.0889)
		(layer "In2.Cu")
		(net "M_I_CPU1_SA_DQ<16>")
	)
	(segment
		(start 141.667738 -235.086906)
		(end 141.67612 -235.091732)
		(width 0.0889)
		(layer "In2.Cu")
		(net "M_I_CPU1_SA_DQ<16>")
	)
	(segment
		(start 153.511758 -225.436938)
		(end 153.511758 -224.443798)
		(width 0.14478)
		(layer "In2.Cu")
		(net "M_I_CPU1_SA_DQ<16>")
	)
	(segment
		(start 146.114008 -232.477564)
		(end 146.114008 -231.894888)
		(width 0.0889)
		(layer "In2.Cu")
		(net "M_I_CPU1_SA_DQ<16>")
	)
	(segment
		(start 174.534576 -215.61044)
		(end 183.19115 -215.61044)
		(width 0.14478)
		(layer "In2.Cu")
		(net "M_I_CPU1_SA_DQ<16>")
	)
	(segment
		(start 136.967722 -235.086906)
		(end 136.976104 -235.091732)
		(width 0.0889)
		(layer "In2.Cu")
		(net "M_I_CPU1_SA_DQ<16>")
	)
	(segment
		(start 146.574256 -231.43464)
		(end 146.96059 -231.43464)
		(width 0.0889)
		(layer "In2.Cu")
		(net "M_I_CPU1_SA_DQ<16>")
	)
	(segment
		(start 133.20776 -235.086906)
		(end 133.216142 -235.091732)
		(width 0.0889)
		(layer "In2.Cu")
		(net "M_I_CPU1_SA_DQ<16>")
	)
	(segment
		(start 183.19115 -215.61044)
		(end 183.616092 -216.035382)
		(width 0.14478)
		(layer "In2.Cu")
		(net "M_I_CPU1_SA_DQ<16>")
	)
	(segment
		(start 144.711928 -233.879644)
		(end 146.114008 -232.477564)
		(width 0.0889)
		(layer "In2.Cu")
		(net "M_I_CPU1_SA_DQ<16>")
	)
	(segment
		(start 161.495232 -216.460324)
		(end 166.174166 -216.460324)
		(width 0.14478)
		(layer "In2.Cu")
		(net "M_I_CPU1_SA_DQ<16>")
	)
	(segment
		(start 129.480818 -235.029756)
		(end 129.50317 -235.113068)
		(width 0.0889)
		(layer "In2.Cu")
		(net "M_I_CPU1_SA_DQ<16>")
	)
	(segment
		(start 143.921734 -235.086906)
		(end 144.711928 -234.296712)
		(width 0.0889)
		(layer "In2.Cu")
		(net "M_I_CPU1_SA_DQ<16>")
	)
	(segment
		(start 132.267706 -235.086906)
		(end 132.276088 -235.091732)
		(width 0.0889)
		(layer "In2.Cu")
		(net "M_I_CPU1_SA_DQ<16>")
	)
	(segment
		(start 153.511758 -224.443798)
		(end 161.495232 -216.460324)
		(width 0.14478)
		(layer "In2.Cu")
		(net "M_I_CPU1_SA_DQ<16>")
	)
	(segment
		(start 144.711928 -234.296712)
		(end 144.711928 -233.879644)
		(width 0.0889)
		(layer "In2.Cu")
		(net "M_I_CPU1_SA_DQ<16>")
	)
	(segment
		(start 169.776648 -215.61044)
		(end 170.626532 -216.460324)
		(width 0.14478)
		(layer "In2.Cu")
		(net "M_I_CPU1_SA_DQ<16>")
	)
	(arc
		(start 143.547592 -235.086906)
		(mid 143.729843 -235.137256)
		(end 143.913352 -235.091732)
		(width 0.0889)
		(layer "In2.Cu")
		(net "M_I_CPU1_SA_DQ<16>")
	)
	(arc
		(start 130.76174 -235.086906)
		(mid 131.044696 -235.010729)
		(end 131.327652 -235.086906)
		(width 0.0889)
		(layer "In2.Cu")
		(net "M_I_CPU1_SA_DQ<16>")
	)
	(arc
		(start 139.78763 -235.086906)
		(mid 139.969881 -235.137256)
		(end 140.15339 -235.091732)
		(width 0.0889)
		(layer "In2.Cu")
		(net "M_I_CPU1_SA_DQ<16>")
	)
	(arc
		(start 137.916158 -235.091732)
		(mid 138.099666 -235.137226)
		(end 138.281918 -235.086906)
		(width 0.0889)
		(layer "In2.Cu")
		(net "M_I_CPU1_SA_DQ<16>")
	)
	(arc
		(start 141.67612 -235.091732)
		(mid 141.859628 -235.137226)
		(end 142.04188 -235.086906)
		(width 0.0889)
		(layer "In2.Cu")
		(net "M_I_CPU1_SA_DQ<16>")
	)
	(arc
		(start 140.161772 -235.086906)
		(mid 140.444728 -235.010729)
		(end 140.727684 -235.086906)
		(width 0.0889)
		(layer "In2.Cu")
		(net "M_I_CPU1_SA_DQ<16>")
	)
	(arc
		(start 137.341864 -235.086906)
		(mid 137.62482 -235.010729)
		(end 137.907776 -235.086906)
		(width 0.0889)
		(layer "In2.Cu")
		(net "M_I_CPU1_SA_DQ<16>")
	)
	(arc
		(start 140.727684 -235.086906)
		(mid 140.909935 -235.137256)
		(end 141.093444 -235.091732)
		(width 0.0889)
		(layer "In2.Cu")
		(net "M_I_CPU1_SA_DQ<16>")
	)
	(arc
		(start 136.976104 -235.091732)
		(mid 137.159612 -235.137226)
		(end 137.341864 -235.086906)
		(width 0.0889)
		(layer "In2.Cu")
		(net "M_I_CPU1_SA_DQ<16>")
	)
	(arc
		(start 142.04188 -235.086906)
		(mid 142.324836 -235.010729)
		(end 142.607792 -235.086906)
		(width 0.0889)
		(layer "In2.Cu")
		(net "M_I_CPU1_SA_DQ<16>")
	)
	(arc
		(start 130.387598 -235.086906)
		(mid 130.569849 -235.137256)
		(end 130.753358 -235.091732)
		(width 0.0889)
		(layer "In2.Cu")
		(net "M_I_CPU1_SA_DQ<16>")
	)
	(arc
		(start 132.641848 -235.086906)
		(mid 132.924804 -235.010729)
		(end 133.20776 -235.086906)
		(width 0.0889)
		(layer "In2.Cu")
		(net "M_I_CPU1_SA_DQ<16>")
	)
	(arc
		(start 138.84783 -235.086906)
		(mid 139.034774 -235.137161)
		(end 139.221718 -235.086906)
		(width 0.0889)
		(layer "In2.Cu")
		(net "M_I_CPU1_SA_DQ<16>")
	)
	(arc
		(start 129.50317 -235.113068)
		(mid 129.665359 -235.135803)
		(end 129.821686 -235.086906)
		(width 0.0889)
		(layer "In2.Cu")
		(net "M_I_CPU1_SA_DQ<16>")
	)
	(arc
		(start 131.701794 -235.086906)
		(mid 131.98475 -235.010729)
		(end 132.267706 -235.086906)
		(width 0.0889)
		(layer "In2.Cu")
		(net "M_I_CPU1_SA_DQ<16>")
	)
	(arc
		(start 136.027668 -235.086906)
		(mid 136.209919 -235.137256)
		(end 136.393428 -235.091732)
		(width 0.0889)
		(layer "In2.Cu")
		(net "M_I_CPU1_SA_DQ<16>")
	)
	(arc
		(start 133.216142 -235.091732)
		(mid 133.39965 -235.137226)
		(end 133.581902 -235.086906)
		(width 0.0889)
		(layer "In2.Cu")
		(net "M_I_CPU1_SA_DQ<16>")
	)
	(arc
		(start 141.101826 -235.086906)
		(mid 141.384782 -235.010729)
		(end 141.667738 -235.086906)
		(width 0.0889)
		(layer "In2.Cu")
		(net "M_I_CPU1_SA_DQ<16>")
	)
	(arc
		(start 136.40181 -235.086906)
		(mid 136.684766 -235.010729)
		(end 136.967722 -235.086906)
		(width 0.0889)
		(layer "In2.Cu")
		(net "M_I_CPU1_SA_DQ<16>")
	)
	(arc
		(start 138.281918 -235.086906)
		(mid 138.564874 -235.010729)
		(end 138.84783 -235.086906)
		(width 0.0889)
		(layer "In2.Cu")
		(net "M_I_CPU1_SA_DQ<16>")
	)
	(arc
		(start 142.98168 -235.086906)
		(mid 143.264636 -235.010729)
		(end 143.547592 -235.086906)
		(width 0.0889)
		(layer "In2.Cu")
		(net "M_I_CPU1_SA_DQ<16>")
	)
	(arc
		(start 129.821686 -235.086906)
		(mid 130.104642 -235.010729)
		(end 130.387598 -235.086906)
		(width 0.0889)
		(layer "In2.Cu")
		(net "M_I_CPU1_SA_DQ<16>")
	)
	(arc
		(start 131.327652 -235.086906)
		(mid 131.509903 -235.137256)
		(end 131.693412 -235.091732)
		(width 0.0889)
		(layer "In2.Cu")
		(net "M_I_CPU1_SA_DQ<16>")
	)
	(arc
		(start 142.607792 -235.086906)
		(mid 142.794736 -235.137161)
		(end 142.98168 -235.086906)
		(width 0.0889)
		(layer "In2.Cu")
		(net "M_I_CPU1_SA_DQ<16>")
	)
	(arc
		(start 134.521702 -235.086906)
		(mid 134.804658 -235.010729)
		(end 135.087614 -235.086906)
		(width 0.0889)
		(layer "In2.Cu")
		(net "M_I_CPU1_SA_DQ<16>")
	)
	(arc
		(start 139.221718 -235.086906)
		(mid 139.504674 -235.010729)
		(end 139.78763 -235.086906)
		(width 0.0889)
		(layer "In2.Cu")
		(net "M_I_CPU1_SA_DQ<16>")
	)
	(arc
		(start 135.087614 -235.086906)
		(mid 135.269865 -235.137256)
		(end 135.453374 -235.091732)
		(width 0.0889)
		(layer "In2.Cu")
		(net "M_I_CPU1_SA_DQ<16>")
	)
	(arc
		(start 134.147814 -235.086906)
		(mid 134.334758 -235.137161)
		(end 134.521702 -235.086906)
		(width 0.0889)
		(layer "In2.Cu")
		(net "M_I_CPU1_SA_DQ<16>")
	)
	(arc
		(start 135.461756 -235.086906)
		(mid 135.744712 -235.010729)
		(end 136.027668 -235.086906)
		(width 0.0889)
		(layer "In2.Cu")
		(net "M_I_CPU1_SA_DQ<16>")
	)
	(arc
		(start 132.276088 -235.091732)
		(mid 132.459596 -235.137226)
		(end 132.641848 -235.086906)
		(width 0.0889)
		(layer "In2.Cu")
		(net "M_I_CPU1_SA_DQ<16>")
	)
	(arc
		(start 133.581902 -235.086906)
		(mid 133.864858 -235.010729)
		(end 134.147814 -235.086906)
		(width 0.0889)
		(layer "In2.Cu")
		(net "M_I_CPU1_SA_DQ<16>")
	)
	(segment
		(start 127.287782 -235.030264)
		(end 127.754634 -234.764326)
		(width 0.10668)
		(layer "F.Cu")
		(net "M_I_CPU1_SA_DQ<15>")
	)
	(segment
		(start 152.960578 -225.208592)
		(end 152.960578 -224.215452)
		(width 0.14478)
		(layer "In2.Cu")
		(net "M_I_CPU1_SA_DQ<15>")
	)
	(segment
		(start 146.866356 -230.837486)
		(end 147.331684 -230.837486)
		(width 0.0889)
		(layer "In2.Cu")
		(net "M_I_CPU1_SA_DQ<15>")
	)
	(segment
		(start 161.56559 -215.61044)
		(end 166.065454 -215.61044)
		(width 0.14478)
		(layer "In2.Cu")
		(net "M_I_CPU1_SA_DQ<15>")
	)
	(segment
		(start 157.141418 -219.343986)
		(end 157.30347 -219.181934)
		(width 0.14478)
		(layer "In2.Cu")
		(net "M_I_CPU1_SA_DQ<15>")
	)
	(segment
		(start 158.864046 -217.621358)
		(end 159.092138 -217.621358)
		(width 0.14478)
		(layer "In2.Cu")
		(net "M_I_CPU1_SA_DQ<15>")
	)
	(segment
		(start 155.580842 -220.904562)
		(end 155.742894 -220.74251)
		(width 0.14478)
		(layer "In2.Cu")
		(net "M_I_CPU1_SA_DQ<15>")
	)
	(segment
		(start 154.13736 -223.03867)
		(end 154.13736 -222.810324)
		(width 0.14478)
		(layer "In2.Cu")
		(net "M_I_CPU1_SA_DQ<15>")
	)
	(segment
		(start 153.630122 -223.083374)
		(end 153.747216 -223.200722)
		(width 0.14478)
		(layer "In2.Cu")
		(net "M_I_CPU1_SA_DQ<15>")
	)
	(segment
		(start 145.823686 -231.880156)
		(end 146.866356 -230.837486)
		(width 0.0889)
		(layer "In2.Cu")
		(net "M_I_CPU1_SA_DQ<15>")
	)
	(segment
		(start 154.182318 -222.303086)
		(end 154.41041 -222.303086)
		(width 0.14478)
		(layer "In2.Cu")
		(net "M_I_CPU1_SA_DQ<15>")
	)
	(segment
		(start 130.753358 -234.43692)
		(end 130.76174 -234.441746)
		(width 0.0889)
		(layer "In2.Cu")
		(net "M_I_CPU1_SA_DQ<15>")
	)
	(segment
		(start 135.453374 -234.43692)
		(end 135.461756 -234.441746)
		(width 0.0889)
		(layer "In2.Cu")
		(net "M_I_CPU1_SA_DQ<15>")
	)
	(segment
		(start 154.020266 -222.465138)
		(end 154.182318 -222.303086)
		(width 0.14478)
		(layer "In2.Cu")
		(net "M_I_CPU1_SA_DQ<15>")
	)
	(segment
		(start 153.357072 -223.590612)
		(end 153.239978 -223.473518)
		(width 0.14478)
		(layer "In2.Cu")
		(net "M_I_CPU1_SA_DQ<15>")
	)
	(segment
		(start 156.523182 -219.962222)
		(end 156.751274 -219.962222)
		(width 0.14478)
		(layer "In2.Cu")
		(net "M_I_CPU1_SA_DQ<15>")
	)
	(segment
		(start 160.217612 -216.958418)
		(end 160.379664 -216.796366)
		(width 0.14478)
		(layer "In2.Cu")
		(net "M_I_CPU1_SA_DQ<15>")
	)
	(segment
		(start 156.36113 -220.124274)
		(end 156.523182 -219.962222)
		(width 0.14478)
		(layer "In2.Cu")
		(net "M_I_CPU1_SA_DQ<15>")
	)
	(segment
		(start 156.36113 -220.352366)
		(end 156.36113 -220.124274)
		(width 0.14478)
		(layer "In2.Cu")
		(net "M_I_CPU1_SA_DQ<15>")
	)
	(segment
		(start 141.093444 -234.43692)
		(end 141.101826 -234.441746)
		(width 0.0889)
		(layer "In2.Cu")
		(net "M_I_CPU1_SA_DQ<15>")
	)
	(segment
		(start 158.819088 -218.128596)
		(end 158.701994 -218.011502)
		(width 0.14478)
		(layer "In2.Cu")
		(net "M_I_CPU1_SA_DQ<15>")
	)
	(segment
		(start 156.478224 -220.697806)
		(end 156.478224 -220.46946)
		(width 0.14478)
		(layer "In2.Cu")
		(net "M_I_CPU1_SA_DQ<15>")
	)
	(segment
		(start 157.258512 -219.689172)
		(end 157.141418 -219.572078)
		(width 0.14478)
		(layer "In2.Cu")
		(net "M_I_CPU1_SA_DQ<15>")
	)
	(segment
		(start 169.760646 -214.760302)
		(end 170.610784 -215.61044)
		(width 0.14478)
		(layer "In2.Cu")
		(net "M_I_CPU1_SA_DQ<15>")
	)
	(segment
		(start 157.30347 -219.181934)
		(end 157.531562 -219.181934)
		(width 0.14478)
		(layer "In2.Cu")
		(net "M_I_CPU1_SA_DQ<15>")
	)
	(segment
		(start 159.482282 -217.231214)
		(end 159.482282 -217.003122)
		(width 0.14478)
		(layer "In2.Cu")
		(net "M_I_CPU1_SA_DQ<15>")
	)
	(segment
		(start 153.747216 -223.200722)
		(end 153.975308 -223.200722)
		(width 0.14478)
		(layer "In2.Cu")
		(net "M_I_CPU1_SA_DQ<15>")
	)
	(segment
		(start 153.239978 -223.473518)
		(end 153.239978 -223.245426)
		(width 0.14478)
		(layer "In2.Cu")
		(net "M_I_CPU1_SA_DQ<15>")
	)
	(segment
		(start 156.478224 -220.46946)
		(end 156.36113 -220.352366)
		(width 0.14478)
		(layer "In2.Cu")
		(net "M_I_CPU1_SA_DQ<15>")
	)
	(segment
		(start 145.823686 -232.465626)
		(end 145.823686 -231.880156)
		(width 0.0889)
		(layer "In2.Cu")
		(net "M_I_CPU1_SA_DQ<15>")
	)
	(segment
		(start 154.755596 -222.420434)
		(end 154.917648 -222.258382)
		(width 0.14478)
		(layer "In2.Cu")
		(net "M_I_CPU1_SA_DQ<15>")
	)
	(segment
		(start 136.967722 -234.441746)
		(end 136.976104 -234.43692)
		(width 0.0889)
		(layer "In2.Cu")
		(net "M_I_CPU1_SA_DQ<15>")
	)
	(segment
		(start 166.915592 -214.760302)
		(end 169.760646 -214.760302)
		(width 0.14478)
		(layer "In2.Cu")
		(net "M_I_CPU1_SA_DQ<15>")
	)
	(segment
		(start 159.437324 -217.738706)
		(end 159.599376 -217.576654)
		(width 0.14478)
		(layer "In2.Cu")
		(net "M_I_CPU1_SA_DQ<15>")
	)
	(segment
		(start 157.921706 -218.563698)
		(end 158.083758 -218.401646)
		(width 0.14478)
		(layer "In2.Cu")
		(net "M_I_CPU1_SA_DQ<15>")
	)
	(segment
		(start 155.697936 -221.478094)
		(end 155.697936 -221.249748)
		(width 0.14478)
		(layer "In2.Cu")
		(net "M_I_CPU1_SA_DQ<15>")
	)
	(segment
		(start 166.065454 -215.61044)
		(end 166.915592 -214.760302)
		(width 0.14478)
		(layer "In2.Cu")
		(net "M_I_CPU1_SA_DQ<15>")
	)
	(segment
		(start 155.307792 -221.640146)
		(end 155.535884 -221.640146)
		(width 0.14478)
		(layer "In2.Cu")
		(net "M_I_CPU1_SA_DQ<15>")
	)
	(segment
		(start 156.316172 -220.859858)
		(end 156.478224 -220.697806)
		(width 0.14478)
		(layer "In2.Cu")
		(net "M_I_CPU1_SA_DQ<15>")
	)
	(segment
		(start 127.754634 -234.764326)
		(end 127.908812 -234.498896)
		(width 0.0889)
		(layer "In2.Cu")
		(net "M_I_CPU1_SA_DQ<15>")
	)
	(segment
		(start 153.975308 -223.200722)
		(end 154.13736 -223.03867)
		(width 0.14478)
		(layer "In2.Cu")
		(net "M_I_CPU1_SA_DQ<15>")
	)
	(segment
		(start 140.15339 -234.43692)
		(end 140.161772 -234.441746)
		(width 0.0889)
		(layer "In2.Cu")
		(net "M_I_CPU1_SA_DQ<15>")
	)
	(segment
		(start 159.482282 -217.003122)
		(end 159.644334 -216.84107)
		(width 0.14478)
		(layer "In2.Cu")
		(net "M_I_CPU1_SA_DQ<15>")
	)
	(segment
		(start 158.0388 -219.13723)
		(end 158.0388 -218.908884)
		(width 0.14478)
		(layer "In2.Cu")
		(net "M_I_CPU1_SA_DQ<15>")
	)
	(segment
		(start 154.13736 -222.810324)
		(end 154.020266 -222.69323)
		(width 0.14478)
		(layer "In2.Cu")
		(net "M_I_CPU1_SA_DQ<15>")
	)
	(segment
		(start 154.962606 -221.522798)
		(end 155.190698 -221.522798)
		(width 0.14478)
		(layer "In2.Cu")
		(net "M_I_CPU1_SA_DQ<15>")
	)
	(segment
		(start 154.800554 -221.68485)
		(end 154.962606 -221.522798)
		(width 0.14478)
		(layer "In2.Cu")
		(net "M_I_CPU1_SA_DQ<15>")
	)
	(segment
		(start 144.043146 -234.246166)
		(end 145.823686 -232.465626)
		(width 0.0889)
		(layer "In2.Cu")
		(net "M_I_CPU1_SA_DQ<15>")
	)
	(segment
		(start 158.31185 -218.401646)
		(end 158.428944 -218.518994)
		(width 0.14478)
		(layer "In2.Cu")
		(net "M_I_CPU1_SA_DQ<15>")
	)
	(segment
		(start 170.610784 -215.61044)
		(end 173.66234 -215.61044)
		(width 0.14478)
		(layer "In2.Cu")
		(net "M_I_CPU1_SA_DQ<15>")
	)
	(segment
		(start 154.800554 -221.912942)
		(end 154.800554 -221.68485)
		(width 0.14478)
		(layer "In2.Cu")
		(net "M_I_CPU1_SA_DQ<15>")
	)
	(segment
		(start 132.267706 -234.441746)
		(end 132.276088 -234.43692)
		(width 0.0889)
		(layer "In2.Cu")
		(net "M_I_CPU1_SA_DQ<15>")
	)
	(segment
		(start 154.527504 -222.420434)
		(end 154.755596 -222.420434)
		(width 0.14478)
		(layer "In2.Cu")
		(net "M_I_CPU1_SA_DQ<15>")
	)
	(segment
		(start 153.40203 -223.083374)
		(end 153.630122 -223.083374)
		(width 0.14478)
		(layer "In2.Cu")
		(net "M_I_CPU1_SA_DQ<15>")
	)
	(segment
		(start 158.701994 -217.78341)
		(end 158.864046 -217.621358)
		(width 0.14478)
		(layer "In2.Cu")
		(net "M_I_CPU1_SA_DQ<15>")
	)
	(segment
		(start 155.697936 -221.249748)
		(end 155.580842 -221.132654)
		(width 0.14478)
		(layer "In2.Cu")
		(net "M_I_CPU1_SA_DQ<15>")
	)
	(segment
		(start 153.239978 -223.245426)
		(end 153.40203 -223.083374)
		(width 0.14478)
		(layer "In2.Cu")
		(net "M_I_CPU1_SA_DQ<15>")
	)
	(segment
		(start 153.357072 -223.818958)
		(end 153.357072 -223.590612)
		(width 0.14478)
		(layer "In2.Cu")
		(net "M_I_CPU1_SA_DQ<15>")
	)
	(segment
		(start 157.648656 -219.299282)
		(end 157.876748 -219.299282)
		(width 0.14478)
		(layer "In2.Cu")
		(net "M_I_CPU1_SA_DQ<15>")
	)
	(segment
		(start 141.667738 -234.441746)
		(end 141.67612 -234.43692)
		(width 0.0889)
		(layer "In2.Cu")
		(net "M_I_CPU1_SA_DQ<15>")
	)
	(segment
		(start 159.599376 -217.348308)
		(end 159.482282 -217.231214)
		(width 0.14478)
		(layer "In2.Cu")
		(net "M_I_CPU1_SA_DQ<15>")
	)
	(segment
		(start 154.917648 -222.030036)
		(end 154.800554 -221.912942)
		(width 0.14478)
		(layer "In2.Cu")
		(net "M_I_CPU1_SA_DQ<15>")
	)
	(segment
		(start 173.66234 -215.61044)
		(end 174.512478 -214.760302)
		(width 0.14478)
		(layer "In2.Cu")
		(net "M_I_CPU1_SA_DQ<15>")
	)
	(segment
		(start 155.190698 -221.522798)
		(end 155.307792 -221.640146)
		(width 0.14478)
		(layer "In2.Cu")
		(net "M_I_CPU1_SA_DQ<15>")
	)
	(segment
		(start 160.26257 -216.450926)
		(end 160.26257 -216.222834)
		(width 0.14478)
		(layer "In2.Cu")
		(net "M_I_CPU1_SA_DQ<15>")
	)
	(segment
		(start 159.092138 -217.621358)
		(end 159.209232 -217.738706)
		(width 0.14478)
		(layer "In2.Cu")
		(net "M_I_CPU1_SA_DQ<15>")
	)
	(segment
		(start 160.379664 -216.56802)
		(end 160.26257 -216.450926)
		(width 0.14478)
		(layer "In2.Cu")
		(net "M_I_CPU1_SA_DQ<15>")
	)
	(segment
		(start 154.020266 -222.69323)
		(end 154.020266 -222.465138)
		(width 0.14478)
		(layer "In2.Cu")
		(net "M_I_CPU1_SA_DQ<15>")
	)
	(segment
		(start 159.599376 -217.576654)
		(end 159.599376 -217.348308)
		(width 0.14478)
		(layer "In2.Cu")
		(net "M_I_CPU1_SA_DQ<15>")
	)
	(segment
		(start 160.26257 -216.222834)
		(end 160.424622 -216.060782)
		(width 0.14478)
		(layer "In2.Cu")
		(net "M_I_CPU1_SA_DQ<15>")
	)
	(segment
		(start 155.580842 -221.132654)
		(end 155.580842 -220.904562)
		(width 0.14478)
		(layer "In2.Cu")
		(net "M_I_CPU1_SA_DQ<15>")
	)
	(segment
		(start 159.98952 -216.958418)
		(end 160.217612 -216.958418)
		(width 0.14478)
		(layer "In2.Cu")
		(net "M_I_CPU1_SA_DQ<15>")
	)
	(segment
		(start 131.693412 -234.43692)
		(end 131.701794 -234.441746)
		(width 0.0889)
		(layer "In2.Cu")
		(net "M_I_CPU1_SA_DQ<15>")
	)
	(segment
		(start 159.872426 -216.84107)
		(end 159.98952 -216.958418)
		(width 0.14478)
		(layer "In2.Cu")
		(net "M_I_CPU1_SA_DQ<15>")
	)
	(segment
		(start 155.535884 -221.640146)
		(end 155.697936 -221.478094)
		(width 0.14478)
		(layer "In2.Cu")
		(net "M_I_CPU1_SA_DQ<15>")
	)
	(segment
		(start 137.907776 -234.441746)
		(end 137.916158 -234.43692)
		(width 0.0889)
		(layer "In2.Cu")
		(net "M_I_CPU1_SA_DQ<15>")
	)
	(segment
		(start 136.393428 -234.43692)
		(end 136.40181 -234.441746)
		(width 0.0889)
		(layer "In2.Cu")
		(net "M_I_CPU1_SA_DQ<15>")
	)
	(segment
		(start 157.258512 -219.917518)
		(end 157.258512 -219.689172)
		(width 0.14478)
		(layer "In2.Cu")
		(net "M_I_CPU1_SA_DQ<15>")
	)
	(segment
		(start 158.819088 -218.356942)
		(end 158.819088 -218.128596)
		(width 0.14478)
		(layer "In2.Cu")
		(net "M_I_CPU1_SA_DQ<15>")
	)
	(segment
		(start 160.769808 -216.17813)
		(end 160.9979 -216.17813)
		(width 0.14478)
		(layer "In2.Cu")
		(net "M_I_CPU1_SA_DQ<15>")
	)
	(segment
		(start 179.091082 -214.760302)
		(end 179.516024 -215.185244)
		(width 0.14478)
		(layer "In2.Cu")
		(net "M_I_CPU1_SA_DQ<15>")
	)
	(segment
		(start 155.970986 -220.74251)
		(end 156.08808 -220.859858)
		(width 0.14478)
		(layer "In2.Cu")
		(net "M_I_CPU1_SA_DQ<15>")
	)
	(segment
		(start 158.428944 -218.518994)
		(end 158.657036 -218.518994)
		(width 0.14478)
		(layer "In2.Cu")
		(net "M_I_CPU1_SA_DQ<15>")
	)
	(segment
		(start 158.0388 -218.908884)
		(end 157.921706 -218.79179)
		(width 0.14478)
		(layer "In2.Cu")
		(net "M_I_CPU1_SA_DQ<15>")
	)
	(segment
		(start 157.876748 -219.299282)
		(end 158.0388 -219.13723)
		(width 0.14478)
		(layer "In2.Cu")
		(net "M_I_CPU1_SA_DQ<15>")
	)
	(segment
		(start 155.742894 -220.74251)
		(end 155.970986 -220.74251)
		(width 0.14478)
		(layer "In2.Cu")
		(net "M_I_CPU1_SA_DQ<15>")
	)
	(segment
		(start 127.908812 -234.498896)
		(end 128.005078 -234.473496)
		(width 0.0889)
		(layer "In2.Cu")
		(net "M_I_CPU1_SA_DQ<15>")
	)
	(segment
		(start 156.08808 -220.859858)
		(end 156.316172 -220.859858)
		(width 0.14478)
		(layer "In2.Cu")
		(net "M_I_CPU1_SA_DQ<15>")
	)
	(segment
		(start 154.41041 -222.303086)
		(end 154.527504 -222.420434)
		(width 0.14478)
		(layer "In2.Cu")
		(net "M_I_CPU1_SA_DQ<15>")
	)
	(segment
		(start 158.083758 -218.401646)
		(end 158.31185 -218.401646)
		(width 0.14478)
		(layer "In2.Cu")
		(net "M_I_CPU1_SA_DQ<15>")
	)
	(segment
		(start 174.512478 -214.760302)
		(end 179.091082 -214.760302)
		(width 0.14478)
		(layer "In2.Cu")
		(net "M_I_CPU1_SA_DQ<15>")
	)
	(segment
		(start 133.20776 -234.441746)
		(end 133.216142 -234.43692)
		(width 0.0889)
		(layer "In2.Cu")
		(net "M_I_CPU1_SA_DQ<15>")
	)
	(segment
		(start 147.331684 -230.837486)
		(end 152.960578 -225.208592)
		(width 0.14478)
		(layer "In2.Cu")
		(net "M_I_CPU1_SA_DQ<15>")
	)
	(segment
		(start 156.868368 -220.07957)
		(end 157.09646 -220.07957)
		(width 0.14478)
		(layer "In2.Cu")
		(net "M_I_CPU1_SA_DQ<15>")
	)
	(segment
		(start 158.701994 -218.011502)
		(end 158.701994 -217.78341)
		(width 0.14478)
		(layer "In2.Cu")
		(net "M_I_CPU1_SA_DQ<15>")
	)
	(segment
		(start 128.507744 -234.441746)
		(end 128.516126 -234.43692)
		(width 0.0889)
		(layer "In2.Cu")
		(net "M_I_CPU1_SA_DQ<15>")
	)
	(segment
		(start 160.652714 -216.060782)
		(end 160.769808 -216.17813)
		(width 0.14478)
		(layer "In2.Cu")
		(net "M_I_CPU1_SA_DQ<15>")
	)
	(segment
		(start 160.379664 -216.796366)
		(end 160.379664 -216.56802)
		(width 0.14478)
		(layer "In2.Cu")
		(net "M_I_CPU1_SA_DQ<15>")
	)
	(segment
		(start 158.657036 -218.518994)
		(end 158.819088 -218.356942)
		(width 0.14478)
		(layer "In2.Cu")
		(net "M_I_CPU1_SA_DQ<15>")
	)
	(segment
		(start 152.960578 -224.215452)
		(end 153.357072 -223.818958)
		(width 0.14478)
		(layer "In2.Cu")
		(net "M_I_CPU1_SA_DQ<15>")
	)
	(segment
		(start 157.09646 -220.07957)
		(end 157.258512 -219.917518)
		(width 0.14478)
		(layer "In2.Cu")
		(net "M_I_CPU1_SA_DQ<15>")
	)
	(segment
		(start 159.644334 -216.84107)
		(end 159.872426 -216.84107)
		(width 0.14478)
		(layer "In2.Cu")
		(net "M_I_CPU1_SA_DQ<15>")
	)
	(segment
		(start 160.424622 -216.060782)
		(end 160.652714 -216.060782)
		(width 0.14478)
		(layer "In2.Cu")
		(net "M_I_CPU1_SA_DQ<15>")
	)
	(segment
		(start 154.917648 -222.258382)
		(end 154.917648 -222.030036)
		(width 0.14478)
		(layer "In2.Cu")
		(net "M_I_CPU1_SA_DQ<15>")
	)
	(segment
		(start 157.141418 -219.572078)
		(end 157.141418 -219.343986)
		(width 0.14478)
		(layer "In2.Cu")
		(net "M_I_CPU1_SA_DQ<15>")
	)
	(segment
		(start 159.209232 -217.738706)
		(end 159.437324 -217.738706)
		(width 0.14478)
		(layer "In2.Cu")
		(net "M_I_CPU1_SA_DQ<15>")
	)
	(segment
		(start 156.751274 -219.962222)
		(end 156.868368 -220.07957)
		(width 0.14478)
		(layer "In2.Cu")
		(net "M_I_CPU1_SA_DQ<15>")
	)
	(segment
		(start 160.9979 -216.17813)
		(end 161.56559 -215.61044)
		(width 0.14478)
		(layer "In2.Cu")
		(net "M_I_CPU1_SA_DQ<15>")
	)
	(segment
		(start 157.921706 -218.79179)
		(end 157.921706 -218.563698)
		(width 0.14478)
		(layer "In2.Cu")
		(net "M_I_CPU1_SA_DQ<15>")
	)
	(segment
		(start 157.531562 -219.181934)
		(end 157.648656 -219.299282)
		(width 0.14478)
		(layer "In2.Cu")
		(net "M_I_CPU1_SA_DQ<15>")
	)
	(arc
		(start 142.98168 -234.441746)
		(mid 143.264636 -234.517923)
		(end 143.547592 -234.441746)
		(width 0.0889)
		(layer "In2.Cu")
		(net "M_I_CPU1_SA_DQ<15>")
	)
	(arc
		(start 142.04188 -234.441746)
		(mid 142.324836 -234.517923)
		(end 142.607792 -234.441746)
		(width 0.0889)
		(layer "In2.Cu")
		(net "M_I_CPU1_SA_DQ<15>")
	)
	(arc
		(start 143.73479 -234.3912)
		(mid 143.90517 -234.353131)
		(end 144.043146 -234.246166)
		(width 0.0889)
		(layer "In2.Cu")
		(net "M_I_CPU1_SA_DQ<15>")
	)
	(arc
		(start 137.341864 -234.441746)
		(mid 137.62482 -234.517923)
		(end 137.907776 -234.441746)
		(width 0.0889)
		(layer "In2.Cu")
		(net "M_I_CPU1_SA_DQ<15>")
	)
	(arc
		(start 129.821686 -234.441746)
		(mid 130.104642 -234.517923)
		(end 130.387598 -234.441746)
		(width 0.0889)
		(layer "In2.Cu")
		(net "M_I_CPU1_SA_DQ<15>")
	)
	(arc
		(start 138.84783 -234.441746)
		(mid 139.034774 -234.391491)
		(end 139.221718 -234.441746)
		(width 0.0889)
		(layer "In2.Cu")
		(net "M_I_CPU1_SA_DQ<15>")
	)
	(arc
		(start 136.027668 -234.441746)
		(mid 136.209919 -234.391396)
		(end 136.393428 -234.43692)
		(width 0.0889)
		(layer "In2.Cu")
		(net "M_I_CPU1_SA_DQ<15>")
	)
	(arc
		(start 128.881886 -234.441746)
		(mid 129.164842 -234.517923)
		(end 129.447798 -234.441746)
		(width 0.0889)
		(layer "In2.Cu")
		(net "M_I_CPU1_SA_DQ<15>")
	)
	(arc
		(start 140.727684 -234.441746)
		(mid 140.909935 -234.391396)
		(end 141.093444 -234.43692)
		(width 0.0889)
		(layer "In2.Cu")
		(net "M_I_CPU1_SA_DQ<15>")
	)
	(arc
		(start 134.521702 -234.441746)
		(mid 134.804658 -234.517923)
		(end 135.087614 -234.441746)
		(width 0.0889)
		(layer "In2.Cu")
		(net "M_I_CPU1_SA_DQ<15>")
	)
	(arc
		(start 139.221718 -234.441746)
		(mid 139.504674 -234.517923)
		(end 139.78763 -234.441746)
		(width 0.0889)
		(layer "In2.Cu")
		(net "M_I_CPU1_SA_DQ<15>")
	)
	(arc
		(start 131.701794 -234.441746)
		(mid 131.98475 -234.517923)
		(end 132.267706 -234.441746)
		(width 0.0889)
		(layer "In2.Cu")
		(net "M_I_CPU1_SA_DQ<15>")
	)
	(arc
		(start 130.76174 -234.441746)
		(mid 131.044696 -234.517923)
		(end 131.327652 -234.441746)
		(width 0.0889)
		(layer "In2.Cu")
		(net "M_I_CPU1_SA_DQ<15>")
	)
	(arc
		(start 130.387598 -234.441746)
		(mid 130.569849 -234.391396)
		(end 130.753358 -234.43692)
		(width 0.0889)
		(layer "In2.Cu")
		(net "M_I_CPU1_SA_DQ<15>")
	)
	(arc
		(start 133.216142 -234.43692)
		(mid 133.39965 -234.391426)
		(end 133.581902 -234.441746)
		(width 0.0889)
		(layer "In2.Cu")
		(net "M_I_CPU1_SA_DQ<15>")
	)
	(arc
		(start 136.40181 -234.441746)
		(mid 136.684766 -234.517923)
		(end 136.967722 -234.441746)
		(width 0.0889)
		(layer "In2.Cu")
		(net "M_I_CPU1_SA_DQ<15>")
	)
	(arc
		(start 135.087614 -234.441746)
		(mid 135.269865 -234.391396)
		(end 135.453374 -234.43692)
		(width 0.0889)
		(layer "In2.Cu")
		(net "M_I_CPU1_SA_DQ<15>")
	)
	(arc
		(start 139.78763 -234.441746)
		(mid 139.969881 -234.391396)
		(end 140.15339 -234.43692)
		(width 0.0889)
		(layer "In2.Cu")
		(net "M_I_CPU1_SA_DQ<15>")
	)
	(arc
		(start 141.67612 -234.43692)
		(mid 141.859628 -234.391426)
		(end 142.04188 -234.441746)
		(width 0.0889)
		(layer "In2.Cu")
		(net "M_I_CPU1_SA_DQ<15>")
	)
	(arc
		(start 136.976104 -234.43692)
		(mid 137.159612 -234.391426)
		(end 137.341864 -234.441746)
		(width 0.0889)
		(layer "In2.Cu")
		(net "M_I_CPU1_SA_DQ<15>")
	)
	(arc
		(start 135.461756 -234.441746)
		(mid 135.744712 -234.517923)
		(end 136.027668 -234.441746)
		(width 0.0889)
		(layer "In2.Cu")
		(net "M_I_CPU1_SA_DQ<15>")
	)
	(arc
		(start 132.641848 -234.441746)
		(mid 132.924804 -234.517923)
		(end 133.20776 -234.441746)
		(width 0.0889)
		(layer "In2.Cu")
		(net "M_I_CPU1_SA_DQ<15>")
	)
	(arc
		(start 133.581902 -234.441746)
		(mid 133.864858 -234.517923)
		(end 134.147814 -234.441746)
		(width 0.0889)
		(layer "In2.Cu")
		(net "M_I_CPU1_SA_DQ<15>")
	)
	(arc
		(start 129.447798 -234.441746)
		(mid 129.634742 -234.391491)
		(end 129.821686 -234.441746)
		(width 0.0889)
		(layer "In2.Cu")
		(net "M_I_CPU1_SA_DQ<15>")
	)
	(arc
		(start 143.547592 -234.441746)
		(mid 143.637852 -234.404118)
		(end 143.73479 -234.3912)
		(width 0.0889)
		(layer "In2.Cu")
		(net "M_I_CPU1_SA_DQ<15>")
	)
	(arc
		(start 141.101826 -234.441746)
		(mid 141.384782 -234.517923)
		(end 141.667738 -234.441746)
		(width 0.0889)
		(layer "In2.Cu")
		(net "M_I_CPU1_SA_DQ<15>")
	)
	(arc
		(start 142.607792 -234.441746)
		(mid 142.794736 -234.391491)
		(end 142.98168 -234.441746)
		(width 0.0889)
		(layer "In2.Cu")
		(net "M_I_CPU1_SA_DQ<15>")
	)
	(arc
		(start 140.161772 -234.441746)
		(mid 140.444728 -234.517923)
		(end 140.727684 -234.441746)
		(width 0.0889)
		(layer "In2.Cu")
		(net "M_I_CPU1_SA_DQ<15>")
	)
	(arc
		(start 131.327652 -234.441746)
		(mid 131.509903 -234.391396)
		(end 131.693412 -234.43692)
		(width 0.0889)
		(layer "In2.Cu")
		(net "M_I_CPU1_SA_DQ<15>")
	)
	(arc
		(start 134.147814 -234.441746)
		(mid 134.334758 -234.391491)
		(end 134.521702 -234.441746)
		(width 0.0889)
		(layer "In2.Cu")
		(net "M_I_CPU1_SA_DQ<15>")
	)
	(arc
		(start 128.516126 -234.43692)
		(mid 128.699634 -234.391426)
		(end 128.881886 -234.441746)
		(width 0.0889)
		(layer "In2.Cu")
		(net "M_I_CPU1_SA_DQ<15>")
	)
	(arc
		(start 132.276088 -234.43692)
		(mid 132.459596 -234.391426)
		(end 132.641848 -234.441746)
		(width 0.0889)
		(layer "In2.Cu")
		(net "M_I_CPU1_SA_DQ<15>")
	)
	(arc
		(start 137.916158 -234.43692)
		(mid 138.099666 -234.391426)
		(end 138.281918 -234.441746)
		(width 0.0889)
		(layer "In2.Cu")
		(net "M_I_CPU1_SA_DQ<15>")
	)
	(arc
		(start 138.281918 -234.441746)
		(mid 138.564874 -234.517923)
		(end 138.84783 -234.441746)
		(width 0.0889)
		(layer "In2.Cu")
		(net "M_I_CPU1_SA_DQ<15>")
	)
	(arc
		(start 128.005078 -234.473496)
		(mid 128.260143 -234.516847)
		(end 128.507744 -234.441746)
		(width 0.0889)
		(layer "In2.Cu")
		(net "M_I_CPU1_SA_DQ<15>")
	)
	(segment
		(start 128.69799 -234.220258)
		(end 129.164842 -233.95432)
		(width 0.10668)
		(layer "F.Cu")
		(net "M_I_CPU1_SA_DQ<14>")
	)
	(segment
		(start 148.589492 -227.946458)
		(end 148.817584 -227.946458)
		(width 0.14478)
		(layer "In2.Cu")
		(net "M_I_CPU1_SA_DQ<14>")
	)
	(segment
		(start 138.743436 -233.626914)
		(end 138.751818 -233.63174)
		(width 0.0889)
		(layer "In2.Cu")
		(net "M_I_CPU1_SA_DQ<14>")
	)
	(segment
		(start 148.199348 -228.336602)
		(end 147.994878 -228.131878)
		(width 0.14478)
		(layer "In2.Cu")
		(net "M_I_CPU1_SA_DQ<14>")
	)
	(segment
		(start 150.150068 -226.385882)
		(end 150.37816 -226.385882)
		(width 0.14478)
		(layer "In2.Cu")
		(net "M_I_CPU1_SA_DQ<14>")
	)
	(segment
		(start 147.34667 -229.417372)
		(end 148.199348 -228.564694)
		(width 0.14478)
		(layer "In2.Cu")
		(net "M_I_CPU1_SA_DQ<14>")
	)
	(segment
		(start 151.938736 -224.825306)
		(end 152.061418 -224.702624)
		(width 0.14478)
		(layer "In2.Cu")
		(net "M_I_CPU1_SA_DQ<14>")
	)
	(segment
		(start 151.3205 -225.443542)
		(end 151.3205 -225.21545)
		(width 0.14478)
		(layer "In2.Cu")
		(net "M_I_CPU1_SA_DQ<14>")
	)
	(segment
		(start 149.36978 -227.16617)
		(end 149.597872 -227.16617)
		(width 0.14478)
		(layer "In2.Cu")
		(net "M_I_CPU1_SA_DQ<14>")
	)
	(segment
		(start 149.555454 -226.571302)
		(end 149.555454 -226.34321)
		(width 0.14478)
		(layer "In2.Cu")
		(net "M_I_CPU1_SA_DQ<14>")
	)
	(segment
		(start 148.817584 -227.946458)
		(end 148.979636 -227.784406)
		(width 0.14478)
		(layer "In2.Cu")
		(net "M_I_CPU1_SA_DQ<14>")
	)
	(segment
		(start 147.994878 -228.131878)
		(end 147.994878 -227.903786)
		(width 0.14478)
		(layer "In2.Cu")
		(net "M_I_CPU1_SA_DQ<14>")
	)
	(segment
		(start 150.37816 -226.385882)
		(end 150.540212 -226.22383)
		(width 0.14478)
		(layer "In2.Cu")
		(net "M_I_CPU1_SA_DQ<14>")
	)
	(segment
		(start 149.759924 -226.776026)
		(end 149.555454 -226.571302)
		(width 0.14478)
		(layer "In2.Cu")
		(net "M_I_CPU1_SA_DQ<14>")
	)
	(segment
		(start 169.588688 -213.06028)
		(end 170.438826 -213.910418)
		(width 0.14478)
		(layer "In2.Cu")
		(net "M_I_CPU1_SA_DQ<14>")
	)
	(segment
		(start 148.979636 -227.556314)
		(end 148.775166 -227.35159)
		(width 0.14478)
		(layer "In2.Cu")
		(net "M_I_CPU1_SA_DQ<14>")
	)
	(segment
		(start 167.077898 -213.06028)
		(end 169.588688 -213.06028)
		(width 0.14478)
		(layer "In2.Cu")
		(net "M_I_CPU1_SA_DQ<14>")
	)
	(segment
		(start 129.164842 -233.95432)
		(end 129.318766 -233.68889)
		(width 0.0889)
		(layer "In2.Cu")
		(net "M_I_CPU1_SA_DQ<14>")
	)
	(segment
		(start 150.540212 -226.22383)
		(end 150.540212 -225.995738)
		(width 0.14478)
		(layer "In2.Cu")
		(net "M_I_CPU1_SA_DQ<14>")
	)
	(segment
		(start 145.703544 -231.040686)
		(end 145.703544 -230.515414)
		(width 0.0889)
		(layer "In2.Cu")
		(net "M_I_CPU1_SA_DQ<14>")
	)
	(segment
		(start 173.496732 -213.910418)
		(end 174.34687 -213.06028)
		(width 0.14478)
		(layer "In2.Cu")
		(net "M_I_CPU1_SA_DQ<14>")
	)
	(segment
		(start 150.930356 -225.605594)
		(end 151.158448 -225.605594)
		(width 0.14478)
		(layer "In2.Cu")
		(net "M_I_CPU1_SA_DQ<14>")
	)
	(segment
		(start 179.091082 -213.06028)
		(end 179.516024 -213.485222)
		(width 0.14478)
		(layer "In2.Cu")
		(net "M_I_CPU1_SA_DQ<14>")
	)
	(segment
		(start 149.945598 -226.181158)
		(end 150.150068 -226.385882)
		(width 0.14478)
		(layer "In2.Cu")
		(net "M_I_CPU1_SA_DQ<14>")
	)
	(segment
		(start 170.438826 -213.910418)
		(end 173.496732 -213.910418)
		(width 0.14478)
		(layer "In2.Cu")
		(net "M_I_CPU1_SA_DQ<14>")
	)
	(segment
		(start 174.34687 -213.06028)
		(end 179.091082 -213.06028)
		(width 0.14478)
		(layer "In2.Cu")
		(net "M_I_CPU1_SA_DQ<14>")
	)
	(segment
		(start 134.04342 -233.626914)
		(end 134.051802 -233.63174)
		(width 0.0889)
		(layer "In2.Cu")
		(net "M_I_CPU1_SA_DQ<14>")
	)
	(segment
		(start 147.120356 -229.643686)
		(end 147.34667 -229.417372)
		(width 0.0889)
		(layer "In2.Cu")
		(net "M_I_CPU1_SA_DQ<14>")
	)
	(segment
		(start 150.540212 -225.995738)
		(end 149.996652 -225.451416)
		(width 0.14478)
		(layer "In2.Cu")
		(net "M_I_CPU1_SA_DQ<14>")
	)
	(segment
		(start 152.061418 -223.1517)
		(end 161.3027 -213.910418)
		(width 0.14478)
		(layer "In2.Cu")
		(net "M_I_CPU1_SA_DQ<14>")
	)
	(segment
		(start 150.158704 -225.061272)
		(end 150.386796 -225.061272)
		(width 0.14478)
		(layer "In2.Cu")
		(net "M_I_CPU1_SA_DQ<14>")
	)
	(segment
		(start 149.996652 -225.451416)
		(end 149.996652 -225.223324)
		(width 0.14478)
		(layer "In2.Cu")
		(net "M_I_CPU1_SA_DQ<14>")
	)
	(segment
		(start 148.775166 -227.35159)
		(end 148.775166 -227.123498)
		(width 0.14478)
		(layer "In2.Cu")
		(net "M_I_CPU1_SA_DQ<14>")
	)
	(segment
		(start 148.385022 -227.741734)
		(end 148.589492 -227.946458)
		(width 0.14478)
		(layer "In2.Cu")
		(net "M_I_CPU1_SA_DQ<14>")
	)
	(segment
		(start 147.994878 -227.903786)
		(end 148.15693 -227.741734)
		(width 0.14478)
		(layer "In2.Cu")
		(net "M_I_CPU1_SA_DQ<14>")
	)
	(segment
		(start 149.597872 -227.16617)
		(end 149.759924 -227.004118)
		(width 0.14478)
		(layer "In2.Cu")
		(net "M_I_CPU1_SA_DQ<14>")
	)
	(segment
		(start 144.777206 -232.914698)
		(end 144.777206 -231.967024)
		(width 0.0889)
		(layer "In2.Cu")
		(net "M_I_CPU1_SA_DQ<14>")
	)
	(segment
		(start 149.759924 -227.004118)
		(end 149.759924 -226.776026)
		(width 0.14478)
		(layer "In2.Cu")
		(net "M_I_CPU1_SA_DQ<14>")
	)
	(segment
		(start 149.16531 -226.961446)
		(end 149.36978 -227.16617)
		(width 0.14478)
		(layer "In2.Cu")
		(net "M_I_CPU1_SA_DQ<14>")
	)
	(segment
		(start 140.257784 -233.63174)
		(end 140.266166 -233.626914)
		(width 0.0889)
		(layer "In2.Cu")
		(net "M_I_CPU1_SA_DQ<14>")
	)
	(segment
		(start 166.22776 -213.910418)
		(end 167.077898 -213.06028)
		(width 0.14478)
		(layer "In2.Cu")
		(net "M_I_CPU1_SA_DQ<14>")
	)
	(segment
		(start 151.3205 -225.21545)
		(end 150.79345 -224.687638)
		(width 0.14478)
		(layer "In2.Cu")
		(net "M_I_CPU1_SA_DQ<14>")
	)
	(segment
		(start 150.955502 -224.297494)
		(end 151.183594 -224.297494)
		(width 0.14478)
		(layer "In2.Cu")
		(net "M_I_CPU1_SA_DQ<14>")
	)
	(segment
		(start 149.555454 -226.34321)
		(end 149.717506 -226.181158)
		(width 0.14478)
		(layer "In2.Cu")
		(net "M_I_CPU1_SA_DQ<14>")
	)
	(segment
		(start 145.703544 -230.515414)
		(end 146.575272 -229.643686)
		(width 0.0889)
		(layer "In2.Cu")
		(net "M_I_CPU1_SA_DQ<14>")
	)
	(segment
		(start 151.183594 -224.297494)
		(end 151.710644 -224.825306)
		(width 0.14478)
		(layer "In2.Cu")
		(net "M_I_CPU1_SA_DQ<14>")
	)
	(segment
		(start 144.007078 -233.637836)
		(end 144.120362 -233.571542)
		(width 0.0889)
		(layer "In2.Cu")
		(net "M_I_CPU1_SA_DQ<14>")
	)
	(segment
		(start 148.775166 -227.123498)
		(end 148.937218 -226.961446)
		(width 0.14478)
		(layer "In2.Cu")
		(net "M_I_CPU1_SA_DQ<14>")
	)
	(segment
		(start 129.318766 -233.68889)
		(end 129.414778 -233.66349)
		(width 0.0889)
		(layer "In2.Cu")
		(net "M_I_CPU1_SA_DQ<14>")
	)
	(segment
		(start 135.557768 -233.63174)
		(end 135.56615 -233.626914)
		(width 0.0889)
		(layer "In2.Cu")
		(net "M_I_CPU1_SA_DQ<14>")
	)
	(segment
		(start 148.979636 -227.784406)
		(end 148.979636 -227.556314)
		(width 0.14478)
		(layer "In2.Cu")
		(net "M_I_CPU1_SA_DQ<14>")
	)
	(segment
		(start 152.061418 -224.702624)
		(end 152.061418 -223.1517)
		(width 0.14478)
		(layer "In2.Cu")
		(net "M_I_CPU1_SA_DQ<14>")
	)
	(segment
		(start 133.103366 -233.626914)
		(end 133.111748 -233.63174)
		(width 0.0889)
		(layer "In2.Cu")
		(net "M_I_CPU1_SA_DQ<14>")
	)
	(segment
		(start 144.120362 -233.571542)
		(end 144.777206 -232.914698)
		(width 0.0889)
		(layer "In2.Cu")
		(net "M_I_CPU1_SA_DQ<14>")
	)
	(segment
		(start 130.857752 -233.63174)
		(end 130.866134 -233.626914)
		(width 0.0889)
		(layer "In2.Cu")
		(net "M_I_CPU1_SA_DQ<14>")
	)
	(segment
		(start 150.79345 -224.459546)
		(end 150.955502 -224.297494)
		(width 0.14478)
		(layer "In2.Cu")
		(net "M_I_CPU1_SA_DQ<14>")
	)
	(segment
		(start 139.31773 -233.63174)
		(end 139.326112 -233.626914)
		(width 0.0889)
		(layer "In2.Cu")
		(net "M_I_CPU1_SA_DQ<14>")
	)
	(segment
		(start 150.79345 -224.687638)
		(end 150.79345 -224.459546)
		(width 0.14478)
		(layer "In2.Cu")
		(net "M_I_CPU1_SA_DQ<14>")
	)
	(segment
		(start 137.803382 -233.626914)
		(end 137.811764 -233.63174)
		(width 0.0889)
		(layer "In2.Cu")
		(net "M_I_CPU1_SA_DQ<14>")
	)
	(segment
		(start 148.15693 -227.741734)
		(end 148.385022 -227.741734)
		(width 0.14478)
		(layer "In2.Cu")
		(net "M_I_CPU1_SA_DQ<14>")
	)
	(segment
		(start 144.777206 -231.967024)
		(end 145.703544 -231.040686)
		(width 0.0889)
		(layer "In2.Cu")
		(net "M_I_CPU1_SA_DQ<14>")
	)
	(segment
		(start 151.710644 -224.825306)
		(end 151.938736 -224.825306)
		(width 0.14478)
		(layer "In2.Cu")
		(net "M_I_CPU1_SA_DQ<14>")
	)
	(segment
		(start 149.996652 -225.223324)
		(end 150.158704 -225.061272)
		(width 0.14478)
		(layer "In2.Cu")
		(net "M_I_CPU1_SA_DQ<14>")
	)
	(segment
		(start 129.917698 -233.63174)
		(end 129.92608 -233.626914)
		(width 0.0889)
		(layer "In2.Cu")
		(net "M_I_CPU1_SA_DQ<14>")
	)
	(segment
		(start 148.199348 -228.564694)
		(end 148.199348 -228.336602)
		(width 0.14478)
		(layer "In2.Cu")
		(net "M_I_CPU1_SA_DQ<14>")
	)
	(segment
		(start 142.503398 -233.626914)
		(end 142.51178 -233.63174)
		(width 0.0889)
		(layer "In2.Cu")
		(net "M_I_CPU1_SA_DQ<14>")
	)
	(segment
		(start 148.937218 -226.961446)
		(end 149.16531 -226.961446)
		(width 0.14478)
		(layer "In2.Cu")
		(net "M_I_CPU1_SA_DQ<14>")
	)
	(segment
		(start 150.386796 -225.061272)
		(end 150.930356 -225.605594)
		(width 0.14478)
		(layer "In2.Cu")
		(net "M_I_CPU1_SA_DQ<14>")
	)
	(segment
		(start 143.077692 -233.63174)
		(end 143.086074 -233.626914)
		(width 0.0889)
		(layer "In2.Cu")
		(net "M_I_CPU1_SA_DQ<14>")
	)
	(segment
		(start 134.617714 -233.63174)
		(end 134.626096 -233.626914)
		(width 0.0889)
		(layer "In2.Cu")
		(net "M_I_CPU1_SA_DQ<14>")
	)
	(segment
		(start 151.158448 -225.605594)
		(end 151.3205 -225.443542)
		(width 0.14478)
		(layer "In2.Cu")
		(net "M_I_CPU1_SA_DQ<14>")
	)
	(segment
		(start 161.3027 -213.910418)
		(end 166.22776 -213.910418)
		(width 0.14478)
		(layer "In2.Cu")
		(net "M_I_CPU1_SA_DQ<14>")
	)
	(segment
		(start 149.717506 -226.181158)
		(end 149.945598 -226.181158)
		(width 0.14478)
		(layer "In2.Cu")
		(net "M_I_CPU1_SA_DQ<14>")
	)
	(segment
		(start 146.575272 -229.643686)
		(end 147.120356 -229.643686)
		(width 0.0889)
		(layer "In2.Cu")
		(net "M_I_CPU1_SA_DQ<14>")
	)
	(arc
		(start 129.92608 -233.626914)
		(mid 130.109588 -233.58142)
		(end 130.29184 -233.63174)
		(width 0.0889)
		(layer "In2.Cu")
		(net "M_I_CPU1_SA_DQ<14>")
	)
	(arc
		(start 132.171694 -233.63174)
		(mid 132.45465 -233.707917)
		(end 132.737606 -233.63174)
		(width 0.0889)
		(layer "In2.Cu")
		(net "M_I_CPU1_SA_DQ<14>")
	)
	(arc
		(start 131.797806 -233.63174)
		(mid 131.98475 -233.581485)
		(end 132.171694 -233.63174)
		(width 0.0889)
		(layer "In2.Cu")
		(net "M_I_CPU1_SA_DQ<14>")
	)
	(arc
		(start 135.56615 -233.626914)
		(mid 135.749658 -233.58142)
		(end 135.93191 -233.63174)
		(width 0.0889)
		(layer "In2.Cu")
		(net "M_I_CPU1_SA_DQ<14>")
	)
	(arc
		(start 135.93191 -233.63174)
		(mid 136.214866 -233.707917)
		(end 136.497822 -233.63174)
		(width 0.0889)
		(layer "In2.Cu")
		(net "M_I_CPU1_SA_DQ<14>")
	)
	(arc
		(start 134.626096 -233.626914)
		(mid 134.809604 -233.58142)
		(end 134.991856 -233.63174)
		(width 0.0889)
		(layer "In2.Cu")
		(net "M_I_CPU1_SA_DQ<14>")
	)
	(arc
		(start 140.266166 -233.626914)
		(mid 140.449674 -233.58142)
		(end 140.631926 -233.63174)
		(width 0.0889)
		(layer "In2.Cu")
		(net "M_I_CPU1_SA_DQ<14>")
	)
	(arc
		(start 142.51178 -233.63174)
		(mid 142.794736 -233.707917)
		(end 143.077692 -233.63174)
		(width 0.0889)
		(layer "In2.Cu")
		(net "M_I_CPU1_SA_DQ<14>")
	)
	(arc
		(start 138.377676 -233.63174)
		(mid 138.559927 -233.58139)
		(end 138.743436 -233.626914)
		(width 0.0889)
		(layer "In2.Cu")
		(net "M_I_CPU1_SA_DQ<14>")
	)
	(arc
		(start 138.751818 -233.63174)
		(mid 139.034774 -233.707917)
		(end 139.31773 -233.63174)
		(width 0.0889)
		(layer "In2.Cu")
		(net "M_I_CPU1_SA_DQ<14>")
	)
	(arc
		(start 134.991856 -233.63174)
		(mid 135.274812 -233.707917)
		(end 135.557768 -233.63174)
		(width 0.0889)
		(layer "In2.Cu")
		(net "M_I_CPU1_SA_DQ<14>")
	)
	(arc
		(start 130.29184 -233.63174)
		(mid 130.574796 -233.707917)
		(end 130.857752 -233.63174)
		(width 0.0889)
		(layer "In2.Cu")
		(net "M_I_CPU1_SA_DQ<14>")
	)
	(arc
		(start 137.811764 -233.63174)
		(mid 138.09472 -233.707917)
		(end 138.377676 -233.63174)
		(width 0.0889)
		(layer "In2.Cu")
		(net "M_I_CPU1_SA_DQ<14>")
	)
	(arc
		(start 143.451834 -233.63174)
		(mid 143.728647 -233.707883)
		(end 144.007078 -233.637836)
		(width 0.0889)
		(layer "In2.Cu")
		(net "M_I_CPU1_SA_DQ<14>")
	)
	(arc
		(start 140.631926 -233.63174)
		(mid 140.914882 -233.707917)
		(end 141.197838 -233.63174)
		(width 0.0889)
		(layer "In2.Cu")
		(net "M_I_CPU1_SA_DQ<14>")
	)
	(arc
		(start 133.67766 -233.63174)
		(mid 133.859911 -233.58139)
		(end 134.04342 -233.626914)
		(width 0.0889)
		(layer "In2.Cu")
		(net "M_I_CPU1_SA_DQ<14>")
	)
	(arc
		(start 131.231894 -233.63174)
		(mid 131.51485 -233.707917)
		(end 131.797806 -233.63174)
		(width 0.0889)
		(layer "In2.Cu")
		(net "M_I_CPU1_SA_DQ<14>")
	)
	(arc
		(start 141.197838 -233.63174)
		(mid 141.384782 -233.581485)
		(end 141.571726 -233.63174)
		(width 0.0889)
		(layer "In2.Cu")
		(net "M_I_CPU1_SA_DQ<14>")
	)
	(arc
		(start 136.87171 -233.63174)
		(mid 137.154666 -233.707917)
		(end 137.437622 -233.63174)
		(width 0.0889)
		(layer "In2.Cu")
		(net "M_I_CPU1_SA_DQ<14>")
	)
	(arc
		(start 139.691872 -233.63174)
		(mid 139.974828 -233.707917)
		(end 140.257784 -233.63174)
		(width 0.0889)
		(layer "In2.Cu")
		(net "M_I_CPU1_SA_DQ<14>")
	)
	(arc
		(start 141.571726 -233.63174)
		(mid 141.854682 -233.707917)
		(end 142.137638 -233.63174)
		(width 0.0889)
		(layer "In2.Cu")
		(net "M_I_CPU1_SA_DQ<14>")
	)
	(arc
		(start 143.086074 -233.626914)
		(mid 143.269582 -233.58142)
		(end 143.451834 -233.63174)
		(width 0.0889)
		(layer "In2.Cu")
		(net "M_I_CPU1_SA_DQ<14>")
	)
	(arc
		(start 142.137638 -233.63174)
		(mid 142.319889 -233.58139)
		(end 142.503398 -233.626914)
		(width 0.0889)
		(layer "In2.Cu")
		(net "M_I_CPU1_SA_DQ<14>")
	)
	(arc
		(start 133.111748 -233.63174)
		(mid 133.394704 -233.707917)
		(end 133.67766 -233.63174)
		(width 0.0889)
		(layer "In2.Cu")
		(net "M_I_CPU1_SA_DQ<14>")
	)
	(arc
		(start 130.866134 -233.626914)
		(mid 131.049642 -233.58142)
		(end 131.231894 -233.63174)
		(width 0.0889)
		(layer "In2.Cu")
		(net "M_I_CPU1_SA_DQ<14>")
	)
	(arc
		(start 134.051802 -233.63174)
		(mid 134.334758 -233.707917)
		(end 134.617714 -233.63174)
		(width 0.0889)
		(layer "In2.Cu")
		(net "M_I_CPU1_SA_DQ<14>")
	)
	(arc
		(start 139.326112 -233.626914)
		(mid 139.50962 -233.58142)
		(end 139.691872 -233.63174)
		(width 0.0889)
		(layer "In2.Cu")
		(net "M_I_CPU1_SA_DQ<14>")
	)
	(arc
		(start 132.737606 -233.63174)
		(mid 132.919857 -233.58139)
		(end 133.103366 -233.626914)
		(width 0.0889)
		(layer "In2.Cu")
		(net "M_I_CPU1_SA_DQ<14>")
	)
	(arc
		(start 129.414778 -233.66349)
		(mid 129.669986 -233.706967)
		(end 129.917698 -233.63174)
		(width 0.0889)
		(layer "In2.Cu")
		(net "M_I_CPU1_SA_DQ<14>")
	)
	(arc
		(start 136.497822 -233.63174)
		(mid 136.684766 -233.581485)
		(end 136.87171 -233.63174)
		(width 0.0889)
		(layer "In2.Cu")
		(net "M_I_CPU1_SA_DQ<14>")
	)
	(arc
		(start 137.437622 -233.63174)
		(mid 137.619873 -233.58139)
		(end 137.803382 -233.626914)
		(width 0.0889)
		(layer "In2.Cu")
		(net "M_I_CPU1_SA_DQ<14>")
	)
	(segment
		(start 127.757936 -234.220258)
		(end 128.224788 -233.95432)
		(width 0.10668)
		(layer "F.Cu")
		(net "M_I_CPU1_SA_DQ<13>")
	)
	(segment
		(start 134.617714 -234.2769)
		(end 134.626096 -234.281726)
		(width 0.0889)
		(layer "In2.Cu")
		(net "M_I_CPU1_SA_DQ<13>")
	)
	(segment
		(start 145.556986 -231.859074)
		(end 147.141692 -230.274368)
		(width 0.0889)
		(layer "In2.Cu")
		(net "M_I_CPU1_SA_DQ<13>")
	)
	(segment
		(start 130.857752 -234.2769)
		(end 130.866134 -234.281726)
		(width 0.0889)
		(layer "In2.Cu")
		(net "M_I_CPU1_SA_DQ<13>")
	)
	(segment
		(start 174.640748 -213.910418)
		(end 181.428898 -213.910418)
		(width 0.14478)
		(layer "In2.Cu")
		(net "M_I_CPU1_SA_DQ<13>")
	)
	(segment
		(start 181.980332 -214.789766)
		(end 182.141876 -214.628222)
		(width 0.14478)
		(layer "In2.Cu")
		(net "M_I_CPU1_SA_DQ<13>")
	)
	(segment
		(start 181.590442 -214.071962)
		(end 181.590442 -214.628222)
		(width 0.14478)
		(layer "In2.Cu")
		(net "M_I_CPU1_SA_DQ<13>")
	)
	(segment
		(start 135.557768 -234.2769)
		(end 135.56615 -234.281726)
		(width 0.0889)
		(layer "In2.Cu")
		(net "M_I_CPU1_SA_DQ<13>")
	)
	(segment
		(start 173.790864 -214.760302)
		(end 174.640748 -213.910418)
		(width 0.14478)
		(layer "In2.Cu")
		(net "M_I_CPU1_SA_DQ<13>")
	)
	(segment
		(start 182.30342 -213.910418)
		(end 183.19115 -213.910418)
		(width 0.14478)
		(layer "In2.Cu")
		(net "M_I_CPU1_SA_DQ<13>")
	)
	(segment
		(start 140.257784 -234.2769)
		(end 140.266166 -234.281726)
		(width 0.0889)
		(layer "In2.Cu")
		(net "M_I_CPU1_SA_DQ<13>")
	)
	(segment
		(start 128.224788 -233.95432)
		(end 128.07061 -234.21975)
		(width 0.0889)
		(layer "In2.Cu")
		(net "M_I_CPU1_SA_DQ<13>")
	)
	(segment
		(start 142.503398 -234.281726)
		(end 142.51178 -234.2769)
		(width 0.0889)
		(layer "In2.Cu")
		(net "M_I_CPU1_SA_DQ<13>")
	)
	(segment
		(start 128.07061 -234.21975)
		(end 128.092962 -234.303062)
		(width 0.0889)
		(layer "In2.Cu")
		(net "M_I_CPU1_SA_DQ<13>")
	)
	(segment
		(start 129.343404 -234.281726)
		(end 129.351786 -234.2769)
		(width 0.0889)
		(layer "In2.Cu")
		(net "M_I_CPU1_SA_DQ<13>")
	)
	(segment
		(start 137.803382 -234.281726)
		(end 137.811764 -234.2769)
		(width 0.0889)
		(layer "In2.Cu")
		(net "M_I_CPU1_SA_DQ<13>")
	)
	(segment
		(start 147.141692 -230.274368)
		(end 152.510998 -224.905062)
		(width 0.14478)
		(layer "In2.Cu")
		(net "M_I_CPU1_SA_DQ<13>")
	)
	(segment
		(start 181.590442 -214.628222)
		(end 181.751986 -214.789766)
		(width 0.14478)
		(layer "In2.Cu")
		(net "M_I_CPU1_SA_DQ<13>")
	)
	(segment
		(start 169.679366 -213.910418)
		(end 170.52925 -214.760302)
		(width 0.14478)
		(layer "In2.Cu")
		(net "M_I_CPU1_SA_DQ<13>")
	)
	(segment
		(start 139.31773 -234.2769)
		(end 139.326112 -234.281726)
		(width 0.0889)
		(layer "In2.Cu")
		(net "M_I_CPU1_SA_DQ<13>")
	)
	(segment
		(start 182.141876 -214.628222)
		(end 182.141876 -214.071962)
		(width 0.14478)
		(layer "In2.Cu")
		(net "M_I_CPU1_SA_DQ<13>")
	)
	(segment
		(start 181.428898 -213.910418)
		(end 181.590442 -214.071962)
		(width 0.14478)
		(layer "In2.Cu")
		(net "M_I_CPU1_SA_DQ<13>")
	)
	(segment
		(start 134.04342 -234.281726)
		(end 134.051802 -234.2769)
		(width 0.0889)
		(layer "In2.Cu")
		(net "M_I_CPU1_SA_DQ<13>")
	)
	(segment
		(start 143.077692 -234.2769)
		(end 143.086074 -234.281726)
		(width 0.0889)
		(layer "In2.Cu")
		(net "M_I_CPU1_SA_DQ<13>")
	)
	(segment
		(start 183.19115 -213.910418)
		(end 183.616092 -214.33536)
		(width 0.14478)
		(layer "In2.Cu")
		(net "M_I_CPU1_SA_DQ<13>")
	)
	(segment
		(start 129.917698 -234.2769)
		(end 129.92608 -234.281726)
		(width 0.0889)
		(layer "In2.Cu")
		(net "M_I_CPU1_SA_DQ<13>")
	)
	(segment
		(start 133.103366 -234.281726)
		(end 133.111748 -234.2769)
		(width 0.0889)
		(layer "In2.Cu")
		(net "M_I_CPU1_SA_DQ<13>")
	)
	(segment
		(start 138.743436 -234.281726)
		(end 138.751818 -234.2769)
		(width 0.0889)
		(layer "In2.Cu")
		(net "M_I_CPU1_SA_DQ<13>")
	)
	(segment
		(start 181.751986 -214.789766)
		(end 181.980332 -214.789766)
		(width 0.14478)
		(layer "In2.Cu")
		(net "M_I_CPU1_SA_DQ<13>")
	)
	(segment
		(start 152.510998 -224.905062)
		(end 152.510998 -223.338136)
		(width 0.14478)
		(layer "In2.Cu")
		(net "M_I_CPU1_SA_DQ<13>")
	)
	(segment
		(start 161.088832 -214.760302)
		(end 166.221918 -214.760302)
		(width 0.14478)
		(layer "In2.Cu")
		(net "M_I_CPU1_SA_DQ<13>")
	)
	(segment
		(start 145.556986 -232.424986)
		(end 145.556986 -231.859074)
		(width 0.0889)
		(layer "In2.Cu")
		(net "M_I_CPU1_SA_DQ<13>")
	)
	(segment
		(start 167.071802 -213.910418)
		(end 169.679366 -213.910418)
		(width 0.14478)
		(layer "In2.Cu")
		(net "M_I_CPU1_SA_DQ<13>")
	)
	(segment
		(start 143.97609 -234.005882)
		(end 145.556986 -232.424986)
		(width 0.0889)
		(layer "In2.Cu")
		(net "M_I_CPU1_SA_DQ<13>")
	)
	(segment
		(start 128.40335 -234.281726)
		(end 128.411732 -234.2769)
		(width 0.0889)
		(layer "In2.Cu")
		(net "M_I_CPU1_SA_DQ<13>")
	)
	(segment
		(start 166.221918 -214.760302)
		(end 167.071802 -213.910418)
		(width 0.14478)
		(layer "In2.Cu")
		(net "M_I_CPU1_SA_DQ<13>")
	)
	(segment
		(start 170.52925 -214.760302)
		(end 173.790864 -214.760302)
		(width 0.14478)
		(layer "In2.Cu")
		(net "M_I_CPU1_SA_DQ<13>")
	)
	(segment
		(start 152.510998 -223.338136)
		(end 161.088832 -214.760302)
		(width 0.14478)
		(layer "In2.Cu")
		(net "M_I_CPU1_SA_DQ<13>")
	)
	(segment
		(start 182.141876 -214.071962)
		(end 182.30342 -213.910418)
		(width 0.14478)
		(layer "In2.Cu")
		(net "M_I_CPU1_SA_DQ<13>")
	)
	(arc
		(start 133.111748 -234.2769)
		(mid 133.394704 -234.200723)
		(end 133.67766 -234.2769)
		(width 0.0889)
		(layer "In2.Cu")
		(net "M_I_CPU1_SA_DQ<13>")
	)
	(arc
		(start 143.086074 -234.281726)
		(mid 143.269582 -234.32722)
		(end 143.451834 -234.2769)
		(width 0.0889)
		(layer "In2.Cu")
		(net "M_I_CPU1_SA_DQ<13>")
	)
	(arc
		(start 142.51178 -234.2769)
		(mid 142.794736 -234.200723)
		(end 143.077692 -234.2769)
		(width 0.0889)
		(layer "In2.Cu")
		(net "M_I_CPU1_SA_DQ<13>")
	)
	(arc
		(start 136.497822 -234.2769)
		(mid 136.684766 -234.327155)
		(end 136.87171 -234.2769)
		(width 0.0889)
		(layer "In2.Cu")
		(net "M_I_CPU1_SA_DQ<13>")
	)
	(arc
		(start 140.266166 -234.281726)
		(mid 140.449674 -234.32722)
		(end 140.631926 -234.2769)
		(width 0.0889)
		(layer "In2.Cu")
		(net "M_I_CPU1_SA_DQ<13>")
	)
	(arc
		(start 135.56615 -234.281726)
		(mid 135.749658 -234.32722)
		(end 135.93191 -234.2769)
		(width 0.0889)
		(layer "In2.Cu")
		(net "M_I_CPU1_SA_DQ<13>")
	)
	(arc
		(start 137.437622 -234.2769)
		(mid 137.619873 -234.32725)
		(end 137.803382 -234.281726)
		(width 0.0889)
		(layer "In2.Cu")
		(net "M_I_CPU1_SA_DQ<13>")
	)
	(arc
		(start 141.197838 -234.2769)
		(mid 141.384782 -234.327155)
		(end 141.571726 -234.2769)
		(width 0.0889)
		(layer "In2.Cu")
		(net "M_I_CPU1_SA_DQ<13>")
	)
	(arc
		(start 139.691872 -234.2769)
		(mid 139.974828 -234.200723)
		(end 140.257784 -234.2769)
		(width 0.0889)
		(layer "In2.Cu")
		(net "M_I_CPU1_SA_DQ<13>")
	)
	(arc
		(start 143.451834 -234.2769)
		(mid 143.541806 -234.227605)
		(end 143.639032 -234.194858)
		(width 0.0889)
		(layer "In2.Cu")
		(net "M_I_CPU1_SA_DQ<13>")
	)
	(arc
		(start 131.231894 -234.2769)
		(mid 131.51485 -234.200723)
		(end 131.797806 -234.2769)
		(width 0.0889)
		(layer "In2.Cu")
		(net "M_I_CPU1_SA_DQ<13>")
	)
	(arc
		(start 143.639032 -234.194858)
		(mid 143.820606 -234.123638)
		(end 143.97609 -234.005882)
		(width 0.0889)
		(layer "In2.Cu")
		(net "M_I_CPU1_SA_DQ<13>")
	)
	(arc
		(start 134.626096 -234.281726)
		(mid 134.809604 -234.32722)
		(end 134.991856 -234.2769)
		(width 0.0889)
		(layer "In2.Cu")
		(net "M_I_CPU1_SA_DQ<13>")
	)
	(arc
		(start 130.866134 -234.281726)
		(mid 131.049642 -234.32722)
		(end 131.231894 -234.2769)
		(width 0.0889)
		(layer "In2.Cu")
		(net "M_I_CPU1_SA_DQ<13>")
	)
	(arc
		(start 136.87171 -234.2769)
		(mid 137.154666 -234.200723)
		(end 137.437622 -234.2769)
		(width 0.0889)
		(layer "In2.Cu")
		(net "M_I_CPU1_SA_DQ<13>")
	)
	(arc
		(start 128.092962 -234.303062)
		(mid 128.250472 -234.32626)
		(end 128.40335 -234.281726)
		(width 0.0889)
		(layer "In2.Cu")
		(net "M_I_CPU1_SA_DQ<13>")
	)
	(arc
		(start 131.797806 -234.2769)
		(mid 131.98475 -234.327155)
		(end 132.171694 -234.2769)
		(width 0.0889)
		(layer "In2.Cu")
		(net "M_I_CPU1_SA_DQ<13>")
	)
	(arc
		(start 139.326112 -234.281726)
		(mid 139.50962 -234.32722)
		(end 139.691872 -234.2769)
		(width 0.0889)
		(layer "In2.Cu")
		(net "M_I_CPU1_SA_DQ<13>")
	)
	(arc
		(start 134.051802 -234.2769)
		(mid 134.334758 -234.200723)
		(end 134.617714 -234.2769)
		(width 0.0889)
		(layer "In2.Cu")
		(net "M_I_CPU1_SA_DQ<13>")
	)
	(arc
		(start 132.737606 -234.2769)
		(mid 132.919857 -234.32725)
		(end 133.103366 -234.281726)
		(width 0.0889)
		(layer "In2.Cu")
		(net "M_I_CPU1_SA_DQ<13>")
	)
	(arc
		(start 130.29184 -234.2769)
		(mid 130.574796 -234.200723)
		(end 130.857752 -234.2769)
		(width 0.0889)
		(layer "In2.Cu")
		(net "M_I_CPU1_SA_DQ<13>")
	)
	(arc
		(start 140.631926 -234.2769)
		(mid 140.914882 -234.200723)
		(end 141.197838 -234.2769)
		(width 0.0889)
		(layer "In2.Cu")
		(net "M_I_CPU1_SA_DQ<13>")
	)
	(arc
		(start 137.811764 -234.2769)
		(mid 138.09472 -234.200723)
		(end 138.377676 -234.2769)
		(width 0.0889)
		(layer "In2.Cu")
		(net "M_I_CPU1_SA_DQ<13>")
	)
	(arc
		(start 128.977644 -234.2769)
		(mid 129.159895 -234.32725)
		(end 129.343404 -234.281726)
		(width 0.0889)
		(layer "In2.Cu")
		(net "M_I_CPU1_SA_DQ<13>")
	)
	(arc
		(start 129.351786 -234.2769)
		(mid 129.634742 -234.200723)
		(end 129.917698 -234.2769)
		(width 0.0889)
		(layer "In2.Cu")
		(net "M_I_CPU1_SA_DQ<13>")
	)
	(arc
		(start 129.92608 -234.281726)
		(mid 130.109588 -234.32722)
		(end 130.29184 -234.2769)
		(width 0.0889)
		(layer "In2.Cu")
		(net "M_I_CPU1_SA_DQ<13>")
	)
	(arc
		(start 133.67766 -234.2769)
		(mid 133.859911 -234.32725)
		(end 134.04342 -234.281726)
		(width 0.0889)
		(layer "In2.Cu")
		(net "M_I_CPU1_SA_DQ<13>")
	)
	(arc
		(start 132.171694 -234.2769)
		(mid 132.45465 -234.200723)
		(end 132.737606 -234.2769)
		(width 0.0889)
		(layer "In2.Cu")
		(net "M_I_CPU1_SA_DQ<13>")
	)
	(arc
		(start 142.137638 -234.2769)
		(mid 142.319889 -234.32725)
		(end 142.503398 -234.281726)
		(width 0.0889)
		(layer "In2.Cu")
		(net "M_I_CPU1_SA_DQ<13>")
	)
	(arc
		(start 141.571726 -234.2769)
		(mid 141.854682 -234.200723)
		(end 142.137638 -234.2769)
		(width 0.0889)
		(layer "In2.Cu")
		(net "M_I_CPU1_SA_DQ<13>")
	)
	(arc
		(start 135.93191 -234.2769)
		(mid 136.214866 -234.200723)
		(end 136.497822 -234.2769)
		(width 0.0889)
		(layer "In2.Cu")
		(net "M_I_CPU1_SA_DQ<13>")
	)
	(arc
		(start 138.377676 -234.2769)
		(mid 138.559927 -234.32725)
		(end 138.743436 -234.281726)
		(width 0.0889)
		(layer "In2.Cu")
		(net "M_I_CPU1_SA_DQ<13>")
	)
	(arc
		(start 138.751818 -234.2769)
		(mid 139.034774 -234.200723)
		(end 139.31773 -234.2769)
		(width 0.0889)
		(layer "In2.Cu")
		(net "M_I_CPU1_SA_DQ<13>")
	)
	(arc
		(start 128.411732 -234.2769)
		(mid 128.694688 -234.200723)
		(end 128.977644 -234.2769)
		(width 0.0889)
		(layer "In2.Cu")
		(net "M_I_CPU1_SA_DQ<13>")
	)
	(arc
		(start 134.991856 -234.2769)
		(mid 135.274812 -234.200723)
		(end 135.557768 -234.2769)
		(width 0.0889)
		(layer "In2.Cu")
		(net "M_I_CPU1_SA_DQ<13>")
	)
	(segment
		(start 129.16789 -233.410252)
		(end 129.634742 -233.144314)
		(width 0.10668)
		(layer "F.Cu")
		(net "M_I_CPU1_SA_DQ<12>")
	)
	(segment
		(start 170.69181 -213.069932)
		(end 173.64329 -213.069932)
		(width 0.14478)
		(layer "In2.Cu")
		(net "M_I_CPU1_SA_DQ<12>")
	)
	(segment
		(start 147.098512 -228.832918)
		(end 147.098512 -228.148642)
		(width 0.0889)
		(layer "In2.Cu")
		(net "M_I_CPU1_SA_DQ<12>")
	)
	(segment
		(start 181.159404 -212.058504)
		(end 181.159404 -211.577174)
		(width 0.14478)
		(layer "In2.Cu")
		(net "M_I_CPU1_SA_DQ<12>")
	)
	(segment
		(start 144.56918 -231.880664)
		(end 145.500344 -230.9495)
		(width 0.0889)
		(layer "In2.Cu")
		(net "M_I_CPU1_SA_DQ<12>")
	)
	(segment
		(start 181.872382 -213.024466)
		(end 182.100728 -213.024466)
		(width 0.14478)
		(layer "In2.Cu")
		(net "M_I_CPU1_SA_DQ<12>")
	)
	(segment
		(start 144.56918 -232.828592)
		(end 144.56918 -231.880664)
		(width 0.0889)
		(layer "In2.Cu")
		(net "M_I_CPU1_SA_DQ<12>")
	)
	(segment
		(start 129.634742 -233.144314)
		(end 129.480818 -233.409744)
		(width 0.0889)
		(layer "In2.Cu")
		(net "M_I_CPU1_SA_DQ<12>")
	)
	(segment
		(start 174.493174 -212.220048)
		(end 180.99786 -212.220048)
		(width 0.14478)
		(layer "In2.Cu")
		(net "M_I_CPU1_SA_DQ<12>")
	)
	(segment
		(start 133.20776 -233.466894)
		(end 133.216142 -233.47172)
		(width 0.0889)
		(layer "In2.Cu")
		(net "M_I_CPU1_SA_DQ<12>")
	)
	(segment
		(start 143.913352 -233.47172)
		(end 143.921734 -233.466894)
		(width 0.0889)
		(layer "In2.Cu")
		(net "M_I_CPU1_SA_DQ<12>")
	)
	(segment
		(start 169.841926 -212.220048)
		(end 170.69181 -213.069932)
		(width 0.14478)
		(layer "In2.Cu")
		(net "M_I_CPU1_SA_DQ<12>")
	)
	(segment
		(start 137.907776 -233.466894)
		(end 137.916158 -233.47172)
		(width 0.0889)
		(layer "In2.Cu")
		(net "M_I_CPU1_SA_DQ<12>")
	)
	(segment
		(start 149.05355 -226.193604)
		(end 149.05355 -225.523298)
		(width 0.14478)
		(layer "In2.Cu")
		(net "M_I_CPU1_SA_DQ<12>")
	)
	(segment
		(start 181.710838 -212.862922)
		(end 181.872382 -213.024466)
		(width 0.14478)
		(layer "In2.Cu")
		(net "M_I_CPU1_SA_DQ<12>")
	)
	(segment
		(start 130.753358 -233.47172)
		(end 130.76174 -233.466894)
		(width 0.0889)
		(layer "In2.Cu")
		(net "M_I_CPU1_SA_DQ<12>")
	)
	(segment
		(start 166.32047 -213.069932)
		(end 167.170354 -212.220048)
		(width 0.14478)
		(layer "In2.Cu")
		(net "M_I_CPU1_SA_DQ<12>")
	)
	(segment
		(start 141.667738 -233.466894)
		(end 141.67612 -233.47172)
		(width 0.0889)
		(layer "In2.Cu")
		(net "M_I_CPU1_SA_DQ<12>")
	)
	(segment
		(start 143.96085 -233.436922)
		(end 144.56918 -232.828592)
		(width 0.0889)
		(layer "In2.Cu")
		(net "M_I_CPU1_SA_DQ<12>")
	)
	(segment
		(start 173.64329 -213.069932)
		(end 174.493174 -212.220048)
		(width 0.14478)
		(layer "In2.Cu")
		(net "M_I_CPU1_SA_DQ<12>")
	)
	(segment
		(start 140.15339 -233.47172)
		(end 140.161772 -233.466894)
		(width 0.0889)
		(layer "In2.Cu")
		(net "M_I_CPU1_SA_DQ<12>")
	)
	(segment
		(start 149.05355 -225.523298)
		(end 161.506916 -213.069932)
		(width 0.14478)
		(layer "In2.Cu")
		(net "M_I_CPU1_SA_DQ<12>")
	)
	(segment
		(start 181.320948 -211.41563)
		(end 181.549294 -211.41563)
		(width 0.14478)
		(layer "In2.Cu")
		(net "M_I_CPU1_SA_DQ<12>")
	)
	(segment
		(start 180.99786 -212.220048)
		(end 181.159404 -212.058504)
		(width 0.14478)
		(layer "In2.Cu")
		(net "M_I_CPU1_SA_DQ<12>")
	)
	(segment
		(start 132.267706 -233.466894)
		(end 132.276088 -233.47172)
		(width 0.0889)
		(layer "In2.Cu")
		(net "M_I_CPU1_SA_DQ<12>")
	)
	(segment
		(start 182.423816 -212.220048)
		(end 183.200802 -212.220048)
		(width 0.14478)
		(layer "In2.Cu")
		(net "M_I_CPU1_SA_DQ<12>")
	)
	(segment
		(start 181.159404 -211.577174)
		(end 181.320948 -211.41563)
		(width 0.14478)
		(layer "In2.Cu")
		(net "M_I_CPU1_SA_DQ<12>")
	)
	(segment
		(start 136.393428 -233.47172)
		(end 136.40181 -233.466894)
		(width 0.0889)
		(layer "In2.Cu")
		(net "M_I_CPU1_SA_DQ<12>")
	)
	(segment
		(start 161.506916 -213.069932)
		(end 166.32047 -213.069932)
		(width 0.14478)
		(layer "In2.Cu")
		(net "M_I_CPU1_SA_DQ<12>")
	)
	(segment
		(start 145.500344 -230.9495)
		(end 145.500344 -230.431086)
		(width 0.0889)
		(layer "In2.Cu")
		(net "M_I_CPU1_SA_DQ<12>")
	)
	(segment
		(start 181.549294 -211.41563)
		(end 181.710838 -211.577174)
		(width 0.14478)
		(layer "In2.Cu")
		(net "M_I_CPU1_SA_DQ<12>")
	)
	(segment
		(start 183.200802 -212.220048)
		(end 183.616092 -212.635338)
		(width 0.14478)
		(layer "In2.Cu")
		(net "M_I_CPU1_SA_DQ<12>")
	)
	(segment
		(start 181.710838 -211.577174)
		(end 181.710838 -212.862922)
		(width 0.14478)
		(layer "In2.Cu")
		(net "M_I_CPU1_SA_DQ<12>")
	)
	(segment
		(start 129.480818 -233.409744)
		(end 129.50317 -233.493056)
		(width 0.0889)
		(layer "In2.Cu")
		(net "M_I_CPU1_SA_DQ<12>")
	)
	(segment
		(start 182.262272 -212.862922)
		(end 182.262272 -212.381592)
		(width 0.14478)
		(layer "In2.Cu")
		(net "M_I_CPU1_SA_DQ<12>")
	)
	(segment
		(start 182.100728 -213.024466)
		(end 182.262272 -212.862922)
		(width 0.14478)
		(layer "In2.Cu")
		(net "M_I_CPU1_SA_DQ<12>")
	)
	(segment
		(start 147.330922 -227.916232)
		(end 149.05355 -226.193604)
		(width 0.14478)
		(layer "In2.Cu")
		(net "M_I_CPU1_SA_DQ<12>")
	)
	(segment
		(start 141.093444 -233.47172)
		(end 141.101826 -233.466894)
		(width 0.0889)
		(layer "In2.Cu")
		(net "M_I_CPU1_SA_DQ<12>")
	)
	(segment
		(start 145.500344 -230.431086)
		(end 147.098512 -228.832918)
		(width 0.0889)
		(layer "In2.Cu")
		(net "M_I_CPU1_SA_DQ<12>")
	)
	(segment
		(start 147.098512 -228.148642)
		(end 147.330922 -227.916232)
		(width 0.0889)
		(layer "In2.Cu")
		(net "M_I_CPU1_SA_DQ<12>")
	)
	(segment
		(start 182.262272 -212.381592)
		(end 182.423816 -212.220048)
		(width 0.14478)
		(layer "In2.Cu")
		(net "M_I_CPU1_SA_DQ<12>")
	)
	(segment
		(start 167.170354 -212.220048)
		(end 169.841926 -212.220048)
		(width 0.14478)
		(layer "In2.Cu")
		(net "M_I_CPU1_SA_DQ<12>")
	)
	(segment
		(start 135.453374 -233.47172)
		(end 135.461756 -233.466894)
		(width 0.0889)
		(layer "In2.Cu")
		(net "M_I_CPU1_SA_DQ<12>")
	)
	(segment
		(start 131.693412 -233.47172)
		(end 131.701794 -233.466894)
		(width 0.0889)
		(layer "In2.Cu")
		(net "M_I_CPU1_SA_DQ<12>")
	)
	(segment
		(start 136.967722 -233.466894)
		(end 136.976104 -233.47172)
		(width 0.0889)
		(layer "In2.Cu")
		(net "M_I_CPU1_SA_DQ<12>")
	)
	(arc
		(start 139.78763 -233.466894)
		(mid 139.969881 -233.517244)
		(end 140.15339 -233.47172)
		(width 0.0889)
		(layer "In2.Cu")
		(net "M_I_CPU1_SA_DQ<12>")
	)
	(arc
		(start 137.916158 -233.47172)
		(mid 138.099666 -233.517214)
		(end 138.281918 -233.466894)
		(width 0.0889)
		(layer "In2.Cu")
		(net "M_I_CPU1_SA_DQ<12>")
	)
	(arc
		(start 134.147814 -233.466894)
		(mid 134.334758 -233.517149)
		(end 134.521702 -233.466894)
		(width 0.0889)
		(layer "In2.Cu")
		(net "M_I_CPU1_SA_DQ<12>")
	)
	(arc
		(start 136.027668 -233.466894)
		(mid 136.209919 -233.517244)
		(end 136.393428 -233.47172)
		(width 0.0889)
		(layer "In2.Cu")
		(net "M_I_CPU1_SA_DQ<12>")
	)
	(arc
		(start 130.387598 -233.466894)
		(mid 130.569849 -233.517244)
		(end 130.753358 -233.47172)
		(width 0.0889)
		(layer "In2.Cu")
		(net "M_I_CPU1_SA_DQ<12>")
	)
	(arc
		(start 142.607792 -233.466894)
		(mid 142.794736 -233.517149)
		(end 142.98168 -233.466894)
		(width 0.0889)
		(layer "In2.Cu")
		(net "M_I_CPU1_SA_DQ<12>")
	)
	(arc
		(start 142.98168 -233.466894)
		(mid 143.264636 -233.390717)
		(end 143.547592 -233.466894)
		(width 0.0889)
		(layer "In2.Cu")
		(net "M_I_CPU1_SA_DQ<12>")
	)
	(arc
		(start 136.40181 -233.466894)
		(mid 136.684766 -233.390717)
		(end 136.967722 -233.466894)
		(width 0.0889)
		(layer "In2.Cu")
		(net "M_I_CPU1_SA_DQ<12>")
	)
	(arc
		(start 141.67612 -233.47172)
		(mid 141.859628 -233.517214)
		(end 142.04188 -233.466894)
		(width 0.0889)
		(layer "In2.Cu")
		(net "M_I_CPU1_SA_DQ<12>")
	)
	(arc
		(start 142.04188 -233.466894)
		(mid 142.324836 -233.390717)
		(end 142.607792 -233.466894)
		(width 0.0889)
		(layer "In2.Cu")
		(net "M_I_CPU1_SA_DQ<12>")
	)
	(arc
		(start 140.161772 -233.466894)
		(mid 140.444728 -233.390717)
		(end 140.727684 -233.466894)
		(width 0.0889)
		(layer "In2.Cu")
		(net "M_I_CPU1_SA_DQ<12>")
	)
	(arc
		(start 129.821686 -233.466894)
		(mid 130.104642 -233.390717)
		(end 130.387598 -233.466894)
		(width 0.0889)
		(layer "In2.Cu")
		(net "M_I_CPU1_SA_DQ<12>")
	)
	(arc
		(start 131.701794 -233.466894)
		(mid 131.98475 -233.390717)
		(end 132.267706 -233.466894)
		(width 0.0889)
		(layer "In2.Cu")
		(net "M_I_CPU1_SA_DQ<12>")
	)
	(arc
		(start 129.50317 -233.493056)
		(mid 129.665359 -233.515791)
		(end 129.821686 -233.466894)
		(width 0.0889)
		(layer "In2.Cu")
		(net "M_I_CPU1_SA_DQ<12>")
	)
	(arc
		(start 134.521702 -233.466894)
		(mid 134.804658 -233.390717)
		(end 135.087614 -233.466894)
		(width 0.0889)
		(layer "In2.Cu")
		(net "M_I_CPU1_SA_DQ<12>")
	)
	(arc
		(start 137.341864 -233.466894)
		(mid 137.62482 -233.390717)
		(end 137.907776 -233.466894)
		(width 0.0889)
		(layer "In2.Cu")
		(net "M_I_CPU1_SA_DQ<12>")
	)
	(arc
		(start 135.087614 -233.466894)
		(mid 135.269865 -233.517244)
		(end 135.453374 -233.47172)
		(width 0.0889)
		(layer "In2.Cu")
		(net "M_I_CPU1_SA_DQ<12>")
	)
	(arc
		(start 133.216142 -233.47172)
		(mid 133.39965 -233.517214)
		(end 133.581902 -233.466894)
		(width 0.0889)
		(layer "In2.Cu")
		(net "M_I_CPU1_SA_DQ<12>")
	)
	(arc
		(start 140.727684 -233.466894)
		(mid 140.909935 -233.517244)
		(end 141.093444 -233.47172)
		(width 0.0889)
		(layer "In2.Cu")
		(net "M_I_CPU1_SA_DQ<12>")
	)
	(arc
		(start 141.101826 -233.466894)
		(mid 141.384782 -233.390717)
		(end 141.667738 -233.466894)
		(width 0.0889)
		(layer "In2.Cu")
		(net "M_I_CPU1_SA_DQ<12>")
	)
	(arc
		(start 133.581902 -233.466894)
		(mid 133.864858 -233.390717)
		(end 134.147814 -233.466894)
		(width 0.0889)
		(layer "In2.Cu")
		(net "M_I_CPU1_SA_DQ<12>")
	)
	(arc
		(start 139.221718 -233.466894)
		(mid 139.504674 -233.390717)
		(end 139.78763 -233.466894)
		(width 0.0889)
		(layer "In2.Cu")
		(net "M_I_CPU1_SA_DQ<12>")
	)
	(arc
		(start 135.461756 -233.466894)
		(mid 135.744712 -233.390717)
		(end 136.027668 -233.466894)
		(width 0.0889)
		(layer "In2.Cu")
		(net "M_I_CPU1_SA_DQ<12>")
	)
	(arc
		(start 130.76174 -233.466894)
		(mid 131.044696 -233.390717)
		(end 131.327652 -233.466894)
		(width 0.0889)
		(layer "In2.Cu")
		(net "M_I_CPU1_SA_DQ<12>")
	)
	(arc
		(start 132.276088 -233.47172)
		(mid 132.459596 -233.517214)
		(end 132.641848 -233.466894)
		(width 0.0889)
		(layer "In2.Cu")
		(net "M_I_CPU1_SA_DQ<12>")
	)
	(arc
		(start 138.281918 -233.466894)
		(mid 138.564874 -233.390717)
		(end 138.84783 -233.466894)
		(width 0.0889)
		(layer "In2.Cu")
		(net "M_I_CPU1_SA_DQ<12>")
	)
	(arc
		(start 143.547592 -233.466894)
		(mid 143.729843 -233.517244)
		(end 143.913352 -233.47172)
		(width 0.0889)
		(layer "In2.Cu")
		(net "M_I_CPU1_SA_DQ<12>")
	)
	(arc
		(start 143.921734 -233.466894)
		(mid 143.942278 -233.453195)
		(end 143.96085 -233.436922)
		(width 0.0889)
		(layer "In2.Cu")
		(net "M_I_CPU1_SA_DQ<12>")
	)
	(arc
		(start 138.84783 -233.466894)
		(mid 139.034774 -233.517149)
		(end 139.221718 -233.466894)
		(width 0.0889)
		(layer "In2.Cu")
		(net "M_I_CPU1_SA_DQ<12>")
	)
	(arc
		(start 132.641848 -233.466894)
		(mid 132.924804 -233.390717)
		(end 133.20776 -233.466894)
		(width 0.0889)
		(layer "In2.Cu")
		(net "M_I_CPU1_SA_DQ<12>")
	)
	(arc
		(start 136.976104 -233.47172)
		(mid 137.159612 -233.517214)
		(end 137.341864 -233.466894)
		(width 0.0889)
		(layer "In2.Cu")
		(net "M_I_CPU1_SA_DQ<12>")
	)
	(arc
		(start 131.327652 -233.466894)
		(mid 131.509903 -233.517244)
		(end 131.693412 -233.47172)
		(width 0.0889)
		(layer "In2.Cu")
		(net "M_I_CPU1_SA_DQ<12>")
	)
	(segment
		(start 127.287782 -231.79024)
		(end 127.754634 -231.524302)
		(width 0.10668)
		(layer "F.Cu")
		(net "M_I_CPU1_SA_DQ<11>")
	)
	(segment
		(start 165.987222 -209.650584)
		(end 167.137842 -208.499964)
		(width 0.14478)
		(layer "In2.Cu")
		(net "M_I_CPU1_SA_DQ<11>")
	)
	(segment
		(start 153.88971 -215.958166)
		(end 154.051254 -215.796622)
		(width 0.14478)
		(layer "In2.Cu")
		(net "M_I_CPU1_SA_DQ<11>")
	)
	(segment
		(start 155.136342 -216.101422)
		(end 155.136342 -215.872822)
		(width 0.14478)
		(layer "In2.Cu")
		(net "M_I_CPU1_SA_DQ<11>")
	)
	(segment
		(start 167.383714 -208.499964)
		(end 167.68445 -208.8007)
		(width 0.14478)
		(layer "In2.Cu")
		(net "M_I_CPU1_SA_DQ<11>")
	)
	(segment
		(start 173.525688 -209.650584)
		(end 174.650908 -208.525364)
		(width 0.14478)
		(layer "In2.Cu")
		(net "M_I_CPU1_SA_DQ<11>")
	)
	(segment
		(start 131.693412 -231.19715)
		(end 131.701794 -231.201976)
		(width 0.0889)
		(layer "In2.Cu")
		(net "M_I_CPU1_SA_DQ<11>")
	)
	(segment
		(start 174.92218 -208.525364)
		(end 175.197516 -208.8007)
		(width 0.14478)
		(layer "In2.Cu")
		(net "M_I_CPU1_SA_DQ<11>")
	)
	(segment
		(start 143.51508 -229.60076)
		(end 143.547592 -229.581964)
		(width 0.0889)
		(layer "In2.Cu")
		(net "M_I_CPU1_SA_DQ<11>")
	)
	(segment
		(start 141.093444 -231.19715)
		(end 141.101826 -231.201976)
		(width 0.0889)
		(layer "In2.Cu")
		(net "M_I_CPU1_SA_DQ<11>")
	)
	(segment
		(start 175.197516 -208.8007)
		(end 177.121566 -208.8007)
		(width 0.14478)
		(layer "In2.Cu")
		(net "M_I_CPU1_SA_DQ<11>")
	)
	(segment
		(start 154.669998 -215.177878)
		(end 160.197292 -209.650584)
		(width 0.14478)
		(layer "In2.Cu")
		(net "M_I_CPU1_SA_DQ<11>")
	)
	(segment
		(start 130.753358 -231.19715)
		(end 130.76174 -231.201976)
		(width 0.0889)
		(layer "In2.Cu")
		(net "M_I_CPU1_SA_DQ<11>")
	)
	(segment
		(start 146.92503 -225.206306)
		(end 146.92503 -224.322386)
		(width 0.0889)
		(layer "In2.Cu")
		(net "M_I_CPU1_SA_DQ<11>")
	)
	(segment
		(start 169.684192 -208.499964)
		(end 169.930064 -208.499964)
		(width 0.14478)
		(layer "In2.Cu")
		(net "M_I_CPU1_SA_DQ<11>")
	)
	(segment
		(start 167.68445 -208.8007)
		(end 169.383456 -208.8007)
		(width 0.14478)
		(layer "In2.Cu")
		(net "M_I_CPU1_SA_DQ<11>")
	)
	(segment
		(start 147.04441 -224.203006)
		(end 154.36088 -216.886536)
		(width 0.14478)
		(layer "In2.Cu")
		(net "M_I_CPU1_SA_DQ<11>")
	)
	(segment
		(start 146.16303 -225.622358)
		(end 146.508978 -225.622358)
		(width 0.0889)
		(layer "In2.Cu")
		(net "M_I_CPU1_SA_DQ<11>")
	)
	(segment
		(start 178.534822 -208.499964)
		(end 178.780694 -208.499964)
		(width 0.14478)
		(layer "In2.Cu")
		(net "M_I_CPU1_SA_DQ<11>")
	)
	(segment
		(start 174.650908 -208.525364)
		(end 174.92218 -208.525364)
		(width 0.14478)
		(layer "In2.Cu")
		(net "M_I_CPU1_SA_DQ<11>")
	)
	(segment
		(start 154.279854 -215.796622)
		(end 154.746198 -216.262966)
		(width 0.14478)
		(layer "In2.Cu")
		(net "M_I_CPU1_SA_DQ<11>")
	)
	(segment
		(start 155.136342 -215.872822)
		(end 154.669998 -215.406478)
		(width 0.14478)
		(layer "In2.Cu")
		(net "M_I_CPU1_SA_DQ<11>")
	)
	(segment
		(start 143.077692 -230.39197)
		(end 143.114268 -230.370634)
		(width 0.0889)
		(layer "In2.Cu")
		(net "M_I_CPU1_SA_DQ<11>")
	)
	(segment
		(start 128.507744 -231.201976)
		(end 128.516126 -231.19715)
		(width 0.0889)
		(layer "In2.Cu")
		(net "M_I_CPU1_SA_DQ<11>")
	)
	(segment
		(start 177.422302 -208.499964)
		(end 177.668174 -208.499964)
		(width 0.14478)
		(layer "In2.Cu")
		(net "M_I_CPU1_SA_DQ<11>")
	)
	(segment
		(start 154.36088 -216.886536)
		(end 154.36088 -216.657936)
		(width 0.14478)
		(layer "In2.Cu")
		(net "M_I_CPU1_SA_DQ<11>")
	)
	(segment
		(start 146.92503 -224.322386)
		(end 147.04441 -224.203006)
		(width 0.0889)
		(layer "In2.Cu")
		(net "M_I_CPU1_SA_DQ<11>")
	)
	(segment
		(start 145.39722 -226.35972)
		(end 145.4277 -226.34194)
		(width 0.0889)
		(layer "In2.Cu")
		(net "M_I_CPU1_SA_DQ<11>")
	)
	(segment
		(start 178.780694 -208.499964)
		(end 179.516024 -209.235294)
		(width 0.14478)
		(layer "In2.Cu")
		(net "M_I_CPU1_SA_DQ<11>")
	)
	(segment
		(start 143.547592 -229.581964)
		(end 143.584676 -229.560628)
		(width 0.0889)
		(layer "In2.Cu")
		(net "M_I_CPU1_SA_DQ<11>")
	)
	(segment
		(start 143.985996 -228.790246)
		(end 144.017746 -228.771958)
		(width 0.0889)
		(layer "In2.Cu")
		(net "M_I_CPU1_SA_DQ<11>")
	)
	(segment
		(start 146.508978 -225.622358)
		(end 146.92503 -225.206306)
		(width 0.0889)
		(layer "In2.Cu")
		(net "M_I_CPU1_SA_DQ<11>")
	)
	(segment
		(start 144.457166 -227.979732)
		(end 144.487646 -227.961952)
		(width 0.0889)
		(layer "In2.Cu")
		(net "M_I_CPU1_SA_DQ<11>")
	)
	(segment
		(start 143.584676 -229.560628)
		(end 143.586708 -229.559104)
		(width 0.0889)
		(layer "In2.Cu")
		(net "M_I_CPU1_SA_DQ<11>")
	)
	(segment
		(start 127.754634 -231.524302)
		(end 127.908812 -231.258872)
		(width 0.0889)
		(layer "In2.Cu")
		(net "M_I_CPU1_SA_DQ<11>")
	)
	(segment
		(start 144.9578 -227.151946)
		(end 144.996916 -227.129086)
		(width 0.0889)
		(layer "In2.Cu")
		(net "M_I_CPU1_SA_DQ<11>")
	)
	(segment
		(start 154.051254 -215.796622)
		(end 154.279854 -215.796622)
		(width 0.14478)
		(layer "In2.Cu")
		(net "M_I_CPU1_SA_DQ<11>")
	)
	(segment
		(start 135.453374 -231.19715)
		(end 135.461756 -231.201976)
		(width 0.0889)
		(layer "In2.Cu")
		(net "M_I_CPU1_SA_DQ<11>")
	)
	(segment
		(start 136.393428 -231.19715)
		(end 136.40181 -231.201976)
		(width 0.0889)
		(layer "In2.Cu")
		(net "M_I_CPU1_SA_DQ<11>")
	)
	(segment
		(start 177.668174 -208.499964)
		(end 177.906934 -208.738724)
		(width 0.14478)
		(layer "In2.Cu")
		(net "M_I_CPU1_SA_DQ<11>")
	)
	(segment
		(start 144.017746 -228.771958)
		(end 144.056862 -228.749098)
		(width 0.0889)
		(layer "In2.Cu")
		(net "M_I_CPU1_SA_DQ<11>")
	)
	(segment
		(start 133.20776 -231.201976)
		(end 133.216142 -231.19715)
		(width 0.0889)
		(layer "In2.Cu")
		(net "M_I_CPU1_SA_DQ<11>")
	)
	(segment
		(start 154.36088 -216.657936)
		(end 153.88971 -216.186766)
		(width 0.14478)
		(layer "In2.Cu")
		(net "M_I_CPU1_SA_DQ<11>")
	)
	(segment
		(start 169.930064 -208.499964)
		(end 171.080684 -209.650584)
		(width 0.14478)
		(layer "In2.Cu")
		(net "M_I_CPU1_SA_DQ<11>")
	)
	(segment
		(start 160.197292 -209.650584)
		(end 165.987222 -209.650584)
		(width 0.14478)
		(layer "In2.Cu")
		(net "M_I_CPU1_SA_DQ<11>")
	)
	(segment
		(start 178.296062 -208.738724)
		(end 178.534822 -208.499964)
		(width 0.14478)
		(layer "In2.Cu")
		(net "M_I_CPU1_SA_DQ<11>")
	)
	(segment
		(start 145.632678 -226.15271)
		(end 146.16303 -225.622358)
		(width 0.0889)
		(layer "In2.Cu")
		(net "M_I_CPU1_SA_DQ<11>")
	)
	(segment
		(start 177.121566 -208.8007)
		(end 177.422302 -208.499964)
		(width 0.14478)
		(layer "In2.Cu")
		(net "M_I_CPU1_SA_DQ<11>")
	)
	(segment
		(start 153.88971 -216.186766)
		(end 153.88971 -215.958166)
		(width 0.14478)
		(layer "In2.Cu")
		(net "M_I_CPU1_SA_DQ<11>")
	)
	(segment
		(start 127.908812 -231.258872)
		(end 128.00457 -231.233472)
		(width 0.0889)
		(layer "In2.Cu")
		(net "M_I_CPU1_SA_DQ<11>")
	)
	(segment
		(start 137.907776 -231.201976)
		(end 137.916158 -231.19715)
		(width 0.0889)
		(layer "In2.Cu")
		(net "M_I_CPU1_SA_DQ<11>")
	)
	(segment
		(start 154.974798 -216.262966)
		(end 155.136342 -216.101422)
		(width 0.14478)
		(layer "In2.Cu")
		(net "M_I_CPU1_SA_DQ<11>")
	)
	(segment
		(start 169.383456 -208.8007)
		(end 169.684192 -208.499964)
		(width 0.14478)
		(layer "In2.Cu")
		(net "M_I_CPU1_SA_DQ<11>")
	)
	(segment
		(start 142.607792 -231.201976)
		(end 142.644114 -231.180894)
		(width 0.0889)
		(layer "In2.Cu")
		(net "M_I_CPU1_SA_DQ<11>")
	)
	(segment
		(start 177.906934 -208.738724)
		(end 178.296062 -208.738724)
		(width 0.14478)
		(layer "In2.Cu")
		(net "M_I_CPU1_SA_DQ<11>")
	)
	(segment
		(start 136.967722 -231.201976)
		(end 136.976104 -231.19715)
		(width 0.0889)
		(layer "In2.Cu")
		(net "M_I_CPU1_SA_DQ<11>")
	)
	(segment
		(start 143.045942 -230.410258)
		(end 143.077692 -230.39197)
		(width 0.0889)
		(layer "In2.Cu")
		(net "M_I_CPU1_SA_DQ<11>")
	)
	(segment
		(start 132.267706 -231.201976)
		(end 132.276088 -231.19715)
		(width 0.0889)
		(layer "In2.Cu")
		(net "M_I_CPU1_SA_DQ<11>")
	)
	(segment
		(start 144.487646 -227.961952)
		(end 144.526762 -227.939092)
		(width 0.0889)
		(layer "In2.Cu")
		(net "M_I_CPU1_SA_DQ<11>")
	)
	(segment
		(start 154.746198 -216.262966)
		(end 154.974798 -216.262966)
		(width 0.14478)
		(layer "In2.Cu")
		(net "M_I_CPU1_SA_DQ<11>")
	)
	(segment
		(start 154.669998 -215.406478)
		(end 154.669998 -215.177878)
		(width 0.14478)
		(layer "In2.Cu")
		(net "M_I_CPU1_SA_DQ<11>")
	)
	(segment
		(start 141.667738 -231.201976)
		(end 141.67612 -231.19715)
		(width 0.0889)
		(layer "In2.Cu")
		(net "M_I_CPU1_SA_DQ<11>")
	)
	(segment
		(start 167.137842 -208.499964)
		(end 167.383714 -208.499964)
		(width 0.14478)
		(layer "In2.Cu")
		(net "M_I_CPU1_SA_DQ<11>")
	)
	(segment
		(start 140.15339 -231.19715)
		(end 140.161772 -231.201976)
		(width 0.0889)
		(layer "In2.Cu")
		(net "M_I_CPU1_SA_DQ<11>")
	)
	(segment
		(start 144.92605 -227.170234)
		(end 144.9578 -227.151946)
		(width 0.0889)
		(layer "In2.Cu")
		(net "M_I_CPU1_SA_DQ<11>")
	)
	(segment
		(start 171.080684 -209.650584)
		(end 173.525688 -209.650584)
		(width 0.14478)
		(layer "In2.Cu")
		(net "M_I_CPU1_SA_DQ<11>")
	)
	(arc
		(start 128.516126 -231.19715)
		(mid 128.699634 -231.151625)
		(end 128.881886 -231.201976)
		(width 0.0889)
		(layer "In2.Cu")
		(net "M_I_CPU1_SA_DQ<11>")
	)
	(arc
		(start 129.821686 -231.201976)
		(mid 130.104642 -231.278153)
		(end 130.387598 -231.201976)
		(width 0.0889)
		(layer "In2.Cu")
		(net "M_I_CPU1_SA_DQ<11>")
	)
	(arc
		(start 144.056862 -228.749098)
		(mid 144.235675 -228.546748)
		(end 144.300194 -228.284532)
		(width 0.0889)
		(layer "In2.Cu")
		(net "M_I_CPU1_SA_DQ<11>")
	)
	(arc
		(start 137.341864 -231.201976)
		(mid 137.62482 -231.278153)
		(end 137.907776 -231.201976)
		(width 0.0889)
		(layer "In2.Cu")
		(net "M_I_CPU1_SA_DQ<11>")
	)
	(arc
		(start 131.701794 -231.201976)
		(mid 131.98475 -231.278153)
		(end 132.267706 -231.201976)
		(width 0.0889)
		(layer "In2.Cu")
		(net "M_I_CPU1_SA_DQ<11>")
	)
	(arc
		(start 144.300194 -228.284532)
		(mid 144.341743 -228.11311)
		(end 144.457166 -227.979732)
		(width 0.0889)
		(layer "In2.Cu")
		(net "M_I_CPU1_SA_DQ<11>")
	)
	(arc
		(start 131.327652 -231.201976)
		(mid 131.509903 -231.151592)
		(end 131.693412 -231.19715)
		(width 0.0889)
		(layer "In2.Cu")
		(net "M_I_CPU1_SA_DQ<11>")
	)
	(arc
		(start 130.387598 -231.201976)
		(mid 130.569849 -231.151592)
		(end 130.753358 -231.19715)
		(width 0.0889)
		(layer "In2.Cu")
		(net "M_I_CPU1_SA_DQ<11>")
	)
	(arc
		(start 144.996916 -227.129086)
		(mid 145.175729 -226.926736)
		(end 145.240248 -226.66452)
		(width 0.0889)
		(layer "In2.Cu")
		(net "M_I_CPU1_SA_DQ<11>")
	)
	(arc
		(start 128.00457 -231.233472)
		(mid 128.259892 -231.277172)
		(end 128.507744 -231.201976)
		(width 0.0889)
		(layer "In2.Cu")
		(net "M_I_CPU1_SA_DQ<11>")
	)
	(arc
		(start 134.147814 -231.201976)
		(mid 134.334758 -231.151687)
		(end 134.521702 -231.201976)
		(width 0.0889)
		(layer "In2.Cu")
		(net "M_I_CPU1_SA_DQ<11>")
	)
	(arc
		(start 140.727684 -231.201976)
		(mid 140.909935 -231.151592)
		(end 141.093444 -231.19715)
		(width 0.0889)
		(layer "In2.Cu")
		(net "M_I_CPU1_SA_DQ<11>")
	)
	(arc
		(start 143.36014 -229.90429)
		(mid 143.401106 -229.733884)
		(end 143.51508 -229.60076)
		(width 0.0889)
		(layer "In2.Cu")
		(net "M_I_CPU1_SA_DQ<11>")
	)
	(arc
		(start 136.976104 -231.19715)
		(mid 137.159612 -231.151625)
		(end 137.341864 -231.201976)
		(width 0.0889)
		(layer "In2.Cu")
		(net "M_I_CPU1_SA_DQ<11>")
	)
	(arc
		(start 142.04188 -231.201976)
		(mid 142.324836 -231.278153)
		(end 142.607792 -231.201976)
		(width 0.0889)
		(layer "In2.Cu")
		(net "M_I_CPU1_SA_DQ<11>")
	)
	(arc
		(start 145.579084 -226.217988)
		(mid 145.604281 -226.184036)
		(end 145.632678 -226.15271)
		(width 0.0889)
		(layer "In2.Cu")
		(net "M_I_CPU1_SA_DQ<11>")
	)
	(arc
		(start 141.101826 -231.201976)
		(mid 141.384782 -231.278153)
		(end 141.667738 -231.201976)
		(width 0.0889)
		(layer "In2.Cu")
		(net "M_I_CPU1_SA_DQ<11>")
	)
	(arc
		(start 141.67612 -231.19715)
		(mid 141.859628 -231.151625)
		(end 142.04188 -231.201976)
		(width 0.0889)
		(layer "In2.Cu")
		(net "M_I_CPU1_SA_DQ<11>")
	)
	(arc
		(start 136.027668 -231.201976)
		(mid 136.209919 -231.151592)
		(end 136.393428 -231.19715)
		(width 0.0889)
		(layer "In2.Cu")
		(net "M_I_CPU1_SA_DQ<11>")
	)
	(arc
		(start 133.581902 -231.201976)
		(mid 133.864858 -231.278153)
		(end 134.147814 -231.201976)
		(width 0.0889)
		(layer "In2.Cu")
		(net "M_I_CPU1_SA_DQ<11>")
	)
	(arc
		(start 144.770094 -227.474526)
		(mid 144.811349 -227.303555)
		(end 144.92605 -227.170234)
		(width 0.0889)
		(layer "In2.Cu")
		(net "M_I_CPU1_SA_DQ<11>")
	)
	(arc
		(start 143.586708 -229.559104)
		(mid 143.765521 -229.356754)
		(end 143.83004 -229.094538)
		(width 0.0889)
		(layer "In2.Cu")
		(net "M_I_CPU1_SA_DQ<11>")
	)
	(arc
		(start 137.916158 -231.19715)
		(mid 138.099666 -231.151625)
		(end 138.281918 -231.201976)
		(width 0.0889)
		(layer "In2.Cu")
		(net "M_I_CPU1_SA_DQ<11>")
	)
	(arc
		(start 130.76174 -231.201976)
		(mid 131.044696 -231.278153)
		(end 131.327652 -231.201976)
		(width 0.0889)
		(layer "In2.Cu")
		(net "M_I_CPU1_SA_DQ<11>")
	)
	(arc
		(start 134.521702 -231.201976)
		(mid 134.804658 -231.278153)
		(end 135.087614 -231.201976)
		(width 0.0889)
		(layer "In2.Cu")
		(net "M_I_CPU1_SA_DQ<11>")
	)
	(arc
		(start 136.40181 -231.201976)
		(mid 136.684766 -231.278153)
		(end 136.967722 -231.201976)
		(width 0.0889)
		(layer "In2.Cu")
		(net "M_I_CPU1_SA_DQ<11>")
	)
	(arc
		(start 129.447798 -231.201976)
		(mid 129.634742 -231.151687)
		(end 129.821686 -231.201976)
		(width 0.0889)
		(layer "In2.Cu")
		(net "M_I_CPU1_SA_DQ<11>")
	)
	(arc
		(start 132.276088 -231.19715)
		(mid 132.459596 -231.151625)
		(end 132.641848 -231.201976)
		(width 0.0889)
		(layer "In2.Cu")
		(net "M_I_CPU1_SA_DQ<11>")
	)
	(arc
		(start 135.461756 -231.201976)
		(mid 135.744712 -231.278153)
		(end 136.027668 -231.201976)
		(width 0.0889)
		(layer "In2.Cu")
		(net "M_I_CPU1_SA_DQ<11>")
	)
	(arc
		(start 138.84783 -231.201976)
		(mid 139.034774 -231.151687)
		(end 139.221718 -231.201976)
		(width 0.0889)
		(layer "In2.Cu")
		(net "M_I_CPU1_SA_DQ<11>")
	)
	(arc
		(start 138.281918 -231.201976)
		(mid 138.564874 -231.278153)
		(end 138.84783 -231.201976)
		(width 0.0889)
		(layer "In2.Cu")
		(net "M_I_CPU1_SA_DQ<11>")
	)
	(arc
		(start 143.83004 -229.094538)
		(mid 143.871295 -228.923567)
		(end 143.985996 -228.790246)
		(width 0.0889)
		(layer "In2.Cu")
		(net "M_I_CPU1_SA_DQ<11>")
	)
	(arc
		(start 144.526762 -227.939092)
		(mid 144.705575 -227.736742)
		(end 144.770094 -227.474526)
		(width 0.0889)
		(layer "In2.Cu")
		(net "M_I_CPU1_SA_DQ<11>")
	)
	(arc
		(start 128.881886 -231.201976)
		(mid 129.164842 -231.278153)
		(end 129.447798 -231.201976)
		(width 0.0889)
		(layer "In2.Cu")
		(net "M_I_CPU1_SA_DQ<11>")
	)
	(arc
		(start 133.216142 -231.19715)
		(mid 133.39965 -231.151625)
		(end 133.581902 -231.201976)
		(width 0.0889)
		(layer "In2.Cu")
		(net "M_I_CPU1_SA_DQ<11>")
	)
	(arc
		(start 142.644114 -231.180894)
		(mid 142.824766 -230.978149)
		(end 142.889986 -230.71455)
		(width 0.0889)
		(layer "In2.Cu")
		(net "M_I_CPU1_SA_DQ<11>")
	)
	(arc
		(start 139.78763 -231.201976)
		(mid 139.969881 -231.151592)
		(end 140.15339 -231.19715)
		(width 0.0889)
		(layer "In2.Cu")
		(net "M_I_CPU1_SA_DQ<11>")
	)
	(arc
		(start 145.52549 -226.283266)
		(mid 145.553887 -226.251941)
		(end 145.579084 -226.217988)
		(width 0.0889)
		(layer "In2.Cu")
		(net "M_I_CPU1_SA_DQ<11>")
	)
	(arc
		(start 142.889986 -230.71455)
		(mid 142.931241 -230.543579)
		(end 143.045942 -230.410258)
		(width 0.0889)
		(layer "In2.Cu")
		(net "M_I_CPU1_SA_DQ<11>")
	)
	(arc
		(start 139.221718 -231.201976)
		(mid 139.504674 -231.278153)
		(end 139.78763 -231.201976)
		(width 0.0889)
		(layer "In2.Cu")
		(net "M_I_CPU1_SA_DQ<11>")
	)
	(arc
		(start 132.641848 -231.201976)
		(mid 132.924804 -231.278153)
		(end 133.20776 -231.201976)
		(width 0.0889)
		(layer "In2.Cu")
		(net "M_I_CPU1_SA_DQ<11>")
	)
	(arc
		(start 145.240248 -226.66452)
		(mid 145.281797 -226.493098)
		(end 145.39722 -226.35972)
		(width 0.0889)
		(layer "In2.Cu")
		(net "M_I_CPU1_SA_DQ<11>")
	)
	(arc
		(start 143.114268 -230.370634)
		(mid 143.29492 -230.167889)
		(end 143.36014 -229.90429)
		(width 0.0889)
		(layer "In2.Cu")
		(net "M_I_CPU1_SA_DQ<11>")
	)
	(arc
		(start 140.161772 -231.201976)
		(mid 140.444728 -231.278153)
		(end 140.727684 -231.201976)
		(width 0.0889)
		(layer "In2.Cu")
		(net "M_I_CPU1_SA_DQ<11>")
	)
	(arc
		(start 145.4277 -226.34194)
		(mid 145.480232 -226.318655)
		(end 145.52549 -226.283266)
		(width 0.0889)
		(layer "In2.Cu")
		(net "M_I_CPU1_SA_DQ<11>")
	)
	(arc
		(start 135.087614 -231.201976)
		(mid 135.269865 -231.151592)
		(end 135.453374 -231.19715)
		(width 0.0889)
		(layer "In2.Cu")
		(net "M_I_CPU1_SA_DQ<11>")
	)
	(segment
		(start 128.69799 -230.980234)
		(end 129.164842 -230.71455)
		(width 0.10668)
		(layer "F.Cu")
		(net "M_I_CPU1_SA_DQ<10>")
	)
	(segment
		(start 143.077692 -228.771958)
		(end 143.116808 -228.749098)
		(width 0.0889)
		(layer "In2.Cu")
		(net "M_I_CPU1_SA_DQ<10>")
	)
	(segment
		(start 151.422608 -218.223084)
		(end 151.02078 -217.821256)
		(width 0.14478)
		(layer "In2.Cu")
		(net "M_I_CPU1_SA_DQ<10>")
	)
	(segment
		(start 146.342608 -223.115632)
		(end 146.368262 -223.1009)
		(width 0.0889)
		(layer "In2.Cu")
		(net "M_I_CPU1_SA_DQ<10>")
	)
	(segment
		(start 144.017746 -227.151946)
		(end 144.056862 -227.129086)
		(width 0.0889)
		(layer "In2.Cu")
		(net "M_I_CPU1_SA_DQ<10>")
	)
	(segment
		(start 152.191212 -216.650824)
		(end 152.59304 -217.052652)
		(width 0.14478)
		(layer "In2.Cu")
		(net "M_I_CPU1_SA_DQ<10>")
	)
	(segment
		(start 145.3896 -224.743518)
		(end 145.428462 -224.720912)
		(width 0.0889)
		(layer "In2.Cu")
		(net "M_I_CPU1_SA_DQ<10>")
	)
	(segment
		(start 151.962612 -216.650824)
		(end 152.191212 -216.650824)
		(width 0.14478)
		(layer "In2.Cu")
		(net "M_I_CPU1_SA_DQ<10>")
	)
	(segment
		(start 146.368262 -223.1009)
		(end 147.284948 -222.589344)
		(width 0.0889)
		(layer "In2.Cu")
		(net "M_I_CPU1_SA_DQ<10>")
	)
	(segment
		(start 173.640496 -207.960468)
		(end 174.490634 -207.11033)
		(width 0.14478)
		(layer "In2.Cu")
		(net "M_I_CPU1_SA_DQ<10>")
	)
	(segment
		(start 144.9578 -225.531934)
		(end 145.001996 -225.50628)
		(width 0.0889)
		(layer "In2.Cu")
		(net "M_I_CPU1_SA_DQ<10>")
	)
	(segment
		(start 129.164842 -230.71455)
		(end 129.318766 -230.44912)
		(width 0.0889)
		(layer "In2.Cu")
		(net "M_I_CPU1_SA_DQ<10>")
	)
	(segment
		(start 152.82164 -217.052652)
		(end 152.99055 -216.883742)
		(width 0.14478)
		(layer "In2.Cu")
		(net "M_I_CPU1_SA_DQ<10>")
	)
	(segment
		(start 177.921666 -207.504538)
		(end 178.152298 -207.504538)
		(width 0.14478)
		(layer "In2.Cu")
		(net "M_I_CPU1_SA_DQ<10>")
	)
	(segment
		(start 144.487646 -226.34194)
		(end 144.526762 -226.31908)
		(width 0.0889)
		(layer "In2.Cu")
		(net "M_I_CPU1_SA_DQ<10>")
	)
	(segment
		(start 135.557768 -230.39197)
		(end 135.56615 -230.387144)
		(width 0.0889)
		(layer "In2.Cu")
		(net "M_I_CPU1_SA_DQ<10>")
	)
	(segment
		(start 142.137638 -230.39197)
		(end 142.174214 -230.370634)
		(width 0.0889)
		(layer "In2.Cu")
		(net "M_I_CPU1_SA_DQ<10>")
	)
	(segment
		(start 177.758852 -206.89062)
		(end 177.758852 -207.341724)
		(width 0.14478)
		(layer "In2.Cu")
		(net "M_I_CPU1_SA_DQ<10>")
	)
	(segment
		(start 178.315112 -206.89062)
		(end 178.477926 -206.727806)
		(width 0.14478)
		(layer "In2.Cu")
		(net "M_I_CPU1_SA_DQ<10>")
	)
	(segment
		(start 144.457166 -226.35972)
		(end 144.487646 -226.34194)
		(width 0.0889)
		(layer "In2.Cu")
		(net "M_I_CPU1_SA_DQ<10>")
	)
	(segment
		(start 143.517112 -227.979732)
		(end 143.547592 -227.961952)
		(width 0.0889)
		(layer "In2.Cu")
		(net "M_I_CPU1_SA_DQ<10>")
	)
	(segment
		(start 152.99055 -215.585294)
		(end 160.615376 -207.960468)
		(width 0.14478)
		(layer "In2.Cu")
		(net "M_I_CPU1_SA_DQ<10>")
	)
	(segment
		(start 130.857752 -230.39197)
		(end 130.866134 -230.387144)
		(width 0.0889)
		(layer "In2.Cu")
		(net "M_I_CPU1_SA_DQ<10>")
	)
	(segment
		(start 178.477926 -206.727806)
		(end 178.708558 -206.727806)
		(width 0.14478)
		(layer "In2.Cu")
		(net "M_I_CPU1_SA_DQ<10>")
	)
	(segment
		(start 147.284948 -222.589344)
		(end 151.422608 -218.451684)
		(width 0.14478)
		(layer "In2.Cu")
		(net "M_I_CPU1_SA_DQ<10>")
	)
	(segment
		(start 139.31773 -230.39197)
		(end 139.326112 -230.387144)
		(width 0.0889)
		(layer "In2.Cu")
		(net "M_I_CPU1_SA_DQ<10>")
	)
	(segment
		(start 152.202896 -217.671396)
		(end 152.202896 -217.442796)
		(width 0.14478)
		(layer "In2.Cu")
		(net "M_I_CPU1_SA_DQ<10>")
	)
	(segment
		(start 140.257784 -230.39197)
		(end 140.266166 -230.387144)
		(width 0.0889)
		(layer "In2.Cu")
		(net "M_I_CPU1_SA_DQ<10>")
	)
	(segment
		(start 143.547592 -227.961952)
		(end 143.586708 -227.939092)
		(width 0.0889)
		(layer "In2.Cu")
		(net "M_I_CPU1_SA_DQ<10>")
	)
	(segment
		(start 167.149272 -207.11033)
		(end 169.942002 -207.11033)
		(width 0.14478)
		(layer "In2.Cu")
		(net "M_I_CPU1_SA_DQ<10>")
	)
	(segment
		(start 129.917698 -230.39197)
		(end 129.92608 -230.387144)
		(width 0.0889)
		(layer "In2.Cu")
		(net "M_I_CPU1_SA_DQ<10>")
	)
	(segment
		(start 177.758852 -207.341724)
		(end 177.921666 -207.504538)
		(width 0.14478)
		(layer "In2.Cu")
		(net "M_I_CPU1_SA_DQ<10>")
	)
	(segment
		(start 134.04342 -230.387144)
		(end 134.051802 -230.39197)
		(width 0.0889)
		(layer "In2.Cu")
		(net "M_I_CPU1_SA_DQ<10>")
	)
	(segment
		(start 151.02078 -217.592656)
		(end 151.182324 -217.431112)
		(width 0.14478)
		(layer "In2.Cu")
		(net "M_I_CPU1_SA_DQ<10>")
	)
	(segment
		(start 142.574264 -229.601522)
		(end 142.607792 -229.581964)
		(width 0.0889)
		(layer "In2.Cu")
		(net "M_I_CPU1_SA_DQ<10>")
	)
	(segment
		(start 177.365406 -206.727806)
		(end 177.596038 -206.727806)
		(width 0.14478)
		(layer "In2.Cu")
		(net "M_I_CPU1_SA_DQ<10>")
	)
	(segment
		(start 137.803382 -230.387144)
		(end 137.811764 -230.39197)
		(width 0.0889)
		(layer "In2.Cu")
		(net "M_I_CPU1_SA_DQ<10>")
	)
	(segment
		(start 177.202592 -206.89062)
		(end 177.365406 -206.727806)
		(width 0.14478)
		(layer "In2.Cu")
		(net "M_I_CPU1_SA_DQ<10>")
	)
	(segment
		(start 151.02078 -217.821256)
		(end 151.02078 -217.592656)
		(width 0.14478)
		(layer "In2.Cu")
		(net "M_I_CPU1_SA_DQ<10>")
	)
	(segment
		(start 178.152298 -207.504538)
		(end 178.315112 -207.341724)
		(width 0.14478)
		(layer "In2.Cu")
		(net "M_I_CPU1_SA_DQ<10>")
	)
	(segment
		(start 151.801068 -217.040968)
		(end 151.801068 -216.812368)
		(width 0.14478)
		(layer "In2.Cu")
		(net "M_I_CPU1_SA_DQ<10>")
	)
	(segment
		(start 143.985996 -227.170234)
		(end 144.017746 -227.151946)
		(width 0.0889)
		(layer "In2.Cu")
		(net "M_I_CPU1_SA_DQ<10>")
	)
	(segment
		(start 176.809146 -207.504538)
		(end 177.039778 -207.504538)
		(width 0.14478)
		(layer "In2.Cu")
		(net "M_I_CPU1_SA_DQ<10>")
	)
	(segment
		(start 145.428462 -224.720912)
		(end 145.472658 -224.695258)
		(width 0.0889)
		(layer "In2.Cu")
		(net "M_I_CPU1_SA_DQ<10>")
	)
	(segment
		(start 151.182324 -217.431112)
		(end 151.410924 -217.431112)
		(width 0.14478)
		(layer "In2.Cu")
		(net "M_I_CPU1_SA_DQ<10>")
	)
	(segment
		(start 134.617714 -230.39197)
		(end 134.626096 -230.387144)
		(width 0.0889)
		(layer "In2.Cu")
		(net "M_I_CPU1_SA_DQ<10>")
	)
	(segment
		(start 151.801068 -216.812368)
		(end 151.962612 -216.650824)
		(width 0.14478)
		(layer "In2.Cu")
		(net "M_I_CPU1_SA_DQ<10>")
	)
	(segment
		(start 145.8976 -223.911922)
		(end 145.936716 -223.889062)
		(width 0.0889)
		(layer "In2.Cu")
		(net "M_I_CPU1_SA_DQ<10>")
	)
	(segment
		(start 169.942002 -207.11033)
		(end 170.79214 -207.960468)
		(width 0.14478)
		(layer "In2.Cu")
		(net "M_I_CPU1_SA_DQ<10>")
	)
	(segment
		(start 144.92605 -225.550222)
		(end 144.9578 -225.531934)
		(width 0.0889)
		(layer "In2.Cu")
		(net "M_I_CPU1_SA_DQ<10>")
	)
	(segment
		(start 152.59304 -217.052652)
		(end 152.82164 -217.052652)
		(width 0.14478)
		(layer "In2.Cu")
		(net "M_I_CPU1_SA_DQ<10>")
	)
	(segment
		(start 177.202592 -207.341724)
		(end 177.202592 -206.89062)
		(width 0.14478)
		(layer "In2.Cu")
		(net "M_I_CPU1_SA_DQ<10>")
	)
	(segment
		(start 152.041352 -217.83294)
		(end 152.202896 -217.671396)
		(width 0.14478)
		(layer "In2.Cu")
		(net "M_I_CPU1_SA_DQ<10>")
	)
	(segment
		(start 166.299134 -207.960468)
		(end 167.149272 -207.11033)
		(width 0.14478)
		(layer "In2.Cu")
		(net "M_I_CPU1_SA_DQ<10>")
	)
	(segment
		(start 151.422608 -218.451684)
		(end 151.422608 -218.223084)
		(width 0.14478)
		(layer "In2.Cu")
		(net "M_I_CPU1_SA_DQ<10>")
	)
	(segment
		(start 129.318766 -230.44912)
		(end 129.414778 -230.42372)
		(width 0.0889)
		(layer "In2.Cu")
		(net "M_I_CPU1_SA_DQ<10>")
	)
	(segment
		(start 160.615376 -207.960468)
		(end 166.299134 -207.960468)
		(width 0.14478)
		(layer "In2.Cu")
		(net "M_I_CPU1_SA_DQ<10>")
	)
	(segment
		(start 145.86712 -223.929702)
		(end 145.8976 -223.911922)
		(width 0.0889)
		(layer "In2.Cu")
		(net "M_I_CPU1_SA_DQ<10>")
	)
	(segment
		(start 152.202896 -217.442796)
		(end 151.801068 -217.040968)
		(width 0.14478)
		(layer "In2.Cu")
		(net "M_I_CPU1_SA_DQ<10>")
	)
	(segment
		(start 151.410924 -217.431112)
		(end 151.812752 -217.83294)
		(width 0.14478)
		(layer "In2.Cu")
		(net "M_I_CPU1_SA_DQ<10>")
	)
	(segment
		(start 177.039778 -207.504538)
		(end 177.202592 -207.341724)
		(width 0.14478)
		(layer "In2.Cu")
		(net "M_I_CPU1_SA_DQ<10>")
	)
	(segment
		(start 138.743436 -230.387144)
		(end 138.751818 -230.39197)
		(width 0.0889)
		(layer "In2.Cu")
		(net "M_I_CPU1_SA_DQ<10>")
	)
	(segment
		(start 178.315112 -207.341724)
		(end 178.315112 -206.89062)
		(width 0.14478)
		(layer "In2.Cu")
		(net "M_I_CPU1_SA_DQ<10>")
	)
	(segment
		(start 176.414938 -207.11033)
		(end 176.809146 -207.504538)
		(width 0.14478)
		(layer "In2.Cu")
		(net "M_I_CPU1_SA_DQ<10>")
	)
	(segment
		(start 142.607792 -229.581964)
		(end 142.644114 -229.560882)
		(width 0.0889)
		(layer "In2.Cu")
		(net "M_I_CPU1_SA_DQ<10>")
	)
	(segment
		(start 178.708558 -206.727806)
		(end 179.516024 -207.535272)
		(width 0.14478)
		(layer "In2.Cu")
		(net "M_I_CPU1_SA_DQ<10>")
	)
	(segment
		(start 143.045942 -228.790246)
		(end 143.077692 -228.771958)
		(width 0.0889)
		(layer "In2.Cu")
		(net "M_I_CPU1_SA_DQ<10>")
	)
	(segment
		(start 152.99055 -216.883742)
		(end 152.99055 -215.585294)
		(width 0.14478)
		(layer "In2.Cu")
		(net "M_I_CPU1_SA_DQ<10>")
	)
	(segment
		(start 174.490634 -207.11033)
		(end 176.414938 -207.11033)
		(width 0.14478)
		(layer "In2.Cu")
		(net "M_I_CPU1_SA_DQ<10>")
	)
	(segment
		(start 177.596038 -206.727806)
		(end 177.758852 -206.89062)
		(width 0.14478)
		(layer "In2.Cu")
		(net "M_I_CPU1_SA_DQ<10>")
	)
	(segment
		(start 151.812752 -217.83294)
		(end 152.041352 -217.83294)
		(width 0.14478)
		(layer "In2.Cu")
		(net "M_I_CPU1_SA_DQ<10>")
	)
	(segment
		(start 170.79214 -207.960468)
		(end 173.640496 -207.960468)
		(width 0.14478)
		(layer "In2.Cu")
		(net "M_I_CPU1_SA_DQ<10>")
	)
	(segment
		(start 133.103366 -230.387144)
		(end 133.111748 -230.39197)
		(width 0.0889)
		(layer "In2.Cu")
		(net "M_I_CPU1_SA_DQ<10>")
	)
	(arc
		(start 145.240756 -225.043238)
		(mid 145.279909 -224.875863)
		(end 145.3896 -224.743518)
		(width 0.0889)
		(layer "In2.Cu")
		(net "M_I_CPU1_SA_DQ<10>")
	)
	(arc
		(start 138.377676 -230.39197)
		(mid 138.559927 -230.34162)
		(end 138.743436 -230.387144)
		(width 0.0889)
		(layer "In2.Cu")
		(net "M_I_CPU1_SA_DQ<10>")
	)
	(arc
		(start 140.266166 -230.387144)
		(mid 140.449674 -230.34165)
		(end 140.631926 -230.39197)
		(width 0.0889)
		(layer "In2.Cu")
		(net "M_I_CPU1_SA_DQ<10>")
	)
	(arc
		(start 141.197838 -230.39197)
		(mid 141.384782 -230.341715)
		(end 141.571726 -230.39197)
		(width 0.0889)
		(layer "In2.Cu")
		(net "M_I_CPU1_SA_DQ<10>")
	)
	(arc
		(start 136.497822 -230.39197)
		(mid 136.684766 -230.341715)
		(end 136.87171 -230.39197)
		(width 0.0889)
		(layer "In2.Cu")
		(net "M_I_CPU1_SA_DQ<10>")
	)
	(arc
		(start 138.751818 -230.39197)
		(mid 139.034774 -230.468113)
		(end 139.31773 -230.39197)
		(width 0.0889)
		(layer "In2.Cu")
		(net "M_I_CPU1_SA_DQ<10>")
	)
	(arc
		(start 139.326112 -230.387144)
		(mid 139.50962 -230.34165)
		(end 139.691872 -230.39197)
		(width 0.0889)
		(layer "In2.Cu")
		(net "M_I_CPU1_SA_DQ<10>")
	)
	(arc
		(start 131.231894 -230.39197)
		(mid 131.51485 -230.468113)
		(end 131.797806 -230.39197)
		(width 0.0889)
		(layer "In2.Cu")
		(net "M_I_CPU1_SA_DQ<10>")
	)
	(arc
		(start 131.797806 -230.39197)
		(mid 131.98475 -230.341715)
		(end 132.171694 -230.39197)
		(width 0.0889)
		(layer "In2.Cu")
		(net "M_I_CPU1_SA_DQ<10>")
	)
	(arc
		(start 145.001996 -225.50628)
		(mid 145.177829 -225.303868)
		(end 145.240756 -225.043238)
		(width 0.0889)
		(layer "In2.Cu")
		(net "M_I_CPU1_SA_DQ<10>")
	)
	(arc
		(start 143.83004 -227.474526)
		(mid 143.871295 -227.303555)
		(end 143.985996 -227.170234)
		(width 0.0889)
		(layer "In2.Cu")
		(net "M_I_CPU1_SA_DQ<10>")
	)
	(arc
		(start 133.111748 -230.39197)
		(mid 133.394704 -230.468113)
		(end 133.67766 -230.39197)
		(width 0.0889)
		(layer "In2.Cu")
		(net "M_I_CPU1_SA_DQ<10>")
	)
	(arc
		(start 129.92608 -230.387144)
		(mid 130.109588 -230.34165)
		(end 130.29184 -230.39197)
		(width 0.0889)
		(layer "In2.Cu")
		(net "M_I_CPU1_SA_DQ<10>")
	)
	(arc
		(start 143.586708 -227.939092)
		(mid 143.765521 -227.736742)
		(end 143.83004 -227.474526)
		(width 0.0889)
		(layer "In2.Cu")
		(net "M_I_CPU1_SA_DQ<10>")
	)
	(arc
		(start 142.644114 -229.560882)
		(mid 142.824766 -229.358137)
		(end 142.889986 -229.094538)
		(width 0.0889)
		(layer "In2.Cu")
		(net "M_I_CPU1_SA_DQ<10>")
	)
	(arc
		(start 144.056862 -227.129086)
		(mid 144.235675 -226.926736)
		(end 144.300194 -226.66452)
		(width 0.0889)
		(layer "In2.Cu")
		(net "M_I_CPU1_SA_DQ<10>")
	)
	(arc
		(start 134.626096 -230.387144)
		(mid 134.809604 -230.34165)
		(end 134.991856 -230.39197)
		(width 0.0889)
		(layer "In2.Cu")
		(net "M_I_CPU1_SA_DQ<10>")
	)
	(arc
		(start 134.991856 -230.39197)
		(mid 135.274812 -230.468113)
		(end 135.557768 -230.39197)
		(width 0.0889)
		(layer "In2.Cu")
		(net "M_I_CPU1_SA_DQ<10>")
	)
	(arc
		(start 144.526762 -226.31908)
		(mid 144.705575 -226.11673)
		(end 144.770094 -225.854514)
		(width 0.0889)
		(layer "In2.Cu")
		(net "M_I_CPU1_SA_DQ<10>")
	)
	(arc
		(start 143.36014 -228.284532)
		(mid 143.401689 -228.11311)
		(end 143.517112 -227.979732)
		(width 0.0889)
		(layer "In2.Cu")
		(net "M_I_CPU1_SA_DQ<10>")
	)
	(arc
		(start 130.29184 -230.39197)
		(mid 130.574796 -230.468113)
		(end 130.857752 -230.39197)
		(width 0.0889)
		(layer "In2.Cu")
		(net "M_I_CPU1_SA_DQ<10>")
	)
	(arc
		(start 134.051802 -230.39197)
		(mid 134.334758 -230.468113)
		(end 134.617714 -230.39197)
		(width 0.0889)
		(layer "In2.Cu")
		(net "M_I_CPU1_SA_DQ<10>")
	)
	(arc
		(start 137.437622 -230.39197)
		(mid 137.619873 -230.34162)
		(end 137.803382 -230.387144)
		(width 0.0889)
		(layer "In2.Cu")
		(net "M_I_CPU1_SA_DQ<10>")
	)
	(arc
		(start 142.889986 -229.094538)
		(mid 142.931241 -228.923567)
		(end 143.045942 -228.790246)
		(width 0.0889)
		(layer "In2.Cu")
		(net "M_I_CPU1_SA_DQ<10>")
	)
	(arc
		(start 135.56615 -230.387144)
		(mid 135.749658 -230.34165)
		(end 135.93191 -230.39197)
		(width 0.0889)
		(layer "In2.Cu")
		(net "M_I_CPU1_SA_DQ<10>")
	)
	(arc
		(start 130.866134 -230.387144)
		(mid 131.049642 -230.34165)
		(end 131.231894 -230.39197)
		(width 0.0889)
		(layer "In2.Cu")
		(net "M_I_CPU1_SA_DQ<10>")
	)
	(arc
		(start 143.116808 -228.749098)
		(mid 143.295621 -228.546748)
		(end 143.36014 -228.284532)
		(width 0.0889)
		(layer "In2.Cu")
		(net "M_I_CPU1_SA_DQ<10>")
	)
	(arc
		(start 132.171694 -230.39197)
		(mid 132.45465 -230.468113)
		(end 132.737606 -230.39197)
		(width 0.0889)
		(layer "In2.Cu")
		(net "M_I_CPU1_SA_DQ<10>")
	)
	(arc
		(start 136.87171 -230.39197)
		(mid 137.154666 -230.468113)
		(end 137.437622 -230.39197)
		(width 0.0889)
		(layer "In2.Cu")
		(net "M_I_CPU1_SA_DQ<10>")
	)
	(arc
		(start 139.691872 -230.39197)
		(mid 139.974828 -230.468113)
		(end 140.257784 -230.39197)
		(width 0.0889)
		(layer "In2.Cu")
		(net "M_I_CPU1_SA_DQ<10>")
	)
	(arc
		(start 145.710148 -224.234502)
		(mid 145.751697 -224.06308)
		(end 145.86712 -223.929702)
		(width 0.0889)
		(layer "In2.Cu")
		(net "M_I_CPU1_SA_DQ<10>")
	)
	(arc
		(start 144.300194 -226.66452)
		(mid 144.341743 -226.493098)
		(end 144.457166 -226.35972)
		(width 0.0889)
		(layer "In2.Cu")
		(net "M_I_CPU1_SA_DQ<10>")
	)
	(arc
		(start 140.631926 -230.39197)
		(mid 140.914882 -230.468113)
		(end 141.197838 -230.39197)
		(width 0.0889)
		(layer "In2.Cu")
		(net "M_I_CPU1_SA_DQ<10>")
	)
	(arc
		(start 141.571726 -230.39197)
		(mid 141.854682 -230.468113)
		(end 142.137638 -230.39197)
		(width 0.0889)
		(layer "In2.Cu")
		(net "M_I_CPU1_SA_DQ<10>")
	)
	(arc
		(start 135.93191 -230.39197)
		(mid 136.214866 -230.468113)
		(end 136.497822 -230.39197)
		(width 0.0889)
		(layer "In2.Cu")
		(net "M_I_CPU1_SA_DQ<10>")
	)
	(arc
		(start 145.936716 -223.889062)
		(mid 146.115529 -223.686712)
		(end 146.180048 -223.424496)
		(width 0.0889)
		(layer "In2.Cu")
		(net "M_I_CPU1_SA_DQ<10>")
	)
	(arc
		(start 144.770094 -225.854514)
		(mid 144.811349 -225.683543)
		(end 144.92605 -225.550222)
		(width 0.0889)
		(layer "In2.Cu")
		(net "M_I_CPU1_SA_DQ<10>")
	)
	(arc
		(start 142.174214 -230.370634)
		(mid 142.354866 -230.167889)
		(end 142.420086 -229.90429)
		(width 0.0889)
		(layer "In2.Cu")
		(net "M_I_CPU1_SA_DQ<10>")
	)
	(arc
		(start 132.737606 -230.39197)
		(mid 132.919857 -230.34162)
		(end 133.103366 -230.387144)
		(width 0.0889)
		(layer "In2.Cu")
		(net "M_I_CPU1_SA_DQ<10>")
	)
	(arc
		(start 145.472658 -224.695258)
		(mid 145.647296 -224.493687)
		(end 145.710148 -224.234502)
		(width 0.0889)
		(layer "In2.Cu")
		(net "M_I_CPU1_SA_DQ<10>")
	)
	(arc
		(start 137.811764 -230.39197)
		(mid 138.09472 -230.468113)
		(end 138.377676 -230.39197)
		(width 0.0889)
		(layer "In2.Cu")
		(net "M_I_CPU1_SA_DQ<10>")
	)
	(arc
		(start 142.420086 -229.90429)
		(mid 142.460848 -229.734406)
		(end 142.574264 -229.601522)
		(width 0.0889)
		(layer "In2.Cu")
		(net "M_I_CPU1_SA_DQ<10>")
	)
	(arc
		(start 146.180048 -223.424496)
		(mid 146.223173 -223.249986)
		(end 146.342608 -223.115632)
		(width 0.0889)
		(layer "In2.Cu")
		(net "M_I_CPU1_SA_DQ<10>")
	)
	(arc
		(start 133.67766 -230.39197)
		(mid 133.859911 -230.34162)
		(end 134.04342 -230.387144)
		(width 0.0889)
		(layer "In2.Cu")
		(net "M_I_CPU1_SA_DQ<10>")
	)
	(arc
		(start 129.414778 -230.42372)
		(mid 129.669986 -230.467177)
		(end 129.917698 -230.39197)
		(width 0.0889)
		(layer "In2.Cu")
		(net "M_I_CPU1_SA_DQ<10>")
	)
	(segment
		(start 129.16789 -225.310446)
		(end 129.634742 -225.044508)
		(width 0.10668)
		(layer "F.Cu")
		(net "M_I_CPU1_SA_DQ<0>")
	)
	(segment
		(start 159.856932 -197.760336)
		(end 165.190932 -197.760336)
		(width 0.14478)
		(layer "In2.Cu")
		(net "M_I_CPU1_SA_DQ<0>")
	)
	(segment
		(start 145.51787 -213.878922)
		(end 145.51787 -212.099398)
		(width 0.14478)
		(layer "In2.Cu")
		(net "M_I_CPU1_SA_DQ<0>")
	)
	(segment
		(start 169.51198 -196.910452)
		(end 171.563792 -197.760336)
		(width 0.14478)
		(layer "In2.Cu")
		(net "M_I_CPU1_SA_DQ<0>")
	)
	(segment
		(start 174.911766 -196.910452)
		(end 183.19115 -196.910452)
		(width 0.14478)
		(layer "In2.Cu")
		(net "M_I_CPU1_SA_DQ<0>")
	)
	(segment
		(start 141.101572 -222.127064)
		(end 141.132052 -222.109284)
		(width 0.0889)
		(layer "In2.Cu")
		(net "M_I_CPU1_SA_DQ<0>")
	)
	(segment
		(start 140.123926 -223.76892)
		(end 140.161772 -223.747076)
		(width 0.0889)
		(layer "In2.Cu")
		(net "M_I_CPU1_SA_DQ<0>")
	)
	(segment
		(start 129.480818 -225.309938)
		(end 129.50317 -225.39325)
		(width 0.0889)
		(layer "In2.Cu")
		(net "M_I_CPU1_SA_DQ<0>")
	)
	(segment
		(start 136.393428 -225.371914)
		(end 136.40181 -225.367088)
		(width 0.0889)
		(layer "In2.Cu")
		(net "M_I_CPU1_SA_DQ<0>")
	)
	(segment
		(start 145.51787 -212.099398)
		(end 159.856932 -197.760336)
		(width 0.14478)
		(layer "In2.Cu")
		(net "M_I_CPU1_SA_DQ<0>")
	)
	(segment
		(start 130.753358 -225.371914)
		(end 130.76174 -225.367088)
		(width 0.0889)
		(layer "In2.Cu")
		(net "M_I_CPU1_SA_DQ<0>")
	)
	(segment
		(start 140.161772 -223.747076)
		(end 140.191236 -223.730058)
		(width 0.0889)
		(layer "In2.Cu")
		(net "M_I_CPU1_SA_DQ<0>")
	)
	(segment
		(start 136.967722 -225.367088)
		(end 136.976104 -225.371914)
		(width 0.0889)
		(layer "In2.Cu")
		(net "M_I_CPU1_SA_DQ<0>")
	)
	(segment
		(start 141.289024 -221.804484)
		(end 141.17701 -221.174564)
		(width 0.0889)
		(layer "In2.Cu")
		(net "M_I_CPU1_SA_DQ<0>")
	)
	(segment
		(start 132.267706 -225.367088)
		(end 132.276088 -225.371914)
		(width 0.0889)
		(layer "In2.Cu")
		(net "M_I_CPU1_SA_DQ<0>")
	)
	(segment
		(start 172.859954 -197.760336)
		(end 174.911766 -196.910452)
		(width 0.14478)
		(layer "In2.Cu")
		(net "M_I_CPU1_SA_DQ<0>")
	)
	(segment
		(start 165.190932 -197.760336)
		(end 166.040816 -196.910452)
		(width 0.14478)
		(layer "In2.Cu")
		(net "M_I_CPU1_SA_DQ<0>")
	)
	(segment
		(start 171.563792 -197.760336)
		(end 172.859954 -197.760336)
		(width 0.14478)
		(layer "In2.Cu")
		(net "M_I_CPU1_SA_DQ<0>")
	)
	(segment
		(start 139.652756 -224.579942)
		(end 139.691872 -224.557082)
		(width 0.0889)
		(layer "In2.Cu")
		(net "M_I_CPU1_SA_DQ<0>")
	)
	(segment
		(start 135.453374 -225.371914)
		(end 135.461756 -225.367088)
		(width 0.0889)
		(layer "In2.Cu")
		(net "M_I_CPU1_SA_DQ<0>")
	)
	(segment
		(start 183.19115 -196.910452)
		(end 183.616092 -197.335394)
		(width 0.14478)
		(layer "In2.Cu")
		(net "M_I_CPU1_SA_DQ<0>")
	)
	(segment
		(start 139.691872 -224.557082)
		(end 139.722352 -224.539302)
		(width 0.0889)
		(layer "In2.Cu")
		(net "M_I_CPU1_SA_DQ<0>")
	)
	(segment
		(start 137.907776 -225.367088)
		(end 137.916158 -225.371914)
		(width 0.0889)
		(layer "In2.Cu")
		(net "M_I_CPU1_SA_DQ<0>")
	)
	(segment
		(start 133.20776 -225.367088)
		(end 133.216142 -225.371914)
		(width 0.0889)
		(layer "In2.Cu")
		(net "M_I_CPU1_SA_DQ<0>")
	)
	(segment
		(start 139.221718 -225.367088)
		(end 139.253468 -225.3488)
		(width 0.0889)
		(layer "In2.Cu")
		(net "M_I_CPU1_SA_DQ<0>")
	)
	(segment
		(start 141.17701 -218.219782)
		(end 145.51787 -213.878922)
		(width 0.14478)
		(layer "In2.Cu")
		(net "M_I_CPU1_SA_DQ<0>")
	)
	(segment
		(start 141.17701 -221.174564)
		(end 141.17701 -218.219782)
		(width 0.14478)
		(layer "In2.Cu")
		(net "M_I_CPU1_SA_DQ<0>")
	)
	(segment
		(start 141.06398 -222.148908)
		(end 141.101572 -222.127064)
		(width 0.0889)
		(layer "In2.Cu")
		(net "M_I_CPU1_SA_DQ<0>")
	)
	(segment
		(start 166.040816 -196.910452)
		(end 169.51198 -196.910452)
		(width 0.14478)
		(layer "In2.Cu")
		(net "M_I_CPU1_SA_DQ<0>")
	)
	(segment
		(start 129.634742 -225.044508)
		(end 129.480818 -225.309938)
		(width 0.0889)
		(layer "In2.Cu")
		(net "M_I_CPU1_SA_DQ<0>")
	)
	(segment
		(start 140.593826 -222.958914)
		(end 140.631672 -222.93707)
		(width 0.0889)
		(layer "In2.Cu")
		(net "M_I_CPU1_SA_DQ<0>")
	)
	(segment
		(start 140.631672 -222.93707)
		(end 140.663422 -222.918782)
		(width 0.0889)
		(layer "In2.Cu")
		(net "M_I_CPU1_SA_DQ<0>")
	)
	(segment
		(start 131.693412 -225.371914)
		(end 131.701794 -225.367088)
		(width 0.0889)
		(layer "In2.Cu")
		(net "M_I_CPU1_SA_DQ<0>")
	)
	(arc
		(start 137.916158 -225.371914)
		(mid 138.099666 -225.417408)
		(end 138.281918 -225.367088)
		(width 0.0889)
		(layer "In2.Cu")
		(net "M_I_CPU1_SA_DQ<0>")
	)
	(arc
		(start 139.253468 -225.3488)
		(mid 139.368144 -225.215466)
		(end 139.409424 -225.044508)
		(width 0.0889)
		(layer "In2.Cu")
		(net "M_I_CPU1_SA_DQ<0>")
	)
	(arc
		(start 134.147814 -225.367088)
		(mid 134.334758 -225.417343)
		(end 134.521702 -225.367088)
		(width 0.0889)
		(layer "In2.Cu")
		(net "M_I_CPU1_SA_DQ<0>")
	)
	(arc
		(start 133.581902 -225.367088)
		(mid 133.864858 -225.290911)
		(end 134.147814 -225.367088)
		(width 0.0889)
		(layer "In2.Cu")
		(net "M_I_CPU1_SA_DQ<0>")
	)
	(arc
		(start 141.132052 -222.109284)
		(mid 141.247479 -221.975908)
		(end 141.289024 -221.804484)
		(width 0.0889)
		(layer "In2.Cu")
		(net "M_I_CPU1_SA_DQ<0>")
	)
	(arc
		(start 139.722352 -224.539302)
		(mid 139.837779 -224.405926)
		(end 139.879324 -224.234502)
		(width 0.0889)
		(layer "In2.Cu")
		(net "M_I_CPU1_SA_DQ<0>")
	)
	(arc
		(start 133.216142 -225.371914)
		(mid 133.39965 -225.417408)
		(end 133.581902 -225.367088)
		(width 0.0889)
		(layer "In2.Cu")
		(net "M_I_CPU1_SA_DQ<0>")
	)
	(arc
		(start 138.84783 -225.367088)
		(mid 139.034774 -225.417343)
		(end 139.221718 -225.367088)
		(width 0.0889)
		(layer "In2.Cu")
		(net "M_I_CPU1_SA_DQ<0>")
	)
	(arc
		(start 138.281918 -225.367088)
		(mid 138.564874 -225.290911)
		(end 138.84783 -225.367088)
		(width 0.0889)
		(layer "In2.Cu")
		(net "M_I_CPU1_SA_DQ<0>")
	)
	(arc
		(start 140.191236 -223.730058)
		(mid 140.307417 -223.596499)
		(end 140.349224 -223.424496)
		(width 0.0889)
		(layer "In2.Cu")
		(net "M_I_CPU1_SA_DQ<0>")
	)
	(arc
		(start 129.50317 -225.39325)
		(mid 129.665359 -225.415985)
		(end 129.821686 -225.367088)
		(width 0.0889)
		(layer "In2.Cu")
		(net "M_I_CPU1_SA_DQ<0>")
	)
	(arc
		(start 132.276088 -225.371914)
		(mid 132.459596 -225.417408)
		(end 132.641848 -225.367088)
		(width 0.0889)
		(layer "In2.Cu")
		(net "M_I_CPU1_SA_DQ<0>")
	)
	(arc
		(start 136.976104 -225.371914)
		(mid 137.159612 -225.417408)
		(end 137.341864 -225.367088)
		(width 0.0889)
		(layer "In2.Cu")
		(net "M_I_CPU1_SA_DQ<0>")
	)
	(arc
		(start 136.027668 -225.367088)
		(mid 136.209919 -225.417438)
		(end 136.393428 -225.371914)
		(width 0.0889)
		(layer "In2.Cu")
		(net "M_I_CPU1_SA_DQ<0>")
	)
	(arc
		(start 131.701794 -225.367088)
		(mid 131.98475 -225.290911)
		(end 132.267706 -225.367088)
		(width 0.0889)
		(layer "In2.Cu")
		(net "M_I_CPU1_SA_DQ<0>")
	)
	(arc
		(start 132.641848 -225.367088)
		(mid 132.924804 -225.290911)
		(end 133.20776 -225.367088)
		(width 0.0889)
		(layer "In2.Cu")
		(net "M_I_CPU1_SA_DQ<0>")
	)
	(arc
		(start 136.40181 -225.367088)
		(mid 136.684766 -225.290911)
		(end 136.967722 -225.367088)
		(width 0.0889)
		(layer "In2.Cu")
		(net "M_I_CPU1_SA_DQ<0>")
	)
	(arc
		(start 131.327652 -225.367088)
		(mid 131.509903 -225.417438)
		(end 131.693412 -225.371914)
		(width 0.0889)
		(layer "In2.Cu")
		(net "M_I_CPU1_SA_DQ<0>")
	)
	(arc
		(start 134.521702 -225.367088)
		(mid 134.804658 -225.290911)
		(end 135.087614 -225.367088)
		(width 0.0889)
		(layer "In2.Cu")
		(net "M_I_CPU1_SA_DQ<0>")
	)
	(arc
		(start 129.821686 -225.367088)
		(mid 130.104642 -225.290911)
		(end 130.387598 -225.367088)
		(width 0.0889)
		(layer "In2.Cu")
		(net "M_I_CPU1_SA_DQ<0>")
	)
	(arc
		(start 140.819378 -222.61449)
		(mid 140.88425 -222.351527)
		(end 141.06398 -222.148908)
		(width 0.0889)
		(layer "In2.Cu")
		(net "M_I_CPU1_SA_DQ<0>")
	)
	(arc
		(start 139.879324 -224.234502)
		(mid 139.944196 -223.971539)
		(end 140.123926 -223.76892)
		(width 0.0889)
		(layer "In2.Cu")
		(net "M_I_CPU1_SA_DQ<0>")
	)
	(arc
		(start 140.349224 -223.424496)
		(mid 140.414096 -223.161533)
		(end 140.593826 -222.958914)
		(width 0.0889)
		(layer "In2.Cu")
		(net "M_I_CPU1_SA_DQ<0>")
	)
	(arc
		(start 130.76174 -225.367088)
		(mid 131.044696 -225.290911)
		(end 131.327652 -225.367088)
		(width 0.0889)
		(layer "In2.Cu")
		(net "M_I_CPU1_SA_DQ<0>")
	)
	(arc
		(start 140.663422 -222.918782)
		(mid 140.778098 -222.785448)
		(end 140.819378 -222.61449)
		(width 0.0889)
		(layer "In2.Cu")
		(net "M_I_CPU1_SA_DQ<0>")
	)
	(arc
		(start 135.087614 -225.367088)
		(mid 135.269865 -225.417438)
		(end 135.453374 -225.371914)
		(width 0.0889)
		(layer "In2.Cu")
		(net "M_I_CPU1_SA_DQ<0>")
	)
	(arc
		(start 130.387598 -225.367088)
		(mid 130.569849 -225.417438)
		(end 130.753358 -225.371914)
		(width 0.0889)
		(layer "In2.Cu")
		(net "M_I_CPU1_SA_DQ<0>")
	)
	(arc
		(start 135.461756 -225.367088)
		(mid 135.744712 -225.290911)
		(end 136.027668 -225.367088)
		(width 0.0889)
		(layer "In2.Cu")
		(net "M_I_CPU1_SA_DQ<0>")
	)
	(arc
		(start 137.341864 -225.367088)
		(mid 137.62482 -225.290911)
		(end 137.907776 -225.367088)
		(width 0.0889)
		(layer "In2.Cu")
		(net "M_I_CPU1_SA_DQ<0>")
	)
	(arc
		(start 139.409424 -225.044508)
		(mid 139.473939 -224.782289)
		(end 139.652756 -224.579942)
		(width 0.0889)
		(layer "In2.Cu")
		(net "M_I_CPU1_SA_DQ<0>")
	)
	(segment
		(start 127.757936 -252.04039)
		(end 128.224788 -251.774452)
		(width 0.10668)
		(layer "F.Cu")
		(net "M_I_CPU1_SA_CS_N<1>")
	)
	(segment
		(start 133.103366 -252.101858)
		(end 133.111748 -252.097032)
		(width 0.0889)
		(layer "In2.Cu")
		(net "M_I_CPU1_SA_CS_N<1>")
	)
	(segment
		(start 137.803382 -252.101858)
		(end 137.811764 -252.097032)
		(width 0.0889)
		(layer "In2.Cu")
		(net "M_I_CPU1_SA_CS_N<1>")
	)
	(segment
		(start 160.499044 -251.96927)
		(end 163.707826 -248.760488)
		(width 0.14478)
		(layer "In2.Cu")
		(net "M_I_CPU1_SA_CS_N<1>")
	)
	(segment
		(start 128.40335 -252.101858)
		(end 128.411732 -252.097032)
		(width 0.0889)
		(layer "In2.Cu")
		(net "M_I_CPU1_SA_CS_N<1>")
	)
	(segment
		(start 144.380966 -252.10389)
		(end 144.39265 -252.097032)
		(width 0.0889)
		(layer "In2.Cu")
		(net "M_I_CPU1_SA_CS_N<1>")
	)
	(segment
		(start 128.07061 -252.039882)
		(end 128.092962 -252.123194)
		(width 0.0889)
		(layer "In2.Cu")
		(net "M_I_CPU1_SA_CS_N<1>")
	)
	(segment
		(start 130.857752 -252.097032)
		(end 130.866134 -252.101858)
		(width 0.0889)
		(layer "In2.Cu")
		(net "M_I_CPU1_SA_CS_N<1>")
	)
	(segment
		(start 146.47291 -252.087126)
		(end 147.365466 -252.087126)
		(width 0.0889)
		(layer "In2.Cu")
		(net "M_I_CPU1_SA_CS_N<1>")
	)
	(segment
		(start 146.46275 -252.076966)
		(end 146.47291 -252.087126)
		(width 0.0889)
		(layer "In2.Cu")
		(net "M_I_CPU1_SA_CS_N<1>")
	)
	(segment
		(start 150.378668 -252.087126)
		(end 150.967948 -251.497846)
		(width 0.14478)
		(layer "In2.Cu")
		(net "M_I_CPU1_SA_CS_N<1>")
	)
	(segment
		(start 135.557768 -252.097032)
		(end 135.56615 -252.101858)
		(width 0.0889)
		(layer "In2.Cu")
		(net "M_I_CPU1_SA_CS_N<1>")
	)
	(segment
		(start 128.224788 -251.774452)
		(end 128.07061 -252.039882)
		(width 0.0889)
		(layer "In2.Cu")
		(net "M_I_CPU1_SA_CS_N<1>")
	)
	(segment
		(start 143.451834 -252.097032)
		(end 143.466566 -252.088396)
		(width 0.0889)
		(layer "In2.Cu")
		(net "M_I_CPU1_SA_CS_N<1>")
	)
	(segment
		(start 157.59049 -251.96927)
		(end 160.499044 -251.96927)
		(width 0.14478)
		(layer "In2.Cu")
		(net "M_I_CPU1_SA_CS_N<1>")
	)
	(segment
		(start 129.343404 -252.101858)
		(end 129.351786 -252.097032)
		(width 0.0889)
		(layer "In2.Cu")
		(net "M_I_CPU1_SA_CS_N<1>")
	)
	(segment
		(start 140.257784 -252.097032)
		(end 140.266166 -252.101858)
		(width 0.0889)
		(layer "In2.Cu")
		(net "M_I_CPU1_SA_CS_N<1>")
	)
	(segment
		(start 138.743436 -252.101858)
		(end 138.751818 -252.097032)
		(width 0.0889)
		(layer "In2.Cu")
		(net "M_I_CPU1_SA_CS_N<1>")
	)
	(segment
		(start 134.617714 -252.097032)
		(end 134.626096 -252.101858)
		(width 0.0889)
		(layer "In2.Cu")
		(net "M_I_CPU1_SA_CS_N<1>")
	)
	(segment
		(start 143.077692 -252.097032)
		(end 143.086074 -252.101858)
		(width 0.0889)
		(layer "In2.Cu")
		(net "M_I_CPU1_SA_CS_N<1>")
	)
	(segment
		(start 147.365466 -252.087126)
		(end 150.378668 -252.087126)
		(width 0.14478)
		(layer "In2.Cu")
		(net "M_I_CPU1_SA_CS_N<1>")
	)
	(segment
		(start 179.090828 -247.060466)
		(end 179.516024 -246.63527)
		(width 0.14478)
		(layer "In2.Cu")
		(net "M_I_CPU1_SA_CS_N<1>")
	)
	(segment
		(start 157.119066 -251.497846)
		(end 157.59049 -251.96927)
		(width 0.14478)
		(layer "In2.Cu")
		(net "M_I_CPU1_SA_CS_N<1>")
	)
	(segment
		(start 163.707826 -248.760488)
		(end 173.404276 -248.760488)
		(width 0.14478)
		(layer "In2.Cu")
		(net "M_I_CPU1_SA_CS_N<1>")
	)
	(segment
		(start 142.503398 -252.101858)
		(end 142.51178 -252.097032)
		(width 0.0889)
		(layer "In2.Cu")
		(net "M_I_CPU1_SA_CS_N<1>")
	)
	(segment
		(start 134.04342 -252.101858)
		(end 134.051802 -252.097032)
		(width 0.0889)
		(layer "In2.Cu")
		(net "M_I_CPU1_SA_CS_N<1>")
	)
	(segment
		(start 144.952466 -252.093476)
		(end 144.958054 -252.096778)
		(width 0.0889)
		(layer "In2.Cu")
		(net "M_I_CPU1_SA_CS_N<1>")
	)
	(segment
		(start 129.917698 -252.097032)
		(end 129.92608 -252.101858)
		(width 0.0889)
		(layer "In2.Cu")
		(net "M_I_CPU1_SA_CS_N<1>")
	)
	(segment
		(start 139.31773 -252.097032)
		(end 139.326112 -252.101858)
		(width 0.0889)
		(layer "In2.Cu")
		(net "M_I_CPU1_SA_CS_N<1>")
	)
	(segment
		(start 145.87601 -252.076966)
		(end 146.46275 -252.076966)
		(width 0.0889)
		(layer "In2.Cu")
		(net "M_I_CPU1_SA_CS_N<1>")
	)
	(segment
		(start 173.404276 -248.760488)
		(end 175.104298 -247.060466)
		(width 0.14478)
		(layer "In2.Cu")
		(net "M_I_CPU1_SA_CS_N<1>")
	)
	(segment
		(start 150.967948 -251.497846)
		(end 157.119066 -251.497846)
		(width 0.14478)
		(layer "In2.Cu")
		(net "M_I_CPU1_SA_CS_N<1>")
	)
	(segment
		(start 175.104298 -247.060466)
		(end 179.090828 -247.060466)
		(width 0.14478)
		(layer "In2.Cu")
		(net "M_I_CPU1_SA_CS_N<1>")
	)
	(arc
		(start 128.411732 -252.097032)
		(mid 128.694688 -252.020855)
		(end 128.977644 -252.097032)
		(width 0.0889)
		(layer "In2.Cu")
		(net "M_I_CPU1_SA_CS_N<1>")
	)
	(arc
		(start 134.051802 -252.097032)
		(mid 134.334758 -252.020855)
		(end 134.617714 -252.097032)
		(width 0.0889)
		(layer "In2.Cu")
		(net "M_I_CPU1_SA_CS_N<1>")
	)
	(arc
		(start 137.811764 -252.097032)
		(mid 138.09472 -252.020855)
		(end 138.377676 -252.097032)
		(width 0.0889)
		(layer "In2.Cu")
		(net "M_I_CPU1_SA_CS_N<1>")
	)
	(arc
		(start 142.51178 -252.097032)
		(mid 142.794736 -252.020855)
		(end 143.077692 -252.097032)
		(width 0.0889)
		(layer "In2.Cu")
		(net "M_I_CPU1_SA_CS_N<1>")
	)
	(arc
		(start 143.086074 -252.101858)
		(mid 143.269582 -252.147352)
		(end 143.451834 -252.097032)
		(width 0.0889)
		(layer "In2.Cu")
		(net "M_I_CPU1_SA_CS_N<1>")
	)
	(arc
		(start 136.87171 -252.097032)
		(mid 137.154666 -252.020855)
		(end 137.437622 -252.097032)
		(width 0.0889)
		(layer "In2.Cu")
		(net "M_I_CPU1_SA_CS_N<1>")
	)
	(arc
		(start 143.466566 -252.088396)
		(mid 143.743549 -252.020592)
		(end 144.018254 -252.097032)
		(width 0.0889)
		(layer "In2.Cu")
		(net "M_I_CPU1_SA_CS_N<1>")
	)
	(arc
		(start 144.018254 -252.097032)
		(mid 144.198712 -252.147476)
		(end 144.380966 -252.10389)
		(width 0.0889)
		(layer "In2.Cu")
		(net "M_I_CPU1_SA_CS_N<1>")
	)
	(arc
		(start 139.691872 -252.097032)
		(mid 139.974828 -252.020855)
		(end 140.257784 -252.097032)
		(width 0.0889)
		(layer "In2.Cu")
		(net "M_I_CPU1_SA_CS_N<1>")
	)
	(arc
		(start 132.737606 -252.097032)
		(mid 132.919857 -252.147382)
		(end 133.103366 -252.101858)
		(width 0.0889)
		(layer "In2.Cu")
		(net "M_I_CPU1_SA_CS_N<1>")
	)
	(arc
		(start 134.626096 -252.101858)
		(mid 134.809604 -252.147352)
		(end 134.991856 -252.097032)
		(width 0.0889)
		(layer "In2.Cu")
		(net "M_I_CPU1_SA_CS_N<1>")
	)
	(arc
		(start 129.92608 -252.101858)
		(mid 130.109588 -252.147352)
		(end 130.29184 -252.097032)
		(width 0.0889)
		(layer "In2.Cu")
		(net "M_I_CPU1_SA_CS_N<1>")
	)
	(arc
		(start 138.751818 -252.097032)
		(mid 139.034774 -252.020855)
		(end 139.31773 -252.097032)
		(width 0.0889)
		(layer "In2.Cu")
		(net "M_I_CPU1_SA_CS_N<1>")
	)
	(arc
		(start 141.571726 -252.097032)
		(mid 141.854682 -252.020855)
		(end 142.137638 -252.097032)
		(width 0.0889)
		(layer "In2.Cu")
		(net "M_I_CPU1_SA_CS_N<1>")
	)
	(arc
		(start 144.958054 -252.096778)
		(mid 145.048167 -252.134547)
		(end 145.144998 -252.147578)
		(width 0.0889)
		(layer "In2.Cu")
		(net "M_I_CPU1_SA_CS_N<1>")
	)
	(arc
		(start 130.29184 -252.097032)
		(mid 130.574796 -252.020855)
		(end 130.857752 -252.097032)
		(width 0.0889)
		(layer "In2.Cu")
		(net "M_I_CPU1_SA_CS_N<1>")
	)
	(arc
		(start 131.797806 -252.097032)
		(mid 131.98475 -252.147287)
		(end 132.171694 -252.097032)
		(width 0.0889)
		(layer "In2.Cu")
		(net "M_I_CPU1_SA_CS_N<1>")
	)
	(arc
		(start 145.31467 -252.099826)
		(mid 145.592377 -252.015519)
		(end 145.87601 -252.076966)
		(width 0.0889)
		(layer "In2.Cu")
		(net "M_I_CPU1_SA_CS_N<1>")
	)
	(arc
		(start 136.497822 -252.097032)
		(mid 136.684766 -252.147287)
		(end 136.87171 -252.097032)
		(width 0.0889)
		(layer "In2.Cu")
		(net "M_I_CPU1_SA_CS_N<1>")
	)
	(arc
		(start 139.326112 -252.101858)
		(mid 139.50962 -252.147352)
		(end 139.691872 -252.097032)
		(width 0.0889)
		(layer "In2.Cu")
		(net "M_I_CPU1_SA_CS_N<1>")
	)
	(arc
		(start 137.437622 -252.097032)
		(mid 137.619873 -252.147382)
		(end 137.803382 -252.101858)
		(width 0.0889)
		(layer "In2.Cu")
		(net "M_I_CPU1_SA_CS_N<1>")
	)
	(arc
		(start 135.93191 -252.097032)
		(mid 136.214866 -252.020855)
		(end 136.497822 -252.097032)
		(width 0.0889)
		(layer "In2.Cu")
		(net "M_I_CPU1_SA_CS_N<1>")
	)
	(arc
		(start 142.137638 -252.097032)
		(mid 142.319889 -252.147382)
		(end 142.503398 -252.101858)
		(width 0.0889)
		(layer "In2.Cu")
		(net "M_I_CPU1_SA_CS_N<1>")
	)
	(arc
		(start 133.111748 -252.097032)
		(mid 133.394704 -252.020855)
		(end 133.67766 -252.097032)
		(width 0.0889)
		(layer "In2.Cu")
		(net "M_I_CPU1_SA_CS_N<1>")
	)
	(arc
		(start 133.67766 -252.097032)
		(mid 133.859911 -252.147382)
		(end 134.04342 -252.101858)
		(width 0.0889)
		(layer "In2.Cu")
		(net "M_I_CPU1_SA_CS_N<1>")
	)
	(arc
		(start 135.56615 -252.101858)
		(mid 135.749658 -252.147352)
		(end 135.93191 -252.097032)
		(width 0.0889)
		(layer "In2.Cu")
		(net "M_I_CPU1_SA_CS_N<1>")
	)
	(arc
		(start 128.977644 -252.097032)
		(mid 129.159895 -252.147382)
		(end 129.343404 -252.101858)
		(width 0.0889)
		(layer "In2.Cu")
		(net "M_I_CPU1_SA_CS_N<1>")
	)
	(arc
		(start 140.631926 -252.097032)
		(mid 140.914882 -252.020855)
		(end 141.197838 -252.097032)
		(width 0.0889)
		(layer "In2.Cu")
		(net "M_I_CPU1_SA_CS_N<1>")
	)
	(arc
		(start 144.39265 -252.097032)
		(mid 144.672078 -252.020866)
		(end 144.952466 -252.093476)
		(width 0.0889)
		(layer "In2.Cu")
		(net "M_I_CPU1_SA_CS_N<1>")
	)
	(arc
		(start 138.377676 -252.097032)
		(mid 138.559927 -252.147382)
		(end 138.743436 -252.101858)
		(width 0.0889)
		(layer "In2.Cu")
		(net "M_I_CPU1_SA_CS_N<1>")
	)
	(arc
		(start 141.197838 -252.097032)
		(mid 141.384782 -252.147287)
		(end 141.571726 -252.097032)
		(width 0.0889)
		(layer "In2.Cu")
		(net "M_I_CPU1_SA_CS_N<1>")
	)
	(arc
		(start 131.231894 -252.097032)
		(mid 131.51485 -252.020855)
		(end 131.797806 -252.097032)
		(width 0.0889)
		(layer "In2.Cu")
		(net "M_I_CPU1_SA_CS_N<1>")
	)
	(arc
		(start 140.266166 -252.101858)
		(mid 140.449674 -252.147352)
		(end 140.631926 -252.097032)
		(width 0.0889)
		(layer "In2.Cu")
		(net "M_I_CPU1_SA_CS_N<1>")
	)
	(arc
		(start 129.351786 -252.097032)
		(mid 129.634742 -252.020855)
		(end 129.917698 -252.097032)
		(width 0.0889)
		(layer "In2.Cu")
		(net "M_I_CPU1_SA_CS_N<1>")
	)
	(arc
		(start 132.171694 -252.097032)
		(mid 132.45465 -252.020855)
		(end 132.737606 -252.097032)
		(width 0.0889)
		(layer "In2.Cu")
		(net "M_I_CPU1_SA_CS_N<1>")
	)
	(arc
		(start 128.092962 -252.123194)
		(mid 128.250472 -252.146392)
		(end 128.40335 -252.101858)
		(width 0.0889)
		(layer "In2.Cu")
		(net "M_I_CPU1_SA_CS_N<1>")
	)
	(arc
		(start 145.144998 -252.147578)
		(mid 145.233131 -252.135415)
		(end 145.31467 -252.099826)
		(width 0.0889)
		(layer "In2.Cu")
		(net "M_I_CPU1_SA_CS_N<1>")
	)
	(arc
		(start 134.991856 -252.097032)
		(mid 135.274812 -252.020855)
		(end 135.557768 -252.097032)
		(width 0.0889)
		(layer "In2.Cu")
		(net "M_I_CPU1_SA_CS_N<1>")
	)
	(arc
		(start 130.866134 -252.101858)
		(mid 131.049642 -252.147352)
		(end 131.231894 -252.097032)
		(width 0.0889)
		(layer "In2.Cu")
		(net "M_I_CPU1_SA_CS_N<1>")
	)
	(segment
		(start 129.16789 -251.230384)
		(end 129.634742 -250.964446)
		(width 0.10668)
		(layer "F.Cu")
		(net "M_I_CPU1_SA_CS_N<0>")
	)
	(segment
		(start 145.889726 -251.632466)
		(end 147.056348 -251.632466)
		(width 0.0889)
		(layer "In2.Cu")
		(net "M_I_CPU1_SA_CS_N<0>")
	)
	(segment
		(start 144.484598 -251.287026)
		(end 144.505172 -251.298964)
		(width 0.0889)
		(layer "In2.Cu")
		(net "M_I_CPU1_SA_CS_N<0>")
	)
	(segment
		(start 157.305502 -251.048266)
		(end 157.776926 -251.51969)
		(width 0.14478)
		(layer "In2.Cu")
		(net "M_I_CPU1_SA_CS_N<0>")
	)
	(segment
		(start 147.056348 -251.632466)
		(end 150.197312 -251.632466)
		(width 0.14478)
		(layer "In2.Cu")
		(net "M_I_CPU1_SA_CS_N<0>")
	)
	(segment
		(start 141.093444 -251.291852)
		(end 141.101826 -251.287026)
		(width 0.0889)
		(layer "In2.Cu")
		(net "M_I_CPU1_SA_CS_N<0>")
	)
	(segment
		(start 131.693412 -251.291852)
		(end 131.701794 -251.287026)
		(width 0.0889)
		(layer "In2.Cu")
		(net "M_I_CPU1_SA_CS_N<0>")
	)
	(segment
		(start 163.47694 -247.91035)
		(end 173.611032 -247.91035)
		(width 0.14478)
		(layer "In2.Cu")
		(net "M_I_CPU1_SA_CS_N<0>")
	)
	(segment
		(start 129.634742 -250.964446)
		(end 129.480818 -251.229876)
		(width 0.0889)
		(layer "In2.Cu")
		(net "M_I_CPU1_SA_CS_N<0>")
	)
	(segment
		(start 175.311054 -246.210328)
		(end 183.19115 -246.210328)
		(width 0.14478)
		(layer "In2.Cu")
		(net "M_I_CPU1_SA_CS_N<0>")
	)
	(segment
		(start 133.20776 -251.287026)
		(end 133.216142 -251.291852)
		(width 0.0889)
		(layer "In2.Cu")
		(net "M_I_CPU1_SA_CS_N<0>")
	)
	(segment
		(start 157.776926 -251.51969)
		(end 159.8676 -251.51969)
		(width 0.14478)
		(layer "In2.Cu")
		(net "M_I_CPU1_SA_CS_N<0>")
	)
	(segment
		(start 183.19115 -246.210328)
		(end 183.616092 -245.785386)
		(width 0.14478)
		(layer "In2.Cu")
		(net "M_I_CPU1_SA_CS_N<0>")
	)
	(segment
		(start 145.09623 -251.381006)
		(end 145.889726 -251.632466)
		(width 0.0889)
		(layer "In2.Cu")
		(net "M_I_CPU1_SA_CS_N<0>")
	)
	(segment
		(start 136.967722 -251.287026)
		(end 136.976104 -251.291852)
		(width 0.0889)
		(layer "In2.Cu")
		(net "M_I_CPU1_SA_CS_N<0>")
	)
	(segment
		(start 173.611032 -247.91035)
		(end 175.311054 -246.210328)
		(width 0.14478)
		(layer "In2.Cu")
		(net "M_I_CPU1_SA_CS_N<0>")
	)
	(segment
		(start 135.453374 -251.291852)
		(end 135.461756 -251.287026)
		(width 0.0889)
		(layer "In2.Cu")
		(net "M_I_CPU1_SA_CS_N<0>")
	)
	(segment
		(start 150.197312 -251.632466)
		(end 150.781512 -251.048266)
		(width 0.14478)
		(layer "In2.Cu")
		(net "M_I_CPU1_SA_CS_N<0>")
	)
	(segment
		(start 150.781512 -251.048266)
		(end 157.305502 -251.048266)
		(width 0.14478)
		(layer "In2.Cu")
		(net "M_I_CPU1_SA_CS_N<0>")
	)
	(segment
		(start 143.897096 -251.300234)
		(end 143.920464 -251.286772)
		(width 0.0889)
		(layer "In2.Cu")
		(net "M_I_CPU1_SA_CS_N<0>")
	)
	(segment
		(start 140.15339 -251.291852)
		(end 140.161772 -251.287026)
		(width 0.0889)
		(layer "In2.Cu")
		(net "M_I_CPU1_SA_CS_N<0>")
	)
	(segment
		(start 159.8676 -251.51969)
		(end 163.47694 -247.91035)
		(width 0.14478)
		(layer "In2.Cu")
		(net "M_I_CPU1_SA_CS_N<0>")
	)
	(segment
		(start 130.753358 -251.291852)
		(end 130.76174 -251.287026)
		(width 0.0889)
		(layer "In2.Cu")
		(net "M_I_CPU1_SA_CS_N<0>")
	)
	(segment
		(start 136.393428 -251.291852)
		(end 136.40181 -251.287026)
		(width 0.0889)
		(layer "In2.Cu")
		(net "M_I_CPU1_SA_CS_N<0>")
	)
	(segment
		(start 141.667738 -251.287026)
		(end 141.67612 -251.291852)
		(width 0.0889)
		(layer "In2.Cu")
		(net "M_I_CPU1_SA_CS_N<0>")
	)
	(segment
		(start 143.920464 -251.286772)
		(end 143.94434 -251.272802)
		(width 0.0889)
		(layer "In2.Cu")
		(net "M_I_CPU1_SA_CS_N<0>")
	)
	(segment
		(start 137.907776 -251.287026)
		(end 137.916158 -251.291852)
		(width 0.0889)
		(layer "In2.Cu")
		(net "M_I_CPU1_SA_CS_N<0>")
	)
	(segment
		(start 132.267706 -251.287026)
		(end 132.276088 -251.291852)
		(width 0.0889)
		(layer "In2.Cu")
		(net "M_I_CPU1_SA_CS_N<0>")
	)
	(segment
		(start 129.480818 -251.229876)
		(end 129.50317 -251.313188)
		(width 0.0889)
		(layer "In2.Cu")
		(net "M_I_CPU1_SA_CS_N<0>")
	)
	(arc
		(start 140.161772 -251.287026)
		(mid 140.444728 -251.210849)
		(end 140.727684 -251.287026)
		(width 0.0889)
		(layer "In2.Cu")
		(net "M_I_CPU1_SA_CS_N<0>")
	)
	(arc
		(start 137.341864 -251.287026)
		(mid 137.62482 -251.210849)
		(end 137.907776 -251.287026)
		(width 0.0889)
		(layer "In2.Cu")
		(net "M_I_CPU1_SA_CS_N<0>")
	)
	(arc
		(start 144.505172 -251.298964)
		(mid 144.59626 -251.330452)
		(end 144.69237 -251.337572)
		(width 0.0889)
		(layer "In2.Cu")
		(net "M_I_CPU1_SA_CS_N<0>")
	)
	(arc
		(start 130.387598 -251.287026)
		(mid 130.569849 -251.337376)
		(end 130.753358 -251.291852)
		(width 0.0889)
		(layer "In2.Cu")
		(net "M_I_CPU1_SA_CS_N<0>")
	)
	(arc
		(start 133.216142 -251.291852)
		(mid 133.39965 -251.337346)
		(end 133.581902 -251.287026)
		(width 0.0889)
		(layer "In2.Cu")
		(net "M_I_CPU1_SA_CS_N<0>")
	)
	(arc
		(start 132.641848 -251.287026)
		(mid 132.924804 -251.210849)
		(end 133.20776 -251.287026)
		(width 0.0889)
		(layer "In2.Cu")
		(net "M_I_CPU1_SA_CS_N<0>")
	)
	(arc
		(start 143.547592 -251.287026)
		(mid 143.7207 -251.337142)
		(end 143.897096 -251.300234)
		(width 0.0889)
		(layer "In2.Cu")
		(net "M_I_CPU1_SA_CS_N<0>")
	)
	(arc
		(start 136.40181 -251.287026)
		(mid 136.684766 -251.210849)
		(end 136.967722 -251.287026)
		(width 0.0889)
		(layer "In2.Cu")
		(net "M_I_CPU1_SA_CS_N<0>")
	)
	(arc
		(start 142.04188 -251.287026)
		(mid 142.324836 -251.210849)
		(end 142.607792 -251.287026)
		(width 0.0889)
		(layer "In2.Cu")
		(net "M_I_CPU1_SA_CS_N<0>")
	)
	(arc
		(start 129.821686 -251.287026)
		(mid 130.104642 -251.210849)
		(end 130.387598 -251.287026)
		(width 0.0889)
		(layer "In2.Cu")
		(net "M_I_CPU1_SA_CS_N<0>")
	)
	(arc
		(start 141.101826 -251.287026)
		(mid 141.384782 -251.210849)
		(end 141.667738 -251.287026)
		(width 0.0889)
		(layer "In2.Cu")
		(net "M_I_CPU1_SA_CS_N<0>")
	)
	(arc
		(start 140.727684 -251.287026)
		(mid 140.909935 -251.337376)
		(end 141.093444 -251.291852)
		(width 0.0889)
		(layer "In2.Cu")
		(net "M_I_CPU1_SA_CS_N<0>")
	)
	(arc
		(start 137.916158 -251.291852)
		(mid 138.099666 -251.337346)
		(end 138.281918 -251.287026)
		(width 0.0889)
		(layer "In2.Cu")
		(net "M_I_CPU1_SA_CS_N<0>")
	)
	(arc
		(start 138.281918 -251.287026)
		(mid 138.564874 -251.210849)
		(end 138.84783 -251.287026)
		(width 0.0889)
		(layer "In2.Cu")
		(net "M_I_CPU1_SA_CS_N<0>")
	)
	(arc
		(start 130.76174 -251.287026)
		(mid 131.044696 -251.210849)
		(end 131.327652 -251.287026)
		(width 0.0889)
		(layer "In2.Cu")
		(net "M_I_CPU1_SA_CS_N<0>")
	)
	(arc
		(start 136.027668 -251.287026)
		(mid 136.209919 -251.337376)
		(end 136.393428 -251.291852)
		(width 0.0889)
		(layer "In2.Cu")
		(net "M_I_CPU1_SA_CS_N<0>")
	)
	(arc
		(start 135.461756 -251.287026)
		(mid 135.744712 -251.210849)
		(end 136.027668 -251.287026)
		(width 0.0889)
		(layer "In2.Cu")
		(net "M_I_CPU1_SA_CS_N<0>")
	)
	(arc
		(start 131.327652 -251.287026)
		(mid 131.509903 -251.337376)
		(end 131.693412 -251.291852)
		(width 0.0889)
		(layer "In2.Cu")
		(net "M_I_CPU1_SA_CS_N<0>")
	)
	(arc
		(start 135.087614 -251.287026)
		(mid 135.269865 -251.337376)
		(end 135.453374 -251.291852)
		(width 0.0889)
		(layer "In2.Cu")
		(net "M_I_CPU1_SA_CS_N<0>")
	)
	(arc
		(start 136.976104 -251.291852)
		(mid 137.159612 -251.337346)
		(end 137.341864 -251.287026)
		(width 0.0889)
		(layer "In2.Cu")
		(net "M_I_CPU1_SA_CS_N<0>")
	)
	(arc
		(start 142.607792 -251.287026)
		(mid 142.794736 -251.337281)
		(end 142.98168 -251.287026)
		(width 0.0889)
		(layer "In2.Cu")
		(net "M_I_CPU1_SA_CS_N<0>")
	)
	(arc
		(start 143.94434 -251.272802)
		(mid 144.216277 -251.210976)
		(end 144.484598 -251.287026)
		(width 0.0889)
		(layer "In2.Cu")
		(net "M_I_CPU1_SA_CS_N<0>")
	)
	(arc
		(start 129.50317 -251.313188)
		(mid 129.665359 -251.335923)
		(end 129.821686 -251.287026)
		(width 0.0889)
		(layer "In2.Cu")
		(net "M_I_CPU1_SA_CS_N<0>")
	)
	(arc
		(start 132.276088 -251.291852)
		(mid 132.459596 -251.337346)
		(end 132.641848 -251.287026)
		(width 0.0889)
		(layer "In2.Cu")
		(net "M_I_CPU1_SA_CS_N<0>")
	)
	(arc
		(start 144.69237 -251.337572)
		(mid 144.896069 -251.342857)
		(end 145.09623 -251.381006)
		(width 0.0889)
		(layer "In2.Cu")
		(net "M_I_CPU1_SA_CS_N<0>")
	)
	(arc
		(start 134.521702 -251.287026)
		(mid 134.804658 -251.210849)
		(end 135.087614 -251.287026)
		(width 0.0889)
		(layer "In2.Cu")
		(net "M_I_CPU1_SA_CS_N<0>")
	)
	(arc
		(start 133.581902 -251.287026)
		(mid 133.864858 -251.210849)
		(end 134.147814 -251.287026)
		(width 0.0889)
		(layer "In2.Cu")
		(net "M_I_CPU1_SA_CS_N<0>")
	)
	(arc
		(start 131.701794 -251.287026)
		(mid 131.98475 -251.210849)
		(end 132.267706 -251.287026)
		(width 0.0889)
		(layer "In2.Cu")
		(net "M_I_CPU1_SA_CS_N<0>")
	)
	(arc
		(start 138.84783 -251.287026)
		(mid 139.034774 -251.337281)
		(end 139.221718 -251.287026)
		(width 0.0889)
		(layer "In2.Cu")
		(net "M_I_CPU1_SA_CS_N<0>")
	)
	(arc
		(start 134.147814 -251.287026)
		(mid 134.334758 -251.337281)
		(end 134.521702 -251.287026)
		(width 0.0889)
		(layer "In2.Cu")
		(net "M_I_CPU1_SA_CS_N<0>")
	)
	(arc
		(start 139.221718 -251.287026)
		(mid 139.504674 -251.210849)
		(end 139.78763 -251.287026)
		(width 0.0889)
		(layer "In2.Cu")
		(net "M_I_CPU1_SA_CS_N<0>")
	)
	(arc
		(start 141.67612 -251.291852)
		(mid 141.859628 -251.337346)
		(end 142.04188 -251.287026)
		(width 0.0889)
		(layer "In2.Cu")
		(net "M_I_CPU1_SA_CS_N<0>")
	)
	(arc
		(start 139.78763 -251.287026)
		(mid 139.969881 -251.337376)
		(end 140.15339 -251.291852)
		(width 0.0889)
		(layer "In2.Cu")
		(net "M_I_CPU1_SA_CS_N<0>")
	)
	(arc
		(start 142.98168 -251.287026)
		(mid 143.264636 -251.210849)
		(end 143.547592 -251.287026)
		(width 0.0889)
		(layer "In2.Cu")
		(net "M_I_CPU1_SA_CS_N<0>")
	)
	(segment
		(start 127.287782 -249.610372)
		(end 127.754634 -249.344434)
		(width 0.10668)
		(layer "F.Cu")
		(net "M_I_CPU1_SA_CB<7>")
	)
	(segment
		(start 153.66619 -248.891806)
		(end 153.92019 -249.145806)
		(width 0.14478)
		(layer "In2.Cu")
		(net "M_I_CPU1_SA_CB<7>")
	)
	(segment
		(start 177.705258 -243.660422)
		(end 178.021234 -243.344446)
		(width 0.14478)
		(layer "In2.Cu")
		(net "M_I_CPU1_SA_CB<7>")
	)
	(segment
		(start 135.453374 -249.017028)
		(end 135.461756 -249.021854)
		(width 0.0889)
		(layer "In2.Cu")
		(net "M_I_CPU1_SA_CB<7>")
	)
	(segment
		(start 175.451008 -243.660422)
		(end 176.60239 -243.660422)
		(width 0.14478)
		(layer "In2.Cu")
		(net "M_I_CPU1_SA_CB<7>")
	)
	(segment
		(start 165.884098 -245.114826)
		(end 166.129716 -245.360444)
		(width 0.14478)
		(layer "In2.Cu")
		(net "M_I_CPU1_SA_CB<7>")
	)
	(segment
		(start 154.217624 -249.145806)
		(end 154.471624 -248.891806)
		(width 0.14478)
		(layer "In2.Cu")
		(net "M_I_CPU1_SA_CB<7>")
	)
	(segment
		(start 155.023058 -249.145806)
		(end 155.320492 -249.145806)
		(width 0.14478)
		(layer "In2.Cu")
		(net "M_I_CPU1_SA_CB<7>")
	)
	(segment
		(start 149.806152 -248.891806)
		(end 150.357586 -248.891806)
		(width 0.14478)
		(layer "In2.Cu")
		(net "M_I_CPU1_SA_CB<7>")
	)
	(segment
		(start 166.435532 -245.360444)
		(end 166.68115 -245.114826)
		(width 0.14478)
		(layer "In2.Cu")
		(net "M_I_CPU1_SA_CB<7>")
	)
	(segment
		(start 156.67736 -248.891806)
		(end 156.974794 -248.891806)
		(width 0.14478)
		(layer "In2.Cu")
		(net "M_I_CPU1_SA_CB<7>")
	)
	(segment
		(start 156.42336 -249.145806)
		(end 156.67736 -248.891806)
		(width 0.14478)
		(layer "In2.Cu")
		(net "M_I_CPU1_SA_CB<7>")
	)
	(segment
		(start 167.784018 -245.114826)
		(end 168.089834 -245.114826)
		(width 0.14478)
		(layer "In2.Cu")
		(net "M_I_CPU1_SA_CB<7>")
	)
	(segment
		(start 176.918366 -243.344446)
		(end 177.153824 -243.344446)
		(width 0.14478)
		(layer "In2.Cu")
		(net "M_I_CPU1_SA_CB<7>")
	)
	(segment
		(start 166.129716 -245.360444)
		(end 166.435532 -245.360444)
		(width 0.14478)
		(layer "In2.Cu")
		(net "M_I_CPU1_SA_CB<7>")
	)
	(segment
		(start 127.908812 -249.079004)
		(end 128.005078 -249.053604)
		(width 0.0889)
		(layer "In2.Cu")
		(net "M_I_CPU1_SA_CB<7>")
	)
	(segment
		(start 155.574492 -248.891806)
		(end 155.871926 -248.891806)
		(width 0.14478)
		(layer "In2.Cu")
		(net "M_I_CPU1_SA_CB<7>")
	)
	(segment
		(start 152.817322 -249.145806)
		(end 153.114756 -249.145806)
		(width 0.14478)
		(layer "In2.Cu")
		(net "M_I_CPU1_SA_CB<7>")
	)
	(segment
		(start 173.819566 -245.010686)
		(end 173.98111 -244.849142)
		(width 0.14478)
		(layer "In2.Cu")
		(net "M_I_CPU1_SA_CB<7>")
	)
	(segment
		(start 146.934936 -249.242326)
		(end 147.332954 -249.640344)
		(width 0.0889)
		(layer "In2.Cu")
		(net "M_I_CPU1_SA_CB<7>")
	)
	(segment
		(start 159.101282 -249.407172)
		(end 159.101282 -249.036586)
		(width 0.14478)
		(layer "In2.Cu")
		(net "M_I_CPU1_SA_CB<7>")
	)
	(segment
		(start 170.919902 -245.360444)
		(end 172.68952 -245.360444)
		(width 0.14478)
		(layer "In2.Cu")
		(net "M_I_CPU1_SA_CB<7>")
	)
	(segment
		(start 178.572668 -243.660422)
		(end 179.090828 -243.660422)
		(width 0.14478)
		(layer "In2.Cu")
		(net "M_I_CPU1_SA_CB<7>")
	)
	(segment
		(start 145.6817 -249.242326)
		(end 146.934936 -249.242326)
		(width 0.0889)
		(layer "In2.Cu")
		(net "M_I_CPU1_SA_CB<7>")
	)
	(segment
		(start 170.07205 -245.360444)
		(end 170.368468 -245.064026)
		(width 0.14478)
		(layer "In2.Cu")
		(net "M_I_CPU1_SA_CB<7>")
	)
	(segment
		(start 159.246062 -248.891806)
		(end 159.804608 -248.891806)
		(width 0.14478)
		(layer "In2.Cu")
		(net "M_I_CPU1_SA_CB<7>")
	)
	(segment
		(start 137.907776 -249.021854)
		(end 137.916158 -249.017028)
		(width 0.0889)
		(layer "In2.Cu")
		(net "M_I_CPU1_SA_CB<7>")
	)
	(segment
		(start 173.819566 -244.458998)
		(end 173.819566 -244.230398)
		(width 0.14478)
		(layer "In2.Cu")
		(net "M_I_CPU1_SA_CB<7>")
	)
	(segment
		(start 130.753358 -249.017028)
		(end 130.76174 -249.021854)
		(width 0.0889)
		(layer "In2.Cu")
		(net "M_I_CPU1_SA_CB<7>")
	)
	(segment
		(start 156.974794 -248.891806)
		(end 157.228794 -249.145806)
		(width 0.14478)
		(layer "In2.Cu")
		(net "M_I_CPU1_SA_CB<7>")
	)
	(segment
		(start 157.526228 -249.145806)
		(end 157.780228 -248.891806)
		(width 0.14478)
		(layer "In2.Cu")
		(net "M_I_CPU1_SA_CB<7>")
	)
	(segment
		(start 176.60239 -243.660422)
		(end 176.918366 -243.344446)
		(width 0.14478)
		(layer "In2.Cu")
		(net "M_I_CPU1_SA_CB<7>")
	)
	(segment
		(start 153.114756 -249.145806)
		(end 153.368756 -248.891806)
		(width 0.14478)
		(layer "In2.Cu")
		(net "M_I_CPU1_SA_CB<7>")
	)
	(segment
		(start 136.393428 -249.017028)
		(end 136.40181 -249.021854)
		(width 0.0889)
		(layer "In2.Cu")
		(net "M_I_CPU1_SA_CB<7>")
	)
	(segment
		(start 149.603968 -249.09399)
		(end 149.806152 -248.891806)
		(width 0.14478)
		(layer "In2.Cu")
		(net "M_I_CPU1_SA_CB<7>")
	)
	(segment
		(start 157.780228 -248.891806)
		(end 158.405068 -248.891806)
		(width 0.14478)
		(layer "In2.Cu")
		(net "M_I_CPU1_SA_CB<7>")
	)
	(segment
		(start 152.563322 -248.891806)
		(end 152.817322 -249.145806)
		(width 0.14478)
		(layer "In2.Cu")
		(net "M_I_CPU1_SA_CB<7>")
	)
	(segment
		(start 168.089834 -245.114826)
		(end 168.335452 -245.360444)
		(width 0.14478)
		(layer "In2.Cu")
		(net "M_I_CPU1_SA_CB<7>")
	)
	(segment
		(start 166.68115 -245.114826)
		(end 166.986966 -245.114826)
		(width 0.14478)
		(layer "In2.Cu")
		(net "M_I_CPU1_SA_CB<7>")
	)
	(segment
		(start 133.20776 -249.021854)
		(end 133.216142 -249.017028)
		(width 0.0889)
		(layer "In2.Cu")
		(net "M_I_CPU1_SA_CB<7>")
	)
	(segment
		(start 143.547592 -249.021854)
		(end 143.555974 -249.017028)
		(width 0.0889)
		(layer "In2.Cu")
		(net "M_I_CPU1_SA_CB<7>")
	)
	(segment
		(start 150.90902 -249.145806)
		(end 151.16302 -248.891806)
		(width 0.14478)
		(layer "In2.Cu")
		(net "M_I_CPU1_SA_CB<7>")
	)
	(segment
		(start 151.714454 -249.145806)
		(end 152.011888 -249.145806)
		(width 0.14478)
		(layer "In2.Cu")
		(net "M_I_CPU1_SA_CB<7>")
	)
	(segment
		(start 147.995386 -249.640344)
		(end 149.442424 -249.640344)
		(width 0.14478)
		(layer "In2.Cu")
		(net "M_I_CPU1_SA_CB<7>")
	)
	(segment
		(start 152.265888 -248.891806)
		(end 152.563322 -248.891806)
		(width 0.14478)
		(layer "In2.Cu")
		(net "M_I_CPU1_SA_CB<7>")
	)
	(segment
		(start 157.228794 -249.145806)
		(end 157.526228 -249.145806)
		(width 0.14478)
		(layer "In2.Cu")
		(net "M_I_CPU1_SA_CB<7>")
	)
	(segment
		(start 174.593758 -243.660422)
		(end 174.899574 -243.354606)
		(width 0.14478)
		(layer "In2.Cu")
		(net "M_I_CPU1_SA_CB<7>")
	)
	(segment
		(start 131.693412 -249.017028)
		(end 131.701794 -249.021854)
		(width 0.0889)
		(layer "In2.Cu")
		(net "M_I_CPU1_SA_CB<7>")
	)
	(segment
		(start 167.5384 -245.360444)
		(end 167.784018 -245.114826)
		(width 0.14478)
		(layer "In2.Cu")
		(net "M_I_CPU1_SA_CB<7>")
	)
	(segment
		(start 177.4698 -243.660422)
		(end 177.705258 -243.660422)
		(width 0.14478)
		(layer "In2.Cu")
		(net "M_I_CPU1_SA_CB<7>")
	)
	(segment
		(start 168.969182 -245.360444)
		(end 169.2656 -245.064026)
		(width 0.14478)
		(layer "In2.Cu")
		(net "M_I_CPU1_SA_CB<7>")
	)
	(segment
		(start 158.549848 -249.036586)
		(end 158.549848 -249.407172)
		(width 0.14478)
		(layer "In2.Cu")
		(net "M_I_CPU1_SA_CB<7>")
	)
	(segment
		(start 149.603968 -249.4788)
		(end 149.603968 -249.09399)
		(width 0.14478)
		(layer "In2.Cu")
		(net "M_I_CPU1_SA_CB<7>")
	)
	(segment
		(start 174.899574 -243.354606)
		(end 175.145192 -243.354606)
		(width 0.14478)
		(layer "In2.Cu")
		(net "M_I_CPU1_SA_CB<7>")
	)
	(segment
		(start 179.090828 -243.660422)
		(end 179.516024 -243.235226)
		(width 0.14478)
		(layer "In2.Cu")
		(net "M_I_CPU1_SA_CB<7>")
	)
	(segment
		(start 158.694628 -249.551952)
		(end 158.956502 -249.551952)
		(width 0.14478)
		(layer "In2.Cu")
		(net "M_I_CPU1_SA_CB<7>")
	)
	(segment
		(start 173.590966 -245.010686)
		(end 173.819566 -245.010686)
		(width 0.14478)
		(layer "In2.Cu")
		(net "M_I_CPU1_SA_CB<7>")
	)
	(segment
		(start 132.267706 -249.021854)
		(end 132.276088 -249.017028)
		(width 0.0889)
		(layer "In2.Cu")
		(net "M_I_CPU1_SA_CB<7>")
	)
	(segment
		(start 167.232584 -245.360444)
		(end 167.5384 -245.360444)
		(width 0.14478)
		(layer "In2.Cu")
		(net "M_I_CPU1_SA_CB<7>")
	)
	(segment
		(start 144.84858 -249.014234)
		(end 144.862296 -249.022108)
		(width 0.0889)
		(layer "In2.Cu")
		(net "M_I_CPU1_SA_CB<7>")
	)
	(segment
		(start 170.623484 -245.064026)
		(end 170.919902 -245.360444)
		(width 0.14478)
		(layer "In2.Cu")
		(net "M_I_CPU1_SA_CB<7>")
	)
	(segment
		(start 169.817034 -245.360444)
		(end 170.07205 -245.360444)
		(width 0.14478)
		(layer "In2.Cu")
		(net "M_I_CPU1_SA_CB<7>")
	)
	(segment
		(start 173.429422 -244.849142)
		(end 173.590966 -245.010686)
		(width 0.14478)
		(layer "In2.Cu")
		(net "M_I_CPU1_SA_CB<7>")
	)
	(segment
		(start 159.101282 -249.036586)
		(end 159.246062 -248.891806)
		(width 0.14478)
		(layer "In2.Cu")
		(net "M_I_CPU1_SA_CB<7>")
	)
	(segment
		(start 127.754634 -249.344434)
		(end 127.908812 -249.079004)
		(width 0.0889)
		(layer "In2.Cu")
		(net "M_I_CPU1_SA_CB<7>")
	)
	(segment
		(start 140.15339 -249.017028)
		(end 140.161772 -249.021854)
		(width 0.0889)
		(layer "In2.Cu")
		(net "M_I_CPU1_SA_CB<7>")
	)
	(segment
		(start 128.507744 -249.021854)
		(end 128.516126 -249.017028)
		(width 0.0889)
		(layer "In2.Cu")
		(net "M_I_CPU1_SA_CB<7>")
	)
	(segment
		(start 136.967722 -249.021854)
		(end 136.976104 -249.017028)
		(width 0.0889)
		(layer "In2.Cu")
		(net "M_I_CPU1_SA_CB<7>")
	)
	(segment
		(start 155.871926 -248.891806)
		(end 156.125926 -249.145806)
		(width 0.14478)
		(layer "In2.Cu")
		(net "M_I_CPU1_SA_CB<7>")
	)
	(segment
		(start 165.332664 -245.360444)
		(end 165.578282 -245.114826)
		(width 0.14478)
		(layer "In2.Cu")
		(net "M_I_CPU1_SA_CB<7>")
	)
	(segment
		(start 159.804608 -248.891806)
		(end 163.33597 -245.360444)
		(width 0.14478)
		(layer "In2.Cu")
		(net "M_I_CPU1_SA_CB<7>")
	)
	(segment
		(start 177.153824 -243.344446)
		(end 177.4698 -243.660422)
		(width 0.14478)
		(layer "In2.Cu")
		(net "M_I_CPU1_SA_CB<7>")
	)
	(segment
		(start 178.256692 -243.344446)
		(end 178.572668 -243.660422)
		(width 0.14478)
		(layer "In2.Cu")
		(net "M_I_CPU1_SA_CB<7>")
	)
	(segment
		(start 175.145192 -243.354606)
		(end 175.451008 -243.660422)
		(width 0.14478)
		(layer "In2.Cu")
		(net "M_I_CPU1_SA_CB<7>")
	)
	(segment
		(start 178.021234 -243.344446)
		(end 178.256692 -243.344446)
		(width 0.14478)
		(layer "In2.Cu")
		(net "M_I_CPU1_SA_CB<7>")
	)
	(segment
		(start 155.320492 -249.145806)
		(end 155.574492 -248.891806)
		(width 0.14478)
		(layer "In2.Cu")
		(net "M_I_CPU1_SA_CB<7>")
	)
	(segment
		(start 174.389542 -243.660422)
		(end 174.593758 -243.660422)
		(width 0.14478)
		(layer "In2.Cu")
		(net "M_I_CPU1_SA_CB<7>")
	)
	(segment
		(start 172.68952 -245.360444)
		(end 173.200822 -244.849142)
		(width 0.14478)
		(layer "In2.Cu")
		(net "M_I_CPU1_SA_CB<7>")
	)
	(segment
		(start 151.460454 -248.891806)
		(end 151.714454 -249.145806)
		(width 0.14478)
		(layer "In2.Cu")
		(net "M_I_CPU1_SA_CB<7>")
	)
	(segment
		(start 144.47393 -249.03049)
		(end 144.488662 -249.021854)
		(width 0.0889)
		(layer "In2.Cu")
		(net "M_I_CPU1_SA_CB<7>")
	)
	(segment
		(start 152.011888 -249.145806)
		(end 152.265888 -248.891806)
		(width 0.14478)
		(layer "In2.Cu")
		(net "M_I_CPU1_SA_CB<7>")
	)
	(segment
		(start 153.92019 -249.145806)
		(end 154.217624 -249.145806)
		(width 0.14478)
		(layer "In2.Cu")
		(net "M_I_CPU1_SA_CB<7>")
	)
	(segment
		(start 158.956502 -249.551952)
		(end 159.101282 -249.407172)
		(width 0.14478)
		(layer "In2.Cu")
		(net "M_I_CPU1_SA_CB<7>")
	)
	(segment
		(start 149.442424 -249.640344)
		(end 149.603968 -249.4788)
		(width 0.14478)
		(layer "In2.Cu")
		(net "M_I_CPU1_SA_CB<7>")
	)
	(segment
		(start 147.332954 -249.640344)
		(end 147.995386 -249.640344)
		(width 0.0889)
		(layer "In2.Cu")
		(net "M_I_CPU1_SA_CB<7>")
	)
	(segment
		(start 169.520616 -245.064026)
		(end 169.817034 -245.360444)
		(width 0.14478)
		(layer "In2.Cu")
		(net "M_I_CPU1_SA_CB<7>")
	)
	(segment
		(start 150.611586 -249.145806)
		(end 150.90902 -249.145806)
		(width 0.14478)
		(layer "In2.Cu")
		(net "M_I_CPU1_SA_CB<7>")
	)
	(segment
		(start 165.578282 -245.114826)
		(end 165.884098 -245.114826)
		(width 0.14478)
		(layer "In2.Cu")
		(net "M_I_CPU1_SA_CB<7>")
	)
	(segment
		(start 170.368468 -245.064026)
		(end 170.623484 -245.064026)
		(width 0.14478)
		(layer "In2.Cu")
		(net "M_I_CPU1_SA_CB<7>")
	)
	(segment
		(start 173.819566 -244.230398)
		(end 174.389542 -243.660422)
		(width 0.14478)
		(layer "In2.Cu")
		(net "M_I_CPU1_SA_CB<7>")
	)
	(segment
		(start 153.368756 -248.891806)
		(end 153.66619 -248.891806)
		(width 0.14478)
		(layer "In2.Cu")
		(net "M_I_CPU1_SA_CB<7>")
	)
	(segment
		(start 141.093444 -249.017028)
		(end 141.101826 -249.021854)
		(width 0.0889)
		(layer "In2.Cu")
		(net "M_I_CPU1_SA_CB<7>")
	)
	(segment
		(start 154.471624 -248.891806)
		(end 154.769058 -248.891806)
		(width 0.14478)
		(layer "In2.Cu")
		(net "M_I_CPU1_SA_CB<7>")
	)
	(segment
		(start 168.335452 -245.360444)
		(end 168.969182 -245.360444)
		(width 0.14478)
		(layer "In2.Cu")
		(net "M_I_CPU1_SA_CB<7>")
	)
	(segment
		(start 154.769058 -248.891806)
		(end 155.023058 -249.145806)
		(width 0.14478)
		(layer "In2.Cu")
		(net "M_I_CPU1_SA_CB<7>")
	)
	(segment
		(start 141.667738 -249.021854)
		(end 141.67612 -249.017028)
		(width 0.0889)
		(layer "In2.Cu")
		(net "M_I_CPU1_SA_CB<7>")
	)
	(segment
		(start 163.33597 -245.360444)
		(end 165.332664 -245.360444)
		(width 0.14478)
		(layer "In2.Cu")
		(net "M_I_CPU1_SA_CB<7>")
	)
	(segment
		(start 150.357586 -248.891806)
		(end 150.611586 -249.145806)
		(width 0.14478)
		(layer "In2.Cu")
		(net "M_I_CPU1_SA_CB<7>")
	)
	(segment
		(start 158.549848 -249.407172)
		(end 158.694628 -249.551952)
		(width 0.14478)
		(layer "In2.Cu")
		(net "M_I_CPU1_SA_CB<7>")
	)
	(segment
		(start 173.98111 -244.849142)
		(end 173.98111 -244.620542)
		(width 0.14478)
		(layer "In2.Cu")
		(net "M_I_CPU1_SA_CB<7>")
	)
	(segment
		(start 151.16302 -248.891806)
		(end 151.460454 -248.891806)
		(width 0.14478)
		(layer "In2.Cu")
		(net "M_I_CPU1_SA_CB<7>")
	)
	(segment
		(start 158.405068 -248.891806)
		(end 158.549848 -249.036586)
		(width 0.14478)
		(layer "In2.Cu")
		(net "M_I_CPU1_SA_CB<7>")
	)
	(segment
		(start 173.200822 -244.849142)
		(end 173.429422 -244.849142)
		(width 0.14478)
		(layer "In2.Cu")
		(net "M_I_CPU1_SA_CB<7>")
	)
	(segment
		(start 156.125926 -249.145806)
		(end 156.42336 -249.145806)
		(width 0.14478)
		(layer "In2.Cu")
		(net "M_I_CPU1_SA_CB<7>")
	)
	(segment
		(start 166.986966 -245.114826)
		(end 167.232584 -245.360444)
		(width 0.14478)
		(layer "In2.Cu")
		(net "M_I_CPU1_SA_CB<7>")
	)
	(segment
		(start 173.98111 -244.620542)
		(end 173.819566 -244.458998)
		(width 0.14478)
		(layer "In2.Cu")
		(net "M_I_CPU1_SA_CB<7>")
	)
	(segment
		(start 169.2656 -245.064026)
		(end 169.520616 -245.064026)
		(width 0.14478)
		(layer "In2.Cu")
		(net "M_I_CPU1_SA_CB<7>")
	)
	(arc
		(start 140.727684 -249.021854)
		(mid 140.909935 -248.971504)
		(end 141.093444 -249.017028)
		(width 0.0889)
		(layer "In2.Cu")
		(net "M_I_CPU1_SA_CB<7>")
	)
	(arc
		(start 132.276088 -249.017028)
		(mid 132.459596 -248.971534)
		(end 132.641848 -249.021854)
		(width 0.0889)
		(layer "In2.Cu")
		(net "M_I_CPU1_SA_CB<7>")
	)
	(arc
		(start 134.521702 -249.021854)
		(mid 134.804658 -249.098031)
		(end 135.087614 -249.021854)
		(width 0.0889)
		(layer "In2.Cu")
		(net "M_I_CPU1_SA_CB<7>")
	)
	(arc
		(start 131.327652 -249.021854)
		(mid 131.509903 -248.971504)
		(end 131.693412 -249.017028)
		(width 0.0889)
		(layer "In2.Cu")
		(net "M_I_CPU1_SA_CB<7>")
	)
	(arc
		(start 139.221718 -249.021854)
		(mid 139.504674 -249.098031)
		(end 139.78763 -249.021854)
		(width 0.0889)
		(layer "In2.Cu")
		(net "M_I_CPU1_SA_CB<7>")
	)
	(arc
		(start 130.76174 -249.021854)
		(mid 131.044696 -249.098031)
		(end 131.327652 -249.021854)
		(width 0.0889)
		(layer "In2.Cu")
		(net "M_I_CPU1_SA_CB<7>")
	)
	(arc
		(start 135.087614 -249.021854)
		(mid 135.269865 -248.971504)
		(end 135.453374 -249.017028)
		(width 0.0889)
		(layer "In2.Cu")
		(net "M_I_CPU1_SA_CB<7>")
	)
	(arc
		(start 134.147814 -249.021854)
		(mid 134.334758 -248.971599)
		(end 134.521702 -249.021854)
		(width 0.0889)
		(layer "In2.Cu")
		(net "M_I_CPU1_SA_CB<7>")
	)
	(arc
		(start 136.40181 -249.021854)
		(mid 136.684766 -249.098031)
		(end 136.967722 -249.021854)
		(width 0.0889)
		(layer "In2.Cu")
		(net "M_I_CPU1_SA_CB<7>")
	)
	(arc
		(start 143.922242 -249.021854)
		(mid 144.196948 -249.098218)
		(end 144.47393 -249.03049)
		(width 0.0889)
		(layer "In2.Cu")
		(net "M_I_CPU1_SA_CB<7>")
	)
	(arc
		(start 132.641848 -249.021854)
		(mid 132.924804 -249.098031)
		(end 133.20776 -249.021854)
		(width 0.0889)
		(layer "In2.Cu")
		(net "M_I_CPU1_SA_CB<7>")
	)
	(arc
		(start 129.447798 -249.021854)
		(mid 129.634742 -248.971599)
		(end 129.821686 -249.021854)
		(width 0.0889)
		(layer "In2.Cu")
		(net "M_I_CPU1_SA_CB<7>")
	)
	(arc
		(start 137.341864 -249.021854)
		(mid 137.62482 -249.098031)
		(end 137.907776 -249.021854)
		(width 0.0889)
		(layer "In2.Cu")
		(net "M_I_CPU1_SA_CB<7>")
	)
	(arc
		(start 138.281918 -249.021854)
		(mid 138.564874 -249.098031)
		(end 138.84783 -249.021854)
		(width 0.0889)
		(layer "In2.Cu")
		(net "M_I_CPU1_SA_CB<7>")
	)
	(arc
		(start 131.701794 -249.021854)
		(mid 131.98475 -249.098031)
		(end 132.267706 -249.021854)
		(width 0.0889)
		(layer "In2.Cu")
		(net "M_I_CPU1_SA_CB<7>")
	)
	(arc
		(start 140.161772 -249.021854)
		(mid 140.444728 -249.098031)
		(end 140.727684 -249.021854)
		(width 0.0889)
		(layer "In2.Cu")
		(net "M_I_CPU1_SA_CB<7>")
	)
	(arc
		(start 128.516126 -249.017028)
		(mid 128.699634 -248.971534)
		(end 128.881886 -249.021854)
		(width 0.0889)
		(layer "In2.Cu")
		(net "M_I_CPU1_SA_CB<7>")
	)
	(arc
		(start 139.78763 -249.021854)
		(mid 139.969881 -248.971504)
		(end 140.15339 -249.017028)
		(width 0.0889)
		(layer "In2.Cu")
		(net "M_I_CPU1_SA_CB<7>")
	)
	(arc
		(start 137.916158 -249.017028)
		(mid 138.099666 -248.971534)
		(end 138.281918 -249.021854)
		(width 0.0889)
		(layer "In2.Cu")
		(net "M_I_CPU1_SA_CB<7>")
	)
	(arc
		(start 144.488662 -249.021854)
		(mid 144.667649 -248.971684)
		(end 144.84858 -249.014234)
		(width 0.0889)
		(layer "In2.Cu")
		(net "M_I_CPU1_SA_CB<7>")
	)
	(arc
		(start 144.862296 -249.022108)
		(mid 145.257454 -249.186344)
		(end 145.6817 -249.242326)
		(width 0.0889)
		(layer "In2.Cu")
		(net "M_I_CPU1_SA_CB<7>")
	)
	(arc
		(start 142.04188 -249.021854)
		(mid 142.324836 -249.098031)
		(end 142.607792 -249.021854)
		(width 0.0889)
		(layer "In2.Cu")
		(net "M_I_CPU1_SA_CB<7>")
	)
	(arc
		(start 141.101826 -249.021854)
		(mid 141.384782 -249.098031)
		(end 141.667738 -249.021854)
		(width 0.0889)
		(layer "In2.Cu")
		(net "M_I_CPU1_SA_CB<7>")
	)
	(arc
		(start 133.581902 -249.021854)
		(mid 133.864858 -249.098031)
		(end 134.147814 -249.021854)
		(width 0.0889)
		(layer "In2.Cu")
		(net "M_I_CPU1_SA_CB<7>")
	)
	(arc
		(start 142.607792 -249.021854)
		(mid 142.794736 -248.971599)
		(end 142.98168 -249.021854)
		(width 0.0889)
		(layer "In2.Cu")
		(net "M_I_CPU1_SA_CB<7>")
	)
	(arc
		(start 130.387598 -249.021854)
		(mid 130.569849 -248.971504)
		(end 130.753358 -249.017028)
		(width 0.0889)
		(layer "In2.Cu")
		(net "M_I_CPU1_SA_CB<7>")
	)
	(arc
		(start 128.881886 -249.021854)
		(mid 129.164842 -249.098031)
		(end 129.447798 -249.021854)
		(width 0.0889)
		(layer "In2.Cu")
		(net "M_I_CPU1_SA_CB<7>")
	)
	(arc
		(start 138.84783 -249.021854)
		(mid 139.034774 -248.971599)
		(end 139.221718 -249.021854)
		(width 0.0889)
		(layer "In2.Cu")
		(net "M_I_CPU1_SA_CB<7>")
	)
	(arc
		(start 135.461756 -249.021854)
		(mid 135.744712 -249.098031)
		(end 136.027668 -249.021854)
		(width 0.0889)
		(layer "In2.Cu")
		(net "M_I_CPU1_SA_CB<7>")
	)
	(arc
		(start 128.005078 -249.053604)
		(mid 128.260143 -249.096955)
		(end 128.507744 -249.021854)
		(width 0.0889)
		(layer "In2.Cu")
		(net "M_I_CPU1_SA_CB<7>")
	)
	(arc
		(start 143.555974 -249.017028)
		(mid 143.739736 -248.971412)
		(end 143.922242 -249.021854)
		(width 0.0889)
		(layer "In2.Cu")
		(net "M_I_CPU1_SA_CB<7>")
	)
	(arc
		(start 136.976104 -249.017028)
		(mid 137.159612 -248.971534)
		(end 137.341864 -249.021854)
		(width 0.0889)
		(layer "In2.Cu")
		(net "M_I_CPU1_SA_CB<7>")
	)
	(arc
		(start 141.67612 -249.017028)
		(mid 141.859628 -248.971534)
		(end 142.04188 -249.021854)
		(width 0.0889)
		(layer "In2.Cu")
		(net "M_I_CPU1_SA_CB<7>")
	)
	(arc
		(start 136.027668 -249.021854)
		(mid 136.209919 -248.971504)
		(end 136.393428 -249.017028)
		(width 0.0889)
		(layer "In2.Cu")
		(net "M_I_CPU1_SA_CB<7>")
	)
	(arc
		(start 142.98168 -249.021854)
		(mid 143.264636 -249.098031)
		(end 143.547592 -249.021854)
		(width 0.0889)
		(layer "In2.Cu")
		(net "M_I_CPU1_SA_CB<7>")
	)
	(arc
		(start 129.821686 -249.021854)
		(mid 130.104642 -249.098031)
		(end 130.387598 -249.021854)
		(width 0.0889)
		(layer "In2.Cu")
		(net "M_I_CPU1_SA_CB<7>")
	)
	(arc
		(start 133.216142 -249.017028)
		(mid 133.39965 -248.971534)
		(end 133.581902 -249.021854)
		(width 0.0889)
		(layer "In2.Cu")
		(net "M_I_CPU1_SA_CB<7>")
	)
	(segment
		(start 128.69799 -248.800366)
		(end 129.164842 -248.534428)
		(width 0.10668)
		(layer "F.Cu")
		(net "M_I_CPU1_SA_CB<6>")
	)
	(segment
		(start 145.330418 -248.212102)
		(end 145.83918 -248.720864)
		(width 0.0889)
		(layer "In2.Cu")
		(net "M_I_CPU1_SA_CB<6>")
	)
	(segment
		(start 142.503398 -248.207022)
		(end 142.51178 -248.211848)
		(width 0.0889)
		(layer "In2.Cu")
		(net "M_I_CPU1_SA_CB<6>")
	)
	(segment
		(start 165.629336 -242.62715)
		(end 165.79088 -242.465606)
		(width 0.14478)
		(layer "In2.Cu")
		(net "M_I_CPU1_SA_CB<6>")
	)
	(segment
		(start 178.223926 -241.670586)
		(end 178.51374 -241.9604)
		(width 0.14478)
		(layer "In2.Cu")
		(net "M_I_CPU1_SA_CB<6>")
	)
	(segment
		(start 165.467792 -243.660422)
		(end 165.629336 -243.498878)
		(width 0.14478)
		(layer "In2.Cu")
		(net "M_I_CPU1_SA_CB<6>")
	)
	(segment
		(start 178.51374 -241.9604)
		(end 179.090828 -241.9604)
		(width 0.14478)
		(layer "In2.Cu")
		(net "M_I_CPU1_SA_CB<6>")
	)
	(segment
		(start 145.300446 -248.19483)
		(end 145.330418 -248.212102)
		(width 0.0889)
		(layer "In2.Cu")
		(net "M_I_CPU1_SA_CB<6>")
	)
	(segment
		(start 169.859198 -243.660422)
		(end 170.087544 -243.660422)
		(width 0.14478)
		(layer "In2.Cu")
		(net "M_I_CPU1_SA_CB<6>")
	)
	(segment
		(start 174.570136 -241.9604)
		(end 176.569624 -241.9604)
		(width 0.14478)
		(layer "In2.Cu")
		(net "M_I_CPU1_SA_CB<6>")
	)
	(segment
		(start 170.249088 -243.498878)
		(end 170.249088 -243.03355)
		(width 0.14478)
		(layer "In2.Cu")
		(net "M_I_CPU1_SA_CB<6>")
	)
	(segment
		(start 167.283638 -242.76177)
		(end 167.283638 -243.498878)
		(width 0.14478)
		(layer "In2.Cu")
		(net "M_I_CPU1_SA_CB<6>")
	)
	(segment
		(start 139.31773 -248.211848)
		(end 139.326112 -248.207022)
		(width 0.0889)
		(layer "In2.Cu")
		(net "M_I_CPU1_SA_CB<6>")
	)
	(segment
		(start 130.857752 -248.211848)
		(end 130.866134 -248.207022)
		(width 0.0889)
		(layer "In2.Cu")
		(net "M_I_CPU1_SA_CB<6>")
	)
	(segment
		(start 167.122094 -242.600226)
		(end 167.283638 -242.76177)
		(width 0.14478)
		(layer "In2.Cu")
		(net "M_I_CPU1_SA_CB<6>")
	)
	(segment
		(start 166.732204 -242.76177)
		(end 166.893748 -242.600226)
		(width 0.14478)
		(layer "In2.Cu")
		(net "M_I_CPU1_SA_CB<6>")
	)
	(segment
		(start 179.090828 -241.9604)
		(end 179.516024 -241.535204)
		(width 0.14478)
		(layer "In2.Cu")
		(net "M_I_CPU1_SA_CB<6>")
	)
	(segment
		(start 163.763706 -243.660422)
		(end 165.467792 -243.660422)
		(width 0.14478)
		(layer "In2.Cu")
		(net "M_I_CPU1_SA_CB<6>")
	)
	(segment
		(start 170.962066 -243.660422)
		(end 172.870114 -243.660422)
		(width 0.14478)
		(layer "In2.Cu")
		(net "M_I_CPU1_SA_CB<6>")
	)
	(segment
		(start 169.53611 -242.872006)
		(end 169.697654 -243.03355)
		(width 0.14478)
		(layer "In2.Cu")
		(net "M_I_CPU1_SA_CB<6>")
	)
	(segment
		(start 165.629336 -243.498878)
		(end 165.629336 -242.62715)
		(width 0.14478)
		(layer "In2.Cu")
		(net "M_I_CPU1_SA_CB<6>")
	)
	(segment
		(start 169.697654 -243.03355)
		(end 169.697654 -243.498878)
		(width 0.14478)
		(layer "In2.Cu")
		(net "M_I_CPU1_SA_CB<6>")
	)
	(segment
		(start 166.18077 -243.498878)
		(end 166.342314 -243.660422)
		(width 0.14478)
		(layer "In2.Cu")
		(net "M_I_CPU1_SA_CB<6>")
	)
	(segment
		(start 170.087544 -243.660422)
		(end 170.249088 -243.498878)
		(width 0.14478)
		(layer "In2.Cu")
		(net "M_I_CPU1_SA_CB<6>")
	)
	(segment
		(start 144.015968 -248.212102)
		(end 144.037812 -248.199656)
		(width 0.0889)
		(layer "In2.Cu")
		(net "M_I_CPU1_SA_CB<6>")
	)
	(segment
		(start 133.103366 -248.207022)
		(end 133.111748 -248.211848)
		(width 0.0889)
		(layer "In2.Cu")
		(net "M_I_CPU1_SA_CB<6>")
	)
	(segment
		(start 177.121058 -241.670586)
		(end 177.410872 -241.9604)
		(width 0.14478)
		(layer "In2.Cu")
		(net "M_I_CPU1_SA_CB<6>")
	)
	(segment
		(start 134.04342 -248.207022)
		(end 134.051802 -248.211848)
		(width 0.0889)
		(layer "In2.Cu")
		(net "M_I_CPU1_SA_CB<6>")
	)
	(segment
		(start 138.743436 -248.207022)
		(end 138.751818 -248.211848)
		(width 0.0889)
		(layer "In2.Cu")
		(net "M_I_CPU1_SA_CB<6>")
	)
	(segment
		(start 167.445182 -243.660422)
		(end 168.984676 -243.660422)
		(width 0.14478)
		(layer "In2.Cu")
		(net "M_I_CPU1_SA_CB<6>")
	)
	(segment
		(start 147.969986 -248.720864)
		(end 148.626068 -248.720864)
		(width 0.14478)
		(layer "In2.Cu")
		(net "M_I_CPU1_SA_CB<6>")
	)
	(segment
		(start 143.077692 -248.211848)
		(end 143.086074 -248.207022)
		(width 0.0889)
		(layer "In2.Cu")
		(net "M_I_CPU1_SA_CB<6>")
	)
	(segment
		(start 170.410632 -242.872006)
		(end 170.638978 -242.872006)
		(width 0.14478)
		(layer "In2.Cu")
		(net "M_I_CPU1_SA_CB<6>")
	)
	(segment
		(start 135.557768 -248.211848)
		(end 135.56615 -248.207022)
		(width 0.0889)
		(layer "In2.Cu")
		(net "M_I_CPU1_SA_CB<6>")
	)
	(segment
		(start 177.672492 -241.9604)
		(end 177.962306 -241.670586)
		(width 0.14478)
		(layer "In2.Cu")
		(net "M_I_CPU1_SA_CB<6>")
	)
	(segment
		(start 159.461454 -247.962674)
		(end 163.763706 -243.660422)
		(width 0.14478)
		(layer "In2.Cu")
		(net "M_I_CPU1_SA_CB<6>")
	)
	(segment
		(start 168.984676 -243.660422)
		(end 169.14622 -243.498878)
		(width 0.14478)
		(layer "In2.Cu")
		(net "M_I_CPU1_SA_CB<6>")
	)
	(segment
		(start 169.307764 -242.872006)
		(end 169.53611 -242.872006)
		(width 0.14478)
		(layer "In2.Cu")
		(net "M_I_CPU1_SA_CB<6>")
	)
	(segment
		(start 170.800522 -243.03355)
		(end 170.800522 -243.498878)
		(width 0.14478)
		(layer "In2.Cu")
		(net "M_I_CPU1_SA_CB<6>")
	)
	(segment
		(start 143.992092 -248.226072)
		(end 144.015968 -248.212102)
		(width 0.0889)
		(layer "In2.Cu")
		(net "M_I_CPU1_SA_CB<6>")
	)
	(segment
		(start 166.893748 -242.600226)
		(end 167.122094 -242.600226)
		(width 0.14478)
		(layer "In2.Cu")
		(net "M_I_CPU1_SA_CB<6>")
	)
	(segment
		(start 169.14622 -243.498878)
		(end 169.14622 -243.03355)
		(width 0.14478)
		(layer "In2.Cu")
		(net "M_I_CPU1_SA_CB<6>")
	)
	(segment
		(start 169.14622 -243.03355)
		(end 169.307764 -242.872006)
		(width 0.14478)
		(layer "In2.Cu")
		(net "M_I_CPU1_SA_CB<6>")
	)
	(segment
		(start 145.83918 -248.720864)
		(end 147.969986 -248.720864)
		(width 0.0889)
		(layer "In2.Cu")
		(net "M_I_CPU1_SA_CB<6>")
	)
	(segment
		(start 172.870114 -243.660422)
		(end 174.570136 -241.9604)
		(width 0.14478)
		(layer "In2.Cu")
		(net "M_I_CPU1_SA_CB<6>")
	)
	(segment
		(start 167.283638 -243.498878)
		(end 167.445182 -243.660422)
		(width 0.14478)
		(layer "In2.Cu")
		(net "M_I_CPU1_SA_CB<6>")
	)
	(segment
		(start 165.79088 -242.465606)
		(end 166.019226 -242.465606)
		(width 0.14478)
		(layer "In2.Cu")
		(net "M_I_CPU1_SA_CB<6>")
	)
	(segment
		(start 177.410872 -241.9604)
		(end 177.672492 -241.9604)
		(width 0.14478)
		(layer "In2.Cu")
		(net "M_I_CPU1_SA_CB<6>")
	)
	(segment
		(start 177.962306 -241.670586)
		(end 178.223926 -241.670586)
		(width 0.14478)
		(layer "In2.Cu")
		(net "M_I_CPU1_SA_CB<6>")
	)
	(segment
		(start 137.803382 -248.207022)
		(end 137.811764 -248.211848)
		(width 0.0889)
		(layer "In2.Cu")
		(net "M_I_CPU1_SA_CB<6>")
	)
	(segment
		(start 129.164842 -248.534428)
		(end 129.318766 -248.268998)
		(width 0.0889)
		(layer "In2.Cu")
		(net "M_I_CPU1_SA_CB<6>")
	)
	(segment
		(start 170.638978 -242.872006)
		(end 170.800522 -243.03355)
		(width 0.14478)
		(layer "In2.Cu")
		(net "M_I_CPU1_SA_CB<6>")
	)
	(segment
		(start 148.626068 -248.720864)
		(end 149.384258 -247.962674)
		(width 0.14478)
		(layer "In2.Cu")
		(net "M_I_CPU1_SA_CB<6>")
	)
	(segment
		(start 169.697654 -243.498878)
		(end 169.859198 -243.660422)
		(width 0.14478)
		(layer "In2.Cu")
		(net "M_I_CPU1_SA_CB<6>")
	)
	(segment
		(start 166.019226 -242.465606)
		(end 166.18077 -242.62715)
		(width 0.14478)
		(layer "In2.Cu")
		(net "M_I_CPU1_SA_CB<6>")
	)
	(segment
		(start 144.388586 -248.211848)
		(end 144.416272 -248.22785)
		(width 0.0889)
		(layer "In2.Cu")
		(net "M_I_CPU1_SA_CB<6>")
	)
	(segment
		(start 176.859438 -241.670586)
		(end 177.121058 -241.670586)
		(width 0.14478)
		(layer "In2.Cu")
		(net "M_I_CPU1_SA_CB<6>")
	)
	(segment
		(start 166.18077 -242.62715)
		(end 166.18077 -243.498878)
		(width 0.14478)
		(layer "In2.Cu")
		(net "M_I_CPU1_SA_CB<6>")
	)
	(segment
		(start 176.569624 -241.9604)
		(end 176.859438 -241.670586)
		(width 0.14478)
		(layer "In2.Cu")
		(net "M_I_CPU1_SA_CB<6>")
	)
	(segment
		(start 140.257784 -248.211848)
		(end 140.266166 -248.207022)
		(width 0.0889)
		(layer "In2.Cu")
		(net "M_I_CPU1_SA_CB<6>")
	)
	(segment
		(start 149.384258 -247.962674)
		(end 159.461454 -247.962674)
		(width 0.14478)
		(layer "In2.Cu")
		(net "M_I_CPU1_SA_CB<6>")
	)
	(segment
		(start 166.57066 -243.660422)
		(end 166.732204 -243.498878)
		(width 0.14478)
		(layer "In2.Cu")
		(net "M_I_CPU1_SA_CB<6>")
	)
	(segment
		(start 170.249088 -243.03355)
		(end 170.410632 -242.872006)
		(width 0.14478)
		(layer "In2.Cu")
		(net "M_I_CPU1_SA_CB<6>")
	)
	(segment
		(start 129.318766 -248.268998)
		(end 129.414778 -248.243598)
		(width 0.0889)
		(layer "In2.Cu")
		(net "M_I_CPU1_SA_CB<6>")
	)
	(segment
		(start 166.342314 -243.660422)
		(end 166.57066 -243.660422)
		(width 0.14478)
		(layer "In2.Cu")
		(net "M_I_CPU1_SA_CB<6>")
	)
	(segment
		(start 134.617714 -248.211848)
		(end 134.626096 -248.207022)
		(width 0.0889)
		(layer "In2.Cu")
		(net "M_I_CPU1_SA_CB<6>")
	)
	(segment
		(start 170.800522 -243.498878)
		(end 170.962066 -243.660422)
		(width 0.14478)
		(layer "In2.Cu")
		(net "M_I_CPU1_SA_CB<6>")
	)
	(segment
		(start 129.917698 -248.211848)
		(end 129.92608 -248.207022)
		(width 0.0889)
		(layer "In2.Cu")
		(net "M_I_CPU1_SA_CB<6>")
	)
	(segment
		(start 166.732204 -243.498878)
		(end 166.732204 -242.76177)
		(width 0.14478)
		(layer "In2.Cu")
		(net "M_I_CPU1_SA_CB<6>")
	)
	(arc
		(start 143.451834 -248.211848)
		(mid 143.720154 -248.287956)
		(end 143.992092 -248.226072)
		(width 0.0889)
		(layer "In2.Cu")
		(net "M_I_CPU1_SA_CB<6>")
	)
	(arc
		(start 134.051802 -248.211848)
		(mid 134.334758 -248.288025)
		(end 134.617714 -248.211848)
		(width 0.0889)
		(layer "In2.Cu")
		(net "M_I_CPU1_SA_CB<6>")
	)
	(arc
		(start 139.691872 -248.211848)
		(mid 139.974828 -248.288025)
		(end 140.257784 -248.211848)
		(width 0.0889)
		(layer "In2.Cu")
		(net "M_I_CPU1_SA_CB<6>")
	)
	(arc
		(start 142.51178 -248.211848)
		(mid 142.794736 -248.288025)
		(end 143.077692 -248.211848)
		(width 0.0889)
		(layer "In2.Cu")
		(net "M_I_CPU1_SA_CB<6>")
	)
	(arc
		(start 143.086074 -248.207022)
		(mid 143.269582 -248.161528)
		(end 143.451834 -248.211848)
		(width 0.0889)
		(layer "In2.Cu")
		(net "M_I_CPU1_SA_CB<6>")
	)
	(arc
		(start 139.326112 -248.207022)
		(mid 139.50962 -248.161528)
		(end 139.691872 -248.211848)
		(width 0.0889)
		(layer "In2.Cu")
		(net "M_I_CPU1_SA_CB<6>")
	)
	(arc
		(start 137.811764 -248.211848)
		(mid 138.09472 -248.288025)
		(end 138.377676 -248.211848)
		(width 0.0889)
		(layer "In2.Cu")
		(net "M_I_CPU1_SA_CB<6>")
	)
	(arc
		(start 129.92608 -248.207022)
		(mid 130.109588 -248.161528)
		(end 130.29184 -248.211848)
		(width 0.0889)
		(layer "In2.Cu")
		(net "M_I_CPU1_SA_CB<6>")
	)
	(arc
		(start 137.437622 -248.211848)
		(mid 137.619873 -248.161498)
		(end 137.803382 -248.207022)
		(width 0.0889)
		(layer "In2.Cu")
		(net "M_I_CPU1_SA_CB<6>")
	)
	(arc
		(start 140.266166 -248.207022)
		(mid 140.449674 -248.161528)
		(end 140.631926 -248.211848)
		(width 0.0889)
		(layer "In2.Cu")
		(net "M_I_CPU1_SA_CB<6>")
	)
	(arc
		(start 138.751818 -248.211848)
		(mid 139.034774 -248.288025)
		(end 139.31773 -248.211848)
		(width 0.0889)
		(layer "In2.Cu")
		(net "M_I_CPU1_SA_CB<6>")
	)
	(arc
		(start 130.29184 -248.211848)
		(mid 130.574796 -248.288025)
		(end 130.857752 -248.211848)
		(width 0.0889)
		(layer "In2.Cu")
		(net "M_I_CPU1_SA_CB<6>")
	)
	(arc
		(start 131.797806 -248.211848)
		(mid 131.98475 -248.161593)
		(end 132.171694 -248.211848)
		(width 0.0889)
		(layer "In2.Cu")
		(net "M_I_CPU1_SA_CB<6>")
	)
	(arc
		(start 144.956276 -248.211848)
		(mid 145.126283 -248.161283)
		(end 145.300446 -248.19483)
		(width 0.0889)
		(layer "In2.Cu")
		(net "M_I_CPU1_SA_CB<6>")
	)
	(arc
		(start 129.414778 -248.243598)
		(mid 129.669986 -248.287075)
		(end 129.917698 -248.211848)
		(width 0.0889)
		(layer "In2.Cu")
		(net "M_I_CPU1_SA_CB<6>")
	)
	(arc
		(start 144.037812 -248.199656)
		(mid 144.21474 -248.161828)
		(end 144.388586 -248.211848)
		(width 0.0889)
		(layer "In2.Cu")
		(net "M_I_CPU1_SA_CB<6>")
	)
	(arc
		(start 134.626096 -248.207022)
		(mid 134.809604 -248.161528)
		(end 134.991856 -248.211848)
		(width 0.0889)
		(layer "In2.Cu")
		(net "M_I_CPU1_SA_CB<6>")
	)
	(arc
		(start 140.631926 -248.211848)
		(mid 140.914882 -248.288025)
		(end 141.197838 -248.211848)
		(width 0.0889)
		(layer "In2.Cu")
		(net "M_I_CPU1_SA_CB<6>")
	)
	(arc
		(start 136.497822 -248.211848)
		(mid 136.684766 -248.161593)
		(end 136.87171 -248.211848)
		(width 0.0889)
		(layer "In2.Cu")
		(net "M_I_CPU1_SA_CB<6>")
	)
	(arc
		(start 142.137638 -248.211848)
		(mid 142.319889 -248.161498)
		(end 142.503398 -248.207022)
		(width 0.0889)
		(layer "In2.Cu")
		(net "M_I_CPU1_SA_CB<6>")
	)
	(arc
		(start 133.67766 -248.211848)
		(mid 133.859911 -248.161498)
		(end 134.04342 -248.207022)
		(width 0.0889)
		(layer "In2.Cu")
		(net "M_I_CPU1_SA_CB<6>")
	)
	(arc
		(start 132.737606 -248.211848)
		(mid 132.919857 -248.161498)
		(end 133.103366 -248.207022)
		(width 0.0889)
		(layer "In2.Cu")
		(net "M_I_CPU1_SA_CB<6>")
	)
	(arc
		(start 132.171694 -248.211848)
		(mid 132.45465 -248.288025)
		(end 132.737606 -248.211848)
		(width 0.0889)
		(layer "In2.Cu")
		(net "M_I_CPU1_SA_CB<6>")
	)
	(arc
		(start 131.231894 -248.211848)
		(mid 131.51485 -248.288025)
		(end 131.797806 -248.211848)
		(width 0.0889)
		(layer "In2.Cu")
		(net "M_I_CPU1_SA_CB<6>")
	)
	(arc
		(start 144.416272 -248.22785)
		(mid 144.688306 -248.288622)
		(end 144.956276 -248.211848)
		(width 0.0889)
		(layer "In2.Cu")
		(net "M_I_CPU1_SA_CB<6>")
	)
	(arc
		(start 133.111748 -248.211848)
		(mid 133.394704 -248.288025)
		(end 133.67766 -248.211848)
		(width 0.0889)
		(layer "In2.Cu")
		(net "M_I_CPU1_SA_CB<6>")
	)
	(arc
		(start 135.56615 -248.207022)
		(mid 135.749658 -248.161528)
		(end 135.93191 -248.211848)
		(width 0.0889)
		(layer "In2.Cu")
		(net "M_I_CPU1_SA_CB<6>")
	)
	(arc
		(start 141.571726 -248.211848)
		(mid 141.854682 -248.288025)
		(end 142.137638 -248.211848)
		(width 0.0889)
		(layer "In2.Cu")
		(net "M_I_CPU1_SA_CB<6>")
	)
	(arc
		(start 138.377676 -248.211848)
		(mid 138.559927 -248.161498)
		(end 138.743436 -248.207022)
		(width 0.0889)
		(layer "In2.Cu")
		(net "M_I_CPU1_SA_CB<6>")
	)
	(arc
		(start 141.197838 -248.211848)
		(mid 141.384782 -248.161593)
		(end 141.571726 -248.211848)
		(width 0.0889)
		(layer "In2.Cu")
		(net "M_I_CPU1_SA_CB<6>")
	)
	(arc
		(start 135.93191 -248.211848)
		(mid 136.214866 -248.288025)
		(end 136.497822 -248.211848)
		(width 0.0889)
		(layer "In2.Cu")
		(net "M_I_CPU1_SA_CB<6>")
	)
	(arc
		(start 130.866134 -248.207022)
		(mid 131.049642 -248.161528)
		(end 131.231894 -248.211848)
		(width 0.0889)
		(layer "In2.Cu")
		(net "M_I_CPU1_SA_CB<6>")
	)
	(arc
		(start 134.991856 -248.211848)
		(mid 135.274812 -248.288025)
		(end 135.557768 -248.211848)
		(width 0.0889)
		(layer "In2.Cu")
		(net "M_I_CPU1_SA_CB<6>")
	)
	(arc
		(start 136.87171 -248.211848)
		(mid 137.154666 -248.288025)
		(end 137.437622 -248.211848)
		(width 0.0889)
		(layer "In2.Cu")
		(net "M_I_CPU1_SA_CB<6>")
	)
	(segment
		(start 127.757936 -248.800366)
		(end 128.224788 -248.534428)
		(width 0.10668)
		(layer "F.Cu")
		(net "M_I_CPU1_SA_CB<5>")
	)
	(segment
		(start 181.42331 -242.810284)
		(end 181.651656 -242.810284)
		(width 0.14478)
		(layer "In2.Cu")
		(net "M_I_CPU1_SA_CB<5>")
	)
	(segment
		(start 181.974744 -242.102386)
		(end 182.20309 -242.102386)
		(width 0.14478)
		(layer "In2.Cu")
		(net "M_I_CPU1_SA_CB<5>")
	)
	(segment
		(start 128.07061 -248.799858)
		(end 128.092962 -248.88317)
		(width 0.0889)
		(layer "In2.Cu")
		(net "M_I_CPU1_SA_CB<5>")
	)
	(segment
		(start 149.567646 -248.426986)
		(end 159.633158 -248.426986)
		(width 0.14478)
		(layer "In2.Cu")
		(net "M_I_CPU1_SA_CB<5>")
	)
	(segment
		(start 130.857752 -248.857008)
		(end 130.866134 -248.861834)
		(width 0.0889)
		(layer "In2.Cu")
		(net "M_I_CPU1_SA_CB<5>")
	)
	(segment
		(start 159.633158 -248.426986)
		(end 163.540186 -244.519958)
		(width 0.14478)
		(layer "In2.Cu")
		(net "M_I_CPU1_SA_CB<5>")
	)
	(segment
		(start 142.503398 -248.861834)
		(end 142.51178 -248.857008)
		(width 0.0889)
		(layer "In2.Cu")
		(net "M_I_CPU1_SA_CB<5>")
	)
	(segment
		(start 180.871876 -242.102386)
		(end 181.100222 -242.102386)
		(width 0.14478)
		(layer "In2.Cu")
		(net "M_I_CPU1_SA_CB<5>")
	)
	(segment
		(start 147.969986 -249.180604)
		(end 148.814028 -249.180604)
		(width 0.14478)
		(layer "In2.Cu")
		(net "M_I_CPU1_SA_CB<5>")
	)
	(segment
		(start 181.261766 -242.64874)
		(end 181.42331 -242.810284)
		(width 0.14478)
		(layer "In2.Cu")
		(net "M_I_CPU1_SA_CB<5>")
	)
	(segment
		(start 135.557768 -248.857008)
		(end 135.56615 -248.861834)
		(width 0.0889)
		(layer "In2.Cu")
		(net "M_I_CPU1_SA_CB<5>")
	)
	(segment
		(start 129.917698 -248.857008)
		(end 129.92608 -248.861834)
		(width 0.0889)
		(layer "In2.Cu")
		(net "M_I_CPU1_SA_CB<5>")
	)
	(segment
		(start 182.526178 -242.810284)
		(end 183.19115 -242.810284)
		(width 0.14478)
		(layer "In2.Cu")
		(net "M_I_CPU1_SA_CB<5>")
	)
	(segment
		(start 182.364634 -242.64874)
		(end 182.526178 -242.810284)
		(width 0.14478)
		(layer "In2.Cu")
		(net "M_I_CPU1_SA_CB<5>")
	)
	(segment
		(start 181.100222 -242.102386)
		(end 181.261766 -242.26393)
		(width 0.14478)
		(layer "In2.Cu")
		(net "M_I_CPU1_SA_CB<5>")
	)
	(segment
		(start 139.31773 -248.857008)
		(end 139.326112 -248.861834)
		(width 0.0889)
		(layer "In2.Cu")
		(net "M_I_CPU1_SA_CB<5>")
	)
	(segment
		(start 181.8132 -242.26393)
		(end 181.974744 -242.102386)
		(width 0.14478)
		(layer "In2.Cu")
		(net "M_I_CPU1_SA_CB<5>")
	)
	(segment
		(start 133.103366 -248.861834)
		(end 133.111748 -248.857008)
		(width 0.0889)
		(layer "In2.Cu")
		(net "M_I_CPU1_SA_CB<5>")
	)
	(segment
		(start 180.710332 -242.64874)
		(end 180.710332 -242.26393)
		(width 0.14478)
		(layer "In2.Cu")
		(net "M_I_CPU1_SA_CB<5>")
	)
	(segment
		(start 128.40335 -248.861834)
		(end 128.411732 -248.857008)
		(width 0.0889)
		(layer "In2.Cu")
		(net "M_I_CPU1_SA_CB<5>")
	)
	(segment
		(start 180.548788 -242.810284)
		(end 180.710332 -242.64874)
		(width 0.14478)
		(layer "In2.Cu")
		(net "M_I_CPU1_SA_CB<5>")
	)
	(segment
		(start 182.20309 -242.102386)
		(end 182.364634 -242.26393)
		(width 0.14478)
		(layer "In2.Cu")
		(net "M_I_CPU1_SA_CB<5>")
	)
	(segment
		(start 183.19115 -242.810284)
		(end 183.616092 -242.385342)
		(width 0.14478)
		(layer "In2.Cu")
		(net "M_I_CPU1_SA_CB<5>")
	)
	(segment
		(start 181.261766 -242.26393)
		(end 181.261766 -242.64874)
		(width 0.14478)
		(layer "In2.Cu")
		(net "M_I_CPU1_SA_CB<5>")
	)
	(segment
		(start 172.705014 -244.519958)
		(end 174.414688 -242.810284)
		(width 0.14478)
		(layer "In2.Cu")
		(net "M_I_CPU1_SA_CB<5>")
	)
	(segment
		(start 134.617714 -248.857008)
		(end 134.626096 -248.861834)
		(width 0.0889)
		(layer "In2.Cu")
		(net "M_I_CPU1_SA_CB<5>")
	)
	(segment
		(start 180.710332 -242.26393)
		(end 180.871876 -242.102386)
		(width 0.14478)
		(layer "In2.Cu")
		(net "M_I_CPU1_SA_CB<5>")
	)
	(segment
		(start 137.803382 -248.861834)
		(end 137.811764 -248.857008)
		(width 0.0889)
		(layer "In2.Cu")
		(net "M_I_CPU1_SA_CB<5>")
	)
	(segment
		(start 134.04342 -248.861834)
		(end 134.051802 -248.857008)
		(width 0.0889)
		(layer "In2.Cu")
		(net "M_I_CPU1_SA_CB<5>")
	)
	(segment
		(start 129.343404 -248.861834)
		(end 129.351786 -248.857008)
		(width 0.0889)
		(layer "In2.Cu")
		(net "M_I_CPU1_SA_CB<5>")
	)
	(segment
		(start 144.952466 -248.853452)
		(end 144.958054 -248.856754)
		(width 0.0889)
		(layer "In2.Cu")
		(net "M_I_CPU1_SA_CB<5>")
	)
	(segment
		(start 148.814028 -249.180604)
		(end 149.567646 -248.426986)
		(width 0.14478)
		(layer "In2.Cu")
		(net "M_I_CPU1_SA_CB<5>")
	)
	(segment
		(start 138.743436 -248.861834)
		(end 138.751818 -248.857008)
		(width 0.0889)
		(layer "In2.Cu")
		(net "M_I_CPU1_SA_CB<5>")
	)
	(segment
		(start 147.274788 -249.180604)
		(end 147.969986 -249.180604)
		(width 0.0889)
		(layer "In2.Cu")
		(net "M_I_CPU1_SA_CB<5>")
	)
	(segment
		(start 145.566638 -249.021346)
		(end 147.11553 -249.021346)
		(width 0.0889)
		(layer "In2.Cu")
		(net "M_I_CPU1_SA_CB<5>")
	)
	(segment
		(start 143.077692 -248.857008)
		(end 143.086074 -248.861834)
		(width 0.0889)
		(layer "In2.Cu")
		(net "M_I_CPU1_SA_CB<5>")
	)
	(segment
		(start 147.11553 -249.021346)
		(end 147.274788 -249.180604)
		(width 0.0889)
		(layer "In2.Cu")
		(net "M_I_CPU1_SA_CB<5>")
	)
	(segment
		(start 143.451834 -248.857008)
		(end 143.466566 -248.848372)
		(width 0.0889)
		(layer "In2.Cu")
		(net "M_I_CPU1_SA_CB<5>")
	)
	(segment
		(start 174.414688 -242.810284)
		(end 180.548788 -242.810284)
		(width 0.14478)
		(layer "In2.Cu")
		(net "M_I_CPU1_SA_CB<5>")
	)
	(segment
		(start 128.224788 -248.534428)
		(end 128.07061 -248.799858)
		(width 0.0889)
		(layer "In2.Cu")
		(net "M_I_CPU1_SA_CB<5>")
	)
	(segment
		(start 163.540186 -244.519958)
		(end 172.705014 -244.519958)
		(width 0.14478)
		(layer "In2.Cu")
		(net "M_I_CPU1_SA_CB<5>")
	)
	(segment
		(start 181.651656 -242.810284)
		(end 181.8132 -242.64874)
		(width 0.14478)
		(layer "In2.Cu")
		(net "M_I_CPU1_SA_CB<5>")
	)
	(segment
		(start 182.364634 -242.26393)
		(end 182.364634 -242.64874)
		(width 0.14478)
		(layer "In2.Cu")
		(net "M_I_CPU1_SA_CB<5>")
	)
	(segment
		(start 181.8132 -242.64874)
		(end 181.8132 -242.26393)
		(width 0.14478)
		(layer "In2.Cu")
		(net "M_I_CPU1_SA_CB<5>")
	)
	(segment
		(start 144.380966 -248.863866)
		(end 144.39265 -248.857008)
		(width 0.0889)
		(layer "In2.Cu")
		(net "M_I_CPU1_SA_CB<5>")
	)
	(segment
		(start 140.257784 -248.857008)
		(end 140.266166 -248.861834)
		(width 0.0889)
		(layer "In2.Cu")
		(net "M_I_CPU1_SA_CB<5>")
	)
	(arc
		(start 143.466566 -248.848372)
		(mid 143.743549 -248.780568)
		(end 144.018254 -248.857008)
		(width 0.0889)
		(layer "In2.Cu")
		(net "M_I_CPU1_SA_CB<5>")
	)
	(arc
		(start 129.351786 -248.857008)
		(mid 129.634742 -248.780831)
		(end 129.917698 -248.857008)
		(width 0.0889)
		(layer "In2.Cu")
		(net "M_I_CPU1_SA_CB<5>")
	)
	(arc
		(start 136.497822 -248.857008)
		(mid 136.684766 -248.907263)
		(end 136.87171 -248.857008)
		(width 0.0889)
		(layer "In2.Cu")
		(net "M_I_CPU1_SA_CB<5>")
	)
	(arc
		(start 137.811764 -248.857008)
		(mid 138.09472 -248.780831)
		(end 138.377676 -248.857008)
		(width 0.0889)
		(layer "In2.Cu")
		(net "M_I_CPU1_SA_CB<5>")
	)
	(arc
		(start 144.39265 -248.857008)
		(mid 144.672078 -248.780842)
		(end 144.952466 -248.853452)
		(width 0.0889)
		(layer "In2.Cu")
		(net "M_I_CPU1_SA_CB<5>")
	)
	(arc
		(start 142.51178 -248.857008)
		(mid 142.794736 -248.780831)
		(end 143.077692 -248.857008)
		(width 0.0889)
		(layer "In2.Cu")
		(net "M_I_CPU1_SA_CB<5>")
	)
	(arc
		(start 138.377676 -248.857008)
		(mid 138.559927 -248.907358)
		(end 138.743436 -248.861834)
		(width 0.0889)
		(layer "In2.Cu")
		(net "M_I_CPU1_SA_CB<5>")
	)
	(arc
		(start 134.991856 -248.857008)
		(mid 135.274812 -248.780831)
		(end 135.557768 -248.857008)
		(width 0.0889)
		(layer "In2.Cu")
		(net "M_I_CPU1_SA_CB<5>")
	)
	(arc
		(start 143.086074 -248.861834)
		(mid 143.269582 -248.907328)
		(end 143.451834 -248.857008)
		(width 0.0889)
		(layer "In2.Cu")
		(net "M_I_CPU1_SA_CB<5>")
	)
	(arc
		(start 139.326112 -248.861834)
		(mid 139.50962 -248.907328)
		(end 139.691872 -248.857008)
		(width 0.0889)
		(layer "In2.Cu")
		(net "M_I_CPU1_SA_CB<5>")
	)
	(arc
		(start 139.691872 -248.857008)
		(mid 139.974828 -248.780831)
		(end 140.257784 -248.857008)
		(width 0.0889)
		(layer "In2.Cu")
		(net "M_I_CPU1_SA_CB<5>")
	)
	(arc
		(start 131.231894 -248.857008)
		(mid 131.51485 -248.780831)
		(end 131.797806 -248.857008)
		(width 0.0889)
		(layer "In2.Cu")
		(net "M_I_CPU1_SA_CB<5>")
	)
	(arc
		(start 134.626096 -248.861834)
		(mid 134.809604 -248.907328)
		(end 134.991856 -248.857008)
		(width 0.0889)
		(layer "In2.Cu")
		(net "M_I_CPU1_SA_CB<5>")
	)
	(arc
		(start 128.977644 -248.857008)
		(mid 129.159895 -248.907358)
		(end 129.343404 -248.861834)
		(width 0.0889)
		(layer "In2.Cu")
		(net "M_I_CPU1_SA_CB<5>")
	)
	(arc
		(start 129.92608 -248.861834)
		(mid 130.109588 -248.907328)
		(end 130.29184 -248.857008)
		(width 0.0889)
		(layer "In2.Cu")
		(net "M_I_CPU1_SA_CB<5>")
	)
	(arc
		(start 142.137638 -248.857008)
		(mid 142.319889 -248.907358)
		(end 142.503398 -248.861834)
		(width 0.0889)
		(layer "In2.Cu")
		(net "M_I_CPU1_SA_CB<5>")
	)
	(arc
		(start 132.171694 -248.857008)
		(mid 132.45465 -248.780831)
		(end 132.737606 -248.857008)
		(width 0.0889)
		(layer "In2.Cu")
		(net "M_I_CPU1_SA_CB<5>")
	)
	(arc
		(start 135.56615 -248.861834)
		(mid 135.749658 -248.907328)
		(end 135.93191 -248.857008)
		(width 0.0889)
		(layer "In2.Cu")
		(net "M_I_CPU1_SA_CB<5>")
	)
	(arc
		(start 137.437622 -248.857008)
		(mid 137.619873 -248.907358)
		(end 137.803382 -248.861834)
		(width 0.0889)
		(layer "In2.Cu")
		(net "M_I_CPU1_SA_CB<5>")
	)
	(arc
		(start 130.29184 -248.857008)
		(mid 130.574796 -248.780831)
		(end 130.857752 -248.857008)
		(width 0.0889)
		(layer "In2.Cu")
		(net "M_I_CPU1_SA_CB<5>")
	)
	(arc
		(start 138.751818 -248.857008)
		(mid 139.034774 -248.780831)
		(end 139.31773 -248.857008)
		(width 0.0889)
		(layer "In2.Cu")
		(net "M_I_CPU1_SA_CB<5>")
	)
	(arc
		(start 141.197838 -248.857008)
		(mid 141.384782 -248.907263)
		(end 141.571726 -248.857008)
		(width 0.0889)
		(layer "In2.Cu")
		(net "M_I_CPU1_SA_CB<5>")
	)
	(arc
		(start 130.866134 -248.861834)
		(mid 131.049642 -248.907328)
		(end 131.231894 -248.857008)
		(width 0.0889)
		(layer "In2.Cu")
		(net "M_I_CPU1_SA_CB<5>")
	)
	(arc
		(start 144.018254 -248.857008)
		(mid 144.198712 -248.907452)
		(end 144.380966 -248.863866)
		(width 0.0889)
		(layer "In2.Cu")
		(net "M_I_CPU1_SA_CB<5>")
	)
	(arc
		(start 140.266166 -248.861834)
		(mid 140.449674 -248.907328)
		(end 140.631926 -248.857008)
		(width 0.0889)
		(layer "In2.Cu")
		(net "M_I_CPU1_SA_CB<5>")
	)
	(arc
		(start 133.67766 -248.857008)
		(mid 133.859911 -248.907358)
		(end 134.04342 -248.861834)
		(width 0.0889)
		(layer "In2.Cu")
		(net "M_I_CPU1_SA_CB<5>")
	)
	(arc
		(start 132.737606 -248.857008)
		(mid 132.919857 -248.907358)
		(end 133.103366 -248.861834)
		(width 0.0889)
		(layer "In2.Cu")
		(net "M_I_CPU1_SA_CB<5>")
	)
	(arc
		(start 141.571726 -248.857008)
		(mid 141.854682 -248.780831)
		(end 142.137638 -248.857008)
		(width 0.0889)
		(layer "In2.Cu")
		(net "M_I_CPU1_SA_CB<5>")
	)
	(arc
		(start 144.958054 -248.856754)
		(mid 145.25142 -248.979437)
		(end 145.566638 -249.021346)
		(width 0.0889)
		(layer "In2.Cu")
		(net "M_I_CPU1_SA_CB<5>")
	)
	(arc
		(start 135.93191 -248.857008)
		(mid 136.214866 -248.780831)
		(end 136.497822 -248.857008)
		(width 0.0889)
		(layer "In2.Cu")
		(net "M_I_CPU1_SA_CB<5>")
	)
	(arc
		(start 128.092962 -248.88317)
		(mid 128.250472 -248.906368)
		(end 128.40335 -248.861834)
		(width 0.0889)
		(layer "In2.Cu")
		(net "M_I_CPU1_SA_CB<5>")
	)
	(arc
		(start 133.111748 -248.857008)
		(mid 133.394704 -248.780831)
		(end 133.67766 -248.857008)
		(width 0.0889)
		(layer "In2.Cu")
		(net "M_I_CPU1_SA_CB<5>")
	)
	(arc
		(start 131.797806 -248.857008)
		(mid 131.98475 -248.907263)
		(end 132.171694 -248.857008)
		(width 0.0889)
		(layer "In2.Cu")
		(net "M_I_CPU1_SA_CB<5>")
	)
	(arc
		(start 134.051802 -248.857008)
		(mid 134.334758 -248.780831)
		(end 134.617714 -248.857008)
		(width 0.0889)
		(layer "In2.Cu")
		(net "M_I_CPU1_SA_CB<5>")
	)
	(arc
		(start 136.87171 -248.857008)
		(mid 137.154666 -248.780831)
		(end 137.437622 -248.857008)
		(width 0.0889)
		(layer "In2.Cu")
		(net "M_I_CPU1_SA_CB<5>")
	)
	(arc
		(start 140.631926 -248.857008)
		(mid 140.914882 -248.780831)
		(end 141.197838 -248.857008)
		(width 0.0889)
		(layer "In2.Cu")
		(net "M_I_CPU1_SA_CB<5>")
	)
	(arc
		(start 128.411732 -248.857008)
		(mid 128.694688 -248.780831)
		(end 128.977644 -248.857008)
		(width 0.0889)
		(layer "In2.Cu")
		(net "M_I_CPU1_SA_CB<5>")
	)
	(segment
		(start 129.16789 -247.99036)
		(end 129.634742 -247.724422)
		(width 0.10668)
		(layer "F.Cu")
		(net "M_I_CPU1_SA_CB<4>")
	)
	(segment
		(start 167.682164 -241.960146)
		(end 173.278292 -241.960146)
		(width 0.14478)
		(layer "In2.Cu")
		(net "M_I_CPU1_SA_CB<4>")
	)
	(segment
		(start 166.969186 -241.798602)
		(end 166.969186 -241.35715)
		(width 0.14478)
		(layer "In2.Cu")
		(net "M_I_CPU1_SA_CB<4>")
	)
	(segment
		(start 167.52062 -241.798602)
		(end 167.682164 -241.960146)
		(width 0.14478)
		(layer "In2.Cu")
		(net "M_I_CPU1_SA_CB<4>")
	)
	(segment
		(start 146.612102 -248.365264)
		(end 147.322032 -248.365264)
		(width 0.0889)
		(layer "In2.Cu")
		(net "M_I_CPU1_SA_CB<4>")
	)
	(segment
		(start 130.753358 -248.051828)
		(end 130.76174 -248.047002)
		(width 0.0889)
		(layer "In2.Cu")
		(net "M_I_CPU1_SA_CB<4>")
	)
	(segment
		(start 140.15339 -248.051828)
		(end 140.161772 -248.047002)
		(width 0.0889)
		(layer "In2.Cu")
		(net "M_I_CPU1_SA_CB<4>")
	)
	(segment
		(start 149.183598 -247.508014)
		(end 159.280098 -247.508014)
		(width 0.14478)
		(layer "In2.Cu")
		(net "M_I_CPU1_SA_CB<4>")
	)
	(segment
		(start 133.20776 -248.047002)
		(end 133.216142 -248.051828)
		(width 0.0889)
		(layer "In2.Cu")
		(net "M_I_CPU1_SA_CB<4>")
	)
	(segment
		(start 166.807642 -241.960146)
		(end 166.969186 -241.798602)
		(width 0.14478)
		(layer "In2.Cu")
		(net "M_I_CPU1_SA_CB<4>")
	)
	(segment
		(start 131.693412 -248.051828)
		(end 131.701794 -248.047002)
		(width 0.0889)
		(layer "In2.Cu")
		(net "M_I_CPU1_SA_CB<4>")
	)
	(segment
		(start 148.430488 -248.261124)
		(end 149.183598 -247.508014)
		(width 0.14478)
		(layer "In2.Cu")
		(net "M_I_CPU1_SA_CB<4>")
	)
	(segment
		(start 145.387822 -248.024904)
		(end 145.425668 -248.046748)
		(width 0.0889)
		(layer "In2.Cu")
		(net "M_I_CPU1_SA_CB<4>")
	)
	(segment
		(start 174.133256 -241.110262)
		(end 183.19115 -241.110262)
		(width 0.14478)
		(layer "In2.Cu")
		(net "M_I_CPU1_SA_CB<4>")
	)
	(segment
		(start 147.919186 -248.261124)
		(end 148.430488 -248.261124)
		(width 0.14478)
		(layer "In2.Cu")
		(net "M_I_CPU1_SA_CB<4>")
	)
	(segment
		(start 137.907776 -248.047002)
		(end 137.916158 -248.051828)
		(width 0.0889)
		(layer "In2.Cu")
		(net "M_I_CPU1_SA_CB<4>")
	)
	(segment
		(start 167.359076 -241.195606)
		(end 167.52062 -241.35715)
		(width 0.14478)
		(layer "In2.Cu")
		(net "M_I_CPU1_SA_CB<4>")
	)
	(segment
		(start 135.453374 -248.051828)
		(end 135.461756 -248.047002)
		(width 0.0889)
		(layer "In2.Cu")
		(net "M_I_CPU1_SA_CB<4>")
	)
	(segment
		(start 167.13073 -241.195606)
		(end 167.359076 -241.195606)
		(width 0.14478)
		(layer "In2.Cu")
		(net "M_I_CPU1_SA_CB<4>")
	)
	(segment
		(start 173.278292 -241.960146)
		(end 174.130716 -241.107722)
		(width 0.14478)
		(layer "In2.Cu")
		(net "M_I_CPU1_SA_CB<4>")
	)
	(segment
		(start 143.897096 -248.06021)
		(end 143.920464 -248.046748)
		(width 0.0889)
		(layer "In2.Cu")
		(net "M_I_CPU1_SA_CB<4>")
	)
	(segment
		(start 163.47821 -243.309902)
		(end 163.47821 -242.44681)
		(width 0.14478)
		(layer "In2.Cu")
		(net "M_I_CPU1_SA_CB<4>")
	)
	(segment
		(start 165.866318 -241.798602)
		(end 165.866318 -241.35715)
		(width 0.14478)
		(layer "In2.Cu")
		(net "M_I_CPU1_SA_CB<4>")
	)
	(segment
		(start 129.480818 -247.989852)
		(end 129.50317 -248.073164)
		(width 0.0889)
		(layer "In2.Cu")
		(net "M_I_CPU1_SA_CB<4>")
	)
	(segment
		(start 166.579296 -241.960146)
		(end 166.807642 -241.960146)
		(width 0.14478)
		(layer "In2.Cu")
		(net "M_I_CPU1_SA_CB<4>")
	)
	(segment
		(start 136.967722 -248.047002)
		(end 136.976104 -248.051828)
		(width 0.0889)
		(layer "In2.Cu")
		(net "M_I_CPU1_SA_CB<4>")
	)
	(segment
		(start 166.027862 -241.195606)
		(end 166.256208 -241.195606)
		(width 0.14478)
		(layer "In2.Cu")
		(net "M_I_CPU1_SA_CB<4>")
	)
	(segment
		(start 166.969186 -241.35715)
		(end 167.13073 -241.195606)
		(width 0.14478)
		(layer "In2.Cu")
		(net "M_I_CPU1_SA_CB<4>")
	)
	(segment
		(start 183.19115 -241.110262)
		(end 183.616092 -240.68532)
		(width 0.14478)
		(layer "In2.Cu")
		(net "M_I_CPU1_SA_CB<4>")
	)
	(segment
		(start 163.47821 -242.44681)
		(end 163.964874 -241.960146)
		(width 0.14478)
		(layer "In2.Cu")
		(net "M_I_CPU1_SA_CB<4>")
	)
	(segment
		(start 163.964874 -241.960146)
		(end 165.704774 -241.960146)
		(width 0.14478)
		(layer "In2.Cu")
		(net "M_I_CPU1_SA_CB<4>")
	)
	(segment
		(start 166.417752 -241.35715)
		(end 166.417752 -241.798602)
		(width 0.14478)
		(layer "In2.Cu")
		(net "M_I_CPU1_SA_CB<4>")
	)
	(segment
		(start 166.417752 -241.798602)
		(end 166.579296 -241.960146)
		(width 0.14478)
		(layer "In2.Cu")
		(net "M_I_CPU1_SA_CB<4>")
	)
	(segment
		(start 129.634742 -247.724422)
		(end 129.480818 -247.989852)
		(width 0.0889)
		(layer "In2.Cu")
		(net "M_I_CPU1_SA_CB<4>")
	)
	(segment
		(start 141.093444 -248.051828)
		(end 141.101826 -248.047002)
		(width 0.0889)
		(layer "In2.Cu")
		(net "M_I_CPU1_SA_CB<4>")
	)
	(segment
		(start 167.52062 -241.35715)
		(end 167.52062 -241.798602)
		(width 0.14478)
		(layer "In2.Cu")
		(net "M_I_CPU1_SA_CB<4>")
	)
	(segment
		(start 165.866318 -241.35715)
		(end 166.027862 -241.195606)
		(width 0.14478)
		(layer "In2.Cu")
		(net "M_I_CPU1_SA_CB<4>")
	)
	(segment
		(start 132.267706 -248.047002)
		(end 132.276088 -248.051828)
		(width 0.0889)
		(layer "In2.Cu")
		(net "M_I_CPU1_SA_CB<4>")
	)
	(segment
		(start 147.426172 -248.261124)
		(end 147.919186 -248.261124)
		(width 0.0889)
		(layer "In2.Cu")
		(net "M_I_CPU1_SA_CB<4>")
	)
	(segment
		(start 144.484598 -248.047002)
		(end 144.505172 -248.05894)
		(width 0.0889)
		(layer "In2.Cu")
		(net "M_I_CPU1_SA_CB<4>")
	)
	(segment
		(start 141.667738 -248.047002)
		(end 141.67612 -248.051828)
		(width 0.0889)
		(layer "In2.Cu")
		(net "M_I_CPU1_SA_CB<4>")
	)
	(segment
		(start 166.256208 -241.195606)
		(end 166.417752 -241.35715)
		(width 0.14478)
		(layer "In2.Cu")
		(net "M_I_CPU1_SA_CB<4>")
	)
	(segment
		(start 159.280098 -247.508014)
		(end 163.47821 -243.309902)
		(width 0.14478)
		(layer "In2.Cu")
		(net "M_I_CPU1_SA_CB<4>")
	)
	(segment
		(start 143.920464 -248.046748)
		(end 143.94434 -248.032778)
		(width 0.0889)
		(layer "In2.Cu")
		(net "M_I_CPU1_SA_CB<4>")
	)
	(segment
		(start 147.322032 -248.365264)
		(end 147.426172 -248.261124)
		(width 0.0889)
		(layer "In2.Cu")
		(net "M_I_CPU1_SA_CB<4>")
	)
	(segment
		(start 165.704774 -241.960146)
		(end 165.866318 -241.798602)
		(width 0.14478)
		(layer "In2.Cu")
		(net "M_I_CPU1_SA_CB<4>")
	)
	(segment
		(start 136.393428 -248.051828)
		(end 136.40181 -248.047002)
		(width 0.0889)
		(layer "In2.Cu")
		(net "M_I_CPU1_SA_CB<4>")
	)
	(segment
		(start 174.130716 -241.107722)
		(end 174.133256 -241.110262)
		(width 0.14478)
		(layer "In2.Cu")
		(net "M_I_CPU1_SA_CB<4>")
	)
	(arc
		(start 140.727684 -248.047002)
		(mid 140.909935 -248.097352)
		(end 141.093444 -248.051828)
		(width 0.0889)
		(layer "In2.Cu")
		(net "M_I_CPU1_SA_CB<4>")
	)
	(arc
		(start 135.461756 -248.047002)
		(mid 135.744712 -247.970825)
		(end 136.027668 -248.047002)
		(width 0.0889)
		(layer "In2.Cu")
		(net "M_I_CPU1_SA_CB<4>")
	)
	(arc
		(start 138.281918 -248.047002)
		(mid 138.564874 -247.970825)
		(end 138.84783 -248.047002)
		(width 0.0889)
		(layer "In2.Cu")
		(net "M_I_CPU1_SA_CB<4>")
	)
	(arc
		(start 130.76174 -248.047002)
		(mid 131.044696 -247.970825)
		(end 131.327652 -248.047002)
		(width 0.0889)
		(layer "In2.Cu")
		(net "M_I_CPU1_SA_CB<4>")
	)
	(arc
		(start 143.94434 -248.032778)
		(mid 144.216277 -247.970952)
		(end 144.484598 -248.047002)
		(width 0.0889)
		(layer "In2.Cu")
		(net "M_I_CPU1_SA_CB<4>")
	)
	(arc
		(start 142.98168 -248.047002)
		(mid 143.264636 -247.970825)
		(end 143.547592 -248.047002)
		(width 0.0889)
		(layer "In2.Cu")
		(net "M_I_CPU1_SA_CB<4>")
	)
	(arc
		(start 140.161772 -248.047002)
		(mid 140.444728 -247.970825)
		(end 140.727684 -248.047002)
		(width 0.0889)
		(layer "In2.Cu")
		(net "M_I_CPU1_SA_CB<4>")
	)
	(arc
		(start 144.86001 -248.047002)
		(mid 145.121168 -247.970423)
		(end 145.387822 -248.024904)
		(width 0.0889)
		(layer "In2.Cu")
		(net "M_I_CPU1_SA_CB<4>")
	)
	(arc
		(start 134.521702 -248.047002)
		(mid 134.804658 -247.970825)
		(end 135.087614 -248.047002)
		(width 0.0889)
		(layer "In2.Cu")
		(net "M_I_CPU1_SA_CB<4>")
	)
	(arc
		(start 137.341864 -248.047002)
		(mid 137.62482 -247.970825)
		(end 137.907776 -248.047002)
		(width 0.0889)
		(layer "In2.Cu")
		(net "M_I_CPU1_SA_CB<4>")
	)
	(arc
		(start 134.147814 -248.047002)
		(mid 134.334758 -248.097257)
		(end 134.521702 -248.047002)
		(width 0.0889)
		(layer "In2.Cu")
		(net "M_I_CPU1_SA_CB<4>")
	)
	(arc
		(start 136.027668 -248.047002)
		(mid 136.209919 -248.097352)
		(end 136.393428 -248.051828)
		(width 0.0889)
		(layer "In2.Cu")
		(net "M_I_CPU1_SA_CB<4>")
	)
	(arc
		(start 129.50317 -248.073164)
		(mid 129.665359 -248.095899)
		(end 129.821686 -248.047002)
		(width 0.0889)
		(layer "In2.Cu")
		(net "M_I_CPU1_SA_CB<4>")
	)
	(arc
		(start 136.976104 -248.051828)
		(mid 137.159612 -248.097322)
		(end 137.341864 -248.047002)
		(width 0.0889)
		(layer "In2.Cu")
		(net "M_I_CPU1_SA_CB<4>")
	)
	(arc
		(start 136.40181 -248.047002)
		(mid 136.684766 -247.970825)
		(end 136.967722 -248.047002)
		(width 0.0889)
		(layer "In2.Cu")
		(net "M_I_CPU1_SA_CB<4>")
	)
	(arc
		(start 137.916158 -248.051828)
		(mid 138.099666 -248.097322)
		(end 138.281918 -248.047002)
		(width 0.0889)
		(layer "In2.Cu")
		(net "M_I_CPU1_SA_CB<4>")
	)
	(arc
		(start 131.701794 -248.047002)
		(mid 131.98475 -247.970825)
		(end 132.267706 -248.047002)
		(width 0.0889)
		(layer "In2.Cu")
		(net "M_I_CPU1_SA_CB<4>")
	)
	(arc
		(start 145.425668 -248.046748)
		(mid 145.997882 -248.284236)
		(end 146.612102 -248.365264)
		(width 0.0889)
		(layer "In2.Cu")
		(net "M_I_CPU1_SA_CB<4>")
	)
	(arc
		(start 139.221718 -248.047002)
		(mid 139.504674 -247.970825)
		(end 139.78763 -248.047002)
		(width 0.0889)
		(layer "In2.Cu")
		(net "M_I_CPU1_SA_CB<4>")
	)
	(arc
		(start 142.607792 -248.047002)
		(mid 142.794736 -248.097257)
		(end 142.98168 -248.047002)
		(width 0.0889)
		(layer "In2.Cu")
		(net "M_I_CPU1_SA_CB<4>")
	)
	(arc
		(start 142.04188 -248.047002)
		(mid 142.324836 -247.970825)
		(end 142.607792 -248.047002)
		(width 0.0889)
		(layer "In2.Cu")
		(net "M_I_CPU1_SA_CB<4>")
	)
	(arc
		(start 133.581902 -248.047002)
		(mid 133.864858 -247.970825)
		(end 134.147814 -248.047002)
		(width 0.0889)
		(layer "In2.Cu")
		(net "M_I_CPU1_SA_CB<4>")
	)
	(arc
		(start 138.84783 -248.047002)
		(mid 139.034774 -248.097257)
		(end 139.221718 -248.047002)
		(width 0.0889)
		(layer "In2.Cu")
		(net "M_I_CPU1_SA_CB<4>")
	)
	(arc
		(start 139.78763 -248.047002)
		(mid 139.969881 -248.097352)
		(end 140.15339 -248.051828)
		(width 0.0889)
		(layer "In2.Cu")
		(net "M_I_CPU1_SA_CB<4>")
	)
	(arc
		(start 135.087614 -248.047002)
		(mid 135.269865 -248.097352)
		(end 135.453374 -248.051828)
		(width 0.0889)
		(layer "In2.Cu")
		(net "M_I_CPU1_SA_CB<4>")
	)
	(arc
		(start 130.387598 -248.047002)
		(mid 130.569849 -248.097352)
		(end 130.753358 -248.051828)
		(width 0.0889)
		(layer "In2.Cu")
		(net "M_I_CPU1_SA_CB<4>")
	)
	(arc
		(start 143.547592 -248.047002)
		(mid 143.7207 -248.097118)
		(end 143.897096 -248.06021)
		(width 0.0889)
		(layer "In2.Cu")
		(net "M_I_CPU1_SA_CB<4>")
	)
	(arc
		(start 141.67612 -248.051828)
		(mid 141.859628 -248.097322)
		(end 142.04188 -248.047002)
		(width 0.0889)
		(layer "In2.Cu")
		(net "M_I_CPU1_SA_CB<4>")
	)
	(arc
		(start 129.821686 -248.047002)
		(mid 130.104642 -247.970825)
		(end 130.387598 -248.047002)
		(width 0.0889)
		(layer "In2.Cu")
		(net "M_I_CPU1_SA_CB<4>")
	)
	(arc
		(start 144.505172 -248.05894)
		(mid 144.6841 -248.097817)
		(end 144.86001 -248.047002)
		(width 0.0889)
		(layer "In2.Cu")
		(net "M_I_CPU1_SA_CB<4>")
	)
	(arc
		(start 141.101826 -248.047002)
		(mid 141.384782 -247.970825)
		(end 141.667738 -248.047002)
		(width 0.0889)
		(layer "In2.Cu")
		(net "M_I_CPU1_SA_CB<4>")
	)
	(arc
		(start 131.327652 -248.047002)
		(mid 131.509903 -248.097352)
		(end 131.693412 -248.051828)
		(width 0.0889)
		(layer "In2.Cu")
		(net "M_I_CPU1_SA_CB<4>")
	)
	(arc
		(start 132.276088 -248.051828)
		(mid 132.459596 -248.097322)
		(end 132.641848 -248.047002)
		(width 0.0889)
		(layer "In2.Cu")
		(net "M_I_CPU1_SA_CB<4>")
	)
	(arc
		(start 132.641848 -248.047002)
		(mid 132.924804 -247.970825)
		(end 133.20776 -248.047002)
		(width 0.0889)
		(layer "In2.Cu")
		(net "M_I_CPU1_SA_CB<4>")
	)
	(arc
		(start 133.216142 -248.051828)
		(mid 133.39965 -248.097322)
		(end 133.581902 -248.047002)
		(width 0.0889)
		(layer "In2.Cu")
		(net "M_I_CPU1_SA_CB<4>")
	)
	(segment
		(start 127.287782 -246.370348)
		(end 127.754634 -246.10441)
		(width 0.10668)
		(layer "F.Cu")
		(net "M_I_CPU1_SA_CB<3>")
	)
	(segment
		(start 178.138836 -236.800644)
		(end 178.392836 -236.546644)
		(width 0.14478)
		(layer "In2.Cu")
		(net "M_I_CPU1_SA_CB<3>")
	)
	(segment
		(start 163.217098 -237.700566)
		(end 165.987222 -237.700566)
		(width 0.14478)
		(layer "In2.Cu")
		(net "M_I_CPU1_SA_CB<3>")
	)
	(segment
		(start 160.781238 -240.136426)
		(end 161.009838 -240.136426)
		(width 0.14478)
		(layer "In2.Cu")
		(net "M_I_CPU1_SA_CB<3>")
	)
	(segment
		(start 161.736024 -240.310924)
		(end 161.736024 -240.082324)
		(width 0.14478)
		(layer "In2.Cu")
		(net "M_I_CPU1_SA_CB<3>")
	)
	(segment
		(start 161.399982 -239.746282)
		(end 161.399982 -239.517682)
		(width 0.14478)
		(layer "In2.Cu")
		(net "M_I_CPU1_SA_CB<3>")
	)
	(segment
		(start 161.399982 -239.517682)
		(end 161.561526 -239.356138)
		(width 0.14478)
		(layer "In2.Cu")
		(net "M_I_CPU1_SA_CB<3>")
	)
	(segment
		(start 145.802096 -245.78183)
		(end 145.95983 -245.939564)
		(width 0.0889)
		(layer "In2.Cu")
		(net "M_I_CPU1_SA_CB<3>")
	)
	(segment
		(start 137.907776 -245.78183)
		(end 137.916158 -245.777004)
		(width 0.0889)
		(layer "In2.Cu")
		(net "M_I_CPU1_SA_CB<3>")
	)
	(segment
		(start 140.15339 -245.777004)
		(end 140.161772 -245.78183)
		(width 0.0889)
		(layer "In2.Cu")
		(net "M_I_CPU1_SA_CB<3>")
	)
	(segment
		(start 161.34588 -240.472468)
		(end 161.57448 -240.472468)
		(width 0.14478)
		(layer "In2.Cu")
		(net "M_I_CPU1_SA_CB<3>")
	)
	(segment
		(start 156.894784 -245.152164)
		(end 160.955736 -241.091212)
		(width 0.14478)
		(layer "In2.Cu")
		(net "M_I_CPU1_SA_CB<3>")
	)
	(segment
		(start 177.520346 -236.546644)
		(end 177.774346 -236.800644)
		(width 0.14478)
		(layer "In2.Cu")
		(net "M_I_CPU1_SA_CB<3>")
	)
	(segment
		(start 131.693412 -245.777004)
		(end 131.701794 -245.78183)
		(width 0.0889)
		(layer "In2.Cu")
		(net "M_I_CPU1_SA_CB<3>")
	)
	(segment
		(start 178.951636 -236.860334)
		(end 179.091082 -236.860334)
		(width 0.14478)
		(layer "In2.Cu")
		(net "M_I_CPU1_SA_CB<3>")
	)
	(segment
		(start 171.080684 -237.700566)
		(end 173.525688 -237.700566)
		(width 0.14478)
		(layer "In2.Cu")
		(net "M_I_CPU1_SA_CB<3>")
	)
	(segment
		(start 161.561526 -239.356138)
		(end 161.790126 -239.356138)
		(width 0.14478)
		(layer "In2.Cu")
		(net "M_I_CPU1_SA_CB<3>")
	)
	(segment
		(start 161.790126 -239.356138)
		(end 162.003486 -239.569498)
		(width 0.14478)
		(layer "In2.Cu")
		(net "M_I_CPU1_SA_CB<3>")
	)
	(segment
		(start 162.003486 -239.569498)
		(end 162.232086 -239.569498)
		(width 0.14478)
		(layer "In2.Cu")
		(net "M_I_CPU1_SA_CB<3>")
	)
	(segment
		(start 160.955736 -240.862612)
		(end 160.619694 -240.52657)
		(width 0.14478)
		(layer "In2.Cu")
		(net "M_I_CPU1_SA_CB<3>")
	)
	(segment
		(start 148.214588 -245.152164)
		(end 156.894784 -245.152164)
		(width 0.14478)
		(layer "In2.Cu")
		(net "M_I_CPU1_SA_CB<3>")
	)
	(segment
		(start 177.275236 -236.546644)
		(end 177.520346 -236.546644)
		(width 0.14478)
		(layer "In2.Cu")
		(net "M_I_CPU1_SA_CB<3>")
	)
	(segment
		(start 166.837106 -236.850682)
		(end 170.210988 -236.850682)
		(width 0.14478)
		(layer "In2.Cu")
		(net "M_I_CPU1_SA_CB<3>")
	)
	(segment
		(start 147.427188 -245.939564)
		(end 148.00326 -245.363492)
		(width 0.0889)
		(layer "In2.Cu")
		(net "M_I_CPU1_SA_CB<3>")
	)
	(segment
		(start 132.267706 -245.78183)
		(end 132.276088 -245.777004)
		(width 0.0889)
		(layer "In2.Cu")
		(net "M_I_CPU1_SA_CB<3>")
	)
	(segment
		(start 141.093444 -245.777004)
		(end 141.101826 -245.78183)
		(width 0.0889)
		(layer "In2.Cu")
		(net "M_I_CPU1_SA_CB<3>")
	)
	(segment
		(start 162.18027 -238.737394)
		(end 163.217098 -237.700566)
		(width 0.14478)
		(layer "In2.Cu")
		(net "M_I_CPU1_SA_CB<3>")
	)
	(segment
		(start 135.453374 -245.777004)
		(end 135.461756 -245.78183)
		(width 0.0889)
		(layer "In2.Cu")
		(net "M_I_CPU1_SA_CB<3>")
	)
	(segment
		(start 176.971198 -236.850682)
		(end 177.275236 -236.546644)
		(width 0.14478)
		(layer "In2.Cu")
		(net "M_I_CPU1_SA_CB<3>")
	)
	(segment
		(start 136.967722 -245.78183)
		(end 136.976104 -245.777004)
		(width 0.0889)
		(layer "In2.Cu")
		(net "M_I_CPU1_SA_CB<3>")
	)
	(segment
		(start 165.987222 -237.700566)
		(end 166.837106 -236.850682)
		(width 0.14478)
		(layer "In2.Cu")
		(net "M_I_CPU1_SA_CB<3>")
	)
	(segment
		(start 145.95983 -245.939564)
		(end 147.427188 -245.939564)
		(width 0.0889)
		(layer "In2.Cu")
		(net "M_I_CPU1_SA_CB<3>")
	)
	(segment
		(start 173.525688 -237.700566)
		(end 174.375572 -236.850682)
		(width 0.14478)
		(layer "In2.Cu")
		(net "M_I_CPU1_SA_CB<3>")
	)
	(segment
		(start 161.009838 -240.136426)
		(end 161.34588 -240.472468)
		(width 0.14478)
		(layer "In2.Cu")
		(net "M_I_CPU1_SA_CB<3>")
	)
	(segment
		(start 141.667738 -245.78183)
		(end 141.67612 -245.777004)
		(width 0.0889)
		(layer "In2.Cu")
		(net "M_I_CPU1_SA_CB<3>")
	)
	(segment
		(start 136.393428 -245.777004)
		(end 136.40181 -245.78183)
		(width 0.0889)
		(layer "In2.Cu")
		(net "M_I_CPU1_SA_CB<3>")
	)
	(segment
		(start 179.091082 -236.860334)
		(end 179.516024 -237.285276)
		(width 0.14478)
		(layer "In2.Cu")
		(net "M_I_CPU1_SA_CB<3>")
	)
	(segment
		(start 133.20776 -245.78183)
		(end 133.216142 -245.777004)
		(width 0.0889)
		(layer "In2.Cu")
		(net "M_I_CPU1_SA_CB<3>")
	)
	(segment
		(start 160.955736 -241.091212)
		(end 160.955736 -240.862612)
		(width 0.14478)
		(layer "In2.Cu")
		(net "M_I_CPU1_SA_CB<3>")
	)
	(segment
		(start 170.210988 -236.850682)
		(end 170.240706 -236.860588)
		(width 0.14478)
		(layer "In2.Cu")
		(net "M_I_CPU1_SA_CB<3>")
	)
	(segment
		(start 127.908812 -245.83898)
		(end 128.005078 -245.81358)
		(width 0.0889)
		(layer "In2.Cu")
		(net "M_I_CPU1_SA_CB<3>")
	)
	(segment
		(start 162.18027 -238.965994)
		(end 162.18027 -238.737394)
		(width 0.14478)
		(layer "In2.Cu")
		(net "M_I_CPU1_SA_CB<3>")
	)
	(segment
		(start 162.39363 -239.179354)
		(end 162.18027 -238.965994)
		(width 0.14478)
		(layer "In2.Cu")
		(net "M_I_CPU1_SA_CB<3>")
	)
	(segment
		(start 177.774346 -236.800644)
		(end 178.138836 -236.800644)
		(width 0.14478)
		(layer "In2.Cu")
		(net "M_I_CPU1_SA_CB<3>")
	)
	(segment
		(start 162.39363 -239.407954)
		(end 162.39363 -239.179354)
		(width 0.14478)
		(layer "In2.Cu")
		(net "M_I_CPU1_SA_CB<3>")
	)
	(segment
		(start 160.619694 -240.29797)
		(end 160.781238 -240.136426)
		(width 0.14478)
		(layer "In2.Cu")
		(net "M_I_CPU1_SA_CB<3>")
	)
	(segment
		(start 160.619694 -240.52657)
		(end 160.619694 -240.29797)
		(width 0.14478)
		(layer "In2.Cu")
		(net "M_I_CPU1_SA_CB<3>")
	)
	(segment
		(start 161.57448 -240.472468)
		(end 161.736024 -240.310924)
		(width 0.14478)
		(layer "In2.Cu")
		(net "M_I_CPU1_SA_CB<3>")
	)
	(segment
		(start 148.00326 -245.363492)
		(end 148.214588 -245.152164)
		(width 0.14478)
		(layer "In2.Cu")
		(net "M_I_CPU1_SA_CB<3>")
	)
	(segment
		(start 130.753358 -245.777004)
		(end 130.76174 -245.78183)
		(width 0.0889)
		(layer "In2.Cu")
		(net "M_I_CPU1_SA_CB<3>")
	)
	(segment
		(start 127.754634 -246.10441)
		(end 127.908812 -245.83898)
		(width 0.0889)
		(layer "In2.Cu")
		(net "M_I_CPU1_SA_CB<3>")
	)
	(segment
		(start 162.232086 -239.569498)
		(end 162.39363 -239.407954)
		(width 0.14478)
		(layer "In2.Cu")
		(net "M_I_CPU1_SA_CB<3>")
	)
	(segment
		(start 128.507744 -245.78183)
		(end 128.516126 -245.777004)
		(width 0.0889)
		(layer "In2.Cu")
		(net "M_I_CPU1_SA_CB<3>")
	)
	(segment
		(start 170.240706 -236.860588)
		(end 171.080684 -237.700566)
		(width 0.14478)
		(layer "In2.Cu")
		(net "M_I_CPU1_SA_CB<3>")
	)
	(segment
		(start 174.375572 -236.850682)
		(end 176.971198 -236.850682)
		(width 0.14478)
		(layer "In2.Cu")
		(net "M_I_CPU1_SA_CB<3>")
	)
	(segment
		(start 178.637946 -236.546644)
		(end 178.951636 -236.860334)
		(width 0.14478)
		(layer "In2.Cu")
		(net "M_I_CPU1_SA_CB<3>")
	)
	(segment
		(start 178.392836 -236.546644)
		(end 178.637946 -236.546644)
		(width 0.14478)
		(layer "In2.Cu")
		(net "M_I_CPU1_SA_CB<3>")
	)
	(segment
		(start 161.736024 -240.082324)
		(end 161.399982 -239.746282)
		(width 0.14478)
		(layer "In2.Cu")
		(net "M_I_CPU1_SA_CB<3>")
	)
	(arc
		(start 145.4277 -245.78183)
		(mid 145.614898 -245.731448)
		(end 145.802096 -245.78183)
		(width 0.0889)
		(layer "In2.Cu")
		(net "M_I_CPU1_SA_CB<3>")
	)
	(arc
		(start 139.221718 -245.78183)
		(mid 139.504674 -245.858007)
		(end 139.78763 -245.78183)
		(width 0.0889)
		(layer "In2.Cu")
		(net "M_I_CPU1_SA_CB<3>")
	)
	(arc
		(start 131.327652 -245.78183)
		(mid 131.509903 -245.73148)
		(end 131.693412 -245.777004)
		(width 0.0889)
		(layer "In2.Cu")
		(net "M_I_CPU1_SA_CB<3>")
	)
	(arc
		(start 132.641848 -245.78183)
		(mid 132.924804 -245.858007)
		(end 133.20776 -245.78183)
		(width 0.0889)
		(layer "In2.Cu")
		(net "M_I_CPU1_SA_CB<3>")
	)
	(arc
		(start 143.547592 -245.78183)
		(mid 143.73479 -245.731448)
		(end 143.921988 -245.78183)
		(width 0.0889)
		(layer "In2.Cu")
		(net "M_I_CPU1_SA_CB<3>")
	)
	(arc
		(start 138.84783 -245.78183)
		(mid 139.034774 -245.731575)
		(end 139.221718 -245.78183)
		(width 0.0889)
		(layer "In2.Cu")
		(net "M_I_CPU1_SA_CB<3>")
	)
	(arc
		(start 132.276088 -245.777004)
		(mid 132.459596 -245.73151)
		(end 132.641848 -245.78183)
		(width 0.0889)
		(layer "In2.Cu")
		(net "M_I_CPU1_SA_CB<3>")
	)
	(arc
		(start 142.04188 -245.78183)
		(mid 142.324836 -245.858007)
		(end 142.607792 -245.78183)
		(width 0.0889)
		(layer "In2.Cu")
		(net "M_I_CPU1_SA_CB<3>")
	)
	(arc
		(start 129.821686 -245.78183)
		(mid 130.104642 -245.858007)
		(end 130.387598 -245.78183)
		(width 0.0889)
		(layer "In2.Cu")
		(net "M_I_CPU1_SA_CB<3>")
	)
	(arc
		(start 135.087614 -245.78183)
		(mid 135.269865 -245.73148)
		(end 135.453374 -245.777004)
		(width 0.0889)
		(layer "In2.Cu")
		(net "M_I_CPU1_SA_CB<3>")
	)
	(arc
		(start 141.67612 -245.777004)
		(mid 141.859628 -245.73151)
		(end 142.04188 -245.78183)
		(width 0.0889)
		(layer "In2.Cu")
		(net "M_I_CPU1_SA_CB<3>")
	)
	(arc
		(start 134.147814 -245.78183)
		(mid 134.334758 -245.731575)
		(end 134.521702 -245.78183)
		(width 0.0889)
		(layer "In2.Cu")
		(net "M_I_CPU1_SA_CB<3>")
	)
	(arc
		(start 128.881886 -245.78183)
		(mid 129.164842 -245.858007)
		(end 129.447798 -245.78183)
		(width 0.0889)
		(layer "In2.Cu")
		(net "M_I_CPU1_SA_CB<3>")
	)
	(arc
		(start 141.101826 -245.78183)
		(mid 141.384782 -245.858007)
		(end 141.667738 -245.78183)
		(width 0.0889)
		(layer "In2.Cu")
		(net "M_I_CPU1_SA_CB<3>")
	)
	(arc
		(start 139.78763 -245.78183)
		(mid 139.969881 -245.73148)
		(end 140.15339 -245.777004)
		(width 0.0889)
		(layer "In2.Cu")
		(net "M_I_CPU1_SA_CB<3>")
	)
	(arc
		(start 136.976104 -245.777004)
		(mid 137.159612 -245.73151)
		(end 137.341864 -245.78183)
		(width 0.0889)
		(layer "In2.Cu")
		(net "M_I_CPU1_SA_CB<3>")
	)
	(arc
		(start 135.461756 -245.78183)
		(mid 135.744712 -245.858007)
		(end 136.027668 -245.78183)
		(width 0.0889)
		(layer "In2.Cu")
		(net "M_I_CPU1_SA_CB<3>")
	)
	(arc
		(start 133.581902 -245.78183)
		(mid 133.864858 -245.858007)
		(end 134.147814 -245.78183)
		(width 0.0889)
		(layer "In2.Cu")
		(net "M_I_CPU1_SA_CB<3>")
	)
	(arc
		(start 130.76174 -245.78183)
		(mid 131.044696 -245.858007)
		(end 131.327652 -245.78183)
		(width 0.0889)
		(layer "In2.Cu")
		(net "M_I_CPU1_SA_CB<3>")
	)
	(arc
		(start 144.4879 -245.78183)
		(mid 144.674844 -245.731575)
		(end 144.861788 -245.78183)
		(width 0.0889)
		(layer "In2.Cu")
		(net "M_I_CPU1_SA_CB<3>")
	)
	(arc
		(start 128.005078 -245.81358)
		(mid 128.260143 -245.856931)
		(end 128.507744 -245.78183)
		(width 0.0889)
		(layer "In2.Cu")
		(net "M_I_CPU1_SA_CB<3>")
	)
	(arc
		(start 143.921988 -245.78183)
		(mid 144.204944 -245.858007)
		(end 144.4879 -245.78183)
		(width 0.0889)
		(layer "In2.Cu")
		(net "M_I_CPU1_SA_CB<3>")
	)
	(arc
		(start 136.40181 -245.78183)
		(mid 136.684766 -245.858007)
		(end 136.967722 -245.78183)
		(width 0.0889)
		(layer "In2.Cu")
		(net "M_I_CPU1_SA_CB<3>")
	)
	(arc
		(start 134.521702 -245.78183)
		(mid 134.804658 -245.858007)
		(end 135.087614 -245.78183)
		(width 0.0889)
		(layer "In2.Cu")
		(net "M_I_CPU1_SA_CB<3>")
	)
	(arc
		(start 140.161772 -245.78183)
		(mid 140.444728 -245.858007)
		(end 140.727684 -245.78183)
		(width 0.0889)
		(layer "In2.Cu")
		(net "M_I_CPU1_SA_CB<3>")
	)
	(arc
		(start 131.701794 -245.78183)
		(mid 131.98475 -245.858007)
		(end 132.267706 -245.78183)
		(width 0.0889)
		(layer "In2.Cu")
		(net "M_I_CPU1_SA_CB<3>")
	)
	(arc
		(start 137.341864 -245.78183)
		(mid 137.62482 -245.858007)
		(end 137.907776 -245.78183)
		(width 0.0889)
		(layer "In2.Cu")
		(net "M_I_CPU1_SA_CB<3>")
	)
	(arc
		(start 144.861788 -245.78183)
		(mid 145.144744 -245.858007)
		(end 145.4277 -245.78183)
		(width 0.0889)
		(layer "In2.Cu")
		(net "M_I_CPU1_SA_CB<3>")
	)
	(arc
		(start 136.027668 -245.78183)
		(mid 136.209919 -245.73148)
		(end 136.393428 -245.777004)
		(width 0.0889)
		(layer "In2.Cu")
		(net "M_I_CPU1_SA_CB<3>")
	)
	(arc
		(start 142.607792 -245.78183)
		(mid 142.794736 -245.731575)
		(end 142.98168 -245.78183)
		(width 0.0889)
		(layer "In2.Cu")
		(net "M_I_CPU1_SA_CB<3>")
	)
	(arc
		(start 140.727684 -245.78183)
		(mid 140.909935 -245.73148)
		(end 141.093444 -245.777004)
		(width 0.0889)
		(layer "In2.Cu")
		(net "M_I_CPU1_SA_CB<3>")
	)
	(arc
		(start 138.281918 -245.78183)
		(mid 138.564874 -245.858007)
		(end 138.84783 -245.78183)
		(width 0.0889)
		(layer "In2.Cu")
		(net "M_I_CPU1_SA_CB<3>")
	)
	(arc
		(start 133.216142 -245.777004)
		(mid 133.39965 -245.73151)
		(end 133.581902 -245.78183)
		(width 0.0889)
		(layer "In2.Cu")
		(net "M_I_CPU1_SA_CB<3>")
	)
	(arc
		(start 142.98168 -245.78183)
		(mid 143.264636 -245.858007)
		(end 143.547592 -245.78183)
		(width 0.0889)
		(layer "In2.Cu")
		(net "M_I_CPU1_SA_CB<3>")
	)
	(arc
		(start 130.387598 -245.78183)
		(mid 130.569849 -245.73148)
		(end 130.753358 -245.777004)
		(width 0.0889)
		(layer "In2.Cu")
		(net "M_I_CPU1_SA_CB<3>")
	)
	(arc
		(start 128.516126 -245.777004)
		(mid 128.699634 -245.73151)
		(end 128.881886 -245.78183)
		(width 0.0889)
		(layer "In2.Cu")
		(net "M_I_CPU1_SA_CB<3>")
	)
	(arc
		(start 137.916158 -245.777004)
		(mid 138.099666 -245.73151)
		(end 138.281918 -245.78183)
		(width 0.0889)
		(layer "In2.Cu")
		(net "M_I_CPU1_SA_CB<3>")
	)
	(arc
		(start 129.447798 -245.78183)
		(mid 129.634742 -245.731575)
		(end 129.821686 -245.78183)
		(width 0.0889)
		(layer "In2.Cu")
		(net "M_I_CPU1_SA_CB<3>")
	)
	(segment
		(start 128.69799 -245.560342)
		(end 129.164842 -245.294404)
		(width 0.10668)
		(layer "F.Cu")
		(net "M_I_CPU1_SA_CB<2>")
	)
	(segment
		(start 158.68777 -240.957608)
		(end 163.634928 -236.01045)
		(width 0.14478)
		(layer "In2.Cu")
		(net "M_I_CPU1_SA_CB<2>")
	)
	(segment
		(start 135.557768 -244.971824)
		(end 135.56615 -244.966998)
		(width 0.0889)
		(layer "In2.Cu")
		(net "M_I_CPU1_SA_CB<2>")
	)
	(segment
		(start 167.149272 -235.160312)
		(end 169.09415 -235.160312)
		(width 0.14478)
		(layer "In2.Cu")
		(net "M_I_CPU1_SA_CB<2>")
	)
	(segment
		(start 173.716442 -235.898944)
		(end 173.970696 -235.793534)
		(width 0.14478)
		(layer "In2.Cu")
		(net "M_I_CPU1_SA_CB<2>")
	)
	(segment
		(start 157.83433 -242.673632)
		(end 158.06293 -242.673632)
		(width 0.14478)
		(layer "In2.Cu")
		(net "M_I_CPU1_SA_CB<2>")
	)
	(segment
		(start 166.299134 -236.01045)
		(end 167.149272 -235.160312)
		(width 0.14478)
		(layer "In2.Cu")
		(net "M_I_CPU1_SA_CB<2>")
	)
	(segment
		(start 179.091082 -235.160312)
		(end 179.516024 -235.585254)
		(width 0.14478)
		(layer "In2.Cu")
		(net "M_I_CPU1_SA_CB<2>")
	)
	(segment
		(start 156.73705 -243.136928)
		(end 157.054042 -243.45392)
		(width 0.14478)
		(layer "In2.Cu")
		(net "M_I_CPU1_SA_CB<2>")
	)
	(segment
		(start 156.346906 -243.298472)
		(end 156.50845 -243.136928)
		(width 0.14478)
		(layer "In2.Cu")
		(net "M_I_CPU1_SA_CB<2>")
	)
	(segment
		(start 156.50845 -243.136928)
		(end 156.73705 -243.136928)
		(width 0.14478)
		(layer "In2.Cu")
		(net "M_I_CPU1_SA_CB<2>")
	)
	(segment
		(start 159.004762 -241.5032)
		(end 158.68777 -241.186208)
		(width 0.14478)
		(layer "In2.Cu")
		(net "M_I_CPU1_SA_CB<2>")
	)
	(segment
		(start 155.407614 -244.237764)
		(end 155.728162 -243.917216)
		(width 0.14478)
		(layer "In2.Cu")
		(net "M_I_CPU1_SA_CB<2>")
	)
	(segment
		(start 178.305968 -235.160312)
		(end 179.091082 -235.160312)
		(width 0.14478)
		(layer "In2.Cu")
		(net "M_I_CPU1_SA_CB<2>")
	)
	(segment
		(start 170.460416 -235.726224)
		(end 171.146724 -236.01045)
		(width 0.14478)
		(layer "In2.Cu")
		(net "M_I_CPU1_SA_CB<2>")
	)
	(segment
		(start 173.345348 -235.74502)
		(end 173.716442 -235.898944)
		(width 0.14478)
		(layer "In2.Cu")
		(net "M_I_CPU1_SA_CB<2>")
	)
	(segment
		(start 143.992092 -244.986048)
		(end 144.015968 -244.972078)
		(width 0.0889)
		(layer "In2.Cu")
		(net "M_I_CPU1_SA_CB<2>")
	)
	(segment
		(start 158.224474 -242.283488)
		(end 157.907482 -241.966496)
		(width 0.14478)
		(layer "In2.Cu")
		(net "M_I_CPU1_SA_CB<2>")
	)
	(segment
		(start 138.743436 -244.966998)
		(end 138.751818 -244.971824)
		(width 0.0889)
		(layer "In2.Cu")
		(net "M_I_CPU1_SA_CB<2>")
	)
	(segment
		(start 155.728162 -243.917216)
		(end 155.956762 -243.917216)
		(width 0.14478)
		(layer "In2.Cu")
		(net "M_I_CPU1_SA_CB<2>")
	)
	(segment
		(start 140.257784 -244.971824)
		(end 140.266166 -244.966998)
		(width 0.0889)
		(layer "In2.Cu")
		(net "M_I_CPU1_SA_CB<2>")
	)
	(segment
		(start 129.318766 -245.028974)
		(end 129.414778 -245.003574)
		(width 0.0889)
		(layer "In2.Cu")
		(net "M_I_CPU1_SA_CB<2>")
	)
	(segment
		(start 155.956762 -243.917216)
		(end 156.273754 -244.234208)
		(width 0.14478)
		(layer "In2.Cu")
		(net "M_I_CPU1_SA_CB<2>")
	)
	(segment
		(start 158.069026 -241.576352)
		(end 158.297626 -241.576352)
		(width 0.14478)
		(layer "In2.Cu")
		(net "M_I_CPU1_SA_CB<2>")
	)
	(segment
		(start 169.09415 -235.160312)
		(end 169.681144 -235.403644)
		(width 0.14478)
		(layer "In2.Cu")
		(net "M_I_CPU1_SA_CB<2>")
	)
	(segment
		(start 158.06293 -242.673632)
		(end 158.224474 -242.512088)
		(width 0.14478)
		(layer "In2.Cu")
		(net "M_I_CPU1_SA_CB<2>")
	)
	(segment
		(start 170.306746 -235.354622)
		(end 170.460416 -235.726224)
		(width 0.14478)
		(layer "In2.Cu")
		(net "M_I_CPU1_SA_CB<2>")
	)
	(segment
		(start 129.164842 -245.294404)
		(end 129.318766 -245.028974)
		(width 0.0889)
		(layer "In2.Cu")
		(net "M_I_CPU1_SA_CB<2>")
	)
	(segment
		(start 169.681144 -235.403644)
		(end 170.053254 -235.249466)
		(width 0.14478)
		(layer "In2.Cu")
		(net "M_I_CPU1_SA_CB<2>")
	)
	(segment
		(start 146.352768 -245.218204)
		(end 146.853148 -245.218204)
		(width 0.0889)
		(layer "In2.Cu")
		(net "M_I_CPU1_SA_CB<2>")
	)
	(segment
		(start 156.663898 -244.072664)
		(end 156.663898 -243.844064)
		(width 0.14478)
		(layer "In2.Cu")
		(net "M_I_CPU1_SA_CB<2>")
	)
	(segment
		(start 157.444186 -243.292376)
		(end 157.444186 -243.063776)
		(width 0.14478)
		(layer "In2.Cu")
		(net "M_I_CPU1_SA_CB<2>")
	)
	(segment
		(start 177.747168 -235.467144)
		(end 177.999136 -235.467144)
		(width 0.14478)
		(layer "In2.Cu")
		(net "M_I_CPU1_SA_CB<2>")
	)
	(segment
		(start 146.181826 -245.047262)
		(end 146.352768 -245.218204)
		(width 0.0889)
		(layer "In2.Cu")
		(net "M_I_CPU1_SA_CB<2>")
	)
	(segment
		(start 156.502354 -244.234208)
		(end 156.663898 -244.072664)
		(width 0.14478)
		(layer "In2.Cu")
		(net "M_I_CPU1_SA_CB<2>")
	)
	(segment
		(start 157.127194 -242.518184)
		(end 157.288738 -242.35664)
		(width 0.14478)
		(layer "In2.Cu")
		(net "M_I_CPU1_SA_CB<2>")
	)
	(segment
		(start 146.853148 -245.218204)
		(end 147.833588 -244.237764)
		(width 0.0889)
		(layer "In2.Cu")
		(net "M_I_CPU1_SA_CB<2>")
	)
	(segment
		(start 147.833588 -244.237764)
		(end 155.407614 -244.237764)
		(width 0.14478)
		(layer "In2.Cu")
		(net "M_I_CPU1_SA_CB<2>")
	)
	(segment
		(start 172.70476 -236.01045)
		(end 173.345348 -235.74502)
		(width 0.14478)
		(layer "In2.Cu")
		(net "M_I_CPU1_SA_CB<2>")
	)
	(segment
		(start 157.127194 -242.746784)
		(end 157.127194 -242.518184)
		(width 0.14478)
		(layer "In2.Cu")
		(net "M_I_CPU1_SA_CB<2>")
	)
	(segment
		(start 142.503398 -244.966998)
		(end 142.51178 -244.971824)
		(width 0.0889)
		(layer "In2.Cu")
		(net "M_I_CPU1_SA_CB<2>")
	)
	(segment
		(start 159.004762 -241.7318)
		(end 159.004762 -241.5032)
		(width 0.14478)
		(layer "In2.Cu")
		(net "M_I_CPU1_SA_CB<2>")
	)
	(segment
		(start 156.273754 -244.234208)
		(end 156.502354 -244.234208)
		(width 0.14478)
		(layer "In2.Cu")
		(net "M_I_CPU1_SA_CB<2>")
	)
	(segment
		(start 171.146724 -236.01045)
		(end 172.70476 -236.01045)
		(width 0.14478)
		(layer "In2.Cu")
		(net "M_I_CPU1_SA_CB<2>")
	)
	(segment
		(start 129.917698 -244.971824)
		(end 129.92608 -244.966998)
		(width 0.0889)
		(layer "In2.Cu")
		(net "M_I_CPU1_SA_CB<2>")
	)
	(segment
		(start 174.124112 -235.422694)
		(end 174.757334 -235.160312)
		(width 0.14478)
		(layer "In2.Cu")
		(net "M_I_CPU1_SA_CB<2>")
	)
	(segment
		(start 158.614618 -241.893344)
		(end 158.843218 -241.893344)
		(width 0.14478)
		(layer "In2.Cu")
		(net "M_I_CPU1_SA_CB<2>")
	)
	(segment
		(start 157.288738 -242.35664)
		(end 157.517338 -242.35664)
		(width 0.14478)
		(layer "In2.Cu")
		(net "M_I_CPU1_SA_CB<2>")
	)
	(segment
		(start 137.803382 -244.966998)
		(end 137.811764 -244.971824)
		(width 0.0889)
		(layer "In2.Cu")
		(net "M_I_CPU1_SA_CB<2>")
	)
	(segment
		(start 157.907482 -241.966496)
		(end 157.907482 -241.737896)
		(width 0.14478)
		(layer "In2.Cu")
		(net "M_I_CPU1_SA_CB<2>")
	)
	(segment
		(start 177.999136 -235.467144)
		(end 178.305968 -235.160312)
		(width 0.14478)
		(layer "In2.Cu")
		(net "M_I_CPU1_SA_CB<2>")
	)
	(segment
		(start 174.757334 -235.160312)
		(end 177.440336 -235.160312)
		(width 0.14478)
		(layer "In2.Cu")
		(net "M_I_CPU1_SA_CB<2>")
	)
	(segment
		(start 130.857752 -244.971824)
		(end 130.866134 -244.966998)
		(width 0.0889)
		(layer "In2.Cu")
		(net "M_I_CPU1_SA_CB<2>")
	)
	(segment
		(start 158.297626 -241.576352)
		(end 158.614618 -241.893344)
		(width 0.14478)
		(layer "In2.Cu")
		(net "M_I_CPU1_SA_CB<2>")
	)
	(segment
		(start 139.31773 -244.971824)
		(end 139.326112 -244.966998)
		(width 0.0889)
		(layer "In2.Cu")
		(net "M_I_CPU1_SA_CB<2>")
	)
	(segment
		(start 133.103366 -244.966998)
		(end 133.111748 -244.971824)
		(width 0.0889)
		(layer "In2.Cu")
		(net "M_I_CPU1_SA_CB<2>")
	)
	(segment
		(start 177.440336 -235.160312)
		(end 177.747168 -235.467144)
		(width 0.14478)
		(layer "In2.Cu")
		(net "M_I_CPU1_SA_CB<2>")
	)
	(segment
		(start 134.04342 -244.966998)
		(end 134.051802 -244.971824)
		(width 0.0889)
		(layer "In2.Cu")
		(net "M_I_CPU1_SA_CB<2>")
	)
	(segment
		(start 144.388586 -244.971824)
		(end 144.416272 -244.987826)
		(width 0.0889)
		(layer "In2.Cu")
		(net "M_I_CPU1_SA_CB<2>")
	)
	(segment
		(start 158.68777 -241.186208)
		(end 158.68777 -240.957608)
		(width 0.14478)
		(layer "In2.Cu")
		(net "M_I_CPU1_SA_CB<2>")
	)
	(segment
		(start 163.634928 -236.01045)
		(end 166.299134 -236.01045)
		(width 0.14478)
		(layer "In2.Cu")
		(net "M_I_CPU1_SA_CB<2>")
	)
	(segment
		(start 157.907482 -241.737896)
		(end 158.069026 -241.576352)
		(width 0.14478)
		(layer "In2.Cu")
		(net "M_I_CPU1_SA_CB<2>")
	)
	(segment
		(start 145.300446 -244.954806)
		(end 145.330418 -244.972078)
		(width 0.0889)
		(layer "In2.Cu")
		(net "M_I_CPU1_SA_CB<2>")
	)
	(segment
		(start 157.054042 -243.45392)
		(end 157.282642 -243.45392)
		(width 0.14478)
		(layer "In2.Cu")
		(net "M_I_CPU1_SA_CB<2>")
	)
	(segment
		(start 173.970696 -235.793534)
		(end 174.124112 -235.422694)
		(width 0.14478)
		(layer "In2.Cu")
		(net "M_I_CPU1_SA_CB<2>")
	)
	(segment
		(start 144.015968 -244.972078)
		(end 144.037812 -244.959632)
		(width 0.0889)
		(layer "In2.Cu")
		(net "M_I_CPU1_SA_CB<2>")
	)
	(segment
		(start 143.077692 -244.971824)
		(end 143.086074 -244.966998)
		(width 0.0889)
		(layer "In2.Cu")
		(net "M_I_CPU1_SA_CB<2>")
	)
	(segment
		(start 156.663898 -243.844064)
		(end 156.346906 -243.527072)
		(width 0.14478)
		(layer "In2.Cu")
		(net "M_I_CPU1_SA_CB<2>")
	)
	(segment
		(start 157.517338 -242.35664)
		(end 157.83433 -242.673632)
		(width 0.14478)
		(layer "In2.Cu")
		(net "M_I_CPU1_SA_CB<2>")
	)
	(segment
		(start 157.444186 -243.063776)
		(end 157.127194 -242.746784)
		(width 0.14478)
		(layer "In2.Cu")
		(net "M_I_CPU1_SA_CB<2>")
	)
	(segment
		(start 156.346906 -243.527072)
		(end 156.346906 -243.298472)
		(width 0.14478)
		(layer "In2.Cu")
		(net "M_I_CPU1_SA_CB<2>")
	)
	(segment
		(start 145.611342 -245.047262)
		(end 146.181826 -245.047262)
		(width 0.0889)
		(layer "In2.Cu")
		(net "M_I_CPU1_SA_CB<2>")
	)
	(segment
		(start 134.617714 -244.971824)
		(end 134.626096 -244.966998)
		(width 0.0889)
		(layer "In2.Cu")
		(net "M_I_CPU1_SA_CB<2>")
	)
	(segment
		(start 157.282642 -243.45392)
		(end 157.444186 -243.292376)
		(width 0.14478)
		(layer "In2.Cu")
		(net "M_I_CPU1_SA_CB<2>")
	)
	(segment
		(start 158.843218 -241.893344)
		(end 159.004762 -241.7318)
		(width 0.14478)
		(layer "In2.Cu")
		(net "M_I_CPU1_SA_CB<2>")
	)
	(segment
		(start 158.224474 -242.512088)
		(end 158.224474 -242.283488)
		(width 0.14478)
		(layer "In2.Cu")
		(net "M_I_CPU1_SA_CB<2>")
	)
	(segment
		(start 170.053254 -235.249466)
		(end 170.306746 -235.354622)
		(width 0.14478)
		(layer "In2.Cu")
		(net "M_I_CPU1_SA_CB<2>")
	)
	(arc
		(start 136.87171 -244.971824)
		(mid 137.154666 -245.048001)
		(end 137.437622 -244.971824)
		(width 0.0889)
		(layer "In2.Cu")
		(net "M_I_CPU1_SA_CB<2>")
	)
	(arc
		(start 142.51178 -244.971824)
		(mid 142.794736 -245.048001)
		(end 143.077692 -244.971824)
		(width 0.0889)
		(layer "In2.Cu")
		(net "M_I_CPU1_SA_CB<2>")
	)
	(arc
		(start 137.811764 -244.971824)
		(mid 138.09472 -245.048001)
		(end 138.377676 -244.971824)
		(width 0.0889)
		(layer "In2.Cu")
		(net "M_I_CPU1_SA_CB<2>")
	)
	(arc
		(start 129.92608 -244.966998)
		(mid 130.109588 -244.921504)
		(end 130.29184 -244.971824)
		(width 0.0889)
		(layer "In2.Cu")
		(net "M_I_CPU1_SA_CB<2>")
	)
	(arc
		(start 135.56615 -244.966998)
		(mid 135.749658 -244.921504)
		(end 135.93191 -244.971824)
		(width 0.0889)
		(layer "In2.Cu")
		(net "M_I_CPU1_SA_CB<2>")
	)
	(arc
		(start 140.631926 -244.971824)
		(mid 140.914882 -245.048001)
		(end 141.197838 -244.971824)
		(width 0.0889)
		(layer "In2.Cu")
		(net "M_I_CPU1_SA_CB<2>")
	)
	(arc
		(start 136.497822 -244.971824)
		(mid 136.684766 -244.921569)
		(end 136.87171 -244.971824)
		(width 0.0889)
		(layer "In2.Cu")
		(net "M_I_CPU1_SA_CB<2>")
	)
	(arc
		(start 135.93191 -244.971824)
		(mid 136.214866 -245.048001)
		(end 136.497822 -244.971824)
		(width 0.0889)
		(layer "In2.Cu")
		(net "M_I_CPU1_SA_CB<2>")
	)
	(arc
		(start 139.691872 -244.971824)
		(mid 139.974828 -245.048001)
		(end 140.257784 -244.971824)
		(width 0.0889)
		(layer "In2.Cu")
		(net "M_I_CPU1_SA_CB<2>")
	)
	(arc
		(start 129.414778 -245.003574)
		(mid 129.669986 -245.047051)
		(end 129.917698 -244.971824)
		(width 0.0889)
		(layer "In2.Cu")
		(net "M_I_CPU1_SA_CB<2>")
	)
	(arc
		(start 143.086074 -244.966998)
		(mid 143.269582 -244.921504)
		(end 143.451834 -244.971824)
		(width 0.0889)
		(layer "In2.Cu")
		(net "M_I_CPU1_SA_CB<2>")
	)
	(arc
		(start 143.451834 -244.971824)
		(mid 143.720154 -245.047932)
		(end 143.992092 -244.986048)
		(width 0.0889)
		(layer "In2.Cu")
		(net "M_I_CPU1_SA_CB<2>")
	)
	(arc
		(start 130.29184 -244.971824)
		(mid 130.574796 -245.048001)
		(end 130.857752 -244.971824)
		(width 0.0889)
		(layer "In2.Cu")
		(net "M_I_CPU1_SA_CB<2>")
	)
	(arc
		(start 142.137638 -244.971824)
		(mid 142.319889 -244.921474)
		(end 142.503398 -244.966998)
		(width 0.0889)
		(layer "In2.Cu")
		(net "M_I_CPU1_SA_CB<2>")
	)
	(arc
		(start 132.737606 -244.971824)
		(mid 132.919857 -244.921474)
		(end 133.103366 -244.966998)
		(width 0.0889)
		(layer "In2.Cu")
		(net "M_I_CPU1_SA_CB<2>")
	)
	(arc
		(start 144.416272 -244.987826)
		(mid 144.688306 -245.048598)
		(end 144.956276 -244.971824)
		(width 0.0889)
		(layer "In2.Cu")
		(net "M_I_CPU1_SA_CB<2>")
	)
	(arc
		(start 131.231894 -244.971824)
		(mid 131.51485 -245.048001)
		(end 131.797806 -244.971824)
		(width 0.0889)
		(layer "In2.Cu")
		(net "M_I_CPU1_SA_CB<2>")
	)
	(arc
		(start 138.751818 -244.971824)
		(mid 139.034774 -245.048001)
		(end 139.31773 -244.971824)
		(width 0.0889)
		(layer "In2.Cu")
		(net "M_I_CPU1_SA_CB<2>")
	)
	(arc
		(start 139.326112 -244.966998)
		(mid 139.50962 -244.921504)
		(end 139.691872 -244.971824)
		(width 0.0889)
		(layer "In2.Cu")
		(net "M_I_CPU1_SA_CB<2>")
	)
	(arc
		(start 138.377676 -244.971824)
		(mid 138.559927 -244.921474)
		(end 138.743436 -244.966998)
		(width 0.0889)
		(layer "In2.Cu")
		(net "M_I_CPU1_SA_CB<2>")
	)
	(arc
		(start 131.797806 -244.971824)
		(mid 131.98475 -244.921569)
		(end 132.171694 -244.971824)
		(width 0.0889)
		(layer "In2.Cu")
		(net "M_I_CPU1_SA_CB<2>")
	)
	(arc
		(start 132.171694 -244.971824)
		(mid 132.45465 -245.048001)
		(end 132.737606 -244.971824)
		(width 0.0889)
		(layer "In2.Cu")
		(net "M_I_CPU1_SA_CB<2>")
	)
	(arc
		(start 145.330418 -244.972078)
		(mid 145.465944 -245.028098)
		(end 145.611342 -245.047262)
		(width 0.0889)
		(layer "In2.Cu")
		(net "M_I_CPU1_SA_CB<2>")
	)
	(arc
		(start 140.266166 -244.966998)
		(mid 140.449674 -244.921504)
		(end 140.631926 -244.971824)
		(width 0.0889)
		(layer "In2.Cu")
		(net "M_I_CPU1_SA_CB<2>")
	)
	(arc
		(start 134.051802 -244.971824)
		(mid 134.334758 -245.048001)
		(end 134.617714 -244.971824)
		(width 0.0889)
		(layer "In2.Cu")
		(net "M_I_CPU1_SA_CB<2>")
	)
	(arc
		(start 141.197838 -244.971824)
		(mid 141.384782 -244.921569)
		(end 141.571726 -244.971824)
		(width 0.0889)
		(layer "In2.Cu")
		(net "M_I_CPU1_SA_CB<2>")
	)
	(arc
		(start 134.626096 -244.966998)
		(mid 134.809604 -244.921504)
		(end 134.991856 -244.971824)
		(width 0.0889)
		(layer "In2.Cu")
		(net "M_I_CPU1_SA_CB<2>")
	)
	(arc
		(start 130.866134 -244.966998)
		(mid 131.049642 -244.921504)
		(end 131.231894 -244.971824)
		(width 0.0889)
		(layer "In2.Cu")
		(net "M_I_CPU1_SA_CB<2>")
	)
	(arc
		(start 133.67766 -244.971824)
		(mid 133.859911 -244.921474)
		(end 134.04342 -244.966998)
		(width 0.0889)
		(layer "In2.Cu")
		(net "M_I_CPU1_SA_CB<2>")
	)
	(arc
		(start 144.956276 -244.971824)
		(mid 145.126283 -244.921259)
		(end 145.300446 -244.954806)
		(width 0.0889)
		(layer "In2.Cu")
		(net "M_I_CPU1_SA_CB<2>")
	)
	(arc
		(start 133.111748 -244.971824)
		(mid 133.394704 -245.048001)
		(end 133.67766 -244.971824)
		(width 0.0889)
		(layer "In2.Cu")
		(net "M_I_CPU1_SA_CB<2>")
	)
	(arc
		(start 144.037812 -244.959632)
		(mid 144.21474 -244.921804)
		(end 144.388586 -244.971824)
		(width 0.0889)
		(layer "In2.Cu")
		(net "M_I_CPU1_SA_CB<2>")
	)
	(arc
		(start 141.571726 -244.971824)
		(mid 141.854682 -245.048001)
		(end 142.137638 -244.971824)
		(width 0.0889)
		(layer "In2.Cu")
		(net "M_I_CPU1_SA_CB<2>")
	)
	(arc
		(start 134.991856 -244.971824)
		(mid 135.274812 -245.048001)
		(end 135.557768 -244.971824)
		(width 0.0889)
		(layer "In2.Cu")
		(net "M_I_CPU1_SA_CB<2>")
	)
	(arc
		(start 137.437622 -244.971824)
		(mid 137.619873 -244.921474)
		(end 137.803382 -244.966998)
		(width 0.0889)
		(layer "In2.Cu")
		(net "M_I_CPU1_SA_CB<2>")
	)
	(segment
		(start 127.757936 -245.560342)
		(end 128.224788 -245.294404)
		(width 0.10668)
		(layer "F.Cu")
		(net "M_I_CPU1_SA_CB<1>")
	)
	(segment
		(start 148.026628 -244.694964)
		(end 156.715968 -244.694964)
		(width 0.14478)
		(layer "In2.Cu")
		(net "M_I_CPU1_SA_CB<1>")
	)
	(segment
		(start 134.04342 -245.62181)
		(end 134.051802 -245.616984)
		(width 0.0889)
		(layer "In2.Cu")
		(net "M_I_CPU1_SA_CB<1>")
	)
	(segment
		(start 169.77487 -236.01045)
		(end 171.826936 -236.860334)
		(width 0.14478)
		(layer "In2.Cu")
		(net "M_I_CPU1_SA_CB<1>")
	)
	(segment
		(start 174.302928 -236.267752)
		(end 175.596804 -236.01045)
		(width 0.14478)
		(layer "In2.Cu")
		(net "M_I_CPU1_SA_CB<1>")
	)
	(segment
		(start 144.9578 -245.616984)
		(end 144.966182 -245.62181)
		(width 0.0889)
		(layer "In2.Cu")
		(net "M_I_CPU1_SA_CB<1>")
	)
	(segment
		(start 147.047204 -245.674388)
		(end 148.026628 -244.694964)
		(width 0.0889)
		(layer "In2.Cu")
		(net "M_I_CPU1_SA_CB<1>")
	)
	(segment
		(start 133.103366 -245.62181)
		(end 133.111748 -245.616984)
		(width 0.0889)
		(layer "In2.Cu")
		(net "M_I_CPU1_SA_CB<1>")
	)
	(segment
		(start 130.857752 -245.616984)
		(end 130.866134 -245.62181)
		(width 0.0889)
		(layer "In2.Cu")
		(net "M_I_CPU1_SA_CB<1>")
	)
	(segment
		(start 139.31773 -245.616984)
		(end 139.326112 -245.62181)
		(width 0.0889)
		(layer "In2.Cu")
		(net "M_I_CPU1_SA_CB<1>")
	)
	(segment
		(start 175.596804 -236.01045)
		(end 183.19115 -236.01045)
		(width 0.14478)
		(layer "In2.Cu")
		(net "M_I_CPU1_SA_CB<1>")
	)
	(segment
		(start 160.170114 -241.240818)
		(end 160.170114 -240.111534)
		(width 0.14478)
		(layer "In2.Cu")
		(net "M_I_CPU1_SA_CB<1>")
	)
	(segment
		(start 135.557768 -245.616984)
		(end 135.56615 -245.62181)
		(width 0.0889)
		(layer "In2.Cu")
		(net "M_I_CPU1_SA_CB<1>")
	)
	(segment
		(start 145.99666 -245.674388)
		(end 147.047204 -245.674388)
		(width 0.0889)
		(layer "In2.Cu")
		(net "M_I_CPU1_SA_CB<1>")
	)
	(segment
		(start 144.383506 -245.62181)
		(end 144.391888 -245.616984)
		(width 0.0889)
		(layer "In2.Cu")
		(net "M_I_CPU1_SA_CB<1>")
	)
	(segment
		(start 145.897854 -245.616984)
		(end 145.99666 -245.674388)
		(width 0.0889)
		(layer "In2.Cu")
		(net "M_I_CPU1_SA_CB<1>")
	)
	(segment
		(start 128.40335 -245.62181)
		(end 128.411732 -245.616984)
		(width 0.0889)
		(layer "In2.Cu")
		(net "M_I_CPU1_SA_CB<1>")
	)
	(segment
		(start 160.170114 -240.111534)
		(end 163.421314 -236.860334)
		(width 0.14478)
		(layer "In2.Cu")
		(net "M_I_CPU1_SA_CB<1>")
	)
	(segment
		(start 163.421314 -236.860334)
		(end 164.609526 -236.860334)
		(width 0.14478)
		(layer "In2.Cu")
		(net "M_I_CPU1_SA_CB<1>")
	)
	(segment
		(start 128.07061 -245.559834)
		(end 128.092962 -245.643146)
		(width 0.0889)
		(layer "In2.Cu")
		(net "M_I_CPU1_SA_CB<1>")
	)
	(segment
		(start 172.283374 -236.860334)
		(end 172.667676 -236.764068)
		(width 0.14478)
		(layer "In2.Cu")
		(net "M_I_CPU1_SA_CB<1>")
	)
	(segment
		(start 167.533574 -236.01045)
		(end 169.77487 -236.01045)
		(width 0.14478)
		(layer "In2.Cu")
		(net "M_I_CPU1_SA_CB<1>")
	)
	(segment
		(start 142.503398 -245.62181)
		(end 142.51178 -245.616984)
		(width 0.0889)
		(layer "In2.Cu")
		(net "M_I_CPU1_SA_CB<1>")
	)
	(segment
		(start 128.224788 -245.294404)
		(end 128.07061 -245.559834)
		(width 0.0889)
		(layer "In2.Cu")
		(net "M_I_CPU1_SA_CB<1>")
	)
	(segment
		(start 164.609526 -236.860334)
		(end 166.287958 -236.526324)
		(width 0.14478)
		(layer "In2.Cu")
		(net "M_I_CPU1_SA_CB<1>")
	)
	(segment
		(start 138.743436 -245.62181)
		(end 138.751818 -245.616984)
		(width 0.0889)
		(layer "In2.Cu")
		(net "M_I_CPU1_SA_CB<1>")
	)
	(segment
		(start 129.343404 -245.62181)
		(end 129.351786 -245.616984)
		(width 0.0889)
		(layer "In2.Cu")
		(net "M_I_CPU1_SA_CB<1>")
	)
	(segment
		(start 183.19115 -236.01045)
		(end 183.616092 -236.435392)
		(width 0.14478)
		(layer "In2.Cu")
		(net "M_I_CPU1_SA_CB<1>")
	)
	(segment
		(start 156.715968 -244.694964)
		(end 160.170114 -241.240818)
		(width 0.14478)
		(layer "In2.Cu")
		(net "M_I_CPU1_SA_CB<1>")
	)
	(segment
		(start 140.257784 -245.616984)
		(end 140.266166 -245.62181)
		(width 0.0889)
		(layer "In2.Cu")
		(net "M_I_CPU1_SA_CB<1>")
	)
	(segment
		(start 166.287958 -236.526324)
		(end 167.533574 -236.01045)
		(width 0.14478)
		(layer "In2.Cu")
		(net "M_I_CPU1_SA_CB<1>")
	)
	(segment
		(start 172.667676 -236.764068)
		(end 174.302928 -236.267752)
		(width 0.14478)
		(layer "In2.Cu")
		(net "M_I_CPU1_SA_CB<1>")
	)
	(segment
		(start 143.077692 -245.616984)
		(end 143.086074 -245.62181)
		(width 0.0889)
		(layer "In2.Cu")
		(net "M_I_CPU1_SA_CB<1>")
	)
	(segment
		(start 137.803382 -245.62181)
		(end 137.811764 -245.616984)
		(width 0.0889)
		(layer "In2.Cu")
		(net "M_I_CPU1_SA_CB<1>")
	)
	(segment
		(start 171.826936 -236.860334)
		(end 172.283374 -236.860334)
		(width 0.14478)
		(layer "In2.Cu")
		(net "M_I_CPU1_SA_CB<1>")
	)
	(segment
		(start 129.917698 -245.616984)
		(end 129.92608 -245.62181)
		(width 0.0889)
		(layer "In2.Cu")
		(net "M_I_CPU1_SA_CB<1>")
	)
	(segment
		(start 134.617714 -245.616984)
		(end 134.626096 -245.62181)
		(width 0.0889)
		(layer "In2.Cu")
		(net "M_I_CPU1_SA_CB<1>")
	)
	(arc
		(start 144.391888 -245.616984)
		(mid 144.674844 -245.540807)
		(end 144.9578 -245.616984)
		(width 0.0889)
		(layer "In2.Cu")
		(net "M_I_CPU1_SA_CB<1>")
	)
	(arc
		(start 142.137638 -245.616984)
		(mid 142.319889 -245.667334)
		(end 142.503398 -245.62181)
		(width 0.0889)
		(layer "In2.Cu")
		(net "M_I_CPU1_SA_CB<1>")
	)
	(arc
		(start 136.497822 -245.616984)
		(mid 136.684766 -245.667239)
		(end 136.87171 -245.616984)
		(width 0.0889)
		(layer "In2.Cu")
		(net "M_I_CPU1_SA_CB<1>")
	)
	(arc
		(start 128.977644 -245.616984)
		(mid 129.159895 -245.667334)
		(end 129.343404 -245.62181)
		(width 0.0889)
		(layer "In2.Cu")
		(net "M_I_CPU1_SA_CB<1>")
	)
	(arc
		(start 128.411732 -245.616984)
		(mid 128.694688 -245.540807)
		(end 128.977644 -245.616984)
		(width 0.0889)
		(layer "In2.Cu")
		(net "M_I_CPU1_SA_CB<1>")
	)
	(arc
		(start 141.571726 -245.616984)
		(mid 141.854682 -245.540807)
		(end 142.137638 -245.616984)
		(width 0.0889)
		(layer "In2.Cu")
		(net "M_I_CPU1_SA_CB<1>")
	)
	(arc
		(start 135.93191 -245.616984)
		(mid 136.214866 -245.540807)
		(end 136.497822 -245.616984)
		(width 0.0889)
		(layer "In2.Cu")
		(net "M_I_CPU1_SA_CB<1>")
	)
	(arc
		(start 132.737606 -245.616984)
		(mid 132.919857 -245.667334)
		(end 133.103366 -245.62181)
		(width 0.0889)
		(layer "In2.Cu")
		(net "M_I_CPU1_SA_CB<1>")
	)
	(arc
		(start 139.691872 -245.616984)
		(mid 139.974828 -245.540807)
		(end 140.257784 -245.616984)
		(width 0.0889)
		(layer "In2.Cu")
		(net "M_I_CPU1_SA_CB<1>")
	)
	(arc
		(start 134.626096 -245.62181)
		(mid 134.809604 -245.667304)
		(end 134.991856 -245.616984)
		(width 0.0889)
		(layer "In2.Cu")
		(net "M_I_CPU1_SA_CB<1>")
	)
	(arc
		(start 137.811764 -245.616984)
		(mid 138.09472 -245.540807)
		(end 138.377676 -245.616984)
		(width 0.0889)
		(layer "In2.Cu")
		(net "M_I_CPU1_SA_CB<1>")
	)
	(arc
		(start 143.086074 -245.62181)
		(mid 143.269582 -245.667304)
		(end 143.451834 -245.616984)
		(width 0.0889)
		(layer "In2.Cu")
		(net "M_I_CPU1_SA_CB<1>")
	)
	(arc
		(start 135.56615 -245.62181)
		(mid 135.749658 -245.667304)
		(end 135.93191 -245.616984)
		(width 0.0889)
		(layer "In2.Cu")
		(net "M_I_CPU1_SA_CB<1>")
	)
	(arc
		(start 140.631926 -245.616984)
		(mid 140.914882 -245.540807)
		(end 141.197838 -245.616984)
		(width 0.0889)
		(layer "In2.Cu")
		(net "M_I_CPU1_SA_CB<1>")
	)
	(arc
		(start 133.111748 -245.616984)
		(mid 133.394704 -245.540807)
		(end 133.67766 -245.616984)
		(width 0.0889)
		(layer "In2.Cu")
		(net "M_I_CPU1_SA_CB<1>")
	)
	(arc
		(start 139.326112 -245.62181)
		(mid 139.50962 -245.667304)
		(end 139.691872 -245.616984)
		(width 0.0889)
		(layer "In2.Cu")
		(net "M_I_CPU1_SA_CB<1>")
	)
	(arc
		(start 138.377676 -245.616984)
		(mid 138.559927 -245.667334)
		(end 138.743436 -245.62181)
		(width 0.0889)
		(layer "In2.Cu")
		(net "M_I_CPU1_SA_CB<1>")
	)
	(arc
		(start 143.451834 -245.616984)
		(mid 143.73479 -245.540807)
		(end 144.017746 -245.616984)
		(width 0.0889)
		(layer "In2.Cu")
		(net "M_I_CPU1_SA_CB<1>")
	)
	(arc
		(start 136.87171 -245.616984)
		(mid 137.154666 -245.540807)
		(end 137.437622 -245.616984)
		(width 0.0889)
		(layer "In2.Cu")
		(net "M_I_CPU1_SA_CB<1>")
	)
	(arc
		(start 131.797806 -245.616984)
		(mid 131.98475 -245.667239)
		(end 132.171694 -245.616984)
		(width 0.0889)
		(layer "In2.Cu")
		(net "M_I_CPU1_SA_CB<1>")
	)
	(arc
		(start 130.866134 -245.62181)
		(mid 131.049642 -245.667304)
		(end 131.231894 -245.616984)
		(width 0.0889)
		(layer "In2.Cu")
		(net "M_I_CPU1_SA_CB<1>")
	)
	(arc
		(start 144.017746 -245.616984)
		(mid 144.199997 -245.667334)
		(end 144.383506 -245.62181)
		(width 0.0889)
		(layer "In2.Cu")
		(net "M_I_CPU1_SA_CB<1>")
	)
	(arc
		(start 132.171694 -245.616984)
		(mid 132.45465 -245.540807)
		(end 132.737606 -245.616984)
		(width 0.0889)
		(layer "In2.Cu")
		(net "M_I_CPU1_SA_CB<1>")
	)
	(arc
		(start 131.231894 -245.616984)
		(mid 131.51485 -245.540807)
		(end 131.797806 -245.616984)
		(width 0.0889)
		(layer "In2.Cu")
		(net "M_I_CPU1_SA_CB<1>")
	)
	(arc
		(start 134.991856 -245.616984)
		(mid 135.274812 -245.540807)
		(end 135.557768 -245.616984)
		(width 0.0889)
		(layer "In2.Cu")
		(net "M_I_CPU1_SA_CB<1>")
	)
	(arc
		(start 129.92608 -245.62181)
		(mid 130.109588 -245.667304)
		(end 130.29184 -245.616984)
		(width 0.0889)
		(layer "In2.Cu")
		(net "M_I_CPU1_SA_CB<1>")
	)
	(arc
		(start 137.437622 -245.616984)
		(mid 137.619873 -245.667334)
		(end 137.803382 -245.62181)
		(width 0.0889)
		(layer "In2.Cu")
		(net "M_I_CPU1_SA_CB<1>")
	)
	(arc
		(start 128.092962 -245.643146)
		(mid 128.250472 -245.666344)
		(end 128.40335 -245.62181)
		(width 0.0889)
		(layer "In2.Cu")
		(net "M_I_CPU1_SA_CB<1>")
	)
	(arc
		(start 145.331942 -245.616984)
		(mid 145.614898 -245.540807)
		(end 145.897854 -245.616984)
		(width 0.0889)
		(layer "In2.Cu")
		(net "M_I_CPU1_SA_CB<1>")
	)
	(arc
		(start 141.197838 -245.616984)
		(mid 141.384782 -245.667239)
		(end 141.571726 -245.616984)
		(width 0.0889)
		(layer "In2.Cu")
		(net "M_I_CPU1_SA_CB<1>")
	)
	(arc
		(start 144.966182 -245.62181)
		(mid 145.14969 -245.667304)
		(end 145.331942 -245.616984)
		(width 0.0889)
		(layer "In2.Cu")
		(net "M_I_CPU1_SA_CB<1>")
	)
	(arc
		(start 133.67766 -245.616984)
		(mid 133.859911 -245.667334)
		(end 134.04342 -245.62181)
		(width 0.0889)
		(layer "In2.Cu")
		(net "M_I_CPU1_SA_CB<1>")
	)
	(arc
		(start 130.29184 -245.616984)
		(mid 130.574796 -245.540807)
		(end 130.857752 -245.616984)
		(width 0.0889)
		(layer "In2.Cu")
		(net "M_I_CPU1_SA_CB<1>")
	)
	(arc
		(start 129.351786 -245.616984)
		(mid 129.634742 -245.540807)
		(end 129.917698 -245.616984)
		(width 0.0889)
		(layer "In2.Cu")
		(net "M_I_CPU1_SA_CB<1>")
	)
	(arc
		(start 138.751818 -245.616984)
		(mid 139.034774 -245.540807)
		(end 139.31773 -245.616984)
		(width 0.0889)
		(layer "In2.Cu")
		(net "M_I_CPU1_SA_CB<1>")
	)
	(arc
		(start 134.051802 -245.616984)
		(mid 134.334758 -245.540807)
		(end 134.617714 -245.616984)
		(width 0.0889)
		(layer "In2.Cu")
		(net "M_I_CPU1_SA_CB<1>")
	)
	(arc
		(start 142.51178 -245.616984)
		(mid 142.794736 -245.540807)
		(end 143.077692 -245.616984)
		(width 0.0889)
		(layer "In2.Cu")
		(net "M_I_CPU1_SA_CB<1>")
	)
	(arc
		(start 140.266166 -245.62181)
		(mid 140.449674 -245.667304)
		(end 140.631926 -245.616984)
		(width 0.0889)
		(layer "In2.Cu")
		(net "M_I_CPU1_SA_CB<1>")
	)
	(segment
		(start 129.16789 -244.750336)
		(end 129.634742 -244.484398)
		(width 0.10668)
		(layer "F.Cu")
		(net "M_I_CPU1_SA_CB<0>")
	)
	(segment
		(start 141.093444 -244.811804)
		(end 141.101826 -244.806978)
		(width 0.0889)
		(layer "In2.Cu")
		(net "M_I_CPU1_SA_CB<0>")
	)
	(segment
		(start 143.920464 -244.806724)
		(end 143.94434 -244.792754)
		(width 0.0889)
		(layer "In2.Cu")
		(net "M_I_CPU1_SA_CB<0>")
	)
	(segment
		(start 141.667738 -244.806978)
		(end 141.67612 -244.811804)
		(width 0.0889)
		(layer "In2.Cu")
		(net "M_I_CPU1_SA_CB<0>")
	)
	(segment
		(start 136.393428 -244.811804)
		(end 136.40181 -244.806978)
		(width 0.0889)
		(layer "In2.Cu")
		(net "M_I_CPU1_SA_CB<0>")
	)
	(segment
		(start 147.665948 -243.780564)
		(end 155.043632 -243.780564)
		(width 0.14478)
		(layer "In2.Cu")
		(net "M_I_CPU1_SA_CB<0>")
	)
	(segment
		(start 136.967722 -244.806978)
		(end 136.976104 -244.811804)
		(width 0.0889)
		(layer "In2.Cu")
		(net "M_I_CPU1_SA_CB<0>")
	)
	(segment
		(start 171.0436 -235.160312)
		(end 172.863764 -235.160312)
		(width 0.14478)
		(layer "In2.Cu")
		(net "M_I_CPU1_SA_CB<0>")
	)
	(segment
		(start 145.387822 -244.78488)
		(end 145.425668 -244.806724)
		(width 0.0889)
		(layer "In2.Cu")
		(net "M_I_CPU1_SA_CB<0>")
	)
	(segment
		(start 181.804564 -234.310428)
		(end 182.1307 -234.636564)
		(width 0.14478)
		(layer "In2.Cu")
		(net "M_I_CPU1_SA_CB<0>")
	)
	(segment
		(start 132.267706 -244.806978)
		(end 132.276088 -244.811804)
		(width 0.0889)
		(layer "In2.Cu")
		(net "M_I_CPU1_SA_CB<0>")
	)
	(segment
		(start 177.623724 -234.636564)
		(end 177.856388 -234.636564)
		(width 0.14478)
		(layer "In2.Cu")
		(net "M_I_CPU1_SA_CB<0>")
	)
	(segment
		(start 146.515328 -244.372384)
		(end 147.074128 -244.372384)
		(width 0.0889)
		(layer "In2.Cu")
		(net "M_I_CPU1_SA_CB<0>")
	)
	(segment
		(start 146.03095 -244.856762)
		(end 146.515328 -244.372384)
		(width 0.0889)
		(layer "In2.Cu")
		(net "M_I_CPU1_SA_CB<0>")
	)
	(segment
		(start 182.363364 -234.636564)
		(end 182.6895 -234.310428)
		(width 0.14478)
		(layer "In2.Cu")
		(net "M_I_CPU1_SA_CB<0>")
	)
	(segment
		(start 131.693412 -244.811804)
		(end 131.701794 -244.806978)
		(width 0.0889)
		(layer "In2.Cu")
		(net "M_I_CPU1_SA_CB<0>")
	)
	(segment
		(start 130.753358 -244.811804)
		(end 130.76174 -244.806978)
		(width 0.0889)
		(layer "In2.Cu")
		(net "M_I_CPU1_SA_CB<0>")
	)
	(segment
		(start 140.15339 -244.811804)
		(end 140.161772 -244.806978)
		(width 0.0889)
		(layer "In2.Cu")
		(net "M_I_CPU1_SA_CB<0>")
	)
	(segment
		(start 177.856388 -234.636564)
		(end 178.182524 -234.310428)
		(width 0.14478)
		(layer "In2.Cu")
		(net "M_I_CPU1_SA_CB<0>")
	)
	(segment
		(start 135.453374 -244.811804)
		(end 135.461756 -244.806978)
		(width 0.0889)
		(layer "In2.Cu")
		(net "M_I_CPU1_SA_CB<0>")
	)
	(segment
		(start 182.1307 -234.636564)
		(end 182.363364 -234.636564)
		(width 0.14478)
		(layer "In2.Cu")
		(net "M_I_CPU1_SA_CB<0>")
	)
	(segment
		(start 181.0131 -234.636564)
		(end 181.245764 -234.636564)
		(width 0.14478)
		(layer "In2.Cu")
		(net "M_I_CPU1_SA_CB<0>")
	)
	(segment
		(start 172.863764 -235.160312)
		(end 174.915576 -234.310428)
		(width 0.14478)
		(layer "In2.Cu")
		(net "M_I_CPU1_SA_CB<0>")
	)
	(segment
		(start 129.634742 -244.484398)
		(end 129.480818 -244.749828)
		(width 0.0889)
		(layer "In2.Cu")
		(net "M_I_CPU1_SA_CB<0>")
	)
	(segment
		(start 155.043632 -243.780564)
		(end 163.663884 -235.160312)
		(width 0.14478)
		(layer "In2.Cu")
		(net "M_I_CPU1_SA_CB<0>")
	)
	(segment
		(start 170.193716 -234.310428)
		(end 171.0436 -235.160312)
		(width 0.14478)
		(layer "In2.Cu")
		(net "M_I_CPU1_SA_CB<0>")
	)
	(segment
		(start 143.897096 -244.820186)
		(end 143.920464 -244.806724)
		(width 0.0889)
		(layer "In2.Cu")
		(net "M_I_CPU1_SA_CB<0>")
	)
	(segment
		(start 137.907776 -244.806978)
		(end 137.916158 -244.811804)
		(width 0.0889)
		(layer "In2.Cu")
		(net "M_I_CPU1_SA_CB<0>")
	)
	(segment
		(start 144.484598 -244.806978)
		(end 144.505172 -244.818916)
		(width 0.0889)
		(layer "In2.Cu")
		(net "M_I_CPU1_SA_CB<0>")
	)
	(segment
		(start 174.915576 -234.310428)
		(end 177.297588 -234.310428)
		(width 0.14478)
		(layer "In2.Cu")
		(net "M_I_CPU1_SA_CB<0>")
	)
	(segment
		(start 181.5719 -234.310428)
		(end 181.804564 -234.310428)
		(width 0.14478)
		(layer "In2.Cu")
		(net "M_I_CPU1_SA_CB<0>")
	)
	(segment
		(start 180.686964 -234.310428)
		(end 181.0131 -234.636564)
		(width 0.14478)
		(layer "In2.Cu")
		(net "M_I_CPU1_SA_CB<0>")
	)
	(segment
		(start 178.182524 -234.310428)
		(end 180.686964 -234.310428)
		(width 0.14478)
		(layer "In2.Cu")
		(net "M_I_CPU1_SA_CB<0>")
	)
	(segment
		(start 145.611596 -244.856762)
		(end 146.03095 -244.856762)
		(width 0.0889)
		(layer "In2.Cu")
		(net "M_I_CPU1_SA_CB<0>")
	)
	(segment
		(start 147.074128 -244.372384)
		(end 147.665948 -243.780564)
		(width 0.0889)
		(layer "In2.Cu")
		(net "M_I_CPU1_SA_CB<0>")
	)
	(segment
		(start 166.501318 -235.160312)
		(end 167.350948 -234.310682)
		(width 0.14478)
		(layer "In2.Cu")
		(net "M_I_CPU1_SA_CB<0>")
	)
	(segment
		(start 182.6895 -234.310428)
		(end 183.19115 -234.310428)
		(width 0.14478)
		(layer "In2.Cu")
		(net "M_I_CPU1_SA_CB<0>")
	)
	(segment
		(start 183.19115 -234.310428)
		(end 183.616092 -234.73537)
		(width 0.14478)
		(layer "In2.Cu")
		(net "M_I_CPU1_SA_CB<0>")
	)
	(segment
		(start 177.297588 -234.310428)
		(end 177.623724 -234.636564)
		(width 0.14478)
		(layer "In2.Cu")
		(net "M_I_CPU1_SA_CB<0>")
	)
	(segment
		(start 163.663884 -235.160312)
		(end 166.501318 -235.160312)
		(width 0.14478)
		(layer "In2.Cu")
		(net "M_I_CPU1_SA_CB<0>")
	)
	(segment
		(start 181.245764 -234.636564)
		(end 181.5719 -234.310428)
		(width 0.14478)
		(layer "In2.Cu")
		(net "M_I_CPU1_SA_CB<0>")
	)
	(segment
		(start 133.20776 -244.806978)
		(end 133.216142 -244.811804)
		(width 0.0889)
		(layer "In2.Cu")
		(net "M_I_CPU1_SA_CB<0>")
	)
	(segment
		(start 167.35171 -234.310428)
		(end 170.193716 -234.310428)
		(width 0.14478)
		(layer "In2.Cu")
		(net "M_I_CPU1_SA_CB<0>")
	)
	(segment
		(start 129.480818 -244.749828)
		(end 129.50317 -244.83314)
		(width 0.0889)
		(layer "In2.Cu")
		(net "M_I_CPU1_SA_CB<0>")
	)
	(segment
		(start 167.350948 -234.310682)
		(end 167.35171 -234.310428)
		(width 0.14478)
		(layer "In2.Cu")
		(net "M_I_CPU1_SA_CB<0>")
	)
	(arc
		(start 143.547592 -244.806978)
		(mid 143.7207 -244.857094)
		(end 143.897096 -244.820186)
		(width 0.0889)
		(layer "In2.Cu")
		(net "M_I_CPU1_SA_CB<0>")
	)
	(arc
		(start 131.327652 -244.806978)
		(mid 131.509903 -244.857328)
		(end 131.693412 -244.811804)
		(width 0.0889)
		(layer "In2.Cu")
		(net "M_I_CPU1_SA_CB<0>")
	)
	(arc
		(start 129.821686 -244.806978)
		(mid 130.104642 -244.730801)
		(end 130.387598 -244.806978)
		(width 0.0889)
		(layer "In2.Cu")
		(net "M_I_CPU1_SA_CB<0>")
	)
	(arc
		(start 130.387598 -244.806978)
		(mid 130.569849 -244.857328)
		(end 130.753358 -244.811804)
		(width 0.0889)
		(layer "In2.Cu")
		(net "M_I_CPU1_SA_CB<0>")
	)
	(arc
		(start 133.581902 -244.806978)
		(mid 133.864858 -244.730801)
		(end 134.147814 -244.806978)
		(width 0.0889)
		(layer "In2.Cu")
		(net "M_I_CPU1_SA_CB<0>")
	)
	(arc
		(start 133.216142 -244.811804)
		(mid 133.39965 -244.857298)
		(end 133.581902 -244.806978)
		(width 0.0889)
		(layer "In2.Cu")
		(net "M_I_CPU1_SA_CB<0>")
	)
	(arc
		(start 131.701794 -244.806978)
		(mid 131.98475 -244.730801)
		(end 132.267706 -244.806978)
		(width 0.0889)
		(layer "In2.Cu")
		(net "M_I_CPU1_SA_CB<0>")
	)
	(arc
		(start 141.67612 -244.811804)
		(mid 141.859628 -244.857298)
		(end 142.04188 -244.806978)
		(width 0.0889)
		(layer "In2.Cu")
		(net "M_I_CPU1_SA_CB<0>")
	)
	(arc
		(start 139.221718 -244.806978)
		(mid 139.504674 -244.730801)
		(end 139.78763 -244.806978)
		(width 0.0889)
		(layer "In2.Cu")
		(net "M_I_CPU1_SA_CB<0>")
	)
	(arc
		(start 144.505172 -244.818916)
		(mid 144.6841 -244.857793)
		(end 144.86001 -244.806978)
		(width 0.0889)
		(layer "In2.Cu")
		(net "M_I_CPU1_SA_CB<0>")
	)
	(arc
		(start 140.727684 -244.806978)
		(mid 140.909935 -244.857328)
		(end 141.093444 -244.811804)
		(width 0.0889)
		(layer "In2.Cu")
		(net "M_I_CPU1_SA_CB<0>")
	)
	(arc
		(start 142.04188 -244.806978)
		(mid 142.324836 -244.730801)
		(end 142.607792 -244.806978)
		(width 0.0889)
		(layer "In2.Cu")
		(net "M_I_CPU1_SA_CB<0>")
	)
	(arc
		(start 132.641848 -244.806978)
		(mid 132.924804 -244.730801)
		(end 133.20776 -244.806978)
		(width 0.0889)
		(layer "In2.Cu")
		(net "M_I_CPU1_SA_CB<0>")
	)
	(arc
		(start 141.101826 -244.806978)
		(mid 141.384782 -244.730801)
		(end 141.667738 -244.806978)
		(width 0.0889)
		(layer "In2.Cu")
		(net "M_I_CPU1_SA_CB<0>")
	)
	(arc
		(start 135.461756 -244.806978)
		(mid 135.744712 -244.730801)
		(end 136.027668 -244.806978)
		(width 0.0889)
		(layer "In2.Cu")
		(net "M_I_CPU1_SA_CB<0>")
	)
	(arc
		(start 138.281918 -244.806978)
		(mid 138.564874 -244.730801)
		(end 138.84783 -244.806978)
		(width 0.0889)
		(layer "In2.Cu")
		(net "M_I_CPU1_SA_CB<0>")
	)
	(arc
		(start 132.276088 -244.811804)
		(mid 132.459596 -244.857298)
		(end 132.641848 -244.806978)
		(width 0.0889)
		(layer "In2.Cu")
		(net "M_I_CPU1_SA_CB<0>")
	)
	(arc
		(start 130.76174 -244.806978)
		(mid 131.044696 -244.730801)
		(end 131.327652 -244.806978)
		(width 0.0889)
		(layer "In2.Cu")
		(net "M_I_CPU1_SA_CB<0>")
	)
	(arc
		(start 139.78763 -244.806978)
		(mid 139.969881 -244.857328)
		(end 140.15339 -244.811804)
		(width 0.0889)
		(layer "In2.Cu")
		(net "M_I_CPU1_SA_CB<0>")
	)
	(arc
		(start 144.86001 -244.806978)
		(mid 145.121168 -244.730399)
		(end 145.387822 -244.78488)
		(width 0.0889)
		(layer "In2.Cu")
		(net "M_I_CPU1_SA_CB<0>")
	)
	(arc
		(start 145.425668 -244.806724)
		(mid 145.515338 -244.843992)
		(end 145.611596 -244.856762)
		(width 0.0889)
		(layer "In2.Cu")
		(net "M_I_CPU1_SA_CB<0>")
	)
	(arc
		(start 137.341864 -244.806978)
		(mid 137.62482 -244.730801)
		(end 137.907776 -244.806978)
		(width 0.0889)
		(layer "In2.Cu")
		(net "M_I_CPU1_SA_CB<0>")
	)
	(arc
		(start 136.40181 -244.806978)
		(mid 136.684766 -244.730801)
		(end 136.967722 -244.806978)
		(width 0.0889)
		(layer "In2.Cu")
		(net "M_I_CPU1_SA_CB<0>")
	)
	(arc
		(start 135.087614 -244.806978)
		(mid 135.269865 -244.857328)
		(end 135.453374 -244.811804)
		(width 0.0889)
		(layer "In2.Cu")
		(net "M_I_CPU1_SA_CB<0>")
	)
	(arc
		(start 129.50317 -244.83314)
		(mid 129.665359 -244.855875)
		(end 129.821686 -244.806978)
		(width 0.0889)
		(layer "In2.Cu")
		(net "M_I_CPU1_SA_CB<0>")
	)
	(arc
		(start 134.147814 -244.806978)
		(mid 134.334758 -244.857233)
		(end 134.521702 -244.806978)
		(width 0.0889)
		(layer "In2.Cu")
		(net "M_I_CPU1_SA_CB<0>")
	)
	(arc
		(start 136.027668 -244.806978)
		(mid 136.209919 -244.857328)
		(end 136.393428 -244.811804)
		(width 0.0889)
		(layer "In2.Cu")
		(net "M_I_CPU1_SA_CB<0>")
	)
	(arc
		(start 142.98168 -244.806978)
		(mid 143.264636 -244.730801)
		(end 143.547592 -244.806978)
		(width 0.0889)
		(layer "In2.Cu")
		(net "M_I_CPU1_SA_CB<0>")
	)
	(arc
		(start 134.521702 -244.806978)
		(mid 134.804658 -244.730801)
		(end 135.087614 -244.806978)
		(width 0.0889)
		(layer "In2.Cu")
		(net "M_I_CPU1_SA_CB<0>")
	)
	(arc
		(start 142.607792 -244.806978)
		(mid 142.794736 -244.857233)
		(end 142.98168 -244.806978)
		(width 0.0889)
		(layer "In2.Cu")
		(net "M_I_CPU1_SA_CB<0>")
	)
	(arc
		(start 137.916158 -244.811804)
		(mid 138.099666 -244.857298)
		(end 138.281918 -244.806978)
		(width 0.0889)
		(layer "In2.Cu")
		(net "M_I_CPU1_SA_CB<0>")
	)
	(arc
		(start 138.84783 -244.806978)
		(mid 139.034774 -244.857233)
		(end 139.221718 -244.806978)
		(width 0.0889)
		(layer "In2.Cu")
		(net "M_I_CPU1_SA_CB<0>")
	)
	(arc
		(start 136.976104 -244.811804)
		(mid 137.159612 -244.857298)
		(end 137.341864 -244.806978)
		(width 0.0889)
		(layer "In2.Cu")
		(net "M_I_CPU1_SA_CB<0>")
	)
	(arc
		(start 140.161772 -244.806978)
		(mid 140.444728 -244.730801)
		(end 140.727684 -244.806978)
		(width 0.0889)
		(layer "In2.Cu")
		(net "M_I_CPU1_SA_CB<0>")
	)
	(arc
		(start 143.94434 -244.792754)
		(mid 144.216277 -244.730928)
		(end 144.484598 -244.806978)
		(width 0.0889)
		(layer "In2.Cu")
		(net "M_I_CPU1_SA_CB<0>")
	)
	(segment
		(start 127.757936 -255.280414)
		(end 128.224788 -255.014476)
		(width 0.10668)
		(layer "F.Cu")
		(net "M_I_CPU1_SA_CA<6>")
	)
	(segment
		(start 128.07061 -255.279906)
		(end 128.092962 -255.363218)
		(width 0.0889)
		(layer "In2.Cu")
		(net "M_I_CPU1_SA_CA<6>")
	)
	(segment
		(start 152.273 -254.644906)
		(end 155.814014 -254.644906)
		(width 0.14478)
		(layer "In2.Cu")
		(net "M_I_CPU1_SA_CA<6>")
	)
	(segment
		(start 145.187924 -255.365758)
		(end 145.277332 -255.343914)
		(width 0.0889)
		(layer "In2.Cu")
		(net "M_I_CPU1_SA_CA<6>")
	)
	(segment
		(start 138.743436 -255.341882)
		(end 138.751818 -255.337056)
		(width 0.0889)
		(layer "In2.Cu")
		(net "M_I_CPU1_SA_CA<6>")
	)
	(segment
		(start 163.049966 -255.11633)
		(end 164.029898 -254.710438)
		(width 0.14478)
		(layer "In2.Cu")
		(net "M_I_CPU1_SA_CA<6>")
	)
	(segment
		(start 179.279042 -252.217428)
		(end 179.285646 -252.217428)
		(width 0.0889)
		(layer "In2.Cu")
		(net "M_I_CPU1_SA_CA<6>")
	)
	(segment
		(start 144.380966 -255.343914)
		(end 144.39265 -255.337056)
		(width 0.0889)
		(layer "In2.Cu")
		(net "M_I_CPU1_SA_CA<6>")
	)
	(segment
		(start 164.029898 -254.710438)
		(end 173.70552 -254.710438)
		(width 0.14478)
		(layer "In2.Cu")
		(net "M_I_CPU1_SA_CA<6>")
	)
	(segment
		(start 129.917698 -255.337056)
		(end 129.92608 -255.341882)
		(width 0.0889)
		(layer "In2.Cu")
		(net "M_I_CPU1_SA_CA<6>")
	)
	(segment
		(start 179.285646 -252.217428)
		(end 179.342796 -252.160278)
		(width 0.0889)
		(layer "In2.Cu")
		(net "M_I_CPU1_SA_CA<6>")
	)
	(segment
		(start 147.30857 -255.912366)
		(end 151.00554 -255.912366)
		(width 0.14478)
		(layer "In2.Cu")
		(net "M_I_CPU1_SA_CA<6>")
	)
	(segment
		(start 173.70552 -254.710438)
		(end 174.915576 -254.209296)
		(width 0.14478)
		(layer "In2.Cu")
		(net "M_I_CPU1_SA_CA<6>")
	)
	(segment
		(start 147.082764 -255.912366)
		(end 147.30857 -255.912366)
		(width 0.0889)
		(layer "In2.Cu")
		(net "M_I_CPU1_SA_CA<6>")
	)
	(segment
		(start 179.118006 -252.378464)
		(end 179.279042 -252.217428)
		(width 0.14478)
		(layer "In2.Cu")
		(net "M_I_CPU1_SA_CA<6>")
	)
	(segment
		(start 175.264572 -253.8603)
		(end 176.811686 -253.8603)
		(width 0.14478)
		(layer "In2.Cu")
		(net "M_I_CPU1_SA_CA<6>")
	)
	(segment
		(start 146.444208 -255.536954)
		(end 146.660362 -255.536954)
		(width 0.0889)
		(layer "In2.Cu")
		(net "M_I_CPU1_SA_CA<6>")
	)
	(segment
		(start 135.557768 -255.337056)
		(end 135.56615 -255.341882)
		(width 0.0889)
		(layer "In2.Cu")
		(net "M_I_CPU1_SA_CA<6>")
	)
	(segment
		(start 129.343404 -255.341882)
		(end 129.351786 -255.337056)
		(width 0.0889)
		(layer "In2.Cu")
		(net "M_I_CPU1_SA_CA<6>")
	)
	(segment
		(start 178.845972 -252.378464)
		(end 179.118006 -252.378464)
		(width 0.14478)
		(layer "In2.Cu")
		(net "M_I_CPU1_SA_CA<6>")
	)
	(segment
		(start 145.299938 -255.336548)
		(end 145.385028 -255.301496)
		(width 0.0889)
		(layer "In2.Cu")
		(net "M_I_CPU1_SA_CA<6>")
	)
	(segment
		(start 146.740626 -255.570228)
		(end 147.082764 -255.912366)
		(width 0.0889)
		(layer "In2.Cu")
		(net "M_I_CPU1_SA_CA<6>")
	)
	(segment
		(start 151.00554 -255.912366)
		(end 152.273 -254.644906)
		(width 0.14478)
		(layer "In2.Cu")
		(net "M_I_CPU1_SA_CA<6>")
	)
	(segment
		(start 128.40335 -255.341882)
		(end 128.411732 -255.337056)
		(width 0.0889)
		(layer "In2.Cu")
		(net "M_I_CPU1_SA_CA<6>")
	)
	(segment
		(start 140.257784 -255.337056)
		(end 140.266166 -255.341882)
		(width 0.0889)
		(layer "In2.Cu")
		(net "M_I_CPU1_SA_CA<6>")
	)
	(segment
		(start 130.857752 -255.337056)
		(end 130.866134 -255.341882)
		(width 0.0889)
		(layer "In2.Cu")
		(net "M_I_CPU1_SA_CA<6>")
	)
	(segment
		(start 179.342796 -252.160278)
		(end 179.701444 -252.160278)
		(width 0.0889)
		(layer "In2.Cu")
		(net "M_I_CPU1_SA_CA<6>")
	)
	(segment
		(start 177.90287 -252.769116)
		(end 178.845972 -252.378464)
		(width 0.14478)
		(layer "In2.Cu")
		(net "M_I_CPU1_SA_CA<6>")
	)
	(segment
		(start 142.503398 -255.341882)
		(end 142.51178 -255.337056)
		(width 0.0889)
		(layer "In2.Cu")
		(net "M_I_CPU1_SA_CA<6>")
	)
	(segment
		(start 143.451834 -255.337056)
		(end 143.466566 -255.32842)
		(width 0.0889)
		(layer "In2.Cu")
		(net "M_I_CPU1_SA_CA<6>")
	)
	(segment
		(start 176.811686 -253.8603)
		(end 177.90287 -252.769116)
		(width 0.14478)
		(layer "In2.Cu")
		(net "M_I_CPU1_SA_CA<6>")
	)
	(segment
		(start 139.31773 -255.337056)
		(end 139.326112 -255.341882)
		(width 0.0889)
		(layer "In2.Cu")
		(net "M_I_CPU1_SA_CA<6>")
	)
	(segment
		(start 183.19115 -252.160278)
		(end 183.616092 -252.58522)
		(width 0.14478)
		(layer "In2.Cu")
		(net "M_I_CPU1_SA_CA<6>")
	)
	(segment
		(start 133.103366 -255.341882)
		(end 133.111748 -255.337056)
		(width 0.0889)
		(layer "In2.Cu")
		(net "M_I_CPU1_SA_CA<6>")
	)
	(segment
		(start 137.803382 -255.341882)
		(end 137.811764 -255.337056)
		(width 0.0889)
		(layer "In2.Cu")
		(net "M_I_CPU1_SA_CA<6>")
	)
	(segment
		(start 155.814014 -254.644906)
		(end 156.285438 -255.11633)
		(width 0.14478)
		(layer "In2.Cu")
		(net "M_I_CPU1_SA_CA<6>")
	)
	(segment
		(start 128.224788 -255.014476)
		(end 128.07061 -255.279906)
		(width 0.0889)
		(layer "In2.Cu")
		(net "M_I_CPU1_SA_CA<6>")
	)
	(segment
		(start 145.187416 -255.365758)
		(end 145.187924 -255.365758)
		(width 0.0889)
		(layer "In2.Cu")
		(net "M_I_CPU1_SA_CA<6>")
	)
	(segment
		(start 174.915576 -254.209296)
		(end 175.264572 -253.8603)
		(width 0.14478)
		(layer "In2.Cu")
		(net "M_I_CPU1_SA_CA<6>")
	)
	(segment
		(start 156.285438 -255.11633)
		(end 163.049966 -255.11633)
		(width 0.14478)
		(layer "In2.Cu")
		(net "M_I_CPU1_SA_CA<6>")
	)
	(segment
		(start 134.617714 -255.337056)
		(end 134.626096 -255.341882)
		(width 0.0889)
		(layer "In2.Cu")
		(net "M_I_CPU1_SA_CA<6>")
	)
	(segment
		(start 179.701444 -252.160278)
		(end 183.19115 -252.160278)
		(width 0.14478)
		(layer "In2.Cu")
		(net "M_I_CPU1_SA_CA<6>")
	)
	(segment
		(start 134.04342 -255.341882)
		(end 134.051802 -255.337056)
		(width 0.0889)
		(layer "In2.Cu")
		(net "M_I_CPU1_SA_CA<6>")
	)
	(segment
		(start 143.077692 -255.337056)
		(end 143.086074 -255.341882)
		(width 0.0889)
		(layer "In2.Cu")
		(net "M_I_CPU1_SA_CA<6>")
	)
	(arc
		(start 145.385028 -255.301496)
		(mid 145.604868 -255.256112)
		(end 145.82648 -255.291844)
		(width 0.0889)
		(layer "In2.Cu")
		(net "M_I_CPU1_SA_CA<6>")
	)
	(arc
		(start 132.737606 -255.337056)
		(mid 132.919857 -255.387406)
		(end 133.103366 -255.341882)
		(width 0.0889)
		(layer "In2.Cu")
		(net "M_I_CPU1_SA_CA<6>")
	)
	(arc
		(start 130.866134 -255.341882)
		(mid 131.049642 -255.387376)
		(end 131.231894 -255.337056)
		(width 0.0889)
		(layer "In2.Cu")
		(net "M_I_CPU1_SA_CA<6>")
	)
	(arc
		(start 138.751818 -255.337056)
		(mid 139.034774 -255.260879)
		(end 139.31773 -255.337056)
		(width 0.0889)
		(layer "In2.Cu")
		(net "M_I_CPU1_SA_CA<6>")
	)
	(arc
		(start 145.277332 -255.343914)
		(mid 145.288775 -255.34066)
		(end 145.299938 -255.336548)
		(width 0.0889)
		(layer "In2.Cu")
		(net "M_I_CPU1_SA_CA<6>")
	)
	(arc
		(start 146.660362 -255.536954)
		(mid 146.703797 -255.545612)
		(end 146.740626 -255.570228)
		(width 0.0889)
		(layer "In2.Cu")
		(net "M_I_CPU1_SA_CA<6>")
	)
	(arc
		(start 145.82648 -255.291844)
		(mid 145.867523 -255.308834)
		(end 145.906744 -255.32969)
		(width 0.0889)
		(layer "In2.Cu")
		(net "M_I_CPU1_SA_CA<6>")
	)
	(arc
		(start 144.39265 -255.337056)
		(mid 144.672078 -255.26089)
		(end 144.952466 -255.3335)
		(width 0.0889)
		(layer "In2.Cu")
		(net "M_I_CPU1_SA_CA<6>")
	)
	(arc
		(start 130.29184 -255.337056)
		(mid 130.574796 -255.260879)
		(end 130.857752 -255.337056)
		(width 0.0889)
		(layer "In2.Cu")
		(net "M_I_CPU1_SA_CA<6>")
	)
	(arc
		(start 128.092962 -255.363218)
		(mid 128.250472 -255.386416)
		(end 128.40335 -255.341882)
		(width 0.0889)
		(layer "In2.Cu")
		(net "M_I_CPU1_SA_CA<6>")
	)
	(arc
		(start 142.137638 -255.337056)
		(mid 142.319889 -255.387406)
		(end 142.503398 -255.341882)
		(width 0.0889)
		(layer "In2.Cu")
		(net "M_I_CPU1_SA_CA<6>")
	)
	(arc
		(start 128.411732 -255.337056)
		(mid 128.694688 -255.260879)
		(end 128.977644 -255.337056)
		(width 0.0889)
		(layer "In2.Cu")
		(net "M_I_CPU1_SA_CA<6>")
	)
	(arc
		(start 134.051802 -255.337056)
		(mid 134.334758 -255.260879)
		(end 134.617714 -255.337056)
		(width 0.0889)
		(layer "In2.Cu")
		(net "M_I_CPU1_SA_CA<6>")
	)
	(arc
		(start 143.086074 -255.341882)
		(mid 143.269582 -255.387376)
		(end 143.451834 -255.337056)
		(width 0.0889)
		(layer "In2.Cu")
		(net "M_I_CPU1_SA_CA<6>")
	)
	(arc
		(start 134.991856 -255.337056)
		(mid 135.274812 -255.260879)
		(end 135.557768 -255.337056)
		(width 0.0889)
		(layer "In2.Cu")
		(net "M_I_CPU1_SA_CA<6>")
	)
	(arc
		(start 133.67766 -255.337056)
		(mid 133.859911 -255.387406)
		(end 134.04342 -255.341882)
		(width 0.0889)
		(layer "In2.Cu")
		(net "M_I_CPU1_SA_CA<6>")
	)
	(arc
		(start 146.35607 -255.524508)
		(mid 146.399697 -255.533863)
		(end 146.444208 -255.536954)
		(width 0.0889)
		(layer "In2.Cu")
		(net "M_I_CPU1_SA_CA<6>")
	)
	(arc
		(start 137.811764 -255.337056)
		(mid 138.09472 -255.260879)
		(end 138.377676 -255.337056)
		(width 0.0889)
		(layer "In2.Cu")
		(net "M_I_CPU1_SA_CA<6>")
	)
	(arc
		(start 141.197838 -255.337056)
		(mid 141.384782 -255.387311)
		(end 141.571726 -255.337056)
		(width 0.0889)
		(layer "In2.Cu")
		(net "M_I_CPU1_SA_CA<6>")
	)
	(arc
		(start 129.351786 -255.337056)
		(mid 129.634742 -255.260879)
		(end 129.917698 -255.337056)
		(width 0.0889)
		(layer "In2.Cu")
		(net "M_I_CPU1_SA_CA<6>")
	)
	(arc
		(start 131.231894 -255.337056)
		(mid 131.51485 -255.260879)
		(end 131.797806 -255.337056)
		(width 0.0889)
		(layer "In2.Cu")
		(net "M_I_CPU1_SA_CA<6>")
	)
	(arc
		(start 136.87171 -255.337056)
		(mid 137.154666 -255.260879)
		(end 137.437622 -255.337056)
		(width 0.0889)
		(layer "In2.Cu")
		(net "M_I_CPU1_SA_CA<6>")
	)
	(arc
		(start 137.437622 -255.337056)
		(mid 137.619873 -255.387406)
		(end 137.803382 -255.341882)
		(width 0.0889)
		(layer "In2.Cu")
		(net "M_I_CPU1_SA_CA<6>")
	)
	(arc
		(start 144.952466 -255.3335)
		(mid 145.066871 -255.371947)
		(end 145.187416 -255.365758)
		(width 0.0889)
		(layer "In2.Cu")
		(net "M_I_CPU1_SA_CA<6>")
	)
	(arc
		(start 142.51178 -255.337056)
		(mid 142.794736 -255.260879)
		(end 143.077692 -255.337056)
		(width 0.0889)
		(layer "In2.Cu")
		(net "M_I_CPU1_SA_CA<6>")
	)
	(arc
		(start 135.56615 -255.341882)
		(mid 135.749658 -255.387376)
		(end 135.93191 -255.337056)
		(width 0.0889)
		(layer "In2.Cu")
		(net "M_I_CPU1_SA_CA<6>")
	)
	(arc
		(start 132.171694 -255.337056)
		(mid 132.45465 -255.260879)
		(end 132.737606 -255.337056)
		(width 0.0889)
		(layer "In2.Cu")
		(net "M_I_CPU1_SA_CA<6>")
	)
	(arc
		(start 129.92608 -255.341882)
		(mid 130.109588 -255.387376)
		(end 130.29184 -255.337056)
		(width 0.0889)
		(layer "In2.Cu")
		(net "M_I_CPU1_SA_CA<6>")
	)
	(arc
		(start 145.906744 -255.32969)
		(mid 146.125287 -255.441213)
		(end 146.35607 -255.524508)
		(width 0.0889)
		(layer "In2.Cu")
		(net "M_I_CPU1_SA_CA<6>")
	)
	(arc
		(start 133.111748 -255.337056)
		(mid 133.394704 -255.260879)
		(end 133.67766 -255.337056)
		(width 0.0889)
		(layer "In2.Cu")
		(net "M_I_CPU1_SA_CA<6>")
	)
	(arc
		(start 143.466566 -255.32842)
		(mid 143.743549 -255.260616)
		(end 144.018254 -255.337056)
		(width 0.0889)
		(layer "In2.Cu")
		(net "M_I_CPU1_SA_CA<6>")
	)
	(arc
		(start 138.377676 -255.337056)
		(mid 138.559927 -255.387406)
		(end 138.743436 -255.341882)
		(width 0.0889)
		(layer "In2.Cu")
		(net "M_I_CPU1_SA_CA<6>")
	)
	(arc
		(start 134.626096 -255.341882)
		(mid 134.809604 -255.387376)
		(end 134.991856 -255.337056)
		(width 0.0889)
		(layer "In2.Cu")
		(net "M_I_CPU1_SA_CA<6>")
	)
	(arc
		(start 128.977644 -255.337056)
		(mid 129.159895 -255.387406)
		(end 129.343404 -255.341882)
		(width 0.0889)
		(layer "In2.Cu")
		(net "M_I_CPU1_SA_CA<6>")
	)
	(arc
		(start 144.018254 -255.337056)
		(mid 144.198712 -255.3875)
		(end 144.380966 -255.343914)
		(width 0.0889)
		(layer "In2.Cu")
		(net "M_I_CPU1_SA_CA<6>")
	)
	(arc
		(start 136.497822 -255.337056)
		(mid 136.684766 -255.387311)
		(end 136.87171 -255.337056)
		(width 0.0889)
		(layer "In2.Cu")
		(net "M_I_CPU1_SA_CA<6>")
	)
	(arc
		(start 131.797806 -255.337056)
		(mid 131.98475 -255.387311)
		(end 132.171694 -255.337056)
		(width 0.0889)
		(layer "In2.Cu")
		(net "M_I_CPU1_SA_CA<6>")
	)
	(arc
		(start 140.266166 -255.341882)
		(mid 140.449674 -255.387376)
		(end 140.631926 -255.337056)
		(width 0.0889)
		(layer "In2.Cu")
		(net "M_I_CPU1_SA_CA<6>")
	)
	(arc
		(start 141.571726 -255.337056)
		(mid 141.854682 -255.260879)
		(end 142.137638 -255.337056)
		(width 0.0889)
		(layer "In2.Cu")
		(net "M_I_CPU1_SA_CA<6>")
	)
	(arc
		(start 135.93191 -255.337056)
		(mid 136.214866 -255.260879)
		(end 136.497822 -255.337056)
		(width 0.0889)
		(layer "In2.Cu")
		(net "M_I_CPU1_SA_CA<6>")
	)
	(arc
		(start 140.631926 -255.337056)
		(mid 140.914882 -255.260879)
		(end 141.197838 -255.337056)
		(width 0.0889)
		(layer "In2.Cu")
		(net "M_I_CPU1_SA_CA<6>")
	)
	(arc
		(start 139.691872 -255.337056)
		(mid 139.974828 -255.260879)
		(end 140.257784 -255.337056)
		(width 0.0889)
		(layer "In2.Cu")
		(net "M_I_CPU1_SA_CA<6>")
	)
	(arc
		(start 139.326112 -255.341882)
		(mid 139.50962 -255.387376)
		(end 139.691872 -255.337056)
		(width 0.0889)
		(layer "In2.Cu")
		(net "M_I_CPU1_SA_CA<6>")
	)
	(segment
		(start 128.69799 -255.280414)
		(end 129.164842 -255.014476)
		(width 0.10668)
		(layer "F.Cu")
		(net "M_I_CPU1_SA_CA<5>")
	)
	(segment
		(start 139.31773 -254.691896)
		(end 139.326112 -254.68707)
		(width 0.0889)
		(layer "In2.Cu")
		(net "M_I_CPU1_SA_CA<5>")
	)
	(segment
		(start 146.625564 -255.134364)
		(end 146.83105 -255.134364)
		(width 0.0889)
		(layer "In2.Cu")
		(net "M_I_CPU1_SA_CA<5>")
	)
	(segment
		(start 129.318766 -254.749046)
		(end 129.414778 -254.723646)
		(width 0.0889)
		(layer "In2.Cu")
		(net "M_I_CPU1_SA_CA<5>")
	)
	(segment
		(start 173.573186 -253.107952)
		(end 173.83506 -253.107952)
		(width 0.14478)
		(layer "In2.Cu")
		(net "M_I_CPU1_SA_CA<5>")
	)
	(segment
		(start 140.257784 -254.691896)
		(end 140.266166 -254.68707)
		(width 0.0889)
		(layer "In2.Cu")
		(net "M_I_CPU1_SA_CA<5>")
	)
	(segment
		(start 173.283626 -253.8603)
		(end 173.428406 -253.71552)
		(width 0.14478)
		(layer "In2.Cu")
		(net "M_I_CPU1_SA_CA<5>")
	)
	(segment
		(start 129.164842 -255.014476)
		(end 129.318766 -254.749046)
		(width 0.0889)
		(layer "In2.Cu")
		(net "M_I_CPU1_SA_CA<5>")
	)
	(segment
		(start 146.83105 -255.134364)
		(end 147.131532 -255.434846)
		(width 0.0889)
		(layer "In2.Cu")
		(net "M_I_CPU1_SA_CA<5>")
	)
	(segment
		(start 138.743436 -254.68707)
		(end 138.751818 -254.691896)
		(width 0.0889)
		(layer "In2.Cu")
		(net "M_I_CPU1_SA_CA<5>")
	)
	(segment
		(start 142.503398 -254.68707)
		(end 142.51178 -254.691896)
		(width 0.0889)
		(layer "In2.Cu")
		(net "M_I_CPU1_SA_CA<5>")
	)
	(segment
		(start 177.849784 -251.735336)
		(end 179.516024 -251.735336)
		(width 0.14478)
		(layer "In2.Cu")
		(net "M_I_CPU1_SA_CA<5>")
	)
	(segment
		(start 173.428406 -253.252732)
		(end 173.573186 -253.107952)
		(width 0.14478)
		(layer "In2.Cu")
		(net "M_I_CPU1_SA_CA<5>")
	)
	(segment
		(start 134.617714 -254.691896)
		(end 134.626096 -254.68707)
		(width 0.0889)
		(layer "In2.Cu")
		(net "M_I_CPU1_SA_CA<5>")
	)
	(segment
		(start 174.820834 -253.590552)
		(end 174.820834 -252.305058)
		(width 0.14478)
		(layer "In2.Cu")
		(net "M_I_CPU1_SA_CA<5>")
	)
	(segment
		(start 176.823878 -252.160278)
		(end 177.849784 -251.735336)
		(width 0.14478)
		(layer "In2.Cu")
		(net "M_I_CPU1_SA_CA<5>")
	)
	(segment
		(start 143.992092 -254.70612)
		(end 144.015968 -254.69215)
		(width 0.0889)
		(layer "In2.Cu")
		(net "M_I_CPU1_SA_CA<5>")
	)
	(segment
		(start 129.917698 -254.691896)
		(end 129.92608 -254.68707)
		(width 0.0889)
		(layer "In2.Cu")
		(net "M_I_CPU1_SA_CA<5>")
	)
	(segment
		(start 137.803382 -254.68707)
		(end 137.811764 -254.691896)
		(width 0.0889)
		(layer "In2.Cu")
		(net "M_I_CPU1_SA_CA<5>")
	)
	(segment
		(start 152.086564 -254.195326)
		(end 156.00045 -254.195326)
		(width 0.14478)
		(layer "In2.Cu")
		(net "M_I_CPU1_SA_CA<5>")
	)
	(segment
		(start 162.493706 -254.66675)
		(end 163.300156 -253.8603)
		(width 0.14478)
		(layer "In2.Cu")
		(net "M_I_CPU1_SA_CA<5>")
	)
	(segment
		(start 144.015968 -254.69215)
		(end 144.037812 -254.679704)
		(width 0.0889)
		(layer "In2.Cu")
		(net "M_I_CPU1_SA_CA<5>")
	)
	(segment
		(start 174.820834 -252.305058)
		(end 174.965614 -252.160278)
		(width 0.14478)
		(layer "In2.Cu")
		(net "M_I_CPU1_SA_CA<5>")
	)
	(segment
		(start 174.551086 -253.8603)
		(end 174.820834 -253.590552)
		(width 0.14478)
		(layer "In2.Cu")
		(net "M_I_CPU1_SA_CA<5>")
	)
	(segment
		(start 173.97984 -253.71552)
		(end 174.12462 -253.8603)
		(width 0.14478)
		(layer "In2.Cu")
		(net "M_I_CPU1_SA_CA<5>")
	)
	(segment
		(start 143.077692 -254.691896)
		(end 143.086074 -254.68707)
		(width 0.0889)
		(layer "In2.Cu")
		(net "M_I_CPU1_SA_CA<5>")
	)
	(segment
		(start 147.36445 -255.434846)
		(end 150.847044 -255.434846)
		(width 0.14478)
		(layer "In2.Cu")
		(net "M_I_CPU1_SA_CA<5>")
	)
	(segment
		(start 156.471874 -254.66675)
		(end 162.493706 -254.66675)
		(width 0.14478)
		(layer "In2.Cu")
		(net "M_I_CPU1_SA_CA<5>")
	)
	(segment
		(start 145.300446 -254.674878)
		(end 145.640552 -254.870966)
		(width 0.0889)
		(layer "In2.Cu")
		(net "M_I_CPU1_SA_CA<5>")
	)
	(segment
		(start 174.12462 -253.8603)
		(end 174.551086 -253.8603)
		(width 0.14478)
		(layer "In2.Cu")
		(net "M_I_CPU1_SA_CA<5>")
	)
	(segment
		(start 173.83506 -253.107952)
		(end 173.97984 -253.252732)
		(width 0.14478)
		(layer "In2.Cu")
		(net "M_I_CPU1_SA_CA<5>")
	)
	(segment
		(start 173.97984 -253.252732)
		(end 173.97984 -253.71552)
		(width 0.14478)
		(layer "In2.Cu")
		(net "M_I_CPU1_SA_CA<5>")
	)
	(segment
		(start 150.847044 -255.434846)
		(end 152.086564 -254.195326)
		(width 0.14478)
		(layer "In2.Cu")
		(net "M_I_CPU1_SA_CA<5>")
	)
	(segment
		(start 144.388586 -254.691896)
		(end 144.416272 -254.707898)
		(width 0.0889)
		(layer "In2.Cu")
		(net "M_I_CPU1_SA_CA<5>")
	)
	(segment
		(start 156.00045 -254.195326)
		(end 156.471874 -254.66675)
		(width 0.14478)
		(layer "In2.Cu")
		(net "M_I_CPU1_SA_CA<5>")
	)
	(segment
		(start 174.965614 -252.160278)
		(end 176.823878 -252.160278)
		(width 0.14478)
		(layer "In2.Cu")
		(net "M_I_CPU1_SA_CA<5>")
	)
	(segment
		(start 130.857752 -254.691896)
		(end 130.866134 -254.68707)
		(width 0.0889)
		(layer "In2.Cu")
		(net "M_I_CPU1_SA_CA<5>")
	)
	(segment
		(start 147.131532 -255.434846)
		(end 147.36445 -255.434846)
		(width 0.0889)
		(layer "In2.Cu")
		(net "M_I_CPU1_SA_CA<5>")
	)
	(segment
		(start 135.557768 -254.691896)
		(end 135.56615 -254.68707)
		(width 0.0889)
		(layer "In2.Cu")
		(net "M_I_CPU1_SA_CA<5>")
	)
	(segment
		(start 134.04342 -254.68707)
		(end 134.051802 -254.691896)
		(width 0.0889)
		(layer "In2.Cu")
		(net "M_I_CPU1_SA_CA<5>")
	)
	(segment
		(start 133.103366 -254.68707)
		(end 133.111748 -254.691896)
		(width 0.0889)
		(layer "In2.Cu")
		(net "M_I_CPU1_SA_CA<5>")
	)
	(segment
		(start 173.428406 -253.71552)
		(end 173.428406 -253.252732)
		(width 0.14478)
		(layer "In2.Cu")
		(net "M_I_CPU1_SA_CA<5>")
	)
	(segment
		(start 163.300156 -253.8603)
		(end 173.283626 -253.8603)
		(width 0.14478)
		(layer "In2.Cu")
		(net "M_I_CPU1_SA_CA<5>")
	)
	(arc
		(start 131.231894 -254.691896)
		(mid 131.51485 -254.768073)
		(end 131.797806 -254.691896)
		(width 0.0889)
		(layer "In2.Cu")
		(net "M_I_CPU1_SA_CA<5>")
	)
	(arc
		(start 133.67766 -254.691896)
		(mid 133.859911 -254.641546)
		(end 134.04342 -254.68707)
		(width 0.0889)
		(layer "In2.Cu")
		(net "M_I_CPU1_SA_CA<5>")
	)
	(arc
		(start 134.991856 -254.691896)
		(mid 135.274812 -254.768073)
		(end 135.557768 -254.691896)
		(width 0.0889)
		(layer "In2.Cu")
		(net "M_I_CPU1_SA_CA<5>")
	)
	(arc
		(start 142.51178 -254.691896)
		(mid 142.794736 -254.768073)
		(end 143.077692 -254.691896)
		(width 0.0889)
		(layer "In2.Cu")
		(net "M_I_CPU1_SA_CA<5>")
	)
	(arc
		(start 141.197838 -254.691896)
		(mid 141.384782 -254.641641)
		(end 141.571726 -254.691896)
		(width 0.0889)
		(layer "In2.Cu")
		(net "M_I_CPU1_SA_CA<5>")
	)
	(arc
		(start 144.956276 -254.691896)
		(mid 145.126283 -254.641331)
		(end 145.300446 -254.674878)
		(width 0.0889)
		(layer "In2.Cu")
		(net "M_I_CPU1_SA_CA<5>")
	)
	(arc
		(start 144.416272 -254.707898)
		(mid 144.688306 -254.76867)
		(end 144.956276 -254.691896)
		(width 0.0889)
		(layer "In2.Cu")
		(net "M_I_CPU1_SA_CA<5>")
	)
	(arc
		(start 138.751818 -254.691896)
		(mid 139.034774 -254.768073)
		(end 139.31773 -254.691896)
		(width 0.0889)
		(layer "In2.Cu")
		(net "M_I_CPU1_SA_CA<5>")
	)
	(arc
		(start 139.691872 -254.691896)
		(mid 139.974828 -254.768073)
		(end 140.257784 -254.691896)
		(width 0.0889)
		(layer "In2.Cu")
		(net "M_I_CPU1_SA_CA<5>")
	)
	(arc
		(start 141.571726 -254.691896)
		(mid 141.854682 -254.768073)
		(end 142.137638 -254.691896)
		(width 0.0889)
		(layer "In2.Cu")
		(net "M_I_CPU1_SA_CA<5>")
	)
	(arc
		(start 140.266166 -254.68707)
		(mid 140.449674 -254.641576)
		(end 140.631926 -254.691896)
		(width 0.0889)
		(layer "In2.Cu")
		(net "M_I_CPU1_SA_CA<5>")
	)
	(arc
		(start 137.437622 -254.691896)
		(mid 137.619873 -254.641546)
		(end 137.803382 -254.68707)
		(width 0.0889)
		(layer "In2.Cu")
		(net "M_I_CPU1_SA_CA<5>")
	)
	(arc
		(start 136.497822 -254.691896)
		(mid 136.684766 -254.641641)
		(end 136.87171 -254.691896)
		(width 0.0889)
		(layer "In2.Cu")
		(net "M_I_CPU1_SA_CA<5>")
	)
	(arc
		(start 135.93191 -254.691896)
		(mid 136.214866 -254.768073)
		(end 136.497822 -254.691896)
		(width 0.0889)
		(layer "In2.Cu")
		(net "M_I_CPU1_SA_CA<5>")
	)
	(arc
		(start 140.631926 -254.691896)
		(mid 140.914882 -254.768073)
		(end 141.197838 -254.691896)
		(width 0.0889)
		(layer "In2.Cu")
		(net "M_I_CPU1_SA_CA<5>")
	)
	(arc
		(start 129.92608 -254.68707)
		(mid 130.109588 -254.641576)
		(end 130.29184 -254.691896)
		(width 0.0889)
		(layer "In2.Cu")
		(net "M_I_CPU1_SA_CA<5>")
	)
	(arc
		(start 132.737606 -254.691896)
		(mid 132.919857 -254.641546)
		(end 133.103366 -254.68707)
		(width 0.0889)
		(layer "In2.Cu")
		(net "M_I_CPU1_SA_CA<5>")
	)
	(arc
		(start 144.037812 -254.679704)
		(mid 144.21474 -254.641876)
		(end 144.388586 -254.691896)
		(width 0.0889)
		(layer "In2.Cu")
		(net "M_I_CPU1_SA_CA<5>")
	)
	(arc
		(start 136.87171 -254.691896)
		(mid 137.154666 -254.768073)
		(end 137.437622 -254.691896)
		(width 0.0889)
		(layer "In2.Cu")
		(net "M_I_CPU1_SA_CA<5>")
	)
	(arc
		(start 131.797806 -254.691896)
		(mid 131.98475 -254.641641)
		(end 132.171694 -254.691896)
		(width 0.0889)
		(layer "In2.Cu")
		(net "M_I_CPU1_SA_CA<5>")
	)
	(arc
		(start 129.414778 -254.723646)
		(mid 129.669986 -254.767123)
		(end 129.917698 -254.691896)
		(width 0.0889)
		(layer "In2.Cu")
		(net "M_I_CPU1_SA_CA<5>")
	)
	(arc
		(start 139.326112 -254.68707)
		(mid 139.50962 -254.641576)
		(end 139.691872 -254.691896)
		(width 0.0889)
		(layer "In2.Cu")
		(net "M_I_CPU1_SA_CA<5>")
	)
	(arc
		(start 145.640552 -254.870966)
		(mid 146.11575 -255.067383)
		(end 146.625564 -255.134364)
		(width 0.0889)
		(layer "In2.Cu")
		(net "M_I_CPU1_SA_CA<5>")
	)
	(arc
		(start 143.451834 -254.691896)
		(mid 143.720154 -254.768004)
		(end 143.992092 -254.70612)
		(width 0.0889)
		(layer "In2.Cu")
		(net "M_I_CPU1_SA_CA<5>")
	)
	(arc
		(start 134.051802 -254.691896)
		(mid 134.334758 -254.768073)
		(end 134.617714 -254.691896)
		(width 0.0889)
		(layer "In2.Cu")
		(net "M_I_CPU1_SA_CA<5>")
	)
	(arc
		(start 130.866134 -254.68707)
		(mid 131.049642 -254.641576)
		(end 131.231894 -254.691896)
		(width 0.0889)
		(layer "In2.Cu")
		(net "M_I_CPU1_SA_CA<5>")
	)
	(arc
		(start 134.626096 -254.68707)
		(mid 134.809604 -254.641576)
		(end 134.991856 -254.691896)
		(width 0.0889)
		(layer "In2.Cu")
		(net "M_I_CPU1_SA_CA<5>")
	)
	(arc
		(start 133.111748 -254.691896)
		(mid 133.394704 -254.768073)
		(end 133.67766 -254.691896)
		(width 0.0889)
		(layer "In2.Cu")
		(net "M_I_CPU1_SA_CA<5>")
	)
	(arc
		(start 143.086074 -254.68707)
		(mid 143.269582 -254.641576)
		(end 143.451834 -254.691896)
		(width 0.0889)
		(layer "In2.Cu")
		(net "M_I_CPU1_SA_CA<5>")
	)
	(arc
		(start 137.811764 -254.691896)
		(mid 138.09472 -254.768073)
		(end 138.377676 -254.691896)
		(width 0.0889)
		(layer "In2.Cu")
		(net "M_I_CPU1_SA_CA<5>")
	)
	(arc
		(start 142.137638 -254.691896)
		(mid 142.319889 -254.641546)
		(end 142.503398 -254.68707)
		(width 0.0889)
		(layer "In2.Cu")
		(net "M_I_CPU1_SA_CA<5>")
	)
	(arc
		(start 135.56615 -254.68707)
		(mid 135.749658 -254.641576)
		(end 135.93191 -254.691896)
		(width 0.0889)
		(layer "In2.Cu")
		(net "M_I_CPU1_SA_CA<5>")
	)
	(arc
		(start 138.377676 -254.691896)
		(mid 138.559927 -254.641546)
		(end 138.743436 -254.68707)
		(width 0.0889)
		(layer "In2.Cu")
		(net "M_I_CPU1_SA_CA<5>")
	)
	(arc
		(start 130.29184 -254.691896)
		(mid 130.574796 -254.768073)
		(end 130.857752 -254.691896)
		(width 0.0889)
		(layer "In2.Cu")
		(net "M_I_CPU1_SA_CA<5>")
	)
	(arc
		(start 132.171694 -254.691896)
		(mid 132.45465 -254.768073)
		(end 132.737606 -254.691896)
		(width 0.0889)
		(layer "In2.Cu")
		(net "M_I_CPU1_SA_CA<5>")
	)
	(segment
		(start 129.16789 -254.470408)
		(end 129.634742 -254.20447)
		(width 0.10668)
		(layer "F.Cu")
		(net "M_I_CPU1_SA_CA<4>")
	)
	(segment
		(start 162.9156 -253.010416)
		(end 172.717714 -253.010416)
		(width 0.14478)
		(layer "In2.Cu")
		(net "M_I_CPU1_SA_CA<4>")
	)
	(segment
		(start 144.484598 -254.52705)
		(end 144.505172 -254.538988)
		(width 0.0889)
		(layer "In2.Cu")
		(net "M_I_CPU1_SA_CA<4>")
	)
	(segment
		(start 130.753358 -254.531876)
		(end 130.76174 -254.52705)
		(width 0.0889)
		(layer "In2.Cu")
		(net "M_I_CPU1_SA_CA<4>")
	)
	(segment
		(start 174.417736 -251.310394)
		(end 177.341022 -251.310394)
		(width 0.14478)
		(layer "In2.Cu")
		(net "M_I_CPU1_SA_CA<4>")
	)
	(segment
		(start 141.093444 -254.531876)
		(end 141.101826 -254.52705)
		(width 0.0889)
		(layer "In2.Cu")
		(net "M_I_CPU1_SA_CA<4>")
	)
	(segment
		(start 179.098702 -251.072904)
		(end 179.279042 -251.253244)
		(width 0.14478)
		(layer "In2.Cu")
		(net "M_I_CPU1_SA_CA<4>")
	)
	(segment
		(start 143.897096 -254.540258)
		(end 143.920464 -254.526796)
		(width 0.0889)
		(layer "In2.Cu")
		(net "M_I_CPU1_SA_CA<4>")
	)
	(segment
		(start 136.967722 -254.52705)
		(end 136.976104 -254.531876)
		(width 0.0889)
		(layer "In2.Cu")
		(net "M_I_CPU1_SA_CA<4>")
	)
	(segment
		(start 137.907776 -254.52705)
		(end 137.916158 -254.531876)
		(width 0.0889)
		(layer "In2.Cu")
		(net "M_I_CPU1_SA_CA<4>")
	)
	(segment
		(start 151.900128 -253.745746)
		(end 156.186886 -253.745746)
		(width 0.14478)
		(layer "In2.Cu")
		(net "M_I_CPU1_SA_CA<4>")
	)
	(segment
		(start 141.667738 -254.52705)
		(end 141.67612 -254.531876)
		(width 0.0889)
		(layer "In2.Cu")
		(net "M_I_CPU1_SA_CA<4>")
	)
	(segment
		(start 177.341022 -251.310394)
		(end 177.578512 -251.072904)
		(width 0.14478)
		(layer "In2.Cu")
		(net "M_I_CPU1_SA_CA<4>")
	)
	(segment
		(start 177.578512 -251.072904)
		(end 179.098702 -251.072904)
		(width 0.14478)
		(layer "In2.Cu")
		(net "M_I_CPU1_SA_CA<4>")
	)
	(segment
		(start 129.480818 -254.4699)
		(end 129.50317 -254.553212)
		(width 0.0889)
		(layer "In2.Cu")
		(net "M_I_CPU1_SA_CA<4>")
	)
	(segment
		(start 150.686008 -254.959866)
		(end 151.900128 -253.745746)
		(width 0.14478)
		(layer "In2.Cu")
		(net "M_I_CPU1_SA_CA<4>")
	)
	(segment
		(start 129.634742 -254.20447)
		(end 129.480818 -254.4699)
		(width 0.0889)
		(layer "In2.Cu")
		(net "M_I_CPU1_SA_CA<4>")
	)
	(segment
		(start 145.387822 -254.504952)
		(end 145.425668 -254.526796)
		(width 0.0889)
		(layer "In2.Cu")
		(net "M_I_CPU1_SA_CA<4>")
	)
	(segment
		(start 147.54733 -254.959866)
		(end 150.686008 -254.959866)
		(width 0.14478)
		(layer "In2.Cu")
		(net "M_I_CPU1_SA_CA<4>")
	)
	(segment
		(start 133.20776 -254.52705)
		(end 133.216142 -254.531876)
		(width 0.0889)
		(layer "In2.Cu")
		(net "M_I_CPU1_SA_CA<4>")
	)
	(segment
		(start 179.285646 -251.253244)
		(end 179.342796 -251.310394)
		(width 0.0889)
		(layer "In2.Cu")
		(net "M_I_CPU1_SA_CA<4>")
	)
	(segment
		(start 140.15339 -254.531876)
		(end 140.161772 -254.52705)
		(width 0.0889)
		(layer "In2.Cu")
		(net "M_I_CPU1_SA_CA<4>")
	)
	(segment
		(start 183.190896 -251.310394)
		(end 183.616092 -250.885198)
		(width 0.14478)
		(layer "In2.Cu")
		(net "M_I_CPU1_SA_CA<4>")
	)
	(segment
		(start 147.37461 -254.959866)
		(end 147.54733 -254.959866)
		(width 0.0889)
		(layer "In2.Cu")
		(net "M_I_CPU1_SA_CA<4>")
	)
	(segment
		(start 135.453374 -254.531876)
		(end 135.461756 -254.52705)
		(width 0.0889)
		(layer "In2.Cu")
		(net "M_I_CPU1_SA_CA<4>")
	)
	(segment
		(start 132.267706 -254.52705)
		(end 132.276088 -254.531876)
		(width 0.0889)
		(layer "In2.Cu")
		(net "M_I_CPU1_SA_CA<4>")
	)
	(segment
		(start 179.342796 -251.310394)
		(end 179.701444 -251.310394)
		(width 0.0889)
		(layer "In2.Cu")
		(net "M_I_CPU1_SA_CA<4>")
	)
	(segment
		(start 131.693412 -254.531876)
		(end 131.701794 -254.52705)
		(width 0.0889)
		(layer "In2.Cu")
		(net "M_I_CPU1_SA_CA<4>")
	)
	(segment
		(start 143.920464 -254.526796)
		(end 143.94434 -254.512826)
		(width 0.0889)
		(layer "In2.Cu")
		(net "M_I_CPU1_SA_CA<4>")
	)
	(segment
		(start 146.581876 -254.837184)
		(end 147.251928 -254.837184)
		(width 0.0889)
		(layer "In2.Cu")
		(net "M_I_CPU1_SA_CA<4>")
	)
	(segment
		(start 172.717714 -253.010416)
		(end 174.417736 -251.310394)
		(width 0.14478)
		(layer "In2.Cu")
		(net "M_I_CPU1_SA_CA<4>")
	)
	(segment
		(start 147.251928 -254.837184)
		(end 147.37461 -254.959866)
		(width 0.0889)
		(layer "In2.Cu")
		(net "M_I_CPU1_SA_CA<4>")
	)
	(segment
		(start 156.186886 -253.745746)
		(end 156.65831 -254.21717)
		(width 0.14478)
		(layer "In2.Cu")
		(net "M_I_CPU1_SA_CA<4>")
	)
	(segment
		(start 161.708846 -254.21717)
		(end 162.9156 -253.010416)
		(width 0.14478)
		(layer "In2.Cu")
		(net "M_I_CPU1_SA_CA<4>")
	)
	(segment
		(start 156.65831 -254.21717)
		(end 161.708846 -254.21717)
		(width 0.14478)
		(layer "In2.Cu")
		(net "M_I_CPU1_SA_CA<4>")
	)
	(segment
		(start 136.393428 -254.531876)
		(end 136.40181 -254.52705)
		(width 0.0889)
		(layer "In2.Cu")
		(net "M_I_CPU1_SA_CA<4>")
	)
	(segment
		(start 179.279042 -251.253244)
		(end 179.285646 -251.253244)
		(width 0.0889)
		(layer "In2.Cu")
		(net "M_I_CPU1_SA_CA<4>")
	)
	(segment
		(start 179.701444 -251.310394)
		(end 183.190896 -251.310394)
		(width 0.14478)
		(layer "In2.Cu")
		(net "M_I_CPU1_SA_CA<4>")
	)
	(arc
		(start 141.101826 -254.52705)
		(mid 141.384782 -254.450873)
		(end 141.667738 -254.52705)
		(width 0.0889)
		(layer "In2.Cu")
		(net "M_I_CPU1_SA_CA<4>")
	)
	(arc
		(start 138.281918 -254.52705)
		(mid 138.564874 -254.450873)
		(end 138.84783 -254.52705)
		(width 0.0889)
		(layer "In2.Cu")
		(net "M_I_CPU1_SA_CA<4>")
	)
	(arc
		(start 135.087614 -254.52705)
		(mid 135.269865 -254.5774)
		(end 135.453374 -254.531876)
		(width 0.0889)
		(layer "In2.Cu")
		(net "M_I_CPU1_SA_CA<4>")
	)
	(arc
		(start 140.727684 -254.52705)
		(mid 140.909935 -254.5774)
		(end 141.093444 -254.531876)
		(width 0.0889)
		(layer "In2.Cu")
		(net "M_I_CPU1_SA_CA<4>")
	)
	(arc
		(start 137.916158 -254.531876)
		(mid 138.099666 -254.57737)
		(end 138.281918 -254.52705)
		(width 0.0889)
		(layer "In2.Cu")
		(net "M_I_CPU1_SA_CA<4>")
	)
	(arc
		(start 132.641848 -254.52705)
		(mid 132.924804 -254.450873)
		(end 133.20776 -254.52705)
		(width 0.0889)
		(layer "In2.Cu")
		(net "M_I_CPU1_SA_CA<4>")
	)
	(arc
		(start 131.327652 -254.52705)
		(mid 131.509903 -254.5774)
		(end 131.693412 -254.531876)
		(width 0.0889)
		(layer "In2.Cu")
		(net "M_I_CPU1_SA_CA<4>")
	)
	(arc
		(start 135.461756 -254.52705)
		(mid 135.744712 -254.450873)
		(end 136.027668 -254.52705)
		(width 0.0889)
		(layer "In2.Cu")
		(net "M_I_CPU1_SA_CA<4>")
	)
	(arc
		(start 140.161772 -254.52705)
		(mid 140.444728 -254.450873)
		(end 140.727684 -254.52705)
		(width 0.0889)
		(layer "In2.Cu")
		(net "M_I_CPU1_SA_CA<4>")
	)
	(arc
		(start 141.67612 -254.531876)
		(mid 141.859628 -254.57737)
		(end 142.04188 -254.52705)
		(width 0.0889)
		(layer "In2.Cu")
		(net "M_I_CPU1_SA_CA<4>")
	)
	(arc
		(start 145.425668 -254.526796)
		(mid 145.983302 -254.758242)
		(end 146.581876 -254.837184)
		(width 0.0889)
		(layer "In2.Cu")
		(net "M_I_CPU1_SA_CA<4>")
	)
	(arc
		(start 138.84783 -254.52705)
		(mid 139.034774 -254.577305)
		(end 139.221718 -254.52705)
		(width 0.0889)
		(layer "In2.Cu")
		(net "M_I_CPU1_SA_CA<4>")
	)
	(arc
		(start 134.147814 -254.52705)
		(mid 134.334758 -254.577305)
		(end 134.521702 -254.52705)
		(width 0.0889)
		(layer "In2.Cu")
		(net "M_I_CPU1_SA_CA<4>")
	)
	(arc
		(start 129.821686 -254.52705)
		(mid 130.104642 -254.450873)
		(end 130.387598 -254.52705)
		(width 0.0889)
		(layer "In2.Cu")
		(net "M_I_CPU1_SA_CA<4>")
	)
	(arc
		(start 136.976104 -254.531876)
		(mid 137.159612 -254.57737)
		(end 137.341864 -254.52705)
		(width 0.0889)
		(layer "In2.Cu")
		(net "M_I_CPU1_SA_CA<4>")
	)
	(arc
		(start 130.76174 -254.52705)
		(mid 131.044696 -254.450873)
		(end 131.327652 -254.52705)
		(width 0.0889)
		(layer "In2.Cu")
		(net "M_I_CPU1_SA_CA<4>")
	)
	(arc
		(start 139.221718 -254.52705)
		(mid 139.504674 -254.450873)
		(end 139.78763 -254.52705)
		(width 0.0889)
		(layer "In2.Cu")
		(net "M_I_CPU1_SA_CA<4>")
	)
	(arc
		(start 130.387598 -254.52705)
		(mid 130.569849 -254.5774)
		(end 130.753358 -254.531876)
		(width 0.0889)
		(layer "In2.Cu")
		(net "M_I_CPU1_SA_CA<4>")
	)
	(arc
		(start 144.86001 -254.52705)
		(mid 145.121168 -254.450471)
		(end 145.387822 -254.504952)
		(width 0.0889)
		(layer "In2.Cu")
		(net "M_I_CPU1_SA_CA<4>")
	)
	(arc
		(start 133.216142 -254.531876)
		(mid 133.39965 -254.57737)
		(end 133.581902 -254.52705)
		(width 0.0889)
		(layer "In2.Cu")
		(net "M_I_CPU1_SA_CA<4>")
	)
	(arc
		(start 132.276088 -254.531876)
		(mid 132.459596 -254.57737)
		(end 132.641848 -254.52705)
		(width 0.0889)
		(layer "In2.Cu")
		(net "M_I_CPU1_SA_CA<4>")
	)
	(arc
		(start 129.50317 -254.553212)
		(mid 129.665359 -254.575947)
		(end 129.821686 -254.52705)
		(width 0.0889)
		(layer "In2.Cu")
		(net "M_I_CPU1_SA_CA<4>")
	)
	(arc
		(start 134.521702 -254.52705)
		(mid 134.804658 -254.450873)
		(end 135.087614 -254.52705)
		(width 0.0889)
		(layer "In2.Cu")
		(net "M_I_CPU1_SA_CA<4>")
	)
	(arc
		(start 142.04188 -254.52705)
		(mid 142.324836 -254.450873)
		(end 142.607792 -254.52705)
		(width 0.0889)
		(layer "In2.Cu")
		(net "M_I_CPU1_SA_CA<4>")
	)
	(arc
		(start 143.94434 -254.512826)
		(mid 144.216277 -254.451)
		(end 144.484598 -254.52705)
		(width 0.0889)
		(layer "In2.Cu")
		(net "M_I_CPU1_SA_CA<4>")
	)
	(arc
		(start 144.505172 -254.538988)
		(mid 144.6841 -254.577865)
		(end 144.86001 -254.52705)
		(width 0.0889)
		(layer "In2.Cu")
		(net "M_I_CPU1_SA_CA<4>")
	)
	(arc
		(start 137.341864 -254.52705)
		(mid 137.62482 -254.450873)
		(end 137.907776 -254.52705)
		(width 0.0889)
		(layer "In2.Cu")
		(net "M_I_CPU1_SA_CA<4>")
	)
	(arc
		(start 139.78763 -254.52705)
		(mid 139.969881 -254.5774)
		(end 140.15339 -254.531876)
		(width 0.0889)
		(layer "In2.Cu")
		(net "M_I_CPU1_SA_CA<4>")
	)
	(arc
		(start 142.607792 -254.52705)
		(mid 142.794736 -254.577305)
		(end 142.98168 -254.52705)
		(width 0.0889)
		(layer "In2.Cu")
		(net "M_I_CPU1_SA_CA<4>")
	)
	(arc
		(start 131.701794 -254.52705)
		(mid 131.98475 -254.450873)
		(end 132.267706 -254.52705)
		(width 0.0889)
		(layer "In2.Cu")
		(net "M_I_CPU1_SA_CA<4>")
	)
	(arc
		(start 133.581902 -254.52705)
		(mid 133.864858 -254.450873)
		(end 134.147814 -254.52705)
		(width 0.0889)
		(layer "In2.Cu")
		(net "M_I_CPU1_SA_CA<4>")
	)
	(arc
		(start 142.98168 -254.52705)
		(mid 143.264636 -254.450873)
		(end 143.547592 -254.52705)
		(width 0.0889)
		(layer "In2.Cu")
		(net "M_I_CPU1_SA_CA<4>")
	)
	(arc
		(start 136.027668 -254.52705)
		(mid 136.209919 -254.5774)
		(end 136.393428 -254.531876)
		(width 0.0889)
		(layer "In2.Cu")
		(net "M_I_CPU1_SA_CA<4>")
	)
	(arc
		(start 136.40181 -254.52705)
		(mid 136.684766 -254.450873)
		(end 136.967722 -254.52705)
		(width 0.0889)
		(layer "In2.Cu")
		(net "M_I_CPU1_SA_CA<4>")
	)
	(arc
		(start 143.547592 -254.52705)
		(mid 143.7207 -254.577166)
		(end 143.897096 -254.540258)
		(width 0.0889)
		(layer "In2.Cu")
		(net "M_I_CPU1_SA_CA<4>")
	)
	(segment
		(start 127.287782 -254.470408)
		(end 127.754634 -254.20447)
		(width 0.10668)
		(layer "F.Cu")
		(net "M_I_CPU1_SA_CA<3>")
	)
	(segment
		(start 172.721524 -252.160278)
		(end 174.421546 -250.460256)
		(width 0.14478)
		(layer "In2.Cu")
		(net "M_I_CPU1_SA_CA<3>")
	)
	(segment
		(start 140.15339 -253.877064)
		(end 140.161772 -253.88189)
		(width 0.0889)
		(layer "In2.Cu")
		(net "M_I_CPU1_SA_CA<3>")
	)
	(segment
		(start 147.34413 -254.482346)
		(end 147.65655 -254.482346)
		(width 0.0889)
		(layer "In2.Cu")
		(net "M_I_CPU1_SA_CA<3>")
	)
	(segment
		(start 146.964908 -254.103124)
		(end 147.34413 -254.482346)
		(width 0.0889)
		(layer "In2.Cu")
		(net "M_I_CPU1_SA_CA<3>")
	)
	(segment
		(start 162.932618 -252.160278)
		(end 172.721524 -252.160278)
		(width 0.14478)
		(layer "In2.Cu")
		(net "M_I_CPU1_SA_CA<3>")
	)
	(segment
		(start 141.667738 -253.88189)
		(end 141.67612 -253.877064)
		(width 0.0889)
		(layer "In2.Cu")
		(net "M_I_CPU1_SA_CA<3>")
	)
	(segment
		(start 127.908812 -253.93904)
		(end 128.005078 -253.91364)
		(width 0.0889)
		(layer "In2.Cu")
		(net "M_I_CPU1_SA_CA<3>")
	)
	(segment
		(start 174.421546 -250.460256)
		(end 179.091082 -250.460256)
		(width 0.14478)
		(layer "In2.Cu")
		(net "M_I_CPU1_SA_CA<3>")
	)
	(segment
		(start 137.907776 -253.88189)
		(end 137.916158 -253.877064)
		(width 0.0889)
		(layer "In2.Cu")
		(net "M_I_CPU1_SA_CA<3>")
	)
	(segment
		(start 132.267706 -253.88189)
		(end 132.276088 -253.877064)
		(width 0.0889)
		(layer "In2.Cu")
		(net "M_I_CPU1_SA_CA<3>")
	)
	(segment
		(start 127.754634 -254.20447)
		(end 127.908812 -253.93904)
		(width 0.0889)
		(layer "In2.Cu")
		(net "M_I_CPU1_SA_CA<3>")
	)
	(segment
		(start 131.693412 -253.877064)
		(end 131.701794 -253.88189)
		(width 0.0889)
		(layer "In2.Cu")
		(net "M_I_CPU1_SA_CA<3>")
	)
	(segment
		(start 136.967722 -253.88189)
		(end 136.976104 -253.877064)
		(width 0.0889)
		(layer "In2.Cu")
		(net "M_I_CPU1_SA_CA<3>")
	)
	(segment
		(start 156.373322 -253.296166)
		(end 156.844746 -253.76759)
		(width 0.14478)
		(layer "In2.Cu")
		(net "M_I_CPU1_SA_CA<3>")
	)
	(segment
		(start 147.65655 -254.482346)
		(end 150.527512 -254.482346)
		(width 0.14478)
		(layer "In2.Cu")
		(net "M_I_CPU1_SA_CA<3>")
	)
	(segment
		(start 179.091082 -250.460256)
		(end 179.516024 -250.035314)
		(width 0.14478)
		(layer "In2.Cu")
		(net "M_I_CPU1_SA_CA<3>")
	)
	(segment
		(start 136.393428 -253.877064)
		(end 136.40181 -253.88189)
		(width 0.0889)
		(layer "In2.Cu")
		(net "M_I_CPU1_SA_CA<3>")
	)
	(segment
		(start 156.844746 -253.76759)
		(end 161.325306 -253.76759)
		(width 0.14478)
		(layer "In2.Cu")
		(net "M_I_CPU1_SA_CA<3>")
	)
	(segment
		(start 150.527512 -254.482346)
		(end 151.713692 -253.296166)
		(width 0.14478)
		(layer "In2.Cu")
		(net "M_I_CPU1_SA_CA<3>")
	)
	(segment
		(start 151.713692 -253.296166)
		(end 156.373322 -253.296166)
		(width 0.14478)
		(layer "In2.Cu")
		(net "M_I_CPU1_SA_CA<3>")
	)
	(segment
		(start 130.753358 -253.877064)
		(end 130.76174 -253.88189)
		(width 0.0889)
		(layer "In2.Cu")
		(net "M_I_CPU1_SA_CA<3>")
	)
	(segment
		(start 133.20776 -253.88189)
		(end 133.216142 -253.877064)
		(width 0.0889)
		(layer "In2.Cu")
		(net "M_I_CPU1_SA_CA<3>")
	)
	(segment
		(start 135.453374 -253.877064)
		(end 135.461756 -253.88189)
		(width 0.0889)
		(layer "In2.Cu")
		(net "M_I_CPU1_SA_CA<3>")
	)
	(segment
		(start 146.623786 -254.103124)
		(end 146.964908 -254.103124)
		(width 0.0889)
		(layer "In2.Cu")
		(net "M_I_CPU1_SA_CA<3>")
	)
	(segment
		(start 128.507744 -253.88189)
		(end 128.516126 -253.877064)
		(width 0.0889)
		(layer "In2.Cu")
		(net "M_I_CPU1_SA_CA<3>")
	)
	(segment
		(start 161.325306 -253.76759)
		(end 162.932618 -252.160278)
		(width 0.14478)
		(layer "In2.Cu")
		(net "M_I_CPU1_SA_CA<3>")
	)
	(segment
		(start 141.093444 -253.877064)
		(end 141.101826 -253.88189)
		(width 0.0889)
		(layer "In2.Cu")
		(net "M_I_CPU1_SA_CA<3>")
	)
	(arc
		(start 137.916158 -253.877064)
		(mid 138.099666 -253.83157)
		(end 138.281918 -253.88189)
		(width 0.0889)
		(layer "In2.Cu")
		(net "M_I_CPU1_SA_CA<3>")
	)
	(arc
		(start 133.581902 -253.88189)
		(mid 133.864858 -253.958067)
		(end 134.147814 -253.88189)
		(width 0.0889)
		(layer "In2.Cu")
		(net "M_I_CPU1_SA_CA<3>")
	)
	(arc
		(start 135.461756 -253.88189)
		(mid 135.744712 -253.958067)
		(end 136.027668 -253.88189)
		(width 0.0889)
		(layer "In2.Cu")
		(net "M_I_CPU1_SA_CA<3>")
	)
	(arc
		(start 133.216142 -253.877064)
		(mid 133.39965 -253.83157)
		(end 133.581902 -253.88189)
		(width 0.0889)
		(layer "In2.Cu")
		(net "M_I_CPU1_SA_CA<3>")
	)
	(arc
		(start 136.40181 -253.88189)
		(mid 136.684766 -253.958067)
		(end 136.967722 -253.88189)
		(width 0.0889)
		(layer "In2.Cu")
		(net "M_I_CPU1_SA_CA<3>")
	)
	(arc
		(start 128.005078 -253.91364)
		(mid 128.260143 -253.956991)
		(end 128.507744 -253.88189)
		(width 0.0889)
		(layer "In2.Cu")
		(net "M_I_CPU1_SA_CA<3>")
	)
	(arc
		(start 140.161772 -253.88189)
		(mid 140.444728 -253.958067)
		(end 140.727684 -253.88189)
		(width 0.0889)
		(layer "In2.Cu")
		(net "M_I_CPU1_SA_CA<3>")
	)
	(arc
		(start 129.447798 -253.88189)
		(mid 129.634742 -253.831635)
		(end 129.821686 -253.88189)
		(width 0.0889)
		(layer "In2.Cu")
		(net "M_I_CPU1_SA_CA<3>")
	)
	(arc
		(start 130.76174 -253.88189)
		(mid 131.044696 -253.958067)
		(end 131.327652 -253.88189)
		(width 0.0889)
		(layer "In2.Cu")
		(net "M_I_CPU1_SA_CA<3>")
	)
	(arc
		(start 140.727684 -253.88189)
		(mid 140.909935 -253.83154)
		(end 141.093444 -253.877064)
		(width 0.0889)
		(layer "In2.Cu")
		(net "M_I_CPU1_SA_CA<3>")
	)
	(arc
		(start 131.701794 -253.88189)
		(mid 131.98475 -253.958067)
		(end 132.267706 -253.88189)
		(width 0.0889)
		(layer "In2.Cu")
		(net "M_I_CPU1_SA_CA<3>")
	)
	(arc
		(start 128.516126 -253.877064)
		(mid 128.699634 -253.83157)
		(end 128.881886 -253.88189)
		(width 0.0889)
		(layer "In2.Cu")
		(net "M_I_CPU1_SA_CA<3>")
	)
	(arc
		(start 145.4277 -253.88189)
		(mid 145.614898 -253.831508)
		(end 145.802096 -253.88189)
		(width 0.0889)
		(layer "In2.Cu")
		(net "M_I_CPU1_SA_CA<3>")
	)
	(arc
		(start 142.98168 -253.88189)
		(mid 143.264636 -253.958067)
		(end 143.547592 -253.88189)
		(width 0.0889)
		(layer "In2.Cu")
		(net "M_I_CPU1_SA_CA<3>")
	)
	(arc
		(start 134.521702 -253.88189)
		(mid 134.804658 -253.958067)
		(end 135.087614 -253.88189)
		(width 0.0889)
		(layer "In2.Cu")
		(net "M_I_CPU1_SA_CA<3>")
	)
	(arc
		(start 130.387598 -253.88189)
		(mid 130.569849 -253.83154)
		(end 130.753358 -253.877064)
		(width 0.0889)
		(layer "In2.Cu")
		(net "M_I_CPU1_SA_CA<3>")
	)
	(arc
		(start 141.67612 -253.877064)
		(mid 141.859628 -253.83157)
		(end 142.04188 -253.88189)
		(width 0.0889)
		(layer "In2.Cu")
		(net "M_I_CPU1_SA_CA<3>")
	)
	(arc
		(start 142.607792 -253.88189)
		(mid 142.794736 -253.831635)
		(end 142.98168 -253.88189)
		(width 0.0889)
		(layer "In2.Cu")
		(net "M_I_CPU1_SA_CA<3>")
	)
	(arc
		(start 144.861788 -253.88189)
		(mid 145.144744 -253.958067)
		(end 145.4277 -253.88189)
		(width 0.0889)
		(layer "In2.Cu")
		(net "M_I_CPU1_SA_CA<3>")
	)
	(arc
		(start 144.4879 -253.88189)
		(mid 144.674844 -253.831635)
		(end 144.861788 -253.88189)
		(width 0.0889)
		(layer "In2.Cu")
		(net "M_I_CPU1_SA_CA<3>")
	)
	(arc
		(start 139.78763 -253.88189)
		(mid 139.969881 -253.83154)
		(end 140.15339 -253.877064)
		(width 0.0889)
		(layer "In2.Cu")
		(net "M_I_CPU1_SA_CA<3>")
	)
	(arc
		(start 128.881886 -253.88189)
		(mid 129.164842 -253.958067)
		(end 129.447798 -253.88189)
		(width 0.0889)
		(layer "In2.Cu")
		(net "M_I_CPU1_SA_CA<3>")
	)
	(arc
		(start 143.921988 -253.88189)
		(mid 144.204944 -253.958067)
		(end 144.4879 -253.88189)
		(width 0.0889)
		(layer "In2.Cu")
		(net "M_I_CPU1_SA_CA<3>")
	)
	(arc
		(start 132.276088 -253.877064)
		(mid 132.459596 -253.83157)
		(end 132.641848 -253.88189)
		(width 0.0889)
		(layer "In2.Cu")
		(net "M_I_CPU1_SA_CA<3>")
	)
	(arc
		(start 139.221718 -253.88189)
		(mid 139.504674 -253.958067)
		(end 139.78763 -253.88189)
		(width 0.0889)
		(layer "In2.Cu")
		(net "M_I_CPU1_SA_CA<3>")
	)
	(arc
		(start 141.101826 -253.88189)
		(mid 141.384782 -253.958067)
		(end 141.667738 -253.88189)
		(width 0.0889)
		(layer "In2.Cu")
		(net "M_I_CPU1_SA_CA<3>")
	)
	(arc
		(start 136.027668 -253.88189)
		(mid 136.209919 -253.83154)
		(end 136.393428 -253.877064)
		(width 0.0889)
		(layer "In2.Cu")
		(net "M_I_CPU1_SA_CA<3>")
	)
	(arc
		(start 134.147814 -253.88189)
		(mid 134.334758 -253.831635)
		(end 134.521702 -253.88189)
		(width 0.0889)
		(layer "In2.Cu")
		(net "M_I_CPU1_SA_CA<3>")
	)
	(arc
		(start 135.087614 -253.88189)
		(mid 135.269865 -253.83154)
		(end 135.453374 -253.877064)
		(width 0.0889)
		(layer "In2.Cu")
		(net "M_I_CPU1_SA_CA<3>")
	)
	(arc
		(start 143.547592 -253.88189)
		(mid 143.73479 -253.831508)
		(end 143.921988 -253.88189)
		(width 0.0889)
		(layer "In2.Cu")
		(net "M_I_CPU1_SA_CA<3>")
	)
	(arc
		(start 138.281918 -253.88189)
		(mid 138.564874 -253.958067)
		(end 138.84783 -253.88189)
		(width 0.0889)
		(layer "In2.Cu")
		(net "M_I_CPU1_SA_CA<3>")
	)
	(arc
		(start 132.641848 -253.88189)
		(mid 132.924804 -253.958067)
		(end 133.20776 -253.88189)
		(width 0.0889)
		(layer "In2.Cu")
		(net "M_I_CPU1_SA_CA<3>")
	)
	(arc
		(start 138.84783 -253.88189)
		(mid 139.034774 -253.831635)
		(end 139.221718 -253.88189)
		(width 0.0889)
		(layer "In2.Cu")
		(net "M_I_CPU1_SA_CA<3>")
	)
	(arc
		(start 145.802096 -253.88189)
		(mid 146.19831 -254.04685)
		(end 146.623786 -254.103124)
		(width 0.0889)
		(layer "In2.Cu")
		(net "M_I_CPU1_SA_CA<3>")
	)
	(arc
		(start 142.04188 -253.88189)
		(mid 142.324836 -253.958067)
		(end 142.607792 -253.88189)
		(width 0.0889)
		(layer "In2.Cu")
		(net "M_I_CPU1_SA_CA<3>")
	)
	(arc
		(start 136.976104 -253.877064)
		(mid 137.159612 -253.83157)
		(end 137.341864 -253.88189)
		(width 0.0889)
		(layer "In2.Cu")
		(net "M_I_CPU1_SA_CA<3>")
	)
	(arc
		(start 137.341864 -253.88189)
		(mid 137.62482 -253.958067)
		(end 137.907776 -253.88189)
		(width 0.0889)
		(layer "In2.Cu")
		(net "M_I_CPU1_SA_CA<3>")
	)
	(arc
		(start 129.821686 -253.88189)
		(mid 130.104642 -253.958067)
		(end 130.387598 -253.88189)
		(width 0.0889)
		(layer "In2.Cu")
		(net "M_I_CPU1_SA_CA<3>")
	)
	(arc
		(start 131.327652 -253.88189)
		(mid 131.509903 -253.83154)
		(end 131.693412 -253.877064)
		(width 0.0889)
		(layer "In2.Cu")
		(net "M_I_CPU1_SA_CA<3>")
	)
	(segment
		(start 127.757936 -253.660402)
		(end 128.224788 -253.394464)
		(width 0.10668)
		(layer "F.Cu")
		(net "M_I_CPU1_SA_CA<2>")
	)
	(segment
		(start 161.058606 -253.31801)
		(end 163.066222 -251.310394)
		(width 0.14478)
		(layer "In2.Cu")
		(net "M_I_CPU1_SA_CA<2>")
	)
	(segment
		(start 156.559758 -252.846586)
		(end 157.031182 -253.31801)
		(width 0.14478)
		(layer "In2.Cu")
		(net "M_I_CPU1_SA_CA<2>")
	)
	(segment
		(start 140.257784 -253.717044)
		(end 140.266166 -253.72187)
		(width 0.0889)
		(layer "In2.Cu")
		(net "M_I_CPU1_SA_CA<2>")
	)
	(segment
		(start 138.743436 -253.72187)
		(end 138.751818 -253.717044)
		(width 0.0889)
		(layer "In2.Cu")
		(net "M_I_CPU1_SA_CA<2>")
	)
	(segment
		(start 144.9578 -253.717044)
		(end 144.966182 -253.72187)
		(width 0.0889)
		(layer "In2.Cu")
		(net "M_I_CPU1_SA_CA<2>")
	)
	(segment
		(start 174.48403 -249.610372)
		(end 183.19115 -249.610372)
		(width 0.14478)
		(layer "In2.Cu")
		(net "M_I_CPU1_SA_CA<2>")
	)
	(segment
		(start 134.04342 -253.72187)
		(end 134.051802 -253.717044)
		(width 0.0889)
		(layer "In2.Cu")
		(net "M_I_CPU1_SA_CA<2>")
	)
	(segment
		(start 150.390098 -253.983744)
		(end 151.527256 -252.846586)
		(width 0.14478)
		(layer "In2.Cu")
		(net "M_I_CPU1_SA_CA<2>")
	)
	(segment
		(start 129.343404 -253.72187)
		(end 129.351786 -253.717044)
		(width 0.0889)
		(layer "In2.Cu")
		(net "M_I_CPU1_SA_CA<2>")
	)
	(segment
		(start 130.857752 -253.717044)
		(end 130.866134 -253.72187)
		(width 0.0889)
		(layer "In2.Cu")
		(net "M_I_CPU1_SA_CA<2>")
	)
	(segment
		(start 147.142708 -253.823724)
		(end 147.302728 -253.983744)
		(width 0.0889)
		(layer "In2.Cu")
		(net "M_I_CPU1_SA_CA<2>")
	)
	(segment
		(start 128.224788 -253.394464)
		(end 128.07061 -253.659894)
		(width 0.0889)
		(layer "In2.Cu")
		(net "M_I_CPU1_SA_CA<2>")
	)
	(segment
		(start 151.527256 -252.846586)
		(end 156.559758 -252.846586)
		(width 0.14478)
		(layer "In2.Cu")
		(net "M_I_CPU1_SA_CA<2>")
	)
	(segment
		(start 135.557768 -253.717044)
		(end 135.56615 -253.72187)
		(width 0.0889)
		(layer "In2.Cu")
		(net "M_I_CPU1_SA_CA<2>")
	)
	(segment
		(start 129.917698 -253.717044)
		(end 129.92608 -253.72187)
		(width 0.0889)
		(layer "In2.Cu")
		(net "M_I_CPU1_SA_CA<2>")
	)
	(segment
		(start 128.40335 -253.72187)
		(end 128.411732 -253.717044)
		(width 0.0889)
		(layer "In2.Cu")
		(net "M_I_CPU1_SA_CA<2>")
	)
	(segment
		(start 133.103366 -253.72187)
		(end 133.111748 -253.717044)
		(width 0.0889)
		(layer "In2.Cu")
		(net "M_I_CPU1_SA_CA<2>")
	)
	(segment
		(start 147.908772 -253.983744)
		(end 150.390098 -253.983744)
		(width 0.14478)
		(layer "In2.Cu")
		(net "M_I_CPU1_SA_CA<2>")
	)
	(segment
		(start 134.617714 -253.717044)
		(end 134.626096 -253.72187)
		(width 0.0889)
		(layer "In2.Cu")
		(net "M_I_CPU1_SA_CA<2>")
	)
	(segment
		(start 172.784008 -251.310394)
		(end 174.48403 -249.610372)
		(width 0.14478)
		(layer "In2.Cu")
		(net "M_I_CPU1_SA_CA<2>")
	)
	(segment
		(start 163.066222 -251.310394)
		(end 172.784008 -251.310394)
		(width 0.14478)
		(layer "In2.Cu")
		(net "M_I_CPU1_SA_CA<2>")
	)
	(segment
		(start 157.031182 -253.31801)
		(end 161.058606 -253.31801)
		(width 0.14478)
		(layer "In2.Cu")
		(net "M_I_CPU1_SA_CA<2>")
	)
	(segment
		(start 146.293586 -253.823724)
		(end 147.142708 -253.823724)
		(width 0.0889)
		(layer "In2.Cu")
		(net "M_I_CPU1_SA_CA<2>")
	)
	(segment
		(start 147.302728 -253.983744)
		(end 147.908772 -253.983744)
		(width 0.0889)
		(layer "In2.Cu")
		(net "M_I_CPU1_SA_CA<2>")
	)
	(segment
		(start 183.19115 -249.610372)
		(end 183.616092 -249.18543)
		(width 0.14478)
		(layer "In2.Cu")
		(net "M_I_CPU1_SA_CA<2>")
	)
	(segment
		(start 139.31773 -253.717044)
		(end 139.326112 -253.72187)
		(width 0.0889)
		(layer "In2.Cu")
		(net "M_I_CPU1_SA_CA<2>")
	)
	(segment
		(start 143.077692 -253.717044)
		(end 143.086074 -253.72187)
		(width 0.0889)
		(layer "In2.Cu")
		(net "M_I_CPU1_SA_CA<2>")
	)
	(segment
		(start 142.503398 -253.72187)
		(end 142.51178 -253.717044)
		(width 0.0889)
		(layer "In2.Cu")
		(net "M_I_CPU1_SA_CA<2>")
	)
	(segment
		(start 137.803382 -253.72187)
		(end 137.811764 -253.717044)
		(width 0.0889)
		(layer "In2.Cu")
		(net "M_I_CPU1_SA_CA<2>")
	)
	(segment
		(start 144.383506 -253.72187)
		(end 144.391888 -253.717044)
		(width 0.0889)
		(layer "In2.Cu")
		(net "M_I_CPU1_SA_CA<2>")
	)
	(segment
		(start 128.07061 -253.659894)
		(end 128.092962 -253.743206)
		(width 0.0889)
		(layer "In2.Cu")
		(net "M_I_CPU1_SA_CA<2>")
	)
	(arc
		(start 128.411732 -253.717044)
		(mid 128.694688 -253.640867)
		(end 128.977644 -253.717044)
		(width 0.0889)
		(layer "In2.Cu")
		(net "M_I_CPU1_SA_CA<2>")
	)
	(arc
		(start 137.437622 -253.717044)
		(mid 137.619873 -253.767394)
		(end 137.803382 -253.72187)
		(width 0.0889)
		(layer "In2.Cu")
		(net "M_I_CPU1_SA_CA<2>")
	)
	(arc
		(start 142.137638 -253.717044)
		(mid 142.319889 -253.767394)
		(end 142.503398 -253.72187)
		(width 0.0889)
		(layer "In2.Cu")
		(net "M_I_CPU1_SA_CA<2>")
	)
	(arc
		(start 139.326112 -253.72187)
		(mid 139.50962 -253.767364)
		(end 139.691872 -253.717044)
		(width 0.0889)
		(layer "In2.Cu")
		(net "M_I_CPU1_SA_CA<2>")
	)
	(arc
		(start 140.266166 -253.72187)
		(mid 140.449674 -253.767364)
		(end 140.631926 -253.717044)
		(width 0.0889)
		(layer "In2.Cu")
		(net "M_I_CPU1_SA_CA<2>")
	)
	(arc
		(start 140.631926 -253.717044)
		(mid 140.914882 -253.640867)
		(end 141.197838 -253.717044)
		(width 0.0889)
		(layer "In2.Cu")
		(net "M_I_CPU1_SA_CA<2>")
	)
	(arc
		(start 134.051802 -253.717044)
		(mid 134.334758 -253.640867)
		(end 134.617714 -253.717044)
		(width 0.0889)
		(layer "In2.Cu")
		(net "M_I_CPU1_SA_CA<2>")
	)
	(arc
		(start 129.92608 -253.72187)
		(mid 130.109588 -253.767364)
		(end 130.29184 -253.717044)
		(width 0.0889)
		(layer "In2.Cu")
		(net "M_I_CPU1_SA_CA<2>")
	)
	(arc
		(start 135.93191 -253.717044)
		(mid 136.214866 -253.640867)
		(end 136.497822 -253.717044)
		(width 0.0889)
		(layer "In2.Cu")
		(net "M_I_CPU1_SA_CA<2>")
	)
	(arc
		(start 135.56615 -253.72187)
		(mid 135.749658 -253.767364)
		(end 135.93191 -253.717044)
		(width 0.0889)
		(layer "In2.Cu")
		(net "M_I_CPU1_SA_CA<2>")
	)
	(arc
		(start 133.67766 -253.717044)
		(mid 133.859911 -253.767394)
		(end 134.04342 -253.72187)
		(width 0.0889)
		(layer "In2.Cu")
		(net "M_I_CPU1_SA_CA<2>")
	)
	(arc
		(start 142.51178 -253.717044)
		(mid 142.794736 -253.640867)
		(end 143.077692 -253.717044)
		(width 0.0889)
		(layer "In2.Cu")
		(net "M_I_CPU1_SA_CA<2>")
	)
	(arc
		(start 141.197838 -253.717044)
		(mid 141.384782 -253.767299)
		(end 141.571726 -253.717044)
		(width 0.0889)
		(layer "In2.Cu")
		(net "M_I_CPU1_SA_CA<2>")
	)
	(arc
		(start 144.966182 -253.72187)
		(mid 145.14969 -253.767364)
		(end 145.331942 -253.717044)
		(width 0.0889)
		(layer "In2.Cu")
		(net "M_I_CPU1_SA_CA<2>")
	)
	(arc
		(start 136.497822 -253.717044)
		(mid 136.684766 -253.767299)
		(end 136.87171 -253.717044)
		(width 0.0889)
		(layer "In2.Cu")
		(net "M_I_CPU1_SA_CA<2>")
	)
	(arc
		(start 134.991856 -253.717044)
		(mid 135.274812 -253.640867)
		(end 135.557768 -253.717044)
		(width 0.0889)
		(layer "In2.Cu")
		(net "M_I_CPU1_SA_CA<2>")
	)
	(arc
		(start 141.571726 -253.717044)
		(mid 141.854682 -253.640867)
		(end 142.137638 -253.717044)
		(width 0.0889)
		(layer "In2.Cu")
		(net "M_I_CPU1_SA_CA<2>")
	)
	(arc
		(start 129.351786 -253.717044)
		(mid 129.634742 -253.640867)
		(end 129.917698 -253.717044)
		(width 0.0889)
		(layer "In2.Cu")
		(net "M_I_CPU1_SA_CA<2>")
	)
	(arc
		(start 130.29184 -253.717044)
		(mid 130.574796 -253.640867)
		(end 130.857752 -253.717044)
		(width 0.0889)
		(layer "In2.Cu")
		(net "M_I_CPU1_SA_CA<2>")
	)
	(arc
		(start 130.866134 -253.72187)
		(mid 131.049642 -253.767364)
		(end 131.231894 -253.717044)
		(width 0.0889)
		(layer "In2.Cu")
		(net "M_I_CPU1_SA_CA<2>")
	)
	(arc
		(start 133.111748 -253.717044)
		(mid 133.394704 -253.640867)
		(end 133.67766 -253.717044)
		(width 0.0889)
		(layer "In2.Cu")
		(net "M_I_CPU1_SA_CA<2>")
	)
	(arc
		(start 134.626096 -253.72187)
		(mid 134.809604 -253.767364)
		(end 134.991856 -253.717044)
		(width 0.0889)
		(layer "In2.Cu")
		(net "M_I_CPU1_SA_CA<2>")
	)
	(arc
		(start 132.737606 -253.717044)
		(mid 132.919857 -253.767394)
		(end 133.103366 -253.72187)
		(width 0.0889)
		(layer "In2.Cu")
		(net "M_I_CPU1_SA_CA<2>")
	)
	(arc
		(start 145.331942 -253.717044)
		(mid 145.614898 -253.640867)
		(end 145.897854 -253.717044)
		(width 0.0889)
		(layer "In2.Cu")
		(net "M_I_CPU1_SA_CA<2>")
	)
	(arc
		(start 128.977644 -253.717044)
		(mid 129.159895 -253.767394)
		(end 129.343404 -253.72187)
		(width 0.0889)
		(layer "In2.Cu")
		(net "M_I_CPU1_SA_CA<2>")
	)
	(arc
		(start 144.017746 -253.717044)
		(mid 144.199997 -253.767394)
		(end 144.383506 -253.72187)
		(width 0.0889)
		(layer "In2.Cu")
		(net "M_I_CPU1_SA_CA<2>")
	)
	(arc
		(start 131.231894 -253.717044)
		(mid 131.51485 -253.640867)
		(end 131.797806 -253.717044)
		(width 0.0889)
		(layer "In2.Cu")
		(net "M_I_CPU1_SA_CA<2>")
	)
	(arc
		(start 137.811764 -253.717044)
		(mid 138.09472 -253.640867)
		(end 138.377676 -253.717044)
		(width 0.0889)
		(layer "In2.Cu")
		(net "M_I_CPU1_SA_CA<2>")
	)
	(arc
		(start 131.797806 -253.717044)
		(mid 131.98475 -253.767299)
		(end 132.171694 -253.717044)
		(width 0.0889)
		(layer "In2.Cu")
		(net "M_I_CPU1_SA_CA<2>")
	)
	(arc
		(start 143.086074 -253.72187)
		(mid 143.269582 -253.767364)
		(end 143.451834 -253.717044)
		(width 0.0889)
		(layer "In2.Cu")
		(net "M_I_CPU1_SA_CA<2>")
	)
	(arc
		(start 132.171694 -253.717044)
		(mid 132.45465 -253.640867)
		(end 132.737606 -253.717044)
		(width 0.0889)
		(layer "In2.Cu")
		(net "M_I_CPU1_SA_CA<2>")
	)
	(arc
		(start 144.391888 -253.717044)
		(mid 144.674844 -253.640867)
		(end 144.9578 -253.717044)
		(width 0.0889)
		(layer "In2.Cu")
		(net "M_I_CPU1_SA_CA<2>")
	)
	(arc
		(start 128.092962 -253.743206)
		(mid 128.250472 -253.766404)
		(end 128.40335 -253.72187)
		(width 0.0889)
		(layer "In2.Cu")
		(net "M_I_CPU1_SA_CA<2>")
	)
	(arc
		(start 139.691872 -253.717044)
		(mid 139.974828 -253.640867)
		(end 140.257784 -253.717044)
		(width 0.0889)
		(layer "In2.Cu")
		(net "M_I_CPU1_SA_CA<2>")
	)
	(arc
		(start 136.87171 -253.717044)
		(mid 137.154666 -253.640867)
		(end 137.437622 -253.717044)
		(width 0.0889)
		(layer "In2.Cu")
		(net "M_I_CPU1_SA_CA<2>")
	)
	(arc
		(start 138.751818 -253.717044)
		(mid 139.034774 -253.640867)
		(end 139.31773 -253.717044)
		(width 0.0889)
		(layer "In2.Cu")
		(net "M_I_CPU1_SA_CA<2>")
	)
	(arc
		(start 138.377676 -253.717044)
		(mid 138.559927 -253.767394)
		(end 138.743436 -253.72187)
		(width 0.0889)
		(layer "In2.Cu")
		(net "M_I_CPU1_SA_CA<2>")
	)
	(arc
		(start 145.897854 -253.717044)
		(mid 146.088658 -253.796579)
		(end 146.293586 -253.823724)
		(width 0.0889)
		(layer "In2.Cu")
		(net "M_I_CPU1_SA_CA<2>")
	)
	(arc
		(start 143.451834 -253.717044)
		(mid 143.73479 -253.640867)
		(end 144.017746 -253.717044)
		(width 0.0889)
		(layer "In2.Cu")
		(net "M_I_CPU1_SA_CA<2>")
	)
	(segment
		(start 128.69799 -253.660402)
		(end 129.164842 -253.394464)
		(width 0.10668)
		(layer "F.Cu")
		(net "M_I_CPU1_SA_CA<1>")
	)
	(segment
		(start 129.164842 -253.394464)
		(end 129.318766 -253.129034)
		(width 0.0889)
		(layer "In2.Cu")
		(net "M_I_CPU1_SA_CA<1>")
	)
	(segment
		(start 134.04342 -253.067058)
		(end 134.051802 -253.071884)
		(width 0.0889)
		(layer "In2.Cu")
		(net "M_I_CPU1_SA_CA<1>")
	)
	(segment
		(start 172.991018 -250.460256)
		(end 174.690786 -248.760488)
		(width 0.14478)
		(layer "In2.Cu")
		(net "M_I_CPU1_SA_CA<1>")
	)
	(segment
		(start 160.87217 -252.86843)
		(end 163.280344 -250.460256)
		(width 0.14478)
		(layer "In2.Cu")
		(net "M_I_CPU1_SA_CA<1>")
	)
	(segment
		(start 156.746194 -252.397006)
		(end 157.217618 -252.86843)
		(width 0.14478)
		(layer "In2.Cu")
		(net "M_I_CPU1_SA_CA<1>")
	)
	(segment
		(start 178.343814 -248.760488)
		(end 179.090828 -248.760488)
		(width 0.14478)
		(layer "In2.Cu")
		(net "M_I_CPU1_SA_CA<1>")
	)
	(segment
		(start 144.015968 -253.072138)
		(end 144.037812 -253.059692)
		(width 0.0889)
		(layer "In2.Cu")
		(net "M_I_CPU1_SA_CA<1>")
	)
	(segment
		(start 150.225506 -253.51232)
		(end 151.34082 -252.397006)
		(width 0.14478)
		(layer "In2.Cu")
		(net "M_I_CPU1_SA_CA<1>")
	)
	(segment
		(start 157.217618 -252.86843)
		(end 160.87217 -252.86843)
		(width 0.14478)
		(layer "In2.Cu")
		(net "M_I_CPU1_SA_CA<1>")
	)
	(segment
		(start 178.02225 -248.438924)
		(end 178.343814 -248.760488)
		(width 0.14478)
		(layer "In2.Cu")
		(net "M_I_CPU1_SA_CA<1>")
	)
	(segment
		(start 145.300446 -253.054866)
		(end 145.330418 -253.072138)
		(width 0.0889)
		(layer "In2.Cu")
		(net "M_I_CPU1_SA_CA<1>")
	)
	(segment
		(start 137.803382 -253.067058)
		(end 137.811764 -253.071884)
		(width 0.0889)
		(layer "In2.Cu")
		(net "M_I_CPU1_SA_CA<1>")
	)
	(segment
		(start 146.97583 -253.51232)
		(end 147.940776 -253.51232)
		(width 0.0889)
		(layer "In2.Cu")
		(net "M_I_CPU1_SA_CA<1>")
	)
	(segment
		(start 167.174926 -250.168664)
		(end 167.466518 -250.460256)
		(width 0.14478)
		(layer "In2.Cu")
		(net "M_I_CPU1_SA_CA<1>")
	)
	(segment
		(start 167.466518 -250.460256)
		(end 169.890948 -250.460256)
		(width 0.14478)
		(layer "In2.Cu")
		(net "M_I_CPU1_SA_CA<1>")
	)
	(segment
		(start 140.257784 -253.071884)
		(end 140.266166 -253.067058)
		(width 0.0889)
		(layer "In2.Cu")
		(net "M_I_CPU1_SA_CA<1>")
	)
	(segment
		(start 166.616126 -250.460256)
		(end 166.907718 -250.168664)
		(width 0.14478)
		(layer "In2.Cu")
		(net "M_I_CPU1_SA_CA<1>")
	)
	(segment
		(start 147.940776 -253.51232)
		(end 150.225506 -253.51232)
		(width 0.14478)
		(layer "In2.Cu")
		(net "M_I_CPU1_SA_CA<1>")
	)
	(segment
		(start 129.318766 -253.129034)
		(end 129.414778 -253.103634)
		(width 0.0889)
		(layer "In2.Cu")
		(net "M_I_CPU1_SA_CA<1>")
	)
	(segment
		(start 151.34082 -252.397006)
		(end 156.746194 -252.397006)
		(width 0.14478)
		(layer "In2.Cu")
		(net "M_I_CPU1_SA_CA<1>")
	)
	(segment
		(start 139.31773 -253.071884)
		(end 139.326112 -253.067058)
		(width 0.0889)
		(layer "In2.Cu")
		(net "M_I_CPU1_SA_CA<1>")
	)
	(segment
		(start 129.917698 -253.071884)
		(end 129.92608 -253.067058)
		(width 0.0889)
		(layer "In2.Cu")
		(net "M_I_CPU1_SA_CA<1>")
	)
	(segment
		(start 142.503398 -253.067058)
		(end 142.51178 -253.071884)
		(width 0.0889)
		(layer "In2.Cu")
		(net "M_I_CPU1_SA_CA<1>")
	)
	(segment
		(start 143.077692 -253.071884)
		(end 143.086074 -253.067058)
		(width 0.0889)
		(layer "In2.Cu")
		(net "M_I_CPU1_SA_CA<1>")
	)
	(segment
		(start 170.449748 -250.168664)
		(end 170.74134 -250.460256)
		(width 0.14478)
		(layer "In2.Cu")
		(net "M_I_CPU1_SA_CA<1>")
	)
	(segment
		(start 163.280344 -250.460256)
		(end 165.498526 -250.460256)
		(width 0.14478)
		(layer "In2.Cu")
		(net "M_I_CPU1_SA_CA<1>")
	)
	(segment
		(start 170.18254 -250.168664)
		(end 170.449748 -250.168664)
		(width 0.14478)
		(layer "In2.Cu")
		(net "M_I_CPU1_SA_CA<1>")
	)
	(segment
		(start 143.992092 -253.086108)
		(end 144.015968 -253.072138)
		(width 0.0889)
		(layer "In2.Cu")
		(net "M_I_CPU1_SA_CA<1>")
	)
	(segment
		(start 166.348918 -250.460256)
		(end 166.616126 -250.460256)
		(width 0.14478)
		(layer "In2.Cu")
		(net "M_I_CPU1_SA_CA<1>")
	)
	(segment
		(start 130.857752 -253.071884)
		(end 130.866134 -253.067058)
		(width 0.0889)
		(layer "In2.Cu")
		(net "M_I_CPU1_SA_CA<1>")
	)
	(segment
		(start 177.785014 -248.438924)
		(end 178.02225 -248.438924)
		(width 0.14478)
		(layer "In2.Cu")
		(net "M_I_CPU1_SA_CA<1>")
	)
	(segment
		(start 179.090828 -248.760488)
		(end 179.516024 -248.335292)
		(width 0.14478)
		(layer "In2.Cu")
		(net "M_I_CPU1_SA_CA<1>")
	)
	(segment
		(start 133.103366 -253.067058)
		(end 133.111748 -253.071884)
		(width 0.0889)
		(layer "In2.Cu")
		(net "M_I_CPU1_SA_CA<1>")
	)
	(segment
		(start 174.690786 -248.760488)
		(end 177.46345 -248.760488)
		(width 0.14478)
		(layer "In2.Cu")
		(net "M_I_CPU1_SA_CA<1>")
	)
	(segment
		(start 177.46345 -248.760488)
		(end 177.785014 -248.438924)
		(width 0.14478)
		(layer "In2.Cu")
		(net "M_I_CPU1_SA_CA<1>")
	)
	(segment
		(start 170.74134 -250.460256)
		(end 172.991018 -250.460256)
		(width 0.14478)
		(layer "In2.Cu")
		(net "M_I_CPU1_SA_CA<1>")
	)
	(segment
		(start 165.498526 -250.460256)
		(end 165.790118 -250.168664)
		(width 0.14478)
		(layer "In2.Cu")
		(net "M_I_CPU1_SA_CA<1>")
	)
	(segment
		(start 166.907718 -250.168664)
		(end 167.174926 -250.168664)
		(width 0.14478)
		(layer "In2.Cu")
		(net "M_I_CPU1_SA_CA<1>")
	)
	(segment
		(start 165.790118 -250.168664)
		(end 166.057326 -250.168664)
		(width 0.14478)
		(layer "In2.Cu")
		(net "M_I_CPU1_SA_CA<1>")
	)
	(segment
		(start 138.743436 -253.067058)
		(end 138.751818 -253.071884)
		(width 0.0889)
		(layer "In2.Cu")
		(net "M_I_CPU1_SA_CA<1>")
	)
	(segment
		(start 144.388586 -253.071884)
		(end 144.416272 -253.087886)
		(width 0.0889)
		(layer "In2.Cu")
		(net "M_I_CPU1_SA_CA<1>")
	)
	(segment
		(start 135.557768 -253.071884)
		(end 135.56615 -253.067058)
		(width 0.0889)
		(layer "In2.Cu")
		(net "M_I_CPU1_SA_CA<1>")
	)
	(segment
		(start 166.057326 -250.168664)
		(end 166.348918 -250.460256)
		(width 0.14478)
		(layer "In2.Cu")
		(net "M_I_CPU1_SA_CA<1>")
	)
	(segment
		(start 134.617714 -253.071884)
		(end 134.626096 -253.067058)
		(width 0.0889)
		(layer "In2.Cu")
		(net "M_I_CPU1_SA_CA<1>")
	)
	(segment
		(start 169.890948 -250.460256)
		(end 170.18254 -250.168664)
		(width 0.14478)
		(layer "In2.Cu")
		(net "M_I_CPU1_SA_CA<1>")
	)
	(arc
		(start 132.737606 -253.071884)
		(mid 132.919857 -253.021534)
		(end 133.103366 -253.067058)
		(width 0.0889)
		(layer "In2.Cu")
		(net "M_I_CPU1_SA_CA<1>")
	)
	(arc
		(start 133.111748 -253.071884)
		(mid 133.394704 -253.148061)
		(end 133.67766 -253.071884)
		(width 0.0889)
		(layer "In2.Cu")
		(net "M_I_CPU1_SA_CA<1>")
	)
	(arc
		(start 130.29184 -253.071884)
		(mid 130.574796 -253.148061)
		(end 130.857752 -253.071884)
		(width 0.0889)
		(layer "In2.Cu")
		(net "M_I_CPU1_SA_CA<1>")
	)
	(arc
		(start 131.797806 -253.071884)
		(mid 131.98475 -253.021629)
		(end 132.171694 -253.071884)
		(width 0.0889)
		(layer "In2.Cu")
		(net "M_I_CPU1_SA_CA<1>")
	)
	(arc
		(start 139.691872 -253.071884)
		(mid 139.974828 -253.148061)
		(end 140.257784 -253.071884)
		(width 0.0889)
		(layer "In2.Cu")
		(net "M_I_CPU1_SA_CA<1>")
	)
	(arc
		(start 139.326112 -253.067058)
		(mid 139.50962 -253.021564)
		(end 139.691872 -253.071884)
		(width 0.0889)
		(layer "In2.Cu")
		(net "M_I_CPU1_SA_CA<1>")
	)
	(arc
		(start 144.416272 -253.087886)
		(mid 144.688306 -253.148658)
		(end 144.956276 -253.071884)
		(width 0.0889)
		(layer "In2.Cu")
		(net "M_I_CPU1_SA_CA<1>")
	)
	(arc
		(start 132.171694 -253.071884)
		(mid 132.45465 -253.148061)
		(end 132.737606 -253.071884)
		(width 0.0889)
		(layer "In2.Cu")
		(net "M_I_CPU1_SA_CA<1>")
	)
	(arc
		(start 143.451834 -253.071884)
		(mid 143.720154 -253.147992)
		(end 143.992092 -253.086108)
		(width 0.0889)
		(layer "In2.Cu")
		(net "M_I_CPU1_SA_CA<1>")
	)
	(arc
		(start 144.956276 -253.071884)
		(mid 145.126283 -253.021319)
		(end 145.300446 -253.054866)
		(width 0.0889)
		(layer "In2.Cu")
		(net "M_I_CPU1_SA_CA<1>")
	)
	(arc
		(start 135.56615 -253.067058)
		(mid 135.749658 -253.021564)
		(end 135.93191 -253.071884)
		(width 0.0889)
		(layer "In2.Cu")
		(net "M_I_CPU1_SA_CA<1>")
	)
	(arc
		(start 130.866134 -253.067058)
		(mid 131.049642 -253.021564)
		(end 131.231894 -253.071884)
		(width 0.0889)
		(layer "In2.Cu")
		(net "M_I_CPU1_SA_CA<1>")
	)
	(arc
		(start 131.231894 -253.071884)
		(mid 131.51485 -253.148061)
		(end 131.797806 -253.071884)
		(width 0.0889)
		(layer "In2.Cu")
		(net "M_I_CPU1_SA_CA<1>")
	)
	(arc
		(start 134.991856 -253.071884)
		(mid 135.274812 -253.148061)
		(end 135.557768 -253.071884)
		(width 0.0889)
		(layer "In2.Cu")
		(net "M_I_CPU1_SA_CA<1>")
	)
	(arc
		(start 143.086074 -253.067058)
		(mid 143.269582 -253.021564)
		(end 143.451834 -253.071884)
		(width 0.0889)
		(layer "In2.Cu")
		(net "M_I_CPU1_SA_CA<1>")
	)
	(arc
		(start 137.437622 -253.071884)
		(mid 137.619873 -253.021534)
		(end 137.803382 -253.067058)
		(width 0.0889)
		(layer "In2.Cu")
		(net "M_I_CPU1_SA_CA<1>")
	)
	(arc
		(start 134.626096 -253.067058)
		(mid 134.809604 -253.021564)
		(end 134.991856 -253.071884)
		(width 0.0889)
		(layer "In2.Cu")
		(net "M_I_CPU1_SA_CA<1>")
	)
	(arc
		(start 141.197838 -253.071884)
		(mid 141.384782 -253.021629)
		(end 141.571726 -253.071884)
		(width 0.0889)
		(layer "In2.Cu")
		(net "M_I_CPU1_SA_CA<1>")
	)
	(arc
		(start 138.751818 -253.071884)
		(mid 139.034774 -253.148061)
		(end 139.31773 -253.071884)
		(width 0.0889)
		(layer "In2.Cu")
		(net "M_I_CPU1_SA_CA<1>")
	)
	(arc
		(start 135.93191 -253.071884)
		(mid 136.214866 -253.148061)
		(end 136.497822 -253.071884)
		(width 0.0889)
		(layer "In2.Cu")
		(net "M_I_CPU1_SA_CA<1>")
	)
	(arc
		(start 129.414778 -253.103634)
		(mid 129.669986 -253.147111)
		(end 129.917698 -253.071884)
		(width 0.0889)
		(layer "In2.Cu")
		(net "M_I_CPU1_SA_CA<1>")
	)
	(arc
		(start 138.377676 -253.071884)
		(mid 138.559927 -253.021534)
		(end 138.743436 -253.067058)
		(width 0.0889)
		(layer "In2.Cu")
		(net "M_I_CPU1_SA_CA<1>")
	)
	(arc
		(start 145.330418 -253.072138)
		(mid 146.124189 -253.400397)
		(end 146.97583 -253.51232)
		(width 0.0889)
		(layer "In2.Cu")
		(net "M_I_CPU1_SA_CA<1>")
	)
	(arc
		(start 137.811764 -253.071884)
		(mid 138.09472 -253.148061)
		(end 138.377676 -253.071884)
		(width 0.0889)
		(layer "In2.Cu")
		(net "M_I_CPU1_SA_CA<1>")
	)
	(arc
		(start 141.571726 -253.071884)
		(mid 141.854682 -253.148061)
		(end 142.137638 -253.071884)
		(width 0.0889)
		(layer "In2.Cu")
		(net "M_I_CPU1_SA_CA<1>")
	)
	(arc
		(start 140.631926 -253.071884)
		(mid 140.914882 -253.148061)
		(end 141.197838 -253.071884)
		(width 0.0889)
		(layer "In2.Cu")
		(net "M_I_CPU1_SA_CA<1>")
	)
	(arc
		(start 142.51178 -253.071884)
		(mid 142.794736 -253.148061)
		(end 143.077692 -253.071884)
		(width 0.0889)
		(layer "In2.Cu")
		(net "M_I_CPU1_SA_CA<1>")
	)
	(arc
		(start 144.037812 -253.059692)
		(mid 144.21474 -253.021864)
		(end 144.388586 -253.071884)
		(width 0.0889)
		(layer "In2.Cu")
		(net "M_I_CPU1_SA_CA<1>")
	)
	(arc
		(start 142.137638 -253.071884)
		(mid 142.319889 -253.021534)
		(end 142.503398 -253.067058)
		(width 0.0889)
		(layer "In2.Cu")
		(net "M_I_CPU1_SA_CA<1>")
	)
	(arc
		(start 129.92608 -253.067058)
		(mid 130.109588 -253.021564)
		(end 130.29184 -253.071884)
		(width 0.0889)
		(layer "In2.Cu")
		(net "M_I_CPU1_SA_CA<1>")
	)
	(arc
		(start 140.266166 -253.067058)
		(mid 140.449674 -253.021564)
		(end 140.631926 -253.071884)
		(width 0.0889)
		(layer "In2.Cu")
		(net "M_I_CPU1_SA_CA<1>")
	)
	(arc
		(start 136.87171 -253.071884)
		(mid 137.154666 -253.148061)
		(end 137.437622 -253.071884)
		(width 0.0889)
		(layer "In2.Cu")
		(net "M_I_CPU1_SA_CA<1>")
	)
	(arc
		(start 134.051802 -253.071884)
		(mid 134.334758 -253.148061)
		(end 134.617714 -253.071884)
		(width 0.0889)
		(layer "In2.Cu")
		(net "M_I_CPU1_SA_CA<1>")
	)
	(arc
		(start 136.497822 -253.071884)
		(mid 136.684766 -253.021629)
		(end 136.87171 -253.071884)
		(width 0.0889)
		(layer "In2.Cu")
		(net "M_I_CPU1_SA_CA<1>")
	)
	(arc
		(start 133.67766 -253.071884)
		(mid 133.859911 -253.021534)
		(end 134.04342 -253.067058)
		(width 0.0889)
		(layer "In2.Cu")
		(net "M_I_CPU1_SA_CA<1>")
	)
	(segment
		(start 129.16789 -252.850396)
		(end 129.634742 -252.584458)
		(width 0.10668)
		(layer "F.Cu")
		(net "M_I_CPU1_SA_CA<0>")
	)
	(segment
		(start 133.20776 -252.907038)
		(end 133.216142 -252.911864)
		(width 0.0889)
		(layer "In2.Cu")
		(net "M_I_CPU1_SA_CA<0>")
	)
	(segment
		(start 150.155656 -252.946154)
		(end 151.154384 -251.947426)
		(width 0.14478)
		(layer "In2.Cu")
		(net "M_I_CPU1_SA_CA<0>")
	)
	(segment
		(start 135.453374 -252.911864)
		(end 135.461756 -252.907038)
		(width 0.0889)
		(layer "In2.Cu")
		(net "M_I_CPU1_SA_CA<0>")
	)
	(segment
		(start 173.19752 -249.610372)
		(end 174.897542 -247.91035)
		(width 0.14478)
		(layer "In2.Cu")
		(net "M_I_CPU1_SA_CA<0>")
	)
	(segment
		(start 174.897542 -247.91035)
		(end 183.19115 -247.91035)
		(width 0.14478)
		(layer "In2.Cu")
		(net "M_I_CPU1_SA_CA<0>")
	)
	(segment
		(start 147.293584 -252.946154)
		(end 147.74037 -252.946154)
		(width 0.0889)
		(layer "In2.Cu")
		(net "M_I_CPU1_SA_CA<0>")
	)
	(segment
		(start 140.15339 -252.911864)
		(end 140.161772 -252.907038)
		(width 0.0889)
		(layer "In2.Cu")
		(net "M_I_CPU1_SA_CA<0>")
	)
	(segment
		(start 151.154384 -251.947426)
		(end 156.93263 -251.947426)
		(width 0.14478)
		(layer "In2.Cu")
		(net "M_I_CPU1_SA_CA<0>")
	)
	(segment
		(start 141.093444 -252.911864)
		(end 141.101826 -252.907038)
		(width 0.0889)
		(layer "In2.Cu")
		(net "M_I_CPU1_SA_CA<0>")
	)
	(segment
		(start 145.387822 -252.88494)
		(end 145.425668 -252.906784)
		(width 0.0889)
		(layer "In2.Cu")
		(net "M_I_CPU1_SA_CA<0>")
	)
	(segment
		(start 143.920464 -252.906784)
		(end 143.94434 -252.892814)
		(width 0.0889)
		(layer "In2.Cu")
		(net "M_I_CPU1_SA_CA<0>")
	)
	(segment
		(start 136.967722 -252.907038)
		(end 136.976104 -252.911864)
		(width 0.0889)
		(layer "In2.Cu")
		(net "M_I_CPU1_SA_CA<0>")
	)
	(segment
		(start 132.267706 -252.907038)
		(end 132.276088 -252.911864)
		(width 0.0889)
		(layer "In2.Cu")
		(net "M_I_CPU1_SA_CA<0>")
	)
	(segment
		(start 157.404054 -252.41885)
		(end 160.68548 -252.41885)
		(width 0.14478)
		(layer "In2.Cu")
		(net "M_I_CPU1_SA_CA<0>")
	)
	(segment
		(start 143.897096 -252.920246)
		(end 143.920464 -252.906784)
		(width 0.0889)
		(layer "In2.Cu")
		(net "M_I_CPU1_SA_CA<0>")
	)
	(segment
		(start 129.634742 -252.584458)
		(end 129.480818 -252.849888)
		(width 0.0889)
		(layer "In2.Cu")
		(net "M_I_CPU1_SA_CA<0>")
	)
	(segment
		(start 130.753358 -252.911864)
		(end 130.76174 -252.907038)
		(width 0.0889)
		(layer "In2.Cu")
		(net "M_I_CPU1_SA_CA<0>")
	)
	(segment
		(start 131.693412 -252.911864)
		(end 131.701794 -252.907038)
		(width 0.0889)
		(layer "In2.Cu")
		(net "M_I_CPU1_SA_CA<0>")
	)
	(segment
		(start 137.907776 -252.907038)
		(end 137.916158 -252.911864)
		(width 0.0889)
		(layer "In2.Cu")
		(net "M_I_CPU1_SA_CA<0>")
	)
	(segment
		(start 136.393428 -252.911864)
		(end 136.40181 -252.907038)
		(width 0.0889)
		(layer "In2.Cu")
		(net "M_I_CPU1_SA_CA<0>")
	)
	(segment
		(start 129.480818 -252.849888)
		(end 129.50317 -252.9332)
		(width 0.0889)
		(layer "In2.Cu")
		(net "M_I_CPU1_SA_CA<0>")
	)
	(segment
		(start 147.022566 -253.217172)
		(end 147.293584 -252.946154)
		(width 0.0889)
		(layer "In2.Cu")
		(net "M_I_CPU1_SA_CA<0>")
	)
	(segment
		(start 160.68548 -252.41885)
		(end 163.493958 -249.610372)
		(width 0.14478)
		(layer "In2.Cu")
		(net "M_I_CPU1_SA_CA<0>")
	)
	(segment
		(start 144.484598 -252.907038)
		(end 144.505172 -252.918976)
		(width 0.0889)
		(layer "In2.Cu")
		(net "M_I_CPU1_SA_CA<0>")
	)
	(segment
		(start 156.93263 -251.947426)
		(end 157.404054 -252.41885)
		(width 0.14478)
		(layer "In2.Cu")
		(net "M_I_CPU1_SA_CA<0>")
	)
	(segment
		(start 147.74037 -252.946154)
		(end 150.155656 -252.946154)
		(width 0.14478)
		(layer "In2.Cu")
		(net "M_I_CPU1_SA_CA<0>")
	)
	(segment
		(start 141.667738 -252.907038)
		(end 141.67612 -252.911864)
		(width 0.0889)
		(layer "In2.Cu")
		(net "M_I_CPU1_SA_CA<0>")
	)
	(segment
		(start 183.19115 -247.91035)
		(end 183.616092 -247.485408)
		(width 0.14478)
		(layer "In2.Cu")
		(net "M_I_CPU1_SA_CA<0>")
	)
	(segment
		(start 146.581876 -253.217172)
		(end 147.022566 -253.217172)
		(width 0.0889)
		(layer "In2.Cu")
		(net "M_I_CPU1_SA_CA<0>")
	)
	(segment
		(start 163.493958 -249.610372)
		(end 173.19752 -249.610372)
		(width 0.14478)
		(layer "In2.Cu")
		(net "M_I_CPU1_SA_CA<0>")
	)
	(arc
		(start 134.521702 -252.907038)
		(mid 134.804658 -252.830861)
		(end 135.087614 -252.907038)
		(width 0.0889)
		(layer "In2.Cu")
		(net "M_I_CPU1_SA_CA<0>")
	)
	(arc
		(start 131.327652 -252.907038)
		(mid 131.509903 -252.957388)
		(end 131.693412 -252.911864)
		(width 0.0889)
		(layer "In2.Cu")
		(net "M_I_CPU1_SA_CA<0>")
	)
	(arc
		(start 141.67612 -252.911864)
		(mid 141.859628 -252.957358)
		(end 142.04188 -252.907038)
		(width 0.0889)
		(layer "In2.Cu")
		(net "M_I_CPU1_SA_CA<0>")
	)
	(arc
		(start 136.976104 -252.911864)
		(mid 137.159612 -252.957358)
		(end 137.341864 -252.907038)
		(width 0.0889)
		(layer "In2.Cu")
		(net "M_I_CPU1_SA_CA<0>")
	)
	(arc
		(start 130.76174 -252.907038)
		(mid 131.044696 -252.830861)
		(end 131.327652 -252.907038)
		(width 0.0889)
		(layer "In2.Cu")
		(net "M_I_CPU1_SA_CA<0>")
	)
	(arc
		(start 134.147814 -252.907038)
		(mid 134.334758 -252.957293)
		(end 134.521702 -252.907038)
		(width 0.0889)
		(layer "In2.Cu")
		(net "M_I_CPU1_SA_CA<0>")
	)
	(arc
		(start 144.505172 -252.918976)
		(mid 144.6841 -252.957853)
		(end 144.86001 -252.907038)
		(width 0.0889)
		(layer "In2.Cu")
		(net "M_I_CPU1_SA_CA<0>")
	)
	(arc
		(start 142.98168 -252.907038)
		(mid 143.264636 -252.830861)
		(end 143.547592 -252.907038)
		(width 0.0889)
		(layer "In2.Cu")
		(net "M_I_CPU1_SA_CA<0>")
	)
	(arc
		(start 139.221718 -252.907038)
		(mid 139.504674 -252.830861)
		(end 139.78763 -252.907038)
		(width 0.0889)
		(layer "In2.Cu")
		(net "M_I_CPU1_SA_CA<0>")
	)
	(arc
		(start 132.276088 -252.911864)
		(mid 132.459596 -252.957358)
		(end 132.641848 -252.907038)
		(width 0.0889)
		(layer "In2.Cu")
		(net "M_I_CPU1_SA_CA<0>")
	)
	(arc
		(start 136.027668 -252.907038)
		(mid 136.209919 -252.957388)
		(end 136.393428 -252.911864)
		(width 0.0889)
		(layer "In2.Cu")
		(net "M_I_CPU1_SA_CA<0>")
	)
	(arc
		(start 140.727684 -252.907038)
		(mid 140.909935 -252.957388)
		(end 141.093444 -252.911864)
		(width 0.0889)
		(layer "In2.Cu")
		(net "M_I_CPU1_SA_CA<0>")
	)
	(arc
		(start 135.087614 -252.907038)
		(mid 135.269865 -252.957388)
		(end 135.453374 -252.911864)
		(width 0.0889)
		(layer "In2.Cu")
		(net "M_I_CPU1_SA_CA<0>")
	)
	(arc
		(start 142.04188 -252.907038)
		(mid 142.324836 -252.830861)
		(end 142.607792 -252.907038)
		(width 0.0889)
		(layer "In2.Cu")
		(net "M_I_CPU1_SA_CA<0>")
	)
	(arc
		(start 140.161772 -252.907038)
		(mid 140.444728 -252.830861)
		(end 140.727684 -252.907038)
		(width 0.0889)
		(layer "In2.Cu")
		(net "M_I_CPU1_SA_CA<0>")
	)
	(arc
		(start 138.281918 -252.907038)
		(mid 138.564874 -252.830861)
		(end 138.84783 -252.907038)
		(width 0.0889)
		(layer "In2.Cu")
		(net "M_I_CPU1_SA_CA<0>")
	)
	(arc
		(start 133.581902 -252.907038)
		(mid 133.864858 -252.830861)
		(end 134.147814 -252.907038)
		(width 0.0889)
		(layer "In2.Cu")
		(net "M_I_CPU1_SA_CA<0>")
	)
	(arc
		(start 135.461756 -252.907038)
		(mid 135.744712 -252.830861)
		(end 136.027668 -252.907038)
		(width 0.0889)
		(layer "In2.Cu")
		(net "M_I_CPU1_SA_CA<0>")
	)
	(arc
		(start 131.701794 -252.907038)
		(mid 131.98475 -252.830861)
		(end 132.267706 -252.907038)
		(width 0.0889)
		(layer "In2.Cu")
		(net "M_I_CPU1_SA_CA<0>")
	)
	(arc
		(start 139.78763 -252.907038)
		(mid 139.969881 -252.957388)
		(end 140.15339 -252.911864)
		(width 0.0889)
		(layer "In2.Cu")
		(net "M_I_CPU1_SA_CA<0>")
	)
	(arc
		(start 137.916158 -252.911864)
		(mid 138.099666 -252.957358)
		(end 138.281918 -252.907038)
		(width 0.0889)
		(layer "In2.Cu")
		(net "M_I_CPU1_SA_CA<0>")
	)
	(arc
		(start 132.641848 -252.907038)
		(mid 132.924804 -252.830861)
		(end 133.20776 -252.907038)
		(width 0.0889)
		(layer "In2.Cu")
		(net "M_I_CPU1_SA_CA<0>")
	)
	(arc
		(start 142.607792 -252.907038)
		(mid 142.794736 -252.957293)
		(end 142.98168 -252.907038)
		(width 0.0889)
		(layer "In2.Cu")
		(net "M_I_CPU1_SA_CA<0>")
	)
	(arc
		(start 138.84783 -252.907038)
		(mid 139.034774 -252.957293)
		(end 139.221718 -252.907038)
		(width 0.0889)
		(layer "In2.Cu")
		(net "M_I_CPU1_SA_CA<0>")
	)
	(arc
		(start 137.341864 -252.907038)
		(mid 137.62482 -252.830861)
		(end 137.907776 -252.907038)
		(width 0.0889)
		(layer "In2.Cu")
		(net "M_I_CPU1_SA_CA<0>")
	)
	(arc
		(start 133.216142 -252.911864)
		(mid 133.39965 -252.957358)
		(end 133.581902 -252.907038)
		(width 0.0889)
		(layer "In2.Cu")
		(net "M_I_CPU1_SA_CA<0>")
	)
	(arc
		(start 145.425668 -252.906784)
		(mid 145.983302 -253.13823)
		(end 146.581876 -253.217172)
		(width 0.0889)
		(layer "In2.Cu")
		(net "M_I_CPU1_SA_CA<0>")
	)
	(arc
		(start 136.40181 -252.907038)
		(mid 136.684766 -252.830861)
		(end 136.967722 -252.907038)
		(width 0.0889)
		(layer "In2.Cu")
		(net "M_I_CPU1_SA_CA<0>")
	)
	(arc
		(start 130.387598 -252.907038)
		(mid 130.569849 -252.957388)
		(end 130.753358 -252.911864)
		(width 0.0889)
		(layer "In2.Cu")
		(net "M_I_CPU1_SA_CA<0>")
	)
	(arc
		(start 144.86001 -252.907038)
		(mid 145.121168 -252.830459)
		(end 145.387822 -252.88494)
		(width 0.0889)
		(layer "In2.Cu")
		(net "M_I_CPU1_SA_CA<0>")
	)
	(arc
		(start 143.547592 -252.907038)
		(mid 143.7207 -252.957154)
		(end 143.897096 -252.920246)
		(width 0.0889)
		(layer "In2.Cu")
		(net "M_I_CPU1_SA_CA<0>")
	)
	(arc
		(start 129.821686 -252.907038)
		(mid 130.104642 -252.830861)
		(end 130.387598 -252.907038)
		(width 0.0889)
		(layer "In2.Cu")
		(net "M_I_CPU1_SA_CA<0>")
	)
	(arc
		(start 143.94434 -252.892814)
		(mid 144.216277 -252.830988)
		(end 144.484598 -252.907038)
		(width 0.0889)
		(layer "In2.Cu")
		(net "M_I_CPU1_SA_CA<0>")
	)
	(arc
		(start 129.50317 -252.9332)
		(mid 129.665359 -252.955935)
		(end 129.821686 -252.907038)
		(width 0.0889)
		(layer "In2.Cu")
		(net "M_I_CPU1_SA_CA<0>")
	)
	(arc
		(start 141.101826 -252.907038)
		(mid 141.384782 -252.830861)
		(end 141.667738 -252.907038)
		(width 0.0889)
		(layer "In2.Cu")
		(net "M_I_CPU1_SA_CA<0>")
	)
	(segment
		(start 127.287782 -251.230384)
		(end 127.754634 -250.964446)
		(width 0.10668)
		(layer "F.Cu")
		(net "M_I_CPU1_RESET_N")
	)
	(segment
		(start 157.612334 -250.307856)
		(end 158.083758 -250.77928)
		(width 0.11684)
		(layer "In2.Cu")
		(net "M_I_CPU1_RESET_N")
	)
	(segment
		(start 141.093444 -250.63704)
		(end 141.101826 -250.641866)
		(width 0.0889)
		(layer "In2.Cu")
		(net "M_I_CPU1_RESET_N")
	)
	(segment
		(start 150.47468 -250.307856)
		(end 157.612334 -250.307856)
		(width 0.11684)
		(layer "In2.Cu")
		(net "M_I_CPU1_RESET_N")
	)
	(segment
		(start 133.20776 -250.641866)
		(end 133.216142 -250.63704)
		(width 0.0889)
		(layer "In2.Cu")
		(net "M_I_CPU1_RESET_N")
	)
	(segment
		(start 173.413674 -247.060466)
		(end 175.113696 -245.360444)
		(width 0.11684)
		(layer "In2.Cu")
		(net "M_I_CPU1_RESET_N")
	)
	(segment
		(start 130.753358 -250.63704)
		(end 130.76174 -250.641866)
		(width 0.0889)
		(layer "In2.Cu")
		(net "M_I_CPU1_RESET_N")
	)
	(segment
		(start 140.15339 -250.63704)
		(end 140.161772 -250.641866)
		(width 0.0889)
		(layer "In2.Cu")
		(net "M_I_CPU1_RESET_N")
	)
	(segment
		(start 132.267706 -250.641866)
		(end 132.276088 -250.63704)
		(width 0.0889)
		(layer "In2.Cu")
		(net "M_I_CPU1_RESET_N")
	)
	(segment
		(start 149.933152 -250.849384)
		(end 150.47468 -250.307856)
		(width 0.11684)
		(layer "In2.Cu")
		(net "M_I_CPU1_RESET_N")
	)
	(segment
		(start 137.907776 -250.641866)
		(end 137.916158 -250.63704)
		(width 0.0889)
		(layer "In2.Cu")
		(net "M_I_CPU1_RESET_N")
	)
	(segment
		(start 127.754634 -250.964446)
		(end 127.908812 -250.699016)
		(width 0.0889)
		(layer "In2.Cu")
		(net "M_I_CPU1_RESET_N")
	)
	(segment
		(start 159.560768 -250.77928)
		(end 163.279582 -247.060466)
		(width 0.11684)
		(layer "In2.Cu")
		(net "M_I_CPU1_RESET_N")
	)
	(segment
		(start 145.615152 -250.59132)
		(end 146.06905 -250.59132)
		(width 0.0889)
		(layer "In2.Cu")
		(net "M_I_CPU1_RESET_N")
	)
	(segment
		(start 158.083758 -250.77928)
		(end 159.560768 -250.77928)
		(width 0.11684)
		(layer "In2.Cu")
		(net "M_I_CPU1_RESET_N")
	)
	(segment
		(start 136.967722 -250.641866)
		(end 136.976104 -250.63704)
		(width 0.0889)
		(layer "In2.Cu")
		(net "M_I_CPU1_RESET_N")
	)
	(segment
		(start 179.090828 -245.360444)
		(end 179.516024 -244.935248)
		(width 0.11684)
		(layer "In2.Cu")
		(net "M_I_CPU1_RESET_N")
	)
	(segment
		(start 147.013168 -250.849384)
		(end 149.933152 -250.849384)
		(width 0.11684)
		(layer "In2.Cu")
		(net "M_I_CPU1_RESET_N")
	)
	(segment
		(start 144.853406 -250.63704)
		(end 144.861788 -250.641866)
		(width 0.0889)
		(layer "In2.Cu")
		(net "M_I_CPU1_RESET_N")
	)
	(segment
		(start 128.507744 -250.641866)
		(end 128.516126 -250.63704)
		(width 0.0889)
		(layer "In2.Cu")
		(net "M_I_CPU1_RESET_N")
	)
	(segment
		(start 163.279582 -247.060466)
		(end 173.413674 -247.060466)
		(width 0.11684)
		(layer "In2.Cu")
		(net "M_I_CPU1_RESET_N")
	)
	(segment
		(start 135.453374 -250.63704)
		(end 135.461756 -250.641866)
		(width 0.0889)
		(layer "In2.Cu")
		(net "M_I_CPU1_RESET_N")
	)
	(segment
		(start 127.908812 -250.699016)
		(end 128.005078 -250.673616)
		(width 0.0889)
		(layer "In2.Cu")
		(net "M_I_CPU1_RESET_N")
	)
	(segment
		(start 143.913352 -250.63704)
		(end 143.921734 -250.641866)
		(width 0.0889)
		(layer "In2.Cu")
		(net "M_I_CPU1_RESET_N")
	)
	(segment
		(start 141.667738 -250.641866)
		(end 141.67612 -250.63704)
		(width 0.0889)
		(layer "In2.Cu")
		(net "M_I_CPU1_RESET_N")
	)
	(segment
		(start 175.113696 -245.360444)
		(end 179.090828 -245.360444)
		(width 0.11684)
		(layer "In2.Cu")
		(net "M_I_CPU1_RESET_N")
	)
	(segment
		(start 131.693412 -250.63704)
		(end 131.701794 -250.641866)
		(width 0.0889)
		(layer "In2.Cu")
		(net "M_I_CPU1_RESET_N")
	)
	(segment
		(start 136.393428 -250.63704)
		(end 136.40181 -250.641866)
		(width 0.0889)
		(layer "In2.Cu")
		(net "M_I_CPU1_RESET_N")
	)
	(arc
		(start 145.4277 -250.641866)
		(mid 145.518079 -250.604179)
		(end 145.615152 -250.59132)
		(width 0.0889)
		(layer "In2.Cu")
		(net "M_I_CPU1_RESET_N")
	)
	(arc
		(start 140.161772 -250.641866)
		(mid 140.444728 -250.718043)
		(end 140.727684 -250.641866)
		(width 0.0889)
		(layer "In2.Cu")
		(net "M_I_CPU1_RESET_N")
	)
	(arc
		(start 143.921734 -250.641866)
		(mid 144.20469 -250.718043)
		(end 144.487646 -250.641866)
		(width 0.0889)
		(layer "In2.Cu")
		(net "M_I_CPU1_RESET_N")
	)
	(arc
		(start 141.67612 -250.63704)
		(mid 141.859628 -250.591546)
		(end 142.04188 -250.641866)
		(width 0.0889)
		(layer "In2.Cu")
		(net "M_I_CPU1_RESET_N")
	)
	(arc
		(start 139.78763 -250.641866)
		(mid 139.969881 -250.591516)
		(end 140.15339 -250.63704)
		(width 0.0889)
		(layer "In2.Cu")
		(net "M_I_CPU1_RESET_N")
	)
	(arc
		(start 130.387598 -250.641866)
		(mid 130.569849 -250.591516)
		(end 130.753358 -250.63704)
		(width 0.0889)
		(layer "In2.Cu")
		(net "M_I_CPU1_RESET_N")
	)
	(arc
		(start 132.641848 -250.641866)
		(mid 132.924804 -250.718043)
		(end 133.20776 -250.641866)
		(width 0.0889)
		(layer "In2.Cu")
		(net "M_I_CPU1_RESET_N")
	)
	(arc
		(start 130.76174 -250.641866)
		(mid 131.044696 -250.718043)
		(end 131.327652 -250.641866)
		(width 0.0889)
		(layer "In2.Cu")
		(net "M_I_CPU1_RESET_N")
	)
	(arc
		(start 136.40181 -250.641866)
		(mid 136.684766 -250.718043)
		(end 136.967722 -250.641866)
		(width 0.0889)
		(layer "In2.Cu")
		(net "M_I_CPU1_RESET_N")
	)
	(arc
		(start 139.221718 -250.641866)
		(mid 139.504674 -250.718043)
		(end 139.78763 -250.641866)
		(width 0.0889)
		(layer "In2.Cu")
		(net "M_I_CPU1_RESET_N")
	)
	(arc
		(start 129.447798 -250.641866)
		(mid 129.634742 -250.591611)
		(end 129.821686 -250.641866)
		(width 0.0889)
		(layer "In2.Cu")
		(net "M_I_CPU1_RESET_N")
	)
	(arc
		(start 142.607792 -250.641866)
		(mid 142.794736 -250.591611)
		(end 142.98168 -250.641866)
		(width 0.0889)
		(layer "In2.Cu")
		(net "M_I_CPU1_RESET_N")
	)
	(arc
		(start 134.521702 -250.641866)
		(mid 134.804658 -250.718043)
		(end 135.087614 -250.641866)
		(width 0.0889)
		(layer "In2.Cu")
		(net "M_I_CPU1_RESET_N")
	)
	(arc
		(start 129.821686 -250.641866)
		(mid 130.104642 -250.718043)
		(end 130.387598 -250.641866)
		(width 0.0889)
		(layer "In2.Cu")
		(net "M_I_CPU1_RESET_N")
	)
	(arc
		(start 138.84783 -250.641866)
		(mid 139.034774 -250.591611)
		(end 139.221718 -250.641866)
		(width 0.0889)
		(layer "In2.Cu")
		(net "M_I_CPU1_RESET_N")
	)
	(arc
		(start 142.04188 -250.641866)
		(mid 142.324836 -250.718043)
		(end 142.607792 -250.641866)
		(width 0.0889)
		(layer "In2.Cu")
		(net "M_I_CPU1_RESET_N")
	)
	(arc
		(start 144.487646 -250.641866)
		(mid 144.669897 -250.591516)
		(end 144.853406 -250.63704)
		(width 0.0889)
		(layer "In2.Cu")
		(net "M_I_CPU1_RESET_N")
	)
	(arc
		(start 128.516126 -250.63704)
		(mid 128.699634 -250.591546)
		(end 128.881886 -250.641866)
		(width 0.0889)
		(layer "In2.Cu")
		(net "M_I_CPU1_RESET_N")
	)
	(arc
		(start 131.327652 -250.641866)
		(mid 131.509903 -250.591516)
		(end 131.693412 -250.63704)
		(width 0.0889)
		(layer "In2.Cu")
		(net "M_I_CPU1_RESET_N")
	)
	(arc
		(start 142.98168 -250.641866)
		(mid 143.264636 -250.718043)
		(end 143.547592 -250.641866)
		(width 0.0889)
		(layer "In2.Cu")
		(net "M_I_CPU1_RESET_N")
	)
	(arc
		(start 136.027668 -250.641866)
		(mid 136.209919 -250.591516)
		(end 136.393428 -250.63704)
		(width 0.0889)
		(layer "In2.Cu")
		(net "M_I_CPU1_RESET_N")
	)
	(arc
		(start 137.341864 -250.641866)
		(mid 137.62482 -250.718043)
		(end 137.907776 -250.641866)
		(width 0.0889)
		(layer "In2.Cu")
		(net "M_I_CPU1_RESET_N")
	)
	(arc
		(start 138.281918 -250.641866)
		(mid 138.564874 -250.718043)
		(end 138.84783 -250.641866)
		(width 0.0889)
		(layer "In2.Cu")
		(net "M_I_CPU1_RESET_N")
	)
	(arc
		(start 134.147814 -250.641866)
		(mid 134.334758 -250.591611)
		(end 134.521702 -250.641866)
		(width 0.0889)
		(layer "In2.Cu")
		(net "M_I_CPU1_RESET_N")
	)
	(arc
		(start 141.101826 -250.641866)
		(mid 141.384782 -250.718043)
		(end 141.667738 -250.641866)
		(width 0.0889)
		(layer "In2.Cu")
		(net "M_I_CPU1_RESET_N")
	)
	(arc
		(start 144.861788 -250.641866)
		(mid 145.144744 -250.718043)
		(end 145.4277 -250.641866)
		(width 0.0889)
		(layer "In2.Cu")
		(net "M_I_CPU1_RESET_N")
	)
	(arc
		(start 133.216142 -250.63704)
		(mid 133.39965 -250.591546)
		(end 133.581902 -250.641866)
		(width 0.0889)
		(layer "In2.Cu")
		(net "M_I_CPU1_RESET_N")
	)
	(arc
		(start 133.581902 -250.641866)
		(mid 133.864858 -250.718043)
		(end 134.147814 -250.641866)
		(width 0.0889)
		(layer "In2.Cu")
		(net "M_I_CPU1_RESET_N")
	)
	(arc
		(start 131.701794 -250.641866)
		(mid 131.98475 -250.718043)
		(end 132.267706 -250.641866)
		(width 0.0889)
		(layer "In2.Cu")
		(net "M_I_CPU1_RESET_N")
	)
	(arc
		(start 140.727684 -250.641866)
		(mid 140.909935 -250.591516)
		(end 141.093444 -250.63704)
		(width 0.0889)
		(layer "In2.Cu")
		(net "M_I_CPU1_RESET_N")
	)
	(arc
		(start 132.276088 -250.63704)
		(mid 132.459596 -250.591546)
		(end 132.641848 -250.641866)
		(width 0.0889)
		(layer "In2.Cu")
		(net "M_I_CPU1_RESET_N")
	)
	(arc
		(start 146.06905 -250.59132)
		(mid 146.558425 -250.657)
		(end 147.013168 -250.849384)
		(width 0.0889)
		(layer "In2.Cu")
		(net "M_I_CPU1_RESET_N")
	)
	(arc
		(start 137.916158 -250.63704)
		(mid 138.099666 -250.591546)
		(end 138.281918 -250.641866)
		(width 0.0889)
		(layer "In2.Cu")
		(net "M_I_CPU1_RESET_N")
	)
	(arc
		(start 135.087614 -250.641866)
		(mid 135.269865 -250.591516)
		(end 135.453374 -250.63704)
		(width 0.0889)
		(layer "In2.Cu")
		(net "M_I_CPU1_RESET_N")
	)
	(arc
		(start 143.547592 -250.641866)
		(mid 143.729843 -250.591516)
		(end 143.913352 -250.63704)
		(width 0.0889)
		(layer "In2.Cu")
		(net "M_I_CPU1_RESET_N")
	)
	(arc
		(start 128.881886 -250.641866)
		(mid 129.164842 -250.718043)
		(end 129.447798 -250.641866)
		(width 0.0889)
		(layer "In2.Cu")
		(net "M_I_CPU1_RESET_N")
	)
	(arc
		(start 136.976104 -250.63704)
		(mid 137.159612 -250.591546)
		(end 137.341864 -250.641866)
		(width 0.0889)
		(layer "In2.Cu")
		(net "M_I_CPU1_RESET_N")
	)
	(arc
		(start 135.461756 -250.641866)
		(mid 135.744712 -250.718043)
		(end 136.027668 -250.641866)
		(width 0.0889)
		(layer "In2.Cu")
		(net "M_I_CPU1_RESET_N")
	)
	(arc
		(start 128.005078 -250.673616)
		(mid 128.260143 -250.716967)
		(end 128.507744 -250.641866)
		(width 0.0889)
		(layer "In2.Cu")
		(net "M_I_CPU1_RESET_N")
	)
	(segment
		(start 129.16789 -256.09042)
		(end 129.634742 -255.824482)
		(width 0.14732)
		(layer "F.Cu")
		(net "M_I_CPU1_CLK_DP<0>")
	)
	(segment
		(start 146.094958 -256.793492)
		(end 145.746978 -256.445512)
		(width 0.09525)
		(layer "In2.Cu")
		(net "M_I_CPU1_CLK_DP<0>")
	)
	(segment
		(start 171.186856 -256.356866)
		(end 170.849798 -256.693924)
		(width 0.16002)
		(layer "In2.Cu")
		(net "M_I_CPU1_CLK_DP<0>")
	)
	(segment
		(start 152.558242 -255.929638)
		(end 151.447754 -257.040126)
		(width 0.16002)
		(layer "In2.Cu")
		(net "M_I_CPU1_CLK_DP<0>")
	)
	(segment
		(start 131.703318 -256.149602)
		(end 131.694936 -256.154428)
		(width 0.09525)
		(layer "In2.Cu")
		(net "M_I_CPU1_CLK_DP<0>")
	)
	(segment
		(start 155.528518 -255.929638)
		(end 152.558242 -255.929638)
		(width 0.16002)
		(layer "In2.Cu")
		(net "M_I_CPU1_CLK_DP<0>")
	)
	(segment
		(start 136.403334 -256.149602)
		(end 136.394952 -256.154428)
		(width 0.09525)
		(layer "In2.Cu")
		(net "M_I_CPU1_CLK_DP<0>")
	)
	(segment
		(start 170.079924 -256.693924)
		(end 169.742866 -256.356866)
		(width 0.16002)
		(layer "In2.Cu")
		(net "M_I_CPU1_CLK_DP<0>")
	)
	(segment
		(start 136.97458 -256.154428)
		(end 136.966198 -256.149602)
		(width 0.09525)
		(layer "In2.Cu")
		(net "M_I_CPU1_CLK_DP<0>")
	)
	(segment
		(start 144.516348 -256.16789)
		(end 144.484344 -256.149348)
		(width 0.09525)
		(layer "In2.Cu")
		(net "M_I_CPU1_CLK_DP<0>")
	)
	(segment
		(start 143.923258 -256.149602)
		(end 143.914876 -256.154428)
		(width 0.09525)
		(layer "In2.Cu")
		(net "M_I_CPU1_CLK_DP<0>")
	)
	(segment
		(start 145.424144 -256.149348)
		(end 145.388838 -256.129028)
		(width 0.09525)
		(layer "In2.Cu")
		(net "M_I_CPU1_CLK_DP<0>")
	)
	(segment
		(start 129.503932 -256.176526)
		(end 129.480818 -256.089912)
		(width 0.09525)
		(layer "In2.Cu")
		(net "M_I_CPU1_CLK_DP<0>")
	)
	(segment
		(start 170.079924 -257.052318)
		(end 170.079924 -256.693924)
		(width 0.16002)
		(layer "In2.Cu")
		(net "M_I_CPU1_CLK_DP<0>")
	)
	(segment
		(start 168.70553 -257.052318)
		(end 168.54551 -257.212338)
		(width 0.16002)
		(layer "In2.Cu")
		(net "M_I_CPU1_CLK_DP<0>")
	)
	(segment
		(start 176.042828 -256.356866)
		(end 175.562768 -256.356866)
		(width 0.16002)
		(layer "In2.Cu")
		(net "M_I_CPU1_CLK_DP<0>")
	)
	(segment
		(start 177.236628 -256.356866)
		(end 176.756568 -256.356866)
		(width 0.16002)
		(layer "In2.Cu")
		(net "M_I_CPU1_CLK_DP<0>")
	)
	(segment
		(start 130.763264 -256.149602)
		(end 130.754882 -256.154428)
		(width 0.09525)
		(layer "In2.Cu")
		(net "M_I_CPU1_CLK_DP<0>")
	)
	(segment
		(start 179.516024 -253.435358)
		(end 179.241196 -253.710186)
		(width 0.16002)
		(layer "In2.Cu")
		(net "M_I_CPU1_CLK_DP<0>")
	)
	(segment
		(start 145.747486 -256.445258)
		(end 145.54073 -256.238502)
		(width 0.09525)
		(layer "In2.Cu")
		(net "M_I_CPU1_CLK_DP<0>")
	)
	(segment
		(start 146.195542 -256.810256)
		(end 146.178778 -256.793492)
		(width 0.09525)
		(layer "In2.Cu")
		(net "M_I_CPU1_CLK_DP<0>")
	)
	(segment
		(start 174.849028 -256.356866)
		(end 171.186856 -256.356866)
		(width 0.16002)
		(layer "In2.Cu")
		(net "M_I_CPU1_CLK_DP<0>")
	)
	(segment
		(start 176.159668 -256.240026)
		(end 176.042828 -256.356866)
		(width 0.16002)
		(layer "In2.Cu")
		(net "M_I_CPU1_CLK_DP<0>")
	)
	(segment
		(start 146.178778 -256.793492)
		(end 146.094958 -256.793492)
		(width 0.09525)
		(layer "In2.Cu")
		(net "M_I_CPU1_CLK_DP<0>")
	)
	(segment
		(start 129.480818 -256.089912)
		(end 129.634742 -255.824482)
		(width 0.09525)
		(layer "In2.Cu")
		(net "M_I_CPU1_CLK_DP<0>")
	)
	(segment
		(start 144.484344 -256.149348)
		(end 144.460468 -256.135632)
		(width 0.09525)
		(layer "In2.Cu")
		(net "M_I_CPU1_CLK_DP<0>")
	)
	(segment
		(start 169.042588 -256.356866)
		(end 168.70553 -256.693924)
		(width 0.16002)
		(layer "In2.Cu")
		(net "M_I_CPU1_CLK_DP<0>")
	)
	(segment
		(start 178.11877 -255.474724)
		(end 177.236628 -256.356866)
		(width 0.16002)
		(layer "In2.Cu")
		(net "M_I_CPU1_CLK_DP<0>")
	)
	(segment
		(start 175.445928 -256.240026)
		(end 174.965868 -256.240026)
		(width 0.16002)
		(layer "In2.Cu")
		(net "M_I_CPU1_CLK_DP<0>")
	)
	(segment
		(start 170.849798 -257.052318)
		(end 170.689778 -257.212338)
		(width 0.16002)
		(layer "In2.Cu")
		(net "M_I_CPU1_CLK_DP<0>")
	)
	(segment
		(start 170.849798 -256.693924)
		(end 170.849798 -257.052318)
		(width 0.16002)
		(layer "In2.Cu")
		(net "M_I_CPU1_CLK_DP<0>")
	)
	(segment
		(start 170.689778 -257.212338)
		(end 170.239944 -257.212338)
		(width 0.16002)
		(layer "In2.Cu")
		(net "M_I_CPU1_CLK_DP<0>")
	)
	(segment
		(start 178.11877 -254.123444)
		(end 178.11877 -255.474724)
		(width 0.16002)
		(layer "In2.Cu")
		(net "M_I_CPU1_CLK_DP<0>")
	)
	(segment
		(start 174.965868 -256.240026)
		(end 174.849028 -256.356866)
		(width 0.16002)
		(layer "In2.Cu")
		(net "M_I_CPU1_CLK_DP<0>")
	)
	(segment
		(start 167.935656 -256.693924)
		(end 167.598598 -256.356866)
		(width 0.16002)
		(layer "In2.Cu")
		(net "M_I_CPU1_CLK_DP<0>")
	)
	(segment
		(start 175.562768 -256.356866)
		(end 175.445928 -256.240026)
		(width 0.16002)
		(layer "In2.Cu")
		(net "M_I_CPU1_CLK_DP<0>")
	)
	(segment
		(start 167.935656 -257.052318)
		(end 167.935656 -256.693924)
		(width 0.16002)
		(layer "In2.Cu")
		(net "M_I_CPU1_CLK_DP<0>")
	)
	(segment
		(start 167.598598 -256.356866)
		(end 155.955746 -256.356866)
		(width 0.16002)
		(layer "In2.Cu")
		(net "M_I_CPU1_CLK_DP<0>")
	)
	(segment
		(start 169.742866 -256.356866)
		(end 169.042588 -256.356866)
		(width 0.16002)
		(layer "In2.Cu")
		(net "M_I_CPU1_CLK_DP<0>")
	)
	(segment
		(start 168.54551 -257.212338)
		(end 168.095676 -257.212338)
		(width 0.16002)
		(layer "In2.Cu")
		(net "M_I_CPU1_CLK_DP<0>")
	)
	(segment
		(start 141.674596 -256.154428)
		(end 141.666214 -256.149602)
		(width 0.09525)
		(layer "In2.Cu")
		(net "M_I_CPU1_CLK_DP<0>")
	)
	(segment
		(start 137.914634 -256.154428)
		(end 137.906252 -256.149602)
		(width 0.09525)
		(layer "In2.Cu")
		(net "M_I_CPU1_CLK_DP<0>")
	)
	(segment
		(start 140.163296 -256.149602)
		(end 140.154914 -256.154428)
		(width 0.09525)
		(layer "In2.Cu")
		(net "M_I_CPU1_CLK_DP<0>")
	)
	(segment
		(start 133.214618 -256.154428)
		(end 133.206236 -256.149602)
		(width 0.09525)
		(layer "In2.Cu")
		(net "M_I_CPU1_CLK_DP<0>")
	)
	(segment
		(start 155.955746 -256.356866)
		(end 155.528518 -255.929638)
		(width 0.16002)
		(layer "In2.Cu")
		(net "M_I_CPU1_CLK_DP<0>")
	)
	(segment
		(start 145.746978 -256.445512)
		(end 145.747486 -256.445258)
		(width 0.09525)
		(layer "In2.Cu")
		(net "M_I_CPU1_CLK_DP<0>")
	)
	(segment
		(start 170.239944 -257.212338)
		(end 170.079924 -257.052318)
		(width 0.16002)
		(layer "In2.Cu")
		(net "M_I_CPU1_CLK_DP<0>")
	)
	(segment
		(start 179.241196 -253.710186)
		(end 178.532028 -253.710186)
		(width 0.16002)
		(layer "In2.Cu")
		(net "M_I_CPU1_CLK_DP<0>")
	)
	(segment
		(start 168.70553 -256.693924)
		(end 168.70553 -257.052318)
		(width 0.16002)
		(layer "In2.Cu")
		(net "M_I_CPU1_CLK_DP<0>")
	)
	(segment
		(start 141.10335 -256.149602)
		(end 141.094968 -256.154428)
		(width 0.09525)
		(layer "In2.Cu")
		(net "M_I_CPU1_CLK_DP<0>")
	)
	(segment
		(start 132.274564 -256.154428)
		(end 132.266182 -256.149602)
		(width 0.09525)
		(layer "In2.Cu")
		(net "M_I_CPU1_CLK_DP<0>")
	)
	(segment
		(start 176.756568 -256.356866)
		(end 176.639728 -256.240026)
		(width 0.16002)
		(layer "In2.Cu")
		(net "M_I_CPU1_CLK_DP<0>")
	)
	(segment
		(start 176.639728 -256.240026)
		(end 176.159668 -256.240026)
		(width 0.16002)
		(layer "In2.Cu")
		(net "M_I_CPU1_CLK_DP<0>")
	)
	(segment
		(start 151.447754 -257.040126)
		(end 146.425412 -257.040126)
		(width 0.16002)
		(layer "In2.Cu")
		(net "M_I_CPU1_CLK_DP<0>")
	)
	(segment
		(start 146.425412 -257.040126)
		(end 146.195542 -256.810256)
		(width 0.16002)
		(layer "In2.Cu")
		(net "M_I_CPU1_CLK_DP<0>")
	)
	(segment
		(start 135.46328 -256.149602)
		(end 135.454898 -256.154428)
		(width 0.09525)
		(layer "In2.Cu")
		(net "M_I_CPU1_CLK_DP<0>")
	)
	(segment
		(start 178.532028 -253.710186)
		(end 178.11877 -254.123444)
		(width 0.16002)
		(layer "In2.Cu")
		(net "M_I_CPU1_CLK_DP<0>")
	)
	(segment
		(start 168.095676 -257.212338)
		(end 167.935656 -257.052318)
		(width 0.16002)
		(layer "In2.Cu")
		(net "M_I_CPU1_CLK_DP<0>")
	)
	(arc
		(start 133.206236 -256.149602)
		(mid 132.924804 -256.073847)
		(end 132.643372 -256.149602)
		(width 0.09525)
		(layer "In2.Cu")
		(net "M_I_CPU1_CLK_DP<0>")
	)
	(arc
		(start 131.326128 -256.149602)
		(mid 131.044696 -256.073847)
		(end 130.763264 -256.149602)
		(width 0.09525)
		(layer "In2.Cu")
		(net "M_I_CPU1_CLK_DP<0>")
	)
	(arc
		(start 144.460468 -256.135632)
		(mid 144.190085 -256.074072)
		(end 143.923258 -256.149602)
		(width 0.09525)
		(layer "In2.Cu")
		(net "M_I_CPU1_CLK_DP<0>")
	)
	(arc
		(start 134.14629 -256.149602)
		(mid 133.864858 -256.073847)
		(end 133.583426 -256.149602)
		(width 0.09525)
		(layer "In2.Cu")
		(net "M_I_CPU1_CLK_DP<0>")
	)
	(arc
		(start 136.966198 -256.149602)
		(mid 136.684766 -256.073847)
		(end 136.403334 -256.149602)
		(width 0.09525)
		(layer "In2.Cu")
		(net "M_I_CPU1_CLK_DP<0>")
	)
	(arc
		(start 138.283442 -256.149602)
		(mid 138.099667 -256.200374)
		(end 137.914634 -256.154428)
		(width 0.09525)
		(layer "In2.Cu")
		(net "M_I_CPU1_CLK_DP<0>")
	)
	(arc
		(start 143.914876 -256.154428)
		(mid 143.729844 -256.200342)
		(end 143.546068 -256.149602)
		(width 0.09525)
		(layer "In2.Cu")
		(net "M_I_CPU1_CLK_DP<0>")
	)
	(arc
		(start 132.643372 -256.149602)
		(mid 132.459597 -256.200374)
		(end 132.274564 -256.154428)
		(width 0.09525)
		(layer "In2.Cu")
		(net "M_I_CPU1_CLK_DP<0>")
	)
	(arc
		(start 134.523226 -256.149602)
		(mid 134.334758 -256.200279)
		(end 134.14629 -256.149602)
		(width 0.09525)
		(layer "In2.Cu")
		(net "M_I_CPU1_CLK_DP<0>")
	)
	(arc
		(start 140.72616 -256.149602)
		(mid 140.444728 -256.073847)
		(end 140.163296 -256.149602)
		(width 0.09525)
		(layer "In2.Cu")
		(net "M_I_CPU1_CLK_DP<0>")
	)
	(arc
		(start 140.154914 -256.154428)
		(mid 139.969882 -256.200342)
		(end 139.786106 -256.149602)
		(width 0.09525)
		(layer "In2.Cu")
		(net "M_I_CPU1_CLK_DP<0>")
	)
	(arc
		(start 136.026144 -256.149602)
		(mid 135.744712 -256.073847)
		(end 135.46328 -256.149602)
		(width 0.09525)
		(layer "In2.Cu")
		(net "M_I_CPU1_CLK_DP<0>")
	)
	(arc
		(start 141.094968 -256.154428)
		(mid 140.909936 -256.200342)
		(end 140.72616 -256.149602)
		(width 0.09525)
		(layer "In2.Cu")
		(net "M_I_CPU1_CLK_DP<0>")
	)
	(arc
		(start 133.583426 -256.149602)
		(mid 133.399651 -256.200374)
		(end 133.214618 -256.154428)
		(width 0.09525)
		(layer "In2.Cu")
		(net "M_I_CPU1_CLK_DP<0>")
	)
	(arc
		(start 129.82321 -256.149602)
		(mid 129.666583 -256.198788)
		(end 129.503932 -256.176526)
		(width 0.09525)
		(layer "In2.Cu")
		(net "M_I_CPU1_CLK_DP<0>")
	)
	(arc
		(start 137.343388 -256.149602)
		(mid 137.159613 -256.200374)
		(end 136.97458 -256.154428)
		(width 0.09525)
		(layer "In2.Cu")
		(net "M_I_CPU1_CLK_DP<0>")
	)
	(arc
		(start 135.08609 -256.149602)
		(mid 134.804658 -256.073847)
		(end 134.523226 -256.149602)
		(width 0.09525)
		(layer "In2.Cu")
		(net "M_I_CPU1_CLK_DP<0>")
	)
	(arc
		(start 141.666214 -256.149602)
		(mid 141.384782 -256.073847)
		(end 141.10335 -256.149602)
		(width 0.09525)
		(layer "In2.Cu")
		(net "M_I_CPU1_CLK_DP<0>")
	)
	(arc
		(start 138.846306 -256.149602)
		(mid 138.564874 -256.073847)
		(end 138.283442 -256.149602)
		(width 0.09525)
		(layer "In2.Cu")
		(net "M_I_CPU1_CLK_DP<0>")
	)
	(arc
		(start 135.454898 -256.154428)
		(mid 135.269866 -256.200342)
		(end 135.08609 -256.149602)
		(width 0.09525)
		(layer "In2.Cu")
		(net "M_I_CPU1_CLK_DP<0>")
	)
	(arc
		(start 145.388838 -256.129028)
		(mid 145.122586 -256.073613)
		(end 144.861534 -256.149856)
		(width 0.09525)
		(layer "In2.Cu")
		(net "M_I_CPU1_CLK_DP<0>")
	)
	(arc
		(start 143.546068 -256.149602)
		(mid 143.264636 -256.073847)
		(end 142.983204 -256.149602)
		(width 0.09525)
		(layer "In2.Cu")
		(net "M_I_CPU1_CLK_DP<0>")
	)
	(arc
		(start 131.694936 -256.154428)
		(mid 131.509904 -256.200342)
		(end 131.326128 -256.149602)
		(width 0.09525)
		(layer "In2.Cu")
		(net "M_I_CPU1_CLK_DP<0>")
	)
	(arc
		(start 142.043404 -256.149602)
		(mid 141.859629 -256.200374)
		(end 141.674596 -256.154428)
		(width 0.09525)
		(layer "In2.Cu")
		(net "M_I_CPU1_CLK_DP<0>")
	)
	(arc
		(start 145.54073 -256.238502)
		(mid 145.485377 -256.19008)
		(end 145.424144 -256.149348)
		(width 0.09525)
		(layer "In2.Cu")
		(net "M_I_CPU1_CLK_DP<0>")
	)
	(arc
		(start 142.606268 -256.149602)
		(mid 142.324836 -256.073847)
		(end 142.043404 -256.149602)
		(width 0.09525)
		(layer "In2.Cu")
		(net "M_I_CPU1_CLK_DP<0>")
	)
	(arc
		(start 130.386074 -256.149602)
		(mid 130.104642 -256.073847)
		(end 129.82321 -256.149602)
		(width 0.09525)
		(layer "In2.Cu")
		(net "M_I_CPU1_CLK_DP<0>")
	)
	(arc
		(start 139.786106 -256.149602)
		(mid 139.504674 -256.073847)
		(end 139.223242 -256.149602)
		(width 0.09525)
		(layer "In2.Cu")
		(net "M_I_CPU1_CLK_DP<0>")
	)
	(arc
		(start 144.861534 -256.149856)
		(mid 144.691137 -256.200755)
		(end 144.516348 -256.16789)
		(width 0.09525)
		(layer "In2.Cu")
		(net "M_I_CPU1_CLK_DP<0>")
	)
	(arc
		(start 132.266182 -256.149602)
		(mid 131.98475 -256.073847)
		(end 131.703318 -256.149602)
		(width 0.09525)
		(layer "In2.Cu")
		(net "M_I_CPU1_CLK_DP<0>")
	)
	(arc
		(start 136.394952 -256.154428)
		(mid 136.20992 -256.200342)
		(end 136.026144 -256.149602)
		(width 0.09525)
		(layer "In2.Cu")
		(net "M_I_CPU1_CLK_DP<0>")
	)
	(arc
		(start 139.223242 -256.149602)
		(mid 139.034774 -256.200279)
		(end 138.846306 -256.149602)
		(width 0.09525)
		(layer "In2.Cu")
		(net "M_I_CPU1_CLK_DP<0>")
	)
	(arc
		(start 137.906252 -256.149602)
		(mid 137.62482 -256.073847)
		(end 137.343388 -256.149602)
		(width 0.09525)
		(layer "In2.Cu")
		(net "M_I_CPU1_CLK_DP<0>")
	)
	(arc
		(start 142.983204 -256.149602)
		(mid 142.794736 -256.200279)
		(end 142.606268 -256.149602)
		(width 0.09525)
		(layer "In2.Cu")
		(net "M_I_CPU1_CLK_DP<0>")
	)
	(arc
		(start 130.754882 -256.154428)
		(mid 130.56985 -256.200342)
		(end 130.386074 -256.149602)
		(width 0.09525)
		(layer "In2.Cu")
		(net "M_I_CPU1_CLK_DP<0>")
	)
	(segment
		(start 128.69799 -256.900426)
		(end 129.164842 -256.634488)
		(width 0.14732)
		(layer "F.Cu")
		(net "M_I_CPU1_CLK_DN<0>")
	)
	(segment
		(start 167.970454 -257.514598)
		(end 167.633396 -257.17754)
		(width 0.16002)
		(layer "In2.Cu")
		(net "M_I_CPU1_CLK_DN<0>")
	)
	(segment
		(start 145.616676 -256.575814)
		(end 145.410428 -256.369058)
		(width 0.09525)
		(layer "In2.Cu")
		(net "M_I_CPU1_CLK_DN<0>")
	)
	(segment
		(start 169.617644 -256.659126)
		(end 169.16781 -256.659126)
		(width 0.16002)
		(layer "In2.Cu")
		(net "M_I_CPU1_CLK_DN<0>")
	)
	(segment
		(start 171.312078 -256.659126)
		(end 171.152058 -256.819146)
		(width 0.16002)
		(layer "In2.Cu")
		(net "M_I_CPU1_CLK_DN<0>")
	)
	(segment
		(start 179.516024 -254.285242)
		(end 179.243228 -254.012446)
		(width 0.16002)
		(layer "In2.Cu")
		(net "M_I_CPU1_CLK_DN<0>")
	)
	(segment
		(start 169.00779 -257.17754)
		(end 168.670732 -257.514598)
		(width 0.16002)
		(layer "In2.Cu")
		(net "M_I_CPU1_CLK_DN<0>")
	)
	(segment
		(start 140.264642 -256.304542)
		(end 140.25626 -256.309368)
		(width 0.09525)
		(layer "In2.Cu")
		(net "M_I_CPU1_CLK_DN<0>")
	)
	(segment
		(start 178.65725 -254.012446)
		(end 178.42103 -254.248666)
		(width 0.16002)
		(layer "In2.Cu")
		(net "M_I_CPU1_CLK_DN<0>")
	)
	(segment
		(start 169.777664 -257.17754)
		(end 169.777664 -256.819146)
		(width 0.16002)
		(layer "In2.Cu")
		(net "M_I_CPU1_CLK_DN<0>")
	)
	(segment
		(start 169.777664 -256.819146)
		(end 169.617644 -256.659126)
		(width 0.16002)
		(layer "In2.Cu")
		(net "M_I_CPU1_CLK_DN<0>")
	)
	(segment
		(start 167.633396 -256.819146)
		(end 167.473376 -256.659126)
		(width 0.16002)
		(layer "In2.Cu")
		(net "M_I_CPU1_CLK_DN<0>")
	)
	(segment
		(start 152.683464 -256.231898)
		(end 151.572976 -257.342386)
		(width 0.16002)
		(layer "In2.Cu")
		(net "M_I_CPU1_CLK_DN<0>")
	)
	(segment
		(start 145.410428 -256.369058)
		(end 145.410428 -256.368804)
		(width 0.09525)
		(layer "In2.Cu")
		(net "M_I_CPU1_CLK_DN<0>")
	)
	(segment
		(start 170.114722 -257.514598)
		(end 169.777664 -257.17754)
		(width 0.16002)
		(layer "In2.Cu")
		(net "M_I_CPU1_CLK_DN<0>")
	)
	(segment
		(start 171.152058 -257.17754)
		(end 170.815 -257.514598)
		(width 0.16002)
		(layer "In2.Cu")
		(net "M_I_CPU1_CLK_DN<0>")
	)
	(segment
		(start 137.813288 -256.309368)
		(end 137.804906 -256.304542)
		(width 0.09525)
		(layer "In2.Cu")
		(net "M_I_CPU1_CLK_DN<0>")
	)
	(segment
		(start 134.053326 -256.309368)
		(end 134.044944 -256.304542)
		(width 0.09525)
		(layer "In2.Cu")
		(net "M_I_CPU1_CLK_DN<0>")
	)
	(segment
		(start 129.318766 -256.369058)
		(end 129.164842 -256.634488)
		(width 0.09525)
		(layer "In2.Cu")
		(net "M_I_CPU1_CLK_DN<0>")
	)
	(segment
		(start 129.419604 -256.342388)
		(end 129.318766 -256.369058)
		(width 0.09525)
		(layer "In2.Cu")
		(net "M_I_CPU1_CLK_DN<0>")
	)
	(segment
		(start 171.152058 -256.819146)
		(end 171.152058 -257.17754)
		(width 0.16002)
		(layer "In2.Cu")
		(net "M_I_CPU1_CLK_DN<0>")
	)
	(segment
		(start 179.243228 -254.012446)
		(end 178.65725 -254.012446)
		(width 0.16002)
		(layer "In2.Cu")
		(net "M_I_CPU1_CLK_DN<0>")
	)
	(segment
		(start 139.324588 -256.304542)
		(end 139.316206 -256.309368)
		(width 0.09525)
		(layer "In2.Cu")
		(net "M_I_CPU1_CLK_DN<0>")
	)
	(segment
		(start 167.633396 -257.17754)
		(end 167.633396 -256.819146)
		(width 0.16002)
		(layer "In2.Cu")
		(net "M_I_CPU1_CLK_DN<0>")
	)
	(segment
		(start 169.16781 -256.659126)
		(end 169.00779 -256.819146)
		(width 0.16002)
		(layer "In2.Cu")
		(net "M_I_CPU1_CLK_DN<0>")
	)
	(segment
		(start 145.981928 -257.024124)
		(end 145.965164 -257.00736)
		(width 0.09525)
		(layer "In2.Cu")
		(net "M_I_CPU1_CLK_DN<0>")
	)
	(segment
		(start 145.965164 -257.00736)
		(end 145.965164 -256.924556)
		(width 0.09525)
		(layer "In2.Cu")
		(net "M_I_CPU1_CLK_DN<0>")
	)
	(segment
		(start 169.00779 -256.819146)
		(end 169.00779 -257.17754)
		(width 0.16002)
		(layer "In2.Cu")
		(net "M_I_CPU1_CLK_DN<0>")
	)
	(segment
		(start 145.331942 -256.309622)
		(end 145.299938 -256.29108)
		(width 0.09525)
		(layer "In2.Cu")
		(net "M_I_CPU1_CLK_DN<0>")
	)
	(segment
		(start 135.564626 -256.304542)
		(end 135.556244 -256.309368)
		(width 0.09525)
		(layer "In2.Cu")
		(net "M_I_CPU1_CLK_DN<0>")
	)
	(segment
		(start 133.113272 -256.309368)
		(end 133.10489 -256.304542)
		(width 0.09525)
		(layer "In2.Cu")
		(net "M_I_CPU1_CLK_DN<0>")
	)
	(segment
		(start 170.815 -257.514598)
		(end 170.114722 -257.514598)
		(width 0.16002)
		(layer "In2.Cu")
		(net "M_I_CPU1_CLK_DN<0>")
	)
	(segment
		(start 144.391888 -256.309622)
		(end 144.370044 -256.297176)
		(width 0.09525)
		(layer "In2.Cu")
		(net "M_I_CPU1_CLK_DN<0>")
	)
	(segment
		(start 155.830524 -256.659126)
		(end 155.403296 -256.231898)
		(width 0.16002)
		(layer "In2.Cu")
		(net "M_I_CPU1_CLK_DN<0>")
	)
	(segment
		(start 129.924556 -256.304542)
		(end 129.916174 -256.309368)
		(width 0.09525)
		(layer "In2.Cu")
		(net "M_I_CPU1_CLK_DN<0>")
	)
	(segment
		(start 142.513304 -256.309368)
		(end 142.504922 -256.304542)
		(width 0.09525)
		(layer "In2.Cu")
		(net "M_I_CPU1_CLK_DN<0>")
	)
	(segment
		(start 167.473376 -256.659126)
		(end 155.830524 -256.659126)
		(width 0.16002)
		(layer "In2.Cu")
		(net "M_I_CPU1_CLK_DN<0>")
	)
	(segment
		(start 178.42103 -255.599946)
		(end 177.36185 -256.659126)
		(width 0.16002)
		(layer "In2.Cu")
		(net "M_I_CPU1_CLK_DN<0>")
	)
	(segment
		(start 168.670732 -257.514598)
		(end 167.970454 -257.514598)
		(width 0.16002)
		(layer "In2.Cu")
		(net "M_I_CPU1_CLK_DN<0>")
	)
	(segment
		(start 146.30019 -257.342386)
		(end 145.981928 -257.024124)
		(width 0.16002)
		(layer "In2.Cu")
		(net "M_I_CPU1_CLK_DN<0>")
	)
	(segment
		(start 178.42103 -254.248666)
		(end 178.42103 -255.599946)
		(width 0.16002)
		(layer "In2.Cu")
		(net "M_I_CPU1_CLK_DN<0>")
	)
	(segment
		(start 151.572976 -257.342386)
		(end 146.30019 -257.342386)
		(width 0.16002)
		(layer "In2.Cu")
		(net "M_I_CPU1_CLK_DN<0>")
	)
	(segment
		(start 144.42567 -256.32918)
		(end 144.391888 -256.309622)
		(width 0.09525)
		(layer "In2.Cu")
		(net "M_I_CPU1_CLK_DN<0>")
	)
	(segment
		(start 134.624572 -256.304542)
		(end 134.61619 -256.309368)
		(width 0.09525)
		(layer "In2.Cu")
		(net "M_I_CPU1_CLK_DN<0>")
	)
	(segment
		(start 155.403296 -256.231898)
		(end 152.683464 -256.231898)
		(width 0.16002)
		(layer "In2.Cu")
		(net "M_I_CPU1_CLK_DN<0>")
	)
	(segment
		(start 177.36185 -256.659126)
		(end 171.312078 -256.659126)
		(width 0.16002)
		(layer "In2.Cu")
		(net "M_I_CPU1_CLK_DN<0>")
	)
	(segment
		(start 143.08455 -256.304542)
		(end 143.076168 -256.309368)
		(width 0.09525)
		(layer "In2.Cu")
		(net "M_I_CPU1_CLK_DN<0>")
	)
	(segment
		(start 145.965164 -256.924556)
		(end 145.616676 -256.575814)
		(width 0.09525)
		(layer "In2.Cu")
		(net "M_I_CPU1_CLK_DN<0>")
	)
	(segment
		(start 130.86461 -256.304542)
		(end 130.856228 -256.309368)
		(width 0.09525)
		(layer "In2.Cu")
		(net "M_I_CPU1_CLK_DN<0>")
	)
	(segment
		(start 138.753342 -256.309368)
		(end 138.74496 -256.304542)
		(width 0.09525)
		(layer "In2.Cu")
		(net "M_I_CPU1_CLK_DN<0>")
	)
	(arc
		(start 136.496298 -256.309368)
		(mid 136.214866 -256.385123)
		(end 135.933434 -256.309368)
		(width 0.09525)
		(layer "In2.Cu")
		(net "M_I_CPU1_CLK_DN<0>")
	)
	(arc
		(start 140.25626 -256.309368)
		(mid 139.974828 -256.385123)
		(end 139.693396 -256.309368)
		(width 0.09525)
		(layer "In2.Cu")
		(net "M_I_CPU1_CLK_DN<0>")
	)
	(arc
		(start 141.57325 -256.309368)
		(mid 141.384782 -256.258691)
		(end 141.196314 -256.309368)
		(width 0.09525)
		(layer "In2.Cu")
		(net "M_I_CPU1_CLK_DN<0>")
	)
	(arc
		(start 131.796282 -256.309368)
		(mid 131.51485 -256.385123)
		(end 131.233418 -256.309368)
		(width 0.09525)
		(layer "In2.Cu")
		(net "M_I_CPU1_CLK_DN<0>")
	)
	(arc
		(start 130.293364 -256.309368)
		(mid 130.109589 -256.258596)
		(end 129.924556 -256.304542)
		(width 0.09525)
		(layer "In2.Cu")
		(net "M_I_CPU1_CLK_DN<0>")
	)
	(arc
		(start 144.954752 -256.309114)
		(mid 144.692734 -256.385398)
		(end 144.42567 -256.32918)
		(width 0.09525)
		(layer "In2.Cu")
		(net "M_I_CPU1_CLK_DN<0>")
	)
	(arc
		(start 139.316206 -256.309368)
		(mid 139.034774 -256.385123)
		(end 138.753342 -256.309368)
		(width 0.09525)
		(layer "In2.Cu")
		(net "M_I_CPU1_CLK_DN<0>")
	)
	(arc
		(start 129.439416 -256.350262)
		(mid 129.429473 -256.346419)
		(end 129.419604 -256.342388)
		(width 0.09525)
		(layer "In2.Cu")
		(net "M_I_CPU1_CLK_DN<0>")
	)
	(arc
		(start 135.556244 -256.309368)
		(mid 135.274812 -256.385123)
		(end 134.99338 -256.309368)
		(width 0.09525)
		(layer "In2.Cu")
		(net "M_I_CPU1_CLK_DN<0>")
	)
	(arc
		(start 140.63345 -256.309368)
		(mid 140.449675 -256.258596)
		(end 140.264642 -256.304542)
		(width 0.09525)
		(layer "In2.Cu")
		(net "M_I_CPU1_CLK_DN<0>")
	)
	(arc
		(start 132.736082 -256.309368)
		(mid 132.45465 -256.385123)
		(end 132.173218 -256.309368)
		(width 0.09525)
		(layer "In2.Cu")
		(net "M_I_CPU1_CLK_DN<0>")
	)
	(arc
		(start 136.873234 -256.309368)
		(mid 136.684766 -256.258691)
		(end 136.496298 -256.309368)
		(width 0.09525)
		(layer "In2.Cu")
		(net "M_I_CPU1_CLK_DN<0>")
	)
	(arc
		(start 139.693396 -256.309368)
		(mid 139.509621 -256.258596)
		(end 139.324588 -256.304542)
		(width 0.09525)
		(layer "In2.Cu")
		(net "M_I_CPU1_CLK_DN<0>")
	)
	(arc
		(start 142.136114 -256.309368)
		(mid 141.854682 -256.385123)
		(end 141.57325 -256.309368)
		(width 0.09525)
		(layer "In2.Cu")
		(net "M_I_CPU1_CLK_DN<0>")
	)
	(arc
		(start 134.044944 -256.304542)
		(mid 133.859912 -256.258628)
		(end 133.676136 -256.309368)
		(width 0.09525)
		(layer "In2.Cu")
		(net "M_I_CPU1_CLK_DN<0>")
	)
	(arc
		(start 145.410428 -256.368804)
		(mid 145.373126 -256.33664)
		(end 145.331942 -256.309622)
		(width 0.09525)
		(layer "In2.Cu")
		(net "M_I_CPU1_CLK_DN<0>")
	)
	(arc
		(start 141.196314 -256.309368)
		(mid 140.914882 -256.385123)
		(end 140.63345 -256.309368)
		(width 0.09525)
		(layer "In2.Cu")
		(net "M_I_CPU1_CLK_DN<0>")
	)
	(arc
		(start 142.504922 -256.304542)
		(mid 142.31989 -256.258628)
		(end 142.136114 -256.309368)
		(width 0.09525)
		(layer "In2.Cu")
		(net "M_I_CPU1_CLK_DN<0>")
	)
	(arc
		(start 133.676136 -256.309368)
		(mid 133.394704 -256.385123)
		(end 133.113272 -256.309368)
		(width 0.09525)
		(layer "In2.Cu")
		(net "M_I_CPU1_CLK_DN<0>")
	)
	(arc
		(start 130.856228 -256.309368)
		(mid 130.574796 -256.385123)
		(end 130.293364 -256.309368)
		(width 0.09525)
		(layer "In2.Cu")
		(net "M_I_CPU1_CLK_DN<0>")
	)
	(arc
		(start 133.10489 -256.304542)
		(mid 132.919858 -256.258628)
		(end 132.736082 -256.309368)
		(width 0.09525)
		(layer "In2.Cu")
		(net "M_I_CPU1_CLK_DN<0>")
	)
	(arc
		(start 129.916174 -256.309368)
		(mid 129.682379 -256.383235)
		(end 129.439416 -256.350262)
		(width 0.09525)
		(layer "In2.Cu")
		(net "M_I_CPU1_CLK_DN<0>")
	)
	(arc
		(start 134.99338 -256.309368)
		(mid 134.809605 -256.258596)
		(end 134.624572 -256.304542)
		(width 0.09525)
		(layer "In2.Cu")
		(net "M_I_CPU1_CLK_DN<0>")
	)
	(arc
		(start 145.299938 -256.29108)
		(mid 145.125146 -256.25815)
		(end 144.954752 -256.309114)
		(width 0.09525)
		(layer "In2.Cu")
		(net "M_I_CPU1_CLK_DN<0>")
	)
	(arc
		(start 143.076168 -256.309368)
		(mid 142.794736 -256.385123)
		(end 142.513304 -256.309368)
		(width 0.09525)
		(layer "In2.Cu")
		(net "M_I_CPU1_CLK_DN<0>")
	)
	(arc
		(start 134.61619 -256.309368)
		(mid 134.334758 -256.385123)
		(end 134.053326 -256.309368)
		(width 0.09525)
		(layer "In2.Cu")
		(net "M_I_CPU1_CLK_DN<0>")
	)
	(arc
		(start 144.370044 -256.297176)
		(mid 144.191592 -256.258934)
		(end 144.016222 -256.309368)
		(width 0.09525)
		(layer "In2.Cu")
		(net "M_I_CPU1_CLK_DN<0>")
	)
	(arc
		(start 132.173218 -256.309368)
		(mid 131.98475 -256.258691)
		(end 131.796282 -256.309368)
		(width 0.09525)
		(layer "In2.Cu")
		(net "M_I_CPU1_CLK_DN<0>")
	)
	(arc
		(start 144.016222 -256.309368)
		(mid 143.73479 -256.385123)
		(end 143.453358 -256.309368)
		(width 0.09525)
		(layer "In2.Cu")
		(net "M_I_CPU1_CLK_DN<0>")
	)
	(arc
		(start 138.376152 -256.309368)
		(mid 138.09472 -256.385123)
		(end 137.813288 -256.309368)
		(width 0.09525)
		(layer "In2.Cu")
		(net "M_I_CPU1_CLK_DN<0>")
	)
	(arc
		(start 137.436098 -256.309368)
		(mid 137.154666 -256.385123)
		(end 136.873234 -256.309368)
		(width 0.09525)
		(layer "In2.Cu")
		(net "M_I_CPU1_CLK_DN<0>")
	)
	(arc
		(start 135.933434 -256.309368)
		(mid 135.749659 -256.258596)
		(end 135.564626 -256.304542)
		(width 0.09525)
		(layer "In2.Cu")
		(net "M_I_CPU1_CLK_DN<0>")
	)
	(arc
		(start 131.233418 -256.309368)
		(mid 131.049643 -256.258596)
		(end 130.86461 -256.304542)
		(width 0.09525)
		(layer "In2.Cu")
		(net "M_I_CPU1_CLK_DN<0>")
	)
	(arc
		(start 138.74496 -256.304542)
		(mid 138.559928 -256.258628)
		(end 138.376152 -256.309368)
		(width 0.09525)
		(layer "In2.Cu")
		(net "M_I_CPU1_CLK_DN<0>")
	)
	(arc
		(start 137.804906 -256.304542)
		(mid 137.619874 -256.258628)
		(end 137.436098 -256.309368)
		(width 0.09525)
		(layer "In2.Cu")
		(net "M_I_CPU1_CLK_DN<0>")
	)
	(arc
		(start 143.453358 -256.309368)
		(mid 143.269583 -256.258596)
		(end 143.08455 -256.304542)
		(width 0.09525)
		(layer "In2.Cu")
		(net "M_I_CPU1_CLK_DN<0>")
	)
	(segment
		(start 127.757936 -250.420378)
		(end 128.224788 -250.15444)
		(width 0.10668)
		(layer "F.Cu")
		(net "M_I_CPU1_ALERT_R_N")
	)
	(segment
		(start 129.343404 -250.481846)
		(end 129.351786 -250.47702)
		(width 0.0889)
		(layer "In2.Cu")
		(net "M_I_CPU1_ALERT_R_N")
	)
	(segment
		(start 179.333652 -244.494304)
		(end 179.698396 -244.494304)
		(width 0.11684)
		(layer "In2.Cu")
		(net "M_I_CPU1_ALERT_R_N")
	)
	(segment
		(start 158.25851 -250.35764)
		(end 159.386016 -250.35764)
		(width 0.11684)
		(layer "In2.Cu")
		(net "M_I_CPU1_ALERT_R_N")
	)
	(segment
		(start 146.972274 -250.395486)
		(end 146.972528 -250.395232)
		(width 0.0889)
		(layer "In2.Cu")
		(net "M_I_CPU1_ALERT_R_N")
	)
	(segment
		(start 140.257784 -250.47702)
		(end 140.266166 -250.481846)
		(width 0.0889)
		(layer "In2.Cu")
		(net "M_I_CPU1_ALERT_R_N")
	)
	(segment
		(start 146.972528 -250.395232)
		(end 149.790912 -250.395232)
		(width 0.11684)
		(layer "In2.Cu")
		(net "M_I_CPU1_ALERT_R_N")
	)
	(segment
		(start 145.63471 -250.395486)
		(end 146.972274 -250.395486)
		(width 0.0889)
		(layer "In2.Cu")
		(net "M_I_CPU1_ALERT_R_N")
	)
	(segment
		(start 149.790912 -250.395232)
		(end 150.299928 -249.886216)
		(width 0.11684)
		(layer "In2.Cu")
		(net "M_I_CPU1_ALERT_R_N")
	)
	(segment
		(start 128.224788 -250.15444)
		(end 128.07061 -250.41987)
		(width 0.0889)
		(layer "In2.Cu")
		(net "M_I_CPU1_ALERT_R_N")
	)
	(segment
		(start 179.714398 -244.510306)
		(end 181.79415 -244.510306)
		(width 0.11684)
		(layer "In2.Cu")
		(net "M_I_CPU1_ALERT_R_N")
	)
	(segment
		(start 138.743436 -250.481846)
		(end 138.751818 -250.47702)
		(width 0.0889)
		(layer "In2.Cu")
		(net "M_I_CPU1_ALERT_R_N")
	)
	(segment
		(start 135.557768 -250.47702)
		(end 135.56615 -250.481846)
		(width 0.0889)
		(layer "In2.Cu")
		(net "M_I_CPU1_ALERT_R_N")
	)
	(segment
		(start 179.31765 -244.510306)
		(end 179.333652 -244.494304)
		(width 0.11684)
		(layer "In2.Cu")
		(net "M_I_CPU1_ALERT_R_N")
	)
	(segment
		(start 134.04342 -250.481846)
		(end 134.051802 -250.47702)
		(width 0.0889)
		(layer "In2.Cu")
		(net "M_I_CPU1_ALERT_R_N")
	)
	(segment
		(start 163.533328 -246.210328)
		(end 173.667166 -246.210328)
		(width 0.11684)
		(layer "In2.Cu")
		(net "M_I_CPU1_ALERT_R_N")
	)
	(segment
		(start 142.503398 -250.481846)
		(end 142.51178 -250.47702)
		(width 0.0889)
		(layer "In2.Cu")
		(net "M_I_CPU1_ALERT_R_N")
	)
	(segment
		(start 181.79415 -244.510306)
		(end 182.219092 -244.085364)
		(width 0.11684)
		(layer "In2.Cu")
		(net "M_I_CPU1_ALERT_R_N")
	)
	(segment
		(start 173.667166 -246.210328)
		(end 175.367188 -244.510306)
		(width 0.11684)
		(layer "In2.Cu")
		(net "M_I_CPU1_ALERT_R_N")
	)
	(segment
		(start 128.07061 -250.41987)
		(end 128.092962 -250.503182)
		(width 0.0889)
		(layer "In2.Cu")
		(net "M_I_CPU1_ALERT_R_N")
	)
	(segment
		(start 137.803382 -250.481846)
		(end 137.811764 -250.47702)
		(width 0.0889)
		(layer "In2.Cu")
		(net "M_I_CPU1_ALERT_R_N")
	)
	(segment
		(start 143.077692 -250.47702)
		(end 143.086074 -250.481846)
		(width 0.0889)
		(layer "In2.Cu")
		(net "M_I_CPU1_ALERT_R_N")
	)
	(segment
		(start 150.299928 -249.886216)
		(end 157.787086 -249.886216)
		(width 0.11684)
		(layer "In2.Cu")
		(net "M_I_CPU1_ALERT_R_N")
	)
	(segment
		(start 159.386016 -250.35764)
		(end 163.533328 -246.210328)
		(width 0.11684)
		(layer "In2.Cu")
		(net "M_I_CPU1_ALERT_R_N")
	)
	(segment
		(start 175.367188 -244.510306)
		(end 179.31765 -244.510306)
		(width 0.11684)
		(layer "In2.Cu")
		(net "M_I_CPU1_ALERT_R_N")
	)
	(segment
		(start 129.917698 -250.47702)
		(end 129.92608 -250.481846)
		(width 0.0889)
		(layer "In2.Cu")
		(net "M_I_CPU1_ALERT_R_N")
	)
	(segment
		(start 139.31773 -250.47702)
		(end 139.326112 -250.481846)
		(width 0.0889)
		(layer "In2.Cu")
		(net "M_I_CPU1_ALERT_R_N")
	)
	(segment
		(start 134.617714 -250.47702)
		(end 134.626096 -250.481846)
		(width 0.0889)
		(layer "In2.Cu")
		(net "M_I_CPU1_ALERT_R_N")
	)
	(segment
		(start 128.40335 -250.481846)
		(end 128.411732 -250.47702)
		(width 0.0889)
		(layer "In2.Cu")
		(net "M_I_CPU1_ALERT_R_N")
	)
	(segment
		(start 144.9578 -250.47702)
		(end 144.966182 -250.481846)
		(width 0.0889)
		(layer "In2.Cu")
		(net "M_I_CPU1_ALERT_R_N")
	)
	(segment
		(start 144.017746 -250.47702)
		(end 144.026128 -250.481846)
		(width 0.0889)
		(layer "In2.Cu")
		(net "M_I_CPU1_ALERT_R_N")
	)
	(segment
		(start 133.103366 -250.481846)
		(end 133.111748 -250.47702)
		(width 0.0889)
		(layer "In2.Cu")
		(net "M_I_CPU1_ALERT_R_N")
	)
	(segment
		(start 157.787086 -249.886216)
		(end 158.25851 -250.35764)
		(width 0.11684)
		(layer "In2.Cu")
		(net "M_I_CPU1_ALERT_R_N")
	)
	(segment
		(start 130.857752 -250.47702)
		(end 130.866134 -250.481846)
		(width 0.0889)
		(layer "In2.Cu")
		(net "M_I_CPU1_ALERT_R_N")
	)
	(segment
		(start 179.698396 -244.494304)
		(end 179.714398 -244.510306)
		(width 0.11684)
		(layer "In2.Cu")
		(net "M_I_CPU1_ALERT_R_N")
	)
	(arc
		(start 130.29184 -250.47702)
		(mid 130.574796 -250.400843)
		(end 130.857752 -250.47702)
		(width 0.0889)
		(layer "In2.Cu")
		(net "M_I_CPU1_ALERT_R_N")
	)
	(arc
		(start 137.811764 -250.47702)
		(mid 138.09472 -250.400843)
		(end 138.377676 -250.47702)
		(width 0.0889)
		(layer "In2.Cu")
		(net "M_I_CPU1_ALERT_R_N")
	)
	(arc
		(start 135.93191 -250.47702)
		(mid 136.214866 -250.400843)
		(end 136.497822 -250.47702)
		(width 0.0889)
		(layer "In2.Cu")
		(net "M_I_CPU1_ALERT_R_N")
	)
	(arc
		(start 136.87171 -250.47702)
		(mid 137.154666 -250.400843)
		(end 137.437622 -250.47702)
		(width 0.0889)
		(layer "In2.Cu")
		(net "M_I_CPU1_ALERT_R_N")
	)
	(arc
		(start 128.092962 -250.503182)
		(mid 128.250472 -250.52638)
		(end 128.40335 -250.481846)
		(width 0.0889)
		(layer "In2.Cu")
		(net "M_I_CPU1_ALERT_R_N")
	)
	(arc
		(start 133.67766 -250.47702)
		(mid 133.859911 -250.52737)
		(end 134.04342 -250.481846)
		(width 0.0889)
		(layer "In2.Cu")
		(net "M_I_CPU1_ALERT_R_N")
	)
	(arc
		(start 129.351786 -250.47702)
		(mid 129.634742 -250.400843)
		(end 129.917698 -250.47702)
		(width 0.0889)
		(layer "In2.Cu")
		(net "M_I_CPU1_ALERT_R_N")
	)
	(arc
		(start 141.197838 -250.47702)
		(mid 141.384782 -250.527275)
		(end 141.571726 -250.47702)
		(width 0.0889)
		(layer "In2.Cu")
		(net "M_I_CPU1_ALERT_R_N")
	)
	(arc
		(start 141.571726 -250.47702)
		(mid 141.854682 -250.400843)
		(end 142.137638 -250.47702)
		(width 0.0889)
		(layer "In2.Cu")
		(net "M_I_CPU1_ALERT_R_N")
	)
	(arc
		(start 133.111748 -250.47702)
		(mid 133.394704 -250.400843)
		(end 133.67766 -250.47702)
		(width 0.0889)
		(layer "In2.Cu")
		(net "M_I_CPU1_ALERT_R_N")
	)
	(arc
		(start 134.991856 -250.47702)
		(mid 135.274812 -250.400843)
		(end 135.557768 -250.47702)
		(width 0.0889)
		(layer "In2.Cu")
		(net "M_I_CPU1_ALERT_R_N")
	)
	(arc
		(start 142.51178 -250.47702)
		(mid 142.794736 -250.400843)
		(end 143.077692 -250.47702)
		(width 0.0889)
		(layer "In2.Cu")
		(net "M_I_CPU1_ALERT_R_N")
	)
	(arc
		(start 135.56615 -250.481846)
		(mid 135.749658 -250.52734)
		(end 135.93191 -250.47702)
		(width 0.0889)
		(layer "In2.Cu")
		(net "M_I_CPU1_ALERT_R_N")
	)
	(arc
		(start 128.411732 -250.47702)
		(mid 128.694688 -250.400843)
		(end 128.977644 -250.47702)
		(width 0.0889)
		(layer "In2.Cu")
		(net "M_I_CPU1_ALERT_R_N")
	)
	(arc
		(start 132.171694 -250.47702)
		(mid 132.45465 -250.400843)
		(end 132.737606 -250.47702)
		(width 0.0889)
		(layer "In2.Cu")
		(net "M_I_CPU1_ALERT_R_N")
	)
	(arc
		(start 143.086074 -250.481846)
		(mid 143.269582 -250.52734)
		(end 143.451834 -250.47702)
		(width 0.0889)
		(layer "In2.Cu")
		(net "M_I_CPU1_ALERT_R_N")
	)
	(arc
		(start 144.026128 -250.481846)
		(mid 144.209636 -250.52734)
		(end 144.391888 -250.47702)
		(width 0.0889)
		(layer "In2.Cu")
		(net "M_I_CPU1_ALERT_R_N")
	)
	(arc
		(start 137.437622 -250.47702)
		(mid 137.619873 -250.52737)
		(end 137.803382 -250.481846)
		(width 0.0889)
		(layer "In2.Cu")
		(net "M_I_CPU1_ALERT_R_N")
	)
	(arc
		(start 129.92608 -250.481846)
		(mid 130.109588 -250.52734)
		(end 130.29184 -250.47702)
		(width 0.0889)
		(layer "In2.Cu")
		(net "M_I_CPU1_ALERT_R_N")
	)
	(arc
		(start 131.797806 -250.47702)
		(mid 131.98475 -250.527275)
		(end 132.171694 -250.47702)
		(width 0.0889)
		(layer "In2.Cu")
		(net "M_I_CPU1_ALERT_R_N")
	)
	(arc
		(start 140.266166 -250.481846)
		(mid 140.449674 -250.52734)
		(end 140.631926 -250.47702)
		(width 0.0889)
		(layer "In2.Cu")
		(net "M_I_CPU1_ALERT_R_N")
	)
	(arc
		(start 130.866134 -250.481846)
		(mid 131.049642 -250.52734)
		(end 131.231894 -250.47702)
		(width 0.0889)
		(layer "In2.Cu")
		(net "M_I_CPU1_ALERT_R_N")
	)
	(arc
		(start 132.737606 -250.47702)
		(mid 132.919857 -250.52737)
		(end 133.103366 -250.481846)
		(width 0.0889)
		(layer "In2.Cu")
		(net "M_I_CPU1_ALERT_R_N")
	)
	(arc
		(start 145.331942 -250.47702)
		(mid 145.477934 -250.416234)
		(end 145.63471 -250.395486)
		(width 0.0889)
		(layer "In2.Cu")
		(net "M_I_CPU1_ALERT_R_N")
	)
	(arc
		(start 144.966182 -250.481846)
		(mid 145.14969 -250.52734)
		(end 145.331942 -250.47702)
		(width 0.0889)
		(layer "In2.Cu")
		(net "M_I_CPU1_ALERT_R_N")
	)
	(arc
		(start 144.391888 -250.47702)
		(mid 144.674844 -250.400843)
		(end 144.9578 -250.47702)
		(width 0.0889)
		(layer "In2.Cu")
		(net "M_I_CPU1_ALERT_R_N")
	)
	(arc
		(start 142.137638 -250.47702)
		(mid 142.319889 -250.52737)
		(end 142.503398 -250.481846)
		(width 0.0889)
		(layer "In2.Cu")
		(net "M_I_CPU1_ALERT_R_N")
	)
	(arc
		(start 131.231894 -250.47702)
		(mid 131.51485 -250.400843)
		(end 131.797806 -250.47702)
		(width 0.0889)
		(layer "In2.Cu")
		(net "M_I_CPU1_ALERT_R_N")
	)
	(arc
		(start 138.751818 -250.47702)
		(mid 139.034774 -250.400843)
		(end 139.31773 -250.47702)
		(width 0.0889)
		(layer "In2.Cu")
		(net "M_I_CPU1_ALERT_R_N")
	)
	(arc
		(start 134.051802 -250.47702)
		(mid 134.334758 -250.400843)
		(end 134.617714 -250.47702)
		(width 0.0889)
		(layer "In2.Cu")
		(net "M_I_CPU1_ALERT_R_N")
	)
	(arc
		(start 139.691872 -250.47702)
		(mid 139.974828 -250.400843)
		(end 140.257784 -250.47702)
		(width 0.0889)
		(layer "In2.Cu")
		(net "M_I_CPU1_ALERT_R_N")
	)
	(arc
		(start 143.451834 -250.47702)
		(mid 143.73479 -250.400843)
		(end 144.017746 -250.47702)
		(width 0.0889)
		(layer "In2.Cu")
		(net "M_I_CPU1_ALERT_R_N")
	)
	(arc
		(start 140.631926 -250.47702)
		(mid 140.914882 -250.400843)
		(end 141.197838 -250.47702)
		(width 0.0889)
		(layer "In2.Cu")
		(net "M_I_CPU1_ALERT_R_N")
	)
	(arc
		(start 128.977644 -250.47702)
		(mid 129.159895 -250.52737)
		(end 129.343404 -250.481846)
		(width 0.0889)
		(layer "In2.Cu")
		(net "M_I_CPU1_ALERT_R_N")
	)
	(arc
		(start 134.626096 -250.481846)
		(mid 134.809604 -250.52734)
		(end 134.991856 -250.47702)
		(width 0.0889)
		(layer "In2.Cu")
		(net "M_I_CPU1_ALERT_R_N")
	)
	(arc
		(start 138.377676 -250.47702)
		(mid 138.559927 -250.52737)
		(end 138.743436 -250.481846)
		(width 0.0889)
		(layer "In2.Cu")
		(net "M_I_CPU1_ALERT_R_N")
	)
	(arc
		(start 139.326112 -250.481846)
		(mid 139.50962 -250.52734)
		(end 139.691872 -250.47702)
		(width 0.0889)
		(layer "In2.Cu")
		(net "M_I_CPU1_ALERT_R_N")
	)
	(arc
		(start 136.497822 -250.47702)
		(mid 136.684766 -250.527275)
		(end 136.87171 -250.47702)
		(width 0.0889)
		(layer "In2.Cu")
		(net "M_I_CPU1_ALERT_R_N")
	)
	(via
		(at 183.616092 -244.085364)
		(size 0.4826)
		(drill 0.254)
		(layers "F.Cu" "B.Cu")
		(net "M_I_CPU1_ALERT_N")
	)
	(segment
		(start 183.019192 -244.085364)
		(end 183.616092 -244.085364)
		(width 0.10668)
		(layer "B.Cu")
		(net "M_I_CPU1_ALERT_N")
	)
	(segment
		(start 376.938032 -267.34008)
		(end 377.404884 -267.606018)
		(width 0.10668)
		(layer "F.Cu")
		(net "M_I_CPU0_SB_RSP<0>")
	)
	(segment
		(start 380.037848 -267.283438)
		(end 380.04623 -267.278612)
		(width 0.0889)
		(layer "In2.Cu")
		(net "M_I_CPU0_SB_RSP<0>")
	)
	(segment
		(start 394.361416 -266.164314)
		(end 395.149832 -266.164314)
		(width 0.0889)
		(layer "In2.Cu")
		(net "M_I_CPU0_SB_RSP<0>")
	)
	(segment
		(start 386.983478 -267.278612)
		(end 386.99186 -267.283438)
		(width 0.0889)
		(layer "In2.Cu")
		(net "M_I_CPU0_SB_RSP<0>")
	)
	(segment
		(start 378.5235 -267.278612)
		(end 378.531882 -267.283438)
		(width 0.0889)
		(layer "In2.Cu")
		(net "M_I_CPU0_SB_RSP<0>")
	)
	(segment
		(start 395.403832 -266.418314)
		(end 395.555978 -266.57046)
		(width 0.11684)
		(layer "In2.Cu")
		(net "M_I_CPU0_SB_RSP<0>")
	)
	(segment
		(start 405.747728 -266.57046)
		(end 411.53207 -270.860012)
		(width 0.11684)
		(layer "In2.Cu")
		(net "M_I_CPU0_SB_RSP<0>")
	)
	(segment
		(start 382.857756 -267.283438)
		(end 382.866138 -267.278612)
		(width 0.0889)
		(layer "In2.Cu")
		(net "M_I_CPU0_SB_RSP<0>")
	)
	(segment
		(start 390.74344 -267.278612)
		(end 390.751822 -267.283438)
		(width 0.0889)
		(layer "In2.Cu")
		(net "M_I_CPU0_SB_RSP<0>")
	)
	(segment
		(start 382.283462 -267.278612)
		(end 382.291844 -267.283438)
		(width 0.0889)
		(layer "In2.Cu")
		(net "M_I_CPU0_SB_RSP<0>")
	)
	(segment
		(start 377.410472 -267.608304)
		(end 378.237242 -267.253974)
		(width 0.0889)
		(layer "In2.Cu")
		(net "M_I_CPU0_SB_RSP<0>")
	)
	(segment
		(start 387.557772 -267.283438)
		(end 387.566154 -267.278612)
		(width 0.0889)
		(layer "In2.Cu")
		(net "M_I_CPU0_SB_RSP<0>")
	)
	(segment
		(start 392.255756 -267.283692)
		(end 392.2776 -267.271246)
		(width 0.0889)
		(layer "In2.Cu")
		(net "M_I_CPU0_SB_RSP<0>")
	)
	(segment
		(start 411.53207 -270.860012)
		(end 431.131218 -270.860012)
		(width 0.11684)
		(layer "In2.Cu")
		(net "M_I_CPU0_SB_RSP<0>")
	)
	(segment
		(start 388.497826 -267.283438)
		(end 388.506208 -267.278612)
		(width 0.0889)
		(layer "In2.Cu")
		(net "M_I_CPU0_SB_RSP<0>")
	)
	(segment
		(start 393.277598 -267.248132)
		(end 394.361416 -266.164314)
		(width 0.0889)
		(layer "In2.Cu")
		(net "M_I_CPU0_SB_RSP<0>")
	)
	(segment
		(start 395.555978 -266.57046)
		(end 405.747728 -266.57046)
		(width 0.11684)
		(layer "In2.Cu")
		(net "M_I_CPU0_SB_RSP<0>")
	)
	(segment
		(start 386.043424 -267.278612)
		(end 386.051806 -267.283438)
		(width 0.0889)
		(layer "In2.Cu")
		(net "M_I_CPU0_SB_RSP<0>")
	)
	(segment
		(start 391.317734 -267.283438)
		(end 391.326116 -267.278612)
		(width 0.0889)
		(layer "In2.Cu")
		(net "M_I_CPU0_SB_RSP<0>")
	)
	(segment
		(start 431.131218 -270.860012)
		(end 431.55616 -270.43507)
		(width 0.11684)
		(layer "In2.Cu")
		(net "M_I_CPU0_SB_RSP<0>")
	)
	(segment
		(start 383.79781 -267.283438)
		(end 383.806192 -267.278612)
		(width 0.0889)
		(layer "In2.Cu")
		(net "M_I_CPU0_SB_RSP<0>")
	)
	(segment
		(start 395.149832 -266.164314)
		(end 395.403832 -266.418314)
		(width 0.0889)
		(layer "In2.Cu")
		(net "M_I_CPU0_SB_RSP<0>")
	)
	(segment
		(start 392.229594 -267.298678)
		(end 392.255756 -267.283692)
		(width 0.0889)
		(layer "In2.Cu")
		(net "M_I_CPU0_SB_RSP<0>")
	)
	(segment
		(start 379.097794 -267.283438)
		(end 379.106176 -267.278612)
		(width 0.0889)
		(layer "In2.Cu")
		(net "M_I_CPU0_SB_RSP<0>")
	)
	(segment
		(start 377.404884 -267.606018)
		(end 377.410472 -267.608304)
		(width 0.0889)
		(layer "In2.Cu")
		(net "M_I_CPU0_SB_RSP<0>")
	)
	(segment
		(start 392.628374 -267.283438)
		(end 392.657838 -267.30071)
		(width 0.0889)
		(layer "In2.Cu")
		(net "M_I_CPU0_SB_RSP<0>")
	)
	(arc
		(start 386.617718 -267.283438)
		(mid 386.799969 -267.233088)
		(end 386.983478 -267.278612)
		(width 0.0889)
		(layer "In2.Cu")
		(net "M_I_CPU0_SB_RSP<0>")
	)
	(arc
		(start 390.751822 -267.283438)
		(mid 391.034778 -267.359615)
		(end 391.317734 -267.283438)
		(width 0.0889)
		(layer "In2.Cu")
		(net "M_I_CPU0_SB_RSP<0>")
	)
	(arc
		(start 392.657838 -267.30071)
		(mid 392.929258 -267.360387)
		(end 393.196318 -267.283438)
		(width 0.0889)
		(layer "In2.Cu")
		(net "M_I_CPU0_SB_RSP<0>")
	)
	(arc
		(start 382.291844 -267.283438)
		(mid 382.5748 -267.359615)
		(end 382.857756 -267.283438)
		(width 0.0889)
		(layer "In2.Cu")
		(net "M_I_CPU0_SB_RSP<0>")
	)
	(arc
		(start 383.231898 -267.283438)
		(mid 383.514854 -267.359615)
		(end 383.79781 -267.283438)
		(width 0.0889)
		(layer "In2.Cu")
		(net "M_I_CPU0_SB_RSP<0>")
	)
	(arc
		(start 388.871968 -267.283438)
		(mid 389.154924 -267.359615)
		(end 389.43788 -267.283438)
		(width 0.0889)
		(layer "In2.Cu")
		(net "M_I_CPU0_SB_RSP<0>")
	)
	(arc
		(start 390.37768 -267.283438)
		(mid 390.559931 -267.233088)
		(end 390.74344 -267.278612)
		(width 0.0889)
		(layer "In2.Cu")
		(net "M_I_CPU0_SB_RSP<0>")
	)
	(arc
		(start 379.106176 -267.278612)
		(mid 379.289684 -267.233118)
		(end 379.471936 -267.283438)
		(width 0.0889)
		(layer "In2.Cu")
		(net "M_I_CPU0_SB_RSP<0>")
	)
	(arc
		(start 385.111752 -267.283438)
		(mid 385.394708 -267.359615)
		(end 385.677664 -267.283438)
		(width 0.0889)
		(layer "In2.Cu")
		(net "M_I_CPU0_SB_RSP<0>")
	)
	(arc
		(start 378.531882 -267.283438)
		(mid 378.814838 -267.359615)
		(end 379.097794 -267.283438)
		(width 0.0889)
		(layer "In2.Cu")
		(net "M_I_CPU0_SB_RSP<0>")
	)
	(arc
		(start 389.811768 -267.283438)
		(mid 390.094724 -267.359615)
		(end 390.37768 -267.283438)
		(width 0.0889)
		(layer "In2.Cu")
		(net "M_I_CPU0_SB_RSP<0>")
	)
	(arc
		(start 380.41199 -267.283438)
		(mid 380.694946 -267.359615)
		(end 380.977902 -267.283438)
		(width 0.0889)
		(layer "In2.Cu")
		(net "M_I_CPU0_SB_RSP<0>")
	)
	(arc
		(start 386.051806 -267.283438)
		(mid 386.334762 -267.359615)
		(end 386.617718 -267.283438)
		(width 0.0889)
		(layer "In2.Cu")
		(net "M_I_CPU0_SB_RSP<0>")
	)
	(arc
		(start 383.806192 -267.278612)
		(mid 383.9897 -267.233118)
		(end 384.171952 -267.283438)
		(width 0.0889)
		(layer "In2.Cu")
		(net "M_I_CPU0_SB_RSP<0>")
	)
	(arc
		(start 391.691876 -267.283438)
		(mid 391.958806 -267.359387)
		(end 392.229594 -267.298678)
		(width 0.0889)
		(layer "In2.Cu")
		(net "M_I_CPU0_SB_RSP<0>")
	)
	(arc
		(start 388.506208 -267.278612)
		(mid 388.689716 -267.233118)
		(end 388.871968 -267.283438)
		(width 0.0889)
		(layer "In2.Cu")
		(net "M_I_CPU0_SB_RSP<0>")
	)
	(arc
		(start 385.677664 -267.283438)
		(mid 385.859915 -267.233088)
		(end 386.043424 -267.278612)
		(width 0.0889)
		(layer "In2.Cu")
		(net "M_I_CPU0_SB_RSP<0>")
	)
	(arc
		(start 392.2776 -267.271246)
		(mid 392.454528 -267.233418)
		(end 392.628374 -267.283438)
		(width 0.0889)
		(layer "In2.Cu")
		(net "M_I_CPU0_SB_RSP<0>")
	)
	(arc
		(start 381.917702 -267.283438)
		(mid 382.099953 -267.233088)
		(end 382.283462 -267.278612)
		(width 0.0889)
		(layer "In2.Cu")
		(net "M_I_CPU0_SB_RSP<0>")
	)
	(arc
		(start 391.326116 -267.278612)
		(mid 391.509624 -267.233118)
		(end 391.691876 -267.283438)
		(width 0.0889)
		(layer "In2.Cu")
		(net "M_I_CPU0_SB_RSP<0>")
	)
	(arc
		(start 387.931914 -267.283438)
		(mid 388.21487 -267.359615)
		(end 388.497826 -267.283438)
		(width 0.0889)
		(layer "In2.Cu")
		(net "M_I_CPU0_SB_RSP<0>")
	)
	(arc
		(start 384.737864 -267.283438)
		(mid 384.924808 -267.233183)
		(end 385.111752 -267.283438)
		(width 0.0889)
		(layer "In2.Cu")
		(net "M_I_CPU0_SB_RSP<0>")
	)
	(arc
		(start 380.04623 -267.278612)
		(mid 380.229738 -267.233118)
		(end 380.41199 -267.283438)
		(width 0.0889)
		(layer "In2.Cu")
		(net "M_I_CPU0_SB_RSP<0>")
	)
	(arc
		(start 389.43788 -267.283438)
		(mid 389.624824 -267.233183)
		(end 389.811768 -267.283438)
		(width 0.0889)
		(layer "In2.Cu")
		(net "M_I_CPU0_SB_RSP<0>")
	)
	(arc
		(start 386.99186 -267.283438)
		(mid 387.274816 -267.359615)
		(end 387.557772 -267.283438)
		(width 0.0889)
		(layer "In2.Cu")
		(net "M_I_CPU0_SB_RSP<0>")
	)
	(arc
		(start 378.237242 -267.253974)
		(mid 378.279665 -267.240054)
		(end 378.323856 -267.233654)
		(width 0.0889)
		(layer "In2.Cu")
		(net "M_I_CPU0_SB_RSP<0>")
	)
	(arc
		(start 384.171952 -267.283438)
		(mid 384.454908 -267.359615)
		(end 384.737864 -267.283438)
		(width 0.0889)
		(layer "In2.Cu")
		(net "M_I_CPU0_SB_RSP<0>")
	)
	(arc
		(start 387.566154 -267.278612)
		(mid 387.749662 -267.233118)
		(end 387.931914 -267.283438)
		(width 0.0889)
		(layer "In2.Cu")
		(net "M_I_CPU0_SB_RSP<0>")
	)
	(arc
		(start 382.866138 -267.278612)
		(mid 383.049646 -267.233118)
		(end 383.231898 -267.283438)
		(width 0.0889)
		(layer "In2.Cu")
		(net "M_I_CPU0_SB_RSP<0>")
	)
	(arc
		(start 381.35179 -267.283438)
		(mid 381.634746 -267.359615)
		(end 381.917702 -267.283438)
		(width 0.0889)
		(layer "In2.Cu")
		(net "M_I_CPU0_SB_RSP<0>")
	)
	(arc
		(start 378.323856 -267.233654)
		(mid 378.426827 -267.242159)
		(end 378.5235 -267.278612)
		(width 0.0889)
		(layer "In2.Cu")
		(net "M_I_CPU0_SB_RSP<0>")
	)
	(arc
		(start 380.977902 -267.283438)
		(mid 381.164846 -267.233183)
		(end 381.35179 -267.283438)
		(width 0.0889)
		(layer "In2.Cu")
		(net "M_I_CPU0_SB_RSP<0>")
	)
	(arc
		(start 379.471936 -267.283438)
		(mid 379.754892 -267.359615)
		(end 380.037848 -267.283438)
		(width 0.0889)
		(layer "In2.Cu")
		(net "M_I_CPU0_SB_RSP<0>")
	)
	(arc
		(start 393.196318 -267.283438)
		(mid 393.235906 -267.263363)
		(end 393.277598 -267.248132)
		(width 0.0889)
		(layer "In2.Cu")
		(net "M_I_CPU0_SB_RSP<0>")
	)
	(segment
		(start 375.528078 -264.910062)
		(end 375.99493 -265.176)
		(width 0.10668)
		(layer "F.Cu")
		(net "M_I_CPU0_SB_PAR")
	)
	(segment
		(start 388.393432 -265.503406)
		(end 388.401814 -265.49858)
		(width 0.0889)
		(layer "In2.Cu")
		(net "M_I_CPU0_SB_PAR")
	)
	(segment
		(start 423.177208 -267.460222)
		(end 427.030896 -267.460222)
		(width 0.14478)
		(layer "In2.Cu")
		(net "M_I_CPU0_SB_PAR")
	)
	(segment
		(start 395.228572 -264.544302)
		(end 395.478 -264.79373)
		(width 0.0889)
		(layer "In2.Cu")
		(net "M_I_CPU0_SB_PAR")
	)
	(segment
		(start 377.68784 -265.49858)
		(end 377.696222 -265.503406)
		(width 0.0889)
		(layer "In2.Cu")
		(net "M_I_CPU0_SB_PAR")
	)
	(segment
		(start 427.030896 -267.460222)
		(end 427.456092 -267.035026)
		(width 0.14478)
		(layer "In2.Cu")
		(net "M_I_CPU0_SB_PAR")
	)
	(segment
		(start 380.873508 -265.503406)
		(end 380.88189 -265.49858)
		(width 0.0889)
		(layer "In2.Cu")
		(net "M_I_CPU0_SB_PAR")
	)
	(segment
		(start 389.90778 -265.49858)
		(end 389.916162 -265.503406)
		(width 0.0889)
		(layer "In2.Cu")
		(net "M_I_CPU0_SB_PAR")
	)
	(segment
		(start 376.747786 -265.49858)
		(end 376.756168 -265.503406)
		(width 0.0889)
		(layer "In2.Cu")
		(net "M_I_CPU0_SB_PAR")
	)
	(segment
		(start 375.99493 -265.176)
		(end 376.148854 -265.44143)
		(width 0.0889)
		(layer "In2.Cu")
		(net "M_I_CPU0_SB_PAR")
	)
	(segment
		(start 393.099798 -265.49858)
		(end 394.054076 -264.544302)
		(width 0.0889)
		(layer "In2.Cu")
		(net "M_I_CPU0_SB_PAR")
	)
	(segment
		(start 384.63347 -265.503406)
		(end 384.641852 -265.49858)
		(width 0.0889)
		(layer "In2.Cu")
		(net "M_I_CPU0_SB_PAR")
	)
	(segment
		(start 383.693416 -265.503406)
		(end 383.701798 -265.49858)
		(width 0.0889)
		(layer "In2.Cu")
		(net "M_I_CPU0_SB_PAR")
	)
	(segment
		(start 394.054076 -264.544302)
		(end 395.228572 -264.544302)
		(width 0.0889)
		(layer "In2.Cu")
		(net "M_I_CPU0_SB_PAR")
	)
	(segment
		(start 392.160506 -265.498326)
		(end 392.186668 -265.48334)
		(width 0.0889)
		(layer "In2.Cu")
		(net "M_I_CPU0_SB_PAR")
	)
	(segment
		(start 385.207764 -265.49858)
		(end 385.216146 -265.503406)
		(width 0.0889)
		(layer "In2.Cu")
		(net "M_I_CPU0_SB_PAR")
	)
	(segment
		(start 406.562306 -264.79373)
		(end 411.550612 -267.460222)
		(width 0.14478)
		(layer "In2.Cu")
		(net "M_I_CPU0_SB_PAR")
	)
	(segment
		(start 422.625774 -267.184632)
		(end 422.901618 -267.184632)
		(width 0.14478)
		(layer "In2.Cu")
		(net "M_I_CPU0_SB_PAR")
	)
	(segment
		(start 395.478 -264.79373)
		(end 406.562306 -264.79373)
		(width 0.14478)
		(layer "In2.Cu")
		(net "M_I_CPU0_SB_PAR")
	)
	(segment
		(start 411.550612 -267.460222)
		(end 422.350184 -267.460222)
		(width 0.14478)
		(layer "In2.Cu")
		(net "M_I_CPU0_SB_PAR")
	)
	(segment
		(start 379.933454 -265.503406)
		(end 379.941836 -265.49858)
		(width 0.0889)
		(layer "In2.Cu")
		(net "M_I_CPU0_SB_PAR")
	)
	(segment
		(start 422.901618 -267.184632)
		(end 423.177208 -267.460222)
		(width 0.14478)
		(layer "In2.Cu")
		(net "M_I_CPU0_SB_PAR")
	)
	(segment
		(start 376.148854 -265.44143)
		(end 376.244866 -265.46683)
		(width 0.0889)
		(layer "In2.Cu")
		(net "M_I_CPU0_SB_PAR")
	)
	(segment
		(start 392.724386 -265.49858)
		(end 392.74496 -265.510518)
		(width 0.0889)
		(layer "In2.Cu")
		(net "M_I_CPU0_SB_PAR")
	)
	(segment
		(start 392.137138 -265.511788)
		(end 392.160506 -265.498326)
		(width 0.0889)
		(layer "In2.Cu")
		(net "M_I_CPU0_SB_PAR")
	)
	(segment
		(start 381.447802 -265.49858)
		(end 381.456184 -265.503406)
		(width 0.0889)
		(layer "In2.Cu")
		(net "M_I_CPU0_SB_PAR")
	)
	(segment
		(start 386.147818 -265.49858)
		(end 386.1562 -265.503406)
		(width 0.0889)
		(layer "In2.Cu")
		(net "M_I_CPU0_SB_PAR")
	)
	(segment
		(start 422.350184 -267.460222)
		(end 422.625774 -267.184632)
		(width 0.14478)
		(layer "In2.Cu")
		(net "M_I_CPU0_SB_PAR")
	)
	(segment
		(start 389.333486 -265.503406)
		(end 389.341868 -265.49858)
		(width 0.0889)
		(layer "In2.Cu")
		(net "M_I_CPU0_SB_PAR")
	)
	(arc
		(start 383.327656 -265.49858)
		(mid 383.509907 -265.54893)
		(end 383.693416 -265.503406)
		(width 0.0889)
		(layer "In2.Cu")
		(net "M_I_CPU0_SB_PAR")
	)
	(arc
		(start 390.281922 -265.49858)
		(mid 390.564878 -265.422403)
		(end 390.847834 -265.49858)
		(width 0.0889)
		(layer "In2.Cu")
		(net "M_I_CPU0_SB_PAR")
	)
	(arc
		(start 390.847834 -265.49858)
		(mid 391.034778 -265.548835)
		(end 391.221722 -265.49858)
		(width 0.0889)
		(layer "In2.Cu")
		(net "M_I_CPU0_SB_PAR")
	)
	(arc
		(start 384.26771 -265.49858)
		(mid 384.449961 -265.54893)
		(end 384.63347 -265.503406)
		(width 0.0889)
		(layer "In2.Cu")
		(net "M_I_CPU0_SB_PAR")
	)
	(arc
		(start 391.221722 -265.49858)
		(mid 391.504678 -265.422403)
		(end 391.787634 -265.49858)
		(width 0.0889)
		(layer "In2.Cu")
		(net "M_I_CPU0_SB_PAR")
	)
	(arc
		(start 378.627894 -265.49858)
		(mid 378.814838 -265.548835)
		(end 379.001782 -265.49858)
		(width 0.0889)
		(layer "In2.Cu")
		(net "M_I_CPU0_SB_PAR")
	)
	(arc
		(start 389.916162 -265.503406)
		(mid 390.09967 -265.5489)
		(end 390.281922 -265.49858)
		(width 0.0889)
		(layer "In2.Cu")
		(net "M_I_CPU0_SB_PAR")
	)
	(arc
		(start 377.121928 -265.49858)
		(mid 377.404884 -265.422403)
		(end 377.68784 -265.49858)
		(width 0.0889)
		(layer "In2.Cu")
		(net "M_I_CPU0_SB_PAR")
	)
	(arc
		(start 385.216146 -265.503406)
		(mid 385.399654 -265.5489)
		(end 385.581906 -265.49858)
		(width 0.0889)
		(layer "In2.Cu")
		(net "M_I_CPU0_SB_PAR")
	)
	(arc
		(start 376.244866 -265.46683)
		(mid 376.500074 -265.423353)
		(end 376.747786 -265.49858)
		(width 0.0889)
		(layer "In2.Cu")
		(net "M_I_CPU0_SB_PAR")
	)
	(arc
		(start 381.456184 -265.503406)
		(mid 381.639692 -265.5489)
		(end 381.821944 -265.49858)
		(width 0.0889)
		(layer "In2.Cu")
		(net "M_I_CPU0_SB_PAR")
	)
	(arc
		(start 391.787634 -265.49858)
		(mid 391.960742 -265.548696)
		(end 392.137138 -265.511788)
		(width 0.0889)
		(layer "In2.Cu")
		(net "M_I_CPU0_SB_PAR")
	)
	(arc
		(start 379.567694 -265.49858)
		(mid 379.749945 -265.54893)
		(end 379.933454 -265.503406)
		(width 0.0889)
		(layer "In2.Cu")
		(net "M_I_CPU0_SB_PAR")
	)
	(arc
		(start 388.401814 -265.49858)
		(mid 388.68477 -265.422403)
		(end 388.967726 -265.49858)
		(width 0.0889)
		(layer "In2.Cu")
		(net "M_I_CPU0_SB_PAR")
	)
	(arc
		(start 392.74496 -265.510518)
		(mid 392.923888 -265.549395)
		(end 393.099798 -265.49858)
		(width 0.0889)
		(layer "In2.Cu")
		(net "M_I_CPU0_SB_PAR")
	)
	(arc
		(start 378.061982 -265.49858)
		(mid 378.344938 -265.422403)
		(end 378.627894 -265.49858)
		(width 0.0889)
		(layer "In2.Cu")
		(net "M_I_CPU0_SB_PAR")
	)
	(arc
		(start 383.701798 -265.49858)
		(mid 383.984754 -265.422403)
		(end 384.26771 -265.49858)
		(width 0.0889)
		(layer "In2.Cu")
		(net "M_I_CPU0_SB_PAR")
	)
	(arc
		(start 388.967726 -265.49858)
		(mid 389.149977 -265.54893)
		(end 389.333486 -265.503406)
		(width 0.0889)
		(layer "In2.Cu")
		(net "M_I_CPU0_SB_PAR")
	)
	(arc
		(start 377.696222 -265.503406)
		(mid 377.87973 -265.5489)
		(end 378.061982 -265.49858)
		(width 0.0889)
		(layer "In2.Cu")
		(net "M_I_CPU0_SB_PAR")
	)
	(arc
		(start 386.52196 -265.49858)
		(mid 386.804916 -265.422403)
		(end 387.087872 -265.49858)
		(width 0.0889)
		(layer "In2.Cu")
		(net "M_I_CPU0_SB_PAR")
	)
	(arc
		(start 389.341868 -265.49858)
		(mid 389.624824 -265.422403)
		(end 389.90778 -265.49858)
		(width 0.0889)
		(layer "In2.Cu")
		(net "M_I_CPU0_SB_PAR")
	)
	(arc
		(start 382.761744 -265.49858)
		(mid 383.0447 -265.422403)
		(end 383.327656 -265.49858)
		(width 0.0889)
		(layer "In2.Cu")
		(net "M_I_CPU0_SB_PAR")
	)
	(arc
		(start 381.821944 -265.49858)
		(mid 382.1049 -265.422403)
		(end 382.387856 -265.49858)
		(width 0.0889)
		(layer "In2.Cu")
		(net "M_I_CPU0_SB_PAR")
	)
	(arc
		(start 387.46176 -265.49858)
		(mid 387.744716 -265.422403)
		(end 388.027672 -265.49858)
		(width 0.0889)
		(layer "In2.Cu")
		(net "M_I_CPU0_SB_PAR")
	)
	(arc
		(start 384.641852 -265.49858)
		(mid 384.924808 -265.422403)
		(end 385.207764 -265.49858)
		(width 0.0889)
		(layer "In2.Cu")
		(net "M_I_CPU0_SB_PAR")
	)
	(arc
		(start 392.186668 -265.48334)
		(mid 392.457454 -265.422694)
		(end 392.724386 -265.49858)
		(width 0.0889)
		(layer "In2.Cu")
		(net "M_I_CPU0_SB_PAR")
	)
	(arc
		(start 382.387856 -265.49858)
		(mid 382.5748 -265.548835)
		(end 382.761744 -265.49858)
		(width 0.0889)
		(layer "In2.Cu")
		(net "M_I_CPU0_SB_PAR")
	)
	(arc
		(start 376.756168 -265.503406)
		(mid 376.939676 -265.5489)
		(end 377.121928 -265.49858)
		(width 0.0889)
		(layer "In2.Cu")
		(net "M_I_CPU0_SB_PAR")
	)
	(arc
		(start 388.027672 -265.49858)
		(mid 388.209923 -265.54893)
		(end 388.393432 -265.503406)
		(width 0.0889)
		(layer "In2.Cu")
		(net "M_I_CPU0_SB_PAR")
	)
	(arc
		(start 386.1562 -265.503406)
		(mid 386.339708 -265.5489)
		(end 386.52196 -265.49858)
		(width 0.0889)
		(layer "In2.Cu")
		(net "M_I_CPU0_SB_PAR")
	)
	(arc
		(start 379.941836 -265.49858)
		(mid 380.224792 -265.422403)
		(end 380.507748 -265.49858)
		(width 0.0889)
		(layer "In2.Cu")
		(net "M_I_CPU0_SB_PAR")
	)
	(arc
		(start 380.88189 -265.49858)
		(mid 381.164846 -265.422403)
		(end 381.447802 -265.49858)
		(width 0.0889)
		(layer "In2.Cu")
		(net "M_I_CPU0_SB_PAR")
	)
	(arc
		(start 387.087872 -265.49858)
		(mid 387.274816 -265.548835)
		(end 387.46176 -265.49858)
		(width 0.0889)
		(layer "In2.Cu")
		(net "M_I_CPU0_SB_PAR")
	)
	(arc
		(start 379.001782 -265.49858)
		(mid 379.284738 -265.422403)
		(end 379.567694 -265.49858)
		(width 0.0889)
		(layer "In2.Cu")
		(net "M_I_CPU0_SB_PAR")
	)
	(arc
		(start 385.581906 -265.49858)
		(mid 385.864862 -265.422403)
		(end 386.147818 -265.49858)
		(width 0.0889)
		(layer "In2.Cu")
		(net "M_I_CPU0_SB_PAR")
	)
	(arc
		(start 380.507748 -265.49858)
		(mid 380.689999 -265.54893)
		(end 380.873508 -265.503406)
		(width 0.0889)
		(layer "In2.Cu")
		(net "M_I_CPU0_SB_PAR")
	)
	(segment
		(start 376.938032 -270.580104)
		(end 377.404884 -270.846042)
		(width 0.12954)
		(layer "F.Cu")
		(net "M_I_CPU0_SB_DQS_DP<9>")
	)
	(segment
		(start 429.091344 -275.99259)
		(end 429.274224 -275.80971)
		(width 0.16002)
		(layer "In2.Cu")
		(net "M_I_CPU0_SB_DQS_DP<9>")
	)
	(segment
		(start 418.40785 -275.384006)
		(end 420.541196 -275.384006)
		(width 0.16002)
		(layer "In2.Cu")
		(net "M_I_CPU0_SB_DQS_DP<9>")
	)
	(segment
		(start 421.12438 -275.96719)
		(end 421.466264 -275.96719)
		(width 0.16002)
		(layer "In2.Cu")
		(net "M_I_CPU0_SB_DQS_DP<9>")
	)
	(segment
		(start 412.997142 -275.384006)
		(end 413.580326 -275.96719)
		(width 0.16002)
		(layer "In2.Cu")
		(net "M_I_CPU0_SB_DQS_DP<9>")
	)
	(segment
		(start 410.391864 -275.07438)
		(end 411.139132 -275.384006)
		(width 0.16002)
		(layer "In2.Cu")
		(net "M_I_CPU0_SB_DQS_DP<9>")
	)
	(segment
		(start 382.284986 -271.175988)
		(end 382.293368 -271.171162)
		(width 0.09525)
		(layer "In2.Cu")
		(net "M_I_CPU0_SB_DQS_DP<9>")
	)
	(segment
		(start 380.036324 -271.171162)
		(end 380.044706 -271.175988)
		(width 0.09525)
		(layer "In2.Cu")
		(net "M_I_CPU0_SB_DQS_DP<9>")
	)
	(segment
		(start 425.360592 -274.809966)
		(end 426.74667 -275.384006)
		(width 0.16002)
		(layer "In2.Cu")
		(net "M_I_CPU0_SB_DQS_DP<9>")
	)
	(segment
		(start 394.433552 -269.30223)
		(end 394.637514 -269.30223)
		(width 0.09525)
		(layer "In2.Cu")
		(net "M_I_CPU0_SB_DQS_DP<9>")
	)
	(segment
		(start 413.92221 -275.96719)
		(end 414.76295 -275.12645)
		(width 0.16002)
		(layer "In2.Cu")
		(net "M_I_CPU0_SB_DQS_DP<9>")
	)
	(segment
		(start 422.307004 -275.12645)
		(end 422.832276 -275.12645)
		(width 0.16002)
		(layer "In2.Cu")
		(net "M_I_CPU0_SB_DQS_DP<9>")
	)
	(segment
		(start 423.14876 -274.809966)
		(end 425.360592 -274.809966)
		(width 0.16002)
		(layer "In2.Cu")
		(net "M_I_CPU0_SB_DQS_DP<9>")
	)
	(segment
		(start 395.62024 -269.2527)
		(end 395.643862 -269.2527)
		(width 0.09525)
		(layer "In2.Cu")
		(net "M_I_CPU0_SB_DQS_DP<9>")
	)
	(segment
		(start 391.31621 -271.171162)
		(end 391.324592 -271.175988)
		(width 0.09525)
		(layer "In2.Cu")
		(net "M_I_CPU0_SB_DQS_DP<9>")
	)
	(segment
		(start 413.580326 -275.96719)
		(end 413.92221 -275.96719)
		(width 0.16002)
		(layer "In2.Cu")
		(net "M_I_CPU0_SB_DQS_DP<9>")
	)
	(segment
		(start 394.01877 -269.717012)
		(end 394.433552 -269.30223)
		(width 0.09525)
		(layer "In2.Cu")
		(net "M_I_CPU0_SB_DQS_DP<9>")
	)
	(segment
		(start 388.496302 -271.171162)
		(end 388.504684 -271.175988)
		(width 0.09525)
		(layer "In2.Cu")
		(net "M_I_CPU0_SB_DQS_DP<9>")
	)
	(segment
		(start 429.274224 -275.80971)
		(end 431.281586 -275.80971)
		(width 0.16002)
		(layer "In2.Cu")
		(net "M_I_CPU0_SB_DQS_DP<9>")
	)
	(segment
		(start 421.466264 -275.96719)
		(end 422.307004 -275.12645)
		(width 0.16002)
		(layer "In2.Cu")
		(net "M_I_CPU0_SB_DQS_DP<9>")
	)
	(segment
		(start 394.637514 -269.30223)
		(end 394.746734 -269.19301)
		(width 0.09525)
		(layer "In2.Cu")
		(net "M_I_CPU0_SB_DQS_DP<9>")
	)
	(segment
		(start 386.044948 -271.175988)
		(end 386.05333 -271.171162)
		(width 0.09525)
		(layer "In2.Cu")
		(net "M_I_CPU0_SB_DQS_DP<9>")
	)
	(segment
		(start 417.83381 -274.809966)
		(end 418.40785 -275.384006)
		(width 0.16002)
		(layer "In2.Cu")
		(net "M_I_CPU0_SB_DQS_DP<9>")
	)
	(segment
		(start 394.746734 -269.19301)
		(end 395.28115 -269.19301)
		(width 0.09525)
		(layer "In2.Cu")
		(net "M_I_CPU0_SB_DQS_DP<9>")
	)
	(segment
		(start 393.752578 -270.885412)
		(end 393.752578 -270.359886)
		(width 0.09525)
		(layer "In2.Cu")
		(net "M_I_CPU0_SB_DQS_DP<9>")
	)
	(segment
		(start 395.643862 -269.2527)
		(end 404.570184 -269.2527)
		(width 0.16002)
		(layer "In2.Cu")
		(net "M_I_CPU0_SB_DQS_DP<9>")
	)
	(segment
		(start 378.525024 -271.175988)
		(end 378.533406 -271.171162)
		(width 0.09525)
		(layer "In2.Cu")
		(net "M_I_CPU0_SB_DQS_DP<9>")
	)
	(segment
		(start 377.404884 -270.846042)
		(end 377.558808 -271.111472)
		(width 0.09525)
		(layer "In2.Cu")
		(net "M_I_CPU0_SB_DQS_DP<9>")
	)
	(segment
		(start 379.09627 -271.171162)
		(end 379.104652 -271.175988)
		(width 0.09525)
		(layer "In2.Cu")
		(net "M_I_CPU0_SB_DQS_DP<9>")
	)
	(segment
		(start 393.196318 -271.171162)
		(end 393.2047 -271.175988)
		(width 0.09525)
		(layer "In2.Cu")
		(net "M_I_CPU0_SB_DQS_DP<9>")
	)
	(segment
		(start 386.985002 -271.175988)
		(end 386.993384 -271.171162)
		(width 0.09525)
		(layer "In2.Cu")
		(net "M_I_CPU0_SB_DQS_DP<9>")
	)
	(segment
		(start 393.752578 -270.359886)
		(end 394.01877 -269.717012)
		(width 0.09525)
		(layer "In2.Cu")
		(net "M_I_CPU0_SB_DQS_DP<9>")
	)
	(segment
		(start 431.281586 -275.80971)
		(end 431.55616 -275.535136)
		(width 0.16002)
		(layer "In2.Cu")
		(net "M_I_CPU0_SB_DQS_DP<9>")
	)
	(segment
		(start 404.570184 -269.2527)
		(end 410.391864 -275.07438)
		(width 0.16002)
		(layer "In2.Cu")
		(net "M_I_CPU0_SB_DQS_DP<9>")
	)
	(segment
		(start 415.288222 -275.12645)
		(end 415.604706 -274.809966)
		(width 0.16002)
		(layer "In2.Cu")
		(net "M_I_CPU0_SB_DQS_DP<9>")
	)
	(segment
		(start 382.856232 -271.171162)
		(end 382.864614 -271.175988)
		(width 0.09525)
		(layer "In2.Cu")
		(net "M_I_CPU0_SB_DQS_DP<9>")
	)
	(segment
		(start 383.796286 -271.171162)
		(end 383.804668 -271.175988)
		(width 0.09525)
		(layer "In2.Cu")
		(net "M_I_CPU0_SB_DQS_DP<9>")
	)
	(segment
		(start 395.561058 -269.311882)
		(end 395.62024 -269.2527)
		(width 0.09525)
		(layer "In2.Cu")
		(net "M_I_CPU0_SB_DQS_DP<9>")
	)
	(segment
		(start 422.832276 -275.12645)
		(end 423.14876 -274.809966)
		(width 0.16002)
		(layer "In2.Cu")
		(net "M_I_CPU0_SB_DQS_DP<9>")
	)
	(segment
		(start 420.541196 -275.384006)
		(end 421.12438 -275.96719)
		(width 0.16002)
		(layer "In2.Cu")
		(net "M_I_CPU0_SB_DQS_DP<9>")
	)
	(segment
		(start 390.744964 -271.175988)
		(end 390.753346 -271.171162)
		(width 0.09525)
		(layer "In2.Cu")
		(net "M_I_CPU0_SB_DQS_DP<9>")
	)
	(segment
		(start 426.74667 -275.384006)
		(end 428.084996 -275.384006)
		(width 0.16002)
		(layer "In2.Cu")
		(net "M_I_CPU0_SB_DQS_DP<9>")
	)
	(segment
		(start 428.084996 -275.384006)
		(end 428.69358 -275.99259)
		(width 0.16002)
		(layer "In2.Cu")
		(net "M_I_CPU0_SB_DQS_DP<9>")
	)
	(segment
		(start 395.28115 -269.19301)
		(end 395.400022 -269.311882)
		(width 0.09525)
		(layer "In2.Cu")
		(net "M_I_CPU0_SB_DQS_DP<9>")
	)
	(segment
		(start 377.558808 -271.111472)
		(end 377.659646 -271.138142)
		(width 0.09525)
		(layer "In2.Cu")
		(net "M_I_CPU0_SB_DQS_DP<9>")
	)
	(segment
		(start 392.625072 -271.175988)
		(end 392.633454 -271.171162)
		(width 0.09525)
		(layer "In2.Cu")
		(net "M_I_CPU0_SB_DQS_DP<9>")
	)
	(segment
		(start 411.139132 -275.384006)
		(end 412.997142 -275.384006)
		(width 0.16002)
		(layer "In2.Cu")
		(net "M_I_CPU0_SB_DQS_DP<9>")
	)
	(segment
		(start 387.556248 -271.171162)
		(end 387.56463 -271.175988)
		(width 0.09525)
		(layer "In2.Cu")
		(net "M_I_CPU0_SB_DQS_DP<9>")
	)
	(segment
		(start 395.400022 -269.311882)
		(end 395.561058 -269.311882)
		(width 0.09525)
		(layer "In2.Cu")
		(net "M_I_CPU0_SB_DQS_DP<9>")
	)
	(segment
		(start 428.69358 -275.99259)
		(end 429.091344 -275.99259)
		(width 0.16002)
		(layer "In2.Cu")
		(net "M_I_CPU0_SB_DQS_DP<9>")
	)
	(segment
		(start 414.76295 -275.12645)
		(end 415.288222 -275.12645)
		(width 0.16002)
		(layer "In2.Cu")
		(net "M_I_CPU0_SB_DQS_DP<9>")
	)
	(segment
		(start 415.604706 -274.809966)
		(end 417.83381 -274.809966)
		(width 0.16002)
		(layer "In2.Cu")
		(net "M_I_CPU0_SB_DQS_DP<9>")
	)
	(arc
		(start 379.47346 -271.171162)
		(mid 379.754892 -271.095407)
		(end 380.036324 -271.171162)
		(width 0.09525)
		(layer "In2.Cu")
		(net "M_I_CPU0_SB_DQS_DP<9>")
	)
	(arc
		(start 377.659646 -271.138142)
		(mid 377.911787 -271.096572)
		(end 378.156216 -271.171162)
		(width 0.09525)
		(layer "In2.Cu")
		(net "M_I_CPU0_SB_DQS_DP<9>")
	)
	(arc
		(start 378.533406 -271.171162)
		(mid 378.814838 -271.095407)
		(end 379.09627 -271.171162)
		(width 0.09525)
		(layer "In2.Cu")
		(net "M_I_CPU0_SB_DQS_DP<9>")
	)
	(arc
		(start 383.804668 -271.175988)
		(mid 383.9897 -271.221902)
		(end 384.173476 -271.171162)
		(width 0.09525)
		(layer "In2.Cu")
		(net "M_I_CPU0_SB_DQS_DP<9>")
	)
	(arc
		(start 391.6934 -271.171162)
		(mid 391.974832 -271.095407)
		(end 392.256264 -271.171162)
		(width 0.09525)
		(layer "In2.Cu")
		(net "M_I_CPU0_SB_DQS_DP<9>")
	)
	(arc
		(start 382.864614 -271.175988)
		(mid 383.049646 -271.221902)
		(end 383.233422 -271.171162)
		(width 0.09525)
		(layer "In2.Cu")
		(net "M_I_CPU0_SB_DQS_DP<9>")
	)
	(arc
		(start 385.67614 -271.171162)
		(mid 385.859915 -271.221934)
		(end 386.044948 -271.175988)
		(width 0.09525)
		(layer "In2.Cu")
		(net "M_I_CPU0_SB_DQS_DP<9>")
	)
	(arc
		(start 391.324592 -271.175988)
		(mid 391.509624 -271.221902)
		(end 391.6934 -271.171162)
		(width 0.09525)
		(layer "In2.Cu")
		(net "M_I_CPU0_SB_DQS_DP<9>")
	)
	(arc
		(start 380.976378 -271.171162)
		(mid 381.164846 -271.221839)
		(end 381.353314 -271.171162)
		(width 0.09525)
		(layer "In2.Cu")
		(net "M_I_CPU0_SB_DQS_DP<9>")
	)
	(arc
		(start 390.376156 -271.171162)
		(mid 390.559931 -271.221934)
		(end 390.744964 -271.175988)
		(width 0.09525)
		(layer "In2.Cu")
		(net "M_I_CPU0_SB_DQS_DP<9>")
	)
	(arc
		(start 387.933438 -271.171162)
		(mid 388.21487 -271.095407)
		(end 388.496302 -271.171162)
		(width 0.09525)
		(layer "In2.Cu")
		(net "M_I_CPU0_SB_DQS_DP<9>")
	)
	(arc
		(start 382.293368 -271.171162)
		(mid 382.5748 -271.095407)
		(end 382.856232 -271.171162)
		(width 0.09525)
		(layer "In2.Cu")
		(net "M_I_CPU0_SB_DQS_DP<9>")
	)
	(arc
		(start 379.104652 -271.175988)
		(mid 379.289684 -271.221902)
		(end 379.47346 -271.171162)
		(width 0.09525)
		(layer "In2.Cu")
		(net "M_I_CPU0_SB_DQS_DP<9>")
	)
	(arc
		(start 387.56463 -271.175988)
		(mid 387.749662 -271.221902)
		(end 387.933438 -271.171162)
		(width 0.09525)
		(layer "In2.Cu")
		(net "M_I_CPU0_SB_DQS_DP<9>")
	)
	(arc
		(start 388.504684 -271.175988)
		(mid 388.689716 -271.221902)
		(end 388.873492 -271.171162)
		(width 0.09525)
		(layer "In2.Cu")
		(net "M_I_CPU0_SB_DQS_DP<9>")
	)
	(arc
		(start 381.353314 -271.171162)
		(mid 381.634746 -271.095407)
		(end 381.916178 -271.171162)
		(width 0.09525)
		(layer "In2.Cu")
		(net "M_I_CPU0_SB_DQS_DP<9>")
	)
	(arc
		(start 380.044706 -271.175988)
		(mid 380.229738 -271.221902)
		(end 380.413514 -271.171162)
		(width 0.09525)
		(layer "In2.Cu")
		(net "M_I_CPU0_SB_DQS_DP<9>")
	)
	(arc
		(start 380.413514 -271.171162)
		(mid 380.694946 -271.095407)
		(end 380.976378 -271.171162)
		(width 0.09525)
		(layer "In2.Cu")
		(net "M_I_CPU0_SB_DQS_DP<9>")
	)
	(arc
		(start 392.633454 -271.171162)
		(mid 392.914886 -271.095407)
		(end 393.196318 -271.171162)
		(width 0.09525)
		(layer "In2.Cu")
		(net "M_I_CPU0_SB_DQS_DP<9>")
	)
	(arc
		(start 388.873492 -271.171162)
		(mid 389.154924 -271.095407)
		(end 389.436356 -271.171162)
		(width 0.09525)
		(layer "In2.Cu")
		(net "M_I_CPU0_SB_DQS_DP<9>")
	)
	(arc
		(start 381.916178 -271.171162)
		(mid 382.099953 -271.221934)
		(end 382.284986 -271.175988)
		(width 0.09525)
		(layer "In2.Cu")
		(net "M_I_CPU0_SB_DQS_DP<9>")
	)
	(arc
		(start 384.173476 -271.171162)
		(mid 384.454908 -271.095407)
		(end 384.73634 -271.171162)
		(width 0.09525)
		(layer "In2.Cu")
		(net "M_I_CPU0_SB_DQS_DP<9>")
	)
	(arc
		(start 389.436356 -271.171162)
		(mid 389.624824 -271.221839)
		(end 389.813292 -271.171162)
		(width 0.09525)
		(layer "In2.Cu")
		(net "M_I_CPU0_SB_DQS_DP<9>")
	)
	(arc
		(start 390.753346 -271.171162)
		(mid 391.034778 -271.095407)
		(end 391.31621 -271.171162)
		(width 0.09525)
		(layer "In2.Cu")
		(net "M_I_CPU0_SB_DQS_DP<9>")
	)
	(arc
		(start 393.2047 -271.175988)
		(mid 393.389732 -271.221902)
		(end 393.573508 -271.171162)
		(width 0.09525)
		(layer "In2.Cu")
		(net "M_I_CPU0_SB_DQS_DP<9>")
	)
	(arc
		(start 386.993384 -271.171162)
		(mid 387.274816 -271.095407)
		(end 387.556248 -271.171162)
		(width 0.09525)
		(layer "In2.Cu")
		(net "M_I_CPU0_SB_DQS_DP<9>")
	)
	(arc
		(start 384.73634 -271.171162)
		(mid 384.924808 -271.221839)
		(end 385.113276 -271.171162)
		(width 0.09525)
		(layer "In2.Cu")
		(net "M_I_CPU0_SB_DQS_DP<9>")
	)
	(arc
		(start 386.616194 -271.171162)
		(mid 386.799969 -271.221934)
		(end 386.985002 -271.175988)
		(width 0.09525)
		(layer "In2.Cu")
		(net "M_I_CPU0_SB_DQS_DP<9>")
	)
	(arc
		(start 393.573508 -271.171162)
		(mid 393.698426 -271.050455)
		(end 393.752578 -270.885412)
		(width 0.09525)
		(layer "In2.Cu")
		(net "M_I_CPU0_SB_DQS_DP<9>")
	)
	(arc
		(start 385.113276 -271.171162)
		(mid 385.394708 -271.095407)
		(end 385.67614 -271.171162)
		(width 0.09525)
		(layer "In2.Cu")
		(net "M_I_CPU0_SB_DQS_DP<9>")
	)
	(arc
		(start 389.813292 -271.171162)
		(mid 390.094724 -271.095407)
		(end 390.376156 -271.171162)
		(width 0.09525)
		(layer "In2.Cu")
		(net "M_I_CPU0_SB_DQS_DP<9>")
	)
	(arc
		(start 383.233422 -271.171162)
		(mid 383.514854 -271.095407)
		(end 383.796286 -271.171162)
		(width 0.09525)
		(layer "In2.Cu")
		(net "M_I_CPU0_SB_DQS_DP<9>")
	)
	(arc
		(start 386.05333 -271.171162)
		(mid 386.334762 -271.095407)
		(end 386.616194 -271.171162)
		(width 0.09525)
		(layer "In2.Cu")
		(net "M_I_CPU0_SB_DQS_DP<9>")
	)
	(arc
		(start 392.256264 -271.171162)
		(mid 392.440039 -271.221934)
		(end 392.625072 -271.175988)
		(width 0.09525)
		(layer "In2.Cu")
		(net "M_I_CPU0_SB_DQS_DP<9>")
	)
	(arc
		(start 378.156216 -271.171162)
		(mid 378.339991 -271.221934)
		(end 378.525024 -271.175988)
		(width 0.09525)
		(layer "In2.Cu")
		(net "M_I_CPU0_SB_DQS_DP<9>")
	)
	(segment
		(start 375.997978 -291.640006)
		(end 376.46483 -291.905944)
		(width 0.12954)
		(layer "F.Cu")
		(net "M_I_CPU0_SB_DQS_DP<8>")
	)
	(segment
		(start 393.458192 -296.32402)
		(end 393.399264 -296.382948)
		(width 0.09525)
		(layer "In2.Cu")
		(net "M_I_CPU0_SB_DQS_DP<8>")
	)
	(segment
		(start 400.9517 -305.578256)
		(end 401.207732 -305.834288)
		(width 0.16002)
		(layer "In2.Cu")
		(net "M_I_CPU0_SB_DQS_DP<8>")
	)
	(segment
		(start 418.886894 -315.360304)
		(end 420.802562 -315.360304)
		(width 0.16002)
		(layer "In2.Cu")
		(net "M_I_CPU0_SB_DQS_DP<8>")
	)
	(segment
		(start 394.77188 -300.083728)
		(end 395.457172 -300.083728)
		(width 0.16002)
		(layer "In2.Cu")
		(net "M_I_CPU0_SB_DQS_DP<8>")
	)
	(segment
		(start 399.8341 -305.145948)
		(end 400.266408 -305.578256)
		(width 0.16002)
		(layer "In2.Cu")
		(net "M_I_CPU0_SB_DQS_DP<8>")
	)
	(segment
		(start 399.578068 -304.204624)
		(end 399.8341 -304.460656)
		(width 0.16002)
		(layer "In2.Cu")
		(net "M_I_CPU0_SB_DQS_DP<8>")
	)
	(segment
		(start 387.556248 -291.580824)
		(end 387.56463 -291.575998)
		(width 0.09525)
		(layer "In2.Cu")
		(net "M_I_CPU0_SB_DQS_DP<8>")
	)
	(segment
		(start 391.6934 -293.200836)
		(end 391.724896 -293.219124)
		(width 0.09525)
		(layer "In2.Cu")
		(net "M_I_CPU0_SB_DQS_DP<8>")
	)
	(segment
		(start 396.830804 -301.45736)
		(end 397.086836 -301.713392)
		(width 0.16002)
		(layer "In2.Cu")
		(net "M_I_CPU0_SB_DQS_DP<8>")
	)
	(segment
		(start 386.985002 -291.575998)
		(end 386.993384 -291.580824)
		(width 0.09525)
		(layer "In2.Cu")
		(net "M_I_CPU0_SB_DQS_DP<8>")
	)
	(segment
		(start 415.26587 -314.202826)
		(end 415.849054 -314.78601)
		(width 0.16002)
		(layer "In2.Cu")
		(net "M_I_CPU0_SB_DQS_DP<8>")
	)
	(segment
		(start 414.060386 -314.995306)
		(end 414.852866 -314.202826)
		(width 0.16002)
		(layer "In2.Cu")
		(net "M_I_CPU0_SB_DQS_DP<8>")
	)
	(segment
		(start 397.086836 -301.713392)
		(end 397.086836 -302.398684)
		(width 0.16002)
		(layer "In2.Cu")
		(net "M_I_CPU0_SB_DQS_DP<8>")
	)
	(segment
		(start 393.458192 -295.985692)
		(end 393.458192 -296.32402)
		(width 0.09525)
		(layer "In2.Cu")
		(net "M_I_CPU0_SB_DQS_DP<8>")
	)
	(segment
		(start 378.525024 -291.575998)
		(end 378.533406 -291.580824)
		(width 0.09525)
		(layer "In2.Cu")
		(net "M_I_CPU0_SB_DQS_DP<8>")
	)
	(segment
		(start 376.46483 -291.905944)
		(end 376.310906 -291.640514)
		(width 0.09525)
		(layer "In2.Cu")
		(net "M_I_CPU0_SB_DQS_DP<8>")
	)
	(segment
		(start 397.519144 -302.830992)
		(end 398.204436 -302.830992)
		(width 0.16002)
		(layer "In2.Cu")
		(net "M_I_CPU0_SB_DQS_DP<8>")
	)
	(segment
		(start 414.852866 -314.202826)
		(end 415.26587 -314.202826)
		(width 0.16002)
		(layer "In2.Cu")
		(net "M_I_CPU0_SB_DQS_DP<8>")
	)
	(segment
		(start 391.188194 -292.370256)
		(end 391.223246 -292.39083)
		(width 0.09525)
		(layer "In2.Cu")
		(net "M_I_CPU0_SB_DQS_DP<8>")
	)
	(segment
		(start 382.856232 -291.580824)
		(end 382.864614 -291.575998)
		(width 0.09525)
		(layer "In2.Cu")
		(net "M_I_CPU0_SB_DQS_DP<8>")
	)
	(segment
		(start 395.457172 -300.083728)
		(end 395.713204 -300.33976)
		(width 0.16002)
		(layer "In2.Cu")
		(net "M_I_CPU0_SB_DQS_DP<8>")
	)
	(segment
		(start 410.048202 -315.36005)
		(end 413.258762 -315.36005)
		(width 0.16002)
		(layer "In2.Cu")
		(net "M_I_CPU0_SB_DQS_DP<8>")
	)
	(segment
		(start 425.339256 -314.36183)
		(end 427.182788 -314.36183)
		(width 0.16002)
		(layer "In2.Cu")
		(net "M_I_CPU0_SB_DQS_DP<8>")
	)
	(segment
		(start 393.399264 -296.40657)
		(end 393.399264 -297.19016)
		(width 0.16002)
		(layer "In2.Cu")
		(net "M_I_CPU0_SB_DQS_DP<8>")
	)
	(segment
		(start 396.145512 -301.45736)
		(end 396.830804 -301.45736)
		(width 0.16002)
		(layer "In2.Cu")
		(net "M_I_CPU0_SB_DQS_DP<8>")
	)
	(segment
		(start 418.3126 -314.78601)
		(end 418.886894 -315.360304)
		(width 0.16002)
		(layer "In2.Cu")
		(net "M_I_CPU0_SB_DQS_DP<8>")
	)
	(segment
		(start 395.713204 -300.33976)
		(end 395.713204 -301.025052)
		(width 0.16002)
		(layer "In2.Cu")
		(net "M_I_CPU0_SB_DQS_DP<8>")
	)
	(segment
		(start 382.284986 -291.575998)
		(end 382.293368 -291.580824)
		(width 0.09525)
		(layer "In2.Cu")
		(net "M_I_CPU0_SB_DQS_DP<8>")
	)
	(segment
		(start 392.597894 -294.800274)
		(end 392.632946 -294.820848)
		(width 0.09525)
		(layer "In2.Cu")
		(net "M_I_CPU0_SB_DQS_DP<8>")
	)
	(segment
		(start 390.744964 -291.575998)
		(end 390.753346 -291.580824)
		(width 0.09525)
		(layer "In2.Cu")
		(net "M_I_CPU0_SB_DQS_DP<8>")
	)
	(segment
		(start 401.207732 -305.834288)
		(end 401.207732 -306.51958)
		(width 0.16002)
		(layer "In2.Cu")
		(net "M_I_CPU0_SB_DQS_DP<8>")
	)
	(segment
		(start 391.6553 -293.178738)
		(end 391.6934 -293.200836)
		(width 0.09525)
		(layer "In2.Cu")
		(net "M_I_CPU0_SB_DQS_DP<8>")
	)
	(segment
		(start 383.796286 -291.580824)
		(end 383.804668 -291.575998)
		(width 0.09525)
		(layer "In2.Cu")
		(net "M_I_CPU0_SB_DQS_DP<8>")
	)
	(segment
		(start 392.632946 -294.820848)
		(end 392.667744 -294.840914)
		(width 0.09525)
		(layer "In2.Cu")
		(net "M_I_CPU0_SB_DQS_DP<8>")
	)
	(segment
		(start 390.753346 -291.580824)
		(end 390.785858 -291.59962)
		(width 0.09525)
		(layer "In2.Cu")
		(net "M_I_CPU0_SB_DQS_DP<8>")
	)
	(segment
		(start 376.310906 -291.640514)
		(end 376.33402 -291.5539)
		(width 0.09525)
		(layer "In2.Cu")
		(net "M_I_CPU0_SB_DQS_DP<8>")
	)
	(segment
		(start 398.892776 -304.204624)
		(end 399.578068 -304.204624)
		(width 0.16002)
		(layer "In2.Cu")
		(net "M_I_CPU0_SB_DQS_DP<8>")
	)
	(segment
		(start 398.204436 -302.830992)
		(end 398.460468 -303.087024)
		(width 0.16002)
		(layer "In2.Cu")
		(net "M_I_CPU0_SB_DQS_DP<8>")
	)
	(segment
		(start 397.086836 -302.398684)
		(end 397.519144 -302.830992)
		(width 0.16002)
		(layer "In2.Cu")
		(net "M_I_CPU0_SB_DQS_DP<8>")
	)
	(segment
		(start 398.460468 -303.087024)
		(end 398.460468 -303.772316)
		(width 0.16002)
		(layer "In2.Cu")
		(net "M_I_CPU0_SB_DQS_DP<8>")
	)
	(segment
		(start 395.713204 -301.025052)
		(end 396.145512 -301.45736)
		(width 0.16002)
		(layer "In2.Cu")
		(net "M_I_CPU0_SB_DQS_DP<8>")
	)
	(segment
		(start 379.09627 -291.580824)
		(end 379.104652 -291.575998)
		(width 0.09525)
		(layer "In2.Cu")
		(net "M_I_CPU0_SB_DQS_DP<8>")
	)
	(segment
		(start 393.103354 -295.630854)
		(end 393.458192 -295.985692)
		(width 0.09525)
		(layer "In2.Cu")
		(net "M_I_CPU0_SB_DQS_DP<8>")
	)
	(segment
		(start 422.809924 -314.202826)
		(end 423.393108 -314.78601)
		(width 0.16002)
		(layer "In2.Cu")
		(net "M_I_CPU0_SB_DQS_DP<8>")
	)
	(segment
		(start 377.58497 -291.575998)
		(end 377.593352 -291.580824)
		(width 0.09525)
		(layer "In2.Cu")
		(net "M_I_CPU0_SB_DQS_DP<8>")
	)
	(segment
		(start 421.16756 -314.995306)
		(end 421.60444 -314.995306)
		(width 0.16002)
		(layer "In2.Cu")
		(net "M_I_CPU0_SB_DQS_DP<8>")
	)
	(segment
		(start 399.8341 -304.460656)
		(end 399.8341 -305.145948)
		(width 0.16002)
		(layer "In2.Cu")
		(net "M_I_CPU0_SB_DQS_DP<8>")
	)
	(segment
		(start 421.60444 -314.995306)
		(end 422.39692 -314.202826)
		(width 0.16002)
		(layer "In2.Cu")
		(net "M_I_CPU0_SB_DQS_DP<8>")
	)
	(segment
		(start 388.496302 -291.580824)
		(end 388.504684 -291.575998)
		(width 0.09525)
		(layer "In2.Cu")
		(net "M_I_CPU0_SB_DQS_DP<8>")
	)
	(segment
		(start 422.39692 -314.202826)
		(end 422.809924 -314.202826)
		(width 0.16002)
		(layer "In2.Cu")
		(net "M_I_CPU0_SB_DQS_DP<8>")
	)
	(segment
		(start 393.399264 -296.382948)
		(end 393.399264 -296.40657)
		(width 0.09525)
		(layer "In2.Cu")
		(net "M_I_CPU0_SB_DQS_DP<8>")
	)
	(segment
		(start 400.266408 -305.578256)
		(end 400.9517 -305.578256)
		(width 0.16002)
		(layer "In2.Cu")
		(net "M_I_CPU0_SB_DQS_DP<8>")
	)
	(segment
		(start 380.036324 -291.580824)
		(end 380.044706 -291.575998)
		(width 0.09525)
		(layer "In2.Cu")
		(net "M_I_CPU0_SB_DQS_DP<8>")
	)
	(segment
		(start 427.182788 -314.36183)
		(end 427.456092 -314.635134)
		(width 0.16002)
		(layer "In2.Cu")
		(net "M_I_CPU0_SB_DQS_DP<8>")
	)
	(segment
		(start 413.258762 -315.36005)
		(end 413.623506 -314.995306)
		(width 0.16002)
		(layer "In2.Cu")
		(net "M_I_CPU0_SB_DQS_DP<8>")
	)
	(segment
		(start 398.460468 -303.772316)
		(end 398.892776 -304.204624)
		(width 0.16002)
		(layer "In2.Cu")
		(net "M_I_CPU0_SB_DQS_DP<8>")
	)
	(segment
		(start 423.393108 -314.78601)
		(end 424.915076 -314.78601)
		(width 0.16002)
		(layer "In2.Cu")
		(net "M_I_CPU0_SB_DQS_DP<8>")
	)
	(segment
		(start 424.915076 -314.78601)
		(end 425.339256 -314.36183)
		(width 0.16002)
		(layer "In2.Cu")
		(net "M_I_CPU0_SB_DQS_DP<8>")
	)
	(segment
		(start 420.802562 -315.360304)
		(end 421.16756 -314.995306)
		(width 0.16002)
		(layer "In2.Cu")
		(net "M_I_CPU0_SB_DQS_DP<8>")
	)
	(segment
		(start 386.044948 -291.575998)
		(end 386.05333 -291.580824)
		(width 0.09525)
		(layer "In2.Cu")
		(net "M_I_CPU0_SB_DQS_DP<8>")
	)
	(segment
		(start 394.4747 -299.786548)
		(end 394.77188 -300.083728)
		(width 0.16002)
		(layer "In2.Cu")
		(net "M_I_CPU0_SB_DQS_DP<8>")
	)
	(segment
		(start 393.065254 -295.608756)
		(end 393.103354 -295.630854)
		(width 0.09525)
		(layer "In2.Cu")
		(net "M_I_CPU0_SB_DQS_DP<8>")
	)
	(segment
		(start 415.849054 -314.78601)
		(end 418.3126 -314.78601)
		(width 0.16002)
		(layer "In2.Cu")
		(net "M_I_CPU0_SB_DQS_DP<8>")
	)
	(segment
		(start 392.1252 -293.988744)
		(end 392.1633 -294.010842)
		(width 0.09525)
		(layer "In2.Cu")
		(net "M_I_CPU0_SB_DQS_DP<8>")
	)
	(segment
		(start 392.1633 -294.010842)
		(end 392.194796 -294.02913)
		(width 0.09525)
		(layer "In2.Cu")
		(net "M_I_CPU0_SB_DQS_DP<8>")
	)
	(segment
		(start 413.623506 -314.995306)
		(end 414.060386 -314.995306)
		(width 0.16002)
		(layer "In2.Cu")
		(net "M_I_CPU0_SB_DQS_DP<8>")
	)
	(segment
		(start 391.223246 -292.39083)
		(end 391.255758 -292.409626)
		(width 0.09525)
		(layer "In2.Cu")
		(net "M_I_CPU0_SB_DQS_DP<8>")
	)
	(segment
		(start 401.207732 -306.51958)
		(end 410.048202 -315.36005)
		(width 0.16002)
		(layer "In2.Cu")
		(net "M_I_CPU0_SB_DQS_DP<8>")
	)
	(segment
		(start 393.399264 -297.19016)
		(end 394.4747 -299.786548)
		(width 0.16002)
		(layer "In2.Cu")
		(net "M_I_CPU0_SB_DQS_DP<8>")
	)
	(arc
		(start 389.436356 -291.580824)
		(mid 389.624824 -291.530147)
		(end 389.813292 -291.580824)
		(width 0.09525)
		(layer "In2.Cu")
		(net "M_I_CPU0_SB_DQS_DP<8>")
	)
	(arc
		(start 380.413514 -291.580824)
		(mid 380.694946 -291.656579)
		(end 380.976378 -291.580824)
		(width 0.09525)
		(layer "In2.Cu")
		(net "M_I_CPU0_SB_DQS_DP<8>")
	)
	(arc
		(start 392.667744 -294.840914)
		(mid 392.781529 -294.974958)
		(end 392.82243 -295.145968)
		(width 0.09525)
		(layer "In2.Cu")
		(net "M_I_CPU0_SB_DQS_DP<8>")
	)
	(arc
		(start 384.173476 -291.580824)
		(mid 384.454908 -291.656579)
		(end 384.73634 -291.580824)
		(width 0.09525)
		(layer "In2.Cu")
		(net "M_I_CPU0_SB_DQS_DP<8>")
	)
	(arc
		(start 378.533406 -291.580824)
		(mid 378.814838 -291.656579)
		(end 379.09627 -291.580824)
		(width 0.09525)
		(layer "In2.Cu")
		(net "M_I_CPU0_SB_DQS_DP<8>")
	)
	(arc
		(start 389.813292 -291.580824)
		(mid 390.094724 -291.656579)
		(end 390.376156 -291.580824)
		(width 0.09525)
		(layer "In2.Cu")
		(net "M_I_CPU0_SB_DQS_DP<8>")
	)
	(arc
		(start 383.233422 -291.580824)
		(mid 383.514854 -291.656579)
		(end 383.796286 -291.580824)
		(width 0.09525)
		(layer "In2.Cu")
		(net "M_I_CPU0_SB_DQS_DP<8>")
	)
	(arc
		(start 386.993384 -291.580824)
		(mid 387.274816 -291.656579)
		(end 387.556248 -291.580824)
		(width 0.09525)
		(layer "In2.Cu")
		(net "M_I_CPU0_SB_DQS_DP<8>")
	)
	(arc
		(start 384.73634 -291.580824)
		(mid 384.924808 -291.530147)
		(end 385.113276 -291.580824)
		(width 0.09525)
		(layer "In2.Cu")
		(net "M_I_CPU0_SB_DQS_DP<8>")
	)
	(arc
		(start 390.942576 -291.905944)
		(mid 391.007823 -292.168547)
		(end 391.188194 -292.370256)
		(width 0.09525)
		(layer "In2.Cu")
		(net "M_I_CPU0_SB_DQS_DP<8>")
	)
	(arc
		(start 391.412476 -292.71595)
		(mid 391.476873 -292.977256)
		(end 391.6553 -293.178738)
		(width 0.09525)
		(layer "In2.Cu")
		(net "M_I_CPU0_SB_DQS_DP<8>")
	)
	(arc
		(start 391.255758 -292.409626)
		(mid 391.371032 -292.543904)
		(end 391.412476 -292.71595)
		(width 0.09525)
		(layer "In2.Cu")
		(net "M_I_CPU0_SB_DQS_DP<8>")
	)
	(arc
		(start 386.05333 -291.580824)
		(mid 386.334762 -291.656579)
		(end 386.616194 -291.580824)
		(width 0.09525)
		(layer "In2.Cu")
		(net "M_I_CPU0_SB_DQS_DP<8>")
	)
	(arc
		(start 392.194796 -294.02913)
		(mid 392.310594 -294.163524)
		(end 392.352276 -294.335962)
		(width 0.09525)
		(layer "In2.Cu")
		(net "M_I_CPU0_SB_DQS_DP<8>")
	)
	(arc
		(start 383.804668 -291.575998)
		(mid 383.9897 -291.530084)
		(end 384.173476 -291.580824)
		(width 0.09525)
		(layer "In2.Cu")
		(net "M_I_CPU0_SB_DQS_DP<8>")
	)
	(arc
		(start 381.916178 -291.580824)
		(mid 382.099953 -291.530052)
		(end 382.284986 -291.575998)
		(width 0.09525)
		(layer "In2.Cu")
		(net "M_I_CPU0_SB_DQS_DP<8>")
	)
	(arc
		(start 391.882376 -293.525956)
		(mid 391.946773 -293.787262)
		(end 392.1252 -293.988744)
		(width 0.09525)
		(layer "In2.Cu")
		(net "M_I_CPU0_SB_DQS_DP<8>")
	)
	(arc
		(start 385.113276 -291.580824)
		(mid 385.394708 -291.656579)
		(end 385.67614 -291.580824)
		(width 0.09525)
		(layer "In2.Cu")
		(net "M_I_CPU0_SB_DQS_DP<8>")
	)
	(arc
		(start 390.785858 -291.59962)
		(mid 390.901132 -291.733898)
		(end 390.942576 -291.905944)
		(width 0.09525)
		(layer "In2.Cu")
		(net "M_I_CPU0_SB_DQS_DP<8>")
	)
	(arc
		(start 380.976378 -291.580824)
		(mid 381.164846 -291.530147)
		(end 381.353314 -291.580824)
		(width 0.09525)
		(layer "In2.Cu")
		(net "M_I_CPU0_SB_DQS_DP<8>")
	)
	(arc
		(start 388.873492 -291.580824)
		(mid 389.154924 -291.656579)
		(end 389.436356 -291.580824)
		(width 0.09525)
		(layer "In2.Cu")
		(net "M_I_CPU0_SB_DQS_DP<8>")
	)
	(arc
		(start 381.353314 -291.580824)
		(mid 381.634746 -291.656579)
		(end 381.916178 -291.580824)
		(width 0.09525)
		(layer "In2.Cu")
		(net "M_I_CPU0_SB_DQS_DP<8>")
	)
	(arc
		(start 376.653298 -291.580824)
		(mid 376.93473 -291.656579)
		(end 377.216162 -291.580824)
		(width 0.09525)
		(layer "In2.Cu")
		(net "M_I_CPU0_SB_DQS_DP<8>")
	)
	(arc
		(start 378.156216 -291.580824)
		(mid 378.339991 -291.530052)
		(end 378.525024 -291.575998)
		(width 0.09525)
		(layer "In2.Cu")
		(net "M_I_CPU0_SB_DQS_DP<8>")
	)
	(arc
		(start 376.33402 -291.5539)
		(mid 376.496671 -291.53164)
		(end 376.653298 -291.580824)
		(width 0.09525)
		(layer "In2.Cu")
		(net "M_I_CPU0_SB_DQS_DP<8>")
	)
	(arc
		(start 388.504684 -291.575998)
		(mid 388.689716 -291.530084)
		(end 388.873492 -291.580824)
		(width 0.09525)
		(layer "In2.Cu")
		(net "M_I_CPU0_SB_DQS_DP<8>")
	)
	(arc
		(start 385.67614 -291.580824)
		(mid 385.859915 -291.530052)
		(end 386.044948 -291.575998)
		(width 0.09525)
		(layer "In2.Cu")
		(net "M_I_CPU0_SB_DQS_DP<8>")
	)
	(arc
		(start 377.593352 -291.580824)
		(mid 377.874784 -291.656579)
		(end 378.156216 -291.580824)
		(width 0.09525)
		(layer "In2.Cu")
		(net "M_I_CPU0_SB_DQS_DP<8>")
	)
	(arc
		(start 377.216162 -291.580824)
		(mid 377.399937 -291.530052)
		(end 377.58497 -291.575998)
		(width 0.09525)
		(layer "In2.Cu")
		(net "M_I_CPU0_SB_DQS_DP<8>")
	)
	(arc
		(start 382.293368 -291.580824)
		(mid 382.5748 -291.656579)
		(end 382.856232 -291.580824)
		(width 0.09525)
		(layer "In2.Cu")
		(net "M_I_CPU0_SB_DQS_DP<8>")
	)
	(arc
		(start 379.104652 -291.575998)
		(mid 379.289684 -291.530084)
		(end 379.47346 -291.580824)
		(width 0.09525)
		(layer "In2.Cu")
		(net "M_I_CPU0_SB_DQS_DP<8>")
	)
	(arc
		(start 391.724896 -293.219124)
		(mid 391.840694 -293.353518)
		(end 391.882376 -293.525956)
		(width 0.09525)
		(layer "In2.Cu")
		(net "M_I_CPU0_SB_DQS_DP<8>")
	)
	(arc
		(start 380.044706 -291.575998)
		(mid 380.229738 -291.530084)
		(end 380.413514 -291.580824)
		(width 0.09525)
		(layer "In2.Cu")
		(net "M_I_CPU0_SB_DQS_DP<8>")
	)
	(arc
		(start 392.82243 -295.145968)
		(mid 392.886827 -295.407274)
		(end 393.065254 -295.608756)
		(width 0.09525)
		(layer "In2.Cu")
		(net "M_I_CPU0_SB_DQS_DP<8>")
	)
	(arc
		(start 386.616194 -291.580824)
		(mid 386.799969 -291.530052)
		(end 386.985002 -291.575998)
		(width 0.09525)
		(layer "In2.Cu")
		(net "M_I_CPU0_SB_DQS_DP<8>")
	)
	(arc
		(start 392.352276 -294.335962)
		(mid 392.417523 -294.598565)
		(end 392.597894 -294.800274)
		(width 0.09525)
		(layer "In2.Cu")
		(net "M_I_CPU0_SB_DQS_DP<8>")
	)
	(arc
		(start 387.933438 -291.580824)
		(mid 388.21487 -291.656579)
		(end 388.496302 -291.580824)
		(width 0.09525)
		(layer "In2.Cu")
		(net "M_I_CPU0_SB_DQS_DP<8>")
	)
	(arc
		(start 387.56463 -291.575998)
		(mid 387.749662 -291.530084)
		(end 387.933438 -291.580824)
		(width 0.09525)
		(layer "In2.Cu")
		(net "M_I_CPU0_SB_DQS_DP<8>")
	)
	(arc
		(start 379.47346 -291.580824)
		(mid 379.754892 -291.656579)
		(end 380.036324 -291.580824)
		(width 0.09525)
		(layer "In2.Cu")
		(net "M_I_CPU0_SB_DQS_DP<8>")
	)
	(arc
		(start 390.376156 -291.580824)
		(mid 390.559931 -291.530052)
		(end 390.744964 -291.575998)
		(width 0.09525)
		(layer "In2.Cu")
		(net "M_I_CPU0_SB_DQS_DP<8>")
	)
	(arc
		(start 382.864614 -291.575998)
		(mid 383.049646 -291.530084)
		(end 383.233422 -291.580824)
		(width 0.09525)
		(layer "In2.Cu")
		(net "M_I_CPU0_SB_DQS_DP<8>")
	)
	(segment
		(start 375.997978 -286.780224)
		(end 376.46483 -287.045908)
		(width 0.12954)
		(layer "F.Cu")
		(net "M_I_CPU0_SB_DQS_DP<7>")
	)
	(segment
		(start 404.8506 -300.138084)
		(end 404.469092 -300.519592)
		(width 0.16002)
		(layer "In2.Cu")
		(net "M_I_CPU0_SB_DQS_DP<7>")
	)
	(segment
		(start 421.16756 -305.645312)
		(end 421.60444 -305.645312)
		(width 0.16002)
		(layer "In2.Cu")
		(net "M_I_CPU0_SB_DQS_DP<7>")
	)
	(segment
		(start 377.58497 -286.715962)
		(end 377.593352 -286.720788)
		(width 0.09525)
		(layer "In2.Cu")
		(net "M_I_CPU0_SB_DQS_DP<7>")
	)
	(segment
		(start 422.809924 -304.852832)
		(end 423.117264 -305.160172)
		(width 0.16002)
		(layer "In2.Cu")
		(net "M_I_CPU0_SB_DQS_DP<7>")
	)
	(segment
		(start 390.744964 -286.715962)
		(end 390.753346 -286.720788)
		(width 0.09525)
		(layer "In2.Cu")
		(net "M_I_CPU0_SB_DQS_DP<7>")
	)
	(segment
		(start 404.469092 -300.519592)
		(end 404.469092 -301.04715)
		(width 0.16002)
		(layer "In2.Cu")
		(net "M_I_CPU0_SB_DQS_DP<7>")
	)
	(segment
		(start 422.39692 -304.852832)
		(end 422.809924 -304.852832)
		(width 0.16002)
		(layer "In2.Cu")
		(net "M_I_CPU0_SB_DQS_DP<7>")
	)
	(segment
		(start 392.441684 -286.670242)
		(end 393.619228 -286.670242)
		(width 0.09525)
		(layer "In2.Cu")
		(net "M_I_CPU0_SB_DQS_DP<7>")
	)
	(segment
		(start 413.623506 -305.645312)
		(end 414.060386 -305.645312)
		(width 0.16002)
		(layer "In2.Cu")
		(net "M_I_CPU0_SB_DQS_DP<7>")
	)
	(segment
		(start 414.852866 -304.852832)
		(end 415.26587 -304.852832)
		(width 0.16002)
		(layer "In2.Cu")
		(net "M_I_CPU0_SB_DQS_DP<7>")
	)
	(segment
		(start 394.137388 -287.188402)
		(end 394.137388 -287.602676)
		(width 0.09525)
		(layer "In2.Cu")
		(net "M_I_CPU0_SB_DQS_DP<7>")
	)
	(segment
		(start 378.525024 -286.715962)
		(end 378.533406 -286.720788)
		(width 0.09525)
		(layer "In2.Cu")
		(net "M_I_CPU0_SB_DQS_DP<7>")
	)
	(segment
		(start 407.124662 -302.411892)
		(end 407.401014 -302.411892)
		(width 0.16002)
		(layer "In2.Cu")
		(net "M_I_CPU0_SB_DQS_DP<7>")
	)
	(segment
		(start 383.796286 -286.720788)
		(end 383.804668 -286.715962)
		(width 0.09525)
		(layer "In2.Cu")
		(net "M_I_CPU0_SB_DQS_DP<7>")
	)
	(segment
		(start 414.060386 -305.645312)
		(end 414.852866 -304.852832)
		(width 0.16002)
		(layer "In2.Cu")
		(net "M_I_CPU0_SB_DQS_DP<7>")
	)
	(segment
		(start 392.228324 -286.736028)
		(end 392.254232 -286.721042)
		(width 0.09525)
		(layer "In2.Cu")
		(net "M_I_CPU0_SB_DQS_DP<7>")
	)
	(segment
		(start 427.182788 -305.011836)
		(end 427.456092 -305.28514)
		(width 0.16002)
		(layer "In2.Cu")
		(net "M_I_CPU0_SB_DQS_DP<7>")
	)
	(segment
		(start 376.310906 -286.780478)
		(end 376.33402 -286.693864)
		(width 0.09525)
		(layer "In2.Cu")
		(net "M_I_CPU0_SB_DQS_DP<7>")
	)
	(segment
		(start 388.496302 -286.720788)
		(end 388.504684 -286.715962)
		(width 0.09525)
		(layer "In2.Cu")
		(net "M_I_CPU0_SB_DQS_DP<7>")
	)
	(segment
		(start 408.261312 -304.83937)
		(end 411.08757 -306.010056)
		(width 0.16002)
		(layer "In2.Cu")
		(net "M_I_CPU0_SB_DQS_DP<7>")
	)
	(segment
		(start 395.120876 -288.669222)
		(end 395.13764 -288.685986)
		(width 0.09525)
		(layer "In2.Cu")
		(net "M_I_CPU0_SB_DQS_DP<7>")
	)
	(segment
		(start 405.842724 -301.893224)
		(end 405.842724 -302.420782)
		(width 0.16002)
		(layer "In2.Cu")
		(net "M_I_CPU0_SB_DQS_DP<7>")
	)
	(segment
		(start 423.117264 -305.160172)
		(end 425.19092 -305.160172)
		(width 0.16002)
		(layer "In2.Cu")
		(net "M_I_CPU0_SB_DQS_DP<7>")
	)
	(segment
		(start 418.986462 -306.01031)
		(end 420.802562 -306.01031)
		(width 0.16002)
		(layer "In2.Cu")
		(net "M_I_CPU0_SB_DQS_DP<7>")
	)
	(segment
		(start 425.339256 -305.011836)
		(end 427.182788 -305.011836)
		(width 0.16002)
		(layer "In2.Cu")
		(net "M_I_CPU0_SB_DQS_DP<7>")
	)
	(segment
		(start 386.985002 -286.715962)
		(end 386.993384 -286.720788)
		(width 0.09525)
		(layer "In2.Cu")
		(net "M_I_CPU0_SB_DQS_DP<7>")
	)
	(segment
		(start 395.13764 -288.685986)
		(end 396.4178 -289.966146)
		(width 0.16002)
		(layer "In2.Cu")
		(net "M_I_CPU0_SB_DQS_DP<7>")
	)
	(segment
		(start 394.137388 -287.602676)
		(end 395.120876 -288.586418)
		(width 0.09525)
		(layer "In2.Cu")
		(net "M_I_CPU0_SB_DQS_DP<7>")
	)
	(segment
		(start 407.597864 -302.608742)
		(end 407.597864 -302.885348)
		(width 0.16002)
		(layer "In2.Cu")
		(net "M_I_CPU0_SB_DQS_DP<7>")
	)
	(segment
		(start 415.57321 -305.160172)
		(end 418.136324 -305.160172)
		(width 0.16002)
		(layer "In2.Cu")
		(net "M_I_CPU0_SB_DQS_DP<7>")
	)
	(segment
		(start 406.224232 -301.511716)
		(end 405.842724 -301.893224)
		(width 0.16002)
		(layer "In2.Cu")
		(net "M_I_CPU0_SB_DQS_DP<7>")
	)
	(segment
		(start 425.19092 -305.160172)
		(end 425.339256 -305.011836)
		(width 0.16002)
		(layer "In2.Cu")
		(net "M_I_CPU0_SB_DQS_DP<7>")
	)
	(segment
		(start 407.401014 -302.411892)
		(end 407.597864 -302.608742)
		(width 0.16002)
		(layer "In2.Cu")
		(net "M_I_CPU0_SB_DQS_DP<7>")
	)
	(segment
		(start 405.842724 -302.420782)
		(end 406.215596 -302.793654)
		(width 0.16002)
		(layer "In2.Cu")
		(net "M_I_CPU0_SB_DQS_DP<7>")
	)
	(segment
		(start 407.216356 -303.266856)
		(end 407.216356 -303.794414)
		(width 0.16002)
		(layer "In2.Cu")
		(net "M_I_CPU0_SB_DQS_DP<7>")
	)
	(segment
		(start 406.027382 -301.03826)
		(end 406.224232 -301.23511)
		(width 0.16002)
		(layer "In2.Cu")
		(net "M_I_CPU0_SB_DQS_DP<7>")
	)
	(segment
		(start 415.26587 -304.852832)
		(end 415.57321 -305.160172)
		(width 0.16002)
		(layer "In2.Cu")
		(net "M_I_CPU0_SB_DQS_DP<7>")
	)
	(segment
		(start 382.856232 -286.720788)
		(end 382.864614 -286.715962)
		(width 0.09525)
		(layer "In2.Cu")
		(net "M_I_CPU0_SB_DQS_DP<7>")
	)
	(segment
		(start 405.75103 -301.03826)
		(end 406.027382 -301.03826)
		(width 0.16002)
		(layer "In2.Cu")
		(net "M_I_CPU0_SB_DQS_DP<7>")
	)
	(segment
		(start 380.036324 -286.720788)
		(end 380.044706 -286.715962)
		(width 0.09525)
		(layer "In2.Cu")
		(net "M_I_CPU0_SB_DQS_DP<7>")
	)
	(segment
		(start 413.258762 -306.010056)
		(end 413.623506 -305.645312)
		(width 0.16002)
		(layer "In2.Cu")
		(net "M_I_CPU0_SB_DQS_DP<7>")
	)
	(segment
		(start 379.09627 -286.720788)
		(end 379.104652 -286.715962)
		(width 0.09525)
		(layer "In2.Cu")
		(net "M_I_CPU0_SB_DQS_DP<7>")
	)
	(segment
		(start 387.556248 -286.720788)
		(end 387.56463 -286.715962)
		(width 0.09525)
		(layer "In2.Cu")
		(net "M_I_CPU0_SB_DQS_DP<7>")
	)
	(segment
		(start 420.802562 -306.01031)
		(end 421.16756 -305.645312)
		(width 0.16002)
		(layer "In2.Cu")
		(net "M_I_CPU0_SB_DQS_DP<7>")
	)
	(segment
		(start 421.60444 -305.645312)
		(end 422.39692 -304.852832)
		(width 0.16002)
		(layer "In2.Cu")
		(net "M_I_CPU0_SB_DQS_DP<7>")
	)
	(segment
		(start 391.31621 -286.720788)
		(end 391.324592 -286.715962)
		(width 0.09525)
		(layer "In2.Cu")
		(net "M_I_CPU0_SB_DQS_DP<7>")
	)
	(segment
		(start 407.597864 -302.885348)
		(end 407.216356 -303.266856)
		(width 0.16002)
		(layer "In2.Cu")
		(net "M_I_CPU0_SB_DQS_DP<7>")
	)
	(segment
		(start 407.216356 -303.794414)
		(end 408.261312 -304.83937)
		(width 0.16002)
		(layer "In2.Cu")
		(net "M_I_CPU0_SB_DQS_DP<7>")
	)
	(segment
		(start 395.120876 -288.586418)
		(end 395.120876 -288.669222)
		(width 0.09525)
		(layer "In2.Cu")
		(net "M_I_CPU0_SB_DQS_DP<7>")
	)
	(segment
		(start 393.619228 -286.670242)
		(end 394.137388 -287.188402)
		(width 0.09525)
		(layer "In2.Cu")
		(net "M_I_CPU0_SB_DQS_DP<7>")
	)
	(segment
		(start 411.08757 -306.010056)
		(end 413.258762 -306.010056)
		(width 0.16002)
		(layer "In2.Cu")
		(net "M_I_CPU0_SB_DQS_DP<7>")
	)
	(segment
		(start 396.4178 -289.966146)
		(end 397.4465 -292.448742)
		(width 0.16002)
		(layer "In2.Cu")
		(net "M_I_CPU0_SB_DQS_DP<7>")
	)
	(segment
		(start 418.136324 -305.160172)
		(end 418.986462 -306.01031)
		(width 0.16002)
		(layer "In2.Cu")
		(net "M_I_CPU0_SB_DQS_DP<7>")
	)
	(segment
		(start 404.8506 -299.852842)
		(end 404.8506 -300.138084)
		(width 0.16002)
		(layer "In2.Cu")
		(net "M_I_CPU0_SB_DQS_DP<7>")
	)
	(segment
		(start 404.469092 -301.04715)
		(end 404.841964 -301.420022)
		(width 0.16002)
		(layer "In2.Cu")
		(net "M_I_CPU0_SB_DQS_DP<7>")
	)
	(segment
		(start 382.284986 -286.715962)
		(end 382.293368 -286.720788)
		(width 0.09525)
		(layer "In2.Cu")
		(net "M_I_CPU0_SB_DQS_DP<7>")
	)
	(segment
		(start 405.369268 -301.420022)
		(end 405.75103 -301.03826)
		(width 0.16002)
		(layer "In2.Cu")
		(net "M_I_CPU0_SB_DQS_DP<7>")
	)
	(segment
		(start 397.4465 -292.448742)
		(end 404.8506 -299.852842)
		(width 0.16002)
		(layer "In2.Cu")
		(net "M_I_CPU0_SB_DQS_DP<7>")
	)
	(segment
		(start 406.7429 -302.793654)
		(end 407.124662 -302.411892)
		(width 0.16002)
		(layer "In2.Cu")
		(net "M_I_CPU0_SB_DQS_DP<7>")
	)
	(segment
		(start 406.215596 -302.793654)
		(end 406.7429 -302.793654)
		(width 0.16002)
		(layer "In2.Cu")
		(net "M_I_CPU0_SB_DQS_DP<7>")
	)
	(segment
		(start 386.044948 -286.715962)
		(end 386.05333 -286.720788)
		(width 0.09525)
		(layer "In2.Cu")
		(net "M_I_CPU0_SB_DQS_DP<7>")
	)
	(segment
		(start 406.224232 -301.23511)
		(end 406.224232 -301.511716)
		(width 0.16002)
		(layer "In2.Cu")
		(net "M_I_CPU0_SB_DQS_DP<7>")
	)
	(segment
		(start 376.46483 -287.045908)
		(end 376.310906 -286.780478)
		(width 0.09525)
		(layer "In2.Cu")
		(net "M_I_CPU0_SB_DQS_DP<7>")
	)
	(segment
		(start 404.841964 -301.420022)
		(end 405.369268 -301.420022)
		(width 0.16002)
		(layer "In2.Cu")
		(net "M_I_CPU0_SB_DQS_DP<7>")
	)
	(arc
		(start 376.33402 -286.693864)
		(mid 376.496671 -286.671604)
		(end 376.653298 -286.720788)
		(width 0.09525)
		(layer "In2.Cu")
		(net "M_I_CPU0_SB_DQS_DP<7>")
	)
	(arc
		(start 382.293368 -286.720788)
		(mid 382.5748 -286.796577)
		(end 382.856232 -286.720788)
		(width 0.09525)
		(layer "In2.Cu")
		(net "M_I_CPU0_SB_DQS_DP<7>")
	)
	(arc
		(start 388.873492 -286.720788)
		(mid 389.154924 -286.796577)
		(end 389.436356 -286.720788)
		(width 0.09525)
		(layer "In2.Cu")
		(net "M_I_CPU0_SB_DQS_DP<7>")
	)
	(arc
		(start 379.104652 -286.715962)
		(mid 379.289684 -286.670048)
		(end 379.47346 -286.720788)
		(width 0.09525)
		(layer "In2.Cu")
		(net "M_I_CPU0_SB_DQS_DP<7>")
	)
	(arc
		(start 380.976378 -286.720788)
		(mid 381.164846 -286.670111)
		(end 381.353314 -286.720788)
		(width 0.09525)
		(layer "In2.Cu")
		(net "M_I_CPU0_SB_DQS_DP<7>")
	)
	(arc
		(start 390.753346 -286.720788)
		(mid 391.034778 -286.796577)
		(end 391.31621 -286.720788)
		(width 0.09525)
		(layer "In2.Cu")
		(net "M_I_CPU0_SB_DQS_DP<7>")
	)
	(arc
		(start 384.73634 -286.720788)
		(mid 384.924808 -286.670111)
		(end 385.113276 -286.720788)
		(width 0.09525)
		(layer "In2.Cu")
		(net "M_I_CPU0_SB_DQS_DP<7>")
	)
	(arc
		(start 387.56463 -286.715962)
		(mid 387.749662 -286.670048)
		(end 387.933438 -286.720788)
		(width 0.09525)
		(layer "In2.Cu")
		(net "M_I_CPU0_SB_DQS_DP<7>")
	)
	(arc
		(start 377.216162 -286.720788)
		(mid 377.399937 -286.670016)
		(end 377.58497 -286.715962)
		(width 0.09525)
		(layer "In2.Cu")
		(net "M_I_CPU0_SB_DQS_DP<7>")
	)
	(arc
		(start 387.933438 -286.720788)
		(mid 388.21487 -286.796577)
		(end 388.496302 -286.720788)
		(width 0.09525)
		(layer "In2.Cu")
		(net "M_I_CPU0_SB_DQS_DP<7>")
	)
	(arc
		(start 386.05333 -286.720788)
		(mid 386.334762 -286.796577)
		(end 386.616194 -286.720788)
		(width 0.09525)
		(layer "In2.Cu")
		(net "M_I_CPU0_SB_DQS_DP<7>")
	)
	(arc
		(start 389.436356 -286.720788)
		(mid 389.624824 -286.670111)
		(end 389.813292 -286.720788)
		(width 0.09525)
		(layer "In2.Cu")
		(net "M_I_CPU0_SB_DQS_DP<7>")
	)
	(arc
		(start 391.6934 -286.720788)
		(mid 391.95892 -286.796351)
		(end 392.228324 -286.736028)
		(width 0.09525)
		(layer "In2.Cu")
		(net "M_I_CPU0_SB_DQS_DP<7>")
	)
	(arc
		(start 376.653298 -286.720788)
		(mid 376.93473 -286.796577)
		(end 377.216162 -286.720788)
		(width 0.09525)
		(layer "In2.Cu")
		(net "M_I_CPU0_SB_DQS_DP<7>")
	)
	(arc
		(start 379.47346 -286.720788)
		(mid 379.754892 -286.796577)
		(end 380.036324 -286.720788)
		(width 0.09525)
		(layer "In2.Cu")
		(net "M_I_CPU0_SB_DQS_DP<7>")
	)
	(arc
		(start 378.533406 -286.720788)
		(mid 378.814838 -286.796577)
		(end 379.09627 -286.720788)
		(width 0.09525)
		(layer "In2.Cu")
		(net "M_I_CPU0_SB_DQS_DP<7>")
	)
	(arc
		(start 377.593352 -286.720788)
		(mid 377.874784 -286.796577)
		(end 378.156216 -286.720788)
		(width 0.09525)
		(layer "In2.Cu")
		(net "M_I_CPU0_SB_DQS_DP<7>")
	)
	(arc
		(start 383.233422 -286.720788)
		(mid 383.514854 -286.796577)
		(end 383.796286 -286.720788)
		(width 0.09525)
		(layer "In2.Cu")
		(net "M_I_CPU0_SB_DQS_DP<7>")
	)
	(arc
		(start 385.113276 -286.720788)
		(mid 385.394708 -286.796577)
		(end 385.67614 -286.720788)
		(width 0.09525)
		(layer "In2.Cu")
		(net "M_I_CPU0_SB_DQS_DP<7>")
	)
	(arc
		(start 380.413514 -286.720788)
		(mid 380.694946 -286.796577)
		(end 380.976378 -286.720788)
		(width 0.09525)
		(layer "In2.Cu")
		(net "M_I_CPU0_SB_DQS_DP<7>")
	)
	(arc
		(start 381.916178 -286.720788)
		(mid 382.099953 -286.670016)
		(end 382.284986 -286.715962)
		(width 0.09525)
		(layer "In2.Cu")
		(net "M_I_CPU0_SB_DQS_DP<7>")
	)
	(arc
		(start 381.353314 -286.720788)
		(mid 381.634746 -286.796577)
		(end 381.916178 -286.720788)
		(width 0.09525)
		(layer "In2.Cu")
		(net "M_I_CPU0_SB_DQS_DP<7>")
	)
	(arc
		(start 383.804668 -286.715962)
		(mid 383.9897 -286.670048)
		(end 384.173476 -286.720788)
		(width 0.09525)
		(layer "In2.Cu")
		(net "M_I_CPU0_SB_DQS_DP<7>")
	)
	(arc
		(start 389.813292 -286.720788)
		(mid 390.094724 -286.796577)
		(end 390.376156 -286.720788)
		(width 0.09525)
		(layer "In2.Cu")
		(net "M_I_CPU0_SB_DQS_DP<7>")
	)
	(arc
		(start 384.173476 -286.720788)
		(mid 384.454908 -286.796577)
		(end 384.73634 -286.720788)
		(width 0.09525)
		(layer "In2.Cu")
		(net "M_I_CPU0_SB_DQS_DP<7>")
	)
	(arc
		(start 380.044706 -286.715962)
		(mid 380.229738 -286.670048)
		(end 380.413514 -286.720788)
		(width 0.09525)
		(layer "In2.Cu")
		(net "M_I_CPU0_SB_DQS_DP<7>")
	)
	(arc
		(start 390.376156 -286.720788)
		(mid 390.559931 -286.670016)
		(end 390.744964 -286.715962)
		(width 0.09525)
		(layer "In2.Cu")
		(net "M_I_CPU0_SB_DQS_DP<7>")
	)
	(arc
		(start 378.156216 -286.720788)
		(mid 378.339991 -286.670016)
		(end 378.525024 -286.715962)
		(width 0.09525)
		(layer "In2.Cu")
		(net "M_I_CPU0_SB_DQS_DP<7>")
	)
	(arc
		(start 392.254232 -286.721042)
		(mid 392.34462 -286.683337)
		(end 392.441684 -286.670242)
		(width 0.09525)
		(layer "In2.Cu")
		(net "M_I_CPU0_SB_DQS_DP<7>")
	)
	(arc
		(start 388.504684 -286.715962)
		(mid 388.689716 -286.670048)
		(end 388.873492 -286.720788)
		(width 0.09525)
		(layer "In2.Cu")
		(net "M_I_CPU0_SB_DQS_DP<7>")
	)
	(arc
		(start 385.67614 -286.720788)
		(mid 385.859915 -286.670016)
		(end 386.044948 -286.715962)
		(width 0.09525)
		(layer "In2.Cu")
		(net "M_I_CPU0_SB_DQS_DP<7>")
	)
	(arc
		(start 386.993384 -286.720788)
		(mid 387.274816 -286.796577)
		(end 387.556248 -286.720788)
		(width 0.09525)
		(layer "In2.Cu")
		(net "M_I_CPU0_SB_DQS_DP<7>")
	)
	(arc
		(start 391.324592 -286.715962)
		(mid 391.509624 -286.670048)
		(end 391.6934 -286.720788)
		(width 0.09525)
		(layer "In2.Cu")
		(net "M_I_CPU0_SB_DQS_DP<7>")
	)
	(arc
		(start 382.864614 -286.715962)
		(mid 383.049646 -286.670048)
		(end 383.233422 -286.720788)
		(width 0.09525)
		(layer "In2.Cu")
		(net "M_I_CPU0_SB_DQS_DP<7>")
	)
	(arc
		(start 386.616194 -286.720788)
		(mid 386.799969 -286.670016)
		(end 386.985002 -286.715962)
		(width 0.09525)
		(layer "In2.Cu")
		(net "M_I_CPU0_SB_DQS_DP<7>")
	)
	(segment
		(start 375.997978 -281.920188)
		(end 376.46483 -282.186126)
		(width 0.12954)
		(layer "F.Cu")
		(net "M_I_CPU0_SB_DQS_DP<6>")
	)
	(segment
		(start 402.554186 -287.023302)
		(end 402.554186 -287.751774)
		(width 0.16002)
		(layer "In2.Cu")
		(net "M_I_CPU0_SB_DQS_DP<6>")
	)
	(segment
		(start 395.776704 -282.061412)
		(end 395.835632 -282.12034)
		(width 0.09525)
		(layer "In2.Cu")
		(net "M_I_CPU0_SB_DQS_DP<6>")
	)
	(segment
		(start 390.744964 -281.85618)
		(end 390.753346 -281.861006)
		(width 0.09525)
		(layer "In2.Cu")
		(net "M_I_CPU0_SB_DQS_DP<6>")
	)
	(segment
		(start 393.883388 -282.061412)
		(end 395.776704 -282.061412)
		(width 0.09525)
		(layer "In2.Cu")
		(net "M_I_CPU0_SB_DQS_DP<6>")
	)
	(segment
		(start 392.254232 -281.86126)
		(end 392.276076 -281.848814)
		(width 0.09525)
		(layer "In2.Cu")
		(net "M_I_CPU0_SB_DQS_DP<6>")
	)
	(segment
		(start 413.258762 -296.660062)
		(end 413.623506 -296.295318)
		(width 0.16002)
		(layer "In2.Cu")
		(net "M_I_CPU0_SB_DQS_DP<6>")
	)
	(segment
		(start 415.57321 -295.810178)
		(end 418.036756 -295.810178)
		(width 0.16002)
		(layer "In2.Cu")
		(net "M_I_CPU0_SB_DQS_DP<6>")
	)
	(segment
		(start 396.922752 -282.12034)
		(end 401.591272 -286.78886)
		(width 0.16002)
		(layer "In2.Cu")
		(net "M_I_CPU0_SB_DQS_DP<6>")
	)
	(segment
		(start 402.319744 -286.78886)
		(end 402.554186 -287.023302)
		(width 0.16002)
		(layer "In2.Cu")
		(net "M_I_CPU0_SB_DQS_DP<6>")
	)
	(segment
		(start 395.835632 -282.12034)
		(end 395.859254 -282.12034)
		(width 0.09525)
		(layer "In2.Cu")
		(net "M_I_CPU0_SB_DQS_DP<6>")
	)
	(segment
		(start 380.036324 -281.861006)
		(end 380.044706 -281.85618)
		(width 0.09525)
		(layer "In2.Cu")
		(net "M_I_CPU0_SB_DQS_DP<6>")
	)
	(segment
		(start 408.048714 -292.51783)
		(end 408.048714 -293.246302)
		(width 0.16002)
		(layer "In2.Cu")
		(net "M_I_CPU0_SB_DQS_DP<6>")
	)
	(segment
		(start 401.591272 -286.78886)
		(end 402.319744 -286.78886)
		(width 0.16002)
		(layer "In2.Cu")
		(net "M_I_CPU0_SB_DQS_DP<6>")
	)
	(segment
		(start 402.554186 -287.751774)
		(end 402.964904 -288.162492)
		(width 0.16002)
		(layer "In2.Cu")
		(net "M_I_CPU0_SB_DQS_DP<6>")
	)
	(segment
		(start 391.31621 -281.861006)
		(end 391.324592 -281.85618)
		(width 0.09525)
		(layer "In2.Cu")
		(net "M_I_CPU0_SB_DQS_DP<6>")
	)
	(segment
		(start 409.187904 -293.65702)
		(end 409.422346 -293.891462)
		(width 0.16002)
		(layer "In2.Cu")
		(net "M_I_CPU0_SB_DQS_DP<6>")
	)
	(segment
		(start 388.496302 -281.861006)
		(end 388.504684 -281.85618)
		(width 0.09525)
		(layer "In2.Cu")
		(net "M_I_CPU0_SB_DQS_DP<6>")
	)
	(segment
		(start 378.525024 -281.85618)
		(end 378.533406 -281.861006)
		(width 0.09525)
		(layer "In2.Cu")
		(net "M_I_CPU0_SB_DQS_DP<6>")
	)
	(segment
		(start 382.856232 -281.861006)
		(end 382.864614 -281.85618)
		(width 0.09525)
		(layer "In2.Cu")
		(net "M_I_CPU0_SB_DQS_DP<6>")
	)
	(segment
		(start 387.556248 -281.861006)
		(end 387.56463 -281.85618)
		(width 0.09525)
		(layer "In2.Cu")
		(net "M_I_CPU0_SB_DQS_DP<6>")
	)
	(segment
		(start 409.422346 -293.891462)
		(end 409.422346 -294.619934)
		(width 0.16002)
		(layer "In2.Cu")
		(net "M_I_CPU0_SB_DQS_DP<6>")
	)
	(segment
		(start 376.310906 -281.920696)
		(end 376.33402 -281.834082)
		(width 0.09525)
		(layer "In2.Cu")
		(net "M_I_CPU0_SB_DQS_DP<6>")
	)
	(segment
		(start 425.936156 -295.778682)
		(end 426.416216 -295.778682)
		(width 0.16002)
		(layer "In2.Cu")
		(net "M_I_CPU0_SB_DQS_DP<6>")
	)
	(segment
		(start 421.913558 -295.9862)
		(end 422.39692 -295.502838)
		(width 0.16002)
		(layer "In2.Cu")
		(net "M_I_CPU0_SB_DQS_DP<6>")
	)
	(segment
		(start 408.459432 -293.65702)
		(end 409.187904 -293.65702)
		(width 0.16002)
		(layer "In2.Cu")
		(net "M_I_CPU0_SB_DQS_DP<6>")
	)
	(segment
		(start 392.629898 -281.861006)
		(end 392.65606 -281.876246)
		(width 0.09525)
		(layer "In2.Cu")
		(net "M_I_CPU0_SB_DQS_DP<6>")
	)
	(segment
		(start 393.63142 -281.809444)
		(end 393.883388 -282.061412)
		(width 0.09525)
		(layer "In2.Cu")
		(net "M_I_CPU0_SB_DQS_DP<6>")
	)
	(segment
		(start 425.19092 -295.810178)
		(end 425.339256 -295.661842)
		(width 0.16002)
		(layer "In2.Cu")
		(net "M_I_CPU0_SB_DQS_DP<6>")
	)
	(segment
		(start 422.809924 -295.502838)
		(end 423.117264 -295.810178)
		(width 0.16002)
		(layer "In2.Cu")
		(net "M_I_CPU0_SB_DQS_DP<6>")
	)
	(segment
		(start 418.036756 -295.810178)
		(end 418.886894 -296.660316)
		(width 0.16002)
		(layer "In2.Cu")
		(net "M_I_CPU0_SB_DQS_DP<6>")
	)
	(segment
		(start 411.462474 -296.660062)
		(end 413.258762 -296.660062)
		(width 0.16002)
		(layer "In2.Cu")
		(net "M_I_CPU0_SB_DQS_DP<6>")
	)
	(segment
		(start 414.060386 -296.295318)
		(end 414.852866 -295.502838)
		(width 0.16002)
		(layer "In2.Cu")
		(net "M_I_CPU0_SB_DQS_DP<6>")
	)
	(segment
		(start 426.533056 -295.661842)
		(end 427.182788 -295.661842)
		(width 0.16002)
		(layer "In2.Cu")
		(net "M_I_CPU0_SB_DQS_DP<6>")
	)
	(segment
		(start 405.067008 -289.536124)
		(end 405.30145 -289.770566)
		(width 0.16002)
		(layer "In2.Cu")
		(net "M_I_CPU0_SB_DQS_DP<6>")
	)
	(segment
		(start 422.39692 -295.502838)
		(end 422.809924 -295.502838)
		(width 0.16002)
		(layer "In2.Cu")
		(net "M_I_CPU0_SB_DQS_DP<6>")
	)
	(segment
		(start 377.58497 -281.85618)
		(end 377.593352 -281.861006)
		(width 0.09525)
		(layer "In2.Cu")
		(net "M_I_CPU0_SB_DQS_DP<6>")
	)
	(segment
		(start 423.117264 -295.810178)
		(end 425.19092 -295.810178)
		(width 0.16002)
		(layer "In2.Cu")
		(net "M_I_CPU0_SB_DQS_DP<6>")
	)
	(segment
		(start 402.964904 -288.162492)
		(end 403.693376 -288.162492)
		(width 0.16002)
		(layer "In2.Cu")
		(net "M_I_CPU0_SB_DQS_DP<6>")
	)
	(segment
		(start 406.44064 -290.909756)
		(end 406.675082 -291.144198)
		(width 0.16002)
		(layer "In2.Cu")
		(net "M_I_CPU0_SB_DQS_DP<6>")
	)
	(segment
		(start 379.09627 -281.861006)
		(end 379.104652 -281.85618)
		(width 0.09525)
		(layer "In2.Cu")
		(net "M_I_CPU0_SB_DQS_DP<6>")
	)
	(segment
		(start 383.796286 -281.861006)
		(end 383.804668 -281.85618)
		(width 0.09525)
		(layer "In2.Cu")
		(net "M_I_CPU0_SB_DQS_DP<6>")
	)
	(segment
		(start 425.339256 -295.661842)
		(end 425.819316 -295.661842)
		(width 0.16002)
		(layer "In2.Cu")
		(net "M_I_CPU0_SB_DQS_DP<6>")
	)
	(segment
		(start 427.182788 -295.661842)
		(end 427.456092 -295.935146)
		(width 0.16002)
		(layer "In2.Cu")
		(net "M_I_CPU0_SB_DQS_DP<6>")
	)
	(segment
		(start 421.16756 -296.295318)
		(end 421.913558 -295.9862)
		(width 0.16002)
		(layer "In2.Cu")
		(net "M_I_CPU0_SB_DQS_DP<6>")
	)
	(segment
		(start 426.416216 -295.778682)
		(end 426.533056 -295.661842)
		(width 0.16002)
		(layer "In2.Cu")
		(net "M_I_CPU0_SB_DQS_DP<6>")
	)
	(segment
		(start 386.044948 -281.85618)
		(end 386.05333 -281.861006)
		(width 0.09525)
		(layer "In2.Cu")
		(net "M_I_CPU0_SB_DQS_DP<6>")
	)
	(segment
		(start 418.886894 -296.660316)
		(end 420.802562 -296.660316)
		(width 0.16002)
		(layer "In2.Cu")
		(net "M_I_CPU0_SB_DQS_DP<6>")
	)
	(segment
		(start 393.384786 -281.809444)
		(end 393.63142 -281.809444)
		(width 0.09525)
		(layer "In2.Cu")
		(net "M_I_CPU0_SB_DQS_DP<6>")
	)
	(segment
		(start 404.338536 -289.536124)
		(end 405.067008 -289.536124)
		(width 0.16002)
		(layer "In2.Cu")
		(net "M_I_CPU0_SB_DQS_DP<6>")
	)
	(segment
		(start 405.712168 -290.909756)
		(end 406.44064 -290.909756)
		(width 0.16002)
		(layer "In2.Cu")
		(net "M_I_CPU0_SB_DQS_DP<6>")
	)
	(segment
		(start 407.0858 -292.283388)
		(end 407.814272 -292.283388)
		(width 0.16002)
		(layer "In2.Cu")
		(net "M_I_CPU0_SB_DQS_DP<6>")
	)
	(segment
		(start 403.927818 -289.125406)
		(end 404.338536 -289.536124)
		(width 0.16002)
		(layer "In2.Cu")
		(net "M_I_CPU0_SB_DQS_DP<6>")
	)
	(segment
		(start 386.985002 -281.85618)
		(end 386.993384 -281.861006)
		(width 0.09525)
		(layer "In2.Cu")
		(net "M_I_CPU0_SB_DQS_DP<6>")
	)
	(segment
		(start 382.284986 -281.85618)
		(end 382.293368 -281.861006)
		(width 0.09525)
		(layer "In2.Cu")
		(net "M_I_CPU0_SB_DQS_DP<6>")
	)
	(segment
		(start 408.048714 -293.246302)
		(end 408.459432 -293.65702)
		(width 0.16002)
		(layer "In2.Cu")
		(net "M_I_CPU0_SB_DQS_DP<6>")
	)
	(segment
		(start 405.30145 -290.499038)
		(end 405.712168 -290.909756)
		(width 0.16002)
		(layer "In2.Cu")
		(net "M_I_CPU0_SB_DQS_DP<6>")
	)
	(segment
		(start 413.623506 -296.295318)
		(end 414.060386 -296.295318)
		(width 0.16002)
		(layer "In2.Cu")
		(net "M_I_CPU0_SB_DQS_DP<6>")
	)
	(segment
		(start 407.814272 -292.283388)
		(end 408.048714 -292.51783)
		(width 0.16002)
		(layer "In2.Cu")
		(net "M_I_CPU0_SB_DQS_DP<6>")
	)
	(segment
		(start 420.802562 -296.660316)
		(end 421.16756 -296.295318)
		(width 0.16002)
		(layer "In2.Cu")
		(net "M_I_CPU0_SB_DQS_DP<6>")
	)
	(segment
		(start 415.26587 -295.502838)
		(end 415.57321 -295.810178)
		(width 0.16002)
		(layer "In2.Cu")
		(net "M_I_CPU0_SB_DQS_DP<6>")
	)
	(segment
		(start 405.30145 -289.770566)
		(end 405.30145 -290.499038)
		(width 0.16002)
		(layer "In2.Cu")
		(net "M_I_CPU0_SB_DQS_DP<6>")
	)
	(segment
		(start 414.852866 -295.502838)
		(end 415.26587 -295.502838)
		(width 0.16002)
		(layer "In2.Cu")
		(net "M_I_CPU0_SB_DQS_DP<6>")
	)
	(segment
		(start 425.819316 -295.661842)
		(end 425.936156 -295.778682)
		(width 0.16002)
		(layer "In2.Cu")
		(net "M_I_CPU0_SB_DQS_DP<6>")
	)
	(segment
		(start 406.675082 -291.87267)
		(end 407.0858 -292.283388)
		(width 0.16002)
		(layer "In2.Cu")
		(net "M_I_CPU0_SB_DQS_DP<6>")
	)
	(segment
		(start 403.927818 -288.396934)
		(end 403.927818 -289.125406)
		(width 0.16002)
		(layer "In2.Cu")
		(net "M_I_CPU0_SB_DQS_DP<6>")
	)
	(segment
		(start 392.228324 -281.876246)
		(end 392.254232 -281.86126)
		(width 0.09525)
		(layer "In2.Cu")
		(net "M_I_CPU0_SB_DQS_DP<6>")
	)
	(segment
		(start 409.422346 -294.619934)
		(end 411.462474 -296.660062)
		(width 0.16002)
		(layer "In2.Cu")
		(net "M_I_CPU0_SB_DQS_DP<6>")
	)
	(segment
		(start 395.859254 -282.12034)
		(end 396.922752 -282.12034)
		(width 0.16002)
		(layer "In2.Cu")
		(net "M_I_CPU0_SB_DQS_DP<6>")
	)
	(segment
		(start 376.46483 -282.186126)
		(end 376.310906 -281.920696)
		(width 0.09525)
		(layer "In2.Cu")
		(net "M_I_CPU0_SB_DQS_DP<6>")
	)
	(segment
		(start 406.675082 -291.144198)
		(end 406.675082 -291.87267)
		(width 0.16002)
		(layer "In2.Cu")
		(net "M_I_CPU0_SB_DQS_DP<6>")
	)
	(segment
		(start 403.693376 -288.162492)
		(end 403.927818 -288.396934)
		(width 0.16002)
		(layer "In2.Cu")
		(net "M_I_CPU0_SB_DQS_DP<6>")
	)
	(arc
		(start 380.044706 -281.85618)
		(mid 380.229738 -281.810266)
		(end 380.413514 -281.861006)
		(width 0.09525)
		(layer "In2.Cu")
		(net "M_I_CPU0_SB_DQS_DP<6>")
	)
	(arc
		(start 392.65606 -281.876246)
		(mid 392.927416 -281.937395)
		(end 393.194794 -281.860752)
		(width 0.09525)
		(layer "In2.Cu")
		(net "M_I_CPU0_SB_DQS_DP<6>")
	)
	(arc
		(start 386.616194 -281.861006)
		(mid 386.799969 -281.810234)
		(end 386.985002 -281.85618)
		(width 0.09525)
		(layer "In2.Cu")
		(net "M_I_CPU0_SB_DQS_DP<6>")
	)
	(arc
		(start 393.194794 -281.860752)
		(mid 393.286382 -281.822484)
		(end 393.384786 -281.809444)
		(width 0.09525)
		(layer "In2.Cu")
		(net "M_I_CPU0_SB_DQS_DP<6>")
	)
	(arc
		(start 382.293368 -281.861006)
		(mid 382.5748 -281.936761)
		(end 382.856232 -281.861006)
		(width 0.09525)
		(layer "In2.Cu")
		(net "M_I_CPU0_SB_DQS_DP<6>")
	)
	(arc
		(start 387.933438 -281.861006)
		(mid 388.21487 -281.936761)
		(end 388.496302 -281.861006)
		(width 0.09525)
		(layer "In2.Cu")
		(net "M_I_CPU0_SB_DQS_DP<6>")
	)
	(arc
		(start 386.05333 -281.861006)
		(mid 386.334762 -281.936761)
		(end 386.616194 -281.861006)
		(width 0.09525)
		(layer "In2.Cu")
		(net "M_I_CPU0_SB_DQS_DP<6>")
	)
	(arc
		(start 386.993384 -281.861006)
		(mid 387.274816 -281.936761)
		(end 387.556248 -281.861006)
		(width 0.09525)
		(layer "In2.Cu")
		(net "M_I_CPU0_SB_DQS_DP<6>")
	)
	(arc
		(start 376.33402 -281.834082)
		(mid 376.496671 -281.811822)
		(end 376.653298 -281.861006)
		(width 0.09525)
		(layer "In2.Cu")
		(net "M_I_CPU0_SB_DQS_DP<6>")
	)
	(arc
		(start 377.216162 -281.861006)
		(mid 377.399937 -281.810234)
		(end 377.58497 -281.85618)
		(width 0.09525)
		(layer "In2.Cu")
		(net "M_I_CPU0_SB_DQS_DP<6>")
	)
	(arc
		(start 384.73634 -281.861006)
		(mid 384.924808 -281.810329)
		(end 385.113276 -281.861006)
		(width 0.09525)
		(layer "In2.Cu")
		(net "M_I_CPU0_SB_DQS_DP<6>")
	)
	(arc
		(start 390.376156 -281.861006)
		(mid 390.559931 -281.810234)
		(end 390.744964 -281.85618)
		(width 0.09525)
		(layer "In2.Cu")
		(net "M_I_CPU0_SB_DQS_DP<6>")
	)
	(arc
		(start 388.873492 -281.861006)
		(mid 389.154924 -281.936761)
		(end 389.436356 -281.861006)
		(width 0.09525)
		(layer "In2.Cu")
		(net "M_I_CPU0_SB_DQS_DP<6>")
	)
	(arc
		(start 378.533406 -281.861006)
		(mid 378.814838 -281.936761)
		(end 379.09627 -281.861006)
		(width 0.09525)
		(layer "In2.Cu")
		(net "M_I_CPU0_SB_DQS_DP<6>")
	)
	(arc
		(start 378.156216 -281.861006)
		(mid 378.339991 -281.810234)
		(end 378.525024 -281.85618)
		(width 0.09525)
		(layer "In2.Cu")
		(net "M_I_CPU0_SB_DQS_DP<6>")
	)
	(arc
		(start 382.864614 -281.85618)
		(mid 383.049646 -281.810266)
		(end 383.233422 -281.861006)
		(width 0.09525)
		(layer "In2.Cu")
		(net "M_I_CPU0_SB_DQS_DP<6>")
	)
	(arc
		(start 390.753346 -281.861006)
		(mid 391.034778 -281.936761)
		(end 391.31621 -281.861006)
		(width 0.09525)
		(layer "In2.Cu")
		(net "M_I_CPU0_SB_DQS_DP<6>")
	)
	(arc
		(start 376.653298 -281.861006)
		(mid 376.93473 -281.936761)
		(end 377.216162 -281.861006)
		(width 0.09525)
		(layer "In2.Cu")
		(net "M_I_CPU0_SB_DQS_DP<6>")
	)
	(arc
		(start 377.593352 -281.861006)
		(mid 377.874784 -281.936761)
		(end 378.156216 -281.861006)
		(width 0.09525)
		(layer "In2.Cu")
		(net "M_I_CPU0_SB_DQS_DP<6>")
	)
	(arc
		(start 387.56463 -281.85618)
		(mid 387.749662 -281.810266)
		(end 387.933438 -281.861006)
		(width 0.09525)
		(layer "In2.Cu")
		(net "M_I_CPU0_SB_DQS_DP<6>")
	)
	(arc
		(start 389.436356 -281.861006)
		(mid 389.624824 -281.810329)
		(end 389.813292 -281.861006)
		(width 0.09525)
		(layer "In2.Cu")
		(net "M_I_CPU0_SB_DQS_DP<6>")
	)
	(arc
		(start 379.47346 -281.861006)
		(mid 379.754892 -281.936761)
		(end 380.036324 -281.861006)
		(width 0.09525)
		(layer "In2.Cu")
		(net "M_I_CPU0_SB_DQS_DP<6>")
	)
	(arc
		(start 392.276076 -281.848814)
		(mid 392.454528 -281.810572)
		(end 392.629898 -281.861006)
		(width 0.09525)
		(layer "In2.Cu")
		(net "M_I_CPU0_SB_DQS_DP<6>")
	)
	(arc
		(start 380.413514 -281.861006)
		(mid 380.694946 -281.936761)
		(end 380.976378 -281.861006)
		(width 0.09525)
		(layer "In2.Cu")
		(net "M_I_CPU0_SB_DQS_DP<6>")
	)
	(arc
		(start 391.324592 -281.85618)
		(mid 391.509624 -281.810266)
		(end 391.6934 -281.861006)
		(width 0.09525)
		(layer "In2.Cu")
		(net "M_I_CPU0_SB_DQS_DP<6>")
	)
	(arc
		(start 381.916178 -281.861006)
		(mid 382.099953 -281.810234)
		(end 382.284986 -281.85618)
		(width 0.09525)
		(layer "In2.Cu")
		(net "M_I_CPU0_SB_DQS_DP<6>")
	)
	(arc
		(start 385.113276 -281.861006)
		(mid 385.394708 -281.936761)
		(end 385.67614 -281.861006)
		(width 0.09525)
		(layer "In2.Cu")
		(net "M_I_CPU0_SB_DQS_DP<6>")
	)
	(arc
		(start 381.353314 -281.861006)
		(mid 381.634746 -281.936761)
		(end 381.916178 -281.861006)
		(width 0.09525)
		(layer "In2.Cu")
		(net "M_I_CPU0_SB_DQS_DP<6>")
	)
	(arc
		(start 384.173476 -281.861006)
		(mid 384.454908 -281.936761)
		(end 384.73634 -281.861006)
		(width 0.09525)
		(layer "In2.Cu")
		(net "M_I_CPU0_SB_DQS_DP<6>")
	)
	(arc
		(start 389.813292 -281.861006)
		(mid 390.094724 -281.936761)
		(end 390.376156 -281.861006)
		(width 0.09525)
		(layer "In2.Cu")
		(net "M_I_CPU0_SB_DQS_DP<6>")
	)
	(arc
		(start 380.976378 -281.861006)
		(mid 381.164846 -281.810329)
		(end 381.353314 -281.861006)
		(width 0.09525)
		(layer "In2.Cu")
		(net "M_I_CPU0_SB_DQS_DP<6>")
	)
	(arc
		(start 385.67614 -281.861006)
		(mid 385.859915 -281.810234)
		(end 386.044948 -281.85618)
		(width 0.09525)
		(layer "In2.Cu")
		(net "M_I_CPU0_SB_DQS_DP<6>")
	)
	(arc
		(start 379.104652 -281.85618)
		(mid 379.289684 -281.810266)
		(end 379.47346 -281.861006)
		(width 0.09525)
		(layer "In2.Cu")
		(net "M_I_CPU0_SB_DQS_DP<6>")
	)
	(arc
		(start 383.233422 -281.861006)
		(mid 383.514854 -281.936761)
		(end 383.796286 -281.861006)
		(width 0.09525)
		(layer "In2.Cu")
		(net "M_I_CPU0_SB_DQS_DP<6>")
	)
	(arc
		(start 388.504684 -281.85618)
		(mid 388.689716 -281.810266)
		(end 388.873492 -281.861006)
		(width 0.09525)
		(layer "In2.Cu")
		(net "M_I_CPU0_SB_DQS_DP<6>")
	)
	(arc
		(start 383.804668 -281.85618)
		(mid 383.9897 -281.810266)
		(end 384.173476 -281.861006)
		(width 0.09525)
		(layer "In2.Cu")
		(net "M_I_CPU0_SB_DQS_DP<6>")
	)
	(arc
		(start 391.6934 -281.861006)
		(mid 391.95892 -281.936535)
		(end 392.228324 -281.876246)
		(width 0.09525)
		(layer "In2.Cu")
		(net "M_I_CPU0_SB_DQS_DP<6>")
	)
	(segment
		(start 375.997978 -277.060152)
		(end 376.46483 -277.32609)
		(width 0.12954)
		(layer "F.Cu")
		(net "M_I_CPU0_SB_DQS_DP<5>")
	)
	(segment
		(start 404.646892 -281.125422)
		(end 404.241508 -280.720038)
		(width 0.16002)
		(layer "In2.Cu")
		(net "M_I_CPU0_SB_DQS_DP<5>")
	)
	(segment
		(start 401.494244 -277.972774)
		(end 401.494244 -277.482554)
		(width 0.16002)
		(layer "In2.Cu")
		(net "M_I_CPU0_SB_DQS_DP<5>")
	)
	(segment
		(start 393.85748 -276.80412)
		(end 393.636246 -276.80412)
		(width 0.09525)
		(layer "In2.Cu")
		(net "M_I_CPU0_SB_DQS_DP<5>")
	)
	(segment
		(start 402.495766 -278.484076)
		(end 402.005546 -278.484076)
		(width 0.16002)
		(layer "In2.Cu")
		(net "M_I_CPU0_SB_DQS_DP<5>")
	)
	(segment
		(start 421.60444 -286.945324)
		(end 421.16756 -286.945324)
		(width 0.16002)
		(layer "In2.Cu")
		(net "M_I_CPU0_SB_DQS_DP<5>")
	)
	(segment
		(start 414.946084 -286.059626)
		(end 414.060386 -286.945324)
		(width 0.16002)
		(layer "In2.Cu")
		(net "M_I_CPU0_SB_DQS_DP<5>")
	)
	(segment
		(start 402.867876 -279.346406)
		(end 402.867876 -278.856186)
		(width 0.16002)
		(layer "In2.Cu")
		(net "M_I_CPU0_SB_DQS_DP<5>")
	)
	(segment
		(start 427.456092 -286.585152)
		(end 427.182788 -286.311848)
		(width 0.16002)
		(layer "In2.Cu")
		(net "M_I_CPU0_SB_DQS_DP<5>")
	)
	(segment
		(start 422.716706 -286.059626)
		(end 422.490138 -286.059626)
		(width 0.16002)
		(layer "In2.Cu")
		(net "M_I_CPU0_SB_DQS_DP<5>")
	)
	(segment
		(start 403.379178 -279.857708)
		(end 402.867876 -279.346406)
		(width 0.16002)
		(layer "In2.Cu")
		(net "M_I_CPU0_SB_DQS_DP<5>")
	)
	(segment
		(start 402.005546 -278.484076)
		(end 401.494244 -277.972774)
		(width 0.16002)
		(layer "In2.Cu")
		(net "M_I_CPU0_SB_DQS_DP<5>")
	)
	(segment
		(start 400.631914 -277.110444)
		(end 400.026378 -276.504908)
		(width 0.16002)
		(layer "In2.Cu")
		(net "M_I_CPU0_SB_DQS_DP<5>")
	)
	(segment
		(start 426.533056 -286.311848)
		(end 426.416216 -286.428688)
		(width 0.16002)
		(layer "In2.Cu")
		(net "M_I_CPU0_SB_DQS_DP<5>")
	)
	(segment
		(start 400.026378 -276.504908)
		(end 400.026378 -276.27834)
		(width 0.16002)
		(layer "In2.Cu")
		(net "M_I_CPU0_SB_DQS_DP<5>")
	)
	(segment
		(start 393.202668 -277.000716)
		(end 393.194794 -277.000716)
		(width 0.09525)
		(layer "In2.Cu")
		(net "M_I_CPU0_SB_DQS_DP<5>")
	)
	(segment
		(start 401.494244 -277.482554)
		(end 401.122134 -277.110444)
		(width 0.16002)
		(layer "In2.Cu")
		(net "M_I_CPU0_SB_DQS_DP<5>")
	)
	(segment
		(start 427.182788 -286.311848)
		(end 426.533056 -286.311848)
		(width 0.16002)
		(layer "In2.Cu")
		(net "M_I_CPU0_SB_DQS_DP<5>")
	)
	(segment
		(start 402.867876 -278.856186)
		(end 402.495766 -278.484076)
		(width 0.16002)
		(layer "In2.Cu")
		(net "M_I_CPU0_SB_DQS_DP<5>")
	)
	(segment
		(start 425.936156 -286.428688)
		(end 425.819316 -286.311848)
		(width 0.16002)
		(layer "In2.Cu")
		(net "M_I_CPU0_SB_DQS_DP<5>")
	)
	(segment
		(start 425.19092 -286.460184)
		(end 423.117264 -286.460184)
		(width 0.16002)
		(layer "In2.Cu")
		(net "M_I_CPU0_SB_DQS_DP<5>")
	)
	(segment
		(start 376.33402 -276.974046)
		(end 376.310906 -277.06066)
		(width 0.09525)
		(layer "In2.Cu")
		(net "M_I_CPU0_SB_DQS_DP<5>")
	)
	(segment
		(start 394.90015 -275.76145)
		(end 393.85748 -276.80412)
		(width 0.09525)
		(layer "In2.Cu")
		(net "M_I_CPU0_SB_DQS_DP<5>")
	)
	(segment
		(start 408.91079 -284.2514)
		(end 408.611324 -283.951934)
		(width 0.16002)
		(layer "In2.Cu")
		(net "M_I_CPU0_SB_DQS_DP<5>")
	)
	(segment
		(start 405.176228 -281.125422)
		(end 404.646892 -281.125422)
		(width 0.16002)
		(layer "In2.Cu")
		(net "M_I_CPU0_SB_DQS_DP<5>")
	)
	(segment
		(start 395.776704 -276.059138)
		(end 395.357096 -276.059138)
		(width 0.09525)
		(layer "In2.Cu")
		(net "M_I_CPU0_SB_DQS_DP<5>")
	)
	(segment
		(start 387.56463 -276.996144)
		(end 387.556248 -277.00097)
		(width 0.09525)
		(layer "In2.Cu")
		(net "M_I_CPU0_SB_DQS_DP<5>")
	)
	(segment
		(start 425.819316 -286.311848)
		(end 425.339256 -286.311848)
		(width 0.16002)
		(layer "In2.Cu")
		(net "M_I_CPU0_SB_DQS_DP<5>")
	)
	(segment
		(start 395.357096 -276.059138)
		(end 395.059408 -275.76145)
		(width 0.09525)
		(layer "In2.Cu")
		(net "M_I_CPU0_SB_DQS_DP<5>")
	)
	(segment
		(start 386.05333 -277.00097)
		(end 386.044948 -276.996144)
		(width 0.09525)
		(layer "In2.Cu")
		(net "M_I_CPU0_SB_DQS_DP<5>")
	)
	(segment
		(start 422.490138 -286.059626)
		(end 421.60444 -286.945324)
		(width 0.16002)
		(layer "In2.Cu")
		(net "M_I_CPU0_SB_DQS_DP<5>")
	)
	(segment
		(start 409.364434 -285.313628)
		(end 408.91079 -284.859984)
		(width 0.16002)
		(layer "In2.Cu")
		(net "M_I_CPU0_SB_DQS_DP<5>")
	)
	(segment
		(start 404.241508 -280.229818)
		(end 403.869398 -279.857708)
		(width 0.16002)
		(layer "In2.Cu")
		(net "M_I_CPU0_SB_DQS_DP<5>")
	)
	(segment
		(start 408.91079 -284.859984)
		(end 408.91079 -284.2514)
		(width 0.16002)
		(layer "In2.Cu")
		(net "M_I_CPU0_SB_DQS_DP<5>")
	)
	(segment
		(start 403.869398 -279.857708)
		(end 403.379178 -279.857708)
		(width 0.16002)
		(layer "In2.Cu")
		(net "M_I_CPU0_SB_DQS_DP<5>")
	)
	(segment
		(start 378.533406 -277.00097)
		(end 378.525024 -276.996144)
		(width 0.09525)
		(layer "In2.Cu")
		(net "M_I_CPU0_SB_DQS_DP<5>")
	)
	(segment
		(start 420.802562 -287.310322)
		(end 418.886894 -287.310322)
		(width 0.16002)
		(layer "In2.Cu")
		(net "M_I_CPU0_SB_DQS_DP<5>")
	)
	(segment
		(start 395.835632 -276.118066)
		(end 395.776704 -276.059138)
		(width 0.09525)
		(layer "In2.Cu")
		(net "M_I_CPU0_SB_DQS_DP<5>")
	)
	(segment
		(start 425.339256 -286.311848)
		(end 425.19092 -286.460184)
		(width 0.16002)
		(layer "In2.Cu")
		(net "M_I_CPU0_SB_DQS_DP<5>")
	)
	(segment
		(start 393.231624 -276.97176)
		(end 393.202668 -277.000716)
		(width 0.09525)
		(layer "In2.Cu")
		(net "M_I_CPU0_SB_DQS_DP<5>")
	)
	(segment
		(start 377.593352 -277.00097)
		(end 377.58497 -276.996144)
		(width 0.09525)
		(layer "In2.Cu")
		(net "M_I_CPU0_SB_DQS_DP<5>")
	)
	(segment
		(start 400.026378 -276.27834)
		(end 399.866104 -276.118066)
		(width 0.16002)
		(layer "In2.Cu")
		(net "M_I_CPU0_SB_DQS_DP<5>")
	)
	(segment
		(start 386.993384 -277.00097)
		(end 386.985002 -276.996144)
		(width 0.09525)
		(layer "In2.Cu")
		(net "M_I_CPU0_SB_DQS_DP<5>")
	)
	(segment
		(start 376.310906 -277.06066)
		(end 376.46483 -277.32609)
		(width 0.09525)
		(layer "In2.Cu")
		(net "M_I_CPU0_SB_DQS_DP<5>")
	)
	(segment
		(start 413.623506 -286.945324)
		(end 413.258762 -287.310068)
		(width 0.16002)
		(layer "In2.Cu")
		(net "M_I_CPU0_SB_DQS_DP<5>")
	)
	(segment
		(start 409.973018 -285.313628)
		(end 409.364434 -285.313628)
		(width 0.16002)
		(layer "In2.Cu")
		(net "M_I_CPU0_SB_DQS_DP<5>")
	)
	(segment
		(start 392.254232 -277.001224)
		(end 392.228324 -277.01621)
		(width 0.09525)
		(layer "In2.Cu")
		(net "M_I_CPU0_SB_DQS_DP<5>")
	)
	(segment
		(start 408.00274 -283.951934)
		(end 405.176228 -281.125422)
		(width 0.16002)
		(layer "In2.Cu")
		(net "M_I_CPU0_SB_DQS_DP<5>")
	)
	(segment
		(start 410.29636 -286.245554)
		(end 410.29636 -285.63697)
		(width 0.16002)
		(layer "In2.Cu")
		(net "M_I_CPU0_SB_DQS_DP<5>")
	)
	(segment
		(start 410.29636 -285.63697)
		(end 409.973018 -285.313628)
		(width 0.16002)
		(layer "In2.Cu")
		(net "M_I_CPU0_SB_DQS_DP<5>")
	)
	(segment
		(start 423.117264 -286.460184)
		(end 422.716706 -286.059626)
		(width 0.16002)
		(layer "In2.Cu")
		(net "M_I_CPU0_SB_DQS_DP<5>")
	)
	(segment
		(start 382.293368 -277.00097)
		(end 382.284986 -276.996144)
		(width 0.09525)
		(layer "In2.Cu")
		(net "M_I_CPU0_SB_DQS_DP<5>")
	)
	(segment
		(start 388.504684 -276.996144)
		(end 388.496302 -277.00097)
		(width 0.09525)
		(layer "In2.Cu")
		(net "M_I_CPU0_SB_DQS_DP<5>")
	)
	(segment
		(start 418.036756 -286.460184)
		(end 415.57321 -286.460184)
		(width 0.16002)
		(layer "In2.Cu")
		(net "M_I_CPU0_SB_DQS_DP<5>")
	)
	(segment
		(start 401.122134 -277.110444)
		(end 400.631914 -277.110444)
		(width 0.16002)
		(layer "In2.Cu")
		(net "M_I_CPU0_SB_DQS_DP<5>")
	)
	(segment
		(start 414.060386 -286.945324)
		(end 413.623506 -286.945324)
		(width 0.16002)
		(layer "In2.Cu")
		(net "M_I_CPU0_SB_DQS_DP<5>")
	)
	(segment
		(start 418.886894 -287.310322)
		(end 418.036756 -286.460184)
		(width 0.16002)
		(layer "In2.Cu")
		(net "M_I_CPU0_SB_DQS_DP<5>")
	)
	(segment
		(start 415.172652 -286.059626)
		(end 414.946084 -286.059626)
		(width 0.16002)
		(layer "In2.Cu")
		(net "M_I_CPU0_SB_DQS_DP<5>")
	)
	(segment
		(start 421.16756 -286.945324)
		(end 420.802562 -287.310322)
		(width 0.16002)
		(layer "In2.Cu")
		(net "M_I_CPU0_SB_DQS_DP<5>")
	)
	(segment
		(start 379.104652 -276.996144)
		(end 379.09627 -277.00097)
		(width 0.09525)
		(layer "In2.Cu")
		(net "M_I_CPU0_SB_DQS_DP<5>")
	)
	(segment
		(start 392.65606 -277.01621)
		(end 392.629898 -277.00097)
		(width 0.09525)
		(layer "In2.Cu")
		(net "M_I_CPU0_SB_DQS_DP<5>")
	)
	(segment
		(start 426.416216 -286.428688)
		(end 425.936156 -286.428688)
		(width 0.16002)
		(layer "In2.Cu")
		(net "M_I_CPU0_SB_DQS_DP<5>")
	)
	(segment
		(start 380.044706 -276.996144)
		(end 380.036324 -277.00097)
		(width 0.09525)
		(layer "In2.Cu")
		(net "M_I_CPU0_SB_DQS_DP<5>")
	)
	(segment
		(start 390.753346 -277.00097)
		(end 390.744964 -276.996144)
		(width 0.09525)
		(layer "In2.Cu")
		(net "M_I_CPU0_SB_DQS_DP<5>")
	)
	(segment
		(start 392.276076 -276.988778)
		(end 392.254232 -277.001224)
		(width 0.09525)
		(layer "In2.Cu")
		(net "M_I_CPU0_SB_DQS_DP<5>")
	)
	(segment
		(start 411.360874 -287.310068)
		(end 410.29636 -286.245554)
		(width 0.16002)
		(layer "In2.Cu")
		(net "M_I_CPU0_SB_DQS_DP<5>")
	)
	(segment
		(start 391.324592 -276.996144)
		(end 391.31621 -277.00097)
		(width 0.09525)
		(layer "In2.Cu")
		(net "M_I_CPU0_SB_DQS_DP<5>")
	)
	(segment
		(start 395.859254 -276.118066)
		(end 395.835632 -276.118066)
		(width 0.09525)
		(layer "In2.Cu")
		(net "M_I_CPU0_SB_DQS_DP<5>")
	)
	(segment
		(start 395.059408 -275.76145)
		(end 394.90015 -275.76145)
		(width 0.09525)
		(layer "In2.Cu")
		(net "M_I_CPU0_SB_DQS_DP<5>")
	)
	(segment
		(start 383.804668 -276.996144)
		(end 383.796286 -277.00097)
		(width 0.09525)
		(layer "In2.Cu")
		(net "M_I_CPU0_SB_DQS_DP<5>")
	)
	(segment
		(start 408.611324 -283.951934)
		(end 408.00274 -283.951934)
		(width 0.16002)
		(layer "In2.Cu")
		(net "M_I_CPU0_SB_DQS_DP<5>")
	)
	(segment
		(start 415.57321 -286.460184)
		(end 415.172652 -286.059626)
		(width 0.16002)
		(layer "In2.Cu")
		(net "M_I_CPU0_SB_DQS_DP<5>")
	)
	(segment
		(start 399.866104 -276.118066)
		(end 395.859254 -276.118066)
		(width 0.16002)
		(layer "In2.Cu")
		(net "M_I_CPU0_SB_DQS_DP<5>")
	)
	(segment
		(start 413.258762 -287.310068)
		(end 411.360874 -287.310068)
		(width 0.16002)
		(layer "In2.Cu")
		(net "M_I_CPU0_SB_DQS_DP<5>")
	)
	(segment
		(start 404.241508 -280.720038)
		(end 404.241508 -280.229818)
		(width 0.16002)
		(layer "In2.Cu")
		(net "M_I_CPU0_SB_DQS_DP<5>")
	)
	(segment
		(start 382.864614 -276.996144)
		(end 382.856232 -277.00097)
		(width 0.09525)
		(layer "In2.Cu")
		(net "M_I_CPU0_SB_DQS_DP<5>")
	)
	(arc
		(start 376.653298 -277.00097)
		(mid 376.496671 -276.951784)
		(end 376.33402 -276.974046)
		(width 0.09525)
		(layer "In2.Cu")
		(net "M_I_CPU0_SB_DQS_DP<5>")
	)
	(arc
		(start 387.556248 -277.00097)
		(mid 387.274816 -277.076725)
		(end 386.993384 -277.00097)
		(width 0.09525)
		(layer "In2.Cu")
		(net "M_I_CPU0_SB_DQS_DP<5>")
	)
	(arc
		(start 377.216162 -277.00097)
		(mid 376.93473 -277.076725)
		(end 376.653298 -277.00097)
		(width 0.09525)
		(layer "In2.Cu")
		(net "M_I_CPU0_SB_DQS_DP<5>")
	)
	(arc
		(start 384.173476 -277.00097)
		(mid 383.989701 -276.950198)
		(end 383.804668 -276.996144)
		(width 0.09525)
		(layer "In2.Cu")
		(net "M_I_CPU0_SB_DQS_DP<5>")
	)
	(arc
		(start 378.525024 -276.996144)
		(mid 378.339992 -276.95023)
		(end 378.156216 -277.00097)
		(width 0.09525)
		(layer "In2.Cu")
		(net "M_I_CPU0_SB_DQS_DP<5>")
	)
	(arc
		(start 385.113276 -277.00097)
		(mid 384.924808 -276.950293)
		(end 384.73634 -277.00097)
		(width 0.09525)
		(layer "In2.Cu")
		(net "M_I_CPU0_SB_DQS_DP<5>")
	)
	(arc
		(start 393.636246 -276.80412)
		(mid 393.417265 -276.847696)
		(end 393.231624 -276.97176)
		(width 0.09525)
		(layer "In2.Cu")
		(net "M_I_CPU0_SB_DQS_DP<5>")
	)
	(arc
		(start 390.744964 -276.996144)
		(mid 390.559932 -276.95023)
		(end 390.376156 -277.00097)
		(width 0.09525)
		(layer "In2.Cu")
		(net "M_I_CPU0_SB_DQS_DP<5>")
	)
	(arc
		(start 378.156216 -277.00097)
		(mid 377.874784 -277.076725)
		(end 377.593352 -277.00097)
		(width 0.09525)
		(layer "In2.Cu")
		(net "M_I_CPU0_SB_DQS_DP<5>")
	)
	(arc
		(start 386.616194 -277.00097)
		(mid 386.334762 -277.076725)
		(end 386.05333 -277.00097)
		(width 0.09525)
		(layer "In2.Cu")
		(net "M_I_CPU0_SB_DQS_DP<5>")
	)
	(arc
		(start 383.233422 -277.00097)
		(mid 383.049647 -276.950198)
		(end 382.864614 -276.996144)
		(width 0.09525)
		(layer "In2.Cu")
		(net "M_I_CPU0_SB_DQS_DP<5>")
	)
	(arc
		(start 388.873492 -277.00097)
		(mid 388.689717 -276.950198)
		(end 388.504684 -276.996144)
		(width 0.09525)
		(layer "In2.Cu")
		(net "M_I_CPU0_SB_DQS_DP<5>")
	)
	(arc
		(start 392.228324 -277.01621)
		(mid 391.958918 -277.076558)
		(end 391.6934 -277.00097)
		(width 0.09525)
		(layer "In2.Cu")
		(net "M_I_CPU0_SB_DQS_DP<5>")
	)
	(arc
		(start 386.985002 -276.996144)
		(mid 386.79997 -276.95023)
		(end 386.616194 -277.00097)
		(width 0.09525)
		(layer "In2.Cu")
		(net "M_I_CPU0_SB_DQS_DP<5>")
	)
	(arc
		(start 379.09627 -277.00097)
		(mid 378.814838 -277.076725)
		(end 378.533406 -277.00097)
		(width 0.09525)
		(layer "In2.Cu")
		(net "M_I_CPU0_SB_DQS_DP<5>")
	)
	(arc
		(start 381.916178 -277.00097)
		(mid 381.634746 -277.076725)
		(end 381.353314 -277.00097)
		(width 0.09525)
		(layer "In2.Cu")
		(net "M_I_CPU0_SB_DQS_DP<5>")
	)
	(arc
		(start 390.376156 -277.00097)
		(mid 390.094724 -277.076725)
		(end 389.813292 -277.00097)
		(width 0.09525)
		(layer "In2.Cu")
		(net "M_I_CPU0_SB_DQS_DP<5>")
	)
	(arc
		(start 380.036324 -277.00097)
		(mid 379.754892 -277.076725)
		(end 379.47346 -277.00097)
		(width 0.09525)
		(layer "In2.Cu")
		(net "M_I_CPU0_SB_DQS_DP<5>")
	)
	(arc
		(start 383.796286 -277.00097)
		(mid 383.514854 -277.076725)
		(end 383.233422 -277.00097)
		(width 0.09525)
		(layer "In2.Cu")
		(net "M_I_CPU0_SB_DQS_DP<5>")
	)
	(arc
		(start 389.813292 -277.00097)
		(mid 389.624824 -276.950293)
		(end 389.436356 -277.00097)
		(width 0.09525)
		(layer "In2.Cu")
		(net "M_I_CPU0_SB_DQS_DP<5>")
	)
	(arc
		(start 386.044948 -276.996144)
		(mid 385.859916 -276.95023)
		(end 385.67614 -277.00097)
		(width 0.09525)
		(layer "In2.Cu")
		(net "M_I_CPU0_SB_DQS_DP<5>")
	)
	(arc
		(start 387.933438 -277.00097)
		(mid 387.749663 -276.950198)
		(end 387.56463 -276.996144)
		(width 0.09525)
		(layer "In2.Cu")
		(net "M_I_CPU0_SB_DQS_DP<5>")
	)
	(arc
		(start 385.67614 -277.00097)
		(mid 385.394708 -277.076725)
		(end 385.113276 -277.00097)
		(width 0.09525)
		(layer "In2.Cu")
		(net "M_I_CPU0_SB_DQS_DP<5>")
	)
	(arc
		(start 389.436356 -277.00097)
		(mid 389.154924 -277.076725)
		(end 388.873492 -277.00097)
		(width 0.09525)
		(layer "In2.Cu")
		(net "M_I_CPU0_SB_DQS_DP<5>")
	)
	(arc
		(start 382.284986 -276.996144)
		(mid 382.099954 -276.95023)
		(end 381.916178 -277.00097)
		(width 0.09525)
		(layer "In2.Cu")
		(net "M_I_CPU0_SB_DQS_DP<5>")
	)
	(arc
		(start 381.353314 -277.00097)
		(mid 381.164846 -276.950293)
		(end 380.976378 -277.00097)
		(width 0.09525)
		(layer "In2.Cu")
		(net "M_I_CPU0_SB_DQS_DP<5>")
	)
	(arc
		(start 379.47346 -277.00097)
		(mid 379.289685 -276.950198)
		(end 379.104652 -276.996144)
		(width 0.09525)
		(layer "In2.Cu")
		(net "M_I_CPU0_SB_DQS_DP<5>")
	)
	(arc
		(start 388.496302 -277.00097)
		(mid 388.21487 -277.076725)
		(end 387.933438 -277.00097)
		(width 0.09525)
		(layer "In2.Cu")
		(net "M_I_CPU0_SB_DQS_DP<5>")
	)
	(arc
		(start 384.73634 -277.00097)
		(mid 384.454908 -277.076725)
		(end 384.173476 -277.00097)
		(width 0.09525)
		(layer "In2.Cu")
		(net "M_I_CPU0_SB_DQS_DP<5>")
	)
	(arc
		(start 380.976378 -277.00097)
		(mid 380.694946 -277.076725)
		(end 380.413514 -277.00097)
		(width 0.09525)
		(layer "In2.Cu")
		(net "M_I_CPU0_SB_DQS_DP<5>")
	)
	(arc
		(start 393.194794 -277.000716)
		(mid 392.927415 -277.077298)
		(end 392.65606 -277.01621)
		(width 0.09525)
		(layer "In2.Cu")
		(net "M_I_CPU0_SB_DQS_DP<5>")
	)
	(arc
		(start 392.629898 -277.00097)
		(mid 392.454524 -276.95064)
		(end 392.276076 -276.988778)
		(width 0.09525)
		(layer "In2.Cu")
		(net "M_I_CPU0_SB_DQS_DP<5>")
	)
	(arc
		(start 391.31621 -277.00097)
		(mid 391.034778 -277.076725)
		(end 390.753346 -277.00097)
		(width 0.09525)
		(layer "In2.Cu")
		(net "M_I_CPU0_SB_DQS_DP<5>")
	)
	(arc
		(start 391.6934 -277.00097)
		(mid 391.509625 -276.950198)
		(end 391.324592 -276.996144)
		(width 0.09525)
		(layer "In2.Cu")
		(net "M_I_CPU0_SB_DQS_DP<5>")
	)
	(arc
		(start 377.58497 -276.996144)
		(mid 377.399938 -276.95023)
		(end 377.216162 -277.00097)
		(width 0.09525)
		(layer "In2.Cu")
		(net "M_I_CPU0_SB_DQS_DP<5>")
	)
	(arc
		(start 382.856232 -277.00097)
		(mid 382.5748 -277.076725)
		(end 382.293368 -277.00097)
		(width 0.09525)
		(layer "In2.Cu")
		(net "M_I_CPU0_SB_DQS_DP<5>")
	)
	(arc
		(start 380.413514 -277.00097)
		(mid 380.229739 -276.950198)
		(end 380.044706 -276.996144)
		(width 0.09525)
		(layer "In2.Cu")
		(net "M_I_CPU0_SB_DQS_DP<5>")
	)
	(segment
		(start 375.997978 -272.200116)
		(end 376.46483 -272.466054)
		(width 0.12954)
		(layer "F.Cu")
		(net "M_I_CPU0_SB_DQS_DP<4>")
	)
	(segment
		(start 415.26587 -276.80285)
		(end 415.57321 -277.11019)
		(width 0.16002)
		(layer "In2.Cu")
		(net "M_I_CPU0_SB_DQS_DP<4>")
	)
	(segment
		(start 422.39692 -276.80285)
		(end 422.809924 -276.80285)
		(width 0.16002)
		(layer "In2.Cu")
		(net "M_I_CPU0_SB_DQS_DP<4>")
	)
	(segment
		(start 411.265878 -277.960074)
		(end 413.258762 -277.960074)
		(width 0.16002)
		(layer "In2.Cu")
		(net "M_I_CPU0_SB_DQS_DP<4>")
	)
	(segment
		(start 408.468322 -274.885658)
		(end 408.468322 -275.66239)
		(width 0.16002)
		(layer "In2.Cu")
		(net "M_I_CPU0_SB_DQS_DP<4>")
	)
	(segment
		(start 382.284986 -272.136108)
		(end 382.293368 -272.140934)
		(width 0.09525)
		(layer "In2.Cu")
		(net "M_I_CPU0_SB_DQS_DP<4>")
	)
	(segment
		(start 393.678918 -272.009108)
		(end 394.257784 -271.430242)
		(width 0.09525)
		(layer "In2.Cu")
		(net "M_I_CPU0_SB_DQS_DP<4>")
	)
	(segment
		(start 422.809924 -276.80285)
		(end 423.117264 -277.11019)
		(width 0.16002)
		(layer "In2.Cu")
		(net "M_I_CPU0_SB_DQS_DP<4>")
	)
	(segment
		(start 421.16756 -277.59533)
		(end 421.60444 -277.59533)
		(width 0.16002)
		(layer "In2.Cu")
		(net "M_I_CPU0_SB_DQS_DP<4>")
	)
	(segment
		(start 413.623506 -277.59533)
		(end 414.060386 -277.59533)
		(width 0.16002)
		(layer "In2.Cu")
		(net "M_I_CPU0_SB_DQS_DP<4>")
	)
	(segment
		(start 394.362686 -270.944594)
		(end 394.919708 -270.387572)
		(width 0.09525)
		(layer "In2.Cu")
		(net "M_I_CPU0_SB_DQS_DP<4>")
	)
	(segment
		(start 407.48204 -274.676108)
		(end 408.258772 -274.676108)
		(width 0.16002)
		(layer "In2.Cu")
		(net "M_I_CPU0_SB_DQS_DP<4>")
	)
	(segment
		(start 427.182788 -276.961854)
		(end 427.456092 -277.235158)
		(width 0.16002)
		(layer "In2.Cu")
		(net "M_I_CPU0_SB_DQS_DP<4>")
	)
	(segment
		(start 377.58497 -272.136108)
		(end 377.593352 -272.140934)
		(width 0.09525)
		(layer "In2.Cu")
		(net "M_I_CPU0_SB_DQS_DP<4>")
	)
	(segment
		(start 413.258762 -277.960074)
		(end 413.623506 -277.59533)
		(width 0.16002)
		(layer "In2.Cu")
		(net "M_I_CPU0_SB_DQS_DP<4>")
	)
	(segment
		(start 407.09469 -274.288758)
		(end 407.48204 -274.676108)
		(width 0.16002)
		(layer "In2.Cu")
		(net "M_I_CPU0_SB_DQS_DP<4>")
	)
	(segment
		(start 409.841954 -276.25929)
		(end 409.841954 -277.036022)
		(width 0.16002)
		(layer "In2.Cu")
		(net "M_I_CPU0_SB_DQS_DP<4>")
	)
	(segment
		(start 386.044948 -272.136108)
		(end 386.05333 -272.140934)
		(width 0.09525)
		(layer "In2.Cu")
		(net "M_I_CPU0_SB_DQS_DP<4>")
	)
	(segment
		(start 410.729176 -277.423372)
		(end 411.265878 -277.960074)
		(width 0.16002)
		(layer "In2.Cu")
		(net "M_I_CPU0_SB_DQS_DP<4>")
	)
	(segment
		(start 409.841954 -277.036022)
		(end 410.229304 -277.423372)
		(width 0.16002)
		(layer "In2.Cu")
		(net "M_I_CPU0_SB_DQS_DP<4>")
	)
	(segment
		(start 395.633194 -270.4465)
		(end 404.029164 -270.4465)
		(width 0.16002)
		(layer "In2.Cu")
		(net "M_I_CPU0_SB_DQS_DP<4>")
	)
	(segment
		(start 405.721058 -272.138394)
		(end 405.721058 -272.915126)
		(width 0.16002)
		(layer "In2.Cu")
		(net "M_I_CPU0_SB_DQS_DP<4>")
	)
	(segment
		(start 423.117264 -277.11019)
		(end 425.19092 -277.11019)
		(width 0.16002)
		(layer "In2.Cu")
		(net "M_I_CPU0_SB_DQS_DP<4>")
	)
	(segment
		(start 406.88514 -273.302476)
		(end 407.09469 -273.512026)
		(width 0.16002)
		(layer "In2.Cu")
		(net "M_I_CPU0_SB_DQS_DP<4>")
	)
	(segment
		(start 383.796286 -272.140934)
		(end 383.804668 -272.136108)
		(width 0.09525)
		(layer "In2.Cu")
		(net "M_I_CPU0_SB_DQS_DP<4>")
	)
	(segment
		(start 425.339256 -276.961854)
		(end 425.819316 -276.961854)
		(width 0.16002)
		(layer "In2.Cu")
		(net "M_I_CPU0_SB_DQS_DP<4>")
	)
	(segment
		(start 404.029164 -270.4465)
		(end 404.347426 -270.764762)
		(width 0.16002)
		(layer "In2.Cu")
		(net "M_I_CPU0_SB_DQS_DP<4>")
	)
	(segment
		(start 394.257784 -271.430242)
		(end 394.362686 -271.17675)
		(width 0.09525)
		(layer "In2.Cu")
		(net "M_I_CPU0_SB_DQS_DP<4>")
	)
	(segment
		(start 392.629898 -272.140934)
		(end 392.65606 -272.156174)
		(width 0.09525)
		(layer "In2.Cu")
		(net "M_I_CPU0_SB_DQS_DP<4>")
	)
	(segment
		(start 407.09469 -273.512026)
		(end 407.09469 -274.288758)
		(width 0.16002)
		(layer "In2.Cu")
		(net "M_I_CPU0_SB_DQS_DP<4>")
	)
	(segment
		(start 394.362686 -271.17675)
		(end 394.362686 -270.944594)
		(width 0.09525)
		(layer "In2.Cu")
		(net "M_I_CPU0_SB_DQS_DP<4>")
	)
	(segment
		(start 393.48537 -272.089372)
		(end 393.678918 -272.009108)
		(width 0.09525)
		(layer "In2.Cu")
		(net "M_I_CPU0_SB_DQS_DP<4>")
	)
	(segment
		(start 408.258772 -274.676108)
		(end 408.468322 -274.885658)
		(width 0.16002)
		(layer "In2.Cu")
		(net "M_I_CPU0_SB_DQS_DP<4>")
	)
	(segment
		(start 388.496302 -272.140934)
		(end 388.504684 -272.136108)
		(width 0.09525)
		(layer "In2.Cu")
		(net "M_I_CPU0_SB_DQS_DP<4>")
	)
	(segment
		(start 380.036324 -272.140934)
		(end 380.044706 -272.136108)
		(width 0.09525)
		(layer "In2.Cu")
		(net "M_I_CPU0_SB_DQS_DP<4>")
	)
	(segment
		(start 393.386818 -272.089372)
		(end 393.48537 -272.089372)
		(width 0.09525)
		(layer "In2.Cu")
		(net "M_I_CPU0_SB_DQS_DP<4>")
	)
	(segment
		(start 382.856232 -272.140934)
		(end 382.864614 -272.136108)
		(width 0.09525)
		(layer "In2.Cu")
		(net "M_I_CPU0_SB_DQS_DP<4>")
	)
	(segment
		(start 408.855672 -276.04974)
		(end 409.632404 -276.04974)
		(width 0.16002)
		(layer "In2.Cu")
		(net "M_I_CPU0_SB_DQS_DP<4>")
	)
	(segment
		(start 406.108408 -273.302476)
		(end 406.88514 -273.302476)
		(width 0.16002)
		(layer "In2.Cu")
		(net "M_I_CPU0_SB_DQS_DP<4>")
	)
	(segment
		(start 376.310906 -272.200624)
		(end 376.33402 -272.11401)
		(width 0.09525)
		(layer "In2.Cu")
		(net "M_I_CPU0_SB_DQS_DP<4>")
	)
	(segment
		(start 404.347426 -271.541494)
		(end 404.734776 -271.928844)
		(width 0.16002)
		(layer "In2.Cu")
		(net "M_I_CPU0_SB_DQS_DP<4>")
	)
	(segment
		(start 405.721058 -272.915126)
		(end 406.108408 -273.302476)
		(width 0.16002)
		(layer "In2.Cu")
		(net "M_I_CPU0_SB_DQS_DP<4>")
	)
	(segment
		(start 405.511508 -271.928844)
		(end 405.721058 -272.138394)
		(width 0.16002)
		(layer "In2.Cu")
		(net "M_I_CPU0_SB_DQS_DP<4>")
	)
	(segment
		(start 379.09627 -272.140934)
		(end 379.104652 -272.136108)
		(width 0.09525)
		(layer "In2.Cu")
		(net "M_I_CPU0_SB_DQS_DP<4>")
	)
	(segment
		(start 414.060386 -277.59533)
		(end 414.852866 -276.80285)
		(width 0.16002)
		(layer "In2.Cu")
		(net "M_I_CPU0_SB_DQS_DP<4>")
	)
	(segment
		(start 378.525024 -272.136108)
		(end 378.533406 -272.140934)
		(width 0.09525)
		(layer "In2.Cu")
		(net "M_I_CPU0_SB_DQS_DP<4>")
	)
	(segment
		(start 426.533056 -276.961854)
		(end 427.182788 -276.961854)
		(width 0.16002)
		(layer "In2.Cu")
		(net "M_I_CPU0_SB_DQS_DP<4>")
	)
	(segment
		(start 386.985002 -272.136108)
		(end 386.993384 -272.140934)
		(width 0.09525)
		(layer "In2.Cu")
		(net "M_I_CPU0_SB_DQS_DP<4>")
	)
	(segment
		(start 404.347426 -270.764762)
		(end 404.347426 -271.541494)
		(width 0.16002)
		(layer "In2.Cu")
		(net "M_I_CPU0_SB_DQS_DP<4>")
	)
	(segment
		(start 425.819316 -276.961854)
		(end 425.936156 -277.078694)
		(width 0.16002)
		(layer "In2.Cu")
		(net "M_I_CPU0_SB_DQS_DP<4>")
	)
	(segment
		(start 387.556248 -272.140934)
		(end 387.56463 -272.136108)
		(width 0.09525)
		(layer "In2.Cu")
		(net "M_I_CPU0_SB_DQS_DP<4>")
	)
	(segment
		(start 410.229304 -277.423372)
		(end 410.729176 -277.423372)
		(width 0.16002)
		(layer "In2.Cu")
		(net "M_I_CPU0_SB_DQS_DP<4>")
	)
	(segment
		(start 392.254232 -272.141188)
		(end 392.276076 -272.128742)
		(width 0.09525)
		(layer "In2.Cu")
		(net "M_I_CPU0_SB_DQS_DP<4>")
	)
	(segment
		(start 390.744964 -272.136108)
		(end 390.753346 -272.140934)
		(width 0.09525)
		(layer "In2.Cu")
		(net "M_I_CPU0_SB_DQS_DP<4>")
	)
	(segment
		(start 408.468322 -275.66239)
		(end 408.855672 -276.04974)
		(width 0.16002)
		(layer "In2.Cu")
		(net "M_I_CPU0_SB_DQS_DP<4>")
	)
	(segment
		(start 392.228324 -272.156174)
		(end 392.254232 -272.141188)
		(width 0.09525)
		(layer "In2.Cu")
		(net "M_I_CPU0_SB_DQS_DP<4>")
	)
	(segment
		(start 394.919708 -270.387572)
		(end 395.550644 -270.387572)
		(width 0.09525)
		(layer "In2.Cu")
		(net "M_I_CPU0_SB_DQS_DP<4>")
	)
	(segment
		(start 420.802562 -277.960328)
		(end 421.16756 -277.59533)
		(width 0.16002)
		(layer "In2.Cu")
		(net "M_I_CPU0_SB_DQS_DP<4>")
	)
	(segment
		(start 391.31621 -272.140934)
		(end 391.324592 -272.136108)
		(width 0.09525)
		(layer "In2.Cu")
		(net "M_I_CPU0_SB_DQS_DP<4>")
	)
	(segment
		(start 418.886894 -277.960328)
		(end 420.802562 -277.960328)
		(width 0.16002)
		(layer "In2.Cu")
		(net "M_I_CPU0_SB_DQS_DP<4>")
	)
	(segment
		(start 414.852866 -276.80285)
		(end 415.26587 -276.80285)
		(width 0.16002)
		(layer "In2.Cu")
		(net "M_I_CPU0_SB_DQS_DP<4>")
	)
	(segment
		(start 425.19092 -277.11019)
		(end 425.339256 -276.961854)
		(width 0.16002)
		(layer "In2.Cu")
		(net "M_I_CPU0_SB_DQS_DP<4>")
	)
	(segment
		(start 395.550644 -270.387572)
		(end 395.609572 -270.4465)
		(width 0.09525)
		(layer "In2.Cu")
		(net "M_I_CPU0_SB_DQS_DP<4>")
	)
	(segment
		(start 395.609572 -270.4465)
		(end 395.633194 -270.4465)
		(width 0.09525)
		(layer "In2.Cu")
		(net "M_I_CPU0_SB_DQS_DP<4>")
	)
	(segment
		(start 426.416216 -277.078694)
		(end 426.533056 -276.961854)
		(width 0.16002)
		(layer "In2.Cu")
		(net "M_I_CPU0_SB_DQS_DP<4>")
	)
	(segment
		(start 425.936156 -277.078694)
		(end 426.416216 -277.078694)
		(width 0.16002)
		(layer "In2.Cu")
		(net "M_I_CPU0_SB_DQS_DP<4>")
	)
	(segment
		(start 415.57321 -277.11019)
		(end 418.036756 -277.11019)
		(width 0.16002)
		(layer "In2.Cu")
		(net "M_I_CPU0_SB_DQS_DP<4>")
	)
	(segment
		(start 376.46483 -272.466054)
		(end 376.310906 -272.200624)
		(width 0.09525)
		(layer "In2.Cu")
		(net "M_I_CPU0_SB_DQS_DP<4>")
	)
	(segment
		(start 418.036756 -277.11019)
		(end 418.886894 -277.960328)
		(width 0.16002)
		(layer "In2.Cu")
		(net "M_I_CPU0_SB_DQS_DP<4>")
	)
	(segment
		(start 421.60444 -277.59533)
		(end 422.39692 -276.80285)
		(width 0.16002)
		(layer "In2.Cu")
		(net "M_I_CPU0_SB_DQS_DP<4>")
	)
	(segment
		(start 409.632404 -276.04974)
		(end 409.841954 -276.25929)
		(width 0.16002)
		(layer "In2.Cu")
		(net "M_I_CPU0_SB_DQS_DP<4>")
	)
	(segment
		(start 404.734776 -271.928844)
		(end 405.511508 -271.928844)
		(width 0.16002)
		(layer "In2.Cu")
		(net "M_I_CPU0_SB_DQS_DP<4>")
	)
	(arc
		(start 390.753346 -272.140934)
		(mid 391.034778 -272.216689)
		(end 391.31621 -272.140934)
		(width 0.09525)
		(layer "In2.Cu")
		(net "M_I_CPU0_SB_DQS_DP<4>")
	)
	(arc
		(start 392.276076 -272.128742)
		(mid 392.454528 -272.0905)
		(end 392.629898 -272.140934)
		(width 0.09525)
		(layer "In2.Cu")
		(net "M_I_CPU0_SB_DQS_DP<4>")
	)
	(arc
		(start 388.873492 -272.140934)
		(mid 389.154924 -272.216689)
		(end 389.436356 -272.140934)
		(width 0.09525)
		(layer "In2.Cu")
		(net "M_I_CPU0_SB_DQS_DP<4>")
	)
	(arc
		(start 382.293368 -272.140934)
		(mid 382.5748 -272.216689)
		(end 382.856232 -272.140934)
		(width 0.09525)
		(layer "In2.Cu")
		(net "M_I_CPU0_SB_DQS_DP<4>")
	)
	(arc
		(start 380.413514 -272.140934)
		(mid 380.694946 -272.216689)
		(end 380.976378 -272.140934)
		(width 0.09525)
		(layer "In2.Cu")
		(net "M_I_CPU0_SB_DQS_DP<4>")
	)
	(arc
		(start 380.044706 -272.136108)
		(mid 380.229738 -272.090194)
		(end 380.413514 -272.140934)
		(width 0.09525)
		(layer "In2.Cu")
		(net "M_I_CPU0_SB_DQS_DP<4>")
	)
	(arc
		(start 376.33402 -272.11401)
		(mid 376.496671 -272.09175)
		(end 376.653298 -272.140934)
		(width 0.09525)
		(layer "In2.Cu")
		(net "M_I_CPU0_SB_DQS_DP<4>")
	)
	(arc
		(start 384.73634 -272.140934)
		(mid 384.924808 -272.090257)
		(end 385.113276 -272.140934)
		(width 0.09525)
		(layer "In2.Cu")
		(net "M_I_CPU0_SB_DQS_DP<4>")
	)
	(arc
		(start 392.65606 -272.156174)
		(mid 392.927416 -272.217323)
		(end 393.194794 -272.14068)
		(width 0.09525)
		(layer "In2.Cu")
		(net "M_I_CPU0_SB_DQS_DP<4>")
	)
	(arc
		(start 386.05333 -272.140934)
		(mid 386.334762 -272.216689)
		(end 386.616194 -272.140934)
		(width 0.09525)
		(layer "In2.Cu")
		(net "M_I_CPU0_SB_DQS_DP<4>")
	)
	(arc
		(start 384.173476 -272.140934)
		(mid 384.454908 -272.216689)
		(end 384.73634 -272.140934)
		(width 0.09525)
		(layer "In2.Cu")
		(net "M_I_CPU0_SB_DQS_DP<4>")
	)
	(arc
		(start 393.194794 -272.14068)
		(mid 393.287363 -272.102149)
		(end 393.386818 -272.089372)
		(width 0.09525)
		(layer "In2.Cu")
		(net "M_I_CPU0_SB_DQS_DP<4>")
	)
	(arc
		(start 381.353314 -272.140934)
		(mid 381.634746 -272.216689)
		(end 381.916178 -272.140934)
		(width 0.09525)
		(layer "In2.Cu")
		(net "M_I_CPU0_SB_DQS_DP<4>")
	)
	(arc
		(start 376.653298 -272.140934)
		(mid 376.93473 -272.216689)
		(end 377.216162 -272.140934)
		(width 0.09525)
		(layer "In2.Cu")
		(net "M_I_CPU0_SB_DQS_DP<4>")
	)
	(arc
		(start 387.933438 -272.140934)
		(mid 388.21487 -272.216689)
		(end 388.496302 -272.140934)
		(width 0.09525)
		(layer "In2.Cu")
		(net "M_I_CPU0_SB_DQS_DP<4>")
	)
	(arc
		(start 379.104652 -272.136108)
		(mid 379.289684 -272.090194)
		(end 379.47346 -272.140934)
		(width 0.09525)
		(layer "In2.Cu")
		(net "M_I_CPU0_SB_DQS_DP<4>")
	)
	(arc
		(start 391.6934 -272.140934)
		(mid 391.95892 -272.216463)
		(end 392.228324 -272.156174)
		(width 0.09525)
		(layer "In2.Cu")
		(net "M_I_CPU0_SB_DQS_DP<4>")
	)
	(arc
		(start 378.533406 -272.140934)
		(mid 378.814838 -272.216689)
		(end 379.09627 -272.140934)
		(width 0.09525)
		(layer "In2.Cu")
		(net "M_I_CPU0_SB_DQS_DP<4>")
	)
	(arc
		(start 383.804668 -272.136108)
		(mid 383.9897 -272.090194)
		(end 384.173476 -272.140934)
		(width 0.09525)
		(layer "In2.Cu")
		(net "M_I_CPU0_SB_DQS_DP<4>")
	)
	(arc
		(start 385.67614 -272.140934)
		(mid 385.859915 -272.090162)
		(end 386.044948 -272.136108)
		(width 0.09525)
		(layer "In2.Cu")
		(net "M_I_CPU0_SB_DQS_DP<4>")
	)
	(arc
		(start 379.47346 -272.140934)
		(mid 379.754892 -272.216689)
		(end 380.036324 -272.140934)
		(width 0.09525)
		(layer "In2.Cu")
		(net "M_I_CPU0_SB_DQS_DP<4>")
	)
	(arc
		(start 385.113276 -272.140934)
		(mid 385.394708 -272.216689)
		(end 385.67614 -272.140934)
		(width 0.09525)
		(layer "In2.Cu")
		(net "M_I_CPU0_SB_DQS_DP<4>")
	)
	(arc
		(start 389.813292 -272.140934)
		(mid 390.094724 -272.216689)
		(end 390.376156 -272.140934)
		(width 0.09525)
		(layer "In2.Cu")
		(net "M_I_CPU0_SB_DQS_DP<4>")
	)
	(arc
		(start 381.916178 -272.140934)
		(mid 382.099953 -272.090162)
		(end 382.284986 -272.136108)
		(width 0.09525)
		(layer "In2.Cu")
		(net "M_I_CPU0_SB_DQS_DP<4>")
	)
	(arc
		(start 380.976378 -272.140934)
		(mid 381.164846 -272.090257)
		(end 381.353314 -272.140934)
		(width 0.09525)
		(layer "In2.Cu")
		(net "M_I_CPU0_SB_DQS_DP<4>")
	)
	(arc
		(start 387.56463 -272.136108)
		(mid 387.749662 -272.090194)
		(end 387.933438 -272.140934)
		(width 0.09525)
		(layer "In2.Cu")
		(net "M_I_CPU0_SB_DQS_DP<4>")
	)
	(arc
		(start 377.593352 -272.140934)
		(mid 377.874784 -272.216689)
		(end 378.156216 -272.140934)
		(width 0.09525)
		(layer "In2.Cu")
		(net "M_I_CPU0_SB_DQS_DP<4>")
	)
	(arc
		(start 390.376156 -272.140934)
		(mid 390.559931 -272.090162)
		(end 390.744964 -272.136108)
		(width 0.09525)
		(layer "In2.Cu")
		(net "M_I_CPU0_SB_DQS_DP<4>")
	)
	(arc
		(start 389.436356 -272.140934)
		(mid 389.624824 -272.090257)
		(end 389.813292 -272.140934)
		(width 0.09525)
		(layer "In2.Cu")
		(net "M_I_CPU0_SB_DQS_DP<4>")
	)
	(arc
		(start 382.864614 -272.136108)
		(mid 383.049646 -272.090194)
		(end 383.233422 -272.140934)
		(width 0.09525)
		(layer "In2.Cu")
		(net "M_I_CPU0_SB_DQS_DP<4>")
	)
	(arc
		(start 383.233422 -272.140934)
		(mid 383.514854 -272.216689)
		(end 383.796286 -272.140934)
		(width 0.09525)
		(layer "In2.Cu")
		(net "M_I_CPU0_SB_DQS_DP<4>")
	)
	(arc
		(start 377.216162 -272.140934)
		(mid 377.399937 -272.090162)
		(end 377.58497 -272.136108)
		(width 0.09525)
		(layer "In2.Cu")
		(net "M_I_CPU0_SB_DQS_DP<4>")
	)
	(arc
		(start 388.504684 -272.136108)
		(mid 388.689716 -272.090194)
		(end 388.873492 -272.140934)
		(width 0.09525)
		(layer "In2.Cu")
		(net "M_I_CPU0_SB_DQS_DP<4>")
	)
	(arc
		(start 386.993384 -272.140934)
		(mid 387.274816 -272.216689)
		(end 387.556248 -272.140934)
		(width 0.09525)
		(layer "In2.Cu")
		(net "M_I_CPU0_SB_DQS_DP<4>")
	)
	(arc
		(start 378.156216 -272.140934)
		(mid 378.339991 -272.090162)
		(end 378.525024 -272.136108)
		(width 0.09525)
		(layer "In2.Cu")
		(net "M_I_CPU0_SB_DQS_DP<4>")
	)
	(arc
		(start 391.324592 -272.136108)
		(mid 391.509624 -272.090194)
		(end 391.6934 -272.140934)
		(width 0.09525)
		(layer "In2.Cu")
		(net "M_I_CPU0_SB_DQS_DP<4>")
	)
	(arc
		(start 386.616194 -272.140934)
		(mid 386.799969 -272.090162)
		(end 386.985002 -272.136108)
		(width 0.09525)
		(layer "In2.Cu")
		(net "M_I_CPU0_SB_DQS_DP<4>")
	)
	(segment
		(start 376.938032 -290.019994)
		(end 377.404884 -290.285932)
		(width 0.12954)
		(layer "F.Cu")
		(net "M_I_CPU0_SB_DQS_DP<3>")
	)
	(segment
		(start 430.560988 -313.209686)
		(end 431.281586 -313.209686)
		(width 0.16002)
		(layer "In2.Cu")
		(net "M_I_CPU0_SB_DQS_DP<3>")
	)
	(segment
		(start 392.06678 -291.905944)
		(end 392.067034 -291.905944)
		(width 0.09525)
		(layer "In2.Cu")
		(net "M_I_CPU0_SB_DQS_DP<3>")
	)
	(segment
		(start 402.634704 -306.290472)
		(end 409.404058 -313.059826)
		(width 0.16002)
		(layer "In2.Cu")
		(net "M_I_CPU0_SB_DQS_DP<3>")
	)
	(segment
		(start 377.558808 -290.551362)
		(end 377.659646 -290.578032)
		(width 0.09525)
		(layer "In2.Cu")
		(net "M_I_CPU0_SB_DQS_DP<3>")
	)
	(segment
		(start 383.796286 -290.611052)
		(end 383.804668 -290.615878)
		(width 0.09525)
		(layer "In2.Cu")
		(net "M_I_CPU0_SB_DQS_DP<3>")
	)
	(segment
		(start 394.564362 -296.234866)
		(end 394.623544 -296.294048)
		(width 0.09525)
		(layer "In2.Cu")
		(net "M_I_CPU0_SB_DQS_DP<3>")
	)
	(segment
		(start 394.564362 -295.974262)
		(end 394.564362 -296.234866)
		(width 0.09525)
		(layer "In2.Cu")
		(net "M_I_CPU0_SB_DQS_DP<3>")
	)
	(segment
		(start 386.985002 -290.615878)
		(end 386.993384 -290.611052)
		(width 0.09525)
		(layer "In2.Cu")
		(net "M_I_CPU0_SB_DQS_DP<3>")
	)
	(segment
		(start 415.604706 -312.209942)
		(end 417.83381 -312.209942)
		(width 0.16002)
		(layer "In2.Cu")
		(net "M_I_CPU0_SB_DQS_DP<3>")
	)
	(segment
		(start 431.281586 -313.209686)
		(end 431.55616 -312.935112)
		(width 0.16002)
		(layer "In2.Cu")
		(net "M_I_CPU0_SB_DQS_DP<3>")
	)
	(segment
		(start 393.703302 -294.682926)
		(end 393.705334 -294.684196)
		(width 0.09525)
		(layer "In2.Cu")
		(net "M_I_CPU0_SB_DQS_DP<3>")
	)
	(segment
		(start 391.78611 -291.421058)
		(end 391.821162 -291.441632)
		(width 0.09525)
		(layer "In2.Cu")
		(net "M_I_CPU0_SB_DQS_DP<3>")
	)
	(segment
		(start 429.847248 -313.209686)
		(end 429.964088 -313.092846)
		(width 0.16002)
		(layer "In2.Cu")
		(net "M_I_CPU0_SB_DQS_DP<3>")
	)
	(segment
		(start 393.196064 -293.851076)
		(end 393.234164 -293.873174)
		(width 0.09525)
		(layer "In2.Cu")
		(net "M_I_CPU0_SB_DQS_DP<3>")
	)
	(segment
		(start 387.556248 -290.611052)
		(end 387.56463 -290.615878)
		(width 0.09525)
		(layer "In2.Cu")
		(net "M_I_CPU0_SB_DQS_DP<3>")
	)
	(segment
		(start 394.623544 -296.522648)
		(end 395.27353 -298.092114)
		(width 0.16002)
		(layer "In2.Cu")
		(net "M_I_CPU0_SB_DQS_DP<3>")
	)
	(segment
		(start 394.623544 -296.294048)
		(end 394.623544 -296.31767)
		(width 0.09525)
		(layer "In2.Cu")
		(net "M_I_CPU0_SB_DQS_DP<3>")
	)
	(segment
		(start 392.692636 -293.021512)
		(end 392.726418 -293.04107)
		(width 0.09525)
		(layer "In2.Cu")
		(net "M_I_CPU0_SB_DQS_DP<3>")
	)
	(segment
		(start 420.81704 -313.059826)
		(end 421.12438 -313.367166)
		(width 0.16002)
		(layer "In2.Cu")
		(net "M_I_CPU0_SB_DQS_DP<3>")
	)
	(segment
		(start 393.164568 -293.832788)
		(end 393.196064 -293.851076)
		(width 0.09525)
		(layer "In2.Cu")
		(net "M_I_CPU0_SB_DQS_DP<3>")
	)
	(segment
		(start 430.444148 -313.092846)
		(end 430.560988 -313.209686)
		(width 0.16002)
		(layer "In2.Cu")
		(net "M_I_CPU0_SB_DQS_DP<3>")
	)
	(segment
		(start 402.634704 -305.453288)
		(end 402.634704 -306.290472)
		(width 0.16002)
		(layer "In2.Cu")
		(net "M_I_CPU0_SB_DQS_DP<3>")
	)
	(segment
		(start 413.580326 -313.367166)
		(end 413.92221 -313.367166)
		(width 0.16002)
		(layer "In2.Cu")
		(net "M_I_CPU0_SB_DQS_DP<3>")
	)
	(segment
		(start 417.83381 -312.209942)
		(end 418.683694 -313.059826)
		(width 0.16002)
		(layer "In2.Cu")
		(net "M_I_CPU0_SB_DQS_DP<3>")
	)
	(segment
		(start 409.404058 -313.059826)
		(end 413.272986 -313.059826)
		(width 0.16002)
		(layer "In2.Cu")
		(net "M_I_CPU0_SB_DQS_DP<3>")
	)
	(segment
		(start 429.304704 -313.209686)
		(end 429.847248 -313.209686)
		(width 0.16002)
		(layer "In2.Cu")
		(net "M_I_CPU0_SB_DQS_DP<3>")
	)
	(segment
		(start 425.999656 -312.783982)
		(end 428.084996 -312.783982)
		(width 0.16002)
		(layer "In2.Cu")
		(net "M_I_CPU0_SB_DQS_DP<3>")
	)
	(segment
		(start 413.272986 -313.059826)
		(end 413.580326 -313.367166)
		(width 0.16002)
		(layer "In2.Cu")
		(net "M_I_CPU0_SB_DQS_DP<3>")
	)
	(segment
		(start 395.27353 -298.092114)
		(end 402.634704 -305.453288)
		(width 0.16002)
		(layer "In2.Cu")
		(net "M_I_CPU0_SB_DQS_DP<3>")
	)
	(segment
		(start 393.946634 -295.145968)
		(end 393.946634 -295.356534)
		(width 0.09525)
		(layer "In2.Cu")
		(net "M_I_CPU0_SB_DQS_DP<3>")
	)
	(segment
		(start 418.683694 -313.059826)
		(end 420.81704 -313.059826)
		(width 0.16002)
		(layer "In2.Cu")
		(net "M_I_CPU0_SB_DQS_DP<3>")
	)
	(segment
		(start 423.14876 -312.209942)
		(end 425.425616 -312.209942)
		(width 0.16002)
		(layer "In2.Cu")
		(net "M_I_CPU0_SB_DQS_DP<3>")
	)
	(segment
		(start 415.288222 -312.526426)
		(end 415.604706 -312.209942)
		(width 0.16002)
		(layer "In2.Cu")
		(net "M_I_CPU0_SB_DQS_DP<3>")
	)
	(segment
		(start 428.084996 -312.783982)
		(end 428.69358 -313.392566)
		(width 0.16002)
		(layer "In2.Cu")
		(net "M_I_CPU0_SB_DQS_DP<3>")
	)
	(segment
		(start 379.09627 -290.611052)
		(end 379.104652 -290.615878)
		(width 0.09525)
		(layer "In2.Cu")
		(net "M_I_CPU0_SB_DQS_DP<3>")
	)
	(segment
		(start 388.496302 -290.611052)
		(end 388.504684 -290.615878)
		(width 0.09525)
		(layer "In2.Cu")
		(net "M_I_CPU0_SB_DQS_DP<3>")
	)
	(segment
		(start 428.69358 -313.392566)
		(end 429.121824 -313.392566)
		(width 0.16002)
		(layer "In2.Cu")
		(net "M_I_CPU0_SB_DQS_DP<3>")
	)
	(segment
		(start 390.744964 -290.615878)
		(end 390.753346 -290.611052)
		(width 0.09525)
		(layer "In2.Cu")
		(net "M_I_CPU0_SB_DQS_DP<3>")
	)
	(segment
		(start 421.466264 -313.367166)
		(end 422.307004 -312.526426)
		(width 0.16002)
		(layer "In2.Cu")
		(net "M_I_CPU0_SB_DQS_DP<3>")
	)
	(segment
		(start 378.525024 -290.615878)
		(end 378.533406 -290.611052)
		(width 0.09525)
		(layer "In2.Cu")
		(net "M_I_CPU0_SB_DQS_DP<3>")
	)
	(segment
		(start 382.284986 -290.615878)
		(end 382.293368 -290.611052)
		(width 0.09525)
		(layer "In2.Cu")
		(net "M_I_CPU0_SB_DQS_DP<3>")
	)
	(segment
		(start 391.754614 -291.40277)
		(end 391.78611 -291.421058)
		(width 0.09525)
		(layer "In2.Cu")
		(net "M_I_CPU0_SB_DQS_DP<3>")
	)
	(segment
		(start 429.121824 -313.392566)
		(end 429.304704 -313.209686)
		(width 0.16002)
		(layer "In2.Cu")
		(net "M_I_CPU0_SB_DQS_DP<3>")
	)
	(segment
		(start 391.31621 -290.611052)
		(end 391.35431 -290.63315)
		(width 0.09525)
		(layer "In2.Cu")
		(net "M_I_CPU0_SB_DQS_DP<3>")
	)
	(segment
		(start 382.856232 -290.611052)
		(end 382.864614 -290.615878)
		(width 0.09525)
		(layer "In2.Cu")
		(net "M_I_CPU0_SB_DQS_DP<3>")
	)
	(segment
		(start 422.832276 -312.526426)
		(end 423.14876 -312.209942)
		(width 0.16002)
		(layer "In2.Cu")
		(net "M_I_CPU0_SB_DQS_DP<3>")
	)
	(segment
		(start 421.12438 -313.367166)
		(end 421.466264 -313.367166)
		(width 0.16002)
		(layer "In2.Cu")
		(net "M_I_CPU0_SB_DQS_DP<3>")
	)
	(segment
		(start 422.307004 -312.526426)
		(end 422.832276 -312.526426)
		(width 0.16002)
		(layer "In2.Cu")
		(net "M_I_CPU0_SB_DQS_DP<3>")
	)
	(segment
		(start 377.404884 -290.285932)
		(end 377.558808 -290.551362)
		(width 0.09525)
		(layer "In2.Cu")
		(net "M_I_CPU0_SB_DQS_DP<3>")
	)
	(segment
		(start 425.425616 -312.209942)
		(end 425.999656 -312.783982)
		(width 0.16002)
		(layer "In2.Cu")
		(net "M_I_CPU0_SB_DQS_DP<3>")
	)
	(segment
		(start 393.946634 -295.356534)
		(end 394.564362 -295.974262)
		(width 0.09525)
		(layer "In2.Cu")
		(net "M_I_CPU0_SB_DQS_DP<3>")
	)
	(segment
		(start 414.76295 -312.526426)
		(end 415.288222 -312.526426)
		(width 0.16002)
		(layer "In2.Cu")
		(net "M_I_CPU0_SB_DQS_DP<3>")
	)
	(segment
		(start 392.222482 -292.211506)
		(end 392.256264 -292.231064)
		(width 0.09525)
		(layer "In2.Cu")
		(net "M_I_CPU0_SB_DQS_DP<3>")
	)
	(segment
		(start 393.633706 -294.642286)
		(end 393.70127 -294.681656)
		(width 0.09525)
		(layer "In2.Cu")
		(net "M_I_CPU0_SB_DQS_DP<3>")
	)
	(segment
		(start 392.726418 -293.04107)
		(end 392.762994 -293.062406)
		(width 0.09525)
		(layer "In2.Cu")
		(net "M_I_CPU0_SB_DQS_DP<3>")
	)
	(segment
		(start 386.044948 -290.615878)
		(end 386.05333 -290.611052)
		(width 0.09525)
		(layer "In2.Cu")
		(net "M_I_CPU0_SB_DQS_DP<3>")
	)
	(segment
		(start 413.92221 -313.367166)
		(end 414.76295 -312.526426)
		(width 0.16002)
		(layer "In2.Cu")
		(net "M_I_CPU0_SB_DQS_DP<3>")
	)
	(segment
		(start 429.964088 -313.092846)
		(end 430.444148 -313.092846)
		(width 0.16002)
		(layer "In2.Cu")
		(net "M_I_CPU0_SB_DQS_DP<3>")
	)
	(segment
		(start 392.256264 -292.231064)
		(end 392.294364 -292.253162)
		(width 0.09525)
		(layer "In2.Cu")
		(net "M_I_CPU0_SB_DQS_DP<3>")
	)
	(segment
		(start 394.623544 -296.31767)
		(end 394.623544 -296.522648)
		(width 0.16002)
		(layer "In2.Cu")
		(net "M_I_CPU0_SB_DQS_DP<3>")
	)
	(segment
		(start 380.036324 -290.611052)
		(end 380.044706 -290.615878)
		(width 0.09525)
		(layer "In2.Cu")
		(net "M_I_CPU0_SB_DQS_DP<3>")
	)
	(arc
		(start 392.762994 -293.062406)
		(mid 392.942366 -293.264001)
		(end 393.007088 -293.525956)
		(width 0.09525)
		(layer "In2.Cu")
		(net "M_I_CPU0_SB_DQS_DP<3>")
	)
	(arc
		(start 378.533406 -290.611052)
		(mid 378.814838 -290.535297)
		(end 379.09627 -290.611052)
		(width 0.09525)
		(layer "In2.Cu")
		(net "M_I_CPU0_SB_DQS_DP<3>")
	)
	(arc
		(start 380.976378 -290.611052)
		(mid 381.164846 -290.661729)
		(end 381.353314 -290.611052)
		(width 0.09525)
		(layer "In2.Cu")
		(net "M_I_CPU0_SB_DQS_DP<3>")
	)
	(arc
		(start 377.659646 -290.578032)
		(mid 377.669768 -290.573997)
		(end 377.679966 -290.570158)
		(width 0.09525)
		(layer "In2.Cu")
		(net "M_I_CPU0_SB_DQS_DP<3>")
	)
	(arc
		(start 379.104652 -290.615878)
		(mid 379.289684 -290.661792)
		(end 379.47346 -290.611052)
		(width 0.09525)
		(layer "In2.Cu")
		(net "M_I_CPU0_SB_DQS_DP<3>")
	)
	(arc
		(start 385.67614 -290.611052)
		(mid 385.859915 -290.661824)
		(end 386.044948 -290.615878)
		(width 0.09525)
		(layer "In2.Cu")
		(net "M_I_CPU0_SB_DQS_DP<3>")
	)
	(arc
		(start 385.113276 -290.611052)
		(mid 385.394708 -290.535297)
		(end 385.67614 -290.611052)
		(width 0.09525)
		(layer "In2.Cu")
		(net "M_I_CPU0_SB_DQS_DP<3>")
	)
	(arc
		(start 392.537188 -292.71595)
		(mid 392.57829 -292.887356)
		(end 392.692636 -293.021512)
		(width 0.09525)
		(layer "In2.Cu")
		(net "M_I_CPU0_SB_DQS_DP<3>")
	)
	(arc
		(start 378.156216 -290.611052)
		(mid 378.339991 -290.661824)
		(end 378.525024 -290.615878)
		(width 0.09525)
		(layer "In2.Cu")
		(net "M_I_CPU0_SB_DQS_DP<3>")
	)
	(arc
		(start 390.376156 -290.611052)
		(mid 390.559931 -290.661824)
		(end 390.744964 -290.615878)
		(width 0.09525)
		(layer "In2.Cu")
		(net "M_I_CPU0_SB_DQS_DP<3>")
	)
	(arc
		(start 392.067034 -291.905944)
		(mid 392.108136 -292.07735)
		(end 392.222482 -292.211506)
		(width 0.09525)
		(layer "In2.Cu")
		(net "M_I_CPU0_SB_DQS_DP<3>")
	)
	(arc
		(start 386.993384 -290.611052)
		(mid 387.274816 -290.535297)
		(end 387.556248 -290.611052)
		(width 0.09525)
		(layer "In2.Cu")
		(net "M_I_CPU0_SB_DQS_DP<3>")
	)
	(arc
		(start 383.804668 -290.615878)
		(mid 383.9897 -290.661792)
		(end 384.173476 -290.611052)
		(width 0.09525)
		(layer "In2.Cu")
		(net "M_I_CPU0_SB_DQS_DP<3>")
	)
	(arc
		(start 387.56463 -290.615878)
		(mid 387.749662 -290.661792)
		(end 387.933438 -290.611052)
		(width 0.09525)
		(layer "In2.Cu")
		(net "M_I_CPU0_SB_DQS_DP<3>")
	)
	(arc
		(start 388.504684 -290.615878)
		(mid 388.689716 -290.661792)
		(end 388.873492 -290.611052)
		(width 0.09525)
		(layer "In2.Cu")
		(net "M_I_CPU0_SB_DQS_DP<3>")
	)
	(arc
		(start 377.679966 -290.570158)
		(mid 377.922678 -290.537275)
		(end 378.156216 -290.611052)
		(width 0.09525)
		(layer "In2.Cu")
		(net "M_I_CPU0_SB_DQS_DP<3>")
	)
	(arc
		(start 387.933438 -290.611052)
		(mid 388.21487 -290.535297)
		(end 388.496302 -290.611052)
		(width 0.09525)
		(layer "In2.Cu")
		(net "M_I_CPU0_SB_DQS_DP<3>")
	)
	(arc
		(start 390.753346 -290.611052)
		(mid 391.034778 -290.535297)
		(end 391.31621 -290.611052)
		(width 0.09525)
		(layer "In2.Cu")
		(net "M_I_CPU0_SB_DQS_DP<3>")
	)
	(arc
		(start 386.616194 -290.611052)
		(mid 386.799969 -290.661824)
		(end 386.985002 -290.615878)
		(width 0.09525)
		(layer "In2.Cu")
		(net "M_I_CPU0_SB_DQS_DP<3>")
	)
	(arc
		(start 381.916178 -290.611052)
		(mid 382.099953 -290.661824)
		(end 382.284986 -290.615878)
		(width 0.09525)
		(layer "In2.Cu")
		(net "M_I_CPU0_SB_DQS_DP<3>")
	)
	(arc
		(start 388.873492 -290.611052)
		(mid 389.154924 -290.535297)
		(end 389.436356 -290.611052)
		(width 0.09525)
		(layer "In2.Cu")
		(net "M_I_CPU0_SB_DQS_DP<3>")
	)
	(arc
		(start 393.007088 -293.525956)
		(mid 393.048753 -293.698403)
		(end 393.164568 -293.832788)
		(width 0.09525)
		(layer "In2.Cu")
		(net "M_I_CPU0_SB_DQS_DP<3>")
	)
	(arc
		(start 382.864614 -290.615878)
		(mid 383.049646 -290.661792)
		(end 383.233422 -290.611052)
		(width 0.09525)
		(layer "In2.Cu")
		(net "M_I_CPU0_SB_DQS_DP<3>")
	)
	(arc
		(start 379.47346 -290.611052)
		(mid 379.754892 -290.535297)
		(end 380.036324 -290.611052)
		(width 0.09525)
		(layer "In2.Cu")
		(net "M_I_CPU0_SB_DQS_DP<3>")
	)
	(arc
		(start 393.705334 -294.684196)
		(mid 393.882699 -294.88544)
		(end 393.946634 -295.145968)
		(width 0.09525)
		(layer "In2.Cu")
		(net "M_I_CPU0_SB_DQS_DP<3>")
	)
	(arc
		(start 384.73634 -290.611052)
		(mid 384.924808 -290.661729)
		(end 385.113276 -290.611052)
		(width 0.09525)
		(layer "In2.Cu")
		(net "M_I_CPU0_SB_DQS_DP<3>")
	)
	(arc
		(start 386.05333 -290.611052)
		(mid 386.334762 -290.535297)
		(end 386.616194 -290.611052)
		(width 0.09525)
		(layer "In2.Cu")
		(net "M_I_CPU0_SB_DQS_DP<3>")
	)
	(arc
		(start 389.436356 -290.611052)
		(mid 389.624824 -290.661729)
		(end 389.813292 -290.611052)
		(width 0.09525)
		(layer "In2.Cu")
		(net "M_I_CPU0_SB_DQS_DP<3>")
	)
	(arc
		(start 392.294364 -292.253162)
		(mid 392.472814 -292.454632)
		(end 392.537188 -292.71595)
		(width 0.09525)
		(layer "In2.Cu")
		(net "M_I_CPU0_SB_DQS_DP<3>")
	)
	(arc
		(start 382.293368 -290.611052)
		(mid 382.5748 -290.535297)
		(end 382.856232 -290.611052)
		(width 0.09525)
		(layer "In2.Cu")
		(net "M_I_CPU0_SB_DQS_DP<3>")
	)
	(arc
		(start 393.476988 -294.335962)
		(mid 393.518445 -294.508002)
		(end 393.633706 -294.642286)
		(width 0.09525)
		(layer "In2.Cu")
		(net "M_I_CPU0_SB_DQS_DP<3>")
	)
	(arc
		(start 391.35431 -290.63315)
		(mid 391.53276 -290.83462)
		(end 391.597134 -291.095938)
		(width 0.09525)
		(layer "In2.Cu")
		(net "M_I_CPU0_SB_DQS_DP<3>")
	)
	(arc
		(start 380.413514 -290.611052)
		(mid 380.694946 -290.535297)
		(end 380.976378 -290.611052)
		(width 0.09525)
		(layer "In2.Cu")
		(net "M_I_CPU0_SB_DQS_DP<3>")
	)
	(arc
		(start 391.821162 -291.441632)
		(mid 392.001553 -291.643331)
		(end 392.06678 -291.905944)
		(width 0.09525)
		(layer "In2.Cu")
		(net "M_I_CPU0_SB_DQS_DP<3>")
	)
	(arc
		(start 384.173476 -290.611052)
		(mid 384.454908 -290.535297)
		(end 384.73634 -290.611052)
		(width 0.09525)
		(layer "In2.Cu")
		(net "M_I_CPU0_SB_DQS_DP<3>")
	)
	(arc
		(start 389.813292 -290.611052)
		(mid 390.094724 -290.535297)
		(end 390.376156 -290.611052)
		(width 0.09525)
		(layer "In2.Cu")
		(net "M_I_CPU0_SB_DQS_DP<3>")
	)
	(arc
		(start 391.597134 -291.095938)
		(mid 391.638799 -291.268385)
		(end 391.754614 -291.40277)
		(width 0.09525)
		(layer "In2.Cu")
		(net "M_I_CPU0_SB_DQS_DP<3>")
	)
	(arc
		(start 393.234164 -293.873174)
		(mid 393.412614 -294.074644)
		(end 393.476988 -294.335962)
		(width 0.09525)
		(layer "In2.Cu")
		(net "M_I_CPU0_SB_DQS_DP<3>")
	)
	(arc
		(start 393.70127 -294.681656)
		(mid 393.702287 -294.68229)
		(end 393.703302 -294.682926)
		(width 0.09525)
		(layer "In2.Cu")
		(net "M_I_CPU0_SB_DQS_DP<3>")
	)
	(arc
		(start 383.233422 -290.611052)
		(mid 383.514854 -290.535297)
		(end 383.796286 -290.611052)
		(width 0.09525)
		(layer "In2.Cu")
		(net "M_I_CPU0_SB_DQS_DP<3>")
	)
	(arc
		(start 381.353314 -290.611052)
		(mid 381.634746 -290.535297)
		(end 381.916178 -290.611052)
		(width 0.09525)
		(layer "In2.Cu")
		(net "M_I_CPU0_SB_DQS_DP<3>")
	)
	(arc
		(start 380.044706 -290.615878)
		(mid 380.229738 -290.661792)
		(end 380.413514 -290.611052)
		(width 0.09525)
		(layer "In2.Cu")
		(net "M_I_CPU0_SB_DQS_DP<3>")
	)
	(segment
		(start 376.938032 -285.160212)
		(end 377.404884 -285.42615)
		(width 0.12954)
		(layer "F.Cu")
		(net "M_I_CPU0_SB_DQS_DP<2>")
	)
	(segment
		(start 395.84249 -287.733486)
		(end 395.859254 -287.75025)
		(width 0.09525)
		(layer "In2.Cu")
		(net "M_I_CPU0_SB_DQS_DP<2>")
	)
	(segment
		(start 423.14876 -302.859948)
		(end 425.425616 -302.859948)
		(width 0.16002)
		(layer "In2.Cu")
		(net "M_I_CPU0_SB_DQS_DP<2>")
	)
	(segment
		(start 409.1051 -302.451262)
		(end 409.1051 -302.978566)
		(width 0.16002)
		(layer "In2.Cu")
		(net "M_I_CPU0_SB_DQS_DP<2>")
	)
	(segment
		(start 408.734514 -303.349152)
		(end 408.734514 -303.625758)
		(width 0.16002)
		(layer "In2.Cu")
		(net "M_I_CPU0_SB_DQS_DP<2>")
	)
	(segment
		(start 391.31621 -285.75127)
		(end 391.324592 -285.756096)
		(width 0.09525)
		(layer "In2.Cu")
		(net "M_I_CPU0_SB_DQS_DP<2>")
	)
	(segment
		(start 379.09627 -285.75127)
		(end 379.104652 -285.756096)
		(width 0.09525)
		(layer "In2.Cu")
		(net "M_I_CPU0_SB_DQS_DP<2>")
	)
	(segment
		(start 408.734514 -303.625758)
		(end 408.93111 -303.822354)
		(width 0.16002)
		(layer "In2.Cu")
		(net "M_I_CPU0_SB_DQS_DP<2>")
	)
	(segment
		(start 394.915898 -286.862012)
		(end 395.13129 -286.862012)
		(width 0.09525)
		(layer "In2.Cu")
		(net "M_I_CPU0_SB_DQS_DP<2>")
	)
	(segment
		(start 413.272986 -303.709832)
		(end 413.580326 -304.017172)
		(width 0.16002)
		(layer "In2.Cu")
		(net "M_I_CPU0_SB_DQS_DP<2>")
	)
	(segment
		(start 418.683694 -303.709832)
		(end 420.81704 -303.709832)
		(width 0.16002)
		(layer "In2.Cu")
		(net "M_I_CPU0_SB_DQS_DP<2>")
	)
	(segment
		(start 395.536674 -287.267396)
		(end 395.536674 -287.51149)
		(width 0.09525)
		(layer "In2.Cu")
		(net "M_I_CPU0_SB_DQS_DP<2>")
	)
	(segment
		(start 397.409924 -289.30092)
		(end 398.439894 -291.786056)
		(width 0.16002)
		(layer "In2.Cu")
		(net "M_I_CPU0_SB_DQS_DP<2>")
	)
	(segment
		(start 377.558808 -285.69158)
		(end 377.659646 -285.71825)
		(width 0.09525)
		(layer "In2.Cu")
		(net "M_I_CPU0_SB_DQS_DP<2>")
	)
	(segment
		(start 409.1051 -302.978566)
		(end 408.734514 -303.349152)
		(width 0.16002)
		(layer "In2.Cu")
		(net "M_I_CPU0_SB_DQS_DP<2>")
	)
	(segment
		(start 382.856232 -285.75127)
		(end 382.864614 -285.756096)
		(width 0.09525)
		(layer "In2.Cu")
		(net "M_I_CPU0_SB_DQS_DP<2>")
	)
	(segment
		(start 415.288222 -303.176432)
		(end 415.604706 -302.859948)
		(width 0.16002)
		(layer "In2.Cu")
		(net "M_I_CPU0_SB_DQS_DP<2>")
	)
	(segment
		(start 386.985002 -285.756096)
		(end 386.993384 -285.75127)
		(width 0.09525)
		(layer "In2.Cu")
		(net "M_I_CPU0_SB_DQS_DP<2>")
	)
	(segment
		(start 429.896016 -303.859692)
		(end 431.281586 -303.859692)
		(width 0.16002)
		(layer "In2.Cu")
		(net "M_I_CPU0_SB_DQS_DP<2>")
	)
	(segment
		(start 422.832276 -303.176432)
		(end 423.14876 -302.859948)
		(width 0.16002)
		(layer "In2.Cu")
		(net "M_I_CPU0_SB_DQS_DP<2>")
	)
	(segment
		(start 390.744964 -285.756096)
		(end 390.753346 -285.75127)
		(width 0.09525)
		(layer "In2.Cu")
		(net "M_I_CPU0_SB_DQS_DP<2>")
	)
	(segment
		(start 395.75867 -287.733486)
		(end 395.84249 -287.733486)
		(width 0.09525)
		(layer "In2.Cu")
		(net "M_I_CPU0_SB_DQS_DP<2>")
	)
	(segment
		(start 428.084996 -303.433988)
		(end 428.69358 -304.042572)
		(width 0.16002)
		(layer "In2.Cu")
		(net "M_I_CPU0_SB_DQS_DP<2>")
	)
	(segment
		(start 393.856464 -285.802578)
		(end 394.915898 -286.862012)
		(width 0.09525)
		(layer "In2.Cu")
		(net "M_I_CPU0_SB_DQS_DP<2>")
	)
	(segment
		(start 422.307004 -303.176432)
		(end 422.832276 -303.176432)
		(width 0.16002)
		(layer "In2.Cu")
		(net "M_I_CPU0_SB_DQS_DP<2>")
	)
	(segment
		(start 410.10586 -303.452022)
		(end 410.36367 -303.709832)
		(width 0.16002)
		(layer "In2.Cu")
		(net "M_I_CPU0_SB_DQS_DP<2>")
	)
	(segment
		(start 425.425616 -302.859948)
		(end 425.999656 -303.433988)
		(width 0.16002)
		(layer "In2.Cu")
		(net "M_I_CPU0_SB_DQS_DP<2>")
	)
	(segment
		(start 395.859254 -287.75025)
		(end 397.409924 -289.30092)
		(width 0.16002)
		(layer "In2.Cu")
		(net "M_I_CPU0_SB_DQS_DP<2>")
	)
	(segment
		(start 393.384786 -285.802578)
		(end 393.856464 -285.802578)
		(width 0.09525)
		(layer "In2.Cu")
		(net "M_I_CPU0_SB_DQS_DP<2>")
	)
	(segment
		(start 415.604706 -302.859948)
		(end 417.83381 -302.859948)
		(width 0.16002)
		(layer "In2.Cu")
		(net "M_I_CPU0_SB_DQS_DP<2>")
	)
	(segment
		(start 413.580326 -304.017172)
		(end 413.92221 -304.017172)
		(width 0.16002)
		(layer "In2.Cu")
		(net "M_I_CPU0_SB_DQS_DP<2>")
	)
	(segment
		(start 386.044948 -285.756096)
		(end 386.05333 -285.75127)
		(width 0.09525)
		(layer "In2.Cu")
		(net "M_I_CPU0_SB_DQS_DP<2>")
	)
	(segment
		(start 409.20797 -303.822354)
		(end 409.578302 -303.452022)
		(width 0.16002)
		(layer "In2.Cu")
		(net "M_I_CPU0_SB_DQS_DP<2>")
	)
	(segment
		(start 425.999656 -303.433988)
		(end 428.084996 -303.433988)
		(width 0.16002)
		(layer "In2.Cu")
		(net "M_I_CPU0_SB_DQS_DP<2>")
	)
	(segment
		(start 428.69358 -304.042572)
		(end 429.713136 -304.042572)
		(width 0.16002)
		(layer "In2.Cu")
		(net "M_I_CPU0_SB_DQS_DP<2>")
	)
	(segment
		(start 383.796286 -285.75127)
		(end 383.804668 -285.756096)
		(width 0.09525)
		(layer "In2.Cu")
		(net "M_I_CPU0_SB_DQS_DP<2>")
	)
	(segment
		(start 431.281586 -303.859692)
		(end 431.55616 -303.585118)
		(width 0.16002)
		(layer "In2.Cu")
		(net "M_I_CPU0_SB_DQS_DP<2>")
	)
	(segment
		(start 380.036324 -285.75127)
		(end 380.044706 -285.756096)
		(width 0.09525)
		(layer "In2.Cu")
		(net "M_I_CPU0_SB_DQS_DP<2>")
	)
	(segment
		(start 398.439894 -291.786056)
		(end 409.1051 -302.451262)
		(width 0.16002)
		(layer "In2.Cu")
		(net "M_I_CPU0_SB_DQS_DP<2>")
	)
	(segment
		(start 382.284986 -285.756096)
		(end 382.293368 -285.75127)
		(width 0.09525)
		(layer "In2.Cu")
		(net "M_I_CPU0_SB_DQS_DP<2>")
	)
	(segment
		(start 377.404884 -285.42615)
		(end 377.558808 -285.69158)
		(width 0.09525)
		(layer "In2.Cu")
		(net "M_I_CPU0_SB_DQS_DP<2>")
	)
	(segment
		(start 410.36367 -303.709832)
		(end 413.272986 -303.709832)
		(width 0.16002)
		(layer "In2.Cu")
		(net "M_I_CPU0_SB_DQS_DP<2>")
	)
	(segment
		(start 395.536674 -287.51149)
		(end 395.75867 -287.733486)
		(width 0.09525)
		(layer "In2.Cu")
		(net "M_I_CPU0_SB_DQS_DP<2>")
	)
	(segment
		(start 409.578302 -303.452022)
		(end 410.10586 -303.452022)
		(width 0.16002)
		(layer "In2.Cu")
		(net "M_I_CPU0_SB_DQS_DP<2>")
	)
	(segment
		(start 408.93111 -303.822354)
		(end 409.20797 -303.822354)
		(width 0.16002)
		(layer "In2.Cu")
		(net "M_I_CPU0_SB_DQS_DP<2>")
	)
	(segment
		(start 420.81704 -303.709832)
		(end 421.12438 -304.017172)
		(width 0.16002)
		(layer "In2.Cu")
		(net "M_I_CPU0_SB_DQS_DP<2>")
	)
	(segment
		(start 421.12438 -304.017172)
		(end 421.466264 -304.017172)
		(width 0.16002)
		(layer "In2.Cu")
		(net "M_I_CPU0_SB_DQS_DP<2>")
	)
	(segment
		(start 413.92221 -304.017172)
		(end 414.76295 -303.176432)
		(width 0.16002)
		(layer "In2.Cu")
		(net "M_I_CPU0_SB_DQS_DP<2>")
	)
	(segment
		(start 378.525024 -285.756096)
		(end 378.533406 -285.75127)
		(width 0.09525)
		(layer "In2.Cu")
		(net "M_I_CPU0_SB_DQS_DP<2>")
	)
	(segment
		(start 429.713136 -304.042572)
		(end 429.896016 -303.859692)
		(width 0.16002)
		(layer "In2.Cu")
		(net "M_I_CPU0_SB_DQS_DP<2>")
	)
	(segment
		(start 417.83381 -302.859948)
		(end 418.683694 -303.709832)
		(width 0.16002)
		(layer "In2.Cu")
		(net "M_I_CPU0_SB_DQS_DP<2>")
	)
	(segment
		(start 395.13129 -286.862012)
		(end 395.536674 -287.267396)
		(width 0.09525)
		(layer "In2.Cu")
		(net "M_I_CPU0_SB_DQS_DP<2>")
	)
	(segment
		(start 392.256264 -285.75127)
		(end 392.264646 -285.756096)
		(width 0.09525)
		(layer "In2.Cu")
		(net "M_I_CPU0_SB_DQS_DP<2>")
	)
	(segment
		(start 387.556248 -285.75127)
		(end 387.56463 -285.756096)
		(width 0.09525)
		(layer "In2.Cu")
		(net "M_I_CPU0_SB_DQS_DP<2>")
	)
	(segment
		(start 421.466264 -304.017172)
		(end 422.307004 -303.176432)
		(width 0.16002)
		(layer "In2.Cu")
		(net "M_I_CPU0_SB_DQS_DP<2>")
	)
	(segment
		(start 414.76295 -303.176432)
		(end 415.288222 -303.176432)
		(width 0.16002)
		(layer "In2.Cu")
		(net "M_I_CPU0_SB_DQS_DP<2>")
	)
	(segment
		(start 388.496302 -285.75127)
		(end 388.504684 -285.756096)
		(width 0.09525)
		(layer "In2.Cu")
		(net "M_I_CPU0_SB_DQS_DP<2>")
	)
	(arc
		(start 383.233422 -285.75127)
		(mid 383.514854 -285.675515)
		(end 383.796286 -285.75127)
		(width 0.09525)
		(layer "In2.Cu")
		(net "M_I_CPU0_SB_DQS_DP<2>")
	)
	(arc
		(start 382.864614 -285.756096)
		(mid 383.049646 -285.80201)
		(end 383.233422 -285.75127)
		(width 0.09525)
		(layer "In2.Cu")
		(net "M_I_CPU0_SB_DQS_DP<2>")
	)
	(arc
		(start 385.67614 -285.75127)
		(mid 385.859915 -285.802042)
		(end 386.044948 -285.756096)
		(width 0.09525)
		(layer "In2.Cu")
		(net "M_I_CPU0_SB_DQS_DP<2>")
	)
	(arc
		(start 382.293368 -285.75127)
		(mid 382.5748 -285.675515)
		(end 382.856232 -285.75127)
		(width 0.09525)
		(layer "In2.Cu")
		(net "M_I_CPU0_SB_DQS_DP<2>")
	)
	(arc
		(start 391.324592 -285.756096)
		(mid 391.509624 -285.80201)
		(end 391.6934 -285.75127)
		(width 0.09525)
		(layer "In2.Cu")
		(net "M_I_CPU0_SB_DQS_DP<2>")
	)
	(arc
		(start 378.533406 -285.75127)
		(mid 378.814838 -285.675515)
		(end 379.09627 -285.75127)
		(width 0.09525)
		(layer "In2.Cu")
		(net "M_I_CPU0_SB_DQS_DP<2>")
	)
	(arc
		(start 388.504684 -285.756096)
		(mid 388.689716 -285.80201)
		(end 388.873492 -285.75127)
		(width 0.09525)
		(layer "In2.Cu")
		(net "M_I_CPU0_SB_DQS_DP<2>")
	)
	(arc
		(start 386.616194 -285.75127)
		(mid 386.799969 -285.802042)
		(end 386.985002 -285.756096)
		(width 0.09525)
		(layer "In2.Cu")
		(net "M_I_CPU0_SB_DQS_DP<2>")
	)
	(arc
		(start 391.6934 -285.75127)
		(mid 391.974832 -285.675515)
		(end 392.256264 -285.75127)
		(width 0.09525)
		(layer "In2.Cu")
		(net "M_I_CPU0_SB_DQS_DP<2>")
	)
	(arc
		(start 380.044706 -285.756096)
		(mid 380.229738 -285.80201)
		(end 380.413514 -285.75127)
		(width 0.09525)
		(layer "In2.Cu")
		(net "M_I_CPU0_SB_DQS_DP<2>")
	)
	(arc
		(start 393.196318 -285.75127)
		(mid 393.287161 -285.789389)
		(end 393.384786 -285.802578)
		(width 0.09525)
		(layer "In2.Cu")
		(net "M_I_CPU0_SB_DQS_DP<2>")
	)
	(arc
		(start 384.173476 -285.75127)
		(mid 384.454908 -285.675515)
		(end 384.73634 -285.75127)
		(width 0.09525)
		(layer "In2.Cu")
		(net "M_I_CPU0_SB_DQS_DP<2>")
	)
	(arc
		(start 389.813292 -285.75127)
		(mid 390.094724 -285.675515)
		(end 390.376156 -285.75127)
		(width 0.09525)
		(layer "In2.Cu")
		(net "M_I_CPU0_SB_DQS_DP<2>")
	)
	(arc
		(start 392.633454 -285.75127)
		(mid 392.914886 -285.675515)
		(end 393.196318 -285.75127)
		(width 0.09525)
		(layer "In2.Cu")
		(net "M_I_CPU0_SB_DQS_DP<2>")
	)
	(arc
		(start 383.804668 -285.756096)
		(mid 383.9897 -285.80201)
		(end 384.173476 -285.75127)
		(width 0.09525)
		(layer "In2.Cu")
		(net "M_I_CPU0_SB_DQS_DP<2>")
	)
	(arc
		(start 388.873492 -285.75127)
		(mid 389.154924 -285.675515)
		(end 389.436356 -285.75127)
		(width 0.09525)
		(layer "In2.Cu")
		(net "M_I_CPU0_SB_DQS_DP<2>")
	)
	(arc
		(start 385.113276 -285.75127)
		(mid 385.394708 -285.675515)
		(end 385.67614 -285.75127)
		(width 0.09525)
		(layer "In2.Cu")
		(net "M_I_CPU0_SB_DQS_DP<2>")
	)
	(arc
		(start 386.05333 -285.75127)
		(mid 386.334762 -285.675515)
		(end 386.616194 -285.75127)
		(width 0.09525)
		(layer "In2.Cu")
		(net "M_I_CPU0_SB_DQS_DP<2>")
	)
	(arc
		(start 377.659646 -285.71825)
		(mid 377.911787 -285.67668)
		(end 378.156216 -285.75127)
		(width 0.09525)
		(layer "In2.Cu")
		(net "M_I_CPU0_SB_DQS_DP<2>")
	)
	(arc
		(start 392.264646 -285.756096)
		(mid 392.449678 -285.80201)
		(end 392.633454 -285.75127)
		(width 0.09525)
		(layer "In2.Cu")
		(net "M_I_CPU0_SB_DQS_DP<2>")
	)
	(arc
		(start 378.156216 -285.75127)
		(mid 378.339991 -285.802042)
		(end 378.525024 -285.756096)
		(width 0.09525)
		(layer "In2.Cu")
		(net "M_I_CPU0_SB_DQS_DP<2>")
	)
	(arc
		(start 390.753346 -285.75127)
		(mid 391.034778 -285.675515)
		(end 391.31621 -285.75127)
		(width 0.09525)
		(layer "In2.Cu")
		(net "M_I_CPU0_SB_DQS_DP<2>")
	)
	(arc
		(start 387.56463 -285.756096)
		(mid 387.749662 -285.80201)
		(end 387.933438 -285.75127)
		(width 0.09525)
		(layer "In2.Cu")
		(net "M_I_CPU0_SB_DQS_DP<2>")
	)
	(arc
		(start 387.933438 -285.75127)
		(mid 388.21487 -285.675515)
		(end 388.496302 -285.75127)
		(width 0.09525)
		(layer "In2.Cu")
		(net "M_I_CPU0_SB_DQS_DP<2>")
	)
	(arc
		(start 379.104652 -285.756096)
		(mid 379.289684 -285.80201)
		(end 379.47346 -285.75127)
		(width 0.09525)
		(layer "In2.Cu")
		(net "M_I_CPU0_SB_DQS_DP<2>")
	)
	(arc
		(start 384.73634 -285.75127)
		(mid 384.924808 -285.801947)
		(end 385.113276 -285.75127)
		(width 0.09525)
		(layer "In2.Cu")
		(net "M_I_CPU0_SB_DQS_DP<2>")
	)
	(arc
		(start 379.47346 -285.75127)
		(mid 379.754892 -285.675515)
		(end 380.036324 -285.75127)
		(width 0.09525)
		(layer "In2.Cu")
		(net "M_I_CPU0_SB_DQS_DP<2>")
	)
	(arc
		(start 390.376156 -285.75127)
		(mid 390.559931 -285.802042)
		(end 390.744964 -285.756096)
		(width 0.09525)
		(layer "In2.Cu")
		(net "M_I_CPU0_SB_DQS_DP<2>")
	)
	(arc
		(start 381.916178 -285.75127)
		(mid 382.099953 -285.802042)
		(end 382.284986 -285.756096)
		(width 0.09525)
		(layer "In2.Cu")
		(net "M_I_CPU0_SB_DQS_DP<2>")
	)
	(arc
		(start 380.413514 -285.75127)
		(mid 380.694946 -285.675515)
		(end 380.976378 -285.75127)
		(width 0.09525)
		(layer "In2.Cu")
		(net "M_I_CPU0_SB_DQS_DP<2>")
	)
	(arc
		(start 389.436356 -285.75127)
		(mid 389.624824 -285.801947)
		(end 389.813292 -285.75127)
		(width 0.09525)
		(layer "In2.Cu")
		(net "M_I_CPU0_SB_DQS_DP<2>")
	)
	(arc
		(start 380.976378 -285.75127)
		(mid 381.164846 -285.801947)
		(end 381.353314 -285.75127)
		(width 0.09525)
		(layer "In2.Cu")
		(net "M_I_CPU0_SB_DQS_DP<2>")
	)
	(arc
		(start 386.993384 -285.75127)
		(mid 387.274816 -285.675515)
		(end 387.556248 -285.75127)
		(width 0.09525)
		(layer "In2.Cu")
		(net "M_I_CPU0_SB_DQS_DP<2>")
	)
	(arc
		(start 381.353314 -285.75127)
		(mid 381.634746 -285.675515)
		(end 381.916178 -285.75127)
		(width 0.09525)
		(layer "In2.Cu")
		(net "M_I_CPU0_SB_DQS_DP<2>")
	)
	(segment
		(start 376.938032 -280.300176)
		(end 377.404884 -280.566114)
		(width 0.12954)
		(layer "F.Cu")
		(net "M_I_CPU0_SB_DQS_DP<1>")
	)
	(segment
		(start 395.77645 -280.985722)
		(end 395.835632 -280.92654)
		(width 0.09525)
		(layer "In2.Cu")
		(net "M_I_CPU0_SB_DQS_DP<1>")
	)
	(segment
		(start 395.630146 -280.985722)
		(end 395.77645 -280.985722)
		(width 0.09525)
		(layer "In2.Cu")
		(net "M_I_CPU0_SB_DQS_DP<1>")
	)
	(segment
		(start 393.18184 -280.882598)
		(end 393.196572 -280.891234)
		(width 0.09525)
		(layer "In2.Cu")
		(net "M_I_CPU0_SB_DQS_DP<1>")
	)
	(segment
		(start 394.245084 -280.534872)
		(end 395.179296 -280.534872)
		(width 0.09525)
		(layer "In2.Cu")
		(net "M_I_CPU0_SB_DQS_DP<1>")
	)
	(segment
		(start 395.859254 -280.92654)
		(end 397.385032 -280.92654)
		(width 0.16002)
		(layer "In2.Cu")
		(net "M_I_CPU0_SB_DQS_DP<1>")
	)
	(segment
		(start 382.856232 -280.891234)
		(end 382.864614 -280.89606)
		(width 0.09525)
		(layer "In2.Cu")
		(net "M_I_CPU0_SB_DQS_DP<1>")
	)
	(segment
		(start 386.044948 -280.89606)
		(end 386.05333 -280.891234)
		(width 0.09525)
		(layer "In2.Cu")
		(net "M_I_CPU0_SB_DQS_DP<1>")
	)
	(segment
		(start 423.14876 -293.509954)
		(end 425.425616 -293.509954)
		(width 0.16002)
		(layer "In2.Cu")
		(net "M_I_CPU0_SB_DQS_DP<1>")
	)
	(segment
		(start 378.525024 -280.89606)
		(end 378.533406 -280.891234)
		(width 0.09525)
		(layer "In2.Cu")
		(net "M_I_CPU0_SB_DQS_DP<1>")
	)
	(segment
		(start 391.6934 -280.891234)
		(end 391.708132 -280.882598)
		(width 0.09525)
		(layer "In2.Cu")
		(net "M_I_CPU0_SB_DQS_DP<1>")
	)
	(segment
		(start 425.999656 -294.083994)
		(end 428.084996 -294.083994)
		(width 0.16002)
		(layer "In2.Cu")
		(net "M_I_CPU0_SB_DQS_DP<1>")
	)
	(segment
		(start 392.622278 -280.898092)
		(end 392.634216 -280.891234)
		(width 0.09525)
		(layer "In2.Cu")
		(net "M_I_CPU0_SB_DQS_DP<1>")
	)
	(segment
		(start 402.53285 -285.206694)
		(end 410.836618 -293.510462)
		(width 0.16002)
		(layer "In2.Cu")
		(net "M_I_CPU0_SB_DQS_DP<1>")
	)
	(segment
		(start 388.496302 -280.891234)
		(end 388.504684 -280.89606)
		(width 0.09525)
		(layer "In2.Cu")
		(net "M_I_CPU0_SB_DQS_DP<1>")
	)
	(segment
		(start 393.47648 -280.942034)
		(end 393.476988 -280.942542)
		(width 0.09525)
		(layer "In2.Cu")
		(net "M_I_CPU0_SB_DQS_DP<1>")
	)
	(segment
		(start 415.288222 -293.826438)
		(end 415.604706 -293.509954)
		(width 0.16002)
		(layer "In2.Cu")
		(net "M_I_CPU0_SB_DQS_DP<1>")
	)
	(segment
		(start 413.92221 -294.667178)
		(end 414.76295 -293.826438)
		(width 0.16002)
		(layer "In2.Cu")
		(net "M_I_CPU0_SB_DQS_DP<1>")
	)
	(segment
		(start 393.837414 -280.942542)
		(end 394.245084 -280.534872)
		(width 0.09525)
		(layer "In2.Cu")
		(net "M_I_CPU0_SB_DQS_DP<1>")
	)
	(segment
		(start 387.556248 -280.891234)
		(end 387.56463 -280.89606)
		(width 0.09525)
		(layer "In2.Cu")
		(net "M_I_CPU0_SB_DQS_DP<1>")
	)
	(segment
		(start 393.476988 -280.942542)
		(end 393.837414 -280.942542)
		(width 0.09525)
		(layer "In2.Cu")
		(net "M_I_CPU0_SB_DQS_DP<1>")
	)
	(segment
		(start 413.272986 -294.359838)
		(end 413.580326 -294.667178)
		(width 0.16002)
		(layer "In2.Cu")
		(net "M_I_CPU0_SB_DQS_DP<1>")
	)
	(segment
		(start 386.985002 -280.89606)
		(end 386.993384 -280.891234)
		(width 0.09525)
		(layer "In2.Cu")
		(net "M_I_CPU0_SB_DQS_DP<1>")
	)
	(segment
		(start 425.425616 -293.509954)
		(end 425.999656 -294.083994)
		(width 0.16002)
		(layer "In2.Cu")
		(net "M_I_CPU0_SB_DQS_DP<1>")
	)
	(segment
		(start 410.836618 -293.877238)
		(end 411.319218 -294.359838)
		(width 0.16002)
		(layer "In2.Cu")
		(net "M_I_CPU0_SB_DQS_DP<1>")
	)
	(segment
		(start 429.320452 -294.509698)
		(end 431.281586 -294.509698)
		(width 0.16002)
		(layer "In2.Cu")
		(net "M_I_CPU0_SB_DQS_DP<1>")
	)
	(segment
		(start 413.580326 -294.667178)
		(end 413.92221 -294.667178)
		(width 0.16002)
		(layer "In2.Cu")
		(net "M_I_CPU0_SB_DQS_DP<1>")
	)
	(segment
		(start 395.179296 -280.534872)
		(end 395.630146 -280.985722)
		(width 0.09525)
		(layer "In2.Cu")
		(net "M_I_CPU0_SB_DQS_DP<1>")
	)
	(segment
		(start 397.385032 -280.92654)
		(end 401.665186 -285.206694)
		(width 0.16002)
		(layer "In2.Cu")
		(net "M_I_CPU0_SB_DQS_DP<1>")
	)
	(segment
		(start 393.196572 -280.891234)
		(end 393.21105 -280.899616)
		(width 0.09525)
		(layer "In2.Cu")
		(net "M_I_CPU0_SB_DQS_DP<1>")
	)
	(segment
		(start 429.137572 -294.692578)
		(end 429.320452 -294.509698)
		(width 0.16002)
		(layer "In2.Cu")
		(net "M_I_CPU0_SB_DQS_DP<1>")
	)
	(segment
		(start 421.12438 -294.667178)
		(end 421.466264 -294.667178)
		(width 0.16002)
		(layer "In2.Cu")
		(net "M_I_CPU0_SB_DQS_DP<1>")
	)
	(segment
		(start 414.76295 -293.826438)
		(end 415.288222 -293.826438)
		(width 0.16002)
		(layer "In2.Cu")
		(net "M_I_CPU0_SB_DQS_DP<1>")
	)
	(segment
		(start 422.832276 -293.826438)
		(end 423.14876 -293.509954)
		(width 0.16002)
		(layer "In2.Cu")
		(net "M_I_CPU0_SB_DQS_DP<1>")
	)
	(segment
		(start 411.319218 -294.359838)
		(end 413.272986 -294.359838)
		(width 0.16002)
		(layer "In2.Cu")
		(net "M_I_CPU0_SB_DQS_DP<1>")
	)
	(segment
		(start 422.307004 -293.826438)
		(end 422.832276 -293.826438)
		(width 0.16002)
		(layer "In2.Cu")
		(net "M_I_CPU0_SB_DQS_DP<1>")
	)
	(segment
		(start 415.604706 -293.509954)
		(end 417.83381 -293.509954)
		(width 0.16002)
		(layer "In2.Cu")
		(net "M_I_CPU0_SB_DQS_DP<1>")
	)
	(segment
		(start 391.31621 -280.891234)
		(end 391.324592 -280.89606)
		(width 0.09525)
		(layer "In2.Cu")
		(net "M_I_CPU0_SB_DQS_DP<1>")
	)
	(segment
		(start 383.796286 -280.891234)
		(end 383.804668 -280.89606)
		(width 0.09525)
		(layer "In2.Cu")
		(net "M_I_CPU0_SB_DQS_DP<1>")
	)
	(segment
		(start 428.084996 -294.083994)
		(end 428.69358 -294.692578)
		(width 0.16002)
		(layer "In2.Cu")
		(net "M_I_CPU0_SB_DQS_DP<1>")
	)
	(segment
		(start 395.835632 -280.92654)
		(end 395.859254 -280.92654)
		(width 0.09525)
		(layer "In2.Cu")
		(net "M_I_CPU0_SB_DQS_DP<1>")
	)
	(segment
		(start 421.466264 -294.667178)
		(end 422.307004 -293.826438)
		(width 0.16002)
		(layer "In2.Cu")
		(net "M_I_CPU0_SB_DQS_DP<1>")
	)
	(segment
		(start 420.81704 -294.359838)
		(end 421.12438 -294.667178)
		(width 0.16002)
		(layer "In2.Cu")
		(net "M_I_CPU0_SB_DQS_DP<1>")
	)
	(segment
		(start 410.836618 -293.510462)
		(end 410.836618 -293.877238)
		(width 0.16002)
		(layer "In2.Cu")
		(net "M_I_CPU0_SB_DQS_DP<1>")
	)
	(segment
		(start 390.744964 -280.89606)
		(end 390.753346 -280.891234)
		(width 0.09525)
		(layer "In2.Cu")
		(net "M_I_CPU0_SB_DQS_DP<1>")
	)
	(segment
		(start 418.683694 -294.359838)
		(end 420.81704 -294.359838)
		(width 0.16002)
		(layer "In2.Cu")
		(net "M_I_CPU0_SB_DQS_DP<1>")
	)
	(segment
		(start 377.558808 -280.831544)
		(end 377.659646 -280.858214)
		(width 0.09525)
		(layer "In2.Cu")
		(net "M_I_CPU0_SB_DQS_DP<1>")
	)
	(segment
		(start 382.284986 -280.89606)
		(end 382.293368 -280.891234)
		(width 0.09525)
		(layer "In2.Cu")
		(net "M_I_CPU0_SB_DQS_DP<1>")
	)
	(segment
		(start 428.69358 -294.692578)
		(end 429.137572 -294.692578)
		(width 0.16002)
		(layer "In2.Cu")
		(net "M_I_CPU0_SB_DQS_DP<1>")
	)
	(segment
		(start 431.281586 -294.509698)
		(end 431.55616 -294.235124)
		(width 0.16002)
		(layer "In2.Cu")
		(net "M_I_CPU0_SB_DQS_DP<1>")
	)
	(segment
		(start 401.665186 -285.206694)
		(end 402.53285 -285.206694)
		(width 0.16002)
		(layer "In2.Cu")
		(net "M_I_CPU0_SB_DQS_DP<1>")
	)
	(segment
		(start 379.09627 -280.891234)
		(end 379.104652 -280.89606)
		(width 0.09525)
		(layer "In2.Cu")
		(net "M_I_CPU0_SB_DQS_DP<1>")
	)
	(segment
		(start 393.381738 -280.942034)
		(end 393.47648 -280.942034)
		(width 0.09525)
		(layer "In2.Cu")
		(net "M_I_CPU0_SB_DQS_DP<1>")
	)
	(segment
		(start 380.036324 -280.891234)
		(end 380.044706 -280.89606)
		(width 0.09525)
		(layer "In2.Cu")
		(net "M_I_CPU0_SB_DQS_DP<1>")
	)
	(segment
		(start 377.404884 -280.566114)
		(end 377.558808 -280.831544)
		(width 0.09525)
		(layer "In2.Cu")
		(net "M_I_CPU0_SB_DQS_DP<1>")
	)
	(segment
		(start 417.83381 -293.509954)
		(end 418.683694 -294.359838)
		(width 0.16002)
		(layer "In2.Cu")
		(net "M_I_CPU0_SB_DQS_DP<1>")
	)
	(arc
		(start 383.804668 -280.89606)
		(mid 383.9897 -280.941974)
		(end 384.173476 -280.891234)
		(width 0.09525)
		(layer "In2.Cu")
		(net "M_I_CPU0_SB_DQS_DP<1>")
	)
	(arc
		(start 389.813292 -280.891234)
		(mid 390.094724 -280.815479)
		(end 390.376156 -280.891234)
		(width 0.09525)
		(layer "In2.Cu")
		(net "M_I_CPU0_SB_DQS_DP<1>")
	)
	(arc
		(start 381.916178 -280.891234)
		(mid 382.099953 -280.942006)
		(end 382.284986 -280.89606)
		(width 0.09525)
		(layer "In2.Cu")
		(net "M_I_CPU0_SB_DQS_DP<1>")
	)
	(arc
		(start 387.56463 -280.89606)
		(mid 387.749662 -280.941974)
		(end 387.933438 -280.891234)
		(width 0.09525)
		(layer "In2.Cu")
		(net "M_I_CPU0_SB_DQS_DP<1>")
	)
	(arc
		(start 382.293368 -280.891234)
		(mid 382.5748 -280.815479)
		(end 382.856232 -280.891234)
		(width 0.09525)
		(layer "In2.Cu")
		(net "M_I_CPU0_SB_DQS_DP<1>")
	)
	(arc
		(start 385.67614 -280.891234)
		(mid 385.859915 -280.942006)
		(end 386.044948 -280.89606)
		(width 0.09525)
		(layer "In2.Cu")
		(net "M_I_CPU0_SB_DQS_DP<1>")
	)
	(arc
		(start 378.156216 -280.891234)
		(mid 378.339991 -280.942006)
		(end 378.525024 -280.89606)
		(width 0.09525)
		(layer "In2.Cu")
		(net "M_I_CPU0_SB_DQS_DP<1>")
	)
	(arc
		(start 384.173476 -280.891234)
		(mid 384.454908 -280.815479)
		(end 384.73634 -280.891234)
		(width 0.09525)
		(layer "In2.Cu")
		(net "M_I_CPU0_SB_DQS_DP<1>")
	)
	(arc
		(start 393.21105 -280.899616)
		(mid 393.293879 -280.930945)
		(end 393.381738 -280.942034)
		(width 0.09525)
		(layer "In2.Cu")
		(net "M_I_CPU0_SB_DQS_DP<1>")
	)
	(arc
		(start 377.659646 -280.858214)
		(mid 377.911787 -280.816644)
		(end 378.156216 -280.891234)
		(width 0.09525)
		(layer "In2.Cu")
		(net "M_I_CPU0_SB_DQS_DP<1>")
	)
	(arc
		(start 392.634216 -280.891234)
		(mid 392.90689 -280.815547)
		(end 393.18184 -280.882598)
		(width 0.09525)
		(layer "In2.Cu")
		(net "M_I_CPU0_SB_DQS_DP<1>")
	)
	(arc
		(start 379.47346 -280.891234)
		(mid 379.754892 -280.815479)
		(end 380.036324 -280.891234)
		(width 0.09525)
		(layer "In2.Cu")
		(net "M_I_CPU0_SB_DQS_DP<1>")
	)
	(arc
		(start 378.533406 -280.891234)
		(mid 378.814838 -280.815479)
		(end 379.09627 -280.891234)
		(width 0.09525)
		(layer "In2.Cu")
		(net "M_I_CPU0_SB_DQS_DP<1>")
	)
	(arc
		(start 381.353314 -280.891234)
		(mid 381.634746 -280.815479)
		(end 381.916178 -280.891234)
		(width 0.09525)
		(layer "In2.Cu")
		(net "M_I_CPU0_SB_DQS_DP<1>")
	)
	(arc
		(start 391.324592 -280.89606)
		(mid 391.509624 -280.941974)
		(end 391.6934 -280.891234)
		(width 0.09525)
		(layer "In2.Cu")
		(net "M_I_CPU0_SB_DQS_DP<1>")
	)
	(arc
		(start 388.873492 -280.891234)
		(mid 389.154924 -280.815479)
		(end 389.436356 -280.891234)
		(width 0.09525)
		(layer "In2.Cu")
		(net "M_I_CPU0_SB_DQS_DP<1>")
	)
	(arc
		(start 389.436356 -280.891234)
		(mid 389.624824 -280.941911)
		(end 389.813292 -280.891234)
		(width 0.09525)
		(layer "In2.Cu")
		(net "M_I_CPU0_SB_DQS_DP<1>")
	)
	(arc
		(start 390.753346 -280.891234)
		(mid 391.034778 -280.815479)
		(end 391.31621 -280.891234)
		(width 0.09525)
		(layer "In2.Cu")
		(net "M_I_CPU0_SB_DQS_DP<1>")
	)
	(arc
		(start 387.933438 -280.891234)
		(mid 388.21487 -280.815479)
		(end 388.496302 -280.891234)
		(width 0.09525)
		(layer "In2.Cu")
		(net "M_I_CPU0_SB_DQS_DP<1>")
	)
	(arc
		(start 382.864614 -280.89606)
		(mid 383.049646 -280.941974)
		(end 383.233422 -280.891234)
		(width 0.09525)
		(layer "In2.Cu")
		(net "M_I_CPU0_SB_DQS_DP<1>")
	)
	(arc
		(start 388.504684 -280.89606)
		(mid 388.689716 -280.941974)
		(end 388.873492 -280.891234)
		(width 0.09525)
		(layer "In2.Cu")
		(net "M_I_CPU0_SB_DQS_DP<1>")
	)
	(arc
		(start 392.256772 -280.891234)
		(mid 392.438642 -280.942099)
		(end 392.622278 -280.898092)
		(width 0.09525)
		(layer "In2.Cu")
		(net "M_I_CPU0_SB_DQS_DP<1>")
	)
	(arc
		(start 379.104652 -280.89606)
		(mid 379.289684 -280.941974)
		(end 379.47346 -280.891234)
		(width 0.09525)
		(layer "In2.Cu")
		(net "M_I_CPU0_SB_DQS_DP<1>")
	)
	(arc
		(start 380.976378 -280.891234)
		(mid 381.164846 -280.941911)
		(end 381.353314 -280.891234)
		(width 0.09525)
		(layer "In2.Cu")
		(net "M_I_CPU0_SB_DQS_DP<1>")
	)
	(arc
		(start 384.73634 -280.891234)
		(mid 384.924808 -280.941911)
		(end 385.113276 -280.891234)
		(width 0.09525)
		(layer "In2.Cu")
		(net "M_I_CPU0_SB_DQS_DP<1>")
	)
	(arc
		(start 383.233422 -280.891234)
		(mid 383.514854 -280.815479)
		(end 383.796286 -280.891234)
		(width 0.09525)
		(layer "In2.Cu")
		(net "M_I_CPU0_SB_DQS_DP<1>")
	)
	(arc
		(start 380.044706 -280.89606)
		(mid 380.229738 -280.941974)
		(end 380.413514 -280.891234)
		(width 0.09525)
		(layer "In2.Cu")
		(net "M_I_CPU0_SB_DQS_DP<1>")
	)
	(arc
		(start 385.113276 -280.891234)
		(mid 385.394708 -280.815479)
		(end 385.67614 -280.891234)
		(width 0.09525)
		(layer "In2.Cu")
		(net "M_I_CPU0_SB_DQS_DP<1>")
	)
	(arc
		(start 386.05333 -280.891234)
		(mid 386.334762 -280.815479)
		(end 386.616194 -280.891234)
		(width 0.09525)
		(layer "In2.Cu")
		(net "M_I_CPU0_SB_DQS_DP<1>")
	)
	(arc
		(start 391.708132 -280.882598)
		(mid 391.983591 -280.815213)
		(end 392.256772 -280.891234)
		(width 0.09525)
		(layer "In2.Cu")
		(net "M_I_CPU0_SB_DQS_DP<1>")
	)
	(arc
		(start 380.413514 -280.891234)
		(mid 380.694946 -280.815479)
		(end 380.976378 -280.891234)
		(width 0.09525)
		(layer "In2.Cu")
		(net "M_I_CPU0_SB_DQS_DP<1>")
	)
	(arc
		(start 386.993384 -280.891234)
		(mid 387.274816 -280.815479)
		(end 387.556248 -280.891234)
		(width 0.09525)
		(layer "In2.Cu")
		(net "M_I_CPU0_SB_DQS_DP<1>")
	)
	(arc
		(start 390.376156 -280.891234)
		(mid 390.559931 -280.942006)
		(end 390.744964 -280.89606)
		(width 0.09525)
		(layer "In2.Cu")
		(net "M_I_CPU0_SB_DQS_DP<1>")
	)
	(arc
		(start 386.616194 -280.891234)
		(mid 386.799969 -280.942006)
		(end 386.985002 -280.89606)
		(width 0.09525)
		(layer "In2.Cu")
		(net "M_I_CPU0_SB_DQS_DP<1>")
	)
	(segment
		(start 376.938032 -275.44014)
		(end 377.404884 -275.706078)
		(width 0.12954)
		(layer "F.Cu")
		(net "M_I_CPU0_SB_DQS_DP<0>")
	)
	(segment
		(start 429.282352 -285.159704)
		(end 431.281586 -285.159704)
		(width 0.16002)
		(layer "In2.Cu")
		(net "M_I_CPU0_SB_DQS_DP<0>")
	)
	(segment
		(start 425.999656 -284.734)
		(end 428.084996 -284.734)
		(width 0.16002)
		(layer "In2.Cu")
		(net "M_I_CPU0_SB_DQS_DP<0>")
	)
	(segment
		(start 395.77645 -274.956778)
		(end 395.835632 -274.897596)
		(width 0.09525)
		(layer "In2.Cu")
		(net "M_I_CPU0_SB_DQS_DP<0>")
	)
	(segment
		(start 414.76295 -284.476444)
		(end 415.288222 -284.476444)
		(width 0.16002)
		(layer "In2.Cu")
		(net "M_I_CPU0_SB_DQS_DP<0>")
	)
	(segment
		(start 387.556248 -276.031198)
		(end 387.56463 -276.036024)
		(width 0.09525)
		(layer "In2.Cu")
		(net "M_I_CPU0_SB_DQS_DP<0>")
	)
	(segment
		(start 425.425616 -284.15996)
		(end 425.999656 -284.734)
		(width 0.16002)
		(layer "In2.Cu")
		(net "M_I_CPU0_SB_DQS_DP<0>")
	)
	(segment
		(start 421.12438 -285.317184)
		(end 421.466264 -285.317184)
		(width 0.16002)
		(layer "In2.Cu")
		(net "M_I_CPU0_SB_DQS_DP<0>")
	)
	(segment
		(start 386.985002 -276.036024)
		(end 386.993384 -276.031198)
		(width 0.09525)
		(layer "In2.Cu")
		(net "M_I_CPU0_SB_DQS_DP<0>")
	)
	(segment
		(start 379.09627 -276.031198)
		(end 379.104652 -276.036024)
		(width 0.09525)
		(layer "In2.Cu")
		(net "M_I_CPU0_SB_DQS_DP<0>")
	)
	(segment
		(start 415.604706 -284.15996)
		(end 417.83381 -284.15996)
		(width 0.16002)
		(layer "In2.Cu")
		(net "M_I_CPU0_SB_DQS_DP<0>")
	)
	(segment
		(start 388.496302 -276.031198)
		(end 388.504684 -276.036024)
		(width 0.09525)
		(layer "In2.Cu")
		(net "M_I_CPU0_SB_DQS_DP<0>")
	)
	(segment
		(start 392.622278 -276.038056)
		(end 392.634216 -276.031198)
		(width 0.09525)
		(layer "In2.Cu")
		(net "M_I_CPU0_SB_DQS_DP<0>")
	)
	(segment
		(start 377.558808 -275.971508)
		(end 377.659646 -275.998178)
		(width 0.09525)
		(layer "In2.Cu")
		(net "M_I_CPU0_SB_DQS_DP<0>")
	)
	(segment
		(start 408.922728 -282.607258)
		(end 411.325314 -285.009844)
		(width 0.16002)
		(layer "In2.Cu")
		(net "M_I_CPU0_SB_DQS_DP<0>")
	)
	(segment
		(start 395.859254 -274.897596)
		(end 400.604482 -274.897596)
		(width 0.16002)
		(layer "In2.Cu")
		(net "M_I_CPU0_SB_DQS_DP<0>")
	)
	(segment
		(start 417.83381 -284.15996)
		(end 418.683694 -285.009844)
		(width 0.16002)
		(layer "In2.Cu")
		(net "M_I_CPU0_SB_DQS_DP<0>")
	)
	(segment
		(start 423.14876 -284.15996)
		(end 425.425616 -284.15996)
		(width 0.16002)
		(layer "In2.Cu")
		(net "M_I_CPU0_SB_DQS_DP<0>")
	)
	(segment
		(start 422.307004 -284.476444)
		(end 422.832276 -284.476444)
		(width 0.16002)
		(layer "In2.Cu")
		(net "M_I_CPU0_SB_DQS_DP<0>")
	)
	(segment
		(start 428.084996 -284.734)
		(end 428.69358 -285.342584)
		(width 0.16002)
		(layer "In2.Cu")
		(net "M_I_CPU0_SB_DQS_DP<0>")
	)
	(segment
		(start 391.31621 -276.031198)
		(end 391.324592 -276.036024)
		(width 0.09525)
		(layer "In2.Cu")
		(net "M_I_CPU0_SB_DQS_DP<0>")
	)
	(segment
		(start 413.580326 -285.317184)
		(end 413.92221 -285.317184)
		(width 0.16002)
		(layer "In2.Cu")
		(net "M_I_CPU0_SB_DQS_DP<0>")
	)
	(segment
		(start 377.404884 -275.706078)
		(end 377.558808 -275.971508)
		(width 0.09525)
		(layer "In2.Cu")
		(net "M_I_CPU0_SB_DQS_DP<0>")
	)
	(segment
		(start 413.92221 -285.317184)
		(end 414.76295 -284.476444)
		(width 0.16002)
		(layer "In2.Cu")
		(net "M_I_CPU0_SB_DQS_DP<0>")
	)
	(segment
		(start 411.325314 -285.009844)
		(end 413.272986 -285.009844)
		(width 0.16002)
		(layer "In2.Cu")
		(net "M_I_CPU0_SB_DQS_DP<0>")
	)
	(segment
		(start 382.284986 -276.036024)
		(end 382.293368 -276.031198)
		(width 0.09525)
		(layer "In2.Cu")
		(net "M_I_CPU0_SB_DQS_DP<0>")
	)
	(segment
		(start 393.196572 -276.031198)
		(end 393.21105 -276.03958)
		(width 0.09525)
		(layer "In2.Cu")
		(net "M_I_CPU0_SB_DQS_DP<0>")
	)
	(segment
		(start 386.044948 -276.036024)
		(end 386.05333 -276.031198)
		(width 0.09525)
		(layer "In2.Cu")
		(net "M_I_CPU0_SB_DQS_DP<0>")
	)
	(segment
		(start 380.036324 -276.031198)
		(end 380.044706 -276.036024)
		(width 0.09525)
		(layer "In2.Cu")
		(net "M_I_CPU0_SB_DQS_DP<0>")
	)
	(segment
		(start 382.856232 -276.031198)
		(end 382.864614 -276.036024)
		(width 0.09525)
		(layer "In2.Cu")
		(net "M_I_CPU0_SB_DQS_DP<0>")
	)
	(segment
		(start 415.288222 -284.476444)
		(end 415.604706 -284.15996)
		(width 0.16002)
		(layer "In2.Cu")
		(net "M_I_CPU0_SB_DQS_DP<0>")
	)
	(segment
		(start 394.604494 -275.018754)
		(end 395.148308 -275.018754)
		(width 0.09525)
		(layer "In2.Cu")
		(net "M_I_CPU0_SB_DQS_DP<0>")
	)
	(segment
		(start 383.796286 -276.031198)
		(end 383.804668 -276.036024)
		(width 0.09525)
		(layer "In2.Cu")
		(net "M_I_CPU0_SB_DQS_DP<0>")
	)
	(segment
		(start 391.6934 -276.031198)
		(end 391.708132 -276.022562)
		(width 0.09525)
		(layer "In2.Cu")
		(net "M_I_CPU0_SB_DQS_DP<0>")
	)
	(segment
		(start 395.835632 -274.897596)
		(end 395.859254 -274.897596)
		(width 0.09525)
		(layer "In2.Cu")
		(net "M_I_CPU0_SB_DQS_DP<0>")
	)
	(segment
		(start 395.148308 -275.018754)
		(end 395.210284 -274.956778)
		(width 0.09525)
		(layer "In2.Cu")
		(net "M_I_CPU0_SB_DQS_DP<0>")
	)
	(segment
		(start 429.099472 -285.342584)
		(end 429.282352 -285.159704)
		(width 0.16002)
		(layer "In2.Cu")
		(net "M_I_CPU0_SB_DQS_DP<0>")
	)
	(segment
		(start 420.81704 -285.009844)
		(end 421.12438 -285.317184)
		(width 0.16002)
		(layer "In2.Cu")
		(net "M_I_CPU0_SB_DQS_DP<0>")
	)
	(segment
		(start 393.18184 -276.022562)
		(end 393.196572 -276.031198)
		(width 0.09525)
		(layer "In2.Cu")
		(net "M_I_CPU0_SB_DQS_DP<0>")
	)
	(segment
		(start 390.744964 -276.036024)
		(end 390.753346 -276.031198)
		(width 0.09525)
		(layer "In2.Cu")
		(net "M_I_CPU0_SB_DQS_DP<0>")
	)
	(segment
		(start 393.650978 -275.97227)
		(end 394.604494 -275.018754)
		(width 0.09525)
		(layer "In2.Cu")
		(net "M_I_CPU0_SB_DQS_DP<0>")
	)
	(segment
		(start 428.69358 -285.342584)
		(end 429.099472 -285.342584)
		(width 0.16002)
		(layer "In2.Cu")
		(net "M_I_CPU0_SB_DQS_DP<0>")
	)
	(segment
		(start 421.466264 -285.317184)
		(end 422.307004 -284.476444)
		(width 0.16002)
		(layer "In2.Cu")
		(net "M_I_CPU0_SB_DQS_DP<0>")
	)
	(segment
		(start 400.604482 -274.897596)
		(end 408.314144 -282.607258)
		(width 0.16002)
		(layer "In2.Cu")
		(net "M_I_CPU0_SB_DQS_DP<0>")
	)
	(segment
		(start 413.272986 -285.009844)
		(end 413.580326 -285.317184)
		(width 0.16002)
		(layer "In2.Cu")
		(net "M_I_CPU0_SB_DQS_DP<0>")
	)
	(segment
		(start 378.525024 -276.036024)
		(end 378.533406 -276.031198)
		(width 0.09525)
		(layer "In2.Cu")
		(net "M_I_CPU0_SB_DQS_DP<0>")
	)
	(segment
		(start 395.210284 -274.956778)
		(end 395.77645 -274.956778)
		(width 0.09525)
		(layer "In2.Cu")
		(net "M_I_CPU0_SB_DQS_DP<0>")
	)
	(segment
		(start 408.314144 -282.607258)
		(end 408.922728 -282.607258)
		(width 0.16002)
		(layer "In2.Cu")
		(net "M_I_CPU0_SB_DQS_DP<0>")
	)
	(segment
		(start 431.281586 -285.159704)
		(end 431.55616 -284.88513)
		(width 0.16002)
		(layer "In2.Cu")
		(net "M_I_CPU0_SB_DQS_DP<0>")
	)
	(segment
		(start 422.832276 -284.476444)
		(end 423.14876 -284.15996)
		(width 0.16002)
		(layer "In2.Cu")
		(net "M_I_CPU0_SB_DQS_DP<0>")
	)
	(segment
		(start 418.683694 -285.009844)
		(end 420.81704 -285.009844)
		(width 0.16002)
		(layer "In2.Cu")
		(net "M_I_CPU0_SB_DQS_DP<0>")
	)
	(arc
		(start 386.616194 -276.031198)
		(mid 386.799969 -276.08197)
		(end 386.985002 -276.036024)
		(width 0.09525)
		(layer "In2.Cu")
		(net "M_I_CPU0_SB_DQS_DP<0>")
	)
	(arc
		(start 378.533406 -276.031198)
		(mid 378.814838 -275.955443)
		(end 379.09627 -276.031198)
		(width 0.09525)
		(layer "In2.Cu")
		(net "M_I_CPU0_SB_DQS_DP<0>")
	)
	(arc
		(start 392.256772 -276.031198)
		(mid 392.438642 -276.082063)
		(end 392.622278 -276.038056)
		(width 0.09525)
		(layer "In2.Cu")
		(net "M_I_CPU0_SB_DQS_DP<0>")
	)
	(arc
		(start 391.324592 -276.036024)
		(mid 391.509624 -276.081938)
		(end 391.6934 -276.031198)
		(width 0.09525)
		(layer "In2.Cu")
		(net "M_I_CPU0_SB_DQS_DP<0>")
	)
	(arc
		(start 379.104652 -276.036024)
		(mid 379.289684 -276.081938)
		(end 379.47346 -276.031198)
		(width 0.09525)
		(layer "In2.Cu")
		(net "M_I_CPU0_SB_DQS_DP<0>")
	)
	(arc
		(start 385.113276 -276.031198)
		(mid 385.394708 -275.955443)
		(end 385.67614 -276.031198)
		(width 0.09525)
		(layer "In2.Cu")
		(net "M_I_CPU0_SB_DQS_DP<0>")
	)
	(arc
		(start 393.573762 -276.031198)
		(mid 393.614286 -276.004243)
		(end 393.650978 -275.97227)
		(width 0.09525)
		(layer "In2.Cu")
		(net "M_I_CPU0_SB_DQS_DP<0>")
	)
	(arc
		(start 381.353314 -276.031198)
		(mid 381.634746 -275.955443)
		(end 381.916178 -276.031198)
		(width 0.09525)
		(layer "In2.Cu")
		(net "M_I_CPU0_SB_DQS_DP<0>")
	)
	(arc
		(start 388.504684 -276.036024)
		(mid 388.689716 -276.081938)
		(end 388.873492 -276.031198)
		(width 0.09525)
		(layer "In2.Cu")
		(net "M_I_CPU0_SB_DQS_DP<0>")
	)
	(arc
		(start 391.708132 -276.022562)
		(mid 391.983591 -275.955177)
		(end 392.256772 -276.031198)
		(width 0.09525)
		(layer "In2.Cu")
		(net "M_I_CPU0_SB_DQS_DP<0>")
	)
	(arc
		(start 389.813292 -276.031198)
		(mid 390.094724 -275.955443)
		(end 390.376156 -276.031198)
		(width 0.09525)
		(layer "In2.Cu")
		(net "M_I_CPU0_SB_DQS_DP<0>")
	)
	(arc
		(start 387.56463 -276.036024)
		(mid 387.749662 -276.081938)
		(end 387.933438 -276.031198)
		(width 0.09525)
		(layer "In2.Cu")
		(net "M_I_CPU0_SB_DQS_DP<0>")
	)
	(arc
		(start 392.634216 -276.031198)
		(mid 392.90689 -275.955511)
		(end 393.18184 -276.022562)
		(width 0.09525)
		(layer "In2.Cu")
		(net "M_I_CPU0_SB_DQS_DP<0>")
	)
	(arc
		(start 384.73634 -276.031198)
		(mid 384.924808 -276.081875)
		(end 385.113276 -276.031198)
		(width 0.09525)
		(layer "In2.Cu")
		(net "M_I_CPU0_SB_DQS_DP<0>")
	)
	(arc
		(start 390.753346 -276.031198)
		(mid 391.034778 -275.955443)
		(end 391.31621 -276.031198)
		(width 0.09525)
		(layer "In2.Cu")
		(net "M_I_CPU0_SB_DQS_DP<0>")
	)
	(arc
		(start 380.044706 -276.036024)
		(mid 380.229738 -276.081938)
		(end 380.413514 -276.031198)
		(width 0.09525)
		(layer "In2.Cu")
		(net "M_I_CPU0_SB_DQS_DP<0>")
	)
	(arc
		(start 379.47346 -276.031198)
		(mid 379.754892 -275.955443)
		(end 380.036324 -276.031198)
		(width 0.09525)
		(layer "In2.Cu")
		(net "M_I_CPU0_SB_DQS_DP<0>")
	)
	(arc
		(start 380.413514 -276.031198)
		(mid 380.694946 -275.955443)
		(end 380.976378 -276.031198)
		(width 0.09525)
		(layer "In2.Cu")
		(net "M_I_CPU0_SB_DQS_DP<0>")
	)
	(arc
		(start 386.05333 -276.031198)
		(mid 386.334762 -275.955443)
		(end 386.616194 -276.031198)
		(width 0.09525)
		(layer "In2.Cu")
		(net "M_I_CPU0_SB_DQS_DP<0>")
	)
	(arc
		(start 378.156216 -276.031198)
		(mid 378.339991 -276.08197)
		(end 378.525024 -276.036024)
		(width 0.09525)
		(layer "In2.Cu")
		(net "M_I_CPU0_SB_DQS_DP<0>")
	)
	(arc
		(start 389.436356 -276.031198)
		(mid 389.624824 -276.081875)
		(end 389.813292 -276.031198)
		(width 0.09525)
		(layer "In2.Cu")
		(net "M_I_CPU0_SB_DQS_DP<0>")
	)
	(arc
		(start 380.976378 -276.031198)
		(mid 381.164846 -276.081875)
		(end 381.353314 -276.031198)
		(width 0.09525)
		(layer "In2.Cu")
		(net "M_I_CPU0_SB_DQS_DP<0>")
	)
	(arc
		(start 382.864614 -276.036024)
		(mid 383.049646 -276.081938)
		(end 383.233422 -276.031198)
		(width 0.09525)
		(layer "In2.Cu")
		(net "M_I_CPU0_SB_DQS_DP<0>")
	)
	(arc
		(start 383.804668 -276.036024)
		(mid 383.9897 -276.081938)
		(end 384.173476 -276.031198)
		(width 0.09525)
		(layer "In2.Cu")
		(net "M_I_CPU0_SB_DQS_DP<0>")
	)
	(arc
		(start 382.293368 -276.031198)
		(mid 382.5748 -275.955443)
		(end 382.856232 -276.031198)
		(width 0.09525)
		(layer "In2.Cu")
		(net "M_I_CPU0_SB_DQS_DP<0>")
	)
	(arc
		(start 390.376156 -276.031198)
		(mid 390.559931 -276.08197)
		(end 390.744964 -276.036024)
		(width 0.09525)
		(layer "In2.Cu")
		(net "M_I_CPU0_SB_DQS_DP<0>")
	)
	(arc
		(start 383.233422 -276.031198)
		(mid 383.514854 -275.955443)
		(end 383.796286 -276.031198)
		(width 0.09525)
		(layer "In2.Cu")
		(net "M_I_CPU0_SB_DQS_DP<0>")
	)
	(arc
		(start 384.173476 -276.031198)
		(mid 384.454908 -275.955443)
		(end 384.73634 -276.031198)
		(width 0.09525)
		(layer "In2.Cu")
		(net "M_I_CPU0_SB_DQS_DP<0>")
	)
	(arc
		(start 381.916178 -276.031198)
		(mid 382.099953 -276.08197)
		(end 382.284986 -276.036024)
		(width 0.09525)
		(layer "In2.Cu")
		(net "M_I_CPU0_SB_DQS_DP<0>")
	)
	(arc
		(start 385.67614 -276.031198)
		(mid 385.859915 -276.08197)
		(end 386.044948 -276.036024)
		(width 0.09525)
		(layer "In2.Cu")
		(net "M_I_CPU0_SB_DQS_DP<0>")
	)
	(arc
		(start 387.933438 -276.031198)
		(mid 388.21487 -275.955443)
		(end 388.496302 -276.031198)
		(width 0.09525)
		(layer "In2.Cu")
		(net "M_I_CPU0_SB_DQS_DP<0>")
	)
	(arc
		(start 386.993384 -276.031198)
		(mid 387.274816 -275.955443)
		(end 387.556248 -276.031198)
		(width 0.09525)
		(layer "In2.Cu")
		(net "M_I_CPU0_SB_DQS_DP<0>")
	)
	(arc
		(start 388.873492 -276.031198)
		(mid 389.154924 -275.955443)
		(end 389.436356 -276.031198)
		(width 0.09525)
		(layer "In2.Cu")
		(net "M_I_CPU0_SB_DQS_DP<0>")
	)
	(arc
		(start 377.659646 -275.998178)
		(mid 377.911787 -275.956608)
		(end 378.156216 -276.031198)
		(width 0.09525)
		(layer "In2.Cu")
		(net "M_I_CPU0_SB_DQS_DP<0>")
	)
	(arc
		(start 393.21105 -276.03958)
		(mid 393.393482 -276.08202)
		(end 393.573762 -276.031198)
		(width 0.09525)
		(layer "In2.Cu")
		(net "M_I_CPU0_SB_DQS_DP<0>")
	)
	(segment
		(start 377.407932 -271.39011)
		(end 377.874784 -271.656048)
		(width 0.12954)
		(layer "F.Cu")
		(net "M_I_CPU0_SB_DQS_DN<9>")
	)
	(segment
		(start 395.62024 -269.55496)
		(end 395.643862 -269.55496)
		(width 0.09525)
		(layer "In2.Cu")
		(net "M_I_CPU0_SB_DQS_DN<9>")
	)
	(segment
		(start 413.455104 -276.26945)
		(end 414.047432 -276.26945)
		(width 0.16002)
		(layer "In2.Cu")
		(net "M_I_CPU0_SB_DQS_DN<9>")
	)
	(segment
		(start 414.047432 -276.26945)
		(end 414.888172 -275.42871)
		(width 0.16002)
		(layer "In2.Cu")
		(net "M_I_CPU0_SB_DQS_DN<9>")
	)
	(segment
		(start 411.078934 -275.686266)
		(end 412.87192 -275.686266)
		(width 0.16002)
		(layer "In2.Cu")
		(net "M_I_CPU0_SB_DQS_DN<9>")
	)
	(segment
		(start 393.936728 -270.396716)
		(end 394.17498 -269.821406)
		(width 0.09525)
		(layer "In2.Cu")
		(net "M_I_CPU0_SB_DQS_DN<9>")
	)
	(segment
		(start 428.568358 -276.29485)
		(end 429.216566 -276.29485)
		(width 0.16002)
		(layer "In2.Cu")
		(net "M_I_CPU0_SB_DQS_DN<9>")
	)
	(segment
		(start 404.444962 -269.55496)
		(end 410.220668 -275.330666)
		(width 0.16002)
		(layer "In2.Cu")
		(net "M_I_CPU0_SB_DQS_DN<9>")
	)
	(segment
		(start 395.204696 -269.37716)
		(end 395.323568 -269.496032)
		(width 0.09525)
		(layer "In2.Cu")
		(net "M_I_CPU0_SB_DQS_DN<9>")
	)
	(segment
		(start 431.28311 -276.11197)
		(end 431.55616 -276.38502)
		(width 0.16002)
		(layer "In2.Cu")
		(net "M_I_CPU0_SB_DQS_DN<9>")
	)
	(segment
		(start 394.510006 -269.48638)
		(end 394.713968 -269.48638)
		(width 0.09525)
		(layer "In2.Cu")
		(net "M_I_CPU0_SB_DQS_DN<9>")
	)
	(segment
		(start 394.713968 -269.48638)
		(end 394.823188 -269.37716)
		(width 0.09525)
		(layer "In2.Cu")
		(net "M_I_CPU0_SB_DQS_DN<9>")
	)
	(segment
		(start 418.282628 -275.686266)
		(end 420.415974 -275.686266)
		(width 0.16002)
		(layer "In2.Cu")
		(net "M_I_CPU0_SB_DQS_DN<9>")
	)
	(segment
		(start 394.17498 -269.821406)
		(end 394.510006 -269.48638)
		(width 0.09525)
		(layer "In2.Cu")
		(net "M_I_CPU0_SB_DQS_DN<9>")
	)
	(segment
		(start 377.72086 -271.390618)
		(end 377.744228 -271.30375)
		(width 0.09525)
		(layer "In2.Cu")
		(net "M_I_CPU0_SB_DQS_DN<9>")
	)
	(segment
		(start 394.823188 -269.37716)
		(end 395.204696 -269.37716)
		(width 0.09525)
		(layer "In2.Cu")
		(net "M_I_CPU0_SB_DQS_DN<9>")
	)
	(segment
		(start 415.729928 -275.112226)
		(end 417.708588 -275.112226)
		(width 0.16002)
		(layer "In2.Cu")
		(net "M_I_CPU0_SB_DQS_DN<9>")
	)
	(segment
		(start 429.879506 -276.11197)
		(end 429.996346 -276.22881)
		(width 0.16002)
		(layer "In2.Cu")
		(net "M_I_CPU0_SB_DQS_DN<9>")
	)
	(segment
		(start 429.216566 -276.29485)
		(end 429.399446 -276.11197)
		(width 0.16002)
		(layer "In2.Cu")
		(net "M_I_CPU0_SB_DQS_DN<9>")
	)
	(segment
		(start 427.959774 -275.686266)
		(end 428.568358 -276.29485)
		(width 0.16002)
		(layer "In2.Cu")
		(net "M_I_CPU0_SB_DQS_DN<9>")
	)
	(segment
		(start 430.476406 -276.22881)
		(end 430.593246 -276.11197)
		(width 0.16002)
		(layer "In2.Cu")
		(net "M_I_CPU0_SB_DQS_DN<9>")
	)
	(segment
		(start 421.591486 -276.26945)
		(end 422.432226 -275.42871)
		(width 0.16002)
		(layer "In2.Cu")
		(net "M_I_CPU0_SB_DQS_DN<9>")
	)
	(segment
		(start 395.643862 -269.55496)
		(end 404.444962 -269.55496)
		(width 0.16002)
		(layer "In2.Cu")
		(net "M_I_CPU0_SB_DQS_DN<9>")
	)
	(segment
		(start 393.936728 -270.891762)
		(end 393.936728 -270.396716)
		(width 0.09525)
		(layer "In2.Cu")
		(net "M_I_CPU0_SB_DQS_DN<9>")
	)
	(segment
		(start 380.875032 -271.326102)
		(end 380.883414 -271.330928)
		(width 0.09525)
		(layer "In2.Cu")
		(net "M_I_CPU0_SB_DQS_DN<9>")
	)
	(segment
		(start 377.874784 -271.656048)
		(end 377.72086 -271.390618)
		(width 0.09525)
		(layer "In2.Cu")
		(net "M_I_CPU0_SB_DQS_DN<9>")
	)
	(segment
		(start 381.446278 -271.330928)
		(end 381.45466 -271.326102)
		(width 0.09525)
		(layer "In2.Cu")
		(net "M_I_CPU0_SB_DQS_DN<9>")
	)
	(segment
		(start 422.432226 -275.42871)
		(end 422.957498 -275.42871)
		(width 0.16002)
		(layer "In2.Cu")
		(net "M_I_CPU0_SB_DQS_DN<9>")
	)
	(segment
		(start 389.33501 -271.326102)
		(end 389.343392 -271.330928)
		(width 0.09525)
		(layer "In2.Cu")
		(net "M_I_CPU0_SB_DQS_DN<9>")
	)
	(segment
		(start 415.413444 -275.42871)
		(end 415.729928 -275.112226)
		(width 0.16002)
		(layer "In2.Cu")
		(net "M_I_CPU0_SB_DQS_DN<9>")
	)
	(segment
		(start 429.399446 -276.11197)
		(end 429.879506 -276.11197)
		(width 0.16002)
		(layer "In2.Cu")
		(net "M_I_CPU0_SB_DQS_DN<9>")
	)
	(segment
		(start 423.273982 -275.112226)
		(end 425.300394 -275.112226)
		(width 0.16002)
		(layer "In2.Cu")
		(net "M_I_CPU0_SB_DQS_DN<9>")
	)
	(segment
		(start 420.999158 -276.26945)
		(end 421.591486 -276.26945)
		(width 0.16002)
		(layer "In2.Cu")
		(net "M_I_CPU0_SB_DQS_DN<9>")
	)
	(segment
		(start 430.593246 -276.11197)
		(end 431.28311 -276.11197)
		(width 0.16002)
		(layer "In2.Cu")
		(net "M_I_CPU0_SB_DQS_DN<9>")
	)
	(segment
		(start 412.87192 -275.686266)
		(end 413.455104 -276.26945)
		(width 0.16002)
		(layer "In2.Cu")
		(net "M_I_CPU0_SB_DQS_DN<9>")
	)
	(segment
		(start 420.415974 -275.686266)
		(end 420.999158 -276.26945)
		(width 0.16002)
		(layer "In2.Cu")
		(net "M_I_CPU0_SB_DQS_DN<9>")
	)
	(segment
		(start 384.634994 -271.326102)
		(end 384.643376 -271.330928)
		(width 0.09525)
		(layer "In2.Cu")
		(net "M_I_CPU0_SB_DQS_DN<9>")
	)
	(segment
		(start 422.957498 -275.42871)
		(end 423.273982 -275.112226)
		(width 0.16002)
		(layer "In2.Cu")
		(net "M_I_CPU0_SB_DQS_DN<9>")
	)
	(segment
		(start 425.300394 -275.112226)
		(end 426.686472 -275.686266)
		(width 0.16002)
		(layer "In2.Cu")
		(net "M_I_CPU0_SB_DQS_DN<9>")
	)
	(segment
		(start 383.69494 -271.326102)
		(end 383.703322 -271.330928)
		(width 0.09525)
		(layer "In2.Cu")
		(net "M_I_CPU0_SB_DQS_DN<9>")
	)
	(segment
		(start 386.146294 -271.330928)
		(end 386.154676 -271.326102)
		(width 0.09525)
		(layer "In2.Cu")
		(net "M_I_CPU0_SB_DQS_DN<9>")
	)
	(segment
		(start 417.708588 -275.112226)
		(end 418.282628 -275.686266)
		(width 0.16002)
		(layer "In2.Cu")
		(net "M_I_CPU0_SB_DQS_DN<9>")
	)
	(segment
		(start 414.888172 -275.42871)
		(end 415.413444 -275.42871)
		(width 0.16002)
		(layer "In2.Cu")
		(net "M_I_CPU0_SB_DQS_DN<9>")
	)
	(segment
		(start 379.934978 -271.326102)
		(end 379.94336 -271.330928)
		(width 0.09525)
		(layer "In2.Cu")
		(net "M_I_CPU0_SB_DQS_DN<9>")
	)
	(segment
		(start 393.665964 -271.331182)
		(end 393.66571 -271.330674)
		(width 0.09525)
		(layer "In2.Cu")
		(net "M_I_CPU0_SB_DQS_DN<9>")
	)
	(segment
		(start 429.996346 -276.22881)
		(end 430.476406 -276.22881)
		(width 0.16002)
		(layer "In2.Cu")
		(net "M_I_CPU0_SB_DQS_DN<9>")
	)
	(segment
		(start 388.394956 -271.326102)
		(end 388.403338 -271.330928)
		(width 0.09525)
		(layer "In2.Cu")
		(net "M_I_CPU0_SB_DQS_DN<9>")
	)
	(segment
		(start 410.220668 -275.330666)
		(end 411.078934 -275.686266)
		(width 0.16002)
		(layer "In2.Cu")
		(net "M_I_CPU0_SB_DQS_DN<9>")
	)
	(segment
		(start 389.906256 -271.330928)
		(end 389.914638 -271.326102)
		(width 0.09525)
		(layer "In2.Cu")
		(net "M_I_CPU0_SB_DQS_DN<9>")
	)
	(segment
		(start 395.561312 -269.496032)
		(end 395.62024 -269.55496)
		(width 0.09525)
		(layer "In2.Cu")
		(net "M_I_CPU0_SB_DQS_DN<9>")
	)
	(segment
		(start 426.686472 -275.686266)
		(end 427.959774 -275.686266)
		(width 0.16002)
		(layer "In2.Cu")
		(net "M_I_CPU0_SB_DQS_DN<9>")
	)
	(segment
		(start 395.323568 -269.496032)
		(end 395.561312 -269.496032)
		(width 0.09525)
		(layer "In2.Cu")
		(net "M_I_CPU0_SB_DQS_DN<9>")
	)
	(segment
		(start 385.20624 -271.330928)
		(end 385.214622 -271.326102)
		(width 0.09525)
		(layer "In2.Cu")
		(net "M_I_CPU0_SB_DQS_DN<9>")
	)
	(arc
		(start 386.523484 -271.330928)
		(mid 386.804916 -271.406683)
		(end 387.086348 -271.330928)
		(width 0.09525)
		(layer "In2.Cu")
		(net "M_I_CPU0_SB_DQS_DN<9>")
	)
	(arc
		(start 383.326132 -271.330928)
		(mid 383.509907 -271.280156)
		(end 383.69494 -271.326102)
		(width 0.09525)
		(layer "In2.Cu")
		(net "M_I_CPU0_SB_DQS_DN<9>")
	)
	(arc
		(start 392.163554 -271.330928)
		(mid 392.444986 -271.406683)
		(end 392.726418 -271.330928)
		(width 0.09525)
		(layer "In2.Cu")
		(net "M_I_CPU0_SB_DQS_DN<9>")
	)
	(arc
		(start 384.266186 -271.330928)
		(mid 384.449961 -271.280156)
		(end 384.634994 -271.326102)
		(width 0.09525)
		(layer "In2.Cu")
		(net "M_I_CPU0_SB_DQS_DN<9>")
	)
	(arc
		(start 382.763268 -271.330928)
		(mid 383.0447 -271.406683)
		(end 383.326132 -271.330928)
		(width 0.09525)
		(layer "In2.Cu")
		(net "M_I_CPU0_SB_DQS_DN<9>")
	)
	(arc
		(start 381.823468 -271.330928)
		(mid 382.1049 -271.406683)
		(end 382.386332 -271.330928)
		(width 0.09525)
		(layer "In2.Cu")
		(net "M_I_CPU0_SB_DQS_DN<9>")
	)
	(arc
		(start 381.45466 -271.326102)
		(mid 381.639692 -271.280188)
		(end 381.823468 -271.330928)
		(width 0.09525)
		(layer "In2.Cu")
		(net "M_I_CPU0_SB_DQS_DN<9>")
	)
	(arc
		(start 378.62637 -271.330928)
		(mid 378.814838 -271.280251)
		(end 379.003306 -271.330928)
		(width 0.09525)
		(layer "In2.Cu")
		(net "M_I_CPU0_SB_DQS_DN<9>")
	)
	(arc
		(start 391.78611 -271.330928)
		(mid 391.974832 -271.280124)
		(end 392.163554 -271.330928)
		(width 0.09525)
		(layer "In2.Cu")
		(net "M_I_CPU0_SB_DQS_DN<9>")
	)
	(arc
		(start 387.463284 -271.330928)
		(mid 387.744716 -271.406683)
		(end 388.026148 -271.330928)
		(width 0.09525)
		(layer "In2.Cu")
		(net "M_I_CPU0_SB_DQS_DN<9>")
	)
	(arc
		(start 393.103354 -271.330928)
		(mid 393.384612 -271.406683)
		(end 393.665964 -271.331182)
		(width 0.09525)
		(layer "In2.Cu")
		(net "M_I_CPU0_SB_DQS_DN<9>")
	)
	(arc
		(start 384.643376 -271.330928)
		(mid 384.924808 -271.406683)
		(end 385.20624 -271.330928)
		(width 0.09525)
		(layer "In2.Cu")
		(net "M_I_CPU0_SB_DQS_DN<9>")
	)
	(arc
		(start 388.026148 -271.330928)
		(mid 388.209923 -271.280156)
		(end 388.394956 -271.326102)
		(width 0.09525)
		(layer "In2.Cu")
		(net "M_I_CPU0_SB_DQS_DN<9>")
	)
	(arc
		(start 379.003306 -271.330928)
		(mid 379.284738 -271.406683)
		(end 379.56617 -271.330928)
		(width 0.09525)
		(layer "In2.Cu")
		(net "M_I_CPU0_SB_DQS_DN<9>")
	)
	(arc
		(start 385.214622 -271.326102)
		(mid 385.399654 -271.280188)
		(end 385.58343 -271.330928)
		(width 0.09525)
		(layer "In2.Cu")
		(net "M_I_CPU0_SB_DQS_DN<9>")
	)
	(arc
		(start 379.56617 -271.330928)
		(mid 379.749945 -271.280156)
		(end 379.934978 -271.326102)
		(width 0.09525)
		(layer "In2.Cu")
		(net "M_I_CPU0_SB_DQS_DN<9>")
	)
	(arc
		(start 380.883414 -271.330928)
		(mid 381.164846 -271.406683)
		(end 381.446278 -271.330928)
		(width 0.09525)
		(layer "In2.Cu")
		(net "M_I_CPU0_SB_DQS_DN<9>")
	)
	(arc
		(start 382.386332 -271.330928)
		(mid 382.5748 -271.280251)
		(end 382.763268 -271.330928)
		(width 0.09525)
		(layer "In2.Cu")
		(net "M_I_CPU0_SB_DQS_DN<9>")
	)
	(arc
		(start 386.154676 -271.326102)
		(mid 386.339708 -271.280188)
		(end 386.523484 -271.330928)
		(width 0.09525)
		(layer "In2.Cu")
		(net "M_I_CPU0_SB_DQS_DN<9>")
	)
	(arc
		(start 389.914638 -271.326102)
		(mid 390.09967 -271.280188)
		(end 390.283446 -271.330928)
		(width 0.09525)
		(layer "In2.Cu")
		(net "M_I_CPU0_SB_DQS_DN<9>")
	)
	(arc
		(start 388.966202 -271.330928)
		(mid 389.149977 -271.280156)
		(end 389.33501 -271.326102)
		(width 0.09525)
		(layer "In2.Cu")
		(net "M_I_CPU0_SB_DQS_DN<9>")
	)
	(arc
		(start 380.506224 -271.330928)
		(mid 380.689999 -271.280156)
		(end 380.875032 -271.326102)
		(width 0.09525)
		(layer "In2.Cu")
		(net "M_I_CPU0_SB_DQS_DN<9>")
	)
	(arc
		(start 385.58343 -271.330928)
		(mid 385.864862 -271.406683)
		(end 386.146294 -271.330928)
		(width 0.09525)
		(layer "In2.Cu")
		(net "M_I_CPU0_SB_DQS_DN<9>")
	)
	(arc
		(start 383.703322 -271.330928)
		(mid 383.984754 -271.406683)
		(end 384.266186 -271.330928)
		(width 0.09525)
		(layer "In2.Cu")
		(net "M_I_CPU0_SB_DQS_DN<9>")
	)
	(arc
		(start 378.063506 -271.330928)
		(mid 378.344938 -271.406683)
		(end 378.62637 -271.330928)
		(width 0.09525)
		(layer "In2.Cu")
		(net "M_I_CPU0_SB_DQS_DN<9>")
	)
	(arc
		(start 379.94336 -271.330928)
		(mid 380.224792 -271.406683)
		(end 380.506224 -271.330928)
		(width 0.09525)
		(layer "In2.Cu")
		(net "M_I_CPU0_SB_DQS_DN<9>")
	)
	(arc
		(start 388.403338 -271.330928)
		(mid 388.68477 -271.406683)
		(end 388.966202 -271.330928)
		(width 0.09525)
		(layer "In2.Cu")
		(net "M_I_CPU0_SB_DQS_DN<9>")
	)
	(arc
		(start 390.283446 -271.330928)
		(mid 390.564878 -271.406683)
		(end 390.84631 -271.330928)
		(width 0.09525)
		(layer "In2.Cu")
		(net "M_I_CPU0_SB_DQS_DN<9>")
	)
	(arc
		(start 391.223246 -271.330928)
		(mid 391.504678 -271.406683)
		(end 391.78611 -271.330928)
		(width 0.09525)
		(layer "In2.Cu")
		(net "M_I_CPU0_SB_DQS_DN<9>")
	)
	(arc
		(start 387.086348 -271.330928)
		(mid 387.274816 -271.280251)
		(end 387.463284 -271.330928)
		(width 0.09525)
		(layer "In2.Cu")
		(net "M_I_CPU0_SB_DQS_DN<9>")
	)
	(arc
		(start 389.343392 -271.330928)
		(mid 389.624824 -271.406683)
		(end 389.906256 -271.330928)
		(width 0.09525)
		(layer "In2.Cu")
		(net "M_I_CPU0_SB_DQS_DN<9>")
	)
	(arc
		(start 392.726418 -271.330928)
		(mid 392.914886 -271.280251)
		(end 393.103354 -271.330928)
		(width 0.09525)
		(layer "In2.Cu")
		(net "M_I_CPU0_SB_DQS_DN<9>")
	)
	(arc
		(start 390.84631 -271.330928)
		(mid 391.034778 -271.280251)
		(end 391.223246 -271.330928)
		(width 0.09525)
		(layer "In2.Cu")
		(net "M_I_CPU0_SB_DQS_DN<9>")
	)
	(arc
		(start 393.66571 -271.330674)
		(mid 393.856416 -271.145284)
		(end 393.936728 -270.891762)
		(width 0.09525)
		(layer "In2.Cu")
		(net "M_I_CPU0_SB_DQS_DN<9>")
	)
	(arc
		(start 377.744228 -271.30375)
		(mid 377.90691 -271.281618)
		(end 378.063506 -271.330928)
		(width 0.09525)
		(layer "In2.Cu")
		(net "M_I_CPU0_SB_DQS_DN<9>")
	)
	(segment
		(start 375.528078 -290.83)
		(end 375.99493 -291.095938)
		(width 0.12954)
		(layer "F.Cu")
		(net "M_I_CPU0_SB_DQS_DN<8>")
	)
	(segment
		(start 424.789854 -314.48375)
		(end 425.214034 -314.05957)
		(width 0.16002)
		(layer "In2.Cu")
		(net "M_I_CPU0_SB_DQS_DN<8>")
	)
	(segment
		(start 394.897102 -299.781468)
		(end 395.582394 -299.781468)
		(width 0.16002)
		(layer "In2.Cu")
		(net "M_I_CPU0_SB_DQS_DN<8>")
	)
	(segment
		(start 380.875032 -291.425884)
		(end 380.883414 -291.421058)
		(width 0.09525)
		(layer "In2.Cu")
		(net "M_I_CPU0_SB_DQS_DN<8>")
	)
	(segment
		(start 393.196318 -295.471088)
		(end 393.216638 -295.483534)
		(width 0.09525)
		(layer "In2.Cu")
		(net "M_I_CPU0_SB_DQS_DN<8>")
	)
	(segment
		(start 397.389096 -302.273462)
		(end 397.644366 -302.528732)
		(width 0.16002)
		(layer "In2.Cu")
		(net "M_I_CPU0_SB_DQS_DN<8>")
	)
	(segment
		(start 425.694094 -314.05957)
		(end 425.810934 -313.94273)
		(width 0.16002)
		(layer "In2.Cu")
		(net "M_I_CPU0_SB_DQS_DN<8>")
	)
	(segment
		(start 389.906256 -291.421058)
		(end 389.914638 -291.425884)
		(width 0.09525)
		(layer "In2.Cu")
		(net "M_I_CPU0_SB_DQS_DN<8>")
	)
	(segment
		(start 421.042338 -314.693046)
		(end 421.479218 -314.693046)
		(width 0.16002)
		(layer "In2.Cu")
		(net "M_I_CPU0_SB_DQS_DN<8>")
	)
	(segment
		(start 393.701524 -297.129962)
		(end 394.730986 -299.615352)
		(width 0.16002)
		(layer "In2.Cu")
		(net "M_I_CPU0_SB_DQS_DN<8>")
	)
	(segment
		(start 413.498284 -314.693046)
		(end 413.935164 -314.693046)
		(width 0.16002)
		(layer "In2.Cu")
		(net "M_I_CPU0_SB_DQS_DN<8>")
	)
	(segment
		(start 400.39163 -305.275996)
		(end 401.076922 -305.275996)
		(width 0.16002)
		(layer "In2.Cu")
		(net "M_I_CPU0_SB_DQS_DN<8>")
	)
	(segment
		(start 383.69494 -291.425884)
		(end 383.703322 -291.421058)
		(width 0.09525)
		(layer "In2.Cu")
		(net "M_I_CPU0_SB_DQS_DN<8>")
	)
	(segment
		(start 422.271698 -313.900566)
		(end 422.935146 -313.900566)
		(width 0.16002)
		(layer "In2.Cu")
		(net "M_I_CPU0_SB_DQS_DN<8>")
	)
	(segment
		(start 396.015464 -300.89983)
		(end 396.270734 -301.1551)
		(width 0.16002)
		(layer "In2.Cu")
		(net "M_I_CPU0_SB_DQS_DN<8>")
	)
	(segment
		(start 386.146294 -291.421058)
		(end 386.154676 -291.425884)
		(width 0.09525)
		(layer "In2.Cu")
		(net "M_I_CPU0_SB_DQS_DN<8>")
	)
	(segment
		(start 398.329658 -302.528732)
		(end 398.762728 -302.961802)
		(width 0.16002)
		(layer "In2.Cu")
		(net "M_I_CPU0_SB_DQS_DN<8>")
	)
	(segment
		(start 391.78611 -293.04107)
		(end 391.82421 -293.063168)
		(width 0.09525)
		(layer "In2.Cu")
		(net "M_I_CPU0_SB_DQS_DN<8>")
	)
	(segment
		(start 392.224514 -293.832788)
		(end 392.25601 -293.851076)
		(width 0.09525)
		(layer "In2.Cu")
		(net "M_I_CPU0_SB_DQS_DN<8>")
	)
	(segment
		(start 393.642342 -296.323766)
		(end 393.701524 -296.382948)
		(width 0.09525)
		(layer "In2.Cu")
		(net "M_I_CPU0_SB_DQS_DN<8>")
	)
	(segment
		(start 379.934978 -291.425884)
		(end 379.94336 -291.421058)
		(width 0.09525)
		(layer "In2.Cu")
		(net "M_I_CPU0_SB_DQS_DN<8>")
	)
	(segment
		(start 396.956026 -301.1551)
		(end 397.389096 -301.58817)
		(width 0.16002)
		(layer "In2.Cu")
		(net "M_I_CPU0_SB_DQS_DN<8>")
	)
	(segment
		(start 418.437822 -314.48375)
		(end 419.012116 -315.058044)
		(width 0.16002)
		(layer "In2.Cu")
		(net "M_I_CPU0_SB_DQS_DN<8>")
	)
	(segment
		(start 388.394956 -291.425884)
		(end 388.395972 -291.425376)
		(width 0.09525)
		(layer "In2.Cu")
		(net "M_I_CPU0_SB_DQS_DN<8>")
	)
	(segment
		(start 377.686316 -291.421058)
		(end 377.694698 -291.425884)
		(width 0.09525)
		(layer "In2.Cu")
		(net "M_I_CPU0_SB_DQS_DN<8>")
	)
	(segment
		(start 397.389096 -301.58817)
		(end 397.389096 -302.273462)
		(width 0.16002)
		(layer "In2.Cu")
		(net "M_I_CPU0_SB_DQS_DN<8>")
	)
	(segment
		(start 415.391092 -313.900566)
		(end 415.974276 -314.48375)
		(width 0.16002)
		(layer "In2.Cu")
		(net "M_I_CPU0_SB_DQS_DN<8>")
	)
	(segment
		(start 394.730986 -299.615352)
		(end 394.897102 -299.781468)
		(width 0.16002)
		(layer "In2.Cu")
		(net "M_I_CPU0_SB_DQS_DN<8>")
	)
	(segment
		(start 393.701524 -296.40657)
		(end 393.701524 -297.129962)
		(width 0.16002)
		(layer "In2.Cu")
		(net "M_I_CPU0_SB_DQS_DN<8>")
	)
	(segment
		(start 423.51833 -314.48375)
		(end 424.789854 -314.48375)
		(width 0.16002)
		(layer "In2.Cu")
		(net "M_I_CPU0_SB_DQS_DN<8>")
	)
	(segment
		(start 398.762728 -302.961802)
		(end 398.762728 -303.647094)
		(width 0.16002)
		(layer "In2.Cu")
		(net "M_I_CPU0_SB_DQS_DN<8>")
	)
	(segment
		(start 392.693398 -294.642286)
		(end 392.72591 -294.661082)
		(width 0.09525)
		(layer "In2.Cu")
		(net "M_I_CPU0_SB_DQS_DN<8>")
	)
	(segment
		(start 385.20624 -291.421058)
		(end 385.214622 -291.425884)
		(width 0.09525)
		(layer "In2.Cu")
		(net "M_I_CPU0_SB_DQS_DN<8>")
	)
	(segment
		(start 420.67734 -315.058044)
		(end 421.042338 -314.693046)
		(width 0.16002)
		(layer "In2.Cu")
		(net "M_I_CPU0_SB_DQS_DN<8>")
	)
	(segment
		(start 389.33501 -291.425884)
		(end 389.343392 -291.421058)
		(width 0.09525)
		(layer "In2.Cu")
		(net "M_I_CPU0_SB_DQS_DN<8>")
	)
	(segment
		(start 427.181518 -314.05957)
		(end 427.456092 -313.784996)
		(width 0.16002)
		(layer "In2.Cu")
		(net "M_I_CPU0_SB_DQS_DN<8>")
	)
	(segment
		(start 393.642342 -295.909238)
		(end 393.642342 -296.323766)
		(width 0.09525)
		(layer "In2.Cu")
		(net "M_I_CPU0_SB_DQS_DN<8>")
	)
	(segment
		(start 400.13636 -304.335434)
		(end 400.13636 -305.020726)
		(width 0.16002)
		(layer "In2.Cu")
		(net "M_I_CPU0_SB_DQS_DN<8>")
	)
	(segment
		(start 398.762728 -303.647094)
		(end 399.017998 -303.902364)
		(width 0.16002)
		(layer "In2.Cu")
		(net "M_I_CPU0_SB_DQS_DN<8>")
	)
	(segment
		(start 410.173424 -315.05779)
		(end 413.13354 -315.05779)
		(width 0.16002)
		(layer "In2.Cu")
		(net "M_I_CPU0_SB_DQS_DN<8>")
	)
	(segment
		(start 393.216638 -295.483534)
		(end 393.642342 -295.909238)
		(width 0.09525)
		(layer "In2.Cu")
		(net "M_I_CPU0_SB_DQS_DN<8>")
	)
	(segment
		(start 395.582394 -299.781468)
		(end 396.015464 -300.214538)
		(width 0.16002)
		(layer "In2.Cu")
		(net "M_I_CPU0_SB_DQS_DN<8>")
	)
	(segment
		(start 393.701524 -296.382948)
		(end 393.701524 -296.40657)
		(width 0.09525)
		(layer "In2.Cu")
		(net "M_I_CPU0_SB_DQS_DN<8>")
	)
	(segment
		(start 381.446278 -291.421058)
		(end 381.45466 -291.425884)
		(width 0.09525)
		(layer "In2.Cu")
		(net "M_I_CPU0_SB_DQS_DN<8>")
	)
	(segment
		(start 376.746262 -291.421058)
		(end 376.754644 -291.425884)
		(width 0.09525)
		(layer "In2.Cu")
		(net "M_I_CPU0_SB_DQS_DN<8>")
	)
	(segment
		(start 392.72591 -294.661082)
		(end 392.76401 -294.68318)
		(width 0.09525)
		(layer "In2.Cu")
		(net "M_I_CPU0_SB_DQS_DN<8>")
	)
	(segment
		(start 391.754614 -293.022782)
		(end 391.78611 -293.04107)
		(width 0.09525)
		(layer "In2.Cu")
		(net "M_I_CPU0_SB_DQS_DN<8>")
	)
	(segment
		(start 392.25601 -293.851076)
		(end 392.291062 -293.87165)
		(width 0.09525)
		(layer "In2.Cu")
		(net "M_I_CPU0_SB_DQS_DN<8>")
	)
	(segment
		(start 399.017998 -303.902364)
		(end 399.70329 -303.902364)
		(width 0.16002)
		(layer "In2.Cu")
		(net "M_I_CPU0_SB_DQS_DN<8>")
	)
	(segment
		(start 401.509992 -305.709066)
		(end 401.509992 -306.394358)
		(width 0.16002)
		(layer "In2.Cu")
		(net "M_I_CPU0_SB_DQS_DN<8>")
	)
	(segment
		(start 401.076922 -305.275996)
		(end 401.509992 -305.709066)
		(width 0.16002)
		(layer "In2.Cu")
		(net "M_I_CPU0_SB_DQS_DN<8>")
	)
	(segment
		(start 426.290994 -313.94273)
		(end 426.407834 -314.05957)
		(width 0.16002)
		(layer "In2.Cu")
		(net "M_I_CPU0_SB_DQS_DN<8>")
	)
	(segment
		(start 396.270734 -301.1551)
		(end 396.956026 -301.1551)
		(width 0.16002)
		(layer "In2.Cu")
		(net "M_I_CPU0_SB_DQS_DN<8>")
	)
	(segment
		(start 415.974276 -314.48375)
		(end 418.437822 -314.48375)
		(width 0.16002)
		(layer "In2.Cu")
		(net "M_I_CPU0_SB_DQS_DN<8>")
	)
	(segment
		(start 397.644366 -302.528732)
		(end 398.329658 -302.528732)
		(width 0.16002)
		(layer "In2.Cu")
		(net "M_I_CPU0_SB_DQS_DN<8>")
	)
	(segment
		(start 425.214034 -314.05957)
		(end 425.694094 -314.05957)
		(width 0.16002)
		(layer "In2.Cu")
		(net "M_I_CPU0_SB_DQS_DN<8>")
	)
	(segment
		(start 425.810934 -313.94273)
		(end 426.290994 -313.94273)
		(width 0.16002)
		(layer "In2.Cu")
		(net "M_I_CPU0_SB_DQS_DN<8>")
	)
	(segment
		(start 413.13354 -315.05779)
		(end 413.498284 -314.693046)
		(width 0.16002)
		(layer "In2.Cu")
		(net "M_I_CPU0_SB_DQS_DN<8>")
	)
	(segment
		(start 426.407834 -314.05957)
		(end 427.181518 -314.05957)
		(width 0.16002)
		(layer "In2.Cu")
		(net "M_I_CPU0_SB_DQS_DN<8>")
	)
	(segment
		(start 400.13636 -305.020726)
		(end 400.39163 -305.275996)
		(width 0.16002)
		(layer "In2.Cu")
		(net "M_I_CPU0_SB_DQS_DN<8>")
	)
	(segment
		(start 401.509992 -306.394358)
		(end 410.173424 -315.05779)
		(width 0.16002)
		(layer "In2.Cu")
		(net "M_I_CPU0_SB_DQS_DN<8>")
	)
	(segment
		(start 388.395972 -291.425376)
		(end 388.403338 -291.421058)
		(width 0.09525)
		(layer "In2.Cu")
		(net "M_I_CPU0_SB_DQS_DN<8>")
	)
	(segment
		(start 414.727644 -313.900566)
		(end 415.391092 -313.900566)
		(width 0.16002)
		(layer "In2.Cu")
		(net "M_I_CPU0_SB_DQS_DN<8>")
	)
	(segment
		(start 375.99493 -291.095938)
		(end 376.148854 -291.361368)
		(width 0.09525)
		(layer "In2.Cu")
		(net "M_I_CPU0_SB_DQS_DN<8>")
	)
	(segment
		(start 393.16152 -295.451022)
		(end 393.196318 -295.471088)
		(width 0.09525)
		(layer "In2.Cu")
		(net "M_I_CPU0_SB_DQS_DN<8>")
	)
	(segment
		(start 422.935146 -313.900566)
		(end 423.51833 -314.48375)
		(width 0.16002)
		(layer "In2.Cu")
		(net "M_I_CPU0_SB_DQS_DN<8>")
	)
	(segment
		(start 421.479218 -314.693046)
		(end 422.271698 -313.900566)
		(width 0.16002)
		(layer "In2.Cu")
		(net "M_I_CPU0_SB_DQS_DN<8>")
	)
	(segment
		(start 390.84631 -291.421058)
		(end 390.881362 -291.441632)
		(width 0.09525)
		(layer "In2.Cu")
		(net "M_I_CPU0_SB_DQS_DN<8>")
	)
	(segment
		(start 391.283698 -292.212268)
		(end 391.31621 -292.231064)
		(width 0.09525)
		(layer "In2.Cu")
		(net "M_I_CPU0_SB_DQS_DN<8>")
	)
	(segment
		(start 413.935164 -314.693046)
		(end 414.727644 -313.900566)
		(width 0.16002)
		(layer "In2.Cu")
		(net "M_I_CPU0_SB_DQS_DN<8>")
	)
	(segment
		(start 376.148854 -291.361368)
		(end 376.249692 -291.388038)
		(width 0.09525)
		(layer "In2.Cu")
		(net "M_I_CPU0_SB_DQS_DN<8>")
	)
	(segment
		(start 384.634994 -291.425884)
		(end 384.643376 -291.421058)
		(width 0.09525)
		(layer "In2.Cu")
		(net "M_I_CPU0_SB_DQS_DN<8>")
	)
	(segment
		(start 399.70329 -303.902364)
		(end 400.13636 -304.335434)
		(width 0.16002)
		(layer "In2.Cu")
		(net "M_I_CPU0_SB_DQS_DN<8>")
	)
	(segment
		(start 396.015464 -300.214538)
		(end 396.015464 -300.89983)
		(width 0.16002)
		(layer "In2.Cu")
		(net "M_I_CPU0_SB_DQS_DN<8>")
	)
	(segment
		(start 419.012116 -315.058044)
		(end 420.67734 -315.058044)
		(width 0.16002)
		(layer "In2.Cu")
		(net "M_I_CPU0_SB_DQS_DN<8>")
	)
	(segment
		(start 391.31621 -292.231064)
		(end 391.35431 -292.253162)
		(width 0.09525)
		(layer "In2.Cu")
		(net "M_I_CPU0_SB_DQS_DN<8>")
	)
	(arc
		(start 378.62637 -291.421058)
		(mid 378.814838 -291.471735)
		(end 379.003306 -291.421058)
		(width 0.09525)
		(layer "In2.Cu")
		(net "M_I_CPU0_SB_DQS_DN<8>")
	)
	(arc
		(start 391.597134 -292.71595)
		(mid 391.638799 -292.888397)
		(end 391.754614 -293.022782)
		(width 0.09525)
		(layer "In2.Cu")
		(net "M_I_CPU0_SB_DQS_DN<8>")
	)
	(arc
		(start 388.026148 -291.421058)
		(mid 388.209923 -291.47183)
		(end 388.394956 -291.425884)
		(width 0.09525)
		(layer "In2.Cu")
		(net "M_I_CPU0_SB_DQS_DN<8>")
	)
	(arc
		(start 391.35431 -292.253162)
		(mid 391.53276 -292.454632)
		(end 391.597134 -292.71595)
		(width 0.09525)
		(layer "In2.Cu")
		(net "M_I_CPU0_SB_DQS_DN<8>")
	)
	(arc
		(start 384.643376 -291.421058)
		(mid 384.924808 -291.345303)
		(end 385.20624 -291.421058)
		(width 0.09525)
		(layer "In2.Cu")
		(net "M_I_CPU0_SB_DQS_DN<8>")
	)
	(arc
		(start 381.45466 -291.425884)
		(mid 381.639692 -291.471798)
		(end 381.823468 -291.421058)
		(width 0.09525)
		(layer "In2.Cu")
		(net "M_I_CPU0_SB_DQS_DN<8>")
	)
	(arc
		(start 381.823468 -291.421058)
		(mid 382.1049 -291.345303)
		(end 382.386332 -291.421058)
		(width 0.09525)
		(layer "In2.Cu")
		(net "M_I_CPU0_SB_DQS_DN<8>")
	)
	(arc
		(start 392.53668 -294.335962)
		(mid 392.578137 -294.508002)
		(end 392.693398 -294.642286)
		(width 0.09525)
		(layer "In2.Cu")
		(net "M_I_CPU0_SB_DQS_DN<8>")
	)
	(arc
		(start 379.56617 -291.421058)
		(mid 379.749945 -291.47183)
		(end 379.934978 -291.425884)
		(width 0.09525)
		(layer "In2.Cu")
		(net "M_I_CPU0_SB_DQS_DN<8>")
	)
	(arc
		(start 392.291062 -293.87165)
		(mid 392.471453 -294.073349)
		(end 392.53668 -294.335962)
		(width 0.09525)
		(layer "In2.Cu")
		(net "M_I_CPU0_SB_DQS_DN<8>")
	)
	(arc
		(start 376.249692 -291.388038)
		(mid 376.501833 -291.346468)
		(end 376.746262 -291.421058)
		(width 0.09525)
		(layer "In2.Cu")
		(net "M_I_CPU0_SB_DQS_DN<8>")
	)
	(arc
		(start 392.76401 -294.68318)
		(mid 392.94246 -294.88465)
		(end 393.006834 -295.145968)
		(width 0.09525)
		(layer "In2.Cu")
		(net "M_I_CPU0_SB_DQS_DN<8>")
	)
	(arc
		(start 376.754644 -291.425884)
		(mid 376.939676 -291.471798)
		(end 377.123452 -291.421058)
		(width 0.09525)
		(layer "In2.Cu")
		(net "M_I_CPU0_SB_DQS_DN<8>")
	)
	(arc
		(start 386.154676 -291.425884)
		(mid 386.339708 -291.471798)
		(end 386.523484 -291.421058)
		(width 0.09525)
		(layer "In2.Cu")
		(net "M_I_CPU0_SB_DQS_DN<8>")
	)
	(arc
		(start 383.326132 -291.421058)
		(mid 383.509907 -291.47183)
		(end 383.69494 -291.425884)
		(width 0.09525)
		(layer "In2.Cu")
		(net "M_I_CPU0_SB_DQS_DN<8>")
	)
	(arc
		(start 385.214622 -291.425884)
		(mid 385.399654 -291.471798)
		(end 385.58343 -291.421058)
		(width 0.09525)
		(layer "In2.Cu")
		(net "M_I_CPU0_SB_DQS_DN<8>")
	)
	(arc
		(start 385.58343 -291.421058)
		(mid 385.864862 -291.345303)
		(end 386.146294 -291.421058)
		(width 0.09525)
		(layer "In2.Cu")
		(net "M_I_CPU0_SB_DQS_DN<8>")
	)
	(arc
		(start 387.463284 -291.421058)
		(mid 387.744716 -291.345303)
		(end 388.026148 -291.421058)
		(width 0.09525)
		(layer "In2.Cu")
		(net "M_I_CPU0_SB_DQS_DN<8>")
	)
	(arc
		(start 389.914638 -291.425884)
		(mid 390.09967 -291.471798)
		(end 390.283446 -291.421058)
		(width 0.09525)
		(layer "In2.Cu")
		(net "M_I_CPU0_SB_DQS_DN<8>")
	)
	(arc
		(start 383.703322 -291.421058)
		(mid 383.984754 -291.345303)
		(end 384.266186 -291.421058)
		(width 0.09525)
		(layer "In2.Cu")
		(net "M_I_CPU0_SB_DQS_DN<8>")
	)
	(arc
		(start 379.94336 -291.421058)
		(mid 380.224792 -291.345303)
		(end 380.506224 -291.421058)
		(width 0.09525)
		(layer "In2.Cu")
		(net "M_I_CPU0_SB_DQS_DN<8>")
	)
	(arc
		(start 387.086348 -291.421058)
		(mid 387.274816 -291.471735)
		(end 387.463284 -291.421058)
		(width 0.09525)
		(layer "In2.Cu")
		(net "M_I_CPU0_SB_DQS_DN<8>")
	)
	(arc
		(start 380.506224 -291.421058)
		(mid 380.689999 -291.47183)
		(end 380.875032 -291.425884)
		(width 0.09525)
		(layer "In2.Cu")
		(net "M_I_CPU0_SB_DQS_DN<8>")
	)
	(arc
		(start 391.82421 -293.063168)
		(mid 392.00266 -293.264638)
		(end 392.067034 -293.525956)
		(width 0.09525)
		(layer "In2.Cu")
		(net "M_I_CPU0_SB_DQS_DN<8>")
	)
	(arc
		(start 388.966202 -291.421058)
		(mid 389.149977 -291.47183)
		(end 389.33501 -291.425884)
		(width 0.09525)
		(layer "In2.Cu")
		(net "M_I_CPU0_SB_DQS_DN<8>")
	)
	(arc
		(start 386.523484 -291.421058)
		(mid 386.804916 -291.345303)
		(end 387.086348 -291.421058)
		(width 0.09525)
		(layer "In2.Cu")
		(net "M_I_CPU0_SB_DQS_DN<8>")
	)
	(arc
		(start 379.003306 -291.421058)
		(mid 379.284738 -291.345303)
		(end 379.56617 -291.421058)
		(width 0.09525)
		(layer "In2.Cu")
		(net "M_I_CPU0_SB_DQS_DN<8>")
	)
	(arc
		(start 391.12698 -291.905944)
		(mid 391.168437 -292.077984)
		(end 391.283698 -292.212268)
		(width 0.09525)
		(layer "In2.Cu")
		(net "M_I_CPU0_SB_DQS_DN<8>")
	)
	(arc
		(start 377.123452 -291.421058)
		(mid 377.404884 -291.345303)
		(end 377.686316 -291.421058)
		(width 0.09525)
		(layer "In2.Cu")
		(net "M_I_CPU0_SB_DQS_DN<8>")
	)
	(arc
		(start 392.067034 -293.525956)
		(mid 392.108699 -293.698403)
		(end 392.224514 -293.832788)
		(width 0.09525)
		(layer "In2.Cu")
		(net "M_I_CPU0_SB_DQS_DN<8>")
	)
	(arc
		(start 378.063506 -291.421058)
		(mid 378.344938 -291.345303)
		(end 378.62637 -291.421058)
		(width 0.09525)
		(layer "In2.Cu")
		(net "M_I_CPU0_SB_DQS_DN<8>")
	)
	(arc
		(start 384.266186 -291.421058)
		(mid 384.449961 -291.47183)
		(end 384.634994 -291.425884)
		(width 0.09525)
		(layer "In2.Cu")
		(net "M_I_CPU0_SB_DQS_DN<8>")
	)
	(arc
		(start 390.881362 -291.441632)
		(mid 391.061753 -291.643331)
		(end 391.12698 -291.905944)
		(width 0.09525)
		(layer "In2.Cu")
		(net "M_I_CPU0_SB_DQS_DN<8>")
	)
	(arc
		(start 389.343392 -291.421058)
		(mid 389.624824 -291.345303)
		(end 389.906256 -291.421058)
		(width 0.09525)
		(layer "In2.Cu")
		(net "M_I_CPU0_SB_DQS_DN<8>")
	)
	(arc
		(start 388.403338 -291.421058)
		(mid 388.68477 -291.345303)
		(end 388.966202 -291.421058)
		(width 0.09525)
		(layer "In2.Cu")
		(net "M_I_CPU0_SB_DQS_DN<8>")
	)
	(arc
		(start 393.006834 -295.145968)
		(mid 393.04771 -295.31699)
		(end 393.16152 -295.451022)
		(width 0.09525)
		(layer "In2.Cu")
		(net "M_I_CPU0_SB_DQS_DN<8>")
	)
	(arc
		(start 382.763268 -291.421058)
		(mid 383.0447 -291.345303)
		(end 383.326132 -291.421058)
		(width 0.09525)
		(layer "In2.Cu")
		(net "M_I_CPU0_SB_DQS_DN<8>")
	)
	(arc
		(start 380.883414 -291.421058)
		(mid 381.164846 -291.345303)
		(end 381.446278 -291.421058)
		(width 0.09525)
		(layer "In2.Cu")
		(net "M_I_CPU0_SB_DQS_DN<8>")
	)
	(arc
		(start 390.283446 -291.421058)
		(mid 390.564878 -291.345303)
		(end 390.84631 -291.421058)
		(width 0.09525)
		(layer "In2.Cu")
		(net "M_I_CPU0_SB_DQS_DN<8>")
	)
	(arc
		(start 377.694698 -291.425884)
		(mid 377.87973 -291.471798)
		(end 378.063506 -291.421058)
		(width 0.09525)
		(layer "In2.Cu")
		(net "M_I_CPU0_SB_DQS_DN<8>")
	)
	(arc
		(start 382.386332 -291.421058)
		(mid 382.5748 -291.471735)
		(end 382.763268 -291.421058)
		(width 0.09525)
		(layer "In2.Cu")
		(net "M_I_CPU0_SB_DQS_DN<8>")
	)
	(segment
		(start 375.528078 -285.970218)
		(end 375.99493 -286.236156)
		(width 0.12954)
		(layer "F.Cu")
		(net "M_I_CPU0_SB_DQS_DN<7>")
	)
	(segment
		(start 427.181518 -304.709576)
		(end 427.456092 -304.435002)
		(width 0.16002)
		(layer "In2.Cu")
		(net "M_I_CPU0_SB_DQS_DN<7>")
	)
	(segment
		(start 408.432508 -304.583084)
		(end 411.147768 -305.707796)
		(width 0.16002)
		(layer "In2.Cu")
		(net "M_I_CPU0_SB_DQS_DN<7>")
	)
	(segment
		(start 375.99493 -286.236156)
		(end 376.148854 -286.501586)
		(width 0.09525)
		(layer "In2.Cu")
		(net "M_I_CPU0_SB_DQS_DN<7>")
	)
	(segment
		(start 392.15187 -286.567372)
		(end 392.152632 -286.566864)
		(width 0.09525)
		(layer "In2.Cu")
		(net "M_I_CPU0_SB_DQS_DN<7>")
	)
	(segment
		(start 392.153648 -286.566356)
		(end 392.162538 -286.561276)
		(width 0.09525)
		(layer "In2.Cu")
		(net "M_I_CPU0_SB_DQS_DN<7>")
	)
	(segment
		(start 419.111684 -305.70805)
		(end 420.67734 -305.70805)
		(width 0.16002)
		(layer "In2.Cu")
		(net "M_I_CPU0_SB_DQS_DN<7>")
	)
	(segment
		(start 393.695682 -286.486092)
		(end 394.321538 -287.111948)
		(width 0.09525)
		(layer "In2.Cu")
		(net "M_I_CPU0_SB_DQS_DN<7>")
	)
	(segment
		(start 407.518616 -303.392332)
		(end 407.518616 -303.669192)
		(width 0.16002)
		(layer "In2.Cu")
		(net "M_I_CPU0_SB_DQS_DN<7>")
	)
	(segment
		(start 406.152604 -300.735746)
		(end 406.526492 -301.109634)
		(width 0.16002)
		(layer "In2.Cu")
		(net "M_I_CPU0_SB_DQS_DN<7>")
	)
	(segment
		(start 415.391092 -304.550572)
		(end 415.698432 -304.857912)
		(width 0.16002)
		(layer "In2.Cu")
		(net "M_I_CPU0_SB_DQS_DN<7>")
	)
	(segment
		(start 406.99944 -302.109632)
		(end 407.526236 -302.109378)
		(width 0.16002)
		(layer "In2.Cu")
		(net "M_I_CPU0_SB_DQS_DN<7>")
	)
	(segment
		(start 392.152632 -286.566864)
		(end 392.153648 -286.566356)
		(width 0.09525)
		(layer "In2.Cu")
		(net "M_I_CPU0_SB_DQS_DN<7>")
	)
	(segment
		(start 415.698432 -304.857912)
		(end 418.261546 -304.857912)
		(width 0.16002)
		(layer "In2.Cu")
		(net "M_I_CPU0_SB_DQS_DN<7>")
	)
	(segment
		(start 404.771352 -300.644814)
		(end 404.771352 -300.921928)
		(width 0.16002)
		(layer "In2.Cu")
		(net "M_I_CPU0_SB_DQS_DN<7>")
	)
	(segment
		(start 405.15286 -299.72762)
		(end 405.15286 -300.263306)
		(width 0.16002)
		(layer "In2.Cu")
		(net "M_I_CPU0_SB_DQS_DN<7>")
	)
	(segment
		(start 395.351508 -288.472372)
		(end 396.674086 -289.79495)
		(width 0.16002)
		(layer "In2.Cu")
		(net "M_I_CPU0_SB_DQS_DN<7>")
	)
	(segment
		(start 425.065698 -304.857912)
		(end 425.214034 -304.709576)
		(width 0.16002)
		(layer "In2.Cu")
		(net "M_I_CPU0_SB_DQS_DN<7>")
	)
	(segment
		(start 407.900378 -303.01057)
		(end 407.518616 -303.392332)
		(width 0.16002)
		(layer "In2.Cu")
		(net "M_I_CPU0_SB_DQS_DN<7>")
	)
	(segment
		(start 386.146294 -286.561276)
		(end 386.154676 -286.566102)
		(width 0.09525)
		(layer "In2.Cu")
		(net "M_I_CPU0_SB_DQS_DN<7>")
	)
	(segment
		(start 383.69494 -286.566102)
		(end 383.703322 -286.561276)
		(width 0.09525)
		(layer "In2.Cu")
		(net "M_I_CPU0_SB_DQS_DN<7>")
	)
	(segment
		(start 405.625808 -300.736)
		(end 406.152604 -300.735746)
		(width 0.16002)
		(layer "In2.Cu")
		(net "M_I_CPU0_SB_DQS_DN<7>")
	)
	(segment
		(start 404.967186 -301.117762)
		(end 405.244046 -301.117762)
		(width 0.16002)
		(layer "In2.Cu")
		(net "M_I_CPU0_SB_DQS_DN<7>")
	)
	(segment
		(start 389.33501 -286.566102)
		(end 389.343392 -286.561276)
		(width 0.09525)
		(layer "In2.Cu")
		(net "M_I_CPU0_SB_DQS_DN<7>")
	)
	(segment
		(start 425.214034 -304.709576)
		(end 427.181518 -304.709576)
		(width 0.16002)
		(layer "In2.Cu")
		(net "M_I_CPU0_SB_DQS_DN<7>")
	)
	(segment
		(start 379.934978 -286.566102)
		(end 379.94336 -286.561276)
		(width 0.09525)
		(layer "In2.Cu")
		(net "M_I_CPU0_SB_DQS_DN<7>")
	)
	(segment
		(start 388.394956 -286.566102)
		(end 388.403338 -286.561276)
		(width 0.09525)
		(layer "In2.Cu")
		(net "M_I_CPU0_SB_DQS_DN<7>")
	)
	(segment
		(start 407.526236 -302.109378)
		(end 407.900124 -302.483266)
		(width 0.16002)
		(layer "In2.Cu")
		(net "M_I_CPU0_SB_DQS_DN<7>")
	)
	(segment
		(start 392.44143 -286.486092)
		(end 393.695682 -286.486092)
		(width 0.09525)
		(layer "In2.Cu")
		(net "M_I_CPU0_SB_DQS_DN<7>")
	)
	(segment
		(start 395.250924 -288.455608)
		(end 395.334744 -288.455608)
		(width 0.09525)
		(layer "In2.Cu")
		(net "M_I_CPU0_SB_DQS_DN<7>")
	)
	(segment
		(start 421.042338 -305.343052)
		(end 421.479218 -305.343052)
		(width 0.16002)
		(layer "In2.Cu")
		(net "M_I_CPU0_SB_DQS_DN<7>")
	)
	(segment
		(start 396.674086 -289.79495)
		(end 397.702786 -292.277546)
		(width 0.16002)
		(layer "In2.Cu")
		(net "M_I_CPU0_SB_DQS_DN<7>")
	)
	(segment
		(start 385.20624 -286.561276)
		(end 385.214622 -286.566102)
		(width 0.09525)
		(layer "In2.Cu")
		(net "M_I_CPU0_SB_DQS_DN<7>")
	)
	(segment
		(start 392.138662 -286.574484)
		(end 392.15187 -286.567372)
		(width 0.09525)
		(layer "In2.Cu")
		(net "M_I_CPU0_SB_DQS_DN<7>")
	)
	(segment
		(start 406.526746 -301.636938)
		(end 406.144984 -302.0187)
		(width 0.16002)
		(layer "In2.Cu")
		(net "M_I_CPU0_SB_DQS_DN<7>")
	)
	(segment
		(start 389.906256 -286.561276)
		(end 389.914638 -286.566102)
		(width 0.09525)
		(layer "In2.Cu")
		(net "M_I_CPU0_SB_DQS_DN<7>")
	)
	(segment
		(start 394.321538 -287.111948)
		(end 394.321538 -287.526222)
		(width 0.09525)
		(layer "In2.Cu")
		(net "M_I_CPU0_SB_DQS_DN<7>")
	)
	(segment
		(start 413.498284 -305.343052)
		(end 413.935164 -305.343052)
		(width 0.16002)
		(layer "In2.Cu")
		(net "M_I_CPU0_SB_DQS_DN<7>")
	)
	(segment
		(start 413.935164 -305.343052)
		(end 414.727644 -304.550572)
		(width 0.16002)
		(layer "In2.Cu")
		(net "M_I_CPU0_SB_DQS_DN<7>")
	)
	(segment
		(start 395.334744 -288.455608)
		(end 395.351508 -288.472372)
		(width 0.09525)
		(layer "In2.Cu")
		(net "M_I_CPU0_SB_DQS_DN<7>")
	)
	(segment
		(start 407.518616 -303.669192)
		(end 408.432508 -304.583084)
		(width 0.16002)
		(layer "In2.Cu")
		(net "M_I_CPU0_SB_DQS_DN<7>")
	)
	(segment
		(start 384.634994 -286.566102)
		(end 384.643376 -286.561276)
		(width 0.09525)
		(layer "In2.Cu")
		(net "M_I_CPU0_SB_DQS_DN<7>")
	)
	(segment
		(start 406.526492 -301.109634)
		(end 406.526746 -301.636938)
		(width 0.16002)
		(layer "In2.Cu")
		(net "M_I_CPU0_SB_DQS_DN<7>")
	)
	(segment
		(start 414.727644 -304.550572)
		(end 415.391092 -304.550572)
		(width 0.16002)
		(layer "In2.Cu")
		(net "M_I_CPU0_SB_DQS_DN<7>")
	)
	(segment
		(start 407.900124 -302.483266)
		(end 407.900378 -303.01057)
		(width 0.16002)
		(layer "In2.Cu")
		(net "M_I_CPU0_SB_DQS_DN<7>")
	)
	(segment
		(start 420.67734 -305.70805)
		(end 421.042338 -305.343052)
		(width 0.16002)
		(layer "In2.Cu")
		(net "M_I_CPU0_SB_DQS_DN<7>")
	)
	(segment
		(start 381.446278 -286.561276)
		(end 381.45466 -286.566102)
		(width 0.09525)
		(layer "In2.Cu")
		(net "M_I_CPU0_SB_DQS_DN<7>")
	)
	(segment
		(start 421.479218 -305.343052)
		(end 422.271698 -304.550572)
		(width 0.16002)
		(layer "In2.Cu")
		(net "M_I_CPU0_SB_DQS_DN<7>")
	)
	(segment
		(start 406.144984 -302.29556)
		(end 406.340818 -302.491394)
		(width 0.16002)
		(layer "In2.Cu")
		(net "M_I_CPU0_SB_DQS_DN<7>")
	)
	(segment
		(start 406.144984 -302.0187)
		(end 406.144984 -302.29556)
		(width 0.16002)
		(layer "In2.Cu")
		(net "M_I_CPU0_SB_DQS_DN<7>")
	)
	(segment
		(start 377.686316 -286.561276)
		(end 377.694698 -286.566102)
		(width 0.09525)
		(layer "In2.Cu")
		(net "M_I_CPU0_SB_DQS_DN<7>")
	)
	(segment
		(start 413.13354 -305.707796)
		(end 413.498284 -305.343052)
		(width 0.16002)
		(layer "In2.Cu")
		(net "M_I_CPU0_SB_DQS_DN<7>")
	)
	(segment
		(start 404.771352 -300.921928)
		(end 404.967186 -301.117762)
		(width 0.16002)
		(layer "In2.Cu")
		(net "M_I_CPU0_SB_DQS_DN<7>")
	)
	(segment
		(start 405.15286 -300.263306)
		(end 404.771352 -300.644814)
		(width 0.16002)
		(layer "In2.Cu")
		(net "M_I_CPU0_SB_DQS_DN<7>")
	)
	(segment
		(start 418.261546 -304.857912)
		(end 419.111684 -305.70805)
		(width 0.16002)
		(layer "In2.Cu")
		(net "M_I_CPU0_SB_DQS_DN<7>")
	)
	(segment
		(start 376.746262 -286.561276)
		(end 376.754644 -286.566102)
		(width 0.09525)
		(layer "In2.Cu")
		(net "M_I_CPU0_SB_DQS_DN<7>")
	)
	(segment
		(start 423.242486 -304.857912)
		(end 425.065698 -304.857912)
		(width 0.16002)
		(layer "In2.Cu")
		(net "M_I_CPU0_SB_DQS_DN<7>")
	)
	(segment
		(start 422.271698 -304.550572)
		(end 422.935146 -304.550572)
		(width 0.16002)
		(layer "In2.Cu")
		(net "M_I_CPU0_SB_DQS_DN<7>")
	)
	(segment
		(start 405.244046 -301.117762)
		(end 405.625808 -300.736)
		(width 0.16002)
		(layer "In2.Cu")
		(net "M_I_CPU0_SB_DQS_DN<7>")
	)
	(segment
		(start 397.702786 -292.277546)
		(end 405.15286 -299.72762)
		(width 0.16002)
		(layer "In2.Cu")
		(net "M_I_CPU0_SB_DQS_DN<7>")
	)
	(segment
		(start 380.875032 -286.566102)
		(end 380.883414 -286.561276)
		(width 0.09525)
		(layer "In2.Cu")
		(net "M_I_CPU0_SB_DQS_DN<7>")
	)
	(segment
		(start 376.148854 -286.501586)
		(end 376.249692 -286.528256)
		(width 0.09525)
		(layer "In2.Cu")
		(net "M_I_CPU0_SB_DQS_DN<7>")
	)
	(segment
		(start 411.147768 -305.707796)
		(end 413.13354 -305.707796)
		(width 0.16002)
		(layer "In2.Cu")
		(net "M_I_CPU0_SB_DQS_DN<7>")
	)
	(segment
		(start 394.321538 -287.526222)
		(end 395.250924 -288.455608)
		(width 0.09525)
		(layer "In2.Cu")
		(net "M_I_CPU0_SB_DQS_DN<7>")
	)
	(segment
		(start 406.617678 -302.491394)
		(end 406.99944 -302.109632)
		(width 0.16002)
		(layer "In2.Cu")
		(net "M_I_CPU0_SB_DQS_DN<7>")
	)
	(segment
		(start 422.935146 -304.550572)
		(end 423.242486 -304.857912)
		(width 0.16002)
		(layer "In2.Cu")
		(net "M_I_CPU0_SB_DQS_DN<7>")
	)
	(segment
		(start 406.340818 -302.491394)
		(end 406.617678 -302.491394)
		(width 0.16002)
		(layer "In2.Cu")
		(net "M_I_CPU0_SB_DQS_DN<7>")
	)
	(arc
		(start 386.523484 -286.561276)
		(mid 386.804916 -286.485487)
		(end 387.086348 -286.561276)
		(width 0.09525)
		(layer "In2.Cu")
		(net "M_I_CPU0_SB_DQS_DN<7>")
	)
	(arc
		(start 380.883414 -286.561276)
		(mid 381.164846 -286.485487)
		(end 381.446278 -286.561276)
		(width 0.09525)
		(layer "In2.Cu")
		(net "M_I_CPU0_SB_DQS_DN<7>")
	)
	(arc
		(start 379.56617 -286.561276)
		(mid 379.749945 -286.612048)
		(end 379.934978 -286.566102)
		(width 0.09525)
		(layer "In2.Cu")
		(net "M_I_CPU0_SB_DQS_DN<7>")
	)
	(arc
		(start 379.003306 -286.561276)
		(mid 379.284738 -286.485487)
		(end 379.56617 -286.561276)
		(width 0.09525)
		(layer "In2.Cu")
		(net "M_I_CPU0_SB_DQS_DN<7>")
	)
	(arc
		(start 378.063506 -286.561276)
		(mid 378.344938 -286.485487)
		(end 378.62637 -286.561276)
		(width 0.09525)
		(layer "In2.Cu")
		(net "M_I_CPU0_SB_DQS_DN<7>")
	)
	(arc
		(start 380.506224 -286.561276)
		(mid 380.689999 -286.612048)
		(end 380.875032 -286.566102)
		(width 0.09525)
		(layer "In2.Cu")
		(net "M_I_CPU0_SB_DQS_DN<7>")
	)
	(arc
		(start 381.823468 -286.561276)
		(mid 382.1049 -286.485487)
		(end 382.386332 -286.561276)
		(width 0.09525)
		(layer "In2.Cu")
		(net "M_I_CPU0_SB_DQS_DN<7>")
	)
	(arc
		(start 387.463284 -286.561276)
		(mid 387.744716 -286.485487)
		(end 388.026148 -286.561276)
		(width 0.09525)
		(layer "In2.Cu")
		(net "M_I_CPU0_SB_DQS_DN<7>")
	)
	(arc
		(start 387.086348 -286.561276)
		(mid 387.274816 -286.611953)
		(end 387.463284 -286.561276)
		(width 0.09525)
		(layer "In2.Cu")
		(net "M_I_CPU0_SB_DQS_DN<7>")
	)
	(arc
		(start 389.343392 -286.561276)
		(mid 389.624824 -286.485487)
		(end 389.906256 -286.561276)
		(width 0.09525)
		(layer "In2.Cu")
		(net "M_I_CPU0_SB_DQS_DN<7>")
	)
	(arc
		(start 390.283446 -286.561276)
		(mid 390.564878 -286.485487)
		(end 390.84631 -286.561276)
		(width 0.09525)
		(layer "In2.Cu")
		(net "M_I_CPU0_SB_DQS_DN<7>")
	)
	(arc
		(start 378.62637 -286.561276)
		(mid 378.814838 -286.611953)
		(end 379.003306 -286.561276)
		(width 0.09525)
		(layer "In2.Cu")
		(net "M_I_CPU0_SB_DQS_DN<7>")
	)
	(arc
		(start 390.84631 -286.561276)
		(mid 391.034778 -286.611953)
		(end 391.223246 -286.561276)
		(width 0.09525)
		(layer "In2.Cu")
		(net "M_I_CPU0_SB_DQS_DN<7>")
	)
	(arc
		(start 384.266186 -286.561276)
		(mid 384.449961 -286.612048)
		(end 384.634994 -286.566102)
		(width 0.09525)
		(layer "In2.Cu")
		(net "M_I_CPU0_SB_DQS_DN<7>")
	)
	(arc
		(start 392.162538 -286.561276)
		(mid 392.297049 -286.505378)
		(end 392.44143 -286.486092)
		(width 0.09525)
		(layer "In2.Cu")
		(net "M_I_CPU0_SB_DQS_DN<7>")
	)
	(arc
		(start 383.326132 -286.561276)
		(mid 383.509907 -286.612048)
		(end 383.69494 -286.566102)
		(width 0.09525)
		(layer "In2.Cu")
		(net "M_I_CPU0_SB_DQS_DN<7>")
	)
	(arc
		(start 388.026148 -286.561276)
		(mid 388.209923 -286.612048)
		(end 388.394956 -286.566102)
		(width 0.09525)
		(layer "In2.Cu")
		(net "M_I_CPU0_SB_DQS_DN<7>")
	)
	(arc
		(start 386.154676 -286.566102)
		(mid 386.339708 -286.612016)
		(end 386.523484 -286.561276)
		(width 0.09525)
		(layer "In2.Cu")
		(net "M_I_CPU0_SB_DQS_DN<7>")
	)
	(arc
		(start 382.386332 -286.561276)
		(mid 382.5748 -286.611953)
		(end 382.763268 -286.561276)
		(width 0.09525)
		(layer "In2.Cu")
		(net "M_I_CPU0_SB_DQS_DN<7>")
	)
	(arc
		(start 379.94336 -286.561276)
		(mid 380.224792 -286.485487)
		(end 380.506224 -286.561276)
		(width 0.09525)
		(layer "In2.Cu")
		(net "M_I_CPU0_SB_DQS_DN<7>")
	)
	(arc
		(start 384.643376 -286.561276)
		(mid 384.924808 -286.485487)
		(end 385.20624 -286.561276)
		(width 0.09525)
		(layer "In2.Cu")
		(net "M_I_CPU0_SB_DQS_DN<7>")
	)
	(arc
		(start 377.123452 -286.561276)
		(mid 377.404884 -286.485487)
		(end 377.686316 -286.561276)
		(width 0.09525)
		(layer "In2.Cu")
		(net "M_I_CPU0_SB_DQS_DN<7>")
	)
	(arc
		(start 376.249692 -286.528256)
		(mid 376.501832 -286.486667)
		(end 376.746262 -286.561276)
		(width 0.09525)
		(layer "In2.Cu")
		(net "M_I_CPU0_SB_DQS_DN<7>")
	)
	(arc
		(start 385.58343 -286.561276)
		(mid 385.864862 -286.485487)
		(end 386.146294 -286.561276)
		(width 0.09525)
		(layer "In2.Cu")
		(net "M_I_CPU0_SB_DQS_DN<7>")
	)
	(arc
		(start 382.763268 -286.561276)
		(mid 383.0447 -286.485487)
		(end 383.326132 -286.561276)
		(width 0.09525)
		(layer "In2.Cu")
		(net "M_I_CPU0_SB_DQS_DN<7>")
	)
	(arc
		(start 391.223246 -286.561276)
		(mid 391.504678 -286.485487)
		(end 391.78611 -286.561276)
		(width 0.09525)
		(layer "In2.Cu")
		(net "M_I_CPU0_SB_DQS_DN<7>")
	)
	(arc
		(start 377.694698 -286.566102)
		(mid 377.87973 -286.612016)
		(end 378.063506 -286.561276)
		(width 0.09525)
		(layer "In2.Cu")
		(net "M_I_CPU0_SB_DQS_DN<7>")
	)
	(arc
		(start 383.703322 -286.561276)
		(mid 383.984754 -286.485487)
		(end 384.266186 -286.561276)
		(width 0.09525)
		(layer "In2.Cu")
		(net "M_I_CPU0_SB_DQS_DN<7>")
	)
	(arc
		(start 385.214622 -286.566102)
		(mid 385.399654 -286.612016)
		(end 385.58343 -286.561276)
		(width 0.09525)
		(layer "In2.Cu")
		(net "M_I_CPU0_SB_DQS_DN<7>")
	)
	(arc
		(start 388.966202 -286.561276)
		(mid 389.149977 -286.612048)
		(end 389.33501 -286.566102)
		(width 0.09525)
		(layer "In2.Cu")
		(net "M_I_CPU0_SB_DQS_DN<7>")
	)
	(arc
		(start 376.754644 -286.566102)
		(mid 376.939676 -286.612016)
		(end 377.123452 -286.561276)
		(width 0.09525)
		(layer "In2.Cu")
		(net "M_I_CPU0_SB_DQS_DN<7>")
	)
	(arc
		(start 389.914638 -286.566102)
		(mid 390.09967 -286.612016)
		(end 390.283446 -286.561276)
		(width 0.09525)
		(layer "In2.Cu")
		(net "M_I_CPU0_SB_DQS_DN<7>")
	)
	(arc
		(start 388.403338 -286.561276)
		(mid 388.68477 -286.485487)
		(end 388.966202 -286.561276)
		(width 0.09525)
		(layer "In2.Cu")
		(net "M_I_CPU0_SB_DQS_DN<7>")
	)
	(arc
		(start 391.78611 -286.561276)
		(mid 391.960742 -286.611816)
		(end 392.138662 -286.574484)
		(width 0.09525)
		(layer "In2.Cu")
		(net "M_I_CPU0_SB_DQS_DN<7>")
	)
	(arc
		(start 381.45466 -286.566102)
		(mid 381.639692 -286.612016)
		(end 381.823468 -286.561276)
		(width 0.09525)
		(layer "In2.Cu")
		(net "M_I_CPU0_SB_DQS_DN<7>")
	)
	(segment
		(start 375.528078 -281.110182)
		(end 375.99493 -281.37612)
		(width 0.12954)
		(layer "F.Cu")
		(net "M_I_CPU0_SB_DQS_DN<6>")
	)
	(segment
		(start 393.384786 -281.624532)
		(end 393.385548 -281.625294)
		(width 0.09525)
		(layer "In2.Cu")
		(net "M_I_CPU0_SB_DQS_DN<6>")
	)
	(segment
		(start 405.60371 -289.645344)
		(end 405.60371 -290.373816)
		(width 0.16002)
		(layer "In2.Cu")
		(net "M_I_CPU0_SB_DQS_DN<6>")
	)
	(segment
		(start 425.065698 -295.507918)
		(end 425.214034 -295.359582)
		(width 0.16002)
		(layer "In2.Cu")
		(net "M_I_CPU0_SB_DQS_DN<6>")
	)
	(segment
		(start 414.727644 -295.200578)
		(end 415.391092 -295.200578)
		(width 0.16002)
		(layer "In2.Cu")
		(net "M_I_CPU0_SB_DQS_DN<6>")
	)
	(segment
		(start 383.69494 -281.706066)
		(end 383.703322 -281.70124)
		(width 0.09525)
		(layer "In2.Cu")
		(net "M_I_CPU0_SB_DQS_DN<6>")
	)
	(segment
		(start 389.906256 -281.70124)
		(end 389.914638 -281.706066)
		(width 0.09525)
		(layer "In2.Cu")
		(net "M_I_CPU0_SB_DQS_DN<6>")
	)
	(segment
		(start 425.214034 -295.359582)
		(end 427.181518 -295.359582)
		(width 0.16002)
		(layer "In2.Cu")
		(net "M_I_CPU0_SB_DQS_DN<6>")
	)
	(segment
		(start 411.587696 -296.357802)
		(end 413.13354 -296.357802)
		(width 0.16002)
		(layer "In2.Cu")
		(net "M_I_CPU0_SB_DQS_DN<6>")
	)
	(segment
		(start 405.83739 -290.607496)
		(end 406.565862 -290.607496)
		(width 0.16002)
		(layer "In2.Cu")
		(net "M_I_CPU0_SB_DQS_DN<6>")
	)
	(segment
		(start 422.935146 -295.200578)
		(end 423.242486 -295.507918)
		(width 0.16002)
		(layer "In2.Cu")
		(net "M_I_CPU0_SB_DQS_DN<6>")
	)
	(segment
		(start 415.391092 -295.200578)
		(end 415.698432 -295.507918)
		(width 0.16002)
		(layer "In2.Cu")
		(net "M_I_CPU0_SB_DQS_DN<6>")
	)
	(segment
		(start 402.856446 -286.89808)
		(end 402.856446 -287.626552)
		(width 0.16002)
		(layer "In2.Cu")
		(net "M_I_CPU0_SB_DQS_DN<6>")
	)
	(segment
		(start 392.16203 -281.700986)
		(end 392.187938 -281.686)
		(width 0.09525)
		(layer "In2.Cu")
		(net "M_I_CPU0_SB_DQS_DN<6>")
	)
	(segment
		(start 386.146294 -281.70124)
		(end 386.154676 -281.706066)
		(width 0.09525)
		(layer "In2.Cu")
		(net "M_I_CPU0_SB_DQS_DN<6>")
	)
	(segment
		(start 422.271698 -295.200578)
		(end 422.935146 -295.200578)
		(width 0.16002)
		(layer "In2.Cu")
		(net "M_I_CPU0_SB_DQS_DN<6>")
	)
	(segment
		(start 392.722862 -281.70124)
		(end 392.74623 -281.714702)
		(width 0.09525)
		(layer "In2.Cu")
		(net "M_I_CPU0_SB_DQS_DN<6>")
	)
	(segment
		(start 395.77645 -281.877262)
		(end 395.835632 -281.81808)
		(width 0.09525)
		(layer "In2.Cu")
		(net "M_I_CPU0_SB_DQS_DN<6>")
	)
	(segment
		(start 408.350974 -292.392608)
		(end 408.350974 -293.12108)
		(width 0.16002)
		(layer "In2.Cu")
		(net "M_I_CPU0_SB_DQS_DN<6>")
	)
	(segment
		(start 409.724606 -294.494712)
		(end 411.587696 -296.357802)
		(width 0.16002)
		(layer "In2.Cu")
		(net "M_I_CPU0_SB_DQS_DN<6>")
	)
	(segment
		(start 384.634994 -281.706066)
		(end 384.643376 -281.70124)
		(width 0.09525)
		(layer "In2.Cu")
		(net "M_I_CPU0_SB_DQS_DN<6>")
	)
	(segment
		(start 393.959842 -281.877262)
		(end 395.77645 -281.877262)
		(width 0.09525)
		(layer "In2.Cu")
		(net "M_I_CPU0_SB_DQS_DN<6>")
	)
	(segment
		(start 413.13354 -296.357802)
		(end 413.498284 -295.993058)
		(width 0.16002)
		(layer "In2.Cu")
		(net "M_I_CPU0_SB_DQS_DN<6>")
	)
	(segment
		(start 392.138662 -281.714448)
		(end 392.16203 -281.700986)
		(width 0.09525)
		(layer "In2.Cu")
		(net "M_I_CPU0_SB_DQS_DN<6>")
	)
	(segment
		(start 377.686316 -281.70124)
		(end 377.694698 -281.706066)
		(width 0.09525)
		(layer "In2.Cu")
		(net "M_I_CPU0_SB_DQS_DN<6>")
	)
	(segment
		(start 405.60371 -290.373816)
		(end 405.83739 -290.607496)
		(width 0.16002)
		(layer "In2.Cu")
		(net "M_I_CPU0_SB_DQS_DN<6>")
	)
	(segment
		(start 408.350974 -293.12108)
		(end 408.584654 -293.35476)
		(width 0.16002)
		(layer "In2.Cu")
		(net "M_I_CPU0_SB_DQS_DN<6>")
	)
	(segment
		(start 406.977342 -291.747448)
		(end 407.211022 -291.981128)
		(width 0.16002)
		(layer "In2.Cu")
		(net "M_I_CPU0_SB_DQS_DN<6>")
	)
	(segment
		(start 404.230078 -289.000184)
		(end 404.463758 -289.233864)
		(width 0.16002)
		(layer "In2.Cu")
		(net "M_I_CPU0_SB_DQS_DN<6>")
	)
	(segment
		(start 404.230078 -288.271712)
		(end 404.230078 -289.000184)
		(width 0.16002)
		(layer "In2.Cu")
		(net "M_I_CPU0_SB_DQS_DN<6>")
	)
	(segment
		(start 381.446278 -281.70124)
		(end 381.45466 -281.706066)
		(width 0.09525)
		(layer "In2.Cu")
		(net "M_I_CPU0_SB_DQS_DN<6>")
	)
	(segment
		(start 380.875032 -281.706066)
		(end 380.883414 -281.70124)
		(width 0.09525)
		(layer "In2.Cu")
		(net "M_I_CPU0_SB_DQS_DN<6>")
	)
	(segment
		(start 376.148854 -281.64155)
		(end 376.249692 -281.66822)
		(width 0.09525)
		(layer "In2.Cu")
		(net "M_I_CPU0_SB_DQS_DN<6>")
	)
	(segment
		(start 376.746262 -281.70124)
		(end 376.754644 -281.706066)
		(width 0.09525)
		(layer "In2.Cu")
		(net "M_I_CPU0_SB_DQS_DN<6>")
	)
	(segment
		(start 420.67734 -296.358056)
		(end 420.996364 -296.039032)
		(width 0.16002)
		(layer "In2.Cu")
		(net "M_I_CPU0_SB_DQS_DN<6>")
	)
	(segment
		(start 403.818598 -287.860232)
		(end 404.230078 -288.271712)
		(width 0.16002)
		(layer "In2.Cu")
		(net "M_I_CPU0_SB_DQS_DN<6>")
	)
	(segment
		(start 420.996364 -296.039032)
		(end 421.742362 -295.729914)
		(width 0.16002)
		(layer "In2.Cu")
		(net "M_I_CPU0_SB_DQS_DN<6>")
	)
	(segment
		(start 401.716494 -286.4866)
		(end 402.444966 -286.4866)
		(width 0.16002)
		(layer "In2.Cu")
		(net "M_I_CPU0_SB_DQS_DN<6>")
	)
	(segment
		(start 389.33501 -281.706066)
		(end 389.343392 -281.70124)
		(width 0.09525)
		(layer "In2.Cu")
		(net "M_I_CPU0_SB_DQS_DN<6>")
	)
	(segment
		(start 409.724606 -293.76624)
		(end 409.724606 -294.494712)
		(width 0.16002)
		(layer "In2.Cu")
		(net "M_I_CPU0_SB_DQS_DN<6>")
	)
	(segment
		(start 397.047974 -281.81808)
		(end 401.716494 -286.4866)
		(width 0.16002)
		(layer "In2.Cu")
		(net "M_I_CPU0_SB_DQS_DN<6>")
	)
	(segment
		(start 402.856446 -287.626552)
		(end 403.090126 -287.860232)
		(width 0.16002)
		(layer "In2.Cu")
		(net "M_I_CPU0_SB_DQS_DN<6>")
	)
	(segment
		(start 406.977342 -291.018976)
		(end 406.977342 -291.747448)
		(width 0.16002)
		(layer "In2.Cu")
		(net "M_I_CPU0_SB_DQS_DN<6>")
	)
	(segment
		(start 407.211022 -291.981128)
		(end 407.939494 -291.981128)
		(width 0.16002)
		(layer "In2.Cu")
		(net "M_I_CPU0_SB_DQS_DN<6>")
	)
	(segment
		(start 419.012116 -296.358056)
		(end 420.67734 -296.358056)
		(width 0.16002)
		(layer "In2.Cu")
		(net "M_I_CPU0_SB_DQS_DN<6>")
	)
	(segment
		(start 407.939494 -291.981128)
		(end 408.350974 -292.392608)
		(width 0.16002)
		(layer "In2.Cu")
		(net "M_I_CPU0_SB_DQS_DN<6>")
	)
	(segment
		(start 409.313126 -293.35476)
		(end 409.724606 -293.76624)
		(width 0.16002)
		(layer "In2.Cu")
		(net "M_I_CPU0_SB_DQS_DN<6>")
	)
	(segment
		(start 427.181518 -295.359582)
		(end 427.456092 -295.085008)
		(width 0.16002)
		(layer "In2.Cu")
		(net "M_I_CPU0_SB_DQS_DN<6>")
	)
	(segment
		(start 395.859254 -281.81808)
		(end 397.047974 -281.81808)
		(width 0.16002)
		(layer "In2.Cu")
		(net "M_I_CPU0_SB_DQS_DN<6>")
	)
	(segment
		(start 418.161978 -295.507918)
		(end 419.012116 -296.358056)
		(width 0.16002)
		(layer "In2.Cu")
		(net "M_I_CPU0_SB_DQS_DN<6>")
	)
	(segment
		(start 415.698432 -295.507918)
		(end 418.161978 -295.507918)
		(width 0.16002)
		(layer "In2.Cu")
		(net "M_I_CPU0_SB_DQS_DN<6>")
	)
	(segment
		(start 413.498284 -295.993058)
		(end 413.935164 -295.993058)
		(width 0.16002)
		(layer "In2.Cu")
		(net "M_I_CPU0_SB_DQS_DN<6>")
	)
	(segment
		(start 408.584654 -293.35476)
		(end 409.313126 -293.35476)
		(width 0.16002)
		(layer "In2.Cu")
		(net "M_I_CPU0_SB_DQS_DN<6>")
	)
	(segment
		(start 393.385548 -281.625294)
		(end 393.707874 -281.625294)
		(width 0.09525)
		(layer "In2.Cu")
		(net "M_I_CPU0_SB_DQS_DN<6>")
	)
	(segment
		(start 388.394956 -281.706066)
		(end 388.403338 -281.70124)
		(width 0.09525)
		(layer "In2.Cu")
		(net "M_I_CPU0_SB_DQS_DN<6>")
	)
	(segment
		(start 421.742362 -295.729914)
		(end 422.271698 -295.200578)
		(width 0.16002)
		(layer "In2.Cu")
		(net "M_I_CPU0_SB_DQS_DN<6>")
	)
	(segment
		(start 385.20624 -281.70124)
		(end 385.214622 -281.706066)
		(width 0.09525)
		(layer "In2.Cu")
		(net "M_I_CPU0_SB_DQS_DN<6>")
	)
	(segment
		(start 375.99493 -281.37612)
		(end 376.148854 -281.64155)
		(width 0.09525)
		(layer "In2.Cu")
		(net "M_I_CPU0_SB_DQS_DN<6>")
	)
	(segment
		(start 413.935164 -295.993058)
		(end 414.727644 -295.200578)
		(width 0.16002)
		(layer "In2.Cu")
		(net "M_I_CPU0_SB_DQS_DN<6>")
	)
	(segment
		(start 395.835632 -281.81808)
		(end 395.859254 -281.81808)
		(width 0.09525)
		(layer "In2.Cu")
		(net "M_I_CPU0_SB_DQS_DN<6>")
	)
	(segment
		(start 404.463758 -289.233864)
		(end 405.19223 -289.233864)
		(width 0.16002)
		(layer "In2.Cu")
		(net "M_I_CPU0_SB_DQS_DN<6>")
	)
	(segment
		(start 403.090126 -287.860232)
		(end 403.818598 -287.860232)
		(width 0.16002)
		(layer "In2.Cu")
		(net "M_I_CPU0_SB_DQS_DN<6>")
	)
	(segment
		(start 423.242486 -295.507918)
		(end 425.065698 -295.507918)
		(width 0.16002)
		(layer "In2.Cu")
		(net "M_I_CPU0_SB_DQS_DN<6>")
	)
	(segment
		(start 406.565862 -290.607496)
		(end 406.977342 -291.018976)
		(width 0.16002)
		(layer "In2.Cu")
		(net "M_I_CPU0_SB_DQS_DN<6>")
	)
	(segment
		(start 393.707874 -281.625294)
		(end 393.959842 -281.877262)
		(width 0.09525)
		(layer "In2.Cu")
		(net "M_I_CPU0_SB_DQS_DN<6>")
	)
	(segment
		(start 405.19223 -289.233864)
		(end 405.60371 -289.645344)
		(width 0.16002)
		(layer "In2.Cu")
		(net "M_I_CPU0_SB_DQS_DN<6>")
	)
	(segment
		(start 402.444966 -286.4866)
		(end 402.856446 -286.89808)
		(width 0.16002)
		(layer "In2.Cu")
		(net "M_I_CPU0_SB_DQS_DN<6>")
	)
	(segment
		(start 379.934978 -281.706066)
		(end 379.94336 -281.70124)
		(width 0.09525)
		(layer "In2.Cu")
		(net "M_I_CPU0_SB_DQS_DN<6>")
	)
	(arc
		(start 379.94336 -281.70124)
		(mid 380.224792 -281.625485)
		(end 380.506224 -281.70124)
		(width 0.09525)
		(layer "In2.Cu")
		(net "M_I_CPU0_SB_DQS_DN<6>")
	)
	(arc
		(start 384.266186 -281.70124)
		(mid 384.449961 -281.752012)
		(end 384.634994 -281.706066)
		(width 0.09525)
		(layer "In2.Cu")
		(net "M_I_CPU0_SB_DQS_DN<6>")
	)
	(arc
		(start 388.026148 -281.70124)
		(mid 388.209923 -281.752012)
		(end 388.394956 -281.706066)
		(width 0.09525)
		(layer "In2.Cu")
		(net "M_I_CPU0_SB_DQS_DN<6>")
	)
	(arc
		(start 387.463284 -281.70124)
		(mid 387.744716 -281.625485)
		(end 388.026148 -281.70124)
		(width 0.09525)
		(layer "In2.Cu")
		(net "M_I_CPU0_SB_DQS_DN<6>")
	)
	(arc
		(start 392.74623 -281.714702)
		(mid 392.925418 -281.752547)
		(end 393.101322 -281.701494)
		(width 0.09525)
		(layer "In2.Cu")
		(net "M_I_CPU0_SB_DQS_DN<6>")
	)
	(arc
		(start 386.523484 -281.70124)
		(mid 386.804916 -281.625485)
		(end 387.086348 -281.70124)
		(width 0.09525)
		(layer "In2.Cu")
		(net "M_I_CPU0_SB_DQS_DN<6>")
	)
	(arc
		(start 388.966202 -281.70124)
		(mid 389.149977 -281.752012)
		(end 389.33501 -281.706066)
		(width 0.09525)
		(layer "In2.Cu")
		(net "M_I_CPU0_SB_DQS_DN<6>")
	)
	(arc
		(start 377.123452 -281.70124)
		(mid 377.404884 -281.625485)
		(end 377.686316 -281.70124)
		(width 0.09525)
		(layer "In2.Cu")
		(net "M_I_CPU0_SB_DQS_DN<6>")
	)
	(arc
		(start 392.187938 -281.686)
		(mid 392.457344 -281.625652)
		(end 392.722862 -281.70124)
		(width 0.09525)
		(layer "In2.Cu")
		(net "M_I_CPU0_SB_DQS_DN<6>")
	)
	(arc
		(start 378.063506 -281.70124)
		(mid 378.344938 -281.625485)
		(end 378.62637 -281.70124)
		(width 0.09525)
		(layer "In2.Cu")
		(net "M_I_CPU0_SB_DQS_DN<6>")
	)
	(arc
		(start 384.643376 -281.70124)
		(mid 384.924808 -281.625485)
		(end 385.20624 -281.70124)
		(width 0.09525)
		(layer "In2.Cu")
		(net "M_I_CPU0_SB_DQS_DN<6>")
	)
	(arc
		(start 389.914638 -281.706066)
		(mid 390.09967 -281.75198)
		(end 390.283446 -281.70124)
		(width 0.09525)
		(layer "In2.Cu")
		(net "M_I_CPU0_SB_DQS_DN<6>")
	)
	(arc
		(start 378.62637 -281.70124)
		(mid 378.814838 -281.751917)
		(end 379.003306 -281.70124)
		(width 0.09525)
		(layer "In2.Cu")
		(net "M_I_CPU0_SB_DQS_DN<6>")
	)
	(arc
		(start 382.763268 -281.70124)
		(mid 383.0447 -281.625485)
		(end 383.326132 -281.70124)
		(width 0.09525)
		(layer "In2.Cu")
		(net "M_I_CPU0_SB_DQS_DN<6>")
	)
	(arc
		(start 380.506224 -281.70124)
		(mid 380.689999 -281.752012)
		(end 380.875032 -281.706066)
		(width 0.09525)
		(layer "In2.Cu")
		(net "M_I_CPU0_SB_DQS_DN<6>")
	)
	(arc
		(start 381.823468 -281.70124)
		(mid 382.1049 -281.625485)
		(end 382.386332 -281.70124)
		(width 0.09525)
		(layer "In2.Cu")
		(net "M_I_CPU0_SB_DQS_DN<6>")
	)
	(arc
		(start 388.403338 -281.70124)
		(mid 388.68477 -281.625485)
		(end 388.966202 -281.70124)
		(width 0.09525)
		(layer "In2.Cu")
		(net "M_I_CPU0_SB_DQS_DN<6>")
	)
	(arc
		(start 379.003306 -281.70124)
		(mid 379.284738 -281.625485)
		(end 379.56617 -281.70124)
		(width 0.09525)
		(layer "In2.Cu")
		(net "M_I_CPU0_SB_DQS_DN<6>")
	)
	(arc
		(start 379.56617 -281.70124)
		(mid 379.749945 -281.752012)
		(end 379.934978 -281.706066)
		(width 0.09525)
		(layer "In2.Cu")
		(net "M_I_CPU0_SB_DQS_DN<6>")
	)
	(arc
		(start 391.223246 -281.70124)
		(mid 391.504678 -281.625485)
		(end 391.78611 -281.70124)
		(width 0.09525)
		(layer "In2.Cu")
		(net "M_I_CPU0_SB_DQS_DN<6>")
	)
	(arc
		(start 383.703322 -281.70124)
		(mid 383.984754 -281.625485)
		(end 384.266186 -281.70124)
		(width 0.09525)
		(layer "In2.Cu")
		(net "M_I_CPU0_SB_DQS_DN<6>")
	)
	(arc
		(start 387.086348 -281.70124)
		(mid 387.274816 -281.751917)
		(end 387.463284 -281.70124)
		(width 0.09525)
		(layer "In2.Cu")
		(net "M_I_CPU0_SB_DQS_DN<6>")
	)
	(arc
		(start 376.754644 -281.706066)
		(mid 376.939676 -281.75198)
		(end 377.123452 -281.70124)
		(width 0.09525)
		(layer "In2.Cu")
		(net "M_I_CPU0_SB_DQS_DN<6>")
	)
	(arc
		(start 391.78611 -281.70124)
		(mid 391.960742 -281.75178)
		(end 392.138662 -281.714448)
		(width 0.09525)
		(layer "In2.Cu")
		(net "M_I_CPU0_SB_DQS_DN<6>")
	)
	(arc
		(start 377.694698 -281.706066)
		(mid 377.87973 -281.75198)
		(end 378.063506 -281.70124)
		(width 0.09525)
		(layer "In2.Cu")
		(net "M_I_CPU0_SB_DQS_DN<6>")
	)
	(arc
		(start 390.283446 -281.70124)
		(mid 390.564878 -281.625485)
		(end 390.84631 -281.70124)
		(width 0.09525)
		(layer "In2.Cu")
		(net "M_I_CPU0_SB_DQS_DN<6>")
	)
	(arc
		(start 376.249692 -281.66822)
		(mid 376.501833 -281.62665)
		(end 376.746262 -281.70124)
		(width 0.09525)
		(layer "In2.Cu")
		(net "M_I_CPU0_SB_DQS_DN<6>")
	)
	(arc
		(start 390.84631 -281.70124)
		(mid 391.034778 -281.751917)
		(end 391.223246 -281.70124)
		(width 0.09525)
		(layer "In2.Cu")
		(net "M_I_CPU0_SB_DQS_DN<6>")
	)
	(arc
		(start 385.58343 -281.70124)
		(mid 385.864862 -281.625485)
		(end 386.146294 -281.70124)
		(width 0.09525)
		(layer "In2.Cu")
		(net "M_I_CPU0_SB_DQS_DN<6>")
	)
	(arc
		(start 382.386332 -281.70124)
		(mid 382.5748 -281.751917)
		(end 382.763268 -281.70124)
		(width 0.09525)
		(layer "In2.Cu")
		(net "M_I_CPU0_SB_DQS_DN<6>")
	)
	(arc
		(start 386.154676 -281.706066)
		(mid 386.339708 -281.75198)
		(end 386.523484 -281.70124)
		(width 0.09525)
		(layer "In2.Cu")
		(net "M_I_CPU0_SB_DQS_DN<6>")
	)
	(arc
		(start 380.883414 -281.70124)
		(mid 381.164846 -281.625485)
		(end 381.446278 -281.70124)
		(width 0.09525)
		(layer "In2.Cu")
		(net "M_I_CPU0_SB_DQS_DN<6>")
	)
	(arc
		(start 393.101322 -281.701494)
		(mid 393.237935 -281.644163)
		(end 393.384786 -281.624532)
		(width 0.09525)
		(layer "In2.Cu")
		(net "M_I_CPU0_SB_DQS_DN<6>")
	)
	(arc
		(start 385.214622 -281.706066)
		(mid 385.399654 -281.75198)
		(end 385.58343 -281.70124)
		(width 0.09525)
		(layer "In2.Cu")
		(net "M_I_CPU0_SB_DQS_DN<6>")
	)
	(arc
		(start 383.326132 -281.70124)
		(mid 383.509907 -281.752012)
		(end 383.69494 -281.706066)
		(width 0.09525)
		(layer "In2.Cu")
		(net "M_I_CPU0_SB_DQS_DN<6>")
	)
	(arc
		(start 389.343392 -281.70124)
		(mid 389.624824 -281.625485)
		(end 389.906256 -281.70124)
		(width 0.09525)
		(layer "In2.Cu")
		(net "M_I_CPU0_SB_DQS_DN<6>")
	)
	(arc
		(start 381.45466 -281.706066)
		(mid 381.639692 -281.75198)
		(end 381.823468 -281.70124)
		(width 0.09525)
		(layer "In2.Cu")
		(net "M_I_CPU0_SB_DQS_DN<6>")
	)
	(segment
		(start 375.528078 -276.250146)
		(end 375.99493 -276.516084)
		(width 0.12954)
		(layer "F.Cu")
		(net "M_I_CPU0_SB_DQS_DN<5>")
	)
	(segment
		(start 408.127962 -283.649674)
		(end 405.30145 -280.823162)
		(width 0.16002)
		(layer "In2.Cu")
		(net "M_I_CPU0_SB_DQS_DN<5>")
	)
	(segment
		(start 404.543768 -280.594816)
		(end 404.543768 -280.104596)
		(width 0.16002)
		(layer "In2.Cu")
		(net "M_I_CPU0_SB_DQS_DN<5>")
	)
	(segment
		(start 399.991326 -275.815806)
		(end 395.859254 -275.815806)
		(width 0.16002)
		(layer "In2.Cu")
		(net "M_I_CPU0_SB_DQS_DN<5>")
	)
	(segment
		(start 413.498284 -286.643064)
		(end 413.13354 -287.007808)
		(width 0.16002)
		(layer "In2.Cu")
		(net "M_I_CPU0_SB_DQS_DN<5>")
	)
	(segment
		(start 408.736546 -283.649674)
		(end 408.127962 -283.649674)
		(width 0.16002)
		(layer "In2.Cu")
		(net "M_I_CPU0_SB_DQS_DN<5>")
	)
	(segment
		(start 401.247356 -276.808184)
		(end 400.757136 -276.808184)
		(width 0.16002)
		(layer "In2.Cu")
		(net "M_I_CPU0_SB_DQS_DN<5>")
	)
	(segment
		(start 401.796504 -277.847552)
		(end 401.796504 -277.357332)
		(width 0.16002)
		(layer "In2.Cu")
		(net "M_I_CPU0_SB_DQS_DN<5>")
	)
	(segment
		(start 413.13354 -287.007808)
		(end 411.486096 -287.007808)
		(width 0.16002)
		(layer "In2.Cu")
		(net "M_I_CPU0_SB_DQS_DN<5>")
	)
	(segment
		(start 376.148854 -276.781514)
		(end 375.99493 -276.516084)
		(width 0.09525)
		(layer "In2.Cu")
		(net "M_I_CPU0_SB_DQS_DN<5>")
	)
	(segment
		(start 418.161978 -286.157924)
		(end 415.698432 -286.157924)
		(width 0.16002)
		(layer "In2.Cu")
		(net "M_I_CPU0_SB_DQS_DN<5>")
	)
	(segment
		(start 402.130768 -278.181816)
		(end 401.796504 -277.847552)
		(width 0.16002)
		(layer "In2.Cu")
		(net "M_I_CPU0_SB_DQS_DN<5>")
	)
	(segment
		(start 403.170136 -278.730964)
		(end 402.620988 -278.181816)
		(width 0.16002)
		(layer "In2.Cu")
		(net "M_I_CPU0_SB_DQS_DN<5>")
	)
	(segment
		(start 404.543768 -280.104596)
		(end 403.99462 -279.555448)
		(width 0.16002)
		(layer "In2.Cu")
		(net "M_I_CPU0_SB_DQS_DN<5>")
	)
	(segment
		(start 376.754644 -276.84603)
		(end 376.746262 -276.841204)
		(width 0.09525)
		(layer "In2.Cu")
		(net "M_I_CPU0_SB_DQS_DN<5>")
	)
	(segment
		(start 410.59862 -286.120332)
		(end 410.59862 -285.511748)
		(width 0.16002)
		(layer "In2.Cu")
		(net "M_I_CPU0_SB_DQS_DN<5>")
	)
	(segment
		(start 376.249692 -276.808184)
		(end 376.148854 -276.781514)
		(width 0.09525)
		(layer "In2.Cu")
		(net "M_I_CPU0_SB_DQS_DN<5>")
	)
	(segment
		(start 385.214622 -276.84603)
		(end 385.20624 -276.841204)
		(width 0.09525)
		(layer "In2.Cu")
		(net "M_I_CPU0_SB_DQS_DN<5>")
	)
	(segment
		(start 410.09824 -285.011368)
		(end 409.489656 -285.011368)
		(width 0.16002)
		(layer "In2.Cu")
		(net "M_I_CPU0_SB_DQS_DN<5>")
	)
	(segment
		(start 409.21305 -284.126178)
		(end 408.736546 -283.649674)
		(width 0.16002)
		(layer "In2.Cu")
		(net "M_I_CPU0_SB_DQS_DN<5>")
	)
	(segment
		(start 392.187938 -276.825964)
		(end 392.16203 -276.84095)
		(width 0.09525)
		(layer "In2.Cu")
		(net "M_I_CPU0_SB_DQS_DN<5>")
	)
	(segment
		(start 405.30145 -280.823162)
		(end 404.772114 -280.823162)
		(width 0.16002)
		(layer "In2.Cu")
		(net "M_I_CPU0_SB_DQS_DN<5>")
	)
	(segment
		(start 400.757136 -276.808184)
		(end 400.328638 -276.379686)
		(width 0.16002)
		(layer "In2.Cu")
		(net "M_I_CPU0_SB_DQS_DN<5>")
	)
	(segment
		(start 384.643376 -276.841204)
		(end 384.634994 -276.84603)
		(width 0.09525)
		(layer "In2.Cu")
		(net "M_I_CPU0_SB_DQS_DN<5>")
	)
	(segment
		(start 427.181518 -286.009588)
		(end 425.214034 -286.009588)
		(width 0.16002)
		(layer "In2.Cu")
		(net "M_I_CPU0_SB_DQS_DN<5>")
	)
	(segment
		(start 389.343392 -276.841204)
		(end 389.33501 -276.84603)
		(width 0.09525)
		(layer "In2.Cu")
		(net "M_I_CPU0_SB_DQS_DN<5>")
	)
	(segment
		(start 409.489656 -285.011368)
		(end 409.21305 -284.734762)
		(width 0.16002)
		(layer "In2.Cu")
		(net "M_I_CPU0_SB_DQS_DN<5>")
	)
	(segment
		(start 423.242486 -286.157924)
		(end 422.841928 -285.757366)
		(width 0.16002)
		(layer "In2.Cu")
		(net "M_I_CPU0_SB_DQS_DN<5>")
	)
	(segment
		(start 392.74623 -276.854666)
		(end 392.722862 -276.841204)
		(width 0.09525)
		(layer "In2.Cu")
		(net "M_I_CPU0_SB_DQS_DN<5>")
	)
	(segment
		(start 386.154676 -276.84603)
		(end 386.146294 -276.841204)
		(width 0.09525)
		(layer "In2.Cu")
		(net "M_I_CPU0_SB_DQS_DN<5>")
	)
	(segment
		(start 421.042338 -286.643064)
		(end 420.67734 -287.008062)
		(width 0.16002)
		(layer "In2.Cu")
		(net "M_I_CPU0_SB_DQS_DN<5>")
	)
	(segment
		(start 381.45466 -276.84603)
		(end 381.446278 -276.841204)
		(width 0.09525)
		(layer "In2.Cu")
		(net "M_I_CPU0_SB_DQS_DN<5>")
	)
	(segment
		(start 380.883414 -276.841204)
		(end 380.875032 -276.84603)
		(width 0.09525)
		(layer "In2.Cu")
		(net "M_I_CPU0_SB_DQS_DN<5>")
	)
	(segment
		(start 414.820862 -285.757366)
		(end 413.935164 -286.643064)
		(width 0.16002)
		(layer "In2.Cu")
		(net "M_I_CPU0_SB_DQS_DN<5>")
	)
	(segment
		(start 400.328638 -276.379686)
		(end 400.328638 -276.153118)
		(width 0.16002)
		(layer "In2.Cu")
		(net "M_I_CPU0_SB_DQS_DN<5>")
	)
	(segment
		(start 415.698432 -286.157924)
		(end 415.297874 -285.757366)
		(width 0.16002)
		(layer "In2.Cu")
		(net "M_I_CPU0_SB_DQS_DN<5>")
	)
	(segment
		(start 393.781026 -276.61997)
		(end 393.635992 -276.61997)
		(width 0.09525)
		(layer "In2.Cu")
		(net "M_I_CPU0_SB_DQS_DN<5>")
	)
	(segment
		(start 420.67734 -287.008062)
		(end 419.012116 -287.008062)
		(width 0.16002)
		(layer "In2.Cu")
		(net "M_I_CPU0_SB_DQS_DN<5>")
	)
	(segment
		(start 410.59862 -285.511748)
		(end 410.09824 -285.011368)
		(width 0.16002)
		(layer "In2.Cu")
		(net "M_I_CPU0_SB_DQS_DN<5>")
	)
	(segment
		(start 422.364916 -285.757366)
		(end 421.479218 -286.643064)
		(width 0.16002)
		(layer "In2.Cu")
		(net "M_I_CPU0_SB_DQS_DN<5>")
	)
	(segment
		(start 403.99462 -279.555448)
		(end 403.5044 -279.555448)
		(width 0.16002)
		(layer "In2.Cu")
		(net "M_I_CPU0_SB_DQS_DN<5>")
	)
	(segment
		(start 395.859254 -275.815806)
		(end 395.835632 -275.815806)
		(width 0.09525)
		(layer "In2.Cu")
		(net "M_I_CPU0_SB_DQS_DN<5>")
	)
	(segment
		(start 395.135862 -275.5773)
		(end 394.823696 -275.5773)
		(width 0.09525)
		(layer "In2.Cu")
		(net "M_I_CPU0_SB_DQS_DN<5>")
	)
	(segment
		(start 395.43355 -275.874988)
		(end 395.135862 -275.5773)
		(width 0.09525)
		(layer "In2.Cu")
		(net "M_I_CPU0_SB_DQS_DN<5>")
	)
	(segment
		(start 392.16203 -276.84095)
		(end 392.138662 -276.854412)
		(width 0.09525)
		(layer "In2.Cu")
		(net "M_I_CPU0_SB_DQS_DN<5>")
	)
	(segment
		(start 383.703322 -276.841204)
		(end 383.69494 -276.84603)
		(width 0.09525)
		(layer "In2.Cu")
		(net "M_I_CPU0_SB_DQS_DN<5>")
	)
	(segment
		(start 400.328638 -276.153118)
		(end 399.991326 -275.815806)
		(width 0.16002)
		(layer "In2.Cu")
		(net "M_I_CPU0_SB_DQS_DN<5>")
	)
	(segment
		(start 425.214034 -286.009588)
		(end 425.065698 -286.157924)
		(width 0.16002)
		(layer "In2.Cu")
		(net "M_I_CPU0_SB_DQS_DN<5>")
	)
	(segment
		(start 421.479218 -286.643064)
		(end 421.042338 -286.643064)
		(width 0.16002)
		(layer "In2.Cu")
		(net "M_I_CPU0_SB_DQS_DN<5>")
	)
	(segment
		(start 413.935164 -286.643064)
		(end 413.498284 -286.643064)
		(width 0.16002)
		(layer "In2.Cu")
		(net "M_I_CPU0_SB_DQS_DN<5>")
	)
	(segment
		(start 401.796504 -277.357332)
		(end 401.247356 -276.808184)
		(width 0.16002)
		(layer "In2.Cu")
		(net "M_I_CPU0_SB_DQS_DN<5>")
	)
	(segment
		(start 425.065698 -286.157924)
		(end 423.242486 -286.157924)
		(width 0.16002)
		(layer "In2.Cu")
		(net "M_I_CPU0_SB_DQS_DN<5>")
	)
	(segment
		(start 404.772114 -280.823162)
		(end 404.543768 -280.594816)
		(width 0.16002)
		(layer "In2.Cu")
		(net "M_I_CPU0_SB_DQS_DN<5>")
	)
	(segment
		(start 427.456092 -285.735014)
		(end 427.181518 -286.009588)
		(width 0.16002)
		(layer "In2.Cu")
		(net "M_I_CPU0_SB_DQS_DN<5>")
	)
	(segment
		(start 403.170136 -279.221184)
		(end 403.170136 -278.730964)
		(width 0.16002)
		(layer "In2.Cu")
		(net "M_I_CPU0_SB_DQS_DN<5>")
	)
	(segment
		(start 419.012116 -287.008062)
		(end 418.161978 -286.157924)
		(width 0.16002)
		(layer "In2.Cu")
		(net "M_I_CPU0_SB_DQS_DN<5>")
	)
	(segment
		(start 409.21305 -284.734762)
		(end 409.21305 -284.126178)
		(width 0.16002)
		(layer "In2.Cu")
		(net "M_I_CPU0_SB_DQS_DN<5>")
	)
	(segment
		(start 402.620988 -278.181816)
		(end 402.130768 -278.181816)
		(width 0.16002)
		(layer "In2.Cu")
		(net "M_I_CPU0_SB_DQS_DN<5>")
	)
	(segment
		(start 377.694698 -276.84603)
		(end 377.686316 -276.841204)
		(width 0.09525)
		(layer "In2.Cu")
		(net "M_I_CPU0_SB_DQS_DN<5>")
	)
	(segment
		(start 411.486096 -287.007808)
		(end 410.59862 -286.120332)
		(width 0.16002)
		(layer "In2.Cu")
		(net "M_I_CPU0_SB_DQS_DN<5>")
	)
	(segment
		(start 394.823696 -275.5773)
		(end 393.781026 -276.61997)
		(width 0.09525)
		(layer "In2.Cu")
		(net "M_I_CPU0_SB_DQS_DN<5>")
	)
	(segment
		(start 395.77645 -275.874988)
		(end 395.43355 -275.874988)
		(width 0.09525)
		(layer "In2.Cu")
		(net "M_I_CPU0_SB_DQS_DN<5>")
	)
	(segment
		(start 395.835632 -275.815806)
		(end 395.77645 -275.874988)
		(width 0.09525)
		(layer "In2.Cu")
		(net "M_I_CPU0_SB_DQS_DN<5>")
	)
	(segment
		(start 403.5044 -279.555448)
		(end 403.170136 -279.221184)
		(width 0.16002)
		(layer "In2.Cu")
		(net "M_I_CPU0_SB_DQS_DN<5>")
	)
	(segment
		(start 379.94336 -276.841204)
		(end 379.934978 -276.84603)
		(width 0.09525)
		(layer "In2.Cu")
		(net "M_I_CPU0_SB_DQS_DN<5>")
	)
	(segment
		(start 415.297874 -285.757366)
		(end 414.820862 -285.757366)
		(width 0.16002)
		(layer "In2.Cu")
		(net "M_I_CPU0_SB_DQS_DN<5>")
	)
	(segment
		(start 422.841928 -285.757366)
		(end 422.364916 -285.757366)
		(width 0.16002)
		(layer "In2.Cu")
		(net "M_I_CPU0_SB_DQS_DN<5>")
	)
	(segment
		(start 389.914638 -276.84603)
		(end 389.906256 -276.841204)
		(width 0.09525)
		(layer "In2.Cu")
		(net "M_I_CPU0_SB_DQS_DN<5>")
	)
	(segment
		(start 388.403338 -276.841204)
		(end 388.394956 -276.84603)
		(width 0.09525)
		(layer "In2.Cu")
		(net "M_I_CPU0_SB_DQS_DN<5>")
	)
	(arc
		(start 392.138662 -276.854412)
		(mid 391.960743 -276.891727)
		(end 391.78611 -276.841204)
		(width 0.09525)
		(layer "In2.Cu")
		(net "M_I_CPU0_SB_DQS_DN<5>")
	)
	(arc
		(start 386.523484 -276.841204)
		(mid 386.339709 -276.891976)
		(end 386.154676 -276.84603)
		(width 0.09525)
		(layer "In2.Cu")
		(net "M_I_CPU0_SB_DQS_DN<5>")
	)
	(arc
		(start 378.62637 -276.841204)
		(mid 378.344938 -276.765449)
		(end 378.063506 -276.841204)
		(width 0.09525)
		(layer "In2.Cu")
		(net "M_I_CPU0_SB_DQS_DN<5>")
	)
	(arc
		(start 383.69494 -276.84603)
		(mid 383.509908 -276.891944)
		(end 383.326132 -276.841204)
		(width 0.09525)
		(layer "In2.Cu")
		(net "M_I_CPU0_SB_DQS_DN<5>")
	)
	(arc
		(start 391.78611 -276.841204)
		(mid 391.504678 -276.765449)
		(end 391.223246 -276.841204)
		(width 0.09525)
		(layer "In2.Cu")
		(net "M_I_CPU0_SB_DQS_DN<5>")
	)
	(arc
		(start 390.84631 -276.841204)
		(mid 390.564878 -276.765449)
		(end 390.283446 -276.841204)
		(width 0.09525)
		(layer "In2.Cu")
		(net "M_I_CPU0_SB_DQS_DN<5>")
	)
	(arc
		(start 382.386332 -276.841204)
		(mid 382.1049 -276.765449)
		(end 381.823468 -276.841204)
		(width 0.09525)
		(layer "In2.Cu")
		(net "M_I_CPU0_SB_DQS_DN<5>")
	)
	(arc
		(start 380.875032 -276.84603)
		(mid 380.69 -276.891944)
		(end 380.506224 -276.841204)
		(width 0.09525)
		(layer "In2.Cu")
		(net "M_I_CPU0_SB_DQS_DN<5>")
	)
	(arc
		(start 381.823468 -276.841204)
		(mid 381.639693 -276.891976)
		(end 381.45466 -276.84603)
		(width 0.09525)
		(layer "In2.Cu")
		(net "M_I_CPU0_SB_DQS_DN<5>")
	)
	(arc
		(start 393.635992 -276.61997)
		(mid 393.346623 -276.677529)
		(end 393.101322 -276.841458)
		(width 0.09525)
		(layer "In2.Cu")
		(net "M_I_CPU0_SB_DQS_DN<5>")
	)
	(arc
		(start 386.146294 -276.841204)
		(mid 385.864862 -276.765449)
		(end 385.58343 -276.841204)
		(width 0.09525)
		(layer "In2.Cu")
		(net "M_I_CPU0_SB_DQS_DN<5>")
	)
	(arc
		(start 383.326132 -276.841204)
		(mid 383.0447 -276.765449)
		(end 382.763268 -276.841204)
		(width 0.09525)
		(layer "In2.Cu")
		(net "M_I_CPU0_SB_DQS_DN<5>")
	)
	(arc
		(start 392.722862 -276.841204)
		(mid 392.457342 -276.765675)
		(end 392.187938 -276.825964)
		(width 0.09525)
		(layer "In2.Cu")
		(net "M_I_CPU0_SB_DQS_DN<5>")
	)
	(arc
		(start 389.906256 -276.841204)
		(mid 389.624824 -276.765449)
		(end 389.343392 -276.841204)
		(width 0.09525)
		(layer "In2.Cu")
		(net "M_I_CPU0_SB_DQS_DN<5>")
	)
	(arc
		(start 380.506224 -276.841204)
		(mid 380.224792 -276.765449)
		(end 379.94336 -276.841204)
		(width 0.09525)
		(layer "In2.Cu")
		(net "M_I_CPU0_SB_DQS_DN<5>")
	)
	(arc
		(start 377.123452 -276.841204)
		(mid 376.939677 -276.891976)
		(end 376.754644 -276.84603)
		(width 0.09525)
		(layer "In2.Cu")
		(net "M_I_CPU0_SB_DQS_DN<5>")
	)
	(arc
		(start 384.634994 -276.84603)
		(mid 384.449962 -276.891944)
		(end 384.266186 -276.841204)
		(width 0.09525)
		(layer "In2.Cu")
		(net "M_I_CPU0_SB_DQS_DN<5>")
	)
	(arc
		(start 379.934978 -276.84603)
		(mid 379.749946 -276.891944)
		(end 379.56617 -276.841204)
		(width 0.09525)
		(layer "In2.Cu")
		(net "M_I_CPU0_SB_DQS_DN<5>")
	)
	(arc
		(start 385.20624 -276.841204)
		(mid 384.924808 -276.765449)
		(end 384.643376 -276.841204)
		(width 0.09525)
		(layer "In2.Cu")
		(net "M_I_CPU0_SB_DQS_DN<5>")
	)
	(arc
		(start 381.446278 -276.841204)
		(mid 381.164846 -276.765449)
		(end 380.883414 -276.841204)
		(width 0.09525)
		(layer "In2.Cu")
		(net "M_I_CPU0_SB_DQS_DN<5>")
	)
	(arc
		(start 388.026148 -276.841204)
		(mid 387.744716 -276.765449)
		(end 387.463284 -276.841204)
		(width 0.09525)
		(layer "In2.Cu")
		(net "M_I_CPU0_SB_DQS_DN<5>")
	)
	(arc
		(start 382.763268 -276.841204)
		(mid 382.5748 -276.891881)
		(end 382.386332 -276.841204)
		(width 0.09525)
		(layer "In2.Cu")
		(net "M_I_CPU0_SB_DQS_DN<5>")
	)
	(arc
		(start 387.463284 -276.841204)
		(mid 387.274816 -276.891881)
		(end 387.086348 -276.841204)
		(width 0.09525)
		(layer "In2.Cu")
		(net "M_I_CPU0_SB_DQS_DN<5>")
	)
	(arc
		(start 388.394956 -276.84603)
		(mid 388.209924 -276.891944)
		(end 388.026148 -276.841204)
		(width 0.09525)
		(layer "In2.Cu")
		(net "M_I_CPU0_SB_DQS_DN<5>")
	)
	(arc
		(start 376.269504 -276.80031)
		(mid 376.259561 -276.804153)
		(end 376.249692 -276.808184)
		(width 0.09525)
		(layer "In2.Cu")
		(net "M_I_CPU0_SB_DQS_DN<5>")
	)
	(arc
		(start 378.063506 -276.841204)
		(mid 377.879731 -276.891976)
		(end 377.694698 -276.84603)
		(width 0.09525)
		(layer "In2.Cu")
		(net "M_I_CPU0_SB_DQS_DN<5>")
	)
	(arc
		(start 379.003306 -276.841204)
		(mid 378.814838 -276.891881)
		(end 378.62637 -276.841204)
		(width 0.09525)
		(layer "In2.Cu")
		(net "M_I_CPU0_SB_DQS_DN<5>")
	)
	(arc
		(start 388.966202 -276.841204)
		(mid 388.68477 -276.765449)
		(end 388.403338 -276.841204)
		(width 0.09525)
		(layer "In2.Cu")
		(net "M_I_CPU0_SB_DQS_DN<5>")
	)
	(arc
		(start 387.086348 -276.841204)
		(mid 386.804916 -276.765449)
		(end 386.523484 -276.841204)
		(width 0.09525)
		(layer "In2.Cu")
		(net "M_I_CPU0_SB_DQS_DN<5>")
	)
	(arc
		(start 385.58343 -276.841204)
		(mid 385.399655 -276.891976)
		(end 385.214622 -276.84603)
		(width 0.09525)
		(layer "In2.Cu")
		(net "M_I_CPU0_SB_DQS_DN<5>")
	)
	(arc
		(start 390.283446 -276.841204)
		(mid 390.099671 -276.891976)
		(end 389.914638 -276.84603)
		(width 0.09525)
		(layer "In2.Cu")
		(net "M_I_CPU0_SB_DQS_DN<5>")
	)
	(arc
		(start 389.33501 -276.84603)
		(mid 389.149978 -276.891944)
		(end 388.966202 -276.841204)
		(width 0.09525)
		(layer "In2.Cu")
		(net "M_I_CPU0_SB_DQS_DN<5>")
	)
	(arc
		(start 377.686316 -276.841204)
		(mid 377.404884 -276.765449)
		(end 377.123452 -276.841204)
		(width 0.09525)
		(layer "In2.Cu")
		(net "M_I_CPU0_SB_DQS_DN<5>")
	)
	(arc
		(start 376.746262 -276.841204)
		(mid 376.512467 -276.767337)
		(end 376.269504 -276.80031)
		(width 0.09525)
		(layer "In2.Cu")
		(net "M_I_CPU0_SB_DQS_DN<5>")
	)
	(arc
		(start 379.56617 -276.841204)
		(mid 379.284738 -276.765449)
		(end 379.003306 -276.841204)
		(width 0.09525)
		(layer "In2.Cu")
		(net "M_I_CPU0_SB_DQS_DN<5>")
	)
	(arc
		(start 384.266186 -276.841204)
		(mid 383.984754 -276.765449)
		(end 383.703322 -276.841204)
		(width 0.09525)
		(layer "In2.Cu")
		(net "M_I_CPU0_SB_DQS_DN<5>")
	)
	(arc
		(start 393.101322 -276.841458)
		(mid 392.925421 -276.892603)
		(end 392.74623 -276.854666)
		(width 0.09525)
		(layer "In2.Cu")
		(net "M_I_CPU0_SB_DQS_DN<5>")
	)
	(arc
		(start 391.223246 -276.841204)
		(mid 391.034778 -276.891881)
		(end 390.84631 -276.841204)
		(width 0.09525)
		(layer "In2.Cu")
		(net "M_I_CPU0_SB_DQS_DN<5>")
	)
	(segment
		(start 375.528078 -271.39011)
		(end 375.99493 -271.656048)
		(width 0.12954)
		(layer "F.Cu")
		(net "M_I_CPU0_SB_DQS_DN<4>")
	)
	(segment
		(start 394.178536 -271.13992)
		(end 394.178536 -270.86814)
		(width 0.09525)
		(layer "In2.Cu")
		(net "M_I_CPU0_SB_DQS_DN<4>")
	)
	(segment
		(start 384.634994 -271.985994)
		(end 384.643376 -271.981168)
		(width 0.09525)
		(layer "In2.Cu")
		(net "M_I_CPU0_SB_DQS_DN<4>")
	)
	(segment
		(start 407.607262 -274.373848)
		(end 408.383994 -274.373848)
		(width 0.16002)
		(layer "In2.Cu")
		(net "M_I_CPU0_SB_DQS_DN<4>")
	)
	(segment
		(start 425.065698 -276.80793)
		(end 425.214034 -276.659594)
		(width 0.16002)
		(layer "In2.Cu")
		(net "M_I_CPU0_SB_DQS_DN<4>")
	)
	(segment
		(start 380.875032 -271.985994)
		(end 380.883414 -271.981168)
		(width 0.09525)
		(layer "In2.Cu")
		(net "M_I_CPU0_SB_DQS_DN<4>")
	)
	(segment
		(start 404.649686 -271.416272)
		(end 404.859998 -271.626584)
		(width 0.16002)
		(layer "In2.Cu")
		(net "M_I_CPU0_SB_DQS_DN<4>")
	)
	(segment
		(start 408.980894 -275.74748)
		(end 409.757626 -275.74748)
		(width 0.16002)
		(layer "In2.Cu")
		(net "M_I_CPU0_SB_DQS_DN<4>")
	)
	(segment
		(start 419.012116 -277.658068)
		(end 420.67734 -277.658068)
		(width 0.16002)
		(layer "In2.Cu")
		(net "M_I_CPU0_SB_DQS_DN<4>")
	)
	(segment
		(start 405.63673 -271.626584)
		(end 406.023318 -272.013172)
		(width 0.16002)
		(layer "In2.Cu")
		(net "M_I_CPU0_SB_DQS_DN<4>")
	)
	(segment
		(start 392.138662 -271.994376)
		(end 392.16203 -271.980914)
		(width 0.09525)
		(layer "In2.Cu")
		(net "M_I_CPU0_SB_DQS_DN<4>")
	)
	(segment
		(start 422.935146 -276.50059)
		(end 423.242486 -276.80793)
		(width 0.16002)
		(layer "In2.Cu")
		(net "M_I_CPU0_SB_DQS_DN<4>")
	)
	(segment
		(start 389.906256 -271.981168)
		(end 389.914638 -271.985994)
		(width 0.09525)
		(layer "In2.Cu")
		(net "M_I_CPU0_SB_DQS_DN<4>")
	)
	(segment
		(start 393.387326 -271.905222)
		(end 393.44854 -271.905222)
		(width 0.09525)
		(layer "In2.Cu")
		(net "M_I_CPU0_SB_DQS_DN<4>")
	)
	(segment
		(start 411.3911 -277.657814)
		(end 413.13354 -277.657814)
		(width 0.16002)
		(layer "In2.Cu")
		(net "M_I_CPU0_SB_DQS_DN<4>")
	)
	(segment
		(start 389.33501 -271.985994)
		(end 389.343392 -271.981168)
		(width 0.09525)
		(layer "In2.Cu")
		(net "M_I_CPU0_SB_DQS_DN<4>")
	)
	(segment
		(start 425.214034 -276.659594)
		(end 427.181518 -276.659594)
		(width 0.16002)
		(layer "In2.Cu")
		(net "M_I_CPU0_SB_DQS_DN<4>")
	)
	(segment
		(start 386.146294 -271.981168)
		(end 386.154676 -271.985994)
		(width 0.09525)
		(layer "In2.Cu")
		(net "M_I_CPU0_SB_DQS_DN<4>")
	)
	(segment
		(start 415.391092 -276.50059)
		(end 415.698432 -276.80793)
		(width 0.16002)
		(layer "In2.Cu")
		(net "M_I_CPU0_SB_DQS_DN<4>")
	)
	(segment
		(start 406.023318 -272.789904)
		(end 406.23363 -273.000216)
		(width 0.16002)
		(layer "In2.Cu")
		(net "M_I_CPU0_SB_DQS_DN<4>")
	)
	(segment
		(start 407.39695 -274.163536)
		(end 407.607262 -274.373848)
		(width 0.16002)
		(layer "In2.Cu")
		(net "M_I_CPU0_SB_DQS_DN<4>")
	)
	(segment
		(start 375.99493 -271.656048)
		(end 376.148854 -271.921478)
		(width 0.09525)
		(layer "In2.Cu")
		(net "M_I_CPU0_SB_DQS_DN<4>")
	)
	(segment
		(start 395.633194 -270.14424)
		(end 404.154386 -270.14424)
		(width 0.16002)
		(layer "In2.Cu")
		(net "M_I_CPU0_SB_DQS_DN<4>")
	)
	(segment
		(start 410.854398 -277.121112)
		(end 411.3911 -277.657814)
		(width 0.16002)
		(layer "In2.Cu")
		(net "M_I_CPU0_SB_DQS_DN<4>")
	)
	(segment
		(start 408.383994 -274.373848)
		(end 408.770582 -274.760436)
		(width 0.16002)
		(layer "In2.Cu")
		(net "M_I_CPU0_SB_DQS_DN<4>")
	)
	(segment
		(start 420.67734 -277.658068)
		(end 421.042338 -277.29307)
		(width 0.16002)
		(layer "In2.Cu")
		(net "M_I_CPU0_SB_DQS_DN<4>")
	)
	(segment
		(start 381.446278 -271.981168)
		(end 381.45466 -271.985994)
		(width 0.09525)
		(layer "In2.Cu")
		(net "M_I_CPU0_SB_DQS_DN<4>")
	)
	(segment
		(start 413.13354 -277.657814)
		(end 413.498284 -277.29307)
		(width 0.16002)
		(layer "In2.Cu")
		(net "M_I_CPU0_SB_DQS_DN<4>")
	)
	(segment
		(start 404.154386 -270.14424)
		(end 404.649686 -270.63954)
		(width 0.16002)
		(layer "In2.Cu")
		(net "M_I_CPU0_SB_DQS_DN<4>")
	)
	(segment
		(start 410.354526 -277.121112)
		(end 410.854398 -277.121112)
		(width 0.16002)
		(layer "In2.Cu")
		(net "M_I_CPU0_SB_DQS_DN<4>")
	)
	(segment
		(start 385.20624 -271.981168)
		(end 385.214622 -271.985994)
		(width 0.09525)
		(layer "In2.Cu")
		(net "M_I_CPU0_SB_DQS_DN<4>")
	)
	(segment
		(start 388.394956 -271.985994)
		(end 388.403338 -271.981168)
		(width 0.09525)
		(layer "In2.Cu")
		(net "M_I_CPU0_SB_DQS_DN<4>")
	)
	(segment
		(start 407.010362 -273.000216)
		(end 407.39695 -273.386804)
		(width 0.16002)
		(layer "In2.Cu")
		(net "M_I_CPU0_SB_DQS_DN<4>")
	)
	(segment
		(start 392.16203 -271.980914)
		(end 392.187938 -271.965928)
		(width 0.09525)
		(layer "In2.Cu")
		(net "M_I_CPU0_SB_DQS_DN<4>")
	)
	(segment
		(start 379.934978 -271.985994)
		(end 379.94336 -271.981168)
		(width 0.09525)
		(layer "In2.Cu")
		(net "M_I_CPU0_SB_DQS_DN<4>")
	)
	(segment
		(start 406.23363 -273.000216)
		(end 407.010362 -273.000216)
		(width 0.16002)
		(layer "In2.Cu")
		(net "M_I_CPU0_SB_DQS_DN<4>")
	)
	(segment
		(start 404.859998 -271.626584)
		(end 405.63673 -271.626584)
		(width 0.16002)
		(layer "In2.Cu")
		(net "M_I_CPU0_SB_DQS_DN<4>")
	)
	(segment
		(start 394.843254 -270.203422)
		(end 395.55039 -270.203422)
		(width 0.09525)
		(layer "In2.Cu")
		(net "M_I_CPU0_SB_DQS_DN<4>")
	)
	(segment
		(start 376.148854 -271.921478)
		(end 376.249692 -271.948148)
		(width 0.09525)
		(layer "In2.Cu")
		(net "M_I_CPU0_SB_DQS_DN<4>")
	)
	(segment
		(start 423.242486 -276.80793)
		(end 425.065698 -276.80793)
		(width 0.16002)
		(layer "In2.Cu")
		(net "M_I_CPU0_SB_DQS_DN<4>")
	)
	(segment
		(start 395.609572 -270.14424)
		(end 395.633194 -270.14424)
		(width 0.09525)
		(layer "In2.Cu")
		(net "M_I_CPU0_SB_DQS_DN<4>")
	)
	(segment
		(start 418.161978 -276.80793)
		(end 419.012116 -277.658068)
		(width 0.16002)
		(layer "In2.Cu")
		(net "M_I_CPU0_SB_DQS_DN<4>")
	)
	(segment
		(start 393.574524 -271.852898)
		(end 394.101574 -271.325848)
		(width 0.09525)
		(layer "In2.Cu")
		(net "M_I_CPU0_SB_DQS_DN<4>")
	)
	(segment
		(start 414.727644 -276.50059)
		(end 415.391092 -276.50059)
		(width 0.16002)
		(layer "In2.Cu")
		(net "M_I_CPU0_SB_DQS_DN<4>")
	)
	(segment
		(start 421.042338 -277.29307)
		(end 421.479218 -277.29307)
		(width 0.16002)
		(layer "In2.Cu")
		(net "M_I_CPU0_SB_DQS_DN<4>")
	)
	(segment
		(start 413.935164 -277.29307)
		(end 414.727644 -276.50059)
		(width 0.16002)
		(layer "In2.Cu")
		(net "M_I_CPU0_SB_DQS_DN<4>")
	)
	(segment
		(start 394.178536 -270.86814)
		(end 394.843254 -270.203422)
		(width 0.09525)
		(layer "In2.Cu")
		(net "M_I_CPU0_SB_DQS_DN<4>")
	)
	(segment
		(start 415.698432 -276.80793)
		(end 418.161978 -276.80793)
		(width 0.16002)
		(layer "In2.Cu")
		(net "M_I_CPU0_SB_DQS_DN<4>")
	)
	(segment
		(start 404.649686 -270.63954)
		(end 404.649686 -271.416272)
		(width 0.16002)
		(layer "In2.Cu")
		(net "M_I_CPU0_SB_DQS_DN<4>")
	)
	(segment
		(start 409.757626 -275.74748)
		(end 410.144214 -276.134068)
		(width 0.16002)
		(layer "In2.Cu")
		(net "M_I_CPU0_SB_DQS_DN<4>")
	)
	(segment
		(start 392.722862 -271.981168)
		(end 392.74623 -271.99463)
		(width 0.09525)
		(layer "In2.Cu")
		(net "M_I_CPU0_SB_DQS_DN<4>")
	)
	(segment
		(start 422.271698 -276.50059)
		(end 422.935146 -276.50059)
		(width 0.16002)
		(layer "In2.Cu")
		(net "M_I_CPU0_SB_DQS_DN<4>")
	)
	(segment
		(start 410.144214 -276.134068)
		(end 410.144214 -276.9108)
		(width 0.16002)
		(layer "In2.Cu")
		(net "M_I_CPU0_SB_DQS_DN<4>")
	)
	(segment
		(start 406.023318 -272.013172)
		(end 406.023318 -272.789904)
		(width 0.16002)
		(layer "In2.Cu")
		(net "M_I_CPU0_SB_DQS_DN<4>")
	)
	(segment
		(start 393.101322 -271.981422)
		(end 393.10183 -271.981676)
		(width 0.09525)
		(layer "In2.Cu")
		(net "M_I_CPU0_SB_DQS_DN<4>")
	)
	(segment
		(start 421.479218 -277.29307)
		(end 422.271698 -276.50059)
		(width 0.16002)
		(layer "In2.Cu")
		(net "M_I_CPU0_SB_DQS_DN<4>")
	)
	(segment
		(start 376.746262 -271.981168)
		(end 376.754644 -271.985994)
		(width 0.09525)
		(layer "In2.Cu")
		(net "M_I_CPU0_SB_DQS_DN<4>")
	)
	(segment
		(start 410.144214 -276.9108)
		(end 410.354526 -277.121112)
		(width 0.16002)
		(layer "In2.Cu")
		(net "M_I_CPU0_SB_DQS_DN<4>")
	)
	(segment
		(start 408.770582 -274.760436)
		(end 408.770582 -275.537168)
		(width 0.16002)
		(layer "In2.Cu")
		(net "M_I_CPU0_SB_DQS_DN<4>")
	)
	(segment
		(start 395.55039 -270.203422)
		(end 395.609572 -270.14424)
		(width 0.09525)
		(layer "In2.Cu")
		(net "M_I_CPU0_SB_DQS_DN<4>")
	)
	(segment
		(start 427.181518 -276.659594)
		(end 427.456092 -276.38502)
		(width 0.16002)
		(layer "In2.Cu")
		(net "M_I_CPU0_SB_DQS_DN<4>")
	)
	(segment
		(start 393.44854 -271.905222)
		(end 393.574524 -271.852898)
		(width 0.09525)
		(layer "In2.Cu")
		(net "M_I_CPU0_SB_DQS_DN<4>")
	)
	(segment
		(start 383.69494 -271.985994)
		(end 383.703322 -271.981168)
		(width 0.09525)
		(layer "In2.Cu")
		(net "M_I_CPU0_SB_DQS_DN<4>")
	)
	(segment
		(start 413.498284 -277.29307)
		(end 413.935164 -277.29307)
		(width 0.16002)
		(layer "In2.Cu")
		(net "M_I_CPU0_SB_DQS_DN<4>")
	)
	(segment
		(start 407.39695 -273.386804)
		(end 407.39695 -274.163536)
		(width 0.16002)
		(layer "In2.Cu")
		(net "M_I_CPU0_SB_DQS_DN<4>")
	)
	(segment
		(start 377.686316 -271.981168)
		(end 377.694698 -271.985994)
		(width 0.09525)
		(layer "In2.Cu")
		(net "M_I_CPU0_SB_DQS_DN<4>")
	)
	(segment
		(start 394.101574 -271.325848)
		(end 394.178536 -271.13992)
		(width 0.09525)
		(layer "In2.Cu")
		(net "M_I_CPU0_SB_DQS_DN<4>")
	)
	(segment
		(start 408.770582 -275.537168)
		(end 408.980894 -275.74748)
		(width 0.16002)
		(layer "In2.Cu")
		(net "M_I_CPU0_SB_DQS_DN<4>")
	)
	(arc
		(start 383.703322 -271.981168)
		(mid 383.984754 -271.905413)
		(end 384.266186 -271.981168)
		(width 0.09525)
		(layer "In2.Cu")
		(net "M_I_CPU0_SB_DQS_DN<4>")
	)
	(arc
		(start 387.086348 -271.981168)
		(mid 387.274816 -272.031845)
		(end 387.463284 -271.981168)
		(width 0.09525)
		(layer "In2.Cu")
		(net "M_I_CPU0_SB_DQS_DN<4>")
	)
	(arc
		(start 392.74623 -271.99463)
		(mid 392.925418 -272.032475)
		(end 393.101322 -271.981422)
		(width 0.09525)
		(layer "In2.Cu")
		(net "M_I_CPU0_SB_DQS_DN<4>")
	)
	(arc
		(start 389.914638 -271.985994)
		(mid 390.09967 -272.031908)
		(end 390.283446 -271.981168)
		(width 0.09525)
		(layer "In2.Cu")
		(net "M_I_CPU0_SB_DQS_DN<4>")
	)
	(arc
		(start 379.003306 -271.981168)
		(mid 379.284738 -271.905413)
		(end 379.56617 -271.981168)
		(width 0.09525)
		(layer "In2.Cu")
		(net "M_I_CPU0_SB_DQS_DN<4>")
	)
	(arc
		(start 382.763268 -271.981168)
		(mid 383.0447 -271.905413)
		(end 383.326132 -271.981168)
		(width 0.09525)
		(layer "In2.Cu")
		(net "M_I_CPU0_SB_DQS_DN<4>")
	)
	(arc
		(start 390.283446 -271.981168)
		(mid 390.564878 -271.905413)
		(end 390.84631 -271.981168)
		(width 0.09525)
		(layer "In2.Cu")
		(net "M_I_CPU0_SB_DQS_DN<4>")
	)
	(arc
		(start 377.123452 -271.981168)
		(mid 377.404884 -271.905413)
		(end 377.686316 -271.981168)
		(width 0.09525)
		(layer "In2.Cu")
		(net "M_I_CPU0_SB_DQS_DN<4>")
	)
	(arc
		(start 384.643376 -271.981168)
		(mid 384.924808 -271.905413)
		(end 385.20624 -271.981168)
		(width 0.09525)
		(layer "In2.Cu")
		(net "M_I_CPU0_SB_DQS_DN<4>")
	)
	(arc
		(start 380.883414 -271.981168)
		(mid 381.164846 -271.905413)
		(end 381.446278 -271.981168)
		(width 0.09525)
		(layer "In2.Cu")
		(net "M_I_CPU0_SB_DQS_DN<4>")
	)
	(arc
		(start 386.154676 -271.985994)
		(mid 386.339708 -272.031908)
		(end 386.523484 -271.981168)
		(width 0.09525)
		(layer "In2.Cu")
		(net "M_I_CPU0_SB_DQS_DN<4>")
	)
	(arc
		(start 376.754644 -271.985994)
		(mid 376.939676 -272.031908)
		(end 377.123452 -271.981168)
		(width 0.09525)
		(layer "In2.Cu")
		(net "M_I_CPU0_SB_DQS_DN<4>")
	)
	(arc
		(start 381.823468 -271.981168)
		(mid 382.1049 -271.905413)
		(end 382.386332 -271.981168)
		(width 0.09525)
		(layer "In2.Cu")
		(net "M_I_CPU0_SB_DQS_DN<4>")
	)
	(arc
		(start 388.403338 -271.981168)
		(mid 388.68477 -271.905413)
		(end 388.966202 -271.981168)
		(width 0.09525)
		(layer "In2.Cu")
		(net "M_I_CPU0_SB_DQS_DN<4>")
	)
	(arc
		(start 378.62637 -271.981168)
		(mid 378.814838 -272.031845)
		(end 379.003306 -271.981168)
		(width 0.09525)
		(layer "In2.Cu")
		(net "M_I_CPU0_SB_DQS_DN<4>")
	)
	(arc
		(start 389.343392 -271.981168)
		(mid 389.624824 -271.905413)
		(end 389.906256 -271.981168)
		(width 0.09525)
		(layer "In2.Cu")
		(net "M_I_CPU0_SB_DQS_DN<4>")
	)
	(arc
		(start 377.694698 -271.985994)
		(mid 377.87973 -272.031908)
		(end 378.063506 -271.981168)
		(width 0.09525)
		(layer "In2.Cu")
		(net "M_I_CPU0_SB_DQS_DN<4>")
	)
	(arc
		(start 391.78611 -271.981168)
		(mid 391.960742 -272.031708)
		(end 392.138662 -271.994376)
		(width 0.09525)
		(layer "In2.Cu")
		(net "M_I_CPU0_SB_DQS_DN<4>")
	)
	(arc
		(start 386.523484 -271.981168)
		(mid 386.804916 -271.905413)
		(end 387.086348 -271.981168)
		(width 0.09525)
		(layer "In2.Cu")
		(net "M_I_CPU0_SB_DQS_DN<4>")
	)
	(arc
		(start 384.266186 -271.981168)
		(mid 384.449961 -272.03194)
		(end 384.634994 -271.985994)
		(width 0.09525)
		(layer "In2.Cu")
		(net "M_I_CPU0_SB_DQS_DN<4>")
	)
	(arc
		(start 388.966202 -271.981168)
		(mid 389.149977 -272.03194)
		(end 389.33501 -271.985994)
		(width 0.09525)
		(layer "In2.Cu")
		(net "M_I_CPU0_SB_DQS_DN<4>")
	)
	(arc
		(start 388.026148 -271.981168)
		(mid 388.209923 -272.03194)
		(end 388.394956 -271.985994)
		(width 0.09525)
		(layer "In2.Cu")
		(net "M_I_CPU0_SB_DQS_DN<4>")
	)
	(arc
		(start 378.063506 -271.981168)
		(mid 378.344938 -271.905413)
		(end 378.62637 -271.981168)
		(width 0.09525)
		(layer "In2.Cu")
		(net "M_I_CPU0_SB_DQS_DN<4>")
	)
	(arc
		(start 385.214622 -271.985994)
		(mid 385.399654 -272.031908)
		(end 385.58343 -271.981168)
		(width 0.09525)
		(layer "In2.Cu")
		(net "M_I_CPU0_SB_DQS_DN<4>")
	)
	(arc
		(start 392.187938 -271.965928)
		(mid 392.457344 -271.90558)
		(end 392.722862 -271.981168)
		(width 0.09525)
		(layer "In2.Cu")
		(net "M_I_CPU0_SB_DQS_DN<4>")
	)
	(arc
		(start 376.249692 -271.948148)
		(mid 376.501833 -271.906578)
		(end 376.746262 -271.981168)
		(width 0.09525)
		(layer "In2.Cu")
		(net "M_I_CPU0_SB_DQS_DN<4>")
	)
	(arc
		(start 385.58343 -271.981168)
		(mid 385.864862 -271.905413)
		(end 386.146294 -271.981168)
		(width 0.09525)
		(layer "In2.Cu")
		(net "M_I_CPU0_SB_DQS_DN<4>")
	)
	(arc
		(start 393.10183 -271.981676)
		(mid 393.239451 -271.924303)
		(end 393.387326 -271.905222)
		(width 0.09525)
		(layer "In2.Cu")
		(net "M_I_CPU0_SB_DQS_DN<4>")
	)
	(arc
		(start 391.223246 -271.981168)
		(mid 391.504678 -271.905413)
		(end 391.78611 -271.981168)
		(width 0.09525)
		(layer "In2.Cu")
		(net "M_I_CPU0_SB_DQS_DN<4>")
	)
	(arc
		(start 390.84631 -271.981168)
		(mid 391.034778 -272.031845)
		(end 391.223246 -271.981168)
		(width 0.09525)
		(layer "In2.Cu")
		(net "M_I_CPU0_SB_DQS_DN<4>")
	)
	(arc
		(start 383.326132 -271.981168)
		(mid 383.509907 -272.03194)
		(end 383.69494 -271.985994)
		(width 0.09525)
		(layer "In2.Cu")
		(net "M_I_CPU0_SB_DQS_DN<4>")
	)
	(arc
		(start 381.45466 -271.985994)
		(mid 381.639692 -272.031908)
		(end 381.823468 -271.981168)
		(width 0.09525)
		(layer "In2.Cu")
		(net "M_I_CPU0_SB_DQS_DN<4>")
	)
	(arc
		(start 380.506224 -271.981168)
		(mid 380.689999 -272.03194)
		(end 380.875032 -271.985994)
		(width 0.09525)
		(layer "In2.Cu")
		(net "M_I_CPU0_SB_DQS_DN<4>")
	)
	(arc
		(start 382.386332 -271.981168)
		(mid 382.5748 -272.031845)
		(end 382.763268 -271.981168)
		(width 0.09525)
		(layer "In2.Cu")
		(net "M_I_CPU0_SB_DQS_DN<4>")
	)
	(arc
		(start 379.94336 -271.981168)
		(mid 380.224792 -271.905413)
		(end 380.506224 -271.981168)
		(width 0.09525)
		(layer "In2.Cu")
		(net "M_I_CPU0_SB_DQS_DN<4>")
	)
	(arc
		(start 387.463284 -271.981168)
		(mid 387.744716 -271.905413)
		(end 388.026148 -271.981168)
		(width 0.09525)
		(layer "In2.Cu")
		(net "M_I_CPU0_SB_DQS_DN<4>")
	)
	(arc
		(start 379.56617 -271.981168)
		(mid 379.749945 -272.03194)
		(end 379.934978 -271.985994)
		(width 0.09525)
		(layer "In2.Cu")
		(net "M_I_CPU0_SB_DQS_DN<4>")
	)
	(segment
		(start 377.407932 -290.83)
		(end 377.874784 -291.095938)
		(width 0.12954)
		(layer "F.Cu")
		(net "M_I_CPU0_SB_DQS_DN<3>")
	)
	(segment
		(start 392.633454 -293.200836)
		(end 392.66495 -293.219124)
		(width 0.09525)
		(layer "In2.Cu")
		(net "M_I_CPU0_SB_DQS_DN<3>")
	)
	(segment
		(start 393.065254 -293.988744)
		(end 393.103354 -294.010842)
		(width 0.09525)
		(layer "In2.Cu")
		(net "M_I_CPU0_SB_DQS_DN<3>")
	)
	(segment
		(start 394.321284 -296.582846)
		(end 395.017244 -298.26331)
		(width 0.16002)
		(layer "In2.Cu")
		(net "M_I_CPU0_SB_DQS_DN<3>")
	)
	(segment
		(start 391.223246 -290.770818)
		(end 391.255758 -290.789614)
		(width 0.09525)
		(layer "In2.Cu")
		(net "M_I_CPU0_SB_DQS_DN<3>")
	)
	(segment
		(start 427.959774 -313.086242)
		(end 428.568358 -313.694826)
		(width 0.16002)
		(layer "In2.Cu")
		(net "M_I_CPU0_SB_DQS_DN<3>")
	)
	(segment
		(start 395.017244 -298.26331)
		(end 402.332444 -305.57851)
		(width 0.16002)
		(layer "In2.Cu")
		(net "M_I_CPU0_SB_DQS_DN<3>")
	)
	(segment
		(start 420.999158 -313.669426)
		(end 421.591486 -313.669426)
		(width 0.16002)
		(layer "In2.Cu")
		(net "M_I_CPU0_SB_DQS_DN<3>")
	)
	(segment
		(start 393.535154 -294.79875)
		(end 393.573254 -294.820848)
		(width 0.09525)
		(layer "In2.Cu")
		(net "M_I_CPU0_SB_DQS_DN<3>")
	)
	(segment
		(start 391.882376 -291.905944)
		(end 391.88263 -291.905944)
		(width 0.09525)
		(layer "In2.Cu")
		(net "M_I_CPU0_SB_DQS_DN<3>")
	)
	(segment
		(start 413.147764 -313.362086)
		(end 413.455104 -313.669426)
		(width 0.16002)
		(layer "In2.Cu")
		(net "M_I_CPU0_SB_DQS_DN<3>")
	)
	(segment
		(start 392.125454 -292.368732)
		(end 392.163554 -292.39083)
		(width 0.09525)
		(layer "In2.Cu")
		(net "M_I_CPU0_SB_DQS_DN<3>")
	)
	(segment
		(start 431.28311 -313.511946)
		(end 431.55616 -313.784996)
		(width 0.16002)
		(layer "In2.Cu")
		(net "M_I_CPU0_SB_DQS_DN<3>")
	)
	(segment
		(start 429.247046 -313.694826)
		(end 429.429926 -313.511946)
		(width 0.16002)
		(layer "In2.Cu")
		(net "M_I_CPU0_SB_DQS_DN<3>")
	)
	(segment
		(start 392.596878 -293.1795)
		(end 392.633454 -293.200836)
		(width 0.09525)
		(layer "In2.Cu")
		(net "M_I_CPU0_SB_DQS_DN<3>")
	)
	(segment
		(start 384.634994 -290.765992)
		(end 384.643376 -290.770818)
		(width 0.09525)
		(layer "In2.Cu")
		(net "M_I_CPU0_SB_DQS_DN<3>")
	)
	(segment
		(start 422.957498 -312.828686)
		(end 423.273982 -312.512202)
		(width 0.16002)
		(layer "In2.Cu")
		(net "M_I_CPU0_SB_DQS_DN<3>")
	)
	(segment
		(start 422.432226 -312.828686)
		(end 422.957498 -312.828686)
		(width 0.16002)
		(layer "In2.Cu")
		(net "M_I_CPU0_SB_DQS_DN<3>")
	)
	(segment
		(start 394.321284 -296.31767)
		(end 394.321284 -296.582846)
		(width 0.16002)
		(layer "In2.Cu")
		(net "M_I_CPU0_SB_DQS_DN<3>")
	)
	(segment
		(start 393.762484 -295.432988)
		(end 394.380212 -296.050716)
		(width 0.09525)
		(layer "In2.Cu")
		(net "M_I_CPU0_SB_DQS_DN<3>")
	)
	(segment
		(start 415.413444 -312.828686)
		(end 415.729928 -312.512202)
		(width 0.16002)
		(layer "In2.Cu")
		(net "M_I_CPU0_SB_DQS_DN<3>")
	)
	(segment
		(start 388.394956 -290.765992)
		(end 388.403338 -290.770818)
		(width 0.09525)
		(layer "In2.Cu")
		(net "M_I_CPU0_SB_DQS_DN<3>")
	)
	(segment
		(start 425.874434 -313.086242)
		(end 427.959774 -313.086242)
		(width 0.16002)
		(layer "In2.Cu")
		(net "M_I_CPU0_SB_DQS_DN<3>")
	)
	(segment
		(start 414.047432 -313.669426)
		(end 414.888172 -312.828686)
		(width 0.16002)
		(layer "In2.Cu")
		(net "M_I_CPU0_SB_DQS_DN<3>")
	)
	(segment
		(start 429.429926 -313.511946)
		(end 431.28311 -313.511946)
		(width 0.16002)
		(layer "In2.Cu")
		(net "M_I_CPU0_SB_DQS_DN<3>")
	)
	(segment
		(start 418.558472 -313.362086)
		(end 420.691818 -313.362086)
		(width 0.16002)
		(layer "In2.Cu")
		(net "M_I_CPU0_SB_DQS_DN<3>")
	)
	(segment
		(start 385.20624 -290.770818)
		(end 385.214622 -290.765992)
		(width 0.09525)
		(layer "In2.Cu")
		(net "M_I_CPU0_SB_DQS_DN<3>")
	)
	(segment
		(start 413.455104 -313.669426)
		(end 414.047432 -313.669426)
		(width 0.16002)
		(layer "In2.Cu")
		(net "M_I_CPU0_SB_DQS_DN<3>")
	)
	(segment
		(start 380.875032 -290.765992)
		(end 380.883414 -290.770818)
		(width 0.09525)
		(layer "In2.Cu")
		(net "M_I_CPU0_SB_DQS_DN<3>")
	)
	(segment
		(start 391.6553 -291.558726)
		(end 391.6934 -291.580824)
		(width 0.09525)
		(layer "In2.Cu")
		(net "M_I_CPU0_SB_DQS_DN<3>")
	)
	(segment
		(start 428.568358 -313.694826)
		(end 429.247046 -313.694826)
		(width 0.16002)
		(layer "In2.Cu")
		(net "M_I_CPU0_SB_DQS_DN<3>")
	)
	(segment
		(start 379.934978 -290.765992)
		(end 379.94336 -290.770818)
		(width 0.09525)
		(layer "In2.Cu")
		(net "M_I_CPU0_SB_DQS_DN<3>")
	)
	(segment
		(start 415.729928 -312.512202)
		(end 417.708588 -312.512202)
		(width 0.16002)
		(layer "In2.Cu")
		(net "M_I_CPU0_SB_DQS_DN<3>")
	)
	(segment
		(start 377.72086 -290.830508)
		(end 377.744228 -290.74364)
		(width 0.09525)
		(layer "In2.Cu")
		(net "M_I_CPU0_SB_DQS_DN<3>")
	)
	(segment
		(start 386.146294 -290.770818)
		(end 386.154676 -290.765992)
		(width 0.09525)
		(layer "In2.Cu")
		(net "M_I_CPU0_SB_DQS_DN<3>")
	)
	(segment
		(start 377.874784 -291.095938)
		(end 377.72086 -290.830508)
		(width 0.09525)
		(layer "In2.Cu")
		(net "M_I_CPU0_SB_DQS_DN<3>")
	)
	(segment
		(start 393.573254 -294.820848)
		(end 393.605766 -294.839644)
		(width 0.09525)
		(layer "In2.Cu")
		(net "M_I_CPU0_SB_DQS_DN<3>")
	)
	(segment
		(start 402.332444 -306.415694)
		(end 409.278836 -313.362086)
		(width 0.16002)
		(layer "In2.Cu")
		(net "M_I_CPU0_SB_DQS_DN<3>")
	)
	(segment
		(start 421.591486 -313.669426)
		(end 422.432226 -312.828686)
		(width 0.16002)
		(layer "In2.Cu")
		(net "M_I_CPU0_SB_DQS_DN<3>")
	)
	(segment
		(start 383.69494 -290.765992)
		(end 383.703322 -290.770818)
		(width 0.09525)
		(layer "In2.Cu")
		(net "M_I_CPU0_SB_DQS_DN<3>")
	)
	(segment
		(start 394.321284 -296.294048)
		(end 394.321284 -296.31767)
		(width 0.09525)
		(layer "In2.Cu")
		(net "M_I_CPU0_SB_DQS_DN<3>")
	)
	(segment
		(start 393.103354 -294.010842)
		(end 393.13485 -294.02913)
		(width 0.09525)
		(layer "In2.Cu")
		(net "M_I_CPU0_SB_DQS_DN<3>")
	)
	(segment
		(start 409.278836 -313.362086)
		(end 413.147764 -313.362086)
		(width 0.16002)
		(layer "In2.Cu")
		(net "M_I_CPU0_SB_DQS_DN<3>")
	)
	(segment
		(start 393.762484 -295.145968)
		(end 393.762484 -295.432988)
		(width 0.09525)
		(layer "In2.Cu")
		(net "M_I_CPU0_SB_DQS_DN<3>")
	)
	(segment
		(start 381.446278 -290.770818)
		(end 381.45466 -290.765992)
		(width 0.09525)
		(layer "In2.Cu")
		(net "M_I_CPU0_SB_DQS_DN<3>")
	)
	(segment
		(start 425.300394 -312.512202)
		(end 425.874434 -313.086242)
		(width 0.16002)
		(layer "In2.Cu")
		(net "M_I_CPU0_SB_DQS_DN<3>")
	)
	(segment
		(start 402.332444 -305.57851)
		(end 402.332444 -306.415694)
		(width 0.16002)
		(layer "In2.Cu")
		(net "M_I_CPU0_SB_DQS_DN<3>")
	)
	(segment
		(start 391.6934 -291.580824)
		(end 391.724896 -291.599112)
		(width 0.09525)
		(layer "In2.Cu")
		(net "M_I_CPU0_SB_DQS_DN<3>")
	)
	(segment
		(start 417.708588 -312.512202)
		(end 418.558472 -313.362086)
		(width 0.16002)
		(layer "In2.Cu")
		(net "M_I_CPU0_SB_DQS_DN<3>")
	)
	(segment
		(start 389.906256 -290.770818)
		(end 389.914638 -290.765992)
		(width 0.09525)
		(layer "In2.Cu")
		(net "M_I_CPU0_SB_DQS_DN<3>")
	)
	(segment
		(start 394.380212 -296.050716)
		(end 394.380212 -296.23512)
		(width 0.09525)
		(layer "In2.Cu")
		(net "M_I_CPU0_SB_DQS_DN<3>")
	)
	(segment
		(start 420.691818 -313.362086)
		(end 420.999158 -313.669426)
		(width 0.16002)
		(layer "In2.Cu")
		(net "M_I_CPU0_SB_DQS_DN<3>")
	)
	(segment
		(start 414.888172 -312.828686)
		(end 415.413444 -312.828686)
		(width 0.16002)
		(layer "In2.Cu")
		(net "M_I_CPU0_SB_DQS_DN<3>")
	)
	(segment
		(start 389.33501 -290.765992)
		(end 389.343392 -290.770818)
		(width 0.09525)
		(layer "In2.Cu")
		(net "M_I_CPU0_SB_DQS_DN<3>")
	)
	(segment
		(start 392.163554 -292.39083)
		(end 392.197336 -292.410388)
		(width 0.09525)
		(layer "In2.Cu")
		(net "M_I_CPU0_SB_DQS_DN<3>")
	)
	(segment
		(start 423.273982 -312.512202)
		(end 425.300394 -312.512202)
		(width 0.16002)
		(layer "In2.Cu")
		(net "M_I_CPU0_SB_DQS_DN<3>")
	)
	(segment
		(start 394.380212 -296.23512)
		(end 394.321284 -296.294048)
		(width 0.09525)
		(layer "In2.Cu")
		(net "M_I_CPU0_SB_DQS_DN<3>")
	)
	(arc
		(start 387.463284 -290.770818)
		(mid 387.744716 -290.846573)
		(end 388.026148 -290.770818)
		(width 0.09525)
		(layer "In2.Cu")
		(net "M_I_CPU0_SB_DQS_DN<3>")
	)
	(arc
		(start 385.58343 -290.770818)
		(mid 385.864862 -290.846573)
		(end 386.146294 -290.770818)
		(width 0.09525)
		(layer "In2.Cu")
		(net "M_I_CPU0_SB_DQS_DN<3>")
	)
	(arc
		(start 379.56617 -290.770818)
		(mid 379.749945 -290.720046)
		(end 379.934978 -290.765992)
		(width 0.09525)
		(layer "In2.Cu")
		(net "M_I_CPU0_SB_DQS_DN<3>")
	)
	(arc
		(start 392.352784 -292.71595)
		(mid 392.417544 -292.977885)
		(end 392.596878 -293.1795)
		(width 0.09525)
		(layer "In2.Cu")
		(net "M_I_CPU0_SB_DQS_DN<3>")
	)
	(arc
		(start 377.744228 -290.74364)
		(mid 377.90691 -290.721508)
		(end 378.063506 -290.770818)
		(width 0.09525)
		(layer "In2.Cu")
		(net "M_I_CPU0_SB_DQS_DN<3>")
	)
	(arc
		(start 383.326132 -290.770818)
		(mid 383.509907 -290.720046)
		(end 383.69494 -290.765992)
		(width 0.09525)
		(layer "In2.Cu")
		(net "M_I_CPU0_SB_DQS_DN<3>")
	)
	(arc
		(start 388.966202 -290.770818)
		(mid 389.149977 -290.720046)
		(end 389.33501 -290.765992)
		(width 0.09525)
		(layer "In2.Cu")
		(net "M_I_CPU0_SB_DQS_DN<3>")
	)
	(arc
		(start 391.255758 -290.789614)
		(mid 391.371032 -290.923892)
		(end 391.412476 -291.095938)
		(width 0.09525)
		(layer "In2.Cu")
		(net "M_I_CPU0_SB_DQS_DN<3>")
	)
	(arc
		(start 391.724896 -291.599112)
		(mid 391.840694 -291.733506)
		(end 391.882376 -291.905944)
		(width 0.09525)
		(layer "In2.Cu")
		(net "M_I_CPU0_SB_DQS_DN<3>")
	)
	(arc
		(start 382.386332 -290.770818)
		(mid 382.5748 -290.720141)
		(end 382.763268 -290.770818)
		(width 0.09525)
		(layer "In2.Cu")
		(net "M_I_CPU0_SB_DQS_DN<3>")
	)
	(arc
		(start 381.823468 -290.770818)
		(mid 382.1049 -290.846573)
		(end 382.386332 -290.770818)
		(width 0.09525)
		(layer "In2.Cu")
		(net "M_I_CPU0_SB_DQS_DN<3>")
	)
	(arc
		(start 384.643376 -290.770818)
		(mid 384.924808 -290.846573)
		(end 385.20624 -290.770818)
		(width 0.09525)
		(layer "In2.Cu")
		(net "M_I_CPU0_SB_DQS_DN<3>")
	)
	(arc
		(start 386.523484 -290.770818)
		(mid 386.804916 -290.846573)
		(end 387.086348 -290.770818)
		(width 0.09525)
		(layer "In2.Cu")
		(net "M_I_CPU0_SB_DQS_DN<3>")
	)
	(arc
		(start 389.343392 -290.770818)
		(mid 389.624824 -290.846573)
		(end 389.906256 -290.770818)
		(width 0.09525)
		(layer "In2.Cu")
		(net "M_I_CPU0_SB_DQS_DN<3>")
	)
	(arc
		(start 391.412476 -291.095938)
		(mid 391.476873 -291.357244)
		(end 391.6553 -291.558726)
		(width 0.09525)
		(layer "In2.Cu")
		(net "M_I_CPU0_SB_DQS_DN<3>")
	)
	(arc
		(start 379.003306 -290.770818)
		(mid 379.284738 -290.846573)
		(end 379.56617 -290.770818)
		(width 0.09525)
		(layer "In2.Cu")
		(net "M_I_CPU0_SB_DQS_DN<3>")
	)
	(arc
		(start 387.086348 -290.770818)
		(mid 387.274816 -290.720141)
		(end 387.463284 -290.770818)
		(width 0.09525)
		(layer "In2.Cu")
		(net "M_I_CPU0_SB_DQS_DN<3>")
	)
	(arc
		(start 393.13485 -294.02913)
		(mid 393.250648 -294.163524)
		(end 393.29233 -294.335962)
		(width 0.09525)
		(layer "In2.Cu")
		(net "M_I_CPU0_SB_DQS_DN<3>")
	)
	(arc
		(start 379.94336 -290.770818)
		(mid 380.224792 -290.846573)
		(end 380.506224 -290.770818)
		(width 0.09525)
		(layer "In2.Cu")
		(net "M_I_CPU0_SB_DQS_DN<3>")
	)
	(arc
		(start 392.82243 -293.525956)
		(mid 392.886827 -293.787262)
		(end 393.065254 -293.988744)
		(width 0.09525)
		(layer "In2.Cu")
		(net "M_I_CPU0_SB_DQS_DN<3>")
	)
	(arc
		(start 382.763268 -290.770818)
		(mid 383.0447 -290.846573)
		(end 383.326132 -290.770818)
		(width 0.09525)
		(layer "In2.Cu")
		(net "M_I_CPU0_SB_DQS_DN<3>")
	)
	(arc
		(start 381.45466 -290.765992)
		(mid 381.639692 -290.720078)
		(end 381.823468 -290.770818)
		(width 0.09525)
		(layer "In2.Cu")
		(net "M_I_CPU0_SB_DQS_DN<3>")
	)
	(arc
		(start 390.283446 -290.770818)
		(mid 390.564878 -290.846573)
		(end 390.84631 -290.770818)
		(width 0.09525)
		(layer "In2.Cu")
		(net "M_I_CPU0_SB_DQS_DN<3>")
	)
	(arc
		(start 392.197336 -292.410388)
		(mid 392.311715 -292.544527)
		(end 392.352784 -292.71595)
		(width 0.09525)
		(layer "In2.Cu")
		(net "M_I_CPU0_SB_DQS_DN<3>")
	)
	(arc
		(start 378.62637 -290.770818)
		(mid 378.814838 -290.720141)
		(end 379.003306 -290.770818)
		(width 0.09525)
		(layer "In2.Cu")
		(net "M_I_CPU0_SB_DQS_DN<3>")
	)
	(arc
		(start 389.914638 -290.765992)
		(mid 390.09967 -290.720078)
		(end 390.283446 -290.770818)
		(width 0.09525)
		(layer "In2.Cu")
		(net "M_I_CPU0_SB_DQS_DN<3>")
	)
	(arc
		(start 378.063506 -290.770818)
		(mid 378.344938 -290.846573)
		(end 378.62637 -290.770818)
		(width 0.09525)
		(layer "In2.Cu")
		(net "M_I_CPU0_SB_DQS_DN<3>")
	)
	(arc
		(start 388.403338 -290.770818)
		(mid 388.68477 -290.846573)
		(end 388.966202 -290.770818)
		(width 0.09525)
		(layer "In2.Cu")
		(net "M_I_CPU0_SB_DQS_DN<3>")
	)
	(arc
		(start 388.026148 -290.770818)
		(mid 388.209923 -290.720046)
		(end 388.394956 -290.765992)
		(width 0.09525)
		(layer "In2.Cu")
		(net "M_I_CPU0_SB_DQS_DN<3>")
	)
	(arc
		(start 393.605766 -294.839644)
		(mid 393.72104 -294.973922)
		(end 393.762484 -295.145968)
		(width 0.09525)
		(layer "In2.Cu")
		(net "M_I_CPU0_SB_DQS_DN<3>")
	)
	(arc
		(start 386.154676 -290.765992)
		(mid 386.339708 -290.720078)
		(end 386.523484 -290.770818)
		(width 0.09525)
		(layer "In2.Cu")
		(net "M_I_CPU0_SB_DQS_DN<3>")
	)
	(arc
		(start 392.66495 -293.219124)
		(mid 392.780748 -293.353518)
		(end 392.82243 -293.525956)
		(width 0.09525)
		(layer "In2.Cu")
		(net "M_I_CPU0_SB_DQS_DN<3>")
	)
	(arc
		(start 393.29233 -294.335962)
		(mid 393.356727 -294.597268)
		(end 393.535154 -294.79875)
		(width 0.09525)
		(layer "In2.Cu")
		(net "M_I_CPU0_SB_DQS_DN<3>")
	)
	(arc
		(start 390.84631 -290.770818)
		(mid 391.034778 -290.720141)
		(end 391.223246 -290.770818)
		(width 0.09525)
		(layer "In2.Cu")
		(net "M_I_CPU0_SB_DQS_DN<3>")
	)
	(arc
		(start 380.506224 -290.770818)
		(mid 380.689999 -290.720046)
		(end 380.875032 -290.765992)
		(width 0.09525)
		(layer "In2.Cu")
		(net "M_I_CPU0_SB_DQS_DN<3>")
	)
	(arc
		(start 391.88263 -291.905944)
		(mid 391.947027 -292.16725)
		(end 392.125454 -292.368732)
		(width 0.09525)
		(layer "In2.Cu")
		(net "M_I_CPU0_SB_DQS_DN<3>")
	)
	(arc
		(start 384.266186 -290.770818)
		(mid 384.449961 -290.720046)
		(end 384.634994 -290.765992)
		(width 0.09525)
		(layer "In2.Cu")
		(net "M_I_CPU0_SB_DQS_DN<3>")
	)
	(arc
		(start 380.883414 -290.770818)
		(mid 381.164846 -290.846573)
		(end 381.446278 -290.770818)
		(width 0.09525)
		(layer "In2.Cu")
		(net "M_I_CPU0_SB_DQS_DN<3>")
	)
	(arc
		(start 383.703322 -290.770818)
		(mid 383.984754 -290.846573)
		(end 384.266186 -290.770818)
		(width 0.09525)
		(layer "In2.Cu")
		(net "M_I_CPU0_SB_DQS_DN<3>")
	)
	(arc
		(start 385.214622 -290.765992)
		(mid 385.399654 -290.720078)
		(end 385.58343 -290.770818)
		(width 0.09525)
		(layer "In2.Cu")
		(net "M_I_CPU0_SB_DQS_DN<3>")
	)
	(segment
		(start 377.407932 -285.970218)
		(end 377.874784 -286.236156)
		(width 0.12954)
		(layer "F.Cu")
		(net "M_I_CPU0_SB_DQS_DN<2>")
	)
	(segment
		(start 377.874784 -286.236156)
		(end 377.72086 -285.970726)
		(width 0.09525)
		(layer "In2.Cu")
		(net "M_I_CPU0_SB_DQS_DN<2>")
	)
	(segment
		(start 423.273982 -303.162208)
		(end 425.300394 -303.162208)
		(width 0.16002)
		(layer "In2.Cu")
		(net "M_I_CPU0_SB_DQS_DN<2>")
	)
	(segment
		(start 420.691818 -304.012092)
		(end 420.999158 -304.319432)
		(width 0.16002)
		(layer "In2.Cu")
		(net "M_I_CPU0_SB_DQS_DN<2>")
	)
	(segment
		(start 425.874434 -303.736248)
		(end 427.959774 -303.736248)
		(width 0.16002)
		(layer "In2.Cu")
		(net "M_I_CPU0_SB_DQS_DN<2>")
	)
	(segment
		(start 422.432226 -303.478692)
		(end 422.957498 -303.478692)
		(width 0.16002)
		(layer "In2.Cu")
		(net "M_I_CPU0_SB_DQS_DN<2>")
	)
	(segment
		(start 389.906256 -285.911036)
		(end 389.914638 -285.90621)
		(width 0.09525)
		(layer "In2.Cu")
		(net "M_I_CPU0_SB_DQS_DN<2>")
	)
	(segment
		(start 393.384786 -285.986728)
		(end 393.78001 -285.986728)
		(width 0.09525)
		(layer "In2.Cu")
		(net "M_I_CPU0_SB_DQS_DN<2>")
	)
	(segment
		(start 408.805888 -304.124614)
		(end 409.333192 -304.124868)
		(width 0.16002)
		(layer "In2.Cu")
		(net "M_I_CPU0_SB_DQS_DN<2>")
	)
	(segment
		(start 398.183608 -291.957252)
		(end 408.80284 -302.576484)
		(width 0.16002)
		(layer "In2.Cu")
		(net "M_I_CPU0_SB_DQS_DN<2>")
	)
	(segment
		(start 392.154918 -285.90621)
		(end 392.1633 -285.911036)
		(width 0.09525)
		(layer "In2.Cu")
		(net "M_I_CPU0_SB_DQS_DN<2>")
	)
	(segment
		(start 393.094972 -285.90621)
		(end 393.103354 -285.911036)
		(width 0.09525)
		(layer "In2.Cu")
		(net "M_I_CPU0_SB_DQS_DN<2>")
	)
	(segment
		(start 414.888172 -303.478692)
		(end 415.413444 -303.478692)
		(width 0.16002)
		(layer "In2.Cu")
		(net "M_I_CPU0_SB_DQS_DN<2>")
	)
	(segment
		(start 427.959774 -303.736248)
		(end 428.568358 -304.344832)
		(width 0.16002)
		(layer "In2.Cu")
		(net "M_I_CPU0_SB_DQS_DN<2>")
	)
	(segment
		(start 410.238448 -304.012092)
		(end 413.147764 -304.012092)
		(width 0.16002)
		(layer "In2.Cu")
		(net "M_I_CPU0_SB_DQS_DN<2>")
	)
	(segment
		(start 408.80284 -302.576484)
		(end 408.80284 -302.853344)
		(width 0.16002)
		(layer "In2.Cu")
		(net "M_I_CPU0_SB_DQS_DN<2>")
	)
	(segment
		(start 417.708588 -303.162208)
		(end 418.558472 -304.012092)
		(width 0.16002)
		(layer "In2.Cu")
		(net "M_I_CPU0_SB_DQS_DN<2>")
	)
	(segment
		(start 388.394956 -285.90621)
		(end 388.403338 -285.911036)
		(width 0.09525)
		(layer "In2.Cu")
		(net "M_I_CPU0_SB_DQS_DN<2>")
	)
	(segment
		(start 414.047432 -304.319432)
		(end 414.888172 -303.478692)
		(width 0.16002)
		(layer "In2.Cu")
		(net "M_I_CPU0_SB_DQS_DN<2>")
	)
	(segment
		(start 397.153638 -289.472116)
		(end 398.183608 -291.957252)
		(width 0.16002)
		(layer "In2.Cu")
		(net "M_I_CPU0_SB_DQS_DN<2>")
	)
	(segment
		(start 413.147764 -304.012092)
		(end 413.455104 -304.319432)
		(width 0.16002)
		(layer "In2.Cu")
		(net "M_I_CPU0_SB_DQS_DN<2>")
	)
	(segment
		(start 408.432 -303.750726)
		(end 408.805888 -304.124614)
		(width 0.16002)
		(layer "In2.Cu")
		(net "M_I_CPU0_SB_DQS_DN<2>")
	)
	(segment
		(start 393.78001 -285.986728)
		(end 394.839444 -287.046162)
		(width 0.09525)
		(layer "In2.Cu")
		(net "M_I_CPU0_SB_DQS_DN<2>")
	)
	(segment
		(start 418.558472 -304.012092)
		(end 420.691818 -304.012092)
		(width 0.16002)
		(layer "In2.Cu")
		(net "M_I_CPU0_SB_DQS_DN<2>")
	)
	(segment
		(start 420.999158 -304.319432)
		(end 421.591486 -304.319432)
		(width 0.16002)
		(layer "In2.Cu")
		(net "M_I_CPU0_SB_DQS_DN<2>")
	)
	(segment
		(start 409.333192 -304.124868)
		(end 409.703778 -303.754282)
		(width 0.16002)
		(layer "In2.Cu")
		(net "M_I_CPU0_SB_DQS_DN<2>")
	)
	(segment
		(start 408.432254 -303.22393)
		(end 408.432 -303.750726)
		(width 0.16002)
		(layer "In2.Cu")
		(net "M_I_CPU0_SB_DQS_DN<2>")
	)
	(segment
		(start 395.628876 -287.86455)
		(end 395.628876 -287.947354)
		(width 0.09525)
		(layer "In2.Cu")
		(net "M_I_CPU0_SB_DQS_DN<2>")
	)
	(segment
		(start 379.934978 -285.90621)
		(end 379.94336 -285.911036)
		(width 0.09525)
		(layer "In2.Cu")
		(net "M_I_CPU0_SB_DQS_DN<2>")
	)
	(segment
		(start 422.957498 -303.478692)
		(end 423.273982 -303.162208)
		(width 0.16002)
		(layer "In2.Cu")
		(net "M_I_CPU0_SB_DQS_DN<2>")
	)
	(segment
		(start 421.591486 -304.319432)
		(end 422.432226 -303.478692)
		(width 0.16002)
		(layer "In2.Cu")
		(net "M_I_CPU0_SB_DQS_DN<2>")
	)
	(segment
		(start 389.33501 -285.90621)
		(end 389.343392 -285.911036)
		(width 0.09525)
		(layer "In2.Cu")
		(net "M_I_CPU0_SB_DQS_DN<2>")
	)
	(segment
		(start 385.20624 -285.911036)
		(end 385.214622 -285.90621)
		(width 0.09525)
		(layer "In2.Cu")
		(net "M_I_CPU0_SB_DQS_DN<2>")
	)
	(segment
		(start 384.634994 -285.90621)
		(end 384.643376 -285.911036)
		(width 0.09525)
		(layer "In2.Cu")
		(net "M_I_CPU0_SB_DQS_DN<2>")
	)
	(segment
		(start 386.146294 -285.911036)
		(end 386.154676 -285.90621)
		(width 0.09525)
		(layer "In2.Cu")
		(net "M_I_CPU0_SB_DQS_DN<2>")
	)
	(segment
		(start 381.446278 -285.911036)
		(end 381.45466 -285.90621)
		(width 0.09525)
		(layer "In2.Cu")
		(net "M_I_CPU0_SB_DQS_DN<2>")
	)
	(segment
		(start 431.28311 -304.161952)
		(end 431.55616 -304.435002)
		(width 0.16002)
		(layer "In2.Cu")
		(net "M_I_CPU0_SB_DQS_DN<2>")
	)
	(segment
		(start 380.875032 -285.90621)
		(end 380.883414 -285.911036)
		(width 0.09525)
		(layer "In2.Cu")
		(net "M_I_CPU0_SB_DQS_DN<2>")
	)
	(segment
		(start 429.838358 -304.344832)
		(end 430.021238 -304.161952)
		(width 0.16002)
		(layer "In2.Cu")
		(net "M_I_CPU0_SB_DQS_DN<2>")
	)
	(segment
		(start 428.568358 -304.344832)
		(end 429.838358 -304.344832)
		(width 0.16002)
		(layer "In2.Cu")
		(net "M_I_CPU0_SB_DQS_DN<2>")
	)
	(segment
		(start 395.628876 -287.947354)
		(end 395.64564 -287.964118)
		(width 0.09525)
		(layer "In2.Cu")
		(net "M_I_CPU0_SB_DQS_DN<2>")
	)
	(segment
		(start 415.413444 -303.478692)
		(end 415.729928 -303.162208)
		(width 0.16002)
		(layer "In2.Cu")
		(net "M_I_CPU0_SB_DQS_DN<2>")
	)
	(segment
		(start 415.729928 -303.162208)
		(end 417.708588 -303.162208)
		(width 0.16002)
		(layer "In2.Cu")
		(net "M_I_CPU0_SB_DQS_DN<2>")
	)
	(segment
		(start 377.72086 -285.970726)
		(end 377.744228 -285.883858)
		(width 0.09525)
		(layer "In2.Cu")
		(net "M_I_CPU0_SB_DQS_DN<2>")
	)
	(segment
		(start 383.69494 -285.90621)
		(end 383.703322 -285.911036)
		(width 0.09525)
		(layer "In2.Cu")
		(net "M_I_CPU0_SB_DQS_DN<2>")
	)
	(segment
		(start 395.64564 -287.964118)
		(end 397.153638 -289.472116)
		(width 0.16002)
		(layer "In2.Cu")
		(net "M_I_CPU0_SB_DQS_DN<2>")
	)
	(segment
		(start 413.455104 -304.319432)
		(end 414.047432 -304.319432)
		(width 0.16002)
		(layer "In2.Cu")
		(net "M_I_CPU0_SB_DQS_DN<2>")
	)
	(segment
		(start 409.703778 -303.754282)
		(end 409.980638 -303.754282)
		(width 0.16002)
		(layer "In2.Cu")
		(net "M_I_CPU0_SB_DQS_DN<2>")
	)
	(segment
		(start 425.300394 -303.162208)
		(end 425.874434 -303.736248)
		(width 0.16002)
		(layer "In2.Cu")
		(net "M_I_CPU0_SB_DQS_DN<2>")
	)
	(segment
		(start 395.054836 -287.046162)
		(end 395.352524 -287.34385)
		(width 0.09525)
		(layer "In2.Cu")
		(net "M_I_CPU0_SB_DQS_DN<2>")
	)
	(segment
		(start 394.839444 -287.046162)
		(end 395.054836 -287.046162)
		(width 0.09525)
		(layer "In2.Cu")
		(net "M_I_CPU0_SB_DQS_DN<2>")
	)
	(segment
		(start 395.352524 -287.34385)
		(end 395.352524 -287.587944)
		(width 0.09525)
		(layer "In2.Cu")
		(net "M_I_CPU0_SB_DQS_DN<2>")
	)
	(segment
		(start 409.980638 -303.754282)
		(end 410.238448 -304.012092)
		(width 0.16002)
		(layer "In2.Cu")
		(net "M_I_CPU0_SB_DQS_DN<2>")
	)
	(segment
		(start 408.80284 -302.853344)
		(end 408.432254 -303.22393)
		(width 0.16002)
		(layer "In2.Cu")
		(net "M_I_CPU0_SB_DQS_DN<2>")
	)
	(segment
		(start 395.352524 -287.587944)
		(end 395.628876 -287.86455)
		(width 0.09525)
		(layer "In2.Cu")
		(net "M_I_CPU0_SB_DQS_DN<2>")
	)
	(segment
		(start 430.021238 -304.161952)
		(end 431.28311 -304.161952)
		(width 0.16002)
		(layer "In2.Cu")
		(net "M_I_CPU0_SB_DQS_DN<2>")
	)
	(arc
		(start 391.223246 -285.911036)
		(mid 391.504678 -285.986791)
		(end 391.78611 -285.911036)
		(width 0.09525)
		(layer "In2.Cu")
		(net "M_I_CPU0_SB_DQS_DN<2>")
	)
	(arc
		(start 389.343392 -285.911036)
		(mid 389.624824 -285.986791)
		(end 389.906256 -285.911036)
		(width 0.09525)
		(layer "In2.Cu")
		(net "M_I_CPU0_SB_DQS_DN<2>")
	)
	(arc
		(start 390.283446 -285.911036)
		(mid 390.564878 -285.986791)
		(end 390.84631 -285.911036)
		(width 0.09525)
		(layer "In2.Cu")
		(net "M_I_CPU0_SB_DQS_DN<2>")
	)
	(arc
		(start 384.643376 -285.911036)
		(mid 384.924808 -285.986791)
		(end 385.20624 -285.911036)
		(width 0.09525)
		(layer "In2.Cu")
		(net "M_I_CPU0_SB_DQS_DN<2>")
	)
	(arc
		(start 387.086348 -285.911036)
		(mid 387.274816 -285.860359)
		(end 387.463284 -285.911036)
		(width 0.09525)
		(layer "In2.Cu")
		(net "M_I_CPU0_SB_DQS_DN<2>")
	)
	(arc
		(start 386.154676 -285.90621)
		(mid 386.339708 -285.860296)
		(end 386.523484 -285.911036)
		(width 0.09525)
		(layer "In2.Cu")
		(net "M_I_CPU0_SB_DQS_DN<2>")
	)
	(arc
		(start 385.214622 -285.90621)
		(mid 385.399654 -285.860296)
		(end 385.58343 -285.911036)
		(width 0.09525)
		(layer "In2.Cu")
		(net "M_I_CPU0_SB_DQS_DN<2>")
	)
	(arc
		(start 379.003306 -285.911036)
		(mid 379.284738 -285.986791)
		(end 379.56617 -285.911036)
		(width 0.09525)
		(layer "In2.Cu")
		(net "M_I_CPU0_SB_DQS_DN<2>")
	)
	(arc
		(start 386.523484 -285.911036)
		(mid 386.804916 -285.986791)
		(end 387.086348 -285.911036)
		(width 0.09525)
		(layer "In2.Cu")
		(net "M_I_CPU0_SB_DQS_DN<2>")
	)
	(arc
		(start 383.326132 -285.911036)
		(mid 383.509907 -285.860264)
		(end 383.69494 -285.90621)
		(width 0.09525)
		(layer "In2.Cu")
		(net "M_I_CPU0_SB_DQS_DN<2>")
	)
	(arc
		(start 383.703322 -285.911036)
		(mid 383.984754 -285.986791)
		(end 384.266186 -285.911036)
		(width 0.09525)
		(layer "In2.Cu")
		(net "M_I_CPU0_SB_DQS_DN<2>")
	)
	(arc
		(start 382.763268 -285.911036)
		(mid 383.0447 -285.986791)
		(end 383.326132 -285.911036)
		(width 0.09525)
		(layer "In2.Cu")
		(net "M_I_CPU0_SB_DQS_DN<2>")
	)
	(arc
		(start 381.45466 -285.90621)
		(mid 381.639692 -285.860296)
		(end 381.823468 -285.911036)
		(width 0.09525)
		(layer "In2.Cu")
		(net "M_I_CPU0_SB_DQS_DN<2>")
	)
	(arc
		(start 384.266186 -285.911036)
		(mid 384.449961 -285.860264)
		(end 384.634994 -285.90621)
		(width 0.09525)
		(layer "In2.Cu")
		(net "M_I_CPU0_SB_DQS_DN<2>")
	)
	(arc
		(start 392.726164 -285.911036)
		(mid 392.909939 -285.860264)
		(end 393.094972 -285.90621)
		(width 0.09525)
		(layer "In2.Cu")
		(net "M_I_CPU0_SB_DQS_DN<2>")
	)
	(arc
		(start 379.94336 -285.911036)
		(mid 380.224792 -285.986791)
		(end 380.506224 -285.911036)
		(width 0.09525)
		(layer "In2.Cu")
		(net "M_I_CPU0_SB_DQS_DN<2>")
	)
	(arc
		(start 392.1633 -285.911036)
		(mid 392.444732 -285.986791)
		(end 392.726164 -285.911036)
		(width 0.09525)
		(layer "In2.Cu")
		(net "M_I_CPU0_SB_DQS_DN<2>")
	)
	(arc
		(start 385.58343 -285.911036)
		(mid 385.864862 -285.986791)
		(end 386.146294 -285.911036)
		(width 0.09525)
		(layer "In2.Cu")
		(net "M_I_CPU0_SB_DQS_DN<2>")
	)
	(arc
		(start 382.386332 -285.911036)
		(mid 382.5748 -285.860359)
		(end 382.763268 -285.911036)
		(width 0.09525)
		(layer "In2.Cu")
		(net "M_I_CPU0_SB_DQS_DN<2>")
	)
	(arc
		(start 378.62637 -285.911036)
		(mid 378.814838 -285.860359)
		(end 379.003306 -285.911036)
		(width 0.09525)
		(layer "In2.Cu")
		(net "M_I_CPU0_SB_DQS_DN<2>")
	)
	(arc
		(start 379.56617 -285.911036)
		(mid 379.749945 -285.860264)
		(end 379.934978 -285.90621)
		(width 0.09525)
		(layer "In2.Cu")
		(net "M_I_CPU0_SB_DQS_DN<2>")
	)
	(arc
		(start 380.883414 -285.911036)
		(mid 381.164846 -285.986791)
		(end 381.446278 -285.911036)
		(width 0.09525)
		(layer "In2.Cu")
		(net "M_I_CPU0_SB_DQS_DN<2>")
	)
	(arc
		(start 391.78611 -285.911036)
		(mid 391.969885 -285.860264)
		(end 392.154918 -285.90621)
		(width 0.09525)
		(layer "In2.Cu")
		(net "M_I_CPU0_SB_DQS_DN<2>")
	)
	(arc
		(start 387.463284 -285.911036)
		(mid 387.744716 -285.986791)
		(end 388.026148 -285.911036)
		(width 0.09525)
		(layer "In2.Cu")
		(net "M_I_CPU0_SB_DQS_DN<2>")
	)
	(arc
		(start 378.063506 -285.911036)
		(mid 378.344938 -285.986791)
		(end 378.62637 -285.911036)
		(width 0.09525)
		(layer "In2.Cu")
		(net "M_I_CPU0_SB_DQS_DN<2>")
	)
	(arc
		(start 389.914638 -285.90621)
		(mid 390.09967 -285.860296)
		(end 390.283446 -285.911036)
		(width 0.09525)
		(layer "In2.Cu")
		(net "M_I_CPU0_SB_DQS_DN<2>")
	)
	(arc
		(start 381.823468 -285.911036)
		(mid 382.1049 -285.986791)
		(end 382.386332 -285.911036)
		(width 0.09525)
		(layer "In2.Cu")
		(net "M_I_CPU0_SB_DQS_DN<2>")
	)
	(arc
		(start 393.103354 -285.911036)
		(mid 393.239061 -285.967521)
		(end 393.384786 -285.986728)
		(width 0.09525)
		(layer "In2.Cu")
		(net "M_I_CPU0_SB_DQS_DN<2>")
	)
	(arc
		(start 390.84631 -285.911036)
		(mid 391.034778 -285.860359)
		(end 391.223246 -285.911036)
		(width 0.09525)
		(layer "In2.Cu")
		(net "M_I_CPU0_SB_DQS_DN<2>")
	)
	(arc
		(start 388.966202 -285.911036)
		(mid 389.149977 -285.860264)
		(end 389.33501 -285.90621)
		(width 0.09525)
		(layer "In2.Cu")
		(net "M_I_CPU0_SB_DQS_DN<2>")
	)
	(arc
		(start 377.744228 -285.883858)
		(mid 377.90691 -285.861726)
		(end 378.063506 -285.911036)
		(width 0.09525)
		(layer "In2.Cu")
		(net "M_I_CPU0_SB_DQS_DN<2>")
	)
	(arc
		(start 388.026148 -285.911036)
		(mid 388.209923 -285.860264)
		(end 388.394956 -285.90621)
		(width 0.09525)
		(layer "In2.Cu")
		(net "M_I_CPU0_SB_DQS_DN<2>")
	)
	(arc
		(start 388.403338 -285.911036)
		(mid 388.68477 -285.986791)
		(end 388.966202 -285.911036)
		(width 0.09525)
		(layer "In2.Cu")
		(net "M_I_CPU0_SB_DQS_DN<2>")
	)
	(arc
		(start 380.506224 -285.911036)
		(mid 380.689999 -285.860264)
		(end 380.875032 -285.90621)
		(width 0.09525)
		(layer "In2.Cu")
		(net "M_I_CPU0_SB_DQS_DN<2>")
	)
	(segment
		(start 377.407932 -281.110182)
		(end 377.874784 -281.37612)
		(width 0.12954)
		(layer "F.Cu")
		(net "M_I_CPU0_SB_DQS_DN<1>")
	)
	(segment
		(start 420.691818 -294.662098)
		(end 420.999158 -294.969438)
		(width 0.16002)
		(layer "In2.Cu")
		(net "M_I_CPU0_SB_DQS_DN<1>")
	)
	(segment
		(start 411.193996 -294.662098)
		(end 413.147764 -294.662098)
		(width 0.16002)
		(layer "In2.Cu")
		(net "M_I_CPU0_SB_DQS_DN<1>")
	)
	(segment
		(start 393.913868 -281.126692)
		(end 394.321538 -280.719022)
		(width 0.09525)
		(layer "In2.Cu")
		(net "M_I_CPU0_SB_DQS_DN<1>")
	)
	(segment
		(start 417.708588 -293.812214)
		(end 418.558472 -294.662098)
		(width 0.16002)
		(layer "In2.Cu")
		(net "M_I_CPU0_SB_DQS_DN<1>")
	)
	(segment
		(start 395.835632 -281.2288)
		(end 395.859254 -281.2288)
		(width 0.09525)
		(layer "In2.Cu")
		(net "M_I_CPU0_SB_DQS_DN<1>")
	)
	(segment
		(start 402.407628 -285.508954)
		(end 410.534358 -293.635684)
		(width 0.16002)
		(layer "In2.Cu")
		(net "M_I_CPU0_SB_DQS_DN<1>")
	)
	(segment
		(start 389.906256 -281.051)
		(end 389.914638 -281.046174)
		(width 0.09525)
		(layer "In2.Cu")
		(net "M_I_CPU0_SB_DQS_DN<1>")
	)
	(segment
		(start 414.888172 -294.128698)
		(end 415.413444 -294.128698)
		(width 0.16002)
		(layer "In2.Cu")
		(net "M_I_CPU0_SB_DQS_DN<1>")
	)
	(segment
		(start 395.553692 -281.169872)
		(end 395.776704 -281.169872)
		(width 0.09525)
		(layer "In2.Cu")
		(net "M_I_CPU0_SB_DQS_DN<1>")
	)
	(segment
		(start 393.381738 -281.126946)
		(end 393.476734 -281.126946)
		(width 0.09525)
		(layer "In2.Cu")
		(net "M_I_CPU0_SB_DQS_DN<1>")
	)
	(segment
		(start 410.534358 -293.635684)
		(end 410.534358 -294.00246)
		(width 0.16002)
		(layer "In2.Cu")
		(net "M_I_CPU0_SB_DQS_DN<1>")
	)
	(segment
		(start 377.874784 -281.37612)
		(end 377.72086 -281.11069)
		(width 0.09525)
		(layer "In2.Cu")
		(net "M_I_CPU0_SB_DQS_DN<1>")
	)
	(segment
		(start 413.147764 -294.662098)
		(end 413.455104 -294.969438)
		(width 0.16002)
		(layer "In2.Cu")
		(net "M_I_CPU0_SB_DQS_DN<1>")
	)
	(segment
		(start 381.446278 -281.051)
		(end 381.45466 -281.046174)
		(width 0.09525)
		(layer "In2.Cu")
		(net "M_I_CPU0_SB_DQS_DN<1>")
	)
	(segment
		(start 413.455104 -294.969438)
		(end 414.047432 -294.969438)
		(width 0.16002)
		(layer "In2.Cu")
		(net "M_I_CPU0_SB_DQS_DN<1>")
	)
	(segment
		(start 429.925734 -294.811958)
		(end 430.042574 -294.928798)
		(width 0.16002)
		(layer "In2.Cu")
		(net "M_I_CPU0_SB_DQS_DN<1>")
	)
	(segment
		(start 431.28311 -294.811958)
		(end 431.55616 -295.085008)
		(width 0.16002)
		(layer "In2.Cu")
		(net "M_I_CPU0_SB_DQS_DN<1>")
	)
	(segment
		(start 421.591486 -294.969438)
		(end 422.432226 -294.128698)
		(width 0.16002)
		(layer "In2.Cu")
		(net "M_I_CPU0_SB_DQS_DN<1>")
	)
	(segment
		(start 380.875032 -281.046174)
		(end 380.883414 -281.051)
		(width 0.09525)
		(layer "In2.Cu")
		(net "M_I_CPU0_SB_DQS_DN<1>")
	)
	(segment
		(start 430.042574 -294.928798)
		(end 430.522634 -294.928798)
		(width 0.16002)
		(layer "In2.Cu")
		(net "M_I_CPU0_SB_DQS_DN<1>")
	)
	(segment
		(start 420.999158 -294.969438)
		(end 421.591486 -294.969438)
		(width 0.16002)
		(layer "In2.Cu")
		(net "M_I_CPU0_SB_DQS_DN<1>")
	)
	(segment
		(start 430.639474 -294.811958)
		(end 431.28311 -294.811958)
		(width 0.16002)
		(layer "In2.Cu")
		(net "M_I_CPU0_SB_DQS_DN<1>")
	)
	(segment
		(start 393.476988 -281.126692)
		(end 393.913868 -281.126692)
		(width 0.09525)
		(layer "In2.Cu")
		(net "M_I_CPU0_SB_DQS_DN<1>")
	)
	(segment
		(start 410.534358 -294.00246)
		(end 411.193996 -294.662098)
		(width 0.16002)
		(layer "In2.Cu")
		(net "M_I_CPU0_SB_DQS_DN<1>")
	)
	(segment
		(start 428.568358 -294.994838)
		(end 429.262794 -294.994838)
		(width 0.16002)
		(layer "In2.Cu")
		(net "M_I_CPU0_SB_DQS_DN<1>")
	)
	(segment
		(start 418.558472 -294.662098)
		(end 420.691818 -294.662098)
		(width 0.16002)
		(layer "In2.Cu")
		(net "M_I_CPU0_SB_DQS_DN<1>")
	)
	(segment
		(start 389.33501 -281.046174)
		(end 389.343392 -281.051)
		(width 0.09525)
		(layer "In2.Cu")
		(net "M_I_CPU0_SB_DQS_DN<1>")
	)
	(segment
		(start 393.476734 -281.126946)
		(end 393.476988 -281.126692)
		(width 0.09525)
		(layer "In2.Cu")
		(net "M_I_CPU0_SB_DQS_DN<1>")
	)
	(segment
		(start 429.262794 -294.994838)
		(end 429.445674 -294.811958)
		(width 0.16002)
		(layer "In2.Cu")
		(net "M_I_CPU0_SB_DQS_DN<1>")
	)
	(segment
		(start 397.25981 -281.2288)
		(end 401.539964 -285.508954)
		(width 0.16002)
		(layer "In2.Cu")
		(net "M_I_CPU0_SB_DQS_DN<1>")
	)
	(segment
		(start 394.321538 -280.719022)
		(end 395.102842 -280.719022)
		(width 0.09525)
		(layer "In2.Cu")
		(net "M_I_CPU0_SB_DQS_DN<1>")
	)
	(segment
		(start 425.300394 -293.812214)
		(end 425.874434 -294.386254)
		(width 0.16002)
		(layer "In2.Cu")
		(net "M_I_CPU0_SB_DQS_DN<1>")
	)
	(segment
		(start 393.103862 -281.051)
		(end 393.12469 -281.063192)
		(width 0.09525)
		(layer "In2.Cu")
		(net "M_I_CPU0_SB_DQS_DN<1>")
	)
	(segment
		(start 377.72086 -281.11069)
		(end 377.744228 -281.023822)
		(width 0.09525)
		(layer "In2.Cu")
		(net "M_I_CPU0_SB_DQS_DN<1>")
	)
	(segment
		(start 415.413444 -294.128698)
		(end 415.729928 -293.812214)
		(width 0.16002)
		(layer "In2.Cu")
		(net "M_I_CPU0_SB_DQS_DN<1>")
	)
	(segment
		(start 401.539964 -285.508954)
		(end 402.407628 -285.508954)
		(width 0.16002)
		(layer "In2.Cu")
		(net "M_I_CPU0_SB_DQS_DN<1>")
	)
	(segment
		(start 393.09548 -281.046174)
		(end 393.103862 -281.051)
		(width 0.09525)
		(layer "In2.Cu")
		(net "M_I_CPU0_SB_DQS_DN<1>")
	)
	(segment
		(start 384.634994 -281.046174)
		(end 384.643376 -281.051)
		(width 0.09525)
		(layer "In2.Cu")
		(net "M_I_CPU0_SB_DQS_DN<1>")
	)
	(segment
		(start 422.957498 -294.128698)
		(end 423.273982 -293.812214)
		(width 0.16002)
		(layer "In2.Cu")
		(net "M_I_CPU0_SB_DQS_DN<1>")
	)
	(segment
		(start 422.432226 -294.128698)
		(end 422.957498 -294.128698)
		(width 0.16002)
		(layer "In2.Cu")
		(net "M_I_CPU0_SB_DQS_DN<1>")
	)
	(segment
		(start 427.959774 -294.386254)
		(end 428.568358 -294.994838)
		(width 0.16002)
		(layer "In2.Cu")
		(net "M_I_CPU0_SB_DQS_DN<1>")
	)
	(segment
		(start 385.20624 -281.051)
		(end 385.214622 -281.046174)
		(width 0.09525)
		(layer "In2.Cu")
		(net "M_I_CPU0_SB_DQS_DN<1>")
	)
	(segment
		(start 386.146294 -281.051)
		(end 386.154676 -281.046174)
		(width 0.09525)
		(layer "In2.Cu")
		(net "M_I_CPU0_SB_DQS_DN<1>")
	)
	(segment
		(start 395.859254 -281.2288)
		(end 397.25981 -281.2288)
		(width 0.16002)
		(layer "In2.Cu")
		(net "M_I_CPU0_SB_DQS_DN<1>")
	)
	(segment
		(start 425.874434 -294.386254)
		(end 427.959774 -294.386254)
		(width 0.16002)
		(layer "In2.Cu")
		(net "M_I_CPU0_SB_DQS_DN<1>")
	)
	(segment
		(start 379.934978 -281.046174)
		(end 379.94336 -281.051)
		(width 0.09525)
		(layer "In2.Cu")
		(net "M_I_CPU0_SB_DQS_DN<1>")
	)
	(segment
		(start 414.047432 -294.969438)
		(end 414.888172 -294.128698)
		(width 0.16002)
		(layer "In2.Cu")
		(net "M_I_CPU0_SB_DQS_DN<1>")
	)
	(segment
		(start 430.522634 -294.928798)
		(end 430.639474 -294.811958)
		(width 0.16002)
		(layer "In2.Cu")
		(net "M_I_CPU0_SB_DQS_DN<1>")
	)
	(segment
		(start 415.729928 -293.812214)
		(end 417.708588 -293.812214)
		(width 0.16002)
		(layer "In2.Cu")
		(net "M_I_CPU0_SB_DQS_DN<1>")
	)
	(segment
		(start 429.445674 -294.811958)
		(end 429.925734 -294.811958)
		(width 0.16002)
		(layer "In2.Cu")
		(net "M_I_CPU0_SB_DQS_DN<1>")
	)
	(segment
		(start 423.273982 -293.812214)
		(end 425.300394 -293.812214)
		(width 0.16002)
		(layer "In2.Cu")
		(net "M_I_CPU0_SB_DQS_DN<1>")
	)
	(segment
		(start 391.78611 -281.051)
		(end 391.794492 -281.046174)
		(width 0.09525)
		(layer "In2.Cu")
		(net "M_I_CPU0_SB_DQS_DN<1>")
	)
	(segment
		(start 383.69494 -281.046174)
		(end 383.703322 -281.051)
		(width 0.09525)
		(layer "In2.Cu")
		(net "M_I_CPU0_SB_DQS_DN<1>")
	)
	(segment
		(start 388.394956 -281.046174)
		(end 388.403338 -281.051)
		(width 0.09525)
		(layer "In2.Cu")
		(net "M_I_CPU0_SB_DQS_DN<1>")
	)
	(segment
		(start 395.102842 -280.719022)
		(end 395.553692 -281.169872)
		(width 0.09525)
		(layer "In2.Cu")
		(net "M_I_CPU0_SB_DQS_DN<1>")
	)
	(segment
		(start 395.776704 -281.169872)
		(end 395.835632 -281.2288)
		(width 0.09525)
		(layer "In2.Cu")
		(net "M_I_CPU0_SB_DQS_DN<1>")
	)
	(segment
		(start 392.712448 -281.059636)
		(end 392.72718 -281.051)
		(width 0.09525)
		(layer "In2.Cu")
		(net "M_I_CPU0_SB_DQS_DN<1>")
	)
	(arc
		(start 383.326132 -281.051)
		(mid 383.509907 -281.000228)
		(end 383.69494 -281.046174)
		(width 0.09525)
		(layer "In2.Cu")
		(net "M_I_CPU0_SB_DQS_DN<1>")
	)
	(arc
		(start 382.386332 -281.051)
		(mid 382.5748 -281.000323)
		(end 382.763268 -281.051)
		(width 0.09525)
		(layer "In2.Cu")
		(net "M_I_CPU0_SB_DQS_DN<1>")
	)
	(arc
		(start 389.343392 -281.051)
		(mid 389.624824 -281.126755)
		(end 389.906256 -281.051)
		(width 0.09525)
		(layer "In2.Cu")
		(net "M_I_CPU0_SB_DQS_DN<1>")
	)
	(arc
		(start 386.523484 -281.051)
		(mid 386.804916 -281.126755)
		(end 387.086348 -281.051)
		(width 0.09525)
		(layer "In2.Cu")
		(net "M_I_CPU0_SB_DQS_DN<1>")
	)
	(arc
		(start 393.12469 -281.063192)
		(mid 393.249393 -281.110487)
		(end 393.381738 -281.126946)
		(width 0.09525)
		(layer "In2.Cu")
		(net "M_I_CPU0_SB_DQS_DN<1>")
	)
	(arc
		(start 385.58343 -281.051)
		(mid 385.864862 -281.126755)
		(end 386.146294 -281.051)
		(width 0.09525)
		(layer "In2.Cu")
		(net "M_I_CPU0_SB_DQS_DN<1>")
	)
	(arc
		(start 390.84631 -281.051)
		(mid 391.034778 -281.000323)
		(end 391.223246 -281.051)
		(width 0.09525)
		(layer "In2.Cu")
		(net "M_I_CPU0_SB_DQS_DN<1>")
	)
	(arc
		(start 380.883414 -281.051)
		(mid 381.164846 -281.126755)
		(end 381.446278 -281.051)
		(width 0.09525)
		(layer "In2.Cu")
		(net "M_I_CPU0_SB_DQS_DN<1>")
	)
	(arc
		(start 381.45466 -281.046174)
		(mid 381.639692 -281.00026)
		(end 381.823468 -281.051)
		(width 0.09525)
		(layer "In2.Cu")
		(net "M_I_CPU0_SB_DQS_DN<1>")
	)
	(arc
		(start 385.214622 -281.046174)
		(mid 385.399654 -281.00026)
		(end 385.58343 -281.051)
		(width 0.09525)
		(layer "In2.Cu")
		(net "M_I_CPU0_SB_DQS_DN<1>")
	)
	(arc
		(start 387.463284 -281.051)
		(mid 387.744716 -281.126755)
		(end 388.026148 -281.051)
		(width 0.09525)
		(layer "In2.Cu")
		(net "M_I_CPU0_SB_DQS_DN<1>")
	)
	(arc
		(start 392.163808 -281.051)
		(mid 392.43699 -281.126942)
		(end 392.712448 -281.059636)
		(width 0.09525)
		(layer "In2.Cu")
		(net "M_I_CPU0_SB_DQS_DN<1>")
	)
	(arc
		(start 377.744228 -281.023822)
		(mid 377.90691 -281.00169)
		(end 378.063506 -281.051)
		(width 0.09525)
		(layer "In2.Cu")
		(net "M_I_CPU0_SB_DQS_DN<1>")
	)
	(arc
		(start 388.403338 -281.051)
		(mid 388.68477 -281.126755)
		(end 388.966202 -281.051)
		(width 0.09525)
		(layer "In2.Cu")
		(net "M_I_CPU0_SB_DQS_DN<1>")
	)
	(arc
		(start 388.966202 -281.051)
		(mid 389.149977 -281.000228)
		(end 389.33501 -281.046174)
		(width 0.09525)
		(layer "In2.Cu")
		(net "M_I_CPU0_SB_DQS_DN<1>")
	)
	(arc
		(start 387.086348 -281.051)
		(mid 387.274816 -281.000323)
		(end 387.463284 -281.051)
		(width 0.09525)
		(layer "In2.Cu")
		(net "M_I_CPU0_SB_DQS_DN<1>")
	)
	(arc
		(start 391.794492 -281.046174)
		(mid 391.979778 -281.000138)
		(end 392.163808 -281.051)
		(width 0.09525)
		(layer "In2.Cu")
		(net "M_I_CPU0_SB_DQS_DN<1>")
	)
	(arc
		(start 379.94336 -281.051)
		(mid 380.224792 -281.126755)
		(end 380.506224 -281.051)
		(width 0.09525)
		(layer "In2.Cu")
		(net "M_I_CPU0_SB_DQS_DN<1>")
	)
	(arc
		(start 384.643376 -281.051)
		(mid 384.924808 -281.126755)
		(end 385.20624 -281.051)
		(width 0.09525)
		(layer "In2.Cu")
		(net "M_I_CPU0_SB_DQS_DN<1>")
	)
	(arc
		(start 378.62637 -281.051)
		(mid 378.814838 -281.000323)
		(end 379.003306 -281.051)
		(width 0.09525)
		(layer "In2.Cu")
		(net "M_I_CPU0_SB_DQS_DN<1>")
	)
	(arc
		(start 384.266186 -281.051)
		(mid 384.449961 -281.000228)
		(end 384.634994 -281.046174)
		(width 0.09525)
		(layer "In2.Cu")
		(net "M_I_CPU0_SB_DQS_DN<1>")
	)
	(arc
		(start 379.56617 -281.051)
		(mid 379.749945 -281.000228)
		(end 379.934978 -281.046174)
		(width 0.09525)
		(layer "In2.Cu")
		(net "M_I_CPU0_SB_DQS_DN<1>")
	)
	(arc
		(start 381.823468 -281.051)
		(mid 382.1049 -281.126755)
		(end 382.386332 -281.051)
		(width 0.09525)
		(layer "In2.Cu")
		(net "M_I_CPU0_SB_DQS_DN<1>")
	)
	(arc
		(start 386.154676 -281.046174)
		(mid 386.339708 -281.00026)
		(end 386.523484 -281.051)
		(width 0.09525)
		(layer "In2.Cu")
		(net "M_I_CPU0_SB_DQS_DN<1>")
	)
	(arc
		(start 379.003306 -281.051)
		(mid 379.284738 -281.126755)
		(end 379.56617 -281.051)
		(width 0.09525)
		(layer "In2.Cu")
		(net "M_I_CPU0_SB_DQS_DN<1>")
	)
	(arc
		(start 382.763268 -281.051)
		(mid 383.0447 -281.126755)
		(end 383.326132 -281.051)
		(width 0.09525)
		(layer "In2.Cu")
		(net "M_I_CPU0_SB_DQS_DN<1>")
	)
	(arc
		(start 380.506224 -281.051)
		(mid 380.689999 -281.000228)
		(end 380.875032 -281.046174)
		(width 0.09525)
		(layer "In2.Cu")
		(net "M_I_CPU0_SB_DQS_DN<1>")
	)
	(arc
		(start 390.283446 -281.051)
		(mid 390.564878 -281.126755)
		(end 390.84631 -281.051)
		(width 0.09525)
		(layer "In2.Cu")
		(net "M_I_CPU0_SB_DQS_DN<1>")
	)
	(arc
		(start 388.026148 -281.051)
		(mid 388.209923 -281.000228)
		(end 388.394956 -281.046174)
		(width 0.09525)
		(layer "In2.Cu")
		(net "M_I_CPU0_SB_DQS_DN<1>")
	)
	(arc
		(start 383.703322 -281.051)
		(mid 383.984754 -281.126755)
		(end 384.266186 -281.051)
		(width 0.09525)
		(layer "In2.Cu")
		(net "M_I_CPU0_SB_DQS_DN<1>")
	)
	(arc
		(start 391.223246 -281.051)
		(mid 391.504678 -281.126755)
		(end 391.78611 -281.051)
		(width 0.09525)
		(layer "In2.Cu")
		(net "M_I_CPU0_SB_DQS_DN<1>")
	)
	(arc
		(start 392.72718 -281.051)
		(mid 392.910701 -281.000356)
		(end 393.09548 -281.046174)
		(width 0.09525)
		(layer "In2.Cu")
		(net "M_I_CPU0_SB_DQS_DN<1>")
	)
	(arc
		(start 389.914638 -281.046174)
		(mid 390.09967 -281.00026)
		(end 390.283446 -281.051)
		(width 0.09525)
		(layer "In2.Cu")
		(net "M_I_CPU0_SB_DQS_DN<1>")
	)
	(arc
		(start 378.063506 -281.051)
		(mid 378.344938 -281.126755)
		(end 378.62637 -281.051)
		(width 0.09525)
		(layer "In2.Cu")
		(net "M_I_CPU0_SB_DQS_DN<1>")
	)
	(segment
		(start 377.407932 -276.250146)
		(end 377.874784 -276.516084)
		(width 0.12954)
		(layer "F.Cu")
		(net "M_I_CPU0_SB_DQS_DN<0>")
	)
	(segment
		(start 385.20624 -276.190964)
		(end 385.214622 -276.186138)
		(width 0.09525)
		(layer "In2.Cu")
		(net "M_I_CPU0_SB_DQS_DN<0>")
	)
	(segment
		(start 422.432226 -284.778704)
		(end 422.957498 -284.778704)
		(width 0.16002)
		(layer "In2.Cu")
		(net "M_I_CPU0_SB_DQS_DN<0>")
	)
	(segment
		(start 389.906256 -276.190964)
		(end 389.914638 -276.186138)
		(width 0.09525)
		(layer "In2.Cu")
		(net "M_I_CPU0_SB_DQS_DN<0>")
	)
	(segment
		(start 395.776704 -275.140928)
		(end 395.835632 -275.199856)
		(width 0.09525)
		(layer "In2.Cu")
		(net "M_I_CPU0_SB_DQS_DN<0>")
	)
	(segment
		(start 389.33501 -276.186138)
		(end 389.343392 -276.190964)
		(width 0.09525)
		(layer "In2.Cu")
		(net "M_I_CPU0_SB_DQS_DN<0>")
	)
	(segment
		(start 388.394956 -276.186138)
		(end 388.403338 -276.190964)
		(width 0.09525)
		(layer "In2.Cu")
		(net "M_I_CPU0_SB_DQS_DN<0>")
	)
	(segment
		(start 392.712448 -276.1996)
		(end 392.72718 -276.190964)
		(width 0.09525)
		(layer "In2.Cu")
		(net "M_I_CPU0_SB_DQS_DN<0>")
	)
	(segment
		(start 381.446278 -276.190964)
		(end 381.45466 -276.186138)
		(width 0.09525)
		(layer "In2.Cu")
		(net "M_I_CPU0_SB_DQS_DN<0>")
	)
	(segment
		(start 429.224694 -285.644844)
		(end 429.407574 -285.461964)
		(width 0.16002)
		(layer "In2.Cu")
		(net "M_I_CPU0_SB_DQS_DN<0>")
	)
	(segment
		(start 413.455104 -285.619444)
		(end 414.047432 -285.619444)
		(width 0.16002)
		(layer "In2.Cu")
		(net "M_I_CPU0_SB_DQS_DN<0>")
	)
	(segment
		(start 408.188922 -282.909518)
		(end 408.797506 -282.909518)
		(width 0.16002)
		(layer "In2.Cu")
		(net "M_I_CPU0_SB_DQS_DN<0>")
	)
	(segment
		(start 393.103862 -276.190964)
		(end 393.12469 -276.203156)
		(width 0.09525)
		(layer "In2.Cu")
		(net "M_I_CPU0_SB_DQS_DN<0>")
	)
	(segment
		(start 393.78128 -276.102572)
		(end 394.680948 -275.202904)
		(width 0.09525)
		(layer "In2.Cu")
		(net "M_I_CPU0_SB_DQS_DN<0>")
	)
	(segment
		(start 422.957498 -284.778704)
		(end 423.273982 -284.46222)
		(width 0.16002)
		(layer "In2.Cu")
		(net "M_I_CPU0_SB_DQS_DN<0>")
	)
	(segment
		(start 415.413444 -284.778704)
		(end 415.729928 -284.46222)
		(width 0.16002)
		(layer "In2.Cu")
		(net "M_I_CPU0_SB_DQS_DN<0>")
	)
	(segment
		(start 391.78611 -276.190964)
		(end 391.794492 -276.186138)
		(width 0.09525)
		(layer "In2.Cu")
		(net "M_I_CPU0_SB_DQS_DN<0>")
	)
	(segment
		(start 384.634994 -276.186138)
		(end 384.643376 -276.190964)
		(width 0.09525)
		(layer "In2.Cu")
		(net "M_I_CPU0_SB_DQS_DN<0>")
	)
	(segment
		(start 379.934978 -276.186138)
		(end 379.94336 -276.190964)
		(width 0.09525)
		(layer "In2.Cu")
		(net "M_I_CPU0_SB_DQS_DN<0>")
	)
	(segment
		(start 423.273982 -284.46222)
		(end 425.300394 -284.46222)
		(width 0.16002)
		(layer "In2.Cu")
		(net "M_I_CPU0_SB_DQS_DN<0>")
	)
	(segment
		(start 413.147764 -285.312104)
		(end 413.455104 -285.619444)
		(width 0.16002)
		(layer "In2.Cu")
		(net "M_I_CPU0_SB_DQS_DN<0>")
	)
	(segment
		(start 408.797506 -282.909518)
		(end 411.200092 -285.312104)
		(width 0.16002)
		(layer "In2.Cu")
		(net "M_I_CPU0_SB_DQS_DN<0>")
	)
	(segment
		(start 377.874784 -276.516084)
		(end 377.72086 -276.250654)
		(width 0.09525)
		(layer "In2.Cu")
		(net "M_I_CPU0_SB_DQS_DN<0>")
	)
	(segment
		(start 420.999158 -285.619444)
		(end 421.591486 -285.619444)
		(width 0.16002)
		(layer "In2.Cu")
		(net "M_I_CPU0_SB_DQS_DN<0>")
	)
	(segment
		(start 414.047432 -285.619444)
		(end 414.888172 -284.778704)
		(width 0.16002)
		(layer "In2.Cu")
		(net "M_I_CPU0_SB_DQS_DN<0>")
	)
	(segment
		(start 395.835632 -275.199856)
		(end 395.859254 -275.199856)
		(width 0.09525)
		(layer "In2.Cu")
		(net "M_I_CPU0_SB_DQS_DN<0>")
	)
	(segment
		(start 400.47926 -275.199856)
		(end 408.188922 -282.909518)
		(width 0.16002)
		(layer "In2.Cu")
		(net "M_I_CPU0_SB_DQS_DN<0>")
	)
	(segment
		(start 418.558472 -285.312104)
		(end 420.691818 -285.312104)
		(width 0.16002)
		(layer "In2.Cu")
		(net "M_I_CPU0_SB_DQS_DN<0>")
	)
	(segment
		(start 430.601374 -285.461964)
		(end 431.28311 -285.461964)
		(width 0.16002)
		(layer "In2.Cu")
		(net "M_I_CPU0_SB_DQS_DN<0>")
	)
	(segment
		(start 415.729928 -284.46222)
		(end 417.708588 -284.46222)
		(width 0.16002)
		(layer "In2.Cu")
		(net "M_I_CPU0_SB_DQS_DN<0>")
	)
	(segment
		(start 431.28311 -285.461964)
		(end 431.55616 -285.735014)
		(width 0.16002)
		(layer "In2.Cu")
		(net "M_I_CPU0_SB_DQS_DN<0>")
	)
	(segment
		(start 377.72086 -276.250654)
		(end 377.744228 -276.163786)
		(width 0.09525)
		(layer "In2.Cu")
		(net "M_I_CPU0_SB_DQS_DN<0>")
	)
	(segment
		(start 425.300394 -284.46222)
		(end 425.874434 -285.03626)
		(width 0.16002)
		(layer "In2.Cu")
		(net "M_I_CPU0_SB_DQS_DN<0>")
	)
	(segment
		(start 393.09548 -276.186138)
		(end 393.103862 -276.190964)
		(width 0.09525)
		(layer "In2.Cu")
		(net "M_I_CPU0_SB_DQS_DN<0>")
	)
	(segment
		(start 430.484534 -285.578804)
		(end 430.601374 -285.461964)
		(width 0.16002)
		(layer "In2.Cu")
		(net "M_I_CPU0_SB_DQS_DN<0>")
	)
	(segment
		(start 380.875032 -276.186138)
		(end 380.883414 -276.190964)
		(width 0.09525)
		(layer "In2.Cu")
		(net "M_I_CPU0_SB_DQS_DN<0>")
	)
	(segment
		(start 414.888172 -284.778704)
		(end 415.413444 -284.778704)
		(width 0.16002)
		(layer "In2.Cu")
		(net "M_I_CPU0_SB_DQS_DN<0>")
	)
	(segment
		(start 395.286738 -275.140928)
		(end 395.776704 -275.140928)
		(width 0.09525)
		(layer "In2.Cu")
		(net "M_I_CPU0_SB_DQS_DN<0>")
	)
	(segment
		(start 430.004474 -285.578804)
		(end 430.484534 -285.578804)
		(width 0.16002)
		(layer "In2.Cu")
		(net "M_I_CPU0_SB_DQS_DN<0>")
	)
	(segment
		(start 417.708588 -284.46222)
		(end 418.558472 -285.312104)
		(width 0.16002)
		(layer "In2.Cu")
		(net "M_I_CPU0_SB_DQS_DN<0>")
	)
	(segment
		(start 428.568358 -285.644844)
		(end 429.224694 -285.644844)
		(width 0.16002)
		(layer "In2.Cu")
		(net "M_I_CPU0_SB_DQS_DN<0>")
	)
	(segment
		(start 383.69494 -276.186138)
		(end 383.703322 -276.190964)
		(width 0.09525)
		(layer "In2.Cu")
		(net "M_I_CPU0_SB_DQS_DN<0>")
	)
	(segment
		(start 427.959774 -285.03626)
		(end 428.568358 -285.644844)
		(width 0.16002)
		(layer "In2.Cu")
		(net "M_I_CPU0_SB_DQS_DN<0>")
	)
	(segment
		(start 429.407574 -285.461964)
		(end 429.887634 -285.461964)
		(width 0.16002)
		(layer "In2.Cu")
		(net "M_I_CPU0_SB_DQS_DN<0>")
	)
	(segment
		(start 411.200092 -285.312104)
		(end 413.147764 -285.312104)
		(width 0.16002)
		(layer "In2.Cu")
		(net "M_I_CPU0_SB_DQS_DN<0>")
	)
	(segment
		(start 395.224762 -275.202904)
		(end 395.286738 -275.140928)
		(width 0.09525)
		(layer "In2.Cu")
		(net "M_I_CPU0_SB_DQS_DN<0>")
	)
	(segment
		(start 429.887634 -285.461964)
		(end 430.004474 -285.578804)
		(width 0.16002)
		(layer "In2.Cu")
		(net "M_I_CPU0_SB_DQS_DN<0>")
	)
	(segment
		(start 386.146294 -276.190964)
		(end 386.154676 -276.186138)
		(width 0.09525)
		(layer "In2.Cu")
		(net "M_I_CPU0_SB_DQS_DN<0>")
	)
	(segment
		(start 425.874434 -285.03626)
		(end 427.959774 -285.03626)
		(width 0.16002)
		(layer "In2.Cu")
		(net "M_I_CPU0_SB_DQS_DN<0>")
	)
	(segment
		(start 395.859254 -275.199856)
		(end 400.47926 -275.199856)
		(width 0.16002)
		(layer "In2.Cu")
		(net "M_I_CPU0_SB_DQS_DN<0>")
	)
	(segment
		(start 394.680948 -275.202904)
		(end 395.224762 -275.202904)
		(width 0.09525)
		(layer "In2.Cu")
		(net "M_I_CPU0_SB_DQS_DN<0>")
	)
	(segment
		(start 420.691818 -285.312104)
		(end 420.999158 -285.619444)
		(width 0.16002)
		(layer "In2.Cu")
		(net "M_I_CPU0_SB_DQS_DN<0>")
	)
	(segment
		(start 421.591486 -285.619444)
		(end 422.432226 -284.778704)
		(width 0.16002)
		(layer "In2.Cu")
		(net "M_I_CPU0_SB_DQS_DN<0>")
	)
	(arc
		(start 393.12469 -276.203156)
		(mid 393.397295 -276.266952)
		(end 393.666726 -276.190964)
		(width 0.09525)
		(layer "In2.Cu")
		(net "M_I_CPU0_SB_DQS_DN<0>")
	)
	(arc
		(start 393.666726 -276.190964)
		(mid 393.726861 -276.150473)
		(end 393.78128 -276.102572)
		(width 0.09525)
		(layer "In2.Cu")
		(net "M_I_CPU0_SB_DQS_DN<0>")
	)
	(arc
		(start 382.763268 -276.190964)
		(mid 383.0447 -276.266719)
		(end 383.326132 -276.190964)
		(width 0.09525)
		(layer "In2.Cu")
		(net "M_I_CPU0_SB_DQS_DN<0>")
	)
	(arc
		(start 391.223246 -276.190964)
		(mid 391.504678 -276.266719)
		(end 391.78611 -276.190964)
		(width 0.09525)
		(layer "In2.Cu")
		(net "M_I_CPU0_SB_DQS_DN<0>")
	)
	(arc
		(start 389.914638 -276.186138)
		(mid 390.09967 -276.140224)
		(end 390.283446 -276.190964)
		(width 0.09525)
		(layer "In2.Cu")
		(net "M_I_CPU0_SB_DQS_DN<0>")
	)
	(arc
		(start 386.523484 -276.190964)
		(mid 386.804916 -276.266719)
		(end 387.086348 -276.190964)
		(width 0.09525)
		(layer "In2.Cu")
		(net "M_I_CPU0_SB_DQS_DN<0>")
	)
	(arc
		(start 392.72718 -276.190964)
		(mid 392.910701 -276.14032)
		(end 393.09548 -276.186138)
		(width 0.09525)
		(layer "In2.Cu")
		(net "M_I_CPU0_SB_DQS_DN<0>")
	)
	(arc
		(start 389.343392 -276.190964)
		(mid 389.624824 -276.266719)
		(end 389.906256 -276.190964)
		(width 0.09525)
		(layer "In2.Cu")
		(net "M_I_CPU0_SB_DQS_DN<0>")
	)
	(arc
		(start 378.62637 -276.190964)
		(mid 378.814838 -276.140287)
		(end 379.003306 -276.190964)
		(width 0.09525)
		(layer "In2.Cu")
		(net "M_I_CPU0_SB_DQS_DN<0>")
	)
	(arc
		(start 379.003306 -276.190964)
		(mid 379.284738 -276.266719)
		(end 379.56617 -276.190964)
		(width 0.09525)
		(layer "In2.Cu")
		(net "M_I_CPU0_SB_DQS_DN<0>")
	)
	(arc
		(start 385.214622 -276.186138)
		(mid 385.399654 -276.140224)
		(end 385.58343 -276.190964)
		(width 0.09525)
		(layer "In2.Cu")
		(net "M_I_CPU0_SB_DQS_DN<0>")
	)
	(arc
		(start 379.56617 -276.190964)
		(mid 379.749945 -276.140192)
		(end 379.934978 -276.186138)
		(width 0.09525)
		(layer "In2.Cu")
		(net "M_I_CPU0_SB_DQS_DN<0>")
	)
	(arc
		(start 386.154676 -276.186138)
		(mid 386.339708 -276.140224)
		(end 386.523484 -276.190964)
		(width 0.09525)
		(layer "In2.Cu")
		(net "M_I_CPU0_SB_DQS_DN<0>")
	)
	(arc
		(start 378.063506 -276.190964)
		(mid 378.344938 -276.266719)
		(end 378.62637 -276.190964)
		(width 0.09525)
		(layer "In2.Cu")
		(net "M_I_CPU0_SB_DQS_DN<0>")
	)
	(arc
		(start 388.966202 -276.190964)
		(mid 389.149977 -276.140192)
		(end 389.33501 -276.186138)
		(width 0.09525)
		(layer "In2.Cu")
		(net "M_I_CPU0_SB_DQS_DN<0>")
	)
	(arc
		(start 390.84631 -276.190964)
		(mid 391.034778 -276.140287)
		(end 391.223246 -276.190964)
		(width 0.09525)
		(layer "In2.Cu")
		(net "M_I_CPU0_SB_DQS_DN<0>")
	)
	(arc
		(start 388.403338 -276.190964)
		(mid 388.68477 -276.266719)
		(end 388.966202 -276.190964)
		(width 0.09525)
		(layer "In2.Cu")
		(net "M_I_CPU0_SB_DQS_DN<0>")
	)
	(arc
		(start 381.823468 -276.190964)
		(mid 382.1049 -276.266719)
		(end 382.386332 -276.190964)
		(width 0.09525)
		(layer "In2.Cu")
		(net "M_I_CPU0_SB_DQS_DN<0>")
	)
	(arc
		(start 381.45466 -276.186138)
		(mid 381.639692 -276.140224)
		(end 381.823468 -276.190964)
		(width 0.09525)
		(layer "In2.Cu")
		(net "M_I_CPU0_SB_DQS_DN<0>")
	)
	(arc
		(start 387.086348 -276.190964)
		(mid 387.274816 -276.140287)
		(end 387.463284 -276.190964)
		(width 0.09525)
		(layer "In2.Cu")
		(net "M_I_CPU0_SB_DQS_DN<0>")
	)
	(arc
		(start 391.794492 -276.186138)
		(mid 391.979778 -276.140102)
		(end 392.163808 -276.190964)
		(width 0.09525)
		(layer "In2.Cu")
		(net "M_I_CPU0_SB_DQS_DN<0>")
	)
	(arc
		(start 382.386332 -276.190964)
		(mid 382.5748 -276.140287)
		(end 382.763268 -276.190964)
		(width 0.09525)
		(layer "In2.Cu")
		(net "M_I_CPU0_SB_DQS_DN<0>")
	)
	(arc
		(start 384.266186 -276.190964)
		(mid 384.449961 -276.140192)
		(end 384.634994 -276.186138)
		(width 0.09525)
		(layer "In2.Cu")
		(net "M_I_CPU0_SB_DQS_DN<0>")
	)
	(arc
		(start 390.283446 -276.190964)
		(mid 390.564878 -276.266719)
		(end 390.84631 -276.190964)
		(width 0.09525)
		(layer "In2.Cu")
		(net "M_I_CPU0_SB_DQS_DN<0>")
	)
	(arc
		(start 383.326132 -276.190964)
		(mid 383.509907 -276.140192)
		(end 383.69494 -276.186138)
		(width 0.09525)
		(layer "In2.Cu")
		(net "M_I_CPU0_SB_DQS_DN<0>")
	)
	(arc
		(start 380.506224 -276.190964)
		(mid 380.689999 -276.140192)
		(end 380.875032 -276.186138)
		(width 0.09525)
		(layer "In2.Cu")
		(net "M_I_CPU0_SB_DQS_DN<0>")
	)
	(arc
		(start 388.026148 -276.190964)
		(mid 388.209923 -276.140192)
		(end 388.394956 -276.186138)
		(width 0.09525)
		(layer "In2.Cu")
		(net "M_I_CPU0_SB_DQS_DN<0>")
	)
	(arc
		(start 379.94336 -276.190964)
		(mid 380.224792 -276.266719)
		(end 380.506224 -276.190964)
		(width 0.09525)
		(layer "In2.Cu")
		(net "M_I_CPU0_SB_DQS_DN<0>")
	)
	(arc
		(start 377.744228 -276.163786)
		(mid 377.90691 -276.141654)
		(end 378.063506 -276.190964)
		(width 0.09525)
		(layer "In2.Cu")
		(net "M_I_CPU0_SB_DQS_DN<0>")
	)
	(arc
		(start 387.463284 -276.190964)
		(mid 387.744716 -276.266719)
		(end 388.026148 -276.190964)
		(width 0.09525)
		(layer "In2.Cu")
		(net "M_I_CPU0_SB_DQS_DN<0>")
	)
	(arc
		(start 385.58343 -276.190964)
		(mid 385.864862 -276.266719)
		(end 386.146294 -276.190964)
		(width 0.09525)
		(layer "In2.Cu")
		(net "M_I_CPU0_SB_DQS_DN<0>")
	)
	(arc
		(start 383.703322 -276.190964)
		(mid 383.984754 -276.266719)
		(end 384.266186 -276.190964)
		(width 0.09525)
		(layer "In2.Cu")
		(net "M_I_CPU0_SB_DQS_DN<0>")
	)
	(arc
		(start 380.883414 -276.190964)
		(mid 381.164846 -276.266719)
		(end 381.446278 -276.190964)
		(width 0.09525)
		(layer "In2.Cu")
		(net "M_I_CPU0_SB_DQS_DN<0>")
	)
	(arc
		(start 392.163808 -276.190964)
		(mid 392.43699 -276.266906)
		(end 392.712448 -276.1996)
		(width 0.09525)
		(layer "In2.Cu")
		(net "M_I_CPU0_SB_DQS_DN<0>")
	)
	(arc
		(start 384.643376 -276.190964)
		(mid 384.924808 -276.266719)
		(end 385.20624 -276.190964)
		(width 0.09525)
		(layer "In2.Cu")
		(net "M_I_CPU0_SB_DQS_DN<0>")
	)
	(segment
		(start 375.528078 -279.49017)
		(end 375.99493 -279.756108)
		(width 0.10668)
		(layer "F.Cu")
		(net "M_I_CPU0_SB_DQ<9>")
	)
	(segment
		(start 393.679934 -280.008838)
		(end 393.789662 -279.89911)
		(width 0.0889)
		(layer "In2.Cu")
		(net "M_I_CPU0_SB_DQ<9>")
	)
	(segment
		(start 389.333486 -280.083514)
		(end 389.341868 -280.078688)
		(width 0.0889)
		(layer "In2.Cu")
		(net "M_I_CPU0_SB_DQ<9>")
	)
	(segment
		(start 419.699694 -292.960044)
		(end 420.252652 -292.960044)
		(width 0.14478)
		(layer "In2.Cu")
		(net "M_I_CPU0_SB_DQ<9>")
	)
	(segment
		(start 383.693416 -280.083514)
		(end 383.701798 -280.078688)
		(width 0.0889)
		(layer "In2.Cu")
		(net "M_I_CPU0_SB_DQ<9>")
	)
	(segment
		(start 422.304464 -292.11016)
		(end 428.742602 -292.11016)
		(width 0.14478)
		(layer "In2.Cu")
		(net "M_I_CPU0_SB_DQ<9>")
	)
	(segment
		(start 401.858988 -283.08808)
		(end 411.730952 -292.960044)
		(width 0.14478)
		(layer "In2.Cu")
		(net "M_I_CPU0_SB_DQ<9>")
	)
	(segment
		(start 381.447802 -280.078688)
		(end 381.456184 -280.083514)
		(width 0.0889)
		(layer "In2.Cu")
		(net "M_I_CPU0_SB_DQ<9>")
	)
	(segment
		(start 429.294036 -292.790372)
		(end 429.45558 -292.628828)
		(width 0.14478)
		(layer "In2.Cu")
		(net "M_I_CPU0_SB_DQ<9>")
	)
	(segment
		(start 376.148854 -280.021538)
		(end 376.244866 -280.046938)
		(width 0.0889)
		(layer "In2.Cu")
		(net "M_I_CPU0_SB_DQ<9>")
	)
	(segment
		(start 400.973544 -283.08808)
		(end 401.858988 -283.08808)
		(width 0.14478)
		(layer "In2.Cu")
		(net "M_I_CPU0_SB_DQ<9>")
	)
	(segment
		(start 379.933454 -280.083514)
		(end 379.941836 -280.078688)
		(width 0.0889)
		(layer "In2.Cu")
		(net "M_I_CPU0_SB_DQ<9>")
	)
	(segment
		(start 388.393432 -280.083514)
		(end 388.401814 -280.078688)
		(width 0.0889)
		(layer "In2.Cu")
		(net "M_I_CPU0_SB_DQ<9>")
	)
	(segment
		(start 392.137138 -280.091896)
		(end 392.160506 -280.078434)
		(width 0.0889)
		(layer "In2.Cu")
		(net "M_I_CPU0_SB_DQ<9>")
	)
	(segment
		(start 415.204402 -292.11016)
		(end 417.64839 -292.11016)
		(width 0.14478)
		(layer "In2.Cu")
		(net "M_I_CPU0_SB_DQ<9>")
	)
	(segment
		(start 428.742602 -292.11016)
		(end 428.904146 -292.271704)
		(width 0.14478)
		(layer "In2.Cu")
		(net "M_I_CPU0_SB_DQ<9>")
	)
	(segment
		(start 429.06569 -292.790372)
		(end 429.294036 -292.790372)
		(width 0.14478)
		(layer "In2.Cu")
		(net "M_I_CPU0_SB_DQ<9>")
	)
	(segment
		(start 413.15259 -292.960044)
		(end 415.204402 -292.11016)
		(width 0.14478)
		(layer "In2.Cu")
		(net "M_I_CPU0_SB_DQ<9>")
	)
	(segment
		(start 420.252652 -292.960044)
		(end 422.304464 -292.11016)
		(width 0.14478)
		(layer "In2.Cu")
		(net "M_I_CPU0_SB_DQ<9>")
	)
	(segment
		(start 393.099798 -280.078688)
		(end 393.100052 -280.078942)
		(width 0.0889)
		(layer "In2.Cu")
		(net "M_I_CPU0_SB_DQ<9>")
	)
	(segment
		(start 417.64839 -292.11016)
		(end 419.699694 -292.960044)
		(width 0.14478)
		(layer "In2.Cu")
		(net "M_I_CPU0_SB_DQ<9>")
	)
	(segment
		(start 397.784574 -279.89911)
		(end 400.973544 -283.08808)
		(width 0.14478)
		(layer "In2.Cu")
		(net "M_I_CPU0_SB_DQ<9>")
	)
	(segment
		(start 395.795246 -279.89911)
		(end 397.784574 -279.89911)
		(width 0.14478)
		(layer "In2.Cu")
		(net "M_I_CPU0_SB_DQ<9>")
	)
	(segment
		(start 429.45558 -292.628828)
		(end 429.45558 -292.271704)
		(width 0.14478)
		(layer "In2.Cu")
		(net "M_I_CPU0_SB_DQ<9>")
	)
	(segment
		(start 429.617124 -292.11016)
		(end 431.131218 -292.11016)
		(width 0.14478)
		(layer "In2.Cu")
		(net "M_I_CPU0_SB_DQ<9>")
	)
	(segment
		(start 375.99493 -279.756108)
		(end 376.148854 -280.021538)
		(width 0.0889)
		(layer "In2.Cu")
		(net "M_I_CPU0_SB_DQ<9>")
	)
	(segment
		(start 380.873508 -280.083514)
		(end 380.88189 -280.078688)
		(width 0.0889)
		(layer "In2.Cu")
		(net "M_I_CPU0_SB_DQ<9>")
	)
	(segment
		(start 392.160506 -280.078434)
		(end 392.186668 -280.063448)
		(width 0.0889)
		(layer "In2.Cu")
		(net "M_I_CPU0_SB_DQ<9>")
	)
	(segment
		(start 393.29741 -280.008838)
		(end 393.679934 -280.008838)
		(width 0.0889)
		(layer "In2.Cu")
		(net "M_I_CPU0_SB_DQ<9>")
	)
	(segment
		(start 429.45558 -292.271704)
		(end 429.617124 -292.11016)
		(width 0.14478)
		(layer "In2.Cu")
		(net "M_I_CPU0_SB_DQ<9>")
	)
	(segment
		(start 431.131218 -292.11016)
		(end 431.55616 -292.535102)
		(width 0.14478)
		(layer "In2.Cu")
		(net "M_I_CPU0_SB_DQ<9>")
	)
	(segment
		(start 376.747786 -280.078688)
		(end 376.756168 -280.083514)
		(width 0.0889)
		(layer "In2.Cu")
		(net "M_I_CPU0_SB_DQ<9>")
	)
	(segment
		(start 411.730952 -292.960044)
		(end 413.15259 -292.960044)
		(width 0.14478)
		(layer "In2.Cu")
		(net "M_I_CPU0_SB_DQ<9>")
	)
	(segment
		(start 393.789662 -279.89911)
		(end 395.795246 -279.89911)
		(width 0.0889)
		(layer "In2.Cu")
		(net "M_I_CPU0_SB_DQ<9>")
	)
	(segment
		(start 386.147818 -280.078688)
		(end 386.1562 -280.083514)
		(width 0.0889)
		(layer "In2.Cu")
		(net "M_I_CPU0_SB_DQ<9>")
	)
	(segment
		(start 389.90778 -280.078688)
		(end 389.916162 -280.083514)
		(width 0.0889)
		(layer "In2.Cu")
		(net "M_I_CPU0_SB_DQ<9>")
	)
	(segment
		(start 377.68784 -280.078688)
		(end 377.696222 -280.083514)
		(width 0.0889)
		(layer "In2.Cu")
		(net "M_I_CPU0_SB_DQ<9>")
	)
	(segment
		(start 392.724386 -280.078688)
		(end 392.74496 -280.090626)
		(width 0.0889)
		(layer "In2.Cu")
		(net "M_I_CPU0_SB_DQ<9>")
	)
	(segment
		(start 384.63347 -280.083514)
		(end 384.641852 -280.078688)
		(width 0.0889)
		(layer "In2.Cu")
		(net "M_I_CPU0_SB_DQ<9>")
	)
	(segment
		(start 385.207764 -280.078688)
		(end 385.216146 -280.083514)
		(width 0.0889)
		(layer "In2.Cu")
		(net "M_I_CPU0_SB_DQ<9>")
	)
	(segment
		(start 428.904146 -292.271704)
		(end 428.904146 -292.628828)
		(width 0.14478)
		(layer "In2.Cu")
		(net "M_I_CPU0_SB_DQ<9>")
	)
	(segment
		(start 428.904146 -292.628828)
		(end 429.06569 -292.790372)
		(width 0.14478)
		(layer "In2.Cu")
		(net "M_I_CPU0_SB_DQ<9>")
	)
	(arc
		(start 386.52196 -280.078688)
		(mid 386.804916 -280.002511)
		(end 387.087872 -280.078688)
		(width 0.0889)
		(layer "In2.Cu")
		(net "M_I_CPU0_SB_DQ<9>")
	)
	(arc
		(start 389.341868 -280.078688)
		(mid 389.624824 -280.002511)
		(end 389.90778 -280.078688)
		(width 0.0889)
		(layer "In2.Cu")
		(net "M_I_CPU0_SB_DQ<9>")
	)
	(arc
		(start 378.627894 -280.078688)
		(mid 378.814838 -280.128943)
		(end 379.001782 -280.078688)
		(width 0.0889)
		(layer "In2.Cu")
		(net "M_I_CPU0_SB_DQ<9>")
	)
	(arc
		(start 386.1562 -280.083514)
		(mid 386.339708 -280.129008)
		(end 386.52196 -280.078688)
		(width 0.0889)
		(layer "In2.Cu")
		(net "M_I_CPU0_SB_DQ<9>")
	)
	(arc
		(start 387.46176 -280.078688)
		(mid 387.744716 -280.002511)
		(end 388.027672 -280.078688)
		(width 0.0889)
		(layer "In2.Cu")
		(net "M_I_CPU0_SB_DQ<9>")
	)
	(arc
		(start 391.787634 -280.078688)
		(mid 391.960742 -280.128804)
		(end 392.137138 -280.091896)
		(width 0.0889)
		(layer "In2.Cu")
		(net "M_I_CPU0_SB_DQ<9>")
	)
	(arc
		(start 388.967726 -280.078688)
		(mid 389.149977 -280.129038)
		(end 389.333486 -280.083514)
		(width 0.0889)
		(layer "In2.Cu")
		(net "M_I_CPU0_SB_DQ<9>")
	)
	(arc
		(start 381.456184 -280.083514)
		(mid 381.639692 -280.129008)
		(end 381.821944 -280.078688)
		(width 0.0889)
		(layer "In2.Cu")
		(net "M_I_CPU0_SB_DQ<9>")
	)
	(arc
		(start 381.821944 -280.078688)
		(mid 382.1049 -280.002511)
		(end 382.387856 -280.078688)
		(width 0.0889)
		(layer "In2.Cu")
		(net "M_I_CPU0_SB_DQ<9>")
	)
	(arc
		(start 383.701798 -280.078688)
		(mid 383.984754 -280.002511)
		(end 384.26771 -280.078688)
		(width 0.0889)
		(layer "In2.Cu")
		(net "M_I_CPU0_SB_DQ<9>")
	)
	(arc
		(start 393.100052 -280.078942)
		(mid 393.195452 -280.03466)
		(end 393.29741 -280.008838)
		(width 0.0889)
		(layer "In2.Cu")
		(net "M_I_CPU0_SB_DQ<9>")
	)
	(arc
		(start 383.327656 -280.078688)
		(mid 383.509907 -280.129038)
		(end 383.693416 -280.083514)
		(width 0.0889)
		(layer "In2.Cu")
		(net "M_I_CPU0_SB_DQ<9>")
	)
	(arc
		(start 382.761744 -280.078688)
		(mid 383.0447 -280.002511)
		(end 383.327656 -280.078688)
		(width 0.0889)
		(layer "In2.Cu")
		(net "M_I_CPU0_SB_DQ<9>")
	)
	(arc
		(start 379.941836 -280.078688)
		(mid 380.224792 -280.002511)
		(end 380.507748 -280.078688)
		(width 0.0889)
		(layer "In2.Cu")
		(net "M_I_CPU0_SB_DQ<9>")
	)
	(arc
		(start 376.756168 -280.083514)
		(mid 376.939676 -280.129008)
		(end 377.121928 -280.078688)
		(width 0.0889)
		(layer "In2.Cu")
		(net "M_I_CPU0_SB_DQ<9>")
	)
	(arc
		(start 392.186668 -280.063448)
		(mid 392.457454 -280.002802)
		(end 392.724386 -280.078688)
		(width 0.0889)
		(layer "In2.Cu")
		(net "M_I_CPU0_SB_DQ<9>")
	)
	(arc
		(start 388.027672 -280.078688)
		(mid 388.209923 -280.129038)
		(end 388.393432 -280.083514)
		(width 0.0889)
		(layer "In2.Cu")
		(net "M_I_CPU0_SB_DQ<9>")
	)
	(arc
		(start 376.244866 -280.046938)
		(mid 376.500074 -280.003461)
		(end 376.747786 -280.078688)
		(width 0.0889)
		(layer "In2.Cu")
		(net "M_I_CPU0_SB_DQ<9>")
	)
	(arc
		(start 378.061982 -280.078688)
		(mid 378.344938 -280.002511)
		(end 378.627894 -280.078688)
		(width 0.0889)
		(layer "In2.Cu")
		(net "M_I_CPU0_SB_DQ<9>")
	)
	(arc
		(start 384.641852 -280.078688)
		(mid 384.924808 -280.002511)
		(end 385.207764 -280.078688)
		(width 0.0889)
		(layer "In2.Cu")
		(net "M_I_CPU0_SB_DQ<9>")
	)
	(arc
		(start 380.507748 -280.078688)
		(mid 380.689999 -280.129038)
		(end 380.873508 -280.083514)
		(width 0.0889)
		(layer "In2.Cu")
		(net "M_I_CPU0_SB_DQ<9>")
	)
	(arc
		(start 377.121928 -280.078688)
		(mid 377.404884 -280.002511)
		(end 377.68784 -280.078688)
		(width 0.0889)
		(layer "In2.Cu")
		(net "M_I_CPU0_SB_DQ<9>")
	)
	(arc
		(start 391.221722 -280.078688)
		(mid 391.504678 -280.002511)
		(end 391.787634 -280.078688)
		(width 0.0889)
		(layer "In2.Cu")
		(net "M_I_CPU0_SB_DQ<9>")
	)
	(arc
		(start 382.387856 -280.078688)
		(mid 382.5748 -280.128943)
		(end 382.761744 -280.078688)
		(width 0.0889)
		(layer "In2.Cu")
		(net "M_I_CPU0_SB_DQ<9>")
	)
	(arc
		(start 390.281922 -280.078688)
		(mid 390.564878 -280.002511)
		(end 390.847834 -280.078688)
		(width 0.0889)
		(layer "In2.Cu")
		(net "M_I_CPU0_SB_DQ<9>")
	)
	(arc
		(start 385.216146 -280.083514)
		(mid 385.399654 -280.129008)
		(end 385.581906 -280.078688)
		(width 0.0889)
		(layer "In2.Cu")
		(net "M_I_CPU0_SB_DQ<9>")
	)
	(arc
		(start 389.916162 -280.083514)
		(mid 390.09967 -280.129008)
		(end 390.281922 -280.078688)
		(width 0.0889)
		(layer "In2.Cu")
		(net "M_I_CPU0_SB_DQ<9>")
	)
	(arc
		(start 384.26771 -280.078688)
		(mid 384.449961 -280.129038)
		(end 384.63347 -280.083514)
		(width 0.0889)
		(layer "In2.Cu")
		(net "M_I_CPU0_SB_DQ<9>")
	)
	(arc
		(start 379.567694 -280.078688)
		(mid 379.749945 -280.129038)
		(end 379.933454 -280.083514)
		(width 0.0889)
		(layer "In2.Cu")
		(net "M_I_CPU0_SB_DQ<9>")
	)
	(arc
		(start 388.401814 -280.078688)
		(mid 388.68477 -280.002511)
		(end 388.967726 -280.078688)
		(width 0.0889)
		(layer "In2.Cu")
		(net "M_I_CPU0_SB_DQ<9>")
	)
	(arc
		(start 387.087872 -280.078688)
		(mid 387.274816 -280.128943)
		(end 387.46176 -280.078688)
		(width 0.0889)
		(layer "In2.Cu")
		(net "M_I_CPU0_SB_DQ<9>")
	)
	(arc
		(start 385.581906 -280.078688)
		(mid 385.864862 -280.002511)
		(end 386.147818 -280.078688)
		(width 0.0889)
		(layer "In2.Cu")
		(net "M_I_CPU0_SB_DQ<9>")
	)
	(arc
		(start 392.74496 -280.090626)
		(mid 392.923888 -280.129503)
		(end 393.099798 -280.078688)
		(width 0.0889)
		(layer "In2.Cu")
		(net "M_I_CPU0_SB_DQ<9>")
	)
	(arc
		(start 390.847834 -280.078688)
		(mid 391.034778 -280.128943)
		(end 391.221722 -280.078688)
		(width 0.0889)
		(layer "In2.Cu")
		(net "M_I_CPU0_SB_DQ<9>")
	)
	(arc
		(start 379.001782 -280.078688)
		(mid 379.284738 -280.002511)
		(end 379.567694 -280.078688)
		(width 0.0889)
		(layer "In2.Cu")
		(net "M_I_CPU0_SB_DQ<9>")
	)
	(arc
		(start 377.696222 -280.083514)
		(mid 377.87973 -280.129008)
		(end 378.061982 -280.078688)
		(width 0.0889)
		(layer "In2.Cu")
		(net "M_I_CPU0_SB_DQ<9>")
	)
	(arc
		(start 380.88189 -280.078688)
		(mid 381.164846 -280.002511)
		(end 381.447802 -280.078688)
		(width 0.0889)
		(layer "In2.Cu")
		(net "M_I_CPU0_SB_DQ<9>")
	)
	(segment
		(start 376.938032 -278.680164)
		(end 377.404884 -278.946102)
		(width 0.10668)
		(layer "F.Cu")
		(net "M_I_CPU0_SB_DQ<8>")
	)
	(segment
		(start 394.411708 -278.542496)
		(end 395.359128 -278.542496)
		(width 0.0889)
		(layer "In2.Cu")
		(net "M_I_CPU0_SB_DQ<8>")
	)
	(segment
		(start 415.55797 -290.410138)
		(end 417.223702 -290.410138)
		(width 0.14478)
		(layer "In2.Cu")
		(net "M_I_CPU0_SB_DQ<8>")
	)
	(segment
		(start 386.983478 -279.273508)
		(end 386.99186 -279.268682)
		(width 0.0889)
		(layer "In2.Cu")
		(net "M_I_CPU0_SB_DQ<8>")
	)
	(segment
		(start 393.182348 -279.259284)
		(end 393.198096 -279.268428)
		(width 0.0889)
		(layer "In2.Cu")
		(net "M_I_CPU0_SB_DQ<8>")
	)
	(segment
		(start 395.427708 -278.611076)
		(end 395.953488 -278.611076)
		(width 0.0889)
		(layer "In2.Cu")
		(net "M_I_CPU0_SB_DQ<8>")
	)
	(segment
		(start 387.557772 -279.268682)
		(end 387.566154 -279.273508)
		(width 0.0889)
		(layer "In2.Cu")
		(net "M_I_CPU0_SB_DQ<8>")
	)
	(segment
		(start 398.654016 -278.611076)
		(end 410.633926 -290.590986)
		(width 0.14478)
		(layer "In2.Cu")
		(net "M_I_CPU0_SB_DQ<8>")
	)
	(segment
		(start 393.376658 -279.318974)
		(end 393.63523 -279.318974)
		(width 0.0889)
		(layer "In2.Cu")
		(net "M_I_CPU0_SB_DQ<8>")
	)
	(segment
		(start 429.809656 -291.04717)
		(end 429.959516 -290.89731)
		(width 0.14478)
		(layer "In2.Cu")
		(net "M_I_CPU0_SB_DQ<8>")
	)
	(segment
		(start 430.109376 -290.410138)
		(end 431.131218 -290.410138)
		(width 0.14478)
		(layer "In2.Cu")
		(net "M_I_CPU0_SB_DQ<8>")
	)
	(segment
		(start 412.250128 -291.260022)
		(end 412.758128 -291.260022)
		(width 0.14478)
		(layer "In2.Cu")
		(net "M_I_CPU0_SB_DQ<8>")
	)
	(segment
		(start 410.633926 -290.590986)
		(end 412.250128 -291.260022)
		(width 0.14478)
		(layer "In2.Cu")
		(net "M_I_CPU0_SB_DQ<8>")
	)
	(segment
		(start 417.223702 -290.410138)
		(end 418.081968 -290.580826)
		(width 0.14478)
		(layer "In2.Cu")
		(net "M_I_CPU0_SB_DQ<8>")
	)
	(segment
		(start 395.953488 -278.611076)
		(end 398.654016 -278.611076)
		(width 0.14478)
		(layer "In2.Cu")
		(net "M_I_CPU0_SB_DQ<8>")
	)
	(segment
		(start 418.081968 -290.580826)
		(end 419.721538 -291.260022)
		(width 0.14478)
		(layer "In2.Cu")
		(net "M_I_CPU0_SB_DQ<8>")
	)
	(segment
		(start 380.037848 -279.268682)
		(end 380.04623 -279.273508)
		(width 0.0889)
		(layer "In2.Cu")
		(net "M_I_CPU0_SB_DQ<8>")
	)
	(segment
		(start 428.841916 -290.260278)
		(end 428.841916 -289.88639)
		(width 0.14478)
		(layer "In2.Cu")
		(net "M_I_CPU0_SB_DQ<8>")
	)
	(segment
		(start 429.550576 -291.04717)
		(end 429.809656 -291.04717)
		(width 0.14478)
		(layer "In2.Cu")
		(net "M_I_CPU0_SB_DQ<8>")
	)
	(segment
		(start 393.198096 -279.268428)
		(end 393.216384 -279.278842)
		(width 0.0889)
		(layer "In2.Cu")
		(net "M_I_CPU0_SB_DQ<8>")
	)
	(segment
		(start 428.692056 -290.410138)
		(end 428.841916 -290.260278)
		(width 0.14478)
		(layer "In2.Cu")
		(net "M_I_CPU0_SB_DQ<8>")
	)
	(segment
		(start 382.283462 -279.273508)
		(end 382.291844 -279.268682)
		(width 0.0889)
		(layer "In2.Cu")
		(net "M_I_CPU0_SB_DQ<8>")
	)
	(segment
		(start 429.400716 -290.89731)
		(end 429.550576 -291.04717)
		(width 0.14478)
		(layer "In2.Cu")
		(net "M_I_CPU0_SB_DQ<8>")
	)
	(segment
		(start 429.959516 -290.89731)
		(end 429.959516 -290.559998)
		(width 0.14478)
		(layer "In2.Cu")
		(net "M_I_CPU0_SB_DQ<8>")
	)
	(segment
		(start 428.841916 -289.88639)
		(end 428.991776 -289.73653)
		(width 0.14478)
		(layer "In2.Cu")
		(net "M_I_CPU0_SB_DQ<8>")
	)
	(segment
		(start 383.79781 -279.268682)
		(end 383.806192 -279.273508)
		(width 0.0889)
		(layer "In2.Cu")
		(net "M_I_CPU0_SB_DQ<8>")
	)
	(segment
		(start 429.250856 -289.73653)
		(end 429.400716 -289.88639)
		(width 0.14478)
		(layer "In2.Cu")
		(net "M_I_CPU0_SB_DQ<8>")
	)
	(segment
		(start 377.558808 -279.211532)
		(end 377.65482 -279.236932)
		(width 0.0889)
		(layer "In2.Cu")
		(net "M_I_CPU0_SB_DQ<8>")
	)
	(segment
		(start 412.758128 -291.260022)
		(end 415.55797 -290.410138)
		(width 0.14478)
		(layer "In2.Cu")
		(net "M_I_CPU0_SB_DQ<8>")
	)
	(segment
		(start 386.043424 -279.273508)
		(end 386.051806 -279.268682)
		(width 0.0889)
		(layer "In2.Cu")
		(net "M_I_CPU0_SB_DQ<8>")
	)
	(segment
		(start 395.359128 -278.542496)
		(end 395.427708 -278.611076)
		(width 0.0889)
		(layer "In2.Cu")
		(net "M_I_CPU0_SB_DQ<8>")
	)
	(segment
		(start 419.721538 -291.260022)
		(end 420.411402 -291.260022)
		(width 0.14478)
		(layer "In2.Cu")
		(net "M_I_CPU0_SB_DQ<8>")
	)
	(segment
		(start 390.74344 -279.273508)
		(end 390.751822 -279.268682)
		(width 0.0889)
		(layer "In2.Cu")
		(net "M_I_CPU0_SB_DQ<8>")
	)
	(segment
		(start 382.857756 -279.268682)
		(end 382.866138 -279.273508)
		(width 0.0889)
		(layer "In2.Cu")
		(net "M_I_CPU0_SB_DQ<8>")
	)
	(segment
		(start 420.411402 -291.260022)
		(end 421.74795 -290.706302)
		(width 0.14478)
		(layer "In2.Cu")
		(net "M_I_CPU0_SB_DQ<8>")
	)
	(segment
		(start 393.63523 -279.318974)
		(end 394.411708 -278.542496)
		(width 0.0889)
		(layer "In2.Cu")
		(net "M_I_CPU0_SB_DQ<8>")
	)
	(segment
		(start 391.317734 -279.268682)
		(end 391.326116 -279.273508)
		(width 0.0889)
		(layer "In2.Cu")
		(net "M_I_CPU0_SB_DQ<8>")
	)
	(segment
		(start 428.991776 -289.73653)
		(end 429.250856 -289.73653)
		(width 0.14478)
		(layer "In2.Cu")
		(net "M_I_CPU0_SB_DQ<8>")
	)
	(segment
		(start 392.257788 -279.268682)
		(end 392.269472 -279.27554)
		(width 0.0889)
		(layer "In2.Cu")
		(net "M_I_CPU0_SB_DQ<8>")
	)
	(segment
		(start 421.74795 -290.706302)
		(end 423.237406 -290.410138)
		(width 0.14478)
		(layer "In2.Cu")
		(net "M_I_CPU0_SB_DQ<8>")
	)
	(segment
		(start 423.237406 -290.410138)
		(end 428.692056 -290.410138)
		(width 0.14478)
		(layer "In2.Cu")
		(net "M_I_CPU0_SB_DQ<8>")
	)
	(segment
		(start 388.497826 -279.268682)
		(end 388.506208 -279.273508)
		(width 0.0889)
		(layer "In2.Cu")
		(net "M_I_CPU0_SB_DQ<8>")
	)
	(segment
		(start 429.400716 -289.88639)
		(end 429.400716 -290.89731)
		(width 0.14478)
		(layer "In2.Cu")
		(net "M_I_CPU0_SB_DQ<8>")
	)
	(segment
		(start 429.959516 -290.559998)
		(end 430.109376 -290.410138)
		(width 0.14478)
		(layer "In2.Cu")
		(net "M_I_CPU0_SB_DQ<8>")
	)
	(segment
		(start 431.131218 -290.410138)
		(end 431.55616 -290.83508)
		(width 0.14478)
		(layer "In2.Cu")
		(net "M_I_CPU0_SB_DQ<8>")
	)
	(segment
		(start 378.5235 -279.273508)
		(end 378.531882 -279.268682)
		(width 0.0889)
		(layer "In2.Cu")
		(net "M_I_CPU0_SB_DQ<8>")
	)
	(segment
		(start 377.404884 -278.946102)
		(end 377.558808 -279.211532)
		(width 0.0889)
		(layer "In2.Cu")
		(net "M_I_CPU0_SB_DQ<8>")
	)
	(segment
		(start 379.097794 -279.268682)
		(end 379.106176 -279.273508)
		(width 0.0889)
		(layer "In2.Cu")
		(net "M_I_CPU0_SB_DQ<8>")
	)
	(arc
		(start 380.04623 -279.273508)
		(mid 380.229738 -279.319002)
		(end 380.41199 -279.268682)
		(width 0.0889)
		(layer "In2.Cu")
		(net "M_I_CPU0_SB_DQ<8>")
	)
	(arc
		(start 383.231898 -279.268682)
		(mid 383.514854 -279.192505)
		(end 383.79781 -279.268682)
		(width 0.0889)
		(layer "In2.Cu")
		(net "M_I_CPU0_SB_DQ<8>")
	)
	(arc
		(start 392.269472 -279.27554)
		(mid 392.451727 -279.319193)
		(end 392.632184 -279.268682)
		(width 0.0889)
		(layer "In2.Cu")
		(net "M_I_CPU0_SB_DQ<8>")
	)
	(arc
		(start 384.737864 -279.268682)
		(mid 384.924808 -279.318937)
		(end 385.111752 -279.268682)
		(width 0.0889)
		(layer "In2.Cu")
		(net "M_I_CPU0_SB_DQ<8>")
	)
	(arc
		(start 384.171952 -279.268682)
		(mid 384.454908 -279.192505)
		(end 384.737864 -279.268682)
		(width 0.0889)
		(layer "In2.Cu")
		(net "M_I_CPU0_SB_DQ<8>")
	)
	(arc
		(start 391.326116 -279.273508)
		(mid 391.509624 -279.319002)
		(end 391.691876 -279.268682)
		(width 0.0889)
		(layer "In2.Cu")
		(net "M_I_CPU0_SB_DQ<8>")
	)
	(arc
		(start 378.531882 -279.268682)
		(mid 378.814838 -279.192505)
		(end 379.097794 -279.268682)
		(width 0.0889)
		(layer "In2.Cu")
		(net "M_I_CPU0_SB_DQ<8>")
	)
	(arc
		(start 385.677664 -279.268682)
		(mid 385.859915 -279.319032)
		(end 386.043424 -279.273508)
		(width 0.0889)
		(layer "In2.Cu")
		(net "M_I_CPU0_SB_DQ<8>")
	)
	(arc
		(start 379.471936 -279.268682)
		(mid 379.754892 -279.192505)
		(end 380.037848 -279.268682)
		(width 0.0889)
		(layer "In2.Cu")
		(net "M_I_CPU0_SB_DQ<8>")
	)
	(arc
		(start 389.811768 -279.268682)
		(mid 390.094724 -279.192505)
		(end 390.37768 -279.268682)
		(width 0.0889)
		(layer "In2.Cu")
		(net "M_I_CPU0_SB_DQ<8>")
	)
	(arc
		(start 391.691876 -279.268682)
		(mid 391.974832 -279.192505)
		(end 392.257788 -279.268682)
		(width 0.0889)
		(layer "In2.Cu")
		(net "M_I_CPU0_SB_DQ<8>")
	)
	(arc
		(start 387.931914 -279.268682)
		(mid 388.21487 -279.192505)
		(end 388.497826 -279.268682)
		(width 0.0889)
		(layer "In2.Cu")
		(net "M_I_CPU0_SB_DQ<8>")
	)
	(arc
		(start 382.291844 -279.268682)
		(mid 382.5748 -279.192505)
		(end 382.857756 -279.268682)
		(width 0.0889)
		(layer "In2.Cu")
		(net "M_I_CPU0_SB_DQ<8>")
	)
	(arc
		(start 380.977902 -279.268682)
		(mid 381.164846 -279.318937)
		(end 381.35179 -279.268682)
		(width 0.0889)
		(layer "In2.Cu")
		(net "M_I_CPU0_SB_DQ<8>")
	)
	(arc
		(start 379.106176 -279.273508)
		(mid 379.289684 -279.319002)
		(end 379.471936 -279.268682)
		(width 0.0889)
		(layer "In2.Cu")
		(net "M_I_CPU0_SB_DQ<8>")
	)
	(arc
		(start 387.566154 -279.273508)
		(mid 387.749662 -279.319002)
		(end 387.931914 -279.268682)
		(width 0.0889)
		(layer "In2.Cu")
		(net "M_I_CPU0_SB_DQ<8>")
	)
	(arc
		(start 382.866138 -279.273508)
		(mid 383.049646 -279.319002)
		(end 383.231898 -279.268682)
		(width 0.0889)
		(layer "In2.Cu")
		(net "M_I_CPU0_SB_DQ<8>")
	)
	(arc
		(start 377.65482 -279.236932)
		(mid 377.910028 -279.193455)
		(end 378.15774 -279.268682)
		(width 0.0889)
		(layer "In2.Cu")
		(net "M_I_CPU0_SB_DQ<8>")
	)
	(arc
		(start 383.806192 -279.273508)
		(mid 383.9897 -279.319002)
		(end 384.171952 -279.268682)
		(width 0.0889)
		(layer "In2.Cu")
		(net "M_I_CPU0_SB_DQ<8>")
	)
	(arc
		(start 386.051806 -279.268682)
		(mid 386.334762 -279.192505)
		(end 386.617718 -279.268682)
		(width 0.0889)
		(layer "In2.Cu")
		(net "M_I_CPU0_SB_DQ<8>")
	)
	(arc
		(start 389.43788 -279.268682)
		(mid 389.624824 -279.318937)
		(end 389.811768 -279.268682)
		(width 0.0889)
		(layer "In2.Cu")
		(net "M_I_CPU0_SB_DQ<8>")
	)
	(arc
		(start 388.506208 -279.273508)
		(mid 388.689716 -279.319002)
		(end 388.871968 -279.268682)
		(width 0.0889)
		(layer "In2.Cu")
		(net "M_I_CPU0_SB_DQ<8>")
	)
	(arc
		(start 390.37768 -279.268682)
		(mid 390.559931 -279.319032)
		(end 390.74344 -279.273508)
		(width 0.0889)
		(layer "In2.Cu")
		(net "M_I_CPU0_SB_DQ<8>")
	)
	(arc
		(start 386.99186 -279.268682)
		(mid 387.274816 -279.192505)
		(end 387.557772 -279.268682)
		(width 0.0889)
		(layer "In2.Cu")
		(net "M_I_CPU0_SB_DQ<8>")
	)
	(arc
		(start 380.41199 -279.268682)
		(mid 380.694946 -279.192505)
		(end 380.977902 -279.268682)
		(width 0.0889)
		(layer "In2.Cu")
		(net "M_I_CPU0_SB_DQ<8>")
	)
	(arc
		(start 386.617718 -279.268682)
		(mid 386.799969 -279.319032)
		(end 386.983478 -279.273508)
		(width 0.0889)
		(layer "In2.Cu")
		(net "M_I_CPU0_SB_DQ<8>")
	)
	(arc
		(start 392.632184 -279.268682)
		(mid 392.906039 -279.192332)
		(end 393.182348 -279.259284)
		(width 0.0889)
		(layer "In2.Cu")
		(net "M_I_CPU0_SB_DQ<8>")
	)
	(arc
		(start 393.216384 -279.278842)
		(mid 393.294273 -279.307879)
		(end 393.376658 -279.318974)
		(width 0.0889)
		(layer "In2.Cu")
		(net "M_I_CPU0_SB_DQ<8>")
	)
	(arc
		(start 390.751822 -279.268682)
		(mid 391.034778 -279.192505)
		(end 391.317734 -279.268682)
		(width 0.0889)
		(layer "In2.Cu")
		(net "M_I_CPU0_SB_DQ<8>")
	)
	(arc
		(start 381.917702 -279.268682)
		(mid 382.099953 -279.319032)
		(end 382.283462 -279.273508)
		(width 0.0889)
		(layer "In2.Cu")
		(net "M_I_CPU0_SB_DQ<8>")
	)
	(arc
		(start 378.15774 -279.268682)
		(mid 378.339991 -279.319032)
		(end 378.5235 -279.273508)
		(width 0.0889)
		(layer "In2.Cu")
		(net "M_I_CPU0_SB_DQ<8>")
	)
	(arc
		(start 388.871968 -279.268682)
		(mid 389.154924 -279.192505)
		(end 389.43788 -279.268682)
		(width 0.0889)
		(layer "In2.Cu")
		(net "M_I_CPU0_SB_DQ<8>")
	)
	(arc
		(start 385.111752 -279.268682)
		(mid 385.394708 -279.192505)
		(end 385.677664 -279.268682)
		(width 0.0889)
		(layer "In2.Cu")
		(net "M_I_CPU0_SB_DQ<8>")
	)
	(arc
		(start 381.35179 -279.268682)
		(mid 381.634746 -279.192505)
		(end 381.917702 -279.268682)
		(width 0.0889)
		(layer "In2.Cu")
		(net "M_I_CPU0_SB_DQ<8>")
	)
	(segment
		(start 375.997978 -278.680164)
		(end 376.46483 -278.946102)
		(width 0.10668)
		(layer "F.Cu")
		(net "M_I_CPU0_SB_DQ<7>")
	)
	(segment
		(start 410.93644 -290.113974)
		(end 411.652974 -290.410392)
		(width 0.14478)
		(layer "In2.Cu")
		(net "M_I_CPU0_SB_DQ<7>")
	)
	(segment
		(start 388.497826 -278.623522)
		(end 388.506208 -278.618696)
		(width 0.0889)
		(layer "In2.Cu")
		(net "M_I_CPU0_SB_DQ<7>")
	)
	(segment
		(start 382.857756 -278.623522)
		(end 382.866138 -278.618696)
		(width 0.0889)
		(layer "In2.Cu")
		(net "M_I_CPU0_SB_DQ<7>")
	)
	(segment
		(start 415.437066 -289.657282)
		(end 415.618676 -289.766248)
		(width 0.14478)
		(layer "In2.Cu")
		(net "M_I_CPU0_SB_DQ<7>")
	)
	(segment
		(start 425.50207 -289.69843)
		(end 425.65193 -289.84829)
		(width 0.14478)
		(layer "In2.Cu")
		(net "M_I_CPU0_SB_DQ<7>")
	)
	(segment
		(start 417.89731 -289.27552)
		(end 418.093398 -289.3568)
		(width 0.14478)
		(layer "In2.Cu")
		(net "M_I_CPU0_SB_DQ<7>")
	)
	(segment
		(start 380.037848 -278.623522)
		(end 380.04623 -278.618696)
		(width 0.0889)
		(layer "In2.Cu")
		(net "M_I_CPU0_SB_DQ<7>")
	)
	(segment
		(start 379.097794 -278.623522)
		(end 379.106176 -278.618696)
		(width 0.0889)
		(layer "In2.Cu")
		(net "M_I_CPU0_SB_DQ<7>")
	)
	(segment
		(start 427.03115 -289.560254)
		(end 427.456092 -289.985196)
		(width 0.14478)
		(layer "In2.Cu")
		(net "M_I_CPU0_SB_DQ<7>")
	)
	(segment
		(start 414.534604 -290.038028)
		(end 414.786064 -289.974782)
		(width 0.14478)
		(layer "In2.Cu")
		(net "M_I_CPU0_SB_DQ<7>")
	)
	(segment
		(start 395.34973 -278.054816)
		(end 395.95933 -278.054816)
		(width 0.0889)
		(layer "In2.Cu")
		(net "M_I_CPU0_SB_DQ<7>")
	)
	(segment
		(start 418.093398 -289.3568)
		(end 418.187378 -289.583368)
		(width 0.14478)
		(layer "In2.Cu")
		(net "M_I_CPU0_SB_DQ<7>")
	)
	(segment
		(start 426.06087 -289.69843)
		(end 426.06087 -289.32505)
		(width 0.14478)
		(layer "In2.Cu")
		(net "M_I_CPU0_SB_DQ<7>")
	)
	(segment
		(start 413.810958 -290.064952)
		(end 413.761682 -289.86861)
		(width 0.14478)
		(layer "In2.Cu")
		(net "M_I_CPU0_SB_DQ<7>")
	)
	(segment
		(start 418.187378 -289.583368)
		(end 418.112448 -289.763708)
		(width 0.14478)
		(layer "In2.Cu")
		(net "M_I_CPU0_SB_DQ<7>")
	)
	(segment
		(start 415.20618 -289.351974)
		(end 415.38779 -289.46094)
		(width 0.14478)
		(layer "In2.Cu")
		(net "M_I_CPU0_SB_DQ<7>")
	)
	(segment
		(start 425.91101 -289.84829)
		(end 426.06087 -289.69843)
		(width 0.14478)
		(layer "In2.Cu")
		(net "M_I_CPU0_SB_DQ<7>")
	)
	(segment
		(start 411.652974 -290.410392)
		(end 413.209232 -290.410392)
		(width 0.14478)
		(layer "In2.Cu")
		(net "M_I_CPU0_SB_DQ<7>")
	)
	(segment
		(start 418.112448 -289.763708)
		(end 418.224716 -290.034472)
		(width 0.14478)
		(layer "In2.Cu")
		(net "M_I_CPU0_SB_DQ<7>")
	)
	(segment
		(start 413.761682 -289.86861)
		(end 413.870648 -289.687)
		(width 0.14478)
		(layer "In2.Cu")
		(net "M_I_CPU0_SB_DQ<7>")
	)
	(segment
		(start 393.613132 -278.579326)
		(end 393.613894 -278.580088)
		(width 0.0889)
		(layer "In2.Cu")
		(net "M_I_CPU0_SB_DQ<7>")
	)
	(segment
		(start 414.786064 -289.974782)
		(end 414.89503 -289.793172)
		(width 0.14478)
		(layer "In2.Cu")
		(net "M_I_CPU0_SB_DQ<7>")
	)
	(segment
		(start 415.618676 -289.766248)
		(end 416.440874 -289.560254)
		(width 0.14478)
		(layer "In2.Cu")
		(net "M_I_CPU0_SB_DQ<7>")
	)
	(segment
		(start 395.95933 -278.054816)
		(end 398.877282 -278.054816)
		(width 0.14478)
		(layer "In2.Cu")
		(net "M_I_CPU0_SB_DQ<7>")
	)
	(segment
		(start 386.043424 -278.618696)
		(end 386.051806 -278.623522)
		(width 0.0889)
		(layer "In2.Cu")
		(net "M_I_CPU0_SB_DQ<7>")
	)
	(segment
		(start 417.23056 -289.560254)
		(end 417.400486 -289.630866)
		(width 0.14478)
		(layer "In2.Cu")
		(net "M_I_CPU0_SB_DQ<7>")
	)
	(segment
		(start 414.352994 -289.929062)
		(end 414.534604 -290.038028)
		(width 0.14478)
		(layer "In2.Cu")
		(net "M_I_CPU0_SB_DQ<7>")
	)
	(segment
		(start 426.06087 -289.32505)
		(end 426.21073 -289.17519)
		(width 0.14478)
		(layer "In2.Cu")
		(net "M_I_CPU0_SB_DQ<7>")
	)
	(segment
		(start 424.772328 -289.560254)
		(end 425.139866 -289.192716)
		(width 0.14478)
		(layer "In2.Cu")
		(net "M_I_CPU0_SB_DQ<7>")
	)
	(segment
		(start 419.132512 -290.410392)
		(end 420.928292 -290.410392)
		(width 0.14478)
		(layer "In2.Cu")
		(net "M_I_CPU0_SB_DQ<7>")
	)
	(segment
		(start 417.596066 -289.549586)
		(end 417.670742 -289.3695)
		(width 0.14478)
		(layer "In2.Cu")
		(net "M_I_CPU0_SB_DQ<7>")
	)
	(segment
		(start 383.79781 -278.623522)
		(end 383.806192 -278.618696)
		(width 0.0889)
		(layer "In2.Cu")
		(net "M_I_CPU0_SB_DQ<7>")
	)
	(segment
		(start 415.38779 -289.46094)
		(end 415.437066 -289.657282)
		(width 0.14478)
		(layer "In2.Cu")
		(net "M_I_CPU0_SB_DQ<7>")
	)
	(segment
		(start 414.845754 -289.59683)
		(end 414.95472 -289.41522)
		(width 0.14478)
		(layer "In2.Cu")
		(net "M_I_CPU0_SB_DQ<7>")
	)
	(segment
		(start 413.673544 -290.293806)
		(end 413.810958 -290.064952)
		(width 0.14478)
		(layer "In2.Cu")
		(net "M_I_CPU0_SB_DQ<7>")
	)
	(segment
		(start 417.670742 -289.3695)
		(end 417.89731 -289.27552)
		(width 0.14478)
		(layer "In2.Cu")
		(net "M_I_CPU0_SB_DQ<7>")
	)
	(segment
		(start 414.89503 -289.793172)
		(end 414.845754 -289.59683)
		(width 0.14478)
		(layer "In2.Cu")
		(net "M_I_CPU0_SB_DQ<7>")
	)
	(segment
		(start 425.139866 -289.192716)
		(end 425.35221 -289.192716)
		(width 0.14478)
		(layer "In2.Cu")
		(net "M_I_CPU0_SB_DQ<7>")
	)
	(segment
		(start 417.400486 -289.630866)
		(end 417.596066 -289.549586)
		(width 0.14478)
		(layer "In2.Cu")
		(net "M_I_CPU0_SB_DQ<7>")
	)
	(segment
		(start 395.168628 -278.235918)
		(end 395.34973 -278.054816)
		(width 0.0889)
		(layer "In2.Cu")
		(net "M_I_CPU0_SB_DQ<7>")
	)
	(segment
		(start 426.88129 -289.17519)
		(end 427.03115 -289.32505)
		(width 0.14478)
		(layer "In2.Cu")
		(net "M_I_CPU0_SB_DQ<7>")
	)
	(segment
		(start 377.583446 -278.618696)
		(end 377.591828 -278.623522)
		(width 0.0889)
		(layer "In2.Cu")
		(net "M_I_CPU0_SB_DQ<7>")
	)
	(segment
		(start 413.209232 -290.410392)
		(end 413.673544 -290.293806)
		(width 0.14478)
		(layer "In2.Cu")
		(net "M_I_CPU0_SB_DQ<7>")
	)
	(segment
		(start 382.283462 -278.618696)
		(end 382.291844 -278.623522)
		(width 0.0889)
		(layer "In2.Cu")
		(net "M_I_CPU0_SB_DQ<7>")
	)
	(segment
		(start 390.74344 -278.618696)
		(end 390.751822 -278.623522)
		(width 0.0889)
		(layer "In2.Cu")
		(net "M_I_CPU0_SB_DQ<7>")
	)
	(segment
		(start 420.928292 -290.410392)
		(end 421.105584 -290.336986)
		(width 0.14478)
		(layer "In2.Cu")
		(net "M_I_CPU0_SB_DQ<7>")
	)
	(segment
		(start 421.56634 -289.701224)
		(end 421.958262 -289.864546)
		(width 0.14478)
		(layer "In2.Cu")
		(net "M_I_CPU0_SB_DQ<7>")
	)
	(segment
		(start 376.310906 -278.680672)
		(end 376.333258 -278.59736)
		(width 0.0889)
		(layer "In2.Cu")
		(net "M_I_CPU0_SB_DQ<7>")
	)
	(segment
		(start 426.21073 -289.17519)
		(end 426.88129 -289.17519)
		(width 0.14478)
		(layer "In2.Cu")
		(net "M_I_CPU0_SB_DQ<7>")
	)
	(segment
		(start 386.983478 -278.618696)
		(end 386.99186 -278.623522)
		(width 0.0889)
		(layer "In2.Cu")
		(net "M_I_CPU0_SB_DQ<7>")
	)
	(segment
		(start 421.958262 -289.864546)
		(end 422.692322 -289.560254)
		(width 0.14478)
		(layer "In2.Cu")
		(net "M_I_CPU0_SB_DQ<7>")
	)
	(segment
		(start 392.229594 -278.638762)
		(end 392.255756 -278.623776)
		(width 0.0889)
		(layer "In2.Cu")
		(net "M_I_CPU0_SB_DQ<7>")
	)
	(segment
		(start 387.557772 -278.623522)
		(end 387.566154 -278.618696)
		(width 0.0889)
		(layer "In2.Cu")
		(net "M_I_CPU0_SB_DQ<7>")
	)
	(segment
		(start 394.3604 -278.235918)
		(end 395.168628 -278.235918)
		(width 0.0889)
		(layer "In2.Cu")
		(net "M_I_CPU0_SB_DQ<7>")
	)
	(segment
		(start 392.628374 -278.623522)
		(end 392.657838 -278.640794)
		(width 0.0889)
		(layer "In2.Cu")
		(net "M_I_CPU0_SB_DQ<7>")
	)
	(segment
		(start 416.440874 -289.560254)
		(end 417.23056 -289.560254)
		(width 0.14478)
		(layer "In2.Cu")
		(net "M_I_CPU0_SB_DQ<7>")
	)
	(segment
		(start 414.95472 -289.41522)
		(end 415.20618 -289.351974)
		(width 0.14478)
		(layer "In2.Cu")
		(net "M_I_CPU0_SB_DQ<7>")
	)
	(segment
		(start 398.877282 -278.054816)
		(end 410.93644 -290.113974)
		(width 0.14478)
		(layer "In2.Cu")
		(net "M_I_CPU0_SB_DQ<7>")
	)
	(segment
		(start 427.03115 -289.32505)
		(end 427.03115 -289.560254)
		(width 0.14478)
		(layer "In2.Cu")
		(net "M_I_CPU0_SB_DQ<7>")
	)
	(segment
		(start 425.35221 -289.192716)
		(end 425.50207 -289.342576)
		(width 0.14478)
		(layer "In2.Cu")
		(net "M_I_CPU0_SB_DQ<7>")
	)
	(segment
		(start 414.122108 -289.623754)
		(end 414.303718 -289.73272)
		(width 0.14478)
		(layer "In2.Cu")
		(net "M_I_CPU0_SB_DQ<7>")
	)
	(segment
		(start 393.613894 -278.580088)
		(end 394.01623 -278.580088)
		(width 0.0889)
		(layer "In2.Cu")
		(net "M_I_CPU0_SB_DQ<7>")
	)
	(segment
		(start 392.255756 -278.623776)
		(end 392.2776 -278.61133)
		(width 0.0889)
		(layer "In2.Cu")
		(net "M_I_CPU0_SB_DQ<7>")
	)
	(segment
		(start 376.46483 -278.946102)
		(end 376.310906 -278.680672)
		(width 0.0889)
		(layer "In2.Cu")
		(net "M_I_CPU0_SB_DQ<7>")
	)
	(segment
		(start 391.317734 -278.623522)
		(end 391.326116 -278.618696)
		(width 0.0889)
		(layer "In2.Cu")
		(net "M_I_CPU0_SB_DQ<7>")
	)
	(segment
		(start 394.01623 -278.580088)
		(end 394.3604 -278.235918)
		(width 0.0889)
		(layer "In2.Cu")
		(net "M_I_CPU0_SB_DQ<7>")
	)
	(segment
		(start 422.692322 -289.560254)
		(end 424.772328 -289.560254)
		(width 0.14478)
		(layer "In2.Cu")
		(net "M_I_CPU0_SB_DQ<7>")
	)
	(segment
		(start 421.326564 -289.800792)
		(end 421.56634 -289.701224)
		(width 0.14478)
		(layer "In2.Cu")
		(net "M_I_CPU0_SB_DQ<7>")
	)
	(segment
		(start 414.303718 -289.73272)
		(end 414.352994 -289.929062)
		(width 0.14478)
		(layer "In2.Cu")
		(net "M_I_CPU0_SB_DQ<7>")
	)
	(segment
		(start 378.5235 -278.618696)
		(end 378.531882 -278.623522)
		(width 0.0889)
		(layer "In2.Cu")
		(net "M_I_CPU0_SB_DQ<7>")
	)
	(segment
		(start 425.65193 -289.84829)
		(end 425.91101 -289.84829)
		(width 0.14478)
		(layer "In2.Cu")
		(net "M_I_CPU0_SB_DQ<7>")
	)
	(segment
		(start 393.31392 -278.579326)
		(end 393.613132 -278.579326)
		(width 0.0889)
		(layer "In2.Cu")
		(net "M_I_CPU0_SB_DQ<7>")
	)
	(segment
		(start 425.50207 -289.342576)
		(end 425.50207 -289.69843)
		(width 0.14478)
		(layer "In2.Cu")
		(net "M_I_CPU0_SB_DQ<7>")
	)
	(segment
		(start 421.105584 -290.336986)
		(end 421.326564 -289.800792)
		(width 0.14478)
		(layer "In2.Cu")
		(net "M_I_CPU0_SB_DQ<7>")
	)
	(segment
		(start 418.224716 -290.034472)
		(end 419.132512 -290.410392)
		(width 0.14478)
		(layer "In2.Cu")
		(net "M_I_CPU0_SB_DQ<7>")
	)
	(segment
		(start 413.870648 -289.687)
		(end 414.122108 -289.623754)
		(width 0.14478)
		(layer "In2.Cu")
		(net "M_I_CPU0_SB_DQ<7>")
	)
	(arc
		(start 389.811768 -278.623522)
		(mid 390.094724 -278.699699)
		(end 390.37768 -278.623522)
		(width 0.0889)
		(layer "In2.Cu")
		(net "M_I_CPU0_SB_DQ<7>")
	)
	(arc
		(start 380.41199 -278.623522)
		(mid 380.694946 -278.699699)
		(end 380.977902 -278.623522)
		(width 0.0889)
		(layer "In2.Cu")
		(net "M_I_CPU0_SB_DQ<7>")
	)
	(arc
		(start 392.657838 -278.640794)
		(mid 392.929258 -278.700471)
		(end 393.196318 -278.623522)
		(width 0.0889)
		(layer "In2.Cu")
		(net "M_I_CPU0_SB_DQ<7>")
	)
	(arc
		(start 384.171952 -278.623522)
		(mid 384.454908 -278.699699)
		(end 384.737864 -278.623522)
		(width 0.0889)
		(layer "In2.Cu")
		(net "M_I_CPU0_SB_DQ<7>")
	)
	(arc
		(start 378.15774 -278.623522)
		(mid 378.339991 -278.573172)
		(end 378.5235 -278.618696)
		(width 0.0889)
		(layer "In2.Cu")
		(net "M_I_CPU0_SB_DQ<7>")
	)
	(arc
		(start 385.677664 -278.623522)
		(mid 385.859915 -278.573172)
		(end 386.043424 -278.618696)
		(width 0.0889)
		(layer "In2.Cu")
		(net "M_I_CPU0_SB_DQ<7>")
	)
	(arc
		(start 390.37768 -278.623522)
		(mid 390.559931 -278.573172)
		(end 390.74344 -278.618696)
		(width 0.0889)
		(layer "In2.Cu")
		(net "M_I_CPU0_SB_DQ<7>")
	)
	(arc
		(start 379.106176 -278.618696)
		(mid 379.289684 -278.573202)
		(end 379.471936 -278.623522)
		(width 0.0889)
		(layer "In2.Cu")
		(net "M_I_CPU0_SB_DQ<7>")
	)
	(arc
		(start 386.051806 -278.623522)
		(mid 386.334762 -278.699699)
		(end 386.617718 -278.623522)
		(width 0.0889)
		(layer "In2.Cu")
		(net "M_I_CPU0_SB_DQ<7>")
	)
	(arc
		(start 387.566154 -278.618696)
		(mid 387.749662 -278.573202)
		(end 387.931914 -278.623522)
		(width 0.0889)
		(layer "In2.Cu")
		(net "M_I_CPU0_SB_DQ<7>")
	)
	(arc
		(start 390.751822 -278.623522)
		(mid 391.034778 -278.699699)
		(end 391.317734 -278.623522)
		(width 0.0889)
		(layer "In2.Cu")
		(net "M_I_CPU0_SB_DQ<7>")
	)
	(arc
		(start 387.931914 -278.623522)
		(mid 388.21487 -278.699699)
		(end 388.497826 -278.623522)
		(width 0.0889)
		(layer "In2.Cu")
		(net "M_I_CPU0_SB_DQ<7>")
	)
	(arc
		(start 386.99186 -278.623522)
		(mid 387.274816 -278.699699)
		(end 387.557772 -278.623522)
		(width 0.0889)
		(layer "In2.Cu")
		(net "M_I_CPU0_SB_DQ<7>")
	)
	(arc
		(start 386.617718 -278.623522)
		(mid 386.799969 -278.573172)
		(end 386.983478 -278.618696)
		(width 0.0889)
		(layer "In2.Cu")
		(net "M_I_CPU0_SB_DQ<7>")
	)
	(arc
		(start 381.917702 -278.623522)
		(mid 382.099953 -278.573172)
		(end 382.283462 -278.618696)
		(width 0.0889)
		(layer "In2.Cu")
		(net "M_I_CPU0_SB_DQ<7>")
	)
	(arc
		(start 381.35179 -278.623522)
		(mid 381.634746 -278.699699)
		(end 381.917702 -278.623522)
		(width 0.0889)
		(layer "In2.Cu")
		(net "M_I_CPU0_SB_DQ<7>")
	)
	(arc
		(start 380.04623 -278.618696)
		(mid 380.229738 -278.573202)
		(end 380.41199 -278.623522)
		(width 0.0889)
		(layer "In2.Cu")
		(net "M_I_CPU0_SB_DQ<7>")
	)
	(arc
		(start 389.43788 -278.623522)
		(mid 389.624824 -278.573267)
		(end 389.811768 -278.623522)
		(width 0.0889)
		(layer "In2.Cu")
		(net "M_I_CPU0_SB_DQ<7>")
	)
	(arc
		(start 378.531882 -278.623522)
		(mid 378.814838 -278.699699)
		(end 379.097794 -278.623522)
		(width 0.0889)
		(layer "In2.Cu")
		(net "M_I_CPU0_SB_DQ<7>")
	)
	(arc
		(start 393.196318 -278.623522)
		(mid 393.253242 -278.596425)
		(end 393.31392 -278.579326)
		(width 0.0889)
		(layer "In2.Cu")
		(net "M_I_CPU0_SB_DQ<7>")
	)
	(arc
		(start 391.691876 -278.623522)
		(mid 391.958806 -278.699471)
		(end 392.229594 -278.638762)
		(width 0.0889)
		(layer "In2.Cu")
		(net "M_I_CPU0_SB_DQ<7>")
	)
	(arc
		(start 376.333258 -278.59736)
		(mid 376.495447 -278.574625)
		(end 376.651774 -278.623522)
		(width 0.0889)
		(layer "In2.Cu")
		(net "M_I_CPU0_SB_DQ<7>")
	)
	(arc
		(start 382.866138 -278.618696)
		(mid 383.049646 -278.573202)
		(end 383.231898 -278.623522)
		(width 0.0889)
		(layer "In2.Cu")
		(net "M_I_CPU0_SB_DQ<7>")
	)
	(arc
		(start 391.326116 -278.618696)
		(mid 391.509624 -278.573202)
		(end 391.691876 -278.623522)
		(width 0.0889)
		(layer "In2.Cu")
		(net "M_I_CPU0_SB_DQ<7>")
	)
	(arc
		(start 392.2776 -278.61133)
		(mid 392.454528 -278.573502)
		(end 392.628374 -278.623522)
		(width 0.0889)
		(layer "In2.Cu")
		(net "M_I_CPU0_SB_DQ<7>")
	)
	(arc
		(start 376.651774 -278.623522)
		(mid 376.93473 -278.699699)
		(end 377.217686 -278.623522)
		(width 0.0889)
		(layer "In2.Cu")
		(net "M_I_CPU0_SB_DQ<7>")
	)
	(arc
		(start 377.591828 -278.623522)
		(mid 377.874784 -278.699699)
		(end 378.15774 -278.623522)
		(width 0.0889)
		(layer "In2.Cu")
		(net "M_I_CPU0_SB_DQ<7>")
	)
	(arc
		(start 388.506208 -278.618696)
		(mid 388.689716 -278.573202)
		(end 388.871968 -278.623522)
		(width 0.0889)
		(layer "In2.Cu")
		(net "M_I_CPU0_SB_DQ<7>")
	)
	(arc
		(start 382.291844 -278.623522)
		(mid 382.5748 -278.699699)
		(end 382.857756 -278.623522)
		(width 0.0889)
		(layer "In2.Cu")
		(net "M_I_CPU0_SB_DQ<7>")
	)
	(arc
		(start 379.471936 -278.623522)
		(mid 379.754892 -278.699699)
		(end 380.037848 -278.623522)
		(width 0.0889)
		(layer "In2.Cu")
		(net "M_I_CPU0_SB_DQ<7>")
	)
	(arc
		(start 377.217686 -278.623522)
		(mid 377.399937 -278.573172)
		(end 377.583446 -278.618696)
		(width 0.0889)
		(layer "In2.Cu")
		(net "M_I_CPU0_SB_DQ<7>")
	)
	(arc
		(start 383.231898 -278.623522)
		(mid 383.514854 -278.699699)
		(end 383.79781 -278.623522)
		(width 0.0889)
		(layer "In2.Cu")
		(net "M_I_CPU0_SB_DQ<7>")
	)
	(arc
		(start 380.977902 -278.623522)
		(mid 381.164846 -278.573267)
		(end 381.35179 -278.623522)
		(width 0.0889)
		(layer "In2.Cu")
		(net "M_I_CPU0_SB_DQ<7>")
	)
	(arc
		(start 385.111752 -278.623522)
		(mid 385.394708 -278.699699)
		(end 385.677664 -278.623522)
		(width 0.0889)
		(layer "In2.Cu")
		(net "M_I_CPU0_SB_DQ<7>")
	)
	(arc
		(start 383.806192 -278.618696)
		(mid 383.9897 -278.573202)
		(end 384.171952 -278.623522)
		(width 0.0889)
		(layer "In2.Cu")
		(net "M_I_CPU0_SB_DQ<7>")
	)
	(arc
		(start 384.737864 -278.623522)
		(mid 384.924808 -278.573267)
		(end 385.111752 -278.623522)
		(width 0.0889)
		(layer "In2.Cu")
		(net "M_I_CPU0_SB_DQ<7>")
	)
	(arc
		(start 388.871968 -278.623522)
		(mid 389.154924 -278.699699)
		(end 389.43788 -278.623522)
		(width 0.0889)
		(layer "In2.Cu")
		(net "M_I_CPU0_SB_DQ<7>")
	)
	(segment
		(start 377.407932 -277.870158)
		(end 377.874784 -278.136096)
		(width 0.10668)
		(layer "F.Cu")
		(net "M_I_CPU0_SB_DQ<6>")
	)
	(segment
		(start 405.104346 -283.009594)
		(end 405.332692 -283.009594)
		(width 0.14478)
		(layer "In2.Cu")
		(net "M_I_CPU0_SB_DQ<6>")
	)
	(segment
		(start 389.90778 -277.813516)
		(end 389.916162 -277.80869)
		(width 0.0889)
		(layer "In2.Cu")
		(net "M_I_CPU0_SB_DQ<6>")
	)
	(segment
		(start 407.296366 -284.94736)
		(end 407.283158 -284.960314)
		(width 0.14478)
		(layer "In2.Cu")
		(net "M_I_CPU0_SB_DQ<6>")
	)
	(segment
		(start 415.30651 -288.009838)
		(end 415.524442 -288.22777)
		(width 0.14478)
		(layer "In2.Cu")
		(net "M_I_CPU0_SB_DQ<6>")
	)
	(segment
		(start 393.384278 -277.890224)
		(end 393.39012 -277.896066)
		(width 0.0889)
		(layer "In2.Cu")
		(net "M_I_CPU0_SB_DQ<6>")
	)
	(segment
		(start 385.207764 -277.813516)
		(end 385.216146 -277.80869)
		(width 0.0889)
		(layer "In2.Cu")
		(net "M_I_CPU0_SB_DQ<6>")
	)
	(segment
		(start 408.076654 -285.727648)
		(end 408.063446 -285.740602)
		(width 0.14478)
		(layer "In2.Cu")
		(net "M_I_CPU0_SB_DQ<6>")
	)
	(segment
		(start 384.63347 -277.80869)
		(end 384.641852 -277.813516)
		(width 0.0889)
		(layer "In2.Cu")
		(net "M_I_CPU0_SB_DQ<6>")
	)
	(segment
		(start 409.234132 -286.911034)
		(end 409.246832 -286.898334)
		(width 0.14478)
		(layer "In2.Cu")
		(net "M_I_CPU0_SB_DQ<6>")
	)
	(segment
		(start 408.466544 -286.118046)
		(end 408.695144 -286.118046)
		(width 0.14478)
		(layer "In2.Cu")
		(net "M_I_CPU0_SB_DQ<6>")
	)
	(segment
		(start 407.673556 -285.350458)
		(end 407.686256 -285.337758)
		(width 0.14478)
		(layer "In2.Cu")
		(net "M_I_CPU0_SB_DQ<6>")
	)
	(segment
		(start 404.955502 -282.378404)
		(end 404.955502 -282.606496)
		(width 0.14478)
		(layer "In2.Cu")
		(net "M_I_CPU0_SB_DQ<6>")
	)
	(segment
		(start 410.772102 -288.67735)
		(end 410.851858 -288.71037)
		(width 0.14478)
		(layer "In2.Cu")
		(net "M_I_CPU0_SB_DQ<6>")
	)
	(segment
		(start 426.65396 -287.479232)
		(end 427.304708 -287.479232)
		(width 0.14478)
		(layer "In2.Cu")
		(net "M_I_CPU0_SB_DQ<6>")
	)
	(segment
		(start 409.63723 -287.060132)
		(end 409.63723 -287.288224)
		(width 0.14478)
		(layer "In2.Cu")
		(net "M_I_CPU0_SB_DQ<6>")
	)
	(segment
		(start 404.565104 -282.216606)
		(end 404.793704 -282.216606)
		(width 0.14478)
		(layer "In2.Cu")
		(net "M_I_CPU0_SB_DQ<6>")
	)
	(segment
		(start 410.25572 -287.678622)
		(end 410.417518 -287.84042)
		(width 0.14478)
		(layer "In2.Cu")
		(net "M_I_CPU0_SB_DQ<6>")
	)
	(segment
		(start 404.942294 -282.61945)
		(end 404.942294 -282.847542)
		(width 0.14478)
		(layer "In2.Cu")
		(net "M_I_CPU0_SB_DQ<6>")
	)
	(segment
		(start 408.063446 -285.968694)
		(end 408.225498 -286.130746)
		(width 0.14478)
		(layer "In2.Cu")
		(net "M_I_CPU0_SB_DQ<6>")
	)
	(segment
		(start 383.693416 -277.80869)
		(end 383.701798 -277.813516)
		(width 0.0889)
		(layer "In2.Cu")
		(net "M_I_CPU0_SB_DQ<6>")
	)
	(segment
		(start 409.246832 -286.898334)
		(end 409.475432 -286.898334)
		(width 0.14478)
		(layer "In2.Cu")
		(net "M_I_CPU0_SB_DQ<6>")
	)
	(segment
		(start 415.524442 -288.22777)
		(end 415.783522 -288.22777)
		(width 0.14478)
		(layer "In2.Cu")
		(net "M_I_CPU0_SB_DQ<6>")
	)
	(segment
		(start 407.686256 -285.337758)
		(end 407.914856 -285.337758)
		(width 0.14478)
		(layer "In2.Cu")
		(net "M_I_CPU0_SB_DQ<6>")
	)
	(segment
		(start 407.283158 -285.188406)
		(end 407.44521 -285.350458)
		(width 0.14478)
		(layer "In2.Cu")
		(net "M_I_CPU0_SB_DQ<6>")
	)
	(segment
		(start 377.874784 -278.136096)
		(end 377.72086 -277.870666)
		(width 0.0889)
		(layer "In2.Cu")
		(net "M_I_CPU0_SB_DQ<6>")
	)
	(segment
		(start 410.417518 -288.068512)
		(end 410.40431 -288.081466)
		(width 0.14478)
		(layer "In2.Cu")
		(net "M_I_CPU0_SB_DQ<6>")
	)
	(segment
		(start 422.741852 -287.860232)
		(end 424.178222 -287.860232)
		(width 0.14478)
		(layer "In2.Cu")
		(net "M_I_CPU0_SB_DQ<6>")
	)
	(segment
		(start 406.664922 -284.57017)
		(end 406.893268 -284.57017)
		(width 0.14478)
		(layer "In2.Cu")
		(net "M_I_CPU0_SB_DQ<6>")
	)
	(segment
		(start 410.417518 -287.84042)
		(end 410.417518 -288.068512)
		(width 0.14478)
		(layer "In2.Cu")
		(net "M_I_CPU0_SB_DQ<6>")
	)
	(segment
		(start 416.15106 -287.860232)
		(end 417.12261 -287.860232)
		(width 0.14478)
		(layer "In2.Cu")
		(net "M_I_CPU0_SB_DQ<6>")
	)
	(segment
		(start 404.942294 -282.847542)
		(end 405.104346 -283.009594)
		(width 0.14478)
		(layer "In2.Cu")
		(net "M_I_CPU0_SB_DQ<6>")
	)
	(segment
		(start 424.571668 -288.253678)
		(end 424.85183 -288.253678)
		(width 0.14478)
		(layer "In2.Cu")
		(net "M_I_CPU0_SB_DQ<6>")
	)
	(segment
		(start 405.345392 -282.996894)
		(end 405.573992 -282.996894)
		(width 0.14478)
		(layer "In2.Cu")
		(net "M_I_CPU0_SB_DQ<6>")
	)
	(segment
		(start 404.793704 -282.216606)
		(end 404.955502 -282.378404)
		(width 0.14478)
		(layer "In2.Cu")
		(net "M_I_CPU0_SB_DQ<6>")
	)
	(segment
		(start 407.914856 -285.337758)
		(end 408.076654 -285.499556)
		(width 0.14478)
		(layer "In2.Cu")
		(net "M_I_CPU0_SB_DQ<6>")
	)
	(segment
		(start 408.453844 -286.130746)
		(end 408.466544 -286.118046)
		(width 0.14478)
		(layer "In2.Cu")
		(net "M_I_CPU0_SB_DQ<6>")
	)
	(segment
		(start 427.456092 -287.630616)
		(end 427.456092 -288.285174)
		(width 0.14478)
		(layer "In2.Cu")
		(net "M_I_CPU0_SB_DQ<6>")
	)
	(segment
		(start 393.679426 -277.896066)
		(end 394.429996 -277.145496)
		(width 0.0889)
		(layer "In2.Cu")
		(net "M_I_CPU0_SB_DQ<6>")
	)
	(segment
		(start 405.884634 -283.789882)
		(end 406.11298 -283.789882)
		(width 0.14478)
		(layer "In2.Cu")
		(net "M_I_CPU0_SB_DQ<6>")
	)
	(segment
		(start 409.475432 -286.898334)
		(end 409.63723 -287.060132)
		(width 0.14478)
		(layer "In2.Cu")
		(net "M_I_CPU0_SB_DQ<6>")
	)
	(segment
		(start 410.01442 -287.691322)
		(end 410.02712 -287.678622)
		(width 0.14478)
		(layer "In2.Cu")
		(net "M_I_CPU0_SB_DQ<6>")
	)
	(segment
		(start 409.786074 -287.691322)
		(end 410.01442 -287.691322)
		(width 0.14478)
		(layer "In2.Cu")
		(net "M_I_CPU0_SB_DQ<6>")
	)
	(segment
		(start 414.67024 -288.090102)
		(end 415.007044 -287.950402)
		(width 0.14478)
		(layer "In2.Cu")
		(net "M_I_CPU0_SB_DQ<6>")
	)
	(segment
		(start 406.893268 -284.57017)
		(end 406.905968 -284.55747)
		(width 0.14478)
		(layer "In2.Cu")
		(net "M_I_CPU0_SB_DQ<6>")
	)
	(segment
		(start 406.50287 -284.408118)
		(end 406.664922 -284.57017)
		(width 0.14478)
		(layer "In2.Cu")
		(net "M_I_CPU0_SB_DQ<6>")
	)
	(segment
		(start 405.73579 -283.386784)
		(end 405.722582 -283.399738)
		(width 0.14478)
		(layer "In2.Cu")
		(net "M_I_CPU0_SB_DQ<6>")
	)
	(segment
		(start 422.397174 -288.003234)
		(end 422.741852 -287.860232)
		(width 0.14478)
		(layer "In2.Cu")
		(net "M_I_CPU0_SB_DQ<6>")
	)
	(segment
		(start 406.905968 -284.55747)
		(end 407.134568 -284.55747)
		(width 0.14478)
		(layer "In2.Cu")
		(net "M_I_CPU0_SB_DQ<6>")
	)
	(segment
		(start 417.46297 -288.000694)
		(end 419.174422 -288.71037)
		(width 0.14478)
		(layer "In2.Cu")
		(net "M_I_CPU0_SB_DQ<6>")
	)
	(segment
		(start 425.803314 -288.045144)
		(end 425.9961 -288.23793)
		(width 0.14478)
		(layer "In2.Cu")
		(net "M_I_CPU0_SB_DQ<6>")
	)
	(segment
		(start 409.624022 -287.301178)
		(end 409.624022 -287.52927)
		(width 0.14478)
		(layer "In2.Cu")
		(net "M_I_CPU0_SB_DQ<6>")
	)
	(segment
		(start 417.462208 -288.000948)
		(end 417.46297 -288.000694)
		(width 0.14478)
		(layer "In2.Cu")
		(net "M_I_CPU0_SB_DQ<6>")
	)
	(segment
		(start 406.11298 -283.789882)
		(end 406.12568 -283.777182)
		(width 0.14478)
		(layer "In2.Cu")
		(net "M_I_CPU0_SB_DQ<6>")
	)
	(segment
		(start 408.063446 -285.740602)
		(end 408.063446 -285.968694)
		(width 0.14478)
		(layer "In2.Cu")
		(net "M_I_CPU0_SB_DQ<6>")
	)
	(segment
		(start 394.429996 -277.145496)
		(end 395.938502 -277.145496)
		(width 0.0889)
		(layer "In2.Cu")
		(net "M_I_CPU0_SB_DQ<6>")
	)
	(segment
		(start 386.147818 -277.813516)
		(end 386.1562 -277.80869)
		(width 0.0889)
		(layer "In2.Cu")
		(net "M_I_CPU0_SB_DQ<6>")
	)
	(segment
		(start 381.447802 -277.813516)
		(end 381.456184 -277.80869)
		(width 0.0889)
		(layer "In2.Cu")
		(net "M_I_CPU0_SB_DQ<6>")
	)
	(segment
		(start 399.240248 -277.145496)
		(end 404.324058 -282.229306)
		(width 0.14478)
		(layer "In2.Cu")
		(net "M_I_CPU0_SB_DQ<6>")
	)
	(segment
		(start 426.461174 -288.045144)
		(end 426.461174 -287.672018)
		(width 0.14478)
		(layer "In2.Cu")
		(net "M_I_CPU0_SB_DQ<6>")
	)
	(segment
		(start 425.9961 -288.23793)
		(end 426.268388 -288.23793)
		(width 0.14478)
		(layer "In2.Cu")
		(net "M_I_CPU0_SB_DQ<6>")
	)
	(segment
		(start 404.552404 -282.229306)
		(end 404.565104 -282.216606)
		(width 0.14478)
		(layer "In2.Cu")
		(net "M_I_CPU0_SB_DQ<6>")
	)
	(segment
		(start 407.283158 -284.960314)
		(end 407.283158 -285.188406)
		(width 0.14478)
		(layer "In2.Cu")
		(net "M_I_CPU0_SB_DQ<6>")
	)
	(segment
		(start 407.296366 -284.719268)
		(end 407.296366 -284.94736)
		(width 0.14478)
		(layer "In2.Cu")
		(net "M_I_CPU0_SB_DQ<6>")
	)
	(segment
		(start 425.255182 -287.481772)
		(end 425.610528 -287.481772)
		(width 0.14478)
		(layer "In2.Cu")
		(net "M_I_CPU0_SB_DQ<6>")
	)
	(segment
		(start 417.12261 -287.860232)
		(end 417.462208 -288.000948)
		(width 0.14478)
		(layer "In2.Cu")
		(net "M_I_CPU0_SB_DQ<6>")
	)
	(segment
		(start 425.07662 -288.028888)
		(end 425.07662 -287.660334)
		(width 0.14478)
		(layer "In2.Cu")
		(net "M_I_CPU0_SB_DQ<6>")
	)
	(segment
		(start 404.955502 -282.606496)
		(end 404.942294 -282.61945)
		(width 0.14478)
		(layer "In2.Cu")
		(net "M_I_CPU0_SB_DQ<6>")
	)
	(segment
		(start 424.178222 -287.860232)
		(end 424.571668 -288.253678)
		(width 0.14478)
		(layer "In2.Cu")
		(net "M_I_CPU0_SB_DQ<6>")
	)
	(segment
		(start 414.22574 -288.657792)
		(end 414.478724 -288.552636)
		(width 0.14478)
		(layer "In2.Cu")
		(net "M_I_CPU0_SB_DQ<6>")
	)
	(segment
		(start 393.39012 -277.896066)
		(end 393.679426 -277.896066)
		(width 0.0889)
		(layer "In2.Cu")
		(net "M_I_CPU0_SB_DQ<6>")
	)
	(segment
		(start 408.843734 -286.52089)
		(end 408.843734 -286.748982)
		(width 0.14478)
		(layer "In2.Cu")
		(net "M_I_CPU0_SB_DQ<6>")
	)
	(segment
		(start 380.873508 -277.80869)
		(end 380.88189 -277.813516)
		(width 0.0889)
		(layer "In2.Cu")
		(net "M_I_CPU0_SB_DQ<6>")
	)
	(segment
		(start 424.85183 -288.253678)
		(end 425.07662 -288.028888)
		(width 0.14478)
		(layer "In2.Cu")
		(net "M_I_CPU0_SB_DQ<6>")
	)
	(segment
		(start 413.18561 -288.71037)
		(end 413.769556 -288.468308)
		(width 0.14478)
		(layer "In2.Cu")
		(net "M_I_CPU0_SB_DQ<6>")
	)
	(segment
		(start 392.153394 -277.80869)
		(end 392.161776 -277.813516)
		(width 0.0889)
		(layer "In2.Cu")
		(net "M_I_CPU0_SB_DQ<6>")
	)
	(segment
		(start 409.624022 -287.52927)
		(end 409.786074 -287.691322)
		(width 0.14478)
		(layer "In2.Cu")
		(net "M_I_CPU0_SB_DQ<6>")
	)
	(segment
		(start 414.478724 -288.552636)
		(end 414.67024 -288.090102)
		(width 0.14478)
		(layer "In2.Cu")
		(net "M_I_CPU0_SB_DQ<6>")
	)
	(segment
		(start 406.516078 -284.167072)
		(end 406.50287 -284.180026)
		(width 0.14478)
		(layer "In2.Cu")
		(net "M_I_CPU0_SB_DQ<6>")
	)
	(segment
		(start 408.225498 -286.130746)
		(end 408.453844 -286.130746)
		(width 0.14478)
		(layer "In2.Cu")
		(net "M_I_CPU0_SB_DQ<6>")
	)
	(segment
		(start 409.005786 -286.911034)
		(end 409.234132 -286.911034)
		(width 0.14478)
		(layer "In2.Cu")
		(net "M_I_CPU0_SB_DQ<6>")
	)
	(segment
		(start 408.695144 -286.118046)
		(end 408.856942 -286.279844)
		(width 0.14478)
		(layer "In2.Cu")
		(net "M_I_CPU0_SB_DQ<6>")
	)
	(segment
		(start 406.35428 -283.777182)
		(end 406.516078 -283.93898)
		(width 0.14478)
		(layer "In2.Cu")
		(net "M_I_CPU0_SB_DQ<6>")
	)
	(segment
		(start 410.02712 -287.678622)
		(end 410.25572 -287.678622)
		(width 0.14478)
		(layer "In2.Cu")
		(net "M_I_CPU0_SB_DQ<6>")
	)
	(segment
		(start 421.941752 -288.593276)
		(end 422.197276 -288.487358)
		(width 0.14478)
		(layer "In2.Cu")
		(net "M_I_CPU0_SB_DQ<6>")
	)
	(segment
		(start 379.933454 -277.80869)
		(end 379.941836 -277.813516)
		(width 0.0889)
		(layer "In2.Cu")
		(net "M_I_CPU0_SB_DQ<6>")
	)
	(segment
		(start 406.12568 -283.777182)
		(end 406.35428 -283.777182)
		(width 0.14478)
		(layer "In2.Cu")
		(net "M_I_CPU0_SB_DQ<6>")
	)
	(segment
		(start 408.856942 -286.507936)
		(end 408.843734 -286.52089)
		(width 0.14478)
		(layer "In2.Cu")
		(net "M_I_CPU0_SB_DQ<6>")
	)
	(segment
		(start 425.610528 -287.481772)
		(end 425.803314 -287.674558)
		(width 0.14478)
		(layer "In2.Cu")
		(net "M_I_CPU0_SB_DQ<6>")
	)
	(segment
		(start 405.722582 -283.62783)
		(end 405.884634 -283.789882)
		(width 0.14478)
		(layer "In2.Cu")
		(net "M_I_CPU0_SB_DQ<6>")
	)
	(segment
		(start 392.161776 -277.813516)
		(end 392.176508 -277.822152)
		(width 0.0889)
		(layer "In2.Cu")
		(net "M_I_CPU0_SB_DQ<6>")
	)
	(segment
		(start 421.458136 -288.392616)
		(end 421.941752 -288.593276)
		(width 0.14478)
		(layer "In2.Cu")
		(net "M_I_CPU0_SB_DQ<6>")
	)
	(segment
		(start 415.007044 -287.950402)
		(end 415.30651 -288.009838)
		(width 0.14478)
		(layer "In2.Cu")
		(net "M_I_CPU0_SB_DQ<6>")
	)
	(segment
		(start 405.73579 -283.158692)
		(end 405.73579 -283.386784)
		(width 0.14478)
		(layer "In2.Cu")
		(net "M_I_CPU0_SB_DQ<6>")
	)
	(segment
		(start 405.722582 -283.399738)
		(end 405.722582 -283.62783)
		(width 0.14478)
		(layer "In2.Cu")
		(net "M_I_CPU0_SB_DQ<6>")
	)
	(segment
		(start 422.197276 -288.487358)
		(end 422.397174 -288.003234)
		(width 0.14478)
		(layer "In2.Cu")
		(net "M_I_CPU0_SB_DQ<6>")
	)
	(segment
		(start 410.40431 -288.081466)
		(end 410.40431 -288.309558)
		(width 0.14478)
		(layer "In2.Cu")
		(net "M_I_CPU0_SB_DQ<6>")
	)
	(segment
		(start 405.573992 -282.996894)
		(end 405.73579 -283.158692)
		(width 0.14478)
		(layer "In2.Cu")
		(net "M_I_CPU0_SB_DQ<6>")
	)
	(segment
		(start 405.332692 -283.009594)
		(end 405.345392 -282.996894)
		(width 0.14478)
		(layer "In2.Cu")
		(net "M_I_CPU0_SB_DQ<6>")
	)
	(segment
		(start 407.44521 -285.350458)
		(end 407.673556 -285.350458)
		(width 0.14478)
		(layer "In2.Cu")
		(net "M_I_CPU0_SB_DQ<6>")
	)
	(segment
		(start 404.324058 -282.229306)
		(end 404.552404 -282.229306)
		(width 0.14478)
		(layer "In2.Cu")
		(net "M_I_CPU0_SB_DQ<6>")
	)
	(segment
		(start 408.076654 -285.499556)
		(end 408.076654 -285.727648)
		(width 0.14478)
		(layer "In2.Cu")
		(net "M_I_CPU0_SB_DQ<6>")
	)
	(segment
		(start 395.938502 -277.145496)
		(end 399.240248 -277.145496)
		(width 0.14478)
		(layer "In2.Cu")
		(net "M_I_CPU0_SB_DQ<6>")
	)
	(segment
		(start 425.07662 -287.660334)
		(end 425.255182 -287.481772)
		(width 0.14478)
		(layer "In2.Cu")
		(net "M_I_CPU0_SB_DQ<6>")
	)
	(segment
		(start 409.63723 -287.288224)
		(end 409.624022 -287.301178)
		(width 0.14478)
		(layer "In2.Cu")
		(net "M_I_CPU0_SB_DQ<6>")
	)
	(segment
		(start 420.69131 -288.71037)
		(end 421.458136 -288.392616)
		(width 0.14478)
		(layer "In2.Cu")
		(net "M_I_CPU0_SB_DQ<6>")
	)
	(segment
		(start 406.516078 -283.93898)
		(end 406.516078 -284.167072)
		(width 0.14478)
		(layer "In2.Cu")
		(net "M_I_CPU0_SB_DQ<6>")
	)
	(segment
		(start 419.174422 -288.71037)
		(end 420.69131 -288.71037)
		(width 0.14478)
		(layer "In2.Cu")
		(net "M_I_CPU0_SB_DQ<6>")
	)
	(segment
		(start 408.856942 -286.279844)
		(end 408.856942 -286.507936)
		(width 0.14478)
		(layer "In2.Cu")
		(net "M_I_CPU0_SB_DQ<6>")
	)
	(segment
		(start 377.72086 -277.870666)
		(end 377.743212 -277.787354)
		(width 0.0889)
		(layer "In2.Cu")
		(net "M_I_CPU0_SB_DQ<6>")
	)
	(segment
		(start 410.851858 -288.71037)
		(end 413.18561 -288.71037)
		(width 0.14478)
		(layer "In2.Cu")
		(net "M_I_CPU0_SB_DQ<6>")
	)
	(segment
		(start 415.783522 -288.22777)
		(end 416.15106 -287.860232)
		(width 0.14478)
		(layer "In2.Cu")
		(net "M_I_CPU0_SB_DQ<6>")
	)
	(segment
		(start 413.769556 -288.468308)
		(end 414.22574 -288.657792)
		(width 0.14478)
		(layer "In2.Cu")
		(net "M_I_CPU0_SB_DQ<6>")
	)
	(segment
		(start 426.268388 -288.23793)
		(end 426.461174 -288.045144)
		(width 0.14478)
		(layer "In2.Cu")
		(net "M_I_CPU0_SB_DQ<6>")
	)
	(segment
		(start 425.803314 -287.674558)
		(end 425.803314 -288.045144)
		(width 0.14478)
		(layer "In2.Cu")
		(net "M_I_CPU0_SB_DQ<6>")
	)
	(segment
		(start 389.333486 -277.80869)
		(end 389.341868 -277.813516)
		(width 0.0889)
		(layer "In2.Cu")
		(net "M_I_CPU0_SB_DQ<6>")
	)
	(segment
		(start 410.40431 -288.309558)
		(end 410.772102 -288.67735)
		(width 0.14478)
		(layer "In2.Cu")
		(net "M_I_CPU0_SB_DQ<6>")
	)
	(segment
		(start 388.393432 -277.80869)
		(end 388.401814 -277.813516)
		(width 0.0889)
		(layer "In2.Cu")
		(net "M_I_CPU0_SB_DQ<6>")
	)
	(segment
		(start 426.461174 -287.672018)
		(end 426.65396 -287.479232)
		(width 0.14478)
		(layer "In2.Cu")
		(net "M_I_CPU0_SB_DQ<6>")
	)
	(segment
		(start 407.134568 -284.55747)
		(end 407.296366 -284.719268)
		(width 0.14478)
		(layer "In2.Cu")
		(net "M_I_CPU0_SB_DQ<6>")
	)
	(segment
		(start 408.843734 -286.748982)
		(end 409.005786 -286.911034)
		(width 0.14478)
		(layer "In2.Cu")
		(net "M_I_CPU0_SB_DQ<6>")
	)
	(segment
		(start 427.304708 -287.479232)
		(end 427.456092 -287.630616)
		(width 0.14478)
		(layer "In2.Cu")
		(net "M_I_CPU0_SB_DQ<6>")
	)
	(segment
		(start 406.50287 -284.180026)
		(end 406.50287 -284.408118)
		(width 0.14478)
		(layer "In2.Cu")
		(net "M_I_CPU0_SB_DQ<6>")
	)
	(arc
		(start 388.027672 -277.813516)
		(mid 388.209923 -277.763166)
		(end 388.393432 -277.80869)
		(width 0.0889)
		(layer "In2.Cu")
		(net "M_I_CPU0_SB_DQ<6>")
	)
	(arc
		(start 390.847834 -277.813516)
		(mid 391.034778 -277.763261)
		(end 391.221722 -277.813516)
		(width 0.0889)
		(layer "In2.Cu")
		(net "M_I_CPU0_SB_DQ<6>")
	)
	(arc
		(start 382.387856 -277.813516)
		(mid 382.5748 -277.763261)
		(end 382.761744 -277.813516)
		(width 0.0889)
		(layer "In2.Cu")
		(net "M_I_CPU0_SB_DQ<6>")
	)
	(arc
		(start 381.821944 -277.813516)
		(mid 382.1049 -277.889693)
		(end 382.387856 -277.813516)
		(width 0.0889)
		(layer "In2.Cu")
		(net "M_I_CPU0_SB_DQ<6>")
	)
	(arc
		(start 378.061982 -277.813516)
		(mid 378.344938 -277.889693)
		(end 378.627894 -277.813516)
		(width 0.0889)
		(layer "In2.Cu")
		(net "M_I_CPU0_SB_DQ<6>")
	)
	(arc
		(start 391.787634 -277.813516)
		(mid 391.969885 -277.763166)
		(end 392.153394 -277.80869)
		(width 0.0889)
		(layer "In2.Cu")
		(net "M_I_CPU0_SB_DQ<6>")
	)
	(arc
		(start 387.46176 -277.813516)
		(mid 387.744716 -277.889693)
		(end 388.027672 -277.813516)
		(width 0.0889)
		(layer "In2.Cu")
		(net "M_I_CPU0_SB_DQ<6>")
	)
	(arc
		(start 379.001782 -277.813516)
		(mid 379.284738 -277.889693)
		(end 379.567694 -277.813516)
		(width 0.0889)
		(layer "In2.Cu")
		(net "M_I_CPU0_SB_DQ<6>")
	)
	(arc
		(start 389.916162 -277.80869)
		(mid 390.09967 -277.763196)
		(end 390.281922 -277.813516)
		(width 0.0889)
		(layer "In2.Cu")
		(net "M_I_CPU0_SB_DQ<6>")
	)
	(arc
		(start 383.701798 -277.813516)
		(mid 383.984754 -277.889693)
		(end 384.26771 -277.813516)
		(width 0.0889)
		(layer "In2.Cu")
		(net "M_I_CPU0_SB_DQ<6>")
	)
	(arc
		(start 377.743212 -277.787354)
		(mid 377.905544 -277.764536)
		(end 378.061982 -277.813516)
		(width 0.0889)
		(layer "In2.Cu")
		(net "M_I_CPU0_SB_DQ<6>")
	)
	(arc
		(start 384.641852 -277.813516)
		(mid 384.924808 -277.889693)
		(end 385.207764 -277.813516)
		(width 0.0889)
		(layer "In2.Cu")
		(net "M_I_CPU0_SB_DQ<6>")
	)
	(arc
		(start 378.627894 -277.813516)
		(mid 378.814838 -277.763261)
		(end 379.001782 -277.813516)
		(width 0.0889)
		(layer "In2.Cu")
		(net "M_I_CPU0_SB_DQ<6>")
	)
	(arc
		(start 379.567694 -277.813516)
		(mid 379.749945 -277.763166)
		(end 379.933454 -277.80869)
		(width 0.0889)
		(layer "In2.Cu")
		(net "M_I_CPU0_SB_DQ<6>")
	)
	(arc
		(start 392.176508 -277.822152)
		(mid 392.453491 -277.889956)
		(end 392.728196 -277.813516)
		(width 0.0889)
		(layer "In2.Cu")
		(net "M_I_CPU0_SB_DQ<6>")
	)
	(arc
		(start 385.216146 -277.80869)
		(mid 385.399654 -277.763196)
		(end 385.581906 -277.813516)
		(width 0.0889)
		(layer "In2.Cu")
		(net "M_I_CPU0_SB_DQ<6>")
	)
	(arc
		(start 389.341868 -277.813516)
		(mid 389.624824 -277.889693)
		(end 389.90778 -277.813516)
		(width 0.0889)
		(layer "In2.Cu")
		(net "M_I_CPU0_SB_DQ<6>")
	)
	(arc
		(start 393.08405 -277.803356)
		(mid 393.228029 -277.867987)
		(end 393.384278 -277.890224)
		(width 0.0889)
		(layer "In2.Cu")
		(net "M_I_CPU0_SB_DQ<6>")
	)
	(arc
		(start 380.507748 -277.813516)
		(mid 380.689999 -277.763166)
		(end 380.873508 -277.80869)
		(width 0.0889)
		(layer "In2.Cu")
		(net "M_I_CPU0_SB_DQ<6>")
	)
	(arc
		(start 386.52196 -277.813516)
		(mid 386.804916 -277.889693)
		(end 387.087872 -277.813516)
		(width 0.0889)
		(layer "In2.Cu")
		(net "M_I_CPU0_SB_DQ<6>")
	)
	(arc
		(start 379.941836 -277.813516)
		(mid 380.224792 -277.889693)
		(end 380.507748 -277.813516)
		(width 0.0889)
		(layer "In2.Cu")
		(net "M_I_CPU0_SB_DQ<6>")
	)
	(arc
		(start 390.281922 -277.813516)
		(mid 390.564878 -277.889693)
		(end 390.847834 -277.813516)
		(width 0.0889)
		(layer "In2.Cu")
		(net "M_I_CPU0_SB_DQ<6>")
	)
	(arc
		(start 382.761744 -277.813516)
		(mid 383.0447 -277.889693)
		(end 383.327656 -277.813516)
		(width 0.0889)
		(layer "In2.Cu")
		(net "M_I_CPU0_SB_DQ<6>")
	)
	(arc
		(start 383.327656 -277.813516)
		(mid 383.509907 -277.763166)
		(end 383.693416 -277.80869)
		(width 0.0889)
		(layer "In2.Cu")
		(net "M_I_CPU0_SB_DQ<6>")
	)
	(arc
		(start 381.456184 -277.80869)
		(mid 381.639692 -277.763196)
		(end 381.821944 -277.813516)
		(width 0.0889)
		(layer "In2.Cu")
		(net "M_I_CPU0_SB_DQ<6>")
	)
	(arc
		(start 380.88189 -277.813516)
		(mid 381.164846 -277.889693)
		(end 381.447802 -277.813516)
		(width 0.0889)
		(layer "In2.Cu")
		(net "M_I_CPU0_SB_DQ<6>")
	)
	(arc
		(start 388.401814 -277.813516)
		(mid 388.68477 -277.889693)
		(end 388.967726 -277.813516)
		(width 0.0889)
		(layer "In2.Cu")
		(net "M_I_CPU0_SB_DQ<6>")
	)
	(arc
		(start 391.221722 -277.813516)
		(mid 391.504678 -277.889693)
		(end 391.787634 -277.813516)
		(width 0.0889)
		(layer "In2.Cu")
		(net "M_I_CPU0_SB_DQ<6>")
	)
	(arc
		(start 388.967726 -277.813516)
		(mid 389.149977 -277.763166)
		(end 389.333486 -277.80869)
		(width 0.0889)
		(layer "In2.Cu")
		(net "M_I_CPU0_SB_DQ<6>")
	)
	(arc
		(start 392.728196 -277.813516)
		(mid 392.904824 -277.763283)
		(end 393.08405 -277.803356)
		(width 0.0889)
		(layer "In2.Cu")
		(net "M_I_CPU0_SB_DQ<6>")
	)
	(arc
		(start 384.26771 -277.813516)
		(mid 384.449961 -277.763166)
		(end 384.63347 -277.80869)
		(width 0.0889)
		(layer "In2.Cu")
		(net "M_I_CPU0_SB_DQ<6>")
	)
	(arc
		(start 386.1562 -277.80869)
		(mid 386.339708 -277.763196)
		(end 386.52196 -277.813516)
		(width 0.0889)
		(layer "In2.Cu")
		(net "M_I_CPU0_SB_DQ<6>")
	)
	(arc
		(start 385.581906 -277.813516)
		(mid 385.864862 -277.889693)
		(end 386.147818 -277.813516)
		(width 0.0889)
		(layer "In2.Cu")
		(net "M_I_CPU0_SB_DQ<6>")
	)
	(arc
		(start 387.087872 -277.813516)
		(mid 387.274816 -277.763261)
		(end 387.46176 -277.813516)
		(width 0.0889)
		(layer "In2.Cu")
		(net "M_I_CPU0_SB_DQ<6>")
	)
	(segment
		(start 375.528078 -277.870158)
		(end 375.99493 -278.136096)
		(width 0.10668)
		(layer "F.Cu")
		(net "M_I_CPU0_SB_DQ<5>")
	)
	(segment
		(start 377.68784 -278.458676)
		(end 377.696222 -278.463502)
		(width 0.0889)
		(layer "In2.Cu")
		(net "M_I_CPU0_SB_DQ<5>")
	)
	(segment
		(start 376.747786 -278.458676)
		(end 376.756168 -278.463502)
		(width 0.0889)
		(layer "In2.Cu")
		(net "M_I_CPU0_SB_DQ<5>")
	)
	(segment
		(start 412.128208 -289.560254)
		(end 412.37281 -289.560254)
		(width 0.14478)
		(layer "In2.Cu")
		(net "M_I_CPU0_SB_DQ<5>")
	)
	(segment
		(start 431.131472 -288.71037)
		(end 431.55616 -289.135058)
		(width 0.14478)
		(layer "In2.Cu")
		(net "M_I_CPU0_SB_DQ<5>")
	)
	(segment
		(start 385.207764 -278.458676)
		(end 385.216146 -278.463502)
		(width 0.0889)
		(layer "In2.Cu")
		(net "M_I_CPU0_SB_DQ<5>")
	)
	(segment
		(start 420.062152 -289.560254)
		(end 423.454576 -288.71037)
		(width 0.14478)
		(layer "In2.Cu")
		(net "M_I_CPU0_SB_DQ<5>")
	)
	(segment
		(start 411.597856 -289.427666)
		(end 412.128208 -289.560254)
		(width 0.14478)
		(layer "In2.Cu")
		(net "M_I_CPU0_SB_DQ<5>")
	)
	(segment
		(start 410.889196 -289.212782)
		(end 411.597856 -289.427666)
		(width 0.14478)
		(layer "In2.Cu")
		(net "M_I_CPU0_SB_DQ<5>")
	)
	(segment
		(start 392.160506 -278.458422)
		(end 392.186668 -278.443436)
		(width 0.0889)
		(layer "In2.Cu")
		(net "M_I_CPU0_SB_DQ<5>")
	)
	(segment
		(start 386.147818 -278.458676)
		(end 386.1562 -278.463502)
		(width 0.0889)
		(layer "In2.Cu")
		(net "M_I_CPU0_SB_DQ<5>")
	)
	(segment
		(start 384.63347 -278.463502)
		(end 384.641852 -278.458676)
		(width 0.0889)
		(layer "In2.Cu")
		(net "M_I_CPU0_SB_DQ<5>")
	)
	(segment
		(start 389.90778 -278.458676)
		(end 389.916162 -278.463502)
		(width 0.0889)
		(layer "In2.Cu")
		(net "M_I_CPU0_SB_DQ<5>")
	)
	(segment
		(start 417.420044 -288.71037)
		(end 418.018722 -288.829496)
		(width 0.14478)
		(layer "In2.Cu")
		(net "M_I_CPU0_SB_DQ<5>")
	)
	(segment
		(start 380.873508 -278.463502)
		(end 380.88189 -278.458676)
		(width 0.0889)
		(layer "In2.Cu")
		(net "M_I_CPU0_SB_DQ<5>")
	)
	(segment
		(start 399.058892 -277.600156)
		(end 410.517848 -289.059112)
		(width 0.14478)
		(layer "In2.Cu")
		(net "M_I_CPU0_SB_DQ<5>")
	)
	(segment
		(start 410.517848 -289.059112)
		(end 410.889196 -289.212782)
		(width 0.14478)
		(layer "In2.Cu")
		(net "M_I_CPU0_SB_DQ<5>")
	)
	(segment
		(start 393.754356 -278.388826)
		(end 394.639292 -277.50389)
		(width 0.0889)
		(layer "In2.Cu")
		(net "M_I_CPU0_SB_DQ<5>")
	)
	(segment
		(start 418.018722 -288.829496)
		(end 419.782752 -289.560254)
		(width 0.14478)
		(layer "In2.Cu")
		(net "M_I_CPU0_SB_DQ<5>")
	)
	(segment
		(start 392.724386 -278.458676)
		(end 392.74496 -278.470614)
		(width 0.0889)
		(layer "In2.Cu")
		(net "M_I_CPU0_SB_DQ<5>")
	)
	(segment
		(start 393.29741 -278.388826)
		(end 393.754356 -278.388826)
		(width 0.0889)
		(layer "In2.Cu")
		(net "M_I_CPU0_SB_DQ<5>")
	)
	(segment
		(start 412.37281 -289.560254)
		(end 412.971742 -289.441128)
		(width 0.14478)
		(layer "In2.Cu")
		(net "M_I_CPU0_SB_DQ<5>")
	)
	(segment
		(start 392.137138 -278.471884)
		(end 392.160506 -278.458422)
		(width 0.0889)
		(layer "In2.Cu")
		(net "M_I_CPU0_SB_DQ<5>")
	)
	(segment
		(start 375.99493 -278.136096)
		(end 376.148854 -278.401526)
		(width 0.0889)
		(layer "In2.Cu")
		(net "M_I_CPU0_SB_DQ<5>")
	)
	(segment
		(start 381.447802 -278.458676)
		(end 381.456184 -278.463502)
		(width 0.0889)
		(layer "In2.Cu")
		(net "M_I_CPU0_SB_DQ<5>")
	)
	(segment
		(start 388.393432 -278.463502)
		(end 388.401814 -278.458676)
		(width 0.0889)
		(layer "In2.Cu")
		(net "M_I_CPU0_SB_DQ<5>")
	)
	(segment
		(start 423.454576 -288.71037)
		(end 431.131472 -288.71037)
		(width 0.14478)
		(layer "In2.Cu")
		(net "M_I_CPU0_SB_DQ<5>")
	)
	(segment
		(start 395.6939 -277.600156)
		(end 399.058892 -277.600156)
		(width 0.14478)
		(layer "In2.Cu")
		(net "M_I_CPU0_SB_DQ<5>")
	)
	(segment
		(start 415.885884 -288.71037)
		(end 417.420044 -288.71037)
		(width 0.14478)
		(layer "In2.Cu")
		(net "M_I_CPU0_SB_DQ<5>")
	)
	(segment
		(start 419.782752 -289.560254)
		(end 420.062152 -289.560254)
		(width 0.14478)
		(layer "In2.Cu")
		(net "M_I_CPU0_SB_DQ<5>")
	)
	(segment
		(start 412.971742 -289.441128)
		(end 415.885884 -288.71037)
		(width 0.14478)
		(layer "In2.Cu")
		(net "M_I_CPU0_SB_DQ<5>")
	)
	(segment
		(start 395.597634 -277.50389)
		(end 395.6939 -277.600156)
		(width 0.0889)
		(layer "In2.Cu")
		(net "M_I_CPU0_SB_DQ<5>")
	)
	(segment
		(start 394.639292 -277.50389)
		(end 395.597634 -277.50389)
		(width 0.0889)
		(layer "In2.Cu")
		(net "M_I_CPU0_SB_DQ<5>")
	)
	(segment
		(start 389.333486 -278.463502)
		(end 389.341868 -278.458676)
		(width 0.0889)
		(layer "In2.Cu")
		(net "M_I_CPU0_SB_DQ<5>")
	)
	(segment
		(start 379.933454 -278.463502)
		(end 379.941836 -278.458676)
		(width 0.0889)
		(layer "In2.Cu")
		(net "M_I_CPU0_SB_DQ<5>")
	)
	(segment
		(start 393.099798 -278.458676)
		(end 393.100052 -278.45893)
		(width 0.0889)
		(layer "In2.Cu")
		(net "M_I_CPU0_SB_DQ<5>")
	)
	(segment
		(start 376.148854 -278.401526)
		(end 376.244866 -278.426926)
		(width 0.0889)
		(layer "In2.Cu")
		(net "M_I_CPU0_SB_DQ<5>")
	)
	(segment
		(start 383.693416 -278.463502)
		(end 383.701798 -278.458676)
		(width 0.0889)
		(layer "In2.Cu")
		(net "M_I_CPU0_SB_DQ<5>")
	)
	(arc
		(start 387.087872 -278.458676)
		(mid 387.274816 -278.508931)
		(end 387.46176 -278.458676)
		(width 0.0889)
		(layer "In2.Cu")
		(net "M_I_CPU0_SB_DQ<5>")
	)
	(arc
		(start 380.88189 -278.458676)
		(mid 381.164846 -278.382499)
		(end 381.447802 -278.458676)
		(width 0.0889)
		(layer "In2.Cu")
		(net "M_I_CPU0_SB_DQ<5>")
	)
	(arc
		(start 380.507748 -278.458676)
		(mid 380.689999 -278.509026)
		(end 380.873508 -278.463502)
		(width 0.0889)
		(layer "In2.Cu")
		(net "M_I_CPU0_SB_DQ<5>")
	)
	(arc
		(start 379.567694 -278.458676)
		(mid 379.749945 -278.509026)
		(end 379.933454 -278.463502)
		(width 0.0889)
		(layer "In2.Cu")
		(net "M_I_CPU0_SB_DQ<5>")
	)
	(arc
		(start 390.847834 -278.458676)
		(mid 391.034778 -278.508931)
		(end 391.221722 -278.458676)
		(width 0.0889)
		(layer "In2.Cu")
		(net "M_I_CPU0_SB_DQ<5>")
	)
	(arc
		(start 384.26771 -278.458676)
		(mid 384.449961 -278.509026)
		(end 384.63347 -278.463502)
		(width 0.0889)
		(layer "In2.Cu")
		(net "M_I_CPU0_SB_DQ<5>")
	)
	(arc
		(start 382.387856 -278.458676)
		(mid 382.5748 -278.508931)
		(end 382.761744 -278.458676)
		(width 0.0889)
		(layer "In2.Cu")
		(net "M_I_CPU0_SB_DQ<5>")
	)
	(arc
		(start 376.244866 -278.426926)
		(mid 376.500074 -278.383449)
		(end 376.747786 -278.458676)
		(width 0.0889)
		(layer "In2.Cu")
		(net "M_I_CPU0_SB_DQ<5>")
	)
	(arc
		(start 383.701798 -278.458676)
		(mid 383.984754 -278.382499)
		(end 384.26771 -278.458676)
		(width 0.0889)
		(layer "In2.Cu")
		(net "M_I_CPU0_SB_DQ<5>")
	)
	(arc
		(start 392.186668 -278.443436)
		(mid 392.457454 -278.38279)
		(end 392.724386 -278.458676)
		(width 0.0889)
		(layer "In2.Cu")
		(net "M_I_CPU0_SB_DQ<5>")
	)
	(arc
		(start 386.1562 -278.463502)
		(mid 386.339708 -278.508996)
		(end 386.52196 -278.458676)
		(width 0.0889)
		(layer "In2.Cu")
		(net "M_I_CPU0_SB_DQ<5>")
	)
	(arc
		(start 377.121928 -278.458676)
		(mid 377.404884 -278.382499)
		(end 377.68784 -278.458676)
		(width 0.0889)
		(layer "In2.Cu")
		(net "M_I_CPU0_SB_DQ<5>")
	)
	(arc
		(start 388.027672 -278.458676)
		(mid 388.209923 -278.509026)
		(end 388.393432 -278.463502)
		(width 0.0889)
		(layer "In2.Cu")
		(net "M_I_CPU0_SB_DQ<5>")
	)
	(arc
		(start 386.52196 -278.458676)
		(mid 386.804916 -278.382499)
		(end 387.087872 -278.458676)
		(width 0.0889)
		(layer "In2.Cu")
		(net "M_I_CPU0_SB_DQ<5>")
	)
	(arc
		(start 392.74496 -278.470614)
		(mid 392.923888 -278.509491)
		(end 393.099798 -278.458676)
		(width 0.0889)
		(layer "In2.Cu")
		(net "M_I_CPU0_SB_DQ<5>")
	)
	(arc
		(start 377.696222 -278.463502)
		(mid 377.87973 -278.508996)
		(end 378.061982 -278.458676)
		(width 0.0889)
		(layer "In2.Cu")
		(net "M_I_CPU0_SB_DQ<5>")
	)
	(arc
		(start 388.401814 -278.458676)
		(mid 388.68477 -278.382499)
		(end 388.967726 -278.458676)
		(width 0.0889)
		(layer "In2.Cu")
		(net "M_I_CPU0_SB_DQ<5>")
	)
	(arc
		(start 382.761744 -278.458676)
		(mid 383.0447 -278.382499)
		(end 383.327656 -278.458676)
		(width 0.0889)
		(layer "In2.Cu")
		(net "M_I_CPU0_SB_DQ<5>")
	)
	(arc
		(start 381.821944 -278.458676)
		(mid 382.1049 -278.382499)
		(end 382.387856 -278.458676)
		(width 0.0889)
		(layer "In2.Cu")
		(net "M_I_CPU0_SB_DQ<5>")
	)
	(arc
		(start 378.627894 -278.458676)
		(mid 378.814838 -278.508931)
		(end 379.001782 -278.458676)
		(width 0.0889)
		(layer "In2.Cu")
		(net "M_I_CPU0_SB_DQ<5>")
	)
	(arc
		(start 379.941836 -278.458676)
		(mid 380.224792 -278.382499)
		(end 380.507748 -278.458676)
		(width 0.0889)
		(layer "In2.Cu")
		(net "M_I_CPU0_SB_DQ<5>")
	)
	(arc
		(start 393.100052 -278.45893)
		(mid 393.195452 -278.414648)
		(end 393.29741 -278.388826)
		(width 0.0889)
		(layer "In2.Cu")
		(net "M_I_CPU0_SB_DQ<5>")
	)
	(arc
		(start 385.216146 -278.463502)
		(mid 385.399654 -278.508996)
		(end 385.581906 -278.458676)
		(width 0.0889)
		(layer "In2.Cu")
		(net "M_I_CPU0_SB_DQ<5>")
	)
	(arc
		(start 389.341868 -278.458676)
		(mid 389.624824 -278.382499)
		(end 389.90778 -278.458676)
		(width 0.0889)
		(layer "In2.Cu")
		(net "M_I_CPU0_SB_DQ<5>")
	)
	(arc
		(start 385.581906 -278.458676)
		(mid 385.864862 -278.382499)
		(end 386.147818 -278.458676)
		(width 0.0889)
		(layer "In2.Cu")
		(net "M_I_CPU0_SB_DQ<5>")
	)
	(arc
		(start 379.001782 -278.458676)
		(mid 379.284738 -278.382499)
		(end 379.567694 -278.458676)
		(width 0.0889)
		(layer "In2.Cu")
		(net "M_I_CPU0_SB_DQ<5>")
	)
	(arc
		(start 390.281922 -278.458676)
		(mid 390.564878 -278.382499)
		(end 390.847834 -278.458676)
		(width 0.0889)
		(layer "In2.Cu")
		(net "M_I_CPU0_SB_DQ<5>")
	)
	(arc
		(start 376.756168 -278.463502)
		(mid 376.939676 -278.508996)
		(end 377.121928 -278.458676)
		(width 0.0889)
		(layer "In2.Cu")
		(net "M_I_CPU0_SB_DQ<5>")
	)
	(arc
		(start 381.456184 -278.463502)
		(mid 381.639692 -278.508996)
		(end 381.821944 -278.458676)
		(width 0.0889)
		(layer "In2.Cu")
		(net "M_I_CPU0_SB_DQ<5>")
	)
	(arc
		(start 384.641852 -278.458676)
		(mid 384.924808 -278.382499)
		(end 385.207764 -278.458676)
		(width 0.0889)
		(layer "In2.Cu")
		(net "M_I_CPU0_SB_DQ<5>")
	)
	(arc
		(start 383.327656 -278.458676)
		(mid 383.509907 -278.509026)
		(end 383.693416 -278.463502)
		(width 0.0889)
		(layer "In2.Cu")
		(net "M_I_CPU0_SB_DQ<5>")
	)
	(arc
		(start 391.221722 -278.458676)
		(mid 391.504678 -278.382499)
		(end 391.787634 -278.458676)
		(width 0.0889)
		(layer "In2.Cu")
		(net "M_I_CPU0_SB_DQ<5>")
	)
	(arc
		(start 387.46176 -278.458676)
		(mid 387.744716 -278.382499)
		(end 388.027672 -278.458676)
		(width 0.0889)
		(layer "In2.Cu")
		(net "M_I_CPU0_SB_DQ<5>")
	)
	(arc
		(start 388.967726 -278.458676)
		(mid 389.149977 -278.509026)
		(end 389.333486 -278.463502)
		(width 0.0889)
		(layer "In2.Cu")
		(net "M_I_CPU0_SB_DQ<5>")
	)
	(arc
		(start 378.061982 -278.458676)
		(mid 378.344938 -278.382499)
		(end 378.627894 -278.458676)
		(width 0.0889)
		(layer "In2.Cu")
		(net "M_I_CPU0_SB_DQ<5>")
	)
	(arc
		(start 391.787634 -278.458676)
		(mid 391.960742 -278.508792)
		(end 392.137138 -278.471884)
		(width 0.0889)
		(layer "In2.Cu")
		(net "M_I_CPU0_SB_DQ<5>")
	)
	(arc
		(start 389.916162 -278.463502)
		(mid 390.09967 -278.508996)
		(end 390.281922 -278.458676)
		(width 0.0889)
		(layer "In2.Cu")
		(net "M_I_CPU0_SB_DQ<5>")
	)
	(segment
		(start 376.938032 -277.060152)
		(end 377.404884 -277.32609)
		(width 0.10668)
		(layer "F.Cu")
		(net "M_I_CPU0_SB_DQ<4>")
	)
	(segment
		(start 380.04623 -277.653496)
		(end 380.037848 -277.64867)
		(width 0.0889)
		(layer "In2.Cu")
		(net "M_I_CPU0_SB_DQ<4>")
	)
	(segment
		(start 421.406066 -287.869884)
		(end 418.59835 -287.869884)
		(width 0.14478)
		(layer "In2.Cu")
		(net "M_I_CPU0_SB_DQ<4>")
	)
	(segment
		(start 392.269472 -277.655528)
		(end 392.257788 -277.64867)
		(width 0.0889)
		(layer "In2.Cu")
		(net "M_I_CPU0_SB_DQ<4>")
	)
	(segment
		(start 391.326116 -277.653496)
		(end 391.317734 -277.64867)
		(width 0.0889)
		(layer "In2.Cu")
		(net "M_I_CPU0_SB_DQ<4>")
	)
	(segment
		(start 386.99186 -277.64867)
		(end 386.983478 -277.653496)
		(width 0.0889)
		(layer "In2.Cu")
		(net "M_I_CPU0_SB_DQ<4>")
	)
	(segment
		(start 382.866138 -277.653496)
		(end 382.857756 -277.64867)
		(width 0.0889)
		(layer "In2.Cu")
		(net "M_I_CPU0_SB_DQ<4>")
	)
	(segment
		(start 382.291844 -277.64867)
		(end 382.283462 -277.653496)
		(width 0.0889)
		(layer "In2.Cu")
		(net "M_I_CPU0_SB_DQ<4>")
	)
	(segment
		(start 390.751822 -277.64867)
		(end 390.74344 -277.653496)
		(width 0.0889)
		(layer "In2.Cu")
		(net "M_I_CPU0_SB_DQ<4>")
	)
	(segment
		(start 422.67886 -287.019746)
		(end 421.406066 -287.869884)
		(width 0.14478)
		(layer "In2.Cu")
		(net "M_I_CPU0_SB_DQ<4>")
	)
	(segment
		(start 379.106176 -277.653496)
		(end 379.097794 -277.64867)
		(width 0.0889)
		(layer "In2.Cu")
		(net "M_I_CPU0_SB_DQ<4>")
	)
	(segment
		(start 378.531882 -277.64867)
		(end 378.5235 -277.653496)
		(width 0.0889)
		(layer "In2.Cu")
		(net "M_I_CPU0_SB_DQ<4>")
	)
	(segment
		(start 377.558808 -277.59152)
		(end 377.404884 -277.32609)
		(width 0.0889)
		(layer "In2.Cu")
		(net "M_I_CPU0_SB_DQ<4>")
	)
	(segment
		(start 404.95601 -281.695906)
		(end 404.426674 -281.695906)
		(width 0.14478)
		(layer "In2.Cu")
		(net "M_I_CPU0_SB_DQ<4>")
	)
	(segment
		(start 413.825436 -287.869884)
		(end 411.129988 -287.869884)
		(width 0.14478)
		(layer "In2.Cu")
		(net "M_I_CPU0_SB_DQ<4>")
	)
	(segment
		(start 377.65482 -277.61692)
		(end 377.558808 -277.59152)
		(width 0.0889)
		(layer "In2.Cu")
		(net "M_I_CPU0_SB_DQ<4>")
	)
	(segment
		(start 387.566154 -277.653496)
		(end 387.557772 -277.64867)
		(width 0.0889)
		(layer "In2.Cu")
		(net "M_I_CPU0_SB_DQ<4>")
	)
	(segment
		(start 394.597128 -276.690836)
		(end 393.58824 -277.699724)
		(width 0.0889)
		(layer "In2.Cu")
		(net "M_I_CPU0_SB_DQ<4>")
	)
	(segment
		(start 388.506208 -277.653496)
		(end 388.497826 -277.64867)
		(width 0.0889)
		(layer "In2.Cu")
		(net "M_I_CPU0_SB_DQ<4>")
	)
	(segment
		(start 411.129988 -287.869884)
		(end 404.95601 -281.695906)
		(width 0.14478)
		(layer "In2.Cu")
		(net "M_I_CPU0_SB_DQ<4>")
	)
	(segment
		(start 399.421604 -276.690836)
		(end 395.971268 -276.690836)
		(width 0.14478)
		(layer "In2.Cu")
		(net "M_I_CPU0_SB_DQ<4>")
	)
	(segment
		(start 414.419034 -287.624012)
		(end 413.825436 -287.869884)
		(width 0.14478)
		(layer "In2.Cu")
		(net "M_I_CPU0_SB_DQ<4>")
	)
	(segment
		(start 404.426674 -281.695906)
		(end 399.421604 -276.690836)
		(width 0.14478)
		(layer "In2.Cu")
		(net "M_I_CPU0_SB_DQ<4>")
	)
	(segment
		(start 417.748212 -287.019746)
		(end 415.0233 -287.019746)
		(width 0.14478)
		(layer "In2.Cu")
		(net "M_I_CPU0_SB_DQ<4>")
	)
	(segment
		(start 395.971268 -276.690836)
		(end 394.597128 -276.690836)
		(width 0.0889)
		(layer "In2.Cu")
		(net "M_I_CPU0_SB_DQ<4>")
	)
	(segment
		(start 431.55616 -287.435036)
		(end 431.14087 -287.019746)
		(width 0.14478)
		(layer "In2.Cu")
		(net "M_I_CPU0_SB_DQ<4>")
	)
	(segment
		(start 383.806192 -277.653496)
		(end 383.79781 -277.64867)
		(width 0.0889)
		(layer "In2.Cu")
		(net "M_I_CPU0_SB_DQ<4>")
	)
	(segment
		(start 393.58824 -277.699724)
		(end 393.384786 -277.699724)
		(width 0.0889)
		(layer "In2.Cu")
		(net "M_I_CPU0_SB_DQ<4>")
	)
	(segment
		(start 386.051806 -277.64867)
		(end 386.043424 -277.653496)
		(width 0.0889)
		(layer "In2.Cu")
		(net "M_I_CPU0_SB_DQ<4>")
	)
	(segment
		(start 418.59835 -287.869884)
		(end 417.748212 -287.019746)
		(width 0.14478)
		(layer "In2.Cu")
		(net "M_I_CPU0_SB_DQ<4>")
	)
	(segment
		(start 415.0233 -287.019746)
		(end 414.419034 -287.624012)
		(width 0.14478)
		(layer "In2.Cu")
		(net "M_I_CPU0_SB_DQ<4>")
	)
	(segment
		(start 431.14087 -287.019746)
		(end 422.67886 -287.019746)
		(width 0.14478)
		(layer "In2.Cu")
		(net "M_I_CPU0_SB_DQ<4>")
	)
	(arc
		(start 383.79781 -277.64867)
		(mid 383.514854 -277.572493)
		(end 383.231898 -277.64867)
		(width 0.0889)
		(layer "In2.Cu")
		(net "M_I_CPU0_SB_DQ<4>")
	)
	(arc
		(start 382.857756 -277.64867)
		(mid 382.5748 -277.572493)
		(end 382.291844 -277.64867)
		(width 0.0889)
		(layer "In2.Cu")
		(net "M_I_CPU0_SB_DQ<4>")
	)
	(arc
		(start 387.557772 -277.64867)
		(mid 387.274816 -277.572493)
		(end 386.99186 -277.64867)
		(width 0.0889)
		(layer "In2.Cu")
		(net "M_I_CPU0_SB_DQ<4>")
	)
	(arc
		(start 384.737864 -277.64867)
		(mid 384.454908 -277.572493)
		(end 384.171952 -277.64867)
		(width 0.0889)
		(layer "In2.Cu")
		(net "M_I_CPU0_SB_DQ<4>")
	)
	(arc
		(start 393.182348 -277.639272)
		(mid 392.906039 -277.572296)
		(end 392.632184 -277.64867)
		(width 0.0889)
		(layer "In2.Cu")
		(net "M_I_CPU0_SB_DQ<4>")
	)
	(arc
		(start 386.617718 -277.64867)
		(mid 386.334762 -277.572493)
		(end 386.051806 -277.64867)
		(width 0.0889)
		(layer "In2.Cu")
		(net "M_I_CPU0_SB_DQ<4>")
	)
	(arc
		(start 381.35179 -277.64867)
		(mid 381.164846 -277.698925)
		(end 380.977902 -277.64867)
		(width 0.0889)
		(layer "In2.Cu")
		(net "M_I_CPU0_SB_DQ<4>")
	)
	(arc
		(start 385.111752 -277.64867)
		(mid 384.924808 -277.698925)
		(end 384.737864 -277.64867)
		(width 0.0889)
		(layer "In2.Cu")
		(net "M_I_CPU0_SB_DQ<4>")
	)
	(arc
		(start 381.917702 -277.64867)
		(mid 381.634746 -277.572493)
		(end 381.35179 -277.64867)
		(width 0.0889)
		(layer "In2.Cu")
		(net "M_I_CPU0_SB_DQ<4>")
	)
	(arc
		(start 386.043424 -277.653496)
		(mid 385.859916 -277.69899)
		(end 385.677664 -277.64867)
		(width 0.0889)
		(layer "In2.Cu")
		(net "M_I_CPU0_SB_DQ<4>")
	)
	(arc
		(start 384.171952 -277.64867)
		(mid 383.989701 -277.69902)
		(end 383.806192 -277.653496)
		(width 0.0889)
		(layer "In2.Cu")
		(net "M_I_CPU0_SB_DQ<4>")
	)
	(arc
		(start 388.871968 -277.64867)
		(mid 388.689717 -277.69902)
		(end 388.506208 -277.653496)
		(width 0.0889)
		(layer "In2.Cu")
		(net "M_I_CPU0_SB_DQ<4>")
	)
	(arc
		(start 382.283462 -277.653496)
		(mid 382.099954 -277.69899)
		(end 381.917702 -277.64867)
		(width 0.0889)
		(layer "In2.Cu")
		(net "M_I_CPU0_SB_DQ<4>")
	)
	(arc
		(start 378.5235 -277.653496)
		(mid 378.339992 -277.69899)
		(end 378.15774 -277.64867)
		(width 0.0889)
		(layer "In2.Cu")
		(net "M_I_CPU0_SB_DQ<4>")
	)
	(arc
		(start 389.811768 -277.64867)
		(mid 389.624824 -277.698925)
		(end 389.43788 -277.64867)
		(width 0.0889)
		(layer "In2.Cu")
		(net "M_I_CPU0_SB_DQ<4>")
	)
	(arc
		(start 383.231898 -277.64867)
		(mid 383.049647 -277.69902)
		(end 382.866138 -277.653496)
		(width 0.0889)
		(layer "In2.Cu")
		(net "M_I_CPU0_SB_DQ<4>")
	)
	(arc
		(start 391.691876 -277.64867)
		(mid 391.509625 -277.69902)
		(end 391.326116 -277.653496)
		(width 0.0889)
		(layer "In2.Cu")
		(net "M_I_CPU0_SB_DQ<4>")
	)
	(arc
		(start 379.471936 -277.64867)
		(mid 379.289685 -277.69902)
		(end 379.106176 -277.653496)
		(width 0.0889)
		(layer "In2.Cu")
		(net "M_I_CPU0_SB_DQ<4>")
	)
	(arc
		(start 389.43788 -277.64867)
		(mid 389.154924 -277.572493)
		(end 388.871968 -277.64867)
		(width 0.0889)
		(layer "In2.Cu")
		(net "M_I_CPU0_SB_DQ<4>")
	)
	(arc
		(start 380.41199 -277.64867)
		(mid 380.229739 -277.69902)
		(end 380.04623 -277.653496)
		(width 0.0889)
		(layer "In2.Cu")
		(net "M_I_CPU0_SB_DQ<4>")
	)
	(arc
		(start 379.097794 -277.64867)
		(mid 378.814838 -277.572493)
		(end 378.531882 -277.64867)
		(width 0.0889)
		(layer "In2.Cu")
		(net "M_I_CPU0_SB_DQ<4>")
	)
	(arc
		(start 391.317734 -277.64867)
		(mid 391.034778 -277.572493)
		(end 390.751822 -277.64867)
		(width 0.0889)
		(layer "In2.Cu")
		(net "M_I_CPU0_SB_DQ<4>")
	)
	(arc
		(start 385.677664 -277.64867)
		(mid 385.394708 -277.572493)
		(end 385.111752 -277.64867)
		(width 0.0889)
		(layer "In2.Cu")
		(net "M_I_CPU0_SB_DQ<4>")
	)
	(arc
		(start 393.384786 -277.699724)
		(mid 393.279204 -277.684111)
		(end 393.182348 -277.639272)
		(width 0.0889)
		(layer "In2.Cu")
		(net "M_I_CPU0_SB_DQ<4>")
	)
	(arc
		(start 392.257788 -277.64867)
		(mid 391.974832 -277.572493)
		(end 391.691876 -277.64867)
		(width 0.0889)
		(layer "In2.Cu")
		(net "M_I_CPU0_SB_DQ<4>")
	)
	(arc
		(start 380.037848 -277.64867)
		(mid 379.754892 -277.572493)
		(end 379.471936 -277.64867)
		(width 0.0889)
		(layer "In2.Cu")
		(net "M_I_CPU0_SB_DQ<4>")
	)
	(arc
		(start 390.74344 -277.653496)
		(mid 390.559932 -277.69899)
		(end 390.37768 -277.64867)
		(width 0.0889)
		(layer "In2.Cu")
		(net "M_I_CPU0_SB_DQ<4>")
	)
	(arc
		(start 390.37768 -277.64867)
		(mid 390.094724 -277.572493)
		(end 389.811768 -277.64867)
		(width 0.0889)
		(layer "In2.Cu")
		(net "M_I_CPU0_SB_DQ<4>")
	)
	(arc
		(start 387.931914 -277.64867)
		(mid 387.749663 -277.69902)
		(end 387.566154 -277.653496)
		(width 0.0889)
		(layer "In2.Cu")
		(net "M_I_CPU0_SB_DQ<4>")
	)
	(arc
		(start 378.15774 -277.64867)
		(mid 377.910027 -277.57345)
		(end 377.65482 -277.61692)
		(width 0.0889)
		(layer "In2.Cu")
		(net "M_I_CPU0_SB_DQ<4>")
	)
	(arc
		(start 380.977902 -277.64867)
		(mid 380.694946 -277.572493)
		(end 380.41199 -277.64867)
		(width 0.0889)
		(layer "In2.Cu")
		(net "M_I_CPU0_SB_DQ<4>")
	)
	(arc
		(start 386.983478 -277.653496)
		(mid 386.79997 -277.69899)
		(end 386.617718 -277.64867)
		(width 0.0889)
		(layer "In2.Cu")
		(net "M_I_CPU0_SB_DQ<4>")
	)
	(arc
		(start 392.632184 -277.64867)
		(mid 392.451726 -277.699114)
		(end 392.269472 -277.655528)
		(width 0.0889)
		(layer "In2.Cu")
		(net "M_I_CPU0_SB_DQ<4>")
	)
	(arc
		(start 388.497826 -277.64867)
		(mid 388.21487 -277.572493)
		(end 387.931914 -277.64867)
		(width 0.0889)
		(layer "In2.Cu")
		(net "M_I_CPU0_SB_DQ<4>")
	)
	(segment
		(start 375.997978 -275.44014)
		(end 376.46483 -275.706078)
		(width 0.10668)
		(layer "F.Cu")
		(net "M_I_CPU0_SB_DQ<3>")
	)
	(segment
		(start 393.755118 -275.080476)
		(end 394.129006 -274.903438)
		(width 0.0889)
		(layer "In2.Cu")
		(net "M_I_CPU0_SB_DQ<3>")
	)
	(segment
		(start 386.983478 -275.378672)
		(end 386.99186 -275.383498)
		(width 0.0889)
		(layer "In2.Cu")
		(net "M_I_CPU0_SB_DQ<3>")
	)
	(segment
		(start 409.343352 -282.237434)
		(end 411.5562 -284.450282)
		(width 0.14478)
		(layer "In2.Cu")
		(net "M_I_CPU0_SB_DQ<3>")
	)
	(segment
		(start 418.927788 -284.450282)
		(end 420.826692 -284.450282)
		(width 0.14478)
		(layer "In2.Cu")
		(net "M_I_CPU0_SB_DQ<3>")
	)
	(segment
		(start 406.985216 -280.487882)
		(end 407.213816 -280.487882)
		(width 0.14478)
		(layer "In2.Cu")
		(net "M_I_CPU0_SB_DQ<3>")
	)
	(segment
		(start 377.583446 -275.378672)
		(end 377.591828 -275.383498)
		(width 0.0889)
		(layer "In2.Cu")
		(net "M_I_CPU0_SB_DQ<3>")
	)
	(segment
		(start 415.600388 -283.600398)
		(end 418.077904 -283.600398)
		(width 0.14478)
		(layer "In2.Cu")
		(net "M_I_CPU0_SB_DQ<3>")
	)
	(segment
		(start 425.866306 -283.67863)
		(end 426.013626 -283.82595)
		(width 0.14478)
		(layer "In2.Cu")
		(net "M_I_CPU0_SB_DQ<3>")
	)
	(segment
		(start 395.382242 -274.25777)
		(end 395.427962 -274.30349)
		(width 0.0889)
		(layer "In2.Cu")
		(net "M_I_CPU0_SB_DQ<3>")
	)
	(segment
		(start 427.03115 -283.61005)
		(end 427.456092 -284.034992)
		(width 0.14478)
		(layer "In2.Cu")
		(net "M_I_CPU0_SB_DQ<3>")
	)
	(segment
		(start 388.497826 -275.383498)
		(end 388.506208 -275.378672)
		(width 0.0889)
		(layer "In2.Cu")
		(net "M_I_CPU0_SB_DQ<3>")
	)
	(segment
		(start 390.74344 -275.378672)
		(end 390.751822 -275.383498)
		(width 0.0889)
		(layer "In2.Cu")
		(net "M_I_CPU0_SB_DQ<3>")
	)
	(segment
		(start 394.129006 -274.903438)
		(end 394.774674 -274.25777)
		(width 0.0889)
		(layer "In2.Cu")
		(net "M_I_CPU0_SB_DQ<3>")
	)
	(segment
		(start 411.5562 -284.450282)
		(end 413.15259 -284.450282)
		(width 0.14478)
		(layer "In2.Cu")
		(net "M_I_CPU0_SB_DQ<3>")
	)
	(segment
		(start 413.694626 -284.225746)
		(end 413.951928 -284.33268)
		(width 0.14478)
		(layer "In2.Cu")
		(net "M_I_CPU0_SB_DQ<3>")
	)
	(segment
		(start 407.994104 -281.26817)
		(end 408.17292 -281.089354)
		(width 0.14478)
		(layer "In2.Cu")
		(net "M_I_CPU0_SB_DQ<3>")
	)
	(segment
		(start 407.213816 -280.487882)
		(end 407.392632 -280.309066)
		(width 0.14478)
		(layer "In2.Cu")
		(net "M_I_CPU0_SB_DQ<3>")
	)
	(segment
		(start 408.17292 -281.089354)
		(end 408.40152 -281.089354)
		(width 0.14478)
		(layer "In2.Cu")
		(net "M_I_CPU0_SB_DQ<3>")
	)
	(segment
		(start 407.392632 -280.309066)
		(end 407.621232 -280.309066)
		(width 0.14478)
		(layer "In2.Cu")
		(net "M_I_CPU0_SB_DQ<3>")
	)
	(segment
		(start 408.563064 -281.479498)
		(end 408.384248 -281.658314)
		(width 0.14478)
		(layer "In2.Cu")
		(net "M_I_CPU0_SB_DQ<3>")
	)
	(segment
		(start 395.427962 -274.30349)
		(end 396.018766 -274.30349)
		(width 0.0889)
		(layer "In2.Cu")
		(net "M_I_CPU0_SB_DQ<3>")
	)
	(segment
		(start 408.545792 -282.048458)
		(end 408.774392 -282.048458)
		(width 0.14478)
		(layer "In2.Cu")
		(net "M_I_CPU0_SB_DQ<3>")
	)
	(segment
		(start 407.002488 -279.918922)
		(end 406.823672 -280.097738)
		(width 0.14478)
		(layer "In2.Cu")
		(net "M_I_CPU0_SB_DQ<3>")
	)
	(segment
		(start 387.557772 -275.383498)
		(end 387.566154 -275.378672)
		(width 0.0889)
		(layer "In2.Cu")
		(net "M_I_CPU0_SB_DQ<3>")
	)
	(segment
		(start 376.310906 -275.440648)
		(end 376.333258 -275.357336)
		(width 0.0889)
		(layer "In2.Cu")
		(net "M_I_CPU0_SB_DQ<3>")
	)
	(segment
		(start 425.866306 -283.46273)
		(end 425.866306 -283.67863)
		(width 0.14478)
		(layer "In2.Cu")
		(net "M_I_CPU0_SB_DQ<3>")
	)
	(segment
		(start 400.800824 -274.30349)
		(end 406.204928 -279.707594)
		(width 0.14478)
		(layer "In2.Cu")
		(net "M_I_CPU0_SB_DQ<3>")
	)
	(segment
		(start 425.169838 -283.600398)
		(end 425.454826 -283.31541)
		(width 0.14478)
		(layer "In2.Cu")
		(net "M_I_CPU0_SB_DQ<3>")
	)
	(segment
		(start 414.39211 -283.824934)
		(end 415.297366 -283.45003)
		(width 0.14478)
		(layer "In2.Cu")
		(net "M_I_CPU0_SB_DQ<3>")
	)
	(segment
		(start 407.60396 -281.106626)
		(end 407.765504 -281.26817)
		(width 0.14478)
		(layer "In2.Cu")
		(net "M_I_CPU0_SB_DQ<3>")
	)
	(segment
		(start 425.454826 -283.31541)
		(end 425.718986 -283.31541)
		(width 0.14478)
		(layer "In2.Cu")
		(net "M_I_CPU0_SB_DQ<3>")
	)
	(segment
		(start 407.621232 -280.309066)
		(end 407.782776 -280.47061)
		(width 0.14478)
		(layer "In2.Cu")
		(net "M_I_CPU0_SB_DQ<3>")
	)
	(segment
		(start 406.823672 -280.097738)
		(end 406.823672 -280.326338)
		(width 0.14478)
		(layer "In2.Cu")
		(net "M_I_CPU0_SB_DQ<3>")
	)
	(segment
		(start 407.60396 -280.878026)
		(end 407.60396 -281.106626)
		(width 0.14478)
		(layer "In2.Cu")
		(net "M_I_CPU0_SB_DQ<3>")
	)
	(segment
		(start 376.46483 -275.706078)
		(end 376.310906 -275.440648)
		(width 0.0889)
		(layer "In2.Cu")
		(net "M_I_CPU0_SB_DQ<3>")
	)
	(segment
		(start 408.384248 -281.658314)
		(end 408.384248 -281.886914)
		(width 0.14478)
		(layer "In2.Cu")
		(net "M_I_CPU0_SB_DQ<3>")
	)
	(segment
		(start 409.181808 -281.869642)
		(end 409.343352 -282.031186)
		(width 0.14478)
		(layer "In2.Cu")
		(net "M_I_CPU0_SB_DQ<3>")
	)
	(segment
		(start 386.043424 -275.378672)
		(end 386.051806 -275.383498)
		(width 0.0889)
		(layer "In2.Cu")
		(net "M_I_CPU0_SB_DQ<3>")
	)
	(segment
		(start 413.15259 -284.450282)
		(end 413.694626 -284.225746)
		(width 0.14478)
		(layer "In2.Cu")
		(net "M_I_CPU0_SB_DQ<3>")
	)
	(segment
		(start 408.563064 -281.250898)
		(end 408.563064 -281.479498)
		(width 0.14478)
		(layer "In2.Cu")
		(net "M_I_CPU0_SB_DQ<3>")
	)
	(segment
		(start 413.951928 -284.33268)
		(end 414.22955 -284.217618)
		(width 0.14478)
		(layer "In2.Cu")
		(net "M_I_CPU0_SB_DQ<3>")
	)
	(segment
		(start 409.343352 -282.031186)
		(end 409.343352 -282.237434)
		(width 0.14478)
		(layer "In2.Cu")
		(net "M_I_CPU0_SB_DQ<3>")
	)
	(segment
		(start 408.953208 -281.869642)
		(end 409.181808 -281.869642)
		(width 0.14478)
		(layer "In2.Cu")
		(net "M_I_CPU0_SB_DQ<3>")
	)
	(segment
		(start 379.097794 -275.383498)
		(end 379.106176 -275.378672)
		(width 0.0889)
		(layer "In2.Cu")
		(net "M_I_CPU0_SB_DQ<3>")
	)
	(segment
		(start 382.857756 -275.383498)
		(end 382.866138 -275.378672)
		(width 0.0889)
		(layer "In2.Cu")
		(net "M_I_CPU0_SB_DQ<3>")
	)
	(segment
		(start 414.22955 -284.217618)
		(end 414.39211 -283.824934)
		(width 0.14478)
		(layer "In2.Cu")
		(net "M_I_CPU0_SB_DQ<3>")
	)
	(segment
		(start 415.297366 -283.45003)
		(end 415.45002 -283.45003)
		(width 0.14478)
		(layer "In2.Cu")
		(net "M_I_CPU0_SB_DQ<3>")
	)
	(segment
		(start 426.572426 -283.61005)
		(end 427.03115 -283.61005)
		(width 0.14478)
		(layer "In2.Cu")
		(net "M_I_CPU0_SB_DQ<3>")
	)
	(segment
		(start 378.5235 -275.378672)
		(end 378.531882 -275.383498)
		(width 0.0889)
		(layer "In2.Cu")
		(net "M_I_CPU0_SB_DQ<3>")
	)
	(segment
		(start 392.229594 -275.398738)
		(end 392.255756 -275.383752)
		(width 0.0889)
		(layer "In2.Cu")
		(net "M_I_CPU0_SB_DQ<3>")
	)
	(segment
		(start 418.077904 -283.600398)
		(end 418.927788 -284.450282)
		(width 0.14478)
		(layer "In2.Cu")
		(net "M_I_CPU0_SB_DQ<3>")
	)
	(segment
		(start 407.782776 -280.69921)
		(end 407.60396 -280.878026)
		(width 0.14478)
		(layer "In2.Cu")
		(net "M_I_CPU0_SB_DQ<3>")
	)
	(segment
		(start 406.612344 -279.528778)
		(end 406.840944 -279.528778)
		(width 0.14478)
		(layer "In2.Cu")
		(net "M_I_CPU0_SB_DQ<3>")
	)
	(segment
		(start 407.782776 -280.47061)
		(end 407.782776 -280.69921)
		(width 0.14478)
		(layer "In2.Cu")
		(net "M_I_CPU0_SB_DQ<3>")
	)
	(segment
		(start 406.204928 -279.707594)
		(end 406.433528 -279.707594)
		(width 0.14478)
		(layer "In2.Cu")
		(net "M_I_CPU0_SB_DQ<3>")
	)
	(segment
		(start 426.356526 -283.82595)
		(end 426.572426 -283.61005)
		(width 0.14478)
		(layer "In2.Cu")
		(net "M_I_CPU0_SB_DQ<3>")
	)
	(segment
		(start 392.628374 -275.383498)
		(end 392.657838 -275.40077)
		(width 0.0889)
		(layer "In2.Cu")
		(net "M_I_CPU0_SB_DQ<3>")
	)
	(segment
		(start 425.718986 -283.31541)
		(end 425.866306 -283.46273)
		(width 0.14478)
		(layer "In2.Cu")
		(net "M_I_CPU0_SB_DQ<3>")
	)
	(segment
		(start 380.037848 -275.383498)
		(end 380.04623 -275.378672)
		(width 0.0889)
		(layer "In2.Cu")
		(net "M_I_CPU0_SB_DQ<3>")
	)
	(segment
		(start 407.002488 -279.690322)
		(end 407.002488 -279.918922)
		(width 0.14478)
		(layer "In2.Cu")
		(net "M_I_CPU0_SB_DQ<3>")
	)
	(segment
		(start 415.45002 -283.45003)
		(end 415.600388 -283.600398)
		(width 0.14478)
		(layer "In2.Cu")
		(net "M_I_CPU0_SB_DQ<3>")
	)
	(segment
		(start 394.774674 -274.25777)
		(end 395.382242 -274.25777)
		(width 0.0889)
		(layer "In2.Cu")
		(net "M_I_CPU0_SB_DQ<3>")
	)
	(segment
		(start 393.196318 -275.383498)
		(end 393.755118 -275.080476)
		(width 0.0889)
		(layer "In2.Cu")
		(net "M_I_CPU0_SB_DQ<3>")
	)
	(segment
		(start 408.774392 -282.048458)
		(end 408.953208 -281.869642)
		(width 0.14478)
		(layer "In2.Cu")
		(net "M_I_CPU0_SB_DQ<3>")
	)
	(segment
		(start 383.79781 -275.383498)
		(end 383.806192 -275.378672)
		(width 0.0889)
		(layer "In2.Cu")
		(net "M_I_CPU0_SB_DQ<3>")
	)
	(segment
		(start 420.826692 -284.450282)
		(end 422.415462 -283.600398)
		(width 0.14478)
		(layer "In2.Cu")
		(net "M_I_CPU0_SB_DQ<3>")
	)
	(segment
		(start 408.384248 -281.886914)
		(end 408.545792 -282.048458)
		(width 0.14478)
		(layer "In2.Cu")
		(net "M_I_CPU0_SB_DQ<3>")
	)
	(segment
		(start 382.283462 -275.378672)
		(end 382.291844 -275.383498)
		(width 0.0889)
		(layer "In2.Cu")
		(net "M_I_CPU0_SB_DQ<3>")
	)
	(segment
		(start 406.433528 -279.707594)
		(end 406.612344 -279.528778)
		(width 0.14478)
		(layer "In2.Cu")
		(net "M_I_CPU0_SB_DQ<3>")
	)
	(segment
		(start 407.765504 -281.26817)
		(end 407.994104 -281.26817)
		(width 0.14478)
		(layer "In2.Cu")
		(net "M_I_CPU0_SB_DQ<3>")
	)
	(segment
		(start 396.018766 -274.30349)
		(end 400.800824 -274.30349)
		(width 0.14478)
		(layer "In2.Cu")
		(net "M_I_CPU0_SB_DQ<3>")
	)
	(segment
		(start 392.255756 -275.383752)
		(end 392.2776 -275.371306)
		(width 0.0889)
		(layer "In2.Cu")
		(net "M_I_CPU0_SB_DQ<3>")
	)
	(segment
		(start 406.823672 -280.326338)
		(end 406.985216 -280.487882)
		(width 0.14478)
		(layer "In2.Cu")
		(net "M_I_CPU0_SB_DQ<3>")
	)
	(segment
		(start 408.40152 -281.089354)
		(end 408.563064 -281.250898)
		(width 0.14478)
		(layer "In2.Cu")
		(net "M_I_CPU0_SB_DQ<3>")
	)
	(segment
		(start 406.840944 -279.528778)
		(end 407.002488 -279.690322)
		(width 0.14478)
		(layer "In2.Cu")
		(net "M_I_CPU0_SB_DQ<3>")
	)
	(segment
		(start 422.415462 -283.600398)
		(end 425.169838 -283.600398)
		(width 0.14478)
		(layer "In2.Cu")
		(net "M_I_CPU0_SB_DQ<3>")
	)
	(segment
		(start 391.317734 -275.383498)
		(end 391.326116 -275.378672)
		(width 0.0889)
		(layer "In2.Cu")
		(net "M_I_CPU0_SB_DQ<3>")
	)
	(segment
		(start 426.013626 -283.82595)
		(end 426.356526 -283.82595)
		(width 0.14478)
		(layer "In2.Cu")
		(net "M_I_CPU0_SB_DQ<3>")
	)
	(arc
		(start 376.333258 -275.357336)
		(mid 376.495447 -275.334601)
		(end 376.651774 -275.383498)
		(width 0.0889)
		(layer "In2.Cu")
		(net "M_I_CPU0_SB_DQ<3>")
	)
	(arc
		(start 386.99186 -275.383498)
		(mid 387.274816 -275.459675)
		(end 387.557772 -275.383498)
		(width 0.0889)
		(layer "In2.Cu")
		(net "M_I_CPU0_SB_DQ<3>")
	)
	(arc
		(start 384.171952 -275.383498)
		(mid 384.454908 -275.459675)
		(end 384.737864 -275.383498)
		(width 0.0889)
		(layer "In2.Cu")
		(net "M_I_CPU0_SB_DQ<3>")
	)
	(arc
		(start 386.617718 -275.383498)
		(mid 386.799969 -275.333148)
		(end 386.983478 -275.378672)
		(width 0.0889)
		(layer "In2.Cu")
		(net "M_I_CPU0_SB_DQ<3>")
	)
	(arc
		(start 388.506208 -275.378672)
		(mid 388.689716 -275.333178)
		(end 388.871968 -275.383498)
		(width 0.0889)
		(layer "In2.Cu")
		(net "M_I_CPU0_SB_DQ<3>")
	)
	(arc
		(start 387.566154 -275.378672)
		(mid 387.749662 -275.333178)
		(end 387.931914 -275.383498)
		(width 0.0889)
		(layer "In2.Cu")
		(net "M_I_CPU0_SB_DQ<3>")
	)
	(arc
		(start 380.04623 -275.378672)
		(mid 380.229738 -275.333178)
		(end 380.41199 -275.383498)
		(width 0.0889)
		(layer "In2.Cu")
		(net "M_I_CPU0_SB_DQ<3>")
	)
	(arc
		(start 382.866138 -275.378672)
		(mid 383.049646 -275.333178)
		(end 383.231898 -275.383498)
		(width 0.0889)
		(layer "In2.Cu")
		(net "M_I_CPU0_SB_DQ<3>")
	)
	(arc
		(start 382.291844 -275.383498)
		(mid 382.5748 -275.459675)
		(end 382.857756 -275.383498)
		(width 0.0889)
		(layer "In2.Cu")
		(net "M_I_CPU0_SB_DQ<3>")
	)
	(arc
		(start 389.811768 -275.383498)
		(mid 390.094724 -275.459675)
		(end 390.37768 -275.383498)
		(width 0.0889)
		(layer "In2.Cu")
		(net "M_I_CPU0_SB_DQ<3>")
	)
	(arc
		(start 389.43788 -275.383498)
		(mid 389.624824 -275.333243)
		(end 389.811768 -275.383498)
		(width 0.0889)
		(layer "In2.Cu")
		(net "M_I_CPU0_SB_DQ<3>")
	)
	(arc
		(start 381.917702 -275.383498)
		(mid 382.099953 -275.333148)
		(end 382.283462 -275.378672)
		(width 0.0889)
		(layer "In2.Cu")
		(net "M_I_CPU0_SB_DQ<3>")
	)
	(arc
		(start 380.977902 -275.383498)
		(mid 381.164846 -275.333243)
		(end 381.35179 -275.383498)
		(width 0.0889)
		(layer "In2.Cu")
		(net "M_I_CPU0_SB_DQ<3>")
	)
	(arc
		(start 385.111752 -275.383498)
		(mid 385.394708 -275.459675)
		(end 385.677664 -275.383498)
		(width 0.0889)
		(layer "In2.Cu")
		(net "M_I_CPU0_SB_DQ<3>")
	)
	(arc
		(start 383.806192 -275.378672)
		(mid 383.9897 -275.333178)
		(end 384.171952 -275.383498)
		(width 0.0889)
		(layer "In2.Cu")
		(net "M_I_CPU0_SB_DQ<3>")
	)
	(arc
		(start 381.35179 -275.383498)
		(mid 381.634746 -275.459675)
		(end 381.917702 -275.383498)
		(width 0.0889)
		(layer "In2.Cu")
		(net "M_I_CPU0_SB_DQ<3>")
	)
	(arc
		(start 391.326116 -275.378672)
		(mid 391.509624 -275.333178)
		(end 391.691876 -275.383498)
		(width 0.0889)
		(layer "In2.Cu")
		(net "M_I_CPU0_SB_DQ<3>")
	)
	(arc
		(start 384.737864 -275.383498)
		(mid 384.924808 -275.333243)
		(end 385.111752 -275.383498)
		(width 0.0889)
		(layer "In2.Cu")
		(net "M_I_CPU0_SB_DQ<3>")
	)
	(arc
		(start 377.217686 -275.383498)
		(mid 377.399937 -275.333148)
		(end 377.583446 -275.378672)
		(width 0.0889)
		(layer "In2.Cu")
		(net "M_I_CPU0_SB_DQ<3>")
	)
	(arc
		(start 392.657838 -275.40077)
		(mid 392.929258 -275.460447)
		(end 393.196318 -275.383498)
		(width 0.0889)
		(layer "In2.Cu")
		(net "M_I_CPU0_SB_DQ<3>")
	)
	(arc
		(start 390.751822 -275.383498)
		(mid 391.034778 -275.459675)
		(end 391.317734 -275.383498)
		(width 0.0889)
		(layer "In2.Cu")
		(net "M_I_CPU0_SB_DQ<3>")
	)
	(arc
		(start 376.651774 -275.383498)
		(mid 376.93473 -275.459675)
		(end 377.217686 -275.383498)
		(width 0.0889)
		(layer "In2.Cu")
		(net "M_I_CPU0_SB_DQ<3>")
	)
	(arc
		(start 383.231898 -275.383498)
		(mid 383.514854 -275.459675)
		(end 383.79781 -275.383498)
		(width 0.0889)
		(layer "In2.Cu")
		(net "M_I_CPU0_SB_DQ<3>")
	)
	(arc
		(start 379.471936 -275.383498)
		(mid 379.754892 -275.459675)
		(end 380.037848 -275.383498)
		(width 0.0889)
		(layer "In2.Cu")
		(net "M_I_CPU0_SB_DQ<3>")
	)
	(arc
		(start 386.051806 -275.383498)
		(mid 386.334762 -275.459675)
		(end 386.617718 -275.383498)
		(width 0.0889)
		(layer "In2.Cu")
		(net "M_I_CPU0_SB_DQ<3>")
	)
	(arc
		(start 392.2776 -275.371306)
		(mid 392.454528 -275.333478)
		(end 392.628374 -275.383498)
		(width 0.0889)
		(layer "In2.Cu")
		(net "M_I_CPU0_SB_DQ<3>")
	)
	(arc
		(start 390.37768 -275.383498)
		(mid 390.559931 -275.333148)
		(end 390.74344 -275.378672)
		(width 0.0889)
		(layer "In2.Cu")
		(net "M_I_CPU0_SB_DQ<3>")
	)
	(arc
		(start 387.931914 -275.383498)
		(mid 388.21487 -275.459675)
		(end 388.497826 -275.383498)
		(width 0.0889)
		(layer "In2.Cu")
		(net "M_I_CPU0_SB_DQ<3>")
	)
	(arc
		(start 388.871968 -275.383498)
		(mid 389.154924 -275.459675)
		(end 389.43788 -275.383498)
		(width 0.0889)
		(layer "In2.Cu")
		(net "M_I_CPU0_SB_DQ<3>")
	)
	(arc
		(start 380.41199 -275.383498)
		(mid 380.694946 -275.459675)
		(end 380.977902 -275.383498)
		(width 0.0889)
		(layer "In2.Cu")
		(net "M_I_CPU0_SB_DQ<3>")
	)
	(arc
		(start 378.15774 -275.383498)
		(mid 378.339991 -275.333148)
		(end 378.5235 -275.378672)
		(width 0.0889)
		(layer "In2.Cu")
		(net "M_I_CPU0_SB_DQ<3>")
	)
	(arc
		(start 385.677664 -275.383498)
		(mid 385.859915 -275.333148)
		(end 386.043424 -275.378672)
		(width 0.0889)
		(layer "In2.Cu")
		(net "M_I_CPU0_SB_DQ<3>")
	)
	(arc
		(start 379.106176 -275.378672)
		(mid 379.289684 -275.333178)
		(end 379.471936 -275.383498)
		(width 0.0889)
		(layer "In2.Cu")
		(net "M_I_CPU0_SB_DQ<3>")
	)
	(arc
		(start 377.591828 -275.383498)
		(mid 377.874784 -275.459675)
		(end 378.15774 -275.383498)
		(width 0.0889)
		(layer "In2.Cu")
		(net "M_I_CPU0_SB_DQ<3>")
	)
	(arc
		(start 378.531882 -275.383498)
		(mid 378.814838 -275.459675)
		(end 379.097794 -275.383498)
		(width 0.0889)
		(layer "In2.Cu")
		(net "M_I_CPU0_SB_DQ<3>")
	)
	(arc
		(start 391.691876 -275.383498)
		(mid 391.958806 -275.459447)
		(end 392.229594 -275.398738)
		(width 0.0889)
		(layer "In2.Cu")
		(net "M_I_CPU0_SB_DQ<3>")
	)
	(segment
		(start 375.997978 -293.260018)
		(end 376.46483 -293.525956)
		(width 0.10668)
		(layer "F.Cu")
		(net "M_I_CPU0_SB_DQ<31>")
	)
	(segment
		(start 382.283462 -293.19855)
		(end 382.291844 -293.203376)
		(width 0.0889)
		(layer "In2.Cu")
		(net "M_I_CPU0_SB_DQ<31>")
	)
	(segment
		(start 402.199094 -310.485028)
		(end 402.07819 -310.605678)
		(width 0.14478)
		(layer "In2.Cu")
		(net "M_I_CPU0_SB_DQ<31>")
	)
	(segment
		(start 401.297902 -309.82539)
		(end 401.297902 -310.053482)
		(width 0.14478)
		(layer "In2.Cu")
		(net "M_I_CPU0_SB_DQ<31>")
	)
	(segment
		(start 401.459954 -310.215534)
		(end 401.6883 -310.215534)
		(width 0.14478)
		(layer "In2.Cu")
		(net "M_I_CPU0_SB_DQ<31>")
	)
	(segment
		(start 378.5235 -293.19855)
		(end 378.531882 -293.203376)
		(width 0.0889)
		(layer "In2.Cu")
		(net "M_I_CPU0_SB_DQ<31>")
	)
	(segment
		(start 386.043424 -293.19855)
		(end 386.051806 -293.203376)
		(width 0.0889)
		(layer "In2.Cu")
		(net "M_I_CPU0_SB_DQ<31>")
	)
	(segment
		(start 402.81733 -310.875172)
		(end 402.979382 -311.037224)
		(width 0.14478)
		(layer "In2.Cu")
		(net "M_I_CPU0_SB_DQ<31>")
	)
	(segment
		(start 379.097794 -293.203376)
		(end 379.106176 -293.19855)
		(width 0.0889)
		(layer "In2.Cu")
		(net "M_I_CPU0_SB_DQ<31>")
	)
	(segment
		(start 404.029164 -312.556398)
		(end 404.149814 -312.435748)
		(width 0.14478)
		(layer "In2.Cu")
		(net "M_I_CPU0_SB_DQ<31>")
	)
	(segment
		(start 402.858478 -311.614058)
		(end 403.02053 -311.77611)
		(width 0.14478)
		(layer "In2.Cu")
		(net "M_I_CPU0_SB_DQ<31>")
	)
	(segment
		(start 382.857756 -293.203376)
		(end 382.866138 -293.19855)
		(width 0.0889)
		(layer "In2.Cu")
		(net "M_I_CPU0_SB_DQ<31>")
	)
	(segment
		(start 402.07819 -310.605678)
		(end 402.07819 -310.83377)
		(width 0.14478)
		(layer "In2.Cu")
		(net "M_I_CPU0_SB_DQ<31>")
	)
	(segment
		(start 403.75967 -311.817512)
		(end 403.75967 -312.045604)
		(width 0.14478)
		(layer "In2.Cu")
		(net "M_I_CPU0_SB_DQ<31>")
	)
	(segment
		(start 403.638766 -312.394346)
		(end 403.800818 -312.556398)
		(width 0.14478)
		(layer "In2.Cu")
		(net "M_I_CPU0_SB_DQ<31>")
	)
	(segment
		(start 427.03115 -318.46012)
		(end 427.456092 -318.035178)
		(width 0.14478)
		(layer "In2.Cu")
		(net "M_I_CPU0_SB_DQ<31>")
	)
	(segment
		(start 403.638766 -312.166254)
		(end 403.638766 -312.394346)
		(width 0.14478)
		(layer "In2.Cu")
		(net "M_I_CPU0_SB_DQ<31>")
	)
	(segment
		(start 401.256754 -309.314596)
		(end 401.418806 -309.476648)
		(width 0.14478)
		(layer "In2.Cu")
		(net "M_I_CPU0_SB_DQ<31>")
	)
	(segment
		(start 402.979382 -311.037224)
		(end 402.979382 -311.265316)
		(width 0.14478)
		(layer "In2.Cu")
		(net "M_I_CPU0_SB_DQ<31>")
	)
	(segment
		(start 390.281922 -294.013382)
		(end 390.312402 -294.031162)
		(width 0.0889)
		(layer "In2.Cu")
		(net "M_I_CPU0_SB_DQ<31>")
	)
	(segment
		(start 403.597618 -311.65546)
		(end 403.75967 -311.817512)
		(width 0.14478)
		(layer "In2.Cu")
		(net "M_I_CPU0_SB_DQ<31>")
	)
	(segment
		(start 408.410156 -317.165736)
		(end 411.535372 -318.46012)
		(width 0.14478)
		(layer "In2.Cu")
		(net "M_I_CPU0_SB_DQ<31>")
	)
	(segment
		(start 403.75967 -312.045604)
		(end 403.638766 -312.166254)
		(width 0.14478)
		(layer "In2.Cu")
		(net "M_I_CPU0_SB_DQ<31>")
	)
	(segment
		(start 401.297902 -310.053482)
		(end 401.459954 -310.215534)
		(width 0.14478)
		(layer "In2.Cu")
		(net "M_I_CPU0_SB_DQ<31>")
	)
	(segment
		(start 391.221722 -295.633394)
		(end 391.253472 -295.651682)
		(width 0.0889)
		(layer "In2.Cu")
		(net "M_I_CPU0_SB_DQ<31>")
	)
	(segment
		(start 377.583446 -293.19855)
		(end 377.591828 -293.203376)
		(width 0.0889)
		(layer "In2.Cu")
		(net "M_I_CPU0_SB_DQ<31>")
	)
	(segment
		(start 376.310906 -293.260526)
		(end 376.333258 -293.177214)
		(width 0.0889)
		(layer "In2.Cu")
		(net "M_I_CPU0_SB_DQ<31>")
	)
	(segment
		(start 400.127724 -308.654958)
		(end 400.248374 -308.534308)
		(width 0.14478)
		(layer "In2.Cu")
		(net "M_I_CPU0_SB_DQ<31>")
	)
	(segment
		(start 393.268962 -302.024542)
		(end 399.899378 -308.654958)
		(width 0.14478)
		(layer "In2.Cu")
		(net "M_I_CPU0_SB_DQ<31>")
	)
	(segment
		(start 404.419054 -312.946542)
		(end 404.419054 -313.174634)
		(width 0.14478)
		(layer "In2.Cu")
		(net "M_I_CPU0_SB_DQ<31>")
	)
	(segment
		(start 391.259314 -297.173142)
		(end 393.268962 -302.024542)
		(width 0.14478)
		(layer "In2.Cu")
		(net "M_I_CPU0_SB_DQ<31>")
	)
	(segment
		(start 401.80895 -310.094884)
		(end 402.037042 -310.094884)
		(width 0.14478)
		(layer "In2.Cu")
		(net "M_I_CPU0_SB_DQ<31>")
	)
	(segment
		(start 400.517614 -309.045102)
		(end 400.517614 -309.273194)
		(width 0.14478)
		(layer "In2.Cu")
		(net "M_I_CPU0_SB_DQ<31>")
	)
	(segment
		(start 404.539958 -312.825892)
		(end 404.419054 -312.946542)
		(width 0.14478)
		(layer "In2.Cu")
		(net "M_I_CPU0_SB_DQ<31>")
	)
	(segment
		(start 400.476466 -308.534308)
		(end 400.638518 -308.69636)
		(width 0.14478)
		(layer "In2.Cu")
		(net "M_I_CPU0_SB_DQ<31>")
	)
	(segment
		(start 404.149814 -312.435748)
		(end 404.377906 -312.435748)
		(width 0.14478)
		(layer "In2.Cu")
		(net "M_I_CPU0_SB_DQ<31>")
	)
	(segment
		(start 404.539958 -312.5978)
		(end 404.539958 -312.825892)
		(width 0.14478)
		(layer "In2.Cu")
		(net "M_I_CPU0_SB_DQ<31>")
	)
	(segment
		(start 402.468588 -310.995822)
		(end 402.589238 -310.875172)
		(width 0.14478)
		(layer "In2.Cu")
		(net "M_I_CPU0_SB_DQ<31>")
	)
	(segment
		(start 402.037042 -310.094884)
		(end 402.199094 -310.256936)
		(width 0.14478)
		(layer "In2.Cu")
		(net "M_I_CPU0_SB_DQ<31>")
	)
	(segment
		(start 388.497826 -293.203376)
		(end 388.506208 -293.19855)
		(width 0.0889)
		(layer "In2.Cu")
		(net "M_I_CPU0_SB_DQ<31>")
	)
	(segment
		(start 400.679666 -309.435246)
		(end 400.908012 -309.435246)
		(width 0.14478)
		(layer "In2.Cu")
		(net "M_I_CPU0_SB_DQ<31>")
	)
	(segment
		(start 403.800818 -312.556398)
		(end 404.029164 -312.556398)
		(width 0.14478)
		(layer "In2.Cu")
		(net "M_I_CPU0_SB_DQ<31>")
	)
	(segment
		(start 402.199094 -310.256936)
		(end 402.199094 -310.485028)
		(width 0.14478)
		(layer "In2.Cu")
		(net "M_I_CPU0_SB_DQ<31>")
	)
	(segment
		(start 402.240242 -310.995822)
		(end 402.468588 -310.995822)
		(width 0.14478)
		(layer "In2.Cu")
		(net "M_I_CPU0_SB_DQ<31>")
	)
	(segment
		(start 387.557772 -293.203376)
		(end 387.566154 -293.19855)
		(width 0.0889)
		(layer "In2.Cu")
		(net "M_I_CPU0_SB_DQ<31>")
	)
	(segment
		(start 383.79781 -293.203376)
		(end 383.806192 -293.19855)
		(width 0.0889)
		(layer "In2.Cu")
		(net "M_I_CPU0_SB_DQ<31>")
	)
	(segment
		(start 376.46483 -293.525956)
		(end 376.310906 -293.260526)
		(width 0.0889)
		(layer "In2.Cu")
		(net "M_I_CPU0_SB_DQ<31>")
	)
	(segment
		(start 403.02053 -311.77611)
		(end 403.248876 -311.77611)
		(width 0.14478)
		(layer "In2.Cu")
		(net "M_I_CPU0_SB_DQ<31>")
	)
	(segment
		(start 400.248374 -308.534308)
		(end 400.476466 -308.534308)
		(width 0.14478)
		(layer "In2.Cu")
		(net "M_I_CPU0_SB_DQ<31>")
	)
	(segment
		(start 402.858478 -311.385966)
		(end 402.858478 -311.614058)
		(width 0.14478)
		(layer "In2.Cu")
		(net "M_I_CPU0_SB_DQ<31>")
	)
	(segment
		(start 390.242806 -293.990522)
		(end 390.281922 -294.013382)
		(width 0.0889)
		(layer "In2.Cu")
		(net "M_I_CPU0_SB_DQ<31>")
	)
	(segment
		(start 401.418806 -309.70474)
		(end 401.297902 -309.82539)
		(width 0.14478)
		(layer "In2.Cu")
		(net "M_I_CPU0_SB_DQ<31>")
	)
	(segment
		(start 403.248876 -311.77611)
		(end 403.369526 -311.65546)
		(width 0.14478)
		(layer "In2.Cu")
		(net "M_I_CPU0_SB_DQ<31>")
	)
	(segment
		(start 390.712706 -294.800528)
		(end 390.751822 -294.823388)
		(width 0.0889)
		(layer "In2.Cu")
		(net "M_I_CPU0_SB_DQ<31>")
	)
	(segment
		(start 404.419054 -313.174634)
		(end 408.410156 -317.165736)
		(width 0.14478)
		(layer "In2.Cu")
		(net "M_I_CPU0_SB_DQ<31>")
	)
	(segment
		(start 401.418806 -309.476648)
		(end 401.418806 -309.70474)
		(width 0.14478)
		(layer "In2.Cu")
		(net "M_I_CPU0_SB_DQ<31>")
	)
	(segment
		(start 411.535372 -318.46012)
		(end 427.03115 -318.46012)
		(width 0.14478)
		(layer "In2.Cu")
		(net "M_I_CPU0_SB_DQ<31>")
	)
	(segment
		(start 380.037848 -293.203376)
		(end 380.04623 -293.19855)
		(width 0.0889)
		(layer "In2.Cu")
		(net "M_I_CPU0_SB_DQ<31>")
	)
	(segment
		(start 400.638518 -308.924452)
		(end 400.517614 -309.045102)
		(width 0.14478)
		(layer "In2.Cu")
		(net "M_I_CPU0_SB_DQ<31>")
	)
	(segment
		(start 386.983478 -293.19855)
		(end 386.99186 -293.203376)
		(width 0.0889)
		(layer "In2.Cu")
		(net "M_I_CPU0_SB_DQ<31>")
	)
	(segment
		(start 400.908012 -309.435246)
		(end 401.028662 -309.314596)
		(width 0.14478)
		(layer "In2.Cu")
		(net "M_I_CPU0_SB_DQ<31>")
	)
	(segment
		(start 402.07819 -310.83377)
		(end 402.240242 -310.995822)
		(width 0.14478)
		(layer "In2.Cu")
		(net "M_I_CPU0_SB_DQ<31>")
	)
	(segment
		(start 399.899378 -308.654958)
		(end 400.127724 -308.654958)
		(width 0.14478)
		(layer "In2.Cu")
		(net "M_I_CPU0_SB_DQ<31>")
	)
	(segment
		(start 403.369526 -311.65546)
		(end 403.597618 -311.65546)
		(width 0.14478)
		(layer "In2.Cu")
		(net "M_I_CPU0_SB_DQ<31>")
	)
	(segment
		(start 391.409428 -296.47007)
		(end 391.259314 -296.620184)
		(width 0.0889)
		(layer "In2.Cu")
		(net "M_I_CPU0_SB_DQ<31>")
	)
	(segment
		(start 400.638518 -308.69636)
		(end 400.638518 -308.924452)
		(width 0.14478)
		(layer "In2.Cu")
		(net "M_I_CPU0_SB_DQ<31>")
	)
	(segment
		(start 402.589238 -310.875172)
		(end 402.81733 -310.875172)
		(width 0.14478)
		(layer "In2.Cu")
		(net "M_I_CPU0_SB_DQ<31>")
	)
	(segment
		(start 402.979382 -311.265316)
		(end 402.858478 -311.385966)
		(width 0.14478)
		(layer "In2.Cu")
		(net "M_I_CPU0_SB_DQ<31>")
	)
	(segment
		(start 401.6883 -310.215534)
		(end 401.80895 -310.094884)
		(width 0.14478)
		(layer "In2.Cu")
		(net "M_I_CPU0_SB_DQ<31>")
	)
	(segment
		(start 401.028662 -309.314596)
		(end 401.256754 -309.314596)
		(width 0.14478)
		(layer "In2.Cu")
		(net "M_I_CPU0_SB_DQ<31>")
	)
	(segment
		(start 404.377906 -312.435748)
		(end 404.539958 -312.5978)
		(width 0.14478)
		(layer "In2.Cu")
		(net "M_I_CPU0_SB_DQ<31>")
	)
	(segment
		(start 391.409428 -295.955974)
		(end 391.409428 -296.47007)
		(width 0.0889)
		(layer "In2.Cu")
		(net "M_I_CPU0_SB_DQ<31>")
	)
	(segment
		(start 390.751822 -294.823388)
		(end 390.783572 -294.841676)
		(width 0.0889)
		(layer "In2.Cu")
		(net "M_I_CPU0_SB_DQ<31>")
	)
	(segment
		(start 391.259314 -296.620184)
		(end 391.259314 -297.173142)
		(width 0.14478)
		(layer "In2.Cu")
		(net "M_I_CPU0_SB_DQ<31>")
	)
	(segment
		(start 400.517614 -309.273194)
		(end 400.679666 -309.435246)
		(width 0.14478)
		(layer "In2.Cu")
		(net "M_I_CPU0_SB_DQ<31>")
	)
	(segment
		(start 391.1854 -295.612312)
		(end 391.221722 -295.633394)
		(width 0.0889)
		(layer "In2.Cu")
		(net "M_I_CPU0_SB_DQ<31>")
	)
	(segment
		(start 389.811768 -293.203376)
		(end 389.843518 -293.221664)
		(width 0.0889)
		(layer "In2.Cu")
		(net "M_I_CPU0_SB_DQ<31>")
	)
	(arc
		(start 390.783572 -294.841676)
		(mid 390.898248 -294.97501)
		(end 390.939528 -295.145968)
		(width 0.0889)
		(layer "In2.Cu")
		(net "M_I_CPU0_SB_DQ<31>")
	)
	(arc
		(start 390.469374 -294.335962)
		(mid 390.533889 -294.598181)
		(end 390.712706 -294.800528)
		(width 0.0889)
		(layer "In2.Cu")
		(net "M_I_CPU0_SB_DQ<31>")
	)
	(arc
		(start 387.931914 -293.203376)
		(mid 388.21487 -293.279553)
		(end 388.497826 -293.203376)
		(width 0.0889)
		(layer "In2.Cu")
		(net "M_I_CPU0_SB_DQ<31>")
	)
	(arc
		(start 391.253472 -295.651682)
		(mid 391.368148 -295.785016)
		(end 391.409428 -295.955974)
		(width 0.0889)
		(layer "In2.Cu")
		(net "M_I_CPU0_SB_DQ<31>")
	)
	(arc
		(start 378.15774 -293.203376)
		(mid 378.339991 -293.153026)
		(end 378.5235 -293.19855)
		(width 0.0889)
		(layer "In2.Cu")
		(net "M_I_CPU0_SB_DQ<31>")
	)
	(arc
		(start 382.866138 -293.19855)
		(mid 383.049646 -293.153056)
		(end 383.231898 -293.203376)
		(width 0.0889)
		(layer "In2.Cu")
		(net "M_I_CPU0_SB_DQ<31>")
	)
	(arc
		(start 376.333258 -293.177214)
		(mid 376.495447 -293.154479)
		(end 376.651774 -293.203376)
		(width 0.0889)
		(layer "In2.Cu")
		(net "M_I_CPU0_SB_DQ<31>")
	)
	(arc
		(start 380.04623 -293.19855)
		(mid 380.229738 -293.153056)
		(end 380.41199 -293.203376)
		(width 0.0889)
		(layer "In2.Cu")
		(net "M_I_CPU0_SB_DQ<31>")
	)
	(arc
		(start 388.871968 -293.203376)
		(mid 389.154924 -293.279553)
		(end 389.43788 -293.203376)
		(width 0.0889)
		(layer "In2.Cu")
		(net "M_I_CPU0_SB_DQ<31>")
	)
	(arc
		(start 377.217686 -293.203376)
		(mid 377.399937 -293.153026)
		(end 377.583446 -293.19855)
		(width 0.0889)
		(layer "In2.Cu")
		(net "M_I_CPU0_SB_DQ<31>")
	)
	(arc
		(start 381.917702 -293.203376)
		(mid 382.099953 -293.153026)
		(end 382.283462 -293.19855)
		(width 0.0889)
		(layer "In2.Cu")
		(net "M_I_CPU0_SB_DQ<31>")
	)
	(arc
		(start 390.939528 -295.145968)
		(mid 391.004764 -295.409559)
		(end 391.1854 -295.612312)
		(width 0.0889)
		(layer "In2.Cu")
		(net "M_I_CPU0_SB_DQ<31>")
	)
	(arc
		(start 386.99186 -293.203376)
		(mid 387.274816 -293.279553)
		(end 387.557772 -293.203376)
		(width 0.0889)
		(layer "In2.Cu")
		(net "M_I_CPU0_SB_DQ<31>")
	)
	(arc
		(start 384.171952 -293.203376)
		(mid 384.454908 -293.279553)
		(end 384.737864 -293.203376)
		(width 0.0889)
		(layer "In2.Cu")
		(net "M_I_CPU0_SB_DQ<31>")
	)
	(arc
		(start 390.312402 -294.031162)
		(mid 390.427829 -294.164538)
		(end 390.469374 -294.335962)
		(width 0.0889)
		(layer "In2.Cu")
		(net "M_I_CPU0_SB_DQ<31>")
	)
	(arc
		(start 383.806192 -293.19855)
		(mid 383.9897 -293.153056)
		(end 384.171952 -293.203376)
		(width 0.0889)
		(layer "In2.Cu")
		(net "M_I_CPU0_SB_DQ<31>")
	)
	(arc
		(start 385.111752 -293.203376)
		(mid 385.394708 -293.279553)
		(end 385.677664 -293.203376)
		(width 0.0889)
		(layer "In2.Cu")
		(net "M_I_CPU0_SB_DQ<31>")
	)
	(arc
		(start 386.051806 -293.203376)
		(mid 386.334762 -293.279553)
		(end 386.617718 -293.203376)
		(width 0.0889)
		(layer "In2.Cu")
		(net "M_I_CPU0_SB_DQ<31>")
	)
	(arc
		(start 387.566154 -293.19855)
		(mid 387.749662 -293.153056)
		(end 387.931914 -293.203376)
		(width 0.0889)
		(layer "In2.Cu")
		(net "M_I_CPU0_SB_DQ<31>")
	)
	(arc
		(start 377.591828 -293.203376)
		(mid 377.874784 -293.279553)
		(end 378.15774 -293.203376)
		(width 0.0889)
		(layer "In2.Cu")
		(net "M_I_CPU0_SB_DQ<31>")
	)
	(arc
		(start 376.651774 -293.203376)
		(mid 376.93473 -293.279553)
		(end 377.217686 -293.203376)
		(width 0.0889)
		(layer "In2.Cu")
		(net "M_I_CPU0_SB_DQ<31>")
	)
	(arc
		(start 379.471936 -293.203376)
		(mid 379.754892 -293.279553)
		(end 380.037848 -293.203376)
		(width 0.0889)
		(layer "In2.Cu")
		(net "M_I_CPU0_SB_DQ<31>")
	)
	(arc
		(start 389.43788 -293.203376)
		(mid 389.624824 -293.153121)
		(end 389.811768 -293.203376)
		(width 0.0889)
		(layer "In2.Cu")
		(net "M_I_CPU0_SB_DQ<31>")
	)
	(arc
		(start 380.41199 -293.203376)
		(mid 380.694946 -293.279553)
		(end 380.977902 -293.203376)
		(width 0.0889)
		(layer "In2.Cu")
		(net "M_I_CPU0_SB_DQ<31>")
	)
	(arc
		(start 388.506208 -293.19855)
		(mid 388.689716 -293.153056)
		(end 388.871968 -293.203376)
		(width 0.0889)
		(layer "In2.Cu")
		(net "M_I_CPU0_SB_DQ<31>")
	)
	(arc
		(start 381.35179 -293.203376)
		(mid 381.634746 -293.279553)
		(end 381.917702 -293.203376)
		(width 0.0889)
		(layer "In2.Cu")
		(net "M_I_CPU0_SB_DQ<31>")
	)
	(arc
		(start 382.291844 -293.203376)
		(mid 382.5748 -293.279553)
		(end 382.857756 -293.203376)
		(width 0.0889)
		(layer "In2.Cu")
		(net "M_I_CPU0_SB_DQ<31>")
	)
	(arc
		(start 378.531882 -293.203376)
		(mid 378.814838 -293.279553)
		(end 379.097794 -293.203376)
		(width 0.0889)
		(layer "In2.Cu")
		(net "M_I_CPU0_SB_DQ<31>")
	)
	(arc
		(start 389.843518 -293.221664)
		(mid 389.958194 -293.354998)
		(end 389.999474 -293.525956)
		(width 0.0889)
		(layer "In2.Cu")
		(net "M_I_CPU0_SB_DQ<31>")
	)
	(arc
		(start 386.617718 -293.203376)
		(mid 386.799969 -293.153026)
		(end 386.983478 -293.19855)
		(width 0.0889)
		(layer "In2.Cu")
		(net "M_I_CPU0_SB_DQ<31>")
	)
	(arc
		(start 384.737864 -293.203376)
		(mid 384.924808 -293.153121)
		(end 385.111752 -293.203376)
		(width 0.0889)
		(layer "In2.Cu")
		(net "M_I_CPU0_SB_DQ<31>")
	)
	(arc
		(start 389.999474 -293.525956)
		(mid 390.063989 -293.788175)
		(end 390.242806 -293.990522)
		(width 0.0889)
		(layer "In2.Cu")
		(net "M_I_CPU0_SB_DQ<31>")
	)
	(arc
		(start 379.106176 -293.19855)
		(mid 379.289684 -293.153056)
		(end 379.471936 -293.203376)
		(width 0.0889)
		(layer "In2.Cu")
		(net "M_I_CPU0_SB_DQ<31>")
	)
	(arc
		(start 383.231898 -293.203376)
		(mid 383.514854 -293.279553)
		(end 383.79781 -293.203376)
		(width 0.0889)
		(layer "In2.Cu")
		(net "M_I_CPU0_SB_DQ<31>")
	)
	(arc
		(start 380.977902 -293.203376)
		(mid 381.164846 -293.153121)
		(end 381.35179 -293.203376)
		(width 0.0889)
		(layer "In2.Cu")
		(net "M_I_CPU0_SB_DQ<31>")
	)
	(arc
		(start 385.677664 -293.203376)
		(mid 385.859915 -293.153026)
		(end 386.043424 -293.19855)
		(width 0.0889)
		(layer "In2.Cu")
		(net "M_I_CPU0_SB_DQ<31>")
	)
	(segment
		(start 377.407932 -292.450012)
		(end 377.874784 -292.71595)
		(width 0.10668)
		(layer "F.Cu")
		(net "M_I_CPU0_SB_DQ<30>")
	)
	(segment
		(start 379.933454 -292.388544)
		(end 379.941836 -292.39337)
		(width 0.0889)
		(layer "In2.Cu")
		(net "M_I_CPU0_SB_DQ<30>")
	)
	(segment
		(start 414.226248 -316.760098)
		(end 414.4899 -316.760098)
		(width 0.14478)
		(layer "In2.Cu")
		(net "M_I_CPU0_SB_DQ<30>")
	)
	(segment
		(start 407.89733 -315.152024)
		(end 407.89733 -315.380624)
		(width 0.14478)
		(layer "In2.Cu")
		(net "M_I_CPU0_SB_DQ<30>")
	)
	(segment
		(start 406.090374 -313.05754)
		(end 406.318974 -313.05754)
		(width 0.14478)
		(layer "In2.Cu")
		(net "M_I_CPU0_SB_DQ<30>")
	)
	(segment
		(start 389.90778 -292.39337)
		(end 389.916162 -292.388544)
		(width 0.0889)
		(layer "In2.Cu")
		(net "M_I_CPU0_SB_DQ<30>")
	)
	(segment
		(start 408.659838 -315.398404)
		(end 408.821382 -315.559948)
		(width 0.14478)
		(layer "In2.Cu")
		(net "M_I_CPU0_SB_DQ<30>")
	)
	(segment
		(start 385.207764 -292.39337)
		(end 385.216146 -292.388544)
		(width 0.0889)
		(layer "In2.Cu")
		(net "M_I_CPU0_SB_DQ<30>")
	)
	(segment
		(start 413.667448 -316.46495)
		(end 413.9311 -316.46495)
		(width 0.14478)
		(layer "In2.Cu")
		(net "M_I_CPU0_SB_DQ<30>")
	)
	(segment
		(start 406.498298 -313.981592)
		(end 406.726898 -313.981592)
		(width 0.14478)
		(layer "In2.Cu")
		(net "M_I_CPU0_SB_DQ<30>")
	)
	(segment
		(start 407.89733 -315.380624)
		(end 408.058874 -315.542168)
		(width 0.14478)
		(layer "In2.Cu")
		(net "M_I_CPU0_SB_DQ<30>")
	)
	(segment
		(start 386.147818 -292.39337)
		(end 386.1562 -292.388544)
		(width 0.0889)
		(layer "In2.Cu")
		(net "M_I_CPU0_SB_DQ<30>")
	)
	(segment
		(start 406.336754 -313.820048)
		(end 406.498298 -313.981592)
		(width 0.14478)
		(layer "In2.Cu")
		(net "M_I_CPU0_SB_DQ<30>")
	)
	(segment
		(start 409.440126 -316.178692)
		(end 409.718764 -316.45733)
		(width 0.14478)
		(layer "In2.Cu")
		(net "M_I_CPU0_SB_DQ<30>")
	)
	(segment
		(start 418.032438 -316.760098)
		(end 418.335206 -316.45733)
		(width 0.14478)
		(layer "In2.Cu")
		(net "M_I_CPU0_SB_DQ<30>")
	)
	(segment
		(start 391.1854 -293.9923)
		(end 391.221722 -294.013382)
		(width 0.0889)
		(layer "In2.Cu")
		(net "M_I_CPU0_SB_DQ<30>")
	)
	(segment
		(start 408.041094 -315.00826)
		(end 407.89733 -315.152024)
		(width 0.14478)
		(layer "In2.Cu")
		(net "M_I_CPU0_SB_DQ<30>")
	)
	(segment
		(start 408.041094 -314.77966)
		(end 408.041094 -315.00826)
		(width 0.14478)
		(layer "In2.Cu")
		(net "M_I_CPU0_SB_DQ<30>")
	)
	(segment
		(start 405.70023 -312.667396)
		(end 405.556466 -312.81116)
		(width 0.14478)
		(layer "In2.Cu")
		(net "M_I_CPU0_SB_DQ<30>")
	)
	(segment
		(start 392.349228 -296.282364)
		(end 392.209274 -296.422318)
		(width 0.0889)
		(layer "In2.Cu")
		(net "M_I_CPU0_SB_DQ<30>")
	)
	(segment
		(start 407.507186 -314.76188)
		(end 407.65095 -314.618116)
		(width 0.14478)
		(layer "In2.Cu")
		(net "M_I_CPU0_SB_DQ<30>")
	)
	(segment
		(start 418.591238 -316.45733)
		(end 418.894006 -316.760098)
		(width 0.14478)
		(layer "In2.Cu")
		(net "M_I_CPU0_SB_DQ<30>")
	)
	(segment
		(start 408.058874 -315.542168)
		(end 408.287474 -315.542168)
		(width 0.14478)
		(layer "In2.Cu")
		(net "M_I_CPU0_SB_DQ<30>")
	)
	(segment
		(start 417.776406 -316.760098)
		(end 418.032438 -316.760098)
		(width 0.14478)
		(layer "In2.Cu")
		(net "M_I_CPU0_SB_DQ<30>")
	)
	(segment
		(start 411.14726 -316.518036)
		(end 411.389322 -316.760098)
		(width 0.14478)
		(layer "In2.Cu")
		(net "M_I_CPU0_SB_DQ<30>")
	)
	(segment
		(start 407.87955 -314.618116)
		(end 408.041094 -314.77966)
		(width 0.14478)
		(layer "In2.Cu")
		(net "M_I_CPU0_SB_DQ<30>")
	)
	(segment
		(start 407.260806 -313.999372)
		(end 407.260806 -314.227972)
		(width 0.14478)
		(layer "In2.Cu")
		(net "M_I_CPU0_SB_DQ<30>")
	)
	(segment
		(start 422.075102 -316.760098)
		(end 422.39565 -316.43955)
		(width 0.14478)
		(layer "In2.Cu")
		(net "M_I_CPU0_SB_DQ<30>")
	)
	(segment
		(start 418.894006 -316.760098)
		(end 420.957502 -316.760098)
		(width 0.14478)
		(layer "In2.Cu")
		(net "M_I_CPU0_SB_DQ<30>")
	)
	(segment
		(start 407.65095 -314.618116)
		(end 407.87955 -314.618116)
		(width 0.14478)
		(layer "In2.Cu")
		(net "M_I_CPU0_SB_DQ<30>")
	)
	(segment
		(start 414.4899 -316.760098)
		(end 414.785048 -316.46495)
		(width 0.14478)
		(layer "In2.Cu")
		(net "M_I_CPU0_SB_DQ<30>")
	)
	(segment
		(start 405.71801 -313.201304)
		(end 405.94661 -313.201304)
		(width 0.14478)
		(layer "In2.Cu")
		(net "M_I_CPU0_SB_DQ<30>")
	)
	(segment
		(start 406.480518 -313.447684)
		(end 406.336754 -313.591448)
		(width 0.14478)
		(layer "In2.Cu")
		(net "M_I_CPU0_SB_DQ<30>")
	)
	(segment
		(start 409.211526 -316.178692)
		(end 409.440126 -316.178692)
		(width 0.14478)
		(layer "In2.Cu")
		(net "M_I_CPU0_SB_DQ<30>")
	)
	(segment
		(start 425.151804 -316.760098)
		(end 425.454572 -316.45733)
		(width 0.14478)
		(layer "In2.Cu")
		(net "M_I_CPU0_SB_DQ<30>")
	)
	(segment
		(start 421.516302 -316.43955)
		(end 421.83685 -316.760098)
		(width 0.14478)
		(layer "In2.Cu")
		(net "M_I_CPU0_SB_DQ<30>")
	)
	(segment
		(start 392.209274 -296.422318)
		(end 392.209274 -297.024552)
		(width 0.14478)
		(layer "In2.Cu")
		(net "M_I_CPU0_SB_DQ<30>")
	)
	(segment
		(start 406.480518 -313.219084)
		(end 406.480518 -313.447684)
		(width 0.14478)
		(layer "In2.Cu")
		(net "M_I_CPU0_SB_DQ<30>")
	)
	(segment
		(start 407.260806 -314.227972)
		(end 407.117042 -314.371736)
		(width 0.14478)
		(layer "In2.Cu")
		(net "M_I_CPU0_SB_DQ<30>")
	)
	(segment
		(start 413.3723 -316.760098)
		(end 413.667448 -316.46495)
		(width 0.14478)
		(layer "In2.Cu")
		(net "M_I_CPU0_SB_DQ<30>")
	)
	(segment
		(start 392.349228 -295.955974)
		(end 392.349228 -296.282364)
		(width 0.0889)
		(layer "In2.Cu")
		(net "M_I_CPU0_SB_DQ<30>")
	)
	(segment
		(start 405.70023 -312.438796)
		(end 405.70023 -312.667396)
		(width 0.14478)
		(layer "In2.Cu")
		(net "M_I_CPU0_SB_DQ<30>")
	)
	(segment
		(start 420.957502 -316.760098)
		(end 421.27805 -316.43955)
		(width 0.14478)
		(layer "In2.Cu")
		(net "M_I_CPU0_SB_DQ<30>")
	)
	(segment
		(start 413.9311 -316.46495)
		(end 414.226248 -316.760098)
		(width 0.14478)
		(layer "In2.Cu")
		(net "M_I_CPU0_SB_DQ<30>")
	)
	(segment
		(start 406.318974 -313.05754)
		(end 406.480518 -313.219084)
		(width 0.14478)
		(layer "In2.Cu")
		(net "M_I_CPU0_SB_DQ<30>")
	)
	(segment
		(start 392.209274 -297.024552)
		(end 393.569444 -300.30801)
		(width 0.14478)
		(layer "In2.Cu")
		(net "M_I_CPU0_SB_DQ<30>")
	)
	(segment
		(start 389.333486 -292.388544)
		(end 389.341868 -292.39337)
		(width 0.0889)
		(layer "In2.Cu")
		(net "M_I_CPU0_SB_DQ<30>")
	)
	(segment
		(start 408.287474 -315.542168)
		(end 408.431238 -315.398404)
		(width 0.14478)
		(layer "In2.Cu")
		(net "M_I_CPU0_SB_DQ<30>")
	)
	(segment
		(start 408.821382 -315.788548)
		(end 408.677618 -315.932312)
		(width 0.14478)
		(layer "In2.Cu")
		(net "M_I_CPU0_SB_DQ<30>")
	)
	(segment
		(start 410.64053 -316.760098)
		(end 410.882592 -316.518036)
		(width 0.14478)
		(layer "In2.Cu")
		(net "M_I_CPU0_SB_DQ<30>")
	)
	(segment
		(start 427.03115 -316.760098)
		(end 427.456092 -316.335156)
		(width 0.14478)
		(layer "In2.Cu")
		(net "M_I_CPU0_SB_DQ<30>")
	)
	(segment
		(start 408.839162 -316.322456)
		(end 409.067762 -316.322456)
		(width 0.14478)
		(layer "In2.Cu")
		(net "M_I_CPU0_SB_DQ<30>")
	)
	(segment
		(start 415.343848 -316.760098)
		(end 416.914838 -316.760098)
		(width 0.14478)
		(layer "In2.Cu")
		(net "M_I_CPU0_SB_DQ<30>")
	)
	(segment
		(start 384.63347 -292.388544)
		(end 384.641852 -292.39337)
		(width 0.0889)
		(layer "In2.Cu")
		(net "M_I_CPU0_SB_DQ<30>")
	)
	(segment
		(start 390.281922 -292.39337)
		(end 390.312402 -292.41115)
		(width 0.0889)
		(layer "In2.Cu")
		(net "M_I_CPU0_SB_DQ<30>")
	)
	(segment
		(start 406.726898 -313.981592)
		(end 406.870662 -313.837828)
		(width 0.14478)
		(layer "In2.Cu")
		(net "M_I_CPU0_SB_DQ<30>")
	)
	(segment
		(start 407.278586 -314.76188)
		(end 407.507186 -314.76188)
		(width 0.14478)
		(layer "In2.Cu")
		(net "M_I_CPU0_SB_DQ<30>")
	)
	(segment
		(start 388.394448 -292.389052)
		(end 388.401814 -292.39337)
		(width 0.0889)
		(layer "In2.Cu")
		(net "M_I_CPU0_SB_DQ<30>")
	)
	(segment
		(start 422.39565 -316.43955)
		(end 422.633902 -316.43955)
		(width 0.14478)
		(layer "In2.Cu")
		(net "M_I_CPU0_SB_DQ<30>")
	)
	(segment
		(start 422.95445 -316.760098)
		(end 425.151804 -316.760098)
		(width 0.14478)
		(layer "In2.Cu")
		(net "M_I_CPU0_SB_DQ<30>")
	)
	(segment
		(start 381.447802 -292.39337)
		(end 381.456184 -292.388544)
		(width 0.0889)
		(layer "In2.Cu")
		(net "M_I_CPU0_SB_DQ<30>")
	)
	(segment
		(start 390.751822 -293.203376)
		(end 390.783572 -293.221664)
		(width 0.0889)
		(layer "In2.Cu")
		(net "M_I_CPU0_SB_DQ<30>")
	)
	(segment
		(start 414.785048 -316.46495)
		(end 415.0487 -316.46495)
		(width 0.14478)
		(layer "In2.Cu")
		(net "M_I_CPU0_SB_DQ<30>")
	)
	(segment
		(start 380.873508 -292.388544)
		(end 380.88189 -292.39337)
		(width 0.0889)
		(layer "In2.Cu")
		(net "M_I_CPU0_SB_DQ<30>")
	)
	(segment
		(start 407.099262 -313.837828)
		(end 407.260806 -313.999372)
		(width 0.14478)
		(layer "In2.Cu")
		(net "M_I_CPU0_SB_DQ<30>")
	)
	(segment
		(start 415.0487 -316.46495)
		(end 415.343848 -316.760098)
		(width 0.14478)
		(layer "In2.Cu")
		(net "M_I_CPU0_SB_DQ<30>")
	)
	(segment
		(start 388.393432 -292.388544)
		(end 388.394448 -292.389052)
		(width 0.0889)
		(layer "In2.Cu")
		(net "M_I_CPU0_SB_DQ<30>")
	)
	(segment
		(start 391.691622 -294.823388)
		(end 391.723372 -294.841676)
		(width 0.0889)
		(layer "In2.Cu")
		(net "M_I_CPU0_SB_DQ<30>")
	)
	(segment
		(start 405.556466 -313.03976)
		(end 405.71801 -313.201304)
		(width 0.14478)
		(layer "In2.Cu")
		(net "M_I_CPU0_SB_DQ<30>")
	)
	(segment
		(start 410.08173 -316.45733)
		(end 410.384498 -316.760098)
		(width 0.14478)
		(layer "In2.Cu")
		(net "M_I_CPU0_SB_DQ<30>")
	)
	(segment
		(start 426.013372 -316.760098)
		(end 427.03115 -316.760098)
		(width 0.14478)
		(layer "In2.Cu")
		(net "M_I_CPU0_SB_DQ<30>")
	)
	(segment
		(start 421.83685 -316.760098)
		(end 422.075102 -316.760098)
		(width 0.14478)
		(layer "In2.Cu")
		(net "M_I_CPU0_SB_DQ<30>")
	)
	(segment
		(start 393.569444 -300.30801)
		(end 405.70023 -312.438796)
		(width 0.14478)
		(layer "In2.Cu")
		(net "M_I_CPU0_SB_DQ<30>")
	)
	(segment
		(start 425.454572 -316.45733)
		(end 425.710604 -316.45733)
		(width 0.14478)
		(layer "In2.Cu")
		(net "M_I_CPU0_SB_DQ<30>")
	)
	(segment
		(start 418.335206 -316.45733)
		(end 418.591238 -316.45733)
		(width 0.14478)
		(layer "In2.Cu")
		(net "M_I_CPU0_SB_DQ<30>")
	)
	(segment
		(start 407.117042 -314.600336)
		(end 407.278586 -314.76188)
		(width 0.14478)
		(layer "In2.Cu")
		(net "M_I_CPU0_SB_DQ<30>")
	)
	(segment
		(start 422.633902 -316.43955)
		(end 422.95445 -316.760098)
		(width 0.14478)
		(layer "In2.Cu")
		(net "M_I_CPU0_SB_DQ<30>")
	)
	(segment
		(start 383.693416 -292.388544)
		(end 383.701798 -292.39337)
		(width 0.0889)
		(layer "In2.Cu")
		(net "M_I_CPU0_SB_DQ<30>")
	)
	(segment
		(start 410.384498 -316.760098)
		(end 410.64053 -316.760098)
		(width 0.14478)
		(layer "In2.Cu")
		(net "M_I_CPU0_SB_DQ<30>")
	)
	(segment
		(start 390.712706 -293.180516)
		(end 390.751822 -293.203376)
		(width 0.0889)
		(layer "In2.Cu")
		(net "M_I_CPU0_SB_DQ<30>")
	)
	(segment
		(start 410.882592 -316.518036)
		(end 411.14726 -316.518036)
		(width 0.14478)
		(layer "In2.Cu")
		(net "M_I_CPU0_SB_DQ<30>")
	)
	(segment
		(start 425.710604 -316.45733)
		(end 426.013372 -316.760098)
		(width 0.14478)
		(layer "In2.Cu")
		(net "M_I_CPU0_SB_DQ<30>")
	)
	(segment
		(start 391.221722 -294.013382)
		(end 391.253472 -294.03167)
		(width 0.0889)
		(layer "In2.Cu")
		(net "M_I_CPU0_SB_DQ<30>")
	)
	(segment
		(start 406.336754 -313.591448)
		(end 406.336754 -313.820048)
		(width 0.14478)
		(layer "In2.Cu")
		(net "M_I_CPU0_SB_DQ<30>")
	)
	(segment
		(start 408.431238 -315.398404)
		(end 408.659838 -315.398404)
		(width 0.14478)
		(layer "In2.Cu")
		(net "M_I_CPU0_SB_DQ<30>")
	)
	(segment
		(start 408.821382 -315.559948)
		(end 408.821382 -315.788548)
		(width 0.14478)
		(layer "In2.Cu")
		(net "M_I_CPU0_SB_DQ<30>")
	)
	(segment
		(start 377.874784 -292.71595)
		(end 377.72086 -292.45052)
		(width 0.0889)
		(layer "In2.Cu")
		(net "M_I_CPU0_SB_DQ<30>")
	)
	(segment
		(start 409.718764 -316.45733)
		(end 410.08173 -316.45733)
		(width 0.14478)
		(layer "In2.Cu")
		(net "M_I_CPU0_SB_DQ<30>")
	)
	(segment
		(start 417.217606 -316.45733)
		(end 417.473638 -316.45733)
		(width 0.14478)
		(layer "In2.Cu")
		(net "M_I_CPU0_SB_DQ<30>")
	)
	(segment
		(start 409.067762 -316.322456)
		(end 409.211526 -316.178692)
		(width 0.14478)
		(layer "In2.Cu")
		(net "M_I_CPU0_SB_DQ<30>")
	)
	(segment
		(start 411.389322 -316.760098)
		(end 413.3723 -316.760098)
		(width 0.14478)
		(layer "In2.Cu")
		(net "M_I_CPU0_SB_DQ<30>")
	)
	(segment
		(start 377.72086 -292.45052)
		(end 377.743212 -292.367208)
		(width 0.0889)
		(layer "In2.Cu")
		(net "M_I_CPU0_SB_DQ<30>")
	)
	(segment
		(start 421.27805 -316.43955)
		(end 421.516302 -316.43955)
		(width 0.14478)
		(layer "In2.Cu")
		(net "M_I_CPU0_SB_DQ<30>")
	)
	(segment
		(start 391.6553 -294.802306)
		(end 391.691622 -294.823388)
		(width 0.0889)
		(layer "In2.Cu")
		(net "M_I_CPU0_SB_DQ<30>")
	)
	(segment
		(start 405.94661 -313.201304)
		(end 406.090374 -313.05754)
		(width 0.14478)
		(layer "In2.Cu")
		(net "M_I_CPU0_SB_DQ<30>")
	)
	(segment
		(start 416.914838 -316.760098)
		(end 417.217606 -316.45733)
		(width 0.14478)
		(layer "In2.Cu")
		(net "M_I_CPU0_SB_DQ<30>")
	)
	(segment
		(start 406.870662 -313.837828)
		(end 407.099262 -313.837828)
		(width 0.14478)
		(layer "In2.Cu")
		(net "M_I_CPU0_SB_DQ<30>")
	)
	(segment
		(start 392.1252 -295.612312)
		(end 392.161522 -295.633394)
		(width 0.0889)
		(layer "In2.Cu")
		(net "M_I_CPU0_SB_DQ<30>")
	)
	(segment
		(start 408.677618 -316.160912)
		(end 408.839162 -316.322456)
		(width 0.14478)
		(layer "In2.Cu")
		(net "M_I_CPU0_SB_DQ<30>")
	)
	(segment
		(start 392.161522 -295.633394)
		(end 392.194288 -295.652444)
		(width 0.0889)
		(layer "In2.Cu")
		(net "M_I_CPU0_SB_DQ<30>")
	)
	(segment
		(start 408.677618 -315.932312)
		(end 408.677618 -316.160912)
		(width 0.14478)
		(layer "In2.Cu")
		(net "M_I_CPU0_SB_DQ<30>")
	)
	(segment
		(start 417.473638 -316.45733)
		(end 417.776406 -316.760098)
		(width 0.14478)
		(layer "In2.Cu")
		(net "M_I_CPU0_SB_DQ<30>")
	)
	(segment
		(start 407.117042 -314.371736)
		(end 407.117042 -314.600336)
		(width 0.14478)
		(layer "In2.Cu")
		(net "M_I_CPU0_SB_DQ<30>")
	)
	(segment
		(start 405.556466 -312.81116)
		(end 405.556466 -313.03976)
		(width 0.14478)
		(layer "In2.Cu")
		(net "M_I_CPU0_SB_DQ<30>")
	)
	(arc
		(start 390.469374 -292.71595)
		(mid 390.533889 -292.978169)
		(end 390.712706 -293.180516)
		(width 0.0889)
		(layer "In2.Cu")
		(net "M_I_CPU0_SB_DQ<30>")
	)
	(arc
		(start 385.216146 -292.388544)
		(mid 385.399654 -292.34305)
		(end 385.581906 -292.39337)
		(width 0.0889)
		(layer "In2.Cu")
		(net "M_I_CPU0_SB_DQ<30>")
	)
	(arc
		(start 383.701798 -292.39337)
		(mid 383.984754 -292.469547)
		(end 384.26771 -292.39337)
		(width 0.0889)
		(layer "In2.Cu")
		(net "M_I_CPU0_SB_DQ<30>")
	)
	(arc
		(start 379.001782 -292.39337)
		(mid 379.284738 -292.469547)
		(end 379.567694 -292.39337)
		(width 0.0889)
		(layer "In2.Cu")
		(net "M_I_CPU0_SB_DQ<30>")
	)
	(arc
		(start 387.46176 -292.39337)
		(mid 387.744716 -292.469547)
		(end 388.027672 -292.39337)
		(width 0.0889)
		(layer "In2.Cu")
		(net "M_I_CPU0_SB_DQ<30>")
	)
	(arc
		(start 391.253472 -294.03167)
		(mid 391.368148 -294.165004)
		(end 391.409428 -294.335962)
		(width 0.0889)
		(layer "In2.Cu")
		(net "M_I_CPU0_SB_DQ<30>")
	)
	(arc
		(start 379.567694 -292.39337)
		(mid 379.749945 -292.34302)
		(end 379.933454 -292.388544)
		(width 0.0889)
		(layer "In2.Cu")
		(net "M_I_CPU0_SB_DQ<30>")
	)
	(arc
		(start 391.723372 -294.841676)
		(mid 391.838048 -294.97501)
		(end 391.879328 -295.145968)
		(width 0.0889)
		(layer "In2.Cu")
		(net "M_I_CPU0_SB_DQ<30>")
	)
	(arc
		(start 385.581906 -292.39337)
		(mid 385.864862 -292.469547)
		(end 386.147818 -292.39337)
		(width 0.0889)
		(layer "In2.Cu")
		(net "M_I_CPU0_SB_DQ<30>")
	)
	(arc
		(start 390.939528 -293.525956)
		(mid 391.004764 -293.789547)
		(end 391.1854 -293.9923)
		(width 0.0889)
		(layer "In2.Cu")
		(net "M_I_CPU0_SB_DQ<30>")
	)
	(arc
		(start 384.26771 -292.39337)
		(mid 384.449961 -292.34302)
		(end 384.63347 -292.388544)
		(width 0.0889)
		(layer "In2.Cu")
		(net "M_I_CPU0_SB_DQ<30>")
	)
	(arc
		(start 388.401814 -292.39337)
		(mid 388.68477 -292.469547)
		(end 388.967726 -292.39337)
		(width 0.0889)
		(layer "In2.Cu")
		(net "M_I_CPU0_SB_DQ<30>")
	)
	(arc
		(start 377.743212 -292.367208)
		(mid 377.905544 -292.34439)
		(end 378.061982 -292.39337)
		(width 0.0889)
		(layer "In2.Cu")
		(net "M_I_CPU0_SB_DQ<30>")
	)
	(arc
		(start 382.387856 -292.39337)
		(mid 382.5748 -292.343115)
		(end 382.761744 -292.39337)
		(width 0.0889)
		(layer "In2.Cu")
		(net "M_I_CPU0_SB_DQ<30>")
	)
	(arc
		(start 380.88189 -292.39337)
		(mid 381.164846 -292.469547)
		(end 381.447802 -292.39337)
		(width 0.0889)
		(layer "In2.Cu")
		(net "M_I_CPU0_SB_DQ<30>")
	)
	(arc
		(start 389.341868 -292.39337)
		(mid 389.624824 -292.469547)
		(end 389.90778 -292.39337)
		(width 0.0889)
		(layer "In2.Cu")
		(net "M_I_CPU0_SB_DQ<30>")
	)
	(arc
		(start 390.312402 -292.41115)
		(mid 390.427829 -292.544526)
		(end 390.469374 -292.71595)
		(width 0.0889)
		(layer "In2.Cu")
		(net "M_I_CPU0_SB_DQ<30>")
	)
	(arc
		(start 383.327656 -292.39337)
		(mid 383.509907 -292.34302)
		(end 383.693416 -292.388544)
		(width 0.0889)
		(layer "In2.Cu")
		(net "M_I_CPU0_SB_DQ<30>")
	)
	(arc
		(start 389.916162 -292.388544)
		(mid 390.09967 -292.34305)
		(end 390.281922 -292.39337)
		(width 0.0889)
		(layer "In2.Cu")
		(net "M_I_CPU0_SB_DQ<30>")
	)
	(arc
		(start 387.087872 -292.39337)
		(mid 387.274816 -292.343115)
		(end 387.46176 -292.39337)
		(width 0.0889)
		(layer "In2.Cu")
		(net "M_I_CPU0_SB_DQ<30>")
	)
	(arc
		(start 378.061982 -292.39337)
		(mid 378.344938 -292.469547)
		(end 378.627894 -292.39337)
		(width 0.0889)
		(layer "In2.Cu")
		(net "M_I_CPU0_SB_DQ<30>")
	)
	(arc
		(start 390.783572 -293.221664)
		(mid 390.898248 -293.354998)
		(end 390.939528 -293.525956)
		(width 0.0889)
		(layer "In2.Cu")
		(net "M_I_CPU0_SB_DQ<30>")
	)
	(arc
		(start 379.941836 -292.39337)
		(mid 380.224792 -292.469547)
		(end 380.507748 -292.39337)
		(width 0.0889)
		(layer "In2.Cu")
		(net "M_I_CPU0_SB_DQ<30>")
	)
	(arc
		(start 392.194288 -295.652444)
		(mid 392.308217 -295.785591)
		(end 392.349228 -295.955974)
		(width 0.0889)
		(layer "In2.Cu")
		(net "M_I_CPU0_SB_DQ<30>")
	)
	(arc
		(start 381.456184 -292.388544)
		(mid 381.639692 -292.34305)
		(end 381.821944 -292.39337)
		(width 0.0889)
		(layer "In2.Cu")
		(net "M_I_CPU0_SB_DQ<30>")
	)
	(arc
		(start 381.821944 -292.39337)
		(mid 382.1049 -292.469547)
		(end 382.387856 -292.39337)
		(width 0.0889)
		(layer "In2.Cu")
		(net "M_I_CPU0_SB_DQ<30>")
	)
	(arc
		(start 386.52196 -292.39337)
		(mid 386.804916 -292.469547)
		(end 387.087872 -292.39337)
		(width 0.0889)
		(layer "In2.Cu")
		(net "M_I_CPU0_SB_DQ<30>")
	)
	(arc
		(start 384.641852 -292.39337)
		(mid 384.924808 -292.469547)
		(end 385.207764 -292.39337)
		(width 0.0889)
		(layer "In2.Cu")
		(net "M_I_CPU0_SB_DQ<30>")
	)
	(arc
		(start 386.1562 -292.388544)
		(mid 386.339708 -292.34305)
		(end 386.52196 -292.39337)
		(width 0.0889)
		(layer "In2.Cu")
		(net "M_I_CPU0_SB_DQ<30>")
	)
	(arc
		(start 388.027672 -292.39337)
		(mid 388.209923 -292.34302)
		(end 388.393432 -292.388544)
		(width 0.0889)
		(layer "In2.Cu")
		(net "M_I_CPU0_SB_DQ<30>")
	)
	(arc
		(start 388.967726 -292.39337)
		(mid 389.149977 -292.34302)
		(end 389.333486 -292.388544)
		(width 0.0889)
		(layer "In2.Cu")
		(net "M_I_CPU0_SB_DQ<30>")
	)
	(arc
		(start 391.879328 -295.145968)
		(mid 391.944564 -295.409559)
		(end 392.1252 -295.612312)
		(width 0.0889)
		(layer "In2.Cu")
		(net "M_I_CPU0_SB_DQ<30>")
	)
	(arc
		(start 382.761744 -292.39337)
		(mid 383.0447 -292.469547)
		(end 383.327656 -292.39337)
		(width 0.0889)
		(layer "In2.Cu")
		(net "M_I_CPU0_SB_DQ<30>")
	)
	(arc
		(start 391.409428 -294.335962)
		(mid 391.474664 -294.599553)
		(end 391.6553 -294.802306)
		(width 0.0889)
		(layer "In2.Cu")
		(net "M_I_CPU0_SB_DQ<30>")
	)
	(arc
		(start 378.627894 -292.39337)
		(mid 378.814838 -292.343115)
		(end 379.001782 -292.39337)
		(width 0.0889)
		(layer "In2.Cu")
		(net "M_I_CPU0_SB_DQ<30>")
	)
	(arc
		(start 380.507748 -292.39337)
		(mid 380.689999 -292.34302)
		(end 380.873508 -292.388544)
		(width 0.0889)
		(layer "In2.Cu")
		(net "M_I_CPU0_SB_DQ<30>")
	)
	(segment
		(start 377.407932 -274.630134)
		(end 377.874784 -274.896072)
		(width 0.10668)
		(layer "F.Cu")
		(net "M_I_CPU0_SB_DQ<2>")
	)
	(segment
		(start 384.63347 -274.568666)
		(end 384.641852 -274.573492)
		(width 0.0889)
		(layer "In2.Cu")
		(net "M_I_CPU0_SB_DQ<2>")
	)
	(segment
		(start 423.10304 -281.910028)
		(end 424.90136 -281.910028)
		(width 0.14478)
		(layer "In2.Cu")
		(net "M_I_CPU0_SB_DQ<2>")
	)
	(segment
		(start 421.649398 -281.787346)
		(end 422.262554 -281.17419)
		(width 0.14478)
		(layer "In2.Cu")
		(net "M_I_CPU0_SB_DQ<2>")
	)
	(segment
		(start 421.042338 -282.394406)
		(end 421.254174 -282.394406)
		(width 0.14478)
		(layer "In2.Cu")
		(net "M_I_CPU0_SB_DQ<2>")
	)
	(segment
		(start 395.988286 -273.39417)
		(end 401.16379 -273.39417)
		(width 0.14478)
		(layer "In2.Cu")
		(net "M_I_CPU0_SB_DQ<2>")
	)
	(segment
		(start 381.447802 -274.573492)
		(end 381.456184 -274.568666)
		(width 0.0889)
		(layer "In2.Cu")
		(net "M_I_CPU0_SB_DQ<2>")
	)
	(segment
		(start 395.183106 -273.64563)
		(end 395.434566 -273.39417)
		(width 0.0889)
		(layer "In2.Cu")
		(net "M_I_CPU0_SB_DQ<2>")
	)
	(segment
		(start 413.47517 -282.6639)
		(end 413.67075 -282.74518)
		(width 0.14478)
		(layer "In2.Cu")
		(net "M_I_CPU0_SB_DQ<2>")
	)
	(segment
		(start 425.533058 -281.53741)
		(end 425.682918 -281.68727)
		(width 0.14478)
		(layer "In2.Cu")
		(net "M_I_CPU0_SB_DQ<2>")
	)
	(segment
		(start 383.693416 -274.568666)
		(end 383.701798 -274.573492)
		(width 0.0889)
		(layer "In2.Cu")
		(net "M_I_CPU0_SB_DQ<2>")
	)
	(segment
		(start 414.753044 -281.567636)
		(end 414.94837 -281.648662)
		(width 0.14478)
		(layer "In2.Cu")
		(net "M_I_CPU0_SB_DQ<2>")
	)
	(segment
		(start 413.67075 -282.74518)
		(end 413.75076 -282.937966)
		(width 0.14478)
		(layer "In2.Cu")
		(net "M_I_CPU0_SB_DQ<2>")
	)
	(segment
		(start 388.393432 -274.568666)
		(end 388.401814 -274.573492)
		(width 0.0889)
		(layer "In2.Cu")
		(net "M_I_CPU0_SB_DQ<2>")
	)
	(segment
		(start 395.434566 -273.39417)
		(end 395.988286 -273.39417)
		(width 0.0889)
		(layer "In2.Cu")
		(net "M_I_CPU0_SB_DQ<2>")
	)
	(segment
		(start 426.650658 -281.53741)
		(end 427.023276 -281.910028)
		(width 0.14478)
		(layer "In2.Cu")
		(net "M_I_CPU0_SB_DQ<2>")
	)
	(segment
		(start 414.94837 -281.648662)
		(end 415.0233 -281.829256)
		(width 0.14478)
		(layer "In2.Cu")
		(net "M_I_CPU0_SB_DQ<2>")
	)
	(segment
		(start 414.518094 -282.070048)
		(end 414.431988 -281.86253)
		(width 0.14478)
		(layer "In2.Cu")
		(net "M_I_CPU0_SB_DQ<2>")
	)
	(segment
		(start 393.774168 -274.567396)
		(end 394.695934 -273.64563)
		(width 0.0889)
		(layer "In2.Cu")
		(net "M_I_CPU0_SB_DQ<2>")
	)
	(segment
		(start 425.682918 -282.132786)
		(end 425.832778 -282.282646)
		(width 0.14478)
		(layer "In2.Cu")
		(net "M_I_CPU0_SB_DQ<2>")
	)
	(segment
		(start 422.80078 -281.17419)
		(end 422.95064 -281.32405)
		(width 0.14478)
		(layer "In2.Cu")
		(net "M_I_CPU0_SB_DQ<2>")
	)
	(segment
		(start 392.153394 -274.568666)
		(end 392.161776 -274.573492)
		(width 0.0889)
		(layer "In2.Cu")
		(net "M_I_CPU0_SB_DQ<2>")
	)
	(segment
		(start 421.82034 -282.748482)
		(end 422.003728 -282.565094)
		(width 0.14478)
		(layer "In2.Cu")
		(net "M_I_CPU0_SB_DQ<2>")
	)
	(segment
		(start 380.873508 -274.568666)
		(end 380.88189 -274.573492)
		(width 0.0889)
		(layer "In2.Cu")
		(net "M_I_CPU0_SB_DQ<2>")
	)
	(segment
		(start 377.874784 -274.896072)
		(end 377.72086 -274.630642)
		(width 0.0889)
		(layer "In2.Cu")
		(net "M_I_CPU0_SB_DQ<2>")
	)
	(segment
		(start 426.241718 -281.68727)
		(end 426.391578 -281.53741)
		(width 0.14478)
		(layer "In2.Cu")
		(net "M_I_CPU0_SB_DQ<2>")
	)
	(segment
		(start 421.608504 -282.748482)
		(end 421.82034 -282.748482)
		(width 0.14478)
		(layer "In2.Cu")
		(net "M_I_CPU0_SB_DQ<2>")
	)
	(segment
		(start 426.241718 -282.132786)
		(end 426.241718 -281.68727)
		(width 0.14478)
		(layer "In2.Cu")
		(net "M_I_CPU0_SB_DQ<2>")
	)
	(segment
		(start 414.185862 -282.919932)
		(end 414.267142 -282.724098)
		(width 0.14478)
		(layer "In2.Cu")
		(net "M_I_CPU0_SB_DQ<2>")
	)
	(segment
		(start 426.091858 -282.282646)
		(end 426.241718 -282.132786)
		(width 0.14478)
		(layer "In2.Cu")
		(net "M_I_CPU0_SB_DQ<2>")
	)
	(segment
		(start 425.832778 -282.282646)
		(end 426.091858 -282.282646)
		(width 0.14478)
		(layer "In2.Cu")
		(net "M_I_CPU0_SB_DQ<2>")
	)
	(segment
		(start 427.023276 -281.910028)
		(end 427.03115 -281.910028)
		(width 0.14478)
		(layer "In2.Cu")
		(net "M_I_CPU0_SB_DQ<2>")
	)
	(segment
		(start 389.90778 -274.573492)
		(end 389.916162 -274.568666)
		(width 0.0889)
		(layer "In2.Cu")
		(net "M_I_CPU0_SB_DQ<2>")
	)
	(segment
		(start 414.431988 -281.86253)
		(end 414.513268 -281.667204)
		(width 0.14478)
		(layer "In2.Cu")
		(net "M_I_CPU0_SB_DQ<2>")
	)
	(segment
		(start 427.03115 -281.910028)
		(end 427.456092 -282.33497)
		(width 0.14478)
		(layer "In2.Cu")
		(net "M_I_CPU0_SB_DQ<2>")
	)
	(segment
		(start 393.670282 -274.610576)
		(end 393.774168 -274.567396)
		(width 0.0889)
		(layer "In2.Cu")
		(net "M_I_CPU0_SB_DQ<2>")
	)
	(segment
		(start 386.147818 -274.573492)
		(end 386.1562 -274.568666)
		(width 0.0889)
		(layer "In2.Cu")
		(net "M_I_CPU0_SB_DQ<2>")
	)
	(segment
		(start 415.0233 -281.829256)
		(end 415.219134 -281.910028)
		(width 0.14478)
		(layer "In2.Cu")
		(net "M_I_CPU0_SB_DQ<2>")
	)
	(segment
		(start 414.267142 -282.724098)
		(end 414.187132 -282.531312)
		(width 0.14478)
		(layer "In2.Cu")
		(net "M_I_CPU0_SB_DQ<2>")
	)
	(segment
		(start 393.102338 -274.573746)
		(end 393.118086 -274.58289)
		(width 0.0889)
		(layer "In2.Cu")
		(net "M_I_CPU0_SB_DQ<2>")
	)
	(segment
		(start 414.187132 -282.531312)
		(end 414.268412 -282.335478)
		(width 0.14478)
		(layer "In2.Cu")
		(net "M_I_CPU0_SB_DQ<2>")
	)
	(segment
		(start 417.928298 -281.910028)
		(end 418.778436 -282.760166)
		(width 0.14478)
		(layer "In2.Cu")
		(net "M_I_CPU0_SB_DQ<2>")
	)
	(segment
		(start 379.933454 -274.568666)
		(end 379.941836 -274.573492)
		(width 0.0889)
		(layer "In2.Cu")
		(net "M_I_CPU0_SB_DQ<2>")
	)
	(segment
		(start 422.262554 -281.17419)
		(end 422.80078 -281.17419)
		(width 0.14478)
		(layer "In2.Cu")
		(net "M_I_CPU0_SB_DQ<2>")
	)
	(segment
		(start 385.207764 -274.573492)
		(end 385.216146 -274.568666)
		(width 0.0889)
		(layer "In2.Cu")
		(net "M_I_CPU0_SB_DQ<2>")
	)
	(segment
		(start 392.161776 -274.573492)
		(end 392.176508 -274.582128)
		(width 0.0889)
		(layer "In2.Cu")
		(net "M_I_CPU0_SB_DQ<2>")
	)
	(segment
		(start 422.003728 -282.353258)
		(end 421.649398 -281.999182)
		(width 0.14478)
		(layer "In2.Cu")
		(net "M_I_CPU0_SB_DQ<2>")
	)
	(segment
		(start 413.75076 -282.937966)
		(end 413.94634 -283.019246)
		(width 0.14478)
		(layer "In2.Cu")
		(net "M_I_CPU0_SB_DQ<2>")
	)
	(segment
		(start 407.193496 -278.57958)
		(end 411.374082 -282.760166)
		(width 0.14478)
		(layer "In2.Cu")
		(net "M_I_CPU0_SB_DQ<2>")
	)
	(segment
		(start 413.94634 -283.019246)
		(end 414.185862 -282.919932)
		(width 0.14478)
		(layer "In2.Cu")
		(net "M_I_CPU0_SB_DQ<2>")
	)
	(segment
		(start 415.219134 -281.910028)
		(end 417.928298 -281.910028)
		(width 0.14478)
		(layer "In2.Cu")
		(net "M_I_CPU0_SB_DQ<2>")
	)
	(segment
		(start 422.003728 -282.565094)
		(end 422.003728 -282.353258)
		(width 0.14478)
		(layer "In2.Cu")
		(net "M_I_CPU0_SB_DQ<2>")
	)
	(segment
		(start 422.95064 -281.32405)
		(end 422.95064 -281.757628)
		(width 0.14478)
		(layer "In2.Cu")
		(net "M_I_CPU0_SB_DQ<2>")
	)
	(segment
		(start 425.273978 -281.53741)
		(end 425.533058 -281.53741)
		(width 0.14478)
		(layer "In2.Cu")
		(net "M_I_CPU0_SB_DQ<2>")
	)
	(segment
		(start 418.778436 -282.760166)
		(end 420.676578 -282.760166)
		(width 0.14478)
		(layer "In2.Cu")
		(net "M_I_CPU0_SB_DQ<2>")
	)
	(segment
		(start 393.08405 -274.563332)
		(end 393.102338 -274.573746)
		(width 0.0889)
		(layer "In2.Cu")
		(net "M_I_CPU0_SB_DQ<2>")
	)
	(segment
		(start 377.72086 -274.630642)
		(end 377.743212 -274.54733)
		(width 0.0889)
		(layer "In2.Cu")
		(net "M_I_CPU0_SB_DQ<2>")
	)
	(segment
		(start 414.436814 -282.265628)
		(end 414.518094 -282.070048)
		(width 0.14478)
		(layer "In2.Cu")
		(net "M_I_CPU0_SB_DQ<2>")
	)
	(segment
		(start 413.243014 -282.760166)
		(end 413.47517 -282.6639)
		(width 0.14478)
		(layer "In2.Cu")
		(net "M_I_CPU0_SB_DQ<2>")
	)
	(segment
		(start 401.16379 -273.39417)
		(end 406.3492 -278.57958)
		(width 0.14478)
		(layer "In2.Cu")
		(net "M_I_CPU0_SB_DQ<2>")
	)
	(segment
		(start 421.254174 -282.394406)
		(end 421.608504 -282.748482)
		(width 0.14478)
		(layer "In2.Cu")
		(net "M_I_CPU0_SB_DQ<2>")
	)
	(segment
		(start 424.90136 -281.910028)
		(end 425.273978 -281.53741)
		(width 0.14478)
		(layer "In2.Cu")
		(net "M_I_CPU0_SB_DQ<2>")
	)
	(segment
		(start 394.695934 -273.64563)
		(end 395.183106 -273.64563)
		(width 0.0889)
		(layer "In2.Cu")
		(net "M_I_CPU0_SB_DQ<2>")
	)
	(segment
		(start 426.391578 -281.53741)
		(end 426.650658 -281.53741)
		(width 0.14478)
		(layer "In2.Cu")
		(net "M_I_CPU0_SB_DQ<2>")
	)
	(segment
		(start 411.374082 -282.760166)
		(end 413.243014 -282.760166)
		(width 0.14478)
		(layer "In2.Cu")
		(net "M_I_CPU0_SB_DQ<2>")
	)
	(segment
		(start 414.513268 -281.667204)
		(end 414.753044 -281.567636)
		(width 0.14478)
		(layer "In2.Cu")
		(net "M_I_CPU0_SB_DQ<2>")
	)
	(segment
		(start 425.682918 -281.68727)
		(end 425.682918 -282.132786)
		(width 0.14478)
		(layer "In2.Cu")
		(net "M_I_CPU0_SB_DQ<2>")
	)
	(segment
		(start 389.333486 -274.568666)
		(end 389.341868 -274.573492)
		(width 0.0889)
		(layer "In2.Cu")
		(net "M_I_CPU0_SB_DQ<2>")
	)
	(segment
		(start 422.95064 -281.757628)
		(end 423.10304 -281.910028)
		(width 0.14478)
		(layer "In2.Cu")
		(net "M_I_CPU0_SB_DQ<2>")
	)
	(segment
		(start 420.676578 -282.760166)
		(end 421.042338 -282.394406)
		(width 0.14478)
		(layer "In2.Cu")
		(net "M_I_CPU0_SB_DQ<2>")
	)
	(segment
		(start 421.649398 -281.999182)
		(end 421.649398 -281.787346)
		(width 0.14478)
		(layer "In2.Cu")
		(net "M_I_CPU0_SB_DQ<2>")
	)
	(segment
		(start 414.268412 -282.335478)
		(end 414.436814 -282.265628)
		(width 0.14478)
		(layer "In2.Cu")
		(net "M_I_CPU0_SB_DQ<2>")
	)
	(segment
		(start 406.3492 -278.57958)
		(end 407.193496 -278.57958)
		(width 0.14478)
		(layer "In2.Cu")
		(net "M_I_CPU0_SB_DQ<2>")
	)
	(arc
		(start 389.341868 -274.573492)
		(mid 389.624824 -274.649669)
		(end 389.90778 -274.573492)
		(width 0.0889)
		(layer "In2.Cu")
		(net "M_I_CPU0_SB_DQ<2>")
	)
	(arc
		(start 379.941836 -274.573492)
		(mid 380.224792 -274.649669)
		(end 380.507748 -274.573492)
		(width 0.0889)
		(layer "In2.Cu")
		(net "M_I_CPU0_SB_DQ<2>")
	)
	(arc
		(start 377.743212 -274.54733)
		(mid 377.905544 -274.524512)
		(end 378.061982 -274.573492)
		(width 0.0889)
		(layer "In2.Cu")
		(net "M_I_CPU0_SB_DQ<2>")
	)
	(arc
		(start 379.567694 -274.573492)
		(mid 379.749945 -274.523142)
		(end 379.933454 -274.568666)
		(width 0.0889)
		(layer "In2.Cu")
		(net "M_I_CPU0_SB_DQ<2>")
	)
	(arc
		(start 381.821944 -274.573492)
		(mid 382.1049 -274.649669)
		(end 382.387856 -274.573492)
		(width 0.0889)
		(layer "In2.Cu")
		(net "M_I_CPU0_SB_DQ<2>")
	)
	(arc
		(start 379.001782 -274.573492)
		(mid 379.284738 -274.649669)
		(end 379.567694 -274.573492)
		(width 0.0889)
		(layer "In2.Cu")
		(net "M_I_CPU0_SB_DQ<2>")
	)
	(arc
		(start 386.1562 -274.568666)
		(mid 386.339708 -274.523172)
		(end 386.52196 -274.573492)
		(width 0.0889)
		(layer "In2.Cu")
		(net "M_I_CPU0_SB_DQ<2>")
	)
	(arc
		(start 380.88189 -274.573492)
		(mid 381.164846 -274.649669)
		(end 381.447802 -274.573492)
		(width 0.0889)
		(layer "In2.Cu")
		(net "M_I_CPU0_SB_DQ<2>")
	)
	(arc
		(start 381.456184 -274.568666)
		(mid 381.639692 -274.523172)
		(end 381.821944 -274.573492)
		(width 0.0889)
		(layer "In2.Cu")
		(net "M_I_CPU0_SB_DQ<2>")
	)
	(arc
		(start 388.967726 -274.573492)
		(mid 389.149977 -274.523142)
		(end 389.333486 -274.568666)
		(width 0.0889)
		(layer "In2.Cu")
		(net "M_I_CPU0_SB_DQ<2>")
	)
	(arc
		(start 384.26771 -274.573492)
		(mid 384.449961 -274.523142)
		(end 384.63347 -274.568666)
		(width 0.0889)
		(layer "In2.Cu")
		(net "M_I_CPU0_SB_DQ<2>")
	)
	(arc
		(start 390.847834 -274.573492)
		(mid 391.034778 -274.523237)
		(end 391.221722 -274.573492)
		(width 0.0889)
		(layer "In2.Cu")
		(net "M_I_CPU0_SB_DQ<2>")
	)
	(arc
		(start 387.46176 -274.573492)
		(mid 387.744716 -274.649669)
		(end 388.027672 -274.573492)
		(width 0.0889)
		(layer "In2.Cu")
		(net "M_I_CPU0_SB_DQ<2>")
	)
	(arc
		(start 380.507748 -274.573492)
		(mid 380.689999 -274.523142)
		(end 380.873508 -274.568666)
		(width 0.0889)
		(layer "In2.Cu")
		(net "M_I_CPU0_SB_DQ<2>")
	)
	(arc
		(start 385.216146 -274.568666)
		(mid 385.399654 -274.523172)
		(end 385.581906 -274.573492)
		(width 0.0889)
		(layer "In2.Cu")
		(net "M_I_CPU0_SB_DQ<2>")
	)
	(arc
		(start 383.701798 -274.573492)
		(mid 383.984754 -274.649669)
		(end 384.26771 -274.573492)
		(width 0.0889)
		(layer "In2.Cu")
		(net "M_I_CPU0_SB_DQ<2>")
	)
	(arc
		(start 391.787634 -274.573492)
		(mid 391.969885 -274.523142)
		(end 392.153394 -274.568666)
		(width 0.0889)
		(layer "In2.Cu")
		(net "M_I_CPU0_SB_DQ<2>")
	)
	(arc
		(start 392.728196 -274.573492)
		(mid 392.904824 -274.523259)
		(end 393.08405 -274.563332)
		(width 0.0889)
		(layer "In2.Cu")
		(net "M_I_CPU0_SB_DQ<2>")
	)
	(arc
		(start 390.281922 -274.573492)
		(mid 390.564878 -274.649669)
		(end 390.847834 -274.573492)
		(width 0.0889)
		(layer "In2.Cu")
		(net "M_I_CPU0_SB_DQ<2>")
	)
	(arc
		(start 392.176508 -274.582128)
		(mid 392.453491 -274.649932)
		(end 392.728196 -274.573492)
		(width 0.0889)
		(layer "In2.Cu")
		(net "M_I_CPU0_SB_DQ<2>")
	)
	(arc
		(start 385.581906 -274.573492)
		(mid 385.864862 -274.649669)
		(end 386.147818 -274.573492)
		(width 0.0889)
		(layer "In2.Cu")
		(net "M_I_CPU0_SB_DQ<2>")
	)
	(arc
		(start 389.916162 -274.568666)
		(mid 390.09967 -274.523172)
		(end 390.281922 -274.573492)
		(width 0.0889)
		(layer "In2.Cu")
		(net "M_I_CPU0_SB_DQ<2>")
	)
	(arc
		(start 387.087872 -274.573492)
		(mid 387.274816 -274.523237)
		(end 387.46176 -274.573492)
		(width 0.0889)
		(layer "In2.Cu")
		(net "M_I_CPU0_SB_DQ<2>")
	)
	(arc
		(start 383.327656 -274.573492)
		(mid 383.509907 -274.523142)
		(end 383.693416 -274.568666)
		(width 0.0889)
		(layer "In2.Cu")
		(net "M_I_CPU0_SB_DQ<2>")
	)
	(arc
		(start 393.118086 -274.58289)
		(mid 393.391069 -274.65891)
		(end 393.670282 -274.610576)
		(width 0.0889)
		(layer "In2.Cu")
		(net "M_I_CPU0_SB_DQ<2>")
	)
	(arc
		(start 384.641852 -274.573492)
		(mid 384.924808 -274.649669)
		(end 385.207764 -274.573492)
		(width 0.0889)
		(layer "In2.Cu")
		(net "M_I_CPU0_SB_DQ<2>")
	)
	(arc
		(start 382.761744 -274.573492)
		(mid 383.0447 -274.649669)
		(end 383.327656 -274.573492)
		(width 0.0889)
		(layer "In2.Cu")
		(net "M_I_CPU0_SB_DQ<2>")
	)
	(arc
		(start 378.061982 -274.573492)
		(mid 378.344938 -274.649669)
		(end 378.627894 -274.573492)
		(width 0.0889)
		(layer "In2.Cu")
		(net "M_I_CPU0_SB_DQ<2>")
	)
	(arc
		(start 382.387856 -274.573492)
		(mid 382.5748 -274.523237)
		(end 382.761744 -274.573492)
		(width 0.0889)
		(layer "In2.Cu")
		(net "M_I_CPU0_SB_DQ<2>")
	)
	(arc
		(start 388.401814 -274.573492)
		(mid 388.68477 -274.649669)
		(end 388.967726 -274.573492)
		(width 0.0889)
		(layer "In2.Cu")
		(net "M_I_CPU0_SB_DQ<2>")
	)
	(arc
		(start 386.52196 -274.573492)
		(mid 386.804916 -274.649669)
		(end 387.087872 -274.573492)
		(width 0.0889)
		(layer "In2.Cu")
		(net "M_I_CPU0_SB_DQ<2>")
	)
	(arc
		(start 388.027672 -274.573492)
		(mid 388.209923 -274.523142)
		(end 388.393432 -274.568666)
		(width 0.0889)
		(layer "In2.Cu")
		(net "M_I_CPU0_SB_DQ<2>")
	)
	(arc
		(start 391.221722 -274.573492)
		(mid 391.504678 -274.649669)
		(end 391.787634 -274.573492)
		(width 0.0889)
		(layer "In2.Cu")
		(net "M_I_CPU0_SB_DQ<2>")
	)
	(arc
		(start 378.627894 -274.573492)
		(mid 378.814838 -274.523237)
		(end 379.001782 -274.573492)
		(width 0.0889)
		(layer "In2.Cu")
		(net "M_I_CPU0_SB_DQ<2>")
	)
	(segment
		(start 375.528078 -292.450012)
		(end 375.99493 -292.71595)
		(width 0.10668)
		(layer "F.Cu")
		(net "M_I_CPU0_SB_DQ<29>")
	)
	(segment
		(start 375.99493 -292.71595)
		(end 376.148854 -292.98138)
		(width 0.0889)
		(layer "In2.Cu")
		(net "M_I_CPU0_SB_DQ<29>")
	)
	(segment
		(start 388.393432 -293.043356)
		(end 388.394448 -293.042848)
		(width 0.0889)
		(layer "In2.Cu")
		(net "M_I_CPU0_SB_DQ<29>")
	)
	(segment
		(start 431.130964 -317.610236)
		(end 431.55616 -317.18504)
		(width 0.14478)
		(layer "In2.Cu")
		(net "M_I_CPU0_SB_DQ<29>")
	)
	(segment
		(start 383.693416 -293.043356)
		(end 383.701798 -293.03853)
		(width 0.0889)
		(layer "In2.Cu")
		(net "M_I_CPU0_SB_DQ<29>")
	)
	(segment
		(start 380.873508 -293.043356)
		(end 380.88189 -293.03853)
		(width 0.0889)
		(layer "In2.Cu")
		(net "M_I_CPU0_SB_DQ<29>")
	)
	(segment
		(start 389.333486 -293.043356)
		(end 389.341868 -293.03853)
		(width 0.0889)
		(layer "In2.Cu")
		(net "M_I_CPU0_SB_DQ<29>")
	)
	(segment
		(start 390.816084 -294.640254)
		(end 390.847834 -294.658542)
		(width 0.0889)
		(layer "In2.Cu")
		(net "M_I_CPU0_SB_DQ<29>")
	)
	(segment
		(start 376.148854 -292.98138)
		(end 376.244866 -293.00678)
		(width 0.0889)
		(layer "In2.Cu")
		(net "M_I_CPU0_SB_DQ<29>")
	)
	(segment
		(start 384.63347 -293.043356)
		(end 384.641852 -293.03853)
		(width 0.0889)
		(layer "In2.Cu")
		(net "M_I_CPU0_SB_DQ<29>")
	)
	(segment
		(start 379.933454 -293.043356)
		(end 379.941836 -293.03853)
		(width 0.0889)
		(layer "In2.Cu")
		(net "M_I_CPU0_SB_DQ<29>")
	)
	(segment
		(start 390.847834 -294.658542)
		(end 390.884156 -294.679624)
		(width 0.0889)
		(layer "In2.Cu")
		(net "M_I_CPU0_SB_DQ<29>")
	)
	(segment
		(start 408.583892 -316.703456)
		(end 410.773118 -317.610236)
		(width 0.14478)
		(layer "In2.Cu")
		(net "M_I_CPU0_SB_DQ<29>")
	)
	(segment
		(start 405.106886 -313.22645)
		(end 408.583892 -316.703456)
		(width 0.14478)
		(layer "In2.Cu")
		(net "M_I_CPU0_SB_DQ<29>")
	)
	(segment
		(start 405.106886 -312.481722)
		(end 405.106886 -313.22645)
		(width 0.14478)
		(layer "In2.Cu")
		(net "M_I_CPU0_SB_DQ<29>")
	)
	(segment
		(start 385.207764 -293.03853)
		(end 385.216146 -293.043356)
		(width 0.0889)
		(layer "In2.Cu")
		(net "M_I_CPU0_SB_DQ<29>")
	)
	(segment
		(start 391.754614 -296.624502)
		(end 391.754614 -297.120056)
		(width 0.14478)
		(layer "In2.Cu")
		(net "M_I_CPU0_SB_DQ<29>")
	)
	(segment
		(start 389.90778 -293.03853)
		(end 389.946896 -293.06139)
		(width 0.0889)
		(layer "In2.Cu")
		(net "M_I_CPU0_SB_DQ<29>")
	)
	(segment
		(start 376.747786 -293.03853)
		(end 376.756168 -293.043356)
		(width 0.0889)
		(layer "In2.Cu")
		(net "M_I_CPU0_SB_DQ<29>")
	)
	(segment
		(start 391.317734 -295.468548)
		(end 391.354056 -295.48963)
		(width 0.0889)
		(layer "In2.Cu")
		(net "M_I_CPU0_SB_DQ<29>")
	)
	(segment
		(start 391.285984 -295.45026)
		(end 391.317734 -295.468548)
		(width 0.0889)
		(layer "In2.Cu")
		(net "M_I_CPU0_SB_DQ<29>")
	)
	(segment
		(start 377.68784 -293.03853)
		(end 377.696222 -293.043356)
		(width 0.0889)
		(layer "In2.Cu")
		(net "M_I_CPU0_SB_DQ<29>")
	)
	(segment
		(start 381.447802 -293.03853)
		(end 381.456184 -293.043356)
		(width 0.0889)
		(layer "In2.Cu")
		(net "M_I_CPU0_SB_DQ<29>")
	)
	(segment
		(start 410.773118 -317.610236)
		(end 431.130964 -317.610236)
		(width 0.14478)
		(layer "In2.Cu")
		(net "M_I_CPU0_SB_DQ<29>")
	)
	(segment
		(start 391.599928 -296.469816)
		(end 391.754614 -296.624502)
		(width 0.0889)
		(layer "In2.Cu")
		(net "M_I_CPU0_SB_DQ<29>")
	)
	(segment
		(start 390.3472 -293.830756)
		(end 390.37768 -293.848536)
		(width 0.0889)
		(layer "In2.Cu")
		(net "M_I_CPU0_SB_DQ<29>")
	)
	(segment
		(start 390.37768 -293.848536)
		(end 390.416796 -293.871396)
		(width 0.0889)
		(layer "In2.Cu")
		(net "M_I_CPU0_SB_DQ<29>")
	)
	(segment
		(start 388.394448 -293.042848)
		(end 388.401814 -293.03853)
		(width 0.0889)
		(layer "In2.Cu")
		(net "M_I_CPU0_SB_DQ<29>")
	)
	(segment
		(start 391.599928 -295.955974)
		(end 391.599928 -296.469816)
		(width 0.0889)
		(layer "In2.Cu")
		(net "M_I_CPU0_SB_DQ<29>")
	)
	(segment
		(start 391.754614 -297.120056)
		(end 393.175236 -300.550072)
		(width 0.14478)
		(layer "In2.Cu")
		(net "M_I_CPU0_SB_DQ<29>")
	)
	(segment
		(start 393.175236 -300.550072)
		(end 405.106886 -312.481722)
		(width 0.14478)
		(layer "In2.Cu")
		(net "M_I_CPU0_SB_DQ<29>")
	)
	(segment
		(start 386.147818 -293.03853)
		(end 386.1562 -293.043356)
		(width 0.0889)
		(layer "In2.Cu")
		(net "M_I_CPU0_SB_DQ<29>")
	)
	(arc
		(start 379.001782 -293.03853)
		(mid 379.284738 -292.962353)
		(end 379.567694 -293.03853)
		(width 0.0889)
		(layer "In2.Cu")
		(net "M_I_CPU0_SB_DQ<29>")
	)
	(arc
		(start 384.26771 -293.03853)
		(mid 384.449961 -293.08888)
		(end 384.63347 -293.043356)
		(width 0.0889)
		(layer "In2.Cu")
		(net "M_I_CPU0_SB_DQ<29>")
	)
	(arc
		(start 390.190228 -293.525956)
		(mid 390.231777 -293.697378)
		(end 390.3472 -293.830756)
		(width 0.0889)
		(layer "In2.Cu")
		(net "M_I_CPU0_SB_DQ<29>")
	)
	(arc
		(start 391.130028 -295.145968)
		(mid 391.171283 -295.316939)
		(end 391.285984 -295.45026)
		(width 0.0889)
		(layer "In2.Cu")
		(net "M_I_CPU0_SB_DQ<29>")
	)
	(arc
		(start 381.821944 -293.03853)
		(mid 382.1049 -292.962353)
		(end 382.387856 -293.03853)
		(width 0.0889)
		(layer "In2.Cu")
		(net "M_I_CPU0_SB_DQ<29>")
	)
	(arc
		(start 376.756168 -293.043356)
		(mid 376.939676 -293.08885)
		(end 377.121928 -293.03853)
		(width 0.0889)
		(layer "In2.Cu")
		(net "M_I_CPU0_SB_DQ<29>")
	)
	(arc
		(start 385.216146 -293.043356)
		(mid 385.399654 -293.08885)
		(end 385.581906 -293.03853)
		(width 0.0889)
		(layer "In2.Cu")
		(net "M_I_CPU0_SB_DQ<29>")
	)
	(arc
		(start 390.884156 -294.679624)
		(mid 391.064808 -294.882369)
		(end 391.130028 -295.145968)
		(width 0.0889)
		(layer "In2.Cu")
		(net "M_I_CPU0_SB_DQ<29>")
	)
	(arc
		(start 387.087872 -293.03853)
		(mid 387.274816 -293.088785)
		(end 387.46176 -293.03853)
		(width 0.0889)
		(layer "In2.Cu")
		(net "M_I_CPU0_SB_DQ<29>")
	)
	(arc
		(start 380.507748 -293.03853)
		(mid 380.689999 -293.08888)
		(end 380.873508 -293.043356)
		(width 0.0889)
		(layer "In2.Cu")
		(net "M_I_CPU0_SB_DQ<29>")
	)
	(arc
		(start 382.761744 -293.03853)
		(mid 383.0447 -292.962353)
		(end 383.327656 -293.03853)
		(width 0.0889)
		(layer "In2.Cu")
		(net "M_I_CPU0_SB_DQ<29>")
	)
	(arc
		(start 390.416796 -293.871396)
		(mid 390.595609 -294.073746)
		(end 390.660128 -294.335962)
		(width 0.0889)
		(layer "In2.Cu")
		(net "M_I_CPU0_SB_DQ<29>")
	)
	(arc
		(start 383.701798 -293.03853)
		(mid 383.984754 -292.962353)
		(end 384.26771 -293.03853)
		(width 0.0889)
		(layer "In2.Cu")
		(net "M_I_CPU0_SB_DQ<29>")
	)
	(arc
		(start 385.581906 -293.03853)
		(mid 385.864862 -292.962353)
		(end 386.147818 -293.03853)
		(width 0.0889)
		(layer "In2.Cu")
		(net "M_I_CPU0_SB_DQ<29>")
	)
	(arc
		(start 389.946896 -293.06139)
		(mid 390.125709 -293.26374)
		(end 390.190228 -293.525956)
		(width 0.0889)
		(layer "In2.Cu")
		(net "M_I_CPU0_SB_DQ<29>")
	)
	(arc
		(start 387.46176 -293.03853)
		(mid 387.744716 -292.962353)
		(end 388.027672 -293.03853)
		(width 0.0889)
		(layer "In2.Cu")
		(net "M_I_CPU0_SB_DQ<29>")
	)
	(arc
		(start 379.941836 -293.03853)
		(mid 380.224792 -292.962353)
		(end 380.507748 -293.03853)
		(width 0.0889)
		(layer "In2.Cu")
		(net "M_I_CPU0_SB_DQ<29>")
	)
	(arc
		(start 390.660128 -294.335962)
		(mid 390.701383 -294.506933)
		(end 390.816084 -294.640254)
		(width 0.0889)
		(layer "In2.Cu")
		(net "M_I_CPU0_SB_DQ<29>")
	)
	(arc
		(start 382.387856 -293.03853)
		(mid 382.5748 -293.088785)
		(end 382.761744 -293.03853)
		(width 0.0889)
		(layer "In2.Cu")
		(net "M_I_CPU0_SB_DQ<29>")
	)
	(arc
		(start 383.327656 -293.03853)
		(mid 383.509907 -293.08888)
		(end 383.693416 -293.043356)
		(width 0.0889)
		(layer "In2.Cu")
		(net "M_I_CPU0_SB_DQ<29>")
	)
	(arc
		(start 386.1562 -293.043356)
		(mid 386.339708 -293.08885)
		(end 386.52196 -293.03853)
		(width 0.0889)
		(layer "In2.Cu")
		(net "M_I_CPU0_SB_DQ<29>")
	)
	(arc
		(start 388.401814 -293.03853)
		(mid 388.68477 -292.962353)
		(end 388.967726 -293.03853)
		(width 0.0889)
		(layer "In2.Cu")
		(net "M_I_CPU0_SB_DQ<29>")
	)
	(arc
		(start 378.627894 -293.03853)
		(mid 378.814838 -293.088785)
		(end 379.001782 -293.03853)
		(width 0.0889)
		(layer "In2.Cu")
		(net "M_I_CPU0_SB_DQ<29>")
	)
	(arc
		(start 388.027672 -293.03853)
		(mid 388.209923 -293.08888)
		(end 388.393432 -293.043356)
		(width 0.0889)
		(layer "In2.Cu")
		(net "M_I_CPU0_SB_DQ<29>")
	)
	(arc
		(start 388.967726 -293.03853)
		(mid 389.149977 -293.08888)
		(end 389.333486 -293.043356)
		(width 0.0889)
		(layer "In2.Cu")
		(net "M_I_CPU0_SB_DQ<29>")
	)
	(arc
		(start 386.52196 -293.03853)
		(mid 386.804916 -292.962353)
		(end 387.087872 -293.03853)
		(width 0.0889)
		(layer "In2.Cu")
		(net "M_I_CPU0_SB_DQ<29>")
	)
	(arc
		(start 391.354056 -295.48963)
		(mid 391.534708 -295.692375)
		(end 391.599928 -295.955974)
		(width 0.0889)
		(layer "In2.Cu")
		(net "M_I_CPU0_SB_DQ<29>")
	)
	(arc
		(start 381.456184 -293.043356)
		(mid 381.639692 -293.08885)
		(end 381.821944 -293.03853)
		(width 0.0889)
		(layer "In2.Cu")
		(net "M_I_CPU0_SB_DQ<29>")
	)
	(arc
		(start 377.121928 -293.03853)
		(mid 377.404884 -292.962353)
		(end 377.68784 -293.03853)
		(width 0.0889)
		(layer "In2.Cu")
		(net "M_I_CPU0_SB_DQ<29>")
	)
	(arc
		(start 379.567694 -293.03853)
		(mid 379.749945 -293.08888)
		(end 379.933454 -293.043356)
		(width 0.0889)
		(layer "In2.Cu")
		(net "M_I_CPU0_SB_DQ<29>")
	)
	(arc
		(start 389.341868 -293.03853)
		(mid 389.624824 -292.962353)
		(end 389.90778 -293.03853)
		(width 0.0889)
		(layer "In2.Cu")
		(net "M_I_CPU0_SB_DQ<29>")
	)
	(arc
		(start 376.244866 -293.00678)
		(mid 376.500074 -292.963303)
		(end 376.747786 -293.03853)
		(width 0.0889)
		(layer "In2.Cu")
		(net "M_I_CPU0_SB_DQ<29>")
	)
	(arc
		(start 384.641852 -293.03853)
		(mid 384.924808 -292.962353)
		(end 385.207764 -293.03853)
		(width 0.0889)
		(layer "In2.Cu")
		(net "M_I_CPU0_SB_DQ<29>")
	)
	(arc
		(start 377.696222 -293.043356)
		(mid 377.87973 -293.08885)
		(end 378.061982 -293.03853)
		(width 0.0889)
		(layer "In2.Cu")
		(net "M_I_CPU0_SB_DQ<29>")
	)
	(arc
		(start 380.88189 -293.03853)
		(mid 381.164846 -292.962353)
		(end 381.447802 -293.03853)
		(width 0.0889)
		(layer "In2.Cu")
		(net "M_I_CPU0_SB_DQ<29>")
	)
	(arc
		(start 378.061982 -293.03853)
		(mid 378.344938 -292.962353)
		(end 378.627894 -293.03853)
		(width 0.0889)
		(layer "In2.Cu")
		(net "M_I_CPU0_SB_DQ<29>")
	)
	(segment
		(start 376.938032 -291.640006)
		(end 377.404884 -291.905944)
		(width 0.10668)
		(layer "F.Cu")
		(net "M_I_CPU0_SB_DQ<28>")
	)
	(segment
		(start 430.420272 -316.595252)
		(end 430.581816 -316.433708)
		(width 0.14478)
		(layer "In2.Cu")
		(net "M_I_CPU0_SB_DQ<28>")
	)
	(segment
		(start 429.089058 -316.595252)
		(end 429.317404 -316.595252)
		(width 0.14478)
		(layer "In2.Cu")
		(net "M_I_CPU0_SB_DQ<28>")
	)
	(segment
		(start 429.478948 -316.433708)
		(end 429.478948 -316.08141)
		(width 0.14478)
		(layer "In2.Cu")
		(net "M_I_CPU0_SB_DQ<28>")
	)
	(segment
		(start 392.672062 -296.907966)
		(end 393.991592 -300.093888)
		(width 0.14478)
		(layer "In2.Cu")
		(net "M_I_CPU0_SB_DQ<28>")
	)
	(segment
		(start 392.672062 -296.413936)
		(end 392.672062 -296.907966)
		(width 0.14478)
		(layer "In2.Cu")
		(net "M_I_CPU0_SB_DQ<28>")
	)
	(segment
		(start 393.991592 -300.093888)
		(end 409.81757 -315.919866)
		(width 0.14478)
		(layer "In2.Cu")
		(net "M_I_CPU0_SB_DQ<28>")
	)
	(segment
		(start 390.816084 -293.020242)
		(end 390.847834 -293.03853)
		(width 0.0889)
		(layer "In2.Cu")
		(net "M_I_CPU0_SB_DQ<28>")
	)
	(segment
		(start 430.581816 -316.08141)
		(end 430.74336 -315.919866)
		(width 0.14478)
		(layer "In2.Cu")
		(net "M_I_CPU0_SB_DQ<28>")
	)
	(segment
		(start 430.191926 -316.595252)
		(end 430.420272 -316.595252)
		(width 0.14478)
		(layer "In2.Cu")
		(net "M_I_CPU0_SB_DQ<28>")
	)
	(segment
		(start 431.121312 -315.919866)
		(end 431.55616 -315.485018)
		(width 0.14478)
		(layer "In2.Cu")
		(net "M_I_CPU0_SB_DQ<28>")
	)
	(segment
		(start 391.755884 -294.640254)
		(end 391.787634 -294.658542)
		(width 0.0889)
		(layer "In2.Cu")
		(net "M_I_CPU0_SB_DQ<28>")
	)
	(segment
		(start 379.097794 -292.228524)
		(end 379.106176 -292.23335)
		(width 0.0889)
		(layer "In2.Cu")
		(net "M_I_CPU0_SB_DQ<28>")
	)
	(segment
		(start 429.478948 -316.08141)
		(end 429.640492 -315.919866)
		(width 0.14478)
		(layer "In2.Cu")
		(net "M_I_CPU0_SB_DQ<28>")
	)
	(segment
		(start 392.2268 -295.450768)
		(end 392.25728 -295.468548)
		(width 0.0889)
		(layer "In2.Cu")
		(net "M_I_CPU0_SB_DQ<28>")
	)
	(segment
		(start 391.285984 -293.830248)
		(end 391.317734 -293.848536)
		(width 0.0889)
		(layer "In2.Cu")
		(net "M_I_CPU0_SB_DQ<28>")
	)
	(segment
		(start 429.317404 -316.595252)
		(end 429.478948 -316.433708)
		(width 0.14478)
		(layer "In2.Cu")
		(net "M_I_CPU0_SB_DQ<28>")
	)
	(segment
		(start 429.868838 -315.919866)
		(end 430.030382 -316.08141)
		(width 0.14478)
		(layer "In2.Cu")
		(net "M_I_CPU0_SB_DQ<28>")
	)
	(segment
		(start 387.557772 -292.228524)
		(end 387.566154 -292.23335)
		(width 0.0889)
		(layer "In2.Cu")
		(net "M_I_CPU0_SB_DQ<28>")
	)
	(segment
		(start 428.76597 -315.919866)
		(end 428.927514 -316.08141)
		(width 0.14478)
		(layer "In2.Cu")
		(net "M_I_CPU0_SB_DQ<28>")
	)
	(segment
		(start 377.558808 -292.171374)
		(end 377.65482 -292.196774)
		(width 0.0889)
		(layer "In2.Cu")
		(net "M_I_CPU0_SB_DQ<28>")
	)
	(segment
		(start 391.317734 -293.848536)
		(end 391.354056 -293.869618)
		(width 0.0889)
		(layer "In2.Cu")
		(net "M_I_CPU0_SB_DQ<28>")
	)
	(segment
		(start 380.037848 -292.228524)
		(end 380.04623 -292.23335)
		(width 0.0889)
		(layer "In2.Cu")
		(net "M_I_CPU0_SB_DQ<28>")
	)
	(segment
		(start 409.81757 -315.919866)
		(end 428.76597 -315.919866)
		(width 0.14478)
		(layer "In2.Cu")
		(net "M_I_CPU0_SB_DQ<28>")
	)
	(segment
		(start 392.539982 -295.955974)
		(end 392.539982 -296.281856)
		(width 0.0889)
		(layer "In2.Cu")
		(net "M_I_CPU0_SB_DQ<28>")
	)
	(segment
		(start 430.581816 -316.433708)
		(end 430.581816 -316.08141)
		(width 0.14478)
		(layer "In2.Cu")
		(net "M_I_CPU0_SB_DQ<28>")
	)
	(segment
		(start 428.927514 -316.08141)
		(end 428.927514 -316.433708)
		(width 0.14478)
		(layer "In2.Cu")
		(net "M_I_CPU0_SB_DQ<28>")
	)
	(segment
		(start 428.927514 -316.433708)
		(end 429.089058 -316.595252)
		(width 0.14478)
		(layer "In2.Cu")
		(net "M_I_CPU0_SB_DQ<28>")
	)
	(segment
		(start 430.74336 -315.919866)
		(end 431.121312 -315.919866)
		(width 0.14478)
		(layer "In2.Cu")
		(net "M_I_CPU0_SB_DQ<28>")
	)
	(segment
		(start 382.857756 -292.228524)
		(end 382.866138 -292.23335)
		(width 0.0889)
		(layer "In2.Cu")
		(net "M_I_CPU0_SB_DQ<28>")
	)
	(segment
		(start 429.640492 -315.919866)
		(end 429.868838 -315.919866)
		(width 0.14478)
		(layer "In2.Cu")
		(net "M_I_CPU0_SB_DQ<28>")
	)
	(segment
		(start 383.79781 -292.228524)
		(end 383.806192 -292.23335)
		(width 0.0889)
		(layer "In2.Cu")
		(net "M_I_CPU0_SB_DQ<28>")
	)
	(segment
		(start 392.539982 -296.281856)
		(end 392.672062 -296.413936)
		(width 0.0889)
		(layer "In2.Cu")
		(net "M_I_CPU0_SB_DQ<28>")
	)
	(segment
		(start 430.030382 -316.08141)
		(end 430.030382 -316.433708)
		(width 0.14478)
		(layer "In2.Cu")
		(net "M_I_CPU0_SB_DQ<28>")
	)
	(segment
		(start 430.030382 -316.433708)
		(end 430.191926 -316.595252)
		(width 0.14478)
		(layer "In2.Cu")
		(net "M_I_CPU0_SB_DQ<28>")
	)
	(segment
		(start 382.283462 -292.23335)
		(end 382.291844 -292.228524)
		(width 0.0889)
		(layer "In2.Cu")
		(net "M_I_CPU0_SB_DQ<28>")
	)
	(segment
		(start 386.983478 -292.23335)
		(end 386.99186 -292.228524)
		(width 0.0889)
		(layer "In2.Cu")
		(net "M_I_CPU0_SB_DQ<28>")
	)
	(segment
		(start 386.043424 -292.23335)
		(end 386.051806 -292.228524)
		(width 0.0889)
		(layer "In2.Cu")
		(net "M_I_CPU0_SB_DQ<28>")
	)
	(segment
		(start 390.847834 -293.03853)
		(end 390.884156 -293.059612)
		(width 0.0889)
		(layer "In2.Cu")
		(net "M_I_CPU0_SB_DQ<28>")
	)
	(segment
		(start 388.497826 -292.228524)
		(end 388.506208 -292.23335)
		(width 0.0889)
		(layer "In2.Cu")
		(net "M_I_CPU0_SB_DQ<28>")
	)
	(segment
		(start 390.37768 -292.228524)
		(end 390.416796 -292.251384)
		(width 0.0889)
		(layer "In2.Cu")
		(net "M_I_CPU0_SB_DQ<28>")
	)
	(segment
		(start 391.787634 -294.658542)
		(end 391.823956 -294.679624)
		(width 0.0889)
		(layer "In2.Cu")
		(net "M_I_CPU0_SB_DQ<28>")
	)
	(segment
		(start 377.404884 -291.905944)
		(end 377.558808 -292.171374)
		(width 0.0889)
		(layer "In2.Cu")
		(net "M_I_CPU0_SB_DQ<28>")
	)
	(segment
		(start 378.5235 -292.23335)
		(end 378.531882 -292.228524)
		(width 0.0889)
		(layer "In2.Cu")
		(net "M_I_CPU0_SB_DQ<28>")
	)
	(segment
		(start 392.25728 -295.468548)
		(end 392.29919 -295.492932)
		(width 0.0889)
		(layer "In2.Cu")
		(net "M_I_CPU0_SB_DQ<28>")
	)
	(arc
		(start 390.884156 -293.059612)
		(mid 391.064808 -293.262357)
		(end 391.130028 -293.525956)
		(width 0.0889)
		(layer "In2.Cu")
		(net "M_I_CPU0_SB_DQ<28>")
	)
	(arc
		(start 382.866138 -292.23335)
		(mid 383.049646 -292.278844)
		(end 383.231898 -292.228524)
		(width 0.0889)
		(layer "In2.Cu")
		(net "M_I_CPU0_SB_DQ<28>")
	)
	(arc
		(start 378.531882 -292.228524)
		(mid 378.814838 -292.152347)
		(end 379.097794 -292.228524)
		(width 0.0889)
		(layer "In2.Cu")
		(net "M_I_CPU0_SB_DQ<28>")
	)
	(arc
		(start 389.43788 -292.228524)
		(mid 389.624824 -292.278779)
		(end 389.811768 -292.228524)
		(width 0.0889)
		(layer "In2.Cu")
		(net "M_I_CPU0_SB_DQ<28>")
	)
	(arc
		(start 377.65482 -292.196774)
		(mid 377.910028 -292.153297)
		(end 378.15774 -292.228524)
		(width 0.0889)
		(layer "In2.Cu")
		(net "M_I_CPU0_SB_DQ<28>")
	)
	(arc
		(start 391.823956 -294.679624)
		(mid 392.004608 -294.882369)
		(end 392.069828 -295.145968)
		(width 0.0889)
		(layer "In2.Cu")
		(net "M_I_CPU0_SB_DQ<28>")
	)
	(arc
		(start 384.737864 -292.228524)
		(mid 384.924808 -292.278779)
		(end 385.111752 -292.228524)
		(width 0.0889)
		(layer "In2.Cu")
		(net "M_I_CPU0_SB_DQ<28>")
	)
	(arc
		(start 380.41199 -292.228524)
		(mid 380.694946 -292.152347)
		(end 380.977902 -292.228524)
		(width 0.0889)
		(layer "In2.Cu")
		(net "M_I_CPU0_SB_DQ<28>")
	)
	(arc
		(start 387.566154 -292.23335)
		(mid 387.749662 -292.278844)
		(end 387.931914 -292.228524)
		(width 0.0889)
		(layer "In2.Cu")
		(net "M_I_CPU0_SB_DQ<28>")
	)
	(arc
		(start 392.069828 -295.145968)
		(mid 392.111377 -295.31739)
		(end 392.2268 -295.450768)
		(width 0.0889)
		(layer "In2.Cu")
		(net "M_I_CPU0_SB_DQ<28>")
	)
	(arc
		(start 388.871968 -292.228524)
		(mid 389.154924 -292.152347)
		(end 389.43788 -292.228524)
		(width 0.0889)
		(layer "In2.Cu")
		(net "M_I_CPU0_SB_DQ<28>")
	)
	(arc
		(start 381.917702 -292.228524)
		(mid 382.099953 -292.278874)
		(end 382.283462 -292.23335)
		(width 0.0889)
		(layer "In2.Cu")
		(net "M_I_CPU0_SB_DQ<28>")
	)
	(arc
		(start 390.660128 -292.71595)
		(mid 390.701383 -292.886921)
		(end 390.816084 -293.020242)
		(width 0.0889)
		(layer "In2.Cu")
		(net "M_I_CPU0_SB_DQ<28>")
	)
	(arc
		(start 380.04623 -292.23335)
		(mid 380.229738 -292.278844)
		(end 380.41199 -292.228524)
		(width 0.0889)
		(layer "In2.Cu")
		(net "M_I_CPU0_SB_DQ<28>")
	)
	(arc
		(start 382.291844 -292.228524)
		(mid 382.5748 -292.152347)
		(end 382.857756 -292.228524)
		(width 0.0889)
		(layer "In2.Cu")
		(net "M_I_CPU0_SB_DQ<28>")
	)
	(arc
		(start 391.130028 -293.525956)
		(mid 391.171283 -293.696927)
		(end 391.285984 -293.830248)
		(width 0.0889)
		(layer "In2.Cu")
		(net "M_I_CPU0_SB_DQ<28>")
	)
	(arc
		(start 387.931914 -292.228524)
		(mid 388.21487 -292.152347)
		(end 388.497826 -292.228524)
		(width 0.0889)
		(layer "In2.Cu")
		(net "M_I_CPU0_SB_DQ<28>")
	)
	(arc
		(start 384.171952 -292.228524)
		(mid 384.454908 -292.152347)
		(end 384.737864 -292.228524)
		(width 0.0889)
		(layer "In2.Cu")
		(net "M_I_CPU0_SB_DQ<28>")
	)
	(arc
		(start 383.231898 -292.228524)
		(mid 383.514854 -292.152347)
		(end 383.79781 -292.228524)
		(width 0.0889)
		(layer "In2.Cu")
		(net "M_I_CPU0_SB_DQ<28>")
	)
	(arc
		(start 385.677664 -292.228524)
		(mid 385.859915 -292.278874)
		(end 386.043424 -292.23335)
		(width 0.0889)
		(layer "In2.Cu")
		(net "M_I_CPU0_SB_DQ<28>")
	)
	(arc
		(start 386.99186 -292.228524)
		(mid 387.274816 -292.152347)
		(end 387.557772 -292.228524)
		(width 0.0889)
		(layer "In2.Cu")
		(net "M_I_CPU0_SB_DQ<28>")
	)
	(arc
		(start 379.106176 -292.23335)
		(mid 379.289684 -292.278844)
		(end 379.471936 -292.228524)
		(width 0.0889)
		(layer "In2.Cu")
		(net "M_I_CPU0_SB_DQ<28>")
	)
	(arc
		(start 383.806192 -292.23335)
		(mid 383.9897 -292.278844)
		(end 384.171952 -292.228524)
		(width 0.0889)
		(layer "In2.Cu")
		(net "M_I_CPU0_SB_DQ<28>")
	)
	(arc
		(start 391.354056 -293.869618)
		(mid 391.534708 -294.072363)
		(end 391.599928 -294.335962)
		(width 0.0889)
		(layer "In2.Cu")
		(net "M_I_CPU0_SB_DQ<28>")
	)
	(arc
		(start 380.977902 -292.228524)
		(mid 381.164846 -292.278779)
		(end 381.35179 -292.228524)
		(width 0.0889)
		(layer "In2.Cu")
		(net "M_I_CPU0_SB_DQ<28>")
	)
	(arc
		(start 391.599928 -294.335962)
		(mid 391.641183 -294.506933)
		(end 391.755884 -294.640254)
		(width 0.0889)
		(layer "In2.Cu")
		(net "M_I_CPU0_SB_DQ<28>")
	)
	(arc
		(start 390.416796 -292.251384)
		(mid 390.595609 -292.453734)
		(end 390.660128 -292.71595)
		(width 0.0889)
		(layer "In2.Cu")
		(net "M_I_CPU0_SB_DQ<28>")
	)
	(arc
		(start 388.506208 -292.23335)
		(mid 388.689716 -292.278844)
		(end 388.871968 -292.228524)
		(width 0.0889)
		(layer "In2.Cu")
		(net "M_I_CPU0_SB_DQ<28>")
	)
	(arc
		(start 392.29919 -295.492932)
		(mid 392.476172 -295.695024)
		(end 392.539982 -295.955974)
		(width 0.0889)
		(layer "In2.Cu")
		(net "M_I_CPU0_SB_DQ<28>")
	)
	(arc
		(start 386.617718 -292.228524)
		(mid 386.799969 -292.278874)
		(end 386.983478 -292.23335)
		(width 0.0889)
		(layer "In2.Cu")
		(net "M_I_CPU0_SB_DQ<28>")
	)
	(arc
		(start 379.471936 -292.228524)
		(mid 379.754892 -292.152347)
		(end 380.037848 -292.228524)
		(width 0.0889)
		(layer "In2.Cu")
		(net "M_I_CPU0_SB_DQ<28>")
	)
	(arc
		(start 386.051806 -292.228524)
		(mid 386.334762 -292.152347)
		(end 386.617718 -292.228524)
		(width 0.0889)
		(layer "In2.Cu")
		(net "M_I_CPU0_SB_DQ<28>")
	)
	(arc
		(start 381.35179 -292.228524)
		(mid 381.634746 -292.152347)
		(end 381.917702 -292.228524)
		(width 0.0889)
		(layer "In2.Cu")
		(net "M_I_CPU0_SB_DQ<28>")
	)
	(arc
		(start 385.111752 -292.228524)
		(mid 385.394708 -292.152347)
		(end 385.677664 -292.228524)
		(width 0.0889)
		(layer "In2.Cu")
		(net "M_I_CPU0_SB_DQ<28>")
	)
	(arc
		(start 389.811768 -292.228524)
		(mid 390.094724 -292.152347)
		(end 390.37768 -292.228524)
		(width 0.0889)
		(layer "In2.Cu")
		(net "M_I_CPU0_SB_DQ<28>")
	)
	(arc
		(start 378.15774 -292.228524)
		(mid 378.339991 -292.278874)
		(end 378.5235 -292.23335)
		(width 0.0889)
		(layer "In2.Cu")
		(net "M_I_CPU0_SB_DQ<28>")
	)
	(segment
		(start 375.997978 -290.019994)
		(end 376.46483 -290.285932)
		(width 0.10668)
		(layer "F.Cu")
		(net "M_I_CPU0_SB_DQ<27>")
	)
	(segment
		(start 404.55469 -306.810664)
		(end 404.782782 -306.810664)
		(width 0.14478)
		(layer "In2.Cu")
		(net "M_I_CPU0_SB_DQ<27>")
	)
	(segment
		(start 404.135844 -307.001164)
		(end 404.36419 -307.001164)
		(width 0.14478)
		(layer "In2.Cu")
		(net "M_I_CPU0_SB_DQ<27>")
	)
	(segment
		(start 414.274762 -312.057542)
		(end 414.681924 -311.65038)
		(width 0.14478)
		(layer "In2.Cu")
		(net "M_I_CPU0_SB_DQ<27>")
	)
	(segment
		(start 414.681924 -311.65038)
		(end 418.083746 -311.65038)
		(width 0.14478)
		(layer "In2.Cu")
		(net "M_I_CPU0_SB_DQ<27>")
	)
	(segment
		(start 411.269434 -312.293762)
		(end 411.475936 -312.500264)
		(width 0.14478)
		(layer "In2.Cu")
		(net "M_I_CPU0_SB_DQ<27>")
	)
	(segment
		(start 421.57523 -311.708292)
		(end 421.995854 -311.792366)
		(width 0.14478)
		(layer "In2.Cu")
		(net "M_I_CPU0_SB_DQ<27>")
	)
	(segment
		(start 404.002494 -306.030376)
		(end 404.164546 -306.192428)
		(width 0.14478)
		(layer "In2.Cu")
		(net "M_I_CPU0_SB_DQ<27>")
	)
	(segment
		(start 410.63164 -312.42635)
		(end 410.764228 -312.293762)
		(width 0.14478)
		(layer "In2.Cu")
		(net "M_I_CPU0_SB_DQ<27>")
	)
	(segment
		(start 386.043424 -289.958526)
		(end 386.051806 -289.963352)
		(width 0.0889)
		(layer "In2.Cu")
		(net "M_I_CPU0_SB_DQ<27>")
	)
	(segment
		(start 396.631922 -298.659804)
		(end 403.384258 -305.41214)
		(width 0.14478)
		(layer "In2.Cu")
		(net "M_I_CPU0_SB_DQ<27>")
	)
	(segment
		(start 403.384258 -305.41214)
		(end 403.384258 -305.640232)
		(width 0.14478)
		(layer "In2.Cu")
		(net "M_I_CPU0_SB_DQ<27>")
	)
	(segment
		(start 403.583902 -306.220876)
		(end 403.774402 -306.030376)
		(width 0.14478)
		(layer "In2.Cu")
		(net "M_I_CPU0_SB_DQ<27>")
	)
	(segment
		(start 380.037848 -289.963352)
		(end 380.04623 -289.958526)
		(width 0.0889)
		(layer "In2.Cu")
		(net "M_I_CPU0_SB_DQ<27>")
	)
	(segment
		(start 404.75408 -307.391308)
		(end 404.75408 -307.6194)
		(width 0.14478)
		(layer "In2.Cu")
		(net "M_I_CPU0_SB_DQ<27>")
	)
	(segment
		(start 378.5235 -289.958526)
		(end 378.531882 -289.963352)
		(width 0.0889)
		(layer "In2.Cu")
		(net "M_I_CPU0_SB_DQ<27>")
	)
	(segment
		(start 392.83259 -292.214046)
		(end 393.949428 -293.323518)
		(width 0.0889)
		(layer "In2.Cu")
		(net "M_I_CPU0_SB_DQ<27>")
	)
	(segment
		(start 394.219938 -294.50919)
		(end 394.261848 -294.720264)
		(width 0.0889)
		(layer "In2.Cu")
		(net "M_I_CPU0_SB_DQ<27>")
	)
	(segment
		(start 386.983478 -289.958526)
		(end 386.99186 -289.963352)
		(width 0.0889)
		(layer "In2.Cu")
		(net "M_I_CPU0_SB_DQ<27>")
	)
	(segment
		(start 420.93642 -312.500264)
		(end 421.278812 -312.27141)
		(width 0.14478)
		(layer "In2.Cu")
		(net "M_I_CPU0_SB_DQ<27>")
	)
	(segment
		(start 376.46483 -290.285932)
		(end 376.310906 -290.020502)
		(width 0.0889)
		(layer "In2.Cu")
		(net "M_I_CPU0_SB_DQ<27>")
	)
	(segment
		(start 404.36419 -307.001164)
		(end 404.55469 -306.810664)
		(width 0.14478)
		(layer "In2.Cu")
		(net "M_I_CPU0_SB_DQ<27>")
	)
	(segment
		(start 394.525754 -295.255442)
		(end 395.713712 -296.4434)
		(width 0.14478)
		(layer "In2.Cu")
		(net "M_I_CPU0_SB_DQ<27>")
	)
	(segment
		(start 403.193504 -306.058824)
		(end 403.355556 -306.220876)
		(width 0.14478)
		(layer "In2.Cu")
		(net "M_I_CPU0_SB_DQ<27>")
	)
	(segment
		(start 383.79781 -289.963352)
		(end 383.806192 -289.958526)
		(width 0.0889)
		(layer "In2.Cu")
		(net "M_I_CPU0_SB_DQ<27>")
	)
	(segment
		(start 403.774402 -306.030376)
		(end 404.002494 -306.030376)
		(width 0.14478)
		(layer "In2.Cu")
		(net "M_I_CPU0_SB_DQ<27>")
	)
	(segment
		(start 409.56103 -312.42635)
		(end 410.63164 -312.42635)
		(width 0.14478)
		(layer "In2.Cu")
		(net "M_I_CPU0_SB_DQ<27>")
	)
	(segment
		(start 413.20593 -312.500264)
		(end 414.274762 -312.057542)
		(width 0.14478)
		(layer "In2.Cu")
		(net "M_I_CPU0_SB_DQ<27>")
	)
	(segment
		(start 405.56307 -307.590952)
		(end 405.725122 -307.753004)
		(width 0.14478)
		(layer "In2.Cu")
		(net "M_I_CPU0_SB_DQ<27>")
	)
	(segment
		(start 425.31919 -311.38495)
		(end 425.602908 -311.38495)
		(width 0.14478)
		(layer "In2.Cu")
		(net "M_I_CPU0_SB_DQ<27>")
	)
	(segment
		(start 391.317734 -289.963352)
		(end 391.326116 -289.958526)
		(width 0.0889)
		(layer "In2.Cu")
		(net "M_I_CPU0_SB_DQ<27>")
	)
	(segment
		(start 404.944834 -306.972716)
		(end 404.944834 -307.200808)
		(width 0.14478)
		(layer "In2.Cu")
		(net "M_I_CPU0_SB_DQ<27>")
	)
	(segment
		(start 404.164546 -306.42052)
		(end 403.973792 -306.61102)
		(width 0.14478)
		(layer "In2.Cu")
		(net "M_I_CPU0_SB_DQ<27>")
	)
	(segment
		(start 421.362632 -311.850532)
		(end 421.57523 -311.708292)
		(width 0.14478)
		(layer "In2.Cu")
		(net "M_I_CPU0_SB_DQ<27>")
	)
	(segment
		(start 405.534368 -308.171596)
		(end 405.534368 -308.399688)
		(width 0.14478)
		(layer "In2.Cu")
		(net "M_I_CPU0_SB_DQ<27>")
	)
	(segment
		(start 376.310906 -290.020502)
		(end 376.333258 -289.93719)
		(width 0.0889)
		(layer "In2.Cu")
		(net "M_I_CPU0_SB_DQ<27>")
	)
	(segment
		(start 425.87799 -311.660032)
		(end 427.03115 -311.660032)
		(width 0.14478)
		(layer "In2.Cu")
		(net "M_I_CPU0_SB_DQ<27>")
	)
	(segment
		(start 392.12266 -290.750498)
		(end 392.161776 -290.773358)
		(width 0.0889)
		(layer "In2.Cu")
		(net "M_I_CPU0_SB_DQ<27>")
	)
	(segment
		(start 418.93363 -312.500264)
		(end 420.93642 -312.500264)
		(width 0.14478)
		(layer "In2.Cu")
		(net "M_I_CPU0_SB_DQ<27>")
	)
	(segment
		(start 404.944834 -307.200808)
		(end 404.75408 -307.391308)
		(width 0.14478)
		(layer "In2.Cu")
		(net "M_I_CPU0_SB_DQ<27>")
	)
	(segment
		(start 405.334978 -307.590952)
		(end 405.56307 -307.590952)
		(width 0.14478)
		(layer "In2.Cu")
		(net "M_I_CPU0_SB_DQ<27>")
	)
	(segment
		(start 394.303758 -295.033446)
		(end 394.525754 -295.255442)
		(width 0.0889)
		(layer "In2.Cu")
		(net "M_I_CPU0_SB_DQ<27>")
	)
	(segment
		(start 382.857756 -289.963352)
		(end 382.866138 -289.958526)
		(width 0.0889)
		(layer "In2.Cu")
		(net "M_I_CPU0_SB_DQ<27>")
	)
	(segment
		(start 387.557772 -289.963352)
		(end 387.566154 -289.958526)
		(width 0.0889)
		(layer "In2.Cu")
		(net "M_I_CPU0_SB_DQ<27>")
	)
	(segment
		(start 421.278812 -312.27141)
		(end 421.362632 -311.850532)
		(width 0.14478)
		(layer "In2.Cu")
		(net "M_I_CPU0_SB_DQ<27>")
	)
	(segment
		(start 425.602908 -311.38495)
		(end 425.87799 -311.660032)
		(width 0.14478)
		(layer "In2.Cu")
		(net "M_I_CPU0_SB_DQ<27>")
	)
	(segment
		(start 394.303758 -294.821356)
		(end 394.303758 -295.033446)
		(width 0.0889)
		(layer "In2.Cu")
		(net "M_I_CPU0_SB_DQ<27>")
	)
	(segment
		(start 404.75408 -307.6194)
		(end 404.916132 -307.781452)
		(width 0.14478)
		(layer "In2.Cu")
		(net "M_I_CPU0_SB_DQ<27>")
	)
	(segment
		(start 392.161776 -290.773358)
		(end 392.193526 -290.791646)
		(width 0.0889)
		(layer "In2.Cu")
		(net "M_I_CPU0_SB_DQ<27>")
	)
	(segment
		(start 392.708638 -292.069012)
		(end 392.83259 -292.214046)
		(width 0.0889)
		(layer "In2.Cu")
		(net "M_I_CPU0_SB_DQ<27>")
	)
	(segment
		(start 427.03115 -311.660032)
		(end 427.456092 -312.084974)
		(width 0.14478)
		(layer "In2.Cu")
		(net "M_I_CPU0_SB_DQ<27>")
	)
	(segment
		(start 405.534368 -308.399688)
		(end 409.56103 -312.42635)
		(width 0.14478)
		(layer "In2.Cu")
		(net "M_I_CPU0_SB_DQ<27>")
	)
	(segment
		(start 404.164546 -306.192428)
		(end 404.164546 -306.42052)
		(width 0.14478)
		(layer "In2.Cu")
		(net "M_I_CPU0_SB_DQ<27>")
	)
	(segment
		(start 418.083746 -311.65038)
		(end 418.93363 -312.500264)
		(width 0.14478)
		(layer "In2.Cu")
		(net "M_I_CPU0_SB_DQ<27>")
	)
	(segment
		(start 425.05376 -311.65038)
		(end 425.31919 -311.38495)
		(width 0.14478)
		(layer "In2.Cu")
		(net "M_I_CPU0_SB_DQ<27>")
	)
	(segment
		(start 390.74344 -289.958526)
		(end 390.751822 -289.963352)
		(width 0.0889)
		(layer "In2.Cu")
		(net "M_I_CPU0_SB_DQ<27>")
	)
	(segment
		(start 403.384258 -305.640232)
		(end 403.193504 -305.830732)
		(width 0.14478)
		(layer "In2.Cu")
		(net "M_I_CPU0_SB_DQ<27>")
	)
	(segment
		(start 410.764228 -312.293762)
		(end 411.269434 -312.293762)
		(width 0.14478)
		(layer "In2.Cu")
		(net "M_I_CPU0_SB_DQ<27>")
	)
	(segment
		(start 411.475936 -312.500264)
		(end 413.20593 -312.500264)
		(width 0.14478)
		(layer "In2.Cu")
		(net "M_I_CPU0_SB_DQ<27>")
	)
	(segment
		(start 421.995854 -311.792366)
		(end 422.208452 -311.65038)
		(width 0.14478)
		(layer "In2.Cu")
		(net "M_I_CPU0_SB_DQ<27>")
	)
	(segment
		(start 377.583446 -289.958526)
		(end 377.591828 -289.963352)
		(width 0.0889)
		(layer "In2.Cu")
		(net "M_I_CPU0_SB_DQ<27>")
	)
	(segment
		(start 388.497826 -289.963352)
		(end 388.506208 -289.958526)
		(width 0.0889)
		(layer "In2.Cu")
		(net "M_I_CPU0_SB_DQ<27>")
	)
	(segment
		(start 391.691876 -289.963352)
		(end 391.722356 -289.981132)
		(width 0.0889)
		(layer "In2.Cu")
		(net "M_I_CPU0_SB_DQ<27>")
	)
	(segment
		(start 379.097794 -289.963352)
		(end 379.106176 -289.958526)
		(width 0.0889)
		(layer "In2.Cu")
		(net "M_I_CPU0_SB_DQ<27>")
	)
	(segment
		(start 404.782782 -306.810664)
		(end 404.944834 -306.972716)
		(width 0.14478)
		(layer "In2.Cu")
		(net "M_I_CPU0_SB_DQ<27>")
	)
	(segment
		(start 394.219938 -293.88308)
		(end 394.219938 -294.50919)
		(width 0.0889)
		(layer "In2.Cu")
		(net "M_I_CPU0_SB_DQ<27>")
	)
	(segment
		(start 405.725122 -307.753004)
		(end 405.725122 -307.981096)
		(width 0.14478)
		(layer "In2.Cu")
		(net "M_I_CPU0_SB_DQ<27>")
	)
	(segment
		(start 404.916132 -307.781452)
		(end 405.144478 -307.781452)
		(width 0.14478)
		(layer "In2.Cu")
		(net "M_I_CPU0_SB_DQ<27>")
	)
	(segment
		(start 394.261848 -294.720264)
		(end 394.303758 -294.821356)
		(width 0.0889)
		(layer "In2.Cu")
		(net "M_I_CPU0_SB_DQ<27>")
	)
	(segment
		(start 422.208452 -311.65038)
		(end 425.05376 -311.65038)
		(width 0.14478)
		(layer "In2.Cu")
		(net "M_I_CPU0_SB_DQ<27>")
	)
	(segment
		(start 403.193504 -305.830732)
		(end 403.193504 -306.058824)
		(width 0.14478)
		(layer "In2.Cu")
		(net "M_I_CPU0_SB_DQ<27>")
	)
	(segment
		(start 403.355556 -306.220876)
		(end 403.583902 -306.220876)
		(width 0.14478)
		(layer "In2.Cu")
		(net "M_I_CPU0_SB_DQ<27>")
	)
	(segment
		(start 403.973792 -306.839112)
		(end 404.135844 -307.001164)
		(width 0.14478)
		(layer "In2.Cu")
		(net "M_I_CPU0_SB_DQ<27>")
	)
	(segment
		(start 395.713712 -296.4434)
		(end 396.631922 -298.659804)
		(width 0.14478)
		(layer "In2.Cu")
		(net "M_I_CPU0_SB_DQ<27>")
	)
	(segment
		(start 405.725122 -307.981096)
		(end 405.534368 -308.171596)
		(width 0.14478)
		(layer "In2.Cu")
		(net "M_I_CPU0_SB_DQ<27>")
	)
	(segment
		(start 403.973792 -306.61102)
		(end 403.973792 -306.839112)
		(width 0.14478)
		(layer "In2.Cu")
		(net "M_I_CPU0_SB_DQ<27>")
	)
	(segment
		(start 405.144478 -307.781452)
		(end 405.334978 -307.590952)
		(width 0.14478)
		(layer "In2.Cu")
		(net "M_I_CPU0_SB_DQ<27>")
	)
	(segment
		(start 382.283462 -289.958526)
		(end 382.291844 -289.963352)
		(width 0.0889)
		(layer "In2.Cu")
		(net "M_I_CPU0_SB_DQ<27>")
	)
	(arc
		(start 381.35179 -289.963352)
		(mid 381.634746 -290.039529)
		(end 381.917702 -289.963352)
		(width 0.0889)
		(layer "In2.Cu")
		(net "M_I_CPU0_SB_DQ<27>")
	)
	(arc
		(start 388.506208 -289.958526)
		(mid 388.689716 -289.913032)
		(end 388.871968 -289.963352)
		(width 0.0889)
		(layer "In2.Cu")
		(net "M_I_CPU0_SB_DQ<27>")
	)
	(arc
		(start 380.04623 -289.958526)
		(mid 380.229738 -289.913032)
		(end 380.41199 -289.963352)
		(width 0.0889)
		(layer "In2.Cu")
		(net "M_I_CPU0_SB_DQ<27>")
	)
	(arc
		(start 391.722356 -289.981132)
		(mid 391.837783 -290.114508)
		(end 391.879328 -290.285932)
		(width 0.0889)
		(layer "In2.Cu")
		(net "M_I_CPU0_SB_DQ<27>")
	)
	(arc
		(start 392.349482 -291.095938)
		(mid 392.442133 -291.614561)
		(end 392.708638 -292.069012)
		(width 0.0889)
		(layer "In2.Cu")
		(net "M_I_CPU0_SB_DQ<27>")
	)
	(arc
		(start 384.737864 -289.963352)
		(mid 384.924808 -289.913097)
		(end 385.111752 -289.963352)
		(width 0.0889)
		(layer "In2.Cu")
		(net "M_I_CPU0_SB_DQ<27>")
	)
	(arc
		(start 387.566154 -289.958526)
		(mid 387.749662 -289.913032)
		(end 387.931914 -289.963352)
		(width 0.0889)
		(layer "In2.Cu")
		(net "M_I_CPU0_SB_DQ<27>")
	)
	(arc
		(start 389.43788 -289.963352)
		(mid 389.624824 -289.913097)
		(end 389.811768 -289.963352)
		(width 0.0889)
		(layer "In2.Cu")
		(net "M_I_CPU0_SB_DQ<27>")
	)
	(arc
		(start 389.811768 -289.963352)
		(mid 390.094724 -290.039529)
		(end 390.37768 -289.963352)
		(width 0.0889)
		(layer "In2.Cu")
		(net "M_I_CPU0_SB_DQ<27>")
	)
	(arc
		(start 378.531882 -289.963352)
		(mid 378.814838 -290.039529)
		(end 379.097794 -289.963352)
		(width 0.0889)
		(layer "In2.Cu")
		(net "M_I_CPU0_SB_DQ<27>")
	)
	(arc
		(start 384.171952 -289.963352)
		(mid 384.454908 -290.039529)
		(end 384.737864 -289.963352)
		(width 0.0889)
		(layer "In2.Cu")
		(net "M_I_CPU0_SB_DQ<27>")
	)
	(arc
		(start 376.333258 -289.93719)
		(mid 376.495447 -289.914455)
		(end 376.651774 -289.963352)
		(width 0.0889)
		(layer "In2.Cu")
		(net "M_I_CPU0_SB_DQ<27>")
	)
	(arc
		(start 383.806192 -289.958526)
		(mid 383.9897 -289.913032)
		(end 384.171952 -289.963352)
		(width 0.0889)
		(layer "In2.Cu")
		(net "M_I_CPU0_SB_DQ<27>")
	)
	(arc
		(start 386.617718 -289.963352)
		(mid 386.799969 -289.913002)
		(end 386.983478 -289.958526)
		(width 0.0889)
		(layer "In2.Cu")
		(net "M_I_CPU0_SB_DQ<27>")
	)
	(arc
		(start 383.231898 -289.963352)
		(mid 383.514854 -290.039529)
		(end 383.79781 -289.963352)
		(width 0.0889)
		(layer "In2.Cu")
		(net "M_I_CPU0_SB_DQ<27>")
	)
	(arc
		(start 387.931914 -289.963352)
		(mid 388.21487 -290.039529)
		(end 388.497826 -289.963352)
		(width 0.0889)
		(layer "In2.Cu")
		(net "M_I_CPU0_SB_DQ<27>")
	)
	(arc
		(start 376.651774 -289.963352)
		(mid 376.93473 -290.039529)
		(end 377.217686 -289.963352)
		(width 0.0889)
		(layer "In2.Cu")
		(net "M_I_CPU0_SB_DQ<27>")
	)
	(arc
		(start 388.871968 -289.963352)
		(mid 389.154924 -290.039529)
		(end 389.43788 -289.963352)
		(width 0.0889)
		(layer "In2.Cu")
		(net "M_I_CPU0_SB_DQ<27>")
	)
	(arc
		(start 379.106176 -289.958526)
		(mid 379.289684 -289.913032)
		(end 379.471936 -289.963352)
		(width 0.0889)
		(layer "In2.Cu")
		(net "M_I_CPU0_SB_DQ<27>")
	)
	(arc
		(start 380.41199 -289.963352)
		(mid 380.694946 -290.039529)
		(end 380.977902 -289.963352)
		(width 0.0889)
		(layer "In2.Cu")
		(net "M_I_CPU0_SB_DQ<27>")
	)
	(arc
		(start 377.591828 -289.963352)
		(mid 377.874784 -290.039529)
		(end 378.15774 -289.963352)
		(width 0.0889)
		(layer "In2.Cu")
		(net "M_I_CPU0_SB_DQ<27>")
	)
	(arc
		(start 385.677664 -289.963352)
		(mid 385.859915 -289.913002)
		(end 386.043424 -289.958526)
		(width 0.0889)
		(layer "In2.Cu")
		(net "M_I_CPU0_SB_DQ<27>")
	)
	(arc
		(start 391.326116 -289.958526)
		(mid 391.509624 -289.913032)
		(end 391.691876 -289.963352)
		(width 0.0889)
		(layer "In2.Cu")
		(net "M_I_CPU0_SB_DQ<27>")
	)
	(arc
		(start 382.866138 -289.958526)
		(mid 383.049646 -289.913032)
		(end 383.231898 -289.963352)
		(width 0.0889)
		(layer "In2.Cu")
		(net "M_I_CPU0_SB_DQ<27>")
	)
	(arc
		(start 393.949428 -293.323518)
		(mid 394.13201 -293.580422)
		(end 394.219938 -293.88308)
		(width 0.0889)
		(layer "In2.Cu")
		(net "M_I_CPU0_SB_DQ<27>")
	)
	(arc
		(start 386.051806 -289.963352)
		(mid 386.334762 -290.039529)
		(end 386.617718 -289.963352)
		(width 0.0889)
		(layer "In2.Cu")
		(net "M_I_CPU0_SB_DQ<27>")
	)
	(arc
		(start 392.193526 -290.791646)
		(mid 392.308202 -290.92498)
		(end 392.349482 -291.095938)
		(width 0.0889)
		(layer "In2.Cu")
		(net "M_I_CPU0_SB_DQ<27>")
	)
	(arc
		(start 380.977902 -289.963352)
		(mid 381.164846 -289.913097)
		(end 381.35179 -289.963352)
		(width 0.0889)
		(layer "In2.Cu")
		(net "M_I_CPU0_SB_DQ<27>")
	)
	(arc
		(start 381.917702 -289.963352)
		(mid 382.099953 -289.913002)
		(end 382.283462 -289.958526)
		(width 0.0889)
		(layer "In2.Cu")
		(net "M_I_CPU0_SB_DQ<27>")
	)
	(arc
		(start 391.879328 -290.285932)
		(mid 391.943843 -290.548151)
		(end 392.12266 -290.750498)
		(width 0.0889)
		(layer "In2.Cu")
		(net "M_I_CPU0_SB_DQ<27>")
	)
	(arc
		(start 390.751822 -289.963352)
		(mid 391.034778 -290.039529)
		(end 391.317734 -289.963352)
		(width 0.0889)
		(layer "In2.Cu")
		(net "M_I_CPU0_SB_DQ<27>")
	)
	(arc
		(start 385.111752 -289.963352)
		(mid 385.394708 -290.039529)
		(end 385.677664 -289.963352)
		(width 0.0889)
		(layer "In2.Cu")
		(net "M_I_CPU0_SB_DQ<27>")
	)
	(arc
		(start 382.291844 -289.963352)
		(mid 382.5748 -290.039529)
		(end 382.857756 -289.963352)
		(width 0.0889)
		(layer "In2.Cu")
		(net "M_I_CPU0_SB_DQ<27>")
	)
	(arc
		(start 390.37768 -289.963352)
		(mid 390.559931 -289.913002)
		(end 390.74344 -289.958526)
		(width 0.0889)
		(layer "In2.Cu")
		(net "M_I_CPU0_SB_DQ<27>")
	)
	(arc
		(start 378.15774 -289.963352)
		(mid 378.339991 -289.913002)
		(end 378.5235 -289.958526)
		(width 0.0889)
		(layer "In2.Cu")
		(net "M_I_CPU0_SB_DQ<27>")
	)
	(arc
		(start 377.217686 -289.963352)
		(mid 377.399937 -289.913002)
		(end 377.583446 -289.958526)
		(width 0.0889)
		(layer "In2.Cu")
		(net "M_I_CPU0_SB_DQ<27>")
	)
	(arc
		(start 386.99186 -289.963352)
		(mid 387.274816 -290.039529)
		(end 387.557772 -289.963352)
		(width 0.0889)
		(layer "In2.Cu")
		(net "M_I_CPU0_SB_DQ<27>")
	)
	(arc
		(start 379.471936 -289.963352)
		(mid 379.754892 -290.039529)
		(end 380.037848 -289.963352)
		(width 0.0889)
		(layer "In2.Cu")
		(net "M_I_CPU0_SB_DQ<27>")
	)
	(segment
		(start 377.407932 -289.209988)
		(end 377.874784 -289.475926)
		(width 0.10668)
		(layer "F.Cu")
		(net "M_I_CPU0_SB_DQ<26>")
	)
	(segment
		(start 407.617422 -309.210456)
		(end 407.846022 -309.210456)
		(width 0.14478)
		(layer "In2.Cu")
		(net "M_I_CPU0_SB_DQ<26>")
	)
	(segment
		(start 408.832812 -309.784242)
		(end 409.061412 -309.784242)
		(width 0.14478)
		(layer "In2.Cu")
		(net "M_I_CPU0_SB_DQ<26>")
	)
	(segment
		(start 379.933454 -289.14852)
		(end 379.941836 -289.153346)
		(width 0.0889)
		(layer "In2.Cu")
		(net "M_I_CPU0_SB_DQ<26>")
	)
	(segment
		(start 409.016454 -310.380888)
		(end 409.016454 -310.609488)
		(width 0.14478)
		(layer "In2.Cu")
		(net "M_I_CPU0_SB_DQ<26>")
	)
	(segment
		(start 425.557696 -309.796434)
		(end 425.721272 -309.96001)
		(width 0.14478)
		(layer "In2.Cu")
		(net "M_I_CPU0_SB_DQ<26>")
	)
	(segment
		(start 415.079434 -309.96001)
		(end 415.25317 -309.96001)
		(width 0.14478)
		(layer "In2.Cu")
		(net "M_I_CPU0_SB_DQ<26>")
	)
	(segment
		(start 423.023792 -310.23941)
		(end 423.303192 -310.23941)
		(width 0.14478)
		(layer "In2.Cu")
		(net "M_I_CPU0_SB_DQ<26>")
	)
	(segment
		(start 409.222956 -309.945786)
		(end 409.222956 -310.174386)
		(width 0.14478)
		(layer "In2.Cu")
		(net "M_I_CPU0_SB_DQ<26>")
	)
	(segment
		(start 410.087318 -310.810148)
		(end 413.02686 -310.810148)
		(width 0.14478)
		(layer "In2.Cu")
		(net "M_I_CPU0_SB_DQ<26>")
	)
	(segment
		(start 418.666676 -310.810148)
		(end 420.81577 -310.810148)
		(width 0.14478)
		(layer "In2.Cu")
		(net "M_I_CPU0_SB_DQ<26>")
	)
	(segment
		(start 377.874784 -289.475926)
		(end 377.72086 -289.210496)
		(width 0.0889)
		(layer "In2.Cu")
		(net "M_I_CPU0_SB_DQ<26>")
	)
	(segment
		(start 395.209014 -293.815008)
		(end 395.209014 -294.603424)
		(width 0.0889)
		(layer "In2.Cu")
		(net "M_I_CPU0_SB_DQ<26>")
	)
	(segment
		(start 388.393432 -289.14852)
		(end 388.401814 -289.153346)
		(width 0.0889)
		(layer "In2.Cu")
		(net "M_I_CPU0_SB_DQ<26>")
	)
	(segment
		(start 407.455878 -309.048912)
		(end 407.617422 -309.210456)
		(width 0.14478)
		(layer "In2.Cu")
		(net "M_I_CPU0_SB_DQ<26>")
	)
	(segment
		(start 408.281124 -309.003954)
		(end 408.442668 -309.165498)
		(width 0.14478)
		(layer "In2.Cu")
		(net "M_I_CPU0_SB_DQ<26>")
	)
	(segment
		(start 422.744392 -309.96001)
		(end 423.023792 -310.23941)
		(width 0.14478)
		(layer "In2.Cu")
		(net "M_I_CPU0_SB_DQ<26>")
	)
	(segment
		(start 389.333486 -289.14852)
		(end 389.341868 -289.153346)
		(width 0.0889)
		(layer "In2.Cu")
		(net "M_I_CPU0_SB_DQ<26>")
	)
	(segment
		(start 425.721272 -309.96001)
		(end 425.95292 -309.96001)
		(width 0.14478)
		(layer "In2.Cu")
		(net "M_I_CPU0_SB_DQ<26>")
	)
	(segment
		(start 416.09899 -309.96001)
		(end 417.237164 -309.96001)
		(width 0.14478)
		(layer "In2.Cu")
		(net "M_I_CPU0_SB_DQ<26>")
	)
	(segment
		(start 406.837134 -308.430168)
		(end 407.065734 -308.430168)
		(width 0.14478)
		(layer "In2.Cu")
		(net "M_I_CPU0_SB_DQ<26>")
	)
	(segment
		(start 426.24248 -309.67045)
		(end 426.549312 -309.67045)
		(width 0.14478)
		(layer "In2.Cu")
		(net "M_I_CPU0_SB_DQ<26>")
	)
	(segment
		(start 407.66238 -308.38521)
		(end 407.66238 -308.61381)
		(width 0.14478)
		(layer "In2.Cu")
		(net "M_I_CPU0_SB_DQ<26>")
	)
	(segment
		(start 426.549312 -309.67045)
		(end 426.838872 -309.96001)
		(width 0.14478)
		(layer "In2.Cu")
		(net "M_I_CPU0_SB_DQ<26>")
	)
	(segment
		(start 407.846022 -309.210456)
		(end 408.052524 -309.003954)
		(width 0.14478)
		(layer "In2.Cu")
		(net "M_I_CPU0_SB_DQ<26>")
	)
	(segment
		(start 383.693416 -289.14852)
		(end 383.701798 -289.153346)
		(width 0.0889)
		(layer "In2.Cu")
		(net "M_I_CPU0_SB_DQ<26>")
	)
	(segment
		(start 408.39771 -309.990744)
		(end 408.62631 -309.990744)
		(width 0.14478)
		(layer "In2.Cu")
		(net "M_I_CPU0_SB_DQ<26>")
	)
	(segment
		(start 425.162472 -309.42915)
		(end 425.39412 -309.42915)
		(width 0.14478)
		(layer "In2.Cu")
		(net "M_I_CPU0_SB_DQ<26>")
	)
	(segment
		(start 407.272236 -308.223666)
		(end 407.500836 -308.223666)
		(width 0.14478)
		(layer "In2.Cu")
		(net "M_I_CPU0_SB_DQ<26>")
	)
	(segment
		(start 415.81197 -310.24703)
		(end 416.09899 -309.96001)
		(width 0.14478)
		(layer "In2.Cu")
		(net "M_I_CPU0_SB_DQ<26>")
	)
	(segment
		(start 417.237164 -309.96001)
		(end 417.533582 -310.082946)
		(width 0.14478)
		(layer "In2.Cu")
		(net "M_I_CPU0_SB_DQ<26>")
	)
	(segment
		(start 415.54019 -310.24703)
		(end 415.81197 -310.24703)
		(width 0.14478)
		(layer "In2.Cu")
		(net "M_I_CPU0_SB_DQ<26>")
	)
	(segment
		(start 418.477446 -310.731662)
		(end 418.666676 -310.810148)
		(width 0.14478)
		(layer "In2.Cu")
		(net "M_I_CPU0_SB_DQ<26>")
	)
	(segment
		(start 424.998896 -309.796434)
		(end 424.998896 -309.592726)
		(width 0.14478)
		(layer "In2.Cu")
		(net "M_I_CPU0_SB_DQ<26>")
	)
	(segment
		(start 394.398754 -292.596824)
		(end 394.398754 -293.004748)
		(width 0.0889)
		(layer "In2.Cu")
		(net "M_I_CPU0_SB_DQ<26>")
	)
	(segment
		(start 408.236166 -309.8292)
		(end 408.39771 -309.990744)
		(width 0.14478)
		(layer "In2.Cu")
		(net "M_I_CPU0_SB_DQ<26>")
	)
	(segment
		(start 385.207764 -289.153346)
		(end 385.216146 -289.14852)
		(width 0.0889)
		(layer "In2.Cu")
		(net "M_I_CPU0_SB_DQ<26>")
	)
	(segment
		(start 420.81577 -310.810148)
		(end 421.096694 -310.693816)
		(width 0.14478)
		(layer "In2.Cu")
		(net "M_I_CPU0_SB_DQ<26>")
	)
	(segment
		(start 409.177998 -310.771032)
		(end 409.406598 -310.771032)
		(width 0.14478)
		(layer "In2.Cu")
		(net "M_I_CPU0_SB_DQ<26>")
	)
	(segment
		(start 425.39412 -309.42915)
		(end 425.557696 -309.592726)
		(width 0.14478)
		(layer "In2.Cu")
		(net "M_I_CPU0_SB_DQ<26>")
	)
	(segment
		(start 413.02686 -310.810148)
		(end 413.795718 -310.491632)
		(width 0.14478)
		(layer "In2.Cu")
		(net "M_I_CPU0_SB_DQ<26>")
	)
	(segment
		(start 421.096694 -310.693816)
		(end 421.224202 -310.384952)
		(width 0.14478)
		(layer "In2.Cu")
		(net "M_I_CPU0_SB_DQ<26>")
	)
	(segment
		(start 395.209014 -294.603424)
		(end 395.384782 -294.779192)
		(width 0.0889)
		(layer "In2.Cu")
		(net "M_I_CPU0_SB_DQ<26>")
	)
	(segment
		(start 406.882092 -307.604922)
		(end 406.882092 -307.833522)
		(width 0.14478)
		(layer "In2.Cu")
		(net "M_I_CPU0_SB_DQ<26>")
	)
	(segment
		(start 396.456408 -295.850564)
		(end 397.395954 -298.118784)
		(width 0.14478)
		(layer "In2.Cu")
		(net "M_I_CPU0_SB_DQ<26>")
	)
	(segment
		(start 418.17671 -309.989982)
		(end 418.336984 -310.384952)
		(width 0.14478)
		(layer "In2.Cu")
		(net "M_I_CPU0_SB_DQ<26>")
	)
	(segment
		(start 394.398754 -293.004748)
		(end 395.209014 -293.815008)
		(width 0.0889)
		(layer "In2.Cu")
		(net "M_I_CPU0_SB_DQ<26>")
	)
	(segment
		(start 380.873508 -289.14852)
		(end 380.88189 -289.153346)
		(width 0.0889)
		(layer "In2.Cu")
		(net "M_I_CPU0_SB_DQ<26>")
	)
	(segment
		(start 421.953944 -310.21909)
		(end 422.579546 -309.96001)
		(width 0.14478)
		(layer "In2.Cu")
		(net "M_I_CPU0_SB_DQ<26>")
	)
	(segment
		(start 408.052524 -309.003954)
		(end 408.281124 -309.003954)
		(width 0.14478)
		(layer "In2.Cu")
		(net "M_I_CPU0_SB_DQ<26>")
	)
	(segment
		(start 415.25317 -309.96001)
		(end 415.54019 -310.24703)
		(width 0.14478)
		(layer "In2.Cu")
		(net "M_I_CPU0_SB_DQ<26>")
	)
	(segment
		(start 413.952944 -310.11114)
		(end 414.200594 -310.008524)
		(width 0.14478)
		(layer "In2.Cu")
		(net "M_I_CPU0_SB_DQ<26>")
	)
	(segment
		(start 422.579546 -309.96001)
		(end 422.744392 -309.96001)
		(width 0.14478)
		(layer "In2.Cu")
		(net "M_I_CPU0_SB_DQ<26>")
	)
	(segment
		(start 408.62631 -309.990744)
		(end 408.832812 -309.784242)
		(width 0.14478)
		(layer "In2.Cu")
		(net "M_I_CPU0_SB_DQ<26>")
	)
	(segment
		(start 395.384782 -294.779192)
		(end 396.456408 -295.850564)
		(width 0.14478)
		(layer "In2.Cu")
		(net "M_I_CPU0_SB_DQ<26>")
	)
	(segment
		(start 413.795718 -310.491632)
		(end 413.839914 -310.384952)
		(width 0.14478)
		(layer "In2.Cu")
		(net "M_I_CPU0_SB_DQ<26>")
	)
	(segment
		(start 377.72086 -289.210496)
		(end 377.743212 -289.127184)
		(width 0.0889)
		(layer "In2.Cu")
		(net "M_I_CPU0_SB_DQ<26>")
	)
	(segment
		(start 407.065734 -308.430168)
		(end 407.272236 -308.223666)
		(width 0.14478)
		(layer "In2.Cu")
		(net "M_I_CPU0_SB_DQ<26>")
	)
	(segment
		(start 427.03115 -309.96001)
		(end 427.456092 -310.384952)
		(width 0.14478)
		(layer "In2.Cu")
		(net "M_I_CPU0_SB_DQ<26>")
	)
	(segment
		(start 393.843256 -291.256212)
		(end 394.398754 -292.596824)
		(width 0.0889)
		(layer "In2.Cu")
		(net "M_I_CPU0_SB_DQ<26>")
	)
	(segment
		(start 421.320722 -310.151526)
		(end 421.55618 -310.05399)
		(width 0.14478)
		(layer "In2.Cu")
		(net "M_I_CPU0_SB_DQ<26>")
	)
	(segment
		(start 417.962334 -309.901082)
		(end 418.17671 -309.989982)
		(width 0.14478)
		(layer "In2.Cu")
		(net "M_I_CPU0_SB_DQ<26>")
	)
	(segment
		(start 407.66238 -308.61381)
		(end 407.455878 -308.820312)
		(width 0.14478)
		(layer "In2.Cu")
		(net "M_I_CPU0_SB_DQ<26>")
	)
	(segment
		(start 414.581086 -310.166512)
		(end 415.079434 -309.96001)
		(width 0.14478)
		(layer "In2.Cu")
		(net "M_I_CPU0_SB_DQ<26>")
	)
	(segment
		(start 391.974832 -289.103054)
		(end 392.632438 -289.103054)
		(width 0.0889)
		(layer "In2.Cu")
		(net "M_I_CPU0_SB_DQ<26>")
	)
	(segment
		(start 393.011914 -289.48253)
		(end 393.011914 -290.350448)
		(width 0.0889)
		(layer "In2.Cu")
		(net "M_I_CPU0_SB_DQ<26>")
	)
	(segment
		(start 393.011914 -290.350448)
		(end 393.064492 -290.477448)
		(width 0.0889)
		(layer "In2.Cu")
		(net "M_I_CPU0_SB_DQ<26>")
	)
	(segment
		(start 424.998896 -309.592726)
		(end 425.162472 -309.42915)
		(width 0.14478)
		(layer "In2.Cu")
		(net "M_I_CPU0_SB_DQ<26>")
	)
	(segment
		(start 425.557696 -309.592726)
		(end 425.557696 -309.796434)
		(width 0.14478)
		(layer "In2.Cu")
		(net "M_I_CPU0_SB_DQ<26>")
	)
	(segment
		(start 421.55618 -310.05399)
		(end 421.953944 -310.21909)
		(width 0.14478)
		(layer "In2.Cu")
		(net "M_I_CPU0_SB_DQ<26>")
	)
	(segment
		(start 425.95292 -309.96001)
		(end 426.24248 -309.67045)
		(width 0.14478)
		(layer "In2.Cu")
		(net "M_I_CPU0_SB_DQ<26>")
	)
	(segment
		(start 409.222956 -310.174386)
		(end 409.016454 -310.380888)
		(width 0.14478)
		(layer "In2.Cu")
		(net "M_I_CPU0_SB_DQ<26>")
	)
	(segment
		(start 421.224202 -310.384952)
		(end 421.320722 -310.151526)
		(width 0.14478)
		(layer "In2.Cu")
		(net "M_I_CPU0_SB_DQ<26>")
	)
	(segment
		(start 407.500836 -308.223666)
		(end 407.66238 -308.38521)
		(width 0.14478)
		(layer "In2.Cu")
		(net "M_I_CPU0_SB_DQ<26>")
	)
	(segment
		(start 409.8417 -310.56453)
		(end 410.087318 -310.810148)
		(width 0.14478)
		(layer "In2.Cu")
		(net "M_I_CPU0_SB_DQ<26>")
	)
	(segment
		(start 381.447802 -289.153346)
		(end 381.456184 -289.14852)
		(width 0.0889)
		(layer "In2.Cu")
		(net "M_I_CPU0_SB_DQ<26>")
	)
	(segment
		(start 409.406598 -310.771032)
		(end 409.6131 -310.56453)
		(width 0.14478)
		(layer "In2.Cu")
		(net "M_I_CPU0_SB_DQ<26>")
	)
	(segment
		(start 393.064492 -290.477448)
		(end 393.843256 -291.256212)
		(width 0.0889)
		(layer "In2.Cu")
		(net "M_I_CPU0_SB_DQ<26>")
	)
	(segment
		(start 424.83532 -309.96001)
		(end 424.998896 -309.796434)
		(width 0.14478)
		(layer "In2.Cu")
		(net "M_I_CPU0_SB_DQ<26>")
	)
	(segment
		(start 406.67559 -308.040024)
		(end 406.67559 -308.268624)
		(width 0.14478)
		(layer "In2.Cu")
		(net "M_I_CPU0_SB_DQ<26>")
	)
	(segment
		(start 423.582592 -309.96001)
		(end 424.83532 -309.96001)
		(width 0.14478)
		(layer "In2.Cu")
		(net "M_I_CPU0_SB_DQ<26>")
	)
	(segment
		(start 389.90778 -289.153346)
		(end 389.916162 -289.14852)
		(width 0.0889)
		(layer "In2.Cu")
		(net "M_I_CPU0_SB_DQ<26>")
	)
	(segment
		(start 386.147818 -289.153346)
		(end 386.1562 -289.14852)
		(width 0.0889)
		(layer "In2.Cu")
		(net "M_I_CPU0_SB_DQ<26>")
	)
	(segment
		(start 409.061412 -309.784242)
		(end 409.222956 -309.945786)
		(width 0.14478)
		(layer "In2.Cu")
		(net "M_I_CPU0_SB_DQ<26>")
	)
	(segment
		(start 413.839914 -310.384952)
		(end 413.952944 -310.11114)
		(width 0.14478)
		(layer "In2.Cu")
		(net "M_I_CPU0_SB_DQ<26>")
	)
	(segment
		(start 392.632438 -289.103054)
		(end 393.011914 -289.48253)
		(width 0.0889)
		(layer "In2.Cu")
		(net "M_I_CPU0_SB_DQ<26>")
	)
	(segment
		(start 406.882092 -307.833522)
		(end 406.67559 -308.040024)
		(width 0.14478)
		(layer "In2.Cu")
		(net "M_I_CPU0_SB_DQ<26>")
	)
	(segment
		(start 417.533582 -310.082946)
		(end 417.962334 -309.901082)
		(width 0.14478)
		(layer "In2.Cu")
		(net "M_I_CPU0_SB_DQ<26>")
	)
	(segment
		(start 418.336984 -310.384952)
		(end 418.477446 -310.731662)
		(width 0.14478)
		(layer "In2.Cu")
		(net "M_I_CPU0_SB_DQ<26>")
	)
	(segment
		(start 407.455878 -308.820312)
		(end 407.455878 -309.048912)
		(width 0.14478)
		(layer "In2.Cu")
		(net "M_I_CPU0_SB_DQ<26>")
	)
	(segment
		(start 384.63347 -289.14852)
		(end 384.641852 -289.153346)
		(width 0.0889)
		(layer "In2.Cu")
		(net "M_I_CPU0_SB_DQ<26>")
	)
	(segment
		(start 423.303192 -310.23941)
		(end 423.582592 -309.96001)
		(width 0.14478)
		(layer "In2.Cu")
		(net "M_I_CPU0_SB_DQ<26>")
	)
	(segment
		(start 426.838872 -309.96001)
		(end 427.03115 -309.96001)
		(width 0.14478)
		(layer "In2.Cu")
		(net "M_I_CPU0_SB_DQ<26>")
	)
	(segment
		(start 409.6131 -310.56453)
		(end 409.8417 -310.56453)
		(width 0.14478)
		(layer "In2.Cu")
		(net "M_I_CPU0_SB_DQ<26>")
	)
	(segment
		(start 408.442668 -309.394098)
		(end 408.236166 -309.6006)
		(width 0.14478)
		(layer "In2.Cu")
		(net "M_I_CPU0_SB_DQ<26>")
	)
	(segment
		(start 397.395954 -298.118784)
		(end 406.882092 -307.604922)
		(width 0.14478)
		(layer "In2.Cu")
		(net "M_I_CPU0_SB_DQ<26>")
	)
	(segment
		(start 409.016454 -310.609488)
		(end 409.177998 -310.771032)
		(width 0.14478)
		(layer "In2.Cu")
		(net "M_I_CPU0_SB_DQ<26>")
	)
	(segment
		(start 406.67559 -308.268624)
		(end 406.837134 -308.430168)
		(width 0.14478)
		(layer "In2.Cu")
		(net "M_I_CPU0_SB_DQ<26>")
	)
	(segment
		(start 408.442668 -309.165498)
		(end 408.442668 -309.394098)
		(width 0.14478)
		(layer "In2.Cu")
		(net "M_I_CPU0_SB_DQ<26>")
	)
	(segment
		(start 408.236166 -309.6006)
		(end 408.236166 -309.8292)
		(width 0.14478)
		(layer "In2.Cu")
		(net "M_I_CPU0_SB_DQ<26>")
	)
	(segment
		(start 414.200594 -310.008524)
		(end 414.581086 -310.166512)
		(width 0.14478)
		(layer "In2.Cu")
		(net "M_I_CPU0_SB_DQ<26>")
	)
	(arc
		(start 382.761744 -289.153346)
		(mid 383.0447 -289.229523)
		(end 383.327656 -289.153346)
		(width 0.0889)
		(layer "In2.Cu")
		(net "M_I_CPU0_SB_DQ<26>")
	)
	(arc
		(start 388.967726 -289.153346)
		(mid 389.149977 -289.102996)
		(end 389.333486 -289.14852)
		(width 0.0889)
		(layer "In2.Cu")
		(net "M_I_CPU0_SB_DQ<26>")
	)
	(arc
		(start 382.387856 -289.153346)
		(mid 382.5748 -289.103091)
		(end 382.761744 -289.153346)
		(width 0.0889)
		(layer "In2.Cu")
		(net "M_I_CPU0_SB_DQ<26>")
	)
	(arc
		(start 380.88189 -289.153346)
		(mid 381.164846 -289.229523)
		(end 381.447802 -289.153346)
		(width 0.0889)
		(layer "In2.Cu")
		(net "M_I_CPU0_SB_DQ<26>")
	)
	(arc
		(start 387.46176 -289.153346)
		(mid 387.744716 -289.229523)
		(end 388.027672 -289.153346)
		(width 0.0889)
		(layer "In2.Cu")
		(net "M_I_CPU0_SB_DQ<26>")
	)
	(arc
		(start 388.401814 -289.153346)
		(mid 388.68477 -289.229523)
		(end 388.967726 -289.153346)
		(width 0.0889)
		(layer "In2.Cu")
		(net "M_I_CPU0_SB_DQ<26>")
	)
	(arc
		(start 390.281922 -289.153346)
		(mid 390.564878 -289.229523)
		(end 390.847834 -289.153346)
		(width 0.0889)
		(layer "In2.Cu")
		(net "M_I_CPU0_SB_DQ<26>")
	)
	(arc
		(start 381.821944 -289.153346)
		(mid 382.1049 -289.229523)
		(end 382.387856 -289.153346)
		(width 0.0889)
		(layer "In2.Cu")
		(net "M_I_CPU0_SB_DQ<26>")
	)
	(arc
		(start 379.001782 -289.153346)
		(mid 379.284738 -289.229523)
		(end 379.567694 -289.153346)
		(width 0.0889)
		(layer "In2.Cu")
		(net "M_I_CPU0_SB_DQ<26>")
	)
	(arc
		(start 377.743212 -289.127184)
		(mid 377.905544 -289.104366)
		(end 378.061982 -289.153346)
		(width 0.0889)
		(layer "In2.Cu")
		(net "M_I_CPU0_SB_DQ<26>")
	)
	(arc
		(start 388.027672 -289.153346)
		(mid 388.209923 -289.102996)
		(end 388.393432 -289.14852)
		(width 0.0889)
		(layer "In2.Cu")
		(net "M_I_CPU0_SB_DQ<26>")
	)
	(arc
		(start 385.216146 -289.14852)
		(mid 385.399654 -289.103026)
		(end 385.581906 -289.153346)
		(width 0.0889)
		(layer "In2.Cu")
		(net "M_I_CPU0_SB_DQ<26>")
	)
	(arc
		(start 381.456184 -289.14852)
		(mid 381.639692 -289.103026)
		(end 381.821944 -289.153346)
		(width 0.0889)
		(layer "In2.Cu")
		(net "M_I_CPU0_SB_DQ<26>")
	)
	(arc
		(start 384.641852 -289.153346)
		(mid 384.924808 -289.229523)
		(end 385.207764 -289.153346)
		(width 0.0889)
		(layer "In2.Cu")
		(net "M_I_CPU0_SB_DQ<26>")
	)
	(arc
		(start 390.847834 -289.153346)
		(mid 391.034778 -289.103091)
		(end 391.221722 -289.153346)
		(width 0.0889)
		(layer "In2.Cu")
		(net "M_I_CPU0_SB_DQ<26>")
	)
	(arc
		(start 391.787634 -289.153346)
		(mid 391.87791 -289.115841)
		(end 391.974832 -289.103054)
		(width 0.0889)
		(layer "In2.Cu")
		(net "M_I_CPU0_SB_DQ<26>")
	)
	(arc
		(start 380.507748 -289.153346)
		(mid 380.689999 -289.102996)
		(end 380.873508 -289.14852)
		(width 0.0889)
		(layer "In2.Cu")
		(net "M_I_CPU0_SB_DQ<26>")
	)
	(arc
		(start 389.916162 -289.14852)
		(mid 390.09967 -289.103026)
		(end 390.281922 -289.153346)
		(width 0.0889)
		(layer "In2.Cu")
		(net "M_I_CPU0_SB_DQ<26>")
	)
	(arc
		(start 386.52196 -289.153346)
		(mid 386.804916 -289.229523)
		(end 387.087872 -289.153346)
		(width 0.0889)
		(layer "In2.Cu")
		(net "M_I_CPU0_SB_DQ<26>")
	)
	(arc
		(start 389.341868 -289.153346)
		(mid 389.624824 -289.229523)
		(end 389.90778 -289.153346)
		(width 0.0889)
		(layer "In2.Cu")
		(net "M_I_CPU0_SB_DQ<26>")
	)
	(arc
		(start 378.061982 -289.153346)
		(mid 378.344938 -289.229523)
		(end 378.627894 -289.153346)
		(width 0.0889)
		(layer "In2.Cu")
		(net "M_I_CPU0_SB_DQ<26>")
	)
	(arc
		(start 387.087872 -289.153346)
		(mid 387.274816 -289.103091)
		(end 387.46176 -289.153346)
		(width 0.0889)
		(layer "In2.Cu")
		(net "M_I_CPU0_SB_DQ<26>")
	)
	(arc
		(start 378.627894 -289.153346)
		(mid 378.814838 -289.103091)
		(end 379.001782 -289.153346)
		(width 0.0889)
		(layer "In2.Cu")
		(net "M_I_CPU0_SB_DQ<26>")
	)
	(arc
		(start 391.221722 -289.153346)
		(mid 391.504678 -289.229523)
		(end 391.787634 -289.153346)
		(width 0.0889)
		(layer "In2.Cu")
		(net "M_I_CPU0_SB_DQ<26>")
	)
	(arc
		(start 384.26771 -289.153346)
		(mid 384.449961 -289.102996)
		(end 384.63347 -289.14852)
		(width 0.0889)
		(layer "In2.Cu")
		(net "M_I_CPU0_SB_DQ<26>")
	)
	(arc
		(start 379.567694 -289.153346)
		(mid 379.749945 -289.102996)
		(end 379.933454 -289.14852)
		(width 0.0889)
		(layer "In2.Cu")
		(net "M_I_CPU0_SB_DQ<26>")
	)
	(arc
		(start 383.327656 -289.153346)
		(mid 383.509907 -289.102996)
		(end 383.693416 -289.14852)
		(width 0.0889)
		(layer "In2.Cu")
		(net "M_I_CPU0_SB_DQ<26>")
	)
	(arc
		(start 379.941836 -289.153346)
		(mid 380.224792 -289.229523)
		(end 380.507748 -289.153346)
		(width 0.0889)
		(layer "In2.Cu")
		(net "M_I_CPU0_SB_DQ<26>")
	)
	(arc
		(start 383.701798 -289.153346)
		(mid 383.984754 -289.229523)
		(end 384.26771 -289.153346)
		(width 0.0889)
		(layer "In2.Cu")
		(net "M_I_CPU0_SB_DQ<26>")
	)
	(arc
		(start 385.581906 -289.153346)
		(mid 385.864862 -289.229523)
		(end 386.147818 -289.153346)
		(width 0.0889)
		(layer "In2.Cu")
		(net "M_I_CPU0_SB_DQ<26>")
	)
	(arc
		(start 386.1562 -289.14852)
		(mid 386.339708 -289.103026)
		(end 386.52196 -289.153346)
		(width 0.0889)
		(layer "In2.Cu")
		(net "M_I_CPU0_SB_DQ<26>")
	)
	(segment
		(start 375.528078 -289.209988)
		(end 375.99493 -289.475926)
		(width 0.10668)
		(layer "F.Cu")
		(net "M_I_CPU0_SB_DQ<25>")
	)
	(segment
		(start 376.148854 -289.741356)
		(end 376.244866 -289.766756)
		(width 0.0889)
		(layer "In2.Cu")
		(net "M_I_CPU0_SB_DQ<25>")
	)
	(segment
		(start 422.2623 -310.810148)
		(end 425.044108 -310.810148)
		(width 0.14478)
		(layer "In2.Cu")
		(net "M_I_CPU0_SB_DQ<25>")
	)
	(segment
		(start 425.044108 -310.810148)
		(end 425.348146 -310.50611)
		(width 0.14478)
		(layer "In2.Cu")
		(net "M_I_CPU0_SB_DQ<25>")
	)
	(segment
		(start 396.990062 -298.349162)
		(end 406.22601 -307.58511)
		(width 0.14478)
		(layer "In2.Cu")
		(net "M_I_CPU0_SB_DQ<25>")
	)
	(segment
		(start 389.90778 -289.798506)
		(end 389.916162 -289.803332)
		(width 0.0889)
		(layer "In2.Cu")
		(net "M_I_CPU0_SB_DQ<25>")
	)
	(segment
		(start 392.97229 -292.084252)
		(end 394.084048 -293.18839)
		(width 0.0889)
		(layer "In2.Cu")
		(net "M_I_CPU0_SB_DQ<25>")
	)
	(segment
		(start 379.933454 -289.803332)
		(end 379.941836 -289.798506)
		(width 0.0889)
		(layer "In2.Cu")
		(net "M_I_CPU0_SB_DQ<25>")
	)
	(segment
		(start 430.2252 -310.51119)
		(end 430.524158 -310.810148)
		(width 0.14478)
		(layer "In2.Cu")
		(net "M_I_CPU0_SB_DQ<25>")
	)
	(segment
		(start 429.406558 -310.810148)
		(end 429.6664 -310.810148)
		(width 0.14478)
		(layer "In2.Cu")
		(net "M_I_CPU0_SB_DQ<25>")
	)
	(segment
		(start 419.364414 -311.660032)
		(end 420.210488 -311.660032)
		(width 0.14478)
		(layer "In2.Cu")
		(net "M_I_CPU0_SB_DQ<25>")
	)
	(segment
		(start 394.795756 -294.869108)
		(end 396.080742 -296.154094)
		(width 0.14478)
		(layer "In2.Cu")
		(net "M_I_CPU0_SB_DQ<25>")
	)
	(segment
		(start 376.747786 -289.798506)
		(end 376.756168 -289.803332)
		(width 0.0889)
		(layer "In2.Cu")
		(net "M_I_CPU0_SB_DQ<25>")
	)
	(segment
		(start 425.906946 -310.810148)
		(end 428.5488 -310.810148)
		(width 0.14478)
		(layer "In2.Cu")
		(net "M_I_CPU0_SB_DQ<25>")
	)
	(segment
		(start 385.207764 -289.798506)
		(end 385.216146 -289.803332)
		(width 0.0889)
		(layer "In2.Cu")
		(net "M_I_CPU0_SB_DQ<25>")
	)
	(segment
		(start 383.693416 -289.803332)
		(end 383.701798 -289.798506)
		(width 0.0889)
		(layer "In2.Cu")
		(net "M_I_CPU0_SB_DQ<25>")
	)
	(segment
		(start 391.787634 -289.798506)
		(end 391.82675 -289.821366)
		(width 0.0889)
		(layer "In2.Cu")
		(net "M_I_CPU0_SB_DQ<25>")
	)
	(segment
		(start 425.348146 -310.50611)
		(end 425.602908 -310.50611)
		(width 0.14478)
		(layer "In2.Cu")
		(net "M_I_CPU0_SB_DQ<25>")
	)
	(segment
		(start 406.22601 -308.455314)
		(end 409.430728 -311.660032)
		(width 0.14478)
		(layer "In2.Cu")
		(net "M_I_CPU0_SB_DQ<25>")
	)
	(segment
		(start 380.873508 -289.803332)
		(end 380.88189 -289.798506)
		(width 0.0889)
		(layer "In2.Cu")
		(net "M_I_CPU0_SB_DQ<25>")
	)
	(segment
		(start 420.210488 -311.660032)
		(end 422.2623 -310.810148)
		(width 0.14478)
		(layer "In2.Cu")
		(net "M_I_CPU0_SB_DQ<25>")
	)
	(segment
		(start 431.131218 -310.810148)
		(end 431.55616 -311.23509)
		(width 0.14478)
		(layer "In2.Cu")
		(net "M_I_CPU0_SB_DQ<25>")
	)
	(segment
		(start 409.430728 -311.660032)
		(end 412.77413 -311.660032)
		(width 0.14478)
		(layer "In2.Cu")
		(net "M_I_CPU0_SB_DQ<25>")
	)
	(segment
		(start 388.393432 -289.803332)
		(end 388.401814 -289.798506)
		(width 0.0889)
		(layer "In2.Cu")
		(net "M_I_CPU0_SB_DQ<25>")
	)
	(segment
		(start 375.99493 -289.475926)
		(end 376.148854 -289.741356)
		(width 0.0889)
		(layer "In2.Cu")
		(net "M_I_CPU0_SB_DQ<25>")
	)
	(segment
		(start 414.825942 -310.810148)
		(end 417.312602 -310.810148)
		(width 0.14478)
		(layer "In2.Cu")
		(net "M_I_CPU0_SB_DQ<25>")
	)
	(segment
		(start 396.080742 -296.154094)
		(end 396.990062 -298.349162)
		(width 0.14478)
		(layer "In2.Cu")
		(net "M_I_CPU0_SB_DQ<25>")
	)
	(segment
		(start 425.602908 -310.50611)
		(end 425.906946 -310.810148)
		(width 0.14478)
		(layer "In2.Cu")
		(net "M_I_CPU0_SB_DQ<25>")
	)
	(segment
		(start 406.22601 -307.58511)
		(end 406.22601 -308.455314)
		(width 0.14478)
		(layer "In2.Cu")
		(net "M_I_CPU0_SB_DQ<25>")
	)
	(segment
		(start 381.447802 -289.798506)
		(end 381.456184 -289.803332)
		(width 0.0889)
		(layer "In2.Cu")
		(net "M_I_CPU0_SB_DQ<25>")
	)
	(segment
		(start 377.68784 -289.798506)
		(end 377.696222 -289.803332)
		(width 0.0889)
		(layer "In2.Cu")
		(net "M_I_CPU0_SB_DQ<25>")
	)
	(segment
		(start 389.333486 -289.803332)
		(end 389.341868 -289.798506)
		(width 0.0889)
		(layer "In2.Cu")
		(net "M_I_CPU0_SB_DQ<25>")
	)
	(segment
		(start 394.410438 -294.389048)
		(end 394.477494 -294.550846)
		(width 0.0889)
		(layer "In2.Cu")
		(net "M_I_CPU0_SB_DQ<25>")
	)
	(segment
		(start 386.147818 -289.798506)
		(end 386.1562 -289.803332)
		(width 0.0889)
		(layer "In2.Cu")
		(net "M_I_CPU0_SB_DQ<25>")
	)
	(segment
		(start 429.6664 -310.810148)
		(end 429.965358 -310.51119)
		(width 0.14478)
		(layer "In2.Cu")
		(net "M_I_CPU0_SB_DQ<25>")
	)
	(segment
		(start 429.1076 -310.51119)
		(end 429.406558 -310.810148)
		(width 0.14478)
		(layer "In2.Cu")
		(net "M_I_CPU0_SB_DQ<25>")
	)
	(segment
		(start 392.226038 -290.590224)
		(end 392.296904 -290.631372)
		(width 0.0889)
		(layer "In2.Cu")
		(net "M_I_CPU0_SB_DQ<25>")
	)
	(segment
		(start 394.410438 -293.872412)
		(end 394.410438 -294.389048)
		(width 0.0889)
		(layer "In2.Cu")
		(net "M_I_CPU0_SB_DQ<25>")
	)
	(segment
		(start 429.965358 -310.51119)
		(end 430.2252 -310.51119)
		(width 0.14478)
		(layer "In2.Cu")
		(net "M_I_CPU0_SB_DQ<25>")
	)
	(segment
		(start 394.477494 -294.550846)
		(end 394.795756 -294.869108)
		(width 0.0889)
		(layer "In2.Cu")
		(net "M_I_CPU0_SB_DQ<25>")
	)
	(segment
		(start 412.77413 -311.660032)
		(end 414.825942 -310.810148)
		(width 0.14478)
		(layer "In2.Cu")
		(net "M_I_CPU0_SB_DQ<25>")
	)
	(segment
		(start 428.847758 -310.51119)
		(end 429.1076 -310.51119)
		(width 0.14478)
		(layer "In2.Cu")
		(net "M_I_CPU0_SB_DQ<25>")
	)
	(segment
		(start 384.63347 -289.803332)
		(end 384.641852 -289.798506)
		(width 0.0889)
		(layer "In2.Cu")
		(net "M_I_CPU0_SB_DQ<25>")
	)
	(segment
		(start 392.853672 -291.94506)
		(end 392.97229 -292.084252)
		(width 0.0889)
		(layer "In2.Cu")
		(net "M_I_CPU0_SB_DQ<25>")
	)
	(segment
		(start 430.524158 -310.810148)
		(end 431.131218 -310.810148)
		(width 0.14478)
		(layer "In2.Cu")
		(net "M_I_CPU0_SB_DQ<25>")
	)
	(segment
		(start 428.5488 -310.810148)
		(end 428.847758 -310.51119)
		(width 0.14478)
		(layer "In2.Cu")
		(net "M_I_CPU0_SB_DQ<25>")
	)
	(segment
		(start 417.312602 -310.810148)
		(end 419.364414 -311.660032)
		(width 0.14478)
		(layer "In2.Cu")
		(net "M_I_CPU0_SB_DQ<25>")
	)
	(arc
		(start 381.456184 -289.803332)
		(mid 381.639692 -289.848826)
		(end 381.821944 -289.798506)
		(width 0.0889)
		(layer "In2.Cu")
		(net "M_I_CPU0_SB_DQ<25>")
	)
	(arc
		(start 392.296904 -290.631372)
		(mid 392.475717 -290.833722)
		(end 392.540236 -291.095938)
		(width 0.0889)
		(layer "In2.Cu")
		(net "M_I_CPU0_SB_DQ<25>")
	)
	(arc
		(start 394.084048 -293.18839)
		(mid 394.30599 -293.502371)
		(end 394.410438 -293.872412)
		(width 0.0889)
		(layer "In2.Cu")
		(net "M_I_CPU0_SB_DQ<25>")
	)
	(arc
		(start 379.001782 -289.798506)
		(mid 379.284738 -289.722329)
		(end 379.567694 -289.798506)
		(width 0.0889)
		(layer "In2.Cu")
		(net "M_I_CPU0_SB_DQ<25>")
	)
	(arc
		(start 388.401814 -289.798506)
		(mid 388.68477 -289.722329)
		(end 388.967726 -289.798506)
		(width 0.0889)
		(layer "In2.Cu")
		(net "M_I_CPU0_SB_DQ<25>")
	)
	(arc
		(start 387.087872 -289.798506)
		(mid 387.274816 -289.848761)
		(end 387.46176 -289.798506)
		(width 0.0889)
		(layer "In2.Cu")
		(net "M_I_CPU0_SB_DQ<25>")
	)
	(arc
		(start 385.216146 -289.803332)
		(mid 385.399654 -289.848826)
		(end 385.581906 -289.798506)
		(width 0.0889)
		(layer "In2.Cu")
		(net "M_I_CPU0_SB_DQ<25>")
	)
	(arc
		(start 392.070082 -290.285932)
		(mid 392.111337 -290.456903)
		(end 392.226038 -290.590224)
		(width 0.0889)
		(layer "In2.Cu")
		(net "M_I_CPU0_SB_DQ<25>")
	)
	(arc
		(start 391.221722 -289.798506)
		(mid 391.504678 -289.722329)
		(end 391.787634 -289.798506)
		(width 0.0889)
		(layer "In2.Cu")
		(net "M_I_CPU0_SB_DQ<25>")
	)
	(arc
		(start 390.281922 -289.798506)
		(mid 390.564878 -289.722329)
		(end 390.847834 -289.798506)
		(width 0.0889)
		(layer "In2.Cu")
		(net "M_I_CPU0_SB_DQ<25>")
	)
	(arc
		(start 379.567694 -289.798506)
		(mid 379.749945 -289.848856)
		(end 379.933454 -289.803332)
		(width 0.0889)
		(layer "In2.Cu")
		(net "M_I_CPU0_SB_DQ<25>")
	)
	(arc
		(start 382.761744 -289.798506)
		(mid 383.0447 -289.722329)
		(end 383.327656 -289.798506)
		(width 0.0889)
		(layer "In2.Cu")
		(net "M_I_CPU0_SB_DQ<25>")
	)
	(arc
		(start 377.696222 -289.803332)
		(mid 377.87973 -289.848826)
		(end 378.061982 -289.798506)
		(width 0.0889)
		(layer "In2.Cu")
		(net "M_I_CPU0_SB_DQ<25>")
	)
	(arc
		(start 378.061982 -289.798506)
		(mid 378.344938 -289.722329)
		(end 378.627894 -289.798506)
		(width 0.0889)
		(layer "In2.Cu")
		(net "M_I_CPU0_SB_DQ<25>")
	)
	(arc
		(start 389.916162 -289.803332)
		(mid 390.09967 -289.848826)
		(end 390.281922 -289.798506)
		(width 0.0889)
		(layer "In2.Cu")
		(net "M_I_CPU0_SB_DQ<25>")
	)
	(arc
		(start 378.627894 -289.798506)
		(mid 378.814838 -289.848761)
		(end 379.001782 -289.798506)
		(width 0.0889)
		(layer "In2.Cu")
		(net "M_I_CPU0_SB_DQ<25>")
	)
	(arc
		(start 392.540236 -291.095938)
		(mid 392.621099 -291.548498)
		(end 392.853672 -291.94506)
		(width 0.0889)
		(layer "In2.Cu")
		(net "M_I_CPU0_SB_DQ<25>")
	)
	(arc
		(start 379.941836 -289.798506)
		(mid 380.224792 -289.722329)
		(end 380.507748 -289.798506)
		(width 0.0889)
		(layer "In2.Cu")
		(net "M_I_CPU0_SB_DQ<25>")
	)
	(arc
		(start 386.52196 -289.798506)
		(mid 386.804916 -289.722329)
		(end 387.087872 -289.798506)
		(width 0.0889)
		(layer "In2.Cu")
		(net "M_I_CPU0_SB_DQ<25>")
	)
	(arc
		(start 388.027672 -289.798506)
		(mid 388.209923 -289.848856)
		(end 388.393432 -289.803332)
		(width 0.0889)
		(layer "In2.Cu")
		(net "M_I_CPU0_SB_DQ<25>")
	)
	(arc
		(start 377.121928 -289.798506)
		(mid 377.404884 -289.722329)
		(end 377.68784 -289.798506)
		(width 0.0889)
		(layer "In2.Cu")
		(net "M_I_CPU0_SB_DQ<25>")
	)
	(arc
		(start 380.507748 -289.798506)
		(mid 380.689999 -289.848856)
		(end 380.873508 -289.803332)
		(width 0.0889)
		(layer "In2.Cu")
		(net "M_I_CPU0_SB_DQ<25>")
	)
	(arc
		(start 384.641852 -289.798506)
		(mid 384.924808 -289.722329)
		(end 385.207764 -289.798506)
		(width 0.0889)
		(layer "In2.Cu")
		(net "M_I_CPU0_SB_DQ<25>")
	)
	(arc
		(start 384.26771 -289.798506)
		(mid 384.449961 -289.848856)
		(end 384.63347 -289.803332)
		(width 0.0889)
		(layer "In2.Cu")
		(net "M_I_CPU0_SB_DQ<25>")
	)
	(arc
		(start 381.821944 -289.798506)
		(mid 382.1049 -289.722329)
		(end 382.387856 -289.798506)
		(width 0.0889)
		(layer "In2.Cu")
		(net "M_I_CPU0_SB_DQ<25>")
	)
	(arc
		(start 382.387856 -289.798506)
		(mid 382.5748 -289.848761)
		(end 382.761744 -289.798506)
		(width 0.0889)
		(layer "In2.Cu")
		(net "M_I_CPU0_SB_DQ<25>")
	)
	(arc
		(start 387.46176 -289.798506)
		(mid 387.744716 -289.722329)
		(end 388.027672 -289.798506)
		(width 0.0889)
		(layer "In2.Cu")
		(net "M_I_CPU0_SB_DQ<25>")
	)
	(arc
		(start 380.88189 -289.798506)
		(mid 381.164846 -289.722329)
		(end 381.447802 -289.798506)
		(width 0.0889)
		(layer "In2.Cu")
		(net "M_I_CPU0_SB_DQ<25>")
	)
	(arc
		(start 376.244866 -289.766756)
		(mid 376.500074 -289.723279)
		(end 376.747786 -289.798506)
		(width 0.0889)
		(layer "In2.Cu")
		(net "M_I_CPU0_SB_DQ<25>")
	)
	(arc
		(start 383.701798 -289.798506)
		(mid 383.984754 -289.722329)
		(end 384.26771 -289.798506)
		(width 0.0889)
		(layer "In2.Cu")
		(net "M_I_CPU0_SB_DQ<25>")
	)
	(arc
		(start 376.756168 -289.803332)
		(mid 376.939676 -289.848826)
		(end 377.121928 -289.798506)
		(width 0.0889)
		(layer "In2.Cu")
		(net "M_I_CPU0_SB_DQ<25>")
	)
	(arc
		(start 390.847834 -289.798506)
		(mid 391.034778 -289.848761)
		(end 391.221722 -289.798506)
		(width 0.0889)
		(layer "In2.Cu")
		(net "M_I_CPU0_SB_DQ<25>")
	)
	(arc
		(start 385.581906 -289.798506)
		(mid 385.864862 -289.722329)
		(end 386.147818 -289.798506)
		(width 0.0889)
		(layer "In2.Cu")
		(net "M_I_CPU0_SB_DQ<25>")
	)
	(arc
		(start 389.341868 -289.798506)
		(mid 389.624824 -289.722329)
		(end 389.90778 -289.798506)
		(width 0.0889)
		(layer "In2.Cu")
		(net "M_I_CPU0_SB_DQ<25>")
	)
	(arc
		(start 388.967726 -289.798506)
		(mid 389.149977 -289.848856)
		(end 389.333486 -289.803332)
		(width 0.0889)
		(layer "In2.Cu")
		(net "M_I_CPU0_SB_DQ<25>")
	)
	(arc
		(start 386.1562 -289.803332)
		(mid 386.339708 -289.848826)
		(end 386.52196 -289.798506)
		(width 0.0889)
		(layer "In2.Cu")
		(net "M_I_CPU0_SB_DQ<25>")
	)
	(arc
		(start 383.327656 -289.798506)
		(mid 383.509907 -289.848856)
		(end 383.693416 -289.803332)
		(width 0.0889)
		(layer "In2.Cu")
		(net "M_I_CPU0_SB_DQ<25>")
	)
	(arc
		(start 391.82675 -289.821366)
		(mid 392.005563 -290.023716)
		(end 392.070082 -290.285932)
		(width 0.0889)
		(layer "In2.Cu")
		(net "M_I_CPU0_SB_DQ<25>")
	)
	(segment
		(start 376.938032 -288.399982)
		(end 377.404884 -288.66592)
		(width 0.10668)
		(layer "F.Cu")
		(net "M_I_CPU0_SB_DQ<24>")
	)
	(segment
		(start 429.806354 -308.94655)
		(end 429.806354 -308.607206)
		(width 0.14478)
		(layer "In2.Cu")
		(net "M_I_CPU0_SB_DQ<24>")
	)
	(segment
		(start 395.772132 -294.42791)
		(end 396.938246 -295.594024)
		(width 0.14478)
		(layer "In2.Cu")
		(net "M_I_CPU0_SB_DQ<24>")
	)
	(segment
		(start 387.557772 -288.9885)
		(end 387.566154 -288.993326)
		(width 0.0889)
		(layer "In2.Cu")
		(net "M_I_CPU0_SB_DQ<24>")
	)
	(segment
		(start 382.283462 -288.993326)
		(end 382.291844 -288.9885)
		(width 0.0889)
		(layer "In2.Cu")
		(net "M_I_CPU0_SB_DQ<24>")
	)
	(segment
		(start 429.247554 -308.607206)
		(end 429.247554 -308.94655)
		(width 0.14478)
		(layer "In2.Cu")
		(net "M_I_CPU0_SB_DQ<24>")
	)
	(segment
		(start 409.902914 -309.96001)
		(end 412.980886 -309.96001)
		(width 0.14478)
		(layer "In2.Cu")
		(net "M_I_CPU0_SB_DQ<24>")
	)
	(segment
		(start 395.475714 -293.77259)
		(end 395.475714 -294.131492)
		(width 0.0889)
		(layer "In2.Cu")
		(net "M_I_CPU0_SB_DQ<24>")
	)
	(segment
		(start 382.857756 -288.9885)
		(end 382.866138 -288.993326)
		(width 0.0889)
		(layer "In2.Cu")
		(net "M_I_CPU0_SB_DQ<24>")
	)
	(segment
		(start 386.983478 -288.993326)
		(end 386.99186 -288.9885)
		(width 0.0889)
		(layer "In2.Cu")
		(net "M_I_CPU0_SB_DQ<24>")
	)
	(segment
		(start 429.642778 -309.110126)
		(end 429.806354 -308.94655)
		(width 0.14478)
		(layer "In2.Cu")
		(net "M_I_CPU0_SB_DQ<24>")
	)
	(segment
		(start 394.617194 -292.91407)
		(end 395.475714 -293.77259)
		(width 0.0889)
		(layer "In2.Cu")
		(net "M_I_CPU0_SB_DQ<24>")
	)
	(segment
		(start 388.497826 -288.9885)
		(end 388.506208 -288.993326)
		(width 0.0889)
		(layer "In2.Cu")
		(net "M_I_CPU0_SB_DQ<24>")
	)
	(segment
		(start 428.688754 -308.607206)
		(end 428.85233 -308.44363)
		(width 0.14478)
		(layer "In2.Cu")
		(net "M_I_CPU0_SB_DQ<24>")
	)
	(segment
		(start 419.325806 -309.96001)
		(end 420.410132 -309.96001)
		(width 0.14478)
		(layer "In2.Cu")
		(net "M_I_CPU0_SB_DQ<24>")
	)
	(segment
		(start 424.83532 -309.110126)
		(end 425.110656 -308.83479)
		(width 0.14478)
		(layer "In2.Cu")
		(net "M_I_CPU0_SB_DQ<24>")
	)
	(segment
		(start 394.068554 -291.228526)
		(end 394.617194 -292.553136)
		(width 0.0889)
		(layer "In2.Cu")
		(net "M_I_CPU0_SB_DQ<24>")
	)
	(segment
		(start 377.404884 -288.66592)
		(end 377.558808 -288.93135)
		(width 0.0889)
		(layer "In2.Cu")
		(net "M_I_CPU0_SB_DQ<24>")
	)
	(segment
		(start 430.201578 -308.44363)
		(end 430.365154 -308.607206)
		(width 0.14478)
		(layer "In2.Cu")
		(net "M_I_CPU0_SB_DQ<24>")
	)
	(segment
		(start 429.806354 -308.607206)
		(end 429.96993 -308.44363)
		(width 0.14478)
		(layer "In2.Cu")
		(net "M_I_CPU0_SB_DQ<24>")
	)
	(segment
		(start 428.85233 -308.44363)
		(end 429.083978 -308.44363)
		(width 0.14478)
		(layer "In2.Cu")
		(net "M_I_CPU0_SB_DQ<24>")
	)
	(segment
		(start 386.043424 -288.993326)
		(end 386.051806 -288.9885)
		(width 0.0889)
		(layer "In2.Cu")
		(net "M_I_CPU0_SB_DQ<24>")
	)
	(segment
		(start 426.330364 -308.83479)
		(end 426.6057 -309.110126)
		(width 0.14478)
		(layer "In2.Cu")
		(net "M_I_CPU0_SB_DQ<24>")
	)
	(segment
		(start 379.097794 -288.9885)
		(end 379.106176 -288.993326)
		(width 0.0889)
		(layer "In2.Cu")
		(net "M_I_CPU0_SB_DQ<24>")
	)
	(segment
		(start 383.79781 -288.9885)
		(end 383.806192 -288.993326)
		(width 0.0889)
		(layer "In2.Cu")
		(net "M_I_CPU0_SB_DQ<24>")
	)
	(segment
		(start 426.6057 -309.110126)
		(end 428.525178 -309.110126)
		(width 0.14478)
		(layer "In2.Cu")
		(net "M_I_CPU0_SB_DQ<24>")
	)
	(segment
		(start 422.461944 -309.110126)
		(end 424.83532 -309.110126)
		(width 0.14478)
		(layer "In2.Cu")
		(net "M_I_CPU0_SB_DQ<24>")
	)
	(segment
		(start 415.032698 -309.110126)
		(end 417.273994 -309.110126)
		(width 0.14478)
		(layer "In2.Cu")
		(net "M_I_CPU0_SB_DQ<24>")
	)
	(segment
		(start 412.980886 -309.96001)
		(end 415.032698 -309.110126)
		(width 0.14478)
		(layer "In2.Cu")
		(net "M_I_CPU0_SB_DQ<24>")
	)
	(segment
		(start 417.273994 -309.110126)
		(end 419.325806 -309.96001)
		(width 0.14478)
		(layer "In2.Cu")
		(net "M_I_CPU0_SB_DQ<24>")
	)
	(segment
		(start 396.938246 -295.594024)
		(end 397.929354 -297.98645)
		(width 0.14478)
		(layer "In2.Cu")
		(net "M_I_CPU0_SB_DQ<24>")
	)
	(segment
		(start 390.74344 -288.993326)
		(end 390.751822 -288.9885)
		(width 0.0889)
		(layer "In2.Cu")
		(net "M_I_CPU0_SB_DQ<24>")
	)
	(segment
		(start 393.517374 -289.562286)
		(end 393.939776 -290.581588)
		(width 0.0889)
		(layer "In2.Cu")
		(net "M_I_CPU0_SB_DQ<24>")
	)
	(segment
		(start 394.617194 -292.553136)
		(end 394.617194 -292.91407)
		(width 0.0889)
		(layer "In2.Cu")
		(net "M_I_CPU0_SB_DQ<24>")
	)
	(segment
		(start 380.037848 -288.9885)
		(end 380.04623 -288.993326)
		(width 0.0889)
		(layer "In2.Cu")
		(net "M_I_CPU0_SB_DQ<24>")
	)
	(segment
		(start 429.083978 -308.44363)
		(end 429.247554 -308.607206)
		(width 0.14478)
		(layer "In2.Cu")
		(net "M_I_CPU0_SB_DQ<24>")
	)
	(segment
		(start 430.365154 -308.94655)
		(end 430.52873 -309.110126)
		(width 0.14478)
		(layer "In2.Cu")
		(net "M_I_CPU0_SB_DQ<24>")
	)
	(segment
		(start 429.96993 -308.44363)
		(end 430.201578 -308.44363)
		(width 0.14478)
		(layer "In2.Cu")
		(net "M_I_CPU0_SB_DQ<24>")
	)
	(segment
		(start 431.131218 -309.110126)
		(end 431.55616 -309.535068)
		(width 0.14478)
		(layer "In2.Cu")
		(net "M_I_CPU0_SB_DQ<24>")
	)
	(segment
		(start 428.525178 -309.110126)
		(end 428.688754 -308.94655)
		(width 0.14478)
		(layer "In2.Cu")
		(net "M_I_CPU0_SB_DQ<24>")
	)
	(segment
		(start 391.974832 -288.9123)
		(end 392.867388 -288.9123)
		(width 0.0889)
		(layer "In2.Cu")
		(net "M_I_CPU0_SB_DQ<24>")
	)
	(segment
		(start 391.317734 -288.9885)
		(end 391.326116 -288.993326)
		(width 0.0889)
		(layer "In2.Cu")
		(net "M_I_CPU0_SB_DQ<24>")
	)
	(segment
		(start 378.5235 -288.993326)
		(end 378.531882 -288.9885)
		(width 0.0889)
		(layer "In2.Cu")
		(net "M_I_CPU0_SB_DQ<24>")
	)
	(segment
		(start 425.110656 -308.83479)
		(end 426.330364 -308.83479)
		(width 0.14478)
		(layer "In2.Cu")
		(net "M_I_CPU0_SB_DQ<24>")
	)
	(segment
		(start 377.558808 -288.93135)
		(end 377.65482 -288.95675)
		(width 0.0889)
		(layer "In2.Cu")
		(net "M_I_CPU0_SB_DQ<24>")
	)
	(segment
		(start 429.41113 -309.110126)
		(end 429.642778 -309.110126)
		(width 0.14478)
		(layer "In2.Cu")
		(net "M_I_CPU0_SB_DQ<24>")
	)
	(segment
		(start 397.929354 -297.98645)
		(end 409.902914 -309.96001)
		(width 0.14478)
		(layer "In2.Cu")
		(net "M_I_CPU0_SB_DQ<24>")
	)
	(segment
		(start 393.939776 -290.581588)
		(end 394.068554 -291.228526)
		(width 0.0889)
		(layer "In2.Cu")
		(net "M_I_CPU0_SB_DQ<24>")
	)
	(segment
		(start 420.410132 -309.96001)
		(end 422.461944 -309.110126)
		(width 0.14478)
		(layer "In2.Cu")
		(net "M_I_CPU0_SB_DQ<24>")
	)
	(segment
		(start 429.247554 -308.94655)
		(end 429.41113 -309.110126)
		(width 0.14478)
		(layer "In2.Cu")
		(net "M_I_CPU0_SB_DQ<24>")
	)
	(segment
		(start 395.475714 -294.131492)
		(end 395.772132 -294.42791)
		(width 0.0889)
		(layer "In2.Cu")
		(net "M_I_CPU0_SB_DQ<24>")
	)
	(segment
		(start 430.52873 -309.110126)
		(end 431.131218 -309.110126)
		(width 0.14478)
		(layer "In2.Cu")
		(net "M_I_CPU0_SB_DQ<24>")
	)
	(segment
		(start 428.688754 -308.94655)
		(end 428.688754 -308.607206)
		(width 0.14478)
		(layer "In2.Cu")
		(net "M_I_CPU0_SB_DQ<24>")
	)
	(segment
		(start 430.365154 -308.607206)
		(end 430.365154 -308.94655)
		(width 0.14478)
		(layer "In2.Cu")
		(net "M_I_CPU0_SB_DQ<24>")
	)
	(segment
		(start 392.867388 -288.9123)
		(end 393.517374 -289.562286)
		(width 0.0889)
		(layer "In2.Cu")
		(net "M_I_CPU0_SB_DQ<24>")
	)
	(arc
		(start 386.617718 -288.9885)
		(mid 386.799969 -289.03885)
		(end 386.983478 -288.993326)
		(width 0.0889)
		(layer "In2.Cu")
		(net "M_I_CPU0_SB_DQ<24>")
	)
	(arc
		(start 384.171952 -288.9885)
		(mid 384.454908 -288.912323)
		(end 384.737864 -288.9885)
		(width 0.0889)
		(layer "In2.Cu")
		(net "M_I_CPU0_SB_DQ<24>")
	)
	(arc
		(start 385.111752 -288.9885)
		(mid 385.394708 -288.912323)
		(end 385.677664 -288.9885)
		(width 0.0889)
		(layer "In2.Cu")
		(net "M_I_CPU0_SB_DQ<24>")
	)
	(arc
		(start 385.677664 -288.9885)
		(mid 385.859915 -289.03885)
		(end 386.043424 -288.993326)
		(width 0.0889)
		(layer "In2.Cu")
		(net "M_I_CPU0_SB_DQ<24>")
	)
	(arc
		(start 389.43788 -288.9885)
		(mid 389.624824 -289.038755)
		(end 389.811768 -288.9885)
		(width 0.0889)
		(layer "In2.Cu")
		(net "M_I_CPU0_SB_DQ<24>")
	)
	(arc
		(start 387.931914 -288.9885)
		(mid 388.21487 -288.912323)
		(end 388.497826 -288.9885)
		(width 0.0889)
		(layer "In2.Cu")
		(net "M_I_CPU0_SB_DQ<24>")
	)
	(arc
		(start 388.871968 -288.9885)
		(mid 389.154924 -288.912323)
		(end 389.43788 -288.9885)
		(width 0.0889)
		(layer "In2.Cu")
		(net "M_I_CPU0_SB_DQ<24>")
	)
	(arc
		(start 382.866138 -288.993326)
		(mid 383.049646 -289.03882)
		(end 383.231898 -288.9885)
		(width 0.0889)
		(layer "In2.Cu")
		(net "M_I_CPU0_SB_DQ<24>")
	)
	(arc
		(start 381.35179 -288.9885)
		(mid 381.634746 -288.912323)
		(end 381.917702 -288.9885)
		(width 0.0889)
		(layer "In2.Cu")
		(net "M_I_CPU0_SB_DQ<24>")
	)
	(arc
		(start 378.15774 -288.9885)
		(mid 378.339991 -289.03885)
		(end 378.5235 -288.993326)
		(width 0.0889)
		(layer "In2.Cu")
		(net "M_I_CPU0_SB_DQ<24>")
	)
	(arc
		(start 386.99186 -288.9885)
		(mid 387.274816 -288.912323)
		(end 387.557772 -288.9885)
		(width 0.0889)
		(layer "In2.Cu")
		(net "M_I_CPU0_SB_DQ<24>")
	)
	(arc
		(start 391.326116 -288.993326)
		(mid 391.509624 -289.03882)
		(end 391.691876 -288.9885)
		(width 0.0889)
		(layer "In2.Cu")
		(net "M_I_CPU0_SB_DQ<24>")
	)
	(arc
		(start 379.106176 -288.993326)
		(mid 379.289684 -289.03882)
		(end 379.471936 -288.9885)
		(width 0.0889)
		(layer "In2.Cu")
		(net "M_I_CPU0_SB_DQ<24>")
	)
	(arc
		(start 390.751822 -288.9885)
		(mid 391.034778 -288.912323)
		(end 391.317734 -288.9885)
		(width 0.0889)
		(layer "In2.Cu")
		(net "M_I_CPU0_SB_DQ<24>")
	)
	(arc
		(start 386.051806 -288.9885)
		(mid 386.334762 -288.912323)
		(end 386.617718 -288.9885)
		(width 0.0889)
		(layer "In2.Cu")
		(net "M_I_CPU0_SB_DQ<24>")
	)
	(arc
		(start 388.506208 -288.993326)
		(mid 388.689716 -289.03882)
		(end 388.871968 -288.9885)
		(width 0.0889)
		(layer "In2.Cu")
		(net "M_I_CPU0_SB_DQ<24>")
	)
	(arc
		(start 389.811768 -288.9885)
		(mid 390.094724 -288.912323)
		(end 390.37768 -288.9885)
		(width 0.0889)
		(layer "In2.Cu")
		(net "M_I_CPU0_SB_DQ<24>")
	)
	(arc
		(start 378.531882 -288.9885)
		(mid 378.814838 -288.912323)
		(end 379.097794 -288.9885)
		(width 0.0889)
		(layer "In2.Cu")
		(net "M_I_CPU0_SB_DQ<24>")
	)
	(arc
		(start 381.917702 -288.9885)
		(mid 382.099953 -289.03885)
		(end 382.283462 -288.993326)
		(width 0.0889)
		(layer "In2.Cu")
		(net "M_I_CPU0_SB_DQ<24>")
	)
	(arc
		(start 380.41199 -288.9885)
		(mid 380.694946 -288.912323)
		(end 380.977902 -288.9885)
		(width 0.0889)
		(layer "In2.Cu")
		(net "M_I_CPU0_SB_DQ<24>")
	)
	(arc
		(start 380.04623 -288.993326)
		(mid 380.229738 -289.03882)
		(end 380.41199 -288.9885)
		(width 0.0889)
		(layer "In2.Cu")
		(net "M_I_CPU0_SB_DQ<24>")
	)
	(arc
		(start 382.291844 -288.9885)
		(mid 382.5748 -288.912323)
		(end 382.857756 -288.9885)
		(width 0.0889)
		(layer "In2.Cu")
		(net "M_I_CPU0_SB_DQ<24>")
	)
	(arc
		(start 383.806192 -288.993326)
		(mid 383.9897 -289.03882)
		(end 384.171952 -288.9885)
		(width 0.0889)
		(layer "In2.Cu")
		(net "M_I_CPU0_SB_DQ<24>")
	)
	(arc
		(start 383.231898 -288.9885)
		(mid 383.514854 -288.912323)
		(end 383.79781 -288.9885)
		(width 0.0889)
		(layer "In2.Cu")
		(net "M_I_CPU0_SB_DQ<24>")
	)
	(arc
		(start 384.737864 -288.9885)
		(mid 384.924808 -289.038755)
		(end 385.111752 -288.9885)
		(width 0.0889)
		(layer "In2.Cu")
		(net "M_I_CPU0_SB_DQ<24>")
	)
	(arc
		(start 379.471936 -288.9885)
		(mid 379.754892 -288.912323)
		(end 380.037848 -288.9885)
		(width 0.0889)
		(layer "In2.Cu")
		(net "M_I_CPU0_SB_DQ<24>")
	)
	(arc
		(start 390.37768 -288.9885)
		(mid 390.559931 -289.03885)
		(end 390.74344 -288.993326)
		(width 0.0889)
		(layer "In2.Cu")
		(net "M_I_CPU0_SB_DQ<24>")
	)
	(arc
		(start 377.65482 -288.95675)
		(mid 377.910028 -288.913273)
		(end 378.15774 -288.9885)
		(width 0.0889)
		(layer "In2.Cu")
		(net "M_I_CPU0_SB_DQ<24>")
	)
	(arc
		(start 391.691876 -288.9885)
		(mid 391.828312 -288.931675)
		(end 391.974832 -288.9123)
		(width 0.0889)
		(layer "In2.Cu")
		(net "M_I_CPU0_SB_DQ<24>")
	)
	(arc
		(start 387.566154 -288.993326)
		(mid 387.749662 -289.03882)
		(end 387.931914 -288.9885)
		(width 0.0889)
		(layer "In2.Cu")
		(net "M_I_CPU0_SB_DQ<24>")
	)
	(arc
		(start 380.977902 -288.9885)
		(mid 381.164846 -289.038755)
		(end 381.35179 -288.9885)
		(width 0.0889)
		(layer "In2.Cu")
		(net "M_I_CPU0_SB_DQ<24>")
	)
	(segment
		(start 375.997978 -288.399982)
		(end 376.46483 -288.66592)
		(width 0.10668)
		(layer "F.Cu")
		(net "M_I_CPU0_SB_DQ<23>")
	)
	(segment
		(start 387.557772 -288.343594)
		(end 387.566154 -288.338768)
		(width 0.0889)
		(layer "In2.Cu")
		(net "M_I_CPU0_SB_DQ<23>")
	)
	(segment
		(start 394.565886 -291.455602)
		(end 394.865606 -291.755322)
		(width 0.0889)
		(layer "In2.Cu")
		(net "M_I_CPU0_SB_DQ<23>")
	)
	(segment
		(start 399.534634 -298.437808)
		(end 400.01571 -297.956732)
		(width 0.14478)
		(layer "In2.Cu")
		(net "M_I_CPU0_SB_DQ<23>")
	)
	(segment
		(start 378.5235 -288.338768)
		(end 378.531882 -288.343594)
		(width 0.0889)
		(layer "In2.Cu")
		(net "M_I_CPU0_SB_DQ<23>")
	)
	(segment
		(start 399.306034 -298.437808)
		(end 399.534634 -298.437808)
		(width 0.14478)
		(layer "In2.Cu")
		(net "M_I_CPU0_SB_DQ<23>")
	)
	(segment
		(start 394.865606 -291.755322)
		(end 395.285722 -292.175438)
		(width 0.14478)
		(layer "In2.Cu")
		(net "M_I_CPU0_SB_DQ<23>")
	)
	(segment
		(start 401.263866 -300.541436)
		(end 408.587194 -307.864764)
		(width 0.14478)
		(layer "In2.Cu")
		(net "M_I_CPU0_SB_DQ<23>")
	)
	(segment
		(start 376.310906 -288.40049)
		(end 376.333004 -288.317432)
		(width 0.0889)
		(layer "In2.Cu")
		(net "M_I_CPU0_SB_DQ<23>")
	)
	(segment
		(start 416.919918 -308.260242)
		(end 418.972492 -309.11038)
		(width 0.14478)
		(layer "In2.Cu")
		(net "M_I_CPU0_SB_DQ<23>")
	)
	(segment
		(start 383.79781 -288.343594)
		(end 383.806192 -288.338768)
		(width 0.0889)
		(layer "In2.Cu")
		(net "M_I_CPU0_SB_DQ<23>")
	)
	(segment
		(start 400.405854 -298.118276)
		(end 400.405854 -298.346876)
		(width 0.14478)
		(layer "In2.Cu")
		(net "M_I_CPU0_SB_DQ<23>")
	)
	(segment
		(start 392.226292 -288.360612)
		(end 392.255756 -288.343594)
		(width 0.0889)
		(layer "In2.Cu")
		(net "M_I_CPU0_SB_DQ<23>")
	)
	(segment
		(start 427.03115 -308.260242)
		(end 427.456092 -308.685184)
		(width 0.14478)
		(layer "In2.Cu")
		(net "M_I_CPU0_SB_DQ<23>")
	)
	(segment
		(start 395.285722 -292.175438)
		(end 395.866874 -293.579296)
		(width 0.14478)
		(layer "In2.Cu")
		(net "M_I_CPU0_SB_DQ<23>")
	)
	(segment
		(start 401.024598 -298.73702)
		(end 401.263866 -298.976288)
		(width 0.14478)
		(layer "In2.Cu")
		(net "M_I_CPU0_SB_DQ<23>")
	)
	(segment
		(start 399.14449 -298.276264)
		(end 399.306034 -298.437808)
		(width 0.14478)
		(layer "In2.Cu")
		(net "M_I_CPU0_SB_DQ<23>")
	)
	(segment
		(start 390.74344 -288.338768)
		(end 390.751822 -288.343594)
		(width 0.0889)
		(layer "In2.Cu")
		(net "M_I_CPU0_SB_DQ<23>")
	)
	(segment
		(start 413.17291 -309.11038)
		(end 415.225484 -308.260242)
		(width 0.14478)
		(layer "In2.Cu")
		(net "M_I_CPU0_SB_DQ<23>")
	)
	(segment
		(start 401.263866 -298.976288)
		(end 401.263866 -300.541436)
		(width 0.14478)
		(layer "In2.Cu")
		(net "M_I_CPU0_SB_DQ<23>")
	)
	(segment
		(start 415.225484 -308.260242)
		(end 416.919918 -308.260242)
		(width 0.14478)
		(layer "In2.Cu")
		(net "M_I_CPU0_SB_DQ<23>")
	)
	(segment
		(start 393.847574 -288.57575)
		(end 393.847574 -289.72129)
		(width 0.0889)
		(layer "In2.Cu")
		(net "M_I_CPU0_SB_DQ<23>")
	)
	(segment
		(start 395.866874 -293.579296)
		(end 399.625566 -297.337988)
		(width 0.14478)
		(layer "In2.Cu")
		(net "M_I_CPU0_SB_DQ<23>")
	)
	(segment
		(start 408.587194 -307.864764)
		(end 411.5943 -309.11038)
		(width 0.14478)
		(layer "In2.Cu")
		(net "M_I_CPU0_SB_DQ<23>")
	)
	(segment
		(start 388.497826 -288.343594)
		(end 388.506208 -288.338768)
		(width 0.0889)
		(layer "In2.Cu")
		(net "M_I_CPU0_SB_DQ<23>")
	)
	(segment
		(start 377.583446 -288.338768)
		(end 377.591828 -288.343594)
		(width 0.0889)
		(layer "In2.Cu")
		(net "M_I_CPU0_SB_DQ<23>")
	)
	(segment
		(start 386.983478 -288.338768)
		(end 386.99186 -288.343594)
		(width 0.0889)
		(layer "In2.Cu")
		(net "M_I_CPU0_SB_DQ<23>")
	)
	(segment
		(start 400.086322 -299.218096)
		(end 400.314922 -299.218096)
		(width 0.14478)
		(layer "In2.Cu")
		(net "M_I_CPU0_SB_DQ<23>")
	)
	(segment
		(start 418.972492 -309.11038)
		(end 420.943024 -309.11038)
		(width 0.14478)
		(layer "In2.Cu")
		(net "M_I_CPU0_SB_DQ<23>")
	)
	(segment
		(start 380.037848 -288.343594)
		(end 380.04623 -288.338768)
		(width 0.0889)
		(layer "In2.Cu")
		(net "M_I_CPU0_SB_DQ<23>")
	)
	(segment
		(start 393.535154 -288.26333)
		(end 393.847574 -288.57575)
		(width 0.0889)
		(layer "In2.Cu")
		(net "M_I_CPU0_SB_DQ<23>")
	)
	(segment
		(start 399.924778 -298.827952)
		(end 399.924778 -299.056552)
		(width 0.14478)
		(layer "In2.Cu")
		(net "M_I_CPU0_SB_DQ<23>")
	)
	(segment
		(start 399.625566 -297.337988)
		(end 399.625566 -297.566588)
		(width 0.14478)
		(layer "In2.Cu")
		(net "M_I_CPU0_SB_DQ<23>")
	)
	(segment
		(start 382.283462 -288.338768)
		(end 382.291844 -288.343594)
		(width 0.0889)
		(layer "In2.Cu")
		(net "M_I_CPU0_SB_DQ<23>")
	)
	(segment
		(start 386.043424 -288.338768)
		(end 386.051806 -288.343594)
		(width 0.0889)
		(layer "In2.Cu")
		(net "M_I_CPU0_SB_DQ<23>")
	)
	(segment
		(start 393.847574 -289.72129)
		(end 394.565886 -291.455602)
		(width 0.0889)
		(layer "In2.Cu")
		(net "M_I_CPU0_SB_DQ<23>")
	)
	(segment
		(start 411.5943 -309.11038)
		(end 413.17291 -309.11038)
		(width 0.14478)
		(layer "In2.Cu")
		(net "M_I_CPU0_SB_DQ<23>")
	)
	(segment
		(start 392.555476 -288.26333)
		(end 393.535154 -288.26333)
		(width 0.0889)
		(layer "In2.Cu")
		(net "M_I_CPU0_SB_DQ<23>")
	)
	(segment
		(start 399.14449 -298.047664)
		(end 399.14449 -298.276264)
		(width 0.14478)
		(layer "In2.Cu")
		(net "M_I_CPU0_SB_DQ<23>")
	)
	(segment
		(start 399.625566 -297.566588)
		(end 399.14449 -298.047664)
		(width 0.14478)
		(layer "In2.Cu")
		(net "M_I_CPU0_SB_DQ<23>")
	)
	(segment
		(start 376.46483 -288.66592)
		(end 376.310906 -288.40049)
		(width 0.0889)
		(layer "In2.Cu")
		(net "M_I_CPU0_SB_DQ<23>")
	)
	(segment
		(start 382.857756 -288.343594)
		(end 382.866138 -288.338768)
		(width 0.0889)
		(layer "In2.Cu")
		(net "M_I_CPU0_SB_DQ<23>")
	)
	(segment
		(start 400.314922 -299.218096)
		(end 400.795998 -298.73702)
		(width 0.14478)
		(layer "In2.Cu")
		(net "M_I_CPU0_SB_DQ<23>")
	)
	(segment
		(start 400.01571 -297.956732)
		(end 400.24431 -297.956732)
		(width 0.14478)
		(layer "In2.Cu")
		(net "M_I_CPU0_SB_DQ<23>")
	)
	(segment
		(start 420.943024 -309.11038)
		(end 422.995598 -308.260242)
		(width 0.14478)
		(layer "In2.Cu")
		(net "M_I_CPU0_SB_DQ<23>")
	)
	(segment
		(start 391.317734 -288.343594)
		(end 391.326116 -288.338768)
		(width 0.0889)
		(layer "In2.Cu")
		(net "M_I_CPU0_SB_DQ<23>")
	)
	(segment
		(start 399.924778 -299.056552)
		(end 400.086322 -299.218096)
		(width 0.14478)
		(layer "In2.Cu")
		(net "M_I_CPU0_SB_DQ<23>")
	)
	(segment
		(start 422.995598 -308.260242)
		(end 427.03115 -308.260242)
		(width 0.14478)
		(layer "In2.Cu")
		(net "M_I_CPU0_SB_DQ<23>")
	)
	(segment
		(start 400.795998 -298.73702)
		(end 401.024598 -298.73702)
		(width 0.14478)
		(layer "In2.Cu")
		(net "M_I_CPU0_SB_DQ<23>")
	)
	(segment
		(start 379.097794 -288.343594)
		(end 379.106176 -288.338768)
		(width 0.0889)
		(layer "In2.Cu")
		(net "M_I_CPU0_SB_DQ<23>")
	)
	(segment
		(start 400.405854 -298.346876)
		(end 399.924778 -298.827952)
		(width 0.14478)
		(layer "In2.Cu")
		(net "M_I_CPU0_SB_DQ<23>")
	)
	(segment
		(start 400.24431 -297.956732)
		(end 400.405854 -298.118276)
		(width 0.14478)
		(layer "In2.Cu")
		(net "M_I_CPU0_SB_DQ<23>")
	)
	(arc
		(start 382.866138 -288.338768)
		(mid 383.049646 -288.293243)
		(end 383.231898 -288.343594)
		(width 0.0889)
		(layer "In2.Cu")
		(net "M_I_CPU0_SB_DQ<23>")
	)
	(arc
		(start 380.41199 -288.343594)
		(mid 380.694946 -288.419771)
		(end 380.977902 -288.343594)
		(width 0.0889)
		(layer "In2.Cu")
		(net "M_I_CPU0_SB_DQ<23>")
	)
	(arc
		(start 376.333004 -288.317432)
		(mid 376.495335 -288.294583)
		(end 376.651774 -288.343594)
		(width 0.0889)
		(layer "In2.Cu")
		(net "M_I_CPU0_SB_DQ<23>")
	)
	(arc
		(start 391.326116 -288.338768)
		(mid 391.509624 -288.293243)
		(end 391.691876 -288.343594)
		(width 0.0889)
		(layer "In2.Cu")
		(net "M_I_CPU0_SB_DQ<23>")
	)
	(arc
		(start 386.051806 -288.343594)
		(mid 386.334762 -288.419771)
		(end 386.617718 -288.343594)
		(width 0.0889)
		(layer "In2.Cu")
		(net "M_I_CPU0_SB_DQ<23>")
	)
	(arc
		(start 382.291844 -288.343594)
		(mid 382.5748 -288.419771)
		(end 382.857756 -288.343594)
		(width 0.0889)
		(layer "In2.Cu")
		(net "M_I_CPU0_SB_DQ<23>")
	)
	(arc
		(start 390.751822 -288.343594)
		(mid 391.034778 -288.419771)
		(end 391.317734 -288.343594)
		(width 0.0889)
		(layer "In2.Cu")
		(net "M_I_CPU0_SB_DQ<23>")
	)
	(arc
		(start 389.43788 -288.343594)
		(mid 389.624824 -288.293305)
		(end 389.811768 -288.343594)
		(width 0.0889)
		(layer "In2.Cu")
		(net "M_I_CPU0_SB_DQ<23>")
	)
	(arc
		(start 378.15774 -288.343594)
		(mid 378.339991 -288.29321)
		(end 378.5235 -288.338768)
		(width 0.0889)
		(layer "In2.Cu")
		(net "M_I_CPU0_SB_DQ<23>")
	)
	(arc
		(start 386.99186 -288.343594)
		(mid 387.274816 -288.419771)
		(end 387.557772 -288.343594)
		(width 0.0889)
		(layer "In2.Cu")
		(net "M_I_CPU0_SB_DQ<23>")
	)
	(arc
		(start 378.531882 -288.343594)
		(mid 378.814838 -288.419771)
		(end 379.097794 -288.343594)
		(width 0.0889)
		(layer "In2.Cu")
		(net "M_I_CPU0_SB_DQ<23>")
	)
	(arc
		(start 377.591828 -288.343594)
		(mid 377.874784 -288.419771)
		(end 378.15774 -288.343594)
		(width 0.0889)
		(layer "In2.Cu")
		(net "M_I_CPU0_SB_DQ<23>")
	)
	(arc
		(start 379.106176 -288.338768)
		(mid 379.289684 -288.293243)
		(end 379.471936 -288.343594)
		(width 0.0889)
		(layer "In2.Cu")
		(net "M_I_CPU0_SB_DQ<23>")
	)
	(arc
		(start 376.651774 -288.343594)
		(mid 376.93473 -288.419771)
		(end 377.217686 -288.343594)
		(width 0.0889)
		(layer "In2.Cu")
		(net "M_I_CPU0_SB_DQ<23>")
	)
	(arc
		(start 389.811768 -288.343594)
		(mid 390.094724 -288.419771)
		(end 390.37768 -288.343594)
		(width 0.0889)
		(layer "In2.Cu")
		(net "M_I_CPU0_SB_DQ<23>")
	)
	(arc
		(start 390.37768 -288.343594)
		(mid 390.559931 -288.29321)
		(end 390.74344 -288.338768)
		(width 0.0889)
		(layer "In2.Cu")
		(net "M_I_CPU0_SB_DQ<23>")
	)
	(arc
		(start 392.255756 -288.343594)
		(mid 392.400339 -288.283764)
		(end 392.555476 -288.26333)
		(width 0.0889)
		(layer "In2.Cu")
		(net "M_I_CPU0_SB_DQ<23>")
	)
	(arc
		(start 387.931914 -288.343594)
		(mid 388.21487 -288.419771)
		(end 388.497826 -288.343594)
		(width 0.0889)
		(layer "In2.Cu")
		(net "M_I_CPU0_SB_DQ<23>")
	)
	(arc
		(start 385.677664 -288.343594)
		(mid 385.859915 -288.29321)
		(end 386.043424 -288.338768)
		(width 0.0889)
		(layer "In2.Cu")
		(net "M_I_CPU0_SB_DQ<23>")
	)
	(arc
		(start 380.04623 -288.338768)
		(mid 380.229738 -288.293243)
		(end 380.41199 -288.343594)
		(width 0.0889)
		(layer "In2.Cu")
		(net "M_I_CPU0_SB_DQ<23>")
	)
	(arc
		(start 388.506208 -288.338768)
		(mid 388.689716 -288.293243)
		(end 388.871968 -288.343594)
		(width 0.0889)
		(layer "In2.Cu")
		(net "M_I_CPU0_SB_DQ<23>")
	)
	(arc
		(start 381.35179 -288.343594)
		(mid 381.634746 -288.419771)
		(end 381.917702 -288.343594)
		(width 0.0889)
		(layer "In2.Cu")
		(net "M_I_CPU0_SB_DQ<23>")
	)
	(arc
		(start 381.917702 -288.343594)
		(mid 382.099953 -288.29321)
		(end 382.283462 -288.338768)
		(width 0.0889)
		(layer "In2.Cu")
		(net "M_I_CPU0_SB_DQ<23>")
	)
	(arc
		(start 391.691876 -288.343594)
		(mid 391.956933 -288.419487)
		(end 392.226292 -288.360612)
		(width 0.0889)
		(layer "In2.Cu")
		(net "M_I_CPU0_SB_DQ<23>")
	)
	(arc
		(start 387.566154 -288.338768)
		(mid 387.749662 -288.293243)
		(end 387.931914 -288.343594)
		(width 0.0889)
		(layer "In2.Cu")
		(net "M_I_CPU0_SB_DQ<23>")
	)
	(arc
		(start 380.977902 -288.343594)
		(mid 381.164846 -288.293305)
		(end 381.35179 -288.343594)
		(width 0.0889)
		(layer "In2.Cu")
		(net "M_I_CPU0_SB_DQ<23>")
	)
	(arc
		(start 377.217686 -288.343594)
		(mid 377.399937 -288.29321)
		(end 377.583446 -288.338768)
		(width 0.0889)
		(layer "In2.Cu")
		(net "M_I_CPU0_SB_DQ<23>")
	)
	(arc
		(start 388.871968 -288.343594)
		(mid 389.154924 -288.419771)
		(end 389.43788 -288.343594)
		(width 0.0889)
		(layer "In2.Cu")
		(net "M_I_CPU0_SB_DQ<23>")
	)
	(arc
		(start 385.111752 -288.343594)
		(mid 385.394708 -288.419771)
		(end 385.677664 -288.343594)
		(width 0.0889)
		(layer "In2.Cu")
		(net "M_I_CPU0_SB_DQ<23>")
	)
	(arc
		(start 383.806192 -288.338768)
		(mid 383.9897 -288.293243)
		(end 384.171952 -288.343594)
		(width 0.0889)
		(layer "In2.Cu")
		(net "M_I_CPU0_SB_DQ<23>")
	)
	(arc
		(start 384.171952 -288.343594)
		(mid 384.454908 -288.419771)
		(end 384.737864 -288.343594)
		(width 0.0889)
		(layer "In2.Cu")
		(net "M_I_CPU0_SB_DQ<23>")
	)
	(arc
		(start 379.471936 -288.343594)
		(mid 379.754892 -288.419771)
		(end 380.037848 -288.343594)
		(width 0.0889)
		(layer "In2.Cu")
		(net "M_I_CPU0_SB_DQ<23>")
	)
	(arc
		(start 383.231898 -288.343594)
		(mid 383.514854 -288.419771)
		(end 383.79781 -288.343594)
		(width 0.0889)
		(layer "In2.Cu")
		(net "M_I_CPU0_SB_DQ<23>")
	)
	(arc
		(start 386.617718 -288.343594)
		(mid 386.799969 -288.29321)
		(end 386.983478 -288.338768)
		(width 0.0889)
		(layer "In2.Cu")
		(net "M_I_CPU0_SB_DQ<23>")
	)
	(arc
		(start 384.737864 -288.343594)
		(mid 384.924808 -288.293305)
		(end 385.111752 -288.343594)
		(width 0.0889)
		(layer "In2.Cu")
		(net "M_I_CPU0_SB_DQ<23>")
	)
	(segment
		(start 377.407932 -287.59023)
		(end 377.874784 -287.856168)
		(width 0.10668)
		(layer "F.Cu")
		(net "M_I_CPU0_SB_DQ<22>")
	)
	(segment
		(start 423.206926 -306.86883)
		(end 423.457116 -306.86883)
		(width 0.14478)
		(layer "In2.Cu")
		(net "M_I_CPU0_SB_DQ<22>")
	)
	(segment
		(start 423.457116 -306.86883)
		(end 423.765726 -306.56022)
		(width 0.14478)
		(layer "In2.Cu")
		(net "M_I_CPU0_SB_DQ<22>")
	)
	(segment
		(start 424.727624 -306.56022)
		(end 425.045124 -306.24272)
		(width 0.14478)
		(layer "In2.Cu")
		(net "M_I_CPU0_SB_DQ<22>")
	)
	(segment
		(start 414.10382 -307.35397)
		(end 414.334706 -307.258212)
		(width 0.14478)
		(layer "In2.Cu")
		(net "M_I_CPU0_SB_DQ<22>")
	)
	(segment
		(start 415.345626 -306.56022)
		(end 415.633916 -306.84851)
		(width 0.14478)
		(layer "In2.Cu")
		(net "M_I_CPU0_SB_DQ<22>")
	)
	(segment
		(start 415.633916 -306.84851)
		(end 415.904426 -306.84851)
		(width 0.14478)
		(layer "In2.Cu")
		(net "M_I_CPU0_SB_DQ<22>")
	)
	(segment
		(start 426.13326 -306.24145)
		(end 427.305978 -306.24145)
		(width 0.14478)
		(layer "In2.Cu")
		(net "M_I_CPU0_SB_DQ<22>")
	)
	(segment
		(start 420.978076 -307.410358)
		(end 421.40378 -307.234082)
		(width 0.14478)
		(layer "In2.Cu")
		(net "M_I_CPU0_SB_DQ<22>")
	)
	(segment
		(start 396.5194 -292.948614)
		(end 402.722334 -299.151548)
		(width 0.14478)
		(layer "In2.Cu")
		(net "M_I_CPU0_SB_DQ<22>")
	)
	(segment
		(start 392.66368 -287.668716)
		(end 393.51839 -287.668716)
		(width 0.0889)
		(layer "In2.Cu")
		(net "M_I_CPU0_SB_DQ<22>")
	)
	(segment
		(start 411.569408 -307.410358)
		(end 413.16021 -307.410358)
		(width 0.14478)
		(layer "In2.Cu")
		(net "M_I_CPU0_SB_DQ<22>")
	)
	(segment
		(start 402.722334 -299.151548)
		(end 402.722334 -299.380148)
		(width 0.14478)
		(layer "In2.Cu")
		(net "M_I_CPU0_SB_DQ<22>")
	)
	(segment
		(start 402.722334 -299.380148)
		(end 402.163026 -299.939456)
		(width 0.14478)
		(layer "In2.Cu")
		(net "M_I_CPU0_SB_DQ<22>")
	)
	(segment
		(start 386.147818 -287.533588)
		(end 386.1562 -287.528762)
		(width 0.0889)
		(layer "In2.Cu")
		(net "M_I_CPU0_SB_DQ<22>")
	)
	(segment
		(start 416.192716 -306.56022)
		(end 417.027868 -306.56022)
		(width 0.14478)
		(layer "In2.Cu")
		(net "M_I_CPU0_SB_DQ<22>")
	)
	(segment
		(start 417.027868 -306.56022)
		(end 417.354258 -306.88661)
		(width 0.14478)
		(layer "In2.Cu")
		(net "M_I_CPU0_SB_DQ<22>")
	)
	(segment
		(start 384.63347 -287.528762)
		(end 384.641852 -287.533588)
		(width 0.0889)
		(layer "In2.Cu")
		(net "M_I_CPU0_SB_DQ<22>")
	)
	(segment
		(start 418.972492 -307.410358)
		(end 420.978076 -307.410358)
		(width 0.14478)
		(layer "In2.Cu")
		(net "M_I_CPU0_SB_DQ<22>")
	)
	(segment
		(start 402.943314 -300.719744)
		(end 402.943314 -300.948344)
		(width 0.14478)
		(layer "In2.Cu")
		(net "M_I_CPU0_SB_DQ<22>")
	)
	(segment
		(start 389.333486 -287.528762)
		(end 389.341868 -287.533588)
		(width 0.0889)
		(layer "In2.Cu")
		(net "M_I_CPU0_SB_DQ<22>")
	)
	(segment
		(start 425.974002 -306.719732)
		(end 425.974002 -306.400708)
		(width 0.14478)
		(layer "In2.Cu")
		(net "M_I_CPU0_SB_DQ<22>")
	)
	(segment
		(start 415.904426 -306.84851)
		(end 416.192716 -306.56022)
		(width 0.14478)
		(layer "In2.Cu")
		(net "M_I_CPU0_SB_DQ<22>")
	)
	(segment
		(start 385.207764 -287.533588)
		(end 385.216146 -287.528762)
		(width 0.0889)
		(layer "In2.Cu")
		(net "M_I_CPU0_SB_DQ<22>")
	)
	(segment
		(start 388.393432 -287.528762)
		(end 388.401814 -287.533588)
		(width 0.0889)
		(layer "In2.Cu")
		(net "M_I_CPU0_SB_DQ<22>")
	)
	(segment
		(start 394.322554 -289.410394)
		(end 394.964666 -290.052506)
		(width 0.0889)
		(layer "In2.Cu")
		(net "M_I_CPU0_SB_DQ<22>")
	)
	(segment
		(start 413.69996 -307.186584)
		(end 414.10382 -307.35397)
		(width 0.14478)
		(layer "In2.Cu")
		(net "M_I_CPU0_SB_DQ<22>")
	)
	(segment
		(start 425.415202 -306.719732)
		(end 425.57446 -306.87899)
		(width 0.14478)
		(layer "In2.Cu")
		(net "M_I_CPU0_SB_DQ<22>")
	)
	(segment
		(start 381.447802 -287.533588)
		(end 381.456184 -287.528762)
		(width 0.0889)
		(layer "In2.Cu")
		(net "M_I_CPU0_SB_DQ<22>")
	)
	(segment
		(start 402.163026 -300.168056)
		(end 402.32457 -300.3296)
		(width 0.14478)
		(layer "In2.Cu")
		(net "M_I_CPU0_SB_DQ<22>")
	)
	(segment
		(start 421.81399 -307.404262)
		(end 422.04005 -307.310536)
		(width 0.14478)
		(layer "In2.Cu")
		(net "M_I_CPU0_SB_DQ<22>")
	)
	(segment
		(start 402.55317 -300.3296)
		(end 403.052788 -299.829982)
		(width 0.14478)
		(layer "In2.Cu")
		(net "M_I_CPU0_SB_DQ<22>")
	)
	(segment
		(start 425.57446 -306.87899)
		(end 425.814744 -306.87899)
		(width 0.14478)
		(layer "In2.Cu")
		(net "M_I_CPU0_SB_DQ<22>")
	)
	(segment
		(start 427.305978 -306.24145)
		(end 427.456092 -306.391564)
		(width 0.14478)
		(layer "In2.Cu")
		(net "M_I_CPU0_SB_DQ<22>")
	)
	(segment
		(start 422.04005 -307.310536)
		(end 422.294558 -306.695856)
		(width 0.14478)
		(layer "In2.Cu")
		(net "M_I_CPU0_SB_DQ<22>")
	)
	(segment
		(start 421.40378 -307.234082)
		(end 421.81399 -307.404262)
		(width 0.14478)
		(layer "In2.Cu")
		(net "M_I_CPU0_SB_DQ<22>")
	)
	(segment
		(start 403.281388 -299.829982)
		(end 403.442932 -299.991526)
		(width 0.14478)
		(layer "In2.Cu")
		(net "M_I_CPU0_SB_DQ<22>")
	)
	(segment
		(start 380.873508 -287.528762)
		(end 380.88189 -287.533588)
		(width 0.0889)
		(layer "In2.Cu")
		(net "M_I_CPU0_SB_DQ<22>")
	)
	(segment
		(start 417.354258 -306.88661)
		(end 417.707826 -306.88661)
		(width 0.14478)
		(layer "In2.Cu")
		(net "M_I_CPU0_SB_DQ<22>")
	)
	(segment
		(start 425.045124 -306.24272)
		(end 425.257214 -306.24272)
		(width 0.14478)
		(layer "In2.Cu")
		(net "M_I_CPU0_SB_DQ<22>")
	)
	(segment
		(start 402.32457 -300.3296)
		(end 402.55317 -300.3296)
		(width 0.14478)
		(layer "In2.Cu")
		(net "M_I_CPU0_SB_DQ<22>")
	)
	(segment
		(start 377.72086 -287.590738)
		(end 377.743212 -287.507426)
		(width 0.0889)
		(layer "In2.Cu")
		(net "M_I_CPU0_SB_DQ<22>")
	)
	(segment
		(start 403.442932 -300.220126)
		(end 402.943314 -300.719744)
		(width 0.14478)
		(layer "In2.Cu")
		(net "M_I_CPU0_SB_DQ<22>")
	)
	(segment
		(start 379.933454 -287.528762)
		(end 379.941836 -287.533588)
		(width 0.0889)
		(layer "In2.Cu")
		(net "M_I_CPU0_SB_DQ<22>")
	)
	(segment
		(start 423.765726 -306.56022)
		(end 424.727624 -306.56022)
		(width 0.14478)
		(layer "In2.Cu")
		(net "M_I_CPU0_SB_DQ<22>")
	)
	(segment
		(start 389.90778 -287.533588)
		(end 389.916162 -287.528762)
		(width 0.0889)
		(layer "In2.Cu")
		(net "M_I_CPU0_SB_DQ<22>")
	)
	(segment
		(start 425.415202 -306.400708)
		(end 425.415202 -306.719732)
		(width 0.14478)
		(layer "In2.Cu")
		(net "M_I_CPU0_SB_DQ<22>")
	)
	(segment
		(start 422.294558 -306.695856)
		(end 422.622218 -306.56022)
		(width 0.14478)
		(layer "In2.Cu")
		(net "M_I_CPU0_SB_DQ<22>")
	)
	(segment
		(start 394.322554 -288.42589)
		(end 394.322554 -289.410394)
		(width 0.0889)
		(layer "In2.Cu")
		(net "M_I_CPU0_SB_DQ<22>")
	)
	(segment
		(start 407.874978 -305.880008)
		(end 411.569408 -307.410358)
		(width 0.14478)
		(layer "In2.Cu")
		(net "M_I_CPU0_SB_DQ<22>")
	)
	(segment
		(start 417.707826 -306.88661)
		(end 418.972492 -307.410358)
		(width 0.14478)
		(layer "In2.Cu")
		(net "M_I_CPU0_SB_DQ<22>")
	)
	(segment
		(start 395.571472 -290.659312)
		(end 396.5194 -292.948614)
		(width 0.14478)
		(layer "In2.Cu")
		(net "M_I_CPU0_SB_DQ<22>")
	)
	(segment
		(start 415.112962 -306.56022)
		(end 415.345626 -306.56022)
		(width 0.14478)
		(layer "In2.Cu")
		(net "M_I_CPU0_SB_DQ<22>")
	)
	(segment
		(start 422.622218 -306.56022)
		(end 422.898316 -306.56022)
		(width 0.14478)
		(layer "In2.Cu")
		(net "M_I_CPU0_SB_DQ<22>")
	)
	(segment
		(start 377.874784 -287.856168)
		(end 377.72086 -287.590738)
		(width 0.0889)
		(layer "In2.Cu")
		(net "M_I_CPU0_SB_DQ<22>")
	)
	(segment
		(start 425.814744 -306.87899)
		(end 425.974002 -306.719732)
		(width 0.14478)
		(layer "In2.Cu")
		(net "M_I_CPU0_SB_DQ<22>")
	)
	(segment
		(start 403.052788 -299.829982)
		(end 403.281388 -299.829982)
		(width 0.14478)
		(layer "In2.Cu")
		(net "M_I_CPU0_SB_DQ<22>")
	)
	(segment
		(start 383.693416 -287.528762)
		(end 383.701798 -287.533588)
		(width 0.0889)
		(layer "In2.Cu")
		(net "M_I_CPU0_SB_DQ<22>")
	)
	(segment
		(start 425.257214 -306.24272)
		(end 425.415202 -306.400708)
		(width 0.14478)
		(layer "In2.Cu")
		(net "M_I_CPU0_SB_DQ<22>")
	)
	(segment
		(start 414.522158 -306.804822)
		(end 415.112962 -306.56022)
		(width 0.14478)
		(layer "In2.Cu")
		(net "M_I_CPU0_SB_DQ<22>")
	)
	(segment
		(start 413.16021 -307.410358)
		(end 413.69996 -307.186584)
		(width 0.14478)
		(layer "In2.Cu")
		(net "M_I_CPU0_SB_DQ<22>")
	)
	(segment
		(start 394.964666 -290.052506)
		(end 395.571472 -290.659312)
		(width 0.14478)
		(layer "In2.Cu")
		(net "M_I_CPU0_SB_DQ<22>")
	)
	(segment
		(start 402.943314 -300.948344)
		(end 407.874978 -305.880008)
		(width 0.14478)
		(layer "In2.Cu")
		(net "M_I_CPU0_SB_DQ<22>")
	)
	(segment
		(start 422.898316 -306.56022)
		(end 423.206926 -306.86883)
		(width 0.14478)
		(layer "In2.Cu")
		(net "M_I_CPU0_SB_DQ<22>")
	)
	(segment
		(start 425.974002 -306.400708)
		(end 426.13326 -306.24145)
		(width 0.14478)
		(layer "In2.Cu")
		(net "M_I_CPU0_SB_DQ<22>")
	)
	(segment
		(start 391.787634 -287.533588)
		(end 391.796016 -287.528762)
		(width 0.0889)
		(layer "In2.Cu")
		(net "M_I_CPU0_SB_DQ<22>")
	)
	(segment
		(start 403.442932 -299.991526)
		(end 403.442932 -300.220126)
		(width 0.14478)
		(layer "In2.Cu")
		(net "M_I_CPU0_SB_DQ<22>")
	)
	(segment
		(start 427.456092 -306.391564)
		(end 427.456092 -306.985162)
		(width 0.14478)
		(layer "In2.Cu")
		(net "M_I_CPU0_SB_DQ<22>")
	)
	(segment
		(start 393.598654 -287.70199)
		(end 394.322554 -288.42589)
		(width 0.0889)
		(layer "In2.Cu")
		(net "M_I_CPU0_SB_DQ<22>")
	)
	(segment
		(start 402.163026 -299.939456)
		(end 402.163026 -300.168056)
		(width 0.14478)
		(layer "In2.Cu")
		(net "M_I_CPU0_SB_DQ<22>")
	)
	(segment
		(start 414.334706 -307.258212)
		(end 414.522158 -306.804822)
		(width 0.14478)
		(layer "In2.Cu")
		(net "M_I_CPU0_SB_DQ<22>")
	)
	(arc
		(start 388.401814 -287.533588)
		(mid 388.68477 -287.609731)
		(end 388.967726 -287.533588)
		(width 0.0889)
		(layer "In2.Cu")
		(net "M_I_CPU0_SB_DQ<22>")
	)
	(arc
		(start 392.162284 -287.533588)
		(mid 392.404031 -287.634375)
		(end 392.66368 -287.668716)
		(width 0.0889)
		(layer "In2.Cu")
		(net "M_I_CPU0_SB_DQ<22>")
	)
	(arc
		(start 382.761744 -287.533588)
		(mid 383.0447 -287.609731)
		(end 383.327656 -287.533588)
		(width 0.0889)
		(layer "In2.Cu")
		(net "M_I_CPU0_SB_DQ<22>")
	)
	(arc
		(start 381.821944 -287.533588)
		(mid 382.1049 -287.609731)
		(end 382.387856 -287.533588)
		(width 0.0889)
		(layer "In2.Cu")
		(net "M_I_CPU0_SB_DQ<22>")
	)
	(arc
		(start 385.581906 -287.533588)
		(mid 385.864862 -287.609731)
		(end 386.147818 -287.533588)
		(width 0.0889)
		(layer "In2.Cu")
		(net "M_I_CPU0_SB_DQ<22>")
	)
	(arc
		(start 383.701798 -287.533588)
		(mid 383.984754 -287.609731)
		(end 384.26771 -287.533588)
		(width 0.0889)
		(layer "In2.Cu")
		(net "M_I_CPU0_SB_DQ<22>")
	)
	(arc
		(start 389.341868 -287.533588)
		(mid 389.624824 -287.609731)
		(end 389.90778 -287.533588)
		(width 0.0889)
		(layer "In2.Cu")
		(net "M_I_CPU0_SB_DQ<22>")
	)
	(arc
		(start 383.327656 -287.533588)
		(mid 383.509907 -287.483238)
		(end 383.693416 -287.528762)
		(width 0.0889)
		(layer "In2.Cu")
		(net "M_I_CPU0_SB_DQ<22>")
	)
	(arc
		(start 380.88189 -287.533588)
		(mid 381.164846 -287.609731)
		(end 381.447802 -287.533588)
		(width 0.0889)
		(layer "In2.Cu")
		(net "M_I_CPU0_SB_DQ<22>")
	)
	(arc
		(start 388.027672 -287.533588)
		(mid 388.209923 -287.483238)
		(end 388.393432 -287.528762)
		(width 0.0889)
		(layer "In2.Cu")
		(net "M_I_CPU0_SB_DQ<22>")
	)
	(arc
		(start 390.281922 -287.533588)
		(mid 390.564878 -287.609731)
		(end 390.847834 -287.533588)
		(width 0.0889)
		(layer "In2.Cu")
		(net "M_I_CPU0_SB_DQ<22>")
	)
	(arc
		(start 378.061982 -287.533588)
		(mid 378.344938 -287.609731)
		(end 378.627894 -287.533588)
		(width 0.0889)
		(layer "In2.Cu")
		(net "M_I_CPU0_SB_DQ<22>")
	)
	(arc
		(start 377.743212 -287.507426)
		(mid 377.905544 -287.484608)
		(end 378.061982 -287.533588)
		(width 0.0889)
		(layer "In2.Cu")
		(net "M_I_CPU0_SB_DQ<22>")
	)
	(arc
		(start 386.52196 -287.533588)
		(mid 386.804916 -287.609731)
		(end 387.087872 -287.533588)
		(width 0.0889)
		(layer "In2.Cu")
		(net "M_I_CPU0_SB_DQ<22>")
	)
	(arc
		(start 379.941836 -287.533588)
		(mid 380.224792 -287.609731)
		(end 380.507748 -287.533588)
		(width 0.0889)
		(layer "In2.Cu")
		(net "M_I_CPU0_SB_DQ<22>")
	)
	(arc
		(start 393.51839 -287.668716)
		(mid 393.561825 -287.677374)
		(end 393.598654 -287.70199)
		(width 0.0889)
		(layer "In2.Cu")
		(net "M_I_CPU0_SB_DQ<22>")
	)
	(arc
		(start 382.387856 -287.533588)
		(mid 382.5748 -287.483333)
		(end 382.761744 -287.533588)
		(width 0.0889)
		(layer "In2.Cu")
		(net "M_I_CPU0_SB_DQ<22>")
	)
	(arc
		(start 381.456184 -287.528762)
		(mid 381.639692 -287.483268)
		(end 381.821944 -287.533588)
		(width 0.0889)
		(layer "In2.Cu")
		(net "M_I_CPU0_SB_DQ<22>")
	)
	(arc
		(start 379.001782 -287.533588)
		(mid 379.284738 -287.609731)
		(end 379.567694 -287.533588)
		(width 0.0889)
		(layer "In2.Cu")
		(net "M_I_CPU0_SB_DQ<22>")
	)
	(arc
		(start 389.916162 -287.528762)
		(mid 390.09967 -287.483268)
		(end 390.281922 -287.533588)
		(width 0.0889)
		(layer "In2.Cu")
		(net "M_I_CPU0_SB_DQ<22>")
	)
	(arc
		(start 384.26771 -287.533588)
		(mid 384.449961 -287.483238)
		(end 384.63347 -287.528762)
		(width 0.0889)
		(layer "In2.Cu")
		(net "M_I_CPU0_SB_DQ<22>")
	)
	(arc
		(start 391.221722 -287.533588)
		(mid 391.504678 -287.609731)
		(end 391.787634 -287.533588)
		(width 0.0889)
		(layer "In2.Cu")
		(net "M_I_CPU0_SB_DQ<22>")
	)
	(arc
		(start 387.46176 -287.533588)
		(mid 387.744716 -287.609731)
		(end 388.027672 -287.533588)
		(width 0.0889)
		(layer "In2.Cu")
		(net "M_I_CPU0_SB_DQ<22>")
	)
	(arc
		(start 378.627894 -287.533588)
		(mid 378.814838 -287.483333)
		(end 379.001782 -287.533588)
		(width 0.0889)
		(layer "In2.Cu")
		(net "M_I_CPU0_SB_DQ<22>")
	)
	(arc
		(start 386.1562 -287.528762)
		(mid 386.339708 -287.483268)
		(end 386.52196 -287.533588)
		(width 0.0889)
		(layer "In2.Cu")
		(net "M_I_CPU0_SB_DQ<22>")
	)
	(arc
		(start 380.507748 -287.533588)
		(mid 380.689999 -287.483238)
		(end 380.873508 -287.528762)
		(width 0.0889)
		(layer "In2.Cu")
		(net "M_I_CPU0_SB_DQ<22>")
	)
	(arc
		(start 391.796016 -287.528762)
		(mid 391.979778 -287.483146)
		(end 392.162284 -287.533588)
		(width 0.0889)
		(layer "In2.Cu")
		(net "M_I_CPU0_SB_DQ<22>")
	)
	(arc
		(start 384.641852 -287.533588)
		(mid 384.924808 -287.609731)
		(end 385.207764 -287.533588)
		(width 0.0889)
		(layer "In2.Cu")
		(net "M_I_CPU0_SB_DQ<22>")
	)
	(arc
		(start 385.216146 -287.528762)
		(mid 385.399654 -287.483268)
		(end 385.581906 -287.533588)
		(width 0.0889)
		(layer "In2.Cu")
		(net "M_I_CPU0_SB_DQ<22>")
	)
	(arc
		(start 390.847834 -287.533588)
		(mid 391.034778 -287.483333)
		(end 391.221722 -287.533588)
		(width 0.0889)
		(layer "In2.Cu")
		(net "M_I_CPU0_SB_DQ<22>")
	)
	(arc
		(start 387.087872 -287.533588)
		(mid 387.274816 -287.483333)
		(end 387.46176 -287.533588)
		(width 0.0889)
		(layer "In2.Cu")
		(net "M_I_CPU0_SB_DQ<22>")
	)
	(arc
		(start 379.567694 -287.533588)
		(mid 379.749945 -287.483238)
		(end 379.933454 -287.528762)
		(width 0.0889)
		(layer "In2.Cu")
		(net "M_I_CPU0_SB_DQ<22>")
	)
	(arc
		(start 388.967726 -287.533588)
		(mid 389.149977 -287.483238)
		(end 389.333486 -287.528762)
		(width 0.0889)
		(layer "In2.Cu")
		(net "M_I_CPU0_SB_DQ<22>")
	)
	(segment
		(start 375.528078 -287.59023)
		(end 375.99493 -287.856168)
		(width 0.10668)
		(layer "F.Cu")
		(net "M_I_CPU0_SB_DQ<21>")
	)
	(segment
		(start 395.052804 -291.299392)
		(end 395.55039 -291.796978)
		(width 0.14478)
		(layer "In2.Cu")
		(net "M_I_CPU0_SB_DQ<21>")
	)
	(segment
		(start 419.970966 -308.260242)
		(end 422.277794 -307.801264)
		(width 0.14478)
		(layer "In2.Cu")
		(net "M_I_CPU0_SB_DQ<21>")
	)
	(segment
		(start 423.221912 -307.410358)
		(end 431.131472 -307.410358)
		(width 0.14478)
		(layer "In2.Cu")
		(net "M_I_CPU0_SB_DQ<21>")
	)
	(segment
		(start 395.55039 -291.796978)
		(end 396.129764 -293.195248)
		(width 0.14478)
		(layer "In2.Cu")
		(net "M_I_CPU0_SB_DQ<21>")
	)
	(segment
		(start 392.631422 -288.05251)
		(end 393.636754 -288.05251)
		(width 0.0889)
		(layer "In2.Cu")
		(net "M_I_CPU0_SB_DQ<21>")
	)
	(segment
		(start 396.129764 -293.195248)
		(end 401.713446 -298.77893)
		(width 0.14478)
		(layer "In2.Cu")
		(net "M_I_CPU0_SB_DQ<21>")
	)
	(segment
		(start 411.496256 -308.130702)
		(end 412.147258 -308.260242)
		(width 0.14478)
		(layer "In2.Cu")
		(net "M_I_CPU0_SB_DQ<21>")
	)
	(segment
		(start 385.207764 -288.178494)
		(end 385.216146 -288.18332)
		(width 0.0889)
		(layer "In2.Cu")
		(net "M_I_CPU0_SB_DQ<21>")
	)
	(segment
		(start 380.873508 -288.18332)
		(end 380.88189 -288.178494)
		(width 0.0889)
		(layer "In2.Cu")
		(net "M_I_CPU0_SB_DQ<21>")
	)
	(segment
		(start 401.713446 -298.77893)
		(end 401.713446 -300.354746)
		(width 0.14478)
		(layer "In2.Cu")
		(net "M_I_CPU0_SB_DQ<21>")
	)
	(segment
		(start 383.693416 -288.18332)
		(end 383.701798 -288.178494)
		(width 0.0889)
		(layer "In2.Cu")
		(net "M_I_CPU0_SB_DQ<21>")
	)
	(segment
		(start 394.096494 -288.51225)
		(end 394.096494 -289.743896)
		(width 0.0889)
		(layer "In2.Cu")
		(net "M_I_CPU0_SB_DQ<21>")
	)
	(segment
		(start 394.8176 -291.201856)
		(end 395.052804 -291.299392)
		(width 0.0889)
		(layer "In2.Cu")
		(net "M_I_CPU0_SB_DQ<21>")
	)
	(segment
		(start 381.447802 -288.178494)
		(end 381.456184 -288.18332)
		(width 0.0889)
		(layer "In2.Cu")
		(net "M_I_CPU0_SB_DQ<21>")
	)
	(segment
		(start 384.63347 -288.18332)
		(end 384.641852 -288.178494)
		(width 0.0889)
		(layer "In2.Cu")
		(net "M_I_CPU0_SB_DQ<21>")
	)
	(segment
		(start 408.07005 -306.71135)
		(end 411.496256 -308.130702)
		(width 0.14478)
		(layer "In2.Cu")
		(net "M_I_CPU0_SB_DQ<21>")
	)
	(segment
		(start 422.277794 -307.801264)
		(end 423.221912 -307.410358)
		(width 0.14478)
		(layer "In2.Cu")
		(net "M_I_CPU0_SB_DQ<21>")
	)
	(segment
		(start 394.617448 -291.001704)
		(end 394.8176 -291.201856)
		(width 0.0889)
		(layer "In2.Cu")
		(net "M_I_CPU0_SB_DQ<21>")
	)
	(segment
		(start 401.713446 -300.354746)
		(end 408.07005 -306.71135)
		(width 0.14478)
		(layer "In2.Cu")
		(net "M_I_CPU0_SB_DQ<21>")
	)
	(segment
		(start 412.392114 -308.260242)
		(end 415.785808 -307.410358)
		(width 0.14478)
		(layer "In2.Cu")
		(net "M_I_CPU0_SB_DQ<21>")
	)
	(segment
		(start 419.763702 -308.260242)
		(end 419.970966 -308.260242)
		(width 0.14478)
		(layer "In2.Cu")
		(net "M_I_CPU0_SB_DQ<21>")
	)
	(segment
		(start 417.197794 -307.410358)
		(end 417.469066 -307.46446)
		(width 0.14478)
		(layer "In2.Cu")
		(net "M_I_CPU0_SB_DQ<21>")
	)
	(segment
		(start 377.68784 -288.178494)
		(end 377.696222 -288.18332)
		(width 0.0889)
		(layer "In2.Cu")
		(net "M_I_CPU0_SB_DQ<21>")
	)
	(segment
		(start 392.139932 -288.190178)
		(end 392.160506 -288.178494)
		(width 0.0889)
		(layer "In2.Cu")
		(net "M_I_CPU0_SB_DQ<21>")
	)
	(segment
		(start 376.148854 -288.121598)
		(end 376.244612 -288.146998)
		(width 0.0889)
		(layer "In2.Cu")
		(net "M_I_CPU0_SB_DQ<21>")
	)
	(segment
		(start 379.933454 -288.18332)
		(end 379.941836 -288.178494)
		(width 0.0889)
		(layer "In2.Cu")
		(net "M_I_CPU0_SB_DQ<21>")
	)
	(segment
		(start 412.147258 -308.260242)
		(end 412.392114 -308.260242)
		(width 0.14478)
		(layer "In2.Cu")
		(net "M_I_CPU0_SB_DQ<21>")
	)
	(segment
		(start 431.131472 -307.410358)
		(end 431.55616 -307.835046)
		(width 0.14478)
		(layer "In2.Cu")
		(net "M_I_CPU0_SB_DQ<21>")
	)
	(segment
		(start 418.863018 -307.88737)
		(end 419.763702 -308.260242)
		(width 0.14478)
		(layer "In2.Cu")
		(net "M_I_CPU0_SB_DQ<21>")
	)
	(segment
		(start 376.747786 -288.178494)
		(end 376.756168 -288.18332)
		(width 0.0889)
		(layer "In2.Cu")
		(net "M_I_CPU0_SB_DQ<21>")
	)
	(segment
		(start 375.99493 -287.856168)
		(end 376.148854 -288.121598)
		(width 0.0889)
		(layer "In2.Cu")
		(net "M_I_CPU0_SB_DQ<21>")
	)
	(segment
		(start 386.147818 -288.178494)
		(end 386.1562 -288.18332)
		(width 0.0889)
		(layer "In2.Cu")
		(net "M_I_CPU0_SB_DQ<21>")
	)
	(segment
		(start 394.096494 -289.743896)
		(end 394.617448 -291.001704)
		(width 0.0889)
		(layer "In2.Cu")
		(net "M_I_CPU0_SB_DQ<21>")
	)
	(segment
		(start 393.636754 -288.05251)
		(end 394.096494 -288.51225)
		(width 0.0889)
		(layer "In2.Cu")
		(net "M_I_CPU0_SB_DQ<21>")
	)
	(segment
		(start 415.785808 -307.410358)
		(end 417.197794 -307.410358)
		(width 0.14478)
		(layer "In2.Cu")
		(net "M_I_CPU0_SB_DQ<21>")
	)
	(segment
		(start 388.393432 -288.18332)
		(end 388.401814 -288.178494)
		(width 0.0889)
		(layer "In2.Cu")
		(net "M_I_CPU0_SB_DQ<21>")
	)
	(segment
		(start 389.90778 -288.178494)
		(end 389.916162 -288.18332)
		(width 0.0889)
		(layer "In2.Cu")
		(net "M_I_CPU0_SB_DQ<21>")
	)
	(segment
		(start 417.469066 -307.46446)
		(end 418.863018 -307.88737)
		(width 0.14478)
		(layer "In2.Cu")
		(net "M_I_CPU0_SB_DQ<21>")
	)
	(segment
		(start 389.333486 -288.18332)
		(end 389.341868 -288.178494)
		(width 0.0889)
		(layer "In2.Cu")
		(net "M_I_CPU0_SB_DQ<21>")
	)
	(arc
		(start 390.847834 -288.178494)
		(mid 391.034778 -288.228783)
		(end 391.221722 -288.178494)
		(width 0.0889)
		(layer "In2.Cu")
		(net "M_I_CPU0_SB_DQ<21>")
	)
	(arc
		(start 388.401814 -288.178494)
		(mid 388.68477 -288.102317)
		(end 388.967726 -288.178494)
		(width 0.0889)
		(layer "In2.Cu")
		(net "M_I_CPU0_SB_DQ<21>")
	)
	(arc
		(start 389.341868 -288.178494)
		(mid 389.624824 -288.102317)
		(end 389.90778 -288.178494)
		(width 0.0889)
		(layer "In2.Cu")
		(net "M_I_CPU0_SB_DQ<21>")
	)
	(arc
		(start 377.121928 -288.178494)
		(mid 377.404884 -288.102317)
		(end 377.68784 -288.178494)
		(width 0.0889)
		(layer "In2.Cu")
		(net "M_I_CPU0_SB_DQ<21>")
	)
	(arc
		(start 384.641852 -288.178494)
		(mid 384.924808 -288.102317)
		(end 385.207764 -288.178494)
		(width 0.0889)
		(layer "In2.Cu")
		(net "M_I_CPU0_SB_DQ<21>")
	)
	(arc
		(start 391.787634 -288.178494)
		(mid 391.962305 -288.228581)
		(end 392.139932 -288.190178)
		(width 0.0889)
		(layer "In2.Cu")
		(net "M_I_CPU0_SB_DQ<21>")
	)
	(arc
		(start 387.46176 -288.178494)
		(mid 387.744716 -288.102317)
		(end 388.027672 -288.178494)
		(width 0.0889)
		(layer "In2.Cu")
		(net "M_I_CPU0_SB_DQ<21>")
	)
	(arc
		(start 377.696222 -288.18332)
		(mid 377.87973 -288.228845)
		(end 378.061982 -288.178494)
		(width 0.0889)
		(layer "In2.Cu")
		(net "M_I_CPU0_SB_DQ<21>")
	)
	(arc
		(start 380.507748 -288.178494)
		(mid 380.689999 -288.228878)
		(end 380.873508 -288.18332)
		(width 0.0889)
		(layer "In2.Cu")
		(net "M_I_CPU0_SB_DQ<21>")
	)
	(arc
		(start 388.027672 -288.178494)
		(mid 388.209923 -288.228878)
		(end 388.393432 -288.18332)
		(width 0.0889)
		(layer "In2.Cu")
		(net "M_I_CPU0_SB_DQ<21>")
	)
	(arc
		(start 385.216146 -288.18332)
		(mid 385.399654 -288.228845)
		(end 385.581906 -288.178494)
		(width 0.0889)
		(layer "In2.Cu")
		(net "M_I_CPU0_SB_DQ<21>")
	)
	(arc
		(start 386.52196 -288.178494)
		(mid 386.804916 -288.102317)
		(end 387.087872 -288.178494)
		(width 0.0889)
		(layer "In2.Cu")
		(net "M_I_CPU0_SB_DQ<21>")
	)
	(arc
		(start 389.916162 -288.18332)
		(mid 390.09967 -288.228845)
		(end 390.281922 -288.178494)
		(width 0.0889)
		(layer "In2.Cu")
		(net "M_I_CPU0_SB_DQ<21>")
	)
	(arc
		(start 378.061982 -288.178494)
		(mid 378.344938 -288.102317)
		(end 378.627894 -288.178494)
		(width 0.0889)
		(layer "In2.Cu")
		(net "M_I_CPU0_SB_DQ<21>")
	)
	(arc
		(start 376.756168 -288.18332)
		(mid 376.939676 -288.228845)
		(end 377.121928 -288.178494)
		(width 0.0889)
		(layer "In2.Cu")
		(net "M_I_CPU0_SB_DQ<21>")
	)
	(arc
		(start 383.327656 -288.178494)
		(mid 383.509907 -288.228878)
		(end 383.693416 -288.18332)
		(width 0.0889)
		(layer "In2.Cu")
		(net "M_I_CPU0_SB_DQ<21>")
	)
	(arc
		(start 381.456184 -288.18332)
		(mid 381.639692 -288.228845)
		(end 381.821944 -288.178494)
		(width 0.0889)
		(layer "In2.Cu")
		(net "M_I_CPU0_SB_DQ<21>")
	)
	(arc
		(start 376.244612 -288.146998)
		(mid 376.499934 -288.103298)
		(end 376.747786 -288.178494)
		(width 0.0889)
		(layer "In2.Cu")
		(net "M_I_CPU0_SB_DQ<21>")
	)
	(arc
		(start 392.160506 -288.178494)
		(mid 392.387679 -288.084524)
		(end 392.631422 -288.05251)
		(width 0.0889)
		(layer "In2.Cu")
		(net "M_I_CPU0_SB_DQ<21>")
	)
	(arc
		(start 391.221722 -288.178494)
		(mid 391.504678 -288.102317)
		(end 391.787634 -288.178494)
		(width 0.0889)
		(layer "In2.Cu")
		(net "M_I_CPU0_SB_DQ<21>")
	)
	(arc
		(start 384.26771 -288.178494)
		(mid 384.449961 -288.228878)
		(end 384.63347 -288.18332)
		(width 0.0889)
		(layer "In2.Cu")
		(net "M_I_CPU0_SB_DQ<21>")
	)
	(arc
		(start 390.281922 -288.178494)
		(mid 390.564878 -288.102317)
		(end 390.847834 -288.178494)
		(width 0.0889)
		(layer "In2.Cu")
		(net "M_I_CPU0_SB_DQ<21>")
	)
	(arc
		(start 379.001782 -288.178494)
		(mid 379.284738 -288.102317)
		(end 379.567694 -288.178494)
		(width 0.0889)
		(layer "In2.Cu")
		(net "M_I_CPU0_SB_DQ<21>")
	)
	(arc
		(start 382.761744 -288.178494)
		(mid 383.0447 -288.102317)
		(end 383.327656 -288.178494)
		(width 0.0889)
		(layer "In2.Cu")
		(net "M_I_CPU0_SB_DQ<21>")
	)
	(arc
		(start 388.967726 -288.178494)
		(mid 389.149977 -288.228878)
		(end 389.333486 -288.18332)
		(width 0.0889)
		(layer "In2.Cu")
		(net "M_I_CPU0_SB_DQ<21>")
	)
	(arc
		(start 386.1562 -288.18332)
		(mid 386.339708 -288.228845)
		(end 386.52196 -288.178494)
		(width 0.0889)
		(layer "In2.Cu")
		(net "M_I_CPU0_SB_DQ<21>")
	)
	(arc
		(start 378.627894 -288.178494)
		(mid 378.814838 -288.228783)
		(end 379.001782 -288.178494)
		(width 0.0889)
		(layer "In2.Cu")
		(net "M_I_CPU0_SB_DQ<21>")
	)
	(arc
		(start 380.88189 -288.178494)
		(mid 381.164846 -288.102317)
		(end 381.447802 -288.178494)
		(width 0.0889)
		(layer "In2.Cu")
		(net "M_I_CPU0_SB_DQ<21>")
	)
	(arc
		(start 385.581906 -288.178494)
		(mid 385.864862 -288.102317)
		(end 386.147818 -288.178494)
		(width 0.0889)
		(layer "In2.Cu")
		(net "M_I_CPU0_SB_DQ<21>")
	)
	(arc
		(start 381.821944 -288.178494)
		(mid 382.1049 -288.102317)
		(end 382.387856 -288.178494)
		(width 0.0889)
		(layer "In2.Cu")
		(net "M_I_CPU0_SB_DQ<21>")
	)
	(arc
		(start 387.087872 -288.178494)
		(mid 387.274816 -288.228783)
		(end 387.46176 -288.178494)
		(width 0.0889)
		(layer "In2.Cu")
		(net "M_I_CPU0_SB_DQ<21>")
	)
	(arc
		(start 383.701798 -288.178494)
		(mid 383.984754 -288.102317)
		(end 384.26771 -288.178494)
		(width 0.0889)
		(layer "In2.Cu")
		(net "M_I_CPU0_SB_DQ<21>")
	)
	(arc
		(start 382.387856 -288.178494)
		(mid 382.5748 -288.228783)
		(end 382.761744 -288.178494)
		(width 0.0889)
		(layer "In2.Cu")
		(net "M_I_CPU0_SB_DQ<21>")
	)
	(arc
		(start 379.941836 -288.178494)
		(mid 380.224792 -288.102317)
		(end 380.507748 -288.178494)
		(width 0.0889)
		(layer "In2.Cu")
		(net "M_I_CPU0_SB_DQ<21>")
	)
	(arc
		(start 379.567694 -288.178494)
		(mid 379.749945 -288.228878)
		(end 379.933454 -288.18332)
		(width 0.0889)
		(layer "In2.Cu")
		(net "M_I_CPU0_SB_DQ<21>")
	)
	(segment
		(start 376.938032 -286.780224)
		(end 377.404884 -287.045908)
		(width 0.10668)
		(layer "F.Cu")
		(net "M_I_CPU0_SB_DQ<20>")
	)
	(segment
		(start 394.525754 -289.282124)
		(end 394.81506 -289.57143)
		(width 0.0889)
		(layer "In2.Cu")
		(net "M_I_CPU0_SB_DQ<20>")
	)
	(segment
		(start 414.935416 -305.719734)
		(end 417.857432 -305.719734)
		(width 0.14478)
		(layer "In2.Cu")
		(net "M_I_CPU0_SB_DQ<20>")
	)
	(segment
		(start 431.14087 -305.719734)
		(end 431.55616 -306.135024)
		(width 0.14478)
		(layer "In2.Cu")
		(net "M_I_CPU0_SB_DQ<20>")
	)
	(segment
		(start 421.717216 -306.569872)
		(end 422.567354 -305.719734)
		(width 0.14478)
		(layer "In2.Cu")
		(net "M_I_CPU0_SB_DQ<20>")
	)
	(segment
		(start 418.708078 -306.569872)
		(end 421.717216 -306.569872)
		(width 0.14478)
		(layer "In2.Cu")
		(net "M_I_CPU0_SB_DQ<20>")
	)
	(segment
		(start 430.228502 -305.881278)
		(end 430.390046 -305.719734)
		(width 0.14478)
		(layer "In2.Cu")
		(net "M_I_CPU0_SB_DQ<20>")
	)
	(segment
		(start 391.691876 -287.368488)
		(end 391.706608 -287.359852)
		(width 0.0889)
		(layer "In2.Cu")
		(net "M_I_CPU0_SB_DQ<20>")
	)
	(segment
		(start 386.043424 -287.373314)
		(end 386.051806 -287.368488)
		(width 0.0889)
		(layer "In2.Cu")
		(net "M_I_CPU0_SB_DQ<20>")
	)
	(segment
		(start 396.919958 -292.712902)
		(end 403.910292 -299.703236)
		(width 0.14478)
		(layer "In2.Cu")
		(net "M_I_CPU0_SB_DQ<20>")
	)
	(segment
		(start 377.404884 -287.045908)
		(end 377.558808 -287.311338)
		(width 0.0889)
		(layer "In2.Cu")
		(net "M_I_CPU0_SB_DQ<20>")
	)
	(segment
		(start 429.515524 -305.719734)
		(end 429.677068 -305.881278)
		(width 0.14478)
		(layer "In2.Cu")
		(net "M_I_CPU0_SB_DQ<20>")
	)
	(segment
		(start 395.181074 -289.57143)
		(end 395.4018 -289.792156)
		(width 0.0889)
		(layer "In2.Cu")
		(net "M_I_CPU0_SB_DQ<20>")
	)
	(segment
		(start 429.677068 -305.881278)
		(end 429.677068 -306.332128)
		(width 0.14478)
		(layer "In2.Cu")
		(net "M_I_CPU0_SB_DQ<20>")
	)
	(segment
		(start 403.910292 -299.703236)
		(end 403.910292 -301.279052)
		(width 0.14478)
		(layer "In2.Cu")
		(net "M_I_CPU0_SB_DQ<20>")
	)
	(segment
		(start 394.525754 -288.33445)
		(end 394.525754 -289.282124)
		(width 0.0889)
		(layer "In2.Cu")
		(net "M_I_CPU0_SB_DQ<20>")
	)
	(segment
		(start 417.858194 -305.719988)
		(end 418.708078 -306.569872)
		(width 0.14478)
		(layer "In2.Cu")
		(net "M_I_CPU0_SB_DQ<20>")
	)
	(segment
		(start 430.066958 -306.493672)
		(end 430.228502 -306.332128)
		(width 0.14478)
		(layer "In2.Cu")
		(net "M_I_CPU0_SB_DQ<20>")
	)
	(segment
		(start 380.037848 -287.368488)
		(end 380.04623 -287.373314)
		(width 0.0889)
		(layer "In2.Cu")
		(net "M_I_CPU0_SB_DQ<20>")
	)
	(segment
		(start 377.558808 -287.311338)
		(end 377.65482 -287.336738)
		(width 0.0889)
		(layer "In2.Cu")
		(net "M_I_CPU0_SB_DQ<20>")
	)
	(segment
		(start 395.927834 -290.31819)
		(end 396.919958 -292.712902)
		(width 0.14478)
		(layer "In2.Cu")
		(net "M_I_CPU0_SB_DQ<20>")
	)
	(segment
		(start 391.317734 -287.368488)
		(end 391.326116 -287.373314)
		(width 0.0889)
		(layer "In2.Cu")
		(net "M_I_CPU0_SB_DQ<20>")
	)
	(segment
		(start 395.4018 -289.792156)
		(end 395.927834 -290.31819)
		(width 0.14478)
		(layer "In2.Cu")
		(net "M_I_CPU0_SB_DQ<20>")
	)
	(segment
		(start 403.910292 -301.279052)
		(end 407.944066 -305.312826)
		(width 0.14478)
		(layer "In2.Cu")
		(net "M_I_CPU0_SB_DQ<20>")
	)
	(segment
		(start 422.567354 -305.719734)
		(end 429.515524 -305.719734)
		(width 0.14478)
		(layer "In2.Cu")
		(net "M_I_CPU0_SB_DQ<20>")
	)
	(segment
		(start 414.085278 -306.569872)
		(end 414.935416 -305.719734)
		(width 0.14478)
		(layer "In2.Cu")
		(net "M_I_CPU0_SB_DQ<20>")
	)
	(segment
		(start 430.228502 -306.332128)
		(end 430.228502 -305.881278)
		(width 0.14478)
		(layer "In2.Cu")
		(net "M_I_CPU0_SB_DQ<20>")
	)
	(segment
		(start 393.682728 -287.491424)
		(end 394.525754 -288.33445)
		(width 0.0889)
		(layer "In2.Cu")
		(net "M_I_CPU0_SB_DQ<20>")
	)
	(segment
		(start 410.978858 -306.569872)
		(end 414.085278 -306.569872)
		(width 0.14478)
		(layer "In2.Cu")
		(net "M_I_CPU0_SB_DQ<20>")
	)
	(segment
		(start 429.838612 -306.493672)
		(end 430.066958 -306.493672)
		(width 0.14478)
		(layer "In2.Cu")
		(net "M_I_CPU0_SB_DQ<20>")
	)
	(segment
		(start 382.857756 -287.368488)
		(end 382.866138 -287.373314)
		(width 0.0889)
		(layer "In2.Cu")
		(net "M_I_CPU0_SB_DQ<20>")
	)
	(segment
		(start 378.5235 -287.373314)
		(end 378.531882 -287.368488)
		(width 0.0889)
		(layer "In2.Cu")
		(net "M_I_CPU0_SB_DQ<20>")
	)
	(segment
		(start 388.497826 -287.368488)
		(end 388.506208 -287.373314)
		(width 0.0889)
		(layer "In2.Cu")
		(net "M_I_CPU0_SB_DQ<20>")
	)
	(segment
		(start 394.81506 -289.57143)
		(end 395.181074 -289.57143)
		(width 0.0889)
		(layer "In2.Cu")
		(net "M_I_CPU0_SB_DQ<20>")
	)
	(segment
		(start 379.097794 -287.368488)
		(end 379.106176 -287.373314)
		(width 0.0889)
		(layer "In2.Cu")
		(net "M_I_CPU0_SB_DQ<20>")
	)
	(segment
		(start 382.283462 -287.373314)
		(end 382.291844 -287.368488)
		(width 0.0889)
		(layer "In2.Cu")
		(net "M_I_CPU0_SB_DQ<20>")
	)
	(segment
		(start 390.74344 -287.373314)
		(end 390.751822 -287.368488)
		(width 0.0889)
		(layer "In2.Cu")
		(net "M_I_CPU0_SB_DQ<20>")
	)
	(segment
		(start 383.79781 -287.368488)
		(end 383.806192 -287.373314)
		(width 0.0889)
		(layer "In2.Cu")
		(net "M_I_CPU0_SB_DQ<20>")
	)
	(segment
		(start 407.944066 -305.312826)
		(end 410.978858 -306.569872)
		(width 0.14478)
		(layer "In2.Cu")
		(net "M_I_CPU0_SB_DQ<20>")
	)
	(segment
		(start 392.589258 -287.45815)
		(end 393.602464 -287.45815)
		(width 0.0889)
		(layer "In2.Cu")
		(net "M_I_CPU0_SB_DQ<20>")
	)
	(segment
		(start 386.983478 -287.373314)
		(end 386.99186 -287.368488)
		(width 0.0889)
		(layer "In2.Cu")
		(net "M_I_CPU0_SB_DQ<20>")
	)
	(segment
		(start 417.857432 -305.719734)
		(end 417.858194 -305.719988)
		(width 0.14478)
		(layer "In2.Cu")
		(net "M_I_CPU0_SB_DQ<20>")
	)
	(segment
		(start 387.557772 -287.368488)
		(end 387.566154 -287.373314)
		(width 0.0889)
		(layer "In2.Cu")
		(net "M_I_CPU0_SB_DQ<20>")
	)
	(segment
		(start 430.390046 -305.719734)
		(end 431.14087 -305.719734)
		(width 0.14478)
		(layer "In2.Cu")
		(net "M_I_CPU0_SB_DQ<20>")
	)
	(segment
		(start 429.677068 -306.332128)
		(end 429.838612 -306.493672)
		(width 0.14478)
		(layer "In2.Cu")
		(net "M_I_CPU0_SB_DQ<20>")
	)
	(arc
		(start 392.258296 -287.368488)
		(mid 392.417819 -287.435295)
		(end 392.589258 -287.45815)
		(width 0.0889)
		(layer "In2.Cu")
		(net "M_I_CPU0_SB_DQ<20>")
	)
	(arc
		(start 384.171952 -287.368488)
		(mid 384.454908 -287.292345)
		(end 384.737864 -287.368488)
		(width 0.0889)
		(layer "In2.Cu")
		(net "M_I_CPU0_SB_DQ<20>")
	)
	(arc
		(start 387.566154 -287.373314)
		(mid 387.749662 -287.418808)
		(end 387.931914 -287.368488)
		(width 0.0889)
		(layer "In2.Cu")
		(net "M_I_CPU0_SB_DQ<20>")
	)
	(arc
		(start 385.677664 -287.368488)
		(mid 385.859915 -287.418838)
		(end 386.043424 -287.373314)
		(width 0.0889)
		(layer "In2.Cu")
		(net "M_I_CPU0_SB_DQ<20>")
	)
	(arc
		(start 381.917702 -287.368488)
		(mid 382.099953 -287.418838)
		(end 382.283462 -287.373314)
		(width 0.0889)
		(layer "In2.Cu")
		(net "M_I_CPU0_SB_DQ<20>")
	)
	(arc
		(start 388.871968 -287.368488)
		(mid 389.154924 -287.292345)
		(end 389.43788 -287.368488)
		(width 0.0889)
		(layer "In2.Cu")
		(net "M_I_CPU0_SB_DQ<20>")
	)
	(arc
		(start 389.811768 -287.368488)
		(mid 390.094724 -287.292345)
		(end 390.37768 -287.368488)
		(width 0.0889)
		(layer "In2.Cu")
		(net "M_I_CPU0_SB_DQ<20>")
	)
	(arc
		(start 388.506208 -287.373314)
		(mid 388.689716 -287.418808)
		(end 388.871968 -287.368488)
		(width 0.0889)
		(layer "In2.Cu")
		(net "M_I_CPU0_SB_DQ<20>")
	)
	(arc
		(start 383.231898 -287.368488)
		(mid 383.514854 -287.292345)
		(end 383.79781 -287.368488)
		(width 0.0889)
		(layer "In2.Cu")
		(net "M_I_CPU0_SB_DQ<20>")
	)
	(arc
		(start 378.531882 -287.368488)
		(mid 378.814838 -287.292345)
		(end 379.097794 -287.368488)
		(width 0.0889)
		(layer "In2.Cu")
		(net "M_I_CPU0_SB_DQ<20>")
	)
	(arc
		(start 386.617718 -287.368488)
		(mid 386.799969 -287.418838)
		(end 386.983478 -287.373314)
		(width 0.0889)
		(layer "In2.Cu")
		(net "M_I_CPU0_SB_DQ<20>")
	)
	(arc
		(start 383.806192 -287.373314)
		(mid 383.9897 -287.418808)
		(end 384.171952 -287.368488)
		(width 0.0889)
		(layer "In2.Cu")
		(net "M_I_CPU0_SB_DQ<20>")
	)
	(arc
		(start 382.866138 -287.373314)
		(mid 383.049646 -287.418808)
		(end 383.231898 -287.368488)
		(width 0.0889)
		(layer "In2.Cu")
		(net "M_I_CPU0_SB_DQ<20>")
	)
	(arc
		(start 391.706608 -287.359852)
		(mid 391.983591 -287.292078)
		(end 392.258296 -287.368488)
		(width 0.0889)
		(layer "In2.Cu")
		(net "M_I_CPU0_SB_DQ<20>")
	)
	(arc
		(start 380.41199 -287.368488)
		(mid 380.694946 -287.292345)
		(end 380.977902 -287.368488)
		(width 0.0889)
		(layer "In2.Cu")
		(net "M_I_CPU0_SB_DQ<20>")
	)
	(arc
		(start 386.99186 -287.368488)
		(mid 387.274816 -287.292345)
		(end 387.557772 -287.368488)
		(width 0.0889)
		(layer "In2.Cu")
		(net "M_I_CPU0_SB_DQ<20>")
	)
	(arc
		(start 385.111752 -287.368488)
		(mid 385.394708 -287.292345)
		(end 385.677664 -287.368488)
		(width 0.0889)
		(layer "In2.Cu")
		(net "M_I_CPU0_SB_DQ<20>")
	)
	(arc
		(start 382.291844 -287.368488)
		(mid 382.5748 -287.292345)
		(end 382.857756 -287.368488)
		(width 0.0889)
		(layer "In2.Cu")
		(net "M_I_CPU0_SB_DQ<20>")
	)
	(arc
		(start 380.04623 -287.373314)
		(mid 380.229738 -287.418808)
		(end 380.41199 -287.368488)
		(width 0.0889)
		(layer "In2.Cu")
		(net "M_I_CPU0_SB_DQ<20>")
	)
	(arc
		(start 389.43788 -287.368488)
		(mid 389.624824 -287.418743)
		(end 389.811768 -287.368488)
		(width 0.0889)
		(layer "In2.Cu")
		(net "M_I_CPU0_SB_DQ<20>")
	)
	(arc
		(start 377.65482 -287.336738)
		(mid 377.910028 -287.293281)
		(end 378.15774 -287.368488)
		(width 0.0889)
		(layer "In2.Cu")
		(net "M_I_CPU0_SB_DQ<20>")
	)
	(arc
		(start 393.602464 -287.45815)
		(mid 393.645899 -287.466808)
		(end 393.682728 -287.491424)
		(width 0.0889)
		(layer "In2.Cu")
		(net "M_I_CPU0_SB_DQ<20>")
	)
	(arc
		(start 384.737864 -287.368488)
		(mid 384.924808 -287.418743)
		(end 385.111752 -287.368488)
		(width 0.0889)
		(layer "In2.Cu")
		(net "M_I_CPU0_SB_DQ<20>")
	)
	(arc
		(start 390.37768 -287.368488)
		(mid 390.559931 -287.418838)
		(end 390.74344 -287.373314)
		(width 0.0889)
		(layer "In2.Cu")
		(net "M_I_CPU0_SB_DQ<20>")
	)
	(arc
		(start 391.326116 -287.373314)
		(mid 391.509624 -287.418808)
		(end 391.691876 -287.368488)
		(width 0.0889)
		(layer "In2.Cu")
		(net "M_I_CPU0_SB_DQ<20>")
	)
	(arc
		(start 380.977902 -287.368488)
		(mid 381.164846 -287.418743)
		(end 381.35179 -287.368488)
		(width 0.0889)
		(layer "In2.Cu")
		(net "M_I_CPU0_SB_DQ<20>")
	)
	(arc
		(start 381.35179 -287.368488)
		(mid 381.634746 -287.292345)
		(end 381.917702 -287.368488)
		(width 0.0889)
		(layer "In2.Cu")
		(net "M_I_CPU0_SB_DQ<20>")
	)
	(arc
		(start 378.15774 -287.368488)
		(mid 378.339991 -287.418838)
		(end 378.5235 -287.373314)
		(width 0.0889)
		(layer "In2.Cu")
		(net "M_I_CPU0_SB_DQ<20>")
	)
	(arc
		(start 390.751822 -287.368488)
		(mid 391.034778 -287.292345)
		(end 391.317734 -287.368488)
		(width 0.0889)
		(layer "In2.Cu")
		(net "M_I_CPU0_SB_DQ<20>")
	)
	(arc
		(start 386.051806 -287.368488)
		(mid 386.334762 -287.292345)
		(end 386.617718 -287.368488)
		(width 0.0889)
		(layer "In2.Cu")
		(net "M_I_CPU0_SB_DQ<20>")
	)
	(arc
		(start 387.931914 -287.368488)
		(mid 388.21487 -287.292345)
		(end 388.497826 -287.368488)
		(width 0.0889)
		(layer "In2.Cu")
		(net "M_I_CPU0_SB_DQ<20>")
	)
	(arc
		(start 379.471936 -287.368488)
		(mid 379.754892 -287.292345)
		(end 380.037848 -287.368488)
		(width 0.0889)
		(layer "In2.Cu")
		(net "M_I_CPU0_SB_DQ<20>")
	)
	(arc
		(start 379.106176 -287.373314)
		(mid 379.289684 -287.418808)
		(end 379.471936 -287.368488)
		(width 0.0889)
		(layer "In2.Cu")
		(net "M_I_CPU0_SB_DQ<20>")
	)
	(segment
		(start 375.528078 -274.630134)
		(end 375.99493 -274.896072)
		(width 0.10668)
		(layer "F.Cu")
		(net "M_I_CPU0_SB_DQ<1>")
	)
	(segment
		(start 395.20622 -274.00885)
		(end 394.688568 -274.00885)
		(width 0.0889)
		(layer "In2.Cu")
		(net "M_I_CPU0_SB_DQ<1>")
	)
	(segment
		(start 422.980866 -282.760166)
		(end 420.928546 -283.61005)
		(width 0.14478)
		(layer "In2.Cu")
		(net "M_I_CPU0_SB_DQ<1>")
	)
	(segment
		(start 393.694666 -274.859242)
		(end 393.099798 -275.218652)
		(width 0.0889)
		(layer "In2.Cu")
		(net "M_I_CPU0_SB_DQ<1>")
	)
	(segment
		(start 385.216146 -275.223478)
		(end 385.207764 -275.218652)
		(width 0.0889)
		(layer "In2.Cu")
		(net "M_I_CPU0_SB_DQ<1>")
	)
	(segment
		(start 400.98218 -273.84883)
		(end 396.000986 -273.84883)
		(width 0.14478)
		(layer "In2.Cu")
		(net "M_I_CPU0_SB_DQ<1>")
	)
	(segment
		(start 381.456184 -275.223478)
		(end 381.447802 -275.218652)
		(width 0.0889)
		(layer "In2.Cu")
		(net "M_I_CPU0_SB_DQ<1>")
	)
	(segment
		(start 392.74496 -275.23059)
		(end 392.724386 -275.218652)
		(width 0.0889)
		(layer "In2.Cu")
		(net "M_I_CPU0_SB_DQ<1>")
	)
	(segment
		(start 376.756168 -275.223478)
		(end 376.747786 -275.218652)
		(width 0.0889)
		(layer "In2.Cu")
		(net "M_I_CPU0_SB_DQ<1>")
	)
	(segment
		(start 388.401814 -275.218652)
		(end 388.393432 -275.223478)
		(width 0.0889)
		(layer "In2.Cu")
		(net "M_I_CPU0_SB_DQ<1>")
	)
	(segment
		(start 431.131218 -282.760166)
		(end 422.980866 -282.760166)
		(width 0.14478)
		(layer "In2.Cu")
		(net "M_I_CPU0_SB_DQ<1>")
	)
	(segment
		(start 395.36624 -273.84883)
		(end 395.20622 -274.00885)
		(width 0.0889)
		(layer "In2.Cu")
		(net "M_I_CPU0_SB_DQ<1>")
	)
	(segment
		(start 384.641852 -275.218652)
		(end 384.63347 -275.223478)
		(width 0.0889)
		(layer "In2.Cu")
		(net "M_I_CPU0_SB_DQ<1>")
	)
	(segment
		(start 380.88189 -275.218652)
		(end 380.873508 -275.223478)
		(width 0.0889)
		(layer "In2.Cu")
		(net "M_I_CPU0_SB_DQ<1>")
	)
	(segment
		(start 415.762948 -282.760166)
		(end 413.711644 -283.61005)
		(width 0.14478)
		(layer "In2.Cu")
		(net "M_I_CPU0_SB_DQ<1>")
	)
	(segment
		(start 379.941836 -275.218652)
		(end 379.933454 -275.223478)
		(width 0.0889)
		(layer "In2.Cu")
		(net "M_I_CPU0_SB_DQ<1>")
	)
	(segment
		(start 411.587696 -283.61005)
		(end 407.006806 -279.02916)
		(width 0.14478)
		(layer "In2.Cu")
		(net "M_I_CPU0_SB_DQ<1>")
	)
	(segment
		(start 394.688568 -274.00885)
		(end 393.977622 -274.719796)
		(width 0.0889)
		(layer "In2.Cu")
		(net "M_I_CPU0_SB_DQ<1>")
	)
	(segment
		(start 406.16251 -279.02916)
		(end 400.98218 -273.84883)
		(width 0.14478)
		(layer "In2.Cu")
		(net "M_I_CPU0_SB_DQ<1>")
	)
	(segment
		(start 377.696222 -275.223478)
		(end 377.68784 -275.218652)
		(width 0.0889)
		(layer "In2.Cu")
		(net "M_I_CPU0_SB_DQ<1>")
	)
	(segment
		(start 393.977622 -274.719796)
		(end 393.694666 -274.859242)
		(width 0.0889)
		(layer "In2.Cu")
		(net "M_I_CPU0_SB_DQ<1>")
	)
	(segment
		(start 383.701798 -275.218652)
		(end 383.693416 -275.223478)
		(width 0.0889)
		(layer "In2.Cu")
		(net "M_I_CPU0_SB_DQ<1>")
	)
	(segment
		(start 376.244866 -275.186902)
		(end 376.148854 -275.161502)
		(width 0.0889)
		(layer "In2.Cu")
		(net "M_I_CPU0_SB_DQ<1>")
	)
	(segment
		(start 389.341868 -275.218652)
		(end 389.333486 -275.223478)
		(width 0.0889)
		(layer "In2.Cu")
		(net "M_I_CPU0_SB_DQ<1>")
	)
	(segment
		(start 389.916162 -275.223478)
		(end 389.90778 -275.218652)
		(width 0.0889)
		(layer "In2.Cu")
		(net "M_I_CPU0_SB_DQ<1>")
	)
	(segment
		(start 376.148854 -275.161502)
		(end 375.99493 -274.896072)
		(width 0.0889)
		(layer "In2.Cu")
		(net "M_I_CPU0_SB_DQ<1>")
	)
	(segment
		(start 386.1562 -275.223478)
		(end 386.147818 -275.218652)
		(width 0.0889)
		(layer "In2.Cu")
		(net "M_I_CPU0_SB_DQ<1>")
	)
	(segment
		(start 407.006806 -279.02916)
		(end 406.16251 -279.02916)
		(width 0.14478)
		(layer "In2.Cu")
		(net "M_I_CPU0_SB_DQ<1>")
	)
	(segment
		(start 418.86124 -283.61005)
		(end 418.011356 -282.760166)
		(width 0.14478)
		(layer "In2.Cu")
		(net "M_I_CPU0_SB_DQ<1>")
	)
	(segment
		(start 396.000986 -273.84883)
		(end 395.36624 -273.84883)
		(width 0.0889)
		(layer "In2.Cu")
		(net "M_I_CPU0_SB_DQ<1>")
	)
	(segment
		(start 420.928546 -283.61005)
		(end 418.86124 -283.61005)
		(width 0.14478)
		(layer "In2.Cu")
		(net "M_I_CPU0_SB_DQ<1>")
	)
	(segment
		(start 392.160506 -275.218398)
		(end 392.137138 -275.23186)
		(width 0.0889)
		(layer "In2.Cu")
		(net "M_I_CPU0_SB_DQ<1>")
	)
	(segment
		(start 413.711644 -283.61005)
		(end 411.587696 -283.61005)
		(width 0.14478)
		(layer "In2.Cu")
		(net "M_I_CPU0_SB_DQ<1>")
	)
	(segment
		(start 392.186668 -275.203412)
		(end 392.160506 -275.218398)
		(width 0.0889)
		(layer "In2.Cu")
		(net "M_I_CPU0_SB_DQ<1>")
	)
	(segment
		(start 431.55616 -283.185108)
		(end 431.131218 -282.760166)
		(width 0.14478)
		(layer "In2.Cu")
		(net "M_I_CPU0_SB_DQ<1>")
	)
	(segment
		(start 418.011356 -282.760166)
		(end 415.762948 -282.760166)
		(width 0.14478)
		(layer "In2.Cu")
		(net "M_I_CPU0_SB_DQ<1>")
	)
	(arc
		(start 385.207764 -275.218652)
		(mid 384.924808 -275.142475)
		(end 384.641852 -275.218652)
		(width 0.0889)
		(layer "In2.Cu")
		(net "M_I_CPU0_SB_DQ<1>")
	)
	(arc
		(start 387.087872 -275.218652)
		(mid 386.804916 -275.142475)
		(end 386.52196 -275.218652)
		(width 0.0889)
		(layer "In2.Cu")
		(net "M_I_CPU0_SB_DQ<1>")
	)
	(arc
		(start 387.46176 -275.218652)
		(mid 387.274816 -275.268907)
		(end 387.087872 -275.218652)
		(width 0.0889)
		(layer "In2.Cu")
		(net "M_I_CPU0_SB_DQ<1>")
	)
	(arc
		(start 385.581906 -275.218652)
		(mid 385.399655 -275.269002)
		(end 385.216146 -275.223478)
		(width 0.0889)
		(layer "In2.Cu")
		(net "M_I_CPU0_SB_DQ<1>")
	)
	(arc
		(start 379.933454 -275.223478)
		(mid 379.749946 -275.268972)
		(end 379.567694 -275.218652)
		(width 0.0889)
		(layer "In2.Cu")
		(net "M_I_CPU0_SB_DQ<1>")
	)
	(arc
		(start 376.747786 -275.218652)
		(mid 376.500073 -275.143432)
		(end 376.244866 -275.186902)
		(width 0.0889)
		(layer "In2.Cu")
		(net "M_I_CPU0_SB_DQ<1>")
	)
	(arc
		(start 393.099798 -275.218652)
		(mid 392.923888 -275.269462)
		(end 392.74496 -275.23059)
		(width 0.0889)
		(layer "In2.Cu")
		(net "M_I_CPU0_SB_DQ<1>")
	)
	(arc
		(start 384.26771 -275.218652)
		(mid 383.984754 -275.142475)
		(end 383.701798 -275.218652)
		(width 0.0889)
		(layer "In2.Cu")
		(net "M_I_CPU0_SB_DQ<1>")
	)
	(arc
		(start 379.001782 -275.218652)
		(mid 378.814838 -275.268907)
		(end 378.627894 -275.218652)
		(width 0.0889)
		(layer "In2.Cu")
		(net "M_I_CPU0_SB_DQ<1>")
	)
	(arc
		(start 381.447802 -275.218652)
		(mid 381.164846 -275.142475)
		(end 380.88189 -275.218652)
		(width 0.0889)
		(layer "In2.Cu")
		(net "M_I_CPU0_SB_DQ<1>")
	)
	(arc
		(start 384.63347 -275.223478)
		(mid 384.449962 -275.268972)
		(end 384.26771 -275.218652)
		(width 0.0889)
		(layer "In2.Cu")
		(net "M_I_CPU0_SB_DQ<1>")
	)
	(arc
		(start 380.507748 -275.218652)
		(mid 380.224792 -275.142475)
		(end 379.941836 -275.218652)
		(width 0.0889)
		(layer "In2.Cu")
		(net "M_I_CPU0_SB_DQ<1>")
	)
	(arc
		(start 391.787634 -275.218652)
		(mid 391.504678 -275.142475)
		(end 391.221722 -275.218652)
		(width 0.0889)
		(layer "In2.Cu")
		(net "M_I_CPU0_SB_DQ<1>")
	)
	(arc
		(start 377.68784 -275.218652)
		(mid 377.404884 -275.142475)
		(end 377.121928 -275.218652)
		(width 0.0889)
		(layer "In2.Cu")
		(net "M_I_CPU0_SB_DQ<1>")
	)
	(arc
		(start 378.061982 -275.218652)
		(mid 377.879731 -275.269002)
		(end 377.696222 -275.223478)
		(width 0.0889)
		(layer "In2.Cu")
		(net "M_I_CPU0_SB_DQ<1>")
	)
	(arc
		(start 380.873508 -275.223478)
		(mid 380.69 -275.268972)
		(end 380.507748 -275.218652)
		(width 0.0889)
		(layer "In2.Cu")
		(net "M_I_CPU0_SB_DQ<1>")
	)
	(arc
		(start 392.137138 -275.23186)
		(mid 391.960743 -275.268763)
		(end 391.787634 -275.218652)
		(width 0.0889)
		(layer "In2.Cu")
		(net "M_I_CPU0_SB_DQ<1>")
	)
	(arc
		(start 377.121928 -275.218652)
		(mid 376.939677 -275.269002)
		(end 376.756168 -275.223478)
		(width 0.0889)
		(layer "In2.Cu")
		(net "M_I_CPU0_SB_DQ<1>")
	)
	(arc
		(start 382.387856 -275.218652)
		(mid 382.1049 -275.142475)
		(end 381.821944 -275.218652)
		(width 0.0889)
		(layer "In2.Cu")
		(net "M_I_CPU0_SB_DQ<1>")
	)
	(arc
		(start 378.627894 -275.218652)
		(mid 378.344938 -275.142475)
		(end 378.061982 -275.218652)
		(width 0.0889)
		(layer "In2.Cu")
		(net "M_I_CPU0_SB_DQ<1>")
	)
	(arc
		(start 389.90778 -275.218652)
		(mid 389.624824 -275.142475)
		(end 389.341868 -275.218652)
		(width 0.0889)
		(layer "In2.Cu")
		(net "M_I_CPU0_SB_DQ<1>")
	)
	(arc
		(start 390.281922 -275.218652)
		(mid 390.099671 -275.269002)
		(end 389.916162 -275.223478)
		(width 0.0889)
		(layer "In2.Cu")
		(net "M_I_CPU0_SB_DQ<1>")
	)
	(arc
		(start 381.821944 -275.218652)
		(mid 381.639693 -275.269002)
		(end 381.456184 -275.223478)
		(width 0.0889)
		(layer "In2.Cu")
		(net "M_I_CPU0_SB_DQ<1>")
	)
	(arc
		(start 382.761744 -275.218652)
		(mid 382.5748 -275.268907)
		(end 382.387856 -275.218652)
		(width 0.0889)
		(layer "In2.Cu")
		(net "M_I_CPU0_SB_DQ<1>")
	)
	(arc
		(start 391.221722 -275.218652)
		(mid 391.034778 -275.268907)
		(end 390.847834 -275.218652)
		(width 0.0889)
		(layer "In2.Cu")
		(net "M_I_CPU0_SB_DQ<1>")
	)
	(arc
		(start 379.567694 -275.218652)
		(mid 379.284738 -275.142475)
		(end 379.001782 -275.218652)
		(width 0.0889)
		(layer "In2.Cu")
		(net "M_I_CPU0_SB_DQ<1>")
	)
	(arc
		(start 392.724386 -275.218652)
		(mid 392.457456 -275.142703)
		(end 392.186668 -275.203412)
		(width 0.0889)
		(layer "In2.Cu")
		(net "M_I_CPU0_SB_DQ<1>")
	)
	(arc
		(start 383.327656 -275.218652)
		(mid 383.0447 -275.142475)
		(end 382.761744 -275.218652)
		(width 0.0889)
		(layer "In2.Cu")
		(net "M_I_CPU0_SB_DQ<1>")
	)
	(arc
		(start 389.333486 -275.223478)
		(mid 389.149978 -275.268972)
		(end 388.967726 -275.218652)
		(width 0.0889)
		(layer "In2.Cu")
		(net "M_I_CPU0_SB_DQ<1>")
	)
	(arc
		(start 386.52196 -275.218652)
		(mid 386.339709 -275.269002)
		(end 386.1562 -275.223478)
		(width 0.0889)
		(layer "In2.Cu")
		(net "M_I_CPU0_SB_DQ<1>")
	)
	(arc
		(start 383.693416 -275.223478)
		(mid 383.509908 -275.268972)
		(end 383.327656 -275.218652)
		(width 0.0889)
		(layer "In2.Cu")
		(net "M_I_CPU0_SB_DQ<1>")
	)
	(arc
		(start 388.027672 -275.218652)
		(mid 387.744716 -275.142475)
		(end 387.46176 -275.218652)
		(width 0.0889)
		(layer "In2.Cu")
		(net "M_I_CPU0_SB_DQ<1>")
	)
	(arc
		(start 388.393432 -275.223478)
		(mid 388.209924 -275.268972)
		(end 388.027672 -275.218652)
		(width 0.0889)
		(layer "In2.Cu")
		(net "M_I_CPU0_SB_DQ<1>")
	)
	(arc
		(start 388.967726 -275.218652)
		(mid 388.68477 -275.142475)
		(end 388.401814 -275.218652)
		(width 0.0889)
		(layer "In2.Cu")
		(net "M_I_CPU0_SB_DQ<1>")
	)
	(arc
		(start 386.147818 -275.218652)
		(mid 385.864862 -275.142475)
		(end 385.581906 -275.218652)
		(width 0.0889)
		(layer "In2.Cu")
		(net "M_I_CPU0_SB_DQ<1>")
	)
	(arc
		(start 390.847834 -275.218652)
		(mid 390.564878 -275.142475)
		(end 390.281922 -275.218652)
		(width 0.0889)
		(layer "In2.Cu")
		(net "M_I_CPU0_SB_DQ<1>")
	)
	(segment
		(start 375.997978 -285.160212)
		(end 376.46483 -285.42615)
		(width 0.10668)
		(layer "F.Cu")
		(net "M_I_CPU0_SB_DQ<19>")
	)
	(segment
		(start 394.835634 -286.325818)
		(end 395.265148 -286.325818)
		(width 0.0889)
		(layer "In2.Cu")
		(net "M_I_CPU0_SB_DQ<19>")
	)
	(segment
		(start 408.019504 -299.752512)
		(end 408.181048 -299.914056)
		(width 0.14478)
		(layer "In2.Cu")
		(net "M_I_CPU0_SB_DQ<19>")
	)
	(segment
		(start 386.043424 -285.098744)
		(end 386.051806 -285.10357)
		(width 0.0889)
		(layer "In2.Cu")
		(net "M_I_CPU0_SB_DQ<19>")
	)
	(segment
		(start 405.819102 -298.374562)
		(end 406.047702 -298.374562)
		(width 0.14478)
		(layer "In2.Cu")
		(net "M_I_CPU0_SB_DQ<19>")
	)
	(segment
		(start 407.998422 -300.553882)
		(end 408.159966 -300.715426)
		(width 0.14478)
		(layer "In2.Cu")
		(net "M_I_CPU0_SB_DQ<19>")
	)
	(segment
		(start 376.310906 -285.16072)
		(end 376.333258 -285.077408)
		(width 0.0889)
		(layer "In2.Cu")
		(net "M_I_CPU0_SB_DQ<19>")
	)
	(segment
		(start 393.613894 -285.104078)
		(end 394.835634 -286.325818)
		(width 0.0889)
		(layer "In2.Cu")
		(net "M_I_CPU0_SB_DQ<19>")
	)
	(segment
		(start 410.339286 -302.894746)
		(end 410.59481 -303.15027)
		(width 0.14478)
		(layer "In2.Cu")
		(net "M_I_CPU0_SB_DQ<19>")
	)
	(segment
		(start 407.239216 -298.972224)
		(end 407.40076 -299.133768)
		(width 0.14478)
		(layer "In2.Cu")
		(net "M_I_CPU0_SB_DQ<19>")
	)
	(segment
		(start 420.824914 -303.15027)
		(end 421.49014 -302.874426)
		(width 0.14478)
		(layer "In2.Cu")
		(net "M_I_CPU0_SB_DQ<19>")
	)
	(segment
		(start 409.558998 -301.885858)
		(end 409.558998 -302.114458)
		(width 0.14478)
		(layer "In2.Cu")
		(net "M_I_CPU0_SB_DQ<19>")
	)
	(segment
		(start 418.657278 -302.588168)
		(end 418.845492 -303.04232)
		(width 0.14478)
		(layer "In2.Cu")
		(net "M_I_CPU0_SB_DQ<19>")
	)
	(segment
		(start 409.720542 -302.276002)
		(end 409.949142 -302.276002)
		(width 0.14478)
		(layer "In2.Cu")
		(net "M_I_CPU0_SB_DQ<19>")
	)
	(segment
		(start 409.168854 -301.495714)
		(end 409.35148 -301.313088)
		(width 0.14478)
		(layer "In2.Cu")
		(net "M_I_CPU0_SB_DQ<19>")
	)
	(segment
		(start 395.877288 -286.937958)
		(end 398.205198 -289.265868)
		(width 0.14478)
		(layer "In2.Cu")
		(net "M_I_CPU0_SB_DQ<19>")
	)
	(segment
		(start 399.2626 -291.81806)
		(end 405.038814 -297.594274)
		(width 0.14478)
		(layer "In2.Cu")
		(net "M_I_CPU0_SB_DQ<19>")
	)
	(segment
		(start 410.360368 -302.093376)
		(end 410.521912 -302.25492)
		(width 0.14478)
		(layer "In2.Cu")
		(net "M_I_CPU0_SB_DQ<19>")
	)
	(segment
		(start 405.45004 -297.411648)
		(end 405.67864 -297.411648)
		(width 0.14478)
		(layer "In2.Cu")
		(net "M_I_CPU0_SB_DQ<19>")
	)
	(segment
		(start 392.628374 -285.10357)
		(end 392.657838 -285.120842)
		(width 0.0889)
		(layer "In2.Cu")
		(net "M_I_CPU0_SB_DQ<19>")
	)
	(segment
		(start 419.106604 -303.15027)
		(end 420.824914 -303.15027)
		(width 0.14478)
		(layer "In2.Cu")
		(net "M_I_CPU0_SB_DQ<19>")
	)
	(segment
		(start 406.620472 -298.35348)
		(end 406.620472 -298.58208)
		(width 0.14478)
		(layer "In2.Cu")
		(net "M_I_CPU0_SB_DQ<19>")
	)
	(segment
		(start 413.3977 -303.15027)
		(end 413.87522 -302.67275)
		(width 0.14478)
		(layer "In2.Cu")
		(net "M_I_CPU0_SB_DQ<19>")
	)
	(segment
		(start 407.608278 -299.935138)
		(end 407.790904 -299.752512)
		(width 0.14478)
		(layer "In2.Cu")
		(net "M_I_CPU0_SB_DQ<19>")
	)
	(segment
		(start 388.497826 -285.10357)
		(end 388.506208 -285.098744)
		(width 0.0889)
		(layer "In2.Cu")
		(net "M_I_CPU0_SB_DQ<19>")
	)
	(segment
		(start 406.047702 -298.374562)
		(end 406.230328 -298.191936)
		(width 0.14478)
		(layer "In2.Cu")
		(net "M_I_CPU0_SB_DQ<19>")
	)
	(segment
		(start 408.181048 -300.142656)
		(end 407.998422 -300.325282)
		(width 0.14478)
		(layer "In2.Cu")
		(net "M_I_CPU0_SB_DQ<19>")
	)
	(segment
		(start 405.840184 -297.573192)
		(end 405.840184 -297.801792)
		(width 0.14478)
		(layer "In2.Cu")
		(net "M_I_CPU0_SB_DQ<19>")
	)
	(segment
		(start 395.265148 -286.325818)
		(end 395.877288 -286.937958)
		(width 0.0889)
		(layer "In2.Cu")
		(net "M_I_CPU0_SB_DQ<19>")
	)
	(segment
		(start 392.229594 -285.11881)
		(end 392.255756 -285.103824)
		(width 0.0889)
		(layer "In2.Cu")
		(net "M_I_CPU0_SB_DQ<19>")
	)
	(segment
		(start 410.521912 -302.25492)
		(end 410.521912 -302.48352)
		(width 0.14478)
		(layer "In2.Cu")
		(net "M_I_CPU0_SB_DQ<19>")
	)
	(segment
		(start 409.35148 -301.313088)
		(end 409.58008 -301.313088)
		(width 0.14478)
		(layer "In2.Cu")
		(net "M_I_CPU0_SB_DQ<19>")
	)
	(segment
		(start 379.097794 -285.10357)
		(end 379.106176 -285.098744)
		(width 0.0889)
		(layer "In2.Cu")
		(net "M_I_CPU0_SB_DQ<19>")
	)
	(segment
		(start 405.657558 -298.213018)
		(end 405.819102 -298.374562)
		(width 0.14478)
		(layer "In2.Cu")
		(net "M_I_CPU0_SB_DQ<19>")
	)
	(segment
		(start 413.87522 -302.67275)
		(end 414.774126 -302.300386)
		(width 0.14478)
		(layer "In2.Cu")
		(net "M_I_CPU0_SB_DQ<19>")
	)
	(segment
		(start 406.82799 -299.15485)
		(end 407.010616 -298.972224)
		(width 0.14478)
		(layer "In2.Cu")
		(net "M_I_CPU0_SB_DQ<19>")
	)
	(segment
		(start 427.021498 -302.300386)
		(end 427.456092 -302.73498)
		(width 0.14478)
		(layer "In2.Cu")
		(net "M_I_CPU0_SB_DQ<19>")
	)
	(segment
		(start 410.521912 -302.48352)
		(end 410.339286 -302.666146)
		(width 0.14478)
		(layer "In2.Cu")
		(net "M_I_CPU0_SB_DQ<19>")
	)
	(segment
		(start 380.037848 -285.10357)
		(end 380.04623 -285.098744)
		(width 0.0889)
		(layer "In2.Cu")
		(net "M_I_CPU0_SB_DQ<19>")
	)
	(segment
		(start 406.59939 -299.15485)
		(end 406.82799 -299.15485)
		(width 0.14478)
		(layer "In2.Cu")
		(net "M_I_CPU0_SB_DQ<19>")
	)
	(segment
		(start 391.317734 -285.10357)
		(end 391.326116 -285.098744)
		(width 0.0889)
		(layer "In2.Cu")
		(net "M_I_CPU0_SB_DQ<19>")
	)
	(segment
		(start 408.159966 -300.715426)
		(end 408.388566 -300.715426)
		(width 0.14478)
		(layer "In2.Cu")
		(net "M_I_CPU0_SB_DQ<19>")
	)
	(segment
		(start 386.983478 -285.098744)
		(end 386.99186 -285.10357)
		(width 0.0889)
		(layer "In2.Cu")
		(net "M_I_CPU0_SB_DQ<19>")
	)
	(segment
		(start 407.010616 -298.972224)
		(end 407.239216 -298.972224)
		(width 0.14478)
		(layer "In2.Cu")
		(net "M_I_CPU0_SB_DQ<19>")
	)
	(segment
		(start 405.67864 -297.411648)
		(end 405.840184 -297.573192)
		(width 0.14478)
		(layer "In2.Cu")
		(net "M_I_CPU0_SB_DQ<19>")
	)
	(segment
		(start 421.641016 -302.510952)
		(end 422.14927 -302.300386)
		(width 0.14478)
		(layer "In2.Cu")
		(net "M_I_CPU0_SB_DQ<19>")
	)
	(segment
		(start 406.437846 -298.993306)
		(end 406.59939 -299.15485)
		(width 0.14478)
		(layer "In2.Cu")
		(net "M_I_CPU0_SB_DQ<19>")
	)
	(segment
		(start 376.46483 -285.42615)
		(end 376.310906 -285.16072)
		(width 0.0889)
		(layer "In2.Cu")
		(net "M_I_CPU0_SB_DQ<19>")
	)
	(segment
		(start 407.40076 -299.362368)
		(end 407.218134 -299.544994)
		(width 0.14478)
		(layer "In2.Cu")
		(net "M_I_CPU0_SB_DQ<19>")
	)
	(segment
		(start 406.437846 -298.764706)
		(end 406.437846 -298.993306)
		(width 0.14478)
		(layer "In2.Cu")
		(net "M_I_CPU0_SB_DQ<19>")
	)
	(segment
		(start 383.79781 -285.10357)
		(end 383.806192 -285.098744)
		(width 0.0889)
		(layer "In2.Cu")
		(net "M_I_CPU0_SB_DQ<19>")
	)
	(segment
		(start 407.998422 -300.325282)
		(end 407.998422 -300.553882)
		(width 0.14478)
		(layer "In2.Cu")
		(net "M_I_CPU0_SB_DQ<19>")
	)
	(segment
		(start 410.339286 -302.666146)
		(end 410.339286 -302.894746)
		(width 0.14478)
		(layer "In2.Cu")
		(net "M_I_CPU0_SB_DQ<19>")
	)
	(segment
		(start 408.77871 -301.10557)
		(end 408.77871 -301.33417)
		(width 0.14478)
		(layer "In2.Cu")
		(net "M_I_CPU0_SB_DQ<19>")
	)
	(segment
		(start 410.59481 -303.15027)
		(end 413.3977 -303.15027)
		(width 0.14478)
		(layer "In2.Cu")
		(net "M_I_CPU0_SB_DQ<19>")
	)
	(segment
		(start 387.557772 -285.10357)
		(end 387.566154 -285.098744)
		(width 0.0889)
		(layer "In2.Cu")
		(net "M_I_CPU0_SB_DQ<19>")
	)
	(segment
		(start 390.74344 -285.098744)
		(end 390.751822 -285.10357)
		(width 0.0889)
		(layer "In2.Cu")
		(net "M_I_CPU0_SB_DQ<19>")
	)
	(segment
		(start 382.857756 -285.10357)
		(end 382.866138 -285.098744)
		(width 0.0889)
		(layer "In2.Cu")
		(net "M_I_CPU0_SB_DQ<19>")
	)
	(segment
		(start 393.505944 -285.059374)
		(end 393.613894 -285.104078)
		(width 0.0889)
		(layer "In2.Cu")
		(net "M_I_CPU0_SB_DQ<19>")
	)
	(segment
		(start 408.799792 -300.5328)
		(end 408.961336 -300.694344)
		(width 0.14478)
		(layer "In2.Cu")
		(net "M_I_CPU0_SB_DQ<19>")
	)
	(segment
		(start 405.038814 -297.594274)
		(end 405.267414 -297.594274)
		(width 0.14478)
		(layer "In2.Cu")
		(net "M_I_CPU0_SB_DQ<19>")
	)
	(segment
		(start 407.218134 -299.544994)
		(end 407.218134 -299.773594)
		(width 0.14478)
		(layer "In2.Cu")
		(net "M_I_CPU0_SB_DQ<19>")
	)
	(segment
		(start 393.31392 -285.059374)
		(end 393.505944 -285.059374)
		(width 0.0889)
		(layer "In2.Cu")
		(net "M_I_CPU0_SB_DQ<19>")
	)
	(segment
		(start 406.458928 -298.191936)
		(end 406.620472 -298.35348)
		(width 0.14478)
		(layer "In2.Cu")
		(net "M_I_CPU0_SB_DQ<19>")
	)
	(segment
		(start 408.77871 -301.33417)
		(end 408.940254 -301.495714)
		(width 0.14478)
		(layer "In2.Cu")
		(net "M_I_CPU0_SB_DQ<19>")
	)
	(segment
		(start 418.845492 -303.04232)
		(end 419.106604 -303.15027)
		(width 0.14478)
		(layer "In2.Cu")
		(net "M_I_CPU0_SB_DQ<19>")
	)
	(segment
		(start 382.283462 -285.098744)
		(end 382.291844 -285.10357)
		(width 0.0889)
		(layer "In2.Cu")
		(net "M_I_CPU0_SB_DQ<19>")
	)
	(segment
		(start 392.255756 -285.103824)
		(end 392.2776 -285.091378)
		(width 0.0889)
		(layer "In2.Cu")
		(net "M_I_CPU0_SB_DQ<19>")
	)
	(segment
		(start 422.14927 -302.300386)
		(end 427.021498 -302.300386)
		(width 0.14478)
		(layer "In2.Cu")
		(net "M_I_CPU0_SB_DQ<19>")
	)
	(segment
		(start 408.181048 -299.914056)
		(end 408.181048 -300.142656)
		(width 0.14478)
		(layer "In2.Cu")
		(net "M_I_CPU0_SB_DQ<19>")
	)
	(segment
		(start 408.571192 -300.5328)
		(end 408.799792 -300.5328)
		(width 0.14478)
		(layer "In2.Cu")
		(net "M_I_CPU0_SB_DQ<19>")
	)
	(segment
		(start 407.379678 -299.935138)
		(end 407.608278 -299.935138)
		(width 0.14478)
		(layer "In2.Cu")
		(net "M_I_CPU0_SB_DQ<19>")
	)
	(segment
		(start 409.949142 -302.276002)
		(end 410.131768 -302.093376)
		(width 0.14478)
		(layer "In2.Cu")
		(net "M_I_CPU0_SB_DQ<19>")
	)
	(segment
		(start 409.741624 -301.474632)
		(end 409.741624 -301.703232)
		(width 0.14478)
		(layer "In2.Cu")
		(net "M_I_CPU0_SB_DQ<19>")
	)
	(segment
		(start 408.388566 -300.715426)
		(end 408.571192 -300.5328)
		(width 0.14478)
		(layer "In2.Cu")
		(net "M_I_CPU0_SB_DQ<19>")
	)
	(segment
		(start 410.131768 -302.093376)
		(end 410.360368 -302.093376)
		(width 0.14478)
		(layer "In2.Cu")
		(net "M_I_CPU0_SB_DQ<19>")
	)
	(segment
		(start 407.218134 -299.773594)
		(end 407.379678 -299.935138)
		(width 0.14478)
		(layer "In2.Cu")
		(net "M_I_CPU0_SB_DQ<19>")
	)
	(segment
		(start 378.5235 -285.098744)
		(end 378.531882 -285.10357)
		(width 0.0889)
		(layer "In2.Cu")
		(net "M_I_CPU0_SB_DQ<19>")
	)
	(segment
		(start 398.205198 -289.265868)
		(end 399.2626 -291.81806)
		(width 0.14478)
		(layer "In2.Cu")
		(net "M_I_CPU0_SB_DQ<19>")
	)
	(segment
		(start 377.583446 -285.098744)
		(end 377.591828 -285.10357)
		(width 0.0889)
		(layer "In2.Cu")
		(net "M_I_CPU0_SB_DQ<19>")
	)
	(segment
		(start 408.961336 -300.694344)
		(end 408.961336 -300.922944)
		(width 0.14478)
		(layer "In2.Cu")
		(net "M_I_CPU0_SB_DQ<19>")
	)
	(segment
		(start 408.961336 -300.922944)
		(end 408.77871 -301.10557)
		(width 0.14478)
		(layer "In2.Cu")
		(net "M_I_CPU0_SB_DQ<19>")
	)
	(segment
		(start 421.49014 -302.874426)
		(end 421.641016 -302.510952)
		(width 0.14478)
		(layer "In2.Cu")
		(net "M_I_CPU0_SB_DQ<19>")
	)
	(segment
		(start 407.790904 -299.752512)
		(end 408.019504 -299.752512)
		(width 0.14478)
		(layer "In2.Cu")
		(net "M_I_CPU0_SB_DQ<19>")
	)
	(segment
		(start 405.267414 -297.594274)
		(end 405.45004 -297.411648)
		(width 0.14478)
		(layer "In2.Cu")
		(net "M_I_CPU0_SB_DQ<19>")
	)
	(segment
		(start 408.940254 -301.495714)
		(end 409.168854 -301.495714)
		(width 0.14478)
		(layer "In2.Cu")
		(net "M_I_CPU0_SB_DQ<19>")
	)
	(segment
		(start 414.774126 -302.300386)
		(end 417.962842 -302.300386)
		(width 0.14478)
		(layer "In2.Cu")
		(net "M_I_CPU0_SB_DQ<19>")
	)
	(segment
		(start 406.620472 -298.58208)
		(end 406.437846 -298.764706)
		(width 0.14478)
		(layer "In2.Cu")
		(net "M_I_CPU0_SB_DQ<19>")
	)
	(segment
		(start 405.840184 -297.801792)
		(end 405.657558 -297.984418)
		(width 0.14478)
		(layer "In2.Cu")
		(net "M_I_CPU0_SB_DQ<19>")
	)
	(segment
		(start 409.58008 -301.313088)
		(end 409.741624 -301.474632)
		(width 0.14478)
		(layer "In2.Cu")
		(net "M_I_CPU0_SB_DQ<19>")
	)
	(segment
		(start 405.657558 -297.984418)
		(end 405.657558 -298.213018)
		(width 0.14478)
		(layer "In2.Cu")
		(net "M_I_CPU0_SB_DQ<19>")
	)
	(segment
		(start 406.230328 -298.191936)
		(end 406.458928 -298.191936)
		(width 0.14478)
		(layer "In2.Cu")
		(net "M_I_CPU0_SB_DQ<19>")
	)
	(segment
		(start 407.40076 -299.133768)
		(end 407.40076 -299.362368)
		(width 0.14478)
		(layer "In2.Cu")
		(net "M_I_CPU0_SB_DQ<19>")
	)
	(segment
		(start 409.558998 -302.114458)
		(end 409.720542 -302.276002)
		(width 0.14478)
		(layer "In2.Cu")
		(net "M_I_CPU0_SB_DQ<19>")
	)
	(segment
		(start 409.741624 -301.703232)
		(end 409.558998 -301.885858)
		(width 0.14478)
		(layer "In2.Cu")
		(net "M_I_CPU0_SB_DQ<19>")
	)
	(segment
		(start 417.962842 -302.300386)
		(end 418.657278 -302.588168)
		(width 0.14478)
		(layer "In2.Cu")
		(net "M_I_CPU0_SB_DQ<19>")
	)
	(arc
		(start 393.196318 -285.10357)
		(mid 393.253242 -285.076473)
		(end 393.31392 -285.059374)
		(width 0.0889)
		(layer "In2.Cu")
		(net "M_I_CPU0_SB_DQ<19>")
	)
	(arc
		(start 388.871968 -285.10357)
		(mid 389.154924 -285.179747)
		(end 389.43788 -285.10357)
		(width 0.0889)
		(layer "In2.Cu")
		(net "M_I_CPU0_SB_DQ<19>")
	)
	(arc
		(start 378.531882 -285.10357)
		(mid 378.814838 -285.179747)
		(end 379.097794 -285.10357)
		(width 0.0889)
		(layer "In2.Cu")
		(net "M_I_CPU0_SB_DQ<19>")
	)
	(arc
		(start 381.35179 -285.10357)
		(mid 381.634746 -285.179747)
		(end 381.917702 -285.10357)
		(width 0.0889)
		(layer "In2.Cu")
		(net "M_I_CPU0_SB_DQ<19>")
	)
	(arc
		(start 390.751822 -285.10357)
		(mid 391.034778 -285.179747)
		(end 391.317734 -285.10357)
		(width 0.0889)
		(layer "In2.Cu")
		(net "M_I_CPU0_SB_DQ<19>")
	)
	(arc
		(start 386.051806 -285.10357)
		(mid 386.334762 -285.179747)
		(end 386.617718 -285.10357)
		(width 0.0889)
		(layer "In2.Cu")
		(net "M_I_CPU0_SB_DQ<19>")
	)
	(arc
		(start 391.326116 -285.098744)
		(mid 391.509624 -285.05325)
		(end 391.691876 -285.10357)
		(width 0.0889)
		(layer "In2.Cu")
		(net "M_I_CPU0_SB_DQ<19>")
	)
	(arc
		(start 386.99186 -285.10357)
		(mid 387.274816 -285.179747)
		(end 387.557772 -285.10357)
		(width 0.0889)
		(layer "In2.Cu")
		(net "M_I_CPU0_SB_DQ<19>")
	)
	(arc
		(start 387.566154 -285.098744)
		(mid 387.749662 -285.05325)
		(end 387.931914 -285.10357)
		(width 0.0889)
		(layer "In2.Cu")
		(net "M_I_CPU0_SB_DQ<19>")
	)
	(arc
		(start 379.471936 -285.10357)
		(mid 379.754892 -285.179747)
		(end 380.037848 -285.10357)
		(width 0.0889)
		(layer "In2.Cu")
		(net "M_I_CPU0_SB_DQ<19>")
	)
	(arc
		(start 380.41199 -285.10357)
		(mid 380.694946 -285.179747)
		(end 380.977902 -285.10357)
		(width 0.0889)
		(layer "In2.Cu")
		(net "M_I_CPU0_SB_DQ<19>")
	)
	(arc
		(start 384.171952 -285.10357)
		(mid 384.454908 -285.179747)
		(end 384.737864 -285.10357)
		(width 0.0889)
		(layer "In2.Cu")
		(net "M_I_CPU0_SB_DQ<19>")
	)
	(arc
		(start 391.691876 -285.10357)
		(mid 391.958806 -285.179519)
		(end 392.229594 -285.11881)
		(width 0.0889)
		(layer "In2.Cu")
		(net "M_I_CPU0_SB_DQ<19>")
	)
	(arc
		(start 376.651774 -285.10357)
		(mid 376.93473 -285.179747)
		(end 377.217686 -285.10357)
		(width 0.0889)
		(layer "In2.Cu")
		(net "M_I_CPU0_SB_DQ<19>")
	)
	(arc
		(start 380.04623 -285.098744)
		(mid 380.229738 -285.05325)
		(end 380.41199 -285.10357)
		(width 0.0889)
		(layer "In2.Cu")
		(net "M_I_CPU0_SB_DQ<19>")
	)
	(arc
		(start 386.617718 -285.10357)
		(mid 386.799969 -285.05322)
		(end 386.983478 -285.098744)
		(width 0.0889)
		(layer "In2.Cu")
		(net "M_I_CPU0_SB_DQ<19>")
	)
	(arc
		(start 392.2776 -285.091378)
		(mid 392.454528 -285.05355)
		(end 392.628374 -285.10357)
		(width 0.0889)
		(layer "In2.Cu")
		(net "M_I_CPU0_SB_DQ<19>")
	)
	(arc
		(start 387.931914 -285.10357)
		(mid 388.21487 -285.179747)
		(end 388.497826 -285.10357)
		(width 0.0889)
		(layer "In2.Cu")
		(net "M_I_CPU0_SB_DQ<19>")
	)
	(arc
		(start 380.977902 -285.10357)
		(mid 381.164846 -285.053315)
		(end 381.35179 -285.10357)
		(width 0.0889)
		(layer "In2.Cu")
		(net "M_I_CPU0_SB_DQ<19>")
	)
	(arc
		(start 388.506208 -285.098744)
		(mid 388.689716 -285.05325)
		(end 388.871968 -285.10357)
		(width 0.0889)
		(layer "In2.Cu")
		(net "M_I_CPU0_SB_DQ<19>")
	)
	(arc
		(start 385.677664 -285.10357)
		(mid 385.859915 -285.05322)
		(end 386.043424 -285.098744)
		(width 0.0889)
		(layer "In2.Cu")
		(net "M_I_CPU0_SB_DQ<19>")
	)
	(arc
		(start 377.217686 -285.10357)
		(mid 377.399937 -285.05322)
		(end 377.583446 -285.098744)
		(width 0.0889)
		(layer "In2.Cu")
		(net "M_I_CPU0_SB_DQ<19>")
	)
	(arc
		(start 383.806192 -285.098744)
		(mid 383.9897 -285.05325)
		(end 384.171952 -285.10357)
		(width 0.0889)
		(layer "In2.Cu")
		(net "M_I_CPU0_SB_DQ<19>")
	)
	(arc
		(start 383.231898 -285.10357)
		(mid 383.514854 -285.179747)
		(end 383.79781 -285.10357)
		(width 0.0889)
		(layer "In2.Cu")
		(net "M_I_CPU0_SB_DQ<19>")
	)
	(arc
		(start 389.811768 -285.10357)
		(mid 390.094724 -285.179747)
		(end 390.37768 -285.10357)
		(width 0.0889)
		(layer "In2.Cu")
		(net "M_I_CPU0_SB_DQ<19>")
	)
	(arc
		(start 385.111752 -285.10357)
		(mid 385.394708 -285.179747)
		(end 385.677664 -285.10357)
		(width 0.0889)
		(layer "In2.Cu")
		(net "M_I_CPU0_SB_DQ<19>")
	)
	(arc
		(start 381.917702 -285.10357)
		(mid 382.099953 -285.05322)
		(end 382.283462 -285.098744)
		(width 0.0889)
		(layer "In2.Cu")
		(net "M_I_CPU0_SB_DQ<19>")
	)
	(arc
		(start 390.37768 -285.10357)
		(mid 390.559931 -285.05322)
		(end 390.74344 -285.098744)
		(width 0.0889)
		(layer "In2.Cu")
		(net "M_I_CPU0_SB_DQ<19>")
	)
	(arc
		(start 389.43788 -285.10357)
		(mid 389.624824 -285.053315)
		(end 389.811768 -285.10357)
		(width 0.0889)
		(layer "In2.Cu")
		(net "M_I_CPU0_SB_DQ<19>")
	)
	(arc
		(start 379.106176 -285.098744)
		(mid 379.289684 -285.05325)
		(end 379.471936 -285.10357)
		(width 0.0889)
		(layer "In2.Cu")
		(net "M_I_CPU0_SB_DQ<19>")
	)
	(arc
		(start 377.591828 -285.10357)
		(mid 377.874784 -285.179747)
		(end 378.15774 -285.10357)
		(width 0.0889)
		(layer "In2.Cu")
		(net "M_I_CPU0_SB_DQ<19>")
	)
	(arc
		(start 382.291844 -285.10357)
		(mid 382.5748 -285.179747)
		(end 382.857756 -285.10357)
		(width 0.0889)
		(layer "In2.Cu")
		(net "M_I_CPU0_SB_DQ<19>")
	)
	(arc
		(start 378.15774 -285.10357)
		(mid 378.339991 -285.05322)
		(end 378.5235 -285.098744)
		(width 0.0889)
		(layer "In2.Cu")
		(net "M_I_CPU0_SB_DQ<19>")
	)
	(arc
		(start 392.657838 -285.120842)
		(mid 392.929258 -285.180519)
		(end 393.196318 -285.10357)
		(width 0.0889)
		(layer "In2.Cu")
		(net "M_I_CPU0_SB_DQ<19>")
	)
	(arc
		(start 382.866138 -285.098744)
		(mid 383.049646 -285.05325)
		(end 383.231898 -285.10357)
		(width 0.0889)
		(layer "In2.Cu")
		(net "M_I_CPU0_SB_DQ<19>")
	)
	(arc
		(start 384.737864 -285.10357)
		(mid 384.924808 -285.053315)
		(end 385.111752 -285.10357)
		(width 0.0889)
		(layer "In2.Cu")
		(net "M_I_CPU0_SB_DQ<19>")
	)
	(arc
		(start 376.333258 -285.077408)
		(mid 376.495447 -285.054673)
		(end 376.651774 -285.10357)
		(width 0.0889)
		(layer "In2.Cu")
		(net "M_I_CPU0_SB_DQ<19>")
	)
	(segment
		(start 377.407932 -284.350206)
		(end 377.874784 -284.616144)
		(width 0.10668)
		(layer "F.Cu")
		(net "M_I_CPU0_SB_DQ<18>")
	)
	(segment
		(start 388.393432 -284.288738)
		(end 388.401814 -284.293564)
		(width 0.0889)
		(layer "In2.Cu")
		(net "M_I_CPU0_SB_DQ<18>")
	)
	(segment
		(start 418.759386 -300.891194)
		(end 418.973762 -301.394114)
		(width 0.14478)
		(layer "In2.Cu")
		(net "M_I_CPU0_SB_DQ<18>")
	)
	(segment
		(start 427.03115 -300.610016)
		(end 427.456092 -301.034958)
		(width 0.14478)
		(layer "In2.Cu")
		(net "M_I_CPU0_SB_DQ<18>")
	)
	(segment
		(start 414.16732 -300.61154)
		(end 414.238186 -300.782736)
		(width 0.14478)
		(layer "In2.Cu")
		(net "M_I_CPU0_SB_DQ<18>")
	)
	(segment
		(start 393.731242 -284.370018)
		(end 394.444982 -285.083758)
		(width 0.0889)
		(layer "In2.Cu")
		(net "M_I_CPU0_SB_DQ<18>")
	)
	(segment
		(start 426.314108 -300.773592)
		(end 426.477684 -300.610016)
		(width 0.14478)
		(layer "In2.Cu")
		(net "M_I_CPU0_SB_DQ<18>")
	)
	(segment
		(start 381.447802 -284.293564)
		(end 381.456184 -284.288738)
		(width 0.0889)
		(layer "In2.Cu")
		(net "M_I_CPU0_SB_DQ<18>")
	)
	(segment
		(start 393.384786 -284.370018)
		(end 393.731242 -284.370018)
		(width 0.0889)
		(layer "In2.Cu")
		(net "M_I_CPU0_SB_DQ<18>")
	)
	(segment
		(start 420.721028 -301.460154)
		(end 421.152066 -301.281592)
		(width 0.14478)
		(layer "In2.Cu")
		(net "M_I_CPU0_SB_DQ<18>")
	)
	(segment
		(start 400.20113 -290.821618)
		(end 400.072098 -290.95192)
		(width 0.14478)
		(layer "In2.Cu")
		(net "M_I_CPU0_SB_DQ<18>")
	)
	(segment
		(start 422.90492 -300.610016)
		(end 423.176954 -300.88205)
		(width 0.14478)
		(layer "In2.Cu")
		(net "M_I_CPU0_SB_DQ<18>")
	)
	(segment
		(start 417.20643 -300.91253)
		(end 417.462716 -300.91253)
		(width 0.14478)
		(layer "In2.Cu")
		(net "M_I_CPU0_SB_DQ<18>")
	)
	(segment
		(start 421.983408 -300.91126)
		(end 422.711118 -300.610016)
		(width 0.14478)
		(layer "In2.Cu")
		(net "M_I_CPU0_SB_DQ<18>")
	)
	(segment
		(start 401.727162 -292.970458)
		(end 401.955508 -292.969442)
		(width 0.14478)
		(layer "In2.Cu")
		(net "M_I_CPU0_SB_DQ<18>")
	)
	(segment
		(start 399.686272 -289.415728)
		(end 399.686272 -290.084764)
		(width 0.14478)
		(layer "In2.Cu")
		(net "M_I_CPU0_SB_DQ<18>")
	)
	(segment
		(start 389.333486 -284.288738)
		(end 389.341868 -284.293564)
		(width 0.0889)
		(layer "In2.Cu")
		(net "M_I_CPU0_SB_DQ<18>")
	)
	(segment
		(start 413.721804 -300.996604)
		(end 413.650938 -300.825662)
		(width 0.14478)
		(layer "In2.Cu")
		(net "M_I_CPU0_SB_DQ<18>")
	)
	(segment
		(start 403.95652 -294.31361)
		(end 411.173168 -301.460154)
		(width 0.14478)
		(layer "In2.Cu")
		(net "M_I_CPU0_SB_DQ<18>")
	)
	(segment
		(start 394.444982 -285.083758)
		(end 395.354302 -285.083758)
		(width 0.0889)
		(layer "In2.Cu")
		(net "M_I_CPU0_SB_DQ<18>")
	)
	(segment
		(start 393.102338 -284.293818)
		(end 393.118086 -284.302962)
		(width 0.0889)
		(layer "In2.Cu")
		(net "M_I_CPU0_SB_DQ<18>")
	)
	(segment
		(start 403.728428 -294.314626)
		(end 403.95652 -294.31361)
		(width 0.14478)
		(layer "In2.Cu")
		(net "M_I_CPU0_SB_DQ<18>")
	)
	(segment
		(start 423.735754 -300.610016)
		(end 425.032932 -300.610016)
		(width 0.14478)
		(layer "In2.Cu")
		(net "M_I_CPU0_SB_DQ<18>")
	)
	(segment
		(start 392.153394 -284.288738)
		(end 392.161776 -284.293564)
		(width 0.0889)
		(layer "In2.Cu")
		(net "M_I_CPU0_SB_DQ<18>")
	)
	(segment
		(start 417.462716 -300.91253)
		(end 417.76523 -300.610016)
		(width 0.14478)
		(layer "In2.Cu")
		(net "M_I_CPU0_SB_DQ<18>")
	)
	(segment
		(start 418.973762 -301.394114)
		(end 419.1381 -301.460154)
		(width 0.14478)
		(layer "In2.Cu")
		(net "M_I_CPU0_SB_DQ<18>")
	)
	(segment
		(start 400.235674 -291.341302)
		(end 400.463766 -291.340286)
		(width 0.14478)
		(layer "In2.Cu")
		(net "M_I_CPU0_SB_DQ<18>")
	)
	(segment
		(start 401.171664 -292.193218)
		(end 401.376896 -291.985954)
		(width 0.14478)
		(layer "In2.Cu")
		(net "M_I_CPU0_SB_DQ<18>")
	)
	(segment
		(start 414.451546 -300.871382)
		(end 415.08299 -300.610016)
		(width 0.14478)
		(layer "In2.Cu")
		(net "M_I_CPU0_SB_DQ<18>")
	)
	(segment
		(start 418.060632 -300.610016)
		(end 418.759386 -300.891194)
		(width 0.14478)
		(layer "In2.Cu")
		(net "M_I_CPU0_SB_DQ<18>")
	)
	(segment
		(start 422.711118 -300.610016)
		(end 422.90492 -300.610016)
		(width 0.14478)
		(layer "In2.Cu")
		(net "M_I_CPU0_SB_DQ<18>")
	)
	(segment
		(start 383.693416 -284.288738)
		(end 383.701798 -284.293564)
		(width 0.0889)
		(layer "In2.Cu")
		(net "M_I_CPU0_SB_DQ<18>")
	)
	(segment
		(start 393.08405 -284.283404)
		(end 393.102338 -284.293818)
		(width 0.0889)
		(layer "In2.Cu")
		(net "M_I_CPU0_SB_DQ<18>")
	)
	(segment
		(start 395.354302 -285.083758)
		(end 395.828266 -285.557722)
		(width 0.0889)
		(layer "In2.Cu")
		(net "M_I_CPU0_SB_DQ<18>")
	)
	(segment
		(start 403.131274 -294.133778)
		(end 403.13229 -294.36187)
		(width 0.14478)
		(layer "In2.Cu")
		(net "M_I_CPU0_SB_DQ<18>")
	)
	(segment
		(start 401.604988 -291.984938)
		(end 401.767802 -292.145974)
		(width 0.14478)
		(layer "In2.Cu")
		(net "M_I_CPU0_SB_DQ<18>")
	)
	(segment
		(start 413.292544 -301.460154)
		(end 413.578548 -301.341536)
		(width 0.14478)
		(layer "In2.Cu")
		(net "M_I_CPU0_SB_DQ<18>")
	)
	(segment
		(start 395.828266 -285.557722)
		(end 399.686272 -289.415728)
		(width 0.14478)
		(layer "In2.Cu")
		(net "M_I_CPU0_SB_DQ<18>")
	)
	(segment
		(start 403.29485 -294.522906)
		(end 403.523196 -294.52189)
		(width 0.14478)
		(layer "In2.Cu")
		(net "M_I_CPU0_SB_DQ<18>")
	)
	(segment
		(start 403.523196 -294.52189)
		(end 403.728428 -294.314626)
		(width 0.14478)
		(layer "In2.Cu")
		(net "M_I_CPU0_SB_DQ<18>")
	)
	(segment
		(start 403.336506 -293.926514)
		(end 403.131274 -294.133778)
		(width 0.14478)
		(layer "In2.Cu")
		(net "M_I_CPU0_SB_DQ<18>")
	)
	(segment
		(start 403.13229 -294.36187)
		(end 403.29485 -294.522906)
		(width 0.14478)
		(layer "In2.Cu")
		(net "M_I_CPU0_SB_DQ<18>")
	)
	(segment
		(start 413.95396 -300.523148)
		(end 414.16732 -300.61154)
		(width 0.14478)
		(layer "In2.Cu")
		(net "M_I_CPU0_SB_DQ<18>")
	)
	(segment
		(start 386.147818 -284.293564)
		(end 386.1562 -284.288738)
		(width 0.0889)
		(layer "In2.Cu")
		(net "M_I_CPU0_SB_DQ<18>")
	)
	(segment
		(start 384.63347 -284.288738)
		(end 384.641852 -284.293564)
		(width 0.0889)
		(layer "In2.Cu")
		(net "M_I_CPU0_SB_DQ<18>")
	)
	(segment
		(start 416.075368 -300.610016)
		(end 416.903916 -300.610016)
		(width 0.14478)
		(layer "In2.Cu")
		(net "M_I_CPU0_SB_DQ<18>")
	)
	(segment
		(start 377.874784 -284.616144)
		(end 377.72086 -284.350714)
		(width 0.0889)
		(layer "In2.Cu")
		(net "M_I_CPU0_SB_DQ<18>")
	)
	(segment
		(start 400.943318 -292.194234)
		(end 401.171664 -292.193218)
		(width 0.14478)
		(layer "In2.Cu")
		(net "M_I_CPU0_SB_DQ<18>")
	)
	(segment
		(start 399.686272 -290.084764)
		(end 400.200114 -290.593526)
		(width 0.14478)
		(layer "In2.Cu")
		(net "M_I_CPU0_SB_DQ<18>")
	)
	(segment
		(start 416.903916 -300.610016)
		(end 417.20643 -300.91253)
		(width 0.14478)
		(layer "In2.Cu")
		(net "M_I_CPU0_SB_DQ<18>")
	)
	(segment
		(start 413.739584 -300.612048)
		(end 413.95396 -300.523148)
		(width 0.14478)
		(layer "In2.Cu")
		(net "M_I_CPU0_SB_DQ<18>")
	)
	(segment
		(start 401.768818 -292.374066)
		(end 401.563586 -292.58133)
		(width 0.14478)
		(layer "In2.Cu")
		(net "M_I_CPU0_SB_DQ<18>")
	)
	(segment
		(start 402.551646 -292.922198)
		(end 402.552662 -293.15029)
		(width 0.14478)
		(layer "In2.Cu")
		(net "M_I_CPU0_SB_DQ<18>")
	)
	(segment
		(start 380.873508 -284.288738)
		(end 380.88189 -284.293564)
		(width 0.0889)
		(layer "In2.Cu")
		(net "M_I_CPU0_SB_DQ<18>")
	)
	(segment
		(start 402.552662 -293.15029)
		(end 402.34743 -293.357554)
		(width 0.14478)
		(layer "In2.Cu")
		(net "M_I_CPU0_SB_DQ<18>")
	)
	(segment
		(start 400.780758 -292.033198)
		(end 400.943318 -292.194234)
		(width 0.14478)
		(layer "In2.Cu")
		(net "M_I_CPU0_SB_DQ<18>")
	)
	(segment
		(start 425.755308 -301.030386)
		(end 425.918884 -301.193962)
		(width 0.14478)
		(layer "In2.Cu")
		(net "M_I_CPU0_SB_DQ<18>")
	)
	(segment
		(start 415.08299 -300.610016)
		(end 415.208974 -300.610016)
		(width 0.14478)
		(layer "In2.Cu")
		(net "M_I_CPU0_SB_DQ<18>")
	)
	(segment
		(start 421.341296 -300.820582)
		(end 421.555672 -300.731682)
		(width 0.14478)
		(layer "In2.Cu")
		(net "M_I_CPU0_SB_DQ<18>")
	)
	(segment
		(start 400.984974 -291.597842)
		(end 400.779742 -291.805106)
		(width 0.14478)
		(layer "In2.Cu")
		(net "M_I_CPU0_SB_DQ<18>")
	)
	(segment
		(start 426.314108 -301.030386)
		(end 426.314108 -300.773592)
		(width 0.14478)
		(layer "In2.Cu")
		(net "M_I_CPU0_SB_DQ<18>")
	)
	(segment
		(start 400.983958 -291.36975)
		(end 400.984974 -291.597842)
		(width 0.14478)
		(layer "In2.Cu")
		(net "M_I_CPU0_SB_DQ<18>")
	)
	(segment
		(start 402.34743 -293.357554)
		(end 402.348446 -293.585646)
		(width 0.14478)
		(layer "In2.Cu")
		(net "M_I_CPU0_SB_DQ<18>")
	)
	(segment
		(start 400.200114 -290.593526)
		(end 400.20113 -290.821618)
		(width 0.14478)
		(layer "In2.Cu")
		(net "M_I_CPU0_SB_DQ<18>")
	)
	(segment
		(start 421.555672 -300.731682)
		(end 421.983408 -300.91126)
		(width 0.14478)
		(layer "In2.Cu")
		(net "M_I_CPU0_SB_DQ<18>")
	)
	(segment
		(start 401.563586 -292.58133)
		(end 401.564602 -292.809422)
		(width 0.14478)
		(layer "In2.Cu")
		(net "M_I_CPU0_SB_DQ<18>")
	)
	(segment
		(start 425.032932 -300.610016)
		(end 425.196508 -300.44644)
		(width 0.14478)
		(layer "In2.Cu")
		(net "M_I_CPU0_SB_DQ<18>")
	)
	(segment
		(start 417.76523 -300.610016)
		(end 418.060632 -300.610016)
		(width 0.14478)
		(layer "In2.Cu")
		(net "M_I_CPU0_SB_DQ<18>")
	)
	(segment
		(start 425.196508 -300.189646)
		(end 425.360084 -300.02607)
		(width 0.14478)
		(layer "In2.Cu")
		(net "M_I_CPU0_SB_DQ<18>")
	)
	(segment
		(start 413.650938 -300.825662)
		(end 413.739584 -300.612048)
		(width 0.14478)
		(layer "In2.Cu")
		(net "M_I_CPU0_SB_DQ<18>")
	)
	(segment
		(start 401.767802 -292.145974)
		(end 401.768818 -292.374066)
		(width 0.14478)
		(layer "In2.Cu")
		(net "M_I_CPU0_SB_DQ<18>")
	)
	(segment
		(start 415.767774 -300.91761)
		(end 416.075368 -300.610016)
		(width 0.14478)
		(layer "In2.Cu")
		(net "M_I_CPU0_SB_DQ<18>")
	)
	(segment
		(start 411.173168 -301.460154)
		(end 413.292544 -301.460154)
		(width 0.14478)
		(layer "In2.Cu")
		(net "M_I_CPU0_SB_DQ<18>")
	)
	(segment
		(start 415.208974 -300.610016)
		(end 415.516568 -300.91761)
		(width 0.14478)
		(layer "In2.Cu")
		(net "M_I_CPU0_SB_DQ<18>")
	)
	(segment
		(start 423.176954 -300.88205)
		(end 423.46372 -300.88205)
		(width 0.14478)
		(layer "In2.Cu")
		(net "M_I_CPU0_SB_DQ<18>")
	)
	(segment
		(start 400.779742 -291.805106)
		(end 400.780758 -292.033198)
		(width 0.14478)
		(layer "In2.Cu")
		(net "M_I_CPU0_SB_DQ<18>")
	)
	(segment
		(start 377.72086 -284.350714)
		(end 377.743212 -284.267402)
		(width 0.0889)
		(layer "In2.Cu")
		(net "M_I_CPU0_SB_DQ<18>")
	)
	(segment
		(start 400.072098 -290.95192)
		(end 400.073114 -291.180266)
		(width 0.14478)
		(layer "In2.Cu")
		(net "M_I_CPU0_SB_DQ<18>")
	)
	(segment
		(start 400.821144 -291.208714)
		(end 400.983958 -291.36975)
		(width 0.14478)
		(layer "In2.Cu")
		(net "M_I_CPU0_SB_DQ<18>")
	)
	(segment
		(start 402.944584 -293.538402)
		(end 403.172676 -293.537386)
		(width 0.14478)
		(layer "In2.Cu")
		(net "M_I_CPU0_SB_DQ<18>")
	)
	(segment
		(start 402.511006 -293.746682)
		(end 402.739352 -293.745666)
		(width 0.14478)
		(layer "In2.Cu")
		(net "M_I_CPU0_SB_DQ<18>")
	)
	(segment
		(start 402.348446 -293.585646)
		(end 402.511006 -293.746682)
		(width 0.14478)
		(layer "In2.Cu")
		(net "M_I_CPU0_SB_DQ<18>")
	)
	(segment
		(start 392.161776 -284.293564)
		(end 392.176508 -284.3022)
		(width 0.0889)
		(layer "In2.Cu")
		(net "M_I_CPU0_SB_DQ<18>")
	)
	(segment
		(start 421.152066 -301.281592)
		(end 421.341296 -300.820582)
		(width 0.14478)
		(layer "In2.Cu")
		(net "M_I_CPU0_SB_DQ<18>")
	)
	(segment
		(start 403.33549 -293.698422)
		(end 403.336506 -293.926514)
		(width 0.14478)
		(layer "In2.Cu")
		(net "M_I_CPU0_SB_DQ<18>")
	)
	(segment
		(start 400.073114 -291.180266)
		(end 400.235674 -291.341302)
		(width 0.14478)
		(layer "In2.Cu")
		(net "M_I_CPU0_SB_DQ<18>")
	)
	(segment
		(start 385.207764 -284.293564)
		(end 385.216146 -284.288738)
		(width 0.0889)
		(layer "In2.Cu")
		(net "M_I_CPU0_SB_DQ<18>")
	)
	(segment
		(start 402.388832 -292.761162)
		(end 402.551646 -292.922198)
		(width 0.14478)
		(layer "In2.Cu")
		(net "M_I_CPU0_SB_DQ<18>")
	)
	(segment
		(start 425.360084 -300.02607)
		(end 425.591732 -300.02607)
		(width 0.14478)
		(layer "In2.Cu")
		(net "M_I_CPU0_SB_DQ<18>")
	)
	(segment
		(start 425.196508 -300.44644)
		(end 425.196508 -300.189646)
		(width 0.14478)
		(layer "In2.Cu")
		(net "M_I_CPU0_SB_DQ<18>")
	)
	(segment
		(start 426.150532 -301.193962)
		(end 426.314108 -301.030386)
		(width 0.14478)
		(layer "In2.Cu")
		(net "M_I_CPU0_SB_DQ<18>")
	)
	(segment
		(start 415.516568 -300.91761)
		(end 415.767774 -300.91761)
		(width 0.14478)
		(layer "In2.Cu")
		(net "M_I_CPU0_SB_DQ<18>")
	)
	(segment
		(start 403.172676 -293.537386)
		(end 403.33549 -293.698422)
		(width 0.14478)
		(layer "In2.Cu")
		(net "M_I_CPU0_SB_DQ<18>")
	)
	(segment
		(start 413.578548 -301.341536)
		(end 413.721804 -300.996604)
		(width 0.14478)
		(layer "In2.Cu")
		(net "M_I_CPU0_SB_DQ<18>")
	)
	(segment
		(start 400.593052 -291.20973)
		(end 400.821144 -291.208714)
		(width 0.14478)
		(layer "In2.Cu")
		(net "M_I_CPU0_SB_DQ<18>")
	)
	(segment
		(start 401.376896 -291.985954)
		(end 401.604988 -291.984938)
		(width 0.14478)
		(layer "In2.Cu")
		(net "M_I_CPU0_SB_DQ<18>")
	)
	(segment
		(start 400.463766 -291.340286)
		(end 400.593052 -291.20973)
		(width 0.14478)
		(layer "In2.Cu")
		(net "M_I_CPU0_SB_DQ<18>")
	)
	(segment
		(start 425.755308 -300.189646)
		(end 425.755308 -301.030386)
		(width 0.14478)
		(layer "In2.Cu")
		(net "M_I_CPU0_SB_DQ<18>")
	)
	(segment
		(start 426.477684 -300.610016)
		(end 427.03115 -300.610016)
		(width 0.14478)
		(layer "In2.Cu")
		(net "M_I_CPU0_SB_DQ<18>")
	)
	(segment
		(start 419.1381 -301.460154)
		(end 420.721028 -301.460154)
		(width 0.14478)
		(layer "In2.Cu")
		(net "M_I_CPU0_SB_DQ<18>")
	)
	(segment
		(start 401.564602 -292.809422)
		(end 401.727162 -292.970458)
		(width 0.14478)
		(layer "In2.Cu")
		(net "M_I_CPU0_SB_DQ<18>")
	)
	(segment
		(start 401.955508 -292.969442)
		(end 402.16074 -292.762178)
		(width 0.14478)
		(layer "In2.Cu")
		(net "M_I_CPU0_SB_DQ<18>")
	)
	(segment
		(start 389.90778 -284.293564)
		(end 389.916162 -284.288738)
		(width 0.0889)
		(layer "In2.Cu")
		(net "M_I_CPU0_SB_DQ<18>")
	)
	(segment
		(start 402.739352 -293.745666)
		(end 402.944584 -293.538402)
		(width 0.14478)
		(layer "In2.Cu")
		(net "M_I_CPU0_SB_DQ<18>")
	)
	(segment
		(start 379.933454 -284.288738)
		(end 379.941836 -284.293564)
		(width 0.0889)
		(layer "In2.Cu")
		(net "M_I_CPU0_SB_DQ<18>")
	)
	(segment
		(start 423.46372 -300.88205)
		(end 423.735754 -300.610016)
		(width 0.14478)
		(layer "In2.Cu")
		(net "M_I_CPU0_SB_DQ<18>")
	)
	(segment
		(start 425.591732 -300.02607)
		(end 425.755308 -300.189646)
		(width 0.14478)
		(layer "In2.Cu")
		(net "M_I_CPU0_SB_DQ<18>")
	)
	(segment
		(start 414.238186 -300.782736)
		(end 414.451546 -300.871382)
		(width 0.14478)
		(layer "In2.Cu")
		(net "M_I_CPU0_SB_DQ<18>")
	)
	(segment
		(start 425.918884 -301.193962)
		(end 426.150532 -301.193962)
		(width 0.14478)
		(layer "In2.Cu")
		(net "M_I_CPU0_SB_DQ<18>")
	)
	(segment
		(start 402.16074 -292.762178)
		(end 402.388832 -292.761162)
		(width 0.14478)
		(layer "In2.Cu")
		(net "M_I_CPU0_SB_DQ<18>")
	)
	(arc
		(start 393.118086 -284.302962)
		(mid 393.247285 -284.352999)
		(end 393.384786 -284.370018)
		(width 0.0889)
		(layer "In2.Cu")
		(net "M_I_CPU0_SB_DQ<18>")
	)
	(arc
		(start 386.52196 -284.293564)
		(mid 386.804916 -284.369741)
		(end 387.087872 -284.293564)
		(width 0.0889)
		(layer "In2.Cu")
		(net "M_I_CPU0_SB_DQ<18>")
	)
	(arc
		(start 380.507748 -284.293564)
		(mid 380.689999 -284.243214)
		(end 380.873508 -284.288738)
		(width 0.0889)
		(layer "In2.Cu")
		(net "M_I_CPU0_SB_DQ<18>")
	)
	(arc
		(start 390.281922 -284.293564)
		(mid 390.564878 -284.369741)
		(end 390.847834 -284.293564)
		(width 0.0889)
		(layer "In2.Cu")
		(net "M_I_CPU0_SB_DQ<18>")
	)
	(arc
		(start 379.001782 -284.293564)
		(mid 379.284738 -284.369741)
		(end 379.567694 -284.293564)
		(width 0.0889)
		(layer "In2.Cu")
		(net "M_I_CPU0_SB_DQ<18>")
	)
	(arc
		(start 391.787634 -284.293564)
		(mid 391.969885 -284.243214)
		(end 392.153394 -284.288738)
		(width 0.0889)
		(layer "In2.Cu")
		(net "M_I_CPU0_SB_DQ<18>")
	)
	(arc
		(start 386.1562 -284.288738)
		(mid 386.339708 -284.243244)
		(end 386.52196 -284.293564)
		(width 0.0889)
		(layer "In2.Cu")
		(net "M_I_CPU0_SB_DQ<18>")
	)
	(arc
		(start 379.567694 -284.293564)
		(mid 379.749945 -284.243214)
		(end 379.933454 -284.288738)
		(width 0.0889)
		(layer "In2.Cu")
		(net "M_I_CPU0_SB_DQ<18>")
	)
	(arc
		(start 385.581906 -284.293564)
		(mid 385.864862 -284.369741)
		(end 386.147818 -284.293564)
		(width 0.0889)
		(layer "In2.Cu")
		(net "M_I_CPU0_SB_DQ<18>")
	)
	(arc
		(start 389.916162 -284.288738)
		(mid 390.09967 -284.243244)
		(end 390.281922 -284.293564)
		(width 0.0889)
		(layer "In2.Cu")
		(net "M_I_CPU0_SB_DQ<18>")
	)
	(arc
		(start 384.26771 -284.293564)
		(mid 384.449961 -284.243214)
		(end 384.63347 -284.288738)
		(width 0.0889)
		(layer "In2.Cu")
		(net "M_I_CPU0_SB_DQ<18>")
	)
	(arc
		(start 390.847834 -284.293564)
		(mid 391.034778 -284.243309)
		(end 391.221722 -284.293564)
		(width 0.0889)
		(layer "In2.Cu")
		(net "M_I_CPU0_SB_DQ<18>")
	)
	(arc
		(start 383.327656 -284.293564)
		(mid 383.509907 -284.243214)
		(end 383.693416 -284.288738)
		(width 0.0889)
		(layer "In2.Cu")
		(net "M_I_CPU0_SB_DQ<18>")
	)
	(arc
		(start 377.743212 -284.267402)
		(mid 377.905544 -284.244584)
		(end 378.061982 -284.293564)
		(width 0.0889)
		(layer "In2.Cu")
		(net "M_I_CPU0_SB_DQ<18>")
	)
	(arc
		(start 382.761744 -284.293564)
		(mid 383.0447 -284.369741)
		(end 383.327656 -284.293564)
		(width 0.0889)
		(layer "In2.Cu")
		(net "M_I_CPU0_SB_DQ<18>")
	)
	(arc
		(start 388.967726 -284.293564)
		(mid 389.149977 -284.243214)
		(end 389.333486 -284.288738)
		(width 0.0889)
		(layer "In2.Cu")
		(net "M_I_CPU0_SB_DQ<18>")
	)
	(arc
		(start 384.641852 -284.293564)
		(mid 384.924808 -284.369741)
		(end 385.207764 -284.293564)
		(width 0.0889)
		(layer "In2.Cu")
		(net "M_I_CPU0_SB_DQ<18>")
	)
	(arc
		(start 391.221722 -284.293564)
		(mid 391.504678 -284.369741)
		(end 391.787634 -284.293564)
		(width 0.0889)
		(layer "In2.Cu")
		(net "M_I_CPU0_SB_DQ<18>")
	)
	(arc
		(start 378.061982 -284.293564)
		(mid 378.344938 -284.369741)
		(end 378.627894 -284.293564)
		(width 0.0889)
		(layer "In2.Cu")
		(net "M_I_CPU0_SB_DQ<18>")
	)
	(arc
		(start 381.456184 -284.288738)
		(mid 381.639692 -284.243244)
		(end 381.821944 -284.293564)
		(width 0.0889)
		(layer "In2.Cu")
		(net "M_I_CPU0_SB_DQ<18>")
	)
	(arc
		(start 388.027672 -284.293564)
		(mid 388.209923 -284.243214)
		(end 388.393432 -284.288738)
		(width 0.0889)
		(layer "In2.Cu")
		(net "M_I_CPU0_SB_DQ<18>")
	)
	(arc
		(start 392.728196 -284.293564)
		(mid 392.904824 -284.243331)
		(end 393.08405 -284.283404)
		(width 0.0889)
		(layer "In2.Cu")
		(net "M_I_CPU0_SB_DQ<18>")
	)
	(arc
		(start 389.341868 -284.293564)
		(mid 389.624824 -284.369741)
		(end 389.90778 -284.293564)
		(width 0.0889)
		(layer "In2.Cu")
		(net "M_I_CPU0_SB_DQ<18>")
	)
	(arc
		(start 381.821944 -284.293564)
		(mid 382.1049 -284.369741)
		(end 382.387856 -284.293564)
		(width 0.0889)
		(layer "In2.Cu")
		(net "M_I_CPU0_SB_DQ<18>")
	)
	(arc
		(start 392.176508 -284.3022)
		(mid 392.453491 -284.370004)
		(end 392.728196 -284.293564)
		(width 0.0889)
		(layer "In2.Cu")
		(net "M_I_CPU0_SB_DQ<18>")
	)
	(arc
		(start 380.88189 -284.293564)
		(mid 381.164846 -284.369741)
		(end 381.447802 -284.293564)
		(width 0.0889)
		(layer "In2.Cu")
		(net "M_I_CPU0_SB_DQ<18>")
	)
	(arc
		(start 379.941836 -284.293564)
		(mid 380.224792 -284.369741)
		(end 380.507748 -284.293564)
		(width 0.0889)
		(layer "In2.Cu")
		(net "M_I_CPU0_SB_DQ<18>")
	)
	(arc
		(start 383.701798 -284.293564)
		(mid 383.984754 -284.369741)
		(end 384.26771 -284.293564)
		(width 0.0889)
		(layer "In2.Cu")
		(net "M_I_CPU0_SB_DQ<18>")
	)
	(arc
		(start 387.46176 -284.293564)
		(mid 387.744716 -284.369741)
		(end 388.027672 -284.293564)
		(width 0.0889)
		(layer "In2.Cu")
		(net "M_I_CPU0_SB_DQ<18>")
	)
	(arc
		(start 385.216146 -284.288738)
		(mid 385.399654 -284.243244)
		(end 385.581906 -284.293564)
		(width 0.0889)
		(layer "In2.Cu")
		(net "M_I_CPU0_SB_DQ<18>")
	)
	(arc
		(start 388.401814 -284.293564)
		(mid 388.68477 -284.369741)
		(end 388.967726 -284.293564)
		(width 0.0889)
		(layer "In2.Cu")
		(net "M_I_CPU0_SB_DQ<18>")
	)
	(arc
		(start 387.087872 -284.293564)
		(mid 387.274816 -284.243309)
		(end 387.46176 -284.293564)
		(width 0.0889)
		(layer "In2.Cu")
		(net "M_I_CPU0_SB_DQ<18>")
	)
	(arc
		(start 382.387856 -284.293564)
		(mid 382.5748 -284.243309)
		(end 382.761744 -284.293564)
		(width 0.0889)
		(layer "In2.Cu")
		(net "M_I_CPU0_SB_DQ<18>")
	)
	(arc
		(start 378.627894 -284.293564)
		(mid 378.814838 -284.243309)
		(end 379.001782 -284.293564)
		(width 0.0889)
		(layer "In2.Cu")
		(net "M_I_CPU0_SB_DQ<18>")
	)
	(segment
		(start 375.528078 -284.350206)
		(end 375.99493 -284.616144)
		(width 0.10668)
		(layer "F.Cu")
		(net "M_I_CPU0_SB_DQ<17>")
	)
	(segment
		(start 403.943566 -295.862756)
		(end 404.10511 -296.0243)
		(width 0.14478)
		(layer "In2.Cu")
		(net "M_I_CPU0_SB_DQ<17>")
	)
	(segment
		(start 388.393432 -284.94355)
		(end 388.401814 -284.938724)
		(width 0.0889)
		(layer "In2.Cu")
		(net "M_I_CPU0_SB_DQ<17>")
	)
	(segment
		(start 404.959312 -295.950386)
		(end 404.959312 -296.178986)
		(width 0.14478)
		(layer "In2.Cu")
		(net "M_I_CPU0_SB_DQ<17>")
	)
	(segment
		(start 394.929868 -285.317438)
		(end 395.846808 -286.234378)
		(width 0.0889)
		(layer "In2.Cu")
		(net "M_I_CPU0_SB_DQ<17>")
	)
	(segment
		(start 424.744134 -301.460154)
		(end 425.685712 -301.647352)
		(width 0.14478)
		(layer "In2.Cu")
		(net "M_I_CPU0_SB_DQ<17>")
	)
	(segment
		(start 425.685712 -301.647352)
		(end 426.299884 -301.647352)
		(width 0.14478)
		(layer "In2.Cu")
		(net "M_I_CPU0_SB_DQ<17>")
	)
	(segment
		(start 427.241462 -301.460154)
		(end 431.131218 -301.460154)
		(width 0.14478)
		(layer "In2.Cu")
		(net "M_I_CPU0_SB_DQ<17>")
	)
	(segment
		(start 403.324822 -295.244012)
		(end 403.553422 -295.244012)
		(width 0.14478)
		(layer "In2.Cu")
		(net "M_I_CPU0_SB_DQ<17>")
	)
	(segment
		(start 389.333486 -284.94355)
		(end 389.341868 -284.938724)
		(width 0.0889)
		(layer "In2.Cu")
		(net "M_I_CPU0_SB_DQ<17>")
	)
	(segment
		(start 404.723854 -296.643044)
		(end 404.885398 -296.804588)
		(width 0.14478)
		(layer "In2.Cu")
		(net "M_I_CPU0_SB_DQ<17>")
	)
	(segment
		(start 392.137138 -284.951932)
		(end 392.160506 -284.93847)
		(width 0.0889)
		(layer "In2.Cu")
		(net "M_I_CPU0_SB_DQ<17>")
	)
	(segment
		(start 394.15339 -285.317438)
		(end 394.929868 -285.317438)
		(width 0.0889)
		(layer "In2.Cu")
		(net "M_I_CPU0_SB_DQ<17>")
	)
	(segment
		(start 421.332914 -301.788576)
		(end 422.98366 -301.460154)
		(width 0.14478)
		(layer "In2.Cu")
		(net "M_I_CPU0_SB_DQ<17>")
	)
	(segment
		(start 393.29741 -284.868874)
		(end 393.577318 -284.868874)
		(width 0.0889)
		(layer "In2.Cu")
		(net "M_I_CPU0_SB_DQ<17>")
	)
	(segment
		(start 404.33371 -296.0243)
		(end 404.569168 -295.788842)
		(width 0.14478)
		(layer "In2.Cu")
		(net "M_I_CPU0_SB_DQ<17>")
	)
	(segment
		(start 393.577318 -284.868874)
		(end 393.794996 -284.959044)
		(width 0.0889)
		(layer "In2.Cu")
		(net "M_I_CPU0_SB_DQ<17>")
	)
	(segment
		(start 404.723854 -296.414444)
		(end 404.723854 -296.643044)
		(width 0.14478)
		(layer "In2.Cu")
		(net "M_I_CPU0_SB_DQ<17>")
	)
	(segment
		(start 422.98366 -301.460154)
		(end 424.744134 -301.460154)
		(width 0.14478)
		(layer "In2.Cu")
		(net "M_I_CPU0_SB_DQ<17>")
	)
	(segment
		(start 383.693416 -284.94355)
		(end 383.701798 -284.938724)
		(width 0.0889)
		(layer "In2.Cu")
		(net "M_I_CPU0_SB_DQ<17>")
	)
	(segment
		(start 399.816574 -291.735764)
		(end 403.324822 -295.244012)
		(width 0.14478)
		(layer "In2.Cu")
		(net "M_I_CPU0_SB_DQ<17>")
	)
	(segment
		(start 380.873508 -284.94355)
		(end 380.88189 -284.938724)
		(width 0.0889)
		(layer "In2.Cu")
		(net "M_I_CPU0_SB_DQ<17>")
	)
	(segment
		(start 392.160506 -284.93847)
		(end 392.186668 -284.923484)
		(width 0.0889)
		(layer "In2.Cu")
		(net "M_I_CPU0_SB_DQ<17>")
	)
	(segment
		(start 381.447802 -284.938724)
		(end 381.456184 -284.94355)
		(width 0.0889)
		(layer "In2.Cu")
		(net "M_I_CPU0_SB_DQ<17>")
	)
	(segment
		(start 395.846808 -286.234378)
		(end 398.733518 -289.121088)
		(width 0.14478)
		(layer "In2.Cu")
		(net "M_I_CPU0_SB_DQ<17>")
	)
	(segment
		(start 417.608512 -301.460154)
		(end 419.66007 -302.310038)
		(width 0.14478)
		(layer "In2.Cu")
		(net "M_I_CPU0_SB_DQ<17>")
	)
	(segment
		(start 431.131218 -301.460154)
		(end 431.55616 -301.885096)
		(width 0.14478)
		(layer "In2.Cu")
		(net "M_I_CPU0_SB_DQ<17>")
	)
	(segment
		(start 426.299884 -301.647352)
		(end 427.241462 -301.460154)
		(width 0.14478)
		(layer "In2.Cu")
		(net "M_I_CPU0_SB_DQ<17>")
	)
	(segment
		(start 375.99493 -284.616144)
		(end 376.148854 -284.881574)
		(width 0.0889)
		(layer "In2.Cu")
		(net "M_I_CPU0_SB_DQ<17>")
	)
	(segment
		(start 403.943566 -295.634156)
		(end 403.943566 -295.862756)
		(width 0.14478)
		(layer "In2.Cu")
		(net "M_I_CPU0_SB_DQ<17>")
	)
	(segment
		(start 404.10511 -296.0243)
		(end 404.33371 -296.0243)
		(width 0.14478)
		(layer "In2.Cu")
		(net "M_I_CPU0_SB_DQ<17>")
	)
	(segment
		(start 405.349456 -296.56913)
		(end 405.578056 -296.56913)
		(width 0.14478)
		(layer "In2.Cu")
		(net "M_I_CPU0_SB_DQ<17>")
	)
	(segment
		(start 389.90778 -284.938724)
		(end 389.916162 -284.94355)
		(width 0.0889)
		(layer "In2.Cu")
		(net "M_I_CPU0_SB_DQ<17>")
	)
	(segment
		(start 404.885398 -296.804588)
		(end 405.113998 -296.804588)
		(width 0.14478)
		(layer "In2.Cu")
		(net "M_I_CPU0_SB_DQ<17>")
	)
	(segment
		(start 386.147818 -284.938724)
		(end 386.1562 -284.94355)
		(width 0.0889)
		(layer "In2.Cu")
		(net "M_I_CPU0_SB_DQ<17>")
	)
	(segment
		(start 420.073836 -302.310038)
		(end 421.332914 -301.788576)
		(width 0.14478)
		(layer "In2.Cu")
		(net "M_I_CPU0_SB_DQ<17>")
	)
	(segment
		(start 376.148854 -284.881574)
		(end 376.244866 -284.906974)
		(width 0.0889)
		(layer "In2.Cu")
		(net "M_I_CPU0_SB_DQ<17>")
	)
	(segment
		(start 398.733518 -289.121088)
		(end 399.816574 -291.735764)
		(width 0.14478)
		(layer "In2.Cu")
		(net "M_I_CPU0_SB_DQ<17>")
	)
	(segment
		(start 404.569168 -295.788842)
		(end 404.797768 -295.788842)
		(width 0.14478)
		(layer "In2.Cu")
		(net "M_I_CPU0_SB_DQ<17>")
	)
	(segment
		(start 412.980886 -302.310038)
		(end 415.032698 -301.460154)
		(width 0.14478)
		(layer "In2.Cu")
		(net "M_I_CPU0_SB_DQ<17>")
	)
	(segment
		(start 405.578056 -296.56913)
		(end 411.318964 -302.310038)
		(width 0.14478)
		(layer "In2.Cu")
		(net "M_I_CPU0_SB_DQ<17>")
	)
	(segment
		(start 419.66007 -302.310038)
		(end 420.073836 -302.310038)
		(width 0.14478)
		(layer "In2.Cu")
		(net "M_I_CPU0_SB_DQ<17>")
	)
	(segment
		(start 379.933454 -284.94355)
		(end 379.941836 -284.938724)
		(width 0.0889)
		(layer "In2.Cu")
		(net "M_I_CPU0_SB_DQ<17>")
	)
	(segment
		(start 404.01748 -295.008554)
		(end 404.179024 -295.170098)
		(width 0.14478)
		(layer "In2.Cu")
		(net "M_I_CPU0_SB_DQ<17>")
	)
	(segment
		(start 404.959312 -296.178986)
		(end 404.723854 -296.414444)
		(width 0.14478)
		(layer "In2.Cu")
		(net "M_I_CPU0_SB_DQ<17>")
	)
	(segment
		(start 404.179024 -295.170098)
		(end 404.179024 -295.398698)
		(width 0.14478)
		(layer "In2.Cu")
		(net "M_I_CPU0_SB_DQ<17>")
	)
	(segment
		(start 415.032698 -301.460154)
		(end 417.608512 -301.460154)
		(width 0.14478)
		(layer "In2.Cu")
		(net "M_I_CPU0_SB_DQ<17>")
	)
	(segment
		(start 404.797768 -295.788842)
		(end 404.959312 -295.950386)
		(width 0.14478)
		(layer "In2.Cu")
		(net "M_I_CPU0_SB_DQ<17>")
	)
	(segment
		(start 392.724386 -284.938724)
		(end 392.74496 -284.950662)
		(width 0.0889)
		(layer "In2.Cu")
		(net "M_I_CPU0_SB_DQ<17>")
	)
	(segment
		(start 393.099798 -284.938724)
		(end 393.100052 -284.938978)
		(width 0.0889)
		(layer "In2.Cu")
		(net "M_I_CPU0_SB_DQ<17>")
	)
	(segment
		(start 385.207764 -284.938724)
		(end 385.216146 -284.94355)
		(width 0.0889)
		(layer "In2.Cu")
		(net "M_I_CPU0_SB_DQ<17>")
	)
	(segment
		(start 403.78888 -295.008554)
		(end 404.01748 -295.008554)
		(width 0.14478)
		(layer "In2.Cu")
		(net "M_I_CPU0_SB_DQ<17>")
	)
	(segment
		(start 405.113998 -296.804588)
		(end 405.349456 -296.56913)
		(width 0.14478)
		(layer "In2.Cu")
		(net "M_I_CPU0_SB_DQ<17>")
	)
	(segment
		(start 403.553422 -295.244012)
		(end 403.78888 -295.008554)
		(width 0.14478)
		(layer "In2.Cu")
		(net "M_I_CPU0_SB_DQ<17>")
	)
	(segment
		(start 384.63347 -284.94355)
		(end 384.641852 -284.938724)
		(width 0.0889)
		(layer "In2.Cu")
		(net "M_I_CPU0_SB_DQ<17>")
	)
	(segment
		(start 377.68784 -284.938724)
		(end 377.696222 -284.94355)
		(width 0.0889)
		(layer "In2.Cu")
		(net "M_I_CPU0_SB_DQ<17>")
	)
	(segment
		(start 404.179024 -295.398698)
		(end 403.943566 -295.634156)
		(width 0.14478)
		(layer "In2.Cu")
		(net "M_I_CPU0_SB_DQ<17>")
	)
	(segment
		(start 393.794996 -284.959044)
		(end 394.15339 -285.317438)
		(width 0.0889)
		(layer "In2.Cu")
		(net "M_I_CPU0_SB_DQ<17>")
	)
	(segment
		(start 411.318964 -302.310038)
		(end 412.980886 -302.310038)
		(width 0.14478)
		(layer "In2.Cu")
		(net "M_I_CPU0_SB_DQ<17>")
	)
	(segment
		(start 376.747786 -284.938724)
		(end 376.756168 -284.94355)
		(width 0.0889)
		(layer "In2.Cu")
		(net "M_I_CPU0_SB_DQ<17>")
	)
	(arc
		(start 392.186668 -284.923484)
		(mid 392.457454 -284.862838)
		(end 392.724386 -284.938724)
		(width 0.0889)
		(layer "In2.Cu")
		(net "M_I_CPU0_SB_DQ<17>")
	)
	(arc
		(start 385.216146 -284.94355)
		(mid 385.399654 -284.989044)
		(end 385.581906 -284.938724)
		(width 0.0889)
		(layer "In2.Cu")
		(net "M_I_CPU0_SB_DQ<17>")
	)
	(arc
		(start 386.52196 -284.938724)
		(mid 386.804916 -284.862547)
		(end 387.087872 -284.938724)
		(width 0.0889)
		(layer "In2.Cu")
		(net "M_I_CPU0_SB_DQ<17>")
	)
	(arc
		(start 383.701798 -284.938724)
		(mid 383.984754 -284.862547)
		(end 384.26771 -284.938724)
		(width 0.0889)
		(layer "In2.Cu")
		(net "M_I_CPU0_SB_DQ<17>")
	)
	(arc
		(start 379.567694 -284.938724)
		(mid 379.749945 -284.989074)
		(end 379.933454 -284.94355)
		(width 0.0889)
		(layer "In2.Cu")
		(net "M_I_CPU0_SB_DQ<17>")
	)
	(arc
		(start 384.641852 -284.938724)
		(mid 384.924808 -284.862547)
		(end 385.207764 -284.938724)
		(width 0.0889)
		(layer "In2.Cu")
		(net "M_I_CPU0_SB_DQ<17>")
	)
	(arc
		(start 390.847834 -284.938724)
		(mid 391.034778 -284.988979)
		(end 391.221722 -284.938724)
		(width 0.0889)
		(layer "In2.Cu")
		(net "M_I_CPU0_SB_DQ<17>")
	)
	(arc
		(start 377.121928 -284.938724)
		(mid 377.404884 -284.862547)
		(end 377.68784 -284.938724)
		(width 0.0889)
		(layer "In2.Cu")
		(net "M_I_CPU0_SB_DQ<17>")
	)
	(arc
		(start 381.821944 -284.938724)
		(mid 382.1049 -284.862547)
		(end 382.387856 -284.938724)
		(width 0.0889)
		(layer "In2.Cu")
		(net "M_I_CPU0_SB_DQ<17>")
	)
	(arc
		(start 387.46176 -284.938724)
		(mid 387.744716 -284.862547)
		(end 388.027672 -284.938724)
		(width 0.0889)
		(layer "In2.Cu")
		(net "M_I_CPU0_SB_DQ<17>")
	)
	(arc
		(start 380.88189 -284.938724)
		(mid 381.164846 -284.862547)
		(end 381.447802 -284.938724)
		(width 0.0889)
		(layer "In2.Cu")
		(net "M_I_CPU0_SB_DQ<17>")
	)
	(arc
		(start 376.244866 -284.906974)
		(mid 376.500074 -284.863497)
		(end 376.747786 -284.938724)
		(width 0.0889)
		(layer "In2.Cu")
		(net "M_I_CPU0_SB_DQ<17>")
	)
	(arc
		(start 389.916162 -284.94355)
		(mid 390.09967 -284.989044)
		(end 390.281922 -284.938724)
		(width 0.0889)
		(layer "In2.Cu")
		(net "M_I_CPU0_SB_DQ<17>")
	)
	(arc
		(start 388.027672 -284.938724)
		(mid 388.209923 -284.989074)
		(end 388.393432 -284.94355)
		(width 0.0889)
		(layer "In2.Cu")
		(net "M_I_CPU0_SB_DQ<17>")
	)
	(arc
		(start 381.456184 -284.94355)
		(mid 381.639692 -284.989044)
		(end 381.821944 -284.938724)
		(width 0.0889)
		(layer "In2.Cu")
		(net "M_I_CPU0_SB_DQ<17>")
	)
	(arc
		(start 380.507748 -284.938724)
		(mid 380.689999 -284.989074)
		(end 380.873508 -284.94355)
		(width 0.0889)
		(layer "In2.Cu")
		(net "M_I_CPU0_SB_DQ<17>")
	)
	(arc
		(start 388.401814 -284.938724)
		(mid 388.68477 -284.862547)
		(end 388.967726 -284.938724)
		(width 0.0889)
		(layer "In2.Cu")
		(net "M_I_CPU0_SB_DQ<17>")
	)
	(arc
		(start 393.100052 -284.938978)
		(mid 393.195452 -284.894696)
		(end 393.29741 -284.868874)
		(width 0.0889)
		(layer "In2.Cu")
		(net "M_I_CPU0_SB_DQ<17>")
	)
	(arc
		(start 388.967726 -284.938724)
		(mid 389.149977 -284.989074)
		(end 389.333486 -284.94355)
		(width 0.0889)
		(layer "In2.Cu")
		(net "M_I_CPU0_SB_DQ<17>")
	)
	(arc
		(start 376.756168 -284.94355)
		(mid 376.939676 -284.989044)
		(end 377.121928 -284.938724)
		(width 0.0889)
		(layer "In2.Cu")
		(net "M_I_CPU0_SB_DQ<17>")
	)
	(arc
		(start 385.581906 -284.938724)
		(mid 385.864862 -284.862547)
		(end 386.147818 -284.938724)
		(width 0.0889)
		(layer "In2.Cu")
		(net "M_I_CPU0_SB_DQ<17>")
	)
	(arc
		(start 391.787634 -284.938724)
		(mid 391.960742 -284.98884)
		(end 392.137138 -284.951932)
		(width 0.0889)
		(layer "In2.Cu")
		(net "M_I_CPU0_SB_DQ<17>")
	)
	(arc
		(start 390.281922 -284.938724)
		(mid 390.564878 -284.862547)
		(end 390.847834 -284.938724)
		(width 0.0889)
		(layer "In2.Cu")
		(net "M_I_CPU0_SB_DQ<17>")
	)
	(arc
		(start 386.1562 -284.94355)
		(mid 386.339708 -284.989044)
		(end 386.52196 -284.938724)
		(width 0.0889)
		(layer "In2.Cu")
		(net "M_I_CPU0_SB_DQ<17>")
	)
	(arc
		(start 377.696222 -284.94355)
		(mid 377.87973 -284.989044)
		(end 378.061982 -284.938724)
		(width 0.0889)
		(layer "In2.Cu")
		(net "M_I_CPU0_SB_DQ<17>")
	)
	(arc
		(start 384.26771 -284.938724)
		(mid 384.449961 -284.989074)
		(end 384.63347 -284.94355)
		(width 0.0889)
		(layer "In2.Cu")
		(net "M_I_CPU0_SB_DQ<17>")
	)
	(arc
		(start 392.74496 -284.950662)
		(mid 392.923888 -284.989539)
		(end 393.099798 -284.938724)
		(width 0.0889)
		(layer "In2.Cu")
		(net "M_I_CPU0_SB_DQ<17>")
	)
	(arc
		(start 379.001782 -284.938724)
		(mid 379.284738 -284.862547)
		(end 379.567694 -284.938724)
		(width 0.0889)
		(layer "In2.Cu")
		(net "M_I_CPU0_SB_DQ<17>")
	)
	(arc
		(start 378.627894 -284.938724)
		(mid 378.814838 -284.988979)
		(end 379.001782 -284.938724)
		(width 0.0889)
		(layer "In2.Cu")
		(net "M_I_CPU0_SB_DQ<17>")
	)
	(arc
		(start 378.061982 -284.938724)
		(mid 378.344938 -284.862547)
		(end 378.627894 -284.938724)
		(width 0.0889)
		(layer "In2.Cu")
		(net "M_I_CPU0_SB_DQ<17>")
	)
	(arc
		(start 382.387856 -284.938724)
		(mid 382.5748 -284.988979)
		(end 382.761744 -284.938724)
		(width 0.0889)
		(layer "In2.Cu")
		(net "M_I_CPU0_SB_DQ<17>")
	)
	(arc
		(start 382.761744 -284.938724)
		(mid 383.0447 -284.862547)
		(end 383.327656 -284.938724)
		(width 0.0889)
		(layer "In2.Cu")
		(net "M_I_CPU0_SB_DQ<17>")
	)
	(arc
		(start 383.327656 -284.938724)
		(mid 383.509907 -284.989074)
		(end 383.693416 -284.94355)
		(width 0.0889)
		(layer "In2.Cu")
		(net "M_I_CPU0_SB_DQ<17>")
	)
	(arc
		(start 391.221722 -284.938724)
		(mid 391.504678 -284.862547)
		(end 391.787634 -284.938724)
		(width 0.0889)
		(layer "In2.Cu")
		(net "M_I_CPU0_SB_DQ<17>")
	)
	(arc
		(start 387.087872 -284.938724)
		(mid 387.274816 -284.988979)
		(end 387.46176 -284.938724)
		(width 0.0889)
		(layer "In2.Cu")
		(net "M_I_CPU0_SB_DQ<17>")
	)
	(arc
		(start 379.941836 -284.938724)
		(mid 380.224792 -284.862547)
		(end 380.507748 -284.938724)
		(width 0.0889)
		(layer "In2.Cu")
		(net "M_I_CPU0_SB_DQ<17>")
	)
	(arc
		(start 389.341868 -284.938724)
		(mid 389.624824 -284.862547)
		(end 389.90778 -284.938724)
		(width 0.0889)
		(layer "In2.Cu")
		(net "M_I_CPU0_SB_DQ<17>")
	)
	(segment
		(start 376.938032 -283.5402)
		(end 377.404884 -283.806138)
		(width 0.10668)
		(layer "F.Cu")
		(net "M_I_CPU0_SB_DQ<16>")
	)
	(segment
		(start 425.9961 -299.760132)
		(end 429.081184 -299.760132)
		(width 0.14478)
		(layer "In2.Cu")
		(net "M_I_CPU0_SB_DQ<16>")
	)
	(segment
		(start 410.953712 -300.610016)
		(end 412.55569 -300.610016)
		(width 0.14478)
		(layer "In2.Cu")
		(net "M_I_CPU0_SB_DQ<16>")
	)
	(segment
		(start 386.043424 -284.133544)
		(end 386.051806 -284.128718)
		(width 0.0889)
		(layer "In2.Cu")
		(net "M_I_CPU0_SB_DQ<16>")
	)
	(segment
		(start 393.828016 -284.179264)
		(end 394.389102 -284.74035)
		(width 0.0889)
		(layer "In2.Cu")
		(net "M_I_CPU0_SB_DQ<16>")
	)
	(segment
		(start 402.87575 -291.775642)
		(end 402.87575 -292.532054)
		(width 0.14478)
		(layer "In2.Cu")
		(net "M_I_CPU0_SB_DQ<16>")
	)
	(segment
		(start 382.283462 -284.133544)
		(end 382.291844 -284.128718)
		(width 0.0889)
		(layer "In2.Cu")
		(net "M_I_CPU0_SB_DQ<16>")
	)
	(segment
		(start 417.502086 -299.760132)
		(end 419.553898 -300.610016)
		(width 0.14478)
		(layer "In2.Cu")
		(net "M_I_CPU0_SB_DQ<16>")
	)
	(segment
		(start 401.9042 -290.804092)
		(end 402.066252 -290.966144)
		(width 0.14478)
		(layer "In2.Cu")
		(net "M_I_CPU0_SB_DQ<16>")
	)
	(segment
		(start 382.857756 -284.128718)
		(end 382.866138 -284.133544)
		(width 0.0889)
		(layer "In2.Cu")
		(net "M_I_CPU0_SB_DQ<16>")
	)
	(segment
		(start 401.123912 -290.023804)
		(end 401.285964 -290.185856)
		(width 0.14478)
		(layer "In2.Cu")
		(net "M_I_CPU0_SB_DQ<16>")
	)
	(segment
		(start 429.955706 -299.760132)
		(end 431.131218 -299.760132)
		(width 0.14478)
		(layer "In2.Cu")
		(net "M_I_CPU0_SB_DQ<16>")
	)
	(segment
		(start 412.55569 -300.610016)
		(end 414.607502 -299.760132)
		(width 0.14478)
		(layer "In2.Cu")
		(net "M_I_CPU0_SB_DQ<16>")
	)
	(segment
		(start 402.684488 -291.58438)
		(end 402.87575 -291.775642)
		(width 0.14478)
		(layer "In2.Cu")
		(net "M_I_CPU0_SB_DQ<16>")
	)
	(segment
		(start 424.942 -299.760132)
		(end 425.173902 -299.52823)
		(width 0.14478)
		(layer "In2.Cu")
		(net "M_I_CPU0_SB_DQ<16>")
	)
	(segment
		(start 383.79781 -284.128718)
		(end 383.806192 -284.133544)
		(width 0.0889)
		(layer "In2.Cu")
		(net "M_I_CPU0_SB_DQ<16>")
	)
	(segment
		(start 401.89023 -291.598096)
		(end 402.052282 -291.760148)
		(width 0.14478)
		(layer "In2.Cu")
		(net "M_I_CPU0_SB_DQ<16>")
	)
	(segment
		(start 390.74344 -284.133544)
		(end 390.751822 -284.128718)
		(width 0.0889)
		(layer "In2.Cu")
		(net "M_I_CPU0_SB_DQ<16>")
	)
	(segment
		(start 401.50034 -290.97986)
		(end 401.676108 -290.804092)
		(width 0.14478)
		(layer "In2.Cu")
		(net "M_I_CPU0_SB_DQ<16>")
	)
	(segment
		(start 400.720052 -290.199572)
		(end 400.89582 -290.023804)
		(width 0.14478)
		(layer "In2.Cu")
		(net "M_I_CPU0_SB_DQ<16>")
	)
	(segment
		(start 393.384786 -284.179264)
		(end 393.828016 -284.179264)
		(width 0.0889)
		(layer "In2.Cu")
		(net "M_I_CPU0_SB_DQ<16>")
	)
	(segment
		(start 400.329654 -289.809428)
		(end 400.329654 -290.03752)
		(width 0.14478)
		(layer "In2.Cu")
		(net "M_I_CPU0_SB_DQ<16>")
	)
	(segment
		(start 429.242728 -300.383448)
		(end 429.404272 -300.544992)
		(width 0.14478)
		(layer "In2.Cu")
		(net "M_I_CPU0_SB_DQ<16>")
	)
	(segment
		(start 402.052282 -291.760148)
		(end 402.280628 -291.760148)
		(width 0.14478)
		(layer "In2.Cu")
		(net "M_I_CPU0_SB_DQ<16>")
	)
	(segment
		(start 378.5235 -284.133544)
		(end 378.531882 -284.128718)
		(width 0.0889)
		(layer "In2.Cu")
		(net "M_I_CPU0_SB_DQ<16>")
	)
	(segment
		(start 402.066252 -291.194236)
		(end 401.89023 -291.370004)
		(width 0.14478)
		(layer "In2.Cu")
		(net "M_I_CPU0_SB_DQ<16>")
	)
	(segment
		(start 422.435274 -299.760132)
		(end 424.942 -299.760132)
		(width 0.14478)
		(layer "In2.Cu")
		(net "M_I_CPU0_SB_DQ<16>")
	)
	(segment
		(start 392.257788 -284.128718)
		(end 392.269472 -284.135576)
		(width 0.0889)
		(layer "In2.Cu")
		(net "M_I_CPU0_SB_DQ<16>")
	)
	(segment
		(start 425.764198 -299.52823)
		(end 425.9961 -299.760132)
		(width 0.14478)
		(layer "In2.Cu")
		(net "M_I_CPU0_SB_DQ<16>")
	)
	(segment
		(start 429.242728 -299.921676)
		(end 429.242728 -300.383448)
		(width 0.14478)
		(layer "In2.Cu")
		(net "M_I_CPU0_SB_DQ<16>")
	)
	(segment
		(start 400.329654 -290.03752)
		(end 400.491706 -290.199572)
		(width 0.14478)
		(layer "In2.Cu")
		(net "M_I_CPU0_SB_DQ<16>")
	)
	(segment
		(start 429.632618 -300.544992)
		(end 429.794162 -300.383448)
		(width 0.14478)
		(layer "In2.Cu")
		(net "M_I_CPU0_SB_DQ<16>")
	)
	(segment
		(start 401.89023 -291.370004)
		(end 401.89023 -291.598096)
		(width 0.14478)
		(layer "In2.Cu")
		(net "M_I_CPU0_SB_DQ<16>")
	)
	(segment
		(start 400.491706 -290.199572)
		(end 400.720052 -290.199572)
		(width 0.14478)
		(layer "In2.Cu")
		(net "M_I_CPU0_SB_DQ<16>")
	)
	(segment
		(start 400.505676 -289.63366)
		(end 400.329654 -289.809428)
		(width 0.14478)
		(layer "In2.Cu")
		(net "M_I_CPU0_SB_DQ<16>")
	)
	(segment
		(start 386.983478 -284.133544)
		(end 386.99186 -284.128718)
		(width 0.0889)
		(layer "In2.Cu")
		(net "M_I_CPU0_SB_DQ<16>")
	)
	(segment
		(start 400.89582 -290.023804)
		(end 401.123912 -290.023804)
		(width 0.14478)
		(layer "In2.Cu")
		(net "M_I_CPU0_SB_DQ<16>")
	)
	(segment
		(start 393.182348 -284.11932)
		(end 393.198096 -284.128464)
		(width 0.0889)
		(layer "In2.Cu")
		(net "M_I_CPU0_SB_DQ<16>")
	)
	(segment
		(start 429.404272 -300.544992)
		(end 429.632618 -300.544992)
		(width 0.14478)
		(layer "In2.Cu")
		(net "M_I_CPU0_SB_DQ<16>")
	)
	(segment
		(start 429.081184 -299.760132)
		(end 429.242728 -299.921676)
		(width 0.14478)
		(layer "In2.Cu")
		(net "M_I_CPU0_SB_DQ<16>")
	)
	(segment
		(start 414.607502 -299.760132)
		(end 417.502086 -299.760132)
		(width 0.14478)
		(layer "In2.Cu")
		(net "M_I_CPU0_SB_DQ<16>")
	)
	(segment
		(start 425.173902 -299.52823)
		(end 425.764198 -299.52823)
		(width 0.14478)
		(layer "In2.Cu")
		(net "M_I_CPU0_SB_DQ<16>")
	)
	(segment
		(start 401.285964 -290.413948)
		(end 401.109942 -290.589716)
		(width 0.14478)
		(layer "In2.Cu")
		(net "M_I_CPU0_SB_DQ<16>")
	)
	(segment
		(start 395.840458 -284.74035)
		(end 400.505676 -289.405568)
		(width 0.14478)
		(layer "In2.Cu")
		(net "M_I_CPU0_SB_DQ<16>")
	)
	(segment
		(start 391.317734 -284.128718)
		(end 391.326116 -284.133544)
		(width 0.0889)
		(layer "In2.Cu")
		(net "M_I_CPU0_SB_DQ<16>")
	)
	(segment
		(start 401.285964 -290.185856)
		(end 401.285964 -290.413948)
		(width 0.14478)
		(layer "In2.Cu")
		(net "M_I_CPU0_SB_DQ<16>")
	)
	(segment
		(start 429.794162 -300.383448)
		(end 429.794162 -299.921676)
		(width 0.14478)
		(layer "In2.Cu")
		(net "M_I_CPU0_SB_DQ<16>")
	)
	(segment
		(start 402.280628 -291.760148)
		(end 402.456396 -291.58438)
		(width 0.14478)
		(layer "In2.Cu")
		(net "M_I_CPU0_SB_DQ<16>")
	)
	(segment
		(start 380.037848 -284.128718)
		(end 380.04623 -284.133544)
		(width 0.0889)
		(layer "In2.Cu")
		(net "M_I_CPU0_SB_DQ<16>")
	)
	(segment
		(start 401.676108 -290.804092)
		(end 401.9042 -290.804092)
		(width 0.14478)
		(layer "In2.Cu")
		(net "M_I_CPU0_SB_DQ<16>")
	)
	(segment
		(start 431.131218 -299.760132)
		(end 431.55616 -300.185074)
		(width 0.14478)
		(layer "In2.Cu")
		(net "M_I_CPU0_SB_DQ<16>")
	)
	(segment
		(start 420.383462 -300.610016)
		(end 422.435274 -299.760132)
		(width 0.14478)
		(layer "In2.Cu")
		(net "M_I_CPU0_SB_DQ<16>")
	)
	(segment
		(start 393.198096 -284.128464)
		(end 393.216384 -284.138878)
		(width 0.0889)
		(layer "In2.Cu")
		(net "M_I_CPU0_SB_DQ<16>")
	)
	(segment
		(start 394.389102 -284.74035)
		(end 395.840458 -284.74035)
		(width 0.0889)
		(layer "In2.Cu")
		(net "M_I_CPU0_SB_DQ<16>")
	)
	(segment
		(start 401.109942 -290.589716)
		(end 401.109942 -290.817808)
		(width 0.14478)
		(layer "In2.Cu")
		(net "M_I_CPU0_SB_DQ<16>")
	)
	(segment
		(start 388.497826 -284.128718)
		(end 388.506208 -284.133544)
		(width 0.0889)
		(layer "In2.Cu")
		(net "M_I_CPU0_SB_DQ<16>")
	)
	(segment
		(start 387.557772 -284.128718)
		(end 387.566154 -284.133544)
		(width 0.0889)
		(layer "In2.Cu")
		(net "M_I_CPU0_SB_DQ<16>")
	)
	(segment
		(start 419.553898 -300.610016)
		(end 420.383462 -300.610016)
		(width 0.14478)
		(layer "In2.Cu")
		(net "M_I_CPU0_SB_DQ<16>")
	)
	(segment
		(start 402.87575 -292.532054)
		(end 410.953712 -300.610016)
		(width 0.14478)
		(layer "In2.Cu")
		(net "M_I_CPU0_SB_DQ<16>")
	)
	(segment
		(start 401.109942 -290.817808)
		(end 401.271994 -290.97986)
		(width 0.14478)
		(layer "In2.Cu")
		(net "M_I_CPU0_SB_DQ<16>")
	)
	(segment
		(start 401.271994 -290.97986)
		(end 401.50034 -290.97986)
		(width 0.14478)
		(layer "In2.Cu")
		(net "M_I_CPU0_SB_DQ<16>")
	)
	(segment
		(start 402.456396 -291.58438)
		(end 402.684488 -291.58438)
		(width 0.14478)
		(layer "In2.Cu")
		(net "M_I_CPU0_SB_DQ<16>")
	)
	(segment
		(start 400.505676 -289.405568)
		(end 400.505676 -289.63366)
		(width 0.14478)
		(layer "In2.Cu")
		(net "M_I_CPU0_SB_DQ<16>")
	)
	(segment
		(start 402.066252 -290.966144)
		(end 402.066252 -291.194236)
		(width 0.14478)
		(layer "In2.Cu")
		(net "M_I_CPU0_SB_DQ<16>")
	)
	(segment
		(start 429.794162 -299.921676)
		(end 429.955706 -299.760132)
		(width 0.14478)
		(layer "In2.Cu")
		(net "M_I_CPU0_SB_DQ<16>")
	)
	(segment
		(start 379.097794 -284.128718)
		(end 379.106176 -284.133544)
		(width 0.0889)
		(layer "In2.Cu")
		(net "M_I_CPU0_SB_DQ<16>")
	)
	(segment
		(start 377.558808 -284.071568)
		(end 377.65482 -284.096968)
		(width 0.0889)
		(layer "In2.Cu")
		(net "M_I_CPU0_SB_DQ<16>")
	)
	(segment
		(start 377.404884 -283.806138)
		(end 377.558808 -284.071568)
		(width 0.0889)
		(layer "In2.Cu")
		(net "M_I_CPU0_SB_DQ<16>")
	)
	(arc
		(start 389.43788 -284.128718)
		(mid 389.624824 -284.178973)
		(end 389.811768 -284.128718)
		(width 0.0889)
		(layer "In2.Cu")
		(net "M_I_CPU0_SB_DQ<16>")
	)
	(arc
		(start 388.506208 -284.133544)
		(mid 388.689716 -284.179038)
		(end 388.871968 -284.128718)
		(width 0.0889)
		(layer "In2.Cu")
		(net "M_I_CPU0_SB_DQ<16>")
	)
	(arc
		(start 389.811768 -284.128718)
		(mid 390.094724 -284.052541)
		(end 390.37768 -284.128718)
		(width 0.0889)
		(layer "In2.Cu")
		(net "M_I_CPU0_SB_DQ<16>")
	)
	(arc
		(start 384.171952 -284.128718)
		(mid 384.454908 -284.052541)
		(end 384.737864 -284.128718)
		(width 0.0889)
		(layer "In2.Cu")
		(net "M_I_CPU0_SB_DQ<16>")
	)
	(arc
		(start 377.65482 -284.096968)
		(mid 377.910028 -284.053491)
		(end 378.15774 -284.128718)
		(width 0.0889)
		(layer "In2.Cu")
		(net "M_I_CPU0_SB_DQ<16>")
	)
	(arc
		(start 380.977902 -284.128718)
		(mid 381.164846 -284.178973)
		(end 381.35179 -284.128718)
		(width 0.0889)
		(layer "In2.Cu")
		(net "M_I_CPU0_SB_DQ<16>")
	)
	(arc
		(start 385.111752 -284.128718)
		(mid 385.394708 -284.052541)
		(end 385.677664 -284.128718)
		(width 0.0889)
		(layer "In2.Cu")
		(net "M_I_CPU0_SB_DQ<16>")
	)
	(arc
		(start 381.917702 -284.128718)
		(mid 382.099953 -284.179068)
		(end 382.283462 -284.133544)
		(width 0.0889)
		(layer "In2.Cu")
		(net "M_I_CPU0_SB_DQ<16>")
	)
	(arc
		(start 387.566154 -284.133544)
		(mid 387.749662 -284.179038)
		(end 387.931914 -284.128718)
		(width 0.0889)
		(layer "In2.Cu")
		(net "M_I_CPU0_SB_DQ<16>")
	)
	(arc
		(start 378.15774 -284.128718)
		(mid 378.339991 -284.179068)
		(end 378.5235 -284.133544)
		(width 0.0889)
		(layer "In2.Cu")
		(net "M_I_CPU0_SB_DQ<16>")
	)
	(arc
		(start 383.231898 -284.128718)
		(mid 383.514854 -284.052541)
		(end 383.79781 -284.128718)
		(width 0.0889)
		(layer "In2.Cu")
		(net "M_I_CPU0_SB_DQ<16>")
	)
	(arc
		(start 393.216384 -284.138878)
		(mid 393.298208 -284.168991)
		(end 393.384786 -284.179264)
		(width 0.0889)
		(layer "In2.Cu")
		(net "M_I_CPU0_SB_DQ<16>")
	)
	(arc
		(start 390.37768 -284.128718)
		(mid 390.559931 -284.179068)
		(end 390.74344 -284.133544)
		(width 0.0889)
		(layer "In2.Cu")
		(net "M_I_CPU0_SB_DQ<16>")
	)
	(arc
		(start 392.632184 -284.128718)
		(mid 392.906039 -284.052368)
		(end 393.182348 -284.11932)
		(width 0.0889)
		(layer "In2.Cu")
		(net "M_I_CPU0_SB_DQ<16>")
	)
	(arc
		(start 387.931914 -284.128718)
		(mid 388.21487 -284.052541)
		(end 388.497826 -284.128718)
		(width 0.0889)
		(layer "In2.Cu")
		(net "M_I_CPU0_SB_DQ<16>")
	)
	(arc
		(start 379.471936 -284.128718)
		(mid 379.754892 -284.052541)
		(end 380.037848 -284.128718)
		(width 0.0889)
		(layer "In2.Cu")
		(net "M_I_CPU0_SB_DQ<16>")
	)
	(arc
		(start 380.41199 -284.128718)
		(mid 380.694946 -284.052541)
		(end 380.977902 -284.128718)
		(width 0.0889)
		(layer "In2.Cu")
		(net "M_I_CPU0_SB_DQ<16>")
	)
	(arc
		(start 379.106176 -284.133544)
		(mid 379.289684 -284.179038)
		(end 379.471936 -284.128718)
		(width 0.0889)
		(layer "In2.Cu")
		(net "M_I_CPU0_SB_DQ<16>")
	)
	(arc
		(start 388.871968 -284.128718)
		(mid 389.154924 -284.052541)
		(end 389.43788 -284.128718)
		(width 0.0889)
		(layer "In2.Cu")
		(net "M_I_CPU0_SB_DQ<16>")
	)
	(arc
		(start 382.866138 -284.133544)
		(mid 383.049646 -284.179038)
		(end 383.231898 -284.128718)
		(width 0.0889)
		(layer "In2.Cu")
		(net "M_I_CPU0_SB_DQ<16>")
	)
	(arc
		(start 384.737864 -284.128718)
		(mid 384.924808 -284.178973)
		(end 385.111752 -284.128718)
		(width 0.0889)
		(layer "In2.Cu")
		(net "M_I_CPU0_SB_DQ<16>")
	)
	(arc
		(start 391.326116 -284.133544)
		(mid 391.509624 -284.179038)
		(end 391.691876 -284.128718)
		(width 0.0889)
		(layer "In2.Cu")
		(net "M_I_CPU0_SB_DQ<16>")
	)
	(arc
		(start 382.291844 -284.128718)
		(mid 382.5748 -284.052541)
		(end 382.857756 -284.128718)
		(width 0.0889)
		(layer "In2.Cu")
		(net "M_I_CPU0_SB_DQ<16>")
	)
	(arc
		(start 383.806192 -284.133544)
		(mid 383.9897 -284.179038)
		(end 384.171952 -284.128718)
		(width 0.0889)
		(layer "In2.Cu")
		(net "M_I_CPU0_SB_DQ<16>")
	)
	(arc
		(start 380.04623 -284.133544)
		(mid 380.229738 -284.179038)
		(end 380.41199 -284.128718)
		(width 0.0889)
		(layer "In2.Cu")
		(net "M_I_CPU0_SB_DQ<16>")
	)
	(arc
		(start 385.677664 -284.128718)
		(mid 385.859915 -284.179068)
		(end 386.043424 -284.133544)
		(width 0.0889)
		(layer "In2.Cu")
		(net "M_I_CPU0_SB_DQ<16>")
	)
	(arc
		(start 386.051806 -284.128718)
		(mid 386.334762 -284.052541)
		(end 386.617718 -284.128718)
		(width 0.0889)
		(layer "In2.Cu")
		(net "M_I_CPU0_SB_DQ<16>")
	)
	(arc
		(start 378.531882 -284.128718)
		(mid 378.814838 -284.052541)
		(end 379.097794 -284.128718)
		(width 0.0889)
		(layer "In2.Cu")
		(net "M_I_CPU0_SB_DQ<16>")
	)
	(arc
		(start 391.691876 -284.128718)
		(mid 391.974832 -284.052541)
		(end 392.257788 -284.128718)
		(width 0.0889)
		(layer "In2.Cu")
		(net "M_I_CPU0_SB_DQ<16>")
	)
	(arc
		(start 386.99186 -284.128718)
		(mid 387.274816 -284.052541)
		(end 387.557772 -284.128718)
		(width 0.0889)
		(layer "In2.Cu")
		(net "M_I_CPU0_SB_DQ<16>")
	)
	(arc
		(start 381.35179 -284.128718)
		(mid 381.634746 -284.052541)
		(end 381.917702 -284.128718)
		(width 0.0889)
		(layer "In2.Cu")
		(net "M_I_CPU0_SB_DQ<16>")
	)
	(arc
		(start 390.751822 -284.128718)
		(mid 391.034778 -284.052541)
		(end 391.317734 -284.128718)
		(width 0.0889)
		(layer "In2.Cu")
		(net "M_I_CPU0_SB_DQ<16>")
	)
	(arc
		(start 392.269472 -284.135576)
		(mid 392.451727 -284.179229)
		(end 392.632184 -284.128718)
		(width 0.0889)
		(layer "In2.Cu")
		(net "M_I_CPU0_SB_DQ<16>")
	)
	(arc
		(start 386.617718 -284.128718)
		(mid 386.799969 -284.179068)
		(end 386.983478 -284.133544)
		(width 0.0889)
		(layer "In2.Cu")
		(net "M_I_CPU0_SB_DQ<16>")
	)
	(segment
		(start 375.997978 -283.5402)
		(end 376.46483 -283.806138)
		(width 0.10668)
		(layer "F.Cu")
		(net "M_I_CPU0_SB_DQ<15>")
	)
	(segment
		(start 418.240718 -299.463968)
		(end 418.95649 -299.760386)
		(width 0.14478)
		(layer "In2.Cu")
		(net "M_I_CPU0_SB_DQ<15>")
	)
	(segment
		(start 425.598844 -298.61637)
		(end 425.892722 -298.910248)
		(width 0.14478)
		(layer "In2.Cu")
		(net "M_I_CPU0_SB_DQ<15>")
	)
	(segment
		(start 403.581362 -291.692076)
		(end 403.581362 -291.920676)
		(width 0.14478)
		(layer "In2.Cu")
		(net "M_I_CPU0_SB_DQ<15>")
	)
	(segment
		(start 382.283462 -283.478732)
		(end 382.291844 -283.483558)
		(width 0.0889)
		(layer "In2.Cu")
		(net "M_I_CPU0_SB_DQ<15>")
	)
	(segment
		(start 393.31392 -283.439362)
		(end 393.714986 -283.439362)
		(width 0.0889)
		(layer "In2.Cu")
		(net "M_I_CPU0_SB_DQ<15>")
	)
	(segment
		(start 383.79781 -283.483558)
		(end 383.806192 -283.478732)
		(width 0.0889)
		(layer "In2.Cu")
		(net "M_I_CPU0_SB_DQ<15>")
	)
	(segment
		(start 420.831772 -299.760386)
		(end 421.173148 -299.618908)
		(width 0.14478)
		(layer "In2.Cu")
		(net "M_I_CPU0_SB_DQ<15>")
	)
	(segment
		(start 403.42693 -292.075108)
		(end 403.42693 -292.303708)
		(width 0.14478)
		(layer "In2.Cu")
		(net "M_I_CPU0_SB_DQ<15>")
	)
	(segment
		(start 410.883608 -299.760386)
		(end 413.15259 -299.760386)
		(width 0.14478)
		(layer "In2.Cu")
		(net "M_I_CPU0_SB_DQ<15>")
	)
	(segment
		(start 404.36165 -292.700964)
		(end 404.207218 -292.855396)
		(width 0.14478)
		(layer "In2.Cu")
		(net "M_I_CPU0_SB_DQ<15>")
	)
	(segment
		(start 382.857756 -283.483558)
		(end 382.866138 -283.478732)
		(width 0.0889)
		(layer "In2.Cu")
		(net "M_I_CPU0_SB_DQ<15>")
	)
	(segment
		(start 392.628374 -283.483558)
		(end 392.657838 -283.50083)
		(width 0.0889)
		(layer "In2.Cu")
		(net "M_I_CPU0_SB_DQ<15>")
	)
	(segment
		(start 416.903916 -298.910248)
		(end 417.42233 -299.125132)
		(width 0.14478)
		(layer "In2.Cu")
		(net "M_I_CPU0_SB_DQ<15>")
	)
	(segment
		(start 404.207218 -293.083996)
		(end 404.368762 -293.24554)
		(width 0.14478)
		(layer "In2.Cu")
		(net "M_I_CPU0_SB_DQ<15>")
	)
	(segment
		(start 376.46483 -283.806138)
		(end 376.310906 -283.540708)
		(width 0.0889)
		(layer "In2.Cu")
		(net "M_I_CPU0_SB_DQ<15>")
	)
	(segment
		(start 417.63569 -299.03674)
		(end 417.712652 -298.850558)
		(width 0.14478)
		(layer "In2.Cu")
		(net "M_I_CPU0_SB_DQ<15>")
	)
	(segment
		(start 423.080688 -299.14469)
		(end 423.405046 -299.14469)
		(width 0.14478)
		(layer "In2.Cu")
		(net "M_I_CPU0_SB_DQ<15>")
	)
	(segment
		(start 404.987506 -293.635684)
		(end 404.987506 -293.864284)
		(width 0.14478)
		(layer "In2.Cu")
		(net "M_I_CPU0_SB_DQ<15>")
	)
	(segment
		(start 405.141938 -293.252652)
		(end 405.141938 -293.481252)
		(width 0.14478)
		(layer "In2.Cu")
		(net "M_I_CPU0_SB_DQ<15>")
	)
	(segment
		(start 395.642338 -284.207712)
		(end 395.779498 -284.207712)
		(width 0.0889)
		(layer "In2.Cu")
		(net "M_I_CPU0_SB_DQ<15>")
	)
	(segment
		(start 423.405046 -299.14469)
		(end 423.639488 -298.910248)
		(width 0.14478)
		(layer "In2.Cu")
		(net "M_I_CPU0_SB_DQ<15>")
	)
	(segment
		(start 403.581362 -291.920676)
		(end 403.42693 -292.075108)
		(width 0.14478)
		(layer "In2.Cu")
		(net "M_I_CPU0_SB_DQ<15>")
	)
	(segment
		(start 388.497826 -283.483558)
		(end 388.506208 -283.478732)
		(width 0.0889)
		(layer "In2.Cu")
		(net "M_I_CPU0_SB_DQ<15>")
	)
	(segment
		(start 418.140388 -298.851066)
		(end 418.229034 -299.06468)
		(width 0.14478)
		(layer "In2.Cu")
		(net "M_I_CPU0_SB_DQ<15>")
	)
	(segment
		(start 404.36165 -292.472364)
		(end 404.36165 -292.700964)
		(width 0.14478)
		(layer "In2.Cu")
		(net "M_I_CPU0_SB_DQ<15>")
	)
	(segment
		(start 403.971506 -292.31082)
		(end 404.200106 -292.31082)
		(width 0.14478)
		(layer "In2.Cu")
		(net "M_I_CPU0_SB_DQ<15>")
	)
	(segment
		(start 421.173148 -299.618908)
		(end 421.366442 -299.151294)
		(width 0.14478)
		(layer "In2.Cu")
		(net "M_I_CPU0_SB_DQ<15>")
	)
	(segment
		(start 404.207218 -292.855396)
		(end 404.207218 -293.083996)
		(width 0.14478)
		(layer "In2.Cu")
		(net "M_I_CPU0_SB_DQ<15>")
	)
	(segment
		(start 396.096998 -284.207712)
		(end 403.581362 -291.692076)
		(width 0.14478)
		(layer "In2.Cu")
		(net "M_I_CPU0_SB_DQ<15>")
	)
	(segment
		(start 421.366442 -299.151294)
		(end 421.585136 -299.060616)
		(width 0.14478)
		(layer "In2.Cu")
		(net "M_I_CPU0_SB_DQ<15>")
	)
	(segment
		(start 421.585136 -299.060616)
		(end 421.879268 -299.182536)
		(width 0.14478)
		(layer "In2.Cu")
		(net "M_I_CPU0_SB_DQ<15>")
	)
	(segment
		(start 425.892722 -298.910248)
		(end 427.03115 -298.910248)
		(width 0.14478)
		(layer "In2.Cu")
		(net "M_I_CPU0_SB_DQ<15>")
	)
	(segment
		(start 395.779498 -284.207712)
		(end 396.096998 -284.207712)
		(width 0.14478)
		(layer "In2.Cu")
		(net "M_I_CPU0_SB_DQ<15>")
	)
	(segment
		(start 392.229594 -283.498798)
		(end 392.255756 -283.483812)
		(width 0.0889)
		(layer "In2.Cu")
		(net "M_I_CPU0_SB_DQ<15>")
	)
	(segment
		(start 403.817074 -292.465252)
		(end 403.971506 -292.31082)
		(width 0.14478)
		(layer "In2.Cu")
		(net "M_I_CPU0_SB_DQ<15>")
	)
	(segment
		(start 422.53662 -298.910248)
		(end 422.846246 -298.910248)
		(width 0.14478)
		(layer "In2.Cu")
		(net "M_I_CPU0_SB_DQ<15>")
	)
	(segment
		(start 413.15259 -299.760386)
		(end 413.631634 -299.561758)
		(width 0.14478)
		(layer "In2.Cu")
		(net "M_I_CPU0_SB_DQ<15>")
	)
	(segment
		(start 403.42693 -292.303708)
		(end 403.588474 -292.465252)
		(width 0.14478)
		(layer "In2.Cu")
		(net "M_I_CPU0_SB_DQ<15>")
	)
	(segment
		(start 386.983478 -283.478732)
		(end 386.99186 -283.483558)
		(width 0.0889)
		(layer "In2.Cu")
		(net "M_I_CPU0_SB_DQ<15>")
	)
	(segment
		(start 387.557772 -283.483558)
		(end 387.566154 -283.478732)
		(width 0.0889)
		(layer "In2.Cu")
		(net "M_I_CPU0_SB_DQ<15>")
	)
	(segment
		(start 423.639488 -298.910248)
		(end 425.040044 -298.910248)
		(width 0.14478)
		(layer "In2.Cu")
		(net "M_I_CPU0_SB_DQ<15>")
	)
	(segment
		(start 413.795972 -299.165264)
		(end 414.046924 -299.061124)
		(width 0.14478)
		(layer "In2.Cu")
		(net "M_I_CPU0_SB_DQ<15>")
	)
	(segment
		(start 379.097794 -283.483558)
		(end 379.106176 -283.478732)
		(width 0.0889)
		(layer "In2.Cu")
		(net "M_I_CPU0_SB_DQ<15>")
	)
	(segment
		(start 377.583446 -283.478732)
		(end 377.591828 -283.483558)
		(width 0.0889)
		(layer "In2.Cu")
		(net "M_I_CPU0_SB_DQ<15>")
	)
	(segment
		(start 416.21837 -298.910248)
		(end 416.903916 -298.910248)
		(width 0.14478)
		(layer "In2.Cu")
		(net "M_I_CPU0_SB_DQ<15>")
	)
	(segment
		(start 376.310906 -283.540708)
		(end 376.333258 -283.457396)
		(width 0.0889)
		(layer "In2.Cu")
		(net "M_I_CPU0_SB_DQ<15>")
	)
	(segment
		(start 405.141938 -293.481252)
		(end 404.987506 -293.635684)
		(width 0.14478)
		(layer "In2.Cu")
		(net "M_I_CPU0_SB_DQ<15>")
	)
	(segment
		(start 425.040044 -298.910248)
		(end 425.333922 -298.61637)
		(width 0.14478)
		(layer "In2.Cu")
		(net "M_I_CPU0_SB_DQ<15>")
	)
	(segment
		(start 418.229034 -299.06468)
		(end 418.152072 -299.250354)
		(width 0.14478)
		(layer "In2.Cu")
		(net "M_I_CPU0_SB_DQ<15>")
	)
	(segment
		(start 417.42233 -299.125132)
		(end 417.63569 -299.03674)
		(width 0.14478)
		(layer "In2.Cu")
		(net "M_I_CPU0_SB_DQ<15>")
	)
	(segment
		(start 404.987506 -293.864284)
		(end 410.883608 -299.760386)
		(width 0.14478)
		(layer "In2.Cu")
		(net "M_I_CPU0_SB_DQ<15>")
	)
	(segment
		(start 415.65957 -299.11421)
		(end 416.014408 -299.11421)
		(width 0.14478)
		(layer "In2.Cu")
		(net "M_I_CPU0_SB_DQ<15>")
	)
	(segment
		(start 404.751794 -293.091108)
		(end 404.980394 -293.091108)
		(width 0.14478)
		(layer "In2.Cu")
		(net "M_I_CPU0_SB_DQ<15>")
	)
	(segment
		(start 417.926012 -298.762166)
		(end 418.140388 -298.851066)
		(width 0.14478)
		(layer "In2.Cu")
		(net "M_I_CPU0_SB_DQ<15>")
	)
	(segment
		(start 417.712652 -298.850558)
		(end 417.926012 -298.762166)
		(width 0.14478)
		(layer "In2.Cu")
		(net "M_I_CPU0_SB_DQ<15>")
	)
	(segment
		(start 415.163508 -298.910248)
		(end 415.455608 -298.910248)
		(width 0.14478)
		(layer "In2.Cu")
		(net "M_I_CPU0_SB_DQ<15>")
	)
	(segment
		(start 403.588474 -292.465252)
		(end 403.817074 -292.465252)
		(width 0.14478)
		(layer "In2.Cu")
		(net "M_I_CPU0_SB_DQ<15>")
	)
	(segment
		(start 391.317734 -283.483558)
		(end 391.326116 -283.478732)
		(width 0.0889)
		(layer "In2.Cu")
		(net "M_I_CPU0_SB_DQ<15>")
	)
	(segment
		(start 425.333922 -298.61637)
		(end 425.598844 -298.61637)
		(width 0.14478)
		(layer "In2.Cu")
		(net "M_I_CPU0_SB_DQ<15>")
	)
	(segment
		(start 394.27023 -283.994606)
		(end 395.429232 -283.994606)
		(width 0.0889)
		(layer "In2.Cu")
		(net "M_I_CPU0_SB_DQ<15>")
	)
	(segment
		(start 390.74344 -283.478732)
		(end 390.751822 -283.483558)
		(width 0.0889)
		(layer "In2.Cu")
		(net "M_I_CPU0_SB_DQ<15>")
	)
	(segment
		(start 416.014408 -299.11421)
		(end 416.21837 -298.910248)
		(width 0.14478)
		(layer "In2.Cu")
		(net "M_I_CPU0_SB_DQ<15>")
	)
	(segment
		(start 392.255756 -283.483812)
		(end 392.2776 -283.471366)
		(width 0.0889)
		(layer "In2.Cu")
		(net "M_I_CPU0_SB_DQ<15>")
	)
	(segment
		(start 393.714986 -283.439362)
		(end 394.27023 -283.994606)
		(width 0.0889)
		(layer "In2.Cu")
		(net "M_I_CPU0_SB_DQ<15>")
	)
	(segment
		(start 422.846246 -298.910248)
		(end 423.080688 -299.14469)
		(width 0.14478)
		(layer "In2.Cu")
		(net "M_I_CPU0_SB_DQ<15>")
	)
	(segment
		(start 404.200106 -292.31082)
		(end 404.36165 -292.472364)
		(width 0.14478)
		(layer "In2.Cu")
		(net "M_I_CPU0_SB_DQ<15>")
	)
	(segment
		(start 380.037848 -283.483558)
		(end 380.04623 -283.478732)
		(width 0.0889)
		(layer "In2.Cu")
		(net "M_I_CPU0_SB_DQ<15>")
	)
	(segment
		(start 404.980394 -293.091108)
		(end 405.141938 -293.252652)
		(width 0.14478)
		(layer "In2.Cu")
		(net "M_I_CPU0_SB_DQ<15>")
	)
	(segment
		(start 395.429232 -283.994606)
		(end 395.642338 -284.207712)
		(width 0.0889)
		(layer "In2.Cu")
		(net "M_I_CPU0_SB_DQ<15>")
	)
	(segment
		(start 427.03115 -298.910248)
		(end 427.456092 -299.33519)
		(width 0.14478)
		(layer "In2.Cu")
		(net "M_I_CPU0_SB_DQ<15>")
	)
	(segment
		(start 404.597362 -293.24554)
		(end 404.751794 -293.091108)
		(width 0.14478)
		(layer "In2.Cu")
		(net "M_I_CPU0_SB_DQ<15>")
	)
	(segment
		(start 404.368762 -293.24554)
		(end 404.597362 -293.24554)
		(width 0.14478)
		(layer "In2.Cu")
		(net "M_I_CPU0_SB_DQ<15>")
	)
	(segment
		(start 414.046924 -299.061124)
		(end 414.42259 -299.21708)
		(width 0.14478)
		(layer "In2.Cu")
		(net "M_I_CPU0_SB_DQ<15>")
	)
	(segment
		(start 415.455608 -298.910248)
		(end 415.65957 -299.11421)
		(width 0.14478)
		(layer "In2.Cu")
		(net "M_I_CPU0_SB_DQ<15>")
	)
	(segment
		(start 378.5235 -283.478732)
		(end 378.531882 -283.483558)
		(width 0.0889)
		(layer "In2.Cu")
		(net "M_I_CPU0_SB_DQ<15>")
	)
	(segment
		(start 413.631634 -299.561758)
		(end 413.795972 -299.165264)
		(width 0.14478)
		(layer "In2.Cu")
		(net "M_I_CPU0_SB_DQ<15>")
	)
	(segment
		(start 418.152072 -299.250354)
		(end 418.240718 -299.463968)
		(width 0.14478)
		(layer "In2.Cu")
		(net "M_I_CPU0_SB_DQ<15>")
	)
	(segment
		(start 386.043424 -283.478732)
		(end 386.051806 -283.483558)
		(width 0.0889)
		(layer "In2.Cu")
		(net "M_I_CPU0_SB_DQ<15>")
	)
	(segment
		(start 418.95649 -299.760386)
		(end 420.831772 -299.760386)
		(width 0.14478)
		(layer "In2.Cu")
		(net "M_I_CPU0_SB_DQ<15>")
	)
	(segment
		(start 414.42259 -299.21708)
		(end 415.163508 -298.910248)
		(width 0.14478)
		(layer "In2.Cu")
		(net "M_I_CPU0_SB_DQ<15>")
	)
	(segment
		(start 421.879268 -299.182536)
		(end 422.53662 -298.910248)
		(width 0.14478)
		(layer "In2.Cu")
		(net "M_I_CPU0_SB_DQ<15>")
	)
	(arc
		(start 385.677664 -283.483558)
		(mid 385.859915 -283.433208)
		(end 386.043424 -283.478732)
		(width 0.0889)
		(layer "In2.Cu")
		(net "M_I_CPU0_SB_DQ<15>")
	)
	(arc
		(start 378.15774 -283.483558)
		(mid 378.339991 -283.433208)
		(end 378.5235 -283.478732)
		(width 0.0889)
		(layer "In2.Cu")
		(net "M_I_CPU0_SB_DQ<15>")
	)
	(arc
		(start 383.806192 -283.478732)
		(mid 383.9897 -283.433238)
		(end 384.171952 -283.483558)
		(width 0.0889)
		(layer "In2.Cu")
		(net "M_I_CPU0_SB_DQ<15>")
	)
	(arc
		(start 388.506208 -283.478732)
		(mid 388.689716 -283.433238)
		(end 388.871968 -283.483558)
		(width 0.0889)
		(layer "In2.Cu")
		(net "M_I_CPU0_SB_DQ<15>")
	)
	(arc
		(start 381.917702 -283.483558)
		(mid 382.099953 -283.433208)
		(end 382.283462 -283.478732)
		(width 0.0889)
		(layer "In2.Cu")
		(net "M_I_CPU0_SB_DQ<15>")
	)
	(arc
		(start 376.333258 -283.457396)
		(mid 376.495447 -283.434661)
		(end 376.651774 -283.483558)
		(width 0.0889)
		(layer "In2.Cu")
		(net "M_I_CPU0_SB_DQ<15>")
	)
	(arc
		(start 389.811768 -283.483558)
		(mid 390.094724 -283.559735)
		(end 390.37768 -283.483558)
		(width 0.0889)
		(layer "In2.Cu")
		(net "M_I_CPU0_SB_DQ<15>")
	)
	(arc
		(start 379.106176 -283.478732)
		(mid 379.289684 -283.433238)
		(end 379.471936 -283.483558)
		(width 0.0889)
		(layer "In2.Cu")
		(net "M_I_CPU0_SB_DQ<15>")
	)
	(arc
		(start 380.41199 -283.483558)
		(mid 380.694946 -283.559735)
		(end 380.977902 -283.483558)
		(width 0.0889)
		(layer "In2.Cu")
		(net "M_I_CPU0_SB_DQ<15>")
	)
	(arc
		(start 386.617718 -283.483558)
		(mid 386.799969 -283.433208)
		(end 386.983478 -283.478732)
		(width 0.0889)
		(layer "In2.Cu")
		(net "M_I_CPU0_SB_DQ<15>")
	)
	(arc
		(start 388.871968 -283.483558)
		(mid 389.154924 -283.559735)
		(end 389.43788 -283.483558)
		(width 0.0889)
		(layer "In2.Cu")
		(net "M_I_CPU0_SB_DQ<15>")
	)
	(arc
		(start 391.326116 -283.478732)
		(mid 391.509624 -283.433238)
		(end 391.691876 -283.483558)
		(width 0.0889)
		(layer "In2.Cu")
		(net "M_I_CPU0_SB_DQ<15>")
	)
	(arc
		(start 392.657838 -283.50083)
		(mid 392.929258 -283.560507)
		(end 393.196318 -283.483558)
		(width 0.0889)
		(layer "In2.Cu")
		(net "M_I_CPU0_SB_DQ<15>")
	)
	(arc
		(start 390.751822 -283.483558)
		(mid 391.034778 -283.559735)
		(end 391.317734 -283.483558)
		(width 0.0889)
		(layer "In2.Cu")
		(net "M_I_CPU0_SB_DQ<15>")
	)
	(arc
		(start 387.566154 -283.478732)
		(mid 387.749662 -283.433238)
		(end 387.931914 -283.483558)
		(width 0.0889)
		(layer "In2.Cu")
		(net "M_I_CPU0_SB_DQ<15>")
	)
	(arc
		(start 383.231898 -283.483558)
		(mid 383.514854 -283.559735)
		(end 383.79781 -283.483558)
		(width 0.0889)
		(layer "In2.Cu")
		(net "M_I_CPU0_SB_DQ<15>")
	)
	(arc
		(start 377.591828 -283.483558)
		(mid 377.874784 -283.559735)
		(end 378.15774 -283.483558)
		(width 0.0889)
		(layer "In2.Cu")
		(net "M_I_CPU0_SB_DQ<15>")
	)
	(arc
		(start 393.196318 -283.483558)
		(mid 393.253242 -283.456461)
		(end 393.31392 -283.439362)
		(width 0.0889)
		(layer "In2.Cu")
		(net "M_I_CPU0_SB_DQ<15>")
	)
	(arc
		(start 382.291844 -283.483558)
		(mid 382.5748 -283.559735)
		(end 382.857756 -283.483558)
		(width 0.0889)
		(layer "In2.Cu")
		(net "M_I_CPU0_SB_DQ<15>")
	)
	(arc
		(start 386.99186 -283.483558)
		(mid 387.274816 -283.559735)
		(end 387.557772 -283.483558)
		(width 0.0889)
		(layer "In2.Cu")
		(net "M_I_CPU0_SB_DQ<15>")
	)
	(arc
		(start 379.471936 -283.483558)
		(mid 379.754892 -283.559735)
		(end 380.037848 -283.483558)
		(width 0.0889)
		(layer "In2.Cu")
		(net "M_I_CPU0_SB_DQ<15>")
	)
	(arc
		(start 384.171952 -283.483558)
		(mid 384.454908 -283.559735)
		(end 384.737864 -283.483558)
		(width 0.0889)
		(layer "In2.Cu")
		(net "M_I_CPU0_SB_DQ<15>")
	)
	(arc
		(start 385.111752 -283.483558)
		(mid 385.394708 -283.559735)
		(end 385.677664 -283.483558)
		(width 0.0889)
		(layer "In2.Cu")
		(net "M_I_CPU0_SB_DQ<15>")
	)
	(arc
		(start 377.217686 -283.483558)
		(mid 377.399937 -283.433208)
		(end 377.583446 -283.478732)
		(width 0.0889)
		(layer "In2.Cu")
		(net "M_I_CPU0_SB_DQ<15>")
	)
	(arc
		(start 389.43788 -283.483558)
		(mid 389.624824 -283.433303)
		(end 389.811768 -283.483558)
		(width 0.0889)
		(layer "In2.Cu")
		(net "M_I_CPU0_SB_DQ<15>")
	)
	(arc
		(start 386.051806 -283.483558)
		(mid 386.334762 -283.559735)
		(end 386.617718 -283.483558)
		(width 0.0889)
		(layer "In2.Cu")
		(net "M_I_CPU0_SB_DQ<15>")
	)
	(arc
		(start 391.691876 -283.483558)
		(mid 391.958806 -283.559507)
		(end 392.229594 -283.498798)
		(width 0.0889)
		(layer "In2.Cu")
		(net "M_I_CPU0_SB_DQ<15>")
	)
	(arc
		(start 387.931914 -283.483558)
		(mid 388.21487 -283.559735)
		(end 388.497826 -283.483558)
		(width 0.0889)
		(layer "In2.Cu")
		(net "M_I_CPU0_SB_DQ<15>")
	)
	(arc
		(start 381.35179 -283.483558)
		(mid 381.634746 -283.559735)
		(end 381.917702 -283.483558)
		(width 0.0889)
		(layer "In2.Cu")
		(net "M_I_CPU0_SB_DQ<15>")
	)
	(arc
		(start 376.651774 -283.483558)
		(mid 376.93473 -283.559735)
		(end 377.217686 -283.483558)
		(width 0.0889)
		(layer "In2.Cu")
		(net "M_I_CPU0_SB_DQ<15>")
	)
	(arc
		(start 380.04623 -283.478732)
		(mid 380.229738 -283.433238)
		(end 380.41199 -283.483558)
		(width 0.0889)
		(layer "In2.Cu")
		(net "M_I_CPU0_SB_DQ<15>")
	)
	(arc
		(start 378.531882 -283.483558)
		(mid 378.814838 -283.559735)
		(end 379.097794 -283.483558)
		(width 0.0889)
		(layer "In2.Cu")
		(net "M_I_CPU0_SB_DQ<15>")
	)
	(arc
		(start 380.977902 -283.483558)
		(mid 381.164846 -283.433303)
		(end 381.35179 -283.483558)
		(width 0.0889)
		(layer "In2.Cu")
		(net "M_I_CPU0_SB_DQ<15>")
	)
	(arc
		(start 390.37768 -283.483558)
		(mid 390.559931 -283.433208)
		(end 390.74344 -283.478732)
		(width 0.0889)
		(layer "In2.Cu")
		(net "M_I_CPU0_SB_DQ<15>")
	)
	(arc
		(start 384.737864 -283.483558)
		(mid 384.924808 -283.433303)
		(end 385.111752 -283.483558)
		(width 0.0889)
		(layer "In2.Cu")
		(net "M_I_CPU0_SB_DQ<15>")
	)
	(arc
		(start 382.866138 -283.478732)
		(mid 383.049646 -283.433238)
		(end 383.231898 -283.483558)
		(width 0.0889)
		(layer "In2.Cu")
		(net "M_I_CPU0_SB_DQ<15>")
	)
	(arc
		(start 392.2776 -283.471366)
		(mid 392.454528 -283.433538)
		(end 392.628374 -283.483558)
		(width 0.0889)
		(layer "In2.Cu")
		(net "M_I_CPU0_SB_DQ<15>")
	)
	(segment
		(start 377.407932 -282.730194)
		(end 377.874784 -282.996132)
		(width 0.10668)
		(layer "F.Cu")
		(net "M_I_CPU0_SB_DQ<14>")
	)
	(segment
		(start 410.564076 -297.612816)
		(end 410.792168 -297.612816)
		(width 0.14478)
		(layer "In2.Cu")
		(net "M_I_CPU0_SB_DQ<14>")
	)
	(segment
		(start 409.393644 -296.442638)
		(end 409.229814 -296.606468)
		(width 0.14478)
		(layer "In2.Cu")
		(net "M_I_CPU0_SB_DQ<14>")
	)
	(segment
		(start 409.229814 -296.83456)
		(end 409.391866 -296.996612)
		(width 0.14478)
		(layer "In2.Cu")
		(net "M_I_CPU0_SB_DQ<14>")
	)
	(segment
		(start 410.400246 -297.7769)
		(end 410.564076 -297.612816)
		(width 0.14478)
		(layer "In2.Cu")
		(net "M_I_CPU0_SB_DQ<14>")
	)
	(segment
		(start 410.010102 -297.386756)
		(end 410.010102 -297.614848)
		(width 0.14478)
		(layer "In2.Cu")
		(net "M_I_CPU0_SB_DQ<14>")
	)
	(segment
		(start 417.477956 -297.31589)
		(end 417.746688 -297.204384)
		(width 0.14478)
		(layer "In2.Cu")
		(net "M_I_CPU0_SB_DQ<14>")
	)
	(segment
		(start 406.108662 -293.713408)
		(end 406.270714 -293.87546)
		(width 0.14478)
		(layer "In2.Cu")
		(net "M_I_CPU0_SB_DQ<14>")
	)
	(segment
		(start 407.669238 -295.045892)
		(end 407.669238 -295.273984)
		(width 0.14478)
		(layer "In2.Cu")
		(net "M_I_CPU0_SB_DQ<14>")
	)
	(segment
		(start 422.04386 -297.486324)
		(end 422.710102 -297.210226)
		(width 0.14478)
		(layer "In2.Cu")
		(net "M_I_CPU0_SB_DQ<14>")
	)
	(segment
		(start 385.207764 -282.673552)
		(end 385.216146 -282.668726)
		(width 0.0889)
		(layer "In2.Cu")
		(net "M_I_CPU0_SB_DQ<14>")
	)
	(segment
		(start 419.07714 -298.060364)
		(end 420.85006 -298.060364)
		(width 0.14478)
		(layer "In2.Cu")
		(net "M_I_CPU0_SB_DQ<14>")
	)
	(segment
		(start 422.710102 -297.210226)
		(end 424.382692 -297.210226)
		(width 0.14478)
		(layer "In2.Cu")
		(net "M_I_CPU0_SB_DQ<14>")
	)
	(segment
		(start 421.917368 -297.791632)
		(end 422.04386 -297.486324)
		(width 0.14478)
		(layer "In2.Cu")
		(net "M_I_CPU0_SB_DQ<14>")
	)
	(segment
		(start 425.209716 -297.210226)
		(end 425.500292 -297.210226)
		(width 0.14478)
		(layer "In2.Cu")
		(net "M_I_CPU0_SB_DQ<14>")
	)
	(segment
		(start 427.03115 -297.210226)
		(end 427.456092 -297.635168)
		(width 0.14478)
		(layer "In2.Cu")
		(net "M_I_CPU0_SB_DQ<14>")
	)
	(segment
		(start 408.83967 -296.216324)
		(end 409.0035 -296.05224)
		(width 0.14478)
		(layer "In2.Cu")
		(net "M_I_CPU0_SB_DQ<14>")
	)
	(segment
		(start 408.059382 -295.436036)
		(end 408.223212 -295.271952)
		(width 0.14478)
		(layer "In2.Cu")
		(net "M_I_CPU0_SB_DQ<14>")
	)
	(segment
		(start 418.936678 -297.919902)
		(end 419.07714 -298.060364)
		(width 0.14478)
		(layer "In2.Cu")
		(net "M_I_CPU0_SB_DQ<14>")
	)
	(segment
		(start 420.85006 -298.060364)
		(end 420.986204 -297.92422)
		(width 0.14478)
		(layer "In2.Cu")
		(net "M_I_CPU0_SB_DQ<14>")
	)
	(segment
		(start 409.619958 -296.996612)
		(end 409.783788 -296.832528)
		(width 0.14478)
		(layer "In2.Cu")
		(net "M_I_CPU0_SB_DQ<14>")
	)
	(segment
		(start 383.693416 -282.668726)
		(end 383.701798 -282.673552)
		(width 0.0889)
		(layer "In2.Cu")
		(net "M_I_CPU0_SB_DQ<14>")
	)
	(segment
		(start 379.933454 -282.668726)
		(end 379.941836 -282.673552)
		(width 0.0889)
		(layer "In2.Cu")
		(net "M_I_CPU0_SB_DQ<14>")
	)
	(segment
		(start 407.279094 -294.655748)
		(end 407.442924 -294.491664)
		(width 0.14478)
		(layer "In2.Cu")
		(net "M_I_CPU0_SB_DQ<14>")
	)
	(segment
		(start 380.873508 -282.668726)
		(end 380.88189 -282.673552)
		(width 0.0889)
		(layer "In2.Cu")
		(net "M_I_CPU0_SB_DQ<14>")
	)
	(segment
		(start 406.88895 -294.265604)
		(end 406.88895 -294.493696)
		(width 0.14478)
		(layer "In2.Cu")
		(net "M_I_CPU0_SB_DQ<14>")
	)
	(segment
		(start 409.783788 -296.832528)
		(end 410.01188 -296.832528)
		(width 0.14478)
		(layer "In2.Cu")
		(net "M_I_CPU0_SB_DQ<14>")
	)
	(segment
		(start 424.650916 -297.47845)
		(end 424.941492 -297.47845)
		(width 0.14478)
		(layer "In2.Cu")
		(net "M_I_CPU0_SB_DQ<14>")
	)
	(segment
		(start 421.616886 -297.916346)
		(end 421.917368 -297.791632)
		(width 0.14478)
		(layer "In2.Cu")
		(net "M_I_CPU0_SB_DQ<14>")
	)
	(segment
		(start 425.500292 -297.210226)
		(end 425.768516 -297.47845)
		(width 0.14478)
		(layer "In2.Cu")
		(net "M_I_CPU0_SB_DQ<14>")
	)
	(segment
		(start 414.231328 -297.598846)
		(end 415.169096 -297.210226)
		(width 0.14478)
		(layer "In2.Cu")
		(net "M_I_CPU0_SB_DQ<14>")
	)
	(segment
		(start 408.449526 -295.82618)
		(end 408.449526 -296.054272)
		(width 0.14478)
		(layer "In2.Cu")
		(net "M_I_CPU0_SB_DQ<14>")
	)
	(segment
		(start 418.264086 -297.641264)
		(end 418.936678 -297.919902)
		(width 0.14478)
		(layer "In2.Cu")
		(net "M_I_CPU0_SB_DQ<14>")
	)
	(segment
		(start 417.223194 -297.210226)
		(end 417.477956 -297.31589)
		(width 0.14478)
		(layer "In2.Cu")
		(net "M_I_CPU0_SB_DQ<14>")
	)
	(segment
		(start 409.393644 -296.214292)
		(end 409.393644 -296.442638)
		(width 0.14478)
		(layer "In2.Cu")
		(net "M_I_CPU0_SB_DQ<14>")
	)
	(segment
		(start 408.613356 -295.66235)
		(end 408.449526 -295.82618)
		(width 0.14478)
		(layer "In2.Cu")
		(net "M_I_CPU0_SB_DQ<14>")
	)
	(segment
		(start 410.172154 -297.7769)
		(end 410.400246 -297.7769)
		(width 0.14478)
		(layer "In2.Cu")
		(net "M_I_CPU0_SB_DQ<14>")
	)
	(segment
		(start 389.90778 -282.673552)
		(end 389.916162 -282.668726)
		(width 0.0889)
		(layer "In2.Cu")
		(net "M_I_CPU0_SB_DQ<14>")
	)
	(segment
		(start 395.526514 -283.14777)
		(end 395.878558 -283.14777)
		(width 0.0889)
		(layer "In2.Cu")
		(net "M_I_CPU0_SB_DQ<14>")
	)
	(segment
		(start 393.86383 -282.750006)
		(end 394.495274 -283.38145)
		(width 0.0889)
		(layer "In2.Cu")
		(net "M_I_CPU0_SB_DQ<14>")
	)
	(segment
		(start 395.878558 -283.14777)
		(end 396.327122 -283.14777)
		(width 0.14478)
		(layer "In2.Cu")
		(net "M_I_CPU0_SB_DQ<14>")
	)
	(segment
		(start 409.229814 -296.606468)
		(end 409.229814 -296.83456)
		(width 0.14478)
		(layer "In2.Cu")
		(net "M_I_CPU0_SB_DQ<14>")
	)
	(segment
		(start 408.223212 -295.271952)
		(end 408.451304 -295.271952)
		(width 0.14478)
		(layer "In2.Cu")
		(net "M_I_CPU0_SB_DQ<14>")
	)
	(segment
		(start 407.833068 -294.882062)
		(end 407.669238 -295.045892)
		(width 0.14478)
		(layer "In2.Cu")
		(net "M_I_CPU0_SB_DQ<14>")
	)
	(segment
		(start 407.051002 -294.655748)
		(end 407.279094 -294.655748)
		(width 0.14478)
		(layer "In2.Cu")
		(net "M_I_CPU0_SB_DQ<14>")
	)
	(segment
		(start 393.384786 -282.750006)
		(end 393.86383 -282.750006)
		(width 0.0889)
		(layer "In2.Cu")
		(net "M_I_CPU0_SB_DQ<14>")
	)
	(segment
		(start 424.941492 -297.47845)
		(end 425.209716 -297.210226)
		(width 0.14478)
		(layer "In2.Cu")
		(net "M_I_CPU0_SB_DQ<14>")
	)
	(segment
		(start 426.327316 -297.210226)
		(end 427.03115 -297.210226)
		(width 0.14478)
		(layer "In2.Cu")
		(net "M_I_CPU0_SB_DQ<14>")
	)
	(segment
		(start 421.311578 -297.789346)
		(end 421.616886 -297.916346)
		(width 0.14478)
		(layer "In2.Cu")
		(net "M_I_CPU0_SB_DQ<14>")
	)
	(segment
		(start 393.102338 -282.673806)
		(end 393.118086 -282.68295)
		(width 0.0889)
		(layer "In2.Cu")
		(net "M_I_CPU0_SB_DQ<14>")
	)
	(segment
		(start 406.272492 -293.321486)
		(end 406.108662 -293.485316)
		(width 0.14478)
		(layer "In2.Cu")
		(net "M_I_CPU0_SB_DQ<14>")
	)
	(segment
		(start 395.292834 -283.38145)
		(end 395.526514 -283.14777)
		(width 0.0889)
		(layer "In2.Cu")
		(net "M_I_CPU0_SB_DQ<14>")
	)
	(segment
		(start 408.611578 -296.216324)
		(end 408.83967 -296.216324)
		(width 0.14478)
		(layer "In2.Cu")
		(net "M_I_CPU0_SB_DQ<14>")
	)
	(segment
		(start 408.613356 -295.434004)
		(end 408.613356 -295.66235)
		(width 0.14478)
		(layer "In2.Cu")
		(net "M_I_CPU0_SB_DQ<14>")
	)
	(segment
		(start 413.817816 -298.061888)
		(end 414.085532 -297.95089)
		(width 0.14478)
		(layer "In2.Cu")
		(net "M_I_CPU0_SB_DQ<14>")
	)
	(segment
		(start 381.447802 -282.673552)
		(end 381.456184 -282.668726)
		(width 0.0889)
		(layer "In2.Cu")
		(net "M_I_CPU0_SB_DQ<14>")
	)
	(segment
		(start 424.382692 -297.210226)
		(end 424.650916 -297.47845)
		(width 0.14478)
		(layer "In2.Cu")
		(net "M_I_CPU0_SB_DQ<14>")
	)
	(segment
		(start 413.224472 -298.060364)
		(end 413.520128 -297.937936)
		(width 0.14478)
		(layer "In2.Cu")
		(net "M_I_CPU0_SB_DQ<14>")
	)
	(segment
		(start 420.986204 -297.92422)
		(end 421.311578 -297.789346)
		(width 0.14478)
		(layer "In2.Cu")
		(net "M_I_CPU0_SB_DQ<14>")
	)
	(segment
		(start 426.059092 -297.47845)
		(end 426.327316 -297.210226)
		(width 0.14478)
		(layer "In2.Cu")
		(net "M_I_CPU0_SB_DQ<14>")
	)
	(segment
		(start 406.890728 -293.711376)
		(end 407.05278 -293.873428)
		(width 0.14478)
		(layer "In2.Cu")
		(net "M_I_CPU0_SB_DQ<14>")
	)
	(segment
		(start 410.173932 -297.222926)
		(end 410.010102 -297.386756)
		(width 0.14478)
		(layer "In2.Cu")
		(net "M_I_CPU0_SB_DQ<14>")
	)
	(segment
		(start 410.792168 -297.612816)
		(end 411.046676 -297.867324)
		(width 0.14478)
		(layer "In2.Cu")
		(net "M_I_CPU0_SB_DQ<14>")
	)
	(segment
		(start 407.442924 -294.491664)
		(end 407.671016 -294.491664)
		(width 0.14478)
		(layer "In2.Cu")
		(net "M_I_CPU0_SB_DQ<14>")
	)
	(segment
		(start 407.05278 -293.873428)
		(end 407.05278 -294.101774)
		(width 0.14478)
		(layer "In2.Cu")
		(net "M_I_CPU0_SB_DQ<14>")
	)
	(segment
		(start 394.495274 -283.38145)
		(end 395.292834 -283.38145)
		(width 0.0889)
		(layer "In2.Cu")
		(net "M_I_CPU0_SB_DQ<14>")
	)
	(segment
		(start 377.874784 -282.996132)
		(end 377.72086 -282.730702)
		(width 0.0889)
		(layer "In2.Cu")
		(net "M_I_CPU0_SB_DQ<14>")
	)
	(segment
		(start 413.520128 -297.937936)
		(end 413.817816 -298.061888)
		(width 0.14478)
		(layer "In2.Cu")
		(net "M_I_CPU0_SB_DQ<14>")
	)
	(segment
		(start 414.085532 -297.95089)
		(end 414.231328 -297.598846)
		(width 0.14478)
		(layer "In2.Cu")
		(net "M_I_CPU0_SB_DQ<14>")
	)
	(segment
		(start 377.72086 -282.730702)
		(end 377.743212 -282.64739)
		(width 0.0889)
		(layer "In2.Cu")
		(net "M_I_CPU0_SB_DQ<14>")
	)
	(segment
		(start 388.393432 -282.668726)
		(end 388.401814 -282.673552)
		(width 0.0889)
		(layer "In2.Cu")
		(net "M_I_CPU0_SB_DQ<14>")
	)
	(segment
		(start 409.0035 -296.05224)
		(end 409.231592 -296.05224)
		(width 0.14478)
		(layer "In2.Cu")
		(net "M_I_CPU0_SB_DQ<14>")
	)
	(segment
		(start 406.88895 -294.493696)
		(end 407.051002 -294.655748)
		(width 0.14478)
		(layer "In2.Cu")
		(net "M_I_CPU0_SB_DQ<14>")
	)
	(segment
		(start 406.272492 -293.09314)
		(end 406.272492 -293.321486)
		(width 0.14478)
		(layer "In2.Cu")
		(net "M_I_CPU0_SB_DQ<14>")
	)
	(segment
		(start 417.746688 -297.204384)
		(end 418.152834 -297.372786)
		(width 0.14478)
		(layer "In2.Cu")
		(net "M_I_CPU0_SB_DQ<14>")
	)
	(segment
		(start 406.108662 -293.485316)
		(end 406.108662 -293.713408)
		(width 0.14478)
		(layer "In2.Cu")
		(net "M_I_CPU0_SB_DQ<14>")
	)
	(segment
		(start 408.451304 -295.271952)
		(end 408.613356 -295.434004)
		(width 0.14478)
		(layer "In2.Cu")
		(net "M_I_CPU0_SB_DQ<14>")
	)
	(segment
		(start 407.833068 -294.653716)
		(end 407.833068 -294.882062)
		(width 0.14478)
		(layer "In2.Cu")
		(net "M_I_CPU0_SB_DQ<14>")
	)
	(segment
		(start 407.671016 -294.491664)
		(end 407.833068 -294.653716)
		(width 0.14478)
		(layer "In2.Cu")
		(net "M_I_CPU0_SB_DQ<14>")
	)
	(segment
		(start 406.270714 -293.87546)
		(end 406.498806 -293.87546)
		(width 0.14478)
		(layer "In2.Cu")
		(net "M_I_CPU0_SB_DQ<14>")
	)
	(segment
		(start 384.63347 -282.668726)
		(end 384.641852 -282.673552)
		(width 0.0889)
		(layer "In2.Cu")
		(net "M_I_CPU0_SB_DQ<14>")
	)
	(segment
		(start 410.010102 -297.614848)
		(end 410.172154 -297.7769)
		(width 0.14478)
		(layer "In2.Cu")
		(net "M_I_CPU0_SB_DQ<14>")
	)
	(segment
		(start 411.046676 -297.867324)
		(end 411.513782 -298.060364)
		(width 0.14478)
		(layer "In2.Cu")
		(net "M_I_CPU0_SB_DQ<14>")
	)
	(segment
		(start 425.768516 -297.47845)
		(end 426.059092 -297.47845)
		(width 0.14478)
		(layer "In2.Cu")
		(net "M_I_CPU0_SB_DQ<14>")
	)
	(segment
		(start 418.152834 -297.372786)
		(end 418.264086 -297.641264)
		(width 0.14478)
		(layer "In2.Cu")
		(net "M_I_CPU0_SB_DQ<14>")
	)
	(segment
		(start 407.669238 -295.273984)
		(end 407.83129 -295.436036)
		(width 0.14478)
		(layer "In2.Cu")
		(net "M_I_CPU0_SB_DQ<14>")
	)
	(segment
		(start 393.08405 -282.663392)
		(end 393.102338 -282.673806)
		(width 0.0889)
		(layer "In2.Cu")
		(net "M_I_CPU0_SB_DQ<14>")
	)
	(segment
		(start 407.05278 -294.101774)
		(end 406.88895 -294.265604)
		(width 0.14478)
		(layer "In2.Cu")
		(net "M_I_CPU0_SB_DQ<14>")
	)
	(segment
		(start 409.231592 -296.05224)
		(end 409.393644 -296.214292)
		(width 0.14478)
		(layer "In2.Cu")
		(net "M_I_CPU0_SB_DQ<14>")
	)
	(segment
		(start 386.147818 -282.673552)
		(end 386.1562 -282.668726)
		(width 0.0889)
		(layer "In2.Cu")
		(net "M_I_CPU0_SB_DQ<14>")
	)
	(segment
		(start 392.161776 -282.673552)
		(end 392.176508 -282.682188)
		(width 0.0889)
		(layer "In2.Cu")
		(net "M_I_CPU0_SB_DQ<14>")
	)
	(segment
		(start 409.391866 -296.996612)
		(end 409.619958 -296.996612)
		(width 0.14478)
		(layer "In2.Cu")
		(net "M_I_CPU0_SB_DQ<14>")
	)
	(segment
		(start 406.662636 -293.711376)
		(end 406.890728 -293.711376)
		(width 0.14478)
		(layer "In2.Cu")
		(net "M_I_CPU0_SB_DQ<14>")
	)
	(segment
		(start 396.327122 -283.14777)
		(end 406.272492 -293.09314)
		(width 0.14478)
		(layer "In2.Cu")
		(net "M_I_CPU0_SB_DQ<14>")
	)
	(segment
		(start 415.169096 -297.210226)
		(end 417.223194 -297.210226)
		(width 0.14478)
		(layer "In2.Cu")
		(net "M_I_CPU0_SB_DQ<14>")
	)
	(segment
		(start 410.173932 -296.99458)
		(end 410.173932 -297.222926)
		(width 0.14478)
		(layer "In2.Cu")
		(net "M_I_CPU0_SB_DQ<14>")
	)
	(segment
		(start 406.498806 -293.87546)
		(end 406.662636 -293.711376)
		(width 0.14478)
		(layer "In2.Cu")
		(net "M_I_CPU0_SB_DQ<14>")
	)
	(segment
		(start 407.83129 -295.436036)
		(end 408.059382 -295.436036)
		(width 0.14478)
		(layer "In2.Cu")
		(net "M_I_CPU0_SB_DQ<14>")
	)
	(segment
		(start 389.333486 -282.668726)
		(end 389.341868 -282.673552)
		(width 0.0889)
		(layer "In2.Cu")
		(net "M_I_CPU0_SB_DQ<14>")
	)
	(segment
		(start 411.513782 -298.060364)
		(end 413.224472 -298.060364)
		(width 0.14478)
		(layer "In2.Cu")
		(net "M_I_CPU0_SB_DQ<14>")
	)
	(segment
		(start 392.153394 -282.668726)
		(end 392.161776 -282.673552)
		(width 0.0889)
		(layer "In2.Cu")
		(net "M_I_CPU0_SB_DQ<14>")
	)
	(segment
		(start 410.01188 -296.832528)
		(end 410.173932 -296.99458)
		(width 0.14478)
		(layer "In2.Cu")
		(net "M_I_CPU0_SB_DQ<14>")
	)
	(segment
		(start 408.449526 -296.054272)
		(end 408.611578 -296.216324)
		(width 0.14478)
		(layer "In2.Cu")
		(net "M_I_CPU0_SB_DQ<14>")
	)
	(arc
		(start 384.26771 -282.673552)
		(mid 384.449961 -282.623202)
		(end 384.63347 -282.668726)
		(width 0.0889)
		(layer "In2.Cu")
		(net "M_I_CPU0_SB_DQ<14>")
	)
	(arc
		(start 386.1562 -282.668726)
		(mid 386.339708 -282.623232)
		(end 386.52196 -282.673552)
		(width 0.0889)
		(layer "In2.Cu")
		(net "M_I_CPU0_SB_DQ<14>")
	)
	(arc
		(start 380.88189 -282.673552)
		(mid 381.164846 -282.749729)
		(end 381.447802 -282.673552)
		(width 0.0889)
		(layer "In2.Cu")
		(net "M_I_CPU0_SB_DQ<14>")
	)
	(arc
		(start 388.027672 -282.673552)
		(mid 388.209923 -282.623202)
		(end 388.393432 -282.668726)
		(width 0.0889)
		(layer "In2.Cu")
		(net "M_I_CPU0_SB_DQ<14>")
	)
	(arc
		(start 385.216146 -282.668726)
		(mid 385.399654 -282.623232)
		(end 385.581906 -282.673552)
		(width 0.0889)
		(layer "In2.Cu")
		(net "M_I_CPU0_SB_DQ<14>")
	)
	(arc
		(start 379.001782 -282.673552)
		(mid 379.284738 -282.749729)
		(end 379.567694 -282.673552)
		(width 0.0889)
		(layer "In2.Cu")
		(net "M_I_CPU0_SB_DQ<14>")
	)
	(arc
		(start 384.641852 -282.673552)
		(mid 384.924808 -282.749729)
		(end 385.207764 -282.673552)
		(width 0.0889)
		(layer "In2.Cu")
		(net "M_I_CPU0_SB_DQ<14>")
	)
	(arc
		(start 392.176508 -282.682188)
		(mid 392.453491 -282.749992)
		(end 392.728196 -282.673552)
		(width 0.0889)
		(layer "In2.Cu")
		(net "M_I_CPU0_SB_DQ<14>")
	)
	(arc
		(start 381.821944 -282.673552)
		(mid 382.1049 -282.749729)
		(end 382.387856 -282.673552)
		(width 0.0889)
		(layer "In2.Cu")
		(net "M_I_CPU0_SB_DQ<14>")
	)
	(arc
		(start 383.327656 -282.673552)
		(mid 383.509907 -282.623202)
		(end 383.693416 -282.668726)
		(width 0.0889)
		(layer "In2.Cu")
		(net "M_I_CPU0_SB_DQ<14>")
	)
	(arc
		(start 379.941836 -282.673552)
		(mid 380.224792 -282.749729)
		(end 380.507748 -282.673552)
		(width 0.0889)
		(layer "In2.Cu")
		(net "M_I_CPU0_SB_DQ<14>")
	)
	(arc
		(start 378.061982 -282.673552)
		(mid 378.344938 -282.749729)
		(end 378.627894 -282.673552)
		(width 0.0889)
		(layer "In2.Cu")
		(net "M_I_CPU0_SB_DQ<14>")
	)
	(arc
		(start 391.787634 -282.673552)
		(mid 391.969885 -282.623202)
		(end 392.153394 -282.668726)
		(width 0.0889)
		(layer "In2.Cu")
		(net "M_I_CPU0_SB_DQ<14>")
	)
	(arc
		(start 382.387856 -282.673552)
		(mid 382.5748 -282.623297)
		(end 382.761744 -282.673552)
		(width 0.0889)
		(layer "In2.Cu")
		(net "M_I_CPU0_SB_DQ<14>")
	)
	(arc
		(start 388.401814 -282.673552)
		(mid 388.68477 -282.749729)
		(end 388.967726 -282.673552)
		(width 0.0889)
		(layer "In2.Cu")
		(net "M_I_CPU0_SB_DQ<14>")
	)
	(arc
		(start 380.507748 -282.673552)
		(mid 380.689999 -282.623202)
		(end 380.873508 -282.668726)
		(width 0.0889)
		(layer "In2.Cu")
		(net "M_I_CPU0_SB_DQ<14>")
	)
	(arc
		(start 389.916162 -282.668726)
		(mid 390.09967 -282.623232)
		(end 390.281922 -282.673552)
		(width 0.0889)
		(layer "In2.Cu")
		(net "M_I_CPU0_SB_DQ<14>")
	)
	(arc
		(start 377.743212 -282.64739)
		(mid 377.905544 -282.624572)
		(end 378.061982 -282.673552)
		(width 0.0889)
		(layer "In2.Cu")
		(net "M_I_CPU0_SB_DQ<14>")
	)
	(arc
		(start 388.967726 -282.673552)
		(mid 389.149977 -282.623202)
		(end 389.333486 -282.668726)
		(width 0.0889)
		(layer "In2.Cu")
		(net "M_I_CPU0_SB_DQ<14>")
	)
	(arc
		(start 389.341868 -282.673552)
		(mid 389.624824 -282.749729)
		(end 389.90778 -282.673552)
		(width 0.0889)
		(layer "In2.Cu")
		(net "M_I_CPU0_SB_DQ<14>")
	)
	(arc
		(start 390.281922 -282.673552)
		(mid 390.564878 -282.749729)
		(end 390.847834 -282.673552)
		(width 0.0889)
		(layer "In2.Cu")
		(net "M_I_CPU0_SB_DQ<14>")
	)
	(arc
		(start 390.847834 -282.673552)
		(mid 391.034778 -282.623297)
		(end 391.221722 -282.673552)
		(width 0.0889)
		(layer "In2.Cu")
		(net "M_I_CPU0_SB_DQ<14>")
	)
	(arc
		(start 391.221722 -282.673552)
		(mid 391.504678 -282.749729)
		(end 391.787634 -282.673552)
		(width 0.0889)
		(layer "In2.Cu")
		(net "M_I_CPU0_SB_DQ<14>")
	)
	(arc
		(start 383.701798 -282.673552)
		(mid 383.984754 -282.749729)
		(end 384.26771 -282.673552)
		(width 0.0889)
		(layer "In2.Cu")
		(net "M_I_CPU0_SB_DQ<14>")
	)
	(arc
		(start 392.728196 -282.673552)
		(mid 392.904824 -282.623319)
		(end 393.08405 -282.663392)
		(width 0.0889)
		(layer "In2.Cu")
		(net "M_I_CPU0_SB_DQ<14>")
	)
	(arc
		(start 381.456184 -282.668726)
		(mid 381.639692 -282.623232)
		(end 381.821944 -282.673552)
		(width 0.0889)
		(layer "In2.Cu")
		(net "M_I_CPU0_SB_DQ<14>")
	)
	(arc
		(start 387.087872 -282.673552)
		(mid 387.274816 -282.623297)
		(end 387.46176 -282.673552)
		(width 0.0889)
		(layer "In2.Cu")
		(net "M_I_CPU0_SB_DQ<14>")
	)
	(arc
		(start 387.46176 -282.673552)
		(mid 387.744716 -282.749729)
		(end 388.027672 -282.673552)
		(width 0.0889)
		(layer "In2.Cu")
		(net "M_I_CPU0_SB_DQ<14>")
	)
	(arc
		(start 382.761744 -282.673552)
		(mid 383.0447 -282.749729)
		(end 383.327656 -282.673552)
		(width 0.0889)
		(layer "In2.Cu")
		(net "M_I_CPU0_SB_DQ<14>")
	)
	(arc
		(start 385.581906 -282.673552)
		(mid 385.864862 -282.749729)
		(end 386.147818 -282.673552)
		(width 0.0889)
		(layer "In2.Cu")
		(net "M_I_CPU0_SB_DQ<14>")
	)
	(arc
		(start 393.118086 -282.68295)
		(mid 393.247285 -282.732987)
		(end 393.384786 -282.750006)
		(width 0.0889)
		(layer "In2.Cu")
		(net "M_I_CPU0_SB_DQ<14>")
	)
	(arc
		(start 378.627894 -282.673552)
		(mid 378.814838 -282.623297)
		(end 379.001782 -282.673552)
		(width 0.0889)
		(layer "In2.Cu")
		(net "M_I_CPU0_SB_DQ<14>")
	)
	(arc
		(start 386.52196 -282.673552)
		(mid 386.804916 -282.749729)
		(end 387.087872 -282.673552)
		(width 0.0889)
		(layer "In2.Cu")
		(net "M_I_CPU0_SB_DQ<14>")
	)
	(arc
		(start 379.567694 -282.673552)
		(mid 379.749945 -282.623202)
		(end 379.933454 -282.668726)
		(width 0.0889)
		(layer "In2.Cu")
		(net "M_I_CPU0_SB_DQ<14>")
	)
	(segment
		(start 375.528078 -282.730194)
		(end 375.99493 -282.996132)
		(width 0.10668)
		(layer "F.Cu")
		(net "M_I_CPU0_SB_DQ<13>")
	)
	(segment
		(start 376.148854 -283.261562)
		(end 376.244866 -283.286962)
		(width 0.0889)
		(layer "In2.Cu")
		(net "M_I_CPU0_SB_DQ<13>")
	)
	(segment
		(start 409.917392 -298.158154)
		(end 410.481272 -298.391834)
		(width 0.14478)
		(layer "In2.Cu")
		(net "M_I_CPU0_SB_DQ<13>")
	)
	(segment
		(start 405.659082 -293.803578)
		(end 405.727154 -293.967916)
		(width 0.14478)
		(layer "In2.Cu")
		(net "M_I_CPU0_SB_DQ<13>")
	)
	(segment
		(start 384.63347 -283.323538)
		(end 384.641852 -283.318712)
		(width 0.0889)
		(layer "In2.Cu")
		(net "M_I_CPU0_SB_DQ<13>")
	)
	(segment
		(start 392.724386 -283.318712)
		(end 392.74496 -283.33065)
		(width 0.0889)
		(layer "In2.Cu")
		(net "M_I_CPU0_SB_DQ<13>")
	)
	(segment
		(start 419.691566 -298.910248)
		(end 420.081456 -298.910248)
		(width 0.14478)
		(layer "In2.Cu")
		(net "M_I_CPU0_SB_DQ<13>")
	)
	(segment
		(start 423.38625 -298.060364)
		(end 431.131472 -298.060364)
		(width 0.14478)
		(layer "In2.Cu")
		(net "M_I_CPU0_SB_DQ<13>")
	)
	(segment
		(start 388.393432 -283.323538)
		(end 388.401814 -283.318712)
		(width 0.0889)
		(layer "In2.Cu")
		(net "M_I_CPU0_SB_DQ<13>")
	)
	(segment
		(start 385.207764 -283.318712)
		(end 385.216146 -283.323538)
		(width 0.0889)
		(layer "In2.Cu")
		(net "M_I_CPU0_SB_DQ<13>")
	)
	(segment
		(start 411.86481 -298.811442)
		(end 412.361126 -298.910248)
		(width 0.14478)
		(layer "In2.Cu")
		(net "M_I_CPU0_SB_DQ<13>")
	)
	(segment
		(start 417.639754 -298.060364)
		(end 419.691566 -298.910248)
		(width 0.14478)
		(layer "In2.Cu")
		(net "M_I_CPU0_SB_DQ<13>")
	)
	(segment
		(start 376.747786 -283.318712)
		(end 376.756168 -283.323538)
		(width 0.0889)
		(layer "In2.Cu")
		(net "M_I_CPU0_SB_DQ<13>")
	)
	(segment
		(start 420.976298 -298.539662)
		(end 423.38625 -298.060364)
		(width 0.14478)
		(layer "In2.Cu")
		(net "M_I_CPU0_SB_DQ<13>")
	)
	(segment
		(start 405.727154 -293.967916)
		(end 409.917392 -298.158154)
		(width 0.14478)
		(layer "In2.Cu")
		(net "M_I_CPU0_SB_DQ<13>")
	)
	(segment
		(start 412.588202 -298.910248)
		(end 415.389568 -298.060364)
		(width 0.14478)
		(layer "In2.Cu")
		(net "M_I_CPU0_SB_DQ<13>")
	)
	(segment
		(start 389.333486 -283.323538)
		(end 389.341868 -283.318712)
		(width 0.0889)
		(layer "In2.Cu")
		(net "M_I_CPU0_SB_DQ<13>")
	)
	(segment
		(start 415.389568 -298.060364)
		(end 417.639754 -298.060364)
		(width 0.14478)
		(layer "In2.Cu")
		(net "M_I_CPU0_SB_DQ<13>")
	)
	(segment
		(start 392.160506 -283.318458)
		(end 392.186668 -283.303472)
		(width 0.0889)
		(layer "In2.Cu")
		(net "M_I_CPU0_SB_DQ<13>")
	)
	(segment
		(start 386.147818 -283.318712)
		(end 386.1562 -283.323538)
		(width 0.0889)
		(layer "In2.Cu")
		(net "M_I_CPU0_SB_DQ<13>")
	)
	(segment
		(start 393.29741 -283.248862)
		(end 393.812014 -283.248862)
		(width 0.0889)
		(layer "In2.Cu")
		(net "M_I_CPU0_SB_DQ<13>")
	)
	(segment
		(start 431.131472 -298.060364)
		(end 431.55616 -298.485052)
		(width 0.14478)
		(layer "In2.Cu")
		(net "M_I_CPU0_SB_DQ<13>")
	)
	(segment
		(start 405.659082 -293.319454)
		(end 405.659082 -293.803578)
		(width 0.14478)
		(layer "In2.Cu")
		(net "M_I_CPU0_SB_DQ<13>")
	)
	(segment
		(start 375.99493 -282.996132)
		(end 376.148854 -283.261562)
		(width 0.0889)
		(layer "In2.Cu")
		(net "M_I_CPU0_SB_DQ<13>")
	)
	(segment
		(start 380.873508 -283.323538)
		(end 380.88189 -283.318712)
		(width 0.0889)
		(layer "In2.Cu")
		(net "M_I_CPU0_SB_DQ<13>")
	)
	(segment
		(start 410.481272 -298.391834)
		(end 411.86481 -298.811442)
		(width 0.14478)
		(layer "In2.Cu")
		(net "M_I_CPU0_SB_DQ<13>")
	)
	(segment
		(start 405.515318 -292.972236)
		(end 405.659082 -293.319454)
		(width 0.14478)
		(layer "In2.Cu")
		(net "M_I_CPU0_SB_DQ<13>")
	)
	(segment
		(start 377.68784 -283.318712)
		(end 377.696222 -283.323538)
		(width 0.0889)
		(layer "In2.Cu")
		(net "M_I_CPU0_SB_DQ<13>")
	)
	(segment
		(start 383.693416 -283.323538)
		(end 383.701798 -283.318712)
		(width 0.0889)
		(layer "In2.Cu")
		(net "M_I_CPU0_SB_DQ<13>")
	)
	(segment
		(start 395.899386 -283.70403)
		(end 396.066518 -283.70403)
		(width 0.14478)
		(layer "In2.Cu")
		(net "M_I_CPU0_SB_DQ<13>")
	)
	(segment
		(start 393.099798 -283.318712)
		(end 393.100052 -283.318966)
		(width 0.0889)
		(layer "In2.Cu")
		(net "M_I_CPU0_SB_DQ<13>")
	)
	(segment
		(start 394.522452 -283.70403)
		(end 395.899386 -283.70403)
		(width 0.0889)
		(layer "In2.Cu")
		(net "M_I_CPU0_SB_DQ<13>")
	)
	(segment
		(start 389.90778 -283.318712)
		(end 389.916162 -283.323538)
		(width 0.0889)
		(layer "In2.Cu")
		(net "M_I_CPU0_SB_DQ<13>")
	)
	(segment
		(start 396.375128 -283.832046)
		(end 405.515318 -292.972236)
		(width 0.14478)
		(layer "In2.Cu")
		(net "M_I_CPU0_SB_DQ<13>")
	)
	(segment
		(start 393.812014 -283.248862)
		(end 394.086588 -283.523436)
		(width 0.0889)
		(layer "In2.Cu")
		(net "M_I_CPU0_SB_DQ<13>")
	)
	(segment
		(start 379.933454 -283.323538)
		(end 379.941836 -283.318712)
		(width 0.0889)
		(layer "In2.Cu")
		(net "M_I_CPU0_SB_DQ<13>")
	)
	(segment
		(start 394.086588 -283.523436)
		(end 394.522452 -283.70403)
		(width 0.0889)
		(layer "In2.Cu")
		(net "M_I_CPU0_SB_DQ<13>")
	)
	(segment
		(start 381.447802 -283.318712)
		(end 381.456184 -283.323538)
		(width 0.0889)
		(layer "In2.Cu")
		(net "M_I_CPU0_SB_DQ<13>")
	)
	(segment
		(start 412.361126 -298.910248)
		(end 412.588202 -298.910248)
		(width 0.14478)
		(layer "In2.Cu")
		(net "M_I_CPU0_SB_DQ<13>")
	)
	(segment
		(start 420.081456 -298.910248)
		(end 420.976298 -298.539662)
		(width 0.14478)
		(layer "In2.Cu")
		(net "M_I_CPU0_SB_DQ<13>")
	)
	(segment
		(start 396.066518 -283.70403)
		(end 396.375128 -283.832046)
		(width 0.14478)
		(layer "In2.Cu")
		(net "M_I_CPU0_SB_DQ<13>")
	)
	(segment
		(start 392.137138 -283.33192)
		(end 392.160506 -283.318458)
		(width 0.0889)
		(layer "In2.Cu")
		(net "M_I_CPU0_SB_DQ<13>")
	)
	(arc
		(start 386.1562 -283.323538)
		(mid 386.339708 -283.369032)
		(end 386.52196 -283.318712)
		(width 0.0889)
		(layer "In2.Cu")
		(net "M_I_CPU0_SB_DQ<13>")
	)
	(arc
		(start 382.387856 -283.318712)
		(mid 382.5748 -283.368967)
		(end 382.761744 -283.318712)
		(width 0.0889)
		(layer "In2.Cu")
		(net "M_I_CPU0_SB_DQ<13>")
	)
	(arc
		(start 379.567694 -283.318712)
		(mid 379.749945 -283.369062)
		(end 379.933454 -283.323538)
		(width 0.0889)
		(layer "In2.Cu")
		(net "M_I_CPU0_SB_DQ<13>")
	)
	(arc
		(start 377.696222 -283.323538)
		(mid 377.87973 -283.369032)
		(end 378.061982 -283.318712)
		(width 0.0889)
		(layer "In2.Cu")
		(net "M_I_CPU0_SB_DQ<13>")
	)
	(arc
		(start 385.581906 -283.318712)
		(mid 385.864862 -283.242535)
		(end 386.147818 -283.318712)
		(width 0.0889)
		(layer "In2.Cu")
		(net "M_I_CPU0_SB_DQ<13>")
	)
	(arc
		(start 392.186668 -283.303472)
		(mid 392.457454 -283.242826)
		(end 392.724386 -283.318712)
		(width 0.0889)
		(layer "In2.Cu")
		(net "M_I_CPU0_SB_DQ<13>")
	)
	(arc
		(start 393.100052 -283.318966)
		(mid 393.195452 -283.274684)
		(end 393.29741 -283.248862)
		(width 0.0889)
		(layer "In2.Cu")
		(net "M_I_CPU0_SB_DQ<13>")
	)
	(arc
		(start 376.244866 -283.286962)
		(mid 376.500074 -283.243485)
		(end 376.747786 -283.318712)
		(width 0.0889)
		(layer "In2.Cu")
		(net "M_I_CPU0_SB_DQ<13>")
	)
	(arc
		(start 388.967726 -283.318712)
		(mid 389.149977 -283.369062)
		(end 389.333486 -283.323538)
		(width 0.0889)
		(layer "In2.Cu")
		(net "M_I_CPU0_SB_DQ<13>")
	)
	(arc
		(start 389.916162 -283.323538)
		(mid 390.09967 -283.369032)
		(end 390.281922 -283.318712)
		(width 0.0889)
		(layer "In2.Cu")
		(net "M_I_CPU0_SB_DQ<13>")
	)
	(arc
		(start 376.756168 -283.323538)
		(mid 376.939676 -283.369032)
		(end 377.121928 -283.318712)
		(width 0.0889)
		(layer "In2.Cu")
		(net "M_I_CPU0_SB_DQ<13>")
	)
	(arc
		(start 390.847834 -283.318712)
		(mid 391.034778 -283.368967)
		(end 391.221722 -283.318712)
		(width 0.0889)
		(layer "In2.Cu")
		(net "M_I_CPU0_SB_DQ<13>")
	)
	(arc
		(start 390.281922 -283.318712)
		(mid 390.564878 -283.242535)
		(end 390.847834 -283.318712)
		(width 0.0889)
		(layer "In2.Cu")
		(net "M_I_CPU0_SB_DQ<13>")
	)
	(arc
		(start 386.52196 -283.318712)
		(mid 386.804916 -283.242535)
		(end 387.087872 -283.318712)
		(width 0.0889)
		(layer "In2.Cu")
		(net "M_I_CPU0_SB_DQ<13>")
	)
	(arc
		(start 378.061982 -283.318712)
		(mid 378.344938 -283.242535)
		(end 378.627894 -283.318712)
		(width 0.0889)
		(layer "In2.Cu")
		(net "M_I_CPU0_SB_DQ<13>")
	)
	(arc
		(start 388.027672 -283.318712)
		(mid 388.209923 -283.369062)
		(end 388.393432 -283.323538)
		(width 0.0889)
		(layer "In2.Cu")
		(net "M_I_CPU0_SB_DQ<13>")
	)
	(arc
		(start 388.401814 -283.318712)
		(mid 388.68477 -283.242535)
		(end 388.967726 -283.318712)
		(width 0.0889)
		(layer "In2.Cu")
		(net "M_I_CPU0_SB_DQ<13>")
	)
	(arc
		(start 387.46176 -283.318712)
		(mid 387.744716 -283.242535)
		(end 388.027672 -283.318712)
		(width 0.0889)
		(layer "In2.Cu")
		(net "M_I_CPU0_SB_DQ<13>")
	)
	(arc
		(start 377.121928 -283.318712)
		(mid 377.404884 -283.242535)
		(end 377.68784 -283.318712)
		(width 0.0889)
		(layer "In2.Cu")
		(net "M_I_CPU0_SB_DQ<13>")
	)
	(arc
		(start 387.087872 -283.318712)
		(mid 387.274816 -283.368967)
		(end 387.46176 -283.318712)
		(width 0.0889)
		(layer "In2.Cu")
		(net "M_I_CPU0_SB_DQ<13>")
	)
	(arc
		(start 385.216146 -283.323538)
		(mid 385.399654 -283.369032)
		(end 385.581906 -283.318712)
		(width 0.0889)
		(layer "In2.Cu")
		(net "M_I_CPU0_SB_DQ<13>")
	)
	(arc
		(start 380.88189 -283.318712)
		(mid 381.164846 -283.242535)
		(end 381.447802 -283.318712)
		(width 0.0889)
		(layer "In2.Cu")
		(net "M_I_CPU0_SB_DQ<13>")
	)
	(arc
		(start 380.507748 -283.318712)
		(mid 380.689999 -283.369062)
		(end 380.873508 -283.323538)
		(width 0.0889)
		(layer "In2.Cu")
		(net "M_I_CPU0_SB_DQ<13>")
	)
	(arc
		(start 391.787634 -283.318712)
		(mid 391.960742 -283.368828)
		(end 392.137138 -283.33192)
		(width 0.0889)
		(layer "In2.Cu")
		(net "M_I_CPU0_SB_DQ<13>")
	)
	(arc
		(start 382.761744 -283.318712)
		(mid 383.0447 -283.242535)
		(end 383.327656 -283.318712)
		(width 0.0889)
		(layer "In2.Cu")
		(net "M_I_CPU0_SB_DQ<13>")
	)
	(arc
		(start 383.327656 -283.318712)
		(mid 383.509907 -283.369062)
		(end 383.693416 -283.323538)
		(width 0.0889)
		(layer "In2.Cu")
		(net "M_I_CPU0_SB_DQ<13>")
	)
	(arc
		(start 383.701798 -283.318712)
		(mid 383.984754 -283.242535)
		(end 384.26771 -283.318712)
		(width 0.0889)
		(layer "In2.Cu")
		(net "M_I_CPU0_SB_DQ<13>")
	)
	(arc
		(start 392.74496 -283.33065)
		(mid 392.923888 -283.369527)
		(end 393.099798 -283.318712)
		(width 0.0889)
		(layer "In2.Cu")
		(net "M_I_CPU0_SB_DQ<13>")
	)
	(arc
		(start 379.941836 -283.318712)
		(mid 380.224792 -283.242535)
		(end 380.507748 -283.318712)
		(width 0.0889)
		(layer "In2.Cu")
		(net "M_I_CPU0_SB_DQ<13>")
	)
	(arc
		(start 379.001782 -283.318712)
		(mid 379.284738 -283.242535)
		(end 379.567694 -283.318712)
		(width 0.0889)
		(layer "In2.Cu")
		(net "M_I_CPU0_SB_DQ<13>")
	)
	(arc
		(start 381.456184 -283.323538)
		(mid 381.639692 -283.369032)
		(end 381.821944 -283.318712)
		(width 0.0889)
		(layer "In2.Cu")
		(net "M_I_CPU0_SB_DQ<13>")
	)
	(arc
		(start 384.26771 -283.318712)
		(mid 384.449961 -283.369062)
		(end 384.63347 -283.323538)
		(width 0.0889)
		(layer "In2.Cu")
		(net "M_I_CPU0_SB_DQ<13>")
	)
	(arc
		(start 381.821944 -283.318712)
		(mid 382.1049 -283.242535)
		(end 382.387856 -283.318712)
		(width 0.0889)
		(layer "In2.Cu")
		(net "M_I_CPU0_SB_DQ<13>")
	)
	(arc
		(start 378.627894 -283.318712)
		(mid 378.814838 -283.368967)
		(end 379.001782 -283.318712)
		(width 0.0889)
		(layer "In2.Cu")
		(net "M_I_CPU0_SB_DQ<13>")
	)
	(arc
		(start 389.341868 -283.318712)
		(mid 389.624824 -283.242535)
		(end 389.90778 -283.318712)
		(width 0.0889)
		(layer "In2.Cu")
		(net "M_I_CPU0_SB_DQ<13>")
	)
	(arc
		(start 391.221722 -283.318712)
		(mid 391.504678 -283.242535)
		(end 391.787634 -283.318712)
		(width 0.0889)
		(layer "In2.Cu")
		(net "M_I_CPU0_SB_DQ<13>")
	)
	(arc
		(start 384.641852 -283.318712)
		(mid 384.924808 -283.242535)
		(end 385.207764 -283.318712)
		(width 0.0889)
		(layer "In2.Cu")
		(net "M_I_CPU0_SB_DQ<13>")
	)
	(segment
		(start 376.938032 -281.920188)
		(end 377.404884 -282.186126)
		(width 0.10668)
		(layer "F.Cu")
		(net "M_I_CPU0_SB_DQ<12>")
	)
	(segment
		(start 426.26788 -296.69867)
		(end 426.606208 -296.360342)
		(width 0.14478)
		(layer "In2.Cu")
		(net "M_I_CPU0_SB_DQ<12>")
	)
	(segment
		(start 393.182348 -282.499308)
		(end 393.198096 -282.508452)
		(width 0.0889)
		(layer "In2.Cu")
		(net "M_I_CPU0_SB_DQ<12>")
	)
	(segment
		(start 377.558808 -282.451556)
		(end 377.65482 -282.476956)
		(width 0.0889)
		(layer "In2.Cu")
		(net "M_I_CPU0_SB_DQ<12>")
	)
	(segment
		(start 393.384786 -282.559252)
		(end 393.960604 -282.559252)
		(width 0.0889)
		(layer "In2.Cu")
		(net "M_I_CPU0_SB_DQ<12>")
	)
	(segment
		(start 393.198096 -282.508452)
		(end 393.216384 -282.518866)
		(width 0.0889)
		(layer "In2.Cu")
		(net "M_I_CPU0_SB_DQ<12>")
	)
	(segment
		(start 386.983478 -282.513532)
		(end 386.99186 -282.508706)
		(width 0.0889)
		(layer "In2.Cu")
		(net "M_I_CPU0_SB_DQ<12>")
	)
	(segment
		(start 390.74344 -282.513532)
		(end 390.751822 -282.508706)
		(width 0.0889)
		(layer "In2.Cu")
		(net "M_I_CPU0_SB_DQ<12>")
	)
	(segment
		(start 431.131472 -296.360342)
		(end 431.55616 -296.78503)
		(width 0.14478)
		(layer "In2.Cu")
		(net "M_I_CPU0_SB_DQ<12>")
	)
	(segment
		(start 414.421066 -296.971974)
		(end 415.0233 -296.36974)
		(width 0.14478)
		(layer "In2.Cu")
		(net "M_I_CPU0_SB_DQ<12>")
	)
	(segment
		(start 395.567154 -282.69311)
		(end 395.83106 -282.69311)
		(width 0.0889)
		(layer "In2.Cu")
		(net "M_I_CPU0_SB_DQ<12>")
	)
	(segment
		(start 382.283462 -282.513532)
		(end 382.291844 -282.508706)
		(width 0.0889)
		(layer "In2.Cu")
		(net "M_I_CPU0_SB_DQ<12>")
	)
	(segment
		(start 382.857756 -282.508706)
		(end 382.866138 -282.513532)
		(width 0.0889)
		(layer "In2.Cu")
		(net "M_I_CPU0_SB_DQ<12>")
	)
	(segment
		(start 393.960604 -282.559252)
		(end 394.503402 -283.10205)
		(width 0.0889)
		(layer "In2.Cu")
		(net "M_I_CPU0_SB_DQ<12>")
	)
	(segment
		(start 392.257788 -282.508706)
		(end 392.269472 -282.515564)
		(width 0.0889)
		(layer "In2.Cu")
		(net "M_I_CPU0_SB_DQ<12>")
	)
	(segment
		(start 417.803584 -296.36974)
		(end 418.653722 -297.219878)
		(width 0.14478)
		(layer "In2.Cu")
		(net "M_I_CPU0_SB_DQ<12>")
	)
	(segment
		(start 413.822642 -297.219878)
		(end 414.421066 -296.971974)
		(width 0.14478)
		(layer "In2.Cu")
		(net "M_I_CPU0_SB_DQ<12>")
	)
	(segment
		(start 383.79781 -282.508706)
		(end 383.806192 -282.513532)
		(width 0.0889)
		(layer "In2.Cu")
		(net "M_I_CPU0_SB_DQ<12>")
	)
	(segment
		(start 425.762928 -296.69867)
		(end 426.26788 -296.69867)
		(width 0.14478)
		(layer "In2.Cu")
		(net "M_I_CPU0_SB_DQ<12>")
	)
	(segment
		(start 378.5235 -282.513532)
		(end 378.531882 -282.508706)
		(width 0.0889)
		(layer "In2.Cu")
		(net "M_I_CPU0_SB_DQ<12>")
	)
	(segment
		(start 418.653722 -297.219878)
		(end 421.527478 -297.219878)
		(width 0.14478)
		(layer "In2.Cu")
		(net "M_I_CPU0_SB_DQ<12>")
	)
	(segment
		(start 391.317734 -282.508706)
		(end 391.326116 -282.513532)
		(width 0.0889)
		(layer "In2.Cu")
		(net "M_I_CPU0_SB_DQ<12>")
	)
	(segment
		(start 387.557772 -282.508706)
		(end 387.566154 -282.513532)
		(width 0.0889)
		(layer "In2.Cu")
		(net "M_I_CPU0_SB_DQ<12>")
	)
	(segment
		(start 396.508478 -282.69311)
		(end 411.035246 -297.219878)
		(width 0.14478)
		(layer "In2.Cu")
		(net "M_I_CPU0_SB_DQ<12>")
	)
	(segment
		(start 380.037848 -282.508706)
		(end 380.04623 -282.513532)
		(width 0.0889)
		(layer "In2.Cu")
		(net "M_I_CPU0_SB_DQ<12>")
	)
	(segment
		(start 411.035246 -297.219878)
		(end 413.822642 -297.219878)
		(width 0.14478)
		(layer "In2.Cu")
		(net "M_I_CPU0_SB_DQ<12>")
	)
	(segment
		(start 421.527478 -297.219878)
		(end 422.377616 -296.36974)
		(width 0.14478)
		(layer "In2.Cu")
		(net "M_I_CPU0_SB_DQ<12>")
	)
	(segment
		(start 395.158214 -283.10205)
		(end 395.567154 -282.69311)
		(width 0.0889)
		(layer "In2.Cu")
		(net "M_I_CPU0_SB_DQ<12>")
	)
	(segment
		(start 377.404884 -282.186126)
		(end 377.558808 -282.451556)
		(width 0.0889)
		(layer "In2.Cu")
		(net "M_I_CPU0_SB_DQ<12>")
	)
	(segment
		(start 379.097794 -282.508706)
		(end 379.106176 -282.513532)
		(width 0.0889)
		(layer "In2.Cu")
		(net "M_I_CPU0_SB_DQ<12>")
	)
	(segment
		(start 395.83106 -282.69311)
		(end 396.508478 -282.69311)
		(width 0.14478)
		(layer "In2.Cu")
		(net "M_I_CPU0_SB_DQ<12>")
	)
	(segment
		(start 388.497826 -282.508706)
		(end 388.506208 -282.513532)
		(width 0.0889)
		(layer "In2.Cu")
		(net "M_I_CPU0_SB_DQ<12>")
	)
	(segment
		(start 394.503402 -283.10205)
		(end 395.158214 -283.10205)
		(width 0.0889)
		(layer "In2.Cu")
		(net "M_I_CPU0_SB_DQ<12>")
	)
	(segment
		(start 415.0233 -296.36974)
		(end 417.803584 -296.36974)
		(width 0.14478)
		(layer "In2.Cu")
		(net "M_I_CPU0_SB_DQ<12>")
	)
	(segment
		(start 426.606208 -296.360342)
		(end 431.131472 -296.360342)
		(width 0.14478)
		(layer "In2.Cu")
		(net "M_I_CPU0_SB_DQ<12>")
	)
	(segment
		(start 422.377616 -296.36974)
		(end 425.433998 -296.36974)
		(width 0.14478)
		(layer "In2.Cu")
		(net "M_I_CPU0_SB_DQ<12>")
	)
	(segment
		(start 386.043424 -282.513532)
		(end 386.051806 -282.508706)
		(width 0.0889)
		(layer "In2.Cu")
		(net "M_I_CPU0_SB_DQ<12>")
	)
	(segment
		(start 425.433998 -296.36974)
		(end 425.762928 -296.69867)
		(width 0.14478)
		(layer "In2.Cu")
		(net "M_I_CPU0_SB_DQ<12>")
	)
	(arc
		(start 388.506208 -282.513532)
		(mid 388.689716 -282.559026)
		(end 388.871968 -282.508706)
		(width 0.0889)
		(layer "In2.Cu")
		(net "M_I_CPU0_SB_DQ<12>")
	)
	(arc
		(start 387.566154 -282.513532)
		(mid 387.749662 -282.559026)
		(end 387.931914 -282.508706)
		(width 0.0889)
		(layer "In2.Cu")
		(net "M_I_CPU0_SB_DQ<12>")
	)
	(arc
		(start 388.871968 -282.508706)
		(mid 389.154924 -282.432529)
		(end 389.43788 -282.508706)
		(width 0.0889)
		(layer "In2.Cu")
		(net "M_I_CPU0_SB_DQ<12>")
	)
	(arc
		(start 385.111752 -282.508706)
		(mid 385.394708 -282.432529)
		(end 385.677664 -282.508706)
		(width 0.0889)
		(layer "In2.Cu")
		(net "M_I_CPU0_SB_DQ<12>")
	)
	(arc
		(start 384.737864 -282.508706)
		(mid 384.924808 -282.558961)
		(end 385.111752 -282.508706)
		(width 0.0889)
		(layer "In2.Cu")
		(net "M_I_CPU0_SB_DQ<12>")
	)
	(arc
		(start 390.37768 -282.508706)
		(mid 390.559931 -282.559056)
		(end 390.74344 -282.513532)
		(width 0.0889)
		(layer "In2.Cu")
		(net "M_I_CPU0_SB_DQ<12>")
	)
	(arc
		(start 393.216384 -282.518866)
		(mid 393.298208 -282.548979)
		(end 393.384786 -282.559252)
		(width 0.0889)
		(layer "In2.Cu")
		(net "M_I_CPU0_SB_DQ<12>")
	)
	(arc
		(start 380.04623 -282.513532)
		(mid 380.229738 -282.559026)
		(end 380.41199 -282.508706)
		(width 0.0889)
		(layer "In2.Cu")
		(net "M_I_CPU0_SB_DQ<12>")
	)
	(arc
		(start 389.811768 -282.508706)
		(mid 390.094724 -282.432529)
		(end 390.37768 -282.508706)
		(width 0.0889)
		(layer "In2.Cu")
		(net "M_I_CPU0_SB_DQ<12>")
	)
	(arc
		(start 386.617718 -282.508706)
		(mid 386.799969 -282.559056)
		(end 386.983478 -282.513532)
		(width 0.0889)
		(layer "In2.Cu")
		(net "M_I_CPU0_SB_DQ<12>")
	)
	(arc
		(start 392.632184 -282.508706)
		(mid 392.906039 -282.432356)
		(end 393.182348 -282.499308)
		(width 0.0889)
		(layer "In2.Cu")
		(net "M_I_CPU0_SB_DQ<12>")
	)
	(arc
		(start 378.15774 -282.508706)
		(mid 378.339991 -282.559056)
		(end 378.5235 -282.513532)
		(width 0.0889)
		(layer "In2.Cu")
		(net "M_I_CPU0_SB_DQ<12>")
	)
	(arc
		(start 380.41199 -282.508706)
		(mid 380.694946 -282.432529)
		(end 380.977902 -282.508706)
		(width 0.0889)
		(layer "In2.Cu")
		(net "M_I_CPU0_SB_DQ<12>")
	)
	(arc
		(start 379.471936 -282.508706)
		(mid 379.754892 -282.432529)
		(end 380.037848 -282.508706)
		(width 0.0889)
		(layer "In2.Cu")
		(net "M_I_CPU0_SB_DQ<12>")
	)
	(arc
		(start 389.43788 -282.508706)
		(mid 389.624824 -282.558961)
		(end 389.811768 -282.508706)
		(width 0.0889)
		(layer "In2.Cu")
		(net "M_I_CPU0_SB_DQ<12>")
	)
	(arc
		(start 391.326116 -282.513532)
		(mid 391.509624 -282.559026)
		(end 391.691876 -282.508706)
		(width 0.0889)
		(layer "In2.Cu")
		(net "M_I_CPU0_SB_DQ<12>")
	)
	(arc
		(start 379.106176 -282.513532)
		(mid 379.289684 -282.559026)
		(end 379.471936 -282.508706)
		(width 0.0889)
		(layer "In2.Cu")
		(net "M_I_CPU0_SB_DQ<12>")
	)
	(arc
		(start 381.35179 -282.508706)
		(mid 381.634746 -282.432529)
		(end 381.917702 -282.508706)
		(width 0.0889)
		(layer "In2.Cu")
		(net "M_I_CPU0_SB_DQ<12>")
	)
	(arc
		(start 386.99186 -282.508706)
		(mid 387.274816 -282.432529)
		(end 387.557772 -282.508706)
		(width 0.0889)
		(layer "In2.Cu")
		(net "M_I_CPU0_SB_DQ<12>")
	)
	(arc
		(start 383.806192 -282.513532)
		(mid 383.9897 -282.559026)
		(end 384.171952 -282.508706)
		(width 0.0889)
		(layer "In2.Cu")
		(net "M_I_CPU0_SB_DQ<12>")
	)
	(arc
		(start 384.171952 -282.508706)
		(mid 384.454908 -282.432529)
		(end 384.737864 -282.508706)
		(width 0.0889)
		(layer "In2.Cu")
		(net "M_I_CPU0_SB_DQ<12>")
	)
	(arc
		(start 390.751822 -282.508706)
		(mid 391.034778 -282.432529)
		(end 391.317734 -282.508706)
		(width 0.0889)
		(layer "In2.Cu")
		(net "M_I_CPU0_SB_DQ<12>")
	)
	(arc
		(start 391.691876 -282.508706)
		(mid 391.974832 -282.432529)
		(end 392.257788 -282.508706)
		(width 0.0889)
		(layer "In2.Cu")
		(net "M_I_CPU0_SB_DQ<12>")
	)
	(arc
		(start 378.531882 -282.508706)
		(mid 378.814838 -282.432529)
		(end 379.097794 -282.508706)
		(width 0.0889)
		(layer "In2.Cu")
		(net "M_I_CPU0_SB_DQ<12>")
	)
	(arc
		(start 392.269472 -282.515564)
		(mid 392.451727 -282.559217)
		(end 392.632184 -282.508706)
		(width 0.0889)
		(layer "In2.Cu")
		(net "M_I_CPU0_SB_DQ<12>")
	)
	(arc
		(start 380.977902 -282.508706)
		(mid 381.164846 -282.558961)
		(end 381.35179 -282.508706)
		(width 0.0889)
		(layer "In2.Cu")
		(net "M_I_CPU0_SB_DQ<12>")
	)
	(arc
		(start 383.231898 -282.508706)
		(mid 383.514854 -282.432529)
		(end 383.79781 -282.508706)
		(width 0.0889)
		(layer "In2.Cu")
		(net "M_I_CPU0_SB_DQ<12>")
	)
	(arc
		(start 385.677664 -282.508706)
		(mid 385.859915 -282.559056)
		(end 386.043424 -282.513532)
		(width 0.0889)
		(layer "In2.Cu")
		(net "M_I_CPU0_SB_DQ<12>")
	)
	(arc
		(start 377.65482 -282.476956)
		(mid 377.910028 -282.433479)
		(end 378.15774 -282.508706)
		(width 0.0889)
		(layer "In2.Cu")
		(net "M_I_CPU0_SB_DQ<12>")
	)
	(arc
		(start 382.866138 -282.513532)
		(mid 383.049646 -282.559026)
		(end 383.231898 -282.508706)
		(width 0.0889)
		(layer "In2.Cu")
		(net "M_I_CPU0_SB_DQ<12>")
	)
	(arc
		(start 387.931914 -282.508706)
		(mid 388.21487 -282.432529)
		(end 388.497826 -282.508706)
		(width 0.0889)
		(layer "In2.Cu")
		(net "M_I_CPU0_SB_DQ<12>")
	)
	(arc
		(start 381.917702 -282.508706)
		(mid 382.099953 -282.559056)
		(end 382.283462 -282.513532)
		(width 0.0889)
		(layer "In2.Cu")
		(net "M_I_CPU0_SB_DQ<12>")
	)
	(arc
		(start 382.291844 -282.508706)
		(mid 382.5748 -282.432529)
		(end 382.857756 -282.508706)
		(width 0.0889)
		(layer "In2.Cu")
		(net "M_I_CPU0_SB_DQ<12>")
	)
	(arc
		(start 386.051806 -282.508706)
		(mid 386.334762 -282.432529)
		(end 386.617718 -282.508706)
		(width 0.0889)
		(layer "In2.Cu")
		(net "M_I_CPU0_SB_DQ<12>")
	)
	(segment
		(start 375.997978 -280.300176)
		(end 376.46483 -280.566114)
		(width 0.10668)
		(layer "F.Cu")
		(net "M_I_CPU0_SB_DQ<11>")
	)
	(segment
		(start 395.336522 -280.199338)
		(end 395.490954 -280.35377)
		(width 0.0889)
		(layer "In2.Cu")
		(net "M_I_CPU0_SB_DQ<11>")
	)
	(segment
		(start 402.125942 -284.647894)
		(end 402.33092 -284.442916)
		(width 0.14478)
		(layer "In2.Cu")
		(net "M_I_CPU0_SB_DQ<11>")
	)
	(segment
		(start 386.043424 -280.238708)
		(end 386.051806 -280.243534)
		(width 0.0889)
		(layer "In2.Cu")
		(net "M_I_CPU0_SB_DQ<11>")
	)
	(segment
		(start 421.255952 -293.558976)
		(end 421.605202 -293.628826)
		(width 0.14478)
		(layer "In2.Cu")
		(net "M_I_CPU0_SB_DQ<11>")
	)
	(segment
		(start 392.255756 -280.243788)
		(end 392.2776 -280.231342)
		(width 0.0889)
		(layer "In2.Cu")
		(net "M_I_CPU0_SB_DQ<11>")
	)
	(segment
		(start 388.497826 -280.243534)
		(end 388.506208 -280.238708)
		(width 0.0889)
		(layer "In2.Cu")
		(net "M_I_CPU0_SB_DQ<11>")
	)
	(segment
		(start 427.09084 -293.019734)
		(end 427.456092 -293.384986)
		(width 0.14478)
		(layer "In2.Cu")
		(net "M_I_CPU0_SB_DQ<11>")
	)
	(segment
		(start 419.142926 -293.800276)
		(end 420.894764 -293.800276)
		(width 0.14478)
		(layer "In2.Cu")
		(net "M_I_CPU0_SB_DQ<11>")
	)
	(segment
		(start 392.229594 -280.258774)
		(end 392.255756 -280.243788)
		(width 0.0889)
		(layer "In2.Cu")
		(net "M_I_CPU0_SB_DQ<11>")
	)
	(segment
		(start 422.152064 -292.960044)
		(end 422.525698 -292.58641)
		(width 0.14478)
		(layer "In2.Cu")
		(net "M_I_CPU0_SB_DQ<11>")
	)
	(segment
		(start 422.809924 -292.58641)
		(end 423.173906 -292.950392)
		(width 0.14478)
		(layer "In2.Cu")
		(net "M_I_CPU0_SB_DQ<11>")
	)
	(segment
		(start 426.381418 -293.412164)
		(end 426.531278 -293.262304)
		(width 0.14478)
		(layer "In2.Cu")
		(net "M_I_CPU0_SB_DQ<11>")
	)
	(segment
		(start 386.983478 -280.238708)
		(end 386.99186 -280.243534)
		(width 0.0889)
		(layer "In2.Cu")
		(net "M_I_CPU0_SB_DQ<11>")
	)
	(segment
		(start 417.42868 -292.950392)
		(end 417.9443 -292.73627)
		(width 0.14478)
		(layer "In2.Cu")
		(net "M_I_CPU0_SB_DQ<11>")
	)
	(segment
		(start 423.173906 -292.950392)
		(end 425.27347 -292.950392)
		(width 0.14478)
		(layer "In2.Cu")
		(net "M_I_CPU0_SB_DQ<11>")
	)
	(segment
		(start 401.3454 -283.86786)
		(end 401.550632 -283.662628)
		(width 0.14478)
		(layer "In2.Cu")
		(net "M_I_CPU0_SB_DQ<11>")
	)
	(segment
		(start 411.395418 -293.645336)
		(end 411.550358 -293.800276)
		(width 0.14478)
		(layer "In2.Cu")
		(net "M_I_CPU0_SB_DQ<11>")
	)
	(segment
		(start 418.553392 -293.210742)
		(end 419.142926 -293.800276)
		(width 0.14478)
		(layer "In2.Cu")
		(net "M_I_CPU0_SB_DQ<11>")
	)
	(segment
		(start 417.9443 -292.73627)
		(end 418.44214 -292.942772)
		(width 0.14478)
		(layer "In2.Cu")
		(net "M_I_CPU0_SB_DQ<11>")
	)
	(segment
		(start 413.785304 -293.273734)
		(end 414.045146 -293.166038)
		(width 0.14478)
		(layer "In2.Cu")
		(net "M_I_CPU0_SB_DQ<11>")
	)
	(segment
		(start 401.940776 -283.824172)
		(end 401.940776 -284.052772)
		(width 0.14478)
		(layer "In2.Cu")
		(net "M_I_CPU0_SB_DQ<11>")
	)
	(segment
		(start 401.897342 -284.647894)
		(end 402.125942 -284.647894)
		(width 0.14478)
		(layer "In2.Cu")
		(net "M_I_CPU0_SB_DQ<11>")
	)
	(segment
		(start 401.550632 -283.662628)
		(end 401.779232 -283.662628)
		(width 0.14478)
		(layer "In2.Cu")
		(net "M_I_CPU0_SB_DQ<11>")
	)
	(segment
		(start 426.681138 -292.62197)
		(end 426.94098 -292.62197)
		(width 0.14478)
		(layer "In2.Cu")
		(net "M_I_CPU0_SB_DQ<11>")
	)
	(segment
		(start 414.862264 -292.950392)
		(end 417.42868 -292.950392)
		(width 0.14478)
		(layer "In2.Cu")
		(net "M_I_CPU0_SB_DQ<11>")
	)
	(segment
		(start 414.045146 -293.166038)
		(end 414.408112 -293.316914)
		(width 0.14478)
		(layer "In2.Cu")
		(net "M_I_CPU0_SB_DQ<11>")
	)
	(segment
		(start 401.117308 -283.86786)
		(end 401.3454 -283.86786)
		(width 0.14478)
		(layer "In2.Cu")
		(net "M_I_CPU0_SB_DQ<11>")
	)
	(segment
		(start 422.525698 -292.58641)
		(end 422.809924 -292.58641)
		(width 0.14478)
		(layer "In2.Cu")
		(net "M_I_CPU0_SB_DQ<11>")
	)
	(segment
		(start 401.940776 -284.052772)
		(end 401.735798 -284.25775)
		(width 0.14478)
		(layer "In2.Cu")
		(net "M_I_CPU0_SB_DQ<11>")
	)
	(segment
		(start 414.557464 -293.255192)
		(end 414.862264 -292.950392)
		(width 0.14478)
		(layer "In2.Cu")
		(net "M_I_CPU0_SB_DQ<11>")
	)
	(segment
		(start 382.283462 -280.238708)
		(end 382.291844 -280.243534)
		(width 0.0889)
		(layer "In2.Cu")
		(net "M_I_CPU0_SB_DQ<11>")
	)
	(segment
		(start 382.857756 -280.243534)
		(end 382.866138 -280.238708)
		(width 0.0889)
		(layer "In2.Cu")
		(net "M_I_CPU0_SB_DQ<11>")
	)
	(segment
		(start 393.31392 -280.199338)
		(end 395.336522 -280.199338)
		(width 0.0889)
		(layer "In2.Cu")
		(net "M_I_CPU0_SB_DQ<11>")
	)
	(segment
		(start 426.94098 -292.62197)
		(end 427.09084 -292.77183)
		(width 0.14478)
		(layer "In2.Cu")
		(net "M_I_CPU0_SB_DQ<11>")
	)
	(segment
		(start 387.557772 -280.243534)
		(end 387.566154 -280.238708)
		(width 0.0889)
		(layer "In2.Cu")
		(net "M_I_CPU0_SB_DQ<11>")
	)
	(segment
		(start 425.822618 -292.66515)
		(end 425.972478 -292.81501)
		(width 0.14478)
		(layer "In2.Cu")
		(net "M_I_CPU0_SB_DQ<11>")
	)
	(segment
		(start 379.097794 -280.243534)
		(end 379.106176 -280.238708)
		(width 0.0889)
		(layer "In2.Cu")
		(net "M_I_CPU0_SB_DQ<11>")
	)
	(segment
		(start 421.605202 -293.628826)
		(end 421.860726 -293.457884)
		(width 0.14478)
		(layer "In2.Cu")
		(net "M_I_CPU0_SB_DQ<11>")
	)
	(segment
		(start 425.27347 -292.950392)
		(end 425.558712 -292.66515)
		(width 0.14478)
		(layer "In2.Cu")
		(net "M_I_CPU0_SB_DQ<11>")
	)
	(segment
		(start 426.531278 -292.77183)
		(end 426.681138 -292.62197)
		(width 0.14478)
		(layer "In2.Cu")
		(net "M_I_CPU0_SB_DQ<11>")
	)
	(segment
		(start 418.44214 -292.942772)
		(end 418.553392 -293.210742)
		(width 0.14478)
		(layer "In2.Cu")
		(net "M_I_CPU0_SB_DQ<11>")
	)
	(segment
		(start 421.930068 -293.108634)
		(end 422.152064 -292.960044)
		(width 0.14478)
		(layer "In2.Cu")
		(net "M_I_CPU0_SB_DQ<11>")
	)
	(segment
		(start 380.037848 -280.243534)
		(end 380.04623 -280.238708)
		(width 0.0889)
		(layer "In2.Cu")
		(net "M_I_CPU0_SB_DQ<11>")
	)
	(segment
		(start 421.860726 -293.457884)
		(end 421.930068 -293.108634)
		(width 0.14478)
		(layer "In2.Cu")
		(net "M_I_CPU0_SB_DQ<11>")
	)
	(segment
		(start 377.583446 -280.238708)
		(end 377.591828 -280.243534)
		(width 0.0889)
		(layer "In2.Cu")
		(net "M_I_CPU0_SB_DQ<11>")
	)
	(segment
		(start 397.602964 -280.35377)
		(end 401.117308 -283.86786)
		(width 0.14478)
		(layer "In2.Cu")
		(net "M_I_CPU0_SB_DQ<11>")
	)
	(segment
		(start 402.55952 -284.442916)
		(end 411.395418 -293.277798)
		(width 0.14478)
		(layer "In2.Cu")
		(net "M_I_CPU0_SB_DQ<11>")
	)
	(segment
		(start 391.317734 -280.243534)
		(end 391.326116 -280.238708)
		(width 0.0889)
		(layer "In2.Cu")
		(net "M_I_CPU0_SB_DQ<11>")
	)
	(segment
		(start 426.531278 -293.262304)
		(end 426.531278 -292.77183)
		(width 0.14478)
		(layer "In2.Cu")
		(net "M_I_CPU0_SB_DQ<11>")
	)
	(segment
		(start 390.74344 -280.238708)
		(end 390.751822 -280.243534)
		(width 0.0889)
		(layer "In2.Cu")
		(net "M_I_CPU0_SB_DQ<11>")
	)
	(segment
		(start 411.395418 -293.277798)
		(end 411.395418 -293.645336)
		(width 0.14478)
		(layer "In2.Cu")
		(net "M_I_CPU0_SB_DQ<11>")
	)
	(segment
		(start 401.779232 -283.662628)
		(end 401.940776 -283.824172)
		(width 0.14478)
		(layer "In2.Cu")
		(net "M_I_CPU0_SB_DQ<11>")
	)
	(segment
		(start 402.33092 -284.442916)
		(end 402.55952 -284.442916)
		(width 0.14478)
		(layer "In2.Cu")
		(net "M_I_CPU0_SB_DQ<11>")
	)
	(segment
		(start 413.63519 -293.636954)
		(end 413.785304 -293.273734)
		(width 0.14478)
		(layer "In2.Cu")
		(net "M_I_CPU0_SB_DQ<11>")
	)
	(segment
		(start 413.241236 -293.800276)
		(end 413.63519 -293.636954)
		(width 0.14478)
		(layer "In2.Cu")
		(net "M_I_CPU0_SB_DQ<11>")
	)
	(segment
		(start 395.836902 -280.35377)
		(end 397.602964 -280.35377)
		(width 0.14478)
		(layer "In2.Cu")
		(net "M_I_CPU0_SB_DQ<11>")
	)
	(segment
		(start 420.894764 -293.800276)
		(end 421.255952 -293.558976)
		(width 0.14478)
		(layer "In2.Cu")
		(net "M_I_CPU0_SB_DQ<11>")
	)
	(segment
		(start 392.628374 -280.243534)
		(end 392.657838 -280.260806)
		(width 0.0889)
		(layer "In2.Cu")
		(net "M_I_CPU0_SB_DQ<11>")
	)
	(segment
		(start 378.5235 -280.238708)
		(end 378.531882 -280.243534)
		(width 0.0889)
		(layer "In2.Cu")
		(net "M_I_CPU0_SB_DQ<11>")
	)
	(segment
		(start 427.09084 -292.77183)
		(end 427.09084 -293.019734)
		(width 0.14478)
		(layer "In2.Cu")
		(net "M_I_CPU0_SB_DQ<11>")
	)
	(segment
		(start 425.558712 -292.66515)
		(end 425.822618 -292.66515)
		(width 0.14478)
		(layer "In2.Cu")
		(net "M_I_CPU0_SB_DQ<11>")
	)
	(segment
		(start 425.972478 -293.262304)
		(end 426.122338 -293.412164)
		(width 0.14478)
		(layer "In2.Cu")
		(net "M_I_CPU0_SB_DQ<11>")
	)
	(segment
		(start 414.408112 -293.316914)
		(end 414.557464 -293.255192)
		(width 0.14478)
		(layer "In2.Cu")
		(net "M_I_CPU0_SB_DQ<11>")
	)
	(segment
		(start 383.79781 -280.243534)
		(end 383.806192 -280.238708)
		(width 0.0889)
		(layer "In2.Cu")
		(net "M_I_CPU0_SB_DQ<11>")
	)
	(segment
		(start 401.735798 -284.25775)
		(end 401.735798 -284.48635)
		(width 0.14478)
		(layer "In2.Cu")
		(net "M_I_CPU0_SB_DQ<11>")
	)
	(segment
		(start 425.972478 -292.81501)
		(end 425.972478 -293.262304)
		(width 0.14478)
		(layer "In2.Cu")
		(net "M_I_CPU0_SB_DQ<11>")
	)
	(segment
		(start 401.735798 -284.48635)
		(end 401.897342 -284.647894)
		(width 0.14478)
		(layer "In2.Cu")
		(net "M_I_CPU0_SB_DQ<11>")
	)
	(segment
		(start 411.550358 -293.800276)
		(end 413.241236 -293.800276)
		(width 0.14478)
		(layer "In2.Cu")
		(net "M_I_CPU0_SB_DQ<11>")
	)
	(segment
		(start 376.46483 -280.566114)
		(end 376.310906 -280.300684)
		(width 0.0889)
		(layer "In2.Cu")
		(net "M_I_CPU0_SB_DQ<11>")
	)
	(segment
		(start 376.310906 -280.300684)
		(end 376.333258 -280.217372)
		(width 0.0889)
		(layer "In2.Cu")
		(net "M_I_CPU0_SB_DQ<11>")
	)
	(segment
		(start 426.122338 -293.412164)
		(end 426.381418 -293.412164)
		(width 0.14478)
		(layer "In2.Cu")
		(net "M_I_CPU0_SB_DQ<11>")
	)
	(segment
		(start 395.490954 -280.35377)
		(end 395.836902 -280.35377)
		(width 0.0889)
		(layer "In2.Cu")
		(net "M_I_CPU0_SB_DQ<11>")
	)
	(arc
		(start 378.15774 -280.243534)
		(mid 378.339991 -280.193184)
		(end 378.5235 -280.238708)
		(width 0.0889)
		(layer "In2.Cu")
		(net "M_I_CPU0_SB_DQ<11>")
	)
	(arc
		(start 377.217686 -280.243534)
		(mid 377.399937 -280.193184)
		(end 377.583446 -280.238708)
		(width 0.0889)
		(layer "In2.Cu")
		(net "M_I_CPU0_SB_DQ<11>")
	)
	(arc
		(start 379.471936 -280.243534)
		(mid 379.754892 -280.319711)
		(end 380.037848 -280.243534)
		(width 0.0889)
		(layer "In2.Cu")
		(net "M_I_CPU0_SB_DQ<11>")
	)
	(arc
		(start 384.737864 -280.243534)
		(mid 384.924808 -280.193279)
		(end 385.111752 -280.243534)
		(width 0.0889)
		(layer "In2.Cu")
		(net "M_I_CPU0_SB_DQ<11>")
	)
	(arc
		(start 383.231898 -280.243534)
		(mid 383.514854 -280.319711)
		(end 383.79781 -280.243534)
		(width 0.0889)
		(layer "In2.Cu")
		(net "M_I_CPU0_SB_DQ<11>")
	)
	(arc
		(start 377.591828 -280.243534)
		(mid 377.874784 -280.319711)
		(end 378.15774 -280.243534)
		(width 0.0889)
		(layer "In2.Cu")
		(net "M_I_CPU0_SB_DQ<11>")
	)
	(arc
		(start 387.566154 -280.238708)
		(mid 387.749662 -280.193214)
		(end 387.931914 -280.243534)
		(width 0.0889)
		(layer "In2.Cu")
		(net "M_I_CPU0_SB_DQ<11>")
	)
	(arc
		(start 388.871968 -280.243534)
		(mid 389.154924 -280.319711)
		(end 389.43788 -280.243534)
		(width 0.0889)
		(layer "In2.Cu")
		(net "M_I_CPU0_SB_DQ<11>")
	)
	(arc
		(start 378.531882 -280.243534)
		(mid 378.814838 -280.319711)
		(end 379.097794 -280.243534)
		(width 0.0889)
		(layer "In2.Cu")
		(net "M_I_CPU0_SB_DQ<11>")
	)
	(arc
		(start 381.35179 -280.243534)
		(mid 381.634746 -280.319711)
		(end 381.917702 -280.243534)
		(width 0.0889)
		(layer "In2.Cu")
		(net "M_I_CPU0_SB_DQ<11>")
	)
	(arc
		(start 387.931914 -280.243534)
		(mid 388.21487 -280.319711)
		(end 388.497826 -280.243534)
		(width 0.0889)
		(layer "In2.Cu")
		(net "M_I_CPU0_SB_DQ<11>")
	)
	(arc
		(start 386.617718 -280.243534)
		(mid 386.799969 -280.193184)
		(end 386.983478 -280.238708)
		(width 0.0889)
		(layer "In2.Cu")
		(net "M_I_CPU0_SB_DQ<11>")
	)
	(arc
		(start 385.677664 -280.243534)
		(mid 385.859915 -280.193184)
		(end 386.043424 -280.238708)
		(width 0.0889)
		(layer "In2.Cu")
		(net "M_I_CPU0_SB_DQ<11>")
	)
	(arc
		(start 379.106176 -280.238708)
		(mid 379.289684 -280.193214)
		(end 379.471936 -280.243534)
		(width 0.0889)
		(layer "In2.Cu")
		(net "M_I_CPU0_SB_DQ<11>")
	)
	(arc
		(start 390.751822 -280.243534)
		(mid 391.034778 -280.319711)
		(end 391.317734 -280.243534)
		(width 0.0889)
		(layer "In2.Cu")
		(net "M_I_CPU0_SB_DQ<11>")
	)
	(arc
		(start 381.917702 -280.243534)
		(mid 382.099953 -280.193184)
		(end 382.283462 -280.238708)
		(width 0.0889)
		(layer "In2.Cu")
		(net "M_I_CPU0_SB_DQ<11>")
	)
	(arc
		(start 392.657838 -280.260806)
		(mid 392.929258 -280.320483)
		(end 393.196318 -280.243534)
		(width 0.0889)
		(layer "In2.Cu")
		(net "M_I_CPU0_SB_DQ<11>")
	)
	(arc
		(start 385.111752 -280.243534)
		(mid 385.394708 -280.319711)
		(end 385.677664 -280.243534)
		(width 0.0889)
		(layer "In2.Cu")
		(net "M_I_CPU0_SB_DQ<11>")
	)
	(arc
		(start 384.171952 -280.243534)
		(mid 384.454908 -280.319711)
		(end 384.737864 -280.243534)
		(width 0.0889)
		(layer "In2.Cu")
		(net "M_I_CPU0_SB_DQ<11>")
	)
	(arc
		(start 382.291844 -280.243534)
		(mid 382.5748 -280.319711)
		(end 382.857756 -280.243534)
		(width 0.0889)
		(layer "In2.Cu")
		(net "M_I_CPU0_SB_DQ<11>")
	)
	(arc
		(start 390.37768 -280.243534)
		(mid 390.559931 -280.193184)
		(end 390.74344 -280.238708)
		(width 0.0889)
		(layer "In2.Cu")
		(net "M_I_CPU0_SB_DQ<11>")
	)
	(arc
		(start 392.2776 -280.231342)
		(mid 392.454528 -280.193514)
		(end 392.628374 -280.243534)
		(width 0.0889)
		(layer "In2.Cu")
		(net "M_I_CPU0_SB_DQ<11>")
	)
	(arc
		(start 380.04623 -280.238708)
		(mid 380.229738 -280.193214)
		(end 380.41199 -280.243534)
		(width 0.0889)
		(layer "In2.Cu")
		(net "M_I_CPU0_SB_DQ<11>")
	)
	(arc
		(start 386.051806 -280.243534)
		(mid 386.334762 -280.319711)
		(end 386.617718 -280.243534)
		(width 0.0889)
		(layer "In2.Cu")
		(net "M_I_CPU0_SB_DQ<11>")
	)
	(arc
		(start 383.806192 -280.238708)
		(mid 383.9897 -280.193214)
		(end 384.171952 -280.243534)
		(width 0.0889)
		(layer "In2.Cu")
		(net "M_I_CPU0_SB_DQ<11>")
	)
	(arc
		(start 386.99186 -280.243534)
		(mid 387.274816 -280.319711)
		(end 387.557772 -280.243534)
		(width 0.0889)
		(layer "In2.Cu")
		(net "M_I_CPU0_SB_DQ<11>")
	)
	(arc
		(start 391.326116 -280.238708)
		(mid 391.509624 -280.193214)
		(end 391.691876 -280.243534)
		(width 0.0889)
		(layer "In2.Cu")
		(net "M_I_CPU0_SB_DQ<11>")
	)
	(arc
		(start 382.866138 -280.238708)
		(mid 383.049646 -280.193214)
		(end 383.231898 -280.243534)
		(width 0.0889)
		(layer "In2.Cu")
		(net "M_I_CPU0_SB_DQ<11>")
	)
	(arc
		(start 393.196318 -280.243534)
		(mid 393.253242 -280.216437)
		(end 393.31392 -280.199338)
		(width 0.0889)
		(layer "In2.Cu")
		(net "M_I_CPU0_SB_DQ<11>")
	)
	(arc
		(start 380.41199 -280.243534)
		(mid 380.694946 -280.319711)
		(end 380.977902 -280.243534)
		(width 0.0889)
		(layer "In2.Cu")
		(net "M_I_CPU0_SB_DQ<11>")
	)
	(arc
		(start 389.811768 -280.243534)
		(mid 390.094724 -280.319711)
		(end 390.37768 -280.243534)
		(width 0.0889)
		(layer "In2.Cu")
		(net "M_I_CPU0_SB_DQ<11>")
	)
	(arc
		(start 391.691876 -280.243534)
		(mid 391.958806 -280.319483)
		(end 392.229594 -280.258774)
		(width 0.0889)
		(layer "In2.Cu")
		(net "M_I_CPU0_SB_DQ<11>")
	)
	(arc
		(start 388.506208 -280.238708)
		(mid 388.689716 -280.193214)
		(end 388.871968 -280.243534)
		(width 0.0889)
		(layer "In2.Cu")
		(net "M_I_CPU0_SB_DQ<11>")
	)
	(arc
		(start 376.333258 -280.217372)
		(mid 376.495447 -280.194637)
		(end 376.651774 -280.243534)
		(width 0.0889)
		(layer "In2.Cu")
		(net "M_I_CPU0_SB_DQ<11>")
	)
	(arc
		(start 380.977902 -280.243534)
		(mid 381.164846 -280.193279)
		(end 381.35179 -280.243534)
		(width 0.0889)
		(layer "In2.Cu")
		(net "M_I_CPU0_SB_DQ<11>")
	)
	(arc
		(start 376.651774 -280.243534)
		(mid 376.93473 -280.319711)
		(end 377.217686 -280.243534)
		(width 0.0889)
		(layer "In2.Cu")
		(net "M_I_CPU0_SB_DQ<11>")
	)
	(arc
		(start 389.43788 -280.243534)
		(mid 389.624824 -280.193279)
		(end 389.811768 -280.243534)
		(width 0.0889)
		(layer "In2.Cu")
		(net "M_I_CPU0_SB_DQ<11>")
	)
	(segment
		(start 377.407932 -279.49017)
		(end 377.874784 -279.756108)
		(width 0.10668)
		(layer "F.Cu")
		(net "M_I_CPU0_SB_DQ<10>")
	)
	(segment
		(start 414.241996 -291.35832)
		(end 414.539938 -291.234876)
		(width 0.14478)
		(layer "In2.Cu")
		(net "M_I_CPU0_SB_DQ<10>")
	)
	(segment
		(start 400.432524 -281.0256)
		(end 400.432524 -281.253692)
		(width 0.14478)
		(layer "In2.Cu")
		(net "M_I_CPU0_SB_DQ<10>")
	)
	(segment
		(start 421.672258 -291.23513)
		(end 422.193466 -291.451538)
		(width 0.14478)
		(layer "In2.Cu")
		(net "M_I_CPU0_SB_DQ<10>")
	)
	(segment
		(start 417.20516 -291.260022)
		(end 417.49472 -291.380164)
		(width 0.14478)
		(layer "In2.Cu")
		(net "M_I_CPU0_SB_DQ<10>")
	)
	(segment
		(start 395.934438 -279.14219)
		(end 398.549114 -279.14219)
		(width 0.14478)
		(layer "In2.Cu")
		(net "M_I_CPU0_SB_DQ<10>")
	)
	(segment
		(start 401.831048 -282.424124)
		(end 411.517084 -292.11016)
		(width 0.14478)
		(layer "In2.Cu")
		(net "M_I_CPU0_SB_DQ<10>")
	)
	(segment
		(start 399.262092 -280.08326)
		(end 399.490184 -280.08326)
		(width 0.14478)
		(layer "In2.Cu")
		(net "M_I_CPU0_SB_DQ<10>")
	)
	(segment
		(start 400.432524 -281.253692)
		(end 400.217894 -281.468068)
		(width 0.14478)
		(layer "In2.Cu")
		(net "M_I_CPU0_SB_DQ<10>")
	)
	(segment
		(start 426.189902 -291.61105)
		(end 426.54093 -291.260022)
		(width 0.14478)
		(layer "In2.Cu")
		(net "M_I_CPU0_SB_DQ<10>")
	)
	(segment
		(start 400.998182 -282.476448)
		(end 401.160234 -282.6385)
		(width 0.14478)
		(layer "In2.Cu")
		(net "M_I_CPU0_SB_DQ<10>")
	)
	(segment
		(start 392.153394 -279.428702)
		(end 392.161776 -279.433528)
		(width 0.0889)
		(layer "In2.Cu")
		(net "M_I_CPU0_SB_DQ<10>")
	)
	(segment
		(start 426.54093 -291.260022)
		(end 427.03115 -291.260022)
		(width 0.14478)
		(layer "In2.Cu")
		(net "M_I_CPU0_SB_DQ<10>")
	)
	(segment
		(start 422.655238 -291.260022)
		(end 424.216322 -291.260022)
		(width 0.14478)
		(layer "In2.Cu")
		(net "M_I_CPU0_SB_DQ<10>")
	)
	(segment
		(start 398.657318 -280.135584)
		(end 398.81937 -280.297636)
		(width 0.14478)
		(layer "In2.Cu")
		(net "M_I_CPU0_SB_DQ<10>")
	)
	(segment
		(start 413.582104 -291.97808)
		(end 413.958024 -292.134036)
		(width 0.14478)
		(layer "In2.Cu")
		(net "M_I_CPU0_SB_DQ<10>")
	)
	(segment
		(start 415.580068 -291.61867)
		(end 415.87928 -291.61867)
		(width 0.14478)
		(layer "In2.Cu")
		(net "M_I_CPU0_SB_DQ<10>")
	)
	(segment
		(start 398.81937 -280.297636)
		(end 399.047462 -280.297636)
		(width 0.14478)
		(layer "In2.Cu")
		(net "M_I_CPU0_SB_DQ<10>")
	)
	(segment
		(start 400.270472 -280.863548)
		(end 400.432524 -281.0256)
		(width 0.14478)
		(layer "In2.Cu")
		(net "M_I_CPU0_SB_DQ<10>")
	)
	(segment
		(start 417.77031 -291.106352)
		(end 417.96589 -291.025072)
		(width 0.14478)
		(layer "In2.Cu")
		(net "M_I_CPU0_SB_DQ<10>")
	)
	(segment
		(start 377.874784 -279.756108)
		(end 377.72086 -279.490678)
		(width 0.0889)
		(layer "In2.Cu")
		(net "M_I_CPU0_SB_DQ<10>")
	)
	(segment
		(start 398.871948 -279.465024)
		(end 398.871948 -279.693116)
		(width 0.14478)
		(layer "In2.Cu")
		(net "M_I_CPU0_SB_DQ<10>")
	)
	(segment
		(start 392.161776 -279.433528)
		(end 392.176508 -279.442164)
		(width 0.0889)
		(layer "In2.Cu")
		(net "M_I_CPU0_SB_DQ<10>")
	)
	(segment
		(start 414.177988 -291.512752)
		(end 414.241996 -291.35832)
		(width 0.14478)
		(layer "In2.Cu")
		(net "M_I_CPU0_SB_DQ<10>")
	)
	(segment
		(start 413.26308 -292.11016)
		(end 413.582104 -291.97808)
		(width 0.14478)
		(layer "In2.Cu")
		(net "M_I_CPU0_SB_DQ<10>")
	)
	(segment
		(start 414.848802 -291.363146)
		(end 415.09823 -291.260022)
		(width 0.14478)
		(layer "In2.Cu")
		(net "M_I_CPU0_SB_DQ<10>")
	)
	(segment
		(start 424.216322 -291.260022)
		(end 424.56735 -291.61105)
		(width 0.14478)
		(layer "In2.Cu")
		(net "M_I_CPU0_SB_DQ<10>")
	)
	(segment
		(start 377.72086 -279.490678)
		(end 377.743212 -279.407366)
		(width 0.0889)
		(layer "In2.Cu")
		(net "M_I_CPU0_SB_DQ<10>")
	)
	(segment
		(start 401.602956 -282.424124)
		(end 401.831048 -282.424124)
		(width 0.14478)
		(layer "In2.Cu")
		(net "M_I_CPU0_SB_DQ<10>")
	)
	(segment
		(start 399.437606 -280.68778)
		(end 399.437606 -280.915872)
		(width 0.14478)
		(layer "In2.Cu")
		(net "M_I_CPU0_SB_DQ<10>")
	)
	(segment
		(start 419.07841 -292.11016)
		(end 420.749984 -292.11016)
		(width 0.14478)
		(layer "In2.Cu")
		(net "M_I_CPU0_SB_DQ<10>")
	)
	(segment
		(start 393.820142 -279.509982)
		(end 394.416534 -278.91359)
		(width 0.0889)
		(layer "In2.Cu")
		(net "M_I_CPU0_SB_DQ<10>")
	)
	(segment
		(start 417.49472 -291.380164)
		(end 417.6903 -291.298884)
		(width 0.14478)
		(layer "In2.Cu")
		(net "M_I_CPU0_SB_DQ<10>")
	)
	(segment
		(start 418.206682 -291.513006)
		(end 418.3253 -291.798248)
		(width 0.14478)
		(layer "In2.Cu")
		(net "M_I_CPU0_SB_DQ<10>")
	)
	(segment
		(start 425.22521 -291.260022)
		(end 425.532042 -291.260022)
		(width 0.14478)
		(layer "In2.Cu")
		(net "M_I_CPU0_SB_DQ<10>")
	)
	(segment
		(start 401.05076 -281.643836)
		(end 401.212812 -281.805888)
		(width 0.14478)
		(layer "In2.Cu")
		(net "M_I_CPU0_SB_DQ<10>")
	)
	(segment
		(start 417.96589 -291.025072)
		(end 418.205412 -291.124386)
		(width 0.14478)
		(layer "In2.Cu")
		(net "M_I_CPU0_SB_DQ<10>")
	)
	(segment
		(start 421.184832 -291.92982)
		(end 421.432482 -291.334698)
		(width 0.14478)
		(layer "In2.Cu")
		(net "M_I_CPU0_SB_DQ<10>")
	)
	(segment
		(start 393.102338 -279.433782)
		(end 393.118086 -279.442926)
		(width 0.0889)
		(layer "In2.Cu")
		(net "M_I_CPU0_SB_DQ<10>")
	)
	(segment
		(start 420.749984 -292.11016)
		(end 421.184832 -291.92982)
		(width 0.14478)
		(layer "In2.Cu")
		(net "M_I_CPU0_SB_DQ<10>")
	)
	(segment
		(start 418.205412 -291.124386)
		(end 418.286692 -291.32022)
		(width 0.14478)
		(layer "In2.Cu")
		(net "M_I_CPU0_SB_DQ<10>")
	)
	(segment
		(start 393.376658 -279.509982)
		(end 393.820142 -279.509982)
		(width 0.0889)
		(layer "In2.Cu")
		(net "M_I_CPU0_SB_DQ<10>")
	)
	(segment
		(start 399.652236 -280.245312)
		(end 399.652236 -280.473404)
		(width 0.14478)
		(layer "In2.Cu")
		(net "M_I_CPU0_SB_DQ<10>")
	)
	(segment
		(start 400.998182 -282.248356)
		(end 400.998182 -282.476448)
		(width 0.14478)
		(layer "In2.Cu")
		(net "M_I_CPU0_SB_DQ<10>")
	)
	(segment
		(start 424.874182 -291.61105)
		(end 425.22521 -291.260022)
		(width 0.14478)
		(layer "In2.Cu")
		(net "M_I_CPU0_SB_DQ<10>")
	)
	(segment
		(start 399.490184 -280.08326)
		(end 399.652236 -280.245312)
		(width 0.14478)
		(layer "In2.Cu")
		(net "M_I_CPU0_SB_DQ<10>")
	)
	(segment
		(start 415.22142 -291.260022)
		(end 415.580068 -291.61867)
		(width 0.14478)
		(layer "In2.Cu")
		(net "M_I_CPU0_SB_DQ<10>")
	)
	(segment
		(start 389.333486 -279.428702)
		(end 389.341868 -279.433528)
		(width 0.0889)
		(layer "In2.Cu")
		(net "M_I_CPU0_SB_DQ<10>")
	)
	(segment
		(start 398.657318 -279.907492)
		(end 398.657318 -280.135584)
		(width 0.14478)
		(layer "In2.Cu")
		(net "M_I_CPU0_SB_DQ<10>")
	)
	(segment
		(start 415.87928 -291.61867)
		(end 416.237928 -291.260022)
		(width 0.14478)
		(layer "In2.Cu")
		(net "M_I_CPU0_SB_DQ<10>")
	)
	(segment
		(start 395.343634 -278.91359)
		(end 395.572234 -279.14219)
		(width 0.0889)
		(layer "In2.Cu")
		(net "M_I_CPU0_SB_DQ<10>")
	)
	(segment
		(start 379.933454 -279.428702)
		(end 379.941836 -279.433528)
		(width 0.0889)
		(layer "In2.Cu")
		(net "M_I_CPU0_SB_DQ<10>")
	)
	(segment
		(start 388.393432 -279.428702)
		(end 388.401814 -279.433528)
		(width 0.0889)
		(layer "In2.Cu")
		(net "M_I_CPU0_SB_DQ<10>")
	)
	(segment
		(start 421.432482 -291.334698)
		(end 421.672258 -291.23513)
		(width 0.14478)
		(layer "In2.Cu")
		(net "M_I_CPU0_SB_DQ<10>")
	)
	(segment
		(start 413.958024 -292.134036)
		(end 414.255712 -292.010846)
		(width 0.14478)
		(layer "In2.Cu")
		(net "M_I_CPU0_SB_DQ<10>")
	)
	(segment
		(start 400.04238 -280.863548)
		(end 400.270472 -280.863548)
		(width 0.14478)
		(layer "In2.Cu")
		(net "M_I_CPU0_SB_DQ<10>")
	)
	(segment
		(start 381.447802 -279.433528)
		(end 381.456184 -279.428702)
		(width 0.0889)
		(layer "In2.Cu")
		(net "M_I_CPU0_SB_DQ<10>")
	)
	(segment
		(start 425.532042 -291.260022)
		(end 425.88307 -291.61105)
		(width 0.14478)
		(layer "In2.Cu")
		(net "M_I_CPU0_SB_DQ<10>")
	)
	(segment
		(start 386.147818 -279.433528)
		(end 386.1562 -279.428702)
		(width 0.0889)
		(layer "In2.Cu")
		(net "M_I_CPU0_SB_DQ<10>")
	)
	(segment
		(start 400.217894 -281.468068)
		(end 400.217894 -281.69616)
		(width 0.14478)
		(layer "In2.Cu")
		(net "M_I_CPU0_SB_DQ<10>")
	)
	(segment
		(start 401.388326 -282.6385)
		(end 401.602956 -282.424124)
		(width 0.14478)
		(layer "In2.Cu")
		(net "M_I_CPU0_SB_DQ<10>")
	)
	(segment
		(start 414.255712 -292.010846)
		(end 414.31972 -291.85616)
		(width 0.14478)
		(layer "In2.Cu")
		(net "M_I_CPU0_SB_DQ<10>")
	)
	(segment
		(start 385.207764 -279.433528)
		(end 385.216146 -279.428702)
		(width 0.0889)
		(layer "In2.Cu")
		(net "M_I_CPU0_SB_DQ<10>")
	)
	(segment
		(start 414.539938 -291.234876)
		(end 414.848802 -291.363146)
		(width 0.14478)
		(layer "In2.Cu")
		(net "M_I_CPU0_SB_DQ<10>")
	)
	(segment
		(start 417.6903 -291.298884)
		(end 417.77031 -291.106352)
		(width 0.14478)
		(layer "In2.Cu")
		(net "M_I_CPU0_SB_DQ<10>")
	)
	(segment
		(start 393.08405 -279.423368)
		(end 393.102338 -279.433782)
		(width 0.0889)
		(layer "In2.Cu")
		(net "M_I_CPU0_SB_DQ<10>")
	)
	(segment
		(start 411.517084 -292.11016)
		(end 413.26308 -292.11016)
		(width 0.14478)
		(layer "In2.Cu")
		(net "M_I_CPU0_SB_DQ<10>")
	)
	(segment
		(start 400.217894 -281.69616)
		(end 400.379946 -281.858212)
		(width 0.14478)
		(layer "In2.Cu")
		(net "M_I_CPU0_SB_DQ<10>")
	)
	(segment
		(start 389.90778 -279.433528)
		(end 389.916162 -279.428702)
		(width 0.0889)
		(layer "In2.Cu")
		(net "M_I_CPU0_SB_DQ<10>")
	)
	(segment
		(start 399.047462 -280.297636)
		(end 399.262092 -280.08326)
		(width 0.14478)
		(layer "In2.Cu")
		(net "M_I_CPU0_SB_DQ<10>")
	)
	(segment
		(start 427.03115 -291.260022)
		(end 427.456092 -291.684964)
		(width 0.14478)
		(layer "In2.Cu")
		(net "M_I_CPU0_SB_DQ<10>")
	)
	(segment
		(start 418.3253 -291.798248)
		(end 419.07841 -292.11016)
		(width 0.14478)
		(layer "In2.Cu")
		(net "M_I_CPU0_SB_DQ<10>")
	)
	(segment
		(start 424.56735 -291.61105)
		(end 424.874182 -291.61105)
		(width 0.14478)
		(layer "In2.Cu")
		(net "M_I_CPU0_SB_DQ<10>")
	)
	(segment
		(start 380.873508 -279.428702)
		(end 380.88189 -279.433528)
		(width 0.0889)
		(layer "In2.Cu")
		(net "M_I_CPU0_SB_DQ<10>")
	)
	(segment
		(start 400.608038 -281.858212)
		(end 400.822668 -281.643836)
		(width 0.14478)
		(layer "In2.Cu")
		(net "M_I_CPU0_SB_DQ<10>")
	)
	(segment
		(start 422.193466 -291.451538)
		(end 422.655238 -291.260022)
		(width 0.14478)
		(layer "In2.Cu")
		(net "M_I_CPU0_SB_DQ<10>")
	)
	(segment
		(start 398.549114 -279.14219)
		(end 398.871948 -279.465024)
		(width 0.14478)
		(layer "In2.Cu")
		(net "M_I_CPU0_SB_DQ<10>")
	)
	(segment
		(start 394.416534 -278.91359)
		(end 395.343634 -278.91359)
		(width 0.0889)
		(layer "In2.Cu")
		(net "M_I_CPU0_SB_DQ<10>")
	)
	(segment
		(start 383.693416 -279.428702)
		(end 383.701798 -279.433528)
		(width 0.0889)
		(layer "In2.Cu")
		(net "M_I_CPU0_SB_DQ<10>")
	)
	(segment
		(start 401.212812 -281.805888)
		(end 401.212812 -282.03398)
		(width 0.14478)
		(layer "In2.Cu")
		(net "M_I_CPU0_SB_DQ<10>")
	)
	(segment
		(start 414.31972 -291.85616)
		(end 414.177988 -291.512752)
		(width 0.14478)
		(layer "In2.Cu")
		(net "M_I_CPU0_SB_DQ<10>")
	)
	(segment
		(start 425.88307 -291.61105)
		(end 426.189902 -291.61105)
		(width 0.14478)
		(layer "In2.Cu")
		(net "M_I_CPU0_SB_DQ<10>")
	)
	(segment
		(start 399.437606 -280.915872)
		(end 399.599658 -281.077924)
		(width 0.14478)
		(layer "In2.Cu")
		(net "M_I_CPU0_SB_DQ<10>")
	)
	(segment
		(start 401.160234 -282.6385)
		(end 401.388326 -282.6385)
		(width 0.14478)
		(layer "In2.Cu")
		(net "M_I_CPU0_SB_DQ<10>")
	)
	(segment
		(start 400.822668 -281.643836)
		(end 401.05076 -281.643836)
		(width 0.14478)
		(layer "In2.Cu")
		(net "M_I_CPU0_SB_DQ<10>")
	)
	(segment
		(start 399.599658 -281.077924)
		(end 399.82775 -281.077924)
		(width 0.14478)
		(layer "In2.Cu")
		(net "M_I_CPU0_SB_DQ<10>")
	)
	(segment
		(start 399.652236 -280.473404)
		(end 399.437606 -280.68778)
		(width 0.14478)
		(layer "In2.Cu")
		(net "M_I_CPU0_SB_DQ<10>")
	)
	(segment
		(start 399.82775 -281.077924)
		(end 400.04238 -280.863548)
		(width 0.14478)
		(layer "In2.Cu")
		(net "M_I_CPU0_SB_DQ<10>")
	)
	(segment
		(start 415.09823 -291.260022)
		(end 415.22142 -291.260022)
		(width 0.14478)
		(layer "In2.Cu")
		(net "M_I_CPU0_SB_DQ<10>")
	)
	(segment
		(start 395.572234 -279.14219)
		(end 395.934438 -279.14219)
		(width 0.0889)
		(layer "In2.Cu")
		(net "M_I_CPU0_SB_DQ<10>")
	)
	(segment
		(start 384.63347 -279.428702)
		(end 384.641852 -279.433528)
		(width 0.0889)
		(layer "In2.Cu")
		(net "M_I_CPU0_SB_DQ<10>")
	)
	(segment
		(start 398.871948 -279.693116)
		(end 398.657318 -279.907492)
		(width 0.14478)
		(layer "In2.Cu")
		(net "M_I_CPU0_SB_DQ<10>")
	)
	(segment
		(start 401.212812 -282.03398)
		(end 400.998182 -282.248356)
		(width 0.14478)
		(layer "In2.Cu")
		(net "M_I_CPU0_SB_DQ<10>")
	)
	(segment
		(start 416.237928 -291.260022)
		(end 417.20516 -291.260022)
		(width 0.14478)
		(layer "In2.Cu")
		(net "M_I_CPU0_SB_DQ<10>")
	)
	(segment
		(start 418.286692 -291.32022)
		(end 418.206682 -291.513006)
		(width 0.14478)
		(layer "In2.Cu")
		(net "M_I_CPU0_SB_DQ<10>")
	)
	(segment
		(start 400.379946 -281.858212)
		(end 400.608038 -281.858212)
		(width 0.14478)
		(layer "In2.Cu")
		(net "M_I_CPU0_SB_DQ<10>")
	)
	(arc
		(start 390.281922 -279.433528)
		(mid 390.564878 -279.509705)
		(end 390.847834 -279.433528)
		(width 0.0889)
		(layer "In2.Cu")
		(net "M_I_CPU0_SB_DQ<10>")
	)
	(arc
		(start 381.821944 -279.433528)
		(mid 382.1049 -279.509705)
		(end 382.387856 -279.433528)
		(width 0.0889)
		(layer "In2.Cu")
		(net "M_I_CPU0_SB_DQ<10>")
	)
	(arc
		(start 383.327656 -279.433528)
		(mid 383.509907 -279.383178)
		(end 383.693416 -279.428702)
		(width 0.0889)
		(layer "In2.Cu")
		(net "M_I_CPU0_SB_DQ<10>")
	)
	(arc
		(start 388.401814 -279.433528)
		(mid 388.68477 -279.509705)
		(end 388.967726 -279.433528)
		(width 0.0889)
		(layer "In2.Cu")
		(net "M_I_CPU0_SB_DQ<10>")
	)
	(arc
		(start 379.567694 -279.433528)
		(mid 379.749945 -279.383178)
		(end 379.933454 -279.428702)
		(width 0.0889)
		(layer "In2.Cu")
		(net "M_I_CPU0_SB_DQ<10>")
	)
	(arc
		(start 385.581906 -279.433528)
		(mid 385.864862 -279.509705)
		(end 386.147818 -279.433528)
		(width 0.0889)
		(layer "In2.Cu")
		(net "M_I_CPU0_SB_DQ<10>")
	)
	(arc
		(start 378.061982 -279.433528)
		(mid 378.344938 -279.509705)
		(end 378.627894 -279.433528)
		(width 0.0889)
		(layer "In2.Cu")
		(net "M_I_CPU0_SB_DQ<10>")
	)
	(arc
		(start 379.941836 -279.433528)
		(mid 380.224792 -279.509705)
		(end 380.507748 -279.433528)
		(width 0.0889)
		(layer "In2.Cu")
		(net "M_I_CPU0_SB_DQ<10>")
	)
	(arc
		(start 384.641852 -279.433528)
		(mid 384.924808 -279.509705)
		(end 385.207764 -279.433528)
		(width 0.0889)
		(layer "In2.Cu")
		(net "M_I_CPU0_SB_DQ<10>")
	)
	(arc
		(start 379.001782 -279.433528)
		(mid 379.284738 -279.509705)
		(end 379.567694 -279.433528)
		(width 0.0889)
		(layer "In2.Cu")
		(net "M_I_CPU0_SB_DQ<10>")
	)
	(arc
		(start 380.88189 -279.433528)
		(mid 381.164846 -279.509705)
		(end 381.447802 -279.433528)
		(width 0.0889)
		(layer "In2.Cu")
		(net "M_I_CPU0_SB_DQ<10>")
	)
	(arc
		(start 385.216146 -279.428702)
		(mid 385.399654 -279.383208)
		(end 385.581906 -279.433528)
		(width 0.0889)
		(layer "In2.Cu")
		(net "M_I_CPU0_SB_DQ<10>")
	)
	(arc
		(start 386.1562 -279.428702)
		(mid 386.339708 -279.383208)
		(end 386.52196 -279.433528)
		(width 0.0889)
		(layer "In2.Cu")
		(net "M_I_CPU0_SB_DQ<10>")
	)
	(arc
		(start 388.967726 -279.433528)
		(mid 389.149977 -279.383178)
		(end 389.333486 -279.428702)
		(width 0.0889)
		(layer "In2.Cu")
		(net "M_I_CPU0_SB_DQ<10>")
	)
	(arc
		(start 377.743212 -279.407366)
		(mid 377.905544 -279.384548)
		(end 378.061982 -279.433528)
		(width 0.0889)
		(layer "In2.Cu")
		(net "M_I_CPU0_SB_DQ<10>")
	)
	(arc
		(start 389.916162 -279.428702)
		(mid 390.09967 -279.383208)
		(end 390.281922 -279.433528)
		(width 0.0889)
		(layer "In2.Cu")
		(net "M_I_CPU0_SB_DQ<10>")
	)
	(arc
		(start 378.627894 -279.433528)
		(mid 378.814838 -279.383273)
		(end 379.001782 -279.433528)
		(width 0.0889)
		(layer "In2.Cu")
		(net "M_I_CPU0_SB_DQ<10>")
	)
	(arc
		(start 387.46176 -279.433528)
		(mid 387.744716 -279.509705)
		(end 388.027672 -279.433528)
		(width 0.0889)
		(layer "In2.Cu")
		(net "M_I_CPU0_SB_DQ<10>")
	)
	(arc
		(start 384.26771 -279.433528)
		(mid 384.449961 -279.383178)
		(end 384.63347 -279.428702)
		(width 0.0889)
		(layer "In2.Cu")
		(net "M_I_CPU0_SB_DQ<10>")
	)
	(arc
		(start 381.456184 -279.428702)
		(mid 381.639692 -279.383208)
		(end 381.821944 -279.433528)
		(width 0.0889)
		(layer "In2.Cu")
		(net "M_I_CPU0_SB_DQ<10>")
	)
	(arc
		(start 390.847834 -279.433528)
		(mid 391.034778 -279.383273)
		(end 391.221722 -279.433528)
		(width 0.0889)
		(layer "In2.Cu")
		(net "M_I_CPU0_SB_DQ<10>")
	)
	(arc
		(start 386.52196 -279.433528)
		(mid 386.804916 -279.509705)
		(end 387.087872 -279.433528)
		(width 0.0889)
		(layer "In2.Cu")
		(net "M_I_CPU0_SB_DQ<10>")
	)
	(arc
		(start 382.387856 -279.433528)
		(mid 382.5748 -279.383273)
		(end 382.761744 -279.433528)
		(width 0.0889)
		(layer "In2.Cu")
		(net "M_I_CPU0_SB_DQ<10>")
	)
	(arc
		(start 391.221722 -279.433528)
		(mid 391.504678 -279.509705)
		(end 391.787634 -279.433528)
		(width 0.0889)
		(layer "In2.Cu")
		(net "M_I_CPU0_SB_DQ<10>")
	)
	(arc
		(start 383.701798 -279.433528)
		(mid 383.984754 -279.509705)
		(end 384.26771 -279.433528)
		(width 0.0889)
		(layer "In2.Cu")
		(net "M_I_CPU0_SB_DQ<10>")
	)
	(arc
		(start 392.728196 -279.433528)
		(mid 392.904824 -279.383295)
		(end 393.08405 -279.423368)
		(width 0.0889)
		(layer "In2.Cu")
		(net "M_I_CPU0_SB_DQ<10>")
	)
	(arc
		(start 393.118086 -279.442926)
		(mid 393.243348 -279.491958)
		(end 393.376658 -279.509982)
		(width 0.0889)
		(layer "In2.Cu")
		(net "M_I_CPU0_SB_DQ<10>")
	)
	(arc
		(start 391.787634 -279.433528)
		(mid 391.969885 -279.383178)
		(end 392.153394 -279.428702)
		(width 0.0889)
		(layer "In2.Cu")
		(net "M_I_CPU0_SB_DQ<10>")
	)
	(arc
		(start 380.507748 -279.433528)
		(mid 380.689999 -279.383178)
		(end 380.873508 -279.428702)
		(width 0.0889)
		(layer "In2.Cu")
		(net "M_I_CPU0_SB_DQ<10>")
	)
	(arc
		(start 382.761744 -279.433528)
		(mid 383.0447 -279.509705)
		(end 383.327656 -279.433528)
		(width 0.0889)
		(layer "In2.Cu")
		(net "M_I_CPU0_SB_DQ<10>")
	)
	(arc
		(start 387.087872 -279.433528)
		(mid 387.274816 -279.383273)
		(end 387.46176 -279.433528)
		(width 0.0889)
		(layer "In2.Cu")
		(net "M_I_CPU0_SB_DQ<10>")
	)
	(arc
		(start 389.341868 -279.433528)
		(mid 389.624824 -279.509705)
		(end 389.90778 -279.433528)
		(width 0.0889)
		(layer "In2.Cu")
		(net "M_I_CPU0_SB_DQ<10>")
	)
	(arc
		(start 388.027672 -279.433528)
		(mid 388.209923 -279.383178)
		(end 388.393432 -279.428702)
		(width 0.0889)
		(layer "In2.Cu")
		(net "M_I_CPU0_SB_DQ<10>")
	)
	(arc
		(start 392.176508 -279.442164)
		(mid 392.453491 -279.509968)
		(end 392.728196 -279.433528)
		(width 0.0889)
		(layer "In2.Cu")
		(net "M_I_CPU0_SB_DQ<10>")
	)
	(segment
		(start 376.938032 -273.820128)
		(end 377.404884 -274.086066)
		(width 0.10668)
		(layer "F.Cu")
		(net "M_I_CPU0_SB_DQ<0>")
	)
	(segment
		(start 413.787336 -282.033726)
		(end 413.868616 -281.837892)
		(width 0.14478)
		(layer "In2.Cu")
		(net "M_I_CPU0_SB_DQ<0>")
	)
	(segment
		(start 413.868616 -281.837892)
		(end 413.776922 -281.616658)
		(width 0.14478)
		(layer "In2.Cu")
		(net "M_I_CPU0_SB_DQ<0>")
	)
	(segment
		(start 421.64762 -280.817066)
		(end 421.80764 -280.657046)
		(width 0.14478)
		(layer "In2.Cu")
		(net "M_I_CPU0_SB_DQ<0>")
	)
	(segment
		(start 411.160214 -281.910028)
		(end 412.677356 -281.910028)
		(width 0.14478)
		(layer "In2.Cu")
		(net "M_I_CPU0_SB_DQ<0>")
	)
	(segment
		(start 420.183818 -281.910028)
		(end 421.356282 -281.42438)
		(width 0.14478)
		(layer "In2.Cu")
		(net "M_I_CPU0_SB_DQ<0>")
	)
	(segment
		(start 419.301422 -281.910028)
		(end 420.183818 -281.910028)
		(width 0.14478)
		(layer "In2.Cu")
		(net "M_I_CPU0_SB_DQ<0>")
	)
	(segment
		(start 380.037848 -274.408646)
		(end 380.04623 -274.413472)
		(width 0.0889)
		(layer "In2.Cu")
		(net "M_I_CPU0_SB_DQ<0>")
	)
	(segment
		(start 421.64762 -281.133042)
		(end 421.64762 -280.817066)
		(width 0.14478)
		(layer "In2.Cu")
		(net "M_I_CPU0_SB_DQ<0>")
	)
	(segment
		(start 395.992096 -272.93951)
		(end 401.3454 -272.93951)
		(width 0.14478)
		(layer "In2.Cu")
		(net "M_I_CPU0_SB_DQ<0>")
	)
	(segment
		(start 421.356282 -281.42438)
		(end 421.64762 -281.133042)
		(width 0.14478)
		(layer "In2.Cu")
		(net "M_I_CPU0_SB_DQ<0>")
	)
	(segment
		(start 423.7609 -281.060144)
		(end 431.131218 -281.060144)
		(width 0.14478)
		(layer "In2.Cu")
		(net "M_I_CPU0_SB_DQ<0>")
	)
	(segment
		(start 377.558808 -274.351496)
		(end 377.65482 -274.376896)
		(width 0.0889)
		(layer "In2.Cu")
		(net "M_I_CPU0_SB_DQ<0>")
	)
	(segment
		(start 413.26054 -281.830526)
		(end 413.352234 -282.05176)
		(width 0.14478)
		(layer "In2.Cu")
		(net "M_I_CPU0_SB_DQ<0>")
	)
	(segment
		(start 383.79781 -274.408646)
		(end 383.806192 -274.413472)
		(width 0.0889)
		(layer "In2.Cu")
		(net "M_I_CPU0_SB_DQ<0>")
	)
	(segment
		(start 422.787064 -280.657046)
		(end 423.7609 -281.060144)
		(width 0.14478)
		(layer "In2.Cu")
		(net "M_I_CPU0_SB_DQ<0>")
	)
	(segment
		(start 413.776922 -281.616658)
		(end 413.858202 -281.421078)
		(width 0.14478)
		(layer "In2.Cu")
		(net "M_I_CPU0_SB_DQ<0>")
	)
	(segment
		(start 395.559534 -272.93951)
		(end 395.992096 -272.93951)
		(width 0.0889)
		(layer "In2.Cu")
		(net "M_I_CPU0_SB_DQ<0>")
	)
	(segment
		(start 390.74344 -274.413472)
		(end 390.751822 -274.408646)
		(width 0.0889)
		(layer "In2.Cu")
		(net "M_I_CPU0_SB_DQ<0>")
	)
	(segment
		(start 413.547814 -282.13304)
		(end 413.787336 -282.033726)
		(width 0.14478)
		(layer "In2.Cu")
		(net "M_I_CPU0_SB_DQ<0>")
	)
	(segment
		(start 406.53589 -278.13)
		(end 407.380186 -278.13)
		(width 0.14478)
		(layer "In2.Cu")
		(net "M_I_CPU0_SB_DQ<0>")
	)
	(segment
		(start 431.131218 -281.060144)
		(end 431.55616 -281.485086)
		(width 0.14478)
		(layer "In2.Cu")
		(net "M_I_CPU0_SB_DQ<0>")
	)
	(segment
		(start 414.729168 -281.060144)
		(end 417.65855 -281.060144)
		(width 0.14478)
		(layer "In2.Cu")
		(net "M_I_CPU0_SB_DQ<0>")
	)
	(segment
		(start 407.380186 -278.13)
		(end 411.160214 -281.910028)
		(width 0.14478)
		(layer "In2.Cu")
		(net "M_I_CPU0_SB_DQ<0>")
	)
	(segment
		(start 378.5235 -274.413472)
		(end 378.531882 -274.408646)
		(width 0.0889)
		(layer "In2.Cu")
		(net "M_I_CPU0_SB_DQ<0>")
	)
	(segment
		(start 401.3454 -272.93951)
		(end 406.53589 -278.13)
		(width 0.14478)
		(layer "In2.Cu")
		(net "M_I_CPU0_SB_DQ<0>")
	)
	(segment
		(start 387.557772 -274.408646)
		(end 387.566154 -274.413472)
		(width 0.0889)
		(layer "In2.Cu")
		(net "M_I_CPU0_SB_DQ<0>")
	)
	(segment
		(start 382.283462 -274.413472)
		(end 382.291844 -274.408646)
		(width 0.0889)
		(layer "In2.Cu")
		(net "M_I_CPU0_SB_DQ<0>")
	)
	(segment
		(start 386.043424 -274.413472)
		(end 386.051806 -274.408646)
		(width 0.0889)
		(layer "In2.Cu")
		(net "M_I_CPU0_SB_DQ<0>")
	)
	(segment
		(start 382.857756 -274.408646)
		(end 382.866138 -274.413472)
		(width 0.0889)
		(layer "In2.Cu")
		(net "M_I_CPU0_SB_DQ<0>")
	)
	(segment
		(start 421.80764 -280.657046)
		(end 422.787064 -280.657046)
		(width 0.14478)
		(layer "In2.Cu")
		(net "M_I_CPU0_SB_DQ<0>")
	)
	(segment
		(start 413.352234 -282.05176)
		(end 413.547814 -282.13304)
		(width 0.14478)
		(layer "In2.Cu")
		(net "M_I_CPU0_SB_DQ<0>")
	)
	(segment
		(start 393.198096 -274.408392)
		(end 393.216384 -274.418806)
		(width 0.0889)
		(layer "In2.Cu")
		(net "M_I_CPU0_SB_DQ<0>")
	)
	(segment
		(start 394.606526 -273.39417)
		(end 395.104874 -273.39417)
		(width 0.0889)
		(layer "In2.Cu")
		(net "M_I_CPU0_SB_DQ<0>")
	)
	(segment
		(start 377.404884 -274.086066)
		(end 377.558808 -274.351496)
		(width 0.0889)
		(layer "In2.Cu")
		(net "M_I_CPU0_SB_DQ<0>")
	)
	(segment
		(start 417.65855 -281.060144)
		(end 418.430456 -281.37993)
		(width 0.14478)
		(layer "In2.Cu")
		(net "M_I_CPU0_SB_DQ<0>")
	)
	(segment
		(start 393.182348 -274.399248)
		(end 393.198096 -274.408392)
		(width 0.0889)
		(layer "In2.Cu")
		(net "M_I_CPU0_SB_DQ<0>")
	)
	(segment
		(start 413.858202 -281.421078)
		(end 414.729168 -281.060144)
		(width 0.14478)
		(layer "In2.Cu")
		(net "M_I_CPU0_SB_DQ<0>")
	)
	(segment
		(start 392.257788 -274.408646)
		(end 392.269472 -274.415504)
		(width 0.0889)
		(layer "In2.Cu")
		(net "M_I_CPU0_SB_DQ<0>")
	)
	(segment
		(start 386.983478 -274.413472)
		(end 386.99186 -274.408646)
		(width 0.0889)
		(layer "In2.Cu")
		(net "M_I_CPU0_SB_DQ<0>")
	)
	(segment
		(start 413.065214 -281.749246)
		(end 413.26054 -281.830526)
		(width 0.14478)
		(layer "In2.Cu")
		(net "M_I_CPU0_SB_DQ<0>")
	)
	(segment
		(start 395.104874 -273.39417)
		(end 395.559534 -272.93951)
		(width 0.0889)
		(layer "In2.Cu")
		(net "M_I_CPU0_SB_DQ<0>")
	)
	(segment
		(start 418.515038 -281.5844)
		(end 419.301422 -281.910028)
		(width 0.14478)
		(layer "In2.Cu")
		(net "M_I_CPU0_SB_DQ<0>")
	)
	(segment
		(start 412.677356 -281.910028)
		(end 413.065214 -281.749246)
		(width 0.14478)
		(layer "In2.Cu")
		(net "M_I_CPU0_SB_DQ<0>")
	)
	(segment
		(start 388.497826 -274.408646)
		(end 388.506208 -274.413472)
		(width 0.0889)
		(layer "In2.Cu")
		(net "M_I_CPU0_SB_DQ<0>")
	)
	(segment
		(start 379.097794 -274.408646)
		(end 379.106176 -274.413472)
		(width 0.0889)
		(layer "In2.Cu")
		(net "M_I_CPU0_SB_DQ<0>")
	)
	(segment
		(start 393.572238 -274.408646)
		(end 394.606526 -273.39417)
		(width 0.0889)
		(layer "In2.Cu")
		(net "M_I_CPU0_SB_DQ<0>")
	)
	(segment
		(start 391.317734 -274.408646)
		(end 391.326116 -274.413472)
		(width 0.0889)
		(layer "In2.Cu")
		(net "M_I_CPU0_SB_DQ<0>")
	)
	(segment
		(start 418.430456 -281.37993)
		(end 418.515038 -281.5844)
		(width 0.14478)
		(layer "In2.Cu")
		(net "M_I_CPU0_SB_DQ<0>")
	)
	(arc
		(start 378.15774 -274.408646)
		(mid 378.339991 -274.458996)
		(end 378.5235 -274.413472)
		(width 0.0889)
		(layer "In2.Cu")
		(net "M_I_CPU0_SB_DQ<0>")
	)
	(arc
		(start 383.806192 -274.413472)
		(mid 383.9897 -274.458966)
		(end 384.171952 -274.408646)
		(width 0.0889)
		(layer "In2.Cu")
		(net "M_I_CPU0_SB_DQ<0>")
	)
	(arc
		(start 383.231898 -274.408646)
		(mid 383.514854 -274.332469)
		(end 383.79781 -274.408646)
		(width 0.0889)
		(layer "In2.Cu")
		(net "M_I_CPU0_SB_DQ<0>")
	)
	(arc
		(start 386.051806 -274.408646)
		(mid 386.334762 -274.332469)
		(end 386.617718 -274.408646)
		(width 0.0889)
		(layer "In2.Cu")
		(net "M_I_CPU0_SB_DQ<0>")
	)
	(arc
		(start 379.471936 -274.408646)
		(mid 379.754892 -274.332469)
		(end 380.037848 -274.408646)
		(width 0.0889)
		(layer "In2.Cu")
		(net "M_I_CPU0_SB_DQ<0>")
	)
	(arc
		(start 381.917702 -274.408646)
		(mid 382.099953 -274.458996)
		(end 382.283462 -274.413472)
		(width 0.0889)
		(layer "In2.Cu")
		(net "M_I_CPU0_SB_DQ<0>")
	)
	(arc
		(start 377.65482 -274.376896)
		(mid 377.910028 -274.333419)
		(end 378.15774 -274.408646)
		(width 0.0889)
		(layer "In2.Cu")
		(net "M_I_CPU0_SB_DQ<0>")
	)
	(arc
		(start 378.531882 -274.408646)
		(mid 378.814838 -274.332469)
		(end 379.097794 -274.408646)
		(width 0.0889)
		(layer "In2.Cu")
		(net "M_I_CPU0_SB_DQ<0>")
	)
	(arc
		(start 382.866138 -274.413472)
		(mid 383.049646 -274.458966)
		(end 383.231898 -274.408646)
		(width 0.0889)
		(layer "In2.Cu")
		(net "M_I_CPU0_SB_DQ<0>")
	)
	(arc
		(start 388.506208 -274.413472)
		(mid 388.689716 -274.458966)
		(end 388.871968 -274.408646)
		(width 0.0889)
		(layer "In2.Cu")
		(net "M_I_CPU0_SB_DQ<0>")
	)
	(arc
		(start 385.111752 -274.408646)
		(mid 385.394708 -274.332469)
		(end 385.677664 -274.408646)
		(width 0.0889)
		(layer "In2.Cu")
		(net "M_I_CPU0_SB_DQ<0>")
	)
	(arc
		(start 385.677664 -274.408646)
		(mid 385.859915 -274.458996)
		(end 386.043424 -274.413472)
		(width 0.0889)
		(layer "In2.Cu")
		(net "M_I_CPU0_SB_DQ<0>")
	)
	(arc
		(start 389.43788 -274.408646)
		(mid 389.624824 -274.458901)
		(end 389.811768 -274.408646)
		(width 0.0889)
		(layer "In2.Cu")
		(net "M_I_CPU0_SB_DQ<0>")
	)
	(arc
		(start 391.326116 -274.413472)
		(mid 391.509624 -274.458966)
		(end 391.691876 -274.408646)
		(width 0.0889)
		(layer "In2.Cu")
		(net "M_I_CPU0_SB_DQ<0>")
	)
	(arc
		(start 380.41199 -274.408646)
		(mid 380.694946 -274.332469)
		(end 380.977902 -274.408646)
		(width 0.0889)
		(layer "In2.Cu")
		(net "M_I_CPU0_SB_DQ<0>")
	)
	(arc
		(start 393.216384 -274.418806)
		(mid 393.395613 -274.458959)
		(end 393.572238 -274.408646)
		(width 0.0889)
		(layer "In2.Cu")
		(net "M_I_CPU0_SB_DQ<0>")
	)
	(arc
		(start 382.291844 -274.408646)
		(mid 382.5748 -274.332469)
		(end 382.857756 -274.408646)
		(width 0.0889)
		(layer "In2.Cu")
		(net "M_I_CPU0_SB_DQ<0>")
	)
	(arc
		(start 387.566154 -274.413472)
		(mid 387.749662 -274.458966)
		(end 387.931914 -274.408646)
		(width 0.0889)
		(layer "In2.Cu")
		(net "M_I_CPU0_SB_DQ<0>")
	)
	(arc
		(start 387.931914 -274.408646)
		(mid 388.21487 -274.332469)
		(end 388.497826 -274.408646)
		(width 0.0889)
		(layer "In2.Cu")
		(net "M_I_CPU0_SB_DQ<0>")
	)
	(arc
		(start 388.871968 -274.408646)
		(mid 389.154924 -274.332469)
		(end 389.43788 -274.408646)
		(width 0.0889)
		(layer "In2.Cu")
		(net "M_I_CPU0_SB_DQ<0>")
	)
	(arc
		(start 379.106176 -274.413472)
		(mid 379.289684 -274.458966)
		(end 379.471936 -274.408646)
		(width 0.0889)
		(layer "In2.Cu")
		(net "M_I_CPU0_SB_DQ<0>")
	)
	(arc
		(start 380.977902 -274.408646)
		(mid 381.164846 -274.458901)
		(end 381.35179 -274.408646)
		(width 0.0889)
		(layer "In2.Cu")
		(net "M_I_CPU0_SB_DQ<0>")
	)
	(arc
		(start 390.751822 -274.408646)
		(mid 391.034778 -274.332469)
		(end 391.317734 -274.408646)
		(width 0.0889)
		(layer "In2.Cu")
		(net "M_I_CPU0_SB_DQ<0>")
	)
	(arc
		(start 386.617718 -274.408646)
		(mid 386.799969 -274.458996)
		(end 386.983478 -274.413472)
		(width 0.0889)
		(layer "In2.Cu")
		(net "M_I_CPU0_SB_DQ<0>")
	)
	(arc
		(start 380.04623 -274.413472)
		(mid 380.229738 -274.458966)
		(end 380.41199 -274.408646)
		(width 0.0889)
		(layer "In2.Cu")
		(net "M_I_CPU0_SB_DQ<0>")
	)
	(arc
		(start 384.737864 -274.408646)
		(mid 384.924808 -274.458901)
		(end 385.111752 -274.408646)
		(width 0.0889)
		(layer "In2.Cu")
		(net "M_I_CPU0_SB_DQ<0>")
	)
	(arc
		(start 390.37768 -274.408646)
		(mid 390.559931 -274.458996)
		(end 390.74344 -274.413472)
		(width 0.0889)
		(layer "In2.Cu")
		(net "M_I_CPU0_SB_DQ<0>")
	)
	(arc
		(start 386.99186 -274.408646)
		(mid 387.274816 -274.332469)
		(end 387.557772 -274.408646)
		(width 0.0889)
		(layer "In2.Cu")
		(net "M_I_CPU0_SB_DQ<0>")
	)
	(arc
		(start 381.35179 -274.408646)
		(mid 381.634746 -274.332469)
		(end 381.917702 -274.408646)
		(width 0.0889)
		(layer "In2.Cu")
		(net "M_I_CPU0_SB_DQ<0>")
	)
	(arc
		(start 392.269472 -274.415504)
		(mid 392.451727 -274.459157)
		(end 392.632184 -274.408646)
		(width 0.0889)
		(layer "In2.Cu")
		(net "M_I_CPU0_SB_DQ<0>")
	)
	(arc
		(start 392.632184 -274.408646)
		(mid 392.906039 -274.332296)
		(end 393.182348 -274.399248)
		(width 0.0889)
		(layer "In2.Cu")
		(net "M_I_CPU0_SB_DQ<0>")
	)
	(arc
		(start 389.811768 -274.408646)
		(mid 390.094724 -274.332469)
		(end 390.37768 -274.408646)
		(width 0.0889)
		(layer "In2.Cu")
		(net "M_I_CPU0_SB_DQ<0>")
	)
	(arc
		(start 384.171952 -274.408646)
		(mid 384.454908 -274.332469)
		(end 384.737864 -274.408646)
		(width 0.0889)
		(layer "In2.Cu")
		(net "M_I_CPU0_SB_DQ<0>")
	)
	(arc
		(start 391.691876 -274.408646)
		(mid 391.974832 -274.332469)
		(end 392.257788 -274.408646)
		(width 0.0889)
		(layer "In2.Cu")
		(net "M_I_CPU0_SB_DQ<0>")
	)
	(segment
		(start 377.407932 -266.530074)
		(end 377.874784 -266.796012)
		(width 0.10668)
		(layer "F.Cu")
		(net "M_I_CPU0_SB_CS_N<1>")
	)
	(segment
		(start 413.912304 -268.84249)
		(end 414.15335 -268.84249)
		(width 0.14478)
		(layer "In2.Cu")
		(net "M_I_CPU0_SB_CS_N<1>")
	)
	(segment
		(start 389.333486 -266.468606)
		(end 389.341868 -266.473432)
		(width 0.0889)
		(layer "In2.Cu")
		(net "M_I_CPU0_SB_CS_N<1>")
	)
	(segment
		(start 379.933454 -266.468606)
		(end 379.941836 -266.473432)
		(width 0.0889)
		(layer "In2.Cu")
		(net "M_I_CPU0_SB_CS_N<1>")
	)
	(segment
		(start 394.251434 -265.63701)
		(end 395.602714 -265.63701)
		(width 0.0889)
		(layer "In2.Cu")
		(net "M_I_CPU0_SB_CS_N<1>")
	)
	(segment
		(start 393.010136 -266.435332)
		(end 393.453112 -266.435332)
		(width 0.0889)
		(layer "In2.Cu")
		(net "M_I_CPU0_SB_CS_N<1>")
	)
	(segment
		(start 421.107108 -269.160244)
		(end 421.422322 -268.84503)
		(width 0.14478)
		(layer "In2.Cu")
		(net "M_I_CPU0_SB_CS_N<1>")
	)
	(segment
		(start 377.874784 -266.796012)
		(end 377.72086 -266.530582)
		(width 0.0889)
		(layer "In2.Cu")
		(net "M_I_CPU0_SB_CS_N<1>")
	)
	(segment
		(start 380.873508 -266.468606)
		(end 380.88189 -266.473432)
		(width 0.0889)
		(layer "In2.Cu")
		(net "M_I_CPU0_SB_CS_N<1>")
	)
	(segment
		(start 418.083238 -268.88567)
		(end 418.357812 -269.160244)
		(width 0.14478)
		(layer "In2.Cu")
		(net "M_I_CPU0_SB_CS_N<1>")
	)
	(segment
		(start 385.207764 -266.473432)
		(end 385.216146 -266.468606)
		(width 0.0889)
		(layer "In2.Cu")
		(net "M_I_CPU0_SB_CS_N<1>")
	)
	(segment
		(start 422.224708 -269.160244)
		(end 422.539922 -268.84503)
		(width 0.14478)
		(layer "In2.Cu")
		(net "M_I_CPU0_SB_CS_N<1>")
	)
	(segment
		(start 406.08758 -265.70305)
		(end 411.261306 -269.160244)
		(width 0.14478)
		(layer "In2.Cu")
		(net "M_I_CPU0_SB_CS_N<1>")
	)
	(segment
		(start 395.602714 -265.63701)
		(end 395.668754 -265.70305)
		(width 0.0889)
		(layer "In2.Cu")
		(net "M_I_CPU0_SB_CS_N<1>")
	)
	(segment
		(start 417.799012 -268.88567)
		(end 418.083238 -268.88567)
		(width 0.14478)
		(layer "In2.Cu")
		(net "M_I_CPU0_SB_CS_N<1>")
	)
	(segment
		(start 415.27095 -268.84249)
		(end 415.588704 -269.160244)
		(width 0.14478)
		(layer "In2.Cu")
		(net "M_I_CPU0_SB_CS_N<1>")
	)
	(segment
		(start 388.393432 -266.468606)
		(end 388.401814 -266.473432)
		(width 0.0889)
		(layer "In2.Cu")
		(net "M_I_CPU0_SB_CS_N<1>")
	)
	(segment
		(start 422.783508 -268.84503)
		(end 423.098722 -269.160244)
		(width 0.14478)
		(layer "In2.Cu")
		(net "M_I_CPU0_SB_CS_N<1>")
	)
	(segment
		(start 414.15335 -268.84249)
		(end 414.471104 -269.160244)
		(width 0.14478)
		(layer "In2.Cu")
		(net "M_I_CPU0_SB_CS_N<1>")
	)
	(segment
		(start 421.665908 -268.84503)
		(end 421.981122 -269.160244)
		(width 0.14478)
		(layer "In2.Cu")
		(net "M_I_CPU0_SB_CS_N<1>")
	)
	(segment
		(start 423.098722 -269.160244)
		(end 425.142914 -269.160244)
		(width 0.14478)
		(layer "In2.Cu")
		(net "M_I_CPU0_SB_CS_N<1>")
	)
	(segment
		(start 427.030896 -269.160244)
		(end 427.456092 -268.735048)
		(width 0.14478)
		(layer "In2.Cu")
		(net "M_I_CPU0_SB_CS_N<1>")
	)
	(segment
		(start 381.447802 -266.473432)
		(end 381.456184 -266.468606)
		(width 0.0889)
		(layer "In2.Cu")
		(net "M_I_CPU0_SB_CS_N<1>")
	)
	(segment
		(start 393.453112 -266.435332)
		(end 394.251434 -265.63701)
		(width 0.0889)
		(layer "In2.Cu")
		(net "M_I_CPU0_SB_CS_N<1>")
	)
	(segment
		(start 425.701714 -268.86027)
		(end 426.001688 -269.160244)
		(width 0.14478)
		(layer "In2.Cu")
		(net "M_I_CPU0_SB_CS_N<1>")
	)
	(segment
		(start 417.524438 -269.160244)
		(end 417.799012 -268.88567)
		(width 0.14478)
		(layer "In2.Cu")
		(net "M_I_CPU0_SB_CS_N<1>")
	)
	(segment
		(start 389.90778 -266.473432)
		(end 389.916162 -266.468606)
		(width 0.0889)
		(layer "In2.Cu")
		(net "M_I_CPU0_SB_CS_N<1>")
	)
	(segment
		(start 392.161776 -266.473432)
		(end 392.176508 -266.482068)
		(width 0.0889)
		(layer "In2.Cu")
		(net "M_I_CPU0_SB_CS_N<1>")
	)
	(segment
		(start 426.001688 -269.160244)
		(end 427.030896 -269.160244)
		(width 0.14478)
		(layer "In2.Cu")
		(net "M_I_CPU0_SB_CS_N<1>")
	)
	(segment
		(start 421.981122 -269.160244)
		(end 422.224708 -269.160244)
		(width 0.14478)
		(layer "In2.Cu")
		(net "M_I_CPU0_SB_CS_N<1>")
	)
	(segment
		(start 377.72086 -266.530582)
		(end 377.743212 -266.44727)
		(width 0.0889)
		(layer "In2.Cu")
		(net "M_I_CPU0_SB_CS_N<1>")
	)
	(segment
		(start 386.147818 -266.473432)
		(end 386.1562 -266.468606)
		(width 0.0889)
		(layer "In2.Cu")
		(net "M_I_CPU0_SB_CS_N<1>")
	)
	(segment
		(start 425.442888 -268.86027)
		(end 425.701714 -268.86027)
		(width 0.14478)
		(layer "In2.Cu")
		(net "M_I_CPU0_SB_CS_N<1>")
	)
	(segment
		(start 415.029904 -268.84249)
		(end 415.27095 -268.84249)
		(width 0.14478)
		(layer "In2.Cu")
		(net "M_I_CPU0_SB_CS_N<1>")
	)
	(segment
		(start 414.71215 -269.160244)
		(end 415.029904 -268.84249)
		(width 0.14478)
		(layer "In2.Cu")
		(net "M_I_CPU0_SB_CS_N<1>")
	)
	(segment
		(start 383.693416 -266.468606)
		(end 383.701798 -266.473432)
		(width 0.0889)
		(layer "In2.Cu")
		(net "M_I_CPU0_SB_CS_N<1>")
	)
	(segment
		(start 395.668754 -265.70305)
		(end 406.08758 -265.70305)
		(width 0.14478)
		(layer "In2.Cu")
		(net "M_I_CPU0_SB_CS_N<1>")
	)
	(segment
		(start 422.539922 -268.84503)
		(end 422.783508 -268.84503)
		(width 0.14478)
		(layer "In2.Cu")
		(net "M_I_CPU0_SB_CS_N<1>")
	)
	(segment
		(start 411.261306 -269.160244)
		(end 413.59455 -269.160244)
		(width 0.14478)
		(layer "In2.Cu")
		(net "M_I_CPU0_SB_CS_N<1>")
	)
	(segment
		(start 415.588704 -269.160244)
		(end 417.524438 -269.160244)
		(width 0.14478)
		(layer "In2.Cu")
		(net "M_I_CPU0_SB_CS_N<1>")
	)
	(segment
		(start 413.59455 -269.160244)
		(end 413.912304 -268.84249)
		(width 0.14478)
		(layer "In2.Cu")
		(net "M_I_CPU0_SB_CS_N<1>")
	)
	(segment
		(start 384.63347 -266.468606)
		(end 384.641852 -266.473432)
		(width 0.0889)
		(layer "In2.Cu")
		(net "M_I_CPU0_SB_CS_N<1>")
	)
	(segment
		(start 425.142914 -269.160244)
		(end 425.442888 -268.86027)
		(width 0.14478)
		(layer "In2.Cu")
		(net "M_I_CPU0_SB_CS_N<1>")
	)
	(segment
		(start 418.357812 -269.160244)
		(end 421.107108 -269.160244)
		(width 0.14478)
		(layer "In2.Cu")
		(net "M_I_CPU0_SB_CS_N<1>")
	)
	(segment
		(start 421.422322 -268.84503)
		(end 421.665908 -268.84503)
		(width 0.14478)
		(layer "In2.Cu")
		(net "M_I_CPU0_SB_CS_N<1>")
	)
	(segment
		(start 414.471104 -269.160244)
		(end 414.71215 -269.160244)
		(width 0.14478)
		(layer "In2.Cu")
		(net "M_I_CPU0_SB_CS_N<1>")
	)
	(segment
		(start 392.153394 -266.468606)
		(end 392.161776 -266.473432)
		(width 0.0889)
		(layer "In2.Cu")
		(net "M_I_CPU0_SB_CS_N<1>")
	)
	(arc
		(start 392.728196 -266.473432)
		(mid 392.865392 -266.426417)
		(end 393.010136 -266.435332)
		(width 0.0889)
		(layer "In2.Cu")
		(net "M_I_CPU0_SB_CS_N<1>")
	)
	(arc
		(start 392.176508 -266.482068)
		(mid 392.453491 -266.549872)
		(end 392.728196 -266.473432)
		(width 0.0889)
		(layer "In2.Cu")
		(net "M_I_CPU0_SB_CS_N<1>")
	)
	(arc
		(start 390.847834 -266.473432)
		(mid 391.034778 -266.423177)
		(end 391.221722 -266.473432)
		(width 0.0889)
		(layer "In2.Cu")
		(net "M_I_CPU0_SB_CS_N<1>")
	)
	(arc
		(start 379.001782 -266.473432)
		(mid 379.284738 -266.549609)
		(end 379.567694 -266.473432)
		(width 0.0889)
		(layer "In2.Cu")
		(net "M_I_CPU0_SB_CS_N<1>")
	)
	(arc
		(start 388.401814 -266.473432)
		(mid 388.68477 -266.549609)
		(end 388.967726 -266.473432)
		(width 0.0889)
		(layer "In2.Cu")
		(net "M_I_CPU0_SB_CS_N<1>")
	)
	(arc
		(start 379.567694 -266.473432)
		(mid 379.749945 -266.423082)
		(end 379.933454 -266.468606)
		(width 0.0889)
		(layer "In2.Cu")
		(net "M_I_CPU0_SB_CS_N<1>")
	)
	(arc
		(start 385.581906 -266.473432)
		(mid 385.864862 -266.549609)
		(end 386.147818 -266.473432)
		(width 0.0889)
		(layer "In2.Cu")
		(net "M_I_CPU0_SB_CS_N<1>")
	)
	(arc
		(start 379.941836 -266.473432)
		(mid 380.224792 -266.549609)
		(end 380.507748 -266.473432)
		(width 0.0889)
		(layer "In2.Cu")
		(net "M_I_CPU0_SB_CS_N<1>")
	)
	(arc
		(start 387.087872 -266.473432)
		(mid 387.274816 -266.423177)
		(end 387.46176 -266.473432)
		(width 0.0889)
		(layer "In2.Cu")
		(net "M_I_CPU0_SB_CS_N<1>")
	)
	(arc
		(start 381.821944 -266.473432)
		(mid 382.1049 -266.549609)
		(end 382.387856 -266.473432)
		(width 0.0889)
		(layer "In2.Cu")
		(net "M_I_CPU0_SB_CS_N<1>")
	)
	(arc
		(start 389.916162 -266.468606)
		(mid 390.09967 -266.423112)
		(end 390.281922 -266.473432)
		(width 0.0889)
		(layer "In2.Cu")
		(net "M_I_CPU0_SB_CS_N<1>")
	)
	(arc
		(start 377.743212 -266.44727)
		(mid 377.905544 -266.424452)
		(end 378.061982 -266.473432)
		(width 0.0889)
		(layer "In2.Cu")
		(net "M_I_CPU0_SB_CS_N<1>")
	)
	(arc
		(start 380.507748 -266.473432)
		(mid 380.689999 -266.423082)
		(end 380.873508 -266.468606)
		(width 0.0889)
		(layer "In2.Cu")
		(net "M_I_CPU0_SB_CS_N<1>")
	)
	(arc
		(start 386.52196 -266.473432)
		(mid 386.804916 -266.549609)
		(end 387.087872 -266.473432)
		(width 0.0889)
		(layer "In2.Cu")
		(net "M_I_CPU0_SB_CS_N<1>")
	)
	(arc
		(start 382.387856 -266.473432)
		(mid 382.5748 -266.423177)
		(end 382.761744 -266.473432)
		(width 0.0889)
		(layer "In2.Cu")
		(net "M_I_CPU0_SB_CS_N<1>")
	)
	(arc
		(start 388.967726 -266.473432)
		(mid 389.149977 -266.423082)
		(end 389.333486 -266.468606)
		(width 0.0889)
		(layer "In2.Cu")
		(net "M_I_CPU0_SB_CS_N<1>")
	)
	(arc
		(start 387.46176 -266.473432)
		(mid 387.744716 -266.549609)
		(end 388.027672 -266.473432)
		(width 0.0889)
		(layer "In2.Cu")
		(net "M_I_CPU0_SB_CS_N<1>")
	)
	(arc
		(start 381.456184 -266.468606)
		(mid 381.639692 -266.423112)
		(end 381.821944 -266.473432)
		(width 0.0889)
		(layer "In2.Cu")
		(net "M_I_CPU0_SB_CS_N<1>")
	)
	(arc
		(start 383.327656 -266.473432)
		(mid 383.509907 -266.423082)
		(end 383.693416 -266.468606)
		(width 0.0889)
		(layer "In2.Cu")
		(net "M_I_CPU0_SB_CS_N<1>")
	)
	(arc
		(start 391.787634 -266.473432)
		(mid 391.969885 -266.423082)
		(end 392.153394 -266.468606)
		(width 0.0889)
		(layer "In2.Cu")
		(net "M_I_CPU0_SB_CS_N<1>")
	)
	(arc
		(start 388.027672 -266.473432)
		(mid 388.209923 -266.423082)
		(end 388.393432 -266.468606)
		(width 0.0889)
		(layer "In2.Cu")
		(net "M_I_CPU0_SB_CS_N<1>")
	)
	(arc
		(start 384.26771 -266.473432)
		(mid 384.449961 -266.423082)
		(end 384.63347 -266.468606)
		(width 0.0889)
		(layer "In2.Cu")
		(net "M_I_CPU0_SB_CS_N<1>")
	)
	(arc
		(start 380.88189 -266.473432)
		(mid 381.164846 -266.549609)
		(end 381.447802 -266.473432)
		(width 0.0889)
		(layer "In2.Cu")
		(net "M_I_CPU0_SB_CS_N<1>")
	)
	(arc
		(start 383.701798 -266.473432)
		(mid 383.984754 -266.549609)
		(end 384.26771 -266.473432)
		(width 0.0889)
		(layer "In2.Cu")
		(net "M_I_CPU0_SB_CS_N<1>")
	)
	(arc
		(start 382.761744 -266.473432)
		(mid 383.0447 -266.549609)
		(end 383.327656 -266.473432)
		(width 0.0889)
		(layer "In2.Cu")
		(net "M_I_CPU0_SB_CS_N<1>")
	)
	(arc
		(start 378.061982 -266.473432)
		(mid 378.344938 -266.549609)
		(end 378.627894 -266.473432)
		(width 0.0889)
		(layer "In2.Cu")
		(net "M_I_CPU0_SB_CS_N<1>")
	)
	(arc
		(start 378.627894 -266.473432)
		(mid 378.814838 -266.423177)
		(end 379.001782 -266.473432)
		(width 0.0889)
		(layer "In2.Cu")
		(net "M_I_CPU0_SB_CS_N<1>")
	)
	(arc
		(start 385.216146 -266.468606)
		(mid 385.399654 -266.423112)
		(end 385.581906 -266.473432)
		(width 0.0889)
		(layer "In2.Cu")
		(net "M_I_CPU0_SB_CS_N<1>")
	)
	(arc
		(start 386.1562 -266.468606)
		(mid 386.339708 -266.423112)
		(end 386.52196 -266.473432)
		(width 0.0889)
		(layer "In2.Cu")
		(net "M_I_CPU0_SB_CS_N<1>")
	)
	(arc
		(start 390.281922 -266.473432)
		(mid 390.564878 -266.549609)
		(end 390.847834 -266.473432)
		(width 0.0889)
		(layer "In2.Cu")
		(net "M_I_CPU0_SB_CS_N<1>")
	)
	(arc
		(start 384.641852 -266.473432)
		(mid 384.924808 -266.549609)
		(end 385.207764 -266.473432)
		(width 0.0889)
		(layer "In2.Cu")
		(net "M_I_CPU0_SB_CS_N<1>")
	)
	(arc
		(start 391.221722 -266.473432)
		(mid 391.504678 -266.549609)
		(end 391.787634 -266.473432)
		(width 0.0889)
		(layer "In2.Cu")
		(net "M_I_CPU0_SB_CS_N<1>")
	)
	(arc
		(start 389.341868 -266.473432)
		(mid 389.624824 -266.549609)
		(end 389.90778 -266.473432)
		(width 0.0889)
		(layer "In2.Cu")
		(net "M_I_CPU0_SB_CS_N<1>")
	)
	(segment
		(start 375.997978 -265.720068)
		(end 376.46483 -265.986006)
		(width 0.10668)
		(layer "F.Cu")
		(net "M_I_CPU0_SB_CS_N<0>")
	)
	(segment
		(start 386.043424 -265.6586)
		(end 386.051806 -265.663426)
		(width 0.0889)
		(layer "In2.Cu")
		(net "M_I_CPU0_SB_CS_N<0>")
	)
	(segment
		(start 395.117066 -265.308588)
		(end 395.177264 -265.24839)
		(width 0.0889)
		(layer "In2.Cu")
		(net "M_I_CPU0_SB_CS_N<0>")
	)
	(segment
		(start 431.131218 -268.310106)
		(end 431.55616 -267.885164)
		(width 0.14478)
		(layer "In2.Cu")
		(net "M_I_CPU0_SB_CS_N<0>")
	)
	(segment
		(start 390.74344 -265.6586)
		(end 390.751822 -265.663426)
		(width 0.0889)
		(layer "In2.Cu")
		(net "M_I_CPU0_SB_CS_N<0>")
	)
	(segment
		(start 391.317734 -265.663426)
		(end 391.326116 -265.6586)
		(width 0.0889)
		(layer "In2.Cu")
		(net "M_I_CPU0_SB_CS_N<0>")
	)
	(segment
		(start 393.624562 -265.308588)
		(end 395.117066 -265.308588)
		(width 0.0889)
		(layer "In2.Cu")
		(net "M_I_CPU0_SB_CS_N<0>")
	)
	(segment
		(start 379.097794 -265.663426)
		(end 379.106176 -265.6586)
		(width 0.0889)
		(layer "In2.Cu")
		(net "M_I_CPU0_SB_CS_N<0>")
	)
	(segment
		(start 411.70225 -268.310106)
		(end 431.131218 -268.310106)
		(width 0.14478)
		(layer "In2.Cu")
		(net "M_I_CPU0_SB_CS_N<0>")
	)
	(segment
		(start 392.255756 -265.66368)
		(end 392.2776 -265.651234)
		(width 0.0889)
		(layer "In2.Cu")
		(net "M_I_CPU0_SB_CS_N<0>")
	)
	(segment
		(start 386.983478 -265.6586)
		(end 386.99186 -265.663426)
		(width 0.0889)
		(layer "In2.Cu")
		(net "M_I_CPU0_SB_CS_N<0>")
	)
	(segment
		(start 388.497826 -265.663426)
		(end 388.506208 -265.6586)
		(width 0.0889)
		(layer "In2.Cu")
		(net "M_I_CPU0_SB_CS_N<0>")
	)
	(segment
		(start 387.557772 -265.663426)
		(end 387.566154 -265.6586)
		(width 0.0889)
		(layer "In2.Cu")
		(net "M_I_CPU0_SB_CS_N<0>")
	)
	(segment
		(start 395.177264 -265.24839)
		(end 395.694154 -265.24839)
		(width 0.0889)
		(layer "In2.Cu")
		(net "M_I_CPU0_SB_CS_N<0>")
	)
	(segment
		(start 382.857756 -265.663426)
		(end 382.866138 -265.6586)
		(width 0.0889)
		(layer "In2.Cu")
		(net "M_I_CPU0_SB_CS_N<0>")
	)
	(segment
		(start 392.229594 -265.678666)
		(end 392.255756 -265.66368)
		(width 0.0889)
		(layer "In2.Cu")
		(net "M_I_CPU0_SB_CS_N<0>")
	)
	(segment
		(start 376.46483 -265.986006)
		(end 376.310906 -265.720576)
		(width 0.0889)
		(layer "In2.Cu")
		(net "M_I_CPU0_SB_CS_N<0>")
	)
	(segment
		(start 378.5235 -265.6586)
		(end 378.531882 -265.663426)
		(width 0.0889)
		(layer "In2.Cu")
		(net "M_I_CPU0_SB_CS_N<0>")
	)
	(segment
		(start 406.297892 -265.24839)
		(end 411.70225 -268.310106)
		(width 0.14478)
		(layer "In2.Cu")
		(net "M_I_CPU0_SB_CS_N<0>")
	)
	(segment
		(start 393.31392 -265.61923)
		(end 393.624562 -265.308588)
		(width 0.0889)
		(layer "In2.Cu")
		(net "M_I_CPU0_SB_CS_N<0>")
	)
	(segment
		(start 377.583446 -265.6586)
		(end 377.591828 -265.663426)
		(width 0.0889)
		(layer "In2.Cu")
		(net "M_I_CPU0_SB_CS_N<0>")
	)
	(segment
		(start 380.037848 -265.663426)
		(end 380.04623 -265.6586)
		(width 0.0889)
		(layer "In2.Cu")
		(net "M_I_CPU0_SB_CS_N<0>")
	)
	(segment
		(start 383.79781 -265.663426)
		(end 383.806192 -265.6586)
		(width 0.0889)
		(layer "In2.Cu")
		(net "M_I_CPU0_SB_CS_N<0>")
	)
	(segment
		(start 392.628374 -265.663426)
		(end 392.657838 -265.680698)
		(width 0.0889)
		(layer "In2.Cu")
		(net "M_I_CPU0_SB_CS_N<0>")
	)
	(segment
		(start 376.310906 -265.720576)
		(end 376.333258 -265.637264)
		(width 0.0889)
		(layer "In2.Cu")
		(net "M_I_CPU0_SB_CS_N<0>")
	)
	(segment
		(start 382.283462 -265.6586)
		(end 382.291844 -265.663426)
		(width 0.0889)
		(layer "In2.Cu")
		(net "M_I_CPU0_SB_CS_N<0>")
	)
	(segment
		(start 395.694154 -265.24839)
		(end 406.297892 -265.24839)
		(width 0.14478)
		(layer "In2.Cu")
		(net "M_I_CPU0_SB_CS_N<0>")
	)
	(arc
		(start 382.291844 -265.663426)
		(mid 382.5748 -265.739603)
		(end 382.857756 -265.663426)
		(width 0.0889)
		(layer "In2.Cu")
		(net "M_I_CPU0_SB_CS_N<0>")
	)
	(arc
		(start 386.051806 -265.663426)
		(mid 386.334762 -265.739603)
		(end 386.617718 -265.663426)
		(width 0.0889)
		(layer "In2.Cu")
		(net "M_I_CPU0_SB_CS_N<0>")
	)
	(arc
		(start 385.111752 -265.663426)
		(mid 385.394708 -265.739603)
		(end 385.677664 -265.663426)
		(width 0.0889)
		(layer "In2.Cu")
		(net "M_I_CPU0_SB_CS_N<0>")
	)
	(arc
		(start 380.977902 -265.663426)
		(mid 381.164846 -265.613171)
		(end 381.35179 -265.663426)
		(width 0.0889)
		(layer "In2.Cu")
		(net "M_I_CPU0_SB_CS_N<0>")
	)
	(arc
		(start 393.196318 -265.663426)
		(mid 393.253242 -265.636329)
		(end 393.31392 -265.61923)
		(width 0.0889)
		(layer "In2.Cu")
		(net "M_I_CPU0_SB_CS_N<0>")
	)
	(arc
		(start 392.657838 -265.680698)
		(mid 392.929258 -265.740375)
		(end 393.196318 -265.663426)
		(width 0.0889)
		(layer "In2.Cu")
		(net "M_I_CPU0_SB_CS_N<0>")
	)
	(arc
		(start 382.866138 -265.6586)
		(mid 383.049646 -265.613106)
		(end 383.231898 -265.663426)
		(width 0.0889)
		(layer "In2.Cu")
		(net "M_I_CPU0_SB_CS_N<0>")
	)
	(arc
		(start 378.15774 -265.663426)
		(mid 378.339991 -265.613076)
		(end 378.5235 -265.6586)
		(width 0.0889)
		(layer "In2.Cu")
		(net "M_I_CPU0_SB_CS_N<0>")
	)
	(arc
		(start 379.471936 -265.663426)
		(mid 379.754892 -265.739603)
		(end 380.037848 -265.663426)
		(width 0.0889)
		(layer "In2.Cu")
		(net "M_I_CPU0_SB_CS_N<0>")
	)
	(arc
		(start 385.677664 -265.663426)
		(mid 385.859915 -265.613076)
		(end 386.043424 -265.6586)
		(width 0.0889)
		(layer "In2.Cu")
		(net "M_I_CPU0_SB_CS_N<0>")
	)
	(arc
		(start 381.35179 -265.663426)
		(mid 381.634746 -265.739603)
		(end 381.917702 -265.663426)
		(width 0.0889)
		(layer "In2.Cu")
		(net "M_I_CPU0_SB_CS_N<0>")
	)
	(arc
		(start 380.04623 -265.6586)
		(mid 380.229738 -265.613106)
		(end 380.41199 -265.663426)
		(width 0.0889)
		(layer "In2.Cu")
		(net "M_I_CPU0_SB_CS_N<0>")
	)
	(arc
		(start 381.917702 -265.663426)
		(mid 382.099953 -265.613076)
		(end 382.283462 -265.6586)
		(width 0.0889)
		(layer "In2.Cu")
		(net "M_I_CPU0_SB_CS_N<0>")
	)
	(arc
		(start 389.43788 -265.663426)
		(mid 389.624824 -265.613171)
		(end 389.811768 -265.663426)
		(width 0.0889)
		(layer "In2.Cu")
		(net "M_I_CPU0_SB_CS_N<0>")
	)
	(arc
		(start 392.2776 -265.651234)
		(mid 392.454528 -265.613406)
		(end 392.628374 -265.663426)
		(width 0.0889)
		(layer "In2.Cu")
		(net "M_I_CPU0_SB_CS_N<0>")
	)
	(arc
		(start 377.217686 -265.663426)
		(mid 377.399937 -265.613076)
		(end 377.583446 -265.6586)
		(width 0.0889)
		(layer "In2.Cu")
		(net "M_I_CPU0_SB_CS_N<0>")
	)
	(arc
		(start 380.41199 -265.663426)
		(mid 380.694946 -265.739603)
		(end 380.977902 -265.663426)
		(width 0.0889)
		(layer "In2.Cu")
		(net "M_I_CPU0_SB_CS_N<0>")
	)
	(arc
		(start 388.506208 -265.6586)
		(mid 388.689716 -265.613106)
		(end 388.871968 -265.663426)
		(width 0.0889)
		(layer "In2.Cu")
		(net "M_I_CPU0_SB_CS_N<0>")
	)
	(arc
		(start 391.326116 -265.6586)
		(mid 391.509624 -265.613106)
		(end 391.691876 -265.663426)
		(width 0.0889)
		(layer "In2.Cu")
		(net "M_I_CPU0_SB_CS_N<0>")
	)
	(arc
		(start 376.333258 -265.637264)
		(mid 376.495447 -265.614529)
		(end 376.651774 -265.663426)
		(width 0.0889)
		(layer "In2.Cu")
		(net "M_I_CPU0_SB_CS_N<0>")
	)
	(arc
		(start 376.651774 -265.663426)
		(mid 376.93473 -265.739603)
		(end 377.217686 -265.663426)
		(width 0.0889)
		(layer "In2.Cu")
		(net "M_I_CPU0_SB_CS_N<0>")
	)
	(arc
		(start 383.806192 -265.6586)
		(mid 383.9897 -265.613106)
		(end 384.171952 -265.663426)
		(width 0.0889)
		(layer "In2.Cu")
		(net "M_I_CPU0_SB_CS_N<0>")
	)
	(arc
		(start 390.37768 -265.663426)
		(mid 390.559931 -265.613076)
		(end 390.74344 -265.6586)
		(width 0.0889)
		(layer "In2.Cu")
		(net "M_I_CPU0_SB_CS_N<0>")
	)
	(arc
		(start 386.617718 -265.663426)
		(mid 386.799969 -265.613076)
		(end 386.983478 -265.6586)
		(width 0.0889)
		(layer "In2.Cu")
		(net "M_I_CPU0_SB_CS_N<0>")
	)
	(arc
		(start 377.591828 -265.663426)
		(mid 377.874784 -265.739603)
		(end 378.15774 -265.663426)
		(width 0.0889)
		(layer "In2.Cu")
		(net "M_I_CPU0_SB_CS_N<0>")
	)
	(arc
		(start 384.171952 -265.663426)
		(mid 384.454908 -265.739603)
		(end 384.737864 -265.663426)
		(width 0.0889)
		(layer "In2.Cu")
		(net "M_I_CPU0_SB_CS_N<0>")
	)
	(arc
		(start 386.99186 -265.663426)
		(mid 387.274816 -265.739603)
		(end 387.557772 -265.663426)
		(width 0.0889)
		(layer "In2.Cu")
		(net "M_I_CPU0_SB_CS_N<0>")
	)
	(arc
		(start 387.931914 -265.663426)
		(mid 388.21487 -265.739603)
		(end 388.497826 -265.663426)
		(width 0.0889)
		(layer "In2.Cu")
		(net "M_I_CPU0_SB_CS_N<0>")
	)
	(arc
		(start 389.811768 -265.663426)
		(mid 390.094724 -265.739603)
		(end 390.37768 -265.663426)
		(width 0.0889)
		(layer "In2.Cu")
		(net "M_I_CPU0_SB_CS_N<0>")
	)
	(arc
		(start 391.691876 -265.663426)
		(mid 391.958806 -265.739375)
		(end 392.229594 -265.678666)
		(width 0.0889)
		(layer "In2.Cu")
		(net "M_I_CPU0_SB_CS_N<0>")
	)
	(arc
		(start 383.231898 -265.663426)
		(mid 383.514854 -265.739603)
		(end 383.79781 -265.663426)
		(width 0.0889)
		(layer "In2.Cu")
		(net "M_I_CPU0_SB_CS_N<0>")
	)
	(arc
		(start 388.871968 -265.663426)
		(mid 389.154924 -265.739603)
		(end 389.43788 -265.663426)
		(width 0.0889)
		(layer "In2.Cu")
		(net "M_I_CPU0_SB_CS_N<0>")
	)
	(arc
		(start 387.566154 -265.6586)
		(mid 387.749662 -265.613106)
		(end 387.931914 -265.663426)
		(width 0.0889)
		(layer "In2.Cu")
		(net "M_I_CPU0_SB_CS_N<0>")
	)
	(arc
		(start 379.106176 -265.6586)
		(mid 379.289684 -265.613106)
		(end 379.471936 -265.663426)
		(width 0.0889)
		(layer "In2.Cu")
		(net "M_I_CPU0_SB_CS_N<0>")
	)
	(arc
		(start 390.751822 -265.663426)
		(mid 391.034778 -265.739603)
		(end 391.317734 -265.663426)
		(width 0.0889)
		(layer "In2.Cu")
		(net "M_I_CPU0_SB_CS_N<0>")
	)
	(arc
		(start 378.531882 -265.663426)
		(mid 378.814838 -265.739603)
		(end 379.097794 -265.663426)
		(width 0.0889)
		(layer "In2.Cu")
		(net "M_I_CPU0_SB_CS_N<0>")
	)
	(arc
		(start 384.737864 -265.663426)
		(mid 384.924808 -265.613171)
		(end 385.111752 -265.663426)
		(width 0.0889)
		(layer "In2.Cu")
		(net "M_I_CPU0_SB_CS_N<0>")
	)
	(segment
		(start 375.997978 -270.580104)
		(end 376.46483 -270.846042)
		(width 0.10668)
		(layer "F.Cu")
		(net "M_I_CPU0_SB_CB<7>")
	)
	(segment
		(start 421.078914 -274.250404)
		(end 421.240458 -274.411948)
		(width 0.14478)
		(layer "In2.Cu")
		(net "M_I_CPU0_SB_CB<7>")
	)
	(segment
		(start 425.96054 -274.250404)
		(end 426.274992 -273.935952)
		(width 0.14478)
		(layer "In2.Cu")
		(net "M_I_CPU0_SB_CB<7>")
	)
	(segment
		(start 422.343326 -274.031456)
		(end 422.343326 -274.08886)
		(width 0.14478)
		(layer "In2.Cu")
		(net "M_I_CPU0_SB_CB<7>")
	)
	(segment
		(start 426.274992 -273.935952)
		(end 426.511974 -273.935952)
		(width 0.14478)
		(layer "In2.Cu")
		(net "M_I_CPU0_SB_CB<7>")
	)
	(segment
		(start 382.283462 -270.518636)
		(end 382.291844 -270.523462)
		(width 0.0889)
		(layer "In2.Cu")
		(net "M_I_CPU0_SB_CB<7>")
	)
	(segment
		(start 419.41242 -274.250404)
		(end 421.078914 -274.250404)
		(width 0.14478)
		(layer "In2.Cu")
		(net "M_I_CPU0_SB_CB<7>")
	)
	(segment
		(start 413.70123 -274.031456)
		(end 413.70123 -274.469352)
		(width 0.14478)
		(layer "In2.Cu")
		(net "M_I_CPU0_SB_CB<7>")
	)
	(segment
		(start 421.240458 -274.469352)
		(end 421.402002 -274.630896)
		(width 0.14478)
		(layer "In2.Cu")
		(net "M_I_CPU0_SB_CB<7>")
	)
	(segment
		(start 424.857672 -274.250404)
		(end 425.172124 -273.935952)
		(width 0.14478)
		(layer "In2.Cu")
		(net "M_I_CPU0_SB_CB<7>")
	)
	(segment
		(start 393.197588 -270.52397)
		(end 393.242292 -270.497808)
		(width 0.0889)
		(layer "In2.Cu")
		(net "M_I_CPU0_SB_CB<7>")
	)
	(segment
		(start 395.529054 -268.67993)
		(end 404.788116 -268.67993)
		(width 0.14478)
		(layer "In2.Cu")
		(net "M_I_CPU0_SB_CB<7>")
	)
	(segment
		(start 409.296108 -273.187922)
		(end 410.737812 -273.784822)
		(width 0.14478)
		(layer "In2.Cu")
		(net "M_I_CPU0_SB_CB<7>")
	)
	(segment
		(start 425.409106 -273.935952)
		(end 425.723558 -274.250404)
		(width 0.14478)
		(layer "In2.Cu")
		(net "M_I_CPU0_SB_CB<7>")
	)
	(segment
		(start 414.252664 -274.031456)
		(end 414.414208 -273.869912)
		(width 0.14478)
		(layer "In2.Cu")
		(net "M_I_CPU0_SB_CB<7>")
	)
	(segment
		(start 413.539686 -273.869912)
		(end 413.70123 -274.031456)
		(width 0.14478)
		(layer "In2.Cu")
		(net "M_I_CPU0_SB_CB<7>")
	)
	(segment
		(start 390.74344 -270.518636)
		(end 390.751822 -270.523462)
		(width 0.0889)
		(layer "In2.Cu")
		(net "M_I_CPU0_SB_CB<7>")
	)
	(segment
		(start 413.149796 -274.08886)
		(end 413.149796 -274.031456)
		(width 0.14478)
		(layer "In2.Cu")
		(net "M_I_CPU0_SB_CB<7>")
	)
	(segment
		(start 386.043424 -270.518636)
		(end 386.051806 -270.523462)
		(width 0.0889)
		(layer "In2.Cu")
		(net "M_I_CPU0_SB_CB<7>")
	)
	(segment
		(start 413.70123 -274.469352)
		(end 413.862774 -274.630896)
		(width 0.14478)
		(layer "In2.Cu")
		(net "M_I_CPU0_SB_CB<7>")
	)
	(segment
		(start 421.791892 -274.031456)
		(end 421.953436 -273.869912)
		(width 0.14478)
		(layer "In2.Cu")
		(net "M_I_CPU0_SB_CB<7>")
	)
	(segment
		(start 394.579602 -268.83741)
		(end 395.371574 -268.83741)
		(width 0.0889)
		(layer "In2.Cu")
		(net "M_I_CPU0_SB_CB<7>")
	)
	(segment
		(start 382.857756 -270.523462)
		(end 382.866138 -270.518636)
		(width 0.0889)
		(layer "In2.Cu")
		(net "M_I_CPU0_SB_CB<7>")
	)
	(segment
		(start 421.402002 -274.630896)
		(end 421.630348 -274.630896)
		(width 0.14478)
		(layer "In2.Cu")
		(net "M_I_CPU0_SB_CB<7>")
	)
	(segment
		(start 392.631422 -270.52397)
		(end 392.641836 -270.530066)
		(width 0.0889)
		(layer "In2.Cu")
		(net "M_I_CPU0_SB_CB<7>")
	)
	(segment
		(start 411.861254 -274.250404)
		(end 412.988252 -274.250404)
		(width 0.14478)
		(layer "In2.Cu")
		(net "M_I_CPU0_SB_CB<7>")
	)
	(segment
		(start 426.826426 -274.250404)
		(end 427.021498 -274.250404)
		(width 0.14478)
		(layer "In2.Cu")
		(net "M_I_CPU0_SB_CB<7>")
	)
	(segment
		(start 392.615928 -270.51508)
		(end 392.631422 -270.52397)
		(width 0.0889)
		(layer "In2.Cu")
		(net "M_I_CPU0_SB_CB<7>")
	)
	(segment
		(start 388.497826 -270.523462)
		(end 388.506208 -270.518636)
		(width 0.0889)
		(layer "In2.Cu")
		(net "M_I_CPU0_SB_CB<7>")
	)
	(segment
		(start 387.557772 -270.523462)
		(end 387.566154 -270.518636)
		(width 0.0889)
		(layer "In2.Cu")
		(net "M_I_CPU0_SB_CB<7>")
	)
	(segment
		(start 418.309552 -274.250404)
		(end 418.538914 -274.250404)
		(width 0.14478)
		(layer "In2.Cu")
		(net "M_I_CPU0_SB_CB<7>")
	)
	(segment
		(start 414.09112 -274.630896)
		(end 414.252664 -274.469352)
		(width 0.14478)
		(layer "In2.Cu")
		(net "M_I_CPU0_SB_CB<7>")
	)
	(segment
		(start 422.181782 -273.869912)
		(end 422.343326 -274.031456)
		(width 0.14478)
		(layer "In2.Cu")
		(net "M_I_CPU0_SB_CB<7>")
	)
	(segment
		(start 393.732766 -269.67561)
		(end 393.761722 -269.65529)
		(width 0.0889)
		(layer "In2.Cu")
		(net "M_I_CPU0_SB_CB<7>")
	)
	(segment
		(start 379.097794 -270.523462)
		(end 379.106176 -270.518636)
		(width 0.0889)
		(layer "In2.Cu")
		(net "M_I_CPU0_SB_CB<7>")
	)
	(segment
		(start 383.79781 -270.523462)
		(end 383.806192 -270.518636)
		(width 0.0889)
		(layer "In2.Cu")
		(net "M_I_CPU0_SB_CB<7>")
	)
	(segment
		(start 413.862774 -274.630896)
		(end 414.09112 -274.630896)
		(width 0.14478)
		(layer "In2.Cu")
		(net "M_I_CPU0_SB_CB<7>")
	)
	(segment
		(start 412.988252 -274.250404)
		(end 413.149796 -274.08886)
		(width 0.14478)
		(layer "In2.Cu")
		(net "M_I_CPU0_SB_CB<7>")
	)
	(segment
		(start 414.804098 -274.08886)
		(end 414.965642 -274.250404)
		(width 0.14478)
		(layer "In2.Cu")
		(net "M_I_CPU0_SB_CB<7>")
	)
	(segment
		(start 392.24712 -270.529558)
		(end 392.257534 -270.523462)
		(width 0.0889)
		(layer "In2.Cu")
		(net "M_I_CPU0_SB_CB<7>")
	)
	(segment
		(start 380.037848 -270.523462)
		(end 380.04623 -270.518636)
		(width 0.0889)
		(layer "In2.Cu")
		(net "M_I_CPU0_SB_CB<7>")
	)
	(segment
		(start 414.804098 -274.031456)
		(end 414.804098 -274.08886)
		(width 0.14478)
		(layer "In2.Cu")
		(net "M_I_CPU0_SB_CB<7>")
	)
	(segment
		(start 419.090348 -273.928332)
		(end 419.41242 -274.250404)
		(width 0.14478)
		(layer "In2.Cu")
		(net "M_I_CPU0_SB_CB<7>")
	)
	(segment
		(start 421.953436 -273.869912)
		(end 422.181782 -273.869912)
		(width 0.14478)
		(layer "In2.Cu")
		(net "M_I_CPU0_SB_CB<7>")
	)
	(segment
		(start 425.723558 -274.250404)
		(end 425.96054 -274.250404)
		(width 0.14478)
		(layer "In2.Cu")
		(net "M_I_CPU0_SB_CB<7>")
	)
	(segment
		(start 410.656024 -274.404074)
		(end 410.7434 -274.614894)
		(width 0.14478)
		(layer "In2.Cu")
		(net "M_I_CPU0_SB_CB<7>")
	)
	(segment
		(start 410.825188 -273.995642)
		(end 410.656024 -274.404074)
		(width 0.14478)
		(layer "In2.Cu")
		(net "M_I_CPU0_SB_CB<7>")
	)
	(segment
		(start 410.954728 -274.702524)
		(end 411.165548 -274.615148)
		(width 0.14478)
		(layer "In2.Cu")
		(net "M_I_CPU0_SB_CB<7>")
	)
	(segment
		(start 376.310906 -270.580612)
		(end 376.333258 -270.4973)
		(width 0.0889)
		(layer "In2.Cu")
		(net "M_I_CPU0_SB_CB<7>")
	)
	(segment
		(start 421.240458 -274.411948)
		(end 421.240458 -274.469352)
		(width 0.14478)
		(layer "In2.Cu")
		(net "M_I_CPU0_SB_CB<7>")
	)
	(segment
		(start 418.860986 -273.928332)
		(end 419.090348 -273.928332)
		(width 0.14478)
		(layer "In2.Cu")
		(net "M_I_CPU0_SB_CB<7>")
	)
	(segment
		(start 414.965642 -274.250404)
		(end 417.436046 -274.250404)
		(width 0.14478)
		(layer "In2.Cu")
		(net "M_I_CPU0_SB_CB<7>")
	)
	(segment
		(start 414.252664 -274.469352)
		(end 414.252664 -274.031456)
		(width 0.14478)
		(layer "In2.Cu")
		(net "M_I_CPU0_SB_CB<7>")
	)
	(segment
		(start 404.788116 -268.67993)
		(end 409.296108 -273.187922)
		(width 0.14478)
		(layer "In2.Cu")
		(net "M_I_CPU0_SB_CB<7>")
	)
	(segment
		(start 422.50487 -274.250404)
		(end 424.857672 -274.250404)
		(width 0.14478)
		(layer "In2.Cu")
		(net "M_I_CPU0_SB_CB<7>")
	)
	(segment
		(start 391.317734 -270.523462)
		(end 391.326116 -270.518636)
		(width 0.0889)
		(layer "In2.Cu")
		(net "M_I_CPU0_SB_CB<7>")
	)
	(segment
		(start 421.791892 -274.469352)
		(end 421.791892 -274.031456)
		(width 0.14478)
		(layer "In2.Cu")
		(net "M_I_CPU0_SB_CB<7>")
	)
	(segment
		(start 417.436046 -274.250404)
		(end 417.758118 -273.928332)
		(width 0.14478)
		(layer "In2.Cu")
		(net "M_I_CPU0_SB_CB<7>")
	)
	(segment
		(start 411.165548 -274.615148)
		(end 411.334712 -274.206716)
		(width 0.14478)
		(layer "In2.Cu")
		(net "M_I_CPU0_SB_CB<7>")
	)
	(segment
		(start 414.414208 -273.869912)
		(end 414.642554 -273.869912)
		(width 0.14478)
		(layer "In2.Cu")
		(net "M_I_CPU0_SB_CB<7>")
	)
	(segment
		(start 411.545532 -274.11934)
		(end 411.861254 -274.250404)
		(width 0.14478)
		(layer "In2.Cu")
		(net "M_I_CPU0_SB_CB<7>")
	)
	(segment
		(start 426.511974 -273.935952)
		(end 426.826426 -274.250404)
		(width 0.14478)
		(layer "In2.Cu")
		(net "M_I_CPU0_SB_CB<7>")
	)
	(segment
		(start 410.737812 -273.784822)
		(end 410.825188 -273.995642)
		(width 0.14478)
		(layer "In2.Cu")
		(net "M_I_CPU0_SB_CB<7>")
	)
	(segment
		(start 422.343326 -274.08886)
		(end 422.50487 -274.250404)
		(width 0.14478)
		(layer "In2.Cu")
		(net "M_I_CPU0_SB_CB<7>")
	)
	(segment
		(start 421.630348 -274.630896)
		(end 421.791892 -274.469352)
		(width 0.14478)
		(layer "In2.Cu")
		(net "M_I_CPU0_SB_CB<7>")
	)
	(segment
		(start 411.334712 -274.206716)
		(end 411.545532 -274.11934)
		(width 0.14478)
		(layer "In2.Cu")
		(net "M_I_CPU0_SB_CB<7>")
	)
	(segment
		(start 414.642554 -273.869912)
		(end 414.804098 -274.031456)
		(width 0.14478)
		(layer "In2.Cu")
		(net "M_I_CPU0_SB_CB<7>")
	)
	(segment
		(start 413.31134 -273.869912)
		(end 413.539686 -273.869912)
		(width 0.14478)
		(layer "In2.Cu")
		(net "M_I_CPU0_SB_CB<7>")
	)
	(segment
		(start 413.149796 -274.031456)
		(end 413.31134 -273.869912)
		(width 0.14478)
		(layer "In2.Cu")
		(net "M_I_CPU0_SB_CB<7>")
	)
	(segment
		(start 376.46483 -270.846042)
		(end 376.310906 -270.580612)
		(width 0.0889)
		(layer "In2.Cu")
		(net "M_I_CPU0_SB_CB<7>")
	)
	(segment
		(start 417.758118 -273.928332)
		(end 417.98748 -273.928332)
		(width 0.14478)
		(layer "In2.Cu")
		(net "M_I_CPU0_SB_CB<7>")
	)
	(segment
		(start 393.634976 -269.732506)
		(end 393.732766 -269.67561)
		(width 0.0889)
		(layer "In2.Cu")
		(net "M_I_CPU0_SB_CB<7>")
	)
	(segment
		(start 395.371574 -268.83741)
		(end 395.529054 -268.67993)
		(width 0.0889)
		(layer "In2.Cu")
		(net "M_I_CPU0_SB_CB<7>")
	)
	(segment
		(start 386.983478 -270.518636)
		(end 386.99186 -270.523462)
		(width 0.0889)
		(layer "In2.Cu")
		(net "M_I_CPU0_SB_CB<7>")
	)
	(segment
		(start 378.5235 -270.518636)
		(end 378.531882 -270.523462)
		(width 0.0889)
		(layer "In2.Cu")
		(net "M_I_CPU0_SB_CB<7>")
	)
	(segment
		(start 418.538914 -274.250404)
		(end 418.860986 -273.928332)
		(width 0.14478)
		(layer "In2.Cu")
		(net "M_I_CPU0_SB_CB<7>")
	)
	(segment
		(start 393.761722 -269.65529)
		(end 394.579602 -268.83741)
		(width 0.0889)
		(layer "In2.Cu")
		(net "M_I_CPU0_SB_CB<7>")
	)
	(segment
		(start 377.583446 -270.518636)
		(end 377.591828 -270.523462)
		(width 0.0889)
		(layer "In2.Cu")
		(net "M_I_CPU0_SB_CB<7>")
	)
	(segment
		(start 410.7434 -274.614894)
		(end 410.954728 -274.702524)
		(width 0.14478)
		(layer "In2.Cu")
		(net "M_I_CPU0_SB_CB<7>")
	)
	(segment
		(start 417.98748 -273.928332)
		(end 418.309552 -274.250404)
		(width 0.14478)
		(layer "In2.Cu")
		(net "M_I_CPU0_SB_CB<7>")
	)
	(segment
		(start 425.172124 -273.935952)
		(end 425.409106 -273.935952)
		(width 0.14478)
		(layer "In2.Cu")
		(net "M_I_CPU0_SB_CB<7>")
	)
	(segment
		(start 427.021498 -274.250404)
		(end 427.456092 -274.684998)
		(width 0.14478)
		(layer "In2.Cu")
		(net "M_I_CPU0_SB_CB<7>")
	)
	(arc
		(start 384.737864 -270.523462)
		(mid 384.924808 -270.473207)
		(end 385.111752 -270.523462)
		(width 0.0889)
		(layer "In2.Cu")
		(net "M_I_CPU0_SB_CB<7>")
	)
	(arc
		(start 386.99186 -270.523462)
		(mid 387.274816 -270.599639)
		(end 387.557772 -270.523462)
		(width 0.0889)
		(layer "In2.Cu")
		(net "M_I_CPU0_SB_CB<7>")
	)
	(arc
		(start 392.641836 -270.530066)
		(mid 392.920522 -270.60035)
		(end 393.197588 -270.52397)
		(width 0.0889)
		(layer "In2.Cu")
		(net "M_I_CPU0_SB_CB<7>")
	)
	(arc
		(start 382.291844 -270.523462)
		(mid 382.5748 -270.599639)
		(end 382.857756 -270.523462)
		(width 0.0889)
		(layer "In2.Cu")
		(net "M_I_CPU0_SB_CB<7>")
	)
	(arc
		(start 385.111752 -270.523462)
		(mid 385.394708 -270.599639)
		(end 385.677664 -270.523462)
		(width 0.0889)
		(layer "In2.Cu")
		(net "M_I_CPU0_SB_CB<7>")
	)
	(arc
		(start 382.866138 -270.518636)
		(mid 383.049646 -270.473142)
		(end 383.231898 -270.523462)
		(width 0.0889)
		(layer "In2.Cu")
		(net "M_I_CPU0_SB_CB<7>")
	)
	(arc
		(start 393.480036 -270.03629)
		(mid 393.520944 -269.865743)
		(end 393.634976 -269.732506)
		(width 0.0889)
		(layer "In2.Cu")
		(net "M_I_CPU0_SB_CB<7>")
	)
	(arc
		(start 388.506208 -270.518636)
		(mid 388.689716 -270.473142)
		(end 388.871968 -270.523462)
		(width 0.0889)
		(layer "In2.Cu")
		(net "M_I_CPU0_SB_CB<7>")
	)
	(arc
		(start 392.257534 -270.523462)
		(mid 392.435669 -270.473311)
		(end 392.615928 -270.51508)
		(width 0.0889)
		(layer "In2.Cu")
		(net "M_I_CPU0_SB_CB<7>")
	)
	(arc
		(start 379.471936 -270.523462)
		(mid 379.754892 -270.599639)
		(end 380.037848 -270.523462)
		(width 0.0889)
		(layer "In2.Cu")
		(net "M_I_CPU0_SB_CB<7>")
	)
	(arc
		(start 385.677664 -270.523462)
		(mid 385.859915 -270.473112)
		(end 386.043424 -270.518636)
		(width 0.0889)
		(layer "In2.Cu")
		(net "M_I_CPU0_SB_CB<7>")
	)
	(arc
		(start 376.333258 -270.4973)
		(mid 376.495447 -270.474565)
		(end 376.651774 -270.523462)
		(width 0.0889)
		(layer "In2.Cu")
		(net "M_I_CPU0_SB_CB<7>")
	)
	(arc
		(start 384.171952 -270.523462)
		(mid 384.454908 -270.599639)
		(end 384.737864 -270.523462)
		(width 0.0889)
		(layer "In2.Cu")
		(net "M_I_CPU0_SB_CB<7>")
	)
	(arc
		(start 387.566154 -270.518636)
		(mid 387.749662 -270.473142)
		(end 387.931914 -270.523462)
		(width 0.0889)
		(layer "In2.Cu")
		(net "M_I_CPU0_SB_CB<7>")
	)
	(arc
		(start 387.931914 -270.523462)
		(mid 388.21487 -270.599639)
		(end 388.497826 -270.523462)
		(width 0.0889)
		(layer "In2.Cu")
		(net "M_I_CPU0_SB_CB<7>")
	)
	(arc
		(start 377.591828 -270.523462)
		(mid 377.874784 -270.599639)
		(end 378.15774 -270.523462)
		(width 0.0889)
		(layer "In2.Cu")
		(net "M_I_CPU0_SB_CB<7>")
	)
	(arc
		(start 383.231898 -270.523462)
		(mid 383.514854 -270.599639)
		(end 383.79781 -270.523462)
		(width 0.0889)
		(layer "In2.Cu")
		(net "M_I_CPU0_SB_CB<7>")
	)
	(arc
		(start 388.871968 -270.523462)
		(mid 389.154924 -270.599639)
		(end 389.43788 -270.523462)
		(width 0.0889)
		(layer "In2.Cu")
		(net "M_I_CPU0_SB_CB<7>")
	)
	(arc
		(start 381.917702 -270.523462)
		(mid 382.099953 -270.473112)
		(end 382.283462 -270.518636)
		(width 0.0889)
		(layer "In2.Cu")
		(net "M_I_CPU0_SB_CB<7>")
	)
	(arc
		(start 391.691876 -270.523462)
		(mid 391.968689 -270.599605)
		(end 392.24712 -270.529558)
		(width 0.0889)
		(layer "In2.Cu")
		(net "M_I_CPU0_SB_CB<7>")
	)
	(arc
		(start 380.04623 -270.518636)
		(mid 380.229738 -270.473142)
		(end 380.41199 -270.523462)
		(width 0.0889)
		(layer "In2.Cu")
		(net "M_I_CPU0_SB_CB<7>")
	)
	(arc
		(start 376.651774 -270.523462)
		(mid 376.93473 -270.599639)
		(end 377.217686 -270.523462)
		(width 0.0889)
		(layer "In2.Cu")
		(net "M_I_CPU0_SB_CB<7>")
	)
	(arc
		(start 389.43788 -270.523462)
		(mid 389.624824 -270.473207)
		(end 389.811768 -270.523462)
		(width 0.0889)
		(layer "In2.Cu")
		(net "M_I_CPU0_SB_CB<7>")
	)
	(arc
		(start 378.15774 -270.523462)
		(mid 378.339991 -270.473112)
		(end 378.5235 -270.518636)
		(width 0.0889)
		(layer "In2.Cu")
		(net "M_I_CPU0_SB_CB<7>")
	)
	(arc
		(start 390.37768 -270.523462)
		(mid 390.559931 -270.473112)
		(end 390.74344 -270.518636)
		(width 0.0889)
		(layer "In2.Cu")
		(net "M_I_CPU0_SB_CB<7>")
	)
	(arc
		(start 389.811768 -270.523462)
		(mid 390.094724 -270.599639)
		(end 390.37768 -270.523462)
		(width 0.0889)
		(layer "In2.Cu")
		(net "M_I_CPU0_SB_CB<7>")
	)
	(arc
		(start 379.106176 -270.518636)
		(mid 379.289684 -270.473142)
		(end 379.471936 -270.523462)
		(width 0.0889)
		(layer "In2.Cu")
		(net "M_I_CPU0_SB_CB<7>")
	)
	(arc
		(start 390.751822 -270.523462)
		(mid 391.034778 -270.599639)
		(end 391.317734 -270.523462)
		(width 0.0889)
		(layer "In2.Cu")
		(net "M_I_CPU0_SB_CB<7>")
	)
	(arc
		(start 391.326116 -270.518636)
		(mid 391.509624 -270.473142)
		(end 391.691876 -270.523462)
		(width 0.0889)
		(layer "In2.Cu")
		(net "M_I_CPU0_SB_CB<7>")
	)
	(arc
		(start 380.977902 -270.523462)
		(mid 381.164846 -270.473207)
		(end 381.35179 -270.523462)
		(width 0.0889)
		(layer "In2.Cu")
		(net "M_I_CPU0_SB_CB<7>")
	)
	(arc
		(start 386.051806 -270.523462)
		(mid 386.334762 -270.599639)
		(end 386.617718 -270.523462)
		(width 0.0889)
		(layer "In2.Cu")
		(net "M_I_CPU0_SB_CB<7>")
	)
	(arc
		(start 381.35179 -270.523462)
		(mid 381.634746 -270.599639)
		(end 381.917702 -270.523462)
		(width 0.0889)
		(layer "In2.Cu")
		(net "M_I_CPU0_SB_CB<7>")
	)
	(arc
		(start 383.806192 -270.518636)
		(mid 383.9897 -270.473142)
		(end 384.171952 -270.523462)
		(width 0.0889)
		(layer "In2.Cu")
		(net "M_I_CPU0_SB_CB<7>")
	)
	(arc
		(start 378.531882 -270.523462)
		(mid 378.814838 -270.599639)
		(end 379.097794 -270.523462)
		(width 0.0889)
		(layer "In2.Cu")
		(net "M_I_CPU0_SB_CB<7>")
	)
	(arc
		(start 380.41199 -270.523462)
		(mid 380.694946 -270.599639)
		(end 380.977902 -270.523462)
		(width 0.0889)
		(layer "In2.Cu")
		(net "M_I_CPU0_SB_CB<7>")
	)
	(arc
		(start 393.242292 -270.497808)
		(mid 393.417272 -270.295942)
		(end 393.480036 -270.03629)
		(width 0.0889)
		(layer "In2.Cu")
		(net "M_I_CPU0_SB_CB<7>")
	)
	(arc
		(start 386.617718 -270.523462)
		(mid 386.799969 -270.473112)
		(end 386.983478 -270.518636)
		(width 0.0889)
		(layer "In2.Cu")
		(net "M_I_CPU0_SB_CB<7>")
	)
	(arc
		(start 377.217686 -270.523462)
		(mid 377.399937 -270.473112)
		(end 377.583446 -270.518636)
		(width 0.0889)
		(layer "In2.Cu")
		(net "M_I_CPU0_SB_CB<7>")
	)
	(segment
		(start 377.407932 -269.770098)
		(end 377.874784 -270.036036)
		(width 0.10668)
		(layer "F.Cu")
		(net "M_I_CPU0_SB_CB<6>")
	)
	(segment
		(start 423.099738 -272.560034)
		(end 424.996102 -272.560034)
		(width 0.14478)
		(layer "In2.Cu")
		(net "M_I_CPU0_SB_CB<6>")
	)
	(segment
		(start 420.756842 -272.560034)
		(end 421.126158 -272.92935)
		(width 0.14478)
		(layer "In2.Cu")
		(net "M_I_CPU0_SB_CB<6>")
	)
	(segment
		(start 408.224482 -270.844264)
		(end 408.436318 -270.844264)
		(width 0.14478)
		(layer "In2.Cu")
		(net "M_I_CPU0_SB_CB<6>")
	)
	(segment
		(start 409.192222 -270.667226)
		(end 409.192222 -270.879062)
		(width 0.14478)
		(layer "In2.Cu")
		(net "M_I_CPU0_SB_CB<6>")
	)
	(segment
		(start 389.90778 -269.713456)
		(end 389.916162 -269.70863)
		(width 0.0889)
		(layer "In2.Cu")
		(net "M_I_CPU0_SB_CB<6>")
	)
	(segment
		(start 409.01493 -271.634712)
		(end 409.226766 -271.634712)
		(width 0.14478)
		(layer "In2.Cu")
		(net "M_I_CPU0_SB_CB<6>")
	)
	(segment
		(start 408.436318 -270.844264)
		(end 408.796998 -270.484092)
		(width 0.14478)
		(layer "In2.Cu")
		(net "M_I_CPU0_SB_CB<6>")
	)
	(segment
		(start 389.333486 -269.70863)
		(end 389.341868 -269.713456)
		(width 0.0889)
		(layer "In2.Cu")
		(net "M_I_CPU0_SB_CB<6>")
	)
	(segment
		(start 409.805378 -272.42516)
		(end 410.017214 -272.42516)
		(width 0.14478)
		(layer "In2.Cu")
		(net "M_I_CPU0_SB_CB<6>")
	)
	(segment
		(start 408.831542 -271.239742)
		(end 408.831542 -271.451324)
		(width 0.14478)
		(layer "In2.Cu")
		(net "M_I_CPU0_SB_CB<6>")
	)
	(segment
		(start 406.643586 -269.263368)
		(end 406.855676 -269.263368)
		(width 0.14478)
		(layer "In2.Cu")
		(net "M_I_CPU0_SB_CB<6>")
	)
	(segment
		(start 413.71393 -272.16481)
		(end 414.009586 -272.16481)
		(width 0.14478)
		(layer "In2.Cu")
		(net "M_I_CPU0_SB_CB<6>")
	)
	(segment
		(start 409.009088 -270.484092)
		(end 409.192222 -270.667226)
		(width 0.14478)
		(layer "In2.Cu")
		(net "M_I_CPU0_SB_CB<6>")
	)
	(segment
		(start 408.041094 -270.660876)
		(end 408.224482 -270.844264)
		(width 0.14478)
		(layer "In2.Cu")
		(net "M_I_CPU0_SB_CB<6>")
	)
	(segment
		(start 408.101038 -269.810738)
		(end 408.284426 -269.994126)
		(width 0.14478)
		(layer "In2.Cu")
		(net "M_I_CPU0_SB_CB<6>")
	)
	(segment
		(start 383.693416 -269.70863)
		(end 383.701798 -269.713456)
		(width 0.0889)
		(layer "In2.Cu")
		(net "M_I_CPU0_SB_CB<6>")
	)
	(segment
		(start 379.933454 -269.70863)
		(end 379.941836 -269.713456)
		(width 0.0889)
		(layer "In2.Cu")
		(net "M_I_CPU0_SB_CB<6>")
	)
	(segment
		(start 394.754354 -267.76045)
		(end 395.427454 -267.76045)
		(width 0.0889)
		(layer "In2.Cu")
		(net "M_I_CPU0_SB_CB<6>")
	)
	(segment
		(start 409.705048 -271.157192)
		(end 409.91663 -271.157192)
		(width 0.14478)
		(layer "In2.Cu")
		(net "M_I_CPU0_SB_CB<6>")
	)
	(segment
		(start 414.009586 -272.16481)
		(end 414.27273 -272.427954)
		(width 0.14478)
		(layer "In2.Cu")
		(net "M_I_CPU0_SB_CB<6>")
	)
	(segment
		(start 410.017214 -272.42516)
		(end 410.332936 -272.109946)
		(width 0.14478)
		(layer "In2.Cu")
		(net "M_I_CPU0_SB_CB<6>")
	)
	(segment
		(start 394.166344 -268.34846)
		(end 394.754354 -267.76045)
		(width 0.0889)
		(layer "In2.Cu")
		(net "M_I_CPU0_SB_CB<6>")
	)
	(segment
		(start 409.91663 -271.157192)
		(end 410.100018 -271.34058)
		(width 0.14478)
		(layer "In2.Cu")
		(net "M_I_CPU0_SB_CB<6>")
	)
	(segment
		(start 388.393432 -269.70863)
		(end 388.401814 -269.713456)
		(width 0.0889)
		(layer "In2.Cu")
		(net "M_I_CPU0_SB_CB<6>")
	)
	(segment
		(start 408.831542 -271.451324)
		(end 409.01493 -271.634712)
		(width 0.14478)
		(layer "In2.Cu")
		(net "M_I_CPU0_SB_CB<6>")
	)
	(segment
		(start 421.59936 -272.744692)
		(end 421.59936 -272.375376)
		(width 0.14478)
		(layer "In2.Cu")
		(net "M_I_CPU0_SB_CB<6>")
	)
	(segment
		(start 392.153394 -269.70863)
		(end 392.161776 -269.713456)
		(width 0.0889)
		(layer "In2.Cu")
		(net "M_I_CPU0_SB_CB<6>")
	)
	(segment
		(start 409.62199 -272.03019)
		(end 409.62199 -272.241772)
		(width 0.14478)
		(layer "In2.Cu")
		(net "M_I_CPU0_SB_CB<6>")
	)
	(segment
		(start 385.207764 -269.713456)
		(end 385.216146 -269.70863)
		(width 0.0889)
		(layer "In2.Cu")
		(net "M_I_CPU0_SB_CB<6>")
	)
	(segment
		(start 407.376884 -269.320772)
		(end 407.376884 -269.532608)
		(width 0.14478)
		(layer "In2.Cu")
		(net "M_I_CPU0_SB_CB<6>")
	)
	(segment
		(start 414.83153 -272.16481)
		(end 415.127186 -272.16481)
		(width 0.14478)
		(layer "In2.Cu")
		(net "M_I_CPU0_SB_CB<6>")
	)
	(segment
		(start 426.113702 -272.560034)
		(end 426.381926 -272.29181)
		(width 0.14478)
		(layer "In2.Cu")
		(net "M_I_CPU0_SB_CB<6>")
	)
	(segment
		(start 415.127186 -272.16481)
		(end 415.52241 -272.560034)
		(width 0.14478)
		(layer "In2.Cu")
		(net "M_I_CPU0_SB_CB<6>")
	)
	(segment
		(start 407.889202 -269.810738)
		(end 408.101038 -269.810738)
		(width 0.14478)
		(layer "In2.Cu")
		(net "M_I_CPU0_SB_CB<6>")
	)
	(segment
		(start 408.041094 -270.449294)
		(end 408.041094 -270.660876)
		(width 0.14478)
		(layer "In2.Cu")
		(net "M_I_CPU0_SB_CB<6>")
	)
	(segment
		(start 408.284426 -269.994126)
		(end 408.284426 -270.205962)
		(width 0.14478)
		(layer "In2.Cu")
		(net "M_I_CPU0_SB_CB<6>")
	)
	(segment
		(start 407.646124 -270.053816)
		(end 407.889202 -269.810738)
		(width 0.14478)
		(layer "In2.Cu")
		(net "M_I_CPU0_SB_CB<6>")
	)
	(segment
		(start 426.381926 -272.29181)
		(end 426.762926 -272.29181)
		(width 0.14478)
		(layer "In2.Cu")
		(net "M_I_CPU0_SB_CB<6>")
	)
	(segment
		(start 392.71702 -269.719552)
		(end 392.727434 -269.713456)
		(width 0.0889)
		(layer "In2.Cu")
		(net "M_I_CPU0_SB_CB<6>")
	)
	(segment
		(start 421.59936 -272.375376)
		(end 421.784018 -272.190718)
		(width 0.14478)
		(layer "In2.Cu")
		(net "M_I_CPU0_SB_CB<6>")
	)
	(segment
		(start 424.996102 -272.560034)
		(end 425.264326 -272.29181)
		(width 0.14478)
		(layer "In2.Cu")
		(net "M_I_CPU0_SB_CB<6>")
	)
	(segment
		(start 422.25722 -272.375376)
		(end 422.25722 -272.744692)
		(width 0.14478)
		(layer "In2.Cu")
		(net "M_I_CPU0_SB_CB<6>")
	)
	(segment
		(start 386.147818 -269.713456)
		(end 386.1562 -269.70863)
		(width 0.0889)
		(layer "In2.Cu")
		(net "M_I_CPU0_SB_CB<6>")
	)
	(segment
		(start 425.264326 -272.29181)
		(end 425.554902 -272.29181)
		(width 0.14478)
		(layer "In2.Cu")
		(net "M_I_CPU0_SB_CB<6>")
	)
	(segment
		(start 405.140668 -267.76045)
		(end 406.643586 -269.263368)
		(width 0.14478)
		(layer "In2.Cu")
		(net "M_I_CPU0_SB_CB<6>")
	)
	(segment
		(start 407.376884 -269.532608)
		(end 407.250646 -269.658846)
		(width 0.14478)
		(layer "In2.Cu")
		(net "M_I_CPU0_SB_CB<6>")
	)
	(segment
		(start 409.62199 -272.241772)
		(end 409.805378 -272.42516)
		(width 0.14478)
		(layer "In2.Cu")
		(net "M_I_CPU0_SB_CB<6>")
	)
	(segment
		(start 421.126158 -272.92935)
		(end 421.414702 -272.92935)
		(width 0.14478)
		(layer "In2.Cu")
		(net "M_I_CPU0_SB_CB<6>")
	)
	(segment
		(start 377.72086 -269.770606)
		(end 377.743212 -269.687294)
		(width 0.0889)
		(layer "In2.Cu")
		(net "M_I_CPU0_SB_CB<6>")
	)
	(segment
		(start 422.441878 -272.92935)
		(end 422.730422 -272.92935)
		(width 0.14478)
		(layer "In2.Cu")
		(net "M_I_CPU0_SB_CB<6>")
	)
	(segment
		(start 407.193496 -269.137384)
		(end 407.376884 -269.320772)
		(width 0.14478)
		(layer "In2.Cu")
		(net "M_I_CPU0_SB_CB<6>")
	)
	(segment
		(start 421.414702 -272.92935)
		(end 421.59936 -272.744692)
		(width 0.14478)
		(layer "In2.Cu")
		(net "M_I_CPU0_SB_CB<6>")
	)
	(segment
		(start 392.727688 -269.713456)
		(end 392.766804 -269.690596)
		(width 0.0889)
		(layer "In2.Cu")
		(net "M_I_CPU0_SB_CB<6>")
	)
	(segment
		(start 409.192222 -270.879062)
		(end 408.831542 -271.239742)
		(width 0.14478)
		(layer "In2.Cu")
		(net "M_I_CPU0_SB_CB<6>")
	)
	(segment
		(start 421.784018 -272.190718)
		(end 422.072562 -272.190718)
		(width 0.14478)
		(layer "In2.Cu")
		(net "M_I_CPU0_SB_CB<6>")
	)
	(segment
		(start 407.434034 -270.053816)
		(end 407.646124 -270.053816)
		(width 0.14478)
		(layer "In2.Cu")
		(net "M_I_CPU0_SB_CB<6>")
	)
	(segment
		(start 408.796998 -270.484092)
		(end 409.009088 -270.484092)
		(width 0.14478)
		(layer "In2.Cu")
		(net "M_I_CPU0_SB_CB<6>")
	)
	(segment
		(start 407.250646 -269.658846)
		(end 407.250646 -269.870428)
		(width 0.14478)
		(layer "In2.Cu")
		(net "M_I_CPU0_SB_CB<6>")
	)
	(segment
		(start 393.197842 -268.90345)
		(end 394.166344 -268.34846)
		(width 0.0889)
		(layer "In2.Cu")
		(net "M_I_CPU0_SB_CB<6>")
	)
	(segment
		(start 410.544518 -272.109946)
		(end 410.994606 -272.560034)
		(width 0.14478)
		(layer "In2.Cu")
		(net "M_I_CPU0_SB_CB<6>")
	)
	(segment
		(start 414.27273 -272.427954)
		(end 414.568386 -272.427954)
		(width 0.14478)
		(layer "In2.Cu")
		(net "M_I_CPU0_SB_CB<6>")
	)
	(segment
		(start 406.98166 -269.137384)
		(end 407.193496 -269.137384)
		(width 0.14478)
		(layer "In2.Cu")
		(net "M_I_CPU0_SB_CB<6>")
	)
	(segment
		(start 384.63347 -269.70863)
		(end 384.641852 -269.713456)
		(width 0.0889)
		(layer "In2.Cu")
		(net "M_I_CPU0_SB_CB<6>")
	)
	(segment
		(start 392.727434 -269.713456)
		(end 392.727688 -269.713456)
		(width 0.0889)
		(layer "In2.Cu")
		(net "M_I_CPU0_SB_CB<6>")
	)
	(segment
		(start 380.873508 -269.70863)
		(end 380.88189 -269.713456)
		(width 0.0889)
		(layer "In2.Cu")
		(net "M_I_CPU0_SB_CB<6>")
	)
	(segment
		(start 406.855676 -269.263368)
		(end 406.98166 -269.137384)
		(width 0.14478)
		(layer "In2.Cu")
		(net "M_I_CPU0_SB_CB<6>")
	)
	(segment
		(start 422.072562 -272.190718)
		(end 422.25722 -272.375376)
		(width 0.14478)
		(layer "In2.Cu")
		(net "M_I_CPU0_SB_CB<6>")
	)
	(segment
		(start 395.427454 -267.76045)
		(end 405.140668 -267.76045)
		(width 0.14478)
		(layer "In2.Cu")
		(net "M_I_CPU0_SB_CB<6>")
	)
	(segment
		(start 415.52241 -272.560034)
		(end 420.756842 -272.560034)
		(width 0.14478)
		(layer "In2.Cu")
		(net "M_I_CPU0_SB_CB<6>")
	)
	(segment
		(start 410.332936 -272.109946)
		(end 410.544518 -272.109946)
		(width 0.14478)
		(layer "In2.Cu")
		(net "M_I_CPU0_SB_CB<6>")
	)
	(segment
		(start 377.874784 -270.036036)
		(end 377.72086 -269.770606)
		(width 0.0889)
		(layer "In2.Cu")
		(net "M_I_CPU0_SB_CB<6>")
	)
	(segment
		(start 409.226766 -271.634712)
		(end 409.705048 -271.157192)
		(width 0.14478)
		(layer "In2.Cu")
		(net "M_I_CPU0_SB_CB<6>")
	)
	(segment
		(start 410.100018 -271.34058)
		(end 410.100018 -271.552162)
		(width 0.14478)
		(layer "In2.Cu")
		(net "M_I_CPU0_SB_CB<6>")
	)
	(segment
		(start 425.823126 -272.560034)
		(end 426.113702 -272.560034)
		(width 0.14478)
		(layer "In2.Cu")
		(net "M_I_CPU0_SB_CB<6>")
	)
	(segment
		(start 422.25722 -272.744692)
		(end 422.441878 -272.92935)
		(width 0.14478)
		(layer "In2.Cu")
		(net "M_I_CPU0_SB_CB<6>")
	)
	(segment
		(start 408.284426 -270.205962)
		(end 408.041094 -270.449294)
		(width 0.14478)
		(layer "In2.Cu")
		(net "M_I_CPU0_SB_CB<6>")
	)
	(segment
		(start 381.447802 -269.713456)
		(end 381.456184 -269.70863)
		(width 0.0889)
		(layer "In2.Cu")
		(net "M_I_CPU0_SB_CB<6>")
	)
	(segment
		(start 414.568386 -272.427954)
		(end 414.83153 -272.16481)
		(width 0.14478)
		(layer "In2.Cu")
		(net "M_I_CPU0_SB_CB<6>")
	)
	(segment
		(start 393.166092 -268.921738)
		(end 393.197842 -268.90345)
		(width 0.0889)
		(layer "In2.Cu")
		(net "M_I_CPU0_SB_CB<6>")
	)
	(segment
		(start 410.100018 -271.552162)
		(end 409.62199 -272.03019)
		(width 0.14478)
		(layer "In2.Cu")
		(net "M_I_CPU0_SB_CB<6>")
	)
	(segment
		(start 422.730422 -272.92935)
		(end 423.099738 -272.560034)
		(width 0.14478)
		(layer "In2.Cu")
		(net "M_I_CPU0_SB_CB<6>")
	)
	(segment
		(start 407.250646 -269.870428)
		(end 407.434034 -270.053816)
		(width 0.14478)
		(layer "In2.Cu")
		(net "M_I_CPU0_SB_CB<6>")
	)
	(segment
		(start 410.994606 -272.560034)
		(end 413.318706 -272.560034)
		(width 0.14478)
		(layer "In2.Cu")
		(net "M_I_CPU0_SB_CB<6>")
	)
	(segment
		(start 426.762926 -272.29181)
		(end 427.456092 -272.984976)
		(width 0.14478)
		(layer "In2.Cu")
		(net "M_I_CPU0_SB_CB<6>")
	)
	(segment
		(start 425.554902 -272.29181)
		(end 425.823126 -272.560034)
		(width 0.14478)
		(layer "In2.Cu")
		(net "M_I_CPU0_SB_CB<6>")
	)
	(segment
		(start 413.318706 -272.560034)
		(end 413.71393 -272.16481)
		(width 0.14478)
		(layer "In2.Cu")
		(net "M_I_CPU0_SB_CB<6>")
	)
	(arc
		(start 378.061982 -269.713456)
		(mid 378.344938 -269.789633)
		(end 378.627894 -269.713456)
		(width 0.0889)
		(layer "In2.Cu")
		(net "M_I_CPU0_SB_CB<6>")
	)
	(arc
		(start 386.1562 -269.70863)
		(mid 386.339708 -269.663136)
		(end 386.52196 -269.713456)
		(width 0.0889)
		(layer "In2.Cu")
		(net "M_I_CPU0_SB_CB<6>")
	)
	(arc
		(start 390.847834 -269.713456)
		(mid 391.034778 -269.663201)
		(end 391.221722 -269.713456)
		(width 0.0889)
		(layer "In2.Cu")
		(net "M_I_CPU0_SB_CB<6>")
	)
	(arc
		(start 392.766804 -269.690596)
		(mid 392.945617 -269.488246)
		(end 393.010136 -269.22603)
		(width 0.0889)
		(layer "In2.Cu")
		(net "M_I_CPU0_SB_CB<6>")
	)
	(arc
		(start 381.821944 -269.713456)
		(mid 382.1049 -269.789633)
		(end 382.387856 -269.713456)
		(width 0.0889)
		(layer "In2.Cu")
		(net "M_I_CPU0_SB_CB<6>")
	)
	(arc
		(start 381.456184 -269.70863)
		(mid 381.639692 -269.663136)
		(end 381.821944 -269.713456)
		(width 0.0889)
		(layer "In2.Cu")
		(net "M_I_CPU0_SB_CB<6>")
	)
	(arc
		(start 380.88189 -269.713456)
		(mid 381.164846 -269.789633)
		(end 381.447802 -269.713456)
		(width 0.0889)
		(layer "In2.Cu")
		(net "M_I_CPU0_SB_CB<6>")
	)
	(arc
		(start 378.627894 -269.713456)
		(mid 378.814838 -269.663201)
		(end 379.001782 -269.713456)
		(width 0.0889)
		(layer "In2.Cu")
		(net "M_I_CPU0_SB_CB<6>")
	)
	(arc
		(start 388.027672 -269.713456)
		(mid 388.209923 -269.663106)
		(end 388.393432 -269.70863)
		(width 0.0889)
		(layer "In2.Cu")
		(net "M_I_CPU0_SB_CB<6>")
	)
	(arc
		(start 388.967726 -269.713456)
		(mid 389.149977 -269.663106)
		(end 389.333486 -269.70863)
		(width 0.0889)
		(layer "In2.Cu")
		(net "M_I_CPU0_SB_CB<6>")
	)
	(arc
		(start 387.46176 -269.713456)
		(mid 387.744716 -269.789633)
		(end 388.027672 -269.713456)
		(width 0.0889)
		(layer "In2.Cu")
		(net "M_I_CPU0_SB_CB<6>")
	)
	(arc
		(start 379.567694 -269.713456)
		(mid 379.749945 -269.663106)
		(end 379.933454 -269.70863)
		(width 0.0889)
		(layer "In2.Cu")
		(net "M_I_CPU0_SB_CB<6>")
	)
	(arc
		(start 379.001782 -269.713456)
		(mid 379.284738 -269.789633)
		(end 379.567694 -269.713456)
		(width 0.0889)
		(layer "In2.Cu")
		(net "M_I_CPU0_SB_CB<6>")
	)
	(arc
		(start 385.216146 -269.70863)
		(mid 385.399654 -269.663136)
		(end 385.581906 -269.713456)
		(width 0.0889)
		(layer "In2.Cu")
		(net "M_I_CPU0_SB_CB<6>")
	)
	(arc
		(start 390.281922 -269.713456)
		(mid 390.564878 -269.789633)
		(end 390.847834 -269.713456)
		(width 0.0889)
		(layer "In2.Cu")
		(net "M_I_CPU0_SB_CB<6>")
	)
	(arc
		(start 384.26771 -269.713456)
		(mid 384.449961 -269.663106)
		(end 384.63347 -269.70863)
		(width 0.0889)
		(layer "In2.Cu")
		(net "M_I_CPU0_SB_CB<6>")
	)
	(arc
		(start 383.327656 -269.713456)
		(mid 383.509907 -269.663106)
		(end 383.693416 -269.70863)
		(width 0.0889)
		(layer "In2.Cu")
		(net "M_I_CPU0_SB_CB<6>")
	)
	(arc
		(start 386.52196 -269.713456)
		(mid 386.804916 -269.789633)
		(end 387.087872 -269.713456)
		(width 0.0889)
		(layer "In2.Cu")
		(net "M_I_CPU0_SB_CB<6>")
	)
	(arc
		(start 382.387856 -269.713456)
		(mid 382.5748 -269.663201)
		(end 382.761744 -269.713456)
		(width 0.0889)
		(layer "In2.Cu")
		(net "M_I_CPU0_SB_CB<6>")
	)
	(arc
		(start 384.641852 -269.713456)
		(mid 384.924808 -269.789633)
		(end 385.207764 -269.713456)
		(width 0.0889)
		(layer "In2.Cu")
		(net "M_I_CPU0_SB_CB<6>")
	)
	(arc
		(start 382.761744 -269.713456)
		(mid 383.0447 -269.789633)
		(end 383.327656 -269.713456)
		(width 0.0889)
		(layer "In2.Cu")
		(net "M_I_CPU0_SB_CB<6>")
	)
	(arc
		(start 383.701798 -269.713456)
		(mid 383.984754 -269.789633)
		(end 384.26771 -269.713456)
		(width 0.0889)
		(layer "In2.Cu")
		(net "M_I_CPU0_SB_CB<6>")
	)
	(arc
		(start 388.401814 -269.713456)
		(mid 388.68477 -269.789633)
		(end 388.967726 -269.713456)
		(width 0.0889)
		(layer "In2.Cu")
		(net "M_I_CPU0_SB_CB<6>")
	)
	(arc
		(start 379.941836 -269.713456)
		(mid 380.224792 -269.789633)
		(end 380.507748 -269.713456)
		(width 0.0889)
		(layer "In2.Cu")
		(net "M_I_CPU0_SB_CB<6>")
	)
	(arc
		(start 389.916162 -269.70863)
		(mid 390.09967 -269.663136)
		(end 390.281922 -269.713456)
		(width 0.0889)
		(layer "In2.Cu")
		(net "M_I_CPU0_SB_CB<6>")
	)
	(arc
		(start 377.743212 -269.687294)
		(mid 377.905544 -269.664476)
		(end 378.061982 -269.713456)
		(width 0.0889)
		(layer "In2.Cu")
		(net "M_I_CPU0_SB_CB<6>")
	)
	(arc
		(start 391.221722 -269.713456)
		(mid 391.504678 -269.789633)
		(end 391.787634 -269.713456)
		(width 0.0889)
		(layer "In2.Cu")
		(net "M_I_CPU0_SB_CB<6>")
	)
	(arc
		(start 393.010136 -269.22603)
		(mid 393.051391 -269.055059)
		(end 393.166092 -268.921738)
		(width 0.0889)
		(layer "In2.Cu")
		(net "M_I_CPU0_SB_CB<6>")
	)
	(arc
		(start 387.087872 -269.713456)
		(mid 387.274816 -269.663201)
		(end 387.46176 -269.713456)
		(width 0.0889)
		(layer "In2.Cu")
		(net "M_I_CPU0_SB_CB<6>")
	)
	(arc
		(start 391.787634 -269.713456)
		(mid 391.969885 -269.663106)
		(end 392.153394 -269.70863)
		(width 0.0889)
		(layer "In2.Cu")
		(net "M_I_CPU0_SB_CB<6>")
	)
	(arc
		(start 392.161776 -269.713456)
		(mid 392.438589 -269.789599)
		(end 392.71702 -269.719552)
		(width 0.0889)
		(layer "In2.Cu")
		(net "M_I_CPU0_SB_CB<6>")
	)
	(arc
		(start 380.507748 -269.713456)
		(mid 380.689999 -269.663106)
		(end 380.873508 -269.70863)
		(width 0.0889)
		(layer "In2.Cu")
		(net "M_I_CPU0_SB_CB<6>")
	)
	(arc
		(start 385.581906 -269.713456)
		(mid 385.864862 -269.789633)
		(end 386.147818 -269.713456)
		(width 0.0889)
		(layer "In2.Cu")
		(net "M_I_CPU0_SB_CB<6>")
	)
	(arc
		(start 389.341868 -269.713456)
		(mid 389.624824 -269.789633)
		(end 389.90778 -269.713456)
		(width 0.0889)
		(layer "In2.Cu")
		(net "M_I_CPU0_SB_CB<6>")
	)
	(segment
		(start 375.528078 -269.770098)
		(end 375.99493 -270.036036)
		(width 0.10668)
		(layer "F.Cu")
		(net "M_I_CPU0_SB_CB<5>")
	)
	(segment
		(start 429.558704 -273.987768)
		(end 429.558704 -273.571716)
		(width 0.14478)
		(layer "In2.Cu")
		(net "M_I_CPU0_SB_CB<5>")
	)
	(segment
		(start 380.873508 -270.363442)
		(end 380.88189 -270.358616)
		(width 0.0889)
		(layer "In2.Cu")
		(net "M_I_CPU0_SB_CB<5>")
	)
	(segment
		(start 404.954232 -268.21003)
		(end 409.55087 -272.806668)
		(width 0.14478)
		(layer "In2.Cu")
		(net "M_I_CPU0_SB_CB<5>")
	)
	(segment
		(start 429.558704 -273.571716)
		(end 429.720248 -273.410172)
		(width 0.14478)
		(layer "In2.Cu")
		(net "M_I_CPU0_SB_CB<5>")
	)
	(segment
		(start 392.153394 -270.363442)
		(end 392.161776 -270.358616)
		(width 0.0889)
		(layer "In2.Cu")
		(net "M_I_CPU0_SB_CB<5>")
	)
	(segment
		(start 383.693416 -270.363442)
		(end 383.701798 -270.358616)
		(width 0.0889)
		(layer "In2.Cu")
		(net "M_I_CPU0_SB_CB<5>")
	)
	(segment
		(start 394.54074 -268.58849)
		(end 395.054074 -268.58849)
		(width 0.0889)
		(layer "In2.Cu")
		(net "M_I_CPU0_SB_CB<5>")
	)
	(segment
		(start 429.00727 -273.987768)
		(end 429.168814 -274.149312)
		(width 0.14478)
		(layer "In2.Cu")
		(net "M_I_CPU0_SB_CB<5>")
	)
	(segment
		(start 429.39716 -274.149312)
		(end 429.558704 -273.987768)
		(width 0.14478)
		(layer "In2.Cu")
		(net "M_I_CPU0_SB_CB<5>")
	)
	(segment
		(start 385.207764 -270.358616)
		(end 385.216146 -270.363442)
		(width 0.0889)
		(layer "In2.Cu")
		(net "M_I_CPU0_SB_CB<5>")
	)
	(segment
		(start 386.147818 -270.358616)
		(end 386.1562 -270.363442)
		(width 0.0889)
		(layer "In2.Cu")
		(net "M_I_CPU0_SB_CB<5>")
	)
	(segment
		(start 409.55087 -272.806668)
		(end 411.008322 -273.410172)
		(width 0.14478)
		(layer "In2.Cu")
		(net "M_I_CPU0_SB_CB<5>")
	)
	(segment
		(start 411.008322 -273.410172)
		(end 428.845726 -273.410172)
		(width 0.14478)
		(layer "In2.Cu")
		(net "M_I_CPU0_SB_CB<5>")
	)
	(segment
		(start 384.63347 -270.363442)
		(end 384.641852 -270.358616)
		(width 0.0889)
		(layer "In2.Cu")
		(net "M_I_CPU0_SB_CB<5>")
	)
	(segment
		(start 389.90778 -270.358616)
		(end 389.916162 -270.363442)
		(width 0.0889)
		(layer "In2.Cu")
		(net "M_I_CPU0_SB_CB<5>")
	)
	(segment
		(start 379.933454 -270.363442)
		(end 379.941836 -270.358616)
		(width 0.0889)
		(layer "In2.Cu")
		(net "M_I_CPU0_SB_CB<5>")
	)
	(segment
		(start 429.720248 -273.410172)
		(end 431.131218 -273.410172)
		(width 0.14478)
		(layer "In2.Cu")
		(net "M_I_CPU0_SB_CB<5>")
	)
	(segment
		(start 388.393432 -270.363442)
		(end 388.401814 -270.358616)
		(width 0.0889)
		(layer "In2.Cu")
		(net "M_I_CPU0_SB_CB<5>")
	)
	(segment
		(start 376.747786 -270.358616)
		(end 376.756168 -270.363442)
		(width 0.0889)
		(layer "In2.Cu")
		(net "M_I_CPU0_SB_CB<5>")
	)
	(segment
		(start 376.148854 -270.301466)
		(end 376.244866 -270.326866)
		(width 0.0889)
		(layer "In2.Cu")
		(net "M_I_CPU0_SB_CB<5>")
	)
	(segment
		(start 381.447802 -270.358616)
		(end 381.456184 -270.363442)
		(width 0.0889)
		(layer "In2.Cu")
		(net "M_I_CPU0_SB_CB<5>")
	)
	(segment
		(start 392.711178 -270.349472)
		(end 392.727434 -270.359124)
		(width 0.0889)
		(layer "In2.Cu")
		(net "M_I_CPU0_SB_CB<5>")
	)
	(segment
		(start 428.845726 -273.410172)
		(end 429.00727 -273.571716)
		(width 0.14478)
		(layer "In2.Cu")
		(net "M_I_CPU0_SB_CB<5>")
	)
	(segment
		(start 392.727434 -270.359124)
		(end 392.735816 -270.36395)
		(width 0.0889)
		(layer "In2.Cu")
		(net "M_I_CPU0_SB_CB<5>")
	)
	(segment
		(start 375.99493 -270.036036)
		(end 376.148854 -270.301466)
		(width 0.0889)
		(layer "In2.Cu")
		(net "M_I_CPU0_SB_CB<5>")
	)
	(segment
		(start 393.101576 -270.359124)
		(end 393.137898 -270.338042)
		(width 0.0889)
		(layer "In2.Cu")
		(net "M_I_CPU0_SB_CB<5>")
	)
	(segment
		(start 395.432534 -268.21003)
		(end 404.954232 -268.21003)
		(width 0.14478)
		(layer "In2.Cu")
		(net "M_I_CPU0_SB_CB<5>")
	)
	(segment
		(start 431.131218 -273.410172)
		(end 431.55616 -273.835114)
		(width 0.14478)
		(layer "In2.Cu")
		(net "M_I_CPU0_SB_CB<5>")
	)
	(segment
		(start 389.333486 -270.363442)
		(end 389.341868 -270.358616)
		(width 0.0889)
		(layer "In2.Cu")
		(net "M_I_CPU0_SB_CB<5>")
	)
	(segment
		(start 393.530074 -269.572994)
		(end 393.571984 -269.54861)
		(width 0.0889)
		(layer "In2.Cu")
		(net "M_I_CPU0_SB_CB<5>")
	)
	(segment
		(start 429.00727 -273.571716)
		(end 429.00727 -273.987768)
		(width 0.14478)
		(layer "In2.Cu")
		(net "M_I_CPU0_SB_CB<5>")
	)
	(segment
		(start 395.054074 -268.58849)
		(end 395.432534 -268.21003)
		(width 0.0889)
		(layer "In2.Cu")
		(net "M_I_CPU0_SB_CB<5>")
	)
	(segment
		(start 393.571984 -269.54861)
		(end 394.54074 -268.58849)
		(width 0.0889)
		(layer "In2.Cu")
		(net "M_I_CPU0_SB_CB<5>")
	)
	(segment
		(start 429.168814 -274.149312)
		(end 429.39716 -274.149312)
		(width 0.14478)
		(layer "In2.Cu")
		(net "M_I_CPU0_SB_CB<5>")
	)
	(segment
		(start 377.68784 -270.358616)
		(end 377.696222 -270.363442)
		(width 0.0889)
		(layer "In2.Cu")
		(net "M_I_CPU0_SB_CB<5>")
	)
	(arc
		(start 393.137898 -270.338042)
		(mid 393.249365 -270.205397)
		(end 393.289282 -270.036798)
		(width 0.0889)
		(layer "In2.Cu")
		(net "M_I_CPU0_SB_CB<5>")
	)
	(arc
		(start 379.001782 -270.358616)
		(mid 379.284738 -270.282439)
		(end 379.567694 -270.358616)
		(width 0.0889)
		(layer "In2.Cu")
		(net "M_I_CPU0_SB_CB<5>")
	)
	(arc
		(start 389.916162 -270.363442)
		(mid 390.09967 -270.408936)
		(end 390.281922 -270.358616)
		(width 0.0889)
		(layer "In2.Cu")
		(net "M_I_CPU0_SB_CB<5>")
	)
	(arc
		(start 390.281922 -270.358616)
		(mid 390.564878 -270.282439)
		(end 390.847834 -270.358616)
		(width 0.0889)
		(layer "In2.Cu")
		(net "M_I_CPU0_SB_CB<5>")
	)
	(arc
		(start 378.627894 -270.358616)
		(mid 378.814838 -270.408871)
		(end 379.001782 -270.358616)
		(width 0.0889)
		(layer "In2.Cu")
		(net "M_I_CPU0_SB_CB<5>")
	)
	(arc
		(start 387.087872 -270.358616)
		(mid 387.274816 -270.408871)
		(end 387.46176 -270.358616)
		(width 0.0889)
		(layer "In2.Cu")
		(net "M_I_CPU0_SB_CB<5>")
	)
	(arc
		(start 385.581906 -270.358616)
		(mid 385.864862 -270.282439)
		(end 386.147818 -270.358616)
		(width 0.0889)
		(layer "In2.Cu")
		(net "M_I_CPU0_SB_CB<5>")
	)
	(arc
		(start 388.967726 -270.358616)
		(mid 389.149977 -270.408966)
		(end 389.333486 -270.363442)
		(width 0.0889)
		(layer "In2.Cu")
		(net "M_I_CPU0_SB_CB<5>")
	)
	(arc
		(start 390.847834 -270.358616)
		(mid 391.034778 -270.408871)
		(end 391.221722 -270.358616)
		(width 0.0889)
		(layer "In2.Cu")
		(net "M_I_CPU0_SB_CB<5>")
	)
	(arc
		(start 379.567694 -270.358616)
		(mid 379.749945 -270.408966)
		(end 379.933454 -270.363442)
		(width 0.0889)
		(layer "In2.Cu")
		(net "M_I_CPU0_SB_CB<5>")
	)
	(arc
		(start 384.26771 -270.358616)
		(mid 384.449961 -270.408966)
		(end 384.63347 -270.363442)
		(width 0.0889)
		(layer "In2.Cu")
		(net "M_I_CPU0_SB_CB<5>")
	)
	(arc
		(start 384.641852 -270.358616)
		(mid 384.924808 -270.282439)
		(end 385.207764 -270.358616)
		(width 0.0889)
		(layer "In2.Cu")
		(net "M_I_CPU0_SB_CB<5>")
	)
	(arc
		(start 391.221722 -270.358616)
		(mid 391.504678 -270.282439)
		(end 391.787634 -270.358616)
		(width 0.0889)
		(layer "In2.Cu")
		(net "M_I_CPU0_SB_CB<5>")
	)
	(arc
		(start 376.244866 -270.326866)
		(mid 376.500074 -270.283389)
		(end 376.747786 -270.358616)
		(width 0.0889)
		(layer "In2.Cu")
		(net "M_I_CPU0_SB_CB<5>")
	)
	(arc
		(start 392.735816 -270.36395)
		(mid 392.919324 -270.409506)
		(end 393.101576 -270.359124)
		(width 0.0889)
		(layer "In2.Cu")
		(net "M_I_CPU0_SB_CB<5>")
	)
	(arc
		(start 386.52196 -270.358616)
		(mid 386.804916 -270.282439)
		(end 387.087872 -270.358616)
		(width 0.0889)
		(layer "In2.Cu")
		(net "M_I_CPU0_SB_CB<5>")
	)
	(arc
		(start 386.1562 -270.363442)
		(mid 386.339708 -270.408936)
		(end 386.52196 -270.358616)
		(width 0.0889)
		(layer "In2.Cu")
		(net "M_I_CPU0_SB_CB<5>")
	)
	(arc
		(start 389.341868 -270.358616)
		(mid 389.624824 -270.282439)
		(end 389.90778 -270.358616)
		(width 0.0889)
		(layer "In2.Cu")
		(net "M_I_CPU0_SB_CB<5>")
	)
	(arc
		(start 388.027672 -270.358616)
		(mid 388.209923 -270.408966)
		(end 388.393432 -270.363442)
		(width 0.0889)
		(layer "In2.Cu")
		(net "M_I_CPU0_SB_CB<5>")
	)
	(arc
		(start 387.46176 -270.358616)
		(mid 387.744716 -270.282439)
		(end 388.027672 -270.358616)
		(width 0.0889)
		(layer "In2.Cu")
		(net "M_I_CPU0_SB_CB<5>")
	)
	(arc
		(start 381.821944 -270.358616)
		(mid 382.1049 -270.282439)
		(end 382.387856 -270.358616)
		(width 0.0889)
		(layer "In2.Cu")
		(net "M_I_CPU0_SB_CB<5>")
	)
	(arc
		(start 382.761744 -270.358616)
		(mid 383.0447 -270.282439)
		(end 383.327656 -270.358616)
		(width 0.0889)
		(layer "In2.Cu")
		(net "M_I_CPU0_SB_CB<5>")
	)
	(arc
		(start 378.061982 -270.358616)
		(mid 378.344938 -270.282439)
		(end 378.627894 -270.358616)
		(width 0.0889)
		(layer "In2.Cu")
		(net "M_I_CPU0_SB_CB<5>")
	)
	(arc
		(start 382.387856 -270.358616)
		(mid 382.5748 -270.408871)
		(end 382.761744 -270.358616)
		(width 0.0889)
		(layer "In2.Cu")
		(net "M_I_CPU0_SB_CB<5>")
	)
	(arc
		(start 377.121928 -270.358616)
		(mid 377.404884 -270.282439)
		(end 377.68784 -270.358616)
		(width 0.0889)
		(layer "In2.Cu")
		(net "M_I_CPU0_SB_CB<5>")
	)
	(arc
		(start 381.456184 -270.363442)
		(mid 381.639692 -270.408936)
		(end 381.821944 -270.358616)
		(width 0.0889)
		(layer "In2.Cu")
		(net "M_I_CPU0_SB_CB<5>")
	)
	(arc
		(start 388.401814 -270.358616)
		(mid 388.68477 -270.282439)
		(end 388.967726 -270.358616)
		(width 0.0889)
		(layer "In2.Cu")
		(net "M_I_CPU0_SB_CB<5>")
	)
	(arc
		(start 392.161776 -270.358616)
		(mid 392.435295 -270.282518)
		(end 392.711178 -270.349472)
		(width 0.0889)
		(layer "In2.Cu")
		(net "M_I_CPU0_SB_CB<5>")
	)
	(arc
		(start 391.787634 -270.358616)
		(mid 391.969885 -270.408966)
		(end 392.153394 -270.363442)
		(width 0.0889)
		(layer "In2.Cu")
		(net "M_I_CPU0_SB_CB<5>")
	)
	(arc
		(start 376.756168 -270.363442)
		(mid 376.939676 -270.408936)
		(end 377.121928 -270.358616)
		(width 0.0889)
		(layer "In2.Cu")
		(net "M_I_CPU0_SB_CB<5>")
	)
	(arc
		(start 379.941836 -270.358616)
		(mid 380.224792 -270.282439)
		(end 380.507748 -270.358616)
		(width 0.0889)
		(layer "In2.Cu")
		(net "M_I_CPU0_SB_CB<5>")
	)
	(arc
		(start 380.88189 -270.358616)
		(mid 381.164846 -270.282439)
		(end 381.447802 -270.358616)
		(width 0.0889)
		(layer "In2.Cu")
		(net "M_I_CPU0_SB_CB<5>")
	)
	(arc
		(start 380.507748 -270.358616)
		(mid 380.689999 -270.408966)
		(end 380.873508 -270.363442)
		(width 0.0889)
		(layer "In2.Cu")
		(net "M_I_CPU0_SB_CB<5>")
	)
	(arc
		(start 393.289282 -270.036798)
		(mid 393.352898 -269.775415)
		(end 393.530074 -269.572994)
		(width 0.0889)
		(layer "In2.Cu")
		(net "M_I_CPU0_SB_CB<5>")
	)
	(arc
		(start 383.327656 -270.358616)
		(mid 383.509907 -270.408966)
		(end 383.693416 -270.363442)
		(width 0.0889)
		(layer "In2.Cu")
		(net "M_I_CPU0_SB_CB<5>")
	)
	(arc
		(start 383.701798 -270.358616)
		(mid 383.984754 -270.282439)
		(end 384.26771 -270.358616)
		(width 0.0889)
		(layer "In2.Cu")
		(net "M_I_CPU0_SB_CB<5>")
	)
	(arc
		(start 377.696222 -270.363442)
		(mid 377.87973 -270.408936)
		(end 378.061982 -270.358616)
		(width 0.0889)
		(layer "In2.Cu")
		(net "M_I_CPU0_SB_CB<5>")
	)
	(arc
		(start 385.216146 -270.363442)
		(mid 385.399654 -270.408936)
		(end 385.581906 -270.358616)
		(width 0.0889)
		(layer "In2.Cu")
		(net "M_I_CPU0_SB_CB<5>")
	)
	(segment
		(start 376.938032 -268.960092)
		(end 377.404884 -269.22603)
		(width 0.10668)
		(layer "F.Cu")
		(net "M_I_CPU0_SB_CB<4>")
	)
	(segment
		(start 429.860964 -272.610072)
		(end 430.022508 -272.448528)
		(width 0.14478)
		(layer "In2.Cu")
		(net "M_I_CPU0_SB_CB<4>")
	)
	(segment
		(start 395.648434 -267.31087)
		(end 405.49449 -267.31087)
		(width 0.14478)
		(layer "In2.Cu")
		(net "M_I_CPU0_SB_CB<4>")
	)
	(segment
		(start 428.52975 -272.610072)
		(end 428.758096 -272.610072)
		(width 0.14478)
		(layer "In2.Cu")
		(net "M_I_CPU0_SB_CB<4>")
	)
	(segment
		(start 431.131218 -271.71015)
		(end 431.55616 -272.135092)
		(width 0.14478)
		(layer "In2.Cu")
		(net "M_I_CPU0_SB_CB<4>")
	)
	(segment
		(start 393.062714 -268.761464)
		(end 393.10183 -268.738604)
		(width 0.0889)
		(layer "In2.Cu")
		(net "M_I_CPU0_SB_CB<4>")
	)
	(segment
		(start 383.79781 -269.54861)
		(end 383.806192 -269.553436)
		(width 0.0889)
		(layer "In2.Cu")
		(net "M_I_CPU0_SB_CB<4>")
	)
	(segment
		(start 411.711902 -271.71015)
		(end 428.206662 -271.71015)
		(width 0.14478)
		(layer "In2.Cu")
		(net "M_I_CPU0_SB_CB<4>")
	)
	(segment
		(start 390.74344 -269.553436)
		(end 390.751822 -269.54861)
		(width 0.0889)
		(layer "In2.Cu")
		(net "M_I_CPU0_SB_CB<4>")
	)
	(segment
		(start 392.63193 -269.54861)
		(end 392.66241 -269.53083)
		(width 0.0889)
		(layer "In2.Cu")
		(net "M_I_CPU0_SB_CB<4>")
	)
	(segment
		(start 428.206662 -271.71015)
		(end 428.368206 -271.871694)
		(width 0.14478)
		(layer "In2.Cu")
		(net "M_I_CPU0_SB_CB<4>")
	)
	(segment
		(start 429.30953 -271.71015)
		(end 429.471074 -271.871694)
		(width 0.14478)
		(layer "In2.Cu")
		(net "M_I_CPU0_SB_CB<4>")
	)
	(segment
		(start 394.891768 -267.31087)
		(end 395.648434 -267.31087)
		(width 0.0889)
		(layer "In2.Cu")
		(net "M_I_CPU0_SB_CB<4>")
	)
	(segment
		(start 377.558808 -269.49146)
		(end 377.65482 -269.51686)
		(width 0.0889)
		(layer "In2.Cu")
		(net "M_I_CPU0_SB_CB<4>")
	)
	(segment
		(start 387.557772 -269.54861)
		(end 387.566154 -269.553436)
		(width 0.0889)
		(layer "In2.Cu")
		(net "M_I_CPU0_SB_CB<4>")
	)
	(segment
		(start 377.404884 -269.22603)
		(end 377.558808 -269.49146)
		(width 0.0889)
		(layer "In2.Cu")
		(net "M_I_CPU0_SB_CB<4>")
	)
	(segment
		(start 429.081184 -271.71015)
		(end 429.30953 -271.71015)
		(width 0.14478)
		(layer "In2.Cu")
		(net "M_I_CPU0_SB_CB<4>")
	)
	(segment
		(start 428.758096 -272.610072)
		(end 428.91964 -272.448528)
		(width 0.14478)
		(layer "In2.Cu")
		(net "M_I_CPU0_SB_CB<4>")
	)
	(segment
		(start 386.043424 -269.553436)
		(end 386.051806 -269.54861)
		(width 0.0889)
		(layer "In2.Cu")
		(net "M_I_CPU0_SB_CB<4>")
	)
	(segment
		(start 386.983478 -269.553436)
		(end 386.99186 -269.54861)
		(width 0.0889)
		(layer "In2.Cu")
		(net "M_I_CPU0_SB_CB<4>")
	)
	(segment
		(start 428.91964 -272.448528)
		(end 428.91964 -271.871694)
		(width 0.14478)
		(layer "In2.Cu")
		(net "M_I_CPU0_SB_CB<4>")
	)
	(segment
		(start 388.497826 -269.54861)
		(end 388.506208 -269.553436)
		(width 0.0889)
		(layer "In2.Cu")
		(net "M_I_CPU0_SB_CB<4>")
	)
	(segment
		(start 379.097794 -269.54861)
		(end 379.106176 -269.553436)
		(width 0.0889)
		(layer "In2.Cu")
		(net "M_I_CPU0_SB_CB<4>")
	)
	(segment
		(start 428.368206 -271.871694)
		(end 428.368206 -272.448528)
		(width 0.14478)
		(layer "In2.Cu")
		(net "M_I_CPU0_SB_CB<4>")
	)
	(segment
		(start 429.471074 -272.448528)
		(end 429.632618 -272.610072)
		(width 0.14478)
		(layer "In2.Cu")
		(net "M_I_CPU0_SB_CB<4>")
	)
	(segment
		(start 411.195266 -271.539462)
		(end 411.711902 -271.71015)
		(width 0.14478)
		(layer "In2.Cu")
		(net "M_I_CPU0_SB_CB<4>")
	)
	(segment
		(start 393.991084 -268.211554)
		(end 394.891768 -267.31087)
		(width 0.0889)
		(layer "In2.Cu")
		(net "M_I_CPU0_SB_CB<4>")
	)
	(segment
		(start 382.857756 -269.54861)
		(end 382.866138 -269.553436)
		(width 0.0889)
		(layer "In2.Cu")
		(net "M_I_CPU0_SB_CB<4>")
	)
	(segment
		(start 380.037848 -269.54861)
		(end 380.04623 -269.553436)
		(width 0.0889)
		(layer "In2.Cu")
		(net "M_I_CPU0_SB_CB<4>")
	)
	(segment
		(start 391.317734 -269.54861)
		(end 391.326116 -269.553436)
		(width 0.0889)
		(layer "In2.Cu")
		(net "M_I_CPU0_SB_CB<4>")
	)
	(segment
		(start 392.631676 -269.54861)
		(end 392.63193 -269.54861)
		(width 0.0889)
		(layer "In2.Cu")
		(net "M_I_CPU0_SB_CB<4>")
	)
	(segment
		(start 393.10183 -268.738604)
		(end 393.991084 -268.211554)
		(width 0.0889)
		(layer "In2.Cu")
		(net "M_I_CPU0_SB_CB<4>")
	)
	(segment
		(start 429.471074 -271.871694)
		(end 429.471074 -272.448528)
		(width 0.14478)
		(layer "In2.Cu")
		(net "M_I_CPU0_SB_CB<4>")
	)
	(segment
		(start 405.49449 -267.31087)
		(end 411.195266 -271.539462)
		(width 0.14478)
		(layer "In2.Cu")
		(net "M_I_CPU0_SB_CB<4>")
	)
	(segment
		(start 430.022508 -271.871694)
		(end 430.184052 -271.71015)
		(width 0.14478)
		(layer "In2.Cu")
		(net "M_I_CPU0_SB_CB<4>")
	)
	(segment
		(start 429.632618 -272.610072)
		(end 429.860964 -272.610072)
		(width 0.14478)
		(layer "In2.Cu")
		(net "M_I_CPU0_SB_CB<4>")
	)
	(segment
		(start 378.5235 -269.553436)
		(end 378.531882 -269.54861)
		(width 0.0889)
		(layer "In2.Cu")
		(net "M_I_CPU0_SB_CB<4>")
	)
	(segment
		(start 430.184052 -271.71015)
		(end 431.131218 -271.71015)
		(width 0.14478)
		(layer "In2.Cu")
		(net "M_I_CPU0_SB_CB<4>")
	)
	(segment
		(start 430.022508 -272.448528)
		(end 430.022508 -271.871694)
		(width 0.14478)
		(layer "In2.Cu")
		(net "M_I_CPU0_SB_CB<4>")
	)
	(segment
		(start 428.91964 -271.871694)
		(end 429.081184 -271.71015)
		(width 0.14478)
		(layer "In2.Cu")
		(net "M_I_CPU0_SB_CB<4>")
	)
	(segment
		(start 428.368206 -272.448528)
		(end 428.52975 -272.610072)
		(width 0.14478)
		(layer "In2.Cu")
		(net "M_I_CPU0_SB_CB<4>")
	)
	(segment
		(start 382.283462 -269.553436)
		(end 382.291844 -269.54861)
		(width 0.0889)
		(layer "In2.Cu")
		(net "M_I_CPU0_SB_CB<4>")
	)
	(arc
		(start 392.819382 -269.22603)
		(mid 392.883897 -268.963811)
		(end 393.062714 -268.761464)
		(width 0.0889)
		(layer "In2.Cu")
		(net "M_I_CPU0_SB_CB<4>")
	)
	(arc
		(start 381.917702 -269.54861)
		(mid 382.099953 -269.59896)
		(end 382.283462 -269.553436)
		(width 0.0889)
		(layer "In2.Cu")
		(net "M_I_CPU0_SB_CB<4>")
	)
	(arc
		(start 384.171952 -269.54861)
		(mid 384.454908 -269.472433)
		(end 384.737864 -269.54861)
		(width 0.0889)
		(layer "In2.Cu")
		(net "M_I_CPU0_SB_CB<4>")
	)
	(arc
		(start 381.35179 -269.54861)
		(mid 381.634746 -269.472433)
		(end 381.917702 -269.54861)
		(width 0.0889)
		(layer "In2.Cu")
		(net "M_I_CPU0_SB_CB<4>")
	)
	(arc
		(start 385.677664 -269.54861)
		(mid 385.859915 -269.59896)
		(end 386.043424 -269.553436)
		(width 0.0889)
		(layer "In2.Cu")
		(net "M_I_CPU0_SB_CB<4>")
	)
	(arc
		(start 386.051806 -269.54861)
		(mid 386.334762 -269.472433)
		(end 386.617718 -269.54861)
		(width 0.0889)
		(layer "In2.Cu")
		(net "M_I_CPU0_SB_CB<4>")
	)
	(arc
		(start 392.257788 -269.54861)
		(mid 392.444732 -269.598865)
		(end 392.631676 -269.54861)
		(width 0.0889)
		(layer "In2.Cu")
		(net "M_I_CPU0_SB_CB<4>")
	)
	(arc
		(start 379.471936 -269.54861)
		(mid 379.754892 -269.472433)
		(end 380.037848 -269.54861)
		(width 0.0889)
		(layer "In2.Cu")
		(net "M_I_CPU0_SB_CB<4>")
	)
	(arc
		(start 390.37768 -269.54861)
		(mid 390.559931 -269.59896)
		(end 390.74344 -269.553436)
		(width 0.0889)
		(layer "In2.Cu")
		(net "M_I_CPU0_SB_CB<4>")
	)
	(arc
		(start 382.866138 -269.553436)
		(mid 383.049646 -269.59893)
		(end 383.231898 -269.54861)
		(width 0.0889)
		(layer "In2.Cu")
		(net "M_I_CPU0_SB_CB<4>")
	)
	(arc
		(start 392.66241 -269.53083)
		(mid 392.777837 -269.397454)
		(end 392.819382 -269.22603)
		(width 0.0889)
		(layer "In2.Cu")
		(net "M_I_CPU0_SB_CB<4>")
	)
	(arc
		(start 391.691876 -269.54861)
		(mid 391.974832 -269.472433)
		(end 392.257788 -269.54861)
		(width 0.0889)
		(layer "In2.Cu")
		(net "M_I_CPU0_SB_CB<4>")
	)
	(arc
		(start 383.231898 -269.54861)
		(mid 383.514854 -269.472433)
		(end 383.79781 -269.54861)
		(width 0.0889)
		(layer "In2.Cu")
		(net "M_I_CPU0_SB_CB<4>")
	)
	(arc
		(start 384.737864 -269.54861)
		(mid 384.924808 -269.598865)
		(end 385.111752 -269.54861)
		(width 0.0889)
		(layer "In2.Cu")
		(net "M_I_CPU0_SB_CB<4>")
	)
	(arc
		(start 390.751822 -269.54861)
		(mid 391.034778 -269.472433)
		(end 391.317734 -269.54861)
		(width 0.0889)
		(layer "In2.Cu")
		(net "M_I_CPU0_SB_CB<4>")
	)
	(arc
		(start 382.291844 -269.54861)
		(mid 382.5748 -269.472433)
		(end 382.857756 -269.54861)
		(width 0.0889)
		(layer "In2.Cu")
		(net "M_I_CPU0_SB_CB<4>")
	)
	(arc
		(start 388.506208 -269.553436)
		(mid 388.689716 -269.59893)
		(end 388.871968 -269.54861)
		(width 0.0889)
		(layer "In2.Cu")
		(net "M_I_CPU0_SB_CB<4>")
	)
	(arc
		(start 387.931914 -269.54861)
		(mid 388.21487 -269.472433)
		(end 388.497826 -269.54861)
		(width 0.0889)
		(layer "In2.Cu")
		(net "M_I_CPU0_SB_CB<4>")
	)
	(arc
		(start 380.41199 -269.54861)
		(mid 380.694946 -269.472433)
		(end 380.977902 -269.54861)
		(width 0.0889)
		(layer "In2.Cu")
		(net "M_I_CPU0_SB_CB<4>")
	)
	(arc
		(start 388.871968 -269.54861)
		(mid 389.154924 -269.472433)
		(end 389.43788 -269.54861)
		(width 0.0889)
		(layer "In2.Cu")
		(net "M_I_CPU0_SB_CB<4>")
	)
	(arc
		(start 378.15774 -269.54861)
		(mid 378.339991 -269.59896)
		(end 378.5235 -269.553436)
		(width 0.0889)
		(layer "In2.Cu")
		(net "M_I_CPU0_SB_CB<4>")
	)
	(arc
		(start 377.65482 -269.51686)
		(mid 377.910028 -269.473383)
		(end 378.15774 -269.54861)
		(width 0.0889)
		(layer "In2.Cu")
		(net "M_I_CPU0_SB_CB<4>")
	)
	(arc
		(start 380.04623 -269.553436)
		(mid 380.229738 -269.59893)
		(end 380.41199 -269.54861)
		(width 0.0889)
		(layer "In2.Cu")
		(net "M_I_CPU0_SB_CB<4>")
	)
	(arc
		(start 378.531882 -269.54861)
		(mid 378.814838 -269.472433)
		(end 379.097794 -269.54861)
		(width 0.0889)
		(layer "In2.Cu")
		(net "M_I_CPU0_SB_CB<4>")
	)
	(arc
		(start 380.977902 -269.54861)
		(mid 381.164846 -269.598865)
		(end 381.35179 -269.54861)
		(width 0.0889)
		(layer "In2.Cu")
		(net "M_I_CPU0_SB_CB<4>")
	)
	(arc
		(start 386.99186 -269.54861)
		(mid 387.274816 -269.472433)
		(end 387.557772 -269.54861)
		(width 0.0889)
		(layer "In2.Cu")
		(net "M_I_CPU0_SB_CB<4>")
	)
	(arc
		(start 386.617718 -269.54861)
		(mid 386.799969 -269.59896)
		(end 386.983478 -269.553436)
		(width 0.0889)
		(layer "In2.Cu")
		(net "M_I_CPU0_SB_CB<4>")
	)
	(arc
		(start 391.326116 -269.553436)
		(mid 391.509624 -269.59893)
		(end 391.691876 -269.54861)
		(width 0.0889)
		(layer "In2.Cu")
		(net "M_I_CPU0_SB_CB<4>")
	)
	(arc
		(start 387.566154 -269.553436)
		(mid 387.749662 -269.59893)
		(end 387.931914 -269.54861)
		(width 0.0889)
		(layer "In2.Cu")
		(net "M_I_CPU0_SB_CB<4>")
	)
	(arc
		(start 379.106176 -269.553436)
		(mid 379.289684 -269.59893)
		(end 379.471936 -269.54861)
		(width 0.0889)
		(layer "In2.Cu")
		(net "M_I_CPU0_SB_CB<4>")
	)
	(arc
		(start 389.811768 -269.54861)
		(mid 390.094724 -269.472433)
		(end 390.37768 -269.54861)
		(width 0.0889)
		(layer "In2.Cu")
		(net "M_I_CPU0_SB_CB<4>")
	)
	(arc
		(start 383.806192 -269.553436)
		(mid 383.9897 -269.59893)
		(end 384.171952 -269.54861)
		(width 0.0889)
		(layer "In2.Cu")
		(net "M_I_CPU0_SB_CB<4>")
	)
	(arc
		(start 385.111752 -269.54861)
		(mid 385.394708 -269.472433)
		(end 385.677664 -269.54861)
		(width 0.0889)
		(layer "In2.Cu")
		(net "M_I_CPU0_SB_CB<4>")
	)
	(arc
		(start 389.43788 -269.54861)
		(mid 389.624824 -269.598865)
		(end 389.811768 -269.54861)
		(width 0.0889)
		(layer "In2.Cu")
		(net "M_I_CPU0_SB_CB<4>")
	)
	(segment
		(start 375.997978 -273.820128)
		(end 376.46483 -274.086066)
		(width 0.10668)
		(layer "F.Cu")
		(net "M_I_CPU0_SB_CB<3>")
	)
	(segment
		(start 423.2275 -280.210006)
		(end 424.879008 -280.210006)
		(width 0.14478)
		(layer "In2.Cu")
		(net "M_I_CPU0_SB_CB<3>")
	)
	(segment
		(start 420.691056 -281.060144)
		(end 420.948612 -280.981912)
		(width 0.14478)
		(layer "In2.Cu")
		(net "M_I_CPU0_SB_CB<3>")
	)
	(segment
		(start 401.591272 -272.38325)
		(end 406.006554 -276.798532)
		(width 0.14478)
		(layer "In2.Cu")
		(net "M_I_CPU0_SB_CB<3>")
	)
	(segment
		(start 392.628374 -273.763486)
		(end 392.657838 -273.780758)
		(width 0.0889)
		(layer "In2.Cu")
		(net "M_I_CPU0_SB_CB<3>")
	)
	(segment
		(start 418.96538 -281.060144)
		(end 420.691056 -281.060144)
		(width 0.14478)
		(layer "In2.Cu")
		(net "M_I_CPU0_SB_CB<3>")
	)
	(segment
		(start 426.083984 -280.39695)
		(end 426.658024 -279.82291)
		(width 0.14478)
		(layer "In2.Cu")
		(net "M_I_CPU0_SB_CB<3>")
	)
	(segment
		(start 425.87164 -280.39695)
		(end 426.083984 -280.39695)
		(width 0.14478)
		(layer "In2.Cu")
		(net "M_I_CPU0_SB_CB<3>")
	)
	(segment
		(start 406.625298 -277.417276)
		(end 406.786842 -277.57882)
		(width 0.14478)
		(layer "In2.Cu")
		(net "M_I_CPU0_SB_CB<3>")
	)
	(segment
		(start 414.537398 -280.368756)
		(end 414.733232 -280.450036)
		(width 0.14478)
		(layer "In2.Cu")
		(net "M_I_CPU0_SB_CB<3>")
	)
	(segment
		(start 418.44849 -280.38806)
		(end 418.373306 -280.569416)
		(width 0.14478)
		(layer "In2.Cu")
		(net "M_I_CPU0_SB_CB<3>")
	)
	(segment
		(start 395.183106 -272.49247)
		(end 395.292326 -272.38325)
		(width 0.0889)
		(layer "In2.Cu")
		(net "M_I_CPU0_SB_CB<3>")
	)
	(segment
		(start 418.454078 -280.764742)
		(end 418.822378 -280.917142)
		(width 0.14478)
		(layer "In2.Cu")
		(net "M_I_CPU0_SB_CB<3>")
	)
	(segment
		(start 388.497826 -273.763486)
		(end 388.506208 -273.75866)
		(width 0.0889)
		(layer "In2.Cu")
		(net "M_I_CPU0_SB_CB<3>")
	)
	(segment
		(start 407.426414 -277.396448)
		(end 411.09011 -281.060144)
		(width 0.14478)
		(layer "In2.Cu")
		(net "M_I_CPU0_SB_CB<3>")
	)
	(segment
		(start 406.80767 -277.006304)
		(end 406.625298 -277.188676)
		(width 0.14478)
		(layer "In2.Cu")
		(net "M_I_CPU0_SB_CB<3>")
	)
	(segment
		(start 426.658024 -279.82291)
		(end 426.88129 -279.82291)
		(width 0.14478)
		(layer "In2.Cu")
		(net "M_I_CPU0_SB_CB<3>")
	)
	(segment
		(start 417.931854 -280.174192)
		(end 418.127688 -280.092912)
		(width 0.14478)
		(layer "In2.Cu")
		(net "M_I_CPU0_SB_CB<3>")
	)
	(segment
		(start 406.417526 -276.61616)
		(end 406.646126 -276.61616)
		(width 0.14478)
		(layer "In2.Cu")
		(net "M_I_CPU0_SB_CB<3>")
	)
	(segment
		(start 418.36721 -280.192226)
		(end 418.44849 -280.38806)
		(width 0.14478)
		(layer "In2.Cu")
		(net "M_I_CPU0_SB_CB<3>")
	)
	(segment
		(start 417.114228 -280.210006)
		(end 417.66109 -280.436574)
		(width 0.14478)
		(layer "In2.Cu")
		(net "M_I_CPU0_SB_CB<3>")
	)
	(segment
		(start 391.317734 -273.763486)
		(end 391.326116 -273.75866)
		(width 0.0889)
		(layer "In2.Cu")
		(net "M_I_CPU0_SB_CB<3>")
	)
	(segment
		(start 424.879008 -280.210006)
		(end 425.17568 -279.913334)
		(width 0.14478)
		(layer "In2.Cu")
		(net "M_I_CPU0_SB_CB<3>")
	)
	(segment
		(start 379.097794 -273.763486)
		(end 379.106176 -273.75866)
		(width 0.0889)
		(layer "In2.Cu")
		(net "M_I_CPU0_SB_CB<3>")
	)
	(segment
		(start 378.5235 -273.75866)
		(end 378.531882 -273.763486)
		(width 0.0889)
		(layer "In2.Cu")
		(net "M_I_CPU0_SB_CB<3>")
	)
	(segment
		(start 406.006554 -276.798532)
		(end 406.235154 -276.798532)
		(width 0.14478)
		(layer "In2.Cu")
		(net "M_I_CPU0_SB_CB<3>")
	)
	(segment
		(start 427.03115 -279.97277)
		(end 427.03115 -280.210006)
		(width 0.14478)
		(layer "In2.Cu")
		(net "M_I_CPU0_SB_CB<3>")
	)
	(segment
		(start 413.259778 -281.060144)
		(end 413.93999 -280.778204)
		(width 0.14478)
		(layer "In2.Cu")
		(net "M_I_CPU0_SB_CB<3>")
	)
	(segment
		(start 395.292326 -272.38325)
		(end 396.006828 -272.38325)
		(width 0.0889)
		(layer "In2.Cu")
		(net "M_I_CPU0_SB_CB<3>")
	)
	(segment
		(start 393.384786 -273.719544)
		(end 393.901422 -273.505422)
		(width 0.0889)
		(layer "In2.Cu")
		(net "M_I_CPU0_SB_CB<3>")
	)
	(segment
		(start 414.02127 -280.582624)
		(end 413.974026 -280.469086)
		(width 0.14478)
		(layer "In2.Cu")
		(net "M_I_CPU0_SB_CB<3>")
	)
	(segment
		(start 407.197814 -277.396448)
		(end 407.426414 -277.396448)
		(width 0.14478)
		(layer "In2.Cu")
		(net "M_I_CPU0_SB_CB<3>")
	)
	(segment
		(start 418.127688 -280.092912)
		(end 418.36721 -280.192226)
		(width 0.14478)
		(layer "In2.Cu")
		(net "M_I_CPU0_SB_CB<3>")
	)
	(segment
		(start 380.037848 -273.763486)
		(end 380.04623 -273.75866)
		(width 0.0889)
		(layer "In2.Cu")
		(net "M_I_CPU0_SB_CB<3>")
	)
	(segment
		(start 386.043424 -273.75866)
		(end 386.051806 -273.763486)
		(width 0.0889)
		(layer "In2.Cu")
		(net "M_I_CPU0_SB_CB<3>")
	)
	(segment
		(start 421.057832 -280.800048)
		(end 420.994078 -280.47569)
		(width 0.14478)
		(layer "In2.Cu")
		(net "M_I_CPU0_SB_CB<3>")
	)
	(segment
		(start 413.93999 -280.778204)
		(end 414.02127 -280.582624)
		(width 0.14478)
		(layer "In2.Cu")
		(net "M_I_CPU0_SB_CB<3>")
	)
	(segment
		(start 425.17568 -279.913334)
		(end 425.388024 -279.913334)
		(width 0.14478)
		(layer "In2.Cu")
		(net "M_I_CPU0_SB_CB<3>")
	)
	(segment
		(start 376.310906 -273.820636)
		(end 376.333258 -273.737324)
		(width 0.0889)
		(layer "In2.Cu")
		(net "M_I_CPU0_SB_CB<3>")
	)
	(segment
		(start 390.74344 -273.75866)
		(end 390.751822 -273.763486)
		(width 0.0889)
		(layer "In2.Cu")
		(net "M_I_CPU0_SB_CB<3>")
	)
	(segment
		(start 406.625298 -277.188676)
		(end 406.625298 -277.417276)
		(width 0.14478)
		(layer "In2.Cu")
		(net "M_I_CPU0_SB_CB<3>")
	)
	(segment
		(start 406.80767 -276.777704)
		(end 406.80767 -277.006304)
		(width 0.14478)
		(layer "In2.Cu")
		(net "M_I_CPU0_SB_CB<3>")
	)
	(segment
		(start 383.79781 -273.763486)
		(end 383.806192 -273.75866)
		(width 0.0889)
		(layer "In2.Cu")
		(net "M_I_CPU0_SB_CB<3>")
	)
	(segment
		(start 406.235154 -276.798532)
		(end 406.417526 -276.61616)
		(width 0.14478)
		(layer "In2.Cu")
		(net "M_I_CPU0_SB_CB<3>")
	)
	(segment
		(start 394.914374 -272.49247)
		(end 395.183106 -272.49247)
		(width 0.0889)
		(layer "In2.Cu")
		(net "M_I_CPU0_SB_CB<3>")
	)
	(segment
		(start 414.295082 -280.174192)
		(end 414.490408 -280.255472)
		(width 0.14478)
		(layer "In2.Cu")
		(net "M_I_CPU0_SB_CB<3>")
	)
	(segment
		(start 377.583446 -273.75866)
		(end 377.591828 -273.763486)
		(width 0.0889)
		(layer "In2.Cu")
		(net "M_I_CPU0_SB_CB<3>")
	)
	(segment
		(start 418.373306 -280.569416)
		(end 418.454078 -280.764742)
		(width 0.14478)
		(layer "In2.Cu")
		(net "M_I_CPU0_SB_CB<3>")
	)
	(segment
		(start 418.822378 -280.917142)
		(end 418.96538 -281.060144)
		(width 0.14478)
		(layer "In2.Cu")
		(net "M_I_CPU0_SB_CB<3>")
	)
	(segment
		(start 406.786842 -277.57882)
		(end 407.015442 -277.57882)
		(width 0.14478)
		(layer "In2.Cu")
		(net "M_I_CPU0_SB_CB<3>")
	)
	(segment
		(start 417.85667 -280.355294)
		(end 417.931854 -280.174192)
		(width 0.14478)
		(layer "In2.Cu")
		(net "M_I_CPU0_SB_CB<3>")
	)
	(segment
		(start 413.974026 -280.469086)
		(end 414.055052 -280.27376)
		(width 0.14478)
		(layer "In2.Cu")
		(net "M_I_CPU0_SB_CB<3>")
	)
	(segment
		(start 421.167306 -280.216864)
		(end 422.76395 -279.900126)
		(width 0.14478)
		(layer "In2.Cu")
		(net "M_I_CPU0_SB_CB<3>")
	)
	(segment
		(start 386.983478 -273.75866)
		(end 386.99186 -273.763486)
		(width 0.0889)
		(layer "In2.Cu")
		(net "M_I_CPU0_SB_CB<3>")
	)
	(segment
		(start 415.312352 -280.210006)
		(end 417.114228 -280.210006)
		(width 0.14478)
		(layer "In2.Cu")
		(net "M_I_CPU0_SB_CB<3>")
	)
	(segment
		(start 417.66109 -280.436574)
		(end 417.85667 -280.355294)
		(width 0.14478)
		(layer "In2.Cu")
		(net "M_I_CPU0_SB_CB<3>")
	)
	(segment
		(start 376.46483 -274.086066)
		(end 376.310906 -273.820636)
		(width 0.0889)
		(layer "In2.Cu")
		(net "M_I_CPU0_SB_CB<3>")
	)
	(segment
		(start 392.255756 -273.76374)
		(end 392.2776 -273.751294)
		(width 0.0889)
		(layer "In2.Cu")
		(net "M_I_CPU0_SB_CB<3>")
	)
	(segment
		(start 396.006828 -272.38325)
		(end 401.591272 -272.38325)
		(width 0.14478)
		(layer "In2.Cu")
		(net "M_I_CPU0_SB_CB<3>")
	)
	(segment
		(start 387.557772 -273.763486)
		(end 387.566154 -273.75866)
		(width 0.0889)
		(layer "In2.Cu")
		(net "M_I_CPU0_SB_CB<3>")
	)
	(segment
		(start 427.03115 -280.210006)
		(end 427.456092 -280.634948)
		(width 0.14478)
		(layer "In2.Cu")
		(net "M_I_CPU0_SB_CB<3>")
	)
	(segment
		(start 426.88129 -279.82291)
		(end 427.03115 -279.97277)
		(width 0.14478)
		(layer "In2.Cu")
		(net "M_I_CPU0_SB_CB<3>")
	)
	(segment
		(start 422.76395 -279.900126)
		(end 423.2275 -280.210006)
		(width 0.14478)
		(layer "In2.Cu")
		(net "M_I_CPU0_SB_CB<3>")
	)
	(segment
		(start 414.733232 -280.450036)
		(end 415.312352 -280.210006)
		(width 0.14478)
		(layer "In2.Cu")
		(net "M_I_CPU0_SB_CB<3>")
	)
	(segment
		(start 420.948612 -280.981912)
		(end 421.057832 -280.800048)
		(width 0.14478)
		(layer "In2.Cu")
		(net "M_I_CPU0_SB_CB<3>")
	)
	(segment
		(start 414.490408 -280.255472)
		(end 414.537398 -280.368756)
		(width 0.14478)
		(layer "In2.Cu")
		(net "M_I_CPU0_SB_CB<3>")
	)
	(segment
		(start 411.09011 -281.060144)
		(end 413.259778 -281.060144)
		(width 0.14478)
		(layer "In2.Cu")
		(net "M_I_CPU0_SB_CB<3>")
	)
	(segment
		(start 407.015442 -277.57882)
		(end 407.197814 -277.396448)
		(width 0.14478)
		(layer "In2.Cu")
		(net "M_I_CPU0_SB_CB<3>")
	)
	(segment
		(start 382.857756 -273.763486)
		(end 382.866138 -273.75866)
		(width 0.0889)
		(layer "In2.Cu")
		(net "M_I_CPU0_SB_CB<3>")
	)
	(segment
		(start 425.388024 -279.913334)
		(end 425.87164 -280.39695)
		(width 0.14478)
		(layer "In2.Cu")
		(net "M_I_CPU0_SB_CB<3>")
	)
	(segment
		(start 406.646126 -276.61616)
		(end 406.80767 -276.777704)
		(width 0.14478)
		(layer "In2.Cu")
		(net "M_I_CPU0_SB_CB<3>")
	)
	(segment
		(start 414.055052 -280.27376)
		(end 414.295082 -280.174192)
		(width 0.14478)
		(layer "In2.Cu")
		(net "M_I_CPU0_SB_CB<3>")
	)
	(segment
		(start 393.31392 -273.71929)
		(end 393.384786 -273.719544)
		(width 0.0889)
		(layer "In2.Cu")
		(net "M_I_CPU0_SB_CB<3>")
	)
	(segment
		(start 392.229594 -273.778726)
		(end 392.255756 -273.76374)
		(width 0.0889)
		(layer "In2.Cu")
		(net "M_I_CPU0_SB_CB<3>")
	)
	(segment
		(start 382.283462 -273.75866)
		(end 382.291844 -273.763486)
		(width 0.0889)
		(layer "In2.Cu")
		(net "M_I_CPU0_SB_CB<3>")
	)
	(segment
		(start 420.994078 -280.47569)
		(end 421.167306 -280.216864)
		(width 0.14478)
		(layer "In2.Cu")
		(net "M_I_CPU0_SB_CB<3>")
	)
	(segment
		(start 393.901422 -273.505422)
		(end 394.914374 -272.49247)
		(width 0.0889)
		(layer "In2.Cu")
		(net "M_I_CPU0_SB_CB<3>")
	)
	(arc
		(start 381.917702 -273.763486)
		(mid 382.099953 -273.713136)
		(end 382.283462 -273.75866)
		(width 0.0889)
		(layer "In2.Cu")
		(net "M_I_CPU0_SB_CB<3>")
	)
	(arc
		(start 386.051806 -273.763486)
		(mid 386.334762 -273.839663)
		(end 386.617718 -273.763486)
		(width 0.0889)
		(layer "In2.Cu")
		(net "M_I_CPU0_SB_CB<3>")
	)
	(arc
		(start 385.677664 -273.763486)
		(mid 385.859915 -273.713136)
		(end 386.043424 -273.75866)
		(width 0.0889)
		(layer "In2.Cu")
		(net "M_I_CPU0_SB_CB<3>")
	)
	(arc
		(start 388.871968 -273.763486)
		(mid 389.154924 -273.839663)
		(end 389.43788 -273.763486)
		(width 0.0889)
		(layer "In2.Cu")
		(net "M_I_CPU0_SB_CB<3>")
	)
	(arc
		(start 392.2776 -273.751294)
		(mid 392.454528 -273.713466)
		(end 392.628374 -273.763486)
		(width 0.0889)
		(layer "In2.Cu")
		(net "M_I_CPU0_SB_CB<3>")
	)
	(arc
		(start 383.806192 -273.75866)
		(mid 383.9897 -273.713166)
		(end 384.171952 -273.763486)
		(width 0.0889)
		(layer "In2.Cu")
		(net "M_I_CPU0_SB_CB<3>")
	)
	(arc
		(start 392.657838 -273.780758)
		(mid 392.929258 -273.840435)
		(end 393.196318 -273.763486)
		(width 0.0889)
		(layer "In2.Cu")
		(net "M_I_CPU0_SB_CB<3>")
	)
	(arc
		(start 383.231898 -273.763486)
		(mid 383.514854 -273.839663)
		(end 383.79781 -273.763486)
		(width 0.0889)
		(layer "In2.Cu")
		(net "M_I_CPU0_SB_CB<3>")
	)
	(arc
		(start 380.04623 -273.75866)
		(mid 380.229738 -273.713166)
		(end 380.41199 -273.763486)
		(width 0.0889)
		(layer "In2.Cu")
		(net "M_I_CPU0_SB_CB<3>")
	)
	(arc
		(start 388.506208 -273.75866)
		(mid 388.689716 -273.713166)
		(end 388.871968 -273.763486)
		(width 0.0889)
		(layer "In2.Cu")
		(net "M_I_CPU0_SB_CB<3>")
	)
	(arc
		(start 384.171952 -273.763486)
		(mid 384.454908 -273.839663)
		(end 384.737864 -273.763486)
		(width 0.0889)
		(layer "In2.Cu")
		(net "M_I_CPU0_SB_CB<3>")
	)
	(arc
		(start 376.651774 -273.763486)
		(mid 376.93473 -273.839663)
		(end 377.217686 -273.763486)
		(width 0.0889)
		(layer "In2.Cu")
		(net "M_I_CPU0_SB_CB<3>")
	)
	(arc
		(start 382.866138 -273.75866)
		(mid 383.049646 -273.713166)
		(end 383.231898 -273.763486)
		(width 0.0889)
		(layer "In2.Cu")
		(net "M_I_CPU0_SB_CB<3>")
	)
	(arc
		(start 376.333258 -273.737324)
		(mid 376.495447 -273.714589)
		(end 376.651774 -273.763486)
		(width 0.0889)
		(layer "In2.Cu")
		(net "M_I_CPU0_SB_CB<3>")
	)
	(arc
		(start 379.106176 -273.75866)
		(mid 379.289684 -273.713166)
		(end 379.471936 -273.763486)
		(width 0.0889)
		(layer "In2.Cu")
		(net "M_I_CPU0_SB_CB<3>")
	)
	(arc
		(start 377.217686 -273.763486)
		(mid 377.399937 -273.713136)
		(end 377.583446 -273.75866)
		(width 0.0889)
		(layer "In2.Cu")
		(net "M_I_CPU0_SB_CB<3>")
	)
	(arc
		(start 391.326116 -273.75866)
		(mid 391.509624 -273.713166)
		(end 391.691876 -273.763486)
		(width 0.0889)
		(layer "In2.Cu")
		(net "M_I_CPU0_SB_CB<3>")
	)
	(arc
		(start 387.931914 -273.763486)
		(mid 388.21487 -273.839663)
		(end 388.497826 -273.763486)
		(width 0.0889)
		(layer "In2.Cu")
		(net "M_I_CPU0_SB_CB<3>")
	)
	(arc
		(start 393.196318 -273.763486)
		(mid 393.253242 -273.736389)
		(end 393.31392 -273.71929)
		(width 0.0889)
		(layer "In2.Cu")
		(net "M_I_CPU0_SB_CB<3>")
	)
	(arc
		(start 378.531882 -273.763486)
		(mid 378.814838 -273.839663)
		(end 379.097794 -273.763486)
		(width 0.0889)
		(layer "In2.Cu")
		(net "M_I_CPU0_SB_CB<3>")
	)
	(arc
		(start 390.37768 -273.763486)
		(mid 390.559931 -273.713136)
		(end 390.74344 -273.75866)
		(width 0.0889)
		(layer "In2.Cu")
		(net "M_I_CPU0_SB_CB<3>")
	)
	(arc
		(start 391.691876 -273.763486)
		(mid 391.958806 -273.839435)
		(end 392.229594 -273.778726)
		(width 0.0889)
		(layer "In2.Cu")
		(net "M_I_CPU0_SB_CB<3>")
	)
	(arc
		(start 389.811768 -273.763486)
		(mid 390.094724 -273.839663)
		(end 390.37768 -273.763486)
		(width 0.0889)
		(layer "In2.Cu")
		(net "M_I_CPU0_SB_CB<3>")
	)
	(arc
		(start 384.737864 -273.763486)
		(mid 384.924808 -273.713231)
		(end 385.111752 -273.763486)
		(width 0.0889)
		(layer "In2.Cu")
		(net "M_I_CPU0_SB_CB<3>")
	)
	(arc
		(start 379.471936 -273.763486)
		(mid 379.754892 -273.839663)
		(end 380.037848 -273.763486)
		(width 0.0889)
		(layer "In2.Cu")
		(net "M_I_CPU0_SB_CB<3>")
	)
	(arc
		(start 387.566154 -273.75866)
		(mid 387.749662 -273.713166)
		(end 387.931914 -273.763486)
		(width 0.0889)
		(layer "In2.Cu")
		(net "M_I_CPU0_SB_CB<3>")
	)
	(arc
		(start 377.591828 -273.763486)
		(mid 377.874784 -273.839663)
		(end 378.15774 -273.763486)
		(width 0.0889)
		(layer "In2.Cu")
		(net "M_I_CPU0_SB_CB<3>")
	)
	(arc
		(start 385.111752 -273.763486)
		(mid 385.394708 -273.839663)
		(end 385.677664 -273.763486)
		(width 0.0889)
		(layer "In2.Cu")
		(net "M_I_CPU0_SB_CB<3>")
	)
	(arc
		(start 378.15774 -273.763486)
		(mid 378.339991 -273.713136)
		(end 378.5235 -273.75866)
		(width 0.0889)
		(layer "In2.Cu")
		(net "M_I_CPU0_SB_CB<3>")
	)
	(arc
		(start 390.751822 -273.763486)
		(mid 391.034778 -273.839663)
		(end 391.317734 -273.763486)
		(width 0.0889)
		(layer "In2.Cu")
		(net "M_I_CPU0_SB_CB<3>")
	)
	(arc
		(start 382.291844 -273.763486)
		(mid 382.5748 -273.839663)
		(end 382.857756 -273.763486)
		(width 0.0889)
		(layer "In2.Cu")
		(net "M_I_CPU0_SB_CB<3>")
	)
	(arc
		(start 380.977902 -273.763486)
		(mid 381.164846 -273.713231)
		(end 381.35179 -273.763486)
		(width 0.0889)
		(layer "In2.Cu")
		(net "M_I_CPU0_SB_CB<3>")
	)
	(arc
		(start 380.41199 -273.763486)
		(mid 380.694946 -273.839663)
		(end 380.977902 -273.763486)
		(width 0.0889)
		(layer "In2.Cu")
		(net "M_I_CPU0_SB_CB<3>")
	)
	(arc
		(start 386.617718 -273.763486)
		(mid 386.799969 -273.713136)
		(end 386.983478 -273.75866)
		(width 0.0889)
		(layer "In2.Cu")
		(net "M_I_CPU0_SB_CB<3>")
	)
	(arc
		(start 389.43788 -273.763486)
		(mid 389.624824 -273.713231)
		(end 389.811768 -273.763486)
		(width 0.0889)
		(layer "In2.Cu")
		(net "M_I_CPU0_SB_CB<3>")
	)
	(arc
		(start 386.99186 -273.763486)
		(mid 387.274816 -273.839663)
		(end 387.557772 -273.763486)
		(width 0.0889)
		(layer "In2.Cu")
		(net "M_I_CPU0_SB_CB<3>")
	)
	(arc
		(start 381.35179 -273.763486)
		(mid 381.634746 -273.839663)
		(end 381.917702 -273.763486)
		(width 0.0889)
		(layer "In2.Cu")
		(net "M_I_CPU0_SB_CB<3>")
	)
	(segment
		(start 377.407932 -273.010122)
		(end 377.874784 -273.27606)
		(width 0.10668)
		(layer "F.Cu")
		(net "M_I_CPU0_SB_CB<2>")
	)
	(segment
		(start 393.874752 -272.830544)
		(end 394.949426 -271.75587)
		(width 0.0889)
		(layer "In2.Cu")
		(net "M_I_CPU0_SB_CB<2>")
	)
	(segment
		(start 403.694138 -272.985992)
		(end 403.694138 -273.214084)
		(width 0.14478)
		(layer "In2.Cu")
		(net "M_I_CPU0_SB_CB<2>")
	)
	(segment
		(start 406.256236 -274.877276)
		(end 406.256236 -275.105368)
		(width 0.14478)
		(layer "In2.Cu")
		(net "M_I_CPU0_SB_CB<2>")
	)
	(segment
		(start 405.644858 -274.936712)
		(end 405.866092 -274.715224)
		(width 0.14478)
		(layer "In2.Cu")
		(net "M_I_CPU0_SB_CB<2>")
	)
	(segment
		(start 405.085804 -273.934936)
		(end 405.313896 -273.934936)
		(width 0.14478)
		(layer "In2.Cu")
		(net "M_I_CPU0_SB_CB<2>")
	)
	(segment
		(start 426.473366 -278.23795)
		(end 426.758862 -278.23795)
		(width 0.14478)
		(layer "In2.Cu")
		(net "M_I_CPU0_SB_CB<2>")
	)
	(segment
		(start 403.915372 -272.536412)
		(end 403.915372 -272.764504)
		(width 0.14478)
		(layer "In2.Cu")
		(net "M_I_CPU0_SB_CB<2>")
	)
	(segment
		(start 389.333486 -272.948654)
		(end 389.341868 -272.95348)
		(width 0.0889)
		(layer "In2.Cu")
		(net "M_I_CPU0_SB_CB<2>")
	)
	(segment
		(start 402.91385 -272.433796)
		(end 403.075902 -272.595848)
		(width 0.14478)
		(layer "In2.Cu")
		(net "M_I_CPU0_SB_CB<2>")
	)
	(segment
		(start 425.642532 -278.23795)
		(end 425.914566 -278.509984)
		(width 0.14478)
		(layer "In2.Cu")
		(net "M_I_CPU0_SB_CB<2>")
	)
	(segment
		(start 388.393432 -272.948654)
		(end 388.401814 -272.95348)
		(width 0.0889)
		(layer "In2.Cu")
		(net "M_I_CPU0_SB_CB<2>")
	)
	(segment
		(start 403.85619 -273.376136)
		(end 404.084282 -273.376136)
		(width 0.14478)
		(layer "In2.Cu")
		(net "M_I_CPU0_SB_CB<2>")
	)
	(segment
		(start 392.153394 -272.948654)
		(end 392.161776 -272.95348)
		(width 0.0889)
		(layer "In2.Cu")
		(net "M_I_CPU0_SB_CB<2>")
	)
	(segment
		(start 402.85289 -271.47393)
		(end 403.135084 -271.756124)
		(width 0.14478)
		(layer "In2.Cu")
		(net "M_I_CPU0_SB_CB<2>")
	)
	(segment
		(start 406.874472 -275.495512)
		(end 410.739082 -279.360122)
		(width 0.14478)
		(layer "In2.Cu")
		(net "M_I_CPU0_SB_CB<2>")
	)
	(segment
		(start 406.197054 -275.717)
		(end 406.425146 -275.717)
		(width 0.14478)
		(layer "In2.Cu")
		(net "M_I_CPU0_SB_CB<2>")
	)
	(segment
		(start 393.102338 -272.953734)
		(end 393.118086 -272.962878)
		(width 0.0889)
		(layer "In2.Cu")
		(net "M_I_CPU0_SB_CB<2>")
	)
	(segment
		(start 406.425146 -275.717)
		(end 406.64638 -275.495512)
		(width 0.14478)
		(layer "In2.Cu")
		(net "M_I_CPU0_SB_CB<2>")
	)
	(segment
		(start 403.135084 -271.984216)
		(end 402.91385 -272.205704)
		(width 0.14478)
		(layer "In2.Cu")
		(net "M_I_CPU0_SB_CB<2>")
	)
	(segment
		(start 404.86457 -274.156424)
		(end 405.085804 -273.934936)
		(width 0.14478)
		(layer "In2.Cu")
		(net "M_I_CPU0_SB_CB<2>")
	)
	(segment
		(start 404.474426 -273.994372)
		(end 404.636478 -274.156424)
		(width 0.14478)
		(layer "In2.Cu")
		(net "M_I_CPU0_SB_CB<2>")
	)
	(segment
		(start 396.006828 -271.47393)
		(end 402.85289 -271.47393)
		(width 0.14478)
		(layer "In2.Cu")
		(net "M_I_CPU0_SB_CB<2>")
	)
	(segment
		(start 404.69566 -273.544792)
		(end 404.474426 -273.76628)
		(width 0.14478)
		(layer "In2.Cu")
		(net "M_I_CPU0_SB_CB<2>")
	)
	(segment
		(start 406.035002 -275.554948)
		(end 406.197054 -275.717)
		(width 0.14478)
		(layer "In2.Cu")
		(net "M_I_CPU0_SB_CB<2>")
	)
	(segment
		(start 425.083732 -278.509984)
		(end 425.355766 -278.23795)
		(width 0.14478)
		(layer "In2.Cu")
		(net "M_I_CPU0_SB_CB<2>")
	)
	(segment
		(start 384.63347 -272.948654)
		(end 384.641852 -272.95348)
		(width 0.0889)
		(layer "In2.Cu")
		(net "M_I_CPU0_SB_CB<2>")
	)
	(segment
		(start 406.035002 -275.326856)
		(end 406.035002 -275.554948)
		(width 0.14478)
		(layer "In2.Cu")
		(net "M_I_CPU0_SB_CB<2>")
	)
	(segment
		(start 395.134846 -271.75587)
		(end 395.416786 -271.47393)
		(width 0.0889)
		(layer "In2.Cu")
		(net "M_I_CPU0_SB_CB<2>")
	)
	(segment
		(start 404.533608 -273.154648)
		(end 404.69566 -273.3167)
		(width 0.14478)
		(layer "In2.Cu")
		(net "M_I_CPU0_SB_CB<2>")
	)
	(segment
		(start 386.147818 -272.95348)
		(end 386.1562 -272.948654)
		(width 0.0889)
		(layer "In2.Cu")
		(net "M_I_CPU0_SB_CB<2>")
	)
	(segment
		(start 405.254714 -274.77466)
		(end 405.416766 -274.936712)
		(width 0.14478)
		(layer "In2.Cu")
		(net "M_I_CPU0_SB_CB<2>")
	)
	(segment
		(start 426.201332 -278.509984)
		(end 426.473366 -278.23795)
		(width 0.14478)
		(layer "In2.Cu")
		(net "M_I_CPU0_SB_CB<2>")
	)
	(segment
		(start 385.207764 -272.95348)
		(end 385.216146 -272.948654)
		(width 0.0889)
		(layer "In2.Cu")
		(net "M_I_CPU0_SB_CB<2>")
	)
	(segment
		(start 403.303994 -272.595848)
		(end 403.525228 -272.37436)
		(width 0.14478)
		(layer "In2.Cu")
		(net "M_I_CPU0_SB_CB<2>")
	)
	(segment
		(start 404.69566 -273.3167)
		(end 404.69566 -273.544792)
		(width 0.14478)
		(layer "In2.Cu")
		(net "M_I_CPU0_SB_CB<2>")
	)
	(segment
		(start 380.873508 -272.948654)
		(end 380.88189 -272.95348)
		(width 0.0889)
		(layer "In2.Cu")
		(net "M_I_CPU0_SB_CB<2>")
	)
	(segment
		(start 419.156388 -279.360122)
		(end 420.851076 -279.360122)
		(width 0.14478)
		(layer "In2.Cu")
		(net "M_I_CPU0_SB_CB<2>")
	)
	(segment
		(start 394.949426 -271.75587)
		(end 395.134846 -271.75587)
		(width 0.0889)
		(layer "In2.Cu")
		(net "M_I_CPU0_SB_CB<2>")
	)
	(segment
		(start 404.305516 -273.154648)
		(end 404.533608 -273.154648)
		(width 0.14478)
		(layer "In2.Cu")
		(net "M_I_CPU0_SB_CB<2>")
	)
	(segment
		(start 420.851076 -279.360122)
		(end 422.903396 -278.509984)
		(width 0.14478)
		(layer "In2.Cu")
		(net "M_I_CPU0_SB_CB<2>")
	)
	(segment
		(start 405.475948 -274.096988)
		(end 405.475948 -274.32508)
		(width 0.14478)
		(layer "In2.Cu")
		(net "M_I_CPU0_SB_CB<2>")
	)
	(segment
		(start 418.033454 -278.895048)
		(end 419.156388 -279.360122)
		(width 0.14478)
		(layer "In2.Cu")
		(net "M_I_CPU0_SB_CB<2>")
	)
	(segment
		(start 377.72086 -273.01063)
		(end 377.743212 -272.927318)
		(width 0.0889)
		(layer "In2.Cu")
		(net "M_I_CPU0_SB_CB<2>")
	)
	(segment
		(start 377.874784 -273.27606)
		(end 377.72086 -273.01063)
		(width 0.0889)
		(layer "In2.Cu")
		(net "M_I_CPU0_SB_CB<2>")
	)
	(segment
		(start 405.416766 -274.936712)
		(end 405.644858 -274.936712)
		(width 0.14478)
		(layer "In2.Cu")
		(net "M_I_CPU0_SB_CB<2>")
	)
	(segment
		(start 403.75332 -272.37436)
		(end 403.915372 -272.536412)
		(width 0.14478)
		(layer "In2.Cu")
		(net "M_I_CPU0_SB_CB<2>")
	)
	(segment
		(start 406.094184 -274.715224)
		(end 406.256236 -274.877276)
		(width 0.14478)
		(layer "In2.Cu")
		(net "M_I_CPU0_SB_CB<2>")
	)
	(segment
		(start 415.396426 -278.509984)
		(end 417.64839 -278.509984)
		(width 0.14478)
		(layer "In2.Cu")
		(net "M_I_CPU0_SB_CB<2>")
	)
	(segment
		(start 379.933454 -272.948654)
		(end 379.941836 -272.95348)
		(width 0.0889)
		(layer "In2.Cu")
		(net "M_I_CPU0_SB_CB<2>")
	)
	(segment
		(start 403.525228 -272.37436)
		(end 403.75332 -272.37436)
		(width 0.14478)
		(layer "In2.Cu")
		(net "M_I_CPU0_SB_CB<2>")
	)
	(segment
		(start 392.161776 -272.95348)
		(end 392.176508 -272.962116)
		(width 0.0889)
		(layer "In2.Cu")
		(net "M_I_CPU0_SB_CB<2>")
	)
	(segment
		(start 403.694138 -273.214084)
		(end 403.85619 -273.376136)
		(width 0.14478)
		(layer "In2.Cu")
		(net "M_I_CPU0_SB_CB<2>")
	)
	(segment
		(start 402.91385 -272.205704)
		(end 402.91385 -272.433796)
		(width 0.14478)
		(layer "In2.Cu")
		(net "M_I_CPU0_SB_CB<2>")
	)
	(segment
		(start 405.313896 -273.934936)
		(end 405.475948 -274.096988)
		(width 0.14478)
		(layer "In2.Cu")
		(net "M_I_CPU0_SB_CB<2>")
	)
	(segment
		(start 422.903396 -278.509984)
		(end 425.083732 -278.509984)
		(width 0.14478)
		(layer "In2.Cu")
		(net "M_I_CPU0_SB_CB<2>")
	)
	(segment
		(start 417.64839 -278.509984)
		(end 418.033454 -278.895048)
		(width 0.14478)
		(layer "In2.Cu")
		(net "M_I_CPU0_SB_CB<2>")
	)
	(segment
		(start 403.915372 -272.764504)
		(end 403.694138 -272.985992)
		(width 0.14478)
		(layer "In2.Cu")
		(net "M_I_CPU0_SB_CB<2>")
	)
	(segment
		(start 393.67587 -272.993866)
		(end 393.874752 -272.830544)
		(width 0.0889)
		(layer "In2.Cu")
		(net "M_I_CPU0_SB_CB<2>")
	)
	(segment
		(start 404.474426 -273.76628)
		(end 404.474426 -273.994372)
		(width 0.14478)
		(layer "In2.Cu")
		(net "M_I_CPU0_SB_CB<2>")
	)
	(segment
		(start 403.135084 -271.756124)
		(end 403.135084 -271.984216)
		(width 0.14478)
		(layer "In2.Cu")
		(net "M_I_CPU0_SB_CB<2>")
	)
	(segment
		(start 413.343598 -279.360122)
		(end 415.396426 -278.509984)
		(width 0.14478)
		(layer "In2.Cu")
		(net "M_I_CPU0_SB_CB<2>")
	)
	(segment
		(start 405.254714 -274.546568)
		(end 405.254714 -274.77466)
		(width 0.14478)
		(layer "In2.Cu")
		(net "M_I_CPU0_SB_CB<2>")
	)
	(segment
		(start 404.084282 -273.376136)
		(end 404.305516 -273.154648)
		(width 0.14478)
		(layer "In2.Cu")
		(net "M_I_CPU0_SB_CB<2>")
	)
	(segment
		(start 425.355766 -278.23795)
		(end 425.642532 -278.23795)
		(width 0.14478)
		(layer "In2.Cu")
		(net "M_I_CPU0_SB_CB<2>")
	)
	(segment
		(start 393.08405 -272.94332)
		(end 393.102338 -272.953734)
		(width 0.0889)
		(layer "In2.Cu")
		(net "M_I_CPU0_SB_CB<2>")
	)
	(segment
		(start 425.914566 -278.509984)
		(end 426.201332 -278.509984)
		(width 0.14478)
		(layer "In2.Cu")
		(net "M_I_CPU0_SB_CB<2>")
	)
	(segment
		(start 406.256236 -275.105368)
		(end 406.035002 -275.326856)
		(width 0.14478)
		(layer "In2.Cu")
		(net "M_I_CPU0_SB_CB<2>")
	)
	(segment
		(start 406.64638 -275.495512)
		(end 406.874472 -275.495512)
		(width 0.14478)
		(layer "In2.Cu")
		(net "M_I_CPU0_SB_CB<2>")
	)
	(segment
		(start 393.381738 -273.029934)
		(end 393.575286 -273.029934)
		(width 0.0889)
		(layer "In2.Cu")
		(net "M_I_CPU0_SB_CB<2>")
	)
	(segment
		(start 393.575286 -273.029934)
		(end 393.67587 -272.993866)
		(width 0.0889)
		(layer "In2.Cu")
		(net "M_I_CPU0_SB_CB<2>")
	)
	(segment
		(start 405.866092 -274.715224)
		(end 406.094184 -274.715224)
		(width 0.14478)
		(layer "In2.Cu")
		(net "M_I_CPU0_SB_CB<2>")
	)
	(segment
		(start 395.416786 -271.47393)
		(end 396.006828 -271.47393)
		(width 0.0889)
		(layer "In2.Cu")
		(net "M_I_CPU0_SB_CB<2>")
	)
	(segment
		(start 383.693416 -272.948654)
		(end 383.701798 -272.95348)
		(width 0.0889)
		(layer "In2.Cu")
		(net "M_I_CPU0_SB_CB<2>")
	)
	(segment
		(start 404.636478 -274.156424)
		(end 404.86457 -274.156424)
		(width 0.14478)
		(layer "In2.Cu")
		(net "M_I_CPU0_SB_CB<2>")
	)
	(segment
		(start 381.447802 -272.95348)
		(end 381.456184 -272.948654)
		(width 0.0889)
		(layer "In2.Cu")
		(net "M_I_CPU0_SB_CB<2>")
	)
	(segment
		(start 405.475948 -274.32508)
		(end 405.254714 -274.546568)
		(width 0.14478)
		(layer "In2.Cu")
		(net "M_I_CPU0_SB_CB<2>")
	)
	(segment
		(start 403.075902 -272.595848)
		(end 403.303994 -272.595848)
		(width 0.14478)
		(layer "In2.Cu")
		(net "M_I_CPU0_SB_CB<2>")
	)
	(segment
		(start 410.739082 -279.360122)
		(end 413.343598 -279.360122)
		(width 0.14478)
		(layer "In2.Cu")
		(net "M_I_CPU0_SB_CB<2>")
	)
	(segment
		(start 389.90778 -272.95348)
		(end 389.916162 -272.948654)
		(width 0.0889)
		(layer "In2.Cu")
		(net "M_I_CPU0_SB_CB<2>")
	)
	(segment
		(start 426.758862 -278.23795)
		(end 427.456092 -278.93518)
		(width 0.14478)
		(layer "In2.Cu")
		(net "M_I_CPU0_SB_CB<2>")
	)
	(arc
		(start 383.327656 -272.95348)
		(mid 383.509907 -272.90313)
		(end 383.693416 -272.948654)
		(width 0.0889)
		(layer "In2.Cu")
		(net "M_I_CPU0_SB_CB<2>")
	)
	(arc
		(start 390.847834 -272.95348)
		(mid 391.034778 -272.903225)
		(end 391.221722 -272.95348)
		(width 0.0889)
		(layer "In2.Cu")
		(net "M_I_CPU0_SB_CB<2>")
	)
	(arc
		(start 380.88189 -272.95348)
		(mid 381.164846 -273.029657)
		(end 381.447802 -272.95348)
		(width 0.0889)
		(layer "In2.Cu")
		(net "M_I_CPU0_SB_CB<2>")
	)
	(arc
		(start 388.967726 -272.95348)
		(mid 389.149977 -272.90313)
		(end 389.333486 -272.948654)
		(width 0.0889)
		(layer "In2.Cu")
		(net "M_I_CPU0_SB_CB<2>")
	)
	(arc
		(start 377.743212 -272.927318)
		(mid 377.905544 -272.9045)
		(end 378.061982 -272.95348)
		(width 0.0889)
		(layer "In2.Cu")
		(net "M_I_CPU0_SB_CB<2>")
	)
	(arc
		(start 386.1562 -272.948654)
		(mid 386.339708 -272.90316)
		(end 386.52196 -272.95348)
		(width 0.0889)
		(layer "In2.Cu")
		(net "M_I_CPU0_SB_CB<2>")
	)
	(arc
		(start 381.456184 -272.948654)
		(mid 381.639692 -272.90316)
		(end 381.821944 -272.95348)
		(width 0.0889)
		(layer "In2.Cu")
		(net "M_I_CPU0_SB_CB<2>")
	)
	(arc
		(start 378.627894 -272.95348)
		(mid 378.814838 -272.903225)
		(end 379.001782 -272.95348)
		(width 0.0889)
		(layer "In2.Cu")
		(net "M_I_CPU0_SB_CB<2>")
	)
	(arc
		(start 381.821944 -272.95348)
		(mid 382.1049 -273.029657)
		(end 382.387856 -272.95348)
		(width 0.0889)
		(layer "In2.Cu")
		(net "M_I_CPU0_SB_CB<2>")
	)
	(arc
		(start 379.941836 -272.95348)
		(mid 380.224792 -273.029657)
		(end 380.507748 -272.95348)
		(width 0.0889)
		(layer "In2.Cu")
		(net "M_I_CPU0_SB_CB<2>")
	)
	(arc
		(start 383.701798 -272.95348)
		(mid 383.984754 -273.029657)
		(end 384.26771 -272.95348)
		(width 0.0889)
		(layer "In2.Cu")
		(net "M_I_CPU0_SB_CB<2>")
	)
	(arc
		(start 387.46176 -272.95348)
		(mid 387.744716 -273.029657)
		(end 388.027672 -272.95348)
		(width 0.0889)
		(layer "In2.Cu")
		(net "M_I_CPU0_SB_CB<2>")
	)
	(arc
		(start 392.728196 -272.95348)
		(mid 392.904824 -272.903247)
		(end 393.08405 -272.94332)
		(width 0.0889)
		(layer "In2.Cu")
		(net "M_I_CPU0_SB_CB<2>")
	)
	(arc
		(start 384.26771 -272.95348)
		(mid 384.449961 -272.90313)
		(end 384.63347 -272.948654)
		(width 0.0889)
		(layer "In2.Cu")
		(net "M_I_CPU0_SB_CB<2>")
	)
	(arc
		(start 393.118086 -272.962878)
		(mid 393.245808 -273.012541)
		(end 393.381738 -273.029934)
		(width 0.0889)
		(layer "In2.Cu")
		(net "M_I_CPU0_SB_CB<2>")
	)
	(arc
		(start 387.087872 -272.95348)
		(mid 387.274816 -272.903225)
		(end 387.46176 -272.95348)
		(width 0.0889)
		(layer "In2.Cu")
		(net "M_I_CPU0_SB_CB<2>")
	)
	(arc
		(start 380.507748 -272.95348)
		(mid 380.689999 -272.90313)
		(end 380.873508 -272.948654)
		(width 0.0889)
		(layer "In2.Cu")
		(net "M_I_CPU0_SB_CB<2>")
	)
	(arc
		(start 379.567694 -272.95348)
		(mid 379.749945 -272.90313)
		(end 379.933454 -272.948654)
		(width 0.0889)
		(layer "In2.Cu")
		(net "M_I_CPU0_SB_CB<2>")
	)
	(arc
		(start 379.001782 -272.95348)
		(mid 379.284738 -273.029657)
		(end 379.567694 -272.95348)
		(width 0.0889)
		(layer "In2.Cu")
		(net "M_I_CPU0_SB_CB<2>")
	)
	(arc
		(start 385.216146 -272.948654)
		(mid 385.399654 -272.90316)
		(end 385.581906 -272.95348)
		(width 0.0889)
		(layer "In2.Cu")
		(net "M_I_CPU0_SB_CB<2>")
	)
	(arc
		(start 392.176508 -272.962116)
		(mid 392.453491 -273.02992)
		(end 392.728196 -272.95348)
		(width 0.0889)
		(layer "In2.Cu")
		(net "M_I_CPU0_SB_CB<2>")
	)
	(arc
		(start 388.401814 -272.95348)
		(mid 388.68477 -273.029657)
		(end 388.967726 -272.95348)
		(width 0.0889)
		(layer "In2.Cu")
		(net "M_I_CPU0_SB_CB<2>")
	)
	(arc
		(start 385.581906 -272.95348)
		(mid 385.864862 -273.029657)
		(end 386.147818 -272.95348)
		(width 0.0889)
		(layer "In2.Cu")
		(net "M_I_CPU0_SB_CB<2>")
	)
	(arc
		(start 388.027672 -272.95348)
		(mid 388.209923 -272.90313)
		(end 388.393432 -272.948654)
		(width 0.0889)
		(layer "In2.Cu")
		(net "M_I_CPU0_SB_CB<2>")
	)
	(arc
		(start 391.787634 -272.95348)
		(mid 391.969885 -272.90313)
		(end 392.153394 -272.948654)
		(width 0.0889)
		(layer "In2.Cu")
		(net "M_I_CPU0_SB_CB<2>")
	)
	(arc
		(start 390.281922 -272.95348)
		(mid 390.564878 -273.029657)
		(end 390.847834 -272.95348)
		(width 0.0889)
		(layer "In2.Cu")
		(net "M_I_CPU0_SB_CB<2>")
	)
	(arc
		(start 382.387856 -272.95348)
		(mid 382.5748 -272.903225)
		(end 382.761744 -272.95348)
		(width 0.0889)
		(layer "In2.Cu")
		(net "M_I_CPU0_SB_CB<2>")
	)
	(arc
		(start 391.221722 -272.95348)
		(mid 391.504678 -273.029657)
		(end 391.787634 -272.95348)
		(width 0.0889)
		(layer "In2.Cu")
		(net "M_I_CPU0_SB_CB<2>")
	)
	(arc
		(start 378.061982 -272.95348)
		(mid 378.344938 -273.029657)
		(end 378.627894 -272.95348)
		(width 0.0889)
		(layer "In2.Cu")
		(net "M_I_CPU0_SB_CB<2>")
	)
	(arc
		(start 386.52196 -272.95348)
		(mid 386.804916 -273.029657)
		(end 387.087872 -272.95348)
		(width 0.0889)
		(layer "In2.Cu")
		(net "M_I_CPU0_SB_CB<2>")
	)
	(arc
		(start 389.916162 -272.948654)
		(mid 390.09967 -272.90316)
		(end 390.281922 -272.95348)
		(width 0.0889)
		(layer "In2.Cu")
		(net "M_I_CPU0_SB_CB<2>")
	)
	(arc
		(start 384.641852 -272.95348)
		(mid 384.924808 -273.029657)
		(end 385.207764 -272.95348)
		(width 0.0889)
		(layer "In2.Cu")
		(net "M_I_CPU0_SB_CB<2>")
	)
	(arc
		(start 389.341868 -272.95348)
		(mid 389.624824 -273.029657)
		(end 389.90778 -272.95348)
		(width 0.0889)
		(layer "In2.Cu")
		(net "M_I_CPU0_SB_CB<2>")
	)
	(arc
		(start 382.761744 -272.95348)
		(mid 383.0447 -273.029657)
		(end 383.327656 -272.95348)
		(width 0.0889)
		(layer "In2.Cu")
		(net "M_I_CPU0_SB_CB<2>")
	)
	(segment
		(start 375.528078 -273.010122)
		(end 375.99493 -273.27606)
		(width 0.10668)
		(layer "F.Cu")
		(net "M_I_CPU0_SB_CB<1>")
	)
	(segment
		(start 376.148854 -273.54149)
		(end 376.244866 -273.56689)
		(width 0.0889)
		(layer "In2.Cu")
		(net "M_I_CPU0_SB_CB<1>")
	)
	(segment
		(start 375.99493 -273.27606)
		(end 376.148854 -273.54149)
		(width 0.0889)
		(layer "In2.Cu")
		(net "M_I_CPU0_SB_CB<1>")
	)
	(segment
		(start 394.969746 -272.14957)
		(end 395.139926 -272.14957)
		(width 0.0889)
		(layer "In2.Cu")
		(net "M_I_CPU0_SB_CB<1>")
	)
	(segment
		(start 395.360906 -271.92859)
		(end 395.989048 -271.92859)
		(width 0.0889)
		(layer "In2.Cu")
		(net "M_I_CPU0_SB_CB<1>")
	)
	(segment
		(start 386.147818 -273.59864)
		(end 386.1562 -273.603466)
		(width 0.0889)
		(layer "In2.Cu")
		(net "M_I_CPU0_SB_CB<1>")
	)
	(segment
		(start 410.952696 -280.210006)
		(end 412.980886 -280.210006)
		(width 0.14478)
		(layer "In2.Cu")
		(net "M_I_CPU0_SB_CB<1>")
	)
	(segment
		(start 417.604448 -279.360122)
		(end 419.656006 -280.210006)
		(width 0.14478)
		(layer "In2.Cu")
		(net "M_I_CPU0_SB_CB<1>")
	)
	(segment
		(start 389.90778 -273.59864)
		(end 389.916162 -273.603466)
		(width 0.0889)
		(layer "In2.Cu")
		(net "M_I_CPU0_SB_CB<1>")
	)
	(segment
		(start 383.693416 -273.603466)
		(end 383.701798 -273.59864)
		(width 0.0889)
		(layer "In2.Cu")
		(net "M_I_CPU0_SB_CB<1>")
	)
	(segment
		(start 377.68784 -273.59864)
		(end 377.696222 -273.603466)
		(width 0.0889)
		(layer "In2.Cu")
		(net "M_I_CPU0_SB_CB<1>")
	)
	(segment
		(start 381.447802 -273.59864)
		(end 381.456184 -273.603466)
		(width 0.0889)
		(layer "In2.Cu")
		(net "M_I_CPU0_SB_CB<1>")
	)
	(segment
		(start 379.933454 -273.603466)
		(end 379.941836 -273.59864)
		(width 0.0889)
		(layer "In2.Cu")
		(net "M_I_CPU0_SB_CB<1>")
	)
	(segment
		(start 395.989048 -271.92859)
		(end 401.772628 -271.92859)
		(width 0.14478)
		(layer "In2.Cu")
		(net "M_I_CPU0_SB_CB<1>")
	)
	(segment
		(start 389.333486 -273.603466)
		(end 389.341868 -273.59864)
		(width 0.0889)
		(layer "In2.Cu")
		(net "M_I_CPU0_SB_CB<1>")
	)
	(segment
		(start 406.90927 -276.16658)
		(end 410.952696 -280.210006)
		(width 0.14478)
		(layer "In2.Cu")
		(net "M_I_CPU0_SB_CB<1>")
	)
	(segment
		(start 385.207764 -273.59864)
		(end 385.216146 -273.603466)
		(width 0.0889)
		(layer "In2.Cu")
		(net "M_I_CPU0_SB_CB<1>")
	)
	(segment
		(start 395.139926 -272.14957)
		(end 395.360906 -271.92859)
		(width 0.0889)
		(layer "In2.Cu")
		(net "M_I_CPU0_SB_CB<1>")
	)
	(segment
		(start 380.873508 -273.603466)
		(end 380.88189 -273.59864)
		(width 0.0889)
		(layer "In2.Cu")
		(net "M_I_CPU0_SB_CB<1>")
	)
	(segment
		(start 392.137138 -273.611848)
		(end 392.160506 -273.598386)
		(width 0.0889)
		(layer "In2.Cu")
		(net "M_I_CPU0_SB_CB<1>")
	)
	(segment
		(start 392.724386 -273.59864)
		(end 392.74496 -273.610578)
		(width 0.0889)
		(layer "In2.Cu")
		(net "M_I_CPU0_SB_CB<1>")
	)
	(segment
		(start 393.099798 -273.59864)
		(end 393.100052 -273.598894)
		(width 0.0889)
		(layer "In2.Cu")
		(net "M_I_CPU0_SB_CB<1>")
	)
	(segment
		(start 415.032698 -279.360122)
		(end 417.604448 -279.360122)
		(width 0.14478)
		(layer "In2.Cu")
		(net "M_I_CPU0_SB_CB<1>")
	)
	(segment
		(start 393.824206 -273.29511)
		(end 394.969746 -272.14957)
		(width 0.0889)
		(layer "In2.Cu")
		(net "M_I_CPU0_SB_CB<1>")
	)
	(segment
		(start 376.747786 -273.59864)
		(end 376.756168 -273.603466)
		(width 0.0889)
		(layer "In2.Cu")
		(net "M_I_CPU0_SB_CB<1>")
	)
	(segment
		(start 392.160506 -273.598386)
		(end 392.186668 -273.5834)
		(width 0.0889)
		(layer "In2.Cu")
		(net "M_I_CPU0_SB_CB<1>")
	)
	(segment
		(start 401.772628 -271.92859)
		(end 406.010618 -276.16658)
		(width 0.14478)
		(layer "In2.Cu")
		(net "M_I_CPU0_SB_CB<1>")
	)
	(segment
		(start 422.666668 -279.360122)
		(end 431.131218 -279.360122)
		(width 0.14478)
		(layer "In2.Cu")
		(net "M_I_CPU0_SB_CB<1>")
	)
	(segment
		(start 393.29741 -273.52879)
		(end 393.824206 -273.29511)
		(width 0.0889)
		(layer "In2.Cu")
		(net "M_I_CPU0_SB_CB<1>")
	)
	(segment
		(start 419.988746 -280.210006)
		(end 421.461946 -279.599644)
		(width 0.14478)
		(layer "In2.Cu")
		(net "M_I_CPU0_SB_CB<1>")
	)
	(segment
		(start 421.461946 -279.599644)
		(end 422.666668 -279.360122)
		(width 0.14478)
		(layer "In2.Cu")
		(net "M_I_CPU0_SB_CB<1>")
	)
	(segment
		(start 406.010618 -276.16658)
		(end 406.90927 -276.16658)
		(width 0.14478)
		(layer "In2.Cu")
		(net "M_I_CPU0_SB_CB<1>")
	)
	(segment
		(start 412.980886 -280.210006)
		(end 415.032698 -279.360122)
		(width 0.14478)
		(layer "In2.Cu")
		(net "M_I_CPU0_SB_CB<1>")
	)
	(segment
		(start 419.656006 -280.210006)
		(end 419.988746 -280.210006)
		(width 0.14478)
		(layer "In2.Cu")
		(net "M_I_CPU0_SB_CB<1>")
	)
	(segment
		(start 431.131218 -279.360122)
		(end 431.55616 -279.785064)
		(width 0.14478)
		(layer "In2.Cu")
		(net "M_I_CPU0_SB_CB<1>")
	)
	(segment
		(start 384.63347 -273.603466)
		(end 384.641852 -273.59864)
		(width 0.0889)
		(layer "In2.Cu")
		(net "M_I_CPU0_SB_CB<1>")
	)
	(segment
		(start 388.393432 -273.603466)
		(end 388.401814 -273.59864)
		(width 0.0889)
		(layer "In2.Cu")
		(net "M_I_CPU0_SB_CB<1>")
	)
	(arc
		(start 391.221722 -273.59864)
		(mid 391.504678 -273.522463)
		(end 391.787634 -273.59864)
		(width 0.0889)
		(layer "In2.Cu")
		(net "M_I_CPU0_SB_CB<1>")
	)
	(arc
		(start 386.52196 -273.59864)
		(mid 386.804916 -273.522463)
		(end 387.087872 -273.59864)
		(width 0.0889)
		(layer "In2.Cu")
		(net "M_I_CPU0_SB_CB<1>")
	)
	(arc
		(start 384.641852 -273.59864)
		(mid 384.924808 -273.522463)
		(end 385.207764 -273.59864)
		(width 0.0889)
		(layer "In2.Cu")
		(net "M_I_CPU0_SB_CB<1>")
	)
	(arc
		(start 383.701798 -273.59864)
		(mid 383.984754 -273.522463)
		(end 384.26771 -273.59864)
		(width 0.0889)
		(layer "In2.Cu")
		(net "M_I_CPU0_SB_CB<1>")
	)
	(arc
		(start 376.756168 -273.603466)
		(mid 376.939676 -273.64896)
		(end 377.121928 -273.59864)
		(width 0.0889)
		(layer "In2.Cu")
		(net "M_I_CPU0_SB_CB<1>")
	)
	(arc
		(start 387.087872 -273.59864)
		(mid 387.274816 -273.648895)
		(end 387.46176 -273.59864)
		(width 0.0889)
		(layer "In2.Cu")
		(net "M_I_CPU0_SB_CB<1>")
	)
	(arc
		(start 381.456184 -273.603466)
		(mid 381.639692 -273.64896)
		(end 381.821944 -273.59864)
		(width 0.0889)
		(layer "In2.Cu")
		(net "M_I_CPU0_SB_CB<1>")
	)
	(arc
		(start 388.967726 -273.59864)
		(mid 389.149977 -273.64899)
		(end 389.333486 -273.603466)
		(width 0.0889)
		(layer "In2.Cu")
		(net "M_I_CPU0_SB_CB<1>")
	)
	(arc
		(start 377.696222 -273.603466)
		(mid 377.87973 -273.64896)
		(end 378.061982 -273.59864)
		(width 0.0889)
		(layer "In2.Cu")
		(net "M_I_CPU0_SB_CB<1>")
	)
	(arc
		(start 393.100052 -273.598894)
		(mid 393.195452 -273.554612)
		(end 393.29741 -273.52879)
		(width 0.0889)
		(layer "In2.Cu")
		(net "M_I_CPU0_SB_CB<1>")
	)
	(arc
		(start 384.26771 -273.59864)
		(mid 384.449961 -273.64899)
		(end 384.63347 -273.603466)
		(width 0.0889)
		(layer "In2.Cu")
		(net "M_I_CPU0_SB_CB<1>")
	)
	(arc
		(start 385.216146 -273.603466)
		(mid 385.399654 -273.64896)
		(end 385.581906 -273.59864)
		(width 0.0889)
		(layer "In2.Cu")
		(net "M_I_CPU0_SB_CB<1>")
	)
	(arc
		(start 376.244866 -273.56689)
		(mid 376.500074 -273.523413)
		(end 376.747786 -273.59864)
		(width 0.0889)
		(layer "In2.Cu")
		(net "M_I_CPU0_SB_CB<1>")
	)
	(arc
		(start 383.327656 -273.59864)
		(mid 383.509907 -273.64899)
		(end 383.693416 -273.603466)
		(width 0.0889)
		(layer "In2.Cu")
		(net "M_I_CPU0_SB_CB<1>")
	)
	(arc
		(start 391.787634 -273.59864)
		(mid 391.960742 -273.648756)
		(end 392.137138 -273.611848)
		(width 0.0889)
		(layer "In2.Cu")
		(net "M_I_CPU0_SB_CB<1>")
	)
	(arc
		(start 378.061982 -273.59864)
		(mid 378.344938 -273.522463)
		(end 378.627894 -273.59864)
		(width 0.0889)
		(layer "In2.Cu")
		(net "M_I_CPU0_SB_CB<1>")
	)
	(arc
		(start 389.341868 -273.59864)
		(mid 389.624824 -273.522463)
		(end 389.90778 -273.59864)
		(width 0.0889)
		(layer "In2.Cu")
		(net "M_I_CPU0_SB_CB<1>")
	)
	(arc
		(start 379.941836 -273.59864)
		(mid 380.224792 -273.522463)
		(end 380.507748 -273.59864)
		(width 0.0889)
		(layer "In2.Cu")
		(net "M_I_CPU0_SB_CB<1>")
	)
	(arc
		(start 390.847834 -273.59864)
		(mid 391.034778 -273.648895)
		(end 391.221722 -273.59864)
		(width 0.0889)
		(layer "In2.Cu")
		(net "M_I_CPU0_SB_CB<1>")
	)
	(arc
		(start 379.001782 -273.59864)
		(mid 379.284738 -273.522463)
		(end 379.567694 -273.59864)
		(width 0.0889)
		(layer "In2.Cu")
		(net "M_I_CPU0_SB_CB<1>")
	)
	(arc
		(start 392.74496 -273.610578)
		(mid 392.923888 -273.649455)
		(end 393.099798 -273.59864)
		(width 0.0889)
		(layer "In2.Cu")
		(net "M_I_CPU0_SB_CB<1>")
	)
	(arc
		(start 380.88189 -273.59864)
		(mid 381.164846 -273.522463)
		(end 381.447802 -273.59864)
		(width 0.0889)
		(layer "In2.Cu")
		(net "M_I_CPU0_SB_CB<1>")
	)
	(arc
		(start 389.916162 -273.603466)
		(mid 390.09967 -273.64896)
		(end 390.281922 -273.59864)
		(width 0.0889)
		(layer "In2.Cu")
		(net "M_I_CPU0_SB_CB<1>")
	)
	(arc
		(start 378.627894 -273.59864)
		(mid 378.814838 -273.648895)
		(end 379.001782 -273.59864)
		(width 0.0889)
		(layer "In2.Cu")
		(net "M_I_CPU0_SB_CB<1>")
	)
	(arc
		(start 388.401814 -273.59864)
		(mid 388.68477 -273.522463)
		(end 388.967726 -273.59864)
		(width 0.0889)
		(layer "In2.Cu")
		(net "M_I_CPU0_SB_CB<1>")
	)
	(arc
		(start 390.281922 -273.59864)
		(mid 390.564878 -273.522463)
		(end 390.847834 -273.59864)
		(width 0.0889)
		(layer "In2.Cu")
		(net "M_I_CPU0_SB_CB<1>")
	)
	(arc
		(start 386.1562 -273.603466)
		(mid 386.339708 -273.64896)
		(end 386.52196 -273.59864)
		(width 0.0889)
		(layer "In2.Cu")
		(net "M_I_CPU0_SB_CB<1>")
	)
	(arc
		(start 379.567694 -273.59864)
		(mid 379.749945 -273.64899)
		(end 379.933454 -273.603466)
		(width 0.0889)
		(layer "In2.Cu")
		(net "M_I_CPU0_SB_CB<1>")
	)
	(arc
		(start 387.46176 -273.59864)
		(mid 387.744716 -273.522463)
		(end 388.027672 -273.59864)
		(width 0.0889)
		(layer "In2.Cu")
		(net "M_I_CPU0_SB_CB<1>")
	)
	(arc
		(start 392.186668 -273.5834)
		(mid 392.457454 -273.522754)
		(end 392.724386 -273.59864)
		(width 0.0889)
		(layer "In2.Cu")
		(net "M_I_CPU0_SB_CB<1>")
	)
	(arc
		(start 380.507748 -273.59864)
		(mid 380.689999 -273.64899)
		(end 380.873508 -273.603466)
		(width 0.0889)
		(layer "In2.Cu")
		(net "M_I_CPU0_SB_CB<1>")
	)
	(arc
		(start 388.027672 -273.59864)
		(mid 388.209923 -273.64899)
		(end 388.393432 -273.603466)
		(width 0.0889)
		(layer "In2.Cu")
		(net "M_I_CPU0_SB_CB<1>")
	)
	(arc
		(start 381.821944 -273.59864)
		(mid 382.1049 -273.522463)
		(end 382.387856 -273.59864)
		(width 0.0889)
		(layer "In2.Cu")
		(net "M_I_CPU0_SB_CB<1>")
	)
	(arc
		(start 382.761744 -273.59864)
		(mid 383.0447 -273.522463)
		(end 383.327656 -273.59864)
		(width 0.0889)
		(layer "In2.Cu")
		(net "M_I_CPU0_SB_CB<1>")
	)
	(arc
		(start 377.121928 -273.59864)
		(mid 377.404884 -273.522463)
		(end 377.68784 -273.59864)
		(width 0.0889)
		(layer "In2.Cu")
		(net "M_I_CPU0_SB_CB<1>")
	)
	(arc
		(start 382.387856 -273.59864)
		(mid 382.5748 -273.648895)
		(end 382.761744 -273.59864)
		(width 0.0889)
		(layer "In2.Cu")
		(net "M_I_CPU0_SB_CB<1>")
	)
	(arc
		(start 385.581906 -273.59864)
		(mid 385.864862 -273.522463)
		(end 386.147818 -273.59864)
		(width 0.0889)
		(layer "In2.Cu")
		(net "M_I_CPU0_SB_CB<1>")
	)
	(segment
		(start 376.938032 -272.200116)
		(end 377.404884 -272.466054)
		(width 0.10668)
		(layer "F.Cu")
		(net "M_I_CPU0_SB_CB<0>")
	)
	(segment
		(start 430.573434 -277.6601)
		(end 431.131218 -277.6601)
		(width 0.14478)
		(layer "In2.Cu")
		(net "M_I_CPU0_SB_CB<0>")
	)
	(segment
		(start 382.857756 -272.788634)
		(end 382.866138 -272.79346)
		(width 0.0889)
		(layer "In2.Cu")
		(net "M_I_CPU0_SB_CB<0>")
	)
	(segment
		(start 386.983478 -272.79346)
		(end 386.99186 -272.788634)
		(width 0.0889)
		(layer "In2.Cu")
		(net "M_I_CPU0_SB_CB<0>")
	)
	(segment
		(start 393.198096 -272.78838)
		(end 393.216384 -272.798794)
		(width 0.0889)
		(layer "In2.Cu")
		(net "M_I_CPU0_SB_CB<0>")
	)
	(segment
		(start 386.043424 -272.79346)
		(end 386.051806 -272.788634)
		(width 0.0889)
		(layer "In2.Cu")
		(net "M_I_CPU0_SB_CB<0>")
	)
	(segment
		(start 430.273714 -278.18461)
		(end 430.423574 -278.03475)
		(width 0.14478)
		(layer "In2.Cu")
		(net "M_I_CPU0_SB_CB<0>")
	)
	(segment
		(start 415.023046 -277.669752)
		(end 417.674298 -277.669752)
		(width 0.14478)
		(layer "In2.Cu")
		(net "M_I_CPU0_SB_CB<0>")
	)
	(segment
		(start 430.423574 -277.80996)
		(end 430.573434 -277.6601)
		(width 0.14478)
		(layer "In2.Cu")
		(net "M_I_CPU0_SB_CB<0>")
	)
	(segment
		(start 421.515794 -278.51989)
		(end 422.365932 -277.669752)
		(width 0.14478)
		(layer "In2.Cu")
		(net "M_I_CPU0_SB_CB<0>")
	)
	(segment
		(start 377.404884 -272.466054)
		(end 377.558808 -272.731484)
		(width 0.0889)
		(layer "In2.Cu")
		(net "M_I_CPU0_SB_CB<0>")
	)
	(segment
		(start 431.131218 -277.6601)
		(end 431.55616 -278.085042)
		(width 0.14478)
		(layer "In2.Cu")
		(net "M_I_CPU0_SB_CB<0>")
	)
	(segment
		(start 422.365932 -277.669752)
		(end 429.719994 -277.669752)
		(width 0.14478)
		(layer "In2.Cu")
		(net "M_I_CPU0_SB_CB<0>")
	)
	(segment
		(start 429.864774 -278.03475)
		(end 430.014634 -278.18461)
		(width 0.14478)
		(layer "In2.Cu")
		(net "M_I_CPU0_SB_CB<0>")
	)
	(segment
		(start 414.172908 -278.51989)
		(end 415.023046 -277.669752)
		(width 0.14478)
		(layer "In2.Cu")
		(net "M_I_CPU0_SB_CB<0>")
	)
	(segment
		(start 429.719994 -277.669752)
		(end 429.864774 -277.814532)
		(width 0.14478)
		(layer "In2.Cu")
		(net "M_I_CPU0_SB_CB<0>")
	)
	(segment
		(start 430.014634 -278.18461)
		(end 430.273714 -278.18461)
		(width 0.14478)
		(layer "In2.Cu")
		(net "M_I_CPU0_SB_CB<0>")
	)
	(segment
		(start 418.524436 -278.51989)
		(end 421.515794 -278.51989)
		(width 0.14478)
		(layer "In2.Cu")
		(net "M_I_CPU0_SB_CB<0>")
	)
	(segment
		(start 395.94155 -271.01927)
		(end 403.0345 -271.01927)
		(width 0.14478)
		(layer "In2.Cu")
		(net "M_I_CPU0_SB_CB<0>")
	)
	(segment
		(start 410.53512 -278.51989)
		(end 414.172908 -278.51989)
		(width 0.14478)
		(layer "In2.Cu")
		(net "M_I_CPU0_SB_CB<0>")
	)
	(segment
		(start 380.037848 -272.788634)
		(end 380.04623 -272.79346)
		(width 0.0889)
		(layer "In2.Cu")
		(net "M_I_CPU0_SB_CB<0>")
	)
	(segment
		(start 383.79781 -272.788634)
		(end 383.806192 -272.79346)
		(width 0.0889)
		(layer "In2.Cu")
		(net "M_I_CPU0_SB_CB<0>")
	)
	(segment
		(start 392.257788 -272.788634)
		(end 392.269472 -272.795492)
		(width 0.0889)
		(layer "In2.Cu")
		(net "M_I_CPU0_SB_CB<0>")
	)
	(segment
		(start 378.5235 -272.79346)
		(end 378.531882 -272.788634)
		(width 0.0889)
		(layer "In2.Cu")
		(net "M_I_CPU0_SB_CB<0>")
	)
	(segment
		(start 417.674298 -277.669752)
		(end 418.524436 -278.51989)
		(width 0.14478)
		(layer "In2.Cu")
		(net "M_I_CPU0_SB_CB<0>")
	)
	(segment
		(start 394.412216 -271.660366)
		(end 394.584174 -271.24533)
		(width 0.0889)
		(layer "In2.Cu")
		(net "M_I_CPU0_SB_CB<0>")
	)
	(segment
		(start 379.097794 -272.788634)
		(end 379.106176 -272.79346)
		(width 0.0889)
		(layer "In2.Cu")
		(net "M_I_CPU0_SB_CB<0>")
	)
	(segment
		(start 393.572238 -272.788634)
		(end 393.728194 -272.683986)
		(width 0.0889)
		(layer "In2.Cu")
		(net "M_I_CPU0_SB_CB<0>")
	)
	(segment
		(start 430.423574 -278.03475)
		(end 430.423574 -277.80996)
		(width 0.14478)
		(layer "In2.Cu")
		(net "M_I_CPU0_SB_CB<0>")
	)
	(segment
		(start 394.584174 -271.24533)
		(end 394.810234 -271.01927)
		(width 0.0889)
		(layer "In2.Cu")
		(net "M_I_CPU0_SB_CB<0>")
	)
	(segment
		(start 429.864774 -277.814532)
		(end 429.864774 -278.03475)
		(width 0.14478)
		(layer "In2.Cu")
		(net "M_I_CPU0_SB_CB<0>")
	)
	(segment
		(start 382.283462 -272.79346)
		(end 382.291844 -272.788634)
		(width 0.0889)
		(layer "In2.Cu")
		(net "M_I_CPU0_SB_CB<0>")
	)
	(segment
		(start 391.317734 -272.788634)
		(end 391.326116 -272.79346)
		(width 0.0889)
		(layer "In2.Cu")
		(net "M_I_CPU0_SB_CB<0>")
	)
	(segment
		(start 388.497826 -272.788634)
		(end 388.506208 -272.79346)
		(width 0.0889)
		(layer "In2.Cu")
		(net "M_I_CPU0_SB_CB<0>")
	)
	(segment
		(start 393.728194 -272.683986)
		(end 394.412216 -271.660366)
		(width 0.0889)
		(layer "In2.Cu")
		(net "M_I_CPU0_SB_CB<0>")
	)
	(segment
		(start 390.74344 -272.79346)
		(end 390.751822 -272.788634)
		(width 0.0889)
		(layer "In2.Cu")
		(net "M_I_CPU0_SB_CB<0>")
	)
	(segment
		(start 387.557772 -272.788634)
		(end 387.566154 -272.79346)
		(width 0.0889)
		(layer "In2.Cu")
		(net "M_I_CPU0_SB_CB<0>")
	)
	(segment
		(start 394.810234 -271.01927)
		(end 395.94155 -271.01927)
		(width 0.0889)
		(layer "In2.Cu")
		(net "M_I_CPU0_SB_CB<0>")
	)
	(segment
		(start 393.182348 -272.779236)
		(end 393.198096 -272.78838)
		(width 0.0889)
		(layer "In2.Cu")
		(net "M_I_CPU0_SB_CB<0>")
	)
	(segment
		(start 377.558808 -272.731484)
		(end 377.65482 -272.756884)
		(width 0.0889)
		(layer "In2.Cu")
		(net "M_I_CPU0_SB_CB<0>")
	)
	(segment
		(start 403.0345 -271.01927)
		(end 410.53512 -278.51989)
		(width 0.14478)
		(layer "In2.Cu")
		(net "M_I_CPU0_SB_CB<0>")
	)
	(arc
		(start 384.737864 -272.788634)
		(mid 384.924808 -272.838889)
		(end 385.111752 -272.788634)
		(width 0.0889)
		(layer "In2.Cu")
		(net "M_I_CPU0_SB_CB<0>")
	)
	(arc
		(start 389.43788 -272.788634)
		(mid 389.624824 -272.838889)
		(end 389.811768 -272.788634)
		(width 0.0889)
		(layer "In2.Cu")
		(net "M_I_CPU0_SB_CB<0>")
	)
	(arc
		(start 393.216384 -272.798794)
		(mid 393.395613 -272.838947)
		(end 393.572238 -272.788634)
		(width 0.0889)
		(layer "In2.Cu")
		(net "M_I_CPU0_SB_CB<0>")
	)
	(arc
		(start 384.171952 -272.788634)
		(mid 384.454908 -272.712457)
		(end 384.737864 -272.788634)
		(width 0.0889)
		(layer "In2.Cu")
		(net "M_I_CPU0_SB_CB<0>")
	)
	(arc
		(start 391.326116 -272.79346)
		(mid 391.509624 -272.838954)
		(end 391.691876 -272.788634)
		(width 0.0889)
		(layer "In2.Cu")
		(net "M_I_CPU0_SB_CB<0>")
	)
	(arc
		(start 383.231898 -272.788634)
		(mid 383.514854 -272.712457)
		(end 383.79781 -272.788634)
		(width 0.0889)
		(layer "In2.Cu")
		(net "M_I_CPU0_SB_CB<0>")
	)
	(arc
		(start 379.106176 -272.79346)
		(mid 379.289684 -272.838954)
		(end 379.471936 -272.788634)
		(width 0.0889)
		(layer "In2.Cu")
		(net "M_I_CPU0_SB_CB<0>")
	)
	(arc
		(start 377.65482 -272.756884)
		(mid 377.910028 -272.713407)
		(end 378.15774 -272.788634)
		(width 0.0889)
		(layer "In2.Cu")
		(net "M_I_CPU0_SB_CB<0>")
	)
	(arc
		(start 386.051806 -272.788634)
		(mid 386.334762 -272.712457)
		(end 386.617718 -272.788634)
		(width 0.0889)
		(layer "In2.Cu")
		(net "M_I_CPU0_SB_CB<0>")
	)
	(arc
		(start 390.37768 -272.788634)
		(mid 390.559931 -272.838984)
		(end 390.74344 -272.79346)
		(width 0.0889)
		(layer "In2.Cu")
		(net "M_I_CPU0_SB_CB<0>")
	)
	(arc
		(start 385.111752 -272.788634)
		(mid 385.394708 -272.712457)
		(end 385.677664 -272.788634)
		(width 0.0889)
		(layer "In2.Cu")
		(net "M_I_CPU0_SB_CB<0>")
	)
	(arc
		(start 379.471936 -272.788634)
		(mid 379.754892 -272.712457)
		(end 380.037848 -272.788634)
		(width 0.0889)
		(layer "In2.Cu")
		(net "M_I_CPU0_SB_CB<0>")
	)
	(arc
		(start 382.866138 -272.79346)
		(mid 383.049646 -272.838954)
		(end 383.231898 -272.788634)
		(width 0.0889)
		(layer "In2.Cu")
		(net "M_I_CPU0_SB_CB<0>")
	)
	(arc
		(start 387.566154 -272.79346)
		(mid 387.749662 -272.838954)
		(end 387.931914 -272.788634)
		(width 0.0889)
		(layer "In2.Cu")
		(net "M_I_CPU0_SB_CB<0>")
	)
	(arc
		(start 378.531882 -272.788634)
		(mid 378.814838 -272.712457)
		(end 379.097794 -272.788634)
		(width 0.0889)
		(layer "In2.Cu")
		(net "M_I_CPU0_SB_CB<0>")
	)
	(arc
		(start 380.41199 -272.788634)
		(mid 380.694946 -272.712457)
		(end 380.977902 -272.788634)
		(width 0.0889)
		(layer "In2.Cu")
		(net "M_I_CPU0_SB_CB<0>")
	)
	(arc
		(start 382.291844 -272.788634)
		(mid 382.5748 -272.712457)
		(end 382.857756 -272.788634)
		(width 0.0889)
		(layer "In2.Cu")
		(net "M_I_CPU0_SB_CB<0>")
	)
	(arc
		(start 392.632184 -272.788634)
		(mid 392.906039 -272.712284)
		(end 393.182348 -272.779236)
		(width 0.0889)
		(layer "In2.Cu")
		(net "M_I_CPU0_SB_CB<0>")
	)
	(arc
		(start 391.691876 -272.788634)
		(mid 391.974832 -272.712457)
		(end 392.257788 -272.788634)
		(width 0.0889)
		(layer "In2.Cu")
		(net "M_I_CPU0_SB_CB<0>")
	)
	(arc
		(start 386.99186 -272.788634)
		(mid 387.274816 -272.712457)
		(end 387.557772 -272.788634)
		(width 0.0889)
		(layer "In2.Cu")
		(net "M_I_CPU0_SB_CB<0>")
	)
	(arc
		(start 388.506208 -272.79346)
		(mid 388.689716 -272.838954)
		(end 388.871968 -272.788634)
		(width 0.0889)
		(layer "In2.Cu")
		(net "M_I_CPU0_SB_CB<0>")
	)
	(arc
		(start 381.35179 -272.788634)
		(mid 381.634746 -272.712457)
		(end 381.917702 -272.788634)
		(width 0.0889)
		(layer "In2.Cu")
		(net "M_I_CPU0_SB_CB<0>")
	)
	(arc
		(start 387.931914 -272.788634)
		(mid 388.21487 -272.712457)
		(end 388.497826 -272.788634)
		(width 0.0889)
		(layer "In2.Cu")
		(net "M_I_CPU0_SB_CB<0>")
	)
	(arc
		(start 380.04623 -272.79346)
		(mid 380.229738 -272.838954)
		(end 380.41199 -272.788634)
		(width 0.0889)
		(layer "In2.Cu")
		(net "M_I_CPU0_SB_CB<0>")
	)
	(arc
		(start 383.806192 -272.79346)
		(mid 383.9897 -272.838954)
		(end 384.171952 -272.788634)
		(width 0.0889)
		(layer "In2.Cu")
		(net "M_I_CPU0_SB_CB<0>")
	)
	(arc
		(start 388.871968 -272.788634)
		(mid 389.154924 -272.712457)
		(end 389.43788 -272.788634)
		(width 0.0889)
		(layer "In2.Cu")
		(net "M_I_CPU0_SB_CB<0>")
	)
	(arc
		(start 381.917702 -272.788634)
		(mid 382.099953 -272.838984)
		(end 382.283462 -272.79346)
		(width 0.0889)
		(layer "In2.Cu")
		(net "M_I_CPU0_SB_CB<0>")
	)
	(arc
		(start 385.677664 -272.788634)
		(mid 385.859915 -272.838984)
		(end 386.043424 -272.79346)
		(width 0.0889)
		(layer "In2.Cu")
		(net "M_I_CPU0_SB_CB<0>")
	)
	(arc
		(start 392.269472 -272.795492)
		(mid 392.451727 -272.839145)
		(end 392.632184 -272.788634)
		(width 0.0889)
		(layer "In2.Cu")
		(net "M_I_CPU0_SB_CB<0>")
	)
	(arc
		(start 386.617718 -272.788634)
		(mid 386.799969 -272.838984)
		(end 386.983478 -272.79346)
		(width 0.0889)
		(layer "In2.Cu")
		(net "M_I_CPU0_SB_CB<0>")
	)
	(arc
		(start 390.751822 -272.788634)
		(mid 391.034778 -272.712457)
		(end 391.317734 -272.788634)
		(width 0.0889)
		(layer "In2.Cu")
		(net "M_I_CPU0_SB_CB<0>")
	)
	(arc
		(start 380.977902 -272.788634)
		(mid 381.164846 -272.838889)
		(end 381.35179 -272.788634)
		(width 0.0889)
		(layer "In2.Cu")
		(net "M_I_CPU0_SB_CB<0>")
	)
	(arc
		(start 378.15774 -272.788634)
		(mid 378.339991 -272.838984)
		(end 378.5235 -272.79346)
		(width 0.0889)
		(layer "In2.Cu")
		(net "M_I_CPU0_SB_CB<0>")
	)
	(arc
		(start 389.811768 -272.788634)
		(mid 390.094724 -272.712457)
		(end 390.37768 -272.788634)
		(width 0.0889)
		(layer "In2.Cu")
		(net "M_I_CPU0_SB_CB<0>")
	)
	(segment
		(start 376.938032 -264.100056)
		(end 377.404884 -264.365994)
		(width 0.10668)
		(layer "F.Cu")
		(net "M_I_CPU0_SB_CA<6>")
	)
	(segment
		(start 377.558808 -264.631424)
		(end 377.65482 -264.656824)
		(width 0.0889)
		(layer "In2.Cu")
		(net "M_I_CPU0_SB_CA<6>")
	)
	(segment
		(start 388.497826 -264.688574)
		(end 388.506208 -264.6934)
		(width 0.0889)
		(layer "In2.Cu")
		(net "M_I_CPU0_SB_CA<6>")
	)
	(segment
		(start 382.857756 -264.688574)
		(end 382.866138 -264.6934)
		(width 0.0889)
		(layer "In2.Cu")
		(net "M_I_CPU0_SB_CA<6>")
	)
	(segment
		(start 390.74344 -264.6934)
		(end 390.751822 -264.688574)
		(width 0.0889)
		(layer "In2.Cu")
		(net "M_I_CPU0_SB_CA<6>")
	)
	(segment
		(start 378.5235 -264.6934)
		(end 378.531882 -264.688574)
		(width 0.0889)
		(layer "In2.Cu")
		(net "M_I_CPU0_SB_CA<6>")
	)
	(segment
		(start 393.198096 -264.68832)
		(end 393.216384 -264.698734)
		(width 0.0889)
		(layer "In2.Cu")
		(net "M_I_CPU0_SB_CA<6>")
	)
	(segment
		(start 386.043424 -264.6934)
		(end 386.051806 -264.688574)
		(width 0.0889)
		(layer "In2.Cu")
		(net "M_I_CPU0_SB_CA<6>")
	)
	(segment
		(start 393.572238 -264.688574)
		(end 393.87653 -264.384282)
		(width 0.0889)
		(layer "In2.Cu")
		(net "M_I_CPU0_SB_CA<6>")
	)
	(segment
		(start 379.097794 -264.688574)
		(end 379.106176 -264.6934)
		(width 0.0889)
		(layer "In2.Cu")
		(net "M_I_CPU0_SB_CA<6>")
	)
	(segment
		(start 382.283462 -264.6934)
		(end 382.291844 -264.688574)
		(width 0.0889)
		(layer "In2.Cu")
		(net "M_I_CPU0_SB_CA<6>")
	)
	(segment
		(start 377.404884 -264.365994)
		(end 377.558808 -264.631424)
		(width 0.0889)
		(layer "In2.Cu")
		(net "M_I_CPU0_SB_CA<6>")
	)
	(segment
		(start 393.87653 -264.384282)
		(end 393.98575 -264.33907)
		(width 0.0889)
		(layer "In2.Cu")
		(net "M_I_CPU0_SB_CA<6>")
	)
	(segment
		(start 393.98575 -264.33907)
		(end 395.45006 -264.33907)
		(width 0.0889)
		(layer "In2.Cu")
		(net "M_I_CPU0_SB_CA<6>")
	)
	(segment
		(start 391.317734 -264.688574)
		(end 391.326116 -264.6934)
		(width 0.0889)
		(layer "In2.Cu")
		(net "M_I_CPU0_SB_CA<6>")
	)
	(segment
		(start 380.037848 -264.688574)
		(end 380.04623 -264.6934)
		(width 0.0889)
		(layer "In2.Cu")
		(net "M_I_CPU0_SB_CA<6>")
	)
	(segment
		(start 393.182348 -264.679176)
		(end 393.198096 -264.68832)
		(width 0.0889)
		(layer "In2.Cu")
		(net "M_I_CPU0_SB_CA<6>")
	)
	(segment
		(start 431.131218 -266.610084)
		(end 431.55616 -266.185142)
		(width 0.14478)
		(layer "In2.Cu")
		(net "M_I_CPU0_SB_CA<6>")
	)
	(segment
		(start 387.557772 -264.688574)
		(end 387.566154 -264.6934)
		(width 0.0889)
		(layer "In2.Cu")
		(net "M_I_CPU0_SB_CA<6>")
	)
	(segment
		(start 386.983478 -264.6934)
		(end 386.99186 -264.688574)
		(width 0.0889)
		(layer "In2.Cu")
		(net "M_I_CPU0_SB_CA<6>")
	)
	(segment
		(start 406.848056 -264.33907)
		(end 411.648402 -266.610084)
		(width 0.14478)
		(layer "In2.Cu")
		(net "M_I_CPU0_SB_CA<6>")
	)
	(segment
		(start 392.257788 -264.688574)
		(end 392.269472 -264.695432)
		(width 0.0889)
		(layer "In2.Cu")
		(net "M_I_CPU0_SB_CA<6>")
	)
	(segment
		(start 395.45006 -264.33907)
		(end 406.848056 -264.33907)
		(width 0.14478)
		(layer "In2.Cu")
		(net "M_I_CPU0_SB_CA<6>")
	)
	(segment
		(start 383.79781 -264.688574)
		(end 383.806192 -264.6934)
		(width 0.0889)
		(layer "In2.Cu")
		(net "M_I_CPU0_SB_CA<6>")
	)
	(segment
		(start 411.648402 -266.610084)
		(end 431.131218 -266.610084)
		(width 0.14478)
		(layer "In2.Cu")
		(net "M_I_CPU0_SB_CA<6>")
	)
	(arc
		(start 382.866138 -264.6934)
		(mid 383.049646 -264.738894)
		(end 383.231898 -264.688574)
		(width 0.0889)
		(layer "In2.Cu")
		(net "M_I_CPU0_SB_CA<6>")
	)
	(arc
		(start 392.269472 -264.695432)
		(mid 392.451727 -264.739085)
		(end 392.632184 -264.688574)
		(width 0.0889)
		(layer "In2.Cu")
		(net "M_I_CPU0_SB_CA<6>")
	)
	(arc
		(start 381.35179 -264.688574)
		(mid 381.634746 -264.612397)
		(end 381.917702 -264.688574)
		(width 0.0889)
		(layer "In2.Cu")
		(net "M_I_CPU0_SB_CA<6>")
	)
	(arc
		(start 389.811768 -264.688574)
		(mid 390.094724 -264.612397)
		(end 390.37768 -264.688574)
		(width 0.0889)
		(layer "In2.Cu")
		(net "M_I_CPU0_SB_CA<6>")
	)
	(arc
		(start 383.231898 -264.688574)
		(mid 383.514854 -264.612397)
		(end 383.79781 -264.688574)
		(width 0.0889)
		(layer "In2.Cu")
		(net "M_I_CPU0_SB_CA<6>")
	)
	(arc
		(start 385.677664 -264.688574)
		(mid 385.859915 -264.738924)
		(end 386.043424 -264.6934)
		(width 0.0889)
		(layer "In2.Cu")
		(net "M_I_CPU0_SB_CA<6>")
	)
	(arc
		(start 386.051806 -264.688574)
		(mid 386.334762 -264.612397)
		(end 386.617718 -264.688574)
		(width 0.0889)
		(layer "In2.Cu")
		(net "M_I_CPU0_SB_CA<6>")
	)
	(arc
		(start 386.99186 -264.688574)
		(mid 387.274816 -264.612397)
		(end 387.557772 -264.688574)
		(width 0.0889)
		(layer "In2.Cu")
		(net "M_I_CPU0_SB_CA<6>")
	)
	(arc
		(start 387.931914 -264.688574)
		(mid 388.21487 -264.612397)
		(end 388.497826 -264.688574)
		(width 0.0889)
		(layer "In2.Cu")
		(net "M_I_CPU0_SB_CA<6>")
	)
	(arc
		(start 380.04623 -264.6934)
		(mid 380.229738 -264.738894)
		(end 380.41199 -264.688574)
		(width 0.0889)
		(layer "In2.Cu")
		(net "M_I_CPU0_SB_CA<6>")
	)
	(arc
		(start 384.737864 -264.688574)
		(mid 384.924808 -264.738829)
		(end 385.111752 -264.688574)
		(width 0.0889)
		(layer "In2.Cu")
		(net "M_I_CPU0_SB_CA<6>")
	)
	(arc
		(start 379.471936 -264.688574)
		(mid 379.754892 -264.612397)
		(end 380.037848 -264.688574)
		(width 0.0889)
		(layer "In2.Cu")
		(net "M_I_CPU0_SB_CA<6>")
	)
	(arc
		(start 383.806192 -264.6934)
		(mid 383.9897 -264.738894)
		(end 384.171952 -264.688574)
		(width 0.0889)
		(layer "In2.Cu")
		(net "M_I_CPU0_SB_CA<6>")
	)
	(arc
		(start 388.871968 -264.688574)
		(mid 389.154924 -264.612397)
		(end 389.43788 -264.688574)
		(width 0.0889)
		(layer "In2.Cu")
		(net "M_I_CPU0_SB_CA<6>")
	)
	(arc
		(start 385.111752 -264.688574)
		(mid 385.394708 -264.612397)
		(end 385.677664 -264.688574)
		(width 0.0889)
		(layer "In2.Cu")
		(net "M_I_CPU0_SB_CA<6>")
	)
	(arc
		(start 382.291844 -264.688574)
		(mid 382.5748 -264.612397)
		(end 382.857756 -264.688574)
		(width 0.0889)
		(layer "In2.Cu")
		(net "M_I_CPU0_SB_CA<6>")
	)
	(arc
		(start 387.566154 -264.6934)
		(mid 387.749662 -264.738894)
		(end 387.931914 -264.688574)
		(width 0.0889)
		(layer "In2.Cu")
		(net "M_I_CPU0_SB_CA<6>")
	)
	(arc
		(start 389.43788 -264.688574)
		(mid 389.624824 -264.738829)
		(end 389.811768 -264.688574)
		(width 0.0889)
		(layer "In2.Cu")
		(net "M_I_CPU0_SB_CA<6>")
	)
	(arc
		(start 391.691876 -264.688574)
		(mid 391.974832 -264.612397)
		(end 392.257788 -264.688574)
		(width 0.0889)
		(layer "In2.Cu")
		(net "M_I_CPU0_SB_CA<6>")
	)
	(arc
		(start 390.37768 -264.688574)
		(mid 390.559931 -264.738924)
		(end 390.74344 -264.6934)
		(width 0.0889)
		(layer "In2.Cu")
		(net "M_I_CPU0_SB_CA<6>")
	)
	(arc
		(start 388.506208 -264.6934)
		(mid 388.689716 -264.738894)
		(end 388.871968 -264.688574)
		(width 0.0889)
		(layer "In2.Cu")
		(net "M_I_CPU0_SB_CA<6>")
	)
	(arc
		(start 378.15774 -264.688574)
		(mid 378.339991 -264.738924)
		(end 378.5235 -264.6934)
		(width 0.0889)
		(layer "In2.Cu")
		(net "M_I_CPU0_SB_CA<6>")
	)
	(arc
		(start 378.531882 -264.688574)
		(mid 378.814838 -264.612397)
		(end 379.097794 -264.688574)
		(width 0.0889)
		(layer "In2.Cu")
		(net "M_I_CPU0_SB_CA<6>")
	)
	(arc
		(start 379.106176 -264.6934)
		(mid 379.289684 -264.738894)
		(end 379.471936 -264.688574)
		(width 0.0889)
		(layer "In2.Cu")
		(net "M_I_CPU0_SB_CA<6>")
	)
	(arc
		(start 380.41199 -264.688574)
		(mid 380.694946 -264.612397)
		(end 380.977902 -264.688574)
		(width 0.0889)
		(layer "In2.Cu")
		(net "M_I_CPU0_SB_CA<6>")
	)
	(arc
		(start 390.751822 -264.688574)
		(mid 391.034778 -264.612397)
		(end 391.317734 -264.688574)
		(width 0.0889)
		(layer "In2.Cu")
		(net "M_I_CPU0_SB_CA<6>")
	)
	(arc
		(start 381.917702 -264.688574)
		(mid 382.099953 -264.738924)
		(end 382.283462 -264.6934)
		(width 0.0889)
		(layer "In2.Cu")
		(net "M_I_CPU0_SB_CA<6>")
	)
	(arc
		(start 384.171952 -264.688574)
		(mid 384.454908 -264.612397)
		(end 384.737864 -264.688574)
		(width 0.0889)
		(layer "In2.Cu")
		(net "M_I_CPU0_SB_CA<6>")
	)
	(arc
		(start 392.632184 -264.688574)
		(mid 392.906039 -264.612224)
		(end 393.182348 -264.679176)
		(width 0.0889)
		(layer "In2.Cu")
		(net "M_I_CPU0_SB_CA<6>")
	)
	(arc
		(start 393.216384 -264.698734)
		(mid 393.395613 -264.738887)
		(end 393.572238 -264.688574)
		(width 0.0889)
		(layer "In2.Cu")
		(net "M_I_CPU0_SB_CA<6>")
	)
	(arc
		(start 386.617718 -264.688574)
		(mid 386.799969 -264.738924)
		(end 386.983478 -264.6934)
		(width 0.0889)
		(layer "In2.Cu")
		(net "M_I_CPU0_SB_CA<6>")
	)
	(arc
		(start 377.65482 -264.656824)
		(mid 377.910028 -264.613347)
		(end 378.15774 -264.688574)
		(width 0.0889)
		(layer "In2.Cu")
		(net "M_I_CPU0_SB_CA<6>")
	)
	(arc
		(start 391.326116 -264.6934)
		(mid 391.509624 -264.738894)
		(end 391.691876 -264.688574)
		(width 0.0889)
		(layer "In2.Cu")
		(net "M_I_CPU0_SB_CA<6>")
	)
	(arc
		(start 380.977902 -264.688574)
		(mid 381.164846 -264.738829)
		(end 381.35179 -264.688574)
		(width 0.0889)
		(layer "In2.Cu")
		(net "M_I_CPU0_SB_CA<6>")
	)
	(segment
		(start 375.997978 -264.100056)
		(end 376.46483 -264.365994)
		(width 0.10668)
		(layer "F.Cu")
		(net "M_I_CPU0_SB_CA<5>")
	)
	(segment
		(start 382.857756 -264.043414)
		(end 382.866138 -264.038588)
		(width 0.0889)
		(layer "In2.Cu")
		(net "M_I_CPU0_SB_CA<5>")
	)
	(segment
		(start 408.579828 -264.489184)
		(end 408.834336 -264.594594)
		(width 0.14478)
		(layer "In2.Cu")
		(net "M_I_CPU0_SB_CA<5>")
	)
	(segment
		(start 414.049464 -265.46429)
		(end 414.345374 -265.7602)
		(width 0.14478)
		(layer "In2.Cu")
		(net "M_I_CPU0_SB_CA<5>")
	)
	(segment
		(start 415.167064 -265.46429)
		(end 415.462974 -265.7602)
		(width 0.14478)
		(layer "In2.Cu")
		(net "M_I_CPU0_SB_CA<5>")
	)
	(segment
		(start 410.237686 -264.868406)
		(end 410.491686 -264.973816)
		(width 0.14478)
		(layer "In2.Cu")
		(net "M_I_CPU0_SB_CA<5>")
	)
	(segment
		(start 407.119582 -263.88441)
		(end 407.801572 -264.166858)
		(width 0.14478)
		(layer "In2.Cu")
		(net "M_I_CPU0_SB_CA<5>")
	)
	(segment
		(start 410.491686 -264.973816)
		(end 410.645356 -265.344656)
		(width 0.14478)
		(layer "In2.Cu")
		(net "M_I_CPU0_SB_CA<5>")
	)
	(segment
		(start 391.317734 -264.043414)
		(end 391.326116 -264.038588)
		(width 0.0889)
		(layer "In2.Cu")
		(net "M_I_CPU0_SB_CA<5>")
	)
	(segment
		(start 393.31392 -263.999218)
		(end 395.36243 -263.999218)
		(width 0.0889)
		(layer "In2.Cu")
		(net "M_I_CPU0_SB_CA<5>")
	)
	(segment
		(start 409.458922 -264.54608)
		(end 409.612592 -264.91692)
		(width 0.14478)
		(layer "In2.Cu")
		(net "M_I_CPU0_SB_CA<5>")
	)
	(segment
		(start 376.46483 -264.365994)
		(end 376.310906 -264.100564)
		(width 0.0889)
		(layer "In2.Cu")
		(net "M_I_CPU0_SB_CA<5>")
	)
	(segment
		(start 410.645356 -265.344656)
		(end 411.0609 -265.7602)
		(width 0.14478)
		(layer "In2.Cu")
		(net "M_I_CPU0_SB_CA<5>")
	)
	(segment
		(start 390.74344 -264.038588)
		(end 390.751822 -264.043414)
		(width 0.0889)
		(layer "In2.Cu")
		(net "M_I_CPU0_SB_CA<5>")
	)
	(segment
		(start 414.904174 -265.46429)
		(end 415.167064 -265.46429)
		(width 0.14478)
		(layer "In2.Cu")
		(net "M_I_CPU0_SB_CA<5>")
	)
	(segment
		(start 409.204922 -264.44067)
		(end 409.458922 -264.54608)
		(width 0.14478)
		(layer "In2.Cu")
		(net "M_I_CPU0_SB_CA<5>")
	)
	(segment
		(start 379.097794 -264.043414)
		(end 379.106176 -264.038588)
		(width 0.0889)
		(layer "In2.Cu")
		(net "M_I_CPU0_SB_CA<5>")
	)
	(segment
		(start 409.8671 -265.02233)
		(end 410.237686 -264.868406)
		(width 0.14478)
		(layer "In2.Cu")
		(net "M_I_CPU0_SB_CA<5>")
	)
	(segment
		(start 408.172158 -264.012934)
		(end 408.426158 -264.118344)
		(width 0.14478)
		(layer "In2.Cu")
		(net "M_I_CPU0_SB_CA<5>")
	)
	(segment
		(start 392.229594 -264.058654)
		(end 392.255756 -264.043668)
		(width 0.0889)
		(layer "In2.Cu")
		(net "M_I_CPU0_SB_CA<5>")
	)
	(segment
		(start 408.426158 -264.118344)
		(end 408.579828 -264.489184)
		(width 0.14478)
		(layer "In2.Cu")
		(net "M_I_CPU0_SB_CA<5>")
	)
	(segment
		(start 395.477238 -263.88441)
		(end 407.119582 -263.88441)
		(width 0.14478)
		(layer "In2.Cu")
		(net "M_I_CPU0_SB_CA<5>")
	)
	(segment
		(start 414.345374 -265.7602)
		(end 414.608264 -265.7602)
		(width 0.14478)
		(layer "In2.Cu")
		(net "M_I_CPU0_SB_CA<5>")
	)
	(segment
		(start 388.497826 -264.043414)
		(end 388.506208 -264.038588)
		(width 0.0889)
		(layer "In2.Cu")
		(net "M_I_CPU0_SB_CA<5>")
	)
	(segment
		(start 386.043424 -264.038588)
		(end 386.051806 -264.043414)
		(width 0.0889)
		(layer "In2.Cu")
		(net "M_I_CPU0_SB_CA<5>")
	)
	(segment
		(start 392.255756 -264.043668)
		(end 392.2776 -264.031222)
		(width 0.0889)
		(layer "In2.Cu")
		(net "M_I_CPU0_SB_CA<5>")
	)
	(segment
		(start 407.801572 -264.166858)
		(end 408.172158 -264.012934)
		(width 0.14478)
		(layer "In2.Cu")
		(net "M_I_CPU0_SB_CA<5>")
	)
	(segment
		(start 408.834336 -264.594594)
		(end 409.204922 -264.44067)
		(width 0.14478)
		(layer "In2.Cu")
		(net "M_I_CPU0_SB_CA<5>")
	)
	(segment
		(start 383.79781 -264.043414)
		(end 383.806192 -264.038588)
		(width 0.0889)
		(layer "In2.Cu")
		(net "M_I_CPU0_SB_CA<5>")
	)
	(segment
		(start 395.36243 -263.999218)
		(end 395.477238 -263.88441)
		(width 0.0889)
		(layer "In2.Cu")
		(net "M_I_CPU0_SB_CA<5>")
	)
	(segment
		(start 387.557772 -264.043414)
		(end 387.566154 -264.038588)
		(width 0.0889)
		(layer "In2.Cu")
		(net "M_I_CPU0_SB_CA<5>")
	)
	(segment
		(start 427.030896 -265.7602)
		(end 427.456092 -265.335004)
		(width 0.14478)
		(layer "In2.Cu")
		(net "M_I_CPU0_SB_CA<5>")
	)
	(segment
		(start 380.037848 -264.043414)
		(end 380.04623 -264.038588)
		(width 0.0889)
		(layer "In2.Cu")
		(net "M_I_CPU0_SB_CA<5>")
	)
	(segment
		(start 376.310906 -264.100564)
		(end 376.333258 -264.017252)
		(width 0.0889)
		(layer "In2.Cu")
		(net "M_I_CPU0_SB_CA<5>")
	)
	(segment
		(start 415.462974 -265.7602)
		(end 427.030896 -265.7602)
		(width 0.14478)
		(layer "In2.Cu")
		(net "M_I_CPU0_SB_CA<5>")
	)
	(segment
		(start 413.786574 -265.46429)
		(end 414.049464 -265.46429)
		(width 0.14478)
		(layer "In2.Cu")
		(net "M_I_CPU0_SB_CA<5>")
	)
	(segment
		(start 382.283462 -264.038588)
		(end 382.291844 -264.043414)
		(width 0.0889)
		(layer "In2.Cu")
		(net "M_I_CPU0_SB_CA<5>")
	)
	(segment
		(start 414.608264 -265.7602)
		(end 414.904174 -265.46429)
		(width 0.14478)
		(layer "In2.Cu")
		(net "M_I_CPU0_SB_CA<5>")
	)
	(segment
		(start 378.5235 -264.038588)
		(end 378.531882 -264.043414)
		(width 0.0889)
		(layer "In2.Cu")
		(net "M_I_CPU0_SB_CA<5>")
	)
	(segment
		(start 392.628374 -264.043414)
		(end 392.657838 -264.060686)
		(width 0.0889)
		(layer "In2.Cu")
		(net "M_I_CPU0_SB_CA<5>")
	)
	(segment
		(start 413.490664 -265.7602)
		(end 413.786574 -265.46429)
		(width 0.14478)
		(layer "In2.Cu")
		(net "M_I_CPU0_SB_CA<5>")
	)
	(segment
		(start 409.612592 -264.91692)
		(end 409.8671 -265.02233)
		(width 0.14478)
		(layer "In2.Cu")
		(net "M_I_CPU0_SB_CA<5>")
	)
	(segment
		(start 386.983478 -264.038588)
		(end 386.99186 -264.043414)
		(width 0.0889)
		(layer "In2.Cu")
		(net "M_I_CPU0_SB_CA<5>")
	)
	(segment
		(start 377.583446 -264.038588)
		(end 377.591828 -264.043414)
		(width 0.0889)
		(layer "In2.Cu")
		(net "M_I_CPU0_SB_CA<5>")
	)
	(segment
		(start 411.0609 -265.7602)
		(end 413.490664 -265.7602)
		(width 0.14478)
		(layer "In2.Cu")
		(net "M_I_CPU0_SB_CA<5>")
	)
	(arc
		(start 388.871968 -264.043414)
		(mid 389.154924 -264.119591)
		(end 389.43788 -264.043414)
		(width 0.0889)
		(layer "In2.Cu")
		(net "M_I_CPU0_SB_CA<5>")
	)
	(arc
		(start 391.691876 -264.043414)
		(mid 391.958806 -264.119363)
		(end 392.229594 -264.058654)
		(width 0.0889)
		(layer "In2.Cu")
		(net "M_I_CPU0_SB_CA<5>")
	)
	(arc
		(start 376.333258 -264.017252)
		(mid 376.495447 -263.994517)
		(end 376.651774 -264.043414)
		(width 0.0889)
		(layer "In2.Cu")
		(net "M_I_CPU0_SB_CA<5>")
	)
	(arc
		(start 393.196318 -264.043414)
		(mid 393.253242 -264.016317)
		(end 393.31392 -263.999218)
		(width 0.0889)
		(layer "In2.Cu")
		(net "M_I_CPU0_SB_CA<5>")
	)
	(arc
		(start 387.931914 -264.043414)
		(mid 388.21487 -264.119591)
		(end 388.497826 -264.043414)
		(width 0.0889)
		(layer "In2.Cu")
		(net "M_I_CPU0_SB_CA<5>")
	)
	(arc
		(start 380.977902 -264.043414)
		(mid 381.164846 -263.993159)
		(end 381.35179 -264.043414)
		(width 0.0889)
		(layer "In2.Cu")
		(net "M_I_CPU0_SB_CA<5>")
	)
	(arc
		(start 384.171952 -264.043414)
		(mid 384.454908 -264.119591)
		(end 384.737864 -264.043414)
		(width 0.0889)
		(layer "In2.Cu")
		(net "M_I_CPU0_SB_CA<5>")
	)
	(arc
		(start 389.811768 -264.043414)
		(mid 390.094724 -264.119591)
		(end 390.37768 -264.043414)
		(width 0.0889)
		(layer "In2.Cu")
		(net "M_I_CPU0_SB_CA<5>")
	)
	(arc
		(start 380.41199 -264.043414)
		(mid 380.694946 -264.119591)
		(end 380.977902 -264.043414)
		(width 0.0889)
		(layer "In2.Cu")
		(net "M_I_CPU0_SB_CA<5>")
	)
	(arc
		(start 385.677664 -264.043414)
		(mid 385.859915 -263.993064)
		(end 386.043424 -264.038588)
		(width 0.0889)
		(layer "In2.Cu")
		(net "M_I_CPU0_SB_CA<5>")
	)
	(arc
		(start 390.751822 -264.043414)
		(mid 391.034778 -264.119591)
		(end 391.317734 -264.043414)
		(width 0.0889)
		(layer "In2.Cu")
		(net "M_I_CPU0_SB_CA<5>")
	)
	(arc
		(start 377.217686 -264.043414)
		(mid 377.399937 -263.993064)
		(end 377.583446 -264.038588)
		(width 0.0889)
		(layer "In2.Cu")
		(net "M_I_CPU0_SB_CA<5>")
	)
	(arc
		(start 392.657838 -264.060686)
		(mid 392.929258 -264.120363)
		(end 393.196318 -264.043414)
		(width 0.0889)
		(layer "In2.Cu")
		(net "M_I_CPU0_SB_CA<5>")
	)
	(arc
		(start 382.866138 -264.038588)
		(mid 383.049646 -263.993094)
		(end 383.231898 -264.043414)
		(width 0.0889)
		(layer "In2.Cu")
		(net "M_I_CPU0_SB_CA<5>")
	)
	(arc
		(start 392.2776 -264.031222)
		(mid 392.454528 -263.993394)
		(end 392.628374 -264.043414)
		(width 0.0889)
		(layer "In2.Cu")
		(net "M_I_CPU0_SB_CA<5>")
	)
	(arc
		(start 387.566154 -264.038588)
		(mid 387.749662 -263.993094)
		(end 387.931914 -264.043414)
		(width 0.0889)
		(layer "In2.Cu")
		(net "M_I_CPU0_SB_CA<5>")
	)
	(arc
		(start 384.737864 -264.043414)
		(mid 384.924808 -263.993159)
		(end 385.111752 -264.043414)
		(width 0.0889)
		(layer "In2.Cu")
		(net "M_I_CPU0_SB_CA<5>")
	)
	(arc
		(start 383.231898 -264.043414)
		(mid 383.514854 -264.119591)
		(end 383.79781 -264.043414)
		(width 0.0889)
		(layer "In2.Cu")
		(net "M_I_CPU0_SB_CA<5>")
	)
	(arc
		(start 381.35179 -264.043414)
		(mid 381.634746 -264.119591)
		(end 381.917702 -264.043414)
		(width 0.0889)
		(layer "In2.Cu")
		(net "M_I_CPU0_SB_CA<5>")
	)
	(arc
		(start 382.291844 -264.043414)
		(mid 382.5748 -264.119591)
		(end 382.857756 -264.043414)
		(width 0.0889)
		(layer "In2.Cu")
		(net "M_I_CPU0_SB_CA<5>")
	)
	(arc
		(start 386.99186 -264.043414)
		(mid 387.274816 -264.119591)
		(end 387.557772 -264.043414)
		(width 0.0889)
		(layer "In2.Cu")
		(net "M_I_CPU0_SB_CA<5>")
	)
	(arc
		(start 386.617718 -264.043414)
		(mid 386.799969 -263.993064)
		(end 386.983478 -264.038588)
		(width 0.0889)
		(layer "In2.Cu")
		(net "M_I_CPU0_SB_CA<5>")
	)
	(arc
		(start 389.43788 -264.043414)
		(mid 389.624824 -263.993159)
		(end 389.811768 -264.043414)
		(width 0.0889)
		(layer "In2.Cu")
		(net "M_I_CPU0_SB_CA<5>")
	)
	(arc
		(start 381.917702 -264.043414)
		(mid 382.099953 -263.993064)
		(end 382.283462 -264.038588)
		(width 0.0889)
		(layer "In2.Cu")
		(net "M_I_CPU0_SB_CA<5>")
	)
	(arc
		(start 383.806192 -264.038588)
		(mid 383.9897 -263.993094)
		(end 384.171952 -264.043414)
		(width 0.0889)
		(layer "In2.Cu")
		(net "M_I_CPU0_SB_CA<5>")
	)
	(arc
		(start 391.326116 -264.038588)
		(mid 391.509624 -263.993094)
		(end 391.691876 -264.043414)
		(width 0.0889)
		(layer "In2.Cu")
		(net "M_I_CPU0_SB_CA<5>")
	)
	(arc
		(start 379.471936 -264.043414)
		(mid 379.754892 -264.119591)
		(end 380.037848 -264.043414)
		(width 0.0889)
		(layer "In2.Cu")
		(net "M_I_CPU0_SB_CA<5>")
	)
	(arc
		(start 378.15774 -264.043414)
		(mid 378.339991 -263.993064)
		(end 378.5235 -264.038588)
		(width 0.0889)
		(layer "In2.Cu")
		(net "M_I_CPU0_SB_CA<5>")
	)
	(arc
		(start 378.531882 -264.043414)
		(mid 378.814838 -264.119591)
		(end 379.097794 -264.043414)
		(width 0.0889)
		(layer "In2.Cu")
		(net "M_I_CPU0_SB_CA<5>")
	)
	(arc
		(start 390.37768 -264.043414)
		(mid 390.559931 -263.993064)
		(end 390.74344 -264.038588)
		(width 0.0889)
		(layer "In2.Cu")
		(net "M_I_CPU0_SB_CA<5>")
	)
	(arc
		(start 380.04623 -264.038588)
		(mid 380.229738 -263.993094)
		(end 380.41199 -264.043414)
		(width 0.0889)
		(layer "In2.Cu")
		(net "M_I_CPU0_SB_CA<5>")
	)
	(arc
		(start 377.591828 -264.043414)
		(mid 377.874784 -264.119591)
		(end 378.15774 -264.043414)
		(width 0.0889)
		(layer "In2.Cu")
		(net "M_I_CPU0_SB_CA<5>")
	)
	(arc
		(start 379.106176 -264.038588)
		(mid 379.289684 -263.993094)
		(end 379.471936 -264.043414)
		(width 0.0889)
		(layer "In2.Cu")
		(net "M_I_CPU0_SB_CA<5>")
	)
	(arc
		(start 376.651774 -264.043414)
		(mid 376.93473 -264.119591)
		(end 377.217686 -264.043414)
		(width 0.0889)
		(layer "In2.Cu")
		(net "M_I_CPU0_SB_CA<5>")
	)
	(arc
		(start 385.111752 -264.043414)
		(mid 385.394708 -264.119591)
		(end 385.677664 -264.043414)
		(width 0.0889)
		(layer "In2.Cu")
		(net "M_I_CPU0_SB_CA<5>")
	)
	(arc
		(start 386.051806 -264.043414)
		(mid 386.334762 -264.119591)
		(end 386.617718 -264.043414)
		(width 0.0889)
		(layer "In2.Cu")
		(net "M_I_CPU0_SB_CA<5>")
	)
	(arc
		(start 388.506208 -264.038588)
		(mid 388.689716 -263.993094)
		(end 388.871968 -264.043414)
		(width 0.0889)
		(layer "In2.Cu")
		(net "M_I_CPU0_SB_CA<5>")
	)
	(segment
		(start 375.528078 -263.29005)
		(end 375.99493 -263.555988)
		(width 0.10668)
		(layer "F.Cu")
		(net "M_I_CPU0_SB_CA<4>")
	)
	(segment
		(start 375.99493 -263.555988)
		(end 376.148854 -263.821418)
		(width 0.0889)
		(layer "In2.Cu")
		(net "M_I_CPU0_SB_CA<4>")
	)
	(segment
		(start 393.099798 -263.878568)
		(end 393.100052 -263.878822)
		(width 0.0889)
		(layer "In2.Cu")
		(net "M_I_CPU0_SB_CA<4>")
	)
	(segment
		(start 395.084046 -263.808718)
		(end 395.463014 -263.42975)
		(width 0.0889)
		(layer "In2.Cu")
		(net "M_I_CPU0_SB_CA<4>")
	)
	(segment
		(start 389.90778 -263.878568)
		(end 389.916162 -263.883394)
		(width 0.0889)
		(layer "In2.Cu")
		(net "M_I_CPU0_SB_CA<4>")
	)
	(segment
		(start 376.747786 -263.878568)
		(end 376.756168 -263.883394)
		(width 0.0889)
		(layer "In2.Cu")
		(net "M_I_CPU0_SB_CA<4>")
	)
	(segment
		(start 393.29741 -263.808718)
		(end 395.084046 -263.808718)
		(width 0.0889)
		(layer "In2.Cu")
		(net "M_I_CPU0_SB_CA<4>")
	)
	(segment
		(start 386.147818 -263.878568)
		(end 386.1562 -263.883394)
		(width 0.0889)
		(layer "In2.Cu")
		(net "M_I_CPU0_SB_CA<4>")
	)
	(segment
		(start 395.463014 -263.42975)
		(end 408.116532 -263.42975)
		(width 0.14478)
		(layer "In2.Cu")
		(net "M_I_CPU0_SB_CA<4>")
	)
	(segment
		(start 392.137138 -263.891776)
		(end 392.160506 -263.878314)
		(width 0.0889)
		(layer "In2.Cu")
		(net "M_I_CPU0_SB_CA<4>")
	)
	(segment
		(start 381.447802 -263.878568)
		(end 381.456184 -263.883394)
		(width 0.0889)
		(layer "In2.Cu")
		(net "M_I_CPU0_SB_CA<4>")
	)
	(segment
		(start 392.160506 -263.878314)
		(end 392.186668 -263.863328)
		(width 0.0889)
		(layer "In2.Cu")
		(net "M_I_CPU0_SB_CA<4>")
	)
	(segment
		(start 431.131218 -264.910062)
		(end 431.55616 -264.48512)
		(width 0.14478)
		(layer "In2.Cu")
		(net "M_I_CPU0_SB_CA<4>")
	)
	(segment
		(start 389.333486 -263.883394)
		(end 389.341868 -263.878568)
		(width 0.0889)
		(layer "In2.Cu")
		(net "M_I_CPU0_SB_CA<4>")
	)
	(segment
		(start 379.933454 -263.883394)
		(end 379.941836 -263.878568)
		(width 0.0889)
		(layer "In2.Cu")
		(net "M_I_CPU0_SB_CA<4>")
	)
	(segment
		(start 408.116532 -263.42975)
		(end 411.691074 -264.910062)
		(width 0.14478)
		(layer "In2.Cu")
		(net "M_I_CPU0_SB_CA<4>")
	)
	(segment
		(start 384.63347 -263.883394)
		(end 384.641852 -263.878568)
		(width 0.0889)
		(layer "In2.Cu")
		(net "M_I_CPU0_SB_CA<4>")
	)
	(segment
		(start 377.68784 -263.878568)
		(end 377.696222 -263.883394)
		(width 0.0889)
		(layer "In2.Cu")
		(net "M_I_CPU0_SB_CA<4>")
	)
	(segment
		(start 380.873508 -263.883394)
		(end 380.88189 -263.878568)
		(width 0.0889)
		(layer "In2.Cu")
		(net "M_I_CPU0_SB_CA<4>")
	)
	(segment
		(start 383.693416 -263.883394)
		(end 383.701798 -263.878568)
		(width 0.0889)
		(layer "In2.Cu")
		(net "M_I_CPU0_SB_CA<4>")
	)
	(segment
		(start 376.148854 -263.821418)
		(end 376.244866 -263.846818)
		(width 0.0889)
		(layer "In2.Cu")
		(net "M_I_CPU0_SB_CA<4>")
	)
	(segment
		(start 385.207764 -263.878568)
		(end 385.216146 -263.883394)
		(width 0.0889)
		(layer "In2.Cu")
		(net "M_I_CPU0_SB_CA<4>")
	)
	(segment
		(start 388.393432 -263.883394)
		(end 388.401814 -263.878568)
		(width 0.0889)
		(layer "In2.Cu")
		(net "M_I_CPU0_SB_CA<4>")
	)
	(segment
		(start 411.691074 -264.910062)
		(end 431.131218 -264.910062)
		(width 0.14478)
		(layer "In2.Cu")
		(net "M_I_CPU0_SB_CA<4>")
	)
	(segment
		(start 392.724386 -263.878568)
		(end 392.74496 -263.890506)
		(width 0.0889)
		(layer "In2.Cu")
		(net "M_I_CPU0_SB_CA<4>")
	)
	(arc
		(start 378.627894 -263.878568)
		(mid 378.814838 -263.928823)
		(end 379.001782 -263.878568)
		(width 0.0889)
		(layer "In2.Cu")
		(net "M_I_CPU0_SB_CA<4>")
	)
	(arc
		(start 391.787634 -263.878568)
		(mid 391.960742 -263.928684)
		(end 392.137138 -263.891776)
		(width 0.0889)
		(layer "In2.Cu")
		(net "M_I_CPU0_SB_CA<4>")
	)
	(arc
		(start 385.581906 -263.878568)
		(mid 385.864862 -263.802391)
		(end 386.147818 -263.878568)
		(width 0.0889)
		(layer "In2.Cu")
		(net "M_I_CPU0_SB_CA<4>")
	)
	(arc
		(start 377.121928 -263.878568)
		(mid 377.404884 -263.802391)
		(end 377.68784 -263.878568)
		(width 0.0889)
		(layer "In2.Cu")
		(net "M_I_CPU0_SB_CA<4>")
	)
	(arc
		(start 388.967726 -263.878568)
		(mid 389.149977 -263.928918)
		(end 389.333486 -263.883394)
		(width 0.0889)
		(layer "In2.Cu")
		(net "M_I_CPU0_SB_CA<4>")
	)
	(arc
		(start 390.281922 -263.878568)
		(mid 390.564878 -263.802391)
		(end 390.847834 -263.878568)
		(width 0.0889)
		(layer "In2.Cu")
		(net "M_I_CPU0_SB_CA<4>")
	)
	(arc
		(start 391.221722 -263.878568)
		(mid 391.504678 -263.802391)
		(end 391.787634 -263.878568)
		(width 0.0889)
		(layer "In2.Cu")
		(net "M_I_CPU0_SB_CA<4>")
	)
	(arc
		(start 379.941836 -263.878568)
		(mid 380.224792 -263.802391)
		(end 380.507748 -263.878568)
		(width 0.0889)
		(layer "In2.Cu")
		(net "M_I_CPU0_SB_CA<4>")
	)
	(arc
		(start 377.696222 -263.883394)
		(mid 377.87973 -263.928888)
		(end 378.061982 -263.878568)
		(width 0.0889)
		(layer "In2.Cu")
		(net "M_I_CPU0_SB_CA<4>")
	)
	(arc
		(start 376.756168 -263.883394)
		(mid 376.939676 -263.928888)
		(end 377.121928 -263.878568)
		(width 0.0889)
		(layer "In2.Cu")
		(net "M_I_CPU0_SB_CA<4>")
	)
	(arc
		(start 384.26771 -263.878568)
		(mid 384.449961 -263.928918)
		(end 384.63347 -263.883394)
		(width 0.0889)
		(layer "In2.Cu")
		(net "M_I_CPU0_SB_CA<4>")
	)
	(arc
		(start 384.641852 -263.878568)
		(mid 384.924808 -263.802391)
		(end 385.207764 -263.878568)
		(width 0.0889)
		(layer "In2.Cu")
		(net "M_I_CPU0_SB_CA<4>")
	)
	(arc
		(start 379.567694 -263.878568)
		(mid 379.749945 -263.928918)
		(end 379.933454 -263.883394)
		(width 0.0889)
		(layer "In2.Cu")
		(net "M_I_CPU0_SB_CA<4>")
	)
	(arc
		(start 381.456184 -263.883394)
		(mid 381.639692 -263.928888)
		(end 381.821944 -263.878568)
		(width 0.0889)
		(layer "In2.Cu")
		(net "M_I_CPU0_SB_CA<4>")
	)
	(arc
		(start 393.100052 -263.878822)
		(mid 393.195452 -263.83454)
		(end 393.29741 -263.808718)
		(width 0.0889)
		(layer "In2.Cu")
		(net "M_I_CPU0_SB_CA<4>")
	)
	(arc
		(start 389.916162 -263.883394)
		(mid 390.09967 -263.928888)
		(end 390.281922 -263.878568)
		(width 0.0889)
		(layer "In2.Cu")
		(net "M_I_CPU0_SB_CA<4>")
	)
	(arc
		(start 392.74496 -263.890506)
		(mid 392.923888 -263.929383)
		(end 393.099798 -263.878568)
		(width 0.0889)
		(layer "In2.Cu")
		(net "M_I_CPU0_SB_CA<4>")
	)
	(arc
		(start 380.507748 -263.878568)
		(mid 380.689999 -263.928918)
		(end 380.873508 -263.883394)
		(width 0.0889)
		(layer "In2.Cu")
		(net "M_I_CPU0_SB_CA<4>")
	)
	(arc
		(start 382.761744 -263.878568)
		(mid 383.0447 -263.802391)
		(end 383.327656 -263.878568)
		(width 0.0889)
		(layer "In2.Cu")
		(net "M_I_CPU0_SB_CA<4>")
	)
	(arc
		(start 388.027672 -263.878568)
		(mid 388.209923 -263.928918)
		(end 388.393432 -263.883394)
		(width 0.0889)
		(layer "In2.Cu")
		(net "M_I_CPU0_SB_CA<4>")
	)
	(arc
		(start 380.88189 -263.878568)
		(mid 381.164846 -263.802391)
		(end 381.447802 -263.878568)
		(width 0.0889)
		(layer "In2.Cu")
		(net "M_I_CPU0_SB_CA<4>")
	)
	(arc
		(start 392.186668 -263.863328)
		(mid 392.457454 -263.802682)
		(end 392.724386 -263.878568)
		(width 0.0889)
		(layer "In2.Cu")
		(net "M_I_CPU0_SB_CA<4>")
	)
	(arc
		(start 386.1562 -263.883394)
		(mid 386.339708 -263.928888)
		(end 386.52196 -263.878568)
		(width 0.0889)
		(layer "In2.Cu")
		(net "M_I_CPU0_SB_CA<4>")
	)
	(arc
		(start 387.46176 -263.878568)
		(mid 387.744716 -263.802391)
		(end 388.027672 -263.878568)
		(width 0.0889)
		(layer "In2.Cu")
		(net "M_I_CPU0_SB_CA<4>")
	)
	(arc
		(start 383.327656 -263.878568)
		(mid 383.509907 -263.928918)
		(end 383.693416 -263.883394)
		(width 0.0889)
		(layer "In2.Cu")
		(net "M_I_CPU0_SB_CA<4>")
	)
	(arc
		(start 378.061982 -263.878568)
		(mid 378.344938 -263.802391)
		(end 378.627894 -263.878568)
		(width 0.0889)
		(layer "In2.Cu")
		(net "M_I_CPU0_SB_CA<4>")
	)
	(arc
		(start 390.847834 -263.878568)
		(mid 391.034778 -263.928823)
		(end 391.221722 -263.878568)
		(width 0.0889)
		(layer "In2.Cu")
		(net "M_I_CPU0_SB_CA<4>")
	)
	(arc
		(start 385.216146 -263.883394)
		(mid 385.399654 -263.928888)
		(end 385.581906 -263.878568)
		(width 0.0889)
		(layer "In2.Cu")
		(net "M_I_CPU0_SB_CA<4>")
	)
	(arc
		(start 383.701798 -263.878568)
		(mid 383.984754 -263.802391)
		(end 384.26771 -263.878568)
		(width 0.0889)
		(layer "In2.Cu")
		(net "M_I_CPU0_SB_CA<4>")
	)
	(arc
		(start 381.821944 -263.878568)
		(mid 382.1049 -263.802391)
		(end 382.387856 -263.878568)
		(width 0.0889)
		(layer "In2.Cu")
		(net "M_I_CPU0_SB_CA<4>")
	)
	(arc
		(start 389.341868 -263.878568)
		(mid 389.624824 -263.802391)
		(end 389.90778 -263.878568)
		(width 0.0889)
		(layer "In2.Cu")
		(net "M_I_CPU0_SB_CA<4>")
	)
	(arc
		(start 379.001782 -263.878568)
		(mid 379.284738 -263.802391)
		(end 379.567694 -263.878568)
		(width 0.0889)
		(layer "In2.Cu")
		(net "M_I_CPU0_SB_CA<4>")
	)
	(arc
		(start 387.087872 -263.878568)
		(mid 387.274816 -263.928823)
		(end 387.46176 -263.878568)
		(width 0.0889)
		(layer "In2.Cu")
		(net "M_I_CPU0_SB_CA<4>")
	)
	(arc
		(start 388.401814 -263.878568)
		(mid 388.68477 -263.802391)
		(end 388.967726 -263.878568)
		(width 0.0889)
		(layer "In2.Cu")
		(net "M_I_CPU0_SB_CA<4>")
	)
	(arc
		(start 382.387856 -263.878568)
		(mid 382.5748 -263.928823)
		(end 382.761744 -263.878568)
		(width 0.0889)
		(layer "In2.Cu")
		(net "M_I_CPU0_SB_CA<4>")
	)
	(arc
		(start 386.52196 -263.878568)
		(mid 386.804916 -263.802391)
		(end 387.087872 -263.878568)
		(width 0.0889)
		(layer "In2.Cu")
		(net "M_I_CPU0_SB_CA<4>")
	)
	(arc
		(start 376.244866 -263.846818)
		(mid 376.500074 -263.803341)
		(end 376.747786 -263.878568)
		(width 0.0889)
		(layer "In2.Cu")
		(net "M_I_CPU0_SB_CA<4>")
	)
	(segment
		(start 377.407932 -263.29005)
		(end 377.874784 -263.555988)
		(width 0.10668)
		(layer "F.Cu")
		(net "M_I_CPU0_SB_CA<3>")
	)
	(segment
		(start 385.207764 -263.233408)
		(end 385.216146 -263.228582)
		(width 0.0889)
		(layer "In2.Cu")
		(net "M_I_CPU0_SB_CA<3>")
	)
	(segment
		(start 415.311082 -264.060178)
		(end 415.557208 -263.814052)
		(width 0.14478)
		(layer "In2.Cu")
		(net "M_I_CPU0_SB_CA<3>")
	)
	(segment
		(start 389.90778 -263.233408)
		(end 389.916162 -263.228582)
		(width 0.0889)
		(layer "In2.Cu")
		(net "M_I_CPU0_SB_CA<3>")
	)
	(segment
		(start 420.995856 -263.755632)
		(end 421.242744 -263.755632)
		(width 0.14478)
		(layer "In2.Cu")
		(net "M_I_CPU0_SB_CA<3>")
	)
	(segment
		(start 413.65678 -263.814052)
		(end 413.902906 -264.060178)
		(width 0.14478)
		(layer "In2.Cu")
		(net "M_I_CPU0_SB_CA<3>")
	)
	(segment
		(start 409.464764 -263.45388)
		(end 409.69311 -263.548368)
		(width 0.14478)
		(layer "In2.Cu")
		(net "M_I_CPU0_SB_CA<3>")
	)
	(segment
		(start 409.3337 -263.137142)
		(end 409.464764 -263.45388)
		(width 0.14478)
		(layer "In2.Cu")
		(net "M_I_CPU0_SB_CA<3>")
	)
	(segment
		(start 417.680902 -264.060178)
		(end 417.92017 -264.060178)
		(width 0.14478)
		(layer "In2.Cu")
		(net "M_I_CPU0_SB_CA<3>")
	)
	(segment
		(start 415.557208 -263.814052)
		(end 415.862516 -263.814052)
		(width 0.14478)
		(layer "In2.Cu")
		(net "M_I_CPU0_SB_CA<3>")
	)
	(segment
		(start 410.497528 -263.881362)
		(end 410.929074 -264.060178)
		(width 0.14478)
		(layer "In2.Cu")
		(net "M_I_CPU0_SB_CA<3>")
	)
	(segment
		(start 408.309318 -262.97509)
		(end 408.660346 -263.120632)
		(width 0.14478)
		(layer "In2.Cu")
		(net "M_I_CPU0_SB_CA<3>")
	)
	(segment
		(start 418.471604 -263.748012)
		(end 418.78377 -264.060178)
		(width 0.14478)
		(layer "In2.Cu")
		(net "M_I_CPU0_SB_CA<3>")
	)
	(segment
		(start 389.333486 -263.228582)
		(end 389.341868 -263.233408)
		(width 0.0889)
		(layer "In2.Cu")
		(net "M_I_CPU0_SB_CA<3>")
	)
	(segment
		(start 417.129468 -263.748012)
		(end 417.368736 -263.748012)
		(width 0.14478)
		(layer "In2.Cu")
		(net "M_I_CPU0_SB_CA<3>")
	)
	(segment
		(start 425.33697 -263.76249)
		(end 425.598082 -263.76249)
		(width 0.14478)
		(layer "In2.Cu")
		(net "M_I_CPU0_SB_CA<3>")
	)
	(segment
		(start 420.69131 -264.060178)
		(end 420.995856 -263.755632)
		(width 0.14478)
		(layer "In2.Cu")
		(net "M_I_CPU0_SB_CA<3>")
	)
	(segment
		(start 393.088622 -263.225788)
		(end 393.102338 -263.233662)
		(width 0.0889)
		(layer "In2.Cu")
		(net "M_I_CPU0_SB_CA<3>")
	)
	(segment
		(start 392.713972 -263.242044)
		(end 392.728704 -263.233408)
		(width 0.0889)
		(layer "In2.Cu")
		(net "M_I_CPU0_SB_CA<3>")
	)
	(segment
		(start 413.351472 -263.814052)
		(end 413.65678 -263.814052)
		(width 0.14478)
		(layer "In2.Cu")
		(net "M_I_CPU0_SB_CA<3>")
	)
	(segment
		(start 408.660346 -263.120632)
		(end 408.97683 -262.989314)
		(width 0.14478)
		(layer "In2.Cu")
		(net "M_I_CPU0_SB_CA<3>")
	)
	(segment
		(start 410.31922 -263.450832)
		(end 410.497528 -263.881362)
		(width 0.14478)
		(layer "In2.Cu")
		(net "M_I_CPU0_SB_CA<3>")
	)
	(segment
		(start 423.201592 -263.755632)
		(end 423.44848 -263.755632)
		(width 0.14478)
		(layer "In2.Cu")
		(net "M_I_CPU0_SB_CA<3>")
	)
	(segment
		(start 421.794178 -264.060178)
		(end 422.098724 -263.755632)
		(width 0.14478)
		(layer "In2.Cu")
		(net "M_I_CPU0_SB_CA<3>")
	)
	(segment
		(start 380.873508 -263.228582)
		(end 380.88189 -263.233408)
		(width 0.0889)
		(layer "In2.Cu")
		(net "M_I_CPU0_SB_CA<3>")
	)
	(segment
		(start 417.92017 -264.060178)
		(end 418.232336 -263.748012)
		(width 0.14478)
		(layer "In2.Cu")
		(net "M_I_CPU0_SB_CA<3>")
	)
	(segment
		(start 410.929074 -264.060178)
		(end 413.105346 -264.060178)
		(width 0.14478)
		(layer "In2.Cu")
		(net "M_I_CPU0_SB_CA<3>")
	)
	(segment
		(start 425.89577 -264.060178)
		(end 427.030896 -264.060178)
		(width 0.14478)
		(layer "In2.Cu")
		(net "M_I_CPU0_SB_CA<3>")
	)
	(segment
		(start 414.45434 -263.814052)
		(end 414.759648 -263.814052)
		(width 0.14478)
		(layer "In2.Cu")
		(net "M_I_CPU0_SB_CA<3>")
	)
	(segment
		(start 381.447802 -263.233408)
		(end 381.456184 -263.228582)
		(width 0.0889)
		(layer "In2.Cu")
		(net "M_I_CPU0_SB_CA<3>")
	)
	(segment
		(start 413.902906 -264.060178)
		(end 414.208214 -264.060178)
		(width 0.14478)
		(layer "In2.Cu")
		(net "M_I_CPU0_SB_CA<3>")
	)
	(segment
		(start 413.105346 -264.060178)
		(end 413.351472 -263.814052)
		(width 0.14478)
		(layer "In2.Cu")
		(net "M_I_CPU0_SB_CA<3>")
	)
	(segment
		(start 393.102338 -263.233662)
		(end 393.118086 -263.242806)
		(width 0.0889)
		(layer "In2.Cu")
		(net "M_I_CPU0_SB_CA<3>")
	)
	(segment
		(start 427.030896 -264.060178)
		(end 427.456092 -263.634982)
		(width 0.14478)
		(layer "In2.Cu")
		(net "M_I_CPU0_SB_CA<3>")
	)
	(segment
		(start 425.598082 -263.76249)
		(end 425.89577 -264.060178)
		(width 0.14478)
		(layer "In2.Cu")
		(net "M_I_CPU0_SB_CA<3>")
	)
	(segment
		(start 410.123132 -263.369806)
		(end 410.31922 -263.450832)
		(width 0.14478)
		(layer "In2.Cu")
		(net "M_I_CPU0_SB_CA<3>")
	)
	(segment
		(start 418.78377 -264.060178)
		(end 420.69131 -264.060178)
		(width 0.14478)
		(layer "In2.Cu")
		(net "M_I_CPU0_SB_CA<3>")
	)
	(segment
		(start 408.97683 -262.989314)
		(end 409.3337 -263.137142)
		(width 0.14478)
		(layer "In2.Cu")
		(net "M_I_CPU0_SB_CA<3>")
	)
	(segment
		(start 422.897046 -264.060178)
		(end 423.201592 -263.755632)
		(width 0.14478)
		(layer "In2.Cu")
		(net "M_I_CPU0_SB_CA<3>")
	)
	(segment
		(start 409.69311 -263.548368)
		(end 410.123132 -263.369806)
		(width 0.14478)
		(layer "In2.Cu")
		(net "M_I_CPU0_SB_CA<3>")
	)
	(segment
		(start 391.787634 -263.233408)
		(end 391.796016 -263.228582)
		(width 0.0889)
		(layer "In2.Cu")
		(net "M_I_CPU0_SB_CA<3>")
	)
	(segment
		(start 383.693416 -263.228582)
		(end 383.701798 -263.233408)
		(width 0.0889)
		(layer "In2.Cu")
		(net "M_I_CPU0_SB_CA<3>")
	)
	(segment
		(start 379.933454 -263.228582)
		(end 379.941836 -263.233408)
		(width 0.0889)
		(layer "In2.Cu")
		(net "M_I_CPU0_SB_CA<3>")
	)
	(segment
		(start 417.368736 -263.748012)
		(end 417.680902 -264.060178)
		(width 0.14478)
		(layer "In2.Cu")
		(net "M_I_CPU0_SB_CA<3>")
	)
	(segment
		(start 421.54729 -264.060178)
		(end 421.794178 -264.060178)
		(width 0.14478)
		(layer "In2.Cu")
		(net "M_I_CPU0_SB_CA<3>")
	)
	(segment
		(start 393.610846 -263.269476)
		(end 394.464032 -262.92429)
		(width 0.0889)
		(layer "In2.Cu")
		(net "M_I_CPU0_SB_CA<3>")
	)
	(segment
		(start 421.242744 -263.755632)
		(end 421.54729 -264.060178)
		(width 0.14478)
		(layer "In2.Cu")
		(net "M_I_CPU0_SB_CA<3>")
	)
	(segment
		(start 416.108642 -264.060178)
		(end 416.817302 -264.060178)
		(width 0.14478)
		(layer "In2.Cu")
		(net "M_I_CPU0_SB_CA<3>")
	)
	(segment
		(start 384.63347 -263.228582)
		(end 384.641852 -263.233408)
		(width 0.0889)
		(layer "In2.Cu")
		(net "M_I_CPU0_SB_CA<3>")
	)
	(segment
		(start 422.650158 -264.060178)
		(end 422.897046 -264.060178)
		(width 0.14478)
		(layer "In2.Cu")
		(net "M_I_CPU0_SB_CA<3>")
	)
	(segment
		(start 415.005774 -264.060178)
		(end 415.311082 -264.060178)
		(width 0.14478)
		(layer "In2.Cu")
		(net "M_I_CPU0_SB_CA<3>")
	)
	(segment
		(start 422.098724 -263.755632)
		(end 422.345612 -263.755632)
		(width 0.14478)
		(layer "In2.Cu")
		(net "M_I_CPU0_SB_CA<3>")
	)
	(segment
		(start 418.232336 -263.748012)
		(end 418.471604 -263.748012)
		(width 0.14478)
		(layer "In2.Cu")
		(net "M_I_CPU0_SB_CA<3>")
	)
	(segment
		(start 425.039282 -264.060178)
		(end 425.33697 -263.76249)
		(width 0.14478)
		(layer "In2.Cu")
		(net "M_I_CPU0_SB_CA<3>")
	)
	(segment
		(start 377.72086 -263.290558)
		(end 377.743212 -263.207246)
		(width 0.0889)
		(layer "In2.Cu")
		(net "M_I_CPU0_SB_CA<3>")
	)
	(segment
		(start 415.862516 -263.814052)
		(end 416.108642 -264.060178)
		(width 0.14478)
		(layer "In2.Cu")
		(net "M_I_CPU0_SB_CA<3>")
	)
	(segment
		(start 386.147818 -263.233408)
		(end 386.1562 -263.228582)
		(width 0.0889)
		(layer "In2.Cu")
		(net "M_I_CPU0_SB_CA<3>")
	)
	(segment
		(start 416.817302 -264.060178)
		(end 417.129468 -263.748012)
		(width 0.14478)
		(layer "In2.Cu")
		(net "M_I_CPU0_SB_CA<3>")
	)
	(segment
		(start 395.574774 -262.97509)
		(end 408.309318 -262.97509)
		(width 0.14478)
		(layer "In2.Cu")
		(net "M_I_CPU0_SB_CA<3>")
	)
	(segment
		(start 388.393432 -263.228582)
		(end 388.401814 -263.233408)
		(width 0.0889)
		(layer "In2.Cu")
		(net "M_I_CPU0_SB_CA<3>")
	)
	(segment
		(start 423.753026 -264.060178)
		(end 425.039282 -264.060178)
		(width 0.14478)
		(layer "In2.Cu")
		(net "M_I_CPU0_SB_CA<3>")
	)
	(segment
		(start 422.345612 -263.755632)
		(end 422.650158 -264.060178)
		(width 0.14478)
		(layer "In2.Cu")
		(net "M_I_CPU0_SB_CA<3>")
	)
	(segment
		(start 395.523974 -262.92429)
		(end 395.574774 -262.97509)
		(width 0.14478)
		(layer "In2.Cu")
		(net "M_I_CPU0_SB_CA<3>")
	)
	(segment
		(start 414.759648 -263.814052)
		(end 415.005774 -264.060178)
		(width 0.14478)
		(layer "In2.Cu")
		(net "M_I_CPU0_SB_CA<3>")
	)
	(segment
		(start 394.464032 -262.92429)
		(end 395.523974 -262.92429)
		(width 0.0889)
		(layer "In2.Cu")
		(net "M_I_CPU0_SB_CA<3>")
	)
	(segment
		(start 377.874784 -263.555988)
		(end 377.72086 -263.290558)
		(width 0.0889)
		(layer "In2.Cu")
		(net "M_I_CPU0_SB_CA<3>")
	)
	(segment
		(start 423.44848 -263.755632)
		(end 423.753026 -264.060178)
		(width 0.14478)
		(layer "In2.Cu")
		(net "M_I_CPU0_SB_CA<3>")
	)
	(segment
		(start 414.208214 -264.060178)
		(end 414.45434 -263.814052)
		(width 0.14478)
		(layer "In2.Cu")
		(net "M_I_CPU0_SB_CA<3>")
	)
	(arc
		(start 390.281922 -263.233408)
		(mid 390.564878 -263.309585)
		(end 390.847834 -263.233408)
		(width 0.0889)
		(layer "In2.Cu")
		(net "M_I_CPU0_SB_CA<3>")
	)
	(arc
		(start 385.581906 -263.233408)
		(mid 385.864862 -263.309585)
		(end 386.147818 -263.233408)
		(width 0.0889)
		(layer "In2.Cu")
		(net "M_I_CPU0_SB_CA<3>")
	)
	(arc
		(start 390.847834 -263.233408)
		(mid 391.034778 -263.183153)
		(end 391.221722 -263.233408)
		(width 0.0889)
		(layer "In2.Cu")
		(net "M_I_CPU0_SB_CA<3>")
	)
	(arc
		(start 386.52196 -263.233408)
		(mid 386.804916 -263.309585)
		(end 387.087872 -263.233408)
		(width 0.0889)
		(layer "In2.Cu")
		(net "M_I_CPU0_SB_CA<3>")
	)
	(arc
		(start 383.327656 -263.233408)
		(mid 383.509907 -263.183058)
		(end 383.693416 -263.228582)
		(width 0.0889)
		(layer "In2.Cu")
		(net "M_I_CPU0_SB_CA<3>")
	)
	(arc
		(start 392.728704 -263.233408)
		(mid 392.907691 -263.183238)
		(end 393.088622 -263.225788)
		(width 0.0889)
		(layer "In2.Cu")
		(net "M_I_CPU0_SB_CA<3>")
	)
	(arc
		(start 387.087872 -263.233408)
		(mid 387.274816 -263.183153)
		(end 387.46176 -263.233408)
		(width 0.0889)
		(layer "In2.Cu")
		(net "M_I_CPU0_SB_CA<3>")
	)
	(arc
		(start 391.221722 -263.233408)
		(mid 391.504678 -263.309585)
		(end 391.787634 -263.233408)
		(width 0.0889)
		(layer "In2.Cu")
		(net "M_I_CPU0_SB_CA<3>")
	)
	(arc
		(start 384.641852 -263.233408)
		(mid 384.924808 -263.309585)
		(end 385.207764 -263.233408)
		(width 0.0889)
		(layer "In2.Cu")
		(net "M_I_CPU0_SB_CA<3>")
	)
	(arc
		(start 381.821944 -263.233408)
		(mid 382.1049 -263.309585)
		(end 382.387856 -263.233408)
		(width 0.0889)
		(layer "In2.Cu")
		(net "M_I_CPU0_SB_CA<3>")
	)
	(arc
		(start 393.118086 -263.242806)
		(mid 393.361495 -263.311046)
		(end 393.610846 -263.269476)
		(width 0.0889)
		(layer "In2.Cu")
		(net "M_I_CPU0_SB_CA<3>")
	)
	(arc
		(start 384.26771 -263.233408)
		(mid 384.449961 -263.183058)
		(end 384.63347 -263.228582)
		(width 0.0889)
		(layer "In2.Cu")
		(net "M_I_CPU0_SB_CA<3>")
	)
	(arc
		(start 389.341868 -263.233408)
		(mid 389.624824 -263.309585)
		(end 389.90778 -263.233408)
		(width 0.0889)
		(layer "In2.Cu")
		(net "M_I_CPU0_SB_CA<3>")
	)
	(arc
		(start 379.001782 -263.233408)
		(mid 379.284738 -263.309585)
		(end 379.567694 -263.233408)
		(width 0.0889)
		(layer "In2.Cu")
		(net "M_I_CPU0_SB_CA<3>")
	)
	(arc
		(start 383.701798 -263.233408)
		(mid 383.984754 -263.309585)
		(end 384.26771 -263.233408)
		(width 0.0889)
		(layer "In2.Cu")
		(net "M_I_CPU0_SB_CA<3>")
	)
	(arc
		(start 388.027672 -263.233408)
		(mid 388.209923 -263.183058)
		(end 388.393432 -263.228582)
		(width 0.0889)
		(layer "In2.Cu")
		(net "M_I_CPU0_SB_CA<3>")
	)
	(arc
		(start 380.88189 -263.233408)
		(mid 381.164846 -263.309585)
		(end 381.447802 -263.233408)
		(width 0.0889)
		(layer "In2.Cu")
		(net "M_I_CPU0_SB_CA<3>")
	)
	(arc
		(start 388.401814 -263.233408)
		(mid 388.68477 -263.309585)
		(end 388.967726 -263.233408)
		(width 0.0889)
		(layer "In2.Cu")
		(net "M_I_CPU0_SB_CA<3>")
	)
	(arc
		(start 382.387856 -263.233408)
		(mid 382.5748 -263.183153)
		(end 382.761744 -263.233408)
		(width 0.0889)
		(layer "In2.Cu")
		(net "M_I_CPU0_SB_CA<3>")
	)
	(arc
		(start 381.456184 -263.228582)
		(mid 381.639692 -263.183088)
		(end 381.821944 -263.233408)
		(width 0.0889)
		(layer "In2.Cu")
		(net "M_I_CPU0_SB_CA<3>")
	)
	(arc
		(start 378.061982 -263.233408)
		(mid 378.344938 -263.309585)
		(end 378.627894 -263.233408)
		(width 0.0889)
		(layer "In2.Cu")
		(net "M_I_CPU0_SB_CA<3>")
	)
	(arc
		(start 379.941836 -263.233408)
		(mid 380.224792 -263.309585)
		(end 380.507748 -263.233408)
		(width 0.0889)
		(layer "In2.Cu")
		(net "M_I_CPU0_SB_CA<3>")
	)
	(arc
		(start 382.761744 -263.233408)
		(mid 383.0447 -263.309585)
		(end 383.327656 -263.233408)
		(width 0.0889)
		(layer "In2.Cu")
		(net "M_I_CPU0_SB_CA<3>")
	)
	(arc
		(start 387.46176 -263.233408)
		(mid 387.744716 -263.309585)
		(end 388.027672 -263.233408)
		(width 0.0889)
		(layer "In2.Cu")
		(net "M_I_CPU0_SB_CA<3>")
	)
	(arc
		(start 392.162284 -263.233408)
		(mid 392.43699 -263.309772)
		(end 392.713972 -263.242044)
		(width 0.0889)
		(layer "In2.Cu")
		(net "M_I_CPU0_SB_CA<3>")
	)
	(arc
		(start 385.216146 -263.228582)
		(mid 385.399654 -263.183088)
		(end 385.581906 -263.233408)
		(width 0.0889)
		(layer "In2.Cu")
		(net "M_I_CPU0_SB_CA<3>")
	)
	(arc
		(start 386.1562 -263.228582)
		(mid 386.339708 -263.183088)
		(end 386.52196 -263.233408)
		(width 0.0889)
		(layer "In2.Cu")
		(net "M_I_CPU0_SB_CA<3>")
	)
	(arc
		(start 380.507748 -263.233408)
		(mid 380.689999 -263.183058)
		(end 380.873508 -263.228582)
		(width 0.0889)
		(layer "In2.Cu")
		(net "M_I_CPU0_SB_CA<3>")
	)
	(arc
		(start 379.567694 -263.233408)
		(mid 379.749945 -263.183058)
		(end 379.933454 -263.228582)
		(width 0.0889)
		(layer "In2.Cu")
		(net "M_I_CPU0_SB_CA<3>")
	)
	(arc
		(start 378.627894 -263.233408)
		(mid 378.814838 -263.183153)
		(end 379.001782 -263.233408)
		(width 0.0889)
		(layer "In2.Cu")
		(net "M_I_CPU0_SB_CA<3>")
	)
	(arc
		(start 377.743212 -263.207246)
		(mid 377.905544 -263.184428)
		(end 378.061982 -263.233408)
		(width 0.0889)
		(layer "In2.Cu")
		(net "M_I_CPU0_SB_CA<3>")
	)
	(arc
		(start 389.916162 -263.228582)
		(mid 390.09967 -263.183088)
		(end 390.281922 -263.233408)
		(width 0.0889)
		(layer "In2.Cu")
		(net "M_I_CPU0_SB_CA<3>")
	)
	(arc
		(start 391.796016 -263.228582)
		(mid 391.979778 -263.182966)
		(end 392.162284 -263.233408)
		(width 0.0889)
		(layer "In2.Cu")
		(net "M_I_CPU0_SB_CA<3>")
	)
	(arc
		(start 388.967726 -263.233408)
		(mid 389.149977 -263.183058)
		(end 389.333486 -263.228582)
		(width 0.0889)
		(layer "In2.Cu")
		(net "M_I_CPU0_SB_CA<3>")
	)
	(segment
		(start 376.938032 -262.480044)
		(end 377.404884 -262.745982)
		(width 0.10668)
		(layer "F.Cu")
		(net "M_I_CPU0_SB_CA<2>")
	)
	(segment
		(start 431.131218 -263.21004)
		(end 431.55616 -262.785098)
		(width 0.14478)
		(layer "In2.Cu")
		(net "M_I_CPU0_SB_CA<2>")
	)
	(segment
		(start 393.572238 -263.068562)
		(end 394.38072 -262.72109)
		(width 0.0889)
		(layer "In2.Cu")
		(net "M_I_CPU0_SB_CA<2>")
	)
	(segment
		(start 391.691876 -263.068562)
		(end 391.706608 -263.059926)
		(width 0.0889)
		(layer "In2.Cu")
		(net "M_I_CPU0_SB_CA<2>")
	)
	(segment
		(start 388.497826 -263.068562)
		(end 388.506208 -263.073388)
		(width 0.0889)
		(layer "In2.Cu")
		(net "M_I_CPU0_SB_CA<2>")
	)
	(segment
		(start 386.043424 -263.073388)
		(end 386.051806 -263.068562)
		(width 0.0889)
		(layer "In2.Cu")
		(net "M_I_CPU0_SB_CA<2>")
	)
	(segment
		(start 393.192508 -263.065006)
		(end 393.198096 -263.068308)
		(width 0.0889)
		(layer "In2.Cu")
		(net "M_I_CPU0_SB_CA<2>")
	)
	(segment
		(start 378.5235 -263.073388)
		(end 378.531882 -263.068562)
		(width 0.0889)
		(layer "In2.Cu")
		(net "M_I_CPU0_SB_CA<2>")
	)
	(segment
		(start 377.558808 -263.011412)
		(end 377.65482 -263.036812)
		(width 0.0889)
		(layer "In2.Cu")
		(net "M_I_CPU0_SB_CA<2>")
	)
	(segment
		(start 392.621008 -263.07542)
		(end 392.632692 -263.068562)
		(width 0.0889)
		(layer "In2.Cu")
		(net "M_I_CPU0_SB_CA<2>")
	)
	(segment
		(start 386.983478 -263.073388)
		(end 386.99186 -263.068562)
		(width 0.0889)
		(layer "In2.Cu")
		(net "M_I_CPU0_SB_CA<2>")
	)
	(segment
		(start 387.557772 -263.068562)
		(end 387.566154 -263.073388)
		(width 0.0889)
		(layer "In2.Cu")
		(net "M_I_CPU0_SB_CA<2>")
	)
	(segment
		(start 379.097794 -263.068562)
		(end 379.106176 -263.073388)
		(width 0.0889)
		(layer "In2.Cu")
		(net "M_I_CPU0_SB_CA<2>")
	)
	(segment
		(start 395.470888 -262.52043)
		(end 409.739338 -262.52043)
		(width 0.14478)
		(layer "In2.Cu")
		(net "M_I_CPU0_SB_CA<2>")
	)
	(segment
		(start 383.79781 -263.068562)
		(end 383.806192 -263.073388)
		(width 0.0889)
		(layer "In2.Cu")
		(net "M_I_CPU0_SB_CA<2>")
	)
	(segment
		(start 411.404562 -263.21004)
		(end 431.131218 -263.21004)
		(width 0.14478)
		(layer "In2.Cu")
		(net "M_I_CPU0_SB_CA<2>")
	)
	(segment
		(start 382.857756 -263.068562)
		(end 382.866138 -263.073388)
		(width 0.0889)
		(layer "In2.Cu")
		(net "M_I_CPU0_SB_CA<2>")
	)
	(segment
		(start 394.38072 -262.72109)
		(end 395.270228 -262.72109)
		(width 0.0889)
		(layer "In2.Cu")
		(net "M_I_CPU0_SB_CA<2>")
	)
	(segment
		(start 393.198096 -263.068308)
		(end 393.216384 -263.078722)
		(width 0.0889)
		(layer "In2.Cu")
		(net "M_I_CPU0_SB_CA<2>")
	)
	(segment
		(start 377.404884 -262.745982)
		(end 377.558808 -263.011412)
		(width 0.0889)
		(layer "In2.Cu")
		(net "M_I_CPU0_SB_CA<2>")
	)
	(segment
		(start 390.74344 -263.073388)
		(end 390.751822 -263.068562)
		(width 0.0889)
		(layer "In2.Cu")
		(net "M_I_CPU0_SB_CA<2>")
	)
	(segment
		(start 380.037848 -263.068562)
		(end 380.04623 -263.073388)
		(width 0.0889)
		(layer "In2.Cu")
		(net "M_I_CPU0_SB_CA<2>")
	)
	(segment
		(start 382.283462 -263.073388)
		(end 382.291844 -263.068562)
		(width 0.0889)
		(layer "In2.Cu")
		(net "M_I_CPU0_SB_CA<2>")
	)
	(segment
		(start 395.270228 -262.72109)
		(end 395.470888 -262.52043)
		(width 0.0889)
		(layer "In2.Cu")
		(net "M_I_CPU0_SB_CA<2>")
	)
	(segment
		(start 409.739338 -262.52043)
		(end 411.404562 -263.21004)
		(width 0.14478)
		(layer "In2.Cu")
		(net "M_I_CPU0_SB_CA<2>")
	)
	(segment
		(start 391.317734 -263.068562)
		(end 391.326116 -263.073388)
		(width 0.0889)
		(layer "In2.Cu")
		(net "M_I_CPU0_SB_CA<2>")
	)
	(arc
		(start 383.806192 -263.073388)
		(mid 383.9897 -263.118882)
		(end 384.171952 -263.068562)
		(width 0.0889)
		(layer "In2.Cu")
		(net "M_I_CPU0_SB_CA<2>")
	)
	(arc
		(start 391.706608 -263.059926)
		(mid 391.983591 -262.992122)
		(end 392.258296 -263.068562)
		(width 0.0889)
		(layer "In2.Cu")
		(net "M_I_CPU0_SB_CA<2>")
	)
	(arc
		(start 377.65482 -263.036812)
		(mid 377.910028 -262.993335)
		(end 378.15774 -263.068562)
		(width 0.0889)
		(layer "In2.Cu")
		(net "M_I_CPU0_SB_CA<2>")
	)
	(arc
		(start 379.471936 -263.068562)
		(mid 379.754892 -262.992385)
		(end 380.037848 -263.068562)
		(width 0.0889)
		(layer "In2.Cu")
		(net "M_I_CPU0_SB_CA<2>")
	)
	(arc
		(start 391.326116 -263.073388)
		(mid 391.509624 -263.118882)
		(end 391.691876 -263.068562)
		(width 0.0889)
		(layer "In2.Cu")
		(net "M_I_CPU0_SB_CA<2>")
	)
	(arc
		(start 385.677664 -263.068562)
		(mid 385.859915 -263.118912)
		(end 386.043424 -263.073388)
		(width 0.0889)
		(layer "In2.Cu")
		(net "M_I_CPU0_SB_CA<2>")
	)
	(arc
		(start 387.931914 -263.068562)
		(mid 388.21487 -262.992385)
		(end 388.497826 -263.068562)
		(width 0.0889)
		(layer "In2.Cu")
		(net "M_I_CPU0_SB_CA<2>")
	)
	(arc
		(start 386.99186 -263.068562)
		(mid 387.274816 -262.992385)
		(end 387.557772 -263.068562)
		(width 0.0889)
		(layer "In2.Cu")
		(net "M_I_CPU0_SB_CA<2>")
	)
	(arc
		(start 381.917702 -263.068562)
		(mid 382.099953 -263.118912)
		(end 382.283462 -263.073388)
		(width 0.0889)
		(layer "In2.Cu")
		(net "M_I_CPU0_SB_CA<2>")
	)
	(arc
		(start 382.866138 -263.073388)
		(mid 383.049646 -263.118882)
		(end 383.231898 -263.068562)
		(width 0.0889)
		(layer "In2.Cu")
		(net "M_I_CPU0_SB_CA<2>")
	)
	(arc
		(start 386.617718 -263.068562)
		(mid 386.799969 -263.118912)
		(end 386.983478 -263.073388)
		(width 0.0889)
		(layer "In2.Cu")
		(net "M_I_CPU0_SB_CA<2>")
	)
	(arc
		(start 384.737864 -263.068562)
		(mid 384.924808 -263.118817)
		(end 385.111752 -263.068562)
		(width 0.0889)
		(layer "In2.Cu")
		(net "M_I_CPU0_SB_CA<2>")
	)
	(arc
		(start 382.291844 -263.068562)
		(mid 382.5748 -262.992385)
		(end 382.857756 -263.068562)
		(width 0.0889)
		(layer "In2.Cu")
		(net "M_I_CPU0_SB_CA<2>")
	)
	(arc
		(start 380.04623 -263.073388)
		(mid 380.229738 -263.118882)
		(end 380.41199 -263.068562)
		(width 0.0889)
		(layer "In2.Cu")
		(net "M_I_CPU0_SB_CA<2>")
	)
	(arc
		(start 384.171952 -263.068562)
		(mid 384.454908 -262.992385)
		(end 384.737864 -263.068562)
		(width 0.0889)
		(layer "In2.Cu")
		(net "M_I_CPU0_SB_CA<2>")
	)
	(arc
		(start 378.531882 -263.068562)
		(mid 378.814838 -262.992385)
		(end 379.097794 -263.068562)
		(width 0.0889)
		(layer "In2.Cu")
		(net "M_I_CPU0_SB_CA<2>")
	)
	(arc
		(start 390.37768 -263.068562)
		(mid 390.559931 -263.118912)
		(end 390.74344 -263.073388)
		(width 0.0889)
		(layer "In2.Cu")
		(net "M_I_CPU0_SB_CA<2>")
	)
	(arc
		(start 389.43788 -263.068562)
		(mid 389.624824 -263.118817)
		(end 389.811768 -263.068562)
		(width 0.0889)
		(layer "In2.Cu")
		(net "M_I_CPU0_SB_CA<2>")
	)
	(arc
		(start 393.216384 -263.078722)
		(mid 393.395613 -263.118875)
		(end 393.572238 -263.068562)
		(width 0.0889)
		(layer "In2.Cu")
		(net "M_I_CPU0_SB_CA<2>")
	)
	(arc
		(start 379.106176 -263.073388)
		(mid 379.289684 -263.118882)
		(end 379.471936 -263.068562)
		(width 0.0889)
		(layer "In2.Cu")
		(net "M_I_CPU0_SB_CA<2>")
	)
	(arc
		(start 388.506208 -263.073388)
		(mid 388.689716 -263.118882)
		(end 388.871968 -263.068562)
		(width 0.0889)
		(layer "In2.Cu")
		(net "M_I_CPU0_SB_CA<2>")
	)
	(arc
		(start 387.566154 -263.073388)
		(mid 387.749662 -263.118882)
		(end 387.931914 -263.068562)
		(width 0.0889)
		(layer "In2.Cu")
		(net "M_I_CPU0_SB_CA<2>")
	)
	(arc
		(start 386.051806 -263.068562)
		(mid 386.334762 -262.992385)
		(end 386.617718 -263.068562)
		(width 0.0889)
		(layer "In2.Cu")
		(net "M_I_CPU0_SB_CA<2>")
	)
	(arc
		(start 390.751822 -263.068562)
		(mid 391.034778 -262.992385)
		(end 391.317734 -263.068562)
		(width 0.0889)
		(layer "In2.Cu")
		(net "M_I_CPU0_SB_CA<2>")
	)
	(arc
		(start 392.258296 -263.068562)
		(mid 392.438754 -263.119006)
		(end 392.621008 -263.07542)
		(width 0.0889)
		(layer "In2.Cu")
		(net "M_I_CPU0_SB_CA<2>")
	)
	(arc
		(start 383.231898 -263.068562)
		(mid 383.514854 -262.992385)
		(end 383.79781 -263.068562)
		(width 0.0889)
		(layer "In2.Cu")
		(net "M_I_CPU0_SB_CA<2>")
	)
	(arc
		(start 378.15774 -263.068562)
		(mid 378.339991 -263.118912)
		(end 378.5235 -263.073388)
		(width 0.0889)
		(layer "In2.Cu")
		(net "M_I_CPU0_SB_CA<2>")
	)
	(arc
		(start 380.41199 -263.068562)
		(mid 380.694946 -262.992385)
		(end 380.977902 -263.068562)
		(width 0.0889)
		(layer "In2.Cu")
		(net "M_I_CPU0_SB_CA<2>")
	)
	(arc
		(start 388.871968 -263.068562)
		(mid 389.154924 -262.992385)
		(end 389.43788 -263.068562)
		(width 0.0889)
		(layer "In2.Cu")
		(net "M_I_CPU0_SB_CA<2>")
	)
	(arc
		(start 389.811768 -263.068562)
		(mid 390.094724 -262.992385)
		(end 390.37768 -263.068562)
		(width 0.0889)
		(layer "In2.Cu")
		(net "M_I_CPU0_SB_CA<2>")
	)
	(arc
		(start 380.977902 -263.068562)
		(mid 381.164846 -263.118817)
		(end 381.35179 -263.068562)
		(width 0.0889)
		(layer "In2.Cu")
		(net "M_I_CPU0_SB_CA<2>")
	)
	(arc
		(start 392.632692 -263.068562)
		(mid 392.91212 -262.992396)
		(end 393.192508 -263.065006)
		(width 0.0889)
		(layer "In2.Cu")
		(net "M_I_CPU0_SB_CA<2>")
	)
	(arc
		(start 381.35179 -263.068562)
		(mid 381.634746 -262.992385)
		(end 381.917702 -263.068562)
		(width 0.0889)
		(layer "In2.Cu")
		(net "M_I_CPU0_SB_CA<2>")
	)
	(arc
		(start 385.111752 -263.068562)
		(mid 385.394708 -262.992385)
		(end 385.677664 -263.068562)
		(width 0.0889)
		(layer "In2.Cu")
		(net "M_I_CPU0_SB_CA<2>")
	)
	(segment
		(start 375.997978 -262.480044)
		(end 376.46483 -262.745982)
		(width 0.10668)
		(layer "F.Cu")
		(net "M_I_CPU0_SB_CA<1>")
	)
	(segment
		(start 414.588198 -262.360156)
		(end 414.910524 -262.03783)
		(width 0.14478)
		(layer "In2.Cu")
		(net "M_I_CPU0_SB_CA<1>")
	)
	(segment
		(start 386.043424 -262.418576)
		(end 386.051806 -262.423402)
		(width 0.0889)
		(layer "In2.Cu")
		(net "M_I_CPU0_SB_CA<1>")
	)
	(segment
		(start 422.323006 -262.08101)
		(end 422.60266 -262.08101)
		(width 0.14478)
		(layer "In2.Cu")
		(net "M_I_CPU0_SB_CA<1>")
	)
	(segment
		(start 420.92626 -262.360156)
		(end 421.205406 -262.08101)
		(width 0.14478)
		(layer "In2.Cu")
		(net "M_I_CPU0_SB_CA<1>")
	)
	(segment
		(start 395.245844 -262.37184)
		(end 395.551914 -262.06577)
		(width 0.0889)
		(layer "In2.Cu")
		(net "M_I_CPU0_SB_CA<1>")
	)
	(segment
		(start 382.283462 -262.418576)
		(end 382.291844 -262.423402)
		(width 0.0889)
		(layer "In2.Cu")
		(net "M_I_CPU0_SB_CA<1>")
	)
	(segment
		(start 395.551914 -262.06577)
		(end 410.292296 -262.06577)
		(width 0.14478)
		(layer "In2.Cu")
		(net "M_I_CPU0_SB_CA<1>")
	)
	(segment
		(start 376.46483 -262.745982)
		(end 376.310906 -262.480552)
		(width 0.0889)
		(layer "In2.Cu")
		(net "M_I_CPU0_SB_CA<1>")
	)
	(segment
		(start 425.47921 -262.360156)
		(end 425.771056 -262.06831)
		(width 0.14478)
		(layer "In2.Cu")
		(net "M_I_CPU0_SB_CA<1>")
	)
	(segment
		(start 414.351724 -262.360156)
		(end 414.588198 -262.360156)
		(width 0.14478)
		(layer "In2.Cu")
		(net "M_I_CPU0_SB_CA<1>")
	)
	(segment
		(start 379.097794 -262.423402)
		(end 379.106176 -262.418576)
		(width 0.0889)
		(layer "In2.Cu")
		(net "M_I_CPU0_SB_CA<1>")
	)
	(segment
		(start 388.497826 -262.423402)
		(end 388.506208 -262.418576)
		(width 0.0889)
		(layer "In2.Cu")
		(net "M_I_CPU0_SB_CA<1>")
	)
	(segment
		(start 426.329856 -262.360156)
		(end 427.030896 -262.360156)
		(width 0.14478)
		(layer "In2.Cu")
		(net "M_I_CPU0_SB_CA<1>")
	)
	(segment
		(start 413.470598 -262.360156)
		(end 413.792924 -262.03783)
		(width 0.14478)
		(layer "In2.Cu")
		(net "M_I_CPU0_SB_CA<1>")
	)
	(segment
		(start 421.48506 -262.08101)
		(end 421.764206 -262.360156)
		(width 0.14478)
		(layer "In2.Cu")
		(net "M_I_CPU0_SB_CA<1>")
	)
	(segment
		(start 426.03801 -262.06831)
		(end 426.329856 -262.360156)
		(width 0.14478)
		(layer "In2.Cu")
		(net "M_I_CPU0_SB_CA<1>")
	)
	(segment
		(start 383.79781 -262.423402)
		(end 383.806192 -262.418576)
		(width 0.0889)
		(layer "In2.Cu")
		(net "M_I_CPU0_SB_CA<1>")
	)
	(segment
		(start 421.764206 -262.360156)
		(end 422.04386 -262.360156)
		(width 0.14478)
		(layer "In2.Cu")
		(net "M_I_CPU0_SB_CA<1>")
	)
	(segment
		(start 391.317734 -262.423402)
		(end 391.326116 -262.418576)
		(width 0.0889)
		(layer "In2.Cu")
		(net "M_I_CPU0_SB_CA<1>")
	)
	(segment
		(start 421.205406 -262.08101)
		(end 421.48506 -262.08101)
		(width 0.14478)
		(layer "In2.Cu")
		(net "M_I_CPU0_SB_CA<1>")
	)
	(segment
		(start 415.146998 -262.03783)
		(end 415.469324 -262.360156)
		(width 0.14478)
		(layer "In2.Cu")
		(net "M_I_CPU0_SB_CA<1>")
	)
	(segment
		(start 414.029398 -262.03783)
		(end 414.351724 -262.360156)
		(width 0.14478)
		(layer "In2.Cu")
		(net "M_I_CPU0_SB_CA<1>")
	)
	(segment
		(start 392.628374 -262.423402)
		(end 392.657838 -262.440674)
		(width 0.0889)
		(layer "In2.Cu")
		(net "M_I_CPU0_SB_CA<1>")
	)
	(segment
		(start 390.74344 -262.418576)
		(end 390.751822 -262.423402)
		(width 0.0889)
		(layer "In2.Cu")
		(net "M_I_CPU0_SB_CA<1>")
	)
	(segment
		(start 425.771056 -262.06831)
		(end 426.03801 -262.06831)
		(width 0.14478)
		(layer "In2.Cu")
		(net "M_I_CPU0_SB_CA<1>")
	)
	(segment
		(start 382.857756 -262.423402)
		(end 382.866138 -262.418576)
		(width 0.0889)
		(layer "In2.Cu")
		(net "M_I_CPU0_SB_CA<1>")
	)
	(segment
		(start 387.557772 -262.423402)
		(end 387.566154 -262.418576)
		(width 0.0889)
		(layer "In2.Cu")
		(net "M_I_CPU0_SB_CA<1>")
	)
	(segment
		(start 378.5235 -262.418576)
		(end 378.531882 -262.423402)
		(width 0.0889)
		(layer "In2.Cu")
		(net "M_I_CPU0_SB_CA<1>")
	)
	(segment
		(start 422.60266 -262.08101)
		(end 422.881806 -262.360156)
		(width 0.14478)
		(layer "In2.Cu")
		(net "M_I_CPU0_SB_CA<1>")
	)
	(segment
		(start 422.881806 -262.360156)
		(end 425.47921 -262.360156)
		(width 0.14478)
		(layer "In2.Cu")
		(net "M_I_CPU0_SB_CA<1>")
	)
	(segment
		(start 427.030896 -262.360156)
		(end 427.456092 -261.93496)
		(width 0.14478)
		(layer "In2.Cu")
		(net "M_I_CPU0_SB_CA<1>")
	)
	(segment
		(start 414.910524 -262.03783)
		(end 415.146998 -262.03783)
		(width 0.14478)
		(layer "In2.Cu")
		(net "M_I_CPU0_SB_CA<1>")
	)
	(segment
		(start 386.983478 -262.418576)
		(end 386.99186 -262.423402)
		(width 0.0889)
		(layer "In2.Cu")
		(net "M_I_CPU0_SB_CA<1>")
	)
	(segment
		(start 411.003496 -262.360156)
		(end 413.470598 -262.360156)
		(width 0.14478)
		(layer "In2.Cu")
		(net "M_I_CPU0_SB_CA<1>")
	)
	(segment
		(start 377.583446 -262.418576)
		(end 377.591828 -262.423402)
		(width 0.0889)
		(layer "In2.Cu")
		(net "M_I_CPU0_SB_CA<1>")
	)
	(segment
		(start 410.292296 -262.06577)
		(end 411.003496 -262.360156)
		(width 0.14478)
		(layer "In2.Cu")
		(net "M_I_CPU0_SB_CA<1>")
	)
	(segment
		(start 393.384786 -262.37184)
		(end 395.245844 -262.37184)
		(width 0.0889)
		(layer "In2.Cu")
		(net "M_I_CPU0_SB_CA<1>")
	)
	(segment
		(start 413.792924 -262.03783)
		(end 414.029398 -262.03783)
		(width 0.14478)
		(layer "In2.Cu")
		(net "M_I_CPU0_SB_CA<1>")
	)
	(segment
		(start 392.229594 -262.438642)
		(end 392.255756 -262.423656)
		(width 0.0889)
		(layer "In2.Cu")
		(net "M_I_CPU0_SB_CA<1>")
	)
	(segment
		(start 376.310906 -262.480552)
		(end 376.333258 -262.39724)
		(width 0.0889)
		(layer "In2.Cu")
		(net "M_I_CPU0_SB_CA<1>")
	)
	(segment
		(start 392.255756 -262.423656)
		(end 392.2776 -262.41121)
		(width 0.0889)
		(layer "In2.Cu")
		(net "M_I_CPU0_SB_CA<1>")
	)
	(segment
		(start 415.469324 -262.360156)
		(end 420.92626 -262.360156)
		(width 0.14478)
		(layer "In2.Cu")
		(net "M_I_CPU0_SB_CA<1>")
	)
	(segment
		(start 381.343408 -262.418576)
		(end 381.35179 -262.423402)
		(width 0.0889)
		(layer "In2.Cu")
		(net "M_I_CPU0_SB_CA<1>")
	)
	(segment
		(start 422.04386 -262.360156)
		(end 422.323006 -262.08101)
		(width 0.14478)
		(layer "In2.Cu")
		(net "M_I_CPU0_SB_CA<1>")
	)
	(arc
		(start 384.171952 -262.423402)
		(mid 384.454908 -262.499579)
		(end 384.737864 -262.423402)
		(width 0.0889)
		(layer "In2.Cu")
		(net "M_I_CPU0_SB_CA<1>")
	)
	(arc
		(start 377.217686 -262.423402)
		(mid 377.399937 -262.373052)
		(end 377.583446 -262.418576)
		(width 0.0889)
		(layer "In2.Cu")
		(net "M_I_CPU0_SB_CA<1>")
	)
	(arc
		(start 386.99186 -262.423402)
		(mid 387.274816 -262.499579)
		(end 387.557772 -262.423402)
		(width 0.0889)
		(layer "In2.Cu")
		(net "M_I_CPU0_SB_CA<1>")
	)
	(arc
		(start 382.866138 -262.418576)
		(mid 383.049646 -262.373082)
		(end 383.231898 -262.423402)
		(width 0.0889)
		(layer "In2.Cu")
		(net "M_I_CPU0_SB_CA<1>")
	)
	(arc
		(start 387.566154 -262.418576)
		(mid 387.749662 -262.373082)
		(end 387.931914 -262.423402)
		(width 0.0889)
		(layer "In2.Cu")
		(net "M_I_CPU0_SB_CA<1>")
	)
	(arc
		(start 382.291844 -262.423402)
		(mid 382.5748 -262.499579)
		(end 382.857756 -262.423402)
		(width 0.0889)
		(layer "In2.Cu")
		(net "M_I_CPU0_SB_CA<1>")
	)
	(arc
		(start 380.411736 -262.423402)
		(mid 380.694692 -262.499579)
		(end 380.977648 -262.423402)
		(width 0.0889)
		(layer "In2.Cu")
		(net "M_I_CPU0_SB_CA<1>")
	)
	(arc
		(start 385.677664 -262.423402)
		(mid 385.859915 -262.373052)
		(end 386.043424 -262.418576)
		(width 0.0889)
		(layer "In2.Cu")
		(net "M_I_CPU0_SB_CA<1>")
	)
	(arc
		(start 378.531882 -262.423402)
		(mid 378.814838 -262.499579)
		(end 379.097794 -262.423402)
		(width 0.0889)
		(layer "In2.Cu")
		(net "M_I_CPU0_SB_CA<1>")
	)
	(arc
		(start 376.651774 -262.423402)
		(mid 376.93473 -262.499579)
		(end 377.217686 -262.423402)
		(width 0.0889)
		(layer "In2.Cu")
		(net "M_I_CPU0_SB_CA<1>")
	)
	(arc
		(start 388.871968 -262.423402)
		(mid 389.154924 -262.499579)
		(end 389.43788 -262.423402)
		(width 0.0889)
		(layer "In2.Cu")
		(net "M_I_CPU0_SB_CA<1>")
	)
	(arc
		(start 391.691876 -262.423402)
		(mid 391.958806 -262.499351)
		(end 392.229594 -262.438642)
		(width 0.0889)
		(layer "In2.Cu")
		(net "M_I_CPU0_SB_CA<1>")
	)
	(arc
		(start 376.333258 -262.39724)
		(mid 376.495447 -262.374505)
		(end 376.651774 -262.423402)
		(width 0.0889)
		(layer "In2.Cu")
		(net "M_I_CPU0_SB_CA<1>")
	)
	(arc
		(start 380.037848 -262.423402)
		(mid 380.224792 -262.373147)
		(end 380.411736 -262.423402)
		(width 0.0889)
		(layer "In2.Cu")
		(net "M_I_CPU0_SB_CA<1>")
	)
	(arc
		(start 381.35179 -262.423402)
		(mid 381.634746 -262.499579)
		(end 381.917702 -262.423402)
		(width 0.0889)
		(layer "In2.Cu")
		(net "M_I_CPU0_SB_CA<1>")
	)
	(arc
		(start 383.806192 -262.418576)
		(mid 383.9897 -262.373082)
		(end 384.171952 -262.423402)
		(width 0.0889)
		(layer "In2.Cu")
		(net "M_I_CPU0_SB_CA<1>")
	)
	(arc
		(start 377.591828 -262.423402)
		(mid 377.874784 -262.499579)
		(end 378.15774 -262.423402)
		(width 0.0889)
		(layer "In2.Cu")
		(net "M_I_CPU0_SB_CA<1>")
	)
	(arc
		(start 386.617718 -262.423402)
		(mid 386.799969 -262.373052)
		(end 386.983478 -262.418576)
		(width 0.0889)
		(layer "In2.Cu")
		(net "M_I_CPU0_SB_CA<1>")
	)
	(arc
		(start 392.2776 -262.41121)
		(mid 392.454528 -262.373382)
		(end 392.628374 -262.423402)
		(width 0.0889)
		(layer "In2.Cu")
		(net "M_I_CPU0_SB_CA<1>")
	)
	(arc
		(start 389.811768 -262.423402)
		(mid 390.094724 -262.499579)
		(end 390.37768 -262.423402)
		(width 0.0889)
		(layer "In2.Cu")
		(net "M_I_CPU0_SB_CA<1>")
	)
	(arc
		(start 379.106176 -262.418576)
		(mid 379.289684 -262.373082)
		(end 379.471936 -262.423402)
		(width 0.0889)
		(layer "In2.Cu")
		(net "M_I_CPU0_SB_CA<1>")
	)
	(arc
		(start 378.15774 -262.423402)
		(mid 378.339991 -262.373052)
		(end 378.5235 -262.418576)
		(width 0.0889)
		(layer "In2.Cu")
		(net "M_I_CPU0_SB_CA<1>")
	)
	(arc
		(start 384.737864 -262.423402)
		(mid 384.924808 -262.373147)
		(end 385.111752 -262.423402)
		(width 0.0889)
		(layer "In2.Cu")
		(net "M_I_CPU0_SB_CA<1>")
	)
	(arc
		(start 387.931914 -262.423402)
		(mid 388.21487 -262.499579)
		(end 388.497826 -262.423402)
		(width 0.0889)
		(layer "In2.Cu")
		(net "M_I_CPU0_SB_CA<1>")
	)
	(arc
		(start 390.751822 -262.423402)
		(mid 391.034778 -262.499579)
		(end 391.317734 -262.423402)
		(width 0.0889)
		(layer "In2.Cu")
		(net "M_I_CPU0_SB_CA<1>")
	)
	(arc
		(start 389.43788 -262.423402)
		(mid 389.624824 -262.373147)
		(end 389.811768 -262.423402)
		(width 0.0889)
		(layer "In2.Cu")
		(net "M_I_CPU0_SB_CA<1>")
	)
	(arc
		(start 386.051806 -262.423402)
		(mid 386.334762 -262.499579)
		(end 386.617718 -262.423402)
		(width 0.0889)
		(layer "In2.Cu")
		(net "M_I_CPU0_SB_CA<1>")
	)
	(arc
		(start 390.37768 -262.423402)
		(mid 390.559931 -262.373052)
		(end 390.74344 -262.418576)
		(width 0.0889)
		(layer "In2.Cu")
		(net "M_I_CPU0_SB_CA<1>")
	)
	(arc
		(start 392.657838 -262.440674)
		(mid 392.929258 -262.500351)
		(end 393.196318 -262.423402)
		(width 0.0889)
		(layer "In2.Cu")
		(net "M_I_CPU0_SB_CA<1>")
	)
	(arc
		(start 393.196318 -262.423402)
		(mid 393.287124 -262.385089)
		(end 393.384786 -262.37184)
		(width 0.0889)
		(layer "In2.Cu")
		(net "M_I_CPU0_SB_CA<1>")
	)
	(arc
		(start 383.231898 -262.423402)
		(mid 383.514854 -262.499579)
		(end 383.79781 -262.423402)
		(width 0.0889)
		(layer "In2.Cu")
		(net "M_I_CPU0_SB_CA<1>")
	)
	(arc
		(start 380.977648 -262.423402)
		(mid 381.159899 -262.373052)
		(end 381.343408 -262.418576)
		(width 0.0889)
		(layer "In2.Cu")
		(net "M_I_CPU0_SB_CA<1>")
	)
	(arc
		(start 391.326116 -262.418576)
		(mid 391.509624 -262.373082)
		(end 391.691876 -262.423402)
		(width 0.0889)
		(layer "In2.Cu")
		(net "M_I_CPU0_SB_CA<1>")
	)
	(arc
		(start 379.471936 -262.423402)
		(mid 379.754892 -262.499579)
		(end 380.037848 -262.423402)
		(width 0.0889)
		(layer "In2.Cu")
		(net "M_I_CPU0_SB_CA<1>")
	)
	(arc
		(start 385.111752 -262.423402)
		(mid 385.394708 -262.499579)
		(end 385.677664 -262.423402)
		(width 0.0889)
		(layer "In2.Cu")
		(net "M_I_CPU0_SB_CA<1>")
	)
	(arc
		(start 388.506208 -262.418576)
		(mid 388.689716 -262.373082)
		(end 388.871968 -262.423402)
		(width 0.0889)
		(layer "In2.Cu")
		(net "M_I_CPU0_SB_CA<1>")
	)
	(arc
		(start 381.917702 -262.423402)
		(mid 382.099953 -262.373052)
		(end 382.283462 -262.418576)
		(width 0.0889)
		(layer "In2.Cu")
		(net "M_I_CPU0_SB_CA<1>")
	)
	(segment
		(start 375.528078 -261.670038)
		(end 375.99493 -261.935976)
		(width 0.10668)
		(layer "F.Cu")
		(net "M_I_CPU0_SB_CA<0>")
	)
	(segment
		(start 389.90778 -262.258556)
		(end 389.916162 -262.263382)
		(width 0.0889)
		(layer "In2.Cu")
		(net "M_I_CPU0_SB_CA<0>")
	)
	(segment
		(start 395.660626 -261.510018)
		(end 431.131218 -261.510018)
		(width 0.14478)
		(layer "In2.Cu")
		(net "M_I_CPU0_SB_CA<0>")
	)
	(segment
		(start 385.207764 -262.258556)
		(end 385.216146 -262.263382)
		(width 0.0889)
		(layer "In2.Cu")
		(net "M_I_CPU0_SB_CA<0>")
	)
	(segment
		(start 375.99493 -261.935976)
		(end 376.148854 -262.201406)
		(width 0.0889)
		(layer "In2.Cu")
		(net "M_I_CPU0_SB_CA<0>")
	)
	(segment
		(start 379.933454 -262.263382)
		(end 379.941836 -262.258556)
		(width 0.0889)
		(layer "In2.Cu")
		(net "M_I_CPU0_SB_CA<0>")
	)
	(segment
		(start 377.68784 -262.258556)
		(end 377.696222 -262.263382)
		(width 0.0889)
		(layer "In2.Cu")
		(net "M_I_CPU0_SB_CA<0>")
	)
	(segment
		(start 381.447802 -262.258556)
		(end 381.456184 -262.263382)
		(width 0.0889)
		(layer "In2.Cu")
		(net "M_I_CPU0_SB_CA<0>")
	)
	(segment
		(start 380.507748 -262.258556)
		(end 380.51613 -262.263382)
		(width 0.0889)
		(layer "In2.Cu")
		(net "M_I_CPU0_SB_CA<0>")
	)
	(segment
		(start 393.384532 -262.18134)
		(end 394.989304 -262.18134)
		(width 0.0889)
		(layer "In2.Cu")
		(net "M_I_CPU0_SB_CA<0>")
	)
	(segment
		(start 392.724386 -262.258556)
		(end 392.74496 -262.270494)
		(width 0.0889)
		(layer "In2.Cu")
		(net "M_I_CPU0_SB_CA<0>")
	)
	(segment
		(start 431.131218 -261.510018)
		(end 431.55616 -261.085076)
		(width 0.14478)
		(layer "In2.Cu")
		(net "M_I_CPU0_SB_CA<0>")
	)
	(segment
		(start 392.137138 -262.271764)
		(end 392.160506 -262.258302)
		(width 0.0889)
		(layer "In2.Cu")
		(net "M_I_CPU0_SB_CA<0>")
	)
	(segment
		(start 384.63347 -262.263382)
		(end 384.641852 -262.258556)
		(width 0.0889)
		(layer "In2.Cu")
		(net "M_I_CPU0_SB_CA<0>")
	)
	(segment
		(start 389.333486 -262.263382)
		(end 389.341868 -262.258556)
		(width 0.0889)
		(layer "In2.Cu")
		(net "M_I_CPU0_SB_CA<0>")
	)
	(segment
		(start 388.393432 -262.263382)
		(end 388.401814 -262.258556)
		(width 0.0889)
		(layer "In2.Cu")
		(net "M_I_CPU0_SB_CA<0>")
	)
	(segment
		(start 394.989304 -262.18134)
		(end 395.660626 -261.510018)
		(width 0.0889)
		(layer "In2.Cu")
		(net "M_I_CPU0_SB_CA<0>")
	)
	(segment
		(start 376.148854 -262.201406)
		(end 376.244866 -262.226806)
		(width 0.0889)
		(layer "In2.Cu")
		(net "M_I_CPU0_SB_CA<0>")
	)
	(segment
		(start 383.693416 -262.263382)
		(end 383.701798 -262.258556)
		(width 0.0889)
		(layer "In2.Cu")
		(net "M_I_CPU0_SB_CA<0>")
	)
	(segment
		(start 376.747786 -262.258556)
		(end 376.756168 -262.263382)
		(width 0.0889)
		(layer "In2.Cu")
		(net "M_I_CPU0_SB_CA<0>")
	)
	(segment
		(start 392.160506 -262.258302)
		(end 392.186668 -262.243316)
		(width 0.0889)
		(layer "In2.Cu")
		(net "M_I_CPU0_SB_CA<0>")
	)
	(segment
		(start 386.147818 -262.258556)
		(end 386.1562 -262.263382)
		(width 0.0889)
		(layer "In2.Cu")
		(net "M_I_CPU0_SB_CA<0>")
	)
	(arc
		(start 376.756168 -262.263382)
		(mid 376.939676 -262.308876)
		(end 377.121928 -262.258556)
		(width 0.0889)
		(layer "In2.Cu")
		(net "M_I_CPU0_SB_CA<0>")
	)
	(arc
		(start 389.341868 -262.258556)
		(mid 389.624824 -262.182379)
		(end 389.90778 -262.258556)
		(width 0.0889)
		(layer "In2.Cu")
		(net "M_I_CPU0_SB_CA<0>")
	)
	(arc
		(start 393.36345 -262.181594)
		(mid 393.37399 -262.18137)
		(end 393.384532 -262.18134)
		(width 0.0889)
		(layer "In2.Cu")
		(net "M_I_CPU0_SB_CA<0>")
	)
	(arc
		(start 381.456184 -262.263382)
		(mid 381.639692 -262.308876)
		(end 381.821944 -262.258556)
		(width 0.0889)
		(layer "In2.Cu")
		(net "M_I_CPU0_SB_CA<0>")
	)
	(arc
		(start 387.087872 -262.258556)
		(mid 387.274816 -262.308811)
		(end 387.46176 -262.258556)
		(width 0.0889)
		(layer "In2.Cu")
		(net "M_I_CPU0_SB_CA<0>")
	)
	(arc
		(start 377.121928 -262.258556)
		(mid 377.404884 -262.182379)
		(end 377.68784 -262.258556)
		(width 0.0889)
		(layer "In2.Cu")
		(net "M_I_CPU0_SB_CA<0>")
	)
	(arc
		(start 382.761744 -262.258556)
		(mid 383.0447 -262.182379)
		(end 383.327656 -262.258556)
		(width 0.0889)
		(layer "In2.Cu")
		(net "M_I_CPU0_SB_CA<0>")
	)
	(arc
		(start 382.387856 -262.258556)
		(mid 382.5748 -262.308811)
		(end 382.761744 -262.258556)
		(width 0.0889)
		(layer "In2.Cu")
		(net "M_I_CPU0_SB_CA<0>")
	)
	(arc
		(start 379.941836 -262.258556)
		(mid 380.224792 -262.182379)
		(end 380.507748 -262.258556)
		(width 0.0889)
		(layer "In2.Cu")
		(net "M_I_CPU0_SB_CA<0>")
	)
	(arc
		(start 376.244866 -262.226806)
		(mid 376.500074 -262.183329)
		(end 376.747786 -262.258556)
		(width 0.0889)
		(layer "In2.Cu")
		(net "M_I_CPU0_SB_CA<0>")
	)
	(arc
		(start 388.967726 -262.258556)
		(mid 389.149977 -262.308906)
		(end 389.333486 -262.263382)
		(width 0.0889)
		(layer "In2.Cu")
		(net "M_I_CPU0_SB_CA<0>")
	)
	(arc
		(start 381.821944 -262.258556)
		(mid 382.1049 -262.182379)
		(end 382.387856 -262.258556)
		(width 0.0889)
		(layer "In2.Cu")
		(net "M_I_CPU0_SB_CA<0>")
	)
	(arc
		(start 378.627894 -262.258556)
		(mid 378.814838 -262.308811)
		(end 379.001782 -262.258556)
		(width 0.0889)
		(layer "In2.Cu")
		(net "M_I_CPU0_SB_CA<0>")
	)
	(arc
		(start 383.701798 -262.258556)
		(mid 383.984754 -262.182379)
		(end 384.26771 -262.258556)
		(width 0.0889)
		(layer "In2.Cu")
		(net "M_I_CPU0_SB_CA<0>")
	)
	(arc
		(start 385.216146 -262.263382)
		(mid 385.399654 -262.308876)
		(end 385.581906 -262.258556)
		(width 0.0889)
		(layer "In2.Cu")
		(net "M_I_CPU0_SB_CA<0>")
	)
	(arc
		(start 380.88189 -262.258556)
		(mid 381.164846 -262.182379)
		(end 381.447802 -262.258556)
		(width 0.0889)
		(layer "In2.Cu")
		(net "M_I_CPU0_SB_CA<0>")
	)
	(arc
		(start 388.027672 -262.258556)
		(mid 388.209923 -262.308906)
		(end 388.393432 -262.263382)
		(width 0.0889)
		(layer "In2.Cu")
		(net "M_I_CPU0_SB_CA<0>")
	)
	(arc
		(start 377.696222 -262.263382)
		(mid 377.87973 -262.308876)
		(end 378.061982 -262.258556)
		(width 0.0889)
		(layer "In2.Cu")
		(net "M_I_CPU0_SB_CA<0>")
	)
	(arc
		(start 378.061982 -262.258556)
		(mid 378.344938 -262.182379)
		(end 378.627894 -262.258556)
		(width 0.0889)
		(layer "In2.Cu")
		(net "M_I_CPU0_SB_CA<0>")
	)
	(arc
		(start 391.787634 -262.258556)
		(mid 391.960742 -262.308672)
		(end 392.137138 -262.271764)
		(width 0.0889)
		(layer "In2.Cu")
		(net "M_I_CPU0_SB_CA<0>")
	)
	(arc
		(start 390.281922 -262.258556)
		(mid 390.564878 -262.182379)
		(end 390.847834 -262.258556)
		(width 0.0889)
		(layer "In2.Cu")
		(net "M_I_CPU0_SB_CA<0>")
	)
	(arc
		(start 386.1562 -262.263382)
		(mid 386.339708 -262.308876)
		(end 386.52196 -262.258556)
		(width 0.0889)
		(layer "In2.Cu")
		(net "M_I_CPU0_SB_CA<0>")
	)
	(arc
		(start 393.099798 -262.258556)
		(mid 393.226878 -262.203827)
		(end 393.36345 -262.181594)
		(width 0.0889)
		(layer "In2.Cu")
		(net "M_I_CPU0_SB_CA<0>")
	)
	(arc
		(start 388.401814 -262.258556)
		(mid 388.68477 -262.182379)
		(end 388.967726 -262.258556)
		(width 0.0889)
		(layer "In2.Cu")
		(net "M_I_CPU0_SB_CA<0>")
	)
	(arc
		(start 379.001782 -262.258556)
		(mid 379.284738 -262.182379)
		(end 379.567694 -262.258556)
		(width 0.0889)
		(layer "In2.Cu")
		(net "M_I_CPU0_SB_CA<0>")
	)
	(arc
		(start 390.847834 -262.258556)
		(mid 391.034778 -262.308811)
		(end 391.221722 -262.258556)
		(width 0.0889)
		(layer "In2.Cu")
		(net "M_I_CPU0_SB_CA<0>")
	)
	(arc
		(start 392.74496 -262.270494)
		(mid 392.923888 -262.309371)
		(end 393.099798 -262.258556)
		(width 0.0889)
		(layer "In2.Cu")
		(net "M_I_CPU0_SB_CA<0>")
	)
	(arc
		(start 384.26771 -262.258556)
		(mid 384.449961 -262.308906)
		(end 384.63347 -262.263382)
		(width 0.0889)
		(layer "In2.Cu")
		(net "M_I_CPU0_SB_CA<0>")
	)
	(arc
		(start 379.567694 -262.258556)
		(mid 379.749945 -262.308906)
		(end 379.933454 -262.263382)
		(width 0.0889)
		(layer "In2.Cu")
		(net "M_I_CPU0_SB_CA<0>")
	)
	(arc
		(start 384.641852 -262.258556)
		(mid 384.924808 -262.182379)
		(end 385.207764 -262.258556)
		(width 0.0889)
		(layer "In2.Cu")
		(net "M_I_CPU0_SB_CA<0>")
	)
	(arc
		(start 380.51613 -262.263382)
		(mid 380.699638 -262.308876)
		(end 380.88189 -262.258556)
		(width 0.0889)
		(layer "In2.Cu")
		(net "M_I_CPU0_SB_CA<0>")
	)
	(arc
		(start 387.46176 -262.258556)
		(mid 387.744716 -262.182379)
		(end 388.027672 -262.258556)
		(width 0.0889)
		(layer "In2.Cu")
		(net "M_I_CPU0_SB_CA<0>")
	)
	(arc
		(start 392.186668 -262.243316)
		(mid 392.457454 -262.18267)
		(end 392.724386 -262.258556)
		(width 0.0889)
		(layer "In2.Cu")
		(net "M_I_CPU0_SB_CA<0>")
	)
	(arc
		(start 385.581906 -262.258556)
		(mid 385.864862 -262.182379)
		(end 386.147818 -262.258556)
		(width 0.0889)
		(layer "In2.Cu")
		(net "M_I_CPU0_SB_CA<0>")
	)
	(arc
		(start 391.221722 -262.258556)
		(mid 391.504678 -262.182379)
		(end 391.787634 -262.258556)
		(width 0.0889)
		(layer "In2.Cu")
		(net "M_I_CPU0_SB_CA<0>")
	)
	(arc
		(start 386.52196 -262.258556)
		(mid 386.804916 -262.182379)
		(end 387.087872 -262.258556)
		(width 0.0889)
		(layer "In2.Cu")
		(net "M_I_CPU0_SB_CA<0>")
	)
	(arc
		(start 389.916162 -262.263382)
		(mid 390.09967 -262.308876)
		(end 390.281922 -262.258556)
		(width 0.0889)
		(layer "In2.Cu")
		(net "M_I_CPU0_SB_CA<0>")
	)
	(arc
		(start 383.327656 -262.258556)
		(mid 383.509907 -262.308906)
		(end 383.693416 -262.263382)
		(width 0.0889)
		(layer "In2.Cu")
		(net "M_I_CPU0_SB_CA<0>")
	)
	(segment
		(start 375.528078 -266.530074)
		(end 375.99493 -266.796012)
		(width 0.10668)
		(layer "F.Cu")
		(net "M_I_CPU0_SA_RSP<0>")
	)
	(segment
		(start 395.6177 -266.14374)
		(end 405.913336 -266.14374)
		(width 0.11684)
		(layer "In2.Cu")
		(net "M_I_CPU0_SA_RSP<0>")
	)
	(segment
		(start 389.333486 -267.123418)
		(end 389.341868 -267.118592)
		(width 0.0889)
		(layer "In2.Cu")
		(net "M_I_CPU0_SA_RSP<0>")
	)
	(segment
		(start 405.913336 -266.14374)
		(end 411.700218 -270.010382)
		(width 0.11684)
		(layer "In2.Cu")
		(net "M_I_CPU0_SA_RSP<0>")
	)
	(segment
		(start 376.148854 -267.061442)
		(end 376.244866 -267.086842)
		(width 0.0889)
		(layer "In2.Cu")
		(net "M_I_CPU0_SA_RSP<0>")
	)
	(segment
		(start 376.747786 -267.118592)
		(end 376.756168 -267.123418)
		(width 0.0889)
		(layer "In2.Cu")
		(net "M_I_CPU0_SA_RSP<0>")
	)
	(segment
		(start 381.447802 -267.118592)
		(end 381.456184 -267.123418)
		(width 0.0889)
		(layer "In2.Cu")
		(net "M_I_CPU0_SA_RSP<0>")
	)
	(segment
		(start 383.693416 -267.123418)
		(end 383.701798 -267.118592)
		(width 0.0889)
		(layer "In2.Cu")
		(net "M_I_CPU0_SA_RSP<0>")
	)
	(segment
		(start 384.63347 -267.123418)
		(end 384.641852 -267.118592)
		(width 0.0889)
		(layer "In2.Cu")
		(net "M_I_CPU0_SA_RSP<0>")
	)
	(segment
		(start 392.724386 -267.118592)
		(end 392.74496 -267.13053)
		(width 0.0889)
		(layer "In2.Cu")
		(net "M_I_CPU0_SA_RSP<0>")
	)
	(segment
		(start 393.099798 -267.118592)
		(end 394.27912 -265.93927)
		(width 0.0889)
		(layer "In2.Cu")
		(net "M_I_CPU0_SA_RSP<0>")
	)
	(segment
		(start 389.90778 -267.118592)
		(end 389.916162 -267.123418)
		(width 0.0889)
		(layer "In2.Cu")
		(net "M_I_CPU0_SA_RSP<0>")
	)
	(segment
		(start 431.130964 -270.010382)
		(end 431.55616 -269.585186)
		(width 0.11684)
		(layer "In2.Cu")
		(net "M_I_CPU0_SA_RSP<0>")
	)
	(segment
		(start 379.933454 -267.123418)
		(end 379.941836 -267.118592)
		(width 0.0889)
		(layer "In2.Cu")
		(net "M_I_CPU0_SA_RSP<0>")
	)
	(segment
		(start 385.207764 -267.118592)
		(end 385.216146 -267.123418)
		(width 0.0889)
		(layer "In2.Cu")
		(net "M_I_CPU0_SA_RSP<0>")
	)
	(segment
		(start 375.99493 -266.796012)
		(end 376.148854 -267.061442)
		(width 0.0889)
		(layer "In2.Cu")
		(net "M_I_CPU0_SA_RSP<0>")
	)
	(segment
		(start 392.160506 -267.118338)
		(end 392.186668 -267.103352)
		(width 0.0889)
		(layer "In2.Cu")
		(net "M_I_CPU0_SA_RSP<0>")
	)
	(segment
		(start 388.393432 -267.123418)
		(end 388.401814 -267.118592)
		(width 0.0889)
		(layer "In2.Cu")
		(net "M_I_CPU0_SA_RSP<0>")
	)
	(segment
		(start 395.41323 -265.93927)
		(end 395.6177 -266.14374)
		(width 0.0889)
		(layer "In2.Cu")
		(net "M_I_CPU0_SA_RSP<0>")
	)
	(segment
		(start 394.27912 -265.93927)
		(end 395.41323 -265.93927)
		(width 0.0889)
		(layer "In2.Cu")
		(net "M_I_CPU0_SA_RSP<0>")
	)
	(segment
		(start 380.873508 -267.123418)
		(end 380.88189 -267.118592)
		(width 0.0889)
		(layer "In2.Cu")
		(net "M_I_CPU0_SA_RSP<0>")
	)
	(segment
		(start 411.700218 -270.010382)
		(end 431.130964 -270.010382)
		(width 0.11684)
		(layer "In2.Cu")
		(net "M_I_CPU0_SA_RSP<0>")
	)
	(segment
		(start 392.137138 -267.1318)
		(end 392.160506 -267.118338)
		(width 0.0889)
		(layer "In2.Cu")
		(net "M_I_CPU0_SA_RSP<0>")
	)
	(segment
		(start 377.68784 -267.118592)
		(end 377.696222 -267.123418)
		(width 0.0889)
		(layer "In2.Cu")
		(net "M_I_CPU0_SA_RSP<0>")
	)
	(segment
		(start 386.147818 -267.118592)
		(end 386.1562 -267.123418)
		(width 0.0889)
		(layer "In2.Cu")
		(net "M_I_CPU0_SA_RSP<0>")
	)
	(arc
		(start 379.001782 -267.118592)
		(mid 379.284738 -267.042415)
		(end 379.567694 -267.118592)
		(width 0.0889)
		(layer "In2.Cu")
		(net "M_I_CPU0_SA_RSP<0>")
	)
	(arc
		(start 377.696222 -267.123418)
		(mid 377.87973 -267.168912)
		(end 378.061982 -267.118592)
		(width 0.0889)
		(layer "In2.Cu")
		(net "M_I_CPU0_SA_RSP<0>")
	)
	(arc
		(start 386.52196 -267.118592)
		(mid 386.804916 -267.042415)
		(end 387.087872 -267.118592)
		(width 0.0889)
		(layer "In2.Cu")
		(net "M_I_CPU0_SA_RSP<0>")
	)
	(arc
		(start 391.221722 -267.118592)
		(mid 391.504678 -267.042415)
		(end 391.787634 -267.118592)
		(width 0.0889)
		(layer "In2.Cu")
		(net "M_I_CPU0_SA_RSP<0>")
	)
	(arc
		(start 389.916162 -267.123418)
		(mid 390.09967 -267.168912)
		(end 390.281922 -267.118592)
		(width 0.0889)
		(layer "In2.Cu")
		(net "M_I_CPU0_SA_RSP<0>")
	)
	(arc
		(start 382.761744 -267.118592)
		(mid 383.0447 -267.042415)
		(end 383.327656 -267.118592)
		(width 0.0889)
		(layer "In2.Cu")
		(net "M_I_CPU0_SA_RSP<0>")
	)
	(arc
		(start 376.244866 -267.086842)
		(mid 376.500074 -267.043365)
		(end 376.747786 -267.118592)
		(width 0.0889)
		(layer "In2.Cu")
		(net "M_I_CPU0_SA_RSP<0>")
	)
	(arc
		(start 388.401814 -267.118592)
		(mid 388.68477 -267.042415)
		(end 388.967726 -267.118592)
		(width 0.0889)
		(layer "In2.Cu")
		(net "M_I_CPU0_SA_RSP<0>")
	)
	(arc
		(start 385.216146 -267.123418)
		(mid 385.399654 -267.168912)
		(end 385.581906 -267.118592)
		(width 0.0889)
		(layer "In2.Cu")
		(net "M_I_CPU0_SA_RSP<0>")
	)
	(arc
		(start 387.46176 -267.118592)
		(mid 387.744716 -267.042415)
		(end 388.027672 -267.118592)
		(width 0.0889)
		(layer "In2.Cu")
		(net "M_I_CPU0_SA_RSP<0>")
	)
	(arc
		(start 384.641852 -267.118592)
		(mid 384.924808 -267.042415)
		(end 385.207764 -267.118592)
		(width 0.0889)
		(layer "In2.Cu")
		(net "M_I_CPU0_SA_RSP<0>")
	)
	(arc
		(start 380.507748 -267.118592)
		(mid 380.689999 -267.168942)
		(end 380.873508 -267.123418)
		(width 0.0889)
		(layer "In2.Cu")
		(net "M_I_CPU0_SA_RSP<0>")
	)
	(arc
		(start 379.567694 -267.118592)
		(mid 379.749945 -267.168942)
		(end 379.933454 -267.123418)
		(width 0.0889)
		(layer "In2.Cu")
		(net "M_I_CPU0_SA_RSP<0>")
	)
	(arc
		(start 392.74496 -267.13053)
		(mid 392.923888 -267.169407)
		(end 393.099798 -267.118592)
		(width 0.0889)
		(layer "In2.Cu")
		(net "M_I_CPU0_SA_RSP<0>")
	)
	(arc
		(start 378.061982 -267.118592)
		(mid 378.344938 -267.042415)
		(end 378.627894 -267.118592)
		(width 0.0889)
		(layer "In2.Cu")
		(net "M_I_CPU0_SA_RSP<0>")
	)
	(arc
		(start 379.941836 -267.118592)
		(mid 380.224792 -267.042415)
		(end 380.507748 -267.118592)
		(width 0.0889)
		(layer "In2.Cu")
		(net "M_I_CPU0_SA_RSP<0>")
	)
	(arc
		(start 386.1562 -267.123418)
		(mid 386.339708 -267.168912)
		(end 386.52196 -267.118592)
		(width 0.0889)
		(layer "In2.Cu")
		(net "M_I_CPU0_SA_RSP<0>")
	)
	(arc
		(start 387.087872 -267.118592)
		(mid 387.274816 -267.168847)
		(end 387.46176 -267.118592)
		(width 0.0889)
		(layer "In2.Cu")
		(net "M_I_CPU0_SA_RSP<0>")
	)
	(arc
		(start 390.281922 -267.118592)
		(mid 390.564878 -267.042415)
		(end 390.847834 -267.118592)
		(width 0.0889)
		(layer "In2.Cu")
		(net "M_I_CPU0_SA_RSP<0>")
	)
	(arc
		(start 389.341868 -267.118592)
		(mid 389.624824 -267.042415)
		(end 389.90778 -267.118592)
		(width 0.0889)
		(layer "In2.Cu")
		(net "M_I_CPU0_SA_RSP<0>")
	)
	(arc
		(start 381.456184 -267.123418)
		(mid 381.639692 -267.168912)
		(end 381.821944 -267.118592)
		(width 0.0889)
		(layer "In2.Cu")
		(net "M_I_CPU0_SA_RSP<0>")
	)
	(arc
		(start 383.327656 -267.118592)
		(mid 383.509907 -267.168942)
		(end 383.693416 -267.123418)
		(width 0.0889)
		(layer "In2.Cu")
		(net "M_I_CPU0_SA_RSP<0>")
	)
	(arc
		(start 390.847834 -267.118592)
		(mid 391.034778 -267.168847)
		(end 391.221722 -267.118592)
		(width 0.0889)
		(layer "In2.Cu")
		(net "M_I_CPU0_SA_RSP<0>")
	)
	(arc
		(start 384.26771 -267.118592)
		(mid 384.449961 -267.168942)
		(end 384.63347 -267.123418)
		(width 0.0889)
		(layer "In2.Cu")
		(net "M_I_CPU0_SA_RSP<0>")
	)
	(arc
		(start 383.701798 -267.118592)
		(mid 383.984754 -267.042415)
		(end 384.26771 -267.118592)
		(width 0.0889)
		(layer "In2.Cu")
		(net "M_I_CPU0_SA_RSP<0>")
	)
	(arc
		(start 378.627894 -267.118592)
		(mid 378.814838 -267.168847)
		(end 379.001782 -267.118592)
		(width 0.0889)
		(layer "In2.Cu")
		(net "M_I_CPU0_SA_RSP<0>")
	)
	(arc
		(start 381.821944 -267.118592)
		(mid 382.1049 -267.042415)
		(end 382.387856 -267.118592)
		(width 0.0889)
		(layer "In2.Cu")
		(net "M_I_CPU0_SA_RSP<0>")
	)
	(arc
		(start 388.027672 -267.118592)
		(mid 388.209923 -267.168942)
		(end 388.393432 -267.123418)
		(width 0.0889)
		(layer "In2.Cu")
		(net "M_I_CPU0_SA_RSP<0>")
	)
	(arc
		(start 377.121928 -267.118592)
		(mid 377.404884 -267.042415)
		(end 377.68784 -267.118592)
		(width 0.0889)
		(layer "In2.Cu")
		(net "M_I_CPU0_SA_RSP<0>")
	)
	(arc
		(start 376.756168 -267.123418)
		(mid 376.939676 -267.168912)
		(end 377.121928 -267.118592)
		(width 0.0889)
		(layer "In2.Cu")
		(net "M_I_CPU0_SA_RSP<0>")
	)
	(arc
		(start 382.387856 -267.118592)
		(mid 382.5748 -267.168847)
		(end 382.761744 -267.118592)
		(width 0.0889)
		(layer "In2.Cu")
		(net "M_I_CPU0_SA_RSP<0>")
	)
	(arc
		(start 385.581906 -267.118592)
		(mid 385.864862 -267.042415)
		(end 386.147818 -267.118592)
		(width 0.0889)
		(layer "In2.Cu")
		(net "M_I_CPU0_SA_RSP<0>")
	)
	(arc
		(start 392.186668 -267.103352)
		(mid 392.457454 -267.042706)
		(end 392.724386 -267.118592)
		(width 0.0889)
		(layer "In2.Cu")
		(net "M_I_CPU0_SA_RSP<0>")
	)
	(arc
		(start 380.88189 -267.118592)
		(mid 381.164846 -267.042415)
		(end 381.447802 -267.118592)
		(width 0.0889)
		(layer "In2.Cu")
		(net "M_I_CPU0_SA_RSP<0>")
	)
	(arc
		(start 388.967726 -267.118592)
		(mid 389.149977 -267.168942)
		(end 389.333486 -267.123418)
		(width 0.0889)
		(layer "In2.Cu")
		(net "M_I_CPU0_SA_RSP<0>")
	)
	(arc
		(start 391.787634 -267.118592)
		(mid 391.960742 -267.168708)
		(end 392.137138 -267.1318)
		(width 0.0889)
		(layer "In2.Cu")
		(net "M_I_CPU0_SA_RSP<0>")
	)
	(segment
		(start 375.22785 -256.090166)
		(end 375.694702 -255.824228)
		(width 0.10668)
		(layer "F.Cu")
		(net "M_I_CPU0_SA_PAR")
	)
	(segment
		(start 380.207774 -255.501648)
		(end 380.216156 -255.496822)
		(width 0.0889)
		(layer "In2.Cu")
		(net "M_I_CPU0_SA_PAR")
	)
	(segment
		(start 394.799566 -256.503424)
		(end 394.928598 -256.374392)
		(width 0.0889)
		(layer "In2.Cu")
		(net "M_I_CPU0_SA_PAR")
	)
	(segment
		(start 392.413998 -255.510284)
		(end 392.42873 -255.501648)
		(width 0.0889)
		(layer "In2.Cu")
		(net "M_I_CPU0_SA_PAR")
	)
	(segment
		(start 425.190412 -254.493776)
		(end 425.499022 -253.748794)
		(width 0.14478)
		(layer "In2.Cu")
		(net "M_I_CPU0_SA_PAR")
	)
	(segment
		(start 425.499022 -253.748794)
		(end 426.0977 -253.150116)
		(width 0.14478)
		(layer "In2.Cu")
		(net "M_I_CPU0_SA_PAR")
	)
	(segment
		(start 375.84888 -255.558798)
		(end 375.945146 -255.533398)
		(width 0.0889)
		(layer "In2.Cu")
		(net "M_I_CPU0_SA_PAR")
	)
	(segment
		(start 393.56919 -255.660652)
		(end 394.411962 -256.503424)
		(width 0.0889)
		(layer "In2.Cu")
		(net "M_I_CPU0_SA_PAR")
	)
	(segment
		(start 389.607806 -255.501648)
		(end 389.616188 -255.496822)
		(width 0.0889)
		(layer "In2.Cu")
		(net "M_I_CPU0_SA_PAR")
	)
	(segment
		(start 399.119344 -256.374392)
		(end 400.399504 -255.094232)
		(width 0.14478)
		(layer "In2.Cu")
		(net "M_I_CPU0_SA_PAR")
	)
	(segment
		(start 384.90779 -255.501648)
		(end 384.916172 -255.496822)
		(width 0.0889)
		(layer "In2.Cu")
		(net "M_I_CPU0_SA_PAR")
	)
	(segment
		(start 428.677832 -253.104904)
		(end 431.115724 -253.844552)
		(width 0.14478)
		(layer "In2.Cu")
		(net "M_I_CPU0_SA_PAR")
	)
	(segment
		(start 395.230858 -256.374392)
		(end 399.119344 -256.374392)
		(width 0.14478)
		(layer "In2.Cu")
		(net "M_I_CPU0_SA_PAR")
	)
	(segment
		(start 403.567646 -255.094232)
		(end 404.03907 -255.565656)
		(width 0.14478)
		(layer "In2.Cu")
		(net "M_I_CPU0_SA_PAR")
	)
	(segment
		(start 392.788648 -255.494028)
		(end 392.802364 -255.501902)
		(width 0.0889)
		(layer "In2.Cu")
		(net "M_I_CPU0_SA_PAR")
	)
	(segment
		(start 385.847844 -255.501648)
		(end 385.856226 -255.496822)
		(width 0.0889)
		(layer "In2.Cu")
		(net "M_I_CPU0_SA_PAR")
	)
	(segment
		(start 424.974004 -254.710184)
		(end 425.190412 -254.493776)
		(width 0.14478)
		(layer "In2.Cu")
		(net "M_I_CPU0_SA_PAR")
	)
	(segment
		(start 391.48766 -255.501648)
		(end 391.496042 -255.496822)
		(width 0.0889)
		(layer "In2.Cu")
		(net "M_I_CPU0_SA_PAR")
	)
	(segment
		(start 422.477946 -255.09855)
		(end 423.416222 -254.710184)
		(width 0.14478)
		(layer "In2.Cu")
		(net "M_I_CPU0_SA_PAR")
	)
	(segment
		(start 384.333496 -255.496822)
		(end 384.341878 -255.501648)
		(width 0.0889)
		(layer "In2.Cu")
		(net "M_I_CPU0_SA_PAR")
	)
	(segment
		(start 394.928598 -256.374392)
		(end 395.230858 -256.374392)
		(width 0.0889)
		(layer "In2.Cu")
		(net "M_I_CPU0_SA_PAR")
	)
	(segment
		(start 400.399504 -255.094232)
		(end 403.567646 -255.094232)
		(width 0.14478)
		(layer "In2.Cu")
		(net "M_I_CPU0_SA_PAR")
	)
	(segment
		(start 426.0977 -253.150116)
		(end 426.435774 -253.010162)
		(width 0.14478)
		(layer "In2.Cu")
		(net "M_I_CPU0_SA_PAR")
	)
	(segment
		(start 431.115724 -253.844552)
		(end 431.55616 -254.284988)
		(width 0.14478)
		(layer "In2.Cu")
		(net "M_I_CPU0_SA_PAR")
	)
	(segment
		(start 389.033512 -255.496822)
		(end 389.041894 -255.501648)
		(width 0.0889)
		(layer "In2.Cu")
		(net "M_I_CPU0_SA_PAR")
	)
	(segment
		(start 428.201836 -253.010162)
		(end 428.677832 -253.104904)
		(width 0.14478)
		(layer "In2.Cu")
		(net "M_I_CPU0_SA_PAR")
	)
	(segment
		(start 388.093458 -255.496822)
		(end 388.10184 -255.501648)
		(width 0.0889)
		(layer "In2.Cu")
		(net "M_I_CPU0_SA_PAR")
	)
	(segment
		(start 379.63348 -255.496822)
		(end 379.641862 -255.501648)
		(width 0.0889)
		(layer "In2.Cu")
		(net "M_I_CPU0_SA_PAR")
	)
	(segment
		(start 423.416222 -254.710184)
		(end 424.974004 -254.710184)
		(width 0.14478)
		(layer "In2.Cu")
		(net "M_I_CPU0_SA_PAR")
	)
	(segment
		(start 420.128954 -255.565656)
		(end 422.477946 -255.09855)
		(width 0.14478)
		(layer "In2.Cu")
		(net "M_I_CPU0_SA_PAR")
	)
	(segment
		(start 381.147828 -255.501648)
		(end 381.15621 -255.496822)
		(width 0.0889)
		(layer "In2.Cu")
		(net "M_I_CPU0_SA_PAR")
	)
	(segment
		(start 426.435774 -253.010162)
		(end 428.201836 -253.010162)
		(width 0.14478)
		(layer "In2.Cu")
		(net "M_I_CPU0_SA_PAR")
	)
	(segment
		(start 375.694702 -255.824228)
		(end 375.84888 -255.558798)
		(width 0.0889)
		(layer "In2.Cu")
		(net "M_I_CPU0_SA_PAR")
	)
	(segment
		(start 383.393442 -255.496822)
		(end 383.401824 -255.501648)
		(width 0.0889)
		(layer "In2.Cu")
		(net "M_I_CPU0_SA_PAR")
	)
	(segment
		(start 378.693426 -255.496822)
		(end 378.701808 -255.501648)
		(width 0.0889)
		(layer "In2.Cu")
		(net "M_I_CPU0_SA_PAR")
	)
	(segment
		(start 404.03907 -255.565656)
		(end 420.128954 -255.565656)
		(width 0.14478)
		(layer "In2.Cu")
		(net "M_I_CPU0_SA_PAR")
	)
	(segment
		(start 394.411962 -256.503424)
		(end 394.799566 -256.503424)
		(width 0.0889)
		(layer "In2.Cu")
		(net "M_I_CPU0_SA_PAR")
	)
	(segment
		(start 393.392914 -255.660652)
		(end 393.56919 -255.660652)
		(width 0.0889)
		(layer "In2.Cu")
		(net "M_I_CPU0_SA_PAR")
	)
	(segment
		(start 376.447812 -255.501648)
		(end 376.456194 -255.496822)
		(width 0.0889)
		(layer "In2.Cu")
		(net "M_I_CPU0_SA_PAR")
	)
	(arc
		(start 379.641862 -255.501648)
		(mid 379.924818 -255.577825)
		(end 380.207774 -255.501648)
		(width 0.0889)
		(layer "In2.Cu")
		(net "M_I_CPU0_SA_PAR")
	)
	(arc
		(start 381.15621 -255.496822)
		(mid 381.339718 -255.451328)
		(end 381.52197 -255.501648)
		(width 0.0889)
		(layer "In2.Cu")
		(net "M_I_CPU0_SA_PAR")
	)
	(arc
		(start 390.54786 -255.501648)
		(mid 390.734804 -255.451393)
		(end 390.921748 -255.501648)
		(width 0.0889)
		(layer "In2.Cu")
		(net "M_I_CPU0_SA_PAR")
	)
	(arc
		(start 384.341878 -255.501648)
		(mid 384.624834 -255.577825)
		(end 384.90779 -255.501648)
		(width 0.0889)
		(layer "In2.Cu")
		(net "M_I_CPU0_SA_PAR")
	)
	(arc
		(start 387.161786 -255.501648)
		(mid 387.444742 -255.577825)
		(end 387.727698 -255.501648)
		(width 0.0889)
		(layer "In2.Cu")
		(net "M_I_CPU0_SA_PAR")
	)
	(arc
		(start 391.496042 -255.496822)
		(mid 391.679804 -255.451206)
		(end 391.86231 -255.501648)
		(width 0.0889)
		(layer "In2.Cu")
		(net "M_I_CPU0_SA_PAR")
	)
	(arc
		(start 388.667752 -255.501648)
		(mid 388.850003 -255.451298)
		(end 389.033512 -255.496822)
		(width 0.0889)
		(layer "In2.Cu")
		(net "M_I_CPU0_SA_PAR")
	)
	(arc
		(start 385.856226 -255.496822)
		(mid 386.039734 -255.451328)
		(end 386.221986 -255.501648)
		(width 0.0889)
		(layer "In2.Cu")
		(net "M_I_CPU0_SA_PAR")
	)
	(arc
		(start 377.761754 -255.501648)
		(mid 378.04471 -255.577825)
		(end 378.327666 -255.501648)
		(width 0.0889)
		(layer "In2.Cu")
		(net "M_I_CPU0_SA_PAR")
	)
	(arc
		(start 382.46177 -255.501648)
		(mid 382.744726 -255.577825)
		(end 383.027682 -255.501648)
		(width 0.0889)
		(layer "In2.Cu")
		(net "M_I_CPU0_SA_PAR")
	)
	(arc
		(start 378.701808 -255.501648)
		(mid 378.984764 -255.577825)
		(end 379.26772 -255.501648)
		(width 0.0889)
		(layer "In2.Cu")
		(net "M_I_CPU0_SA_PAR")
	)
	(arc
		(start 377.387866 -255.501648)
		(mid 377.57481 -255.451393)
		(end 377.761754 -255.501648)
		(width 0.0889)
		(layer "In2.Cu")
		(net "M_I_CPU0_SA_PAR")
	)
	(arc
		(start 389.616188 -255.496822)
		(mid 389.799696 -255.451328)
		(end 389.981948 -255.501648)
		(width 0.0889)
		(layer "In2.Cu")
		(net "M_I_CPU0_SA_PAR")
	)
	(arc
		(start 386.221986 -255.501648)
		(mid 386.504942 -255.577825)
		(end 386.787898 -255.501648)
		(width 0.0889)
		(layer "In2.Cu")
		(net "M_I_CPU0_SA_PAR")
	)
	(arc
		(start 384.916172 -255.496822)
		(mid 385.09968 -255.451328)
		(end 385.281932 -255.501648)
		(width 0.0889)
		(layer "In2.Cu")
		(net "M_I_CPU0_SA_PAR")
	)
	(arc
		(start 383.027682 -255.501648)
		(mid 383.209933 -255.451298)
		(end 383.393442 -255.496822)
		(width 0.0889)
		(layer "In2.Cu")
		(net "M_I_CPU0_SA_PAR")
	)
	(arc
		(start 390.921748 -255.501648)
		(mid 391.204704 -255.577825)
		(end 391.48766 -255.501648)
		(width 0.0889)
		(layer "In2.Cu")
		(net "M_I_CPU0_SA_PAR")
	)
	(arc
		(start 375.945146 -255.533398)
		(mid 376.200211 -255.576749)
		(end 376.447812 -255.501648)
		(width 0.0889)
		(layer "In2.Cu")
		(net "M_I_CPU0_SA_PAR")
	)
	(arc
		(start 378.327666 -255.501648)
		(mid 378.509917 -255.451298)
		(end 378.693426 -255.496822)
		(width 0.0889)
		(layer "In2.Cu")
		(net "M_I_CPU0_SA_PAR")
	)
	(arc
		(start 389.041894 -255.501648)
		(mid 389.32485 -255.577825)
		(end 389.607806 -255.501648)
		(width 0.0889)
		(layer "In2.Cu")
		(net "M_I_CPU0_SA_PAR")
	)
	(arc
		(start 380.216156 -255.496822)
		(mid 380.399664 -255.451328)
		(end 380.581916 -255.501648)
		(width 0.0889)
		(layer "In2.Cu")
		(net "M_I_CPU0_SA_PAR")
	)
	(arc
		(start 379.26772 -255.501648)
		(mid 379.449971 -255.451298)
		(end 379.63348 -255.496822)
		(width 0.0889)
		(layer "In2.Cu")
		(net "M_I_CPU0_SA_PAR")
	)
	(arc
		(start 382.087882 -255.501648)
		(mid 382.274826 -255.451393)
		(end 382.46177 -255.501648)
		(width 0.0889)
		(layer "In2.Cu")
		(net "M_I_CPU0_SA_PAR")
	)
	(arc
		(start 380.581916 -255.501648)
		(mid 380.864872 -255.577825)
		(end 381.147828 -255.501648)
		(width 0.0889)
		(layer "In2.Cu")
		(net "M_I_CPU0_SA_PAR")
	)
	(arc
		(start 376.821954 -255.501648)
		(mid 377.10491 -255.577825)
		(end 377.387866 -255.501648)
		(width 0.0889)
		(layer "In2.Cu")
		(net "M_I_CPU0_SA_PAR")
	)
	(arc
		(start 383.967736 -255.501648)
		(mid 384.149987 -255.451298)
		(end 384.333496 -255.496822)
		(width 0.0889)
		(layer "In2.Cu")
		(net "M_I_CPU0_SA_PAR")
	)
	(arc
		(start 389.981948 -255.501648)
		(mid 390.264904 -255.577825)
		(end 390.54786 -255.501648)
		(width 0.0889)
		(layer "In2.Cu")
		(net "M_I_CPU0_SA_PAR")
	)
	(arc
		(start 388.10184 -255.501648)
		(mid 388.384796 -255.577825)
		(end 388.667752 -255.501648)
		(width 0.0889)
		(layer "In2.Cu")
		(net "M_I_CPU0_SA_PAR")
	)
	(arc
		(start 386.787898 -255.501648)
		(mid 386.974842 -255.451393)
		(end 387.161786 -255.501648)
		(width 0.0889)
		(layer "In2.Cu")
		(net "M_I_CPU0_SA_PAR")
	)
	(arc
		(start 387.727698 -255.501648)
		(mid 387.909949 -255.451298)
		(end 388.093458 -255.496822)
		(width 0.0889)
		(layer "In2.Cu")
		(net "M_I_CPU0_SA_PAR")
	)
	(arc
		(start 385.281932 -255.501648)
		(mid 385.564888 -255.577825)
		(end 385.847844 -255.501648)
		(width 0.0889)
		(layer "In2.Cu")
		(net "M_I_CPU0_SA_PAR")
	)
	(arc
		(start 391.86231 -255.501648)
		(mid 392.137016 -255.578012)
		(end 392.413998 -255.510284)
		(width 0.0889)
		(layer "In2.Cu")
		(net "M_I_CPU0_SA_PAR")
	)
	(arc
		(start 376.456194 -255.496822)
		(mid 376.639702 -255.451328)
		(end 376.821954 -255.501648)
		(width 0.0889)
		(layer "In2.Cu")
		(net "M_I_CPU0_SA_PAR")
	)
	(arc
		(start 392.802364 -255.501902)
		(mid 393.087161 -255.620247)
		(end 393.392914 -255.660652)
		(width 0.0889)
		(layer "In2.Cu")
		(net "M_I_CPU0_SA_PAR")
	)
	(arc
		(start 381.52197 -255.501648)
		(mid 381.804926 -255.577825)
		(end 382.087882 -255.501648)
		(width 0.0889)
		(layer "In2.Cu")
		(net "M_I_CPU0_SA_PAR")
	)
	(arc
		(start 392.42873 -255.501648)
		(mid 392.607717 -255.451478)
		(end 392.788648 -255.494028)
		(width 0.0889)
		(layer "In2.Cu")
		(net "M_I_CPU0_SA_PAR")
	)
	(arc
		(start 383.401824 -255.501648)
		(mid 383.68478 -255.577825)
		(end 383.967736 -255.501648)
		(width 0.0889)
		(layer "In2.Cu")
		(net "M_I_CPU0_SA_PAR")
	)
	(segment
		(start 375.22785 -247.990106)
		(end 375.694702 -247.724168)
		(width 0.12954)
		(layer "F.Cu")
		(net "M_I_CPU0_SA_DQS_DP<9>")
	)
	(segment
		(start 384.906266 -247.399048)
		(end 384.914648 -247.394222)
		(width 0.09525)
		(layer "In2.Cu")
		(net "M_I_CPU0_SA_DQS_DP<9>")
	)
	(segment
		(start 407.985468 -245.378478)
		(end 408.512772 -245.378478)
		(width 0.16002)
		(layer "In2.Cu")
		(net "M_I_CPU0_SA_DQS_DP<9>")
	)
	(segment
		(start 396.89278 -246.935752)
		(end 405.497538 -246.935752)
		(width 0.16002)
		(layer "In2.Cu")
		(net "M_I_CPU0_SA_DQS_DP<9>")
	)
	(segment
		(start 410.260038 -243.103908)
		(end 409.93314 -242.77701)
		(width 0.16002)
		(layer "In2.Cu")
		(net "M_I_CPU0_SA_DQS_DP<9>")
	)
	(segment
		(start 422.39692 -239.402874)
		(end 422.809924 -239.402874)
		(width 0.16002)
		(layer "In2.Cu")
		(net "M_I_CPU0_SA_DQS_DP<9>")
	)
	(segment
		(start 405.497538 -246.935752)
		(end 406.008078 -246.425212)
		(width 0.16002)
		(layer "In2.Cu")
		(net "M_I_CPU0_SA_DQS_DP<9>")
	)
	(segment
		(start 385.84632 -247.399048)
		(end 385.854702 -247.394222)
		(width 0.09525)
		(layer "In2.Cu")
		(net "M_I_CPU0_SA_DQS_DP<9>")
	)
	(segment
		(start 415.849308 -239.986312)
		(end 418.312854 -239.986312)
		(width 0.16002)
		(layer "In2.Cu")
		(net "M_I_CPU0_SA_DQS_DP<9>")
	)
	(segment
		(start 375.848626 -247.458738)
		(end 375.949464 -247.432068)
		(width 0.09525)
		(layer "In2.Cu")
		(net "M_I_CPU0_SA_DQS_DP<9>")
	)
	(segment
		(start 414.852866 -239.402874)
		(end 415.26587 -239.402874)
		(width 0.16002)
		(layer "In2.Cu")
		(net "M_I_CPU0_SA_DQS_DP<9>")
	)
	(segment
		(start 420.526718 -240.836196)
		(end 421.16756 -240.195354)
		(width 0.16002)
		(layer "In2.Cu")
		(net "M_I_CPU0_SA_DQS_DP<9>")
	)
	(segment
		(start 395.597634 -247.47474)
		(end 395.656562 -247.533668)
		(width 0.09525)
		(layer "In2.Cu")
		(net "M_I_CPU0_SA_DQS_DP<9>")
	)
	(segment
		(start 407.38171 -245.05158)
		(end 407.65857 -245.05158)
		(width 0.16002)
		(layer "In2.Cu")
		(net "M_I_CPU0_SA_DQS_DP<9>")
	)
	(segment
		(start 379.635004 -247.394222)
		(end 379.643386 -247.399048)
		(width 0.09525)
		(layer "In2.Cu")
		(net "M_I_CPU0_SA_DQS_DP<9>")
	)
	(segment
		(start 409.93314 -242.77701)
		(end 409.93314 -242.50015)
		(width 0.16002)
		(layer "In2.Cu")
		(net "M_I_CPU0_SA_DQS_DP<9>")
	)
	(segment
		(start 380.20625 -247.399048)
		(end 380.214632 -247.394222)
		(width 0.09525)
		(layer "In2.Cu")
		(net "M_I_CPU0_SA_DQS_DP<9>")
	)
	(segment
		(start 408.755342 -243.677948)
		(end 409.032202 -243.677948)
		(width 0.16002)
		(layer "In2.Cu")
		(net "M_I_CPU0_SA_DQS_DP<9>")
	)
	(segment
		(start 409.3591 -244.004846)
		(end 409.886404 -244.004846)
		(width 0.16002)
		(layer "In2.Cu")
		(net "M_I_CPU0_SA_DQS_DP<9>")
	)
	(segment
		(start 427.182788 -239.561878)
		(end 427.456092 -239.835182)
		(width 0.16002)
		(layer "In2.Cu")
		(net "M_I_CPU0_SA_DQS_DP<9>")
	)
	(segment
		(start 392.795506 -247.394222)
		(end 392.803888 -247.399048)
		(width 0.09525)
		(layer "In2.Cu")
		(net "M_I_CPU0_SA_DQS_DP<9>")
	)
	(segment
		(start 406.611836 -246.75211)
		(end 407.13914 -246.75211)
		(width 0.16002)
		(layer "In2.Cu")
		(net "M_I_CPU0_SA_DQS_DP<9>")
	)
	(segment
		(start 407.512774 -245.851172)
		(end 407.185876 -245.524274)
		(width 0.16002)
		(layer "In2.Cu")
		(net "M_I_CPU0_SA_DQS_DP<9>")
	)
	(segment
		(start 395.656562 -247.533668)
		(end 395.680184 -247.533668)
		(width 0.09525)
		(layer "In2.Cu")
		(net "M_I_CPU0_SA_DQS_DP<9>")
	)
	(segment
		(start 409.886404 -244.004846)
		(end 410.260038 -243.631212)
		(width 0.16002)
		(layer "In2.Cu")
		(net "M_I_CPU0_SA_DQS_DP<9>")
	)
	(segment
		(start 408.559508 -243.873782)
		(end 408.755342 -243.677948)
		(width 0.16002)
		(layer "In2.Cu")
		(net "M_I_CPU0_SA_DQS_DP<9>")
	)
	(segment
		(start 376.446288 -247.399048)
		(end 376.45467 -247.394222)
		(width 0.09525)
		(layer "In2.Cu")
		(net "M_I_CPU0_SA_DQS_DP<9>")
	)
	(segment
		(start 392.803888 -247.399048)
		(end 392.824716 -247.41124)
		(width 0.09525)
		(layer "In2.Cu")
		(net "M_I_CPU0_SA_DQS_DP<9>")
	)
	(segment
		(start 383.394966 -247.394222)
		(end 383.403348 -247.399048)
		(width 0.09525)
		(layer "In2.Cu")
		(net "M_I_CPU0_SA_DQS_DP<9>")
	)
	(segment
		(start 406.284938 -246.425212)
		(end 406.611836 -246.75211)
		(width 0.16002)
		(layer "In2.Cu")
		(net "M_I_CPU0_SA_DQS_DP<9>")
	)
	(segment
		(start 407.512774 -246.378476)
		(end 407.512774 -245.851172)
		(width 0.16002)
		(layer "In2.Cu")
		(net "M_I_CPU0_SA_DQS_DP<9>")
	)
	(segment
		(start 408.512772 -245.378478)
		(end 408.886406 -245.004844)
		(width 0.16002)
		(layer "In2.Cu")
		(net "M_I_CPU0_SA_DQS_DP<9>")
	)
	(segment
		(start 422.809924 -239.402874)
		(end 423.117264 -239.710214)
		(width 0.16002)
		(layer "In2.Cu")
		(net "M_I_CPU0_SA_DQS_DP<9>")
	)
	(segment
		(start 378.69495 -247.394222)
		(end 378.703332 -247.399048)
		(width 0.09525)
		(layer "In2.Cu")
		(net "M_I_CPU0_SA_DQS_DP<9>")
	)
	(segment
		(start 389.606282 -247.399048)
		(end 389.614664 -247.394222)
		(width 0.09525)
		(layer "In2.Cu")
		(net "M_I_CPU0_SA_DQS_DP<9>")
	)
	(segment
		(start 413.623506 -240.195354)
		(end 414.060386 -240.195354)
		(width 0.16002)
		(layer "In2.Cu")
		(net "M_I_CPU0_SA_DQS_DP<9>")
	)
	(segment
		(start 408.886406 -244.47754)
		(end 408.559508 -244.150642)
		(width 0.16002)
		(layer "In2.Cu")
		(net "M_I_CPU0_SA_DQS_DP<9>")
	)
	(segment
		(start 407.13914 -246.75211)
		(end 407.512774 -246.378476)
		(width 0.16002)
		(layer "In2.Cu")
		(net "M_I_CPU0_SA_DQS_DP<9>")
	)
	(segment
		(start 396.294864 -247.533668)
		(end 396.89278 -246.935752)
		(width 0.16002)
		(layer "In2.Cu")
		(net "M_I_CPU0_SA_DQS_DP<9>")
	)
	(segment
		(start 392.412474 -247.407684)
		(end 392.427206 -247.399048)
		(width 0.09525)
		(layer "In2.Cu")
		(net "M_I_CPU0_SA_DQS_DP<9>")
	)
	(segment
		(start 406.008078 -246.425212)
		(end 406.284938 -246.425212)
		(width 0.16002)
		(layer "In2.Cu")
		(net "M_I_CPU0_SA_DQS_DP<9>")
	)
	(segment
		(start 418.312854 -239.986312)
		(end 419.162738 -240.836196)
		(width 0.16002)
		(layer "In2.Cu")
		(net "M_I_CPU0_SA_DQS_DP<9>")
	)
	(segment
		(start 425.19092 -239.710214)
		(end 425.339256 -239.561878)
		(width 0.16002)
		(layer "In2.Cu")
		(net "M_I_CPU0_SA_DQS_DP<9>")
	)
	(segment
		(start 393.736068 -247.394222)
		(end 393.74445 -247.399048)
		(width 0.09525)
		(layer "In2.Cu")
		(net "M_I_CPU0_SA_DQS_DP<9>")
	)
	(segment
		(start 415.26587 -239.402874)
		(end 415.849308 -239.986312)
		(width 0.16002)
		(layer "In2.Cu")
		(net "M_I_CPU0_SA_DQS_DP<9>")
	)
	(segment
		(start 381.146304 -247.399048)
		(end 381.154686 -247.394222)
		(width 0.09525)
		(layer "In2.Cu")
		(net "M_I_CPU0_SA_DQS_DP<9>")
	)
	(segment
		(start 421.60444 -240.195354)
		(end 422.39692 -239.402874)
		(width 0.16002)
		(layer "In2.Cu")
		(net "M_I_CPU0_SA_DQS_DP<9>")
	)
	(segment
		(start 419.162738 -240.836196)
		(end 420.526718 -240.836196)
		(width 0.16002)
		(layer "In2.Cu")
		(net "M_I_CPU0_SA_DQS_DP<9>")
	)
	(segment
		(start 407.65857 -245.05158)
		(end 407.985468 -245.378478)
		(width 0.16002)
		(layer "In2.Cu")
		(net "M_I_CPU0_SA_DQS_DP<9>")
	)
	(segment
		(start 421.16756 -240.195354)
		(end 421.60444 -240.195354)
		(width 0.16002)
		(layer "In2.Cu")
		(net "M_I_CPU0_SA_DQS_DP<9>")
	)
	(segment
		(start 395.680184 -247.533668)
		(end 396.294864 -247.533668)
		(width 0.16002)
		(layer "In2.Cu")
		(net "M_I_CPU0_SA_DQS_DP<9>")
	)
	(segment
		(start 409.032202 -243.677948)
		(end 409.3591 -244.004846)
		(width 0.16002)
		(layer "In2.Cu")
		(net "M_I_CPU0_SA_DQS_DP<9>")
	)
	(segment
		(start 407.185876 -245.247414)
		(end 407.38171 -245.05158)
		(width 0.16002)
		(layer "In2.Cu")
		(net "M_I_CPU0_SA_DQS_DP<9>")
	)
	(segment
		(start 423.117264 -239.710214)
		(end 425.19092 -239.710214)
		(width 0.16002)
		(layer "In2.Cu")
		(net "M_I_CPU0_SA_DQS_DP<9>")
	)
	(segment
		(start 409.93314 -242.50015)
		(end 411.597094 -240.836196)
		(width 0.16002)
		(layer "In2.Cu")
		(net "M_I_CPU0_SA_DQS_DP<9>")
	)
	(segment
		(start 384.33502 -247.394222)
		(end 384.343402 -247.399048)
		(width 0.09525)
		(layer "In2.Cu")
		(net "M_I_CPU0_SA_DQS_DP<9>")
	)
	(segment
		(start 391.486136 -247.399048)
		(end 391.494518 -247.394222)
		(width 0.09525)
		(layer "In2.Cu")
		(net "M_I_CPU0_SA_DQS_DP<9>")
	)
	(segment
		(start 408.886406 -245.004844)
		(end 408.886406 -244.47754)
		(width 0.16002)
		(layer "In2.Cu")
		(net "M_I_CPU0_SA_DQS_DP<9>")
	)
	(segment
		(start 411.597094 -240.836196)
		(end 412.982664 -240.836196)
		(width 0.16002)
		(layer "In2.Cu")
		(net "M_I_CPU0_SA_DQS_DP<9>")
	)
	(segment
		(start 408.559508 -244.150642)
		(end 408.559508 -243.873782)
		(width 0.16002)
		(layer "In2.Cu")
		(net "M_I_CPU0_SA_DQS_DP<9>")
	)
	(segment
		(start 394.025882 -247.47474)
		(end 395.597634 -247.47474)
		(width 0.09525)
		(layer "In2.Cu")
		(net "M_I_CPU0_SA_DQS_DP<9>")
	)
	(segment
		(start 388.094982 -247.394222)
		(end 388.103364 -247.399048)
		(width 0.09525)
		(layer "In2.Cu")
		(net "M_I_CPU0_SA_DQS_DP<9>")
	)
	(segment
		(start 375.694702 -247.724168)
		(end 375.848626 -247.458738)
		(width 0.09525)
		(layer "In2.Cu")
		(net "M_I_CPU0_SA_DQS_DP<9>")
	)
	(segment
		(start 407.185876 -245.524274)
		(end 407.185876 -245.247414)
		(width 0.16002)
		(layer "In2.Cu")
		(net "M_I_CPU0_SA_DQS_DP<9>")
	)
	(segment
		(start 425.339256 -239.561878)
		(end 427.182788 -239.561878)
		(width 0.16002)
		(layer "In2.Cu")
		(net "M_I_CPU0_SA_DQS_DP<9>")
	)
	(segment
		(start 410.260038 -243.631212)
		(end 410.260038 -243.103908)
		(width 0.16002)
		(layer "In2.Cu")
		(net "M_I_CPU0_SA_DQS_DP<9>")
	)
	(segment
		(start 412.982664 -240.836196)
		(end 413.623506 -240.195354)
		(width 0.16002)
		(layer "In2.Cu")
		(net "M_I_CPU0_SA_DQS_DP<9>")
	)
	(segment
		(start 414.060386 -240.195354)
		(end 414.852866 -239.402874)
		(width 0.16002)
		(layer "In2.Cu")
		(net "M_I_CPU0_SA_DQS_DP<9>")
	)
	(segment
		(start 389.035036 -247.394222)
		(end 389.043418 -247.399048)
		(width 0.09525)
		(layer "In2.Cu")
		(net "M_I_CPU0_SA_DQS_DP<9>")
	)
	(arc
		(start 380.214632 -247.394222)
		(mid 380.399664 -247.348308)
		(end 380.58344 -247.399048)
		(width 0.09525)
		(layer "In2.Cu")
		(net "M_I_CPU0_SA_DQS_DP<9>")
	)
	(arc
		(start 376.45467 -247.394222)
		(mid 376.639702 -247.348308)
		(end 376.823478 -247.399048)
		(width 0.09525)
		(layer "In2.Cu")
		(net "M_I_CPU0_SA_DQS_DP<9>")
	)
	(arc
		(start 381.523494 -247.399048)
		(mid 381.804926 -247.474803)
		(end 382.086358 -247.399048)
		(width 0.09525)
		(layer "In2.Cu")
		(net "M_I_CPU0_SA_DQS_DP<9>")
	)
	(arc
		(start 375.970038 -247.440196)
		(mid 376.21278 -247.472966)
		(end 376.446288 -247.399048)
		(width 0.09525)
		(layer "In2.Cu")
		(net "M_I_CPU0_SA_DQS_DP<9>")
	)
	(arc
		(start 382.463294 -247.399048)
		(mid 382.744726 -247.474803)
		(end 383.026158 -247.399048)
		(width 0.09525)
		(layer "In2.Cu")
		(net "M_I_CPU0_SA_DQS_DP<9>")
	)
	(arc
		(start 379.266196 -247.399048)
		(mid 379.449971 -247.348276)
		(end 379.635004 -247.394222)
		(width 0.09525)
		(layer "In2.Cu")
		(net "M_I_CPU0_SA_DQS_DP<9>")
	)
	(arc
		(start 393.74445 -247.399048)
		(mid 393.880157 -247.455533)
		(end 394.025882 -247.47474)
		(width 0.09525)
		(layer "In2.Cu")
		(net "M_I_CPU0_SA_DQS_DP<9>")
	)
	(arc
		(start 377.386342 -247.399048)
		(mid 377.57481 -247.348371)
		(end 377.763278 -247.399048)
		(width 0.09525)
		(layer "In2.Cu")
		(net "M_I_CPU0_SA_DQS_DP<9>")
	)
	(arc
		(start 378.703332 -247.399048)
		(mid 378.984764 -247.474803)
		(end 379.266196 -247.399048)
		(width 0.09525)
		(layer "In2.Cu")
		(net "M_I_CPU0_SA_DQS_DP<9>")
	)
	(arc
		(start 386.786374 -247.399048)
		(mid 386.974842 -247.348371)
		(end 387.16331 -247.399048)
		(width 0.09525)
		(layer "In2.Cu")
		(net "M_I_CPU0_SA_DQS_DP<9>")
	)
	(arc
		(start 385.283456 -247.399048)
		(mid 385.564888 -247.474803)
		(end 385.84632 -247.399048)
		(width 0.09525)
		(layer "In2.Cu")
		(net "M_I_CPU0_SA_DQS_DP<9>")
	)
	(arc
		(start 387.16331 -247.399048)
		(mid 387.444742 -247.474803)
		(end 387.726174 -247.399048)
		(width 0.09525)
		(layer "In2.Cu")
		(net "M_I_CPU0_SA_DQS_DP<9>")
	)
	(arc
		(start 391.494518 -247.394222)
		(mid 391.679804 -247.348186)
		(end 391.863834 -247.399048)
		(width 0.09525)
		(layer "In2.Cu")
		(net "M_I_CPU0_SA_DQS_DP<9>")
	)
	(arc
		(start 384.343402 -247.399048)
		(mid 384.624834 -247.474803)
		(end 384.906266 -247.399048)
		(width 0.09525)
		(layer "In2.Cu")
		(net "M_I_CPU0_SA_DQS_DP<9>")
	)
	(arc
		(start 393.366752 -247.399048)
		(mid 393.550781 -247.348149)
		(end 393.736068 -247.394222)
		(width 0.09525)
		(layer "In2.Cu")
		(net "M_I_CPU0_SA_DQS_DP<9>")
	)
	(arc
		(start 390.546336 -247.399048)
		(mid 390.734804 -247.348371)
		(end 390.923272 -247.399048)
		(width 0.09525)
		(layer "In2.Cu")
		(net "M_I_CPU0_SA_DQS_DP<9>")
	)
	(arc
		(start 380.58344 -247.399048)
		(mid 380.864872 -247.474803)
		(end 381.146304 -247.399048)
		(width 0.09525)
		(layer "In2.Cu")
		(net "M_I_CPU0_SA_DQS_DP<9>")
	)
	(arc
		(start 392.824716 -247.41124)
		(mid 393.097321 -247.475036)
		(end 393.366752 -247.399048)
		(width 0.09525)
		(layer "In2.Cu")
		(net "M_I_CPU0_SA_DQS_DP<9>")
	)
	(arc
		(start 390.923272 -247.399048)
		(mid 391.204704 -247.474803)
		(end 391.486136 -247.399048)
		(width 0.09525)
		(layer "In2.Cu")
		(net "M_I_CPU0_SA_DQS_DP<9>")
	)
	(arc
		(start 376.823478 -247.399048)
		(mid 377.10491 -247.474803)
		(end 377.386342 -247.399048)
		(width 0.09525)
		(layer "In2.Cu")
		(net "M_I_CPU0_SA_DQS_DP<9>")
	)
	(arc
		(start 378.326142 -247.399048)
		(mid 378.509917 -247.348276)
		(end 378.69495 -247.394222)
		(width 0.09525)
		(layer "In2.Cu")
		(net "M_I_CPU0_SA_DQS_DP<9>")
	)
	(arc
		(start 386.22351 -247.399048)
		(mid 386.504942 -247.474803)
		(end 386.786374 -247.399048)
		(width 0.09525)
		(layer "In2.Cu")
		(net "M_I_CPU0_SA_DQS_DP<9>")
	)
	(arc
		(start 389.983472 -247.399048)
		(mid 390.264904 -247.474803)
		(end 390.546336 -247.399048)
		(width 0.09525)
		(layer "In2.Cu")
		(net "M_I_CPU0_SA_DQS_DP<9>")
	)
	(arc
		(start 388.666228 -247.399048)
		(mid 388.850003 -247.348276)
		(end 389.035036 -247.394222)
		(width 0.09525)
		(layer "In2.Cu")
		(net "M_I_CPU0_SA_DQS_DP<9>")
	)
	(arc
		(start 388.103364 -247.399048)
		(mid 388.384796 -247.474803)
		(end 388.666228 -247.399048)
		(width 0.09525)
		(layer "In2.Cu")
		(net "M_I_CPU0_SA_DQS_DP<9>")
	)
	(arc
		(start 375.949464 -247.432068)
		(mid 375.959712 -247.436231)
		(end 375.970038 -247.440196)
		(width 0.09525)
		(layer "In2.Cu")
		(net "M_I_CPU0_SA_DQS_DP<9>")
	)
	(arc
		(start 377.763278 -247.399048)
		(mid 378.04471 -247.474803)
		(end 378.326142 -247.399048)
		(width 0.09525)
		(layer "In2.Cu")
		(net "M_I_CPU0_SA_DQS_DP<9>")
	)
	(arc
		(start 392.427206 -247.399048)
		(mid 392.610727 -247.348404)
		(end 392.795506 -247.394222)
		(width 0.09525)
		(layer "In2.Cu")
		(net "M_I_CPU0_SA_DQS_DP<9>")
	)
	(arc
		(start 389.614664 -247.394222)
		(mid 389.799696 -247.348308)
		(end 389.983472 -247.399048)
		(width 0.09525)
		(layer "In2.Cu")
		(net "M_I_CPU0_SA_DQS_DP<9>")
	)
	(arc
		(start 382.086358 -247.399048)
		(mid 382.274826 -247.348371)
		(end 382.463294 -247.399048)
		(width 0.09525)
		(layer "In2.Cu")
		(net "M_I_CPU0_SA_DQS_DP<9>")
	)
	(arc
		(start 387.726174 -247.399048)
		(mid 387.909949 -247.348276)
		(end 388.094982 -247.394222)
		(width 0.09525)
		(layer "In2.Cu")
		(net "M_I_CPU0_SA_DQS_DP<9>")
	)
	(arc
		(start 384.914648 -247.394222)
		(mid 385.09968 -247.348308)
		(end 385.283456 -247.399048)
		(width 0.09525)
		(layer "In2.Cu")
		(net "M_I_CPU0_SA_DQS_DP<9>")
	)
	(arc
		(start 379.643386 -247.399048)
		(mid 379.924818 -247.474803)
		(end 380.20625 -247.399048)
		(width 0.09525)
		(layer "In2.Cu")
		(net "M_I_CPU0_SA_DQS_DP<9>")
	)
	(arc
		(start 391.863834 -247.399048)
		(mid 392.137016 -247.47499)
		(end 392.412474 -247.407684)
		(width 0.09525)
		(layer "In2.Cu")
		(net "M_I_CPU0_SA_DQS_DP<9>")
	)
	(arc
		(start 385.854702 -247.394222)
		(mid 386.039734 -247.348308)
		(end 386.22351 -247.399048)
		(width 0.09525)
		(layer "In2.Cu")
		(net "M_I_CPU0_SA_DQS_DP<9>")
	)
	(arc
		(start 381.154686 -247.394222)
		(mid 381.339718 -247.348308)
		(end 381.523494 -247.399048)
		(width 0.09525)
		(layer "In2.Cu")
		(net "M_I_CPU0_SA_DQS_DP<9>")
	)
	(arc
		(start 383.026158 -247.399048)
		(mid 383.209933 -247.348276)
		(end 383.394966 -247.394222)
		(width 0.09525)
		(layer "In2.Cu")
		(net "M_I_CPU0_SA_DQS_DP<9>")
	)
	(arc
		(start 383.966212 -247.399048)
		(mid 384.149987 -247.348276)
		(end 384.33502 -247.394222)
		(width 0.09525)
		(layer "In2.Cu")
		(net "M_I_CPU0_SA_DQS_DP<9>")
	)
	(arc
		(start 383.403348 -247.399048)
		(mid 383.68478 -247.474803)
		(end 383.966212 -247.399048)
		(width 0.09525)
		(layer "In2.Cu")
		(net "M_I_CPU0_SA_DQS_DP<9>")
	)
	(arc
		(start 389.043418 -247.399048)
		(mid 389.32485 -247.474803)
		(end 389.606282 -247.399048)
		(width 0.09525)
		(layer "In2.Cu")
		(net "M_I_CPU0_SA_DQS_DP<9>")
	)
	(segment
		(start 375.22785 -243.13007)
		(end 375.694702 -242.864132)
		(width 0.12954)
		(layer "F.Cu")
		(net "M_I_CPU0_SA_DQS_DP<8>")
	)
	(segment
		(start 375.848626 -242.598702)
		(end 375.949464 -242.572032)
		(width 0.09525)
		(layer "In2.Cu")
		(net "M_I_CPU0_SA_DQS_DP<8>")
	)
	(segment
		(start 425.19092 -230.36022)
		(end 425.339256 -230.211884)
		(width 0.16002)
		(layer "In2.Cu")
		(net "M_I_CPU0_SA_DQS_DP<8>")
	)
	(segment
		(start 403.84476 -238.307626)
		(end 404.217632 -237.934754)
		(width 0.16002)
		(layer "In2.Cu")
		(net "M_I_CPU0_SA_DQS_DP<8>")
	)
	(segment
		(start 422.39692 -230.05288)
		(end 422.809924 -230.05288)
		(width 0.16002)
		(layer "In2.Cu")
		(net "M_I_CPU0_SA_DQS_DP<8>")
	)
	(segment
		(start 401.194524 -239.601756)
		(end 401.39112 -239.40516)
		(width 0.16002)
		(layer "In2.Cu")
		(net "M_I_CPU0_SA_DQS_DP<8>")
	)
	(segment
		(start 425.339256 -230.211884)
		(end 427.182788 -230.211884)
		(width 0.16002)
		(layer "In2.Cu")
		(net "M_I_CPU0_SA_DQS_DP<8>")
	)
	(segment
		(start 413.623506 -230.84536)
		(end 414.060386 -230.84536)
		(width 0.16002)
		(layer "In2.Cu")
		(net "M_I_CPU0_SA_DQS_DP<8>")
	)
	(segment
		(start 384.33502 -242.534186)
		(end 384.343402 -242.539012)
		(width 0.09525)
		(layer "In2.Cu")
		(net "M_I_CPU0_SA_DQS_DP<8>")
	)
	(segment
		(start 395.686026 -241.25555)
		(end 400.896836 -241.25555)
		(width 0.16002)
		(layer "In2.Cu")
		(net "M_I_CPU0_SA_DQS_DP<8>")
	)
	(segment
		(start 385.84632 -242.539012)
		(end 385.854702 -242.534186)
		(width 0.09525)
		(layer "In2.Cu")
		(net "M_I_CPU0_SA_DQS_DP<8>")
	)
	(segment
		(start 413.258762 -231.210104)
		(end 413.623506 -230.84536)
		(width 0.16002)
		(layer "In2.Cu")
		(net "M_I_CPU0_SA_DQS_DP<8>")
	)
	(segment
		(start 402.844 -239.308386)
		(end 402.844 -238.780828)
		(width 0.16002)
		(layer "In2.Cu")
		(net "M_I_CPU0_SA_DQS_DP<8>")
	)
	(segment
		(start 378.69495 -242.534186)
		(end 378.703332 -242.539012)
		(width 0.09525)
		(layer "In2.Cu")
		(net "M_I_CPU0_SA_DQS_DP<8>")
	)
	(segment
		(start 421.16756 -230.84536)
		(end 421.60444 -230.84536)
		(width 0.16002)
		(layer "In2.Cu")
		(net "M_I_CPU0_SA_DQS_DP<8>")
	)
	(segment
		(start 381.146304 -242.539012)
		(end 381.154686 -242.534186)
		(width 0.09525)
		(layer "In2.Cu")
		(net "M_I_CPU0_SA_DQS_DP<8>")
	)
	(segment
		(start 404.217632 -237.934754)
		(end 404.217632 -237.407196)
		(width 0.16002)
		(layer "In2.Cu")
		(net "M_I_CPU0_SA_DQS_DP<8>")
	)
	(segment
		(start 394.24483 -242.12804)
		(end 394.846302 -242.12804)
		(width 0.09525)
		(layer "In2.Cu")
		(net "M_I_CPU0_SA_DQS_DP<8>")
	)
	(segment
		(start 401.470368 -240.15446)
		(end 401.194524 -239.878616)
		(width 0.16002)
		(layer "In2.Cu")
		(net "M_I_CPU0_SA_DQS_DP<8>")
	)
	(segment
		(start 410.942282 -231.210104)
		(end 413.258762 -231.210104)
		(width 0.16002)
		(layer "In2.Cu")
		(net "M_I_CPU0_SA_DQS_DP<8>")
	)
	(segment
		(start 423.117264 -230.36022)
		(end 425.19092 -230.36022)
		(width 0.16002)
		(layer "In2.Cu")
		(net "M_I_CPU0_SA_DQS_DP<8>")
	)
	(segment
		(start 391.486136 -242.539012)
		(end 391.494518 -242.534186)
		(width 0.09525)
		(layer "In2.Cu")
		(net "M_I_CPU0_SA_DQS_DP<8>")
	)
	(segment
		(start 403.041358 -238.031528)
		(end 403.317456 -238.307626)
		(width 0.16002)
		(layer "In2.Cu")
		(net "M_I_CPU0_SA_DQS_DP<8>")
	)
	(segment
		(start 389.606282 -242.539012)
		(end 389.614664 -242.534186)
		(width 0.09525)
		(layer "In2.Cu")
		(net "M_I_CPU0_SA_DQS_DP<8>")
	)
	(segment
		(start 395.603476 -241.196622)
		(end 395.662404 -241.25555)
		(width 0.09525)
		(layer "In2.Cu")
		(net "M_I_CPU0_SA_DQS_DP<8>")
	)
	(segment
		(start 405.218392 -236.933994)
		(end 410.942282 -231.210104)
		(width 0.16002)
		(layer "In2.Cu")
		(net "M_I_CPU0_SA_DQS_DP<8>")
	)
	(segment
		(start 375.694702 -242.864132)
		(end 375.848626 -242.598702)
		(width 0.09525)
		(layer "In2.Cu")
		(net "M_I_CPU0_SA_DQS_DP<8>")
	)
	(segment
		(start 394.11021 -242.26266)
		(end 394.24483 -242.12804)
		(width 0.09525)
		(layer "In2.Cu")
		(net "M_I_CPU0_SA_DQS_DP<8>")
	)
	(segment
		(start 401.39112 -239.40516)
		(end 401.667726 -239.40516)
		(width 0.16002)
		(layer "In2.Cu")
		(net "M_I_CPU0_SA_DQS_DP<8>")
	)
	(segment
		(start 402.568156 -238.504984)
		(end 402.568156 -238.228124)
		(width 0.16002)
		(layer "In2.Cu")
		(net "M_I_CPU0_SA_DQS_DP<8>")
	)
	(segment
		(start 404.691088 -236.933994)
		(end 405.218392 -236.933994)
		(width 0.16002)
		(layer "In2.Cu")
		(net "M_I_CPU0_SA_DQS_DP<8>")
	)
	(segment
		(start 394.846302 -242.12804)
		(end 395.234668 -241.739674)
		(width 0.09525)
		(layer "In2.Cu")
		(net "M_I_CPU0_SA_DQS_DP<8>")
	)
	(segment
		(start 392.803888 -242.539012)
		(end 392.827256 -242.552474)
		(width 0.09525)
		(layer "In2.Cu")
		(net "M_I_CPU0_SA_DQS_DP<8>")
	)
	(segment
		(start 415.26587 -230.05288)
		(end 415.57321 -230.36022)
		(width 0.16002)
		(layer "In2.Cu")
		(net "M_I_CPU0_SA_DQS_DP<8>")
	)
	(segment
		(start 402.764752 -238.031528)
		(end 403.041358 -238.031528)
		(width 0.16002)
		(layer "In2.Cu")
		(net "M_I_CPU0_SA_DQS_DP<8>")
	)
	(segment
		(start 427.182788 -230.211884)
		(end 427.456092 -230.485188)
		(width 0.16002)
		(layer "In2.Cu")
		(net "M_I_CPU0_SA_DQS_DP<8>")
	)
	(segment
		(start 383.394966 -242.534186)
		(end 383.403348 -242.539012)
		(width 0.09525)
		(layer "In2.Cu")
		(net "M_I_CPU0_SA_DQS_DP<8>")
	)
	(segment
		(start 403.317456 -238.307626)
		(end 403.84476 -238.307626)
		(width 0.16002)
		(layer "In2.Cu")
		(net "M_I_CPU0_SA_DQS_DP<8>")
	)
	(segment
		(start 402.568156 -238.228124)
		(end 402.764752 -238.031528)
		(width 0.16002)
		(layer "In2.Cu")
		(net "M_I_CPU0_SA_DQS_DP<8>")
	)
	(segment
		(start 401.943824 -239.681258)
		(end 402.471128 -239.681258)
		(width 0.16002)
		(layer "In2.Cu")
		(net "M_I_CPU0_SA_DQS_DP<8>")
	)
	(segment
		(start 393.48156 -242.450874)
		(end 393.669774 -242.26266)
		(width 0.09525)
		(layer "In2.Cu")
		(net "M_I_CPU0_SA_DQS_DP<8>")
	)
	(segment
		(start 403.941788 -237.131352)
		(end 403.941788 -236.854492)
		(width 0.16002)
		(layer "In2.Cu")
		(net "M_I_CPU0_SA_DQS_DP<8>")
	)
	(segment
		(start 395.234668 -241.739674)
		(end 395.234668 -241.299746)
		(width 0.09525)
		(layer "In2.Cu")
		(net "M_I_CPU0_SA_DQS_DP<8>")
	)
	(segment
		(start 392.79195 -242.532154)
		(end 392.803888 -242.539012)
		(width 0.09525)
		(layer "In2.Cu")
		(net "M_I_CPU0_SA_DQS_DP<8>")
	)
	(segment
		(start 403.941788 -236.854492)
		(end 404.138384 -236.657896)
		(width 0.16002)
		(layer "In2.Cu")
		(net "M_I_CPU0_SA_DQS_DP<8>")
	)
	(segment
		(start 415.57321 -230.36022)
		(end 418.036756 -230.36022)
		(width 0.16002)
		(layer "In2.Cu")
		(net "M_I_CPU0_SA_DQS_DP<8>")
	)
	(segment
		(start 418.036756 -230.36022)
		(end 418.886894 -231.210358)
		(width 0.16002)
		(layer "In2.Cu")
		(net "M_I_CPU0_SA_DQS_DP<8>")
	)
	(segment
		(start 388.094982 -242.534186)
		(end 388.103364 -242.539012)
		(width 0.09525)
		(layer "In2.Cu")
		(net "M_I_CPU0_SA_DQS_DP<8>")
	)
	(segment
		(start 421.60444 -230.84536)
		(end 422.39692 -230.05288)
		(width 0.16002)
		(layer "In2.Cu")
		(net "M_I_CPU0_SA_DQS_DP<8>")
	)
	(segment
		(start 402.844 -238.780828)
		(end 402.568156 -238.504984)
		(width 0.16002)
		(layer "In2.Cu")
		(net "M_I_CPU0_SA_DQS_DP<8>")
	)
	(segment
		(start 395.662404 -241.25555)
		(end 395.686026 -241.25555)
		(width 0.09525)
		(layer "In2.Cu")
		(net "M_I_CPU0_SA_DQS_DP<8>")
	)
	(segment
		(start 384.906266 -242.539012)
		(end 384.914648 -242.534186)
		(width 0.09525)
		(layer "In2.Cu")
		(net "M_I_CPU0_SA_DQS_DP<8>")
	)
	(segment
		(start 392.416538 -242.545108)
		(end 392.426952 -242.539012)
		(width 0.09525)
		(layer "In2.Cu")
		(net "M_I_CPU0_SA_DQS_DP<8>")
	)
	(segment
		(start 401.667726 -239.40516)
		(end 401.943824 -239.681258)
		(width 0.16002)
		(layer "In2.Cu")
		(net "M_I_CPU0_SA_DQS_DP<8>")
	)
	(segment
		(start 404.138384 -236.657896)
		(end 404.41499 -236.657896)
		(width 0.16002)
		(layer "In2.Cu")
		(net "M_I_CPU0_SA_DQS_DP<8>")
	)
	(segment
		(start 380.20625 -242.539012)
		(end 380.214632 -242.534186)
		(width 0.09525)
		(layer "In2.Cu")
		(net "M_I_CPU0_SA_DQS_DP<8>")
	)
	(segment
		(start 401.194524 -239.878616)
		(end 401.194524 -239.601756)
		(width 0.16002)
		(layer "In2.Cu")
		(net "M_I_CPU0_SA_DQS_DP<8>")
	)
	(segment
		(start 402.471128 -239.681258)
		(end 402.844 -239.308386)
		(width 0.16002)
		(layer "In2.Cu")
		(net "M_I_CPU0_SA_DQS_DP<8>")
	)
	(segment
		(start 389.035036 -242.534186)
		(end 389.043418 -242.539012)
		(width 0.09525)
		(layer "In2.Cu")
		(net "M_I_CPU0_SA_DQS_DP<8>")
	)
	(segment
		(start 422.809924 -230.05288)
		(end 423.117264 -230.36022)
		(width 0.16002)
		(layer "In2.Cu")
		(net "M_I_CPU0_SA_DQS_DP<8>")
	)
	(segment
		(start 420.802562 -231.210358)
		(end 421.16756 -230.84536)
		(width 0.16002)
		(layer "In2.Cu")
		(net "M_I_CPU0_SA_DQS_DP<8>")
	)
	(segment
		(start 414.060386 -230.84536)
		(end 414.852866 -230.05288)
		(width 0.16002)
		(layer "In2.Cu")
		(net "M_I_CPU0_SA_DQS_DP<8>")
	)
	(segment
		(start 404.217632 -237.407196)
		(end 403.941788 -237.131352)
		(width 0.16002)
		(layer "In2.Cu")
		(net "M_I_CPU0_SA_DQS_DP<8>")
	)
	(segment
		(start 404.41499 -236.657896)
		(end 404.691088 -236.933994)
		(width 0.16002)
		(layer "In2.Cu")
		(net "M_I_CPU0_SA_DQS_DP<8>")
	)
	(segment
		(start 400.896836 -241.25555)
		(end 401.470368 -240.682018)
		(width 0.16002)
		(layer "In2.Cu")
		(net "M_I_CPU0_SA_DQS_DP<8>")
	)
	(segment
		(start 393.669774 -242.26266)
		(end 394.11021 -242.26266)
		(width 0.09525)
		(layer "In2.Cu")
		(net "M_I_CPU0_SA_DQS_DP<8>")
	)
	(segment
		(start 379.635004 -242.534186)
		(end 379.643386 -242.539012)
		(width 0.09525)
		(layer "In2.Cu")
		(net "M_I_CPU0_SA_DQS_DP<8>")
	)
	(segment
		(start 395.234668 -241.299746)
		(end 395.337792 -241.196622)
		(width 0.09525)
		(layer "In2.Cu")
		(net "M_I_CPU0_SA_DQS_DP<8>")
	)
	(segment
		(start 418.886894 -231.210358)
		(end 420.802562 -231.210358)
		(width 0.16002)
		(layer "In2.Cu")
		(net "M_I_CPU0_SA_DQS_DP<8>")
	)
	(segment
		(start 395.337792 -241.196622)
		(end 395.603476 -241.196622)
		(width 0.09525)
		(layer "In2.Cu")
		(net "M_I_CPU0_SA_DQS_DP<8>")
	)
	(segment
		(start 376.446288 -242.539012)
		(end 376.45467 -242.534186)
		(width 0.09525)
		(layer "In2.Cu")
		(net "M_I_CPU0_SA_DQS_DP<8>")
	)
	(segment
		(start 414.852866 -230.05288)
		(end 415.26587 -230.05288)
		(width 0.16002)
		(layer "In2.Cu")
		(net "M_I_CPU0_SA_DQS_DP<8>")
	)
	(segment
		(start 401.470368 -240.682018)
		(end 401.470368 -240.15446)
		(width 0.16002)
		(layer "In2.Cu")
		(net "M_I_CPU0_SA_DQS_DP<8>")
	)
	(arc
		(start 383.026158 -242.539012)
		(mid 383.209933 -242.48824)
		(end 383.394966 -242.534186)
		(width 0.09525)
		(layer "In2.Cu")
		(net "M_I_CPU0_SA_DQS_DP<8>")
	)
	(arc
		(start 375.949464 -242.572032)
		(mid 375.959712 -242.576195)
		(end 375.970038 -242.58016)
		(width 0.09525)
		(layer "In2.Cu")
		(net "M_I_CPU0_SA_DQS_DP<8>")
	)
	(arc
		(start 392.827256 -242.552474)
		(mid 393.098849 -242.614919)
		(end 393.367006 -242.539012)
		(width 0.09525)
		(layer "In2.Cu")
		(net "M_I_CPU0_SA_DQS_DP<8>")
	)
	(arc
		(start 385.854702 -242.534186)
		(mid 386.039734 -242.488272)
		(end 386.22351 -242.539012)
		(width 0.09525)
		(layer "In2.Cu")
		(net "M_I_CPU0_SA_DQS_DP<8>")
	)
	(arc
		(start 381.154686 -242.534186)
		(mid 381.339718 -242.488272)
		(end 381.523494 -242.539012)
		(width 0.09525)
		(layer "In2.Cu")
		(net "M_I_CPU0_SA_DQS_DP<8>")
	)
	(arc
		(start 391.863834 -242.539012)
		(mid 392.139377 -242.614861)
		(end 392.416538 -242.545108)
		(width 0.09525)
		(layer "In2.Cu")
		(net "M_I_CPU0_SA_DQS_DP<8>")
	)
	(arc
		(start 387.726174 -242.539012)
		(mid 387.909949 -242.48824)
		(end 388.094982 -242.534186)
		(width 0.09525)
		(layer "In2.Cu")
		(net "M_I_CPU0_SA_DQS_DP<8>")
	)
	(arc
		(start 378.326142 -242.539012)
		(mid 378.509917 -242.48824)
		(end 378.69495 -242.534186)
		(width 0.09525)
		(layer "In2.Cu")
		(net "M_I_CPU0_SA_DQS_DP<8>")
	)
	(arc
		(start 379.266196 -242.539012)
		(mid 379.449971 -242.48824)
		(end 379.635004 -242.534186)
		(width 0.09525)
		(layer "In2.Cu")
		(net "M_I_CPU0_SA_DQS_DP<8>")
	)
	(arc
		(start 384.343402 -242.539012)
		(mid 384.624834 -242.614767)
		(end 384.906266 -242.539012)
		(width 0.09525)
		(layer "In2.Cu")
		(net "M_I_CPU0_SA_DQS_DP<8>")
	)
	(arc
		(start 393.367006 -242.539012)
		(mid 393.427143 -242.498658)
		(end 393.48156 -242.450874)
		(width 0.09525)
		(layer "In2.Cu")
		(net "M_I_CPU0_SA_DQS_DP<8>")
	)
	(arc
		(start 381.523494 -242.539012)
		(mid 381.804926 -242.614767)
		(end 382.086358 -242.539012)
		(width 0.09525)
		(layer "In2.Cu")
		(net "M_I_CPU0_SA_DQS_DP<8>")
	)
	(arc
		(start 388.666228 -242.539012)
		(mid 388.850003 -242.48824)
		(end 389.035036 -242.534186)
		(width 0.09525)
		(layer "In2.Cu")
		(net "M_I_CPU0_SA_DQS_DP<8>")
	)
	(arc
		(start 383.966212 -242.539012)
		(mid 384.149987 -242.48824)
		(end 384.33502 -242.534186)
		(width 0.09525)
		(layer "In2.Cu")
		(net "M_I_CPU0_SA_DQS_DP<8>")
	)
	(arc
		(start 387.16331 -242.539012)
		(mid 387.444742 -242.614767)
		(end 387.726174 -242.539012)
		(width 0.09525)
		(layer "In2.Cu")
		(net "M_I_CPU0_SA_DQS_DP<8>")
	)
	(arc
		(start 392.426952 -242.539012)
		(mid 392.608568 -242.488275)
		(end 392.79195 -242.532154)
		(width 0.09525)
		(layer "In2.Cu")
		(net "M_I_CPU0_SA_DQS_DP<8>")
	)
	(arc
		(start 382.463294 -242.539012)
		(mid 382.744726 -242.614767)
		(end 383.026158 -242.539012)
		(width 0.09525)
		(layer "In2.Cu")
		(net "M_I_CPU0_SA_DQS_DP<8>")
	)
	(arc
		(start 383.403348 -242.539012)
		(mid 383.68478 -242.614767)
		(end 383.966212 -242.539012)
		(width 0.09525)
		(layer "In2.Cu")
		(net "M_I_CPU0_SA_DQS_DP<8>")
	)
	(arc
		(start 391.494518 -242.534186)
		(mid 391.679804 -242.48815)
		(end 391.863834 -242.539012)
		(width 0.09525)
		(layer "In2.Cu")
		(net "M_I_CPU0_SA_DQS_DP<8>")
	)
	(arc
		(start 385.283456 -242.539012)
		(mid 385.564888 -242.614767)
		(end 385.84632 -242.539012)
		(width 0.09525)
		(layer "In2.Cu")
		(net "M_I_CPU0_SA_DQS_DP<8>")
	)
	(arc
		(start 379.643386 -242.539012)
		(mid 379.924818 -242.614767)
		(end 380.20625 -242.539012)
		(width 0.09525)
		(layer "In2.Cu")
		(net "M_I_CPU0_SA_DQS_DP<8>")
	)
	(arc
		(start 389.043418 -242.539012)
		(mid 389.32485 -242.614767)
		(end 389.606282 -242.539012)
		(width 0.09525)
		(layer "In2.Cu")
		(net "M_I_CPU0_SA_DQS_DP<8>")
	)
	(arc
		(start 388.103364 -242.539012)
		(mid 388.384796 -242.614767)
		(end 388.666228 -242.539012)
		(width 0.09525)
		(layer "In2.Cu")
		(net "M_I_CPU0_SA_DQS_DP<8>")
	)
	(arc
		(start 380.58344 -242.539012)
		(mid 380.864872 -242.614767)
		(end 381.146304 -242.539012)
		(width 0.09525)
		(layer "In2.Cu")
		(net "M_I_CPU0_SA_DQS_DP<8>")
	)
	(arc
		(start 386.22351 -242.539012)
		(mid 386.504942 -242.614767)
		(end 386.786374 -242.539012)
		(width 0.09525)
		(layer "In2.Cu")
		(net "M_I_CPU0_SA_DQS_DP<8>")
	)
	(arc
		(start 377.763278 -242.539012)
		(mid 378.04471 -242.614767)
		(end 378.326142 -242.539012)
		(width 0.09525)
		(layer "In2.Cu")
		(net "M_I_CPU0_SA_DQS_DP<8>")
	)
	(arc
		(start 378.703332 -242.539012)
		(mid 378.984764 -242.614767)
		(end 379.266196 -242.539012)
		(width 0.09525)
		(layer "In2.Cu")
		(net "M_I_CPU0_SA_DQS_DP<8>")
	)
	(arc
		(start 389.614664 -242.534186)
		(mid 389.799696 -242.488272)
		(end 389.983472 -242.539012)
		(width 0.09525)
		(layer "In2.Cu")
		(net "M_I_CPU0_SA_DQS_DP<8>")
	)
	(arc
		(start 390.923272 -242.539012)
		(mid 391.204704 -242.614767)
		(end 391.486136 -242.539012)
		(width 0.09525)
		(layer "In2.Cu")
		(net "M_I_CPU0_SA_DQS_DP<8>")
	)
	(arc
		(start 389.983472 -242.539012)
		(mid 390.264904 -242.614767)
		(end 390.546336 -242.539012)
		(width 0.09525)
		(layer "In2.Cu")
		(net "M_I_CPU0_SA_DQS_DP<8>")
	)
	(arc
		(start 380.214632 -242.534186)
		(mid 380.399664 -242.488272)
		(end 380.58344 -242.539012)
		(width 0.09525)
		(layer "In2.Cu")
		(net "M_I_CPU0_SA_DQS_DP<8>")
	)
	(arc
		(start 377.386342 -242.539012)
		(mid 377.57481 -242.488335)
		(end 377.763278 -242.539012)
		(width 0.09525)
		(layer "In2.Cu")
		(net "M_I_CPU0_SA_DQS_DP<8>")
	)
	(arc
		(start 376.823478 -242.539012)
		(mid 377.10491 -242.614767)
		(end 377.386342 -242.539012)
		(width 0.09525)
		(layer "In2.Cu")
		(net "M_I_CPU0_SA_DQS_DP<8>")
	)
	(arc
		(start 384.914648 -242.534186)
		(mid 385.09968 -242.488272)
		(end 385.283456 -242.539012)
		(width 0.09525)
		(layer "In2.Cu")
		(net "M_I_CPU0_SA_DQS_DP<8>")
	)
	(arc
		(start 376.45467 -242.534186)
		(mid 376.639702 -242.488272)
		(end 376.823478 -242.539012)
		(width 0.09525)
		(layer "In2.Cu")
		(net "M_I_CPU0_SA_DQS_DP<8>")
	)
	(arc
		(start 382.086358 -242.539012)
		(mid 382.274826 -242.488335)
		(end 382.463294 -242.539012)
		(width 0.09525)
		(layer "In2.Cu")
		(net "M_I_CPU0_SA_DQS_DP<8>")
	)
	(arc
		(start 386.786374 -242.539012)
		(mid 386.974842 -242.488335)
		(end 387.16331 -242.539012)
		(width 0.09525)
		(layer "In2.Cu")
		(net "M_I_CPU0_SA_DQS_DP<8>")
	)
	(arc
		(start 390.546336 -242.539012)
		(mid 390.734804 -242.488335)
		(end 390.923272 -242.539012)
		(width 0.09525)
		(layer "In2.Cu")
		(net "M_I_CPU0_SA_DQS_DP<8>")
	)
	(arc
		(start 375.970038 -242.58016)
		(mid 376.21278 -242.61293)
		(end 376.446288 -242.539012)
		(width 0.09525)
		(layer "In2.Cu")
		(net "M_I_CPU0_SA_DQS_DP<8>")
	)
	(segment
		(start 375.22785 -238.270034)
		(end 375.694702 -238.004096)
		(width 0.12954)
		(layer "F.Cu")
		(net "M_I_CPU0_SA_DQS_DP<7>")
	)
	(segment
		(start 422.39692 -220.702886)
		(end 421.60444 -221.495366)
		(width 0.16002)
		(layer "In2.Cu")
		(net "M_I_CPU0_SA_DQS_DP<7>")
	)
	(segment
		(start 385.854702 -237.67415)
		(end 385.84632 -237.678976)
		(width 0.09525)
		(layer "In2.Cu")
		(net "M_I_CPU0_SA_DQS_DP<7>")
	)
	(segment
		(start 392.314938 -237.413038)
		(end 392.158728 -237.527846)
		(width 0.09525)
		(layer "In2.Cu")
		(net "M_I_CPU0_SA_DQS_DP<7>")
	)
	(segment
		(start 399.30578 -232.218992)
		(end 399.109184 -232.415588)
		(width 0.16002)
		(layer "In2.Cu")
		(net "M_I_CPU0_SA_DQS_DP<7>")
	)
	(segment
		(start 388.103364 -237.678976)
		(end 388.094982 -237.67415)
		(width 0.09525)
		(layer "In2.Cu")
		(net "M_I_CPU0_SA_DQS_DP<7>")
	)
	(segment
		(start 392.877802 -236.84992)
		(end 392.314938 -237.413038)
		(width 0.09525)
		(layer "In2.Cu")
		(net "M_I_CPU0_SA_DQS_DP<7>")
	)
	(segment
		(start 397.735552 -234.06608)
		(end 398.007586 -234.338114)
		(width 0.16002)
		(layer "In2.Cu")
		(net "M_I_CPU0_SA_DQS_DP<7>")
	)
	(segment
		(start 389.043418 -237.678976)
		(end 389.035036 -237.67415)
		(width 0.09525)
		(layer "In2.Cu")
		(net "M_I_CPU0_SA_DQS_DP<7>")
	)
	(segment
		(start 409.664662 -221.86011)
		(end 401.856448 -229.668324)
		(width 0.16002)
		(layer "In2.Cu")
		(net "M_I_CPU0_SA_DQS_DP<7>")
	)
	(segment
		(start 400.956272 -230.84536)
		(end 400.679412 -230.84536)
		(width 0.16002)
		(layer "In2.Cu")
		(net "M_I_CPU0_SA_DQS_DP<7>")
	)
	(segment
		(start 400.482816 -231.318816)
		(end 400.75485 -231.59085)
		(width 0.16002)
		(layer "In2.Cu")
		(net "M_I_CPU0_SA_DQS_DP<7>")
	)
	(segment
		(start 383.403348 -237.678976)
		(end 383.394966 -237.67415)
		(width 0.09525)
		(layer "In2.Cu")
		(net "M_I_CPU0_SA_DQS_DP<7>")
	)
	(segment
		(start 402.128482 -230.217218)
		(end 402.128482 -230.744522)
		(width 0.16002)
		(layer "In2.Cu")
		(net "M_I_CPU0_SA_DQS_DP<7>")
	)
	(segment
		(start 399.008346 -233.864658)
		(end 398.481042 -233.864658)
		(width 0.16002)
		(layer "In2.Cu")
		(net "M_I_CPU0_SA_DQS_DP<7>")
	)
	(segment
		(start 399.109184 -232.692448)
		(end 399.381218 -232.964482)
		(width 0.16002)
		(layer "In2.Cu")
		(net "M_I_CPU0_SA_DQS_DP<7>")
	)
	(segment
		(start 390.923526 -237.678976)
		(end 390.923272 -237.678976)
		(width 0.09525)
		(layer "In2.Cu")
		(net "M_I_CPU0_SA_DQS_DP<7>")
	)
	(segment
		(start 398.209008 -233.592624)
		(end 397.932148 -233.592624)
		(width 0.16002)
		(layer "In2.Cu")
		(net "M_I_CPU0_SA_DQS_DP<7>")
	)
	(segment
		(start 399.109184 -232.415588)
		(end 399.109184 -232.692448)
		(width 0.16002)
		(layer "In2.Cu")
		(net "M_I_CPU0_SA_DQS_DP<7>")
	)
	(segment
		(start 380.214632 -237.67415)
		(end 380.20625 -237.678976)
		(width 0.09525)
		(layer "In2.Cu")
		(net "M_I_CPU0_SA_DQS_DP<7>")
	)
	(segment
		(start 423.117264 -221.010226)
		(end 422.809924 -220.702886)
		(width 0.16002)
		(layer "In2.Cu")
		(net "M_I_CPU0_SA_DQS_DP<7>")
	)
	(segment
		(start 425.19092 -221.010226)
		(end 423.117264 -221.010226)
		(width 0.16002)
		(layer "In2.Cu")
		(net "M_I_CPU0_SA_DQS_DP<7>")
	)
	(segment
		(start 397.932148 -233.592624)
		(end 397.735552 -233.78922)
		(width 0.16002)
		(layer "In2.Cu")
		(net "M_I_CPU0_SA_DQS_DP<7>")
	)
	(segment
		(start 421.60444 -221.495366)
		(end 421.16756 -221.495366)
		(width 0.16002)
		(layer "In2.Cu")
		(net "M_I_CPU0_SA_DQS_DP<7>")
	)
	(segment
		(start 420.802816 -221.86011)
		(end 418.88664 -221.86011)
		(width 0.16002)
		(layer "In2.Cu")
		(net "M_I_CPU0_SA_DQS_DP<7>")
	)
	(segment
		(start 400.482816 -231.041956)
		(end 400.482816 -231.318816)
		(width 0.16002)
		(layer "In2.Cu")
		(net "M_I_CPU0_SA_DQS_DP<7>")
	)
	(segment
		(start 418.88664 -221.86011)
		(end 418.036756 -221.010226)
		(width 0.16002)
		(layer "In2.Cu")
		(net "M_I_CPU0_SA_DQS_DP<7>")
	)
	(segment
		(start 427.456092 -221.13494)
		(end 427.183042 -220.86189)
		(width 0.16002)
		(layer "In2.Cu")
		(net "M_I_CPU0_SA_DQS_DP<7>")
	)
	(segment
		(start 421.16756 -221.495366)
		(end 420.802816 -221.86011)
		(width 0.16002)
		(layer "In2.Cu")
		(net "M_I_CPU0_SA_DQS_DP<7>")
	)
	(segment
		(start 398.007586 -234.338114)
		(end 398.007586 -234.865418)
		(width 0.16002)
		(layer "In2.Cu")
		(net "M_I_CPU0_SA_DQS_DP<7>")
	)
	(segment
		(start 384.343402 -237.678976)
		(end 384.33502 -237.67415)
		(width 0.09525)
		(layer "In2.Cu")
		(net "M_I_CPU0_SA_DQS_DP<7>")
	)
	(segment
		(start 378.703332 -237.678976)
		(end 378.69495 -237.67415)
		(width 0.09525)
		(layer "In2.Cu")
		(net "M_I_CPU0_SA_DQS_DP<7>")
	)
	(segment
		(start 401.228306 -231.117394)
		(end 400.956272 -230.84536)
		(width 0.16002)
		(layer "In2.Cu")
		(net "M_I_CPU0_SA_DQS_DP<7>")
	)
	(segment
		(start 400.75485 -231.59085)
		(end 400.75485 -232.118154)
		(width 0.16002)
		(layer "In2.Cu")
		(net "M_I_CPU0_SA_DQS_DP<7>")
	)
	(segment
		(start 398.481042 -233.864658)
		(end 398.209008 -233.592624)
		(width 0.16002)
		(layer "In2.Cu")
		(net "M_I_CPU0_SA_DQS_DP<7>")
	)
	(segment
		(start 414.852866 -220.702886)
		(end 414.060386 -221.495366)
		(width 0.16002)
		(layer "In2.Cu")
		(net "M_I_CPU0_SA_DQS_DP<7>")
	)
	(segment
		(start 400.679412 -230.84536)
		(end 400.482816 -231.041956)
		(width 0.16002)
		(layer "In2.Cu")
		(net "M_I_CPU0_SA_DQS_DP<7>")
	)
	(segment
		(start 398.007586 -234.865418)
		(end 397.500094 -235.37291)
		(width 0.16002)
		(layer "In2.Cu")
		(net "M_I_CPU0_SA_DQS_DP<7>")
	)
	(segment
		(start 415.57321 -221.010226)
		(end 415.26587 -220.702886)
		(width 0.16002)
		(layer "In2.Cu")
		(net "M_I_CPU0_SA_DQS_DP<7>")
	)
	(segment
		(start 381.154686 -237.67415)
		(end 381.146304 -237.678976)
		(width 0.09525)
		(layer "In2.Cu")
		(net "M_I_CPU0_SA_DQS_DP<7>")
	)
	(segment
		(start 395.19352 -235.313982)
		(end 393.731242 -236.77626)
		(width 0.09525)
		(layer "In2.Cu")
		(net "M_I_CPU0_SA_DQS_DP<7>")
	)
	(segment
		(start 422.809924 -220.702886)
		(end 422.39692 -220.702886)
		(width 0.16002)
		(layer "In2.Cu")
		(net "M_I_CPU0_SA_DQS_DP<7>")
	)
	(segment
		(start 400.381978 -232.491026)
		(end 399.854674 -232.491026)
		(width 0.16002)
		(layer "In2.Cu")
		(net "M_I_CPU0_SA_DQS_DP<7>")
	)
	(segment
		(start 397.500094 -235.37291)
		(end 395.657324 -235.37291)
		(width 0.16002)
		(layer "In2.Cu")
		(net "M_I_CPU0_SA_DQS_DP<7>")
	)
	(segment
		(start 425.339256 -220.86189)
		(end 425.19092 -221.010226)
		(width 0.16002)
		(layer "In2.Cu")
		(net "M_I_CPU0_SA_DQS_DP<7>")
	)
	(segment
		(start 399.381218 -233.491786)
		(end 399.008346 -233.864658)
		(width 0.16002)
		(layer "In2.Cu")
		(net "M_I_CPU0_SA_DQS_DP<7>")
	)
	(segment
		(start 415.26587 -220.702886)
		(end 414.852866 -220.702886)
		(width 0.16002)
		(layer "In2.Cu")
		(net "M_I_CPU0_SA_DQS_DP<7>")
	)
	(segment
		(start 389.614664 -237.67415)
		(end 389.606282 -237.678976)
		(width 0.09525)
		(layer "In2.Cu")
		(net "M_I_CPU0_SA_DQS_DP<7>")
	)
	(segment
		(start 393.055348 -236.77626)
		(end 392.877802 -236.84992)
		(width 0.09525)
		(layer "In2.Cu")
		(net "M_I_CPU0_SA_DQS_DP<7>")
	)
	(segment
		(start 391.854182 -237.627668)
		(end 391.674858 -237.627668)
		(width 0.09525)
		(layer "In2.Cu")
		(net "M_I_CPU0_SA_DQS_DP<7>")
	)
	(segment
		(start 375.848626 -237.738666)
		(end 375.694702 -238.004096)
		(width 0.09525)
		(layer "In2.Cu")
		(net "M_I_CPU0_SA_DQS_DP<7>")
	)
	(segment
		(start 393.731242 -236.77626)
		(end 393.055348 -236.77626)
		(width 0.09525)
		(layer "In2.Cu")
		(net "M_I_CPU0_SA_DQS_DP<7>")
	)
	(segment
		(start 400.75485 -232.118154)
		(end 400.381978 -232.491026)
		(width 0.16002)
		(layer "In2.Cu")
		(net "M_I_CPU0_SA_DQS_DP<7>")
	)
	(segment
		(start 401.856448 -229.668324)
		(end 401.856448 -229.945184)
		(width 0.16002)
		(layer "In2.Cu")
		(net "M_I_CPU0_SA_DQS_DP<7>")
	)
	(segment
		(start 390.934194 -237.684818)
		(end 390.923526 -237.678976)
		(width 0.09525)
		(layer "In2.Cu")
		(net "M_I_CPU0_SA_DQS_DP<7>")
	)
	(segment
		(start 418.036756 -221.010226)
		(end 415.57321 -221.010226)
		(width 0.16002)
		(layer "In2.Cu")
		(net "M_I_CPU0_SA_DQS_DP<7>")
	)
	(segment
		(start 427.183042 -220.86189)
		(end 425.339256 -220.86189)
		(width 0.16002)
		(layer "In2.Cu")
		(net "M_I_CPU0_SA_DQS_DP<7>")
	)
	(segment
		(start 399.381218 -232.964482)
		(end 399.381218 -233.491786)
		(width 0.16002)
		(layer "In2.Cu")
		(net "M_I_CPU0_SA_DQS_DP<7>")
	)
	(segment
		(start 395.633702 -235.37291)
		(end 395.574774 -235.313982)
		(width 0.09525)
		(layer "In2.Cu")
		(net "M_I_CPU0_SA_DQS_DP<7>")
	)
	(segment
		(start 401.856448 -229.945184)
		(end 402.128482 -230.217218)
		(width 0.16002)
		(layer "In2.Cu")
		(net "M_I_CPU0_SA_DQS_DP<7>")
	)
	(segment
		(start 414.060386 -221.495366)
		(end 413.623506 -221.495366)
		(width 0.16002)
		(layer "In2.Cu")
		(net "M_I_CPU0_SA_DQS_DP<7>")
	)
	(segment
		(start 399.854674 -232.491026)
		(end 399.58264 -232.218992)
		(width 0.16002)
		(layer "In2.Cu")
		(net "M_I_CPU0_SA_DQS_DP<7>")
	)
	(segment
		(start 384.914648 -237.67415)
		(end 384.906266 -237.678976)
		(width 0.09525)
		(layer "In2.Cu")
		(net "M_I_CPU0_SA_DQS_DP<7>")
	)
	(segment
		(start 399.58264 -232.218992)
		(end 399.30578 -232.218992)
		(width 0.16002)
		(layer "In2.Cu")
		(net "M_I_CPU0_SA_DQS_DP<7>")
	)
	(segment
		(start 376.45467 -237.67415)
		(end 376.446288 -237.678976)
		(width 0.09525)
		(layer "In2.Cu")
		(net "M_I_CPU0_SA_DQS_DP<7>")
	)
	(segment
		(start 402.128482 -230.744522)
		(end 401.75561 -231.117394)
		(width 0.16002)
		(layer "In2.Cu")
		(net "M_I_CPU0_SA_DQS_DP<7>")
	)
	(segment
		(start 395.657324 -235.37291)
		(end 395.633702 -235.37291)
		(width 0.09525)
		(layer "In2.Cu")
		(net "M_I_CPU0_SA_DQS_DP<7>")
	)
	(segment
		(start 375.949464 -237.711996)
		(end 375.848626 -237.738666)
		(width 0.09525)
		(layer "In2.Cu")
		(net "M_I_CPU0_SA_DQS_DP<7>")
	)
	(segment
		(start 401.75561 -231.117394)
		(end 401.228306 -231.117394)
		(width 0.16002)
		(layer "In2.Cu")
		(net "M_I_CPU0_SA_DQS_DP<7>")
	)
	(segment
		(start 379.643386 -237.678976)
		(end 379.635004 -237.67415)
		(width 0.09525)
		(layer "In2.Cu")
		(net "M_I_CPU0_SA_DQS_DP<7>")
	)
	(segment
		(start 397.735552 -233.78922)
		(end 397.735552 -234.06608)
		(width 0.16002)
		(layer "In2.Cu")
		(net "M_I_CPU0_SA_DQS_DP<7>")
	)
	(segment
		(start 395.574774 -235.313982)
		(end 395.19352 -235.313982)
		(width 0.09525)
		(layer "In2.Cu")
		(net "M_I_CPU0_SA_DQS_DP<7>")
	)
	(segment
		(start 413.623506 -221.495366)
		(end 413.258762 -221.86011)
		(width 0.16002)
		(layer "In2.Cu")
		(net "M_I_CPU0_SA_DQS_DP<7>")
	)
	(segment
		(start 413.258762 -221.86011)
		(end 409.664662 -221.86011)
		(width 0.16002)
		(layer "In2.Cu")
		(net "M_I_CPU0_SA_DQS_DP<7>")
	)
	(arc
		(start 381.146304 -237.678976)
		(mid 380.864872 -237.754731)
		(end 380.58344 -237.678976)
		(width 0.09525)
		(layer "In2.Cu")
		(net "M_I_CPU0_SA_DQS_DP<7>")
	)
	(arc
		(start 383.966212 -237.678976)
		(mid 383.68478 -237.754731)
		(end 383.403348 -237.678976)
		(width 0.09525)
		(layer "In2.Cu")
		(net "M_I_CPU0_SA_DQS_DP<7>")
	)
	(arc
		(start 382.086358 -237.678976)
		(mid 381.804926 -237.754731)
		(end 381.523494 -237.678976)
		(width 0.09525)
		(layer "In2.Cu")
		(net "M_I_CPU0_SA_DQS_DP<7>")
	)
	(arc
		(start 384.33502 -237.67415)
		(mid 384.149988 -237.628236)
		(end 383.966212 -237.678976)
		(width 0.09525)
		(layer "In2.Cu")
		(net "M_I_CPU0_SA_DQS_DP<7>")
	)
	(arc
		(start 385.84632 -237.678976)
		(mid 385.564888 -237.754731)
		(end 385.283456 -237.678976)
		(width 0.09525)
		(layer "In2.Cu")
		(net "M_I_CPU0_SA_DQS_DP<7>")
	)
	(arc
		(start 377.386342 -237.678976)
		(mid 377.10491 -237.754731)
		(end 376.823478 -237.678976)
		(width 0.09525)
		(layer "In2.Cu")
		(net "M_I_CPU0_SA_DQS_DP<7>")
	)
	(arc
		(start 387.726174 -237.678976)
		(mid 387.444742 -237.754731)
		(end 387.16331 -237.678976)
		(width 0.09525)
		(layer "In2.Cu")
		(net "M_I_CPU0_SA_DQS_DP<7>")
	)
	(arc
		(start 390.546336 -237.678976)
		(mid 390.264904 -237.754731)
		(end 389.983472 -237.678976)
		(width 0.09525)
		(layer "In2.Cu")
		(net "M_I_CPU0_SA_DQS_DP<7>")
	)
	(arc
		(start 383.026158 -237.678976)
		(mid 382.744726 -237.754731)
		(end 382.463294 -237.678976)
		(width 0.09525)
		(layer "In2.Cu")
		(net "M_I_CPU0_SA_DQS_DP<7>")
	)
	(arc
		(start 380.20625 -237.678976)
		(mid 379.924818 -237.754731)
		(end 379.643386 -237.678976)
		(width 0.09525)
		(layer "In2.Cu")
		(net "M_I_CPU0_SA_DQS_DP<7>")
	)
	(arc
		(start 386.786374 -237.678976)
		(mid 386.504942 -237.754731)
		(end 386.22351 -237.678976)
		(width 0.09525)
		(layer "In2.Cu")
		(net "M_I_CPU0_SA_DQS_DP<7>")
	)
	(arc
		(start 388.094982 -237.67415)
		(mid 387.90995 -237.628236)
		(end 387.726174 -237.678976)
		(width 0.09525)
		(layer "In2.Cu")
		(net "M_I_CPU0_SA_DQS_DP<7>")
	)
	(arc
		(start 387.16331 -237.678976)
		(mid 386.974842 -237.628299)
		(end 386.786374 -237.678976)
		(width 0.09525)
		(layer "In2.Cu")
		(net "M_I_CPU0_SA_DQS_DP<7>")
	)
	(arc
		(start 376.446288 -237.678976)
		(mid 376.212774 -237.752819)
		(end 375.970038 -237.720124)
		(width 0.09525)
		(layer "In2.Cu")
		(net "M_I_CPU0_SA_DQS_DP<7>")
	)
	(arc
		(start 382.463294 -237.678976)
		(mid 382.274826 -237.628299)
		(end 382.086358 -237.678976)
		(width 0.09525)
		(layer "In2.Cu")
		(net "M_I_CPU0_SA_DQS_DP<7>")
	)
	(arc
		(start 379.635004 -237.67415)
		(mid 379.449972 -237.628236)
		(end 379.266196 -237.678976)
		(width 0.09525)
		(layer "In2.Cu")
		(net "M_I_CPU0_SA_DQS_DP<7>")
	)
	(arc
		(start 378.326142 -237.678976)
		(mid 378.04471 -237.754731)
		(end 377.763278 -237.678976)
		(width 0.09525)
		(layer "In2.Cu")
		(net "M_I_CPU0_SA_DQS_DP<7>")
	)
	(arc
		(start 376.823478 -237.678976)
		(mid 376.639703 -237.628204)
		(end 376.45467 -237.67415)
		(width 0.09525)
		(layer "In2.Cu")
		(net "M_I_CPU0_SA_DQS_DP<7>")
	)
	(arc
		(start 389.983472 -237.678976)
		(mid 389.799697 -237.628204)
		(end 389.614664 -237.67415)
		(width 0.09525)
		(layer "In2.Cu")
		(net "M_I_CPU0_SA_DQS_DP<7>")
	)
	(arc
		(start 380.58344 -237.678976)
		(mid 380.399665 -237.628204)
		(end 380.214632 -237.67415)
		(width 0.09525)
		(layer "In2.Cu")
		(net "M_I_CPU0_SA_DQS_DP<7>")
	)
	(arc
		(start 386.22351 -237.678976)
		(mid 386.039735 -237.628204)
		(end 385.854702 -237.67415)
		(width 0.09525)
		(layer "In2.Cu")
		(net "M_I_CPU0_SA_DQS_DP<7>")
	)
	(arc
		(start 381.523494 -237.678976)
		(mid 381.339719 -237.628204)
		(end 381.154686 -237.67415)
		(width 0.09525)
		(layer "In2.Cu")
		(net "M_I_CPU0_SA_DQS_DP<7>")
	)
	(arc
		(start 379.266196 -237.678976)
		(mid 378.984764 -237.754731)
		(end 378.703332 -237.678976)
		(width 0.09525)
		(layer "In2.Cu")
		(net "M_I_CPU0_SA_DQS_DP<7>")
	)
	(arc
		(start 383.394966 -237.67415)
		(mid 383.209934 -237.628236)
		(end 383.026158 -237.678976)
		(width 0.09525)
		(layer "In2.Cu")
		(net "M_I_CPU0_SA_DQS_DP<7>")
	)
	(arc
		(start 384.906266 -237.678976)
		(mid 384.624834 -237.754731)
		(end 384.343402 -237.678976)
		(width 0.09525)
		(layer "In2.Cu")
		(net "M_I_CPU0_SA_DQS_DP<7>")
	)
	(arc
		(start 378.69495 -237.67415)
		(mid 378.509918 -237.628236)
		(end 378.326142 -237.678976)
		(width 0.09525)
		(layer "In2.Cu")
		(net "M_I_CPU0_SA_DQS_DP<7>")
	)
	(arc
		(start 389.035036 -237.67415)
		(mid 388.850004 -237.628236)
		(end 388.666228 -237.678976)
		(width 0.09525)
		(layer "In2.Cu")
		(net "M_I_CPU0_SA_DQS_DP<7>")
	)
	(arc
		(start 392.158728 -237.527846)
		(mid 392.014447 -237.602132)
		(end 391.854182 -237.627668)
		(width 0.09525)
		(layer "In2.Cu")
		(net "M_I_CPU0_SA_DQS_DP<7>")
	)
	(arc
		(start 391.485882 -237.678722)
		(mid 391.210847 -237.75435)
		(end 390.934194 -237.684818)
		(width 0.09525)
		(layer "In2.Cu")
		(net "M_I_CPU0_SA_DQS_DP<7>")
	)
	(arc
		(start 389.606282 -237.678976)
		(mid 389.32485 -237.754731)
		(end 389.043418 -237.678976)
		(width 0.09525)
		(layer "In2.Cu")
		(net "M_I_CPU0_SA_DQS_DP<7>")
	)
	(arc
		(start 391.674858 -237.627668)
		(mid 391.576988 -237.640682)
		(end 391.485882 -237.678722)
		(width 0.09525)
		(layer "In2.Cu")
		(net "M_I_CPU0_SA_DQS_DP<7>")
	)
	(arc
		(start 377.763278 -237.678976)
		(mid 377.57481 -237.628299)
		(end 377.386342 -237.678976)
		(width 0.09525)
		(layer "In2.Cu")
		(net "M_I_CPU0_SA_DQS_DP<7>")
	)
	(arc
		(start 390.923272 -237.678976)
		(mid 390.734804 -237.628299)
		(end 390.546336 -237.678976)
		(width 0.09525)
		(layer "In2.Cu")
		(net "M_I_CPU0_SA_DQS_DP<7>")
	)
	(arc
		(start 375.970038 -237.720124)
		(mid 375.95971 -237.716164)
		(end 375.949464 -237.711996)
		(width 0.09525)
		(layer "In2.Cu")
		(net "M_I_CPU0_SA_DQS_DP<7>")
	)
	(arc
		(start 385.283456 -237.678976)
		(mid 385.099681 -237.628204)
		(end 384.914648 -237.67415)
		(width 0.09525)
		(layer "In2.Cu")
		(net "M_I_CPU0_SA_DQS_DP<7>")
	)
	(arc
		(start 388.666228 -237.678976)
		(mid 388.384796 -237.754731)
		(end 388.103364 -237.678976)
		(width 0.09525)
		(layer "In2.Cu")
		(net "M_I_CPU0_SA_DQS_DP<7>")
	)
	(segment
		(start 375.22785 -233.409998)
		(end 375.694702 -233.14406)
		(width 0.12954)
		(layer "F.Cu")
		(net "M_I_CPU0_SA_DQS_DP<6>")
	)
	(segment
		(start 375.694702 -233.14406)
		(end 375.848626 -232.87863)
		(width 0.09525)
		(layer "In2.Cu")
		(net "M_I_CPU0_SA_DQS_DP<6>")
	)
	(segment
		(start 405.149812 -216.576148)
		(end 405.149812 -216.048844)
		(width 0.16002)
		(layer "In2.Cu")
		(net "M_I_CPU0_SA_DQS_DP<6>")
	)
	(segment
		(start 393.988798 -228.616764)
		(end 393.988544 -228.616764)
		(width 0.09525)
		(layer "In2.Cu")
		(net "M_I_CPU0_SA_DQS_DP<6>")
	)
	(segment
		(start 405.279606 -215.231726)
		(end 405.623268 -215.575388)
		(width 0.16002)
		(layer "In2.Cu")
		(net "M_I_CPU0_SA_DQS_DP<6>")
	)
	(segment
		(start 407.75001 -212.484462)
		(end 408.02687 -212.484462)
		(width 0.16002)
		(layer "In2.Cu")
		(net "M_I_CPU0_SA_DQS_DP<6>")
	)
	(segment
		(start 408.370532 -212.828124)
		(end 408.897836 -212.828124)
		(width 0.16002)
		(layer "In2.Cu")
		(net "M_I_CPU0_SA_DQS_DP<6>")
	)
	(segment
		(start 425.339256 -211.511896)
		(end 427.183042 -211.511896)
		(width 0.16002)
		(layer "In2.Cu")
		(net "M_I_CPU0_SA_DQS_DP<6>")
	)
	(segment
		(start 389.035036 -232.814114)
		(end 389.043418 -232.81894)
		(width 0.09525)
		(layer "In2.Cu")
		(net "M_I_CPU0_SA_DQS_DP<6>")
	)
	(segment
		(start 406.9969 -214.201756)
		(end 407.524204 -214.201756)
		(width 0.16002)
		(layer "In2.Cu")
		(net "M_I_CPU0_SA_DQS_DP<6>")
	)
	(segment
		(start 423.117264 -211.660232)
		(end 425.19092 -211.660232)
		(width 0.16002)
		(layer "In2.Cu")
		(net "M_I_CPU0_SA_DQS_DP<6>")
	)
	(segment
		(start 418.88664 -212.510116)
		(end 420.802816 -212.510116)
		(width 0.16002)
		(layer "In2.Cu")
		(net "M_I_CPU0_SA_DQS_DP<6>")
	)
	(segment
		(start 418.036756 -211.660232)
		(end 418.88664 -212.510116)
		(width 0.16002)
		(layer "In2.Cu")
		(net "M_I_CPU0_SA_DQS_DP<6>")
	)
	(segment
		(start 415.26587 -211.352892)
		(end 415.57321 -211.660232)
		(width 0.16002)
		(layer "In2.Cu")
		(net "M_I_CPU0_SA_DQS_DP<6>")
	)
	(segment
		(start 407.897076 -213.30158)
		(end 407.553414 -212.957918)
		(width 0.16002)
		(layer "In2.Cu")
		(net "M_I_CPU0_SA_DQS_DP<6>")
	)
	(segment
		(start 391.95629 -232.008934)
		(end 391.99439 -231.986836)
		(width 0.09525)
		(layer "In2.Cu")
		(net "M_I_CPU0_SA_DQS_DP<6>")
	)
	(segment
		(start 405.623268 -215.575388)
		(end 406.150572 -215.575388)
		(width 0.16002)
		(layer "In2.Cu")
		(net "M_I_CPU0_SA_DQS_DP<6>")
	)
	(segment
		(start 407.553414 -212.681058)
		(end 407.75001 -212.484462)
		(width 0.16002)
		(layer "In2.Cu")
		(net "M_I_CPU0_SA_DQS_DP<6>")
	)
	(segment
		(start 394.381482 -227.926392)
		(end 394.483844 -227.82403)
		(width 0.09525)
		(layer "In2.Cu")
		(net "M_I_CPU0_SA_DQS_DP<6>")
	)
	(segment
		(start 389.606282 -232.81894)
		(end 389.614664 -232.814114)
		(width 0.09525)
		(layer "In2.Cu")
		(net "M_I_CPU0_SA_DQS_DP<6>")
	)
	(segment
		(start 394.282422 -227.926392)
		(end 394.381482 -227.926392)
		(width 0.09525)
		(layer "In2.Cu")
		(net "M_I_CPU0_SA_DQS_DP<6>")
	)
	(segment
		(start 392.896344 -230.389176)
		(end 392.931904 -230.368602)
		(width 0.09525)
		(layer "In2.Cu")
		(net "M_I_CPU0_SA_DQS_DP<6>")
	)
	(segment
		(start 388.094982 -232.814114)
		(end 388.103364 -232.81894)
		(width 0.09525)
		(layer "In2.Cu")
		(net "M_I_CPU0_SA_DQS_DP<6>")
	)
	(segment
		(start 406.653238 -213.858094)
		(end 406.9969 -214.201756)
		(width 0.16002)
		(layer "In2.Cu")
		(net "M_I_CPU0_SA_DQS_DP<6>")
	)
	(segment
		(start 422.809924 -211.352892)
		(end 423.117264 -211.660232)
		(width 0.16002)
		(layer "In2.Cu")
		(net "M_I_CPU0_SA_DQS_DP<6>")
	)
	(segment
		(start 407.524204 -214.201756)
		(end 407.897076 -213.828884)
		(width 0.16002)
		(layer "In2.Cu")
		(net "M_I_CPU0_SA_DQS_DP<6>")
	)
	(segment
		(start 405.149812 -216.048844)
		(end 404.80615 -215.705182)
		(width 0.16002)
		(layer "In2.Cu")
		(net "M_I_CPU0_SA_DQS_DP<6>")
	)
	(segment
		(start 404.80615 -215.705182)
		(end 404.80615 -215.428322)
		(width 0.16002)
		(layer "In2.Cu")
		(net "M_I_CPU0_SA_DQS_DP<6>")
	)
	(segment
		(start 406.179782 -214.33155)
		(end 406.179782 -214.05469)
		(width 0.16002)
		(layer "In2.Cu")
		(net "M_I_CPU0_SA_DQS_DP<6>")
	)
	(segment
		(start 391.486136 -232.81894)
		(end 391.524236 -232.796842)
		(width 0.09525)
		(layer "In2.Cu")
		(net "M_I_CPU0_SA_DQS_DP<6>")
	)
	(segment
		(start 406.179782 -214.05469)
		(end 406.376378 -213.858094)
		(width 0.16002)
		(layer "In2.Cu")
		(net "M_I_CPU0_SA_DQS_DP<6>")
	)
	(segment
		(start 394.111988 -228.49332)
		(end 394.111988 -228.096826)
		(width 0.09525)
		(layer "In2.Cu")
		(net "M_I_CPU0_SA_DQS_DP<6>")
	)
	(segment
		(start 427.183042 -211.511896)
		(end 427.456092 -211.784946)
		(width 0.16002)
		(layer "In2.Cu")
		(net "M_I_CPU0_SA_DQS_DP<6>")
	)
	(segment
		(start 422.39692 -211.352892)
		(end 422.809924 -211.352892)
		(width 0.16002)
		(layer "In2.Cu")
		(net "M_I_CPU0_SA_DQS_DP<6>")
	)
	(segment
		(start 406.523444 -214.675212)
		(end 406.179782 -214.33155)
		(width 0.16002)
		(layer "In2.Cu")
		(net "M_I_CPU0_SA_DQS_DP<6>")
	)
	(segment
		(start 396.406878 -225.319082)
		(end 405.149812 -216.576148)
		(width 0.16002)
		(layer "In2.Cu")
		(net "M_I_CPU0_SA_DQS_DP<6>")
	)
	(segment
		(start 394.583666 -227.807266)
		(end 396.406878 -225.984054)
		(width 0.16002)
		(layer "In2.Cu")
		(net "M_I_CPU0_SA_DQS_DP<6>")
	)
	(segment
		(start 384.906266 -232.81894)
		(end 384.914648 -232.814114)
		(width 0.09525)
		(layer "In2.Cu")
		(net "M_I_CPU0_SA_DQS_DP<6>")
	)
	(segment
		(start 393.803886 -228.78796)
		(end 393.824206 -228.775768)
		(width 0.09525)
		(layer "In2.Cu")
		(net "M_I_CPU0_SA_DQS_DP<6>")
	)
	(segment
		(start 421.16756 -212.145372)
		(end 421.60444 -212.145372)
		(width 0.16002)
		(layer "In2.Cu")
		(net "M_I_CPU0_SA_DQS_DP<6>")
	)
	(segment
		(start 413.258762 -212.510116)
		(end 413.623506 -212.145372)
		(width 0.16002)
		(layer "In2.Cu")
		(net "M_I_CPU0_SA_DQS_DP<6>")
	)
	(segment
		(start 378.69495 -232.814114)
		(end 378.703332 -232.81894)
		(width 0.09525)
		(layer "In2.Cu")
		(net "M_I_CPU0_SA_DQS_DP<6>")
	)
	(segment
		(start 392.394694 -231.217216)
		(end 392.42619 -231.198928)
		(width 0.09525)
		(layer "In2.Cu")
		(net "M_I_CPU0_SA_DQS_DP<6>")
	)
	(segment
		(start 393.334748 -229.597204)
		(end 393.366244 -229.578916)
		(width 0.09525)
		(layer "In2.Cu")
		(net "M_I_CPU0_SA_DQS_DP<6>")
	)
	(segment
		(start 421.60444 -212.145372)
		(end 422.39692 -211.352892)
		(width 0.16002)
		(layer "In2.Cu")
		(net "M_I_CPU0_SA_DQS_DP<6>")
	)
	(segment
		(start 406.523444 -215.202516)
		(end 406.523444 -214.675212)
		(width 0.16002)
		(layer "In2.Cu")
		(net "M_I_CPU0_SA_DQS_DP<6>")
	)
	(segment
		(start 384.33502 -232.814114)
		(end 384.343402 -232.81894)
		(width 0.09525)
		(layer "In2.Cu")
		(net "M_I_CPU0_SA_DQS_DP<6>")
	)
	(segment
		(start 409.215844 -212.510116)
		(end 413.258762 -212.510116)
		(width 0.16002)
		(layer "In2.Cu")
		(net "M_I_CPU0_SA_DQS_DP<6>")
	)
	(segment
		(start 380.20625 -232.81894)
		(end 380.214632 -232.814114)
		(width 0.09525)
		(layer "In2.Cu")
		(net "M_I_CPU0_SA_DQS_DP<6>")
	)
	(segment
		(start 392.863832 -230.407972)
		(end 392.896344 -230.389176)
		(width 0.09525)
		(layer "In2.Cu")
		(net "M_I_CPU0_SA_DQS_DP<6>")
	)
	(segment
		(start 420.802816 -212.510116)
		(end 421.16756 -212.145372)
		(width 0.16002)
		(layer "In2.Cu")
		(net "M_I_CPU0_SA_DQS_DP<6>")
	)
	(segment
		(start 393.988544 -228.616764)
		(end 394.111988 -228.49332)
		(width 0.09525)
		(layer "In2.Cu")
		(net "M_I_CPU0_SA_DQS_DP<6>")
	)
	(segment
		(start 394.483844 -227.82403)
		(end 394.566902 -227.82403)
		(width 0.09525)
		(layer "In2.Cu")
		(net "M_I_CPU0_SA_DQS_DP<6>")
	)
	(segment
		(start 415.57321 -211.660232)
		(end 418.036756 -211.660232)
		(width 0.16002)
		(layer "In2.Cu")
		(net "M_I_CPU0_SA_DQS_DP<6>")
	)
	(segment
		(start 381.146304 -232.81894)
		(end 381.154686 -232.814114)
		(width 0.09525)
		(layer "In2.Cu")
		(net "M_I_CPU0_SA_DQS_DP<6>")
	)
	(segment
		(start 394.566902 -227.82403)
		(end 394.583666 -227.807266)
		(width 0.09525)
		(layer "In2.Cu")
		(net "M_I_CPU0_SA_DQS_DP<6>")
	)
	(segment
		(start 385.84632 -232.81894)
		(end 385.854702 -232.814114)
		(width 0.09525)
		(layer "In2.Cu")
		(net "M_I_CPU0_SA_DQS_DP<6>")
	)
	(segment
		(start 406.150572 -215.575388)
		(end 406.523444 -215.202516)
		(width 0.16002)
		(layer "In2.Cu")
		(net "M_I_CPU0_SA_DQS_DP<6>")
	)
	(segment
		(start 394.111988 -228.096826)
		(end 394.282422 -227.926392)
		(width 0.09525)
		(layer "In2.Cu")
		(net "M_I_CPU0_SA_DQS_DP<6>")
	)
	(segment
		(start 425.19092 -211.660232)
		(end 425.339256 -211.511896)
		(width 0.16002)
		(layer "In2.Cu")
		(net "M_I_CPU0_SA_DQS_DP<6>")
	)
	(segment
		(start 408.897836 -212.828124)
		(end 409.215844 -212.510116)
		(width 0.16002)
		(layer "In2.Cu")
		(net "M_I_CPU0_SA_DQS_DP<6>")
	)
	(segment
		(start 407.553414 -212.957918)
		(end 407.553414 -212.681058)
		(width 0.16002)
		(layer "In2.Cu")
		(net "M_I_CPU0_SA_DQS_DP<6>")
	)
	(segment
		(start 393.824206 -228.775768)
		(end 393.83716 -228.768402)
		(width 0.09525)
		(layer "In2.Cu")
		(net "M_I_CPU0_SA_DQS_DP<6>")
	)
	(segment
		(start 393.366244 -229.578916)
		(end 393.40663 -229.555294)
		(width 0.09525)
		(layer "In2.Cu")
		(net "M_I_CPU0_SA_DQS_DP<6>")
	)
	(segment
		(start 414.852866 -211.352892)
		(end 415.26587 -211.352892)
		(width 0.16002)
		(layer "In2.Cu")
		(net "M_I_CPU0_SA_DQS_DP<6>")
	)
	(segment
		(start 413.623506 -212.145372)
		(end 414.060386 -212.145372)
		(width 0.16002)
		(layer "In2.Cu")
		(net "M_I_CPU0_SA_DQS_DP<6>")
	)
	(segment
		(start 396.406878 -225.984054)
		(end 396.406878 -225.319082)
		(width 0.16002)
		(layer "In2.Cu")
		(net "M_I_CPU0_SA_DQS_DP<6>")
	)
	(segment
		(start 393.83716 -228.768402)
		(end 393.988798 -228.616764)
		(width 0.09525)
		(layer "In2.Cu")
		(net "M_I_CPU0_SA_DQS_DP<6>")
	)
	(segment
		(start 383.394966 -232.814114)
		(end 383.403348 -232.81894)
		(width 0.09525)
		(layer "In2.Cu")
		(net "M_I_CPU0_SA_DQS_DP<6>")
	)
	(segment
		(start 391.923778 -232.02773)
		(end 391.95629 -232.008934)
		(width 0.09525)
		(layer "In2.Cu")
		(net "M_I_CPU0_SA_DQS_DP<6>")
	)
	(segment
		(start 392.42619 -231.198928)
		(end 392.466576 -231.175306)
		(width 0.09525)
		(layer "In2.Cu")
		(net "M_I_CPU0_SA_DQS_DP<6>")
	)
	(segment
		(start 375.848626 -232.87863)
		(end 375.949464 -232.85196)
		(width 0.09525)
		(layer "In2.Cu")
		(net "M_I_CPU0_SA_DQS_DP<6>")
	)
	(segment
		(start 376.446288 -232.81894)
		(end 376.45467 -232.814114)
		(width 0.09525)
		(layer "In2.Cu")
		(net "M_I_CPU0_SA_DQS_DP<6>")
	)
	(segment
		(start 404.80615 -215.428322)
		(end 405.002746 -215.231726)
		(width 0.16002)
		(layer "In2.Cu")
		(net "M_I_CPU0_SA_DQS_DP<6>")
	)
	(segment
		(start 414.060386 -212.145372)
		(end 414.852866 -211.352892)
		(width 0.16002)
		(layer "In2.Cu")
		(net "M_I_CPU0_SA_DQS_DP<6>")
	)
	(segment
		(start 407.897076 -213.828884)
		(end 407.897076 -213.30158)
		(width 0.16002)
		(layer "In2.Cu")
		(net "M_I_CPU0_SA_DQS_DP<6>")
	)
	(segment
		(start 408.02687 -212.484462)
		(end 408.370532 -212.828124)
		(width 0.16002)
		(layer "In2.Cu")
		(net "M_I_CPU0_SA_DQS_DP<6>")
	)
	(segment
		(start 379.635004 -232.814114)
		(end 379.643386 -232.81894)
		(width 0.09525)
		(layer "In2.Cu")
		(net "M_I_CPU0_SA_DQS_DP<6>")
	)
	(segment
		(start 406.376378 -213.858094)
		(end 406.653238 -213.858094)
		(width 0.16002)
		(layer "In2.Cu")
		(net "M_I_CPU0_SA_DQS_DP<6>")
	)
	(segment
		(start 405.002746 -215.231726)
		(end 405.279606 -215.231726)
		(width 0.16002)
		(layer "In2.Cu")
		(net "M_I_CPU0_SA_DQS_DP<6>")
	)
	(arc
		(start 379.266196 -232.81894)
		(mid 379.449971 -232.768168)
		(end 379.635004 -232.814114)
		(width 0.09525)
		(layer "In2.Cu")
		(net "M_I_CPU0_SA_DQS_DP<6>")
	)
	(arc
		(start 387.726174 -232.81894)
		(mid 387.909949 -232.768168)
		(end 388.094982 -232.814114)
		(width 0.09525)
		(layer "In2.Cu")
		(net "M_I_CPU0_SA_DQS_DP<6>")
	)
	(arc
		(start 380.214632 -232.814114)
		(mid 380.399664 -232.7682)
		(end 380.58344 -232.81894)
		(width 0.09525)
		(layer "In2.Cu")
		(net "M_I_CPU0_SA_DQS_DP<6>")
	)
	(arc
		(start 389.043418 -232.81894)
		(mid 389.32485 -232.894695)
		(end 389.606282 -232.81894)
		(width 0.09525)
		(layer "In2.Cu")
		(net "M_I_CPU0_SA_DQS_DP<6>")
	)
	(arc
		(start 375.949464 -232.85196)
		(mid 375.959712 -232.856123)
		(end 375.970038 -232.860088)
		(width 0.09525)
		(layer "In2.Cu")
		(net "M_I_CPU0_SA_DQS_DP<6>")
	)
	(arc
		(start 378.703332 -232.81894)
		(mid 378.984764 -232.894695)
		(end 379.266196 -232.81894)
		(width 0.09525)
		(layer "In2.Cu")
		(net "M_I_CPU0_SA_DQS_DP<6>")
	)
	(arc
		(start 389.614664 -232.814114)
		(mid 389.799696 -232.7682)
		(end 389.983472 -232.81894)
		(width 0.09525)
		(layer "In2.Cu")
		(net "M_I_CPU0_SA_DQS_DP<6>")
	)
	(arc
		(start 383.403348 -232.81894)
		(mid 383.68478 -232.894695)
		(end 383.966212 -232.81894)
		(width 0.09525)
		(layer "In2.Cu")
		(net "M_I_CPU0_SA_DQS_DP<6>")
	)
	(arc
		(start 381.523494 -232.81894)
		(mid 381.804926 -232.894695)
		(end 382.086358 -232.81894)
		(width 0.09525)
		(layer "In2.Cu")
		(net "M_I_CPU0_SA_DQS_DP<6>")
	)
	(arc
		(start 392.466576 -231.175306)
		(mid 392.643348 -230.974285)
		(end 392.707114 -230.714296)
		(width 0.09525)
		(layer "In2.Cu")
		(net "M_I_CPU0_SA_DQS_DP<6>")
	)
	(arc
		(start 390.923272 -232.81894)
		(mid 391.204704 -232.894695)
		(end 391.486136 -232.81894)
		(width 0.09525)
		(layer "In2.Cu")
		(net "M_I_CPU0_SA_DQS_DP<6>")
	)
	(arc
		(start 384.343402 -232.81894)
		(mid 384.624834 -232.894695)
		(end 384.906266 -232.81894)
		(width 0.09525)
		(layer "In2.Cu")
		(net "M_I_CPU0_SA_DQS_DP<6>")
	)
	(arc
		(start 381.154686 -232.814114)
		(mid 381.339718 -232.7682)
		(end 381.523494 -232.81894)
		(width 0.09525)
		(layer "In2.Cu")
		(net "M_I_CPU0_SA_DQS_DP<6>")
	)
	(arc
		(start 382.086358 -232.81894)
		(mid 382.274826 -232.768263)
		(end 382.463294 -232.81894)
		(width 0.09525)
		(layer "In2.Cu")
		(net "M_I_CPU0_SA_DQS_DP<6>")
	)
	(arc
		(start 377.763278 -232.81894)
		(mid 378.04471 -232.894695)
		(end 378.326142 -232.81894)
		(width 0.09525)
		(layer "In2.Cu")
		(net "M_I_CPU0_SA_DQS_DP<6>")
	)
	(arc
		(start 386.786374 -232.81894)
		(mid 386.974842 -232.768263)
		(end 387.16331 -232.81894)
		(width 0.09525)
		(layer "In2.Cu")
		(net "M_I_CPU0_SA_DQS_DP<6>")
	)
	(arc
		(start 392.707114 -230.714296)
		(mid 392.748571 -230.542256)
		(end 392.863832 -230.407972)
		(width 0.09525)
		(layer "In2.Cu")
		(net "M_I_CPU0_SA_DQS_DP<6>")
	)
	(arc
		(start 387.16331 -232.81894)
		(mid 387.444742 -232.894695)
		(end 387.726174 -232.81894)
		(width 0.09525)
		(layer "In2.Cu")
		(net "M_I_CPU0_SA_DQS_DP<6>")
	)
	(arc
		(start 383.966212 -232.81894)
		(mid 384.149987 -232.768168)
		(end 384.33502 -232.814114)
		(width 0.09525)
		(layer "In2.Cu")
		(net "M_I_CPU0_SA_DQS_DP<6>")
	)
	(arc
		(start 391.524236 -232.796842)
		(mid 391.702686 -232.595372)
		(end 391.76706 -232.334054)
		(width 0.09525)
		(layer "In2.Cu")
		(net "M_I_CPU0_SA_DQS_DP<6>")
	)
	(arc
		(start 390.546336 -232.81894)
		(mid 390.734804 -232.768263)
		(end 390.923272 -232.81894)
		(width 0.09525)
		(layer "In2.Cu")
		(net "M_I_CPU0_SA_DQS_DP<6>")
	)
	(arc
		(start 386.22351 -232.81894)
		(mid 386.504942 -232.894695)
		(end 386.786374 -232.81894)
		(width 0.09525)
		(layer "In2.Cu")
		(net "M_I_CPU0_SA_DQS_DP<6>")
	)
	(arc
		(start 392.931904 -230.368602)
		(mid 393.112197 -230.166739)
		(end 393.177268 -229.904036)
		(width 0.09525)
		(layer "In2.Cu")
		(net "M_I_CPU0_SA_DQS_DP<6>")
	)
	(arc
		(start 380.58344 -232.81894)
		(mid 380.864872 -232.894695)
		(end 381.146304 -232.81894)
		(width 0.09525)
		(layer "In2.Cu")
		(net "M_I_CPU0_SA_DQS_DP<6>")
	)
	(arc
		(start 392.237214 -231.524048)
		(mid 392.278879 -231.351601)
		(end 392.394694 -231.217216)
		(width 0.09525)
		(layer "In2.Cu")
		(net "M_I_CPU0_SA_DQS_DP<6>")
	)
	(arc
		(start 385.283456 -232.81894)
		(mid 385.564888 -232.894695)
		(end 385.84632 -232.81894)
		(width 0.09525)
		(layer "In2.Cu")
		(net "M_I_CPU0_SA_DQS_DP<6>")
	)
	(arc
		(start 376.45467 -232.814114)
		(mid 376.639702 -232.7682)
		(end 376.823478 -232.81894)
		(width 0.09525)
		(layer "In2.Cu")
		(net "M_I_CPU0_SA_DQS_DP<6>")
	)
	(arc
		(start 393.647168 -229.094284)
		(mid 393.688625 -228.922244)
		(end 393.803886 -228.78796)
		(width 0.09525)
		(layer "In2.Cu")
		(net "M_I_CPU0_SA_DQS_DP<6>")
	)
	(arc
		(start 393.177268 -229.904036)
		(mid 393.218933 -229.731589)
		(end 393.334748 -229.597204)
		(width 0.09525)
		(layer "In2.Cu")
		(net "M_I_CPU0_SA_DQS_DP<6>")
	)
	(arc
		(start 377.386342 -232.81894)
		(mid 377.57481 -232.768263)
		(end 377.763278 -232.81894)
		(width 0.09525)
		(layer "In2.Cu")
		(net "M_I_CPU0_SA_DQS_DP<6>")
	)
	(arc
		(start 379.643386 -232.81894)
		(mid 379.924818 -232.894695)
		(end 380.20625 -232.81894)
		(width 0.09525)
		(layer "In2.Cu")
		(net "M_I_CPU0_SA_DQS_DP<6>")
	)
	(arc
		(start 385.854702 -232.814114)
		(mid 386.039734 -232.7682)
		(end 386.22351 -232.81894)
		(width 0.09525)
		(layer "In2.Cu")
		(net "M_I_CPU0_SA_DQS_DP<6>")
	)
	(arc
		(start 376.823478 -232.81894)
		(mid 377.10491 -232.894695)
		(end 377.386342 -232.81894)
		(width 0.09525)
		(layer "In2.Cu")
		(net "M_I_CPU0_SA_DQS_DP<6>")
	)
	(arc
		(start 388.103364 -232.81894)
		(mid 388.384796 -232.894695)
		(end 388.666228 -232.81894)
		(width 0.09525)
		(layer "In2.Cu")
		(net "M_I_CPU0_SA_DQS_DP<6>")
	)
	(arc
		(start 382.463294 -232.81894)
		(mid 382.744726 -232.894695)
		(end 383.026158 -232.81894)
		(width 0.09525)
		(layer "In2.Cu")
		(net "M_I_CPU0_SA_DQS_DP<6>")
	)
	(arc
		(start 391.99439 -231.986836)
		(mid 392.17284 -231.785366)
		(end 392.237214 -231.524048)
		(width 0.09525)
		(layer "In2.Cu")
		(net "M_I_CPU0_SA_DQS_DP<6>")
	)
	(arc
		(start 388.666228 -232.81894)
		(mid 388.850003 -232.768168)
		(end 389.035036 -232.814114)
		(width 0.09525)
		(layer "In2.Cu")
		(net "M_I_CPU0_SA_DQS_DP<6>")
	)
	(arc
		(start 384.914648 -232.814114)
		(mid 385.09968 -232.7682)
		(end 385.283456 -232.81894)
		(width 0.09525)
		(layer "In2.Cu")
		(net "M_I_CPU0_SA_DQS_DP<6>")
	)
	(arc
		(start 389.983472 -232.81894)
		(mid 390.264904 -232.894695)
		(end 390.546336 -232.81894)
		(width 0.09525)
		(layer "In2.Cu")
		(net "M_I_CPU0_SA_DQS_DP<6>")
	)
	(arc
		(start 391.76706 -232.334054)
		(mid 391.808517 -232.162014)
		(end 391.923778 -232.02773)
		(width 0.09525)
		(layer "In2.Cu")
		(net "M_I_CPU0_SA_DQS_DP<6>")
	)
	(arc
		(start 383.026158 -232.81894)
		(mid 383.209933 -232.768168)
		(end 383.394966 -232.814114)
		(width 0.09525)
		(layer "In2.Cu")
		(net "M_I_CPU0_SA_DQS_DP<6>")
	)
	(arc
		(start 378.326142 -232.81894)
		(mid 378.509917 -232.768168)
		(end 378.69495 -232.814114)
		(width 0.09525)
		(layer "In2.Cu")
		(net "M_I_CPU0_SA_DQS_DP<6>")
	)
	(arc
		(start 393.40663 -229.555294)
		(mid 393.583402 -229.354273)
		(end 393.647168 -229.094284)
		(width 0.09525)
		(layer "In2.Cu")
		(net "M_I_CPU0_SA_DQS_DP<6>")
	)
	(arc
		(start 375.970038 -232.860088)
		(mid 376.21278 -232.892858)
		(end 376.446288 -232.81894)
		(width 0.09525)
		(layer "In2.Cu")
		(net "M_I_CPU0_SA_DQS_DP<6>")
	)
	(segment
		(start 375.22785 -228.550216)
		(end 375.694702 -228.284278)
		(width 0.12954)
		(layer "F.Cu")
		(net "M_I_CPU0_SA_DQS_DP<5>")
	)
	(segment
		(start 421.16756 -202.795378)
		(end 420.802816 -203.160122)
		(width 0.16002)
		(layer "In2.Cu")
		(net "M_I_CPU0_SA_DQS_DP<5>")
	)
	(segment
		(start 398.13865 -213.206076)
		(end 398.403318 -213.470744)
		(width 0.16002)
		(layer "In2.Cu")
		(net "M_I_CPU0_SA_DQS_DP<5>")
	)
	(segment
		(start 380.214632 -227.954332)
		(end 380.20625 -227.959158)
		(width 0.09525)
		(layer "In2.Cu")
		(net "M_I_CPU0_SA_DQS_DP<5>")
	)
	(segment
		(start 402.524214 -209.877152)
		(end 402.151342 -210.250024)
		(width 0.16002)
		(layer "In2.Cu")
		(net "M_I_CPU0_SA_DQS_DP<5>")
	)
	(segment
		(start 426.233336 -202.278742)
		(end 425.753276 -202.278742)
		(width 0.16002)
		(layer "In2.Cu")
		(net "M_I_CPU0_SA_DQS_DP<5>")
	)
	(segment
		(start 378.703332 -227.959158)
		(end 378.69495 -227.954332)
		(width 0.09525)
		(layer "In2.Cu")
		(net "M_I_CPU0_SA_DQS_DP<5>")
	)
	(segment
		(start 427.183042 -202.161902)
		(end 426.350176 -202.161902)
		(width 0.16002)
		(layer "In2.Cu")
		(net "M_I_CPU0_SA_DQS_DP<5>")
	)
	(segment
		(start 402.259546 -208.808574)
		(end 402.259546 -209.08518)
		(width 0.16002)
		(layer "In2.Cu")
		(net "M_I_CPU0_SA_DQS_DP<5>")
	)
	(segment
		(start 390.581388 -224.69856)
		(end 390.546336 -224.719134)
		(width 0.09525)
		(layer "In2.Cu")
		(net "M_I_CPU0_SA_DQS_DP<5>")
	)
	(segment
		(start 422.39692 -202.002898)
		(end 421.60444 -202.795378)
		(width 0.16002)
		(layer "In2.Cu")
		(net "M_I_CPU0_SA_DQS_DP<5>")
	)
	(segment
		(start 392.296142 -220.105224)
		(end 392.296142 -221.17431)
		(width 0.16002)
		(layer "In2.Cu")
		(net "M_I_CPU0_SA_DQS_DP<5>")
	)
	(segment
		(start 415.57321 -202.310238)
		(end 415.26587 -202.002898)
		(width 0.16002)
		(layer "In2.Cu")
		(net "M_I_CPU0_SA_DQS_DP<5>")
	)
	(segment
		(start 401.150582 -210.72348)
		(end 401.150582 -211.250784)
		(width 0.16002)
		(layer "In2.Cu")
		(net "M_I_CPU0_SA_DQS_DP<5>")
	)
	(segment
		(start 402.948902 -208.827878)
		(end 402.733002 -208.611978)
		(width 0.16002)
		(layer "In2.Cu")
		(net "M_I_CPU0_SA_DQS_DP<5>")
	)
	(segment
		(start 423.117264 -202.310238)
		(end 422.809924 -202.002898)
		(width 0.16002)
		(layer "In2.Cu")
		(net "M_I_CPU0_SA_DQS_DP<5>")
	)
	(segment
		(start 389.606282 -226.339146)
		(end 389.57377 -226.357942)
		(width 0.09525)
		(layer "In2.Cu")
		(net "M_I_CPU0_SA_DQS_DP<5>")
	)
	(segment
		(start 400.885914 -210.458812)
		(end 401.150582 -210.72348)
		(width 0.16002)
		(layer "In2.Cu")
		(net "M_I_CPU0_SA_DQS_DP<5>")
	)
	(segment
		(start 399.512282 -211.556092)
		(end 399.512282 -211.832444)
		(width 0.16002)
		(layer "In2.Cu")
		(net "M_I_CPU0_SA_DQS_DP<5>")
	)
	(segment
		(start 391.92708 -222.305626)
		(end 391.92454 -222.307404)
		(width 0.09525)
		(layer "In2.Cu")
		(net "M_I_CPU0_SA_DQS_DP<5>")
	)
	(segment
		(start 398.403318 -213.470744)
		(end 398.403318 -213.998048)
		(width 0.16002)
		(layer "In2.Cu")
		(net "M_I_CPU0_SA_DQS_DP<5>")
	)
	(segment
		(start 398.3355 -212.732874)
		(end 398.13865 -212.929724)
		(width 0.16002)
		(layer "In2.Cu")
		(net "M_I_CPU0_SA_DQS_DP<5>")
	)
	(segment
		(start 391.016236 -223.909128)
		(end 390.983724 -223.927924)
		(width 0.09525)
		(layer "In2.Cu")
		(net "M_I_CPU0_SA_DQS_DP<5>")
	)
	(segment
		(start 402.259546 -209.08518)
		(end 402.524214 -209.349848)
		(width 0.16002)
		(layer "In2.Cu")
		(net "M_I_CPU0_SA_DQS_DP<5>")
	)
	(segment
		(start 384.914648 -227.954332)
		(end 384.906266 -227.959158)
		(width 0.09525)
		(layer "In2.Cu")
		(net "M_I_CPU0_SA_DQS_DP<5>")
	)
	(segment
		(start 399.512282 -211.832444)
		(end 399.77695 -212.097112)
		(width 0.16002)
		(layer "In2.Cu")
		(net "M_I_CPU0_SA_DQS_DP<5>")
	)
	(segment
		(start 414.852866 -202.002898)
		(end 414.060386 -202.795378)
		(width 0.16002)
		(layer "In2.Cu")
		(net "M_I_CPU0_SA_DQS_DP<5>")
	)
	(segment
		(start 425.753276 -202.278742)
		(end 425.636436 -202.161902)
		(width 0.16002)
		(layer "In2.Cu")
		(net "M_I_CPU0_SA_DQS_DP<5>")
	)
	(segment
		(start 399.985738 -211.359242)
		(end 399.709132 -211.359242)
		(width 0.16002)
		(layer "In2.Cu")
		(net "M_I_CPU0_SA_DQS_DP<5>")
	)
	(segment
		(start 427.456092 -202.434952)
		(end 427.183042 -202.161902)
		(width 0.16002)
		(layer "In2.Cu")
		(net "M_I_CPU0_SA_DQS_DP<5>")
	)
	(segment
		(start 398.87652 -212.997288)
		(end 398.612106 -212.732874)
		(width 0.16002)
		(layer "In2.Cu")
		(net "M_I_CPU0_SA_DQS_DP<5>")
	)
	(segment
		(start 403.985984 -207.447642)
		(end 403.985984 -208.268062)
		(width 0.16002)
		(layer "In2.Cu")
		(net "M_I_CPU0_SA_DQS_DP<5>")
	)
	(segment
		(start 388.103364 -227.959158)
		(end 388.094982 -227.954332)
		(width 0.09525)
		(layer "In2.Cu")
		(net "M_I_CPU0_SA_DQS_DP<5>")
	)
	(segment
		(start 401.082764 -209.98561)
		(end 400.885914 -210.18246)
		(width 0.16002)
		(layer "In2.Cu")
		(net "M_I_CPU0_SA_DQS_DP<5>")
	)
	(segment
		(start 414.060386 -202.795378)
		(end 413.623506 -202.795378)
		(width 0.16002)
		(layer "In2.Cu")
		(net "M_I_CPU0_SA_DQS_DP<5>")
	)
	(segment
		(start 426.350176 -202.161902)
		(end 426.233336 -202.278742)
		(width 0.16002)
		(layer "In2.Cu")
		(net "M_I_CPU0_SA_DQS_DP<5>")
	)
	(segment
		(start 401.150582 -211.250784)
		(end 400.77771 -211.623656)
		(width 0.16002)
		(layer "In2.Cu")
		(net "M_I_CPU0_SA_DQS_DP<5>")
	)
	(segment
		(start 381.154686 -227.954332)
		(end 381.146304 -227.959158)
		(width 0.09525)
		(layer "In2.Cu")
		(net "M_I_CPU0_SA_DQS_DP<5>")
	)
	(segment
		(start 391.99693 -222.264986)
		(end 391.92708 -222.305626)
		(width 0.09525)
		(layer "In2.Cu")
		(net "M_I_CPU0_SA_DQS_DP<5>")
	)
	(segment
		(start 392.296142 -221.17431)
		(end 392.296142 -221.197932)
		(width 0.09525)
		(layer "In2.Cu")
		(net "M_I_CPU0_SA_DQS_DP<5>")
	)
	(segment
		(start 399.77695 -212.624416)
		(end 399.404078 -212.997288)
		(width 0.16002)
		(layer "In2.Cu")
		(net "M_I_CPU0_SA_DQS_DP<5>")
	)
	(segment
		(start 403.426168 -208.827878)
		(end 402.948902 -208.827878)
		(width 0.16002)
		(layer "In2.Cu")
		(net "M_I_CPU0_SA_DQS_DP<5>")
	)
	(segment
		(start 391.054336 -223.88703)
		(end 391.016236 -223.909128)
		(width 0.09525)
		(layer "In2.Cu")
		(net "M_I_CPU0_SA_DQS_DP<5>")
	)
	(segment
		(start 402.733002 -208.611978)
		(end 402.456142 -208.611978)
		(width 0.16002)
		(layer "In2.Cu")
		(net "M_I_CPU0_SA_DQS_DP<5>")
	)
	(segment
		(start 401.623784 -210.250024)
		(end 401.35937 -209.98561)
		(width 0.16002)
		(layer "In2.Cu")
		(net "M_I_CPU0_SA_DQS_DP<5>")
	)
	(segment
		(start 385.854702 -227.954332)
		(end 385.84632 -227.959158)
		(width 0.09525)
		(layer "In2.Cu")
		(net "M_I_CPU0_SA_DQS_DP<5>")
	)
	(segment
		(start 399.709132 -211.359242)
		(end 399.512282 -211.556092)
		(width 0.16002)
		(layer "In2.Cu")
		(net "M_I_CPU0_SA_DQS_DP<5>")
	)
	(segment
		(start 398.612106 -212.732874)
		(end 398.3355 -212.732874)
		(width 0.16002)
		(layer "In2.Cu")
		(net "M_I_CPU0_SA_DQS_DP<5>")
	)
	(segment
		(start 389.171434 -227.128578)
		(end 389.136382 -227.149152)
		(width 0.09525)
		(layer "In2.Cu")
		(net "M_I_CPU0_SA_DQS_DP<5>")
	)
	(segment
		(start 392.237214 -221.25686)
		(end 392.237214 -221.803468)
		(width 0.09525)
		(layer "In2.Cu")
		(net "M_I_CPU0_SA_DQS_DP<5>")
	)
	(segment
		(start 390.546336 -224.719134)
		(end 390.513824 -224.73793)
		(width 0.09525)
		(layer "In2.Cu")
		(net "M_I_CPU0_SA_DQS_DP<5>")
	)
	(segment
		(start 391.486136 -223.099122)
		(end 391.45464 -223.11741)
		(width 0.09525)
		(layer "In2.Cu")
		(net "M_I_CPU0_SA_DQS_DP<5>")
	)
	(segment
		(start 418.036756 -202.310238)
		(end 415.57321 -202.310238)
		(width 0.16002)
		(layer "In2.Cu")
		(net "M_I_CPU0_SA_DQS_DP<5>")
	)
	(segment
		(start 413.258762 -203.160122)
		(end 408.273504 -203.160122)
		(width 0.16002)
		(layer "In2.Cu")
		(net "M_I_CPU0_SA_DQS_DP<5>")
	)
	(segment
		(start 375.848626 -228.018848)
		(end 375.694702 -228.284278)
		(width 0.09525)
		(layer "In2.Cu")
		(net "M_I_CPU0_SA_DQS_DP<5>")
	)
	(segment
		(start 383.403348 -227.959158)
		(end 383.394966 -227.954332)
		(width 0.09525)
		(layer "In2.Cu")
		(net "M_I_CPU0_SA_DQS_DP<5>")
	)
	(segment
		(start 388.704328 -227.93706)
		(end 388.666228 -227.959158)
		(width 0.09525)
		(layer "In2.Cu")
		(net "M_I_CPU0_SA_DQS_DP<5>")
	)
	(segment
		(start 391.524236 -223.077024)
		(end 391.486136 -223.099122)
		(width 0.09525)
		(layer "In2.Cu")
		(net "M_I_CPU0_SA_DQS_DP<5>")
	)
	(segment
		(start 400.885914 -210.18246)
		(end 400.885914 -210.458812)
		(width 0.16002)
		(layer "In2.Cu")
		(net "M_I_CPU0_SA_DQS_DP<5>")
	)
	(segment
		(start 379.643386 -227.959158)
		(end 379.635004 -227.954332)
		(width 0.09525)
		(layer "In2.Cu")
		(net "M_I_CPU0_SA_DQS_DP<5>")
	)
	(segment
		(start 384.343402 -227.959158)
		(end 384.33502 -227.954332)
		(width 0.09525)
		(layer "In2.Cu")
		(net "M_I_CPU0_SA_DQS_DP<5>")
	)
	(segment
		(start 425.00804 -202.310238)
		(end 423.117264 -202.310238)
		(width 0.16002)
		(layer "In2.Cu")
		(net "M_I_CPU0_SA_DQS_DP<5>")
	)
	(segment
		(start 413.623506 -202.795378)
		(end 413.258762 -203.160122)
		(width 0.16002)
		(layer "In2.Cu")
		(net "M_I_CPU0_SA_DQS_DP<5>")
	)
	(segment
		(start 422.809924 -202.002898)
		(end 422.39692 -202.002898)
		(width 0.16002)
		(layer "In2.Cu")
		(net "M_I_CPU0_SA_DQS_DP<5>")
	)
	(segment
		(start 402.524214 -209.349848)
		(end 402.524214 -209.877152)
		(width 0.16002)
		(layer "In2.Cu")
		(net "M_I_CPU0_SA_DQS_DP<5>")
	)
	(segment
		(start 390.076182 -225.52914)
		(end 390.044686 -225.547428)
		(width 0.09525)
		(layer "In2.Cu")
		(net "M_I_CPU0_SA_DQS_DP<5>")
	)
	(segment
		(start 376.45467 -227.954332)
		(end 376.446288 -227.959158)
		(width 0.09525)
		(layer "In2.Cu")
		(net "M_I_CPU0_SA_DQS_DP<5>")
	)
	(segment
		(start 420.802816 -203.160122)
		(end 418.88664 -203.160122)
		(width 0.16002)
		(layer "In2.Cu")
		(net "M_I_CPU0_SA_DQS_DP<5>")
	)
	(segment
		(start 421.60444 -202.795378)
		(end 421.16756 -202.795378)
		(width 0.16002)
		(layer "In2.Cu")
		(net "M_I_CPU0_SA_DQS_DP<5>")
	)
	(segment
		(start 399.77695 -212.097112)
		(end 399.77695 -212.624416)
		(width 0.16002)
		(layer "In2.Cu")
		(net "M_I_CPU0_SA_DQS_DP<5>")
	)
	(segment
		(start 389.644382 -226.317048)
		(end 389.606282 -226.339146)
		(width 0.09525)
		(layer "In2.Cu")
		(net "M_I_CPU0_SA_DQS_DP<5>")
	)
	(segment
		(start 400.250152 -211.623656)
		(end 399.985738 -211.359242)
		(width 0.16002)
		(layer "In2.Cu")
		(net "M_I_CPU0_SA_DQS_DP<5>")
	)
	(segment
		(start 392.296142 -221.197932)
		(end 392.237214 -221.25686)
		(width 0.09525)
		(layer "In2.Cu")
		(net "M_I_CPU0_SA_DQS_DP<5>")
	)
	(segment
		(start 375.949464 -227.992178)
		(end 375.848626 -228.018848)
		(width 0.09525)
		(layer "In2.Cu")
		(net "M_I_CPU0_SA_DQS_DP<5>")
	)
	(segment
		(start 389.136382 -227.149152)
		(end 389.10387 -227.167948)
		(width 0.09525)
		(layer "In2.Cu")
		(net "M_I_CPU0_SA_DQS_DP<5>")
	)
	(segment
		(start 402.151342 -210.250024)
		(end 401.623784 -210.250024)
		(width 0.16002)
		(layer "In2.Cu")
		(net "M_I_CPU0_SA_DQS_DP<5>")
	)
	(segment
		(start 400.77771 -211.623656)
		(end 400.250152 -211.623656)
		(width 0.16002)
		(layer "In2.Cu")
		(net "M_I_CPU0_SA_DQS_DP<5>")
	)
	(segment
		(start 390.114282 -225.507042)
		(end 390.076182 -225.52914)
		(width 0.09525)
		(layer "In2.Cu")
		(net "M_I_CPU0_SA_DQS_DP<5>")
	)
	(segment
		(start 408.273504 -203.160122)
		(end 403.985984 -207.447642)
		(width 0.16002)
		(layer "In2.Cu")
		(net "M_I_CPU0_SA_DQS_DP<5>")
	)
	(segment
		(start 399.404078 -212.997288)
		(end 398.87652 -212.997288)
		(width 0.16002)
		(layer "In2.Cu")
		(net "M_I_CPU0_SA_DQS_DP<5>")
	)
	(segment
		(start 425.636436 -202.161902)
		(end 425.156376 -202.161902)
		(width 0.16002)
		(layer "In2.Cu")
		(net "M_I_CPU0_SA_DQS_DP<5>")
	)
	(segment
		(start 415.26587 -202.002898)
		(end 414.852866 -202.002898)
		(width 0.16002)
		(layer "In2.Cu")
		(net "M_I_CPU0_SA_DQS_DP<5>")
	)
	(segment
		(start 401.35937 -209.98561)
		(end 401.082764 -209.98561)
		(width 0.16002)
		(layer "In2.Cu")
		(net "M_I_CPU0_SA_DQS_DP<5>")
	)
	(segment
		(start 402.456142 -208.611978)
		(end 402.259546 -208.808574)
		(width 0.16002)
		(layer "In2.Cu")
		(net "M_I_CPU0_SA_DQS_DP<5>")
	)
	(segment
		(start 425.156376 -202.161902)
		(end 425.00804 -202.310238)
		(width 0.16002)
		(layer "In2.Cu")
		(net "M_I_CPU0_SA_DQS_DP<5>")
	)
	(segment
		(start 403.985984 -208.268062)
		(end 403.426168 -208.827878)
		(width 0.16002)
		(layer "In2.Cu")
		(net "M_I_CPU0_SA_DQS_DP<5>")
	)
	(segment
		(start 398.403318 -213.998048)
		(end 392.296142 -220.105224)
		(width 0.16002)
		(layer "In2.Cu")
		(net "M_I_CPU0_SA_DQS_DP<5>")
	)
	(segment
		(start 418.88664 -203.160122)
		(end 418.036756 -202.310238)
		(width 0.16002)
		(layer "In2.Cu")
		(net "M_I_CPU0_SA_DQS_DP<5>")
	)
	(segment
		(start 398.13865 -212.929724)
		(end 398.13865 -213.206076)
		(width 0.16002)
		(layer "In2.Cu")
		(net "M_I_CPU0_SA_DQS_DP<5>")
	)
	(arc
		(start 391.76706 -222.614236)
		(mid 391.702663 -222.875542)
		(end 391.524236 -223.077024)
		(width 0.09525)
		(layer "In2.Cu")
		(net "M_I_CPU0_SA_DQS_DP<5>")
	)
	(arc
		(start 389.57377 -226.357942)
		(mid 389.458496 -226.49222)
		(end 389.417052 -226.664266)
		(width 0.09525)
		(layer "In2.Cu")
		(net "M_I_CPU0_SA_DQS_DP<5>")
	)
	(arc
		(start 383.026158 -227.959158)
		(mid 382.744726 -228.034913)
		(end 382.463294 -227.959158)
		(width 0.09525)
		(layer "In2.Cu")
		(net "M_I_CPU0_SA_DQS_DP<5>")
	)
	(arc
		(start 386.22351 -227.959158)
		(mid 386.039735 -227.908386)
		(end 385.854702 -227.954332)
		(width 0.09525)
		(layer "In2.Cu")
		(net "M_I_CPU0_SA_DQS_DP<5>")
	)
	(arc
		(start 378.69495 -227.954332)
		(mid 378.509918 -227.908418)
		(end 378.326142 -227.959158)
		(width 0.09525)
		(layer "In2.Cu")
		(net "M_I_CPU0_SA_DQS_DP<5>")
	)
	(arc
		(start 383.394966 -227.954332)
		(mid 383.209934 -227.908418)
		(end 383.026158 -227.959158)
		(width 0.09525)
		(layer "In2.Cu")
		(net "M_I_CPU0_SA_DQS_DP<5>")
	)
	(arc
		(start 391.92454 -222.307404)
		(mid 391.808742 -222.441798)
		(end 391.76706 -222.614236)
		(width 0.09525)
		(layer "In2.Cu")
		(net "M_I_CPU0_SA_DQS_DP<5>")
	)
	(arc
		(start 390.827006 -224.234248)
		(mid 390.761759 -224.496851)
		(end 390.581388 -224.69856)
		(width 0.09525)
		(layer "In2.Cu")
		(net "M_I_CPU0_SA_DQS_DP<5>")
	)
	(arc
		(start 384.33502 -227.954332)
		(mid 384.149988 -227.908418)
		(end 383.966212 -227.959158)
		(width 0.09525)
		(layer "In2.Cu")
		(net "M_I_CPU0_SA_DQS_DP<5>")
	)
	(arc
		(start 376.823478 -227.959158)
		(mid 376.639703 -227.908386)
		(end 376.45467 -227.954332)
		(width 0.09525)
		(layer "In2.Cu")
		(net "M_I_CPU0_SA_DQS_DP<5>")
	)
	(arc
		(start 379.266196 -227.959158)
		(mid 378.984764 -228.034913)
		(end 378.703332 -227.959158)
		(width 0.09525)
		(layer "In2.Cu")
		(net "M_I_CPU0_SA_DQS_DP<5>")
	)
	(arc
		(start 387.726174 -227.959158)
		(mid 387.444742 -228.034913)
		(end 387.16331 -227.959158)
		(width 0.09525)
		(layer "In2.Cu")
		(net "M_I_CPU0_SA_DQS_DP<5>")
	)
	(arc
		(start 380.58344 -227.959158)
		(mid 380.399665 -227.908386)
		(end 380.214632 -227.954332)
		(width 0.09525)
		(layer "In2.Cu")
		(net "M_I_CPU0_SA_DQS_DP<5>")
	)
	(arc
		(start 388.666228 -227.959158)
		(mid 388.384796 -228.034913)
		(end 388.103364 -227.959158)
		(width 0.09525)
		(layer "In2.Cu")
		(net "M_I_CPU0_SA_DQS_DP<5>")
	)
	(arc
		(start 391.45464 -223.11741)
		(mid 391.338842 -223.251804)
		(end 391.29716 -223.424242)
		(width 0.09525)
		(layer "In2.Cu")
		(net "M_I_CPU0_SA_DQS_DP<5>")
	)
	(arc
		(start 389.887206 -225.85426)
		(mid 389.822809 -226.115566)
		(end 389.644382 -226.317048)
		(width 0.09525)
		(layer "In2.Cu")
		(net "M_I_CPU0_SA_DQS_DP<5>")
	)
	(arc
		(start 381.523494 -227.959158)
		(mid 381.339719 -227.908386)
		(end 381.154686 -227.954332)
		(width 0.09525)
		(layer "In2.Cu")
		(net "M_I_CPU0_SA_DQS_DP<5>")
	)
	(arc
		(start 379.635004 -227.954332)
		(mid 379.449972 -227.908418)
		(end 379.266196 -227.959158)
		(width 0.09525)
		(layer "In2.Cu")
		(net "M_I_CPU0_SA_DQS_DP<5>")
	)
	(arc
		(start 389.417052 -226.664266)
		(mid 389.351805 -226.926869)
		(end 389.171434 -227.128578)
		(width 0.09525)
		(layer "In2.Cu")
		(net "M_I_CPU0_SA_DQS_DP<5>")
	)
	(arc
		(start 388.947152 -227.474272)
		(mid 388.882755 -227.735578)
		(end 388.704328 -227.93706)
		(width 0.09525)
		(layer "In2.Cu")
		(net "M_I_CPU0_SA_DQS_DP<5>")
	)
	(arc
		(start 382.463294 -227.959158)
		(mid 382.274826 -227.908481)
		(end 382.086358 -227.959158)
		(width 0.09525)
		(layer "In2.Cu")
		(net "M_I_CPU0_SA_DQS_DP<5>")
	)
	(arc
		(start 392.237214 -221.803468)
		(mid 392.173599 -222.063657)
		(end 391.99693 -222.264986)
		(width 0.09525)
		(layer "In2.Cu")
		(net "M_I_CPU0_SA_DQS_DP<5>")
	)
	(arc
		(start 391.29716 -223.424242)
		(mid 391.232763 -223.685548)
		(end 391.054336 -223.88703)
		(width 0.09525)
		(layer "In2.Cu")
		(net "M_I_CPU0_SA_DQS_DP<5>")
	)
	(arc
		(start 390.983724 -223.927924)
		(mid 390.86845 -224.062202)
		(end 390.827006 -224.234248)
		(width 0.09525)
		(layer "In2.Cu")
		(net "M_I_CPU0_SA_DQS_DP<5>")
	)
	(arc
		(start 376.446288 -227.959158)
		(mid 376.212774 -228.033001)
		(end 375.970038 -228.000306)
		(width 0.09525)
		(layer "In2.Cu")
		(net "M_I_CPU0_SA_DQS_DP<5>")
	)
	(arc
		(start 386.786374 -227.959158)
		(mid 386.504942 -228.034913)
		(end 386.22351 -227.959158)
		(width 0.09525)
		(layer "In2.Cu")
		(net "M_I_CPU0_SA_DQS_DP<5>")
	)
	(arc
		(start 385.283456 -227.959158)
		(mid 385.099681 -227.908386)
		(end 384.914648 -227.954332)
		(width 0.09525)
		(layer "In2.Cu")
		(net "M_I_CPU0_SA_DQS_DP<5>")
	)
	(arc
		(start 384.906266 -227.959158)
		(mid 384.624834 -228.034913)
		(end 384.343402 -227.959158)
		(width 0.09525)
		(layer "In2.Cu")
		(net "M_I_CPU0_SA_DQS_DP<5>")
	)
	(arc
		(start 387.16331 -227.959158)
		(mid 386.974842 -227.908481)
		(end 386.786374 -227.959158)
		(width 0.09525)
		(layer "In2.Cu")
		(net "M_I_CPU0_SA_DQS_DP<5>")
	)
	(arc
		(start 382.086358 -227.959158)
		(mid 381.804926 -228.034913)
		(end 381.523494 -227.959158)
		(width 0.09525)
		(layer "In2.Cu")
		(net "M_I_CPU0_SA_DQS_DP<5>")
	)
	(arc
		(start 380.20625 -227.959158)
		(mid 379.924818 -228.034913)
		(end 379.643386 -227.959158)
		(width 0.09525)
		(layer "In2.Cu")
		(net "M_I_CPU0_SA_DQS_DP<5>")
	)
	(arc
		(start 383.966212 -227.959158)
		(mid 383.68478 -228.034913)
		(end 383.403348 -227.959158)
		(width 0.09525)
		(layer "In2.Cu")
		(net "M_I_CPU0_SA_DQS_DP<5>")
	)
	(arc
		(start 390.357106 -225.044254)
		(mid 390.292709 -225.30556)
		(end 390.114282 -225.507042)
		(width 0.09525)
		(layer "In2.Cu")
		(net "M_I_CPU0_SA_DQS_DP<5>")
	)
	(arc
		(start 389.10387 -227.167948)
		(mid 388.988596 -227.302226)
		(end 388.947152 -227.474272)
		(width 0.09525)
		(layer "In2.Cu")
		(net "M_I_CPU0_SA_DQS_DP<5>")
	)
	(arc
		(start 390.044686 -225.547428)
		(mid 389.928888 -225.681822)
		(end 389.887206 -225.85426)
		(width 0.09525)
		(layer "In2.Cu")
		(net "M_I_CPU0_SA_DQS_DP<5>")
	)
	(arc
		(start 390.513824 -224.73793)
		(mid 390.39855 -224.872208)
		(end 390.357106 -225.044254)
		(width 0.09525)
		(layer "In2.Cu")
		(net "M_I_CPU0_SA_DQS_DP<5>")
	)
	(arc
		(start 375.970038 -228.000306)
		(mid 375.95971 -227.996346)
		(end 375.949464 -227.992178)
		(width 0.09525)
		(layer "In2.Cu")
		(net "M_I_CPU0_SA_DQS_DP<5>")
	)
	(arc
		(start 388.094982 -227.954332)
		(mid 387.90995 -227.908418)
		(end 387.726174 -227.959158)
		(width 0.09525)
		(layer "In2.Cu")
		(net "M_I_CPU0_SA_DQS_DP<5>")
	)
	(arc
		(start 377.763278 -227.959158)
		(mid 377.57481 -227.908481)
		(end 377.386342 -227.959158)
		(width 0.09525)
		(layer "In2.Cu")
		(net "M_I_CPU0_SA_DQS_DP<5>")
	)
	(arc
		(start 385.84632 -227.959158)
		(mid 385.564888 -228.034913)
		(end 385.283456 -227.959158)
		(width 0.09525)
		(layer "In2.Cu")
		(net "M_I_CPU0_SA_DQS_DP<5>")
	)
	(arc
		(start 381.146304 -227.959158)
		(mid 380.864872 -228.034913)
		(end 380.58344 -227.959158)
		(width 0.09525)
		(layer "In2.Cu")
		(net "M_I_CPU0_SA_DQS_DP<5>")
	)
	(arc
		(start 377.386342 -227.959158)
		(mid 377.10491 -228.034913)
		(end 376.823478 -227.959158)
		(width 0.09525)
		(layer "In2.Cu")
		(net "M_I_CPU0_SA_DQS_DP<5>")
	)
	(arc
		(start 378.326142 -227.959158)
		(mid 378.04471 -228.034913)
		(end 377.763278 -227.959158)
		(width 0.09525)
		(layer "In2.Cu")
		(net "M_I_CPU0_SA_DQS_DP<5>")
	)
	(segment
		(start 377.107958 -246.370094)
		(end 377.57481 -246.104156)
		(width 0.12954)
		(layer "F.Cu")
		(net "M_I_CPU0_SA_DQS_DP<4>")
	)
	(segment
		(start 421.466264 -238.567214)
		(end 422.307004 -237.726474)
		(width 0.16002)
		(layer "In2.Cu")
		(net "M_I_CPU0_SA_DQS_DP<4>")
	)
	(segment
		(start 395.816328 -246.33936)
		(end 396.395956 -245.759732)
		(width 0.16002)
		(layer "In2.Cu")
		(net "M_I_CPU0_SA_DQS_DP<4>")
	)
	(segment
		(start 393.55141 -246.479822)
		(end 393.686792 -246.479822)
		(width 0.09525)
		(layer "In2.Cu")
		(net "M_I_CPU0_SA_DQS_DP<4>")
	)
	(segment
		(start 381.146304 -246.429276)
		(end 381.154686 -246.434102)
		(width 0.09525)
		(layer "In2.Cu")
		(net "M_I_CPU0_SA_DQS_DP<4>")
	)
	(segment
		(start 377.420886 -246.369586)
		(end 377.444 -246.4562)
		(width 0.09525)
		(layer "In2.Cu")
		(net "M_I_CPU0_SA_DQS_DP<4>")
	)
	(segment
		(start 428.69358 -238.592614)
		(end 429.151796 -238.592614)
		(width 0.16002)
		(layer "In2.Cu")
		(net "M_I_CPU0_SA_DQS_DP<4>")
	)
	(segment
		(start 393.686792 -246.479822)
		(end 393.97178 -246.76481)
		(width 0.09525)
		(layer "In2.Cu")
		(net "M_I_CPU0_SA_DQS_DP<4>")
	)
	(segment
		(start 391.862056 -246.429022)
		(end 391.885932 -246.415306)
		(width 0.09525)
		(layer "In2.Cu")
		(net "M_I_CPU0_SA_DQS_DP<4>")
	)
	(segment
		(start 429.151796 -238.592614)
		(end 429.334676 -238.409734)
		(width 0.16002)
		(layer "In2.Cu")
		(net "M_I_CPU0_SA_DQS_DP<4>")
	)
	(segment
		(start 396.395956 -245.759732)
		(end 405.017478 -245.759732)
		(width 0.16002)
		(layer "In2.Cu")
		(net "M_I_CPU0_SA_DQS_DP<4>")
	)
	(segment
		(start 384.906266 -246.429276)
		(end 384.914648 -246.434102)
		(width 0.09525)
		(layer "In2.Cu")
		(net "M_I_CPU0_SA_DQS_DP<4>")
	)
	(segment
		(start 420.81704 -238.259874)
		(end 421.12438 -238.567214)
		(width 0.16002)
		(layer "In2.Cu")
		(net "M_I_CPU0_SA_DQS_DP<4>")
	)
	(segment
		(start 421.12438 -238.567214)
		(end 421.466264 -238.567214)
		(width 0.16002)
		(layer "In2.Cu")
		(net "M_I_CPU0_SA_DQS_DP<4>")
	)
	(segment
		(start 425.425616 -237.40999)
		(end 425.999656 -237.98403)
		(width 0.16002)
		(layer "In2.Cu")
		(net "M_I_CPU0_SA_DQS_DP<4>")
	)
	(segment
		(start 430.528476 -238.409734)
		(end 431.281586 -238.409734)
		(width 0.16002)
		(layer "In2.Cu")
		(net "M_I_CPU0_SA_DQS_DP<4>")
	)
	(segment
		(start 413.580326 -238.567214)
		(end 413.92221 -238.567214)
		(width 0.16002)
		(layer "In2.Cu")
		(net "M_I_CPU0_SA_DQS_DP<4>")
	)
	(segment
		(start 392.423142 -246.429276)
		(end 392.44651 -246.442738)
		(width 0.09525)
		(layer "In2.Cu")
		(net "M_I_CPU0_SA_DQS_DP<4>")
	)
	(segment
		(start 423.14876 -237.40999)
		(end 425.425616 -237.40999)
		(width 0.16002)
		(layer "In2.Cu")
		(net "M_I_CPU0_SA_DQS_DP<4>")
	)
	(segment
		(start 389.606282 -246.429276)
		(end 389.614664 -246.434102)
		(width 0.09525)
		(layer "In2.Cu")
		(net "M_I_CPU0_SA_DQS_DP<4>")
	)
	(segment
		(start 429.814736 -238.409734)
		(end 429.931576 -238.292894)
		(width 0.16002)
		(layer "In2.Cu")
		(net "M_I_CPU0_SA_DQS_DP<4>")
	)
	(segment
		(start 391.838688 -246.442484)
		(end 391.862056 -246.429022)
		(width 0.09525)
		(layer "In2.Cu")
		(net "M_I_CPU0_SA_DQS_DP<4>")
	)
	(segment
		(start 415.604706 -237.40999)
		(end 417.83381 -237.40999)
		(width 0.16002)
		(layer "In2.Cu")
		(net "M_I_CPU0_SA_DQS_DP<4>")
	)
	(segment
		(start 417.83381 -237.40999)
		(end 418.683694 -238.259874)
		(width 0.16002)
		(layer "In2.Cu")
		(net "M_I_CPU0_SA_DQS_DP<4>")
	)
	(segment
		(start 410.892498 -239.884712)
		(end 410.892498 -238.755428)
		(width 0.16002)
		(layer "In2.Cu")
		(net "M_I_CPU0_SA_DQS_DP<4>")
	)
	(segment
		(start 385.84632 -246.429276)
		(end 385.854702 -246.434102)
		(width 0.09525)
		(layer "In2.Cu")
		(net "M_I_CPU0_SA_DQS_DP<4>")
	)
	(segment
		(start 414.76295 -237.726474)
		(end 415.288222 -237.726474)
		(width 0.16002)
		(layer "In2.Cu")
		(net "M_I_CPU0_SA_DQS_DP<4>")
	)
	(segment
		(start 395.662404 -246.33936)
		(end 395.686026 -246.33936)
		(width 0.09525)
		(layer "In2.Cu")
		(net "M_I_CPU0_SA_DQS_DP<4>")
	)
	(segment
		(start 411.388052 -238.259874)
		(end 413.272986 -238.259874)
		(width 0.16002)
		(layer "In2.Cu")
		(net "M_I_CPU0_SA_DQS_DP<4>")
	)
	(segment
		(start 415.288222 -237.726474)
		(end 415.604706 -237.40999)
		(width 0.16002)
		(layer "In2.Cu")
		(net "M_I_CPU0_SA_DQS_DP<4>")
	)
	(segment
		(start 380.20625 -246.429276)
		(end 380.214632 -246.434102)
		(width 0.09525)
		(layer "In2.Cu")
		(net "M_I_CPU0_SA_DQS_DP<4>")
	)
	(segment
		(start 418.683694 -238.259874)
		(end 420.81704 -238.259874)
		(width 0.16002)
		(layer "In2.Cu")
		(net "M_I_CPU0_SA_DQS_DP<4>")
	)
	(segment
		(start 379.635004 -246.434102)
		(end 379.643386 -246.429276)
		(width 0.09525)
		(layer "In2.Cu")
		(net "M_I_CPU0_SA_DQS_DP<4>")
	)
	(segment
		(start 378.69495 -246.434102)
		(end 378.703332 -246.429276)
		(width 0.09525)
		(layer "In2.Cu")
		(net "M_I_CPU0_SA_DQS_DP<4>")
	)
	(segment
		(start 384.33502 -246.434102)
		(end 384.343402 -246.429276)
		(width 0.09525)
		(layer "In2.Cu")
		(net "M_I_CPU0_SA_DQS_DP<4>")
	)
	(segment
		(start 425.999656 -237.98403)
		(end 428.084996 -237.98403)
		(width 0.16002)
		(layer "In2.Cu")
		(net "M_I_CPU0_SA_DQS_DP<4>")
	)
	(segment
		(start 405.017478 -245.759732)
		(end 410.892498 -239.884712)
		(width 0.16002)
		(layer "In2.Cu")
		(net "M_I_CPU0_SA_DQS_DP<4>")
	)
	(segment
		(start 395.243558 -246.398542)
		(end 395.603222 -246.398542)
		(width 0.09525)
		(layer "In2.Cu")
		(net "M_I_CPU0_SA_DQS_DP<4>")
	)
	(segment
		(start 413.92221 -238.567214)
		(end 414.76295 -237.726474)
		(width 0.16002)
		(layer "In2.Cu")
		(net "M_I_CPU0_SA_DQS_DP<4>")
	)
	(segment
		(start 410.892498 -238.755428)
		(end 411.388052 -238.259874)
		(width 0.16002)
		(layer "In2.Cu")
		(net "M_I_CPU0_SA_DQS_DP<4>")
	)
	(segment
		(start 395.686026 -246.33936)
		(end 395.816328 -246.33936)
		(width 0.16002)
		(layer "In2.Cu")
		(net "M_I_CPU0_SA_DQS_DP<4>")
	)
	(segment
		(start 428.084996 -237.98403)
		(end 428.69358 -238.592614)
		(width 0.16002)
		(layer "In2.Cu")
		(net "M_I_CPU0_SA_DQS_DP<4>")
	)
	(segment
		(start 413.272986 -238.259874)
		(end 413.580326 -238.567214)
		(width 0.16002)
		(layer "In2.Cu")
		(net "M_I_CPU0_SA_DQS_DP<4>")
	)
	(segment
		(start 429.334676 -238.409734)
		(end 429.814736 -238.409734)
		(width 0.16002)
		(layer "In2.Cu")
		(net "M_I_CPU0_SA_DQS_DP<4>")
	)
	(segment
		(start 383.394966 -246.434102)
		(end 383.403348 -246.429276)
		(width 0.09525)
		(layer "In2.Cu")
		(net "M_I_CPU0_SA_DQS_DP<4>")
	)
	(segment
		(start 429.931576 -238.292894)
		(end 430.411636 -238.292894)
		(width 0.16002)
		(layer "In2.Cu")
		(net "M_I_CPU0_SA_DQS_DP<4>")
	)
	(segment
		(start 389.035036 -246.434102)
		(end 389.043418 -246.429276)
		(width 0.09525)
		(layer "In2.Cu")
		(net "M_I_CPU0_SA_DQS_DP<4>")
	)
	(segment
		(start 431.281586 -238.409734)
		(end 431.55616 -238.13516)
		(width 0.16002)
		(layer "In2.Cu")
		(net "M_I_CPU0_SA_DQS_DP<4>")
	)
	(segment
		(start 388.094982 -246.434102)
		(end 388.103364 -246.429276)
		(width 0.09525)
		(layer "In2.Cu")
		(net "M_I_CPU0_SA_DQS_DP<4>")
	)
	(segment
		(start 393.97178 -246.76481)
		(end 394.87729 -246.76481)
		(width 0.09525)
		(layer "In2.Cu")
		(net "M_I_CPU0_SA_DQS_DP<4>")
	)
	(segment
		(start 430.411636 -238.292894)
		(end 430.528476 -238.409734)
		(width 0.16002)
		(layer "In2.Cu")
		(net "M_I_CPU0_SA_DQS_DP<4>")
	)
	(segment
		(start 393.328906 -246.408702)
		(end 393.364212 -246.429022)
		(width 0.09525)
		(layer "In2.Cu")
		(net "M_I_CPU0_SA_DQS_DP<4>")
	)
	(segment
		(start 395.603222 -246.398542)
		(end 395.662404 -246.33936)
		(width 0.09525)
		(layer "In2.Cu")
		(net "M_I_CPU0_SA_DQS_DP<4>")
	)
	(segment
		(start 422.832276 -237.726474)
		(end 423.14876 -237.40999)
		(width 0.16002)
		(layer "In2.Cu")
		(net "M_I_CPU0_SA_DQS_DP<4>")
	)
	(segment
		(start 377.57481 -246.104156)
		(end 377.420886 -246.369586)
		(width 0.09525)
		(layer "In2.Cu")
		(net "M_I_CPU0_SA_DQS_DP<4>")
	)
	(segment
		(start 394.87729 -246.76481)
		(end 395.243558 -246.398542)
		(width 0.09525)
		(layer "In2.Cu")
		(net "M_I_CPU0_SA_DQS_DP<4>")
	)
	(segment
		(start 422.307004 -237.726474)
		(end 422.832276 -237.726474)
		(width 0.16002)
		(layer "In2.Cu")
		(net "M_I_CPU0_SA_DQS_DP<4>")
	)
	(arc
		(start 378.326142 -246.429276)
		(mid 378.509917 -246.480048)
		(end 378.69495 -246.434102)
		(width 0.09525)
		(layer "In2.Cu")
		(net "M_I_CPU0_SA_DQS_DP<4>")
	)
	(arc
		(start 386.786374 -246.429276)
		(mid 386.974842 -246.479953)
		(end 387.16331 -246.429276)
		(width 0.09525)
		(layer "In2.Cu")
		(net "M_I_CPU0_SA_DQS_DP<4>")
	)
	(arc
		(start 380.214632 -246.434102)
		(mid 380.399664 -246.480016)
		(end 380.58344 -246.429276)
		(width 0.09525)
		(layer "In2.Cu")
		(net "M_I_CPU0_SA_DQS_DP<4>")
	)
	(arc
		(start 380.58344 -246.429276)
		(mid 380.864872 -246.353521)
		(end 381.146304 -246.429276)
		(width 0.09525)
		(layer "In2.Cu")
		(net "M_I_CPU0_SA_DQS_DP<4>")
	)
	(arc
		(start 393.364212 -246.429022)
		(mid 393.454469 -246.466755)
		(end 393.55141 -246.479822)
		(width 0.09525)
		(layer "In2.Cu")
		(net "M_I_CPU0_SA_DQS_DP<4>")
	)
	(arc
		(start 383.403348 -246.429276)
		(mid 383.68478 -246.353521)
		(end 383.966212 -246.429276)
		(width 0.09525)
		(layer "In2.Cu")
		(net "M_I_CPU0_SA_DQS_DP<4>")
	)
	(arc
		(start 387.16331 -246.429276)
		(mid 387.444742 -246.353521)
		(end 387.726174 -246.429276)
		(width 0.09525)
		(layer "In2.Cu")
		(net "M_I_CPU0_SA_DQS_DP<4>")
	)
	(arc
		(start 392.801602 -246.42953)
		(mid 393.062654 -246.353283)
		(end 393.328906 -246.408702)
		(width 0.09525)
		(layer "In2.Cu")
		(net "M_I_CPU0_SA_DQS_DP<4>")
	)
	(arc
		(start 381.523494 -246.429276)
		(mid 381.804926 -246.353521)
		(end 382.086358 -246.429276)
		(width 0.09525)
		(layer "In2.Cu")
		(net "M_I_CPU0_SA_DQS_DP<4>")
	)
	(arc
		(start 389.614664 -246.434102)
		(mid 389.799696 -246.480016)
		(end 389.983472 -246.429276)
		(width 0.09525)
		(layer "In2.Cu")
		(net "M_I_CPU0_SA_DQS_DP<4>")
	)
	(arc
		(start 388.103364 -246.429276)
		(mid 388.384796 -246.353521)
		(end 388.666228 -246.429276)
		(width 0.09525)
		(layer "In2.Cu")
		(net "M_I_CPU0_SA_DQS_DP<4>")
	)
	(arc
		(start 379.266196 -246.429276)
		(mid 379.449971 -246.480048)
		(end 379.635004 -246.434102)
		(width 0.09525)
		(layer "In2.Cu")
		(net "M_I_CPU0_SA_DQS_DP<4>")
	)
	(arc
		(start 388.666228 -246.429276)
		(mid 388.850003 -246.480048)
		(end 389.035036 -246.434102)
		(width 0.09525)
		(layer "In2.Cu")
		(net "M_I_CPU0_SA_DQS_DP<4>")
	)
	(arc
		(start 383.966212 -246.429276)
		(mid 384.149987 -246.480048)
		(end 384.33502 -246.434102)
		(width 0.09525)
		(layer "In2.Cu")
		(net "M_I_CPU0_SA_DQS_DP<4>")
	)
	(arc
		(start 378.703332 -246.429276)
		(mid 378.984764 -246.353521)
		(end 379.266196 -246.429276)
		(width 0.09525)
		(layer "In2.Cu")
		(net "M_I_CPU0_SA_DQS_DP<4>")
	)
	(arc
		(start 389.983472 -246.429276)
		(mid 390.264904 -246.353521)
		(end 390.546336 -246.429276)
		(width 0.09525)
		(layer "In2.Cu")
		(net "M_I_CPU0_SA_DQS_DP<4>")
	)
	(arc
		(start 385.854702 -246.434102)
		(mid 386.039734 -246.480016)
		(end 386.22351 -246.429276)
		(width 0.09525)
		(layer "In2.Cu")
		(net "M_I_CPU0_SA_DQS_DP<4>")
	)
	(arc
		(start 386.22351 -246.429276)
		(mid 386.504942 -246.353521)
		(end 386.786374 -246.429276)
		(width 0.09525)
		(layer "In2.Cu")
		(net "M_I_CPU0_SA_DQS_DP<4>")
	)
	(arc
		(start 383.026158 -246.429276)
		(mid 383.209933 -246.480048)
		(end 383.394966 -246.434102)
		(width 0.09525)
		(layer "In2.Cu")
		(net "M_I_CPU0_SA_DQS_DP<4>")
	)
	(arc
		(start 390.923272 -246.429276)
		(mid 391.204704 -246.353521)
		(end 391.486136 -246.429276)
		(width 0.09525)
		(layer "In2.Cu")
		(net "M_I_CPU0_SA_DQS_DP<4>")
	)
	(arc
		(start 392.44651 -246.442738)
		(mid 392.625698 -246.480583)
		(end 392.801602 -246.42953)
		(width 0.09525)
		(layer "In2.Cu")
		(net "M_I_CPU0_SA_DQS_DP<4>")
	)
	(arc
		(start 391.885932 -246.415306)
		(mid 392.156315 -246.353746)
		(end 392.423142 -246.429276)
		(width 0.09525)
		(layer "In2.Cu")
		(net "M_I_CPU0_SA_DQS_DP<4>")
	)
	(arc
		(start 389.043418 -246.429276)
		(mid 389.32485 -246.353521)
		(end 389.606282 -246.429276)
		(width 0.09525)
		(layer "In2.Cu")
		(net "M_I_CPU0_SA_DQS_DP<4>")
	)
	(arc
		(start 390.546336 -246.429276)
		(mid 390.734804 -246.479953)
		(end 390.923272 -246.429276)
		(width 0.09525)
		(layer "In2.Cu")
		(net "M_I_CPU0_SA_DQS_DP<4>")
	)
	(arc
		(start 377.444 -246.4562)
		(mid 377.606651 -246.47846)
		(end 377.763278 -246.429276)
		(width 0.09525)
		(layer "In2.Cu")
		(net "M_I_CPU0_SA_DQS_DP<4>")
	)
	(arc
		(start 377.763278 -246.429276)
		(mid 378.04471 -246.353521)
		(end 378.326142 -246.429276)
		(width 0.09525)
		(layer "In2.Cu")
		(net "M_I_CPU0_SA_DQS_DP<4>")
	)
	(arc
		(start 382.463294 -246.429276)
		(mid 382.744726 -246.353521)
		(end 383.026158 -246.429276)
		(width 0.09525)
		(layer "In2.Cu")
		(net "M_I_CPU0_SA_DQS_DP<4>")
	)
	(arc
		(start 381.154686 -246.434102)
		(mid 381.339718 -246.480016)
		(end 381.523494 -246.429276)
		(width 0.09525)
		(layer "In2.Cu")
		(net "M_I_CPU0_SA_DQS_DP<4>")
	)
	(arc
		(start 391.486136 -246.429276)
		(mid 391.660768 -246.479816)
		(end 391.838688 -246.442484)
		(width 0.09525)
		(layer "In2.Cu")
		(net "M_I_CPU0_SA_DQS_DP<4>")
	)
	(arc
		(start 382.086358 -246.429276)
		(mid 382.274826 -246.479953)
		(end 382.463294 -246.429276)
		(width 0.09525)
		(layer "In2.Cu")
		(net "M_I_CPU0_SA_DQS_DP<4>")
	)
	(arc
		(start 379.643386 -246.429276)
		(mid 379.924818 -246.353521)
		(end 380.20625 -246.429276)
		(width 0.09525)
		(layer "In2.Cu")
		(net "M_I_CPU0_SA_DQS_DP<4>")
	)
	(arc
		(start 385.283456 -246.429276)
		(mid 385.564888 -246.353521)
		(end 385.84632 -246.429276)
		(width 0.09525)
		(layer "In2.Cu")
		(net "M_I_CPU0_SA_DQS_DP<4>")
	)
	(arc
		(start 384.914648 -246.434102)
		(mid 385.09968 -246.480016)
		(end 385.283456 -246.429276)
		(width 0.09525)
		(layer "In2.Cu")
		(net "M_I_CPU0_SA_DQS_DP<4>")
	)
	(arc
		(start 387.726174 -246.429276)
		(mid 387.909949 -246.480048)
		(end 388.094982 -246.434102)
		(width 0.09525)
		(layer "In2.Cu")
		(net "M_I_CPU0_SA_DQS_DP<4>")
	)
	(arc
		(start 384.343402 -246.429276)
		(mid 384.624834 -246.353521)
		(end 384.906266 -246.429276)
		(width 0.09525)
		(layer "In2.Cu")
		(net "M_I_CPU0_SA_DQS_DP<4>")
	)
	(segment
		(start 377.107958 -241.510058)
		(end 377.57481 -241.24412)
		(width 0.12954)
		(layer "F.Cu")
		(net "M_I_CPU0_SA_DQS_DP<3>")
	)
	(segment
		(start 422.307004 -228.37648)
		(end 422.832276 -228.37648)
		(width 0.16002)
		(layer "In2.Cu")
		(net "M_I_CPU0_SA_DQS_DP<3>")
	)
	(segment
		(start 428.084996 -228.634036)
		(end 428.69358 -229.24262)
		(width 0.16002)
		(layer "In2.Cu")
		(net "M_I_CPU0_SA_DQS_DP<3>")
	)
	(segment
		(start 403.585172 -235.486702)
		(end 404.966424 -235.486702)
		(width 0.16002)
		(layer "In2.Cu")
		(net "M_I_CPU0_SA_DQS_DP<3>")
	)
	(segment
		(start 404.966424 -235.486702)
		(end 409.553156 -230.89997)
		(width 0.16002)
		(layer "In2.Cu")
		(net "M_I_CPU0_SA_DQS_DP<3>")
	)
	(segment
		(start 413.272986 -228.90988)
		(end 413.580326 -229.21722)
		(width 0.16002)
		(layer "In2.Cu")
		(net "M_I_CPU0_SA_DQS_DP<3>")
	)
	(segment
		(start 392.425936 -241.56924)
		(end 392.434318 -241.574066)
		(width 0.09525)
		(layer "In2.Cu")
		(net "M_I_CPU0_SA_DQS_DP<3>")
	)
	(segment
		(start 417.83381 -228.059996)
		(end 418.683694 -228.90988)
		(width 0.16002)
		(layer "In2.Cu")
		(net "M_I_CPU0_SA_DQS_DP<3>")
	)
	(segment
		(start 421.12438 -229.21722)
		(end 421.466264 -229.21722)
		(width 0.16002)
		(layer "In2.Cu")
		(net "M_I_CPU0_SA_DQS_DP<3>")
	)
	(segment
		(start 430.503584 -228.9429)
		(end 430.620424 -229.05974)
		(width 0.16002)
		(layer "In2.Cu")
		(net "M_I_CPU0_SA_DQS_DP<3>")
	)
	(segment
		(start 395.603222 -240.114328)
		(end 395.662404 -240.055146)
		(width 0.09525)
		(layer "In2.Cu")
		(net "M_I_CPU0_SA_DQS_DP<3>")
	)
	(segment
		(start 378.69495 -241.574066)
		(end 378.703332 -241.56924)
		(width 0.09525)
		(layer "In2.Cu")
		(net "M_I_CPU0_SA_DQS_DP<3>")
	)
	(segment
		(start 420.81704 -228.90988)
		(end 421.12438 -229.21722)
		(width 0.16002)
		(layer "In2.Cu")
		(net "M_I_CPU0_SA_DQS_DP<3>")
	)
	(segment
		(start 391.854944 -241.574066)
		(end 391.863326 -241.56924)
		(width 0.09525)
		(layer "In2.Cu")
		(net "M_I_CPU0_SA_DQS_DP<3>")
	)
	(segment
		(start 384.33502 -241.574066)
		(end 384.343402 -241.56924)
		(width 0.09525)
		(layer "In2.Cu")
		(net "M_I_CPU0_SA_DQS_DP<3>")
	)
	(segment
		(start 430.620424 -229.05974)
		(end 431.281586 -229.05974)
		(width 0.16002)
		(layer "In2.Cu")
		(net "M_I_CPU0_SA_DQS_DP<3>")
	)
	(segment
		(start 389.035036 -241.574066)
		(end 389.043418 -241.56924)
		(width 0.09525)
		(layer "In2.Cu")
		(net "M_I_CPU0_SA_DQS_DP<3>")
	)
	(segment
		(start 395.141196 -240.114328)
		(end 395.603222 -240.114328)
		(width 0.09525)
		(layer "In2.Cu")
		(net "M_I_CPU0_SA_DQS_DP<3>")
	)
	(segment
		(start 389.606282 -241.56924)
		(end 389.614664 -241.574066)
		(width 0.09525)
		(layer "In2.Cu")
		(net "M_I_CPU0_SA_DQS_DP<3>")
	)
	(segment
		(start 425.425616 -228.059996)
		(end 425.999656 -228.634036)
		(width 0.16002)
		(layer "In2.Cu")
		(net "M_I_CPU0_SA_DQS_DP<3>")
	)
	(segment
		(start 411.277054 -228.90988)
		(end 413.272986 -228.90988)
		(width 0.16002)
		(layer "In2.Cu")
		(net "M_I_CPU0_SA_DQS_DP<3>")
	)
	(segment
		(start 429.426624 -229.05974)
		(end 429.906684 -229.05974)
		(width 0.16002)
		(layer "In2.Cu")
		(net "M_I_CPU0_SA_DQS_DP<3>")
	)
	(segment
		(start 383.394966 -241.574066)
		(end 383.403348 -241.56924)
		(width 0.09525)
		(layer "In2.Cu")
		(net "M_I_CPU0_SA_DQS_DP<3>")
	)
	(segment
		(start 409.553156 -230.633778)
		(end 411.277054 -228.90988)
		(width 0.16002)
		(layer "In2.Cu")
		(net "M_I_CPU0_SA_DQS_DP<3>")
	)
	(segment
		(start 428.69358 -229.24262)
		(end 429.243744 -229.24262)
		(width 0.16002)
		(layer "In2.Cu")
		(net "M_I_CPU0_SA_DQS_DP<3>")
	)
	(segment
		(start 385.84632 -241.56924)
		(end 385.854702 -241.574066)
		(width 0.09525)
		(layer "In2.Cu")
		(net "M_I_CPU0_SA_DQS_DP<3>")
	)
	(segment
		(start 430.023524 -228.9429)
		(end 430.503584 -228.9429)
		(width 0.16002)
		(layer "In2.Cu")
		(net "M_I_CPU0_SA_DQS_DP<3>")
	)
	(segment
		(start 393.417552 -241.493294)
		(end 393.785852 -241.124994)
		(width 0.09525)
		(layer "In2.Cu")
		(net "M_I_CPU0_SA_DQS_DP<3>")
	)
	(segment
		(start 377.57481 -241.24412)
		(end 377.420886 -241.50955)
		(width 0.09525)
		(layer "In2.Cu")
		(net "M_I_CPU0_SA_DQS_DP<3>")
	)
	(segment
		(start 393.785852 -241.124994)
		(end 394.13053 -241.124994)
		(width 0.09525)
		(layer "In2.Cu")
		(net "M_I_CPU0_SA_DQS_DP<3>")
	)
	(segment
		(start 394.13053 -241.124994)
		(end 395.141196 -240.114328)
		(width 0.09525)
		(layer "In2.Cu")
		(net "M_I_CPU0_SA_DQS_DP<3>")
	)
	(segment
		(start 388.094982 -241.574066)
		(end 388.103364 -241.56924)
		(width 0.09525)
		(layer "In2.Cu")
		(net "M_I_CPU0_SA_DQS_DP<3>")
	)
	(segment
		(start 413.92221 -229.21722)
		(end 414.76295 -228.37648)
		(width 0.16002)
		(layer "In2.Cu")
		(net "M_I_CPU0_SA_DQS_DP<3>")
	)
	(segment
		(start 384.906266 -241.56924)
		(end 384.914648 -241.574066)
		(width 0.09525)
		(layer "In2.Cu")
		(net "M_I_CPU0_SA_DQS_DP<3>")
	)
	(segment
		(start 395.662404 -240.055146)
		(end 395.686026 -240.055146)
		(width 0.09525)
		(layer "In2.Cu")
		(net "M_I_CPU0_SA_DQS_DP<3>")
	)
	(segment
		(start 377.420886 -241.50955)
		(end 377.444 -241.596164)
		(width 0.09525)
		(layer "In2.Cu")
		(net "M_I_CPU0_SA_DQS_DP<3>")
	)
	(segment
		(start 429.243744 -229.24262)
		(end 429.426624 -229.05974)
		(width 0.16002)
		(layer "In2.Cu")
		(net "M_I_CPU0_SA_DQS_DP<3>")
	)
	(segment
		(start 415.604706 -228.059996)
		(end 417.83381 -228.059996)
		(width 0.16002)
		(layer "In2.Cu")
		(net "M_I_CPU0_SA_DQS_DP<3>")
	)
	(segment
		(start 380.20625 -241.56924)
		(end 380.214632 -241.574066)
		(width 0.09525)
		(layer "In2.Cu")
		(net "M_I_CPU0_SA_DQS_DP<3>")
	)
	(segment
		(start 413.580326 -229.21722)
		(end 413.92221 -229.21722)
		(width 0.16002)
		(layer "In2.Cu")
		(net "M_I_CPU0_SA_DQS_DP<3>")
	)
	(segment
		(start 393.084812 -241.493294)
		(end 393.417552 -241.493294)
		(width 0.09525)
		(layer "In2.Cu")
		(net "M_I_CPU0_SA_DQS_DP<3>")
	)
	(segment
		(start 381.146304 -241.56924)
		(end 381.154686 -241.574066)
		(width 0.09525)
		(layer "In2.Cu")
		(net "M_I_CPU0_SA_DQS_DP<3>")
	)
	(segment
		(start 379.635004 -241.574066)
		(end 379.643386 -241.56924)
		(width 0.09525)
		(layer "In2.Cu")
		(net "M_I_CPU0_SA_DQS_DP<3>")
	)
	(segment
		(start 425.999656 -228.634036)
		(end 428.084996 -228.634036)
		(width 0.16002)
		(layer "In2.Cu")
		(net "M_I_CPU0_SA_DQS_DP<3>")
	)
	(segment
		(start 399.016728 -240.055146)
		(end 403.585172 -235.486702)
		(width 0.16002)
		(layer "In2.Cu")
		(net "M_I_CPU0_SA_DQS_DP<3>")
	)
	(segment
		(start 415.288222 -228.37648)
		(end 415.604706 -228.059996)
		(width 0.16002)
		(layer "In2.Cu")
		(net "M_I_CPU0_SA_DQS_DP<3>")
	)
	(segment
		(start 429.906684 -229.05974)
		(end 430.023524 -228.9429)
		(width 0.16002)
		(layer "In2.Cu")
		(net "M_I_CPU0_SA_DQS_DP<3>")
	)
	(segment
		(start 414.76295 -228.37648)
		(end 415.288222 -228.37648)
		(width 0.16002)
		(layer "In2.Cu")
		(net "M_I_CPU0_SA_DQS_DP<3>")
	)
	(segment
		(start 409.553156 -230.89997)
		(end 409.553156 -230.633778)
		(width 0.16002)
		(layer "In2.Cu")
		(net "M_I_CPU0_SA_DQS_DP<3>")
	)
	(segment
		(start 422.832276 -228.37648)
		(end 423.14876 -228.059996)
		(width 0.16002)
		(layer "In2.Cu")
		(net "M_I_CPU0_SA_DQS_DP<3>")
	)
	(segment
		(start 395.686026 -240.055146)
		(end 399.016728 -240.055146)
		(width 0.16002)
		(layer "In2.Cu")
		(net "M_I_CPU0_SA_DQS_DP<3>")
	)
	(segment
		(start 391.863326 -241.56924)
		(end 391.87374 -241.563144)
		(width 0.09525)
		(layer "In2.Cu")
		(net "M_I_CPU0_SA_DQS_DP<3>")
	)
	(segment
		(start 421.466264 -229.21722)
		(end 422.307004 -228.37648)
		(width 0.16002)
		(layer "In2.Cu")
		(net "M_I_CPU0_SA_DQS_DP<3>")
	)
	(segment
		(start 423.14876 -228.059996)
		(end 425.425616 -228.059996)
		(width 0.16002)
		(layer "In2.Cu")
		(net "M_I_CPU0_SA_DQS_DP<3>")
	)
	(segment
		(start 431.281586 -229.05974)
		(end 431.55616 -228.785166)
		(width 0.16002)
		(layer "In2.Cu")
		(net "M_I_CPU0_SA_DQS_DP<3>")
	)
	(segment
		(start 418.683694 -228.90988)
		(end 420.81704 -228.90988)
		(width 0.16002)
		(layer "In2.Cu")
		(net "M_I_CPU0_SA_DQS_DP<3>")
	)
	(arc
		(start 381.154686 -241.574066)
		(mid 381.339718 -241.61998)
		(end 381.523494 -241.56924)
		(width 0.09525)
		(layer "In2.Cu")
		(net "M_I_CPU0_SA_DQS_DP<3>")
	)
	(arc
		(start 381.523494 -241.56924)
		(mid 381.804926 -241.493485)
		(end 382.086358 -241.56924)
		(width 0.09525)
		(layer "In2.Cu")
		(net "M_I_CPU0_SA_DQS_DP<3>")
	)
	(arc
		(start 386.22351 -241.56924)
		(mid 386.504942 -241.493485)
		(end 386.786374 -241.56924)
		(width 0.09525)
		(layer "In2.Cu")
		(net "M_I_CPU0_SA_DQS_DP<3>")
	)
	(arc
		(start 385.283456 -241.56924)
		(mid 385.564888 -241.493485)
		(end 385.84632 -241.56924)
		(width 0.09525)
		(layer "In2.Cu")
		(net "M_I_CPU0_SA_DQS_DP<3>")
	)
	(arc
		(start 390.546336 -241.56924)
		(mid 390.734804 -241.619917)
		(end 390.923272 -241.56924)
		(width 0.09525)
		(layer "In2.Cu")
		(net "M_I_CPU0_SA_DQS_DP<3>")
	)
	(arc
		(start 390.923272 -241.56924)
		(mid 391.204704 -241.493485)
		(end 391.486136 -241.56924)
		(width 0.09525)
		(layer "In2.Cu")
		(net "M_I_CPU0_SA_DQS_DP<3>")
	)
	(arc
		(start 392.803126 -241.56924)
		(mid 392.938948 -241.51266)
		(end 393.084812 -241.493294)
		(width 0.09525)
		(layer "In2.Cu")
		(net "M_I_CPU0_SA_DQS_DP<3>")
	)
	(arc
		(start 389.983472 -241.56924)
		(mid 390.264904 -241.493485)
		(end 390.546336 -241.56924)
		(width 0.09525)
		(layer "In2.Cu")
		(net "M_I_CPU0_SA_DQS_DP<3>")
	)
	(arc
		(start 384.914648 -241.574066)
		(mid 385.09968 -241.61998)
		(end 385.283456 -241.56924)
		(width 0.09525)
		(layer "In2.Cu")
		(net "M_I_CPU0_SA_DQS_DP<3>")
	)
	(arc
		(start 380.214632 -241.574066)
		(mid 380.399664 -241.61998)
		(end 380.58344 -241.56924)
		(width 0.09525)
		(layer "In2.Cu")
		(net "M_I_CPU0_SA_DQS_DP<3>")
	)
	(arc
		(start 377.444 -241.596164)
		(mid 377.606651 -241.618424)
		(end 377.763278 -241.56924)
		(width 0.09525)
		(layer "In2.Cu")
		(net "M_I_CPU0_SA_DQS_DP<3>")
	)
	(arc
		(start 379.266196 -241.56924)
		(mid 379.449971 -241.620012)
		(end 379.635004 -241.574066)
		(width 0.09525)
		(layer "In2.Cu")
		(net "M_I_CPU0_SA_DQS_DP<3>")
	)
	(arc
		(start 389.043418 -241.56924)
		(mid 389.32485 -241.493485)
		(end 389.606282 -241.56924)
		(width 0.09525)
		(layer "In2.Cu")
		(net "M_I_CPU0_SA_DQS_DP<3>")
	)
	(arc
		(start 378.326142 -241.56924)
		(mid 378.509917 -241.620012)
		(end 378.69495 -241.574066)
		(width 0.09525)
		(layer "In2.Cu")
		(net "M_I_CPU0_SA_DQS_DP<3>")
	)
	(arc
		(start 379.643386 -241.56924)
		(mid 379.924818 -241.493485)
		(end 380.20625 -241.56924)
		(width 0.09525)
		(layer "In2.Cu")
		(net "M_I_CPU0_SA_DQS_DP<3>")
	)
	(arc
		(start 385.854702 -241.574066)
		(mid 386.039734 -241.61998)
		(end 386.22351 -241.56924)
		(width 0.09525)
		(layer "In2.Cu")
		(net "M_I_CPU0_SA_DQS_DP<3>")
	)
	(arc
		(start 386.786374 -241.56924)
		(mid 386.974842 -241.619917)
		(end 387.16331 -241.56924)
		(width 0.09525)
		(layer "In2.Cu")
		(net "M_I_CPU0_SA_DQS_DP<3>")
	)
	(arc
		(start 383.403348 -241.56924)
		(mid 383.68478 -241.493485)
		(end 383.966212 -241.56924)
		(width 0.09525)
		(layer "In2.Cu")
		(net "M_I_CPU0_SA_DQS_DP<3>")
	)
	(arc
		(start 392.434318 -241.574066)
		(mid 392.61935 -241.61998)
		(end 392.803126 -241.56924)
		(width 0.09525)
		(layer "In2.Cu")
		(net "M_I_CPU0_SA_DQS_DP<3>")
	)
	(arc
		(start 383.026158 -241.56924)
		(mid 383.209933 -241.620012)
		(end 383.394966 -241.574066)
		(width 0.09525)
		(layer "In2.Cu")
		(net "M_I_CPU0_SA_DQS_DP<3>")
	)
	(arc
		(start 383.966212 -241.56924)
		(mid 384.149987 -241.620012)
		(end 384.33502 -241.574066)
		(width 0.09525)
		(layer "In2.Cu")
		(net "M_I_CPU0_SA_DQS_DP<3>")
	)
	(arc
		(start 382.463294 -241.56924)
		(mid 382.744726 -241.493485)
		(end 383.026158 -241.56924)
		(width 0.09525)
		(layer "In2.Cu")
		(net "M_I_CPU0_SA_DQS_DP<3>")
	)
	(arc
		(start 387.726174 -241.56924)
		(mid 387.909949 -241.620012)
		(end 388.094982 -241.574066)
		(width 0.09525)
		(layer "In2.Cu")
		(net "M_I_CPU0_SA_DQS_DP<3>")
	)
	(arc
		(start 389.614664 -241.574066)
		(mid 389.799696 -241.61998)
		(end 389.983472 -241.56924)
		(width 0.09525)
		(layer "In2.Cu")
		(net "M_I_CPU0_SA_DQS_DP<3>")
	)
	(arc
		(start 388.103364 -241.56924)
		(mid 388.384796 -241.493485)
		(end 388.666228 -241.56924)
		(width 0.09525)
		(layer "In2.Cu")
		(net "M_I_CPU0_SA_DQS_DP<3>")
	)
	(arc
		(start 378.703332 -241.56924)
		(mid 378.984764 -241.493485)
		(end 379.266196 -241.56924)
		(width 0.09525)
		(layer "In2.Cu")
		(net "M_I_CPU0_SA_DQS_DP<3>")
	)
	(arc
		(start 380.58344 -241.56924)
		(mid 380.864872 -241.493485)
		(end 381.146304 -241.56924)
		(width 0.09525)
		(layer "In2.Cu")
		(net "M_I_CPU0_SA_DQS_DP<3>")
	)
	(arc
		(start 391.87374 -241.563144)
		(mid 392.150648 -241.493467)
		(end 392.425936 -241.56924)
		(width 0.09525)
		(layer "In2.Cu")
		(net "M_I_CPU0_SA_DQS_DP<3>")
	)
	(arc
		(start 377.763278 -241.56924)
		(mid 378.04471 -241.493485)
		(end 378.326142 -241.56924)
		(width 0.09525)
		(layer "In2.Cu")
		(net "M_I_CPU0_SA_DQS_DP<3>")
	)
	(arc
		(start 388.666228 -241.56924)
		(mid 388.850003 -241.620012)
		(end 389.035036 -241.574066)
		(width 0.09525)
		(layer "In2.Cu")
		(net "M_I_CPU0_SA_DQS_DP<3>")
	)
	(arc
		(start 391.486136 -241.56924)
		(mid 391.669911 -241.620012)
		(end 391.854944 -241.574066)
		(width 0.09525)
		(layer "In2.Cu")
		(net "M_I_CPU0_SA_DQS_DP<3>")
	)
	(arc
		(start 382.086358 -241.56924)
		(mid 382.274826 -241.619917)
		(end 382.463294 -241.56924)
		(width 0.09525)
		(layer "In2.Cu")
		(net "M_I_CPU0_SA_DQS_DP<3>")
	)
	(arc
		(start 384.343402 -241.56924)
		(mid 384.624834 -241.493485)
		(end 384.906266 -241.56924)
		(width 0.09525)
		(layer "In2.Cu")
		(net "M_I_CPU0_SA_DQS_DP<3>")
	)
	(arc
		(start 387.16331 -241.56924)
		(mid 387.444742 -241.493485)
		(end 387.726174 -241.56924)
		(width 0.09525)
		(layer "In2.Cu")
		(net "M_I_CPU0_SA_DQS_DP<3>")
	)
	(segment
		(start 377.107958 -236.650022)
		(end 377.57481 -236.384084)
		(width 0.12954)
		(layer "F.Cu")
		(net "M_I_CPU0_SA_DQS_DP<2>")
	)
	(segment
		(start 395.628622 -234.202224)
		(end 395.645386 -234.18546)
		(width 0.09525)
		(layer "In2.Cu")
		(net "M_I_CPU0_SA_DQS_DP<2>")
	)
	(segment
		(start 381.146304 -236.709204)
		(end 381.154686 -236.71403)
		(width 0.09525)
		(layer "In2.Cu")
		(net "M_I_CPU0_SA_DQS_DP<2>")
	)
	(segment
		(start 395.628622 -234.286044)
		(end 395.628622 -234.202224)
		(width 0.09525)
		(layer "In2.Cu")
		(net "M_I_CPU0_SA_DQS_DP<2>")
	)
	(segment
		(start 388.094982 -236.71403)
		(end 388.103364 -236.709204)
		(width 0.09525)
		(layer "In2.Cu")
		(net "M_I_CPU0_SA_DQS_DP<2>")
	)
	(segment
		(start 389.606282 -236.709204)
		(end 389.614664 -236.71403)
		(width 0.09525)
		(layer "In2.Cu")
		(net "M_I_CPU0_SA_DQS_DP<2>")
	)
	(segment
		(start 413.272986 -219.559886)
		(end 413.580326 -219.867226)
		(width 0.16002)
		(layer "In2.Cu")
		(net "M_I_CPU0_SA_DQS_DP<2>")
	)
	(segment
		(start 429.713136 -219.892626)
		(end 429.896016 -219.709746)
		(width 0.16002)
		(layer "In2.Cu")
		(net "M_I_CPU0_SA_DQS_DP<2>")
	)
	(segment
		(start 428.69358 -219.892626)
		(end 429.713136 -219.892626)
		(width 0.16002)
		(layer "In2.Cu")
		(net "M_I_CPU0_SA_DQS_DP<2>")
	)
	(segment
		(start 413.92221 -219.867226)
		(end 414.76295 -219.026486)
		(width 0.16002)
		(layer "In2.Cu")
		(net "M_I_CPU0_SA_DQS_DP<2>")
	)
	(segment
		(start 414.76295 -219.026486)
		(end 415.288222 -219.026486)
		(width 0.16002)
		(layer "In2.Cu")
		(net "M_I_CPU0_SA_DQS_DP<2>")
	)
	(segment
		(start 422.307004 -219.026486)
		(end 422.832276 -219.026486)
		(width 0.16002)
		(layer "In2.Cu")
		(net "M_I_CPU0_SA_DQS_DP<2>")
	)
	(segment
		(start 418.683694 -219.559886)
		(end 420.81704 -219.559886)
		(width 0.16002)
		(layer "In2.Cu")
		(net "M_I_CPU0_SA_DQS_DP<2>")
	)
	(segment
		(start 420.81704 -219.559886)
		(end 421.12438 -219.867226)
		(width 0.16002)
		(layer "In2.Cu")
		(net "M_I_CPU0_SA_DQS_DP<2>")
	)
	(segment
		(start 394.033756 -234.816142)
		(end 394.40358 -234.446318)
		(width 0.09525)
		(layer "In2.Cu")
		(net "M_I_CPU0_SA_DQS_DP<2>")
	)
	(segment
		(start 429.896016 -219.709746)
		(end 431.281586 -219.709746)
		(width 0.16002)
		(layer "In2.Cu")
		(net "M_I_CPU0_SA_DQS_DP<2>")
	)
	(segment
		(start 385.84632 -236.709204)
		(end 385.854702 -236.71403)
		(width 0.09525)
		(layer "In2.Cu")
		(net "M_I_CPU0_SA_DQS_DP<2>")
	)
	(segment
		(start 394.40358 -234.446318)
		(end 395.468348 -234.446318)
		(width 0.09525)
		(layer "In2.Cu")
		(net "M_I_CPU0_SA_DQS_DP<2>")
	)
	(segment
		(start 423.14876 -218.710002)
		(end 425.425616 -218.710002)
		(width 0.16002)
		(layer "In2.Cu")
		(net "M_I_CPU0_SA_DQS_DP<2>")
	)
	(segment
		(start 395.468348 -234.446318)
		(end 395.628622 -234.286044)
		(width 0.09525)
		(layer "In2.Cu")
		(net "M_I_CPU0_SA_DQS_DP<2>")
	)
	(segment
		(start 380.20625 -236.709204)
		(end 380.214632 -236.71403)
		(width 0.09525)
		(layer "In2.Cu")
		(net "M_I_CPU0_SA_DQS_DP<2>")
	)
	(segment
		(start 410.27096 -219.559886)
		(end 413.272986 -219.559886)
		(width 0.16002)
		(layer "In2.Cu")
		(net "M_I_CPU0_SA_DQS_DP<2>")
	)
	(segment
		(start 421.466264 -219.867226)
		(end 422.307004 -219.026486)
		(width 0.16002)
		(layer "In2.Cu")
		(net "M_I_CPU0_SA_DQS_DP<2>")
	)
	(segment
		(start 383.394966 -236.71403)
		(end 383.403348 -236.709204)
		(width 0.09525)
		(layer "In2.Cu")
		(net "M_I_CPU0_SA_DQS_DP<2>")
	)
	(segment
		(start 378.69495 -236.71403)
		(end 378.703332 -236.709204)
		(width 0.09525)
		(layer "In2.Cu")
		(net "M_I_CPU0_SA_DQS_DP<2>")
	)
	(segment
		(start 417.83381 -218.710002)
		(end 418.683694 -219.559886)
		(width 0.16002)
		(layer "In2.Cu")
		(net "M_I_CPU0_SA_DQS_DP<2>")
	)
	(segment
		(start 395.645386 -234.18546)
		(end 410.27096 -219.559886)
		(width 0.16002)
		(layer "In2.Cu")
		(net "M_I_CPU0_SA_DQS_DP<2>")
	)
	(segment
		(start 379.635004 -236.71403)
		(end 379.643386 -236.709204)
		(width 0.09525)
		(layer "In2.Cu")
		(net "M_I_CPU0_SA_DQS_DP<2>")
	)
	(segment
		(start 415.288222 -219.026486)
		(end 415.604706 -218.710002)
		(width 0.16002)
		(layer "In2.Cu")
		(net "M_I_CPU0_SA_DQS_DP<2>")
	)
	(segment
		(start 425.425616 -218.710002)
		(end 425.999656 -219.284042)
		(width 0.16002)
		(layer "In2.Cu")
		(net "M_I_CPU0_SA_DQS_DP<2>")
	)
	(segment
		(start 377.57481 -236.384084)
		(end 377.420886 -236.649514)
		(width 0.09525)
		(layer "In2.Cu")
		(net "M_I_CPU0_SA_DQS_DP<2>")
	)
	(segment
		(start 415.604706 -218.710002)
		(end 417.83381 -218.710002)
		(width 0.16002)
		(layer "In2.Cu")
		(net "M_I_CPU0_SA_DQS_DP<2>")
	)
	(segment
		(start 392.560048 -236.03077)
		(end 393.548108 -236.03077)
		(width 0.09525)
		(layer "In2.Cu")
		(net "M_I_CPU0_SA_DQS_DP<2>")
	)
	(segment
		(start 422.832276 -219.026486)
		(end 423.14876 -218.710002)
		(width 0.16002)
		(layer "In2.Cu")
		(net "M_I_CPU0_SA_DQS_DP<2>")
	)
	(segment
		(start 389.035036 -236.71403)
		(end 389.043418 -236.709204)
		(width 0.09525)
		(layer "In2.Cu")
		(net "M_I_CPU0_SA_DQS_DP<2>")
	)
	(segment
		(start 391.940542 -236.650022)
		(end 392.378692 -236.212126)
		(width 0.09525)
		(layer "In2.Cu")
		(net "M_I_CPU0_SA_DQS_DP<2>")
	)
	(segment
		(start 421.12438 -219.867226)
		(end 421.466264 -219.867226)
		(width 0.16002)
		(layer "In2.Cu")
		(net "M_I_CPU0_SA_DQS_DP<2>")
	)
	(segment
		(start 384.906266 -236.709204)
		(end 384.914648 -236.71403)
		(width 0.09525)
		(layer "In2.Cu")
		(net "M_I_CPU0_SA_DQS_DP<2>")
	)
	(segment
		(start 428.084996 -219.284042)
		(end 428.69358 -219.892626)
		(width 0.16002)
		(layer "In2.Cu")
		(net "M_I_CPU0_SA_DQS_DP<2>")
	)
	(segment
		(start 413.580326 -219.867226)
		(end 413.92221 -219.867226)
		(width 0.16002)
		(layer "In2.Cu")
		(net "M_I_CPU0_SA_DQS_DP<2>")
	)
	(segment
		(start 384.33502 -236.71403)
		(end 384.343402 -236.709204)
		(width 0.09525)
		(layer "In2.Cu")
		(net "M_I_CPU0_SA_DQS_DP<2>")
	)
	(segment
		(start 425.999656 -219.284042)
		(end 428.084996 -219.284042)
		(width 0.16002)
		(layer "In2.Cu")
		(net "M_I_CPU0_SA_DQS_DP<2>")
	)
	(segment
		(start 394.033756 -235.545122)
		(end 394.033756 -234.816142)
		(width 0.09525)
		(layer "In2.Cu")
		(net "M_I_CPU0_SA_DQS_DP<2>")
	)
	(segment
		(start 393.548108 -236.03077)
		(end 394.033756 -235.545122)
		(width 0.09525)
		(layer "In2.Cu")
		(net "M_I_CPU0_SA_DQS_DP<2>")
	)
	(segment
		(start 392.378692 -236.212126)
		(end 392.560048 -236.03077)
		(width 0.09525)
		(layer "In2.Cu")
		(net "M_I_CPU0_SA_DQS_DP<2>")
	)
	(segment
		(start 391.940542 -236.649768)
		(end 391.940542 -236.650022)
		(width 0.09525)
		(layer "In2.Cu")
		(net "M_I_CPU0_SA_DQS_DP<2>")
	)
	(segment
		(start 377.420886 -236.649514)
		(end 377.444 -236.736128)
		(width 0.09525)
		(layer "In2.Cu")
		(net "M_I_CPU0_SA_DQS_DP<2>")
	)
	(segment
		(start 431.281586 -219.709746)
		(end 431.55616 -219.435172)
		(width 0.16002)
		(layer "In2.Cu")
		(net "M_I_CPU0_SA_DQS_DP<2>")
	)
	(arc
		(start 382.463294 -236.709204)
		(mid 382.744726 -236.633449)
		(end 383.026158 -236.709204)
		(width 0.09525)
		(layer "In2.Cu")
		(net "M_I_CPU0_SA_DQS_DP<2>")
	)
	(arc
		(start 383.403348 -236.709204)
		(mid 383.68478 -236.633449)
		(end 383.966212 -236.709204)
		(width 0.09525)
		(layer "In2.Cu")
		(net "M_I_CPU0_SA_DQS_DP<2>")
	)
	(arc
		(start 381.523494 -236.709204)
		(mid 381.804926 -236.633449)
		(end 382.086358 -236.709204)
		(width 0.09525)
		(layer "In2.Cu")
		(net "M_I_CPU0_SA_DQS_DP<2>")
	)
	(arc
		(start 378.326142 -236.709204)
		(mid 378.509917 -236.759976)
		(end 378.69495 -236.71403)
		(width 0.09525)
		(layer "In2.Cu")
		(net "M_I_CPU0_SA_DQS_DP<2>")
	)
	(arc
		(start 377.763278 -236.709204)
		(mid 378.04471 -236.633449)
		(end 378.326142 -236.709204)
		(width 0.09525)
		(layer "In2.Cu")
		(net "M_I_CPU0_SA_DQS_DP<2>")
	)
	(arc
		(start 386.786374 -236.709204)
		(mid 386.974842 -236.759881)
		(end 387.16331 -236.709204)
		(width 0.09525)
		(layer "In2.Cu")
		(net "M_I_CPU0_SA_DQS_DP<2>")
	)
	(arc
		(start 383.966212 -236.709204)
		(mid 384.149987 -236.759976)
		(end 384.33502 -236.71403)
		(width 0.09525)
		(layer "In2.Cu")
		(net "M_I_CPU0_SA_DQS_DP<2>")
	)
	(arc
		(start 378.703332 -236.709204)
		(mid 378.984764 -236.633449)
		(end 379.266196 -236.709204)
		(width 0.09525)
		(layer "In2.Cu")
		(net "M_I_CPU0_SA_DQS_DP<2>")
	)
	(arc
		(start 387.726174 -236.709204)
		(mid 387.909949 -236.759976)
		(end 388.094982 -236.71403)
		(width 0.09525)
		(layer "In2.Cu")
		(net "M_I_CPU0_SA_DQS_DP<2>")
	)
	(arc
		(start 379.643386 -236.709204)
		(mid 379.924818 -236.633449)
		(end 380.20625 -236.709204)
		(width 0.09525)
		(layer "In2.Cu")
		(net "M_I_CPU0_SA_DQS_DP<2>")
	)
	(arc
		(start 381.154686 -236.71403)
		(mid 381.339718 -236.759944)
		(end 381.523494 -236.709204)
		(width 0.09525)
		(layer "In2.Cu")
		(net "M_I_CPU0_SA_DQS_DP<2>")
	)
	(arc
		(start 383.026158 -236.709204)
		(mid 383.209933 -236.759976)
		(end 383.394966 -236.71403)
		(width 0.09525)
		(layer "In2.Cu")
		(net "M_I_CPU0_SA_DQS_DP<2>")
	)
	(arc
		(start 391.486136 -236.709204)
		(mid 391.723418 -236.756697)
		(end 391.940542 -236.649768)
		(width 0.09525)
		(layer "In2.Cu")
		(net "M_I_CPU0_SA_DQS_DP<2>")
	)
	(arc
		(start 377.444 -236.736128)
		(mid 377.606651 -236.758388)
		(end 377.763278 -236.709204)
		(width 0.09525)
		(layer "In2.Cu")
		(net "M_I_CPU0_SA_DQS_DP<2>")
	)
	(arc
		(start 385.854702 -236.71403)
		(mid 386.039734 -236.759944)
		(end 386.22351 -236.709204)
		(width 0.09525)
		(layer "In2.Cu")
		(net "M_I_CPU0_SA_DQS_DP<2>")
	)
	(arc
		(start 382.086358 -236.709204)
		(mid 382.274826 -236.759881)
		(end 382.463294 -236.709204)
		(width 0.09525)
		(layer "In2.Cu")
		(net "M_I_CPU0_SA_DQS_DP<2>")
	)
	(arc
		(start 389.614664 -236.71403)
		(mid 389.799696 -236.759944)
		(end 389.983472 -236.709204)
		(width 0.09525)
		(layer "In2.Cu")
		(net "M_I_CPU0_SA_DQS_DP<2>")
	)
	(arc
		(start 380.214632 -236.71403)
		(mid 380.399664 -236.759944)
		(end 380.58344 -236.709204)
		(width 0.09525)
		(layer "In2.Cu")
		(net "M_I_CPU0_SA_DQS_DP<2>")
	)
	(arc
		(start 389.983472 -236.709204)
		(mid 390.264904 -236.633449)
		(end 390.546336 -236.709204)
		(width 0.09525)
		(layer "In2.Cu")
		(net "M_I_CPU0_SA_DQS_DP<2>")
	)
	(arc
		(start 379.266196 -236.709204)
		(mid 379.449971 -236.759976)
		(end 379.635004 -236.71403)
		(width 0.09525)
		(layer "In2.Cu")
		(net "M_I_CPU0_SA_DQS_DP<2>")
	)
	(arc
		(start 384.914648 -236.71403)
		(mid 385.09968 -236.759944)
		(end 385.283456 -236.709204)
		(width 0.09525)
		(layer "In2.Cu")
		(net "M_I_CPU0_SA_DQS_DP<2>")
	)
	(arc
		(start 386.22351 -236.709204)
		(mid 386.504942 -236.633449)
		(end 386.786374 -236.709204)
		(width 0.09525)
		(layer "In2.Cu")
		(net "M_I_CPU0_SA_DQS_DP<2>")
	)
	(arc
		(start 390.923272 -236.709204)
		(mid 391.204704 -236.633449)
		(end 391.486136 -236.709204)
		(width 0.09525)
		(layer "In2.Cu")
		(net "M_I_CPU0_SA_DQS_DP<2>")
	)
	(arc
		(start 389.043418 -236.709204)
		(mid 389.32485 -236.633449)
		(end 389.606282 -236.709204)
		(width 0.09525)
		(layer "In2.Cu")
		(net "M_I_CPU0_SA_DQS_DP<2>")
	)
	(arc
		(start 390.546336 -236.709204)
		(mid 390.734804 -236.759881)
		(end 390.923272 -236.709204)
		(width 0.09525)
		(layer "In2.Cu")
		(net "M_I_CPU0_SA_DQS_DP<2>")
	)
	(arc
		(start 385.283456 -236.709204)
		(mid 385.564888 -236.633449)
		(end 385.84632 -236.709204)
		(width 0.09525)
		(layer "In2.Cu")
		(net "M_I_CPU0_SA_DQS_DP<2>")
	)
	(arc
		(start 387.16331 -236.709204)
		(mid 387.444742 -236.633449)
		(end 387.726174 -236.709204)
		(width 0.09525)
		(layer "In2.Cu")
		(net "M_I_CPU0_SA_DQS_DP<2>")
	)
	(arc
		(start 388.666228 -236.709204)
		(mid 388.850003 -236.759976)
		(end 389.035036 -236.71403)
		(width 0.09525)
		(layer "In2.Cu")
		(net "M_I_CPU0_SA_DQS_DP<2>")
	)
	(arc
		(start 388.103364 -236.709204)
		(mid 388.384796 -236.633449)
		(end 388.666228 -236.709204)
		(width 0.09525)
		(layer "In2.Cu")
		(net "M_I_CPU0_SA_DQS_DP<2>")
	)
	(arc
		(start 380.58344 -236.709204)
		(mid 380.864872 -236.633449)
		(end 381.146304 -236.709204)
		(width 0.09525)
		(layer "In2.Cu")
		(net "M_I_CPU0_SA_DQS_DP<2>")
	)
	(arc
		(start 384.343402 -236.709204)
		(mid 384.624834 -236.633449)
		(end 384.906266 -236.709204)
		(width 0.09525)
		(layer "In2.Cu")
		(net "M_I_CPU0_SA_DQS_DP<2>")
	)
	(segment
		(start 377.107958 -231.789986)
		(end 377.57481 -231.524048)
		(width 0.12954)
		(layer "F.Cu")
		(net "M_I_CPU0_SA_DQS_DP<1>")
	)
	(segment
		(start 393.708128 -227.009452)
		(end 393.74318 -226.989132)
		(width 0.09525)
		(layer "In2.Cu")
		(net "M_I_CPU0_SA_DQS_DP<1>")
	)
	(segment
		(start 383.394966 -231.853994)
		(end 383.403348 -231.849168)
		(width 0.09525)
		(layer "In2.Cu")
		(net "M_I_CPU0_SA_DQS_DP<1>")
	)
	(segment
		(start 391.863326 -230.229156)
		(end 391.895838 -230.21036)
		(width 0.09525)
		(layer "In2.Cu")
		(net "M_I_CPU0_SA_DQS_DP<1>")
	)
	(segment
		(start 417.83381 -209.360008)
		(end 418.683694 -210.209892)
		(width 0.16002)
		(layer "In2.Cu")
		(net "M_I_CPU0_SA_DQS_DP<1>")
	)
	(segment
		(start 393.74318 -226.989132)
		(end 393.82573 -226.94138)
		(width 0.09525)
		(layer "In2.Cu")
		(net "M_I_CPU0_SA_DQS_DP<1>")
	)
	(segment
		(start 421.12438 -210.517232)
		(end 421.466264 -210.517232)
		(width 0.16002)
		(layer "In2.Cu")
		(net "M_I_CPU0_SA_DQS_DP<1>")
	)
	(segment
		(start 392.33348 -229.419404)
		(end 392.364976 -229.401116)
		(width 0.09525)
		(layer "In2.Cu")
		(net "M_I_CPU0_SA_DQS_DP<1>")
	)
	(segment
		(start 393.82573 -226.94138)
		(end 393.910058 -226.857052)
		(width 0.09525)
		(layer "In2.Cu")
		(net "M_I_CPU0_SA_DQS_DP<1>")
	)
	(segment
		(start 420.81704 -210.209892)
		(end 421.12438 -210.517232)
		(width 0.16002)
		(layer "In2.Cu")
		(net "M_I_CPU0_SA_DQS_DP<1>")
	)
	(segment
		(start 392.76528 -228.631496)
		(end 392.80338 -228.609398)
		(width 0.09525)
		(layer "In2.Cu")
		(net "M_I_CPU0_SA_DQS_DP<1>")
	)
	(segment
		(start 395.304518 -225.27895)
		(end 395.304518 -224.765362)
		(width 0.16002)
		(layer "In2.Cu")
		(net "M_I_CPU0_SA_DQS_DP<1>")
	)
	(segment
		(start 403.63521 -214.943182)
		(end 408.3685 -210.209892)
		(width 0.16002)
		(layer "In2.Cu")
		(net "M_I_CPU0_SA_DQS_DP<1>")
	)
	(segment
		(start 381.146304 -231.849168)
		(end 381.154686 -231.853994)
		(width 0.09525)
		(layer "In2.Cu")
		(net "M_I_CPU0_SA_DQS_DP<1>")
	)
	(segment
		(start 394.87475 -225.708972)
		(end 394.891514 -225.692208)
		(width 0.09525)
		(layer "In2.Cu")
		(net "M_I_CPU0_SA_DQS_DP<1>")
	)
	(segment
		(start 422.832276 -209.676492)
		(end 423.14876 -209.360008)
		(width 0.16002)
		(layer "In2.Cu")
		(net "M_I_CPU0_SA_DQS_DP<1>")
	)
	(segment
		(start 384.906266 -231.849168)
		(end 384.914648 -231.853994)
		(width 0.09525)
		(layer "In2.Cu")
		(net "M_I_CPU0_SA_DQS_DP<1>")
	)
	(segment
		(start 378.69495 -231.853994)
		(end 378.703332 -231.849168)
		(width 0.09525)
		(layer "In2.Cu")
		(net "M_I_CPU0_SA_DQS_DP<1>")
	)
	(segment
		(start 403.63521 -216.43467)
		(end 403.63521 -214.943182)
		(width 0.16002)
		(layer "In2.Cu")
		(net "M_I_CPU0_SA_DQS_DP<1>")
	)
	(segment
		(start 393.273534 -227.799392)
		(end 393.302744 -227.782628)
		(width 0.09525)
		(layer "In2.Cu")
		(net "M_I_CPU0_SA_DQS_DP<1>")
	)
	(segment
		(start 394.264388 -226.103942)
		(end 394.5636 -226.103942)
		(width 0.09525)
		(layer "In2.Cu")
		(net "M_I_CPU0_SA_DQS_DP<1>")
	)
	(segment
		(start 391.35304 -231.063038)
		(end 391.393426 -231.039416)
		(width 0.09525)
		(layer "In2.Cu")
		(net "M_I_CPU0_SA_DQS_DP<1>")
	)
	(segment
		(start 384.33502 -231.853994)
		(end 384.343402 -231.849168)
		(width 0.09525)
		(layer "In2.Cu")
		(net "M_I_CPU0_SA_DQS_DP<1>")
	)
	(segment
		(start 388.094982 -231.853994)
		(end 388.103364 -231.849168)
		(width 0.09525)
		(layer "In2.Cu")
		(net "M_I_CPU0_SA_DQS_DP<1>")
	)
	(segment
		(start 377.57481 -231.524048)
		(end 377.420886 -231.789478)
		(width 0.09525)
		(layer "In2.Cu")
		(net "M_I_CPU0_SA_DQS_DP<1>")
	)
	(segment
		(start 418.683694 -210.209892)
		(end 420.81704 -210.209892)
		(width 0.16002)
		(layer "In2.Cu")
		(net "M_I_CPU0_SA_DQS_DP<1>")
	)
	(segment
		(start 413.580326 -210.517232)
		(end 413.92221 -210.517232)
		(width 0.16002)
		(layer "In2.Cu")
		(net "M_I_CPU0_SA_DQS_DP<1>")
	)
	(segment
		(start 379.635004 -231.853994)
		(end 379.643386 -231.849168)
		(width 0.09525)
		(layer "In2.Cu")
		(net "M_I_CPU0_SA_DQS_DP<1>")
	)
	(segment
		(start 394.5636 -226.103942)
		(end 394.87475 -225.792792)
		(width 0.09525)
		(layer "In2.Cu")
		(net "M_I_CPU0_SA_DQS_DP<1>")
	)
	(segment
		(start 408.3685 -210.209892)
		(end 413.272986 -210.209892)
		(width 0.16002)
		(layer "In2.Cu")
		(net "M_I_CPU0_SA_DQS_DP<1>")
	)
	(segment
		(start 392.293094 -229.443026)
		(end 392.33348 -229.419404)
		(width 0.09525)
		(layer "In2.Cu")
		(net "M_I_CPU0_SA_DQS_DP<1>")
	)
	(segment
		(start 393.910058 -226.458272)
		(end 394.264388 -226.103942)
		(width 0.09525)
		(layer "In2.Cu")
		(net "M_I_CPU0_SA_DQS_DP<1>")
	)
	(segment
		(start 390.923272 -231.849168)
		(end 390.955784 -231.830372)
		(width 0.09525)
		(layer "In2.Cu")
		(net "M_I_CPU0_SA_DQS_DP<1>")
	)
	(segment
		(start 393.235434 -227.82149)
		(end 393.273534 -227.799392)
		(width 0.09525)
		(layer "In2.Cu")
		(net "M_I_CPU0_SA_DQS_DP<1>")
	)
	(segment
		(start 422.307004 -209.676492)
		(end 422.832276 -209.676492)
		(width 0.16002)
		(layer "In2.Cu")
		(net "M_I_CPU0_SA_DQS_DP<1>")
	)
	(segment
		(start 421.466264 -210.517232)
		(end 422.307004 -209.676492)
		(width 0.16002)
		(layer "In2.Cu")
		(net "M_I_CPU0_SA_DQS_DP<1>")
	)
	(segment
		(start 431.281586 -210.359752)
		(end 431.55616 -210.085178)
		(width 0.16002)
		(layer "In2.Cu")
		(net "M_I_CPU0_SA_DQS_DP<1>")
	)
	(segment
		(start 389.035036 -231.853994)
		(end 389.043418 -231.849168)
		(width 0.09525)
		(layer "In2.Cu")
		(net "M_I_CPU0_SA_DQS_DP<1>")
	)
	(segment
		(start 395.304518 -224.765362)
		(end 403.63521 -216.43467)
		(width 0.16002)
		(layer "In2.Cu")
		(net "M_I_CPU0_SA_DQS_DP<1>")
	)
	(segment
		(start 413.272986 -210.209892)
		(end 413.580326 -210.517232)
		(width 0.16002)
		(layer "In2.Cu")
		(net "M_I_CPU0_SA_DQS_DP<1>")
	)
	(segment
		(start 423.14876 -209.360008)
		(end 425.453556 -209.360008)
		(width 0.16002)
		(layer "In2.Cu")
		(net "M_I_CPU0_SA_DQS_DP<1>")
	)
	(segment
		(start 429.713136 -210.542632)
		(end 429.896016 -210.359752)
		(width 0.16002)
		(layer "In2.Cu")
		(net "M_I_CPU0_SA_DQS_DP<1>")
	)
	(segment
		(start 380.20625 -231.849168)
		(end 380.214632 -231.853994)
		(width 0.09525)
		(layer "In2.Cu")
		(net "M_I_CPU0_SA_DQS_DP<1>")
	)
	(segment
		(start 392.80338 -228.609398)
		(end 392.835892 -228.590602)
		(width 0.09525)
		(layer "In2.Cu")
		(net "M_I_CPU0_SA_DQS_DP<1>")
	)
	(segment
		(start 377.420886 -231.789478)
		(end 377.444 -231.876092)
		(width 0.09525)
		(layer "In2.Cu")
		(net "M_I_CPU0_SA_DQS_DP<1>")
	)
	(segment
		(start 429.896016 -210.359752)
		(end 431.281586 -210.359752)
		(width 0.16002)
		(layer "In2.Cu")
		(net "M_I_CPU0_SA_DQS_DP<1>")
	)
	(segment
		(start 428.084996 -209.934048)
		(end 428.69358 -210.542632)
		(width 0.16002)
		(layer "In2.Cu")
		(net "M_I_CPU0_SA_DQS_DP<1>")
	)
	(segment
		(start 391.393426 -231.039416)
		(end 391.424922 -231.021128)
		(width 0.09525)
		(layer "In2.Cu")
		(net "M_I_CPU0_SA_DQS_DP<1>")
	)
	(segment
		(start 425.453556 -209.360008)
		(end 426.027596 -209.934048)
		(width 0.16002)
		(layer "In2.Cu")
		(net "M_I_CPU0_SA_DQS_DP<1>")
	)
	(segment
		(start 394.891514 -225.692208)
		(end 395.304518 -225.27895)
		(width 0.16002)
		(layer "In2.Cu")
		(net "M_I_CPU0_SA_DQS_DP<1>")
	)
	(segment
		(start 428.69358 -210.542632)
		(end 429.713136 -210.542632)
		(width 0.16002)
		(layer "In2.Cu")
		(net "M_I_CPU0_SA_DQS_DP<1>")
	)
	(segment
		(start 394.87475 -225.792792)
		(end 394.87475 -225.708972)
		(width 0.09525)
		(layer "In2.Cu")
		(net "M_I_CPU0_SA_DQS_DP<1>")
	)
	(segment
		(start 389.606282 -231.849168)
		(end 389.614664 -231.853994)
		(width 0.09525)
		(layer "In2.Cu")
		(net "M_I_CPU0_SA_DQS_DP<1>")
	)
	(segment
		(start 414.76295 -209.676492)
		(end 415.288222 -209.676492)
		(width 0.16002)
		(layer "In2.Cu")
		(net "M_I_CPU0_SA_DQS_DP<1>")
	)
	(segment
		(start 385.84632 -231.849168)
		(end 385.854702 -231.853994)
		(width 0.09525)
		(layer "In2.Cu")
		(net "M_I_CPU0_SA_DQS_DP<1>")
	)
	(segment
		(start 426.027596 -209.934048)
		(end 428.084996 -209.934048)
		(width 0.16002)
		(layer "In2.Cu")
		(net "M_I_CPU0_SA_DQS_DP<1>")
	)
	(segment
		(start 415.288222 -209.676492)
		(end 415.604706 -209.360008)
		(width 0.16002)
		(layer "In2.Cu")
		(net "M_I_CPU0_SA_DQS_DP<1>")
	)
	(segment
		(start 415.604706 -209.360008)
		(end 417.83381 -209.360008)
		(width 0.16002)
		(layer "In2.Cu")
		(net "M_I_CPU0_SA_DQS_DP<1>")
	)
	(segment
		(start 391.827766 -230.24973)
		(end 391.863326 -230.229156)
		(width 0.09525)
		(layer "In2.Cu")
		(net "M_I_CPU0_SA_DQS_DP<1>")
	)
	(segment
		(start 393.910058 -226.857052)
		(end 393.910058 -226.458272)
		(width 0.09525)
		(layer "In2.Cu")
		(net "M_I_CPU0_SA_DQS_DP<1>")
	)
	(segment
		(start 413.92221 -210.517232)
		(end 414.76295 -209.676492)
		(width 0.16002)
		(layer "In2.Cu")
		(net "M_I_CPU0_SA_DQS_DP<1>")
	)
	(arc
		(start 385.854702 -231.853994)
		(mid 386.039734 -231.899908)
		(end 386.22351 -231.849168)
		(width 0.09525)
		(layer "In2.Cu")
		(net "M_I_CPU0_SA_DQS_DP<1>")
	)
	(arc
		(start 393.462256 -227.474272)
		(mid 393.527453 -227.211319)
		(end 393.708128 -227.009452)
		(width 0.09525)
		(layer "In2.Cu")
		(net "M_I_CPU0_SA_DQS_DP<1>")
	)
	(arc
		(start 378.326142 -231.849168)
		(mid 378.509917 -231.89994)
		(end 378.69495 -231.853994)
		(width 0.09525)
		(layer "In2.Cu")
		(net "M_I_CPU0_SA_DQS_DP<1>")
	)
	(arc
		(start 389.983472 -231.849168)
		(mid 390.264904 -231.773413)
		(end 390.546336 -231.849168)
		(width 0.09525)
		(layer "In2.Cu")
		(net "M_I_CPU0_SA_DQS_DP<1>")
	)
	(arc
		(start 380.58344 -231.849168)
		(mid 380.864872 -231.773413)
		(end 381.146304 -231.849168)
		(width 0.09525)
		(layer "In2.Cu")
		(net "M_I_CPU0_SA_DQS_DP<1>")
	)
	(arc
		(start 383.403348 -231.849168)
		(mid 383.68478 -231.773413)
		(end 383.966212 -231.849168)
		(width 0.09525)
		(layer "In2.Cu")
		(net "M_I_CPU0_SA_DQS_DP<1>")
	)
	(arc
		(start 388.666228 -231.849168)
		(mid 388.850003 -231.89994)
		(end 389.035036 -231.853994)
		(width 0.09525)
		(layer "In2.Cu")
		(net "M_I_CPU0_SA_DQS_DP<1>")
	)
	(arc
		(start 391.112502 -231.524048)
		(mid 391.176248 -231.264048)
		(end 391.35304 -231.063038)
		(width 0.09525)
		(layer "In2.Cu")
		(net "M_I_CPU0_SA_DQS_DP<1>")
	)
	(arc
		(start 392.835892 -228.590602)
		(mid 392.951166 -228.456324)
		(end 392.99261 -228.284278)
		(width 0.09525)
		(layer "In2.Cu")
		(net "M_I_CPU0_SA_DQS_DP<1>")
	)
	(arc
		(start 386.22351 -231.849168)
		(mid 386.504942 -231.773413)
		(end 386.786374 -231.849168)
		(width 0.09525)
		(layer "In2.Cu")
		(net "M_I_CPU0_SA_DQS_DP<1>")
	)
	(arc
		(start 379.266196 -231.849168)
		(mid 379.449971 -231.89994)
		(end 379.635004 -231.853994)
		(width 0.09525)
		(layer "In2.Cu")
		(net "M_I_CPU0_SA_DQS_DP<1>")
	)
	(arc
		(start 387.726174 -231.849168)
		(mid 387.909949 -231.89994)
		(end 388.094982 -231.853994)
		(width 0.09525)
		(layer "In2.Cu")
		(net "M_I_CPU0_SA_DQS_DP<1>")
	)
	(arc
		(start 390.546336 -231.849168)
		(mid 390.734804 -231.899845)
		(end 390.923272 -231.849168)
		(width 0.09525)
		(layer "In2.Cu")
		(net "M_I_CPU0_SA_DQS_DP<1>")
	)
	(arc
		(start 388.103364 -231.849168)
		(mid 388.384796 -231.773413)
		(end 388.666228 -231.849168)
		(width 0.09525)
		(layer "In2.Cu")
		(net "M_I_CPU0_SA_DQS_DP<1>")
	)
	(arc
		(start 386.786374 -231.849168)
		(mid 386.974842 -231.899845)
		(end 387.16331 -231.849168)
		(width 0.09525)
		(layer "In2.Cu")
		(net "M_I_CPU0_SA_DQS_DP<1>")
	)
	(arc
		(start 377.444 -231.876092)
		(mid 377.606651 -231.898352)
		(end 377.763278 -231.849168)
		(width 0.09525)
		(layer "In2.Cu")
		(net "M_I_CPU0_SA_DQS_DP<1>")
	)
	(arc
		(start 377.763278 -231.849168)
		(mid 378.04471 -231.773413)
		(end 378.326142 -231.849168)
		(width 0.09525)
		(layer "In2.Cu")
		(net "M_I_CPU0_SA_DQS_DP<1>")
	)
	(arc
		(start 392.364976 -229.401116)
		(mid 392.480774 -229.266722)
		(end 392.522456 -229.094284)
		(width 0.09525)
		(layer "In2.Cu")
		(net "M_I_CPU0_SA_DQS_DP<1>")
	)
	(arc
		(start 392.052556 -229.904036)
		(mid 392.116302 -229.644036)
		(end 392.293094 -229.443026)
		(width 0.09525)
		(layer "In2.Cu")
		(net "M_I_CPU0_SA_DQS_DP<1>")
	)
	(arc
		(start 393.302744 -227.782628)
		(mid 393.420048 -227.647867)
		(end 393.462256 -227.474272)
		(width 0.09525)
		(layer "In2.Cu")
		(net "M_I_CPU0_SA_DQS_DP<1>")
	)
	(arc
		(start 379.643386 -231.849168)
		(mid 379.924818 -231.773413)
		(end 380.20625 -231.849168)
		(width 0.09525)
		(layer "In2.Cu")
		(net "M_I_CPU0_SA_DQS_DP<1>")
	)
	(arc
		(start 392.99261 -228.284278)
		(mid 393.057007 -228.022972)
		(end 393.235434 -227.82149)
		(width 0.09525)
		(layer "In2.Cu")
		(net "M_I_CPU0_SA_DQS_DP<1>")
	)
	(arc
		(start 391.582402 -230.714296)
		(mid 391.647521 -230.451618)
		(end 391.827766 -230.24973)
		(width 0.09525)
		(layer "In2.Cu")
		(net "M_I_CPU0_SA_DQS_DP<1>")
	)
	(arc
		(start 380.214632 -231.853994)
		(mid 380.399664 -231.899908)
		(end 380.58344 -231.849168)
		(width 0.09525)
		(layer "In2.Cu")
		(net "M_I_CPU0_SA_DQS_DP<1>")
	)
	(arc
		(start 382.463294 -231.849168)
		(mid 382.744726 -231.773413)
		(end 383.026158 -231.849168)
		(width 0.09525)
		(layer "In2.Cu")
		(net "M_I_CPU0_SA_DQS_DP<1>")
	)
	(arc
		(start 389.614664 -231.853994)
		(mid 389.799696 -231.899908)
		(end 389.983472 -231.849168)
		(width 0.09525)
		(layer "In2.Cu")
		(net "M_I_CPU0_SA_DQS_DP<1>")
	)
	(arc
		(start 383.026158 -231.849168)
		(mid 383.209933 -231.89994)
		(end 383.394966 -231.853994)
		(width 0.09525)
		(layer "In2.Cu")
		(net "M_I_CPU0_SA_DQS_DP<1>")
	)
	(arc
		(start 381.154686 -231.853994)
		(mid 381.339718 -231.899908)
		(end 381.523494 -231.849168)
		(width 0.09525)
		(layer "In2.Cu")
		(net "M_I_CPU0_SA_DQS_DP<1>")
	)
	(arc
		(start 384.914648 -231.853994)
		(mid 385.09968 -231.899908)
		(end 385.283456 -231.849168)
		(width 0.09525)
		(layer "In2.Cu")
		(net "M_I_CPU0_SA_DQS_DP<1>")
	)
	(arc
		(start 391.424922 -231.021128)
		(mid 391.54072 -230.886734)
		(end 391.582402 -230.714296)
		(width 0.09525)
		(layer "In2.Cu")
		(net "M_I_CPU0_SA_DQS_DP<1>")
	)
	(arc
		(start 384.343402 -231.849168)
		(mid 384.624834 -231.773413)
		(end 384.906266 -231.849168)
		(width 0.09525)
		(layer "In2.Cu")
		(net "M_I_CPU0_SA_DQS_DP<1>")
	)
	(arc
		(start 381.523494 -231.849168)
		(mid 381.804926 -231.773413)
		(end 382.086358 -231.849168)
		(width 0.09525)
		(layer "In2.Cu")
		(net "M_I_CPU0_SA_DQS_DP<1>")
	)
	(arc
		(start 385.283456 -231.849168)
		(mid 385.564888 -231.773413)
		(end 385.84632 -231.849168)
		(width 0.09525)
		(layer "In2.Cu")
		(net "M_I_CPU0_SA_DQS_DP<1>")
	)
	(arc
		(start 391.895838 -230.21036)
		(mid 392.011112 -230.076082)
		(end 392.052556 -229.904036)
		(width 0.09525)
		(layer "In2.Cu")
		(net "M_I_CPU0_SA_DQS_DP<1>")
	)
	(arc
		(start 389.043418 -231.849168)
		(mid 389.32485 -231.773413)
		(end 389.606282 -231.849168)
		(width 0.09525)
		(layer "In2.Cu")
		(net "M_I_CPU0_SA_DQS_DP<1>")
	)
	(arc
		(start 392.522456 -229.094284)
		(mid 392.586853 -228.832978)
		(end 392.76528 -228.631496)
		(width 0.09525)
		(layer "In2.Cu")
		(net "M_I_CPU0_SA_DQS_DP<1>")
	)
	(arc
		(start 383.966212 -231.849168)
		(mid 384.149987 -231.89994)
		(end 384.33502 -231.853994)
		(width 0.09525)
		(layer "In2.Cu")
		(net "M_I_CPU0_SA_DQS_DP<1>")
	)
	(arc
		(start 390.955784 -231.830372)
		(mid 391.071058 -231.696094)
		(end 391.112502 -231.524048)
		(width 0.09525)
		(layer "In2.Cu")
		(net "M_I_CPU0_SA_DQS_DP<1>")
	)
	(arc
		(start 382.086358 -231.849168)
		(mid 382.274826 -231.899845)
		(end 382.463294 -231.849168)
		(width 0.09525)
		(layer "In2.Cu")
		(net "M_I_CPU0_SA_DQS_DP<1>")
	)
	(arc
		(start 387.16331 -231.849168)
		(mid 387.444742 -231.773413)
		(end 387.726174 -231.849168)
		(width 0.09525)
		(layer "In2.Cu")
		(net "M_I_CPU0_SA_DQS_DP<1>")
	)
	(arc
		(start 378.703332 -231.849168)
		(mid 378.984764 -231.773413)
		(end 379.266196 -231.849168)
		(width 0.09525)
		(layer "In2.Cu")
		(net "M_I_CPU0_SA_DQS_DP<1>")
	)
	(segment
		(start 377.107958 -226.930204)
		(end 377.57481 -226.664266)
		(width 0.12954)
		(layer "F.Cu")
		(net "M_I_CPU0_SA_DQS_DP<0>")
	)
	(segment
		(start 385.854702 -226.994212)
		(end 385.84632 -226.989386)
		(width 0.09525)
		(layer "In2.Cu")
		(net "M_I_CPU0_SA_DQS_DP<0>")
	)
	(segment
		(start 425.999656 -200.584054)
		(end 425.425616 -200.010014)
		(width 0.16002)
		(layer "In2.Cu")
		(net "M_I_CPU0_SA_DQS_DP<0>")
	)
	(segment
		(start 420.81704 -200.859898)
		(end 418.683694 -200.859898)
		(width 0.16002)
		(layer "In2.Cu")
		(net "M_I_CPU0_SA_DQS_DP<0>")
	)
	(segment
		(start 428.69358 -201.192638)
		(end 428.084996 -200.584054)
		(width 0.16002)
		(layer "In2.Cu")
		(net "M_I_CPU0_SA_DQS_DP<0>")
	)
	(segment
		(start 380.214632 -226.994212)
		(end 380.20625 -226.989386)
		(width 0.09525)
		(layer "In2.Cu")
		(net "M_I_CPU0_SA_DQS_DP<0>")
	)
	(segment
		(start 391.053828 -221.17431)
		(end 391.053828 -221.197932)
		(width 0.09525)
		(layer "In2.Cu")
		(net "M_I_CPU0_SA_DQS_DP<0>")
	)
	(segment
		(start 390.484868 -222.921068)
		(end 390.453372 -222.939356)
		(width 0.09525)
		(layer "In2.Cu")
		(net "M_I_CPU0_SA_DQS_DP<0>")
	)
	(segment
		(start 431.55616 -200.735184)
		(end 431.281586 -201.009758)
		(width 0.16002)
		(layer "In2.Cu")
		(net "M_I_CPU0_SA_DQS_DP<0>")
	)
	(segment
		(start 389.54583 -224.540572)
		(end 389.513318 -224.559368)
		(width 0.09525)
		(layer "In2.Cu")
		(net "M_I_CPU0_SA_DQS_DP<0>")
	)
	(segment
		(start 418.683694 -200.859898)
		(end 417.83381 -200.010014)
		(width 0.16002)
		(layer "In2.Cu")
		(net "M_I_CPU0_SA_DQS_DP<0>")
	)
	(segment
		(start 413.272986 -200.859898)
		(end 408.551888 -200.859898)
		(width 0.16002)
		(layer "In2.Cu")
		(net "M_I_CPU0_SA_DQS_DP<0>")
	)
	(segment
		(start 388.135876 -226.97059)
		(end 388.103364 -226.989386)
		(width 0.09525)
		(layer "In2.Cu")
		(net "M_I_CPU0_SA_DQS_DP<0>")
	)
	(segment
		(start 381.154686 -226.994212)
		(end 381.146304 -226.989386)
		(width 0.09525)
		(layer "In2.Cu")
		(net "M_I_CPU0_SA_DQS_DP<0>")
	)
	(segment
		(start 391.053828 -219.691458)
		(end 391.053828 -221.17431)
		(width 0.16002)
		(layer "In2.Cu")
		(net "M_I_CPU0_SA_DQS_DP<0>")
	)
	(segment
		(start 413.580326 -201.167238)
		(end 413.272986 -200.859898)
		(width 0.16002)
		(layer "In2.Cu")
		(net "M_I_CPU0_SA_DQS_DP<0>")
	)
	(segment
		(start 431.281586 -201.009758)
		(end 429.282352 -201.009758)
		(width 0.16002)
		(layer "In2.Cu")
		(net "M_I_CPU0_SA_DQS_DP<0>")
	)
	(segment
		(start 396.967456 -212.44433)
		(end 396.967456 -213.77783)
		(width 0.16002)
		(layer "In2.Cu")
		(net "M_I_CPU0_SA_DQS_DP<0>")
	)
	(segment
		(start 388.605014 -226.161092)
		(end 388.573518 -226.17938)
		(width 0.09525)
		(layer "In2.Cu")
		(net "M_I_CPU0_SA_DQS_DP<0>")
	)
	(segment
		(start 379.643386 -226.989386)
		(end 379.635004 -226.994212)
		(width 0.09525)
		(layer "In2.Cu")
		(net "M_I_CPU0_SA_DQS_DP<0>")
	)
	(segment
		(start 413.92221 -201.167238)
		(end 413.580326 -201.167238)
		(width 0.16002)
		(layer "In2.Cu")
		(net "M_I_CPU0_SA_DQS_DP<0>")
	)
	(segment
		(start 421.466264 -201.167238)
		(end 421.12438 -201.167238)
		(width 0.16002)
		(layer "In2.Cu")
		(net "M_I_CPU0_SA_DQS_DP<0>")
	)
	(segment
		(start 417.83381 -200.010014)
		(end 415.604706 -200.010014)
		(width 0.16002)
		(layer "In2.Cu")
		(net "M_I_CPU0_SA_DQS_DP<0>")
	)
	(segment
		(start 425.425616 -200.010014)
		(end 423.14876 -200.010014)
		(width 0.16002)
		(layer "In2.Cu")
		(net "M_I_CPU0_SA_DQS_DP<0>")
	)
	(segment
		(start 389.07593 -225.350578)
		(end 389.043418 -225.369374)
		(width 0.09525)
		(layer "In2.Cu")
		(net "M_I_CPU0_SA_DQS_DP<0>")
	)
	(segment
		(start 415.288222 -200.326498)
		(end 414.76295 -200.326498)
		(width 0.16002)
		(layer "In2.Cu")
		(net "M_I_CPU0_SA_DQS_DP<0>")
	)
	(segment
		(start 390.954768 -222.111062)
		(end 390.885172 -222.151448)
		(width 0.09525)
		(layer "In2.Cu")
		(net "M_I_CPU0_SA_DQS_DP<0>")
	)
	(segment
		(start 390.014968 -223.731074)
		(end 389.983472 -223.749362)
		(width 0.09525)
		(layer "In2.Cu")
		(net "M_I_CPU0_SA_DQS_DP<0>")
	)
	(segment
		(start 429.099472 -201.192638)
		(end 428.69358 -201.192638)
		(width 0.16002)
		(layer "In2.Cu")
		(net "M_I_CPU0_SA_DQS_DP<0>")
	)
	(segment
		(start 408.551888 -200.859898)
		(end 396.967456 -212.44433)
		(width 0.16002)
		(layer "In2.Cu")
		(net "M_I_CPU0_SA_DQS_DP<0>")
	)
	(segment
		(start 378.703332 -226.989386)
		(end 378.69495 -226.994212)
		(width 0.09525)
		(layer "In2.Cu")
		(net "M_I_CPU0_SA_DQS_DP<0>")
	)
	(segment
		(start 389.043418 -225.369374)
		(end 389.005318 -225.391472)
		(width 0.09525)
		(layer "In2.Cu")
		(net "M_I_CPU0_SA_DQS_DP<0>")
	)
	(segment
		(start 422.307004 -200.326498)
		(end 421.466264 -201.167238)
		(width 0.16002)
		(layer "In2.Cu")
		(net "M_I_CPU0_SA_DQS_DP<0>")
	)
	(segment
		(start 414.76295 -200.326498)
		(end 413.92221 -201.167238)
		(width 0.16002)
		(layer "In2.Cu")
		(net "M_I_CPU0_SA_DQS_DP<0>")
	)
	(segment
		(start 384.914648 -226.994212)
		(end 384.906266 -226.989386)
		(width 0.09525)
		(layer "In2.Cu")
		(net "M_I_CPU0_SA_DQS_DP<0>")
	)
	(segment
		(start 383.403348 -226.989386)
		(end 383.394966 -226.994212)
		(width 0.09525)
		(layer "In2.Cu")
		(net "M_I_CPU0_SA_DQS_DP<0>")
	)
	(segment
		(start 396.967456 -213.77783)
		(end 391.053828 -219.691458)
		(width 0.16002)
		(layer "In2.Cu")
		(net "M_I_CPU0_SA_DQS_DP<0>")
	)
	(segment
		(start 389.513318 -224.559368)
		(end 389.478266 -224.579942)
		(width 0.09525)
		(layer "In2.Cu")
		(net "M_I_CPU0_SA_DQS_DP<0>")
	)
	(segment
		(start 384.343402 -226.989386)
		(end 384.33502 -226.994212)
		(width 0.09525)
		(layer "In2.Cu")
		(net "M_I_CPU0_SA_DQS_DP<0>")
	)
	(segment
		(start 415.604706 -200.010014)
		(end 415.288222 -200.326498)
		(width 0.16002)
		(layer "In2.Cu")
		(net "M_I_CPU0_SA_DQS_DP<0>")
	)
	(segment
		(start 391.112756 -221.25686)
		(end 391.112756 -221.803468)
		(width 0.09525)
		(layer "In2.Cu")
		(net "M_I_CPU0_SA_DQS_DP<0>")
	)
	(segment
		(start 388.103364 -226.989386)
		(end 388.094982 -226.994212)
		(width 0.09525)
		(layer "In2.Cu")
		(net "M_I_CPU0_SA_DQS_DP<0>")
	)
	(segment
		(start 428.084996 -200.584054)
		(end 425.999656 -200.584054)
		(width 0.16002)
		(layer "In2.Cu")
		(net "M_I_CPU0_SA_DQS_DP<0>")
	)
	(segment
		(start 429.282352 -201.009758)
		(end 429.099472 -201.192638)
		(width 0.16002)
		(layer "In2.Cu")
		(net "M_I_CPU0_SA_DQS_DP<0>")
	)
	(segment
		(start 377.420886 -226.929696)
		(end 377.57481 -226.664266)
		(width 0.09525)
		(layer "In2.Cu")
		(net "M_I_CPU0_SA_DQS_DP<0>")
	)
	(segment
		(start 377.444 -227.01631)
		(end 377.420886 -226.929696)
		(width 0.09525)
		(layer "In2.Cu")
		(net "M_I_CPU0_SA_DQS_DP<0>")
	)
	(segment
		(start 421.12438 -201.167238)
		(end 420.81704 -200.859898)
		(width 0.16002)
		(layer "In2.Cu")
		(net "M_I_CPU0_SA_DQS_DP<0>")
	)
	(segment
		(start 391.053828 -221.197932)
		(end 391.112756 -221.25686)
		(width 0.09525)
		(layer "In2.Cu")
		(net "M_I_CPU0_SA_DQS_DP<0>")
	)
	(segment
		(start 388.573518 -226.17938)
		(end 388.535418 -226.201478)
		(width 0.09525)
		(layer "In2.Cu")
		(net "M_I_CPU0_SA_DQS_DP<0>")
	)
	(segment
		(start 389.983472 -223.749362)
		(end 389.945372 -223.77146)
		(width 0.09525)
		(layer "In2.Cu")
		(net "M_I_CPU0_SA_DQS_DP<0>")
	)
	(segment
		(start 422.832276 -200.326498)
		(end 422.307004 -200.326498)
		(width 0.16002)
		(layer "In2.Cu")
		(net "M_I_CPU0_SA_DQS_DP<0>")
	)
	(segment
		(start 390.453372 -222.939356)
		(end 390.415272 -222.961454)
		(width 0.09525)
		(layer "In2.Cu")
		(net "M_I_CPU0_SA_DQS_DP<0>")
	)
	(segment
		(start 423.14876 -200.010014)
		(end 422.832276 -200.326498)
		(width 0.16002)
		(layer "In2.Cu")
		(net "M_I_CPU0_SA_DQS_DP<0>")
	)
	(arc
		(start 390.415272 -222.961454)
		(mid 390.236822 -223.162924)
		(end 390.172448 -223.424242)
		(width 0.09525)
		(layer "In2.Cu")
		(net "M_I_CPU0_SA_DQS_DP<0>")
	)
	(arc
		(start 389.005318 -225.391472)
		(mid 388.826868 -225.592942)
		(end 388.762494 -225.85426)
		(width 0.09525)
		(layer "In2.Cu")
		(net "M_I_CPU0_SA_DQS_DP<0>")
	)
	(arc
		(start 385.84632 -226.989386)
		(mid 385.564888 -226.913631)
		(end 385.283456 -226.989386)
		(width 0.09525)
		(layer "In2.Cu")
		(net "M_I_CPU0_SA_DQS_DP<0>")
	)
	(arc
		(start 391.112756 -221.803468)
		(mid 391.070952 -221.976369)
		(end 390.954768 -222.111062)
		(width 0.09525)
		(layer "In2.Cu")
		(net "M_I_CPU0_SA_DQS_DP<0>")
	)
	(arc
		(start 382.463294 -226.989386)
		(mid 382.274826 -227.040063)
		(end 382.086358 -226.989386)
		(width 0.09525)
		(layer "In2.Cu")
		(net "M_I_CPU0_SA_DQS_DP<0>")
	)
	(arc
		(start 383.966212 -226.989386)
		(mid 383.68478 -226.913631)
		(end 383.403348 -226.989386)
		(width 0.09525)
		(layer "In2.Cu")
		(net "M_I_CPU0_SA_DQS_DP<0>")
	)
	(arc
		(start 390.885172 -222.151448)
		(mid 390.706722 -222.352918)
		(end 390.642348 -222.614236)
		(width 0.09525)
		(layer "In2.Cu")
		(net "M_I_CPU0_SA_DQS_DP<0>")
	)
	(arc
		(start 381.146304 -226.989386)
		(mid 380.864872 -226.913631)
		(end 380.58344 -226.989386)
		(width 0.09525)
		(layer "In2.Cu")
		(net "M_I_CPU0_SA_DQS_DP<0>")
	)
	(arc
		(start 388.292594 -226.664266)
		(mid 388.251137 -226.836306)
		(end 388.135876 -226.97059)
		(width 0.09525)
		(layer "In2.Cu")
		(net "M_I_CPU0_SA_DQS_DP<0>")
	)
	(arc
		(start 386.786374 -226.989386)
		(mid 386.504942 -226.913631)
		(end 386.22351 -226.989386)
		(width 0.09525)
		(layer "In2.Cu")
		(net "M_I_CPU0_SA_DQS_DP<0>")
	)
	(arc
		(start 389.702548 -224.234248)
		(mid 389.661091 -224.406288)
		(end 389.54583 -224.540572)
		(width 0.09525)
		(layer "In2.Cu")
		(net "M_I_CPU0_SA_DQS_DP<0>")
	)
	(arc
		(start 390.172448 -223.424242)
		(mid 390.130783 -223.596689)
		(end 390.014968 -223.731074)
		(width 0.09525)
		(layer "In2.Cu")
		(net "M_I_CPU0_SA_DQS_DP<0>")
	)
	(arc
		(start 379.635004 -226.994212)
		(mid 379.449972 -227.040126)
		(end 379.266196 -226.989386)
		(width 0.09525)
		(layer "In2.Cu")
		(net "M_I_CPU0_SA_DQS_DP<0>")
	)
	(arc
		(start 377.763278 -226.989386)
		(mid 377.606651 -227.038572)
		(end 377.444 -227.01631)
		(width 0.09525)
		(layer "In2.Cu")
		(net "M_I_CPU0_SA_DQS_DP<0>")
	)
	(arc
		(start 384.906266 -226.989386)
		(mid 384.624834 -226.913631)
		(end 384.343402 -226.989386)
		(width 0.09525)
		(layer "In2.Cu")
		(net "M_I_CPU0_SA_DQS_DP<0>")
	)
	(arc
		(start 387.726174 -226.989386)
		(mid 387.444742 -226.913631)
		(end 387.16331 -226.989386)
		(width 0.09525)
		(layer "In2.Cu")
		(net "M_I_CPU0_SA_DQS_DP<0>")
	)
	(arc
		(start 386.22351 -226.989386)
		(mid 386.039735 -227.040158)
		(end 385.854702 -226.994212)
		(width 0.09525)
		(layer "In2.Cu")
		(net "M_I_CPU0_SA_DQS_DP<0>")
	)
	(arc
		(start 389.232648 -225.044254)
		(mid 389.191191 -225.216294)
		(end 389.07593 -225.350578)
		(width 0.09525)
		(layer "In2.Cu")
		(net "M_I_CPU0_SA_DQS_DP<0>")
	)
	(arc
		(start 389.945372 -223.77146)
		(mid 389.766922 -223.97293)
		(end 389.702548 -224.234248)
		(width 0.09525)
		(layer "In2.Cu")
		(net "M_I_CPU0_SA_DQS_DP<0>")
	)
	(arc
		(start 387.16331 -226.989386)
		(mid 386.974842 -227.040063)
		(end 386.786374 -226.989386)
		(width 0.09525)
		(layer "In2.Cu")
		(net "M_I_CPU0_SA_DQS_DP<0>")
	)
	(arc
		(start 378.69495 -226.994212)
		(mid 378.509918 -227.040126)
		(end 378.326142 -226.989386)
		(width 0.09525)
		(layer "In2.Cu")
		(net "M_I_CPU0_SA_DQS_DP<0>")
	)
	(arc
		(start 388.094982 -226.994212)
		(mid 387.90995 -227.040126)
		(end 387.726174 -226.989386)
		(width 0.09525)
		(layer "In2.Cu")
		(net "M_I_CPU0_SA_DQS_DP<0>")
	)
	(arc
		(start 379.266196 -226.989386)
		(mid 378.984764 -226.913631)
		(end 378.703332 -226.989386)
		(width 0.09525)
		(layer "In2.Cu")
		(net "M_I_CPU0_SA_DQS_DP<0>")
	)
	(arc
		(start 383.026158 -226.989386)
		(mid 382.744726 -226.913631)
		(end 382.463294 -226.989386)
		(width 0.09525)
		(layer "In2.Cu")
		(net "M_I_CPU0_SA_DQS_DP<0>")
	)
	(arc
		(start 385.283456 -226.989386)
		(mid 385.099681 -227.040158)
		(end 384.914648 -226.994212)
		(width 0.09525)
		(layer "In2.Cu")
		(net "M_I_CPU0_SA_DQS_DP<0>")
	)
	(arc
		(start 380.58344 -226.989386)
		(mid 380.399665 -227.040158)
		(end 380.214632 -226.994212)
		(width 0.09525)
		(layer "In2.Cu")
		(net "M_I_CPU0_SA_DQS_DP<0>")
	)
	(arc
		(start 388.762494 -225.85426)
		(mid 388.720829 -226.026707)
		(end 388.605014 -226.161092)
		(width 0.09525)
		(layer "In2.Cu")
		(net "M_I_CPU0_SA_DQS_DP<0>")
	)
	(arc
		(start 380.20625 -226.989386)
		(mid 379.924818 -226.913631)
		(end 379.643386 -226.989386)
		(width 0.09525)
		(layer "In2.Cu")
		(net "M_I_CPU0_SA_DQS_DP<0>")
	)
	(arc
		(start 390.642348 -222.614236)
		(mid 390.600683 -222.786683)
		(end 390.484868 -222.921068)
		(width 0.09525)
		(layer "In2.Cu")
		(net "M_I_CPU0_SA_DQS_DP<0>")
	)
	(arc
		(start 381.523494 -226.989386)
		(mid 381.339719 -227.040158)
		(end 381.154686 -226.994212)
		(width 0.09525)
		(layer "In2.Cu")
		(net "M_I_CPU0_SA_DQS_DP<0>")
	)
	(arc
		(start 378.326142 -226.989386)
		(mid 378.04471 -226.913631)
		(end 377.763278 -226.989386)
		(width 0.09525)
		(layer "In2.Cu")
		(net "M_I_CPU0_SA_DQS_DP<0>")
	)
	(arc
		(start 382.086358 -226.989386)
		(mid 381.804926 -226.913631)
		(end 381.523494 -226.989386)
		(width 0.09525)
		(layer "In2.Cu")
		(net "M_I_CPU0_SA_DQS_DP<0>")
	)
	(arc
		(start 384.33502 -226.994212)
		(mid 384.149988 -227.040126)
		(end 383.966212 -226.989386)
		(width 0.09525)
		(layer "In2.Cu")
		(net "M_I_CPU0_SA_DQS_DP<0>")
	)
	(arc
		(start 383.394966 -226.994212)
		(mid 383.209934 -227.040126)
		(end 383.026158 -226.989386)
		(width 0.09525)
		(layer "In2.Cu")
		(net "M_I_CPU0_SA_DQS_DP<0>")
	)
	(arc
		(start 388.535418 -226.201478)
		(mid 388.356968 -226.402948)
		(end 388.292594 -226.664266)
		(width 0.09525)
		(layer "In2.Cu")
		(net "M_I_CPU0_SA_DQS_DP<0>")
	)
	(arc
		(start 389.478266 -224.579942)
		(mid 389.297875 -224.781641)
		(end 389.232648 -225.044254)
		(width 0.09525)
		(layer "In2.Cu")
		(net "M_I_CPU0_SA_DQS_DP<0>")
	)
	(segment
		(start 375.698004 -247.1801)
		(end 376.164856 -246.914162)
		(width 0.12954)
		(layer "F.Cu")
		(net "M_I_CPU0_SA_DQS_DN<9>")
	)
	(segment
		(start 376.010932 -247.179592)
		(end 376.0343 -247.26646)
		(width 0.09525)
		(layer "In2.Cu")
		(net "M_I_CPU0_SA_DQS_DN<9>")
	)
	(segment
		(start 425.694094 -239.259618)
		(end 425.810934 -239.142778)
		(width 0.16002)
		(layer "In2.Cu")
		(net "M_I_CPU0_SA_DQS_DN<9>")
	)
	(segment
		(start 411.471872 -240.533936)
		(end 412.857442 -240.533936)
		(width 0.16002)
		(layer "In2.Cu")
		(net "M_I_CPU0_SA_DQS_DN<9>")
	)
	(segment
		(start 412.857442 -240.533936)
		(end 413.498284 -239.893094)
		(width 0.16002)
		(layer "In2.Cu")
		(net "M_I_CPU0_SA_DQS_DN<9>")
	)
	(segment
		(start 396.767558 -246.633492)
		(end 405.372316 -246.633492)
		(width 0.16002)
		(layer "In2.Cu")
		(net "M_I_CPU0_SA_DQS_DN<9>")
	)
	(segment
		(start 415.391092 -239.100614)
		(end 415.97453 -239.684052)
		(width 0.16002)
		(layer "In2.Cu")
		(net "M_I_CPU0_SA_DQS_DN<9>")
	)
	(segment
		(start 378.796296 -247.239282)
		(end 378.804678 -247.244108)
		(width 0.09525)
		(layer "In2.Cu")
		(net "M_I_CPU0_SA_DQS_DN<9>")
	)
	(segment
		(start 409.761182 -243.702586)
		(end 409.957778 -243.50599)
		(width 0.16002)
		(layer "In2.Cu")
		(net "M_I_CPU0_SA_DQS_DN<9>")
	)
	(segment
		(start 408.257248 -244.275864)
		(end 408.257248 -243.74856)
		(width 0.16002)
		(layer "In2.Cu")
		(net "M_I_CPU0_SA_DQS_DN<9>")
	)
	(segment
		(start 406.883616 -245.649496)
		(end 406.883616 -245.122192)
		(width 0.16002)
		(layer "In2.Cu")
		(net "M_I_CPU0_SA_DQS_DN<9>")
	)
	(segment
		(start 419.28796 -240.533936)
		(end 420.401496 -240.533936)
		(width 0.16002)
		(layer "In2.Cu")
		(net "M_I_CPU0_SA_DQS_DN<9>")
	)
	(segment
		(start 425.214034 -239.259618)
		(end 425.694094 -239.259618)
		(width 0.16002)
		(layer "In2.Cu")
		(net "M_I_CPU0_SA_DQS_DN<9>")
	)
	(segment
		(start 392.896598 -247.239282)
		(end 392.911076 -247.247664)
		(width 0.09525)
		(layer "In2.Cu")
		(net "M_I_CPU0_SA_DQS_DN<9>")
	)
	(segment
		(start 396.169642 -247.231408)
		(end 396.767558 -246.633492)
		(width 0.16002)
		(layer "In2.Cu")
		(net "M_I_CPU0_SA_DQS_DN<9>")
	)
	(segment
		(start 408.38755 -245.076218)
		(end 408.584146 -244.879622)
		(width 0.16002)
		(layer "In2.Cu")
		(net "M_I_CPU0_SA_DQS_DN<9>")
	)
	(segment
		(start 386.685028 -247.244108)
		(end 386.69341 -247.239282)
		(width 0.09525)
		(layer "In2.Cu")
		(net "M_I_CPU0_SA_DQS_DN<9>")
	)
	(segment
		(start 408.584146 -244.879622)
		(end 408.584146 -244.602762)
		(width 0.16002)
		(layer "In2.Cu")
		(net "M_I_CPU0_SA_DQS_DN<9>")
	)
	(segment
		(start 406.883616 -245.122192)
		(end 407.256488 -244.74932)
		(width 0.16002)
		(layer "In2.Cu")
		(net "M_I_CPU0_SA_DQS_DN<9>")
	)
	(segment
		(start 405.882856 -246.122952)
		(end 406.41016 -246.122952)
		(width 0.16002)
		(layer "In2.Cu")
		(net "M_I_CPU0_SA_DQS_DN<9>")
	)
	(segment
		(start 407.256488 -244.74932)
		(end 407.783792 -244.74932)
		(width 0.16002)
		(layer "In2.Cu")
		(net "M_I_CPU0_SA_DQS_DN<9>")
	)
	(segment
		(start 395.59738 -247.29059)
		(end 395.656562 -247.231408)
		(width 0.09525)
		(layer "In2.Cu")
		(net "M_I_CPU0_SA_DQS_DN<9>")
	)
	(segment
		(start 405.372316 -246.633492)
		(end 405.882856 -246.122952)
		(width 0.16002)
		(layer "In2.Cu")
		(net "M_I_CPU0_SA_DQS_DN<9>")
	)
	(segment
		(start 418.438076 -239.684052)
		(end 419.28796 -240.533936)
		(width 0.16002)
		(layer "In2.Cu")
		(net "M_I_CPU0_SA_DQS_DN<9>")
	)
	(segment
		(start 395.656562 -247.231408)
		(end 395.680184 -247.231408)
		(width 0.09525)
		(layer "In2.Cu")
		(net "M_I_CPU0_SA_DQS_DN<9>")
	)
	(segment
		(start 415.97453 -239.684052)
		(end 418.438076 -239.684052)
		(width 0.16002)
		(layer "In2.Cu")
		(net "M_I_CPU0_SA_DQS_DN<9>")
	)
	(segment
		(start 422.935146 -239.100614)
		(end 423.242486 -239.407954)
		(width 0.16002)
		(layer "In2.Cu")
		(net "M_I_CPU0_SA_DQS_DN<9>")
	)
	(segment
		(start 377.856242 -247.239282)
		(end 377.864624 -247.244108)
		(width 0.09525)
		(layer "In2.Cu")
		(net "M_I_CPU0_SA_DQS_DN<9>")
	)
	(segment
		(start 425.810934 -239.142778)
		(end 426.290994 -239.142778)
		(width 0.16002)
		(layer "In2.Cu")
		(net "M_I_CPU0_SA_DQS_DN<9>")
	)
	(segment
		(start 392.881866 -247.230646)
		(end 392.896598 -247.239282)
		(width 0.09525)
		(layer "In2.Cu")
		(net "M_I_CPU0_SA_DQS_DN<9>")
	)
	(segment
		(start 421.042338 -239.893094)
		(end 421.479218 -239.893094)
		(width 0.16002)
		(layer "In2.Cu")
		(net "M_I_CPU0_SA_DQS_DN<9>")
	)
	(segment
		(start 392.322304 -247.24614)
		(end 392.334242 -247.239282)
		(width 0.09525)
		(layer "In2.Cu")
		(net "M_I_CPU0_SA_DQS_DN<9>")
	)
	(segment
		(start 409.957778 -243.22913)
		(end 409.63088 -242.902232)
		(width 0.16002)
		(layer "In2.Cu")
		(net "M_I_CPU0_SA_DQS_DN<9>")
	)
	(segment
		(start 385.744974 -247.244108)
		(end 385.753356 -247.239282)
		(width 0.09525)
		(layer "In2.Cu")
		(net "M_I_CPU0_SA_DQS_DN<9>")
	)
	(segment
		(start 394.025882 -247.29059)
		(end 395.59738 -247.29059)
		(width 0.09525)
		(layer "In2.Cu")
		(net "M_I_CPU0_SA_DQS_DN<9>")
	)
	(segment
		(start 408.584146 -244.602762)
		(end 408.257248 -244.275864)
		(width 0.16002)
		(layer "In2.Cu")
		(net "M_I_CPU0_SA_DQS_DN<9>")
	)
	(segment
		(start 414.727644 -239.100614)
		(end 415.391092 -239.100614)
		(width 0.16002)
		(layer "In2.Cu")
		(net "M_I_CPU0_SA_DQS_DN<9>")
	)
	(segment
		(start 387.256274 -247.239282)
		(end 387.264656 -247.244108)
		(width 0.09525)
		(layer "In2.Cu")
		(net "M_I_CPU0_SA_DQS_DN<9>")
	)
	(segment
		(start 422.271698 -239.100614)
		(end 422.935146 -239.100614)
		(width 0.16002)
		(layer "In2.Cu")
		(net "M_I_CPU0_SA_DQS_DN<9>")
	)
	(segment
		(start 425.065698 -239.407954)
		(end 425.214034 -239.259618)
		(width 0.16002)
		(layer "In2.Cu")
		(net "M_I_CPU0_SA_DQS_DN<9>")
	)
	(segment
		(start 409.157424 -243.375688)
		(end 409.484322 -243.702586)
		(width 0.16002)
		(layer "In2.Cu")
		(net "M_I_CPU0_SA_DQS_DN<9>")
	)
	(segment
		(start 381.044958 -247.244108)
		(end 381.05334 -247.239282)
		(width 0.09525)
		(layer "In2.Cu")
		(net "M_I_CPU0_SA_DQS_DN<9>")
	)
	(segment
		(start 381.985012 -247.244108)
		(end 381.993394 -247.239282)
		(width 0.09525)
		(layer "In2.Cu")
		(net "M_I_CPU0_SA_DQS_DN<9>")
	)
	(segment
		(start 408.257248 -243.74856)
		(end 408.63012 -243.375688)
		(width 0.16002)
		(layer "In2.Cu")
		(net "M_I_CPU0_SA_DQS_DN<9>")
	)
	(segment
		(start 388.196328 -247.239282)
		(end 388.20471 -247.244108)
		(width 0.09525)
		(layer "In2.Cu")
		(net "M_I_CPU0_SA_DQS_DN<9>")
	)
	(segment
		(start 391.393426 -247.239282)
		(end 391.408158 -247.230646)
		(width 0.09525)
		(layer "In2.Cu")
		(net "M_I_CPU0_SA_DQS_DN<9>")
	)
	(segment
		(start 376.164856 -246.914162)
		(end 376.010932 -247.179592)
		(width 0.09525)
		(layer "In2.Cu")
		(net "M_I_CPU0_SA_DQS_DN<9>")
	)
	(segment
		(start 408.63012 -243.375688)
		(end 409.157424 -243.375688)
		(width 0.16002)
		(layer "In2.Cu")
		(net "M_I_CPU0_SA_DQS_DN<9>")
	)
	(segment
		(start 393.822428 -247.230646)
		(end 393.83716 -247.239282)
		(width 0.09525)
		(layer "In2.Cu")
		(net "M_I_CPU0_SA_DQS_DN<9>")
	)
	(segment
		(start 409.63088 -242.374928)
		(end 411.471872 -240.533936)
		(width 0.16002)
		(layer "In2.Cu")
		(net "M_I_CPU0_SA_DQS_DN<9>")
	)
	(segment
		(start 413.935164 -239.893094)
		(end 414.727644 -239.100614)
		(width 0.16002)
		(layer "In2.Cu")
		(net "M_I_CPU0_SA_DQS_DN<9>")
	)
	(segment
		(start 423.242486 -239.407954)
		(end 425.065698 -239.407954)
		(width 0.16002)
		(layer "In2.Cu")
		(net "M_I_CPU0_SA_DQS_DN<9>")
	)
	(segment
		(start 408.11069 -245.076218)
		(end 408.38755 -245.076218)
		(width 0.16002)
		(layer "In2.Cu")
		(net "M_I_CPU0_SA_DQS_DN<9>")
	)
	(segment
		(start 426.290994 -239.142778)
		(end 426.407834 -239.259618)
		(width 0.16002)
		(layer "In2.Cu")
		(net "M_I_CPU0_SA_DQS_DN<9>")
	)
	(segment
		(start 395.680184 -247.231408)
		(end 396.169642 -247.231408)
		(width 0.16002)
		(layer "In2.Cu")
		(net "M_I_CPU0_SA_DQS_DN<9>")
	)
	(segment
		(start 407.210514 -245.976394)
		(end 406.883616 -245.649496)
		(width 0.16002)
		(layer "In2.Cu")
		(net "M_I_CPU0_SA_DQS_DN<9>")
	)
	(segment
		(start 426.407834 -239.259618)
		(end 427.181518 -239.259618)
		(width 0.16002)
		(layer "In2.Cu")
		(net "M_I_CPU0_SA_DQS_DN<9>")
	)
	(segment
		(start 391.016236 -247.239282)
		(end 391.024618 -247.244108)
		(width 0.09525)
		(layer "In2.Cu")
		(net "M_I_CPU0_SA_DQS_DN<9>")
	)
	(segment
		(start 413.498284 -239.893094)
		(end 413.935164 -239.893094)
		(width 0.16002)
		(layer "In2.Cu")
		(net "M_I_CPU0_SA_DQS_DN<9>")
	)
	(segment
		(start 420.401496 -240.533936)
		(end 421.042338 -239.893094)
		(width 0.16002)
		(layer "In2.Cu")
		(net "M_I_CPU0_SA_DQS_DN<9>")
	)
	(segment
		(start 390.44499 -247.244108)
		(end 390.453372 -247.239282)
		(width 0.09525)
		(layer "In2.Cu")
		(net "M_I_CPU0_SA_DQS_DN<9>")
	)
	(segment
		(start 409.957778 -243.50599)
		(end 409.957778 -243.22913)
		(width 0.16002)
		(layer "In2.Cu")
		(net "M_I_CPU0_SA_DQS_DN<9>")
	)
	(segment
		(start 421.479218 -239.893094)
		(end 422.271698 -239.100614)
		(width 0.16002)
		(layer "In2.Cu")
		(net "M_I_CPU0_SA_DQS_DN<9>")
	)
	(segment
		(start 406.737058 -246.44985)
		(end 407.013918 -246.44985)
		(width 0.16002)
		(layer "In2.Cu")
		(net "M_I_CPU0_SA_DQS_DN<9>")
	)
	(segment
		(start 407.783792 -244.74932)
		(end 408.11069 -245.076218)
		(width 0.16002)
		(layer "In2.Cu")
		(net "M_I_CPU0_SA_DQS_DN<9>")
	)
	(segment
		(start 376.344942 -247.244108)
		(end 376.353324 -247.239282)
		(width 0.09525)
		(layer "In2.Cu")
		(net "M_I_CPU0_SA_DQS_DN<9>")
	)
	(segment
		(start 407.013918 -246.44985)
		(end 407.210514 -246.253254)
		(width 0.16002)
		(layer "In2.Cu")
		(net "M_I_CPU0_SA_DQS_DN<9>")
	)
	(segment
		(start 383.496312 -247.239282)
		(end 383.504694 -247.244108)
		(width 0.09525)
		(layer "In2.Cu")
		(net "M_I_CPU0_SA_DQS_DN<9>")
	)
	(segment
		(start 409.484322 -243.702586)
		(end 409.761182 -243.702586)
		(width 0.16002)
		(layer "In2.Cu")
		(net "M_I_CPU0_SA_DQS_DN<9>")
	)
	(segment
		(start 377.284996 -247.244108)
		(end 377.293378 -247.239282)
		(width 0.09525)
		(layer "In2.Cu")
		(net "M_I_CPU0_SA_DQS_DN<9>")
	)
	(segment
		(start 427.181518 -239.259618)
		(end 427.456092 -238.985044)
		(width 0.16002)
		(layer "In2.Cu")
		(net "M_I_CPU0_SA_DQS_DN<9>")
	)
	(segment
		(start 407.210514 -246.253254)
		(end 407.210514 -245.976394)
		(width 0.16002)
		(layer "In2.Cu")
		(net "M_I_CPU0_SA_DQS_DN<9>")
	)
	(segment
		(start 406.41016 -246.122952)
		(end 406.737058 -246.44985)
		(width 0.16002)
		(layer "In2.Cu")
		(net "M_I_CPU0_SA_DQS_DN<9>")
	)
	(segment
		(start 382.556258 -247.239282)
		(end 382.56464 -247.244108)
		(width 0.09525)
		(layer "In2.Cu")
		(net "M_I_CPU0_SA_DQS_DN<9>")
	)
	(segment
		(start 409.63088 -242.902232)
		(end 409.63088 -242.374928)
		(width 0.16002)
		(layer "In2.Cu")
		(net "M_I_CPU0_SA_DQS_DN<9>")
	)
	(arc
		(start 392.334242 -247.239282)
		(mid 392.606916 -247.163595)
		(end 392.881866 -247.230646)
		(width 0.09525)
		(layer "In2.Cu")
		(net "M_I_CPU0_SA_DQS_DN<9>")
	)
	(arc
		(start 382.933448 -247.239282)
		(mid 383.21488 -247.163527)
		(end 383.496312 -247.239282)
		(width 0.09525)
		(layer "In2.Cu")
		(net "M_I_CPU0_SA_DQS_DN<9>")
	)
	(arc
		(start 381.616204 -247.239282)
		(mid 381.799979 -247.290054)
		(end 381.985012 -247.244108)
		(width 0.09525)
		(layer "In2.Cu")
		(net "M_I_CPU0_SA_DQS_DN<9>")
	)
	(arc
		(start 390.076182 -247.239282)
		(mid 390.259957 -247.290054)
		(end 390.44499 -247.244108)
		(width 0.09525)
		(layer "In2.Cu")
		(net "M_I_CPU0_SA_DQS_DN<9>")
	)
	(arc
		(start 379.173486 -247.239282)
		(mid 379.454918 -247.163527)
		(end 379.73635 -247.239282)
		(width 0.09525)
		(layer "In2.Cu")
		(net "M_I_CPU0_SA_DQS_DN<9>")
	)
	(arc
		(start 383.873502 -247.239282)
		(mid 384.154934 -247.163527)
		(end 384.436366 -247.239282)
		(width 0.09525)
		(layer "In2.Cu")
		(net "M_I_CPU0_SA_DQS_DN<9>")
	)
	(arc
		(start 379.73635 -247.239282)
		(mid 379.924818 -247.289959)
		(end 380.113286 -247.239282)
		(width 0.09525)
		(layer "In2.Cu")
		(net "M_I_CPU0_SA_DQS_DN<9>")
	)
	(arc
		(start 376.353324 -247.239282)
		(mid 376.634756 -247.163527)
		(end 376.916188 -247.239282)
		(width 0.09525)
		(layer "In2.Cu")
		(net "M_I_CPU0_SA_DQS_DN<9>")
	)
	(arc
		(start 380.113286 -247.239282)
		(mid 380.394718 -247.163527)
		(end 380.67615 -247.239282)
		(width 0.09525)
		(layer "In2.Cu")
		(net "M_I_CPU0_SA_DQS_DN<9>")
	)
	(arc
		(start 391.408158 -247.230646)
		(mid 391.683617 -247.163261)
		(end 391.956798 -247.239282)
		(width 0.09525)
		(layer "In2.Cu")
		(net "M_I_CPU0_SA_DQS_DN<9>")
	)
	(arc
		(start 386.31622 -247.239282)
		(mid 386.499995 -247.290054)
		(end 386.685028 -247.244108)
		(width 0.09525)
		(layer "In2.Cu")
		(net "M_I_CPU0_SA_DQS_DN<9>")
	)
	(arc
		(start 393.83716 -247.239282)
		(mid 393.928126 -247.277435)
		(end 394.025882 -247.29059)
		(width 0.09525)
		(layer "In2.Cu")
		(net "M_I_CPU0_SA_DQS_DN<9>")
	)
	(arc
		(start 391.956798 -247.239282)
		(mid 392.138668 -247.290147)
		(end 392.322304 -247.24614)
		(width 0.09525)
		(layer "In2.Cu")
		(net "M_I_CPU0_SA_DQS_DN<9>")
	)
	(arc
		(start 377.864624 -247.244108)
		(mid 378.049656 -247.290022)
		(end 378.233432 -247.239282)
		(width 0.09525)
		(layer "In2.Cu")
		(net "M_I_CPU0_SA_DQS_DN<9>")
	)
	(arc
		(start 386.69341 -247.239282)
		(mid 386.974842 -247.163527)
		(end 387.256274 -247.239282)
		(width 0.09525)
		(layer "In2.Cu")
		(net "M_I_CPU0_SA_DQS_DN<9>")
	)
	(arc
		(start 390.453372 -247.239282)
		(mid 390.734804 -247.163527)
		(end 391.016236 -247.239282)
		(width 0.09525)
		(layer "In2.Cu")
		(net "M_I_CPU0_SA_DQS_DN<9>")
	)
	(arc
		(start 378.233432 -247.239282)
		(mid 378.514864 -247.163527)
		(end 378.796296 -247.239282)
		(width 0.09525)
		(layer "In2.Cu")
		(net "M_I_CPU0_SA_DQS_DN<9>")
	)
	(arc
		(start 381.993394 -247.239282)
		(mid 382.274826 -247.163527)
		(end 382.556258 -247.239282)
		(width 0.09525)
		(layer "In2.Cu")
		(net "M_I_CPU0_SA_DQS_DN<9>")
	)
	(arc
		(start 376.0343 -247.26646)
		(mid 376.19205 -247.288979)
		(end 376.344942 -247.244108)
		(width 0.09525)
		(layer "In2.Cu")
		(net "M_I_CPU0_SA_DQS_DN<9>")
	)
	(arc
		(start 393.273788 -247.239282)
		(mid 393.54697 -247.16334)
		(end 393.822428 -247.230646)
		(width 0.09525)
		(layer "In2.Cu")
		(net "M_I_CPU0_SA_DQS_DN<9>")
	)
	(arc
		(start 384.813302 -247.239282)
		(mid 385.094734 -247.163527)
		(end 385.376166 -247.239282)
		(width 0.09525)
		(layer "In2.Cu")
		(net "M_I_CPU0_SA_DQS_DN<9>")
	)
	(arc
		(start 384.436366 -247.239282)
		(mid 384.624834 -247.289959)
		(end 384.813302 -247.239282)
		(width 0.09525)
		(layer "In2.Cu")
		(net "M_I_CPU0_SA_DQS_DN<9>")
	)
	(arc
		(start 388.573518 -247.239282)
		(mid 388.85495 -247.163527)
		(end 389.136382 -247.239282)
		(width 0.09525)
		(layer "In2.Cu")
		(net "M_I_CPU0_SA_DQS_DN<9>")
	)
	(arc
		(start 387.264656 -247.244108)
		(mid 387.449688 -247.290022)
		(end 387.633464 -247.239282)
		(width 0.09525)
		(layer "In2.Cu")
		(net "M_I_CPU0_SA_DQS_DN<9>")
	)
	(arc
		(start 385.376166 -247.239282)
		(mid 385.559941 -247.290054)
		(end 385.744974 -247.244108)
		(width 0.09525)
		(layer "In2.Cu")
		(net "M_I_CPU0_SA_DQS_DN<9>")
	)
	(arc
		(start 387.633464 -247.239282)
		(mid 387.914896 -247.163527)
		(end 388.196328 -247.239282)
		(width 0.09525)
		(layer "In2.Cu")
		(net "M_I_CPU0_SA_DQS_DN<9>")
	)
	(arc
		(start 378.804678 -247.244108)
		(mid 378.98971 -247.290022)
		(end 379.173486 -247.239282)
		(width 0.09525)
		(layer "In2.Cu")
		(net "M_I_CPU0_SA_DQS_DN<9>")
	)
	(arc
		(start 383.504694 -247.244108)
		(mid 383.689726 -247.290022)
		(end 383.873502 -247.239282)
		(width 0.09525)
		(layer "In2.Cu")
		(net "M_I_CPU0_SA_DQS_DN<9>")
	)
	(arc
		(start 376.916188 -247.239282)
		(mid 377.099963 -247.290054)
		(end 377.284996 -247.244108)
		(width 0.09525)
		(layer "In2.Cu")
		(net "M_I_CPU0_SA_DQS_DN<9>")
	)
	(arc
		(start 392.911076 -247.247664)
		(mid 393.093508 -247.290104)
		(end 393.273788 -247.239282)
		(width 0.09525)
		(layer "In2.Cu")
		(net "M_I_CPU0_SA_DQS_DN<9>")
	)
	(arc
		(start 389.513318 -247.239282)
		(mid 389.79475 -247.163527)
		(end 390.076182 -247.239282)
		(width 0.09525)
		(layer "In2.Cu")
		(net "M_I_CPU0_SA_DQS_DN<9>")
	)
	(arc
		(start 381.05334 -247.239282)
		(mid 381.334772 -247.163527)
		(end 381.616204 -247.239282)
		(width 0.09525)
		(layer "In2.Cu")
		(net "M_I_CPU0_SA_DQS_DN<9>")
	)
	(arc
		(start 377.293378 -247.239282)
		(mid 377.57481 -247.163527)
		(end 377.856242 -247.239282)
		(width 0.09525)
		(layer "In2.Cu")
		(net "M_I_CPU0_SA_DQS_DN<9>")
	)
	(arc
		(start 385.753356 -247.239282)
		(mid 386.034788 -247.163527)
		(end 386.31622 -247.239282)
		(width 0.09525)
		(layer "In2.Cu")
		(net "M_I_CPU0_SA_DQS_DN<9>")
	)
	(arc
		(start 388.20471 -247.244108)
		(mid 388.389742 -247.290022)
		(end 388.573518 -247.239282)
		(width 0.09525)
		(layer "In2.Cu")
		(net "M_I_CPU0_SA_DQS_DN<9>")
	)
	(arc
		(start 391.024618 -247.244108)
		(mid 391.20965 -247.290022)
		(end 391.393426 -247.239282)
		(width 0.09525)
		(layer "In2.Cu")
		(net "M_I_CPU0_SA_DQS_DN<9>")
	)
	(arc
		(start 389.136382 -247.239282)
		(mid 389.32485 -247.289959)
		(end 389.513318 -247.239282)
		(width 0.09525)
		(layer "In2.Cu")
		(net "M_I_CPU0_SA_DQS_DN<9>")
	)
	(arc
		(start 382.56464 -247.244108)
		(mid 382.749672 -247.290022)
		(end 382.933448 -247.239282)
		(width 0.09525)
		(layer "In2.Cu")
		(net "M_I_CPU0_SA_DQS_DN<9>")
	)
	(arc
		(start 380.67615 -247.239282)
		(mid 380.859925 -247.290054)
		(end 381.044958 -247.244108)
		(width 0.09525)
		(layer "In2.Cu")
		(net "M_I_CPU0_SA_DQS_DN<9>")
	)
	(segment
		(start 375.698004 -242.320064)
		(end 376.164856 -242.054126)
		(width 0.12954)
		(layer "F.Cu")
		(net "M_I_CPU0_SA_DQS_DN<8>")
	)
	(segment
		(start 381.985012 -242.384072)
		(end 381.993394 -242.379246)
		(width 0.09525)
		(layer "In2.Cu")
		(net "M_I_CPU0_SA_DQS_DN<8>")
	)
	(segment
		(start 391.016236 -242.379246)
		(end 391.024618 -242.384072)
		(width 0.09525)
		(layer "In2.Cu")
		(net "M_I_CPU0_SA_DQS_DN<8>")
	)
	(segment
		(start 413.935164 -230.5431)
		(end 414.727644 -229.75062)
		(width 0.16002)
		(layer "In2.Cu")
		(net "M_I_CPU0_SA_DQS_DN<8>")
	)
	(segment
		(start 414.727644 -229.75062)
		(end 415.391092 -229.75062)
		(width 0.16002)
		(layer "In2.Cu")
		(net "M_I_CPU0_SA_DQS_DN<8>")
	)
	(segment
		(start 405.09317 -236.631734)
		(end 410.81706 -230.907844)
		(width 0.16002)
		(layer "In2.Cu")
		(net "M_I_CPU0_SA_DQS_DN<8>")
	)
	(segment
		(start 376.164856 -242.054126)
		(end 376.010932 -242.319556)
		(width 0.09525)
		(layer "In2.Cu")
		(net "M_I_CPU0_SA_DQS_DN<8>")
	)
	(segment
		(start 403.915372 -237.532672)
		(end 403.639274 -237.256574)
		(width 0.16002)
		(layer "In2.Cu")
		(net "M_I_CPU0_SA_DQS_DN<8>")
	)
	(segment
		(start 395.603222 -241.012472)
		(end 395.662404 -240.95329)
		(width 0.09525)
		(layer "In2.Cu")
		(net "M_I_CPU0_SA_DQS_DN<8>")
	)
	(segment
		(start 394.168376 -241.94389)
		(end 394.769848 -241.94389)
		(width 0.09525)
		(layer "In2.Cu")
		(net "M_I_CPU0_SA_DQS_DN<8>")
	)
	(segment
		(start 376.010932 -242.319556)
		(end 376.0343 -242.406424)
		(width 0.09525)
		(layer "In2.Cu")
		(net "M_I_CPU0_SA_DQS_DN<8>")
	)
	(segment
		(start 404.81631 -236.631734)
		(end 405.09317 -236.631734)
		(width 0.16002)
		(layer "In2.Cu")
		(net "M_I_CPU0_SA_DQS_DN<8>")
	)
	(segment
		(start 425.813728 -229.909624)
		(end 425.930568 -229.792784)
		(width 0.16002)
		(layer "In2.Cu")
		(net "M_I_CPU0_SA_DQS_DN<8>")
	)
	(segment
		(start 386.685028 -242.384072)
		(end 386.69341 -242.379246)
		(width 0.09525)
		(layer "In2.Cu")
		(net "M_I_CPU0_SA_DQS_DN<8>")
	)
	(segment
		(start 381.044958 -242.384072)
		(end 381.05334 -242.379246)
		(width 0.09525)
		(layer "In2.Cu")
		(net "M_I_CPU0_SA_DQS_DN<8>")
	)
	(segment
		(start 392.881866 -242.37061)
		(end 392.896598 -242.379246)
		(width 0.09525)
		(layer "In2.Cu")
		(net "M_I_CPU0_SA_DQS_DN<8>")
	)
	(segment
		(start 404.013416 -236.355382)
		(end 404.540212 -236.355636)
		(width 0.16002)
		(layer "In2.Cu")
		(net "M_I_CPU0_SA_DQS_DN<8>")
	)
	(segment
		(start 403.442678 -238.005366)
		(end 403.719538 -238.005366)
		(width 0.16002)
		(layer "In2.Cu")
		(net "M_I_CPU0_SA_DQS_DN<8>")
	)
	(segment
		(start 426.527468 -229.909624)
		(end 427.181518 -229.909624)
		(width 0.16002)
		(layer "In2.Cu")
		(net "M_I_CPU0_SA_DQS_DN<8>")
	)
	(segment
		(start 393.59332 -242.07851)
		(end 394.033756 -242.07851)
		(width 0.09525)
		(layer "In2.Cu")
		(net "M_I_CPU0_SA_DQS_DN<8>")
	)
	(segment
		(start 395.050518 -241.66322)
		(end 395.050518 -241.223292)
		(width 0.09525)
		(layer "In2.Cu")
		(net "M_I_CPU0_SA_DQS_DN<8>")
	)
	(segment
		(start 402.345906 -239.378998)
		(end 402.54174 -239.183164)
		(width 0.16002)
		(layer "In2.Cu")
		(net "M_I_CPU0_SA_DQS_DN<8>")
	)
	(segment
		(start 395.686026 -240.95329)
		(end 400.771614 -240.95329)
		(width 0.16002)
		(layer "In2.Cu")
		(net "M_I_CPU0_SA_DQS_DN<8>")
	)
	(segment
		(start 421.479218 -230.5431)
		(end 422.271698 -229.75062)
		(width 0.16002)
		(layer "In2.Cu")
		(net "M_I_CPU0_SA_DQS_DN<8>")
	)
	(segment
		(start 382.556258 -242.379246)
		(end 382.56464 -242.384072)
		(width 0.09525)
		(layer "In2.Cu")
		(net "M_I_CPU0_SA_DQS_DN<8>")
	)
	(segment
		(start 395.662404 -240.95329)
		(end 395.686026 -240.95329)
		(width 0.09525)
		(layer "In2.Cu")
		(net "M_I_CPU0_SA_DQS_DN<8>")
	)
	(segment
		(start 427.181518 -229.909624)
		(end 427.456092 -229.63505)
		(width 0.16002)
		(layer "In2.Cu")
		(net "M_I_CPU0_SA_DQS_DN<8>")
	)
	(segment
		(start 395.261338 -241.012472)
		(end 395.603222 -241.012472)
		(width 0.09525)
		(layer "In2.Cu")
		(net "M_I_CPU0_SA_DQS_DN<8>")
	)
	(segment
		(start 419.012116 -230.908098)
		(end 420.67734 -230.908098)
		(width 0.16002)
		(layer "In2.Cu")
		(net "M_I_CPU0_SA_DQS_DN<8>")
	)
	(segment
		(start 391.393426 -242.379246)
		(end 391.40384 -242.37315)
		(width 0.09525)
		(layer "In2.Cu")
		(net "M_I_CPU0_SA_DQS_DN<8>")
	)
	(segment
		(start 415.698432 -230.05796)
		(end 418.161978 -230.05796)
		(width 0.16002)
		(layer "In2.Cu")
		(net "M_I_CPU0_SA_DQS_DN<8>")
	)
	(segment
		(start 401.168108 -240.279936)
		(end 400.89201 -240.003838)
		(width 0.16002)
		(layer "In2.Cu")
		(net "M_I_CPU0_SA_DQS_DN<8>")
	)
	(segment
		(start 393.351258 -242.320572)
		(end 393.59332 -242.07851)
		(width 0.09525)
		(layer "In2.Cu")
		(net "M_I_CPU0_SA_DQS_DN<8>")
	)
	(segment
		(start 404.540212 -236.355636)
		(end 404.81631 -236.631734)
		(width 0.16002)
		(layer "In2.Cu")
		(net "M_I_CPU0_SA_DQS_DN<8>")
	)
	(segment
		(start 415.391092 -229.75062)
		(end 415.698432 -230.05796)
		(width 0.16002)
		(layer "In2.Cu")
		(net "M_I_CPU0_SA_DQS_DN<8>")
	)
	(segment
		(start 378.796296 -242.379246)
		(end 378.804678 -242.384072)
		(width 0.09525)
		(layer "In2.Cu")
		(net "M_I_CPU0_SA_DQS_DN<8>")
	)
	(segment
		(start 421.042338 -230.5431)
		(end 421.479218 -230.5431)
		(width 0.16002)
		(layer "In2.Cu")
		(net "M_I_CPU0_SA_DQS_DN<8>")
	)
	(segment
		(start 402.54174 -238.906304)
		(end 402.265642 -238.630206)
		(width 0.16002)
		(layer "In2.Cu")
		(net "M_I_CPU0_SA_DQS_DN<8>")
	)
	(segment
		(start 400.89201 -240.003838)
		(end 400.892264 -239.476534)
		(width 0.16002)
		(layer "In2.Cu")
		(net "M_I_CPU0_SA_DQS_DN<8>")
	)
	(segment
		(start 388.196328 -242.379246)
		(end 388.20471 -242.384072)
		(width 0.09525)
		(layer "In2.Cu")
		(net "M_I_CPU0_SA_DQS_DN<8>")
	)
	(segment
		(start 418.161978 -230.05796)
		(end 419.012116 -230.908098)
		(width 0.16002)
		(layer "In2.Cu")
		(net "M_I_CPU0_SA_DQS_DN<8>")
	)
	(segment
		(start 400.892264 -239.476534)
		(end 401.266152 -239.102646)
		(width 0.16002)
		(layer "In2.Cu")
		(net "M_I_CPU0_SA_DQS_DN<8>")
	)
	(segment
		(start 401.266152 -239.102646)
		(end 401.792948 -239.1029)
		(width 0.16002)
		(layer "In2.Cu")
		(net "M_I_CPU0_SA_DQS_DN<8>")
	)
	(segment
		(start 392.32586 -242.384072)
		(end 392.334242 -242.379246)
		(width 0.09525)
		(layer "In2.Cu")
		(net "M_I_CPU0_SA_DQS_DN<8>")
	)
	(segment
		(start 403.915372 -237.809532)
		(end 403.915372 -237.532672)
		(width 0.16002)
		(layer "In2.Cu")
		(net "M_I_CPU0_SA_DQS_DN<8>")
	)
	(segment
		(start 401.792948 -239.1029)
		(end 402.069046 -239.378998)
		(width 0.16002)
		(layer "In2.Cu")
		(net "M_I_CPU0_SA_DQS_DN<8>")
	)
	(segment
		(start 403.639274 -237.256574)
		(end 403.639528 -236.72927)
		(width 0.16002)
		(layer "In2.Cu")
		(net "M_I_CPU0_SA_DQS_DN<8>")
	)
	(segment
		(start 392.896598 -242.379246)
		(end 392.911076 -242.387628)
		(width 0.09525)
		(layer "In2.Cu")
		(net "M_I_CPU0_SA_DQS_DN<8>")
	)
	(segment
		(start 402.54174 -239.183164)
		(end 402.54174 -238.906304)
		(width 0.16002)
		(layer "In2.Cu")
		(net "M_I_CPU0_SA_DQS_DN<8>")
	)
	(segment
		(start 425.930568 -229.792784)
		(end 426.410628 -229.792784)
		(width 0.16002)
		(layer "In2.Cu")
		(net "M_I_CPU0_SA_DQS_DN<8>")
	)
	(segment
		(start 402.265896 -238.102902)
		(end 402.639784 -237.729014)
		(width 0.16002)
		(layer "In2.Cu")
		(net "M_I_CPU0_SA_DQS_DN<8>")
	)
	(segment
		(start 413.13354 -230.907844)
		(end 413.498284 -230.5431)
		(width 0.16002)
		(layer "In2.Cu")
		(net "M_I_CPU0_SA_DQS_DN<8>")
	)
	(segment
		(start 401.168108 -240.556796)
		(end 401.168108 -240.279936)
		(width 0.16002)
		(layer "In2.Cu")
		(net "M_I_CPU0_SA_DQS_DN<8>")
	)
	(segment
		(start 425.214034 -229.909624)
		(end 425.813728 -229.909624)
		(width 0.16002)
		(layer "In2.Cu")
		(net "M_I_CPU0_SA_DQS_DN<8>")
	)
	(segment
		(start 385.744974 -242.384072)
		(end 385.753356 -242.379246)
		(width 0.09525)
		(layer "In2.Cu")
		(net "M_I_CPU0_SA_DQS_DN<8>")
	)
	(segment
		(start 377.284996 -242.384072)
		(end 377.293378 -242.379246)
		(width 0.09525)
		(layer "In2.Cu")
		(net "M_I_CPU0_SA_DQS_DN<8>")
	)
	(segment
		(start 420.67734 -230.908098)
		(end 421.042338 -230.5431)
		(width 0.16002)
		(layer "In2.Cu")
		(net "M_I_CPU0_SA_DQS_DN<8>")
	)
	(segment
		(start 410.81706 -230.907844)
		(end 413.13354 -230.907844)
		(width 0.16002)
		(layer "In2.Cu")
		(net "M_I_CPU0_SA_DQS_DN<8>")
	)
	(segment
		(start 394.033756 -242.07851)
		(end 394.168376 -241.94389)
		(width 0.09525)
		(layer "In2.Cu")
		(net "M_I_CPU0_SA_DQS_DN<8>")
	)
	(segment
		(start 377.856242 -242.379246)
		(end 377.864624 -242.384072)
		(width 0.09525)
		(layer "In2.Cu")
		(net "M_I_CPU0_SA_DQS_DN<8>")
	)
	(segment
		(start 402.639784 -237.729014)
		(end 403.16658 -237.729268)
		(width 0.16002)
		(layer "In2.Cu")
		(net "M_I_CPU0_SA_DQS_DN<8>")
	)
	(segment
		(start 402.265642 -238.630206)
		(end 402.265896 -238.102902)
		(width 0.16002)
		(layer "In2.Cu")
		(net "M_I_CPU0_SA_DQS_DN<8>")
	)
	(segment
		(start 425.065698 -230.05796)
		(end 425.214034 -229.909624)
		(width 0.16002)
		(layer "In2.Cu")
		(net "M_I_CPU0_SA_DQS_DN<8>")
	)
	(segment
		(start 413.498284 -230.5431)
		(end 413.935164 -230.5431)
		(width 0.16002)
		(layer "In2.Cu")
		(net "M_I_CPU0_SA_DQS_DN<8>")
	)
	(segment
		(start 403.16658 -237.729268)
		(end 403.442678 -238.005366)
		(width 0.16002)
		(layer "In2.Cu")
		(net "M_I_CPU0_SA_DQS_DN<8>")
	)
	(segment
		(start 423.242486 -230.05796)
		(end 425.065698 -230.05796)
		(width 0.16002)
		(layer "In2.Cu")
		(net "M_I_CPU0_SA_DQS_DN<8>")
	)
	(segment
		(start 422.271698 -229.75062)
		(end 422.935146 -229.75062)
		(width 0.16002)
		(layer "In2.Cu")
		(net "M_I_CPU0_SA_DQS_DN<8>")
	)
	(segment
		(start 400.771614 -240.95329)
		(end 401.168108 -240.556796)
		(width 0.16002)
		(layer "In2.Cu")
		(net "M_I_CPU0_SA_DQS_DN<8>")
	)
	(segment
		(start 395.050518 -241.223292)
		(end 395.261338 -241.012472)
		(width 0.09525)
		(layer "In2.Cu")
		(net "M_I_CPU0_SA_DQS_DN<8>")
	)
	(segment
		(start 387.256274 -242.379246)
		(end 387.264656 -242.384072)
		(width 0.09525)
		(layer "In2.Cu")
		(net "M_I_CPU0_SA_DQS_DN<8>")
	)
	(segment
		(start 403.639528 -236.72927)
		(end 404.013416 -236.355382)
		(width 0.16002)
		(layer "In2.Cu")
		(net "M_I_CPU0_SA_DQS_DN<8>")
	)
	(segment
		(start 390.44499 -242.384072)
		(end 390.453372 -242.379246)
		(width 0.09525)
		(layer "In2.Cu")
		(net "M_I_CPU0_SA_DQS_DN<8>")
	)
	(segment
		(start 426.410628 -229.792784)
		(end 426.527468 -229.909624)
		(width 0.16002)
		(layer "In2.Cu")
		(net "M_I_CPU0_SA_DQS_DN<8>")
	)
	(segment
		(start 376.344942 -242.384072)
		(end 376.353324 -242.379246)
		(width 0.09525)
		(layer "In2.Cu")
		(net "M_I_CPU0_SA_DQS_DN<8>")
	)
	(segment
		(start 422.935146 -229.75062)
		(end 423.242486 -230.05796)
		(width 0.16002)
		(layer "In2.Cu")
		(net "M_I_CPU0_SA_DQS_DN<8>")
	)
	(segment
		(start 403.719538 -238.005366)
		(end 403.915372 -237.809532)
		(width 0.16002)
		(layer "In2.Cu")
		(net "M_I_CPU0_SA_DQS_DN<8>")
	)
	(segment
		(start 394.769848 -241.94389)
		(end 395.050518 -241.66322)
		(width 0.09525)
		(layer "In2.Cu")
		(net "M_I_CPU0_SA_DQS_DN<8>")
	)
	(segment
		(start 383.496312 -242.379246)
		(end 383.504694 -242.384072)
		(width 0.09525)
		(layer "In2.Cu")
		(net "M_I_CPU0_SA_DQS_DN<8>")
	)
	(segment
		(start 402.069046 -239.378998)
		(end 402.345906 -239.378998)
		(width 0.16002)
		(layer "In2.Cu")
		(net "M_I_CPU0_SA_DQS_DN<8>")
	)
	(arc
		(start 377.864624 -242.384072)
		(mid 378.049656 -242.429986)
		(end 378.233432 -242.379246)
		(width 0.09525)
		(layer "In2.Cu")
		(net "M_I_CPU0_SA_DQS_DN<8>")
	)
	(arc
		(start 384.436366 -242.379246)
		(mid 384.624834 -242.429923)
		(end 384.813302 -242.379246)
		(width 0.09525)
		(layer "In2.Cu")
		(net "M_I_CPU0_SA_DQS_DN<8>")
	)
	(arc
		(start 383.873502 -242.379246)
		(mid 384.154934 -242.303491)
		(end 384.436366 -242.379246)
		(width 0.09525)
		(layer "In2.Cu")
		(net "M_I_CPU0_SA_DQS_DN<8>")
	)
	(arc
		(start 379.173486 -242.379246)
		(mid 379.454918 -242.303491)
		(end 379.73635 -242.379246)
		(width 0.09525)
		(layer "In2.Cu")
		(net "M_I_CPU0_SA_DQS_DN<8>")
	)
	(arc
		(start 376.916188 -242.379246)
		(mid 377.099963 -242.430018)
		(end 377.284996 -242.384072)
		(width 0.09525)
		(layer "In2.Cu")
		(net "M_I_CPU0_SA_DQS_DN<8>")
	)
	(arc
		(start 389.136382 -242.379246)
		(mid 389.32485 -242.429923)
		(end 389.513318 -242.379246)
		(width 0.09525)
		(layer "In2.Cu")
		(net "M_I_CPU0_SA_DQS_DN<8>")
	)
	(arc
		(start 392.334242 -242.379246)
		(mid 392.606916 -242.303559)
		(end 392.881866 -242.37061)
		(width 0.09525)
		(layer "In2.Cu")
		(net "M_I_CPU0_SA_DQS_DN<8>")
	)
	(arc
		(start 382.56464 -242.384072)
		(mid 382.749672 -242.429986)
		(end 382.933448 -242.379246)
		(width 0.09525)
		(layer "In2.Cu")
		(net "M_I_CPU0_SA_DQS_DN<8>")
	)
	(arc
		(start 392.911076 -242.387628)
		(mid 393.093508 -242.430068)
		(end 393.273788 -242.379246)
		(width 0.09525)
		(layer "In2.Cu")
		(net "M_I_CPU0_SA_DQS_DN<8>")
	)
	(arc
		(start 376.0343 -242.406424)
		(mid 376.19205 -242.428943)
		(end 376.344942 -242.384072)
		(width 0.09525)
		(layer "In2.Cu")
		(net "M_I_CPU0_SA_DQS_DN<8>")
	)
	(arc
		(start 380.113286 -242.379246)
		(mid 380.394718 -242.303491)
		(end 380.67615 -242.379246)
		(width 0.09525)
		(layer "In2.Cu")
		(net "M_I_CPU0_SA_DQS_DN<8>")
	)
	(arc
		(start 381.05334 -242.379246)
		(mid 381.334772 -242.303491)
		(end 381.616204 -242.379246)
		(width 0.09525)
		(layer "In2.Cu")
		(net "M_I_CPU0_SA_DQS_DN<8>")
	)
	(arc
		(start 390.453372 -242.379246)
		(mid 390.734804 -242.303491)
		(end 391.016236 -242.379246)
		(width 0.09525)
		(layer "In2.Cu")
		(net "M_I_CPU0_SA_DQS_DN<8>")
	)
	(arc
		(start 387.633464 -242.379246)
		(mid 387.914896 -242.303491)
		(end 388.196328 -242.379246)
		(width 0.09525)
		(layer "In2.Cu")
		(net "M_I_CPU0_SA_DQS_DN<8>")
	)
	(arc
		(start 384.813302 -242.379246)
		(mid 385.094734 -242.303491)
		(end 385.376166 -242.379246)
		(width 0.09525)
		(layer "In2.Cu")
		(net "M_I_CPU0_SA_DQS_DN<8>")
	)
	(arc
		(start 389.513318 -242.379246)
		(mid 389.79475 -242.303491)
		(end 390.076182 -242.379246)
		(width 0.09525)
		(layer "In2.Cu")
		(net "M_I_CPU0_SA_DQS_DN<8>")
	)
	(arc
		(start 382.933448 -242.379246)
		(mid 383.21488 -242.303491)
		(end 383.496312 -242.379246)
		(width 0.09525)
		(layer "In2.Cu")
		(net "M_I_CPU0_SA_DQS_DN<8>")
	)
	(arc
		(start 376.353324 -242.379246)
		(mid 376.634756 -242.303491)
		(end 376.916188 -242.379246)
		(width 0.09525)
		(layer "In2.Cu")
		(net "M_I_CPU0_SA_DQS_DN<8>")
	)
	(arc
		(start 381.993394 -242.379246)
		(mid 382.274826 -242.303491)
		(end 382.556258 -242.379246)
		(width 0.09525)
		(layer "In2.Cu")
		(net "M_I_CPU0_SA_DQS_DN<8>")
	)
	(arc
		(start 386.31622 -242.379246)
		(mid 386.499995 -242.430018)
		(end 386.685028 -242.384072)
		(width 0.09525)
		(layer "In2.Cu")
		(net "M_I_CPU0_SA_DQS_DN<8>")
	)
	(arc
		(start 390.076182 -242.379246)
		(mid 390.259957 -242.430018)
		(end 390.44499 -242.384072)
		(width 0.09525)
		(layer "In2.Cu")
		(net "M_I_CPU0_SA_DQS_DN<8>")
	)
	(arc
		(start 393.273788 -242.379246)
		(mid 393.31442 -242.352415)
		(end 393.351258 -242.320572)
		(width 0.09525)
		(layer "In2.Cu")
		(net "M_I_CPU0_SA_DQS_DN<8>")
	)
	(arc
		(start 378.233432 -242.379246)
		(mid 378.514864 -242.303491)
		(end 378.796296 -242.379246)
		(width 0.09525)
		(layer "In2.Cu")
		(net "M_I_CPU0_SA_DQS_DN<8>")
	)
	(arc
		(start 385.376166 -242.379246)
		(mid 385.559941 -242.430018)
		(end 385.744974 -242.384072)
		(width 0.09525)
		(layer "In2.Cu")
		(net "M_I_CPU0_SA_DQS_DN<8>")
	)
	(arc
		(start 381.616204 -242.379246)
		(mid 381.799979 -242.430018)
		(end 381.985012 -242.384072)
		(width 0.09525)
		(layer "In2.Cu")
		(net "M_I_CPU0_SA_DQS_DN<8>")
	)
	(arc
		(start 387.264656 -242.384072)
		(mid 387.449688 -242.429986)
		(end 387.633464 -242.379246)
		(width 0.09525)
		(layer "In2.Cu")
		(net "M_I_CPU0_SA_DQS_DN<8>")
	)
	(arc
		(start 391.956544 -242.379246)
		(mid 392.140573 -242.430145)
		(end 392.32586 -242.384072)
		(width 0.09525)
		(layer "In2.Cu")
		(net "M_I_CPU0_SA_DQS_DN<8>")
	)
	(arc
		(start 385.753356 -242.379246)
		(mid 386.034788 -242.303491)
		(end 386.31622 -242.379246)
		(width 0.09525)
		(layer "In2.Cu")
		(net "M_I_CPU0_SA_DQS_DN<8>")
	)
	(arc
		(start 388.573518 -242.379246)
		(mid 388.85495 -242.303491)
		(end 389.136382 -242.379246)
		(width 0.09525)
		(layer "In2.Cu")
		(net "M_I_CPU0_SA_DQS_DN<8>")
	)
	(arc
		(start 386.69341 -242.379246)
		(mid 386.974842 -242.303491)
		(end 387.256274 -242.379246)
		(width 0.09525)
		(layer "In2.Cu")
		(net "M_I_CPU0_SA_DQS_DN<8>")
	)
	(arc
		(start 391.024618 -242.384072)
		(mid 391.20965 -242.429986)
		(end 391.393426 -242.379246)
		(width 0.09525)
		(layer "In2.Cu")
		(net "M_I_CPU0_SA_DQS_DN<8>")
	)
	(arc
		(start 379.73635 -242.379246)
		(mid 379.924818 -242.429923)
		(end 380.113286 -242.379246)
		(width 0.09525)
		(layer "In2.Cu")
		(net "M_I_CPU0_SA_DQS_DN<8>")
	)
	(arc
		(start 377.293378 -242.379246)
		(mid 377.57481 -242.303491)
		(end 377.856242 -242.379246)
		(width 0.09525)
		(layer "In2.Cu")
		(net "M_I_CPU0_SA_DQS_DN<8>")
	)
	(arc
		(start 388.20471 -242.384072)
		(mid 388.389742 -242.429986)
		(end 388.573518 -242.379246)
		(width 0.09525)
		(layer "In2.Cu")
		(net "M_I_CPU0_SA_DQS_DN<8>")
	)
	(arc
		(start 378.804678 -242.384072)
		(mid 378.98971 -242.429986)
		(end 379.173486 -242.379246)
		(width 0.09525)
		(layer "In2.Cu")
		(net "M_I_CPU0_SA_DQS_DN<8>")
	)
	(arc
		(start 383.504694 -242.384072)
		(mid 383.689726 -242.429986)
		(end 383.873502 -242.379246)
		(width 0.09525)
		(layer "In2.Cu")
		(net "M_I_CPU0_SA_DQS_DN<8>")
	)
	(arc
		(start 380.67615 -242.379246)
		(mid 380.859925 -242.430018)
		(end 381.044958 -242.384072)
		(width 0.09525)
		(layer "In2.Cu")
		(net "M_I_CPU0_SA_DQS_DN<8>")
	)
	(arc
		(start 391.40384 -242.37315)
		(mid 391.681002 -242.30335)
		(end 391.956544 -242.379246)
		(width 0.09525)
		(layer "In2.Cu")
		(net "M_I_CPU0_SA_DQS_DN<8>")
	)
	(segment
		(start 375.698004 -237.460028)
		(end 376.164856 -237.19409)
		(width 0.12954)
		(layer "F.Cu")
		(net "M_I_CPU0_SA_DQS_DN<7>")
	)
	(segment
		(start 400.45259 -231.992932)
		(end 400.256756 -232.188766)
		(width 0.16002)
		(layer "In2.Cu")
		(net "M_I_CPU0_SA_DQS_DN<7>")
	)
	(segment
		(start 426.448728 -220.55963)
		(end 426.331888 -220.44279)
		(width 0.16002)
		(layer "In2.Cu")
		(net "M_I_CPU0_SA_DQS_DN<7>")
	)
	(segment
		(start 397.374872 -235.07065)
		(end 395.657324 -235.07065)
		(width 0.16002)
		(layer "In2.Cu")
		(net "M_I_CPU0_SA_DQS_DN<7>")
	)
	(segment
		(start 399.078958 -233.366564)
		(end 398.883124 -233.562398)
		(width 0.16002)
		(layer "In2.Cu")
		(net "M_I_CPU0_SA_DQS_DN<7>")
	)
	(segment
		(start 399.078958 -233.089704)
		(end 399.078958 -233.366564)
		(width 0.16002)
		(layer "In2.Cu")
		(net "M_I_CPU0_SA_DQS_DN<7>")
	)
	(segment
		(start 420.677594 -221.55785)
		(end 419.011862 -221.55785)
		(width 0.16002)
		(layer "In2.Cu")
		(net "M_I_CPU0_SA_DQS_DN<7>")
	)
	(segment
		(start 401.081494 -230.5431)
		(end 400.55419 -230.5431)
		(width 0.16002)
		(layer "In2.Cu")
		(net "M_I_CPU0_SA_DQS_DN<7>")
	)
	(segment
		(start 397.705326 -234.463336)
		(end 397.705326 -234.740196)
		(width 0.16002)
		(layer "In2.Cu")
		(net "M_I_CPU0_SA_DQS_DN<7>")
	)
	(segment
		(start 400.55419 -230.5431)
		(end 400.180556 -230.916734)
		(width 0.16002)
		(layer "In2.Cu")
		(net "M_I_CPU0_SA_DQS_DN<7>")
	)
	(segment
		(start 399.979896 -232.188766)
		(end 399.707862 -231.916732)
		(width 0.16002)
		(layer "In2.Cu")
		(net "M_I_CPU0_SA_DQS_DN<7>")
	)
	(segment
		(start 401.554188 -229.543102)
		(end 401.554188 -230.070406)
		(width 0.16002)
		(layer "In2.Cu")
		(net "M_I_CPU0_SA_DQS_DN<7>")
	)
	(segment
		(start 378.804678 -237.524036)
		(end 378.796296 -237.51921)
		(width 0.09525)
		(layer "In2.Cu")
		(net "M_I_CPU0_SA_DQS_DN<7>")
	)
	(segment
		(start 415.391092 -220.400626)
		(end 414.727644 -220.400626)
		(width 0.16002)
		(layer "In2.Cu")
		(net "M_I_CPU0_SA_DQS_DN<7>")
	)
	(segment
		(start 425.065698 -220.707966)
		(end 423.242486 -220.707966)
		(width 0.16002)
		(layer "In2.Cu")
		(net "M_I_CPU0_SA_DQS_DN<7>")
	)
	(segment
		(start 395.57452 -235.129832)
		(end 395.117066 -235.129832)
		(width 0.09525)
		(layer "In2.Cu")
		(net "M_I_CPU0_SA_DQS_DN<7>")
	)
	(segment
		(start 422.935146 -220.400626)
		(end 422.271698 -220.400626)
		(width 0.16002)
		(layer "In2.Cu")
		(net "M_I_CPU0_SA_DQS_DN<7>")
	)
	(segment
		(start 401.826222 -230.6193)
		(end 401.630388 -230.815134)
		(width 0.16002)
		(layer "In2.Cu")
		(net "M_I_CPU0_SA_DQS_DN<7>")
	)
	(segment
		(start 414.727644 -220.400626)
		(end 413.935164 -221.193106)
		(width 0.16002)
		(layer "In2.Cu")
		(net "M_I_CPU0_SA_DQS_DN<7>")
	)
	(segment
		(start 425.734988 -220.55963)
		(end 425.214034 -220.55963)
		(width 0.16002)
		(layer "In2.Cu")
		(net "M_I_CPU0_SA_DQS_DN<7>")
	)
	(segment
		(start 400.256756 -232.188766)
		(end 399.979896 -232.188766)
		(width 0.16002)
		(layer "In2.Cu")
		(net "M_I_CPU0_SA_DQS_DN<7>")
	)
	(segment
		(start 425.214034 -220.55963)
		(end 425.065698 -220.707966)
		(width 0.16002)
		(layer "In2.Cu")
		(net "M_I_CPU0_SA_DQS_DN<7>")
	)
	(segment
		(start 413.935164 -221.193106)
		(end 413.498284 -221.193106)
		(width 0.16002)
		(layer "In2.Cu")
		(net "M_I_CPU0_SA_DQS_DN<7>")
	)
	(segment
		(start 409.53944 -221.55785)
		(end 401.554188 -229.543102)
		(width 0.16002)
		(layer "In2.Cu")
		(net "M_I_CPU0_SA_DQS_DN<7>")
	)
	(segment
		(start 388.20471 -237.524036)
		(end 388.196328 -237.51921)
		(width 0.09525)
		(layer "In2.Cu")
		(net "M_I_CPU0_SA_DQS_DN<7>")
	)
	(segment
		(start 385.753356 -237.51921)
		(end 385.744974 -237.524036)
		(width 0.09525)
		(layer "In2.Cu")
		(net "M_I_CPU0_SA_DQS_DN<7>")
	)
	(segment
		(start 413.498284 -221.193106)
		(end 413.13354 -221.55785)
		(width 0.16002)
		(layer "In2.Cu")
		(net "M_I_CPU0_SA_DQS_DN<7>")
	)
	(segment
		(start 390.453372 -237.51921)
		(end 390.44499 -237.524036)
		(width 0.09525)
		(layer "In2.Cu")
		(net "M_I_CPU0_SA_DQS_DN<7>")
	)
	(segment
		(start 400.180556 -231.444038)
		(end 400.45259 -231.716072)
		(width 0.16002)
		(layer "In2.Cu")
		(net "M_I_CPU0_SA_DQS_DN<7>")
	)
	(segment
		(start 398.606264 -233.562398)
		(end 398.33423 -233.290364)
		(width 0.16002)
		(layer "In2.Cu")
		(net "M_I_CPU0_SA_DQS_DN<7>")
	)
	(segment
		(start 382.56464 -237.524036)
		(end 382.556258 -237.51921)
		(width 0.09525)
		(layer "In2.Cu")
		(net "M_I_CPU0_SA_DQS_DN<7>")
	)
	(segment
		(start 423.242486 -220.707966)
		(end 422.935146 -220.400626)
		(width 0.16002)
		(layer "In2.Cu")
		(net "M_I_CPU0_SA_DQS_DN<7>")
	)
	(segment
		(start 397.433292 -233.663998)
		(end 397.433292 -234.191302)
		(width 0.16002)
		(layer "In2.Cu")
		(net "M_I_CPU0_SA_DQS_DN<7>")
	)
	(segment
		(start 398.806924 -232.81767)
		(end 399.078958 -233.089704)
		(width 0.16002)
		(layer "In2.Cu")
		(net "M_I_CPU0_SA_DQS_DN<7>")
	)
	(segment
		(start 399.180558 -231.916732)
		(end 398.806924 -232.290366)
		(width 0.16002)
		(layer "In2.Cu")
		(net "M_I_CPU0_SA_DQS_DN<7>")
	)
	(segment
		(start 400.45259 -231.716072)
		(end 400.45259 -231.992932)
		(width 0.16002)
		(layer "In2.Cu")
		(net "M_I_CPU0_SA_DQS_DN<7>")
	)
	(segment
		(start 401.353528 -230.815134)
		(end 401.081494 -230.5431)
		(width 0.16002)
		(layer "In2.Cu")
		(net "M_I_CPU0_SA_DQS_DN<7>")
	)
	(segment
		(start 397.433292 -234.191302)
		(end 397.705326 -234.463336)
		(width 0.16002)
		(layer "In2.Cu")
		(net "M_I_CPU0_SA_DQS_DN<7>")
	)
	(segment
		(start 391.024618 -237.524036)
		(end 391.016236 -237.51921)
		(width 0.09525)
		(layer "In2.Cu")
		(net "M_I_CPU0_SA_DQS_DN<7>")
	)
	(segment
		(start 376.353324 -237.51921)
		(end 376.344942 -237.524036)
		(width 0.09525)
		(layer "In2.Cu")
		(net "M_I_CPU0_SA_DQS_DN<7>")
	)
	(segment
		(start 377.864624 -237.524036)
		(end 377.856242 -237.51921)
		(width 0.09525)
		(layer "In2.Cu")
		(net "M_I_CPU0_SA_DQS_DN<7>")
	)
	(segment
		(start 401.554188 -230.070406)
		(end 401.826222 -230.34244)
		(width 0.16002)
		(layer "In2.Cu")
		(net "M_I_CPU0_SA_DQS_DN<7>")
	)
	(segment
		(start 400.180556 -230.916734)
		(end 400.180556 -231.444038)
		(width 0.16002)
		(layer "In2.Cu")
		(net "M_I_CPU0_SA_DQS_DN<7>")
	)
	(segment
		(start 391.854436 -237.443518)
		(end 391.674858 -237.443518)
		(width 0.09525)
		(layer "In2.Cu")
		(net "M_I_CPU0_SA_DQS_DN<7>")
	)
	(segment
		(start 418.161978 -220.707966)
		(end 415.698432 -220.707966)
		(width 0.16002)
		(layer "In2.Cu")
		(net "M_I_CPU0_SA_DQS_DN<7>")
	)
	(segment
		(start 397.806926 -233.290364)
		(end 397.433292 -233.663998)
		(width 0.16002)
		(layer "In2.Cu")
		(net "M_I_CPU0_SA_DQS_DN<7>")
	)
	(segment
		(start 392.773408 -236.69371)
		(end 392.194288 -237.27283)
		(width 0.09525)
		(layer "In2.Cu")
		(net "M_I_CPU0_SA_DQS_DN<7>")
	)
	(segment
		(start 387.264656 -237.524036)
		(end 387.256274 -237.51921)
		(width 0.09525)
		(layer "In2.Cu")
		(net "M_I_CPU0_SA_DQS_DN<7>")
	)
	(segment
		(start 398.883124 -233.562398)
		(end 398.606264 -233.562398)
		(width 0.16002)
		(layer "In2.Cu")
		(net "M_I_CPU0_SA_DQS_DN<7>")
	)
	(segment
		(start 401.630388 -230.815134)
		(end 401.353528 -230.815134)
		(width 0.16002)
		(layer "In2.Cu")
		(net "M_I_CPU0_SA_DQS_DN<7>")
	)
	(segment
		(start 376.0343 -237.546388)
		(end 376.010932 -237.45952)
		(width 0.09525)
		(layer "In2.Cu")
		(net "M_I_CPU0_SA_DQS_DN<7>")
	)
	(segment
		(start 398.33423 -233.290364)
		(end 397.806926 -233.290364)
		(width 0.16002)
		(layer "In2.Cu")
		(net "M_I_CPU0_SA_DQS_DN<7>")
	)
	(segment
		(start 393.654788 -236.59211)
		(end 393.018518 -236.59211)
		(width 0.09525)
		(layer "In2.Cu")
		(net "M_I_CPU0_SA_DQS_DN<7>")
	)
	(segment
		(start 381.993394 -237.51921)
		(end 381.985012 -237.524036)
		(width 0.09525)
		(layer "In2.Cu")
		(net "M_I_CPU0_SA_DQS_DN<7>")
	)
	(segment
		(start 381.05334 -237.51921)
		(end 381.044958 -237.524036)
		(width 0.09525)
		(layer "In2.Cu")
		(net "M_I_CPU0_SA_DQS_DN<7>")
	)
	(segment
		(start 426.331888 -220.44279)
		(end 425.851828 -220.44279)
		(width 0.16002)
		(layer "In2.Cu")
		(net "M_I_CPU0_SA_DQS_DN<7>")
	)
	(segment
		(start 395.117066 -235.129832)
		(end 393.654788 -236.59211)
		(width 0.09525)
		(layer "In2.Cu")
		(net "M_I_CPU0_SA_DQS_DN<7>")
	)
	(segment
		(start 413.13354 -221.55785)
		(end 409.53944 -221.55785)
		(width 0.16002)
		(layer "In2.Cu")
		(net "M_I_CPU0_SA_DQS_DN<7>")
	)
	(segment
		(start 401.826222 -230.34244)
		(end 401.826222 -230.6193)
		(width 0.16002)
		(layer "In2.Cu")
		(net "M_I_CPU0_SA_DQS_DN<7>")
	)
	(segment
		(start 422.271698 -220.400626)
		(end 421.479218 -221.193106)
		(width 0.16002)
		(layer "In2.Cu")
		(net "M_I_CPU0_SA_DQS_DN<7>")
	)
	(segment
		(start 395.633702 -235.07065)
		(end 395.57452 -235.129832)
		(width 0.09525)
		(layer "In2.Cu")
		(net "M_I_CPU0_SA_DQS_DN<7>")
	)
	(segment
		(start 392.194288 -237.27283)
		(end 392.049508 -237.37951)
		(width 0.09525)
		(layer "In2.Cu")
		(net "M_I_CPU0_SA_DQS_DN<7>")
	)
	(segment
		(start 421.479218 -221.193106)
		(end 421.042338 -221.193106)
		(width 0.16002)
		(layer "In2.Cu")
		(net "M_I_CPU0_SA_DQS_DN<7>")
	)
	(segment
		(start 397.705326 -234.740196)
		(end 397.374872 -235.07065)
		(width 0.16002)
		(layer "In2.Cu")
		(net "M_I_CPU0_SA_DQS_DN<7>")
	)
	(segment
		(start 398.806924 -232.290366)
		(end 398.806924 -232.81767)
		(width 0.16002)
		(layer "In2.Cu")
		(net "M_I_CPU0_SA_DQS_DN<7>")
	)
	(segment
		(start 419.011862 -221.55785)
		(end 418.161978 -220.707966)
		(width 0.16002)
		(layer "In2.Cu")
		(net "M_I_CPU0_SA_DQS_DN<7>")
	)
	(segment
		(start 393.018518 -236.59211)
		(end 392.773408 -236.69371)
		(width 0.09525)
		(layer "In2.Cu")
		(net "M_I_CPU0_SA_DQS_DN<7>")
	)
	(segment
		(start 427.456092 -220.285056)
		(end 427.181518 -220.55963)
		(width 0.16002)
		(layer "In2.Cu")
		(net "M_I_CPU0_SA_DQS_DN<7>")
	)
	(segment
		(start 421.042338 -221.193106)
		(end 420.677594 -221.55785)
		(width 0.16002)
		(layer "In2.Cu")
		(net "M_I_CPU0_SA_DQS_DN<7>")
	)
	(segment
		(start 377.293378 -237.51921)
		(end 377.284996 -237.524036)
		(width 0.09525)
		(layer "In2.Cu")
		(net "M_I_CPU0_SA_DQS_DN<7>")
	)
	(segment
		(start 425.851828 -220.44279)
		(end 425.734988 -220.55963)
		(width 0.16002)
		(layer "In2.Cu")
		(net "M_I_CPU0_SA_DQS_DN<7>")
	)
	(segment
		(start 386.69341 -237.51921)
		(end 386.685028 -237.524036)
		(width 0.09525)
		(layer "In2.Cu")
		(net "M_I_CPU0_SA_DQS_DN<7>")
	)
	(segment
		(start 415.698432 -220.707966)
		(end 415.391092 -220.400626)
		(width 0.16002)
		(layer "In2.Cu")
		(net "M_I_CPU0_SA_DQS_DN<7>")
	)
	(segment
		(start 427.181518 -220.55963)
		(end 426.448728 -220.55963)
		(width 0.16002)
		(layer "In2.Cu")
		(net "M_I_CPU0_SA_DQS_DN<7>")
	)
	(segment
		(start 399.707862 -231.916732)
		(end 399.180558 -231.916732)
		(width 0.16002)
		(layer "In2.Cu")
		(net "M_I_CPU0_SA_DQS_DN<7>")
	)
	(segment
		(start 395.657324 -235.07065)
		(end 395.633702 -235.07065)
		(width 0.09525)
		(layer "In2.Cu")
		(net "M_I_CPU0_SA_DQS_DN<7>")
	)
	(segment
		(start 376.010932 -237.45952)
		(end 376.164856 -237.19409)
		(width 0.09525)
		(layer "In2.Cu")
		(net "M_I_CPU0_SA_DQS_DN<7>")
	)
	(segment
		(start 383.504694 -237.524036)
		(end 383.496312 -237.51921)
		(width 0.09525)
		(layer "In2.Cu")
		(net "M_I_CPU0_SA_DQS_DN<7>")
	)
	(arc
		(start 383.496312 -237.51921)
		(mid 383.21488 -237.443455)
		(end 382.933448 -237.51921)
		(width 0.09525)
		(layer "In2.Cu")
		(net "M_I_CPU0_SA_DQS_DN<7>")
	)
	(arc
		(start 387.256274 -237.51921)
		(mid 386.974842 -237.443455)
		(end 386.69341 -237.51921)
		(width 0.09525)
		(layer "In2.Cu")
		(net "M_I_CPU0_SA_DQS_DN<7>")
	)
	(arc
		(start 386.31622 -237.51921)
		(mid 386.034788 -237.443455)
		(end 385.753356 -237.51921)
		(width 0.09525)
		(layer "In2.Cu")
		(net "M_I_CPU0_SA_DQS_DN<7>")
	)
	(arc
		(start 381.616204 -237.51921)
		(mid 381.334772 -237.443455)
		(end 381.05334 -237.51921)
		(width 0.09525)
		(layer "In2.Cu")
		(net "M_I_CPU0_SA_DQS_DN<7>")
	)
	(arc
		(start 383.873502 -237.51921)
		(mid 383.689727 -237.569982)
		(end 383.504694 -237.524036)
		(width 0.09525)
		(layer "In2.Cu")
		(net "M_I_CPU0_SA_DQS_DN<7>")
	)
	(arc
		(start 391.393426 -237.51921)
		(mid 391.209651 -237.569982)
		(end 391.024618 -237.524036)
		(width 0.09525)
		(layer "In2.Cu")
		(net "M_I_CPU0_SA_DQS_DN<7>")
	)
	(arc
		(start 385.744974 -237.524036)
		(mid 385.559942 -237.56995)
		(end 385.376166 -237.51921)
		(width 0.09525)
		(layer "In2.Cu")
		(net "M_I_CPU0_SA_DQS_DN<7>")
	)
	(arc
		(start 378.233432 -237.51921)
		(mid 378.049657 -237.569982)
		(end 377.864624 -237.524036)
		(width 0.09525)
		(layer "In2.Cu")
		(net "M_I_CPU0_SA_DQS_DN<7>")
	)
	(arc
		(start 377.856242 -237.51921)
		(mid 377.57481 -237.443455)
		(end 377.293378 -237.51921)
		(width 0.09525)
		(layer "In2.Cu")
		(net "M_I_CPU0_SA_DQS_DN<7>")
	)
	(arc
		(start 386.685028 -237.524036)
		(mid 386.499996 -237.56995)
		(end 386.31622 -237.51921)
		(width 0.09525)
		(layer "In2.Cu")
		(net "M_I_CPU0_SA_DQS_DN<7>")
	)
	(arc
		(start 377.284996 -237.524036)
		(mid 377.099964 -237.56995)
		(end 376.916188 -237.51921)
		(width 0.09525)
		(layer "In2.Cu")
		(net "M_I_CPU0_SA_DQS_DN<7>")
	)
	(arc
		(start 388.196328 -237.51921)
		(mid 387.914896 -237.443455)
		(end 387.633464 -237.51921)
		(width 0.09525)
		(layer "In2.Cu")
		(net "M_I_CPU0_SA_DQS_DN<7>")
	)
	(arc
		(start 379.73635 -237.51921)
		(mid 379.454918 -237.443455)
		(end 379.173486 -237.51921)
		(width 0.09525)
		(layer "In2.Cu")
		(net "M_I_CPU0_SA_DQS_DN<7>")
	)
	(arc
		(start 378.796296 -237.51921)
		(mid 378.514864 -237.443455)
		(end 378.233432 -237.51921)
		(width 0.09525)
		(layer "In2.Cu")
		(net "M_I_CPU0_SA_DQS_DN<7>")
	)
	(arc
		(start 390.44499 -237.524036)
		(mid 390.259958 -237.56995)
		(end 390.076182 -237.51921)
		(width 0.09525)
		(layer "In2.Cu")
		(net "M_I_CPU0_SA_DQS_DN<7>")
	)
	(arc
		(start 387.633464 -237.51921)
		(mid 387.449689 -237.569982)
		(end 387.264656 -237.524036)
		(width 0.09525)
		(layer "In2.Cu")
		(net "M_I_CPU0_SA_DQS_DN<7>")
	)
	(arc
		(start 376.344942 -237.524036)
		(mid 376.192047 -237.568864)
		(end 376.0343 -237.546388)
		(width 0.09525)
		(layer "In2.Cu")
		(net "M_I_CPU0_SA_DQS_DN<7>")
	)
	(arc
		(start 380.67615 -237.51921)
		(mid 380.394718 -237.443455)
		(end 380.113286 -237.51921)
		(width 0.09525)
		(layer "In2.Cu")
		(net "M_I_CPU0_SA_DQS_DN<7>")
	)
	(arc
		(start 391.016236 -237.51921)
		(mid 390.734804 -237.443455)
		(end 390.453372 -237.51921)
		(width 0.09525)
		(layer "In2.Cu")
		(net "M_I_CPU0_SA_DQS_DN<7>")
	)
	(arc
		(start 382.556258 -237.51921)
		(mid 382.274826 -237.443455)
		(end 381.993394 -237.51921)
		(width 0.09525)
		(layer "In2.Cu")
		(net "M_I_CPU0_SA_DQS_DN<7>")
	)
	(arc
		(start 392.049508 -237.37951)
		(mid 391.957088 -237.427082)
		(end 391.854436 -237.443518)
		(width 0.09525)
		(layer "In2.Cu")
		(net "M_I_CPU0_SA_DQS_DN<7>")
	)
	(arc
		(start 381.044958 -237.524036)
		(mid 380.859926 -237.56995)
		(end 380.67615 -237.51921)
		(width 0.09525)
		(layer "In2.Cu")
		(net "M_I_CPU0_SA_DQS_DN<7>")
	)
	(arc
		(start 381.985012 -237.524036)
		(mid 381.79998 -237.56995)
		(end 381.616204 -237.51921)
		(width 0.09525)
		(layer "In2.Cu")
		(net "M_I_CPU0_SA_DQS_DN<7>")
	)
	(arc
		(start 380.113286 -237.51921)
		(mid 379.924818 -237.569887)
		(end 379.73635 -237.51921)
		(width 0.09525)
		(layer "In2.Cu")
		(net "M_I_CPU0_SA_DQS_DN<7>")
	)
	(arc
		(start 379.173486 -237.51921)
		(mid 378.989711 -237.569982)
		(end 378.804678 -237.524036)
		(width 0.09525)
		(layer "In2.Cu")
		(net "M_I_CPU0_SA_DQS_DN<7>")
	)
	(arc
		(start 391.674858 -237.443518)
		(mid 391.52915 -237.462786)
		(end 391.393426 -237.51921)
		(width 0.09525)
		(layer "In2.Cu")
		(net "M_I_CPU0_SA_DQS_DN<7>")
	)
	(arc
		(start 389.513318 -237.51921)
		(mid 389.32485 -237.569887)
		(end 389.136382 -237.51921)
		(width 0.09525)
		(layer "In2.Cu")
		(net "M_I_CPU0_SA_DQS_DN<7>")
	)
	(arc
		(start 382.933448 -237.51921)
		(mid 382.749673 -237.569982)
		(end 382.56464 -237.524036)
		(width 0.09525)
		(layer "In2.Cu")
		(net "M_I_CPU0_SA_DQS_DN<7>")
	)
	(arc
		(start 388.573518 -237.51921)
		(mid 388.389743 -237.569982)
		(end 388.20471 -237.524036)
		(width 0.09525)
		(layer "In2.Cu")
		(net "M_I_CPU0_SA_DQS_DN<7>")
	)
	(arc
		(start 385.376166 -237.51921)
		(mid 385.094734 -237.443455)
		(end 384.813302 -237.51921)
		(width 0.09525)
		(layer "In2.Cu")
		(net "M_I_CPU0_SA_DQS_DN<7>")
	)
	(arc
		(start 384.436366 -237.51921)
		(mid 384.154934 -237.443455)
		(end 383.873502 -237.51921)
		(width 0.09525)
		(layer "In2.Cu")
		(net "M_I_CPU0_SA_DQS_DN<7>")
	)
	(arc
		(start 384.813302 -237.51921)
		(mid 384.624834 -237.569887)
		(end 384.436366 -237.51921)
		(width 0.09525)
		(layer "In2.Cu")
		(net "M_I_CPU0_SA_DQS_DN<7>")
	)
	(arc
		(start 390.076182 -237.51921)
		(mid 389.79475 -237.443455)
		(end 389.513318 -237.51921)
		(width 0.09525)
		(layer "In2.Cu")
		(net "M_I_CPU0_SA_DQS_DN<7>")
	)
	(arc
		(start 376.916188 -237.51921)
		(mid 376.634756 -237.443455)
		(end 376.353324 -237.51921)
		(width 0.09525)
		(layer "In2.Cu")
		(net "M_I_CPU0_SA_DQS_DN<7>")
	)
	(arc
		(start 389.136382 -237.51921)
		(mid 388.85495 -237.443455)
		(end 388.573518 -237.51921)
		(width 0.09525)
		(layer "In2.Cu")
		(net "M_I_CPU0_SA_DQS_DN<7>")
	)
	(segment
		(start 375.698004 -232.599992)
		(end 376.164856 -232.334054)
		(width 0.12954)
		(layer "F.Cu")
		(net "M_I_CPU0_SA_DQS_DN<6>")
	)
	(segment
		(start 394.369798 -227.593652)
		(end 396.104618 -225.858832)
		(width 0.16002)
		(layer "In2.Cu")
		(net "M_I_CPU0_SA_DQS_DN<6>")
	)
	(segment
		(start 414.727644 -211.050632)
		(end 415.391092 -211.050632)
		(width 0.16002)
		(layer "In2.Cu")
		(net "M_I_CPU0_SA_DQS_DN<6>")
	)
	(segment
		(start 413.13354 -212.207856)
		(end 413.498284 -211.843112)
		(width 0.16002)
		(layer "In2.Cu")
		(net "M_I_CPU0_SA_DQS_DN<6>")
	)
	(segment
		(start 425.214034 -211.209636)
		(end 427.181518 -211.209636)
		(width 0.16002)
		(layer "In2.Cu")
		(net "M_I_CPU0_SA_DQS_DN<6>")
	)
	(segment
		(start 407.594816 -213.703662)
		(end 407.594816 -213.426802)
		(width 0.16002)
		(layer "In2.Cu")
		(net "M_I_CPU0_SA_DQS_DN<6>")
	)
	(segment
		(start 396.104618 -225.19386)
		(end 404.847552 -216.450926)
		(width 0.16002)
		(layer "In2.Cu")
		(net "M_I_CPU0_SA_DQS_DN<6>")
	)
	(segment
		(start 415.698432 -211.357972)
		(end 418.161978 -211.357972)
		(width 0.16002)
		(layer "In2.Cu")
		(net "M_I_CPU0_SA_DQS_DN<6>")
	)
	(segment
		(start 422.935146 -211.050632)
		(end 423.242486 -211.357972)
		(width 0.16002)
		(layer "In2.Cu")
		(net "M_I_CPU0_SA_DQS_DN<6>")
	)
	(segment
		(start 396.104618 -225.858832)
		(end 396.104618 -225.19386)
		(width 0.16002)
		(layer "In2.Cu")
		(net "M_I_CPU0_SA_DQS_DN<6>")
	)
	(segment
		(start 392.33348 -231.039416)
		(end 392.364976 -231.021128)
		(width 0.09525)
		(layer "In2.Cu")
		(net "M_I_CPU0_SA_DQS_DN<6>")
	)
	(segment
		(start 406.221184 -214.800434)
		(end 405.877522 -214.456772)
		(width 0.16002)
		(layer "In2.Cu")
		(net "M_I_CPU0_SA_DQS_DN<6>")
	)
	(segment
		(start 423.242486 -211.357972)
		(end 425.065698 -211.357972)
		(width 0.16002)
		(layer "In2.Cu")
		(net "M_I_CPU0_SA_DQS_DN<6>")
	)
	(segment
		(start 408.495754 -212.525864)
		(end 408.772614 -212.525864)
		(width 0.16002)
		(layer "In2.Cu")
		(net "M_I_CPU0_SA_DQS_DN<6>")
	)
	(segment
		(start 413.935164 -211.843112)
		(end 414.727644 -211.050632)
		(width 0.16002)
		(layer "In2.Cu")
		(net "M_I_CPU0_SA_DQS_DN<6>")
	)
	(segment
		(start 421.042338 -211.843112)
		(end 421.479218 -211.843112)
		(width 0.16002)
		(layer "In2.Cu")
		(net "M_I_CPU0_SA_DQS_DN<6>")
	)
	(segment
		(start 404.877524 -214.929466)
		(end 405.404828 -214.929466)
		(width 0.16002)
		(layer "In2.Cu")
		(net "M_I_CPU0_SA_DQS_DN<6>")
	)
	(segment
		(start 422.271698 -211.050632)
		(end 422.935146 -211.050632)
		(width 0.16002)
		(layer "In2.Cu")
		(net "M_I_CPU0_SA_DQS_DN<6>")
	)
	(segment
		(start 421.479218 -211.843112)
		(end 422.271698 -211.050632)
		(width 0.16002)
		(layer "In2.Cu")
		(net "M_I_CPU0_SA_DQS_DN<6>")
	)
	(segment
		(start 378.796296 -232.659174)
		(end 378.804678 -232.664)
		(width 0.09525)
		(layer "In2.Cu")
		(net "M_I_CPU0_SA_DQS_DN<6>")
	)
	(segment
		(start 393.927838 -228.020372)
		(end 394.205968 -227.742242)
		(width 0.09525)
		(layer "In2.Cu")
		(net "M_I_CPU0_SA_DQS_DN<6>")
	)
	(segment
		(start 385.744974 -232.664)
		(end 385.753356 -232.659174)
		(width 0.09525)
		(layer "In2.Cu")
		(net "M_I_CPU0_SA_DQS_DN<6>")
	)
	(segment
		(start 406.77846 -213.555834)
		(end 407.122122 -213.899496)
		(width 0.16002)
		(layer "In2.Cu")
		(net "M_I_CPU0_SA_DQS_DN<6>")
	)
	(segment
		(start 391.393426 -232.659174)
		(end 391.424922 -232.640886)
		(width 0.09525)
		(layer "In2.Cu")
		(net "M_I_CPU0_SA_DQS_DN<6>")
	)
	(segment
		(start 408.152092 -212.182202)
		(end 408.495754 -212.525864)
		(width 0.16002)
		(layer "In2.Cu")
		(net "M_I_CPU0_SA_DQS_DN<6>")
	)
	(segment
		(start 394.305028 -227.742242)
		(end 394.353034 -227.694236)
		(width 0.09525)
		(layer "In2.Cu")
		(net "M_I_CPU0_SA_DQS_DN<6>")
	)
	(segment
		(start 406.221184 -215.077294)
		(end 406.221184 -214.800434)
		(width 0.16002)
		(layer "In2.Cu")
		(net "M_I_CPU0_SA_DQS_DN<6>")
	)
	(segment
		(start 391.016236 -232.659174)
		(end 391.024618 -232.664)
		(width 0.09525)
		(layer "In2.Cu")
		(net "M_I_CPU0_SA_DQS_DN<6>")
	)
	(segment
		(start 392.293094 -231.063038)
		(end 392.33348 -231.039416)
		(width 0.09525)
		(layer "In2.Cu")
		(net "M_I_CPU0_SA_DQS_DN<6>")
	)
	(segment
		(start 393.705334 -228.631496)
		(end 393.72413 -228.620574)
		(width 0.09525)
		(layer "In2.Cu")
		(net "M_I_CPU0_SA_DQS_DN<6>")
	)
	(segment
		(start 407.251154 -213.08314)
		(end 407.251154 -212.555836)
		(width 0.16002)
		(layer "In2.Cu")
		(net "M_I_CPU0_SA_DQS_DN<6>")
	)
	(segment
		(start 390.44499 -232.664)
		(end 390.453372 -232.659174)
		(width 0.09525)
		(layer "In2.Cu")
		(net "M_I_CPU0_SA_DQS_DN<6>")
	)
	(segment
		(start 406.02535 -215.273128)
		(end 406.221184 -215.077294)
		(width 0.16002)
		(layer "In2.Cu")
		(net "M_I_CPU0_SA_DQS_DN<6>")
	)
	(segment
		(start 405.404828 -214.929466)
		(end 405.74849 -215.273128)
		(width 0.16002)
		(layer "In2.Cu")
		(net "M_I_CPU0_SA_DQS_DN<6>")
	)
	(segment
		(start 409.090622 -212.207856)
		(end 413.13354 -212.207856)
		(width 0.16002)
		(layer "In2.Cu")
		(net "M_I_CPU0_SA_DQS_DN<6>")
	)
	(segment
		(start 420.677594 -212.207856)
		(end 421.042338 -211.843112)
		(width 0.16002)
		(layer "In2.Cu")
		(net "M_I_CPU0_SA_DQS_DN<6>")
	)
	(segment
		(start 407.594816 -213.426802)
		(end 407.251154 -213.08314)
		(width 0.16002)
		(layer "In2.Cu")
		(net "M_I_CPU0_SA_DQS_DN<6>")
	)
	(segment
		(start 393.233148 -229.443026)
		(end 393.273534 -229.419404)
		(width 0.09525)
		(layer "In2.Cu")
		(net "M_I_CPU0_SA_DQS_DN<6>")
	)
	(segment
		(start 394.353034 -227.694236)
		(end 394.353034 -227.610416)
		(width 0.09525)
		(layer "In2.Cu")
		(net "M_I_CPU0_SA_DQS_DN<6>")
	)
	(segment
		(start 394.205968 -227.742242)
		(end 394.305028 -227.742242)
		(width 0.09525)
		(layer "In2.Cu")
		(net "M_I_CPU0_SA_DQS_DN<6>")
	)
	(segment
		(start 393.72413 -228.620574)
		(end 393.927838 -228.416866)
		(width 0.09525)
		(layer "In2.Cu")
		(net "M_I_CPU0_SA_DQS_DN<6>")
	)
	(segment
		(start 393.927838 -228.416866)
		(end 393.927838 -228.020372)
		(width 0.09525)
		(layer "In2.Cu")
		(net "M_I_CPU0_SA_DQS_DN<6>")
	)
	(segment
		(start 407.251154 -212.555836)
		(end 407.624788 -212.182202)
		(width 0.16002)
		(layer "In2.Cu")
		(net "M_I_CPU0_SA_DQS_DN<6>")
	)
	(segment
		(start 377.856242 -232.659174)
		(end 377.864624 -232.664)
		(width 0.09525)
		(layer "In2.Cu")
		(net "M_I_CPU0_SA_DQS_DN<6>")
	)
	(segment
		(start 383.496312 -232.659174)
		(end 383.504694 -232.664)
		(width 0.09525)
		(layer "In2.Cu")
		(net "M_I_CPU0_SA_DQS_DN<6>")
	)
	(segment
		(start 406.251156 -213.555834)
		(end 406.77846 -213.555834)
		(width 0.16002)
		(layer "In2.Cu")
		(net "M_I_CPU0_SA_DQS_DN<6>")
	)
	(segment
		(start 405.877522 -213.929468)
		(end 406.251156 -213.555834)
		(width 0.16002)
		(layer "In2.Cu")
		(net "M_I_CPU0_SA_DQS_DN<6>")
	)
	(segment
		(start 415.391092 -211.050632)
		(end 415.698432 -211.357972)
		(width 0.16002)
		(layer "In2.Cu")
		(net "M_I_CPU0_SA_DQS_DN<6>")
	)
	(segment
		(start 391.863326 -231.849168)
		(end 391.895838 -231.830372)
		(width 0.09525)
		(layer "In2.Cu")
		(net "M_I_CPU0_SA_DQS_DN<6>")
	)
	(segment
		(start 391.825226 -231.871266)
		(end 391.863326 -231.849168)
		(width 0.09525)
		(layer "In2.Cu")
		(net "M_I_CPU0_SA_DQS_DN<6>")
	)
	(segment
		(start 425.065698 -211.357972)
		(end 425.214034 -211.209636)
		(width 0.16002)
		(layer "In2.Cu")
		(net "M_I_CPU0_SA_DQS_DN<6>")
	)
	(segment
		(start 408.772614 -212.525864)
		(end 409.090622 -212.207856)
		(width 0.16002)
		(layer "In2.Cu")
		(net "M_I_CPU0_SA_DQS_DN<6>")
	)
	(segment
		(start 377.284996 -232.664)
		(end 377.293378 -232.659174)
		(width 0.09525)
		(layer "In2.Cu")
		(net "M_I_CPU0_SA_DQS_DN<6>")
	)
	(segment
		(start 404.50389 -215.3031)
		(end 404.877524 -214.929466)
		(width 0.16002)
		(layer "In2.Cu")
		(net "M_I_CPU0_SA_DQS_DN<6>")
	)
	(segment
		(start 394.353034 -227.610416)
		(end 394.369798 -227.593652)
		(width 0.09525)
		(layer "In2.Cu")
		(net "M_I_CPU0_SA_DQS_DN<6>")
	)
	(segment
		(start 413.498284 -211.843112)
		(end 413.935164 -211.843112)
		(width 0.16002)
		(layer "In2.Cu")
		(net "M_I_CPU0_SA_DQS_DN<6>")
	)
	(segment
		(start 404.847552 -216.450926)
		(end 404.847552 -216.174066)
		(width 0.16002)
		(layer "In2.Cu")
		(net "M_I_CPU0_SA_DQS_DN<6>")
	)
	(segment
		(start 407.398982 -213.899496)
		(end 407.594816 -213.703662)
		(width 0.16002)
		(layer "In2.Cu")
		(net "M_I_CPU0_SA_DQS_DN<6>")
	)
	(segment
		(start 381.044958 -232.664)
		(end 381.05334 -232.659174)
		(width 0.09525)
		(layer "In2.Cu")
		(net "M_I_CPU0_SA_DQS_DN<6>")
	)
	(segment
		(start 387.256274 -232.659174)
		(end 387.264656 -232.664)
		(width 0.09525)
		(layer "In2.Cu")
		(net "M_I_CPU0_SA_DQS_DN<6>")
	)
	(segment
		(start 393.273534 -229.419404)
		(end 393.30503 -229.401116)
		(width 0.09525)
		(layer "In2.Cu")
		(net "M_I_CPU0_SA_DQS_DN<6>")
	)
	(segment
		(start 376.010932 -232.599484)
		(end 376.0343 -232.686352)
		(width 0.09525)
		(layer "In2.Cu")
		(net "M_I_CPU0_SA_DQS_DN<6>")
	)
	(segment
		(start 405.877522 -214.456772)
		(end 405.877522 -213.929468)
		(width 0.16002)
		(layer "In2.Cu")
		(net "M_I_CPU0_SA_DQS_DN<6>")
	)
	(segment
		(start 388.196328 -232.659174)
		(end 388.20471 -232.664)
		(width 0.09525)
		(layer "In2.Cu")
		(net "M_I_CPU0_SA_DQS_DN<6>")
	)
	(segment
		(start 381.985012 -232.664)
		(end 381.993394 -232.659174)
		(width 0.09525)
		(layer "In2.Cu")
		(net "M_I_CPU0_SA_DQS_DN<6>")
	)
	(segment
		(start 405.74849 -215.273128)
		(end 406.02535 -215.273128)
		(width 0.16002)
		(layer "In2.Cu")
		(net "M_I_CPU0_SA_DQS_DN<6>")
	)
	(segment
		(start 419.011862 -212.207856)
		(end 420.677594 -212.207856)
		(width 0.16002)
		(layer "In2.Cu")
		(net "M_I_CPU0_SA_DQS_DN<6>")
	)
	(segment
		(start 407.122122 -213.899496)
		(end 407.398982 -213.899496)
		(width 0.16002)
		(layer "In2.Cu")
		(net "M_I_CPU0_SA_DQS_DN<6>")
	)
	(segment
		(start 407.624788 -212.182202)
		(end 408.152092 -212.182202)
		(width 0.16002)
		(layer "In2.Cu")
		(net "M_I_CPU0_SA_DQS_DN<6>")
	)
	(segment
		(start 404.847552 -216.174066)
		(end 404.50389 -215.830404)
		(width 0.16002)
		(layer "In2.Cu")
		(net "M_I_CPU0_SA_DQS_DN<6>")
	)
	(segment
		(start 386.685028 -232.664)
		(end 386.69341 -232.659174)
		(width 0.09525)
		(layer "In2.Cu")
		(net "M_I_CPU0_SA_DQS_DN<6>")
	)
	(segment
		(start 376.344942 -232.664)
		(end 376.353324 -232.659174)
		(width 0.09525)
		(layer "In2.Cu")
		(net "M_I_CPU0_SA_DQS_DN<6>")
	)
	(segment
		(start 392.76782 -230.24973)
		(end 392.80338 -230.229156)
		(width 0.09525)
		(layer "In2.Cu")
		(net "M_I_CPU0_SA_DQS_DN<6>")
	)
	(segment
		(start 382.556258 -232.659174)
		(end 382.56464 -232.664)
		(width 0.09525)
		(layer "In2.Cu")
		(net "M_I_CPU0_SA_DQS_DN<6>")
	)
	(segment
		(start 404.50389 -215.830404)
		(end 404.50389 -215.3031)
		(width 0.16002)
		(layer "In2.Cu")
		(net "M_I_CPU0_SA_DQS_DN<6>")
	)
	(segment
		(start 427.181518 -211.209636)
		(end 427.456092 -210.935062)
		(width 0.16002)
		(layer "In2.Cu")
		(net "M_I_CPU0_SA_DQS_DN<6>")
	)
	(segment
		(start 376.164856 -232.334054)
		(end 376.010932 -232.599484)
		(width 0.09525)
		(layer "In2.Cu")
		(net "M_I_CPU0_SA_DQS_DN<6>")
	)
	(segment
		(start 392.80338 -230.229156)
		(end 392.835892 -230.21036)
		(width 0.09525)
		(layer "In2.Cu")
		(net "M_I_CPU0_SA_DQS_DN<6>")
	)
	(segment
		(start 418.161978 -211.357972)
		(end 419.011862 -212.207856)
		(width 0.16002)
		(layer "In2.Cu")
		(net "M_I_CPU0_SA_DQS_DN<6>")
	)
	(arc
		(start 389.513318 -232.659174)
		(mid 389.79475 -232.583419)
		(end 390.076182 -232.659174)
		(width 0.09525)
		(layer "In2.Cu")
		(net "M_I_CPU0_SA_DQS_DN<6>")
	)
	(arc
		(start 377.293378 -232.659174)
		(mid 377.57481 -232.583419)
		(end 377.856242 -232.659174)
		(width 0.09525)
		(layer "In2.Cu")
		(net "M_I_CPU0_SA_DQS_DN<6>")
	)
	(arc
		(start 387.633464 -232.659174)
		(mid 387.914896 -232.583419)
		(end 388.196328 -232.659174)
		(width 0.09525)
		(layer "In2.Cu")
		(net "M_I_CPU0_SA_DQS_DN<6>")
	)
	(arc
		(start 391.424922 -232.640886)
		(mid 391.54072 -232.506492)
		(end 391.582402 -232.334054)
		(width 0.09525)
		(layer "In2.Cu")
		(net "M_I_CPU0_SA_DQS_DN<6>")
	)
	(arc
		(start 392.522456 -230.714296)
		(mid 392.587575 -230.451618)
		(end 392.76782 -230.24973)
		(width 0.09525)
		(layer "In2.Cu")
		(net "M_I_CPU0_SA_DQS_DN<6>")
	)
	(arc
		(start 385.753356 -232.659174)
		(mid 386.034788 -232.583419)
		(end 386.31622 -232.659174)
		(width 0.09525)
		(layer "In2.Cu")
		(net "M_I_CPU0_SA_DQS_DN<6>")
	)
	(arc
		(start 386.69341 -232.659174)
		(mid 386.974842 -232.583419)
		(end 387.256274 -232.659174)
		(width 0.09525)
		(layer "In2.Cu")
		(net "M_I_CPU0_SA_DQS_DN<6>")
	)
	(arc
		(start 376.0343 -232.686352)
		(mid 376.19205 -232.708871)
		(end 376.344942 -232.664)
		(width 0.09525)
		(layer "In2.Cu")
		(net "M_I_CPU0_SA_DQS_DN<6>")
	)
	(arc
		(start 393.46251 -229.094284)
		(mid 393.526907 -228.832978)
		(end 393.705334 -228.631496)
		(width 0.09525)
		(layer "In2.Cu")
		(net "M_I_CPU0_SA_DQS_DN<6>")
	)
	(arc
		(start 384.436366 -232.659174)
		(mid 384.624834 -232.709851)
		(end 384.813302 -232.659174)
		(width 0.09525)
		(layer "In2.Cu")
		(net "M_I_CPU0_SA_DQS_DN<6>")
	)
	(arc
		(start 392.364976 -231.021128)
		(mid 392.480774 -230.886734)
		(end 392.522456 -230.714296)
		(width 0.09525)
		(layer "In2.Cu")
		(net "M_I_CPU0_SA_DQS_DN<6>")
	)
	(arc
		(start 378.233432 -232.659174)
		(mid 378.514864 -232.583419)
		(end 378.796296 -232.659174)
		(width 0.09525)
		(layer "In2.Cu")
		(net "M_I_CPU0_SA_DQS_DN<6>")
	)
	(arc
		(start 381.05334 -232.659174)
		(mid 381.334772 -232.583419)
		(end 381.616204 -232.659174)
		(width 0.09525)
		(layer "In2.Cu")
		(net "M_I_CPU0_SA_DQS_DN<6>")
	)
	(arc
		(start 389.136382 -232.659174)
		(mid 389.32485 -232.709851)
		(end 389.513318 -232.659174)
		(width 0.09525)
		(layer "In2.Cu")
		(net "M_I_CPU0_SA_DQS_DN<6>")
	)
	(arc
		(start 381.616204 -232.659174)
		(mid 381.799979 -232.709946)
		(end 381.985012 -232.664)
		(width 0.09525)
		(layer "In2.Cu")
		(net "M_I_CPU0_SA_DQS_DN<6>")
	)
	(arc
		(start 383.873502 -232.659174)
		(mid 384.154934 -232.583419)
		(end 384.436366 -232.659174)
		(width 0.09525)
		(layer "In2.Cu")
		(net "M_I_CPU0_SA_DQS_DN<6>")
	)
	(arc
		(start 382.933448 -232.659174)
		(mid 383.21488 -232.583419)
		(end 383.496312 -232.659174)
		(width 0.09525)
		(layer "In2.Cu")
		(net "M_I_CPU0_SA_DQS_DN<6>")
	)
	(arc
		(start 390.076182 -232.659174)
		(mid 390.259957 -232.709946)
		(end 390.44499 -232.664)
		(width 0.09525)
		(layer "In2.Cu")
		(net "M_I_CPU0_SA_DQS_DN<6>")
	)
	(arc
		(start 387.264656 -232.664)
		(mid 387.449688 -232.709914)
		(end 387.633464 -232.659174)
		(width 0.09525)
		(layer "In2.Cu")
		(net "M_I_CPU0_SA_DQS_DN<6>")
	)
	(arc
		(start 388.20471 -232.664)
		(mid 388.389742 -232.709914)
		(end 388.573518 -232.659174)
		(width 0.09525)
		(layer "In2.Cu")
		(net "M_I_CPU0_SA_DQS_DN<6>")
	)
	(arc
		(start 380.67615 -232.659174)
		(mid 380.859925 -232.709946)
		(end 381.044958 -232.664)
		(width 0.09525)
		(layer "In2.Cu")
		(net "M_I_CPU0_SA_DQS_DN<6>")
	)
	(arc
		(start 392.99261 -229.904036)
		(mid 393.056356 -229.644036)
		(end 393.233148 -229.443026)
		(width 0.09525)
		(layer "In2.Cu")
		(net "M_I_CPU0_SA_DQS_DN<6>")
	)
	(arc
		(start 380.113286 -232.659174)
		(mid 380.394718 -232.583419)
		(end 380.67615 -232.659174)
		(width 0.09525)
		(layer "In2.Cu")
		(net "M_I_CPU0_SA_DQS_DN<6>")
	)
	(arc
		(start 383.504694 -232.664)
		(mid 383.689726 -232.709914)
		(end 383.873502 -232.659174)
		(width 0.09525)
		(layer "In2.Cu")
		(net "M_I_CPU0_SA_DQS_DN<6>")
	)
	(arc
		(start 384.813302 -232.659174)
		(mid 385.094734 -232.583419)
		(end 385.376166 -232.659174)
		(width 0.09525)
		(layer "In2.Cu")
		(net "M_I_CPU0_SA_DQS_DN<6>")
	)
	(arc
		(start 379.173486 -232.659174)
		(mid 379.454918 -232.583419)
		(end 379.73635 -232.659174)
		(width 0.09525)
		(layer "In2.Cu")
		(net "M_I_CPU0_SA_DQS_DN<6>")
	)
	(arc
		(start 385.376166 -232.659174)
		(mid 385.559941 -232.709946)
		(end 385.744974 -232.664)
		(width 0.09525)
		(layer "In2.Cu")
		(net "M_I_CPU0_SA_DQS_DN<6>")
	)
	(arc
		(start 391.582402 -232.334054)
		(mid 391.646799 -232.072748)
		(end 391.825226 -231.871266)
		(width 0.09525)
		(layer "In2.Cu")
		(net "M_I_CPU0_SA_DQS_DN<6>")
	)
	(arc
		(start 378.804678 -232.664)
		(mid 378.98971 -232.709914)
		(end 379.173486 -232.659174)
		(width 0.09525)
		(layer "In2.Cu")
		(net "M_I_CPU0_SA_DQS_DN<6>")
	)
	(arc
		(start 386.31622 -232.659174)
		(mid 386.499995 -232.709946)
		(end 386.685028 -232.664)
		(width 0.09525)
		(layer "In2.Cu")
		(net "M_I_CPU0_SA_DQS_DN<6>")
	)
	(arc
		(start 388.573518 -232.659174)
		(mid 388.85495 -232.583419)
		(end 389.136382 -232.659174)
		(width 0.09525)
		(layer "In2.Cu")
		(net "M_I_CPU0_SA_DQS_DN<6>")
	)
	(arc
		(start 382.56464 -232.664)
		(mid 382.749672 -232.709914)
		(end 382.933448 -232.659174)
		(width 0.09525)
		(layer "In2.Cu")
		(net "M_I_CPU0_SA_DQS_DN<6>")
	)
	(arc
		(start 393.30503 -229.401116)
		(mid 393.420828 -229.266722)
		(end 393.46251 -229.094284)
		(width 0.09525)
		(layer "In2.Cu")
		(net "M_I_CPU0_SA_DQS_DN<6>")
	)
	(arc
		(start 391.024618 -232.664)
		(mid 391.20965 -232.709914)
		(end 391.393426 -232.659174)
		(width 0.09525)
		(layer "In2.Cu")
		(net "M_I_CPU0_SA_DQS_DN<6>")
	)
	(arc
		(start 391.895838 -231.830372)
		(mid 392.011112 -231.696094)
		(end 392.052556 -231.524048)
		(width 0.09525)
		(layer "In2.Cu")
		(net "M_I_CPU0_SA_DQS_DN<6>")
	)
	(arc
		(start 376.353324 -232.659174)
		(mid 376.634756 -232.583419)
		(end 376.916188 -232.659174)
		(width 0.09525)
		(layer "In2.Cu")
		(net "M_I_CPU0_SA_DQS_DN<6>")
	)
	(arc
		(start 392.052556 -231.524048)
		(mid 392.116302 -231.264048)
		(end 392.293094 -231.063038)
		(width 0.09525)
		(layer "In2.Cu")
		(net "M_I_CPU0_SA_DQS_DN<6>")
	)
	(arc
		(start 381.993394 -232.659174)
		(mid 382.274826 -232.583419)
		(end 382.556258 -232.659174)
		(width 0.09525)
		(layer "In2.Cu")
		(net "M_I_CPU0_SA_DQS_DN<6>")
	)
	(arc
		(start 376.916188 -232.659174)
		(mid 377.099963 -232.709946)
		(end 377.284996 -232.664)
		(width 0.09525)
		(layer "In2.Cu")
		(net "M_I_CPU0_SA_DQS_DN<6>")
	)
	(arc
		(start 390.453372 -232.659174)
		(mid 390.734804 -232.583419)
		(end 391.016236 -232.659174)
		(width 0.09525)
		(layer "In2.Cu")
		(net "M_I_CPU0_SA_DQS_DN<6>")
	)
	(arc
		(start 377.864624 -232.664)
		(mid 378.049656 -232.709914)
		(end 378.233432 -232.659174)
		(width 0.09525)
		(layer "In2.Cu")
		(net "M_I_CPU0_SA_DQS_DN<6>")
	)
	(arc
		(start 392.835892 -230.21036)
		(mid 392.951166 -230.076082)
		(end 392.99261 -229.904036)
		(width 0.09525)
		(layer "In2.Cu")
		(net "M_I_CPU0_SA_DQS_DN<6>")
	)
	(arc
		(start 379.73635 -232.659174)
		(mid 379.924818 -232.709851)
		(end 380.113286 -232.659174)
		(width 0.09525)
		(layer "In2.Cu")
		(net "M_I_CPU0_SA_DQS_DN<6>")
	)
	(segment
		(start 375.698004 -227.74021)
		(end 376.164856 -227.474272)
		(width 0.12954)
		(layer "F.Cu")
		(net "M_I_CPU0_SA_DQS_DN<5>")
	)
	(segment
		(start 399.209768 -211.43087)
		(end 399.210022 -211.957666)
		(width 0.16002)
		(layer "In2.Cu")
		(net "M_I_CPU0_SA_DQS_DN<5>")
	)
	(segment
		(start 386.69341 -227.799392)
		(end 386.685028 -227.804218)
		(width 0.09525)
		(layer "In2.Cu")
		(net "M_I_CPU0_SA_DQS_DN<5>")
	)
	(segment
		(start 401.484592 -209.683096)
		(end 400.957288 -209.68335)
		(width 0.16002)
		(layer "In2.Cu")
		(net "M_I_CPU0_SA_DQS_DN<5>")
	)
	(segment
		(start 390.453372 -224.559368)
		(end 390.415272 -224.581466)
		(width 0.09525)
		(layer "In2.Cu")
		(net "M_I_CPU0_SA_DQS_DN<5>")
	)
	(segment
		(start 400.583654 -210.584034)
		(end 400.848322 -210.848702)
		(width 0.16002)
		(layer "In2.Cu")
		(net "M_I_CPU0_SA_DQS_DN<5>")
	)
	(segment
		(start 420.677594 -202.857862)
		(end 419.011862 -202.857862)
		(width 0.16002)
		(layer "In2.Cu")
		(net "M_I_CPU0_SA_DQS_DN<5>")
	)
	(segment
		(start 403.300946 -208.525618)
		(end 403.074378 -208.525618)
		(width 0.16002)
		(layer "In2.Cu")
		(net "M_I_CPU0_SA_DQS_DN<5>")
	)
	(segment
		(start 425.031154 -201.859642)
		(end 424.882818 -202.007978)
		(width 0.16002)
		(layer "In2.Cu")
		(net "M_I_CPU0_SA_DQS_DN<5>")
	)
	(segment
		(start 383.504694 -227.804218)
		(end 383.496312 -227.799392)
		(width 0.09525)
		(layer "In2.Cu")
		(net "M_I_CPU0_SA_DQS_DN<5>")
	)
	(segment
		(start 400.848322 -211.125562)
		(end 400.652488 -211.321396)
		(width 0.16002)
		(layer "In2.Cu")
		(net "M_I_CPU0_SA_DQS_DN<5>")
	)
	(segment
		(start 397.836136 -212.804502)
		(end 397.83639 -213.331298)
		(width 0.16002)
		(layer "In2.Cu")
		(net "M_I_CPU0_SA_DQS_DN<5>")
	)
	(segment
		(start 402.02612 -209.947764)
		(end 401.74926 -209.947764)
		(width 0.16002)
		(layer "In2.Cu")
		(net "M_I_CPU0_SA_DQS_DN<5>")
	)
	(segment
		(start 391.393426 -222.939356)
		(end 391.355326 -222.961454)
		(width 0.09525)
		(layer "In2.Cu")
		(net "M_I_CPU0_SA_DQS_DN<5>")
	)
	(segment
		(start 377.293378 -227.799392)
		(end 377.284996 -227.804218)
		(width 0.09525)
		(layer "In2.Cu")
		(net "M_I_CPU0_SA_DQS_DN<5>")
	)
	(segment
		(start 381.993394 -227.799392)
		(end 381.985012 -227.804218)
		(width 0.09525)
		(layer "In2.Cu")
		(net "M_I_CPU0_SA_DQS_DN<5>")
	)
	(segment
		(start 413.498284 -202.493118)
		(end 413.13354 -202.857862)
		(width 0.16002)
		(layer "In2.Cu")
		(net "M_I_CPU0_SA_DQS_DN<5>")
	)
	(segment
		(start 391.424922 -222.921068)
		(end 391.393426 -222.939356)
		(width 0.09525)
		(layer "In2.Cu")
		(net "M_I_CPU0_SA_DQS_DN<5>")
	)
	(segment
		(start 388.20471 -227.804218)
		(end 388.196328 -227.799392)
		(width 0.09525)
		(layer "In2.Cu")
		(net "M_I_CPU0_SA_DQS_DN<5>")
	)
	(segment
		(start 378.804678 -227.804218)
		(end 378.796296 -227.799392)
		(width 0.09525)
		(layer "In2.Cu")
		(net "M_I_CPU0_SA_DQS_DN<5>")
	)
	(segment
		(start 421.479218 -202.493118)
		(end 421.042338 -202.493118)
		(width 0.16002)
		(layer "In2.Cu")
		(net "M_I_CPU0_SA_DQS_DN<5>")
	)
	(segment
		(start 400.5834 -210.057238)
		(end 400.583654 -210.584034)
		(width 0.16002)
		(layer "In2.Cu")
		(net "M_I_CPU0_SA_DQS_DN<5>")
	)
	(segment
		(start 399.278856 -212.695028)
		(end 399.001996 -212.695028)
		(width 0.16002)
		(layer "In2.Cu")
		(net "M_I_CPU0_SA_DQS_DN<5>")
	)
	(segment
		(start 415.391092 -201.700638)
		(end 414.727644 -201.700638)
		(width 0.16002)
		(layer "In2.Cu")
		(net "M_I_CPU0_SA_DQS_DN<5>")
	)
	(segment
		(start 400.652488 -211.321396)
		(end 400.375628 -211.321396)
		(width 0.16002)
		(layer "In2.Cu")
		(net "M_I_CPU0_SA_DQS_DN<5>")
	)
	(segment
		(start 422.271698 -201.700638)
		(end 421.479218 -202.493118)
		(width 0.16002)
		(layer "In2.Cu")
		(net "M_I_CPU0_SA_DQS_DN<5>")
	)
	(segment
		(start 398.101058 -213.595966)
		(end 398.101058 -213.872826)
		(width 0.16002)
		(layer "In2.Cu")
		(net "M_I_CPU0_SA_DQS_DN<5>")
	)
	(segment
		(start 389.07593 -226.97059)
		(end 389.043418 -226.989386)
		(width 0.09525)
		(layer "In2.Cu")
		(net "M_I_CPU0_SA_DQS_DN<5>")
	)
	(segment
		(start 413.935164 -202.493118)
		(end 413.498284 -202.493118)
		(width 0.16002)
		(layer "In2.Cu")
		(net "M_I_CPU0_SA_DQS_DN<5>")
	)
	(segment
		(start 399.47469 -212.222334)
		(end 399.47469 -212.499194)
		(width 0.16002)
		(layer "In2.Cu")
		(net "M_I_CPU0_SA_DQS_DN<5>")
	)
	(segment
		(start 391.993882 -219.980002)
		(end 391.993882 -221.17431)
		(width 0.16002)
		(layer "In2.Cu")
		(net "M_I_CPU0_SA_DQS_DN<5>")
	)
	(segment
		(start 392.053064 -221.257114)
		(end 392.053064 -221.803468)
		(width 0.09525)
		(layer "In2.Cu")
		(net "M_I_CPU0_SA_DQS_DN<5>")
	)
	(segment
		(start 423.242486 -202.007978)
		(end 422.935146 -201.700638)
		(width 0.16002)
		(layer "In2.Cu")
		(net "M_I_CPU0_SA_DQS_DN<5>")
	)
	(segment
		(start 387.264656 -227.804218)
		(end 387.256274 -227.799392)
		(width 0.09525)
		(layer "In2.Cu")
		(net "M_I_CPU0_SA_DQS_DN<5>")
	)
	(segment
		(start 390.485884 -224.540572)
		(end 390.453372 -224.559368)
		(width 0.09525)
		(layer "In2.Cu")
		(net "M_I_CPU0_SA_DQS_DN<5>")
	)
	(segment
		(start 391.993882 -221.17431)
		(end 391.993882 -221.197932)
		(width 0.09525)
		(layer "In2.Cu")
		(net "M_I_CPU0_SA_DQS_DN<5>")
	)
	(segment
		(start 402.33092 -208.309718)
		(end 401.957032 -208.683606)
		(width 0.16002)
		(layer "In2.Cu")
		(net "M_I_CPU0_SA_DQS_DN<5>")
	)
	(segment
		(start 400.11096 -211.056728)
		(end 399.583656 -211.056982)
		(width 0.16002)
		(layer "In2.Cu")
		(net "M_I_CPU0_SA_DQS_DN<5>")
	)
	(segment
		(start 427.181518 -201.859642)
		(end 425.031154 -201.859642)
		(width 0.16002)
		(layer "In2.Cu")
		(net "M_I_CPU0_SA_DQS_DN<5>")
	)
	(segment
		(start 402.858224 -208.309464)
		(end 402.33092 -208.309718)
		(width 0.16002)
		(layer "In2.Cu")
		(net "M_I_CPU0_SA_DQS_DN<5>")
	)
	(segment
		(start 385.74599 -227.80371)
		(end 385.744974 -227.804218)
		(width 0.09525)
		(layer "In2.Cu")
		(net "M_I_CPU0_SA_DQS_DN<5>")
	)
	(segment
		(start 400.375628 -211.321396)
		(end 400.11096 -211.056728)
		(width 0.16002)
		(layer "In2.Cu")
		(net "M_I_CPU0_SA_DQS_DN<5>")
	)
	(segment
		(start 399.47469 -212.499194)
		(end 399.278856 -212.695028)
		(width 0.16002)
		(layer "In2.Cu")
		(net "M_I_CPU0_SA_DQS_DN<5>")
	)
	(segment
		(start 389.54583 -226.160584)
		(end 389.513318 -226.17938)
		(width 0.09525)
		(layer "In2.Cu")
		(net "M_I_CPU0_SA_DQS_DN<5>")
	)
	(segment
		(start 403.683724 -208.14284)
		(end 403.300946 -208.525618)
		(width 0.16002)
		(layer "In2.Cu")
		(net "M_I_CPU0_SA_DQS_DN<5>")
	)
	(segment
		(start 398.101058 -213.872826)
		(end 391.993882 -219.980002)
		(width 0.16002)
		(layer "In2.Cu")
		(net "M_I_CPU0_SA_DQS_DN<5>")
	)
	(segment
		(start 422.935146 -201.700638)
		(end 422.271698 -201.700638)
		(width 0.16002)
		(layer "In2.Cu")
		(net "M_I_CPU0_SA_DQS_DN<5>")
	)
	(segment
		(start 403.074378 -208.525618)
		(end 402.858224 -208.309464)
		(width 0.16002)
		(layer "In2.Cu")
		(net "M_I_CPU0_SA_DQS_DN<5>")
	)
	(segment
		(start 390.014968 -225.351086)
		(end 389.983472 -225.369374)
		(width 0.09525)
		(layer "In2.Cu")
		(net "M_I_CPU0_SA_DQS_DN<5>")
	)
	(segment
		(start 391.993882 -221.197932)
		(end 392.053064 -221.257114)
		(width 0.09525)
		(layer "In2.Cu")
		(net "M_I_CPU0_SA_DQS_DN<5>")
	)
	(segment
		(start 419.011862 -202.857862)
		(end 418.161978 -202.007978)
		(width 0.16002)
		(layer "In2.Cu")
		(net "M_I_CPU0_SA_DQS_DN<5>")
	)
	(segment
		(start 398.737328 -212.43036)
		(end 398.210024 -212.430614)
		(width 0.16002)
		(layer "In2.Cu")
		(net "M_I_CPU0_SA_DQS_DN<5>")
	)
	(segment
		(start 402.221954 -209.47507)
		(end 402.221954 -209.75193)
		(width 0.16002)
		(layer "In2.Cu")
		(net "M_I_CPU0_SA_DQS_DN<5>")
	)
	(segment
		(start 401.957286 -209.210402)
		(end 402.221954 -209.47507)
		(width 0.16002)
		(layer "In2.Cu")
		(net "M_I_CPU0_SA_DQS_DN<5>")
	)
	(segment
		(start 415.698432 -202.007978)
		(end 415.391092 -201.700638)
		(width 0.16002)
		(layer "In2.Cu")
		(net "M_I_CPU0_SA_DQS_DN<5>")
	)
	(segment
		(start 421.042338 -202.493118)
		(end 420.677594 -202.857862)
		(width 0.16002)
		(layer "In2.Cu")
		(net "M_I_CPU0_SA_DQS_DN<5>")
	)
	(segment
		(start 377.864624 -227.804218)
		(end 377.856242 -227.799392)
		(width 0.09525)
		(layer "In2.Cu")
		(net "M_I_CPU0_SA_DQS_DN<5>")
	)
	(segment
		(start 390.923272 -223.749362)
		(end 390.88822 -223.769936)
		(width 0.09525)
		(layer "In2.Cu")
		(net "M_I_CPU0_SA_DQS_DN<5>")
	)
	(segment
		(start 385.753356 -227.799392)
		(end 385.74599 -227.80371)
		(width 0.09525)
		(layer "In2.Cu")
		(net "M_I_CPU0_SA_DQS_DN<5>")
	)
	(segment
		(start 391.897108 -222.109792)
		(end 391.825226 -222.151448)
		(width 0.09525)
		(layer "In2.Cu")
		(net "M_I_CPU0_SA_DQS_DN<5>")
	)
	(segment
		(start 389.983472 -225.369374)
		(end 389.945372 -225.391472)
		(width 0.09525)
		(layer "In2.Cu")
		(net "M_I_CPU0_SA_DQS_DN<5>")
	)
	(segment
		(start 397.83639 -213.331298)
		(end 398.101058 -213.595966)
		(width 0.16002)
		(layer "In2.Cu")
		(net "M_I_CPU0_SA_DQS_DN<5>")
	)
	(segment
		(start 400.957288 -209.68335)
		(end 400.5834 -210.057238)
		(width 0.16002)
		(layer "In2.Cu")
		(net "M_I_CPU0_SA_DQS_DN<5>")
	)
	(segment
		(start 388.605014 -227.781104)
		(end 388.573518 -227.799392)
		(width 0.09525)
		(layer "In2.Cu")
		(net "M_I_CPU0_SA_DQS_DN<5>")
	)
	(segment
		(start 389.043418 -226.989386)
		(end 389.005318 -227.011484)
		(width 0.09525)
		(layer "In2.Cu")
		(net "M_I_CPU0_SA_DQS_DN<5>")
	)
	(segment
		(start 399.583656 -211.056982)
		(end 399.209768 -211.43087)
		(width 0.16002)
		(layer "In2.Cu")
		(net "M_I_CPU0_SA_DQS_DN<5>")
	)
	(segment
		(start 418.161978 -202.007978)
		(end 415.698432 -202.007978)
		(width 0.16002)
		(layer "In2.Cu")
		(net "M_I_CPU0_SA_DQS_DN<5>")
	)
	(segment
		(start 390.955784 -223.730566)
		(end 390.923272 -223.749362)
		(width 0.09525)
		(layer "In2.Cu")
		(net "M_I_CPU0_SA_DQS_DN<5>")
	)
	(segment
		(start 401.74926 -209.947764)
		(end 401.484592 -209.683096)
		(width 0.16002)
		(layer "In2.Cu")
		(net "M_I_CPU0_SA_DQS_DN<5>")
	)
	(segment
		(start 400.848322 -210.848702)
		(end 400.848322 -211.125562)
		(width 0.16002)
		(layer "In2.Cu")
		(net "M_I_CPU0_SA_DQS_DN<5>")
	)
	(segment
		(start 398.210024 -212.430614)
		(end 397.836136 -212.804502)
		(width 0.16002)
		(layer "In2.Cu")
		(net "M_I_CPU0_SA_DQS_DN<5>")
	)
	(segment
		(start 402.221954 -209.75193)
		(end 402.02612 -209.947764)
		(width 0.16002)
		(layer "In2.Cu")
		(net "M_I_CPU0_SA_DQS_DN<5>")
	)
	(segment
		(start 413.13354 -202.857862)
		(end 408.148282 -202.857862)
		(width 0.16002)
		(layer "In2.Cu")
		(net "M_I_CPU0_SA_DQS_DN<5>")
	)
	(segment
		(start 408.148282 -202.857862)
		(end 403.683724 -207.32242)
		(width 0.16002)
		(layer "In2.Cu")
		(net "M_I_CPU0_SA_DQS_DN<5>")
	)
	(segment
		(start 389.513318 -226.17938)
		(end 389.478266 -226.199954)
		(width 0.09525)
		(layer "In2.Cu")
		(net "M_I_CPU0_SA_DQS_DN<5>")
	)
	(segment
		(start 427.456092 -201.585068)
		(end 427.181518 -201.859642)
		(width 0.16002)
		(layer "In2.Cu")
		(net "M_I_CPU0_SA_DQS_DN<5>")
	)
	(segment
		(start 376.0343 -227.82657)
		(end 376.010932 -227.739702)
		(width 0.09525)
		(layer "In2.Cu")
		(net "M_I_CPU0_SA_DQS_DN<5>")
	)
	(segment
		(start 424.882818 -202.007978)
		(end 423.242486 -202.007978)
		(width 0.16002)
		(layer "In2.Cu")
		(net "M_I_CPU0_SA_DQS_DN<5>")
	)
	(segment
		(start 381.05334 -227.799392)
		(end 381.044958 -227.804218)
		(width 0.09525)
		(layer "In2.Cu")
		(net "M_I_CPU0_SA_DQS_DN<5>")
	)
	(segment
		(start 399.001996 -212.695028)
		(end 398.737328 -212.43036)
		(width 0.16002)
		(layer "In2.Cu")
		(net "M_I_CPU0_SA_DQS_DN<5>")
	)
	(segment
		(start 403.683724 -207.32242)
		(end 403.683724 -208.14284)
		(width 0.16002)
		(layer "In2.Cu")
		(net "M_I_CPU0_SA_DQS_DN<5>")
	)
	(segment
		(start 399.210022 -211.957666)
		(end 399.47469 -212.222334)
		(width 0.16002)
		(layer "In2.Cu")
		(net "M_I_CPU0_SA_DQS_DN<5>")
	)
	(segment
		(start 414.727644 -201.700638)
		(end 413.935164 -202.493118)
		(width 0.16002)
		(layer "In2.Cu")
		(net "M_I_CPU0_SA_DQS_DN<5>")
	)
	(segment
		(start 376.010932 -227.739702)
		(end 376.164856 -227.474272)
		(width 0.09525)
		(layer "In2.Cu")
		(net "M_I_CPU0_SA_DQS_DN<5>")
	)
	(segment
		(start 382.56464 -227.804218)
		(end 382.556258 -227.799392)
		(width 0.09525)
		(layer "In2.Cu")
		(net "M_I_CPU0_SA_DQS_DN<5>")
	)
	(segment
		(start 376.353324 -227.799392)
		(end 376.344942 -227.804218)
		(width 0.09525)
		(layer "In2.Cu")
		(net "M_I_CPU0_SA_DQS_DN<5>")
	)
	(segment
		(start 401.957032 -208.683606)
		(end 401.957286 -209.210402)
		(width 0.16002)
		(layer "In2.Cu")
		(net "M_I_CPU0_SA_DQS_DN<5>")
	)
	(arc
		(start 391.582402 -222.614236)
		(mid 391.540737 -222.786683)
		(end 391.424922 -222.921068)
		(width 0.09525)
		(layer "In2.Cu")
		(net "M_I_CPU0_SA_DQS_DN<5>")
	)
	(arc
		(start 379.73635 -227.799392)
		(mid 379.454918 -227.723637)
		(end 379.173486 -227.799392)
		(width 0.09525)
		(layer "In2.Cu")
		(net "M_I_CPU0_SA_DQS_DN<5>")
	)
	(arc
		(start 390.172448 -225.044254)
		(mid 390.130783 -225.216701)
		(end 390.014968 -225.351086)
		(width 0.09525)
		(layer "In2.Cu")
		(net "M_I_CPU0_SA_DQS_DN<5>")
	)
	(arc
		(start 383.496312 -227.799392)
		(mid 383.21488 -227.723637)
		(end 382.933448 -227.799392)
		(width 0.09525)
		(layer "In2.Cu")
		(net "M_I_CPU0_SA_DQS_DN<5>")
	)
	(arc
		(start 386.31622 -227.799392)
		(mid 386.034788 -227.723637)
		(end 385.753356 -227.799392)
		(width 0.09525)
		(layer "In2.Cu")
		(net "M_I_CPU0_SA_DQS_DN<5>")
	)
	(arc
		(start 390.642602 -224.234248)
		(mid 390.601145 -224.406288)
		(end 390.485884 -224.540572)
		(width 0.09525)
		(layer "In2.Cu")
		(net "M_I_CPU0_SA_DQS_DN<5>")
	)
	(arc
		(start 388.196328 -227.799392)
		(mid 387.914896 -227.723637)
		(end 387.633464 -227.799392)
		(width 0.09525)
		(layer "In2.Cu")
		(net "M_I_CPU0_SA_DQS_DN<5>")
	)
	(arc
		(start 387.256274 -227.799392)
		(mid 386.974842 -227.723637)
		(end 386.69341 -227.799392)
		(width 0.09525)
		(layer "In2.Cu")
		(net "M_I_CPU0_SA_DQS_DN<5>")
	)
	(arc
		(start 378.796296 -227.799392)
		(mid 378.514864 -227.723637)
		(end 378.233432 -227.799392)
		(width 0.09525)
		(layer "In2.Cu")
		(net "M_I_CPU0_SA_DQS_DN<5>")
	)
	(arc
		(start 391.355326 -222.961454)
		(mid 391.176876 -223.162924)
		(end 391.112502 -223.424242)
		(width 0.09525)
		(layer "In2.Cu")
		(net "M_I_CPU0_SA_DQS_DN<5>")
	)
	(arc
		(start 385.744974 -227.804218)
		(mid 385.559942 -227.850132)
		(end 385.376166 -227.799392)
		(width 0.09525)
		(layer "In2.Cu")
		(net "M_I_CPU0_SA_DQS_DN<5>")
	)
	(arc
		(start 389.478266 -226.199954)
		(mid 389.297875 -226.401653)
		(end 389.232648 -226.664266)
		(width 0.09525)
		(layer "In2.Cu")
		(net "M_I_CPU0_SA_DQS_DN<5>")
	)
	(arc
		(start 390.415272 -224.581466)
		(mid 390.236822 -224.782936)
		(end 390.172448 -225.044254)
		(width 0.09525)
		(layer "In2.Cu")
		(net "M_I_CPU0_SA_DQS_DN<5>")
	)
	(arc
		(start 379.173486 -227.799392)
		(mid 378.989711 -227.850164)
		(end 378.804678 -227.804218)
		(width 0.09525)
		(layer "In2.Cu")
		(net "M_I_CPU0_SA_DQS_DN<5>")
	)
	(arc
		(start 376.916188 -227.799392)
		(mid 376.634756 -227.723637)
		(end 376.353324 -227.799392)
		(width 0.09525)
		(layer "In2.Cu")
		(net "M_I_CPU0_SA_DQS_DN<5>")
	)
	(arc
		(start 377.284996 -227.804218)
		(mid 377.099964 -227.850132)
		(end 376.916188 -227.799392)
		(width 0.09525)
		(layer "In2.Cu")
		(net "M_I_CPU0_SA_DQS_DN<5>")
	)
	(arc
		(start 381.044958 -227.804218)
		(mid 380.859926 -227.850132)
		(end 380.67615 -227.799392)
		(width 0.09525)
		(layer "In2.Cu")
		(net "M_I_CPU0_SA_DQS_DN<5>")
	)
	(arc
		(start 389.702548 -225.85426)
		(mid 389.661091 -226.0263)
		(end 389.54583 -226.160584)
		(width 0.09525)
		(layer "In2.Cu")
		(net "M_I_CPU0_SA_DQS_DN<5>")
	)
	(arc
		(start 378.233432 -227.799392)
		(mid 378.049657 -227.850164)
		(end 377.864624 -227.804218)
		(width 0.09525)
		(layer "In2.Cu")
		(net "M_I_CPU0_SA_DQS_DN<5>")
	)
	(arc
		(start 380.113286 -227.799392)
		(mid 379.924818 -227.850069)
		(end 379.73635 -227.799392)
		(width 0.09525)
		(layer "In2.Cu")
		(net "M_I_CPU0_SA_DQS_DN<5>")
	)
	(arc
		(start 387.633464 -227.799392)
		(mid 387.449689 -227.850164)
		(end 387.264656 -227.804218)
		(width 0.09525)
		(layer "In2.Cu")
		(net "M_I_CPU0_SA_DQS_DN<5>")
	)
	(arc
		(start 377.856242 -227.799392)
		(mid 377.57481 -227.723637)
		(end 377.293378 -227.799392)
		(width 0.09525)
		(layer "In2.Cu")
		(net "M_I_CPU0_SA_DQS_DN<5>")
	)
	(arc
		(start 385.376166 -227.799392)
		(mid 385.094734 -227.723637)
		(end 384.813302 -227.799392)
		(width 0.09525)
		(layer "In2.Cu")
		(net "M_I_CPU0_SA_DQS_DN<5>")
	)
	(arc
		(start 389.005318 -227.011484)
		(mid 388.826868 -227.212954)
		(end 388.762494 -227.474272)
		(width 0.09525)
		(layer "In2.Cu")
		(net "M_I_CPU0_SA_DQS_DN<5>")
	)
	(arc
		(start 381.616204 -227.799392)
		(mid 381.334772 -227.723637)
		(end 381.05334 -227.799392)
		(width 0.09525)
		(layer "In2.Cu")
		(net "M_I_CPU0_SA_DQS_DN<5>")
	)
	(arc
		(start 388.762494 -227.474272)
		(mid 388.720829 -227.646719)
		(end 388.605014 -227.781104)
		(width 0.09525)
		(layer "In2.Cu")
		(net "M_I_CPU0_SA_DQS_DN<5>")
	)
	(arc
		(start 391.825226 -222.151448)
		(mid 391.646776 -222.352918)
		(end 391.582402 -222.614236)
		(width 0.09525)
		(layer "In2.Cu")
		(net "M_I_CPU0_SA_DQS_DN<5>")
	)
	(arc
		(start 392.053064 -221.803468)
		(mid 392.011823 -221.975328)
		(end 391.897108 -222.109792)
		(width 0.09525)
		(layer "In2.Cu")
		(net "M_I_CPU0_SA_DQS_DN<5>")
	)
	(arc
		(start 389.945372 -225.391472)
		(mid 389.766922 -225.592942)
		(end 389.702548 -225.85426)
		(width 0.09525)
		(layer "In2.Cu")
		(net "M_I_CPU0_SA_DQS_DN<5>")
	)
	(arc
		(start 389.232648 -226.664266)
		(mid 389.191191 -226.836306)
		(end 389.07593 -226.97059)
		(width 0.09525)
		(layer "In2.Cu")
		(net "M_I_CPU0_SA_DQS_DN<5>")
	)
	(arc
		(start 383.873502 -227.799392)
		(mid 383.689727 -227.850164)
		(end 383.504694 -227.804218)
		(width 0.09525)
		(layer "In2.Cu")
		(net "M_I_CPU0_SA_DQS_DN<5>")
	)
	(arc
		(start 382.933448 -227.799392)
		(mid 382.749673 -227.850164)
		(end 382.56464 -227.804218)
		(width 0.09525)
		(layer "In2.Cu")
		(net "M_I_CPU0_SA_DQS_DN<5>")
	)
	(arc
		(start 384.813302 -227.799392)
		(mid 384.624834 -227.850069)
		(end 384.436366 -227.799392)
		(width 0.09525)
		(layer "In2.Cu")
		(net "M_I_CPU0_SA_DQS_DN<5>")
	)
	(arc
		(start 381.985012 -227.804218)
		(mid 381.79998 -227.850132)
		(end 381.616204 -227.799392)
		(width 0.09525)
		(layer "In2.Cu")
		(net "M_I_CPU0_SA_DQS_DN<5>")
	)
	(arc
		(start 380.67615 -227.799392)
		(mid 380.394718 -227.723637)
		(end 380.113286 -227.799392)
		(width 0.09525)
		(layer "In2.Cu")
		(net "M_I_CPU0_SA_DQS_DN<5>")
	)
	(arc
		(start 376.344942 -227.804218)
		(mid 376.192047 -227.849046)
		(end 376.0343 -227.82657)
		(width 0.09525)
		(layer "In2.Cu")
		(net "M_I_CPU0_SA_DQS_DN<5>")
	)
	(arc
		(start 382.556258 -227.799392)
		(mid 382.274826 -227.723637)
		(end 381.993394 -227.799392)
		(width 0.09525)
		(layer "In2.Cu")
		(net "M_I_CPU0_SA_DQS_DN<5>")
	)
	(arc
		(start 386.685028 -227.804218)
		(mid 386.499996 -227.850132)
		(end 386.31622 -227.799392)
		(width 0.09525)
		(layer "In2.Cu")
		(net "M_I_CPU0_SA_DQS_DN<5>")
	)
	(arc
		(start 384.436366 -227.799392)
		(mid 384.154934 -227.723637)
		(end 383.873502 -227.799392)
		(width 0.09525)
		(layer "In2.Cu")
		(net "M_I_CPU0_SA_DQS_DN<5>")
	)
	(arc
		(start 388.573518 -227.799392)
		(mid 388.389743 -227.850164)
		(end 388.20471 -227.804218)
		(width 0.09525)
		(layer "In2.Cu")
		(net "M_I_CPU0_SA_DQS_DN<5>")
	)
	(arc
		(start 391.112502 -223.424242)
		(mid 391.071045 -223.596282)
		(end 390.955784 -223.730566)
		(width 0.09525)
		(layer "In2.Cu")
		(net "M_I_CPU0_SA_DQS_DN<5>")
	)
	(arc
		(start 390.88822 -223.769936)
		(mid 390.707829 -223.971635)
		(end 390.642602 -224.234248)
		(width 0.09525)
		(layer "In2.Cu")
		(net "M_I_CPU0_SA_DQS_DN<5>")
	)
	(segment
		(start 376.638058 -247.1801)
		(end 377.10491 -246.914162)
		(width 0.12954)
		(layer "F.Cu")
		(net "M_I_CPU0_SA_DQS_DN<4>")
	)
	(segment
		(start 422.957498 -238.028734)
		(end 423.273982 -237.71225)
		(width 0.16002)
		(layer "In2.Cu")
		(net "M_I_CPU0_SA_DQS_DN<4>")
	)
	(segment
		(start 431.28311 -238.711994)
		(end 431.55616 -238.985044)
		(width 0.16002)
		(layer "In2.Cu")
		(net "M_I_CPU0_SA_DQS_DN<4>")
	)
	(segment
		(start 417.708588 -237.71225)
		(end 418.558472 -238.562134)
		(width 0.16002)
		(layer "In2.Cu")
		(net "M_I_CPU0_SA_DQS_DN<4>")
	)
	(segment
		(start 390.44499 -246.584216)
		(end 390.453372 -246.589042)
		(width 0.09525)
		(layer "In2.Cu")
		(net "M_I_CPU0_SA_DQS_DN<4>")
	)
	(segment
		(start 395.662404 -246.64162)
		(end 395.686026 -246.64162)
		(width 0.09525)
		(layer "In2.Cu")
		(net "M_I_CPU0_SA_DQS_DN<4>")
	)
	(segment
		(start 382.556258 -246.589042)
		(end 382.56464 -246.584216)
		(width 0.09525)
		(layer "In2.Cu")
		(net "M_I_CPU0_SA_DQS_DN<4>")
	)
	(segment
		(start 405.1427 -246.061992)
		(end 411.194758 -240.009934)
		(width 0.16002)
		(layer "In2.Cu")
		(net "M_I_CPU0_SA_DQS_DN<4>")
	)
	(segment
		(start 421.591486 -238.869474)
		(end 422.432226 -238.028734)
		(width 0.16002)
		(layer "In2.Cu")
		(net "M_I_CPU0_SA_DQS_DN<4>")
	)
	(segment
		(start 425.300394 -237.71225)
		(end 425.874434 -238.28629)
		(width 0.16002)
		(layer "In2.Cu")
		(net "M_I_CPU0_SA_DQS_DN<4>")
	)
	(segment
		(start 427.959774 -238.28629)
		(end 428.568358 -238.894874)
		(width 0.16002)
		(layer "In2.Cu")
		(net "M_I_CPU0_SA_DQS_DN<4>")
	)
	(segment
		(start 428.568358 -238.894874)
		(end 429.277018 -238.894874)
		(width 0.16002)
		(layer "In2.Cu")
		(net "M_I_CPU0_SA_DQS_DN<4>")
	)
	(segment
		(start 415.729928 -237.71225)
		(end 417.708588 -237.71225)
		(width 0.16002)
		(layer "In2.Cu")
		(net "M_I_CPU0_SA_DQS_DN<4>")
	)
	(segment
		(start 377.856242 -246.589042)
		(end 377.864624 -246.584216)
		(width 0.09525)
		(layer "In2.Cu")
		(net "M_I_CPU0_SA_DQS_DN<4>")
	)
	(segment
		(start 393.895326 -246.94896)
		(end 394.953744 -246.94896)
		(width 0.09525)
		(layer "In2.Cu")
		(net "M_I_CPU0_SA_DQS_DN<4>")
	)
	(segment
		(start 411.194758 -240.009934)
		(end 411.194758 -238.88065)
		(width 0.16002)
		(layer "In2.Cu")
		(net "M_I_CPU0_SA_DQS_DN<4>")
	)
	(segment
		(start 425.874434 -238.28629)
		(end 427.959774 -238.28629)
		(width 0.16002)
		(layer "In2.Cu")
		(net "M_I_CPU0_SA_DQS_DN<4>")
	)
	(segment
		(start 386.685028 -246.584216)
		(end 386.69341 -246.589042)
		(width 0.09525)
		(layer "In2.Cu")
		(net "M_I_CPU0_SA_DQS_DN<4>")
	)
	(segment
		(start 420.999158 -238.869474)
		(end 421.591486 -238.869474)
		(width 0.16002)
		(layer "In2.Cu")
		(net "M_I_CPU0_SA_DQS_DN<4>")
	)
	(segment
		(start 393.240006 -246.570754)
		(end 393.27201 -246.589296)
		(width 0.09525)
		(layer "In2.Cu")
		(net "M_I_CPU0_SA_DQS_DN<4>")
	)
	(segment
		(start 388.196328 -246.589042)
		(end 388.20471 -246.584216)
		(width 0.09525)
		(layer "In2.Cu")
		(net "M_I_CPU0_SA_DQS_DN<4>")
	)
	(segment
		(start 429.459898 -238.711994)
		(end 431.28311 -238.711994)
		(width 0.16002)
		(layer "In2.Cu")
		(net "M_I_CPU0_SA_DQS_DN<4>")
	)
	(segment
		(start 395.686026 -246.64162)
		(end 395.94155 -246.64162)
		(width 0.16002)
		(layer "In2.Cu")
		(net "M_I_CPU0_SA_DQS_DN<4>")
	)
	(segment
		(start 423.273982 -237.71225)
		(end 425.300394 -237.71225)
		(width 0.16002)
		(layer "In2.Cu")
		(net "M_I_CPU0_SA_DQS_DN<4>")
	)
	(segment
		(start 381.985012 -246.584216)
		(end 381.993394 -246.589042)
		(width 0.09525)
		(layer "In2.Cu")
		(net "M_I_CPU0_SA_DQS_DN<4>")
	)
	(segment
		(start 392.330178 -246.589042)
		(end 392.354054 -246.603012)
		(width 0.09525)
		(layer "In2.Cu")
		(net "M_I_CPU0_SA_DQS_DN<4>")
	)
	(segment
		(start 429.277018 -238.894874)
		(end 429.459898 -238.711994)
		(width 0.16002)
		(layer "In2.Cu")
		(net "M_I_CPU0_SA_DQS_DN<4>")
	)
	(segment
		(start 381.044958 -246.584216)
		(end 381.05334 -246.589042)
		(width 0.09525)
		(layer "In2.Cu")
		(net "M_I_CPU0_SA_DQS_DN<4>")
	)
	(segment
		(start 383.496312 -246.589042)
		(end 383.504694 -246.584216)
		(width 0.09525)
		(layer "In2.Cu")
		(net "M_I_CPU0_SA_DQS_DN<4>")
	)
	(segment
		(start 385.744974 -246.584216)
		(end 385.753356 -246.589042)
		(width 0.09525)
		(layer "In2.Cu")
		(net "M_I_CPU0_SA_DQS_DN<4>")
	)
	(segment
		(start 393.610338 -246.663972)
		(end 393.895326 -246.94896)
		(width 0.09525)
		(layer "In2.Cu")
		(net "M_I_CPU0_SA_DQS_DN<4>")
	)
	(segment
		(start 395.320012 -246.582692)
		(end 395.603476 -246.582692)
		(width 0.09525)
		(layer "In2.Cu")
		(net "M_I_CPU0_SA_DQS_DN<4>")
	)
	(segment
		(start 411.194758 -238.88065)
		(end 411.513274 -238.562134)
		(width 0.16002)
		(layer "In2.Cu")
		(net "M_I_CPU0_SA_DQS_DN<4>")
	)
	(segment
		(start 396.521178 -246.061992)
		(end 405.1427 -246.061992)
		(width 0.16002)
		(layer "In2.Cu")
		(net "M_I_CPU0_SA_DQS_DN<4>")
	)
	(segment
		(start 377.258834 -246.648732)
		(end 377.359672 -246.622062)
		(width 0.09525)
		(layer "In2.Cu")
		(net "M_I_CPU0_SA_DQS_DN<4>")
	)
	(segment
		(start 415.413444 -238.028734)
		(end 415.729928 -237.71225)
		(width 0.16002)
		(layer "In2.Cu")
		(net "M_I_CPU0_SA_DQS_DN<4>")
	)
	(segment
		(start 413.455104 -238.869474)
		(end 414.047432 -238.869474)
		(width 0.16002)
		(layer "In2.Cu")
		(net "M_I_CPU0_SA_DQS_DN<4>")
	)
	(segment
		(start 422.432226 -238.028734)
		(end 422.957498 -238.028734)
		(width 0.16002)
		(layer "In2.Cu")
		(net "M_I_CPU0_SA_DQS_DN<4>")
	)
	(segment
		(start 393.550902 -246.663972)
		(end 393.610338 -246.663972)
		(width 0.09525)
		(layer "In2.Cu")
		(net "M_I_CPU0_SA_DQS_DN<4>")
	)
	(segment
		(start 414.047432 -238.869474)
		(end 414.888172 -238.028734)
		(width 0.16002)
		(layer "In2.Cu")
		(net "M_I_CPU0_SA_DQS_DN<4>")
	)
	(segment
		(start 414.888172 -238.028734)
		(end 415.413444 -238.028734)
		(width 0.16002)
		(layer "In2.Cu")
		(net "M_I_CPU0_SA_DQS_DN<4>")
	)
	(segment
		(start 395.94155 -246.64162)
		(end 396.521178 -246.061992)
		(width 0.16002)
		(layer "In2.Cu")
		(net "M_I_CPU0_SA_DQS_DN<4>")
	)
	(segment
		(start 411.513274 -238.562134)
		(end 413.147764 -238.562134)
		(width 0.16002)
		(layer "In2.Cu")
		(net "M_I_CPU0_SA_DQS_DN<4>")
	)
	(segment
		(start 395.603476 -246.582692)
		(end 395.662404 -246.64162)
		(width 0.09525)
		(layer "In2.Cu")
		(net "M_I_CPU0_SA_DQS_DN<4>")
	)
	(segment
		(start 391.016236 -246.589042)
		(end 391.024618 -246.584216)
		(width 0.09525)
		(layer "In2.Cu")
		(net "M_I_CPU0_SA_DQS_DN<4>")
	)
	(segment
		(start 413.147764 -238.562134)
		(end 413.455104 -238.869474)
		(width 0.16002)
		(layer "In2.Cu")
		(net "M_I_CPU0_SA_DQS_DN<4>")
	)
	(segment
		(start 377.10491 -246.914162)
		(end 377.258834 -246.648732)
		(width 0.09525)
		(layer "In2.Cu")
		(net "M_I_CPU0_SA_DQS_DN<4>")
	)
	(segment
		(start 394.953744 -246.94896)
		(end 395.320012 -246.582692)
		(width 0.09525)
		(layer "In2.Cu")
		(net "M_I_CPU0_SA_DQS_DN<4>")
	)
	(segment
		(start 387.256274 -246.589042)
		(end 387.264656 -246.584216)
		(width 0.09525)
		(layer "In2.Cu")
		(net "M_I_CPU0_SA_DQS_DN<4>")
	)
	(segment
		(start 391.930636 -246.603012)
		(end 391.954512 -246.589296)
		(width 0.09525)
		(layer "In2.Cu")
		(net "M_I_CPU0_SA_DQS_DN<4>")
	)
	(segment
		(start 378.796296 -246.589042)
		(end 378.804678 -246.584216)
		(width 0.09525)
		(layer "In2.Cu")
		(net "M_I_CPU0_SA_DQS_DN<4>")
	)
	(segment
		(start 418.558472 -238.562134)
		(end 420.691818 -238.562134)
		(width 0.16002)
		(layer "In2.Cu")
		(net "M_I_CPU0_SA_DQS_DN<4>")
	)
	(segment
		(start 391.954512 -246.589296)
		(end 391.976356 -246.57685)
		(width 0.09525)
		(layer "In2.Cu")
		(net "M_I_CPU0_SA_DQS_DN<4>")
	)
	(segment
		(start 420.691818 -238.562134)
		(end 420.999158 -238.869474)
		(width 0.16002)
		(layer "In2.Cu")
		(net "M_I_CPU0_SA_DQS_DN<4>")
	)
	(arc
		(start 377.359672 -246.622062)
		(mid 377.36954 -246.626093)
		(end 377.379484 -246.629936)
		(width 0.09525)
		(layer "In2.Cu")
		(net "M_I_CPU0_SA_DQS_DN<4>")
	)
	(arc
		(start 388.20471 -246.584216)
		(mid 388.389742 -246.538302)
		(end 388.573518 -246.589042)
		(width 0.09525)
		(layer "In2.Cu")
		(net "M_I_CPU0_SA_DQS_DN<4>")
	)
	(arc
		(start 378.804678 -246.584216)
		(mid 378.98971 -246.538302)
		(end 379.173486 -246.589042)
		(width 0.09525)
		(layer "In2.Cu")
		(net "M_I_CPU0_SA_DQS_DN<4>")
	)
	(arc
		(start 390.453372 -246.589042)
		(mid 390.734804 -246.664797)
		(end 391.016236 -246.589042)
		(width 0.09525)
		(layer "In2.Cu")
		(net "M_I_CPU0_SA_DQS_DN<4>")
	)
	(arc
		(start 388.573518 -246.589042)
		(mid 388.85495 -246.664797)
		(end 389.136382 -246.589042)
		(width 0.09525)
		(layer "In2.Cu")
		(net "M_I_CPU0_SA_DQS_DN<4>")
	)
	(arc
		(start 389.513318 -246.589042)
		(mid 389.79475 -246.664797)
		(end 390.076182 -246.589042)
		(width 0.09525)
		(layer "In2.Cu")
		(net "M_I_CPU0_SA_DQS_DN<4>")
	)
	(arc
		(start 377.864624 -246.584216)
		(mid 378.049656 -246.538302)
		(end 378.233432 -246.589042)
		(width 0.09525)
		(layer "In2.Cu")
		(net "M_I_CPU0_SA_DQS_DN<4>")
	)
	(arc
		(start 383.873502 -246.589042)
		(mid 384.154934 -246.664797)
		(end 384.436366 -246.589042)
		(width 0.09525)
		(layer "In2.Cu")
		(net "M_I_CPU0_SA_DQS_DN<4>")
	)
	(arc
		(start 378.233432 -246.589042)
		(mid 378.514864 -246.664797)
		(end 378.796296 -246.589042)
		(width 0.09525)
		(layer "In2.Cu")
		(net "M_I_CPU0_SA_DQS_DN<4>")
	)
	(arc
		(start 387.264656 -246.584216)
		(mid 387.449688 -246.538302)
		(end 387.633464 -246.589042)
		(width 0.09525)
		(layer "In2.Cu")
		(net "M_I_CPU0_SA_DQS_DN<4>")
	)
	(arc
		(start 384.436366 -246.589042)
		(mid 384.624834 -246.538365)
		(end 384.813302 -246.589042)
		(width 0.09525)
		(layer "In2.Cu")
		(net "M_I_CPU0_SA_DQS_DN<4>")
	)
	(arc
		(start 381.05334 -246.589042)
		(mid 381.334772 -246.664797)
		(end 381.616204 -246.589042)
		(width 0.09525)
		(layer "In2.Cu")
		(net "M_I_CPU0_SA_DQS_DN<4>")
	)
	(arc
		(start 392.89482 -246.588788)
		(mid 393.065217 -246.537889)
		(end 393.240006 -246.570754)
		(width 0.09525)
		(layer "In2.Cu")
		(net "M_I_CPU0_SA_DQS_DN<4>")
	)
	(arc
		(start 379.173486 -246.589042)
		(mid 379.454918 -246.664797)
		(end 379.73635 -246.589042)
		(width 0.09525)
		(layer "In2.Cu")
		(net "M_I_CPU0_SA_DQS_DN<4>")
	)
	(arc
		(start 381.993394 -246.589042)
		(mid 382.274826 -246.664797)
		(end 382.556258 -246.589042)
		(width 0.09525)
		(layer "In2.Cu")
		(net "M_I_CPU0_SA_DQS_DN<4>")
	)
	(arc
		(start 380.67615 -246.589042)
		(mid 380.859925 -246.53827)
		(end 381.044958 -246.584216)
		(width 0.09525)
		(layer "In2.Cu")
		(net "M_I_CPU0_SA_DQS_DN<4>")
	)
	(arc
		(start 386.69341 -246.589042)
		(mid 386.974842 -246.664797)
		(end 387.256274 -246.589042)
		(width 0.09525)
		(layer "In2.Cu")
		(net "M_I_CPU0_SA_DQS_DN<4>")
	)
	(arc
		(start 392.354054 -246.603012)
		(mid 392.626278 -246.665384)
		(end 392.89482 -246.588788)
		(width 0.09525)
		(layer "In2.Cu")
		(net "M_I_CPU0_SA_DQS_DN<4>")
	)
	(arc
		(start 387.633464 -246.589042)
		(mid 387.914896 -246.664797)
		(end 388.196328 -246.589042)
		(width 0.09525)
		(layer "In2.Cu")
		(net "M_I_CPU0_SA_DQS_DN<4>")
	)
	(arc
		(start 377.379484 -246.629936)
		(mid 377.622448 -246.662923)
		(end 377.856242 -246.589042)
		(width 0.09525)
		(layer "In2.Cu")
		(net "M_I_CPU0_SA_DQS_DN<4>")
	)
	(arc
		(start 391.976356 -246.57685)
		(mid 392.154808 -246.538608)
		(end 392.330178 -246.589042)
		(width 0.09525)
		(layer "In2.Cu")
		(net "M_I_CPU0_SA_DQS_DN<4>")
	)
	(arc
		(start 382.933448 -246.589042)
		(mid 383.21488 -246.664797)
		(end 383.496312 -246.589042)
		(width 0.09525)
		(layer "In2.Cu")
		(net "M_I_CPU0_SA_DQS_DN<4>")
	)
	(arc
		(start 390.076182 -246.589042)
		(mid 390.259957 -246.53827)
		(end 390.44499 -246.584216)
		(width 0.09525)
		(layer "In2.Cu")
		(net "M_I_CPU0_SA_DQS_DN<4>")
	)
	(arc
		(start 385.376166 -246.589042)
		(mid 385.559941 -246.53827)
		(end 385.744974 -246.584216)
		(width 0.09525)
		(layer "In2.Cu")
		(net "M_I_CPU0_SA_DQS_DN<4>")
	)
	(arc
		(start 380.113286 -246.589042)
		(mid 380.394718 -246.664797)
		(end 380.67615 -246.589042)
		(width 0.09525)
		(layer "In2.Cu")
		(net "M_I_CPU0_SA_DQS_DN<4>")
	)
	(arc
		(start 379.73635 -246.589042)
		(mid 379.924818 -246.538365)
		(end 380.113286 -246.589042)
		(width 0.09525)
		(layer "In2.Cu")
		(net "M_I_CPU0_SA_DQS_DN<4>")
	)
	(arc
		(start 385.753356 -246.589042)
		(mid 386.034788 -246.664797)
		(end 386.31622 -246.589042)
		(width 0.09525)
		(layer "In2.Cu")
		(net "M_I_CPU0_SA_DQS_DN<4>")
	)
	(arc
		(start 393.27201 -246.589296)
		(mid 393.405213 -246.644548)
		(end 393.548108 -246.663972)
		(width 0.09525)
		(layer "In2.Cu")
		(net "M_I_CPU0_SA_DQS_DN<4>")
	)
	(arc
		(start 386.31622 -246.589042)
		(mid 386.499995 -246.53827)
		(end 386.685028 -246.584216)
		(width 0.09525)
		(layer "In2.Cu")
		(net "M_I_CPU0_SA_DQS_DN<4>")
	)
	(arc
		(start 382.56464 -246.584216)
		(mid 382.749672 -246.538302)
		(end 382.933448 -246.589042)
		(width 0.09525)
		(layer "In2.Cu")
		(net "M_I_CPU0_SA_DQS_DN<4>")
	)
	(arc
		(start 391.024618 -246.584216)
		(mid 391.20965 -246.538302)
		(end 391.393426 -246.589042)
		(width 0.09525)
		(layer "In2.Cu")
		(net "M_I_CPU0_SA_DQS_DN<4>")
	)
	(arc
		(start 383.504694 -246.584216)
		(mid 383.689726 -246.538302)
		(end 383.873502 -246.589042)
		(width 0.09525)
		(layer "In2.Cu")
		(net "M_I_CPU0_SA_DQS_DN<4>")
	)
	(arc
		(start 393.548108 -246.663972)
		(mid 393.549505 -246.663974)
		(end 393.550902 -246.663972)
		(width 0.09525)
		(layer "In2.Cu")
		(net "M_I_CPU0_SA_DQS_DN<4>")
	)
	(arc
		(start 391.393426 -246.589042)
		(mid 391.660252 -246.664607)
		(end 391.930636 -246.603012)
		(width 0.09525)
		(layer "In2.Cu")
		(net "M_I_CPU0_SA_DQS_DN<4>")
	)
	(arc
		(start 381.616204 -246.589042)
		(mid 381.799979 -246.53827)
		(end 381.985012 -246.584216)
		(width 0.09525)
		(layer "In2.Cu")
		(net "M_I_CPU0_SA_DQS_DN<4>")
	)
	(arc
		(start 384.813302 -246.589042)
		(mid 385.094734 -246.664797)
		(end 385.376166 -246.589042)
		(width 0.09525)
		(layer "In2.Cu")
		(net "M_I_CPU0_SA_DQS_DN<4>")
	)
	(arc
		(start 389.136382 -246.589042)
		(mid 389.32485 -246.538365)
		(end 389.513318 -246.589042)
		(width 0.09525)
		(layer "In2.Cu")
		(net "M_I_CPU0_SA_DQS_DN<4>")
	)
	(segment
		(start 376.638058 -242.320064)
		(end 377.10491 -242.054126)
		(width 0.12954)
		(layer "F.Cu")
		(net "M_I_CPU0_SA_DQS_DN<3>")
	)
	(segment
		(start 385.744974 -241.72418)
		(end 385.753356 -241.729006)
		(width 0.09525)
		(layer "In2.Cu")
		(net "M_I_CPU0_SA_DQS_DN<3>")
	)
	(segment
		(start 405.091646 -235.788962)
		(end 409.855416 -231.025192)
		(width 0.16002)
		(layer "In2.Cu")
		(net "M_I_CPU0_SA_DQS_DN<3>")
	)
	(segment
		(start 422.957498 -228.67874)
		(end 423.273982 -228.362256)
		(width 0.16002)
		(layer "In2.Cu")
		(net "M_I_CPU0_SA_DQS_DN<3>")
	)
	(segment
		(start 381.985012 -241.72418)
		(end 381.993394 -241.729006)
		(width 0.09525)
		(layer "In2.Cu")
		(net "M_I_CPU0_SA_DQS_DN<3>")
	)
	(segment
		(start 409.855416 -230.759)
		(end 411.402276 -229.21214)
		(width 0.16002)
		(layer "In2.Cu")
		(net "M_I_CPU0_SA_DQS_DN<3>")
	)
	(segment
		(start 415.729928 -228.362256)
		(end 417.708588 -228.362256)
		(width 0.16002)
		(layer "In2.Cu")
		(net "M_I_CPU0_SA_DQS_DN<3>")
	)
	(segment
		(start 418.558472 -229.21214)
		(end 420.691818 -229.21214)
		(width 0.16002)
		(layer "In2.Cu")
		(net "M_I_CPU0_SA_DQS_DN<3>")
	)
	(segment
		(start 377.258834 -241.788696)
		(end 377.359672 -241.762026)
		(width 0.09525)
		(layer "In2.Cu")
		(net "M_I_CPU0_SA_DQS_DN<3>")
	)
	(segment
		(start 395.662404 -240.357406)
		(end 395.686026 -240.357406)
		(width 0.09525)
		(layer "In2.Cu")
		(net "M_I_CPU0_SA_DQS_DN<3>")
	)
	(segment
		(start 391.945622 -241.735102)
		(end 391.956036 -241.729006)
		(width 0.09525)
		(layer "In2.Cu")
		(net "M_I_CPU0_SA_DQS_DN<3>")
	)
	(segment
		(start 415.413444 -228.67874)
		(end 415.729928 -228.362256)
		(width 0.16002)
		(layer "In2.Cu")
		(net "M_I_CPU0_SA_DQS_DN<3>")
	)
	(segment
		(start 378.796296 -241.729006)
		(end 378.804678 -241.72418)
		(width 0.09525)
		(layer "In2.Cu")
		(net "M_I_CPU0_SA_DQS_DN<3>")
	)
	(segment
		(start 411.402276 -229.21214)
		(end 413.147764 -229.21214)
		(width 0.16002)
		(layer "In2.Cu")
		(net "M_I_CPU0_SA_DQS_DN<3>")
	)
	(segment
		(start 431.28311 -229.362)
		(end 431.55616 -229.63505)
		(width 0.16002)
		(layer "In2.Cu")
		(net "M_I_CPU0_SA_DQS_DN<3>")
	)
	(segment
		(start 393.494006 -241.677444)
		(end 393.862306 -241.309144)
		(width 0.09525)
		(layer "In2.Cu")
		(net "M_I_CPU0_SA_DQS_DN<3>")
	)
	(segment
		(start 427.959774 -228.936296)
		(end 428.568358 -229.54488)
		(width 0.16002)
		(layer "In2.Cu")
		(net "M_I_CPU0_SA_DQS_DN<3>")
	)
	(segment
		(start 414.047432 -229.51948)
		(end 414.888172 -228.67874)
		(width 0.16002)
		(layer "In2.Cu")
		(net "M_I_CPU0_SA_DQS_DN<3>")
	)
	(segment
		(start 421.591486 -229.51948)
		(end 422.432226 -228.67874)
		(width 0.16002)
		(layer "In2.Cu")
		(net "M_I_CPU0_SA_DQS_DN<3>")
	)
	(segment
		(start 395.21765 -240.298478)
		(end 395.603476 -240.298478)
		(width 0.09525)
		(layer "In2.Cu")
		(net "M_I_CPU0_SA_DQS_DN<3>")
	)
	(segment
		(start 386.685028 -241.72418)
		(end 386.69341 -241.729006)
		(width 0.09525)
		(layer "In2.Cu")
		(net "M_I_CPU0_SA_DQS_DN<3>")
	)
	(segment
		(start 422.432226 -228.67874)
		(end 422.957498 -228.67874)
		(width 0.16002)
		(layer "In2.Cu")
		(net "M_I_CPU0_SA_DQS_DN<3>")
	)
	(segment
		(start 429.368966 -229.54488)
		(end 429.551846 -229.362)
		(width 0.16002)
		(layer "In2.Cu")
		(net "M_I_CPU0_SA_DQS_DN<3>")
	)
	(segment
		(start 382.556258 -241.729006)
		(end 382.56464 -241.72418)
		(width 0.09525)
		(layer "In2.Cu")
		(net "M_I_CPU0_SA_DQS_DN<3>")
	)
	(segment
		(start 417.708588 -228.362256)
		(end 418.558472 -229.21214)
		(width 0.16002)
		(layer "In2.Cu")
		(net "M_I_CPU0_SA_DQS_DN<3>")
	)
	(segment
		(start 429.551846 -229.362)
		(end 431.28311 -229.362)
		(width 0.16002)
		(layer "In2.Cu")
		(net "M_I_CPU0_SA_DQS_DN<3>")
	)
	(segment
		(start 391.016236 -241.729006)
		(end 391.024618 -241.72418)
		(width 0.09525)
		(layer "In2.Cu")
		(net "M_I_CPU0_SA_DQS_DN<3>")
	)
	(segment
		(start 388.196328 -241.729006)
		(end 388.20471 -241.72418)
		(width 0.09525)
		(layer "In2.Cu")
		(net "M_I_CPU0_SA_DQS_DN<3>")
	)
	(segment
		(start 395.686026 -240.357406)
		(end 399.14195 -240.357406)
		(width 0.16002)
		(layer "In2.Cu")
		(net "M_I_CPU0_SA_DQS_DN<3>")
	)
	(segment
		(start 420.691818 -229.21214)
		(end 420.999158 -229.51948)
		(width 0.16002)
		(layer "In2.Cu")
		(net "M_I_CPU0_SA_DQS_DN<3>")
	)
	(segment
		(start 377.10491 -242.054126)
		(end 377.258834 -241.788696)
		(width 0.09525)
		(layer "In2.Cu")
		(net "M_I_CPU0_SA_DQS_DN<3>")
	)
	(segment
		(start 377.856242 -241.729006)
		(end 377.864624 -241.72418)
		(width 0.09525)
		(layer "In2.Cu")
		(net "M_I_CPU0_SA_DQS_DN<3>")
	)
	(segment
		(start 392.332972 -241.729006)
		(end 392.343386 -241.735102)
		(width 0.09525)
		(layer "In2.Cu")
		(net "M_I_CPU0_SA_DQS_DN<3>")
	)
	(segment
		(start 390.44499 -241.72418)
		(end 390.453372 -241.729006)
		(width 0.09525)
		(layer "In2.Cu")
		(net "M_I_CPU0_SA_DQS_DN<3>")
	)
	(segment
		(start 414.888172 -228.67874)
		(end 415.413444 -228.67874)
		(width 0.16002)
		(layer "In2.Cu")
		(net "M_I_CPU0_SA_DQS_DN<3>")
	)
	(segment
		(start 420.999158 -229.51948)
		(end 421.591486 -229.51948)
		(width 0.16002)
		(layer "In2.Cu")
		(net "M_I_CPU0_SA_DQS_DN<3>")
	)
	(segment
		(start 399.14195 -240.357406)
		(end 403.710394 -235.788962)
		(width 0.16002)
		(layer "In2.Cu")
		(net "M_I_CPU0_SA_DQS_DN<3>")
	)
	(segment
		(start 393.862306 -241.309144)
		(end 394.206984 -241.309144)
		(width 0.09525)
		(layer "In2.Cu")
		(net "M_I_CPU0_SA_DQS_DN<3>")
	)
	(segment
		(start 413.455104 -229.51948)
		(end 414.047432 -229.51948)
		(width 0.16002)
		(layer "In2.Cu")
		(net "M_I_CPU0_SA_DQS_DN<3>")
	)
	(segment
		(start 409.855416 -231.025192)
		(end 409.855416 -230.759)
		(width 0.16002)
		(layer "In2.Cu")
		(net "M_I_CPU0_SA_DQS_DN<3>")
	)
	(segment
		(start 425.300394 -228.362256)
		(end 425.874434 -228.936296)
		(width 0.16002)
		(layer "In2.Cu")
		(net "M_I_CPU0_SA_DQS_DN<3>")
	)
	(segment
		(start 381.044958 -241.72418)
		(end 381.05334 -241.729006)
		(width 0.09525)
		(layer "In2.Cu")
		(net "M_I_CPU0_SA_DQS_DN<3>")
	)
	(segment
		(start 403.710394 -235.788962)
		(end 405.091646 -235.788962)
		(width 0.16002)
		(layer "In2.Cu")
		(net "M_I_CPU0_SA_DQS_DN<3>")
	)
	(segment
		(start 383.496312 -241.729006)
		(end 383.504694 -241.72418)
		(width 0.09525)
		(layer "In2.Cu")
		(net "M_I_CPU0_SA_DQS_DN<3>")
	)
	(segment
		(start 394.206984 -241.309144)
		(end 395.21765 -240.298478)
		(width 0.09525)
		(layer "In2.Cu")
		(net "M_I_CPU0_SA_DQS_DN<3>")
	)
	(segment
		(start 395.603476 -240.298478)
		(end 395.662404 -240.357406)
		(width 0.09525)
		(layer "In2.Cu")
		(net "M_I_CPU0_SA_DQS_DN<3>")
	)
	(segment
		(start 423.273982 -228.362256)
		(end 425.300394 -228.362256)
		(width 0.16002)
		(layer "In2.Cu")
		(net "M_I_CPU0_SA_DQS_DN<3>")
	)
	(segment
		(start 387.256274 -241.729006)
		(end 387.264656 -241.72418)
		(width 0.09525)
		(layer "In2.Cu")
		(net "M_I_CPU0_SA_DQS_DN<3>")
	)
	(segment
		(start 393.084812 -241.677444)
		(end 393.494006 -241.677444)
		(width 0.09525)
		(layer "In2.Cu")
		(net "M_I_CPU0_SA_DQS_DN<3>")
	)
	(segment
		(start 413.147764 -229.21214)
		(end 413.455104 -229.51948)
		(width 0.16002)
		(layer "In2.Cu")
		(net "M_I_CPU0_SA_DQS_DN<3>")
	)
	(segment
		(start 428.568358 -229.54488)
		(end 429.368966 -229.54488)
		(width 0.16002)
		(layer "In2.Cu")
		(net "M_I_CPU0_SA_DQS_DN<3>")
	)
	(segment
		(start 425.874434 -228.936296)
		(end 427.959774 -228.936296)
		(width 0.16002)
		(layer "In2.Cu")
		(net "M_I_CPU0_SA_DQS_DN<3>")
	)
	(arc
		(start 384.813302 -241.729006)
		(mid 385.094734 -241.804761)
		(end 385.376166 -241.729006)
		(width 0.09525)
		(layer "In2.Cu")
		(net "M_I_CPU0_SA_DQS_DN<3>")
	)
	(arc
		(start 383.873502 -241.729006)
		(mid 384.154934 -241.804761)
		(end 384.436366 -241.729006)
		(width 0.09525)
		(layer "In2.Cu")
		(net "M_I_CPU0_SA_DQS_DN<3>")
	)
	(arc
		(start 377.359672 -241.762026)
		(mid 377.36954 -241.766057)
		(end 377.379484 -241.7699)
		(width 0.09525)
		(layer "In2.Cu")
		(net "M_I_CPU0_SA_DQS_DN<3>")
	)
	(arc
		(start 378.804678 -241.72418)
		(mid 378.98971 -241.678266)
		(end 379.173486 -241.729006)
		(width 0.09525)
		(layer "In2.Cu")
		(net "M_I_CPU0_SA_DQS_DN<3>")
	)
	(arc
		(start 383.504694 -241.72418)
		(mid 383.689726 -241.678266)
		(end 383.873502 -241.729006)
		(width 0.09525)
		(layer "In2.Cu")
		(net "M_I_CPU0_SA_DQS_DN<3>")
	)
	(arc
		(start 379.73635 -241.729006)
		(mid 379.924818 -241.678329)
		(end 380.113286 -241.729006)
		(width 0.09525)
		(layer "In2.Cu")
		(net "M_I_CPU0_SA_DQS_DN<3>")
	)
	(arc
		(start 388.573518 -241.729006)
		(mid 388.85495 -241.804761)
		(end 389.136382 -241.729006)
		(width 0.09525)
		(layer "In2.Cu")
		(net "M_I_CPU0_SA_DQS_DN<3>")
	)
	(arc
		(start 381.05334 -241.729006)
		(mid 381.334772 -241.804761)
		(end 381.616204 -241.729006)
		(width 0.09525)
		(layer "In2.Cu")
		(net "M_I_CPU0_SA_DQS_DN<3>")
	)
	(arc
		(start 388.20471 -241.72418)
		(mid 388.389742 -241.678266)
		(end 388.573518 -241.729006)
		(width 0.09525)
		(layer "In2.Cu")
		(net "M_I_CPU0_SA_DQS_DN<3>")
	)
	(arc
		(start 391.393426 -241.729006)
		(mid 391.668715 -241.804727)
		(end 391.945622 -241.735102)
		(width 0.09525)
		(layer "In2.Cu")
		(net "M_I_CPU0_SA_DQS_DN<3>")
	)
	(arc
		(start 386.69341 -241.729006)
		(mid 386.974842 -241.804761)
		(end 387.256274 -241.729006)
		(width 0.09525)
		(layer "In2.Cu")
		(net "M_I_CPU0_SA_DQS_DN<3>")
	)
	(arc
		(start 381.993394 -241.729006)
		(mid 382.274826 -241.804761)
		(end 382.556258 -241.729006)
		(width 0.09525)
		(layer "In2.Cu")
		(net "M_I_CPU0_SA_DQS_DN<3>")
	)
	(arc
		(start 390.453372 -241.729006)
		(mid 390.734804 -241.804761)
		(end 391.016236 -241.729006)
		(width 0.09525)
		(layer "In2.Cu")
		(net "M_I_CPU0_SA_DQS_DN<3>")
	)
	(arc
		(start 387.633464 -241.729006)
		(mid 387.914896 -241.804761)
		(end 388.196328 -241.729006)
		(width 0.09525)
		(layer "In2.Cu")
		(net "M_I_CPU0_SA_DQS_DN<3>")
	)
	(arc
		(start 385.753356 -241.729006)
		(mid 386.034788 -241.804761)
		(end 386.31622 -241.729006)
		(width 0.09525)
		(layer "In2.Cu")
		(net "M_I_CPU0_SA_DQS_DN<3>")
	)
	(arc
		(start 386.31622 -241.729006)
		(mid 386.499995 -241.678234)
		(end 386.685028 -241.72418)
		(width 0.09525)
		(layer "In2.Cu")
		(net "M_I_CPU0_SA_DQS_DN<3>")
	)
	(arc
		(start 392.343386 -241.735102)
		(mid 392.620548 -241.804902)
		(end 392.89609 -241.729006)
		(width 0.09525)
		(layer "In2.Cu")
		(net "M_I_CPU0_SA_DQS_DN<3>")
	)
	(arc
		(start 380.67615 -241.729006)
		(mid 380.859925 -241.678234)
		(end 381.044958 -241.72418)
		(width 0.09525)
		(layer "In2.Cu")
		(net "M_I_CPU0_SA_DQS_DN<3>")
	)
	(arc
		(start 378.233432 -241.729006)
		(mid 378.514864 -241.804761)
		(end 378.796296 -241.729006)
		(width 0.09525)
		(layer "In2.Cu")
		(net "M_I_CPU0_SA_DQS_DN<3>")
	)
	(arc
		(start 384.436366 -241.729006)
		(mid 384.624834 -241.678329)
		(end 384.813302 -241.729006)
		(width 0.09525)
		(layer "In2.Cu")
		(net "M_I_CPU0_SA_DQS_DN<3>")
	)
	(arc
		(start 382.933448 -241.729006)
		(mid 383.21488 -241.804761)
		(end 383.496312 -241.729006)
		(width 0.09525)
		(layer "In2.Cu")
		(net "M_I_CPU0_SA_DQS_DN<3>")
	)
	(arc
		(start 379.173486 -241.729006)
		(mid 379.454918 -241.804761)
		(end 379.73635 -241.729006)
		(width 0.09525)
		(layer "In2.Cu")
		(net "M_I_CPU0_SA_DQS_DN<3>")
	)
	(arc
		(start 381.616204 -241.729006)
		(mid 381.799979 -241.678234)
		(end 381.985012 -241.72418)
		(width 0.09525)
		(layer "In2.Cu")
		(net "M_I_CPU0_SA_DQS_DN<3>")
	)
	(arc
		(start 390.076182 -241.729006)
		(mid 390.259957 -241.678234)
		(end 390.44499 -241.72418)
		(width 0.09525)
		(layer "In2.Cu")
		(net "M_I_CPU0_SA_DQS_DN<3>")
	)
	(arc
		(start 385.376166 -241.729006)
		(mid 385.559941 -241.678234)
		(end 385.744974 -241.72418)
		(width 0.09525)
		(layer "In2.Cu")
		(net "M_I_CPU0_SA_DQS_DN<3>")
	)
	(arc
		(start 377.864624 -241.72418)
		(mid 378.049656 -241.678266)
		(end 378.233432 -241.729006)
		(width 0.09525)
		(layer "In2.Cu")
		(net "M_I_CPU0_SA_DQS_DN<3>")
	)
	(arc
		(start 382.56464 -241.72418)
		(mid 382.749672 -241.678266)
		(end 382.933448 -241.729006)
		(width 0.09525)
		(layer "In2.Cu")
		(net "M_I_CPU0_SA_DQS_DN<3>")
	)
	(arc
		(start 387.264656 -241.72418)
		(mid 387.449688 -241.678266)
		(end 387.633464 -241.729006)
		(width 0.09525)
		(layer "In2.Cu")
		(net "M_I_CPU0_SA_DQS_DN<3>")
	)
	(arc
		(start 380.113286 -241.729006)
		(mid 380.394718 -241.804761)
		(end 380.67615 -241.729006)
		(width 0.09525)
		(layer "In2.Cu")
		(net "M_I_CPU0_SA_DQS_DN<3>")
	)
	(arc
		(start 391.024618 -241.72418)
		(mid 391.20965 -241.678266)
		(end 391.393426 -241.729006)
		(width 0.09525)
		(layer "In2.Cu")
		(net "M_I_CPU0_SA_DQS_DN<3>")
	)
	(arc
		(start 377.379484 -241.7699)
		(mid 377.622448 -241.802887)
		(end 377.856242 -241.729006)
		(width 0.09525)
		(layer "In2.Cu")
		(net "M_I_CPU0_SA_DQS_DN<3>")
	)
	(arc
		(start 389.513318 -241.729006)
		(mid 389.79475 -241.804761)
		(end 390.076182 -241.729006)
		(width 0.09525)
		(layer "In2.Cu")
		(net "M_I_CPU0_SA_DQS_DN<3>")
	)
	(arc
		(start 392.89609 -241.729006)
		(mid 392.987036 -241.690705)
		(end 393.084812 -241.677444)
		(width 0.09525)
		(layer "In2.Cu")
		(net "M_I_CPU0_SA_DQS_DN<3>")
	)
	(arc
		(start 389.136382 -241.729006)
		(mid 389.32485 -241.678329)
		(end 389.513318 -241.729006)
		(width 0.09525)
		(layer "In2.Cu")
		(net "M_I_CPU0_SA_DQS_DN<3>")
	)
	(arc
		(start 391.956036 -241.729006)
		(mid 392.144504 -241.678329)
		(end 392.332972 -241.729006)
		(width 0.09525)
		(layer "In2.Cu")
		(net "M_I_CPU0_SA_DQS_DN<3>")
	)
	(segment
		(start 376.638058 -237.460028)
		(end 377.10491 -237.19409)
		(width 0.12954)
		(layer "F.Cu")
		(net "M_I_CPU0_SA_DQS_DN<2>")
	)
	(segment
		(start 395.84249 -234.415838)
		(end 395.859254 -234.399074)
		(width 0.09525)
		(layer "In2.Cu")
		(net "M_I_CPU0_SA_DQS_DN<2>")
	)
	(segment
		(start 383.496312 -236.86897)
		(end 383.504694 -236.864144)
		(width 0.09525)
		(layer "In2.Cu")
		(net "M_I_CPU0_SA_DQS_DN<2>")
	)
	(segment
		(start 388.196328 -236.86897)
		(end 388.20471 -236.864144)
		(width 0.09525)
		(layer "In2.Cu")
		(net "M_I_CPU0_SA_DQS_DN<2>")
	)
	(segment
		(start 393.624562 -236.21492)
		(end 394.217906 -235.621576)
		(width 0.09525)
		(layer "In2.Cu")
		(net "M_I_CPU0_SA_DQS_DN<2>")
	)
	(segment
		(start 385.744974 -236.864144)
		(end 385.753356 -236.86897)
		(width 0.09525)
		(layer "In2.Cu")
		(net "M_I_CPU0_SA_DQS_DN<2>")
	)
	(segment
		(start 429.838358 -220.194886)
		(end 430.021238 -220.012006)
		(width 0.16002)
		(layer "In2.Cu")
		(net "M_I_CPU0_SA_DQS_DN<2>")
	)
	(segment
		(start 425.874434 -219.586302)
		(end 427.959774 -219.586302)
		(width 0.16002)
		(layer "In2.Cu")
		(net "M_I_CPU0_SA_DQS_DN<2>")
	)
	(segment
		(start 420.691818 -219.862146)
		(end 420.999158 -220.169486)
		(width 0.16002)
		(layer "In2.Cu")
		(net "M_I_CPU0_SA_DQS_DN<2>")
	)
	(segment
		(start 377.258834 -236.92866)
		(end 377.359672 -236.90199)
		(width 0.09525)
		(layer "In2.Cu")
		(net "M_I_CPU0_SA_DQS_DN<2>")
	)
	(segment
		(start 395.759432 -234.415838)
		(end 395.84249 -234.415838)
		(width 0.09525)
		(layer "In2.Cu")
		(net "M_I_CPU0_SA_DQS_DN<2>")
	)
	(segment
		(start 395.859254 -234.399074)
		(end 410.396182 -219.862146)
		(width 0.16002)
		(layer "In2.Cu")
		(net "M_I_CPU0_SA_DQS_DN<2>")
	)
	(segment
		(start 428.568358 -220.194886)
		(end 429.838358 -220.194886)
		(width 0.16002)
		(layer "In2.Cu")
		(net "M_I_CPU0_SA_DQS_DN<2>")
	)
	(segment
		(start 431.28311 -220.012006)
		(end 431.55616 -220.285056)
		(width 0.16002)
		(layer "In2.Cu")
		(net "M_I_CPU0_SA_DQS_DN<2>")
	)
	(segment
		(start 394.217906 -235.621576)
		(end 394.217906 -234.892596)
		(width 0.09525)
		(layer "In2.Cu")
		(net "M_I_CPU0_SA_DQS_DN<2>")
	)
	(segment
		(start 391.945622 -236.875066)
		(end 391.956036 -236.86897)
		(width 0.09525)
		(layer "In2.Cu")
		(net "M_I_CPU0_SA_DQS_DN<2>")
	)
	(segment
		(start 395.544802 -234.630468)
		(end 395.759432 -234.415838)
		(width 0.09525)
		(layer "In2.Cu")
		(net "M_I_CPU0_SA_DQS_DN<2>")
	)
	(segment
		(start 410.396182 -219.862146)
		(end 413.147764 -219.862146)
		(width 0.16002)
		(layer "In2.Cu")
		(net "M_I_CPU0_SA_DQS_DN<2>")
	)
	(segment
		(start 422.957498 -219.328746)
		(end 423.273982 -219.012262)
		(width 0.16002)
		(layer "In2.Cu")
		(net "M_I_CPU0_SA_DQS_DN<2>")
	)
	(segment
		(start 425.300394 -219.012262)
		(end 425.874434 -219.586302)
		(width 0.16002)
		(layer "In2.Cu")
		(net "M_I_CPU0_SA_DQS_DN<2>")
	)
	(segment
		(start 422.432226 -219.328746)
		(end 422.957498 -219.328746)
		(width 0.16002)
		(layer "In2.Cu")
		(net "M_I_CPU0_SA_DQS_DN<2>")
	)
	(segment
		(start 382.556258 -236.86897)
		(end 382.56464 -236.864144)
		(width 0.09525)
		(layer "In2.Cu")
		(net "M_I_CPU0_SA_DQS_DN<2>")
	)
	(segment
		(start 430.021238 -220.012006)
		(end 431.28311 -220.012006)
		(width 0.16002)
		(layer "In2.Cu")
		(net "M_I_CPU0_SA_DQS_DN<2>")
	)
	(segment
		(start 421.591486 -220.169486)
		(end 422.432226 -219.328746)
		(width 0.16002)
		(layer "In2.Cu")
		(net "M_I_CPU0_SA_DQS_DN<2>")
	)
	(segment
		(start 394.217906 -234.892596)
		(end 394.480034 -234.630468)
		(width 0.09525)
		(layer "In2.Cu")
		(net "M_I_CPU0_SA_DQS_DN<2>")
	)
	(segment
		(start 377.856242 -236.86897)
		(end 377.864624 -236.864144)
		(width 0.09525)
		(layer "In2.Cu")
		(net "M_I_CPU0_SA_DQS_DN<2>")
	)
	(segment
		(start 413.147764 -219.862146)
		(end 413.455104 -220.169486)
		(width 0.16002)
		(layer "In2.Cu")
		(net "M_I_CPU0_SA_DQS_DN<2>")
	)
	(segment
		(start 392.071098 -236.780324)
		(end 392.636502 -236.21492)
		(width 0.09525)
		(layer "In2.Cu")
		(net "M_I_CPU0_SA_DQS_DN<2>")
	)
	(segment
		(start 415.413444 -219.328746)
		(end 415.729928 -219.012262)
		(width 0.16002)
		(layer "In2.Cu")
		(net "M_I_CPU0_SA_DQS_DN<2>")
	)
	(segment
		(start 390.44499 -236.864144)
		(end 390.453372 -236.86897)
		(width 0.09525)
		(layer "In2.Cu")
		(net "M_I_CPU0_SA_DQS_DN<2>")
	)
	(segment
		(start 392.636502 -236.21492)
		(end 393.624562 -236.21492)
		(width 0.09525)
		(layer "In2.Cu")
		(net "M_I_CPU0_SA_DQS_DN<2>")
	)
	(segment
		(start 413.455104 -220.169486)
		(end 414.047432 -220.169486)
		(width 0.16002)
		(layer "In2.Cu")
		(net "M_I_CPU0_SA_DQS_DN<2>")
	)
	(segment
		(start 418.558472 -219.862146)
		(end 420.691818 -219.862146)
		(width 0.16002)
		(layer "In2.Cu")
		(net "M_I_CPU0_SA_DQS_DN<2>")
	)
	(segment
		(start 391.016236 -236.86897)
		(end 391.024618 -236.864144)
		(width 0.09525)
		(layer "In2.Cu")
		(net "M_I_CPU0_SA_DQS_DN<2>")
	)
	(segment
		(start 417.708588 -219.012262)
		(end 418.558472 -219.862146)
		(width 0.16002)
		(layer "In2.Cu")
		(net "M_I_CPU0_SA_DQS_DN<2>")
	)
	(segment
		(start 381.985012 -236.864144)
		(end 381.993394 -236.86897)
		(width 0.09525)
		(layer "In2.Cu")
		(net "M_I_CPU0_SA_DQS_DN<2>")
	)
	(segment
		(start 387.256274 -236.86897)
		(end 387.264656 -236.864144)
		(width 0.09525)
		(layer "In2.Cu")
		(net "M_I_CPU0_SA_DQS_DN<2>")
	)
	(segment
		(start 378.796296 -236.86897)
		(end 378.804678 -236.864144)
		(width 0.09525)
		(layer "In2.Cu")
		(net "M_I_CPU0_SA_DQS_DN<2>")
	)
	(segment
		(start 377.10491 -237.19409)
		(end 377.258834 -236.92866)
		(width 0.09525)
		(layer "In2.Cu")
		(net "M_I_CPU0_SA_DQS_DN<2>")
	)
	(segment
		(start 381.044958 -236.864144)
		(end 381.05334 -236.86897)
		(width 0.09525)
		(layer "In2.Cu")
		(net "M_I_CPU0_SA_DQS_DN<2>")
	)
	(segment
		(start 394.480034 -234.630468)
		(end 395.544802 -234.630468)
		(width 0.09525)
		(layer "In2.Cu")
		(net "M_I_CPU0_SA_DQS_DN<2>")
	)
	(segment
		(start 414.047432 -220.169486)
		(end 414.888172 -219.328746)
		(width 0.16002)
		(layer "In2.Cu")
		(net "M_I_CPU0_SA_DQS_DN<2>")
	)
	(segment
		(start 420.999158 -220.169486)
		(end 421.591486 -220.169486)
		(width 0.16002)
		(layer "In2.Cu")
		(net "M_I_CPU0_SA_DQS_DN<2>")
	)
	(segment
		(start 427.959774 -219.586302)
		(end 428.568358 -220.194886)
		(width 0.16002)
		(layer "In2.Cu")
		(net "M_I_CPU0_SA_DQS_DN<2>")
	)
	(segment
		(start 415.729928 -219.012262)
		(end 417.708588 -219.012262)
		(width 0.16002)
		(layer "In2.Cu")
		(net "M_I_CPU0_SA_DQS_DN<2>")
	)
	(segment
		(start 423.273982 -219.012262)
		(end 425.300394 -219.012262)
		(width 0.16002)
		(layer "In2.Cu")
		(net "M_I_CPU0_SA_DQS_DN<2>")
	)
	(segment
		(start 414.888172 -219.328746)
		(end 415.413444 -219.328746)
		(width 0.16002)
		(layer "In2.Cu")
		(net "M_I_CPU0_SA_DQS_DN<2>")
	)
	(segment
		(start 386.685028 -236.864144)
		(end 386.69341 -236.86897)
		(width 0.09525)
		(layer "In2.Cu")
		(net "M_I_CPU0_SA_DQS_DN<2>")
	)
	(arc
		(start 389.513318 -236.86897)
		(mid 389.79475 -236.944725)
		(end 390.076182 -236.86897)
		(width 0.09525)
		(layer "In2.Cu")
		(net "M_I_CPU0_SA_DQS_DN<2>")
	)
	(arc
		(start 384.436366 -236.86897)
		(mid 384.624834 -236.818293)
		(end 384.813302 -236.86897)
		(width 0.09525)
		(layer "In2.Cu")
		(net "M_I_CPU0_SA_DQS_DN<2>")
	)
	(arc
		(start 390.453372 -236.86897)
		(mid 390.734804 -236.944725)
		(end 391.016236 -236.86897)
		(width 0.09525)
		(layer "In2.Cu")
		(net "M_I_CPU0_SA_DQS_DN<2>")
	)
	(arc
		(start 377.359672 -236.90199)
		(mid 377.36954 -236.906021)
		(end 377.379484 -236.909864)
		(width 0.09525)
		(layer "In2.Cu")
		(net "M_I_CPU0_SA_DQS_DN<2>")
	)
	(arc
		(start 390.076182 -236.86897)
		(mid 390.259957 -236.818198)
		(end 390.44499 -236.864144)
		(width 0.09525)
		(layer "In2.Cu")
		(net "M_I_CPU0_SA_DQS_DN<2>")
	)
	(arc
		(start 381.616204 -236.86897)
		(mid 381.799979 -236.818198)
		(end 381.985012 -236.864144)
		(width 0.09525)
		(layer "In2.Cu")
		(net "M_I_CPU0_SA_DQS_DN<2>")
	)
	(arc
		(start 377.864624 -236.864144)
		(mid 378.049656 -236.81823)
		(end 378.233432 -236.86897)
		(width 0.09525)
		(layer "In2.Cu")
		(net "M_I_CPU0_SA_DQS_DN<2>")
	)
	(arc
		(start 382.56464 -236.864144)
		(mid 382.749672 -236.81823)
		(end 382.933448 -236.86897)
		(width 0.09525)
		(layer "In2.Cu")
		(net "M_I_CPU0_SA_DQS_DN<2>")
	)
	(arc
		(start 385.753356 -236.86897)
		(mid 386.034788 -236.944725)
		(end 386.31622 -236.86897)
		(width 0.09525)
		(layer "In2.Cu")
		(net "M_I_CPU0_SA_DQS_DN<2>")
	)
	(arc
		(start 383.504694 -236.864144)
		(mid 383.689726 -236.81823)
		(end 383.873502 -236.86897)
		(width 0.09525)
		(layer "In2.Cu")
		(net "M_I_CPU0_SA_DQS_DN<2>")
	)
	(arc
		(start 381.05334 -236.86897)
		(mid 381.334772 -236.944725)
		(end 381.616204 -236.86897)
		(width 0.09525)
		(layer "In2.Cu")
		(net "M_I_CPU0_SA_DQS_DN<2>")
	)
	(arc
		(start 387.633464 -236.86897)
		(mid 387.914896 -236.944725)
		(end 388.196328 -236.86897)
		(width 0.09525)
		(layer "In2.Cu")
		(net "M_I_CPU0_SA_DQS_DN<2>")
	)
	(arc
		(start 383.873502 -236.86897)
		(mid 384.154934 -236.944725)
		(end 384.436366 -236.86897)
		(width 0.09525)
		(layer "In2.Cu")
		(net "M_I_CPU0_SA_DQS_DN<2>")
	)
	(arc
		(start 388.20471 -236.864144)
		(mid 388.389742 -236.81823)
		(end 388.573518 -236.86897)
		(width 0.09525)
		(layer "In2.Cu")
		(net "M_I_CPU0_SA_DQS_DN<2>")
	)
	(arc
		(start 380.113286 -236.86897)
		(mid 380.394718 -236.944725)
		(end 380.67615 -236.86897)
		(width 0.09525)
		(layer "In2.Cu")
		(net "M_I_CPU0_SA_DQS_DN<2>")
	)
	(arc
		(start 391.024618 -236.864144)
		(mid 391.20965 -236.81823)
		(end 391.393426 -236.86897)
		(width 0.09525)
		(layer "In2.Cu")
		(net "M_I_CPU0_SA_DQS_DN<2>")
	)
	(arc
		(start 379.73635 -236.86897)
		(mid 379.924818 -236.818293)
		(end 380.113286 -236.86897)
		(width 0.09525)
		(layer "In2.Cu")
		(net "M_I_CPU0_SA_DQS_DN<2>")
	)
	(arc
		(start 382.933448 -236.86897)
		(mid 383.21488 -236.944725)
		(end 383.496312 -236.86897)
		(width 0.09525)
		(layer "In2.Cu")
		(net "M_I_CPU0_SA_DQS_DN<2>")
	)
	(arc
		(start 388.573518 -236.86897)
		(mid 388.85495 -236.944725)
		(end 389.136382 -236.86897)
		(width 0.09525)
		(layer "In2.Cu")
		(net "M_I_CPU0_SA_DQS_DN<2>")
	)
	(arc
		(start 384.813302 -236.86897)
		(mid 385.094734 -236.944725)
		(end 385.376166 -236.86897)
		(width 0.09525)
		(layer "In2.Cu")
		(net "M_I_CPU0_SA_DQS_DN<2>")
	)
	(arc
		(start 391.956036 -236.86897)
		(mid 392.016451 -236.82839)
		(end 392.071098 -236.780324)
		(width 0.09525)
		(layer "In2.Cu")
		(net "M_I_CPU0_SA_DQS_DN<2>")
	)
	(arc
		(start 378.804678 -236.864144)
		(mid 378.98971 -236.81823)
		(end 379.173486 -236.86897)
		(width 0.09525)
		(layer "In2.Cu")
		(net "M_I_CPU0_SA_DQS_DN<2>")
	)
	(arc
		(start 386.69341 -236.86897)
		(mid 386.974842 -236.944725)
		(end 387.256274 -236.86897)
		(width 0.09525)
		(layer "In2.Cu")
		(net "M_I_CPU0_SA_DQS_DN<2>")
	)
	(arc
		(start 387.264656 -236.864144)
		(mid 387.449688 -236.81823)
		(end 387.633464 -236.86897)
		(width 0.09525)
		(layer "In2.Cu")
		(net "M_I_CPU0_SA_DQS_DN<2>")
	)
	(arc
		(start 389.136382 -236.86897)
		(mid 389.32485 -236.818293)
		(end 389.513318 -236.86897)
		(width 0.09525)
		(layer "In2.Cu")
		(net "M_I_CPU0_SA_DQS_DN<2>")
	)
	(arc
		(start 380.67615 -236.86897)
		(mid 380.859925 -236.818198)
		(end 381.044958 -236.864144)
		(width 0.09525)
		(layer "In2.Cu")
		(net "M_I_CPU0_SA_DQS_DN<2>")
	)
	(arc
		(start 378.233432 -236.86897)
		(mid 378.514864 -236.944725)
		(end 378.796296 -236.86897)
		(width 0.09525)
		(layer "In2.Cu")
		(net "M_I_CPU0_SA_DQS_DN<2>")
	)
	(arc
		(start 377.379484 -236.909864)
		(mid 377.622448 -236.942851)
		(end 377.856242 -236.86897)
		(width 0.09525)
		(layer "In2.Cu")
		(net "M_I_CPU0_SA_DQS_DN<2>")
	)
	(arc
		(start 379.173486 -236.86897)
		(mid 379.454918 -236.944725)
		(end 379.73635 -236.86897)
		(width 0.09525)
		(layer "In2.Cu")
		(net "M_I_CPU0_SA_DQS_DN<2>")
	)
	(arc
		(start 386.31622 -236.86897)
		(mid 386.499995 -236.818198)
		(end 386.685028 -236.864144)
		(width 0.09525)
		(layer "In2.Cu")
		(net "M_I_CPU0_SA_DQS_DN<2>")
	)
	(arc
		(start 385.376166 -236.86897)
		(mid 385.559941 -236.818198)
		(end 385.744974 -236.864144)
		(width 0.09525)
		(layer "In2.Cu")
		(net "M_I_CPU0_SA_DQS_DN<2>")
	)
	(arc
		(start 391.393426 -236.86897)
		(mid 391.668715 -236.944691)
		(end 391.945622 -236.875066)
		(width 0.09525)
		(layer "In2.Cu")
		(net "M_I_CPU0_SA_DQS_DN<2>")
	)
	(arc
		(start 381.993394 -236.86897)
		(mid 382.274826 -236.944725)
		(end 382.556258 -236.86897)
		(width 0.09525)
		(layer "In2.Cu")
		(net "M_I_CPU0_SA_DQS_DN<2>")
	)
	(segment
		(start 376.638058 -232.599992)
		(end 377.10491 -232.334054)
		(width 0.12954)
		(layer "F.Cu")
		(net "M_I_CPU0_SA_DQS_DN<1>")
	)
	(segment
		(start 423.273982 -209.662268)
		(end 425.328334 -209.662268)
		(width 0.16002)
		(layer "In2.Cu")
		(net "M_I_CPU0_SA_DQS_DN<1>")
	)
	(segment
		(start 387.256274 -232.008934)
		(end 387.264656 -232.004108)
		(width 0.09525)
		(layer "In2.Cu")
		(net "M_I_CPU0_SA_DQS_DN<1>")
	)
	(segment
		(start 425.328334 -209.662268)
		(end 425.902374 -210.236308)
		(width 0.16002)
		(layer "In2.Cu")
		(net "M_I_CPU0_SA_DQS_DN<1>")
	)
	(segment
		(start 391.95629 -230.389176)
		(end 391.99185 -230.368602)
		(width 0.09525)
		(layer "In2.Cu")
		(net "M_I_CPU0_SA_DQS_DN<1>")
	)
	(segment
		(start 394.094208 -226.933506)
		(end 394.094208 -226.534726)
		(width 0.09525)
		(layer "In2.Cu")
		(net "M_I_CPU0_SA_DQS_DN<1>")
	)
	(segment
		(start 430.021238 -210.662012)
		(end 431.28311 -210.662012)
		(width 0.16002)
		(layer "In2.Cu")
		(net "M_I_CPU0_SA_DQS_DN<1>")
	)
	(segment
		(start 383.496312 -232.008934)
		(end 383.504694 -232.004108)
		(width 0.09525)
		(layer "In2.Cu")
		(net "M_I_CPU0_SA_DQS_DN<1>")
	)
	(segment
		(start 422.957498 -209.978752)
		(end 423.273982 -209.662268)
		(width 0.16002)
		(layer "In2.Cu")
		(net "M_I_CPU0_SA_DQS_DN<1>")
	)
	(segment
		(start 394.094208 -226.534726)
		(end 394.340842 -226.288092)
		(width 0.09525)
		(layer "In2.Cu")
		(net "M_I_CPU0_SA_DQS_DN<1>")
	)
	(segment
		(start 395.606778 -225.404172)
		(end 395.606778 -224.890584)
		(width 0.16002)
		(layer "In2.Cu")
		(net "M_I_CPU0_SA_DQS_DN<1>")
	)
	(segment
		(start 417.708588 -209.662268)
		(end 418.558472 -210.512152)
		(width 0.16002)
		(layer "In2.Cu")
		(net "M_I_CPU0_SA_DQS_DN<1>")
	)
	(segment
		(start 391.45464 -231.217216)
		(end 391.486136 -231.198928)
		(width 0.09525)
		(layer "In2.Cu")
		(net "M_I_CPU0_SA_DQS_DN<1>")
	)
	(segment
		(start 415.729928 -209.662268)
		(end 417.708588 -209.662268)
		(width 0.16002)
		(layer "In2.Cu")
		(net "M_I_CPU0_SA_DQS_DN<1>")
	)
	(segment
		(start 392.42619 -229.578916)
		(end 392.466576 -229.555294)
		(width 0.09525)
		(layer "In2.Cu")
		(net "M_I_CPU0_SA_DQS_DN<1>")
	)
	(segment
		(start 393.334748 -227.977446)
		(end 393.366244 -227.959158)
		(width 0.09525)
		(layer "In2.Cu")
		(net "M_I_CPU0_SA_DQS_DN<1>")
	)
	(segment
		(start 420.691818 -210.512152)
		(end 420.999158 -210.819492)
		(width 0.16002)
		(layer "In2.Cu")
		(net "M_I_CPU0_SA_DQS_DN<1>")
	)
	(segment
		(start 413.455104 -210.819492)
		(end 414.047432 -210.819492)
		(width 0.16002)
		(layer "In2.Cu")
		(net "M_I_CPU0_SA_DQS_DN<1>")
	)
	(segment
		(start 378.796296 -232.008934)
		(end 378.804678 -232.004108)
		(width 0.09525)
		(layer "In2.Cu")
		(net "M_I_CPU0_SA_DQS_DN<1>")
	)
	(segment
		(start 393.366244 -227.959158)
		(end 393.398248 -227.940616)
		(width 0.09525)
		(layer "In2.Cu")
		(net "M_I_CPU0_SA_DQS_DN<1>")
	)
	(segment
		(start 382.556258 -232.008934)
		(end 382.56464 -232.004108)
		(width 0.09525)
		(layer "In2.Cu")
		(net "M_I_CPU0_SA_DQS_DN<1>")
	)
	(segment
		(start 403.93747 -216.559892)
		(end 403.93747 -215.068404)
		(width 0.16002)
		(layer "In2.Cu")
		(net "M_I_CPU0_SA_DQS_DN<1>")
	)
	(segment
		(start 420.999158 -210.819492)
		(end 421.591486 -210.819492)
		(width 0.16002)
		(layer "In2.Cu")
		(net "M_I_CPU0_SA_DQS_DN<1>")
	)
	(segment
		(start 395.00556 -225.922586)
		(end 395.088364 -225.92284)
		(width 0.09525)
		(layer "In2.Cu")
		(net "M_I_CPU0_SA_DQS_DN<1>")
	)
	(segment
		(start 427.959774 -210.236308)
		(end 428.568358 -210.844892)
		(width 0.16002)
		(layer "In2.Cu")
		(net "M_I_CPU0_SA_DQS_DN<1>")
	)
	(segment
		(start 394.340842 -226.288092)
		(end 394.640054 -226.288092)
		(width 0.09525)
		(layer "In2.Cu")
		(net "M_I_CPU0_SA_DQS_DN<1>")
	)
	(segment
		(start 393.802362 -227.168456)
		(end 393.939014 -227.088954)
		(width 0.09525)
		(layer "In2.Cu")
		(net "M_I_CPU0_SA_DQS_DN<1>")
	)
	(segment
		(start 391.923778 -230.407972)
		(end 391.95629 -230.389176)
		(width 0.09525)
		(layer "In2.Cu")
		(net "M_I_CPU0_SA_DQS_DN<1>")
	)
	(segment
		(start 415.413444 -209.978752)
		(end 415.729928 -209.662268)
		(width 0.16002)
		(layer "In2.Cu")
		(net "M_I_CPU0_SA_DQS_DN<1>")
	)
	(segment
		(start 393.939014 -227.088954)
		(end 394.094208 -226.933506)
		(width 0.09525)
		(layer "In2.Cu")
		(net "M_I_CPU0_SA_DQS_DN<1>")
	)
	(segment
		(start 408.493722 -210.512152)
		(end 413.147764 -210.512152)
		(width 0.16002)
		(layer "In2.Cu")
		(net "M_I_CPU0_SA_DQS_DN<1>")
	)
	(segment
		(start 403.93747 -215.068404)
		(end 408.493722 -210.512152)
		(width 0.16002)
		(layer "In2.Cu")
		(net "M_I_CPU0_SA_DQS_DN<1>")
	)
	(segment
		(start 428.568358 -210.844892)
		(end 429.838358 -210.844892)
		(width 0.16002)
		(layer "In2.Cu")
		(net "M_I_CPU0_SA_DQS_DN<1>")
	)
	(segment
		(start 429.838358 -210.844892)
		(end 430.021238 -210.662012)
		(width 0.16002)
		(layer "In2.Cu")
		(net "M_I_CPU0_SA_DQS_DN<1>")
	)
	(segment
		(start 377.856242 -232.008934)
		(end 377.864624 -232.004108)
		(width 0.09525)
		(layer "In2.Cu")
		(net "M_I_CPU0_SA_DQS_DN<1>")
	)
	(segment
		(start 381.044958 -232.004108)
		(end 381.05334 -232.008934)
		(width 0.09525)
		(layer "In2.Cu")
		(net "M_I_CPU0_SA_DQS_DN<1>")
	)
	(segment
		(start 391.486136 -231.198928)
		(end 391.526522 -231.175306)
		(width 0.09525)
		(layer "In2.Cu")
		(net "M_I_CPU0_SA_DQS_DN<1>")
	)
	(segment
		(start 414.888172 -209.978752)
		(end 415.413444 -209.978752)
		(width 0.16002)
		(layer "In2.Cu")
		(net "M_I_CPU0_SA_DQS_DN<1>")
	)
	(segment
		(start 392.896344 -228.769164)
		(end 392.934444 -228.747066)
		(width 0.09525)
		(layer "In2.Cu")
		(net "M_I_CPU0_SA_DQS_DN<1>")
	)
	(segment
		(start 418.558472 -210.512152)
		(end 420.691818 -210.512152)
		(width 0.16002)
		(layer "In2.Cu")
		(net "M_I_CPU0_SA_DQS_DN<1>")
	)
	(segment
		(start 377.258834 -232.068624)
		(end 377.359672 -232.041954)
		(width 0.09525)
		(layer "In2.Cu")
		(net "M_I_CPU0_SA_DQS_DN<1>")
	)
	(segment
		(start 391.016236 -232.008934)
		(end 391.054336 -231.986836)
		(width 0.09525)
		(layer "In2.Cu")
		(net "M_I_CPU0_SA_DQS_DN<1>")
	)
	(segment
		(start 431.28311 -210.662012)
		(end 431.55616 -210.935062)
		(width 0.16002)
		(layer "In2.Cu")
		(net "M_I_CPU0_SA_DQS_DN<1>")
	)
	(segment
		(start 392.863832 -228.78796)
		(end 392.896344 -228.769164)
		(width 0.09525)
		(layer "In2.Cu")
		(net "M_I_CPU0_SA_DQS_DN<1>")
	)
	(segment
		(start 395.606778 -224.890584)
		(end 403.93747 -216.559892)
		(width 0.16002)
		(layer "In2.Cu")
		(net "M_I_CPU0_SA_DQS_DN<1>")
	)
	(segment
		(start 377.10491 -232.334054)
		(end 377.258834 -232.068624)
		(width 0.09525)
		(layer "In2.Cu")
		(net "M_I_CPU0_SA_DQS_DN<1>")
	)
	(segment
		(start 422.432226 -209.978752)
		(end 422.957498 -209.978752)
		(width 0.16002)
		(layer "In2.Cu")
		(net "M_I_CPU0_SA_DQS_DN<1>")
	)
	(segment
		(start 394.640054 -226.288092)
		(end 395.00556 -225.922586)
		(width 0.09525)
		(layer "In2.Cu")
		(net "M_I_CPU0_SA_DQS_DN<1>")
	)
	(segment
		(start 381.985012 -232.004108)
		(end 381.993394 -232.008934)
		(width 0.09525)
		(layer "In2.Cu")
		(net "M_I_CPU0_SA_DQS_DN<1>")
	)
	(segment
		(start 414.047432 -210.819492)
		(end 414.888172 -209.978752)
		(width 0.16002)
		(layer "In2.Cu")
		(net "M_I_CPU0_SA_DQS_DN<1>")
	)
	(segment
		(start 395.105128 -225.906076)
		(end 395.606778 -225.404172)
		(width 0.16002)
		(layer "In2.Cu")
		(net "M_I_CPU0_SA_DQS_DN<1>")
	)
	(segment
		(start 385.744974 -232.004108)
		(end 385.753356 -232.008934)
		(width 0.09525)
		(layer "In2.Cu")
		(net "M_I_CPU0_SA_DQS_DN<1>")
	)
	(segment
		(start 425.902374 -210.236308)
		(end 427.959774 -210.236308)
		(width 0.16002)
		(layer "In2.Cu")
		(net "M_I_CPU0_SA_DQS_DN<1>")
	)
	(segment
		(start 392.394694 -229.597204)
		(end 392.42619 -229.578916)
		(width 0.09525)
		(layer "In2.Cu")
		(net "M_I_CPU0_SA_DQS_DN<1>")
	)
	(segment
		(start 390.44499 -232.004108)
		(end 390.453372 -232.008934)
		(width 0.09525)
		(layer "In2.Cu")
		(net "M_I_CPU0_SA_DQS_DN<1>")
	)
	(segment
		(start 421.591486 -210.819492)
		(end 422.432226 -209.978752)
		(width 0.16002)
		(layer "In2.Cu")
		(net "M_I_CPU0_SA_DQS_DN<1>")
	)
	(segment
		(start 395.088364 -225.92284)
		(end 395.105128 -225.906076)
		(width 0.09525)
		(layer "In2.Cu")
		(net "M_I_CPU0_SA_DQS_DN<1>")
	)
	(segment
		(start 413.147764 -210.512152)
		(end 413.455104 -210.819492)
		(width 0.16002)
		(layer "In2.Cu")
		(net "M_I_CPU0_SA_DQS_DN<1>")
	)
	(segment
		(start 386.685028 -232.004108)
		(end 386.69341 -232.008934)
		(width 0.09525)
		(layer "In2.Cu")
		(net "M_I_CPU0_SA_DQS_DN<1>")
	)
	(segment
		(start 388.196328 -232.008934)
		(end 388.20471 -232.004108)
		(width 0.09525)
		(layer "In2.Cu")
		(net "M_I_CPU0_SA_DQS_DN<1>")
	)
	(arc
		(start 380.113286 -232.008934)
		(mid 380.394718 -232.084689)
		(end 380.67615 -232.008934)
		(width 0.09525)
		(layer "In2.Cu")
		(net "M_I_CPU0_SA_DQS_DN<1>")
	)
	(arc
		(start 377.379484 -232.049828)
		(mid 377.622448 -232.082815)
		(end 377.856242 -232.008934)
		(width 0.09525)
		(layer "In2.Cu")
		(net "M_I_CPU0_SA_DQS_DN<1>")
	)
	(arc
		(start 391.526522 -231.175306)
		(mid 391.703294 -230.974285)
		(end 391.76706 -230.714296)
		(width 0.09525)
		(layer "In2.Cu")
		(net "M_I_CPU0_SA_DQS_DN<1>")
	)
	(arc
		(start 392.237214 -229.904036)
		(mid 392.278879 -229.731589)
		(end 392.394694 -229.597204)
		(width 0.09525)
		(layer "In2.Cu")
		(net "M_I_CPU0_SA_DQS_DN<1>")
	)
	(arc
		(start 384.813302 -232.008934)
		(mid 385.094734 -232.084689)
		(end 385.376166 -232.008934)
		(width 0.09525)
		(layer "In2.Cu")
		(net "M_I_CPU0_SA_DQS_DN<1>")
	)
	(arc
		(start 384.436366 -232.008934)
		(mid 384.624834 -231.958257)
		(end 384.813302 -232.008934)
		(width 0.09525)
		(layer "In2.Cu")
		(net "M_I_CPU0_SA_DQS_DN<1>")
	)
	(arc
		(start 389.513318 -232.008934)
		(mid 389.79475 -232.084689)
		(end 390.076182 -232.008934)
		(width 0.09525)
		(layer "In2.Cu")
		(net "M_I_CPU0_SA_DQS_DN<1>")
	)
	(arc
		(start 392.707114 -229.094284)
		(mid 392.748571 -228.922244)
		(end 392.863832 -228.78796)
		(width 0.09525)
		(layer "In2.Cu")
		(net "M_I_CPU0_SA_DQS_DN<1>")
	)
	(arc
		(start 391.99185 -230.368602)
		(mid 392.172143 -230.166739)
		(end 392.237214 -229.904036)
		(width 0.09525)
		(layer "In2.Cu")
		(net "M_I_CPU0_SA_DQS_DN<1>")
	)
	(arc
		(start 391.76706 -230.714296)
		(mid 391.808517 -230.542256)
		(end 391.923778 -230.407972)
		(width 0.09525)
		(layer "In2.Cu")
		(net "M_I_CPU0_SA_DQS_DN<1>")
	)
	(arc
		(start 385.376166 -232.008934)
		(mid 385.559941 -231.958162)
		(end 385.744974 -232.004108)
		(width 0.09525)
		(layer "In2.Cu")
		(net "M_I_CPU0_SA_DQS_DN<1>")
	)
	(arc
		(start 391.054336 -231.986836)
		(mid 391.232786 -231.785366)
		(end 391.29716 -231.524048)
		(width 0.09525)
		(layer "In2.Cu")
		(net "M_I_CPU0_SA_DQS_DN<1>")
	)
	(arc
		(start 391.29716 -231.524048)
		(mid 391.338825 -231.351601)
		(end 391.45464 -231.217216)
		(width 0.09525)
		(layer "In2.Cu")
		(net "M_I_CPU0_SA_DQS_DN<1>")
	)
	(arc
		(start 381.993394 -232.008934)
		(mid 382.274826 -232.084689)
		(end 382.556258 -232.008934)
		(width 0.09525)
		(layer "In2.Cu")
		(net "M_I_CPU0_SA_DQS_DN<1>")
	)
	(arc
		(start 390.453372 -232.008934)
		(mid 390.734804 -232.084689)
		(end 391.016236 -232.008934)
		(width 0.09525)
		(layer "In2.Cu")
		(net "M_I_CPU0_SA_DQS_DN<1>")
	)
	(arc
		(start 382.56464 -232.004108)
		(mid 382.749672 -231.958194)
		(end 382.933448 -232.008934)
		(width 0.09525)
		(layer "In2.Cu")
		(net "M_I_CPU0_SA_DQS_DN<1>")
	)
	(arc
		(start 392.934444 -228.747066)
		(mid 393.112894 -228.545596)
		(end 393.177268 -228.284278)
		(width 0.09525)
		(layer "In2.Cu")
		(net "M_I_CPU0_SA_DQS_DN<1>")
	)
	(arc
		(start 387.264656 -232.004108)
		(mid 387.449688 -231.958194)
		(end 387.633464 -232.008934)
		(width 0.09525)
		(layer "In2.Cu")
		(net "M_I_CPU0_SA_DQS_DN<1>")
	)
	(arc
		(start 390.076182 -232.008934)
		(mid 390.259957 -231.958162)
		(end 390.44499 -232.004108)
		(width 0.09525)
		(layer "In2.Cu")
		(net "M_I_CPU0_SA_DQS_DN<1>")
	)
	(arc
		(start 377.359672 -232.041954)
		(mid 377.36954 -232.045985)
		(end 377.379484 -232.049828)
		(width 0.09525)
		(layer "In2.Cu")
		(net "M_I_CPU0_SA_DQS_DN<1>")
	)
	(arc
		(start 393.398248 -227.940616)
		(mid 393.580772 -227.738359)
		(end 393.64666 -227.474018)
		(width 0.09525)
		(layer "In2.Cu")
		(net "M_I_CPU0_SA_DQS_DN<1>")
	)
	(arc
		(start 379.73635 -232.008934)
		(mid 379.924818 -231.958257)
		(end 380.113286 -232.008934)
		(width 0.09525)
		(layer "In2.Cu")
		(net "M_I_CPU0_SA_DQS_DN<1>")
	)
	(arc
		(start 378.804678 -232.004108)
		(mid 378.98971 -231.958194)
		(end 379.173486 -232.008934)
		(width 0.09525)
		(layer "In2.Cu")
		(net "M_I_CPU0_SA_DQS_DN<1>")
	)
	(arc
		(start 386.31622 -232.008934)
		(mid 386.499995 -231.958162)
		(end 386.685028 -232.004108)
		(width 0.09525)
		(layer "In2.Cu")
		(net "M_I_CPU0_SA_DQS_DN<1>")
	)
	(arc
		(start 380.67615 -232.008934)
		(mid 380.859925 -231.958162)
		(end 381.044958 -232.004108)
		(width 0.09525)
		(layer "In2.Cu")
		(net "M_I_CPU0_SA_DQS_DN<1>")
	)
	(arc
		(start 383.504694 -232.004108)
		(mid 383.689726 -231.958194)
		(end 383.873502 -232.008934)
		(width 0.09525)
		(layer "In2.Cu")
		(net "M_I_CPU0_SA_DQS_DN<1>")
	)
	(arc
		(start 388.20471 -232.004108)
		(mid 388.389742 -231.958194)
		(end 388.573518 -232.008934)
		(width 0.09525)
		(layer "In2.Cu")
		(net "M_I_CPU0_SA_DQS_DN<1>")
	)
	(arc
		(start 392.466576 -229.555294)
		(mid 392.643348 -229.354273)
		(end 392.707114 -229.094284)
		(width 0.09525)
		(layer "In2.Cu")
		(net "M_I_CPU0_SA_DQS_DN<1>")
	)
	(arc
		(start 377.864624 -232.004108)
		(mid 378.049656 -231.958194)
		(end 378.233432 -232.008934)
		(width 0.09525)
		(layer "In2.Cu")
		(net "M_I_CPU0_SA_DQS_DN<1>")
	)
	(arc
		(start 389.136382 -232.008934)
		(mid 389.32485 -231.958257)
		(end 389.513318 -232.008934)
		(width 0.09525)
		(layer "In2.Cu")
		(net "M_I_CPU0_SA_DQS_DN<1>")
	)
	(arc
		(start 385.753356 -232.008934)
		(mid 386.034788 -232.084689)
		(end 386.31622 -232.008934)
		(width 0.09525)
		(layer "In2.Cu")
		(net "M_I_CPU0_SA_DQS_DN<1>")
	)
	(arc
		(start 382.933448 -232.008934)
		(mid 383.21488 -232.084689)
		(end 383.496312 -232.008934)
		(width 0.09525)
		(layer "In2.Cu")
		(net "M_I_CPU0_SA_DQS_DN<1>")
	)
	(arc
		(start 383.873502 -232.008934)
		(mid 384.154934 -232.084689)
		(end 384.436366 -232.008934)
		(width 0.09525)
		(layer "In2.Cu")
		(net "M_I_CPU0_SA_DQS_DN<1>")
	)
	(arc
		(start 387.633464 -232.008934)
		(mid 387.914896 -232.084689)
		(end 388.196328 -232.008934)
		(width 0.09525)
		(layer "In2.Cu")
		(net "M_I_CPU0_SA_DQS_DN<1>")
	)
	(arc
		(start 393.64666 -227.474018)
		(mid 393.687828 -227.302544)
		(end 393.802362 -227.168456)
		(width 0.09525)
		(layer "In2.Cu")
		(net "M_I_CPU0_SA_DQS_DN<1>")
	)
	(arc
		(start 381.05334 -232.008934)
		(mid 381.334772 -232.084689)
		(end 381.616204 -232.008934)
		(width 0.09525)
		(layer "In2.Cu")
		(net "M_I_CPU0_SA_DQS_DN<1>")
	)
	(arc
		(start 388.573518 -232.008934)
		(mid 388.85495 -232.084689)
		(end 389.136382 -232.008934)
		(width 0.09525)
		(layer "In2.Cu")
		(net "M_I_CPU0_SA_DQS_DN<1>")
	)
	(arc
		(start 386.69341 -232.008934)
		(mid 386.974842 -232.084689)
		(end 387.256274 -232.008934)
		(width 0.09525)
		(layer "In2.Cu")
		(net "M_I_CPU0_SA_DQS_DN<1>")
	)
	(arc
		(start 378.233432 -232.008934)
		(mid 378.514864 -232.084689)
		(end 378.796296 -232.008934)
		(width 0.09525)
		(layer "In2.Cu")
		(net "M_I_CPU0_SA_DQS_DN<1>")
	)
	(arc
		(start 393.177268 -228.284278)
		(mid 393.218933 -228.111831)
		(end 393.334748 -227.977446)
		(width 0.09525)
		(layer "In2.Cu")
		(net "M_I_CPU0_SA_DQS_DN<1>")
	)
	(arc
		(start 381.616204 -232.008934)
		(mid 381.799979 -231.958162)
		(end 381.985012 -232.004108)
		(width 0.09525)
		(layer "In2.Cu")
		(net "M_I_CPU0_SA_DQS_DN<1>")
	)
	(arc
		(start 379.173486 -232.008934)
		(mid 379.454918 -232.084689)
		(end 379.73635 -232.008934)
		(width 0.09525)
		(layer "In2.Cu")
		(net "M_I_CPU0_SA_DQS_DN<1>")
	)
	(segment
		(start 376.638058 -227.74021)
		(end 377.10491 -227.474272)
		(width 0.12954)
		(layer "F.Cu")
		(net "M_I_CPU0_SA_DQS_DN<0>")
	)
	(segment
		(start 382.56464 -227.144326)
		(end 382.556258 -227.149152)
		(width 0.09525)
		(layer "In2.Cu")
		(net "M_I_CPU0_SA_DQS_DN<0>")
	)
	(segment
		(start 385.753356 -227.149152)
		(end 385.74599 -227.144834)
		(width 0.09525)
		(layer "In2.Cu")
		(net "M_I_CPU0_SA_DQS_DN<0>")
	)
	(segment
		(start 414.888172 -200.628758)
		(end 414.047432 -201.469498)
		(width 0.16002)
		(layer "In2.Cu")
		(net "M_I_CPU0_SA_DQS_DN<0>")
	)
	(segment
		(start 397.269716 -212.569552)
		(end 397.269716 -213.903052)
		(width 0.16002)
		(layer "In2.Cu")
		(net "M_I_CPU0_SA_DQS_DN<0>")
	)
	(segment
		(start 385.74599 -227.144834)
		(end 385.744974 -227.144326)
		(width 0.09525)
		(layer "In2.Cu")
		(net "M_I_CPU0_SA_DQS_DN<0>")
	)
	(segment
		(start 414.047432 -201.469498)
		(end 413.455104 -201.469498)
		(width 0.16002)
		(layer "In2.Cu")
		(net "M_I_CPU0_SA_DQS_DN<0>")
	)
	(segment
		(start 431.28311 -201.312018)
		(end 429.407574 -201.312018)
		(width 0.16002)
		(layer "In2.Cu")
		(net "M_I_CPU0_SA_DQS_DN<0>")
	)
	(segment
		(start 429.224694 -201.494898)
		(end 428.568358 -201.494898)
		(width 0.16002)
		(layer "In2.Cu")
		(net "M_I_CPU0_SA_DQS_DN<0>")
	)
	(segment
		(start 426.354494 -200.886314)
		(end 425.874434 -200.886314)
		(width 0.16002)
		(layer "In2.Cu")
		(net "M_I_CPU0_SA_DQS_DN<0>")
	)
	(segment
		(start 389.136382 -225.52914)
		(end 389.10387 -225.547936)
		(width 0.09525)
		(layer "In2.Cu")
		(net "M_I_CPU0_SA_DQS_DN<0>")
	)
	(segment
		(start 413.455104 -201.469498)
		(end 413.147764 -201.162158)
		(width 0.16002)
		(layer "In2.Cu")
		(net "M_I_CPU0_SA_DQS_DN<0>")
	)
	(segment
		(start 377.359672 -227.182172)
		(end 377.258834 -227.208842)
		(width 0.09525)
		(layer "In2.Cu")
		(net "M_I_CPU0_SA_DQS_DN<0>")
	)
	(segment
		(start 390.114282 -223.88703)
		(end 390.076182 -223.909128)
		(width 0.09525)
		(layer "In2.Cu")
		(net "M_I_CPU0_SA_DQS_DN<0>")
	)
	(segment
		(start 421.591486 -201.469498)
		(end 420.999158 -201.469498)
		(width 0.16002)
		(layer "In2.Cu")
		(net "M_I_CPU0_SA_DQS_DN<0>")
	)
	(segment
		(start 420.999158 -201.469498)
		(end 420.691818 -201.162158)
		(width 0.16002)
		(layer "In2.Cu")
		(net "M_I_CPU0_SA_DQS_DN<0>")
	)
	(segment
		(start 391.356088 -221.17431)
		(end 391.356088 -221.197932)
		(width 0.09525)
		(layer "In2.Cu")
		(net "M_I_CPU0_SA_DQS_DN<0>")
	)
	(segment
		(start 391.296906 -221.257114)
		(end 391.296906 -221.803722)
		(width 0.09525)
		(layer "In2.Cu")
		(net "M_I_CPU0_SA_DQS_DN<0>")
	)
	(segment
		(start 389.606282 -224.719134)
		(end 389.57377 -224.73793)
		(width 0.09525)
		(layer "In2.Cu")
		(net "M_I_CPU0_SA_DQS_DN<0>")
	)
	(segment
		(start 408.67711 -201.162158)
		(end 397.269716 -212.569552)
		(width 0.16002)
		(layer "In2.Cu")
		(net "M_I_CPU0_SA_DQS_DN<0>")
	)
	(segment
		(start 423.273982 -200.312274)
		(end 422.957498 -200.628758)
		(width 0.16002)
		(layer "In2.Cu")
		(net "M_I_CPU0_SA_DQS_DN<0>")
	)
	(segment
		(start 390.987026 -222.305626)
		(end 390.984486 -222.307404)
		(width 0.09525)
		(layer "In2.Cu")
		(net "M_I_CPU0_SA_DQS_DN<0>")
	)
	(segment
		(start 388.234428 -227.127054)
		(end 388.196328 -227.149152)
		(width 0.09525)
		(layer "In2.Cu")
		(net "M_I_CPU0_SA_DQS_DN<0>")
	)
	(segment
		(start 425.300394 -200.312274)
		(end 423.273982 -200.312274)
		(width 0.16002)
		(layer "In2.Cu")
		(net "M_I_CPU0_SA_DQS_DN<0>")
	)
	(segment
		(start 390.076182 -223.909128)
		(end 390.044686 -223.927416)
		(width 0.09525)
		(layer "In2.Cu")
		(net "M_I_CPU0_SA_DQS_DN<0>")
	)
	(segment
		(start 428.568358 -201.494898)
		(end 427.959774 -200.886314)
		(width 0.16002)
		(layer "In2.Cu")
		(net "M_I_CPU0_SA_DQS_DN<0>")
	)
	(segment
		(start 418.558472 -201.162158)
		(end 417.708588 -200.312274)
		(width 0.16002)
		(layer "In2.Cu")
		(net "M_I_CPU0_SA_DQS_DN<0>")
	)
	(segment
		(start 417.708588 -200.312274)
		(end 415.729928 -200.312274)
		(width 0.16002)
		(layer "In2.Cu")
		(net "M_I_CPU0_SA_DQS_DN<0>")
	)
	(segment
		(start 388.666228 -226.339146)
		(end 388.634732 -226.357434)
		(width 0.09525)
		(layer "In2.Cu")
		(net "M_I_CPU0_SA_DQS_DN<0>")
	)
	(segment
		(start 427.068234 -200.886314)
		(end 426.951394 -201.003154)
		(width 0.16002)
		(layer "In2.Cu")
		(net "M_I_CPU0_SA_DQS_DN<0>")
	)
	(segment
		(start 377.258834 -227.208842)
		(end 377.10491 -227.474272)
		(width 0.09525)
		(layer "In2.Cu")
		(net "M_I_CPU0_SA_DQS_DN<0>")
	)
	(segment
		(start 415.729928 -200.312274)
		(end 415.413444 -200.628758)
		(width 0.16002)
		(layer "In2.Cu")
		(net "M_I_CPU0_SA_DQS_DN<0>")
	)
	(segment
		(start 426.951394 -201.003154)
		(end 426.471334 -201.003154)
		(width 0.16002)
		(layer "In2.Cu")
		(net "M_I_CPU0_SA_DQS_DN<0>")
	)
	(segment
		(start 390.584182 -223.077024)
		(end 390.546082 -223.099122)
		(width 0.09525)
		(layer "In2.Cu")
		(net "M_I_CPU0_SA_DQS_DN<0>")
	)
	(segment
		(start 389.171434 -225.508566)
		(end 389.136382 -225.52914)
		(width 0.09525)
		(layer "In2.Cu")
		(net "M_I_CPU0_SA_DQS_DN<0>")
	)
	(segment
		(start 387.264656 -227.144326)
		(end 387.256274 -227.149152)
		(width 0.09525)
		(layer "In2.Cu")
		(net "M_I_CPU0_SA_DQS_DN<0>")
	)
	(segment
		(start 391.356088 -221.197932)
		(end 391.296906 -221.257114)
		(width 0.09525)
		(layer "In2.Cu")
		(net "M_I_CPU0_SA_DQS_DN<0>")
	)
	(segment
		(start 422.432226 -200.628758)
		(end 421.591486 -201.469498)
		(width 0.16002)
		(layer "In2.Cu")
		(net "M_I_CPU0_SA_DQS_DN<0>")
	)
	(segment
		(start 381.05334 -227.149152)
		(end 381.044958 -227.144326)
		(width 0.09525)
		(layer "In2.Cu")
		(net "M_I_CPU0_SA_DQS_DN<0>")
	)
	(segment
		(start 427.959774 -200.886314)
		(end 427.068234 -200.886314)
		(width 0.16002)
		(layer "In2.Cu")
		(net "M_I_CPU0_SA_DQS_DN<0>")
	)
	(segment
		(start 415.413444 -200.628758)
		(end 414.888172 -200.628758)
		(width 0.16002)
		(layer "In2.Cu")
		(net "M_I_CPU0_SA_DQS_DN<0>")
	)
	(segment
		(start 426.471334 -201.003154)
		(end 426.354494 -200.886314)
		(width 0.16002)
		(layer "In2.Cu")
		(net "M_I_CPU0_SA_DQS_DN<0>")
	)
	(segment
		(start 425.874434 -200.886314)
		(end 425.300394 -200.312274)
		(width 0.16002)
		(layer "In2.Cu")
		(net "M_I_CPU0_SA_DQS_DN<0>")
	)
	(segment
		(start 391.054336 -222.26651)
		(end 390.987026 -222.305626)
		(width 0.09525)
		(layer "In2.Cu")
		(net "M_I_CPU0_SA_DQS_DN<0>")
	)
	(segment
		(start 431.55616 -201.585068)
		(end 431.28311 -201.312018)
		(width 0.16002)
		(layer "In2.Cu")
		(net "M_I_CPU0_SA_DQS_DN<0>")
	)
	(segment
		(start 391.356088 -219.81668)
		(end 391.356088 -221.17431)
		(width 0.16002)
		(layer "In2.Cu")
		(net "M_I_CPU0_SA_DQS_DN<0>")
	)
	(segment
		(start 378.804678 -227.144326)
		(end 378.796296 -227.149152)
		(width 0.09525)
		(layer "In2.Cu")
		(net "M_I_CPU0_SA_DQS_DN<0>")
	)
	(segment
		(start 389.644382 -224.697036)
		(end 389.606282 -224.719134)
		(width 0.09525)
		(layer "In2.Cu")
		(net "M_I_CPU0_SA_DQS_DN<0>")
	)
	(segment
		(start 383.504694 -227.144326)
		(end 383.496312 -227.149152)
		(width 0.09525)
		(layer "In2.Cu")
		(net "M_I_CPU0_SA_DQS_DN<0>")
	)
	(segment
		(start 420.691818 -201.162158)
		(end 418.558472 -201.162158)
		(width 0.16002)
		(layer "In2.Cu")
		(net "M_I_CPU0_SA_DQS_DN<0>")
	)
	(segment
		(start 381.993394 -227.149152)
		(end 381.985012 -227.144326)
		(width 0.09525)
		(layer "In2.Cu")
		(net "M_I_CPU0_SA_DQS_DN<0>")
	)
	(segment
		(start 397.269716 -213.903052)
		(end 391.356088 -219.81668)
		(width 0.16002)
		(layer "In2.Cu")
		(net "M_I_CPU0_SA_DQS_DN<0>")
	)
	(segment
		(start 413.147764 -201.162158)
		(end 408.67711 -201.162158)
		(width 0.16002)
		(layer "In2.Cu")
		(net "M_I_CPU0_SA_DQS_DN<0>")
	)
	(segment
		(start 390.546082 -223.099122)
		(end 390.514586 -223.11741)
		(width 0.09525)
		(layer "In2.Cu")
		(net "M_I_CPU0_SA_DQS_DN<0>")
	)
	(segment
		(start 422.957498 -200.628758)
		(end 422.432226 -200.628758)
		(width 0.16002)
		(layer "In2.Cu")
		(net "M_I_CPU0_SA_DQS_DN<0>")
	)
	(segment
		(start 386.69341 -227.149152)
		(end 386.685028 -227.144326)
		(width 0.09525)
		(layer "In2.Cu")
		(net "M_I_CPU0_SA_DQS_DN<0>")
	)
	(segment
		(start 429.407574 -201.312018)
		(end 429.224694 -201.494898)
		(width 0.16002)
		(layer "In2.Cu")
		(net "M_I_CPU0_SA_DQS_DN<0>")
	)
	(segment
		(start 388.704328 -226.317048)
		(end 388.666228 -226.339146)
		(width 0.09525)
		(layer "In2.Cu")
		(net "M_I_CPU0_SA_DQS_DN<0>")
	)
	(segment
		(start 377.864624 -227.144326)
		(end 377.856242 -227.149152)
		(width 0.09525)
		(layer "In2.Cu")
		(net "M_I_CPU0_SA_DQS_DN<0>")
	)
	(arc
		(start 388.196328 -227.149152)
		(mid 387.914896 -227.224907)
		(end 387.633464 -227.149152)
		(width 0.09525)
		(layer "In2.Cu")
		(net "M_I_CPU0_SA_DQS_DN<0>")
	)
	(arc
		(start 383.496312 -227.149152)
		(mid 383.21488 -227.224907)
		(end 382.933448 -227.149152)
		(width 0.09525)
		(layer "In2.Cu")
		(net "M_I_CPU0_SA_DQS_DN<0>")
	)
	(arc
		(start 379.173486 -227.149152)
		(mid 378.989711 -227.09838)
		(end 378.804678 -227.144326)
		(width 0.09525)
		(layer "In2.Cu")
		(net "M_I_CPU0_SA_DQS_DN<0>")
	)
	(arc
		(start 383.873502 -227.149152)
		(mid 383.689727 -227.09838)
		(end 383.504694 -227.144326)
		(width 0.09525)
		(layer "In2.Cu")
		(net "M_I_CPU0_SA_DQS_DN<0>")
	)
	(arc
		(start 378.796296 -227.149152)
		(mid 378.514864 -227.224907)
		(end 378.233432 -227.149152)
		(width 0.09525)
		(layer "In2.Cu")
		(net "M_I_CPU0_SA_DQS_DN<0>")
	)
	(arc
		(start 388.947152 -225.85426)
		(mid 388.882755 -226.115566)
		(end 388.704328 -226.317048)
		(width 0.09525)
		(layer "In2.Cu")
		(net "M_I_CPU0_SA_DQS_DN<0>")
	)
	(arc
		(start 384.436366 -227.149152)
		(mid 384.154934 -227.224907)
		(end 383.873502 -227.149152)
		(width 0.09525)
		(layer "In2.Cu")
		(net "M_I_CPU0_SA_DQS_DN<0>")
	)
	(arc
		(start 386.685028 -227.144326)
		(mid 386.499996 -227.098412)
		(end 386.31622 -227.149152)
		(width 0.09525)
		(layer "In2.Cu")
		(net "M_I_CPU0_SA_DQS_DN<0>")
	)
	(arc
		(start 387.256274 -227.149152)
		(mid 386.974842 -227.224907)
		(end 386.69341 -227.149152)
		(width 0.09525)
		(layer "In2.Cu")
		(net "M_I_CPU0_SA_DQS_DN<0>")
	)
	(arc
		(start 380.67615 -227.149152)
		(mid 380.394718 -227.224907)
		(end 380.113286 -227.149152)
		(width 0.09525)
		(layer "In2.Cu")
		(net "M_I_CPU0_SA_DQS_DN<0>")
	)
	(arc
		(start 390.827006 -222.614236)
		(mid 390.762609 -222.875542)
		(end 390.584182 -223.077024)
		(width 0.09525)
		(layer "In2.Cu")
		(net "M_I_CPU0_SA_DQS_DN<0>")
	)
	(arc
		(start 388.634732 -226.357434)
		(mid 388.518934 -226.491828)
		(end 388.477252 -226.664266)
		(width 0.09525)
		(layer "In2.Cu")
		(net "M_I_CPU0_SA_DQS_DN<0>")
	)
	(arc
		(start 390.514586 -223.11741)
		(mid 390.398788 -223.251804)
		(end 390.357106 -223.424242)
		(width 0.09525)
		(layer "In2.Cu")
		(net "M_I_CPU0_SA_DQS_DN<0>")
	)
	(arc
		(start 389.10387 -225.547936)
		(mid 388.988596 -225.682214)
		(end 388.947152 -225.85426)
		(width 0.09525)
		(layer "In2.Cu")
		(net "M_I_CPU0_SA_DQS_DN<0>")
	)
	(arc
		(start 390.044686 -223.927416)
		(mid 389.928888 -224.06181)
		(end 389.887206 -224.234248)
		(width 0.09525)
		(layer "In2.Cu")
		(net "M_I_CPU0_SA_DQS_DN<0>")
	)
	(arc
		(start 391.296906 -221.803722)
		(mid 391.232577 -222.064961)
		(end 391.054336 -222.26651)
		(width 0.09525)
		(layer "In2.Cu")
		(net "M_I_CPU0_SA_DQS_DN<0>")
	)
	(arc
		(start 385.744974 -227.144326)
		(mid 385.559942 -227.098412)
		(end 385.376166 -227.149152)
		(width 0.09525)
		(layer "In2.Cu")
		(net "M_I_CPU0_SA_DQS_DN<0>")
	)
	(arc
		(start 377.856242 -227.149152)
		(mid 377.622447 -227.223019)
		(end 377.379484 -227.190046)
		(width 0.09525)
		(layer "In2.Cu")
		(net "M_I_CPU0_SA_DQS_DN<0>")
	)
	(arc
		(start 385.376166 -227.149152)
		(mid 385.094734 -227.224907)
		(end 384.813302 -227.149152)
		(width 0.09525)
		(layer "In2.Cu")
		(net "M_I_CPU0_SA_DQS_DN<0>")
	)
	(arc
		(start 382.556258 -227.149152)
		(mid 382.274826 -227.224907)
		(end 381.993394 -227.149152)
		(width 0.09525)
		(layer "In2.Cu")
		(net "M_I_CPU0_SA_DQS_DN<0>")
	)
	(arc
		(start 378.233432 -227.149152)
		(mid 378.049657 -227.09838)
		(end 377.864624 -227.144326)
		(width 0.09525)
		(layer "In2.Cu")
		(net "M_I_CPU0_SA_DQS_DN<0>")
	)
	(arc
		(start 387.633464 -227.149152)
		(mid 387.449689 -227.09838)
		(end 387.264656 -227.144326)
		(width 0.09525)
		(layer "In2.Cu")
		(net "M_I_CPU0_SA_DQS_DN<0>")
	)
	(arc
		(start 386.31622 -227.149152)
		(mid 386.034788 -227.224907)
		(end 385.753356 -227.149152)
		(width 0.09525)
		(layer "In2.Cu")
		(net "M_I_CPU0_SA_DQS_DN<0>")
	)
	(arc
		(start 389.57377 -224.73793)
		(mid 389.458496 -224.872208)
		(end 389.417052 -225.044254)
		(width 0.09525)
		(layer "In2.Cu")
		(net "M_I_CPU0_SA_DQS_DN<0>")
	)
	(arc
		(start 381.985012 -227.144326)
		(mid 381.79998 -227.098412)
		(end 381.616204 -227.149152)
		(width 0.09525)
		(layer "In2.Cu")
		(net "M_I_CPU0_SA_DQS_DN<0>")
	)
	(arc
		(start 381.044958 -227.144326)
		(mid 380.859926 -227.098412)
		(end 380.67615 -227.149152)
		(width 0.09525)
		(layer "In2.Cu")
		(net "M_I_CPU0_SA_DQS_DN<0>")
	)
	(arc
		(start 389.417052 -225.044254)
		(mid 389.351805 -225.306857)
		(end 389.171434 -225.508566)
		(width 0.09525)
		(layer "In2.Cu")
		(net "M_I_CPU0_SA_DQS_DN<0>")
	)
	(arc
		(start 382.933448 -227.149152)
		(mid 382.749673 -227.09838)
		(end 382.56464 -227.144326)
		(width 0.09525)
		(layer "In2.Cu")
		(net "M_I_CPU0_SA_DQS_DN<0>")
	)
	(arc
		(start 389.887206 -224.234248)
		(mid 389.822809 -224.495554)
		(end 389.644382 -224.697036)
		(width 0.09525)
		(layer "In2.Cu")
		(net "M_I_CPU0_SA_DQS_DN<0>")
	)
	(arc
		(start 390.984486 -222.307404)
		(mid 390.868688 -222.441798)
		(end 390.827006 -222.614236)
		(width 0.09525)
		(layer "In2.Cu")
		(net "M_I_CPU0_SA_DQS_DN<0>")
	)
	(arc
		(start 377.379484 -227.190046)
		(mid 377.369541 -227.186203)
		(end 377.359672 -227.182172)
		(width 0.09525)
		(layer "In2.Cu")
		(net "M_I_CPU0_SA_DQS_DN<0>")
	)
	(arc
		(start 390.357106 -223.424242)
		(mid 390.292709 -223.685548)
		(end 390.114282 -223.88703)
		(width 0.09525)
		(layer "In2.Cu")
		(net "M_I_CPU0_SA_DQS_DN<0>")
	)
	(arc
		(start 380.113286 -227.149152)
		(mid 379.924818 -227.098475)
		(end 379.73635 -227.149152)
		(width 0.09525)
		(layer "In2.Cu")
		(net "M_I_CPU0_SA_DQS_DN<0>")
	)
	(arc
		(start 381.616204 -227.149152)
		(mid 381.334772 -227.224907)
		(end 381.05334 -227.149152)
		(width 0.09525)
		(layer "In2.Cu")
		(net "M_I_CPU0_SA_DQS_DN<0>")
	)
	(arc
		(start 379.73635 -227.149152)
		(mid 379.454918 -227.224907)
		(end 379.173486 -227.149152)
		(width 0.09525)
		(layer "In2.Cu")
		(net "M_I_CPU0_SA_DQS_DN<0>")
	)
	(arc
		(start 388.477252 -226.664266)
		(mid 388.412855 -226.925572)
		(end 388.234428 -227.127054)
		(width 0.09525)
		(layer "In2.Cu")
		(net "M_I_CPU0_SA_DQS_DN<0>")
	)
	(arc
		(start 384.813302 -227.149152)
		(mid 384.624834 -227.098475)
		(end 384.436366 -227.149152)
		(width 0.09525)
		(layer "In2.Cu")
		(net "M_I_CPU0_SA_DQS_DN<0>")
	)
	(segment
		(start 375.698004 -230.97998)
		(end 376.164856 -230.714296)
		(width 0.10668)
		(layer "F.Cu")
		(net "M_I_CPU0_SA_DQ<9>")
	)
	(segment
		(start 414.12033 -208.810098)
		(end 408.341576 -208.810098)
		(width 0.14478)
		(layer "In2.Cu")
		(net "M_I_CPU0_SA_DQ<9>")
	)
	(segment
		(start 392.331956 -227.796852)
		(end 392.29284 -227.819712)
		(width 0.0889)
		(layer "In2.Cu")
		(net "M_I_CPU0_SA_DQ<9>")
	)
	(segment
		(start 401.380198 -217.070178)
		(end 394.786358 -223.664018)
		(width 0.14478)
		(layer "In2.Cu")
		(net "M_I_CPU0_SA_DQ<9>")
	)
	(segment
		(start 394.452094 -223.998282)
		(end 394.452094 -224.315782)
		(width 0.0889)
		(layer "In2.Cu")
		(net "M_I_CPU0_SA_DQ<9>")
	)
	(segment
		(start 378.806202 -231.041448)
		(end 378.79782 -231.036622)
		(width 0.0889)
		(layer "In2.Cu")
		(net "M_I_CPU0_SA_DQ<9>")
	)
	(segment
		(start 377.291854 -231.036622)
		(end 377.283472 -231.041448)
		(width 0.0889)
		(layer "In2.Cu")
		(net "M_I_CPU0_SA_DQ<9>")
	)
	(segment
		(start 387.26618 -231.041448)
		(end 387.257798 -231.036622)
		(width 0.0889)
		(layer "In2.Cu")
		(net "M_I_CPU0_SA_DQ<9>")
	)
	(segment
		(start 390.953498 -230.208328)
		(end 390.921748 -230.226616)
		(width 0.0889)
		(layer "In2.Cu")
		(net "M_I_CPU0_SA_DQ<9>")
	)
	(segment
		(start 393.7 -225.55327)
		(end 393.41298 -226.021646)
		(width 0.0889)
		(layer "In2.Cu")
		(net "M_I_CPU0_SA_DQ<9>")
	)
	(segment
		(start 385.751832 -231.036622)
		(end 385.74345 -231.041448)
		(width 0.0889)
		(layer "In2.Cu")
		(net "M_I_CPU0_SA_DQ<9>")
	)
	(segment
		(start 390.485376 -231.017064)
		(end 390.451848 -231.036622)
		(width 0.0889)
		(layer "In2.Cu")
		(net "M_I_CPU0_SA_DQ<9>")
	)
	(segment
		(start 414.970214 -207.960214)
		(end 414.12033 -208.810098)
		(width 0.14478)
		(layer "In2.Cu")
		(net "M_I_CPU0_SA_DQ<9>")
	)
	(segment
		(start 431.55616 -208.385156)
		(end 431.131218 -207.960214)
		(width 0.14478)
		(layer "In2.Cu")
		(net "M_I_CPU0_SA_DQ<9>")
	)
	(segment
		(start 391.391902 -229.41661)
		(end 391.352786 -229.43947)
		(width 0.0889)
		(layer "In2.Cu")
		(net "M_I_CPU0_SA_DQ<9>")
	)
	(segment
		(start 393.27201 -226.17684)
		(end 393.232894 -226.1997)
		(width 0.0889)
		(layer "In2.Cu")
		(net "M_I_CPU0_SA_DQ<9>")
	)
	(segment
		(start 391.861802 -228.606858)
		(end 391.822686 -228.629718)
		(width 0.0889)
		(layer "In2.Cu")
		(net "M_I_CPU0_SA_DQ<9>")
	)
	(segment
		(start 386.691886 -231.036622)
		(end 386.683504 -231.041448)
		(width 0.0889)
		(layer "In2.Cu")
		(net "M_I_CPU0_SA_DQ<9>")
	)
	(segment
		(start 391.893552 -228.58857)
		(end 391.861802 -228.606858)
		(width 0.0889)
		(layer "In2.Cu")
		(net "M_I_CPU0_SA_DQ<9>")
	)
	(segment
		(start 421.434514 -208.810098)
		(end 418.897562 -208.810098)
		(width 0.14478)
		(layer "In2.Cu")
		(net "M_I_CPU0_SA_DQ<9>")
	)
	(segment
		(start 390.921748 -230.226616)
		(end 390.88822 -230.246174)
		(width 0.0889)
		(layer "In2.Cu")
		(net "M_I_CPU0_SA_DQ<9>")
	)
	(segment
		(start 376.3518 -231.036622)
		(end 376.343418 -231.041448)
		(width 0.0889)
		(layer "In2.Cu")
		(net "M_I_CPU0_SA_DQ<9>")
	)
	(segment
		(start 418.897562 -208.810098)
		(end 418.047678 -207.960214)
		(width 0.14478)
		(layer "In2.Cu")
		(net "M_I_CPU0_SA_DQ<9>")
	)
	(segment
		(start 392.833606 -226.968558)
		(end 392.801856 -226.986846)
		(width 0.0889)
		(layer "In2.Cu")
		(net "M_I_CPU0_SA_DQ<9>")
	)
	(segment
		(start 383.506218 -231.041448)
		(end 383.497836 -231.036622)
		(width 0.0889)
		(layer "In2.Cu")
		(net "M_I_CPU0_SA_DQ<9>")
	)
	(segment
		(start 376.010678 -230.979726)
		(end 376.164856 -230.714296)
		(width 0.0889)
		(layer "In2.Cu")
		(net "M_I_CPU0_SA_DQ<9>")
	)
	(segment
		(start 391.424414 -229.397814)
		(end 391.391902 -229.41661)
		(width 0.0889)
		(layer "In2.Cu")
		(net "M_I_CPU0_SA_DQ<9>")
	)
	(segment
		(start 394.452094 -224.315782)
		(end 393.7 -225.067876)
		(width 0.0889)
		(layer "In2.Cu")
		(net "M_I_CPU0_SA_DQ<9>")
	)
	(segment
		(start 393.7 -225.067876)
		(end 393.7 -225.55327)
		(width 0.0889)
		(layer "In2.Cu")
		(net "M_I_CPU0_SA_DQ<9>")
	)
	(segment
		(start 408.341576 -208.810098)
		(end 401.380198 -215.771476)
		(width 0.14478)
		(layer "In2.Cu")
		(net "M_I_CPU0_SA_DQ<9>")
	)
	(segment
		(start 431.131218 -207.960214)
		(end 422.284398 -207.960214)
		(width 0.14478)
		(layer "In2.Cu")
		(net "M_I_CPU0_SA_DQ<9>")
	)
	(segment
		(start 381.99187 -231.036622)
		(end 381.983488 -231.041448)
		(width 0.0889)
		(layer "In2.Cu")
		(net "M_I_CPU0_SA_DQ<9>")
	)
	(segment
		(start 394.786358 -223.664018)
		(end 394.452094 -223.998282)
		(width 0.0889)
		(layer "In2.Cu")
		(net "M_I_CPU0_SA_DQ<9>")
	)
	(segment
		(start 401.380198 -215.771476)
		(end 401.380198 -217.070178)
		(width 0.14478)
		(layer "In2.Cu")
		(net "M_I_CPU0_SA_DQ<9>")
	)
	(segment
		(start 422.284398 -207.960214)
		(end 421.434514 -208.810098)
		(width 0.14478)
		(layer "In2.Cu")
		(net "M_I_CPU0_SA_DQ<9>")
	)
	(segment
		(start 392.801856 -226.986846)
		(end 392.76274 -227.009706)
		(width 0.0889)
		(layer "In2.Cu")
		(net "M_I_CPU0_SA_DQ<9>")
	)
	(segment
		(start 382.566164 -231.041448)
		(end 382.557782 -231.036622)
		(width 0.0889)
		(layer "In2.Cu")
		(net "M_I_CPU0_SA_DQ<9>")
	)
	(segment
		(start 381.051816 -231.036622)
		(end 381.043434 -231.041448)
		(width 0.0889)
		(layer "In2.Cu")
		(net "M_I_CPU0_SA_DQ<9>")
	)
	(segment
		(start 376.032776 -231.062784)
		(end 376.010678 -230.979726)
		(width 0.0889)
		(layer "In2.Cu")
		(net "M_I_CPU0_SA_DQ<9>")
	)
	(segment
		(start 388.206234 -231.041448)
		(end 388.197852 -231.036622)
		(width 0.0889)
		(layer "In2.Cu")
		(net "M_I_CPU0_SA_DQ<9>")
	)
	(segment
		(start 377.866148 -231.041448)
		(end 377.857766 -231.036622)
		(width 0.0889)
		(layer "In2.Cu")
		(net "M_I_CPU0_SA_DQ<9>")
	)
	(segment
		(start 418.047678 -207.960214)
		(end 414.970214 -207.960214)
		(width 0.14478)
		(layer "In2.Cu")
		(net "M_I_CPU0_SA_DQ<9>")
	)
	(segment
		(start 392.362436 -227.779072)
		(end 392.331956 -227.796852)
		(width 0.0889)
		(layer "In2.Cu")
		(net "M_I_CPU0_SA_DQ<9>")
	)
	(segment
		(start 390.451848 -231.036622)
		(end 390.443466 -231.041448)
		(width 0.0889)
		(layer "In2.Cu")
		(net "M_I_CPU0_SA_DQ<9>")
	)
	(arc
		(start 378.231908 -231.036622)
		(mid 378.049657 -231.087006)
		(end 377.866148 -231.041448)
		(width 0.0889)
		(layer "In2.Cu")
		(net "M_I_CPU0_SA_DQ<9>")
	)
	(arc
		(start 382.931924 -231.036622)
		(mid 382.749673 -231.087006)
		(end 382.566164 -231.041448)
		(width 0.0889)
		(layer "In2.Cu")
		(net "M_I_CPU0_SA_DQ<9>")
	)
	(arc
		(start 390.077706 -231.036622)
		(mid 389.79475 -230.960445)
		(end 389.511794 -231.036622)
		(width 0.0889)
		(layer "In2.Cu")
		(net "M_I_CPU0_SA_DQ<9>")
	)
	(arc
		(start 379.737874 -231.036622)
		(mid 379.454918 -230.960445)
		(end 379.171962 -231.036622)
		(width 0.0889)
		(layer "In2.Cu")
		(net "M_I_CPU0_SA_DQ<9>")
	)
	(arc
		(start 390.88822 -230.246174)
		(mid 390.705558 -230.449255)
		(end 390.639554 -230.714296)
		(width 0.0889)
		(layer "In2.Cu")
		(net "M_I_CPU0_SA_DQ<9>")
	)
	(arc
		(start 376.917712 -231.036622)
		(mid 376.634756 -230.960445)
		(end 376.3518 -231.036622)
		(width 0.0889)
		(layer "In2.Cu")
		(net "M_I_CPU0_SA_DQ<9>")
	)
	(arc
		(start 393.41298 -226.021646)
		(mid 393.349807 -226.105887)
		(end 393.27201 -226.17684)
		(width 0.0889)
		(layer "In2.Cu")
		(net "M_I_CPU0_SA_DQ<9>")
	)
	(arc
		(start 376.343418 -231.041448)
		(mid 376.19043 -231.086128)
		(end 376.032776 -231.062784)
		(width 0.0889)
		(layer "In2.Cu")
		(net "M_I_CPU0_SA_DQ<9>")
	)
	(arc
		(start 381.983488 -231.041448)
		(mid 381.79998 -231.086973)
		(end 381.617728 -231.036622)
		(width 0.0889)
		(layer "In2.Cu")
		(net "M_I_CPU0_SA_DQ<9>")
	)
	(arc
		(start 381.617728 -231.036622)
		(mid 381.334772 -230.960445)
		(end 381.051816 -231.036622)
		(width 0.0889)
		(layer "In2.Cu")
		(net "M_I_CPU0_SA_DQ<9>")
	)
	(arc
		(start 382.557782 -231.036622)
		(mid 382.274826 -230.960445)
		(end 381.99187 -231.036622)
		(width 0.0889)
		(layer "In2.Cu")
		(net "M_I_CPU0_SA_DQ<9>")
	)
	(arc
		(start 393.232894 -226.1997)
		(mid 393.054081 -226.40205)
		(end 392.989562 -226.664266)
		(width 0.0889)
		(layer "In2.Cu")
		(net "M_I_CPU0_SA_DQ<9>")
	)
	(arc
		(start 391.352786 -229.43947)
		(mid 391.173973 -229.64182)
		(end 391.109454 -229.904036)
		(width 0.0889)
		(layer "In2.Cu")
		(net "M_I_CPU0_SA_DQ<9>")
	)
	(arc
		(start 378.79782 -231.036622)
		(mid 378.514864 -230.960445)
		(end 378.231908 -231.036622)
		(width 0.0889)
		(layer "In2.Cu")
		(net "M_I_CPU0_SA_DQ<9>")
	)
	(arc
		(start 377.857766 -231.036622)
		(mid 377.57481 -230.960445)
		(end 377.291854 -231.036622)
		(width 0.0889)
		(layer "In2.Cu")
		(net "M_I_CPU0_SA_DQ<9>")
	)
	(arc
		(start 391.822686 -228.629718)
		(mid 391.643873 -228.832068)
		(end 391.579354 -229.094284)
		(width 0.0889)
		(layer "In2.Cu")
		(net "M_I_CPU0_SA_DQ<9>")
	)
	(arc
		(start 386.317744 -231.036622)
		(mid 386.034788 -230.960445)
		(end 385.751832 -231.036622)
		(width 0.0889)
		(layer "In2.Cu")
		(net "M_I_CPU0_SA_DQ<9>")
	)
	(arc
		(start 387.257798 -231.036622)
		(mid 386.974842 -230.960445)
		(end 386.691886 -231.036622)
		(width 0.0889)
		(layer "In2.Cu")
		(net "M_I_CPU0_SA_DQ<9>")
	)
	(arc
		(start 392.049508 -228.284278)
		(mid 392.008253 -228.455249)
		(end 391.893552 -228.58857)
		(width 0.0889)
		(layer "In2.Cu")
		(net "M_I_CPU0_SA_DQ<9>")
	)
	(arc
		(start 392.76274 -227.009706)
		(mid 392.583927 -227.212056)
		(end 392.519408 -227.474272)
		(width 0.0889)
		(layer "In2.Cu")
		(net "M_I_CPU0_SA_DQ<9>")
	)
	(arc
		(start 383.497836 -231.036622)
		(mid 383.21488 -230.960445)
		(end 382.931924 -231.036622)
		(width 0.0889)
		(layer "In2.Cu")
		(net "M_I_CPU0_SA_DQ<9>")
	)
	(arc
		(start 391.579354 -229.094284)
		(mid 391.538388 -229.26469)
		(end 391.424414 -229.397814)
		(width 0.0889)
		(layer "In2.Cu")
		(net "M_I_CPU0_SA_DQ<9>")
	)
	(arc
		(start 388.197852 -231.036622)
		(mid 387.914896 -230.960445)
		(end 387.63194 -231.036622)
		(width 0.0889)
		(layer "In2.Cu")
		(net "M_I_CPU0_SA_DQ<9>")
	)
	(arc
		(start 392.989562 -226.664266)
		(mid 392.948307 -226.835237)
		(end 392.833606 -226.968558)
		(width 0.0889)
		(layer "In2.Cu")
		(net "M_I_CPU0_SA_DQ<9>")
	)
	(arc
		(start 384.811778 -231.036622)
		(mid 384.624834 -231.086911)
		(end 384.43789 -231.036622)
		(width 0.0889)
		(layer "In2.Cu")
		(net "M_I_CPU0_SA_DQ<9>")
	)
	(arc
		(start 390.639554 -230.714296)
		(mid 390.598792 -230.88418)
		(end 390.485376 -231.017064)
		(width 0.0889)
		(layer "In2.Cu")
		(net "M_I_CPU0_SA_DQ<9>")
	)
	(arc
		(start 387.63194 -231.036622)
		(mid 387.449689 -231.087006)
		(end 387.26618 -231.041448)
		(width 0.0889)
		(layer "In2.Cu")
		(net "M_I_CPU0_SA_DQ<9>")
	)
	(arc
		(start 383.871978 -231.036622)
		(mid 383.689727 -231.087006)
		(end 383.506218 -231.041448)
		(width 0.0889)
		(layer "In2.Cu")
		(net "M_I_CPU0_SA_DQ<9>")
	)
	(arc
		(start 384.43789 -231.036622)
		(mid 384.154934 -230.960445)
		(end 383.871978 -231.036622)
		(width 0.0889)
		(layer "In2.Cu")
		(net "M_I_CPU0_SA_DQ<9>")
	)
	(arc
		(start 386.683504 -231.041448)
		(mid 386.499996 -231.086973)
		(end 386.317744 -231.036622)
		(width 0.0889)
		(layer "In2.Cu")
		(net "M_I_CPU0_SA_DQ<9>")
	)
	(arc
		(start 381.043434 -231.041448)
		(mid 380.859926 -231.086973)
		(end 380.677674 -231.036622)
		(width 0.0889)
		(layer "In2.Cu")
		(net "M_I_CPU0_SA_DQ<9>")
	)
	(arc
		(start 380.111762 -231.036622)
		(mid 379.924818 -231.086911)
		(end 379.737874 -231.036622)
		(width 0.0889)
		(layer "In2.Cu")
		(net "M_I_CPU0_SA_DQ<9>")
	)
	(arc
		(start 385.74345 -231.041448)
		(mid 385.559942 -231.086973)
		(end 385.37769 -231.036622)
		(width 0.0889)
		(layer "In2.Cu")
		(net "M_I_CPU0_SA_DQ<9>")
	)
	(arc
		(start 388.571994 -231.036622)
		(mid 388.389743 -231.087006)
		(end 388.206234 -231.041448)
		(width 0.0889)
		(layer "In2.Cu")
		(net "M_I_CPU0_SA_DQ<9>")
	)
	(arc
		(start 379.171962 -231.036622)
		(mid 378.989711 -231.087006)
		(end 378.806202 -231.041448)
		(width 0.0889)
		(layer "In2.Cu")
		(net "M_I_CPU0_SA_DQ<9>")
	)
	(arc
		(start 392.519408 -227.474272)
		(mid 392.477859 -227.645694)
		(end 392.362436 -227.779072)
		(width 0.0889)
		(layer "In2.Cu")
		(net "M_I_CPU0_SA_DQ<9>")
	)
	(arc
		(start 390.443466 -231.041448)
		(mid 390.259958 -231.086973)
		(end 390.077706 -231.036622)
		(width 0.0889)
		(layer "In2.Cu")
		(net "M_I_CPU0_SA_DQ<9>")
	)
	(arc
		(start 385.37769 -231.036622)
		(mid 385.094734 -230.960445)
		(end 384.811778 -231.036622)
		(width 0.0889)
		(layer "In2.Cu")
		(net "M_I_CPU0_SA_DQ<9>")
	)
	(arc
		(start 377.283472 -231.041448)
		(mid 377.099964 -231.086973)
		(end 376.917712 -231.036622)
		(width 0.0889)
		(layer "In2.Cu")
		(net "M_I_CPU0_SA_DQ<9>")
	)
	(arc
		(start 389.137906 -231.036622)
		(mid 388.85495 -230.960445)
		(end 388.571994 -231.036622)
		(width 0.0889)
		(layer "In2.Cu")
		(net "M_I_CPU0_SA_DQ<9>")
	)
	(arc
		(start 391.109454 -229.904036)
		(mid 391.068199 -230.075007)
		(end 390.953498 -230.208328)
		(width 0.0889)
		(layer "In2.Cu")
		(net "M_I_CPU0_SA_DQ<9>")
	)
	(arc
		(start 389.511794 -231.036622)
		(mid 389.32485 -231.086911)
		(end 389.137906 -231.036622)
		(width 0.0889)
		(layer "In2.Cu")
		(net "M_I_CPU0_SA_DQ<9>")
	)
	(arc
		(start 380.677674 -231.036622)
		(mid 380.394718 -230.960445)
		(end 380.111762 -231.036622)
		(width 0.0889)
		(layer "In2.Cu")
		(net "M_I_CPU0_SA_DQ<9>")
	)
	(arc
		(start 392.29284 -227.819712)
		(mid 392.114027 -228.022062)
		(end 392.049508 -228.284278)
		(width 0.0889)
		(layer "In2.Cu")
		(net "M_I_CPU0_SA_DQ<9>")
	)
	(segment
		(start 377.107958 -230.169974)
		(end 377.57481 -229.904036)
		(width 0.10668)
		(layer "F.Cu")
		(net "M_I_CPU0_SA_DQ<8>")
	)
	(segment
		(start 394.183616 -222.952056)
		(end 394.212826 -222.935292)
		(width 0.0889)
		(layer "In2.Cu")
		(net "M_I_CPU0_SA_DQ<8>")
	)
	(segment
		(start 398.511268 -217.368374)
		(end 408.769566 -207.110076)
		(width 0.14478)
		(layer "In2.Cu")
		(net "M_I_CPU0_SA_DQ<8>")
	)
	(segment
		(start 377.420886 -230.169466)
		(end 377.443238 -230.252778)
		(width 0.0889)
		(layer "In2.Cu")
		(net "M_I_CPU0_SA_DQ<8>")
	)
	(segment
		(start 378.693426 -230.231442)
		(end 378.701808 -230.226616)
		(width 0.0889)
		(layer "In2.Cu")
		(net "M_I_CPU0_SA_DQ<8>")
	)
	(segment
		(start 379.63348 -230.231442)
		(end 379.641862 -230.226616)
		(width 0.0889)
		(layer "In2.Cu")
		(net "M_I_CPU0_SA_DQ<8>")
	)
	(segment
		(start 392.76274 -225.389694)
		(end 392.801856 -225.366834)
		(width 0.0889)
		(layer "In2.Cu")
		(net "M_I_CPU0_SA_DQ<8>")
	)
	(segment
		(start 392.801856 -225.366834)
		(end 392.837924 -225.346006)
		(width 0.0889)
		(layer "In2.Cu")
		(net "M_I_CPU0_SA_DQ<8>")
	)
	(segment
		(start 381.147828 -230.226616)
		(end 381.15621 -230.231442)
		(width 0.0889)
		(layer "In2.Cu")
		(net "M_I_CPU0_SA_DQ<8>")
	)
	(segment
		(start 393.74191 -223.746822)
		(end 393.77239 -223.729042)
		(width 0.0889)
		(layer "In2.Cu")
		(net "M_I_CPU0_SA_DQ<8>")
	)
	(segment
		(start 389.033512 -230.231442)
		(end 389.041894 -230.226616)
		(width 0.0889)
		(layer "In2.Cu")
		(net "M_I_CPU0_SA_DQ<8>")
	)
	(segment
		(start 389.981948 -230.226616)
		(end 390.012428 -230.208836)
		(width 0.0889)
		(layer "In2.Cu")
		(net "M_I_CPU0_SA_DQ<8>")
	)
	(segment
		(start 394.963142 -222.214948)
		(end 398.511268 -218.666822)
		(width 0.14478)
		(layer "In2.Cu")
		(net "M_I_CPU0_SA_DQ<8>")
	)
	(segment
		(start 408.769566 -207.110076)
		(end 414.114234 -207.110076)
		(width 0.14478)
		(layer "In2.Cu")
		(net "M_I_CPU0_SA_DQ<8>")
	)
	(segment
		(start 380.207774 -230.226616)
		(end 380.216156 -230.231442)
		(width 0.0889)
		(layer "In2.Cu")
		(net "M_I_CPU0_SA_DQ<8>")
	)
	(segment
		(start 392.331956 -226.17684)
		(end 392.362436 -226.15906)
		(width 0.0889)
		(layer "In2.Cu")
		(net "M_I_CPU0_SA_DQ<8>")
	)
	(segment
		(start 377.57481 -229.904036)
		(end 377.420886 -230.169466)
		(width 0.0889)
		(layer "In2.Cu")
		(net "M_I_CPU0_SA_DQ<8>")
	)
	(segment
		(start 391.391902 -227.796852)
		(end 391.422382 -227.779072)
		(width 0.0889)
		(layer "In2.Cu")
		(net "M_I_CPU0_SA_DQ<8>")
	)
	(segment
		(start 414.114234 -207.110076)
		(end 414.964118 -206.260192)
		(width 0.14478)
		(layer "In2.Cu")
		(net "M_I_CPU0_SA_DQ<8>")
	)
	(segment
		(start 393.272264 -224.556066)
		(end 393.307316 -224.535746)
		(width 0.0889)
		(layer "In2.Cu")
		(net "M_I_CPU0_SA_DQ<8>")
	)
	(segment
		(start 383.393442 -230.231442)
		(end 383.401824 -230.226616)
		(width 0.0889)
		(layer "In2.Cu")
		(net "M_I_CPU0_SA_DQ<8>")
	)
	(segment
		(start 390.451848 -229.41661)
		(end 390.485376 -229.397052)
		(width 0.0889)
		(layer "In2.Cu")
		(net "M_I_CPU0_SA_DQ<8>")
	)
	(segment
		(start 422.474644 -206.260192)
		(end 431.131218 -206.260192)
		(width 0.14478)
		(layer "In2.Cu")
		(net "M_I_CPU0_SA_DQ<8>")
	)
	(segment
		(start 389.607806 -230.226616)
		(end 389.616188 -230.231442)
		(width 0.0889)
		(layer "In2.Cu")
		(net "M_I_CPU0_SA_DQ<8>")
	)
	(segment
		(start 390.412732 -229.43947)
		(end 390.451848 -229.41661)
		(width 0.0889)
		(layer "In2.Cu")
		(net "M_I_CPU0_SA_DQ<8>")
	)
	(segment
		(start 421.62476 -207.110076)
		(end 422.474644 -206.260192)
		(width 0.14478)
		(layer "In2.Cu")
		(net "M_I_CPU0_SA_DQ<8>")
	)
	(segment
		(start 391.822686 -227.009706)
		(end 391.861802 -226.986846)
		(width 0.0889)
		(layer "In2.Cu")
		(net "M_I_CPU0_SA_DQ<8>")
	)
	(segment
		(start 393.223496 -224.584514)
		(end 393.272264 -224.556066)
		(width 0.0889)
		(layer "In2.Cu")
		(net "M_I_CPU0_SA_DQ<8>")
	)
	(segment
		(start 398.511268 -218.666822)
		(end 398.511268 -217.368374)
		(width 0.14478)
		(layer "In2.Cu")
		(net "M_I_CPU0_SA_DQ<8>")
	)
	(segment
		(start 417.716716 -206.260192)
		(end 418.5666 -207.110076)
		(width 0.14478)
		(layer "In2.Cu")
		(net "M_I_CPU0_SA_DQ<8>")
	)
	(segment
		(start 388.093458 -230.231442)
		(end 388.10184 -230.226616)
		(width 0.0889)
		(layer "In2.Cu")
		(net "M_I_CPU0_SA_DQ<8>")
	)
	(segment
		(start 390.921748 -228.606858)
		(end 390.953498 -228.58857)
		(width 0.0889)
		(layer "In2.Cu")
		(net "M_I_CPU0_SA_DQ<8>")
	)
	(segment
		(start 431.131218 -206.260192)
		(end 431.55616 -206.685134)
		(width 0.14478)
		(layer "In2.Cu")
		(net "M_I_CPU0_SA_DQ<8>")
	)
	(segment
		(start 384.90779 -230.226616)
		(end 384.916172 -230.231442)
		(width 0.0889)
		(layer "In2.Cu")
		(net "M_I_CPU0_SA_DQ<8>")
	)
	(segment
		(start 414.964118 -206.260192)
		(end 417.716716 -206.260192)
		(width 0.14478)
		(layer "In2.Cu")
		(net "M_I_CPU0_SA_DQ<8>")
	)
	(segment
		(start 392.29284 -226.1997)
		(end 392.331956 -226.17684)
		(width 0.0889)
		(layer "In2.Cu")
		(net "M_I_CPU0_SA_DQ<8>")
	)
	(segment
		(start 394.212826 -222.935292)
		(end 394.681456 -222.351854)
		(width 0.0889)
		(layer "In2.Cu")
		(net "M_I_CPU0_SA_DQ<8>")
	)
	(segment
		(start 394.681456 -222.351854)
		(end 394.963142 -222.214948)
		(width 0.0889)
		(layer "In2.Cu")
		(net "M_I_CPU0_SA_DQ<8>")
	)
	(segment
		(start 390.885426 -228.62794)
		(end 390.921748 -228.606858)
		(width 0.0889)
		(layer "In2.Cu")
		(net "M_I_CPU0_SA_DQ<8>")
	)
	(segment
		(start 391.352786 -227.819712)
		(end 391.391902 -227.796852)
		(width 0.0889)
		(layer "In2.Cu")
		(net "M_I_CPU0_SA_DQ<8>")
	)
	(segment
		(start 393.702794 -223.769682)
		(end 393.74191 -223.746822)
		(width 0.0889)
		(layer "In2.Cu")
		(net "M_I_CPU0_SA_DQ<8>")
	)
	(segment
		(start 418.5666 -207.110076)
		(end 421.62476 -207.110076)
		(width 0.14478)
		(layer "In2.Cu")
		(net "M_I_CPU0_SA_DQ<8>")
	)
	(segment
		(start 384.333496 -230.231442)
		(end 384.341878 -230.226616)
		(width 0.0889)
		(layer "In2.Cu")
		(net "M_I_CPU0_SA_DQ<8>")
	)
	(segment
		(start 391.861802 -226.986846)
		(end 391.893552 -226.968558)
		(width 0.0889)
		(layer "In2.Cu")
		(net "M_I_CPU0_SA_DQ<8>")
	)
	(segment
		(start 385.847844 -230.226616)
		(end 385.856226 -230.231442)
		(width 0.0889)
		(layer "In2.Cu")
		(net "M_I_CPU0_SA_DQ<8>")
	)
	(arc
		(start 390.012428 -230.208836)
		(mid 390.127855 -230.07546)
		(end 390.1694 -229.904036)
		(width 0.0889)
		(layer "In2.Cu")
		(net "M_I_CPU0_SA_DQ<8>")
	)
	(arc
		(start 377.443238 -230.252778)
		(mid 377.605427 -230.275513)
		(end 377.761754 -230.226616)
		(width 0.0889)
		(layer "In2.Cu")
		(net "M_I_CPU0_SA_DQ<8>")
	)
	(arc
		(start 383.967736 -230.226616)
		(mid 384.149987 -230.276966)
		(end 384.333496 -230.231442)
		(width 0.0889)
		(layer "In2.Cu")
		(net "M_I_CPU0_SA_DQ<8>")
	)
	(arc
		(start 390.639554 -229.094284)
		(mid 390.70479 -228.830693)
		(end 390.885426 -228.62794)
		(width 0.0889)
		(layer "In2.Cu")
		(net "M_I_CPU0_SA_DQ<8>")
	)
	(arc
		(start 388.667752 -230.226616)
		(mid 388.850003 -230.276966)
		(end 389.033512 -230.231442)
		(width 0.0889)
		(layer "In2.Cu")
		(net "M_I_CPU0_SA_DQ<8>")
	)
	(arc
		(start 390.485376 -229.397052)
		(mid 390.598783 -229.264163)
		(end 390.639554 -229.094284)
		(width 0.0889)
		(layer "In2.Cu")
		(net "M_I_CPU0_SA_DQ<8>")
	)
	(arc
		(start 393.459462 -224.234248)
		(mid 393.523977 -223.972029)
		(end 393.702794 -223.769682)
		(width 0.0889)
		(layer "In2.Cu")
		(net "M_I_CPU0_SA_DQ<8>")
	)
	(arc
		(start 392.362436 -226.15906)
		(mid 392.477863 -226.025684)
		(end 392.519408 -225.85426)
		(width 0.0889)
		(layer "In2.Cu")
		(net "M_I_CPU0_SA_DQ<8>")
	)
	(arc
		(start 391.893552 -226.968558)
		(mid 392.008228 -226.835224)
		(end 392.049508 -226.664266)
		(width 0.0889)
		(layer "In2.Cu")
		(net "M_I_CPU0_SA_DQ<8>")
	)
	(arc
		(start 391.579354 -227.474272)
		(mid 391.643869 -227.212053)
		(end 391.822686 -227.009706)
		(width 0.0889)
		(layer "In2.Cu")
		(net "M_I_CPU0_SA_DQ<8>")
	)
	(arc
		(start 387.727698 -230.226616)
		(mid 387.909949 -230.276966)
		(end 388.093458 -230.231442)
		(width 0.0889)
		(layer "In2.Cu")
		(net "M_I_CPU0_SA_DQ<8>")
	)
	(arc
		(start 383.401824 -230.226616)
		(mid 383.68478 -230.150473)
		(end 383.967736 -230.226616)
		(width 0.0889)
		(layer "In2.Cu")
		(net "M_I_CPU0_SA_DQ<8>")
	)
	(arc
		(start 379.641862 -230.226616)
		(mid 379.924818 -230.150473)
		(end 380.207774 -230.226616)
		(width 0.0889)
		(layer "In2.Cu")
		(net "M_I_CPU0_SA_DQ<8>")
	)
	(arc
		(start 390.953498 -228.58857)
		(mid 391.068174 -228.455236)
		(end 391.109454 -228.284278)
		(width 0.0889)
		(layer "In2.Cu")
		(net "M_I_CPU0_SA_DQ<8>")
	)
	(arc
		(start 387.161786 -230.226616)
		(mid 387.444742 -230.150473)
		(end 387.727698 -230.226616)
		(width 0.0889)
		(layer "In2.Cu")
		(net "M_I_CPU0_SA_DQ<8>")
	)
	(arc
		(start 393.929362 -223.424242)
		(mid 393.99696 -223.15609)
		(end 394.183616 -222.952056)
		(width 0.0889)
		(layer "In2.Cu")
		(net "M_I_CPU0_SA_DQ<8>")
	)
	(arc
		(start 386.221986 -230.226616)
		(mid 386.504942 -230.150473)
		(end 386.787898 -230.226616)
		(width 0.0889)
		(layer "In2.Cu")
		(net "M_I_CPU0_SA_DQ<8>")
	)
	(arc
		(start 379.26772 -230.226616)
		(mid 379.449971 -230.276966)
		(end 379.63348 -230.231442)
		(width 0.0889)
		(layer "In2.Cu")
		(net "M_I_CPU0_SA_DQ<8>")
	)
	(arc
		(start 388.10184 -230.226616)
		(mid 388.384796 -230.150473)
		(end 388.667752 -230.226616)
		(width 0.0889)
		(layer "In2.Cu")
		(net "M_I_CPU0_SA_DQ<8>")
	)
	(arc
		(start 383.027682 -230.226616)
		(mid 383.209933 -230.276966)
		(end 383.393442 -230.231442)
		(width 0.0889)
		(layer "In2.Cu")
		(net "M_I_CPU0_SA_DQ<8>")
	)
	(arc
		(start 385.856226 -230.231442)
		(mid 386.039734 -230.276936)
		(end 386.221986 -230.226616)
		(width 0.0889)
		(layer "In2.Cu")
		(net "M_I_CPU0_SA_DQ<8>")
	)
	(arc
		(start 389.616188 -230.231442)
		(mid 389.799696 -230.276936)
		(end 389.981948 -230.226616)
		(width 0.0889)
		(layer "In2.Cu")
		(net "M_I_CPU0_SA_DQ<8>")
	)
	(arc
		(start 378.327666 -230.226616)
		(mid 378.509917 -230.276966)
		(end 378.693426 -230.231442)
		(width 0.0889)
		(layer "In2.Cu")
		(net "M_I_CPU0_SA_DQ<8>")
	)
	(arc
		(start 381.15621 -230.231442)
		(mid 381.339718 -230.276936)
		(end 381.52197 -230.226616)
		(width 0.0889)
		(layer "In2.Cu")
		(net "M_I_CPU0_SA_DQ<8>")
	)
	(arc
		(start 382.087882 -230.226616)
		(mid 382.274826 -230.276871)
		(end 382.46177 -230.226616)
		(width 0.0889)
		(layer "In2.Cu")
		(net "M_I_CPU0_SA_DQ<8>")
	)
	(arc
		(start 385.281932 -230.226616)
		(mid 385.564888 -230.150473)
		(end 385.847844 -230.226616)
		(width 0.0889)
		(layer "In2.Cu")
		(net "M_I_CPU0_SA_DQ<8>")
	)
	(arc
		(start 393.77239 -223.729042)
		(mid 393.887817 -223.595666)
		(end 393.929362 -223.424242)
		(width 0.0889)
		(layer "In2.Cu")
		(net "M_I_CPU0_SA_DQ<8>")
	)
	(arc
		(start 377.761754 -230.226616)
		(mid 378.04471 -230.150473)
		(end 378.327666 -230.226616)
		(width 0.0889)
		(layer "In2.Cu")
		(net "M_I_CPU0_SA_DQ<8>")
	)
	(arc
		(start 393.307316 -224.535746)
		(mid 393.419241 -224.403095)
		(end 393.459462 -224.234248)
		(width 0.0889)
		(layer "In2.Cu")
		(net "M_I_CPU0_SA_DQ<8>")
	)
	(arc
		(start 380.216156 -230.231442)
		(mid 380.399664 -230.276936)
		(end 380.581916 -230.226616)
		(width 0.0889)
		(layer "In2.Cu")
		(net "M_I_CPU0_SA_DQ<8>")
	)
	(arc
		(start 381.52197 -230.226616)
		(mid 381.804926 -230.150473)
		(end 382.087882 -230.226616)
		(width 0.0889)
		(layer "In2.Cu")
		(net "M_I_CPU0_SA_DQ<8>")
	)
	(arc
		(start 380.581916 -230.226616)
		(mid 380.864872 -230.150473)
		(end 381.147828 -230.226616)
		(width 0.0889)
		(layer "In2.Cu")
		(net "M_I_CPU0_SA_DQ<8>")
	)
	(arc
		(start 384.341878 -230.226616)
		(mid 384.624834 -230.150473)
		(end 384.90779 -230.226616)
		(width 0.0889)
		(layer "In2.Cu")
		(net "M_I_CPU0_SA_DQ<8>")
	)
	(arc
		(start 390.1694 -229.904036)
		(mid 390.233915 -229.641817)
		(end 390.412732 -229.43947)
		(width 0.0889)
		(layer "In2.Cu")
		(net "M_I_CPU0_SA_DQ<8>")
	)
	(arc
		(start 392.519408 -225.85426)
		(mid 392.583923 -225.592041)
		(end 392.76274 -225.389694)
		(width 0.0889)
		(layer "In2.Cu")
		(net "M_I_CPU0_SA_DQ<8>")
	)
	(arc
		(start 392.837924 -225.346006)
		(mid 392.950039 -225.21301)
		(end 392.99007 -225.043746)
		(width 0.0889)
		(layer "In2.Cu")
		(net "M_I_CPU0_SA_DQ<8>")
	)
	(arc
		(start 391.109454 -228.284278)
		(mid 391.173969 -228.022059)
		(end 391.352786 -227.819712)
		(width 0.0889)
		(layer "In2.Cu")
		(net "M_I_CPU0_SA_DQ<8>")
	)
	(arc
		(start 392.99007 -225.043746)
		(mid 393.051506 -224.786035)
		(end 393.223496 -224.584514)
		(width 0.0889)
		(layer "In2.Cu")
		(net "M_I_CPU0_SA_DQ<8>")
	)
	(arc
		(start 391.422382 -227.779072)
		(mid 391.537809 -227.645696)
		(end 391.579354 -227.474272)
		(width 0.0889)
		(layer "In2.Cu")
		(net "M_I_CPU0_SA_DQ<8>")
	)
	(arc
		(start 386.787898 -230.226616)
		(mid 386.974842 -230.276871)
		(end 387.161786 -230.226616)
		(width 0.0889)
		(layer "In2.Cu")
		(net "M_I_CPU0_SA_DQ<8>")
	)
	(arc
		(start 382.46177 -230.226616)
		(mid 382.744726 -230.150473)
		(end 383.027682 -230.226616)
		(width 0.0889)
		(layer "In2.Cu")
		(net "M_I_CPU0_SA_DQ<8>")
	)
	(arc
		(start 392.049508 -226.664266)
		(mid 392.114023 -226.402047)
		(end 392.29284 -226.1997)
		(width 0.0889)
		(layer "In2.Cu")
		(net "M_I_CPU0_SA_DQ<8>")
	)
	(arc
		(start 389.041894 -230.226616)
		(mid 389.32485 -230.150473)
		(end 389.607806 -230.226616)
		(width 0.0889)
		(layer "In2.Cu")
		(net "M_I_CPU0_SA_DQ<8>")
	)
	(arc
		(start 378.701808 -230.226616)
		(mid 378.984764 -230.150473)
		(end 379.26772 -230.226616)
		(width 0.0889)
		(layer "In2.Cu")
		(net "M_I_CPU0_SA_DQ<8>")
	)
	(arc
		(start 384.916172 -230.231442)
		(mid 385.09968 -230.276936)
		(end 385.281932 -230.226616)
		(width 0.0889)
		(layer "In2.Cu")
		(net "M_I_CPU0_SA_DQ<8>")
	)
	(segment
		(start 375.22785 -230.169974)
		(end 375.694702 -229.904036)
		(width 0.10668)
		(layer "F.Cu")
		(net "M_I_CPU0_SA_DQ<7>")
	)
	(segment
		(start 425.532804 -205.024228)
		(end 425.695618 -205.187042)
		(width 0.14478)
		(layer "In2.Cu")
		(net "M_I_CPU0_SA_DQ<7>")
	)
	(segment
		(start 389.607806 -229.58171)
		(end 389.646922 -229.55885)
		(width 0.0889)
		(layer "In2.Cu")
		(net "M_I_CPU0_SA_DQ<7>")
	)
	(segment
		(start 393.88542 -222.513144)
		(end 394.781786 -221.616778)
		(width 0.14478)
		(layer "In2.Cu")
		(net "M_I_CPU0_SA_DQ<7>")
	)
	(segment
		(start 418.550852 -206.260192)
		(end 421.602408 -206.260192)
		(width 0.14478)
		(layer "In2.Cu")
		(net "M_I_CPU0_SA_DQ<7>")
	)
	(segment
		(start 417.700714 -205.410054)
		(end 418.550852 -206.260192)
		(width 0.14478)
		(layer "In2.Cu")
		(net "M_I_CPU0_SA_DQ<7>")
	)
	(segment
		(start 395.400022 -220.998542)
		(end 395.562074 -220.83649)
		(width 0.14478)
		(layer "In2.Cu")
		(net "M_I_CPU0_SA_DQ<7>")
	)
	(segment
		(start 396.400782 -219.105988)
		(end 396.732506 -219.437966)
		(width 0.14478)
		(layer "In2.Cu")
		(net "M_I_CPU0_SA_DQ<7>")
	)
	(segment
		(start 422.452546 -205.410054)
		(end 424.452034 -205.410054)
		(width 0.14478)
		(layer "In2.Cu")
		(net "M_I_CPU0_SA_DQ<7>")
	)
	(segment
		(start 383.393442 -229.576884)
		(end 383.401824 -229.58171)
		(width 0.0889)
		(layer "In2.Cu")
		(net "M_I_CPU0_SA_DQ<7>")
	)
	(segment
		(start 395.392402 -219.886276)
		(end 395.620494 -219.886276)
		(width 0.14478)
		(layer "In2.Cu")
		(net "M_I_CPU0_SA_DQ<7>")
	)
	(segment
		(start 425.858432 -205.703932)
		(end 426.089064 -205.703932)
		(width 0.14478)
		(layer "In2.Cu")
		(net "M_I_CPU0_SA_DQ<7>")
	)
	(segment
		(start 397.512794 -218.657678)
		(end 397.740886 -218.657678)
		(width 0.14478)
		(layer "In2.Cu")
		(net "M_I_CPU0_SA_DQ<7>")
	)
	(segment
		(start 395.562074 -220.608398)
		(end 395.23035 -220.27642)
		(width 0.14478)
		(layer "In2.Cu")
		(net "M_I_CPU0_SA_DQ<7>")
	)
	(segment
		(start 395.620494 -219.886276)
		(end 395.952218 -220.218254)
		(width 0.14478)
		(layer "In2.Cu")
		(net "M_I_CPU0_SA_DQ<7>")
	)
	(segment
		(start 395.952218 -220.218254)
		(end 396.18031 -220.218254)
		(width 0.14478)
		(layer "In2.Cu")
		(net "M_I_CPU0_SA_DQ<7>")
	)
	(segment
		(start 425.302172 -205.024228)
		(end 425.532804 -205.024228)
		(width 0.14478)
		(layer "In2.Cu")
		(net "M_I_CPU0_SA_DQ<7>")
	)
	(segment
		(start 397.960088 -218.438476)
		(end 397.960088 -217.140028)
		(width 0.14478)
		(layer "In2.Cu")
		(net "M_I_CPU0_SA_DQ<7>")
	)
	(segment
		(start 392.897868 -223.911668)
		(end 392.93419 -223.890586)
		(width 0.0889)
		(layer "In2.Cu")
		(net "M_I_CPU0_SA_DQ<7>")
	)
	(segment
		(start 425.695618 -205.541118)
		(end 425.858432 -205.703932)
		(width 0.14478)
		(layer "In2.Cu")
		(net "M_I_CPU0_SA_DQ<7>")
	)
	(segment
		(start 388.093458 -229.576884)
		(end 388.10184 -229.58171)
		(width 0.0889)
		(layer "In2.Cu")
		(net "M_I_CPU0_SA_DQ<7>")
	)
	(segment
		(start 389.033512 -229.576884)
		(end 389.041894 -229.58171)
		(width 0.0889)
		(layer "In2.Cu")
		(net "M_I_CPU0_SA_DQ<7>")
	)
	(segment
		(start 376.447812 -229.58171)
		(end 376.456194 -229.576884)
		(width 0.0889)
		(layer "In2.Cu")
		(net "M_I_CPU0_SA_DQ<7>")
	)
	(segment
		(start 396.342362 -220.056202)
		(end 396.342362 -219.82811)
		(width 0.14478)
		(layer "In2.Cu")
		(net "M_I_CPU0_SA_DQ<7>")
	)
	(segment
		(start 396.18031 -220.218254)
		(end 396.342362 -220.056202)
		(width 0.14478)
		(layer "In2.Cu")
		(net "M_I_CPU0_SA_DQ<7>")
	)
	(segment
		(start 424.452034 -205.410054)
		(end 424.745912 -205.703932)
		(width 0.14478)
		(layer "In2.Cu")
		(net "M_I_CPU0_SA_DQ<7>")
	)
	(segment
		(start 396.342362 -219.82811)
		(end 396.010638 -219.496132)
		(width 0.14478)
		(layer "In2.Cu")
		(net "M_I_CPU0_SA_DQ<7>")
	)
	(segment
		(start 395.23035 -220.27642)
		(end 395.23035 -220.048328)
		(width 0.14478)
		(layer "In2.Cu")
		(net "M_I_CPU0_SA_DQ<7>")
	)
	(segment
		(start 375.694702 -229.904036)
		(end 375.84888 -229.638606)
		(width 0.0889)
		(layer "In2.Cu")
		(net "M_I_CPU0_SA_DQ<7>")
	)
	(segment
		(start 396.952978 -218.3257)
		(end 397.18107 -218.3257)
		(width 0.14478)
		(layer "In2.Cu")
		(net "M_I_CPU0_SA_DQ<7>")
	)
	(segment
		(start 414.005522 -206.260192)
		(end 414.85566 -205.410054)
		(width 0.14478)
		(layer "In2.Cu")
		(net "M_I_CPU0_SA_DQ<7>")
	)
	(segment
		(start 380.207774 -229.58171)
		(end 380.216156 -229.576884)
		(width 0.0889)
		(layer "In2.Cu")
		(net "M_I_CPU0_SA_DQ<7>")
	)
	(segment
		(start 390.047226 -228.789484)
		(end 390.077706 -228.771704)
		(width 0.0889)
		(layer "In2.Cu")
		(net "M_I_CPU0_SA_DQ<7>")
	)
	(segment
		(start 393.361672 -223.107758)
		(end 393.43965 -223.062038)
		(width 0.0889)
		(layer "In2.Cu")
		(net "M_I_CPU0_SA_DQ<7>")
	)
	(segment
		(start 390.51611 -227.979986)
		(end 390.54786 -227.961698)
		(width 0.0889)
		(layer "In2.Cu")
		(net "M_I_CPU0_SA_DQ<7>")
	)
	(segment
		(start 392.427714 -224.721674)
		(end 392.46683 -224.698814)
		(width 0.0889)
		(layer "In2.Cu")
		(net "M_I_CPU0_SA_DQ<7>")
	)
	(segment
		(start 397.12265 -219.047822)
		(end 396.790926 -218.715844)
		(width 0.14478)
		(layer "In2.Cu")
		(net "M_I_CPU0_SA_DQ<7>")
	)
	(segment
		(start 391.45718 -226.359466)
		(end 391.48766 -226.341686)
		(width 0.0889)
		(layer "In2.Cu")
		(net "M_I_CPU0_SA_DQ<7>")
	)
	(segment
		(start 424.976544 -205.703932)
		(end 425.139358 -205.541118)
		(width 0.14478)
		(layer "In2.Cu")
		(net "M_I_CPU0_SA_DQ<7>")
	)
	(segment
		(start 394.840206 -220.666564)
		(end 395.17193 -220.998542)
		(width 0.14478)
		(layer "In2.Cu")
		(net "M_I_CPU0_SA_DQ<7>")
	)
	(segment
		(start 425.695618 -205.187042)
		(end 425.695618 -205.541118)
		(width 0.14478)
		(layer "In2.Cu")
		(net "M_I_CPU0_SA_DQ<7>")
	)
	(segment
		(start 390.54786 -227.961698)
		(end 390.584182 -227.940616)
		(width 0.0889)
		(layer "In2.Cu")
		(net "M_I_CPU0_SA_DQ<7>")
	)
	(segment
		(start 396.010638 -219.26804)
		(end 396.17269 -219.105988)
		(width 0.14478)
		(layer "In2.Cu")
		(net "M_I_CPU0_SA_DQ<7>")
	)
	(segment
		(start 394.612114 -220.666564)
		(end 394.840206 -220.666564)
		(width 0.14478)
		(layer "In2.Cu")
		(net "M_I_CPU0_SA_DQ<7>")
	)
	(segment
		(start 385.847844 -229.58171)
		(end 385.856226 -229.576884)
		(width 0.0889)
		(layer "In2.Cu")
		(net "M_I_CPU0_SA_DQ<7>")
	)
	(segment
		(start 391.957814 -225.53168)
		(end 391.99693 -225.50882)
		(width 0.0889)
		(layer "In2.Cu")
		(net "M_I_CPU0_SA_DQ<7>")
	)
	(segment
		(start 421.602408 -206.260192)
		(end 422.452546 -205.410054)
		(width 0.14478)
		(layer "In2.Cu")
		(net "M_I_CPU0_SA_DQ<7>")
	)
	(segment
		(start 395.23035 -220.048328)
		(end 395.392402 -219.886276)
		(width 0.14478)
		(layer "In2.Cu")
		(net "M_I_CPU0_SA_DQ<7>")
	)
	(segment
		(start 394.450062 -221.056708)
		(end 394.450062 -220.828616)
		(width 0.14478)
		(layer "In2.Cu")
		(net "M_I_CPU0_SA_DQ<7>")
	)
	(segment
		(start 393.43965 -223.062038)
		(end 393.454382 -223.05137)
		(width 0.0889)
		(layer "In2.Cu")
		(net "M_I_CPU0_SA_DQ<7>")
	)
	(segment
		(start 384.90779 -229.58171)
		(end 384.916172 -229.576884)
		(width 0.0889)
		(layer "In2.Cu")
		(net "M_I_CPU0_SA_DQ<7>")
	)
	(segment
		(start 426.251878 -205.187042)
		(end 426.414692 -205.024228)
		(width 0.14478)
		(layer "In2.Cu")
		(net "M_I_CPU0_SA_DQ<7>")
	)
	(segment
		(start 396.732506 -219.437966)
		(end 396.960598 -219.437966)
		(width 0.14478)
		(layer "In2.Cu")
		(net "M_I_CPU0_SA_DQ<7>")
	)
	(segment
		(start 395.562074 -220.83649)
		(end 395.562074 -220.608398)
		(width 0.14478)
		(layer "In2.Cu")
		(net "M_I_CPU0_SA_DQ<7>")
	)
	(segment
		(start 394.781786 -221.616778)
		(end 394.781786 -221.388686)
		(width 0.14478)
		(layer "In2.Cu")
		(net "M_I_CPU0_SA_DQ<7>")
	)
	(segment
		(start 392.866118 -223.929956)
		(end 392.897868 -223.911668)
		(width 0.0889)
		(layer "In2.Cu")
		(net "M_I_CPU0_SA_DQ<7>")
	)
	(segment
		(start 425.139358 -205.541118)
		(end 425.139358 -205.187042)
		(width 0.14478)
		(layer "In2.Cu")
		(net "M_I_CPU0_SA_DQ<7>")
	)
	(segment
		(start 396.790926 -218.715844)
		(end 396.790926 -218.487752)
		(width 0.14478)
		(layer "In2.Cu")
		(net "M_I_CPU0_SA_DQ<7>")
	)
	(segment
		(start 396.960598 -219.437966)
		(end 397.12265 -219.275914)
		(width 0.14478)
		(layer "In2.Cu")
		(net "M_I_CPU0_SA_DQ<7>")
	)
	(segment
		(start 397.740886 -218.657678)
		(end 397.960088 -218.438476)
		(width 0.14478)
		(layer "In2.Cu")
		(net "M_I_CPU0_SA_DQ<7>")
	)
	(segment
		(start 391.48766 -226.341686)
		(end 391.526776 -226.318826)
		(width 0.0889)
		(layer "In2.Cu")
		(net "M_I_CPU0_SA_DQ<7>")
	)
	(segment
		(start 391.01776 -227.151692)
		(end 391.056876 -227.128832)
		(width 0.0889)
		(layer "In2.Cu")
		(net "M_I_CPU0_SA_DQ<7>")
	)
	(segment
		(start 408.839924 -206.260192)
		(end 414.005522 -206.260192)
		(width 0.14478)
		(layer "In2.Cu")
		(net "M_I_CPU0_SA_DQ<7>")
	)
	(segment
		(start 426.251878 -205.541118)
		(end 426.251878 -205.187042)
		(width 0.14478)
		(layer "In2.Cu")
		(net "M_I_CPU0_SA_DQ<7>")
	)
	(segment
		(start 375.84888 -229.638606)
		(end 375.944638 -229.613206)
		(width 0.0889)
		(layer "In2.Cu")
		(net "M_I_CPU0_SA_DQ<7>")
	)
	(segment
		(start 394.781786 -221.388686)
		(end 394.450062 -221.056708)
		(width 0.14478)
		(layer "In2.Cu")
		(net "M_I_CPU0_SA_DQ<7>")
	)
	(segment
		(start 426.089064 -205.703932)
		(end 426.251878 -205.541118)
		(width 0.14478)
		(layer "In2.Cu")
		(net "M_I_CPU0_SA_DQ<7>")
	)
	(segment
		(start 391.926064 -225.549968)
		(end 391.957814 -225.53168)
		(width 0.0889)
		(layer "In2.Cu")
		(net "M_I_CPU0_SA_DQ<7>")
	)
	(segment
		(start 426.414692 -205.024228)
		(end 426.645324 -205.024228)
		(width 0.14478)
		(layer "In2.Cu")
		(net "M_I_CPU0_SA_DQ<7>")
	)
	(segment
		(start 384.333496 -229.576884)
		(end 384.341878 -229.58171)
		(width 0.0889)
		(layer "In2.Cu")
		(net "M_I_CPU0_SA_DQ<7>")
	)
	(segment
		(start 395.17193 -220.998542)
		(end 395.400022 -220.998542)
		(width 0.14478)
		(layer "In2.Cu")
		(net "M_I_CPU0_SA_DQ<7>")
	)
	(segment
		(start 381.147828 -229.58171)
		(end 381.15621 -229.576884)
		(width 0.0889)
		(layer "In2.Cu")
		(net "M_I_CPU0_SA_DQ<7>")
	)
	(segment
		(start 397.12265 -219.275914)
		(end 397.12265 -219.047822)
		(width 0.14478)
		(layer "In2.Cu")
		(net "M_I_CPU0_SA_DQ<7>")
	)
	(segment
		(start 414.85566 -205.410054)
		(end 417.700714 -205.410054)
		(width 0.14478)
		(layer "In2.Cu")
		(net "M_I_CPU0_SA_DQ<7>")
	)
	(segment
		(start 396.790926 -218.487752)
		(end 396.952978 -218.3257)
		(width 0.14478)
		(layer "In2.Cu")
		(net "M_I_CPU0_SA_DQ<7>")
	)
	(segment
		(start 392.397234 -224.739454)
		(end 392.427714 -224.721674)
		(width 0.0889)
		(layer "In2.Cu")
		(net "M_I_CPU0_SA_DQ<7>")
	)
	(segment
		(start 425.139358 -205.187042)
		(end 425.302172 -205.024228)
		(width 0.14478)
		(layer "In2.Cu")
		(net "M_I_CPU0_SA_DQ<7>")
	)
	(segment
		(start 378.693426 -229.576884)
		(end 378.701808 -229.58171)
		(width 0.0889)
		(layer "In2.Cu")
		(net "M_I_CPU0_SA_DQ<7>")
	)
	(segment
		(start 397.18107 -218.3257)
		(end 397.512794 -218.657678)
		(width 0.14478)
		(layer "In2.Cu")
		(net "M_I_CPU0_SA_DQ<7>")
	)
	(segment
		(start 379.63348 -229.576884)
		(end 379.641862 -229.58171)
		(width 0.0889)
		(layer "In2.Cu")
		(net "M_I_CPU0_SA_DQ<7>")
	)
	(segment
		(start 396.17269 -219.105988)
		(end 396.400782 -219.105988)
		(width 0.14478)
		(layer "In2.Cu")
		(net "M_I_CPU0_SA_DQ<7>")
	)
	(segment
		(start 390.077706 -228.771704)
		(end 390.116822 -228.748844)
		(width 0.0889)
		(layer "In2.Cu")
		(net "M_I_CPU0_SA_DQ<7>")
	)
	(segment
		(start 394.450062 -220.828616)
		(end 394.612114 -220.666564)
		(width 0.14478)
		(layer "In2.Cu")
		(net "M_I_CPU0_SA_DQ<7>")
	)
	(segment
		(start 397.960088 -217.140028)
		(end 408.839924 -206.260192)
		(width 0.14478)
		(layer "In2.Cu")
		(net "M_I_CPU0_SA_DQ<7>")
	)
	(segment
		(start 393.504928 -223.000824)
		(end 393.88542 -222.513144)
		(width 0.0889)
		(layer "In2.Cu")
		(net "M_I_CPU0_SA_DQ<7>")
	)
	(segment
		(start 426.645324 -205.024228)
		(end 427.456092 -205.834996)
		(width 0.14478)
		(layer "In2.Cu")
		(net "M_I_CPU0_SA_DQ<7>")
	)
	(segment
		(start 396.010638 -219.496132)
		(end 396.010638 -219.26804)
		(width 0.14478)
		(layer "In2.Cu")
		(net "M_I_CPU0_SA_DQ<7>")
	)
	(segment
		(start 390.98601 -227.16998)
		(end 391.01776 -227.151692)
		(width 0.0889)
		(layer "In2.Cu")
		(net "M_I_CPU0_SA_DQ<7>")
	)
	(segment
		(start 424.745912 -205.703932)
		(end 424.976544 -205.703932)
		(width 0.14478)
		(layer "In2.Cu")
		(net "M_I_CPU0_SA_DQ<7>")
	)
	(arc
		(start 391.99693 -225.50882)
		(mid 392.175743 -225.30647)
		(end 392.240262 -225.044254)
		(width 0.0889)
		(layer "In2.Cu")
		(net "M_I_CPU0_SA_DQ<7>")
	)
	(arc
		(start 381.15621 -229.576884)
		(mid 381.339718 -229.531359)
		(end 381.52197 -229.58171)
		(width 0.0889)
		(layer "In2.Cu")
		(net "M_I_CPU0_SA_DQ<7>")
	)
	(arc
		(start 392.46683 -224.698814)
		(mid 392.645643 -224.496464)
		(end 392.710162 -224.234248)
		(width 0.0889)
		(layer "In2.Cu")
		(net "M_I_CPU0_SA_DQ<7>")
	)
	(arc
		(start 376.456194 -229.576884)
		(mid 376.639702 -229.531359)
		(end 376.821954 -229.58171)
		(width 0.0889)
		(layer "In2.Cu")
		(net "M_I_CPU0_SA_DQ<7>")
	)
	(arc
		(start 381.52197 -229.58171)
		(mid 381.804926 -229.657887)
		(end 382.087882 -229.58171)
		(width 0.0889)
		(layer "In2.Cu")
		(net "M_I_CPU0_SA_DQ<7>")
	)
	(arc
		(start 377.387866 -229.58171)
		(mid 377.57481 -229.531421)
		(end 377.761754 -229.58171)
		(width 0.0889)
		(layer "In2.Cu")
		(net "M_I_CPU0_SA_DQ<7>")
	)
	(arc
		(start 390.116822 -228.748844)
		(mid 390.295635 -228.546494)
		(end 390.360154 -228.284278)
		(width 0.0889)
		(layer "In2.Cu")
		(net "M_I_CPU0_SA_DQ<7>")
	)
	(arc
		(start 387.727698 -229.58171)
		(mid 387.909949 -229.531326)
		(end 388.093458 -229.576884)
		(width 0.0889)
		(layer "In2.Cu")
		(net "M_I_CPU0_SA_DQ<7>")
	)
	(arc
		(start 386.221986 -229.58171)
		(mid 386.504942 -229.657887)
		(end 386.787898 -229.58171)
		(width 0.0889)
		(layer "In2.Cu")
		(net "M_I_CPU0_SA_DQ<7>")
	)
	(arc
		(start 382.46177 -229.58171)
		(mid 382.744726 -229.657887)
		(end 383.027682 -229.58171)
		(width 0.0889)
		(layer "In2.Cu")
		(net "M_I_CPU0_SA_DQ<7>")
	)
	(arc
		(start 393.180062 -223.424242)
		(mid 393.228694 -223.241803)
		(end 393.361672 -223.107758)
		(width 0.0889)
		(layer "In2.Cu")
		(net "M_I_CPU0_SA_DQ<7>")
	)
	(arc
		(start 392.710162 -224.234248)
		(mid 392.751417 -224.063277)
		(end 392.866118 -223.929956)
		(width 0.0889)
		(layer "In2.Cu")
		(net "M_I_CPU0_SA_DQ<7>")
	)
	(arc
		(start 391.526776 -226.318826)
		(mid 391.705589 -226.116476)
		(end 391.770108 -225.85426)
		(width 0.0889)
		(layer "In2.Cu")
		(net "M_I_CPU0_SA_DQ<7>")
	)
	(arc
		(start 378.701808 -229.58171)
		(mid 378.984764 -229.657887)
		(end 379.26772 -229.58171)
		(width 0.0889)
		(layer "In2.Cu")
		(net "M_I_CPU0_SA_DQ<7>")
	)
	(arc
		(start 378.327666 -229.58171)
		(mid 378.509917 -229.531326)
		(end 378.693426 -229.576884)
		(width 0.0889)
		(layer "In2.Cu")
		(net "M_I_CPU0_SA_DQ<7>")
	)
	(arc
		(start 379.641862 -229.58171)
		(mid 379.924818 -229.657887)
		(end 380.207774 -229.58171)
		(width 0.0889)
		(layer "In2.Cu")
		(net "M_I_CPU0_SA_DQ<7>")
	)
	(arc
		(start 383.401824 -229.58171)
		(mid 383.68478 -229.657887)
		(end 383.967736 -229.58171)
		(width 0.0889)
		(layer "In2.Cu")
		(net "M_I_CPU0_SA_DQ<7>")
	)
	(arc
		(start 377.761754 -229.58171)
		(mid 378.04471 -229.657887)
		(end 378.327666 -229.58171)
		(width 0.0889)
		(layer "In2.Cu")
		(net "M_I_CPU0_SA_DQ<7>")
	)
	(arc
		(start 391.056876 -227.128832)
		(mid 391.235689 -226.926482)
		(end 391.300208 -226.664266)
		(width 0.0889)
		(layer "In2.Cu")
		(net "M_I_CPU0_SA_DQ<7>")
	)
	(arc
		(start 391.300208 -226.664266)
		(mid 391.341757 -226.492844)
		(end 391.45718 -226.359466)
		(width 0.0889)
		(layer "In2.Cu")
		(net "M_I_CPU0_SA_DQ<7>")
	)
	(arc
		(start 389.041894 -229.58171)
		(mid 389.32485 -229.657887)
		(end 389.607806 -229.58171)
		(width 0.0889)
		(layer "In2.Cu")
		(net "M_I_CPU0_SA_DQ<7>")
	)
	(arc
		(start 380.216156 -229.576884)
		(mid 380.399664 -229.531359)
		(end 380.581916 -229.58171)
		(width 0.0889)
		(layer "In2.Cu")
		(net "M_I_CPU0_SA_DQ<7>")
	)
	(arc
		(start 388.667752 -229.58171)
		(mid 388.850003 -229.531326)
		(end 389.033512 -229.576884)
		(width 0.0889)
		(layer "In2.Cu")
		(net "M_I_CPU0_SA_DQ<7>")
	)
	(arc
		(start 375.944638 -229.613206)
		(mid 376.19996 -229.656906)
		(end 376.447812 -229.58171)
		(width 0.0889)
		(layer "In2.Cu")
		(net "M_I_CPU0_SA_DQ<7>")
	)
	(arc
		(start 390.584182 -227.940616)
		(mid 390.764834 -227.737871)
		(end 390.830054 -227.474272)
		(width 0.0889)
		(layer "In2.Cu")
		(net "M_I_CPU0_SA_DQ<7>")
	)
	(arc
		(start 390.830054 -227.474272)
		(mid 390.871309 -227.303301)
		(end 390.98601 -227.16998)
		(width 0.0889)
		(layer "In2.Cu")
		(net "M_I_CPU0_SA_DQ<7>")
	)
	(arc
		(start 387.161786 -229.58171)
		(mid 387.444742 -229.657887)
		(end 387.727698 -229.58171)
		(width 0.0889)
		(layer "In2.Cu")
		(net "M_I_CPU0_SA_DQ<7>")
	)
	(arc
		(start 379.26772 -229.58171)
		(mid 379.449971 -229.531326)
		(end 379.63348 -229.576884)
		(width 0.0889)
		(layer "In2.Cu")
		(net "M_I_CPU0_SA_DQ<7>")
	)
	(arc
		(start 384.341878 -229.58171)
		(mid 384.624834 -229.657887)
		(end 384.90779 -229.58171)
		(width 0.0889)
		(layer "In2.Cu")
		(net "M_I_CPU0_SA_DQ<7>")
	)
	(arc
		(start 383.027682 -229.58171)
		(mid 383.209933 -229.531326)
		(end 383.393442 -229.576884)
		(width 0.0889)
		(layer "In2.Cu")
		(net "M_I_CPU0_SA_DQ<7>")
	)
	(arc
		(start 385.856226 -229.576884)
		(mid 386.039734 -229.531359)
		(end 386.221986 -229.58171)
		(width 0.0889)
		(layer "In2.Cu")
		(net "M_I_CPU0_SA_DQ<7>")
	)
	(arc
		(start 386.787898 -229.58171)
		(mid 386.974842 -229.531421)
		(end 387.161786 -229.58171)
		(width 0.0889)
		(layer "In2.Cu")
		(net "M_I_CPU0_SA_DQ<7>")
	)
	(arc
		(start 391.770108 -225.85426)
		(mid 391.811363 -225.683289)
		(end 391.926064 -225.549968)
		(width 0.0889)
		(layer "In2.Cu")
		(net "M_I_CPU0_SA_DQ<7>")
	)
	(arc
		(start 392.93419 -223.890586)
		(mid 393.114842 -223.687841)
		(end 393.180062 -223.424242)
		(width 0.0889)
		(layer "In2.Cu")
		(net "M_I_CPU0_SA_DQ<7>")
	)
	(arc
		(start 389.646922 -229.55885)
		(mid 389.825735 -229.3565)
		(end 389.890254 -229.094284)
		(width 0.0889)
		(layer "In2.Cu")
		(net "M_I_CPU0_SA_DQ<7>")
	)
	(arc
		(start 380.581916 -229.58171)
		(mid 380.864872 -229.657887)
		(end 381.147828 -229.58171)
		(width 0.0889)
		(layer "In2.Cu")
		(net "M_I_CPU0_SA_DQ<7>")
	)
	(arc
		(start 385.281932 -229.58171)
		(mid 385.564888 -229.657887)
		(end 385.847844 -229.58171)
		(width 0.0889)
		(layer "In2.Cu")
		(net "M_I_CPU0_SA_DQ<7>")
	)
	(arc
		(start 392.240262 -225.044254)
		(mid 392.281811 -224.872832)
		(end 392.397234 -224.739454)
		(width 0.0889)
		(layer "In2.Cu")
		(net "M_I_CPU0_SA_DQ<7>")
	)
	(arc
		(start 383.967736 -229.58171)
		(mid 384.149987 -229.531326)
		(end 384.333496 -229.576884)
		(width 0.0889)
		(layer "In2.Cu")
		(net "M_I_CPU0_SA_DQ<7>")
	)
	(arc
		(start 382.087882 -229.58171)
		(mid 382.274826 -229.531421)
		(end 382.46177 -229.58171)
		(width 0.0889)
		(layer "In2.Cu")
		(net "M_I_CPU0_SA_DQ<7>")
	)
	(arc
		(start 376.821954 -229.58171)
		(mid 377.10491 -229.657887)
		(end 377.387866 -229.58171)
		(width 0.0889)
		(layer "In2.Cu")
		(net "M_I_CPU0_SA_DQ<7>")
	)
	(arc
		(start 389.890254 -229.094284)
		(mid 389.931803 -228.922862)
		(end 390.047226 -228.789484)
		(width 0.0889)
		(layer "In2.Cu")
		(net "M_I_CPU0_SA_DQ<7>")
	)
	(arc
		(start 388.10184 -229.58171)
		(mid 388.384796 -229.657887)
		(end 388.667752 -229.58171)
		(width 0.0889)
		(layer "In2.Cu")
		(net "M_I_CPU0_SA_DQ<7>")
	)
	(arc
		(start 384.916172 -229.576884)
		(mid 385.09968 -229.531359)
		(end 385.281932 -229.58171)
		(width 0.0889)
		(layer "In2.Cu")
		(net "M_I_CPU0_SA_DQ<7>")
	)
	(arc
		(start 393.454382 -223.05137)
		(mid 393.481247 -223.027689)
		(end 393.504928 -223.000824)
		(width 0.0889)
		(layer "In2.Cu")
		(net "M_I_CPU0_SA_DQ<7>")
	)
	(arc
		(start 390.360154 -228.284278)
		(mid 390.401409 -228.113307)
		(end 390.51611 -227.979986)
		(width 0.0889)
		(layer "In2.Cu")
		(net "M_I_CPU0_SA_DQ<7>")
	)
	(segment
		(start 376.638058 -229.360222)
		(end 377.10491 -229.094284)
		(width 0.10668)
		(layer "F.Cu")
		(net "M_I_CPU0_SA_DQ<6>")
	)
	(segment
		(start 405.868378 -207.959452)
		(end 406.029922 -207.797908)
		(width 0.14478)
		(layer "In2.Cu")
		(net "M_I_CPU0_SA_DQ<6>")
	)
	(segment
		(start 406.81021 -206.78902)
		(end 406.55494 -206.53375)
		(width 0.14478)
		(layer "In2.Cu")
		(net "M_I_CPU0_SA_DQ<6>")
	)
	(segment
		(start 408.115516 -204.973174)
		(end 408.115516 -204.744574)
		(width 0.14478)
		(layer "In2.Cu")
		(net "M_I_CPU0_SA_DQ<6>")
	)
	(segment
		(start 390.54786 -226.341686)
		(end 390.584182 -226.320604)
		(width 0.0889)
		(layer "In2.Cu")
		(net "M_I_CPU0_SA_DQ<6>")
	)
	(segment
		(start 391.48766 -224.721674)
		(end 391.526776 -224.698814)
		(width 0.0889)
		(layer "In2.Cu")
		(net "M_I_CPU0_SA_DQ<6>")
	)
	(segment
		(start 381.983488 -228.766878)
		(end 381.99187 -228.771704)
		(width 0.0889)
		(layer "In2.Cu")
		(net "M_I_CPU0_SA_DQ<6>")
	)
	(segment
		(start 383.497836 -228.771704)
		(end 383.506218 -228.766878)
		(width 0.0889)
		(layer "In2.Cu")
		(net "M_I_CPU0_SA_DQ<6>")
	)
	(segment
		(start 406.716484 -206.143606)
		(end 406.945084 -206.143606)
		(width 0.14478)
		(layer "In2.Cu")
		(net "M_I_CPU0_SA_DQ<6>")
	)
	(segment
		(start 392.427714 -223.101662)
		(end 392.460988 -223.082358)
		(width 0.0889)
		(layer "In2.Cu")
		(net "M_I_CPU0_SA_DQ<6>")
	)
	(segment
		(start 377.10491 -229.094284)
		(end 377.258834 -228.828854)
		(width 0.0889)
		(layer "In2.Cu")
		(net "M_I_CPU0_SA_DQ<6>")
	)
	(segment
		(start 407.590498 -206.008732)
		(end 407.335228 -205.753462)
		(width 0.14478)
		(layer "In2.Cu")
		(net "M_I_CPU0_SA_DQ<6>")
	)
	(segment
		(start 425.695618 -203.524866)
		(end 425.695618 -203.942696)
		(width 0.14478)
		(layer "In2.Cu")
		(net "M_I_CPU0_SA_DQ<6>")
	)
	(segment
		(start 393.449302 -221.703392)
		(end 393.449302 -221.185232)
		(width 0.0889)
		(layer "In2.Cu")
		(net "M_I_CPU0_SA_DQ<6>")
	)
	(segment
		(start 426.645324 -203.324206)
		(end 427.456092 -204.134974)
		(width 0.14478)
		(layer "In2.Cu")
		(net "M_I_CPU0_SA_DQ<6>")
	)
	(segment
		(start 426.251878 -203.942696)
		(end 426.251878 -203.48702)
		(width 0.14478)
		(layer "In2.Cu")
		(net "M_I_CPU0_SA_DQ<6>")
	)
	(segment
		(start 405.936196 -206.923894)
		(end 406.164796 -206.923894)
		(width 0.14478)
		(layer "In2.Cu")
		(net "M_I_CPU0_SA_DQ<6>")
	)
	(segment
		(start 424.350434 -203.710032)
		(end 424.745912 -204.10551)
		(width 0.14478)
		(layer "In2.Cu")
		(net "M_I_CPU0_SA_DQ<6>")
	)
	(segment
		(start 417.528756 -203.710032)
		(end 418.378894 -204.56017)
		(width 0.14478)
		(layer "In2.Cu")
		(net "M_I_CPU0_SA_DQ<6>")
	)
	(segment
		(start 406.420066 -207.179164)
		(end 406.648666 -207.179164)
		(width 0.14478)
		(layer "In2.Cu")
		(net "M_I_CPU0_SA_DQ<6>")
	)
	(segment
		(start 408.76093 -204.8383)
		(end 408.98953 -204.8383)
		(width 0.14478)
		(layer "In2.Cu")
		(net "M_I_CPU0_SA_DQ<6>")
	)
	(segment
		(start 405.774652 -207.314038)
		(end 405.774652 -207.085438)
		(width 0.14478)
		(layer "In2.Cu")
		(net "M_I_CPU0_SA_DQ<6>")
	)
	(segment
		(start 392.397234 -223.119442)
		(end 392.427714 -223.101662)
		(width 0.0889)
		(layer "In2.Cu")
		(net "M_I_CPU0_SA_DQ<6>")
	)
	(segment
		(start 422.286938 -203.710032)
		(end 424.350434 -203.710032)
		(width 0.14478)
		(layer "In2.Cu")
		(net "M_I_CPU0_SA_DQ<6>")
	)
	(segment
		(start 391.957814 -223.911668)
		(end 391.99693 -223.888808)
		(width 0.0889)
		(layer "In2.Cu")
		(net "M_I_CPU0_SA_DQ<6>")
	)
	(segment
		(start 407.428954 -206.398876)
		(end 407.590498 -206.237332)
		(width 0.14478)
		(layer "In2.Cu")
		(net "M_I_CPU0_SA_DQ<6>")
	)
	(segment
		(start 421.4368 -204.56017)
		(end 422.286938 -203.710032)
		(width 0.14478)
		(layer "In2.Cu")
		(net "M_I_CPU0_SA_DQ<6>")
	)
	(segment
		(start 406.648666 -207.179164)
		(end 406.81021 -207.01762)
		(width 0.14478)
		(layer "In2.Cu")
		(net "M_I_CPU0_SA_DQ<6>")
	)
	(segment
		(start 408.50566 -204.58303)
		(end 408.76093 -204.8383)
		(width 0.14478)
		(layer "In2.Cu")
		(net "M_I_CPU0_SA_DQ<6>")
	)
	(segment
		(start 418.378894 -204.56017)
		(end 421.4368 -204.56017)
		(width 0.14478)
		(layer "In2.Cu")
		(net "M_I_CPU0_SA_DQ<6>")
	)
	(segment
		(start 425.858432 -204.10551)
		(end 426.089064 -204.10551)
		(width 0.14478)
		(layer "In2.Cu")
		(net "M_I_CPU0_SA_DQ<6>")
	)
	(segment
		(start 407.590498 -206.237332)
		(end 407.590498 -206.008732)
		(width 0.14478)
		(layer "In2.Cu")
		(net "M_I_CPU0_SA_DQ<6>")
	)
	(segment
		(start 391.926064 -223.929956)
		(end 391.957814 -223.911668)
		(width 0.0889)
		(layer "In2.Cu")
		(net "M_I_CPU0_SA_DQ<6>")
	)
	(segment
		(start 405.249634 -208.349596)
		(end 404.994364 -208.094326)
		(width 0.14478)
		(layer "In2.Cu")
		(net "M_I_CPU0_SA_DQ<6>")
	)
	(segment
		(start 378.79782 -228.771704)
		(end 378.806202 -228.766878)
		(width 0.0889)
		(layer "In2.Cu")
		(net "M_I_CPU0_SA_DQ<6>")
	)
	(segment
		(start 388.197852 -228.771704)
		(end 388.206234 -228.766878)
		(width 0.0889)
		(layer "In2.Cu")
		(net "M_I_CPU0_SA_DQ<6>")
	)
	(segment
		(start 404.994364 -207.865726)
		(end 405.155908 -207.704182)
		(width 0.14478)
		(layer "In2.Cu")
		(net "M_I_CPU0_SA_DQ<6>")
	)
	(segment
		(start 382.557782 -228.771704)
		(end 382.566164 -228.766878)
		(width 0.0889)
		(layer "In2.Cu")
		(net "M_I_CPU0_SA_DQ<6>")
	)
	(segment
		(start 408.370786 -205.228444)
		(end 408.115516 -204.973174)
		(width 0.14478)
		(layer "In2.Cu")
		(net "M_I_CPU0_SA_DQ<6>")
	)
	(segment
		(start 406.55494 -206.53375)
		(end 406.55494 -206.30515)
		(width 0.14478)
		(layer "In2.Cu")
		(net "M_I_CPU0_SA_DQ<6>")
	)
	(segment
		(start 406.945084 -206.143606)
		(end 407.200354 -206.398876)
		(width 0.14478)
		(layer "In2.Cu")
		(net "M_I_CPU0_SA_DQ<6>")
	)
	(segment
		(start 393.449302 -221.185232)
		(end 393.449302 -220.378528)
		(width 0.14478)
		(layer "In2.Cu")
		(net "M_I_CPU0_SA_DQ<6>")
	)
	(segment
		(start 408.115516 -204.744574)
		(end 408.27706 -204.58303)
		(width 0.14478)
		(layer "In2.Cu")
		(net "M_I_CPU0_SA_DQ<6>")
	)
	(segment
		(start 393.066524 -222.171006)
		(end 393.117324 -222.126556)
		(width 0.0889)
		(layer "In2.Cu")
		(net "M_I_CPU0_SA_DQ<6>")
	)
	(segment
		(start 390.51611 -226.359974)
		(end 390.54786 -226.341686)
		(width 0.0889)
		(layer "In2.Cu")
		(net "M_I_CPU0_SA_DQ<6>")
	)
	(segment
		(start 392.85291 -222.329502)
		(end 393.066524 -222.171006)
		(width 0.0889)
		(layer "In2.Cu")
		(net "M_I_CPU0_SA_DQ<6>")
	)
	(segment
		(start 381.043434 -228.766878)
		(end 381.051816 -228.771704)
		(width 0.0889)
		(layer "In2.Cu")
		(net "M_I_CPU0_SA_DQ<6>")
	)
	(segment
		(start 425.532804 -203.362052)
		(end 425.695618 -203.524866)
		(width 0.14478)
		(layer "In2.Cu")
		(net "M_I_CPU0_SA_DQ<6>")
	)
	(segment
		(start 385.744466 -228.767386)
		(end 385.751832 -228.771704)
		(width 0.0889)
		(layer "In2.Cu")
		(net "M_I_CPU0_SA_DQ<6>")
	)
	(segment
		(start 406.029922 -207.797908)
		(end 406.029922 -207.569308)
		(width 0.14478)
		(layer "In2.Cu")
		(net "M_I_CPU0_SA_DQ<6>")
	)
	(segment
		(start 390.047226 -227.169472)
		(end 390.077706 -227.151692)
		(width 0.0889)
		(layer "In2.Cu")
		(net "M_I_CPU0_SA_DQ<6>")
	)
	(segment
		(start 389.137906 -228.771704)
		(end 389.174228 -228.750622)
		(width 0.0889)
		(layer "In2.Cu")
		(net "M_I_CPU0_SA_DQ<6>")
	)
	(segment
		(start 405.155908 -207.704182)
		(end 405.384508 -207.704182)
		(width 0.14478)
		(layer "In2.Cu")
		(net "M_I_CPU0_SA_DQ<6>")
	)
	(segment
		(start 426.089064 -204.10551)
		(end 426.251878 -203.942696)
		(width 0.14478)
		(layer "In2.Cu")
		(net "M_I_CPU0_SA_DQ<6>")
	)
	(segment
		(start 408.209242 -205.618588)
		(end 408.370786 -205.457044)
		(width 0.14478)
		(layer "In2.Cu")
		(net "M_I_CPU0_SA_DQ<6>")
	)
	(segment
		(start 404.994364 -208.094326)
		(end 404.994364 -207.865726)
		(width 0.14478)
		(layer "In2.Cu")
		(net "M_I_CPU0_SA_DQ<6>")
	)
	(segment
		(start 407.725372 -205.363318)
		(end 407.980642 -205.618588)
		(width 0.14478)
		(layer "In2.Cu")
		(net "M_I_CPU0_SA_DQ<6>")
	)
	(segment
		(start 405.249634 -208.578196)
		(end 405.249634 -208.349596)
		(width 0.14478)
		(layer "In2.Cu")
		(net "M_I_CPU0_SA_DQ<6>")
	)
	(segment
		(start 408.98953 -204.8383)
		(end 409.26766 -204.56017)
		(width 0.14478)
		(layer "In2.Cu")
		(net "M_I_CPU0_SA_DQ<6>")
	)
	(segment
		(start 406.55494 -206.30515)
		(end 406.716484 -206.143606)
		(width 0.14478)
		(layer "In2.Cu")
		(net "M_I_CPU0_SA_DQ<6>")
	)
	(segment
		(start 407.980642 -205.618588)
		(end 408.209242 -205.618588)
		(width 0.14478)
		(layer "In2.Cu")
		(net "M_I_CPU0_SA_DQ<6>")
	)
	(segment
		(start 425.139358 -203.942696)
		(end 425.139358 -203.524866)
		(width 0.14478)
		(layer "In2.Cu")
		(net "M_I_CPU0_SA_DQ<6>")
	)
	(segment
		(start 405.774652 -207.085438)
		(end 405.936196 -206.923894)
		(width 0.14478)
		(layer "In2.Cu")
		(net "M_I_CPU0_SA_DQ<6>")
	)
	(segment
		(start 415.017966 -203.710032)
		(end 417.528756 -203.710032)
		(width 0.14478)
		(layer "In2.Cu")
		(net "M_I_CPU0_SA_DQ<6>")
	)
	(segment
		(start 390.98601 -225.549968)
		(end 391.01776 -225.53168)
		(width 0.0889)
		(layer "In2.Cu")
		(net "M_I_CPU0_SA_DQ<6>")
	)
	(segment
		(start 391.01776 -225.53168)
		(end 391.056876 -225.50882)
		(width 0.0889)
		(layer "In2.Cu")
		(net "M_I_CPU0_SA_DQ<6>")
	)
	(segment
		(start 409.26766 -204.56017)
		(end 414.167828 -204.56017)
		(width 0.14478)
		(layer "In2.Cu")
		(net "M_I_CPU0_SA_DQ<6>")
	)
	(segment
		(start 385.74345 -228.766878)
		(end 385.744466 -228.767386)
		(width 0.0889)
		(layer "In2.Cu")
		(net "M_I_CPU0_SA_DQ<6>")
	)
	(segment
		(start 406.164796 -206.923894)
		(end 406.420066 -207.179164)
		(width 0.14478)
		(layer "In2.Cu")
		(net "M_I_CPU0_SA_DQ<6>")
	)
	(segment
		(start 424.745912 -204.10551)
		(end 424.976544 -204.10551)
		(width 0.14478)
		(layer "In2.Cu")
		(net "M_I_CPU0_SA_DQ<6>")
	)
	(segment
		(start 414.167828 -204.56017)
		(end 415.017966 -203.710032)
		(width 0.14478)
		(layer "In2.Cu")
		(net "M_I_CPU0_SA_DQ<6>")
	)
	(segment
		(start 390.077706 -227.151692)
		(end 390.116822 -227.128832)
		(width 0.0889)
		(layer "In2.Cu")
		(net "M_I_CPU0_SA_DQ<6>")
	)
	(segment
		(start 425.695618 -203.942696)
		(end 425.858432 -204.10551)
		(width 0.14478)
		(layer "In2.Cu")
		(net "M_I_CPU0_SA_DQ<6>")
	)
	(segment
		(start 425.302172 -203.362052)
		(end 425.532804 -203.362052)
		(width 0.14478)
		(layer "In2.Cu")
		(net "M_I_CPU0_SA_DQ<6>")
	)
	(segment
		(start 426.251878 -203.48702)
		(end 426.414692 -203.324206)
		(width 0.14478)
		(layer "In2.Cu")
		(net "M_I_CPU0_SA_DQ<6>")
	)
	(segment
		(start 426.414692 -203.324206)
		(end 426.645324 -203.324206)
		(width 0.14478)
		(layer "In2.Cu")
		(net "M_I_CPU0_SA_DQ<6>")
	)
	(segment
		(start 407.200354 -206.398876)
		(end 407.428954 -206.398876)
		(width 0.14478)
		(layer "In2.Cu")
		(net "M_I_CPU0_SA_DQ<6>")
	)
	(segment
		(start 387.257798 -228.771704)
		(end 387.26618 -228.766878)
		(width 0.0889)
		(layer "In2.Cu")
		(net "M_I_CPU0_SA_DQ<6>")
	)
	(segment
		(start 407.335228 -205.524862)
		(end 407.496772 -205.363318)
		(width 0.14478)
		(layer "In2.Cu")
		(net "M_I_CPU0_SA_DQ<6>")
	)
	(segment
		(start 386.683504 -228.766878)
		(end 386.691886 -228.771704)
		(width 0.0889)
		(layer "In2.Cu")
		(net "M_I_CPU0_SA_DQ<6>")
	)
	(segment
		(start 408.370786 -205.457044)
		(end 408.370786 -205.228444)
		(width 0.14478)
		(layer "In2.Cu")
		(net "M_I_CPU0_SA_DQ<6>")
	)
	(segment
		(start 393.117324 -222.126556)
		(end 393.449302 -221.703392)
		(width 0.0889)
		(layer "In2.Cu")
		(net "M_I_CPU0_SA_DQ<6>")
	)
	(segment
		(start 389.607806 -227.961698)
		(end 389.646922 -227.938838)
		(width 0.0889)
		(layer "In2.Cu")
		(net "M_I_CPU0_SA_DQ<6>")
	)
	(segment
		(start 424.976544 -204.10551)
		(end 425.139358 -203.942696)
		(width 0.14478)
		(layer "In2.Cu")
		(net "M_I_CPU0_SA_DQ<6>")
	)
	(segment
		(start 408.27706 -204.58303)
		(end 408.50566 -204.58303)
		(width 0.14478)
		(layer "In2.Cu")
		(net "M_I_CPU0_SA_DQ<6>")
	)
	(segment
		(start 407.496772 -205.363318)
		(end 407.725372 -205.363318)
		(width 0.14478)
		(layer "In2.Cu")
		(net "M_I_CPU0_SA_DQ<6>")
	)
	(segment
		(start 406.81021 -207.01762)
		(end 406.81021 -206.78902)
		(width 0.14478)
		(layer "In2.Cu")
		(net "M_I_CPU0_SA_DQ<6>")
	)
	(segment
		(start 391.45718 -224.739454)
		(end 391.48766 -224.721674)
		(width 0.0889)
		(layer "In2.Cu")
		(net "M_I_CPU0_SA_DQ<6>")
	)
	(segment
		(start 377.258834 -228.828854)
		(end 377.354846 -228.803454)
		(width 0.0889)
		(layer "In2.Cu")
		(net "M_I_CPU0_SA_DQ<6>")
	)
	(segment
		(start 389.576056 -227.979986)
		(end 389.607806 -227.961698)
		(width 0.0889)
		(layer "In2.Cu")
		(net "M_I_CPU0_SA_DQ<6>")
	)
	(segment
		(start 393.449302 -220.378528)
		(end 405.249634 -208.578196)
		(width 0.14478)
		(layer "In2.Cu")
		(net "M_I_CPU0_SA_DQ<6>")
	)
	(segment
		(start 407.335228 -205.753462)
		(end 407.335228 -205.524862)
		(width 0.14478)
		(layer "In2.Cu")
		(net "M_I_CPU0_SA_DQ<6>")
	)
	(segment
		(start 405.639778 -207.959452)
		(end 405.868378 -207.959452)
		(width 0.14478)
		(layer "In2.Cu")
		(net "M_I_CPU0_SA_DQ<6>")
	)
	(segment
		(start 405.384508 -207.704182)
		(end 405.639778 -207.959452)
		(width 0.14478)
		(layer "In2.Cu")
		(net "M_I_CPU0_SA_DQ<6>")
	)
	(segment
		(start 406.029922 -207.569308)
		(end 405.774652 -207.314038)
		(width 0.14478)
		(layer "In2.Cu")
		(net "M_I_CPU0_SA_DQ<6>")
	)
	(segment
		(start 377.857766 -228.771704)
		(end 377.866148 -228.766878)
		(width 0.0889)
		(layer "In2.Cu")
		(net "M_I_CPU0_SA_DQ<6>")
	)
	(segment
		(start 425.139358 -203.524866)
		(end 425.302172 -203.362052)
		(width 0.14478)
		(layer "In2.Cu")
		(net "M_I_CPU0_SA_DQ<6>")
	)
	(arc
		(start 378.231908 -228.771704)
		(mid 378.514864 -228.847881)
		(end 378.79782 -228.771704)
		(width 0.0889)
		(layer "In2.Cu")
		(net "M_I_CPU0_SA_DQ<6>")
	)
	(arc
		(start 389.174228 -228.750622)
		(mid 389.35488 -228.547877)
		(end 389.4201 -228.284278)
		(width 0.0889)
		(layer "In2.Cu")
		(net "M_I_CPU0_SA_DQ<6>")
	)
	(arc
		(start 391.770108 -224.234248)
		(mid 391.811363 -224.063277)
		(end 391.926064 -223.929956)
		(width 0.0889)
		(layer "In2.Cu")
		(net "M_I_CPU0_SA_DQ<6>")
	)
	(arc
		(start 378.806202 -228.766878)
		(mid 378.98971 -228.721384)
		(end 379.171962 -228.771704)
		(width 0.0889)
		(layer "In2.Cu")
		(net "M_I_CPU0_SA_DQ<6>")
	)
	(arc
		(start 379.737874 -228.771704)
		(mid 379.924818 -228.721449)
		(end 380.111762 -228.771704)
		(width 0.0889)
		(layer "In2.Cu")
		(net "M_I_CPU0_SA_DQ<6>")
	)
	(arc
		(start 385.37769 -228.771704)
		(mid 385.559941 -228.721354)
		(end 385.74345 -228.766878)
		(width 0.0889)
		(layer "In2.Cu")
		(net "M_I_CPU0_SA_DQ<6>")
	)
	(arc
		(start 382.931924 -228.771704)
		(mid 383.21488 -228.847881)
		(end 383.497836 -228.771704)
		(width 0.0889)
		(layer "In2.Cu")
		(net "M_I_CPU0_SA_DQ<6>")
	)
	(arc
		(start 386.317744 -228.771704)
		(mid 386.499995 -228.721354)
		(end 386.683504 -228.766878)
		(width 0.0889)
		(layer "In2.Cu")
		(net "M_I_CPU0_SA_DQ<6>")
	)
	(arc
		(start 390.360154 -226.664266)
		(mid 390.401409 -226.493295)
		(end 390.51611 -226.359974)
		(width 0.0889)
		(layer "In2.Cu")
		(net "M_I_CPU0_SA_DQ<6>")
	)
	(arc
		(start 388.571994 -228.771704)
		(mid 388.85495 -228.847881)
		(end 389.137906 -228.771704)
		(width 0.0889)
		(layer "In2.Cu")
		(net "M_I_CPU0_SA_DQ<6>")
	)
	(arc
		(start 390.830054 -225.85426)
		(mid 390.871309 -225.683289)
		(end 390.98601 -225.549968)
		(width 0.0889)
		(layer "In2.Cu")
		(net "M_I_CPU0_SA_DQ<6>")
	)
	(arc
		(start 382.566164 -228.766878)
		(mid 382.749672 -228.721384)
		(end 382.931924 -228.771704)
		(width 0.0889)
		(layer "In2.Cu")
		(net "M_I_CPU0_SA_DQ<6>")
	)
	(arc
		(start 392.460988 -223.082358)
		(mid 392.64365 -222.879277)
		(end 392.709654 -222.614236)
		(width 0.0889)
		(layer "In2.Cu")
		(net "M_I_CPU0_SA_DQ<6>")
	)
	(arc
		(start 377.354846 -228.803454)
		(mid 377.610054 -228.846931)
		(end 377.857766 -228.771704)
		(width 0.0889)
		(layer "In2.Cu")
		(net "M_I_CPU0_SA_DQ<6>")
	)
	(arc
		(start 379.171962 -228.771704)
		(mid 379.454918 -228.847881)
		(end 379.737874 -228.771704)
		(width 0.0889)
		(layer "In2.Cu")
		(net "M_I_CPU0_SA_DQ<6>")
	)
	(arc
		(start 391.99693 -223.888808)
		(mid 392.175743 -223.686458)
		(end 392.240262 -223.424242)
		(width 0.0889)
		(layer "In2.Cu")
		(net "M_I_CPU0_SA_DQ<6>")
	)
	(arc
		(start 384.811778 -228.771704)
		(mid 385.094734 -228.847881)
		(end 385.37769 -228.771704)
		(width 0.0889)
		(layer "In2.Cu")
		(net "M_I_CPU0_SA_DQ<6>")
	)
	(arc
		(start 391.526776 -224.698814)
		(mid 391.705589 -224.496464)
		(end 391.770108 -224.234248)
		(width 0.0889)
		(layer "In2.Cu")
		(net "M_I_CPU0_SA_DQ<6>")
	)
	(arc
		(start 387.63194 -228.771704)
		(mid 387.914896 -228.847881)
		(end 388.197852 -228.771704)
		(width 0.0889)
		(layer "In2.Cu")
		(net "M_I_CPU0_SA_DQ<6>")
	)
	(arc
		(start 390.584182 -226.320604)
		(mid 390.764834 -226.117859)
		(end 390.830054 -225.85426)
		(width 0.0889)
		(layer "In2.Cu")
		(net "M_I_CPU0_SA_DQ<6>")
	)
	(arc
		(start 384.43789 -228.771704)
		(mid 384.624834 -228.721449)
		(end 384.811778 -228.771704)
		(width 0.0889)
		(layer "In2.Cu")
		(net "M_I_CPU0_SA_DQ<6>")
	)
	(arc
		(start 385.751832 -228.771704)
		(mid 386.034788 -228.847881)
		(end 386.317744 -228.771704)
		(width 0.0889)
		(layer "In2.Cu")
		(net "M_I_CPU0_SA_DQ<6>")
	)
	(arc
		(start 377.866148 -228.766878)
		(mid 378.049656 -228.721384)
		(end 378.231908 -228.771704)
		(width 0.0889)
		(layer "In2.Cu")
		(net "M_I_CPU0_SA_DQ<6>")
	)
	(arc
		(start 389.646922 -227.938838)
		(mid 389.825735 -227.736488)
		(end 389.890254 -227.474272)
		(width 0.0889)
		(layer "In2.Cu")
		(net "M_I_CPU0_SA_DQ<6>")
	)
	(arc
		(start 391.056876 -225.50882)
		(mid 391.235689 -225.30647)
		(end 391.300208 -225.044254)
		(width 0.0889)
		(layer "In2.Cu")
		(net "M_I_CPU0_SA_DQ<6>")
	)
	(arc
		(start 381.051816 -228.771704)
		(mid 381.334772 -228.847881)
		(end 381.617728 -228.771704)
		(width 0.0889)
		(layer "In2.Cu")
		(net "M_I_CPU0_SA_DQ<6>")
	)
	(arc
		(start 389.890254 -227.474272)
		(mid 389.931803 -227.30285)
		(end 390.047226 -227.169472)
		(width 0.0889)
		(layer "In2.Cu")
		(net "M_I_CPU0_SA_DQ<6>")
	)
	(arc
		(start 389.4201 -228.284278)
		(mid 389.461355 -228.113307)
		(end 389.576056 -227.979986)
		(width 0.0889)
		(layer "In2.Cu")
		(net "M_I_CPU0_SA_DQ<6>")
	)
	(arc
		(start 392.240262 -223.424242)
		(mid 392.281811 -223.25282)
		(end 392.397234 -223.119442)
		(width 0.0889)
		(layer "In2.Cu")
		(net "M_I_CPU0_SA_DQ<6>")
	)
	(arc
		(start 383.871978 -228.771704)
		(mid 384.154934 -228.847881)
		(end 384.43789 -228.771704)
		(width 0.0889)
		(layer "In2.Cu")
		(net "M_I_CPU0_SA_DQ<6>")
	)
	(arc
		(start 380.677674 -228.771704)
		(mid 380.859925 -228.721354)
		(end 381.043434 -228.766878)
		(width 0.0889)
		(layer "In2.Cu")
		(net "M_I_CPU0_SA_DQ<6>")
	)
	(arc
		(start 383.506218 -228.766878)
		(mid 383.689726 -228.721384)
		(end 383.871978 -228.771704)
		(width 0.0889)
		(layer "In2.Cu")
		(net "M_I_CPU0_SA_DQ<6>")
	)
	(arc
		(start 381.99187 -228.771704)
		(mid 382.274826 -228.847881)
		(end 382.557782 -228.771704)
		(width 0.0889)
		(layer "In2.Cu")
		(net "M_I_CPU0_SA_DQ<6>")
	)
	(arc
		(start 391.300208 -225.044254)
		(mid 391.341757 -224.872832)
		(end 391.45718 -224.739454)
		(width 0.0889)
		(layer "In2.Cu")
		(net "M_I_CPU0_SA_DQ<6>")
	)
	(arc
		(start 381.617728 -228.771704)
		(mid 381.799979 -228.721354)
		(end 381.983488 -228.766878)
		(width 0.0889)
		(layer "In2.Cu")
		(net "M_I_CPU0_SA_DQ<6>")
	)
	(arc
		(start 388.206234 -228.766878)
		(mid 388.389742 -228.721384)
		(end 388.571994 -228.771704)
		(width 0.0889)
		(layer "In2.Cu")
		(net "M_I_CPU0_SA_DQ<6>")
	)
	(arc
		(start 386.691886 -228.771704)
		(mid 386.974842 -228.847881)
		(end 387.257798 -228.771704)
		(width 0.0889)
		(layer "In2.Cu")
		(net "M_I_CPU0_SA_DQ<6>")
	)
	(arc
		(start 387.26618 -228.766878)
		(mid 387.449688 -228.721384)
		(end 387.63194 -228.771704)
		(width 0.0889)
		(layer "In2.Cu")
		(net "M_I_CPU0_SA_DQ<6>")
	)
	(arc
		(start 380.111762 -228.771704)
		(mid 380.394718 -228.847881)
		(end 380.677674 -228.771704)
		(width 0.0889)
		(layer "In2.Cu")
		(net "M_I_CPU0_SA_DQ<6>")
	)
	(arc
		(start 392.709654 -222.614236)
		(mid 392.747487 -222.454867)
		(end 392.85291 -222.329502)
		(width 0.0889)
		(layer "In2.Cu")
		(net "M_I_CPU0_SA_DQ<6>")
	)
	(arc
		(start 390.116822 -227.128832)
		(mid 390.295635 -226.926482)
		(end 390.360154 -226.664266)
		(width 0.0889)
		(layer "In2.Cu")
		(net "M_I_CPU0_SA_DQ<6>")
	)
	(segment
		(start 375.698004 -229.360222)
		(end 376.164856 -229.094284)
		(width 0.10668)
		(layer "F.Cu")
		(net "M_I_CPU0_SA_DQ<5>")
	)
	(segment
		(start 376.3518 -229.41661)
		(end 376.343418 -229.421436)
		(width 0.0889)
		(layer "In2.Cu")
		(net "M_I_CPU0_SA_DQ<5>")
	)
	(segment
		(start 418.469318 -205.410054)
		(end 417.619434 -204.56017)
		(width 0.14478)
		(layer "In2.Cu")
		(net "M_I_CPU0_SA_DQ<5>")
	)
	(segment
		(start 393.271248 -222.937832)
		(end 393.228322 -222.962978)
		(width 0.0889)
		(layer "In2.Cu")
		(net "M_I_CPU0_SA_DQ<5>")
	)
	(segment
		(start 388.206234 -229.421436)
		(end 388.197852 -229.41661)
		(width 0.0889)
		(layer "In2.Cu")
		(net "M_I_CPU0_SA_DQ<5>")
	)
	(segment
		(start 421.730932 -205.410054)
		(end 418.469318 -205.410054)
		(width 0.14478)
		(layer "In2.Cu")
		(net "M_I_CPU0_SA_DQ<5>")
	)
	(segment
		(start 415.01187 -204.56017)
		(end 414.161986 -205.410054)
		(width 0.14478)
		(layer "In2.Cu")
		(net "M_I_CPU0_SA_DQ<5>")
	)
	(segment
		(start 409.054046 -205.410054)
		(end 393.917678 -220.546422)
		(width 0.14478)
		(layer "In2.Cu")
		(net "M_I_CPU0_SA_DQ<5>")
	)
	(segment
		(start 431.55616 -204.985112)
		(end 431.131218 -204.56017)
		(width 0.14478)
		(layer "In2.Cu")
		(net "M_I_CPU0_SA_DQ<5>")
	)
	(segment
		(start 387.26618 -229.421436)
		(end 387.257798 -229.41661)
		(width 0.0889)
		(layer "In2.Cu")
		(net "M_I_CPU0_SA_DQ<5>")
	)
	(segment
		(start 391.422382 -226.15906)
		(end 391.391902 -226.17684)
		(width 0.0889)
		(layer "In2.Cu")
		(net "M_I_CPU0_SA_DQ<5>")
	)
	(segment
		(start 429.567594 -204.721714)
		(end 429.40605 -204.56017)
		(width 0.14478)
		(layer "In2.Cu")
		(net "M_I_CPU0_SA_DQ<5>")
	)
	(segment
		(start 393.844272 -221.918276)
		(end 393.528042 -222.33128)
		(width 0.0889)
		(layer "In2.Cu")
		(net "M_I_CPU0_SA_DQ<5>")
	)
	(segment
		(start 390.483598 -227.778564)
		(end 390.451848 -227.796852)
		(width 0.0889)
		(layer "In2.Cu")
		(net "M_I_CPU0_SA_DQ<5>")
	)
	(segment
		(start 391.893552 -225.348546)
		(end 391.861802 -225.366834)
		(width 0.0889)
		(layer "In2.Cu")
		(net "M_I_CPU0_SA_DQ<5>")
	)
	(segment
		(start 390.921748 -226.986846)
		(end 390.885426 -227.007928)
		(width 0.0889)
		(layer "In2.Cu")
		(net "M_I_CPU0_SA_DQ<5>")
	)
	(segment
		(start 383.506218 -229.421436)
		(end 383.497836 -229.41661)
		(width 0.0889)
		(layer "In2.Cu")
		(net "M_I_CPU0_SA_DQ<5>")
	)
	(segment
		(start 422.580816 -204.56017)
		(end 421.730932 -205.410054)
		(width 0.14478)
		(layer "In2.Cu")
		(net "M_I_CPU0_SA_DQ<5>")
	)
	(segment
		(start 393.30884 -222.915988)
		(end 393.271248 -222.937832)
		(width 0.0889)
		(layer "In2.Cu")
		(net "M_I_CPU0_SA_DQ<5>")
	)
	(segment
		(start 393.917678 -221.314772)
		(end 393.917678 -221.84487)
		(width 0.0889)
		(layer "In2.Cu")
		(net "M_I_CPU0_SA_DQ<5>")
	)
	(segment
		(start 391.391902 -226.17684)
		(end 391.352786 -226.1997)
		(width 0.0889)
		(layer "In2.Cu")
		(net "M_I_CPU0_SA_DQ<5>")
	)
	(segment
		(start 376.032776 -229.442772)
		(end 376.010678 -229.359714)
		(width 0.0889)
		(layer "In2.Cu")
		(net "M_I_CPU0_SA_DQ<5>")
	)
	(segment
		(start 381.051816 -229.41661)
		(end 381.043434 -229.421436)
		(width 0.0889)
		(layer "In2.Cu")
		(net "M_I_CPU0_SA_DQ<5>")
	)
	(segment
		(start 392.331956 -224.556828)
		(end 392.29284 -224.579688)
		(width 0.0889)
		(layer "In2.Cu")
		(net "M_I_CPU0_SA_DQ<5>")
	)
	(segment
		(start 392.833606 -223.728534)
		(end 392.801856 -223.746822)
		(width 0.0889)
		(layer "In2.Cu")
		(net "M_I_CPU0_SA_DQ<5>")
	)
	(segment
		(start 390.451848 -227.796852)
		(end 390.412732 -227.819712)
		(width 0.0889)
		(layer "In2.Cu")
		(net "M_I_CPU0_SA_DQ<5>")
	)
	(segment
		(start 429.957484 -205.658212)
		(end 429.729138 -205.658212)
		(width 0.14478)
		(layer "In2.Cu")
		(net "M_I_CPU0_SA_DQ<5>")
	)
	(segment
		(start 381.99187 -229.41661)
		(end 381.983488 -229.421436)
		(width 0.0889)
		(layer "In2.Cu")
		(net "M_I_CPU0_SA_DQ<5>")
	)
	(segment
		(start 430.280572 -204.56017)
		(end 430.119028 -204.721714)
		(width 0.14478)
		(layer "In2.Cu")
		(net "M_I_CPU0_SA_DQ<5>")
	)
	(segment
		(start 430.119028 -205.496668)
		(end 429.957484 -205.658212)
		(width 0.14478)
		(layer "In2.Cu")
		(net "M_I_CPU0_SA_DQ<5>")
	)
	(segment
		(start 392.801856 -223.746822)
		(end 392.76274 -223.769682)
		(width 0.0889)
		(layer "In2.Cu")
		(net "M_I_CPU0_SA_DQ<5>")
	)
	(segment
		(start 431.131218 -204.56017)
		(end 430.280572 -204.56017)
		(width 0.14478)
		(layer "In2.Cu")
		(net "M_I_CPU0_SA_DQ<5>")
	)
	(segment
		(start 390.012428 -228.589078)
		(end 389.981948 -228.606858)
		(width 0.0889)
		(layer "In2.Cu")
		(net "M_I_CPU0_SA_DQ<5>")
	)
	(segment
		(start 429.40605 -204.56017)
		(end 422.580816 -204.56017)
		(width 0.14478)
		(layer "In2.Cu")
		(net "M_I_CPU0_SA_DQ<5>")
	)
	(segment
		(start 378.806202 -229.421436)
		(end 378.79782 -229.41661)
		(width 0.0889)
		(layer "In2.Cu")
		(net "M_I_CPU0_SA_DQ<5>")
	)
	(segment
		(start 382.566164 -229.421436)
		(end 382.557782 -229.41661)
		(width 0.0889)
		(layer "In2.Cu")
		(net "M_I_CPU0_SA_DQ<5>")
	)
	(segment
		(start 377.866148 -229.421436)
		(end 377.857766 -229.41661)
		(width 0.0889)
		(layer "In2.Cu")
		(net "M_I_CPU0_SA_DQ<5>")
	)
	(segment
		(start 430.119028 -204.721714)
		(end 430.119028 -205.496668)
		(width 0.14478)
		(layer "In2.Cu")
		(net "M_I_CPU0_SA_DQ<5>")
	)
	(segment
		(start 386.691886 -229.41661)
		(end 386.683504 -229.421436)
		(width 0.0889)
		(layer "In2.Cu")
		(net "M_I_CPU0_SA_DQ<5>")
	)
	(segment
		(start 417.619434 -204.56017)
		(end 415.01187 -204.56017)
		(width 0.14478)
		(layer "In2.Cu")
		(net "M_I_CPU0_SA_DQ<5>")
	)
	(segment
		(start 377.291854 -229.41661)
		(end 377.283472 -229.421436)
		(width 0.0889)
		(layer "In2.Cu")
		(net "M_I_CPU0_SA_DQ<5>")
	)
	(segment
		(start 389.545322 -229.397052)
		(end 389.511794 -229.41661)
		(width 0.0889)
		(layer "In2.Cu")
		(net "M_I_CPU0_SA_DQ<5>")
	)
	(segment
		(start 393.917678 -220.546422)
		(end 393.917678 -221.314772)
		(width 0.14478)
		(layer "In2.Cu")
		(net "M_I_CPU0_SA_DQ<5>")
	)
	(segment
		(start 391.861802 -225.366834)
		(end 391.822686 -225.389694)
		(width 0.0889)
		(layer "In2.Cu")
		(net "M_I_CPU0_SA_DQ<5>")
	)
	(segment
		(start 429.729138 -205.658212)
		(end 429.567594 -205.496668)
		(width 0.14478)
		(layer "In2.Cu")
		(net "M_I_CPU0_SA_DQ<5>")
	)
	(segment
		(start 414.161986 -205.410054)
		(end 409.054046 -205.410054)
		(width 0.14478)
		(layer "In2.Cu")
		(net "M_I_CPU0_SA_DQ<5>")
	)
	(segment
		(start 390.953498 -226.968558)
		(end 390.921748 -226.986846)
		(width 0.0889)
		(layer "In2.Cu")
		(net "M_I_CPU0_SA_DQ<5>")
	)
	(segment
		(start 376.010678 -229.359714)
		(end 376.164856 -229.094284)
		(width 0.0889)
		(layer "In2.Cu")
		(net "M_I_CPU0_SA_DQ<5>")
	)
	(segment
		(start 393.917678 -221.84487)
		(end 393.844272 -221.918276)
		(width 0.0889)
		(layer "In2.Cu")
		(net "M_I_CPU0_SA_DQ<5>")
	)
	(segment
		(start 429.567594 -205.496668)
		(end 429.567594 -204.721714)
		(width 0.14478)
		(layer "In2.Cu")
		(net "M_I_CPU0_SA_DQ<5>")
	)
	(segment
		(start 389.981948 -228.606858)
		(end 389.942832 -228.629718)
		(width 0.0889)
		(layer "In2.Cu")
		(net "M_I_CPU0_SA_DQ<5>")
	)
	(segment
		(start 392.362436 -224.539048)
		(end 392.331956 -224.556828)
		(width 0.0889)
		(layer "In2.Cu")
		(net "M_I_CPU0_SA_DQ<5>")
	)
	(segment
		(start 385.751832 -229.41661)
		(end 385.74345 -229.421436)
		(width 0.0889)
		(layer "In2.Cu")
		(net "M_I_CPU0_SA_DQ<5>")
	)
	(arc
		(start 390.412732 -227.819712)
		(mid 390.233919 -228.022062)
		(end 390.1694 -228.284278)
		(width 0.0889)
		(layer "In2.Cu")
		(net "M_I_CPU0_SA_DQ<5>")
	)
	(arc
		(start 383.497836 -229.41661)
		(mid 383.21488 -229.340433)
		(end 382.931924 -229.41661)
		(width 0.0889)
		(layer "In2.Cu")
		(net "M_I_CPU0_SA_DQ<5>")
	)
	(arc
		(start 392.29284 -224.579688)
		(mid 392.114027 -224.782038)
		(end 392.049508 -225.044254)
		(width 0.0889)
		(layer "In2.Cu")
		(net "M_I_CPU0_SA_DQ<5>")
	)
	(arc
		(start 392.049508 -225.044254)
		(mid 392.008253 -225.215225)
		(end 391.893552 -225.348546)
		(width 0.0889)
		(layer "In2.Cu")
		(net "M_I_CPU0_SA_DQ<5>")
	)
	(arc
		(start 383.871978 -229.41661)
		(mid 383.689727 -229.466994)
		(end 383.506218 -229.421436)
		(width 0.0889)
		(layer "In2.Cu")
		(net "M_I_CPU0_SA_DQ<5>")
	)
	(arc
		(start 393.528042 -222.33128)
		(mid 393.463408 -222.466481)
		(end 393.4587 -222.616268)
		(width 0.0889)
		(layer "In2.Cu")
		(net "M_I_CPU0_SA_DQ<5>")
	)
	(arc
		(start 389.511794 -229.41661)
		(mid 389.32485 -229.466899)
		(end 389.137906 -229.41661)
		(width 0.0889)
		(layer "In2.Cu")
		(net "M_I_CPU0_SA_DQ<5>")
	)
	(arc
		(start 388.197852 -229.41661)
		(mid 387.914896 -229.340433)
		(end 387.63194 -229.41661)
		(width 0.0889)
		(layer "In2.Cu")
		(net "M_I_CPU0_SA_DQ<5>")
	)
	(arc
		(start 390.885426 -227.007928)
		(mid 390.704774 -227.210673)
		(end 390.639554 -227.474272)
		(width 0.0889)
		(layer "In2.Cu")
		(net "M_I_CPU0_SA_DQ<5>")
	)
	(arc
		(start 381.983488 -229.421436)
		(mid 381.79998 -229.466961)
		(end 381.617728 -229.41661)
		(width 0.0889)
		(layer "In2.Cu")
		(net "M_I_CPU0_SA_DQ<5>")
	)
	(arc
		(start 376.917712 -229.41661)
		(mid 376.634756 -229.340433)
		(end 376.3518 -229.41661)
		(width 0.0889)
		(layer "In2.Cu")
		(net "M_I_CPU0_SA_DQ<5>")
	)
	(arc
		(start 377.283472 -229.421436)
		(mid 377.099964 -229.466961)
		(end 376.917712 -229.41661)
		(width 0.0889)
		(layer "In2.Cu")
		(net "M_I_CPU0_SA_DQ<5>")
	)
	(arc
		(start 392.519408 -224.234248)
		(mid 392.477859 -224.40567)
		(end 392.362436 -224.539048)
		(width 0.0889)
		(layer "In2.Cu")
		(net "M_I_CPU0_SA_DQ<5>")
	)
	(arc
		(start 387.63194 -229.41661)
		(mid 387.449689 -229.466994)
		(end 387.26618 -229.421436)
		(width 0.0889)
		(layer "In2.Cu")
		(net "M_I_CPU0_SA_DQ<5>")
	)
	(arc
		(start 390.1694 -228.284278)
		(mid 390.127851 -228.4557)
		(end 390.012428 -228.589078)
		(width 0.0889)
		(layer "In2.Cu")
		(net "M_I_CPU0_SA_DQ<5>")
	)
	(arc
		(start 385.37769 -229.41661)
		(mid 385.094734 -229.340433)
		(end 384.811778 -229.41661)
		(width 0.0889)
		(layer "In2.Cu")
		(net "M_I_CPU0_SA_DQ<5>")
	)
	(arc
		(start 385.74345 -229.421436)
		(mid 385.559942 -229.466961)
		(end 385.37769 -229.41661)
		(width 0.0889)
		(layer "In2.Cu")
		(net "M_I_CPU0_SA_DQ<5>")
	)
	(arc
		(start 392.76274 -223.769682)
		(mid 392.583927 -223.972032)
		(end 392.519408 -224.234248)
		(width 0.0889)
		(layer "In2.Cu")
		(net "M_I_CPU0_SA_DQ<5>")
	)
	(arc
		(start 391.109454 -226.664266)
		(mid 391.068199 -226.835237)
		(end 390.953498 -226.968558)
		(width 0.0889)
		(layer "In2.Cu")
		(net "M_I_CPU0_SA_DQ<5>")
	)
	(arc
		(start 384.811778 -229.41661)
		(mid 384.624834 -229.466899)
		(end 384.43789 -229.41661)
		(width 0.0889)
		(layer "In2.Cu")
		(net "M_I_CPU0_SA_DQ<5>")
	)
	(arc
		(start 380.111762 -229.41661)
		(mid 379.924818 -229.466899)
		(end 379.737874 -229.41661)
		(width 0.0889)
		(layer "In2.Cu")
		(net "M_I_CPU0_SA_DQ<5>")
	)
	(arc
		(start 381.617728 -229.41661)
		(mid 381.334772 -229.340433)
		(end 381.051816 -229.41661)
		(width 0.0889)
		(layer "In2.Cu")
		(net "M_I_CPU0_SA_DQ<5>")
	)
	(arc
		(start 384.43789 -229.41661)
		(mid 384.154934 -229.340433)
		(end 383.871978 -229.41661)
		(width 0.0889)
		(layer "In2.Cu")
		(net "M_I_CPU0_SA_DQ<5>")
	)
	(arc
		(start 391.579354 -225.85426)
		(mid 391.537805 -226.025682)
		(end 391.422382 -226.15906)
		(width 0.0889)
		(layer "In2.Cu")
		(net "M_I_CPU0_SA_DQ<5>")
	)
	(arc
		(start 382.557782 -229.41661)
		(mid 382.274826 -229.340433)
		(end 381.99187 -229.41661)
		(width 0.0889)
		(layer "In2.Cu")
		(net "M_I_CPU0_SA_DQ<5>")
	)
	(arc
		(start 392.989562 -223.424242)
		(mid 392.948307 -223.595213)
		(end 392.833606 -223.728534)
		(width 0.0889)
		(layer "In2.Cu")
		(net "M_I_CPU0_SA_DQ<5>")
	)
	(arc
		(start 386.317744 -229.41661)
		(mid 386.034788 -229.340433)
		(end 385.751832 -229.41661)
		(width 0.0889)
		(layer "In2.Cu")
		(net "M_I_CPU0_SA_DQ<5>")
	)
	(arc
		(start 376.343418 -229.421436)
		(mid 376.19043 -229.466116)
		(end 376.032776 -229.442772)
		(width 0.0889)
		(layer "In2.Cu")
		(net "M_I_CPU0_SA_DQ<5>")
	)
	(arc
		(start 378.231908 -229.41661)
		(mid 378.049657 -229.466994)
		(end 377.866148 -229.421436)
		(width 0.0889)
		(layer "In2.Cu")
		(net "M_I_CPU0_SA_DQ<5>")
	)
	(arc
		(start 382.931924 -229.41661)
		(mid 382.749673 -229.466994)
		(end 382.566164 -229.421436)
		(width 0.0889)
		(layer "In2.Cu")
		(net "M_I_CPU0_SA_DQ<5>")
	)
	(arc
		(start 393.228322 -222.962978)
		(mid 393.052777 -223.16454)
		(end 392.989562 -223.424242)
		(width 0.0889)
		(layer "In2.Cu")
		(net "M_I_CPU0_SA_DQ<5>")
	)
	(arc
		(start 393.4587 -222.616268)
		(mid 393.419147 -222.783817)
		(end 393.30884 -222.915988)
		(width 0.0889)
		(layer "In2.Cu")
		(net "M_I_CPU0_SA_DQ<5>")
	)
	(arc
		(start 381.043434 -229.421436)
		(mid 380.859926 -229.466961)
		(end 380.677674 -229.41661)
		(width 0.0889)
		(layer "In2.Cu")
		(net "M_I_CPU0_SA_DQ<5>")
	)
	(arc
		(start 387.257798 -229.41661)
		(mid 386.974842 -229.340433)
		(end 386.691886 -229.41661)
		(width 0.0889)
		(layer "In2.Cu")
		(net "M_I_CPU0_SA_DQ<5>")
	)
	(arc
		(start 389.6995 -229.094284)
		(mid 389.658738 -229.264168)
		(end 389.545322 -229.397052)
		(width 0.0889)
		(layer "In2.Cu")
		(net "M_I_CPU0_SA_DQ<5>")
	)
	(arc
		(start 380.677674 -229.41661)
		(mid 380.394718 -229.340433)
		(end 380.111762 -229.41661)
		(width 0.0889)
		(layer "In2.Cu")
		(net "M_I_CPU0_SA_DQ<5>")
	)
	(arc
		(start 391.822686 -225.389694)
		(mid 391.643873 -225.592044)
		(end 391.579354 -225.85426)
		(width 0.0889)
		(layer "In2.Cu")
		(net "M_I_CPU0_SA_DQ<5>")
	)
	(arc
		(start 389.137906 -229.41661)
		(mid 388.85495 -229.340433)
		(end 388.571994 -229.41661)
		(width 0.0889)
		(layer "In2.Cu")
		(net "M_I_CPU0_SA_DQ<5>")
	)
	(arc
		(start 390.639554 -227.474272)
		(mid 390.598299 -227.645243)
		(end 390.483598 -227.778564)
		(width 0.0889)
		(layer "In2.Cu")
		(net "M_I_CPU0_SA_DQ<5>")
	)
	(arc
		(start 388.571994 -229.41661)
		(mid 388.389743 -229.466994)
		(end 388.206234 -229.421436)
		(width 0.0889)
		(layer "In2.Cu")
		(net "M_I_CPU0_SA_DQ<5>")
	)
	(arc
		(start 379.171962 -229.41661)
		(mid 378.989711 -229.466994)
		(end 378.806202 -229.421436)
		(width 0.0889)
		(layer "In2.Cu")
		(net "M_I_CPU0_SA_DQ<5>")
	)
	(arc
		(start 377.857766 -229.41661)
		(mid 377.57481 -229.340433)
		(end 377.291854 -229.41661)
		(width 0.0889)
		(layer "In2.Cu")
		(net "M_I_CPU0_SA_DQ<5>")
	)
	(arc
		(start 389.942832 -228.629718)
		(mid 389.764019 -228.832068)
		(end 389.6995 -229.094284)
		(width 0.0889)
		(layer "In2.Cu")
		(net "M_I_CPU0_SA_DQ<5>")
	)
	(arc
		(start 378.79782 -229.41661)
		(mid 378.514864 -229.340433)
		(end 378.231908 -229.41661)
		(width 0.0889)
		(layer "In2.Cu")
		(net "M_I_CPU0_SA_DQ<5>")
	)
	(arc
		(start 391.352786 -226.1997)
		(mid 391.173973 -226.40205)
		(end 391.109454 -226.664266)
		(width 0.0889)
		(layer "In2.Cu")
		(net "M_I_CPU0_SA_DQ<5>")
	)
	(arc
		(start 379.737874 -229.41661)
		(mid 379.454918 -229.340433)
		(end 379.171962 -229.41661)
		(width 0.0889)
		(layer "In2.Cu")
		(net "M_I_CPU0_SA_DQ<5>")
	)
	(arc
		(start 386.683504 -229.421436)
		(mid 386.499996 -229.466961)
		(end 386.317744 -229.41661)
		(width 0.0889)
		(layer "In2.Cu")
		(net "M_I_CPU0_SA_DQ<5>")
	)
	(segment
		(start 377.107958 -228.550216)
		(end 377.57481 -228.284278)
		(width 0.10668)
		(layer "F.Cu")
		(net "M_I_CPU0_SA_DQ<4>")
	)
	(segment
		(start 392.994642 -221.276672)
		(end 392.994642 -220.197172)
		(width 0.14478)
		(layer "In2.Cu")
		(net "M_I_CPU0_SA_DQ<4>")
	)
	(segment
		(start 429.55718 -202.8698)
		(end 429.710342 -203.022962)
		(width 0.14478)
		(layer "In2.Cu")
		(net "M_I_CPU0_SA_DQ<4>")
	)
	(segment
		(start 391.391902 -224.556828)
		(end 391.422382 -224.539048)
		(width 0.0889)
		(layer "In2.Cu")
		(net "M_I_CPU0_SA_DQ<4>")
	)
	(segment
		(start 430.266602 -203.803758)
		(end 430.266602 -203.022962)
		(width 0.14478)
		(layer "In2.Cu")
		(net "M_I_CPU0_SA_DQ<4>")
	)
	(segment
		(start 384.333496 -228.611684)
		(end 384.341878 -228.606858)
		(width 0.0889)
		(layer "In2.Cu")
		(net "M_I_CPU0_SA_DQ<4>")
	)
	(segment
		(start 390.451848 -226.17684)
		(end 390.483598 -226.158552)
		(width 0.0889)
		(layer "In2.Cu")
		(net "M_I_CPU0_SA_DQ<4>")
	)
	(segment
		(start 377.57481 -228.284278)
		(end 377.420886 -228.549708)
		(width 0.0889)
		(layer "In2.Cu")
		(net "M_I_CPU0_SA_DQ<4>")
	)
	(segment
		(start 392.29284 -222.959676)
		(end 392.331956 -222.936816)
		(width 0.0889)
		(layer "In2.Cu")
		(net "M_I_CPU0_SA_DQ<4>")
	)
	(segment
		(start 404.544784 -207.67929)
		(end 408.50439 -203.719684)
		(width 0.14478)
		(layer "In2.Cu")
		(net "M_I_CPU0_SA_DQ<4>")
	)
	(segment
		(start 392.331956 -222.936816)
		(end 392.36015 -222.92056)
		(width 0.0889)
		(layer "In2.Cu")
		(net "M_I_CPU0_SA_DQ<4>")
	)
	(segment
		(start 389.981948 -226.986846)
		(end 390.012428 -226.969066)
		(width 0.0889)
		(layer "In2.Cu")
		(net "M_I_CPU0_SA_DQ<4>")
	)
	(segment
		(start 418.569902 -203.719684)
		(end 421.583358 -203.719684)
		(width 0.14478)
		(layer "In2.Cu")
		(net "M_I_CPU0_SA_DQ<4>")
	)
	(segment
		(start 408.50439 -203.719684)
		(end 414.260538 -203.719684)
		(width 0.14478)
		(layer "In2.Cu")
		(net "M_I_CPU0_SA_DQ<4>")
	)
	(segment
		(start 404.544784 -208.64703)
		(end 404.544784 -207.67929)
		(width 0.14478)
		(layer "In2.Cu")
		(net "M_I_CPU0_SA_DQ<4>")
	)
	(segment
		(start 390.921748 -225.366834)
		(end 390.953498 -225.348546)
		(width 0.0889)
		(layer "In2.Cu")
		(net "M_I_CPU0_SA_DQ<4>")
	)
	(segment
		(start 385.847844 -228.606858)
		(end 385.856226 -228.611684)
		(width 0.0889)
		(layer "In2.Cu")
		(net "M_I_CPU0_SA_DQ<4>")
	)
	(segment
		(start 390.412732 -226.1997)
		(end 390.451848 -226.17684)
		(width 0.0889)
		(layer "In2.Cu")
		(net "M_I_CPU0_SA_DQ<4>")
	)
	(segment
		(start 381.147828 -228.606858)
		(end 381.15621 -228.611684)
		(width 0.0889)
		(layer "In2.Cu")
		(net "M_I_CPU0_SA_DQ<4>")
	)
	(segment
		(start 415.110422 -202.8698)
		(end 417.720018 -202.8698)
		(width 0.14478)
		(layer "In2.Cu")
		(net "M_I_CPU0_SA_DQ<4>")
	)
	(segment
		(start 392.813286 -222.119698)
		(end 392.937492 -221.995492)
		(width 0.0889)
		(layer "In2.Cu")
		(net "M_I_CPU0_SA_DQ<4>")
	)
	(segment
		(start 422.433242 -202.8698)
		(end 429.55718 -202.8698)
		(width 0.14478)
		(layer "In2.Cu")
		(net "M_I_CPU0_SA_DQ<4>")
	)
	(segment
		(start 429.710342 -203.803758)
		(end 429.873156 -203.966572)
		(width 0.14478)
		(layer "In2.Cu")
		(net "M_I_CPU0_SA_DQ<4>")
	)
	(segment
		(start 389.041894 -228.606858)
		(end 389.073644 -228.58857)
		(width 0.0889)
		(layer "In2.Cu")
		(net "M_I_CPU0_SA_DQ<4>")
	)
	(segment
		(start 384.90779 -228.606858)
		(end 384.916172 -228.611684)
		(width 0.0889)
		(layer "In2.Cu")
		(net "M_I_CPU0_SA_DQ<4>")
	)
	(segment
		(start 389.033512 -228.611684)
		(end 389.041894 -228.606858)
		(width 0.0889)
		(layer "In2.Cu")
		(net "M_I_CPU0_SA_DQ<4>")
	)
	(segment
		(start 392.937492 -221.995492)
		(end 392.994642 -221.857316)
		(width 0.0889)
		(layer "In2.Cu")
		(net "M_I_CPU0_SA_DQ<4>")
	)
	(segment
		(start 378.693426 -228.611684)
		(end 378.701808 -228.606858)
		(width 0.0889)
		(layer "In2.Cu")
		(net "M_I_CPU0_SA_DQ<4>")
	)
	(segment
		(start 389.475472 -227.817934)
		(end 389.511794 -227.796852)
		(width 0.0889)
		(layer "In2.Cu")
		(net "M_I_CPU0_SA_DQ<4>")
	)
	(segment
		(start 389.942832 -227.009706)
		(end 389.981948 -226.986846)
		(width 0.0889)
		(layer "In2.Cu")
		(net "M_I_CPU0_SA_DQ<4>")
	)
	(segment
		(start 379.63348 -228.611684)
		(end 379.641862 -228.606858)
		(width 0.0889)
		(layer "In2.Cu")
		(net "M_I_CPU0_SA_DQ<4>")
	)
	(segment
		(start 391.861802 -223.746822)
		(end 391.893552 -223.728534)
		(width 0.0889)
		(layer "In2.Cu")
		(net "M_I_CPU0_SA_DQ<4>")
	)
	(segment
		(start 429.710342 -203.022962)
		(end 429.710342 -203.803758)
		(width 0.14478)
		(layer "In2.Cu")
		(net "M_I_CPU0_SA_DQ<4>")
	)
	(segment
		(start 414.260538 -203.719684)
		(end 415.110422 -202.8698)
		(width 0.14478)
		(layer "In2.Cu")
		(net "M_I_CPU0_SA_DQ<4>")
	)
	(segment
		(start 392.994642 -220.197172)
		(end 404.544784 -208.64703)
		(width 0.14478)
		(layer "In2.Cu")
		(net "M_I_CPU0_SA_DQ<4>")
	)
	(segment
		(start 430.429416 -202.860148)
		(end 431.131218 -202.860148)
		(width 0.14478)
		(layer "In2.Cu")
		(net "M_I_CPU0_SA_DQ<4>")
	)
	(segment
		(start 392.768074 -222.146114)
		(end 392.813286 -222.119698)
		(width 0.0889)
		(layer "In2.Cu")
		(net "M_I_CPU0_SA_DQ<4>")
	)
	(segment
		(start 380.207774 -228.606858)
		(end 380.216156 -228.611684)
		(width 0.0889)
		(layer "In2.Cu")
		(net "M_I_CPU0_SA_DQ<4>")
	)
	(segment
		(start 391.822686 -223.769682)
		(end 391.861802 -223.746822)
		(width 0.0889)
		(layer "In2.Cu")
		(net "M_I_CPU0_SA_DQ<4>")
	)
	(segment
		(start 421.583358 -203.719684)
		(end 422.433242 -202.8698)
		(width 0.14478)
		(layer "In2.Cu")
		(net "M_I_CPU0_SA_DQ<4>")
	)
	(segment
		(start 392.994642 -221.857316)
		(end 392.994642 -221.276672)
		(width 0.0889)
		(layer "In2.Cu")
		(net "M_I_CPU0_SA_DQ<4>")
	)
	(segment
		(start 429.873156 -203.966572)
		(end 430.103788 -203.966572)
		(width 0.14478)
		(layer "In2.Cu")
		(net "M_I_CPU0_SA_DQ<4>")
	)
	(segment
		(start 390.885426 -225.387916)
		(end 390.921748 -225.366834)
		(width 0.0889)
		(layer "In2.Cu")
		(net "M_I_CPU0_SA_DQ<4>")
	)
	(segment
		(start 391.352786 -224.579688)
		(end 391.391902 -224.556828)
		(width 0.0889)
		(layer "In2.Cu")
		(net "M_I_CPU0_SA_DQ<4>")
	)
	(segment
		(start 388.093458 -228.611684)
		(end 388.10184 -228.606858)
		(width 0.0889)
		(layer "In2.Cu")
		(net "M_I_CPU0_SA_DQ<4>")
	)
	(segment
		(start 417.720018 -202.8698)
		(end 418.569902 -203.719684)
		(width 0.14478)
		(layer "In2.Cu")
		(net "M_I_CPU0_SA_DQ<4>")
	)
	(segment
		(start 431.131218 -202.860148)
		(end 431.55616 -203.28509)
		(width 0.14478)
		(layer "In2.Cu")
		(net "M_I_CPU0_SA_DQ<4>")
	)
	(segment
		(start 430.266602 -203.022962)
		(end 430.429416 -202.860148)
		(width 0.14478)
		(layer "In2.Cu")
		(net "M_I_CPU0_SA_DQ<4>")
	)
	(segment
		(start 430.103788 -203.966572)
		(end 430.266602 -203.803758)
		(width 0.14478)
		(layer "In2.Cu")
		(net "M_I_CPU0_SA_DQ<4>")
	)
	(segment
		(start 383.393442 -228.611684)
		(end 383.401824 -228.606858)
		(width 0.0889)
		(layer "In2.Cu")
		(net "M_I_CPU0_SA_DQ<4>")
	)
	(segment
		(start 389.511794 -227.796852)
		(end 389.543544 -227.778564)
		(width 0.0889)
		(layer "In2.Cu")
		(net "M_I_CPU0_SA_DQ<4>")
	)
	(segment
		(start 377.420886 -228.549708)
		(end 377.443238 -228.63302)
		(width 0.0889)
		(layer "In2.Cu")
		(net "M_I_CPU0_SA_DQ<4>")
	)
	(arc
		(start 390.953498 -225.348546)
		(mid 391.068174 -225.215212)
		(end 391.109454 -225.044254)
		(width 0.0889)
		(layer "In2.Cu")
		(net "M_I_CPU0_SA_DQ<4>")
	)
	(arc
		(start 390.1694 -226.664266)
		(mid 390.233915 -226.402047)
		(end 390.412732 -226.1997)
		(width 0.0889)
		(layer "In2.Cu")
		(net "M_I_CPU0_SA_DQ<4>")
	)
	(arc
		(start 392.049508 -223.424242)
		(mid 392.114023 -223.162023)
		(end 392.29284 -222.959676)
		(width 0.0889)
		(layer "In2.Cu")
		(net "M_I_CPU0_SA_DQ<4>")
	)
	(arc
		(start 382.087882 -228.606858)
		(mid 382.274826 -228.657113)
		(end 382.46177 -228.606858)
		(width 0.0889)
		(layer "In2.Cu")
		(net "M_I_CPU0_SA_DQ<4>")
	)
	(arc
		(start 381.52197 -228.606858)
		(mid 381.804926 -228.530681)
		(end 382.087882 -228.606858)
		(width 0.0889)
		(layer "In2.Cu")
		(net "M_I_CPU0_SA_DQ<4>")
	)
	(arc
		(start 380.216156 -228.611684)
		(mid 380.399664 -228.657178)
		(end 380.581916 -228.606858)
		(width 0.0889)
		(layer "In2.Cu")
		(net "M_I_CPU0_SA_DQ<4>")
	)
	(arc
		(start 391.109454 -225.044254)
		(mid 391.173969 -224.782035)
		(end 391.352786 -224.579688)
		(width 0.0889)
		(layer "In2.Cu")
		(net "M_I_CPU0_SA_DQ<4>")
	)
	(arc
		(start 386.787898 -228.606858)
		(mid 386.974842 -228.657113)
		(end 387.161786 -228.606858)
		(width 0.0889)
		(layer "In2.Cu")
		(net "M_I_CPU0_SA_DQ<4>")
	)
	(arc
		(start 389.6995 -227.474272)
		(mid 389.764015 -227.212053)
		(end 389.942832 -227.009706)
		(width 0.0889)
		(layer "In2.Cu")
		(net "M_I_CPU0_SA_DQ<4>")
	)
	(arc
		(start 379.641862 -228.606858)
		(mid 379.924818 -228.530681)
		(end 380.207774 -228.606858)
		(width 0.0889)
		(layer "In2.Cu")
		(net "M_I_CPU0_SA_DQ<4>")
	)
	(arc
		(start 392.36015 -222.92056)
		(mid 392.477011 -222.786795)
		(end 392.519154 -222.614236)
		(width 0.0889)
		(layer "In2.Cu")
		(net "M_I_CPU0_SA_DQ<4>")
	)
	(arc
		(start 379.26772 -228.606858)
		(mid 379.449971 -228.657208)
		(end 379.63348 -228.611684)
		(width 0.0889)
		(layer "In2.Cu")
		(net "M_I_CPU0_SA_DQ<4>")
	)
	(arc
		(start 382.46177 -228.606858)
		(mid 382.744726 -228.530681)
		(end 383.027682 -228.606858)
		(width 0.0889)
		(layer "In2.Cu")
		(net "M_I_CPU0_SA_DQ<4>")
	)
	(arc
		(start 392.519154 -222.614236)
		(mid 392.585253 -222.349142)
		(end 392.768074 -222.146114)
		(width 0.0889)
		(layer "In2.Cu")
		(net "M_I_CPU0_SA_DQ<4>")
	)
	(arc
		(start 378.327666 -228.606858)
		(mid 378.509917 -228.657208)
		(end 378.693426 -228.611684)
		(width 0.0889)
		(layer "In2.Cu")
		(net "M_I_CPU0_SA_DQ<4>")
	)
	(arc
		(start 383.027682 -228.606858)
		(mid 383.209933 -228.657208)
		(end 383.393442 -228.611684)
		(width 0.0889)
		(layer "In2.Cu")
		(net "M_I_CPU0_SA_DQ<4>")
	)
	(arc
		(start 391.579354 -224.234248)
		(mid 391.643869 -223.972029)
		(end 391.822686 -223.769682)
		(width 0.0889)
		(layer "In2.Cu")
		(net "M_I_CPU0_SA_DQ<4>")
	)
	(arc
		(start 378.701808 -228.606858)
		(mid 378.984764 -228.530681)
		(end 379.26772 -228.606858)
		(width 0.0889)
		(layer "In2.Cu")
		(net "M_I_CPU0_SA_DQ<4>")
	)
	(arc
		(start 387.727698 -228.606858)
		(mid 387.909949 -228.657208)
		(end 388.093458 -228.611684)
		(width 0.0889)
		(layer "In2.Cu")
		(net "M_I_CPU0_SA_DQ<4>")
	)
	(arc
		(start 390.483598 -226.158552)
		(mid 390.598274 -226.025218)
		(end 390.639554 -225.85426)
		(width 0.0889)
		(layer "In2.Cu")
		(net "M_I_CPU0_SA_DQ<4>")
	)
	(arc
		(start 377.443238 -228.63302)
		(mid 377.605427 -228.655755)
		(end 377.761754 -228.606858)
		(width 0.0889)
		(layer "In2.Cu")
		(net "M_I_CPU0_SA_DQ<4>")
	)
	(arc
		(start 389.073644 -228.58857)
		(mid 389.18832 -228.455236)
		(end 389.2296 -228.284278)
		(width 0.0889)
		(layer "In2.Cu")
		(net "M_I_CPU0_SA_DQ<4>")
	)
	(arc
		(start 383.401824 -228.606858)
		(mid 383.68478 -228.530681)
		(end 383.967736 -228.606858)
		(width 0.0889)
		(layer "In2.Cu")
		(net "M_I_CPU0_SA_DQ<4>")
	)
	(arc
		(start 385.856226 -228.611684)
		(mid 386.039734 -228.657178)
		(end 386.221986 -228.606858)
		(width 0.0889)
		(layer "In2.Cu")
		(net "M_I_CPU0_SA_DQ<4>")
	)
	(arc
		(start 386.221986 -228.606858)
		(mid 386.504942 -228.530681)
		(end 386.787898 -228.606858)
		(width 0.0889)
		(layer "In2.Cu")
		(net "M_I_CPU0_SA_DQ<4>")
	)
	(arc
		(start 383.967736 -228.606858)
		(mid 384.149987 -228.657208)
		(end 384.333496 -228.611684)
		(width 0.0889)
		(layer "In2.Cu")
		(net "M_I_CPU0_SA_DQ<4>")
	)
	(arc
		(start 390.639554 -225.85426)
		(mid 390.70479 -225.590669)
		(end 390.885426 -225.387916)
		(width 0.0889)
		(layer "In2.Cu")
		(net "M_I_CPU0_SA_DQ<4>")
	)
	(arc
		(start 388.10184 -228.606858)
		(mid 388.384796 -228.530681)
		(end 388.667752 -228.606858)
		(width 0.0889)
		(layer "In2.Cu")
		(net "M_I_CPU0_SA_DQ<4>")
	)
	(arc
		(start 390.012428 -226.969066)
		(mid 390.127855 -226.83569)
		(end 390.1694 -226.664266)
		(width 0.0889)
		(layer "In2.Cu")
		(net "M_I_CPU0_SA_DQ<4>")
	)
	(arc
		(start 384.341878 -228.606858)
		(mid 384.624834 -228.530681)
		(end 384.90779 -228.606858)
		(width 0.0889)
		(layer "In2.Cu")
		(net "M_I_CPU0_SA_DQ<4>")
	)
	(arc
		(start 381.15621 -228.611684)
		(mid 381.339718 -228.657178)
		(end 381.52197 -228.606858)
		(width 0.0889)
		(layer "In2.Cu")
		(net "M_I_CPU0_SA_DQ<4>")
	)
	(arc
		(start 384.916172 -228.611684)
		(mid 385.09968 -228.657178)
		(end 385.281932 -228.606858)
		(width 0.0889)
		(layer "In2.Cu")
		(net "M_I_CPU0_SA_DQ<4>")
	)
	(arc
		(start 391.422382 -224.539048)
		(mid 391.537809 -224.405672)
		(end 391.579354 -224.234248)
		(width 0.0889)
		(layer "In2.Cu")
		(net "M_I_CPU0_SA_DQ<4>")
	)
	(arc
		(start 389.543544 -227.778564)
		(mid 389.65822 -227.64523)
		(end 389.6995 -227.474272)
		(width 0.0889)
		(layer "In2.Cu")
		(net "M_I_CPU0_SA_DQ<4>")
	)
	(arc
		(start 387.161786 -228.606858)
		(mid 387.444742 -228.530681)
		(end 387.727698 -228.606858)
		(width 0.0889)
		(layer "In2.Cu")
		(net "M_I_CPU0_SA_DQ<4>")
	)
	(arc
		(start 389.2296 -228.284278)
		(mid 389.294836 -228.020687)
		(end 389.475472 -227.817934)
		(width 0.0889)
		(layer "In2.Cu")
		(net "M_I_CPU0_SA_DQ<4>")
	)
	(arc
		(start 391.893552 -223.728534)
		(mid 392.008228 -223.5952)
		(end 392.049508 -223.424242)
		(width 0.0889)
		(layer "In2.Cu")
		(net "M_I_CPU0_SA_DQ<4>")
	)
	(arc
		(start 377.761754 -228.606858)
		(mid 378.04471 -228.530681)
		(end 378.327666 -228.606858)
		(width 0.0889)
		(layer "In2.Cu")
		(net "M_I_CPU0_SA_DQ<4>")
	)
	(arc
		(start 385.281932 -228.606858)
		(mid 385.564888 -228.530681)
		(end 385.847844 -228.606858)
		(width 0.0889)
		(layer "In2.Cu")
		(net "M_I_CPU0_SA_DQ<4>")
	)
	(arc
		(start 380.581916 -228.606858)
		(mid 380.864872 -228.530681)
		(end 381.147828 -228.606858)
		(width 0.0889)
		(layer "In2.Cu")
		(net "M_I_CPU0_SA_DQ<4>")
	)
	(arc
		(start 388.667752 -228.606858)
		(mid 388.850003 -228.657208)
		(end 389.033512 -228.611684)
		(width 0.0889)
		(layer "In2.Cu")
		(net "M_I_CPU0_SA_DQ<4>")
	)
	(segment
		(start 375.22785 -226.930204)
		(end 375.694702 -226.664266)
		(width 0.10668)
		(layer "F.Cu")
		(net "M_I_CPU0_SA_DQ<3>")
	)
	(segment
		(start 388.636256 -224.739962)
		(end 388.668006 -224.721674)
		(width 0.0889)
		(layer "In2.Cu")
		(net "M_I_CPU0_SA_DQ<3>")
	)
	(segment
		(start 389.578596 -223.11868)
		(end 389.60806 -223.101662)
		(width 0.0889)
		(layer "In2.Cu")
		(net "M_I_CPU0_SA_DQ<3>")
	)
	(segment
		(start 406.484582 -201.605388)
		(end 406.484582 -201.377296)
		(width 0.14478)
		(layer "In2.Cu")
		(net "M_I_CPU0_SA_DQ<3>")
	)
	(segment
		(start 405.855678 -202.765406)
		(end 405.855678 -202.53706)
		(width 0.14478)
		(layer "In2.Cu")
		(net "M_I_CPU0_SA_DQ<3>")
	)
	(segment
		(start 389.890508 -222.614236)
		(end 389.890508 -222.506032)
		(width 0.0889)
		(layer "In2.Cu")
		(net "M_I_CPU0_SA_DQ<3>")
	)
	(segment
		(start 405.866346 -201.995532)
		(end 406.094438 -201.995532)
		(width 0.14478)
		(layer "In2.Cu")
		(net "M_I_CPU0_SA_DQ<3>")
	)
	(segment
		(start 403.753574 -204.336396)
		(end 403.904958 -204.488034)
		(width 0.14478)
		(layer "In2.Cu")
		(net "M_I_CPU0_SA_DQ<3>")
	)
	(segment
		(start 389.13816 -223.911668)
		(end 389.178546 -223.888046)
		(width 0.0889)
		(layer "In2.Cu")
		(net "M_I_CPU0_SA_DQ<3>")
	)
	(segment
		(start 404.295102 -204.325982)
		(end 404.295102 -204.097636)
		(width 0.14478)
		(layer "In2.Cu")
		(net "M_I_CPU0_SA_DQ<3>")
	)
	(segment
		(start 376.447812 -226.341686)
		(end 376.456194 -226.33686)
		(width 0.0889)
		(layer "In2.Cu")
		(net "M_I_CPU0_SA_DQ<3>")
	)
	(segment
		(start 405.465534 -202.927458)
		(end 405.693626 -202.927458)
		(width 0.14478)
		(layer "In2.Cu")
		(net "M_I_CPU0_SA_DQ<3>")
	)
	(segment
		(start 407.806398 -200.586594)
		(end 408.03449 -200.586594)
		(width 0.14478)
		(layer "In2.Cu")
		(net "M_I_CPU0_SA_DQ<3>")
	)
	(segment
		(start 404.295102 -204.097636)
		(end 404.143718 -203.946252)
		(width 0.14478)
		(layer "In2.Cu")
		(net "M_I_CPU0_SA_DQ<3>")
	)
	(segment
		(start 379.63348 -226.33686)
		(end 379.641862 -226.341686)
		(width 0.0889)
		(layer "In2.Cu")
		(net "M_I_CPU0_SA_DQ<3>")
	)
	(segment
		(start 385.847844 -226.341686)
		(end 385.856226 -226.33686)
		(width 0.0889)
		(layer "In2.Cu")
		(net "M_I_CPU0_SA_DQ<3>")
	)
	(segment
		(start 406.646634 -201.215244)
		(end 406.874726 -201.215244)
		(width 0.14478)
		(layer "In2.Cu")
		(net "M_I_CPU0_SA_DQ<3>")
	)
	(segment
		(start 404.685246 -203.707746)
		(end 404.913338 -203.707746)
		(width 0.14478)
		(layer "In2.Cu")
		(net "M_I_CPU0_SA_DQ<3>")
	)
	(segment
		(start 404.924006 -203.165964)
		(end 404.924006 -202.937872)
		(width 0.14478)
		(layer "In2.Cu")
		(net "M_I_CPU0_SA_DQ<3>")
	)
	(segment
		(start 406.473914 -202.14717)
		(end 406.635966 -201.985118)
		(width 0.14478)
		(layer "In2.Cu")
		(net "M_I_CPU0_SA_DQ<3>")
	)
	(segment
		(start 414.777174 -199.450452)
		(end 418.170868 -199.450452)
		(width 0.14478)
		(layer "In2.Cu")
		(net "M_I_CPU0_SA_DQ<3>")
	)
	(segment
		(start 405.855678 -202.53706)
		(end 405.704294 -202.385676)
		(width 0.14478)
		(layer "In2.Cu")
		(net "M_I_CPU0_SA_DQ<3>")
	)
	(segment
		(start 425.064428 -199.450452)
		(end 425.36237 -199.15251)
		(width 0.14478)
		(layer "In2.Cu")
		(net "M_I_CPU0_SA_DQ<3>")
	)
	(segment
		(start 404.533862 -203.556108)
		(end 404.685246 -203.707746)
		(width 0.14478)
		(layer "In2.Cu")
		(net "M_I_CPU0_SA_DQ<3>")
	)
	(segment
		(start 388.166102 -225.549968)
		(end 388.197852 -225.53168)
		(width 0.0889)
		(layer "In2.Cu")
		(net "M_I_CPU0_SA_DQ<3>")
	)
	(segment
		(start 405.704294 -202.385676)
		(end 405.704294 -202.157584)
		(width 0.14478)
		(layer "In2.Cu")
		(net "M_I_CPU0_SA_DQ<3>")
	)
	(segment
		(start 422.31564 -199.450452)
		(end 425.064428 -199.450452)
		(width 0.14478)
		(layer "In2.Cu")
		(net "M_I_CPU0_SA_DQ<3>")
	)
	(segment
		(start 381.147828 -226.341686)
		(end 381.15621 -226.33686)
		(width 0.0889)
		(layer "In2.Cu")
		(net "M_I_CPU0_SA_DQ<3>")
	)
	(segment
		(start 407.254202 -201.366882)
		(end 407.416254 -201.20483)
		(width 0.14478)
		(layer "In2.Cu")
		(net "M_I_CPU0_SA_DQ<3>")
	)
	(segment
		(start 389.60806 -223.101662)
		(end 389.648446 -223.07804)
		(width 0.0889)
		(layer "In2.Cu")
		(net "M_I_CPU0_SA_DQ<3>")
	)
	(segment
		(start 406.635966 -201.985118)
		(end 406.635966 -201.756772)
		(width 0.14478)
		(layer "In2.Cu")
		(net "M_I_CPU0_SA_DQ<3>")
	)
	(segment
		(start 375.84888 -226.398836)
		(end 375.945146 -226.373436)
		(width 0.0889)
		(layer "In2.Cu")
		(net "M_I_CPU0_SA_DQ<3>")
	)
	(segment
		(start 418.170868 -199.450452)
		(end 419.020752 -200.300336)
		(width 0.14478)
		(layer "In2.Cu")
		(net "M_I_CPU0_SA_DQ<3>")
	)
	(segment
		(start 426.47489 -199.15251)
		(end 426.723556 -199.15251)
		(width 0.14478)
		(layer "In2.Cu")
		(net "M_I_CPU0_SA_DQ<3>")
	)
	(segment
		(start 406.874726 -201.215244)
		(end 407.02611 -201.366882)
		(width 0.14478)
		(layer "In2.Cu")
		(net "M_I_CPU0_SA_DQ<3>")
	)
	(segment
		(start 389.107426 -223.929448)
		(end 389.13816 -223.911668)
		(width 0.0889)
		(layer "In2.Cu")
		(net "M_I_CPU0_SA_DQ<3>")
	)
	(segment
		(start 387.727698 -226.341686)
		(end 387.766814 -226.318826)
		(width 0.0889)
		(layer "In2.Cu")
		(net "M_I_CPU0_SA_DQ<3>")
	)
	(segment
		(start 378.693426 -226.33686)
		(end 378.701808 -226.341686)
		(width 0.0889)
		(layer "In2.Cu")
		(net "M_I_CPU0_SA_DQ<3>")
	)
	(segment
		(start 403.525482 -204.336396)
		(end 403.753574 -204.336396)
		(width 0.14478)
		(layer "In2.Cu")
		(net "M_I_CPU0_SA_DQ<3>")
	)
	(segment
		(start 396.408656 -212.212428)
		(end 403.514814 -205.10627)
		(width 0.14478)
		(layer "In2.Cu")
		(net "M_I_CPU0_SA_DQ<3>")
	)
	(segment
		(start 408.320748 -200.300336)
		(end 413.92729 -200.300336)
		(width 0.14478)
		(layer "In2.Cu")
		(net "M_I_CPU0_SA_DQ<3>")
	)
	(segment
		(start 403.36343 -204.498448)
		(end 403.525482 -204.336396)
		(width 0.14478)
		(layer "In2.Cu")
		(net "M_I_CPU0_SA_DQ<3>")
	)
	(segment
		(start 403.904958 -204.488034)
		(end 404.13305 -204.488034)
		(width 0.14478)
		(layer "In2.Cu")
		(net "M_I_CPU0_SA_DQ<3>")
	)
	(segment
		(start 404.143718 -203.946252)
		(end 404.143718 -203.71816)
		(width 0.14478)
		(layer "In2.Cu")
		(net "M_I_CPU0_SA_DQ<3>")
	)
	(segment
		(start 380.207774 -226.341686)
		(end 380.216156 -226.33686)
		(width 0.0889)
		(layer "In2.Cu")
		(net "M_I_CPU0_SA_DQ<3>")
	)
	(segment
		(start 407.416254 -200.976484)
		(end 407.26487 -200.8251)
		(width 0.14478)
		(layer "In2.Cu")
		(net "M_I_CPU0_SA_DQ<3>")
	)
	(segment
		(start 396.408656 -213.545928)
		(end 396.408656 -212.212428)
		(width 0.14478)
		(layer "In2.Cu")
		(net "M_I_CPU0_SA_DQ<3>")
	)
	(segment
		(start 404.924006 -202.937872)
		(end 405.086058 -202.77582)
		(width 0.14478)
		(layer "In2.Cu")
		(net "M_I_CPU0_SA_DQ<3>")
	)
	(segment
		(start 406.484582 -201.377296)
		(end 406.646634 -201.215244)
		(width 0.14478)
		(layer "In2.Cu")
		(net "M_I_CPU0_SA_DQ<3>")
	)
	(segment
		(start 405.07539 -203.545694)
		(end 405.07539 -203.317348)
		(width 0.14478)
		(layer "In2.Cu")
		(net "M_I_CPU0_SA_DQ<3>")
	)
	(segment
		(start 404.143718 -203.71816)
		(end 404.30577 -203.556108)
		(width 0.14478)
		(layer "In2.Cu")
		(net "M_I_CPU0_SA_DQ<3>")
	)
	(segment
		(start 408.03449 -200.586594)
		(end 408.320748 -200.300336)
		(width 0.14478)
		(layer "In2.Cu")
		(net "M_I_CPU0_SA_DQ<3>")
	)
	(segment
		(start 388.668006 -224.721674)
		(end 388.705852 -224.69983)
		(width 0.0889)
		(layer "In2.Cu")
		(net "M_I_CPU0_SA_DQ<3>")
	)
	(segment
		(start 425.91863 -199.460104)
		(end 426.167296 -199.460104)
		(width 0.14478)
		(layer "In2.Cu")
		(net "M_I_CPU0_SA_DQ<3>")
	)
	(segment
		(start 405.086058 -202.77582)
		(end 405.31415 -202.77582)
		(width 0.14478)
		(layer "In2.Cu")
		(net "M_I_CPU0_SA_DQ<3>")
	)
	(segment
		(start 407.02611 -201.366882)
		(end 407.254202 -201.366882)
		(width 0.14478)
		(layer "In2.Cu")
		(net "M_I_CPU0_SA_DQ<3>")
	)
	(segment
		(start 389.890508 -222.506032)
		(end 390.481058 -221.176596)
		(width 0.0889)
		(layer "In2.Cu")
		(net "M_I_CPU0_SA_DQ<3>")
	)
	(segment
		(start 407.426922 -200.434956)
		(end 407.655014 -200.434956)
		(width 0.14478)
		(layer "In2.Cu")
		(net "M_I_CPU0_SA_DQ<3>")
	)
	(segment
		(start 407.26487 -200.597008)
		(end 407.426922 -200.434956)
		(width 0.14478)
		(layer "In2.Cu")
		(net "M_I_CPU0_SA_DQ<3>")
	)
	(segment
		(start 388.197852 -225.53168)
		(end 388.236968 -225.50882)
		(width 0.0889)
		(layer "In2.Cu")
		(net "M_I_CPU0_SA_DQ<3>")
	)
	(segment
		(start 407.26487 -200.8251)
		(end 407.26487 -200.597008)
		(width 0.14478)
		(layer "In2.Cu")
		(net "M_I_CPU0_SA_DQ<3>")
	)
	(segment
		(start 413.92729 -200.300336)
		(end 414.777174 -199.450452)
		(width 0.14478)
		(layer "In2.Cu")
		(net "M_I_CPU0_SA_DQ<3>")
	)
	(segment
		(start 407.416254 -201.20483)
		(end 407.416254 -200.976484)
		(width 0.14478)
		(layer "In2.Cu")
		(net "M_I_CPU0_SA_DQ<3>")
	)
	(segment
		(start 406.094438 -201.995532)
		(end 406.245822 -202.14717)
		(width 0.14478)
		(layer "In2.Cu")
		(net "M_I_CPU0_SA_DQ<3>")
	)
	(segment
		(start 384.333496 -226.33686)
		(end 384.341878 -226.341686)
		(width 0.0889)
		(layer "In2.Cu")
		(net "M_I_CPU0_SA_DQ<3>")
	)
	(segment
		(start 406.245822 -202.14717)
		(end 406.473914 -202.14717)
		(width 0.14478)
		(layer "In2.Cu")
		(net "M_I_CPU0_SA_DQ<3>")
	)
	(segment
		(start 421.465756 -200.300336)
		(end 422.31564 -199.450452)
		(width 0.14478)
		(layer "In2.Cu")
		(net "M_I_CPU0_SA_DQ<3>")
	)
	(segment
		(start 384.90779 -226.341686)
		(end 384.916172 -226.33686)
		(width 0.0889)
		(layer "In2.Cu")
		(net "M_I_CPU0_SA_DQ<3>")
	)
	(segment
		(start 419.020752 -200.300336)
		(end 421.465756 -200.300336)
		(width 0.14478)
		(layer "In2.Cu")
		(net "M_I_CPU0_SA_DQ<3>")
	)
	(segment
		(start 403.514814 -205.10627)
		(end 403.514814 -204.877924)
		(width 0.14478)
		(layer "In2.Cu")
		(net "M_I_CPU0_SA_DQ<3>")
	)
	(segment
		(start 404.13305 -204.488034)
		(end 404.295102 -204.325982)
		(width 0.14478)
		(layer "In2.Cu")
		(net "M_I_CPU0_SA_DQ<3>")
	)
	(segment
		(start 405.07539 -203.317348)
		(end 404.924006 -203.165964)
		(width 0.14478)
		(layer "In2.Cu")
		(net "M_I_CPU0_SA_DQ<3>")
	)
	(segment
		(start 407.655014 -200.434956)
		(end 407.806398 -200.586594)
		(width 0.14478)
		(layer "In2.Cu")
		(net "M_I_CPU0_SA_DQ<3>")
	)
	(segment
		(start 405.693626 -202.927458)
		(end 405.855678 -202.765406)
		(width 0.14478)
		(layer "In2.Cu")
		(net "M_I_CPU0_SA_DQ<3>")
	)
	(segment
		(start 375.694702 -226.664266)
		(end 375.84888 -226.398836)
		(width 0.0889)
		(layer "In2.Cu")
		(net "M_I_CPU0_SA_DQ<3>")
	)
	(segment
		(start 403.36343 -204.72654)
		(end 403.36343 -204.498448)
		(width 0.14478)
		(layer "In2.Cu")
		(net "M_I_CPU0_SA_DQ<3>")
	)
	(segment
		(start 425.611036 -199.15251)
		(end 425.91863 -199.460104)
		(width 0.14478)
		(layer "In2.Cu")
		(net "M_I_CPU0_SA_DQ<3>")
	)
	(segment
		(start 404.30577 -203.556108)
		(end 404.533862 -203.556108)
		(width 0.14478)
		(layer "In2.Cu")
		(net "M_I_CPU0_SA_DQ<3>")
	)
	(segment
		(start 383.393442 -226.33686)
		(end 383.401824 -226.341686)
		(width 0.0889)
		(layer "In2.Cu")
		(net "M_I_CPU0_SA_DQ<3>")
	)
	(segment
		(start 426.723556 -199.15251)
		(end 427.456092 -199.885046)
		(width 0.14478)
		(layer "In2.Cu")
		(net "M_I_CPU0_SA_DQ<3>")
	)
	(segment
		(start 426.167296 -199.460104)
		(end 426.47489 -199.15251)
		(width 0.14478)
		(layer "In2.Cu")
		(net "M_I_CPU0_SA_DQ<3>")
	)
	(segment
		(start 403.514814 -204.877924)
		(end 403.36343 -204.72654)
		(width 0.14478)
		(layer "In2.Cu")
		(net "M_I_CPU0_SA_DQ<3>")
	)
	(segment
		(start 405.704294 -202.157584)
		(end 405.866346 -201.995532)
		(width 0.14478)
		(layer "In2.Cu")
		(net "M_I_CPU0_SA_DQ<3>")
	)
	(segment
		(start 425.36237 -199.15251)
		(end 425.611036 -199.15251)
		(width 0.14478)
		(layer "In2.Cu")
		(net "M_I_CPU0_SA_DQ<3>")
	)
	(segment
		(start 390.481058 -221.176596)
		(end 390.481058 -219.473526)
		(width 0.14478)
		(layer "In2.Cu")
		(net "M_I_CPU0_SA_DQ<3>")
	)
	(segment
		(start 405.31415 -202.77582)
		(end 405.465534 -202.927458)
		(width 0.14478)
		(layer "In2.Cu")
		(net "M_I_CPU0_SA_DQ<3>")
	)
	(segment
		(start 390.481058 -219.473526)
		(end 396.408656 -213.545928)
		(width 0.14478)
		(layer "In2.Cu")
		(net "M_I_CPU0_SA_DQ<3>")
	)
	(segment
		(start 406.635966 -201.756772)
		(end 406.484582 -201.605388)
		(width 0.14478)
		(layer "In2.Cu")
		(net "M_I_CPU0_SA_DQ<3>")
	)
	(segment
		(start 404.913338 -203.707746)
		(end 405.07539 -203.545694)
		(width 0.14478)
		(layer "In2.Cu")
		(net "M_I_CPU0_SA_DQ<3>")
	)
	(arc
		(start 388.236968 -225.50882)
		(mid 388.415781 -225.30647)
		(end 388.4803 -225.044254)
		(width 0.0889)
		(layer "In2.Cu")
		(net "M_I_CPU0_SA_DQ<3>")
	)
	(arc
		(start 385.856226 -226.33686)
		(mid 386.039734 -226.291366)
		(end 386.221986 -226.341686)
		(width 0.0889)
		(layer "In2.Cu")
		(net "M_I_CPU0_SA_DQ<3>")
	)
	(arc
		(start 379.26772 -226.341686)
		(mid 379.449971 -226.291336)
		(end 379.63348 -226.33686)
		(width 0.0889)
		(layer "In2.Cu")
		(net "M_I_CPU0_SA_DQ<3>")
	)
	(arc
		(start 387.766814 -226.318826)
		(mid 387.945627 -226.116476)
		(end 388.010146 -225.85426)
		(width 0.0889)
		(layer "In2.Cu")
		(net "M_I_CPU0_SA_DQ<3>")
	)
	(arc
		(start 389.420862 -223.424242)
		(mid 389.462616 -223.252299)
		(end 389.578596 -223.11868)
		(width 0.0889)
		(layer "In2.Cu")
		(net "M_I_CPU0_SA_DQ<3>")
	)
	(arc
		(start 386.787898 -226.341686)
		(mid 386.974842 -226.291431)
		(end 387.161786 -226.341686)
		(width 0.0889)
		(layer "In2.Cu")
		(net "M_I_CPU0_SA_DQ<3>")
	)
	(arc
		(start 388.4803 -225.044254)
		(mid 388.521555 -224.873283)
		(end 388.636256 -224.739962)
		(width 0.0889)
		(layer "In2.Cu")
		(net "M_I_CPU0_SA_DQ<3>")
	)
	(arc
		(start 389.178546 -223.888046)
		(mid 389.356611 -223.685869)
		(end 389.420862 -223.424242)
		(width 0.0889)
		(layer "In2.Cu")
		(net "M_I_CPU0_SA_DQ<3>")
	)
	(arc
		(start 383.401824 -226.341686)
		(mid 383.68478 -226.417863)
		(end 383.967736 -226.341686)
		(width 0.0889)
		(layer "In2.Cu")
		(net "M_I_CPU0_SA_DQ<3>")
	)
	(arc
		(start 388.010146 -225.85426)
		(mid 388.051401 -225.683289)
		(end 388.166102 -225.549968)
		(width 0.0889)
		(layer "In2.Cu")
		(net "M_I_CPU0_SA_DQ<3>")
	)
	(arc
		(start 381.52197 -226.341686)
		(mid 381.804926 -226.417863)
		(end 382.087882 -226.341686)
		(width 0.0889)
		(layer "In2.Cu")
		(net "M_I_CPU0_SA_DQ<3>")
	)
	(arc
		(start 384.916172 -226.33686)
		(mid 385.09968 -226.291366)
		(end 385.281932 -226.341686)
		(width 0.0889)
		(layer "In2.Cu")
		(net "M_I_CPU0_SA_DQ<3>")
	)
	(arc
		(start 388.705852 -224.69983)
		(mid 388.885581 -224.49721)
		(end 388.950454 -224.234248)
		(width 0.0889)
		(layer "In2.Cu")
		(net "M_I_CPU0_SA_DQ<3>")
	)
	(arc
		(start 382.087882 -226.341686)
		(mid 382.274826 -226.291431)
		(end 382.46177 -226.341686)
		(width 0.0889)
		(layer "In2.Cu")
		(net "M_I_CPU0_SA_DQ<3>")
	)
	(arc
		(start 376.456194 -226.33686)
		(mid 376.639702 -226.291366)
		(end 376.821954 -226.341686)
		(width 0.0889)
		(layer "In2.Cu")
		(net "M_I_CPU0_SA_DQ<3>")
	)
	(arc
		(start 375.945146 -226.373436)
		(mid 376.200211 -226.416787)
		(end 376.447812 -226.341686)
		(width 0.0889)
		(layer "In2.Cu")
		(net "M_I_CPU0_SA_DQ<3>")
	)
	(arc
		(start 381.15621 -226.33686)
		(mid 381.339718 -226.291366)
		(end 381.52197 -226.341686)
		(width 0.0889)
		(layer "In2.Cu")
		(net "M_I_CPU0_SA_DQ<3>")
	)
	(arc
		(start 385.281932 -226.341686)
		(mid 385.564888 -226.417863)
		(end 385.847844 -226.341686)
		(width 0.0889)
		(layer "In2.Cu")
		(net "M_I_CPU0_SA_DQ<3>")
	)
	(arc
		(start 386.221986 -226.341686)
		(mid 386.504942 -226.417863)
		(end 386.787898 -226.341686)
		(width 0.0889)
		(layer "In2.Cu")
		(net "M_I_CPU0_SA_DQ<3>")
	)
	(arc
		(start 387.161786 -226.341686)
		(mid 387.444742 -226.417863)
		(end 387.727698 -226.341686)
		(width 0.0889)
		(layer "In2.Cu")
		(net "M_I_CPU0_SA_DQ<3>")
	)
	(arc
		(start 377.387866 -226.341686)
		(mid 377.57481 -226.291431)
		(end 377.761754 -226.341686)
		(width 0.0889)
		(layer "In2.Cu")
		(net "M_I_CPU0_SA_DQ<3>")
	)
	(arc
		(start 380.216156 -226.33686)
		(mid 380.399664 -226.291366)
		(end 380.581916 -226.341686)
		(width 0.0889)
		(layer "In2.Cu")
		(net "M_I_CPU0_SA_DQ<3>")
	)
	(arc
		(start 378.327666 -226.341686)
		(mid 378.509917 -226.291336)
		(end 378.693426 -226.33686)
		(width 0.0889)
		(layer "In2.Cu")
		(net "M_I_CPU0_SA_DQ<3>")
	)
	(arc
		(start 380.581916 -226.341686)
		(mid 380.864872 -226.417863)
		(end 381.147828 -226.341686)
		(width 0.0889)
		(layer "In2.Cu")
		(net "M_I_CPU0_SA_DQ<3>")
	)
	(arc
		(start 384.341878 -226.341686)
		(mid 384.624834 -226.417863)
		(end 384.90779 -226.341686)
		(width 0.0889)
		(layer "In2.Cu")
		(net "M_I_CPU0_SA_DQ<3>")
	)
	(arc
		(start 383.027682 -226.341686)
		(mid 383.209933 -226.291336)
		(end 383.393442 -226.33686)
		(width 0.0889)
		(layer "In2.Cu")
		(net "M_I_CPU0_SA_DQ<3>")
	)
	(arc
		(start 378.701808 -226.341686)
		(mid 378.984764 -226.417863)
		(end 379.26772 -226.341686)
		(width 0.0889)
		(layer "In2.Cu")
		(net "M_I_CPU0_SA_DQ<3>")
	)
	(arc
		(start 376.821954 -226.341686)
		(mid 377.10491 -226.417863)
		(end 377.387866 -226.341686)
		(width 0.0889)
		(layer "In2.Cu")
		(net "M_I_CPU0_SA_DQ<3>")
	)
	(arc
		(start 383.967736 -226.341686)
		(mid 384.149987 -226.291336)
		(end 384.333496 -226.33686)
		(width 0.0889)
		(layer "In2.Cu")
		(net "M_I_CPU0_SA_DQ<3>")
	)
	(arc
		(start 382.46177 -226.341686)
		(mid 382.744726 -226.417863)
		(end 383.027682 -226.341686)
		(width 0.0889)
		(layer "In2.Cu")
		(net "M_I_CPU0_SA_DQ<3>")
	)
	(arc
		(start 379.641862 -226.341686)
		(mid 379.924818 -226.417863)
		(end 380.207774 -226.341686)
		(width 0.0889)
		(layer "In2.Cu")
		(net "M_I_CPU0_SA_DQ<3>")
	)
	(arc
		(start 377.761754 -226.341686)
		(mid 378.04471 -226.417863)
		(end 378.327666 -226.341686)
		(width 0.0889)
		(layer "In2.Cu")
		(net "M_I_CPU0_SA_DQ<3>")
	)
	(arc
		(start 389.648446 -223.07804)
		(mid 389.826341 -222.875818)
		(end 389.890508 -222.614236)
		(width 0.0889)
		(layer "In2.Cu")
		(net "M_I_CPU0_SA_DQ<3>")
	)
	(arc
		(start 388.950454 -224.234248)
		(mid 388.992003 -224.062826)
		(end 389.107426 -223.929448)
		(width 0.0889)
		(layer "In2.Cu")
		(net "M_I_CPU0_SA_DQ<3>")
	)
	(segment
		(start 375.22785 -244.750082)
		(end 375.694702 -244.484144)
		(width 0.10668)
		(layer "F.Cu")
		(net "M_I_CPU0_SA_DQ<31>")
	)
	(segment
		(start 409.62199 -235.458)
		(end 409.62199 -235.2294)
		(width 0.14478)
		(layer "In2.Cu")
		(net "M_I_CPU0_SA_DQ<31>")
	)
	(segment
		(start 375.84888 -244.218714)
		(end 375.945146 -244.193314)
		(width 0.0889)
		(layer "In2.Cu")
		(net "M_I_CPU0_SA_DQ<31>")
	)
	(segment
		(start 427.03115 -233.460036)
		(end 427.456092 -233.884978)
		(width 0.14478)
		(layer "In2.Cu")
		(net "M_I_CPU0_SA_DQ<31>")
	)
	(segment
		(start 409.179522 -236.576108)
		(end 408.841702 -236.238288)
		(width 0.14478)
		(layer "In2.Cu")
		(net "M_I_CPU0_SA_DQ<31>")
	)
	(segment
		(start 379.63348 -244.156738)
		(end 379.641862 -244.161564)
		(width 0.0889)
		(layer "In2.Cu")
		(net "M_I_CPU0_SA_DQ<31>")
	)
	(segment
		(start 378.693426 -244.156738)
		(end 378.701808 -244.161564)
		(width 0.0889)
		(layer "In2.Cu")
		(net "M_I_CPU0_SA_DQ<31>")
	)
	(segment
		(start 409.003246 -235.848144)
		(end 409.231846 -235.848144)
		(width 0.14478)
		(layer "In2.Cu")
		(net "M_I_CPU0_SA_DQ<31>")
	)
	(segment
		(start 414.08858 -234.412282)
		(end 414.169606 -234.216194)
		(width 0.14478)
		(layer "In2.Cu")
		(net "M_I_CPU0_SA_DQ<31>")
	)
	(segment
		(start 410.740098 -235.244132)
		(end 410.740098 -235.015532)
		(width 0.14478)
		(layer "In2.Cu")
		(net "M_I_CPU0_SA_DQ<31>")
	)
	(segment
		(start 425.842684 -233.73207)
		(end 426.12945 -233.73207)
		(width 0.14478)
		(layer "In2.Cu")
		(net "M_I_CPU0_SA_DQ<31>")
	)
	(segment
		(start 389.607806 -244.161564)
		(end 389.616188 -244.156738)
		(width 0.0889)
		(layer "In2.Cu")
		(net "M_I_CPU0_SA_DQ<31>")
	)
	(segment
		(start 419.002464 -234.310174)
		(end 421.163496 -234.310174)
		(width 0.14478)
		(layer "In2.Cu")
		(net "M_I_CPU0_SA_DQ<31>")
	)
	(segment
		(start 425.57065 -233.460036)
		(end 425.842684 -233.73207)
		(width 0.14478)
		(layer "In2.Cu")
		(net "M_I_CPU0_SA_DQ<31>")
	)
	(segment
		(start 408.841702 -236.009688)
		(end 409.003246 -235.848144)
		(width 0.14478)
		(layer "In2.Cu")
		(net "M_I_CPU0_SA_DQ<31>")
	)
	(segment
		(start 414.169606 -234.216194)
		(end 414.098994 -234.04576)
		(width 0.14478)
		(layer "In2.Cu")
		(net "M_I_CPU0_SA_DQ<31>")
	)
	(segment
		(start 395.935454 -243.22405)
		(end 402.76018 -243.22405)
		(width 0.14478)
		(layer "In2.Cu")
		(net "M_I_CPU0_SA_DQ<31>")
	)
	(segment
		(start 424.45305 -233.460036)
		(end 424.725084 -233.73207)
		(width 0.14478)
		(layer "In2.Cu")
		(net "M_I_CPU0_SA_DQ<31>")
	)
	(segment
		(start 388.093458 -244.156738)
		(end 388.10184 -244.161564)
		(width 0.0889)
		(layer "In2.Cu")
		(net "M_I_CPU0_SA_DQ<31>")
	)
	(segment
		(start 418.543994 -233.851704)
		(end 419.002464 -234.310174)
		(width 0.14478)
		(layer "In2.Cu")
		(net "M_I_CPU0_SA_DQ<31>")
	)
	(segment
		(start 410.402278 -234.449112)
		(end 410.563822 -234.287568)
		(width 0.14478)
		(layer "In2.Cu")
		(net "M_I_CPU0_SA_DQ<31>")
	)
	(segment
		(start 393.554966 -244.111018)
		(end 394.648436 -244.111018)
		(width 0.0889)
		(layer "In2.Cu")
		(net "M_I_CPU0_SA_DQ<31>")
	)
	(segment
		(start 415.38017 -233.72445)
		(end 415.674556 -233.72445)
		(width 0.14478)
		(layer "In2.Cu")
		(net "M_I_CPU0_SA_DQ<31>")
	)
	(segment
		(start 409.569666 -236.185964)
		(end 409.798266 -236.185964)
		(width 0.14478)
		(layer "In2.Cu")
		(net "M_I_CPU0_SA_DQ<31>")
	)
	(segment
		(start 410.578554 -235.405676)
		(end 410.740098 -235.244132)
		(width 0.14478)
		(layer "In2.Cu")
		(net "M_I_CPU0_SA_DQ<31>")
	)
	(segment
		(start 424.725084 -233.73207)
		(end 425.01185 -233.73207)
		(width 0.14478)
		(layer "In2.Cu")
		(net "M_I_CPU0_SA_DQ<31>")
	)
	(segment
		(start 410.349954 -235.405676)
		(end 410.578554 -235.405676)
		(width 0.14478)
		(layer "In2.Cu")
		(net "M_I_CPU0_SA_DQ<31>")
	)
	(segment
		(start 389.033512 -244.156738)
		(end 389.041894 -244.161564)
		(width 0.0889)
		(layer "In2.Cu")
		(net "M_I_CPU0_SA_DQ<31>")
	)
	(segment
		(start 383.393442 -244.156738)
		(end 383.401824 -244.161564)
		(width 0.0889)
		(layer "In2.Cu")
		(net "M_I_CPU0_SA_DQ<31>")
	)
	(segment
		(start 410.563822 -234.287568)
		(end 410.792422 -234.287568)
		(width 0.14478)
		(layer "In2.Cu")
		(net "M_I_CPU0_SA_DQ<31>")
	)
	(segment
		(start 414.266888 -233.64063)
		(end 414.703006 -233.460036)
		(width 0.14478)
		(layer "In2.Cu")
		(net "M_I_CPU0_SA_DQ<31>")
	)
	(segment
		(start 413.849312 -234.511342)
		(end 414.08858 -234.412282)
		(width 0.14478)
		(layer "In2.Cu")
		(net "M_I_CPU0_SA_DQ<31>")
	)
	(segment
		(start 410.012134 -235.067856)
		(end 410.349954 -235.405676)
		(width 0.14478)
		(layer "In2.Cu")
		(net "M_I_CPU0_SA_DQ<31>")
	)
	(segment
		(start 414.703006 -233.460036)
		(end 415.115756 -233.460036)
		(width 0.14478)
		(layer "In2.Cu")
		(net "M_I_CPU0_SA_DQ<31>")
	)
	(segment
		(start 384.333496 -244.156738)
		(end 384.341878 -244.161564)
		(width 0.0889)
		(layer "In2.Cu")
		(net "M_I_CPU0_SA_DQ<31>")
	)
	(segment
		(start 384.90779 -244.161564)
		(end 384.916172 -244.156738)
		(width 0.0889)
		(layer "In2.Cu")
		(net "M_I_CPU0_SA_DQ<31>")
	)
	(segment
		(start 425.283884 -233.460036)
		(end 425.57065 -233.460036)
		(width 0.14478)
		(layer "In2.Cu")
		(net "M_I_CPU0_SA_DQ<31>")
	)
	(segment
		(start 409.798266 -236.185964)
		(end 409.95981 -236.02442)
		(width 0.14478)
		(layer "In2.Cu")
		(net "M_I_CPU0_SA_DQ<31>")
	)
	(segment
		(start 417.598352 -233.460036)
		(end 418.543994 -233.851704)
		(width 0.14478)
		(layer "In2.Cu")
		(net "M_I_CPU0_SA_DQ<31>")
	)
	(segment
		(start 409.95981 -235.79582)
		(end 409.62199 -235.458)
		(width 0.14478)
		(layer "In2.Cu")
		(net "M_I_CPU0_SA_DQ<31>")
	)
	(segment
		(start 375.694702 -244.484144)
		(end 375.84888 -244.218714)
		(width 0.0889)
		(layer "In2.Cu")
		(net "M_I_CPU0_SA_DQ<31>")
	)
	(segment
		(start 413.653224 -234.430316)
		(end 413.849312 -234.511342)
		(width 0.14478)
		(layer "In2.Cu")
		(net "M_I_CPU0_SA_DQ<31>")
	)
	(segment
		(start 413.369252 -234.171236)
		(end 413.582612 -234.259628)
		(width 0.14478)
		(layer "In2.Cu")
		(net "M_I_CPU0_SA_DQ<31>")
	)
	(segment
		(start 410.792422 -234.287568)
		(end 411.046676 -234.541822)
		(width 0.14478)
		(layer "In2.Cu")
		(net "M_I_CPU0_SA_DQ<31>")
	)
	(segment
		(start 413.034226 -234.310174)
		(end 413.369252 -234.171236)
		(width 0.14478)
		(layer "In2.Cu")
		(net "M_I_CPU0_SA_DQ<31>")
	)
	(segment
		(start 415.115756 -233.460036)
		(end 415.38017 -233.72445)
		(width 0.14478)
		(layer "In2.Cu")
		(net "M_I_CPU0_SA_DQ<31>")
	)
	(segment
		(start 414.098994 -234.04576)
		(end 414.266888 -233.64063)
		(width 0.14478)
		(layer "In2.Cu")
		(net "M_I_CPU0_SA_DQ<31>")
	)
	(segment
		(start 411.046676 -234.541822)
		(end 411.251908 -234.541822)
		(width 0.14478)
		(layer "In2.Cu")
		(net "M_I_CPU0_SA_DQ<31>")
	)
	(segment
		(start 415.674556 -233.72445)
		(end 415.93897 -233.460036)
		(width 0.14478)
		(layer "In2.Cu")
		(net "M_I_CPU0_SA_DQ<31>")
	)
	(segment
		(start 409.95981 -236.02442)
		(end 409.95981 -235.79582)
		(width 0.14478)
		(layer "In2.Cu")
		(net "M_I_CPU0_SA_DQ<31>")
	)
	(segment
		(start 381.147828 -244.161564)
		(end 381.15621 -244.156738)
		(width 0.0889)
		(layer "In2.Cu")
		(net "M_I_CPU0_SA_DQ<31>")
	)
	(segment
		(start 426.401484 -233.460036)
		(end 427.03115 -233.460036)
		(width 0.14478)
		(layer "In2.Cu")
		(net "M_I_CPU0_SA_DQ<31>")
	)
	(segment
		(start 410.402278 -234.677712)
		(end 410.402278 -234.449112)
		(width 0.14478)
		(layer "In2.Cu")
		(net "M_I_CPU0_SA_DQ<31>")
	)
	(segment
		(start 421.163496 -234.310174)
		(end 423.21607 -233.460036)
		(width 0.14478)
		(layer "In2.Cu")
		(net "M_I_CPU0_SA_DQ<31>")
	)
	(segment
		(start 423.21607 -233.460036)
		(end 424.45305 -233.460036)
		(width 0.14478)
		(layer "In2.Cu")
		(net "M_I_CPU0_SA_DQ<31>")
	)
	(segment
		(start 411.483556 -234.310174)
		(end 413.034226 -234.310174)
		(width 0.14478)
		(layer "In2.Cu")
		(net "M_I_CPU0_SA_DQ<31>")
	)
	(segment
		(start 415.93897 -233.460036)
		(end 417.598352 -233.460036)
		(width 0.14478)
		(layer "In2.Cu")
		(net "M_I_CPU0_SA_DQ<31>")
	)
	(segment
		(start 394.648436 -244.111018)
		(end 395.535404 -243.22405)
		(width 0.0889)
		(layer "In2.Cu")
		(net "M_I_CPU0_SA_DQ<31>")
	)
	(segment
		(start 409.231846 -235.848144)
		(end 409.569666 -236.185964)
		(width 0.14478)
		(layer "In2.Cu")
		(net "M_I_CPU0_SA_DQ<31>")
	)
	(segment
		(start 385.847844 -244.161564)
		(end 385.856226 -244.156738)
		(width 0.0889)
		(layer "In2.Cu")
		(net "M_I_CPU0_SA_DQ<31>")
	)
	(segment
		(start 409.783534 -235.067856)
		(end 410.012134 -235.067856)
		(width 0.14478)
		(layer "In2.Cu")
		(net "M_I_CPU0_SA_DQ<31>")
	)
	(segment
		(start 410.740098 -235.015532)
		(end 410.402278 -234.677712)
		(width 0.14478)
		(layer "In2.Cu")
		(net "M_I_CPU0_SA_DQ<31>")
	)
	(segment
		(start 413.582612 -234.259628)
		(end 413.653224 -234.430316)
		(width 0.14478)
		(layer "In2.Cu")
		(net "M_I_CPU0_SA_DQ<31>")
	)
	(segment
		(start 395.535404 -243.22405)
		(end 395.935454 -243.22405)
		(width 0.0889)
		(layer "In2.Cu")
		(net "M_I_CPU0_SA_DQ<31>")
	)
	(segment
		(start 425.01185 -233.73207)
		(end 425.283884 -233.460036)
		(width 0.14478)
		(layer "In2.Cu")
		(net "M_I_CPU0_SA_DQ<31>")
	)
	(segment
		(start 409.179522 -236.804708)
		(end 409.179522 -236.576108)
		(width 0.14478)
		(layer "In2.Cu")
		(net "M_I_CPU0_SA_DQ<31>")
	)
	(segment
		(start 408.841702 -236.238288)
		(end 408.841702 -236.009688)
		(width 0.14478)
		(layer "In2.Cu")
		(net "M_I_CPU0_SA_DQ<31>")
	)
	(segment
		(start 426.12945 -233.73207)
		(end 426.401484 -233.460036)
		(width 0.14478)
		(layer "In2.Cu")
		(net "M_I_CPU0_SA_DQ<31>")
	)
	(segment
		(start 380.207774 -244.161564)
		(end 380.216156 -244.156738)
		(width 0.0889)
		(layer "In2.Cu")
		(net "M_I_CPU0_SA_DQ<31>")
	)
	(segment
		(start 402.76018 -243.22405)
		(end 409.179522 -236.804708)
		(width 0.14478)
		(layer "In2.Cu")
		(net "M_I_CPU0_SA_DQ<31>")
	)
	(segment
		(start 411.251908 -234.541822)
		(end 411.483556 -234.310174)
		(width 0.14478)
		(layer "In2.Cu")
		(net "M_I_CPU0_SA_DQ<31>")
	)
	(segment
		(start 376.447812 -244.161564)
		(end 376.456194 -244.156738)
		(width 0.0889)
		(layer "In2.Cu")
		(net "M_I_CPU0_SA_DQ<31>")
	)
	(segment
		(start 409.62199 -235.2294)
		(end 409.783534 -235.067856)
		(width 0.14478)
		(layer "In2.Cu")
		(net "M_I_CPU0_SA_DQ<31>")
	)
	(arc
		(start 380.581916 -244.161564)
		(mid 380.864872 -244.237741)
		(end 381.147828 -244.161564)
		(width 0.0889)
		(layer "In2.Cu")
		(net "M_I_CPU0_SA_DQ<31>")
	)
	(arc
		(start 388.10184 -244.161564)
		(mid 388.384796 -244.237741)
		(end 388.667752 -244.161564)
		(width 0.0889)
		(layer "In2.Cu")
		(net "M_I_CPU0_SA_DQ<31>")
	)
	(arc
		(start 376.821954 -244.161564)
		(mid 377.10491 -244.237741)
		(end 377.387866 -244.161564)
		(width 0.0889)
		(layer "In2.Cu")
		(net "M_I_CPU0_SA_DQ<31>")
	)
	(arc
		(start 377.761754 -244.161564)
		(mid 378.04471 -244.237741)
		(end 378.327666 -244.161564)
		(width 0.0889)
		(layer "In2.Cu")
		(net "M_I_CPU0_SA_DQ<31>")
	)
	(arc
		(start 389.981948 -244.161564)
		(mid 390.264904 -244.237741)
		(end 390.54786 -244.161564)
		(width 0.0889)
		(layer "In2.Cu")
		(net "M_I_CPU0_SA_DQ<31>")
	)
	(arc
		(start 380.216156 -244.156738)
		(mid 380.399664 -244.111244)
		(end 380.581916 -244.161564)
		(width 0.0889)
		(layer "In2.Cu")
		(net "M_I_CPU0_SA_DQ<31>")
	)
	(arc
		(start 382.46177 -244.161564)
		(mid 382.744726 -244.237741)
		(end 383.027682 -244.161564)
		(width 0.0889)
		(layer "In2.Cu")
		(net "M_I_CPU0_SA_DQ<31>")
	)
	(arc
		(start 393.367768 -244.161564)
		(mid 393.458033 -244.123961)
		(end 393.554966 -244.111018)
		(width 0.0889)
		(layer "In2.Cu")
		(net "M_I_CPU0_SA_DQ<31>")
	)
	(arc
		(start 383.027682 -244.161564)
		(mid 383.209933 -244.111214)
		(end 383.393442 -244.156738)
		(width 0.0889)
		(layer "In2.Cu")
		(net "M_I_CPU0_SA_DQ<31>")
	)
	(arc
		(start 389.616188 -244.156738)
		(mid 389.799696 -244.111244)
		(end 389.981948 -244.161564)
		(width 0.0889)
		(layer "In2.Cu")
		(net "M_I_CPU0_SA_DQ<31>")
	)
	(arc
		(start 387.161786 -244.161564)
		(mid 387.444742 -244.237741)
		(end 387.727698 -244.161564)
		(width 0.0889)
		(layer "In2.Cu")
		(net "M_I_CPU0_SA_DQ<31>")
	)
	(arc
		(start 387.727698 -244.161564)
		(mid 387.909949 -244.111214)
		(end 388.093458 -244.156738)
		(width 0.0889)
		(layer "In2.Cu")
		(net "M_I_CPU0_SA_DQ<31>")
	)
	(arc
		(start 385.856226 -244.156738)
		(mid 386.039734 -244.111244)
		(end 386.221986 -244.161564)
		(width 0.0889)
		(layer "In2.Cu")
		(net "M_I_CPU0_SA_DQ<31>")
	)
	(arc
		(start 386.787898 -244.161564)
		(mid 386.974842 -244.111309)
		(end 387.161786 -244.161564)
		(width 0.0889)
		(layer "In2.Cu")
		(net "M_I_CPU0_SA_DQ<31>")
	)
	(arc
		(start 381.52197 -244.161564)
		(mid 381.804926 -244.237741)
		(end 382.087882 -244.161564)
		(width 0.0889)
		(layer "In2.Cu")
		(net "M_I_CPU0_SA_DQ<31>")
	)
	(arc
		(start 383.967736 -244.161564)
		(mid 384.149987 -244.111214)
		(end 384.333496 -244.156738)
		(width 0.0889)
		(layer "In2.Cu")
		(net "M_I_CPU0_SA_DQ<31>")
	)
	(arc
		(start 376.456194 -244.156738)
		(mid 376.639702 -244.111244)
		(end 376.821954 -244.161564)
		(width 0.0889)
		(layer "In2.Cu")
		(net "M_I_CPU0_SA_DQ<31>")
	)
	(arc
		(start 384.341878 -244.161564)
		(mid 384.624834 -244.237741)
		(end 384.90779 -244.161564)
		(width 0.0889)
		(layer "In2.Cu")
		(net "M_I_CPU0_SA_DQ<31>")
	)
	(arc
		(start 379.26772 -244.161564)
		(mid 379.449971 -244.111214)
		(end 379.63348 -244.156738)
		(width 0.0889)
		(layer "In2.Cu")
		(net "M_I_CPU0_SA_DQ<31>")
	)
	(arc
		(start 391.48766 -244.161564)
		(mid 391.674858 -244.111182)
		(end 391.862056 -244.161564)
		(width 0.0889)
		(layer "In2.Cu")
		(net "M_I_CPU0_SA_DQ<31>")
	)
	(arc
		(start 382.087882 -244.161564)
		(mid 382.274826 -244.111309)
		(end 382.46177 -244.161564)
		(width 0.0889)
		(layer "In2.Cu")
		(net "M_I_CPU0_SA_DQ<31>")
	)
	(arc
		(start 388.667752 -244.161564)
		(mid 388.850003 -244.111214)
		(end 389.033512 -244.156738)
		(width 0.0889)
		(layer "In2.Cu")
		(net "M_I_CPU0_SA_DQ<31>")
	)
	(arc
		(start 377.387866 -244.161564)
		(mid 377.57481 -244.111309)
		(end 377.761754 -244.161564)
		(width 0.0889)
		(layer "In2.Cu")
		(net "M_I_CPU0_SA_DQ<31>")
	)
	(arc
		(start 392.427968 -244.161564)
		(mid 392.614912 -244.111309)
		(end 392.801856 -244.161564)
		(width 0.0889)
		(layer "In2.Cu")
		(net "M_I_CPU0_SA_DQ<31>")
	)
	(arc
		(start 378.327666 -244.161564)
		(mid 378.509917 -244.111214)
		(end 378.693426 -244.156738)
		(width 0.0889)
		(layer "In2.Cu")
		(net "M_I_CPU0_SA_DQ<31>")
	)
	(arc
		(start 375.945146 -244.193314)
		(mid 376.200211 -244.236665)
		(end 376.447812 -244.161564)
		(width 0.0889)
		(layer "In2.Cu")
		(net "M_I_CPU0_SA_DQ<31>")
	)
	(arc
		(start 391.862056 -244.161564)
		(mid 392.145012 -244.237741)
		(end 392.427968 -244.161564)
		(width 0.0889)
		(layer "In2.Cu")
		(net "M_I_CPU0_SA_DQ<31>")
	)
	(arc
		(start 378.701808 -244.161564)
		(mid 378.984764 -244.237741)
		(end 379.26772 -244.161564)
		(width 0.0889)
		(layer "In2.Cu")
		(net "M_I_CPU0_SA_DQ<31>")
	)
	(arc
		(start 392.801856 -244.161564)
		(mid 393.084812 -244.237741)
		(end 393.367768 -244.161564)
		(width 0.0889)
		(layer "In2.Cu")
		(net "M_I_CPU0_SA_DQ<31>")
	)
	(arc
		(start 390.921748 -244.161564)
		(mid 391.204704 -244.237741)
		(end 391.48766 -244.161564)
		(width 0.0889)
		(layer "In2.Cu")
		(net "M_I_CPU0_SA_DQ<31>")
	)
	(arc
		(start 390.54786 -244.161564)
		(mid 390.734804 -244.111309)
		(end 390.921748 -244.161564)
		(width 0.0889)
		(layer "In2.Cu")
		(net "M_I_CPU0_SA_DQ<31>")
	)
	(arc
		(start 389.041894 -244.161564)
		(mid 389.32485 -244.237741)
		(end 389.607806 -244.161564)
		(width 0.0889)
		(layer "In2.Cu")
		(net "M_I_CPU0_SA_DQ<31>")
	)
	(arc
		(start 381.15621 -244.156738)
		(mid 381.339718 -244.111244)
		(end 381.52197 -244.161564)
		(width 0.0889)
		(layer "In2.Cu")
		(net "M_I_CPU0_SA_DQ<31>")
	)
	(arc
		(start 386.221986 -244.161564)
		(mid 386.504942 -244.237741)
		(end 386.787898 -244.161564)
		(width 0.0889)
		(layer "In2.Cu")
		(net "M_I_CPU0_SA_DQ<31>")
	)
	(arc
		(start 379.641862 -244.161564)
		(mid 379.924818 -244.237741)
		(end 380.207774 -244.161564)
		(width 0.0889)
		(layer "In2.Cu")
		(net "M_I_CPU0_SA_DQ<31>")
	)
	(arc
		(start 384.916172 -244.156738)
		(mid 385.09968 -244.111244)
		(end 385.281932 -244.161564)
		(width 0.0889)
		(layer "In2.Cu")
		(net "M_I_CPU0_SA_DQ<31>")
	)
	(arc
		(start 385.281932 -244.161564)
		(mid 385.564888 -244.237741)
		(end 385.847844 -244.161564)
		(width 0.0889)
		(layer "In2.Cu")
		(net "M_I_CPU0_SA_DQ<31>")
	)
	(arc
		(start 383.401824 -244.161564)
		(mid 383.68478 -244.237741)
		(end 383.967736 -244.161564)
		(width 0.0889)
		(layer "In2.Cu")
		(net "M_I_CPU0_SA_DQ<31>")
	)
	(segment
		(start 376.638058 -243.940076)
		(end 377.10491 -243.674138)
		(width 0.10668)
		(layer "F.Cu")
		(net "M_I_CPU0_SA_DQ<30>")
	)
	(segment
		(start 394.536676 -242.77193)
		(end 395.072616 -242.77193)
		(width 0.0889)
		(layer "In2.Cu")
		(net "M_I_CPU0_SA_DQ<30>")
	)
	(segment
		(start 413.693864 -232.610152)
		(end 415.746946 -231.760014)
		(width 0.14478)
		(layer "In2.Cu")
		(net "M_I_CPU0_SA_DQ<30>")
	)
	(segment
		(start 425.784772 -231.43591)
		(end 426.017182 -231.43591)
		(width 0.14478)
		(layer "In2.Cu")
		(net "M_I_CPU0_SA_DQ<30>")
	)
	(segment
		(start 386.683504 -243.346732)
		(end 386.691886 -243.351558)
		(width 0.0889)
		(layer "In2.Cu")
		(net "M_I_CPU0_SA_DQ<30>")
	)
	(segment
		(start 426.017182 -231.43591)
		(end 426.341286 -231.760014)
		(width 0.14478)
		(layer "In2.Cu")
		(net "M_I_CPU0_SA_DQ<30>")
	)
	(segment
		(start 422.076626 -232.344976)
		(end 422.251124 -231.914192)
		(width 0.14478)
		(layer "In2.Cu")
		(net "M_I_CPU0_SA_DQ<30>")
	)
	(segment
		(start 407.862024 -236.83468)
		(end 407.862024 -236.60608)
		(width 0.14478)
		(layer "In2.Cu")
		(net "M_I_CPU0_SA_DQ<30>")
	)
	(segment
		(start 406.139904 -238.5568)
		(end 406.301448 -238.395256)
		(width 0.14478)
		(layer "In2.Cu")
		(net "M_I_CPU0_SA_DQ<30>")
	)
	(segment
		(start 410.968952 -232.610152)
		(end 413.693864 -232.610152)
		(width 0.14478)
		(layer "In2.Cu")
		(net "M_I_CPU0_SA_DQ<30>")
	)
	(segment
		(start 390.443466 -243.346732)
		(end 390.451848 -243.351558)
		(width 0.0889)
		(layer "In2.Cu")
		(net "M_I_CPU0_SA_DQ<30>")
	)
	(segment
		(start 422.251124 -231.914192)
		(end 422.464484 -231.825546)
		(width 0.14478)
		(layer "In2.Cu")
		(net "M_I_CPU0_SA_DQ<30>")
	)
	(segment
		(start 406.361392 -237.446312)
		(end 406.691592 -237.776512)
		(width 0.14478)
		(layer "In2.Cu")
		(net "M_I_CPU0_SA_DQ<30>")
	)
	(segment
		(start 415.746946 -231.760014)
		(end 417.854384 -231.760014)
		(width 0.14478)
		(layer "In2.Cu")
		(net "M_I_CPU0_SA_DQ<30>")
	)
	(segment
		(start 395.910054 -242.30711)
		(end 402.389594 -242.30711)
		(width 0.14478)
		(layer "In2.Cu")
		(net "M_I_CPU0_SA_DQ<30>")
	)
	(segment
		(start 406.91308 -236.666024)
		(end 407.14168 -236.666024)
		(width 0.14478)
		(layer "In2.Cu")
		(net "M_I_CPU0_SA_DQ<30>")
	)
	(segment
		(start 407.70048 -236.996224)
		(end 407.862024 -236.83468)
		(width 0.14478)
		(layer "In2.Cu")
		(net "M_I_CPU0_SA_DQ<30>")
	)
	(segment
		(start 381.043434 -243.346732)
		(end 381.051816 -243.351558)
		(width 0.0889)
		(layer "In2.Cu")
		(net "M_I_CPU0_SA_DQ<30>")
	)
	(segment
		(start 425.460668 -231.760014)
		(end 425.784772 -231.43591)
		(width 0.14478)
		(layer "In2.Cu")
		(net "M_I_CPU0_SA_DQ<30>")
	)
	(segment
		(start 406.301448 -238.395256)
		(end 406.301448 -238.166656)
		(width 0.14478)
		(layer "In2.Cu")
		(net "M_I_CPU0_SA_DQ<30>")
	)
	(segment
		(start 385.74345 -243.346732)
		(end 385.751832 -243.351558)
		(width 0.0889)
		(layer "In2.Cu")
		(net "M_I_CPU0_SA_DQ<30>")
	)
	(segment
		(start 421.4368 -232.610152)
		(end 422.076626 -232.344976)
		(width 0.14478)
		(layer "In2.Cu")
		(net "M_I_CPU0_SA_DQ<30>")
	)
	(segment
		(start 406.301448 -238.166656)
		(end 405.971248 -237.836456)
		(width 0.14478)
		(layer "In2.Cu")
		(net "M_I_CPU0_SA_DQ<30>")
	)
	(segment
		(start 404.740872 -239.955832)
		(end 404.740872 -239.727232)
		(width 0.14478)
		(layer "In2.Cu")
		(net "M_I_CPU0_SA_DQ<30>")
	)
	(segment
		(start 426.341286 -231.760014)
		(end 427.03115 -231.760014)
		(width 0.14478)
		(layer "In2.Cu")
		(net "M_I_CPU0_SA_DQ<30>")
	)
	(segment
		(start 423.489374 -231.760014)
		(end 425.460668 -231.760014)
		(width 0.14478)
		(layer "In2.Cu")
		(net "M_I_CPU0_SA_DQ<30>")
	)
	(segment
		(start 405.52116 -239.175544)
		(end 405.52116 -238.946944)
		(width 0.14478)
		(layer "In2.Cu")
		(net "M_I_CPU0_SA_DQ<30>")
	)
	(segment
		(start 407.14168 -236.666024)
		(end 407.47188 -236.996224)
		(width 0.14478)
		(layer "In2.Cu")
		(net "M_I_CPU0_SA_DQ<30>")
	)
	(segment
		(start 418.704522 -232.610152)
		(end 421.4368 -232.610152)
		(width 0.14478)
		(layer "In2.Cu")
		(net "M_I_CPU0_SA_DQ<30>")
	)
	(segment
		(start 405.359616 -239.337088)
		(end 405.52116 -239.175544)
		(width 0.14478)
		(layer "In2.Cu")
		(net "M_I_CPU0_SA_DQ<30>")
	)
	(segment
		(start 405.352504 -238.2266)
		(end 405.581104 -238.2266)
		(width 0.14478)
		(layer "In2.Cu")
		(net "M_I_CPU0_SA_DQ<30>")
	)
	(segment
		(start 383.497836 -243.351558)
		(end 383.506218 -243.346732)
		(width 0.0889)
		(layer "In2.Cu")
		(net "M_I_CPU0_SA_DQ<30>")
	)
	(segment
		(start 406.691592 -237.776512)
		(end 406.920192 -237.776512)
		(width 0.14478)
		(layer "In2.Cu")
		(net "M_I_CPU0_SA_DQ<30>")
	)
	(segment
		(start 405.911304 -238.5568)
		(end 406.139904 -238.5568)
		(width 0.14478)
		(layer "In2.Cu")
		(net "M_I_CPU0_SA_DQ<30>")
	)
	(segment
		(start 402.389594 -242.30711)
		(end 404.740872 -239.955832)
		(width 0.14478)
		(layer "In2.Cu")
		(net "M_I_CPU0_SA_DQ<30>")
	)
	(segment
		(start 406.751536 -237.056168)
		(end 406.751536 -236.827568)
		(width 0.14478)
		(layer "In2.Cu")
		(net "M_I_CPU0_SA_DQ<30>")
	)
	(segment
		(start 417.854384 -231.760014)
		(end 418.704522 -232.610152)
		(width 0.14478)
		(layer "In2.Cu")
		(net "M_I_CPU0_SA_DQ<30>")
	)
	(segment
		(start 395.072616 -242.77193)
		(end 395.537436 -242.30711)
		(width 0.0889)
		(layer "In2.Cu")
		(net "M_I_CPU0_SA_DQ<30>")
	)
	(segment
		(start 407.531824 -236.27588)
		(end 407.531824 -236.04728)
		(width 0.14478)
		(layer "In2.Cu")
		(net "M_I_CPU0_SA_DQ<30>")
	)
	(segment
		(start 406.751536 -236.827568)
		(end 406.91308 -236.666024)
		(width 0.14478)
		(layer "In2.Cu")
		(net "M_I_CPU0_SA_DQ<30>")
	)
	(segment
		(start 394.007594 -243.301012)
		(end 394.536676 -242.77193)
		(width 0.0889)
		(layer "In2.Cu")
		(net "M_I_CPU0_SA_DQ<30>")
	)
	(segment
		(start 406.132792 -237.446312)
		(end 406.361392 -237.446312)
		(width 0.14478)
		(layer "In2.Cu")
		(net "M_I_CPU0_SA_DQ<30>")
	)
	(segment
		(start 427.03115 -231.760014)
		(end 427.456092 -232.184956)
		(width 0.14478)
		(layer "In2.Cu")
		(net "M_I_CPU0_SA_DQ<30>")
	)
	(segment
		(start 395.537436 -242.30711)
		(end 395.910054 -242.30711)
		(width 0.0889)
		(layer "In2.Cu")
		(net "M_I_CPU0_SA_DQ<30>")
	)
	(segment
		(start 405.19096 -238.616744)
		(end 405.19096 -238.388144)
		(width 0.14478)
		(layer "In2.Cu")
		(net "M_I_CPU0_SA_DQ<30>")
	)
	(segment
		(start 404.410672 -239.168432)
		(end 404.572216 -239.006888)
		(width 0.14478)
		(layer "In2.Cu")
		(net "M_I_CPU0_SA_DQ<30>")
	)
	(segment
		(start 388.197852 -243.351558)
		(end 388.206234 -243.346732)
		(width 0.0889)
		(layer "In2.Cu")
		(net "M_I_CPU0_SA_DQ<30>")
	)
	(segment
		(start 378.79782 -243.351558)
		(end 378.806202 -243.346732)
		(width 0.0889)
		(layer "In2.Cu")
		(net "M_I_CPU0_SA_DQ<30>")
	)
	(segment
		(start 405.971248 -237.607856)
		(end 406.132792 -237.446312)
		(width 0.14478)
		(layer "In2.Cu")
		(net "M_I_CPU0_SA_DQ<30>")
	)
	(segment
		(start 381.983488 -243.346732)
		(end 381.99187 -243.351558)
		(width 0.0889)
		(layer "In2.Cu")
		(net "M_I_CPU0_SA_DQ<30>")
	)
	(segment
		(start 393.084812 -243.301012)
		(end 394.007594 -243.301012)
		(width 0.0889)
		(layer "In2.Cu")
		(net "M_I_CPU0_SA_DQ<30>")
	)
	(segment
		(start 404.410672 -239.397032)
		(end 404.410672 -239.168432)
		(width 0.14478)
		(layer "In2.Cu")
		(net "M_I_CPU0_SA_DQ<30>")
	)
	(segment
		(start 407.081736 -237.386368)
		(end 406.751536 -237.056168)
		(width 0.14478)
		(layer "In2.Cu")
		(net "M_I_CPU0_SA_DQ<30>")
	)
	(segment
		(start 404.572216 -239.006888)
		(end 404.800816 -239.006888)
		(width 0.14478)
		(layer "In2.Cu")
		(net "M_I_CPU0_SA_DQ<30>")
	)
	(segment
		(start 405.52116 -238.946944)
		(end 405.19096 -238.616744)
		(width 0.14478)
		(layer "In2.Cu")
		(net "M_I_CPU0_SA_DQ<30>")
	)
	(segment
		(start 387.257798 -243.351558)
		(end 387.26618 -243.346732)
		(width 0.0889)
		(layer "In2.Cu")
		(net "M_I_CPU0_SA_DQ<30>")
	)
	(segment
		(start 407.081736 -237.614968)
		(end 407.081736 -237.386368)
		(width 0.14478)
		(layer "In2.Cu")
		(net "M_I_CPU0_SA_DQ<30>")
	)
	(segment
		(start 422.464484 -231.825546)
		(end 422.89222 -232.00741)
		(width 0.14478)
		(layer "In2.Cu")
		(net "M_I_CPU0_SA_DQ<30>")
	)
	(segment
		(start 405.19096 -238.388144)
		(end 405.352504 -238.2266)
		(width 0.14478)
		(layer "In2.Cu")
		(net "M_I_CPU0_SA_DQ<30>")
	)
	(segment
		(start 406.920192 -237.776512)
		(end 407.081736 -237.614968)
		(width 0.14478)
		(layer "In2.Cu")
		(net "M_I_CPU0_SA_DQ<30>")
	)
	(segment
		(start 404.800816 -239.006888)
		(end 405.131016 -239.337088)
		(width 0.14478)
		(layer "In2.Cu")
		(net "M_I_CPU0_SA_DQ<30>")
	)
	(segment
		(start 392.331448 -243.351558)
		(end 392.341862 -243.357654)
		(width 0.0889)
		(layer "In2.Cu")
		(net "M_I_CPU0_SA_DQ<30>")
	)
	(segment
		(start 391.947146 -243.357654)
		(end 391.95756 -243.351558)
		(width 0.0889)
		(layer "In2.Cu")
		(net "M_I_CPU0_SA_DQ<30>")
	)
	(segment
		(start 405.971248 -237.836456)
		(end 405.971248 -237.607856)
		(width 0.14478)
		(layer "In2.Cu")
		(net "M_I_CPU0_SA_DQ<30>")
	)
	(segment
		(start 377.10491 -243.674138)
		(end 377.258834 -243.408708)
		(width 0.0889)
		(layer "In2.Cu")
		(net "M_I_CPU0_SA_DQ<30>")
	)
	(segment
		(start 422.89222 -232.00741)
		(end 423.489374 -231.760014)
		(width 0.14478)
		(layer "In2.Cu")
		(net "M_I_CPU0_SA_DQ<30>")
	)
	(segment
		(start 391.01776 -243.351558)
		(end 391.026142 -243.346732)
		(width 0.0889)
		(layer "In2.Cu")
		(net "M_I_CPU0_SA_DQ<30>")
	)
	(segment
		(start 407.47188 -236.996224)
		(end 407.70048 -236.996224)
		(width 0.14478)
		(layer "In2.Cu")
		(net "M_I_CPU0_SA_DQ<30>")
	)
	(segment
		(start 377.857766 -243.351558)
		(end 377.866148 -243.346732)
		(width 0.0889)
		(layer "In2.Cu")
		(net "M_I_CPU0_SA_DQ<30>")
	)
	(segment
		(start 407.862024 -236.60608)
		(end 407.531824 -236.27588)
		(width 0.14478)
		(layer "In2.Cu")
		(net "M_I_CPU0_SA_DQ<30>")
	)
	(segment
		(start 405.131016 -239.337088)
		(end 405.359616 -239.337088)
		(width 0.14478)
		(layer "In2.Cu")
		(net "M_I_CPU0_SA_DQ<30>")
	)
	(segment
		(start 407.531824 -236.04728)
		(end 410.968952 -232.610152)
		(width 0.14478)
		(layer "In2.Cu")
		(net "M_I_CPU0_SA_DQ<30>")
	)
	(segment
		(start 382.557782 -243.351558)
		(end 382.566164 -243.346732)
		(width 0.0889)
		(layer "In2.Cu")
		(net "M_I_CPU0_SA_DQ<30>")
	)
	(segment
		(start 405.581104 -238.2266)
		(end 405.911304 -238.5568)
		(width 0.14478)
		(layer "In2.Cu")
		(net "M_I_CPU0_SA_DQ<30>")
	)
	(segment
		(start 377.258834 -243.408708)
		(end 377.354846 -243.383308)
		(width 0.0889)
		(layer "In2.Cu")
		(net "M_I_CPU0_SA_DQ<30>")
	)
	(segment
		(start 404.740872 -239.727232)
		(end 404.410672 -239.397032)
		(width 0.14478)
		(layer "In2.Cu")
		(net "M_I_CPU0_SA_DQ<30>")
	)
	(arc
		(start 392.897614 -243.351558)
		(mid 392.987874 -243.31393)
		(end 393.084812 -243.301012)
		(width 0.0889)
		(layer "In2.Cu")
		(net "M_I_CPU0_SA_DQ<30>")
	)
	(arc
		(start 380.111762 -243.351558)
		(mid 380.394718 -243.427735)
		(end 380.677674 -243.351558)
		(width 0.0889)
		(layer "In2.Cu")
		(net "M_I_CPU0_SA_DQ<30>")
	)
	(arc
		(start 382.566164 -243.346732)
		(mid 382.749672 -243.301238)
		(end 382.931924 -243.351558)
		(width 0.0889)
		(layer "In2.Cu")
		(net "M_I_CPU0_SA_DQ<30>")
	)
	(arc
		(start 386.317744 -243.351558)
		(mid 386.499995 -243.301208)
		(end 386.683504 -243.346732)
		(width 0.0889)
		(layer "In2.Cu")
		(net "M_I_CPU0_SA_DQ<30>")
	)
	(arc
		(start 389.137906 -243.351558)
		(mid 389.32485 -243.301303)
		(end 389.511794 -243.351558)
		(width 0.0889)
		(layer "In2.Cu")
		(net "M_I_CPU0_SA_DQ<30>")
	)
	(arc
		(start 380.677674 -243.351558)
		(mid 380.859925 -243.301208)
		(end 381.043434 -243.346732)
		(width 0.0889)
		(layer "In2.Cu")
		(net "M_I_CPU0_SA_DQ<30>")
	)
	(arc
		(start 386.691886 -243.351558)
		(mid 386.974842 -243.427735)
		(end 387.257798 -243.351558)
		(width 0.0889)
		(layer "In2.Cu")
		(net "M_I_CPU0_SA_DQ<30>")
	)
	(arc
		(start 391.026142 -243.346732)
		(mid 391.20965 -243.301238)
		(end 391.391902 -243.351558)
		(width 0.0889)
		(layer "In2.Cu")
		(net "M_I_CPU0_SA_DQ<30>")
	)
	(arc
		(start 382.931924 -243.351558)
		(mid 383.21488 -243.427735)
		(end 383.497836 -243.351558)
		(width 0.0889)
		(layer "In2.Cu")
		(net "M_I_CPU0_SA_DQ<30>")
	)
	(arc
		(start 387.26618 -243.346732)
		(mid 387.449688 -243.301238)
		(end 387.63194 -243.351558)
		(width 0.0889)
		(layer "In2.Cu")
		(net "M_I_CPU0_SA_DQ<30>")
	)
	(arc
		(start 383.506218 -243.346732)
		(mid 383.689726 -243.301238)
		(end 383.871978 -243.351558)
		(width 0.0889)
		(layer "In2.Cu")
		(net "M_I_CPU0_SA_DQ<30>")
	)
	(arc
		(start 381.617728 -243.351558)
		(mid 381.799979 -243.301208)
		(end 381.983488 -243.346732)
		(width 0.0889)
		(layer "In2.Cu")
		(net "M_I_CPU0_SA_DQ<30>")
	)
	(arc
		(start 388.206234 -243.346732)
		(mid 388.389742 -243.301238)
		(end 388.571994 -243.351558)
		(width 0.0889)
		(layer "In2.Cu")
		(net "M_I_CPU0_SA_DQ<30>")
	)
	(arc
		(start 378.806202 -243.346732)
		(mid 378.98971 -243.301238)
		(end 379.171962 -243.351558)
		(width 0.0889)
		(layer "In2.Cu")
		(net "M_I_CPU0_SA_DQ<30>")
	)
	(arc
		(start 389.511794 -243.351558)
		(mid 389.79475 -243.427735)
		(end 390.077706 -243.351558)
		(width 0.0889)
		(layer "In2.Cu")
		(net "M_I_CPU0_SA_DQ<30>")
	)
	(arc
		(start 391.391902 -243.351558)
		(mid 391.668715 -243.427701)
		(end 391.947146 -243.357654)
		(width 0.0889)
		(layer "In2.Cu")
		(net "M_I_CPU0_SA_DQ<30>")
	)
	(arc
		(start 377.866148 -243.346732)
		(mid 378.049656 -243.301238)
		(end 378.231908 -243.351558)
		(width 0.0889)
		(layer "In2.Cu")
		(net "M_I_CPU0_SA_DQ<30>")
	)
	(arc
		(start 392.341862 -243.357654)
		(mid 392.620548 -243.427874)
		(end 392.897614 -243.351558)
		(width 0.0889)
		(layer "In2.Cu")
		(net "M_I_CPU0_SA_DQ<30>")
	)
	(arc
		(start 390.077706 -243.351558)
		(mid 390.259957 -243.301208)
		(end 390.443466 -243.346732)
		(width 0.0889)
		(layer "In2.Cu")
		(net "M_I_CPU0_SA_DQ<30>")
	)
	(arc
		(start 384.811778 -243.351558)
		(mid 385.094734 -243.427735)
		(end 385.37769 -243.351558)
		(width 0.0889)
		(layer "In2.Cu")
		(net "M_I_CPU0_SA_DQ<30>")
	)
	(arc
		(start 381.99187 -243.351558)
		(mid 382.274826 -243.427735)
		(end 382.557782 -243.351558)
		(width 0.0889)
		(layer "In2.Cu")
		(net "M_I_CPU0_SA_DQ<30>")
	)
	(arc
		(start 377.354846 -243.383308)
		(mid 377.610054 -243.426785)
		(end 377.857766 -243.351558)
		(width 0.0889)
		(layer "In2.Cu")
		(net "M_I_CPU0_SA_DQ<30>")
	)
	(arc
		(start 387.63194 -243.351558)
		(mid 387.914896 -243.427735)
		(end 388.197852 -243.351558)
		(width 0.0889)
		(layer "In2.Cu")
		(net "M_I_CPU0_SA_DQ<30>")
	)
	(arc
		(start 378.231908 -243.351558)
		(mid 378.514864 -243.427735)
		(end 378.79782 -243.351558)
		(width 0.0889)
		(layer "In2.Cu")
		(net "M_I_CPU0_SA_DQ<30>")
	)
	(arc
		(start 381.051816 -243.351558)
		(mid 381.334772 -243.427735)
		(end 381.617728 -243.351558)
		(width 0.0889)
		(layer "In2.Cu")
		(net "M_I_CPU0_SA_DQ<30>")
	)
	(arc
		(start 385.37769 -243.351558)
		(mid 385.559941 -243.301208)
		(end 385.74345 -243.346732)
		(width 0.0889)
		(layer "In2.Cu")
		(net "M_I_CPU0_SA_DQ<30>")
	)
	(arc
		(start 379.737874 -243.351558)
		(mid 379.924818 -243.301303)
		(end 380.111762 -243.351558)
		(width 0.0889)
		(layer "In2.Cu")
		(net "M_I_CPU0_SA_DQ<30>")
	)
	(arc
		(start 390.451848 -243.351558)
		(mid 390.734804 -243.427735)
		(end 391.01776 -243.351558)
		(width 0.0889)
		(layer "In2.Cu")
		(net "M_I_CPU0_SA_DQ<30>")
	)
	(arc
		(start 384.43789 -243.351558)
		(mid 384.624834 -243.301303)
		(end 384.811778 -243.351558)
		(width 0.0889)
		(layer "In2.Cu")
		(net "M_I_CPU0_SA_DQ<30>")
	)
	(arc
		(start 388.571994 -243.351558)
		(mid 388.85495 -243.427735)
		(end 389.137906 -243.351558)
		(width 0.0889)
		(layer "In2.Cu")
		(net "M_I_CPU0_SA_DQ<30>")
	)
	(arc
		(start 379.171962 -243.351558)
		(mid 379.454918 -243.427735)
		(end 379.737874 -243.351558)
		(width 0.0889)
		(layer "In2.Cu")
		(net "M_I_CPU0_SA_DQ<30>")
	)
	(arc
		(start 383.871978 -243.351558)
		(mid 384.154934 -243.427735)
		(end 384.43789 -243.351558)
		(width 0.0889)
		(layer "In2.Cu")
		(net "M_I_CPU0_SA_DQ<30>")
	)
	(arc
		(start 391.95756 -243.351558)
		(mid 392.144504 -243.301303)
		(end 392.331448 -243.351558)
		(width 0.0889)
		(layer "In2.Cu")
		(net "M_I_CPU0_SA_DQ<30>")
	)
	(arc
		(start 385.751832 -243.351558)
		(mid 386.034788 -243.427735)
		(end 386.317744 -243.351558)
		(width 0.0889)
		(layer "In2.Cu")
		(net "M_I_CPU0_SA_DQ<30>")
	)
	(segment
		(start 376.638058 -226.120198)
		(end 377.10491 -225.85426)
		(width 0.10668)
		(layer "F.Cu")
		(net "M_I_CPU0_SA_DQ<2>")
	)
	(segment
		(start 389.107172 -222.309436)
		(end 389.137652 -222.291656)
		(width 0.0889)
		(layer "In2.Cu")
		(net "M_I_CPU0_SA_DQ<2>")
	)
	(segment
		(start 391.340594 -217.341196)
		(end 391.340594 -217.112596)
		(width 0.14478)
		(layer "In2.Cu")
		(net "M_I_CPU0_SA_DQ<2>")
	)
	(segment
		(start 391.220452 -216.992454)
		(end 391.220452 -216.763854)
		(width 0.14478)
		(layer "In2.Cu")
		(net "M_I_CPU0_SA_DQ<2>")
	)
	(segment
		(start 424.750738 -198.15556)
		(end 424.98137 -198.15556)
		(width 0.14478)
		(layer "In2.Cu")
		(net "M_I_CPU0_SA_DQ<2>")
	)
	(segment
		(start 390.398762 -218.283028)
		(end 390.560306 -218.121484)
		(width 0.14478)
		(layer "In2.Cu")
		(net "M_I_CPU0_SA_DQ<2>")
	)
	(segment
		(start 381.043434 -225.526854)
		(end 381.051816 -225.53168)
		(width 0.0889)
		(layer "In2.Cu")
		(net "M_I_CPU0_SA_DQ<2>")
	)
	(segment
		(start 425.700444 -197.992746)
		(end 425.863258 -198.15556)
		(width 0.14478)
		(layer "In2.Cu")
		(net "M_I_CPU0_SA_DQ<2>")
	)
	(segment
		(start 414.239202 -198.61022)
		(end 415.08934 -197.760082)
		(width 0.14478)
		(layer "In2.Cu")
		(net "M_I_CPU0_SA_DQ<2>")
	)
	(segment
		(start 391.340594 -217.112596)
		(end 391.220452 -216.992454)
		(width 0.14478)
		(layer "In2.Cu")
		(net "M_I_CPU0_SA_DQ<2>")
	)
	(segment
		(start 422.430702 -197.760082)
		(end 424.35526 -197.760082)
		(width 0.14478)
		(layer "In2.Cu")
		(net "M_I_CPU0_SA_DQ<2>")
	)
	(segment
		(start 392.739626 -215.942164)
		(end 392.90117 -215.78062)
		(width 0.14478)
		(layer "In2.Cu")
		(net "M_I_CPU0_SA_DQ<2>")
	)
	(segment
		(start 390.830308 -217.382598)
		(end 390.95045 -217.50274)
		(width 0.14478)
		(layer "In2.Cu")
		(net "M_I_CPU0_SA_DQ<2>")
	)
	(segment
		(start 377.10491 -225.85426)
		(end 377.258834 -225.58883)
		(width 0.0889)
		(layer "In2.Cu")
		(net "M_I_CPU0_SA_DQ<2>")
	)
	(segment
		(start 392.120882 -216.560908)
		(end 392.120882 -216.332308)
		(width 0.14478)
		(layer "In2.Cu")
		(net "M_I_CPU0_SA_DQ<2>")
	)
	(segment
		(start 426.419518 -197.379082)
		(end 426.65015 -197.379082)
		(width 0.14478)
		(layer "In2.Cu")
		(net "M_I_CPU0_SA_DQ<2>")
	)
	(segment
		(start 393.171172 -215.041734)
		(end 393.291314 -215.161876)
		(width 0.14478)
		(layer "In2.Cu")
		(net "M_I_CPU0_SA_DQ<2>")
	)
	(segment
		(start 389.82142 -218.162886)
		(end 390.05002 -218.162886)
		(width 0.14478)
		(layer "In2.Cu")
		(net "M_I_CPU0_SA_DQ<2>")
	)
	(segment
		(start 391.17905 -217.50274)
		(end 391.340594 -217.341196)
		(width 0.14478)
		(layer "In2.Cu")
		(net "M_I_CPU0_SA_DQ<2>")
	)
	(segment
		(start 385.744466 -225.527362)
		(end 385.751832 -225.53168)
		(width 0.0889)
		(layer "In2.Cu")
		(net "M_I_CPU0_SA_DQ<2>")
	)
	(segment
		(start 426.09389 -198.15556)
		(end 426.256704 -197.992746)
		(width 0.14478)
		(layer "In2.Cu")
		(net "M_I_CPU0_SA_DQ<2>")
	)
	(segment
		(start 389.137652 -222.291656)
		(end 389.17245 -222.271336)
		(width 0.0889)
		(layer "In2.Cu")
		(net "M_I_CPU0_SA_DQ<2>")
	)
	(segment
		(start 392.90117 -215.78062)
		(end 392.90117 -215.55202)
		(width 0.14478)
		(layer "In2.Cu")
		(net "M_I_CPU0_SA_DQ<2>")
	)
	(segment
		(start 390.560306 -218.121484)
		(end 390.560306 -217.892884)
		(width 0.14478)
		(layer "In2.Cu")
		(net "M_I_CPU0_SA_DQ<2>")
	)
	(segment
		(start 389.571738 -218.412568)
		(end 389.82142 -218.162886)
		(width 0.14478)
		(layer "In2.Cu")
		(net "M_I_CPU0_SA_DQ<2>")
	)
	(segment
		(start 393.291314 -215.161876)
		(end 393.519914 -215.161876)
		(width 0.14478)
		(layer "In2.Cu")
		(net "M_I_CPU0_SA_DQ<2>")
	)
	(segment
		(start 385.74345 -225.526854)
		(end 385.744466 -225.527362)
		(width 0.0889)
		(layer "In2.Cu")
		(net "M_I_CPU0_SA_DQ<2>")
	)
	(segment
		(start 383.497836 -225.53168)
		(end 383.506218 -225.526854)
		(width 0.0889)
		(layer "In2.Cu")
		(net "M_I_CPU0_SA_DQ<2>")
	)
	(segment
		(start 425.53763 -197.364858)
		(end 425.700444 -197.527672)
		(width 0.14478)
		(layer "In2.Cu")
		(net "M_I_CPU0_SA_DQ<2>")
	)
	(segment
		(start 377.857766 -225.53168)
		(end 377.866148 -225.526854)
		(width 0.0889)
		(layer "In2.Cu")
		(net "M_I_CPU0_SA_DQ<2>")
	)
	(segment
		(start 386.683504 -225.526854)
		(end 386.691886 -225.53168)
		(width 0.0889)
		(layer "In2.Cu")
		(net "M_I_CPU0_SA_DQ<2>")
	)
	(segment
		(start 424.98137 -198.15556)
		(end 425.144184 -197.992746)
		(width 0.14478)
		(layer "In2.Cu")
		(net "M_I_CPU0_SA_DQ<2>")
	)
	(segment
		(start 390.601708 -217.382598)
		(end 390.830308 -217.382598)
		(width 0.14478)
		(layer "In2.Cu")
		(net "M_I_CPU0_SA_DQ<2>")
	)
	(segment
		(start 387.697218 -224.739454)
		(end 387.727698 -224.721674)
		(width 0.0889)
		(layer "In2.Cu")
		(net "M_I_CPU0_SA_DQ<2>")
	)
	(segment
		(start 425.144184 -197.992746)
		(end 425.144184 -197.527672)
		(width 0.14478)
		(layer "In2.Cu")
		(net "M_I_CPU0_SA_DQ<2>")
	)
	(segment
		(start 389.571738 -221.17431)
		(end 389.571738 -218.412568)
		(width 0.14478)
		(layer "In2.Cu")
		(net "M_I_CPU0_SA_DQ<2>")
	)
	(segment
		(start 387.727698 -224.721674)
		(end 387.76402 -224.700592)
		(width 0.0889)
		(layer "In2.Cu")
		(net "M_I_CPU0_SA_DQ<2>")
	)
	(segment
		(start 426.65015 -197.379082)
		(end 427.456092 -198.185024)
		(width 0.14478)
		(layer "In2.Cu")
		(net "M_I_CPU0_SA_DQ<2>")
	)
	(segment
		(start 415.08934 -197.760082)
		(end 417.88207 -197.760082)
		(width 0.14478)
		(layer "In2.Cu")
		(net "M_I_CPU0_SA_DQ<2>")
	)
	(segment
		(start 392.00074 -215.983566)
		(end 392.162284 -215.822022)
		(width 0.14478)
		(layer "In2.Cu")
		(net "M_I_CPU0_SA_DQ<2>")
	)
	(segment
		(start 425.306998 -197.364858)
		(end 425.53763 -197.364858)
		(width 0.14478)
		(layer "In2.Cu")
		(net "M_I_CPU0_SA_DQ<2>")
	)
	(segment
		(start 417.88207 -197.760082)
		(end 418.732208 -198.61022)
		(width 0.14478)
		(layer "In2.Cu")
		(net "M_I_CPU0_SA_DQ<2>")
	)
	(segment
		(start 392.120882 -216.332308)
		(end 392.00074 -216.212166)
		(width 0.14478)
		(layer "In2.Cu")
		(net "M_I_CPU0_SA_DQ<2>")
	)
	(segment
		(start 426.256704 -197.541896)
		(end 426.419518 -197.379082)
		(width 0.14478)
		(layer "In2.Cu")
		(net "M_I_CPU0_SA_DQ<2>")
	)
	(segment
		(start 426.256704 -197.992746)
		(end 426.256704 -197.541896)
		(width 0.14478)
		(layer "In2.Cu")
		(net "M_I_CPU0_SA_DQ<2>")
	)
	(segment
		(start 391.730738 -216.722452)
		(end 391.959338 -216.722452)
		(width 0.14478)
		(layer "In2.Cu")
		(net "M_I_CPU0_SA_DQ<2>")
	)
	(segment
		(start 395.509496 -212.47481)
		(end 395.509496 -211.079842)
		(width 0.14478)
		(layer "In2.Cu")
		(net "M_I_CPU0_SA_DQ<2>")
	)
	(segment
		(start 388.165848 -223.929956)
		(end 388.197598 -223.911668)
		(width 0.0889)
		(layer "In2.Cu")
		(net "M_I_CPU0_SA_DQ<2>")
	)
	(segment
		(start 392.781028 -215.431878)
		(end 392.781028 -215.203278)
		(width 0.14478)
		(layer "In2.Cu")
		(net "M_I_CPU0_SA_DQ<2>")
	)
	(segment
		(start 390.440164 -217.772742)
		(end 390.440164 -217.544142)
		(width 0.14478)
		(layer "In2.Cu")
		(net "M_I_CPU0_SA_DQ<2>")
	)
	(segment
		(start 390.170162 -218.283028)
		(end 390.398762 -218.283028)
		(width 0.14478)
		(layer "In2.Cu")
		(net "M_I_CPU0_SA_DQ<2>")
	)
	(segment
		(start 390.560306 -217.892884)
		(end 390.440164 -217.772742)
		(width 0.14478)
		(layer "In2.Cu")
		(net "M_I_CPU0_SA_DQ<2>")
	)
	(segment
		(start 388.638034 -223.11868)
		(end 388.667498 -223.101662)
		(width 0.0889)
		(layer "In2.Cu")
		(net "M_I_CPU0_SA_DQ<2>")
	)
	(segment
		(start 425.863258 -198.15556)
		(end 426.09389 -198.15556)
		(width 0.14478)
		(layer "In2.Cu")
		(net "M_I_CPU0_SA_DQ<2>")
	)
	(segment
		(start 425.700444 -197.527672)
		(end 425.700444 -197.992746)
		(width 0.14478)
		(layer "In2.Cu")
		(net "M_I_CPU0_SA_DQ<2>")
	)
	(segment
		(start 393.519914 -215.161876)
		(end 393.681458 -215.000332)
		(width 0.14478)
		(layer "In2.Cu")
		(net "M_I_CPU0_SA_DQ<2>")
	)
	(segment
		(start 424.35526 -197.760082)
		(end 424.750738 -198.15556)
		(width 0.14478)
		(layer "In2.Cu")
		(net "M_I_CPU0_SA_DQ<2>")
	)
	(segment
		(start 393.561316 -214.42299)
		(end 395.509496 -212.47481)
		(width 0.14478)
		(layer "In2.Cu")
		(net "M_I_CPU0_SA_DQ<2>")
	)
	(segment
		(start 377.258834 -225.58883)
		(end 377.354846 -225.56343)
		(width 0.0889)
		(layer "In2.Cu")
		(net "M_I_CPU0_SA_DQ<2>")
	)
	(segment
		(start 390.440164 -217.544142)
		(end 390.601708 -217.382598)
		(width 0.14478)
		(layer "In2.Cu")
		(net "M_I_CPU0_SA_DQ<2>")
	)
	(segment
		(start 393.561316 -214.65159)
		(end 393.561316 -214.42299)
		(width 0.14478)
		(layer "In2.Cu")
		(net "M_I_CPU0_SA_DQ<2>")
	)
	(segment
		(start 392.942572 -215.041734)
		(end 393.171172 -215.041734)
		(width 0.14478)
		(layer "In2.Cu")
		(net "M_I_CPU0_SA_DQ<2>")
	)
	(segment
		(start 425.144184 -197.527672)
		(end 425.306998 -197.364858)
		(width 0.14478)
		(layer "In2.Cu")
		(net "M_I_CPU0_SA_DQ<2>")
	)
	(segment
		(start 421.580564 -198.61022)
		(end 422.430702 -197.760082)
		(width 0.14478)
		(layer "In2.Cu")
		(net "M_I_CPU0_SA_DQ<2>")
	)
	(segment
		(start 382.557782 -225.53168)
		(end 382.566164 -225.526854)
		(width 0.0889)
		(layer "In2.Cu")
		(net "M_I_CPU0_SA_DQ<2>")
	)
	(segment
		(start 393.681458 -214.771732)
		(end 393.561316 -214.65159)
		(width 0.14478)
		(layer "In2.Cu")
		(net "M_I_CPU0_SA_DQ<2>")
	)
	(segment
		(start 392.90117 -215.55202)
		(end 392.781028 -215.431878)
		(width 0.14478)
		(layer "In2.Cu")
		(net "M_I_CPU0_SA_DQ<2>")
	)
	(segment
		(start 391.959338 -216.722452)
		(end 392.120882 -216.560908)
		(width 0.14478)
		(layer "In2.Cu")
		(net "M_I_CPU0_SA_DQ<2>")
	)
	(segment
		(start 392.781028 -215.203278)
		(end 392.942572 -215.041734)
		(width 0.14478)
		(layer "In2.Cu")
		(net "M_I_CPU0_SA_DQ<2>")
	)
	(segment
		(start 389.419592 -221.80423)
		(end 389.571738 -221.17431)
		(width 0.0889)
		(layer "In2.Cu")
		(net "M_I_CPU0_SA_DQ<2>")
	)
	(segment
		(start 391.610596 -216.60231)
		(end 391.730738 -216.722452)
		(width 0.14478)
		(layer "In2.Cu")
		(net "M_I_CPU0_SA_DQ<2>")
	)
	(segment
		(start 391.381996 -216.60231)
		(end 391.610596 -216.60231)
		(width 0.14478)
		(layer "In2.Cu")
		(net "M_I_CPU0_SA_DQ<2>")
	)
	(segment
		(start 392.162284 -215.822022)
		(end 392.390884 -215.822022)
		(width 0.14478)
		(layer "In2.Cu")
		(net "M_I_CPU0_SA_DQ<2>")
	)
	(segment
		(start 393.681458 -215.000332)
		(end 393.681458 -214.771732)
		(width 0.14478)
		(layer "In2.Cu")
		(net "M_I_CPU0_SA_DQ<2>")
	)
	(segment
		(start 390.95045 -217.50274)
		(end 391.17905 -217.50274)
		(width 0.14478)
		(layer "In2.Cu")
		(net "M_I_CPU0_SA_DQ<2>")
	)
	(segment
		(start 381.983488 -225.526854)
		(end 381.99187 -225.53168)
		(width 0.0889)
		(layer "In2.Cu")
		(net "M_I_CPU0_SA_DQ<2>")
	)
	(segment
		(start 387.257798 -225.53168)
		(end 387.296914 -225.50882)
		(width 0.0889)
		(layer "In2.Cu")
		(net "M_I_CPU0_SA_DQ<2>")
	)
	(segment
		(start 392.00074 -216.212166)
		(end 392.00074 -215.983566)
		(width 0.14478)
		(layer "In2.Cu")
		(net "M_I_CPU0_SA_DQ<2>")
	)
	(segment
		(start 378.79782 -225.53168)
		(end 378.806202 -225.526854)
		(width 0.0889)
		(layer "In2.Cu")
		(net "M_I_CPU0_SA_DQ<2>")
	)
	(segment
		(start 390.05002 -218.162886)
		(end 390.170162 -218.283028)
		(width 0.14478)
		(layer "In2.Cu")
		(net "M_I_CPU0_SA_DQ<2>")
	)
	(segment
		(start 388.667498 -223.101662)
		(end 388.707884 -223.07804)
		(width 0.0889)
		(layer "In2.Cu")
		(net "M_I_CPU0_SA_DQ<2>")
	)
	(segment
		(start 392.511026 -215.942164)
		(end 392.739626 -215.942164)
		(width 0.14478)
		(layer "In2.Cu")
		(net "M_I_CPU0_SA_DQ<2>")
	)
	(segment
		(start 418.732208 -198.61022)
		(end 421.580564 -198.61022)
		(width 0.14478)
		(layer "In2.Cu")
		(net "M_I_CPU0_SA_DQ<2>")
	)
	(segment
		(start 388.197598 -223.911668)
		(end 388.235444 -223.889824)
		(width 0.0889)
		(layer "In2.Cu")
		(net "M_I_CPU0_SA_DQ<2>")
	)
	(segment
		(start 407.979118 -198.61022)
		(end 414.239202 -198.61022)
		(width 0.14478)
		(layer "In2.Cu")
		(net "M_I_CPU0_SA_DQ<2>")
	)
	(segment
		(start 391.220452 -216.763854)
		(end 391.381996 -216.60231)
		(width 0.14478)
		(layer "In2.Cu")
		(net "M_I_CPU0_SA_DQ<2>")
	)
	(segment
		(start 392.390884 -215.822022)
		(end 392.511026 -215.942164)
		(width 0.14478)
		(layer "In2.Cu")
		(net "M_I_CPU0_SA_DQ<2>")
	)
	(segment
		(start 395.509496 -211.079842)
		(end 407.979118 -198.61022)
		(width 0.14478)
		(layer "In2.Cu")
		(net "M_I_CPU0_SA_DQ<2>")
	)
	(arc
		(start 386.691886 -225.53168)
		(mid 386.974842 -225.607857)
		(end 387.257798 -225.53168)
		(width 0.0889)
		(layer "In2.Cu")
		(net "M_I_CPU0_SA_DQ<2>")
	)
	(arc
		(start 378.806202 -225.526854)
		(mid 378.98971 -225.48136)
		(end 379.171962 -225.53168)
		(width 0.0889)
		(layer "In2.Cu")
		(net "M_I_CPU0_SA_DQ<2>")
	)
	(arc
		(start 381.99187 -225.53168)
		(mid 382.274826 -225.607857)
		(end 382.557782 -225.53168)
		(width 0.0889)
		(layer "In2.Cu")
		(net "M_I_CPU0_SA_DQ<2>")
	)
	(arc
		(start 388.480046 -223.424242)
		(mid 388.521886 -223.252256)
		(end 388.638034 -223.11868)
		(width 0.0889)
		(layer "In2.Cu")
		(net "M_I_CPU0_SA_DQ<2>")
	)
	(arc
		(start 387.540246 -225.044254)
		(mid 387.581795 -224.872832)
		(end 387.697218 -224.739454)
		(width 0.0889)
		(layer "In2.Cu")
		(net "M_I_CPU0_SA_DQ<2>")
	)
	(arc
		(start 388.707884 -223.07804)
		(mid 388.885949 -222.875863)
		(end 388.9502 -222.614236)
		(width 0.0889)
		(layer "In2.Cu")
		(net "M_I_CPU0_SA_DQ<2>")
	)
	(arc
		(start 384.43789 -225.53168)
		(mid 384.624834 -225.481425)
		(end 384.811778 -225.53168)
		(width 0.0889)
		(layer "In2.Cu")
		(net "M_I_CPU0_SA_DQ<2>")
	)
	(arc
		(start 379.737874 -225.53168)
		(mid 379.924818 -225.481425)
		(end 380.111762 -225.53168)
		(width 0.0889)
		(layer "In2.Cu")
		(net "M_I_CPU0_SA_DQ<2>")
	)
	(arc
		(start 379.171962 -225.53168)
		(mid 379.454918 -225.607857)
		(end 379.737874 -225.53168)
		(width 0.0889)
		(layer "In2.Cu")
		(net "M_I_CPU0_SA_DQ<2>")
	)
	(arc
		(start 385.37769 -225.53168)
		(mid 385.559941 -225.48133)
		(end 385.74345 -225.526854)
		(width 0.0889)
		(layer "In2.Cu")
		(net "M_I_CPU0_SA_DQ<2>")
	)
	(arc
		(start 388.009892 -224.234248)
		(mid 388.051147 -224.063277)
		(end 388.165848 -223.929956)
		(width 0.0889)
		(layer "In2.Cu")
		(net "M_I_CPU0_SA_DQ<2>")
	)
	(arc
		(start 388.235444 -223.889824)
		(mid 388.415173 -223.687204)
		(end 388.480046 -223.424242)
		(width 0.0889)
		(layer "In2.Cu")
		(net "M_I_CPU0_SA_DQ<2>")
	)
	(arc
		(start 382.566164 -225.526854)
		(mid 382.749672 -225.48136)
		(end 382.931924 -225.53168)
		(width 0.0889)
		(layer "In2.Cu")
		(net "M_I_CPU0_SA_DQ<2>")
	)
	(arc
		(start 388.9502 -222.614236)
		(mid 388.991749 -222.442814)
		(end 389.107172 -222.309436)
		(width 0.0889)
		(layer "In2.Cu")
		(net "M_I_CPU0_SA_DQ<2>")
	)
	(arc
		(start 383.506218 -225.526854)
		(mid 383.689726 -225.48136)
		(end 383.871978 -225.53168)
		(width 0.0889)
		(layer "In2.Cu")
		(net "M_I_CPU0_SA_DQ<2>")
	)
	(arc
		(start 384.811778 -225.53168)
		(mid 385.094734 -225.607857)
		(end 385.37769 -225.53168)
		(width 0.0889)
		(layer "In2.Cu")
		(net "M_I_CPU0_SA_DQ<2>")
	)
	(arc
		(start 380.111762 -225.53168)
		(mid 380.394718 -225.607857)
		(end 380.677674 -225.53168)
		(width 0.0889)
		(layer "In2.Cu")
		(net "M_I_CPU0_SA_DQ<2>")
	)
	(arc
		(start 378.231908 -225.53168)
		(mid 378.514864 -225.607857)
		(end 378.79782 -225.53168)
		(width 0.0889)
		(layer "In2.Cu")
		(net "M_I_CPU0_SA_DQ<2>")
	)
	(arc
		(start 381.051816 -225.53168)
		(mid 381.334772 -225.607857)
		(end 381.617728 -225.53168)
		(width 0.0889)
		(layer "In2.Cu")
		(net "M_I_CPU0_SA_DQ<2>")
	)
	(arc
		(start 389.17245 -222.271336)
		(mid 389.354029 -222.068469)
		(end 389.419592 -221.80423)
		(width 0.0889)
		(layer "In2.Cu")
		(net "M_I_CPU0_SA_DQ<2>")
	)
	(arc
		(start 377.866148 -225.526854)
		(mid 378.049656 -225.48136)
		(end 378.231908 -225.53168)
		(width 0.0889)
		(layer "In2.Cu")
		(net "M_I_CPU0_SA_DQ<2>")
	)
	(arc
		(start 381.617728 -225.53168)
		(mid 381.799979 -225.48133)
		(end 381.983488 -225.526854)
		(width 0.0889)
		(layer "In2.Cu")
		(net "M_I_CPU0_SA_DQ<2>")
	)
	(arc
		(start 385.751832 -225.53168)
		(mid 386.034788 -225.607857)
		(end 386.317744 -225.53168)
		(width 0.0889)
		(layer "In2.Cu")
		(net "M_I_CPU0_SA_DQ<2>")
	)
	(arc
		(start 387.296914 -225.50882)
		(mid 387.475727 -225.30647)
		(end 387.540246 -225.044254)
		(width 0.0889)
		(layer "In2.Cu")
		(net "M_I_CPU0_SA_DQ<2>")
	)
	(arc
		(start 387.76402 -224.700592)
		(mid 387.944672 -224.497847)
		(end 388.009892 -224.234248)
		(width 0.0889)
		(layer "In2.Cu")
		(net "M_I_CPU0_SA_DQ<2>")
	)
	(arc
		(start 377.354846 -225.56343)
		(mid 377.610054 -225.606907)
		(end 377.857766 -225.53168)
		(width 0.0889)
		(layer "In2.Cu")
		(net "M_I_CPU0_SA_DQ<2>")
	)
	(arc
		(start 386.317744 -225.53168)
		(mid 386.499995 -225.48133)
		(end 386.683504 -225.526854)
		(width 0.0889)
		(layer "In2.Cu")
		(net "M_I_CPU0_SA_DQ<2>")
	)
	(arc
		(start 380.677674 -225.53168)
		(mid 380.859925 -225.48133)
		(end 381.043434 -225.526854)
		(width 0.0889)
		(layer "In2.Cu")
		(net "M_I_CPU0_SA_DQ<2>")
	)
	(arc
		(start 383.871978 -225.53168)
		(mid 384.154934 -225.607857)
		(end 384.43789 -225.53168)
		(width 0.0889)
		(layer "In2.Cu")
		(net "M_I_CPU0_SA_DQ<2>")
	)
	(arc
		(start 382.931924 -225.53168)
		(mid 383.21488 -225.607857)
		(end 383.497836 -225.53168)
		(width 0.0889)
		(layer "In2.Cu")
		(net "M_I_CPU0_SA_DQ<2>")
	)
	(segment
		(start 375.698004 -243.940076)
		(end 376.164856 -243.674138)
		(width 0.10668)
		(layer "F.Cu")
		(net "M_I_CPU0_SA_DQ<29>")
	)
	(segment
		(start 421.274748 -233.460036)
		(end 423.32656 -232.610152)
		(width 0.14478)
		(layer "In2.Cu")
		(net "M_I_CPU0_SA_DQ<29>")
	)
	(segment
		(start 385.74345 -244.001544)
		(end 385.751832 -243.996718)
		(width 0.0889)
		(layer "In2.Cu")
		(net "M_I_CPU0_SA_DQ<29>")
	)
	(segment
		(start 415.01187 -232.610152)
		(end 417.17214 -232.610152)
		(width 0.14478)
		(layer "In2.Cu")
		(net "M_I_CPU0_SA_DQ<29>")
	)
	(segment
		(start 391.01776 -243.996718)
		(end 391.026142 -244.001544)
		(width 0.0889)
		(layer "In2.Cu")
		(net "M_I_CPU0_SA_DQ<29>")
	)
	(segment
		(start 395.586204 -242.76685)
		(end 395.910054 -242.76685)
		(width 0.0889)
		(layer "In2.Cu")
		(net "M_I_CPU0_SA_DQ<29>")
	)
	(segment
		(start 376.010678 -243.939568)
		(end 376.03303 -244.02288)
		(width 0.0889)
		(layer "In2.Cu")
		(net "M_I_CPU0_SA_DQ<29>")
	)
	(segment
		(start 390.443466 -244.001544)
		(end 390.451848 -243.996718)
		(width 0.0889)
		(layer "In2.Cu")
		(net "M_I_CPU0_SA_DQ<29>")
	)
	(segment
		(start 417.17214 -232.610152)
		(end 419.223952 -233.460036)
		(width 0.14478)
		(layer "In2.Cu")
		(net "M_I_CPU0_SA_DQ<29>")
	)
	(segment
		(start 386.683504 -244.001544)
		(end 386.691886 -243.996718)
		(width 0.0889)
		(layer "In2.Cu")
		(net "M_I_CPU0_SA_DQ<29>")
	)
	(segment
		(start 392.323574 -244.001544)
		(end 392.331956 -243.996718)
		(width 0.0889)
		(layer "In2.Cu")
		(net "M_I_CPU0_SA_DQ<29>")
	)
	(segment
		(start 431.131218 -232.610152)
		(end 431.55616 -233.035094)
		(width 0.14478)
		(layer "In2.Cu")
		(net "M_I_CPU0_SA_DQ<29>")
	)
	(segment
		(start 393.554712 -243.920518)
		(end 394.432536 -243.920518)
		(width 0.0889)
		(layer "In2.Cu")
		(net "M_I_CPU0_SA_DQ<29>")
	)
	(segment
		(start 412.960058 -233.460036)
		(end 415.01187 -232.610152)
		(width 0.14478)
		(layer "In2.Cu")
		(net "M_I_CPU0_SA_DQ<29>")
	)
	(segment
		(start 388.197852 -243.996718)
		(end 388.206234 -244.001544)
		(width 0.0889)
		(layer "In2.Cu")
		(net "M_I_CPU0_SA_DQ<29>")
	)
	(segment
		(start 423.32656 -232.610152)
		(end 431.131218 -232.610152)
		(width 0.14478)
		(layer "In2.Cu")
		(net "M_I_CPU0_SA_DQ<29>")
	)
	(segment
		(start 382.557782 -243.996718)
		(end 382.566164 -244.001544)
		(width 0.0889)
		(layer "In2.Cu")
		(net "M_I_CPU0_SA_DQ<29>")
	)
	(segment
		(start 392.897868 -243.996718)
		(end 392.90625 -244.001544)
		(width 0.0889)
		(layer "In2.Cu")
		(net "M_I_CPU0_SA_DQ<29>")
	)
	(segment
		(start 408.392122 -236.955838)
		(end 408.392122 -235.822998)
		(width 0.14478)
		(layer "In2.Cu")
		(net "M_I_CPU0_SA_DQ<29>")
	)
	(segment
		(start 376.164856 -243.674138)
		(end 376.010678 -243.939568)
		(width 0.0889)
		(layer "In2.Cu")
		(net "M_I_CPU0_SA_DQ<29>")
	)
	(segment
		(start 377.857766 -243.996718)
		(end 377.866148 -244.001544)
		(width 0.0889)
		(layer "In2.Cu")
		(net "M_I_CPU0_SA_DQ<29>")
	)
	(segment
		(start 378.79782 -243.996718)
		(end 378.806202 -244.001544)
		(width 0.0889)
		(layer "In2.Cu")
		(net "M_I_CPU0_SA_DQ<29>")
	)
	(segment
		(start 395.910054 -242.76685)
		(end 402.58111 -242.76685)
		(width 0.14478)
		(layer "In2.Cu")
		(net "M_I_CPU0_SA_DQ<29>")
	)
	(segment
		(start 402.58111 -242.76685)
		(end 408.392122 -236.955838)
		(width 0.14478)
		(layer "In2.Cu")
		(net "M_I_CPU0_SA_DQ<29>")
	)
	(segment
		(start 377.283472 -244.001544)
		(end 377.291854 -243.996718)
		(width 0.0889)
		(layer "In2.Cu")
		(net "M_I_CPU0_SA_DQ<29>")
	)
	(segment
		(start 383.497836 -243.996718)
		(end 383.506218 -244.001544)
		(width 0.0889)
		(layer "In2.Cu")
		(net "M_I_CPU0_SA_DQ<29>")
	)
	(segment
		(start 376.343418 -244.001544)
		(end 376.3518 -243.996718)
		(width 0.0889)
		(layer "In2.Cu")
		(net "M_I_CPU0_SA_DQ<29>")
	)
	(segment
		(start 394.432536 -243.920518)
		(end 395.586204 -242.76685)
		(width 0.0889)
		(layer "In2.Cu")
		(net "M_I_CPU0_SA_DQ<29>")
	)
	(segment
		(start 408.392122 -235.822998)
		(end 410.755084 -233.460036)
		(width 0.14478)
		(layer "In2.Cu")
		(net "M_I_CPU0_SA_DQ<29>")
	)
	(segment
		(start 387.257798 -243.996718)
		(end 387.26618 -244.001544)
		(width 0.0889)
		(layer "In2.Cu")
		(net "M_I_CPU0_SA_DQ<29>")
	)
	(segment
		(start 381.043434 -244.001544)
		(end 381.051816 -243.996718)
		(width 0.0889)
		(layer "In2.Cu")
		(net "M_I_CPU0_SA_DQ<29>")
	)
	(segment
		(start 410.755084 -233.460036)
		(end 412.960058 -233.460036)
		(width 0.14478)
		(layer "In2.Cu")
		(net "M_I_CPU0_SA_DQ<29>")
	)
	(segment
		(start 419.223952 -233.460036)
		(end 421.274748 -233.460036)
		(width 0.14478)
		(layer "In2.Cu")
		(net "M_I_CPU0_SA_DQ<29>")
	)
	(segment
		(start 381.983488 -244.001544)
		(end 381.99187 -243.996718)
		(width 0.0889)
		(layer "In2.Cu")
		(net "M_I_CPU0_SA_DQ<29>")
	)
	(arc
		(start 381.051816 -243.996718)
		(mid 381.334772 -243.920541)
		(end 381.617728 -243.996718)
		(width 0.0889)
		(layer "In2.Cu")
		(net "M_I_CPU0_SA_DQ<29>")
	)
	(arc
		(start 383.871978 -243.996718)
		(mid 384.154934 -243.920541)
		(end 384.43789 -243.996718)
		(width 0.0889)
		(layer "In2.Cu")
		(net "M_I_CPU0_SA_DQ<29>")
	)
	(arc
		(start 382.566164 -244.001544)
		(mid 382.749672 -244.047038)
		(end 382.931924 -243.996718)
		(width 0.0889)
		(layer "In2.Cu")
		(net "M_I_CPU0_SA_DQ<29>")
	)
	(arc
		(start 389.511794 -243.996718)
		(mid 389.79475 -243.920541)
		(end 390.077706 -243.996718)
		(width 0.0889)
		(layer "In2.Cu")
		(net "M_I_CPU0_SA_DQ<29>")
	)
	(arc
		(start 385.751832 -243.996718)
		(mid 386.034788 -243.920541)
		(end 386.317744 -243.996718)
		(width 0.0889)
		(layer "In2.Cu")
		(net "M_I_CPU0_SA_DQ<29>")
	)
	(arc
		(start 376.917712 -243.996718)
		(mid 377.099963 -244.047068)
		(end 377.283472 -244.001544)
		(width 0.0889)
		(layer "In2.Cu")
		(net "M_I_CPU0_SA_DQ<29>")
	)
	(arc
		(start 392.331956 -243.996718)
		(mid 392.614912 -243.920541)
		(end 392.897868 -243.996718)
		(width 0.0889)
		(layer "In2.Cu")
		(net "M_I_CPU0_SA_DQ<29>")
	)
	(arc
		(start 391.391902 -243.996718)
		(mid 391.674858 -243.920541)
		(end 391.957814 -243.996718)
		(width 0.0889)
		(layer "In2.Cu")
		(net "M_I_CPU0_SA_DQ<29>")
	)
	(arc
		(start 391.026142 -244.001544)
		(mid 391.20965 -244.047038)
		(end 391.391902 -243.996718)
		(width 0.0889)
		(layer "In2.Cu")
		(net "M_I_CPU0_SA_DQ<29>")
	)
	(arc
		(start 381.99187 -243.996718)
		(mid 382.274826 -243.920541)
		(end 382.557782 -243.996718)
		(width 0.0889)
		(layer "In2.Cu")
		(net "M_I_CPU0_SA_DQ<29>")
	)
	(arc
		(start 392.90625 -244.001544)
		(mid 393.089758 -244.047038)
		(end 393.27201 -243.996718)
		(width 0.0889)
		(layer "In2.Cu")
		(net "M_I_CPU0_SA_DQ<29>")
	)
	(arc
		(start 387.63194 -243.996718)
		(mid 387.914896 -243.920541)
		(end 388.197852 -243.996718)
		(width 0.0889)
		(layer "In2.Cu")
		(net "M_I_CPU0_SA_DQ<29>")
	)
	(arc
		(start 384.811778 -243.996718)
		(mid 385.094734 -243.920541)
		(end 385.37769 -243.996718)
		(width 0.0889)
		(layer "In2.Cu")
		(net "M_I_CPU0_SA_DQ<29>")
	)
	(arc
		(start 386.691886 -243.996718)
		(mid 386.974842 -243.920541)
		(end 387.257798 -243.996718)
		(width 0.0889)
		(layer "In2.Cu")
		(net "M_I_CPU0_SA_DQ<29>")
	)
	(arc
		(start 377.866148 -244.001544)
		(mid 378.049656 -244.047038)
		(end 378.231908 -243.996718)
		(width 0.0889)
		(layer "In2.Cu")
		(net "M_I_CPU0_SA_DQ<29>")
	)
	(arc
		(start 390.077706 -243.996718)
		(mid 390.259957 -244.047068)
		(end 390.443466 -244.001544)
		(width 0.0889)
		(layer "In2.Cu")
		(net "M_I_CPU0_SA_DQ<29>")
	)
	(arc
		(start 379.737874 -243.996718)
		(mid 379.924818 -244.046973)
		(end 380.111762 -243.996718)
		(width 0.0889)
		(layer "In2.Cu")
		(net "M_I_CPU0_SA_DQ<29>")
	)
	(arc
		(start 386.317744 -243.996718)
		(mid 386.499995 -244.047068)
		(end 386.683504 -244.001544)
		(width 0.0889)
		(layer "In2.Cu")
		(net "M_I_CPU0_SA_DQ<29>")
	)
	(arc
		(start 378.231908 -243.996718)
		(mid 378.514864 -243.920541)
		(end 378.79782 -243.996718)
		(width 0.0889)
		(layer "In2.Cu")
		(net "M_I_CPU0_SA_DQ<29>")
	)
	(arc
		(start 390.451848 -243.996718)
		(mid 390.734804 -243.920541)
		(end 391.01776 -243.996718)
		(width 0.0889)
		(layer "In2.Cu")
		(net "M_I_CPU0_SA_DQ<29>")
	)
	(arc
		(start 388.571994 -243.996718)
		(mid 388.85495 -243.920541)
		(end 389.137906 -243.996718)
		(width 0.0889)
		(layer "In2.Cu")
		(net "M_I_CPU0_SA_DQ<29>")
	)
	(arc
		(start 379.171962 -243.996718)
		(mid 379.454918 -243.920541)
		(end 379.737874 -243.996718)
		(width 0.0889)
		(layer "In2.Cu")
		(net "M_I_CPU0_SA_DQ<29>")
	)
	(arc
		(start 377.291854 -243.996718)
		(mid 377.57481 -243.920541)
		(end 377.857766 -243.996718)
		(width 0.0889)
		(layer "In2.Cu")
		(net "M_I_CPU0_SA_DQ<29>")
	)
	(arc
		(start 380.111762 -243.996718)
		(mid 380.394718 -243.920541)
		(end 380.677674 -243.996718)
		(width 0.0889)
		(layer "In2.Cu")
		(net "M_I_CPU0_SA_DQ<29>")
	)
	(arc
		(start 384.43789 -243.996718)
		(mid 384.624834 -244.046973)
		(end 384.811778 -243.996718)
		(width 0.0889)
		(layer "In2.Cu")
		(net "M_I_CPU0_SA_DQ<29>")
	)
	(arc
		(start 376.3518 -243.996718)
		(mid 376.634756 -243.920541)
		(end 376.917712 -243.996718)
		(width 0.0889)
		(layer "In2.Cu")
		(net "M_I_CPU0_SA_DQ<29>")
	)
	(arc
		(start 382.931924 -243.996718)
		(mid 383.21488 -243.920541)
		(end 383.497836 -243.996718)
		(width 0.0889)
		(layer "In2.Cu")
		(net "M_I_CPU0_SA_DQ<29>")
	)
	(arc
		(start 383.506218 -244.001544)
		(mid 383.689726 -244.047038)
		(end 383.871978 -243.996718)
		(width 0.0889)
		(layer "In2.Cu")
		(net "M_I_CPU0_SA_DQ<29>")
	)
	(arc
		(start 393.27201 -243.996718)
		(mid 393.408332 -243.939977)
		(end 393.554712 -243.920518)
		(width 0.0889)
		(layer "In2.Cu")
		(net "M_I_CPU0_SA_DQ<29>")
	)
	(arc
		(start 380.677674 -243.996718)
		(mid 380.859925 -244.047068)
		(end 381.043434 -244.001544)
		(width 0.0889)
		(layer "In2.Cu")
		(net "M_I_CPU0_SA_DQ<29>")
	)
	(arc
		(start 385.37769 -243.996718)
		(mid 385.559941 -244.047068)
		(end 385.74345 -244.001544)
		(width 0.0889)
		(layer "In2.Cu")
		(net "M_I_CPU0_SA_DQ<29>")
	)
	(arc
		(start 381.617728 -243.996718)
		(mid 381.799979 -244.047068)
		(end 381.983488 -244.001544)
		(width 0.0889)
		(layer "In2.Cu")
		(net "M_I_CPU0_SA_DQ<29>")
	)
	(arc
		(start 391.957814 -243.996718)
		(mid 392.140065 -244.047068)
		(end 392.323574 -244.001544)
		(width 0.0889)
		(layer "In2.Cu")
		(net "M_I_CPU0_SA_DQ<29>")
	)
	(arc
		(start 378.806202 -244.001544)
		(mid 378.98971 -244.047038)
		(end 379.171962 -243.996718)
		(width 0.0889)
		(layer "In2.Cu")
		(net "M_I_CPU0_SA_DQ<29>")
	)
	(arc
		(start 387.26618 -244.001544)
		(mid 387.449688 -244.047038)
		(end 387.63194 -243.996718)
		(width 0.0889)
		(layer "In2.Cu")
		(net "M_I_CPU0_SA_DQ<29>")
	)
	(arc
		(start 389.137906 -243.996718)
		(mid 389.32485 -244.046973)
		(end 389.511794 -243.996718)
		(width 0.0889)
		(layer "In2.Cu")
		(net "M_I_CPU0_SA_DQ<29>")
	)
	(arc
		(start 376.03303 -244.02288)
		(mid 376.19054 -244.046078)
		(end 376.343418 -244.001544)
		(width 0.0889)
		(layer "In2.Cu")
		(net "M_I_CPU0_SA_DQ<29>")
	)
	(arc
		(start 388.206234 -244.001544)
		(mid 388.389742 -244.047038)
		(end 388.571994 -243.996718)
		(width 0.0889)
		(layer "In2.Cu")
		(net "M_I_CPU0_SA_DQ<29>")
	)
	(segment
		(start 377.107958 -243.13007)
		(end 377.57481 -242.864132)
		(width 0.10668)
		(layer "F.Cu")
		(net "M_I_CPU0_SA_DQ<28>")
	)
	(segment
		(start 414.783778 -230.919782)
		(end 417.717986 -230.919782)
		(width 0.14478)
		(layer "In2.Cu")
		(net "M_I_CPU0_SA_DQ<28>")
	)
	(segment
		(start 393.406376 -242.98783)
		(end 393.949936 -242.98783)
		(width 0.0889)
		(layer "In2.Cu")
		(net "M_I_CPU0_SA_DQ<28>")
	)
	(segment
		(start 395.539976 -241.82959)
		(end 395.884654 -241.82959)
		(width 0.0889)
		(layer "In2.Cu")
		(net "M_I_CPU0_SA_DQ<28>")
	)
	(segment
		(start 377.420886 -243.129562)
		(end 377.443238 -243.212874)
		(width 0.0889)
		(layer "In2.Cu")
		(net "M_I_CPU0_SA_DQ<28>")
	)
	(segment
		(start 430.18202 -231.721914)
		(end 430.18202 -231.073706)
		(width 0.14478)
		(layer "In2.Cu")
		(net "M_I_CPU0_SA_DQ<28>")
	)
	(segment
		(start 421.583358 -231.769666)
		(end 422.433242 -230.919782)
		(width 0.14478)
		(layer "In2.Cu")
		(net "M_I_CPU0_SA_DQ<28>")
	)
	(segment
		(start 429.62322 -231.721914)
		(end 429.786796 -231.88549)
		(width 0.14478)
		(layer "In2.Cu")
		(net "M_I_CPU0_SA_DQ<28>")
	)
	(segment
		(start 395.884654 -241.82959)
		(end 401.113498 -241.82959)
		(width 0.14478)
		(layer "In2.Cu")
		(net "M_I_CPU0_SA_DQ<28>")
	)
	(segment
		(start 429.786796 -231.88549)
		(end 430.018444 -231.88549)
		(width 0.14478)
		(layer "In2.Cu")
		(net "M_I_CPU0_SA_DQ<28>")
	)
	(segment
		(start 388.093458 -243.191538)
		(end 388.10184 -243.186712)
		(width 0.0889)
		(layer "In2.Cu")
		(net "M_I_CPU0_SA_DQ<28>")
	)
	(segment
		(start 384.90779 -243.186712)
		(end 384.916172 -243.191538)
		(width 0.0889)
		(layer "In2.Cu")
		(net "M_I_CPU0_SA_DQ<28>")
	)
	(segment
		(start 392.42746 -243.186712)
		(end 392.435842 -243.191538)
		(width 0.0889)
		(layer "In2.Cu")
		(net "M_I_CPU0_SA_DQ<28>")
	)
	(segment
		(start 430.345596 -230.91013)
		(end 431.131218 -230.91013)
		(width 0.14478)
		(layer "In2.Cu")
		(net "M_I_CPU0_SA_DQ<28>")
	)
	(segment
		(start 430.018444 -231.88549)
		(end 430.18202 -231.721914)
		(width 0.14478)
		(layer "In2.Cu")
		(net "M_I_CPU0_SA_DQ<28>")
	)
	(segment
		(start 377.57481 -242.864132)
		(end 377.420886 -243.129562)
		(width 0.0889)
		(layer "In2.Cu")
		(net "M_I_CPU0_SA_DQ<28>")
	)
	(segment
		(start 429.469296 -230.919782)
		(end 429.62322 -231.073706)
		(width 0.14478)
		(layer "In2.Cu")
		(net "M_I_CPU0_SA_DQ<28>")
	)
	(segment
		(start 380.207774 -243.186712)
		(end 380.216156 -243.191538)
		(width 0.0889)
		(layer "In2.Cu")
		(net "M_I_CPU0_SA_DQ<28>")
	)
	(segment
		(start 422.433242 -230.919782)
		(end 429.469296 -230.919782)
		(width 0.14478)
		(layer "In2.Cu")
		(net "M_I_CPU0_SA_DQ<28>")
	)
	(segment
		(start 393.283694 -243.110512)
		(end 393.406376 -242.98783)
		(width 0.0889)
		(layer "In2.Cu")
		(net "M_I_CPU0_SA_DQ<28>")
	)
	(segment
		(start 394.902436 -242.46713)
		(end 395.539976 -241.82959)
		(width 0.0889)
		(layer "In2.Cu")
		(net "M_I_CPU0_SA_DQ<28>")
	)
	(segment
		(start 394.470636 -242.46713)
		(end 394.902436 -242.46713)
		(width 0.0889)
		(layer "In2.Cu")
		(net "M_I_CPU0_SA_DQ<28>")
	)
	(segment
		(start 381.147828 -243.186712)
		(end 381.15621 -243.191538)
		(width 0.0889)
		(layer "In2.Cu")
		(net "M_I_CPU0_SA_DQ<28>")
	)
	(segment
		(start 417.717986 -230.919782)
		(end 418.56787 -231.769666)
		(width 0.14478)
		(layer "In2.Cu")
		(net "M_I_CPU0_SA_DQ<28>")
	)
	(segment
		(start 385.847844 -243.186712)
		(end 385.856226 -243.191538)
		(width 0.0889)
		(layer "In2.Cu")
		(net "M_I_CPU0_SA_DQ<28>")
	)
	(segment
		(start 391.85342 -243.191538)
		(end 391.861802 -243.186712)
		(width 0.0889)
		(layer "In2.Cu")
		(net "M_I_CPU0_SA_DQ<28>")
	)
	(segment
		(start 389.033512 -243.191538)
		(end 389.041894 -243.186712)
		(width 0.0889)
		(layer "In2.Cu")
		(net "M_I_CPU0_SA_DQ<28>")
	)
	(segment
		(start 391.861802 -243.186712)
		(end 391.872216 -243.180616)
		(width 0.0889)
		(layer "In2.Cu")
		(net "M_I_CPU0_SA_DQ<28>")
	)
	(segment
		(start 430.18202 -231.073706)
		(end 430.345596 -230.91013)
		(width 0.14478)
		(layer "In2.Cu")
		(net "M_I_CPU0_SA_DQ<28>")
	)
	(segment
		(start 429.62322 -231.073706)
		(end 429.62322 -231.721914)
		(width 0.14478)
		(layer "In2.Cu")
		(net "M_I_CPU0_SA_DQ<28>")
	)
	(segment
		(start 411.173422 -231.769666)
		(end 413.933894 -231.769666)
		(width 0.14478)
		(layer "In2.Cu")
		(net "M_I_CPU0_SA_DQ<28>")
	)
	(segment
		(start 418.56787 -231.769666)
		(end 421.583358 -231.769666)
		(width 0.14478)
		(layer "In2.Cu")
		(net "M_I_CPU0_SA_DQ<28>")
	)
	(segment
		(start 413.933894 -231.769666)
		(end 414.783778 -230.919782)
		(width 0.14478)
		(layer "In2.Cu")
		(net "M_I_CPU0_SA_DQ<28>")
	)
	(segment
		(start 393.949936 -242.98783)
		(end 394.470636 -242.46713)
		(width 0.0889)
		(layer "In2.Cu")
		(net "M_I_CPU0_SA_DQ<28>")
	)
	(segment
		(start 379.63348 -243.191538)
		(end 379.641862 -243.186712)
		(width 0.0889)
		(layer "In2.Cu")
		(net "M_I_CPU0_SA_DQ<28>")
	)
	(segment
		(start 383.393442 -243.191538)
		(end 383.401824 -243.186712)
		(width 0.0889)
		(layer "In2.Cu")
		(net "M_I_CPU0_SA_DQ<28>")
	)
	(segment
		(start 393.084812 -243.110512)
		(end 393.283694 -243.110512)
		(width 0.0889)
		(layer "In2.Cu")
		(net "M_I_CPU0_SA_DQ<28>")
	)
	(segment
		(start 401.113498 -241.82959)
		(end 411.173422 -231.769666)
		(width 0.14478)
		(layer "In2.Cu")
		(net "M_I_CPU0_SA_DQ<28>")
	)
	(segment
		(start 378.693426 -243.191538)
		(end 378.701808 -243.186712)
		(width 0.0889)
		(layer "In2.Cu")
		(net "M_I_CPU0_SA_DQ<28>")
	)
	(segment
		(start 389.607806 -243.186712)
		(end 389.616188 -243.191538)
		(width 0.0889)
		(layer "In2.Cu")
		(net "M_I_CPU0_SA_DQ<28>")
	)
	(segment
		(start 384.333496 -243.191538)
		(end 384.341878 -243.186712)
		(width 0.0889)
		(layer "In2.Cu")
		(net "M_I_CPU0_SA_DQ<28>")
	)
	(segment
		(start 431.131218 -230.91013)
		(end 431.55616 -231.335072)
		(width 0.14478)
		(layer "In2.Cu")
		(net "M_I_CPU0_SA_DQ<28>")
	)
	(arc
		(start 378.701808 -243.186712)
		(mid 378.984764 -243.110535)
		(end 379.26772 -243.186712)
		(width 0.0889)
		(layer "In2.Cu")
		(net "M_I_CPU0_SA_DQ<28>")
	)
	(arc
		(start 382.087882 -243.186712)
		(mid 382.274826 -243.236967)
		(end 382.46177 -243.186712)
		(width 0.0889)
		(layer "In2.Cu")
		(net "M_I_CPU0_SA_DQ<28>")
	)
	(arc
		(start 380.581916 -243.186712)
		(mid 380.864872 -243.110535)
		(end 381.147828 -243.186712)
		(width 0.0889)
		(layer "In2.Cu")
		(net "M_I_CPU0_SA_DQ<28>")
	)
	(arc
		(start 387.161786 -243.186712)
		(mid 387.444742 -243.110535)
		(end 387.727698 -243.186712)
		(width 0.0889)
		(layer "In2.Cu")
		(net "M_I_CPU0_SA_DQ<28>")
	)
	(arc
		(start 385.856226 -243.191538)
		(mid 386.039734 -243.237032)
		(end 386.221986 -243.186712)
		(width 0.0889)
		(layer "In2.Cu")
		(net "M_I_CPU0_SA_DQ<28>")
	)
	(arc
		(start 390.54786 -243.186712)
		(mid 390.734804 -243.236967)
		(end 390.921748 -243.186712)
		(width 0.0889)
		(layer "In2.Cu")
		(net "M_I_CPU0_SA_DQ<28>")
	)
	(arc
		(start 390.921748 -243.186712)
		(mid 391.204704 -243.110535)
		(end 391.48766 -243.186712)
		(width 0.0889)
		(layer "In2.Cu")
		(net "M_I_CPU0_SA_DQ<28>")
	)
	(arc
		(start 384.341878 -243.186712)
		(mid 384.624834 -243.110535)
		(end 384.90779 -243.186712)
		(width 0.0889)
		(layer "In2.Cu")
		(net "M_I_CPU0_SA_DQ<28>")
	)
	(arc
		(start 384.916172 -243.191538)
		(mid 385.09968 -243.237032)
		(end 385.281932 -243.186712)
		(width 0.0889)
		(layer "In2.Cu")
		(net "M_I_CPU0_SA_DQ<28>")
	)
	(arc
		(start 383.027682 -243.186712)
		(mid 383.209933 -243.237062)
		(end 383.393442 -243.191538)
		(width 0.0889)
		(layer "In2.Cu")
		(net "M_I_CPU0_SA_DQ<28>")
	)
	(arc
		(start 387.727698 -243.186712)
		(mid 387.909949 -243.237062)
		(end 388.093458 -243.191538)
		(width 0.0889)
		(layer "In2.Cu")
		(net "M_I_CPU0_SA_DQ<28>")
	)
	(arc
		(start 389.041894 -243.186712)
		(mid 389.32485 -243.110535)
		(end 389.607806 -243.186712)
		(width 0.0889)
		(layer "In2.Cu")
		(net "M_I_CPU0_SA_DQ<28>")
	)
	(arc
		(start 381.15621 -243.191538)
		(mid 381.339718 -243.237032)
		(end 381.52197 -243.186712)
		(width 0.0889)
		(layer "In2.Cu")
		(net "M_I_CPU0_SA_DQ<28>")
	)
	(arc
		(start 391.872216 -243.180616)
		(mid 392.150648 -243.110518)
		(end 392.42746 -243.186712)
		(width 0.0889)
		(layer "In2.Cu")
		(net "M_I_CPU0_SA_DQ<28>")
	)
	(arc
		(start 388.667752 -243.186712)
		(mid 388.850003 -243.237062)
		(end 389.033512 -243.191538)
		(width 0.0889)
		(layer "In2.Cu")
		(net "M_I_CPU0_SA_DQ<28>")
	)
	(arc
		(start 388.10184 -243.186712)
		(mid 388.384796 -243.110535)
		(end 388.667752 -243.186712)
		(width 0.0889)
		(layer "In2.Cu")
		(net "M_I_CPU0_SA_DQ<28>")
	)
	(arc
		(start 383.401824 -243.186712)
		(mid 383.68478 -243.110535)
		(end 383.967736 -243.186712)
		(width 0.0889)
		(layer "In2.Cu")
		(net "M_I_CPU0_SA_DQ<28>")
	)
	(arc
		(start 391.48766 -243.186712)
		(mid 391.669911 -243.237062)
		(end 391.85342 -243.191538)
		(width 0.0889)
		(layer "In2.Cu")
		(net "M_I_CPU0_SA_DQ<28>")
	)
	(arc
		(start 389.981948 -243.186712)
		(mid 390.264904 -243.110535)
		(end 390.54786 -243.186712)
		(width 0.0889)
		(layer "In2.Cu")
		(net "M_I_CPU0_SA_DQ<28>")
	)
	(arc
		(start 389.616188 -243.191538)
		(mid 389.799696 -243.237032)
		(end 389.981948 -243.186712)
		(width 0.0889)
		(layer "In2.Cu")
		(net "M_I_CPU0_SA_DQ<28>")
	)
	(arc
		(start 380.216156 -243.191538)
		(mid 380.399664 -243.237032)
		(end 380.581916 -243.186712)
		(width 0.0889)
		(layer "In2.Cu")
		(net "M_I_CPU0_SA_DQ<28>")
	)
	(arc
		(start 385.281932 -243.186712)
		(mid 385.564888 -243.110535)
		(end 385.847844 -243.186712)
		(width 0.0889)
		(layer "In2.Cu")
		(net "M_I_CPU0_SA_DQ<28>")
	)
	(arc
		(start 392.435842 -243.191538)
		(mid 392.61935 -243.237032)
		(end 392.801602 -243.186712)
		(width 0.0889)
		(layer "In2.Cu")
		(net "M_I_CPU0_SA_DQ<28>")
	)
	(arc
		(start 386.221986 -243.186712)
		(mid 386.504942 -243.110535)
		(end 386.787898 -243.186712)
		(width 0.0889)
		(layer "In2.Cu")
		(net "M_I_CPU0_SA_DQ<28>")
	)
	(arc
		(start 381.52197 -243.186712)
		(mid 381.804926 -243.110535)
		(end 382.087882 -243.186712)
		(width 0.0889)
		(layer "In2.Cu")
		(net "M_I_CPU0_SA_DQ<28>")
	)
	(arc
		(start 382.46177 -243.186712)
		(mid 382.744726 -243.110535)
		(end 383.027682 -243.186712)
		(width 0.0889)
		(layer "In2.Cu")
		(net "M_I_CPU0_SA_DQ<28>")
	)
	(arc
		(start 383.967736 -243.186712)
		(mid 384.149987 -243.237062)
		(end 384.333496 -243.191538)
		(width 0.0889)
		(layer "In2.Cu")
		(net "M_I_CPU0_SA_DQ<28>")
	)
	(arc
		(start 386.787898 -243.186712)
		(mid 386.974842 -243.236967)
		(end 387.161786 -243.186712)
		(width 0.0889)
		(layer "In2.Cu")
		(net "M_I_CPU0_SA_DQ<28>")
	)
	(arc
		(start 392.801602 -243.186712)
		(mid 392.938165 -243.129879)
		(end 393.084812 -243.110512)
		(width 0.0889)
		(layer "In2.Cu")
		(net "M_I_CPU0_SA_DQ<28>")
	)
	(arc
		(start 379.26772 -243.186712)
		(mid 379.449971 -243.237062)
		(end 379.63348 -243.191538)
		(width 0.0889)
		(layer "In2.Cu")
		(net "M_I_CPU0_SA_DQ<28>")
	)
	(arc
		(start 379.641862 -243.186712)
		(mid 379.924818 -243.110535)
		(end 380.207774 -243.186712)
		(width 0.0889)
		(layer "In2.Cu")
		(net "M_I_CPU0_SA_DQ<28>")
	)
	(arc
		(start 377.443238 -243.212874)
		(mid 377.605427 -243.235609)
		(end 377.761754 -243.186712)
		(width 0.0889)
		(layer "In2.Cu")
		(net "M_I_CPU0_SA_DQ<28>")
	)
	(arc
		(start 378.327666 -243.186712)
		(mid 378.509917 -243.237062)
		(end 378.693426 -243.191538)
		(width 0.0889)
		(layer "In2.Cu")
		(net "M_I_CPU0_SA_DQ<28>")
	)
	(arc
		(start 377.761754 -243.186712)
		(mid 378.04471 -243.110535)
		(end 378.327666 -243.186712)
		(width 0.0889)
		(layer "In2.Cu")
		(net "M_I_CPU0_SA_DQ<28>")
	)
	(segment
		(start 375.22785 -241.510058)
		(end 375.694702 -241.24412)
		(width 0.10668)
		(layer "F.Cu")
		(net "M_I_CPU0_SA_DQ<27>")
	)
	(segment
		(start 404.921466 -234.512612)
		(end 404.458932 -234.050078)
		(width 0.14478)
		(layer "In2.Cu")
		(net "M_I_CPU0_SA_DQ<27>")
	)
	(segment
		(start 388.093458 -240.916714)
		(end 388.10184 -240.92154)
		(width 0.0889)
		(layer "In2.Cu")
		(net "M_I_CPU0_SA_DQ<27>")
	)
	(segment
		(start 384.333496 -240.916714)
		(end 384.341878 -240.92154)
		(width 0.0889)
		(layer "In2.Cu")
		(net "M_I_CPU0_SA_DQ<27>")
	)
	(segment
		(start 408.931618 -230.212392)
		(end 410.793692 -228.350318)
		(width 0.14478)
		(layer "In2.Cu")
		(net "M_I_CPU0_SA_DQ<27>")
	)
	(segment
		(start 421.465756 -228.350318)
		(end 422.31564 -227.500434)
		(width 0.14478)
		(layer "In2.Cu")
		(net "M_I_CPU0_SA_DQ<27>")
	)
	(segment
		(start 395.884654 -239.47755)
		(end 398.789144 -239.47755)
		(width 0.14478)
		(layer "In2.Cu")
		(net "M_I_CPU0_SA_DQ<27>")
	)
	(segment
		(start 383.393442 -240.916714)
		(end 383.401824 -240.92154)
		(width 0.0889)
		(layer "In2.Cu")
		(net "M_I_CPU0_SA_DQ<27>")
	)
	(segment
		(start 404.458932 -233.821478)
		(end 404.620476 -233.659934)
		(width 0.14478)
		(layer "In2.Cu")
		(net "M_I_CPU0_SA_DQ<27>")
	)
	(segment
		(start 406.091898 -233.34218)
		(end 406.320498 -233.34218)
		(width 0.14478)
		(layer "In2.Cu")
		(net "M_I_CPU0_SA_DQ<27>")
	)
	(segment
		(start 379.63348 -240.916714)
		(end 379.641862 -240.92154)
		(width 0.0889)
		(layer "In2.Cu")
		(net "M_I_CPU0_SA_DQ<27>")
	)
	(segment
		(start 413.92729 -228.350318)
		(end 414.777174 -227.500434)
		(width 0.14478)
		(layer "In2.Cu")
		(net "M_I_CPU0_SA_DQ<27>")
	)
	(segment
		(start 404.849076 -233.659934)
		(end 405.31161 -234.122468)
		(width 0.14478)
		(layer "In2.Cu")
		(net "M_I_CPU0_SA_DQ<27>")
	)
	(segment
		(start 405.54021 -234.122468)
		(end 405.701754 -233.960924)
		(width 0.14478)
		(layer "In2.Cu")
		(net "M_I_CPU0_SA_DQ<27>")
	)
	(segment
		(start 381.147828 -240.92154)
		(end 381.15621 -240.916714)
		(width 0.0889)
		(layer "In2.Cu")
		(net "M_I_CPU0_SA_DQ<27>")
	)
	(segment
		(start 395.466316 -239.53089)
		(end 395.519656 -239.47755)
		(width 0.0889)
		(layer "In2.Cu")
		(net "M_I_CPU0_SA_DQ<27>")
	)
	(segment
		(start 395.519656 -239.47755)
		(end 395.884654 -239.47755)
		(width 0.0889)
		(layer "In2.Cu")
		(net "M_I_CPU0_SA_DQ<27>")
	)
	(segment
		(start 418.170868 -227.500434)
		(end 419.020752 -228.350318)
		(width 0.14478)
		(layer "In2.Cu")
		(net "M_I_CPU0_SA_DQ<27>")
	)
	(segment
		(start 403.338792 -234.927902)
		(end 404.734776 -234.927902)
		(width 0.14478)
		(layer "In2.Cu")
		(net "M_I_CPU0_SA_DQ<27>")
	)
	(segment
		(start 393.483338 -240.83264)
		(end 394.305536 -240.010442)
		(width 0.0889)
		(layer "In2.Cu")
		(net "M_I_CPU0_SA_DQ<27>")
	)
	(segment
		(start 380.207774 -240.92154)
		(end 380.216156 -240.916714)
		(width 0.0889)
		(layer "In2.Cu")
		(net "M_I_CPU0_SA_DQ<27>")
	)
	(segment
		(start 375.84888 -240.97869)
		(end 375.945146 -240.95329)
		(width 0.0889)
		(layer "In2.Cu")
		(net "M_I_CPU0_SA_DQ<27>")
	)
	(segment
		(start 410.793692 -228.350318)
		(end 413.92729 -228.350318)
		(width 0.14478)
		(layer "In2.Cu")
		(net "M_I_CPU0_SA_DQ<27>")
	)
	(segment
		(start 405.629364 -232.879646)
		(end 406.091898 -233.34218)
		(width 0.14478)
		(layer "In2.Cu")
		(net "M_I_CPU0_SA_DQ<27>")
	)
	(segment
		(start 405.23922 -233.04119)
		(end 405.400764 -232.879646)
		(width 0.14478)
		(layer "In2.Cu")
		(net "M_I_CPU0_SA_DQ<27>")
	)
	(segment
		(start 392.42746 -240.92154)
		(end 392.435842 -240.916714)
		(width 0.0889)
		(layer "In2.Cu")
		(net "M_I_CPU0_SA_DQ<27>")
	)
	(segment
		(start 405.400764 -232.879646)
		(end 405.629364 -232.879646)
		(width 0.14478)
		(layer "In2.Cu")
		(net "M_I_CPU0_SA_DQ<27>")
	)
	(segment
		(start 408.931618 -230.73106)
		(end 408.931618 -230.212392)
		(width 0.14478)
		(layer "In2.Cu")
		(net "M_I_CPU0_SA_DQ<27>")
	)
	(segment
		(start 414.777174 -227.500434)
		(end 418.170868 -227.500434)
		(width 0.14478)
		(layer "In2.Cu")
		(net "M_I_CPU0_SA_DQ<27>")
	)
	(segment
		(start 405.31161 -234.122468)
		(end 405.54021 -234.122468)
		(width 0.14478)
		(layer "In2.Cu")
		(net "M_I_CPU0_SA_DQ<27>")
	)
	(segment
		(start 389.033512 -240.916714)
		(end 389.041894 -240.92154)
		(width 0.0889)
		(layer "In2.Cu")
		(net "M_I_CPU0_SA_DQ<27>")
	)
	(segment
		(start 391.861802 -240.92154)
		(end 391.872216 -240.927636)
		(width 0.0889)
		(layer "In2.Cu")
		(net "M_I_CPU0_SA_DQ<27>")
	)
	(segment
		(start 404.458932 -234.050078)
		(end 404.458932 -233.821478)
		(width 0.14478)
		(layer "In2.Cu")
		(net "M_I_CPU0_SA_DQ<27>")
	)
	(segment
		(start 398.789144 -239.47755)
		(end 403.338792 -234.927902)
		(width 0.14478)
		(layer "In2.Cu")
		(net "M_I_CPU0_SA_DQ<27>")
	)
	(segment
		(start 404.734776 -234.927902)
		(end 404.921466 -234.741212)
		(width 0.14478)
		(layer "In2.Cu")
		(net "M_I_CPU0_SA_DQ<27>")
	)
	(segment
		(start 404.921466 -234.741212)
		(end 404.921466 -234.512612)
		(width 0.14478)
		(layer "In2.Cu")
		(net "M_I_CPU0_SA_DQ<27>")
	)
	(segment
		(start 394.305536 -239.71885)
		(end 394.493496 -239.53089)
		(width 0.0889)
		(layer "In2.Cu")
		(net "M_I_CPU0_SA_DQ<27>")
	)
	(segment
		(start 376.447812 -240.92154)
		(end 376.456194 -240.916714)
		(width 0.0889)
		(layer "In2.Cu")
		(net "M_I_CPU0_SA_DQ<27>")
	)
	(segment
		(start 404.620476 -233.659934)
		(end 404.849076 -233.659934)
		(width 0.14478)
		(layer "In2.Cu")
		(net "M_I_CPU0_SA_DQ<27>")
	)
	(segment
		(start 375.694702 -241.24412)
		(end 375.84888 -240.97869)
		(width 0.0889)
		(layer "In2.Cu")
		(net "M_I_CPU0_SA_DQ<27>")
	)
	(segment
		(start 405.701754 -233.960924)
		(end 405.701754 -233.732324)
		(width 0.14478)
		(layer "In2.Cu")
		(net "M_I_CPU0_SA_DQ<27>")
	)
	(segment
		(start 378.693426 -240.916714)
		(end 378.701808 -240.92154)
		(width 0.0889)
		(layer "In2.Cu")
		(net "M_I_CPU0_SA_DQ<27>")
	)
	(segment
		(start 394.305536 -240.010442)
		(end 394.305536 -239.71885)
		(width 0.0889)
		(layer "In2.Cu")
		(net "M_I_CPU0_SA_DQ<27>")
	)
	(segment
		(start 385.847844 -240.92154)
		(end 385.856226 -240.916714)
		(width 0.0889)
		(layer "In2.Cu")
		(net "M_I_CPU0_SA_DQ<27>")
	)
	(segment
		(start 405.701754 -233.732324)
		(end 405.23922 -233.26979)
		(width 0.14478)
		(layer "In2.Cu")
		(net "M_I_CPU0_SA_DQ<27>")
	)
	(segment
		(start 393.352782 -240.930176)
		(end 393.367514 -240.92154)
		(width 0.0889)
		(layer "In2.Cu")
		(net "M_I_CPU0_SA_DQ<27>")
	)
	(segment
		(start 422.31564 -227.500434)
		(end 427.021498 -227.500434)
		(width 0.14478)
		(layer "In2.Cu")
		(net "M_I_CPU0_SA_DQ<27>")
	)
	(segment
		(start 419.020752 -228.350318)
		(end 421.465756 -228.350318)
		(width 0.14478)
		(layer "In2.Cu")
		(net "M_I_CPU0_SA_DQ<27>")
	)
	(segment
		(start 394.493496 -239.53089)
		(end 395.466316 -239.53089)
		(width 0.0889)
		(layer "In2.Cu")
		(net "M_I_CPU0_SA_DQ<27>")
	)
	(segment
		(start 389.607806 -240.92154)
		(end 389.616188 -240.916714)
		(width 0.0889)
		(layer "In2.Cu")
		(net "M_I_CPU0_SA_DQ<27>")
	)
	(segment
		(start 427.021498 -227.500434)
		(end 427.456092 -227.935028)
		(width 0.14478)
		(layer "In2.Cu")
		(net "M_I_CPU0_SA_DQ<27>")
	)
	(segment
		(start 391.85342 -240.916714)
		(end 391.861802 -240.92154)
		(width 0.0889)
		(layer "In2.Cu")
		(net "M_I_CPU0_SA_DQ<27>")
	)
	(segment
		(start 405.23922 -233.26979)
		(end 405.23922 -233.04119)
		(width 0.14478)
		(layer "In2.Cu")
		(net "M_I_CPU0_SA_DQ<27>")
	)
	(segment
		(start 384.90779 -240.92154)
		(end 384.916172 -240.916714)
		(width 0.0889)
		(layer "In2.Cu")
		(net "M_I_CPU0_SA_DQ<27>")
	)
	(segment
		(start 406.320498 -233.34218)
		(end 408.931618 -230.73106)
		(width 0.14478)
		(layer "In2.Cu")
		(net "M_I_CPU0_SA_DQ<27>")
	)
	(arc
		(start 383.027682 -240.92154)
		(mid 383.209933 -240.87119)
		(end 383.393442 -240.916714)
		(width 0.0889)
		(layer "In2.Cu")
		(net "M_I_CPU0_SA_DQ<27>")
	)
	(arc
		(start 383.401824 -240.92154)
		(mid 383.68478 -240.997717)
		(end 383.967736 -240.92154)
		(width 0.0889)
		(layer "In2.Cu")
		(net "M_I_CPU0_SA_DQ<27>")
	)
	(arc
		(start 379.641862 -240.92154)
		(mid 379.924818 -240.997717)
		(end 380.207774 -240.92154)
		(width 0.0889)
		(layer "In2.Cu")
		(net "M_I_CPU0_SA_DQ<27>")
	)
	(arc
		(start 380.581916 -240.92154)
		(mid 380.864872 -240.997717)
		(end 381.147828 -240.92154)
		(width 0.0889)
		(layer "In2.Cu")
		(net "M_I_CPU0_SA_DQ<27>")
	)
	(arc
		(start 384.916172 -240.916714)
		(mid 385.09968 -240.87122)
		(end 385.281932 -240.92154)
		(width 0.0889)
		(layer "In2.Cu")
		(net "M_I_CPU0_SA_DQ<27>")
	)
	(arc
		(start 387.727698 -240.92154)
		(mid 387.909949 -240.87119)
		(end 388.093458 -240.916714)
		(width 0.0889)
		(layer "In2.Cu")
		(net "M_I_CPU0_SA_DQ<27>")
	)
	(arc
		(start 378.701808 -240.92154)
		(mid 378.984764 -240.997717)
		(end 379.26772 -240.92154)
		(width 0.0889)
		(layer "In2.Cu")
		(net "M_I_CPU0_SA_DQ<27>")
	)
	(arc
		(start 377.387866 -240.92154)
		(mid 377.57481 -240.871285)
		(end 377.761754 -240.92154)
		(width 0.0889)
		(layer "In2.Cu")
		(net "M_I_CPU0_SA_DQ<27>")
	)
	(arc
		(start 381.15621 -240.916714)
		(mid 381.339718 -240.87122)
		(end 381.52197 -240.92154)
		(width 0.0889)
		(layer "In2.Cu")
		(net "M_I_CPU0_SA_DQ<27>")
	)
	(arc
		(start 376.456194 -240.916714)
		(mid 376.639702 -240.87122)
		(end 376.821954 -240.92154)
		(width 0.0889)
		(layer "In2.Cu")
		(net "M_I_CPU0_SA_DQ<27>")
	)
	(arc
		(start 385.281932 -240.92154)
		(mid 385.564888 -240.997717)
		(end 385.847844 -240.92154)
		(width 0.0889)
		(layer "In2.Cu")
		(net "M_I_CPU0_SA_DQ<27>")
	)
	(arc
		(start 377.761754 -240.92154)
		(mid 378.04471 -240.997717)
		(end 378.327666 -240.92154)
		(width 0.0889)
		(layer "In2.Cu")
		(net "M_I_CPU0_SA_DQ<27>")
	)
	(arc
		(start 392.801602 -240.92154)
		(mid 393.076054 -240.997776)
		(end 393.352782 -240.930176)
		(width 0.0889)
		(layer "In2.Cu")
		(net "M_I_CPU0_SA_DQ<27>")
	)
	(arc
		(start 388.667752 -240.92154)
		(mid 388.850003 -240.87119)
		(end 389.033512 -240.916714)
		(width 0.0889)
		(layer "In2.Cu")
		(net "M_I_CPU0_SA_DQ<27>")
	)
	(arc
		(start 379.26772 -240.92154)
		(mid 379.449971 -240.87119)
		(end 379.63348 -240.916714)
		(width 0.0889)
		(layer "In2.Cu")
		(net "M_I_CPU0_SA_DQ<27>")
	)
	(arc
		(start 375.945146 -240.95329)
		(mid 376.200211 -240.996641)
		(end 376.447812 -240.92154)
		(width 0.0889)
		(layer "In2.Cu")
		(net "M_I_CPU0_SA_DQ<27>")
	)
	(arc
		(start 383.967736 -240.92154)
		(mid 384.149987 -240.87119)
		(end 384.333496 -240.916714)
		(width 0.0889)
		(layer "In2.Cu")
		(net "M_I_CPU0_SA_DQ<27>")
	)
	(arc
		(start 385.856226 -240.916714)
		(mid 386.039734 -240.87122)
		(end 386.221986 -240.92154)
		(width 0.0889)
		(layer "In2.Cu")
		(net "M_I_CPU0_SA_DQ<27>")
	)
	(arc
		(start 382.087882 -240.92154)
		(mid 382.274826 -240.871285)
		(end 382.46177 -240.92154)
		(width 0.0889)
		(layer "In2.Cu")
		(net "M_I_CPU0_SA_DQ<27>")
	)
	(arc
		(start 380.216156 -240.916714)
		(mid 380.399664 -240.87122)
		(end 380.581916 -240.92154)
		(width 0.0889)
		(layer "In2.Cu")
		(net "M_I_CPU0_SA_DQ<27>")
	)
	(arc
		(start 381.52197 -240.92154)
		(mid 381.804926 -240.997717)
		(end 382.087882 -240.92154)
		(width 0.0889)
		(layer "In2.Cu")
		(net "M_I_CPU0_SA_DQ<27>")
	)
	(arc
		(start 382.46177 -240.92154)
		(mid 382.744726 -240.997717)
		(end 383.027682 -240.92154)
		(width 0.0889)
		(layer "In2.Cu")
		(net "M_I_CPU0_SA_DQ<27>")
	)
	(arc
		(start 389.041894 -240.92154)
		(mid 389.32485 -240.997717)
		(end 389.607806 -240.92154)
		(width 0.0889)
		(layer "In2.Cu")
		(net "M_I_CPU0_SA_DQ<27>")
	)
	(arc
		(start 389.981948 -240.92154)
		(mid 390.264904 -240.997717)
		(end 390.54786 -240.92154)
		(width 0.0889)
		(layer "In2.Cu")
		(net "M_I_CPU0_SA_DQ<27>")
	)
	(arc
		(start 386.787898 -240.92154)
		(mid 386.974842 -240.871285)
		(end 387.161786 -240.92154)
		(width 0.0889)
		(layer "In2.Cu")
		(net "M_I_CPU0_SA_DQ<27>")
	)
	(arc
		(start 393.367514 -240.92154)
		(mid 393.428324 -240.880865)
		(end 393.483338 -240.83264)
		(width 0.0889)
		(layer "In2.Cu")
		(net "M_I_CPU0_SA_DQ<27>")
	)
	(arc
		(start 384.341878 -240.92154)
		(mid 384.624834 -240.997717)
		(end 384.90779 -240.92154)
		(width 0.0889)
		(layer "In2.Cu")
		(net "M_I_CPU0_SA_DQ<27>")
	)
	(arc
		(start 389.616188 -240.916714)
		(mid 389.799696 -240.87122)
		(end 389.981948 -240.92154)
		(width 0.0889)
		(layer "In2.Cu")
		(net "M_I_CPU0_SA_DQ<27>")
	)
	(arc
		(start 390.54786 -240.92154)
		(mid 390.734804 -240.871285)
		(end 390.921748 -240.92154)
		(width 0.0889)
		(layer "In2.Cu")
		(net "M_I_CPU0_SA_DQ<27>")
	)
	(arc
		(start 391.872216 -240.927636)
		(mid 392.150648 -240.997734)
		(end 392.42746 -240.92154)
		(width 0.0889)
		(layer "In2.Cu")
		(net "M_I_CPU0_SA_DQ<27>")
	)
	(arc
		(start 391.48766 -240.92154)
		(mid 391.669911 -240.87119)
		(end 391.85342 -240.916714)
		(width 0.0889)
		(layer "In2.Cu")
		(net "M_I_CPU0_SA_DQ<27>")
	)
	(arc
		(start 387.161786 -240.92154)
		(mid 387.444742 -240.997717)
		(end 387.727698 -240.92154)
		(width 0.0889)
		(layer "In2.Cu")
		(net "M_I_CPU0_SA_DQ<27>")
	)
	(arc
		(start 388.10184 -240.92154)
		(mid 388.384796 -240.997717)
		(end 388.667752 -240.92154)
		(width 0.0889)
		(layer "In2.Cu")
		(net "M_I_CPU0_SA_DQ<27>")
	)
	(arc
		(start 386.221986 -240.92154)
		(mid 386.504942 -240.997717)
		(end 386.787898 -240.92154)
		(width 0.0889)
		(layer "In2.Cu")
		(net "M_I_CPU0_SA_DQ<27>")
	)
	(arc
		(start 390.921748 -240.92154)
		(mid 391.204704 -240.997717)
		(end 391.48766 -240.92154)
		(width 0.0889)
		(layer "In2.Cu")
		(net "M_I_CPU0_SA_DQ<27>")
	)
	(arc
		(start 378.327666 -240.92154)
		(mid 378.509917 -240.87119)
		(end 378.693426 -240.916714)
		(width 0.0889)
		(layer "In2.Cu")
		(net "M_I_CPU0_SA_DQ<27>")
	)
	(arc
		(start 392.435842 -240.916714)
		(mid 392.61935 -240.87122)
		(end 392.801602 -240.92154)
		(width 0.0889)
		(layer "In2.Cu")
		(net "M_I_CPU0_SA_DQ<27>")
	)
	(arc
		(start 376.821954 -240.92154)
		(mid 377.10491 -240.997717)
		(end 377.387866 -240.92154)
		(width 0.0889)
		(layer "In2.Cu")
		(net "M_I_CPU0_SA_DQ<27>")
	)
	(segment
		(start 376.638058 -240.700052)
		(end 377.10491 -240.434114)
		(width 0.10668)
		(layer "F.Cu")
		(net "M_I_CPU0_SA_DQ<26>")
	)
	(segment
		(start 405.956516 -231.259634)
		(end 405.956516 -231.031034)
		(width 0.14478)
		(layer "In2.Cu")
		(net "M_I_CPU0_SA_DQ<26>")
	)
	(segment
		(start 407.188924 -231.160066)
		(end 407.188924 -230.931466)
		(width 0.14478)
		(layer "In2.Cu")
		(net "M_I_CPU0_SA_DQ<26>")
	)
	(segment
		(start 406.898348 -230.089202)
		(end 407.126948 -230.089202)
		(width 0.14478)
		(layer "In2.Cu")
		(net "M_I_CPU0_SA_DQ<26>")
	)
	(segment
		(start 405.566372 -231.649778)
		(end 405.89708 -231.980486)
		(width 0.14478)
		(layer "In2.Cu")
		(net "M_I_CPU0_SA_DQ<26>")
	)
	(segment
		(start 408.10561 -229.507288)
		(end 408.310842 -229.507288)
		(width 0.14478)
		(layer "In2.Cu")
		(net "M_I_CPU0_SA_DQ<26>")
	)
	(segment
		(start 407.02738 -231.32161)
		(end 407.188924 -231.160066)
		(width 0.14478)
		(layer "In2.Cu")
		(net "M_I_CPU0_SA_DQ<26>")
	)
	(segment
		(start 422.414446 -225.810064)
		(end 427.03115 -225.810064)
		(width 0.14478)
		(layer "In2.Cu")
		(net "M_I_CPU0_SA_DQ<26>")
	)
	(segment
		(start 405.337772 -231.649778)
		(end 405.566372 -231.649778)
		(width 0.14478)
		(layer "In2.Cu")
		(net "M_I_CPU0_SA_DQ<26>")
	)
	(segment
		(start 381.983488 -240.106708)
		(end 381.99187 -240.111534)
		(width 0.0889)
		(layer "In2.Cu")
		(net "M_I_CPU0_SA_DQ<26>")
	)
	(segment
		(start 411.157928 -226.660202)
		(end 413.631634 -226.660202)
		(width 0.14478)
		(layer "In2.Cu")
		(net "M_I_CPU0_SA_DQ<26>")
	)
	(segment
		(start 427.03115 -225.810064)
		(end 427.456092 -226.235006)
		(width 0.14478)
		(layer "In2.Cu")
		(net "M_I_CPU0_SA_DQ<26>")
	)
	(segment
		(start 407.907236 -229.308914)
		(end 408.10561 -229.507288)
		(width 0.14478)
		(layer "In2.Cu")
		(net "M_I_CPU0_SA_DQ<26>")
	)
	(segment
		(start 391.01776 -240.111534)
		(end 391.026142 -240.106708)
		(width 0.0889)
		(layer "In2.Cu")
		(net "M_I_CPU0_SA_DQ<26>")
	)
	(segment
		(start 405.956516 -231.031034)
		(end 406.11806 -230.86949)
		(width 0.14478)
		(layer "In2.Cu")
		(net "M_I_CPU0_SA_DQ<26>")
	)
	(segment
		(start 377.857766 -240.111534)
		(end 377.866148 -240.106708)
		(width 0.0889)
		(layer "In2.Cu")
		(net "M_I_CPU0_SA_DQ<26>")
	)
	(segment
		(start 405.89708 -231.980486)
		(end 406.12568 -231.980486)
		(width 0.14478)
		(layer "In2.Cu")
		(net "M_I_CPU0_SA_DQ<26>")
	)
	(segment
		(start 391.947146 -240.11763)
		(end 391.95756 -240.111534)
		(width 0.0889)
		(layer "In2.Cu")
		(net "M_I_CPU0_SA_DQ<26>")
	)
	(segment
		(start 395.562836 -238.55299)
		(end 395.859254 -238.55299)
		(width 0.0889)
		(layer "In2.Cu")
		(net "M_I_CPU0_SA_DQ<26>")
	)
	(segment
		(start 390.443466 -240.106708)
		(end 390.451848 -240.111534)
		(width 0.0889)
		(layer "In2.Cu")
		(net "M_I_CPU0_SA_DQ<26>")
	)
	(segment
		(start 393.084812 -240.060988)
		(end 393.508738 -240.060988)
		(width 0.0889)
		(layer "In2.Cu")
		(net "M_I_CPU0_SA_DQ<26>")
	)
	(segment
		(start 406.736804 -230.250746)
		(end 406.898348 -230.089202)
		(width 0.14478)
		(layer "In2.Cu")
		(net "M_I_CPU0_SA_DQ<26>")
	)
	(segment
		(start 406.79878 -231.32161)
		(end 407.02738 -231.32161)
		(width 0.14478)
		(layer "In2.Cu")
		(net "M_I_CPU0_SA_DQ<26>")
	)
	(segment
		(start 421.564308 -226.660202)
		(end 422.414446 -225.810064)
		(width 0.14478)
		(layer "In2.Cu")
		(net "M_I_CPU0_SA_DQ<26>")
	)
	(segment
		(start 407.188924 -230.931466)
		(end 406.736804 -230.479346)
		(width 0.14478)
		(layer "In2.Cu")
		(net "M_I_CPU0_SA_DQ<26>")
	)
	(segment
		(start 393.751816 -239.50803)
		(end 394.285216 -238.97463)
		(width 0.0889)
		(layer "In2.Cu")
		(net "M_I_CPU0_SA_DQ<26>")
	)
	(segment
		(start 413.631634 -226.660202)
		(end 414.481772 -225.810064)
		(width 0.14478)
		(layer "In2.Cu")
		(net "M_I_CPU0_SA_DQ<26>")
	)
	(segment
		(start 385.74345 -240.106708)
		(end 385.751832 -240.111534)
		(width 0.0889)
		(layer "In2.Cu")
		(net "M_I_CPU0_SA_DQ<26>")
	)
	(segment
		(start 388.197852 -240.111534)
		(end 388.206234 -240.106708)
		(width 0.0889)
		(layer "In2.Cu")
		(net "M_I_CPU0_SA_DQ<26>")
	)
	(segment
		(start 406.736804 -230.479346)
		(end 406.736804 -230.250746)
		(width 0.14478)
		(layer "In2.Cu")
		(net "M_I_CPU0_SA_DQ<26>")
	)
	(segment
		(start 407.969212 -230.379778)
		(end 407.969212 -230.151178)
		(width 0.14478)
		(layer "In2.Cu")
		(net "M_I_CPU0_SA_DQ<26>")
	)
	(segment
		(start 406.12568 -231.980486)
		(end 406.287224 -231.818942)
		(width 0.14478)
		(layer "In2.Cu")
		(net "M_I_CPU0_SA_DQ<26>")
	)
	(segment
		(start 406.11806 -230.86949)
		(end 406.34666 -230.86949)
		(width 0.14478)
		(layer "In2.Cu")
		(net "M_I_CPU0_SA_DQ<26>")
	)
	(segment
		(start 398.43456 -238.55299)
		(end 405.337772 -231.649778)
		(width 0.14478)
		(layer "In2.Cu")
		(net "M_I_CPU0_SA_DQ<26>")
	)
	(segment
		(start 387.257798 -240.111534)
		(end 387.26618 -240.106708)
		(width 0.0889)
		(layer "In2.Cu")
		(net "M_I_CPU0_SA_DQ<26>")
	)
	(segment
		(start 407.126948 -230.089202)
		(end 407.579068 -230.541322)
		(width 0.14478)
		(layer "In2.Cu")
		(net "M_I_CPU0_SA_DQ<26>")
	)
	(segment
		(start 392.331448 -240.111534)
		(end 392.341862 -240.11763)
		(width 0.0889)
		(layer "In2.Cu")
		(net "M_I_CPU0_SA_DQ<26>")
	)
	(segment
		(start 408.310842 -229.507288)
		(end 411.157928 -226.660202)
		(width 0.14478)
		(layer "In2.Cu")
		(net "M_I_CPU0_SA_DQ<26>")
	)
	(segment
		(start 386.683504 -240.106708)
		(end 386.691886 -240.111534)
		(width 0.0889)
		(layer "In2.Cu")
		(net "M_I_CPU0_SA_DQ<26>")
	)
	(segment
		(start 418.845238 -226.660202)
		(end 421.564308 -226.660202)
		(width 0.14478)
		(layer "In2.Cu")
		(net "M_I_CPU0_SA_DQ<26>")
	)
	(segment
		(start 407.579068 -230.541322)
		(end 407.807668 -230.541322)
		(width 0.14478)
		(layer "In2.Cu")
		(net "M_I_CPU0_SA_DQ<26>")
	)
	(segment
		(start 377.258834 -240.168684)
		(end 377.354846 -240.143284)
		(width 0.0889)
		(layer "In2.Cu")
		(net "M_I_CPU0_SA_DQ<26>")
	)
	(segment
		(start 414.481772 -225.810064)
		(end 417.9951 -225.810064)
		(width 0.14478)
		(layer "In2.Cu")
		(net "M_I_CPU0_SA_DQ<26>")
	)
	(segment
		(start 407.807668 -230.541322)
		(end 407.969212 -230.379778)
		(width 0.14478)
		(layer "In2.Cu")
		(net "M_I_CPU0_SA_DQ<26>")
	)
	(segment
		(start 395.859254 -238.55299)
		(end 398.43456 -238.55299)
		(width 0.14478)
		(layer "In2.Cu")
		(net "M_I_CPU0_SA_DQ<26>")
	)
	(segment
		(start 407.517092 -229.470458)
		(end 407.678636 -229.308914)
		(width 0.14478)
		(layer "In2.Cu")
		(net "M_I_CPU0_SA_DQ<26>")
	)
	(segment
		(start 395.141196 -238.97463)
		(end 395.562836 -238.55299)
		(width 0.0889)
		(layer "In2.Cu")
		(net "M_I_CPU0_SA_DQ<26>")
	)
	(segment
		(start 417.9951 -225.810064)
		(end 418.845238 -226.660202)
		(width 0.14478)
		(layer "In2.Cu")
		(net "M_I_CPU0_SA_DQ<26>")
	)
	(segment
		(start 383.497836 -240.111534)
		(end 383.506218 -240.106708)
		(width 0.0889)
		(layer "In2.Cu")
		(net "M_I_CPU0_SA_DQ<26>")
	)
	(segment
		(start 406.287224 -231.590342)
		(end 405.956516 -231.259634)
		(width 0.14478)
		(layer "In2.Cu")
		(net "M_I_CPU0_SA_DQ<26>")
	)
	(segment
		(start 381.043434 -240.106708)
		(end 381.051816 -240.111534)
		(width 0.0889)
		(layer "In2.Cu")
		(net "M_I_CPU0_SA_DQ<26>")
	)
	(segment
		(start 378.79782 -240.111534)
		(end 378.806202 -240.106708)
		(width 0.0889)
		(layer "In2.Cu")
		(net "M_I_CPU0_SA_DQ<26>")
	)
	(segment
		(start 406.34666 -230.86949)
		(end 406.79878 -231.32161)
		(width 0.14478)
		(layer "In2.Cu")
		(net "M_I_CPU0_SA_DQ<26>")
	)
	(segment
		(start 406.287224 -231.818942)
		(end 406.287224 -231.590342)
		(width 0.14478)
		(layer "In2.Cu")
		(net "M_I_CPU0_SA_DQ<26>")
	)
	(segment
		(start 407.517092 -229.699058)
		(end 407.517092 -229.470458)
		(width 0.14478)
		(layer "In2.Cu")
		(net "M_I_CPU0_SA_DQ<26>")
	)
	(segment
		(start 407.678636 -229.308914)
		(end 407.907236 -229.308914)
		(width 0.14478)
		(layer "In2.Cu")
		(net "M_I_CPU0_SA_DQ<26>")
	)
	(segment
		(start 377.10491 -240.434114)
		(end 377.258834 -240.168684)
		(width 0.0889)
		(layer "In2.Cu")
		(net "M_I_CPU0_SA_DQ<26>")
	)
	(segment
		(start 407.969212 -230.151178)
		(end 407.517092 -229.699058)
		(width 0.14478)
		(layer "In2.Cu")
		(net "M_I_CPU0_SA_DQ<26>")
	)
	(segment
		(start 382.557782 -240.111534)
		(end 382.566164 -240.106708)
		(width 0.0889)
		(layer "In2.Cu")
		(net "M_I_CPU0_SA_DQ<26>")
	)
	(segment
		(start 393.508738 -240.060988)
		(end 393.751816 -239.81791)
		(width 0.0889)
		(layer "In2.Cu")
		(net "M_I_CPU0_SA_DQ<26>")
	)
	(segment
		(start 394.285216 -238.97463)
		(end 395.141196 -238.97463)
		(width 0.0889)
		(layer "In2.Cu")
		(net "M_I_CPU0_SA_DQ<26>")
	)
	(segment
		(start 393.751816 -239.81791)
		(end 393.751816 -239.50803)
		(width 0.0889)
		(layer "In2.Cu")
		(net "M_I_CPU0_SA_DQ<26>")
	)
	(arc
		(start 381.99187 -240.111534)
		(mid 382.274826 -240.187711)
		(end 382.557782 -240.111534)
		(width 0.0889)
		(layer "In2.Cu")
		(net "M_I_CPU0_SA_DQ<26>")
	)
	(arc
		(start 386.691886 -240.111534)
		(mid 386.974842 -240.187711)
		(end 387.257798 -240.111534)
		(width 0.0889)
		(layer "In2.Cu")
		(net "M_I_CPU0_SA_DQ<26>")
	)
	(arc
		(start 388.571994 -240.111534)
		(mid 388.85495 -240.187711)
		(end 389.137906 -240.111534)
		(width 0.0889)
		(layer "In2.Cu")
		(net "M_I_CPU0_SA_DQ<26>")
	)
	(arc
		(start 391.391902 -240.111534)
		(mid 391.668715 -240.187677)
		(end 391.947146 -240.11763)
		(width 0.0889)
		(layer "In2.Cu")
		(net "M_I_CPU0_SA_DQ<26>")
	)
	(arc
		(start 385.751832 -240.111534)
		(mid 386.034788 -240.187711)
		(end 386.317744 -240.111534)
		(width 0.0889)
		(layer "In2.Cu")
		(net "M_I_CPU0_SA_DQ<26>")
	)
	(arc
		(start 391.95756 -240.111534)
		(mid 392.144504 -240.061279)
		(end 392.331448 -240.111534)
		(width 0.0889)
		(layer "In2.Cu")
		(net "M_I_CPU0_SA_DQ<26>")
	)
	(arc
		(start 392.341862 -240.11763)
		(mid 392.620548 -240.18785)
		(end 392.897614 -240.111534)
		(width 0.0889)
		(layer "In2.Cu")
		(net "M_I_CPU0_SA_DQ<26>")
	)
	(arc
		(start 390.451848 -240.111534)
		(mid 390.734804 -240.187711)
		(end 391.01776 -240.111534)
		(width 0.0889)
		(layer "In2.Cu")
		(net "M_I_CPU0_SA_DQ<26>")
	)
	(arc
		(start 385.37769 -240.111534)
		(mid 385.559941 -240.061184)
		(end 385.74345 -240.106708)
		(width 0.0889)
		(layer "In2.Cu")
		(net "M_I_CPU0_SA_DQ<26>")
	)
	(arc
		(start 379.171962 -240.111534)
		(mid 379.454918 -240.187711)
		(end 379.737874 -240.111534)
		(width 0.0889)
		(layer "In2.Cu")
		(net "M_I_CPU0_SA_DQ<26>")
	)
	(arc
		(start 378.806202 -240.106708)
		(mid 378.98971 -240.061214)
		(end 379.171962 -240.111534)
		(width 0.0889)
		(layer "In2.Cu")
		(net "M_I_CPU0_SA_DQ<26>")
	)
	(arc
		(start 392.897614 -240.111534)
		(mid 392.987874 -240.073906)
		(end 393.084812 -240.060988)
		(width 0.0889)
		(layer "In2.Cu")
		(net "M_I_CPU0_SA_DQ<26>")
	)
	(arc
		(start 384.43789 -240.111534)
		(mid 384.624834 -240.061279)
		(end 384.811778 -240.111534)
		(width 0.0889)
		(layer "In2.Cu")
		(net "M_I_CPU0_SA_DQ<26>")
	)
	(arc
		(start 387.26618 -240.106708)
		(mid 387.449688 -240.061214)
		(end 387.63194 -240.111534)
		(width 0.0889)
		(layer "In2.Cu")
		(net "M_I_CPU0_SA_DQ<26>")
	)
	(arc
		(start 382.566164 -240.106708)
		(mid 382.749672 -240.061214)
		(end 382.931924 -240.111534)
		(width 0.0889)
		(layer "In2.Cu")
		(net "M_I_CPU0_SA_DQ<26>")
	)
	(arc
		(start 383.871978 -240.111534)
		(mid 384.154934 -240.187711)
		(end 384.43789 -240.111534)
		(width 0.0889)
		(layer "In2.Cu")
		(net "M_I_CPU0_SA_DQ<26>")
	)
	(arc
		(start 387.63194 -240.111534)
		(mid 387.914896 -240.187711)
		(end 388.197852 -240.111534)
		(width 0.0889)
		(layer "In2.Cu")
		(net "M_I_CPU0_SA_DQ<26>")
	)
	(arc
		(start 381.051816 -240.111534)
		(mid 381.334772 -240.187711)
		(end 381.617728 -240.111534)
		(width 0.0889)
		(layer "In2.Cu")
		(net "M_I_CPU0_SA_DQ<26>")
	)
	(arc
		(start 380.677674 -240.111534)
		(mid 380.859925 -240.061184)
		(end 381.043434 -240.106708)
		(width 0.0889)
		(layer "In2.Cu")
		(net "M_I_CPU0_SA_DQ<26>")
	)
	(arc
		(start 390.077706 -240.111534)
		(mid 390.259957 -240.061184)
		(end 390.443466 -240.106708)
		(width 0.0889)
		(layer "In2.Cu")
		(net "M_I_CPU0_SA_DQ<26>")
	)
	(arc
		(start 383.506218 -240.106708)
		(mid 383.689726 -240.061214)
		(end 383.871978 -240.111534)
		(width 0.0889)
		(layer "In2.Cu")
		(net "M_I_CPU0_SA_DQ<26>")
	)
	(arc
		(start 381.617728 -240.111534)
		(mid 381.799979 -240.061184)
		(end 381.983488 -240.106708)
		(width 0.0889)
		(layer "In2.Cu")
		(net "M_I_CPU0_SA_DQ<26>")
	)
	(arc
		(start 380.111762 -240.111534)
		(mid 380.394718 -240.187711)
		(end 380.677674 -240.111534)
		(width 0.0889)
		(layer "In2.Cu")
		(net "M_I_CPU0_SA_DQ<26>")
	)
	(arc
		(start 389.511794 -240.111534)
		(mid 389.79475 -240.187711)
		(end 390.077706 -240.111534)
		(width 0.0889)
		(layer "In2.Cu")
		(net "M_I_CPU0_SA_DQ<26>")
	)
	(arc
		(start 377.354846 -240.143284)
		(mid 377.610054 -240.186761)
		(end 377.857766 -240.111534)
		(width 0.0889)
		(layer "In2.Cu")
		(net "M_I_CPU0_SA_DQ<26>")
	)
	(arc
		(start 379.737874 -240.111534)
		(mid 379.924818 -240.061279)
		(end 380.111762 -240.111534)
		(width 0.0889)
		(layer "In2.Cu")
		(net "M_I_CPU0_SA_DQ<26>")
	)
	(arc
		(start 384.811778 -240.111534)
		(mid 385.094734 -240.187711)
		(end 385.37769 -240.111534)
		(width 0.0889)
		(layer "In2.Cu")
		(net "M_I_CPU0_SA_DQ<26>")
	)
	(arc
		(start 378.231908 -240.111534)
		(mid 378.514864 -240.187711)
		(end 378.79782 -240.111534)
		(width 0.0889)
		(layer "In2.Cu")
		(net "M_I_CPU0_SA_DQ<26>")
	)
	(arc
		(start 377.866148 -240.106708)
		(mid 378.049656 -240.061214)
		(end 378.231908 -240.111534)
		(width 0.0889)
		(layer "In2.Cu")
		(net "M_I_CPU0_SA_DQ<26>")
	)
	(arc
		(start 389.137906 -240.111534)
		(mid 389.32485 -240.061279)
		(end 389.511794 -240.111534)
		(width 0.0889)
		(layer "In2.Cu")
		(net "M_I_CPU0_SA_DQ<26>")
	)
	(arc
		(start 382.931924 -240.111534)
		(mid 383.21488 -240.187711)
		(end 383.497836 -240.111534)
		(width 0.0889)
		(layer "In2.Cu")
		(net "M_I_CPU0_SA_DQ<26>")
	)
	(arc
		(start 388.206234 -240.106708)
		(mid 388.389742 -240.061214)
		(end 388.571994 -240.111534)
		(width 0.0889)
		(layer "In2.Cu")
		(net "M_I_CPU0_SA_DQ<26>")
	)
	(arc
		(start 386.317744 -240.111534)
		(mid 386.499995 -240.061184)
		(end 386.683504 -240.106708)
		(width 0.0889)
		(layer "In2.Cu")
		(net "M_I_CPU0_SA_DQ<26>")
	)
	(arc
		(start 391.026142 -240.106708)
		(mid 391.20965 -240.061214)
		(end 391.391902 -240.111534)
		(width 0.0889)
		(layer "In2.Cu")
		(net "M_I_CPU0_SA_DQ<26>")
	)
	(segment
		(start 375.698004 -240.700052)
		(end 376.164856 -240.434114)
		(width 0.10668)
		(layer "F.Cu")
		(net "M_I_CPU0_SA_DQ<25>")
	)
	(segment
		(start 395.859254 -239.01019)
		(end 398.613376 -239.01019)
		(width 0.14478)
		(layer "In2.Cu")
		(net "M_I_CPU0_SA_DQ<25>")
	)
	(segment
		(start 393.259818 -240.763552)
		(end 393.271502 -240.756694)
		(width 0.0889)
		(layer "In2.Cu")
		(net "M_I_CPU0_SA_DQ<25>")
	)
	(segment
		(start 376.010678 -240.699544)
		(end 376.03303 -240.782856)
		(width 0.0889)
		(layer "In2.Cu")
		(net "M_I_CPU0_SA_DQ<25>")
	)
	(segment
		(start 378.79782 -240.756694)
		(end 378.806202 -240.76152)
		(width 0.0889)
		(layer "In2.Cu")
		(net "M_I_CPU0_SA_DQ<25>")
	)
	(segment
		(start 377.283472 -240.76152)
		(end 377.291854 -240.756694)
		(width 0.0889)
		(layer "In2.Cu")
		(net "M_I_CPU0_SA_DQ<25>")
	)
	(segment
		(start 392.331448 -240.756694)
		(end 392.341862 -240.750598)
		(width 0.0889)
		(layer "In2.Cu")
		(net "M_I_CPU0_SA_DQ<25>")
	)
	(segment
		(start 390.443466 -240.76152)
		(end 390.451848 -240.756694)
		(width 0.0889)
		(layer "In2.Cu")
		(net "M_I_CPU0_SA_DQ<25>")
	)
	(segment
		(start 391.01776 -240.756694)
		(end 391.026142 -240.76152)
		(width 0.0889)
		(layer "In2.Cu")
		(net "M_I_CPU0_SA_DQ<25>")
	)
	(segment
		(start 393.348718 -240.697766)
		(end 394.051536 -239.994948)
		(width 0.0889)
		(layer "In2.Cu")
		(net "M_I_CPU0_SA_DQ<25>")
	)
	(segment
		(start 382.557782 -240.756694)
		(end 382.566164 -240.76152)
		(width 0.0889)
		(layer "In2.Cu")
		(net "M_I_CPU0_SA_DQ<25>")
	)
	(segment
		(start 413.41929 -227.358194)
		(end 415.135314 -226.837748)
		(width 0.14478)
		(layer "In2.Cu")
		(net "M_I_CPU0_SA_DQ<25>")
	)
	(segment
		(start 408.431238 -230.054912)
		(end 410.976064 -227.510086)
		(width 0.14478)
		(layer "In2.Cu")
		(net "M_I_CPU0_SA_DQ<25>")
	)
	(segment
		(start 417.337748 -226.660202)
		(end 419.389814 -227.510086)
		(width 0.14478)
		(layer "In2.Cu")
		(net "M_I_CPU0_SA_DQ<25>")
	)
	(segment
		(start 381.043434 -240.76152)
		(end 381.051816 -240.756694)
		(width 0.0889)
		(layer "In2.Cu")
		(net "M_I_CPU0_SA_DQ<25>")
	)
	(segment
		(start 421.964866 -227.132896)
		(end 423.105834 -226.660202)
		(width 0.14478)
		(layer "In2.Cu")
		(net "M_I_CPU0_SA_DQ<25>")
	)
	(segment
		(start 381.983488 -240.76152)
		(end 381.99187 -240.756694)
		(width 0.0889)
		(layer "In2.Cu")
		(net "M_I_CPU0_SA_DQ<25>")
	)
	(segment
		(start 423.105834 -226.660202)
		(end 431.131218 -226.660202)
		(width 0.14478)
		(layer "In2.Cu")
		(net "M_I_CPU0_SA_DQ<25>")
	)
	(segment
		(start 394.051536 -239.57661)
		(end 394.330936 -239.29721)
		(width 0.0889)
		(layer "In2.Cu")
		(net "M_I_CPU0_SA_DQ<25>")
	)
	(segment
		(start 394.051536 -239.994948)
		(end 394.051536 -239.57661)
		(width 0.0889)
		(layer "In2.Cu")
		(net "M_I_CPU0_SA_DQ<25>")
	)
	(segment
		(start 415.135314 -226.837748)
		(end 416.027362 -226.660202)
		(width 0.14478)
		(layer "In2.Cu")
		(net "M_I_CPU0_SA_DQ<25>")
	)
	(segment
		(start 395.552676 -239.01019)
		(end 395.859254 -239.01019)
		(width 0.0889)
		(layer "In2.Cu")
		(net "M_I_CPU0_SA_DQ<25>")
	)
	(segment
		(start 385.74345 -240.76152)
		(end 385.751832 -240.756694)
		(width 0.0889)
		(layer "In2.Cu")
		(net "M_I_CPU0_SA_DQ<25>")
	)
	(segment
		(start 412.394908 -227.510086)
		(end 413.41929 -227.358194)
		(width 0.14478)
		(layer "In2.Cu")
		(net "M_I_CPU0_SA_DQ<25>")
	)
	(segment
		(start 377.857766 -240.756694)
		(end 377.866148 -240.76152)
		(width 0.0889)
		(layer "In2.Cu")
		(net "M_I_CPU0_SA_DQ<25>")
	)
	(segment
		(start 376.164856 -240.434114)
		(end 376.010678 -240.699544)
		(width 0.0889)
		(layer "In2.Cu")
		(net "M_I_CPU0_SA_DQ<25>")
	)
	(segment
		(start 406.596596 -232.430066)
		(end 408.431238 -230.595424)
		(width 0.14478)
		(layer "In2.Cu")
		(net "M_I_CPU0_SA_DQ<25>")
	)
	(segment
		(start 431.131218 -226.660202)
		(end 431.55616 -227.085144)
		(width 0.14478)
		(layer "In2.Cu")
		(net "M_I_CPU0_SA_DQ<25>")
	)
	(segment
		(start 387.257798 -240.756694)
		(end 387.26618 -240.76152)
		(width 0.0889)
		(layer "In2.Cu")
		(net "M_I_CPU0_SA_DQ<25>")
	)
	(segment
		(start 410.976064 -227.510086)
		(end 412.394908 -227.510086)
		(width 0.14478)
		(layer "In2.Cu")
		(net "M_I_CPU0_SA_DQ<25>")
	)
	(segment
		(start 395.265656 -239.29721)
		(end 395.552676 -239.01019)
		(width 0.0889)
		(layer "In2.Cu")
		(net "M_I_CPU0_SA_DQ<25>")
	)
	(segment
		(start 419.389814 -227.510086)
		(end 420.068502 -227.510086)
		(width 0.14478)
		(layer "In2.Cu")
		(net "M_I_CPU0_SA_DQ<25>")
	)
	(segment
		(start 383.497836 -240.756694)
		(end 383.506218 -240.76152)
		(width 0.0889)
		(layer "In2.Cu")
		(net "M_I_CPU0_SA_DQ<25>")
	)
	(segment
		(start 405.1935 -232.430066)
		(end 406.596596 -232.430066)
		(width 0.14478)
		(layer "In2.Cu")
		(net "M_I_CPU0_SA_DQ<25>")
	)
	(segment
		(start 394.330936 -239.29721)
		(end 395.265656 -239.29721)
		(width 0.0889)
		(layer "In2.Cu")
		(net "M_I_CPU0_SA_DQ<25>")
	)
	(segment
		(start 408.431238 -230.595424)
		(end 408.431238 -230.054912)
		(width 0.14478)
		(layer "In2.Cu")
		(net "M_I_CPU0_SA_DQ<25>")
	)
	(segment
		(start 393.348464 -240.697766)
		(end 393.348718 -240.697766)
		(width 0.0889)
		(layer "In2.Cu")
		(net "M_I_CPU0_SA_DQ<25>")
	)
	(segment
		(start 416.027362 -226.660202)
		(end 417.337748 -226.660202)
		(width 0.14478)
		(layer "In2.Cu")
		(net "M_I_CPU0_SA_DQ<25>")
	)
	(segment
		(start 420.068502 -227.510086)
		(end 421.964866 -227.132896)
		(width 0.14478)
		(layer "In2.Cu")
		(net "M_I_CPU0_SA_DQ<25>")
	)
	(segment
		(start 391.947146 -240.750598)
		(end 391.95756 -240.756694)
		(width 0.0889)
		(layer "In2.Cu")
		(net "M_I_CPU0_SA_DQ<25>")
	)
	(segment
		(start 388.197852 -240.756694)
		(end 388.206234 -240.76152)
		(width 0.0889)
		(layer "In2.Cu")
		(net "M_I_CPU0_SA_DQ<25>")
	)
	(segment
		(start 386.683504 -240.76152)
		(end 386.691886 -240.756694)
		(width 0.0889)
		(layer "In2.Cu")
		(net "M_I_CPU0_SA_DQ<25>")
	)
	(segment
		(start 376.343418 -240.76152)
		(end 376.3518 -240.756694)
		(width 0.0889)
		(layer "In2.Cu")
		(net "M_I_CPU0_SA_DQ<25>")
	)
	(segment
		(start 398.613376 -239.01019)
		(end 405.1935 -232.430066)
		(width 0.14478)
		(layer "In2.Cu")
		(net "M_I_CPU0_SA_DQ<25>")
	)
	(arc
		(start 391.95756 -240.756694)
		(mid 392.144504 -240.806949)
		(end 392.331448 -240.756694)
		(width 0.0889)
		(layer "In2.Cu")
		(net "M_I_CPU0_SA_DQ<25>")
	)
	(arc
		(start 383.506218 -240.76152)
		(mid 383.689726 -240.807014)
		(end 383.871978 -240.756694)
		(width 0.0889)
		(layer "In2.Cu")
		(net "M_I_CPU0_SA_DQ<25>")
	)
	(arc
		(start 390.451848 -240.756694)
		(mid 390.734804 -240.680517)
		(end 391.01776 -240.756694)
		(width 0.0889)
		(layer "In2.Cu")
		(net "M_I_CPU0_SA_DQ<25>")
	)
	(arc
		(start 385.37769 -240.756694)
		(mid 385.559941 -240.807044)
		(end 385.74345 -240.76152)
		(width 0.0889)
		(layer "In2.Cu")
		(net "M_I_CPU0_SA_DQ<25>")
	)
	(arc
		(start 391.026142 -240.76152)
		(mid 391.20965 -240.807014)
		(end 391.391902 -240.756694)
		(width 0.0889)
		(layer "In2.Cu")
		(net "M_I_CPU0_SA_DQ<25>")
	)
	(arc
		(start 376.03303 -240.782856)
		(mid 376.19054 -240.806054)
		(end 376.343418 -240.76152)
		(width 0.0889)
		(layer "In2.Cu")
		(net "M_I_CPU0_SA_DQ<25>")
	)
	(arc
		(start 384.811778 -240.756694)
		(mid 385.094734 -240.680517)
		(end 385.37769 -240.756694)
		(width 0.0889)
		(layer "In2.Cu")
		(net "M_I_CPU0_SA_DQ<25>")
	)
	(arc
		(start 379.171962 -240.756694)
		(mid 379.454918 -240.680517)
		(end 379.737874 -240.756694)
		(width 0.0889)
		(layer "In2.Cu")
		(net "M_I_CPU0_SA_DQ<25>")
	)
	(arc
		(start 377.866148 -240.76152)
		(mid 378.049656 -240.807014)
		(end 378.231908 -240.756694)
		(width 0.0889)
		(layer "In2.Cu")
		(net "M_I_CPU0_SA_DQ<25>")
	)
	(arc
		(start 390.077706 -240.756694)
		(mid 390.259957 -240.807044)
		(end 390.443466 -240.76152)
		(width 0.0889)
		(layer "In2.Cu")
		(net "M_I_CPU0_SA_DQ<25>")
	)
	(arc
		(start 389.511794 -240.756694)
		(mid 389.79475 -240.680517)
		(end 390.077706 -240.756694)
		(width 0.0889)
		(layer "In2.Cu")
		(net "M_I_CPU0_SA_DQ<25>")
	)
	(arc
		(start 378.231908 -240.756694)
		(mid 378.514864 -240.680517)
		(end 378.79782 -240.756694)
		(width 0.0889)
		(layer "In2.Cu")
		(net "M_I_CPU0_SA_DQ<25>")
	)
	(arc
		(start 384.43789 -240.756694)
		(mid 384.624834 -240.806949)
		(end 384.811778 -240.756694)
		(width 0.0889)
		(layer "In2.Cu")
		(net "M_I_CPU0_SA_DQ<25>")
	)
	(arc
		(start 388.206234 -240.76152)
		(mid 388.389742 -240.807014)
		(end 388.571994 -240.756694)
		(width 0.0889)
		(layer "In2.Cu")
		(net "M_I_CPU0_SA_DQ<25>")
	)
	(arc
		(start 387.63194 -240.756694)
		(mid 387.914896 -240.680517)
		(end 388.197852 -240.756694)
		(width 0.0889)
		(layer "In2.Cu")
		(net "M_I_CPU0_SA_DQ<25>")
	)
	(arc
		(start 381.99187 -240.756694)
		(mid 382.274826 -240.680517)
		(end 382.557782 -240.756694)
		(width 0.0889)
		(layer "In2.Cu")
		(net "M_I_CPU0_SA_DQ<25>")
	)
	(arc
		(start 377.291854 -240.756694)
		(mid 377.57481 -240.680517)
		(end 377.857766 -240.756694)
		(width 0.0889)
		(layer "In2.Cu")
		(net "M_I_CPU0_SA_DQ<25>")
	)
	(arc
		(start 386.691886 -240.756694)
		(mid 386.974842 -240.680517)
		(end 387.257798 -240.756694)
		(width 0.0889)
		(layer "In2.Cu")
		(net "M_I_CPU0_SA_DQ<25>")
	)
	(arc
		(start 376.917712 -240.756694)
		(mid 377.099963 -240.807044)
		(end 377.283472 -240.76152)
		(width 0.0889)
		(layer "In2.Cu")
		(net "M_I_CPU0_SA_DQ<25>")
	)
	(arc
		(start 392.341862 -240.750598)
		(mid 392.620548 -240.680378)
		(end 392.897614 -240.756694)
		(width 0.0889)
		(layer "In2.Cu")
		(net "M_I_CPU0_SA_DQ<25>")
	)
	(arc
		(start 392.897614 -240.756694)
		(mid 393.077819 -240.807011)
		(end 393.259818 -240.763552)
		(width 0.0889)
		(layer "In2.Cu")
		(net "M_I_CPU0_SA_DQ<25>")
	)
	(arc
		(start 383.871978 -240.756694)
		(mid 384.154934 -240.680517)
		(end 384.43789 -240.756694)
		(width 0.0889)
		(layer "In2.Cu")
		(net "M_I_CPU0_SA_DQ<25>")
	)
	(arc
		(start 385.751832 -240.756694)
		(mid 386.034788 -240.680517)
		(end 386.317744 -240.756694)
		(width 0.0889)
		(layer "In2.Cu")
		(net "M_I_CPU0_SA_DQ<25>")
	)
	(arc
		(start 388.571994 -240.756694)
		(mid 388.85495 -240.680517)
		(end 389.137906 -240.756694)
		(width 0.0889)
		(layer "In2.Cu")
		(net "M_I_CPU0_SA_DQ<25>")
	)
	(arc
		(start 378.806202 -240.76152)
		(mid 378.98971 -240.807014)
		(end 379.171962 -240.756694)
		(width 0.0889)
		(layer "In2.Cu")
		(net "M_I_CPU0_SA_DQ<25>")
	)
	(arc
		(start 389.137906 -240.756694)
		(mid 389.32485 -240.806949)
		(end 389.511794 -240.756694)
		(width 0.0889)
		(layer "In2.Cu")
		(net "M_I_CPU0_SA_DQ<25>")
	)
	(arc
		(start 391.391902 -240.756694)
		(mid 391.668715 -240.680551)
		(end 391.947146 -240.750598)
		(width 0.0889)
		(layer "In2.Cu")
		(net "M_I_CPU0_SA_DQ<25>")
	)
	(arc
		(start 382.931924 -240.756694)
		(mid 383.21488 -240.680517)
		(end 383.497836 -240.756694)
		(width 0.0889)
		(layer "In2.Cu")
		(net "M_I_CPU0_SA_DQ<25>")
	)
	(arc
		(start 387.26618 -240.76152)
		(mid 387.449688 -240.807014)
		(end 387.63194 -240.756694)
		(width 0.0889)
		(layer "In2.Cu")
		(net "M_I_CPU0_SA_DQ<25>")
	)
	(arc
		(start 380.677674 -240.756694)
		(mid 380.859925 -240.807044)
		(end 381.043434 -240.76152)
		(width 0.0889)
		(layer "In2.Cu")
		(net "M_I_CPU0_SA_DQ<25>")
	)
	(arc
		(start 382.566164 -240.76152)
		(mid 382.749672 -240.807014)
		(end 382.931924 -240.756694)
		(width 0.0889)
		(layer "In2.Cu")
		(net "M_I_CPU0_SA_DQ<25>")
	)
	(arc
		(start 381.051816 -240.756694)
		(mid 381.334772 -240.680517)
		(end 381.617728 -240.756694)
		(width 0.0889)
		(layer "In2.Cu")
		(net "M_I_CPU0_SA_DQ<25>")
	)
	(arc
		(start 376.3518 -240.756694)
		(mid 376.634756 -240.680517)
		(end 376.917712 -240.756694)
		(width 0.0889)
		(layer "In2.Cu")
		(net "M_I_CPU0_SA_DQ<25>")
	)
	(arc
		(start 381.617728 -240.756694)
		(mid 381.799979 -240.807044)
		(end 381.983488 -240.76152)
		(width 0.0889)
		(layer "In2.Cu")
		(net "M_I_CPU0_SA_DQ<25>")
	)
	(arc
		(start 379.737874 -240.756694)
		(mid 379.924818 -240.806949)
		(end 380.111762 -240.756694)
		(width 0.0889)
		(layer "In2.Cu")
		(net "M_I_CPU0_SA_DQ<25>")
	)
	(arc
		(start 393.271502 -240.756694)
		(mid 393.311905 -240.72974)
		(end 393.348464 -240.697766)
		(width 0.0889)
		(layer "In2.Cu")
		(net "M_I_CPU0_SA_DQ<25>")
	)
	(arc
		(start 380.111762 -240.756694)
		(mid 380.394718 -240.680517)
		(end 380.677674 -240.756694)
		(width 0.0889)
		(layer "In2.Cu")
		(net "M_I_CPU0_SA_DQ<25>")
	)
	(arc
		(start 386.317744 -240.756694)
		(mid 386.499995 -240.807044)
		(end 386.683504 -240.76152)
		(width 0.0889)
		(layer "In2.Cu")
		(net "M_I_CPU0_SA_DQ<25>")
	)
	(segment
		(start 377.107958 -239.890046)
		(end 377.57481 -239.624108)
		(width 0.10668)
		(layer "F.Cu")
		(net "M_I_CPU0_SA_DQ<24>")
	)
	(segment
		(start 381.147828 -239.946688)
		(end 381.15621 -239.951514)
		(width 0.0889)
		(layer "In2.Cu")
		(net "M_I_CPU0_SA_DQ<24>")
	)
	(segment
		(start 391.861802 -239.946688)
		(end 391.872216 -239.940592)
		(width 0.0889)
		(layer "In2.Cu")
		(net "M_I_CPU0_SA_DQ<24>")
	)
	(segment
		(start 418.322252 -224.96018)
		(end 419.172136 -225.810064)
		(width 0.14478)
		(layer "In2.Cu")
		(net "M_I_CPU0_SA_DQ<24>")
	)
	(segment
		(start 379.63348 -239.951514)
		(end 379.641862 -239.946688)
		(width 0.0889)
		(layer "In2.Cu")
		(net "M_I_CPU0_SA_DQ<24>")
	)
	(segment
		(start 430.10328 -225.44151)
		(end 430.266094 -225.278696)
		(width 0.14478)
		(layer "In2.Cu")
		(net "M_I_CPU0_SA_DQ<24>")
	)
	(segment
		(start 380.207774 -239.946688)
		(end 380.216156 -239.951514)
		(width 0.0889)
		(layer "In2.Cu")
		(net "M_I_CPU0_SA_DQ<24>")
	)
	(segment
		(start 429.709834 -225.278696)
		(end 429.872648 -225.44151)
		(width 0.14478)
		(layer "In2.Cu")
		(net "M_I_CPU0_SA_DQ<24>")
	)
	(segment
		(start 414.63595 -224.96018)
		(end 418.322252 -224.96018)
		(width 0.14478)
		(layer "In2.Cu")
		(net "M_I_CPU0_SA_DQ<24>")
	)
	(segment
		(start 413.786066 -225.810064)
		(end 414.63595 -224.96018)
		(width 0.14478)
		(layer "In2.Cu")
		(net "M_I_CPU0_SA_DQ<24>")
	)
	(segment
		(start 408.316176 -228.859334)
		(end 411.365446 -225.810064)
		(width 0.14478)
		(layer "In2.Cu")
		(net "M_I_CPU0_SA_DQ<24>")
	)
	(segment
		(start 429.709834 -225.122994)
		(end 429.709834 -225.278696)
		(width 0.14478)
		(layer "In2.Cu")
		(net "M_I_CPU0_SA_DQ<24>")
	)
	(segment
		(start 430.266094 -225.278696)
		(end 430.266094 -225.122994)
		(width 0.14478)
		(layer "In2.Cu")
		(net "M_I_CPU0_SA_DQ<24>")
	)
	(segment
		(start 430.266094 -225.122994)
		(end 430.428908 -224.96018)
		(width 0.14478)
		(layer "In2.Cu")
		(net "M_I_CPU0_SA_DQ<24>")
	)
	(segment
		(start 393.084812 -239.870488)
		(end 393.487656 -239.467644)
		(width 0.0889)
		(layer "In2.Cu")
		(net "M_I_CPU0_SA_DQ<24>")
	)
	(segment
		(start 430.428908 -224.96018)
		(end 431.131218 -224.96018)
		(width 0.14478)
		(layer "In2.Cu")
		(net "M_I_CPU0_SA_DQ<24>")
	)
	(segment
		(start 389.607806 -239.946688)
		(end 389.616188 -239.951514)
		(width 0.0889)
		(layer "In2.Cu")
		(net "M_I_CPU0_SA_DQ<24>")
	)
	(segment
		(start 377.57481 -239.624108)
		(end 377.420886 -239.889538)
		(width 0.0889)
		(layer "In2.Cu")
		(net "M_I_CPU0_SA_DQ<24>")
	)
	(segment
		(start 419.172136 -225.810064)
		(end 421.626792 -225.810064)
		(width 0.14478)
		(layer "In2.Cu")
		(net "M_I_CPU0_SA_DQ<24>")
	)
	(segment
		(start 429.872648 -225.44151)
		(end 430.10328 -225.44151)
		(width 0.14478)
		(layer "In2.Cu")
		(net "M_I_CPU0_SA_DQ<24>")
	)
	(segment
		(start 407.4922 -228.859334)
		(end 408.316176 -228.859334)
		(width 0.14478)
		(layer "In2.Cu")
		(net "M_I_CPU0_SA_DQ<24>")
	)
	(segment
		(start 384.90779 -239.946688)
		(end 384.916172 -239.951514)
		(width 0.0889)
		(layer "In2.Cu")
		(net "M_I_CPU0_SA_DQ<24>")
	)
	(segment
		(start 391.85342 -239.951514)
		(end 391.861802 -239.946688)
		(width 0.0889)
		(layer "In2.Cu")
		(net "M_I_CPU0_SA_DQ<24>")
	)
	(segment
		(start 429.54702 -224.96018)
		(end 429.709834 -225.122994)
		(width 0.14478)
		(layer "In2.Cu")
		(net "M_I_CPU0_SA_DQ<24>")
	)
	(segment
		(start 388.093458 -239.951514)
		(end 388.10184 -239.946688)
		(width 0.0889)
		(layer "In2.Cu")
		(net "M_I_CPU0_SA_DQ<24>")
	)
	(segment
		(start 383.393442 -239.951514)
		(end 383.401824 -239.946688)
		(width 0.0889)
		(layer "In2.Cu")
		(net "M_I_CPU0_SA_DQ<24>")
	)
	(segment
		(start 393.487656 -239.467644)
		(end 393.487656 -239.359694)
		(width 0.0889)
		(layer "In2.Cu")
		(net "M_I_CPU0_SA_DQ<24>")
	)
	(segment
		(start 411.365446 -225.810064)
		(end 413.786066 -225.810064)
		(width 0.14478)
		(layer "In2.Cu")
		(net "M_I_CPU0_SA_DQ<24>")
	)
	(segment
		(start 398.253204 -238.09833)
		(end 407.4922 -228.859334)
		(width 0.14478)
		(layer "In2.Cu")
		(net "M_I_CPU0_SA_DQ<24>")
	)
	(segment
		(start 384.333496 -239.951514)
		(end 384.341878 -239.946688)
		(width 0.0889)
		(layer "In2.Cu")
		(net "M_I_CPU0_SA_DQ<24>")
	)
	(segment
		(start 394.935456 -238.68507)
		(end 395.522196 -238.09833)
		(width 0.0889)
		(layer "In2.Cu")
		(net "M_I_CPU0_SA_DQ<24>")
	)
	(segment
		(start 377.420886 -239.889538)
		(end 377.443238 -239.97285)
		(width 0.0889)
		(layer "In2.Cu")
		(net "M_I_CPU0_SA_DQ<24>")
	)
	(segment
		(start 395.522196 -238.09833)
		(end 395.884654 -238.09833)
		(width 0.0889)
		(layer "In2.Cu")
		(net "M_I_CPU0_SA_DQ<24>")
	)
	(segment
		(start 389.033512 -239.951514)
		(end 389.041894 -239.946688)
		(width 0.0889)
		(layer "In2.Cu")
		(net "M_I_CPU0_SA_DQ<24>")
	)
	(segment
		(start 421.626792 -225.810064)
		(end 422.476676 -224.96018)
		(width 0.14478)
		(layer "In2.Cu")
		(net "M_I_CPU0_SA_DQ<24>")
	)
	(segment
		(start 392.42746 -239.946688)
		(end 392.435842 -239.951514)
		(width 0.0889)
		(layer "In2.Cu")
		(net "M_I_CPU0_SA_DQ<24>")
	)
	(segment
		(start 378.693426 -239.951514)
		(end 378.701808 -239.946688)
		(width 0.0889)
		(layer "In2.Cu")
		(net "M_I_CPU0_SA_DQ<24>")
	)
	(segment
		(start 393.487656 -239.359694)
		(end 394.16228 -238.68507)
		(width 0.0889)
		(layer "In2.Cu")
		(net "M_I_CPU0_SA_DQ<24>")
	)
	(segment
		(start 431.131218 -224.96018)
		(end 431.55616 -225.385122)
		(width 0.14478)
		(layer "In2.Cu")
		(net "M_I_CPU0_SA_DQ<24>")
	)
	(segment
		(start 395.884654 -238.09833)
		(end 398.253204 -238.09833)
		(width 0.14478)
		(layer "In2.Cu")
		(net "M_I_CPU0_SA_DQ<24>")
	)
	(segment
		(start 422.476676 -224.96018)
		(end 429.54702 -224.96018)
		(width 0.14478)
		(layer "In2.Cu")
		(net "M_I_CPU0_SA_DQ<24>")
	)
	(segment
		(start 394.16228 -238.68507)
		(end 394.935456 -238.68507)
		(width 0.0889)
		(layer "In2.Cu")
		(net "M_I_CPU0_SA_DQ<24>")
	)
	(segment
		(start 385.847844 -239.946688)
		(end 385.856226 -239.951514)
		(width 0.0889)
		(layer "In2.Cu")
		(net "M_I_CPU0_SA_DQ<24>")
	)
	(arc
		(start 385.856226 -239.951514)
		(mid 386.039734 -239.997008)
		(end 386.221986 -239.946688)
		(width 0.0889)
		(layer "In2.Cu")
		(net "M_I_CPU0_SA_DQ<24>")
	)
	(arc
		(start 380.216156 -239.951514)
		(mid 380.399664 -239.997008)
		(end 380.581916 -239.946688)
		(width 0.0889)
		(layer "In2.Cu")
		(net "M_I_CPU0_SA_DQ<24>")
	)
	(arc
		(start 385.281932 -239.946688)
		(mid 385.564888 -239.870511)
		(end 385.847844 -239.946688)
		(width 0.0889)
		(layer "In2.Cu")
		(net "M_I_CPU0_SA_DQ<24>")
	)
	(arc
		(start 379.641862 -239.946688)
		(mid 379.924818 -239.870511)
		(end 380.207774 -239.946688)
		(width 0.0889)
		(layer "In2.Cu")
		(net "M_I_CPU0_SA_DQ<24>")
	)
	(arc
		(start 384.341878 -239.946688)
		(mid 384.624834 -239.870511)
		(end 384.90779 -239.946688)
		(width 0.0889)
		(layer "In2.Cu")
		(net "M_I_CPU0_SA_DQ<24>")
	)
	(arc
		(start 381.15621 -239.951514)
		(mid 381.339718 -239.997008)
		(end 381.52197 -239.946688)
		(width 0.0889)
		(layer "In2.Cu")
		(net "M_I_CPU0_SA_DQ<24>")
	)
	(arc
		(start 380.581916 -239.946688)
		(mid 380.864872 -239.870511)
		(end 381.147828 -239.946688)
		(width 0.0889)
		(layer "In2.Cu")
		(net "M_I_CPU0_SA_DQ<24>")
	)
	(arc
		(start 384.916172 -239.951514)
		(mid 385.09968 -239.997008)
		(end 385.281932 -239.946688)
		(width 0.0889)
		(layer "In2.Cu")
		(net "M_I_CPU0_SA_DQ<24>")
	)
	(arc
		(start 390.54786 -239.946688)
		(mid 390.734804 -239.996943)
		(end 390.921748 -239.946688)
		(width 0.0889)
		(layer "In2.Cu")
		(net "M_I_CPU0_SA_DQ<24>")
	)
	(arc
		(start 383.401824 -239.946688)
		(mid 383.68478 -239.870511)
		(end 383.967736 -239.946688)
		(width 0.0889)
		(layer "In2.Cu")
		(net "M_I_CPU0_SA_DQ<24>")
	)
	(arc
		(start 382.46177 -239.946688)
		(mid 382.744726 -239.870511)
		(end 383.027682 -239.946688)
		(width 0.0889)
		(layer "In2.Cu")
		(net "M_I_CPU0_SA_DQ<24>")
	)
	(arc
		(start 392.801602 -239.946688)
		(mid 392.938165 -239.889855)
		(end 393.084812 -239.870488)
		(width 0.0889)
		(layer "In2.Cu")
		(net "M_I_CPU0_SA_DQ<24>")
	)
	(arc
		(start 383.027682 -239.946688)
		(mid 383.209933 -239.997038)
		(end 383.393442 -239.951514)
		(width 0.0889)
		(layer "In2.Cu")
		(net "M_I_CPU0_SA_DQ<24>")
	)
	(arc
		(start 391.872216 -239.940592)
		(mid 392.150648 -239.870494)
		(end 392.42746 -239.946688)
		(width 0.0889)
		(layer "In2.Cu")
		(net "M_I_CPU0_SA_DQ<24>")
	)
	(arc
		(start 386.787898 -239.946688)
		(mid 386.974842 -239.996943)
		(end 387.161786 -239.946688)
		(width 0.0889)
		(layer "In2.Cu")
		(net "M_I_CPU0_SA_DQ<24>")
	)
	(arc
		(start 381.52197 -239.946688)
		(mid 381.804926 -239.870511)
		(end 382.087882 -239.946688)
		(width 0.0889)
		(layer "In2.Cu")
		(net "M_I_CPU0_SA_DQ<24>")
	)
	(arc
		(start 387.727698 -239.946688)
		(mid 387.909949 -239.997038)
		(end 388.093458 -239.951514)
		(width 0.0889)
		(layer "In2.Cu")
		(net "M_I_CPU0_SA_DQ<24>")
	)
	(arc
		(start 388.667752 -239.946688)
		(mid 388.850003 -239.997038)
		(end 389.033512 -239.951514)
		(width 0.0889)
		(layer "In2.Cu")
		(net "M_I_CPU0_SA_DQ<24>")
	)
	(arc
		(start 391.48766 -239.946688)
		(mid 391.669911 -239.997038)
		(end 391.85342 -239.951514)
		(width 0.0889)
		(layer "In2.Cu")
		(net "M_I_CPU0_SA_DQ<24>")
	)
	(arc
		(start 383.967736 -239.946688)
		(mid 384.149987 -239.997038)
		(end 384.333496 -239.951514)
		(width 0.0889)
		(layer "In2.Cu")
		(net "M_I_CPU0_SA_DQ<24>")
	)
	(arc
		(start 390.921748 -239.946688)
		(mid 391.204704 -239.870511)
		(end 391.48766 -239.946688)
		(width 0.0889)
		(layer "In2.Cu")
		(net "M_I_CPU0_SA_DQ<24>")
	)
	(arc
		(start 389.041894 -239.946688)
		(mid 389.32485 -239.870511)
		(end 389.607806 -239.946688)
		(width 0.0889)
		(layer "In2.Cu")
		(net "M_I_CPU0_SA_DQ<24>")
	)
	(arc
		(start 378.701808 -239.946688)
		(mid 378.984764 -239.870511)
		(end 379.26772 -239.946688)
		(width 0.0889)
		(layer "In2.Cu")
		(net "M_I_CPU0_SA_DQ<24>")
	)
	(arc
		(start 388.10184 -239.946688)
		(mid 388.384796 -239.870511)
		(end 388.667752 -239.946688)
		(width 0.0889)
		(layer "In2.Cu")
		(net "M_I_CPU0_SA_DQ<24>")
	)
	(arc
		(start 389.616188 -239.951514)
		(mid 389.799696 -239.997008)
		(end 389.981948 -239.946688)
		(width 0.0889)
		(layer "In2.Cu")
		(net "M_I_CPU0_SA_DQ<24>")
	)
	(arc
		(start 382.087882 -239.946688)
		(mid 382.274826 -239.996943)
		(end 382.46177 -239.946688)
		(width 0.0889)
		(layer "In2.Cu")
		(net "M_I_CPU0_SA_DQ<24>")
	)
	(arc
		(start 379.26772 -239.946688)
		(mid 379.449971 -239.997038)
		(end 379.63348 -239.951514)
		(width 0.0889)
		(layer "In2.Cu")
		(net "M_I_CPU0_SA_DQ<24>")
	)
	(arc
		(start 387.161786 -239.946688)
		(mid 387.444742 -239.870511)
		(end 387.727698 -239.946688)
		(width 0.0889)
		(layer "In2.Cu")
		(net "M_I_CPU0_SA_DQ<24>")
	)
	(arc
		(start 377.443238 -239.97285)
		(mid 377.605427 -239.995585)
		(end 377.761754 -239.946688)
		(width 0.0889)
		(layer "In2.Cu")
		(net "M_I_CPU0_SA_DQ<24>")
	)
	(arc
		(start 392.435842 -239.951514)
		(mid 392.61935 -239.997008)
		(end 392.801602 -239.946688)
		(width 0.0889)
		(layer "In2.Cu")
		(net "M_I_CPU0_SA_DQ<24>")
	)
	(arc
		(start 378.327666 -239.946688)
		(mid 378.509917 -239.997038)
		(end 378.693426 -239.951514)
		(width 0.0889)
		(layer "In2.Cu")
		(net "M_I_CPU0_SA_DQ<24>")
	)
	(arc
		(start 386.221986 -239.946688)
		(mid 386.504942 -239.870511)
		(end 386.787898 -239.946688)
		(width 0.0889)
		(layer "In2.Cu")
		(net "M_I_CPU0_SA_DQ<24>")
	)
	(arc
		(start 389.981948 -239.946688)
		(mid 390.264904 -239.870511)
		(end 390.54786 -239.946688)
		(width 0.0889)
		(layer "In2.Cu")
		(net "M_I_CPU0_SA_DQ<24>")
	)
	(arc
		(start 377.761754 -239.946688)
		(mid 378.04471 -239.870511)
		(end 378.327666 -239.946688)
		(width 0.0889)
		(layer "In2.Cu")
		(net "M_I_CPU0_SA_DQ<24>")
	)
	(segment
		(start 375.22785 -239.890046)
		(end 375.694702 -239.624108)
		(width 0.10668)
		(layer "F.Cu")
		(net "M_I_CPU0_SA_DQ<23>")
	)
	(segment
		(start 408.590496 -227.22078)
		(end 408.7622 -227.392484)
		(width 0.14478)
		(layer "In2.Cu")
		(net "M_I_CPU0_SA_DQ<23>")
	)
	(segment
		(start 383.393442 -239.296702)
		(end 383.401824 -239.301528)
		(width 0.0889)
		(layer "In2.Cu")
		(net "M_I_CPU0_SA_DQ<23>")
	)
	(segment
		(start 421.602408 -224.96018)
		(end 422.452546 -224.110042)
		(width 0.14478)
		(layer "In2.Cu")
		(net "M_I_CPU0_SA_DQ<23>")
	)
	(segment
		(start 388.093458 -239.296702)
		(end 388.10184 -239.301528)
		(width 0.0889)
		(layer "In2.Cu")
		(net "M_I_CPU0_SA_DQ<23>")
	)
	(segment
		(start 409.152344 -227.00234)
		(end 408.7241 -226.574096)
		(width 0.14478)
		(layer "In2.Cu")
		(net "M_I_CPU0_SA_DQ<23>")
	)
	(segment
		(start 413.81045 -224.96018)
		(end 414.660588 -224.110042)
		(width 0.14478)
		(layer "In2.Cu")
		(net "M_I_CPU0_SA_DQ<23>")
	)
	(segment
		(start 408.328876 -227.739448)
		(end 408.200352 -227.610924)
		(width 0.14478)
		(layer "In2.Cu")
		(net "M_I_CPU0_SA_DQ<23>")
	)
	(segment
		(start 411.751272 -224.96018)
		(end 413.81045 -224.96018)
		(width 0.14478)
		(layer "In2.Cu")
		(net "M_I_CPU0_SA_DQ<23>")
	)
	(segment
		(start 409.410408 -225.699828)
		(end 409.410408 -225.471228)
		(width 0.14478)
		(layer "In2.Cu")
		(net "M_I_CPU0_SA_DQ<23>")
	)
	(segment
		(start 408.885644 -226.183952)
		(end 409.114244 -226.183952)
		(width 0.14478)
		(layer "In2.Cu")
		(net "M_I_CPU0_SA_DQ<23>")
	)
	(segment
		(start 394.518896 -237.91037)
		(end 395.158976 -237.91037)
		(width 0.0889)
		(layer "In2.Cu")
		(net "M_I_CPU0_SA_DQ<23>")
	)
	(segment
		(start 409.932632 -226.450652)
		(end 409.932632 -226.222052)
		(width 0.14478)
		(layer "In2.Cu")
		(net "M_I_CPU0_SA_DQ<23>")
	)
	(segment
		(start 408.200352 -227.610924)
		(end 408.200352 -227.382324)
		(width 0.14478)
		(layer "In2.Cu")
		(net "M_I_CPU0_SA_DQ<23>")
	)
	(segment
		(start 409.771088 -226.612196)
		(end 409.932632 -226.450652)
		(width 0.14478)
		(layer "In2.Cu")
		(net "M_I_CPU0_SA_DQ<23>")
	)
	(segment
		(start 384.90779 -239.301528)
		(end 384.916172 -239.296702)
		(width 0.0889)
		(layer "In2.Cu")
		(net "M_I_CPU0_SA_DQ<23>")
	)
	(segment
		(start 408.196034 -228.10089)
		(end 408.328876 -227.968048)
		(width 0.14478)
		(layer "In2.Cu")
		(net "M_I_CPU0_SA_DQ<23>")
	)
	(segment
		(start 410.69768 -225.655124)
		(end 410.69768 -225.426524)
		(width 0.14478)
		(layer "In2.Cu")
		(net "M_I_CPU0_SA_DQ<23>")
	)
	(segment
		(start 409.800552 -225.309684)
		(end 410.307536 -225.816668)
		(width 0.14478)
		(layer "In2.Cu")
		(net "M_I_CPU0_SA_DQ<23>")
	)
	(segment
		(start 393.127738 -239.301528)
		(end 394.518896 -237.91037)
		(width 0.0889)
		(layer "In2.Cu")
		(net "M_I_CPU0_SA_DQ<23>")
	)
	(segment
		(start 408.7241 -226.574096)
		(end 408.7241 -226.345496)
		(width 0.14478)
		(layer "In2.Cu")
		(net "M_I_CPU0_SA_DQ<23>")
	)
	(segment
		(start 385.847844 -239.301528)
		(end 385.856226 -239.296702)
		(width 0.0889)
		(layer "In2.Cu")
		(net "M_I_CPU0_SA_DQ<23>")
	)
	(segment
		(start 408.7622 -227.392484)
		(end 408.9908 -227.392484)
		(width 0.14478)
		(layer "In2.Cu")
		(net "M_I_CPU0_SA_DQ<23>")
	)
	(segment
		(start 410.25318 -224.753424)
		(end 410.414724 -224.59188)
		(width 0.14478)
		(layer "In2.Cu")
		(net "M_I_CPU0_SA_DQ<23>")
	)
	(segment
		(start 408.328876 -227.968048)
		(end 408.328876 -227.739448)
		(width 0.14478)
		(layer "In2.Cu")
		(net "M_I_CPU0_SA_DQ<23>")
	)
	(segment
		(start 378.693426 -239.296702)
		(end 378.701808 -239.301528)
		(width 0.0889)
		(layer "In2.Cu")
		(net "M_I_CPU0_SA_DQ<23>")
	)
	(segment
		(start 409.114244 -226.183952)
		(end 409.542488 -226.612196)
		(width 0.14478)
		(layer "In2.Cu")
		(net "M_I_CPU0_SA_DQ<23>")
	)
	(segment
		(start 389.607806 -239.301528)
		(end 389.616188 -239.296702)
		(width 0.0889)
		(layer "In2.Cu")
		(net "M_I_CPU0_SA_DQ<23>")
	)
	(segment
		(start 398.032478 -237.53953)
		(end 407.471118 -228.10089)
		(width 0.14478)
		(layer "In2.Cu")
		(net "M_I_CPU0_SA_DQ<23>")
	)
	(segment
		(start 410.307536 -225.816668)
		(end 410.536136 -225.816668)
		(width 0.14478)
		(layer "In2.Cu")
		(net "M_I_CPU0_SA_DQ<23>")
	)
	(segment
		(start 410.536136 -225.816668)
		(end 410.69768 -225.655124)
		(width 0.14478)
		(layer "In2.Cu")
		(net "M_I_CPU0_SA_DQ<23>")
	)
	(segment
		(start 410.69768 -225.426524)
		(end 410.25318 -224.982024)
		(width 0.14478)
		(layer "In2.Cu")
		(net "M_I_CPU0_SA_DQ<23>")
	)
	(segment
		(start 410.414724 -224.59188)
		(end 410.643324 -224.59188)
		(width 0.14478)
		(layer "In2.Cu")
		(net "M_I_CPU0_SA_DQ<23>")
	)
	(segment
		(start 408.361896 -227.22078)
		(end 408.590496 -227.22078)
		(width 0.14478)
		(layer "In2.Cu")
		(net "M_I_CPU0_SA_DQ<23>")
	)
	(segment
		(start 395.158976 -237.91037)
		(end 395.529816 -237.53953)
		(width 0.0889)
		(layer "In2.Cu")
		(net "M_I_CPU0_SA_DQ<23>")
	)
	(segment
		(start 380.207774 -239.301528)
		(end 380.216156 -239.296702)
		(width 0.0889)
		(layer "In2.Cu")
		(net "M_I_CPU0_SA_DQ<23>")
	)
	(segment
		(start 411.267148 -225.215704)
		(end 411.495748 -225.215704)
		(width 0.14478)
		(layer "In2.Cu")
		(net "M_I_CPU0_SA_DQ<23>")
	)
	(segment
		(start 409.571952 -225.309684)
		(end 409.800552 -225.309684)
		(width 0.14478)
		(layer "In2.Cu")
		(net "M_I_CPU0_SA_DQ<23>")
	)
	(segment
		(start 409.152344 -227.23094)
		(end 409.152344 -227.00234)
		(width 0.14478)
		(layer "In2.Cu")
		(net "M_I_CPU0_SA_DQ<23>")
	)
	(segment
		(start 422.452546 -224.110042)
		(end 427.03115 -224.110042)
		(width 0.14478)
		(layer "In2.Cu")
		(net "M_I_CPU0_SA_DQ<23>")
	)
	(segment
		(start 389.033512 -239.296702)
		(end 389.041894 -239.301528)
		(width 0.0889)
		(layer "In2.Cu")
		(net "M_I_CPU0_SA_DQ<23>")
	)
	(segment
		(start 409.410408 -225.471228)
		(end 409.571952 -225.309684)
		(width 0.14478)
		(layer "In2.Cu")
		(net "M_I_CPU0_SA_DQ<23>")
	)
	(segment
		(start 418.268658 -224.110042)
		(end 419.118796 -224.96018)
		(width 0.14478)
		(layer "In2.Cu")
		(net "M_I_CPU0_SA_DQ<23>")
	)
	(segment
		(start 384.333496 -239.296702)
		(end 384.341878 -239.301528)
		(width 0.0889)
		(layer "In2.Cu")
		(net "M_I_CPU0_SA_DQ<23>")
	)
	(segment
		(start 381.147828 -239.301528)
		(end 381.15621 -239.296702)
		(width 0.0889)
		(layer "In2.Cu")
		(net "M_I_CPU0_SA_DQ<23>")
	)
	(segment
		(start 379.63348 -239.296702)
		(end 379.641862 -239.301528)
		(width 0.0889)
		(layer "In2.Cu")
		(net "M_I_CPU0_SA_DQ<23>")
	)
	(segment
		(start 391.862056 -239.301528)
		(end 393.127738 -239.301528)
		(width 0.0889)
		(layer "In2.Cu")
		(net "M_I_CPU0_SA_DQ<23>")
	)
	(segment
		(start 427.03115 -224.110042)
		(end 427.456092 -224.534984)
		(width 0.14478)
		(layer "In2.Cu")
		(net "M_I_CPU0_SA_DQ<23>")
	)
	(segment
		(start 408.7241 -226.345496)
		(end 408.885644 -226.183952)
		(width 0.14478)
		(layer "In2.Cu")
		(net "M_I_CPU0_SA_DQ<23>")
	)
	(segment
		(start 408.200352 -227.382324)
		(end 408.361896 -227.22078)
		(width 0.14478)
		(layer "In2.Cu")
		(net "M_I_CPU0_SA_DQ<23>")
	)
	(segment
		(start 408.9908 -227.392484)
		(end 409.152344 -227.23094)
		(width 0.14478)
		(layer "In2.Cu")
		(net "M_I_CPU0_SA_DQ<23>")
	)
	(segment
		(start 376.447812 -239.301528)
		(end 376.456194 -239.296702)
		(width 0.0889)
		(layer "In2.Cu")
		(net "M_I_CPU0_SA_DQ<23>")
	)
	(segment
		(start 395.529816 -237.53953)
		(end 395.910054 -237.53953)
		(width 0.0889)
		(layer "In2.Cu")
		(net "M_I_CPU0_SA_DQ<23>")
	)
	(segment
		(start 395.910054 -237.53953)
		(end 398.032478 -237.53953)
		(width 0.14478)
		(layer "In2.Cu")
		(net "M_I_CPU0_SA_DQ<23>")
	)
	(segment
		(start 409.932632 -226.222052)
		(end 409.410408 -225.699828)
		(width 0.14478)
		(layer "In2.Cu")
		(net "M_I_CPU0_SA_DQ<23>")
	)
	(segment
		(start 375.694702 -239.624108)
		(end 375.84888 -239.358678)
		(width 0.0889)
		(layer "In2.Cu")
		(net "M_I_CPU0_SA_DQ<23>")
	)
	(segment
		(start 411.495748 -225.215704)
		(end 411.751272 -224.96018)
		(width 0.14478)
		(layer "In2.Cu")
		(net "M_I_CPU0_SA_DQ<23>")
	)
	(segment
		(start 375.84888 -239.358678)
		(end 375.945146 -239.333278)
		(width 0.0889)
		(layer "In2.Cu")
		(net "M_I_CPU0_SA_DQ<23>")
	)
	(segment
		(start 410.25318 -224.982024)
		(end 410.25318 -224.753424)
		(width 0.14478)
		(layer "In2.Cu")
		(net "M_I_CPU0_SA_DQ<23>")
	)
	(segment
		(start 409.542488 -226.612196)
		(end 409.771088 -226.612196)
		(width 0.14478)
		(layer "In2.Cu")
		(net "M_I_CPU0_SA_DQ<23>")
	)
	(segment
		(start 419.118796 -224.96018)
		(end 421.602408 -224.96018)
		(width 0.14478)
		(layer "In2.Cu")
		(net "M_I_CPU0_SA_DQ<23>")
	)
	(segment
		(start 414.660588 -224.110042)
		(end 418.268658 -224.110042)
		(width 0.14478)
		(layer "In2.Cu")
		(net "M_I_CPU0_SA_DQ<23>")
	)
	(segment
		(start 407.471118 -228.10089)
		(end 408.196034 -228.10089)
		(width 0.14478)
		(layer "In2.Cu")
		(net "M_I_CPU0_SA_DQ<23>")
	)
	(segment
		(start 410.643324 -224.59188)
		(end 411.267148 -225.215704)
		(width 0.14478)
		(layer "In2.Cu")
		(net "M_I_CPU0_SA_DQ<23>")
	)
	(arc
		(start 390.54786 -239.301528)
		(mid 390.734804 -239.251273)
		(end 390.921748 -239.301528)
		(width 0.0889)
		(layer "In2.Cu")
		(net "M_I_CPU0_SA_DQ<23>")
	)
	(arc
		(start 391.48766 -239.301528)
		(mid 391.674858 -239.251146)
		(end 391.862056 -239.301528)
		(width 0.0889)
		(layer "In2.Cu")
		(net "M_I_CPU0_SA_DQ<23>")
	)
	(arc
		(start 378.701808 -239.301528)
		(mid 378.984764 -239.377705)
		(end 379.26772 -239.301528)
		(width 0.0889)
		(layer "In2.Cu")
		(net "M_I_CPU0_SA_DQ<23>")
	)
	(arc
		(start 377.387866 -239.301528)
		(mid 377.57481 -239.251273)
		(end 377.761754 -239.301528)
		(width 0.0889)
		(layer "In2.Cu")
		(net "M_I_CPU0_SA_DQ<23>")
	)
	(arc
		(start 389.616188 -239.296702)
		(mid 389.799696 -239.251208)
		(end 389.981948 -239.301528)
		(width 0.0889)
		(layer "In2.Cu")
		(net "M_I_CPU0_SA_DQ<23>")
	)
	(arc
		(start 379.641862 -239.301528)
		(mid 379.924818 -239.377705)
		(end 380.207774 -239.301528)
		(width 0.0889)
		(layer "In2.Cu")
		(net "M_I_CPU0_SA_DQ<23>")
	)
	(arc
		(start 376.821954 -239.301528)
		(mid 377.10491 -239.377705)
		(end 377.387866 -239.301528)
		(width 0.0889)
		(layer "In2.Cu")
		(net "M_I_CPU0_SA_DQ<23>")
	)
	(arc
		(start 389.041894 -239.301528)
		(mid 389.32485 -239.377705)
		(end 389.607806 -239.301528)
		(width 0.0889)
		(layer "In2.Cu")
		(net "M_I_CPU0_SA_DQ<23>")
	)
	(arc
		(start 380.216156 -239.296702)
		(mid 380.399664 -239.251208)
		(end 380.581916 -239.301528)
		(width 0.0889)
		(layer "In2.Cu")
		(net "M_I_CPU0_SA_DQ<23>")
	)
	(arc
		(start 379.26772 -239.301528)
		(mid 379.449971 -239.251178)
		(end 379.63348 -239.296702)
		(width 0.0889)
		(layer "In2.Cu")
		(net "M_I_CPU0_SA_DQ<23>")
	)
	(arc
		(start 390.921748 -239.301528)
		(mid 391.204704 -239.377705)
		(end 391.48766 -239.301528)
		(width 0.0889)
		(layer "In2.Cu")
		(net "M_I_CPU0_SA_DQ<23>")
	)
	(arc
		(start 386.221986 -239.301528)
		(mid 386.504942 -239.377705)
		(end 386.787898 -239.301528)
		(width 0.0889)
		(layer "In2.Cu")
		(net "M_I_CPU0_SA_DQ<23>")
	)
	(arc
		(start 380.581916 -239.301528)
		(mid 380.864872 -239.377705)
		(end 381.147828 -239.301528)
		(width 0.0889)
		(layer "In2.Cu")
		(net "M_I_CPU0_SA_DQ<23>")
	)
	(arc
		(start 382.46177 -239.301528)
		(mid 382.744726 -239.377705)
		(end 383.027682 -239.301528)
		(width 0.0889)
		(layer "In2.Cu")
		(net "M_I_CPU0_SA_DQ<23>")
	)
	(arc
		(start 381.15621 -239.296702)
		(mid 381.339718 -239.251208)
		(end 381.52197 -239.301528)
		(width 0.0889)
		(layer "In2.Cu")
		(net "M_I_CPU0_SA_DQ<23>")
	)
	(arc
		(start 383.401824 -239.301528)
		(mid 383.68478 -239.377705)
		(end 383.967736 -239.301528)
		(width 0.0889)
		(layer "In2.Cu")
		(net "M_I_CPU0_SA_DQ<23>")
	)
	(arc
		(start 386.787898 -239.301528)
		(mid 386.974842 -239.251273)
		(end 387.161786 -239.301528)
		(width 0.0889)
		(layer "In2.Cu")
		(net "M_I_CPU0_SA_DQ<23>")
	)
	(arc
		(start 381.52197 -239.301528)
		(mid 381.804926 -239.377705)
		(end 382.087882 -239.301528)
		(width 0.0889)
		(layer "In2.Cu")
		(net "M_I_CPU0_SA_DQ<23>")
	)
	(arc
		(start 383.967736 -239.301528)
		(mid 384.149987 -239.251178)
		(end 384.333496 -239.296702)
		(width 0.0889)
		(layer "In2.Cu")
		(net "M_I_CPU0_SA_DQ<23>")
	)
	(arc
		(start 388.667752 -239.301528)
		(mid 388.850003 -239.251178)
		(end 389.033512 -239.296702)
		(width 0.0889)
		(layer "In2.Cu")
		(net "M_I_CPU0_SA_DQ<23>")
	)
	(arc
		(start 385.281932 -239.301528)
		(mid 385.564888 -239.377705)
		(end 385.847844 -239.301528)
		(width 0.0889)
		(layer "In2.Cu")
		(net "M_I_CPU0_SA_DQ<23>")
	)
	(arc
		(start 384.916172 -239.296702)
		(mid 385.09968 -239.251208)
		(end 385.281932 -239.301528)
		(width 0.0889)
		(layer "In2.Cu")
		(net "M_I_CPU0_SA_DQ<23>")
	)
	(arc
		(start 382.087882 -239.301528)
		(mid 382.274826 -239.251273)
		(end 382.46177 -239.301528)
		(width 0.0889)
		(layer "In2.Cu")
		(net "M_I_CPU0_SA_DQ<23>")
	)
	(arc
		(start 387.161786 -239.301528)
		(mid 387.444742 -239.377705)
		(end 387.727698 -239.301528)
		(width 0.0889)
		(layer "In2.Cu")
		(net "M_I_CPU0_SA_DQ<23>")
	)
	(arc
		(start 377.761754 -239.301528)
		(mid 378.04471 -239.377705)
		(end 378.327666 -239.301528)
		(width 0.0889)
		(layer "In2.Cu")
		(net "M_I_CPU0_SA_DQ<23>")
	)
	(arc
		(start 376.456194 -239.296702)
		(mid 376.639702 -239.251208)
		(end 376.821954 -239.301528)
		(width 0.0889)
		(layer "In2.Cu")
		(net "M_I_CPU0_SA_DQ<23>")
	)
	(arc
		(start 383.027682 -239.301528)
		(mid 383.209933 -239.251178)
		(end 383.393442 -239.296702)
		(width 0.0889)
		(layer "In2.Cu")
		(net "M_I_CPU0_SA_DQ<23>")
	)
	(arc
		(start 388.10184 -239.301528)
		(mid 388.384796 -239.377705)
		(end 388.667752 -239.301528)
		(width 0.0889)
		(layer "In2.Cu")
		(net "M_I_CPU0_SA_DQ<23>")
	)
	(arc
		(start 387.727698 -239.301528)
		(mid 387.909949 -239.251178)
		(end 388.093458 -239.296702)
		(width 0.0889)
		(layer "In2.Cu")
		(net "M_I_CPU0_SA_DQ<23>")
	)
	(arc
		(start 385.856226 -239.296702)
		(mid 386.039734 -239.251208)
		(end 386.221986 -239.301528)
		(width 0.0889)
		(layer "In2.Cu")
		(net "M_I_CPU0_SA_DQ<23>")
	)
	(arc
		(start 389.981948 -239.301528)
		(mid 390.264904 -239.377705)
		(end 390.54786 -239.301528)
		(width 0.0889)
		(layer "In2.Cu")
		(net "M_I_CPU0_SA_DQ<23>")
	)
	(arc
		(start 384.341878 -239.301528)
		(mid 384.624834 -239.377705)
		(end 384.90779 -239.301528)
		(width 0.0889)
		(layer "In2.Cu")
		(net "M_I_CPU0_SA_DQ<23>")
	)
	(arc
		(start 378.327666 -239.301528)
		(mid 378.509917 -239.251178)
		(end 378.693426 -239.296702)
		(width 0.0889)
		(layer "In2.Cu")
		(net "M_I_CPU0_SA_DQ<23>")
	)
	(arc
		(start 375.945146 -239.333278)
		(mid 376.200211 -239.376629)
		(end 376.447812 -239.301528)
		(width 0.0889)
		(layer "In2.Cu")
		(net "M_I_CPU0_SA_DQ<23>")
	)
	(segment
		(start 376.638058 -239.08004)
		(end 377.10491 -238.814102)
		(width 0.10668)
		(layer "F.Cu")
		(net "M_I_CPU0_SA_DQ<22>")
	)
	(segment
		(start 404.113746 -229.061264)
		(end 404.342346 -229.061264)
		(width 0.14478)
		(layer "In2.Cu")
		(net "M_I_CPU0_SA_DQ<22>")
	)
	(segment
		(start 388.197852 -238.491522)
		(end 388.206234 -238.486696)
		(width 0.0889)
		(layer "In2.Cu")
		(net "M_I_CPU0_SA_DQ<22>")
	)
	(segment
		(start 404.73249 -228.67112)
		(end 404.73249 -228.44252)
		(width 0.14478)
		(layer "In2.Cu")
		(net "M_I_CPU0_SA_DQ<22>")
	)
	(segment
		(start 397.679672 -236.62005)
		(end 403.50567 -230.794052)
		(width 0.14478)
		(layer "In2.Cu")
		(net "M_I_CPU0_SA_DQ<22>")
	)
	(segment
		(start 405.68499 -228.614732)
		(end 405.846534 -228.453188)
		(width 0.14478)
		(layer "In2.Cu")
		(net "M_I_CPU0_SA_DQ<22>")
	)
	(segment
		(start 427.03115 -222.41002)
		(end 427.456092 -222.834962)
		(width 0.14478)
		(layer "In2.Cu")
		(net "M_I_CPU0_SA_DQ<22>")
	)
	(segment
		(start 407.40711 -226.664012)
		(end 407.073354 -226.330256)
		(width 0.14478)
		(layer "In2.Cu")
		(net "M_I_CPU0_SA_DQ<22>")
	)
	(segment
		(start 387.257798 -238.491522)
		(end 387.26618 -238.486696)
		(width 0.0889)
		(layer "In2.Cu")
		(net "M_I_CPU0_SA_DQ<22>")
	)
	(segment
		(start 405.066246 -229.004876)
		(end 404.73249 -228.67112)
		(width 0.14478)
		(layer "In2.Cu")
		(net "M_I_CPU0_SA_DQ<22>")
	)
	(segment
		(start 404.285958 -230.013764)
		(end 404.285958 -229.785164)
		(width 0.14478)
		(layer "In2.Cu")
		(net "M_I_CPU0_SA_DQ<22>")
	)
	(segment
		(start 418.759894 -223.260158)
		(end 421.4368 -223.260158)
		(width 0.14478)
		(layer "In2.Cu")
		(net "M_I_CPU0_SA_DQ<22>")
	)
	(segment
		(start 403.50567 -230.794052)
		(end 403.50567 -230.565452)
		(width 0.14478)
		(layer "In2.Cu")
		(net "M_I_CPU0_SA_DQ<22>")
	)
	(segment
		(start 407.073354 -226.330256)
		(end 407.073354 -226.101656)
		(width 0.14478)
		(layer "In2.Cu")
		(net "M_I_CPU0_SA_DQ<22>")
	)
	(segment
		(start 404.894034 -228.280976)
		(end 405.122634 -228.280976)
		(width 0.14478)
		(layer "In2.Cu")
		(net "M_I_CPU0_SA_DQ<22>")
	)
	(segment
		(start 392.822176 -238.20501)
		(end 393.266676 -238.20501)
		(width 0.0889)
		(layer "In2.Cu")
		(net "M_I_CPU0_SA_DQ<22>")
	)
	(segment
		(start 405.066246 -229.233476)
		(end 405.066246 -229.004876)
		(width 0.14478)
		(layer "In2.Cu")
		(net "M_I_CPU0_SA_DQ<22>")
	)
	(segment
		(start 381.043434 -238.486696)
		(end 381.051816 -238.491522)
		(width 0.0889)
		(layer "In2.Cu")
		(net "M_I_CPU0_SA_DQ<22>")
	)
	(segment
		(start 404.73249 -228.44252)
		(end 404.894034 -228.280976)
		(width 0.14478)
		(layer "In2.Cu")
		(net "M_I_CPU0_SA_DQ<22>")
	)
	(segment
		(start 391.01776 -238.491522)
		(end 391.026142 -238.486696)
		(width 0.0889)
		(layer "In2.Cu")
		(net "M_I_CPU0_SA_DQ<22>")
	)
	(segment
		(start 404.285958 -229.785164)
		(end 403.952202 -229.451408)
		(width 0.14478)
		(layer "In2.Cu")
		(net "M_I_CPU0_SA_DQ<22>")
	)
	(segment
		(start 405.45639 -228.614732)
		(end 405.68499 -228.614732)
		(width 0.14478)
		(layer "In2.Cu")
		(net "M_I_CPU0_SA_DQ<22>")
	)
	(segment
		(start 407.40711 -226.892612)
		(end 407.40711 -226.664012)
		(width 0.14478)
		(layer "In2.Cu")
		(net "M_I_CPU0_SA_DQ<22>")
	)
	(segment
		(start 421.4368 -223.260158)
		(end 422.286938 -222.41002)
		(width 0.14478)
		(layer "In2.Cu")
		(net "M_I_CPU0_SA_DQ<22>")
	)
	(segment
		(start 403.333458 -229.841552)
		(end 403.562058 -229.841552)
		(width 0.14478)
		(layer "In2.Cu")
		(net "M_I_CPU0_SA_DQ<22>")
	)
	(segment
		(start 391.692638 -238.567468)
		(end 392.459718 -238.567468)
		(width 0.0889)
		(layer "In2.Cu")
		(net "M_I_CPU0_SA_DQ<22>")
	)
	(segment
		(start 406.293066 -226.881944)
		(end 406.45461 -226.7204)
		(width 0.14478)
		(layer "In2.Cu")
		(net "M_I_CPU0_SA_DQ<22>")
	)
	(segment
		(start 395.534896 -236.62005)
		(end 395.859254 -236.62005)
		(width 0.0889)
		(layer "In2.Cu")
		(net "M_I_CPU0_SA_DQ<22>")
	)
	(segment
		(start 403.171914 -230.231696)
		(end 403.171914 -230.003096)
		(width 0.14478)
		(layer "In2.Cu")
		(net "M_I_CPU0_SA_DQ<22>")
	)
	(segment
		(start 407.245566 -227.054156)
		(end 407.40711 -226.892612)
		(width 0.14478)
		(layer "In2.Cu")
		(net "M_I_CPU0_SA_DQ<22>")
	)
	(segment
		(start 406.626822 -227.4443)
		(end 406.293066 -227.110544)
		(width 0.14478)
		(layer "In2.Cu")
		(net "M_I_CPU0_SA_DQ<22>")
	)
	(segment
		(start 377.857766 -238.491522)
		(end 377.866148 -238.486696)
		(width 0.0889)
		(layer "In2.Cu")
		(net "M_I_CPU0_SA_DQ<22>")
	)
	(segment
		(start 377.258834 -238.548672)
		(end 377.354846 -238.523272)
		(width 0.0889)
		(layer "In2.Cu")
		(net "M_I_CPU0_SA_DQ<22>")
	)
	(segment
		(start 406.626822 -227.6729)
		(end 406.626822 -227.4443)
		(width 0.14478)
		(layer "In2.Cu")
		(net "M_I_CPU0_SA_DQ<22>")
	)
	(segment
		(start 394.785596 -237.36935)
		(end 395.534896 -236.62005)
		(width 0.0889)
		(layer "In2.Cu")
		(net "M_I_CPU0_SA_DQ<22>")
	)
	(segment
		(start 422.286938 -222.41002)
		(end 427.03115 -222.41002)
		(width 0.14478)
		(layer "In2.Cu")
		(net "M_I_CPU0_SA_DQ<22>")
	)
	(segment
		(start 385.74345 -238.486696)
		(end 385.751832 -238.491522)
		(width 0.0889)
		(layer "In2.Cu")
		(net "M_I_CPU0_SA_DQ<22>")
	)
	(segment
		(start 378.79782 -238.491522)
		(end 378.806202 -238.486696)
		(width 0.0889)
		(layer "In2.Cu")
		(net "M_I_CPU0_SA_DQ<22>")
	)
	(segment
		(start 381.983488 -238.486696)
		(end 381.99187 -238.491522)
		(width 0.0889)
		(layer "In2.Cu")
		(net "M_I_CPU0_SA_DQ<22>")
	)
	(segment
		(start 403.562058 -229.841552)
		(end 403.895814 -230.175308)
		(width 0.14478)
		(layer "In2.Cu")
		(net "M_I_CPU0_SA_DQ<22>")
	)
	(segment
		(start 377.10491 -238.814102)
		(end 377.258834 -238.548672)
		(width 0.0889)
		(layer "In2.Cu")
		(net "M_I_CPU0_SA_DQ<22>")
	)
	(segment
		(start 405.674322 -227.500688)
		(end 405.902922 -227.500688)
		(width 0.14478)
		(layer "In2.Cu")
		(net "M_I_CPU0_SA_DQ<22>")
	)
	(segment
		(start 395.859254 -236.62005)
		(end 397.679672 -236.62005)
		(width 0.14478)
		(layer "In2.Cu")
		(net "M_I_CPU0_SA_DQ<22>")
	)
	(segment
		(start 403.171914 -230.003096)
		(end 403.333458 -229.841552)
		(width 0.14478)
		(layer "In2.Cu")
		(net "M_I_CPU0_SA_DQ<22>")
	)
	(segment
		(start 417.909756 -222.41002)
		(end 418.759894 -223.260158)
		(width 0.14478)
		(layer "In2.Cu")
		(net "M_I_CPU0_SA_DQ<22>")
	)
	(segment
		(start 394.102336 -237.36935)
		(end 394.785596 -237.36935)
		(width 0.0889)
		(layer "In2.Cu")
		(net "M_I_CPU0_SA_DQ<22>")
	)
	(segment
		(start 403.50567 -230.565452)
		(end 403.171914 -230.231696)
		(width 0.14478)
		(layer "In2.Cu")
		(net "M_I_CPU0_SA_DQ<22>")
	)
	(segment
		(start 406.236678 -227.834444)
		(end 406.465278 -227.834444)
		(width 0.14478)
		(layer "In2.Cu")
		(net "M_I_CPU0_SA_DQ<22>")
	)
	(segment
		(start 407.016966 -227.054156)
		(end 407.245566 -227.054156)
		(width 0.14478)
		(layer "In2.Cu")
		(net "M_I_CPU0_SA_DQ<22>")
	)
	(segment
		(start 386.683504 -238.486696)
		(end 386.691886 -238.491522)
		(width 0.0889)
		(layer "In2.Cu")
		(net "M_I_CPU0_SA_DQ<22>")
	)
	(segment
		(start 393.266676 -238.20501)
		(end 394.102336 -237.36935)
		(width 0.0889)
		(layer "In2.Cu")
		(net "M_I_CPU0_SA_DQ<22>")
	)
	(segment
		(start 405.846534 -228.224588)
		(end 405.512778 -227.890832)
		(width 0.14478)
		(layer "In2.Cu")
		(net "M_I_CPU0_SA_DQ<22>")
	)
	(segment
		(start 406.465278 -227.834444)
		(end 406.626822 -227.6729)
		(width 0.14478)
		(layer "In2.Cu")
		(net "M_I_CPU0_SA_DQ<22>")
	)
	(segment
		(start 404.904702 -229.39502)
		(end 405.066246 -229.233476)
		(width 0.14478)
		(layer "In2.Cu")
		(net "M_I_CPU0_SA_DQ<22>")
	)
	(segment
		(start 405.512778 -227.662232)
		(end 405.674322 -227.500688)
		(width 0.14478)
		(layer "In2.Cu")
		(net "M_I_CPU0_SA_DQ<22>")
	)
	(segment
		(start 404.676102 -229.39502)
		(end 404.904702 -229.39502)
		(width 0.14478)
		(layer "In2.Cu")
		(net "M_I_CPU0_SA_DQ<22>")
	)
	(segment
		(start 406.68321 -226.7204)
		(end 407.016966 -227.054156)
		(width 0.14478)
		(layer "In2.Cu")
		(net "M_I_CPU0_SA_DQ<22>")
	)
	(segment
		(start 405.122634 -228.280976)
		(end 405.45639 -228.614732)
		(width 0.14478)
		(layer "In2.Cu")
		(net "M_I_CPU0_SA_DQ<22>")
	)
	(segment
		(start 414.167828 -223.260158)
		(end 415.017966 -222.41002)
		(width 0.14478)
		(layer "In2.Cu")
		(net "M_I_CPU0_SA_DQ<22>")
	)
	(segment
		(start 390.443466 -238.486696)
		(end 390.451848 -238.491522)
		(width 0.0889)
		(layer "In2.Cu")
		(net "M_I_CPU0_SA_DQ<22>")
	)
	(segment
		(start 403.952202 -229.451408)
		(end 403.952202 -229.222808)
		(width 0.14478)
		(layer "In2.Cu")
		(net "M_I_CPU0_SA_DQ<22>")
	)
	(segment
		(start 403.952202 -229.222808)
		(end 404.113746 -229.061264)
		(width 0.14478)
		(layer "In2.Cu")
		(net "M_I_CPU0_SA_DQ<22>")
	)
	(segment
		(start 404.124414 -230.175308)
		(end 404.285958 -230.013764)
		(width 0.14478)
		(layer "In2.Cu")
		(net "M_I_CPU0_SA_DQ<22>")
	)
	(segment
		(start 409.914852 -223.260158)
		(end 414.167828 -223.260158)
		(width 0.14478)
		(layer "In2.Cu")
		(net "M_I_CPU0_SA_DQ<22>")
	)
	(segment
		(start 404.342346 -229.061264)
		(end 404.676102 -229.39502)
		(width 0.14478)
		(layer "In2.Cu")
		(net "M_I_CPU0_SA_DQ<22>")
	)
	(segment
		(start 382.557782 -238.491522)
		(end 382.566164 -238.486696)
		(width 0.0889)
		(layer "In2.Cu")
		(net "M_I_CPU0_SA_DQ<22>")
	)
	(segment
		(start 392.459718 -238.567468)
		(end 392.822176 -238.20501)
		(width 0.0889)
		(layer "In2.Cu")
		(net "M_I_CPU0_SA_DQ<22>")
	)
	(segment
		(start 405.512778 -227.890832)
		(end 405.512778 -227.662232)
		(width 0.14478)
		(layer "In2.Cu")
		(net "M_I_CPU0_SA_DQ<22>")
	)
	(segment
		(start 405.846534 -228.453188)
		(end 405.846534 -228.224588)
		(width 0.14478)
		(layer "In2.Cu")
		(net "M_I_CPU0_SA_DQ<22>")
	)
	(segment
		(start 405.902922 -227.500688)
		(end 406.236678 -227.834444)
		(width 0.14478)
		(layer "In2.Cu")
		(net "M_I_CPU0_SA_DQ<22>")
	)
	(segment
		(start 407.073354 -226.101656)
		(end 409.914852 -223.260158)
		(width 0.14478)
		(layer "In2.Cu")
		(net "M_I_CPU0_SA_DQ<22>")
	)
	(segment
		(start 406.45461 -226.7204)
		(end 406.68321 -226.7204)
		(width 0.14478)
		(layer "In2.Cu")
		(net "M_I_CPU0_SA_DQ<22>")
	)
	(segment
		(start 406.293066 -227.110544)
		(end 406.293066 -226.881944)
		(width 0.14478)
		(layer "In2.Cu")
		(net "M_I_CPU0_SA_DQ<22>")
	)
	(segment
		(start 403.895814 -230.175308)
		(end 404.124414 -230.175308)
		(width 0.14478)
		(layer "In2.Cu")
		(net "M_I_CPU0_SA_DQ<22>")
	)
	(segment
		(start 415.017966 -222.41002)
		(end 417.909756 -222.41002)
		(width 0.14478)
		(layer "In2.Cu")
		(net "M_I_CPU0_SA_DQ<22>")
	)
	(segment
		(start 383.497836 -238.491522)
		(end 383.506218 -238.486696)
		(width 0.0889)
		(layer "In2.Cu")
		(net "M_I_CPU0_SA_DQ<22>")
	)
	(arc
		(start 388.571994 -238.491522)
		(mid 388.85495 -238.567699)
		(end 389.137906 -238.491522)
		(width 0.0889)
		(layer "In2.Cu")
		(net "M_I_CPU0_SA_DQ<22>")
	)
	(arc
		(start 377.866148 -238.486696)
		(mid 378.049656 -238.441202)
		(end 378.231908 -238.491522)
		(width 0.0889)
		(layer "In2.Cu")
		(net "M_I_CPU0_SA_DQ<22>")
	)
	(arc
		(start 381.99187 -238.491522)
		(mid 382.274826 -238.567699)
		(end 382.557782 -238.491522)
		(width 0.0889)
		(layer "In2.Cu")
		(net "M_I_CPU0_SA_DQ<22>")
	)
	(arc
		(start 383.871978 -238.491522)
		(mid 384.154934 -238.567699)
		(end 384.43789 -238.491522)
		(width 0.0889)
		(layer "In2.Cu")
		(net "M_I_CPU0_SA_DQ<22>")
	)
	(arc
		(start 380.677674 -238.491522)
		(mid 380.859925 -238.441172)
		(end 381.043434 -238.486696)
		(width 0.0889)
		(layer "In2.Cu")
		(net "M_I_CPU0_SA_DQ<22>")
	)
	(arc
		(start 391.391902 -238.491522)
		(mid 391.536946 -238.550565)
		(end 391.692638 -238.567468)
		(width 0.0889)
		(layer "In2.Cu")
		(net "M_I_CPU0_SA_DQ<22>")
	)
	(arc
		(start 387.26618 -238.486696)
		(mid 387.449688 -238.441202)
		(end 387.63194 -238.491522)
		(width 0.0889)
		(layer "In2.Cu")
		(net "M_I_CPU0_SA_DQ<22>")
	)
	(arc
		(start 391.026142 -238.486696)
		(mid 391.20965 -238.441202)
		(end 391.391902 -238.491522)
		(width 0.0889)
		(layer "In2.Cu")
		(net "M_I_CPU0_SA_DQ<22>")
	)
	(arc
		(start 384.43789 -238.491522)
		(mid 384.624834 -238.441267)
		(end 384.811778 -238.491522)
		(width 0.0889)
		(layer "In2.Cu")
		(net "M_I_CPU0_SA_DQ<22>")
	)
	(arc
		(start 390.077706 -238.491522)
		(mid 390.259957 -238.441172)
		(end 390.443466 -238.486696)
		(width 0.0889)
		(layer "In2.Cu")
		(net "M_I_CPU0_SA_DQ<22>")
	)
	(arc
		(start 389.511794 -238.491522)
		(mid 389.79475 -238.567699)
		(end 390.077706 -238.491522)
		(width 0.0889)
		(layer "In2.Cu")
		(net "M_I_CPU0_SA_DQ<22>")
	)
	(arc
		(start 381.617728 -238.491522)
		(mid 381.799979 -238.441172)
		(end 381.983488 -238.486696)
		(width 0.0889)
		(layer "In2.Cu")
		(net "M_I_CPU0_SA_DQ<22>")
	)
	(arc
		(start 378.806202 -238.486696)
		(mid 378.98971 -238.441202)
		(end 379.171962 -238.491522)
		(width 0.0889)
		(layer "In2.Cu")
		(net "M_I_CPU0_SA_DQ<22>")
	)
	(arc
		(start 384.811778 -238.491522)
		(mid 385.094734 -238.567699)
		(end 385.37769 -238.491522)
		(width 0.0889)
		(layer "In2.Cu")
		(net "M_I_CPU0_SA_DQ<22>")
	)
	(arc
		(start 386.691886 -238.491522)
		(mid 386.974842 -238.567699)
		(end 387.257798 -238.491522)
		(width 0.0889)
		(layer "In2.Cu")
		(net "M_I_CPU0_SA_DQ<22>")
	)
	(arc
		(start 385.37769 -238.491522)
		(mid 385.559941 -238.441172)
		(end 385.74345 -238.486696)
		(width 0.0889)
		(layer "In2.Cu")
		(net "M_I_CPU0_SA_DQ<22>")
	)
	(arc
		(start 379.171962 -238.491522)
		(mid 379.454918 -238.567699)
		(end 379.737874 -238.491522)
		(width 0.0889)
		(layer "In2.Cu")
		(net "M_I_CPU0_SA_DQ<22>")
	)
	(arc
		(start 385.751832 -238.491522)
		(mid 386.034788 -238.567699)
		(end 386.317744 -238.491522)
		(width 0.0889)
		(layer "In2.Cu")
		(net "M_I_CPU0_SA_DQ<22>")
	)
	(arc
		(start 390.451848 -238.491522)
		(mid 390.734804 -238.567699)
		(end 391.01776 -238.491522)
		(width 0.0889)
		(layer "In2.Cu")
		(net "M_I_CPU0_SA_DQ<22>")
	)
	(arc
		(start 382.931924 -238.491522)
		(mid 383.21488 -238.567699)
		(end 383.497836 -238.491522)
		(width 0.0889)
		(layer "In2.Cu")
		(net "M_I_CPU0_SA_DQ<22>")
	)
	(arc
		(start 388.206234 -238.486696)
		(mid 388.389742 -238.441202)
		(end 388.571994 -238.491522)
		(width 0.0889)
		(layer "In2.Cu")
		(net "M_I_CPU0_SA_DQ<22>")
	)
	(arc
		(start 383.506218 -238.486696)
		(mid 383.689726 -238.441202)
		(end 383.871978 -238.491522)
		(width 0.0889)
		(layer "In2.Cu")
		(net "M_I_CPU0_SA_DQ<22>")
	)
	(arc
		(start 386.317744 -238.491522)
		(mid 386.499995 -238.441172)
		(end 386.683504 -238.486696)
		(width 0.0889)
		(layer "In2.Cu")
		(net "M_I_CPU0_SA_DQ<22>")
	)
	(arc
		(start 389.137906 -238.491522)
		(mid 389.32485 -238.441267)
		(end 389.511794 -238.491522)
		(width 0.0889)
		(layer "In2.Cu")
		(net "M_I_CPU0_SA_DQ<22>")
	)
	(arc
		(start 377.354846 -238.523272)
		(mid 377.610054 -238.566749)
		(end 377.857766 -238.491522)
		(width 0.0889)
		(layer "In2.Cu")
		(net "M_I_CPU0_SA_DQ<22>")
	)
	(arc
		(start 379.737874 -238.491522)
		(mid 379.924818 -238.441267)
		(end 380.111762 -238.491522)
		(width 0.0889)
		(layer "In2.Cu")
		(net "M_I_CPU0_SA_DQ<22>")
	)
	(arc
		(start 378.231908 -238.491522)
		(mid 378.514864 -238.567699)
		(end 378.79782 -238.491522)
		(width 0.0889)
		(layer "In2.Cu")
		(net "M_I_CPU0_SA_DQ<22>")
	)
	(arc
		(start 380.111762 -238.491522)
		(mid 380.394718 -238.567699)
		(end 380.677674 -238.491522)
		(width 0.0889)
		(layer "In2.Cu")
		(net "M_I_CPU0_SA_DQ<22>")
	)
	(arc
		(start 387.63194 -238.491522)
		(mid 387.914896 -238.567699)
		(end 388.197852 -238.491522)
		(width 0.0889)
		(layer "In2.Cu")
		(net "M_I_CPU0_SA_DQ<22>")
	)
	(arc
		(start 382.566164 -238.486696)
		(mid 382.749672 -238.441202)
		(end 382.931924 -238.491522)
		(width 0.0889)
		(layer "In2.Cu")
		(net "M_I_CPU0_SA_DQ<22>")
	)
	(arc
		(start 381.051816 -238.491522)
		(mid 381.334772 -238.567699)
		(end 381.617728 -238.491522)
		(width 0.0889)
		(layer "In2.Cu")
		(net "M_I_CPU0_SA_DQ<22>")
	)
	(segment
		(start 375.698004 -239.08004)
		(end 376.164856 -238.814102)
		(width 0.10668)
		(layer "F.Cu")
		(net "M_I_CPU0_SA_DQ<21>")
	)
	(segment
		(start 378.79782 -239.136682)
		(end 378.806202 -239.141508)
		(width 0.0889)
		(layer "In2.Cu")
		(net "M_I_CPU0_SA_DQ<21>")
	)
	(segment
		(start 414.814766 -223.260158)
		(end 418.089842 -223.260158)
		(width 0.14478)
		(layer "In2.Cu")
		(net "M_I_CPU0_SA_DQ<21>")
	)
	(segment
		(start 418.939726 -224.110042)
		(end 421.730932 -224.110042)
		(width 0.14478)
		(layer "In2.Cu")
		(net "M_I_CPU0_SA_DQ<21>")
	)
	(segment
		(start 377.857766 -239.136682)
		(end 377.866148 -239.141508)
		(width 0.0889)
		(layer "In2.Cu")
		(net "M_I_CPU0_SA_DQ<21>")
	)
	(segment
		(start 393.457176 -238.45393)
		(end 394.272516 -237.63859)
		(width 0.0889)
		(layer "In2.Cu")
		(net "M_I_CPU0_SA_DQ<21>")
	)
	(segment
		(start 421.730932 -224.110042)
		(end 422.580816 -223.260158)
		(width 0.14478)
		(layer "In2.Cu")
		(net "M_I_CPU0_SA_DQ<21>")
	)
	(segment
		(start 431.131218 -223.260158)
		(end 431.55616 -223.6851)
		(width 0.14478)
		(layer "In2.Cu")
		(net "M_I_CPU0_SA_DQ<21>")
	)
	(segment
		(start 422.580816 -223.260158)
		(end 429.331374 -223.260158)
		(width 0.14478)
		(layer "In2.Cu")
		(net "M_I_CPU0_SA_DQ<21>")
	)
	(segment
		(start 381.043434 -239.141508)
		(end 381.051816 -239.136682)
		(width 0.0889)
		(layer "In2.Cu")
		(net "M_I_CPU0_SA_DQ<21>")
	)
	(segment
		(start 429.494188 -223.697038)
		(end 429.657002 -223.859852)
		(width 0.14478)
		(layer "In2.Cu")
		(net "M_I_CPU0_SA_DQ<21>")
	)
	(segment
		(start 429.331374 -223.260158)
		(end 429.494188 -223.422972)
		(width 0.14478)
		(layer "In2.Cu")
		(net "M_I_CPU0_SA_DQ<21>")
	)
	(segment
		(start 390.443466 -239.141508)
		(end 390.451848 -239.136682)
		(width 0.0889)
		(layer "In2.Cu")
		(net "M_I_CPU0_SA_DQ<21>")
	)
	(segment
		(start 430.050448 -223.697038)
		(end 430.050448 -223.422972)
		(width 0.14478)
		(layer "In2.Cu")
		(net "M_I_CPU0_SA_DQ<21>")
	)
	(segment
		(start 429.657002 -223.859852)
		(end 429.887634 -223.859852)
		(width 0.14478)
		(layer "In2.Cu")
		(net "M_I_CPU0_SA_DQ<21>")
	)
	(segment
		(start 386.683504 -239.141508)
		(end 386.691886 -239.136682)
		(width 0.0889)
		(layer "In2.Cu")
		(net "M_I_CPU0_SA_DQ<21>")
	)
	(segment
		(start 392.33221 -239.060736)
		(end 392.939016 -238.45393)
		(width 0.0889)
		(layer "In2.Cu")
		(net "M_I_CPU0_SA_DQ<21>")
	)
	(segment
		(start 418.089842 -223.260158)
		(end 418.939726 -224.110042)
		(width 0.14478)
		(layer "In2.Cu")
		(net "M_I_CPU0_SA_DQ<21>")
	)
	(segment
		(start 430.213262 -223.260158)
		(end 431.131218 -223.260158)
		(width 0.14478)
		(layer "In2.Cu")
		(net "M_I_CPU0_SA_DQ<21>")
	)
	(segment
		(start 391.692638 -239.060736)
		(end 392.33221 -239.060736)
		(width 0.0889)
		(layer "In2.Cu")
		(net "M_I_CPU0_SA_DQ<21>")
	)
	(segment
		(start 407.900378 -227.03536)
		(end 407.900378 -225.927412)
		(width 0.14478)
		(layer "In2.Cu")
		(net "M_I_CPU0_SA_DQ<21>")
	)
	(segment
		(start 429.494188 -223.422972)
		(end 429.494188 -223.697038)
		(width 0.14478)
		(layer "In2.Cu")
		(net "M_I_CPU0_SA_DQ<21>")
	)
	(segment
		(start 381.983488 -239.141508)
		(end 381.99187 -239.136682)
		(width 0.0889)
		(layer "In2.Cu")
		(net "M_I_CPU0_SA_DQ<21>")
	)
	(segment
		(start 388.197852 -239.136682)
		(end 388.206234 -239.141508)
		(width 0.0889)
		(layer "In2.Cu")
		(net "M_I_CPU0_SA_DQ<21>")
	)
	(segment
		(start 376.343418 -239.141508)
		(end 376.3518 -239.136682)
		(width 0.0889)
		(layer "In2.Cu")
		(net "M_I_CPU0_SA_DQ<21>")
	)
	(segment
		(start 394.272516 -237.63859)
		(end 394.986256 -237.63859)
		(width 0.0889)
		(layer "In2.Cu")
		(net "M_I_CPU0_SA_DQ<21>")
	)
	(segment
		(start 376.164856 -238.814102)
		(end 376.010678 -239.079532)
		(width 0.0889)
		(layer "In2.Cu")
		(net "M_I_CPU0_SA_DQ<21>")
	)
	(segment
		(start 407.900378 -225.927412)
		(end 409.717748 -224.110042)
		(width 0.14478)
		(layer "In2.Cu")
		(net "M_I_CPU0_SA_DQ<21>")
	)
	(segment
		(start 385.74345 -239.141508)
		(end 385.751832 -239.136682)
		(width 0.0889)
		(layer "In2.Cu")
		(net "M_I_CPU0_SA_DQ<21>")
	)
	(segment
		(start 383.497836 -239.136682)
		(end 383.506218 -239.141508)
		(width 0.0889)
		(layer "In2.Cu")
		(net "M_I_CPU0_SA_DQ<21>")
	)
	(segment
		(start 387.257798 -239.136682)
		(end 387.26618 -239.141508)
		(width 0.0889)
		(layer "In2.Cu")
		(net "M_I_CPU0_SA_DQ<21>")
	)
	(segment
		(start 376.010678 -239.079532)
		(end 376.03303 -239.162844)
		(width 0.0889)
		(layer "In2.Cu")
		(net "M_I_CPU0_SA_DQ<21>")
	)
	(segment
		(start 429.887634 -223.859852)
		(end 430.050448 -223.697038)
		(width 0.14478)
		(layer "In2.Cu")
		(net "M_I_CPU0_SA_DQ<21>")
	)
	(segment
		(start 395.550136 -237.07471)
		(end 395.884654 -237.07471)
		(width 0.0889)
		(layer "In2.Cu")
		(net "M_I_CPU0_SA_DQ<21>")
	)
	(segment
		(start 395.884654 -237.07471)
		(end 397.861028 -237.07471)
		(width 0.14478)
		(layer "In2.Cu")
		(net "M_I_CPU0_SA_DQ<21>")
	)
	(segment
		(start 397.861028 -237.07471)
		(end 407.900378 -227.03536)
		(width 0.14478)
		(layer "In2.Cu")
		(net "M_I_CPU0_SA_DQ<21>")
	)
	(segment
		(start 409.717748 -224.110042)
		(end 413.964882 -224.110042)
		(width 0.14478)
		(layer "In2.Cu")
		(net "M_I_CPU0_SA_DQ<21>")
	)
	(segment
		(start 377.283472 -239.141508)
		(end 377.291854 -239.136682)
		(width 0.0889)
		(layer "In2.Cu")
		(net "M_I_CPU0_SA_DQ<21>")
	)
	(segment
		(start 382.557782 -239.136682)
		(end 382.566164 -239.141508)
		(width 0.0889)
		(layer "In2.Cu")
		(net "M_I_CPU0_SA_DQ<21>")
	)
	(segment
		(start 392.939016 -238.45393)
		(end 393.457176 -238.45393)
		(width 0.0889)
		(layer "In2.Cu")
		(net "M_I_CPU0_SA_DQ<21>")
	)
	(segment
		(start 413.964882 -224.110042)
		(end 414.814766 -223.260158)
		(width 0.14478)
		(layer "In2.Cu")
		(net "M_I_CPU0_SA_DQ<21>")
	)
	(segment
		(start 430.050448 -223.422972)
		(end 430.213262 -223.260158)
		(width 0.14478)
		(layer "In2.Cu")
		(net "M_I_CPU0_SA_DQ<21>")
	)
	(segment
		(start 391.01776 -239.136682)
		(end 391.026142 -239.141508)
		(width 0.0889)
		(layer "In2.Cu")
		(net "M_I_CPU0_SA_DQ<21>")
	)
	(segment
		(start 394.986256 -237.63859)
		(end 395.550136 -237.07471)
		(width 0.0889)
		(layer "In2.Cu")
		(net "M_I_CPU0_SA_DQ<21>")
	)
	(arc
		(start 388.206234 -239.141508)
		(mid 388.389742 -239.187002)
		(end 388.571994 -239.136682)
		(width 0.0889)
		(layer "In2.Cu")
		(net "M_I_CPU0_SA_DQ<21>")
	)
	(arc
		(start 379.737874 -239.136682)
		(mid 379.924818 -239.186937)
		(end 380.111762 -239.136682)
		(width 0.0889)
		(layer "In2.Cu")
		(net "M_I_CPU0_SA_DQ<21>")
	)
	(arc
		(start 385.751832 -239.136682)
		(mid 386.034788 -239.060505)
		(end 386.317744 -239.136682)
		(width 0.0889)
		(layer "In2.Cu")
		(net "M_I_CPU0_SA_DQ<21>")
	)
	(arc
		(start 384.811778 -239.136682)
		(mid 385.094734 -239.060505)
		(end 385.37769 -239.136682)
		(width 0.0889)
		(layer "In2.Cu")
		(net "M_I_CPU0_SA_DQ<21>")
	)
	(arc
		(start 382.931924 -239.136682)
		(mid 383.21488 -239.060505)
		(end 383.497836 -239.136682)
		(width 0.0889)
		(layer "In2.Cu")
		(net "M_I_CPU0_SA_DQ<21>")
	)
	(arc
		(start 380.677674 -239.136682)
		(mid 380.859925 -239.187032)
		(end 381.043434 -239.141508)
		(width 0.0889)
		(layer "In2.Cu")
		(net "M_I_CPU0_SA_DQ<21>")
	)
	(arc
		(start 380.111762 -239.136682)
		(mid 380.394718 -239.060505)
		(end 380.677674 -239.136682)
		(width 0.0889)
		(layer "In2.Cu")
		(net "M_I_CPU0_SA_DQ<21>")
	)
	(arc
		(start 390.077706 -239.136682)
		(mid 390.259957 -239.187032)
		(end 390.443466 -239.141508)
		(width 0.0889)
		(layer "In2.Cu")
		(net "M_I_CPU0_SA_DQ<21>")
	)
	(arc
		(start 378.231908 -239.136682)
		(mid 378.514864 -239.060505)
		(end 378.79782 -239.136682)
		(width 0.0889)
		(layer "In2.Cu")
		(net "M_I_CPU0_SA_DQ<21>")
	)
	(arc
		(start 391.391902 -239.136682)
		(mid 391.536946 -239.077639)
		(end 391.692638 -239.060736)
		(width 0.0889)
		(layer "In2.Cu")
		(net "M_I_CPU0_SA_DQ<21>")
	)
	(arc
		(start 382.566164 -239.141508)
		(mid 382.749672 -239.187002)
		(end 382.931924 -239.136682)
		(width 0.0889)
		(layer "In2.Cu")
		(net "M_I_CPU0_SA_DQ<21>")
	)
	(arc
		(start 385.37769 -239.136682)
		(mid 385.559941 -239.187032)
		(end 385.74345 -239.141508)
		(width 0.0889)
		(layer "In2.Cu")
		(net "M_I_CPU0_SA_DQ<21>")
	)
	(arc
		(start 386.691886 -239.136682)
		(mid 386.974842 -239.060505)
		(end 387.257798 -239.136682)
		(width 0.0889)
		(layer "In2.Cu")
		(net "M_I_CPU0_SA_DQ<21>")
	)
	(arc
		(start 388.571994 -239.136682)
		(mid 388.85495 -239.060505)
		(end 389.137906 -239.136682)
		(width 0.0889)
		(layer "In2.Cu")
		(net "M_I_CPU0_SA_DQ<21>")
	)
	(arc
		(start 377.291854 -239.136682)
		(mid 377.57481 -239.060505)
		(end 377.857766 -239.136682)
		(width 0.0889)
		(layer "In2.Cu")
		(net "M_I_CPU0_SA_DQ<21>")
	)
	(arc
		(start 384.43789 -239.136682)
		(mid 384.624834 -239.186937)
		(end 384.811778 -239.136682)
		(width 0.0889)
		(layer "In2.Cu")
		(net "M_I_CPU0_SA_DQ<21>")
	)
	(arc
		(start 391.026142 -239.141508)
		(mid 391.20965 -239.187002)
		(end 391.391902 -239.136682)
		(width 0.0889)
		(layer "In2.Cu")
		(net "M_I_CPU0_SA_DQ<21>")
	)
	(arc
		(start 386.317744 -239.136682)
		(mid 386.499995 -239.187032)
		(end 386.683504 -239.141508)
		(width 0.0889)
		(layer "In2.Cu")
		(net "M_I_CPU0_SA_DQ<21>")
	)
	(arc
		(start 376.917712 -239.136682)
		(mid 377.099963 -239.187032)
		(end 377.283472 -239.141508)
		(width 0.0889)
		(layer "In2.Cu")
		(net "M_I_CPU0_SA_DQ<21>")
	)
	(arc
		(start 377.866148 -239.141508)
		(mid 378.049656 -239.187002)
		(end 378.231908 -239.136682)
		(width 0.0889)
		(layer "In2.Cu")
		(net "M_I_CPU0_SA_DQ<21>")
	)
	(arc
		(start 379.171962 -239.136682)
		(mid 379.454918 -239.060505)
		(end 379.737874 -239.136682)
		(width 0.0889)
		(layer "In2.Cu")
		(net "M_I_CPU0_SA_DQ<21>")
	)
	(arc
		(start 378.806202 -239.141508)
		(mid 378.98971 -239.187002)
		(end 379.171962 -239.136682)
		(width 0.0889)
		(layer "In2.Cu")
		(net "M_I_CPU0_SA_DQ<21>")
	)
	(arc
		(start 389.511794 -239.136682)
		(mid 389.79475 -239.060505)
		(end 390.077706 -239.136682)
		(width 0.0889)
		(layer "In2.Cu")
		(net "M_I_CPU0_SA_DQ<21>")
	)
	(arc
		(start 383.871978 -239.136682)
		(mid 384.154934 -239.060505)
		(end 384.43789 -239.136682)
		(width 0.0889)
		(layer "In2.Cu")
		(net "M_I_CPU0_SA_DQ<21>")
	)
	(arc
		(start 387.63194 -239.136682)
		(mid 387.914896 -239.060505)
		(end 388.197852 -239.136682)
		(width 0.0889)
		(layer "In2.Cu")
		(net "M_I_CPU0_SA_DQ<21>")
	)
	(arc
		(start 390.451848 -239.136682)
		(mid 390.734804 -239.060505)
		(end 391.01776 -239.136682)
		(width 0.0889)
		(layer "In2.Cu")
		(net "M_I_CPU0_SA_DQ<21>")
	)
	(arc
		(start 389.137906 -239.136682)
		(mid 389.32485 -239.186937)
		(end 389.511794 -239.136682)
		(width 0.0889)
		(layer "In2.Cu")
		(net "M_I_CPU0_SA_DQ<21>")
	)
	(arc
		(start 381.99187 -239.136682)
		(mid 382.274826 -239.060505)
		(end 382.557782 -239.136682)
		(width 0.0889)
		(layer "In2.Cu")
		(net "M_I_CPU0_SA_DQ<21>")
	)
	(arc
		(start 387.26618 -239.141508)
		(mid 387.449688 -239.187002)
		(end 387.63194 -239.136682)
		(width 0.0889)
		(layer "In2.Cu")
		(net "M_I_CPU0_SA_DQ<21>")
	)
	(arc
		(start 376.03303 -239.162844)
		(mid 376.19054 -239.186042)
		(end 376.343418 -239.141508)
		(width 0.0889)
		(layer "In2.Cu")
		(net "M_I_CPU0_SA_DQ<21>")
	)
	(arc
		(start 381.617728 -239.136682)
		(mid 381.799979 -239.187032)
		(end 381.983488 -239.141508)
		(width 0.0889)
		(layer "In2.Cu")
		(net "M_I_CPU0_SA_DQ<21>")
	)
	(arc
		(start 381.051816 -239.136682)
		(mid 381.334772 -239.060505)
		(end 381.617728 -239.136682)
		(width 0.0889)
		(layer "In2.Cu")
		(net "M_I_CPU0_SA_DQ<21>")
	)
	(arc
		(start 376.3518 -239.136682)
		(mid 376.634756 -239.060505)
		(end 376.917712 -239.136682)
		(width 0.0889)
		(layer "In2.Cu")
		(net "M_I_CPU0_SA_DQ<21>")
	)
	(arc
		(start 383.506218 -239.141508)
		(mid 383.689726 -239.187002)
		(end 383.871978 -239.136682)
		(width 0.0889)
		(layer "In2.Cu")
		(net "M_I_CPU0_SA_DQ<21>")
	)
	(segment
		(start 377.107958 -238.270034)
		(end 377.57481 -238.004096)
		(width 0.10668)
		(layer "F.Cu")
		(net "M_I_CPU0_SA_DQ<20>")
	)
	(segment
		(start 397.500602 -236.16285)
		(end 402.687282 -230.97617)
		(width 0.14478)
		(layer "In2.Cu")
		(net "M_I_CPU0_SA_DQ<20>")
	)
	(segment
		(start 394.737336 -237.10519)
		(end 395.306296 -236.53623)
		(width 0.0889)
		(layer "In2.Cu")
		(net "M_I_CPU0_SA_DQ<20>")
	)
	(segment
		(start 429.595788 -222.459296)
		(end 429.758602 -222.62211)
		(width 0.14478)
		(layer "In2.Cu")
		(net "M_I_CPU0_SA_DQ<20>")
	)
	(segment
		(start 389.033512 -238.331502)
		(end 389.041894 -238.326676)
		(width 0.0889)
		(layer "In2.Cu")
		(net "M_I_CPU0_SA_DQ<20>")
	)
	(segment
		(start 392.302492 -238.325914)
		(end 392.664696 -237.96371)
		(width 0.0889)
		(layer "In2.Cu")
		(net "M_I_CPU0_SA_DQ<20>")
	)
	(segment
		(start 395.306296 -236.40669)
		(end 395.550136 -236.16285)
		(width 0.0889)
		(layer "In2.Cu")
		(net "M_I_CPU0_SA_DQ<20>")
	)
	(segment
		(start 430.314862 -221.560136)
		(end 431.131218 -221.560136)
		(width 0.14478)
		(layer "In2.Cu")
		(net "M_I_CPU0_SA_DQ<20>")
	)
	(segment
		(start 389.607806 -238.326676)
		(end 389.616188 -238.331502)
		(width 0.0889)
		(layer "In2.Cu")
		(net "M_I_CPU0_SA_DQ<20>")
	)
	(segment
		(start 402.687282 -229.838758)
		(end 410.106368 -222.419672)
		(width 0.14478)
		(layer "In2.Cu")
		(net "M_I_CPU0_SA_DQ<20>")
	)
	(segment
		(start 415.110422 -221.569788)
		(end 417.774882 -221.569788)
		(width 0.14478)
		(layer "In2.Cu")
		(net "M_I_CPU0_SA_DQ<20>")
	)
	(segment
		(start 395.550136 -236.16285)
		(end 395.859254 -236.16285)
		(width 0.0889)
		(layer "In2.Cu")
		(net "M_I_CPU0_SA_DQ<20>")
	)
	(segment
		(start 429.442626 -221.569788)
		(end 429.595788 -221.72295)
		(width 0.14478)
		(layer "In2.Cu")
		(net "M_I_CPU0_SA_DQ<20>")
	)
	(segment
		(start 414.260538 -222.419672)
		(end 415.110422 -221.569788)
		(width 0.14478)
		(layer "In2.Cu")
		(net "M_I_CPU0_SA_DQ<20>")
	)
	(segment
		(start 410.106368 -222.419672)
		(end 414.260538 -222.419672)
		(width 0.14478)
		(layer "In2.Cu")
		(net "M_I_CPU0_SA_DQ<20>")
	)
	(segment
		(start 381.147828 -238.326676)
		(end 381.15621 -238.331502)
		(width 0.0889)
		(layer "In2.Cu")
		(net "M_I_CPU0_SA_DQ<20>")
	)
	(segment
		(start 421.583358 -222.419672)
		(end 422.433242 -221.569788)
		(width 0.14478)
		(layer "In2.Cu")
		(net "M_I_CPU0_SA_DQ<20>")
	)
	(segment
		(start 392.969496 -237.96371)
		(end 393.828016 -237.10519)
		(width 0.0889)
		(layer "In2.Cu")
		(net "M_I_CPU0_SA_DQ<20>")
	)
	(segment
		(start 380.207774 -238.326676)
		(end 380.216156 -238.331502)
		(width 0.0889)
		(layer "In2.Cu")
		(net "M_I_CPU0_SA_DQ<20>")
	)
	(segment
		(start 393.828016 -237.10519)
		(end 394.737336 -237.10519)
		(width 0.0889)
		(layer "In2.Cu")
		(net "M_I_CPU0_SA_DQ<20>")
	)
	(segment
		(start 395.859254 -236.16285)
		(end 397.500602 -236.16285)
		(width 0.14478)
		(layer "In2.Cu")
		(net "M_I_CPU0_SA_DQ<20>")
	)
	(segment
		(start 402.687282 -230.97617)
		(end 402.687282 -229.838758)
		(width 0.14478)
		(layer "In2.Cu")
		(net "M_I_CPU0_SA_DQ<20>")
	)
	(segment
		(start 429.595788 -221.72295)
		(end 429.595788 -222.459296)
		(width 0.14478)
		(layer "In2.Cu")
		(net "M_I_CPU0_SA_DQ<20>")
	)
	(segment
		(start 392.664696 -237.96371)
		(end 392.969496 -237.96371)
		(width 0.0889)
		(layer "In2.Cu")
		(net "M_I_CPU0_SA_DQ<20>")
	)
	(segment
		(start 418.624766 -222.419672)
		(end 421.583358 -222.419672)
		(width 0.14478)
		(layer "In2.Cu")
		(net "M_I_CPU0_SA_DQ<20>")
	)
	(segment
		(start 417.774882 -221.569788)
		(end 418.624766 -222.419672)
		(width 0.14478)
		(layer "In2.Cu")
		(net "M_I_CPU0_SA_DQ<20>")
	)
	(segment
		(start 429.758602 -222.62211)
		(end 429.989234 -222.62211)
		(width 0.14478)
		(layer "In2.Cu")
		(net "M_I_CPU0_SA_DQ<20>")
	)
	(segment
		(start 384.90779 -238.326676)
		(end 384.916172 -238.331502)
		(width 0.0889)
		(layer "In2.Cu")
		(net "M_I_CPU0_SA_DQ<20>")
	)
	(segment
		(start 430.152048 -222.459296)
		(end 430.152048 -221.72295)
		(width 0.14478)
		(layer "In2.Cu")
		(net "M_I_CPU0_SA_DQ<20>")
	)
	(segment
		(start 430.152048 -221.72295)
		(end 430.314862 -221.560136)
		(width 0.14478)
		(layer "In2.Cu")
		(net "M_I_CPU0_SA_DQ<20>")
	)
	(segment
		(start 391.85342 -238.331502)
		(end 391.861802 -238.326676)
		(width 0.0889)
		(layer "In2.Cu")
		(net "M_I_CPU0_SA_DQ<20>")
	)
	(segment
		(start 388.093458 -238.331502)
		(end 388.10184 -238.326676)
		(width 0.0889)
		(layer "In2.Cu")
		(net "M_I_CPU0_SA_DQ<20>")
	)
	(segment
		(start 422.433242 -221.569788)
		(end 429.442626 -221.569788)
		(width 0.14478)
		(layer "In2.Cu")
		(net "M_I_CPU0_SA_DQ<20>")
	)
	(segment
		(start 395.306296 -236.53623)
		(end 395.306296 -236.40669)
		(width 0.0889)
		(layer "In2.Cu")
		(net "M_I_CPU0_SA_DQ<20>")
	)
	(segment
		(start 383.393442 -238.331502)
		(end 383.401824 -238.326676)
		(width 0.0889)
		(layer "In2.Cu")
		(net "M_I_CPU0_SA_DQ<20>")
	)
	(segment
		(start 431.131218 -221.560136)
		(end 431.55616 -221.985078)
		(width 0.14478)
		(layer "In2.Cu")
		(net "M_I_CPU0_SA_DQ<20>")
	)
	(segment
		(start 391.861802 -238.326676)
		(end 392.302492 -238.325914)
		(width 0.0889)
		(layer "In2.Cu")
		(net "M_I_CPU0_SA_DQ<20>")
	)
	(segment
		(start 384.333496 -238.331502)
		(end 384.341878 -238.326676)
		(width 0.0889)
		(layer "In2.Cu")
		(net "M_I_CPU0_SA_DQ<20>")
	)
	(segment
		(start 385.847844 -238.326676)
		(end 385.856226 -238.331502)
		(width 0.0889)
		(layer "In2.Cu")
		(net "M_I_CPU0_SA_DQ<20>")
	)
	(segment
		(start 429.989234 -222.62211)
		(end 430.152048 -222.459296)
		(width 0.14478)
		(layer "In2.Cu")
		(net "M_I_CPU0_SA_DQ<20>")
	)
	(segment
		(start 377.57481 -238.004096)
		(end 377.420886 -238.269526)
		(width 0.0889)
		(layer "In2.Cu")
		(net "M_I_CPU0_SA_DQ<20>")
	)
	(segment
		(start 378.693426 -238.331502)
		(end 378.701808 -238.326676)
		(width 0.0889)
		(layer "In2.Cu")
		(net "M_I_CPU0_SA_DQ<20>")
	)
	(segment
		(start 379.63348 -238.331502)
		(end 379.641862 -238.326676)
		(width 0.0889)
		(layer "In2.Cu")
		(net "M_I_CPU0_SA_DQ<20>")
	)
	(segment
		(start 377.420886 -238.269526)
		(end 377.443238 -238.352838)
		(width 0.0889)
		(layer "In2.Cu")
		(net "M_I_CPU0_SA_DQ<20>")
	)
	(arc
		(start 383.401824 -238.326676)
		(mid 383.68478 -238.250499)
		(end 383.967736 -238.326676)
		(width 0.0889)
		(layer "In2.Cu")
		(net "M_I_CPU0_SA_DQ<20>")
	)
	(arc
		(start 378.701808 -238.326676)
		(mid 378.984764 -238.250499)
		(end 379.26772 -238.326676)
		(width 0.0889)
		(layer "In2.Cu")
		(net "M_I_CPU0_SA_DQ<20>")
	)
	(arc
		(start 387.727698 -238.326676)
		(mid 387.909949 -238.377026)
		(end 388.093458 -238.331502)
		(width 0.0889)
		(layer "In2.Cu")
		(net "M_I_CPU0_SA_DQ<20>")
	)
	(arc
		(start 391.48766 -238.326676)
		(mid 391.669911 -238.377026)
		(end 391.85342 -238.331502)
		(width 0.0889)
		(layer "In2.Cu")
		(net "M_I_CPU0_SA_DQ<20>")
	)
	(arc
		(start 378.327666 -238.326676)
		(mid 378.509917 -238.377026)
		(end 378.693426 -238.331502)
		(width 0.0889)
		(layer "In2.Cu")
		(net "M_I_CPU0_SA_DQ<20>")
	)
	(arc
		(start 385.281932 -238.326676)
		(mid 385.564888 -238.250499)
		(end 385.847844 -238.326676)
		(width 0.0889)
		(layer "In2.Cu")
		(net "M_I_CPU0_SA_DQ<20>")
	)
	(arc
		(start 381.52197 -238.326676)
		(mid 381.804926 -238.250499)
		(end 382.087882 -238.326676)
		(width 0.0889)
		(layer "In2.Cu")
		(net "M_I_CPU0_SA_DQ<20>")
	)
	(arc
		(start 384.341878 -238.326676)
		(mid 384.624834 -238.250499)
		(end 384.90779 -238.326676)
		(width 0.0889)
		(layer "In2.Cu")
		(net "M_I_CPU0_SA_DQ<20>")
	)
	(arc
		(start 387.161786 -238.326676)
		(mid 387.444742 -238.250499)
		(end 387.727698 -238.326676)
		(width 0.0889)
		(layer "In2.Cu")
		(net "M_I_CPU0_SA_DQ<20>")
	)
	(arc
		(start 389.041894 -238.326676)
		(mid 389.32485 -238.250499)
		(end 389.607806 -238.326676)
		(width 0.0889)
		(layer "In2.Cu")
		(net "M_I_CPU0_SA_DQ<20>")
	)
	(arc
		(start 384.916172 -238.331502)
		(mid 385.09968 -238.376996)
		(end 385.281932 -238.326676)
		(width 0.0889)
		(layer "In2.Cu")
		(net "M_I_CPU0_SA_DQ<20>")
	)
	(arc
		(start 389.981948 -238.326676)
		(mid 390.264904 -238.250499)
		(end 390.54786 -238.326676)
		(width 0.0889)
		(layer "In2.Cu")
		(net "M_I_CPU0_SA_DQ<20>")
	)
	(arc
		(start 382.46177 -238.326676)
		(mid 382.744726 -238.250499)
		(end 383.027682 -238.326676)
		(width 0.0889)
		(layer "In2.Cu")
		(net "M_I_CPU0_SA_DQ<20>")
	)
	(arc
		(start 385.856226 -238.331502)
		(mid 386.039734 -238.376996)
		(end 386.221986 -238.326676)
		(width 0.0889)
		(layer "In2.Cu")
		(net "M_I_CPU0_SA_DQ<20>")
	)
	(arc
		(start 388.667752 -238.326676)
		(mid 388.850003 -238.377026)
		(end 389.033512 -238.331502)
		(width 0.0889)
		(layer "In2.Cu")
		(net "M_I_CPU0_SA_DQ<20>")
	)
	(arc
		(start 380.581916 -238.326676)
		(mid 380.864872 -238.250499)
		(end 381.147828 -238.326676)
		(width 0.0889)
		(layer "In2.Cu")
		(net "M_I_CPU0_SA_DQ<20>")
	)
	(arc
		(start 380.216156 -238.331502)
		(mid 380.399664 -238.376996)
		(end 380.581916 -238.326676)
		(width 0.0889)
		(layer "In2.Cu")
		(net "M_I_CPU0_SA_DQ<20>")
	)
	(arc
		(start 382.087882 -238.326676)
		(mid 382.274826 -238.376931)
		(end 382.46177 -238.326676)
		(width 0.0889)
		(layer "In2.Cu")
		(net "M_I_CPU0_SA_DQ<20>")
	)
	(arc
		(start 386.221986 -238.326676)
		(mid 386.504942 -238.250499)
		(end 386.787898 -238.326676)
		(width 0.0889)
		(layer "In2.Cu")
		(net "M_I_CPU0_SA_DQ<20>")
	)
	(arc
		(start 383.967736 -238.326676)
		(mid 384.149987 -238.377026)
		(end 384.333496 -238.331502)
		(width 0.0889)
		(layer "In2.Cu")
		(net "M_I_CPU0_SA_DQ<20>")
	)
	(arc
		(start 386.787898 -238.326676)
		(mid 386.974842 -238.376931)
		(end 387.161786 -238.326676)
		(width 0.0889)
		(layer "In2.Cu")
		(net "M_I_CPU0_SA_DQ<20>")
	)
	(arc
		(start 383.027682 -238.326676)
		(mid 383.209933 -238.377026)
		(end 383.393442 -238.331502)
		(width 0.0889)
		(layer "In2.Cu")
		(net "M_I_CPU0_SA_DQ<20>")
	)
	(arc
		(start 379.26772 -238.326676)
		(mid 379.449971 -238.377026)
		(end 379.63348 -238.331502)
		(width 0.0889)
		(layer "In2.Cu")
		(net "M_I_CPU0_SA_DQ<20>")
	)
	(arc
		(start 377.761754 -238.326676)
		(mid 378.04471 -238.250499)
		(end 378.327666 -238.326676)
		(width 0.0889)
		(layer "In2.Cu")
		(net "M_I_CPU0_SA_DQ<20>")
	)
	(arc
		(start 388.10184 -238.326676)
		(mid 388.384796 -238.250499)
		(end 388.667752 -238.326676)
		(width 0.0889)
		(layer "In2.Cu")
		(net "M_I_CPU0_SA_DQ<20>")
	)
	(arc
		(start 390.54786 -238.326676)
		(mid 390.734804 -238.376931)
		(end 390.921748 -238.326676)
		(width 0.0889)
		(layer "In2.Cu")
		(net "M_I_CPU0_SA_DQ<20>")
	)
	(arc
		(start 381.15621 -238.331502)
		(mid 381.339718 -238.376996)
		(end 381.52197 -238.326676)
		(width 0.0889)
		(layer "In2.Cu")
		(net "M_I_CPU0_SA_DQ<20>")
	)
	(arc
		(start 389.616188 -238.331502)
		(mid 389.799696 -238.376996)
		(end 389.981948 -238.326676)
		(width 0.0889)
		(layer "In2.Cu")
		(net "M_I_CPU0_SA_DQ<20>")
	)
	(arc
		(start 379.641862 -238.326676)
		(mid 379.924818 -238.250499)
		(end 380.207774 -238.326676)
		(width 0.0889)
		(layer "In2.Cu")
		(net "M_I_CPU0_SA_DQ<20>")
	)
	(arc
		(start 377.443238 -238.352838)
		(mid 377.605427 -238.375573)
		(end 377.761754 -238.326676)
		(width 0.0889)
		(layer "In2.Cu")
		(net "M_I_CPU0_SA_DQ<20>")
	)
	(arc
		(start 390.921748 -238.326676)
		(mid 391.204704 -238.250499)
		(end 391.48766 -238.326676)
		(width 0.0889)
		(layer "In2.Cu")
		(net "M_I_CPU0_SA_DQ<20>")
	)
	(segment
		(start 375.698004 -226.120198)
		(end 376.164856 -225.85426)
		(width 0.10668)
		(layer "F.Cu")
		(net "M_I_CPU0_SA_DQ<1>")
	)
	(segment
		(start 377.857766 -226.17684)
		(end 377.866148 -226.181666)
		(width 0.0889)
		(layer "In2.Cu")
		(net "M_I_CPU0_SA_DQ<1>")
	)
	(segment
		(start 402.91385 -205.071218)
		(end 402.91385 -204.311758)
		(width 0.14478)
		(layer "In2.Cu")
		(net "M_I_CPU0_SA_DQ<1>")
	)
	(segment
		(start 395.959076 -213.359492)
		(end 395.959076 -212.025992)
		(width 0.14478)
		(layer "In2.Cu")
		(net "M_I_CPU0_SA_DQ<1>")
	)
	(segment
		(start 376.164856 -225.85426)
		(end 376.010678 -226.11969)
		(width 0.0889)
		(layer "In2.Cu")
		(net "M_I_CPU0_SA_DQ<1>")
	)
	(segment
		(start 389.700008 -222.415862)
		(end 390.026398 -221.196408)
		(width 0.0889)
		(layer "In2.Cu")
		(net "M_I_CPU0_SA_DQ<1>")
	)
	(segment
		(start 388.062724 -225.389694)
		(end 388.10184 -225.366834)
		(width 0.0889)
		(layer "In2.Cu")
		(net "M_I_CPU0_SA_DQ<1>")
	)
	(segment
		(start 413.839914 -199.460104)
		(end 415.111692 -198.61022)
		(width 0.14478)
		(layer "In2.Cu")
		(net "M_I_CPU0_SA_DQ<1>")
	)
	(segment
		(start 381.983488 -226.181666)
		(end 381.99187 -226.17684)
		(width 0.0889)
		(layer "In2.Cu")
		(net "M_I_CPU0_SA_DQ<1>")
	)
	(segment
		(start 388.572248 -224.556828)
		(end 388.601712 -224.53981)
		(width 0.0889)
		(layer "In2.Cu")
		(net "M_I_CPU0_SA_DQ<1>")
	)
	(segment
		(start 389.512302 -222.936816)
		(end 389.546084 -222.917258)
		(width 0.0889)
		(layer "In2.Cu")
		(net "M_I_CPU0_SA_DQ<1>")
	)
	(segment
		(start 422.604438 -198.61022)
		(end 431.131218 -198.61022)
		(width 0.14478)
		(layer "In2.Cu")
		(net "M_I_CPU0_SA_DQ<1>")
	)
	(segment
		(start 376.343418 -226.181666)
		(end 376.3518 -226.17684)
		(width 0.0889)
		(layer "In2.Cu")
		(net "M_I_CPU0_SA_DQ<1>")
	)
	(segment
		(start 389.004302 -223.768666)
		(end 389.042148 -223.746822)
		(width 0.0889)
		(layer "In2.Cu")
		(net "M_I_CPU0_SA_DQ<1>")
	)
	(segment
		(start 388.10184 -225.366834)
		(end 388.13359 -225.348546)
		(width 0.0889)
		(layer "In2.Cu")
		(net "M_I_CPU0_SA_DQ<1>")
	)
	(segment
		(start 387.63194 -226.17684)
		(end 387.66242 -226.15906)
		(width 0.0889)
		(layer "In2.Cu")
		(net "M_I_CPU0_SA_DQ<1>")
	)
	(segment
		(start 387.257798 -226.17684)
		(end 387.26618 -226.181666)
		(width 0.0889)
		(layer "In2.Cu")
		(net "M_I_CPU0_SA_DQ<1>")
	)
	(segment
		(start 390.026398 -221.196408)
		(end 390.026398 -219.29217)
		(width 0.14478)
		(layer "In2.Cu")
		(net "M_I_CPU0_SA_DQ<1>")
	)
	(segment
		(start 383.497836 -226.17684)
		(end 383.506218 -226.181666)
		(width 0.0889)
		(layer "In2.Cu")
		(net "M_I_CPU0_SA_DQ<1>")
	)
	(segment
		(start 381.043434 -226.181666)
		(end 381.051816 -226.17684)
		(width 0.0889)
		(layer "In2.Cu")
		(net "M_I_CPU0_SA_DQ<1>")
	)
	(segment
		(start 376.010678 -226.11969)
		(end 376.03303 -226.203002)
		(width 0.0889)
		(layer "In2.Cu")
		(net "M_I_CPU0_SA_DQ<1>")
	)
	(segment
		(start 415.111692 -198.61022)
		(end 417.805616 -198.61022)
		(width 0.14478)
		(layer "In2.Cu")
		(net "M_I_CPU0_SA_DQ<1>")
	)
	(segment
		(start 389.700008 -222.614236)
		(end 389.700008 -222.415862)
		(width 0.0889)
		(layer "In2.Cu")
		(net "M_I_CPU0_SA_DQ<1>")
	)
	(segment
		(start 378.79782 -226.17684)
		(end 378.806202 -226.181666)
		(width 0.0889)
		(layer "In2.Cu")
		(net "M_I_CPU0_SA_DQ<1>")
	)
	(segment
		(start 389.47471 -222.95866)
		(end 389.512302 -222.936816)
		(width 0.0889)
		(layer "In2.Cu")
		(net "M_I_CPU0_SA_DQ<1>")
	)
	(segment
		(start 385.74345 -226.181666)
		(end 385.744466 -226.181158)
		(width 0.0889)
		(layer "In2.Cu")
		(net "M_I_CPU0_SA_DQ<1>")
	)
	(segment
		(start 402.91385 -204.311758)
		(end 407.765504 -199.460104)
		(width 0.14478)
		(layer "In2.Cu")
		(net "M_I_CPU0_SA_DQ<1>")
	)
	(segment
		(start 386.683504 -226.181666)
		(end 386.691886 -226.17684)
		(width 0.0889)
		(layer "In2.Cu")
		(net "M_I_CPU0_SA_DQ<1>")
	)
	(segment
		(start 382.557782 -226.17684)
		(end 382.566164 -226.181666)
		(width 0.0889)
		(layer "In2.Cu")
		(net "M_I_CPU0_SA_DQ<1>")
	)
	(segment
		(start 421.332406 -199.460104)
		(end 422.604438 -198.61022)
		(width 0.14478)
		(layer "In2.Cu")
		(net "M_I_CPU0_SA_DQ<1>")
	)
	(segment
		(start 419.077648 -199.460104)
		(end 421.332406 -199.460104)
		(width 0.14478)
		(layer "In2.Cu")
		(net "M_I_CPU0_SA_DQ<1>")
	)
	(segment
		(start 395.959076 -212.025992)
		(end 402.91385 -205.071218)
		(width 0.14478)
		(layer "In2.Cu")
		(net "M_I_CPU0_SA_DQ<1>")
	)
	(segment
		(start 388.531862 -224.58045)
		(end 388.572248 -224.556828)
		(width 0.0889)
		(layer "In2.Cu")
		(net "M_I_CPU0_SA_DQ<1>")
	)
	(segment
		(start 431.131218 -198.61022)
		(end 431.55616 -199.035162)
		(width 0.14478)
		(layer "In2.Cu")
		(net "M_I_CPU0_SA_DQ<1>")
	)
	(segment
		(start 385.744466 -226.181158)
		(end 385.751832 -226.17684)
		(width 0.0889)
		(layer "In2.Cu")
		(net "M_I_CPU0_SA_DQ<1>")
	)
	(segment
		(start 407.765504 -199.460104)
		(end 413.839914 -199.460104)
		(width 0.14478)
		(layer "In2.Cu")
		(net "M_I_CPU0_SA_DQ<1>")
	)
	(segment
		(start 390.026398 -219.29217)
		(end 395.959076 -213.359492)
		(width 0.14478)
		(layer "In2.Cu")
		(net "M_I_CPU0_SA_DQ<1>")
	)
	(segment
		(start 389.042148 -223.746822)
		(end 389.074914 -223.727772)
		(width 0.0889)
		(layer "In2.Cu")
		(net "M_I_CPU0_SA_DQ<1>")
	)
	(segment
		(start 377.283472 -226.181666)
		(end 377.291854 -226.17684)
		(width 0.0889)
		(layer "In2.Cu")
		(net "M_I_CPU0_SA_DQ<1>")
	)
	(segment
		(start 417.805616 -198.61022)
		(end 419.077648 -199.460104)
		(width 0.14478)
		(layer "In2.Cu")
		(net "M_I_CPU0_SA_DQ<1>")
	)
	(arc
		(start 388.289546 -225.044254)
		(mid 388.353839 -224.782649)
		(end 388.531862 -224.58045)
		(width 0.0889)
		(layer "In2.Cu")
		(net "M_I_CPU0_SA_DQ<1>")
	)
	(arc
		(start 387.26618 -226.181666)
		(mid 387.449688 -226.22716)
		(end 387.63194 -226.17684)
		(width 0.0889)
		(layer "In2.Cu")
		(net "M_I_CPU0_SA_DQ<1>")
	)
	(arc
		(start 381.051816 -226.17684)
		(mid 381.334772 -226.100663)
		(end 381.617728 -226.17684)
		(width 0.0889)
		(layer "In2.Cu")
		(net "M_I_CPU0_SA_DQ<1>")
	)
	(arc
		(start 379.737874 -226.17684)
		(mid 379.924818 -226.227095)
		(end 380.111762 -226.17684)
		(width 0.0889)
		(layer "In2.Cu")
		(net "M_I_CPU0_SA_DQ<1>")
	)
	(arc
		(start 381.617728 -226.17684)
		(mid 381.799979 -226.22719)
		(end 381.983488 -226.181666)
		(width 0.0889)
		(layer "In2.Cu")
		(net "M_I_CPU0_SA_DQ<1>")
	)
	(arc
		(start 388.13359 -225.348546)
		(mid 388.248266 -225.215212)
		(end 388.289546 -225.044254)
		(width 0.0889)
		(layer "In2.Cu")
		(net "M_I_CPU0_SA_DQ<1>")
	)
	(arc
		(start 389.546084 -222.917258)
		(mid 389.659343 -222.78418)
		(end 389.700008 -222.614236)
		(width 0.0889)
		(layer "In2.Cu")
		(net "M_I_CPU0_SA_DQ<1>")
	)
	(arc
		(start 376.03303 -226.203002)
		(mid 376.19054 -226.2262)
		(end 376.343418 -226.181666)
		(width 0.0889)
		(layer "In2.Cu")
		(net "M_I_CPU0_SA_DQ<1>")
	)
	(arc
		(start 386.691886 -226.17684)
		(mid 386.974842 -226.100663)
		(end 387.257798 -226.17684)
		(width 0.0889)
		(layer "In2.Cu")
		(net "M_I_CPU0_SA_DQ<1>")
	)
	(arc
		(start 378.231908 -226.17684)
		(mid 378.514864 -226.100663)
		(end 378.79782 -226.17684)
		(width 0.0889)
		(layer "In2.Cu")
		(net "M_I_CPU0_SA_DQ<1>")
	)
	(arc
		(start 389.230108 -223.424242)
		(mid 389.29498 -223.161279)
		(end 389.47471 -222.95866)
		(width 0.0889)
		(layer "In2.Cu")
		(net "M_I_CPU0_SA_DQ<1>")
	)
	(arc
		(start 385.751832 -226.17684)
		(mid 386.034788 -226.100663)
		(end 386.317744 -226.17684)
		(width 0.0889)
		(layer "In2.Cu")
		(net "M_I_CPU0_SA_DQ<1>")
	)
	(arc
		(start 386.317744 -226.17684)
		(mid 386.499995 -226.22719)
		(end 386.683504 -226.181666)
		(width 0.0889)
		(layer "In2.Cu")
		(net "M_I_CPU0_SA_DQ<1>")
	)
	(arc
		(start 377.291854 -226.17684)
		(mid 377.57481 -226.100663)
		(end 377.857766 -226.17684)
		(width 0.0889)
		(layer "In2.Cu")
		(net "M_I_CPU0_SA_DQ<1>")
	)
	(arc
		(start 384.43789 -226.17684)
		(mid 384.624834 -226.227095)
		(end 384.811778 -226.17684)
		(width 0.0889)
		(layer "In2.Cu")
		(net "M_I_CPU0_SA_DQ<1>")
	)
	(arc
		(start 388.7597 -224.234248)
		(mid 388.824572 -223.971285)
		(end 389.004302 -223.768666)
		(width 0.0889)
		(layer "In2.Cu")
		(net "M_I_CPU0_SA_DQ<1>")
	)
	(arc
		(start 387.66242 -226.15906)
		(mid 387.777847 -226.025684)
		(end 387.819392 -225.85426)
		(width 0.0889)
		(layer "In2.Cu")
		(net "M_I_CPU0_SA_DQ<1>")
	)
	(arc
		(start 382.566164 -226.181666)
		(mid 382.749672 -226.22716)
		(end 382.931924 -226.17684)
		(width 0.0889)
		(layer "In2.Cu")
		(net "M_I_CPU0_SA_DQ<1>")
	)
	(arc
		(start 388.601712 -224.53981)
		(mid 388.717893 -224.406251)
		(end 388.7597 -224.234248)
		(width 0.0889)
		(layer "In2.Cu")
		(net "M_I_CPU0_SA_DQ<1>")
	)
	(arc
		(start 383.506218 -226.181666)
		(mid 383.689726 -226.22716)
		(end 383.871978 -226.17684)
		(width 0.0889)
		(layer "In2.Cu")
		(net "M_I_CPU0_SA_DQ<1>")
	)
	(arc
		(start 387.819392 -225.85426)
		(mid 387.883907 -225.592041)
		(end 388.062724 -225.389694)
		(width 0.0889)
		(layer "In2.Cu")
		(net "M_I_CPU0_SA_DQ<1>")
	)
	(arc
		(start 378.806202 -226.181666)
		(mid 378.98971 -226.22716)
		(end 379.171962 -226.17684)
		(width 0.0889)
		(layer "In2.Cu")
		(net "M_I_CPU0_SA_DQ<1>")
	)
	(arc
		(start 376.917712 -226.17684)
		(mid 377.099963 -226.22719)
		(end 377.283472 -226.181666)
		(width 0.0889)
		(layer "In2.Cu")
		(net "M_I_CPU0_SA_DQ<1>")
	)
	(arc
		(start 383.871978 -226.17684)
		(mid 384.154934 -226.100663)
		(end 384.43789 -226.17684)
		(width 0.0889)
		(layer "In2.Cu")
		(net "M_I_CPU0_SA_DQ<1>")
	)
	(arc
		(start 380.111762 -226.17684)
		(mid 380.394718 -226.100663)
		(end 380.677674 -226.17684)
		(width 0.0889)
		(layer "In2.Cu")
		(net "M_I_CPU0_SA_DQ<1>")
	)
	(arc
		(start 385.37769 -226.17684)
		(mid 385.559941 -226.22719)
		(end 385.74345 -226.181666)
		(width 0.0889)
		(layer "In2.Cu")
		(net "M_I_CPU0_SA_DQ<1>")
	)
	(arc
		(start 379.171962 -226.17684)
		(mid 379.454918 -226.100663)
		(end 379.737874 -226.17684)
		(width 0.0889)
		(layer "In2.Cu")
		(net "M_I_CPU0_SA_DQ<1>")
	)
	(arc
		(start 384.811778 -226.17684)
		(mid 385.094734 -226.100663)
		(end 385.37769 -226.17684)
		(width 0.0889)
		(layer "In2.Cu")
		(net "M_I_CPU0_SA_DQ<1>")
	)
	(arc
		(start 381.99187 -226.17684)
		(mid 382.274826 -226.100663)
		(end 382.557782 -226.17684)
		(width 0.0889)
		(layer "In2.Cu")
		(net "M_I_CPU0_SA_DQ<1>")
	)
	(arc
		(start 382.931924 -226.17684)
		(mid 383.21488 -226.100663)
		(end 383.497836 -226.17684)
		(width 0.0889)
		(layer "In2.Cu")
		(net "M_I_CPU0_SA_DQ<1>")
	)
	(arc
		(start 380.677674 -226.17684)
		(mid 380.859925 -226.22719)
		(end 381.043434 -226.181666)
		(width 0.0889)
		(layer "In2.Cu")
		(net "M_I_CPU0_SA_DQ<1>")
	)
	(arc
		(start 376.3518 -226.17684)
		(mid 376.634756 -226.100663)
		(end 376.917712 -226.17684)
		(width 0.0889)
		(layer "In2.Cu")
		(net "M_I_CPU0_SA_DQ<1>")
	)
	(arc
		(start 377.866148 -226.181666)
		(mid 378.049656 -226.22716)
		(end 378.231908 -226.17684)
		(width 0.0889)
		(layer "In2.Cu")
		(net "M_I_CPU0_SA_DQ<1>")
	)
	(arc
		(start 389.074914 -223.727772)
		(mid 389.189067 -223.594696)
		(end 389.230108 -223.424242)
		(width 0.0889)
		(layer "In2.Cu")
		(net "M_I_CPU0_SA_DQ<1>")
	)
	(segment
		(start 375.22785 -236.650022)
		(end 375.694702 -236.384084)
		(width 0.10668)
		(layer "F.Cu")
		(net "M_I_CPU0_SA_DQ<19>")
	)
	(segment
		(start 408.729942 -220.104716)
		(end 408.891486 -219.943172)
		(width 0.14478)
		(layer "In2.Cu")
		(net "M_I_CPU0_SA_DQ<19>")
	)
	(segment
		(start 375.84888 -236.118654)
		(end 375.945146 -236.093254)
		(width 0.0889)
		(layer "In2.Cu")
		(net "M_I_CPU0_SA_DQ<19>")
	)
	(segment
		(start 378.693426 -236.056678)
		(end 378.701808 -236.061504)
		(width 0.0889)
		(layer "In2.Cu")
		(net "M_I_CPU0_SA_DQ<19>")
	)
	(segment
		(start 421.465756 -219.000324)
		(end 422.31564 -218.15044)
		(width 0.14478)
		(layer "In2.Cu")
		(net "M_I_CPU0_SA_DQ<19>")
	)
	(segment
		(start 406.301448 -221.577662)
		(end 406.462992 -221.416118)
		(width 0.14478)
		(layer "In2.Cu")
		(net "M_I_CPU0_SA_DQ<19>")
	)
	(segment
		(start 407.169366 -221.665292)
		(end 407.33091 -221.503748)
		(width 0.14478)
		(layer "In2.Cu")
		(net "M_I_CPU0_SA_DQ<19>")
	)
	(segment
		(start 385.847844 -236.061504)
		(end 385.856226 -236.056678)
		(width 0.0889)
		(layer "In2.Cu")
		(net "M_I_CPU0_SA_DQ<19>")
	)
	(segment
		(start 425.685458 -218.06535)
		(end 426.14342 -218.06535)
		(width 0.14478)
		(layer "In2.Cu")
		(net "M_I_CPU0_SA_DQ<19>")
	)
	(segment
		(start 409.51023 -219.324428)
		(end 409.834334 -219.000324)
		(width 0.14478)
		(layer "In2.Cu")
		(net "M_I_CPU0_SA_DQ<19>")
	)
	(segment
		(start 424.94581 -218.15044)
		(end 425.22394 -217.87231)
		(width 0.14478)
		(layer "In2.Cu")
		(net "M_I_CPU0_SA_DQ<19>")
	)
	(segment
		(start 418.170868 -218.15044)
		(end 419.020752 -219.000324)
		(width 0.14478)
		(layer "In2.Cu")
		(net "M_I_CPU0_SA_DQ<19>")
	)
	(segment
		(start 380.207774 -236.061504)
		(end 380.216156 -236.056678)
		(width 0.0889)
		(layer "In2.Cu")
		(net "M_I_CPU0_SA_DQ<19>")
	)
	(segment
		(start 394.607796 -233.82351)
		(end 395.011148 -233.82351)
		(width 0.0889)
		(layer "In2.Cu")
		(net "M_I_CPU0_SA_DQ<19>")
	)
	(segment
		(start 406.301448 -221.806262)
		(end 406.301448 -221.577662)
		(width 0.14478)
		(layer "In2.Cu")
		(net "M_I_CPU0_SA_DQ<19>")
	)
	(segment
		(start 407.721054 -220.885004)
		(end 407.949654 -220.885004)
		(width 0.14478)
		(layer "In2.Cu")
		(net "M_I_CPU0_SA_DQ<19>")
	)
	(segment
		(start 383.393442 -236.056678)
		(end 383.401824 -236.061504)
		(width 0.0889)
		(layer "In2.Cu")
		(net "M_I_CPU0_SA_DQ<19>")
	)
	(segment
		(start 408.803856 -219.075254)
		(end 409.032456 -219.075254)
		(width 0.14478)
		(layer "In2.Cu")
		(net "M_I_CPU0_SA_DQ<19>")
	)
	(segment
		(start 391.48766 -236.061504)
		(end 393.638532 -234.792774)
		(width 0.0889)
		(layer "In2.Cu")
		(net "M_I_CPU0_SA_DQ<19>")
	)
	(segment
		(start 407.33091 -221.275148)
		(end 407.081736 -221.025974)
		(width 0.14478)
		(layer "In2.Cu")
		(net "M_I_CPU0_SA_DQ<19>")
	)
	(segment
		(start 426.33646 -217.87231)
		(end 426.743368 -217.87231)
		(width 0.14478)
		(layer "In2.Cu")
		(net "M_I_CPU0_SA_DQ<19>")
	)
	(segment
		(start 407.862024 -220.017086)
		(end 408.023568 -219.855542)
		(width 0.14478)
		(layer "In2.Cu")
		(net "M_I_CPU0_SA_DQ<19>")
	)
	(segment
		(start 419.020752 -219.000324)
		(end 421.465756 -219.000324)
		(width 0.14478)
		(layer "In2.Cu")
		(net "M_I_CPU0_SA_DQ<19>")
	)
	(segment
		(start 406.550622 -222.284036)
		(end 406.550622 -222.055436)
		(width 0.14478)
		(layer "In2.Cu")
		(net "M_I_CPU0_SA_DQ<19>")
	)
	(segment
		(start 408.501342 -220.104716)
		(end 408.729942 -220.104716)
		(width 0.14478)
		(layer "In2.Cu")
		(net "M_I_CPU0_SA_DQ<19>")
	)
	(segment
		(start 408.023568 -219.855542)
		(end 408.252168 -219.855542)
		(width 0.14478)
		(layer "In2.Cu")
		(net "M_I_CPU0_SA_DQ<19>")
	)
	(segment
		(start 406.550622 -222.055436)
		(end 406.301448 -221.806262)
		(width 0.14478)
		(layer "In2.Cu")
		(net "M_I_CPU0_SA_DQ<19>")
	)
	(segment
		(start 379.63348 -236.056678)
		(end 379.641862 -236.061504)
		(width 0.0889)
		(layer "In2.Cu")
		(net "M_I_CPU0_SA_DQ<19>")
	)
	(segment
		(start 406.462992 -221.416118)
		(end 406.691592 -221.416118)
		(width 0.14478)
		(layer "In2.Cu")
		(net "M_I_CPU0_SA_DQ<19>")
	)
	(segment
		(start 409.032456 -219.075254)
		(end 409.28163 -219.324428)
		(width 0.14478)
		(layer "In2.Cu")
		(net "M_I_CPU0_SA_DQ<19>")
	)
	(segment
		(start 425.492418 -217.87231)
		(end 425.685458 -218.06535)
		(width 0.14478)
		(layer "In2.Cu")
		(net "M_I_CPU0_SA_DQ<19>")
	)
	(segment
		(start 389.607806 -236.061504)
		(end 389.616188 -236.056678)
		(width 0.0889)
		(layer "In2.Cu")
		(net "M_I_CPU0_SA_DQ<19>")
	)
	(segment
		(start 426.14342 -218.06535)
		(end 426.33646 -217.87231)
		(width 0.14478)
		(layer "In2.Cu")
		(net "M_I_CPU0_SA_DQ<19>")
	)
	(segment
		(start 413.92729 -219.000324)
		(end 414.777174 -218.15044)
		(width 0.14478)
		(layer "In2.Cu")
		(net "M_I_CPU0_SA_DQ<19>")
	)
	(segment
		(start 408.252168 -219.855542)
		(end 408.501342 -220.104716)
		(width 0.14478)
		(layer "In2.Cu")
		(net "M_I_CPU0_SA_DQ<19>")
	)
	(segment
		(start 407.862024 -220.245686)
		(end 407.862024 -220.017086)
		(width 0.14478)
		(layer "In2.Cu")
		(net "M_I_CPU0_SA_DQ<19>")
	)
	(segment
		(start 409.834334 -219.000324)
		(end 413.92729 -219.000324)
		(width 0.14478)
		(layer "In2.Cu")
		(net "M_I_CPU0_SA_DQ<19>")
	)
	(segment
		(start 407.949654 -220.885004)
		(end 408.111198 -220.72346)
		(width 0.14478)
		(layer "In2.Cu")
		(net "M_I_CPU0_SA_DQ<19>")
	)
	(segment
		(start 375.694702 -236.384084)
		(end 375.84888 -236.118654)
		(width 0.0889)
		(layer "In2.Cu")
		(net "M_I_CPU0_SA_DQ<19>")
	)
	(segment
		(start 384.333496 -236.056678)
		(end 384.341878 -236.061504)
		(width 0.0889)
		(layer "In2.Cu")
		(net "M_I_CPU0_SA_DQ<19>")
	)
	(segment
		(start 389.033512 -236.056678)
		(end 389.041894 -236.061504)
		(width 0.0889)
		(layer "In2.Cu")
		(net "M_I_CPU0_SA_DQ<19>")
	)
	(segment
		(start 407.47188 -220.63583)
		(end 407.721054 -220.885004)
		(width 0.14478)
		(layer "In2.Cu")
		(net "M_I_CPU0_SA_DQ<19>")
	)
	(segment
		(start 422.31564 -218.15044)
		(end 424.94581 -218.15044)
		(width 0.14478)
		(layer "In2.Cu")
		(net "M_I_CPU0_SA_DQ<19>")
	)
	(segment
		(start 425.22394 -217.87231)
		(end 425.492418 -217.87231)
		(width 0.14478)
		(layer "In2.Cu")
		(net "M_I_CPU0_SA_DQ<19>")
	)
	(segment
		(start 408.642312 -219.236798)
		(end 408.803856 -219.075254)
		(width 0.14478)
		(layer "In2.Cu")
		(net "M_I_CPU0_SA_DQ<19>")
	)
	(segment
		(start 393.638532 -234.792774)
		(end 394.607796 -233.82351)
		(width 0.0889)
		(layer "In2.Cu")
		(net "M_I_CPU0_SA_DQ<19>")
	)
	(segment
		(start 395.011148 -233.82351)
		(end 395.854174 -232.980484)
		(width 0.0889)
		(layer "In2.Cu")
		(net "M_I_CPU0_SA_DQ<19>")
	)
	(segment
		(start 407.33091 -221.503748)
		(end 407.33091 -221.275148)
		(width 0.14478)
		(layer "In2.Cu")
		(net "M_I_CPU0_SA_DQ<19>")
	)
	(segment
		(start 388.093458 -236.056678)
		(end 388.10184 -236.061504)
		(width 0.0889)
		(layer "In2.Cu")
		(net "M_I_CPU0_SA_DQ<19>")
	)
	(segment
		(start 376.447812 -236.061504)
		(end 376.456194 -236.056678)
		(width 0.0889)
		(layer "In2.Cu")
		(net "M_I_CPU0_SA_DQ<19>")
	)
	(segment
		(start 426.743368 -217.87231)
		(end 427.456092 -218.585034)
		(width 0.14478)
		(layer "In2.Cu")
		(net "M_I_CPU0_SA_DQ<19>")
	)
	(segment
		(start 408.891486 -219.943172)
		(end 408.891486 -219.714572)
		(width 0.14478)
		(layer "In2.Cu")
		(net "M_I_CPU0_SA_DQ<19>")
	)
	(segment
		(start 407.24328 -220.63583)
		(end 407.47188 -220.63583)
		(width 0.14478)
		(layer "In2.Cu")
		(net "M_I_CPU0_SA_DQ<19>")
	)
	(segment
		(start 408.111198 -220.49486)
		(end 407.862024 -220.245686)
		(width 0.14478)
		(layer "In2.Cu")
		(net "M_I_CPU0_SA_DQ<19>")
	)
	(segment
		(start 395.854174 -232.980484)
		(end 406.550622 -222.284036)
		(width 0.14478)
		(layer "In2.Cu")
		(net "M_I_CPU0_SA_DQ<19>")
	)
	(segment
		(start 407.081736 -221.025974)
		(end 407.081736 -220.797374)
		(width 0.14478)
		(layer "In2.Cu")
		(net "M_I_CPU0_SA_DQ<19>")
	)
	(segment
		(start 409.28163 -219.324428)
		(end 409.51023 -219.324428)
		(width 0.14478)
		(layer "In2.Cu")
		(net "M_I_CPU0_SA_DQ<19>")
	)
	(segment
		(start 381.147828 -236.061504)
		(end 381.15621 -236.056678)
		(width 0.0889)
		(layer "In2.Cu")
		(net "M_I_CPU0_SA_DQ<19>")
	)
	(segment
		(start 384.90779 -236.061504)
		(end 384.916172 -236.056678)
		(width 0.0889)
		(layer "In2.Cu")
		(net "M_I_CPU0_SA_DQ<19>")
	)
	(segment
		(start 407.081736 -220.797374)
		(end 407.24328 -220.63583)
		(width 0.14478)
		(layer "In2.Cu")
		(net "M_I_CPU0_SA_DQ<19>")
	)
	(segment
		(start 408.111198 -220.72346)
		(end 408.111198 -220.49486)
		(width 0.14478)
		(layer "In2.Cu")
		(net "M_I_CPU0_SA_DQ<19>")
	)
	(segment
		(start 408.891486 -219.714572)
		(end 408.642312 -219.465398)
		(width 0.14478)
		(layer "In2.Cu")
		(net "M_I_CPU0_SA_DQ<19>")
	)
	(segment
		(start 406.940766 -221.665292)
		(end 407.169366 -221.665292)
		(width 0.14478)
		(layer "In2.Cu")
		(net "M_I_CPU0_SA_DQ<19>")
	)
	(segment
		(start 408.642312 -219.465398)
		(end 408.642312 -219.236798)
		(width 0.14478)
		(layer "In2.Cu")
		(net "M_I_CPU0_SA_DQ<19>")
	)
	(segment
		(start 406.691592 -221.416118)
		(end 406.940766 -221.665292)
		(width 0.14478)
		(layer "In2.Cu")
		(net "M_I_CPU0_SA_DQ<19>")
	)
	(segment
		(start 414.777174 -218.15044)
		(end 418.170868 -218.15044)
		(width 0.14478)
		(layer "In2.Cu")
		(net "M_I_CPU0_SA_DQ<19>")
	)
	(arc
		(start 385.856226 -236.056678)
		(mid 386.039734 -236.011184)
		(end 386.221986 -236.061504)
		(width 0.0889)
		(layer "In2.Cu")
		(net "M_I_CPU0_SA_DQ<19>")
	)
	(arc
		(start 382.087882 -236.061504)
		(mid 382.274826 -236.011249)
		(end 382.46177 -236.061504)
		(width 0.0889)
		(layer "In2.Cu")
		(net "M_I_CPU0_SA_DQ<19>")
	)
	(arc
		(start 377.387866 -236.061504)
		(mid 377.57481 -236.011249)
		(end 377.761754 -236.061504)
		(width 0.0889)
		(layer "In2.Cu")
		(net "M_I_CPU0_SA_DQ<19>")
	)
	(arc
		(start 379.26772 -236.061504)
		(mid 379.449971 -236.011154)
		(end 379.63348 -236.056678)
		(width 0.0889)
		(layer "In2.Cu")
		(net "M_I_CPU0_SA_DQ<19>")
	)
	(arc
		(start 389.041894 -236.061504)
		(mid 389.32485 -236.137681)
		(end 389.607806 -236.061504)
		(width 0.0889)
		(layer "In2.Cu")
		(net "M_I_CPU0_SA_DQ<19>")
	)
	(arc
		(start 387.161786 -236.061504)
		(mid 387.444742 -236.137681)
		(end 387.727698 -236.061504)
		(width 0.0889)
		(layer "In2.Cu")
		(net "M_I_CPU0_SA_DQ<19>")
	)
	(arc
		(start 380.581916 -236.061504)
		(mid 380.864872 -236.137681)
		(end 381.147828 -236.061504)
		(width 0.0889)
		(layer "In2.Cu")
		(net "M_I_CPU0_SA_DQ<19>")
	)
	(arc
		(start 381.52197 -236.061504)
		(mid 381.804926 -236.137681)
		(end 382.087882 -236.061504)
		(width 0.0889)
		(layer "In2.Cu")
		(net "M_I_CPU0_SA_DQ<19>")
	)
	(arc
		(start 386.221986 -236.061504)
		(mid 386.504942 -236.137681)
		(end 386.787898 -236.061504)
		(width 0.0889)
		(layer "In2.Cu")
		(net "M_I_CPU0_SA_DQ<19>")
	)
	(arc
		(start 388.10184 -236.061504)
		(mid 388.384796 -236.137681)
		(end 388.667752 -236.061504)
		(width 0.0889)
		(layer "In2.Cu")
		(net "M_I_CPU0_SA_DQ<19>")
	)
	(arc
		(start 389.616188 -236.056678)
		(mid 389.799696 -236.011184)
		(end 389.981948 -236.061504)
		(width 0.0889)
		(layer "In2.Cu")
		(net "M_I_CPU0_SA_DQ<19>")
	)
	(arc
		(start 386.787898 -236.061504)
		(mid 386.974842 -236.011249)
		(end 387.161786 -236.061504)
		(width 0.0889)
		(layer "In2.Cu")
		(net "M_I_CPU0_SA_DQ<19>")
	)
	(arc
		(start 383.967736 -236.061504)
		(mid 384.149987 -236.011154)
		(end 384.333496 -236.056678)
		(width 0.0889)
		(layer "In2.Cu")
		(net "M_I_CPU0_SA_DQ<19>")
	)
	(arc
		(start 385.281932 -236.061504)
		(mid 385.564888 -236.137681)
		(end 385.847844 -236.061504)
		(width 0.0889)
		(layer "In2.Cu")
		(net "M_I_CPU0_SA_DQ<19>")
	)
	(arc
		(start 381.15621 -236.056678)
		(mid 381.339718 -236.011184)
		(end 381.52197 -236.061504)
		(width 0.0889)
		(layer "In2.Cu")
		(net "M_I_CPU0_SA_DQ<19>")
	)
	(arc
		(start 380.216156 -236.056678)
		(mid 380.399664 -236.011184)
		(end 380.581916 -236.061504)
		(width 0.0889)
		(layer "In2.Cu")
		(net "M_I_CPU0_SA_DQ<19>")
	)
	(arc
		(start 376.821954 -236.061504)
		(mid 377.10491 -236.137681)
		(end 377.387866 -236.061504)
		(width 0.0889)
		(layer "In2.Cu")
		(net "M_I_CPU0_SA_DQ<19>")
	)
	(arc
		(start 383.027682 -236.061504)
		(mid 383.209933 -236.011154)
		(end 383.393442 -236.056678)
		(width 0.0889)
		(layer "In2.Cu")
		(net "M_I_CPU0_SA_DQ<19>")
	)
	(arc
		(start 383.401824 -236.061504)
		(mid 383.68478 -236.137681)
		(end 383.967736 -236.061504)
		(width 0.0889)
		(layer "In2.Cu")
		(net "M_I_CPU0_SA_DQ<19>")
	)
	(arc
		(start 388.667752 -236.061504)
		(mid 388.850003 -236.011154)
		(end 389.033512 -236.056678)
		(width 0.0889)
		(layer "In2.Cu")
		(net "M_I_CPU0_SA_DQ<19>")
	)
	(arc
		(start 389.981948 -236.061504)
		(mid 390.264904 -236.137681)
		(end 390.54786 -236.061504)
		(width 0.0889)
		(layer "In2.Cu")
		(net "M_I_CPU0_SA_DQ<19>")
	)
	(arc
		(start 387.727698 -236.061504)
		(mid 387.909949 -236.011154)
		(end 388.093458 -236.056678)
		(width 0.0889)
		(layer "In2.Cu")
		(net "M_I_CPU0_SA_DQ<19>")
	)
	(arc
		(start 377.761754 -236.061504)
		(mid 378.04471 -236.137681)
		(end 378.327666 -236.061504)
		(width 0.0889)
		(layer "In2.Cu")
		(net "M_I_CPU0_SA_DQ<19>")
	)
	(arc
		(start 384.341878 -236.061504)
		(mid 384.624834 -236.137681)
		(end 384.90779 -236.061504)
		(width 0.0889)
		(layer "In2.Cu")
		(net "M_I_CPU0_SA_DQ<19>")
	)
	(arc
		(start 375.945146 -236.093254)
		(mid 376.200211 -236.136605)
		(end 376.447812 -236.061504)
		(width 0.0889)
		(layer "In2.Cu")
		(net "M_I_CPU0_SA_DQ<19>")
	)
	(arc
		(start 390.921748 -236.061504)
		(mid 391.204704 -236.137681)
		(end 391.48766 -236.061504)
		(width 0.0889)
		(layer "In2.Cu")
		(net "M_I_CPU0_SA_DQ<19>")
	)
	(arc
		(start 379.641862 -236.061504)
		(mid 379.924818 -236.137681)
		(end 380.207774 -236.061504)
		(width 0.0889)
		(layer "In2.Cu")
		(net "M_I_CPU0_SA_DQ<19>")
	)
	(arc
		(start 390.54786 -236.061504)
		(mid 390.734804 -236.011249)
		(end 390.921748 -236.061504)
		(width 0.0889)
		(layer "In2.Cu")
		(net "M_I_CPU0_SA_DQ<19>")
	)
	(arc
		(start 378.327666 -236.061504)
		(mid 378.509917 -236.011154)
		(end 378.693426 -236.056678)
		(width 0.0889)
		(layer "In2.Cu")
		(net "M_I_CPU0_SA_DQ<19>")
	)
	(arc
		(start 376.456194 -236.056678)
		(mid 376.639702 -236.011184)
		(end 376.821954 -236.061504)
		(width 0.0889)
		(layer "In2.Cu")
		(net "M_I_CPU0_SA_DQ<19>")
	)
	(arc
		(start 382.46177 -236.061504)
		(mid 382.744726 -236.137681)
		(end 383.027682 -236.061504)
		(width 0.0889)
		(layer "In2.Cu")
		(net "M_I_CPU0_SA_DQ<19>")
	)
	(arc
		(start 384.916172 -236.056678)
		(mid 385.09968 -236.011184)
		(end 385.281932 -236.061504)
		(width 0.0889)
		(layer "In2.Cu")
		(net "M_I_CPU0_SA_DQ<19>")
	)
	(arc
		(start 378.701808 -236.061504)
		(mid 378.984764 -236.137681)
		(end 379.26772 -236.061504)
		(width 0.0889)
		(layer "In2.Cu")
		(net "M_I_CPU0_SA_DQ<19>")
	)
	(segment
		(start 376.638058 -235.840016)
		(end 377.10491 -235.574078)
		(width 0.10668)
		(layer "F.Cu")
		(net "M_I_CPU0_SA_DQ<18>")
	)
	(segment
		(start 404.514812 -223.018858)
		(end 404.514812 -222.790258)
		(width 0.14478)
		(layer "In2.Cu")
		(net "M_I_CPU0_SA_DQ<18>")
	)
	(segment
		(start 403.461982 -223.069404)
		(end 403.623526 -222.90786)
		(width 0.14478)
		(layer "In2.Cu")
		(net "M_I_CPU0_SA_DQ<18>")
	)
	(segment
		(start 404.514812 -222.790258)
		(end 404.24227 -222.517716)
		(width 0.14478)
		(layer "In2.Cu")
		(net "M_I_CPU0_SA_DQ<18>")
	)
	(segment
		(start 377.10491 -235.574078)
		(end 377.258834 -235.308648)
		(width 0.0889)
		(layer "In2.Cu")
		(net "M_I_CPU0_SA_DQ<18>")
	)
	(segment
		(start 418.732208 -217.310208)
		(end 421.580564 -217.310208)
		(width 0.14478)
		(layer "In2.Cu")
		(net "M_I_CPU0_SA_DQ<18>")
	)
	(segment
		(start 403.461982 -223.298004)
		(end 403.461982 -223.069404)
		(width 0.14478)
		(layer "In2.Cu")
		(net "M_I_CPU0_SA_DQ<18>")
	)
	(segment
		(start 402.681694 -224.078292)
		(end 402.681694 -223.849692)
		(width 0.14478)
		(layer "In2.Cu")
		(net "M_I_CPU0_SA_DQ<18>")
	)
	(segment
		(start 402.681694 -223.849692)
		(end 402.843238 -223.688148)
		(width 0.14478)
		(layer "In2.Cu")
		(net "M_I_CPU0_SA_DQ<18>")
	)
	(segment
		(start 395.034262 -231.956102)
		(end 395.577568 -231.956102)
		(width 0.0889)
		(layer "In2.Cu")
		(net "M_I_CPU0_SA_DQ<18>")
	)
	(segment
		(start 403.34438 -223.96069)
		(end 403.57298 -223.96069)
		(width 0.14478)
		(layer "In2.Cu")
		(net "M_I_CPU0_SA_DQ<18>")
	)
	(segment
		(start 403.623526 -222.90786)
		(end 403.852126 -222.90786)
		(width 0.14478)
		(layer "In2.Cu")
		(net "M_I_CPU0_SA_DQ<18>")
	)
	(segment
		(start 405.022558 -221.508828)
		(end 409.221178 -217.310208)
		(width 0.14478)
		(layer "In2.Cu")
		(net "M_I_CPU0_SA_DQ<18>")
	)
	(segment
		(start 415.08934 -216.46007)
		(end 417.88207 -216.46007)
		(width 0.14478)
		(layer "In2.Cu")
		(net "M_I_CPU0_SA_DQ<18>")
	)
	(segment
		(start 383.497836 -235.251498)
		(end 383.506218 -235.246672)
		(width 0.0889)
		(layer "In2.Cu")
		(net "M_I_CPU0_SA_DQ<18>")
	)
	(segment
		(start 402.06295 -224.468436)
		(end 402.29155 -224.468436)
		(width 0.14478)
		(layer "In2.Cu")
		(net "M_I_CPU0_SA_DQ<18>")
	)
	(segment
		(start 381.983488 -235.246672)
		(end 381.99187 -235.251498)
		(width 0.0889)
		(layer "In2.Cu")
		(net "M_I_CPU0_SA_DQ<18>")
	)
	(segment
		(start 405.133556 -222.400114)
		(end 405.2951 -222.23857)
		(width 0.14478)
		(layer "In2.Cu")
		(net "M_I_CPU0_SA_DQ<18>")
	)
	(segment
		(start 402.792692 -224.740978)
		(end 402.954236 -224.579434)
		(width 0.14478)
		(layer "In2.Cu")
		(net "M_I_CPU0_SA_DQ<18>")
	)
	(segment
		(start 427.03115 -216.46007)
		(end 427.456092 -216.885012)
		(width 0.14478)
		(layer "In2.Cu")
		(net "M_I_CPU0_SA_DQ<18>")
	)
	(segment
		(start 402.173948 -225.359722)
		(end 402.173948 -225.131122)
		(width 0.14478)
		(layer "In2.Cu")
		(net "M_I_CPU0_SA_DQ<18>")
	)
	(segment
		(start 386.683504 -235.246672)
		(end 386.691886 -235.251498)
		(width 0.0889)
		(layer "In2.Cu")
		(net "M_I_CPU0_SA_DQ<18>")
	)
	(segment
		(start 404.24227 -222.517716)
		(end 404.24227 -222.289116)
		(width 0.14478)
		(layer "In2.Cu")
		(net "M_I_CPU0_SA_DQ<18>")
	)
	(segment
		(start 395.577568 -231.956102)
		(end 395.757654 -231.776016)
		(width 0.0889)
		(layer "In2.Cu")
		(net "M_I_CPU0_SA_DQ<18>")
	)
	(segment
		(start 421.580564 -217.310208)
		(end 422.430702 -216.46007)
		(width 0.14478)
		(layer "In2.Cu")
		(net "M_I_CPU0_SA_DQ<18>")
	)
	(segment
		(start 405.2951 -222.00997)
		(end 405.022558 -221.737428)
		(width 0.14478)
		(layer "In2.Cu")
		(net "M_I_CPU0_SA_DQ<18>")
	)
	(segment
		(start 402.173948 -225.131122)
		(end 401.901406 -224.85858)
		(width 0.14478)
		(layer "In2.Cu")
		(net "M_I_CPU0_SA_DQ<18>")
	)
	(segment
		(start 403.071838 -223.688148)
		(end 403.34438 -223.96069)
		(width 0.14478)
		(layer "In2.Cu")
		(net "M_I_CPU0_SA_DQ<18>")
	)
	(segment
		(start 387.257798 -235.251498)
		(end 387.26618 -235.246672)
		(width 0.0889)
		(layer "In2.Cu")
		(net "M_I_CPU0_SA_DQ<18>")
	)
	(segment
		(start 402.843238 -223.688148)
		(end 403.071838 -223.688148)
		(width 0.14478)
		(layer "In2.Cu")
		(net "M_I_CPU0_SA_DQ<18>")
	)
	(segment
		(start 382.557782 -235.251498)
		(end 382.566164 -235.246672)
		(width 0.0889)
		(layer "In2.Cu")
		(net "M_I_CPU0_SA_DQ<18>")
	)
	(segment
		(start 404.632414 -222.127572)
		(end 404.904956 -222.400114)
		(width 0.14478)
		(layer "In2.Cu")
		(net "M_I_CPU0_SA_DQ<18>")
	)
	(segment
		(start 403.57298 -223.96069)
		(end 403.734524 -223.799146)
		(width 0.14478)
		(layer "In2.Cu")
		(net "M_I_CPU0_SA_DQ<18>")
	)
	(segment
		(start 402.29155 -224.468436)
		(end 402.564092 -224.740978)
		(width 0.14478)
		(layer "In2.Cu")
		(net "M_I_CPU0_SA_DQ<18>")
	)
	(segment
		(start 404.904956 -222.400114)
		(end 405.133556 -222.400114)
		(width 0.14478)
		(layer "In2.Cu")
		(net "M_I_CPU0_SA_DQ<18>")
	)
	(segment
		(start 414.239202 -217.310208)
		(end 415.08934 -216.46007)
		(width 0.14478)
		(layer "In2.Cu")
		(net "M_I_CPU0_SA_DQ<18>")
	)
	(segment
		(start 404.124668 -223.180402)
		(end 404.353268 -223.180402)
		(width 0.14478)
		(layer "In2.Cu")
		(net "M_I_CPU0_SA_DQ<18>")
	)
	(segment
		(start 388.197852 -235.251498)
		(end 388.206234 -235.246672)
		(width 0.0889)
		(layer "In2.Cu")
		(net "M_I_CPU0_SA_DQ<18>")
	)
	(segment
		(start 422.430702 -216.46007)
		(end 427.03115 -216.46007)
		(width 0.14478)
		(layer "In2.Cu")
		(net "M_I_CPU0_SA_DQ<18>")
	)
	(segment
		(start 404.24227 -222.289116)
		(end 404.403814 -222.127572)
		(width 0.14478)
		(layer "In2.Cu")
		(net "M_I_CPU0_SA_DQ<18>")
	)
	(segment
		(start 401.901406 -224.85858)
		(end 401.901406 -224.62998)
		(width 0.14478)
		(layer "In2.Cu")
		(net "M_I_CPU0_SA_DQ<18>")
	)
	(segment
		(start 377.857766 -235.251498)
		(end 377.866148 -235.246672)
		(width 0.0889)
		(layer "In2.Cu")
		(net "M_I_CPU0_SA_DQ<18>")
	)
	(segment
		(start 405.2951 -222.23857)
		(end 405.2951 -222.00997)
		(width 0.14478)
		(layer "In2.Cu")
		(net "M_I_CPU0_SA_DQ<18>")
	)
	(segment
		(start 403.852126 -222.90786)
		(end 404.124668 -223.180402)
		(width 0.14478)
		(layer "In2.Cu")
		(net "M_I_CPU0_SA_DQ<18>")
	)
	(segment
		(start 404.353268 -223.180402)
		(end 404.514812 -223.018858)
		(width 0.14478)
		(layer "In2.Cu")
		(net "M_I_CPU0_SA_DQ<18>")
	)
	(segment
		(start 393.573254 -233.41711)
		(end 395.034262 -231.956102)
		(width 0.0889)
		(layer "In2.Cu")
		(net "M_I_CPU0_SA_DQ<18>")
	)
	(segment
		(start 391.01776 -235.251498)
		(end 391.026142 -235.246672)
		(width 0.0889)
		(layer "In2.Cu")
		(net "M_I_CPU0_SA_DQ<18>")
	)
	(segment
		(start 392.1633 -235.131102)
		(end 392.917934 -234.644438)
		(width 0.0889)
		(layer "In2.Cu")
		(net "M_I_CPU0_SA_DQ<18>")
	)
	(segment
		(start 401.901406 -224.62998)
		(end 402.06295 -224.468436)
		(width 0.14478)
		(layer "In2.Cu")
		(net "M_I_CPU0_SA_DQ<18>")
	)
	(segment
		(start 403.734524 -223.799146)
		(end 403.734524 -223.570546)
		(width 0.14478)
		(layer "In2.Cu")
		(net "M_I_CPU0_SA_DQ<18>")
	)
	(segment
		(start 395.757654 -231.776016)
		(end 402.173948 -225.359722)
		(width 0.14478)
		(layer "In2.Cu")
		(net "M_I_CPU0_SA_DQ<18>")
	)
	(segment
		(start 393.573254 -233.974894)
		(end 393.573254 -233.41711)
		(width 0.0889)
		(layer "In2.Cu")
		(net "M_I_CPU0_SA_DQ<18>")
	)
	(segment
		(start 402.954236 -224.350834)
		(end 402.681694 -224.078292)
		(width 0.14478)
		(layer "In2.Cu")
		(net "M_I_CPU0_SA_DQ<18>")
	)
	(segment
		(start 381.043434 -235.246672)
		(end 381.051816 -235.251498)
		(width 0.0889)
		(layer "In2.Cu")
		(net "M_I_CPU0_SA_DQ<18>")
	)
	(segment
		(start 404.403814 -222.127572)
		(end 404.632414 -222.127572)
		(width 0.14478)
		(layer "In2.Cu")
		(net "M_I_CPU0_SA_DQ<18>")
	)
	(segment
		(start 390.443466 -235.246672)
		(end 390.451848 -235.251498)
		(width 0.0889)
		(layer "In2.Cu")
		(net "M_I_CPU0_SA_DQ<18>")
	)
	(segment
		(start 392.917934 -234.644438)
		(end 393.573254 -233.974894)
		(width 0.0889)
		(layer "In2.Cu")
		(net "M_I_CPU0_SA_DQ<18>")
	)
	(segment
		(start 391.947146 -235.257594)
		(end 392.1633 -235.131102)
		(width 0.0889)
		(layer "In2.Cu")
		(net "M_I_CPU0_SA_DQ<18>")
	)
	(segment
		(start 402.954236 -224.579434)
		(end 402.954236 -224.350834)
		(width 0.14478)
		(layer "In2.Cu")
		(net "M_I_CPU0_SA_DQ<18>")
	)
	(segment
		(start 409.221178 -217.310208)
		(end 414.239202 -217.310208)
		(width 0.14478)
		(layer "In2.Cu")
		(net "M_I_CPU0_SA_DQ<18>")
	)
	(segment
		(start 403.734524 -223.570546)
		(end 403.461982 -223.298004)
		(width 0.14478)
		(layer "In2.Cu")
		(net "M_I_CPU0_SA_DQ<18>")
	)
	(segment
		(start 378.79782 -235.251498)
		(end 378.806202 -235.246672)
		(width 0.0889)
		(layer "In2.Cu")
		(net "M_I_CPU0_SA_DQ<18>")
	)
	(segment
		(start 385.74345 -235.246672)
		(end 385.751832 -235.251498)
		(width 0.0889)
		(layer "In2.Cu")
		(net "M_I_CPU0_SA_DQ<18>")
	)
	(segment
		(start 417.88207 -216.46007)
		(end 418.732208 -217.310208)
		(width 0.14478)
		(layer "In2.Cu")
		(net "M_I_CPU0_SA_DQ<18>")
	)
	(segment
		(start 402.564092 -224.740978)
		(end 402.792692 -224.740978)
		(width 0.14478)
		(layer "In2.Cu")
		(net "M_I_CPU0_SA_DQ<18>")
	)
	(segment
		(start 377.258834 -235.308648)
		(end 377.354846 -235.283248)
		(width 0.0889)
		(layer "In2.Cu")
		(net "M_I_CPU0_SA_DQ<18>")
	)
	(segment
		(start 405.022558 -221.737428)
		(end 405.022558 -221.508828)
		(width 0.14478)
		(layer "In2.Cu")
		(net "M_I_CPU0_SA_DQ<18>")
	)
	(arc
		(start 379.171962 -235.251498)
		(mid 379.454918 -235.327675)
		(end 379.737874 -235.251498)
		(width 0.0889)
		(layer "In2.Cu")
		(net "M_I_CPU0_SA_DQ<18>")
	)
	(arc
		(start 383.871978 -235.251498)
		(mid 384.154934 -235.327675)
		(end 384.43789 -235.251498)
		(width 0.0889)
		(layer "In2.Cu")
		(net "M_I_CPU0_SA_DQ<18>")
	)
	(arc
		(start 385.751832 -235.251498)
		(mid 386.034788 -235.327675)
		(end 386.317744 -235.251498)
		(width 0.0889)
		(layer "In2.Cu")
		(net "M_I_CPU0_SA_DQ<18>")
	)
	(arc
		(start 384.43789 -235.251498)
		(mid 384.624834 -235.201243)
		(end 384.811778 -235.251498)
		(width 0.0889)
		(layer "In2.Cu")
		(net "M_I_CPU0_SA_DQ<18>")
	)
	(arc
		(start 382.931924 -235.251498)
		(mid 383.21488 -235.327675)
		(end 383.497836 -235.251498)
		(width 0.0889)
		(layer "In2.Cu")
		(net "M_I_CPU0_SA_DQ<18>")
	)
	(arc
		(start 386.317744 -235.251498)
		(mid 386.499995 -235.201148)
		(end 386.683504 -235.246672)
		(width 0.0889)
		(layer "In2.Cu")
		(net "M_I_CPU0_SA_DQ<18>")
	)
	(arc
		(start 379.737874 -235.251498)
		(mid 379.924818 -235.201243)
		(end 380.111762 -235.251498)
		(width 0.0889)
		(layer "In2.Cu")
		(net "M_I_CPU0_SA_DQ<18>")
	)
	(arc
		(start 387.63194 -235.251498)
		(mid 387.914896 -235.327675)
		(end 388.197852 -235.251498)
		(width 0.0889)
		(layer "In2.Cu")
		(net "M_I_CPU0_SA_DQ<18>")
	)
	(arc
		(start 388.571994 -235.251498)
		(mid 388.85495 -235.327675)
		(end 389.137906 -235.251498)
		(width 0.0889)
		(layer "In2.Cu")
		(net "M_I_CPU0_SA_DQ<18>")
	)
	(arc
		(start 378.231908 -235.251498)
		(mid 378.514864 -235.327675)
		(end 378.79782 -235.251498)
		(width 0.0889)
		(layer "In2.Cu")
		(net "M_I_CPU0_SA_DQ<18>")
	)
	(arc
		(start 386.691886 -235.251498)
		(mid 386.974842 -235.327675)
		(end 387.257798 -235.251498)
		(width 0.0889)
		(layer "In2.Cu")
		(net "M_I_CPU0_SA_DQ<18>")
	)
	(arc
		(start 380.677674 -235.251498)
		(mid 380.859925 -235.201148)
		(end 381.043434 -235.246672)
		(width 0.0889)
		(layer "In2.Cu")
		(net "M_I_CPU0_SA_DQ<18>")
	)
	(arc
		(start 390.451848 -235.251498)
		(mid 390.734804 -235.327675)
		(end 391.01776 -235.251498)
		(width 0.0889)
		(layer "In2.Cu")
		(net "M_I_CPU0_SA_DQ<18>")
	)
	(arc
		(start 384.811778 -235.251498)
		(mid 385.094734 -235.327675)
		(end 385.37769 -235.251498)
		(width 0.0889)
		(layer "In2.Cu")
		(net "M_I_CPU0_SA_DQ<18>")
	)
	(arc
		(start 389.511794 -235.251498)
		(mid 389.79475 -235.327675)
		(end 390.077706 -235.251498)
		(width 0.0889)
		(layer "In2.Cu")
		(net "M_I_CPU0_SA_DQ<18>")
	)
	(arc
		(start 390.077706 -235.251498)
		(mid 390.259957 -235.201148)
		(end 390.443466 -235.246672)
		(width 0.0889)
		(layer "In2.Cu")
		(net "M_I_CPU0_SA_DQ<18>")
	)
	(arc
		(start 381.617728 -235.251498)
		(mid 381.799979 -235.201148)
		(end 381.983488 -235.246672)
		(width 0.0889)
		(layer "In2.Cu")
		(net "M_I_CPU0_SA_DQ<18>")
	)
	(arc
		(start 377.866148 -235.246672)
		(mid 378.049656 -235.201178)
		(end 378.231908 -235.251498)
		(width 0.0889)
		(layer "In2.Cu")
		(net "M_I_CPU0_SA_DQ<18>")
	)
	(arc
		(start 387.26618 -235.246672)
		(mid 387.449688 -235.201178)
		(end 387.63194 -235.251498)
		(width 0.0889)
		(layer "In2.Cu")
		(net "M_I_CPU0_SA_DQ<18>")
	)
	(arc
		(start 380.111762 -235.251498)
		(mid 380.394718 -235.327675)
		(end 380.677674 -235.251498)
		(width 0.0889)
		(layer "In2.Cu")
		(net "M_I_CPU0_SA_DQ<18>")
	)
	(arc
		(start 385.37769 -235.251498)
		(mid 385.559941 -235.201148)
		(end 385.74345 -235.246672)
		(width 0.0889)
		(layer "In2.Cu")
		(net "M_I_CPU0_SA_DQ<18>")
	)
	(arc
		(start 381.99187 -235.251498)
		(mid 382.274826 -235.327675)
		(end 382.557782 -235.251498)
		(width 0.0889)
		(layer "In2.Cu")
		(net "M_I_CPU0_SA_DQ<18>")
	)
	(arc
		(start 381.051816 -235.251498)
		(mid 381.334772 -235.327675)
		(end 381.617728 -235.251498)
		(width 0.0889)
		(layer "In2.Cu")
		(net "M_I_CPU0_SA_DQ<18>")
	)
	(arc
		(start 377.354846 -235.283248)
		(mid 377.610054 -235.326725)
		(end 377.857766 -235.251498)
		(width 0.0889)
		(layer "In2.Cu")
		(net "M_I_CPU0_SA_DQ<18>")
	)
	(arc
		(start 383.506218 -235.246672)
		(mid 383.689726 -235.201178)
		(end 383.871978 -235.251498)
		(width 0.0889)
		(layer "In2.Cu")
		(net "M_I_CPU0_SA_DQ<18>")
	)
	(arc
		(start 378.806202 -235.246672)
		(mid 378.98971 -235.201178)
		(end 379.171962 -235.251498)
		(width 0.0889)
		(layer "In2.Cu")
		(net "M_I_CPU0_SA_DQ<18>")
	)
	(arc
		(start 391.026142 -235.246672)
		(mid 391.20965 -235.201178)
		(end 391.391902 -235.251498)
		(width 0.0889)
		(layer "In2.Cu")
		(net "M_I_CPU0_SA_DQ<18>")
	)
	(arc
		(start 391.391902 -235.251498)
		(mid 391.668715 -235.327641)
		(end 391.947146 -235.257594)
		(width 0.0889)
		(layer "In2.Cu")
		(net "M_I_CPU0_SA_DQ<18>")
	)
	(arc
		(start 388.206234 -235.246672)
		(mid 388.389742 -235.201178)
		(end 388.571994 -235.251498)
		(width 0.0889)
		(layer "In2.Cu")
		(net "M_I_CPU0_SA_DQ<18>")
	)
	(arc
		(start 389.137906 -235.251498)
		(mid 389.32485 -235.201243)
		(end 389.511794 -235.251498)
		(width 0.0889)
		(layer "In2.Cu")
		(net "M_I_CPU0_SA_DQ<18>")
	)
	(arc
		(start 382.566164 -235.246672)
		(mid 382.749672 -235.201178)
		(end 382.931924 -235.251498)
		(width 0.0889)
		(layer "In2.Cu")
		(net "M_I_CPU0_SA_DQ<18>")
	)
	(segment
		(start 375.698004 -235.840016)
		(end 376.164856 -235.574078)
		(width 0.10668)
		(layer "F.Cu")
		(net "M_I_CPU0_SA_DQ<17>")
	)
	(segment
		(start 391.468356 -235.83773)
		(end 393.1031 -234.772708)
		(width 0.0889)
		(layer "In2.Cu")
		(net "M_I_CPU0_SA_DQ<17>")
	)
	(segment
		(start 431.131218 -217.310208)
		(end 431.55616 -217.73515)
		(width 0.14478)
		(layer "In2.Cu")
		(net "M_I_CPU0_SA_DQ<17>")
	)
	(segment
		(start 376.343418 -235.901484)
		(end 376.3518 -235.896658)
		(width 0.0889)
		(layer "In2.Cu")
		(net "M_I_CPU0_SA_DQ<17>")
	)
	(segment
		(start 393.766294 -234.11688)
		(end 394.383768 -233.193082)
		(width 0.0889)
		(layer "In2.Cu")
		(net "M_I_CPU0_SA_DQ<17>")
	)
	(segment
		(start 422.284398 -217.310208)
		(end 431.131218 -217.310208)
		(width 0.14478)
		(layer "In2.Cu")
		(net "M_I_CPU0_SA_DQ<17>")
	)
	(segment
		(start 386.683504 -235.901484)
		(end 386.691886 -235.896658)
		(width 0.0889)
		(layer "In2.Cu")
		(net "M_I_CPU0_SA_DQ<17>")
	)
	(segment
		(start 381.983488 -235.901484)
		(end 381.99187 -235.896658)
		(width 0.0889)
		(layer "In2.Cu")
		(net "M_I_CPU0_SA_DQ<17>")
	)
	(segment
		(start 376.164856 -235.574078)
		(end 376.010678 -235.839508)
		(width 0.0889)
		(layer "In2.Cu")
		(net "M_I_CPU0_SA_DQ<17>")
	)
	(segment
		(start 394.667994 -232.959656)
		(end 395.630146 -232.56113)
		(width 0.0889)
		(layer "In2.Cu")
		(net "M_I_CPU0_SA_DQ<17>")
	)
	(segment
		(start 414.970214 -217.310208)
		(end 418.047678 -217.310208)
		(width 0.14478)
		(layer "In2.Cu")
		(net "M_I_CPU0_SA_DQ<17>")
	)
	(segment
		(start 395.86281 -232.328466)
		(end 405.851868 -222.339408)
		(width 0.14478)
		(layer "In2.Cu")
		(net "M_I_CPU0_SA_DQ<17>")
	)
	(segment
		(start 387.257798 -235.896658)
		(end 387.26618 -235.901484)
		(width 0.0889)
		(layer "In2.Cu")
		(net "M_I_CPU0_SA_DQ<17>")
	)
	(segment
		(start 418.047678 -217.310208)
		(end 418.897562 -218.160092)
		(width 0.14478)
		(layer "In2.Cu")
		(net "M_I_CPU0_SA_DQ<17>")
	)
	(segment
		(start 414.12033 -218.160092)
		(end 414.970214 -217.310208)
		(width 0.14478)
		(layer "In2.Cu")
		(net "M_I_CPU0_SA_DQ<17>")
	)
	(segment
		(start 409.007564 -218.160092)
		(end 414.12033 -218.160092)
		(width 0.14478)
		(layer "In2.Cu")
		(net "M_I_CPU0_SA_DQ<17>")
	)
	(segment
		(start 381.043434 -235.901484)
		(end 381.051816 -235.896658)
		(width 0.0889)
		(layer "In2.Cu")
		(net "M_I_CPU0_SA_DQ<17>")
	)
	(segment
		(start 418.897562 -218.160092)
		(end 421.434514 -218.160092)
		(width 0.14478)
		(layer "In2.Cu")
		(net "M_I_CPU0_SA_DQ<17>")
	)
	(segment
		(start 385.74345 -235.901484)
		(end 385.751832 -235.896658)
		(width 0.0889)
		(layer "In2.Cu")
		(net "M_I_CPU0_SA_DQ<17>")
	)
	(segment
		(start 378.79782 -235.896658)
		(end 378.806202 -235.901484)
		(width 0.0889)
		(layer "In2.Cu")
		(net "M_I_CPU0_SA_DQ<17>")
	)
	(segment
		(start 382.557782 -235.896658)
		(end 382.566164 -235.901484)
		(width 0.0889)
		(layer "In2.Cu")
		(net "M_I_CPU0_SA_DQ<17>")
	)
	(segment
		(start 393.1031 -234.772708)
		(end 393.766294 -234.11688)
		(width 0.0889)
		(layer "In2.Cu")
		(net "M_I_CPU0_SA_DQ<17>")
	)
	(segment
		(start 421.434514 -218.160092)
		(end 422.284398 -217.310208)
		(width 0.14478)
		(layer "In2.Cu")
		(net "M_I_CPU0_SA_DQ<17>")
	)
	(segment
		(start 394.383768 -233.193082)
		(end 394.667994 -232.959656)
		(width 0.0889)
		(layer "In2.Cu")
		(net "M_I_CPU0_SA_DQ<17>")
	)
	(segment
		(start 395.630146 -232.56113)
		(end 395.86281 -232.328466)
		(width 0.0889)
		(layer "In2.Cu")
		(net "M_I_CPU0_SA_DQ<17>")
	)
	(segment
		(start 376.010678 -235.839508)
		(end 376.03303 -235.92282)
		(width 0.0889)
		(layer "In2.Cu")
		(net "M_I_CPU0_SA_DQ<17>")
	)
	(segment
		(start 388.197852 -235.896658)
		(end 388.206234 -235.901484)
		(width 0.0889)
		(layer "In2.Cu")
		(net "M_I_CPU0_SA_DQ<17>")
	)
	(segment
		(start 383.497836 -235.896658)
		(end 383.506218 -235.901484)
		(width 0.0889)
		(layer "In2.Cu")
		(net "M_I_CPU0_SA_DQ<17>")
	)
	(segment
		(start 405.851868 -221.315788)
		(end 409.007564 -218.160092)
		(width 0.14478)
		(layer "In2.Cu")
		(net "M_I_CPU0_SA_DQ<17>")
	)
	(segment
		(start 377.857766 -235.896658)
		(end 377.866148 -235.901484)
		(width 0.0889)
		(layer "In2.Cu")
		(net "M_I_CPU0_SA_DQ<17>")
	)
	(segment
		(start 405.851868 -222.339408)
		(end 405.851868 -221.315788)
		(width 0.14478)
		(layer "In2.Cu")
		(net "M_I_CPU0_SA_DQ<17>")
	)
	(segment
		(start 390.443466 -235.901484)
		(end 390.451848 -235.896658)
		(width 0.0889)
		(layer "In2.Cu")
		(net "M_I_CPU0_SA_DQ<17>")
	)
	(segment
		(start 391.01776 -235.896658)
		(end 391.026142 -235.901484)
		(width 0.0889)
		(layer "In2.Cu")
		(net "M_I_CPU0_SA_DQ<17>")
	)
	(segment
		(start 377.283472 -235.901484)
		(end 377.291854 -235.896658)
		(width 0.0889)
		(layer "In2.Cu")
		(net "M_I_CPU0_SA_DQ<17>")
	)
	(arc
		(start 381.617728 -235.896658)
		(mid 381.799979 -235.947008)
		(end 381.983488 -235.901484)
		(width 0.0889)
		(layer "In2.Cu")
		(net "M_I_CPU0_SA_DQ<17>")
	)
	(arc
		(start 389.137906 -235.896658)
		(mid 389.32485 -235.946913)
		(end 389.511794 -235.896658)
		(width 0.0889)
		(layer "In2.Cu")
		(net "M_I_CPU0_SA_DQ<17>")
	)
	(arc
		(start 385.37769 -235.896658)
		(mid 385.559941 -235.947008)
		(end 385.74345 -235.901484)
		(width 0.0889)
		(layer "In2.Cu")
		(net "M_I_CPU0_SA_DQ<17>")
	)
	(arc
		(start 388.571994 -235.896658)
		(mid 388.85495 -235.820481)
		(end 389.137906 -235.896658)
		(width 0.0889)
		(layer "In2.Cu")
		(net "M_I_CPU0_SA_DQ<17>")
	)
	(arc
		(start 377.866148 -235.901484)
		(mid 378.049656 -235.946978)
		(end 378.231908 -235.896658)
		(width 0.0889)
		(layer "In2.Cu")
		(net "M_I_CPU0_SA_DQ<17>")
	)
	(arc
		(start 380.111762 -235.896658)
		(mid 380.394718 -235.820481)
		(end 380.677674 -235.896658)
		(width 0.0889)
		(layer "In2.Cu")
		(net "M_I_CPU0_SA_DQ<17>")
	)
	(arc
		(start 381.051816 -235.896658)
		(mid 381.334772 -235.820481)
		(end 381.617728 -235.896658)
		(width 0.0889)
		(layer "In2.Cu")
		(net "M_I_CPU0_SA_DQ<17>")
	)
	(arc
		(start 386.317744 -235.896658)
		(mid 386.499995 -235.947008)
		(end 386.683504 -235.901484)
		(width 0.0889)
		(layer "In2.Cu")
		(net "M_I_CPU0_SA_DQ<17>")
	)
	(arc
		(start 382.931924 -235.896658)
		(mid 383.21488 -235.820481)
		(end 383.497836 -235.896658)
		(width 0.0889)
		(layer "In2.Cu")
		(net "M_I_CPU0_SA_DQ<17>")
	)
	(arc
		(start 381.99187 -235.896658)
		(mid 382.274826 -235.820481)
		(end 382.557782 -235.896658)
		(width 0.0889)
		(layer "In2.Cu")
		(net "M_I_CPU0_SA_DQ<17>")
	)
	(arc
		(start 378.806202 -235.901484)
		(mid 378.98971 -235.946978)
		(end 379.171962 -235.896658)
		(width 0.0889)
		(layer "In2.Cu")
		(net "M_I_CPU0_SA_DQ<17>")
	)
	(arc
		(start 391.026142 -235.901484)
		(mid 391.20965 -235.946978)
		(end 391.391902 -235.896658)
		(width 0.0889)
		(layer "In2.Cu")
		(net "M_I_CPU0_SA_DQ<17>")
	)
	(arc
		(start 376.917712 -235.896658)
		(mid 377.099963 -235.947008)
		(end 377.283472 -235.901484)
		(width 0.0889)
		(layer "In2.Cu")
		(net "M_I_CPU0_SA_DQ<17>")
	)
	(arc
		(start 386.691886 -235.896658)
		(mid 386.974842 -235.820481)
		(end 387.257798 -235.896658)
		(width 0.0889)
		(layer "In2.Cu")
		(net "M_I_CPU0_SA_DQ<17>")
	)
	(arc
		(start 376.03303 -235.92282)
		(mid 376.19054 -235.946018)
		(end 376.343418 -235.901484)
		(width 0.0889)
		(layer "In2.Cu")
		(net "M_I_CPU0_SA_DQ<17>")
	)
	(arc
		(start 379.171962 -235.896658)
		(mid 379.454918 -235.820481)
		(end 379.737874 -235.896658)
		(width 0.0889)
		(layer "In2.Cu")
		(net "M_I_CPU0_SA_DQ<17>")
	)
	(arc
		(start 376.3518 -235.896658)
		(mid 376.634756 -235.820481)
		(end 376.917712 -235.896658)
		(width 0.0889)
		(layer "In2.Cu")
		(net "M_I_CPU0_SA_DQ<17>")
	)
	(arc
		(start 388.206234 -235.901484)
		(mid 388.389742 -235.946978)
		(end 388.571994 -235.896658)
		(width 0.0889)
		(layer "In2.Cu")
		(net "M_I_CPU0_SA_DQ<17>")
	)
	(arc
		(start 384.811778 -235.896658)
		(mid 385.094734 -235.820481)
		(end 385.37769 -235.896658)
		(width 0.0889)
		(layer "In2.Cu")
		(net "M_I_CPU0_SA_DQ<17>")
	)
	(arc
		(start 383.506218 -235.901484)
		(mid 383.689726 -235.946978)
		(end 383.871978 -235.896658)
		(width 0.0889)
		(layer "In2.Cu")
		(net "M_I_CPU0_SA_DQ<17>")
	)
	(arc
		(start 378.231908 -235.896658)
		(mid 378.514864 -235.820481)
		(end 378.79782 -235.896658)
		(width 0.0889)
		(layer "In2.Cu")
		(net "M_I_CPU0_SA_DQ<17>")
	)
	(arc
		(start 389.511794 -235.896658)
		(mid 389.79475 -235.820481)
		(end 390.077706 -235.896658)
		(width 0.0889)
		(layer "In2.Cu")
		(net "M_I_CPU0_SA_DQ<17>")
	)
	(arc
		(start 390.451848 -235.896658)
		(mid 390.734804 -235.820481)
		(end 391.01776 -235.896658)
		(width 0.0889)
		(layer "In2.Cu")
		(net "M_I_CPU0_SA_DQ<17>")
	)
	(arc
		(start 390.077706 -235.896658)
		(mid 390.259957 -235.947008)
		(end 390.443466 -235.901484)
		(width 0.0889)
		(layer "In2.Cu")
		(net "M_I_CPU0_SA_DQ<17>")
	)
	(arc
		(start 382.566164 -235.901484)
		(mid 382.749672 -235.946978)
		(end 382.931924 -235.896658)
		(width 0.0889)
		(layer "In2.Cu")
		(net "M_I_CPU0_SA_DQ<17>")
	)
	(arc
		(start 377.291854 -235.896658)
		(mid 377.57481 -235.820481)
		(end 377.857766 -235.896658)
		(width 0.0889)
		(layer "In2.Cu")
		(net "M_I_CPU0_SA_DQ<17>")
	)
	(arc
		(start 387.63194 -235.896658)
		(mid 387.914896 -235.820481)
		(end 388.197852 -235.896658)
		(width 0.0889)
		(layer "In2.Cu")
		(net "M_I_CPU0_SA_DQ<17>")
	)
	(arc
		(start 391.391902 -235.896658)
		(mid 391.432047 -235.869682)
		(end 391.468356 -235.83773)
		(width 0.0889)
		(layer "In2.Cu")
		(net "M_I_CPU0_SA_DQ<17>")
	)
	(arc
		(start 387.26618 -235.901484)
		(mid 387.449688 -235.946978)
		(end 387.63194 -235.896658)
		(width 0.0889)
		(layer "In2.Cu")
		(net "M_I_CPU0_SA_DQ<17>")
	)
	(arc
		(start 385.751832 -235.896658)
		(mid 386.034788 -235.820481)
		(end 386.317744 -235.896658)
		(width 0.0889)
		(layer "In2.Cu")
		(net "M_I_CPU0_SA_DQ<17>")
	)
	(arc
		(start 380.677674 -235.896658)
		(mid 380.859925 -235.947008)
		(end 381.043434 -235.901484)
		(width 0.0889)
		(layer "In2.Cu")
		(net "M_I_CPU0_SA_DQ<17>")
	)
	(arc
		(start 384.43789 -235.896658)
		(mid 384.624834 -235.946913)
		(end 384.811778 -235.896658)
		(width 0.0889)
		(layer "In2.Cu")
		(net "M_I_CPU0_SA_DQ<17>")
	)
	(arc
		(start 379.737874 -235.896658)
		(mid 379.924818 -235.946913)
		(end 380.111762 -235.896658)
		(width 0.0889)
		(layer "In2.Cu")
		(net "M_I_CPU0_SA_DQ<17>")
	)
	(arc
		(start 383.871978 -235.896658)
		(mid 384.154934 -235.820481)
		(end 384.43789 -235.896658)
		(width 0.0889)
		(layer "In2.Cu")
		(net "M_I_CPU0_SA_DQ<17>")
	)
	(segment
		(start 377.107958 -235.03001)
		(end 377.57481 -234.764072)
		(width 0.10668)
		(layer "F.Cu")
		(net "M_I_CPU0_SA_DQ<16>")
	)
	(segment
		(start 394.054076 -232.47731)
		(end 394.054076 -231.894634)
		(width 0.0889)
		(layer "In2.Cu")
		(net "M_I_CPU0_SA_DQ<16>")
	)
	(segment
		(start 418.5666 -216.46007)
		(end 421.62476 -216.46007)
		(width 0.14478)
		(layer "In2.Cu")
		(net "M_I_CPU0_SA_DQ<16>")
	)
	(segment
		(start 389.607806 -235.086652)
		(end 389.616188 -235.091478)
		(width 0.0889)
		(layer "In2.Cu")
		(net "M_I_CPU0_SA_DQ<16>")
	)
	(segment
		(start 388.093458 -235.091478)
		(end 388.10184 -235.086652)
		(width 0.0889)
		(layer "In2.Cu")
		(net "M_I_CPU0_SA_DQ<16>")
	)
	(segment
		(start 392.651996 -233.87939)
		(end 394.054076 -232.47731)
		(width 0.0889)
		(layer "In2.Cu")
		(net "M_I_CPU0_SA_DQ<16>")
	)
	(segment
		(start 380.207774 -235.086652)
		(end 380.216156 -235.091478)
		(width 0.0889)
		(layer "In2.Cu")
		(net "M_I_CPU0_SA_DQ<16>")
	)
	(segment
		(start 422.474644 -215.610186)
		(end 431.131218 -215.610186)
		(width 0.14478)
		(layer "In2.Cu")
		(net "M_I_CPU0_SA_DQ<16>")
	)
	(segment
		(start 385.847844 -235.086652)
		(end 385.856226 -235.091478)
		(width 0.0889)
		(layer "In2.Cu")
		(net "M_I_CPU0_SA_DQ<16>")
	)
	(segment
		(start 392.651996 -234.296458)
		(end 392.651996 -233.87939)
		(width 0.0889)
		(layer "In2.Cu")
		(net "M_I_CPU0_SA_DQ<16>")
	)
	(segment
		(start 379.63348 -235.091478)
		(end 379.641862 -235.086652)
		(width 0.0889)
		(layer "In2.Cu")
		(net "M_I_CPU0_SA_DQ<16>")
	)
	(segment
		(start 389.033512 -235.091478)
		(end 389.041894 -235.086652)
		(width 0.0889)
		(layer "In2.Cu")
		(net "M_I_CPU0_SA_DQ<16>")
	)
	(segment
		(start 378.693426 -235.091478)
		(end 378.701808 -235.086652)
		(width 0.0889)
		(layer "In2.Cu")
		(net "M_I_CPU0_SA_DQ<16>")
	)
	(segment
		(start 401.451826 -225.436684)
		(end 401.451826 -224.443544)
		(width 0.14478)
		(layer "In2.Cu")
		(net "M_I_CPU0_SA_DQ<16>")
	)
	(segment
		(start 381.147828 -235.086652)
		(end 381.15621 -235.091478)
		(width 0.0889)
		(layer "In2.Cu")
		(net "M_I_CPU0_SA_DQ<16>")
	)
	(segment
		(start 401.451826 -224.443544)
		(end 409.4353 -216.46007)
		(width 0.14478)
		(layer "In2.Cu")
		(net "M_I_CPU0_SA_DQ<16>")
	)
	(segment
		(start 414.114234 -216.46007)
		(end 414.964118 -215.610186)
		(width 0.14478)
		(layer "In2.Cu")
		(net "M_I_CPU0_SA_DQ<16>")
	)
	(segment
		(start 391.861802 -235.086652)
		(end 392.651996 -234.296458)
		(width 0.0889)
		(layer "In2.Cu")
		(net "M_I_CPU0_SA_DQ<16>")
	)
	(segment
		(start 391.85342 -235.091478)
		(end 391.861802 -235.086652)
		(width 0.0889)
		(layer "In2.Cu")
		(net "M_I_CPU0_SA_DQ<16>")
	)
	(segment
		(start 394.900658 -231.434386)
		(end 395.454124 -231.434386)
		(width 0.14478)
		(layer "In2.Cu")
		(net "M_I_CPU0_SA_DQ<16>")
	)
	(segment
		(start 384.333496 -235.091478)
		(end 384.341878 -235.086652)
		(width 0.0889)
		(layer "In2.Cu")
		(net "M_I_CPU0_SA_DQ<16>")
	)
	(segment
		(start 394.514324 -231.434386)
		(end 394.900658 -231.434386)
		(width 0.0889)
		(layer "In2.Cu")
		(net "M_I_CPU0_SA_DQ<16>")
	)
	(segment
		(start 414.964118 -215.610186)
		(end 417.716716 -215.610186)
		(width 0.14478)
		(layer "In2.Cu")
		(net "M_I_CPU0_SA_DQ<16>")
	)
	(segment
		(start 409.4353 -216.46007)
		(end 414.114234 -216.46007)
		(width 0.14478)
		(layer "In2.Cu")
		(net "M_I_CPU0_SA_DQ<16>")
	)
	(segment
		(start 394.054076 -231.894634)
		(end 394.514324 -231.434386)
		(width 0.0889)
		(layer "In2.Cu")
		(net "M_I_CPU0_SA_DQ<16>")
	)
	(segment
		(start 377.57481 -234.764072)
		(end 377.420886 -235.029502)
		(width 0.0889)
		(layer "In2.Cu")
		(net "M_I_CPU0_SA_DQ<16>")
	)
	(segment
		(start 417.716716 -215.610186)
		(end 418.5666 -216.46007)
		(width 0.14478)
		(layer "In2.Cu")
		(net "M_I_CPU0_SA_DQ<16>")
	)
	(segment
		(start 377.420886 -235.029502)
		(end 377.443238 -235.112814)
		(width 0.0889)
		(layer "In2.Cu")
		(net "M_I_CPU0_SA_DQ<16>")
	)
	(segment
		(start 431.131218 -215.610186)
		(end 431.55616 -216.035128)
		(width 0.14478)
		(layer "In2.Cu")
		(net "M_I_CPU0_SA_DQ<16>")
	)
	(segment
		(start 395.454124 -231.434386)
		(end 401.451826 -225.436684)
		(width 0.14478)
		(layer "In2.Cu")
		(net "M_I_CPU0_SA_DQ<16>")
	)
	(segment
		(start 421.62476 -216.46007)
		(end 422.474644 -215.610186)
		(width 0.14478)
		(layer "In2.Cu")
		(net "M_I_CPU0_SA_DQ<16>")
	)
	(segment
		(start 384.90779 -235.086652)
		(end 384.916172 -235.091478)
		(width 0.0889)
		(layer "In2.Cu")
		(net "M_I_CPU0_SA_DQ<16>")
	)
	(segment
		(start 383.393442 -235.091478)
		(end 383.401824 -235.086652)
		(width 0.0889)
		(layer "In2.Cu")
		(net "M_I_CPU0_SA_DQ<16>")
	)
	(arc
		(start 383.401824 -235.086652)
		(mid 383.68478 -235.010475)
		(end 383.967736 -235.086652)
		(width 0.0889)
		(layer "In2.Cu")
		(net "M_I_CPU0_SA_DQ<16>")
	)
	(arc
		(start 385.856226 -235.091478)
		(mid 386.039734 -235.136972)
		(end 386.221986 -235.086652)
		(width 0.0889)
		(layer "In2.Cu")
		(net "M_I_CPU0_SA_DQ<16>")
	)
	(arc
		(start 380.581916 -235.086652)
		(mid 380.864872 -235.010475)
		(end 381.147828 -235.086652)
		(width 0.0889)
		(layer "In2.Cu")
		(net "M_I_CPU0_SA_DQ<16>")
	)
	(arc
		(start 387.727698 -235.086652)
		(mid 387.909949 -235.137002)
		(end 388.093458 -235.091478)
		(width 0.0889)
		(layer "In2.Cu")
		(net "M_I_CPU0_SA_DQ<16>")
	)
	(arc
		(start 386.221986 -235.086652)
		(mid 386.504942 -235.010475)
		(end 386.787898 -235.086652)
		(width 0.0889)
		(layer "In2.Cu")
		(net "M_I_CPU0_SA_DQ<16>")
	)
	(arc
		(start 389.616188 -235.091478)
		(mid 389.799696 -235.136972)
		(end 389.981948 -235.086652)
		(width 0.0889)
		(layer "In2.Cu")
		(net "M_I_CPU0_SA_DQ<16>")
	)
	(arc
		(start 389.041894 -235.086652)
		(mid 389.32485 -235.010475)
		(end 389.607806 -235.086652)
		(width 0.0889)
		(layer "In2.Cu")
		(net "M_I_CPU0_SA_DQ<16>")
	)
	(arc
		(start 378.327666 -235.086652)
		(mid 378.509917 -235.137002)
		(end 378.693426 -235.091478)
		(width 0.0889)
		(layer "In2.Cu")
		(net "M_I_CPU0_SA_DQ<16>")
	)
	(arc
		(start 391.48766 -235.086652)
		(mid 391.669911 -235.137002)
		(end 391.85342 -235.091478)
		(width 0.0889)
		(layer "In2.Cu")
		(net "M_I_CPU0_SA_DQ<16>")
	)
	(arc
		(start 389.981948 -235.086652)
		(mid 390.264904 -235.010475)
		(end 390.54786 -235.086652)
		(width 0.0889)
		(layer "In2.Cu")
		(net "M_I_CPU0_SA_DQ<16>")
	)
	(arc
		(start 386.787898 -235.086652)
		(mid 386.974842 -235.136907)
		(end 387.161786 -235.086652)
		(width 0.0889)
		(layer "In2.Cu")
		(net "M_I_CPU0_SA_DQ<16>")
	)
	(arc
		(start 387.161786 -235.086652)
		(mid 387.444742 -235.010475)
		(end 387.727698 -235.086652)
		(width 0.0889)
		(layer "In2.Cu")
		(net "M_I_CPU0_SA_DQ<16>")
	)
	(arc
		(start 378.701808 -235.086652)
		(mid 378.984764 -235.010475)
		(end 379.26772 -235.086652)
		(width 0.0889)
		(layer "In2.Cu")
		(net "M_I_CPU0_SA_DQ<16>")
	)
	(arc
		(start 380.216156 -235.091478)
		(mid 380.399664 -235.136972)
		(end 380.581916 -235.086652)
		(width 0.0889)
		(layer "In2.Cu")
		(net "M_I_CPU0_SA_DQ<16>")
	)
	(arc
		(start 377.761754 -235.086652)
		(mid 378.04471 -235.010475)
		(end 378.327666 -235.086652)
		(width 0.0889)
		(layer "In2.Cu")
		(net "M_I_CPU0_SA_DQ<16>")
	)
	(arc
		(start 384.916172 -235.091478)
		(mid 385.09968 -235.136972)
		(end 385.281932 -235.086652)
		(width 0.0889)
		(layer "In2.Cu")
		(net "M_I_CPU0_SA_DQ<16>")
	)
	(arc
		(start 379.26772 -235.086652)
		(mid 379.449971 -235.137002)
		(end 379.63348 -235.091478)
		(width 0.0889)
		(layer "In2.Cu")
		(net "M_I_CPU0_SA_DQ<16>")
	)
	(arc
		(start 388.667752 -235.086652)
		(mid 388.850003 -235.137002)
		(end 389.033512 -235.091478)
		(width 0.0889)
		(layer "In2.Cu")
		(net "M_I_CPU0_SA_DQ<16>")
	)
	(arc
		(start 381.15621 -235.091478)
		(mid 381.339718 -235.136972)
		(end 381.52197 -235.086652)
		(width 0.0889)
		(layer "In2.Cu")
		(net "M_I_CPU0_SA_DQ<16>")
	)
	(arc
		(start 385.281932 -235.086652)
		(mid 385.564888 -235.010475)
		(end 385.847844 -235.086652)
		(width 0.0889)
		(layer "In2.Cu")
		(net "M_I_CPU0_SA_DQ<16>")
	)
	(arc
		(start 377.443238 -235.112814)
		(mid 377.605427 -235.135549)
		(end 377.761754 -235.086652)
		(width 0.0889)
		(layer "In2.Cu")
		(net "M_I_CPU0_SA_DQ<16>")
	)
	(arc
		(start 383.027682 -235.086652)
		(mid 383.209933 -235.137002)
		(end 383.393442 -235.091478)
		(width 0.0889)
		(layer "In2.Cu")
		(net "M_I_CPU0_SA_DQ<16>")
	)
	(arc
		(start 381.52197 -235.086652)
		(mid 381.804926 -235.010475)
		(end 382.087882 -235.086652)
		(width 0.0889)
		(layer "In2.Cu")
		(net "M_I_CPU0_SA_DQ<16>")
	)
	(arc
		(start 379.641862 -235.086652)
		(mid 379.924818 -235.010475)
		(end 380.207774 -235.086652)
		(width 0.0889)
		(layer "In2.Cu")
		(net "M_I_CPU0_SA_DQ<16>")
	)
	(arc
		(start 390.921748 -235.086652)
		(mid 391.204704 -235.010475)
		(end 391.48766 -235.086652)
		(width 0.0889)
		(layer "In2.Cu")
		(net "M_I_CPU0_SA_DQ<16>")
	)
	(arc
		(start 382.087882 -235.086652)
		(mid 382.274826 -235.136907)
		(end 382.46177 -235.086652)
		(width 0.0889)
		(layer "In2.Cu")
		(net "M_I_CPU0_SA_DQ<16>")
	)
	(arc
		(start 390.54786 -235.086652)
		(mid 390.734804 -235.136907)
		(end 390.921748 -235.086652)
		(width 0.0889)
		(layer "In2.Cu")
		(net "M_I_CPU0_SA_DQ<16>")
	)
	(arc
		(start 382.46177 -235.086652)
		(mid 382.744726 -235.010475)
		(end 383.027682 -235.086652)
		(width 0.0889)
		(layer "In2.Cu")
		(net "M_I_CPU0_SA_DQ<16>")
	)
	(arc
		(start 383.967736 -235.086652)
		(mid 384.149987 -235.137002)
		(end 384.333496 -235.091478)
		(width 0.0889)
		(layer "In2.Cu")
		(net "M_I_CPU0_SA_DQ<16>")
	)
	(arc
		(start 384.341878 -235.086652)
		(mid 384.624834 -235.010475)
		(end 384.90779 -235.086652)
		(width 0.0889)
		(layer "In2.Cu")
		(net "M_I_CPU0_SA_DQ<16>")
	)
	(arc
		(start 388.10184 -235.086652)
		(mid 388.384796 -235.010475)
		(end 388.667752 -235.086652)
		(width 0.0889)
		(layer "In2.Cu")
		(net "M_I_CPU0_SA_DQ<16>")
	)
	(segment
		(start 375.22785 -235.03001)
		(end 375.694702 -234.764072)
		(width 0.10668)
		(layer "F.Cu")
		(net "M_I_CPU0_SA_DQ<15>")
	)
	(segment
		(start 376.447812 -234.441492)
		(end 376.456194 -234.436666)
		(width 0.0889)
		(layer "In2.Cu")
		(net "M_I_CPU0_SA_DQ<15>")
	)
	(segment
		(start 406.759156 -218.128342)
		(end 406.642062 -218.011248)
		(width 0.14478)
		(layer "In2.Cu")
		(net "M_I_CPU0_SA_DQ<15>")
	)
	(segment
		(start 401.180046 -223.245172)
		(end 401.342098 -223.08312)
		(width 0.14478)
		(layer "In2.Cu")
		(net "M_I_CPU0_SA_DQ<15>")
	)
	(segment
		(start 421.602408 -215.610186)
		(end 422.452546 -214.760048)
		(width 0.14478)
		(layer "In2.Cu")
		(net "M_I_CPU0_SA_DQ<15>")
	)
	(segment
		(start 402.857716 -222.029782)
		(end 402.740622 -221.912688)
		(width 0.14478)
		(layer "In2.Cu")
		(net "M_I_CPU0_SA_DQ<15>")
	)
	(segment
		(start 375.84888 -234.498642)
		(end 375.945146 -234.473242)
		(width 0.0889)
		(layer "In2.Cu")
		(net "M_I_CPU0_SA_DQ<15>")
	)
	(segment
		(start 405.081486 -219.571824)
		(end 405.081486 -219.343732)
		(width 0.14478)
		(layer "In2.Cu")
		(net "M_I_CPU0_SA_DQ<15>")
	)
	(segment
		(start 384.333496 -234.436666)
		(end 384.341878 -234.441492)
		(width 0.0889)
		(layer "In2.Cu")
		(net "M_I_CPU0_SA_DQ<15>")
	)
	(segment
		(start 383.393442 -234.436666)
		(end 383.401824 -234.441492)
		(width 0.0889)
		(layer "In2.Cu")
		(net "M_I_CPU0_SA_DQ<15>")
	)
	(segment
		(start 404.46325 -219.961968)
		(end 404.691342 -219.961968)
		(width 0.14478)
		(layer "In2.Cu")
		(net "M_I_CPU0_SA_DQ<15>")
	)
	(segment
		(start 414.85566 -214.760048)
		(end 417.700714 -214.760048)
		(width 0.14478)
		(layer "In2.Cu")
		(net "M_I_CPU0_SA_DQ<15>")
	)
	(segment
		(start 408.319732 -216.567766)
		(end 408.202638 -216.450672)
		(width 0.14478)
		(layer "In2.Cu")
		(net "M_I_CPU0_SA_DQ<15>")
	)
	(segment
		(start 400.900646 -224.215198)
		(end 401.29714 -223.818704)
		(width 0.14478)
		(layer "In2.Cu")
		(net "M_I_CPU0_SA_DQ<15>")
	)
	(segment
		(start 403.475952 -221.639892)
		(end 403.638004 -221.47784)
		(width 0.14478)
		(layer "In2.Cu")
		(net "M_I_CPU0_SA_DQ<15>")
	)
	(segment
		(start 407.539444 -217.348054)
		(end 407.42235 -217.23096)
		(width 0.14478)
		(layer "In2.Cu")
		(net "M_I_CPU0_SA_DQ<15>")
	)
	(segment
		(start 391.983214 -234.245912)
		(end 393.763754 -232.465372)
		(width 0.0889)
		(layer "In2.Cu")
		(net "M_I_CPU0_SA_DQ<15>")
	)
	(segment
		(start 407.1493 -217.738452)
		(end 407.377392 -217.738452)
		(width 0.14478)
		(layer "In2.Cu")
		(net "M_I_CPU0_SA_DQ<15>")
	)
	(segment
		(start 401.960334 -222.464884)
		(end 402.122386 -222.302832)
		(width 0.14478)
		(layer "In2.Cu")
		(net "M_I_CPU0_SA_DQ<15>")
	)
	(segment
		(start 380.207774 -234.441492)
		(end 380.216156 -234.436666)
		(width 0.0889)
		(layer "In2.Cu")
		(net "M_I_CPU0_SA_DQ<15>")
	)
	(segment
		(start 405.816816 -219.299028)
		(end 405.978868 -219.136976)
		(width 0.14478)
		(layer "In2.Cu")
		(net "M_I_CPU0_SA_DQ<15>")
	)
	(segment
		(start 401.915376 -223.200468)
		(end 402.077428 -223.038416)
		(width 0.14478)
		(layer "In2.Cu")
		(net "M_I_CPU0_SA_DQ<15>")
	)
	(segment
		(start 389.607806 -234.441492)
		(end 389.616188 -234.436666)
		(width 0.0889)
		(layer "In2.Cu")
		(net "M_I_CPU0_SA_DQ<15>")
	)
	(segment
		(start 403.638004 -221.249494)
		(end 403.52091 -221.1324)
		(width 0.14478)
		(layer "In2.Cu")
		(net "M_I_CPU0_SA_DQ<15>")
	)
	(segment
		(start 404.691342 -219.961968)
		(end 404.808436 -220.079316)
		(width 0.14478)
		(layer "In2.Cu")
		(net "M_I_CPU0_SA_DQ<15>")
	)
	(segment
		(start 407.42235 -217.002868)
		(end 407.584402 -216.840816)
		(width 0.14478)
		(layer "In2.Cu")
		(net "M_I_CPU0_SA_DQ<15>")
	)
	(segment
		(start 418.550852 -215.610186)
		(end 421.602408 -215.610186)
		(width 0.14478)
		(layer "In2.Cu")
		(net "M_I_CPU0_SA_DQ<15>")
	)
	(segment
		(start 414.005522 -215.610186)
		(end 414.85566 -214.760048)
		(width 0.14478)
		(layer "In2.Cu")
		(net "M_I_CPU0_SA_DQ<15>")
	)
	(segment
		(start 389.033512 -234.436666)
		(end 389.041894 -234.441492)
		(width 0.0889)
		(layer "In2.Cu")
		(net "M_I_CPU0_SA_DQ<15>")
	)
	(segment
		(start 404.418292 -220.697552)
		(end 404.418292 -220.469206)
		(width 0.14478)
		(layer "In2.Cu")
		(net "M_I_CPU0_SA_DQ<15>")
	)
	(segment
		(start 422.452546 -214.760048)
		(end 427.03115 -214.760048)
		(width 0.14478)
		(layer "In2.Cu")
		(net "M_I_CPU0_SA_DQ<15>")
	)
	(segment
		(start 404.808436 -220.079316)
		(end 405.036528 -220.079316)
		(width 0.14478)
		(layer "In2.Cu")
		(net "M_I_CPU0_SA_DQ<15>")
	)
	(segment
		(start 408.36469 -216.060528)
		(end 408.592782 -216.060528)
		(width 0.14478)
		(layer "In2.Cu")
		(net "M_I_CPU0_SA_DQ<15>")
	)
	(segment
		(start 393.763754 -232.465372)
		(end 393.763754 -231.879902)
		(width 0.0889)
		(layer "In2.Cu")
		(net "M_I_CPU0_SA_DQ<15>")
	)
	(segment
		(start 403.682962 -220.742256)
		(end 403.911054 -220.742256)
		(width 0.14478)
		(layer "In2.Cu")
		(net "M_I_CPU0_SA_DQ<15>")
	)
	(segment
		(start 407.032206 -217.621104)
		(end 407.1493 -217.738452)
		(width 0.14478)
		(layer "In2.Cu")
		(net "M_I_CPU0_SA_DQ<15>")
	)
	(segment
		(start 405.588724 -219.299028)
		(end 405.816816 -219.299028)
		(width 0.14478)
		(layer "In2.Cu")
		(net "M_I_CPU0_SA_DQ<15>")
	)
	(segment
		(start 403.130766 -221.522544)
		(end 403.24786 -221.639892)
		(width 0.14478)
		(layer "In2.Cu")
		(net "M_I_CPU0_SA_DQ<15>")
	)
	(segment
		(start 394.806424 -230.837232)
		(end 395.271752 -230.837232)
		(width 0.0889)
		(layer "In2.Cu")
		(net "M_I_CPU0_SA_DQ<15>")
	)
	(segment
		(start 406.023826 -218.401392)
		(end 406.251918 -218.401392)
		(width 0.14478)
		(layer "In2.Cu")
		(net "M_I_CPU0_SA_DQ<15>")
	)
	(segment
		(start 417.700714 -214.760048)
		(end 418.550852 -215.610186)
		(width 0.14478)
		(layer "In2.Cu")
		(net "M_I_CPU0_SA_DQ<15>")
	)
	(segment
		(start 403.52091 -220.904308)
		(end 403.682962 -220.742256)
		(width 0.14478)
		(layer "In2.Cu")
		(net "M_I_CPU0_SA_DQ<15>")
	)
	(segment
		(start 405.19858 -219.688918)
		(end 405.081486 -219.571824)
		(width 0.14478)
		(layer "In2.Cu")
		(net "M_I_CPU0_SA_DQ<15>")
	)
	(segment
		(start 407.584402 -216.840816)
		(end 407.812494 -216.840816)
		(width 0.14478)
		(layer "In2.Cu")
		(net "M_I_CPU0_SA_DQ<15>")
	)
	(segment
		(start 406.642062 -217.783156)
		(end 406.804114 -217.621104)
		(width 0.14478)
		(layer "In2.Cu")
		(net "M_I_CPU0_SA_DQ<15>")
	)
	(segment
		(start 404.028148 -220.859604)
		(end 404.25624 -220.859604)
		(width 0.14478)
		(layer "In2.Cu")
		(net "M_I_CPU0_SA_DQ<15>")
	)
	(segment
		(start 403.638004 -221.47784)
		(end 403.638004 -221.249494)
		(width 0.14478)
		(layer "In2.Cu")
		(net "M_I_CPU0_SA_DQ<15>")
	)
	(segment
		(start 395.271752 -230.837232)
		(end 400.900646 -225.208338)
		(width 0.14478)
		(layer "In2.Cu")
		(net "M_I_CPU0_SA_DQ<15>")
	)
	(segment
		(start 400.900646 -225.208338)
		(end 400.900646 -224.215198)
		(width 0.14478)
		(layer "In2.Cu")
		(net "M_I_CPU0_SA_DQ<15>")
	)
	(segment
		(start 408.15768 -216.958164)
		(end 408.319732 -216.796112)
		(width 0.14478)
		(layer "In2.Cu")
		(net "M_I_CPU0_SA_DQ<15>")
	)
	(segment
		(start 407.377392 -217.738452)
		(end 407.539444 -217.5764)
		(width 0.14478)
		(layer "In2.Cu")
		(net "M_I_CPU0_SA_DQ<15>")
	)
	(segment
		(start 401.687284 -223.200468)
		(end 401.915376 -223.200468)
		(width 0.14478)
		(layer "In2.Cu")
		(net "M_I_CPU0_SA_DQ<15>")
	)
	(segment
		(start 408.709876 -216.177876)
		(end 408.937968 -216.177876)
		(width 0.14478)
		(layer "In2.Cu")
		(net "M_I_CPU0_SA_DQ<15>")
	)
	(segment
		(start 405.861774 -218.563444)
		(end 406.023826 -218.401392)
		(width 0.14478)
		(layer "In2.Cu")
		(net "M_I_CPU0_SA_DQ<15>")
	)
	(segment
		(start 401.342098 -223.08312)
		(end 401.57019 -223.08312)
		(width 0.14478)
		(layer "In2.Cu")
		(net "M_I_CPU0_SA_DQ<15>")
	)
	(segment
		(start 408.592782 -216.060528)
		(end 408.709876 -216.177876)
		(width 0.14478)
		(layer "In2.Cu")
		(net "M_I_CPU0_SA_DQ<15>")
	)
	(segment
		(start 402.467572 -222.42018)
		(end 402.695664 -222.42018)
		(width 0.14478)
		(layer "In2.Cu")
		(net "M_I_CPU0_SA_DQ<15>")
	)
	(segment
		(start 393.763754 -231.879902)
		(end 394.806424 -230.837232)
		(width 0.0889)
		(layer "In2.Cu")
		(net "M_I_CPU0_SA_DQ<15>")
	)
	(segment
		(start 409.505658 -215.610186)
		(end 414.005522 -215.610186)
		(width 0.14478)
		(layer "In2.Cu")
		(net "M_I_CPU0_SA_DQ<15>")
	)
	(segment
		(start 401.29714 -223.818704)
		(end 401.29714 -223.590358)
		(width 0.14478)
		(layer "In2.Cu")
		(net "M_I_CPU0_SA_DQ<15>")
	)
	(segment
		(start 402.350478 -222.302832)
		(end 402.467572 -222.42018)
		(width 0.14478)
		(layer "In2.Cu")
		(net "M_I_CPU0_SA_DQ<15>")
	)
	(segment
		(start 401.180046 -223.473264)
		(end 401.180046 -223.245172)
		(width 0.14478)
		(layer "In2.Cu")
		(net "M_I_CPU0_SA_DQ<15>")
	)
	(segment
		(start 407.812494 -216.840816)
		(end 407.929588 -216.958164)
		(width 0.14478)
		(layer "In2.Cu")
		(net "M_I_CPU0_SA_DQ<15>")
	)
	(segment
		(start 402.902674 -221.522544)
		(end 403.130766 -221.522544)
		(width 0.14478)
		(layer "In2.Cu")
		(net "M_I_CPU0_SA_DQ<15>")
	)
	(segment
		(start 405.861774 -218.791536)
		(end 405.861774 -218.563444)
		(width 0.14478)
		(layer "In2.Cu")
		(net "M_I_CPU0_SA_DQ<15>")
	)
	(segment
		(start 401.57019 -223.08312)
		(end 401.687284 -223.200468)
		(width 0.14478)
		(layer "In2.Cu")
		(net "M_I_CPU0_SA_DQ<15>")
	)
	(segment
		(start 404.25624 -220.859604)
		(end 404.418292 -220.697552)
		(width 0.14478)
		(layer "In2.Cu")
		(net "M_I_CPU0_SA_DQ<15>")
	)
	(segment
		(start 404.301198 -220.12402)
		(end 404.46325 -219.961968)
		(width 0.14478)
		(layer "In2.Cu")
		(net "M_I_CPU0_SA_DQ<15>")
	)
	(segment
		(start 402.740622 -221.684596)
		(end 402.902674 -221.522544)
		(width 0.14478)
		(layer "In2.Cu")
		(net "M_I_CPU0_SA_DQ<15>")
	)
	(segment
		(start 402.740622 -221.912688)
		(end 402.740622 -221.684596)
		(width 0.14478)
		(layer "In2.Cu")
		(net "M_I_CPU0_SA_DQ<15>")
	)
	(segment
		(start 384.90779 -234.441492)
		(end 384.916172 -234.436666)
		(width 0.0889)
		(layer "In2.Cu")
		(net "M_I_CPU0_SA_DQ<15>")
	)
	(segment
		(start 402.122386 -222.302832)
		(end 402.350478 -222.302832)
		(width 0.14478)
		(layer "In2.Cu")
		(net "M_I_CPU0_SA_DQ<15>")
	)
	(segment
		(start 405.978868 -219.136976)
		(end 405.978868 -218.90863)
		(width 0.14478)
		(layer "In2.Cu")
		(net "M_I_CPU0_SA_DQ<15>")
	)
	(segment
		(start 402.857716 -222.258128)
		(end 402.857716 -222.029782)
		(width 0.14478)
		(layer "In2.Cu")
		(net "M_I_CPU0_SA_DQ<15>")
	)
	(segment
		(start 402.077428 -222.81007)
		(end 401.960334 -222.692976)
		(width 0.14478)
		(layer "In2.Cu")
		(net "M_I_CPU0_SA_DQ<15>")
	)
	(segment
		(start 381.147828 -234.441492)
		(end 381.15621 -234.436666)
		(width 0.0889)
		(layer "In2.Cu")
		(net "M_I_CPU0_SA_DQ<15>")
	)
	(segment
		(start 406.642062 -218.011248)
		(end 406.642062 -217.783156)
		(width 0.14478)
		(layer "In2.Cu")
		(net "M_I_CPU0_SA_DQ<15>")
	)
	(segment
		(start 401.960334 -222.692976)
		(end 401.960334 -222.464884)
		(width 0.14478)
		(layer "In2.Cu")
		(net "M_I_CPU0_SA_DQ<15>")
	)
	(segment
		(start 406.597104 -218.51874)
		(end 406.759156 -218.356688)
		(width 0.14478)
		(layer "In2.Cu")
		(net "M_I_CPU0_SA_DQ<15>")
	)
	(segment
		(start 402.077428 -223.038416)
		(end 402.077428 -222.81007)
		(width 0.14478)
		(layer "In2.Cu")
		(net "M_I_CPU0_SA_DQ<15>")
	)
	(segment
		(start 378.693426 -234.436666)
		(end 378.701808 -234.441492)
		(width 0.0889)
		(layer "In2.Cu")
		(net "M_I_CPU0_SA_DQ<15>")
	)
	(segment
		(start 406.251918 -218.401392)
		(end 406.369012 -218.51874)
		(width 0.14478)
		(layer "In2.Cu")
		(net "M_I_CPU0_SA_DQ<15>")
	)
	(segment
		(start 408.202638 -216.22258)
		(end 408.36469 -216.060528)
		(width 0.14478)
		(layer "In2.Cu")
		(net "M_I_CPU0_SA_DQ<15>")
	)
	(segment
		(start 405.243538 -219.18168)
		(end 405.47163 -219.18168)
		(width 0.14478)
		(layer "In2.Cu")
		(net "M_I_CPU0_SA_DQ<15>")
	)
	(segment
		(start 403.52091 -221.1324)
		(end 403.52091 -220.904308)
		(width 0.14478)
		(layer "In2.Cu")
		(net "M_I_CPU0_SA_DQ<15>")
	)
	(segment
		(start 375.694702 -234.764072)
		(end 375.84888 -234.498642)
		(width 0.0889)
		(layer "In2.Cu")
		(net "M_I_CPU0_SA_DQ<15>")
	)
	(segment
		(start 405.978868 -218.90863)
		(end 405.861774 -218.791536)
		(width 0.14478)
		(layer "In2.Cu")
		(net "M_I_CPU0_SA_DQ<15>")
	)
	(segment
		(start 402.695664 -222.42018)
		(end 402.857716 -222.258128)
		(width 0.14478)
		(layer "In2.Cu")
		(net "M_I_CPU0_SA_DQ<15>")
	)
	(segment
		(start 405.19858 -219.917264)
		(end 405.19858 -219.688918)
		(width 0.14478)
		(layer "In2.Cu")
		(net "M_I_CPU0_SA_DQ<15>")
	)
	(segment
		(start 407.539444 -217.5764)
		(end 407.539444 -217.348054)
		(width 0.14478)
		(layer "In2.Cu")
		(net "M_I_CPU0_SA_DQ<15>")
	)
	(segment
		(start 406.759156 -218.356688)
		(end 406.759156 -218.128342)
		(width 0.14478)
		(layer "In2.Cu")
		(net "M_I_CPU0_SA_DQ<15>")
	)
	(segment
		(start 406.804114 -217.621104)
		(end 407.032206 -217.621104)
		(width 0.14478)
		(layer "In2.Cu")
		(net "M_I_CPU0_SA_DQ<15>")
	)
	(segment
		(start 408.202638 -216.450672)
		(end 408.202638 -216.22258)
		(width 0.14478)
		(layer "In2.Cu")
		(net "M_I_CPU0_SA_DQ<15>")
	)
	(segment
		(start 406.369012 -218.51874)
		(end 406.597104 -218.51874)
		(width 0.14478)
		(layer "In2.Cu")
		(net "M_I_CPU0_SA_DQ<15>")
	)
	(segment
		(start 427.03115 -214.760048)
		(end 427.456092 -215.18499)
		(width 0.14478)
		(layer "In2.Cu")
		(net "M_I_CPU0_SA_DQ<15>")
	)
	(segment
		(start 401.29714 -223.590358)
		(end 401.180046 -223.473264)
		(width 0.14478)
		(layer "In2.Cu")
		(net "M_I_CPU0_SA_DQ<15>")
	)
	(segment
		(start 388.093458 -234.436666)
		(end 388.10184 -234.441492)
		(width 0.0889)
		(layer "In2.Cu")
		(net "M_I_CPU0_SA_DQ<15>")
	)
	(segment
		(start 403.911054 -220.742256)
		(end 404.028148 -220.859604)
		(width 0.14478)
		(layer "In2.Cu")
		(net "M_I_CPU0_SA_DQ<15>")
	)
	(segment
		(start 385.847844 -234.441492)
		(end 385.856226 -234.436666)
		(width 0.0889)
		(layer "In2.Cu")
		(net "M_I_CPU0_SA_DQ<15>")
	)
	(segment
		(start 379.63348 -234.436666)
		(end 379.641862 -234.441492)
		(width 0.0889)
		(layer "In2.Cu")
		(net "M_I_CPU0_SA_DQ<15>")
	)
	(segment
		(start 405.081486 -219.343732)
		(end 405.243538 -219.18168)
		(width 0.14478)
		(layer "In2.Cu")
		(net "M_I_CPU0_SA_DQ<15>")
	)
	(segment
		(start 408.937968 -216.177876)
		(end 409.505658 -215.610186)
		(width 0.14478)
		(layer "In2.Cu")
		(net "M_I_CPU0_SA_DQ<15>")
	)
	(segment
		(start 408.319732 -216.796112)
		(end 408.319732 -216.567766)
		(width 0.14478)
		(layer "In2.Cu")
		(net "M_I_CPU0_SA_DQ<15>")
	)
	(segment
		(start 407.42235 -217.23096)
		(end 407.42235 -217.002868)
		(width 0.14478)
		(layer "In2.Cu")
		(net "M_I_CPU0_SA_DQ<15>")
	)
	(segment
		(start 404.301198 -220.352112)
		(end 404.301198 -220.12402)
		(width 0.14478)
		(layer "In2.Cu")
		(net "M_I_CPU0_SA_DQ<15>")
	)
	(segment
		(start 405.47163 -219.18168)
		(end 405.588724 -219.299028)
		(width 0.14478)
		(layer "In2.Cu")
		(net "M_I_CPU0_SA_DQ<15>")
	)
	(segment
		(start 407.929588 -216.958164)
		(end 408.15768 -216.958164)
		(width 0.14478)
		(layer "In2.Cu")
		(net "M_I_CPU0_SA_DQ<15>")
	)
	(segment
		(start 405.036528 -220.079316)
		(end 405.19858 -219.917264)
		(width 0.14478)
		(layer "In2.Cu")
		(net "M_I_CPU0_SA_DQ<15>")
	)
	(segment
		(start 404.418292 -220.469206)
		(end 404.301198 -220.352112)
		(width 0.14478)
		(layer "In2.Cu")
		(net "M_I_CPU0_SA_DQ<15>")
	)
	(segment
		(start 403.24786 -221.639892)
		(end 403.475952 -221.639892)
		(width 0.14478)
		(layer "In2.Cu")
		(net "M_I_CPU0_SA_DQ<15>")
	)
	(arc
		(start 376.821954 -234.441492)
		(mid 377.10491 -234.517669)
		(end 377.387866 -234.441492)
		(width 0.0889)
		(layer "In2.Cu")
		(net "M_I_CPU0_SA_DQ<15>")
	)
	(arc
		(start 381.15621 -234.436666)
		(mid 381.339718 -234.391172)
		(end 381.52197 -234.441492)
		(width 0.0889)
		(layer "In2.Cu")
		(net "M_I_CPU0_SA_DQ<15>")
	)
	(arc
		(start 391.48766 -234.441492)
		(mid 391.57792 -234.403864)
		(end 391.674858 -234.390946)
		(width 0.0889)
		(layer "In2.Cu")
		(net "M_I_CPU0_SA_DQ<15>")
	)
	(arc
		(start 379.641862 -234.441492)
		(mid 379.924818 -234.517669)
		(end 380.207774 -234.441492)
		(width 0.0889)
		(layer "In2.Cu")
		(net "M_I_CPU0_SA_DQ<15>")
	)
	(arc
		(start 375.945146 -234.473242)
		(mid 376.200211 -234.516593)
		(end 376.447812 -234.441492)
		(width 0.0889)
		(layer "In2.Cu")
		(net "M_I_CPU0_SA_DQ<15>")
	)
	(arc
		(start 380.581916 -234.441492)
		(mid 380.864872 -234.517669)
		(end 381.147828 -234.441492)
		(width 0.0889)
		(layer "In2.Cu")
		(net "M_I_CPU0_SA_DQ<15>")
	)
	(arc
		(start 389.981948 -234.441492)
		(mid 390.264904 -234.517669)
		(end 390.54786 -234.441492)
		(width 0.0889)
		(layer "In2.Cu")
		(net "M_I_CPU0_SA_DQ<15>")
	)
	(arc
		(start 384.341878 -234.441492)
		(mid 384.624834 -234.517669)
		(end 384.90779 -234.441492)
		(width 0.0889)
		(layer "In2.Cu")
		(net "M_I_CPU0_SA_DQ<15>")
	)
	(arc
		(start 389.041894 -234.441492)
		(mid 389.32485 -234.517669)
		(end 389.607806 -234.441492)
		(width 0.0889)
		(layer "In2.Cu")
		(net "M_I_CPU0_SA_DQ<15>")
	)
	(arc
		(start 390.54786 -234.441492)
		(mid 390.734804 -234.391237)
		(end 390.921748 -234.441492)
		(width 0.0889)
		(layer "In2.Cu")
		(net "M_I_CPU0_SA_DQ<15>")
	)
	(arc
		(start 387.727698 -234.441492)
		(mid 387.909949 -234.391142)
		(end 388.093458 -234.436666)
		(width 0.0889)
		(layer "In2.Cu")
		(net "M_I_CPU0_SA_DQ<15>")
	)
	(arc
		(start 384.916172 -234.436666)
		(mid 385.09968 -234.391172)
		(end 385.281932 -234.441492)
		(width 0.0889)
		(layer "In2.Cu")
		(net "M_I_CPU0_SA_DQ<15>")
	)
	(arc
		(start 391.674858 -234.390946)
		(mid 391.845238 -234.352877)
		(end 391.983214 -234.245912)
		(width 0.0889)
		(layer "In2.Cu")
		(net "M_I_CPU0_SA_DQ<15>")
	)
	(arc
		(start 385.281932 -234.441492)
		(mid 385.564888 -234.517669)
		(end 385.847844 -234.441492)
		(width 0.0889)
		(layer "In2.Cu")
		(net "M_I_CPU0_SA_DQ<15>")
	)
	(arc
		(start 377.387866 -234.441492)
		(mid 377.57481 -234.391237)
		(end 377.761754 -234.441492)
		(width 0.0889)
		(layer "In2.Cu")
		(net "M_I_CPU0_SA_DQ<15>")
	)
	(arc
		(start 376.456194 -234.436666)
		(mid 376.639702 -234.391172)
		(end 376.821954 -234.441492)
		(width 0.0889)
		(layer "In2.Cu")
		(net "M_I_CPU0_SA_DQ<15>")
	)
	(arc
		(start 383.027682 -234.441492)
		(mid 383.209933 -234.391142)
		(end 383.393442 -234.436666)
		(width 0.0889)
		(layer "In2.Cu")
		(net "M_I_CPU0_SA_DQ<15>")
	)
	(arc
		(start 381.52197 -234.441492)
		(mid 381.804926 -234.517669)
		(end 382.087882 -234.441492)
		(width 0.0889)
		(layer "In2.Cu")
		(net "M_I_CPU0_SA_DQ<15>")
	)
	(arc
		(start 378.701808 -234.441492)
		(mid 378.984764 -234.517669)
		(end 379.26772 -234.441492)
		(width 0.0889)
		(layer "In2.Cu")
		(net "M_I_CPU0_SA_DQ<15>")
	)
	(arc
		(start 389.616188 -234.436666)
		(mid 389.799696 -234.391172)
		(end 389.981948 -234.441492)
		(width 0.0889)
		(layer "In2.Cu")
		(net "M_I_CPU0_SA_DQ<15>")
	)
	(arc
		(start 380.216156 -234.436666)
		(mid 380.399664 -234.391172)
		(end 380.581916 -234.441492)
		(width 0.0889)
		(layer "In2.Cu")
		(net "M_I_CPU0_SA_DQ<15>")
	)
	(arc
		(start 386.787898 -234.441492)
		(mid 386.974842 -234.391237)
		(end 387.161786 -234.441492)
		(width 0.0889)
		(layer "In2.Cu")
		(net "M_I_CPU0_SA_DQ<15>")
	)
	(arc
		(start 383.967736 -234.441492)
		(mid 384.149987 -234.391142)
		(end 384.333496 -234.436666)
		(width 0.0889)
		(layer "In2.Cu")
		(net "M_I_CPU0_SA_DQ<15>")
	)
	(arc
		(start 385.856226 -234.436666)
		(mid 386.039734 -234.391172)
		(end 386.221986 -234.441492)
		(width 0.0889)
		(layer "In2.Cu")
		(net "M_I_CPU0_SA_DQ<15>")
	)
	(arc
		(start 379.26772 -234.441492)
		(mid 379.449971 -234.391142)
		(end 379.63348 -234.436666)
		(width 0.0889)
		(layer "In2.Cu")
		(net "M_I_CPU0_SA_DQ<15>")
	)
	(arc
		(start 377.761754 -234.441492)
		(mid 378.04471 -234.517669)
		(end 378.327666 -234.441492)
		(width 0.0889)
		(layer "In2.Cu")
		(net "M_I_CPU0_SA_DQ<15>")
	)
	(arc
		(start 382.087882 -234.441492)
		(mid 382.274826 -234.391237)
		(end 382.46177 -234.441492)
		(width 0.0889)
		(layer "In2.Cu")
		(net "M_I_CPU0_SA_DQ<15>")
	)
	(arc
		(start 388.10184 -234.441492)
		(mid 388.384796 -234.517669)
		(end 388.667752 -234.441492)
		(width 0.0889)
		(layer "In2.Cu")
		(net "M_I_CPU0_SA_DQ<15>")
	)
	(arc
		(start 390.921748 -234.441492)
		(mid 391.204704 -234.517669)
		(end 391.48766 -234.441492)
		(width 0.0889)
		(layer "In2.Cu")
		(net "M_I_CPU0_SA_DQ<15>")
	)
	(arc
		(start 387.161786 -234.441492)
		(mid 387.444742 -234.517669)
		(end 387.727698 -234.441492)
		(width 0.0889)
		(layer "In2.Cu")
		(net "M_I_CPU0_SA_DQ<15>")
	)
	(arc
		(start 378.327666 -234.441492)
		(mid 378.509917 -234.391142)
		(end 378.693426 -234.436666)
		(width 0.0889)
		(layer "In2.Cu")
		(net "M_I_CPU0_SA_DQ<15>")
	)
	(arc
		(start 388.667752 -234.441492)
		(mid 388.850003 -234.391142)
		(end 389.033512 -234.436666)
		(width 0.0889)
		(layer "In2.Cu")
		(net "M_I_CPU0_SA_DQ<15>")
	)
	(arc
		(start 382.46177 -234.441492)
		(mid 382.744726 -234.517669)
		(end 383.027682 -234.441492)
		(width 0.0889)
		(layer "In2.Cu")
		(net "M_I_CPU0_SA_DQ<15>")
	)
	(arc
		(start 386.221986 -234.441492)
		(mid 386.504942 -234.517669)
		(end 386.787898 -234.441492)
		(width 0.0889)
		(layer "In2.Cu")
		(net "M_I_CPU0_SA_DQ<15>")
	)
	(arc
		(start 383.401824 -234.441492)
		(mid 383.68478 -234.517669)
		(end 383.967736 -234.441492)
		(width 0.0889)
		(layer "In2.Cu")
		(net "M_I_CPU0_SA_DQ<15>")
	)
	(segment
		(start 376.638058 -234.220004)
		(end 377.10491 -233.954066)
		(width 0.10668)
		(layer "F.Cu")
		(net "M_I_CPU0_SA_DQ<14>")
	)
	(segment
		(start 396.32509 -227.74148)
		(end 396.52956 -227.946204)
		(width 0.14478)
		(layer "In2.Cu")
		(net "M_I_CPU0_SA_DQ<14>")
	)
	(segment
		(start 397.495522 -226.571048)
		(end 397.495522 -226.342956)
		(width 0.14478)
		(layer "In2.Cu")
		(net "M_I_CPU0_SA_DQ<14>")
	)
	(segment
		(start 398.733518 -224.459292)
		(end 398.89557 -224.29724)
		(width 0.14478)
		(layer "In2.Cu")
		(net "M_I_CPU0_SA_DQ<14>")
	)
	(segment
		(start 391.947146 -233.637582)
		(end 392.06043 -233.571288)
		(width 0.0889)
		(layer "In2.Cu")
		(net "M_I_CPU0_SA_DQ<14>")
	)
	(segment
		(start 395.934946 -227.903532)
		(end 396.096998 -227.74148)
		(width 0.14478)
		(layer "In2.Cu")
		(net "M_I_CPU0_SA_DQ<14>")
	)
	(segment
		(start 396.715234 -227.351336)
		(end 396.715234 -227.123244)
		(width 0.14478)
		(layer "In2.Cu")
		(net "M_I_CPU0_SA_DQ<14>")
	)
	(segment
		(start 393.643612 -230.51516)
		(end 394.51534 -229.643432)
		(width 0.0889)
		(layer "In2.Cu")
		(net "M_I_CPU0_SA_DQ<14>")
	)
	(segment
		(start 398.318228 -226.385628)
		(end 398.48028 -226.223576)
		(width 0.14478)
		(layer "In2.Cu")
		(net "M_I_CPU0_SA_DQ<14>")
	)
	(segment
		(start 415.017966 -213.060026)
		(end 417.528756 -213.060026)
		(width 0.14478)
		(layer "In2.Cu")
		(net "M_I_CPU0_SA_DQ<14>")
	)
	(segment
		(start 383.497836 -233.631486)
		(end 383.506218 -233.62666)
		(width 0.0889)
		(layer "In2.Cu")
		(net "M_I_CPU0_SA_DQ<14>")
	)
	(segment
		(start 422.286938 -213.060026)
		(end 427.03115 -213.060026)
		(width 0.14478)
		(layer "In2.Cu")
		(net "M_I_CPU0_SA_DQ<14>")
	)
	(segment
		(start 399.878804 -224.825052)
		(end 400.001486 -224.70237)
		(width 0.14478)
		(layer "In2.Cu")
		(net "M_I_CPU0_SA_DQ<14>")
	)
	(segment
		(start 378.79782 -233.631486)
		(end 378.806202 -233.62666)
		(width 0.0889)
		(layer "In2.Cu")
		(net "M_I_CPU0_SA_DQ<14>")
	)
	(segment
		(start 394.51534 -229.643432)
		(end 395.060424 -229.643432)
		(width 0.0889)
		(layer "In2.Cu")
		(net "M_I_CPU0_SA_DQ<14>")
	)
	(segment
		(start 396.919704 -227.784152)
		(end 396.919704 -227.55606)
		(width 0.14478)
		(layer "In2.Cu")
		(net "M_I_CPU0_SA_DQ<14>")
	)
	(segment
		(start 398.326864 -225.061018)
		(end 398.870424 -225.60534)
		(width 0.14478)
		(layer "In2.Cu")
		(net "M_I_CPU0_SA_DQ<14>")
	)
	(segment
		(start 414.167828 -213.910164)
		(end 415.017966 -213.060026)
		(width 0.14478)
		(layer "In2.Cu")
		(net "M_I_CPU0_SA_DQ<14>")
	)
	(segment
		(start 398.870424 -225.60534)
		(end 399.098516 -225.60534)
		(width 0.14478)
		(layer "In2.Cu")
		(net "M_I_CPU0_SA_DQ<14>")
	)
	(segment
		(start 398.733518 -224.687384)
		(end 398.733518 -224.459292)
		(width 0.14478)
		(layer "In2.Cu")
		(net "M_I_CPU0_SA_DQ<14>")
	)
	(segment
		(start 400.001486 -224.70237)
		(end 400.001486 -223.151446)
		(width 0.14478)
		(layer "In2.Cu")
		(net "M_I_CPU0_SA_DQ<14>")
	)
	(segment
		(start 382.557782 -233.631486)
		(end 382.566164 -233.62666)
		(width 0.0889)
		(layer "In2.Cu")
		(net "M_I_CPU0_SA_DQ<14>")
	)
	(segment
		(start 397.309848 -227.165916)
		(end 397.53794 -227.165916)
		(width 0.14478)
		(layer "In2.Cu")
		(net "M_I_CPU0_SA_DQ<14>")
	)
	(segment
		(start 397.699992 -226.775772)
		(end 397.495522 -226.571048)
		(width 0.14478)
		(layer "In2.Cu")
		(net "M_I_CPU0_SA_DQ<14>")
	)
	(segment
		(start 396.715234 -227.123244)
		(end 396.877286 -226.961192)
		(width 0.14478)
		(layer "In2.Cu")
		(net "M_I_CPU0_SA_DQ<14>")
	)
	(segment
		(start 398.48028 -225.995484)
		(end 397.93672 -225.451162)
		(width 0.14478)
		(layer "In2.Cu")
		(net "M_I_CPU0_SA_DQ<14>")
	)
	(segment
		(start 392.717274 -231.96677)
		(end 393.643612 -231.040432)
		(width 0.0889)
		(layer "In2.Cu")
		(net "M_I_CPU0_SA_DQ<14>")
	)
	(segment
		(start 390.443466 -233.62666)
		(end 390.451848 -233.631486)
		(width 0.0889)
		(layer "In2.Cu")
		(net "M_I_CPU0_SA_DQ<14>")
	)
	(segment
		(start 392.717274 -232.914444)
		(end 392.717274 -231.96677)
		(width 0.0889)
		(layer "In2.Cu")
		(net "M_I_CPU0_SA_DQ<14>")
	)
	(segment
		(start 399.098516 -225.60534)
		(end 399.260568 -225.443288)
		(width 0.14478)
		(layer "In2.Cu")
		(net "M_I_CPU0_SA_DQ<14>")
	)
	(segment
		(start 391.01776 -233.631486)
		(end 391.026142 -233.62666)
		(width 0.0889)
		(layer "In2.Cu")
		(net "M_I_CPU0_SA_DQ<14>")
	)
	(segment
		(start 427.03115 -213.060026)
		(end 427.456092 -213.484968)
		(width 0.14478)
		(layer "In2.Cu")
		(net "M_I_CPU0_SA_DQ<14>")
	)
	(segment
		(start 377.258834 -233.688636)
		(end 377.354846 -233.663236)
		(width 0.0889)
		(layer "In2.Cu")
		(net "M_I_CPU0_SA_DQ<14>")
	)
	(segment
		(start 388.197852 -233.631486)
		(end 388.206234 -233.62666)
		(width 0.0889)
		(layer "In2.Cu")
		(net "M_I_CPU0_SA_DQ<14>")
	)
	(segment
		(start 397.53794 -227.165916)
		(end 397.699992 -227.003864)
		(width 0.14478)
		(layer "In2.Cu")
		(net "M_I_CPU0_SA_DQ<14>")
	)
	(segment
		(start 377.857766 -233.631486)
		(end 377.866148 -233.62666)
		(width 0.0889)
		(layer "In2.Cu")
		(net "M_I_CPU0_SA_DQ<14>")
	)
	(segment
		(start 397.93672 -225.22307)
		(end 398.098772 -225.061018)
		(width 0.14478)
		(layer "In2.Cu")
		(net "M_I_CPU0_SA_DQ<14>")
	)
	(segment
		(start 399.123662 -224.29724)
		(end 399.650712 -224.825052)
		(width 0.14478)
		(layer "In2.Cu")
		(net "M_I_CPU0_SA_DQ<14>")
	)
	(segment
		(start 399.650712 -224.825052)
		(end 399.878804 -224.825052)
		(width 0.14478)
		(layer "In2.Cu")
		(net "M_I_CPU0_SA_DQ<14>")
	)
	(segment
		(start 398.090136 -226.385628)
		(end 398.318228 -226.385628)
		(width 0.14478)
		(layer "In2.Cu")
		(net "M_I_CPU0_SA_DQ<14>")
	)
	(segment
		(start 397.657574 -226.180904)
		(end 397.885666 -226.180904)
		(width 0.14478)
		(layer "In2.Cu")
		(net "M_I_CPU0_SA_DQ<14>")
	)
	(segment
		(start 396.877286 -226.961192)
		(end 397.105378 -226.961192)
		(width 0.14478)
		(layer "In2.Cu")
		(net "M_I_CPU0_SA_DQ<14>")
	)
	(segment
		(start 395.060424 -229.643432)
		(end 395.286738 -229.417118)
		(width 0.0889)
		(layer "In2.Cu")
		(net "M_I_CPU0_SA_DQ<14>")
	)
	(segment
		(start 397.105378 -226.961192)
		(end 397.309848 -227.165916)
		(width 0.14478)
		(layer "In2.Cu")
		(net "M_I_CPU0_SA_DQ<14>")
	)
	(segment
		(start 421.4368 -213.910164)
		(end 422.286938 -213.060026)
		(width 0.14478)
		(layer "In2.Cu")
		(net "M_I_CPU0_SA_DQ<14>")
	)
	(segment
		(start 409.242768 -213.910164)
		(end 414.167828 -213.910164)
		(width 0.14478)
		(layer "In2.Cu")
		(net "M_I_CPU0_SA_DQ<14>")
	)
	(segment
		(start 381.043434 -233.62666)
		(end 381.051816 -233.631486)
		(width 0.0889)
		(layer "In2.Cu")
		(net "M_I_CPU0_SA_DQ<14>")
	)
	(segment
		(start 418.378894 -213.910164)
		(end 421.4368 -213.910164)
		(width 0.14478)
		(layer "In2.Cu")
		(net "M_I_CPU0_SA_DQ<14>")
	)
	(segment
		(start 377.10491 -233.954066)
		(end 377.258834 -233.688636)
		(width 0.0889)
		(layer "In2.Cu")
		(net "M_I_CPU0_SA_DQ<14>")
	)
	(segment
		(start 396.096998 -227.74148)
		(end 396.32509 -227.74148)
		(width 0.14478)
		(layer "In2.Cu")
		(net "M_I_CPU0_SA_DQ<14>")
	)
	(segment
		(start 397.93672 -225.451162)
		(end 397.93672 -225.22307)
		(width 0.14478)
		(layer "In2.Cu")
		(net "M_I_CPU0_SA_DQ<14>")
	)
	(segment
		(start 385.74345 -233.62666)
		(end 385.751832 -233.631486)
		(width 0.0889)
		(layer "In2.Cu")
		(net "M_I_CPU0_SA_DQ<14>")
	)
	(segment
		(start 396.919704 -227.55606)
		(end 396.715234 -227.351336)
		(width 0.14478)
		(layer "In2.Cu")
		(net "M_I_CPU0_SA_DQ<14>")
	)
	(segment
		(start 397.699992 -227.003864)
		(end 397.699992 -226.775772)
		(width 0.14478)
		(layer "In2.Cu")
		(net "M_I_CPU0_SA_DQ<14>")
	)
	(segment
		(start 387.257798 -233.631486)
		(end 387.26618 -233.62666)
		(width 0.0889)
		(layer "In2.Cu")
		(net "M_I_CPU0_SA_DQ<14>")
	)
	(segment
		(start 395.286738 -229.417118)
		(end 396.139416 -228.56444)
		(width 0.14478)
		(layer "In2.Cu")
		(net "M_I_CPU0_SA_DQ<14>")
	)
	(segment
		(start 392.06043 -233.571288)
		(end 392.717274 -232.914444)
		(width 0.0889)
		(layer "In2.Cu")
		(net "M_I_CPU0_SA_DQ<14>")
	)
	(segment
		(start 398.48028 -226.223576)
		(end 398.48028 -225.995484)
		(width 0.14478)
		(layer "In2.Cu")
		(net "M_I_CPU0_SA_DQ<14>")
	)
	(segment
		(start 381.983488 -233.62666)
		(end 381.99187 -233.631486)
		(width 0.0889)
		(layer "In2.Cu")
		(net "M_I_CPU0_SA_DQ<14>")
	)
	(segment
		(start 396.52956 -227.946204)
		(end 396.757652 -227.946204)
		(width 0.14478)
		(layer "In2.Cu")
		(net "M_I_CPU0_SA_DQ<14>")
	)
	(segment
		(start 398.098772 -225.061018)
		(end 398.326864 -225.061018)
		(width 0.14478)
		(layer "In2.Cu")
		(net "M_I_CPU0_SA_DQ<14>")
	)
	(segment
		(start 397.495522 -226.342956)
		(end 397.657574 -226.180904)
		(width 0.14478)
		(layer "In2.Cu")
		(net "M_I_CPU0_SA_DQ<14>")
	)
	(segment
		(start 398.89557 -224.29724)
		(end 399.123662 -224.29724)
		(width 0.14478)
		(layer "In2.Cu")
		(net "M_I_CPU0_SA_DQ<14>")
	)
	(segment
		(start 396.757652 -227.946204)
		(end 396.919704 -227.784152)
		(width 0.14478)
		(layer "In2.Cu")
		(net "M_I_CPU0_SA_DQ<14>")
	)
	(segment
		(start 399.260568 -225.443288)
		(end 399.260568 -225.215196)
		(width 0.14478)
		(layer "In2.Cu")
		(net "M_I_CPU0_SA_DQ<14>")
	)
	(segment
		(start 396.139416 -228.56444)
		(end 396.139416 -228.336348)
		(width 0.14478)
		(layer "In2.Cu")
		(net "M_I_CPU0_SA_DQ<14>")
	)
	(segment
		(start 417.528756 -213.060026)
		(end 418.378894 -213.910164)
		(width 0.14478)
		(layer "In2.Cu")
		(net "M_I_CPU0_SA_DQ<14>")
	)
	(segment
		(start 400.001486 -223.151446)
		(end 409.242768 -213.910164)
		(width 0.14478)
		(layer "In2.Cu")
		(net "M_I_CPU0_SA_DQ<14>")
	)
	(segment
		(start 397.885666 -226.180904)
		(end 398.090136 -226.385628)
		(width 0.14478)
		(layer "In2.Cu")
		(net "M_I_CPU0_SA_DQ<14>")
	)
	(segment
		(start 386.683504 -233.62666)
		(end 386.691886 -233.631486)
		(width 0.0889)
		(layer "In2.Cu")
		(net "M_I_CPU0_SA_DQ<14>")
	)
	(segment
		(start 396.139416 -228.336348)
		(end 395.934946 -228.131624)
		(width 0.14478)
		(layer "In2.Cu")
		(net "M_I_CPU0_SA_DQ<14>")
	)
	(segment
		(start 395.934946 -228.131624)
		(end 395.934946 -227.903532)
		(width 0.14478)
		(layer "In2.Cu")
		(net "M_I_CPU0_SA_DQ<14>")
	)
	(segment
		(start 393.643612 -231.040432)
		(end 393.643612 -230.51516)
		(width 0.0889)
		(layer "In2.Cu")
		(net "M_I_CPU0_SA_DQ<14>")
	)
	(segment
		(start 399.260568 -225.215196)
		(end 398.733518 -224.687384)
		(width 0.14478)
		(layer "In2.Cu")
		(net "M_I_CPU0_SA_DQ<14>")
	)
	(arc
		(start 381.99187 -233.631486)
		(mid 382.274826 -233.707663)
		(end 382.557782 -233.631486)
		(width 0.0889)
		(layer "In2.Cu")
		(net "M_I_CPU0_SA_DQ<14>")
	)
	(arc
		(start 386.317744 -233.631486)
		(mid 386.499995 -233.581136)
		(end 386.683504 -233.62666)
		(width 0.0889)
		(layer "In2.Cu")
		(net "M_I_CPU0_SA_DQ<14>")
	)
	(arc
		(start 391.391902 -233.631486)
		(mid 391.668715 -233.707629)
		(end 391.947146 -233.637582)
		(width 0.0889)
		(layer "In2.Cu")
		(net "M_I_CPU0_SA_DQ<14>")
	)
	(arc
		(start 390.451848 -233.631486)
		(mid 390.734804 -233.707663)
		(end 391.01776 -233.631486)
		(width 0.0889)
		(layer "In2.Cu")
		(net "M_I_CPU0_SA_DQ<14>")
	)
	(arc
		(start 382.566164 -233.62666)
		(mid 382.749672 -233.581166)
		(end 382.931924 -233.631486)
		(width 0.0889)
		(layer "In2.Cu")
		(net "M_I_CPU0_SA_DQ<14>")
	)
	(arc
		(start 381.617728 -233.631486)
		(mid 381.799979 -233.581136)
		(end 381.983488 -233.62666)
		(width 0.0889)
		(layer "In2.Cu")
		(net "M_I_CPU0_SA_DQ<14>")
	)
	(arc
		(start 389.511794 -233.631486)
		(mid 389.79475 -233.707663)
		(end 390.077706 -233.631486)
		(width 0.0889)
		(layer "In2.Cu")
		(net "M_I_CPU0_SA_DQ<14>")
	)
	(arc
		(start 387.26618 -233.62666)
		(mid 387.449688 -233.581166)
		(end 387.63194 -233.631486)
		(width 0.0889)
		(layer "In2.Cu")
		(net "M_I_CPU0_SA_DQ<14>")
	)
	(arc
		(start 378.231908 -233.631486)
		(mid 378.514864 -233.707663)
		(end 378.79782 -233.631486)
		(width 0.0889)
		(layer "In2.Cu")
		(net "M_I_CPU0_SA_DQ<14>")
	)
	(arc
		(start 388.571994 -233.631486)
		(mid 388.85495 -233.707663)
		(end 389.137906 -233.631486)
		(width 0.0889)
		(layer "In2.Cu")
		(net "M_I_CPU0_SA_DQ<14>")
	)
	(arc
		(start 380.677674 -233.631486)
		(mid 380.859925 -233.581136)
		(end 381.043434 -233.62666)
		(width 0.0889)
		(layer "In2.Cu")
		(net "M_I_CPU0_SA_DQ<14>")
	)
	(arc
		(start 379.171962 -233.631486)
		(mid 379.454918 -233.707663)
		(end 379.737874 -233.631486)
		(width 0.0889)
		(layer "In2.Cu")
		(net "M_I_CPU0_SA_DQ<14>")
	)
	(arc
		(start 391.026142 -233.62666)
		(mid 391.20965 -233.581166)
		(end 391.391902 -233.631486)
		(width 0.0889)
		(layer "In2.Cu")
		(net "M_I_CPU0_SA_DQ<14>")
	)
	(arc
		(start 380.111762 -233.631486)
		(mid 380.394718 -233.707663)
		(end 380.677674 -233.631486)
		(width 0.0889)
		(layer "In2.Cu")
		(net "M_I_CPU0_SA_DQ<14>")
	)
	(arc
		(start 382.931924 -233.631486)
		(mid 383.21488 -233.707663)
		(end 383.497836 -233.631486)
		(width 0.0889)
		(layer "In2.Cu")
		(net "M_I_CPU0_SA_DQ<14>")
	)
	(arc
		(start 385.751832 -233.631486)
		(mid 386.034788 -233.707663)
		(end 386.317744 -233.631486)
		(width 0.0889)
		(layer "In2.Cu")
		(net "M_I_CPU0_SA_DQ<14>")
	)
	(arc
		(start 384.811778 -233.631486)
		(mid 385.094734 -233.707663)
		(end 385.37769 -233.631486)
		(width 0.0889)
		(layer "In2.Cu")
		(net "M_I_CPU0_SA_DQ<14>")
	)
	(arc
		(start 377.866148 -233.62666)
		(mid 378.049656 -233.581166)
		(end 378.231908 -233.631486)
		(width 0.0889)
		(layer "In2.Cu")
		(net "M_I_CPU0_SA_DQ<14>")
	)
	(arc
		(start 387.63194 -233.631486)
		(mid 387.914896 -233.707663)
		(end 388.197852 -233.631486)
		(width 0.0889)
		(layer "In2.Cu")
		(net "M_I_CPU0_SA_DQ<14>")
	)
	(arc
		(start 379.737874 -233.631486)
		(mid 379.924818 -233.581231)
		(end 380.111762 -233.631486)
		(width 0.0889)
		(layer "In2.Cu")
		(net "M_I_CPU0_SA_DQ<14>")
	)
	(arc
		(start 390.077706 -233.631486)
		(mid 390.259957 -233.581136)
		(end 390.443466 -233.62666)
		(width 0.0889)
		(layer "In2.Cu")
		(net "M_I_CPU0_SA_DQ<14>")
	)
	(arc
		(start 385.37769 -233.631486)
		(mid 385.559941 -233.581136)
		(end 385.74345 -233.62666)
		(width 0.0889)
		(layer "In2.Cu")
		(net "M_I_CPU0_SA_DQ<14>")
	)
	(arc
		(start 381.051816 -233.631486)
		(mid 381.334772 -233.707663)
		(end 381.617728 -233.631486)
		(width 0.0889)
		(layer "In2.Cu")
		(net "M_I_CPU0_SA_DQ<14>")
	)
	(arc
		(start 383.871978 -233.631486)
		(mid 384.154934 -233.707663)
		(end 384.43789 -233.631486)
		(width 0.0889)
		(layer "In2.Cu")
		(net "M_I_CPU0_SA_DQ<14>")
	)
	(arc
		(start 377.354846 -233.663236)
		(mid 377.610054 -233.706713)
		(end 377.857766 -233.631486)
		(width 0.0889)
		(layer "In2.Cu")
		(net "M_I_CPU0_SA_DQ<14>")
	)
	(arc
		(start 389.137906 -233.631486)
		(mid 389.32485 -233.581231)
		(end 389.511794 -233.631486)
		(width 0.0889)
		(layer "In2.Cu")
		(net "M_I_CPU0_SA_DQ<14>")
	)
	(arc
		(start 384.43789 -233.631486)
		(mid 384.624834 -233.581231)
		(end 384.811778 -233.631486)
		(width 0.0889)
		(layer "In2.Cu")
		(net "M_I_CPU0_SA_DQ<14>")
	)
	(arc
		(start 378.806202 -233.62666)
		(mid 378.98971 -233.581166)
		(end 379.171962 -233.631486)
		(width 0.0889)
		(layer "In2.Cu")
		(net "M_I_CPU0_SA_DQ<14>")
	)
	(arc
		(start 386.691886 -233.631486)
		(mid 386.974842 -233.707663)
		(end 387.257798 -233.631486)
		(width 0.0889)
		(layer "In2.Cu")
		(net "M_I_CPU0_SA_DQ<14>")
	)
	(arc
		(start 388.206234 -233.62666)
		(mid 388.389742 -233.581166)
		(end 388.571994 -233.631486)
		(width 0.0889)
		(layer "In2.Cu")
		(net "M_I_CPU0_SA_DQ<14>")
	)
	(arc
		(start 383.506218 -233.62666)
		(mid 383.689726 -233.581166)
		(end 383.871978 -233.631486)
		(width 0.0889)
		(layer "In2.Cu")
		(net "M_I_CPU0_SA_DQ<14>")
	)
	(segment
		(start 375.698004 -234.220004)
		(end 376.164856 -233.954066)
		(width 0.10668)
		(layer "F.Cu")
		(net "M_I_CPU0_SA_DQ<13>")
	)
	(segment
		(start 418.469318 -214.760048)
		(end 417.619434 -213.910164)
		(width 0.14478)
		(layer "In2.Cu")
		(net "M_I_CPU0_SA_DQ<13>")
	)
	(segment
		(start 395.08176 -230.274114)
		(end 393.497054 -231.85882)
		(width 0.0889)
		(layer "In2.Cu")
		(net "M_I_CPU0_SA_DQ<13>")
	)
	(segment
		(start 430.081944 -214.071708)
		(end 430.081944 -214.627968)
		(width 0.14478)
		(layer "In2.Cu")
		(net "M_I_CPU0_SA_DQ<13>")
	)
	(segment
		(start 409.0289 -214.760048)
		(end 400.451066 -223.337882)
		(width 0.14478)
		(layer "In2.Cu")
		(net "M_I_CPU0_SA_DQ<13>")
	)
	(segment
		(start 385.751832 -234.276646)
		(end 385.74345 -234.281472)
		(width 0.0889)
		(layer "In2.Cu")
		(net "M_I_CPU0_SA_DQ<13>")
	)
	(segment
		(start 429.53051 -214.627968)
		(end 429.53051 -214.071708)
		(width 0.14478)
		(layer "In2.Cu")
		(net "M_I_CPU0_SA_DQ<13>")
	)
	(segment
		(start 400.451066 -224.904808)
		(end 395.08176 -230.274114)
		(width 0.14478)
		(layer "In2.Cu")
		(net "M_I_CPU0_SA_DQ<13>")
	)
	(segment
		(start 381.051816 -234.276646)
		(end 381.043434 -234.281472)
		(width 0.0889)
		(layer "In2.Cu")
		(net "M_I_CPU0_SA_DQ<13>")
	)
	(segment
		(start 377.866148 -234.281472)
		(end 377.857766 -234.276646)
		(width 0.0889)
		(layer "In2.Cu")
		(net "M_I_CPU0_SA_DQ<13>")
	)
	(segment
		(start 414.161986 -214.760048)
		(end 409.0289 -214.760048)
		(width 0.14478)
		(layer "In2.Cu")
		(net "M_I_CPU0_SA_DQ<13>")
	)
	(segment
		(start 386.691886 -234.276646)
		(end 386.683504 -234.281472)
		(width 0.0889)
		(layer "In2.Cu")
		(net "M_I_CPU0_SA_DQ<13>")
	)
	(segment
		(start 429.692054 -214.789512)
		(end 429.53051 -214.627968)
		(width 0.14478)
		(layer "In2.Cu")
		(net "M_I_CPU0_SA_DQ<13>")
	)
	(segment
		(start 390.451848 -234.276646)
		(end 390.443466 -234.281472)
		(width 0.0889)
		(layer "In2.Cu")
		(net "M_I_CPU0_SA_DQ<13>")
	)
	(segment
		(start 421.730932 -214.760048)
		(end 418.469318 -214.760048)
		(width 0.14478)
		(layer "In2.Cu")
		(net "M_I_CPU0_SA_DQ<13>")
	)
	(segment
		(start 378.806202 -234.281472)
		(end 378.79782 -234.276646)
		(width 0.0889)
		(layer "In2.Cu")
		(net "M_I_CPU0_SA_DQ<13>")
	)
	(segment
		(start 376.010678 -234.219496)
		(end 376.164856 -233.954066)
		(width 0.0889)
		(layer "In2.Cu")
		(net "M_I_CPU0_SA_DQ<13>")
	)
	(segment
		(start 417.619434 -213.910164)
		(end 415.01187 -213.910164)
		(width 0.14478)
		(layer "In2.Cu")
		(net "M_I_CPU0_SA_DQ<13>")
	)
	(segment
		(start 430.081944 -214.627968)
		(end 429.9204 -214.789512)
		(width 0.14478)
		(layer "In2.Cu")
		(net "M_I_CPU0_SA_DQ<13>")
	)
	(segment
		(start 422.580816 -213.910164)
		(end 421.730932 -214.760048)
		(width 0.14478)
		(layer "In2.Cu")
		(net "M_I_CPU0_SA_DQ<13>")
	)
	(segment
		(start 387.26618 -234.281472)
		(end 387.257798 -234.276646)
		(width 0.0889)
		(layer "In2.Cu")
		(net "M_I_CPU0_SA_DQ<13>")
	)
	(segment
		(start 382.566164 -234.281472)
		(end 382.557782 -234.276646)
		(width 0.0889)
		(layer "In2.Cu")
		(net "M_I_CPU0_SA_DQ<13>")
	)
	(segment
		(start 391.026142 -234.281472)
		(end 391.01776 -234.276646)
		(width 0.0889)
		(layer "In2.Cu")
		(net "M_I_CPU0_SA_DQ<13>")
	)
	(segment
		(start 388.206234 -234.281472)
		(end 388.197852 -234.276646)
		(width 0.0889)
		(layer "In2.Cu")
		(net "M_I_CPU0_SA_DQ<13>")
	)
	(segment
		(start 431.131218 -213.910164)
		(end 430.243488 -213.910164)
		(width 0.14478)
		(layer "In2.Cu")
		(net "M_I_CPU0_SA_DQ<13>")
	)
	(segment
		(start 381.99187 -234.276646)
		(end 381.983488 -234.281472)
		(width 0.0889)
		(layer "In2.Cu")
		(net "M_I_CPU0_SA_DQ<13>")
	)
	(segment
		(start 431.55616 -214.335106)
		(end 431.131218 -213.910164)
		(width 0.14478)
		(layer "In2.Cu")
		(net "M_I_CPU0_SA_DQ<13>")
	)
	(segment
		(start 383.506218 -234.281472)
		(end 383.497836 -234.276646)
		(width 0.0889)
		(layer "In2.Cu")
		(net "M_I_CPU0_SA_DQ<13>")
	)
	(segment
		(start 393.497054 -232.424732)
		(end 391.916158 -234.005628)
		(width 0.0889)
		(layer "In2.Cu")
		(net "M_I_CPU0_SA_DQ<13>")
	)
	(segment
		(start 377.291854 -234.276646)
		(end 377.283472 -234.281472)
		(width 0.0889)
		(layer "In2.Cu")
		(net "M_I_CPU0_SA_DQ<13>")
	)
	(segment
		(start 393.497054 -231.85882)
		(end 393.497054 -232.424732)
		(width 0.0889)
		(layer "In2.Cu")
		(net "M_I_CPU0_SA_DQ<13>")
	)
	(segment
		(start 429.53051 -214.071708)
		(end 429.368966 -213.910164)
		(width 0.14478)
		(layer "In2.Cu")
		(net "M_I_CPU0_SA_DQ<13>")
	)
	(segment
		(start 400.451066 -223.337882)
		(end 400.451066 -224.904808)
		(width 0.14478)
		(layer "In2.Cu")
		(net "M_I_CPU0_SA_DQ<13>")
	)
	(segment
		(start 429.9204 -214.789512)
		(end 429.692054 -214.789512)
		(width 0.14478)
		(layer "In2.Cu")
		(net "M_I_CPU0_SA_DQ<13>")
	)
	(segment
		(start 429.368966 -213.910164)
		(end 422.580816 -213.910164)
		(width 0.14478)
		(layer "In2.Cu")
		(net "M_I_CPU0_SA_DQ<13>")
	)
	(segment
		(start 376.03303 -234.302808)
		(end 376.010678 -234.219496)
		(width 0.0889)
		(layer "In2.Cu")
		(net "M_I_CPU0_SA_DQ<13>")
	)
	(segment
		(start 376.3518 -234.276646)
		(end 376.343418 -234.281472)
		(width 0.0889)
		(layer "In2.Cu")
		(net "M_I_CPU0_SA_DQ<13>")
	)
	(segment
		(start 430.243488 -213.910164)
		(end 430.081944 -214.071708)
		(width 0.14478)
		(layer "In2.Cu")
		(net "M_I_CPU0_SA_DQ<13>")
	)
	(segment
		(start 415.01187 -213.910164)
		(end 414.161986 -214.760048)
		(width 0.14478)
		(layer "In2.Cu")
		(net "M_I_CPU0_SA_DQ<13>")
	)
	(arc
		(start 379.737874 -234.276646)
		(mid 379.454918 -234.200469)
		(end 379.171962 -234.276646)
		(width 0.0889)
		(layer "In2.Cu")
		(net "M_I_CPU0_SA_DQ<13>")
	)
	(arc
		(start 382.931924 -234.276646)
		(mid 382.749673 -234.326996)
		(end 382.566164 -234.281472)
		(width 0.0889)
		(layer "In2.Cu")
		(net "M_I_CPU0_SA_DQ<13>")
	)
	(arc
		(start 380.677674 -234.276646)
		(mid 380.394718 -234.200469)
		(end 380.111762 -234.276646)
		(width 0.0889)
		(layer "In2.Cu")
		(net "M_I_CPU0_SA_DQ<13>")
	)
	(arc
		(start 388.197852 -234.276646)
		(mid 387.914896 -234.200469)
		(end 387.63194 -234.276646)
		(width 0.0889)
		(layer "In2.Cu")
		(net "M_I_CPU0_SA_DQ<13>")
	)
	(arc
		(start 387.257798 -234.276646)
		(mid 386.974842 -234.200469)
		(end 386.691886 -234.276646)
		(width 0.0889)
		(layer "In2.Cu")
		(net "M_I_CPU0_SA_DQ<13>")
	)
	(arc
		(start 376.343418 -234.281472)
		(mid 376.190548 -234.326113)
		(end 376.03303 -234.302808)
		(width 0.0889)
		(layer "In2.Cu")
		(net "M_I_CPU0_SA_DQ<13>")
	)
	(arc
		(start 377.857766 -234.276646)
		(mid 377.57481 -234.200469)
		(end 377.291854 -234.276646)
		(width 0.0889)
		(layer "In2.Cu")
		(net "M_I_CPU0_SA_DQ<13>")
	)
	(arc
		(start 391.5791 -234.194604)
		(mid 391.481869 -234.227339)
		(end 391.391902 -234.276646)
		(width 0.0889)
		(layer "In2.Cu")
		(net "M_I_CPU0_SA_DQ<13>")
	)
	(arc
		(start 378.231908 -234.276646)
		(mid 378.049657 -234.326996)
		(end 377.866148 -234.281472)
		(width 0.0889)
		(layer "In2.Cu")
		(net "M_I_CPU0_SA_DQ<13>")
	)
	(arc
		(start 382.557782 -234.276646)
		(mid 382.274826 -234.200469)
		(end 381.99187 -234.276646)
		(width 0.0889)
		(layer "In2.Cu")
		(net "M_I_CPU0_SA_DQ<13>")
	)
	(arc
		(start 390.077706 -234.276646)
		(mid 389.79475 -234.200469)
		(end 389.511794 -234.276646)
		(width 0.0889)
		(layer "In2.Cu")
		(net "M_I_CPU0_SA_DQ<13>")
	)
	(arc
		(start 388.571994 -234.276646)
		(mid 388.389743 -234.326996)
		(end 388.206234 -234.281472)
		(width 0.0889)
		(layer "In2.Cu")
		(net "M_I_CPU0_SA_DQ<13>")
	)
	(arc
		(start 381.983488 -234.281472)
		(mid 381.79998 -234.326966)
		(end 381.617728 -234.276646)
		(width 0.0889)
		(layer "In2.Cu")
		(net "M_I_CPU0_SA_DQ<13>")
	)
	(arc
		(start 383.871978 -234.276646)
		(mid 383.689727 -234.326996)
		(end 383.506218 -234.281472)
		(width 0.0889)
		(layer "In2.Cu")
		(net "M_I_CPU0_SA_DQ<13>")
	)
	(arc
		(start 391.391902 -234.276646)
		(mid 391.209651 -234.326996)
		(end 391.026142 -234.281472)
		(width 0.0889)
		(layer "In2.Cu")
		(net "M_I_CPU0_SA_DQ<13>")
	)
	(arc
		(start 381.043434 -234.281472)
		(mid 380.859926 -234.326966)
		(end 380.677674 -234.276646)
		(width 0.0889)
		(layer "In2.Cu")
		(net "M_I_CPU0_SA_DQ<13>")
	)
	(arc
		(start 389.511794 -234.276646)
		(mid 389.32485 -234.326901)
		(end 389.137906 -234.276646)
		(width 0.0889)
		(layer "In2.Cu")
		(net "M_I_CPU0_SA_DQ<13>")
	)
	(arc
		(start 381.617728 -234.276646)
		(mid 381.334772 -234.200469)
		(end 381.051816 -234.276646)
		(width 0.0889)
		(layer "In2.Cu")
		(net "M_I_CPU0_SA_DQ<13>")
	)
	(arc
		(start 385.74345 -234.281472)
		(mid 385.559942 -234.326966)
		(end 385.37769 -234.276646)
		(width 0.0889)
		(layer "In2.Cu")
		(net "M_I_CPU0_SA_DQ<13>")
	)
	(arc
		(start 378.79782 -234.276646)
		(mid 378.514864 -234.200469)
		(end 378.231908 -234.276646)
		(width 0.0889)
		(layer "In2.Cu")
		(net "M_I_CPU0_SA_DQ<13>")
	)
	(arc
		(start 386.317744 -234.276646)
		(mid 386.034788 -234.200469)
		(end 385.751832 -234.276646)
		(width 0.0889)
		(layer "In2.Cu")
		(net "M_I_CPU0_SA_DQ<13>")
	)
	(arc
		(start 384.43789 -234.276646)
		(mid 384.154934 -234.200469)
		(end 383.871978 -234.276646)
		(width 0.0889)
		(layer "In2.Cu")
		(net "M_I_CPU0_SA_DQ<13>")
	)
	(arc
		(start 377.283472 -234.281472)
		(mid 377.099964 -234.326966)
		(end 376.917712 -234.276646)
		(width 0.0889)
		(layer "In2.Cu")
		(net "M_I_CPU0_SA_DQ<13>")
	)
	(arc
		(start 384.811778 -234.276646)
		(mid 384.624834 -234.326901)
		(end 384.43789 -234.276646)
		(width 0.0889)
		(layer "In2.Cu")
		(net "M_I_CPU0_SA_DQ<13>")
	)
	(arc
		(start 391.916158 -234.005628)
		(mid 391.760675 -234.123385)
		(end 391.5791 -234.194604)
		(width 0.0889)
		(layer "In2.Cu")
		(net "M_I_CPU0_SA_DQ<13>")
	)
	(arc
		(start 385.37769 -234.276646)
		(mid 385.094734 -234.200469)
		(end 384.811778 -234.276646)
		(width 0.0889)
		(layer "In2.Cu")
		(net "M_I_CPU0_SA_DQ<13>")
	)
	(arc
		(start 387.63194 -234.276646)
		(mid 387.449689 -234.326996)
		(end 387.26618 -234.281472)
		(width 0.0889)
		(layer "In2.Cu")
		(net "M_I_CPU0_SA_DQ<13>")
	)
	(arc
		(start 380.111762 -234.276646)
		(mid 379.924818 -234.326901)
		(end 379.737874 -234.276646)
		(width 0.0889)
		(layer "In2.Cu")
		(net "M_I_CPU0_SA_DQ<13>")
	)
	(arc
		(start 386.683504 -234.281472)
		(mid 386.499996 -234.326966)
		(end 386.317744 -234.276646)
		(width 0.0889)
		(layer "In2.Cu")
		(net "M_I_CPU0_SA_DQ<13>")
	)
	(arc
		(start 389.137906 -234.276646)
		(mid 388.85495 -234.200469)
		(end 388.571994 -234.276646)
		(width 0.0889)
		(layer "In2.Cu")
		(net "M_I_CPU0_SA_DQ<13>")
	)
	(arc
		(start 376.917712 -234.276646)
		(mid 376.634756 -234.200469)
		(end 376.3518 -234.276646)
		(width 0.0889)
		(layer "In2.Cu")
		(net "M_I_CPU0_SA_DQ<13>")
	)
	(arc
		(start 390.443466 -234.281472)
		(mid 390.259958 -234.326966)
		(end 390.077706 -234.276646)
		(width 0.0889)
		(layer "In2.Cu")
		(net "M_I_CPU0_SA_DQ<13>")
	)
	(arc
		(start 383.497836 -234.276646)
		(mid 383.21488 -234.200469)
		(end 382.931924 -234.276646)
		(width 0.0889)
		(layer "In2.Cu")
		(net "M_I_CPU0_SA_DQ<13>")
	)
	(arc
		(start 379.171962 -234.276646)
		(mid 378.989711 -234.326996)
		(end 378.806202 -234.281472)
		(width 0.0889)
		(layer "In2.Cu")
		(net "M_I_CPU0_SA_DQ<13>")
	)
	(arc
		(start 391.01776 -234.276646)
		(mid 390.734804 -234.200469)
		(end 390.451848 -234.276646)
		(width 0.0889)
		(layer "In2.Cu")
		(net "M_I_CPU0_SA_DQ<13>")
	)
	(segment
		(start 377.107958 -233.409998)
		(end 377.57481 -233.14406)
		(width 0.10668)
		(layer "F.Cu")
		(net "M_I_CPU0_SA_DQ<12>")
	)
	(segment
		(start 383.393442 -233.471466)
		(end 383.401824 -233.46664)
		(width 0.0889)
		(layer "In2.Cu")
		(net "M_I_CPU0_SA_DQ<12>")
	)
	(segment
		(start 378.693426 -233.471466)
		(end 378.701808 -233.46664)
		(width 0.0889)
		(layer "In2.Cu")
		(net "M_I_CPU0_SA_DQ<12>")
	)
	(segment
		(start 384.333496 -233.471466)
		(end 384.341878 -233.46664)
		(width 0.0889)
		(layer "In2.Cu")
		(net "M_I_CPU0_SA_DQ<12>")
	)
	(segment
		(start 415.110422 -212.219794)
		(end 417.781994 -212.219794)
		(width 0.14478)
		(layer "In2.Cu")
		(net "M_I_CPU0_SA_DQ<12>")
	)
	(segment
		(start 379.63348 -233.471466)
		(end 379.641862 -233.46664)
		(width 0.0889)
		(layer "In2.Cu")
		(net "M_I_CPU0_SA_DQ<12>")
	)
	(segment
		(start 395.03858 -228.832664)
		(end 395.03858 -228.148388)
		(width 0.0889)
		(layer "In2.Cu")
		(net "M_I_CPU0_SA_DQ<12>")
	)
	(segment
		(start 429.650906 -212.862668)
		(end 429.81245 -213.024212)
		(width 0.14478)
		(layer "In2.Cu")
		(net "M_I_CPU0_SA_DQ<12>")
	)
	(segment
		(start 429.489362 -211.415376)
		(end 429.650906 -211.57692)
		(width 0.14478)
		(layer "In2.Cu")
		(net "M_I_CPU0_SA_DQ<12>")
	)
	(segment
		(start 393.440412 -230.430832)
		(end 395.03858 -228.832664)
		(width 0.0889)
		(layer "In2.Cu")
		(net "M_I_CPU0_SA_DQ<12>")
	)
	(segment
		(start 430.20234 -212.381338)
		(end 430.363884 -212.219794)
		(width 0.14478)
		(layer "In2.Cu")
		(net "M_I_CPU0_SA_DQ<12>")
	)
	(segment
		(start 429.81245 -213.024212)
		(end 430.040796 -213.024212)
		(width 0.14478)
		(layer "In2.Cu")
		(net "M_I_CPU0_SA_DQ<12>")
	)
	(segment
		(start 392.509248 -231.88041)
		(end 393.440412 -230.949246)
		(width 0.0889)
		(layer "In2.Cu")
		(net "M_I_CPU0_SA_DQ<12>")
	)
	(segment
		(start 414.260538 -213.069678)
		(end 415.110422 -212.219794)
		(width 0.14478)
		(layer "In2.Cu")
		(net "M_I_CPU0_SA_DQ<12>")
	)
	(segment
		(start 429.099472 -211.57692)
		(end 429.261016 -211.415376)
		(width 0.14478)
		(layer "In2.Cu")
		(net "M_I_CPU0_SA_DQ<12>")
	)
	(segment
		(start 385.847844 -233.46664)
		(end 385.856226 -233.471466)
		(width 0.0889)
		(layer "In2.Cu")
		(net "M_I_CPU0_SA_DQ<12>")
	)
	(segment
		(start 429.261016 -211.415376)
		(end 429.489362 -211.415376)
		(width 0.14478)
		(layer "In2.Cu")
		(net "M_I_CPU0_SA_DQ<12>")
	)
	(segment
		(start 396.993618 -226.19335)
		(end 396.993618 -225.523044)
		(width 0.14478)
		(layer "In2.Cu")
		(net "M_I_CPU0_SA_DQ<12>")
	)
	(segment
		(start 421.583358 -213.069678)
		(end 422.433242 -212.219794)
		(width 0.14478)
		(layer "In2.Cu")
		(net "M_I_CPU0_SA_DQ<12>")
	)
	(segment
		(start 396.993618 -225.523044)
		(end 409.446984 -213.069678)
		(width 0.14478)
		(layer "In2.Cu")
		(net "M_I_CPU0_SA_DQ<12>")
	)
	(segment
		(start 422.433242 -212.219794)
		(end 428.937928 -212.219794)
		(width 0.14478)
		(layer "In2.Cu")
		(net "M_I_CPU0_SA_DQ<12>")
	)
	(segment
		(start 384.90779 -233.46664)
		(end 384.916172 -233.471466)
		(width 0.0889)
		(layer "In2.Cu")
		(net "M_I_CPU0_SA_DQ<12>")
	)
	(segment
		(start 430.20234 -212.862668)
		(end 430.20234 -212.381338)
		(width 0.14478)
		(layer "In2.Cu")
		(net "M_I_CPU0_SA_DQ<12>")
	)
	(segment
		(start 429.099472 -212.05825)
		(end 429.099472 -211.57692)
		(width 0.14478)
		(layer "In2.Cu")
		(net "M_I_CPU0_SA_DQ<12>")
	)
	(segment
		(start 430.363884 -212.219794)
		(end 431.14087 -212.219794)
		(width 0.14478)
		(layer "In2.Cu")
		(net "M_I_CPU0_SA_DQ<12>")
	)
	(segment
		(start 380.207774 -233.46664)
		(end 380.216156 -233.471466)
		(width 0.0889)
		(layer "In2.Cu")
		(net "M_I_CPU0_SA_DQ<12>")
	)
	(segment
		(start 389.607806 -233.46664)
		(end 389.616188 -233.471466)
		(width 0.0889)
		(layer "In2.Cu")
		(net "M_I_CPU0_SA_DQ<12>")
	)
	(segment
		(start 395.03858 -228.148388)
		(end 395.27099 -227.915978)
		(width 0.0889)
		(layer "In2.Cu")
		(net "M_I_CPU0_SA_DQ<12>")
	)
	(segment
		(start 418.631878 -213.069678)
		(end 421.583358 -213.069678)
		(width 0.14478)
		(layer "In2.Cu")
		(net "M_I_CPU0_SA_DQ<12>")
	)
	(segment
		(start 391.900918 -233.436668)
		(end 392.509248 -232.828338)
		(width 0.0889)
		(layer "In2.Cu")
		(net "M_I_CPU0_SA_DQ<12>")
	)
	(segment
		(start 377.57481 -233.14406)
		(end 377.420886 -233.40949)
		(width 0.0889)
		(layer "In2.Cu")
		(net "M_I_CPU0_SA_DQ<12>")
	)
	(segment
		(start 388.093458 -233.471466)
		(end 388.10184 -233.46664)
		(width 0.0889)
		(layer "In2.Cu")
		(net "M_I_CPU0_SA_DQ<12>")
	)
	(segment
		(start 428.937928 -212.219794)
		(end 429.099472 -212.05825)
		(width 0.14478)
		(layer "In2.Cu")
		(net "M_I_CPU0_SA_DQ<12>")
	)
	(segment
		(start 409.446984 -213.069678)
		(end 414.260538 -213.069678)
		(width 0.14478)
		(layer "In2.Cu")
		(net "M_I_CPU0_SA_DQ<12>")
	)
	(segment
		(start 393.440412 -230.949246)
		(end 393.440412 -230.430832)
		(width 0.0889)
		(layer "In2.Cu")
		(net "M_I_CPU0_SA_DQ<12>")
	)
	(segment
		(start 417.781994 -212.219794)
		(end 418.631878 -213.069678)
		(width 0.14478)
		(layer "In2.Cu")
		(net "M_I_CPU0_SA_DQ<12>")
	)
	(segment
		(start 431.14087 -212.219794)
		(end 431.55616 -212.635084)
		(width 0.14478)
		(layer "In2.Cu")
		(net "M_I_CPU0_SA_DQ<12>")
	)
	(segment
		(start 429.650906 -211.57692)
		(end 429.650906 -212.862668)
		(width 0.14478)
		(layer "In2.Cu")
		(net "M_I_CPU0_SA_DQ<12>")
	)
	(segment
		(start 392.509248 -232.828338)
		(end 392.509248 -231.88041)
		(width 0.0889)
		(layer "In2.Cu")
		(net "M_I_CPU0_SA_DQ<12>")
	)
	(segment
		(start 395.27099 -227.915978)
		(end 396.993618 -226.19335)
		(width 0.14478)
		(layer "In2.Cu")
		(net "M_I_CPU0_SA_DQ<12>")
	)
	(segment
		(start 377.420886 -233.40949)
		(end 377.443238 -233.492802)
		(width 0.0889)
		(layer "In2.Cu")
		(net "M_I_CPU0_SA_DQ<12>")
	)
	(segment
		(start 389.033512 -233.471466)
		(end 389.041894 -233.46664)
		(width 0.0889)
		(layer "In2.Cu")
		(net "M_I_CPU0_SA_DQ<12>")
	)
	(segment
		(start 381.147828 -233.46664)
		(end 381.15621 -233.471466)
		(width 0.0889)
		(layer "In2.Cu")
		(net "M_I_CPU0_SA_DQ<12>")
	)
	(segment
		(start 391.85342 -233.471466)
		(end 391.861802 -233.46664)
		(width 0.0889)
		(layer "In2.Cu")
		(net "M_I_CPU0_SA_DQ<12>")
	)
	(segment
		(start 430.040796 -213.024212)
		(end 430.20234 -212.862668)
		(width 0.14478)
		(layer "In2.Cu")
		(net "M_I_CPU0_SA_DQ<12>")
	)
	(arc
		(start 383.027682 -233.46664)
		(mid 383.209933 -233.51699)
		(end 383.393442 -233.471466)
		(width 0.0889)
		(layer "In2.Cu")
		(net "M_I_CPU0_SA_DQ<12>")
	)
	(arc
		(start 382.46177 -233.46664)
		(mid 382.744726 -233.390463)
		(end 383.027682 -233.46664)
		(width 0.0889)
		(layer "In2.Cu")
		(net "M_I_CPU0_SA_DQ<12>")
	)
	(arc
		(start 379.641862 -233.46664)
		(mid 379.924818 -233.390463)
		(end 380.207774 -233.46664)
		(width 0.0889)
		(layer "In2.Cu")
		(net "M_I_CPU0_SA_DQ<12>")
	)
	(arc
		(start 383.967736 -233.46664)
		(mid 384.149987 -233.51699)
		(end 384.333496 -233.471466)
		(width 0.0889)
		(layer "In2.Cu")
		(net "M_I_CPU0_SA_DQ<12>")
	)
	(arc
		(start 385.281932 -233.46664)
		(mid 385.564888 -233.390463)
		(end 385.847844 -233.46664)
		(width 0.0889)
		(layer "In2.Cu")
		(net "M_I_CPU0_SA_DQ<12>")
	)
	(arc
		(start 389.041894 -233.46664)
		(mid 389.32485 -233.390463)
		(end 389.607806 -233.46664)
		(width 0.0889)
		(layer "In2.Cu")
		(net "M_I_CPU0_SA_DQ<12>")
	)
	(arc
		(start 384.916172 -233.471466)
		(mid 385.09968 -233.51696)
		(end 385.281932 -233.46664)
		(width 0.0889)
		(layer "In2.Cu")
		(net "M_I_CPU0_SA_DQ<12>")
	)
	(arc
		(start 378.701808 -233.46664)
		(mid 378.984764 -233.390463)
		(end 379.26772 -233.46664)
		(width 0.0889)
		(layer "In2.Cu")
		(net "M_I_CPU0_SA_DQ<12>")
	)
	(arc
		(start 386.787898 -233.46664)
		(mid 386.974842 -233.516895)
		(end 387.161786 -233.46664)
		(width 0.0889)
		(layer "In2.Cu")
		(net "M_I_CPU0_SA_DQ<12>")
	)
	(arc
		(start 389.616188 -233.471466)
		(mid 389.799696 -233.51696)
		(end 389.981948 -233.46664)
		(width 0.0889)
		(layer "In2.Cu")
		(net "M_I_CPU0_SA_DQ<12>")
	)
	(arc
		(start 382.087882 -233.46664)
		(mid 382.274826 -233.516895)
		(end 382.46177 -233.46664)
		(width 0.0889)
		(layer "In2.Cu")
		(net "M_I_CPU0_SA_DQ<12>")
	)
	(arc
		(start 379.26772 -233.46664)
		(mid 379.449971 -233.51699)
		(end 379.63348 -233.471466)
		(width 0.0889)
		(layer "In2.Cu")
		(net "M_I_CPU0_SA_DQ<12>")
	)
	(arc
		(start 386.221986 -233.46664)
		(mid 386.504942 -233.390463)
		(end 386.787898 -233.46664)
		(width 0.0889)
		(layer "In2.Cu")
		(net "M_I_CPU0_SA_DQ<12>")
	)
	(arc
		(start 380.581916 -233.46664)
		(mid 380.864872 -233.390463)
		(end 381.147828 -233.46664)
		(width 0.0889)
		(layer "In2.Cu")
		(net "M_I_CPU0_SA_DQ<12>")
	)
	(arc
		(start 390.54786 -233.46664)
		(mid 390.734804 -233.516895)
		(end 390.921748 -233.46664)
		(width 0.0889)
		(layer "In2.Cu")
		(net "M_I_CPU0_SA_DQ<12>")
	)
	(arc
		(start 387.161786 -233.46664)
		(mid 387.444742 -233.390463)
		(end 387.727698 -233.46664)
		(width 0.0889)
		(layer "In2.Cu")
		(net "M_I_CPU0_SA_DQ<12>")
	)
	(arc
		(start 380.216156 -233.471466)
		(mid 380.399664 -233.51696)
		(end 380.581916 -233.46664)
		(width 0.0889)
		(layer "In2.Cu")
		(net "M_I_CPU0_SA_DQ<12>")
	)
	(arc
		(start 390.921748 -233.46664)
		(mid 391.204704 -233.390463)
		(end 391.48766 -233.46664)
		(width 0.0889)
		(layer "In2.Cu")
		(net "M_I_CPU0_SA_DQ<12>")
	)
	(arc
		(start 378.327666 -233.46664)
		(mid 378.509917 -233.51699)
		(end 378.693426 -233.471466)
		(width 0.0889)
		(layer "In2.Cu")
		(net "M_I_CPU0_SA_DQ<12>")
	)
	(arc
		(start 391.861802 -233.46664)
		(mid 391.882346 -233.452941)
		(end 391.900918 -233.436668)
		(width 0.0889)
		(layer "In2.Cu")
		(net "M_I_CPU0_SA_DQ<12>")
	)
	(arc
		(start 385.856226 -233.471466)
		(mid 386.039734 -233.51696)
		(end 386.221986 -233.46664)
		(width 0.0889)
		(layer "In2.Cu")
		(net "M_I_CPU0_SA_DQ<12>")
	)
	(arc
		(start 383.401824 -233.46664)
		(mid 383.68478 -233.390463)
		(end 383.967736 -233.46664)
		(width 0.0889)
		(layer "In2.Cu")
		(net "M_I_CPU0_SA_DQ<12>")
	)
	(arc
		(start 388.10184 -233.46664)
		(mid 388.384796 -233.390463)
		(end 388.667752 -233.46664)
		(width 0.0889)
		(layer "In2.Cu")
		(net "M_I_CPU0_SA_DQ<12>")
	)
	(arc
		(start 377.761754 -233.46664)
		(mid 378.04471 -233.390463)
		(end 378.327666 -233.46664)
		(width 0.0889)
		(layer "In2.Cu")
		(net "M_I_CPU0_SA_DQ<12>")
	)
	(arc
		(start 377.443238 -233.492802)
		(mid 377.605427 -233.515537)
		(end 377.761754 -233.46664)
		(width 0.0889)
		(layer "In2.Cu")
		(net "M_I_CPU0_SA_DQ<12>")
	)
	(arc
		(start 384.341878 -233.46664)
		(mid 384.624834 -233.390463)
		(end 384.90779 -233.46664)
		(width 0.0889)
		(layer "In2.Cu")
		(net "M_I_CPU0_SA_DQ<12>")
	)
	(arc
		(start 391.48766 -233.46664)
		(mid 391.669911 -233.51699)
		(end 391.85342 -233.471466)
		(width 0.0889)
		(layer "In2.Cu")
		(net "M_I_CPU0_SA_DQ<12>")
	)
	(arc
		(start 381.52197 -233.46664)
		(mid 381.804926 -233.390463)
		(end 382.087882 -233.46664)
		(width 0.0889)
		(layer "In2.Cu")
		(net "M_I_CPU0_SA_DQ<12>")
	)
	(arc
		(start 389.981948 -233.46664)
		(mid 390.264904 -233.390463)
		(end 390.54786 -233.46664)
		(width 0.0889)
		(layer "In2.Cu")
		(net "M_I_CPU0_SA_DQ<12>")
	)
	(arc
		(start 388.667752 -233.46664)
		(mid 388.850003 -233.51699)
		(end 389.033512 -233.471466)
		(width 0.0889)
		(layer "In2.Cu")
		(net "M_I_CPU0_SA_DQ<12>")
	)
	(arc
		(start 387.727698 -233.46664)
		(mid 387.909949 -233.51699)
		(end 388.093458 -233.471466)
		(width 0.0889)
		(layer "In2.Cu")
		(net "M_I_CPU0_SA_DQ<12>")
	)
	(arc
		(start 381.15621 -233.471466)
		(mid 381.339718 -233.51696)
		(end 381.52197 -233.46664)
		(width 0.0889)
		(layer "In2.Cu")
		(net "M_I_CPU0_SA_DQ<12>")
	)
	(segment
		(start 375.22785 -231.789986)
		(end 375.694702 -231.524048)
		(width 0.10668)
		(layer "F.Cu")
		(net "M_I_CPU0_SA_DQ<11>")
	)
	(segment
		(start 402.219922 -215.796368)
		(end 402.686266 -216.262712)
		(width 0.14478)
		(layer "In2.Cu")
		(net "M_I_CPU0_SA_DQ<11>")
	)
	(segment
		(start 394.984478 -224.202752)
		(end 402.300948 -216.886282)
		(width 0.14478)
		(layer "In2.Cu")
		(net "M_I_CPU0_SA_DQ<11>")
	)
	(segment
		(start 408.13736 -209.65033)
		(end 413.92729 -209.65033)
		(width 0.14478)
		(layer "In2.Cu")
		(net "M_I_CPU0_SA_DQ<11>")
	)
	(segment
		(start 425.608242 -208.49971)
		(end 425.847002 -208.73847)
		(width 0.14478)
		(layer "In2.Cu")
		(net "M_I_CPU0_SA_DQ<11>")
	)
	(segment
		(start 388.093458 -231.196896)
		(end 388.10184 -231.201722)
		(width 0.0889)
		(layer "In2.Cu")
		(net "M_I_CPU0_SA_DQ<11>")
	)
	(segment
		(start 426.47489 -208.49971)
		(end 426.720762 -208.49971)
		(width 0.14478)
		(layer "In2.Cu")
		(net "M_I_CPU0_SA_DQ<11>")
	)
	(segment
		(start 415.07791 -208.49971)
		(end 415.323782 -208.49971)
		(width 0.14478)
		(layer "In2.Cu")
		(net "M_I_CPU0_SA_DQ<11>")
	)
	(segment
		(start 389.033512 -231.196896)
		(end 389.041894 -231.201722)
		(width 0.0889)
		(layer "In2.Cu")
		(net "M_I_CPU0_SA_DQ<11>")
	)
	(segment
		(start 422.590976 -208.52511)
		(end 422.862248 -208.52511)
		(width 0.14478)
		(layer "In2.Cu")
		(net "M_I_CPU0_SA_DQ<11>")
	)
	(segment
		(start 403.07641 -216.101168)
		(end 403.07641 -215.872568)
		(width 0.14478)
		(layer "In2.Cu")
		(net "M_I_CPU0_SA_DQ<11>")
	)
	(segment
		(start 401.829778 -215.957912)
		(end 401.991322 -215.796368)
		(width 0.14478)
		(layer "In2.Cu")
		(net "M_I_CPU0_SA_DQ<11>")
	)
	(segment
		(start 375.84888 -231.258618)
		(end 375.944638 -231.233218)
		(width 0.0889)
		(layer "In2.Cu")
		(net "M_I_CPU0_SA_DQ<11>")
	)
	(segment
		(start 392.866118 -227.16998)
		(end 392.897868 -227.151692)
		(width 0.0889)
		(layer "In2.Cu")
		(net "M_I_CPU0_SA_DQ<11>")
	)
	(segment
		(start 378.693426 -231.196896)
		(end 378.701808 -231.201722)
		(width 0.0889)
		(layer "In2.Cu")
		(net "M_I_CPU0_SA_DQ<11>")
	)
	(segment
		(start 401.991322 -215.796368)
		(end 402.219922 -215.796368)
		(width 0.14478)
		(layer "In2.Cu")
		(net "M_I_CPU0_SA_DQ<11>")
	)
	(segment
		(start 389.607806 -231.201722)
		(end 389.616188 -231.196896)
		(width 0.0889)
		(layer "In2.Cu")
		(net "M_I_CPU0_SA_DQ<11>")
	)
	(segment
		(start 417.62426 -208.49971)
		(end 417.870132 -208.49971)
		(width 0.14478)
		(layer "In2.Cu")
		(net "M_I_CPU0_SA_DQ<11>")
	)
	(segment
		(start 394.103098 -225.622104)
		(end 394.449046 -225.622104)
		(width 0.0889)
		(layer "In2.Cu")
		(net "M_I_CPU0_SA_DQ<11>")
	)
	(segment
		(start 392.397234 -227.979478)
		(end 392.427714 -227.961698)
		(width 0.0889)
		(layer "In2.Cu")
		(net "M_I_CPU0_SA_DQ<11>")
	)
	(segment
		(start 413.92729 -209.65033)
		(end 415.07791 -208.49971)
		(width 0.14478)
		(layer "In2.Cu")
		(net "M_I_CPU0_SA_DQ<11>")
	)
	(segment
		(start 401.829778 -216.186512)
		(end 401.829778 -215.957912)
		(width 0.14478)
		(layer "In2.Cu")
		(net "M_I_CPU0_SA_DQ<11>")
	)
	(segment
		(start 390.54786 -231.201722)
		(end 390.584182 -231.18064)
		(width 0.0889)
		(layer "In2.Cu")
		(net "M_I_CPU0_SA_DQ<11>")
	)
	(segment
		(start 385.847844 -231.201722)
		(end 385.856226 -231.196896)
		(width 0.0889)
		(layer "In2.Cu")
		(net "M_I_CPU0_SA_DQ<11>")
	)
	(segment
		(start 402.300948 -216.886282)
		(end 402.300948 -216.657682)
		(width 0.14478)
		(layer "In2.Cu")
		(net "M_I_CPU0_SA_DQ<11>")
	)
	(segment
		(start 415.624518 -208.800446)
		(end 417.323524 -208.800446)
		(width 0.14478)
		(layer "In2.Cu")
		(net "M_I_CPU0_SA_DQ<11>")
	)
	(segment
		(start 419.020752 -209.65033)
		(end 421.465756 -209.65033)
		(width 0.14478)
		(layer "In2.Cu")
		(net "M_I_CPU0_SA_DQ<11>")
	)
	(segment
		(start 402.610066 -215.406224)
		(end 402.610066 -215.177624)
		(width 0.14478)
		(layer "In2.Cu")
		(net "M_I_CPU0_SA_DQ<11>")
	)
	(segment
		(start 381.147828 -231.201722)
		(end 381.15621 -231.196896)
		(width 0.0889)
		(layer "In2.Cu")
		(net "M_I_CPU0_SA_DQ<11>")
	)
	(segment
		(start 417.870132 -208.49971)
		(end 419.020752 -209.65033)
		(width 0.14478)
		(layer "In2.Cu")
		(net "M_I_CPU0_SA_DQ<11>")
	)
	(segment
		(start 415.323782 -208.49971)
		(end 415.624518 -208.800446)
		(width 0.14478)
		(layer "In2.Cu")
		(net "M_I_CPU0_SA_DQ<11>")
	)
	(segment
		(start 392.427714 -227.961698)
		(end 392.46683 -227.938838)
		(width 0.0889)
		(layer "In2.Cu")
		(net "M_I_CPU0_SA_DQ<11>")
	)
	(segment
		(start 391.48766 -229.58171)
		(end 391.524744 -229.560374)
		(width 0.0889)
		(layer "In2.Cu")
		(net "M_I_CPU0_SA_DQ<11>")
	)
	(segment
		(start 425.061634 -208.800446)
		(end 425.36237 -208.49971)
		(width 0.14478)
		(layer "In2.Cu")
		(net "M_I_CPU0_SA_DQ<11>")
	)
	(segment
		(start 391.524744 -229.560374)
		(end 391.526776 -229.55885)
		(width 0.0889)
		(layer "In2.Cu")
		(net "M_I_CPU0_SA_DQ<11>")
	)
	(segment
		(start 426.23613 -208.73847)
		(end 426.47489 -208.49971)
		(width 0.14478)
		(layer "In2.Cu")
		(net "M_I_CPU0_SA_DQ<11>")
	)
	(segment
		(start 425.847002 -208.73847)
		(end 426.23613 -208.73847)
		(width 0.14478)
		(layer "In2.Cu")
		(net "M_I_CPU0_SA_DQ<11>")
	)
	(segment
		(start 380.207774 -231.201722)
		(end 380.216156 -231.196896)
		(width 0.0889)
		(layer "In2.Cu")
		(net "M_I_CPU0_SA_DQ<11>")
	)
	(segment
		(start 394.449046 -225.622104)
		(end 394.865098 -225.206052)
		(width 0.0889)
		(layer "In2.Cu")
		(net "M_I_CPU0_SA_DQ<11>")
	)
	(segment
		(start 425.36237 -208.49971)
		(end 425.608242 -208.49971)
		(width 0.14478)
		(layer "In2.Cu")
		(net "M_I_CPU0_SA_DQ<11>")
	)
	(segment
		(start 375.694702 -231.524048)
		(end 375.84888 -231.258618)
		(width 0.0889)
		(layer "In2.Cu")
		(net "M_I_CPU0_SA_DQ<11>")
	)
	(segment
		(start 402.610066 -215.177624)
		(end 408.13736 -209.65033)
		(width 0.14478)
		(layer "In2.Cu")
		(net "M_I_CPU0_SA_DQ<11>")
	)
	(segment
		(start 391.957814 -228.771704)
		(end 391.99693 -228.748844)
		(width 0.0889)
		(layer "In2.Cu")
		(net "M_I_CPU0_SA_DQ<11>")
	)
	(segment
		(start 392.897868 -227.151692)
		(end 392.936984 -227.128832)
		(width 0.0889)
		(layer "In2.Cu")
		(net "M_I_CPU0_SA_DQ<11>")
	)
	(segment
		(start 402.914866 -216.262712)
		(end 403.07641 -216.101168)
		(width 0.14478)
		(layer "In2.Cu")
		(net "M_I_CPU0_SA_DQ<11>")
	)
	(segment
		(start 379.63348 -231.196896)
		(end 379.641862 -231.201722)
		(width 0.0889)
		(layer "In2.Cu")
		(net "M_I_CPU0_SA_DQ<11>")
	)
	(segment
		(start 402.686266 -216.262712)
		(end 402.914866 -216.262712)
		(width 0.14478)
		(layer "In2.Cu")
		(net "M_I_CPU0_SA_DQ<11>")
	)
	(segment
		(start 391.455148 -229.600506)
		(end 391.48766 -229.58171)
		(width 0.0889)
		(layer "In2.Cu")
		(net "M_I_CPU0_SA_DQ<11>")
	)
	(segment
		(start 394.865098 -225.206052)
		(end 394.865098 -224.322132)
		(width 0.0889)
		(layer "In2.Cu")
		(net "M_I_CPU0_SA_DQ<11>")
	)
	(segment
		(start 417.323524 -208.800446)
		(end 417.62426 -208.49971)
		(width 0.14478)
		(layer "In2.Cu")
		(net "M_I_CPU0_SA_DQ<11>")
	)
	(segment
		(start 391.926064 -228.789992)
		(end 391.957814 -228.771704)
		(width 0.0889)
		(layer "In2.Cu")
		(net "M_I_CPU0_SA_DQ<11>")
	)
	(segment
		(start 384.90779 -231.201722)
		(end 384.916172 -231.196896)
		(width 0.0889)
		(layer "In2.Cu")
		(net "M_I_CPU0_SA_DQ<11>")
	)
	(segment
		(start 403.07641 -215.872568)
		(end 402.610066 -215.406224)
		(width 0.14478)
		(layer "In2.Cu")
		(net "M_I_CPU0_SA_DQ<11>")
	)
	(segment
		(start 402.300948 -216.657682)
		(end 401.829778 -216.186512)
		(width 0.14478)
		(layer "In2.Cu")
		(net "M_I_CPU0_SA_DQ<11>")
	)
	(segment
		(start 422.862248 -208.52511)
		(end 423.137584 -208.800446)
		(width 0.14478)
		(layer "In2.Cu")
		(net "M_I_CPU0_SA_DQ<11>")
	)
	(segment
		(start 421.465756 -209.65033)
		(end 422.590976 -208.52511)
		(width 0.14478)
		(layer "In2.Cu")
		(net "M_I_CPU0_SA_DQ<11>")
	)
	(segment
		(start 376.447812 -231.201722)
		(end 376.456194 -231.196896)
		(width 0.0889)
		(layer "In2.Cu")
		(net "M_I_CPU0_SA_DQ<11>")
	)
	(segment
		(start 423.137584 -208.800446)
		(end 425.061634 -208.800446)
		(width 0.14478)
		(layer "In2.Cu")
		(net "M_I_CPU0_SA_DQ<11>")
	)
	(segment
		(start 393.572746 -226.152456)
		(end 394.103098 -225.622104)
		(width 0.0889)
		(layer "In2.Cu")
		(net "M_I_CPU0_SA_DQ<11>")
	)
	(segment
		(start 384.333496 -231.196896)
		(end 384.341878 -231.201722)
		(width 0.0889)
		(layer "In2.Cu")
		(net "M_I_CPU0_SA_DQ<11>")
	)
	(segment
		(start 394.865098 -224.322132)
		(end 394.984478 -224.202752)
		(width 0.0889)
		(layer "In2.Cu")
		(net "M_I_CPU0_SA_DQ<11>")
	)
	(segment
		(start 391.01776 -230.391716)
		(end 391.054336 -230.37038)
		(width 0.0889)
		(layer "In2.Cu")
		(net "M_I_CPU0_SA_DQ<11>")
	)
	(segment
		(start 393.337288 -226.359466)
		(end 393.367768 -226.341686)
		(width 0.0889)
		(layer "In2.Cu")
		(net "M_I_CPU0_SA_DQ<11>")
	)
	(segment
		(start 390.98601 -230.410004)
		(end 391.01776 -230.391716)
		(width 0.0889)
		(layer "In2.Cu")
		(net "M_I_CPU0_SA_DQ<11>")
	)
	(segment
		(start 383.393442 -231.196896)
		(end 383.401824 -231.201722)
		(width 0.0889)
		(layer "In2.Cu")
		(net "M_I_CPU0_SA_DQ<11>")
	)
	(segment
		(start 426.720762 -208.49971)
		(end 427.456092 -209.23504)
		(width 0.14478)
		(layer "In2.Cu")
		(net "M_I_CPU0_SA_DQ<11>")
	)
	(arc
		(start 393.465558 -226.283012)
		(mid 393.493955 -226.251687)
		(end 393.519152 -226.217734)
		(width 0.0889)
		(layer "In2.Cu")
		(net "M_I_CPU0_SA_DQ<11>")
	)
	(arc
		(start 389.981948 -231.201722)
		(mid 390.264904 -231.277899)
		(end 390.54786 -231.201722)
		(width 0.0889)
		(layer "In2.Cu")
		(net "M_I_CPU0_SA_DQ<11>")
	)
	(arc
		(start 392.240262 -228.284278)
		(mid 392.281811 -228.112856)
		(end 392.397234 -227.979478)
		(width 0.0889)
		(layer "In2.Cu")
		(net "M_I_CPU0_SA_DQ<11>")
	)
	(arc
		(start 381.15621 -231.196896)
		(mid 381.339718 -231.151371)
		(end 381.52197 -231.201722)
		(width 0.0889)
		(layer "In2.Cu")
		(net "M_I_CPU0_SA_DQ<11>")
	)
	(arc
		(start 379.641862 -231.201722)
		(mid 379.924818 -231.277899)
		(end 380.207774 -231.201722)
		(width 0.0889)
		(layer "In2.Cu")
		(net "M_I_CPU0_SA_DQ<11>")
	)
	(arc
		(start 392.710162 -227.474272)
		(mid 392.751417 -227.303301)
		(end 392.866118 -227.16998)
		(width 0.0889)
		(layer "In2.Cu")
		(net "M_I_CPU0_SA_DQ<11>")
	)
	(arc
		(start 387.161786 -231.201722)
		(mid 387.444742 -231.277899)
		(end 387.727698 -231.201722)
		(width 0.0889)
		(layer "In2.Cu")
		(net "M_I_CPU0_SA_DQ<11>")
	)
	(arc
		(start 392.936984 -227.128832)
		(mid 393.115797 -226.926482)
		(end 393.180316 -226.664266)
		(width 0.0889)
		(layer "In2.Cu")
		(net "M_I_CPU0_SA_DQ<11>")
	)
	(arc
		(start 391.054336 -230.37038)
		(mid 391.234988 -230.167635)
		(end 391.300208 -229.904036)
		(width 0.0889)
		(layer "In2.Cu")
		(net "M_I_CPU0_SA_DQ<11>")
	)
	(arc
		(start 383.401824 -231.201722)
		(mid 383.68478 -231.277899)
		(end 383.967736 -231.201722)
		(width 0.0889)
		(layer "In2.Cu")
		(net "M_I_CPU0_SA_DQ<11>")
	)
	(arc
		(start 383.967736 -231.201722)
		(mid 384.149987 -231.151338)
		(end 384.333496 -231.196896)
		(width 0.0889)
		(layer "In2.Cu")
		(net "M_I_CPU0_SA_DQ<11>")
	)
	(arc
		(start 388.667752 -231.201722)
		(mid 388.850003 -231.151338)
		(end 389.033512 -231.196896)
		(width 0.0889)
		(layer "In2.Cu")
		(net "M_I_CPU0_SA_DQ<11>")
	)
	(arc
		(start 391.300208 -229.904036)
		(mid 391.341174 -229.73363)
		(end 391.455148 -229.600506)
		(width 0.0889)
		(layer "In2.Cu")
		(net "M_I_CPU0_SA_DQ<11>")
	)
	(arc
		(start 378.701808 -231.201722)
		(mid 378.984764 -231.277899)
		(end 379.26772 -231.201722)
		(width 0.0889)
		(layer "In2.Cu")
		(net "M_I_CPU0_SA_DQ<11>")
	)
	(arc
		(start 389.041894 -231.201722)
		(mid 389.32485 -231.277899)
		(end 389.607806 -231.201722)
		(width 0.0889)
		(layer "In2.Cu")
		(net "M_I_CPU0_SA_DQ<11>")
	)
	(arc
		(start 375.944638 -231.233218)
		(mid 376.19996 -231.276918)
		(end 376.447812 -231.201722)
		(width 0.0889)
		(layer "In2.Cu")
		(net "M_I_CPU0_SA_DQ<11>")
	)
	(arc
		(start 385.281932 -231.201722)
		(mid 385.564888 -231.277899)
		(end 385.847844 -231.201722)
		(width 0.0889)
		(layer "In2.Cu")
		(net "M_I_CPU0_SA_DQ<11>")
	)
	(arc
		(start 384.916172 -231.196896)
		(mid 385.09968 -231.151371)
		(end 385.281932 -231.201722)
		(width 0.0889)
		(layer "In2.Cu")
		(net "M_I_CPU0_SA_DQ<11>")
	)
	(arc
		(start 382.46177 -231.201722)
		(mid 382.744726 -231.277899)
		(end 383.027682 -231.201722)
		(width 0.0889)
		(layer "In2.Cu")
		(net "M_I_CPU0_SA_DQ<11>")
	)
	(arc
		(start 385.856226 -231.196896)
		(mid 386.039734 -231.151371)
		(end 386.221986 -231.201722)
		(width 0.0889)
		(layer "In2.Cu")
		(net "M_I_CPU0_SA_DQ<11>")
	)
	(arc
		(start 378.327666 -231.201722)
		(mid 378.509917 -231.151338)
		(end 378.693426 -231.196896)
		(width 0.0889)
		(layer "In2.Cu")
		(net "M_I_CPU0_SA_DQ<11>")
	)
	(arc
		(start 391.99693 -228.748844)
		(mid 392.175743 -228.546494)
		(end 392.240262 -228.284278)
		(width 0.0889)
		(layer "In2.Cu")
		(net "M_I_CPU0_SA_DQ<11>")
	)
	(arc
		(start 384.341878 -231.201722)
		(mid 384.624834 -231.277899)
		(end 384.90779 -231.201722)
		(width 0.0889)
		(layer "In2.Cu")
		(net "M_I_CPU0_SA_DQ<11>")
	)
	(arc
		(start 388.10184 -231.201722)
		(mid 388.384796 -231.277899)
		(end 388.667752 -231.201722)
		(width 0.0889)
		(layer "In2.Cu")
		(net "M_I_CPU0_SA_DQ<11>")
	)
	(arc
		(start 393.519152 -226.217734)
		(mid 393.544349 -226.183782)
		(end 393.572746 -226.152456)
		(width 0.0889)
		(layer "In2.Cu")
		(net "M_I_CPU0_SA_DQ<11>")
	)
	(arc
		(start 377.387866 -231.201722)
		(mid 377.57481 -231.151433)
		(end 377.761754 -231.201722)
		(width 0.0889)
		(layer "In2.Cu")
		(net "M_I_CPU0_SA_DQ<11>")
	)
	(arc
		(start 376.821954 -231.201722)
		(mid 377.10491 -231.277899)
		(end 377.387866 -231.201722)
		(width 0.0889)
		(layer "In2.Cu")
		(net "M_I_CPU0_SA_DQ<11>")
	)
	(arc
		(start 380.581916 -231.201722)
		(mid 380.864872 -231.277899)
		(end 381.147828 -231.201722)
		(width 0.0889)
		(layer "In2.Cu")
		(net "M_I_CPU0_SA_DQ<11>")
	)
	(arc
		(start 386.787898 -231.201722)
		(mid 386.974842 -231.151433)
		(end 387.161786 -231.201722)
		(width 0.0889)
		(layer "In2.Cu")
		(net "M_I_CPU0_SA_DQ<11>")
	)
	(arc
		(start 389.616188 -231.196896)
		(mid 389.799696 -231.151371)
		(end 389.981948 -231.201722)
		(width 0.0889)
		(layer "In2.Cu")
		(net "M_I_CPU0_SA_DQ<11>")
	)
	(arc
		(start 381.52197 -231.201722)
		(mid 381.804926 -231.277899)
		(end 382.087882 -231.201722)
		(width 0.0889)
		(layer "In2.Cu")
		(net "M_I_CPU0_SA_DQ<11>")
	)
	(arc
		(start 380.216156 -231.196896)
		(mid 380.399664 -231.151371)
		(end 380.581916 -231.201722)
		(width 0.0889)
		(layer "In2.Cu")
		(net "M_I_CPU0_SA_DQ<11>")
	)
	(arc
		(start 387.727698 -231.201722)
		(mid 387.909949 -231.151338)
		(end 388.093458 -231.196896)
		(width 0.0889)
		(layer "In2.Cu")
		(net "M_I_CPU0_SA_DQ<11>")
	)
	(arc
		(start 390.584182 -231.18064)
		(mid 390.764834 -230.977895)
		(end 390.830054 -230.714296)
		(width 0.0889)
		(layer "In2.Cu")
		(net "M_I_CPU0_SA_DQ<11>")
	)
	(arc
		(start 383.027682 -231.201722)
		(mid 383.209933 -231.151338)
		(end 383.393442 -231.196896)
		(width 0.0889)
		(layer "In2.Cu")
		(net "M_I_CPU0_SA_DQ<11>")
	)
	(arc
		(start 376.456194 -231.196896)
		(mid 376.639702 -231.151371)
		(end 376.821954 -231.201722)
		(width 0.0889)
		(layer "In2.Cu")
		(net "M_I_CPU0_SA_DQ<11>")
	)
	(arc
		(start 392.46683 -227.938838)
		(mid 392.645643 -227.736488)
		(end 392.710162 -227.474272)
		(width 0.0889)
		(layer "In2.Cu")
		(net "M_I_CPU0_SA_DQ<11>")
	)
	(arc
		(start 377.761754 -231.201722)
		(mid 378.04471 -231.277899)
		(end 378.327666 -231.201722)
		(width 0.0889)
		(layer "In2.Cu")
		(net "M_I_CPU0_SA_DQ<11>")
	)
	(arc
		(start 393.367768 -226.341686)
		(mid 393.4203 -226.318401)
		(end 393.465558 -226.283012)
		(width 0.0889)
		(layer "In2.Cu")
		(net "M_I_CPU0_SA_DQ<11>")
	)
	(arc
		(start 379.26772 -231.201722)
		(mid 379.449971 -231.151338)
		(end 379.63348 -231.196896)
		(width 0.0889)
		(layer "In2.Cu")
		(net "M_I_CPU0_SA_DQ<11>")
	)
	(arc
		(start 390.830054 -230.714296)
		(mid 390.871309 -230.543325)
		(end 390.98601 -230.410004)
		(width 0.0889)
		(layer "In2.Cu")
		(net "M_I_CPU0_SA_DQ<11>")
	)
	(arc
		(start 391.770108 -229.094284)
		(mid 391.811363 -228.923313)
		(end 391.926064 -228.789992)
		(width 0.0889)
		(layer "In2.Cu")
		(net "M_I_CPU0_SA_DQ<11>")
	)
	(arc
		(start 382.087882 -231.201722)
		(mid 382.274826 -231.151433)
		(end 382.46177 -231.201722)
		(width 0.0889)
		(layer "In2.Cu")
		(net "M_I_CPU0_SA_DQ<11>")
	)
	(arc
		(start 386.221986 -231.201722)
		(mid 386.504942 -231.277899)
		(end 386.787898 -231.201722)
		(width 0.0889)
		(layer "In2.Cu")
		(net "M_I_CPU0_SA_DQ<11>")
	)
	(arc
		(start 391.526776 -229.55885)
		(mid 391.705589 -229.3565)
		(end 391.770108 -229.094284)
		(width 0.0889)
		(layer "In2.Cu")
		(net "M_I_CPU0_SA_DQ<11>")
	)
	(arc
		(start 393.180316 -226.664266)
		(mid 393.221865 -226.492844)
		(end 393.337288 -226.359466)
		(width 0.0889)
		(layer "In2.Cu")
		(net "M_I_CPU0_SA_DQ<11>")
	)
	(segment
		(start 376.638058 -230.97998)
		(end 377.10491 -230.714296)
		(width 0.10668)
		(layer "F.Cu")
		(net "M_I_CPU0_SA_DQ<10>")
	)
	(segment
		(start 399.350992 -217.430858)
		(end 399.75282 -217.832686)
		(width 0.14478)
		(layer "In2.Cu")
		(net "M_I_CPU0_SA_DQ<10>")
	)
	(segment
		(start 422.430702 -207.110076)
		(end 424.355006 -207.110076)
		(width 0.14478)
		(layer "In2.Cu")
		(net "M_I_CPU0_SA_DQ<10>")
	)
	(segment
		(start 392.397234 -226.359466)
		(end 392.427714 -226.341686)
		(width 0.0889)
		(layer "In2.Cu")
		(net "M_I_CPU0_SA_DQ<10>")
	)
	(segment
		(start 398.960848 -217.821002)
		(end 398.960848 -217.592402)
		(width 0.14478)
		(layer "In2.Cu")
		(net "M_I_CPU0_SA_DQ<10>")
	)
	(segment
		(start 400.761708 -217.052398)
		(end 400.930618 -216.883488)
		(width 0.14478)
		(layer "In2.Cu")
		(net "M_I_CPU0_SA_DQ<10>")
	)
	(segment
		(start 425.305474 -206.727552)
		(end 425.536106 -206.727552)
		(width 0.14478)
		(layer "In2.Cu")
		(net "M_I_CPU0_SA_DQ<10>")
	)
	(segment
		(start 399.741136 -216.812114)
		(end 399.90268 -216.65057)
		(width 0.14478)
		(layer "In2.Cu")
		(net "M_I_CPU0_SA_DQ<10>")
	)
	(segment
		(start 391.48766 -227.961698)
		(end 391.526776 -227.938838)
		(width 0.0889)
		(layer "In2.Cu")
		(net "M_I_CPU0_SA_DQ<10>")
	)
	(segment
		(start 399.75282 -217.832686)
		(end 399.98142 -217.832686)
		(width 0.14478)
		(layer "In2.Cu")
		(net "M_I_CPU0_SA_DQ<10>")
	)
	(segment
		(start 398.960848 -217.592402)
		(end 399.122392 -217.430858)
		(width 0.14478)
		(layer "In2.Cu")
		(net "M_I_CPU0_SA_DQ<10>")
	)
	(segment
		(start 424.355006 -207.110076)
		(end 424.749214 -207.504284)
		(width 0.14478)
		(layer "In2.Cu")
		(net "M_I_CPU0_SA_DQ<10>")
	)
	(segment
		(start 390.514332 -229.601268)
		(end 390.54786 -229.58171)
		(width 0.0889)
		(layer "In2.Cu")
		(net "M_I_CPU0_SA_DQ<10>")
	)
	(segment
		(start 394.30833 -223.100646)
		(end 395.225016 -222.58909)
		(width 0.0889)
		(layer "In2.Cu")
		(net "M_I_CPU0_SA_DQ<10>")
	)
	(segment
		(start 415.08934 -207.110076)
		(end 417.88207 -207.110076)
		(width 0.14478)
		(layer "In2.Cu")
		(net "M_I_CPU0_SA_DQ<10>")
	)
	(segment
		(start 391.926064 -227.16998)
		(end 391.957814 -227.151692)
		(width 0.0889)
		(layer "In2.Cu")
		(net "M_I_CPU0_SA_DQ<10>")
	)
	(segment
		(start 382.557782 -230.391716)
		(end 382.566164 -230.38689)
		(width 0.0889)
		(layer "In2.Cu")
		(net "M_I_CPU0_SA_DQ<10>")
	)
	(segment
		(start 399.362676 -218.45143)
		(end 399.362676 -218.22283)
		(width 0.14478)
		(layer "In2.Cu")
		(net "M_I_CPU0_SA_DQ<10>")
	)
	(segment
		(start 417.88207 -207.110076)
		(end 418.732208 -207.960214)
		(width 0.14478)
		(layer "In2.Cu")
		(net "M_I_CPU0_SA_DQ<10>")
	)
	(segment
		(start 426.417994 -206.727552)
		(end 426.648626 -206.727552)
		(width 0.14478)
		(layer "In2.Cu")
		(net "M_I_CPU0_SA_DQ<10>")
	)
	(segment
		(start 414.239202 -207.960214)
		(end 415.08934 -207.110076)
		(width 0.14478)
		(layer "In2.Cu")
		(net "M_I_CPU0_SA_DQ<10>")
	)
	(segment
		(start 408.555444 -207.960214)
		(end 414.239202 -207.960214)
		(width 0.14478)
		(layer "In2.Cu")
		(net "M_I_CPU0_SA_DQ<10>")
	)
	(segment
		(start 399.122392 -217.430858)
		(end 399.350992 -217.430858)
		(width 0.14478)
		(layer "In2.Cu")
		(net "M_I_CPU0_SA_DQ<10>")
	)
	(segment
		(start 425.861734 -207.504284)
		(end 426.092366 -207.504284)
		(width 0.14478)
		(layer "In2.Cu")
		(net "M_I_CPU0_SA_DQ<10>")
	)
	(segment
		(start 392.866118 -225.549968)
		(end 392.897868 -225.53168)
		(width 0.0889)
		(layer "In2.Cu")
		(net "M_I_CPU0_SA_DQ<10>")
	)
	(segment
		(start 399.741136 -217.040714)
		(end 399.741136 -216.812114)
		(width 0.14478)
		(layer "In2.Cu")
		(net "M_I_CPU0_SA_DQ<10>")
	)
	(segment
		(start 387.257798 -230.391716)
		(end 387.26618 -230.38689)
		(width 0.0889)
		(layer "In2.Cu")
		(net "M_I_CPU0_SA_DQ<10>")
	)
	(segment
		(start 393.837668 -223.911668)
		(end 393.876784 -223.888808)
		(width 0.0889)
		(layer "In2.Cu")
		(net "M_I_CPU0_SA_DQ<10>")
	)
	(segment
		(start 421.580564 -207.960214)
		(end 422.430702 -207.110076)
		(width 0.14478)
		(layer "In2.Cu")
		(net "M_I_CPU0_SA_DQ<10>")
	)
	(segment
		(start 391.01776 -228.771704)
		(end 391.056876 -228.748844)
		(width 0.0889)
		(layer "In2.Cu")
		(net "M_I_CPU0_SA_DQ<10>")
	)
	(segment
		(start 392.427714 -226.341686)
		(end 392.46683 -226.318826)
		(width 0.0889)
		(layer "In2.Cu")
		(net "M_I_CPU0_SA_DQ<10>")
	)
	(segment
		(start 381.983488 -230.38689)
		(end 381.99187 -230.391716)
		(width 0.0889)
		(layer "In2.Cu")
		(net "M_I_CPU0_SA_DQ<10>")
	)
	(segment
		(start 425.69892 -207.34147)
		(end 425.861734 -207.504284)
		(width 0.14478)
		(layer "In2.Cu")
		(net "M_I_CPU0_SA_DQ<10>")
	)
	(segment
		(start 393.329668 -224.743264)
		(end 393.36853 -224.720658)
		(width 0.0889)
		(layer "In2.Cu")
		(net "M_I_CPU0_SA_DQ<10>")
	)
	(segment
		(start 399.90268 -216.65057)
		(end 400.13128 -216.65057)
		(width 0.14478)
		(layer "In2.Cu")
		(net "M_I_CPU0_SA_DQ<10>")
	)
	(segment
		(start 400.142964 -217.671142)
		(end 400.142964 -217.442542)
		(width 0.14478)
		(layer "In2.Cu")
		(net "M_I_CPU0_SA_DQ<10>")
	)
	(segment
		(start 383.497836 -230.391716)
		(end 383.506218 -230.38689)
		(width 0.0889)
		(layer "In2.Cu")
		(net "M_I_CPU0_SA_DQ<10>")
	)
	(segment
		(start 400.930618 -215.58504)
		(end 408.555444 -207.960214)
		(width 0.14478)
		(layer "In2.Cu")
		(net "M_I_CPU0_SA_DQ<10>")
	)
	(segment
		(start 377.857766 -230.391716)
		(end 377.866148 -230.38689)
		(width 0.0889)
		(layer "In2.Cu")
		(net "M_I_CPU0_SA_DQ<10>")
	)
	(segment
		(start 425.14266 -207.34147)
		(end 425.14266 -206.890366)
		(width 0.14478)
		(layer "In2.Cu")
		(net "M_I_CPU0_SA_DQ<10>")
	)
	(segment
		(start 426.25518 -207.34147)
		(end 426.25518 -206.890366)
		(width 0.14478)
		(layer "In2.Cu")
		(net "M_I_CPU0_SA_DQ<10>")
	)
	(segment
		(start 378.79782 -230.391716)
		(end 378.806202 -230.38689)
		(width 0.0889)
		(layer "In2.Cu")
		(net "M_I_CPU0_SA_DQ<10>")
	)
	(segment
		(start 393.36853 -224.720658)
		(end 393.412726 -224.695004)
		(width 0.0889)
		(layer "In2.Cu")
		(net "M_I_CPU0_SA_DQ<10>")
	)
	(segment
		(start 399.98142 -217.832686)
		(end 400.142964 -217.671142)
		(width 0.14478)
		(layer "In2.Cu")
		(net "M_I_CPU0_SA_DQ<10>")
	)
	(segment
		(start 426.25518 -206.890366)
		(end 426.417994 -206.727552)
		(width 0.14478)
		(layer "In2.Cu")
		(net "M_I_CPU0_SA_DQ<10>")
	)
	(segment
		(start 424.749214 -207.504284)
		(end 424.979846 -207.504284)
		(width 0.14478)
		(layer "In2.Cu")
		(net "M_I_CPU0_SA_DQ<10>")
	)
	(segment
		(start 425.69892 -206.890366)
		(end 425.69892 -207.34147)
		(width 0.14478)
		(layer "In2.Cu")
		(net "M_I_CPU0_SA_DQ<10>")
	)
	(segment
		(start 386.683504 -230.38689)
		(end 386.691886 -230.391716)
		(width 0.0889)
		(layer "In2.Cu")
		(net "M_I_CPU0_SA_DQ<10>")
	)
	(segment
		(start 391.957814 -227.151692)
		(end 391.99693 -227.128832)
		(width 0.0889)
		(layer "In2.Cu")
		(net "M_I_CPU0_SA_DQ<10>")
	)
	(segment
		(start 385.74345 -230.38689)
		(end 385.751832 -230.391716)
		(width 0.0889)
		(layer "In2.Cu")
		(net "M_I_CPU0_SA_DQ<10>")
	)
	(segment
		(start 425.14266 -206.890366)
		(end 425.305474 -206.727552)
		(width 0.14478)
		(layer "In2.Cu")
		(net "M_I_CPU0_SA_DQ<10>")
	)
	(segment
		(start 392.897868 -225.53168)
		(end 392.942064 -225.506026)
		(width 0.0889)
		(layer "In2.Cu")
		(net "M_I_CPU0_SA_DQ<10>")
	)
	(segment
		(start 388.197852 -230.391716)
		(end 388.206234 -230.38689)
		(width 0.0889)
		(layer "In2.Cu")
		(net "M_I_CPU0_SA_DQ<10>")
	)
	(segment
		(start 390.54786 -229.58171)
		(end 390.584182 -229.560628)
		(width 0.0889)
		(layer "In2.Cu")
		(net "M_I_CPU0_SA_DQ<10>")
	)
	(segment
		(start 394.282676 -223.115378)
		(end 394.30833 -223.100646)
		(width 0.0889)
		(layer "In2.Cu")
		(net "M_I_CPU0_SA_DQ<10>")
	)
	(segment
		(start 381.043434 -230.38689)
		(end 381.051816 -230.391716)
		(width 0.0889)
		(layer "In2.Cu")
		(net "M_I_CPU0_SA_DQ<10>")
	)
	(segment
		(start 425.536106 -206.727552)
		(end 425.69892 -206.890366)
		(width 0.14478)
		(layer "In2.Cu")
		(net "M_I_CPU0_SA_DQ<10>")
	)
	(segment
		(start 377.258834 -230.448866)
		(end 377.354846 -230.423466)
		(width 0.0889)
		(layer "In2.Cu")
		(net "M_I_CPU0_SA_DQ<10>")
	)
	(segment
		(start 390.077706 -230.391716)
		(end 390.114282 -230.37038)
		(width 0.0889)
		(layer "In2.Cu")
		(net "M_I_CPU0_SA_DQ<10>")
	)
	(segment
		(start 399.362676 -218.22283)
		(end 398.960848 -217.821002)
		(width 0.14478)
		(layer "In2.Cu")
		(net "M_I_CPU0_SA_DQ<10>")
	)
	(segment
		(start 400.13128 -216.65057)
		(end 400.533108 -217.052398)
		(width 0.14478)
		(layer "In2.Cu")
		(net "M_I_CPU0_SA_DQ<10>")
	)
	(segment
		(start 400.142964 -217.442542)
		(end 399.741136 -217.040714)
		(width 0.14478)
		(layer "In2.Cu")
		(net "M_I_CPU0_SA_DQ<10>")
	)
	(segment
		(start 391.45718 -227.979478)
		(end 391.48766 -227.961698)
		(width 0.0889)
		(layer "In2.Cu")
		(net "M_I_CPU0_SA_DQ<10>")
	)
	(segment
		(start 426.648626 -206.727552)
		(end 427.456092 -207.535018)
		(width 0.14478)
		(layer "In2.Cu")
		(net "M_I_CPU0_SA_DQ<10>")
	)
	(segment
		(start 426.092366 -207.504284)
		(end 426.25518 -207.34147)
		(width 0.14478)
		(layer "In2.Cu")
		(net "M_I_CPU0_SA_DQ<10>")
	)
	(segment
		(start 400.930618 -216.883488)
		(end 400.930618 -215.58504)
		(width 0.14478)
		(layer "In2.Cu")
		(net "M_I_CPU0_SA_DQ<10>")
	)
	(segment
		(start 390.98601 -228.789992)
		(end 391.01776 -228.771704)
		(width 0.0889)
		(layer "In2.Cu")
		(net "M_I_CPU0_SA_DQ<10>")
	)
	(segment
		(start 424.979846 -207.504284)
		(end 425.14266 -207.34147)
		(width 0.14478)
		(layer "In2.Cu")
		(net "M_I_CPU0_SA_DQ<10>")
	)
	(segment
		(start 400.533108 -217.052398)
		(end 400.761708 -217.052398)
		(width 0.14478)
		(layer "In2.Cu")
		(net "M_I_CPU0_SA_DQ<10>")
	)
	(segment
		(start 377.10491 -230.714296)
		(end 377.258834 -230.448866)
		(width 0.0889)
		(layer "In2.Cu")
		(net "M_I_CPU0_SA_DQ<10>")
	)
	(segment
		(start 395.225016 -222.58909)
		(end 399.362676 -218.45143)
		(width 0.14478)
		(layer "In2.Cu")
		(net "M_I_CPU0_SA_DQ<10>")
	)
	(segment
		(start 393.807188 -223.929448)
		(end 393.837668 -223.911668)
		(width 0.0889)
		(layer "In2.Cu")
		(net "M_I_CPU0_SA_DQ<10>")
	)
	(segment
		(start 418.732208 -207.960214)
		(end 421.580564 -207.960214)
		(width 0.14478)
		(layer "In2.Cu")
		(net "M_I_CPU0_SA_DQ<10>")
	)
	(arc
		(start 380.111762 -230.391716)
		(mid 380.394718 -230.467859)
		(end 380.677674 -230.391716)
		(width 0.0889)
		(layer "In2.Cu")
		(net "M_I_CPU0_SA_DQ<10>")
	)
	(arc
		(start 393.650216 -224.234248)
		(mid 393.691765 -224.062826)
		(end 393.807188 -223.929448)
		(width 0.0889)
		(layer "In2.Cu")
		(net "M_I_CPU0_SA_DQ<10>")
	)
	(arc
		(start 384.43789 -230.391716)
		(mid 384.624834 -230.341461)
		(end 384.811778 -230.391716)
		(width 0.0889)
		(layer "In2.Cu")
		(net "M_I_CPU0_SA_DQ<10>")
	)
	(arc
		(start 381.99187 -230.391716)
		(mid 382.274826 -230.467859)
		(end 382.557782 -230.391716)
		(width 0.0889)
		(layer "In2.Cu")
		(net "M_I_CPU0_SA_DQ<10>")
	)
	(arc
		(start 386.317744 -230.391716)
		(mid 386.499995 -230.341366)
		(end 386.683504 -230.38689)
		(width 0.0889)
		(layer "In2.Cu")
		(net "M_I_CPU0_SA_DQ<10>")
	)
	(arc
		(start 381.617728 -230.391716)
		(mid 381.799979 -230.341366)
		(end 381.983488 -230.38689)
		(width 0.0889)
		(layer "In2.Cu")
		(net "M_I_CPU0_SA_DQ<10>")
	)
	(arc
		(start 378.806202 -230.38689)
		(mid 378.98971 -230.341396)
		(end 379.171962 -230.391716)
		(width 0.0889)
		(layer "In2.Cu")
		(net "M_I_CPU0_SA_DQ<10>")
	)
	(arc
		(start 385.751832 -230.391716)
		(mid 386.034788 -230.467859)
		(end 386.317744 -230.391716)
		(width 0.0889)
		(layer "In2.Cu")
		(net "M_I_CPU0_SA_DQ<10>")
	)
	(arc
		(start 383.506218 -230.38689)
		(mid 383.689726 -230.341396)
		(end 383.871978 -230.391716)
		(width 0.0889)
		(layer "In2.Cu")
		(net "M_I_CPU0_SA_DQ<10>")
	)
	(arc
		(start 393.876784 -223.888808)
		(mid 394.055597 -223.686458)
		(end 394.120116 -223.424242)
		(width 0.0889)
		(layer "In2.Cu")
		(net "M_I_CPU0_SA_DQ<10>")
	)
	(arc
		(start 379.171962 -230.391716)
		(mid 379.454918 -230.467859)
		(end 379.737874 -230.391716)
		(width 0.0889)
		(layer "In2.Cu")
		(net "M_I_CPU0_SA_DQ<10>")
	)
	(arc
		(start 390.114282 -230.37038)
		(mid 390.294934 -230.167635)
		(end 390.360154 -229.904036)
		(width 0.0889)
		(layer "In2.Cu")
		(net "M_I_CPU0_SA_DQ<10>")
	)
	(arc
		(start 392.710162 -225.85426)
		(mid 392.751417 -225.683289)
		(end 392.866118 -225.549968)
		(width 0.0889)
		(layer "In2.Cu")
		(net "M_I_CPU0_SA_DQ<10>")
	)
	(arc
		(start 391.056876 -228.748844)
		(mid 391.235689 -228.546494)
		(end 391.300208 -228.284278)
		(width 0.0889)
		(layer "In2.Cu")
		(net "M_I_CPU0_SA_DQ<10>")
	)
	(arc
		(start 390.584182 -229.560628)
		(mid 390.764834 -229.357883)
		(end 390.830054 -229.094284)
		(width 0.0889)
		(layer "In2.Cu")
		(net "M_I_CPU0_SA_DQ<10>")
	)
	(arc
		(start 383.871978 -230.391716)
		(mid 384.154934 -230.467859)
		(end 384.43789 -230.391716)
		(width 0.0889)
		(layer "In2.Cu")
		(net "M_I_CPU0_SA_DQ<10>")
	)
	(arc
		(start 378.231908 -230.391716)
		(mid 378.514864 -230.467859)
		(end 378.79782 -230.391716)
		(width 0.0889)
		(layer "In2.Cu")
		(net "M_I_CPU0_SA_DQ<10>")
	)
	(arc
		(start 387.63194 -230.391716)
		(mid 387.914896 -230.467859)
		(end 388.197852 -230.391716)
		(width 0.0889)
		(layer "In2.Cu")
		(net "M_I_CPU0_SA_DQ<10>")
	)
	(arc
		(start 388.206234 -230.38689)
		(mid 388.389742 -230.341396)
		(end 388.571994 -230.391716)
		(width 0.0889)
		(layer "In2.Cu")
		(net "M_I_CPU0_SA_DQ<10>")
	)
	(arc
		(start 386.691886 -230.391716)
		(mid 386.974842 -230.467859)
		(end 387.257798 -230.391716)
		(width 0.0889)
		(layer "In2.Cu")
		(net "M_I_CPU0_SA_DQ<10>")
	)
	(arc
		(start 391.770108 -227.474272)
		(mid 391.811363 -227.303301)
		(end 391.926064 -227.16998)
		(width 0.0889)
		(layer "In2.Cu")
		(net "M_I_CPU0_SA_DQ<10>")
	)
	(arc
		(start 389.511794 -230.391716)
		(mid 389.79475 -230.467859)
		(end 390.077706 -230.391716)
		(width 0.0889)
		(layer "In2.Cu")
		(net "M_I_CPU0_SA_DQ<10>")
	)
	(arc
		(start 385.37769 -230.391716)
		(mid 385.559941 -230.341366)
		(end 385.74345 -230.38689)
		(width 0.0889)
		(layer "In2.Cu")
		(net "M_I_CPU0_SA_DQ<10>")
	)
	(arc
		(start 384.811778 -230.391716)
		(mid 385.094734 -230.467859)
		(end 385.37769 -230.391716)
		(width 0.0889)
		(layer "In2.Cu")
		(net "M_I_CPU0_SA_DQ<10>")
	)
	(arc
		(start 393.180824 -225.042984)
		(mid 393.219977 -224.875609)
		(end 393.329668 -224.743264)
		(width 0.0889)
		(layer "In2.Cu")
		(net "M_I_CPU0_SA_DQ<10>")
	)
	(arc
		(start 391.99693 -227.128832)
		(mid 392.175743 -226.926482)
		(end 392.240262 -226.664266)
		(width 0.0889)
		(layer "In2.Cu")
		(net "M_I_CPU0_SA_DQ<10>")
	)
	(arc
		(start 387.26618 -230.38689)
		(mid 387.449688 -230.341396)
		(end 387.63194 -230.391716)
		(width 0.0889)
		(layer "In2.Cu")
		(net "M_I_CPU0_SA_DQ<10>")
	)
	(arc
		(start 377.354846 -230.423466)
		(mid 377.610054 -230.466923)
		(end 377.857766 -230.391716)
		(width 0.0889)
		(layer "In2.Cu")
		(net "M_I_CPU0_SA_DQ<10>")
	)
	(arc
		(start 382.566164 -230.38689)
		(mid 382.749672 -230.341396)
		(end 382.931924 -230.391716)
		(width 0.0889)
		(layer "In2.Cu")
		(net "M_I_CPU0_SA_DQ<10>")
	)
	(arc
		(start 391.300208 -228.284278)
		(mid 391.341757 -228.112856)
		(end 391.45718 -227.979478)
		(width 0.0889)
		(layer "In2.Cu")
		(net "M_I_CPU0_SA_DQ<10>")
	)
	(arc
		(start 388.571994 -230.391716)
		(mid 388.85495 -230.467859)
		(end 389.137906 -230.391716)
		(width 0.0889)
		(layer "In2.Cu")
		(net "M_I_CPU0_SA_DQ<10>")
	)
	(arc
		(start 382.931924 -230.391716)
		(mid 383.21488 -230.467859)
		(end 383.497836 -230.391716)
		(width 0.0889)
		(layer "In2.Cu")
		(net "M_I_CPU0_SA_DQ<10>")
	)
	(arc
		(start 394.120116 -223.424242)
		(mid 394.163241 -223.249732)
		(end 394.282676 -223.115378)
		(width 0.0889)
		(layer "In2.Cu")
		(net "M_I_CPU0_SA_DQ<10>")
	)
	(arc
		(start 381.051816 -230.391716)
		(mid 381.334772 -230.467859)
		(end 381.617728 -230.391716)
		(width 0.0889)
		(layer "In2.Cu")
		(net "M_I_CPU0_SA_DQ<10>")
	)
	(arc
		(start 380.677674 -230.391716)
		(mid 380.859925 -230.341366)
		(end 381.043434 -230.38689)
		(width 0.0889)
		(layer "In2.Cu")
		(net "M_I_CPU0_SA_DQ<10>")
	)
	(arc
		(start 390.830054 -229.094284)
		(mid 390.871309 -228.923313)
		(end 390.98601 -228.789992)
		(width 0.0889)
		(layer "In2.Cu")
		(net "M_I_CPU0_SA_DQ<10>")
	)
	(arc
		(start 392.942064 -225.506026)
		(mid 393.117897 -225.303614)
		(end 393.180824 -225.042984)
		(width 0.0889)
		(layer "In2.Cu")
		(net "M_I_CPU0_SA_DQ<10>")
	)
	(arc
		(start 390.360154 -229.904036)
		(mid 390.400916 -229.734152)
		(end 390.514332 -229.601268)
		(width 0.0889)
		(layer "In2.Cu")
		(net "M_I_CPU0_SA_DQ<10>")
	)
	(arc
		(start 389.137906 -230.391716)
		(mid 389.32485 -230.341461)
		(end 389.511794 -230.391716)
		(width 0.0889)
		(layer "In2.Cu")
		(net "M_I_CPU0_SA_DQ<10>")
	)
	(arc
		(start 393.412726 -224.695004)
		(mid 393.587364 -224.493433)
		(end 393.650216 -224.234248)
		(width 0.0889)
		(layer "In2.Cu")
		(net "M_I_CPU0_SA_DQ<10>")
	)
	(arc
		(start 379.737874 -230.391716)
		(mid 379.924818 -230.341461)
		(end 380.111762 -230.391716)
		(width 0.0889)
		(layer "In2.Cu")
		(net "M_I_CPU0_SA_DQ<10>")
	)
	(arc
		(start 392.240262 -226.664266)
		(mid 392.281811 -226.492844)
		(end 392.397234 -226.359466)
		(width 0.0889)
		(layer "In2.Cu")
		(net "M_I_CPU0_SA_DQ<10>")
	)
	(arc
		(start 392.46683 -226.318826)
		(mid 392.645643 -226.116476)
		(end 392.710162 -225.85426)
		(width 0.0889)
		(layer "In2.Cu")
		(net "M_I_CPU0_SA_DQ<10>")
	)
	(arc
		(start 391.526776 -227.938838)
		(mid 391.705589 -227.736488)
		(end 391.770108 -227.474272)
		(width 0.0889)
		(layer "In2.Cu")
		(net "M_I_CPU0_SA_DQ<10>")
	)
	(arc
		(start 377.866148 -230.38689)
		(mid 378.049656 -230.341396)
		(end 378.231908 -230.391716)
		(width 0.0889)
		(layer "In2.Cu")
		(net "M_I_CPU0_SA_DQ<10>")
	)
	(segment
		(start 377.107958 -225.310192)
		(end 377.57481 -225.044254)
		(width 0.10668)
		(layer "F.Cu")
		(net "M_I_CPU0_SA_DQ<0>")
	)
	(segment
		(start 393.457938 -213.878668)
		(end 393.457938 -212.099144)
		(width 0.14478)
		(layer "In2.Cu")
		(net "M_I_CPU0_SA_DQ<0>")
	)
	(segment
		(start 388.57174 -222.936816)
		(end 388.60349 -222.918528)
		(width 0.0889)
		(layer "In2.Cu")
		(net "M_I_CPU0_SA_DQ<0>")
	)
	(segment
		(start 431.131218 -196.910198)
		(end 431.55616 -197.33514)
		(width 0.14478)
		(layer "In2.Cu")
		(net "M_I_CPU0_SA_DQ<0>")
	)
	(segment
		(start 422.851834 -196.910198)
		(end 431.131218 -196.910198)
		(width 0.14478)
		(layer "In2.Cu")
		(net "M_I_CPU0_SA_DQ<0>")
	)
	(segment
		(start 413.980884 -196.910198)
		(end 417.452048 -196.910198)
		(width 0.14478)
		(layer "In2.Cu")
		(net "M_I_CPU0_SA_DQ<0>")
	)
	(segment
		(start 383.393442 -225.37166)
		(end 383.401824 -225.366834)
		(width 0.0889)
		(layer "In2.Cu")
		(net "M_I_CPU0_SA_DQ<0>")
	)
	(segment
		(start 384.90779 -225.366834)
		(end 384.916172 -225.37166)
		(width 0.0889)
		(layer "In2.Cu")
		(net "M_I_CPU0_SA_DQ<0>")
	)
	(segment
		(start 377.57481 -225.044254)
		(end 377.420886 -225.309684)
		(width 0.0889)
		(layer "In2.Cu")
		(net "M_I_CPU0_SA_DQ<0>")
	)
	(segment
		(start 419.50386 -197.760082)
		(end 420.800022 -197.760082)
		(width 0.14478)
		(layer "In2.Cu")
		(net "M_I_CPU0_SA_DQ<0>")
	)
	(segment
		(start 388.063994 -223.768666)
		(end 388.10184 -223.746822)
		(width 0.0889)
		(layer "In2.Cu")
		(net "M_I_CPU0_SA_DQ<0>")
	)
	(segment
		(start 381.147828 -225.366834)
		(end 381.15621 -225.37166)
		(width 0.0889)
		(layer "In2.Cu")
		(net "M_I_CPU0_SA_DQ<0>")
	)
	(segment
		(start 387.63194 -224.556828)
		(end 387.66242 -224.539048)
		(width 0.0889)
		(layer "In2.Cu")
		(net "M_I_CPU0_SA_DQ<0>")
	)
	(segment
		(start 387.592824 -224.579688)
		(end 387.63194 -224.556828)
		(width 0.0889)
		(layer "In2.Cu")
		(net "M_I_CPU0_SA_DQ<0>")
	)
	(segment
		(start 387.161786 -225.366834)
		(end 387.193536 -225.348546)
		(width 0.0889)
		(layer "In2.Cu")
		(net "M_I_CPU0_SA_DQ<0>")
	)
	(segment
		(start 389.229092 -221.80423)
		(end 389.117078 -221.17431)
		(width 0.0889)
		(layer "In2.Cu")
		(net "M_I_CPU0_SA_DQ<0>")
	)
	(segment
		(start 389.117078 -218.219528)
		(end 393.457938 -213.878668)
		(width 0.14478)
		(layer "In2.Cu")
		(net "M_I_CPU0_SA_DQ<0>")
	)
	(segment
		(start 389.004048 -222.148654)
		(end 389.04164 -222.12681)
		(width 0.0889)
		(layer "In2.Cu")
		(net "M_I_CPU0_SA_DQ<0>")
	)
	(segment
		(start 413.131 -197.760082)
		(end 413.980884 -196.910198)
		(width 0.14478)
		(layer "In2.Cu")
		(net "M_I_CPU0_SA_DQ<0>")
	)
	(segment
		(start 388.10184 -223.746822)
		(end 388.131304 -223.729804)
		(width 0.0889)
		(layer "In2.Cu")
		(net "M_I_CPU0_SA_DQ<0>")
	)
	(segment
		(start 385.847844 -225.366834)
		(end 385.856226 -225.37166)
		(width 0.0889)
		(layer "In2.Cu")
		(net "M_I_CPU0_SA_DQ<0>")
	)
	(segment
		(start 407.797 -197.760082)
		(end 413.131 -197.760082)
		(width 0.14478)
		(layer "In2.Cu")
		(net "M_I_CPU0_SA_DQ<0>")
	)
	(segment
		(start 380.207774 -225.366834)
		(end 380.216156 -225.37166)
		(width 0.0889)
		(layer "In2.Cu")
		(net "M_I_CPU0_SA_DQ<0>")
	)
	(segment
		(start 378.693426 -225.37166)
		(end 378.701808 -225.366834)
		(width 0.0889)
		(layer "In2.Cu")
		(net "M_I_CPU0_SA_DQ<0>")
	)
	(segment
		(start 388.533894 -222.95866)
		(end 388.57174 -222.936816)
		(width 0.0889)
		(layer "In2.Cu")
		(net "M_I_CPU0_SA_DQ<0>")
	)
	(segment
		(start 384.333496 -225.37166)
		(end 384.341878 -225.366834)
		(width 0.0889)
		(layer "In2.Cu")
		(net "M_I_CPU0_SA_DQ<0>")
	)
	(segment
		(start 377.420886 -225.309684)
		(end 377.443238 -225.392996)
		(width 0.0889)
		(layer "In2.Cu")
		(net "M_I_CPU0_SA_DQ<0>")
	)
	(segment
		(start 379.63348 -225.37166)
		(end 379.641862 -225.366834)
		(width 0.0889)
		(layer "In2.Cu")
		(net "M_I_CPU0_SA_DQ<0>")
	)
	(segment
		(start 389.04164 -222.12681)
		(end 389.07212 -222.10903)
		(width 0.0889)
		(layer "In2.Cu")
		(net "M_I_CPU0_SA_DQ<0>")
	)
	(segment
		(start 393.457938 -212.099144)
		(end 407.797 -197.760082)
		(width 0.14478)
		(layer "In2.Cu")
		(net "M_I_CPU0_SA_DQ<0>")
	)
	(segment
		(start 420.800022 -197.760082)
		(end 422.851834 -196.910198)
		(width 0.14478)
		(layer "In2.Cu")
		(net "M_I_CPU0_SA_DQ<0>")
	)
	(segment
		(start 417.452048 -196.910198)
		(end 419.50386 -197.760082)
		(width 0.14478)
		(layer "In2.Cu")
		(net "M_I_CPU0_SA_DQ<0>")
	)
	(segment
		(start 389.117078 -221.17431)
		(end 389.117078 -218.219528)
		(width 0.14478)
		(layer "In2.Cu")
		(net "M_I_CPU0_SA_DQ<0>")
	)
	(arc
		(start 381.52197 -225.366834)
		(mid 381.804926 -225.290657)
		(end 382.087882 -225.366834)
		(width 0.0889)
		(layer "In2.Cu")
		(net "M_I_CPU0_SA_DQ<0>")
	)
	(arc
		(start 387.66242 -224.539048)
		(mid 387.777847 -224.405672)
		(end 387.819392 -224.234248)
		(width 0.0889)
		(layer "In2.Cu")
		(net "M_I_CPU0_SA_DQ<0>")
	)
	(arc
		(start 389.07212 -222.10903)
		(mid 389.187547 -221.975654)
		(end 389.229092 -221.80423)
		(width 0.0889)
		(layer "In2.Cu")
		(net "M_I_CPU0_SA_DQ<0>")
	)
	(arc
		(start 388.759446 -222.614236)
		(mid 388.824318 -222.351273)
		(end 389.004048 -222.148654)
		(width 0.0889)
		(layer "In2.Cu")
		(net "M_I_CPU0_SA_DQ<0>")
	)
	(arc
		(start 381.15621 -225.37166)
		(mid 381.339718 -225.417154)
		(end 381.52197 -225.366834)
		(width 0.0889)
		(layer "In2.Cu")
		(net "M_I_CPU0_SA_DQ<0>")
	)
	(arc
		(start 384.341878 -225.366834)
		(mid 384.624834 -225.290657)
		(end 384.90779 -225.366834)
		(width 0.0889)
		(layer "In2.Cu")
		(net "M_I_CPU0_SA_DQ<0>")
	)
	(arc
		(start 385.281932 -225.366834)
		(mid 385.564888 -225.290657)
		(end 385.847844 -225.366834)
		(width 0.0889)
		(layer "In2.Cu")
		(net "M_I_CPU0_SA_DQ<0>")
	)
	(arc
		(start 387.193536 -225.348546)
		(mid 387.308212 -225.215212)
		(end 387.349492 -225.044254)
		(width 0.0889)
		(layer "In2.Cu")
		(net "M_I_CPU0_SA_DQ<0>")
	)
	(arc
		(start 377.443238 -225.392996)
		(mid 377.605427 -225.415731)
		(end 377.761754 -225.366834)
		(width 0.0889)
		(layer "In2.Cu")
		(net "M_I_CPU0_SA_DQ<0>")
	)
	(arc
		(start 383.967736 -225.366834)
		(mid 384.149987 -225.417184)
		(end 384.333496 -225.37166)
		(width 0.0889)
		(layer "In2.Cu")
		(net "M_I_CPU0_SA_DQ<0>")
	)
	(arc
		(start 387.819392 -224.234248)
		(mid 387.884264 -223.971285)
		(end 388.063994 -223.768666)
		(width 0.0889)
		(layer "In2.Cu")
		(net "M_I_CPU0_SA_DQ<0>")
	)
	(arc
		(start 388.131304 -223.729804)
		(mid 388.247485 -223.596245)
		(end 388.289292 -223.424242)
		(width 0.0889)
		(layer "In2.Cu")
		(net "M_I_CPU0_SA_DQ<0>")
	)
	(arc
		(start 387.349492 -225.044254)
		(mid 387.414007 -224.782035)
		(end 387.592824 -224.579688)
		(width 0.0889)
		(layer "In2.Cu")
		(net "M_I_CPU0_SA_DQ<0>")
	)
	(arc
		(start 377.761754 -225.366834)
		(mid 378.04471 -225.290657)
		(end 378.327666 -225.366834)
		(width 0.0889)
		(layer "In2.Cu")
		(net "M_I_CPU0_SA_DQ<0>")
	)
	(arc
		(start 386.787898 -225.366834)
		(mid 386.974842 -225.417089)
		(end 387.161786 -225.366834)
		(width 0.0889)
		(layer "In2.Cu")
		(net "M_I_CPU0_SA_DQ<0>")
	)
	(arc
		(start 378.701808 -225.366834)
		(mid 378.984764 -225.290657)
		(end 379.26772 -225.366834)
		(width 0.0889)
		(layer "In2.Cu")
		(net "M_I_CPU0_SA_DQ<0>")
	)
	(arc
		(start 378.327666 -225.366834)
		(mid 378.509917 -225.417184)
		(end 378.693426 -225.37166)
		(width 0.0889)
		(layer "In2.Cu")
		(net "M_I_CPU0_SA_DQ<0>")
	)
	(arc
		(start 388.289292 -223.424242)
		(mid 388.354164 -223.161279)
		(end 388.533894 -222.95866)
		(width 0.0889)
		(layer "In2.Cu")
		(net "M_I_CPU0_SA_DQ<0>")
	)
	(arc
		(start 385.856226 -225.37166)
		(mid 386.039734 -225.417154)
		(end 386.221986 -225.366834)
		(width 0.0889)
		(layer "In2.Cu")
		(net "M_I_CPU0_SA_DQ<0>")
	)
	(arc
		(start 386.221986 -225.366834)
		(mid 386.504942 -225.290657)
		(end 386.787898 -225.366834)
		(width 0.0889)
		(layer "In2.Cu")
		(net "M_I_CPU0_SA_DQ<0>")
	)
	(arc
		(start 380.216156 -225.37166)
		(mid 380.399664 -225.417154)
		(end 380.581916 -225.366834)
		(width 0.0889)
		(layer "In2.Cu")
		(net "M_I_CPU0_SA_DQ<0>")
	)
	(arc
		(start 379.641862 -225.366834)
		(mid 379.924818 -225.290657)
		(end 380.207774 -225.366834)
		(width 0.0889)
		(layer "In2.Cu")
		(net "M_I_CPU0_SA_DQ<0>")
	)
	(arc
		(start 384.916172 -225.37166)
		(mid 385.09968 -225.417154)
		(end 385.281932 -225.366834)
		(width 0.0889)
		(layer "In2.Cu")
		(net "M_I_CPU0_SA_DQ<0>")
	)
	(arc
		(start 388.60349 -222.918528)
		(mid 388.718166 -222.785194)
		(end 388.759446 -222.614236)
		(width 0.0889)
		(layer "In2.Cu")
		(net "M_I_CPU0_SA_DQ<0>")
	)
	(arc
		(start 382.46177 -225.366834)
		(mid 382.744726 -225.290657)
		(end 383.027682 -225.366834)
		(width 0.0889)
		(layer "In2.Cu")
		(net "M_I_CPU0_SA_DQ<0>")
	)
	(arc
		(start 379.26772 -225.366834)
		(mid 379.449971 -225.417184)
		(end 379.63348 -225.37166)
		(width 0.0889)
		(layer "In2.Cu")
		(net "M_I_CPU0_SA_DQ<0>")
	)
	(arc
		(start 383.401824 -225.366834)
		(mid 383.68478 -225.290657)
		(end 383.967736 -225.366834)
		(width 0.0889)
		(layer "In2.Cu")
		(net "M_I_CPU0_SA_DQ<0>")
	)
	(arc
		(start 383.027682 -225.366834)
		(mid 383.209933 -225.417184)
		(end 383.393442 -225.37166)
		(width 0.0889)
		(layer "In2.Cu")
		(net "M_I_CPU0_SA_DQ<0>")
	)
	(arc
		(start 382.087882 -225.366834)
		(mid 382.274826 -225.417089)
		(end 382.46177 -225.366834)
		(width 0.0889)
		(layer "In2.Cu")
		(net "M_I_CPU0_SA_DQ<0>")
	)
	(arc
		(start 380.581916 -225.366834)
		(mid 380.864872 -225.290657)
		(end 381.147828 -225.366834)
		(width 0.0889)
		(layer "In2.Cu")
		(net "M_I_CPU0_SA_DQ<0>")
	)
	(segment
		(start 375.698004 -252.040136)
		(end 376.164856 -251.774198)
		(width 0.10668)
		(layer "F.Cu")
		(net "M_I_CPU0_SA_CS_N<1>")
	)
	(segment
		(start 411.647894 -248.760234)
		(end 421.344344 -248.760234)
		(width 0.14478)
		(layer "In2.Cu")
		(net "M_I_CPU0_SA_CS_N<1>")
	)
	(segment
		(start 423.044366 -247.060212)
		(end 427.030896 -247.060212)
		(width 0.14478)
		(layer "In2.Cu")
		(net "M_I_CPU0_SA_CS_N<1>")
	)
	(segment
		(start 376.343418 -252.101604)
		(end 376.3518 -252.096778)
		(width 0.0889)
		(layer "In2.Cu")
		(net "M_I_CPU0_SA_CS_N<1>")
	)
	(segment
		(start 394.412978 -252.086872)
		(end 395.305534 -252.086872)
		(width 0.0889)
		(layer "In2.Cu")
		(net "M_I_CPU0_SA_CS_N<1>")
	)
	(segment
		(start 378.79782 -252.096778)
		(end 378.806202 -252.101604)
		(width 0.0889)
		(layer "In2.Cu")
		(net "M_I_CPU0_SA_CS_N<1>")
	)
	(segment
		(start 377.283472 -252.101604)
		(end 377.291854 -252.096778)
		(width 0.0889)
		(layer "In2.Cu")
		(net "M_I_CPU0_SA_CS_N<1>")
	)
	(segment
		(start 394.402818 -252.076712)
		(end 394.412978 -252.086872)
		(width 0.0889)
		(layer "In2.Cu")
		(net "M_I_CPU0_SA_CS_N<1>")
	)
	(segment
		(start 387.257798 -252.096778)
		(end 387.26618 -252.101604)
		(width 0.0889)
		(layer "In2.Cu")
		(net "M_I_CPU0_SA_CS_N<1>")
	)
	(segment
		(start 381.983488 -252.101604)
		(end 381.99187 -252.096778)
		(width 0.0889)
		(layer "In2.Cu")
		(net "M_I_CPU0_SA_CS_N<1>")
	)
	(segment
		(start 381.043434 -252.101604)
		(end 381.051816 -252.096778)
		(width 0.0889)
		(layer "In2.Cu")
		(net "M_I_CPU0_SA_CS_N<1>")
	)
	(segment
		(start 376.164856 -251.774198)
		(end 376.010678 -252.039628)
		(width 0.0889)
		(layer "In2.Cu")
		(net "M_I_CPU0_SA_CS_N<1>")
	)
	(segment
		(start 405.530558 -251.969016)
		(end 408.439112 -251.969016)
		(width 0.14478)
		(layer "In2.Cu")
		(net "M_I_CPU0_SA_CS_N<1>")
	)
	(segment
		(start 392.892534 -252.093222)
		(end 392.898122 -252.096524)
		(width 0.0889)
		(layer "In2.Cu")
		(net "M_I_CPU0_SA_CS_N<1>")
	)
	(segment
		(start 398.318736 -252.086872)
		(end 398.908016 -251.497592)
		(width 0.14478)
		(layer "In2.Cu")
		(net "M_I_CPU0_SA_CS_N<1>")
	)
	(segment
		(start 393.816078 -252.076712)
		(end 394.402818 -252.076712)
		(width 0.0889)
		(layer "In2.Cu")
		(net "M_I_CPU0_SA_CS_N<1>")
	)
	(segment
		(start 427.030896 -247.060212)
		(end 427.456092 -246.635016)
		(width 0.14478)
		(layer "In2.Cu")
		(net "M_I_CPU0_SA_CS_N<1>")
	)
	(segment
		(start 398.908016 -251.497592)
		(end 405.059134 -251.497592)
		(width 0.14478)
		(layer "In2.Cu")
		(net "M_I_CPU0_SA_CS_N<1>")
	)
	(segment
		(start 405.059134 -251.497592)
		(end 405.530558 -251.969016)
		(width 0.14478)
		(layer "In2.Cu")
		(net "M_I_CPU0_SA_CS_N<1>")
	)
	(segment
		(start 395.305534 -252.086872)
		(end 398.318736 -252.086872)
		(width 0.14478)
		(layer "In2.Cu")
		(net "M_I_CPU0_SA_CS_N<1>")
	)
	(segment
		(start 408.439112 -251.969016)
		(end 411.647894 -248.760234)
		(width 0.14478)
		(layer "In2.Cu")
		(net "M_I_CPU0_SA_CS_N<1>")
	)
	(segment
		(start 386.683504 -252.101604)
		(end 386.691886 -252.096778)
		(width 0.0889)
		(layer "In2.Cu")
		(net "M_I_CPU0_SA_CS_N<1>")
	)
	(segment
		(start 391.01776 -252.096778)
		(end 391.026142 -252.101604)
		(width 0.0889)
		(layer "In2.Cu")
		(net "M_I_CPU0_SA_CS_N<1>")
	)
	(segment
		(start 385.74345 -252.101604)
		(end 385.751832 -252.096778)
		(width 0.0889)
		(layer "In2.Cu")
		(net "M_I_CPU0_SA_CS_N<1>")
	)
	(segment
		(start 392.321034 -252.103636)
		(end 392.332718 -252.096778)
		(width 0.0889)
		(layer "In2.Cu")
		(net "M_I_CPU0_SA_CS_N<1>")
	)
	(segment
		(start 388.197852 -252.096778)
		(end 388.206234 -252.101604)
		(width 0.0889)
		(layer "In2.Cu")
		(net "M_I_CPU0_SA_CS_N<1>")
	)
	(segment
		(start 382.557782 -252.096778)
		(end 382.566164 -252.101604)
		(width 0.0889)
		(layer "In2.Cu")
		(net "M_I_CPU0_SA_CS_N<1>")
	)
	(segment
		(start 376.010678 -252.039628)
		(end 376.03303 -252.12294)
		(width 0.0889)
		(layer "In2.Cu")
		(net "M_I_CPU0_SA_CS_N<1>")
	)
	(segment
		(start 377.857766 -252.096778)
		(end 377.866148 -252.101604)
		(width 0.0889)
		(layer "In2.Cu")
		(net "M_I_CPU0_SA_CS_N<1>")
	)
	(segment
		(start 391.391902 -252.096778)
		(end 391.406634 -252.088142)
		(width 0.0889)
		(layer "In2.Cu")
		(net "M_I_CPU0_SA_CS_N<1>")
	)
	(segment
		(start 421.344344 -248.760234)
		(end 423.044366 -247.060212)
		(width 0.14478)
		(layer "In2.Cu")
		(net "M_I_CPU0_SA_CS_N<1>")
	)
	(segment
		(start 383.497836 -252.096778)
		(end 383.506218 -252.101604)
		(width 0.0889)
		(layer "In2.Cu")
		(net "M_I_CPU0_SA_CS_N<1>")
	)
	(segment
		(start 390.443466 -252.101604)
		(end 390.451848 -252.096778)
		(width 0.0889)
		(layer "In2.Cu")
		(net "M_I_CPU0_SA_CS_N<1>")
	)
	(arc
		(start 380.111762 -252.096778)
		(mid 380.394718 -252.020601)
		(end 380.677674 -252.096778)
		(width 0.0889)
		(layer "In2.Cu")
		(net "M_I_CPU0_SA_CS_N<1>")
	)
	(arc
		(start 376.3518 -252.096778)
		(mid 376.634756 -252.020601)
		(end 376.917712 -252.096778)
		(width 0.0889)
		(layer "In2.Cu")
		(net "M_I_CPU0_SA_CS_N<1>")
	)
	(arc
		(start 392.332718 -252.096778)
		(mid 392.612146 -252.020612)
		(end 392.892534 -252.093222)
		(width 0.0889)
		(layer "In2.Cu")
		(net "M_I_CPU0_SA_CS_N<1>")
	)
	(arc
		(start 390.077706 -252.096778)
		(mid 390.259957 -252.147128)
		(end 390.443466 -252.101604)
		(width 0.0889)
		(layer "In2.Cu")
		(net "M_I_CPU0_SA_CS_N<1>")
	)
	(arc
		(start 386.317744 -252.096778)
		(mid 386.499995 -252.147128)
		(end 386.683504 -252.101604)
		(width 0.0889)
		(layer "In2.Cu")
		(net "M_I_CPU0_SA_CS_N<1>")
	)
	(arc
		(start 383.871978 -252.096778)
		(mid 384.154934 -252.020601)
		(end 384.43789 -252.096778)
		(width 0.0889)
		(layer "In2.Cu")
		(net "M_I_CPU0_SA_CS_N<1>")
	)
	(arc
		(start 383.506218 -252.101604)
		(mid 383.689726 -252.147098)
		(end 383.871978 -252.096778)
		(width 0.0889)
		(layer "In2.Cu")
		(net "M_I_CPU0_SA_CS_N<1>")
	)
	(arc
		(start 391.026142 -252.101604)
		(mid 391.20965 -252.147098)
		(end 391.391902 -252.096778)
		(width 0.0889)
		(layer "In2.Cu")
		(net "M_I_CPU0_SA_CS_N<1>")
	)
	(arc
		(start 393.085066 -252.147324)
		(mid 393.173199 -252.135161)
		(end 393.254738 -252.099572)
		(width 0.0889)
		(layer "In2.Cu")
		(net "M_I_CPU0_SA_CS_N<1>")
	)
	(arc
		(start 385.751832 -252.096778)
		(mid 386.034788 -252.020601)
		(end 386.317744 -252.096778)
		(width 0.0889)
		(layer "In2.Cu")
		(net "M_I_CPU0_SA_CS_N<1>")
	)
	(arc
		(start 380.677674 -252.096778)
		(mid 380.859925 -252.147128)
		(end 381.043434 -252.101604)
		(width 0.0889)
		(layer "In2.Cu")
		(net "M_I_CPU0_SA_CS_N<1>")
	)
	(arc
		(start 391.406634 -252.088142)
		(mid 391.683617 -252.020338)
		(end 391.958322 -252.096778)
		(width 0.0889)
		(layer "In2.Cu")
		(net "M_I_CPU0_SA_CS_N<1>")
	)
	(arc
		(start 378.806202 -252.101604)
		(mid 378.98971 -252.147098)
		(end 379.171962 -252.096778)
		(width 0.0889)
		(layer "In2.Cu")
		(net "M_I_CPU0_SA_CS_N<1>")
	)
	(arc
		(start 384.811778 -252.096778)
		(mid 385.094734 -252.020601)
		(end 385.37769 -252.096778)
		(width 0.0889)
		(layer "In2.Cu")
		(net "M_I_CPU0_SA_CS_N<1>")
	)
	(arc
		(start 381.051816 -252.096778)
		(mid 381.334772 -252.020601)
		(end 381.617728 -252.096778)
		(width 0.0889)
		(layer "In2.Cu")
		(net "M_I_CPU0_SA_CS_N<1>")
	)
	(arc
		(start 378.231908 -252.096778)
		(mid 378.514864 -252.020601)
		(end 378.79782 -252.096778)
		(width 0.0889)
		(layer "In2.Cu")
		(net "M_I_CPU0_SA_CS_N<1>")
	)
	(arc
		(start 376.03303 -252.12294)
		(mid 376.19054 -252.146138)
		(end 376.343418 -252.101604)
		(width 0.0889)
		(layer "In2.Cu")
		(net "M_I_CPU0_SA_CS_N<1>")
	)
	(arc
		(start 388.571994 -252.096778)
		(mid 388.85495 -252.020601)
		(end 389.137906 -252.096778)
		(width 0.0889)
		(layer "In2.Cu")
		(net "M_I_CPU0_SA_CS_N<1>")
	)
	(arc
		(start 381.99187 -252.096778)
		(mid 382.274826 -252.020601)
		(end 382.557782 -252.096778)
		(width 0.0889)
		(layer "In2.Cu")
		(net "M_I_CPU0_SA_CS_N<1>")
	)
	(arc
		(start 382.566164 -252.101604)
		(mid 382.749672 -252.147098)
		(end 382.931924 -252.096778)
		(width 0.0889)
		(layer "In2.Cu")
		(net "M_I_CPU0_SA_CS_N<1>")
	)
	(arc
		(start 390.451848 -252.096778)
		(mid 390.734804 -252.020601)
		(end 391.01776 -252.096778)
		(width 0.0889)
		(layer "In2.Cu")
		(net "M_I_CPU0_SA_CS_N<1>")
	)
	(arc
		(start 377.291854 -252.096778)
		(mid 377.57481 -252.020601)
		(end 377.857766 -252.096778)
		(width 0.0889)
		(layer "In2.Cu")
		(net "M_I_CPU0_SA_CS_N<1>")
	)
	(arc
		(start 379.171962 -252.096778)
		(mid 379.454918 -252.020601)
		(end 379.737874 -252.096778)
		(width 0.0889)
		(layer "In2.Cu")
		(net "M_I_CPU0_SA_CS_N<1>")
	)
	(arc
		(start 389.137906 -252.096778)
		(mid 389.32485 -252.147033)
		(end 389.511794 -252.096778)
		(width 0.0889)
		(layer "In2.Cu")
		(net "M_I_CPU0_SA_CS_N<1>")
	)
	(arc
		(start 381.617728 -252.096778)
		(mid 381.799979 -252.147128)
		(end 381.983488 -252.101604)
		(width 0.0889)
		(layer "In2.Cu")
		(net "M_I_CPU0_SA_CS_N<1>")
	)
	(arc
		(start 387.63194 -252.096778)
		(mid 387.914896 -252.020601)
		(end 388.197852 -252.096778)
		(width 0.0889)
		(layer "In2.Cu")
		(net "M_I_CPU0_SA_CS_N<1>")
	)
	(arc
		(start 387.26618 -252.101604)
		(mid 387.449688 -252.147098)
		(end 387.63194 -252.096778)
		(width 0.0889)
		(layer "In2.Cu")
		(net "M_I_CPU0_SA_CS_N<1>")
	)
	(arc
		(start 376.917712 -252.096778)
		(mid 377.099963 -252.147128)
		(end 377.283472 -252.101604)
		(width 0.0889)
		(layer "In2.Cu")
		(net "M_I_CPU0_SA_CS_N<1>")
	)
	(arc
		(start 384.43789 -252.096778)
		(mid 384.624834 -252.147033)
		(end 384.811778 -252.096778)
		(width 0.0889)
		(layer "In2.Cu")
		(net "M_I_CPU0_SA_CS_N<1>")
	)
	(arc
		(start 385.37769 -252.096778)
		(mid 385.559941 -252.147128)
		(end 385.74345 -252.101604)
		(width 0.0889)
		(layer "In2.Cu")
		(net "M_I_CPU0_SA_CS_N<1>")
	)
	(arc
		(start 386.691886 -252.096778)
		(mid 386.974842 -252.020601)
		(end 387.257798 -252.096778)
		(width 0.0889)
		(layer "In2.Cu")
		(net "M_I_CPU0_SA_CS_N<1>")
	)
	(arc
		(start 389.511794 -252.096778)
		(mid 389.79475 -252.020601)
		(end 390.077706 -252.096778)
		(width 0.0889)
		(layer "In2.Cu")
		(net "M_I_CPU0_SA_CS_N<1>")
	)
	(arc
		(start 391.958322 -252.096778)
		(mid 392.13878 -252.147222)
		(end 392.321034 -252.103636)
		(width 0.0889)
		(layer "In2.Cu")
		(net "M_I_CPU0_SA_CS_N<1>")
	)
	(arc
		(start 377.866148 -252.101604)
		(mid 378.049656 -252.147098)
		(end 378.231908 -252.096778)
		(width 0.0889)
		(layer "In2.Cu")
		(net "M_I_CPU0_SA_CS_N<1>")
	)
	(arc
		(start 393.254738 -252.099572)
		(mid 393.532445 -252.015265)
		(end 393.816078 -252.076712)
		(width 0.0889)
		(layer "In2.Cu")
		(net "M_I_CPU0_SA_CS_N<1>")
	)
	(arc
		(start 392.898122 -252.096524)
		(mid 392.988235 -252.134293)
		(end 393.085066 -252.147324)
		(width 0.0889)
		(layer "In2.Cu")
		(net "M_I_CPU0_SA_CS_N<1>")
	)
	(arc
		(start 379.737874 -252.096778)
		(mid 379.924818 -252.147033)
		(end 380.111762 -252.096778)
		(width 0.0889)
		(layer "In2.Cu")
		(net "M_I_CPU0_SA_CS_N<1>")
	)
	(arc
		(start 382.931924 -252.096778)
		(mid 383.21488 -252.020601)
		(end 383.497836 -252.096778)
		(width 0.0889)
		(layer "In2.Cu")
		(net "M_I_CPU0_SA_CS_N<1>")
	)
	(arc
		(start 388.206234 -252.101604)
		(mid 388.389742 -252.147098)
		(end 388.571994 -252.096778)
		(width 0.0889)
		(layer "In2.Cu")
		(net "M_I_CPU0_SA_CS_N<1>")
	)
	(segment
		(start 377.107958 -251.23013)
		(end 377.57481 -250.964192)
		(width 0.10668)
		(layer "F.Cu")
		(net "M_I_CPU0_SA_CS_N<0>")
	)
	(segment
		(start 377.57481 -250.964192)
		(end 377.420886 -251.229622)
		(width 0.0889)
		(layer "In2.Cu")
		(net "M_I_CPU0_SA_CS_N<0>")
	)
	(segment
		(start 384.90779 -251.286772)
		(end 384.916172 -251.291598)
		(width 0.0889)
		(layer "In2.Cu")
		(net "M_I_CPU0_SA_CS_N<0>")
	)
	(segment
		(start 423.251122 -246.210074)
		(end 431.131218 -246.210074)
		(width 0.14478)
		(layer "In2.Cu")
		(net "M_I_CPU0_SA_CS_N<0>")
	)
	(segment
		(start 398.72158 -251.048012)
		(end 405.24557 -251.048012)
		(width 0.14478)
		(layer "In2.Cu")
		(net "M_I_CPU0_SA_CS_N<0>")
	)
	(segment
		(start 393.036298 -251.380752)
		(end 393.829794 -251.632212)
		(width 0.0889)
		(layer "In2.Cu")
		(net "M_I_CPU0_SA_CS_N<0>")
	)
	(segment
		(start 389.033512 -251.291598)
		(end 389.041894 -251.286772)
		(width 0.0889)
		(layer "In2.Cu")
		(net "M_I_CPU0_SA_CS_N<0>")
	)
	(segment
		(start 411.417008 -247.910096)
		(end 421.5511 -247.910096)
		(width 0.14478)
		(layer "In2.Cu")
		(net "M_I_CPU0_SA_CS_N<0>")
	)
	(segment
		(start 391.837164 -251.29998)
		(end 391.860532 -251.286518)
		(width 0.0889)
		(layer "In2.Cu")
		(net "M_I_CPU0_SA_CS_N<0>")
	)
	(segment
		(start 405.716994 -251.519436)
		(end 407.807668 -251.519436)
		(width 0.14478)
		(layer "In2.Cu")
		(net "M_I_CPU0_SA_CS_N<0>")
	)
	(segment
		(start 391.860532 -251.286518)
		(end 391.884408 -251.272548)
		(width 0.0889)
		(layer "In2.Cu")
		(net "M_I_CPU0_SA_CS_N<0>")
	)
	(segment
		(start 388.093458 -251.291598)
		(end 388.10184 -251.286772)
		(width 0.0889)
		(layer "In2.Cu")
		(net "M_I_CPU0_SA_CS_N<0>")
	)
	(segment
		(start 394.996416 -251.632212)
		(end 398.13738 -251.632212)
		(width 0.14478)
		(layer "In2.Cu")
		(net "M_I_CPU0_SA_CS_N<0>")
	)
	(segment
		(start 384.333496 -251.291598)
		(end 384.341878 -251.286772)
		(width 0.0889)
		(layer "In2.Cu")
		(net "M_I_CPU0_SA_CS_N<0>")
	)
	(segment
		(start 377.420886 -251.229622)
		(end 377.443238 -251.312934)
		(width 0.0889)
		(layer "In2.Cu")
		(net "M_I_CPU0_SA_CS_N<0>")
	)
	(segment
		(start 385.847844 -251.286772)
		(end 385.856226 -251.291598)
		(width 0.0889)
		(layer "In2.Cu")
		(net "M_I_CPU0_SA_CS_N<0>")
	)
	(segment
		(start 379.63348 -251.291598)
		(end 379.641862 -251.286772)
		(width 0.0889)
		(layer "In2.Cu")
		(net "M_I_CPU0_SA_CS_N<0>")
	)
	(segment
		(start 393.829794 -251.632212)
		(end 394.996416 -251.632212)
		(width 0.0889)
		(layer "In2.Cu")
		(net "M_I_CPU0_SA_CS_N<0>")
	)
	(segment
		(start 398.13738 -251.632212)
		(end 398.72158 -251.048012)
		(width 0.14478)
		(layer "In2.Cu")
		(net "M_I_CPU0_SA_CS_N<0>")
	)
	(segment
		(start 378.693426 -251.291598)
		(end 378.701808 -251.286772)
		(width 0.0889)
		(layer "In2.Cu")
		(net "M_I_CPU0_SA_CS_N<0>")
	)
	(segment
		(start 407.807668 -251.519436)
		(end 411.417008 -247.910096)
		(width 0.14478)
		(layer "In2.Cu")
		(net "M_I_CPU0_SA_CS_N<0>")
	)
	(segment
		(start 380.207774 -251.286772)
		(end 380.216156 -251.291598)
		(width 0.0889)
		(layer "In2.Cu")
		(net "M_I_CPU0_SA_CS_N<0>")
	)
	(segment
		(start 421.5511 -247.910096)
		(end 423.251122 -246.210074)
		(width 0.14478)
		(layer "In2.Cu")
		(net "M_I_CPU0_SA_CS_N<0>")
	)
	(segment
		(start 431.131218 -246.210074)
		(end 431.55616 -245.785132)
		(width 0.14478)
		(layer "In2.Cu")
		(net "M_I_CPU0_SA_CS_N<0>")
	)
	(segment
		(start 389.607806 -251.286772)
		(end 389.616188 -251.291598)
		(width 0.0889)
		(layer "In2.Cu")
		(net "M_I_CPU0_SA_CS_N<0>")
	)
	(segment
		(start 392.424666 -251.286772)
		(end 392.44524 -251.29871)
		(width 0.0889)
		(layer "In2.Cu")
		(net "M_I_CPU0_SA_CS_N<0>")
	)
	(segment
		(start 381.147828 -251.286772)
		(end 381.15621 -251.291598)
		(width 0.0889)
		(layer "In2.Cu")
		(net "M_I_CPU0_SA_CS_N<0>")
	)
	(segment
		(start 405.24557 -251.048012)
		(end 405.716994 -251.519436)
		(width 0.14478)
		(layer "In2.Cu")
		(net "M_I_CPU0_SA_CS_N<0>")
	)
	(segment
		(start 383.393442 -251.291598)
		(end 383.401824 -251.286772)
		(width 0.0889)
		(layer "In2.Cu")
		(net "M_I_CPU0_SA_CS_N<0>")
	)
	(arc
		(start 381.15621 -251.291598)
		(mid 381.339718 -251.337092)
		(end 381.52197 -251.286772)
		(width 0.0889)
		(layer "In2.Cu")
		(net "M_I_CPU0_SA_CS_N<0>")
	)
	(arc
		(start 390.54786 -251.286772)
		(mid 390.734804 -251.337027)
		(end 390.921748 -251.286772)
		(width 0.0889)
		(layer "In2.Cu")
		(net "M_I_CPU0_SA_CS_N<0>")
	)
	(arc
		(start 381.52197 -251.286772)
		(mid 381.804926 -251.210595)
		(end 382.087882 -251.286772)
		(width 0.0889)
		(layer "In2.Cu")
		(net "M_I_CPU0_SA_CS_N<0>")
	)
	(arc
		(start 380.581916 -251.286772)
		(mid 380.864872 -251.210595)
		(end 381.147828 -251.286772)
		(width 0.0889)
		(layer "In2.Cu")
		(net "M_I_CPU0_SA_CS_N<0>")
	)
	(arc
		(start 385.856226 -251.291598)
		(mid 386.039734 -251.337092)
		(end 386.221986 -251.286772)
		(width 0.0889)
		(layer "In2.Cu")
		(net "M_I_CPU0_SA_CS_N<0>")
	)
	(arc
		(start 378.327666 -251.286772)
		(mid 378.509917 -251.337122)
		(end 378.693426 -251.291598)
		(width 0.0889)
		(layer "In2.Cu")
		(net "M_I_CPU0_SA_CS_N<0>")
	)
	(arc
		(start 383.401824 -251.286772)
		(mid 383.68478 -251.210595)
		(end 383.967736 -251.286772)
		(width 0.0889)
		(layer "In2.Cu")
		(net "M_I_CPU0_SA_CS_N<0>")
	)
	(arc
		(start 382.087882 -251.286772)
		(mid 382.274826 -251.337027)
		(end 382.46177 -251.286772)
		(width 0.0889)
		(layer "In2.Cu")
		(net "M_I_CPU0_SA_CS_N<0>")
	)
	(arc
		(start 380.216156 -251.291598)
		(mid 380.399664 -251.337092)
		(end 380.581916 -251.286772)
		(width 0.0889)
		(layer "In2.Cu")
		(net "M_I_CPU0_SA_CS_N<0>")
	)
	(arc
		(start 387.727698 -251.286772)
		(mid 387.909949 -251.337122)
		(end 388.093458 -251.291598)
		(width 0.0889)
		(layer "In2.Cu")
		(net "M_I_CPU0_SA_CS_N<0>")
	)
	(arc
		(start 388.10184 -251.286772)
		(mid 388.384796 -251.210595)
		(end 388.667752 -251.286772)
		(width 0.0889)
		(layer "In2.Cu")
		(net "M_I_CPU0_SA_CS_N<0>")
	)
	(arc
		(start 392.44524 -251.29871)
		(mid 392.536328 -251.330198)
		(end 392.632438 -251.337318)
		(width 0.0889)
		(layer "In2.Cu")
		(net "M_I_CPU0_SA_CS_N<0>")
	)
	(arc
		(start 390.921748 -251.286772)
		(mid 391.204704 -251.210595)
		(end 391.48766 -251.286772)
		(width 0.0889)
		(layer "In2.Cu")
		(net "M_I_CPU0_SA_CS_N<0>")
	)
	(arc
		(start 392.632438 -251.337318)
		(mid 392.836137 -251.342603)
		(end 393.036298 -251.380752)
		(width 0.0889)
		(layer "In2.Cu")
		(net "M_I_CPU0_SA_CS_N<0>")
	)
	(arc
		(start 389.041894 -251.286772)
		(mid 389.32485 -251.210595)
		(end 389.607806 -251.286772)
		(width 0.0889)
		(layer "In2.Cu")
		(net "M_I_CPU0_SA_CS_N<0>")
	)
	(arc
		(start 382.46177 -251.286772)
		(mid 382.744726 -251.210595)
		(end 383.027682 -251.286772)
		(width 0.0889)
		(layer "In2.Cu")
		(net "M_I_CPU0_SA_CS_N<0>")
	)
	(arc
		(start 384.916172 -251.291598)
		(mid 385.09968 -251.337092)
		(end 385.281932 -251.286772)
		(width 0.0889)
		(layer "In2.Cu")
		(net "M_I_CPU0_SA_CS_N<0>")
	)
	(arc
		(start 378.701808 -251.286772)
		(mid 378.984764 -251.210595)
		(end 379.26772 -251.286772)
		(width 0.0889)
		(layer "In2.Cu")
		(net "M_I_CPU0_SA_CS_N<0>")
	)
	(arc
		(start 383.967736 -251.286772)
		(mid 384.149987 -251.337122)
		(end 384.333496 -251.291598)
		(width 0.0889)
		(layer "In2.Cu")
		(net "M_I_CPU0_SA_CS_N<0>")
	)
	(arc
		(start 385.281932 -251.286772)
		(mid 385.564888 -251.210595)
		(end 385.847844 -251.286772)
		(width 0.0889)
		(layer "In2.Cu")
		(net "M_I_CPU0_SA_CS_N<0>")
	)
	(arc
		(start 391.48766 -251.286772)
		(mid 391.660768 -251.336888)
		(end 391.837164 -251.29998)
		(width 0.0889)
		(layer "In2.Cu")
		(net "M_I_CPU0_SA_CS_N<0>")
	)
	(arc
		(start 391.884408 -251.272548)
		(mid 392.156345 -251.210722)
		(end 392.424666 -251.286772)
		(width 0.0889)
		(layer "In2.Cu")
		(net "M_I_CPU0_SA_CS_N<0>")
	)
	(arc
		(start 377.761754 -251.286772)
		(mid 378.04471 -251.210595)
		(end 378.327666 -251.286772)
		(width 0.0889)
		(layer "In2.Cu")
		(net "M_I_CPU0_SA_CS_N<0>")
	)
	(arc
		(start 377.443238 -251.312934)
		(mid 377.605427 -251.335669)
		(end 377.761754 -251.286772)
		(width 0.0889)
		(layer "In2.Cu")
		(net "M_I_CPU0_SA_CS_N<0>")
	)
	(arc
		(start 384.341878 -251.286772)
		(mid 384.624834 -251.210595)
		(end 384.90779 -251.286772)
		(width 0.0889)
		(layer "In2.Cu")
		(net "M_I_CPU0_SA_CS_N<0>")
	)
	(arc
		(start 388.667752 -251.286772)
		(mid 388.850003 -251.337122)
		(end 389.033512 -251.291598)
		(width 0.0889)
		(layer "In2.Cu")
		(net "M_I_CPU0_SA_CS_N<0>")
	)
	(arc
		(start 387.161786 -251.286772)
		(mid 387.444742 -251.210595)
		(end 387.727698 -251.286772)
		(width 0.0889)
		(layer "In2.Cu")
		(net "M_I_CPU0_SA_CS_N<0>")
	)
	(arc
		(start 379.641862 -251.286772)
		(mid 379.924818 -251.210595)
		(end 380.207774 -251.286772)
		(width 0.0889)
		(layer "In2.Cu")
		(net "M_I_CPU0_SA_CS_N<0>")
	)
	(arc
		(start 379.26772 -251.286772)
		(mid 379.449971 -251.337122)
		(end 379.63348 -251.291598)
		(width 0.0889)
		(layer "In2.Cu")
		(net "M_I_CPU0_SA_CS_N<0>")
	)
	(arc
		(start 386.221986 -251.286772)
		(mid 386.504942 -251.210595)
		(end 386.787898 -251.286772)
		(width 0.0889)
		(layer "In2.Cu")
		(net "M_I_CPU0_SA_CS_N<0>")
	)
	(arc
		(start 386.787898 -251.286772)
		(mid 386.974842 -251.337027)
		(end 387.161786 -251.286772)
		(width 0.0889)
		(layer "In2.Cu")
		(net "M_I_CPU0_SA_CS_N<0>")
	)
	(arc
		(start 389.616188 -251.291598)
		(mid 389.799696 -251.337092)
		(end 389.981948 -251.286772)
		(width 0.0889)
		(layer "In2.Cu")
		(net "M_I_CPU0_SA_CS_N<0>")
	)
	(arc
		(start 383.027682 -251.286772)
		(mid 383.209933 -251.337122)
		(end 383.393442 -251.291598)
		(width 0.0889)
		(layer "In2.Cu")
		(net "M_I_CPU0_SA_CS_N<0>")
	)
	(arc
		(start 389.981948 -251.286772)
		(mid 390.264904 -251.210595)
		(end 390.54786 -251.286772)
		(width 0.0889)
		(layer "In2.Cu")
		(net "M_I_CPU0_SA_CS_N<0>")
	)
	(segment
		(start 375.22785 -249.610118)
		(end 375.694702 -249.34418)
		(width 0.10668)
		(layer "F.Cu")
		(net "M_I_CPU0_SA_CB<7>")
	)
	(segment
		(start 389.607806 -249.0216)
		(end 389.616188 -249.016774)
		(width 0.0889)
		(layer "In2.Cu")
		(net "M_I_CPU0_SA_CB<7>")
	)
	(segment
		(start 378.693426 -249.016774)
		(end 378.701808 -249.0216)
		(width 0.0889)
		(layer "In2.Cu")
		(net "M_I_CPU0_SA_CB<7>")
	)
	(segment
		(start 398.297654 -248.891552)
		(end 398.551654 -249.145552)
		(width 0.14478)
		(layer "In2.Cu")
		(net "M_I_CPU0_SA_CB<7>")
	)
	(segment
		(start 407.18613 -248.891552)
		(end 407.744676 -248.891552)
		(width 0.14478)
		(layer "In2.Cu")
		(net "M_I_CPU0_SA_CB<7>")
	)
	(segment
		(start 397.544036 -249.093736)
		(end 397.74622 -248.891552)
		(width 0.14478)
		(layer "In2.Cu")
		(net "M_I_CPU0_SA_CB<7>")
	)
	(segment
		(start 406.634696 -249.551698)
		(end 406.89657 -249.551698)
		(width 0.14478)
		(layer "In2.Cu")
		(net "M_I_CPU0_SA_CB<7>")
	)
	(segment
		(start 402.963126 -249.145552)
		(end 403.26056 -249.145552)
		(width 0.14478)
		(layer "In2.Cu")
		(net "M_I_CPU0_SA_CB<7>")
	)
	(segment
		(start 416.029902 -245.114572)
		(end 416.27552 -245.36019)
		(width 0.14478)
		(layer "In2.Cu")
		(net "M_I_CPU0_SA_CB<7>")
	)
	(segment
		(start 388.093458 -249.016774)
		(end 388.10184 -249.0216)
		(width 0.0889)
		(layer "In2.Cu")
		(net "M_I_CPU0_SA_CB<7>")
	)
	(segment
		(start 403.26056 -249.145552)
		(end 403.51456 -248.891552)
		(width 0.14478)
		(layer "In2.Cu")
		(net "M_I_CPU0_SA_CB<7>")
	)
	(segment
		(start 405.168862 -249.145552)
		(end 405.466296 -249.145552)
		(width 0.14478)
		(layer "In2.Cu")
		(net "M_I_CPU0_SA_CB<7>")
	)
	(segment
		(start 381.147828 -249.0216)
		(end 381.15621 -249.016774)
		(width 0.0889)
		(layer "In2.Cu")
		(net "M_I_CPU0_SA_CB<7>")
	)
	(segment
		(start 401.054824 -249.145552)
		(end 401.308824 -248.891552)
		(width 0.14478)
		(layer "In2.Cu")
		(net "M_I_CPU0_SA_CB<7>")
	)
	(segment
		(start 389.033512 -249.016774)
		(end 389.041894 -249.0216)
		(width 0.0889)
		(layer "In2.Cu")
		(net "M_I_CPU0_SA_CB<7>")
	)
	(segment
		(start 399.951956 -249.145552)
		(end 400.205956 -248.891552)
		(width 0.14478)
		(layer "In2.Cu")
		(net "M_I_CPU0_SA_CB<7>")
	)
	(segment
		(start 406.489916 -249.406918)
		(end 406.634696 -249.551698)
		(width 0.14478)
		(layer "In2.Cu")
		(net "M_I_CPU0_SA_CB<7>")
	)
	(segment
		(start 422.32961 -243.660168)
		(end 422.533826 -243.660168)
		(width 0.14478)
		(layer "In2.Cu")
		(net "M_I_CPU0_SA_CB<7>")
	)
	(segment
		(start 407.04135 -249.406918)
		(end 407.04135 -249.036332)
		(width 0.14478)
		(layer "In2.Cu")
		(net "M_I_CPU0_SA_CB<7>")
	)
	(segment
		(start 380.207774 -249.0216)
		(end 380.216156 -249.016774)
		(width 0.0889)
		(layer "In2.Cu")
		(net "M_I_CPU0_SA_CB<7>")
	)
	(segment
		(start 405.466296 -249.145552)
		(end 405.720296 -248.891552)
		(width 0.14478)
		(layer "In2.Cu")
		(net "M_I_CPU0_SA_CB<7>")
	)
	(segment
		(start 376.447812 -249.0216)
		(end 376.456194 -249.016774)
		(width 0.0889)
		(layer "In2.Cu")
		(net "M_I_CPU0_SA_CB<7>")
	)
	(segment
		(start 407.744676 -248.891552)
		(end 411.276038 -245.36019)
		(width 0.14478)
		(layer "In2.Cu")
		(net "M_I_CPU0_SA_CB<7>")
	)
	(segment
		(start 400.50339 -248.891552)
		(end 400.75739 -249.145552)
		(width 0.14478)
		(layer "In2.Cu")
		(net "M_I_CPU0_SA_CB<7>")
	)
	(segment
		(start 418.308536 -245.063772)
		(end 418.563552 -245.063772)
		(width 0.14478)
		(layer "In2.Cu")
		(net "M_I_CPU0_SA_CB<7>")
	)
	(segment
		(start 395.935454 -249.64009)
		(end 397.382492 -249.64009)
		(width 0.14478)
		(layer "In2.Cu")
		(net "M_I_CPU0_SA_CB<7>")
	)
	(segment
		(start 379.63348 -249.016774)
		(end 379.641862 -249.0216)
		(width 0.0889)
		(layer "In2.Cu")
		(net "M_I_CPU0_SA_CB<7>")
	)
	(segment
		(start 385.847844 -249.0216)
		(end 385.856226 -249.016774)
		(width 0.0889)
		(layer "In2.Cu")
		(net "M_I_CPU0_SA_CB<7>")
	)
	(segment
		(start 401.308824 -248.891552)
		(end 401.606258 -248.891552)
		(width 0.14478)
		(layer "In2.Cu")
		(net "M_I_CPU0_SA_CB<7>")
	)
	(segment
		(start 383.393442 -249.016774)
		(end 383.401824 -249.0216)
		(width 0.0889)
		(layer "In2.Cu")
		(net "M_I_CPU0_SA_CB<7>")
	)
	(segment
		(start 399.654522 -249.145552)
		(end 399.951956 -249.145552)
		(width 0.14478)
		(layer "In2.Cu")
		(net "M_I_CPU0_SA_CB<7>")
	)
	(segment
		(start 421.921178 -244.848888)
		(end 421.921178 -244.620288)
		(width 0.14478)
		(layer "In2.Cu")
		(net "M_I_CPU0_SA_CB<7>")
	)
	(segment
		(start 418.012118 -245.36019)
		(end 418.308536 -245.063772)
		(width 0.14478)
		(layer "In2.Cu")
		(net "M_I_CPU0_SA_CB<7>")
	)
	(segment
		(start 397.74622 -248.891552)
		(end 398.297654 -248.891552)
		(width 0.14478)
		(layer "In2.Cu")
		(net "M_I_CPU0_SA_CB<7>")
	)
	(segment
		(start 418.85997 -245.36019)
		(end 420.629588 -245.36019)
		(width 0.14478)
		(layer "In2.Cu")
		(net "M_I_CPU0_SA_CB<7>")
	)
	(segment
		(start 423.08526 -243.354352)
		(end 423.391076 -243.660168)
		(width 0.14478)
		(layer "In2.Cu")
		(net "M_I_CPU0_SA_CB<7>")
	)
	(segment
		(start 425.093892 -243.344192)
		(end 425.409868 -243.660168)
		(width 0.14478)
		(layer "In2.Cu")
		(net "M_I_CPU0_SA_CB<7>")
	)
	(segment
		(start 414.3756 -245.36019)
		(end 414.621218 -245.114572)
		(width 0.14478)
		(layer "In2.Cu")
		(net "M_I_CPU0_SA_CB<7>")
	)
	(segment
		(start 413.51835 -245.114572)
		(end 413.824166 -245.114572)
		(width 0.14478)
		(layer "In2.Cu")
		(net "M_I_CPU0_SA_CB<7>")
	)
	(segment
		(start 405.720296 -248.891552)
		(end 406.345136 -248.891552)
		(width 0.14478)
		(layer "In2.Cu")
		(net "M_I_CPU0_SA_CB<7>")
	)
	(segment
		(start 416.90925 -245.36019)
		(end 417.205668 -245.063772)
		(width 0.14478)
		(layer "In2.Cu")
		(net "M_I_CPU0_SA_CB<7>")
	)
	(segment
		(start 421.531034 -245.010432)
		(end 421.759634 -245.010432)
		(width 0.14478)
		(layer "In2.Cu")
		(net "M_I_CPU0_SA_CB<7>")
	)
	(segment
		(start 424.542458 -243.660168)
		(end 424.858434 -243.344192)
		(width 0.14478)
		(layer "In2.Cu")
		(net "M_I_CPU0_SA_CB<7>")
	)
	(segment
		(start 399.400522 -248.891552)
		(end 399.654522 -249.145552)
		(width 0.14478)
		(layer "In2.Cu")
		(net "M_I_CPU0_SA_CB<7>")
	)
	(segment
		(start 392.788648 -249.01398)
		(end 392.802364 -249.021854)
		(width 0.0889)
		(layer "In2.Cu")
		(net "M_I_CPU0_SA_CB<7>")
	)
	(segment
		(start 375.84888 -249.07875)
		(end 375.945146 -249.05335)
		(width 0.0889)
		(layer "In2.Cu")
		(net "M_I_CPU0_SA_CB<7>")
	)
	(segment
		(start 404.617428 -248.891552)
		(end 404.914862 -248.891552)
		(width 0.14478)
		(layer "In2.Cu")
		(net "M_I_CPU0_SA_CB<7>")
	)
	(segment
		(start 406.345136 -248.891552)
		(end 406.489916 -249.036332)
		(width 0.14478)
		(layer "In2.Cu")
		(net "M_I_CPU0_SA_CB<7>")
	)
	(segment
		(start 413.824166 -245.114572)
		(end 414.069784 -245.36019)
		(width 0.14478)
		(layer "In2.Cu")
		(net "M_I_CPU0_SA_CB<7>")
	)
	(segment
		(start 414.927034 -245.114572)
		(end 415.172652 -245.36019)
		(width 0.14478)
		(layer "In2.Cu")
		(net "M_I_CPU0_SA_CB<7>")
	)
	(segment
		(start 404.065994 -249.145552)
		(end 404.363428 -249.145552)
		(width 0.14478)
		(layer "In2.Cu")
		(net "M_I_CPU0_SA_CB<7>")
	)
	(segment
		(start 417.460684 -245.063772)
		(end 417.757102 -245.36019)
		(width 0.14478)
		(layer "In2.Cu")
		(net "M_I_CPU0_SA_CB<7>")
	)
	(segment
		(start 394.875004 -249.242072)
		(end 395.273022 -249.64009)
		(width 0.0889)
		(layer "In2.Cu")
		(net "M_I_CPU0_SA_CB<7>")
	)
	(segment
		(start 421.14089 -244.848888)
		(end 421.36949 -244.848888)
		(width 0.14478)
		(layer "In2.Cu")
		(net "M_I_CPU0_SA_CB<7>")
	)
	(segment
		(start 420.629588 -245.36019)
		(end 421.14089 -244.848888)
		(width 0.14478)
		(layer "In2.Cu")
		(net "M_I_CPU0_SA_CB<7>")
	)
	(segment
		(start 395.273022 -249.64009)
		(end 395.935454 -249.64009)
		(width 0.0889)
		(layer "In2.Cu")
		(net "M_I_CPU0_SA_CB<7>")
	)
	(segment
		(start 406.89657 -249.551698)
		(end 407.04135 -249.406918)
		(width 0.14478)
		(layer "In2.Cu")
		(net "M_I_CPU0_SA_CB<7>")
	)
	(segment
		(start 415.724086 -245.114572)
		(end 416.029902 -245.114572)
		(width 0.14478)
		(layer "In2.Cu")
		(net "M_I_CPU0_SA_CB<7>")
	)
	(segment
		(start 402.709126 -248.891552)
		(end 402.963126 -249.145552)
		(width 0.14478)
		(layer "In2.Cu")
		(net "M_I_CPU0_SA_CB<7>")
	)
	(segment
		(start 413.272732 -245.36019)
		(end 413.51835 -245.114572)
		(width 0.14478)
		(layer "In2.Cu")
		(net "M_I_CPU0_SA_CB<7>")
	)
	(segment
		(start 403.811994 -248.891552)
		(end 404.065994 -249.145552)
		(width 0.14478)
		(layer "In2.Cu")
		(net "M_I_CPU0_SA_CB<7>")
	)
	(segment
		(start 422.533826 -243.660168)
		(end 422.839642 -243.354352)
		(width 0.14478)
		(layer "In2.Cu")
		(net "M_I_CPU0_SA_CB<7>")
	)
	(segment
		(start 427.030896 -243.660168)
		(end 427.456092 -243.234972)
		(width 0.14478)
		(layer "In2.Cu")
		(net "M_I_CPU0_SA_CB<7>")
	)
	(segment
		(start 421.36949 -244.848888)
		(end 421.531034 -245.010432)
		(width 0.14478)
		(layer "In2.Cu")
		(net "M_I_CPU0_SA_CB<7>")
	)
	(segment
		(start 402.157692 -249.145552)
		(end 402.411692 -248.891552)
		(width 0.14478)
		(layer "In2.Cu")
		(net "M_I_CPU0_SA_CB<7>")
	)
	(segment
		(start 403.51456 -248.891552)
		(end 403.811994 -248.891552)
		(width 0.14478)
		(layer "In2.Cu")
		(net "M_I_CPU0_SA_CB<7>")
	)
	(segment
		(start 417.205668 -245.063772)
		(end 417.460684 -245.063772)
		(width 0.14478)
		(layer "In2.Cu")
		(net "M_I_CPU0_SA_CB<7>")
	)
	(segment
		(start 425.409868 -243.660168)
		(end 425.645326 -243.660168)
		(width 0.14478)
		(layer "In2.Cu")
		(net "M_I_CPU0_SA_CB<7>")
	)
	(segment
		(start 416.27552 -245.36019)
		(end 416.90925 -245.36019)
		(width 0.14478)
		(layer "In2.Cu")
		(net "M_I_CPU0_SA_CB<7>")
	)
	(segment
		(start 422.839642 -243.354352)
		(end 423.08526 -243.354352)
		(width 0.14478)
		(layer "In2.Cu")
		(net "M_I_CPU0_SA_CB<7>")
	)
	(segment
		(start 415.172652 -245.36019)
		(end 415.478468 -245.36019)
		(width 0.14478)
		(layer "In2.Cu")
		(net "M_I_CPU0_SA_CB<7>")
	)
	(segment
		(start 391.48766 -249.0216)
		(end 391.496042 -249.016774)
		(width 0.0889)
		(layer "In2.Cu")
		(net "M_I_CPU0_SA_CB<7>")
	)
	(segment
		(start 384.90779 -249.0216)
		(end 384.916172 -249.016774)
		(width 0.0889)
		(layer "In2.Cu")
		(net "M_I_CPU0_SA_CB<7>")
	)
	(segment
		(start 426.19676 -243.344192)
		(end 426.512736 -243.660168)
		(width 0.14478)
		(layer "In2.Cu")
		(net "M_I_CPU0_SA_CB<7>")
	)
	(segment
		(start 424.858434 -243.344192)
		(end 425.093892 -243.344192)
		(width 0.14478)
		(layer "In2.Cu")
		(net "M_I_CPU0_SA_CB<7>")
	)
	(segment
		(start 414.621218 -245.114572)
		(end 414.927034 -245.114572)
		(width 0.14478)
		(layer "In2.Cu")
		(net "M_I_CPU0_SA_CB<7>")
	)
	(segment
		(start 401.606258 -248.891552)
		(end 401.860258 -249.145552)
		(width 0.14478)
		(layer "In2.Cu")
		(net "M_I_CPU0_SA_CB<7>")
	)
	(segment
		(start 393.621768 -249.242072)
		(end 394.875004 -249.242072)
		(width 0.0889)
		(layer "In2.Cu")
		(net "M_I_CPU0_SA_CB<7>")
	)
	(segment
		(start 400.75739 -249.145552)
		(end 401.054824 -249.145552)
		(width 0.14478)
		(layer "In2.Cu")
		(net "M_I_CPU0_SA_CB<7>")
	)
	(segment
		(start 397.382492 -249.64009)
		(end 397.544036 -249.478546)
		(width 0.14478)
		(layer "In2.Cu")
		(net "M_I_CPU0_SA_CB<7>")
	)
	(segment
		(start 392.413998 -249.030236)
		(end 392.42873 -249.0216)
		(width 0.0889)
		(layer "In2.Cu")
		(net "M_I_CPU0_SA_CB<7>")
	)
	(segment
		(start 417.757102 -245.36019)
		(end 418.012118 -245.36019)
		(width 0.14478)
		(layer "In2.Cu")
		(net "M_I_CPU0_SA_CB<7>")
	)
	(segment
		(start 423.391076 -243.660168)
		(end 424.542458 -243.660168)
		(width 0.14478)
		(layer "In2.Cu")
		(net "M_I_CPU0_SA_CB<7>")
	)
	(segment
		(start 415.478468 -245.36019)
		(end 415.724086 -245.114572)
		(width 0.14478)
		(layer "In2.Cu")
		(net "M_I_CPU0_SA_CB<7>")
	)
	(segment
		(start 399.103088 -248.891552)
		(end 399.400522 -248.891552)
		(width 0.14478)
		(layer "In2.Cu")
		(net "M_I_CPU0_SA_CB<7>")
	)
	(segment
		(start 414.069784 -245.36019)
		(end 414.3756 -245.36019)
		(width 0.14478)
		(layer "In2.Cu")
		(net "M_I_CPU0_SA_CB<7>")
	)
	(segment
		(start 425.961302 -243.344192)
		(end 426.19676 -243.344192)
		(width 0.14478)
		(layer "In2.Cu")
		(net "M_I_CPU0_SA_CB<7>")
	)
	(segment
		(start 401.860258 -249.145552)
		(end 402.157692 -249.145552)
		(width 0.14478)
		(layer "In2.Cu")
		(net "M_I_CPU0_SA_CB<7>")
	)
	(segment
		(start 400.205956 -248.891552)
		(end 400.50339 -248.891552)
		(width 0.14478)
		(layer "In2.Cu")
		(net "M_I_CPU0_SA_CB<7>")
	)
	(segment
		(start 421.921178 -244.620288)
		(end 421.759634 -244.458744)
		(width 0.14478)
		(layer "In2.Cu")
		(net "M_I_CPU0_SA_CB<7>")
	)
	(segment
		(start 406.489916 -249.036332)
		(end 406.489916 -249.406918)
		(width 0.14478)
		(layer "In2.Cu")
		(net "M_I_CPU0_SA_CB<7>")
	)
	(segment
		(start 404.363428 -249.145552)
		(end 404.617428 -248.891552)
		(width 0.14478)
		(layer "In2.Cu")
		(net "M_I_CPU0_SA_CB<7>")
	)
	(segment
		(start 418.563552 -245.063772)
		(end 418.85997 -245.36019)
		(width 0.14478)
		(layer "In2.Cu")
		(net "M_I_CPU0_SA_CB<7>")
	)
	(segment
		(start 421.759634 -244.230144)
		(end 422.32961 -243.660168)
		(width 0.14478)
		(layer "In2.Cu")
		(net "M_I_CPU0_SA_CB<7>")
	)
	(segment
		(start 411.276038 -245.36019)
		(end 413.272732 -245.36019)
		(width 0.14478)
		(layer "In2.Cu")
		(net "M_I_CPU0_SA_CB<7>")
	)
	(segment
		(start 425.645326 -243.660168)
		(end 425.961302 -243.344192)
		(width 0.14478)
		(layer "In2.Cu")
		(net "M_I_CPU0_SA_CB<7>")
	)
	(segment
		(start 404.914862 -248.891552)
		(end 405.168862 -249.145552)
		(width 0.14478)
		(layer "In2.Cu")
		(net "M_I_CPU0_SA_CB<7>")
	)
	(segment
		(start 398.849088 -249.145552)
		(end 399.103088 -248.891552)
		(width 0.14478)
		(layer "In2.Cu")
		(net "M_I_CPU0_SA_CB<7>")
	)
	(segment
		(start 421.759634 -245.010432)
		(end 421.921178 -244.848888)
		(width 0.14478)
		(layer "In2.Cu")
		(net "M_I_CPU0_SA_CB<7>")
	)
	(segment
		(start 407.04135 -249.036332)
		(end 407.18613 -248.891552)
		(width 0.14478)
		(layer "In2.Cu")
		(net "M_I_CPU0_SA_CB<7>")
	)
	(segment
		(start 398.551654 -249.145552)
		(end 398.849088 -249.145552)
		(width 0.14478)
		(layer "In2.Cu")
		(net "M_I_CPU0_SA_CB<7>")
	)
	(segment
		(start 421.759634 -244.458744)
		(end 421.759634 -244.230144)
		(width 0.14478)
		(layer "In2.Cu")
		(net "M_I_CPU0_SA_CB<7>")
	)
	(segment
		(start 426.512736 -243.660168)
		(end 427.030896 -243.660168)
		(width 0.14478)
		(layer "In2.Cu")
		(net "M_I_CPU0_SA_CB<7>")
	)
	(segment
		(start 384.333496 -249.016774)
		(end 384.341878 -249.0216)
		(width 0.0889)
		(layer "In2.Cu")
		(net "M_I_CPU0_SA_CB<7>")
	)
	(segment
		(start 402.411692 -248.891552)
		(end 402.709126 -248.891552)
		(width 0.14478)
		(layer "In2.Cu")
		(net "M_I_CPU0_SA_CB<7>")
	)
	(segment
		(start 397.544036 -249.478546)
		(end 397.544036 -249.093736)
		(width 0.14478)
		(layer "In2.Cu")
		(net "M_I_CPU0_SA_CB<7>")
	)
	(segment
		(start 375.694702 -249.34418)
		(end 375.84888 -249.07875)
		(width 0.0889)
		(layer "In2.Cu")
		(net "M_I_CPU0_SA_CB<7>")
	)
	(arc
		(start 376.456194 -249.016774)
		(mid 376.639702 -248.97128)
		(end 376.821954 -249.0216)
		(width 0.0889)
		(layer "In2.Cu")
		(net "M_I_CPU0_SA_CB<7>")
	)
	(arc
		(start 392.802364 -249.021854)
		(mid 393.197522 -249.18609)
		(end 393.621768 -249.242072)
		(width 0.0889)
		(layer "In2.Cu")
		(net "M_I_CPU0_SA_CB<7>")
	)
	(arc
		(start 390.921748 -249.0216)
		(mid 391.204704 -249.097777)
		(end 391.48766 -249.0216)
		(width 0.0889)
		(layer "In2.Cu")
		(net "M_I_CPU0_SA_CB<7>")
	)
	(arc
		(start 385.281932 -249.0216)
		(mid 385.564888 -249.097777)
		(end 385.847844 -249.0216)
		(width 0.0889)
		(layer "In2.Cu")
		(net "M_I_CPU0_SA_CB<7>")
	)
	(arc
		(start 385.856226 -249.016774)
		(mid 386.039734 -248.97128)
		(end 386.221986 -249.0216)
		(width 0.0889)
		(layer "In2.Cu")
		(net "M_I_CPU0_SA_CB<7>")
	)
	(arc
		(start 383.967736 -249.0216)
		(mid 384.149987 -248.97125)
		(end 384.333496 -249.016774)
		(width 0.0889)
		(layer "In2.Cu")
		(net "M_I_CPU0_SA_CB<7>")
	)
	(arc
		(start 384.341878 -249.0216)
		(mid 384.624834 -249.097777)
		(end 384.90779 -249.0216)
		(width 0.0889)
		(layer "In2.Cu")
		(net "M_I_CPU0_SA_CB<7>")
	)
	(arc
		(start 378.701808 -249.0216)
		(mid 378.984764 -249.097777)
		(end 379.26772 -249.0216)
		(width 0.0889)
		(layer "In2.Cu")
		(net "M_I_CPU0_SA_CB<7>")
	)
	(arc
		(start 381.15621 -249.016774)
		(mid 381.339718 -248.97128)
		(end 381.52197 -249.0216)
		(width 0.0889)
		(layer "In2.Cu")
		(net "M_I_CPU0_SA_CB<7>")
	)
	(arc
		(start 391.86231 -249.0216)
		(mid 392.137016 -249.097964)
		(end 392.413998 -249.030236)
		(width 0.0889)
		(layer "In2.Cu")
		(net "M_I_CPU0_SA_CB<7>")
	)
	(arc
		(start 387.727698 -249.0216)
		(mid 387.909949 -248.97125)
		(end 388.093458 -249.016774)
		(width 0.0889)
		(layer "In2.Cu")
		(net "M_I_CPU0_SA_CB<7>")
	)
	(arc
		(start 378.327666 -249.0216)
		(mid 378.509917 -248.97125)
		(end 378.693426 -249.016774)
		(width 0.0889)
		(layer "In2.Cu")
		(net "M_I_CPU0_SA_CB<7>")
	)
	(arc
		(start 376.821954 -249.0216)
		(mid 377.10491 -249.097777)
		(end 377.387866 -249.0216)
		(width 0.0889)
		(layer "In2.Cu")
		(net "M_I_CPU0_SA_CB<7>")
	)
	(arc
		(start 379.641862 -249.0216)
		(mid 379.924818 -249.097777)
		(end 380.207774 -249.0216)
		(width 0.0889)
		(layer "In2.Cu")
		(net "M_I_CPU0_SA_CB<7>")
	)
	(arc
		(start 388.10184 -249.0216)
		(mid 388.384796 -249.097777)
		(end 388.667752 -249.0216)
		(width 0.0889)
		(layer "In2.Cu")
		(net "M_I_CPU0_SA_CB<7>")
	)
	(arc
		(start 380.216156 -249.016774)
		(mid 380.399664 -248.97128)
		(end 380.581916 -249.0216)
		(width 0.0889)
		(layer "In2.Cu")
		(net "M_I_CPU0_SA_CB<7>")
	)
	(arc
		(start 383.027682 -249.0216)
		(mid 383.209933 -248.97125)
		(end 383.393442 -249.016774)
		(width 0.0889)
		(layer "In2.Cu")
		(net "M_I_CPU0_SA_CB<7>")
	)
	(arc
		(start 382.46177 -249.0216)
		(mid 382.744726 -249.097777)
		(end 383.027682 -249.0216)
		(width 0.0889)
		(layer "In2.Cu")
		(net "M_I_CPU0_SA_CB<7>")
	)
	(arc
		(start 384.916172 -249.016774)
		(mid 385.09968 -248.97128)
		(end 385.281932 -249.0216)
		(width 0.0889)
		(layer "In2.Cu")
		(net "M_I_CPU0_SA_CB<7>")
	)
	(arc
		(start 386.221986 -249.0216)
		(mid 386.504942 -249.097777)
		(end 386.787898 -249.0216)
		(width 0.0889)
		(layer "In2.Cu")
		(net "M_I_CPU0_SA_CB<7>")
	)
	(arc
		(start 389.616188 -249.016774)
		(mid 389.799696 -248.97128)
		(end 389.981948 -249.0216)
		(width 0.0889)
		(layer "In2.Cu")
		(net "M_I_CPU0_SA_CB<7>")
	)
	(arc
		(start 377.387866 -249.0216)
		(mid 377.57481 -248.971345)
		(end 377.761754 -249.0216)
		(width 0.0889)
		(layer "In2.Cu")
		(net "M_I_CPU0_SA_CB<7>")
	)
	(arc
		(start 382.087882 -249.0216)
		(mid 382.274826 -248.971345)
		(end 382.46177 -249.0216)
		(width 0.0889)
		(layer "In2.Cu")
		(net "M_I_CPU0_SA_CB<7>")
	)
	(arc
		(start 389.041894 -249.0216)
		(mid 389.32485 -249.097777)
		(end 389.607806 -249.0216)
		(width 0.0889)
		(layer "In2.Cu")
		(net "M_I_CPU0_SA_CB<7>")
	)
	(arc
		(start 380.581916 -249.0216)
		(mid 380.864872 -249.097777)
		(end 381.147828 -249.0216)
		(width 0.0889)
		(layer "In2.Cu")
		(net "M_I_CPU0_SA_CB<7>")
	)
	(arc
		(start 375.945146 -249.05335)
		(mid 376.200211 -249.096701)
		(end 376.447812 -249.0216)
		(width 0.0889)
		(layer "In2.Cu")
		(net "M_I_CPU0_SA_CB<7>")
	)
	(arc
		(start 381.52197 -249.0216)
		(mid 381.804926 -249.097777)
		(end 382.087882 -249.0216)
		(width 0.0889)
		(layer "In2.Cu")
		(net "M_I_CPU0_SA_CB<7>")
	)
	(arc
		(start 390.54786 -249.0216)
		(mid 390.734804 -248.971345)
		(end 390.921748 -249.0216)
		(width 0.0889)
		(layer "In2.Cu")
		(net "M_I_CPU0_SA_CB<7>")
	)
	(arc
		(start 392.42873 -249.0216)
		(mid 392.607717 -248.97143)
		(end 392.788648 -249.01398)
		(width 0.0889)
		(layer "In2.Cu")
		(net "M_I_CPU0_SA_CB<7>")
	)
	(arc
		(start 386.787898 -249.0216)
		(mid 386.974842 -248.971345)
		(end 387.161786 -249.0216)
		(width 0.0889)
		(layer "In2.Cu")
		(net "M_I_CPU0_SA_CB<7>")
	)
	(arc
		(start 391.496042 -249.016774)
		(mid 391.679804 -248.971158)
		(end 391.86231 -249.0216)
		(width 0.0889)
		(layer "In2.Cu")
		(net "M_I_CPU0_SA_CB<7>")
	)
	(arc
		(start 389.981948 -249.0216)
		(mid 390.264904 -249.097777)
		(end 390.54786 -249.0216)
		(width 0.0889)
		(layer "In2.Cu")
		(net "M_I_CPU0_SA_CB<7>")
	)
	(arc
		(start 383.401824 -249.0216)
		(mid 383.68478 -249.097777)
		(end 383.967736 -249.0216)
		(width 0.0889)
		(layer "In2.Cu")
		(net "M_I_CPU0_SA_CB<7>")
	)
	(arc
		(start 388.667752 -249.0216)
		(mid 388.850003 -248.97125)
		(end 389.033512 -249.016774)
		(width 0.0889)
		(layer "In2.Cu")
		(net "M_I_CPU0_SA_CB<7>")
	)
	(arc
		(start 387.161786 -249.0216)
		(mid 387.444742 -249.097777)
		(end 387.727698 -249.0216)
		(width 0.0889)
		(layer "In2.Cu")
		(net "M_I_CPU0_SA_CB<7>")
	)
	(arc
		(start 379.26772 -249.0216)
		(mid 379.449971 -248.97125)
		(end 379.63348 -249.016774)
		(width 0.0889)
		(layer "In2.Cu")
		(net "M_I_CPU0_SA_CB<7>")
	)
	(arc
		(start 377.761754 -249.0216)
		(mid 378.04471 -249.097777)
		(end 378.327666 -249.0216)
		(width 0.0889)
		(layer "In2.Cu")
		(net "M_I_CPU0_SA_CB<7>")
	)
	(segment
		(start 376.638058 -248.800112)
		(end 377.10491 -248.534174)
		(width 0.10668)
		(layer "F.Cu")
		(net "M_I_CPU0_SA_CB<6>")
	)
	(segment
		(start 426.453808 -241.960146)
		(end 427.030896 -241.960146)
		(width 0.14478)
		(layer "In2.Cu")
		(net "M_I_CPU0_SA_CB<6>")
	)
	(segment
		(start 413.569404 -242.626896)
		(end 413.730948 -242.465352)
		(width 0.14478)
		(layer "In2.Cu")
		(net "M_I_CPU0_SA_CB<6>")
	)
	(segment
		(start 417.799266 -243.660168)
		(end 418.027612 -243.660168)
		(width 0.14478)
		(layer "In2.Cu")
		(net "M_I_CPU0_SA_CB<6>")
	)
	(segment
		(start 415.223706 -243.498624)
		(end 415.38525 -243.660168)
		(width 0.14478)
		(layer "In2.Cu")
		(net "M_I_CPU0_SA_CB<6>")
	)
	(segment
		(start 414.672272 -242.761516)
		(end 414.833816 -242.599972)
		(width 0.14478)
		(layer "In2.Cu")
		(net "M_I_CPU0_SA_CB<6>")
	)
	(segment
		(start 395.910054 -248.72061)
		(end 396.566136 -248.72061)
		(width 0.14478)
		(layer "In2.Cu")
		(net "M_I_CPU0_SA_CB<6>")
	)
	(segment
		(start 377.10491 -248.534174)
		(end 377.258834 -248.268744)
		(width 0.0889)
		(layer "In2.Cu")
		(net "M_I_CPU0_SA_CB<6>")
	)
	(segment
		(start 418.189156 -243.498624)
		(end 418.189156 -243.033296)
		(width 0.14478)
		(layer "In2.Cu")
		(net "M_I_CPU0_SA_CB<6>")
	)
	(segment
		(start 417.086288 -243.498624)
		(end 417.086288 -243.033296)
		(width 0.14478)
		(layer "In2.Cu")
		(net "M_I_CPU0_SA_CB<6>")
	)
	(segment
		(start 391.956036 -248.211848)
		(end 391.97788 -248.199402)
		(width 0.0889)
		(layer "In2.Cu")
		(net "M_I_CPU0_SA_CB<6>")
	)
	(segment
		(start 407.401522 -247.96242)
		(end 411.703774 -243.660168)
		(width 0.14478)
		(layer "In2.Cu")
		(net "M_I_CPU0_SA_CB<6>")
	)
	(segment
		(start 416.924744 -243.660168)
		(end 417.086288 -243.498624)
		(width 0.14478)
		(layer "In2.Cu")
		(net "M_I_CPU0_SA_CB<6>")
	)
	(segment
		(start 386.683504 -248.206768)
		(end 386.691886 -248.211594)
		(width 0.0889)
		(layer "In2.Cu")
		(net "M_I_CPU0_SA_CB<6>")
	)
	(segment
		(start 381.043434 -248.206768)
		(end 381.051816 -248.211594)
		(width 0.0889)
		(layer "In2.Cu")
		(net "M_I_CPU0_SA_CB<6>")
	)
	(segment
		(start 418.3507 -242.871752)
		(end 418.579046 -242.871752)
		(width 0.14478)
		(layer "In2.Cu")
		(net "M_I_CPU0_SA_CB<6>")
	)
	(segment
		(start 414.120838 -242.626896)
		(end 414.120838 -243.498624)
		(width 0.14478)
		(layer "In2.Cu")
		(net "M_I_CPU0_SA_CB<6>")
	)
	(segment
		(start 377.258834 -248.268744)
		(end 377.354846 -248.243344)
		(width 0.0889)
		(layer "In2.Cu")
		(net "M_I_CPU0_SA_CB<6>")
	)
	(segment
		(start 418.027612 -243.660168)
		(end 418.189156 -243.498624)
		(width 0.14478)
		(layer "In2.Cu")
		(net "M_I_CPU0_SA_CB<6>")
	)
	(segment
		(start 418.74059 -243.498624)
		(end 418.902134 -243.660168)
		(width 0.14478)
		(layer "In2.Cu")
		(net "M_I_CPU0_SA_CB<6>")
	)
	(segment
		(start 390.443466 -248.206768)
		(end 390.451848 -248.211594)
		(width 0.0889)
		(layer "In2.Cu")
		(net "M_I_CPU0_SA_CB<6>")
	)
	(segment
		(start 424.509692 -241.960146)
		(end 424.799506 -241.670332)
		(width 0.14478)
		(layer "In2.Cu")
		(net "M_I_CPU0_SA_CB<6>")
	)
	(segment
		(start 387.257798 -248.211594)
		(end 387.26618 -248.206768)
		(width 0.0889)
		(layer "In2.Cu")
		(net "M_I_CPU0_SA_CB<6>")
	)
	(segment
		(start 422.510204 -241.960146)
		(end 424.509692 -241.960146)
		(width 0.14478)
		(layer "In2.Cu")
		(net "M_I_CPU0_SA_CB<6>")
	)
	(segment
		(start 425.35094 -241.960146)
		(end 425.61256 -241.960146)
		(width 0.14478)
		(layer "In2.Cu")
		(net "M_I_CPU0_SA_CB<6>")
	)
	(segment
		(start 426.163994 -241.670332)
		(end 426.453808 -241.960146)
		(width 0.14478)
		(layer "In2.Cu")
		(net "M_I_CPU0_SA_CB<6>")
	)
	(segment
		(start 414.120838 -243.498624)
		(end 414.282382 -243.660168)
		(width 0.14478)
		(layer "In2.Cu")
		(net "M_I_CPU0_SA_CB<6>")
	)
	(segment
		(start 415.223706 -242.761516)
		(end 415.223706 -243.498624)
		(width 0.14478)
		(layer "In2.Cu")
		(net "M_I_CPU0_SA_CB<6>")
	)
	(segment
		(start 414.672272 -243.498624)
		(end 414.672272 -242.761516)
		(width 0.14478)
		(layer "In2.Cu")
		(net "M_I_CPU0_SA_CB<6>")
	)
	(segment
		(start 393.240514 -248.194576)
		(end 393.270486 -248.211848)
		(width 0.0889)
		(layer "In2.Cu")
		(net "M_I_CPU0_SA_CB<6>")
	)
	(segment
		(start 415.062162 -242.599972)
		(end 415.223706 -242.761516)
		(width 0.14478)
		(layer "In2.Cu")
		(net "M_I_CPU0_SA_CB<6>")
	)
	(segment
		(start 418.902134 -243.660168)
		(end 420.810182 -243.660168)
		(width 0.14478)
		(layer "In2.Cu")
		(net "M_I_CPU0_SA_CB<6>")
	)
	(segment
		(start 427.030896 -241.960146)
		(end 427.456092 -241.53495)
		(width 0.14478)
		(layer "In2.Cu")
		(net "M_I_CPU0_SA_CB<6>")
	)
	(segment
		(start 385.74345 -248.206768)
		(end 385.751832 -248.211594)
		(width 0.0889)
		(layer "In2.Cu")
		(net "M_I_CPU0_SA_CB<6>")
	)
	(segment
		(start 413.730948 -242.465352)
		(end 413.959294 -242.465352)
		(width 0.14478)
		(layer "In2.Cu")
		(net "M_I_CPU0_SA_CB<6>")
	)
	(segment
		(start 382.557782 -248.211594)
		(end 382.566164 -248.206768)
		(width 0.0889)
		(layer "In2.Cu")
		(net "M_I_CPU0_SA_CB<6>")
	)
	(segment
		(start 424.799506 -241.670332)
		(end 425.061126 -241.670332)
		(width 0.14478)
		(layer "In2.Cu")
		(net "M_I_CPU0_SA_CB<6>")
	)
	(segment
		(start 411.703774 -243.660168)
		(end 413.40786 -243.660168)
		(width 0.14478)
		(layer "In2.Cu")
		(net "M_I_CPU0_SA_CB<6>")
	)
	(segment
		(start 425.61256 -241.960146)
		(end 425.902374 -241.670332)
		(width 0.14478)
		(layer "In2.Cu")
		(net "M_I_CPU0_SA_CB<6>")
	)
	(segment
		(start 417.637722 -243.033296)
		(end 417.637722 -243.498624)
		(width 0.14478)
		(layer "In2.Cu")
		(net "M_I_CPU0_SA_CB<6>")
	)
	(segment
		(start 418.74059 -243.033296)
		(end 418.74059 -243.498624)
		(width 0.14478)
		(layer "In2.Cu")
		(net "M_I_CPU0_SA_CB<6>")
	)
	(segment
		(start 418.579046 -242.871752)
		(end 418.74059 -243.033296)
		(width 0.14478)
		(layer "In2.Cu")
		(net "M_I_CPU0_SA_CB<6>")
	)
	(segment
		(start 388.197852 -248.211594)
		(end 388.206234 -248.206768)
		(width 0.0889)
		(layer "In2.Cu")
		(net "M_I_CPU0_SA_CB<6>")
	)
	(segment
		(start 392.328654 -248.211594)
		(end 392.35634 -248.227596)
		(width 0.0889)
		(layer "In2.Cu")
		(net "M_I_CPU0_SA_CB<6>")
	)
	(segment
		(start 378.79782 -248.211594)
		(end 378.806202 -248.206768)
		(width 0.0889)
		(layer "In2.Cu")
		(net "M_I_CPU0_SA_CB<6>")
	)
	(segment
		(start 383.497836 -248.211594)
		(end 383.506218 -248.206768)
		(width 0.0889)
		(layer "In2.Cu")
		(net "M_I_CPU0_SA_CB<6>")
	)
	(segment
		(start 413.40786 -243.660168)
		(end 413.569404 -243.498624)
		(width 0.14478)
		(layer "In2.Cu")
		(net "M_I_CPU0_SA_CB<6>")
	)
	(segment
		(start 377.857766 -248.211594)
		(end 377.866148 -248.206768)
		(width 0.0889)
		(layer "In2.Cu")
		(net "M_I_CPU0_SA_CB<6>")
	)
	(segment
		(start 417.637722 -243.498624)
		(end 417.799266 -243.660168)
		(width 0.14478)
		(layer "In2.Cu")
		(net "M_I_CPU0_SA_CB<6>")
	)
	(segment
		(start 391.93216 -248.225818)
		(end 391.956036 -248.211848)
		(width 0.0889)
		(layer "In2.Cu")
		(net "M_I_CPU0_SA_CB<6>")
	)
	(segment
		(start 397.324326 -247.96242)
		(end 407.401522 -247.96242)
		(width 0.14478)
		(layer "In2.Cu")
		(net "M_I_CPU0_SA_CB<6>")
	)
	(segment
		(start 393.270486 -248.211848)
		(end 393.779248 -248.72061)
		(width 0.0889)
		(layer "In2.Cu")
		(net "M_I_CPU0_SA_CB<6>")
	)
	(segment
		(start 414.833816 -242.599972)
		(end 415.062162 -242.599972)
		(width 0.14478)
		(layer "In2.Cu")
		(net "M_I_CPU0_SA_CB<6>")
	)
	(segment
		(start 396.566136 -248.72061)
		(end 397.324326 -247.96242)
		(width 0.14478)
		(layer "In2.Cu")
		(net "M_I_CPU0_SA_CB<6>")
	)
	(segment
		(start 417.086288 -243.033296)
		(end 417.247832 -242.871752)
		(width 0.14478)
		(layer "In2.Cu")
		(net "M_I_CPU0_SA_CB<6>")
	)
	(segment
		(start 425.902374 -241.670332)
		(end 426.163994 -241.670332)
		(width 0.14478)
		(layer "In2.Cu")
		(net "M_I_CPU0_SA_CB<6>")
	)
	(segment
		(start 414.282382 -243.660168)
		(end 414.510728 -243.660168)
		(width 0.14478)
		(layer "In2.Cu")
		(net "M_I_CPU0_SA_CB<6>")
	)
	(segment
		(start 418.189156 -243.033296)
		(end 418.3507 -242.871752)
		(width 0.14478)
		(layer "In2.Cu")
		(net "M_I_CPU0_SA_CB<6>")
	)
	(segment
		(start 393.779248 -248.72061)
		(end 395.910054 -248.72061)
		(width 0.0889)
		(layer "In2.Cu")
		(net "M_I_CPU0_SA_CB<6>")
	)
	(segment
		(start 417.247832 -242.871752)
		(end 417.476178 -242.871752)
		(width 0.14478)
		(layer "In2.Cu")
		(net "M_I_CPU0_SA_CB<6>")
	)
	(segment
		(start 413.569404 -243.498624)
		(end 413.569404 -242.626896)
		(width 0.14478)
		(layer "In2.Cu")
		(net "M_I_CPU0_SA_CB<6>")
	)
	(segment
		(start 417.476178 -242.871752)
		(end 417.637722 -243.033296)
		(width 0.14478)
		(layer "In2.Cu")
		(net "M_I_CPU0_SA_CB<6>")
	)
	(segment
		(start 381.983488 -248.206768)
		(end 381.99187 -248.211594)
		(width 0.0889)
		(layer "In2.Cu")
		(net "M_I_CPU0_SA_CB<6>")
	)
	(segment
		(start 420.810182 -243.660168)
		(end 422.510204 -241.960146)
		(width 0.14478)
		(layer "In2.Cu")
		(net "M_I_CPU0_SA_CB<6>")
	)
	(segment
		(start 415.38525 -243.660168)
		(end 416.924744 -243.660168)
		(width 0.14478)
		(layer "In2.Cu")
		(net "M_I_CPU0_SA_CB<6>")
	)
	(segment
		(start 391.01776 -248.211594)
		(end 391.026142 -248.206768)
		(width 0.0889)
		(layer "In2.Cu")
		(net "M_I_CPU0_SA_CB<6>")
	)
	(segment
		(start 414.510728 -243.660168)
		(end 414.672272 -243.498624)
		(width 0.14478)
		(layer "In2.Cu")
		(net "M_I_CPU0_SA_CB<6>")
	)
	(segment
		(start 425.061126 -241.670332)
		(end 425.35094 -241.960146)
		(width 0.14478)
		(layer "In2.Cu")
		(net "M_I_CPU0_SA_CB<6>")
	)
	(segment
		(start 413.959294 -242.465352)
		(end 414.120838 -242.626896)
		(width 0.14478)
		(layer "In2.Cu")
		(net "M_I_CPU0_SA_CB<6>")
	)
	(arc
		(start 381.99187 -248.211594)
		(mid 382.274826 -248.287771)
		(end 382.557782 -248.211594)
		(width 0.0889)
		(layer "In2.Cu")
		(net "M_I_CPU0_SA_CB<6>")
	)
	(arc
		(start 391.026142 -248.206768)
		(mid 391.20965 -248.161274)
		(end 391.391902 -248.211594)
		(width 0.0889)
		(layer "In2.Cu")
		(net "M_I_CPU0_SA_CB<6>")
	)
	(arc
		(start 379.171962 -248.211594)
		(mid 379.454918 -248.287771)
		(end 379.737874 -248.211594)
		(width 0.0889)
		(layer "In2.Cu")
		(net "M_I_CPU0_SA_CB<6>")
	)
	(arc
		(start 383.871978 -248.211594)
		(mid 384.154934 -248.287771)
		(end 384.43789 -248.211594)
		(width 0.0889)
		(layer "In2.Cu")
		(net "M_I_CPU0_SA_CB<6>")
	)
	(arc
		(start 384.43789 -248.211594)
		(mid 384.624834 -248.161339)
		(end 384.811778 -248.211594)
		(width 0.0889)
		(layer "In2.Cu")
		(net "M_I_CPU0_SA_CB<6>")
	)
	(arc
		(start 382.931924 -248.211594)
		(mid 383.21488 -248.287771)
		(end 383.497836 -248.211594)
		(width 0.0889)
		(layer "In2.Cu")
		(net "M_I_CPU0_SA_CB<6>")
	)
	(arc
		(start 377.866148 -248.206768)
		(mid 378.049656 -248.161274)
		(end 378.231908 -248.211594)
		(width 0.0889)
		(layer "In2.Cu")
		(net "M_I_CPU0_SA_CB<6>")
	)
	(arc
		(start 383.506218 -248.206768)
		(mid 383.689726 -248.161274)
		(end 383.871978 -248.211594)
		(width 0.0889)
		(layer "In2.Cu")
		(net "M_I_CPU0_SA_CB<6>")
	)
	(arc
		(start 391.97788 -248.199402)
		(mid 392.154808 -248.161574)
		(end 392.328654 -248.211594)
		(width 0.0889)
		(layer "In2.Cu")
		(net "M_I_CPU0_SA_CB<6>")
	)
	(arc
		(start 384.811778 -248.211594)
		(mid 385.094734 -248.287771)
		(end 385.37769 -248.211594)
		(width 0.0889)
		(layer "In2.Cu")
		(net "M_I_CPU0_SA_CB<6>")
	)
	(arc
		(start 389.511794 -248.211594)
		(mid 389.79475 -248.287771)
		(end 390.077706 -248.211594)
		(width 0.0889)
		(layer "In2.Cu")
		(net "M_I_CPU0_SA_CB<6>")
	)
	(arc
		(start 390.451848 -248.211594)
		(mid 390.734804 -248.287771)
		(end 391.01776 -248.211594)
		(width 0.0889)
		(layer "In2.Cu")
		(net "M_I_CPU0_SA_CB<6>")
	)
	(arc
		(start 387.26618 -248.206768)
		(mid 387.449688 -248.161274)
		(end 387.63194 -248.211594)
		(width 0.0889)
		(layer "In2.Cu")
		(net "M_I_CPU0_SA_CB<6>")
	)
	(arc
		(start 388.571994 -248.211594)
		(mid 388.85495 -248.287771)
		(end 389.137906 -248.211594)
		(width 0.0889)
		(layer "In2.Cu")
		(net "M_I_CPU0_SA_CB<6>")
	)
	(arc
		(start 380.111762 -248.211594)
		(mid 380.394718 -248.287771)
		(end 380.677674 -248.211594)
		(width 0.0889)
		(layer "In2.Cu")
		(net "M_I_CPU0_SA_CB<6>")
	)
	(arc
		(start 381.617728 -248.211594)
		(mid 381.799979 -248.161244)
		(end 381.983488 -248.206768)
		(width 0.0889)
		(layer "In2.Cu")
		(net "M_I_CPU0_SA_CB<6>")
	)
	(arc
		(start 378.231908 -248.211594)
		(mid 378.514864 -248.287771)
		(end 378.79782 -248.211594)
		(width 0.0889)
		(layer "In2.Cu")
		(net "M_I_CPU0_SA_CB<6>")
	)
	(arc
		(start 387.63194 -248.211594)
		(mid 387.914896 -248.287771)
		(end 388.197852 -248.211594)
		(width 0.0889)
		(layer "In2.Cu")
		(net "M_I_CPU0_SA_CB<6>")
	)
	(arc
		(start 385.37769 -248.211594)
		(mid 385.559941 -248.161244)
		(end 385.74345 -248.206768)
		(width 0.0889)
		(layer "In2.Cu")
		(net "M_I_CPU0_SA_CB<6>")
	)
	(arc
		(start 390.077706 -248.211594)
		(mid 390.259957 -248.161244)
		(end 390.443466 -248.206768)
		(width 0.0889)
		(layer "In2.Cu")
		(net "M_I_CPU0_SA_CB<6>")
	)
	(arc
		(start 385.751832 -248.211594)
		(mid 386.034788 -248.287771)
		(end 386.317744 -248.211594)
		(width 0.0889)
		(layer "In2.Cu")
		(net "M_I_CPU0_SA_CB<6>")
	)
	(arc
		(start 386.691886 -248.211594)
		(mid 386.974842 -248.287771)
		(end 387.257798 -248.211594)
		(width 0.0889)
		(layer "In2.Cu")
		(net "M_I_CPU0_SA_CB<6>")
	)
	(arc
		(start 388.206234 -248.206768)
		(mid 388.389742 -248.161274)
		(end 388.571994 -248.211594)
		(width 0.0889)
		(layer "In2.Cu")
		(net "M_I_CPU0_SA_CB<6>")
	)
	(arc
		(start 377.354846 -248.243344)
		(mid 377.610054 -248.286821)
		(end 377.857766 -248.211594)
		(width 0.0889)
		(layer "In2.Cu")
		(net "M_I_CPU0_SA_CB<6>")
	)
	(arc
		(start 386.317744 -248.211594)
		(mid 386.499995 -248.161244)
		(end 386.683504 -248.206768)
		(width 0.0889)
		(layer "In2.Cu")
		(net "M_I_CPU0_SA_CB<6>")
	)
	(arc
		(start 380.677674 -248.211594)
		(mid 380.859925 -248.161244)
		(end 381.043434 -248.206768)
		(width 0.0889)
		(layer "In2.Cu")
		(net "M_I_CPU0_SA_CB<6>")
	)
	(arc
		(start 389.137906 -248.211594)
		(mid 389.32485 -248.161339)
		(end 389.511794 -248.211594)
		(width 0.0889)
		(layer "In2.Cu")
		(net "M_I_CPU0_SA_CB<6>")
	)
	(arc
		(start 382.566164 -248.206768)
		(mid 382.749672 -248.161274)
		(end 382.931924 -248.211594)
		(width 0.0889)
		(layer "In2.Cu")
		(net "M_I_CPU0_SA_CB<6>")
	)
	(arc
		(start 392.896344 -248.211594)
		(mid 393.066351 -248.161029)
		(end 393.240514 -248.194576)
		(width 0.0889)
		(layer "In2.Cu")
		(net "M_I_CPU0_SA_CB<6>")
	)
	(arc
		(start 378.806202 -248.206768)
		(mid 378.98971 -248.161274)
		(end 379.171962 -248.211594)
		(width 0.0889)
		(layer "In2.Cu")
		(net "M_I_CPU0_SA_CB<6>")
	)
	(arc
		(start 392.35634 -248.227596)
		(mid 392.628374 -248.288368)
		(end 392.896344 -248.211594)
		(width 0.0889)
		(layer "In2.Cu")
		(net "M_I_CPU0_SA_CB<6>")
	)
	(arc
		(start 391.391902 -248.211594)
		(mid 391.660222 -248.287702)
		(end 391.93216 -248.225818)
		(width 0.0889)
		(layer "In2.Cu")
		(net "M_I_CPU0_SA_CB<6>")
	)
	(arc
		(start 379.737874 -248.211594)
		(mid 379.924818 -248.161339)
		(end 380.111762 -248.211594)
		(width 0.0889)
		(layer "In2.Cu")
		(net "M_I_CPU0_SA_CB<6>")
	)
	(arc
		(start 381.051816 -248.211594)
		(mid 381.334772 -248.287771)
		(end 381.617728 -248.211594)
		(width 0.0889)
		(layer "In2.Cu")
		(net "M_I_CPU0_SA_CB<6>")
	)
	(segment
		(start 375.698004 -248.800112)
		(end 376.164856 -248.534174)
		(width 0.10668)
		(layer "F.Cu")
		(net "M_I_CPU0_SA_CB<5>")
	)
	(segment
		(start 381.983488 -248.86158)
		(end 381.99187 -248.856754)
		(width 0.0889)
		(layer "In2.Cu")
		(net "M_I_CPU0_SA_CB<5>")
	)
	(segment
		(start 428.488856 -242.81003)
		(end 428.6504 -242.648486)
		(width 0.14478)
		(layer "In2.Cu")
		(net "M_I_CPU0_SA_CB<5>")
	)
	(segment
		(start 395.910054 -249.18035)
		(end 396.754096 -249.18035)
		(width 0.14478)
		(layer "In2.Cu")
		(net "M_I_CPU0_SA_CB<5>")
	)
	(segment
		(start 377.857766 -248.856754)
		(end 377.866148 -248.86158)
		(width 0.0889)
		(layer "In2.Cu")
		(net "M_I_CPU0_SA_CB<5>")
	)
	(segment
		(start 431.131218 -242.81003)
		(end 431.55616 -242.385088)
		(width 0.14478)
		(layer "In2.Cu")
		(net "M_I_CPU0_SA_CB<5>")
	)
	(segment
		(start 429.363378 -242.81003)
		(end 429.591724 -242.81003)
		(width 0.14478)
		(layer "In2.Cu")
		(net "M_I_CPU0_SA_CB<5>")
	)
	(segment
		(start 381.043434 -248.86158)
		(end 381.051816 -248.856754)
		(width 0.0889)
		(layer "In2.Cu")
		(net "M_I_CPU0_SA_CB<5>")
	)
	(segment
		(start 396.754096 -249.18035)
		(end 397.507714 -248.426732)
		(width 0.14478)
		(layer "In2.Cu")
		(net "M_I_CPU0_SA_CB<5>")
	)
	(segment
		(start 387.257798 -248.856754)
		(end 387.26618 -248.86158)
		(width 0.0889)
		(layer "In2.Cu")
		(net "M_I_CPU0_SA_CB<5>")
	)
	(segment
		(start 393.506706 -249.021092)
		(end 395.055598 -249.021092)
		(width 0.0889)
		(layer "In2.Cu")
		(net "M_I_CPU0_SA_CB<5>")
	)
	(segment
		(start 392.321034 -248.863612)
		(end 392.332718 -248.856754)
		(width 0.0889)
		(layer "In2.Cu")
		(net "M_I_CPU0_SA_CB<5>")
	)
	(segment
		(start 392.892534 -248.853198)
		(end 392.898122 -248.8565)
		(width 0.0889)
		(layer "In2.Cu")
		(net "M_I_CPU0_SA_CB<5>")
	)
	(segment
		(start 422.354756 -242.81003)
		(end 428.488856 -242.81003)
		(width 0.14478)
		(layer "In2.Cu")
		(net "M_I_CPU0_SA_CB<5>")
	)
	(segment
		(start 377.283472 -248.86158)
		(end 377.291854 -248.856754)
		(width 0.0889)
		(layer "In2.Cu")
		(net "M_I_CPU0_SA_CB<5>")
	)
	(segment
		(start 430.304702 -242.648486)
		(end 430.466246 -242.81003)
		(width 0.14478)
		(layer "In2.Cu")
		(net "M_I_CPU0_SA_CB<5>")
	)
	(segment
		(start 430.304702 -242.263676)
		(end 430.304702 -242.648486)
		(width 0.14478)
		(layer "In2.Cu")
		(net "M_I_CPU0_SA_CB<5>")
	)
	(segment
		(start 388.197852 -248.856754)
		(end 388.206234 -248.86158)
		(width 0.0889)
		(layer "In2.Cu")
		(net "M_I_CPU0_SA_CB<5>")
	)
	(segment
		(start 386.683504 -248.86158)
		(end 386.691886 -248.856754)
		(width 0.0889)
		(layer "In2.Cu")
		(net "M_I_CPU0_SA_CB<5>")
	)
	(segment
		(start 429.753268 -242.648486)
		(end 429.753268 -242.263676)
		(width 0.14478)
		(layer "In2.Cu")
		(net "M_I_CPU0_SA_CB<5>")
	)
	(segment
		(start 390.443466 -248.86158)
		(end 390.451848 -248.856754)
		(width 0.0889)
		(layer "In2.Cu")
		(net "M_I_CPU0_SA_CB<5>")
	)
	(segment
		(start 376.343418 -248.86158)
		(end 376.3518 -248.856754)
		(width 0.0889)
		(layer "In2.Cu")
		(net "M_I_CPU0_SA_CB<5>")
	)
	(segment
		(start 428.6504 -242.648486)
		(end 428.6504 -242.263676)
		(width 0.14478)
		(layer "In2.Cu")
		(net "M_I_CPU0_SA_CB<5>")
	)
	(segment
		(start 385.74345 -248.86158)
		(end 385.751832 -248.856754)
		(width 0.0889)
		(layer "In2.Cu")
		(net "M_I_CPU0_SA_CB<5>")
	)
	(segment
		(start 391.391902 -248.856754)
		(end 391.406634 -248.848118)
		(width 0.0889)
		(layer "In2.Cu")
		(net "M_I_CPU0_SA_CB<5>")
	)
	(segment
		(start 391.01776 -248.856754)
		(end 391.026142 -248.86158)
		(width 0.0889)
		(layer "In2.Cu")
		(net "M_I_CPU0_SA_CB<5>")
	)
	(segment
		(start 383.497836 -248.856754)
		(end 383.506218 -248.86158)
		(width 0.0889)
		(layer "In2.Cu")
		(net "M_I_CPU0_SA_CB<5>")
	)
	(segment
		(start 429.753268 -242.263676)
		(end 429.914812 -242.102132)
		(width 0.14478)
		(layer "In2.Cu")
		(net "M_I_CPU0_SA_CB<5>")
	)
	(segment
		(start 395.055598 -249.021092)
		(end 395.214856 -249.18035)
		(width 0.0889)
		(layer "In2.Cu")
		(net "M_I_CPU0_SA_CB<5>")
	)
	(segment
		(start 407.573226 -248.426732)
		(end 411.480254 -244.519704)
		(width 0.14478)
		(layer "In2.Cu")
		(net "M_I_CPU0_SA_CB<5>")
	)
	(segment
		(start 429.201834 -242.263676)
		(end 429.201834 -242.648486)
		(width 0.14478)
		(layer "In2.Cu")
		(net "M_I_CPU0_SA_CB<5>")
	)
	(segment
		(start 428.811944 -242.102132)
		(end 429.04029 -242.102132)
		(width 0.14478)
		(layer "In2.Cu")
		(net "M_I_CPU0_SA_CB<5>")
	)
	(segment
		(start 429.914812 -242.102132)
		(end 430.143158 -242.102132)
		(width 0.14478)
		(layer "In2.Cu")
		(net "M_I_CPU0_SA_CB<5>")
	)
	(segment
		(start 411.480254 -244.519704)
		(end 420.645082 -244.519704)
		(width 0.14478)
		(layer "In2.Cu")
		(net "M_I_CPU0_SA_CB<5>")
	)
	(segment
		(start 429.201834 -242.648486)
		(end 429.363378 -242.81003)
		(width 0.14478)
		(layer "In2.Cu")
		(net "M_I_CPU0_SA_CB<5>")
	)
	(segment
		(start 376.010678 -248.799604)
		(end 376.03303 -248.882916)
		(width 0.0889)
		(layer "In2.Cu")
		(net "M_I_CPU0_SA_CB<5>")
	)
	(segment
		(start 429.04029 -242.102132)
		(end 429.201834 -242.263676)
		(width 0.14478)
		(layer "In2.Cu")
		(net "M_I_CPU0_SA_CB<5>")
	)
	(segment
		(start 376.164856 -248.534174)
		(end 376.010678 -248.799604)
		(width 0.0889)
		(layer "In2.Cu")
		(net "M_I_CPU0_SA_CB<5>")
	)
	(segment
		(start 395.214856 -249.18035)
		(end 395.910054 -249.18035)
		(width 0.0889)
		(layer "In2.Cu")
		(net "M_I_CPU0_SA_CB<5>")
	)
	(segment
		(start 430.466246 -242.81003)
		(end 431.131218 -242.81003)
		(width 0.14478)
		(layer "In2.Cu")
		(net "M_I_CPU0_SA_CB<5>")
	)
	(segment
		(start 429.591724 -242.81003)
		(end 429.753268 -242.648486)
		(width 0.14478)
		(layer "In2.Cu")
		(net "M_I_CPU0_SA_CB<5>")
	)
	(segment
		(start 430.143158 -242.102132)
		(end 430.304702 -242.263676)
		(width 0.14478)
		(layer "In2.Cu")
		(net "M_I_CPU0_SA_CB<5>")
	)
	(segment
		(start 382.557782 -248.856754)
		(end 382.566164 -248.86158)
		(width 0.0889)
		(layer "In2.Cu")
		(net "M_I_CPU0_SA_CB<5>")
	)
	(segment
		(start 397.507714 -248.426732)
		(end 407.573226 -248.426732)
		(width 0.14478)
		(layer "In2.Cu")
		(net "M_I_CPU0_SA_CB<5>")
	)
	(segment
		(start 378.79782 -248.856754)
		(end 378.806202 -248.86158)
		(width 0.0889)
		(layer "In2.Cu")
		(net "M_I_CPU0_SA_CB<5>")
	)
	(segment
		(start 428.6504 -242.263676)
		(end 428.811944 -242.102132)
		(width 0.14478)
		(layer "In2.Cu")
		(net "M_I_CPU0_SA_CB<5>")
	)
	(segment
		(start 420.645082 -244.519704)
		(end 422.354756 -242.81003)
		(width 0.14478)
		(layer "In2.Cu")
		(net "M_I_CPU0_SA_CB<5>")
	)
	(arc
		(start 390.451848 -248.856754)
		(mid 390.734804 -248.780577)
		(end 391.01776 -248.856754)
		(width 0.0889)
		(layer "In2.Cu")
		(net "M_I_CPU0_SA_CB<5>")
	)
	(arc
		(start 389.137906 -248.856754)
		(mid 389.32485 -248.907009)
		(end 389.511794 -248.856754)
		(width 0.0889)
		(layer "In2.Cu")
		(net "M_I_CPU0_SA_CB<5>")
	)
	(arc
		(start 380.677674 -248.856754)
		(mid 380.859925 -248.907104)
		(end 381.043434 -248.86158)
		(width 0.0889)
		(layer "In2.Cu")
		(net "M_I_CPU0_SA_CB<5>")
	)
	(arc
		(start 392.898122 -248.8565)
		(mid 393.191488 -248.979183)
		(end 393.506706 -249.021092)
		(width 0.0889)
		(layer "In2.Cu")
		(net "M_I_CPU0_SA_CB<5>")
	)
	(arc
		(start 376.917712 -248.856754)
		(mid 377.099963 -248.907104)
		(end 377.283472 -248.86158)
		(width 0.0889)
		(layer "In2.Cu")
		(net "M_I_CPU0_SA_CB<5>")
	)
	(arc
		(start 384.811778 -248.856754)
		(mid 385.094734 -248.780577)
		(end 385.37769 -248.856754)
		(width 0.0889)
		(layer "In2.Cu")
		(net "M_I_CPU0_SA_CB<5>")
	)
	(arc
		(start 380.111762 -248.856754)
		(mid 380.394718 -248.780577)
		(end 380.677674 -248.856754)
		(width 0.0889)
		(layer "In2.Cu")
		(net "M_I_CPU0_SA_CB<5>")
	)
	(arc
		(start 377.866148 -248.86158)
		(mid 378.049656 -248.907074)
		(end 378.231908 -248.856754)
		(width 0.0889)
		(layer "In2.Cu")
		(net "M_I_CPU0_SA_CB<5>")
	)
	(arc
		(start 385.751832 -248.856754)
		(mid 386.034788 -248.780577)
		(end 386.317744 -248.856754)
		(width 0.0889)
		(layer "In2.Cu")
		(net "M_I_CPU0_SA_CB<5>")
	)
	(arc
		(start 383.506218 -248.86158)
		(mid 383.689726 -248.907074)
		(end 383.871978 -248.856754)
		(width 0.0889)
		(layer "In2.Cu")
		(net "M_I_CPU0_SA_CB<5>")
	)
	(arc
		(start 384.43789 -248.856754)
		(mid 384.624834 -248.907009)
		(end 384.811778 -248.856754)
		(width 0.0889)
		(layer "In2.Cu")
		(net "M_I_CPU0_SA_CB<5>")
	)
	(arc
		(start 386.317744 -248.856754)
		(mid 386.499995 -248.907104)
		(end 386.683504 -248.86158)
		(width 0.0889)
		(layer "In2.Cu")
		(net "M_I_CPU0_SA_CB<5>")
	)
	(arc
		(start 386.691886 -248.856754)
		(mid 386.974842 -248.780577)
		(end 387.257798 -248.856754)
		(width 0.0889)
		(layer "In2.Cu")
		(net "M_I_CPU0_SA_CB<5>")
	)
	(arc
		(start 390.077706 -248.856754)
		(mid 390.259957 -248.907104)
		(end 390.443466 -248.86158)
		(width 0.0889)
		(layer "In2.Cu")
		(net "M_I_CPU0_SA_CB<5>")
	)
	(arc
		(start 389.511794 -248.856754)
		(mid 389.79475 -248.780577)
		(end 390.077706 -248.856754)
		(width 0.0889)
		(layer "In2.Cu")
		(net "M_I_CPU0_SA_CB<5>")
	)
	(arc
		(start 382.566164 -248.86158)
		(mid 382.749672 -248.907074)
		(end 382.931924 -248.856754)
		(width 0.0889)
		(layer "In2.Cu")
		(net "M_I_CPU0_SA_CB<5>")
	)
	(arc
		(start 381.99187 -248.856754)
		(mid 382.274826 -248.780577)
		(end 382.557782 -248.856754)
		(width 0.0889)
		(layer "In2.Cu")
		(net "M_I_CPU0_SA_CB<5>")
	)
	(arc
		(start 376.03303 -248.882916)
		(mid 376.19054 -248.906114)
		(end 376.343418 -248.86158)
		(width 0.0889)
		(layer "In2.Cu")
		(net "M_I_CPU0_SA_CB<5>")
	)
	(arc
		(start 391.958322 -248.856754)
		(mid 392.13878 -248.907198)
		(end 392.321034 -248.863612)
		(width 0.0889)
		(layer "In2.Cu")
		(net "M_I_CPU0_SA_CB<5>")
	)
	(arc
		(start 378.806202 -248.86158)
		(mid 378.98971 -248.907074)
		(end 379.171962 -248.856754)
		(width 0.0889)
		(layer "In2.Cu")
		(net "M_I_CPU0_SA_CB<5>")
	)
	(arc
		(start 388.206234 -248.86158)
		(mid 388.389742 -248.907074)
		(end 388.571994 -248.856754)
		(width 0.0889)
		(layer "In2.Cu")
		(net "M_I_CPU0_SA_CB<5>")
	)
	(arc
		(start 378.231908 -248.856754)
		(mid 378.514864 -248.780577)
		(end 378.79782 -248.856754)
		(width 0.0889)
		(layer "In2.Cu")
		(net "M_I_CPU0_SA_CB<5>")
	)
	(arc
		(start 392.332718 -248.856754)
		(mid 392.612146 -248.780588)
		(end 392.892534 -248.853198)
		(width 0.0889)
		(layer "In2.Cu")
		(net "M_I_CPU0_SA_CB<5>")
	)
	(arc
		(start 381.051816 -248.856754)
		(mid 381.334772 -248.780577)
		(end 381.617728 -248.856754)
		(width 0.0889)
		(layer "In2.Cu")
		(net "M_I_CPU0_SA_CB<5>")
	)
	(arc
		(start 391.026142 -248.86158)
		(mid 391.20965 -248.907074)
		(end 391.391902 -248.856754)
		(width 0.0889)
		(layer "In2.Cu")
		(net "M_I_CPU0_SA_CB<5>")
	)
	(arc
		(start 388.571994 -248.856754)
		(mid 388.85495 -248.780577)
		(end 389.137906 -248.856754)
		(width 0.0889)
		(layer "In2.Cu")
		(net "M_I_CPU0_SA_CB<5>")
	)
	(arc
		(start 379.737874 -248.856754)
		(mid 379.924818 -248.907009)
		(end 380.111762 -248.856754)
		(width 0.0889)
		(layer "In2.Cu")
		(net "M_I_CPU0_SA_CB<5>")
	)
	(arc
		(start 385.37769 -248.856754)
		(mid 385.559941 -248.907104)
		(end 385.74345 -248.86158)
		(width 0.0889)
		(layer "In2.Cu")
		(net "M_I_CPU0_SA_CB<5>")
	)
	(arc
		(start 383.871978 -248.856754)
		(mid 384.154934 -248.780577)
		(end 384.43789 -248.856754)
		(width 0.0889)
		(layer "In2.Cu")
		(net "M_I_CPU0_SA_CB<5>")
	)
	(arc
		(start 382.931924 -248.856754)
		(mid 383.21488 -248.780577)
		(end 383.497836 -248.856754)
		(width 0.0889)
		(layer "In2.Cu")
		(net "M_I_CPU0_SA_CB<5>")
	)
	(arc
		(start 376.3518 -248.856754)
		(mid 376.634756 -248.780577)
		(end 376.917712 -248.856754)
		(width 0.0889)
		(layer "In2.Cu")
		(net "M_I_CPU0_SA_CB<5>")
	)
	(arc
		(start 377.291854 -248.856754)
		(mid 377.57481 -248.780577)
		(end 377.857766 -248.856754)
		(width 0.0889)
		(layer "In2.Cu")
		(net "M_I_CPU0_SA_CB<5>")
	)
	(arc
		(start 387.63194 -248.856754)
		(mid 387.914896 -248.780577)
		(end 388.197852 -248.856754)
		(width 0.0889)
		(layer "In2.Cu")
		(net "M_I_CPU0_SA_CB<5>")
	)
	(arc
		(start 381.617728 -248.856754)
		(mid 381.799979 -248.907104)
		(end 381.983488 -248.86158)
		(width 0.0889)
		(layer "In2.Cu")
		(net "M_I_CPU0_SA_CB<5>")
	)
	(arc
		(start 391.406634 -248.848118)
		(mid 391.683617 -248.780314)
		(end 391.958322 -248.856754)
		(width 0.0889)
		(layer "In2.Cu")
		(net "M_I_CPU0_SA_CB<5>")
	)
	(arc
		(start 379.171962 -248.856754)
		(mid 379.454918 -248.780577)
		(end 379.737874 -248.856754)
		(width 0.0889)
		(layer "In2.Cu")
		(net "M_I_CPU0_SA_CB<5>")
	)
	(arc
		(start 387.26618 -248.86158)
		(mid 387.449688 -248.907074)
		(end 387.63194 -248.856754)
		(width 0.0889)
		(layer "In2.Cu")
		(net "M_I_CPU0_SA_CB<5>")
	)
	(segment
		(start 377.107958 -247.990106)
		(end 377.57481 -247.724168)
		(width 0.10668)
		(layer "F.Cu")
		(net "M_I_CPU0_SA_CB<4>")
	)
	(segment
		(start 407.220166 -247.50776)
		(end 411.418278 -243.309648)
		(width 0.14478)
		(layer "In2.Cu")
		(net "M_I_CPU0_SA_CB<4>")
	)
	(segment
		(start 395.859254 -248.26087)
		(end 396.370556 -248.26087)
		(width 0.14478)
		(layer "In2.Cu")
		(net "M_I_CPU0_SA_CB<4>")
	)
	(segment
		(start 414.519364 -241.959892)
		(end 414.74771 -241.959892)
		(width 0.14478)
		(layer "In2.Cu")
		(net "M_I_CPU0_SA_CB<4>")
	)
	(segment
		(start 392.424666 -248.046748)
		(end 392.44524 -248.058686)
		(width 0.0889)
		(layer "In2.Cu")
		(net "M_I_CPU0_SA_CB<4>")
	)
	(segment
		(start 431.131218 -241.110008)
		(end 431.55616 -240.685066)
		(width 0.14478)
		(layer "In2.Cu")
		(net "M_I_CPU0_SA_CB<4>")
	)
	(segment
		(start 422.073324 -241.110008)
		(end 431.131218 -241.110008)
		(width 0.14478)
		(layer "In2.Cu")
		(net "M_I_CPU0_SA_CB<4>")
	)
	(segment
		(start 413.806386 -241.798348)
		(end 413.806386 -241.356896)
		(width 0.14478)
		(layer "In2.Cu")
		(net "M_I_CPU0_SA_CB<4>")
	)
	(segment
		(start 383.393442 -248.051574)
		(end 383.401824 -248.046748)
		(width 0.0889)
		(layer "In2.Cu")
		(net "M_I_CPU0_SA_CB<4>")
	)
	(segment
		(start 413.806386 -241.356896)
		(end 413.96793 -241.195352)
		(width 0.14478)
		(layer "In2.Cu")
		(net "M_I_CPU0_SA_CB<4>")
	)
	(segment
		(start 395.2621 -248.36501)
		(end 395.36624 -248.26087)
		(width 0.0889)
		(layer "In2.Cu")
		(net "M_I_CPU0_SA_CB<4>")
	)
	(segment
		(start 378.693426 -248.051574)
		(end 378.701808 -248.046748)
		(width 0.0889)
		(layer "In2.Cu")
		(net "M_I_CPU0_SA_CB<4>")
	)
	(segment
		(start 391.860532 -248.046494)
		(end 391.884408 -248.032524)
		(width 0.0889)
		(layer "In2.Cu")
		(net "M_I_CPU0_SA_CB<4>")
	)
	(segment
		(start 422.070784 -241.107468)
		(end 422.073324 -241.110008)
		(width 0.14478)
		(layer "In2.Cu")
		(net "M_I_CPU0_SA_CB<4>")
	)
	(segment
		(start 414.35782 -241.798348)
		(end 414.519364 -241.959892)
		(width 0.14478)
		(layer "In2.Cu")
		(net "M_I_CPU0_SA_CB<4>")
	)
	(segment
		(start 384.333496 -248.051574)
		(end 384.341878 -248.046748)
		(width 0.0889)
		(layer "In2.Cu")
		(net "M_I_CPU0_SA_CB<4>")
	)
	(segment
		(start 413.96793 -241.195352)
		(end 414.196276 -241.195352)
		(width 0.14478)
		(layer "In2.Cu")
		(net "M_I_CPU0_SA_CB<4>")
	)
	(segment
		(start 421.21836 -241.959892)
		(end 422.070784 -241.107468)
		(width 0.14478)
		(layer "In2.Cu")
		(net "M_I_CPU0_SA_CB<4>")
	)
	(segment
		(start 384.90779 -248.046748)
		(end 384.916172 -248.051574)
		(width 0.0889)
		(layer "In2.Cu")
		(net "M_I_CPU0_SA_CB<4>")
	)
	(segment
		(start 394.55217 -248.36501)
		(end 395.2621 -248.36501)
		(width 0.0889)
		(layer "In2.Cu")
		(net "M_I_CPU0_SA_CB<4>")
	)
	(segment
		(start 414.909254 -241.356896)
		(end 415.070798 -241.195352)
		(width 0.14478)
		(layer "In2.Cu")
		(net "M_I_CPU0_SA_CB<4>")
	)
	(segment
		(start 415.460688 -241.356896)
		(end 415.460688 -241.798348)
		(width 0.14478)
		(layer "In2.Cu")
		(net "M_I_CPU0_SA_CB<4>")
	)
	(segment
		(start 395.36624 -248.26087)
		(end 395.859254 -248.26087)
		(width 0.0889)
		(layer "In2.Cu")
		(net "M_I_CPU0_SA_CB<4>")
	)
	(segment
		(start 414.74771 -241.959892)
		(end 414.909254 -241.798348)
		(width 0.14478)
		(layer "In2.Cu")
		(net "M_I_CPU0_SA_CB<4>")
	)
	(segment
		(start 415.299144 -241.195352)
		(end 415.460688 -241.356896)
		(width 0.14478)
		(layer "In2.Cu")
		(net "M_I_CPU0_SA_CB<4>")
	)
	(segment
		(start 389.033512 -248.051574)
		(end 389.041894 -248.046748)
		(width 0.0889)
		(layer "In2.Cu")
		(net "M_I_CPU0_SA_CB<4>")
	)
	(segment
		(start 415.622232 -241.959892)
		(end 421.21836 -241.959892)
		(width 0.14478)
		(layer "In2.Cu")
		(net "M_I_CPU0_SA_CB<4>")
	)
	(segment
		(start 415.070798 -241.195352)
		(end 415.299144 -241.195352)
		(width 0.14478)
		(layer "In2.Cu")
		(net "M_I_CPU0_SA_CB<4>")
	)
	(segment
		(start 411.904942 -241.959892)
		(end 413.644842 -241.959892)
		(width 0.14478)
		(layer "In2.Cu")
		(net "M_I_CPU0_SA_CB<4>")
	)
	(segment
		(start 415.460688 -241.798348)
		(end 415.622232 -241.959892)
		(width 0.14478)
		(layer "In2.Cu")
		(net "M_I_CPU0_SA_CB<4>")
	)
	(segment
		(start 385.847844 -248.046748)
		(end 385.856226 -248.051574)
		(width 0.0889)
		(layer "In2.Cu")
		(net "M_I_CPU0_SA_CB<4>")
	)
	(segment
		(start 381.147828 -248.046748)
		(end 381.15621 -248.051574)
		(width 0.0889)
		(layer "In2.Cu")
		(net "M_I_CPU0_SA_CB<4>")
	)
	(segment
		(start 414.909254 -241.798348)
		(end 414.909254 -241.356896)
		(width 0.14478)
		(layer "In2.Cu")
		(net "M_I_CPU0_SA_CB<4>")
	)
	(segment
		(start 397.123666 -247.50776)
		(end 407.220166 -247.50776)
		(width 0.14478)
		(layer "In2.Cu")
		(net "M_I_CPU0_SA_CB<4>")
	)
	(segment
		(start 379.63348 -248.051574)
		(end 379.641862 -248.046748)
		(width 0.0889)
		(layer "In2.Cu")
		(net "M_I_CPU0_SA_CB<4>")
	)
	(segment
		(start 414.196276 -241.195352)
		(end 414.35782 -241.356896)
		(width 0.14478)
		(layer "In2.Cu")
		(net "M_I_CPU0_SA_CB<4>")
	)
	(segment
		(start 377.420886 -247.989598)
		(end 377.443238 -248.07291)
		(width 0.0889)
		(layer "In2.Cu")
		(net "M_I_CPU0_SA_CB<4>")
	)
	(segment
		(start 377.57481 -247.724168)
		(end 377.420886 -247.989598)
		(width 0.0889)
		(layer "In2.Cu")
		(net "M_I_CPU0_SA_CB<4>")
	)
	(segment
		(start 414.35782 -241.356896)
		(end 414.35782 -241.798348)
		(width 0.14478)
		(layer "In2.Cu")
		(net "M_I_CPU0_SA_CB<4>")
	)
	(segment
		(start 380.207774 -248.046748)
		(end 380.216156 -248.051574)
		(width 0.0889)
		(layer "In2.Cu")
		(net "M_I_CPU0_SA_CB<4>")
	)
	(segment
		(start 396.370556 -248.26087)
		(end 397.123666 -247.50776)
		(width 0.14478)
		(layer "In2.Cu")
		(net "M_I_CPU0_SA_CB<4>")
	)
	(segment
		(start 388.093458 -248.051574)
		(end 388.10184 -248.046748)
		(width 0.0889)
		(layer "In2.Cu")
		(net "M_I_CPU0_SA_CB<4>")
	)
	(segment
		(start 393.32789 -248.02465)
		(end 393.365736 -248.046494)
		(width 0.0889)
		(layer "In2.Cu")
		(net "M_I_CPU0_SA_CB<4>")
	)
	(segment
		(start 391.837164 -248.059956)
		(end 391.860532 -248.046494)
		(width 0.0889)
		(layer "In2.Cu")
		(net "M_I_CPU0_SA_CB<4>")
	)
	(segment
		(start 411.418278 -242.446556)
		(end 411.904942 -241.959892)
		(width 0.14478)
		(layer "In2.Cu")
		(net "M_I_CPU0_SA_CB<4>")
	)
	(segment
		(start 389.607806 -248.046748)
		(end 389.616188 -248.051574)
		(width 0.0889)
		(layer "In2.Cu")
		(net "M_I_CPU0_SA_CB<4>")
	)
	(segment
		(start 411.418278 -243.309648)
		(end 411.418278 -242.446556)
		(width 0.14478)
		(layer "In2.Cu")
		(net "M_I_CPU0_SA_CB<4>")
	)
	(segment
		(start 413.644842 -241.959892)
		(end 413.806386 -241.798348)
		(width 0.14478)
		(layer "In2.Cu")
		(net "M_I_CPU0_SA_CB<4>")
	)
	(arc
		(start 393.365736 -248.046494)
		(mid 393.93795 -248.283982)
		(end 394.55217 -248.36501)
		(width 0.0889)
		(layer "In2.Cu")
		(net "M_I_CPU0_SA_CB<4>")
	)
	(arc
		(start 392.44524 -248.058686)
		(mid 392.624168 -248.097563)
		(end 392.800078 -248.046748)
		(width 0.0889)
		(layer "In2.Cu")
		(net "M_I_CPU0_SA_CB<4>")
	)
	(arc
		(start 390.921748 -248.046748)
		(mid 391.204704 -247.970571)
		(end 391.48766 -248.046748)
		(width 0.0889)
		(layer "In2.Cu")
		(net "M_I_CPU0_SA_CB<4>")
	)
	(arc
		(start 385.856226 -248.051574)
		(mid 386.039734 -248.097068)
		(end 386.221986 -248.046748)
		(width 0.0889)
		(layer "In2.Cu")
		(net "M_I_CPU0_SA_CB<4>")
	)
	(arc
		(start 389.041894 -248.046748)
		(mid 389.32485 -247.970571)
		(end 389.607806 -248.046748)
		(width 0.0889)
		(layer "In2.Cu")
		(net "M_I_CPU0_SA_CB<4>")
	)
	(arc
		(start 378.701808 -248.046748)
		(mid 378.984764 -247.970571)
		(end 379.26772 -248.046748)
		(width 0.0889)
		(layer "In2.Cu")
		(net "M_I_CPU0_SA_CB<4>")
	)
	(arc
		(start 392.800078 -248.046748)
		(mid 393.061236 -247.970169)
		(end 393.32789 -248.02465)
		(width 0.0889)
		(layer "In2.Cu")
		(net "M_I_CPU0_SA_CB<4>")
	)
	(arc
		(start 380.216156 -248.051574)
		(mid 380.399664 -248.097068)
		(end 380.581916 -248.046748)
		(width 0.0889)
		(layer "In2.Cu")
		(net "M_I_CPU0_SA_CB<4>")
	)
	(arc
		(start 379.26772 -248.046748)
		(mid 379.449971 -248.097098)
		(end 379.63348 -248.051574)
		(width 0.0889)
		(layer "In2.Cu")
		(net "M_I_CPU0_SA_CB<4>")
	)
	(arc
		(start 388.10184 -248.046748)
		(mid 388.384796 -247.970571)
		(end 388.667752 -248.046748)
		(width 0.0889)
		(layer "In2.Cu")
		(net "M_I_CPU0_SA_CB<4>")
	)
	(arc
		(start 378.327666 -248.046748)
		(mid 378.509917 -248.097098)
		(end 378.693426 -248.051574)
		(width 0.0889)
		(layer "In2.Cu")
		(net "M_I_CPU0_SA_CB<4>")
	)
	(arc
		(start 383.401824 -248.046748)
		(mid 383.68478 -247.970571)
		(end 383.967736 -248.046748)
		(width 0.0889)
		(layer "In2.Cu")
		(net "M_I_CPU0_SA_CB<4>")
	)
	(arc
		(start 381.15621 -248.051574)
		(mid 381.339718 -248.097068)
		(end 381.52197 -248.046748)
		(width 0.0889)
		(layer "In2.Cu")
		(net "M_I_CPU0_SA_CB<4>")
	)
	(arc
		(start 389.616188 -248.051574)
		(mid 389.799696 -248.097068)
		(end 389.981948 -248.046748)
		(width 0.0889)
		(layer "In2.Cu")
		(net "M_I_CPU0_SA_CB<4>")
	)
	(arc
		(start 387.161786 -248.046748)
		(mid 387.444742 -247.970571)
		(end 387.727698 -248.046748)
		(width 0.0889)
		(layer "In2.Cu")
		(net "M_I_CPU0_SA_CB<4>")
	)
	(arc
		(start 390.54786 -248.046748)
		(mid 390.734804 -248.097003)
		(end 390.921748 -248.046748)
		(width 0.0889)
		(layer "In2.Cu")
		(net "M_I_CPU0_SA_CB<4>")
	)
	(arc
		(start 387.727698 -248.046748)
		(mid 387.909949 -248.097098)
		(end 388.093458 -248.051574)
		(width 0.0889)
		(layer "In2.Cu")
		(net "M_I_CPU0_SA_CB<4>")
	)
	(arc
		(start 377.761754 -248.046748)
		(mid 378.04471 -247.970571)
		(end 378.327666 -248.046748)
		(width 0.0889)
		(layer "In2.Cu")
		(net "M_I_CPU0_SA_CB<4>")
	)
	(arc
		(start 382.087882 -248.046748)
		(mid 382.274826 -248.097003)
		(end 382.46177 -248.046748)
		(width 0.0889)
		(layer "In2.Cu")
		(net "M_I_CPU0_SA_CB<4>")
	)
	(arc
		(start 389.981948 -248.046748)
		(mid 390.264904 -247.970571)
		(end 390.54786 -248.046748)
		(width 0.0889)
		(layer "In2.Cu")
		(net "M_I_CPU0_SA_CB<4>")
	)
	(arc
		(start 383.967736 -248.046748)
		(mid 384.149987 -248.097098)
		(end 384.333496 -248.051574)
		(width 0.0889)
		(layer "In2.Cu")
		(net "M_I_CPU0_SA_CB<4>")
	)
	(arc
		(start 380.581916 -248.046748)
		(mid 380.864872 -247.970571)
		(end 381.147828 -248.046748)
		(width 0.0889)
		(layer "In2.Cu")
		(net "M_I_CPU0_SA_CB<4>")
	)
	(arc
		(start 386.787898 -248.046748)
		(mid 386.974842 -248.097003)
		(end 387.161786 -248.046748)
		(width 0.0889)
		(layer "In2.Cu")
		(net "M_I_CPU0_SA_CB<4>")
	)
	(arc
		(start 383.027682 -248.046748)
		(mid 383.209933 -248.097098)
		(end 383.393442 -248.051574)
		(width 0.0889)
		(layer "In2.Cu")
		(net "M_I_CPU0_SA_CB<4>")
	)
	(arc
		(start 391.884408 -248.032524)
		(mid 392.156345 -247.970698)
		(end 392.424666 -248.046748)
		(width 0.0889)
		(layer "In2.Cu")
		(net "M_I_CPU0_SA_CB<4>")
	)
	(arc
		(start 386.221986 -248.046748)
		(mid 386.504942 -247.970571)
		(end 386.787898 -248.046748)
		(width 0.0889)
		(layer "In2.Cu")
		(net "M_I_CPU0_SA_CB<4>")
	)
	(arc
		(start 377.443238 -248.07291)
		(mid 377.605427 -248.095645)
		(end 377.761754 -248.046748)
		(width 0.0889)
		(layer "In2.Cu")
		(net "M_I_CPU0_SA_CB<4>")
	)
	(arc
		(start 391.48766 -248.046748)
		(mid 391.660768 -248.096864)
		(end 391.837164 -248.059956)
		(width 0.0889)
		(layer "In2.Cu")
		(net "M_I_CPU0_SA_CB<4>")
	)
	(arc
		(start 384.916172 -248.051574)
		(mid 385.09968 -248.097068)
		(end 385.281932 -248.046748)
		(width 0.0889)
		(layer "In2.Cu")
		(net "M_I_CPU0_SA_CB<4>")
	)
	(arc
		(start 382.46177 -248.046748)
		(mid 382.744726 -247.970571)
		(end 383.027682 -248.046748)
		(width 0.0889)
		(layer "In2.Cu")
		(net "M_I_CPU0_SA_CB<4>")
	)
	(arc
		(start 381.52197 -248.046748)
		(mid 381.804926 -247.970571)
		(end 382.087882 -248.046748)
		(width 0.0889)
		(layer "In2.Cu")
		(net "M_I_CPU0_SA_CB<4>")
	)
	(arc
		(start 384.341878 -248.046748)
		(mid 384.624834 -247.970571)
		(end 384.90779 -248.046748)
		(width 0.0889)
		(layer "In2.Cu")
		(net "M_I_CPU0_SA_CB<4>")
	)
	(arc
		(start 388.667752 -248.046748)
		(mid 388.850003 -248.097098)
		(end 389.033512 -248.051574)
		(width 0.0889)
		(layer "In2.Cu")
		(net "M_I_CPU0_SA_CB<4>")
	)
	(arc
		(start 379.641862 -248.046748)
		(mid 379.924818 -247.970571)
		(end 380.207774 -248.046748)
		(width 0.0889)
		(layer "In2.Cu")
		(net "M_I_CPU0_SA_CB<4>")
	)
	(arc
		(start 385.281932 -248.046748)
		(mid 385.564888 -247.970571)
		(end 385.847844 -248.046748)
		(width 0.0889)
		(layer "In2.Cu")
		(net "M_I_CPU0_SA_CB<4>")
	)
	(segment
		(start 375.22785 -246.370094)
		(end 375.694702 -246.104156)
		(width 0.10668)
		(layer "F.Cu")
		(net "M_I_CPU0_SA_CB<3>")
	)
	(segment
		(start 408.721306 -240.136172)
		(end 408.949906 -240.136172)
		(width 0.14478)
		(layer "In2.Cu")
		(net "M_I_CPU0_SA_CB<3>")
	)
	(segment
		(start 376.447812 -245.781576)
		(end 376.456194 -245.77675)
		(width 0.0889)
		(layer "In2.Cu")
		(net "M_I_CPU0_SA_CB<3>")
	)
	(segment
		(start 375.694702 -246.104156)
		(end 375.84888 -245.838726)
		(width 0.0889)
		(layer "In2.Cu")
		(net "M_I_CPU0_SA_CB<3>")
	)
	(segment
		(start 427.03115 -236.86008)
		(end 427.456092 -237.285022)
		(width 0.14478)
		(layer "In2.Cu")
		(net "M_I_CPU0_SA_CB<3>")
	)
	(segment
		(start 421.465756 -237.700312)
		(end 422.31564 -236.850428)
		(width 0.14478)
		(layer "In2.Cu")
		(net "M_I_CPU0_SA_CB<3>")
	)
	(segment
		(start 393.899898 -245.93931)
		(end 395.367256 -245.93931)
		(width 0.0889)
		(layer "In2.Cu")
		(net "M_I_CPU0_SA_CB<3>")
	)
	(segment
		(start 426.578014 -236.54639)
		(end 426.891704 -236.86008)
		(width 0.14478)
		(layer "In2.Cu")
		(net "M_I_CPU0_SA_CB<3>")
	)
	(segment
		(start 395.943328 -245.363238)
		(end 396.154656 -245.15191)
		(width 0.14478)
		(layer "In2.Cu")
		(net "M_I_CPU0_SA_CB<3>")
	)
	(segment
		(start 410.172154 -239.569244)
		(end 410.333698 -239.4077)
		(width 0.14478)
		(layer "In2.Cu")
		(net "M_I_CPU0_SA_CB<3>")
	)
	(segment
		(start 396.154656 -245.15191)
		(end 404.834852 -245.15191)
		(width 0.14478)
		(layer "In2.Cu")
		(net "M_I_CPU0_SA_CB<3>")
	)
	(segment
		(start 384.90779 -245.781576)
		(end 384.916172 -245.77675)
		(width 0.0889)
		(layer "In2.Cu")
		(net "M_I_CPU0_SA_CB<3>")
	)
	(segment
		(start 426.078904 -236.80039)
		(end 426.332904 -236.54639)
		(width 0.14478)
		(layer "In2.Cu")
		(net "M_I_CPU0_SA_CB<3>")
	)
	(segment
		(start 414.777174 -236.850428)
		(end 418.151056 -236.850428)
		(width 0.14478)
		(layer "In2.Cu")
		(net "M_I_CPU0_SA_CB<3>")
	)
	(segment
		(start 409.943554 -239.569244)
		(end 410.172154 -239.569244)
		(width 0.14478)
		(layer "In2.Cu")
		(net "M_I_CPU0_SA_CB<3>")
	)
	(segment
		(start 426.332904 -236.54639)
		(end 426.578014 -236.54639)
		(width 0.14478)
		(layer "In2.Cu")
		(net "M_I_CPU0_SA_CB<3>")
	)
	(segment
		(start 410.333698 -239.4077)
		(end 410.333698 -239.1791)
		(width 0.14478)
		(layer "In2.Cu")
		(net "M_I_CPU0_SA_CB<3>")
	)
	(segment
		(start 426.891704 -236.86008)
		(end 427.03115 -236.86008)
		(width 0.14478)
		(layer "In2.Cu")
		(net "M_I_CPU0_SA_CB<3>")
	)
	(segment
		(start 413.92729 -237.700312)
		(end 414.777174 -236.850428)
		(width 0.14478)
		(layer "In2.Cu")
		(net "M_I_CPU0_SA_CB<3>")
	)
	(segment
		(start 409.34005 -239.517428)
		(end 409.501594 -239.355884)
		(width 0.14478)
		(layer "In2.Cu")
		(net "M_I_CPU0_SA_CB<3>")
	)
	(segment
		(start 408.895804 -241.090958)
		(end 408.895804 -240.862358)
		(width 0.14478)
		(layer "In2.Cu")
		(net "M_I_CPU0_SA_CB<3>")
	)
	(segment
		(start 418.180774 -236.860334)
		(end 419.020752 -237.700312)
		(width 0.14478)
		(layer "In2.Cu")
		(net "M_I_CPU0_SA_CB<3>")
	)
	(segment
		(start 379.63348 -245.77675)
		(end 379.641862 -245.781576)
		(width 0.0889)
		(layer "In2.Cu")
		(net "M_I_CPU0_SA_CB<3>")
	)
	(segment
		(start 389.033512 -245.77675)
		(end 389.041894 -245.781576)
		(width 0.0889)
		(layer "In2.Cu")
		(net "M_I_CPU0_SA_CB<3>")
	)
	(segment
		(start 409.676092 -240.08207)
		(end 409.34005 -239.746028)
		(width 0.14478)
		(layer "In2.Cu")
		(net "M_I_CPU0_SA_CB<3>")
	)
	(segment
		(start 410.333698 -239.1791)
		(end 410.120338 -238.96574)
		(width 0.14478)
		(layer "In2.Cu")
		(net "M_I_CPU0_SA_CB<3>")
	)
	(segment
		(start 410.120338 -238.96574)
		(end 410.120338 -238.73714)
		(width 0.14478)
		(layer "In2.Cu")
		(net "M_I_CPU0_SA_CB<3>")
	)
	(segment
		(start 409.514548 -240.472214)
		(end 409.676092 -240.31067)
		(width 0.14478)
		(layer "In2.Cu")
		(net "M_I_CPU0_SA_CB<3>")
	)
	(segment
		(start 408.559762 -240.526316)
		(end 408.559762 -240.297716)
		(width 0.14478)
		(layer "In2.Cu")
		(net "M_I_CPU0_SA_CB<3>")
	)
	(segment
		(start 388.093458 -245.77675)
		(end 388.10184 -245.781576)
		(width 0.0889)
		(layer "In2.Cu")
		(net "M_I_CPU0_SA_CB<3>")
	)
	(segment
		(start 409.501594 -239.355884)
		(end 409.730194 -239.355884)
		(width 0.14478)
		(layer "In2.Cu")
		(net "M_I_CPU0_SA_CB<3>")
	)
	(segment
		(start 408.559762 -240.297716)
		(end 408.721306 -240.136172)
		(width 0.14478)
		(layer "In2.Cu")
		(net "M_I_CPU0_SA_CB<3>")
	)
	(segment
		(start 393.742164 -245.781576)
		(end 393.899898 -245.93931)
		(width 0.0889)
		(layer "In2.Cu")
		(net "M_I_CPU0_SA_CB<3>")
	)
	(segment
		(start 409.676092 -240.31067)
		(end 409.676092 -240.08207)
		(width 0.14478)
		(layer "In2.Cu")
		(net "M_I_CPU0_SA_CB<3>")
	)
	(segment
		(start 425.714414 -236.80039)
		(end 426.078904 -236.80039)
		(width 0.14478)
		(layer "In2.Cu")
		(net "M_I_CPU0_SA_CB<3>")
	)
	(segment
		(start 409.285948 -240.472214)
		(end 409.514548 -240.472214)
		(width 0.14478)
		(layer "In2.Cu")
		(net "M_I_CPU0_SA_CB<3>")
	)
	(segment
		(start 425.460414 -236.54639)
		(end 425.714414 -236.80039)
		(width 0.14478)
		(layer "In2.Cu")
		(net "M_I_CPU0_SA_CB<3>")
	)
	(segment
		(start 409.34005 -239.746028)
		(end 409.34005 -239.517428)
		(width 0.14478)
		(layer "In2.Cu")
		(net "M_I_CPU0_SA_CB<3>")
	)
	(segment
		(start 425.215304 -236.54639)
		(end 425.460414 -236.54639)
		(width 0.14478)
		(layer "In2.Cu")
		(net "M_I_CPU0_SA_CB<3>")
	)
	(segment
		(start 409.730194 -239.355884)
		(end 409.943554 -239.569244)
		(width 0.14478)
		(layer "In2.Cu")
		(net "M_I_CPU0_SA_CB<3>")
	)
	(segment
		(start 408.949906 -240.136172)
		(end 409.285948 -240.472214)
		(width 0.14478)
		(layer "In2.Cu")
		(net "M_I_CPU0_SA_CB<3>")
	)
	(segment
		(start 381.147828 -245.781576)
		(end 381.15621 -245.77675)
		(width 0.0889)
		(layer "In2.Cu")
		(net "M_I_CPU0_SA_CB<3>")
	)
	(segment
		(start 383.393442 -245.77675)
		(end 383.401824 -245.781576)
		(width 0.0889)
		(layer "In2.Cu")
		(net "M_I_CPU0_SA_CB<3>")
	)
	(segment
		(start 424.911266 -236.850428)
		(end 425.215304 -236.54639)
		(width 0.14478)
		(layer "In2.Cu")
		(net "M_I_CPU0_SA_CB<3>")
	)
	(segment
		(start 419.020752 -237.700312)
		(end 421.465756 -237.700312)
		(width 0.14478)
		(layer "In2.Cu")
		(net "M_I_CPU0_SA_CB<3>")
	)
	(segment
		(start 378.693426 -245.77675)
		(end 378.701808 -245.781576)
		(width 0.0889)
		(layer "In2.Cu")
		(net "M_I_CPU0_SA_CB<3>")
	)
	(segment
		(start 408.895804 -240.862358)
		(end 408.559762 -240.526316)
		(width 0.14478)
		(layer "In2.Cu")
		(net "M_I_CPU0_SA_CB<3>")
	)
	(segment
		(start 375.84888 -245.838726)
		(end 375.945146 -245.813326)
		(width 0.0889)
		(layer "In2.Cu")
		(net "M_I_CPU0_SA_CB<3>")
	)
	(segment
		(start 389.607806 -245.781576)
		(end 389.616188 -245.77675)
		(width 0.0889)
		(layer "In2.Cu")
		(net "M_I_CPU0_SA_CB<3>")
	)
	(segment
		(start 422.31564 -236.850428)
		(end 424.911266 -236.850428)
		(width 0.14478)
		(layer "In2.Cu")
		(net "M_I_CPU0_SA_CB<3>")
	)
	(segment
		(start 411.157166 -237.700312)
		(end 413.92729 -237.700312)
		(width 0.14478)
		(layer "In2.Cu")
		(net "M_I_CPU0_SA_CB<3>")
	)
	(segment
		(start 418.151056 -236.850428)
		(end 418.180774 -236.860334)
		(width 0.14478)
		(layer "In2.Cu")
		(net "M_I_CPU0_SA_CB<3>")
	)
	(segment
		(start 410.120338 -238.73714)
		(end 411.157166 -237.700312)
		(width 0.14478)
		(layer "In2.Cu")
		(net "M_I_CPU0_SA_CB<3>")
	)
	(segment
		(start 404.834852 -245.15191)
		(end 408.895804 -241.090958)
		(width 0.14478)
		(layer "In2.Cu")
		(net "M_I_CPU0_SA_CB<3>")
	)
	(segment
		(start 380.207774 -245.781576)
		(end 380.216156 -245.77675)
		(width 0.0889)
		(layer "In2.Cu")
		(net "M_I_CPU0_SA_CB<3>")
	)
	(segment
		(start 385.847844 -245.781576)
		(end 385.856226 -245.77675)
		(width 0.0889)
		(layer "In2.Cu")
		(net "M_I_CPU0_SA_CB<3>")
	)
	(segment
		(start 395.367256 -245.93931)
		(end 395.943328 -245.363238)
		(width 0.0889)
		(layer "In2.Cu")
		(net "M_I_CPU0_SA_CB<3>")
	)
	(segment
		(start 384.333496 -245.77675)
		(end 384.341878 -245.781576)
		(width 0.0889)
		(layer "In2.Cu")
		(net "M_I_CPU0_SA_CB<3>")
	)
	(arc
		(start 384.341878 -245.781576)
		(mid 384.624834 -245.857753)
		(end 384.90779 -245.781576)
		(width 0.0889)
		(layer "In2.Cu")
		(net "M_I_CPU0_SA_CB<3>")
	)
	(arc
		(start 388.10184 -245.781576)
		(mid 388.384796 -245.857753)
		(end 388.667752 -245.781576)
		(width 0.0889)
		(layer "In2.Cu")
		(net "M_I_CPU0_SA_CB<3>")
	)
	(arc
		(start 391.48766 -245.781576)
		(mid 391.674858 -245.731194)
		(end 391.862056 -245.781576)
		(width 0.0889)
		(layer "In2.Cu")
		(net "M_I_CPU0_SA_CB<3>")
	)
	(arc
		(start 387.161786 -245.781576)
		(mid 387.444742 -245.857753)
		(end 387.727698 -245.781576)
		(width 0.0889)
		(layer "In2.Cu")
		(net "M_I_CPU0_SA_CB<3>")
	)
	(arc
		(start 390.54786 -245.781576)
		(mid 390.734804 -245.731321)
		(end 390.921748 -245.781576)
		(width 0.0889)
		(layer "In2.Cu")
		(net "M_I_CPU0_SA_CB<3>")
	)
	(arc
		(start 382.46177 -245.781576)
		(mid 382.744726 -245.857753)
		(end 383.027682 -245.781576)
		(width 0.0889)
		(layer "In2.Cu")
		(net "M_I_CPU0_SA_CB<3>")
	)
	(arc
		(start 386.221986 -245.781576)
		(mid 386.504942 -245.857753)
		(end 386.787898 -245.781576)
		(width 0.0889)
		(layer "In2.Cu")
		(net "M_I_CPU0_SA_CB<3>")
	)
	(arc
		(start 387.727698 -245.781576)
		(mid 387.909949 -245.731226)
		(end 388.093458 -245.77675)
		(width 0.0889)
		(layer "In2.Cu")
		(net "M_I_CPU0_SA_CB<3>")
	)
	(arc
		(start 388.667752 -245.781576)
		(mid 388.850003 -245.731226)
		(end 389.033512 -245.77675)
		(width 0.0889)
		(layer "In2.Cu")
		(net "M_I_CPU0_SA_CB<3>")
	)
	(arc
		(start 377.761754 -245.781576)
		(mid 378.04471 -245.857753)
		(end 378.327666 -245.781576)
		(width 0.0889)
		(layer "In2.Cu")
		(net "M_I_CPU0_SA_CB<3>")
	)
	(arc
		(start 382.087882 -245.781576)
		(mid 382.274826 -245.731321)
		(end 382.46177 -245.781576)
		(width 0.0889)
		(layer "In2.Cu")
		(net "M_I_CPU0_SA_CB<3>")
	)
	(arc
		(start 375.945146 -245.813326)
		(mid 376.200211 -245.856677)
		(end 376.447812 -245.781576)
		(width 0.0889)
		(layer "In2.Cu")
		(net "M_I_CPU0_SA_CB<3>")
	)
	(arc
		(start 392.801856 -245.781576)
		(mid 393.084812 -245.857753)
		(end 393.367768 -245.781576)
		(width 0.0889)
		(layer "In2.Cu")
		(net "M_I_CPU0_SA_CB<3>")
	)
	(arc
		(start 384.916172 -245.77675)
		(mid 385.09968 -245.731256)
		(end 385.281932 -245.781576)
		(width 0.0889)
		(layer "In2.Cu")
		(net "M_I_CPU0_SA_CB<3>")
	)
	(arc
		(start 392.427968 -245.781576)
		(mid 392.614912 -245.731321)
		(end 392.801856 -245.781576)
		(width 0.0889)
		(layer "In2.Cu")
		(net "M_I_CPU0_SA_CB<3>")
	)
	(arc
		(start 380.216156 -245.77675)
		(mid 380.399664 -245.731256)
		(end 380.581916 -245.781576)
		(width 0.0889)
		(layer "In2.Cu")
		(net "M_I_CPU0_SA_CB<3>")
	)
	(arc
		(start 376.456194 -245.77675)
		(mid 376.639702 -245.731256)
		(end 376.821954 -245.781576)
		(width 0.0889)
		(layer "In2.Cu")
		(net "M_I_CPU0_SA_CB<3>")
	)
	(arc
		(start 381.15621 -245.77675)
		(mid 381.339718 -245.731256)
		(end 381.52197 -245.781576)
		(width 0.0889)
		(layer "In2.Cu")
		(net "M_I_CPU0_SA_CB<3>")
	)
	(arc
		(start 389.981948 -245.781576)
		(mid 390.264904 -245.857753)
		(end 390.54786 -245.781576)
		(width 0.0889)
		(layer "In2.Cu")
		(net "M_I_CPU0_SA_CB<3>")
	)
	(arc
		(start 386.787898 -245.781576)
		(mid 386.974842 -245.731321)
		(end 387.161786 -245.781576)
		(width 0.0889)
		(layer "In2.Cu")
		(net "M_I_CPU0_SA_CB<3>")
	)
	(arc
		(start 381.52197 -245.781576)
		(mid 381.804926 -245.857753)
		(end 382.087882 -245.781576)
		(width 0.0889)
		(layer "In2.Cu")
		(net "M_I_CPU0_SA_CB<3>")
	)
	(arc
		(start 390.921748 -245.781576)
		(mid 391.204704 -245.857753)
		(end 391.48766 -245.781576)
		(width 0.0889)
		(layer "In2.Cu")
		(net "M_I_CPU0_SA_CB<3>")
	)
	(arc
		(start 389.616188 -245.77675)
		(mid 389.799696 -245.731256)
		(end 389.981948 -245.781576)
		(width 0.0889)
		(layer "In2.Cu")
		(net "M_I_CPU0_SA_CB<3>")
	)
	(arc
		(start 385.856226 -245.77675)
		(mid 386.039734 -245.731256)
		(end 386.221986 -245.781576)
		(width 0.0889)
		(layer "In2.Cu")
		(net "M_I_CPU0_SA_CB<3>")
	)
	(arc
		(start 391.862056 -245.781576)
		(mid 392.145012 -245.857753)
		(end 392.427968 -245.781576)
		(width 0.0889)
		(layer "In2.Cu")
		(net "M_I_CPU0_SA_CB<3>")
	)
	(arc
		(start 376.821954 -245.781576)
		(mid 377.10491 -245.857753)
		(end 377.387866 -245.781576)
		(width 0.0889)
		(layer "In2.Cu")
		(net "M_I_CPU0_SA_CB<3>")
	)
	(arc
		(start 378.327666 -245.781576)
		(mid 378.509917 -245.731226)
		(end 378.693426 -245.77675)
		(width 0.0889)
		(layer "In2.Cu")
		(net "M_I_CPU0_SA_CB<3>")
	)
	(arc
		(start 383.401824 -245.781576)
		(mid 383.68478 -245.857753)
		(end 383.967736 -245.781576)
		(width 0.0889)
		(layer "In2.Cu")
		(net "M_I_CPU0_SA_CB<3>")
	)
	(arc
		(start 378.701808 -245.781576)
		(mid 378.984764 -245.857753)
		(end 379.26772 -245.781576)
		(width 0.0889)
		(layer "In2.Cu")
		(net "M_I_CPU0_SA_CB<3>")
	)
	(arc
		(start 383.967736 -245.781576)
		(mid 384.149987 -245.731226)
		(end 384.333496 -245.77675)
		(width 0.0889)
		(layer "In2.Cu")
		(net "M_I_CPU0_SA_CB<3>")
	)
	(arc
		(start 383.027682 -245.781576)
		(mid 383.209933 -245.731226)
		(end 383.393442 -245.77675)
		(width 0.0889)
		(layer "In2.Cu")
		(net "M_I_CPU0_SA_CB<3>")
	)
	(arc
		(start 393.367768 -245.781576)
		(mid 393.554966 -245.731194)
		(end 393.742164 -245.781576)
		(width 0.0889)
		(layer "In2.Cu")
		(net "M_I_CPU0_SA_CB<3>")
	)
	(arc
		(start 379.641862 -245.781576)
		(mid 379.924818 -245.857753)
		(end 380.207774 -245.781576)
		(width 0.0889)
		(layer "In2.Cu")
		(net "M_I_CPU0_SA_CB<3>")
	)
	(arc
		(start 389.041894 -245.781576)
		(mid 389.32485 -245.857753)
		(end 389.607806 -245.781576)
		(width 0.0889)
		(layer "In2.Cu")
		(net "M_I_CPU0_SA_CB<3>")
	)
	(arc
		(start 385.281932 -245.781576)
		(mid 385.564888 -245.857753)
		(end 385.847844 -245.781576)
		(width 0.0889)
		(layer "In2.Cu")
		(net "M_I_CPU0_SA_CB<3>")
	)
	(arc
		(start 380.581916 -245.781576)
		(mid 380.864872 -245.857753)
		(end 381.147828 -245.781576)
		(width 0.0889)
		(layer "In2.Cu")
		(net "M_I_CPU0_SA_CB<3>")
	)
	(arc
		(start 377.387866 -245.781576)
		(mid 377.57481 -245.731321)
		(end 377.761754 -245.781576)
		(width 0.0889)
		(layer "In2.Cu")
		(net "M_I_CPU0_SA_CB<3>")
	)
	(arc
		(start 379.26772 -245.781576)
		(mid 379.449971 -245.731226)
		(end 379.63348 -245.77675)
		(width 0.0889)
		(layer "In2.Cu")
		(net "M_I_CPU0_SA_CB<3>")
	)
	(segment
		(start 376.638058 -245.560088)
		(end 377.10491 -245.29415)
		(width 0.10668)
		(layer "F.Cu")
		(net "M_I_CPU0_SA_CB<2>")
	)
	(segment
		(start 406.94483 -241.502946)
		(end 406.627838 -241.185954)
		(width 0.14478)
		(layer "In2.Cu")
		(net "M_I_CPU0_SA_CB<2>")
	)
	(segment
		(start 427.03115 -235.160058)
		(end 427.456092 -235.585)
		(width 0.14478)
		(layer "In2.Cu")
		(net "M_I_CPU0_SA_CB<2>")
	)
	(segment
		(start 391.93216 -244.985794)
		(end 391.956036 -244.971824)
		(width 0.0889)
		(layer "In2.Cu")
		(net "M_I_CPU0_SA_CB<2>")
	)
	(segment
		(start 377.10491 -245.29415)
		(end 377.258834 -245.02872)
		(width 0.0889)
		(layer "In2.Cu")
		(net "M_I_CPU0_SA_CB<2>")
	)
	(segment
		(start 417.621212 -235.40339)
		(end 417.993322 -235.249212)
		(width 0.14478)
		(layer "In2.Cu")
		(net "M_I_CPU0_SA_CB<2>")
	)
	(segment
		(start 386.683504 -244.966744)
		(end 386.691886 -244.97157)
		(width 0.0889)
		(layer "In2.Cu")
		(net "M_I_CPU0_SA_CB<2>")
	)
	(segment
		(start 388.197852 -244.97157)
		(end 388.206234 -244.966744)
		(width 0.0889)
		(layer "In2.Cu")
		(net "M_I_CPU0_SA_CB<2>")
	)
	(segment
		(start 419.086792 -236.010196)
		(end 420.644828 -236.010196)
		(width 0.14478)
		(layer "In2.Cu")
		(net "M_I_CPU0_SA_CB<2>")
	)
	(segment
		(start 405.228806 -242.356386)
		(end 405.457406 -242.356386)
		(width 0.14478)
		(layer "In2.Cu")
		(net "M_I_CPU0_SA_CB<2>")
	)
	(segment
		(start 422.697402 -235.160058)
		(end 425.380404 -235.160058)
		(width 0.14478)
		(layer "In2.Cu")
		(net "M_I_CPU0_SA_CB<2>")
	)
	(segment
		(start 426.246036 -235.160058)
		(end 427.03115 -235.160058)
		(width 0.14478)
		(layer "In2.Cu")
		(net "M_I_CPU0_SA_CB<2>")
	)
	(segment
		(start 394.121894 -245.047008)
		(end 394.292836 -245.21795)
		(width 0.0889)
		(layer "In2.Cu")
		(net "M_I_CPU0_SA_CB<2>")
	)
	(segment
		(start 406.009094 -241.576098)
		(end 406.237694 -241.576098)
		(width 0.14478)
		(layer "In2.Cu")
		(net "M_I_CPU0_SA_CB<2>")
	)
	(segment
		(start 381.043434 -244.966744)
		(end 381.051816 -244.97157)
		(width 0.0889)
		(layer "In2.Cu")
		(net "M_I_CPU0_SA_CB<2>")
	)
	(segment
		(start 404.286974 -243.526818)
		(end 404.286974 -243.298218)
		(width 0.14478)
		(layer "In2.Cu")
		(net "M_I_CPU0_SA_CB<2>")
	)
	(segment
		(start 411.574996 -236.010196)
		(end 414.239202 -236.010196)
		(width 0.14478)
		(layer "In2.Cu")
		(net "M_I_CPU0_SA_CB<2>")
	)
	(segment
		(start 385.74345 -244.966744)
		(end 385.751832 -244.97157)
		(width 0.0889)
		(layer "In2.Cu")
		(net "M_I_CPU0_SA_CB<2>")
	)
	(segment
		(start 377.258834 -245.02872)
		(end 377.354846 -245.00332)
		(width 0.0889)
		(layer "In2.Cu")
		(net "M_I_CPU0_SA_CB<2>")
	)
	(segment
		(start 404.603966 -243.84381)
		(end 404.286974 -243.526818)
		(width 0.14478)
		(layer "In2.Cu")
		(net "M_I_CPU0_SA_CB<2>")
	)
	(segment
		(start 404.442422 -244.233954)
		(end 404.603966 -244.07241)
		(width 0.14478)
		(layer "In2.Cu")
		(net "M_I_CPU0_SA_CB<2>")
	)
	(segment
		(start 404.677118 -243.136674)
		(end 404.99411 -243.453666)
		(width 0.14478)
		(layer "In2.Cu")
		(net "M_I_CPU0_SA_CB<2>")
	)
	(segment
		(start 405.457406 -242.356386)
		(end 405.774398 -242.673378)
		(width 0.14478)
		(layer "In2.Cu")
		(net "M_I_CPU0_SA_CB<2>")
	)
	(segment
		(start 387.257798 -244.97157)
		(end 387.26618 -244.966744)
		(width 0.0889)
		(layer "In2.Cu")
		(net "M_I_CPU0_SA_CB<2>")
	)
	(segment
		(start 421.910764 -235.79328)
		(end 422.06418 -235.42244)
		(width 0.14478)
		(layer "In2.Cu")
		(net "M_I_CPU0_SA_CB<2>")
	)
	(segment
		(start 378.79782 -244.97157)
		(end 378.806202 -244.966744)
		(width 0.0889)
		(layer "In2.Cu")
		(net "M_I_CPU0_SA_CB<2>")
	)
	(segment
		(start 382.557782 -244.97157)
		(end 382.566164 -244.966744)
		(width 0.0889)
		(layer "In2.Cu")
		(net "M_I_CPU0_SA_CB<2>")
	)
	(segment
		(start 404.603966 -244.07241)
		(end 404.603966 -243.84381)
		(width 0.14478)
		(layer "In2.Cu")
		(net "M_I_CPU0_SA_CB<2>")
	)
	(segment
		(start 415.08934 -235.160058)
		(end 417.034218 -235.160058)
		(width 0.14478)
		(layer "In2.Cu")
		(net "M_I_CPU0_SA_CB<2>")
	)
	(segment
		(start 403.89683 -243.916962)
		(end 404.213822 -244.233954)
		(width 0.14478)
		(layer "In2.Cu")
		(net "M_I_CPU0_SA_CB<2>")
	)
	(segment
		(start 381.983488 -244.966744)
		(end 381.99187 -244.97157)
		(width 0.0889)
		(layer "In2.Cu")
		(net "M_I_CPU0_SA_CB<2>")
	)
	(segment
		(start 395.773656 -244.23751)
		(end 403.347682 -244.23751)
		(width 0.14478)
		(layer "In2.Cu")
		(net "M_I_CPU0_SA_CB<2>")
	)
	(segment
		(start 422.06418 -235.42244)
		(end 422.697402 -235.160058)
		(width 0.14478)
		(layer "In2.Cu")
		(net "M_I_CPU0_SA_CB<2>")
	)
	(segment
		(start 406.002998 -242.673378)
		(end 406.164542 -242.511834)
		(width 0.14478)
		(layer "In2.Cu")
		(net "M_I_CPU0_SA_CB<2>")
	)
	(segment
		(start 404.448518 -243.136674)
		(end 404.677118 -243.136674)
		(width 0.14478)
		(layer "In2.Cu")
		(net "M_I_CPU0_SA_CB<2>")
	)
	(segment
		(start 405.384254 -243.292122)
		(end 405.384254 -243.063522)
		(width 0.14478)
		(layer "In2.Cu")
		(net "M_I_CPU0_SA_CB<2>")
	)
	(segment
		(start 406.627838 -241.185954)
		(end 406.627838 -240.957354)
		(width 0.14478)
		(layer "In2.Cu")
		(net "M_I_CPU0_SA_CB<2>")
	)
	(segment
		(start 404.213822 -244.233954)
		(end 404.442422 -244.233954)
		(width 0.14478)
		(layer "In2.Cu")
		(net "M_I_CPU0_SA_CB<2>")
	)
	(segment
		(start 403.347682 -244.23751)
		(end 403.66823 -243.916962)
		(width 0.14478)
		(layer "In2.Cu")
		(net "M_I_CPU0_SA_CB<2>")
	)
	(segment
		(start 421.285416 -235.744766)
		(end 421.65651 -235.89869)
		(width 0.14478)
		(layer "In2.Cu")
		(net "M_I_CPU0_SA_CB<2>")
	)
	(segment
		(start 404.99411 -243.453666)
		(end 405.22271 -243.453666)
		(width 0.14478)
		(layer "In2.Cu")
		(net "M_I_CPU0_SA_CB<2>")
	)
	(segment
		(start 377.857766 -244.97157)
		(end 377.866148 -244.966744)
		(width 0.0889)
		(layer "In2.Cu")
		(net "M_I_CPU0_SA_CB<2>")
	)
	(segment
		(start 418.246814 -235.354368)
		(end 418.400484 -235.72597)
		(width 0.14478)
		(layer "In2.Cu")
		(net "M_I_CPU0_SA_CB<2>")
	)
	(segment
		(start 392.328654 -244.97157)
		(end 392.35634 -244.987572)
		(width 0.0889)
		(layer "In2.Cu")
		(net "M_I_CPU0_SA_CB<2>")
	)
	(segment
		(start 425.380404 -235.160058)
		(end 425.687236 -235.46689)
		(width 0.14478)
		(layer "In2.Cu")
		(net "M_I_CPU0_SA_CB<2>")
	)
	(segment
		(start 406.627838 -240.957354)
		(end 411.574996 -236.010196)
		(width 0.14478)
		(layer "In2.Cu")
		(net "M_I_CPU0_SA_CB<2>")
	)
	(segment
		(start 406.783286 -241.89309)
		(end 406.94483 -241.731546)
		(width 0.14478)
		(layer "In2.Cu")
		(net "M_I_CPU0_SA_CB<2>")
	)
	(segment
		(start 403.66823 -243.916962)
		(end 403.89683 -243.916962)
		(width 0.14478)
		(layer "In2.Cu")
		(net "M_I_CPU0_SA_CB<2>")
	)
	(segment
		(start 391.01776 -244.97157)
		(end 391.026142 -244.966744)
		(width 0.0889)
		(layer "In2.Cu")
		(net "M_I_CPU0_SA_CB<2>")
	)
	(segment
		(start 394.292836 -245.21795)
		(end 394.793216 -245.21795)
		(width 0.0889)
		(layer "In2.Cu")
		(net "M_I_CPU0_SA_CB<2>")
	)
	(segment
		(start 404.286974 -243.298218)
		(end 404.448518 -243.136674)
		(width 0.14478)
		(layer "In2.Cu")
		(net "M_I_CPU0_SA_CB<2>")
	)
	(segment
		(start 406.237694 -241.576098)
		(end 406.554686 -241.89309)
		(width 0.14478)
		(layer "In2.Cu")
		(net "M_I_CPU0_SA_CB<2>")
	)
	(segment
		(start 405.067262 -242.74653)
		(end 405.067262 -242.51793)
		(width 0.14478)
		(layer "In2.Cu")
		(net "M_I_CPU0_SA_CB<2>")
	)
	(segment
		(start 420.644828 -236.010196)
		(end 421.285416 -235.744766)
		(width 0.14478)
		(layer "In2.Cu")
		(net "M_I_CPU0_SA_CB<2>")
	)
	(segment
		(start 405.067262 -242.51793)
		(end 405.228806 -242.356386)
		(width 0.14478)
		(layer "In2.Cu")
		(net "M_I_CPU0_SA_CB<2>")
	)
	(segment
		(start 393.240514 -244.954552)
		(end 393.270486 -244.971824)
		(width 0.0889)
		(layer "In2.Cu")
		(net "M_I_CPU0_SA_CB<2>")
	)
	(segment
		(start 418.400484 -235.72597)
		(end 419.086792 -236.010196)
		(width 0.14478)
		(layer "In2.Cu")
		(net "M_I_CPU0_SA_CB<2>")
	)
	(segment
		(start 394.793216 -245.21795)
		(end 395.773656 -244.23751)
		(width 0.0889)
		(layer "In2.Cu")
		(net "M_I_CPU0_SA_CB<2>")
	)
	(segment
		(start 406.94483 -241.731546)
		(end 406.94483 -241.502946)
		(width 0.14478)
		(layer "In2.Cu")
		(net "M_I_CPU0_SA_CB<2>")
	)
	(segment
		(start 390.443466 -244.966744)
		(end 390.451848 -244.97157)
		(width 0.0889)
		(layer "In2.Cu")
		(net "M_I_CPU0_SA_CB<2>")
	)
	(segment
		(start 383.497836 -244.97157)
		(end 383.506218 -244.966744)
		(width 0.0889)
		(layer "In2.Cu")
		(net "M_I_CPU0_SA_CB<2>")
	)
	(segment
		(start 417.034218 -235.160058)
		(end 417.621212 -235.40339)
		(width 0.14478)
		(layer "In2.Cu")
		(net "M_I_CPU0_SA_CB<2>")
	)
	(segment
		(start 405.774398 -242.673378)
		(end 406.002998 -242.673378)
		(width 0.14478)
		(layer "In2.Cu")
		(net "M_I_CPU0_SA_CB<2>")
	)
	(segment
		(start 393.55141 -245.047008)
		(end 394.121894 -245.047008)
		(width 0.0889)
		(layer "In2.Cu")
		(net "M_I_CPU0_SA_CB<2>")
	)
	(segment
		(start 405.84755 -241.966242)
		(end 405.84755 -241.737642)
		(width 0.14478)
		(layer "In2.Cu")
		(net "M_I_CPU0_SA_CB<2>")
	)
	(segment
		(start 406.554686 -241.89309)
		(end 406.783286 -241.89309)
		(width 0.14478)
		(layer "In2.Cu")
		(net "M_I_CPU0_SA_CB<2>")
	)
	(segment
		(start 405.22271 -243.453666)
		(end 405.384254 -243.292122)
		(width 0.14478)
		(layer "In2.Cu")
		(net "M_I_CPU0_SA_CB<2>")
	)
	(segment
		(start 391.956036 -244.971824)
		(end 391.97788 -244.959378)
		(width 0.0889)
		(layer "In2.Cu")
		(net "M_I_CPU0_SA_CB<2>")
	)
	(segment
		(start 425.687236 -235.46689)
		(end 425.939204 -235.46689)
		(width 0.14478)
		(layer "In2.Cu")
		(net "M_I_CPU0_SA_CB<2>")
	)
	(segment
		(start 414.239202 -236.010196)
		(end 415.08934 -235.160058)
		(width 0.14478)
		(layer "In2.Cu")
		(net "M_I_CPU0_SA_CB<2>")
	)
	(segment
		(start 406.164542 -242.283234)
		(end 405.84755 -241.966242)
		(width 0.14478)
		(layer "In2.Cu")
		(net "M_I_CPU0_SA_CB<2>")
	)
	(segment
		(start 421.65651 -235.89869)
		(end 421.910764 -235.79328)
		(width 0.14478)
		(layer "In2.Cu")
		(net "M_I_CPU0_SA_CB<2>")
	)
	(segment
		(start 405.384254 -243.063522)
		(end 405.067262 -242.74653)
		(width 0.14478)
		(layer "In2.Cu")
		(net "M_I_CPU0_SA_CB<2>")
	)
	(segment
		(start 405.84755 -241.737642)
		(end 406.009094 -241.576098)
		(width 0.14478)
		(layer "In2.Cu")
		(net "M_I_CPU0_SA_CB<2>")
	)
	(segment
		(start 425.939204 -235.46689)
		(end 426.246036 -235.160058)
		(width 0.14478)
		(layer "In2.Cu")
		(net "M_I_CPU0_SA_CB<2>")
	)
	(segment
		(start 406.164542 -242.511834)
		(end 406.164542 -242.283234)
		(width 0.14478)
		(layer "In2.Cu")
		(net "M_I_CPU0_SA_CB<2>")
	)
	(segment
		(start 417.993322 -235.249212)
		(end 418.246814 -235.354368)
		(width 0.14478)
		(layer "In2.Cu")
		(net "M_I_CPU0_SA_CB<2>")
	)
	(arc
		(start 391.97788 -244.959378)
		(mid 392.154808 -244.92155)
		(end 392.328654 -244.97157)
		(width 0.0889)
		(layer "In2.Cu")
		(net "M_I_CPU0_SA_CB<2>")
	)
	(arc
		(start 393.270486 -244.971824)
		(mid 393.406012 -245.027844)
		(end 393.55141 -245.047008)
		(width 0.0889)
		(layer "In2.Cu")
		(net "M_I_CPU0_SA_CB<2>")
	)
	(arc
		(start 382.566164 -244.966744)
		(mid 382.749672 -244.92125)
		(end 382.931924 -244.97157)
		(width 0.0889)
		(layer "In2.Cu")
		(net "M_I_CPU0_SA_CB<2>")
	)
	(arc
		(start 381.99187 -244.97157)
		(mid 382.274826 -245.047747)
		(end 382.557782 -244.97157)
		(width 0.0889)
		(layer "In2.Cu")
		(net "M_I_CPU0_SA_CB<2>")
	)
	(arc
		(start 389.137906 -244.97157)
		(mid 389.32485 -244.921315)
		(end 389.511794 -244.97157)
		(width 0.0889)
		(layer "In2.Cu")
		(net "M_I_CPU0_SA_CB<2>")
	)
	(arc
		(start 382.931924 -244.97157)
		(mid 383.21488 -245.047747)
		(end 383.497836 -244.97157)
		(width 0.0889)
		(layer "In2.Cu")
		(net "M_I_CPU0_SA_CB<2>")
	)
	(arc
		(start 378.806202 -244.966744)
		(mid 378.98971 -244.92125)
		(end 379.171962 -244.97157)
		(width 0.0889)
		(layer "In2.Cu")
		(net "M_I_CPU0_SA_CB<2>")
	)
	(arc
		(start 385.37769 -244.97157)
		(mid 385.559941 -244.92122)
		(end 385.74345 -244.966744)
		(width 0.0889)
		(layer "In2.Cu")
		(net "M_I_CPU0_SA_CB<2>")
	)
	(arc
		(start 381.051816 -244.97157)
		(mid 381.334772 -245.047747)
		(end 381.617728 -244.97157)
		(width 0.0889)
		(layer "In2.Cu")
		(net "M_I_CPU0_SA_CB<2>")
	)
	(arc
		(start 386.317744 -244.97157)
		(mid 386.499995 -244.92122)
		(end 386.683504 -244.966744)
		(width 0.0889)
		(layer "In2.Cu")
		(net "M_I_CPU0_SA_CB<2>")
	)
	(arc
		(start 379.737874 -244.97157)
		(mid 379.924818 -244.921315)
		(end 380.111762 -244.97157)
		(width 0.0889)
		(layer "In2.Cu")
		(net "M_I_CPU0_SA_CB<2>")
	)
	(arc
		(start 390.077706 -244.97157)
		(mid 390.259957 -244.92122)
		(end 390.443466 -244.966744)
		(width 0.0889)
		(layer "In2.Cu")
		(net "M_I_CPU0_SA_CB<2>")
	)
	(arc
		(start 392.35634 -244.987572)
		(mid 392.628374 -245.048344)
		(end 392.896344 -244.97157)
		(width 0.0889)
		(layer "In2.Cu")
		(net "M_I_CPU0_SA_CB<2>")
	)
	(arc
		(start 383.506218 -244.966744)
		(mid 383.689726 -244.92125)
		(end 383.871978 -244.97157)
		(width 0.0889)
		(layer "In2.Cu")
		(net "M_I_CPU0_SA_CB<2>")
	)
	(arc
		(start 387.63194 -244.97157)
		(mid 387.914896 -245.047747)
		(end 388.197852 -244.97157)
		(width 0.0889)
		(layer "In2.Cu")
		(net "M_I_CPU0_SA_CB<2>")
	)
	(arc
		(start 389.511794 -244.97157)
		(mid 389.79475 -245.047747)
		(end 390.077706 -244.97157)
		(width 0.0889)
		(layer "In2.Cu")
		(net "M_I_CPU0_SA_CB<2>")
	)
	(arc
		(start 380.111762 -244.97157)
		(mid 380.394718 -245.047747)
		(end 380.677674 -244.97157)
		(width 0.0889)
		(layer "In2.Cu")
		(net "M_I_CPU0_SA_CB<2>")
	)
	(arc
		(start 377.866148 -244.966744)
		(mid 378.049656 -244.92125)
		(end 378.231908 -244.97157)
		(width 0.0889)
		(layer "In2.Cu")
		(net "M_I_CPU0_SA_CB<2>")
	)
	(arc
		(start 392.896344 -244.97157)
		(mid 393.066351 -244.921005)
		(end 393.240514 -244.954552)
		(width 0.0889)
		(layer "In2.Cu")
		(net "M_I_CPU0_SA_CB<2>")
	)
	(arc
		(start 381.617728 -244.97157)
		(mid 381.799979 -244.92122)
		(end 381.983488 -244.966744)
		(width 0.0889)
		(layer "In2.Cu")
		(net "M_I_CPU0_SA_CB<2>")
	)
	(arc
		(start 386.691886 -244.97157)
		(mid 386.974842 -245.047747)
		(end 387.257798 -244.97157)
		(width 0.0889)
		(layer "In2.Cu")
		(net "M_I_CPU0_SA_CB<2>")
	)
	(arc
		(start 388.206234 -244.966744)
		(mid 388.389742 -244.92125)
		(end 388.571994 -244.97157)
		(width 0.0889)
		(layer "In2.Cu")
		(net "M_I_CPU0_SA_CB<2>")
	)
	(arc
		(start 377.354846 -245.00332)
		(mid 377.610054 -245.046797)
		(end 377.857766 -244.97157)
		(width 0.0889)
		(layer "In2.Cu")
		(net "M_I_CPU0_SA_CB<2>")
	)
	(arc
		(start 383.871978 -244.97157)
		(mid 384.154934 -245.047747)
		(end 384.43789 -244.97157)
		(width 0.0889)
		(layer "In2.Cu")
		(net "M_I_CPU0_SA_CB<2>")
	)
	(arc
		(start 380.677674 -244.97157)
		(mid 380.859925 -244.92122)
		(end 381.043434 -244.966744)
		(width 0.0889)
		(layer "In2.Cu")
		(net "M_I_CPU0_SA_CB<2>")
	)
	(arc
		(start 388.571994 -244.97157)
		(mid 388.85495 -245.047747)
		(end 389.137906 -244.97157)
		(width 0.0889)
		(layer "In2.Cu")
		(net "M_I_CPU0_SA_CB<2>")
	)
	(arc
		(start 384.811778 -244.97157)
		(mid 385.094734 -245.047747)
		(end 385.37769 -244.97157)
		(width 0.0889)
		(layer "In2.Cu")
		(net "M_I_CPU0_SA_CB<2>")
	)
	(arc
		(start 379.171962 -244.97157)
		(mid 379.454918 -245.047747)
		(end 379.737874 -244.97157)
		(width 0.0889)
		(layer "In2.Cu")
		(net "M_I_CPU0_SA_CB<2>")
	)
	(arc
		(start 378.231908 -244.97157)
		(mid 378.514864 -245.047747)
		(end 378.79782 -244.97157)
		(width 0.0889)
		(layer "In2.Cu")
		(net "M_I_CPU0_SA_CB<2>")
	)
	(arc
		(start 387.26618 -244.966744)
		(mid 387.449688 -244.92125)
		(end 387.63194 -244.97157)
		(width 0.0889)
		(layer "In2.Cu")
		(net "M_I_CPU0_SA_CB<2>")
	)
	(arc
		(start 385.751832 -244.97157)
		(mid 386.034788 -245.047747)
		(end 386.317744 -244.97157)
		(width 0.0889)
		(layer "In2.Cu")
		(net "M_I_CPU0_SA_CB<2>")
	)
	(arc
		(start 390.451848 -244.97157)
		(mid 390.734804 -245.047747)
		(end 391.01776 -244.97157)
		(width 0.0889)
		(layer "In2.Cu")
		(net "M_I_CPU0_SA_CB<2>")
	)
	(arc
		(start 391.391902 -244.97157)
		(mid 391.660222 -245.047678)
		(end 391.93216 -244.985794)
		(width 0.0889)
		(layer "In2.Cu")
		(net "M_I_CPU0_SA_CB<2>")
	)
	(arc
		(start 391.026142 -244.966744)
		(mid 391.20965 -244.92125)
		(end 391.391902 -244.97157)
		(width 0.0889)
		(layer "In2.Cu")
		(net "M_I_CPU0_SA_CB<2>")
	)
	(arc
		(start 384.43789 -244.97157)
		(mid 384.624834 -244.921315)
		(end 384.811778 -244.97157)
		(width 0.0889)
		(layer "In2.Cu")
		(net "M_I_CPU0_SA_CB<2>")
	)
	(segment
		(start 375.698004 -245.560088)
		(end 376.164856 -245.29415)
		(width 0.10668)
		(layer "F.Cu")
		(net "M_I_CPU0_SA_CB<1>")
	)
	(segment
		(start 390.443466 -245.621556)
		(end 390.451848 -245.61673)
		(width 0.0889)
		(layer "In2.Cu")
		(net "M_I_CPU0_SA_CB<1>")
	)
	(segment
		(start 376.343418 -245.621556)
		(end 376.3518 -245.61673)
		(width 0.0889)
		(layer "In2.Cu")
		(net "M_I_CPU0_SA_CB<1>")
	)
	(segment
		(start 404.656036 -244.69471)
		(end 408.110182 -241.240564)
		(width 0.14478)
		(layer "In2.Cu")
		(net "M_I_CPU0_SA_CB<1>")
	)
	(segment
		(start 392.897868 -245.61673)
		(end 392.90625 -245.621556)
		(width 0.0889)
		(layer "In2.Cu")
		(net "M_I_CPU0_SA_CB<1>")
	)
	(segment
		(start 394.987272 -245.674134)
		(end 395.966696 -244.69471)
		(width 0.0889)
		(layer "In2.Cu")
		(net "M_I_CPU0_SA_CB<1>")
	)
	(segment
		(start 376.010678 -245.55958)
		(end 376.03303 -245.642892)
		(width 0.0889)
		(layer "In2.Cu")
		(net "M_I_CPU0_SA_CB<1>")
	)
	(segment
		(start 377.857766 -245.61673)
		(end 377.866148 -245.621556)
		(width 0.0889)
		(layer "In2.Cu")
		(net "M_I_CPU0_SA_CB<1>")
	)
	(segment
		(start 388.197852 -245.61673)
		(end 388.206234 -245.621556)
		(width 0.0889)
		(layer "In2.Cu")
		(net "M_I_CPU0_SA_CB<1>")
	)
	(segment
		(start 376.164856 -245.29415)
		(end 376.010678 -245.55958)
		(width 0.0889)
		(layer "In2.Cu")
		(net "M_I_CPU0_SA_CB<1>")
	)
	(segment
		(start 423.536872 -236.010196)
		(end 431.131218 -236.010196)
		(width 0.14478)
		(layer "In2.Cu")
		(net "M_I_CPU0_SA_CB<1>")
	)
	(segment
		(start 393.936728 -245.674134)
		(end 394.987272 -245.674134)
		(width 0.0889)
		(layer "In2.Cu")
		(net "M_I_CPU0_SA_CB<1>")
	)
	(segment
		(start 378.79782 -245.61673)
		(end 378.806202 -245.621556)
		(width 0.0889)
		(layer "In2.Cu")
		(net "M_I_CPU0_SA_CB<1>")
	)
	(segment
		(start 412.549594 -236.86008)
		(end 414.228026 -236.52607)
		(width 0.14478)
		(layer "In2.Cu")
		(net "M_I_CPU0_SA_CB<1>")
	)
	(segment
		(start 415.473642 -236.010196)
		(end 417.714938 -236.010196)
		(width 0.14478)
		(layer "In2.Cu")
		(net "M_I_CPU0_SA_CB<1>")
	)
	(segment
		(start 420.223442 -236.86008)
		(end 420.607744 -236.763814)
		(width 0.14478)
		(layer "In2.Cu")
		(net "M_I_CPU0_SA_CB<1>")
	)
	(segment
		(start 419.767004 -236.86008)
		(end 420.223442 -236.86008)
		(width 0.14478)
		(layer "In2.Cu")
		(net "M_I_CPU0_SA_CB<1>")
	)
	(segment
		(start 382.557782 -245.61673)
		(end 382.566164 -245.621556)
		(width 0.0889)
		(layer "In2.Cu")
		(net "M_I_CPU0_SA_CB<1>")
	)
	(segment
		(start 417.714938 -236.010196)
		(end 419.767004 -236.86008)
		(width 0.14478)
		(layer "In2.Cu")
		(net "M_I_CPU0_SA_CB<1>")
	)
	(segment
		(start 411.361382 -236.86008)
		(end 412.549594 -236.86008)
		(width 0.14478)
		(layer "In2.Cu")
		(net "M_I_CPU0_SA_CB<1>")
	)
	(segment
		(start 381.043434 -245.621556)
		(end 381.051816 -245.61673)
		(width 0.0889)
		(layer "In2.Cu")
		(net "M_I_CPU0_SA_CB<1>")
	)
	(segment
		(start 395.966696 -244.69471)
		(end 404.656036 -244.69471)
		(width 0.14478)
		(layer "In2.Cu")
		(net "M_I_CPU0_SA_CB<1>")
	)
	(segment
		(start 392.323574 -245.621556)
		(end 392.331956 -245.61673)
		(width 0.0889)
		(layer "In2.Cu")
		(net "M_I_CPU0_SA_CB<1>")
	)
	(segment
		(start 385.74345 -245.621556)
		(end 385.751832 -245.61673)
		(width 0.0889)
		(layer "In2.Cu")
		(net "M_I_CPU0_SA_CB<1>")
	)
	(segment
		(start 420.607744 -236.763814)
		(end 422.242996 -236.267498)
		(width 0.14478)
		(layer "In2.Cu")
		(net "M_I_CPU0_SA_CB<1>")
	)
	(segment
		(start 381.983488 -245.621556)
		(end 381.99187 -245.61673)
		(width 0.0889)
		(layer "In2.Cu")
		(net "M_I_CPU0_SA_CB<1>")
	)
	(segment
		(start 431.131218 -236.010196)
		(end 431.55616 -236.435138)
		(width 0.14478)
		(layer "In2.Cu")
		(net "M_I_CPU0_SA_CB<1>")
	)
	(segment
		(start 391.01776 -245.61673)
		(end 391.026142 -245.621556)
		(width 0.0889)
		(layer "In2.Cu")
		(net "M_I_CPU0_SA_CB<1>")
	)
	(segment
		(start 387.257798 -245.61673)
		(end 387.26618 -245.621556)
		(width 0.0889)
		(layer "In2.Cu")
		(net "M_I_CPU0_SA_CB<1>")
	)
	(segment
		(start 422.242996 -236.267498)
		(end 423.536872 -236.010196)
		(width 0.14478)
		(layer "In2.Cu")
		(net "M_I_CPU0_SA_CB<1>")
	)
	(segment
		(start 393.837922 -245.61673)
		(end 393.936728 -245.674134)
		(width 0.0889)
		(layer "In2.Cu")
		(net "M_I_CPU0_SA_CB<1>")
	)
	(segment
		(start 377.283472 -245.621556)
		(end 377.291854 -245.61673)
		(width 0.0889)
		(layer "In2.Cu")
		(net "M_I_CPU0_SA_CB<1>")
	)
	(segment
		(start 408.110182 -241.240564)
		(end 408.110182 -240.11128)
		(width 0.14478)
		(layer "In2.Cu")
		(net "M_I_CPU0_SA_CB<1>")
	)
	(segment
		(start 386.683504 -245.621556)
		(end 386.691886 -245.61673)
		(width 0.0889)
		(layer "In2.Cu")
		(net "M_I_CPU0_SA_CB<1>")
	)
	(segment
		(start 414.228026 -236.52607)
		(end 415.473642 -236.010196)
		(width 0.14478)
		(layer "In2.Cu")
		(net "M_I_CPU0_SA_CB<1>")
	)
	(segment
		(start 383.497836 -245.61673)
		(end 383.506218 -245.621556)
		(width 0.0889)
		(layer "In2.Cu")
		(net "M_I_CPU0_SA_CB<1>")
	)
	(segment
		(start 408.110182 -240.11128)
		(end 411.361382 -236.86008)
		(width 0.14478)
		(layer "In2.Cu")
		(net "M_I_CPU0_SA_CB<1>")
	)
	(arc
		(start 388.206234 -245.621556)
		(mid 388.389742 -245.66705)
		(end 388.571994 -245.61673)
		(width 0.0889)
		(layer "In2.Cu")
		(net "M_I_CPU0_SA_CB<1>")
	)
	(arc
		(start 384.811778 -245.61673)
		(mid 385.094734 -245.540553)
		(end 385.37769 -245.61673)
		(width 0.0889)
		(layer "In2.Cu")
		(net "M_I_CPU0_SA_CB<1>")
	)
	(arc
		(start 382.566164 -245.621556)
		(mid 382.749672 -245.66705)
		(end 382.931924 -245.61673)
		(width 0.0889)
		(layer "In2.Cu")
		(net "M_I_CPU0_SA_CB<1>")
	)
	(arc
		(start 390.077706 -245.61673)
		(mid 390.259957 -245.66708)
		(end 390.443466 -245.621556)
		(width 0.0889)
		(layer "In2.Cu")
		(net "M_I_CPU0_SA_CB<1>")
	)
	(arc
		(start 376.3518 -245.61673)
		(mid 376.634756 -245.540553)
		(end 376.917712 -245.61673)
		(width 0.0889)
		(layer "In2.Cu")
		(net "M_I_CPU0_SA_CB<1>")
	)
	(arc
		(start 381.99187 -245.61673)
		(mid 382.274826 -245.540553)
		(end 382.557782 -245.61673)
		(width 0.0889)
		(layer "In2.Cu")
		(net "M_I_CPU0_SA_CB<1>")
	)
	(arc
		(start 380.677674 -245.61673)
		(mid 380.859925 -245.66708)
		(end 381.043434 -245.621556)
		(width 0.0889)
		(layer "In2.Cu")
		(net "M_I_CPU0_SA_CB<1>")
	)
	(arc
		(start 379.171962 -245.61673)
		(mid 379.454918 -245.540553)
		(end 379.737874 -245.61673)
		(width 0.0889)
		(layer "In2.Cu")
		(net "M_I_CPU0_SA_CB<1>")
	)
	(arc
		(start 381.617728 -245.61673)
		(mid 381.799979 -245.66708)
		(end 381.983488 -245.621556)
		(width 0.0889)
		(layer "In2.Cu")
		(net "M_I_CPU0_SA_CB<1>")
	)
	(arc
		(start 387.63194 -245.61673)
		(mid 387.914896 -245.540553)
		(end 388.197852 -245.61673)
		(width 0.0889)
		(layer "In2.Cu")
		(net "M_I_CPU0_SA_CB<1>")
	)
	(arc
		(start 380.111762 -245.61673)
		(mid 380.394718 -245.540553)
		(end 380.677674 -245.61673)
		(width 0.0889)
		(layer "In2.Cu")
		(net "M_I_CPU0_SA_CB<1>")
	)
	(arc
		(start 382.931924 -245.61673)
		(mid 383.21488 -245.540553)
		(end 383.497836 -245.61673)
		(width 0.0889)
		(layer "In2.Cu")
		(net "M_I_CPU0_SA_CB<1>")
	)
	(arc
		(start 393.27201 -245.61673)
		(mid 393.554966 -245.540553)
		(end 393.837922 -245.61673)
		(width 0.0889)
		(layer "In2.Cu")
		(net "M_I_CPU0_SA_CB<1>")
	)
	(arc
		(start 378.231908 -245.61673)
		(mid 378.514864 -245.540553)
		(end 378.79782 -245.61673)
		(width 0.0889)
		(layer "In2.Cu")
		(net "M_I_CPU0_SA_CB<1>")
	)
	(arc
		(start 391.391902 -245.61673)
		(mid 391.674858 -245.540553)
		(end 391.957814 -245.61673)
		(width 0.0889)
		(layer "In2.Cu")
		(net "M_I_CPU0_SA_CB<1>")
	)
	(arc
		(start 377.291854 -245.61673)
		(mid 377.57481 -245.540553)
		(end 377.857766 -245.61673)
		(width 0.0889)
		(layer "In2.Cu")
		(net "M_I_CPU0_SA_CB<1>")
	)
	(arc
		(start 377.866148 -245.621556)
		(mid 378.049656 -245.66705)
		(end 378.231908 -245.61673)
		(width 0.0889)
		(layer "In2.Cu")
		(net "M_I_CPU0_SA_CB<1>")
	)
	(arc
		(start 383.506218 -245.621556)
		(mid 383.689726 -245.66705)
		(end 383.871978 -245.61673)
		(width 0.0889)
		(layer "In2.Cu")
		(net "M_I_CPU0_SA_CB<1>")
	)
	(arc
		(start 389.511794 -245.61673)
		(mid 389.79475 -245.540553)
		(end 390.077706 -245.61673)
		(width 0.0889)
		(layer "In2.Cu")
		(net "M_I_CPU0_SA_CB<1>")
	)
	(arc
		(start 391.026142 -245.621556)
		(mid 391.20965 -245.66705)
		(end 391.391902 -245.61673)
		(width 0.0889)
		(layer "In2.Cu")
		(net "M_I_CPU0_SA_CB<1>")
	)
	(arc
		(start 392.331956 -245.61673)
		(mid 392.614912 -245.540553)
		(end 392.897868 -245.61673)
		(width 0.0889)
		(layer "In2.Cu")
		(net "M_I_CPU0_SA_CB<1>")
	)
	(arc
		(start 389.137906 -245.61673)
		(mid 389.32485 -245.666985)
		(end 389.511794 -245.61673)
		(width 0.0889)
		(layer "In2.Cu")
		(net "M_I_CPU0_SA_CB<1>")
	)
	(arc
		(start 376.917712 -245.61673)
		(mid 377.099963 -245.66708)
		(end 377.283472 -245.621556)
		(width 0.0889)
		(layer "In2.Cu")
		(net "M_I_CPU0_SA_CB<1>")
	)
	(arc
		(start 392.90625 -245.621556)
		(mid 393.089758 -245.66705)
		(end 393.27201 -245.61673)
		(width 0.0889)
		(layer "In2.Cu")
		(net "M_I_CPU0_SA_CB<1>")
	)
	(arc
		(start 381.051816 -245.61673)
		(mid 381.334772 -245.540553)
		(end 381.617728 -245.61673)
		(width 0.0889)
		(layer "In2.Cu")
		(net "M_I_CPU0_SA_CB<1>")
	)
	(arc
		(start 383.871978 -245.61673)
		(mid 384.154934 -245.540553)
		(end 384.43789 -245.61673)
		(width 0.0889)
		(layer "In2.Cu")
		(net "M_I_CPU0_SA_CB<1>")
	)
	(arc
		(start 379.737874 -245.61673)
		(mid 379.924818 -245.666985)
		(end 380.111762 -245.61673)
		(width 0.0889)
		(layer "In2.Cu")
		(net "M_I_CPU0_SA_CB<1>")
	)
	(arc
		(start 384.43789 -245.61673)
		(mid 384.624834 -245.666985)
		(end 384.811778 -245.61673)
		(width 0.0889)
		(layer "In2.Cu")
		(net "M_I_CPU0_SA_CB<1>")
	)
	(arc
		(start 386.317744 -245.61673)
		(mid 386.499995 -245.66708)
		(end 386.683504 -245.621556)
		(width 0.0889)
		(layer "In2.Cu")
		(net "M_I_CPU0_SA_CB<1>")
	)
	(arc
		(start 391.957814 -245.61673)
		(mid 392.140065 -245.66708)
		(end 392.323574 -245.621556)
		(width 0.0889)
		(layer "In2.Cu")
		(net "M_I_CPU0_SA_CB<1>")
	)
	(arc
		(start 378.806202 -245.621556)
		(mid 378.98971 -245.66705)
		(end 379.171962 -245.61673)
		(width 0.0889)
		(layer "In2.Cu")
		(net "M_I_CPU0_SA_CB<1>")
	)
	(arc
		(start 386.691886 -245.61673)
		(mid 386.974842 -245.540553)
		(end 387.257798 -245.61673)
		(width 0.0889)
		(layer "In2.Cu")
		(net "M_I_CPU0_SA_CB<1>")
	)
	(arc
		(start 388.571994 -245.61673)
		(mid 388.85495 -245.540553)
		(end 389.137906 -245.61673)
		(width 0.0889)
		(layer "In2.Cu")
		(net "M_I_CPU0_SA_CB<1>")
	)
	(arc
		(start 385.37769 -245.61673)
		(mid 385.559941 -245.66708)
		(end 385.74345 -245.621556)
		(width 0.0889)
		(layer "In2.Cu")
		(net "M_I_CPU0_SA_CB<1>")
	)
	(arc
		(start 376.03303 -245.642892)
		(mid 376.19054 -245.66609)
		(end 376.343418 -245.621556)
		(width 0.0889)
		(layer "In2.Cu")
		(net "M_I_CPU0_SA_CB<1>")
	)
	(arc
		(start 387.26618 -245.621556)
		(mid 387.449688 -245.66705)
		(end 387.63194 -245.61673)
		(width 0.0889)
		(layer "In2.Cu")
		(net "M_I_CPU0_SA_CB<1>")
	)
	(arc
		(start 385.751832 -245.61673)
		(mid 386.034788 -245.540553)
		(end 386.317744 -245.61673)
		(width 0.0889)
		(layer "In2.Cu")
		(net "M_I_CPU0_SA_CB<1>")
	)
	(arc
		(start 390.451848 -245.61673)
		(mid 390.734804 -245.540553)
		(end 391.01776 -245.61673)
		(width 0.0889)
		(layer "In2.Cu")
		(net "M_I_CPU0_SA_CB<1>")
	)
	(segment
		(start 377.107958 -244.750082)
		(end 377.57481 -244.484144)
		(width 0.10668)
		(layer "F.Cu")
		(net "M_I_CPU0_SA_CB<0>")
	)
	(segment
		(start 389.033512 -244.81155)
		(end 389.041894 -244.806724)
		(width 0.0889)
		(layer "In2.Cu")
		(net "M_I_CPU0_SA_CB<0>")
	)
	(segment
		(start 429.511968 -234.310174)
		(end 429.744632 -234.310174)
		(width 0.14478)
		(layer "In2.Cu")
		(net "M_I_CPU0_SA_CB<0>")
	)
	(segment
		(start 420.803832 -235.160058)
		(end 422.855644 -234.310174)
		(width 0.14478)
		(layer "In2.Cu")
		(net "M_I_CPU0_SA_CB<0>")
	)
	(segment
		(start 388.093458 -244.81155)
		(end 388.10184 -244.806724)
		(width 0.0889)
		(layer "In2.Cu")
		(net "M_I_CPU0_SA_CB<0>")
	)
	(segment
		(start 393.551664 -244.856508)
		(end 393.971018 -244.856508)
		(width 0.0889)
		(layer "In2.Cu")
		(net "M_I_CPU0_SA_CB<0>")
	)
	(segment
		(start 415.291016 -234.310428)
		(end 415.291778 -234.310174)
		(width 0.14478)
		(layer "In2.Cu")
		(net "M_I_CPU0_SA_CB<0>")
	)
	(segment
		(start 422.855644 -234.310174)
		(end 425.237656 -234.310174)
		(width 0.14478)
		(layer "In2.Cu")
		(net "M_I_CPU0_SA_CB<0>")
	)
	(segment
		(start 402.9837 -243.78031)
		(end 411.603952 -235.160058)
		(width 0.14478)
		(layer "In2.Cu")
		(net "M_I_CPU0_SA_CB<0>")
	)
	(segment
		(start 392.424666 -244.806724)
		(end 392.44524 -244.818662)
		(width 0.0889)
		(layer "In2.Cu")
		(net "M_I_CPU0_SA_CB<0>")
	)
	(segment
		(start 428.953168 -234.63631)
		(end 429.185832 -234.63631)
		(width 0.14478)
		(layer "In2.Cu")
		(net "M_I_CPU0_SA_CB<0>")
	)
	(segment
		(start 383.393442 -244.81155)
		(end 383.401824 -244.806724)
		(width 0.0889)
		(layer "In2.Cu")
		(net "M_I_CPU0_SA_CB<0>")
	)
	(segment
		(start 430.070768 -234.63631)
		(end 430.303432 -234.63631)
		(width 0.14478)
		(layer "In2.Cu")
		(net "M_I_CPU0_SA_CB<0>")
	)
	(segment
		(start 430.629568 -234.310174)
		(end 431.131218 -234.310174)
		(width 0.14478)
		(layer "In2.Cu")
		(net "M_I_CPU0_SA_CB<0>")
	)
	(segment
		(start 425.796456 -234.63631)
		(end 426.122592 -234.310174)
		(width 0.14478)
		(layer "In2.Cu")
		(net "M_I_CPU0_SA_CB<0>")
	)
	(segment
		(start 431.131218 -234.310174)
		(end 431.55616 -234.735116)
		(width 0.14478)
		(layer "In2.Cu")
		(net "M_I_CPU0_SA_CB<0>")
	)
	(segment
		(start 418.983668 -235.160058)
		(end 420.803832 -235.160058)
		(width 0.14478)
		(layer "In2.Cu")
		(net "M_I_CPU0_SA_CB<0>")
	)
	(segment
		(start 425.563792 -234.63631)
		(end 425.796456 -234.63631)
		(width 0.14478)
		(layer "In2.Cu")
		(net "M_I_CPU0_SA_CB<0>")
	)
	(segment
		(start 411.603952 -235.160058)
		(end 414.441386 -235.160058)
		(width 0.14478)
		(layer "In2.Cu")
		(net "M_I_CPU0_SA_CB<0>")
	)
	(segment
		(start 393.32789 -244.784626)
		(end 393.365736 -244.80647)
		(width 0.0889)
		(layer "In2.Cu")
		(net "M_I_CPU0_SA_CB<0>")
	)
	(segment
		(start 415.291778 -234.310174)
		(end 418.133784 -234.310174)
		(width 0.14478)
		(layer "In2.Cu")
		(net "M_I_CPU0_SA_CB<0>")
	)
	(segment
		(start 414.441386 -235.160058)
		(end 415.291016 -234.310428)
		(width 0.14478)
		(layer "In2.Cu")
		(net "M_I_CPU0_SA_CB<0>")
	)
	(segment
		(start 429.185832 -234.63631)
		(end 429.511968 -234.310174)
		(width 0.14478)
		(layer "In2.Cu")
		(net "M_I_CPU0_SA_CB<0>")
	)
	(segment
		(start 391.860532 -244.80647)
		(end 391.884408 -244.7925)
		(width 0.0889)
		(layer "In2.Cu")
		(net "M_I_CPU0_SA_CB<0>")
	)
	(segment
		(start 418.133784 -234.310174)
		(end 418.983668 -235.160058)
		(width 0.14478)
		(layer "In2.Cu")
		(net "M_I_CPU0_SA_CB<0>")
	)
	(segment
		(start 393.971018 -244.856508)
		(end 394.455396 -244.37213)
		(width 0.0889)
		(layer "In2.Cu")
		(net "M_I_CPU0_SA_CB<0>")
	)
	(segment
		(start 430.303432 -234.63631)
		(end 430.629568 -234.310174)
		(width 0.14478)
		(layer "In2.Cu")
		(net "M_I_CPU0_SA_CB<0>")
	)
	(segment
		(start 384.333496 -244.81155)
		(end 384.341878 -244.806724)
		(width 0.0889)
		(layer "In2.Cu")
		(net "M_I_CPU0_SA_CB<0>")
	)
	(segment
		(start 377.420886 -244.749574)
		(end 377.443238 -244.832886)
		(width 0.0889)
		(layer "In2.Cu")
		(net "M_I_CPU0_SA_CB<0>")
	)
	(segment
		(start 428.627032 -234.310174)
		(end 428.953168 -234.63631)
		(width 0.14478)
		(layer "In2.Cu")
		(net "M_I_CPU0_SA_CB<0>")
	)
	(segment
		(start 391.837164 -244.819932)
		(end 391.860532 -244.80647)
		(width 0.0889)
		(layer "In2.Cu")
		(net "M_I_CPU0_SA_CB<0>")
	)
	(segment
		(start 395.014196 -244.37213)
		(end 395.606016 -243.78031)
		(width 0.0889)
		(layer "In2.Cu")
		(net "M_I_CPU0_SA_CB<0>")
	)
	(segment
		(start 429.744632 -234.310174)
		(end 430.070768 -234.63631)
		(width 0.14478)
		(layer "In2.Cu")
		(net "M_I_CPU0_SA_CB<0>")
	)
	(segment
		(start 381.147828 -244.806724)
		(end 381.15621 -244.81155)
		(width 0.0889)
		(layer "In2.Cu")
		(net "M_I_CPU0_SA_CB<0>")
	)
	(segment
		(start 425.237656 -234.310174)
		(end 425.563792 -234.63631)
		(width 0.14478)
		(layer "In2.Cu")
		(net "M_I_CPU0_SA_CB<0>")
	)
	(segment
		(start 384.90779 -244.806724)
		(end 384.916172 -244.81155)
		(width 0.0889)
		(layer "In2.Cu")
		(net "M_I_CPU0_SA_CB<0>")
	)
	(segment
		(start 380.207774 -244.806724)
		(end 380.216156 -244.81155)
		(width 0.0889)
		(layer "In2.Cu")
		(net "M_I_CPU0_SA_CB<0>")
	)
	(segment
		(start 377.57481 -244.484144)
		(end 377.420886 -244.749574)
		(width 0.0889)
		(layer "In2.Cu")
		(net "M_I_CPU0_SA_CB<0>")
	)
	(segment
		(start 385.847844 -244.806724)
		(end 385.856226 -244.81155)
		(width 0.0889)
		(layer "In2.Cu")
		(net "M_I_CPU0_SA_CB<0>")
	)
	(segment
		(start 395.606016 -243.78031)
		(end 402.9837 -243.78031)
		(width 0.14478)
		(layer "In2.Cu")
		(net "M_I_CPU0_SA_CB<0>")
	)
	(segment
		(start 389.607806 -244.806724)
		(end 389.616188 -244.81155)
		(width 0.0889)
		(layer "In2.Cu")
		(net "M_I_CPU0_SA_CB<0>")
	)
	(segment
		(start 379.63348 -244.81155)
		(end 379.641862 -244.806724)
		(width 0.0889)
		(layer "In2.Cu")
		(net "M_I_CPU0_SA_CB<0>")
	)
	(segment
		(start 394.455396 -244.37213)
		(end 395.014196 -244.37213)
		(width 0.0889)
		(layer "In2.Cu")
		(net "M_I_CPU0_SA_CB<0>")
	)
	(segment
		(start 426.122592 -234.310174)
		(end 428.627032 -234.310174)
		(width 0.14478)
		(layer "In2.Cu")
		(net "M_I_CPU0_SA_CB<0>")
	)
	(segment
		(start 378.693426 -244.81155)
		(end 378.701808 -244.806724)
		(width 0.0889)
		(layer "In2.Cu")
		(net "M_I_CPU0_SA_CB<0>")
	)
	(arc
		(start 380.216156 -244.81155)
		(mid 380.399664 -244.857044)
		(end 380.581916 -244.806724)
		(width 0.0889)
		(layer "In2.Cu")
		(net "M_I_CPU0_SA_CB<0>")
	)
	(arc
		(start 392.44524 -244.818662)
		(mid 392.624168 -244.857539)
		(end 392.800078 -244.806724)
		(width 0.0889)
		(layer "In2.Cu")
		(net "M_I_CPU0_SA_CB<0>")
	)
	(arc
		(start 387.727698 -244.806724)
		(mid 387.909949 -244.857074)
		(end 388.093458 -244.81155)
		(width 0.0889)
		(layer "In2.Cu")
		(net "M_I_CPU0_SA_CB<0>")
	)
	(arc
		(start 387.161786 -244.806724)
		(mid 387.444742 -244.730547)
		(end 387.727698 -244.806724)
		(width 0.0889)
		(layer "In2.Cu")
		(net "M_I_CPU0_SA_CB<0>")
	)
	(arc
		(start 386.787898 -244.806724)
		(mid 386.974842 -244.856979)
		(end 387.161786 -244.806724)
		(width 0.0889)
		(layer "In2.Cu")
		(net "M_I_CPU0_SA_CB<0>")
	)
	(arc
		(start 381.15621 -244.81155)
		(mid 381.339718 -244.857044)
		(end 381.52197 -244.806724)
		(width 0.0889)
		(layer "In2.Cu")
		(net "M_I_CPU0_SA_CB<0>")
	)
	(arc
		(start 391.884408 -244.7925)
		(mid 392.156345 -244.730674)
		(end 392.424666 -244.806724)
		(width 0.0889)
		(layer "In2.Cu")
		(net "M_I_CPU0_SA_CB<0>")
	)
	(arc
		(start 390.54786 -244.806724)
		(mid 390.734804 -244.856979)
		(end 390.921748 -244.806724)
		(width 0.0889)
		(layer "In2.Cu")
		(net "M_I_CPU0_SA_CB<0>")
	)
	(arc
		(start 391.48766 -244.806724)
		(mid 391.660768 -244.85684)
		(end 391.837164 -244.819932)
		(width 0.0889)
		(layer "In2.Cu")
		(net "M_I_CPU0_SA_CB<0>")
	)
	(arc
		(start 388.667752 -244.806724)
		(mid 388.850003 -244.857074)
		(end 389.033512 -244.81155)
		(width 0.0889)
		(layer "In2.Cu")
		(net "M_I_CPU0_SA_CB<0>")
	)
	(arc
		(start 383.401824 -244.806724)
		(mid 383.68478 -244.730547)
		(end 383.967736 -244.806724)
		(width 0.0889)
		(layer "In2.Cu")
		(net "M_I_CPU0_SA_CB<0>")
	)
	(arc
		(start 389.616188 -244.81155)
		(mid 389.799696 -244.857044)
		(end 389.981948 -244.806724)
		(width 0.0889)
		(layer "In2.Cu")
		(net "M_I_CPU0_SA_CB<0>")
	)
	(arc
		(start 379.26772 -244.806724)
		(mid 379.449971 -244.857074)
		(end 379.63348 -244.81155)
		(width 0.0889)
		(layer "In2.Cu")
		(net "M_I_CPU0_SA_CB<0>")
	)
	(arc
		(start 382.46177 -244.806724)
		(mid 382.744726 -244.730547)
		(end 383.027682 -244.806724)
		(width 0.0889)
		(layer "In2.Cu")
		(net "M_I_CPU0_SA_CB<0>")
	)
	(arc
		(start 377.443238 -244.832886)
		(mid 377.605427 -244.855621)
		(end 377.761754 -244.806724)
		(width 0.0889)
		(layer "In2.Cu")
		(net "M_I_CPU0_SA_CB<0>")
	)
	(arc
		(start 384.341878 -244.806724)
		(mid 384.624834 -244.730547)
		(end 384.90779 -244.806724)
		(width 0.0889)
		(layer "In2.Cu")
		(net "M_I_CPU0_SA_CB<0>")
	)
	(arc
		(start 378.327666 -244.806724)
		(mid 378.509917 -244.857074)
		(end 378.693426 -244.81155)
		(width 0.0889)
		(layer "In2.Cu")
		(net "M_I_CPU0_SA_CB<0>")
	)
	(arc
		(start 382.087882 -244.806724)
		(mid 382.274826 -244.856979)
		(end 382.46177 -244.806724)
		(width 0.0889)
		(layer "In2.Cu")
		(net "M_I_CPU0_SA_CB<0>")
	)
	(arc
		(start 389.041894 -244.806724)
		(mid 389.32485 -244.730547)
		(end 389.607806 -244.806724)
		(width 0.0889)
		(layer "In2.Cu")
		(net "M_I_CPU0_SA_CB<0>")
	)
	(arc
		(start 377.761754 -244.806724)
		(mid 378.04471 -244.730547)
		(end 378.327666 -244.806724)
		(width 0.0889)
		(layer "In2.Cu")
		(net "M_I_CPU0_SA_CB<0>")
	)
	(arc
		(start 385.281932 -244.806724)
		(mid 385.564888 -244.730547)
		(end 385.847844 -244.806724)
		(width 0.0889)
		(layer "In2.Cu")
		(net "M_I_CPU0_SA_CB<0>")
	)
	(arc
		(start 390.921748 -244.806724)
		(mid 391.204704 -244.730547)
		(end 391.48766 -244.806724)
		(width 0.0889)
		(layer "In2.Cu")
		(net "M_I_CPU0_SA_CB<0>")
	)
	(arc
		(start 378.701808 -244.806724)
		(mid 378.984764 -244.730547)
		(end 379.26772 -244.806724)
		(width 0.0889)
		(layer "In2.Cu")
		(net "M_I_CPU0_SA_CB<0>")
	)
	(arc
		(start 383.967736 -244.806724)
		(mid 384.149987 -244.857074)
		(end 384.333496 -244.81155)
		(width 0.0889)
		(layer "In2.Cu")
		(net "M_I_CPU0_SA_CB<0>")
	)
	(arc
		(start 389.981948 -244.806724)
		(mid 390.264904 -244.730547)
		(end 390.54786 -244.806724)
		(width 0.0889)
		(layer "In2.Cu")
		(net "M_I_CPU0_SA_CB<0>")
	)
	(arc
		(start 379.641862 -244.806724)
		(mid 379.924818 -244.730547)
		(end 380.207774 -244.806724)
		(width 0.0889)
		(layer "In2.Cu")
		(net "M_I_CPU0_SA_CB<0>")
	)
	(arc
		(start 381.52197 -244.806724)
		(mid 381.804926 -244.730547)
		(end 382.087882 -244.806724)
		(width 0.0889)
		(layer "In2.Cu")
		(net "M_I_CPU0_SA_CB<0>")
	)
	(arc
		(start 388.10184 -244.806724)
		(mid 388.384796 -244.730547)
		(end 388.667752 -244.806724)
		(width 0.0889)
		(layer "In2.Cu")
		(net "M_I_CPU0_SA_CB<0>")
	)
	(arc
		(start 380.581916 -244.806724)
		(mid 380.864872 -244.730547)
		(end 381.147828 -244.806724)
		(width 0.0889)
		(layer "In2.Cu")
		(net "M_I_CPU0_SA_CB<0>")
	)
	(arc
		(start 392.800078 -244.806724)
		(mid 393.061236 -244.730145)
		(end 393.32789 -244.784626)
		(width 0.0889)
		(layer "In2.Cu")
		(net "M_I_CPU0_SA_CB<0>")
	)
	(arc
		(start 385.856226 -244.81155)
		(mid 386.039734 -244.857044)
		(end 386.221986 -244.806724)
		(width 0.0889)
		(layer "In2.Cu")
		(net "M_I_CPU0_SA_CB<0>")
	)
	(arc
		(start 383.027682 -244.806724)
		(mid 383.209933 -244.857074)
		(end 383.393442 -244.81155)
		(width 0.0889)
		(layer "In2.Cu")
		(net "M_I_CPU0_SA_CB<0>")
	)
	(arc
		(start 384.916172 -244.81155)
		(mid 385.09968 -244.857044)
		(end 385.281932 -244.806724)
		(width 0.0889)
		(layer "In2.Cu")
		(net "M_I_CPU0_SA_CB<0>")
	)
	(arc
		(start 386.221986 -244.806724)
		(mid 386.504942 -244.730547)
		(end 386.787898 -244.806724)
		(width 0.0889)
		(layer "In2.Cu")
		(net "M_I_CPU0_SA_CB<0>")
	)
	(arc
		(start 393.365736 -244.80647)
		(mid 393.455406 -244.843738)
		(end 393.551664 -244.856508)
		(width 0.0889)
		(layer "In2.Cu")
		(net "M_I_CPU0_SA_CB<0>")
	)
	(segment
		(start 375.698004 -255.28016)
		(end 376.164856 -255.014222)
		(width 0.10668)
		(layer "F.Cu")
		(net "M_I_CPU0_SA_CA<6>")
	)
	(segment
		(start 383.497836 -255.336802)
		(end 383.506218 -255.341628)
		(width 0.0889)
		(layer "In2.Cu")
		(net "M_I_CPU0_SA_CA<6>")
	)
	(segment
		(start 377.283472 -255.341628)
		(end 377.291854 -255.336802)
		(width 0.0889)
		(layer "In2.Cu")
		(net "M_I_CPU0_SA_CA<6>")
	)
	(segment
		(start 377.857766 -255.336802)
		(end 377.866148 -255.341628)
		(width 0.0889)
		(layer "In2.Cu")
		(net "M_I_CPU0_SA_CA<6>")
	)
	(segment
		(start 400.213068 -254.644652)
		(end 403.754082 -254.644652)
		(width 0.14478)
		(layer "In2.Cu")
		(net "M_I_CPU0_SA_CA<6>")
	)
	(segment
		(start 425.842938 -252.768862)
		(end 426.78604 -252.37821)
		(width 0.14478)
		(layer "In2.Cu")
		(net "M_I_CPU0_SA_CA<6>")
	)
	(segment
		(start 427.641512 -252.160024)
		(end 431.131218 -252.160024)
		(width 0.14478)
		(layer "In2.Cu")
		(net "M_I_CPU0_SA_CA<6>")
	)
	(segment
		(start 426.78604 -252.37821)
		(end 427.058074 -252.37821)
		(width 0.14478)
		(layer "In2.Cu")
		(net "M_I_CPU0_SA_CA<6>")
	)
	(segment
		(start 423.20464 -253.860046)
		(end 424.751754 -253.860046)
		(width 0.14478)
		(layer "In2.Cu")
		(net "M_I_CPU0_SA_CA<6>")
	)
	(segment
		(start 427.058074 -252.37821)
		(end 427.21911 -252.217174)
		(width 0.14478)
		(layer "In2.Cu")
		(net "M_I_CPU0_SA_CA<6>")
	)
	(segment
		(start 378.79782 -255.336802)
		(end 378.806202 -255.341628)
		(width 0.0889)
		(layer "In2.Cu")
		(net "M_I_CPU0_SA_CA<6>")
	)
	(segment
		(start 376.343418 -255.341628)
		(end 376.3518 -255.336802)
		(width 0.0889)
		(layer "In2.Cu")
		(net "M_I_CPU0_SA_CA<6>")
	)
	(segment
		(start 395.248638 -255.912112)
		(end 398.945608 -255.912112)
		(width 0.14478)
		(layer "In2.Cu")
		(net "M_I_CPU0_SA_CA<6>")
	)
	(segment
		(start 398.945608 -255.912112)
		(end 400.213068 -254.644652)
		(width 0.14478)
		(layer "In2.Cu")
		(net "M_I_CPU0_SA_CA<6>")
	)
	(segment
		(start 421.645588 -254.710184)
		(end 422.855644 -254.209042)
		(width 0.14478)
		(layer "In2.Cu")
		(net "M_I_CPU0_SA_CA<6>")
	)
	(segment
		(start 381.983488 -255.341628)
		(end 381.99187 -255.336802)
		(width 0.0889)
		(layer "In2.Cu")
		(net "M_I_CPU0_SA_CA<6>")
	)
	(segment
		(start 410.990034 -255.116076)
		(end 411.969966 -254.710184)
		(width 0.14478)
		(layer "In2.Cu")
		(net "M_I_CPU0_SA_CA<6>")
	)
	(segment
		(start 427.21911 -252.217174)
		(end 427.225714 -252.217174)
		(width 0.0889)
		(layer "In2.Cu")
		(net "M_I_CPU0_SA_CA<6>")
	)
	(segment
		(start 427.225714 -252.217174)
		(end 427.282864 -252.160024)
		(width 0.0889)
		(layer "In2.Cu")
		(net "M_I_CPU0_SA_CA<6>")
	)
	(segment
		(start 404.225506 -255.116076)
		(end 410.990034 -255.116076)
		(width 0.14478)
		(layer "In2.Cu")
		(net "M_I_CPU0_SA_CA<6>")
	)
	(segment
		(start 431.131218 -252.160024)
		(end 431.55616 -252.584966)
		(width 0.14478)
		(layer "In2.Cu")
		(net "M_I_CPU0_SA_CA<6>")
	)
	(segment
		(start 403.754082 -254.644652)
		(end 404.225506 -255.116076)
		(width 0.14478)
		(layer "In2.Cu")
		(net "M_I_CPU0_SA_CA<6>")
	)
	(segment
		(start 386.683504 -255.341628)
		(end 386.691886 -255.336802)
		(width 0.0889)
		(layer "In2.Cu")
		(net "M_I_CPU0_SA_CA<6>")
	)
	(segment
		(start 391.391902 -255.336802)
		(end 391.406634 -255.328166)
		(width 0.0889)
		(layer "In2.Cu")
		(net "M_I_CPU0_SA_CA<6>")
	)
	(segment
		(start 393.240006 -255.336294)
		(end 393.325096 -255.301242)
		(width 0.0889)
		(layer "In2.Cu")
		(net "M_I_CPU0_SA_CA<6>")
	)
	(segment
		(start 391.01776 -255.336802)
		(end 391.026142 -255.341628)
		(width 0.0889)
		(layer "In2.Cu")
		(net "M_I_CPU0_SA_CA<6>")
	)
	(segment
		(start 394.680694 -255.569974)
		(end 395.022832 -255.912112)
		(width 0.0889)
		(layer "In2.Cu")
		(net "M_I_CPU0_SA_CA<6>")
	)
	(segment
		(start 394.384276 -255.5367)
		(end 394.60043 -255.5367)
		(width 0.0889)
		(layer "In2.Cu")
		(net "M_I_CPU0_SA_CA<6>")
	)
	(segment
		(start 385.74345 -255.341628)
		(end 385.751832 -255.336802)
		(width 0.0889)
		(layer "In2.Cu")
		(net "M_I_CPU0_SA_CA<6>")
	)
	(segment
		(start 388.197852 -255.336802)
		(end 388.206234 -255.341628)
		(width 0.0889)
		(layer "In2.Cu")
		(net "M_I_CPU0_SA_CA<6>")
	)
	(segment
		(start 382.557782 -255.336802)
		(end 382.566164 -255.341628)
		(width 0.0889)
		(layer "In2.Cu")
		(net "M_I_CPU0_SA_CA<6>")
	)
	(segment
		(start 393.127992 -255.365504)
		(end 393.2174 -255.34366)
		(width 0.0889)
		(layer "In2.Cu")
		(net "M_I_CPU0_SA_CA<6>")
	)
	(segment
		(start 376.164856 -255.014222)
		(end 376.010678 -255.279652)
		(width 0.0889)
		(layer "In2.Cu")
		(net "M_I_CPU0_SA_CA<6>")
	)
	(segment
		(start 422.855644 -254.209042)
		(end 423.20464 -253.860046)
		(width 0.14478)
		(layer "In2.Cu")
		(net "M_I_CPU0_SA_CA<6>")
	)
	(segment
		(start 392.321034 -255.34366)
		(end 392.332718 -255.336802)
		(width 0.0889)
		(layer "In2.Cu")
		(net "M_I_CPU0_SA_CA<6>")
	)
	(segment
		(start 411.969966 -254.710184)
		(end 421.645588 -254.710184)
		(width 0.14478)
		(layer "In2.Cu")
		(net "M_I_CPU0_SA_CA<6>")
	)
	(segment
		(start 427.282864 -252.160024)
		(end 427.641512 -252.160024)
		(width 0.0889)
		(layer "In2.Cu")
		(net "M_I_CPU0_SA_CA<6>")
	)
	(segment
		(start 395.022832 -255.912112)
		(end 395.248638 -255.912112)
		(width 0.0889)
		(layer "In2.Cu")
		(net "M_I_CPU0_SA_CA<6>")
	)
	(segment
		(start 387.257798 -255.336802)
		(end 387.26618 -255.341628)
		(width 0.0889)
		(layer "In2.Cu")
		(net "M_I_CPU0_SA_CA<6>")
	)
	(segment
		(start 376.010678 -255.279652)
		(end 376.03303 -255.362964)
		(width 0.0889)
		(layer "In2.Cu")
		(net "M_I_CPU0_SA_CA<6>")
	)
	(segment
		(start 424.751754 -253.860046)
		(end 425.842938 -252.768862)
		(width 0.14478)
		(layer "In2.Cu")
		(net "M_I_CPU0_SA_CA<6>")
	)
	(segment
		(start 390.443466 -255.341628)
		(end 390.451848 -255.336802)
		(width 0.0889)
		(layer "In2.Cu")
		(net "M_I_CPU0_SA_CA<6>")
	)
	(segment
		(start 381.043434 -255.341628)
		(end 381.051816 -255.336802)
		(width 0.0889)
		(layer "In2.Cu")
		(net "M_I_CPU0_SA_CA<6>")
	)
	(segment
		(start 393.127484 -255.365504)
		(end 393.127992 -255.365504)
		(width 0.0889)
		(layer "In2.Cu")
		(net "M_I_CPU0_SA_CA<6>")
	)
	(arc
		(start 391.406634 -255.328166)
		(mid 391.683617 -255.260362)
		(end 391.958322 -255.336802)
		(width 0.0889)
		(layer "In2.Cu")
		(net "M_I_CPU0_SA_CA<6>")
	)
	(arc
		(start 376.917712 -255.336802)
		(mid 377.099963 -255.387152)
		(end 377.283472 -255.341628)
		(width 0.0889)
		(layer "In2.Cu")
		(net "M_I_CPU0_SA_CA<6>")
	)
	(arc
		(start 394.60043 -255.5367)
		(mid 394.643865 -255.545358)
		(end 394.680694 -255.569974)
		(width 0.0889)
		(layer "In2.Cu")
		(net "M_I_CPU0_SA_CA<6>")
	)
	(arc
		(start 377.291854 -255.336802)
		(mid 377.57481 -255.260625)
		(end 377.857766 -255.336802)
		(width 0.0889)
		(layer "In2.Cu")
		(net "M_I_CPU0_SA_CA<6>")
	)
	(arc
		(start 379.171962 -255.336802)
		(mid 379.454918 -255.260625)
		(end 379.737874 -255.336802)
		(width 0.0889)
		(layer "In2.Cu")
		(net "M_I_CPU0_SA_CA<6>")
	)
	(arc
		(start 392.892534 -255.333246)
		(mid 393.006939 -255.371693)
		(end 393.127484 -255.365504)
		(width 0.0889)
		(layer "In2.Cu")
		(net "M_I_CPU0_SA_CA<6>")
	)
	(arc
		(start 393.2174 -255.34366)
		(mid 393.228843 -255.340406)
		(end 393.240006 -255.336294)
		(width 0.0889)
		(layer "In2.Cu")
		(net "M_I_CPU0_SA_CA<6>")
	)
	(arc
		(start 394.296138 -255.524254)
		(mid 394.339765 -255.533609)
		(end 394.384276 -255.5367)
		(width 0.0889)
		(layer "In2.Cu")
		(net "M_I_CPU0_SA_CA<6>")
	)
	(arc
		(start 391.026142 -255.341628)
		(mid 391.20965 -255.387122)
		(end 391.391902 -255.336802)
		(width 0.0889)
		(layer "In2.Cu")
		(net "M_I_CPU0_SA_CA<6>")
	)
	(arc
		(start 393.846812 -255.329436)
		(mid 394.065355 -255.440959)
		(end 394.296138 -255.524254)
		(width 0.0889)
		(layer "In2.Cu")
		(net "M_I_CPU0_SA_CA<6>")
	)
	(arc
		(start 393.766548 -255.29159)
		(mid 393.807591 -255.30858)
		(end 393.846812 -255.329436)
		(width 0.0889)
		(layer "In2.Cu")
		(net "M_I_CPU0_SA_CA<6>")
	)
	(arc
		(start 381.99187 -255.336802)
		(mid 382.274826 -255.260625)
		(end 382.557782 -255.336802)
		(width 0.0889)
		(layer "In2.Cu")
		(net "M_I_CPU0_SA_CA<6>")
	)
	(arc
		(start 386.317744 -255.336802)
		(mid 386.499995 -255.387152)
		(end 386.683504 -255.341628)
		(width 0.0889)
		(layer "In2.Cu")
		(net "M_I_CPU0_SA_CA<6>")
	)
	(arc
		(start 387.63194 -255.336802)
		(mid 387.914896 -255.260625)
		(end 388.197852 -255.336802)
		(width 0.0889)
		(layer "In2.Cu")
		(net "M_I_CPU0_SA_CA<6>")
	)
	(arc
		(start 389.511794 -255.336802)
		(mid 389.79475 -255.260625)
		(end 390.077706 -255.336802)
		(width 0.0889)
		(layer "In2.Cu")
		(net "M_I_CPU0_SA_CA<6>")
	)
	(arc
		(start 376.03303 -255.362964)
		(mid 376.19054 -255.386162)
		(end 376.343418 -255.341628)
		(width 0.0889)
		(layer "In2.Cu")
		(net "M_I_CPU0_SA_CA<6>")
	)
	(arc
		(start 385.37769 -255.336802)
		(mid 385.559941 -255.387152)
		(end 385.74345 -255.341628)
		(width 0.0889)
		(layer "In2.Cu")
		(net "M_I_CPU0_SA_CA<6>")
	)
	(arc
		(start 376.3518 -255.336802)
		(mid 376.634756 -255.260625)
		(end 376.917712 -255.336802)
		(width 0.0889)
		(layer "In2.Cu")
		(net "M_I_CPU0_SA_CA<6>")
	)
	(arc
		(start 382.931924 -255.336802)
		(mid 383.21488 -255.260625)
		(end 383.497836 -255.336802)
		(width 0.0889)
		(layer "In2.Cu")
		(net "M_I_CPU0_SA_CA<6>")
	)
	(arc
		(start 388.571994 -255.336802)
		(mid 388.85495 -255.260625)
		(end 389.137906 -255.336802)
		(width 0.0889)
		(layer "In2.Cu")
		(net "M_I_CPU0_SA_CA<6>")
	)
	(arc
		(start 385.751832 -255.336802)
		(mid 386.034788 -255.260625)
		(end 386.317744 -255.336802)
		(width 0.0889)
		(layer "In2.Cu")
		(net "M_I_CPU0_SA_CA<6>")
	)
	(arc
		(start 380.677674 -255.336802)
		(mid 380.859925 -255.387152)
		(end 381.043434 -255.341628)
		(width 0.0889)
		(layer "In2.Cu")
		(net "M_I_CPU0_SA_CA<6>")
	)
	(arc
		(start 387.26618 -255.341628)
		(mid 387.449688 -255.387122)
		(end 387.63194 -255.336802)
		(width 0.0889)
		(layer "In2.Cu")
		(net "M_I_CPU0_SA_CA<6>")
	)
	(arc
		(start 378.806202 -255.341628)
		(mid 378.98971 -255.387122)
		(end 379.171962 -255.336802)
		(width 0.0889)
		(layer "In2.Cu")
		(net "M_I_CPU0_SA_CA<6>")
	)
	(arc
		(start 392.332718 -255.336802)
		(mid 392.612146 -255.260636)
		(end 392.892534 -255.333246)
		(width 0.0889)
		(layer "In2.Cu")
		(net "M_I_CPU0_SA_CA<6>")
	)
	(arc
		(start 378.231908 -255.336802)
		(mid 378.514864 -255.260625)
		(end 378.79782 -255.336802)
		(width 0.0889)
		(layer "In2.Cu")
		(net "M_I_CPU0_SA_CA<6>")
	)
	(arc
		(start 386.691886 -255.336802)
		(mid 386.974842 -255.260625)
		(end 387.257798 -255.336802)
		(width 0.0889)
		(layer "In2.Cu")
		(net "M_I_CPU0_SA_CA<6>")
	)
	(arc
		(start 383.506218 -255.341628)
		(mid 383.689726 -255.387122)
		(end 383.871978 -255.336802)
		(width 0.0889)
		(layer "In2.Cu")
		(net "M_I_CPU0_SA_CA<6>")
	)
	(arc
		(start 381.617728 -255.336802)
		(mid 381.799979 -255.387152)
		(end 381.983488 -255.341628)
		(width 0.0889)
		(layer "In2.Cu")
		(net "M_I_CPU0_SA_CA<6>")
	)
	(arc
		(start 389.137906 -255.336802)
		(mid 389.32485 -255.387057)
		(end 389.511794 -255.336802)
		(width 0.0889)
		(layer "In2.Cu")
		(net "M_I_CPU0_SA_CA<6>")
	)
	(arc
		(start 382.566164 -255.341628)
		(mid 382.749672 -255.387122)
		(end 382.931924 -255.336802)
		(width 0.0889)
		(layer "In2.Cu")
		(net "M_I_CPU0_SA_CA<6>")
	)
	(arc
		(start 390.077706 -255.336802)
		(mid 390.259957 -255.387152)
		(end 390.443466 -255.341628)
		(width 0.0889)
		(layer "In2.Cu")
		(net "M_I_CPU0_SA_CA<6>")
	)
	(arc
		(start 379.737874 -255.336802)
		(mid 379.924818 -255.387057)
		(end 380.111762 -255.336802)
		(width 0.0889)
		(layer "In2.Cu")
		(net "M_I_CPU0_SA_CA<6>")
	)
	(arc
		(start 381.051816 -255.336802)
		(mid 381.334772 -255.260625)
		(end 381.617728 -255.336802)
		(width 0.0889)
		(layer "In2.Cu")
		(net "M_I_CPU0_SA_CA<6>")
	)
	(arc
		(start 380.111762 -255.336802)
		(mid 380.394718 -255.260625)
		(end 380.677674 -255.336802)
		(width 0.0889)
		(layer "In2.Cu")
		(net "M_I_CPU0_SA_CA<6>")
	)
	(arc
		(start 384.811778 -255.336802)
		(mid 385.094734 -255.260625)
		(end 385.37769 -255.336802)
		(width 0.0889)
		(layer "In2.Cu")
		(net "M_I_CPU0_SA_CA<6>")
	)
	(arc
		(start 390.451848 -255.336802)
		(mid 390.734804 -255.260625)
		(end 391.01776 -255.336802)
		(width 0.0889)
		(layer "In2.Cu")
		(net "M_I_CPU0_SA_CA<6>")
	)
	(arc
		(start 383.871978 -255.336802)
		(mid 384.154934 -255.260625)
		(end 384.43789 -255.336802)
		(width 0.0889)
		(layer "In2.Cu")
		(net "M_I_CPU0_SA_CA<6>")
	)
	(arc
		(start 377.866148 -255.341628)
		(mid 378.049656 -255.387122)
		(end 378.231908 -255.336802)
		(width 0.0889)
		(layer "In2.Cu")
		(net "M_I_CPU0_SA_CA<6>")
	)
	(arc
		(start 384.43789 -255.336802)
		(mid 384.624834 -255.387057)
		(end 384.811778 -255.336802)
		(width 0.0889)
		(layer "In2.Cu")
		(net "M_I_CPU0_SA_CA<6>")
	)
	(arc
		(start 391.958322 -255.336802)
		(mid 392.13878 -255.387246)
		(end 392.321034 -255.34366)
		(width 0.0889)
		(layer "In2.Cu")
		(net "M_I_CPU0_SA_CA<6>")
	)
	(arc
		(start 393.325096 -255.301242)
		(mid 393.544936 -255.255858)
		(end 393.766548 -255.29159)
		(width 0.0889)
		(layer "In2.Cu")
		(net "M_I_CPU0_SA_CA<6>")
	)
	(arc
		(start 388.206234 -255.341628)
		(mid 388.389742 -255.387122)
		(end 388.571994 -255.336802)
		(width 0.0889)
		(layer "In2.Cu")
		(net "M_I_CPU0_SA_CA<6>")
	)
	(segment
		(start 376.638058 -255.28016)
		(end 377.10491 -255.014222)
		(width 0.10668)
		(layer "F.Cu")
		(net "M_I_CPU0_SA_CA<5>")
	)
	(segment
		(start 377.258834 -254.748792)
		(end 377.354846 -254.723392)
		(width 0.0889)
		(layer "In2.Cu")
		(net "M_I_CPU0_SA_CA<5>")
	)
	(segment
		(start 377.857766 -254.691642)
		(end 377.866148 -254.686816)
		(width 0.0889)
		(layer "In2.Cu")
		(net "M_I_CPU0_SA_CA<5>")
	)
	(segment
		(start 421.368474 -253.715266)
		(end 421.368474 -253.252478)
		(width 0.14478)
		(layer "In2.Cu")
		(net "M_I_CPU0_SA_CA<5>")
	)
	(segment
		(start 425.789852 -251.735082)
		(end 427.456092 -251.735082)
		(width 0.14478)
		(layer "In2.Cu")
		(net "M_I_CPU0_SA_CA<5>")
	)
	(segment
		(start 421.919908 -253.715266)
		(end 422.064688 -253.860046)
		(width 0.14478)
		(layer "In2.Cu")
		(net "M_I_CPU0_SA_CA<5>")
	)
	(segment
		(start 410.433774 -254.666496)
		(end 411.240224 -253.860046)
		(width 0.14478)
		(layer "In2.Cu")
		(net "M_I_CPU0_SA_CA<5>")
	)
	(segment
		(start 422.905682 -252.160024)
		(end 424.763946 -252.160024)
		(width 0.14478)
		(layer "In2.Cu")
		(net "M_I_CPU0_SA_CA<5>")
	)
	(segment
		(start 421.368474 -253.252478)
		(end 421.513254 -253.107698)
		(width 0.14478)
		(layer "In2.Cu")
		(net "M_I_CPU0_SA_CA<5>")
	)
	(segment
		(start 388.197852 -254.691642)
		(end 388.206234 -254.686816)
		(width 0.0889)
		(layer "In2.Cu")
		(net "M_I_CPU0_SA_CA<5>")
	)
	(segment
		(start 411.240224 -253.860046)
		(end 421.223694 -253.860046)
		(width 0.14478)
		(layer "In2.Cu")
		(net "M_I_CPU0_SA_CA<5>")
	)
	(segment
		(start 421.919908 -253.252478)
		(end 421.919908 -253.715266)
		(width 0.14478)
		(layer "In2.Cu")
		(net "M_I_CPU0_SA_CA<5>")
	)
	(segment
		(start 403.940518 -254.195072)
		(end 404.411942 -254.666496)
		(width 0.14478)
		(layer "In2.Cu")
		(net "M_I_CPU0_SA_CA<5>")
	)
	(segment
		(start 422.491154 -253.860046)
		(end 422.760902 -253.590298)
		(width 0.14478)
		(layer "In2.Cu")
		(net "M_I_CPU0_SA_CA<5>")
	)
	(segment
		(start 422.760902 -252.304804)
		(end 422.905682 -252.160024)
		(width 0.14478)
		(layer "In2.Cu")
		(net "M_I_CPU0_SA_CA<5>")
	)
	(segment
		(start 400.026632 -254.195072)
		(end 403.940518 -254.195072)
		(width 0.14478)
		(layer "In2.Cu")
		(net "M_I_CPU0_SA_CA<5>")
	)
	(segment
		(start 424.763946 -252.160024)
		(end 425.789852 -251.735082)
		(width 0.14478)
		(layer "In2.Cu")
		(net "M_I_CPU0_SA_CA<5>")
	)
	(segment
		(start 404.411942 -254.666496)
		(end 410.433774 -254.666496)
		(width 0.14478)
		(layer "In2.Cu")
		(net "M_I_CPU0_SA_CA<5>")
	)
	(segment
		(start 394.565632 -255.13411)
		(end 394.771118 -255.13411)
		(width 0.0889)
		(layer "In2.Cu")
		(net "M_I_CPU0_SA_CA<5>")
	)
	(segment
		(start 382.557782 -254.691642)
		(end 382.566164 -254.686816)
		(width 0.0889)
		(layer "In2.Cu")
		(net "M_I_CPU0_SA_CA<5>")
	)
	(segment
		(start 395.0716 -255.434592)
		(end 395.304518 -255.434592)
		(width 0.0889)
		(layer "In2.Cu")
		(net "M_I_CPU0_SA_CA<5>")
	)
	(segment
		(start 391.93216 -254.705866)
		(end 391.956036 -254.691896)
		(width 0.0889)
		(layer "In2.Cu")
		(net "M_I_CPU0_SA_CA<5>")
	)
	(segment
		(start 421.513254 -253.107698)
		(end 421.775128 -253.107698)
		(width 0.14478)
		(layer "In2.Cu")
		(net "M_I_CPU0_SA_CA<5>")
	)
	(segment
		(start 391.01776 -254.691642)
		(end 391.026142 -254.686816)
		(width 0.0889)
		(layer "In2.Cu")
		(net "M_I_CPU0_SA_CA<5>")
	)
	(segment
		(start 386.683504 -254.686816)
		(end 386.691886 -254.691642)
		(width 0.0889)
		(layer "In2.Cu")
		(net "M_I_CPU0_SA_CA<5>")
	)
	(segment
		(start 398.787112 -255.434592)
		(end 400.026632 -254.195072)
		(width 0.14478)
		(layer "In2.Cu")
		(net "M_I_CPU0_SA_CA<5>")
	)
	(segment
		(start 387.257798 -254.691642)
		(end 387.26618 -254.686816)
		(width 0.0889)
		(layer "In2.Cu")
		(net "M_I_CPU0_SA_CA<5>")
	)
	(segment
		(start 422.064688 -253.860046)
		(end 422.491154 -253.860046)
		(width 0.14478)
		(layer "In2.Cu")
		(net "M_I_CPU0_SA_CA<5>")
	)
	(segment
		(start 394.771118 -255.13411)
		(end 395.0716 -255.434592)
		(width 0.0889)
		(layer "In2.Cu")
		(net "M_I_CPU0_SA_CA<5>")
	)
	(segment
		(start 391.956036 -254.691896)
		(end 391.97788 -254.67945)
		(width 0.0889)
		(layer "In2.Cu")
		(net "M_I_CPU0_SA_CA<5>")
	)
	(segment
		(start 383.497836 -254.691642)
		(end 383.506218 -254.686816)
		(width 0.0889)
		(layer "In2.Cu")
		(net "M_I_CPU0_SA_CA<5>")
	)
	(segment
		(start 421.223694 -253.860046)
		(end 421.368474 -253.715266)
		(width 0.14478)
		(layer "In2.Cu")
		(net "M_I_CPU0_SA_CA<5>")
	)
	(segment
		(start 390.443466 -254.686816)
		(end 390.451848 -254.691642)
		(width 0.0889)
		(layer "In2.Cu")
		(net "M_I_CPU0_SA_CA<5>")
	)
	(segment
		(start 421.775128 -253.107698)
		(end 421.919908 -253.252478)
		(width 0.14478)
		(layer "In2.Cu")
		(net "M_I_CPU0_SA_CA<5>")
	)
	(segment
		(start 422.760902 -253.590298)
		(end 422.760902 -252.304804)
		(width 0.14478)
		(layer "In2.Cu")
		(net "M_I_CPU0_SA_CA<5>")
	)
	(segment
		(start 381.983488 -254.686816)
		(end 381.99187 -254.691642)
		(width 0.0889)
		(layer "In2.Cu")
		(net "M_I_CPU0_SA_CA<5>")
	)
	(segment
		(start 385.74345 -254.686816)
		(end 385.751832 -254.691642)
		(width 0.0889)
		(layer "In2.Cu")
		(net "M_I_CPU0_SA_CA<5>")
	)
	(segment
		(start 377.10491 -255.014222)
		(end 377.258834 -254.748792)
		(width 0.0889)
		(layer "In2.Cu")
		(net "M_I_CPU0_SA_CA<5>")
	)
	(segment
		(start 378.79782 -254.691642)
		(end 378.806202 -254.686816)
		(width 0.0889)
		(layer "In2.Cu")
		(net "M_I_CPU0_SA_CA<5>")
	)
	(segment
		(start 393.240514 -254.674624)
		(end 393.58062 -254.870712)
		(width 0.0889)
		(layer "In2.Cu")
		(net "M_I_CPU0_SA_CA<5>")
	)
	(segment
		(start 381.043434 -254.686816)
		(end 381.051816 -254.691642)
		(width 0.0889)
		(layer "In2.Cu")
		(net "M_I_CPU0_SA_CA<5>")
	)
	(segment
		(start 392.328654 -254.691642)
		(end 392.35634 -254.707644)
		(width 0.0889)
		(layer "In2.Cu")
		(net "M_I_CPU0_SA_CA<5>")
	)
	(segment
		(start 395.304518 -255.434592)
		(end 398.787112 -255.434592)
		(width 0.14478)
		(layer "In2.Cu")
		(net "M_I_CPU0_SA_CA<5>")
	)
	(arc
		(start 390.077706 -254.691642)
		(mid 390.259957 -254.641292)
		(end 390.443466 -254.686816)
		(width 0.0889)
		(layer "In2.Cu")
		(net "M_I_CPU0_SA_CA<5>")
	)
	(arc
		(start 380.111762 -254.691642)
		(mid 380.394718 -254.767819)
		(end 380.677674 -254.691642)
		(width 0.0889)
		(layer "In2.Cu")
		(net "M_I_CPU0_SA_CA<5>")
	)
	(arc
		(start 387.63194 -254.691642)
		(mid 387.914896 -254.767819)
		(end 388.197852 -254.691642)
		(width 0.0889)
		(layer "In2.Cu")
		(net "M_I_CPU0_SA_CA<5>")
	)
	(arc
		(start 391.026142 -254.686816)
		(mid 391.20965 -254.641322)
		(end 391.391902 -254.691642)
		(width 0.0889)
		(layer "In2.Cu")
		(net "M_I_CPU0_SA_CA<5>")
	)
	(arc
		(start 378.806202 -254.686816)
		(mid 378.98971 -254.641322)
		(end 379.171962 -254.691642)
		(width 0.0889)
		(layer "In2.Cu")
		(net "M_I_CPU0_SA_CA<5>")
	)
	(arc
		(start 381.617728 -254.691642)
		(mid 381.799979 -254.641292)
		(end 381.983488 -254.686816)
		(width 0.0889)
		(layer "In2.Cu")
		(net "M_I_CPU0_SA_CA<5>")
	)
	(arc
		(start 382.931924 -254.691642)
		(mid 383.21488 -254.767819)
		(end 383.497836 -254.691642)
		(width 0.0889)
		(layer "In2.Cu")
		(net "M_I_CPU0_SA_CA<5>")
	)
	(arc
		(start 380.677674 -254.691642)
		(mid 380.859925 -254.641292)
		(end 381.043434 -254.686816)
		(width 0.0889)
		(layer "In2.Cu")
		(net "M_I_CPU0_SA_CA<5>")
	)
	(arc
		(start 388.206234 -254.686816)
		(mid 388.389742 -254.641322)
		(end 388.571994 -254.691642)
		(width 0.0889)
		(layer "In2.Cu")
		(net "M_I_CPU0_SA_CA<5>")
	)
	(arc
		(start 385.37769 -254.691642)
		(mid 385.559941 -254.641292)
		(end 385.74345 -254.686816)
		(width 0.0889)
		(layer "In2.Cu")
		(net "M_I_CPU0_SA_CA<5>")
	)
	(arc
		(start 383.506218 -254.686816)
		(mid 383.689726 -254.641322)
		(end 383.871978 -254.691642)
		(width 0.0889)
		(layer "In2.Cu")
		(net "M_I_CPU0_SA_CA<5>")
	)
	(arc
		(start 385.751832 -254.691642)
		(mid 386.034788 -254.767819)
		(end 386.317744 -254.691642)
		(width 0.0889)
		(layer "In2.Cu")
		(net "M_I_CPU0_SA_CA<5>")
	)
	(arc
		(start 392.35634 -254.707644)
		(mid 392.628374 -254.768416)
		(end 392.896344 -254.691642)
		(width 0.0889)
		(layer "In2.Cu")
		(net "M_I_CPU0_SA_CA<5>")
	)
	(arc
		(start 391.97788 -254.67945)
		(mid 392.154808 -254.641622)
		(end 392.328654 -254.691642)
		(width 0.0889)
		(layer "In2.Cu")
		(net "M_I_CPU0_SA_CA<5>")
	)
	(arc
		(start 379.171962 -254.691642)
		(mid 379.454918 -254.767819)
		(end 379.737874 -254.691642)
		(width 0.0889)
		(layer "In2.Cu")
		(net "M_I_CPU0_SA_CA<5>")
	)
	(arc
		(start 393.58062 -254.870712)
		(mid 394.055818 -255.067129)
		(end 394.565632 -255.13411)
		(width 0.0889)
		(layer "In2.Cu")
		(net "M_I_CPU0_SA_CA<5>")
	)
	(arc
		(start 381.99187 -254.691642)
		(mid 382.274826 -254.767819)
		(end 382.557782 -254.691642)
		(width 0.0889)
		(layer "In2.Cu")
		(net "M_I_CPU0_SA_CA<5>")
	)
	(arc
		(start 379.737874 -254.691642)
		(mid 379.924818 -254.641387)
		(end 380.111762 -254.691642)
		(width 0.0889)
		(layer "In2.Cu")
		(net "M_I_CPU0_SA_CA<5>")
	)
	(arc
		(start 377.354846 -254.723392)
		(mid 377.610054 -254.766869)
		(end 377.857766 -254.691642)
		(width 0.0889)
		(layer "In2.Cu")
		(net "M_I_CPU0_SA_CA<5>")
	)
	(arc
		(start 392.896344 -254.691642)
		(mid 393.066351 -254.641077)
		(end 393.240514 -254.674624)
		(width 0.0889)
		(layer "In2.Cu")
		(net "M_I_CPU0_SA_CA<5>")
	)
	(arc
		(start 384.43789 -254.691642)
		(mid 384.624834 -254.641387)
		(end 384.811778 -254.691642)
		(width 0.0889)
		(layer "In2.Cu")
		(net "M_I_CPU0_SA_CA<5>")
	)
	(arc
		(start 386.691886 -254.691642)
		(mid 386.974842 -254.767819)
		(end 387.257798 -254.691642)
		(width 0.0889)
		(layer "In2.Cu")
		(net "M_I_CPU0_SA_CA<5>")
	)
	(arc
		(start 381.051816 -254.691642)
		(mid 381.334772 -254.767819)
		(end 381.617728 -254.691642)
		(width 0.0889)
		(layer "In2.Cu")
		(net "M_I_CPU0_SA_CA<5>")
	)
	(arc
		(start 389.137906 -254.691642)
		(mid 389.32485 -254.641387)
		(end 389.511794 -254.691642)
		(width 0.0889)
		(layer "In2.Cu")
		(net "M_I_CPU0_SA_CA<5>")
	)
	(arc
		(start 382.566164 -254.686816)
		(mid 382.749672 -254.641322)
		(end 382.931924 -254.691642)
		(width 0.0889)
		(layer "In2.Cu")
		(net "M_I_CPU0_SA_CA<5>")
	)
	(arc
		(start 388.571994 -254.691642)
		(mid 388.85495 -254.767819)
		(end 389.137906 -254.691642)
		(width 0.0889)
		(layer "In2.Cu")
		(net "M_I_CPU0_SA_CA<5>")
	)
	(arc
		(start 383.871978 -254.691642)
		(mid 384.154934 -254.767819)
		(end 384.43789 -254.691642)
		(width 0.0889)
		(layer "In2.Cu")
		(net "M_I_CPU0_SA_CA<5>")
	)
	(arc
		(start 389.511794 -254.691642)
		(mid 389.79475 -254.767819)
		(end 390.077706 -254.691642)
		(width 0.0889)
		(layer "In2.Cu")
		(net "M_I_CPU0_SA_CA<5>")
	)
	(arc
		(start 386.317744 -254.691642)
		(mid 386.499995 -254.641292)
		(end 386.683504 -254.686816)
		(width 0.0889)
		(layer "In2.Cu")
		(net "M_I_CPU0_SA_CA<5>")
	)
	(arc
		(start 387.26618 -254.686816)
		(mid 387.449688 -254.641322)
		(end 387.63194 -254.691642)
		(width 0.0889)
		(layer "In2.Cu")
		(net "M_I_CPU0_SA_CA<5>")
	)
	(arc
		(start 384.811778 -254.691642)
		(mid 385.094734 -254.767819)
		(end 385.37769 -254.691642)
		(width 0.0889)
		(layer "In2.Cu")
		(net "M_I_CPU0_SA_CA<5>")
	)
	(arc
		(start 378.231908 -254.691642)
		(mid 378.514864 -254.767819)
		(end 378.79782 -254.691642)
		(width 0.0889)
		(layer "In2.Cu")
		(net "M_I_CPU0_SA_CA<5>")
	)
	(arc
		(start 390.451848 -254.691642)
		(mid 390.734804 -254.767819)
		(end 391.01776 -254.691642)
		(width 0.0889)
		(layer "In2.Cu")
		(net "M_I_CPU0_SA_CA<5>")
	)
	(arc
		(start 391.391902 -254.691642)
		(mid 391.660222 -254.76775)
		(end 391.93216 -254.705866)
		(width 0.0889)
		(layer "In2.Cu")
		(net "M_I_CPU0_SA_CA<5>")
	)
	(arc
		(start 377.866148 -254.686816)
		(mid 378.049656 -254.641322)
		(end 378.231908 -254.691642)
		(width 0.0889)
		(layer "In2.Cu")
		(net "M_I_CPU0_SA_CA<5>")
	)
	(segment
		(start 377.107958 -254.470154)
		(end 377.57481 -254.204216)
		(width 0.10668)
		(layer "F.Cu")
		(net "M_I_CPU0_SA_CA<4>")
	)
	(segment
		(start 388.093458 -254.531622)
		(end 388.10184 -254.526796)
		(width 0.0889)
		(layer "In2.Cu")
		(net "M_I_CPU0_SA_CA<4>")
	)
	(segment
		(start 398.626076 -254.959612)
		(end 399.840196 -253.745492)
		(width 0.14478)
		(layer "In2.Cu")
		(net "M_I_CPU0_SA_CA<4>")
	)
	(segment
		(start 395.314678 -254.959612)
		(end 395.487398 -254.959612)
		(width 0.0889)
		(layer "In2.Cu")
		(net "M_I_CPU0_SA_CA<4>")
	)
	(segment
		(start 395.487398 -254.959612)
		(end 398.626076 -254.959612)
		(width 0.14478)
		(layer "In2.Cu")
		(net "M_I_CPU0_SA_CA<4>")
	)
	(segment
		(start 384.90779 -254.526796)
		(end 384.916172 -254.531622)
		(width 0.0889)
		(layer "In2.Cu")
		(net "M_I_CPU0_SA_CA<4>")
	)
	(segment
		(start 409.648914 -254.216916)
		(end 410.855668 -253.010162)
		(width 0.14478)
		(layer "In2.Cu")
		(net "M_I_CPU0_SA_CA<4>")
	)
	(segment
		(start 392.424666 -254.526796)
		(end 392.44524 -254.538734)
		(width 0.0889)
		(layer "In2.Cu")
		(net "M_I_CPU0_SA_CA<4>")
	)
	(segment
		(start 425.28109 -251.31014)
		(end 425.51858 -251.07265)
		(width 0.14478)
		(layer "In2.Cu")
		(net "M_I_CPU0_SA_CA<4>")
	)
	(segment
		(start 395.191996 -254.83693)
		(end 395.314678 -254.959612)
		(width 0.0889)
		(layer "In2.Cu")
		(net "M_I_CPU0_SA_CA<4>")
	)
	(segment
		(start 389.033512 -254.531622)
		(end 389.041894 -254.526796)
		(width 0.0889)
		(layer "In2.Cu")
		(net "M_I_CPU0_SA_CA<4>")
	)
	(segment
		(start 385.847844 -254.526796)
		(end 385.856226 -254.531622)
		(width 0.0889)
		(layer "In2.Cu")
		(net "M_I_CPU0_SA_CA<4>")
	)
	(segment
		(start 425.51858 -251.07265)
		(end 427.03877 -251.07265)
		(width 0.14478)
		(layer "In2.Cu")
		(net "M_I_CPU0_SA_CA<4>")
	)
	(segment
		(start 384.333496 -254.531622)
		(end 384.341878 -254.526796)
		(width 0.0889)
		(layer "In2.Cu")
		(net "M_I_CPU0_SA_CA<4>")
	)
	(segment
		(start 380.207774 -254.526796)
		(end 380.216156 -254.531622)
		(width 0.0889)
		(layer "In2.Cu")
		(net "M_I_CPU0_SA_CA<4>")
	)
	(segment
		(start 391.837164 -254.540004)
		(end 391.860532 -254.526542)
		(width 0.0889)
		(layer "In2.Cu")
		(net "M_I_CPU0_SA_CA<4>")
	)
	(segment
		(start 427.21911 -251.25299)
		(end 427.225714 -251.25299)
		(width 0.0889)
		(layer "In2.Cu")
		(net "M_I_CPU0_SA_CA<4>")
	)
	(segment
		(start 399.840196 -253.745492)
		(end 404.126954 -253.745492)
		(width 0.14478)
		(layer "In2.Cu")
		(net "M_I_CPU0_SA_CA<4>")
	)
	(segment
		(start 410.855668 -253.010162)
		(end 420.657782 -253.010162)
		(width 0.14478)
		(layer "In2.Cu")
		(net "M_I_CPU0_SA_CA<4>")
	)
	(segment
		(start 379.63348 -254.531622)
		(end 379.641862 -254.526796)
		(width 0.0889)
		(layer "In2.Cu")
		(net "M_I_CPU0_SA_CA<4>")
	)
	(segment
		(start 422.357804 -251.31014)
		(end 425.28109 -251.31014)
		(width 0.14478)
		(layer "In2.Cu")
		(net "M_I_CPU0_SA_CA<4>")
	)
	(segment
		(start 383.393442 -254.531622)
		(end 383.401824 -254.526796)
		(width 0.0889)
		(layer "In2.Cu")
		(net "M_I_CPU0_SA_CA<4>")
	)
	(segment
		(start 427.641512 -251.31014)
		(end 431.130964 -251.31014)
		(width 0.14478)
		(layer "In2.Cu")
		(net "M_I_CPU0_SA_CA<4>")
	)
	(segment
		(start 393.32789 -254.504698)
		(end 393.365736 -254.526542)
		(width 0.0889)
		(layer "In2.Cu")
		(net "M_I_CPU0_SA_CA<4>")
	)
	(segment
		(start 377.420886 -254.469646)
		(end 377.443238 -254.552958)
		(width 0.0889)
		(layer "In2.Cu")
		(net "M_I_CPU0_SA_CA<4>")
	)
	(segment
		(start 427.03877 -251.07265)
		(end 427.21911 -251.25299)
		(width 0.14478)
		(layer "In2.Cu")
		(net "M_I_CPU0_SA_CA<4>")
	)
	(segment
		(start 377.57481 -254.204216)
		(end 377.420886 -254.469646)
		(width 0.0889)
		(layer "In2.Cu")
		(net "M_I_CPU0_SA_CA<4>")
	)
	(segment
		(start 394.521944 -254.83693)
		(end 395.191996 -254.83693)
		(width 0.0889)
		(layer "In2.Cu")
		(net "M_I_CPU0_SA_CA<4>")
	)
	(segment
		(start 431.130964 -251.31014)
		(end 431.55616 -250.884944)
		(width 0.14478)
		(layer "In2.Cu")
		(net "M_I_CPU0_SA_CA<4>")
	)
	(segment
		(start 427.282864 -251.31014)
		(end 427.641512 -251.31014)
		(width 0.0889)
		(layer "In2.Cu")
		(net "M_I_CPU0_SA_CA<4>")
	)
	(segment
		(start 391.860532 -254.526542)
		(end 391.884408 -254.512572)
		(width 0.0889)
		(layer "In2.Cu")
		(net "M_I_CPU0_SA_CA<4>")
	)
	(segment
		(start 404.598378 -254.216916)
		(end 409.648914 -254.216916)
		(width 0.14478)
		(layer "In2.Cu")
		(net "M_I_CPU0_SA_CA<4>")
	)
	(segment
		(start 427.225714 -251.25299)
		(end 427.282864 -251.31014)
		(width 0.0889)
		(layer "In2.Cu")
		(net "M_I_CPU0_SA_CA<4>")
	)
	(segment
		(start 389.607806 -254.526796)
		(end 389.616188 -254.531622)
		(width 0.0889)
		(layer "In2.Cu")
		(net "M_I_CPU0_SA_CA<4>")
	)
	(segment
		(start 381.147828 -254.526796)
		(end 381.15621 -254.531622)
		(width 0.0889)
		(layer "In2.Cu")
		(net "M_I_CPU0_SA_CA<4>")
	)
	(segment
		(start 420.657782 -253.010162)
		(end 422.357804 -251.31014)
		(width 0.14478)
		(layer "In2.Cu")
		(net "M_I_CPU0_SA_CA<4>")
	)
	(segment
		(start 404.126954 -253.745492)
		(end 404.598378 -254.216916)
		(width 0.14478)
		(layer "In2.Cu")
		(net "M_I_CPU0_SA_CA<4>")
	)
	(segment
		(start 378.693426 -254.531622)
		(end 378.701808 -254.526796)
		(width 0.0889)
		(layer "In2.Cu")
		(net "M_I_CPU0_SA_CA<4>")
	)
	(arc
		(start 392.44524 -254.538734)
		(mid 392.624168 -254.577611)
		(end 392.800078 -254.526796)
		(width 0.0889)
		(layer "In2.Cu")
		(net "M_I_CPU0_SA_CA<4>")
	)
	(arc
		(start 393.365736 -254.526542)
		(mid 393.92337 -254.757988)
		(end 394.521944 -254.83693)
		(width 0.0889)
		(layer "In2.Cu")
		(net "M_I_CPU0_SA_CA<4>")
	)
	(arc
		(start 392.800078 -254.526796)
		(mid 393.061236 -254.450217)
		(end 393.32789 -254.504698)
		(width 0.0889)
		(layer "In2.Cu")
		(net "M_I_CPU0_SA_CA<4>")
	)
	(arc
		(start 388.10184 -254.526796)
		(mid 388.384796 -254.450619)
		(end 388.667752 -254.526796)
		(width 0.0889)
		(layer "In2.Cu")
		(net "M_I_CPU0_SA_CA<4>")
	)
	(arc
		(start 377.443238 -254.552958)
		(mid 377.605427 -254.575693)
		(end 377.761754 -254.526796)
		(width 0.0889)
		(layer "In2.Cu")
		(net "M_I_CPU0_SA_CA<4>")
	)
	(arc
		(start 386.787898 -254.526796)
		(mid 386.974842 -254.577051)
		(end 387.161786 -254.526796)
		(width 0.0889)
		(layer "In2.Cu")
		(net "M_I_CPU0_SA_CA<4>")
	)
	(arc
		(start 388.667752 -254.526796)
		(mid 388.850003 -254.577146)
		(end 389.033512 -254.531622)
		(width 0.0889)
		(layer "In2.Cu")
		(net "M_I_CPU0_SA_CA<4>")
	)
	(arc
		(start 386.221986 -254.526796)
		(mid 386.504942 -254.450619)
		(end 386.787898 -254.526796)
		(width 0.0889)
		(layer "In2.Cu")
		(net "M_I_CPU0_SA_CA<4>")
	)
	(arc
		(start 379.641862 -254.526796)
		(mid 379.924818 -254.450619)
		(end 380.207774 -254.526796)
		(width 0.0889)
		(layer "In2.Cu")
		(net "M_I_CPU0_SA_CA<4>")
	)
	(arc
		(start 380.216156 -254.531622)
		(mid 380.399664 -254.577116)
		(end 380.581916 -254.526796)
		(width 0.0889)
		(layer "In2.Cu")
		(net "M_I_CPU0_SA_CA<4>")
	)
	(arc
		(start 385.856226 -254.531622)
		(mid 386.039734 -254.577116)
		(end 386.221986 -254.526796)
		(width 0.0889)
		(layer "In2.Cu")
		(net "M_I_CPU0_SA_CA<4>")
	)
	(arc
		(start 378.701808 -254.526796)
		(mid 378.984764 -254.450619)
		(end 379.26772 -254.526796)
		(width 0.0889)
		(layer "In2.Cu")
		(net "M_I_CPU0_SA_CA<4>")
	)
	(arc
		(start 390.54786 -254.526796)
		(mid 390.734804 -254.577051)
		(end 390.921748 -254.526796)
		(width 0.0889)
		(layer "In2.Cu")
		(net "M_I_CPU0_SA_CA<4>")
	)
	(arc
		(start 380.581916 -254.526796)
		(mid 380.864872 -254.450619)
		(end 381.147828 -254.526796)
		(width 0.0889)
		(layer "In2.Cu")
		(net "M_I_CPU0_SA_CA<4>")
	)
	(arc
		(start 377.761754 -254.526796)
		(mid 378.04471 -254.450619)
		(end 378.327666 -254.526796)
		(width 0.0889)
		(layer "In2.Cu")
		(net "M_I_CPU0_SA_CA<4>")
	)
	(arc
		(start 381.15621 -254.531622)
		(mid 381.339718 -254.577116)
		(end 381.52197 -254.526796)
		(width 0.0889)
		(layer "In2.Cu")
		(net "M_I_CPU0_SA_CA<4>")
	)
	(arc
		(start 384.916172 -254.531622)
		(mid 385.09968 -254.577116)
		(end 385.281932 -254.526796)
		(width 0.0889)
		(layer "In2.Cu")
		(net "M_I_CPU0_SA_CA<4>")
	)
	(arc
		(start 387.161786 -254.526796)
		(mid 387.444742 -254.450619)
		(end 387.727698 -254.526796)
		(width 0.0889)
		(layer "In2.Cu")
		(net "M_I_CPU0_SA_CA<4>")
	)
	(arc
		(start 383.401824 -254.526796)
		(mid 383.68478 -254.450619)
		(end 383.967736 -254.526796)
		(width 0.0889)
		(layer "In2.Cu")
		(net "M_I_CPU0_SA_CA<4>")
	)
	(arc
		(start 379.26772 -254.526796)
		(mid 379.449971 -254.577146)
		(end 379.63348 -254.531622)
		(width 0.0889)
		(layer "In2.Cu")
		(net "M_I_CPU0_SA_CA<4>")
	)
	(arc
		(start 384.341878 -254.526796)
		(mid 384.624834 -254.450619)
		(end 384.90779 -254.526796)
		(width 0.0889)
		(layer "In2.Cu")
		(net "M_I_CPU0_SA_CA<4>")
	)
	(arc
		(start 389.981948 -254.526796)
		(mid 390.264904 -254.450619)
		(end 390.54786 -254.526796)
		(width 0.0889)
		(layer "In2.Cu")
		(net "M_I_CPU0_SA_CA<4>")
	)
	(arc
		(start 382.087882 -254.526796)
		(mid 382.274826 -254.577051)
		(end 382.46177 -254.526796)
		(width 0.0889)
		(layer "In2.Cu")
		(net "M_I_CPU0_SA_CA<4>")
	)
	(arc
		(start 378.327666 -254.526796)
		(mid 378.509917 -254.577146)
		(end 378.693426 -254.531622)
		(width 0.0889)
		(layer "In2.Cu")
		(net "M_I_CPU0_SA_CA<4>")
	)
	(arc
		(start 385.281932 -254.526796)
		(mid 385.564888 -254.450619)
		(end 385.847844 -254.526796)
		(width 0.0889)
		(layer "In2.Cu")
		(net "M_I_CPU0_SA_CA<4>")
	)
	(arc
		(start 387.727698 -254.526796)
		(mid 387.909949 -254.577146)
		(end 388.093458 -254.531622)
		(width 0.0889)
		(layer "In2.Cu")
		(net "M_I_CPU0_SA_CA<4>")
	)
	(arc
		(start 381.52197 -254.526796)
		(mid 381.804926 -254.450619)
		(end 382.087882 -254.526796)
		(width 0.0889)
		(layer "In2.Cu")
		(net "M_I_CPU0_SA_CA<4>")
	)
	(arc
		(start 383.967736 -254.526796)
		(mid 384.149987 -254.577146)
		(end 384.333496 -254.531622)
		(width 0.0889)
		(layer "In2.Cu")
		(net "M_I_CPU0_SA_CA<4>")
	)
	(arc
		(start 391.48766 -254.526796)
		(mid 391.660768 -254.576912)
		(end 391.837164 -254.540004)
		(width 0.0889)
		(layer "In2.Cu")
		(net "M_I_CPU0_SA_CA<4>")
	)
	(arc
		(start 389.041894 -254.526796)
		(mid 389.32485 -254.450619)
		(end 389.607806 -254.526796)
		(width 0.0889)
		(layer "In2.Cu")
		(net "M_I_CPU0_SA_CA<4>")
	)
	(arc
		(start 390.921748 -254.526796)
		(mid 391.204704 -254.450619)
		(end 391.48766 -254.526796)
		(width 0.0889)
		(layer "In2.Cu")
		(net "M_I_CPU0_SA_CA<4>")
	)
	(arc
		(start 383.027682 -254.526796)
		(mid 383.209933 -254.577146)
		(end 383.393442 -254.531622)
		(width 0.0889)
		(layer "In2.Cu")
		(net "M_I_CPU0_SA_CA<4>")
	)
	(arc
		(start 382.46177 -254.526796)
		(mid 382.744726 -254.450619)
		(end 383.027682 -254.526796)
		(width 0.0889)
		(layer "In2.Cu")
		(net "M_I_CPU0_SA_CA<4>")
	)
	(arc
		(start 391.884408 -254.512572)
		(mid 392.156345 -254.450746)
		(end 392.424666 -254.526796)
		(width 0.0889)
		(layer "In2.Cu")
		(net "M_I_CPU0_SA_CA<4>")
	)
	(arc
		(start 389.616188 -254.531622)
		(mid 389.799696 -254.577116)
		(end 389.981948 -254.526796)
		(width 0.0889)
		(layer "In2.Cu")
		(net "M_I_CPU0_SA_CA<4>")
	)
	(segment
		(start 375.22785 -254.470154)
		(end 375.694702 -254.204216)
		(width 0.10668)
		(layer "F.Cu")
		(net "M_I_CPU0_SA_CA<3>")
	)
	(segment
		(start 395.284198 -254.482092)
		(end 395.596618 -254.482092)
		(width 0.0889)
		(layer "In2.Cu")
		(net "M_I_CPU0_SA_CA<3>")
	)
	(segment
		(start 389.033512 -253.87681)
		(end 389.041894 -253.881636)
		(width 0.0889)
		(layer "In2.Cu")
		(net "M_I_CPU0_SA_CA<3>")
	)
	(segment
		(start 398.46758 -254.482092)
		(end 399.65376 -253.295912)
		(width 0.14478)
		(layer "In2.Cu")
		(net "M_I_CPU0_SA_CA<3>")
	)
	(segment
		(start 394.563854 -254.10287)
		(end 394.904976 -254.10287)
		(width 0.0889)
		(layer "In2.Cu")
		(net "M_I_CPU0_SA_CA<3>")
	)
	(segment
		(start 384.90779 -253.881636)
		(end 384.916172 -253.87681)
		(width 0.0889)
		(layer "In2.Cu")
		(net "M_I_CPU0_SA_CA<3>")
	)
	(segment
		(start 388.093458 -253.87681)
		(end 388.10184 -253.881636)
		(width 0.0889)
		(layer "In2.Cu")
		(net "M_I_CPU0_SA_CA<3>")
	)
	(segment
		(start 375.694702 -254.204216)
		(end 375.84888 -253.938786)
		(width 0.0889)
		(layer "In2.Cu")
		(net "M_I_CPU0_SA_CA<3>")
	)
	(segment
		(start 404.31339 -253.295912)
		(end 404.784814 -253.767336)
		(width 0.14478)
		(layer "In2.Cu")
		(net "M_I_CPU0_SA_CA<3>")
	)
	(segment
		(start 375.84888 -253.938786)
		(end 375.945146 -253.913386)
		(width 0.0889)
		(layer "In2.Cu")
		(net "M_I_CPU0_SA_CA<3>")
	)
	(segment
		(start 376.447812 -253.881636)
		(end 376.456194 -253.87681)
		(width 0.0889)
		(layer "In2.Cu")
		(net "M_I_CPU0_SA_CA<3>")
	)
	(segment
		(start 379.63348 -253.87681)
		(end 379.641862 -253.881636)
		(width 0.0889)
		(layer "In2.Cu")
		(net "M_I_CPU0_SA_CA<3>")
	)
	(segment
		(start 378.693426 -253.87681)
		(end 378.701808 -253.881636)
		(width 0.0889)
		(layer "In2.Cu")
		(net "M_I_CPU0_SA_CA<3>")
	)
	(segment
		(start 385.847844 -253.881636)
		(end 385.856226 -253.87681)
		(width 0.0889)
		(layer "In2.Cu")
		(net "M_I_CPU0_SA_CA<3>")
	)
	(segment
		(start 389.607806 -253.881636)
		(end 389.616188 -253.87681)
		(width 0.0889)
		(layer "In2.Cu")
		(net "M_I_CPU0_SA_CA<3>")
	)
	(segment
		(start 399.65376 -253.295912)
		(end 404.31339 -253.295912)
		(width 0.14478)
		(layer "In2.Cu")
		(net "M_I_CPU0_SA_CA<3>")
	)
	(segment
		(start 384.333496 -253.87681)
		(end 384.341878 -253.881636)
		(width 0.0889)
		(layer "In2.Cu")
		(net "M_I_CPU0_SA_CA<3>")
	)
	(segment
		(start 395.596618 -254.482092)
		(end 398.46758 -254.482092)
		(width 0.14478)
		(layer "In2.Cu")
		(net "M_I_CPU0_SA_CA<3>")
	)
	(segment
		(start 380.207774 -253.881636)
		(end 380.216156 -253.87681)
		(width 0.0889)
		(layer "In2.Cu")
		(net "M_I_CPU0_SA_CA<3>")
	)
	(segment
		(start 383.393442 -253.87681)
		(end 383.401824 -253.881636)
		(width 0.0889)
		(layer "In2.Cu")
		(net "M_I_CPU0_SA_CA<3>")
	)
	(segment
		(start 410.872686 -252.160024)
		(end 420.661592 -252.160024)
		(width 0.14478)
		(layer "In2.Cu")
		(net "M_I_CPU0_SA_CA<3>")
	)
	(segment
		(start 409.265374 -253.767336)
		(end 410.872686 -252.160024)
		(width 0.14478)
		(layer "In2.Cu")
		(net "M_I_CPU0_SA_CA<3>")
	)
	(segment
		(start 404.784814 -253.767336)
		(end 409.265374 -253.767336)
		(width 0.14478)
		(layer "In2.Cu")
		(net "M_I_CPU0_SA_CA<3>")
	)
	(segment
		(start 394.904976 -254.10287)
		(end 395.284198 -254.482092)
		(width 0.0889)
		(layer "In2.Cu")
		(net "M_I_CPU0_SA_CA<3>")
	)
	(segment
		(start 381.147828 -253.881636)
		(end 381.15621 -253.87681)
		(width 0.0889)
		(layer "In2.Cu")
		(net "M_I_CPU0_SA_CA<3>")
	)
	(segment
		(start 427.03115 -250.460002)
		(end 427.456092 -250.03506)
		(width 0.14478)
		(layer "In2.Cu")
		(net "M_I_CPU0_SA_CA<3>")
	)
	(segment
		(start 422.361614 -250.460002)
		(end 427.03115 -250.460002)
		(width 0.14478)
		(layer "In2.Cu")
		(net "M_I_CPU0_SA_CA<3>")
	)
	(segment
		(start 420.661592 -252.160024)
		(end 422.361614 -250.460002)
		(width 0.14478)
		(layer "In2.Cu")
		(net "M_I_CPU0_SA_CA<3>")
	)
	(arc
		(start 379.641862 -253.881636)
		(mid 379.924818 -253.957813)
		(end 380.207774 -253.881636)
		(width 0.0889)
		(layer "In2.Cu")
		(net "M_I_CPU0_SA_CA<3>")
	)
	(arc
		(start 382.087882 -253.881636)
		(mid 382.274826 -253.831381)
		(end 382.46177 -253.881636)
		(width 0.0889)
		(layer "In2.Cu")
		(net "M_I_CPU0_SA_CA<3>")
	)
	(arc
		(start 381.15621 -253.87681)
		(mid 381.339718 -253.831316)
		(end 381.52197 -253.881636)
		(width 0.0889)
		(layer "In2.Cu")
		(net "M_I_CPU0_SA_CA<3>")
	)
	(arc
		(start 388.10184 -253.881636)
		(mid 388.384796 -253.957813)
		(end 388.667752 -253.881636)
		(width 0.0889)
		(layer "In2.Cu")
		(net "M_I_CPU0_SA_CA<3>")
	)
	(arc
		(start 390.54786 -253.881636)
		(mid 390.734804 -253.831381)
		(end 390.921748 -253.881636)
		(width 0.0889)
		(layer "In2.Cu")
		(net "M_I_CPU0_SA_CA<3>")
	)
	(arc
		(start 384.916172 -253.87681)
		(mid 385.09968 -253.831316)
		(end 385.281932 -253.881636)
		(width 0.0889)
		(layer "In2.Cu")
		(net "M_I_CPU0_SA_CA<3>")
	)
	(arc
		(start 383.967736 -253.881636)
		(mid 384.149987 -253.831286)
		(end 384.333496 -253.87681)
		(width 0.0889)
		(layer "In2.Cu")
		(net "M_I_CPU0_SA_CA<3>")
	)
	(arc
		(start 392.801856 -253.881636)
		(mid 393.084812 -253.957813)
		(end 393.367768 -253.881636)
		(width 0.0889)
		(layer "In2.Cu")
		(net "M_I_CPU0_SA_CA<3>")
	)
	(arc
		(start 376.456194 -253.87681)
		(mid 376.639702 -253.831316)
		(end 376.821954 -253.881636)
		(width 0.0889)
		(layer "In2.Cu")
		(net "M_I_CPU0_SA_CA<3>")
	)
	(arc
		(start 390.921748 -253.881636)
		(mid 391.204704 -253.957813)
		(end 391.48766 -253.881636)
		(width 0.0889)
		(layer "In2.Cu")
		(net "M_I_CPU0_SA_CA<3>")
	)
	(arc
		(start 387.727698 -253.881636)
		(mid 387.909949 -253.831286)
		(end 388.093458 -253.87681)
		(width 0.0889)
		(layer "In2.Cu")
		(net "M_I_CPU0_SA_CA<3>")
	)
	(arc
		(start 380.581916 -253.881636)
		(mid 380.864872 -253.957813)
		(end 381.147828 -253.881636)
		(width 0.0889)
		(layer "In2.Cu")
		(net "M_I_CPU0_SA_CA<3>")
	)
	(arc
		(start 376.821954 -253.881636)
		(mid 377.10491 -253.957813)
		(end 377.387866 -253.881636)
		(width 0.0889)
		(layer "In2.Cu")
		(net "M_I_CPU0_SA_CA<3>")
	)
	(arc
		(start 391.862056 -253.881636)
		(mid 392.145012 -253.957813)
		(end 392.427968 -253.881636)
		(width 0.0889)
		(layer "In2.Cu")
		(net "M_I_CPU0_SA_CA<3>")
	)
	(arc
		(start 393.367768 -253.881636)
		(mid 393.554966 -253.831254)
		(end 393.742164 -253.881636)
		(width 0.0889)
		(layer "In2.Cu")
		(net "M_I_CPU0_SA_CA<3>")
	)
	(arc
		(start 379.26772 -253.881636)
		(mid 379.449971 -253.831286)
		(end 379.63348 -253.87681)
		(width 0.0889)
		(layer "In2.Cu")
		(net "M_I_CPU0_SA_CA<3>")
	)
	(arc
		(start 385.856226 -253.87681)
		(mid 386.039734 -253.831316)
		(end 386.221986 -253.881636)
		(width 0.0889)
		(layer "In2.Cu")
		(net "M_I_CPU0_SA_CA<3>")
	)
	(arc
		(start 383.027682 -253.881636)
		(mid 383.209933 -253.831286)
		(end 383.393442 -253.87681)
		(width 0.0889)
		(layer "In2.Cu")
		(net "M_I_CPU0_SA_CA<3>")
	)
	(arc
		(start 384.341878 -253.881636)
		(mid 384.624834 -253.957813)
		(end 384.90779 -253.881636)
		(width 0.0889)
		(layer "In2.Cu")
		(net "M_I_CPU0_SA_CA<3>")
	)
	(arc
		(start 392.427968 -253.881636)
		(mid 392.614912 -253.831381)
		(end 392.801856 -253.881636)
		(width 0.0889)
		(layer "In2.Cu")
		(net "M_I_CPU0_SA_CA<3>")
	)
	(arc
		(start 386.221986 -253.881636)
		(mid 386.504942 -253.957813)
		(end 386.787898 -253.881636)
		(width 0.0889)
		(layer "In2.Cu")
		(net "M_I_CPU0_SA_CA<3>")
	)
	(arc
		(start 389.981948 -253.881636)
		(mid 390.264904 -253.957813)
		(end 390.54786 -253.881636)
		(width 0.0889)
		(layer "In2.Cu")
		(net "M_I_CPU0_SA_CA<3>")
	)
	(arc
		(start 387.161786 -253.881636)
		(mid 387.444742 -253.957813)
		(end 387.727698 -253.881636)
		(width 0.0889)
		(layer "In2.Cu")
		(net "M_I_CPU0_SA_CA<3>")
	)
	(arc
		(start 386.787898 -253.881636)
		(mid 386.974842 -253.831381)
		(end 387.161786 -253.881636)
		(width 0.0889)
		(layer "In2.Cu")
		(net "M_I_CPU0_SA_CA<3>")
	)
	(arc
		(start 375.945146 -253.913386)
		(mid 376.200211 -253.956737)
		(end 376.447812 -253.881636)
		(width 0.0889)
		(layer "In2.Cu")
		(net "M_I_CPU0_SA_CA<3>")
	)
	(arc
		(start 389.041894 -253.881636)
		(mid 389.32485 -253.957813)
		(end 389.607806 -253.881636)
		(width 0.0889)
		(layer "In2.Cu")
		(net "M_I_CPU0_SA_CA<3>")
	)
	(arc
		(start 377.761754 -253.881636)
		(mid 378.04471 -253.957813)
		(end 378.327666 -253.881636)
		(width 0.0889)
		(layer "In2.Cu")
		(net "M_I_CPU0_SA_CA<3>")
	)
	(arc
		(start 389.616188 -253.87681)
		(mid 389.799696 -253.831316)
		(end 389.981948 -253.881636)
		(width 0.0889)
		(layer "In2.Cu")
		(net "M_I_CPU0_SA_CA<3>")
	)
	(arc
		(start 378.701808 -253.881636)
		(mid 378.984764 -253.957813)
		(end 379.26772 -253.881636)
		(width 0.0889)
		(layer "In2.Cu")
		(net "M_I_CPU0_SA_CA<3>")
	)
	(arc
		(start 382.46177 -253.881636)
		(mid 382.744726 -253.957813)
		(end 383.027682 -253.881636)
		(width 0.0889)
		(layer "In2.Cu")
		(net "M_I_CPU0_SA_CA<3>")
	)
	(arc
		(start 378.327666 -253.881636)
		(mid 378.509917 -253.831286)
		(end 378.693426 -253.87681)
		(width 0.0889)
		(layer "In2.Cu")
		(net "M_I_CPU0_SA_CA<3>")
	)
	(arc
		(start 391.48766 -253.881636)
		(mid 391.674858 -253.831254)
		(end 391.862056 -253.881636)
		(width 0.0889)
		(layer "In2.Cu")
		(net "M_I_CPU0_SA_CA<3>")
	)
	(arc
		(start 381.52197 -253.881636)
		(mid 381.804926 -253.957813)
		(end 382.087882 -253.881636)
		(width 0.0889)
		(layer "In2.Cu")
		(net "M_I_CPU0_SA_CA<3>")
	)
	(arc
		(start 393.742164 -253.881636)
		(mid 394.138378 -254.046596)
		(end 394.563854 -254.10287)
		(width 0.0889)
		(layer "In2.Cu")
		(net "M_I_CPU0_SA_CA<3>")
	)
	(arc
		(start 388.667752 -253.881636)
		(mid 388.850003 -253.831286)
		(end 389.033512 -253.87681)
		(width 0.0889)
		(layer "In2.Cu")
		(net "M_I_CPU0_SA_CA<3>")
	)
	(arc
		(start 385.281932 -253.881636)
		(mid 385.564888 -253.957813)
		(end 385.847844 -253.881636)
		(width 0.0889)
		(layer "In2.Cu")
		(net "M_I_CPU0_SA_CA<3>")
	)
	(arc
		(start 377.387866 -253.881636)
		(mid 377.57481 -253.831381)
		(end 377.761754 -253.881636)
		(width 0.0889)
		(layer "In2.Cu")
		(net "M_I_CPU0_SA_CA<3>")
	)
	(arc
		(start 383.401824 -253.881636)
		(mid 383.68478 -253.957813)
		(end 383.967736 -253.881636)
		(width 0.0889)
		(layer "In2.Cu")
		(net "M_I_CPU0_SA_CA<3>")
	)
	(arc
		(start 380.216156 -253.87681)
		(mid 380.399664 -253.831316)
		(end 380.581916 -253.881636)
		(width 0.0889)
		(layer "In2.Cu")
		(net "M_I_CPU0_SA_CA<3>")
	)
	(segment
		(start 375.698004 -253.660148)
		(end 376.164856 -253.39421)
		(width 0.10668)
		(layer "F.Cu")
		(net "M_I_CPU0_SA_CA<2>")
	)
	(segment
		(start 386.683504 -253.721616)
		(end 386.691886 -253.71679)
		(width 0.0889)
		(layer "In2.Cu")
		(net "M_I_CPU0_SA_CA<2>")
	)
	(segment
		(start 422.424098 -249.610118)
		(end 431.131218 -249.610118)
		(width 0.14478)
		(layer "In2.Cu")
		(net "M_I_CPU0_SA_CA<2>")
	)
	(segment
		(start 420.724076 -251.31014)
		(end 422.424098 -249.610118)
		(width 0.14478)
		(layer "In2.Cu")
		(net "M_I_CPU0_SA_CA<2>")
	)
	(segment
		(start 394.233654 -253.82347)
		(end 395.082776 -253.82347)
		(width 0.0889)
		(layer "In2.Cu")
		(net "M_I_CPU0_SA_CA<2>")
	)
	(segment
		(start 411.00629 -251.31014)
		(end 420.724076 -251.31014)
		(width 0.14478)
		(layer "In2.Cu")
		(net "M_I_CPU0_SA_CA<2>")
	)
	(segment
		(start 408.998674 -253.317756)
		(end 411.00629 -251.31014)
		(width 0.14478)
		(layer "In2.Cu")
		(net "M_I_CPU0_SA_CA<2>")
	)
	(segment
		(start 382.557782 -253.71679)
		(end 382.566164 -253.721616)
		(width 0.0889)
		(layer "In2.Cu")
		(net "M_I_CPU0_SA_CA<2>")
	)
	(segment
		(start 385.74345 -253.721616)
		(end 385.751832 -253.71679)
		(width 0.0889)
		(layer "In2.Cu")
		(net "M_I_CPU0_SA_CA<2>")
	)
	(segment
		(start 392.323574 -253.721616)
		(end 392.331956 -253.71679)
		(width 0.0889)
		(layer "In2.Cu")
		(net "M_I_CPU0_SA_CA<2>")
	)
	(segment
		(start 383.497836 -253.71679)
		(end 383.506218 -253.721616)
		(width 0.0889)
		(layer "In2.Cu")
		(net "M_I_CPU0_SA_CA<2>")
	)
	(segment
		(start 431.131218 -249.610118)
		(end 431.55616 -249.185176)
		(width 0.14478)
		(layer "In2.Cu")
		(net "M_I_CPU0_SA_CA<2>")
	)
	(segment
		(start 381.043434 -253.721616)
		(end 381.051816 -253.71679)
		(width 0.0889)
		(layer "In2.Cu")
		(net "M_I_CPU0_SA_CA<2>")
	)
	(segment
		(start 377.857766 -253.71679)
		(end 377.866148 -253.721616)
		(width 0.0889)
		(layer "In2.Cu")
		(net "M_I_CPU0_SA_CA<2>")
	)
	(segment
		(start 395.242796 -253.98349)
		(end 395.84884 -253.98349)
		(width 0.0889)
		(layer "In2.Cu")
		(net "M_I_CPU0_SA_CA<2>")
	)
	(segment
		(start 399.467324 -252.846332)
		(end 404.499826 -252.846332)
		(width 0.14478)
		(layer "In2.Cu")
		(net "M_I_CPU0_SA_CA<2>")
	)
	(segment
		(start 391.01776 -253.71679)
		(end 391.026142 -253.721616)
		(width 0.0889)
		(layer "In2.Cu")
		(net "M_I_CPU0_SA_CA<2>")
	)
	(segment
		(start 381.983488 -253.721616)
		(end 381.99187 -253.71679)
		(width 0.0889)
		(layer "In2.Cu")
		(net "M_I_CPU0_SA_CA<2>")
	)
	(segment
		(start 387.257798 -253.71679)
		(end 387.26618 -253.721616)
		(width 0.0889)
		(layer "In2.Cu")
		(net "M_I_CPU0_SA_CA<2>")
	)
	(segment
		(start 404.97125 -253.317756)
		(end 408.998674 -253.317756)
		(width 0.14478)
		(layer "In2.Cu")
		(net "M_I_CPU0_SA_CA<2>")
	)
	(segment
		(start 388.197852 -253.71679)
		(end 388.206234 -253.721616)
		(width 0.0889)
		(layer "In2.Cu")
		(net "M_I_CPU0_SA_CA<2>")
	)
	(segment
		(start 376.010678 -253.65964)
		(end 376.03303 -253.742952)
		(width 0.0889)
		(layer "In2.Cu")
		(net "M_I_CPU0_SA_CA<2>")
	)
	(segment
		(start 404.499826 -252.846332)
		(end 404.97125 -253.317756)
		(width 0.14478)
		(layer "In2.Cu")
		(net "M_I_CPU0_SA_CA<2>")
	)
	(segment
		(start 392.897868 -253.71679)
		(end 392.90625 -253.721616)
		(width 0.0889)
		(layer "In2.Cu")
		(net "M_I_CPU0_SA_CA<2>")
	)
	(segment
		(start 376.343418 -253.721616)
		(end 376.3518 -253.71679)
		(width 0.0889)
		(layer "In2.Cu")
		(net "M_I_CPU0_SA_CA<2>")
	)
	(segment
		(start 378.79782 -253.71679)
		(end 378.806202 -253.721616)
		(width 0.0889)
		(layer "In2.Cu")
		(net "M_I_CPU0_SA_CA<2>")
	)
	(segment
		(start 376.164856 -253.39421)
		(end 376.010678 -253.65964)
		(width 0.0889)
		(layer "In2.Cu")
		(net "M_I_CPU0_SA_CA<2>")
	)
	(segment
		(start 398.330166 -253.98349)
		(end 399.467324 -252.846332)
		(width 0.14478)
		(layer "In2.Cu")
		(net "M_I_CPU0_SA_CA<2>")
	)
	(segment
		(start 377.283472 -253.721616)
		(end 377.291854 -253.71679)
		(width 0.0889)
		(layer "In2.Cu")
		(net "M_I_CPU0_SA_CA<2>")
	)
	(segment
		(start 390.443466 -253.721616)
		(end 390.451848 -253.71679)
		(width 0.0889)
		(layer "In2.Cu")
		(net "M_I_CPU0_SA_CA<2>")
	)
	(segment
		(start 395.082776 -253.82347)
		(end 395.242796 -253.98349)
		(width 0.0889)
		(layer "In2.Cu")
		(net "M_I_CPU0_SA_CA<2>")
	)
	(segment
		(start 395.84884 -253.98349)
		(end 398.330166 -253.98349)
		(width 0.14478)
		(layer "In2.Cu")
		(net "M_I_CPU0_SA_CA<2>")
	)
	(arc
		(start 389.137906 -253.71679)
		(mid 389.32485 -253.767045)
		(end 389.511794 -253.71679)
		(width 0.0889)
		(layer "In2.Cu")
		(net "M_I_CPU0_SA_CA<2>")
	)
	(arc
		(start 378.806202 -253.721616)
		(mid 378.98971 -253.76711)
		(end 379.171962 -253.71679)
		(width 0.0889)
		(layer "In2.Cu")
		(net "M_I_CPU0_SA_CA<2>")
	)
	(arc
		(start 388.206234 -253.721616)
		(mid 388.389742 -253.76711)
		(end 388.571994 -253.71679)
		(width 0.0889)
		(layer "In2.Cu")
		(net "M_I_CPU0_SA_CA<2>")
	)
	(arc
		(start 381.617728 -253.71679)
		(mid 381.799979 -253.76714)
		(end 381.983488 -253.721616)
		(width 0.0889)
		(layer "In2.Cu")
		(net "M_I_CPU0_SA_CA<2>")
	)
	(arc
		(start 392.90625 -253.721616)
		(mid 393.089758 -253.76711)
		(end 393.27201 -253.71679)
		(width 0.0889)
		(layer "In2.Cu")
		(net "M_I_CPU0_SA_CA<2>")
	)
	(arc
		(start 378.231908 -253.71679)
		(mid 378.514864 -253.640613)
		(end 378.79782 -253.71679)
		(width 0.0889)
		(layer "In2.Cu")
		(net "M_I_CPU0_SA_CA<2>")
	)
	(arc
		(start 379.171962 -253.71679)
		(mid 379.454918 -253.640613)
		(end 379.737874 -253.71679)
		(width 0.0889)
		(layer "In2.Cu")
		(net "M_I_CPU0_SA_CA<2>")
	)
	(arc
		(start 387.63194 -253.71679)
		(mid 387.914896 -253.640613)
		(end 388.197852 -253.71679)
		(width 0.0889)
		(layer "In2.Cu")
		(net "M_I_CPU0_SA_CA<2>")
	)
	(arc
		(start 377.291854 -253.71679)
		(mid 377.57481 -253.640613)
		(end 377.857766 -253.71679)
		(width 0.0889)
		(layer "In2.Cu")
		(net "M_I_CPU0_SA_CA<2>")
	)
	(arc
		(start 389.511794 -253.71679)
		(mid 389.79475 -253.640613)
		(end 390.077706 -253.71679)
		(width 0.0889)
		(layer "In2.Cu")
		(net "M_I_CPU0_SA_CA<2>")
	)
	(arc
		(start 377.866148 -253.721616)
		(mid 378.049656 -253.76711)
		(end 378.231908 -253.71679)
		(width 0.0889)
		(layer "In2.Cu")
		(net "M_I_CPU0_SA_CA<2>")
	)
	(arc
		(start 376.03303 -253.742952)
		(mid 376.19054 -253.76615)
		(end 376.343418 -253.721616)
		(width 0.0889)
		(layer "In2.Cu")
		(net "M_I_CPU0_SA_CA<2>")
	)
	(arc
		(start 382.566164 -253.721616)
		(mid 382.749672 -253.76711)
		(end 382.931924 -253.71679)
		(width 0.0889)
		(layer "In2.Cu")
		(net "M_I_CPU0_SA_CA<2>")
	)
	(arc
		(start 390.077706 -253.71679)
		(mid 390.259957 -253.76714)
		(end 390.443466 -253.721616)
		(width 0.0889)
		(layer "In2.Cu")
		(net "M_I_CPU0_SA_CA<2>")
	)
	(arc
		(start 391.026142 -253.721616)
		(mid 391.20965 -253.76711)
		(end 391.391902 -253.71679)
		(width 0.0889)
		(layer "In2.Cu")
		(net "M_I_CPU0_SA_CA<2>")
	)
	(arc
		(start 391.391902 -253.71679)
		(mid 391.674858 -253.640613)
		(end 391.957814 -253.71679)
		(width 0.0889)
		(layer "In2.Cu")
		(net "M_I_CPU0_SA_CA<2>")
	)
	(arc
		(start 382.931924 -253.71679)
		(mid 383.21488 -253.640613)
		(end 383.497836 -253.71679)
		(width 0.0889)
		(layer "In2.Cu")
		(net "M_I_CPU0_SA_CA<2>")
	)
	(arc
		(start 391.957814 -253.71679)
		(mid 392.140065 -253.76714)
		(end 392.323574 -253.721616)
		(width 0.0889)
		(layer "In2.Cu")
		(net "M_I_CPU0_SA_CA<2>")
	)
	(arc
		(start 383.506218 -253.721616)
		(mid 383.689726 -253.76711)
		(end 383.871978 -253.71679)
		(width 0.0889)
		(layer "In2.Cu")
		(net "M_I_CPU0_SA_CA<2>")
	)
	(arc
		(start 388.571994 -253.71679)
		(mid 388.85495 -253.640613)
		(end 389.137906 -253.71679)
		(width 0.0889)
		(layer "In2.Cu")
		(net "M_I_CPU0_SA_CA<2>")
	)
	(arc
		(start 380.111762 -253.71679)
		(mid 380.394718 -253.640613)
		(end 380.677674 -253.71679)
		(width 0.0889)
		(layer "In2.Cu")
		(net "M_I_CPU0_SA_CA<2>")
	)
	(arc
		(start 387.26618 -253.721616)
		(mid 387.449688 -253.76711)
		(end 387.63194 -253.71679)
		(width 0.0889)
		(layer "In2.Cu")
		(net "M_I_CPU0_SA_CA<2>")
	)
	(arc
		(start 376.917712 -253.71679)
		(mid 377.099963 -253.76714)
		(end 377.283472 -253.721616)
		(width 0.0889)
		(layer "In2.Cu")
		(net "M_I_CPU0_SA_CA<2>")
	)
	(arc
		(start 392.331956 -253.71679)
		(mid 392.614912 -253.640613)
		(end 392.897868 -253.71679)
		(width 0.0889)
		(layer "In2.Cu")
		(net "M_I_CPU0_SA_CA<2>")
	)
	(arc
		(start 393.27201 -253.71679)
		(mid 393.554966 -253.640613)
		(end 393.837922 -253.71679)
		(width 0.0889)
		(layer "In2.Cu")
		(net "M_I_CPU0_SA_CA<2>")
	)
	(arc
		(start 381.99187 -253.71679)
		(mid 382.274826 -253.640613)
		(end 382.557782 -253.71679)
		(width 0.0889)
		(layer "In2.Cu")
		(net "M_I_CPU0_SA_CA<2>")
	)
	(arc
		(start 386.691886 -253.71679)
		(mid 386.974842 -253.640613)
		(end 387.257798 -253.71679)
		(width 0.0889)
		(layer "In2.Cu")
		(net "M_I_CPU0_SA_CA<2>")
	)
	(arc
		(start 384.43789 -253.71679)
		(mid 384.624834 -253.767045)
		(end 384.811778 -253.71679)
		(width 0.0889)
		(layer "In2.Cu")
		(net "M_I_CPU0_SA_CA<2>")
	)
	(arc
		(start 376.3518 -253.71679)
		(mid 376.634756 -253.640613)
		(end 376.917712 -253.71679)
		(width 0.0889)
		(layer "In2.Cu")
		(net "M_I_CPU0_SA_CA<2>")
	)
	(arc
		(start 381.051816 -253.71679)
		(mid 381.334772 -253.640613)
		(end 381.617728 -253.71679)
		(width 0.0889)
		(layer "In2.Cu")
		(net "M_I_CPU0_SA_CA<2>")
	)
	(arc
		(start 384.811778 -253.71679)
		(mid 385.094734 -253.640613)
		(end 385.37769 -253.71679)
		(width 0.0889)
		(layer "In2.Cu")
		(net "M_I_CPU0_SA_CA<2>")
	)
	(arc
		(start 383.871978 -253.71679)
		(mid 384.154934 -253.640613)
		(end 384.43789 -253.71679)
		(width 0.0889)
		(layer "In2.Cu")
		(net "M_I_CPU0_SA_CA<2>")
	)
	(arc
		(start 379.737874 -253.71679)
		(mid 379.924818 -253.767045)
		(end 380.111762 -253.71679)
		(width 0.0889)
		(layer "In2.Cu")
		(net "M_I_CPU0_SA_CA<2>")
	)
	(arc
		(start 385.751832 -253.71679)
		(mid 386.034788 -253.640613)
		(end 386.317744 -253.71679)
		(width 0.0889)
		(layer "In2.Cu")
		(net "M_I_CPU0_SA_CA<2>")
	)
	(arc
		(start 393.837922 -253.71679)
		(mid 394.028726 -253.796325)
		(end 394.233654 -253.82347)
		(width 0.0889)
		(layer "In2.Cu")
		(net "M_I_CPU0_SA_CA<2>")
	)
	(arc
		(start 386.317744 -253.71679)
		(mid 386.499995 -253.76714)
		(end 386.683504 -253.721616)
		(width 0.0889)
		(layer "In2.Cu")
		(net "M_I_CPU0_SA_CA<2>")
	)
	(arc
		(start 380.677674 -253.71679)
		(mid 380.859925 -253.76714)
		(end 381.043434 -253.721616)
		(width 0.0889)
		(layer "In2.Cu")
		(net "M_I_CPU0_SA_CA<2>")
	)
	(arc
		(start 390.451848 -253.71679)
		(mid 390.734804 -253.640613)
		(end 391.01776 -253.71679)
		(width 0.0889)
		(layer "In2.Cu")
		(net "M_I_CPU0_SA_CA<2>")
	)
	(arc
		(start 385.37769 -253.71679)
		(mid 385.559941 -253.76714)
		(end 385.74345 -253.721616)
		(width 0.0889)
		(layer "In2.Cu")
		(net "M_I_CPU0_SA_CA<2>")
	)
	(segment
		(start 376.638058 -253.660148)
		(end 377.10491 -253.39421)
		(width 0.10668)
		(layer "F.Cu")
		(net "M_I_CPU0_SA_CA<1>")
	)
	(segment
		(start 399.280888 -252.396752)
		(end 404.686262 -252.396752)
		(width 0.14478)
		(layer "In2.Cu")
		(net "M_I_CPU0_SA_CA<1>")
	)
	(segment
		(start 377.10491 -253.39421)
		(end 377.258834 -253.12878)
		(width 0.0889)
		(layer "In2.Cu")
		(net "M_I_CPU0_SA_CA<1>")
	)
	(segment
		(start 387.257798 -253.07163)
		(end 387.26618 -253.066804)
		(width 0.0889)
		(layer "In2.Cu")
		(net "M_I_CPU0_SA_CA<1>")
	)
	(segment
		(start 391.956036 -253.071884)
		(end 391.97788 -253.059438)
		(width 0.0889)
		(layer "In2.Cu")
		(net "M_I_CPU0_SA_CA<1>")
	)
	(segment
		(start 381.043434 -253.066804)
		(end 381.051816 -253.07163)
		(width 0.0889)
		(layer "In2.Cu")
		(net "M_I_CPU0_SA_CA<1>")
	)
	(segment
		(start 414.847786 -250.16841)
		(end 415.114994 -250.16841)
		(width 0.14478)
		(layer "In2.Cu")
		(net "M_I_CPU0_SA_CA<1>")
	)
	(segment
		(start 392.328654 -253.07163)
		(end 392.35634 -253.087632)
		(width 0.0889)
		(layer "In2.Cu")
		(net "M_I_CPU0_SA_CA<1>")
	)
	(segment
		(start 388.197852 -253.07163)
		(end 388.206234 -253.066804)
		(width 0.0889)
		(layer "In2.Cu")
		(net "M_I_CPU0_SA_CA<1>")
	)
	(segment
		(start 377.857766 -253.07163)
		(end 377.866148 -253.066804)
		(width 0.0889)
		(layer "In2.Cu")
		(net "M_I_CPU0_SA_CA<1>")
	)
	(segment
		(start 377.258834 -253.12878)
		(end 377.354846 -253.10338)
		(width 0.0889)
		(layer "In2.Cu")
		(net "M_I_CPU0_SA_CA<1>")
	)
	(segment
		(start 426.283882 -248.760234)
		(end 427.030896 -248.760234)
		(width 0.14478)
		(layer "In2.Cu")
		(net "M_I_CPU0_SA_CA<1>")
	)
	(segment
		(start 417.831016 -250.460002)
		(end 418.122608 -250.16841)
		(width 0.14478)
		(layer "In2.Cu")
		(net "M_I_CPU0_SA_CA<1>")
	)
	(segment
		(start 386.683504 -253.066804)
		(end 386.691886 -253.07163)
		(width 0.0889)
		(layer "In2.Cu")
		(net "M_I_CPU0_SA_CA<1>")
	)
	(segment
		(start 382.557782 -253.07163)
		(end 382.566164 -253.066804)
		(width 0.0889)
		(layer "In2.Cu")
		(net "M_I_CPU0_SA_CA<1>")
	)
	(segment
		(start 385.74345 -253.066804)
		(end 385.751832 -253.07163)
		(width 0.0889)
		(layer "In2.Cu")
		(net "M_I_CPU0_SA_CA<1>")
	)
	(segment
		(start 378.79782 -253.07163)
		(end 378.806202 -253.066804)
		(width 0.0889)
		(layer "In2.Cu")
		(net "M_I_CPU0_SA_CA<1>")
	)
	(segment
		(start 411.220412 -250.460002)
		(end 413.438594 -250.460002)
		(width 0.14478)
		(layer "In2.Cu")
		(net "M_I_CPU0_SA_CA<1>")
	)
	(segment
		(start 391.93216 -253.085854)
		(end 391.956036 -253.071884)
		(width 0.0889)
		(layer "In2.Cu")
		(net "M_I_CPU0_SA_CA<1>")
	)
	(segment
		(start 381.983488 -253.066804)
		(end 381.99187 -253.07163)
		(width 0.0889)
		(layer "In2.Cu")
		(net "M_I_CPU0_SA_CA<1>")
	)
	(segment
		(start 405.157686 -252.868176)
		(end 408.812238 -252.868176)
		(width 0.14478)
		(layer "In2.Cu")
		(net "M_I_CPU0_SA_CA<1>")
	)
	(segment
		(start 418.122608 -250.16841)
		(end 418.389816 -250.16841)
		(width 0.14478)
		(layer "In2.Cu")
		(net "M_I_CPU0_SA_CA<1>")
	)
	(segment
		(start 413.997394 -250.16841)
		(end 414.288986 -250.460002)
		(width 0.14478)
		(layer "In2.Cu")
		(net "M_I_CPU0_SA_CA<1>")
	)
	(segment
		(start 393.240514 -253.054612)
		(end 393.270486 -253.071884)
		(width 0.0889)
		(layer "In2.Cu")
		(net "M_I_CPU0_SA_CA<1>")
	)
	(segment
		(start 420.931086 -250.460002)
		(end 422.630854 -248.760234)
		(width 0.14478)
		(layer "In2.Cu")
		(net "M_I_CPU0_SA_CA<1>")
	)
	(segment
		(start 383.497836 -253.07163)
		(end 383.506218 -253.066804)
		(width 0.0889)
		(layer "In2.Cu")
		(net "M_I_CPU0_SA_CA<1>")
	)
	(segment
		(start 413.730186 -250.16841)
		(end 413.997394 -250.16841)
		(width 0.14478)
		(layer "In2.Cu")
		(net "M_I_CPU0_SA_CA<1>")
	)
	(segment
		(start 413.438594 -250.460002)
		(end 413.730186 -250.16841)
		(width 0.14478)
		(layer "In2.Cu")
		(net "M_I_CPU0_SA_CA<1>")
	)
	(segment
		(start 425.962318 -248.43867)
		(end 426.283882 -248.760234)
		(width 0.14478)
		(layer "In2.Cu")
		(net "M_I_CPU0_SA_CA<1>")
	)
	(segment
		(start 390.443466 -253.066804)
		(end 390.451848 -253.07163)
		(width 0.0889)
		(layer "In2.Cu")
		(net "M_I_CPU0_SA_CA<1>")
	)
	(segment
		(start 398.165574 -253.512066)
		(end 399.280888 -252.396752)
		(width 0.14478)
		(layer "In2.Cu")
		(net "M_I_CPU0_SA_CA<1>")
	)
	(segment
		(start 391.01776 -253.07163)
		(end 391.026142 -253.066804)
		(width 0.0889)
		(layer "In2.Cu")
		(net "M_I_CPU0_SA_CA<1>")
	)
	(segment
		(start 425.403518 -248.760234)
		(end 425.725082 -248.43867)
		(width 0.14478)
		(layer "In2.Cu")
		(net "M_I_CPU0_SA_CA<1>")
	)
	(segment
		(start 415.406586 -250.460002)
		(end 417.831016 -250.460002)
		(width 0.14478)
		(layer "In2.Cu")
		(net "M_I_CPU0_SA_CA<1>")
	)
	(segment
		(start 414.556194 -250.460002)
		(end 414.847786 -250.16841)
		(width 0.14478)
		(layer "In2.Cu")
		(net "M_I_CPU0_SA_CA<1>")
	)
	(segment
		(start 394.915898 -253.512066)
		(end 395.880844 -253.512066)
		(width 0.0889)
		(layer "In2.Cu")
		(net "M_I_CPU0_SA_CA<1>")
	)
	(segment
		(start 395.880844 -253.512066)
		(end 398.165574 -253.512066)
		(width 0.14478)
		(layer "In2.Cu")
		(net "M_I_CPU0_SA_CA<1>")
	)
	(segment
		(start 425.725082 -248.43867)
		(end 425.962318 -248.43867)
		(width 0.14478)
		(layer "In2.Cu")
		(net "M_I_CPU0_SA_CA<1>")
	)
	(segment
		(start 415.114994 -250.16841)
		(end 415.406586 -250.460002)
		(width 0.14478)
		(layer "In2.Cu")
		(net "M_I_CPU0_SA_CA<1>")
	)
	(segment
		(start 418.389816 -250.16841)
		(end 418.681408 -250.460002)
		(width 0.14478)
		(layer "In2.Cu")
		(net "M_I_CPU0_SA_CA<1>")
	)
	(segment
		(start 418.681408 -250.460002)
		(end 420.931086 -250.460002)
		(width 0.14478)
		(layer "In2.Cu")
		(net "M_I_CPU0_SA_CA<1>")
	)
	(segment
		(start 408.812238 -252.868176)
		(end 411.220412 -250.460002)
		(width 0.14478)
		(layer "In2.Cu")
		(net "M_I_CPU0_SA_CA<1>")
	)
	(segment
		(start 414.288986 -250.460002)
		(end 414.556194 -250.460002)
		(width 0.14478)
		(layer "In2.Cu")
		(net "M_I_CPU0_SA_CA<1>")
	)
	(segment
		(start 404.686262 -252.396752)
		(end 405.157686 -252.868176)
		(width 0.14478)
		(layer "In2.Cu")
		(net "M_I_CPU0_SA_CA<1>")
	)
	(segment
		(start 427.030896 -248.760234)
		(end 427.456092 -248.335038)
		(width 0.14478)
		(layer "In2.Cu")
		(net "M_I_CPU0_SA_CA<1>")
	)
	(segment
		(start 422.630854 -248.760234)
		(end 425.403518 -248.760234)
		(width 0.14478)
		(layer "In2.Cu")
		(net "M_I_CPU0_SA_CA<1>")
	)
	(arc
		(start 384.811778 -253.07163)
		(mid 385.094734 -253.147807)
		(end 385.37769 -253.07163)
		(width 0.0889)
		(layer "In2.Cu")
		(net "M_I_CPU0_SA_CA<1>")
	)
	(arc
		(start 379.737874 -253.07163)
		(mid 379.924818 -253.021375)
		(end 380.111762 -253.07163)
		(width 0.0889)
		(layer "In2.Cu")
		(net "M_I_CPU0_SA_CA<1>")
	)
	(arc
		(start 391.97788 -253.059438)
		(mid 392.154808 -253.02161)
		(end 392.328654 -253.07163)
		(width 0.0889)
		(layer "In2.Cu")
		(net "M_I_CPU0_SA_CA<1>")
	)
	(arc
		(start 382.566164 -253.066804)
		(mid 382.749672 -253.02131)
		(end 382.931924 -253.07163)
		(width 0.0889)
		(layer "In2.Cu")
		(net "M_I_CPU0_SA_CA<1>")
	)
	(arc
		(start 389.511794 -253.07163)
		(mid 389.79475 -253.147807)
		(end 390.077706 -253.07163)
		(width 0.0889)
		(layer "In2.Cu")
		(net "M_I_CPU0_SA_CA<1>")
	)
	(arc
		(start 383.871978 -253.07163)
		(mid 384.154934 -253.147807)
		(end 384.43789 -253.07163)
		(width 0.0889)
		(layer "In2.Cu")
		(net "M_I_CPU0_SA_CA<1>")
	)
	(arc
		(start 377.354846 -253.10338)
		(mid 377.610054 -253.146857)
		(end 377.857766 -253.07163)
		(width 0.0889)
		(layer "In2.Cu")
		(net "M_I_CPU0_SA_CA<1>")
	)
	(arc
		(start 381.617728 -253.07163)
		(mid 381.799979 -253.02128)
		(end 381.983488 -253.066804)
		(width 0.0889)
		(layer "In2.Cu")
		(net "M_I_CPU0_SA_CA<1>")
	)
	(arc
		(start 378.806202 -253.066804)
		(mid 378.98971 -253.02131)
		(end 379.171962 -253.07163)
		(width 0.0889)
		(layer "In2.Cu")
		(net "M_I_CPU0_SA_CA<1>")
	)
	(arc
		(start 386.317744 -253.07163)
		(mid 386.499995 -253.02128)
		(end 386.683504 -253.066804)
		(width 0.0889)
		(layer "In2.Cu")
		(net "M_I_CPU0_SA_CA<1>")
	)
	(arc
		(start 385.751832 -253.07163)
		(mid 386.034788 -253.147807)
		(end 386.317744 -253.07163)
		(width 0.0889)
		(layer "In2.Cu")
		(net "M_I_CPU0_SA_CA<1>")
	)
	(arc
		(start 392.896344 -253.07163)
		(mid 393.066351 -253.021065)
		(end 393.240514 -253.054612)
		(width 0.0889)
		(layer "In2.Cu")
		(net "M_I_CPU0_SA_CA<1>")
	)
	(arc
		(start 383.506218 -253.066804)
		(mid 383.689726 -253.02131)
		(end 383.871978 -253.07163)
		(width 0.0889)
		(layer "In2.Cu")
		(net "M_I_CPU0_SA_CA<1>")
	)
	(arc
		(start 381.051816 -253.07163)
		(mid 381.334772 -253.147807)
		(end 381.617728 -253.07163)
		(width 0.0889)
		(layer "In2.Cu")
		(net "M_I_CPU0_SA_CA<1>")
	)
	(arc
		(start 389.137906 -253.07163)
		(mid 389.32485 -253.021375)
		(end 389.511794 -253.07163)
		(width 0.0889)
		(layer "In2.Cu")
		(net "M_I_CPU0_SA_CA<1>")
	)
	(arc
		(start 388.571994 -253.07163)
		(mid 388.85495 -253.147807)
		(end 389.137906 -253.07163)
		(width 0.0889)
		(layer "In2.Cu")
		(net "M_I_CPU0_SA_CA<1>")
	)
	(arc
		(start 380.111762 -253.07163)
		(mid 380.394718 -253.147807)
		(end 380.677674 -253.07163)
		(width 0.0889)
		(layer "In2.Cu")
		(net "M_I_CPU0_SA_CA<1>")
	)
	(arc
		(start 391.391902 -253.07163)
		(mid 391.660222 -253.147738)
		(end 391.93216 -253.085854)
		(width 0.0889)
		(layer "In2.Cu")
		(net "M_I_CPU0_SA_CA<1>")
	)
	(arc
		(start 391.026142 -253.066804)
		(mid 391.20965 -253.02131)
		(end 391.391902 -253.07163)
		(width 0.0889)
		(layer "In2.Cu")
		(net "M_I_CPU0_SA_CA<1>")
	)
	(arc
		(start 381.99187 -253.07163)
		(mid 382.274826 -253.147807)
		(end 382.557782 -253.07163)
		(width 0.0889)
		(layer "In2.Cu")
		(net "M_I_CPU0_SA_CA<1>")
	)
	(arc
		(start 378.231908 -253.07163)
		(mid 378.514864 -253.147807)
		(end 378.79782 -253.07163)
		(width 0.0889)
		(layer "In2.Cu")
		(net "M_I_CPU0_SA_CA<1>")
	)
	(arc
		(start 393.270486 -253.071884)
		(mid 394.064257 -253.400143)
		(end 394.915898 -253.512066)
		(width 0.0889)
		(layer "In2.Cu")
		(net "M_I_CPU0_SA_CA<1>")
	)
	(arc
		(start 388.206234 -253.066804)
		(mid 388.389742 -253.02131)
		(end 388.571994 -253.07163)
		(width 0.0889)
		(layer "In2.Cu")
		(net "M_I_CPU0_SA_CA<1>")
	)
	(arc
		(start 392.35634 -253.087632)
		(mid 392.628374 -253.148404)
		(end 392.896344 -253.07163)
		(width 0.0889)
		(layer "In2.Cu")
		(net "M_I_CPU0_SA_CA<1>")
	)
	(arc
		(start 384.43789 -253.07163)
		(mid 384.624834 -253.021375)
		(end 384.811778 -253.07163)
		(width 0.0889)
		(layer "In2.Cu")
		(net "M_I_CPU0_SA_CA<1>")
	)
	(arc
		(start 377.866148 -253.066804)
		(mid 378.049656 -253.02131)
		(end 378.231908 -253.07163)
		(width 0.0889)
		(layer "In2.Cu")
		(net "M_I_CPU0_SA_CA<1>")
	)
	(arc
		(start 387.63194 -253.07163)
		(mid 387.914896 -253.147807)
		(end 388.197852 -253.07163)
		(width 0.0889)
		(layer "In2.Cu")
		(net "M_I_CPU0_SA_CA<1>")
	)
	(arc
		(start 390.077706 -253.07163)
		(mid 390.259957 -253.02128)
		(end 390.443466 -253.066804)
		(width 0.0889)
		(layer "In2.Cu")
		(net "M_I_CPU0_SA_CA<1>")
	)
	(arc
		(start 382.931924 -253.07163)
		(mid 383.21488 -253.147807)
		(end 383.497836 -253.07163)
		(width 0.0889)
		(layer "In2.Cu")
		(net "M_I_CPU0_SA_CA<1>")
	)
	(arc
		(start 386.691886 -253.07163)
		(mid 386.974842 -253.147807)
		(end 387.257798 -253.07163)
		(width 0.0889)
		(layer "In2.Cu")
		(net "M_I_CPU0_SA_CA<1>")
	)
	(arc
		(start 379.171962 -253.07163)
		(mid 379.454918 -253.147807)
		(end 379.737874 -253.07163)
		(width 0.0889)
		(layer "In2.Cu")
		(net "M_I_CPU0_SA_CA<1>")
	)
	(arc
		(start 390.451848 -253.07163)
		(mid 390.734804 -253.147807)
		(end 391.01776 -253.07163)
		(width 0.0889)
		(layer "In2.Cu")
		(net "M_I_CPU0_SA_CA<1>")
	)
	(arc
		(start 387.26618 -253.066804)
		(mid 387.449688 -253.02131)
		(end 387.63194 -253.07163)
		(width 0.0889)
		(layer "In2.Cu")
		(net "M_I_CPU0_SA_CA<1>")
	)
	(arc
		(start 385.37769 -253.07163)
		(mid 385.559941 -253.02128)
		(end 385.74345 -253.066804)
		(width 0.0889)
		(layer "In2.Cu")
		(net "M_I_CPU0_SA_CA<1>")
	)
	(arc
		(start 380.677674 -253.07163)
		(mid 380.859925 -253.02128)
		(end 381.043434 -253.066804)
		(width 0.0889)
		(layer "In2.Cu")
		(net "M_I_CPU0_SA_CA<1>")
	)
	(segment
		(start 377.107958 -252.850142)
		(end 377.57481 -252.584204)
		(width 0.10668)
		(layer "F.Cu")
		(net "M_I_CPU0_SA_CA<0>")
	)
	(segment
		(start 408.625548 -252.418596)
		(end 411.434026 -249.610118)
		(width 0.14478)
		(layer "In2.Cu")
		(net "M_I_CPU0_SA_CA<0>")
	)
	(segment
		(start 391.837164 -252.919992)
		(end 391.860532 -252.90653)
		(width 0.0889)
		(layer "In2.Cu")
		(net "M_I_CPU0_SA_CA<0>")
	)
	(segment
		(start 389.607806 -252.906784)
		(end 389.616188 -252.91161)
		(width 0.0889)
		(layer "In2.Cu")
		(net "M_I_CPU0_SA_CA<0>")
	)
	(segment
		(start 431.131218 -247.910096)
		(end 431.55616 -247.485154)
		(width 0.14478)
		(layer "In2.Cu")
		(net "M_I_CPU0_SA_CA<0>")
	)
	(segment
		(start 399.094452 -251.947172)
		(end 404.872698 -251.947172)
		(width 0.14478)
		(layer "In2.Cu")
		(net "M_I_CPU0_SA_CA<0>")
	)
	(segment
		(start 384.333496 -252.91161)
		(end 384.341878 -252.906784)
		(width 0.0889)
		(layer "In2.Cu")
		(net "M_I_CPU0_SA_CA<0>")
	)
	(segment
		(start 394.521944 -253.216918)
		(end 394.962634 -253.216918)
		(width 0.0889)
		(layer "In2.Cu")
		(net "M_I_CPU0_SA_CA<0>")
	)
	(segment
		(start 393.32789 -252.884686)
		(end 393.365736 -252.90653)
		(width 0.0889)
		(layer "In2.Cu")
		(net "M_I_CPU0_SA_CA<0>")
	)
	(segment
		(start 385.847844 -252.906784)
		(end 385.856226 -252.91161)
		(width 0.0889)
		(layer "In2.Cu")
		(net "M_I_CPU0_SA_CA<0>")
	)
	(segment
		(start 389.033512 -252.91161)
		(end 389.041894 -252.906784)
		(width 0.0889)
		(layer "In2.Cu")
		(net "M_I_CPU0_SA_CA<0>")
	)
	(segment
		(start 422.83761 -247.910096)
		(end 431.131218 -247.910096)
		(width 0.14478)
		(layer "In2.Cu")
		(net "M_I_CPU0_SA_CA<0>")
	)
	(segment
		(start 377.57481 -252.584204)
		(end 377.420886 -252.849634)
		(width 0.0889)
		(layer "In2.Cu")
		(net "M_I_CPU0_SA_CA<0>")
	)
	(segment
		(start 405.344122 -252.418596)
		(end 408.625548 -252.418596)
		(width 0.14478)
		(layer "In2.Cu")
		(net "M_I_CPU0_SA_CA<0>")
	)
	(segment
		(start 384.90779 -252.906784)
		(end 384.916172 -252.91161)
		(width 0.0889)
		(layer "In2.Cu")
		(net "M_I_CPU0_SA_CA<0>")
	)
	(segment
		(start 380.207774 -252.906784)
		(end 380.216156 -252.91161)
		(width 0.0889)
		(layer "In2.Cu")
		(net "M_I_CPU0_SA_CA<0>")
	)
	(segment
		(start 378.693426 -252.91161)
		(end 378.701808 -252.906784)
		(width 0.0889)
		(layer "In2.Cu")
		(net "M_I_CPU0_SA_CA<0>")
	)
	(segment
		(start 394.962634 -253.216918)
		(end 395.233652 -252.9459)
		(width 0.0889)
		(layer "In2.Cu")
		(net "M_I_CPU0_SA_CA<0>")
	)
	(segment
		(start 381.147828 -252.906784)
		(end 381.15621 -252.91161)
		(width 0.0889)
		(layer "In2.Cu")
		(net "M_I_CPU0_SA_CA<0>")
	)
	(segment
		(start 392.424666 -252.906784)
		(end 392.44524 -252.918722)
		(width 0.0889)
		(layer "In2.Cu")
		(net "M_I_CPU0_SA_CA<0>")
	)
	(segment
		(start 391.860532 -252.90653)
		(end 391.884408 -252.89256)
		(width 0.0889)
		(layer "In2.Cu")
		(net "M_I_CPU0_SA_CA<0>")
	)
	(segment
		(start 388.093458 -252.91161)
		(end 388.10184 -252.906784)
		(width 0.0889)
		(layer "In2.Cu")
		(net "M_I_CPU0_SA_CA<0>")
	)
	(segment
		(start 398.095724 -252.9459)
		(end 399.094452 -251.947172)
		(width 0.14478)
		(layer "In2.Cu")
		(net "M_I_CPU0_SA_CA<0>")
	)
	(segment
		(start 379.63348 -252.91161)
		(end 379.641862 -252.906784)
		(width 0.0889)
		(layer "In2.Cu")
		(net "M_I_CPU0_SA_CA<0>")
	)
	(segment
		(start 395.233652 -252.9459)
		(end 395.680438 -252.9459)
		(width 0.0889)
		(layer "In2.Cu")
		(net "M_I_CPU0_SA_CA<0>")
	)
	(segment
		(start 411.434026 -249.610118)
		(end 421.137588 -249.610118)
		(width 0.14478)
		(layer "In2.Cu")
		(net "M_I_CPU0_SA_CA<0>")
	)
	(segment
		(start 377.420886 -252.849634)
		(end 377.443238 -252.932946)
		(width 0.0889)
		(layer "In2.Cu")
		(net "M_I_CPU0_SA_CA<0>")
	)
	(segment
		(start 395.680438 -252.9459)
		(end 398.095724 -252.9459)
		(width 0.14478)
		(layer "In2.Cu")
		(net "M_I_CPU0_SA_CA<0>")
	)
	(segment
		(start 421.137588 -249.610118)
		(end 422.83761 -247.910096)
		(width 0.14478)
		(layer "In2.Cu")
		(net "M_I_CPU0_SA_CA<0>")
	)
	(segment
		(start 383.393442 -252.91161)
		(end 383.401824 -252.906784)
		(width 0.0889)
		(layer "In2.Cu")
		(net "M_I_CPU0_SA_CA<0>")
	)
	(segment
		(start 404.872698 -251.947172)
		(end 405.344122 -252.418596)
		(width 0.14478)
		(layer "In2.Cu")
		(net "M_I_CPU0_SA_CA<0>")
	)
	(arc
		(start 392.800078 -252.906784)
		(mid 393.061236 -252.830205)
		(end 393.32789 -252.884686)
		(width 0.0889)
		(layer "In2.Cu")
		(net "M_I_CPU0_SA_CA<0>")
	)
	(arc
		(start 386.221986 -252.906784)
		(mid 386.504942 -252.830607)
		(end 386.787898 -252.906784)
		(width 0.0889)
		(layer "In2.Cu")
		(net "M_I_CPU0_SA_CA<0>")
	)
	(arc
		(start 382.087882 -252.906784)
		(mid 382.274826 -252.957039)
		(end 382.46177 -252.906784)
		(width 0.0889)
		(layer "In2.Cu")
		(net "M_I_CPU0_SA_CA<0>")
	)
	(arc
		(start 388.10184 -252.906784)
		(mid 388.384796 -252.830607)
		(end 388.667752 -252.906784)
		(width 0.0889)
		(layer "In2.Cu")
		(net "M_I_CPU0_SA_CA<0>")
	)
	(arc
		(start 391.48766 -252.906784)
		(mid 391.660768 -252.9569)
		(end 391.837164 -252.919992)
		(width 0.0889)
		(layer "In2.Cu")
		(net "M_I_CPU0_SA_CA<0>")
	)
	(arc
		(start 377.761754 -252.906784)
		(mid 378.04471 -252.830607)
		(end 378.327666 -252.906784)
		(width 0.0889)
		(layer "In2.Cu")
		(net "M_I_CPU0_SA_CA<0>")
	)
	(arc
		(start 387.727698 -252.906784)
		(mid 387.909949 -252.957134)
		(end 388.093458 -252.91161)
		(width 0.0889)
		(layer "In2.Cu")
		(net "M_I_CPU0_SA_CA<0>")
	)
	(arc
		(start 379.26772 -252.906784)
		(mid 379.449971 -252.957134)
		(end 379.63348 -252.91161)
		(width 0.0889)
		(layer "In2.Cu")
		(net "M_I_CPU0_SA_CA<0>")
	)
	(arc
		(start 383.027682 -252.906784)
		(mid 383.209933 -252.957134)
		(end 383.393442 -252.91161)
		(width 0.0889)
		(layer "In2.Cu")
		(net "M_I_CPU0_SA_CA<0>")
	)
	(arc
		(start 389.041894 -252.906784)
		(mid 389.32485 -252.830607)
		(end 389.607806 -252.906784)
		(width 0.0889)
		(layer "In2.Cu")
		(net "M_I_CPU0_SA_CA<0>")
	)
	(arc
		(start 390.921748 -252.906784)
		(mid 391.204704 -252.830607)
		(end 391.48766 -252.906784)
		(width 0.0889)
		(layer "In2.Cu")
		(net "M_I_CPU0_SA_CA<0>")
	)
	(arc
		(start 380.216156 -252.91161)
		(mid 380.399664 -252.957104)
		(end 380.581916 -252.906784)
		(width 0.0889)
		(layer "In2.Cu")
		(net "M_I_CPU0_SA_CA<0>")
	)
	(arc
		(start 387.161786 -252.906784)
		(mid 387.444742 -252.830607)
		(end 387.727698 -252.906784)
		(width 0.0889)
		(layer "In2.Cu")
		(net "M_I_CPU0_SA_CA<0>")
	)
	(arc
		(start 385.856226 -252.91161)
		(mid 386.039734 -252.957104)
		(end 386.221986 -252.906784)
		(width 0.0889)
		(layer "In2.Cu")
		(net "M_I_CPU0_SA_CA<0>")
	)
	(arc
		(start 378.701808 -252.906784)
		(mid 378.984764 -252.830607)
		(end 379.26772 -252.906784)
		(width 0.0889)
		(layer "In2.Cu")
		(net "M_I_CPU0_SA_CA<0>")
	)
	(arc
		(start 388.667752 -252.906784)
		(mid 388.850003 -252.957134)
		(end 389.033512 -252.91161)
		(width 0.0889)
		(layer "In2.Cu")
		(net "M_I_CPU0_SA_CA<0>")
	)
	(arc
		(start 381.15621 -252.91161)
		(mid 381.339718 -252.957104)
		(end 381.52197 -252.906784)
		(width 0.0889)
		(layer "In2.Cu")
		(net "M_I_CPU0_SA_CA<0>")
	)
	(arc
		(start 390.54786 -252.906784)
		(mid 390.734804 -252.957039)
		(end 390.921748 -252.906784)
		(width 0.0889)
		(layer "In2.Cu")
		(net "M_I_CPU0_SA_CA<0>")
	)
	(arc
		(start 391.884408 -252.89256)
		(mid 392.156345 -252.830734)
		(end 392.424666 -252.906784)
		(width 0.0889)
		(layer "In2.Cu")
		(net "M_I_CPU0_SA_CA<0>")
	)
	(arc
		(start 382.46177 -252.906784)
		(mid 382.744726 -252.830607)
		(end 383.027682 -252.906784)
		(width 0.0889)
		(layer "In2.Cu")
		(net "M_I_CPU0_SA_CA<0>")
	)
	(arc
		(start 383.401824 -252.906784)
		(mid 383.68478 -252.830607)
		(end 383.967736 -252.906784)
		(width 0.0889)
		(layer "In2.Cu")
		(net "M_I_CPU0_SA_CA<0>")
	)
	(arc
		(start 380.581916 -252.906784)
		(mid 380.864872 -252.830607)
		(end 381.147828 -252.906784)
		(width 0.0889)
		(layer "In2.Cu")
		(net "M_I_CPU0_SA_CA<0>")
	)
	(arc
		(start 377.443238 -252.932946)
		(mid 377.605427 -252.955681)
		(end 377.761754 -252.906784)
		(width 0.0889)
		(layer "In2.Cu")
		(net "M_I_CPU0_SA_CA<0>")
	)
	(arc
		(start 384.341878 -252.906784)
		(mid 384.624834 -252.830607)
		(end 384.90779 -252.906784)
		(width 0.0889)
		(layer "In2.Cu")
		(net "M_I_CPU0_SA_CA<0>")
	)
	(arc
		(start 381.52197 -252.906784)
		(mid 381.804926 -252.830607)
		(end 382.087882 -252.906784)
		(width 0.0889)
		(layer "In2.Cu")
		(net "M_I_CPU0_SA_CA<0>")
	)
	(arc
		(start 393.365736 -252.90653)
		(mid 393.92337 -253.137976)
		(end 394.521944 -253.216918)
		(width 0.0889)
		(layer "In2.Cu")
		(net "M_I_CPU0_SA_CA<0>")
	)
	(arc
		(start 384.916172 -252.91161)
		(mid 385.09968 -252.957104)
		(end 385.281932 -252.906784)
		(width 0.0889)
		(layer "In2.Cu")
		(net "M_I_CPU0_SA_CA<0>")
	)
	(arc
		(start 389.981948 -252.906784)
		(mid 390.264904 -252.830607)
		(end 390.54786 -252.906784)
		(width 0.0889)
		(layer "In2.Cu")
		(net "M_I_CPU0_SA_CA<0>")
	)
	(arc
		(start 389.616188 -252.91161)
		(mid 389.799696 -252.957104)
		(end 389.981948 -252.906784)
		(width 0.0889)
		(layer "In2.Cu")
		(net "M_I_CPU0_SA_CA<0>")
	)
	(arc
		(start 379.641862 -252.906784)
		(mid 379.924818 -252.830607)
		(end 380.207774 -252.906784)
		(width 0.0889)
		(layer "In2.Cu")
		(net "M_I_CPU0_SA_CA<0>")
	)
	(arc
		(start 386.787898 -252.906784)
		(mid 386.974842 -252.957039)
		(end 387.161786 -252.906784)
		(width 0.0889)
		(layer "In2.Cu")
		(net "M_I_CPU0_SA_CA<0>")
	)
	(arc
		(start 378.327666 -252.906784)
		(mid 378.509917 -252.957134)
		(end 378.693426 -252.91161)
		(width 0.0889)
		(layer "In2.Cu")
		(net "M_I_CPU0_SA_CA<0>")
	)
	(arc
		(start 392.44524 -252.918722)
		(mid 392.624168 -252.957599)
		(end 392.800078 -252.906784)
		(width 0.0889)
		(layer "In2.Cu")
		(net "M_I_CPU0_SA_CA<0>")
	)
	(arc
		(start 383.967736 -252.906784)
		(mid 384.149987 -252.957134)
		(end 384.333496 -252.91161)
		(width 0.0889)
		(layer "In2.Cu")
		(net "M_I_CPU0_SA_CA<0>")
	)
	(arc
		(start 385.281932 -252.906784)
		(mid 385.564888 -252.830607)
		(end 385.847844 -252.906784)
		(width 0.0889)
		(layer "In2.Cu")
		(net "M_I_CPU0_SA_CA<0>")
	)
	(segment
		(start 375.22785 -251.23013)
		(end 375.694702 -250.964192)
		(width 0.10668)
		(layer "F.Cu")
		(net "M_I_CPU0_RESET_N")
	)
	(segment
		(start 376.447812 -250.641612)
		(end 376.456194 -250.636786)
		(width 0.0889)
		(layer "In2.Cu")
		(net "M_I_CPU0_RESET_N")
	)
	(segment
		(start 379.63348 -250.636786)
		(end 379.641862 -250.641612)
		(width 0.0889)
		(layer "In2.Cu")
		(net "M_I_CPU0_RESET_N")
	)
	(segment
		(start 389.033512 -250.636786)
		(end 389.041894 -250.641612)
		(width 0.0889)
		(layer "In2.Cu")
		(net "M_I_CPU0_RESET_N")
	)
	(segment
		(start 375.694702 -250.964192)
		(end 375.84888 -250.698762)
		(width 0.0889)
		(layer "In2.Cu")
		(net "M_I_CPU0_RESET_N")
	)
	(segment
		(start 427.030896 -245.36019)
		(end 427.456092 -244.934994)
		(width 0.11684)
		(layer "In2.Cu")
		(net "M_I_CPU0_RESET_N")
	)
	(segment
		(start 389.607806 -250.641612)
		(end 389.616188 -250.636786)
		(width 0.0889)
		(layer "In2.Cu")
		(net "M_I_CPU0_RESET_N")
	)
	(segment
		(start 398.414748 -250.307602)
		(end 405.552402 -250.307602)
		(width 0.11684)
		(layer "In2.Cu")
		(net "M_I_CPU0_RESET_N")
	)
	(segment
		(start 406.023826 -250.779026)
		(end 407.500836 -250.779026)
		(width 0.11684)
		(layer "In2.Cu")
		(net "M_I_CPU0_RESET_N")
	)
	(segment
		(start 407.500836 -250.779026)
		(end 411.21965 -247.060212)
		(width 0.11684)
		(layer "In2.Cu")
		(net "M_I_CPU0_RESET_N")
	)
	(segment
		(start 411.21965 -247.060212)
		(end 421.353742 -247.060212)
		(width 0.11684)
		(layer "In2.Cu")
		(net "M_I_CPU0_RESET_N")
	)
	(segment
		(start 393.55522 -250.591066)
		(end 394.009118 -250.591066)
		(width 0.0889)
		(layer "In2.Cu")
		(net "M_I_CPU0_RESET_N")
	)
	(segment
		(start 378.693426 -250.636786)
		(end 378.701808 -250.641612)
		(width 0.0889)
		(layer "In2.Cu")
		(net "M_I_CPU0_RESET_N")
	)
	(segment
		(start 388.093458 -250.636786)
		(end 388.10184 -250.641612)
		(width 0.0889)
		(layer "In2.Cu")
		(net "M_I_CPU0_RESET_N")
	)
	(segment
		(start 394.953236 -250.84913)
		(end 397.87322 -250.84913)
		(width 0.11684)
		(layer "In2.Cu")
		(net "M_I_CPU0_RESET_N")
	)
	(segment
		(start 397.87322 -250.84913)
		(end 398.414748 -250.307602)
		(width 0.11684)
		(layer "In2.Cu")
		(net "M_I_CPU0_RESET_N")
	)
	(segment
		(start 421.353742 -247.060212)
		(end 423.053764 -245.36019)
		(width 0.11684)
		(layer "In2.Cu")
		(net "M_I_CPU0_RESET_N")
	)
	(segment
		(start 423.053764 -245.36019)
		(end 427.030896 -245.36019)
		(width 0.11684)
		(layer "In2.Cu")
		(net "M_I_CPU0_RESET_N")
	)
	(segment
		(start 383.393442 -250.636786)
		(end 383.401824 -250.641612)
		(width 0.0889)
		(layer "In2.Cu")
		(net "M_I_CPU0_RESET_N")
	)
	(segment
		(start 380.207774 -250.641612)
		(end 380.216156 -250.636786)
		(width 0.0889)
		(layer "In2.Cu")
		(net "M_I_CPU0_RESET_N")
	)
	(segment
		(start 375.84888 -250.698762)
		(end 375.945146 -250.673362)
		(width 0.0889)
		(layer "In2.Cu")
		(net "M_I_CPU0_RESET_N")
	)
	(segment
		(start 381.147828 -250.641612)
		(end 381.15621 -250.636786)
		(width 0.0889)
		(layer "In2.Cu")
		(net "M_I_CPU0_RESET_N")
	)
	(segment
		(start 385.847844 -250.641612)
		(end 385.856226 -250.636786)
		(width 0.0889)
		(layer "In2.Cu")
		(net "M_I_CPU0_RESET_N")
	)
	(segment
		(start 392.793474 -250.636786)
		(end 392.801856 -250.641612)
		(width 0.0889)
		(layer "In2.Cu")
		(net "M_I_CPU0_RESET_N")
	)
	(segment
		(start 391.85342 -250.636786)
		(end 391.861802 -250.641612)
		(width 0.0889)
		(layer "In2.Cu")
		(net "M_I_CPU0_RESET_N")
	)
	(segment
		(start 384.90779 -250.641612)
		(end 384.916172 -250.636786)
		(width 0.0889)
		(layer "In2.Cu")
		(net "M_I_CPU0_RESET_N")
	)
	(segment
		(start 384.333496 -250.636786)
		(end 384.341878 -250.641612)
		(width 0.0889)
		(layer "In2.Cu")
		(net "M_I_CPU0_RESET_N")
	)
	(segment
		(start 405.552402 -250.307602)
		(end 406.023826 -250.779026)
		(width 0.11684)
		(layer "In2.Cu")
		(net "M_I_CPU0_RESET_N")
	)
	(arc
		(start 380.216156 -250.636786)
		(mid 380.399664 -250.591292)
		(end 380.581916 -250.641612)
		(width 0.0889)
		(layer "In2.Cu")
		(net "M_I_CPU0_RESET_N")
	)
	(arc
		(start 392.801856 -250.641612)
		(mid 393.084812 -250.717789)
		(end 393.367768 -250.641612)
		(width 0.0889)
		(layer "In2.Cu")
		(net "M_I_CPU0_RESET_N")
	)
	(arc
		(start 379.26772 -250.641612)
		(mid 379.449971 -250.591262)
		(end 379.63348 -250.636786)
		(width 0.0889)
		(layer "In2.Cu")
		(net "M_I_CPU0_RESET_N")
	)
	(arc
		(start 387.161786 -250.641612)
		(mid 387.444742 -250.717789)
		(end 387.727698 -250.641612)
		(width 0.0889)
		(layer "In2.Cu")
		(net "M_I_CPU0_RESET_N")
	)
	(arc
		(start 378.327666 -250.641612)
		(mid 378.509917 -250.591262)
		(end 378.693426 -250.636786)
		(width 0.0889)
		(layer "In2.Cu")
		(net "M_I_CPU0_RESET_N")
	)
	(arc
		(start 381.52197 -250.641612)
		(mid 381.804926 -250.717789)
		(end 382.087882 -250.641612)
		(width 0.0889)
		(layer "In2.Cu")
		(net "M_I_CPU0_RESET_N")
	)
	(arc
		(start 377.761754 -250.641612)
		(mid 378.04471 -250.717789)
		(end 378.327666 -250.641612)
		(width 0.0889)
		(layer "In2.Cu")
		(net "M_I_CPU0_RESET_N")
	)
	(arc
		(start 375.945146 -250.673362)
		(mid 376.200211 -250.716713)
		(end 376.447812 -250.641612)
		(width 0.0889)
		(layer "In2.Cu")
		(net "M_I_CPU0_RESET_N")
	)
	(arc
		(start 383.967736 -250.641612)
		(mid 384.149987 -250.591262)
		(end 384.333496 -250.636786)
		(width 0.0889)
		(layer "In2.Cu")
		(net "M_I_CPU0_RESET_N")
	)
	(arc
		(start 386.221986 -250.641612)
		(mid 386.504942 -250.717789)
		(end 386.787898 -250.641612)
		(width 0.0889)
		(layer "In2.Cu")
		(net "M_I_CPU0_RESET_N")
	)
	(arc
		(start 383.401824 -250.641612)
		(mid 383.68478 -250.717789)
		(end 383.967736 -250.641612)
		(width 0.0889)
		(layer "In2.Cu")
		(net "M_I_CPU0_RESET_N")
	)
	(arc
		(start 390.54786 -250.641612)
		(mid 390.734804 -250.591357)
		(end 390.921748 -250.641612)
		(width 0.0889)
		(layer "In2.Cu")
		(net "M_I_CPU0_RESET_N")
	)
	(arc
		(start 382.46177 -250.641612)
		(mid 382.744726 -250.717789)
		(end 383.027682 -250.641612)
		(width 0.0889)
		(layer "In2.Cu")
		(net "M_I_CPU0_RESET_N")
	)
	(arc
		(start 384.341878 -250.641612)
		(mid 384.624834 -250.717789)
		(end 384.90779 -250.641612)
		(width 0.0889)
		(layer "In2.Cu")
		(net "M_I_CPU0_RESET_N")
	)
	(arc
		(start 391.861802 -250.641612)
		(mid 392.144758 -250.717789)
		(end 392.427714 -250.641612)
		(width 0.0889)
		(layer "In2.Cu")
		(net "M_I_CPU0_RESET_N")
	)
	(arc
		(start 382.087882 -250.641612)
		(mid 382.274826 -250.591357)
		(end 382.46177 -250.641612)
		(width 0.0889)
		(layer "In2.Cu")
		(net "M_I_CPU0_RESET_N")
	)
	(arc
		(start 384.916172 -250.636786)
		(mid 385.09968 -250.591292)
		(end 385.281932 -250.641612)
		(width 0.0889)
		(layer "In2.Cu")
		(net "M_I_CPU0_RESET_N")
	)
	(arc
		(start 389.041894 -250.641612)
		(mid 389.32485 -250.717789)
		(end 389.607806 -250.641612)
		(width 0.0889)
		(layer "In2.Cu")
		(net "M_I_CPU0_RESET_N")
	)
	(arc
		(start 391.48766 -250.641612)
		(mid 391.669911 -250.591262)
		(end 391.85342 -250.636786)
		(width 0.0889)
		(layer "In2.Cu")
		(net "M_I_CPU0_RESET_N")
	)
	(arc
		(start 394.009118 -250.591066)
		(mid 394.498493 -250.656746)
		(end 394.953236 -250.84913)
		(width 0.0889)
		(layer "In2.Cu")
		(net "M_I_CPU0_RESET_N")
	)
	(arc
		(start 388.667752 -250.641612)
		(mid 388.850003 -250.591262)
		(end 389.033512 -250.636786)
		(width 0.0889)
		(layer "In2.Cu")
		(net "M_I_CPU0_RESET_N")
	)
	(arc
		(start 385.856226 -250.636786)
		(mid 386.039734 -250.591292)
		(end 386.221986 -250.641612)
		(width 0.0889)
		(layer "In2.Cu")
		(net "M_I_CPU0_RESET_N")
	)
	(arc
		(start 387.727698 -250.641612)
		(mid 387.909949 -250.591262)
		(end 388.093458 -250.636786)
		(width 0.0889)
		(layer "In2.Cu")
		(net "M_I_CPU0_RESET_N")
	)
	(arc
		(start 376.821954 -250.641612)
		(mid 377.10491 -250.717789)
		(end 377.387866 -250.641612)
		(width 0.0889)
		(layer "In2.Cu")
		(net "M_I_CPU0_RESET_N")
	)
	(arc
		(start 376.456194 -250.636786)
		(mid 376.639702 -250.591292)
		(end 376.821954 -250.641612)
		(width 0.0889)
		(layer "In2.Cu")
		(net "M_I_CPU0_RESET_N")
	)
	(arc
		(start 380.581916 -250.641612)
		(mid 380.864872 -250.717789)
		(end 381.147828 -250.641612)
		(width 0.0889)
		(layer "In2.Cu")
		(net "M_I_CPU0_RESET_N")
	)
	(arc
		(start 385.281932 -250.641612)
		(mid 385.564888 -250.717789)
		(end 385.847844 -250.641612)
		(width 0.0889)
		(layer "In2.Cu")
		(net "M_I_CPU0_RESET_N")
	)
	(arc
		(start 389.981948 -250.641612)
		(mid 390.264904 -250.717789)
		(end 390.54786 -250.641612)
		(width 0.0889)
		(layer "In2.Cu")
		(net "M_I_CPU0_RESET_N")
	)
	(arc
		(start 392.427714 -250.641612)
		(mid 392.609965 -250.591262)
		(end 392.793474 -250.636786)
		(width 0.0889)
		(layer "In2.Cu")
		(net "M_I_CPU0_RESET_N")
	)
	(arc
		(start 388.10184 -250.641612)
		(mid 388.384796 -250.717789)
		(end 388.667752 -250.641612)
		(width 0.0889)
		(layer "In2.Cu")
		(net "M_I_CPU0_RESET_N")
	)
	(arc
		(start 377.387866 -250.641612)
		(mid 377.57481 -250.591357)
		(end 377.761754 -250.641612)
		(width 0.0889)
		(layer "In2.Cu")
		(net "M_I_CPU0_RESET_N")
	)
	(arc
		(start 381.15621 -250.636786)
		(mid 381.339718 -250.591292)
		(end 381.52197 -250.641612)
		(width 0.0889)
		(layer "In2.Cu")
		(net "M_I_CPU0_RESET_N")
	)
	(arc
		(start 383.027682 -250.641612)
		(mid 383.209933 -250.591262)
		(end 383.393442 -250.636786)
		(width 0.0889)
		(layer "In2.Cu")
		(net "M_I_CPU0_RESET_N")
	)
	(arc
		(start 389.616188 -250.636786)
		(mid 389.799696 -250.591292)
		(end 389.981948 -250.641612)
		(width 0.0889)
		(layer "In2.Cu")
		(net "M_I_CPU0_RESET_N")
	)
	(arc
		(start 386.787898 -250.641612)
		(mid 386.974842 -250.591357)
		(end 387.161786 -250.641612)
		(width 0.0889)
		(layer "In2.Cu")
		(net "M_I_CPU0_RESET_N")
	)
	(arc
		(start 379.641862 -250.641612)
		(mid 379.924818 -250.717789)
		(end 380.207774 -250.641612)
		(width 0.0889)
		(layer "In2.Cu")
		(net "M_I_CPU0_RESET_N")
	)
	(arc
		(start 378.701808 -250.641612)
		(mid 378.984764 -250.717789)
		(end 379.26772 -250.641612)
		(width 0.0889)
		(layer "In2.Cu")
		(net "M_I_CPU0_RESET_N")
	)
	(arc
		(start 390.921748 -250.641612)
		(mid 391.204704 -250.717789)
		(end 391.48766 -250.641612)
		(width 0.0889)
		(layer "In2.Cu")
		(net "M_I_CPU0_RESET_N")
	)
	(arc
		(start 393.367768 -250.641612)
		(mid 393.458147 -250.603925)
		(end 393.55522 -250.591066)
		(width 0.0889)
		(layer "In2.Cu")
		(net "M_I_CPU0_RESET_N")
	)
	(segment
		(start 377.107958 -256.090166)
		(end 377.57481 -255.824228)
		(width 0.14732)
		(layer "F.Cu")
		(net "M_I_CPU0_CLK_DP<0>")
	)
	(segment
		(start 389.035036 -256.154174)
		(end 389.043418 -256.149348)
		(width 0.09525)
		(layer "In2.Cu")
		(net "M_I_CPU0_CLK_DP<0>")
	)
	(segment
		(start 417.682934 -256.356612)
		(end 418.019992 -256.69367)
		(width 0.16002)
		(layer "In2.Cu")
		(net "M_I_CPU0_CLK_DP<0>")
	)
	(segment
		(start 394.13561 -256.810002)
		(end 394.36548 -257.039872)
		(width 0.16002)
		(layer "In2.Cu")
		(net "M_I_CPU0_CLK_DP<0>")
	)
	(segment
		(start 403.468586 -255.929384)
		(end 403.895814 -256.356612)
		(width 0.16002)
		(layer "In2.Cu")
		(net "M_I_CPU0_CLK_DP<0>")
	)
	(segment
		(start 393.480798 -256.238248)
		(end 393.687554 -256.445004)
		(width 0.09525)
		(layer "In2.Cu")
		(net "M_I_CPU0_CLK_DP<0>")
	)
	(segment
		(start 416.035744 -257.212084)
		(end 416.485578 -257.212084)
		(width 0.16002)
		(layer "In2.Cu")
		(net "M_I_CPU0_CLK_DP<0>")
	)
	(segment
		(start 403.895814 -256.356612)
		(end 415.538666 -256.356612)
		(width 0.16002)
		(layer "In2.Cu")
		(net "M_I_CPU0_CLK_DP<0>")
	)
	(segment
		(start 418.789866 -256.69367)
		(end 419.126924 -256.356612)
		(width 0.16002)
		(layer "In2.Cu")
		(net "M_I_CPU0_CLK_DP<0>")
	)
	(segment
		(start 416.645598 -257.052064)
		(end 416.645598 -256.69367)
		(width 0.16002)
		(layer "In2.Cu")
		(net "M_I_CPU0_CLK_DP<0>")
	)
	(segment
		(start 418.019992 -256.69367)
		(end 418.019992 -257.052064)
		(width 0.16002)
		(layer "In2.Cu")
		(net "M_I_CPU0_CLK_DP<0>")
	)
	(segment
		(start 423.502836 -256.356612)
		(end 423.982896 -256.356612)
		(width 0.16002)
		(layer "In2.Cu")
		(net "M_I_CPU0_CLK_DP<0>")
	)
	(segment
		(start 426.058838 -255.47447)
		(end 426.058838 -254.12319)
		(width 0.16002)
		(layer "In2.Cu")
		(net "M_I_CPU0_CLK_DP<0>")
	)
	(segment
		(start 379.635004 -256.154174)
		(end 379.643386 -256.149348)
		(width 0.09525)
		(layer "In2.Cu")
		(net "M_I_CPU0_CLK_DP<0>")
	)
	(segment
		(start 394.035026 -256.793238)
		(end 394.118846 -256.793238)
		(width 0.09525)
		(layer "In2.Cu")
		(net "M_I_CPU0_CLK_DP<0>")
	)
	(segment
		(start 400.49831 -255.929384)
		(end 403.468586 -255.929384)
		(width 0.16002)
		(layer "In2.Cu")
		(net "M_I_CPU0_CLK_DP<0>")
	)
	(segment
		(start 388.094982 -256.154174)
		(end 388.103364 -256.149348)
		(width 0.09525)
		(layer "In2.Cu")
		(net "M_I_CPU0_CLK_DP<0>")
	)
	(segment
		(start 422.789096 -256.356612)
		(end 422.905936 -256.239772)
		(width 0.16002)
		(layer "In2.Cu")
		(net "M_I_CPU0_CLK_DP<0>")
	)
	(segment
		(start 383.394966 -256.154174)
		(end 383.403348 -256.149348)
		(width 0.09525)
		(layer "In2.Cu")
		(net "M_I_CPU0_CLK_DP<0>")
	)
	(segment
		(start 391.854944 -256.154174)
		(end 391.863326 -256.149348)
		(width 0.09525)
		(layer "In2.Cu")
		(net "M_I_CPU0_CLK_DP<0>")
	)
	(segment
		(start 418.629846 -257.212084)
		(end 418.789866 -257.052064)
		(width 0.16002)
		(layer "In2.Cu")
		(net "M_I_CPU0_CLK_DP<0>")
	)
	(segment
		(start 415.875724 -256.69367)
		(end 415.875724 -257.052064)
		(width 0.16002)
		(layer "In2.Cu")
		(net "M_I_CPU0_CLK_DP<0>")
	)
	(segment
		(start 425.176696 -256.356612)
		(end 426.058838 -255.47447)
		(width 0.16002)
		(layer "In2.Cu")
		(net "M_I_CPU0_CLK_DP<0>")
	)
	(segment
		(start 424.579796 -256.239772)
		(end 424.696636 -256.356612)
		(width 0.16002)
		(layer "In2.Cu")
		(net "M_I_CPU0_CLK_DP<0>")
	)
	(segment
		(start 392.400536 -256.135378)
		(end 392.424412 -256.149094)
		(width 0.09525)
		(layer "In2.Cu")
		(net "M_I_CPU0_CLK_DP<0>")
	)
	(segment
		(start 394.36548 -257.039872)
		(end 399.387822 -257.039872)
		(width 0.16002)
		(layer "In2.Cu")
		(net "M_I_CPU0_CLK_DP<0>")
	)
	(segment
		(start 418.789866 -257.052064)
		(end 418.789866 -256.69367)
		(width 0.16002)
		(layer "In2.Cu")
		(net "M_I_CPU0_CLK_DP<0>")
	)
	(segment
		(start 419.126924 -256.356612)
		(end 422.789096 -256.356612)
		(width 0.16002)
		(layer "In2.Cu")
		(net "M_I_CPU0_CLK_DP<0>")
	)
	(segment
		(start 378.69495 -256.154174)
		(end 378.703332 -256.149348)
		(width 0.09525)
		(layer "In2.Cu")
		(net "M_I_CPU0_CLK_DP<0>")
	)
	(segment
		(start 392.424412 -256.149094)
		(end 392.456416 -256.167636)
		(width 0.09525)
		(layer "In2.Cu")
		(net "M_I_CPU0_CLK_DP<0>")
	)
	(segment
		(start 389.606282 -256.149348)
		(end 389.614664 -256.154174)
		(width 0.09525)
		(layer "In2.Cu")
		(net "M_I_CPU0_CLK_DP<0>")
	)
	(segment
		(start 380.20625 -256.149348)
		(end 380.214632 -256.154174)
		(width 0.09525)
		(layer "In2.Cu")
		(net "M_I_CPU0_CLK_DP<0>")
	)
	(segment
		(start 424.696636 -256.356612)
		(end 425.176696 -256.356612)
		(width 0.16002)
		(layer "In2.Cu")
		(net "M_I_CPU0_CLK_DP<0>")
	)
	(segment
		(start 426.058838 -254.12319)
		(end 426.472096 -253.709932)
		(width 0.16002)
		(layer "In2.Cu")
		(net "M_I_CPU0_CLK_DP<0>")
	)
	(segment
		(start 384.33502 -256.154174)
		(end 384.343402 -256.149348)
		(width 0.09525)
		(layer "In2.Cu")
		(net "M_I_CPU0_CLK_DP<0>")
	)
	(segment
		(start 426.472096 -253.709932)
		(end 427.181264 -253.709932)
		(width 0.16002)
		(layer "In2.Cu")
		(net "M_I_CPU0_CLK_DP<0>")
	)
	(segment
		(start 394.118846 -256.793238)
		(end 394.13561 -256.810002)
		(width 0.09525)
		(layer "In2.Cu")
		(net "M_I_CPU0_CLK_DP<0>")
	)
	(segment
		(start 424.099736 -256.239772)
		(end 424.579796 -256.239772)
		(width 0.16002)
		(layer "In2.Cu")
		(net "M_I_CPU0_CLK_DP<0>")
	)
	(segment
		(start 385.84632 -256.149348)
		(end 385.854702 -256.154174)
		(width 0.09525)
		(layer "In2.Cu")
		(net "M_I_CPU0_CLK_DP<0>")
	)
	(segment
		(start 418.019992 -257.052064)
		(end 418.180012 -257.212084)
		(width 0.16002)
		(layer "In2.Cu")
		(net "M_I_CPU0_CLK_DP<0>")
	)
	(segment
		(start 423.982896 -256.356612)
		(end 424.099736 -256.239772)
		(width 0.16002)
		(layer "In2.Cu")
		(net "M_I_CPU0_CLK_DP<0>")
	)
	(segment
		(start 393.687554 -256.445004)
		(end 393.687046 -256.445258)
		(width 0.09525)
		(layer "In2.Cu")
		(net "M_I_CPU0_CLK_DP<0>")
	)
	(segment
		(start 423.385996 -256.239772)
		(end 423.502836 -256.356612)
		(width 0.16002)
		(layer "In2.Cu")
		(net "M_I_CPU0_CLK_DP<0>")
	)
	(segment
		(start 415.875724 -257.052064)
		(end 416.035744 -257.212084)
		(width 0.16002)
		(layer "In2.Cu")
		(net "M_I_CPU0_CLK_DP<0>")
	)
	(segment
		(start 422.905936 -256.239772)
		(end 423.385996 -256.239772)
		(width 0.16002)
		(layer "In2.Cu")
		(net "M_I_CPU0_CLK_DP<0>")
	)
	(segment
		(start 416.645598 -256.69367)
		(end 416.982656 -256.356612)
		(width 0.16002)
		(layer "In2.Cu")
		(net "M_I_CPU0_CLK_DP<0>")
	)
	(segment
		(start 415.538666 -256.356612)
		(end 415.875724 -256.69367)
		(width 0.16002)
		(layer "In2.Cu")
		(net "M_I_CPU0_CLK_DP<0>")
	)
	(segment
		(start 381.146304 -256.149348)
		(end 381.154686 -256.154174)
		(width 0.09525)
		(layer "In2.Cu")
		(net "M_I_CPU0_CLK_DP<0>")
	)
	(segment
		(start 399.387822 -257.039872)
		(end 400.49831 -255.929384)
		(width 0.16002)
		(layer "In2.Cu")
		(net "M_I_CPU0_CLK_DP<0>")
	)
	(segment
		(start 377.57481 -255.824228)
		(end 377.420886 -256.089658)
		(width 0.09525)
		(layer "In2.Cu")
		(net "M_I_CPU0_CLK_DP<0>")
	)
	(segment
		(start 377.420886 -256.089658)
		(end 377.444 -256.176272)
		(width 0.09525)
		(layer "In2.Cu")
		(net "M_I_CPU0_CLK_DP<0>")
	)
	(segment
		(start 384.906266 -256.149348)
		(end 384.914648 -256.154174)
		(width 0.09525)
		(layer "In2.Cu")
		(net "M_I_CPU0_CLK_DP<0>")
	)
	(segment
		(start 416.485578 -257.212084)
		(end 416.645598 -257.052064)
		(width 0.16002)
		(layer "In2.Cu")
		(net "M_I_CPU0_CLK_DP<0>")
	)
	(segment
		(start 393.687046 -256.445258)
		(end 394.035026 -256.793238)
		(width 0.09525)
		(layer "In2.Cu")
		(net "M_I_CPU0_CLK_DP<0>")
	)
	(segment
		(start 416.982656 -256.356612)
		(end 417.682934 -256.356612)
		(width 0.16002)
		(layer "In2.Cu")
		(net "M_I_CPU0_CLK_DP<0>")
	)
	(segment
		(start 427.181264 -253.709932)
		(end 427.456092 -253.435104)
		(width 0.16002)
		(layer "In2.Cu")
		(net "M_I_CPU0_CLK_DP<0>")
	)
	(segment
		(start 418.180012 -257.212084)
		(end 418.629846 -257.212084)
		(width 0.16002)
		(layer "In2.Cu")
		(net "M_I_CPU0_CLK_DP<0>")
	)
	(segment
		(start 393.328906 -256.128774)
		(end 393.364212 -256.149094)
		(width 0.09525)
		(layer "In2.Cu")
		(net "M_I_CPU0_CLK_DP<0>")
	)
	(arc
		(start 377.763278 -256.149348)
		(mid 378.04471 -256.073593)
		(end 378.326142 -256.149348)
		(width 0.09525)
		(layer "In2.Cu")
		(net "M_I_CPU0_CLK_DP<0>")
	)
	(arc
		(start 380.58344 -256.149348)
		(mid 380.864872 -256.073593)
		(end 381.146304 -256.149348)
		(width 0.09525)
		(layer "In2.Cu")
		(net "M_I_CPU0_CLK_DP<0>")
	)
	(arc
		(start 393.364212 -256.149094)
		(mid 393.425433 -256.189841)
		(end 393.480798 -256.238248)
		(width 0.09525)
		(layer "In2.Cu")
		(net "M_I_CPU0_CLK_DP<0>")
	)
	(arc
		(start 384.343402 -256.149348)
		(mid 384.624834 -256.073593)
		(end 384.906266 -256.149348)
		(width 0.09525)
		(layer "In2.Cu")
		(net "M_I_CPU0_CLK_DP<0>")
	)
	(arc
		(start 390.546336 -256.149348)
		(mid 390.734804 -256.200025)
		(end 390.923272 -256.149348)
		(width 0.09525)
		(layer "In2.Cu")
		(net "M_I_CPU0_CLK_DP<0>")
	)
	(arc
		(start 377.444 -256.176272)
		(mid 377.606651 -256.198532)
		(end 377.763278 -256.149348)
		(width 0.09525)
		(layer "In2.Cu")
		(net "M_I_CPU0_CLK_DP<0>")
	)
	(arc
		(start 382.463294 -256.149348)
		(mid 382.744726 -256.073593)
		(end 383.026158 -256.149348)
		(width 0.09525)
		(layer "In2.Cu")
		(net "M_I_CPU0_CLK_DP<0>")
	)
	(arc
		(start 385.854702 -256.154174)
		(mid 386.039734 -256.200088)
		(end 386.22351 -256.149348)
		(width 0.09525)
		(layer "In2.Cu")
		(net "M_I_CPU0_CLK_DP<0>")
	)
	(arc
		(start 386.786374 -256.149348)
		(mid 386.974842 -256.200025)
		(end 387.16331 -256.149348)
		(width 0.09525)
		(layer "In2.Cu")
		(net "M_I_CPU0_CLK_DP<0>")
	)
	(arc
		(start 378.703332 -256.149348)
		(mid 378.984764 -256.073593)
		(end 379.266196 -256.149348)
		(width 0.09525)
		(layer "In2.Cu")
		(net "M_I_CPU0_CLK_DP<0>")
	)
	(arc
		(start 383.966212 -256.149348)
		(mid 384.149987 -256.20012)
		(end 384.33502 -256.154174)
		(width 0.09525)
		(layer "In2.Cu")
		(net "M_I_CPU0_CLK_DP<0>")
	)
	(arc
		(start 391.863326 -256.149348)
		(mid 392.130152 -256.073783)
		(end 392.400536 -256.135378)
		(width 0.09525)
		(layer "In2.Cu")
		(net "M_I_CPU0_CLK_DP<0>")
	)
	(arc
		(start 386.22351 -256.149348)
		(mid 386.504942 -256.073593)
		(end 386.786374 -256.149348)
		(width 0.09525)
		(layer "In2.Cu")
		(net "M_I_CPU0_CLK_DP<0>")
	)
	(arc
		(start 379.643386 -256.149348)
		(mid 379.924818 -256.073593)
		(end 380.20625 -256.149348)
		(width 0.09525)
		(layer "In2.Cu")
		(net "M_I_CPU0_CLK_DP<0>")
	)
	(arc
		(start 391.486136 -256.149348)
		(mid 391.669911 -256.20012)
		(end 391.854944 -256.154174)
		(width 0.09525)
		(layer "In2.Cu")
		(net "M_I_CPU0_CLK_DP<0>")
	)
	(arc
		(start 380.214632 -256.154174)
		(mid 380.399664 -256.200088)
		(end 380.58344 -256.149348)
		(width 0.09525)
		(layer "In2.Cu")
		(net "M_I_CPU0_CLK_DP<0>")
	)
	(arc
		(start 387.726174 -256.149348)
		(mid 387.909949 -256.20012)
		(end 388.094982 -256.154174)
		(width 0.09525)
		(layer "In2.Cu")
		(net "M_I_CPU0_CLK_DP<0>")
	)
	(arc
		(start 388.666228 -256.149348)
		(mid 388.850003 -256.20012)
		(end 389.035036 -256.154174)
		(width 0.09525)
		(layer "In2.Cu")
		(net "M_I_CPU0_CLK_DP<0>")
	)
	(arc
		(start 387.16331 -256.149348)
		(mid 387.444742 -256.073593)
		(end 387.726174 -256.149348)
		(width 0.09525)
		(layer "In2.Cu")
		(net "M_I_CPU0_CLK_DP<0>")
	)
	(arc
		(start 392.456416 -256.167636)
		(mid 392.631208 -256.200566)
		(end 392.801602 -256.149602)
		(width 0.09525)
		(layer "In2.Cu")
		(net "M_I_CPU0_CLK_DP<0>")
	)
	(arc
		(start 379.266196 -256.149348)
		(mid 379.449971 -256.20012)
		(end 379.635004 -256.154174)
		(width 0.09525)
		(layer "In2.Cu")
		(net "M_I_CPU0_CLK_DP<0>")
	)
	(arc
		(start 385.283456 -256.149348)
		(mid 385.564888 -256.073593)
		(end 385.84632 -256.149348)
		(width 0.09525)
		(layer "In2.Cu")
		(net "M_I_CPU0_CLK_DP<0>")
	)
	(arc
		(start 383.026158 -256.149348)
		(mid 383.209933 -256.20012)
		(end 383.394966 -256.154174)
		(width 0.09525)
		(layer "In2.Cu")
		(net "M_I_CPU0_CLK_DP<0>")
	)
	(arc
		(start 389.983472 -256.149348)
		(mid 390.264904 -256.073593)
		(end 390.546336 -256.149348)
		(width 0.09525)
		(layer "In2.Cu")
		(net "M_I_CPU0_CLK_DP<0>")
	)
	(arc
		(start 389.043418 -256.149348)
		(mid 389.32485 -256.073593)
		(end 389.606282 -256.149348)
		(width 0.09525)
		(layer "In2.Cu")
		(net "M_I_CPU0_CLK_DP<0>")
	)
	(arc
		(start 388.103364 -256.149348)
		(mid 388.384796 -256.073593)
		(end 388.666228 -256.149348)
		(width 0.09525)
		(layer "In2.Cu")
		(net "M_I_CPU0_CLK_DP<0>")
	)
	(arc
		(start 383.403348 -256.149348)
		(mid 383.68478 -256.073593)
		(end 383.966212 -256.149348)
		(width 0.09525)
		(layer "In2.Cu")
		(net "M_I_CPU0_CLK_DP<0>")
	)
	(arc
		(start 382.086358 -256.149348)
		(mid 382.274826 -256.200025)
		(end 382.463294 -256.149348)
		(width 0.09525)
		(layer "In2.Cu")
		(net "M_I_CPU0_CLK_DP<0>")
	)
	(arc
		(start 381.154686 -256.154174)
		(mid 381.339718 -256.200088)
		(end 381.523494 -256.149348)
		(width 0.09525)
		(layer "In2.Cu")
		(net "M_I_CPU0_CLK_DP<0>")
	)
	(arc
		(start 378.326142 -256.149348)
		(mid 378.509917 -256.20012)
		(end 378.69495 -256.154174)
		(width 0.09525)
		(layer "In2.Cu")
		(net "M_I_CPU0_CLK_DP<0>")
	)
	(arc
		(start 384.914648 -256.154174)
		(mid 385.09968 -256.200088)
		(end 385.283456 -256.149348)
		(width 0.09525)
		(layer "In2.Cu")
		(net "M_I_CPU0_CLK_DP<0>")
	)
	(arc
		(start 392.801602 -256.149602)
		(mid 393.062654 -256.073355)
		(end 393.328906 -256.128774)
		(width 0.09525)
		(layer "In2.Cu")
		(net "M_I_CPU0_CLK_DP<0>")
	)
	(arc
		(start 390.923272 -256.149348)
		(mid 391.204704 -256.073593)
		(end 391.486136 -256.149348)
		(width 0.09525)
		(layer "In2.Cu")
		(net "M_I_CPU0_CLK_DP<0>")
	)
	(arc
		(start 381.523494 -256.149348)
		(mid 381.804926 -256.073593)
		(end 382.086358 -256.149348)
		(width 0.09525)
		(layer "In2.Cu")
		(net "M_I_CPU0_CLK_DP<0>")
	)
	(arc
		(start 389.614664 -256.154174)
		(mid 389.799696 -256.200088)
		(end 389.983472 -256.149348)
		(width 0.09525)
		(layer "In2.Cu")
		(net "M_I_CPU0_CLK_DP<0>")
	)
	(segment
		(start 376.638058 -256.900172)
		(end 377.10491 -256.634234)
		(width 0.14732)
		(layer "F.Cu")
		(net "M_I_CPU0_CLK_DN<0>")
	)
	(segment
		(start 415.573464 -256.818892)
		(end 415.573464 -257.177286)
		(width 0.16002)
		(layer "In2.Cu")
		(net "M_I_CPU0_CLK_DN<0>")
	)
	(segment
		(start 377.258834 -256.368804)
		(end 377.359672 -256.342134)
		(width 0.09525)
		(layer "In2.Cu")
		(net "M_I_CPU0_CLK_DN<0>")
	)
	(segment
		(start 393.905232 -256.924302)
		(end 393.905232 -257.007106)
		(width 0.09525)
		(layer "In2.Cu")
		(net "M_I_CPU0_CLK_DN<0>")
	)
	(segment
		(start 399.513044 -257.342132)
		(end 400.623532 -256.231644)
		(width 0.16002)
		(layer "In2.Cu")
		(net "M_I_CPU0_CLK_DN<0>")
	)
	(segment
		(start 416.6108 -257.514344)
		(end 416.947858 -257.177286)
		(width 0.16002)
		(layer "In2.Cu")
		(net "M_I_CPU0_CLK_DN<0>")
	)
	(segment
		(start 400.623532 -256.231644)
		(end 403.343364 -256.231644)
		(width 0.16002)
		(layer "In2.Cu")
		(net "M_I_CPU0_CLK_DN<0>")
	)
	(segment
		(start 393.350496 -256.36855)
		(end 393.350496 -256.368804)
		(width 0.09525)
		(layer "In2.Cu")
		(net "M_I_CPU0_CLK_DN<0>")
	)
	(segment
		(start 377.10491 -256.634234)
		(end 377.258834 -256.368804)
		(width 0.09525)
		(layer "In2.Cu")
		(net "M_I_CPU0_CLK_DN<0>")
	)
	(segment
		(start 417.717732 -257.177286)
		(end 418.05479 -257.514344)
		(width 0.16002)
		(layer "In2.Cu")
		(net "M_I_CPU0_CLK_DN<0>")
	)
	(segment
		(start 419.252146 -256.658872)
		(end 425.301918 -256.658872)
		(width 0.16002)
		(layer "In2.Cu")
		(net "M_I_CPU0_CLK_DN<0>")
	)
	(segment
		(start 418.755068 -257.514344)
		(end 419.092126 -257.177286)
		(width 0.16002)
		(layer "In2.Cu")
		(net "M_I_CPU0_CLK_DN<0>")
	)
	(segment
		(start 391.016236 -256.309114)
		(end 391.024618 -256.304288)
		(width 0.09525)
		(layer "In2.Cu")
		(net "M_I_CPU0_CLK_DN<0>")
	)
	(segment
		(start 416.947858 -256.818892)
		(end 417.107878 -256.658872)
		(width 0.16002)
		(layer "In2.Cu")
		(net "M_I_CPU0_CLK_DN<0>")
	)
	(segment
		(start 419.092126 -256.818892)
		(end 419.252146 -256.658872)
		(width 0.16002)
		(layer "In2.Cu")
		(net "M_I_CPU0_CLK_DN<0>")
	)
	(segment
		(start 393.921996 -257.02387)
		(end 394.240258 -257.342132)
		(width 0.16002)
		(layer "In2.Cu")
		(net "M_I_CPU0_CLK_DN<0>")
	)
	(segment
		(start 386.685028 -256.304288)
		(end 386.69341 -256.309114)
		(width 0.09525)
		(layer "In2.Cu")
		(net "M_I_CPU0_CLK_DN<0>")
	)
	(segment
		(start 419.092126 -257.177286)
		(end 419.092126 -256.818892)
		(width 0.16002)
		(layer "In2.Cu")
		(net "M_I_CPU0_CLK_DN<0>")
	)
	(segment
		(start 426.361098 -254.248412)
		(end 426.597318 -254.012192)
		(width 0.16002)
		(layer "In2.Cu")
		(net "M_I_CPU0_CLK_DN<0>")
	)
	(segment
		(start 381.985012 -256.304288)
		(end 381.993394 -256.309114)
		(width 0.09525)
		(layer "In2.Cu")
		(net "M_I_CPU0_CLK_DN<0>")
	)
	(segment
		(start 417.557712 -256.658872)
		(end 417.717732 -256.818892)
		(width 0.16002)
		(layer "In2.Cu")
		(net "M_I_CPU0_CLK_DN<0>")
	)
	(segment
		(start 393.905232 -257.007106)
		(end 393.921996 -257.02387)
		(width 0.09525)
		(layer "In2.Cu")
		(net "M_I_CPU0_CLK_DN<0>")
	)
	(segment
		(start 377.856242 -256.309114)
		(end 377.864624 -256.304288)
		(width 0.09525)
		(layer "In2.Cu")
		(net "M_I_CPU0_CLK_DN<0>")
	)
	(segment
		(start 403.343364 -256.231644)
		(end 403.770592 -256.658872)
		(width 0.16002)
		(layer "In2.Cu")
		(net "M_I_CPU0_CLK_DN<0>")
	)
	(segment
		(start 383.496312 -256.309114)
		(end 383.504694 -256.304288)
		(width 0.09525)
		(layer "In2.Cu")
		(net "M_I_CPU0_CLK_DN<0>")
	)
	(segment
		(start 388.196328 -256.309114)
		(end 388.20471 -256.304288)
		(width 0.09525)
		(layer "In2.Cu")
		(net "M_I_CPU0_CLK_DN<0>")
	)
	(segment
		(start 382.556258 -256.309114)
		(end 382.56464 -256.304288)
		(width 0.09525)
		(layer "In2.Cu")
		(net "M_I_CPU0_CLK_DN<0>")
	)
	(segment
		(start 415.910522 -257.514344)
		(end 416.6108 -257.514344)
		(width 0.16002)
		(layer "In2.Cu")
		(net "M_I_CPU0_CLK_DN<0>")
	)
	(segment
		(start 385.744974 -256.304288)
		(end 385.753356 -256.309114)
		(width 0.09525)
		(layer "In2.Cu")
		(net "M_I_CPU0_CLK_DN<0>")
	)
	(segment
		(start 393.350496 -256.368804)
		(end 393.556744 -256.57556)
		(width 0.09525)
		(layer "In2.Cu")
		(net "M_I_CPU0_CLK_DN<0>")
	)
	(segment
		(start 394.240258 -257.342132)
		(end 399.513044 -257.342132)
		(width 0.16002)
		(layer "In2.Cu")
		(net "M_I_CPU0_CLK_DN<0>")
	)
	(segment
		(start 417.107878 -256.658872)
		(end 417.557712 -256.658872)
		(width 0.16002)
		(layer "In2.Cu")
		(net "M_I_CPU0_CLK_DN<0>")
	)
	(segment
		(start 415.573464 -257.177286)
		(end 415.910522 -257.514344)
		(width 0.16002)
		(layer "In2.Cu")
		(net "M_I_CPU0_CLK_DN<0>")
	)
	(segment
		(start 415.413444 -256.658872)
		(end 415.573464 -256.818892)
		(width 0.16002)
		(layer "In2.Cu")
		(net "M_I_CPU0_CLK_DN<0>")
	)
	(segment
		(start 378.796296 -256.309114)
		(end 378.804678 -256.304288)
		(width 0.09525)
		(layer "In2.Cu")
		(net "M_I_CPU0_CLK_DN<0>")
	)
	(segment
		(start 425.301918 -256.658872)
		(end 426.361098 -255.599692)
		(width 0.16002)
		(layer "In2.Cu")
		(net "M_I_CPU0_CLK_DN<0>")
	)
	(segment
		(start 416.947858 -257.177286)
		(end 416.947858 -256.818892)
		(width 0.16002)
		(layer "In2.Cu")
		(net "M_I_CPU0_CLK_DN<0>")
	)
	(segment
		(start 390.44499 -256.304288)
		(end 390.453372 -256.309114)
		(width 0.09525)
		(layer "In2.Cu")
		(net "M_I_CPU0_CLK_DN<0>")
	)
	(segment
		(start 427.183296 -254.012192)
		(end 427.456092 -254.284988)
		(width 0.16002)
		(layer "In2.Cu")
		(net "M_I_CPU0_CLK_DN<0>")
	)
	(segment
		(start 393.240006 -256.290826)
		(end 393.27201 -256.309368)
		(width 0.09525)
		(layer "In2.Cu")
		(net "M_I_CPU0_CLK_DN<0>")
	)
	(segment
		(start 418.05479 -257.514344)
		(end 418.755068 -257.514344)
		(width 0.16002)
		(layer "In2.Cu")
		(net "M_I_CPU0_CLK_DN<0>")
	)
	(segment
		(start 392.331956 -256.309368)
		(end 392.365738 -256.328926)
		(width 0.09525)
		(layer "In2.Cu")
		(net "M_I_CPU0_CLK_DN<0>")
	)
	(segment
		(start 426.361098 -255.599692)
		(end 426.361098 -254.248412)
		(width 0.16002)
		(layer "In2.Cu")
		(net "M_I_CPU0_CLK_DN<0>")
	)
	(segment
		(start 417.717732 -256.818892)
		(end 417.717732 -257.177286)
		(width 0.16002)
		(layer "In2.Cu")
		(net "M_I_CPU0_CLK_DN<0>")
	)
	(segment
		(start 403.770592 -256.658872)
		(end 415.413444 -256.658872)
		(width 0.16002)
		(layer "In2.Cu")
		(net "M_I_CPU0_CLK_DN<0>")
	)
	(segment
		(start 393.556744 -256.57556)
		(end 393.905232 -256.924302)
		(width 0.09525)
		(layer "In2.Cu")
		(net "M_I_CPU0_CLK_DN<0>")
	)
	(segment
		(start 387.256274 -256.309114)
		(end 387.264656 -256.304288)
		(width 0.09525)
		(layer "In2.Cu")
		(net "M_I_CPU0_CLK_DN<0>")
	)
	(segment
		(start 381.044958 -256.304288)
		(end 381.05334 -256.309114)
		(width 0.09525)
		(layer "In2.Cu")
		(net "M_I_CPU0_CLK_DN<0>")
	)
	(segment
		(start 392.310112 -256.296922)
		(end 392.331956 -256.309368)
		(width 0.09525)
		(layer "In2.Cu")
		(net "M_I_CPU0_CLK_DN<0>")
	)
	(segment
		(start 426.597318 -254.012192)
		(end 427.183296 -254.012192)
		(width 0.16002)
		(layer "In2.Cu")
		(net "M_I_CPU0_CLK_DN<0>")
	)
	(arc
		(start 380.67615 -256.309114)
		(mid 380.859925 -256.258342)
		(end 381.044958 -256.304288)
		(width 0.09525)
		(layer "In2.Cu")
		(net "M_I_CPU0_CLK_DN<0>")
	)
	(arc
		(start 381.993394 -256.309114)
		(mid 382.274826 -256.384869)
		(end 382.556258 -256.309114)
		(width 0.09525)
		(layer "In2.Cu")
		(net "M_I_CPU0_CLK_DN<0>")
	)
	(arc
		(start 388.20471 -256.304288)
		(mid 388.389742 -256.258374)
		(end 388.573518 -256.309114)
		(width 0.09525)
		(layer "In2.Cu")
		(net "M_I_CPU0_CLK_DN<0>")
	)
	(arc
		(start 384.813302 -256.309114)
		(mid 385.094734 -256.384869)
		(end 385.376166 -256.309114)
		(width 0.09525)
		(layer "In2.Cu")
		(net "M_I_CPU0_CLK_DN<0>")
	)
	(arc
		(start 382.56464 -256.304288)
		(mid 382.749672 -256.258374)
		(end 382.933448 -256.309114)
		(width 0.09525)
		(layer "In2.Cu")
		(net "M_I_CPU0_CLK_DN<0>")
	)
	(arc
		(start 383.504694 -256.304288)
		(mid 383.689726 -256.258374)
		(end 383.873502 -256.309114)
		(width 0.09525)
		(layer "In2.Cu")
		(net "M_I_CPU0_CLK_DN<0>")
	)
	(arc
		(start 379.173486 -256.309114)
		(mid 379.454918 -256.384869)
		(end 379.73635 -256.309114)
		(width 0.09525)
		(layer "In2.Cu")
		(net "M_I_CPU0_CLK_DN<0>")
	)
	(arc
		(start 385.376166 -256.309114)
		(mid 385.559941 -256.258342)
		(end 385.744974 -256.304288)
		(width 0.09525)
		(layer "In2.Cu")
		(net "M_I_CPU0_CLK_DN<0>")
	)
	(arc
		(start 377.379484 -256.350008)
		(mid 377.622448 -256.382995)
		(end 377.856242 -256.309114)
		(width 0.09525)
		(layer "In2.Cu")
		(net "M_I_CPU0_CLK_DN<0>")
	)
	(arc
		(start 392.365738 -256.328926)
		(mid 392.632806 -256.385231)
		(end 392.89482 -256.30886)
		(width 0.09525)
		(layer "In2.Cu")
		(net "M_I_CPU0_CLK_DN<0>")
	)
	(arc
		(start 389.136382 -256.309114)
		(mid 389.32485 -256.258437)
		(end 389.513318 -256.309114)
		(width 0.09525)
		(layer "In2.Cu")
		(net "M_I_CPU0_CLK_DN<0>")
	)
	(arc
		(start 378.233432 -256.309114)
		(mid 378.514864 -256.384869)
		(end 378.796296 -256.309114)
		(width 0.09525)
		(layer "In2.Cu")
		(net "M_I_CPU0_CLK_DN<0>")
	)
	(arc
		(start 383.873502 -256.309114)
		(mid 384.154934 -256.384869)
		(end 384.436366 -256.309114)
		(width 0.09525)
		(layer "In2.Cu")
		(net "M_I_CPU0_CLK_DN<0>")
	)
	(arc
		(start 384.436366 -256.309114)
		(mid 384.624834 -256.258437)
		(end 384.813302 -256.309114)
		(width 0.09525)
		(layer "In2.Cu")
		(net "M_I_CPU0_CLK_DN<0>")
	)
	(arc
		(start 391.393426 -256.309114)
		(mid 391.674858 -256.384869)
		(end 391.95629 -256.309114)
		(width 0.09525)
		(layer "In2.Cu")
		(net "M_I_CPU0_CLK_DN<0>")
	)
	(arc
		(start 388.573518 -256.309114)
		(mid 388.85495 -256.384869)
		(end 389.136382 -256.309114)
		(width 0.09525)
		(layer "In2.Cu")
		(net "M_I_CPU0_CLK_DN<0>")
	)
	(arc
		(start 390.453372 -256.309114)
		(mid 390.734804 -256.384869)
		(end 391.016236 -256.309114)
		(width 0.09525)
		(layer "In2.Cu")
		(net "M_I_CPU0_CLK_DN<0>")
	)
	(arc
		(start 380.113286 -256.309114)
		(mid 380.394718 -256.384869)
		(end 380.67615 -256.309114)
		(width 0.09525)
		(layer "In2.Cu")
		(net "M_I_CPU0_CLK_DN<0>")
	)
	(arc
		(start 381.05334 -256.309114)
		(mid 381.334772 -256.384869)
		(end 381.616204 -256.309114)
		(width 0.09525)
		(layer "In2.Cu")
		(net "M_I_CPU0_CLK_DN<0>")
	)
	(arc
		(start 389.513318 -256.309114)
		(mid 389.79475 -256.384869)
		(end 390.076182 -256.309114)
		(width 0.09525)
		(layer "In2.Cu")
		(net "M_I_CPU0_CLK_DN<0>")
	)
	(arc
		(start 381.616204 -256.309114)
		(mid 381.799979 -256.258342)
		(end 381.985012 -256.304288)
		(width 0.09525)
		(layer "In2.Cu")
		(net "M_I_CPU0_CLK_DN<0>")
	)
	(arc
		(start 382.933448 -256.309114)
		(mid 383.21488 -256.384869)
		(end 383.496312 -256.309114)
		(width 0.09525)
		(layer "In2.Cu")
		(net "M_I_CPU0_CLK_DN<0>")
	)
	(arc
		(start 385.753356 -256.309114)
		(mid 386.034788 -256.384869)
		(end 386.31622 -256.309114)
		(width 0.09525)
		(layer "In2.Cu")
		(net "M_I_CPU0_CLK_DN<0>")
	)
	(arc
		(start 391.95629 -256.309114)
		(mid 392.131664 -256.258784)
		(end 392.310112 -256.296922)
		(width 0.09525)
		(layer "In2.Cu")
		(net "M_I_CPU0_CLK_DN<0>")
	)
	(arc
		(start 392.89482 -256.30886)
		(mid 393.065217 -256.257961)
		(end 393.240006 -256.290826)
		(width 0.09525)
		(layer "In2.Cu")
		(net "M_I_CPU0_CLK_DN<0>")
	)
	(arc
		(start 386.31622 -256.309114)
		(mid 386.499995 -256.258342)
		(end 386.685028 -256.304288)
		(width 0.09525)
		(layer "In2.Cu")
		(net "M_I_CPU0_CLK_DN<0>")
	)
	(arc
		(start 379.73635 -256.309114)
		(mid 379.924818 -256.258437)
		(end 380.113286 -256.309114)
		(width 0.09525)
		(layer "In2.Cu")
		(net "M_I_CPU0_CLK_DN<0>")
	)
	(arc
		(start 391.024618 -256.304288)
		(mid 391.20965 -256.258374)
		(end 391.393426 -256.309114)
		(width 0.09525)
		(layer "In2.Cu")
		(net "M_I_CPU0_CLK_DN<0>")
	)
	(arc
		(start 387.633464 -256.309114)
		(mid 387.914896 -256.384869)
		(end 388.196328 -256.309114)
		(width 0.09525)
		(layer "In2.Cu")
		(net "M_I_CPU0_CLK_DN<0>")
	)
	(arc
		(start 393.27201 -256.309368)
		(mid 393.313206 -256.336371)
		(end 393.350496 -256.36855)
		(width 0.09525)
		(layer "In2.Cu")
		(net "M_I_CPU0_CLK_DN<0>")
	)
	(arc
		(start 390.076182 -256.309114)
		(mid 390.259957 -256.258342)
		(end 390.44499 -256.304288)
		(width 0.09525)
		(layer "In2.Cu")
		(net "M_I_CPU0_CLK_DN<0>")
	)
	(arc
		(start 377.864624 -256.304288)
		(mid 378.049656 -256.258374)
		(end 378.233432 -256.309114)
		(width 0.09525)
		(layer "In2.Cu")
		(net "M_I_CPU0_CLK_DN<0>")
	)
	(arc
		(start 386.69341 -256.309114)
		(mid 386.974842 -256.384869)
		(end 387.256274 -256.309114)
		(width 0.09525)
		(layer "In2.Cu")
		(net "M_I_CPU0_CLK_DN<0>")
	)
	(arc
		(start 387.264656 -256.304288)
		(mid 387.449688 -256.258374)
		(end 387.633464 -256.309114)
		(width 0.09525)
		(layer "In2.Cu")
		(net "M_I_CPU0_CLK_DN<0>")
	)
	(arc
		(start 377.359672 -256.342134)
		(mid 377.36954 -256.346165)
		(end 377.379484 -256.350008)
		(width 0.09525)
		(layer "In2.Cu")
		(net "M_I_CPU0_CLK_DN<0>")
	)
	(arc
		(start 378.804678 -256.304288)
		(mid 378.98971 -256.258374)
		(end 379.173486 -256.309114)
		(width 0.09525)
		(layer "In2.Cu")
		(net "M_I_CPU0_CLK_DN<0>")
	)
	(segment
		(start 375.698004 -250.420124)
		(end 376.164856 -250.154186)
		(width 0.10668)
		(layer "F.Cu")
		(net "M_I_CPU0_ALERT_R_N")
	)
	(segment
		(start 427.638464 -244.49405)
		(end 427.654466 -244.510052)
		(width 0.11684)
		(layer "In2.Cu")
		(net "M_I_CPU0_ALERT_R_N")
	)
	(segment
		(start 386.683504 -250.481592)
		(end 386.691886 -250.476766)
		(width 0.0889)
		(layer "In2.Cu")
		(net "M_I_CPU0_ALERT_R_N")
	)
	(segment
		(start 385.74345 -250.481592)
		(end 385.751832 -250.476766)
		(width 0.0889)
		(layer "In2.Cu")
		(net "M_I_CPU0_ALERT_R_N")
	)
	(segment
		(start 381.983488 -250.481592)
		(end 381.99187 -250.476766)
		(width 0.0889)
		(layer "In2.Cu")
		(net "M_I_CPU0_ALERT_R_N")
	)
	(segment
		(start 382.557782 -250.476766)
		(end 382.566164 -250.481592)
		(width 0.0889)
		(layer "In2.Cu")
		(net "M_I_CPU0_ALERT_R_N")
	)
	(segment
		(start 388.197852 -250.476766)
		(end 388.206234 -250.481592)
		(width 0.0889)
		(layer "In2.Cu")
		(net "M_I_CPU0_ALERT_R_N")
	)
	(segment
		(start 427.654466 -244.510052)
		(end 429.734218 -244.510052)
		(width 0.11684)
		(layer "In2.Cu")
		(net "M_I_CPU0_ALERT_R_N")
	)
	(segment
		(start 421.607234 -246.210074)
		(end 423.307256 -244.510052)
		(width 0.11684)
		(layer "In2.Cu")
		(net "M_I_CPU0_ALERT_R_N")
	)
	(segment
		(start 398.239996 -249.885962)
		(end 405.727154 -249.885962)
		(width 0.11684)
		(layer "In2.Cu")
		(net "M_I_CPU0_ALERT_R_N")
	)
	(segment
		(start 429.734218 -244.510052)
		(end 430.15916 -244.08511)
		(width 0.11684)
		(layer "In2.Cu")
		(net "M_I_CPU0_ALERT_R_N")
	)
	(segment
		(start 378.79782 -250.476766)
		(end 378.806202 -250.481592)
		(width 0.0889)
		(layer "In2.Cu")
		(net "M_I_CPU0_ALERT_R_N")
	)
	(segment
		(start 394.912342 -250.395232)
		(end 394.912596 -250.394978)
		(width 0.0889)
		(layer "In2.Cu")
		(net "M_I_CPU0_ALERT_R_N")
	)
	(segment
		(start 391.01776 -250.476766)
		(end 391.026142 -250.481592)
		(width 0.0889)
		(layer "In2.Cu")
		(net "M_I_CPU0_ALERT_R_N")
	)
	(segment
		(start 377.857766 -250.476766)
		(end 377.866148 -250.481592)
		(width 0.0889)
		(layer "In2.Cu")
		(net "M_I_CPU0_ALERT_R_N")
	)
	(segment
		(start 376.010678 -250.419616)
		(end 376.03303 -250.502928)
		(width 0.0889)
		(layer "In2.Cu")
		(net "M_I_CPU0_ALERT_R_N")
	)
	(segment
		(start 392.897868 -250.476766)
		(end 392.90625 -250.481592)
		(width 0.0889)
		(layer "In2.Cu")
		(net "M_I_CPU0_ALERT_R_N")
	)
	(segment
		(start 427.257718 -244.510052)
		(end 427.27372 -244.49405)
		(width 0.11684)
		(layer "In2.Cu")
		(net "M_I_CPU0_ALERT_R_N")
	)
	(segment
		(start 411.473396 -246.210074)
		(end 421.607234 -246.210074)
		(width 0.11684)
		(layer "In2.Cu")
		(net "M_I_CPU0_ALERT_R_N")
	)
	(segment
		(start 376.164856 -250.154186)
		(end 376.010678 -250.419616)
		(width 0.0889)
		(layer "In2.Cu")
		(net "M_I_CPU0_ALERT_R_N")
	)
	(segment
		(start 405.727154 -249.885962)
		(end 406.198578 -250.357386)
		(width 0.11684)
		(layer "In2.Cu")
		(net "M_I_CPU0_ALERT_R_N")
	)
	(segment
		(start 381.043434 -250.481592)
		(end 381.051816 -250.476766)
		(width 0.0889)
		(layer "In2.Cu")
		(net "M_I_CPU0_ALERT_R_N")
	)
	(segment
		(start 394.912596 -250.394978)
		(end 397.73098 -250.394978)
		(width 0.11684)
		(layer "In2.Cu")
		(net "M_I_CPU0_ALERT_R_N")
	)
	(segment
		(start 387.257798 -250.476766)
		(end 387.26618 -250.481592)
		(width 0.0889)
		(layer "In2.Cu")
		(net "M_I_CPU0_ALERT_R_N")
	)
	(segment
		(start 391.957814 -250.476766)
		(end 391.966196 -250.481592)
		(width 0.0889)
		(layer "In2.Cu")
		(net "M_I_CPU0_ALERT_R_N")
	)
	(segment
		(start 406.198578 -250.357386)
		(end 407.326084 -250.357386)
		(width 0.11684)
		(layer "In2.Cu")
		(net "M_I_CPU0_ALERT_R_N")
	)
	(segment
		(start 383.497836 -250.476766)
		(end 383.506218 -250.481592)
		(width 0.0889)
		(layer "In2.Cu")
		(net "M_I_CPU0_ALERT_R_N")
	)
	(segment
		(start 376.343418 -250.481592)
		(end 376.3518 -250.476766)
		(width 0.0889)
		(layer "In2.Cu")
		(net "M_I_CPU0_ALERT_R_N")
	)
	(segment
		(start 423.307256 -244.510052)
		(end 427.257718 -244.510052)
		(width 0.11684)
		(layer "In2.Cu")
		(net "M_I_CPU0_ALERT_R_N")
	)
	(segment
		(start 393.574778 -250.395232)
		(end 394.912342 -250.395232)
		(width 0.0889)
		(layer "In2.Cu")
		(net "M_I_CPU0_ALERT_R_N")
	)
	(segment
		(start 407.326084 -250.357386)
		(end 411.473396 -246.210074)
		(width 0.11684)
		(layer "In2.Cu")
		(net "M_I_CPU0_ALERT_R_N")
	)
	(segment
		(start 377.283472 -250.481592)
		(end 377.291854 -250.476766)
		(width 0.0889)
		(layer "In2.Cu")
		(net "M_I_CPU0_ALERT_R_N")
	)
	(segment
		(start 397.73098 -250.394978)
		(end 398.239996 -249.885962)
		(width 0.11684)
		(layer "In2.Cu")
		(net "M_I_CPU0_ALERT_R_N")
	)
	(segment
		(start 427.27372 -244.49405)
		(end 427.638464 -244.49405)
		(width 0.11684)
		(layer "In2.Cu")
		(net "M_I_CPU0_ALERT_R_N")
	)
	(segment
		(start 390.443466 -250.481592)
		(end 390.451848 -250.476766)
		(width 0.0889)
		(layer "In2.Cu")
		(net "M_I_CPU0_ALERT_R_N")
	)
	(arc
		(start 391.391902 -250.476766)
		(mid 391.674858 -250.400589)
		(end 391.957814 -250.476766)
		(width 0.0889)
		(layer "In2.Cu")
		(net "M_I_CPU0_ALERT_R_N")
	)
	(arc
		(start 380.677674 -250.476766)
		(mid 380.859925 -250.527116)
		(end 381.043434 -250.481592)
		(width 0.0889)
		(layer "In2.Cu")
		(net "M_I_CPU0_ALERT_R_N")
	)
	(arc
		(start 378.806202 -250.481592)
		(mid 378.98971 -250.527086)
		(end 379.171962 -250.476766)
		(width 0.0889)
		(layer "In2.Cu")
		(net "M_I_CPU0_ALERT_R_N")
	)
	(arc
		(start 376.03303 -250.502928)
		(mid 376.19054 -250.526126)
		(end 376.343418 -250.481592)
		(width 0.0889)
		(layer "In2.Cu")
		(net "M_I_CPU0_ALERT_R_N")
	)
	(arc
		(start 389.511794 -250.476766)
		(mid 389.79475 -250.400589)
		(end 390.077706 -250.476766)
		(width 0.0889)
		(layer "In2.Cu")
		(net "M_I_CPU0_ALERT_R_N")
	)
	(arc
		(start 377.291854 -250.476766)
		(mid 377.57481 -250.400589)
		(end 377.857766 -250.476766)
		(width 0.0889)
		(layer "In2.Cu")
		(net "M_I_CPU0_ALERT_R_N")
	)
	(arc
		(start 380.111762 -250.476766)
		(mid 380.394718 -250.400589)
		(end 380.677674 -250.476766)
		(width 0.0889)
		(layer "In2.Cu")
		(net "M_I_CPU0_ALERT_R_N")
	)
	(arc
		(start 378.231908 -250.476766)
		(mid 378.514864 -250.400589)
		(end 378.79782 -250.476766)
		(width 0.0889)
		(layer "In2.Cu")
		(net "M_I_CPU0_ALERT_R_N")
	)
	(arc
		(start 389.137906 -250.476766)
		(mid 389.32485 -250.527021)
		(end 389.511794 -250.476766)
		(width 0.0889)
		(layer "In2.Cu")
		(net "M_I_CPU0_ALERT_R_N")
	)
	(arc
		(start 383.871978 -250.476766)
		(mid 384.154934 -250.400589)
		(end 384.43789 -250.476766)
		(width 0.0889)
		(layer "In2.Cu")
		(net "M_I_CPU0_ALERT_R_N")
	)
	(arc
		(start 392.331956 -250.476766)
		(mid 392.614912 -250.400589)
		(end 392.897868 -250.476766)
		(width 0.0889)
		(layer "In2.Cu")
		(net "M_I_CPU0_ALERT_R_N")
	)
	(arc
		(start 382.566164 -250.481592)
		(mid 382.749672 -250.527086)
		(end 382.931924 -250.476766)
		(width 0.0889)
		(layer "In2.Cu")
		(net "M_I_CPU0_ALERT_R_N")
	)
	(arc
		(start 381.617728 -250.476766)
		(mid 381.799979 -250.527116)
		(end 381.983488 -250.481592)
		(width 0.0889)
		(layer "In2.Cu")
		(net "M_I_CPU0_ALERT_R_N")
	)
	(arc
		(start 387.26618 -250.481592)
		(mid 387.449688 -250.527086)
		(end 387.63194 -250.476766)
		(width 0.0889)
		(layer "In2.Cu")
		(net "M_I_CPU0_ALERT_R_N")
	)
	(arc
		(start 376.917712 -250.476766)
		(mid 377.099963 -250.527116)
		(end 377.283472 -250.481592)
		(width 0.0889)
		(layer "In2.Cu")
		(net "M_I_CPU0_ALERT_R_N")
	)
	(arc
		(start 381.051816 -250.476766)
		(mid 381.334772 -250.400589)
		(end 381.617728 -250.476766)
		(width 0.0889)
		(layer "In2.Cu")
		(net "M_I_CPU0_ALERT_R_N")
	)
	(arc
		(start 386.317744 -250.476766)
		(mid 386.499995 -250.527116)
		(end 386.683504 -250.481592)
		(width 0.0889)
		(layer "In2.Cu")
		(net "M_I_CPU0_ALERT_R_N")
	)
	(arc
		(start 377.866148 -250.481592)
		(mid 378.049656 -250.527086)
		(end 378.231908 -250.476766)
		(width 0.0889)
		(layer "In2.Cu")
		(net "M_I_CPU0_ALERT_R_N")
	)
	(arc
		(start 384.811778 -250.476766)
		(mid 385.094734 -250.400589)
		(end 385.37769 -250.476766)
		(width 0.0889)
		(layer "In2.Cu")
		(net "M_I_CPU0_ALERT_R_N")
	)
	(arc
		(start 383.506218 -250.481592)
		(mid 383.689726 -250.527086)
		(end 383.871978 -250.476766)
		(width 0.0889)
		(layer "In2.Cu")
		(net "M_I_CPU0_ALERT_R_N")
	)
	(arc
		(start 385.37769 -250.476766)
		(mid 385.559941 -250.527116)
		(end 385.74345 -250.481592)
		(width 0.0889)
		(layer "In2.Cu")
		(net "M_I_CPU0_ALERT_R_N")
	)
	(arc
		(start 382.931924 -250.476766)
		(mid 383.21488 -250.400589)
		(end 383.497836 -250.476766)
		(width 0.0889)
		(layer "In2.Cu")
		(net "M_I_CPU0_ALERT_R_N")
	)
	(arc
		(start 384.43789 -250.476766)
		(mid 384.624834 -250.527021)
		(end 384.811778 -250.476766)
		(width 0.0889)
		(layer "In2.Cu")
		(net "M_I_CPU0_ALERT_R_N")
	)
	(arc
		(start 388.571994 -250.476766)
		(mid 388.85495 -250.400589)
		(end 389.137906 -250.476766)
		(width 0.0889)
		(layer "In2.Cu")
		(net "M_I_CPU0_ALERT_R_N")
	)
	(arc
		(start 379.737874 -250.476766)
		(mid 379.924818 -250.527021)
		(end 380.111762 -250.476766)
		(width 0.0889)
		(layer "In2.Cu")
		(net "M_I_CPU0_ALERT_R_N")
	)
	(arc
		(start 386.691886 -250.476766)
		(mid 386.974842 -250.400589)
		(end 387.257798 -250.476766)
		(width 0.0889)
		(layer "In2.Cu")
		(net "M_I_CPU0_ALERT_R_N")
	)
	(arc
		(start 392.90625 -250.481592)
		(mid 393.089758 -250.527086)
		(end 393.27201 -250.476766)
		(width 0.0889)
		(layer "In2.Cu")
		(net "M_I_CPU0_ALERT_R_N")
	)
	(arc
		(start 376.3518 -250.476766)
		(mid 376.634756 -250.400589)
		(end 376.917712 -250.476766)
		(width 0.0889)
		(layer "In2.Cu")
		(net "M_I_CPU0_ALERT_R_N")
	)
	(arc
		(start 390.451848 -250.476766)
		(mid 390.734804 -250.400589)
		(end 391.01776 -250.476766)
		(width 0.0889)
		(layer "In2.Cu")
		(net "M_I_CPU0_ALERT_R_N")
	)
	(arc
		(start 381.99187 -250.476766)
		(mid 382.274826 -250.400589)
		(end 382.557782 -250.476766)
		(width 0.0889)
		(layer "In2.Cu")
		(net "M_I_CPU0_ALERT_R_N")
	)
	(arc
		(start 393.27201 -250.476766)
		(mid 393.418002 -250.41598)
		(end 393.574778 -250.395232)
		(width 0.0889)
		(layer "In2.Cu")
		(net "M_I_CPU0_ALERT_R_N")
	)
	(arc
		(start 387.63194 -250.476766)
		(mid 387.914896 -250.400589)
		(end 388.197852 -250.476766)
		(width 0.0889)
		(layer "In2.Cu")
		(net "M_I_CPU0_ALERT_R_N")
	)
	(arc
		(start 390.077706 -250.476766)
		(mid 390.259957 -250.527116)
		(end 390.443466 -250.481592)
		(width 0.0889)
		(layer "In2.Cu")
		(net "M_I_CPU0_ALERT_R_N")
	)
	(arc
		(start 391.966196 -250.481592)
		(mid 392.149704 -250.527086)
		(end 392.331956 -250.476766)
		(width 0.0889)
		(layer "In2.Cu")
		(net "M_I_CPU0_ALERT_R_N")
	)
	(arc
		(start 379.171962 -250.476766)
		(mid 379.454918 -250.400589)
		(end 379.737874 -250.476766)
		(width 0.0889)
		(layer "In2.Cu")
		(net "M_I_CPU0_ALERT_R_N")
	)
	(arc
		(start 385.751832 -250.476766)
		(mid 386.034788 -250.400589)
		(end 386.317744 -250.476766)
		(width 0.0889)
		(layer "In2.Cu")
		(net "M_I_CPU0_ALERT_R_N")
	)
	(arc
		(start 391.026142 -250.481592)
		(mid 391.20965 -250.527086)
		(end 391.391902 -250.476766)
		(width 0.0889)
		(layer "In2.Cu")
		(net "M_I_CPU0_ALERT_R_N")
	)
	(arc
		(start 388.206234 -250.481592)
		(mid 388.389742 -250.527086)
		(end 388.571994 -250.476766)
		(width 0.0889)
		(layer "In2.Cu")
		(net "M_I_CPU0_ALERT_R_N")
	)
	(via
		(at 431.55616 -244.08511)
		(size 0.4826)
		(drill 0.254)
		(layers "F.Cu" "B.Cu")
		(net "M_I_CPU0_ALERT_N")
	)
	(segment
		(start 430.95926 -244.08511)
		(end 431.55616 -244.08511)
		(width 0.10668)
		(layer "B.Cu")
		(net "M_I_CPU0_ALERT_N")
	)
	(segment
		(start 135.577834 -267.340334)
		(end 136.044686 -267.606272)
		(width 0.10668)
		(layer "F.Cu")
		(net "M_H_CPU1_SB_RSP<0>")
	)
	(segment
		(start 147.55368 -266.570714)
		(end 147.22983 -266.894564)
		(width 0.0889)
		(layer "In13.Cu")
		(net "M_H_CPU1_SB_RSP<0>")
	)
	(segment
		(start 171.697142 -270.86052)
		(end 169.644568 -270.010382)
		(width 0.11684)
		(layer "In13.Cu")
		(net "M_H_CPU1_SB_RSP<0>")
	)
	(segment
		(start 144.334484 -267.939012)
		(end 144.316196 -267.928598)
		(width 0.0889)
		(layer "In13.Cu")
		(net "M_H_CPU1_SB_RSP<0>")
	)
	(segment
		(start 143.386048 -267.933678)
		(end 143.377666 -267.928852)
		(width 0.0889)
		(layer "In13.Cu")
		(net "M_H_CPU1_SB_RSP<0>")
	)
	(segment
		(start 173.720506 -270.435324)
		(end 172.694092 -270.86052)
		(width 0.11684)
		(layer "In13.Cu")
		(net "M_H_CPU1_SB_RSP<0>")
	)
	(segment
		(start 139.617704 -267.928852)
		(end 139.608052 -267.923264)
		(width 0.0889)
		(layer "In13.Cu")
		(net "M_H_CPU1_SB_RSP<0>")
	)
	(segment
		(start 140.56614 -267.933678)
		(end 140.557758 -267.928852)
		(width 0.0889)
		(layer "In13.Cu")
		(net "M_H_CPU1_SB_RSP<0>")
	)
	(segment
		(start 144.71269 -267.915136)
		(end 144.689322 -267.928852)
		(width 0.0889)
		(layer "In13.Cu")
		(net "M_H_CPU1_SB_RSP<0>")
	)
	(segment
		(start 139.626086 -267.933678)
		(end 139.617704 -267.928852)
		(width 0.0889)
		(layer "In13.Cu")
		(net "M_H_CPU1_SB_RSP<0>")
	)
	(segment
		(start 135.895842 -267.862558)
		(end 136.044686 -267.606272)
		(width 0.0889)
		(layer "In13.Cu")
		(net "M_H_CPU1_SB_RSP<0>")
	)
	(segment
		(start 146.66468 -266.894564)
		(end 145.630646 -267.928598)
		(width 0.0889)
		(layer "In13.Cu")
		(net "M_H_CPU1_SB_RSP<0>")
	)
	(segment
		(start 147.22983 -266.894564)
		(end 146.66468 -266.894564)
		(width 0.0889)
		(layer "In13.Cu")
		(net "M_H_CPU1_SB_RSP<0>")
	)
	(segment
		(start 176.072038 -270.435324)
		(end 173.720506 -270.435324)
		(width 0.11684)
		(layer "In13.Cu")
		(net "M_H_CPU1_SB_RSP<0>")
	)
	(segment
		(start 136.23925 -267.917168)
		(end 136.228582 -267.923264)
		(width 0.0889)
		(layer "In13.Cu")
		(net "M_H_CPU1_SB_RSP<0>")
	)
	(segment
		(start 135.91921 -267.950442)
		(end 135.895842 -267.862558)
		(width 0.0889)
		(layer "In13.Cu")
		(net "M_H_CPU1_SB_RSP<0>")
	)
	(segment
		(start 145.630646 -267.928598)
		(end 145.603214 -267.944346)
		(width 0.0889)
		(layer "In13.Cu")
		(net "M_H_CPU1_SB_RSP<0>")
	)
	(segment
		(start 147.77339 -266.570714)
		(end 147.55368 -266.570714)
		(width 0.0889)
		(layer "In13.Cu")
		(net "M_H_CPU1_SB_RSP<0>")
	)
	(segment
		(start 165.217348 -270.86052)
		(end 164.538914 -270.86052)
		(width 0.11684)
		(layer "In13.Cu")
		(net "M_H_CPU1_SB_RSP<0>")
	)
	(segment
		(start 164.538914 -270.86052)
		(end 160.249108 -266.570714)
		(width 0.11684)
		(layer "In13.Cu")
		(net "M_H_CPU1_SB_RSP<0>")
	)
	(segment
		(start 142.811754 -267.928852)
		(end 142.803372 -267.933678)
		(width 0.0889)
		(layer "In13.Cu")
		(net "M_H_CPU1_SB_RSP<0>")
	)
	(segment
		(start 138.119358 -267.917168)
		(end 138.10869 -267.923264)
		(width 0.0889)
		(layer "In13.Cu")
		(net "M_H_CPU1_SB_RSP<0>")
	)
	(segment
		(start 137.179304 -267.917168)
		(end 137.168636 -267.923264)
		(width 0.0889)
		(layer "In13.Cu")
		(net "M_H_CPU1_SB_RSP<0>")
	)
	(segment
		(start 169.644568 -270.010382)
		(end 167.269922 -270.010382)
		(width 0.11684)
		(layer "In13.Cu")
		(net "M_H_CPU1_SB_RSP<0>")
	)
	(segment
		(start 160.249108 -266.570714)
		(end 147.77339 -266.570714)
		(width 0.11684)
		(layer "In13.Cu")
		(net "M_H_CPU1_SB_RSP<0>")
	)
	(segment
		(start 167.269922 -270.010382)
		(end 165.217348 -270.86052)
		(width 0.11684)
		(layer "In13.Cu")
		(net "M_H_CPU1_SB_RSP<0>")
	)
	(segment
		(start 172.694092 -270.86052)
		(end 171.697142 -270.86052)
		(width 0.11684)
		(layer "In13.Cu")
		(net "M_H_CPU1_SB_RSP<0>")
	)
	(segment
		(start 144.316196 -267.928598)
		(end 144.294606 -267.916152)
		(width 0.0889)
		(layer "In13.Cu")
		(net "M_H_CPU1_SB_RSP<0>")
	)
	(arc
		(start 138.10869 -267.923264)
		(mid 137.924794 -267.972744)
		(end 137.740898 -267.923264)
		(width 0.0889)
		(layer "In13.Cu")
		(net "M_H_CPU1_SB_RSP<0>")
	)
	(arc
		(start 137.740898 -267.923264)
		(mid 137.460894 -267.846219)
		(end 137.179304 -267.917168)
		(width 0.0889)
		(layer "In13.Cu")
		(net "M_H_CPU1_SB_RSP<0>")
	)
	(arc
		(start 142.437612 -267.928852)
		(mid 142.154656 -267.852675)
		(end 141.8717 -267.928852)
		(width 0.0889)
		(layer "In13.Cu")
		(net "M_H_CPU1_SB_RSP<0>")
	)
	(arc
		(start 145.256504 -267.928852)
		(mid 144.986347 -267.85209)
		(end 144.71269 -267.915136)
		(width 0.0889)
		(layer "In13.Cu")
		(net "M_H_CPU1_SB_RSP<0>")
	)
	(arc
		(start 139.608052 -267.923264)
		(mid 139.328398 -267.848024)
		(end 139.048744 -267.923264)
		(width 0.0889)
		(layer "In13.Cu")
		(net "M_H_CPU1_SB_RSP<0>")
	)
	(arc
		(start 139.991846 -267.928852)
		(mid 139.809595 -267.979202)
		(end 139.626086 -267.933678)
		(width 0.0889)
		(layer "In13.Cu")
		(net "M_H_CPU1_SB_RSP<0>")
	)
	(arc
		(start 141.497812 -267.928852)
		(mid 141.214856 -267.852675)
		(end 140.9319 -267.928852)
		(width 0.0889)
		(layer "In13.Cu")
		(net "M_H_CPU1_SB_RSP<0>")
	)
	(arc
		(start 143.751808 -267.928852)
		(mid 143.569557 -267.979202)
		(end 143.386048 -267.933678)
		(width 0.0889)
		(layer "In13.Cu")
		(net "M_H_CPU1_SB_RSP<0>")
	)
	(arc
		(start 140.9319 -267.928852)
		(mid 140.749649 -267.979202)
		(end 140.56614 -267.933678)
		(width 0.0889)
		(layer "In13.Cu")
		(net "M_H_CPU1_SB_RSP<0>")
	)
	(arc
		(start 139.048744 -267.923264)
		(mid 138.864848 -267.972744)
		(end 138.680952 -267.923264)
		(width 0.0889)
		(layer "In13.Cu")
		(net "M_H_CPU1_SB_RSP<0>")
	)
	(arc
		(start 144.689322 -267.928852)
		(mid 144.513202 -267.97883)
		(end 144.334484 -267.939012)
		(width 0.0889)
		(layer "In13.Cu")
		(net "M_H_CPU1_SB_RSP<0>")
	)
	(arc
		(start 143.377666 -267.928852)
		(mid 143.09471 -267.852675)
		(end 142.811754 -267.928852)
		(width 0.0889)
		(layer "In13.Cu")
		(net "M_H_CPU1_SB_RSP<0>")
	)
	(arc
		(start 142.803372 -267.933678)
		(mid 142.619864 -267.979172)
		(end 142.437612 -267.928852)
		(width 0.0889)
		(layer "In13.Cu")
		(net "M_H_CPU1_SB_RSP<0>")
	)
	(arc
		(start 140.557758 -267.928852)
		(mid 140.274802 -267.852675)
		(end 139.991846 -267.928852)
		(width 0.0889)
		(layer "In13.Cu")
		(net "M_H_CPU1_SB_RSP<0>")
	)
	(arc
		(start 136.800844 -267.923264)
		(mid 136.52084 -267.846219)
		(end 136.23925 -267.917168)
		(width 0.0889)
		(layer "In13.Cu")
		(net "M_H_CPU1_SB_RSP<0>")
	)
	(arc
		(start 141.8717 -267.928852)
		(mid 141.684756 -267.979107)
		(end 141.497812 -267.928852)
		(width 0.0889)
		(layer "In13.Cu")
		(net "M_H_CPU1_SB_RSP<0>")
	)
	(arc
		(start 136.228582 -267.923264)
		(mid 136.076923 -267.971218)
		(end 135.91921 -267.950442)
		(width 0.0889)
		(layer "In13.Cu")
		(net "M_H_CPU1_SB_RSP<0>")
	)
	(arc
		(start 138.680952 -267.923264)
		(mid 138.400948 -267.846219)
		(end 138.119358 -267.917168)
		(width 0.0889)
		(layer "In13.Cu")
		(net "M_H_CPU1_SB_RSP<0>")
	)
	(arc
		(start 137.168636 -267.923264)
		(mid 136.98474 -267.972744)
		(end 136.800844 -267.923264)
		(width 0.0889)
		(layer "In13.Cu")
		(net "M_H_CPU1_SB_RSP<0>")
	)
	(arc
		(start 144.294606 -267.916152)
		(mid 144.021577 -267.852833)
		(end 143.751808 -267.928852)
		(width 0.0889)
		(layer "In13.Cu")
		(net "M_H_CPU1_SB_RSP<0>")
	)
	(arc
		(start 145.603214 -267.944346)
		(mid 145.427963 -267.979279)
		(end 145.256504 -267.928852)
		(width 0.0889)
		(layer "In13.Cu")
		(net "M_H_CPU1_SB_RSP<0>")
	)
	(segment
		(start 134.16788 -264.910316)
		(end 134.634732 -265.176254)
		(width 0.10668)
		(layer "F.Cu")
		(net "M_H_CPU1_SB_PAR")
	)
	(segment
		(start 137.276078 -265.50366)
		(end 137.267696 -265.498834)
		(width 0.0889)
		(layer "In13.Cu")
		(net "M_H_CPU1_SB_PAR")
	)
	(segment
		(start 164.479224 -267.460476)
		(end 161.812732 -264.793984)
		(width 0.14478)
		(layer "In13.Cu")
		(net "M_H_CPU1_SB_PAR")
	)
	(segment
		(start 170.18254 -266.610338)
		(end 167.000174 -266.610338)
		(width 0.14478)
		(layer "In13.Cu")
		(net "M_H_CPU1_SB_PAR")
	)
	(segment
		(start 167.000174 -266.610338)
		(end 166.150036 -267.460476)
		(width 0.14478)
		(layer "In13.Cu")
		(net "M_H_CPU1_SB_PAR")
	)
	(segment
		(start 135.76173 -265.498834)
		(end 135.753348 -265.50366)
		(width 0.0889)
		(layer "In13.Cu")
		(net "M_H_CPU1_SB_PAR")
	)
	(segment
		(start 166.150036 -267.460476)
		(end 164.479224 -267.460476)
		(width 0.14478)
		(layer "In13.Cu")
		(net "M_H_CPU1_SB_PAR")
	)
	(segment
		(start 140.461746 -265.498834)
		(end 140.453364 -265.50366)
		(width 0.0889)
		(layer "In13.Cu")
		(net "M_H_CPU1_SB_PAR")
	)
	(segment
		(start 144.788382 -265.498834)
		(end 144.777968 -265.492738)
		(width 0.0889)
		(layer "In13.Cu")
		(net "M_H_CPU1_SB_PAR")
	)
	(segment
		(start 171.546774 -267.460476)
		(end 171.032678 -267.460476)
		(width 0.14478)
		(layer "In13.Cu")
		(net "M_H_CPU1_SB_PAR")
	)
	(segment
		(start 143.855948 -265.50366)
		(end 143.847566 -265.498834)
		(width 0.0889)
		(layer "In13.Cu")
		(net "M_H_CPU1_SB_PAR")
	)
	(segment
		(start 147.283424 -264.544556)
		(end 146.109436 -264.544556)
		(width 0.0889)
		(layer "In13.Cu")
		(net "M_H_CPU1_SB_PAR")
	)
	(segment
		(start 146.109436 -264.544556)
		(end 145.146014 -265.507978)
		(width 0.0889)
		(layer "In13.Cu")
		(net "M_H_CPU1_SB_PAR")
	)
	(segment
		(start 138.216132 -265.50366)
		(end 138.20775 -265.498834)
		(width 0.0889)
		(layer "In13.Cu")
		(net "M_H_CPU1_SB_PAR")
	)
	(segment
		(start 134.884668 -265.467084)
		(end 134.788656 -265.441684)
		(width 0.0889)
		(layer "In13.Cu")
		(net "M_H_CPU1_SB_PAR")
	)
	(segment
		(start 141.4018 -265.498834)
		(end 141.393418 -265.50366)
		(width 0.0889)
		(layer "In13.Cu")
		(net "M_H_CPU1_SB_PAR")
	)
	(segment
		(start 171.032678 -267.460476)
		(end 170.18254 -266.610338)
		(width 0.14478)
		(layer "In13.Cu")
		(net "M_H_CPU1_SB_PAR")
	)
	(segment
		(start 134.788656 -265.441684)
		(end 134.634732 -265.176254)
		(width 0.0889)
		(layer "In13.Cu")
		(net "M_H_CPU1_SB_PAR")
	)
	(segment
		(start 148.013674 -264.793984)
		(end 147.532852 -264.793984)
		(width 0.0889)
		(layer "In13.Cu")
		(net "M_H_CPU1_SB_PAR")
	)
	(segment
		(start 141.976094 -265.50366)
		(end 141.967712 -265.498834)
		(width 0.0889)
		(layer "In13.Cu")
		(net "M_H_CPU1_SB_PAR")
	)
	(segment
		(start 147.532852 -264.793984)
		(end 147.283424 -264.544556)
		(width 0.0889)
		(layer "In13.Cu")
		(net "M_H_CPU1_SB_PAR")
	)
	(segment
		(start 136.701784 -265.498834)
		(end 136.693402 -265.50366)
		(width 0.0889)
		(layer "In13.Cu")
		(net "M_H_CPU1_SB_PAR")
	)
	(segment
		(start 161.812732 -264.793984)
		(end 148.013674 -264.793984)
		(width 0.14478)
		(layer "In13.Cu")
		(net "M_H_CPU1_SB_PAR")
	)
	(segment
		(start 171.97197 -267.03528)
		(end 171.546774 -267.460476)
		(width 0.14478)
		(layer "In13.Cu")
		(net "M_H_CPU1_SB_PAR")
	)
	(arc
		(start 136.327642 -265.498834)
		(mid 136.044686 -265.422657)
		(end 135.76173 -265.498834)
		(width 0.0889)
		(layer "In13.Cu")
		(net "M_H_CPU1_SB_PAR")
	)
	(arc
		(start 143.281654 -265.498834)
		(mid 143.09471 -265.549089)
		(end 142.907766 -265.498834)
		(width 0.0889)
		(layer "In13.Cu")
		(net "M_H_CPU1_SB_PAR")
	)
	(arc
		(start 141.967712 -265.498834)
		(mid 141.684756 -265.422657)
		(end 141.4018 -265.498834)
		(width 0.0889)
		(layer "In13.Cu")
		(net "M_H_CPU1_SB_PAR")
	)
	(arc
		(start 141.027658 -265.498834)
		(mid 140.744702 -265.422657)
		(end 140.461746 -265.498834)
		(width 0.0889)
		(layer "In13.Cu")
		(net "M_H_CPU1_SB_PAR")
	)
	(arc
		(start 142.341854 -265.498834)
		(mid 142.159603 -265.549184)
		(end 141.976094 -265.50366)
		(width 0.0889)
		(layer "In13.Cu")
		(net "M_H_CPU1_SB_PAR")
	)
	(arc
		(start 143.847566 -265.498834)
		(mid 143.56461 -265.422657)
		(end 143.281654 -265.498834)
		(width 0.0889)
		(layer "In13.Cu")
		(net "M_H_CPU1_SB_PAR")
	)
	(arc
		(start 144.777968 -265.492738)
		(mid 144.499282 -265.422518)
		(end 144.222216 -265.498834)
		(width 0.0889)
		(layer "In13.Cu")
		(net "M_H_CPU1_SB_PAR")
	)
	(arc
		(start 138.20775 -265.498834)
		(mid 137.924794 -265.422657)
		(end 137.641838 -265.498834)
		(width 0.0889)
		(layer "In13.Cu")
		(net "M_H_CPU1_SB_PAR")
	)
	(arc
		(start 140.453364 -265.50366)
		(mid 140.269856 -265.549154)
		(end 140.087604 -265.498834)
		(width 0.0889)
		(layer "In13.Cu")
		(net "M_H_CPU1_SB_PAR")
	)
	(arc
		(start 137.267696 -265.498834)
		(mid 136.98474 -265.422657)
		(end 136.701784 -265.498834)
		(width 0.0889)
		(layer "In13.Cu")
		(net "M_H_CPU1_SB_PAR")
	)
	(arc
		(start 138.581892 -265.498834)
		(mid 138.399641 -265.549184)
		(end 138.216132 -265.50366)
		(width 0.0889)
		(layer "In13.Cu")
		(net "M_H_CPU1_SB_PAR")
	)
	(arc
		(start 145.146014 -265.507978)
		(mid 144.966032 -265.549078)
		(end 144.788382 -265.498834)
		(width 0.0889)
		(layer "In13.Cu")
		(net "M_H_CPU1_SB_PAR")
	)
	(arc
		(start 136.693402 -265.50366)
		(mid 136.509894 -265.549154)
		(end 136.327642 -265.498834)
		(width 0.0889)
		(layer "In13.Cu")
		(net "M_H_CPU1_SB_PAR")
	)
	(arc
		(start 135.387588 -265.498834)
		(mid 135.139875 -265.423614)
		(end 134.884668 -265.467084)
		(width 0.0889)
		(layer "In13.Cu")
		(net "M_H_CPU1_SB_PAR")
	)
	(arc
		(start 139.147804 -265.498834)
		(mid 138.864848 -265.422657)
		(end 138.581892 -265.498834)
		(width 0.0889)
		(layer "In13.Cu")
		(net "M_H_CPU1_SB_PAR")
	)
	(arc
		(start 140.087604 -265.498834)
		(mid 139.804648 -265.422657)
		(end 139.521692 -265.498834)
		(width 0.0889)
		(layer "In13.Cu")
		(net "M_H_CPU1_SB_PAR")
	)
	(arc
		(start 141.393418 -265.50366)
		(mid 141.20991 -265.549154)
		(end 141.027658 -265.498834)
		(width 0.0889)
		(layer "In13.Cu")
		(net "M_H_CPU1_SB_PAR")
	)
	(arc
		(start 137.641838 -265.498834)
		(mid 137.459587 -265.549184)
		(end 137.276078 -265.50366)
		(width 0.0889)
		(layer "In13.Cu")
		(net "M_H_CPU1_SB_PAR")
	)
	(arc
		(start 135.753348 -265.50366)
		(mid 135.56984 -265.549154)
		(end 135.387588 -265.498834)
		(width 0.0889)
		(layer "In13.Cu")
		(net "M_H_CPU1_SB_PAR")
	)
	(arc
		(start 144.222216 -265.498834)
		(mid 144.039711 -265.549311)
		(end 143.855948 -265.50366)
		(width 0.0889)
		(layer "In13.Cu")
		(net "M_H_CPU1_SB_PAR")
	)
	(arc
		(start 139.521692 -265.498834)
		(mid 139.334748 -265.549089)
		(end 139.147804 -265.498834)
		(width 0.0889)
		(layer "In13.Cu")
		(net "M_H_CPU1_SB_PAR")
	)
	(arc
		(start 142.907766 -265.498834)
		(mid 142.62481 -265.422657)
		(end 142.341854 -265.498834)
		(width 0.0889)
		(layer "In13.Cu")
		(net "M_H_CPU1_SB_PAR")
	)
	(segment
		(start 135.577834 -270.580358)
		(end 136.044686 -270.846296)
		(width 0.12954)
		(layer "F.Cu")
		(net "M_H_CPU1_SB_DQS_DP<9>")
	)
	(segment
		(start 166.755318 -275.22043)
		(end 167.629078 -275.22043)
		(width 0.16002)
		(layer "In13.Cu")
		(net "M_H_CPU1_SB_DQS_DP<9>")
	)
	(segment
		(start 161.06394 -271.849342)
		(end 164.024818 -274.81022)
		(width 0.16002)
		(layer "In13.Cu")
		(net "M_H_CPU1_SB_DQS_DP<9>")
	)
	(segment
		(start 137.173716 -271.17167)
		(end 137.17397 -271.17167)
		(width 0.09525)
		(layer "In13.Cu")
		(net "M_H_CPU1_SB_DQS_DP<9>")
	)
	(segment
		(start 170.070526 -275.22043)
		(end 170.5102 -275.660104)
		(width 0.16002)
		(layer "In13.Cu")
		(net "M_H_CPU1_SB_DQS_DP<9>")
	)
	(segment
		(start 166.345108 -274.81022)
		(end 166.755318 -275.22043)
		(width 0.16002)
		(layer "In13.Cu")
		(net "M_H_CPU1_SB_DQS_DP<9>")
	)
	(segment
		(start 164.024818 -274.81022)
		(end 166.345108 -274.81022)
		(width 0.16002)
		(layer "In13.Cu")
		(net "M_H_CPU1_SB_DQS_DP<9>")
	)
	(segment
		(start 144.69364 -271.17167)
		(end 144.724628 -271.153636)
		(width 0.09525)
		(layer "In13.Cu")
		(net "M_H_CPU1_SB_DQS_DP<9>")
	)
	(segment
		(start 167.629078 -275.22043)
		(end 168.090342 -275.681694)
		(width 0.16002)
		(layer "In13.Cu")
		(net "M_H_CPU1_SB_DQS_DP<9>")
	)
	(segment
		(start 140.545312 -271.165574)
		(end 140.555472 -271.17167)
		(width 0.09525)
		(layer "In13.Cu")
		(net "M_H_CPU1_SB_DQS_DP<9>")
	)
	(segment
		(start 174.077884 -275.836888)
		(end 174.519844 -276.278848)
		(width 0.16002)
		(layer "In13.Cu")
		(net "M_H_CPU1_SB_DQS_DP<9>")
	)
	(segment
		(start 168.090342 -275.681694)
		(end 168.575736 -275.681694)
		(width 0.16002)
		(layer "In13.Cu")
		(net "M_H_CPU1_SB_DQS_DP<9>")
	)
	(segment
		(start 144.31391 -271.170654)
		(end 144.315434 -271.17167)
		(width 0.09525)
		(layer "In13.Cu")
		(net "M_H_CPU1_SB_DQS_DP<9>")
	)
	(segment
		(start 137.17397 -271.17167)
		(end 137.18413 -271.165574)
		(width 0.09525)
		(layer "In13.Cu")
		(net "M_H_CPU1_SB_DQS_DP<9>")
	)
	(segment
		(start 138.11377 -271.17167)
		(end 138.114024 -271.17167)
		(width 0.09525)
		(layer "In13.Cu")
		(net "M_H_CPU1_SB_DQS_DP<9>")
	)
	(segment
		(start 172.752258 -275.99513)
		(end 173.52137 -275.99513)
		(width 0.16002)
		(layer "In13.Cu")
		(net "M_H_CPU1_SB_DQS_DP<9>")
	)
	(segment
		(start 144.312132 -271.169638)
		(end 144.31391 -271.170654)
		(width 0.09525)
		(layer "In13.Cu")
		(net "M_H_CPU1_SB_DQS_DP<9>")
	)
	(segment
		(start 140.555472 -271.17167)
		(end 140.555726 -271.17167)
		(width 0.09525)
		(layer "In13.Cu")
		(net "M_H_CPU1_SB_DQS_DP<9>")
	)
	(segment
		(start 159.856424 -271.849342)
		(end 161.06394 -271.849342)
		(width 0.16002)
		(layer "In13.Cu")
		(net "M_H_CPU1_SB_DQS_DP<9>")
	)
	(segment
		(start 147.8026 -269.252954)
		(end 157.260036 -269.252954)
		(width 0.16002)
		(layer "In13.Cu")
		(net "M_H_CPU1_SB_DQS_DP<9>")
	)
	(segment
		(start 138.114024 -271.17167)
		(end 138.124184 -271.165574)
		(width 0.09525)
		(layer "In13.Cu")
		(net "M_H_CPU1_SB_DQS_DP<9>")
	)
	(segment
		(start 147.281138 -269.172944)
		(end 147.420076 -269.311882)
		(width 0.09525)
		(layer "In13.Cu")
		(net "M_H_CPU1_SB_DQS_DP<9>")
	)
	(segment
		(start 169.037 -275.22043)
		(end 170.070526 -275.22043)
		(width 0.16002)
		(layer "In13.Cu")
		(net "M_H_CPU1_SB_DQS_DP<9>")
	)
	(segment
		(start 141.485366 -271.165574)
		(end 141.495526 -271.17167)
		(width 0.09525)
		(layer "In13.Cu")
		(net "M_H_CPU1_SB_DQS_DP<9>")
	)
	(segment
		(start 141.873986 -271.17167)
		(end 141.884146 -271.165574)
		(width 0.09525)
		(layer "In13.Cu")
		(net "M_H_CPU1_SB_DQS_DP<9>")
	)
	(segment
		(start 136.299448 -271.138396)
		(end 136.298686 -271.139158)
		(width 0.09525)
		(layer "In13.Cu")
		(net "M_H_CPU1_SB_DQS_DP<9>")
	)
	(segment
		(start 144.290034 -271.1577)
		(end 144.30121 -271.163542)
		(width 0.09525)
		(layer "In13.Cu")
		(net "M_H_CPU1_SB_DQS_DP<9>")
	)
	(segment
		(start 172.417232 -275.660104)
		(end 172.752258 -275.99513)
		(width 0.16002)
		(layer "In13.Cu")
		(net "M_H_CPU1_SB_DQS_DP<9>")
	)
	(segment
		(start 136.78535 -271.165574)
		(end 136.79551 -271.17167)
		(width 0.09525)
		(layer "In13.Cu")
		(net "M_H_CPU1_SB_DQS_DP<9>")
	)
	(segment
		(start 144.315434 -271.17167)
		(end 144.315688 -271.17167)
		(width 0.09525)
		(layer "In13.Cu")
		(net "M_H_CPU1_SB_DQS_DP<9>")
	)
	(segment
		(start 175.77054 -275.836888)
		(end 176.072038 -275.53539)
		(width 0.16002)
		(layer "In13.Cu")
		(net "M_H_CPU1_SB_DQS_DP<9>")
	)
	(segment
		(start 173.52137 -275.99513)
		(end 173.679612 -275.836888)
		(width 0.16002)
		(layer "In13.Cu")
		(net "M_H_CPU1_SB_DQS_DP<9>")
	)
	(segment
		(start 141.873732 -271.17167)
		(end 141.873986 -271.17167)
		(width 0.09525)
		(layer "In13.Cu")
		(net "M_H_CPU1_SB_DQS_DP<9>")
	)
	(segment
		(start 157.260036 -269.252954)
		(end 159.856424 -271.849342)
		(width 0.16002)
		(layer "In13.Cu")
		(net "M_H_CPU1_SB_DQS_DP<9>")
	)
	(segment
		(start 136.19861 -271.111726)
		(end 136.299448 -271.138396)
		(width 0.09525)
		(layer "In13.Cu")
		(net "M_H_CPU1_SB_DQS_DP<9>")
	)
	(segment
		(start 175.024542 -276.278848)
		(end 175.466502 -275.836888)
		(width 0.16002)
		(layer "In13.Cu")
		(net "M_H_CPU1_SB_DQS_DP<9>")
	)
	(segment
		(start 147.778978 -269.252954)
		(end 147.8026 -269.252954)
		(width 0.09525)
		(layer "In13.Cu")
		(net "M_H_CPU1_SB_DQS_DP<9>")
	)
	(segment
		(start 146.61515 -269.172944)
		(end 147.281138 -269.172944)
		(width 0.09525)
		(layer "In13.Cu")
		(net "M_H_CPU1_SB_DQS_DP<9>")
	)
	(segment
		(start 136.044686 -270.846296)
		(end 136.19861 -271.111726)
		(width 0.09525)
		(layer "In13.Cu")
		(net "M_H_CPU1_SB_DQS_DP<9>")
	)
	(segment
		(start 147.72005 -269.311882)
		(end 147.778978 -269.252954)
		(width 0.09525)
		(layer "In13.Cu")
		(net "M_H_CPU1_SB_DQS_DP<9>")
	)
	(segment
		(start 174.519844 -276.278848)
		(end 175.024542 -276.278848)
		(width 0.16002)
		(layer "In13.Cu")
		(net "M_H_CPU1_SB_DQS_DP<9>")
	)
	(segment
		(start 145.666206 -270.121888)
		(end 146.61515 -269.172944)
		(width 0.09525)
		(layer "In13.Cu")
		(net "M_H_CPU1_SB_DQS_DP<9>")
	)
	(segment
		(start 145.12417 -270.384524)
		(end 145.14576 -270.372332)
		(width 0.09525)
		(layer "In13.Cu")
		(net "M_H_CPU1_SB_DQS_DP<9>")
	)
	(segment
		(start 170.5102 -275.660104)
		(end 172.417232 -275.660104)
		(width 0.16002)
		(layer "In13.Cu")
		(net "M_H_CPU1_SB_DQS_DP<9>")
	)
	(segment
		(start 173.679612 -275.836888)
		(end 174.077884 -275.836888)
		(width 0.16002)
		(layer "In13.Cu")
		(net "M_H_CPU1_SB_DQS_DP<9>")
	)
	(segment
		(start 147.420076 -269.311882)
		(end 147.72005 -269.311882)
		(width 0.09525)
		(layer "In13.Cu")
		(net "M_H_CPU1_SB_DQS_DP<9>")
	)
	(segment
		(start 168.575736 -275.681694)
		(end 169.037 -275.22043)
		(width 0.16002)
		(layer "In13.Cu")
		(net "M_H_CPU1_SB_DQS_DP<9>")
	)
	(segment
		(start 175.466502 -275.836888)
		(end 175.77054 -275.836888)
		(width 0.16002)
		(layer "In13.Cu")
		(net "M_H_CPU1_SB_DQS_DP<9>")
	)
	(segment
		(start 145.663158 -270.12519)
		(end 145.666206 -270.121888)
		(width 0.09525)
		(layer "In13.Cu")
		(net "M_H_CPU1_SB_DQS_DP<9>")
	)
	(segment
		(start 144.30121 -271.163542)
		(end 144.312132 -271.169638)
		(width 0.09525)
		(layer "In13.Cu")
		(net "M_H_CPU1_SB_DQS_DP<9>")
	)
	(arc
		(start 138.124184 -271.165574)
		(mid 138.400838 -271.095988)
		(end 138.675872 -271.17167)
		(width 0.09525)
		(layer "In13.Cu")
		(net "M_H_CPU1_SB_DQS_DP<9>")
	)
	(arc
		(start 139.615672 -271.17167)
		(mid 139.804648 -271.222567)
		(end 139.993624 -271.17167)
		(width 0.09525)
		(layer "In13.Cu")
		(net "M_H_CPU1_SB_DQS_DP<9>")
	)
	(arc
		(start 143.375634 -271.17167)
		(mid 143.56461 -271.222567)
		(end 143.753586 -271.17167)
		(width 0.09525)
		(layer "In13.Cu")
		(net "M_H_CPU1_SB_DQS_DP<9>")
	)
	(arc
		(start 144.724628 -271.153636)
		(mid 144.840893 -271.019098)
		(end 144.88287 -270.846296)
		(width 0.09525)
		(layer "In13.Cu")
		(net "M_H_CPU1_SB_DQS_DP<9>")
	)
	(arc
		(start 137.735818 -271.17167)
		(mid 137.924794 -271.222567)
		(end 138.11377 -271.17167)
		(width 0.09525)
		(layer "In13.Cu")
		(net "M_H_CPU1_SB_DQS_DP<9>")
	)
	(arc
		(start 136.320022 -271.13103)
		(mid 136.556468 -271.097507)
		(end 136.78535 -271.165574)
		(width 0.09525)
		(layer "In13.Cu")
		(net "M_H_CPU1_SB_DQS_DP<9>")
	)
	(arc
		(start 145.16354 -270.36141)
		(mid 145.256038 -270.318384)
		(end 145.354802 -270.29283)
		(width 0.09525)
		(layer "In13.Cu")
		(net "M_H_CPU1_SB_DQS_DP<9>")
	)
	(arc
		(start 141.884146 -271.165574)
		(mid 142.1608 -271.095988)
		(end 142.435834 -271.17167)
		(width 0.09525)
		(layer "In13.Cu")
		(net "M_H_CPU1_SB_DQS_DP<9>")
	)
	(arc
		(start 142.813786 -271.17167)
		(mid 143.09471 -271.096136)
		(end 143.375634 -271.17167)
		(width 0.09525)
		(layer "In13.Cu")
		(net "M_H_CPU1_SB_DQS_DP<9>")
	)
	(arc
		(start 140.933678 -271.17167)
		(mid 141.208713 -271.096042)
		(end 141.485366 -271.165574)
		(width 0.09525)
		(layer "In13.Cu")
		(net "M_H_CPU1_SB_DQS_DP<9>")
	)
	(arc
		(start 139.993624 -271.17167)
		(mid 140.268659 -271.096042)
		(end 140.545312 -271.165574)
		(width 0.09525)
		(layer "In13.Cu")
		(net "M_H_CPU1_SB_DQS_DP<9>")
	)
	(arc
		(start 137.18413 -271.165574)
		(mid 137.460784 -271.095988)
		(end 137.735818 -271.17167)
		(width 0.09525)
		(layer "In13.Cu")
		(net "M_H_CPU1_SB_DQS_DP<9>")
	)
	(arc
		(start 138.675872 -271.17167)
		(mid 138.864848 -271.222567)
		(end 139.053824 -271.17167)
		(width 0.09525)
		(layer "In13.Cu")
		(net "M_H_CPU1_SB_DQS_DP<9>")
	)
	(arc
		(start 145.14576 -270.372332)
		(mid 145.1546 -270.366789)
		(end 145.16354 -270.36141)
		(width 0.09525)
		(layer "In13.Cu")
		(net "M_H_CPU1_SB_DQS_DP<9>")
	)
	(arc
		(start 142.435834 -271.17167)
		(mid 142.62481 -271.222567)
		(end 142.813786 -271.17167)
		(width 0.09525)
		(layer "In13.Cu")
		(net "M_H_CPU1_SB_DQS_DP<9>")
	)
	(arc
		(start 136.298686 -271.139158)
		(mid 136.309313 -271.134988)
		(end 136.320022 -271.13103)
		(width 0.09525)
		(layer "In13.Cu")
		(net "M_H_CPU1_SB_DQS_DP<9>")
	)
	(arc
		(start 140.555726 -271.17167)
		(mid 140.744702 -271.222567)
		(end 140.933678 -271.17167)
		(width 0.09525)
		(layer "In13.Cu")
		(net "M_H_CPU1_SB_DQS_DP<9>")
	)
	(arc
		(start 144.315688 -271.17167)
		(mid 144.504664 -271.222567)
		(end 144.69364 -271.17167)
		(width 0.09525)
		(layer "In13.Cu")
		(net "M_H_CPU1_SB_DQS_DP<9>")
	)
	(arc
		(start 143.753586 -271.17167)
		(mid 144.020017 -271.096323)
		(end 144.290034 -271.1577)
		(width 0.09525)
		(layer "In13.Cu")
		(net "M_H_CPU1_SB_DQS_DP<9>")
	)
	(arc
		(start 141.495526 -271.17167)
		(mid 141.684646 -271.222695)
		(end 141.873732 -271.17167)
		(width 0.09525)
		(layer "In13.Cu")
		(net "M_H_CPU1_SB_DQS_DP<9>")
	)
	(arc
		(start 144.88287 -270.846296)
		(mid 144.946769 -270.585749)
		(end 145.12417 -270.384524)
		(width 0.09525)
		(layer "In13.Cu")
		(net "M_H_CPU1_SB_DQS_DP<9>")
	)
	(arc
		(start 136.79551 -271.17167)
		(mid 136.98463 -271.222695)
		(end 137.173716 -271.17167)
		(width 0.09525)
		(layer "In13.Cu")
		(net "M_H_CPU1_SB_DQS_DP<9>")
	)
	(arc
		(start 145.354802 -270.29283)
		(mid 145.523254 -270.235263)
		(end 145.663158 -270.12519)
		(width 0.09525)
		(layer "In13.Cu")
		(net "M_H_CPU1_SB_DQS_DP<9>")
	)
	(arc
		(start 139.053824 -271.17167)
		(mid 139.334748 -271.096136)
		(end 139.615672 -271.17167)
		(width 0.09525)
		(layer "In13.Cu")
		(net "M_H_CPU1_SB_DQS_DP<9>")
	)
	(segment
		(start 134.63778 -291.64026)
		(end 135.104632 -291.906198)
		(width 0.12954)
		(layer "F.Cu")
		(net "M_H_CPU1_SB_DQS_DP<8>")
	)
	(segment
		(start 146.074638 -293.994586)
		(end 146.073876 -293.994078)
		(width 0.09525)
		(layer "In13.Cu")
		(net "M_H_CPU1_SB_DQS_DP<8>")
	)
	(segment
		(start 167.898572 -314.986924)
		(end 167.898572 -314.498228)
		(width 0.16002)
		(layer "In13.Cu")
		(net "M_H_CPU1_SB_DQS_DP<8>")
	)
	(segment
		(start 169.360088 -315.323982)
		(end 168.23563 -315.323982)
		(width 0.16002)
		(layer "In13.Cu")
		(net "M_H_CPU1_SB_DQS_DP<8>")
	)
	(segment
		(start 145.603468 -292.877748)
		(end 145.060162 -292.334442)
		(width 0.09525)
		(layer "In13.Cu")
		(net "M_H_CPU1_SB_DQS_DP<8>")
	)
	(segment
		(start 162.22726 -314.881768)
		(end 162.22726 -314.422028)
		(width 0.16002)
		(layer "In13.Cu")
		(net "M_H_CPU1_SB_DQS_DP<8>")
	)
	(segment
		(start 166.06139 -314.997846)
		(end 164.536628 -314.997846)
		(width 0.16002)
		(layer "In13.Cu")
		(net "M_H_CPU1_SB_DQS_DP<8>")
	)
	(segment
		(start 135.8646 -291.576252)
		(end 135.856218 -291.581078)
		(width 0.09525)
		(layer "In13.Cu")
		(net "M_H_CPU1_SB_DQS_DP<8>")
	)
	(segment
		(start 167.435022 -314.034678)
		(end 167.024558 -314.034678)
		(width 0.16002)
		(layer "In13.Cu")
		(net "M_H_CPU1_SB_DQS_DP<8>")
	)
	(segment
		(start 145.822924 -293.407084)
		(end 145.82267 -293.407338)
		(width 0.09525)
		(layer "In13.Cu")
		(net "M_H_CPU1_SB_DQS_DP<8>")
	)
	(segment
		(start 169.697146 -314.46089)
		(end 169.697146 -314.986924)
		(width 0.16002)
		(layer "In13.Cu")
		(net "M_H_CPU1_SB_DQS_DP<8>")
	)
	(segment
		(start 161.55924 -314.422028)
		(end 161.55924 -314.881768)
		(width 0.16002)
		(layer "In13.Cu")
		(net "M_H_CPU1_SB_DQS_DP<8>")
	)
	(segment
		(start 161.222182 -315.218826)
		(end 160.757362 -315.218826)
		(width 0.16002)
		(layer "In13.Cu")
		(net "M_H_CPU1_SB_DQS_DP<8>")
	)
	(segment
		(start 139.624562 -291.576252)
		(end 139.61618 -291.581078)
		(width 0.09525)
		(layer "In13.Cu")
		(net "M_H_CPU1_SB_DQS_DP<8>")
	)
	(segment
		(start 169.697146 -314.986924)
		(end 169.360088 -315.323982)
		(width 0.16002)
		(layer "In13.Cu")
		(net "M_H_CPU1_SB_DQS_DP<8>")
	)
	(segment
		(start 163.655502 -314.685934)
		(end 163.12261 -315.218826)
		(width 0.16002)
		(layer "In13.Cu")
		(net "M_H_CPU1_SB_DQS_DP<8>")
	)
	(segment
		(start 139.053316 -291.581078)
		(end 139.044934 -291.576252)
		(width 0.09525)
		(layer "In13.Cu")
		(net "M_H_CPU1_SB_DQS_DP<8>")
	)
	(segment
		(start 146.874992 -295.225724)
		(end 146.858228 -295.20896)
		(width 0.09525)
		(layer "In13.Cu")
		(net "M_H_CPU1_SB_DQS_DP<8>")
	)
	(segment
		(start 161.55924 -314.881768)
		(end 161.222182 -315.218826)
		(width 0.16002)
		(layer "In13.Cu")
		(net "M_H_CPU1_SB_DQS_DP<8>")
	)
	(segment
		(start 147.06219 -295.41216)
		(end 146.874992 -295.225724)
		(width 0.16002)
		(layer "In13.Cu")
		(net "M_H_CPU1_SB_DQS_DP<8>")
	)
	(segment
		(start 171.637452 -314.30087)
		(end 169.857166 -314.30087)
		(width 0.16002)
		(layer "In13.Cu")
		(net "M_H_CPU1_SB_DQS_DP<8>")
	)
	(segment
		(start 134.974076 -291.5539)
		(end 134.950708 -291.640768)
		(width 0.09525)
		(layer "In13.Cu")
		(net "M_H_CPU1_SB_DQS_DP<8>")
	)
	(segment
		(start 146.857974 -295.125648)
		(end 146.292316 -294.560498)
		(width 0.09525)
		(layer "In13.Cu")
		(net "M_H_CPU1_SB_DQS_DP<8>")
	)
	(segment
		(start 145.822416 -293.52621)
		(end 145.822924 -293.525702)
		(width 0.09525)
		(layer "In13.Cu")
		(net "M_H_CPU1_SB_DQS_DP<8>")
	)
	(segment
		(start 144.88287 -291.906452)
		(end 144.882616 -291.906198)
		(width 0.09525)
		(layer "In13.Cu")
		(net "M_H_CPU1_SB_DQS_DP<8>")
	)
	(segment
		(start 134.950708 -291.640768)
		(end 135.104632 -291.906198)
		(width 0.09525)
		(layer "In13.Cu")
		(net "M_H_CPU1_SB_DQS_DP<8>")
	)
	(segment
		(start 171.97197 -314.635388)
		(end 171.637452 -314.30087)
		(width 0.16002)
		(layer "In13.Cu")
		(net "M_H_CPU1_SB_DQS_DP<8>")
	)
	(segment
		(start 161.71926 -314.262008)
		(end 161.55924 -314.422028)
		(width 0.16002)
		(layer "In13.Cu")
		(net "M_H_CPU1_SB_DQS_DP<8>")
	)
	(segment
		(start 167.024558 -314.034678)
		(end 166.06139 -314.997846)
		(width 0.16002)
		(layer "In13.Cu")
		(net "M_H_CPU1_SB_DQS_DP<8>")
	)
	(segment
		(start 145.822924 -293.525702)
		(end 145.822924 -293.407084)
		(width 0.09525)
		(layer "In13.Cu")
		(net "M_H_CPU1_SB_DQS_DP<8>")
	)
	(segment
		(start 146.134836 -294.029384)
		(end 146.074638 -293.994586)
		(width 0.09525)
		(layer "In13.Cu")
		(net "M_H_CPU1_SB_DQS_DP<8>")
	)
	(segment
		(start 164.224716 -314.685934)
		(end 163.655502 -314.685934)
		(width 0.16002)
		(layer "In13.Cu")
		(net "M_H_CPU1_SB_DQS_DP<8>")
	)
	(segment
		(start 164.536628 -314.997846)
		(end 164.224716 -314.685934)
		(width 0.16002)
		(layer "In13.Cu")
		(net "M_H_CPU1_SB_DQS_DP<8>")
	)
	(segment
		(start 140.564616 -291.576252)
		(end 140.556234 -291.581078)
		(width 0.09525)
		(layer "In13.Cu")
		(net "M_H_CPU1_SB_DQS_DP<8>")
	)
	(segment
		(start 147.06219 -301.523654)
		(end 147.06219 -295.41216)
		(width 0.16002)
		(layer "In13.Cu")
		(net "M_H_CPU1_SB_DQS_DP<8>")
	)
	(segment
		(start 138.113262 -291.581078)
		(end 138.10488 -291.576252)
		(width 0.09525)
		(layer "In13.Cu")
		(net "M_H_CPU1_SB_DQS_DP<8>")
	)
	(segment
		(start 146.073876 -293.994078)
		(end 146.06524 -293.988998)
		(width 0.09525)
		(layer "In13.Cu")
		(net "M_H_CPU1_SB_DQS_DP<8>")
	)
	(segment
		(start 146.292316 -294.560498)
		(end 146.292316 -294.336216)
		(width 0.09525)
		(layer "In13.Cu")
		(net "M_H_CPU1_SB_DQS_DP<8>")
	)
	(segment
		(start 169.857166 -314.30087)
		(end 169.697146 -314.46089)
		(width 0.16002)
		(layer "In13.Cu")
		(net "M_H_CPU1_SB_DQS_DP<8>")
	)
	(segment
		(start 144.724882 -291.599366)
		(end 144.693386 -291.581078)
		(width 0.09525)
		(layer "In13.Cu")
		(net "M_H_CPU1_SB_DQS_DP<8>")
	)
	(segment
		(start 163.12261 -315.218826)
		(end 162.564318 -315.218826)
		(width 0.16002)
		(layer "In13.Cu")
		(net "M_H_CPU1_SB_DQS_DP<8>")
	)
	(segment
		(start 162.06724 -314.262008)
		(end 161.71926 -314.262008)
		(width 0.16002)
		(layer "In13.Cu")
		(net "M_H_CPU1_SB_DQS_DP<8>")
	)
	(segment
		(start 160.757362 -315.218826)
		(end 147.06219 -301.523654)
		(width 0.16002)
		(layer "In13.Cu")
		(net "M_H_CPU1_SB_DQS_DP<8>")
	)
	(segment
		(start 142.813278 -291.581078)
		(end 142.804896 -291.576252)
		(width 0.09525)
		(layer "In13.Cu")
		(net "M_H_CPU1_SB_DQS_DP<8>")
	)
	(segment
		(start 162.22726 -314.422028)
		(end 162.06724 -314.262008)
		(width 0.16002)
		(layer "In13.Cu")
		(net "M_H_CPU1_SB_DQS_DP<8>")
	)
	(segment
		(start 144.324578 -291.576252)
		(end 144.316196 -291.581078)
		(width 0.09525)
		(layer "In13.Cu")
		(net "M_H_CPU1_SB_DQS_DP<8>")
	)
	(segment
		(start 167.898572 -314.498228)
		(end 167.435022 -314.034678)
		(width 0.16002)
		(layer "In13.Cu")
		(net "M_H_CPU1_SB_DQS_DP<8>")
	)
	(segment
		(start 144.882616 -291.906198)
		(end 144.882362 -291.906198)
		(width 0.09525)
		(layer "In13.Cu")
		(net "M_H_CPU1_SB_DQS_DP<8>")
	)
	(segment
		(start 146.858228 -295.20896)
		(end 146.857974 -295.125648)
		(width 0.09525)
		(layer "In13.Cu")
		(net "M_H_CPU1_SB_DQS_DP<8>")
	)
	(segment
		(start 162.564318 -315.218826)
		(end 162.22726 -314.881768)
		(width 0.16002)
		(layer "In13.Cu")
		(net "M_H_CPU1_SB_DQS_DP<8>")
	)
	(segment
		(start 168.23563 -315.323982)
		(end 167.898572 -314.986924)
		(width 0.16002)
		(layer "In13.Cu")
		(net "M_H_CPU1_SB_DQS_DP<8>")
	)
	(segment
		(start 143.384524 -291.576252)
		(end 143.376142 -291.581078)
		(width 0.09525)
		(layer "In13.Cu")
		(net "M_H_CPU1_SB_DQS_DP<8>")
	)
	(arc
		(start 135.293354 -291.581078)
		(mid 135.136756 -291.531789)
		(end 134.974076 -291.5539)
		(width 0.09525)
		(layer "In13.Cu")
		(net "M_H_CPU1_SB_DQS_DP<8>")
	)
	(arc
		(start 142.436088 -291.581078)
		(mid 142.154656 -291.656833)
		(end 141.873224 -291.581078)
		(width 0.09525)
		(layer "In13.Cu")
		(net "M_H_CPU1_SB_DQS_DP<8>")
	)
	(arc
		(start 144.882362 -291.906198)
		(mid 144.840697 -291.733751)
		(end 144.724882 -291.599366)
		(width 0.09525)
		(layer "In13.Cu")
		(net "M_H_CPU1_SB_DQS_DP<8>")
	)
	(arc
		(start 143.753332 -291.581078)
		(mid 143.569557 -291.530306)
		(end 143.384524 -291.576252)
		(width 0.09525)
		(layer "In13.Cu")
		(net "M_H_CPU1_SB_DQS_DP<8>")
	)
	(arc
		(start 140.933424 -291.581078)
		(mid 140.749649 -291.530306)
		(end 140.564616 -291.576252)
		(width 0.09525)
		(layer "In13.Cu")
		(net "M_H_CPU1_SB_DQS_DP<8>")
	)
	(arc
		(start 138.10488 -291.576252)
		(mid 137.919848 -291.530338)
		(end 137.736072 -291.581078)
		(width 0.09525)
		(layer "In13.Cu")
		(net "M_H_CPU1_SB_DQS_DP<8>")
	)
	(arc
		(start 135.856218 -291.581078)
		(mid 135.574786 -291.656833)
		(end 135.293354 -291.581078)
		(width 0.09525)
		(layer "In13.Cu")
		(net "M_H_CPU1_SB_DQS_DP<8>")
	)
	(arc
		(start 139.044934 -291.576252)
		(mid 138.859902 -291.530338)
		(end 138.676126 -291.581078)
		(width 0.09525)
		(layer "In13.Cu")
		(net "M_H_CPU1_SB_DQS_DP<8>")
	)
	(arc
		(start 146.292316 -294.336216)
		(mid 146.250651 -294.163769)
		(end 146.134836 -294.029384)
		(width 0.09525)
		(layer "In13.Cu")
		(net "M_H_CPU1_SB_DQS_DP<8>")
	)
	(arc
		(start 141.496288 -291.581078)
		(mid 141.214856 -291.656833)
		(end 140.933424 -291.581078)
		(width 0.09525)
		(layer "In13.Cu")
		(net "M_H_CPU1_SB_DQS_DP<8>")
	)
	(arc
		(start 138.676126 -291.581078)
		(mid 138.394694 -291.656833)
		(end 138.113262 -291.581078)
		(width 0.09525)
		(layer "In13.Cu")
		(net "M_H_CPU1_SB_DQS_DP<8>")
	)
	(arc
		(start 137.736072 -291.581078)
		(mid 137.45464 -291.656833)
		(end 137.173208 -291.581078)
		(width 0.09525)
		(layer "In13.Cu")
		(net "M_H_CPU1_SB_DQS_DP<8>")
	)
	(arc
		(start 140.556234 -291.581078)
		(mid 140.274802 -291.656833)
		(end 139.99337 -291.581078)
		(width 0.09525)
		(layer "In13.Cu")
		(net "M_H_CPU1_SB_DQS_DP<8>")
	)
	(arc
		(start 141.873224 -291.581078)
		(mid 141.684756 -291.530401)
		(end 141.496288 -291.581078)
		(width 0.09525)
		(layer "In13.Cu")
		(net "M_H_CPU1_SB_DQS_DP<8>")
	)
	(arc
		(start 144.316196 -291.581078)
		(mid 144.034764 -291.656833)
		(end 143.753332 -291.581078)
		(width 0.09525)
		(layer "In13.Cu")
		(net "M_H_CPU1_SB_DQS_DP<8>")
	)
	(arc
		(start 137.173208 -291.581078)
		(mid 136.98474 -291.530401)
		(end 136.796272 -291.581078)
		(width 0.09525)
		(layer "In13.Cu")
		(net "M_H_CPU1_SB_DQS_DP<8>")
	)
	(arc
		(start 143.376142 -291.581078)
		(mid 143.09471 -291.656833)
		(end 142.813278 -291.581078)
		(width 0.09525)
		(layer "In13.Cu")
		(net "M_H_CPU1_SB_DQS_DP<8>")
	)
	(arc
		(start 136.233408 -291.581078)
		(mid 136.049633 -291.530306)
		(end 135.8646 -291.576252)
		(width 0.09525)
		(layer "In13.Cu")
		(net "M_H_CPU1_SB_DQS_DP<8>")
	)
	(arc
		(start 142.804896 -291.576252)
		(mid 142.619864 -291.530338)
		(end 142.436088 -291.581078)
		(width 0.09525)
		(layer "In13.Cu")
		(net "M_H_CPU1_SB_DQS_DP<8>")
	)
	(arc
		(start 139.99337 -291.581078)
		(mid 139.809595 -291.530306)
		(end 139.624562 -291.576252)
		(width 0.09525)
		(layer "In13.Cu")
		(net "M_H_CPU1_SB_DQS_DP<8>")
	)
	(arc
		(start 139.61618 -291.581078)
		(mid 139.334748 -291.656833)
		(end 139.053316 -291.581078)
		(width 0.09525)
		(layer "In13.Cu")
		(net "M_H_CPU1_SB_DQS_DP<8>")
	)
	(arc
		(start 136.796272 -291.581078)
		(mid 136.51484 -291.656833)
		(end 136.233408 -291.581078)
		(width 0.09525)
		(layer "In13.Cu")
		(net "M_H_CPU1_SB_DQS_DP<8>")
	)
	(arc
		(start 145.82267 -293.407338)
		(mid 145.76577 -293.12072)
		(end 145.603468 -292.877748)
		(width 0.09525)
		(layer "In13.Cu")
		(net "M_H_CPU1_SB_DQS_DP<8>")
	)
	(arc
		(start 146.06524 -293.988998)
		(mid 145.88679 -293.787528)
		(end 145.822416 -293.52621)
		(width 0.09525)
		(layer "In13.Cu")
		(net "M_H_CPU1_SB_DQS_DP<8>")
	)
	(arc
		(start 145.060162 -292.334442)
		(mid 144.928927 -292.138079)
		(end 144.88287 -291.906452)
		(width 0.09525)
		(layer "In13.Cu")
		(net "M_H_CPU1_SB_DQS_DP<8>")
	)
	(arc
		(start 144.693386 -291.581078)
		(mid 144.509611 -291.530306)
		(end 144.324578 -291.576252)
		(width 0.09525)
		(layer "In13.Cu")
		(net "M_H_CPU1_SB_DQS_DP<8>")
	)
	(segment
		(start 134.63778 -286.780478)
		(end 135.104632 -287.046162)
		(width 0.12954)
		(layer "F.Cu")
		(net "M_H_CPU1_SB_DQS_DP<7>")
	)
	(segment
		(start 169.940986 -305.016408)
		(end 171.702984 -305.016408)
		(width 0.16002)
		(layer "In13.Cu")
		(net "M_H_CPU1_SB_DQS_DP<7>")
	)
	(segment
		(start 147.474178 -287.506156)
		(end 147.688554 -287.720786)
		(width 0.09525)
		(layer "In13.Cu")
		(net "M_H_CPU1_SB_DQS_DP<7>")
	)
	(segment
		(start 162.995356 -305.642518)
		(end 166.066724 -305.642518)
		(width 0.16002)
		(layer "In13.Cu")
		(net "M_H_CPU1_SB_DQS_DP<7>")
	)
	(segment
		(start 147.688554 -287.80359)
		(end 147.705318 -287.820354)
		(width 0.09525)
		(layer "In13.Cu")
		(net "M_H_CPU1_SB_DQS_DP<7>")
	)
	(segment
		(start 142.804896 -286.716216)
		(end 142.813278 -286.721042)
		(width 0.09525)
		(layer "In13.Cu")
		(net "M_H_CPU1_SB_DQS_DP<7>")
	)
	(segment
		(start 161.888678 -305.065684)
		(end 162.048698 -304.905664)
		(width 0.16002)
		(layer "In13.Cu")
		(net "M_H_CPU1_SB_DQS_DP<7>")
	)
	(segment
		(start 143.376142 -286.721042)
		(end 143.384524 -286.716216)
		(width 0.09525)
		(layer "In13.Cu")
		(net "M_H_CPU1_SB_DQS_DP<7>")
	)
	(segment
		(start 158.899098 -304.08372)
		(end 159.375602 -304.08372)
		(width 0.16002)
		(layer "In13.Cu")
		(net "M_H_CPU1_SB_DQS_DP<7>")
	)
	(segment
		(start 147.705318 -287.820354)
		(end 152.63495 -292.749986)
		(width 0.16002)
		(layer "In13.Cu")
		(net "M_H_CPU1_SB_DQS_DP<7>")
	)
	(segment
		(start 158.659576 -302.711612)
		(end 158.659576 -302.937672)
		(width 0.16002)
		(layer "In13.Cu")
		(net "M_H_CPU1_SB_DQS_DP<7>")
	)
	(segment
		(start 152.63495 -297.824398)
		(end 155.903676 -301.093124)
		(width 0.16002)
		(layer "In13.Cu")
		(net "M_H_CPU1_SB_DQS_DP<7>")
	)
	(segment
		(start 169.71899 -304.794412)
		(end 169.940986 -305.016408)
		(width 0.16002)
		(layer "In13.Cu")
		(net "M_H_CPU1_SB_DQS_DP<7>")
	)
	(segment
		(start 161.888678 -305.30546)
		(end 161.888678 -305.065684)
		(width 0.16002)
		(layer "In13.Cu")
		(net "M_H_CPU1_SB_DQS_DP<7>")
	)
	(segment
		(start 158.444692 -303.629314)
		(end 158.899098 -304.08372)
		(width 0.16002)
		(layer "In13.Cu")
		(net "M_H_CPU1_SB_DQS_DP<7>")
	)
	(segment
		(start 158.444692 -303.152556)
		(end 158.444692 -303.629314)
		(width 0.16002)
		(layer "In13.Cu")
		(net "M_H_CPU1_SB_DQS_DP<7>")
	)
	(segment
		(start 156.823664 -300.8757)
		(end 157.142688 -301.194724)
		(width 0.16002)
		(layer "In13.Cu")
		(net "M_H_CPU1_SB_DQS_DP<7>")
	)
	(segment
		(start 158.659576 -302.937672)
		(end 158.444692 -303.152556)
		(width 0.16002)
		(layer "In13.Cu")
		(net "M_H_CPU1_SB_DQS_DP<7>")
	)
	(segment
		(start 162.658298 -305.065684)
		(end 162.658298 -305.30546)
		(width 0.16002)
		(layer "In13.Cu")
		(net "M_H_CPU1_SB_DQS_DP<7>")
	)
	(segment
		(start 162.498278 -304.905664)
		(end 162.658298 -305.065684)
		(width 0.16002)
		(layer "In13.Cu")
		(net "M_H_CPU1_SB_DQS_DP<7>")
	)
	(segment
		(start 152.63495 -292.749986)
		(end 152.63495 -297.824398)
		(width 0.16002)
		(layer "In13.Cu")
		(net "M_H_CPU1_SB_DQS_DP<7>")
	)
	(segment
		(start 160.151826 -304.171604)
		(end 160.151826 -304.397664)
		(width 0.16002)
		(layer "In13.Cu")
		(net "M_H_CPU1_SB_DQS_DP<7>")
	)
	(segment
		(start 160.457896 -305.642518)
		(end 161.55162 -305.642518)
		(width 0.16002)
		(layer "In13.Cu")
		(net "M_H_CPU1_SB_DQS_DP<7>")
	)
	(segment
		(start 156.925264 -302.114712)
		(end 157.420564 -302.610012)
		(width 0.16002)
		(layer "In13.Cu")
		(net "M_H_CPU1_SB_DQS_DP<7>")
	)
	(segment
		(start 162.658298 -305.30546)
		(end 162.995356 -305.642518)
		(width 0.16002)
		(layer "In13.Cu")
		(net "M_H_CPU1_SB_DQS_DP<7>")
	)
	(segment
		(start 143.753332 -286.721042)
		(end 143.763746 -286.727138)
		(width 0.09525)
		(layer "In13.Cu")
		(net "M_H_CPU1_SB_DQS_DP<7>")
	)
	(segment
		(start 156.38018 -301.093124)
		(end 156.597604 -300.8757)
		(width 0.16002)
		(layer "In13.Cu")
		(net "M_H_CPU1_SB_DQS_DP<7>")
	)
	(segment
		(start 138.10488 -286.716216)
		(end 138.113262 -286.721042)
		(width 0.09525)
		(layer "In13.Cu")
		(net "M_H_CPU1_SB_DQS_DP<7>")
	)
	(segment
		(start 147.474178 -287.396174)
		(end 147.474178 -287.506156)
		(width 0.09525)
		(layer "In13.Cu")
		(net "M_H_CPU1_SB_DQS_DP<7>")
	)
	(segment
		(start 147.688554 -287.720786)
		(end 147.688554 -287.80359)
		(width 0.09525)
		(layer "In13.Cu")
		(net "M_H_CPU1_SB_DQS_DP<7>")
	)
	(segment
		(start 146.077686 -286.669734)
		(end 146.573748 -287.165796)
		(width 0.09525)
		(layer "In13.Cu")
		(net "M_H_CPU1_SB_DQS_DP<7>")
	)
	(segment
		(start 166.91483 -304.794412)
		(end 169.71899 -304.794412)
		(width 0.16002)
		(layer "In13.Cu")
		(net "M_H_CPU1_SB_DQS_DP<7>")
	)
	(segment
		(start 159.920686 -305.105308)
		(end 160.457896 -305.642518)
		(width 0.16002)
		(layer "In13.Cu")
		(net "M_H_CPU1_SB_DQS_DP<7>")
	)
	(segment
		(start 156.925264 -301.638208)
		(end 156.925264 -302.114712)
		(width 0.16002)
		(layer "In13.Cu")
		(net "M_H_CPU1_SB_DQS_DP<7>")
	)
	(segment
		(start 162.048698 -304.905664)
		(end 162.498278 -304.905664)
		(width 0.16002)
		(layer "In13.Cu")
		(net "M_H_CPU1_SB_DQS_DP<7>")
	)
	(segment
		(start 144.505426 -286.669734)
		(end 146.077686 -286.669734)
		(width 0.09525)
		(layer "In13.Cu")
		(net "M_H_CPU1_SB_DQS_DP<7>")
	)
	(segment
		(start 171.702984 -305.016408)
		(end 171.97197 -305.285394)
		(width 0.16002)
		(layer "In13.Cu")
		(net "M_H_CPU1_SB_DQS_DP<7>")
	)
	(segment
		(start 135.104632 -287.046162)
		(end 134.950708 -286.780732)
		(width 0.09525)
		(layer "In13.Cu")
		(net "M_H_CPU1_SB_DQS_DP<7>")
	)
	(segment
		(start 161.55162 -305.642518)
		(end 161.888678 -305.30546)
		(width 0.16002)
		(layer "In13.Cu")
		(net "M_H_CPU1_SB_DQS_DP<7>")
	)
	(segment
		(start 146.573748 -287.165796)
		(end 147.2438 -287.165796)
		(width 0.09525)
		(layer "In13.Cu")
		(net "M_H_CPU1_SB_DQS_DP<7>")
	)
	(segment
		(start 157.420564 -302.610012)
		(end 157.897068 -302.610012)
		(width 0.16002)
		(layer "In13.Cu")
		(net "M_H_CPU1_SB_DQS_DP<7>")
	)
	(segment
		(start 159.375602 -304.08372)
		(end 159.606742 -303.85258)
		(width 0.16002)
		(layer "In13.Cu")
		(net "M_H_CPU1_SB_DQS_DP<7>")
	)
	(segment
		(start 140.556234 -286.721042)
		(end 140.564616 -286.716216)
		(width 0.09525)
		(layer "In13.Cu")
		(net "M_H_CPU1_SB_DQS_DP<7>")
	)
	(segment
		(start 159.832802 -303.85258)
		(end 160.151826 -304.171604)
		(width 0.16002)
		(layer "In13.Cu")
		(net "M_H_CPU1_SB_DQS_DP<7>")
	)
	(segment
		(start 159.606742 -303.85258)
		(end 159.832802 -303.85258)
		(width 0.16002)
		(layer "In13.Cu")
		(net "M_H_CPU1_SB_DQS_DP<7>")
	)
	(segment
		(start 156.597604 -300.8757)
		(end 156.823664 -300.8757)
		(width 0.16002)
		(layer "In13.Cu")
		(net "M_H_CPU1_SB_DQS_DP<7>")
	)
	(segment
		(start 144.31645 -286.721042)
		(end 144.31645 -286.720788)
		(width 0.09525)
		(layer "In13.Cu")
		(net "M_H_CPU1_SB_DQS_DP<7>")
	)
	(segment
		(start 166.066724 -305.642518)
		(end 166.91483 -304.794412)
		(width 0.16002)
		(layer "In13.Cu")
		(net "M_H_CPU1_SB_DQS_DP<7>")
	)
	(segment
		(start 139.61618 -286.721042)
		(end 139.624562 -286.716216)
		(width 0.09525)
		(layer "In13.Cu")
		(net "M_H_CPU1_SB_DQS_DP<7>")
	)
	(segment
		(start 160.151826 -304.397664)
		(end 159.920686 -304.628804)
		(width 0.16002)
		(layer "In13.Cu")
		(net "M_H_CPU1_SB_DQS_DP<7>")
	)
	(segment
		(start 134.950708 -286.780732)
		(end 134.974076 -286.693864)
		(width 0.09525)
		(layer "In13.Cu")
		(net "M_H_CPU1_SB_DQS_DP<7>")
	)
	(segment
		(start 155.903676 -301.093124)
		(end 156.38018 -301.093124)
		(width 0.16002)
		(layer "In13.Cu")
		(net "M_H_CPU1_SB_DQS_DP<7>")
	)
	(segment
		(start 159.920686 -304.628804)
		(end 159.920686 -305.105308)
		(width 0.16002)
		(layer "In13.Cu")
		(net "M_H_CPU1_SB_DQS_DP<7>")
	)
	(segment
		(start 147.2438 -287.165796)
		(end 147.474178 -287.396174)
		(width 0.09525)
		(layer "In13.Cu")
		(net "M_H_CPU1_SB_DQS_DP<7>")
	)
	(segment
		(start 158.114492 -302.392588)
		(end 158.340552 -302.392588)
		(width 0.16002)
		(layer "In13.Cu")
		(net "M_H_CPU1_SB_DQS_DP<7>")
	)
	(segment
		(start 157.142688 -301.420784)
		(end 156.925264 -301.638208)
		(width 0.16002)
		(layer "In13.Cu")
		(net "M_H_CPU1_SB_DQS_DP<7>")
	)
	(segment
		(start 158.340552 -302.392588)
		(end 158.659576 -302.711612)
		(width 0.16002)
		(layer "In13.Cu")
		(net "M_H_CPU1_SB_DQS_DP<7>")
	)
	(segment
		(start 157.142688 -301.194724)
		(end 157.142688 -301.420784)
		(width 0.16002)
		(layer "In13.Cu")
		(net "M_H_CPU1_SB_DQS_DP<7>")
	)
	(segment
		(start 139.044934 -286.716216)
		(end 139.053316 -286.721042)
		(width 0.09525)
		(layer "In13.Cu")
		(net "M_H_CPU1_SB_DQS_DP<7>")
	)
	(segment
		(start 135.856218 -286.721042)
		(end 135.8646 -286.716216)
		(width 0.09525)
		(layer "In13.Cu")
		(net "M_H_CPU1_SB_DQS_DP<7>")
	)
	(segment
		(start 157.897068 -302.610012)
		(end 158.114492 -302.392588)
		(width 0.16002)
		(layer "In13.Cu")
		(net "M_H_CPU1_SB_DQS_DP<7>")
	)
	(arc
		(start 140.564616 -286.716216)
		(mid 140.749648 -286.670302)
		(end 140.933424 -286.721042)
		(width 0.09525)
		(layer "In13.Cu")
		(net "M_H_CPU1_SB_DQS_DP<7>")
	)
	(arc
		(start 141.873224 -286.721042)
		(mid 142.154656 -286.796831)
		(end 142.436088 -286.721042)
		(width 0.09525)
		(layer "In13.Cu")
		(net "M_H_CPU1_SB_DQS_DP<7>")
	)
	(arc
		(start 139.053316 -286.721042)
		(mid 139.334748 -286.796831)
		(end 139.61618 -286.721042)
		(width 0.09525)
		(layer "In13.Cu")
		(net "M_H_CPU1_SB_DQS_DP<7>")
	)
	(arc
		(start 142.436088 -286.721042)
		(mid 142.619863 -286.67027)
		(end 142.804896 -286.716216)
		(width 0.09525)
		(layer "In13.Cu")
		(net "M_H_CPU1_SB_DQS_DP<7>")
	)
	(arc
		(start 143.763746 -286.727138)
		(mid 144.040908 -286.79697)
		(end 144.31645 -286.721042)
		(width 0.09525)
		(layer "In13.Cu")
		(net "M_H_CPU1_SB_DQS_DP<7>")
	)
	(arc
		(start 136.796272 -286.721042)
		(mid 136.98474 -286.670365)
		(end 137.173208 -286.721042)
		(width 0.09525)
		(layer "In13.Cu")
		(net "M_H_CPU1_SB_DQS_DP<7>")
	)
	(arc
		(start 138.113262 -286.721042)
		(mid 138.394694 -286.796831)
		(end 138.676126 -286.721042)
		(width 0.09525)
		(layer "In13.Cu")
		(net "M_H_CPU1_SB_DQS_DP<7>")
	)
	(arc
		(start 143.384524 -286.716216)
		(mid 143.569556 -286.670302)
		(end 143.753332 -286.721042)
		(width 0.09525)
		(layer "In13.Cu")
		(net "M_H_CPU1_SB_DQS_DP<7>")
	)
	(arc
		(start 137.173208 -286.721042)
		(mid 137.45464 -286.796831)
		(end 137.736072 -286.721042)
		(width 0.09525)
		(layer "In13.Cu")
		(net "M_H_CPU1_SB_DQS_DP<7>")
	)
	(arc
		(start 137.736072 -286.721042)
		(mid 137.919847 -286.67027)
		(end 138.10488 -286.716216)
		(width 0.09525)
		(layer "In13.Cu")
		(net "M_H_CPU1_SB_DQS_DP<7>")
	)
	(arc
		(start 142.813278 -286.721042)
		(mid 143.09471 -286.796831)
		(end 143.376142 -286.721042)
		(width 0.09525)
		(layer "In13.Cu")
		(net "M_H_CPU1_SB_DQS_DP<7>")
	)
	(arc
		(start 139.624562 -286.716216)
		(mid 139.809594 -286.670302)
		(end 139.99337 -286.721042)
		(width 0.09525)
		(layer "In13.Cu")
		(net "M_H_CPU1_SB_DQS_DP<7>")
	)
	(arc
		(start 139.99337 -286.721042)
		(mid 140.274802 -286.796831)
		(end 140.556234 -286.721042)
		(width 0.09525)
		(layer "In13.Cu")
		(net "M_H_CPU1_SB_DQS_DP<7>")
	)
	(arc
		(start 135.293354 -286.721042)
		(mid 135.574786 -286.796831)
		(end 135.856218 -286.721042)
		(width 0.09525)
		(layer "In13.Cu")
		(net "M_H_CPU1_SB_DQS_DP<7>")
	)
	(arc
		(start 141.496288 -286.721042)
		(mid 141.684756 -286.670365)
		(end 141.873224 -286.721042)
		(width 0.09525)
		(layer "In13.Cu")
		(net "M_H_CPU1_SB_DQS_DP<7>")
	)
	(arc
		(start 140.933424 -286.721042)
		(mid 141.214856 -286.796831)
		(end 141.496288 -286.721042)
		(width 0.09525)
		(layer "In13.Cu")
		(net "M_H_CPU1_SB_DQS_DP<7>")
	)
	(arc
		(start 138.676126 -286.721042)
		(mid 138.859901 -286.67027)
		(end 139.044934 -286.716216)
		(width 0.09525)
		(layer "In13.Cu")
		(net "M_H_CPU1_SB_DQS_DP<7>")
	)
	(arc
		(start 144.31645 -286.720788)
		(mid 144.407568 -286.682801)
		(end 144.505426 -286.669734)
		(width 0.09525)
		(layer "In13.Cu")
		(net "M_H_CPU1_SB_DQS_DP<7>")
	)
	(arc
		(start 134.974076 -286.693864)
		(mid 135.136758 -286.671732)
		(end 135.293354 -286.721042)
		(width 0.09525)
		(layer "In13.Cu")
		(net "M_H_CPU1_SB_DQS_DP<7>")
	)
	(arc
		(start 136.233408 -286.721042)
		(mid 136.51484 -286.796831)
		(end 136.796272 -286.721042)
		(width 0.09525)
		(layer "In13.Cu")
		(net "M_H_CPU1_SB_DQS_DP<7>")
	)
	(arc
		(start 135.8646 -286.716216)
		(mid 136.049632 -286.670302)
		(end 136.233408 -286.721042)
		(width 0.09525)
		(layer "In13.Cu")
		(net "M_H_CPU1_SB_DQS_DP<7>")
	)
	(segment
		(start 134.63778 -281.920442)
		(end 135.104632 -282.18638)
		(width 0.12954)
		(layer "F.Cu")
		(net "M_H_CPU1_SB_DQS_DP<6>")
	)
	(segment
		(start 144.323816 -281.856434)
		(end 144.315434 -281.86126)
		(width 0.09525)
		(layer "In13.Cu")
		(net "M_H_CPU1_SB_DQS_DP<6>")
	)
	(segment
		(start 158.985966 -293.367206)
		(end 158.509208 -293.367206)
		(width 0.16002)
		(layer "In13.Cu")
		(net "M_H_CPU1_SB_DQS_DP<6>")
	)
	(segment
		(start 147.673314 -282.120594)
		(end 147.649692 -282.120594)
		(width 0.09525)
		(layer "In13.Cu")
		(net "M_H_CPU1_SB_DQS_DP<6>")
	)
	(segment
		(start 145.617438 -281.809444)
		(end 145.444972 -281.809444)
		(width 0.09525)
		(layer "In13.Cu")
		(net "M_H_CPU1_SB_DQS_DP<6>")
	)
	(segment
		(start 159.327342 -294.114474)
		(end 160.247076 -293.19474)
		(width 0.16002)
		(layer "In13.Cu")
		(net "M_H_CPU1_SB_DQS_DP<6>")
	)
	(segment
		(start 164.183568 -295.948862)
		(end 164.023548 -295.788842)
		(width 0.16002)
		(layer "In13.Cu")
		(net "M_H_CPU1_SB_DQS_DP<6>")
	)
	(segment
		(start 171.705778 -295.669208)
		(end 169.94378 -295.669208)
		(width 0.16002)
		(layer "In13.Cu")
		(net "M_H_CPU1_SB_DQS_DP<6>")
	)
	(segment
		(start 143.384524 -281.856434)
		(end 143.376142 -281.86126)
		(width 0.09525)
		(layer "In13.Cu")
		(net "M_H_CPU1_SB_DQS_DP<6>")
	)
	(segment
		(start 161.38779 -296.65168)
		(end 159.327342 -294.591232)
		(width 0.16002)
		(layer "In13.Cu")
		(net "M_H_CPU1_SB_DQS_DP<6>")
	)
	(segment
		(start 146.816572 -282.061666)
		(end 146.600926 -281.84602)
		(width 0.09525)
		(layer "In13.Cu")
		(net "M_H_CPU1_SB_DQS_DP<6>")
	)
	(segment
		(start 140.564616 -281.856434)
		(end 140.556234 -281.86126)
		(width 0.09525)
		(layer "In13.Cu")
		(net "M_H_CPU1_SB_DQS_DP<6>")
	)
	(segment
		(start 158.17215 -290.42487)
		(end 149.867874 -282.120594)
		(width 0.16002)
		(layer "In13.Cu")
		(net "M_H_CPU1_SB_DQS_DP<6>")
	)
	(segment
		(start 164.520626 -296.65168)
		(end 164.183568 -296.314622)
		(width 0.16002)
		(layer "In13.Cu")
		(net "M_H_CPU1_SB_DQS_DP<6>")
	)
	(segment
		(start 160.247076 -292.96868)
		(end 159.928814 -292.650418)
		(width 0.16002)
		(layer "In13.Cu")
		(net "M_H_CPU1_SB_DQS_DP<6>")
	)
	(segment
		(start 158.509208 -293.367206)
		(end 158.17215 -293.030148)
		(width 0.16002)
		(layer "In13.Cu")
		(net "M_H_CPU1_SB_DQS_DP<6>")
	)
	(segment
		(start 166.06139 -296.297858)
		(end 165.560756 -296.297858)
		(width 0.16002)
		(layer "In13.Cu")
		(net "M_H_CPU1_SB_DQS_DP<6>")
	)
	(segment
		(start 135.8646 -281.856434)
		(end 135.856218 -281.86126)
		(width 0.09525)
		(layer "In13.Cu")
		(net "M_H_CPU1_SB_DQS_DP<6>")
	)
	(segment
		(start 145.617692 -281.809698)
		(end 145.617438 -281.809444)
		(width 0.09525)
		(layer "In13.Cu")
		(net "M_H_CPU1_SB_DQS_DP<6>")
	)
	(segment
		(start 142.813278 -281.86126)
		(end 142.804896 -281.856434)
		(width 0.09525)
		(layer "In13.Cu")
		(net "M_H_CPU1_SB_DQS_DP<6>")
	)
	(segment
		(start 163.07689 -296.65168)
		(end 161.38779 -296.65168)
		(width 0.16002)
		(layer "In13.Cu")
		(net "M_H_CPU1_SB_DQS_DP<6>")
	)
	(segment
		(start 163.413948 -296.314622)
		(end 163.07689 -296.65168)
		(width 0.16002)
		(layer "In13.Cu")
		(net "M_H_CPU1_SB_DQS_DP<6>")
	)
	(segment
		(start 139.624562 -281.856434)
		(end 139.61618 -281.86126)
		(width 0.09525)
		(layer "In13.Cu")
		(net "M_H_CPU1_SB_DQS_DP<6>")
	)
	(segment
		(start 163.573968 -295.788842)
		(end 163.413948 -295.948862)
		(width 0.16002)
		(layer "In13.Cu")
		(net "M_H_CPU1_SB_DQS_DP<6>")
	)
	(segment
		(start 169.94378 -295.669208)
		(end 169.71899 -295.444418)
		(width 0.16002)
		(layer "In13.Cu")
		(net "M_H_CPU1_SB_DQS_DP<6>")
	)
	(segment
		(start 158.17215 -293.030148)
		(end 158.17215 -290.42487)
		(width 0.16002)
		(layer "In13.Cu")
		(net "M_H_CPU1_SB_DQS_DP<6>")
	)
	(segment
		(start 171.97197 -295.9354)
		(end 171.705778 -295.669208)
		(width 0.16002)
		(layer "In13.Cu")
		(net "M_H_CPU1_SB_DQS_DP<6>")
	)
	(segment
		(start 144.71015 -281.871674)
		(end 144.692116 -281.86126)
		(width 0.09525)
		(layer "In13.Cu")
		(net "M_H_CPU1_SB_DQS_DP<6>")
	)
	(segment
		(start 149.867874 -282.120594)
		(end 147.673314 -282.120594)
		(width 0.16002)
		(layer "In13.Cu")
		(net "M_H_CPU1_SB_DQS_DP<6>")
	)
	(segment
		(start 160.247076 -293.19474)
		(end 160.247076 -292.96868)
		(width 0.16002)
		(layer "In13.Cu")
		(net "M_H_CPU1_SB_DQS_DP<6>")
	)
	(segment
		(start 164.183568 -296.314622)
		(end 164.183568 -295.948862)
		(width 0.16002)
		(layer "In13.Cu")
		(net "M_H_CPU1_SB_DQS_DP<6>")
	)
	(segment
		(start 147.590764 -282.061666)
		(end 146.816572 -282.061666)
		(width 0.09525)
		(layer "In13.Cu")
		(net "M_H_CPU1_SB_DQS_DP<6>")
	)
	(segment
		(start 165.206934 -296.65168)
		(end 164.520626 -296.65168)
		(width 0.16002)
		(layer "In13.Cu")
		(net "M_H_CPU1_SB_DQS_DP<6>")
	)
	(segment
		(start 166.91483 -295.444418)
		(end 166.06139 -296.297858)
		(width 0.16002)
		(layer "In13.Cu")
		(net "M_H_CPU1_SB_DQS_DP<6>")
	)
	(segment
		(start 134.974076 -281.834082)
		(end 134.950708 -281.92095)
		(width 0.09525)
		(layer "In13.Cu")
		(net "M_H_CPU1_SB_DQS_DP<6>")
	)
	(segment
		(start 138.113262 -281.86126)
		(end 138.10488 -281.856434)
		(width 0.09525)
		(layer "In13.Cu")
		(net "M_H_CPU1_SB_DQS_DP<6>")
	)
	(segment
		(start 144.315434 -281.86126)
		(end 144.2974 -281.871674)
		(width 0.09525)
		(layer "In13.Cu")
		(net "M_H_CPU1_SB_DQS_DP<6>")
	)
	(segment
		(start 159.327342 -294.591232)
		(end 159.327342 -294.114474)
		(width 0.16002)
		(layer "In13.Cu")
		(net "M_H_CPU1_SB_DQS_DP<6>")
	)
	(segment
		(start 159.702754 -292.650418)
		(end 158.985966 -293.367206)
		(width 0.16002)
		(layer "In13.Cu")
		(net "M_H_CPU1_SB_DQS_DP<6>")
	)
	(segment
		(start 139.053316 -281.86126)
		(end 139.044934 -281.856434)
		(width 0.09525)
		(layer "In13.Cu")
		(net "M_H_CPU1_SB_DQS_DP<6>")
	)
	(segment
		(start 169.71899 -295.444418)
		(end 166.91483 -295.444418)
		(width 0.16002)
		(layer "In13.Cu")
		(net "M_H_CPU1_SB_DQS_DP<6>")
	)
	(segment
		(start 163.413948 -295.948862)
		(end 163.413948 -296.314622)
		(width 0.16002)
		(layer "In13.Cu")
		(net "M_H_CPU1_SB_DQS_DP<6>")
	)
	(segment
		(start 164.023548 -295.788842)
		(end 163.573968 -295.788842)
		(width 0.16002)
		(layer "In13.Cu")
		(net "M_H_CPU1_SB_DQS_DP<6>")
	)
	(segment
		(start 146.485864 -281.809698)
		(end 145.617692 -281.809698)
		(width 0.09525)
		(layer "In13.Cu")
		(net "M_H_CPU1_SB_DQS_DP<6>")
	)
	(segment
		(start 147.649692 -282.120594)
		(end 147.590764 -282.061666)
		(width 0.09525)
		(layer "In13.Cu")
		(net "M_H_CPU1_SB_DQS_DP<6>")
	)
	(segment
		(start 159.928814 -292.650418)
		(end 159.702754 -292.650418)
		(width 0.16002)
		(layer "In13.Cu")
		(net "M_H_CPU1_SB_DQS_DP<6>")
	)
	(segment
		(start 134.950708 -281.92095)
		(end 135.104632 -282.18638)
		(width 0.09525)
		(layer "In13.Cu")
		(net "M_H_CPU1_SB_DQS_DP<6>")
	)
	(segment
		(start 165.560756 -296.297858)
		(end 165.206934 -296.65168)
		(width 0.16002)
		(layer "In13.Cu")
		(net "M_H_CPU1_SB_DQS_DP<6>")
	)
	(arc
		(start 142.804896 -281.856434)
		(mid 142.619864 -281.81052)
		(end 142.436088 -281.86126)
		(width 0.09525)
		(layer "In13.Cu")
		(net "M_H_CPU1_SB_DQS_DP<6>")
	)
	(arc
		(start 141.496288 -281.86126)
		(mid 141.214856 -281.937015)
		(end 140.933424 -281.86126)
		(width 0.09525)
		(layer "In13.Cu")
		(net "M_H_CPU1_SB_DQS_DP<6>")
	)
	(arc
		(start 142.436088 -281.86126)
		(mid 142.154656 -281.937015)
		(end 141.873224 -281.86126)
		(width 0.09525)
		(layer "In13.Cu")
		(net "M_H_CPU1_SB_DQS_DP<6>")
	)
	(arc
		(start 143.753332 -281.86126)
		(mid 143.569557 -281.810488)
		(end 143.384524 -281.856434)
		(width 0.09525)
		(layer "In13.Cu")
		(net "M_H_CPU1_SB_DQS_DP<6>")
	)
	(arc
		(start 140.933424 -281.86126)
		(mid 140.749649 -281.810488)
		(end 140.564616 -281.856434)
		(width 0.09525)
		(layer "In13.Cu")
		(net "M_H_CPU1_SB_DQS_DP<6>")
	)
	(arc
		(start 137.173208 -281.86126)
		(mid 136.98474 -281.810583)
		(end 136.796272 -281.86126)
		(width 0.09525)
		(layer "In13.Cu")
		(net "M_H_CPU1_SB_DQS_DP<6>")
	)
	(arc
		(start 146.600926 -281.84602)
		(mid 146.546179 -281.819023)
		(end 146.485864 -281.809698)
		(width 0.09525)
		(layer "In13.Cu")
		(net "M_H_CPU1_SB_DQS_DP<6>")
	)
	(arc
		(start 145.444972 -281.809444)
		(mid 145.346912 -281.822784)
		(end 145.255742 -281.86126)
		(width 0.09525)
		(layer "In13.Cu")
		(net "M_H_CPU1_SB_DQS_DP<6>")
	)
	(arc
		(start 135.293354 -281.86126)
		(mid 135.136756 -281.811971)
		(end 134.974076 -281.834082)
		(width 0.09525)
		(layer "In13.Cu")
		(net "M_H_CPU1_SB_DQS_DP<6>")
	)
	(arc
		(start 137.736072 -281.86126)
		(mid 137.45464 -281.937015)
		(end 137.173208 -281.86126)
		(width 0.09525)
		(layer "In13.Cu")
		(net "M_H_CPU1_SB_DQS_DP<6>")
	)
	(arc
		(start 139.044934 -281.856434)
		(mid 138.859902 -281.81052)
		(end 138.676126 -281.86126)
		(width 0.09525)
		(layer "In13.Cu")
		(net "M_H_CPU1_SB_DQS_DP<6>")
	)
	(arc
		(start 136.796272 -281.86126)
		(mid 136.51484 -281.937015)
		(end 136.233408 -281.86126)
		(width 0.09525)
		(layer "In13.Cu")
		(net "M_H_CPU1_SB_DQS_DP<6>")
	)
	(arc
		(start 136.233408 -281.86126)
		(mid 136.049633 -281.810488)
		(end 135.8646 -281.856434)
		(width 0.09525)
		(layer "In13.Cu")
		(net "M_H_CPU1_SB_DQS_DP<6>")
	)
	(arc
		(start 139.99337 -281.86126)
		(mid 139.809595 -281.810488)
		(end 139.624562 -281.856434)
		(width 0.09525)
		(layer "In13.Cu")
		(net "M_H_CPU1_SB_DQS_DP<6>")
	)
	(arc
		(start 144.2974 -281.871674)
		(mid 144.02402 -281.936895)
		(end 143.753332 -281.86126)
		(width 0.09525)
		(layer "In13.Cu")
		(net "M_H_CPU1_SB_DQS_DP<6>")
	)
	(arc
		(start 138.676126 -281.86126)
		(mid 138.394694 -281.937015)
		(end 138.113262 -281.86126)
		(width 0.09525)
		(layer "In13.Cu")
		(net "M_H_CPU1_SB_DQS_DP<6>")
	)
	(arc
		(start 139.61618 -281.86126)
		(mid 139.334748 -281.937015)
		(end 139.053316 -281.86126)
		(width 0.09525)
		(layer "In13.Cu")
		(net "M_H_CPU1_SB_DQS_DP<6>")
	)
	(arc
		(start 144.692116 -281.86126)
		(mid 144.508595 -281.810616)
		(end 144.323816 -281.856434)
		(width 0.09525)
		(layer "In13.Cu")
		(net "M_H_CPU1_SB_DQS_DP<6>")
	)
	(arc
		(start 140.556234 -281.86126)
		(mid 140.274802 -281.937015)
		(end 139.99337 -281.86126)
		(width 0.09525)
		(layer "In13.Cu")
		(net "M_H_CPU1_SB_DQS_DP<6>")
	)
	(arc
		(start 135.856218 -281.86126)
		(mid 135.574786 -281.937015)
		(end 135.293354 -281.86126)
		(width 0.09525)
		(layer "In13.Cu")
		(net "M_H_CPU1_SB_DQS_DP<6>")
	)
	(arc
		(start 141.873224 -281.86126)
		(mid 141.684756 -281.810583)
		(end 141.496288 -281.86126)
		(width 0.09525)
		(layer "In13.Cu")
		(net "M_H_CPU1_SB_DQS_DP<6>")
	)
	(arc
		(start 145.255742 -281.86126)
		(mid 144.984292 -281.937295)
		(end 144.71015 -281.871674)
		(width 0.09525)
		(layer "In13.Cu")
		(net "M_H_CPU1_SB_DQS_DP<6>")
	)
	(arc
		(start 138.10488 -281.856434)
		(mid 137.919848 -281.81052)
		(end 137.736072 -281.86126)
		(width 0.09525)
		(layer "In13.Cu")
		(net "M_H_CPU1_SB_DQS_DP<6>")
	)
	(arc
		(start 143.376142 -281.86126)
		(mid 143.09471 -281.937015)
		(end 142.813278 -281.86126)
		(width 0.09525)
		(layer "In13.Cu")
		(net "M_H_CPU1_SB_DQS_DP<6>")
	)
	(segment
		(start 134.63778 -277.060406)
		(end 135.104632 -277.326344)
		(width 0.12954)
		(layer "F.Cu")
		(net "M_H_CPU1_SB_DQS_DP<5>")
	)
	(segment
		(start 144.323816 -276.996398)
		(end 144.315434 -277.001224)
		(width 0.09525)
		(layer "In13.Cu")
		(net "M_H_CPU1_SB_DQS_DP<5>")
	)
	(segment
		(start 161.05124 -284.498288)
		(end 161.184844 -284.364684)
		(width 0.16002)
		(layer "In13.Cu")
		(net "M_H_CPU1_SB_DQS_DP<5>")
	)
	(segment
		(start 159.122872 -282.302712)
		(end 158.989268 -282.436316)
		(width 0.16002)
		(layer "In13.Cu")
		(net "M_H_CPU1_SB_DQS_DP<5>")
	)
	(segment
		(start 159.348932 -282.302712)
		(end 159.122872 -282.302712)
		(width 0.16002)
		(layer "In13.Cu")
		(net "M_H_CPU1_SB_DQS_DP<5>")
	)
	(segment
		(start 145.788634 -276.711156)
		(end 145.360644 -276.958298)
		(width 0.09525)
		(layer "In13.Cu")
		(net "M_H_CPU1_SB_DQS_DP<5>")
	)
	(segment
		(start 160.63976 -283.8196)
		(end 160.506156 -283.953204)
		(width 0.16002)
		(layer "In13.Cu")
		(net "M_H_CPU1_SB_DQS_DP<5>")
	)
	(segment
		(start 134.974076 -276.974046)
		(end 134.950708 -277.060914)
		(width 0.09525)
		(layer "In13.Cu")
		(net "M_H_CPU1_SB_DQS_DP<5>")
	)
	(segment
		(start 156.63418 -279.58796)
		(end 156.315156 -279.268936)
		(width 0.16002)
		(layer "In13.Cu")
		(net "M_H_CPU1_SB_DQS_DP<5>")
	)
	(segment
		(start 163.757102 -285.836106)
		(end 162.898074 -285.836106)
		(width 0.16002)
		(layer "In13.Cu")
		(net "M_H_CPU1_SB_DQS_DP<5>")
	)
	(segment
		(start 162.898074 -285.836106)
		(end 162.40887 -285.346902)
		(width 0.16002)
		(layer "In13.Cu")
		(net "M_H_CPU1_SB_DQS_DP<5>")
	)
	(segment
		(start 135.8646 -276.996398)
		(end 135.856218 -277.001224)
		(width 0.09525)
		(layer "In13.Cu")
		(net "M_H_CPU1_SB_DQS_DP<5>")
	)
	(segment
		(start 159.667956 -282.621736)
		(end 159.348932 -282.302712)
		(width 0.16002)
		(layer "In13.Cu")
		(net "M_H_CPU1_SB_DQS_DP<5>")
	)
	(segment
		(start 159.667956 -282.847796)
		(end 159.667956 -282.621736)
		(width 0.16002)
		(layer "In13.Cu")
		(net "M_H_CPU1_SB_DQS_DP<5>")
	)
	(segment
		(start 158.512764 -282.436316)
		(end 158.017464 -281.941016)
		(width 0.16002)
		(layer "In13.Cu")
		(net "M_H_CPU1_SB_DQS_DP<5>")
	)
	(segment
		(start 161.184844 -284.364684)
		(end 161.184844 -284.138624)
		(width 0.16002)
		(layer "In13.Cu")
		(net "M_H_CPU1_SB_DQS_DP<5>")
	)
	(segment
		(start 171.97197 -286.585406)
		(end 171.685712 -286.299148)
		(width 0.16002)
		(layer "In13.Cu")
		(net "M_H_CPU1_SB_DQS_DP<5>")
	)
	(segment
		(start 147.468336 -276.036532)
		(end 147.293838 -275.862034)
		(width 0.09525)
		(layer "In13.Cu")
		(net "M_H_CPU1_SB_DQS_DP<5>")
	)
	(segment
		(start 145.360644 -276.958298)
		(end 145.339562 -276.964648)
		(width 0.09525)
		(layer "In13.Cu")
		(net "M_H_CPU1_SB_DQS_DP<5>")
	)
	(segment
		(start 138.113262 -277.001224)
		(end 138.10488 -276.996398)
		(width 0.09525)
		(layer "In13.Cu")
		(net "M_H_CPU1_SB_DQS_DP<5>")
	)
	(segment
		(start 159.534352 -282.9814)
		(end 159.667956 -282.847796)
		(width 0.16002)
		(layer "In13.Cu")
		(net "M_H_CPU1_SB_DQS_DP<5>")
	)
	(segment
		(start 146.781012 -275.862034)
		(end 146.294348 -276.348698)
		(width 0.09525)
		(layer "In13.Cu")
		(net "M_H_CPU1_SB_DQS_DP<5>")
	)
	(segment
		(start 139.053316 -277.001224)
		(end 139.044934 -276.996398)
		(width 0.09525)
		(layer "In13.Cu")
		(net "M_H_CPU1_SB_DQS_DP<5>")
	)
	(segment
		(start 155.955492 -279.40254)
		(end 155.478988 -279.40254)
		(width 0.16002)
		(layer "In13.Cu")
		(net "M_H_CPU1_SB_DQS_DP<5>")
	)
	(segment
		(start 139.624562 -276.996398)
		(end 139.61618 -277.001224)
		(width 0.09525)
		(layer "In13.Cu")
		(net "M_H_CPU1_SB_DQS_DP<5>")
	)
	(segment
		(start 161.05124 -284.974792)
		(end 161.05124 -284.498288)
		(width 0.16002)
		(layer "In13.Cu")
		(net "M_H_CPU1_SB_DQS_DP<5>")
	)
	(segment
		(start 142.813278 -277.001224)
		(end 142.804896 -276.996398)
		(width 0.09525)
		(layer "In13.Cu")
		(net "M_H_CPU1_SB_DQS_DP<5>")
	)
	(segment
		(start 156.089096 -279.268936)
		(end 155.955492 -279.40254)
		(width 0.16002)
		(layer "In13.Cu")
		(net "M_H_CPU1_SB_DQS_DP<5>")
	)
	(segment
		(start 164.86886 -286.947864)
		(end 163.757102 -285.836106)
		(width 0.16002)
		(layer "In13.Cu")
		(net "M_H_CPU1_SB_DQS_DP<5>")
	)
	(segment
		(start 147.293838 -275.862034)
		(end 146.781012 -275.862034)
		(width 0.09525)
		(layer "In13.Cu")
		(net "M_H_CPU1_SB_DQS_DP<5>")
	)
	(segment
		(start 147.83054 -276.09546)
		(end 147.771612 -276.036532)
		(width 0.09525)
		(layer "In13.Cu")
		(net "M_H_CPU1_SB_DQS_DP<5>")
	)
	(segment
		(start 159.534352 -283.457904)
		(end 159.534352 -282.9814)
		(width 0.16002)
		(layer "In13.Cu")
		(net "M_H_CPU1_SB_DQS_DP<5>")
	)
	(segment
		(start 156.500576 -279.947624)
		(end 156.63418 -279.81402)
		(width 0.16002)
		(layer "In13.Cu")
		(net "M_H_CPU1_SB_DQS_DP<5>")
	)
	(segment
		(start 162.40887 -285.346902)
		(end 161.42335 -285.346902)
		(width 0.16002)
		(layer "In13.Cu")
		(net "M_H_CPU1_SB_DQS_DP<5>")
	)
	(segment
		(start 160.029652 -283.953204)
		(end 159.534352 -283.457904)
		(width 0.16002)
		(layer "In13.Cu")
		(net "M_H_CPU1_SB_DQS_DP<5>")
	)
	(segment
		(start 156.315156 -279.268936)
		(end 156.089096 -279.268936)
		(width 0.16002)
		(layer "In13.Cu")
		(net "M_H_CPU1_SB_DQS_DP<5>")
	)
	(segment
		(start 144.71015 -277.011638)
		(end 144.692116 -277.001224)
		(width 0.09525)
		(layer "In13.Cu")
		(net "M_H_CPU1_SB_DQS_DP<5>")
	)
	(segment
		(start 157.832044 -280.785824)
		(end 157.605984 -280.785824)
		(width 0.16002)
		(layer "In13.Cu")
		(net "M_H_CPU1_SB_DQS_DP<5>")
	)
	(segment
		(start 166.06139 -286.947864)
		(end 164.86886 -286.947864)
		(width 0.16002)
		(layer "In13.Cu")
		(net "M_H_CPU1_SB_DQS_DP<5>")
	)
	(segment
		(start 166.91483 -286.094424)
		(end 166.06139 -286.947864)
		(width 0.16002)
		(layer "In13.Cu")
		(net "M_H_CPU1_SB_DQS_DP<5>")
	)
	(segment
		(start 161.184844 -284.138624)
		(end 160.86582 -283.8196)
		(width 0.16002)
		(layer "In13.Cu")
		(net "M_H_CPU1_SB_DQS_DP<5>")
	)
	(segment
		(start 156.63418 -279.81402)
		(end 156.63418 -279.58796)
		(width 0.16002)
		(layer "In13.Cu")
		(net "M_H_CPU1_SB_DQS_DP<5>")
	)
	(segment
		(start 171.685712 -286.299148)
		(end 170.128946 -286.299148)
		(width 0.16002)
		(layer "In13.Cu")
		(net "M_H_CPU1_SB_DQS_DP<5>")
	)
	(segment
		(start 156.500576 -280.424128)
		(end 156.500576 -279.947624)
		(width 0.16002)
		(layer "In13.Cu")
		(net "M_H_CPU1_SB_DQS_DP<5>")
	)
	(segment
		(start 147.771612 -276.036532)
		(end 147.468336 -276.036532)
		(width 0.09525)
		(layer "In13.Cu")
		(net "M_H_CPU1_SB_DQS_DP<5>")
	)
	(segment
		(start 157.605984 -280.785824)
		(end 157.47238 -280.919428)
		(width 0.16002)
		(layer "In13.Cu")
		(net "M_H_CPU1_SB_DQS_DP<5>")
	)
	(segment
		(start 147.854162 -276.09546)
		(end 147.83054 -276.09546)
		(width 0.09525)
		(layer "In13.Cu")
		(net "M_H_CPU1_SB_DQS_DP<5>")
	)
	(segment
		(start 155.478988 -279.40254)
		(end 152.171908 -276.09546)
		(width 0.16002)
		(layer "In13.Cu")
		(net "M_H_CPU1_SB_DQS_DP<5>")
	)
	(segment
		(start 161.42335 -285.346902)
		(end 161.05124 -284.974792)
		(width 0.16002)
		(layer "In13.Cu")
		(net "M_H_CPU1_SB_DQS_DP<5>")
	)
	(segment
		(start 160.506156 -283.953204)
		(end 160.029652 -283.953204)
		(width 0.16002)
		(layer "In13.Cu")
		(net "M_H_CPU1_SB_DQS_DP<5>")
	)
	(segment
		(start 158.151068 -281.104848)
		(end 157.832044 -280.785824)
		(width 0.16002)
		(layer "In13.Cu")
		(net "M_H_CPU1_SB_DQS_DP<5>")
	)
	(segment
		(start 156.995876 -280.919428)
		(end 156.500576 -280.424128)
		(width 0.16002)
		(layer "In13.Cu")
		(net "M_H_CPU1_SB_DQS_DP<5>")
	)
	(segment
		(start 158.151068 -281.330908)
		(end 158.151068 -281.104848)
		(width 0.16002)
		(layer "In13.Cu")
		(net "M_H_CPU1_SB_DQS_DP<5>")
	)
	(segment
		(start 170.128946 -286.299148)
		(end 169.924222 -286.094424)
		(width 0.16002)
		(layer "In13.Cu")
		(net "M_H_CPU1_SB_DQS_DP<5>")
	)
	(segment
		(start 160.86582 -283.8196)
		(end 160.63976 -283.8196)
		(width 0.16002)
		(layer "In13.Cu")
		(net "M_H_CPU1_SB_DQS_DP<5>")
	)
	(segment
		(start 152.171908 -276.09546)
		(end 147.854162 -276.09546)
		(width 0.16002)
		(layer "In13.Cu")
		(net "M_H_CPU1_SB_DQS_DP<5>")
	)
	(segment
		(start 158.017464 -281.464512)
		(end 158.151068 -281.330908)
		(width 0.16002)
		(layer "In13.Cu")
		(net "M_H_CPU1_SB_DQS_DP<5>")
	)
	(segment
		(start 158.017464 -281.941016)
		(end 158.017464 -281.464512)
		(width 0.16002)
		(layer "In13.Cu")
		(net "M_H_CPU1_SB_DQS_DP<5>")
	)
	(segment
		(start 157.47238 -280.919428)
		(end 156.995876 -280.919428)
		(width 0.16002)
		(layer "In13.Cu")
		(net "M_H_CPU1_SB_DQS_DP<5>")
	)
	(segment
		(start 158.989268 -282.436316)
		(end 158.512764 -282.436316)
		(width 0.16002)
		(layer "In13.Cu")
		(net "M_H_CPU1_SB_DQS_DP<5>")
	)
	(segment
		(start 134.950708 -277.060914)
		(end 135.104632 -277.326344)
		(width 0.09525)
		(layer "In13.Cu")
		(net "M_H_CPU1_SB_DQS_DP<5>")
	)
	(segment
		(start 145.797524 -276.706838)
		(end 145.788634 -276.711156)
		(width 0.09525)
		(layer "In13.Cu")
		(net "M_H_CPU1_SB_DQS_DP<5>")
	)
	(segment
		(start 140.564616 -276.996398)
		(end 140.556234 -277.001224)
		(width 0.09525)
		(layer "In13.Cu")
		(net "M_H_CPU1_SB_DQS_DP<5>")
	)
	(segment
		(start 144.315434 -277.001224)
		(end 144.2974 -277.011638)
		(width 0.09525)
		(layer "In13.Cu")
		(net "M_H_CPU1_SB_DQS_DP<5>")
	)
	(segment
		(start 169.924222 -286.094424)
		(end 166.91483 -286.094424)
		(width 0.16002)
		(layer "In13.Cu")
		(net "M_H_CPU1_SB_DQS_DP<5>")
	)
	(segment
		(start 143.384524 -276.996398)
		(end 143.376142 -277.001224)
		(width 0.09525)
		(layer "In13.Cu")
		(net "M_H_CPU1_SB_DQS_DP<5>")
	)
	(arc
		(start 141.873224 -277.001224)
		(mid 141.684756 -276.950547)
		(end 141.496288 -277.001224)
		(width 0.09525)
		(layer "In13.Cu")
		(net "M_H_CPU1_SB_DQS_DP<5>")
	)
	(arc
		(start 140.556234 -277.001224)
		(mid 140.274802 -277.076979)
		(end 139.99337 -277.001224)
		(width 0.09525)
		(layer "In13.Cu")
		(net "M_H_CPU1_SB_DQS_DP<5>")
	)
	(arc
		(start 144.2974 -277.011638)
		(mid 144.02402 -277.076859)
		(end 143.753332 -277.001224)
		(width 0.09525)
		(layer "In13.Cu")
		(net "M_H_CPU1_SB_DQS_DP<5>")
	)
	(arc
		(start 138.10488 -276.996398)
		(mid 137.919848 -276.950484)
		(end 137.736072 -277.001224)
		(width 0.09525)
		(layer "In13.Cu")
		(net "M_H_CPU1_SB_DQS_DP<5>")
	)
	(arc
		(start 139.044934 -276.996398)
		(mid 138.859902 -276.950484)
		(end 138.676126 -277.001224)
		(width 0.09525)
		(layer "In13.Cu")
		(net "M_H_CPU1_SB_DQS_DP<5>")
	)
	(arc
		(start 142.804896 -276.996398)
		(mid 142.619864 -276.950484)
		(end 142.436088 -277.001224)
		(width 0.09525)
		(layer "In13.Cu")
		(net "M_H_CPU1_SB_DQS_DP<5>")
	)
	(arc
		(start 139.61618 -277.001224)
		(mid 139.334748 -277.076979)
		(end 139.053316 -277.001224)
		(width 0.09525)
		(layer "In13.Cu")
		(net "M_H_CPU1_SB_DQS_DP<5>")
	)
	(arc
		(start 142.436088 -277.001224)
		(mid 142.154656 -277.076979)
		(end 141.873224 -277.001224)
		(width 0.09525)
		(layer "In13.Cu")
		(net "M_H_CPU1_SB_DQS_DP<5>")
	)
	(arc
		(start 136.796272 -277.001224)
		(mid 136.51484 -277.076979)
		(end 136.233408 -277.001224)
		(width 0.09525)
		(layer "In13.Cu")
		(net "M_H_CPU1_SB_DQS_DP<5>")
	)
	(arc
		(start 139.99337 -277.001224)
		(mid 139.809595 -276.950452)
		(end 139.624562 -276.996398)
		(width 0.09525)
		(layer "In13.Cu")
		(net "M_H_CPU1_SB_DQS_DP<5>")
	)
	(arc
		(start 143.753332 -277.001224)
		(mid 143.569557 -276.950452)
		(end 143.384524 -276.996398)
		(width 0.09525)
		(layer "In13.Cu")
		(net "M_H_CPU1_SB_DQS_DP<5>")
	)
	(arc
		(start 145.339562 -276.964648)
		(mid 145.296442 -276.98001)
		(end 145.255488 -277.000462)
		(width 0.09525)
		(layer "In13.Cu")
		(net "M_H_CPU1_SB_DQS_DP<5>")
	)
	(arc
		(start 135.293354 -277.001224)
		(mid 135.136756 -276.951935)
		(end 134.974076 -276.974046)
		(width 0.09525)
		(layer "In13.Cu")
		(net "M_H_CPU1_SB_DQS_DP<5>")
	)
	(arc
		(start 145.255488 -277.000462)
		(mid 145.255614 -277.000843)
		(end 145.255742 -277.001224)
		(width 0.09525)
		(layer "In13.Cu")
		(net "M_H_CPU1_SB_DQS_DP<5>")
	)
	(arc
		(start 143.376142 -277.001224)
		(mid 143.09471 -277.076979)
		(end 142.813278 -277.001224)
		(width 0.09525)
		(layer "In13.Cu")
		(net "M_H_CPU1_SB_DQS_DP<5>")
	)
	(arc
		(start 141.496288 -277.001224)
		(mid 141.214856 -277.076979)
		(end 140.933424 -277.001224)
		(width 0.09525)
		(layer "In13.Cu")
		(net "M_H_CPU1_SB_DQS_DP<5>")
	)
	(arc
		(start 137.173208 -277.001224)
		(mid 136.98474 -276.950547)
		(end 136.796272 -277.001224)
		(width 0.09525)
		(layer "In13.Cu")
		(net "M_H_CPU1_SB_DQS_DP<5>")
	)
	(arc
		(start 138.676126 -277.001224)
		(mid 138.394694 -277.076979)
		(end 138.113262 -277.001224)
		(width 0.09525)
		(layer "In13.Cu")
		(net "M_H_CPU1_SB_DQS_DP<5>")
	)
	(arc
		(start 145.255742 -277.001224)
		(mid 144.984292 -277.077259)
		(end 144.71015 -277.011638)
		(width 0.09525)
		(layer "In13.Cu")
		(net "M_H_CPU1_SB_DQS_DP<5>")
	)
	(arc
		(start 135.856218 -277.001224)
		(mid 135.574786 -277.076979)
		(end 135.293354 -277.001224)
		(width 0.09525)
		(layer "In13.Cu")
		(net "M_H_CPU1_SB_DQS_DP<5>")
	)
	(arc
		(start 136.233408 -277.001224)
		(mid 136.049633 -276.950452)
		(end 135.8646 -276.996398)
		(width 0.09525)
		(layer "In13.Cu")
		(net "M_H_CPU1_SB_DQS_DP<5>")
	)
	(arc
		(start 137.736072 -277.001224)
		(mid 137.45464 -277.076979)
		(end 137.173208 -277.001224)
		(width 0.09525)
		(layer "In13.Cu")
		(net "M_H_CPU1_SB_DQS_DP<5>")
	)
	(arc
		(start 140.933424 -277.001224)
		(mid 140.749649 -276.950452)
		(end 140.564616 -276.996398)
		(width 0.09525)
		(layer "In13.Cu")
		(net "M_H_CPU1_SB_DQS_DP<5>")
	)
	(arc
		(start 146.294348 -276.348698)
		(mid 146.060378 -276.5478)
		(end 145.797524 -276.706838)
		(width 0.09525)
		(layer "In13.Cu")
		(net "M_H_CPU1_SB_DQS_DP<5>")
	)
	(arc
		(start 144.692116 -277.001224)
		(mid 144.508595 -276.95058)
		(end 144.323816 -276.996398)
		(width 0.09525)
		(layer "In13.Cu")
		(net "M_H_CPU1_SB_DQS_DP<5>")
	)
	(segment
		(start 134.63778 -272.20037)
		(end 135.104632 -272.466308)
		(width 0.12954)
		(layer "F.Cu")
		(net "M_H_CPU1_SB_DQS_DP<4>")
	)
	(segment
		(start 168.025572 -277.429976)
		(end 167.240712 -276.645116)
		(width 0.16002)
		(layer "In13.Cu")
		(net "M_H_CPU1_SB_DQS_DP<4>")
	)
	(segment
		(start 143.763746 -272.147284)
		(end 143.753332 -272.141188)
		(width 0.09525)
		(layer "In13.Cu")
		(net "M_H_CPU1_SB_DQS_DP<4>")
	)
	(segment
		(start 162.315144 -274.986496)
		(end 162.315144 -274.760436)
		(width 0.16002)
		(layer "In13.Cu")
		(net "M_H_CPU1_SB_DQS_DP<4>")
	)
	(segment
		(start 169.714164 -276.974808)
		(end 169.222674 -276.974808)
		(width 0.16002)
		(layer "In13.Cu")
		(net "M_H_CPU1_SB_DQS_DP<4>")
	)
	(segment
		(start 161.996882 -274.442174)
		(end 161.770822 -274.442174)
		(width 0.16002)
		(layer "In13.Cu")
		(net "M_H_CPU1_SB_DQS_DP<4>")
	)
	(segment
		(start 169.222674 -276.974808)
		(end 168.767506 -277.429976)
		(width 0.16002)
		(layer "In13.Cu")
		(net "M_H_CPU1_SB_DQS_DP<4>")
	)
	(segment
		(start 164.244274 -276.887178)
		(end 164.244274 -276.689566)
		(width 0.16002)
		(layer "In13.Cu")
		(net "M_H_CPU1_SB_DQS_DP<4>")
	)
	(segment
		(start 166.06139 -277.59787)
		(end 165.152578 -277.59787)
		(width 0.16002)
		(layer "In13.Cu")
		(net "M_H_CPU1_SB_DQS_DP<4>")
	)
	(segment
		(start 160.547558 -274.19681)
		(end 160.547558 -273.720306)
		(width 0.16002)
		(layer "In13.Cu")
		(net "M_H_CPU1_SB_DQS_DP<4>")
	)
	(segment
		(start 156.797502 -270.446754)
		(end 147.810474 -270.446754)
		(width 0.16002)
		(layer "In13.Cu")
		(net "M_H_CPU1_SB_DQS_DP<4>")
	)
	(segment
		(start 164.77996 -277.225252)
		(end 164.582348 -277.225252)
		(width 0.16002)
		(layer "In13.Cu")
		(net "M_H_CPU1_SB_DQS_DP<4>")
	)
	(segment
		(start 162.064446 -275.237194)
		(end 162.315144 -274.986496)
		(width 0.16002)
		(layer "In13.Cu")
		(net "M_H_CPU1_SB_DQS_DP<4>")
	)
	(segment
		(start 147.228814 -270.387826)
		(end 147.01901 -270.59763)
		(width 0.09525)
		(layer "In13.Cu")
		(net "M_H_CPU1_SB_DQS_DP<4>")
	)
	(segment
		(start 134.950708 -272.200878)
		(end 135.104632 -272.466308)
		(width 0.09525)
		(layer "In13.Cu")
		(net "M_H_CPU1_SB_DQS_DP<4>")
	)
	(segment
		(start 163.037012 -276.20976)
		(end 162.560508 -276.20976)
		(width 0.16002)
		(layer "In13.Cu")
		(net "M_H_CPU1_SB_DQS_DP<4>")
	)
	(segment
		(start 167.014144 -276.645116)
		(end 166.06139 -277.59787)
		(width 0.16002)
		(layer "In13.Cu")
		(net "M_H_CPU1_SB_DQS_DP<4>")
	)
	(segment
		(start 162.560508 -276.20976)
		(end 162.064446 -275.713698)
		(width 0.16002)
		(layer "In13.Cu")
		(net "M_H_CPU1_SB_DQS_DP<4>")
	)
	(segment
		(start 170.169332 -277.429976)
		(end 169.714164 -276.974808)
		(width 0.16002)
		(layer "In13.Cu")
		(net "M_H_CPU1_SB_DQS_DP<4>")
	)
	(segment
		(start 142.813278 -272.141188)
		(end 142.804896 -272.136362)
		(width 0.09525)
		(layer "In13.Cu")
		(net "M_H_CPU1_SB_DQS_DP<4>")
	)
	(segment
		(start 164.244274 -276.689566)
		(end 163.51377 -275.959062)
		(width 0.16002)
		(layer "In13.Cu")
		(net "M_H_CPU1_SB_DQS_DP<4>")
	)
	(segment
		(start 140.564616 -272.136362)
		(end 140.556234 -272.141188)
		(width 0.09525)
		(layer "In13.Cu")
		(net "M_H_CPU1_SB_DQS_DP<4>")
	)
	(segment
		(start 159.37103 -273.020282)
		(end 156.797502 -270.446754)
		(width 0.16002)
		(layer "In13.Cu")
		(net "M_H_CPU1_SB_DQS_DP<4>")
	)
	(segment
		(start 171.711366 -276.974808)
		(end 171.366434 -276.974808)
		(width 0.16002)
		(layer "In13.Cu")
		(net "M_H_CPU1_SB_DQS_DP<4>")
	)
	(segment
		(start 143.384524 -272.136362)
		(end 143.376142 -272.141188)
		(width 0.09525)
		(layer "In13.Cu")
		(net "M_H_CPU1_SB_DQS_DP<4>")
	)
	(segment
		(start 171.97197 -277.235412)
		(end 171.711366 -276.974808)
		(width 0.16002)
		(layer "In13.Cu")
		(net "M_H_CPU1_SB_DQS_DP<4>")
	)
	(segment
		(start 163.28771 -275.959062)
		(end 163.037012 -276.20976)
		(width 0.16002)
		(layer "In13.Cu")
		(net "M_H_CPU1_SB_DQS_DP<4>")
	)
	(segment
		(start 161.520124 -274.692872)
		(end 161.04362 -274.692872)
		(width 0.16002)
		(layer "In13.Cu")
		(net "M_H_CPU1_SB_DQS_DP<4>")
	)
	(segment
		(start 146.485102 -270.59763)
		(end 144.993106 -272.089626)
		(width 0.09525)
		(layer "In13.Cu")
		(net "M_H_CPU1_SB_DQS_DP<4>")
	)
	(segment
		(start 147.01901 -270.59763)
		(end 146.485102 -270.59763)
		(width 0.09525)
		(layer "In13.Cu")
		(net "M_H_CPU1_SB_DQS_DP<4>")
	)
	(segment
		(start 161.04362 -274.692872)
		(end 160.547558 -274.19681)
		(width 0.16002)
		(layer "In13.Cu")
		(net "M_H_CPU1_SB_DQS_DP<4>")
	)
	(segment
		(start 147.786852 -270.446754)
		(end 147.727924 -270.387826)
		(width 0.09525)
		(layer "In13.Cu")
		(net "M_H_CPU1_SB_DQS_DP<4>")
	)
	(segment
		(start 170.911266 -277.429976)
		(end 170.169332 -277.429976)
		(width 0.16002)
		(layer "In13.Cu")
		(net "M_H_CPU1_SB_DQS_DP<4>")
	)
	(segment
		(start 171.366434 -276.974808)
		(end 170.911266 -277.429976)
		(width 0.16002)
		(layer "In13.Cu")
		(net "M_H_CPU1_SB_DQS_DP<4>")
	)
	(segment
		(start 165.152578 -277.59787)
		(end 164.77996 -277.225252)
		(width 0.16002)
		(layer "In13.Cu")
		(net "M_H_CPU1_SB_DQS_DP<4>")
	)
	(segment
		(start 139.624562 -272.136362)
		(end 139.61618 -272.141188)
		(width 0.09525)
		(layer "In13.Cu")
		(net "M_H_CPU1_SB_DQS_DP<4>")
	)
	(segment
		(start 161.770822 -274.442174)
		(end 161.520124 -274.692872)
		(width 0.16002)
		(layer "In13.Cu")
		(net "M_H_CPU1_SB_DQS_DP<4>")
	)
	(segment
		(start 160.547558 -273.720306)
		(end 160.798256 -273.469608)
		(width 0.16002)
		(layer "In13.Cu")
		(net "M_H_CPU1_SB_DQS_DP<4>")
	)
	(segment
		(start 138.113262 -272.141188)
		(end 138.10488 -272.136362)
		(width 0.09525)
		(layer "In13.Cu")
		(net "M_H_CPU1_SB_DQS_DP<4>")
	)
	(segment
		(start 168.767506 -277.429976)
		(end 168.025572 -277.429976)
		(width 0.16002)
		(layer "In13.Cu")
		(net "M_H_CPU1_SB_DQS_DP<4>")
	)
	(segment
		(start 162.315144 -274.760436)
		(end 161.996882 -274.442174)
		(width 0.16002)
		(layer "In13.Cu")
		(net "M_H_CPU1_SB_DQS_DP<4>")
	)
	(segment
		(start 162.064446 -275.713698)
		(end 162.064446 -275.237194)
		(width 0.16002)
		(layer "In13.Cu")
		(net "M_H_CPU1_SB_DQS_DP<4>")
	)
	(segment
		(start 135.8646 -272.136362)
		(end 135.856218 -272.141188)
		(width 0.09525)
		(layer "In13.Cu")
		(net "M_H_CPU1_SB_DQS_DP<4>")
	)
	(segment
		(start 144.993106 -272.089626)
		(end 144.505426 -272.089626)
		(width 0.09525)
		(layer "In13.Cu")
		(net "M_H_CPU1_SB_DQS_DP<4>")
	)
	(segment
		(start 163.51377 -275.959062)
		(end 163.28771 -275.959062)
		(width 0.16002)
		(layer "In13.Cu")
		(net "M_H_CPU1_SB_DQS_DP<4>")
	)
	(segment
		(start 164.582348 -277.225252)
		(end 164.244274 -276.887178)
		(width 0.16002)
		(layer "In13.Cu")
		(net "M_H_CPU1_SB_DQS_DP<4>")
	)
	(segment
		(start 134.974076 -272.11401)
		(end 134.950708 -272.200878)
		(width 0.09525)
		(layer "In13.Cu")
		(net "M_H_CPU1_SB_DQS_DP<4>")
	)
	(segment
		(start 147.810474 -270.446754)
		(end 147.786852 -270.446754)
		(width 0.09525)
		(layer "In13.Cu")
		(net "M_H_CPU1_SB_DQS_DP<4>")
	)
	(segment
		(start 160.57499 -273.020282)
		(end 159.37103 -273.020282)
		(width 0.16002)
		(layer "In13.Cu")
		(net "M_H_CPU1_SB_DQS_DP<4>")
	)
	(segment
		(start 139.053316 -272.141188)
		(end 139.044934 -272.136362)
		(width 0.09525)
		(layer "In13.Cu")
		(net "M_H_CPU1_SB_DQS_DP<4>")
	)
	(segment
		(start 160.798256 -273.469608)
		(end 160.798256 -273.243548)
		(width 0.16002)
		(layer "In13.Cu")
		(net "M_H_CPU1_SB_DQS_DP<4>")
	)
	(segment
		(start 147.727924 -270.387826)
		(end 147.228814 -270.387826)
		(width 0.09525)
		(layer "In13.Cu")
		(net "M_H_CPU1_SB_DQS_DP<4>")
	)
	(segment
		(start 167.240712 -276.645116)
		(end 167.014144 -276.645116)
		(width 0.16002)
		(layer "In13.Cu")
		(net "M_H_CPU1_SB_DQS_DP<4>")
	)
	(segment
		(start 160.798256 -273.243548)
		(end 160.57499 -273.020282)
		(width 0.16002)
		(layer "In13.Cu")
		(net "M_H_CPU1_SB_DQS_DP<4>")
	)
	(arc
		(start 143.753332 -272.141188)
		(mid 143.569557 -272.090416)
		(end 143.384524 -272.136362)
		(width 0.09525)
		(layer "In13.Cu")
		(net "M_H_CPU1_SB_DQS_DP<4>")
	)
	(arc
		(start 135.856218 -272.141188)
		(mid 135.574786 -272.216943)
		(end 135.293354 -272.141188)
		(width 0.09525)
		(layer "In13.Cu")
		(net "M_H_CPU1_SB_DQS_DP<4>")
	)
	(arc
		(start 136.233408 -272.141188)
		(mid 136.049633 -272.090416)
		(end 135.8646 -272.136362)
		(width 0.09525)
		(layer "In13.Cu")
		(net "M_H_CPU1_SB_DQS_DP<4>")
	)
	(arc
		(start 137.173208 -272.141188)
		(mid 136.98474 -272.090511)
		(end 136.796272 -272.141188)
		(width 0.09525)
		(layer "In13.Cu")
		(net "M_H_CPU1_SB_DQS_DP<4>")
	)
	(arc
		(start 139.61618 -272.141188)
		(mid 139.334748 -272.216943)
		(end 139.053316 -272.141188)
		(width 0.09525)
		(layer "In13.Cu")
		(net "M_H_CPU1_SB_DQS_DP<4>")
	)
	(arc
		(start 139.99337 -272.141188)
		(mid 139.809595 -272.090416)
		(end 139.624562 -272.136362)
		(width 0.09525)
		(layer "In13.Cu")
		(net "M_H_CPU1_SB_DQS_DP<4>")
	)
	(arc
		(start 138.10488 -272.136362)
		(mid 137.919848 -272.090448)
		(end 137.736072 -272.141188)
		(width 0.09525)
		(layer "In13.Cu")
		(net "M_H_CPU1_SB_DQS_DP<4>")
	)
	(arc
		(start 142.804896 -272.136362)
		(mid 142.619864 -272.090448)
		(end 142.436088 -272.141188)
		(width 0.09525)
		(layer "In13.Cu")
		(net "M_H_CPU1_SB_DQS_DP<4>")
	)
	(arc
		(start 136.796272 -272.141188)
		(mid 136.51484 -272.216943)
		(end 136.233408 -272.141188)
		(width 0.09525)
		(layer "In13.Cu")
		(net "M_H_CPU1_SB_DQS_DP<4>")
	)
	(arc
		(start 143.376142 -272.141188)
		(mid 143.09471 -272.216943)
		(end 142.813278 -272.141188)
		(width 0.09525)
		(layer "In13.Cu")
		(net "M_H_CPU1_SB_DQS_DP<4>")
	)
	(arc
		(start 138.676126 -272.141188)
		(mid 138.394694 -272.216943)
		(end 138.113262 -272.141188)
		(width 0.09525)
		(layer "In13.Cu")
		(net "M_H_CPU1_SB_DQS_DP<4>")
	)
	(arc
		(start 144.505426 -272.089626)
		(mid 144.407529 -272.102912)
		(end 144.31645 -272.141188)
		(width 0.09525)
		(layer "In13.Cu")
		(net "M_H_CPU1_SB_DQS_DP<4>")
	)
	(arc
		(start 142.436088 -272.141188)
		(mid 142.154656 -272.216943)
		(end 141.873224 -272.141188)
		(width 0.09525)
		(layer "In13.Cu")
		(net "M_H_CPU1_SB_DQS_DP<4>")
	)
	(arc
		(start 139.044934 -272.136362)
		(mid 138.859902 -272.090448)
		(end 138.676126 -272.141188)
		(width 0.09525)
		(layer "In13.Cu")
		(net "M_H_CPU1_SB_DQS_DP<4>")
	)
	(arc
		(start 137.736072 -272.141188)
		(mid 137.45464 -272.216943)
		(end 137.173208 -272.141188)
		(width 0.09525)
		(layer "In13.Cu")
		(net "M_H_CPU1_SB_DQS_DP<4>")
	)
	(arc
		(start 140.556234 -272.141188)
		(mid 140.274802 -272.216943)
		(end 139.99337 -272.141188)
		(width 0.09525)
		(layer "In13.Cu")
		(net "M_H_CPU1_SB_DQS_DP<4>")
	)
	(arc
		(start 144.31645 -272.141188)
		(mid 144.040907 -272.217037)
		(end 143.763746 -272.147284)
		(width 0.09525)
		(layer "In13.Cu")
		(net "M_H_CPU1_SB_DQS_DP<4>")
	)
	(arc
		(start 141.873224 -272.141188)
		(mid 141.684756 -272.090511)
		(end 141.496288 -272.141188)
		(width 0.09525)
		(layer "In13.Cu")
		(net "M_H_CPU1_SB_DQS_DP<4>")
	)
	(arc
		(start 135.293354 -272.141188)
		(mid 135.136756 -272.091899)
		(end 134.974076 -272.11401)
		(width 0.09525)
		(layer "In13.Cu")
		(net "M_H_CPU1_SB_DQS_DP<4>")
	)
	(arc
		(start 141.496288 -272.141188)
		(mid 141.214856 -272.216943)
		(end 140.933424 -272.141188)
		(width 0.09525)
		(layer "In13.Cu")
		(net "M_H_CPU1_SB_DQS_DP<4>")
	)
	(arc
		(start 140.933424 -272.141188)
		(mid 140.749649 -272.090416)
		(end 140.564616 -272.136362)
		(width 0.09525)
		(layer "In13.Cu")
		(net "M_H_CPU1_SB_DQS_DP<4>")
	)
	(segment
		(start 135.577834 -290.020248)
		(end 136.044686 -290.286186)
		(width 0.12954)
		(layer "F.Cu")
		(net "M_H_CPU1_SB_DQS_DP<3>")
	)
	(segment
		(start 143.376142 -290.611306)
		(end 143.384524 -290.616132)
		(width 0.09525)
		(layer "In13.Cu")
		(net "M_H_CPU1_SB_DQS_DP<3>")
	)
	(segment
		(start 175.835056 -313.172348)
		(end 176.072038 -312.935366)
		(width 0.16002)
		(layer "In13.Cu")
		(net "M_H_CPU1_SB_DQS_DP<3>")
	)
	(segment
		(start 164.427154 -313.06897)
		(end 165.16985 -313.06897)
		(width 0.16002)
		(layer "In13.Cu")
		(net "M_H_CPU1_SB_DQS_DP<3>")
	)
	(segment
		(start 139.61618 -290.611306)
		(end 139.624562 -290.616132)
		(width 0.09525)
		(layer "In13.Cu")
		(net "M_H_CPU1_SB_DQS_DP<3>")
	)
	(segment
		(start 139.044934 -290.616132)
		(end 139.053316 -290.611306)
		(width 0.09525)
		(layer "In13.Cu")
		(net "M_H_CPU1_SB_DQS_DP<3>")
	)
	(segment
		(start 166.772082 -312.620406)
		(end 167.823642 -312.620406)
		(width 0.16002)
		(layer "In13.Cu")
		(net "M_H_CPU1_SB_DQS_DP<3>")
	)
	(segment
		(start 163.582096 -313.483244)
		(end 164.01288 -313.483244)
		(width 0.16002)
		(layer "In13.Cu")
		(net "M_H_CPU1_SB_DQS_DP<3>")
	)
	(segment
		(start 173.52137 -313.395106)
		(end 173.744128 -313.172348)
		(width 0.16002)
		(layer "In13.Cu")
		(net "M_H_CPU1_SB_DQS_DP<3>")
	)
	(segment
		(start 165.987222 -313.405266)
		(end 166.772082 -312.620406)
		(width 0.16002)
		(layer "In13.Cu")
		(net "M_H_CPU1_SB_DQS_DP<3>")
	)
	(segment
		(start 165.506146 -313.405266)
		(end 165.987222 -313.405266)
		(width 0.16002)
		(layer "In13.Cu")
		(net "M_H_CPU1_SB_DQS_DP<3>")
	)
	(segment
		(start 173.744128 -313.172348)
		(end 175.835056 -313.172348)
		(width 0.16002)
		(layer "In13.Cu")
		(net "M_H_CPU1_SB_DQS_DP<3>")
	)
	(segment
		(start 164.01288 -313.483244)
		(end 164.427154 -313.06897)
		(width 0.16002)
		(layer "In13.Cu")
		(net "M_H_CPU1_SB_DQS_DP<3>")
	)
	(segment
		(start 170.070526 -312.620406)
		(end 170.5102 -313.06008)
		(width 0.16002)
		(layer "In13.Cu")
		(net "M_H_CPU1_SB_DQS_DP<3>")
	)
	(segment
		(start 160.263586 -313.06897)
		(end 163.167822 -313.06897)
		(width 0.16002)
		(layer "In13.Cu")
		(net "M_H_CPU1_SB_DQS_DP<3>")
	)
	(segment
		(start 138.10488 -290.616132)
		(end 138.113262 -290.611306)
		(width 0.09525)
		(layer "In13.Cu")
		(net "M_H_CPU1_SB_DQS_DP<3>")
	)
	(segment
		(start 148.26869 -301.074074)
		(end 160.263586 -313.06897)
		(width 0.16002)
		(layer "In13.Cu")
		(net "M_H_CPU1_SB_DQS_DP<3>")
	)
	(segment
		(start 147.246848 -293.667688)
		(end 147.263612 -293.684452)
		(width 0.09525)
		(layer "In13.Cu")
		(net "M_H_CPU1_SB_DQS_DP<3>")
	)
	(segment
		(start 147.263612 -293.684452)
		(end 148.26869 -294.68953)
		(width 0.16002)
		(layer "In13.Cu")
		(net "M_H_CPU1_SB_DQS_DP<3>")
	)
	(segment
		(start 144.690846 -290.611306)
		(end 144.714214 -290.597844)
		(width 0.09525)
		(layer "In13.Cu")
		(net "M_H_CPU1_SB_DQS_DP<3>")
	)
	(segment
		(start 167.823642 -312.620406)
		(end 168.28516 -313.081924)
		(width 0.16002)
		(layer "In13.Cu")
		(net "M_H_CPU1_SB_DQS_DP<3>")
	)
	(segment
		(start 146.501866 -293.006526)
		(end 147.163028 -293.667688)
		(width 0.09525)
		(layer "In13.Cu")
		(net "M_H_CPU1_SB_DQS_DP<3>")
	)
	(segment
		(start 172.752258 -313.395106)
		(end 173.52137 -313.395106)
		(width 0.16002)
		(layer "In13.Cu")
		(net "M_H_CPU1_SB_DQS_DP<3>")
	)
	(segment
		(start 147.163028 -293.667688)
		(end 147.246848 -293.667688)
		(width 0.09525)
		(layer "In13.Cu")
		(net "M_H_CPU1_SB_DQS_DP<3>")
	)
	(segment
		(start 170.5102 -313.06008)
		(end 172.417232 -313.06008)
		(width 0.16002)
		(layer "In13.Cu")
		(net "M_H_CPU1_SB_DQS_DP<3>")
	)
	(segment
		(start 168.28516 -313.081924)
		(end 168.6687 -313.081924)
		(width 0.16002)
		(layer "In13.Cu")
		(net "M_H_CPU1_SB_DQS_DP<3>")
	)
	(segment
		(start 136.044686 -290.286186)
		(end 136.19861 -290.551616)
		(width 0.09525)
		(layer "In13.Cu")
		(net "M_H_CPU1_SB_DQS_DP<3>")
	)
	(segment
		(start 163.167822 -313.06897)
		(end 163.582096 -313.483244)
		(width 0.16002)
		(layer "In13.Cu")
		(net "M_H_CPU1_SB_DQS_DP<3>")
	)
	(segment
		(start 165.16985 -313.06897)
		(end 165.506146 -313.405266)
		(width 0.16002)
		(layer "In13.Cu")
		(net "M_H_CPU1_SB_DQS_DP<3>")
	)
	(segment
		(start 140.556234 -290.611306)
		(end 140.564616 -290.616132)
		(width 0.09525)
		(layer "In13.Cu")
		(net "M_H_CPU1_SB_DQS_DP<3>")
	)
	(segment
		(start 169.130218 -312.620406)
		(end 170.070526 -312.620406)
		(width 0.16002)
		(layer "In13.Cu")
		(net "M_H_CPU1_SB_DQS_DP<3>")
	)
	(segment
		(start 168.6687 -313.081924)
		(end 169.130218 -312.620406)
		(width 0.16002)
		(layer "In13.Cu")
		(net "M_H_CPU1_SB_DQS_DP<3>")
	)
	(segment
		(start 145.654268 -290.98367)
		(end 146.501866 -293.006526)
		(width 0.09525)
		(layer "In13.Cu")
		(net "M_H_CPU1_SB_DQS_DP<3>")
	)
	(segment
		(start 142.804896 -290.616132)
		(end 142.813278 -290.611306)
		(width 0.09525)
		(layer "In13.Cu")
		(net "M_H_CPU1_SB_DQS_DP<3>")
	)
	(segment
		(start 148.26869 -294.68953)
		(end 148.26869 -301.074074)
		(width 0.16002)
		(layer "In13.Cu")
		(net "M_H_CPU1_SB_DQS_DP<3>")
	)
	(segment
		(start 172.417232 -313.06008)
		(end 172.752258 -313.395106)
		(width 0.16002)
		(layer "In13.Cu")
		(net "M_H_CPU1_SB_DQS_DP<3>")
	)
	(segment
		(start 145.370804 -290.700206)
		(end 145.654268 -290.98367)
		(width 0.09525)
		(layer "In13.Cu")
		(net "M_H_CPU1_SB_DQS_DP<3>")
	)
	(segment
		(start 136.19861 -290.551616)
		(end 136.299448 -290.578286)
		(width 0.09525)
		(layer "In13.Cu")
		(net "M_H_CPU1_SB_DQS_DP<3>")
	)
	(segment
		(start 144.289272 -290.596574)
		(end 144.32915 -290.619688)
		(width 0.09525)
		(layer "In13.Cu")
		(net "M_H_CPU1_SB_DQS_DP<3>")
	)
	(arc
		(start 145.25498 -290.611306)
		(mid 145.3158 -290.651967)
		(end 145.370804 -290.700206)
		(width 0.09525)
		(layer "In13.Cu")
		(net "M_H_CPU1_SB_DQS_DP<3>")
	)
	(arc
		(start 138.113262 -290.611306)
		(mid 138.394694 -290.535551)
		(end 138.676126 -290.611306)
		(width 0.09525)
		(layer "In13.Cu")
		(net "M_H_CPU1_SB_DQS_DP<3>")
	)
	(arc
		(start 139.624562 -290.616132)
		(mid 139.809594 -290.662046)
		(end 139.99337 -290.611306)
		(width 0.09525)
		(layer "In13.Cu")
		(net "M_H_CPU1_SB_DQS_DP<3>")
	)
	(arc
		(start 139.053316 -290.611306)
		(mid 139.334748 -290.535551)
		(end 139.61618 -290.611306)
		(width 0.09525)
		(layer "In13.Cu")
		(net "M_H_CPU1_SB_DQS_DP<3>")
	)
	(arc
		(start 140.564616 -290.616132)
		(mid 140.749648 -290.662046)
		(end 140.933424 -290.611306)
		(width 0.09525)
		(layer "In13.Cu")
		(net "M_H_CPU1_SB_DQS_DP<3>")
	)
	(arc
		(start 136.796272 -290.611306)
		(mid 136.98474 -290.661983)
		(end 137.173208 -290.611306)
		(width 0.09525)
		(layer "In13.Cu")
		(net "M_H_CPU1_SB_DQS_DP<3>")
	)
	(arc
		(start 144.32915 -290.619688)
		(mid 144.511075 -290.661893)
		(end 144.690846 -290.611306)
		(width 0.09525)
		(layer "In13.Cu")
		(net "M_H_CPU1_SB_DQS_DP<3>")
	)
	(arc
		(start 137.736072 -290.611306)
		(mid 137.919847 -290.662078)
		(end 138.10488 -290.616132)
		(width 0.09525)
		(layer "In13.Cu")
		(net "M_H_CPU1_SB_DQS_DP<3>")
	)
	(arc
		(start 139.99337 -290.611306)
		(mid 140.274802 -290.535551)
		(end 140.556234 -290.611306)
		(width 0.09525)
		(layer "In13.Cu")
		(net "M_H_CPU1_SB_DQS_DP<3>")
	)
	(arc
		(start 141.873224 -290.611306)
		(mid 142.154656 -290.535551)
		(end 142.436088 -290.611306)
		(width 0.09525)
		(layer "In13.Cu")
		(net "M_H_CPU1_SB_DQS_DP<3>")
	)
	(arc
		(start 143.384524 -290.616132)
		(mid 143.569556 -290.662046)
		(end 143.753332 -290.611306)
		(width 0.09525)
		(layer "In13.Cu")
		(net "M_H_CPU1_SB_DQS_DP<3>")
	)
	(arc
		(start 142.813278 -290.611306)
		(mid 143.09471 -290.535551)
		(end 143.376142 -290.611306)
		(width 0.09525)
		(layer "In13.Cu")
		(net "M_H_CPU1_SB_DQS_DP<3>")
	)
	(arc
		(start 138.676126 -290.611306)
		(mid 138.859901 -290.662078)
		(end 139.044934 -290.616132)
		(width 0.09525)
		(layer "In13.Cu")
		(net "M_H_CPU1_SB_DQS_DP<3>")
	)
	(arc
		(start 137.173208 -290.611306)
		(mid 137.45464 -290.535551)
		(end 137.736072 -290.611306)
		(width 0.09525)
		(layer "In13.Cu")
		(net "M_H_CPU1_SB_DQS_DP<3>")
	)
	(arc
		(start 141.496288 -290.611306)
		(mid 141.684756 -290.661983)
		(end 141.873224 -290.611306)
		(width 0.09525)
		(layer "In13.Cu")
		(net "M_H_CPU1_SB_DQS_DP<3>")
	)
	(arc
		(start 140.933424 -290.611306)
		(mid 141.214856 -290.535551)
		(end 141.496288 -290.611306)
		(width 0.09525)
		(layer "In13.Cu")
		(net "M_H_CPU1_SB_DQS_DP<3>")
	)
	(arc
		(start 136.320022 -290.570158)
		(mid 136.562764 -290.537388)
		(end 136.796272 -290.611306)
		(width 0.09525)
		(layer "In13.Cu")
		(net "M_H_CPU1_SB_DQS_DP<3>")
	)
	(arc
		(start 143.753332 -290.611306)
		(mid 144.019419 -290.535761)
		(end 144.289272 -290.596574)
		(width 0.09525)
		(layer "In13.Cu")
		(net "M_H_CPU1_SB_DQS_DP<3>")
	)
	(arc
		(start 136.299448 -290.578286)
		(mid 136.309696 -290.574123)
		(end 136.320022 -290.570158)
		(width 0.09525)
		(layer "In13.Cu")
		(net "M_H_CPU1_SB_DQS_DP<3>")
	)
	(arc
		(start 142.436088 -290.611306)
		(mid 142.619863 -290.662078)
		(end 142.804896 -290.616132)
		(width 0.09525)
		(layer "In13.Cu")
		(net "M_H_CPU1_SB_DQS_DP<3>")
	)
	(arc
		(start 144.714214 -290.597844)
		(mid 144.986315 -290.535166)
		(end 145.25498 -290.611306)
		(width 0.09525)
		(layer "In13.Cu")
		(net "M_H_CPU1_SB_DQS_DP<3>")
	)
	(segment
		(start 135.577834 -285.160466)
		(end 136.044686 -285.426404)
		(width 0.12954)
		(layer "F.Cu")
		(net "M_H_CPU1_SB_DQS_DP<2>")
	)
	(segment
		(start 155.924758 -298.283376)
		(end 155.924758 -298.75988)
		(width 0.16002)
		(layer "In13.Cu")
		(net "M_H_CPU1_SB_DQS_DP<2>")
	)
	(segment
		(start 154.195272 -297.68165)
		(end 154.514296 -298.000674)
		(width 0.16002)
		(layer "In13.Cu")
		(net "M_H_CPU1_SB_DQS_DP<2>")
	)
	(segment
		(start 175.517048 -303.875948)
		(end 175.781462 -303.875948)
		(width 0.16002)
		(layer "In13.Cu")
		(net "M_H_CPU1_SB_DQS_DP<2>")
	)
	(segment
		(start 174.908464 -303.267364)
		(end 175.517048 -303.875948)
		(width 0.16002)
		(layer "In13.Cu")
		(net "M_H_CPU1_SB_DQS_DP<2>")
	)
	(segment
		(start 147.80133 -286.681672)
		(end 147.860512 -286.62249)
		(width 0.09525)
		(layer "In13.Cu")
		(net "M_H_CPU1_SB_DQS_DP<2>")
	)
	(segment
		(start 136.19861 -285.691834)
		(end 136.299448 -285.718504)
		(width 0.09525)
		(layer "In13.Cu")
		(net "M_H_CPU1_SB_DQS_DP<2>")
	)
	(segment
		(start 154.740356 -298.000674)
		(end 154.952954 -297.788076)
		(width 0.16002)
		(layer "In13.Cu")
		(net "M_H_CPU1_SB_DQS_DP<2>")
	)
	(segment
		(start 142.804896 -285.75635)
		(end 142.813278 -285.751524)
		(width 0.09525)
		(layer "In13.Cu")
		(net "M_H_CPU1_SB_DQS_DP<2>")
	)
	(segment
		(start 136.044686 -285.426404)
		(end 136.19861 -285.691834)
		(width 0.09525)
		(layer "In13.Cu")
		(net "M_H_CPU1_SB_DQS_DP<2>")
	)
	(segment
		(start 172.417232 -303.710086)
		(end 172.752258 -304.045112)
		(width 0.16002)
		(layer "In13.Cu")
		(net "M_H_CPU1_SB_DQS_DP<2>")
	)
	(segment
		(start 147.860512 -286.62249)
		(end 147.884134 -286.62249)
		(width 0.09525)
		(layer "In13.Cu")
		(net "M_H_CPU1_SB_DQS_DP<2>")
	)
	(segment
		(start 163.24834 -303.71923)
		(end 163.584382 -304.055272)
		(width 0.16002)
		(layer "In13.Cu")
		(net "M_H_CPU1_SB_DQS_DP<2>")
	)
	(segment
		(start 138.10488 -285.75635)
		(end 138.113262 -285.751524)
		(width 0.09525)
		(layer "In13.Cu")
		(net "M_H_CPU1_SB_DQS_DP<2>")
	)
	(segment
		(start 147.884134 -286.62249)
		(end 148.19249 -286.62249)
		(width 0.16002)
		(layer "In13.Cu")
		(net "M_H_CPU1_SB_DQS_DP<2>")
	)
	(segment
		(start 144.289272 -285.736792)
		(end 144.32915 -285.759906)
		(width 0.09525)
		(layer "In13.Cu")
		(net "M_H_CPU1_SB_DQS_DP<2>")
	)
	(segment
		(start 155.71216 -298.972478)
		(end 155.71216 -299.198538)
		(width 0.16002)
		(layer "In13.Cu")
		(net "M_H_CPU1_SB_DQS_DP<2>")
	)
	(segment
		(start 173.653704 -304.045112)
		(end 174.431452 -303.267364)
		(width 0.16002)
		(layer "In13.Cu")
		(net "M_H_CPU1_SB_DQS_DP<2>")
	)
	(segment
		(start 156.469842 -299.304964)
		(end 156.946346 -299.304964)
		(width 0.16002)
		(layer "In13.Cu")
		(net "M_H_CPU1_SB_DQS_DP<2>")
	)
	(segment
		(start 161.360612 -303.71923)
		(end 163.24834 -303.71923)
		(width 0.16002)
		(layer "In13.Cu")
		(net "M_H_CPU1_SB_DQS_DP<2>")
	)
	(segment
		(start 156.257244 -299.517562)
		(end 156.469842 -299.304964)
		(width 0.16002)
		(layer "In13.Cu")
		(net "M_H_CPU1_SB_DQS_DP<2>")
	)
	(segment
		(start 175.781462 -303.875948)
		(end 176.072038 -303.585372)
		(width 0.16002)
		(layer "In13.Cu")
		(net "M_H_CPU1_SB_DQS_DP<2>")
	)
	(segment
		(start 146.854926 -286.378904)
		(end 147.396962 -286.378904)
		(width 0.09525)
		(layer "In13.Cu")
		(net "M_H_CPU1_SB_DQS_DP<2>")
	)
	(segment
		(start 174.431452 -303.267364)
		(end 174.908464 -303.267364)
		(width 0.16002)
		(layer "In13.Cu")
		(net "M_H_CPU1_SB_DQS_DP<2>")
	)
	(segment
		(start 156.031184 -299.517562)
		(end 156.257244 -299.517562)
		(width 0.16002)
		(layer "In13.Cu")
		(net "M_H_CPU1_SB_DQS_DP<2>")
	)
	(segment
		(start 139.044934 -285.75635)
		(end 139.053316 -285.751524)
		(width 0.09525)
		(layer "In13.Cu")
		(net "M_H_CPU1_SB_DQS_DP<2>")
	)
	(segment
		(start 148.19249 -286.62249)
		(end 153.80589 -292.23589)
		(width 0.16002)
		(layer "In13.Cu")
		(net "M_H_CPU1_SB_DQS_DP<2>")
	)
	(segment
		(start 147.396962 -286.378904)
		(end 147.69973 -286.681672)
		(width 0.09525)
		(layer "In13.Cu")
		(net "M_H_CPU1_SB_DQS_DP<2>")
	)
	(segment
		(start 165.987222 -304.055272)
		(end 166.772082 -303.270412)
		(width 0.16002)
		(layer "In13.Cu")
		(net "M_H_CPU1_SB_DQS_DP<2>")
	)
	(segment
		(start 146.279616 -285.803594)
		(end 146.854926 -286.378904)
		(width 0.09525)
		(layer "In13.Cu")
		(net "M_H_CPU1_SB_DQS_DP<2>")
	)
	(segment
		(start 143.376142 -285.751524)
		(end 143.384524 -285.75635)
		(width 0.09525)
		(layer "In13.Cu")
		(net "M_H_CPU1_SB_DQS_DP<2>")
	)
	(segment
		(start 140.556234 -285.751524)
		(end 140.564616 -285.75635)
		(width 0.09525)
		(layer "In13.Cu")
		(net "M_H_CPU1_SB_DQS_DP<2>")
	)
	(segment
		(start 170.5102 -303.710086)
		(end 172.417232 -303.710086)
		(width 0.16002)
		(layer "In13.Cu")
		(net "M_H_CPU1_SB_DQS_DP<2>")
	)
	(segment
		(start 154.195272 -297.45559)
		(end 154.195272 -297.68165)
		(width 0.16002)
		(layer "In13.Cu")
		(net "M_H_CPU1_SB_DQS_DP<2>")
	)
	(segment
		(start 144.690846 -285.751524)
		(end 144.714214 -285.738062)
		(width 0.09525)
		(layer "In13.Cu")
		(net "M_H_CPU1_SB_DQS_DP<2>")
	)
	(segment
		(start 153.80589 -292.23589)
		(end 153.80589 -296.164508)
		(width 0.16002)
		(layer "In13.Cu")
		(net "M_H_CPU1_SB_DQS_DP<2>")
	)
	(segment
		(start 154.40787 -296.766488)
		(end 154.40787 -297.242992)
		(width 0.16002)
		(layer "In13.Cu")
		(net "M_H_CPU1_SB_DQS_DP<2>")
	)
	(segment
		(start 155.71216 -299.198538)
		(end 156.031184 -299.517562)
		(width 0.16002)
		(layer "In13.Cu")
		(net "M_H_CPU1_SB_DQS_DP<2>")
	)
	(segment
		(start 154.952954 -297.788076)
		(end 155.429458 -297.788076)
		(width 0.16002)
		(layer "In13.Cu")
		(net "M_H_CPU1_SB_DQS_DP<2>")
	)
	(segment
		(start 170.070526 -303.270412)
		(end 170.5102 -303.710086)
		(width 0.16002)
		(layer "In13.Cu")
		(net "M_H_CPU1_SB_DQS_DP<2>")
	)
	(segment
		(start 139.61618 -285.751524)
		(end 139.624562 -285.75635)
		(width 0.09525)
		(layer "In13.Cu")
		(net "M_H_CPU1_SB_DQS_DP<2>")
	)
	(segment
		(start 172.752258 -304.045112)
		(end 173.653704 -304.045112)
		(width 0.16002)
		(layer "In13.Cu")
		(net "M_H_CPU1_SB_DQS_DP<2>")
	)
	(segment
		(start 145.444718 -285.803594)
		(end 146.279616 -285.803594)
		(width 0.09525)
		(layer "In13.Cu")
		(net "M_H_CPU1_SB_DQS_DP<2>")
	)
	(segment
		(start 154.40787 -297.242992)
		(end 154.195272 -297.45559)
		(width 0.16002)
		(layer "In13.Cu")
		(net "M_H_CPU1_SB_DQS_DP<2>")
	)
	(segment
		(start 166.772082 -303.270412)
		(end 170.070526 -303.270412)
		(width 0.16002)
		(layer "In13.Cu")
		(net "M_H_CPU1_SB_DQS_DP<2>")
	)
	(segment
		(start 156.946346 -299.304964)
		(end 161.360612 -303.71923)
		(width 0.16002)
		(layer "In13.Cu")
		(net "M_H_CPU1_SB_DQS_DP<2>")
	)
	(segment
		(start 154.514296 -298.000674)
		(end 154.740356 -298.000674)
		(width 0.16002)
		(layer "In13.Cu")
		(net "M_H_CPU1_SB_DQS_DP<2>")
	)
	(segment
		(start 155.924758 -298.75988)
		(end 155.71216 -298.972478)
		(width 0.16002)
		(layer "In13.Cu")
		(net "M_H_CPU1_SB_DQS_DP<2>")
	)
	(segment
		(start 147.69973 -286.681672)
		(end 147.80133 -286.681672)
		(width 0.09525)
		(layer "In13.Cu")
		(net "M_H_CPU1_SB_DQS_DP<2>")
	)
	(segment
		(start 163.584382 -304.055272)
		(end 165.987222 -304.055272)
		(width 0.16002)
		(layer "In13.Cu")
		(net "M_H_CPU1_SB_DQS_DP<2>")
	)
	(segment
		(start 153.80589 -296.164508)
		(end 154.40787 -296.766488)
		(width 0.16002)
		(layer "In13.Cu")
		(net "M_H_CPU1_SB_DQS_DP<2>")
	)
	(segment
		(start 155.429458 -297.788076)
		(end 155.924758 -298.283376)
		(width 0.16002)
		(layer "In13.Cu")
		(net "M_H_CPU1_SB_DQS_DP<2>")
	)
	(arc
		(start 137.736072 -285.751524)
		(mid 137.919847 -285.802296)
		(end 138.10488 -285.75635)
		(width 0.09525)
		(layer "In13.Cu")
		(net "M_H_CPU1_SB_DQS_DP<2>")
	)
	(arc
		(start 139.99337 -285.751524)
		(mid 140.274802 -285.675769)
		(end 140.556234 -285.751524)
		(width 0.09525)
		(layer "In13.Cu")
		(net "M_H_CPU1_SB_DQS_DP<2>")
	)
	(arc
		(start 140.933424 -285.751524)
		(mid 141.214856 -285.675769)
		(end 141.496288 -285.751524)
		(width 0.09525)
		(layer "In13.Cu")
		(net "M_H_CPU1_SB_DQS_DP<2>")
	)
	(arc
		(start 143.384524 -285.75635)
		(mid 143.569556 -285.802264)
		(end 143.753332 -285.751524)
		(width 0.09525)
		(layer "In13.Cu")
		(net "M_H_CPU1_SB_DQS_DP<2>")
	)
	(arc
		(start 136.299448 -285.718504)
		(mid 136.309696 -285.714341)
		(end 136.320022 -285.710376)
		(width 0.09525)
		(layer "In13.Cu")
		(net "M_H_CPU1_SB_DQS_DP<2>")
	)
	(arc
		(start 142.436088 -285.751524)
		(mid 142.619863 -285.802296)
		(end 142.804896 -285.75635)
		(width 0.09525)
		(layer "In13.Cu")
		(net "M_H_CPU1_SB_DQS_DP<2>")
	)
	(arc
		(start 138.676126 -285.751524)
		(mid 138.859901 -285.802296)
		(end 139.044934 -285.75635)
		(width 0.09525)
		(layer "In13.Cu")
		(net "M_H_CPU1_SB_DQS_DP<2>")
	)
	(arc
		(start 139.053316 -285.751524)
		(mid 139.334748 -285.675769)
		(end 139.61618 -285.751524)
		(width 0.09525)
		(layer "In13.Cu")
		(net "M_H_CPU1_SB_DQS_DP<2>")
	)
	(arc
		(start 141.496288 -285.751524)
		(mid 141.684756 -285.802201)
		(end 141.873224 -285.751524)
		(width 0.09525)
		(layer "In13.Cu")
		(net "M_H_CPU1_SB_DQS_DP<2>")
	)
	(arc
		(start 144.714214 -285.738062)
		(mid 144.986315 -285.675384)
		(end 145.25498 -285.751524)
		(width 0.09525)
		(layer "In13.Cu")
		(net "M_H_CPU1_SB_DQS_DP<2>")
	)
	(arc
		(start 137.173208 -285.751524)
		(mid 137.45464 -285.675769)
		(end 137.736072 -285.751524)
		(width 0.09525)
		(layer "In13.Cu")
		(net "M_H_CPU1_SB_DQS_DP<2>")
	)
	(arc
		(start 136.320022 -285.710376)
		(mid 136.562764 -285.677606)
		(end 136.796272 -285.751524)
		(width 0.09525)
		(layer "In13.Cu")
		(net "M_H_CPU1_SB_DQS_DP<2>")
	)
	(arc
		(start 138.113262 -285.751524)
		(mid 138.394694 -285.675769)
		(end 138.676126 -285.751524)
		(width 0.09525)
		(layer "In13.Cu")
		(net "M_H_CPU1_SB_DQS_DP<2>")
	)
	(arc
		(start 143.753332 -285.751524)
		(mid 144.019419 -285.675979)
		(end 144.289272 -285.736792)
		(width 0.09525)
		(layer "In13.Cu")
		(net "M_H_CPU1_SB_DQS_DP<2>")
	)
	(arc
		(start 142.813278 -285.751524)
		(mid 143.09471 -285.675769)
		(end 143.376142 -285.751524)
		(width 0.09525)
		(layer "In13.Cu")
		(net "M_H_CPU1_SB_DQS_DP<2>")
	)
	(arc
		(start 144.32915 -285.759906)
		(mid 144.511075 -285.802111)
		(end 144.690846 -285.751524)
		(width 0.09525)
		(layer "In13.Cu")
		(net "M_H_CPU1_SB_DQS_DP<2>")
	)
	(arc
		(start 140.564616 -285.75635)
		(mid 140.749648 -285.802264)
		(end 140.933424 -285.751524)
		(width 0.09525)
		(layer "In13.Cu")
		(net "M_H_CPU1_SB_DQS_DP<2>")
	)
	(arc
		(start 136.796272 -285.751524)
		(mid 136.98474 -285.802201)
		(end 137.173208 -285.751524)
		(width 0.09525)
		(layer "In13.Cu")
		(net "M_H_CPU1_SB_DQS_DP<2>")
	)
	(arc
		(start 145.25498 -285.751524)
		(mid 145.346392 -285.790144)
		(end 145.444718 -285.803594)
		(width 0.09525)
		(layer "In13.Cu")
		(net "M_H_CPU1_SB_DQS_DP<2>")
	)
	(arc
		(start 141.873224 -285.751524)
		(mid 142.154656 -285.675769)
		(end 142.436088 -285.751524)
		(width 0.09525)
		(layer "In13.Cu")
		(net "M_H_CPU1_SB_DQS_DP<2>")
	)
	(arc
		(start 139.624562 -285.75635)
		(mid 139.809594 -285.802264)
		(end 139.99337 -285.751524)
		(width 0.09525)
		(layer "In13.Cu")
		(net "M_H_CPU1_SB_DQS_DP<2>")
	)
	(segment
		(start 135.577834 -280.30043)
		(end 136.044686 -280.566368)
		(width 0.12954)
		(layer "F.Cu")
		(net "M_H_CPU1_SB_DQS_DP<1>")
	)
	(segment
		(start 147.79244 -280.857452)
		(end 147.768818 -280.857452)
		(width 0.09525)
		(layer "In13.Cu")
		(net "M_H_CPU1_SB_DQS_DP<1>")
	)
	(segment
		(start 172.417232 -294.360092)
		(end 170.5102 -294.360092)
		(width 0.16002)
		(layer "In13.Cu")
		(net "M_H_CPU1_SB_DQS_DP<1>")
	)
	(segment
		(start 161.418016 -294.021002)
		(end 161.418016 -292.483286)
		(width 0.16002)
		(layer "In13.Cu")
		(net "M_H_CPU1_SB_DQS_DP<1>")
	)
	(segment
		(start 162.493706 -294.459914)
		(end 161.786062 -295.167558)
		(width 0.16002)
		(layer "In13.Cu")
		(net "M_H_CPU1_SB_DQS_DP<1>")
	)
	(segment
		(start 161.418016 -292.483286)
		(end 160.414208 -291.479478)
		(width 0.16002)
		(layer "In13.Cu")
		(net "M_H_CPU1_SB_DQS_DP<1>")
	)
	(segment
		(start 161.028634 -294.636444)
		(end 161.028634 -294.410384)
		(width 0.16002)
		(layer "In13.Cu")
		(net "M_H_CPU1_SB_DQS_DP<1>")
	)
	(segment
		(start 139.053316 -280.891488)
		(end 139.044934 -280.896314)
		(width 0.09525)
		(layer "In13.Cu")
		(net "M_H_CPU1_SB_DQS_DP<1>")
	)
	(segment
		(start 170.5102 -294.360092)
		(end 170.070526 -293.920418)
		(width 0.16002)
		(layer "In13.Cu")
		(net "M_H_CPU1_SB_DQS_DP<1>")
	)
	(segment
		(start 147.768818 -280.857452)
		(end 147.709636 -280.916634)
		(width 0.09525)
		(layer "In13.Cu")
		(net "M_H_CPU1_SB_DQS_DP<1>")
	)
	(segment
		(start 140.564616 -280.896314)
		(end 140.556234 -280.891488)
		(width 0.09525)
		(layer "In13.Cu")
		(net "M_H_CPU1_SB_DQS_DP<1>")
	)
	(segment
		(start 136.299448 -280.858468)
		(end 136.19861 -280.831798)
		(width 0.09525)
		(layer "In13.Cu")
		(net "M_H_CPU1_SB_DQS_DP<1>")
	)
	(segment
		(start 136.19861 -280.831798)
		(end 136.044686 -280.566368)
		(width 0.09525)
		(layer "In13.Cu")
		(net "M_H_CPU1_SB_DQS_DP<1>")
	)
	(segment
		(start 159.34309 -289.939476)
		(end 150.261066 -280.857452)
		(width 0.16002)
		(layer "In13.Cu")
		(net "M_H_CPU1_SB_DQS_DP<1>")
	)
	(segment
		(start 172.752258 -294.695118)
		(end 172.417232 -294.360092)
		(width 0.16002)
		(layer "In13.Cu")
		(net "M_H_CPU1_SB_DQS_DP<1>")
	)
	(segment
		(start 176.072038 -294.235378)
		(end 175.829468 -294.477948)
		(width 0.16002)
		(layer "In13.Cu")
		(net "M_H_CPU1_SB_DQS_DP<1>")
	)
	(segment
		(start 145.949416 -280.647394)
		(end 145.653506 -280.943304)
		(width 0.09525)
		(layer "In13.Cu")
		(net "M_H_CPU1_SB_DQS_DP<1>")
	)
	(segment
		(start 174.834804 -294.695118)
		(end 172.752258 -294.695118)
		(width 0.16002)
		(layer "In13.Cu")
		(net "M_H_CPU1_SB_DQS_DP<1>")
	)
	(segment
		(start 175.829468 -294.477948)
		(end 175.051974 -294.477948)
		(width 0.16002)
		(layer "In13.Cu")
		(net "M_H_CPU1_SB_DQS_DP<1>")
	)
	(segment
		(start 161.028634 -294.410384)
		(end 161.418016 -294.021002)
		(width 0.16002)
		(layer "In13.Cu")
		(net "M_H_CPU1_SB_DQS_DP<1>")
	)
	(segment
		(start 165.0238 -294.459914)
		(end 162.493706 -294.459914)
		(width 0.16002)
		(layer "In13.Cu")
		(net "M_H_CPU1_SB_DQS_DP<1>")
	)
	(segment
		(start 159.855916 -291.479478)
		(end 159.34309 -290.966652)
		(width 0.16002)
		(layer "In13.Cu")
		(net "M_H_CPU1_SB_DQS_DP<1>")
	)
	(segment
		(start 150.261066 -280.857452)
		(end 147.79244 -280.857452)
		(width 0.16002)
		(layer "In13.Cu")
		(net "M_H_CPU1_SB_DQS_DP<1>")
	)
	(segment
		(start 170.070526 -293.920418)
		(end 166.772082 -293.920418)
		(width 0.16002)
		(layer "In13.Cu")
		(net "M_H_CPU1_SB_DQS_DP<1>")
	)
	(segment
		(start 143.384524 -280.896314)
		(end 143.376142 -280.891488)
		(width 0.09525)
		(layer "In13.Cu")
		(net "M_H_CPU1_SB_DQS_DP<1>")
	)
	(segment
		(start 144.327118 -280.898346)
		(end 144.294352 -280.879296)
		(width 0.09525)
		(layer "In13.Cu")
		(net "M_H_CPU1_SB_DQS_DP<1>")
	)
	(segment
		(start 166.772082 -293.920418)
		(end 165.987222 -294.705278)
		(width 0.16002)
		(layer "In13.Cu")
		(net "M_H_CPU1_SB_DQS_DP<1>")
	)
	(segment
		(start 160.414208 -291.479478)
		(end 159.855916 -291.479478)
		(width 0.16002)
		(layer "In13.Cu")
		(net "M_H_CPU1_SB_DQS_DP<1>")
	)
	(segment
		(start 165.987222 -294.705278)
		(end 165.269164 -294.705278)
		(width 0.16002)
		(layer "In13.Cu")
		(net "M_H_CPU1_SB_DQS_DP<1>")
	)
	(segment
		(start 175.051974 -294.477948)
		(end 174.834804 -294.695118)
		(width 0.16002)
		(layer "In13.Cu")
		(net "M_H_CPU1_SB_DQS_DP<1>")
	)
	(segment
		(start 165.269164 -294.705278)
		(end 165.0238 -294.459914)
		(width 0.16002)
		(layer "In13.Cu")
		(net "M_H_CPU1_SB_DQS_DP<1>")
	)
	(segment
		(start 147.60829 -280.916634)
		(end 147.229576 -280.53792)
		(width 0.09525)
		(layer "In13.Cu")
		(net "M_H_CPU1_SB_DQS_DP<1>")
	)
	(segment
		(start 142.813278 -280.891488)
		(end 142.804896 -280.896314)
		(width 0.09525)
		(layer "In13.Cu")
		(net "M_H_CPU1_SB_DQS_DP<1>")
	)
	(segment
		(start 161.559748 -295.167558)
		(end 161.028634 -294.636444)
		(width 0.16002)
		(layer "In13.Cu")
		(net "M_H_CPU1_SB_DQS_DP<1>")
	)
	(segment
		(start 144.712436 -280.879296)
		(end 144.691608 -280.891488)
		(width 0.09525)
		(layer "In13.Cu")
		(net "M_H_CPU1_SB_DQS_DP<1>")
	)
	(segment
		(start 161.786062 -295.167558)
		(end 161.559748 -295.167558)
		(width 0.16002)
		(layer "In13.Cu")
		(net "M_H_CPU1_SB_DQS_DP<1>")
	)
	(segment
		(start 138.113262 -280.891488)
		(end 138.10488 -280.896314)
		(width 0.09525)
		(layer "In13.Cu")
		(net "M_H_CPU1_SB_DQS_DP<1>")
	)
	(segment
		(start 147.229576 -280.53792)
		(end 146.213576 -280.53792)
		(width 0.09525)
		(layer "In13.Cu")
		(net "M_H_CPU1_SB_DQS_DP<1>")
	)
	(segment
		(start 159.34309 -290.966652)
		(end 159.34309 -289.939476)
		(width 0.16002)
		(layer "In13.Cu")
		(net "M_H_CPU1_SB_DQS_DP<1>")
	)
	(segment
		(start 145.653506 -280.943304)
		(end 145.444718 -280.943304)
		(width 0.09525)
		(layer "In13.Cu")
		(net "M_H_CPU1_SB_DQS_DP<1>")
	)
	(segment
		(start 147.709636 -280.916634)
		(end 147.60829 -280.916634)
		(width 0.09525)
		(layer "In13.Cu")
		(net "M_H_CPU1_SB_DQS_DP<1>")
	)
	(segment
		(start 139.624562 -280.896314)
		(end 139.61618 -280.891488)
		(width 0.09525)
		(layer "In13.Cu")
		(net "M_H_CPU1_SB_DQS_DP<1>")
	)
	(arc
		(start 140.556234 -280.891488)
		(mid 140.274802 -280.815733)
		(end 139.99337 -280.891488)
		(width 0.09525)
		(layer "In13.Cu")
		(net "M_H_CPU1_SB_DQS_DP<1>")
	)
	(arc
		(start 143.753332 -280.891488)
		(mid 143.569557 -280.94226)
		(end 143.384524 -280.896314)
		(width 0.09525)
		(layer "In13.Cu")
		(net "M_H_CPU1_SB_DQS_DP<1>")
	)
	(arc
		(start 143.376142 -280.891488)
		(mid 143.09471 -280.815733)
		(end 142.813278 -280.891488)
		(width 0.09525)
		(layer "In13.Cu")
		(net "M_H_CPU1_SB_DQS_DP<1>")
	)
	(arc
		(start 139.044934 -280.896314)
		(mid 138.859902 -280.942228)
		(end 138.676126 -280.891488)
		(width 0.09525)
		(layer "In13.Cu")
		(net "M_H_CPU1_SB_DQS_DP<1>")
	)
	(arc
		(start 142.804896 -280.896314)
		(mid 142.619864 -280.942228)
		(end 142.436088 -280.891488)
		(width 0.09525)
		(layer "In13.Cu")
		(net "M_H_CPU1_SB_DQS_DP<1>")
	)
	(arc
		(start 141.873224 -280.891488)
		(mid 141.684756 -280.942165)
		(end 141.496288 -280.891488)
		(width 0.09525)
		(layer "In13.Cu")
		(net "M_H_CPU1_SB_DQS_DP<1>")
	)
	(arc
		(start 139.99337 -280.891488)
		(mid 139.809595 -280.94226)
		(end 139.624562 -280.896314)
		(width 0.09525)
		(layer "In13.Cu")
		(net "M_H_CPU1_SB_DQS_DP<1>")
	)
	(arc
		(start 139.61618 -280.891488)
		(mid 139.334748 -280.815733)
		(end 139.053316 -280.891488)
		(width 0.09525)
		(layer "In13.Cu")
		(net "M_H_CPU1_SB_DQS_DP<1>")
	)
	(arc
		(start 145.255488 -280.891488)
		(mid 144.985547 -280.815362)
		(end 144.712436 -280.879296)
		(width 0.09525)
		(layer "In13.Cu")
		(net "M_H_CPU1_SB_DQS_DP<1>")
	)
	(arc
		(start 138.10488 -280.896314)
		(mid 137.919848 -280.942228)
		(end 137.736072 -280.891488)
		(width 0.09525)
		(layer "In13.Cu")
		(net "M_H_CPU1_SB_DQS_DP<1>")
	)
	(arc
		(start 138.676126 -280.891488)
		(mid 138.394694 -280.815733)
		(end 138.113262 -280.891488)
		(width 0.09525)
		(layer "In13.Cu")
		(net "M_H_CPU1_SB_DQS_DP<1>")
	)
	(arc
		(start 141.496288 -280.891488)
		(mid 141.214856 -280.815733)
		(end 140.933424 -280.891488)
		(width 0.09525)
		(layer "In13.Cu")
		(net "M_H_CPU1_SB_DQS_DP<1>")
	)
	(arc
		(start 137.736072 -280.891488)
		(mid 137.45464 -280.815733)
		(end 137.173208 -280.891488)
		(width 0.09525)
		(layer "In13.Cu")
		(net "M_H_CPU1_SB_DQS_DP<1>")
	)
	(arc
		(start 140.933424 -280.891488)
		(mid 140.749649 -280.94226)
		(end 140.564616 -280.896314)
		(width 0.09525)
		(layer "In13.Cu")
		(net "M_H_CPU1_SB_DQS_DP<1>")
	)
	(arc
		(start 136.320022 -280.85034)
		(mid 136.309694 -280.8543)
		(end 136.299448 -280.858468)
		(width 0.09525)
		(layer "In13.Cu")
		(net "M_H_CPU1_SB_DQS_DP<1>")
	)
	(arc
		(start 144.691608 -280.891488)
		(mid 144.510246 -280.942098)
		(end 144.327118 -280.898346)
		(width 0.09525)
		(layer "In13.Cu")
		(net "M_H_CPU1_SB_DQS_DP<1>")
	)
	(arc
		(start 137.173208 -280.891488)
		(mid 136.98474 -280.942165)
		(end 136.796272 -280.891488)
		(width 0.09525)
		(layer "In13.Cu")
		(net "M_H_CPU1_SB_DQS_DP<1>")
	)
	(arc
		(start 142.436088 -280.891488)
		(mid 142.154656 -280.815733)
		(end 141.873224 -280.891488)
		(width 0.09525)
		(layer "In13.Cu")
		(net "M_H_CPU1_SB_DQS_DP<1>")
	)
	(arc
		(start 145.444718 -280.943304)
		(mid 145.346684 -280.929903)
		(end 145.255488 -280.891488)
		(width 0.09525)
		(layer "In13.Cu")
		(net "M_H_CPU1_SB_DQS_DP<1>")
	)
	(arc
		(start 146.213576 -280.53792)
		(mid 146.070607 -280.566376)
		(end 145.949416 -280.647394)
		(width 0.09525)
		(layer "In13.Cu")
		(net "M_H_CPU1_SB_DQS_DP<1>")
	)
	(arc
		(start 144.294352 -280.879296)
		(mid 144.022289 -280.815858)
		(end 143.753332 -280.891488)
		(width 0.09525)
		(layer "In13.Cu")
		(net "M_H_CPU1_SB_DQS_DP<1>")
	)
	(arc
		(start 136.796272 -280.891488)
		(mid 136.562758 -280.817645)
		(end 136.320022 -280.85034)
		(width 0.09525)
		(layer "In13.Cu")
		(net "M_H_CPU1_SB_DQS_DP<1>")
	)
	(segment
		(start 135.577834 -275.440394)
		(end 136.044686 -275.706332)
		(width 0.12954)
		(layer "F.Cu")
		(net "M_H_CPU1_SB_DQS_DP<0>")
	)
	(segment
		(start 136.19861 -275.971762)
		(end 136.299448 -275.998432)
		(width 0.09525)
		(layer "In13.Cu")
		(net "M_H_CPU1_SB_DQS_DP<0>")
	)
	(segment
		(start 167.964104 -284.205934)
		(end 168.301162 -283.868876)
		(width 0.16002)
		(layer "In13.Cu")
		(net "M_H_CPU1_SB_DQS_DP<0>")
	)
	(segment
		(start 138.10488 -276.036278)
		(end 138.113262 -276.031452)
		(width 0.09525)
		(layer "In13.Cu")
		(net "M_H_CPU1_SB_DQS_DP<0>")
	)
	(segment
		(start 169.338244 -284.410404)
		(end 169.498264 -284.570424)
		(width 0.16002)
		(layer "In13.Cu")
		(net "M_H_CPU1_SB_DQS_DP<0>")
	)
	(segment
		(start 144.294352 -276.01926)
		(end 144.327118 -276.03831)
		(width 0.09525)
		(layer "In13.Cu")
		(net "M_H_CPU1_SB_DQS_DP<0>")
	)
	(segment
		(start 172.523912 -284.738826)
		(end 173.13021 -285.345124)
		(width 0.16002)
		(layer "In13.Cu")
		(net "M_H_CPU1_SB_DQS_DP<0>")
	)
	(segment
		(start 156.30779 -277.589488)
		(end 163.336986 -284.618684)
		(width 0.16002)
		(layer "In13.Cu")
		(net "M_H_CPU1_SB_DQS_DP<0>")
	)
	(segment
		(start 169.81297 -284.570424)
		(end 170.219624 -284.738826)
		(width 0.16002)
		(layer "In13.Cu")
		(net "M_H_CPU1_SB_DQS_DP<0>")
	)
	(segment
		(start 169.338244 -284.205934)
		(end 169.338244 -284.410404)
		(width 0.16002)
		(layer "In13.Cu")
		(net "M_H_CPU1_SB_DQS_DP<0>")
	)
	(segment
		(start 142.804896 -276.036278)
		(end 142.813278 -276.031452)
		(width 0.09525)
		(layer "In13.Cu")
		(net "M_H_CPU1_SB_DQS_DP<0>")
	)
	(segment
		(start 140.556234 -276.031452)
		(end 140.564616 -276.036278)
		(width 0.09525)
		(layer "In13.Cu")
		(net "M_H_CPU1_SB_DQS_DP<0>")
	)
	(segment
		(start 167.804084 -284.570424)
		(end 167.964104 -284.410404)
		(width 0.16002)
		(layer "In13.Cu")
		(net "M_H_CPU1_SB_DQS_DP<0>")
	)
	(segment
		(start 139.61618 -276.031452)
		(end 139.624562 -276.036278)
		(width 0.09525)
		(layer "In13.Cu")
		(net "M_H_CPU1_SB_DQS_DP<0>")
	)
	(segment
		(start 173.13021 -285.345124)
		(end 173.52137 -285.345124)
		(width 0.16002)
		(layer "In13.Cu")
		(net "M_H_CPU1_SB_DQS_DP<0>")
	)
	(segment
		(start 152.630632 -274.89785)
		(end 155.32227 -277.589488)
		(width 0.16002)
		(layer "In13.Cu")
		(net "M_H_CPU1_SB_DQS_DP<0>")
	)
	(segment
		(start 169.498264 -284.570424)
		(end 169.81297 -284.570424)
		(width 0.16002)
		(layer "In13.Cu")
		(net "M_H_CPU1_SB_DQS_DP<0>")
	)
	(segment
		(start 147.7772 -274.89785)
		(end 152.630632 -274.89785)
		(width 0.16002)
		(layer "In13.Cu")
		(net "M_H_CPU1_SB_DQS_DP<0>")
	)
	(segment
		(start 175.801274 -285.156148)
		(end 176.072038 -284.885384)
		(width 0.16002)
		(layer "In13.Cu")
		(net "M_H_CPU1_SB_DQS_DP<0>")
	)
	(segment
		(start 147.283678 -274.997418)
		(end 147.324318 -274.956778)
		(width 0.09525)
		(layer "In13.Cu")
		(net "M_H_CPU1_SB_DQS_DP<0>")
	)
	(segment
		(start 144.712436 -276.01926)
		(end 144.71396 -276.019514)
		(width 0.09525)
		(layer "In13.Cu")
		(net "M_H_CPU1_SB_DQS_DP<0>")
	)
	(segment
		(start 166.772082 -284.570424)
		(end 167.804084 -284.570424)
		(width 0.16002)
		(layer "In13.Cu")
		(net "M_H_CPU1_SB_DQS_DP<0>")
	)
	(segment
		(start 147.324318 -274.956778)
		(end 147.69465 -274.956778)
		(width 0.09525)
		(layer "In13.Cu")
		(net "M_H_CPU1_SB_DQS_DP<0>")
	)
	(segment
		(start 169.001186 -283.868876)
		(end 169.338244 -284.205934)
		(width 0.16002)
		(layer "In13.Cu")
		(net "M_H_CPU1_SB_DQS_DP<0>")
	)
	(segment
		(start 143.376142 -276.031452)
		(end 143.384524 -276.036278)
		(width 0.09525)
		(layer "In13.Cu")
		(net "M_H_CPU1_SB_DQS_DP<0>")
	)
	(segment
		(start 164.947346 -284.618684)
		(end 165.683946 -285.355284)
		(width 0.16002)
		(layer "In13.Cu")
		(net "M_H_CPU1_SB_DQS_DP<0>")
	)
	(segment
		(start 170.219624 -284.738826)
		(end 172.523912 -284.738826)
		(width 0.16002)
		(layer "In13.Cu")
		(net "M_H_CPU1_SB_DQS_DP<0>")
	)
	(segment
		(start 155.32227 -277.589488)
		(end 156.30779 -277.589488)
		(width 0.16002)
		(layer "In13.Cu")
		(net "M_H_CPU1_SB_DQS_DP<0>")
	)
	(segment
		(start 163.336986 -284.618684)
		(end 164.947346 -284.618684)
		(width 0.16002)
		(layer "In13.Cu")
		(net "M_H_CPU1_SB_DQS_DP<0>")
	)
	(segment
		(start 168.301162 -283.868876)
		(end 169.001186 -283.868876)
		(width 0.16002)
		(layer "In13.Cu")
		(net "M_H_CPU1_SB_DQS_DP<0>")
	)
	(segment
		(start 139.044934 -276.036278)
		(end 139.053316 -276.031452)
		(width 0.09525)
		(layer "In13.Cu")
		(net "M_H_CPU1_SB_DQS_DP<0>")
	)
	(segment
		(start 165.683946 -285.355284)
		(end 165.987222 -285.355284)
		(width 0.16002)
		(layer "In13.Cu")
		(net "M_H_CPU1_SB_DQS_DP<0>")
	)
	(segment
		(start 147.69465 -274.956778)
		(end 147.753578 -274.89785)
		(width 0.09525)
		(layer "In13.Cu")
		(net "M_H_CPU1_SB_DQS_DP<0>")
	)
	(segment
		(start 145.70964 -275.972778)
		(end 146.685 -274.997418)
		(width 0.09525)
		(layer "In13.Cu")
		(net "M_H_CPU1_SB_DQS_DP<0>")
	)
	(segment
		(start 136.044686 -275.706332)
		(end 136.19861 -275.971762)
		(width 0.09525)
		(layer "In13.Cu")
		(net "M_H_CPU1_SB_DQS_DP<0>")
	)
	(segment
		(start 165.987222 -285.355284)
		(end 166.772082 -284.570424)
		(width 0.16002)
		(layer "In13.Cu")
		(net "M_H_CPU1_SB_DQS_DP<0>")
	)
	(segment
		(start 167.964104 -284.410404)
		(end 167.964104 -284.205934)
		(width 0.16002)
		(layer "In13.Cu")
		(net "M_H_CPU1_SB_DQS_DP<0>")
	)
	(segment
		(start 146.685 -274.997418)
		(end 147.283678 -274.997418)
		(width 0.09525)
		(layer "In13.Cu")
		(net "M_H_CPU1_SB_DQS_DP<0>")
	)
	(segment
		(start 144.691608 -276.031452)
		(end 144.712436 -276.01926)
		(width 0.09525)
		(layer "In13.Cu")
		(net "M_H_CPU1_SB_DQS_DP<0>")
	)
	(segment
		(start 173.710346 -285.156148)
		(end 175.801274 -285.156148)
		(width 0.16002)
		(layer "In13.Cu")
		(net "M_H_CPU1_SB_DQS_DP<0>")
	)
	(segment
		(start 147.753578 -274.89785)
		(end 147.7772 -274.89785)
		(width 0.09525)
		(layer "In13.Cu")
		(net "M_H_CPU1_SB_DQS_DP<0>")
	)
	(segment
		(start 173.52137 -285.345124)
		(end 173.710346 -285.156148)
		(width 0.16002)
		(layer "In13.Cu")
		(net "M_H_CPU1_SB_DQS_DP<0>")
	)
	(arc
		(start 136.796272 -276.031452)
		(mid 136.98474 -276.082129)
		(end 137.173208 -276.031452)
		(width 0.09525)
		(layer "In13.Cu")
		(net "M_H_CPU1_SB_DQS_DP<0>")
	)
	(arc
		(start 136.299448 -275.998432)
		(mid 136.309696 -275.994269)
		(end 136.320022 -275.990304)
		(width 0.09525)
		(layer "In13.Cu")
		(net "M_H_CPU1_SB_DQS_DP<0>")
	)
	(arc
		(start 138.676126 -276.031452)
		(mid 138.859901 -276.082224)
		(end 139.044934 -276.036278)
		(width 0.09525)
		(layer "In13.Cu")
		(net "M_H_CPU1_SB_DQS_DP<0>")
	)
	(arc
		(start 143.384524 -276.036278)
		(mid 143.569556 -276.082192)
		(end 143.753332 -276.031452)
		(width 0.09525)
		(layer "In13.Cu")
		(net "M_H_CPU1_SB_DQS_DP<0>")
	)
	(arc
		(start 141.496288 -276.031452)
		(mid 141.684756 -276.082129)
		(end 141.873224 -276.031452)
		(width 0.09525)
		(layer "In13.Cu")
		(net "M_H_CPU1_SB_DQS_DP<0>")
	)
	(arc
		(start 141.873224 -276.031452)
		(mid 142.154656 -275.955697)
		(end 142.436088 -276.031452)
		(width 0.09525)
		(layer "In13.Cu")
		(net "M_H_CPU1_SB_DQS_DP<0>")
	)
	(arc
		(start 142.436088 -276.031452)
		(mid 142.619863 -276.082224)
		(end 142.804896 -276.036278)
		(width 0.09525)
		(layer "In13.Cu")
		(net "M_H_CPU1_SB_DQS_DP<0>")
	)
	(arc
		(start 136.320022 -275.990304)
		(mid 136.562764 -275.957534)
		(end 136.796272 -276.031452)
		(width 0.09525)
		(layer "In13.Cu")
		(net "M_H_CPU1_SB_DQS_DP<0>")
	)
	(arc
		(start 140.933424 -276.031452)
		(mid 141.214856 -275.955697)
		(end 141.496288 -276.031452)
		(width 0.09525)
		(layer "In13.Cu")
		(net "M_H_CPU1_SB_DQS_DP<0>")
	)
	(arc
		(start 143.753332 -276.031452)
		(mid 144.022286 -275.955714)
		(end 144.294352 -276.01926)
		(width 0.09525)
		(layer "In13.Cu")
		(net "M_H_CPU1_SB_DQS_DP<0>")
	)
	(arc
		(start 144.327118 -276.03831)
		(mid 144.510245 -276.082022)
		(end 144.691608 -276.031452)
		(width 0.09525)
		(layer "In13.Cu")
		(net "M_H_CPU1_SB_DQS_DP<0>")
	)
	(arc
		(start 138.113262 -276.031452)
		(mid 138.394694 -275.955697)
		(end 138.676126 -276.031452)
		(width 0.09525)
		(layer "In13.Cu")
		(net "M_H_CPU1_SB_DQS_DP<0>")
	)
	(arc
		(start 142.813278 -276.031452)
		(mid 143.09471 -275.955697)
		(end 143.376142 -276.031452)
		(width 0.09525)
		(layer "In13.Cu")
		(net "M_H_CPU1_SB_DQS_DP<0>")
	)
	(arc
		(start 137.173208 -276.031452)
		(mid 137.45464 -275.955697)
		(end 137.736072 -276.031452)
		(width 0.09525)
		(layer "In13.Cu")
		(net "M_H_CPU1_SB_DQS_DP<0>")
	)
	(arc
		(start 139.99337 -276.031452)
		(mid 140.274802 -275.955697)
		(end 140.556234 -276.031452)
		(width 0.09525)
		(layer "In13.Cu")
		(net "M_H_CPU1_SB_DQS_DP<0>")
	)
	(arc
		(start 144.71396 -276.019514)
		(mid 144.986023 -275.956047)
		(end 145.25498 -276.031706)
		(width 0.09525)
		(layer "In13.Cu")
		(net "M_H_CPU1_SB_DQS_DP<0>")
	)
	(arc
		(start 140.564616 -276.036278)
		(mid 140.749648 -276.082192)
		(end 140.933424 -276.031452)
		(width 0.09525)
		(layer "In13.Cu")
		(net "M_H_CPU1_SB_DQS_DP<0>")
	)
	(arc
		(start 139.053316 -276.031452)
		(mid 139.334748 -275.955697)
		(end 139.61618 -276.031452)
		(width 0.09525)
		(layer "In13.Cu")
		(net "M_H_CPU1_SB_DQS_DP<0>")
	)
	(arc
		(start 139.624562 -276.036278)
		(mid 139.809594 -276.082192)
		(end 139.99337 -276.031452)
		(width 0.09525)
		(layer "In13.Cu")
		(net "M_H_CPU1_SB_DQS_DP<0>")
	)
	(arc
		(start 145.25498 -276.031706)
		(mid 145.492316 -276.079548)
		(end 145.70964 -275.972778)
		(width 0.09525)
		(layer "In13.Cu")
		(net "M_H_CPU1_SB_DQS_DP<0>")
	)
	(arc
		(start 137.736072 -276.031452)
		(mid 137.919847 -276.082224)
		(end 138.10488 -276.036278)
		(width 0.09525)
		(layer "In13.Cu")
		(net "M_H_CPU1_SB_DQS_DP<0>")
	)
	(segment
		(start 136.047988 -271.390364)
		(end 136.51484 -271.656302)
		(width 0.12954)
		(layer "F.Cu")
		(net "M_H_CPU1_SB_DQS_DN<9>")
	)
	(segment
		(start 145.79981 -270.249142)
		(end 146.691604 -269.357094)
		(width 0.09525)
		(layer "In13.Cu")
		(net "M_H_CPU1_SB_DQS_DN<9>")
	)
	(segment
		(start 164.377116 -275.11248)
		(end 164.516816 -275.25218)
		(width 0.16002)
		(layer "In13.Cu")
		(net "M_H_CPU1_SB_DQS_DN<9>")
	)
	(segment
		(start 144.221962 -271.33042)
		(end 144.223232 -271.331182)
		(width 0.09525)
		(layer "In13.Cu")
		(net "M_H_CPU1_SB_DQS_DN<9>")
	)
	(segment
		(start 172.29201 -275.962364)
		(end 172.627036 -276.29739)
		(width 0.16002)
		(layer "In13.Cu")
		(net "M_H_CPU1_SB_DQS_DN<9>")
	)
	(segment
		(start 175.591724 -276.139148)
		(end 175.825912 -276.139148)
		(width 0.16002)
		(layer "In13.Cu")
		(net "M_H_CPU1_SB_DQS_DN<9>")
	)
	(segment
		(start 159.731202 -272.151602)
		(end 160.938718 -272.151602)
		(width 0.16002)
		(layer "In13.Cu")
		(net "M_H_CPU1_SB_DQS_DN<9>")
	)
	(segment
		(start 136.360916 -271.390872)
		(end 136.384284 -271.304004)
		(width 0.09525)
		(layer "In13.Cu")
		(net "M_H_CPU1_SB_DQS_DN<9>")
	)
	(segment
		(start 147.204684 -269.357094)
		(end 147.343622 -269.496032)
		(width 0.09525)
		(layer "In13.Cu")
		(net "M_H_CPU1_SB_DQS_DN<9>")
	)
	(segment
		(start 164.994336 -275.25218)
		(end 165.134036 -275.11248)
		(width 0.16002)
		(layer "In13.Cu")
		(net "M_H_CPU1_SB_DQS_DN<9>")
	)
	(segment
		(start 144.213072 -271.32534)
		(end 144.221962 -271.33042)
		(width 0.09525)
		(layer "In13.Cu")
		(net "M_H_CPU1_SB_DQS_DN<9>")
	)
	(segment
		(start 141.966188 -271.331182)
		(end 141.97457 -271.326356)
		(width 0.09525)
		(layer "In13.Cu")
		(net "M_H_CPU1_SB_DQS_DN<9>")
	)
	(segment
		(start 157.134814 -269.555214)
		(end 159.731202 -272.151602)
		(width 0.16002)
		(layer "In13.Cu")
		(net "M_H_CPU1_SB_DQS_DN<9>")
	)
	(segment
		(start 173.804834 -276.139148)
		(end 173.952662 -276.139148)
		(width 0.16002)
		(layer "In13.Cu")
		(net "M_H_CPU1_SB_DQS_DN<9>")
	)
	(segment
		(start 168.700958 -275.983954)
		(end 169.162222 -275.52269)
		(width 0.16002)
		(layer "In13.Cu")
		(net "M_H_CPU1_SB_DQS_DN<9>")
	)
	(segment
		(start 175.149764 -276.581108)
		(end 175.591724 -276.139148)
		(width 0.16002)
		(layer "In13.Cu")
		(net "M_H_CPU1_SB_DQS_DN<9>")
	)
	(segment
		(start 147.8026 -269.555214)
		(end 157.134814 -269.555214)
		(width 0.16002)
		(layer "In13.Cu")
		(net "M_H_CPU1_SB_DQS_DN<9>")
	)
	(segment
		(start 165.134036 -275.11248)
		(end 166.219886 -275.11248)
		(width 0.16002)
		(layer "In13.Cu")
		(net "M_H_CPU1_SB_DQS_DN<9>")
	)
	(segment
		(start 169.945304 -275.52269)
		(end 170.384978 -275.962364)
		(width 0.16002)
		(layer "In13.Cu")
		(net "M_H_CPU1_SB_DQS_DN<9>")
	)
	(segment
		(start 147.778978 -269.555214)
		(end 147.8026 -269.555214)
		(width 0.09525)
		(layer "In13.Cu")
		(net "M_H_CPU1_SB_DQS_DN<9>")
	)
	(segment
		(start 163.899596 -275.11248)
		(end 164.377116 -275.11248)
		(width 0.16002)
		(layer "In13.Cu")
		(net "M_H_CPU1_SB_DQS_DN<9>")
	)
	(segment
		(start 167.96512 -275.983954)
		(end 168.700958 -275.983954)
		(width 0.16002)
		(layer "In13.Cu")
		(net "M_H_CPU1_SB_DQS_DN<9>")
	)
	(segment
		(start 141.394942 -271.326356)
		(end 141.403324 -271.331182)
		(width 0.09525)
		(layer "In13.Cu")
		(net "M_H_CPU1_SB_DQS_DN<9>")
	)
	(segment
		(start 169.162222 -275.52269)
		(end 169.945304 -275.52269)
		(width 0.16002)
		(layer "In13.Cu")
		(net "M_H_CPU1_SB_DQS_DN<9>")
	)
	(segment
		(start 144.786096 -271.331182)
		(end 144.824196 -271.309084)
		(width 0.09525)
		(layer "In13.Cu")
		(net "M_H_CPU1_SB_DQS_DN<9>")
	)
	(segment
		(start 173.646592 -276.29739)
		(end 173.804834 -276.139148)
		(width 0.16002)
		(layer "In13.Cu")
		(net "M_H_CPU1_SB_DQS_DN<9>")
	)
	(segment
		(start 160.938718 -272.151602)
		(end 163.899596 -275.11248)
		(width 0.16002)
		(layer "In13.Cu")
		(net "M_H_CPU1_SB_DQS_DN<9>")
	)
	(segment
		(start 145.25625 -270.521176)
		(end 145.25625 -270.520668)
		(width 0.09525)
		(layer "In13.Cu")
		(net "M_H_CPU1_SB_DQS_DN<9>")
	)
	(segment
		(start 145.223738 -270.539972)
		(end 145.236438 -270.53286)
		(width 0.09525)
		(layer "In13.Cu")
		(net "M_H_CPU1_SB_DQS_DN<9>")
	)
	(segment
		(start 145.236438 -270.53286)
		(end 145.25625 -270.521176)
		(width 0.09525)
		(layer "In13.Cu")
		(net "M_H_CPU1_SB_DQS_DN<9>")
	)
	(segment
		(start 164.516816 -275.25218)
		(end 164.994336 -275.25218)
		(width 0.16002)
		(layer "In13.Cu")
		(net "M_H_CPU1_SB_DQS_DN<9>")
	)
	(segment
		(start 174.394622 -276.581108)
		(end 175.149764 -276.581108)
		(width 0.16002)
		(layer "In13.Cu")
		(net "M_H_CPU1_SB_DQS_DN<9>")
	)
	(segment
		(start 140.454888 -271.326356)
		(end 140.46327 -271.331182)
		(width 0.09525)
		(layer "In13.Cu")
		(net "M_H_CPU1_SB_DQS_DN<9>")
	)
	(segment
		(start 170.384978 -275.962364)
		(end 172.29201 -275.962364)
		(width 0.16002)
		(layer "In13.Cu")
		(net "M_H_CPU1_SB_DQS_DN<9>")
	)
	(segment
		(start 173.952662 -276.139148)
		(end 174.394622 -276.581108)
		(width 0.16002)
		(layer "In13.Cu")
		(net "M_H_CPU1_SB_DQS_DN<9>")
	)
	(segment
		(start 136.51484 -271.656302)
		(end 136.360916 -271.390872)
		(width 0.09525)
		(layer "In13.Cu")
		(net "M_H_CPU1_SB_DQS_DN<9>")
	)
	(segment
		(start 147.719796 -269.496032)
		(end 147.778978 -269.555214)
		(width 0.09525)
		(layer "In13.Cu")
		(net "M_H_CPU1_SB_DQS_DN<9>")
	)
	(segment
		(start 175.825912 -276.139148)
		(end 176.072038 -276.385274)
		(width 0.16002)
		(layer "In13.Cu")
		(net "M_H_CPU1_SB_DQS_DN<9>")
	)
	(segment
		(start 172.627036 -276.29739)
		(end 173.646592 -276.29739)
		(width 0.16002)
		(layer "In13.Cu")
		(net "M_H_CPU1_SB_DQS_DN<9>")
	)
	(segment
		(start 146.691604 -269.357094)
		(end 147.204684 -269.357094)
		(width 0.09525)
		(layer "In13.Cu")
		(net "M_H_CPU1_SB_DQS_DN<9>")
	)
	(segment
		(start 138.206226 -271.331182)
		(end 138.214608 -271.326356)
		(width 0.09525)
		(layer "In13.Cu")
		(net "M_H_CPU1_SB_DQS_DN<9>")
	)
	(segment
		(start 147.343622 -269.496032)
		(end 147.719796 -269.496032)
		(width 0.09525)
		(layer "In13.Cu")
		(net "M_H_CPU1_SB_DQS_DN<9>")
	)
	(segment
		(start 136.694926 -271.326356)
		(end 136.703308 -271.331182)
		(width 0.09525)
		(layer "In13.Cu")
		(net "M_H_CPU1_SB_DQS_DN<9>")
	)
	(segment
		(start 144.205706 -271.32153)
		(end 144.213072 -271.32534)
		(width 0.09525)
		(layer "In13.Cu")
		(net "M_H_CPU1_SB_DQS_DN<9>")
	)
	(segment
		(start 166.630096 -275.52269)
		(end 167.503856 -275.52269)
		(width 0.16002)
		(layer "In13.Cu")
		(net "M_H_CPU1_SB_DQS_DN<9>")
	)
	(segment
		(start 167.503856 -275.52269)
		(end 167.96512 -275.983954)
		(width 0.16002)
		(layer "In13.Cu")
		(net "M_H_CPU1_SB_DQS_DN<9>")
	)
	(segment
		(start 166.219886 -275.11248)
		(end 166.630096 -275.52269)
		(width 0.16002)
		(layer "In13.Cu")
		(net "M_H_CPU1_SB_DQS_DN<9>")
	)
	(segment
		(start 137.266172 -271.331182)
		(end 137.274554 -271.326356)
		(width 0.09525)
		(layer "In13.Cu")
		(net "M_H_CPU1_SB_DQS_DN<9>")
	)
	(arc
		(start 145.25625 -270.520668)
		(mid 145.318159 -270.491831)
		(end 145.384266 -270.474694)
		(width 0.09525)
		(layer "In13.Cu")
		(net "M_H_CPU1_SB_DQS_DN<9>")
	)
	(arc
		(start 144.223232 -271.331182)
		(mid 144.504664 -271.406937)
		(end 144.786096 -271.331182)
		(width 0.09525)
		(layer "In13.Cu")
		(net "M_H_CPU1_SB_DQS_DN<9>")
	)
	(arc
		(start 143.283178 -271.331182)
		(mid 143.56461 -271.406937)
		(end 143.846042 -271.331182)
		(width 0.09525)
		(layer "In13.Cu")
		(net "M_H_CPU1_SB_DQS_DN<9>")
	)
	(arc
		(start 140.46327 -271.331182)
		(mid 140.744702 -271.406937)
		(end 141.026134 -271.331182)
		(width 0.09525)
		(layer "In13.Cu")
		(net "M_H_CPU1_SB_DQS_DN<9>")
	)
	(arc
		(start 138.583416 -271.331182)
		(mid 138.864848 -271.406937)
		(end 139.14628 -271.331182)
		(width 0.09525)
		(layer "In13.Cu")
		(net "M_H_CPU1_SB_DQS_DN<9>")
	)
	(arc
		(start 141.97457 -271.326356)
		(mid 142.159602 -271.280442)
		(end 142.343378 -271.331182)
		(width 0.09525)
		(layer "In13.Cu")
		(net "M_H_CPU1_SB_DQS_DN<9>")
	)
	(arc
		(start 139.14628 -271.331182)
		(mid 139.334748 -271.280505)
		(end 139.523216 -271.331182)
		(width 0.09525)
		(layer "In13.Cu")
		(net "M_H_CPU1_SB_DQS_DN<9>")
	)
	(arc
		(start 140.08608 -271.331182)
		(mid 140.269855 -271.28041)
		(end 140.454888 -271.326356)
		(width 0.09525)
		(layer "In13.Cu")
		(net "M_H_CPU1_SB_DQS_DN<9>")
	)
	(arc
		(start 136.703308 -271.331182)
		(mid 136.98474 -271.406937)
		(end 137.266172 -271.331182)
		(width 0.09525)
		(layer "In13.Cu")
		(net "M_H_CPU1_SB_DQS_DN<9>")
	)
	(arc
		(start 143.846042 -271.331182)
		(mid 144.024648 -271.280514)
		(end 144.205706 -271.32153)
		(width 0.09525)
		(layer "In13.Cu")
		(net "M_H_CPU1_SB_DQS_DN<9>")
	)
	(arc
		(start 138.214608 -271.326356)
		(mid 138.39964 -271.280442)
		(end 138.583416 -271.331182)
		(width 0.09525)
		(layer "In13.Cu")
		(net "M_H_CPU1_SB_DQS_DN<9>")
	)
	(arc
		(start 142.343378 -271.331182)
		(mid 142.62481 -271.406937)
		(end 142.906242 -271.331182)
		(width 0.09525)
		(layer "In13.Cu")
		(net "M_H_CPU1_SB_DQS_DN<9>")
	)
	(arc
		(start 136.384284 -271.304004)
		(mid 136.542034 -271.281485)
		(end 136.694926 -271.326356)
		(width 0.09525)
		(layer "In13.Cu")
		(net "M_H_CPU1_SB_DQS_DN<9>")
	)
	(arc
		(start 144.824196 -271.309084)
		(mid 145.002646 -271.107614)
		(end 145.06702 -270.846296)
		(width 0.09525)
		(layer "In13.Cu")
		(net "M_H_CPU1_SB_DQS_DN<9>")
	)
	(arc
		(start 141.403324 -271.331182)
		(mid 141.684756 -271.406937)
		(end 141.966188 -271.331182)
		(width 0.09525)
		(layer "In13.Cu")
		(net "M_H_CPU1_SB_DQS_DN<9>")
	)
	(arc
		(start 137.643362 -271.331182)
		(mid 137.924794 -271.406937)
		(end 138.206226 -271.331182)
		(width 0.09525)
		(layer "In13.Cu")
		(net "M_H_CPU1_SB_DQS_DN<9>")
	)
	(arc
		(start 145.384266 -270.474694)
		(mid 145.611221 -270.397264)
		(end 145.79981 -270.249142)
		(width 0.09525)
		(layer "In13.Cu")
		(net "M_H_CPU1_SB_DQS_DN<9>")
	)
	(arc
		(start 142.906242 -271.331182)
		(mid 143.09471 -271.280505)
		(end 143.283178 -271.331182)
		(width 0.09525)
		(layer "In13.Cu")
		(net "M_H_CPU1_SB_DQS_DN<9>")
	)
	(arc
		(start 137.274554 -271.326356)
		(mid 137.459586 -271.280442)
		(end 137.643362 -271.331182)
		(width 0.09525)
		(layer "In13.Cu")
		(net "M_H_CPU1_SB_DQS_DN<9>")
	)
	(arc
		(start 139.523216 -271.331182)
		(mid 139.804648 -271.406937)
		(end 140.08608 -271.331182)
		(width 0.09525)
		(layer "In13.Cu")
		(net "M_H_CPU1_SB_DQS_DN<9>")
	)
	(arc
		(start 145.06702 -270.846296)
		(mid 145.108477 -270.674256)
		(end 145.223738 -270.539972)
		(width 0.09525)
		(layer "In13.Cu")
		(net "M_H_CPU1_SB_DQS_DN<9>")
	)
	(arc
		(start 141.026134 -271.331182)
		(mid 141.209909 -271.28041)
		(end 141.394942 -271.326356)
		(width 0.09525)
		(layer "In13.Cu")
		(net "M_H_CPU1_SB_DQS_DN<9>")
	)
	(segment
		(start 134.16788 -290.830254)
		(end 134.634732 -291.096192)
		(width 0.12954)
		(layer "F.Cu")
		(net "M_H_CPU1_SB_DQS_DN<8>")
	)
	(segment
		(start 169.394886 -314.335668)
		(end 169.394886 -314.861702)
		(width 0.16002)
		(layer "In13.Cu")
		(net "M_H_CPU1_SB_DQS_DN<8>")
	)
	(segment
		(start 140.46327 -291.421312)
		(end 140.454888 -291.426138)
		(width 0.09525)
		(layer "In13.Cu")
		(net "M_H_CPU1_SB_DQS_DN<8>")
	)
	(segment
		(start 138.214608 -291.426138)
		(end 138.206226 -291.421312)
		(width 0.09525)
		(layer "In13.Cu")
		(net "M_H_CPU1_SB_DQS_DN<8>")
	)
	(segment
		(start 169.234866 -315.021722)
		(end 168.360852 -315.021722)
		(width 0.16002)
		(layer "In13.Cu")
		(net "M_H_CPU1_SB_DQS_DN<8>")
	)
	(segment
		(start 161.25698 -314.756546)
		(end 161.09696 -314.916566)
		(width 0.16002)
		(layer "In13.Cu")
		(net "M_H_CPU1_SB_DQS_DN<8>")
	)
	(segment
		(start 171.75861 -313.99861)
		(end 169.731944 -313.99861)
		(width 0.16002)
		(layer "In13.Cu")
		(net "M_H_CPU1_SB_DQS_DN<8>")
	)
	(segment
		(start 147.36445 -295.28643)
		(end 147.088098 -295.011094)
		(width 0.16002)
		(layer "In13.Cu")
		(net "M_H_CPU1_SB_DQS_DN<8>")
	)
	(segment
		(start 161.594038 -313.959748)
		(end 161.25698 -314.296806)
		(width 0.16002)
		(layer "In13.Cu")
		(net "M_H_CPU1_SB_DQS_DN<8>")
	)
	(segment
		(start 146.164808 -293.833042)
		(end 146.164554 -293.833042)
		(width 0.09525)
		(layer "In13.Cu")
		(net "M_H_CPU1_SB_DQS_DN<8>")
	)
	(segment
		(start 134.788656 -291.361622)
		(end 134.634732 -291.096192)
		(width 0.09525)
		(layer "In13.Cu")
		(net "M_H_CPU1_SB_DQS_DN<8>")
	)
	(segment
		(start 162.192462 -313.959748)
		(end 161.594038 -313.959748)
		(width 0.16002)
		(layer "In13.Cu")
		(net "M_H_CPU1_SB_DQS_DN<8>")
	)
	(segment
		(start 147.36445 -301.398432)
		(end 147.36445 -295.28643)
		(width 0.16002)
		(layer "In13.Cu")
		(net "M_H_CPU1_SB_DQS_DN<8>")
	)
	(segment
		(start 166.899336 -313.732418)
		(end 165.936168 -314.695586)
		(width 0.16002)
		(layer "In13.Cu")
		(net "M_H_CPU1_SB_DQS_DN<8>")
	)
	(segment
		(start 137.274554 -291.426138)
		(end 137.266172 -291.421312)
		(width 0.09525)
		(layer "In13.Cu")
		(net "M_H_CPU1_SB_DQS_DN<8>")
	)
	(segment
		(start 162.52952 -314.296806)
		(end 162.192462 -313.959748)
		(width 0.16002)
		(layer "In13.Cu")
		(net "M_H_CPU1_SB_DQS_DN<8>")
	)
	(segment
		(start 134.889494 -291.388292)
		(end 134.788656 -291.361622)
		(width 0.09525)
		(layer "In13.Cu")
		(net "M_H_CPU1_SB_DQS_DN<8>")
	)
	(segment
		(start 136.703308 -291.421312)
		(end 136.694926 -291.426138)
		(width 0.09525)
		(layer "In13.Cu")
		(net "M_H_CPU1_SB_DQS_DN<8>")
	)
	(segment
		(start 171.97197 -313.78525)
		(end 171.75861 -313.99861)
		(width 0.16002)
		(layer "In13.Cu")
		(net "M_H_CPU1_SB_DQS_DN<8>")
	)
	(segment
		(start 141.97457 -291.426138)
		(end 141.966188 -291.421312)
		(width 0.09525)
		(layer "In13.Cu")
		(net "M_H_CPU1_SB_DQS_DN<8>")
	)
	(segment
		(start 169.731944 -313.99861)
		(end 169.394886 -314.335668)
		(width 0.16002)
		(layer "In13.Cu")
		(net "M_H_CPU1_SB_DQS_DN<8>")
	)
	(segment
		(start 169.394886 -314.861702)
		(end 169.234866 -315.021722)
		(width 0.16002)
		(layer "In13.Cu")
		(net "M_H_CPU1_SB_DQS_DN<8>")
	)
	(segment
		(start 146.007074 -293.52621)
		(end 146.007074 -293.407338)
		(width 0.09525)
		(layer "In13.Cu")
		(net "M_H_CPU1_SB_DQS_DN<8>")
	)
	(segment
		(start 146.476466 -294.484044)
		(end 146.476466 -294.336216)
		(width 0.09525)
		(layer "In13.Cu")
		(net "M_H_CPU1_SB_DQS_DN<8>")
	)
	(segment
		(start 160.882584 -314.916566)
		(end 147.36445 -301.398432)
		(width 0.16002)
		(layer "In13.Cu")
		(net "M_H_CPU1_SB_DQS_DN<8>")
	)
	(segment
		(start 168.360852 -315.021722)
		(end 168.200832 -314.861702)
		(width 0.16002)
		(layer "In13.Cu")
		(net "M_H_CPU1_SB_DQS_DN<8>")
	)
	(segment
		(start 144.824196 -291.44341)
		(end 144.786096 -291.421312)
		(width 0.09525)
		(layer "In13.Cu")
		(net "M_H_CPU1_SB_DQS_DN<8>")
	)
	(segment
		(start 164.66185 -314.695586)
		(end 164.349938 -314.383674)
		(width 0.16002)
		(layer "In13.Cu")
		(net "M_H_CPU1_SB_DQS_DN<8>")
	)
	(segment
		(start 147.071334 -294.99433)
		(end 146.988022 -294.994838)
		(width 0.09525)
		(layer "In13.Cu")
		(net "M_H_CPU1_SB_DQS_DN<8>")
	)
	(segment
		(start 162.997388 -314.916566)
		(end 162.68954 -314.916566)
		(width 0.16002)
		(layer "In13.Cu")
		(net "M_H_CPU1_SB_DQS_DN<8>")
	)
	(segment
		(start 162.68954 -314.916566)
		(end 162.52952 -314.756546)
		(width 0.16002)
		(layer "In13.Cu")
		(net "M_H_CPU1_SB_DQS_DN<8>")
	)
	(segment
		(start 168.200832 -314.373006)
		(end 167.560244 -313.732418)
		(width 0.16002)
		(layer "In13.Cu")
		(net "M_H_CPU1_SB_DQS_DN<8>")
	)
	(segment
		(start 146.167348 -293.834566)
		(end 146.166332 -293.834058)
		(width 0.09525)
		(layer "In13.Cu")
		(net "M_H_CPU1_SB_DQS_DN<8>")
	)
	(segment
		(start 146.234658 -293.874444)
		(end 146.18081 -293.84244)
		(width 0.09525)
		(layer "In13.Cu")
		(net "M_H_CPU1_SB_DQS_DN<8>")
	)
	(segment
		(start 145.73377 -292.747446)
		(end 145.190464 -292.20414)
		(width 0.09525)
		(layer "In13.Cu")
		(net "M_H_CPU1_SB_DQS_DN<8>")
	)
	(segment
		(start 144.223232 -291.421312)
		(end 144.21485 -291.426138)
		(width 0.09525)
		(layer "In13.Cu")
		(net "M_H_CPU1_SB_DQS_DN<8>")
	)
	(segment
		(start 146.166332 -293.834058)
		(end 146.164808 -293.833042)
		(width 0.09525)
		(layer "In13.Cu")
		(net "M_H_CPU1_SB_DQS_DN<8>")
	)
	(segment
		(start 146.168872 -293.835582)
		(end 146.167348 -293.834566)
		(width 0.09525)
		(layer "In13.Cu")
		(net "M_H_CPU1_SB_DQS_DN<8>")
	)
	(segment
		(start 135.763254 -291.421312)
		(end 135.754872 -291.426138)
		(width 0.09525)
		(layer "In13.Cu")
		(net "M_H_CPU1_SB_DQS_DN<8>")
	)
	(segment
		(start 167.560244 -313.732418)
		(end 166.899336 -313.732418)
		(width 0.16002)
		(layer "In13.Cu")
		(net "M_H_CPU1_SB_DQS_DN<8>")
	)
	(segment
		(start 161.09696 -314.916566)
		(end 160.882584 -314.916566)
		(width 0.16002)
		(layer "In13.Cu")
		(net "M_H_CPU1_SB_DQS_DN<8>")
	)
	(segment
		(start 147.088098 -295.011094)
		(end 147.071334 -294.99433)
		(width 0.09525)
		(layer "In13.Cu")
		(net "M_H_CPU1_SB_DQS_DN<8>")
	)
	(segment
		(start 168.200832 -314.861702)
		(end 168.200832 -314.373006)
		(width 0.16002)
		(layer "In13.Cu")
		(net "M_H_CPU1_SB_DQS_DN<8>")
	)
	(segment
		(start 146.18081 -293.84244)
		(end 146.168872 -293.835582)
		(width 0.09525)
		(layer "In13.Cu")
		(net "M_H_CPU1_SB_DQS_DN<8>")
	)
	(segment
		(start 146.988022 -294.994838)
		(end 146.476466 -294.484044)
		(width 0.09525)
		(layer "In13.Cu")
		(net "M_H_CPU1_SB_DQS_DN<8>")
	)
	(segment
		(start 164.349938 -314.383674)
		(end 163.53028 -314.383674)
		(width 0.16002)
		(layer "In13.Cu")
		(net "M_H_CPU1_SB_DQS_DN<8>")
	)
	(segment
		(start 163.53028 -314.383674)
		(end 162.997388 -314.916566)
		(width 0.16002)
		(layer "In13.Cu")
		(net "M_H_CPU1_SB_DQS_DN<8>")
	)
	(segment
		(start 165.936168 -314.695586)
		(end 164.66185 -314.695586)
		(width 0.16002)
		(layer "In13.Cu")
		(net "M_H_CPU1_SB_DQS_DN<8>")
	)
	(segment
		(start 141.403324 -291.421312)
		(end 141.394942 -291.426138)
		(width 0.09525)
		(layer "In13.Cu")
		(net "M_H_CPU1_SB_DQS_DN<8>")
	)
	(segment
		(start 162.52952 -314.756546)
		(end 162.52952 -314.296806)
		(width 0.16002)
		(layer "In13.Cu")
		(net "M_H_CPU1_SB_DQS_DN<8>")
	)
	(segment
		(start 161.25698 -314.296806)
		(end 161.25698 -314.756546)
		(width 0.16002)
		(layer "In13.Cu")
		(net "M_H_CPU1_SB_DQS_DN<8>")
	)
	(arc
		(start 141.394942 -291.426138)
		(mid 141.20991 -291.472052)
		(end 141.026134 -291.421312)
		(width 0.09525)
		(layer "In13.Cu")
		(net "M_H_CPU1_SB_DQS_DN<8>")
	)
	(arc
		(start 144.786096 -291.421312)
		(mid 144.504664 -291.345557)
		(end 144.223232 -291.421312)
		(width 0.09525)
		(layer "In13.Cu")
		(net "M_H_CPU1_SB_DQS_DN<8>")
	)
	(arc
		(start 144.21485 -291.426138)
		(mid 144.029818 -291.472052)
		(end 143.846042 -291.421312)
		(width 0.09525)
		(layer "In13.Cu")
		(net "M_H_CPU1_SB_DQS_DN<8>")
	)
	(arc
		(start 145.06702 -291.906198)
		(mid 145.002623 -291.644892)
		(end 144.824196 -291.44341)
		(width 0.09525)
		(layer "In13.Cu")
		(net "M_H_CPU1_SB_DQS_DN<8>")
	)
	(arc
		(start 142.906242 -291.421312)
		(mid 142.62481 -291.345557)
		(end 142.343378 -291.421312)
		(width 0.09525)
		(layer "In13.Cu")
		(net "M_H_CPU1_SB_DQS_DN<8>")
	)
	(arc
		(start 143.846042 -291.421312)
		(mid 143.56461 -291.345557)
		(end 143.283178 -291.421312)
		(width 0.09525)
		(layer "In13.Cu")
		(net "M_H_CPU1_SB_DQS_DN<8>")
	)
	(arc
		(start 143.283178 -291.421312)
		(mid 143.09471 -291.471989)
		(end 142.906242 -291.421312)
		(width 0.09525)
		(layer "In13.Cu")
		(net "M_H_CPU1_SB_DQS_DN<8>")
	)
	(arc
		(start 137.266172 -291.421312)
		(mid 136.98474 -291.345557)
		(end 136.703308 -291.421312)
		(width 0.09525)
		(layer "In13.Cu")
		(net "M_H_CPU1_SB_DQS_DN<8>")
	)
	(arc
		(start 135.386064 -291.421312)
		(mid 135.15252 -291.347606)
		(end 134.909814 -291.380418)
		(width 0.09525)
		(layer "In13.Cu")
		(net "M_H_CPU1_SB_DQS_DN<8>")
	)
	(arc
		(start 135.754872 -291.426138)
		(mid 135.56984 -291.472052)
		(end 135.386064 -291.421312)
		(width 0.09525)
		(layer "In13.Cu")
		(net "M_H_CPU1_SB_DQS_DN<8>")
	)
	(arc
		(start 141.966188 -291.421312)
		(mid 141.684756 -291.345557)
		(end 141.403324 -291.421312)
		(width 0.09525)
		(layer "In13.Cu")
		(net "M_H_CPU1_SB_DQS_DN<8>")
	)
	(arc
		(start 140.08608 -291.421312)
		(mid 139.804648 -291.345557)
		(end 139.523216 -291.421312)
		(width 0.09525)
		(layer "In13.Cu")
		(net "M_H_CPU1_SB_DQS_DN<8>")
	)
	(arc
		(start 139.14628 -291.421312)
		(mid 138.864848 -291.345557)
		(end 138.583416 -291.421312)
		(width 0.09525)
		(layer "In13.Cu")
		(net "M_H_CPU1_SB_DQS_DN<8>")
	)
	(arc
		(start 142.343378 -291.421312)
		(mid 142.159603 -291.472084)
		(end 141.97457 -291.426138)
		(width 0.09525)
		(layer "In13.Cu")
		(net "M_H_CPU1_SB_DQS_DN<8>")
	)
	(arc
		(start 146.164554 -293.833042)
		(mid 146.048756 -293.698648)
		(end 146.007074 -293.52621)
		(width 0.09525)
		(layer "In13.Cu")
		(net "M_H_CPU1_SB_DQS_DN<8>")
	)
	(arc
		(start 146.007074 -293.407338)
		(mid 145.936039 -293.050219)
		(end 145.73377 -292.747446)
		(width 0.09525)
		(layer "In13.Cu")
		(net "M_H_CPU1_SB_DQS_DN<8>")
	)
	(arc
		(start 139.523216 -291.421312)
		(mid 139.334748 -291.471989)
		(end 139.14628 -291.421312)
		(width 0.09525)
		(layer "In13.Cu")
		(net "M_H_CPU1_SB_DQS_DN<8>")
	)
	(arc
		(start 138.206226 -291.421312)
		(mid 137.924794 -291.345557)
		(end 137.643362 -291.421312)
		(width 0.09525)
		(layer "In13.Cu")
		(net "M_H_CPU1_SB_DQS_DN<8>")
	)
	(arc
		(start 136.694926 -291.426138)
		(mid 136.509894 -291.472052)
		(end 136.326118 -291.421312)
		(width 0.09525)
		(layer "In13.Cu")
		(net "M_H_CPU1_SB_DQS_DN<8>")
	)
	(arc
		(start 136.326118 -291.421312)
		(mid 136.044686 -291.345557)
		(end 135.763254 -291.421312)
		(width 0.09525)
		(layer "In13.Cu")
		(net "M_H_CPU1_SB_DQS_DN<8>")
	)
	(arc
		(start 140.454888 -291.426138)
		(mid 140.269856 -291.472052)
		(end 140.08608 -291.421312)
		(width 0.09525)
		(layer "In13.Cu")
		(net "M_H_CPU1_SB_DQS_DN<8>")
	)
	(arc
		(start 134.909814 -291.380418)
		(mid 134.899615 -291.384255)
		(end 134.889494 -291.388292)
		(width 0.09525)
		(layer "In13.Cu")
		(net "M_H_CPU1_SB_DQS_DN<8>")
	)
	(arc
		(start 145.190464 -292.20414)
		(mid 145.099126 -292.067443)
		(end 145.06702 -291.906198)
		(width 0.09525)
		(layer "In13.Cu")
		(net "M_H_CPU1_SB_DQS_DN<8>")
	)
	(arc
		(start 146.476466 -294.336216)
		(mid 146.412358 -294.075587)
		(end 146.234658 -293.874444)
		(width 0.09525)
		(layer "In13.Cu")
		(net "M_H_CPU1_SB_DQS_DN<8>")
	)
	(arc
		(start 137.643362 -291.421312)
		(mid 137.459587 -291.472084)
		(end 137.274554 -291.426138)
		(width 0.09525)
		(layer "In13.Cu")
		(net "M_H_CPU1_SB_DQS_DN<8>")
	)
	(arc
		(start 138.583416 -291.421312)
		(mid 138.399641 -291.472084)
		(end 138.214608 -291.426138)
		(width 0.09525)
		(layer "In13.Cu")
		(net "M_H_CPU1_SB_DQS_DN<8>")
	)
	(arc
		(start 141.026134 -291.421312)
		(mid 140.744702 -291.345557)
		(end 140.46327 -291.421312)
		(width 0.09525)
		(layer "In13.Cu")
		(net "M_H_CPU1_SB_DQS_DN<8>")
	)
	(segment
		(start 134.16788 -285.970472)
		(end 134.634732 -286.23641)
		(width 0.12954)
		(layer "F.Cu")
		(net "M_H_CPU1_SB_DQS_DN<7>")
	)
	(segment
		(start 147.658328 -287.429702)
		(end 147.818602 -287.589976)
		(width 0.09525)
		(layer "In13.Cu")
		(net "M_H_CPU1_SB_DQS_DN<7>")
	)
	(segment
		(start 162.960558 -305.180238)
		(end 163.120578 -305.340258)
		(width 0.16002)
		(layer "In13.Cu")
		(net "M_H_CPU1_SB_DQS_DN<7>")
	)
	(segment
		(start 159.958024 -303.55032)
		(end 160.454086 -304.046382)
		(width 0.16002)
		(layer "In13.Cu")
		(net "M_H_CPU1_SB_DQS_DN<7>")
	)
	(segment
		(start 157.227524 -301.98949)
		(end 157.545786 -302.307752)
		(width 0.16002)
		(layer "In13.Cu")
		(net "M_H_CPU1_SB_DQS_DN<7>")
	)
	(segment
		(start 160.222946 -304.754026)
		(end 160.222946 -304.980086)
		(width 0.16002)
		(layer "In13.Cu")
		(net "M_H_CPU1_SB_DQS_DN<7>")
	)
	(segment
		(start 158.961836 -302.58639)
		(end 158.961836 -303.062894)
		(width 0.16002)
		(layer "In13.Cu")
		(net "M_H_CPU1_SB_DQS_DN<7>")
	)
	(segment
		(start 156.254958 -300.790864)
		(end 156.472382 -300.57344)
		(width 0.16002)
		(layer "In13.Cu")
		(net "M_H_CPU1_SB_DQS_DN<7>")
	)
	(segment
		(start 157.444948 -301.069502)
		(end 157.444948 -301.546006)
		(width 0.16002)
		(layer "In13.Cu")
		(net "M_H_CPU1_SB_DQS_DN<7>")
	)
	(segment
		(start 160.222946 -304.980086)
		(end 160.583118 -305.340258)
		(width 0.16002)
		(layer "In13.Cu")
		(net "M_H_CPU1_SB_DQS_DN<7>")
	)
	(segment
		(start 135.754872 -286.566356)
		(end 135.763254 -286.56153)
		(width 0.09525)
		(layer "In13.Cu")
		(net "M_H_CPU1_SB_DQS_DN<7>")
	)
	(segment
		(start 146.650202 -286.981646)
		(end 147.320254 -286.981646)
		(width 0.09525)
		(layer "In13.Cu")
		(net "M_H_CPU1_SB_DQS_DN<7>")
	)
	(segment
		(start 140.454888 -286.566356)
		(end 140.46327 -286.56153)
		(width 0.09525)
		(layer "In13.Cu")
		(net "M_H_CPU1_SB_DQS_DN<7>")
	)
	(segment
		(start 166.789608 -304.492152)
		(end 169.844212 -304.492152)
		(width 0.16002)
		(layer "In13.Cu")
		(net "M_H_CPU1_SB_DQS_DN<7>")
	)
	(segment
		(start 162.960558 -304.940462)
		(end 162.960558 -305.180238)
		(width 0.16002)
		(layer "In13.Cu")
		(net "M_H_CPU1_SB_DQS_DN<7>")
	)
	(segment
		(start 137.266172 -286.56153)
		(end 137.274554 -286.566356)
		(width 0.09525)
		(layer "In13.Cu")
		(net "M_H_CPU1_SB_DQS_DN<7>")
	)
	(segment
		(start 159.02432 -303.78146)
		(end 159.25038 -303.78146)
		(width 0.16002)
		(layer "In13.Cu")
		(net "M_H_CPU1_SB_DQS_DN<7>")
	)
	(segment
		(start 161.586418 -305.180238)
		(end 161.586418 -304.940462)
		(width 0.16002)
		(layer "In13.Cu")
		(net "M_H_CPU1_SB_DQS_DN<7>")
	)
	(segment
		(start 161.923476 -304.603404)
		(end 162.6235 -304.603404)
		(width 0.16002)
		(layer "In13.Cu")
		(net "M_H_CPU1_SB_DQS_DN<7>")
	)
	(segment
		(start 152.93721 -297.699176)
		(end 156.028898 -300.790864)
		(width 0.16002)
		(layer "In13.Cu")
		(net "M_H_CPU1_SB_DQS_DN<7>")
	)
	(segment
		(start 141.394942 -286.566356)
		(end 141.403324 -286.56153)
		(width 0.09525)
		(layer "In13.Cu")
		(net "M_H_CPU1_SB_DQS_DN<7>")
	)
	(segment
		(start 159.25038 -303.78146)
		(end 159.48152 -303.55032)
		(width 0.16002)
		(layer "In13.Cu")
		(net "M_H_CPU1_SB_DQS_DN<7>")
	)
	(segment
		(start 147.320254 -286.981646)
		(end 147.658328 -287.31972)
		(width 0.09525)
		(layer "In13.Cu")
		(net "M_H_CPU1_SB_DQS_DN<7>")
	)
	(segment
		(start 134.634732 -286.23641)
		(end 134.788656 -286.50184)
		(width 0.09525)
		(layer "In13.Cu")
		(net "M_H_CPU1_SB_DQS_DN<7>")
	)
	(segment
		(start 158.746952 -303.277778)
		(end 158.746952 -303.504092)
		(width 0.16002)
		(layer "In13.Cu")
		(net "M_H_CPU1_SB_DQS_DN<7>")
	)
	(segment
		(start 170.066208 -304.714148)
		(end 171.693078 -304.714148)
		(width 0.16002)
		(layer "In13.Cu")
		(net "M_H_CPU1_SB_DQS_DN<7>")
	)
	(segment
		(start 160.454086 -304.522886)
		(end 160.222946 -304.754026)
		(width 0.16002)
		(layer "In13.Cu")
		(net "M_H_CPU1_SB_DQS_DN<7>")
	)
	(segment
		(start 157.227524 -301.76343)
		(end 157.227524 -301.98949)
		(width 0.16002)
		(layer "In13.Cu")
		(net "M_H_CPU1_SB_DQS_DN<7>")
	)
	(segment
		(start 157.98927 -302.090328)
		(end 158.465774 -302.090328)
		(width 0.16002)
		(layer "In13.Cu")
		(net "M_H_CPU1_SB_DQS_DN<7>")
	)
	(segment
		(start 146.15414 -286.485584)
		(end 146.650202 -286.981646)
		(width 0.09525)
		(layer "In13.Cu")
		(net "M_H_CPU1_SB_DQS_DN<7>")
	)
	(segment
		(start 134.788656 -286.50184)
		(end 134.889494 -286.52851)
		(width 0.09525)
		(layer "In13.Cu")
		(net "M_H_CPU1_SB_DQS_DN<7>")
	)
	(segment
		(start 156.472382 -300.57344)
		(end 156.948886 -300.57344)
		(width 0.16002)
		(layer "In13.Cu")
		(net "M_H_CPU1_SB_DQS_DN<7>")
	)
	(segment
		(start 161.426398 -305.340258)
		(end 161.586418 -305.180238)
		(width 0.16002)
		(layer "In13.Cu")
		(net "M_H_CPU1_SB_DQS_DN<7>")
	)
	(segment
		(start 171.693078 -304.714148)
		(end 171.97197 -304.435256)
		(width 0.16002)
		(layer "In13.Cu")
		(net "M_H_CPU1_SB_DQS_DN<7>")
	)
	(segment
		(start 152.93721 -292.624764)
		(end 152.93721 -297.699176)
		(width 0.16002)
		(layer "In13.Cu")
		(net "M_H_CPU1_SB_DQS_DN<7>")
	)
	(segment
		(start 159.48152 -303.55032)
		(end 159.958024 -303.55032)
		(width 0.16002)
		(layer "In13.Cu")
		(net "M_H_CPU1_SB_DQS_DN<7>")
	)
	(segment
		(start 161.586418 -304.940462)
		(end 161.923476 -304.603404)
		(width 0.16002)
		(layer "In13.Cu")
		(net "M_H_CPU1_SB_DQS_DN<7>")
	)
	(segment
		(start 147.919186 -287.60674)
		(end 152.93721 -292.624764)
		(width 0.16002)
		(layer "In13.Cu")
		(net "M_H_CPU1_SB_DQS_DN<7>")
	)
	(segment
		(start 158.746952 -303.504092)
		(end 159.02432 -303.78146)
		(width 0.16002)
		(layer "In13.Cu")
		(net "M_H_CPU1_SB_DQS_DN<7>")
	)
	(segment
		(start 147.902422 -287.589976)
		(end 147.919186 -287.60674)
		(width 0.09525)
		(layer "In13.Cu")
		(net "M_H_CPU1_SB_DQS_DN<7>")
	)
	(segment
		(start 136.694926 -286.566356)
		(end 136.703308 -286.56153)
		(width 0.09525)
		(layer "In13.Cu")
		(net "M_H_CPU1_SB_DQS_DN<7>")
	)
	(segment
		(start 163.120578 -305.340258)
		(end 165.941502 -305.340258)
		(width 0.16002)
		(layer "In13.Cu")
		(net "M_H_CPU1_SB_DQS_DN<7>")
	)
	(segment
		(start 160.454086 -304.046382)
		(end 160.454086 -304.522886)
		(width 0.16002)
		(layer "In13.Cu")
		(net "M_H_CPU1_SB_DQS_DN<7>")
	)
	(segment
		(start 147.818602 -287.589976)
		(end 147.902422 -287.589976)
		(width 0.09525)
		(layer "In13.Cu")
		(net "M_H_CPU1_SB_DQS_DN<7>")
	)
	(segment
		(start 141.966188 -286.56153)
		(end 141.97457 -286.566356)
		(width 0.09525)
		(layer "In13.Cu")
		(net "M_H_CPU1_SB_DQS_DN<7>")
	)
	(segment
		(start 157.771846 -302.307752)
		(end 157.98927 -302.090328)
		(width 0.16002)
		(layer "In13.Cu")
		(net "M_H_CPU1_SB_DQS_DN<7>")
	)
	(segment
		(start 160.583118 -305.340258)
		(end 161.426398 -305.340258)
		(width 0.16002)
		(layer "In13.Cu")
		(net "M_H_CPU1_SB_DQS_DN<7>")
	)
	(segment
		(start 157.545786 -302.307752)
		(end 157.771846 -302.307752)
		(width 0.16002)
		(layer "In13.Cu")
		(net "M_H_CPU1_SB_DQS_DN<7>")
	)
	(segment
		(start 143.846042 -286.56153)
		(end 143.854424 -286.566356)
		(width 0.09525)
		(layer "In13.Cu")
		(net "M_H_CPU1_SB_DQS_DN<7>")
	)
	(segment
		(start 156.948886 -300.57344)
		(end 157.444948 -301.069502)
		(width 0.16002)
		(layer "In13.Cu")
		(net "M_H_CPU1_SB_DQS_DN<7>")
	)
	(segment
		(start 165.941502 -305.340258)
		(end 166.789608 -304.492152)
		(width 0.16002)
		(layer "In13.Cu")
		(net "M_H_CPU1_SB_DQS_DN<7>")
	)
	(segment
		(start 158.961836 -303.062894)
		(end 158.746952 -303.277778)
		(width 0.16002)
		(layer "In13.Cu")
		(net "M_H_CPU1_SB_DQS_DN<7>")
	)
	(segment
		(start 138.206226 -286.56153)
		(end 138.214608 -286.566356)
		(width 0.09525)
		(layer "In13.Cu")
		(net "M_H_CPU1_SB_DQS_DN<7>")
	)
	(segment
		(start 144.50568 -286.485584)
		(end 146.15414 -286.485584)
		(width 0.09525)
		(layer "In13.Cu")
		(net "M_H_CPU1_SB_DQS_DN<7>")
	)
	(segment
		(start 169.844212 -304.492152)
		(end 170.066208 -304.714148)
		(width 0.16002)
		(layer "In13.Cu")
		(net "M_H_CPU1_SB_DQS_DN<7>")
	)
	(segment
		(start 158.465774 -302.090328)
		(end 158.961836 -302.58639)
		(width 0.16002)
		(layer "In13.Cu")
		(net "M_H_CPU1_SB_DQS_DN<7>")
	)
	(segment
		(start 156.028898 -300.790864)
		(end 156.254958 -300.790864)
		(width 0.16002)
		(layer "In13.Cu")
		(net "M_H_CPU1_SB_DQS_DN<7>")
	)
	(segment
		(start 157.444948 -301.546006)
		(end 157.227524 -301.76343)
		(width 0.16002)
		(layer "In13.Cu")
		(net "M_H_CPU1_SB_DQS_DN<7>")
	)
	(segment
		(start 147.658328 -287.31972)
		(end 147.658328 -287.429702)
		(width 0.09525)
		(layer "In13.Cu")
		(net "M_H_CPU1_SB_DQS_DN<7>")
	)
	(segment
		(start 162.6235 -304.603404)
		(end 162.960558 -304.940462)
		(width 0.16002)
		(layer "In13.Cu")
		(net "M_H_CPU1_SB_DQS_DN<7>")
	)
	(arc
		(start 142.343378 -286.56153)
		(mid 142.62481 -286.485741)
		(end 142.906242 -286.56153)
		(width 0.09525)
		(layer "In13.Cu")
		(net "M_H_CPU1_SB_DQS_DN<7>")
	)
	(arc
		(start 141.026134 -286.56153)
		(mid 141.209909 -286.612302)
		(end 141.394942 -286.566356)
		(width 0.09525)
		(layer "In13.Cu")
		(net "M_H_CPU1_SB_DQS_DN<7>")
	)
	(arc
		(start 140.08608 -286.56153)
		(mid 140.269855 -286.612302)
		(end 140.454888 -286.566356)
		(width 0.09525)
		(layer "In13.Cu")
		(net "M_H_CPU1_SB_DQS_DN<7>")
	)
	(arc
		(start 138.214608 -286.566356)
		(mid 138.39964 -286.61227)
		(end 138.583416 -286.56153)
		(width 0.09525)
		(layer "In13.Cu")
		(net "M_H_CPU1_SB_DQS_DN<7>")
	)
	(arc
		(start 139.14628 -286.56153)
		(mid 139.334748 -286.612207)
		(end 139.523216 -286.56153)
		(width 0.09525)
		(layer "In13.Cu")
		(net "M_H_CPU1_SB_DQS_DN<7>")
	)
	(arc
		(start 134.909814 -286.520382)
		(mid 135.152556 -286.487597)
		(end 135.386064 -286.56153)
		(width 0.09525)
		(layer "In13.Cu")
		(net "M_H_CPU1_SB_DQS_DN<7>")
	)
	(arc
		(start 140.46327 -286.56153)
		(mid 140.744702 -286.485741)
		(end 141.026134 -286.56153)
		(width 0.09525)
		(layer "In13.Cu")
		(net "M_H_CPU1_SB_DQS_DN<7>")
	)
	(arc
		(start 135.386064 -286.56153)
		(mid 135.569839 -286.612302)
		(end 135.754872 -286.566356)
		(width 0.09525)
		(layer "In13.Cu")
		(net "M_H_CPU1_SB_DQS_DN<7>")
	)
	(arc
		(start 136.326118 -286.56153)
		(mid 136.509893 -286.612302)
		(end 136.694926 -286.566356)
		(width 0.09525)
		(layer "In13.Cu")
		(net "M_H_CPU1_SB_DQS_DN<7>")
	)
	(arc
		(start 141.403324 -286.56153)
		(mid 141.684756 -286.485741)
		(end 141.966188 -286.56153)
		(width 0.09525)
		(layer "In13.Cu")
		(net "M_H_CPU1_SB_DQS_DN<7>")
	)
	(arc
		(start 143.283178 -286.56153)
		(mid 143.56461 -286.485741)
		(end 143.846042 -286.56153)
		(width 0.09525)
		(layer "In13.Cu")
		(net "M_H_CPU1_SB_DQS_DN<7>")
	)
	(arc
		(start 142.906242 -286.56153)
		(mid 143.09471 -286.612207)
		(end 143.283178 -286.56153)
		(width 0.09525)
		(layer "In13.Cu")
		(net "M_H_CPU1_SB_DQS_DN<7>")
	)
	(arc
		(start 141.97457 -286.566356)
		(mid 142.159602 -286.61227)
		(end 142.343378 -286.56153)
		(width 0.09525)
		(layer "In13.Cu")
		(net "M_H_CPU1_SB_DQS_DN<7>")
	)
	(arc
		(start 137.643362 -286.56153)
		(mid 137.924794 -286.485741)
		(end 138.206226 -286.56153)
		(width 0.09525)
		(layer "In13.Cu")
		(net "M_H_CPU1_SB_DQS_DN<7>")
	)
	(arc
		(start 143.854424 -286.566356)
		(mid 144.03971 -286.612392)
		(end 144.22374 -286.56153)
		(width 0.09525)
		(layer "In13.Cu")
		(net "M_H_CPU1_SB_DQS_DN<7>")
	)
	(arc
		(start 138.583416 -286.56153)
		(mid 138.864848 -286.485741)
		(end 139.14628 -286.56153)
		(width 0.09525)
		(layer "In13.Cu")
		(net "M_H_CPU1_SB_DQS_DN<7>")
	)
	(arc
		(start 136.703308 -286.56153)
		(mid 136.98474 -286.485741)
		(end 137.266172 -286.56153)
		(width 0.09525)
		(layer "In13.Cu")
		(net "M_H_CPU1_SB_DQS_DN<7>")
	)
	(arc
		(start 137.274554 -286.566356)
		(mid 137.459586 -286.61227)
		(end 137.643362 -286.56153)
		(width 0.09525)
		(layer "In13.Cu")
		(net "M_H_CPU1_SB_DQS_DN<7>")
	)
	(arc
		(start 134.889494 -286.52851)
		(mid 134.899615 -286.524348)
		(end 134.909814 -286.520382)
		(width 0.09525)
		(layer "In13.Cu")
		(net "M_H_CPU1_SB_DQS_DN<7>")
	)
	(arc
		(start 139.523216 -286.56153)
		(mid 139.804648 -286.485741)
		(end 140.08608 -286.56153)
		(width 0.09525)
		(layer "In13.Cu")
		(net "M_H_CPU1_SB_DQS_DN<7>")
	)
	(arc
		(start 144.22374 -286.56153)
		(mid 144.359677 -286.504856)
		(end 144.50568 -286.485584)
		(width 0.09525)
		(layer "In13.Cu")
		(net "M_H_CPU1_SB_DQS_DN<7>")
	)
	(arc
		(start 135.763254 -286.56153)
		(mid 136.044686 -286.485741)
		(end 136.326118 -286.56153)
		(width 0.09525)
		(layer "In13.Cu")
		(net "M_H_CPU1_SB_DQS_DN<7>")
	)
	(segment
		(start 134.16788 -281.110436)
		(end 134.634732 -281.376374)
		(width 0.12954)
		(layer "F.Cu")
		(net "M_H_CPU1_SB_DQS_DN<6>")
	)
	(segment
		(start 164.485828 -295.82364)
		(end 164.14877 -295.486582)
		(width 0.16002)
		(layer "In13.Cu")
		(net "M_H_CPU1_SB_DQS_DN<6>")
	)
	(segment
		(start 161.513012 -296.34942)
		(end 159.629602 -294.46601)
		(width 0.16002)
		(layer "In13.Cu")
		(net "M_H_CPU1_SB_DQS_DN<6>")
	)
	(segment
		(start 160.054036 -292.348158)
		(end 159.577532 -292.348158)
		(width 0.16002)
		(layer "In13.Cu")
		(net "M_H_CPU1_SB_DQS_DN<6>")
	)
	(segment
		(start 158.47441 -290.299648)
		(end 149.993096 -281.818334)
		(width 0.16002)
		(layer "In13.Cu")
		(net "M_H_CPU1_SB_DQS_DN<6>")
	)
	(segment
		(start 146.893026 -281.877516)
		(end 146.721576 -281.706066)
		(width 0.09525)
		(layer "In13.Cu")
		(net "M_H_CPU1_SB_DQS_DN<6>")
	)
	(segment
		(start 171.690284 -295.366948)
		(end 170.069002 -295.366948)
		(width 0.16002)
		(layer "In13.Cu")
		(net "M_H_CPU1_SB_DQS_DN<6>")
	)
	(segment
		(start 141.403324 -281.701494)
		(end 141.394942 -281.70632)
		(width 0.09525)
		(layer "In13.Cu")
		(net "M_H_CPU1_SB_DQS_DN<6>")
	)
	(segment
		(start 163.111688 -296.1894)
		(end 162.951668 -296.34942)
		(width 0.16002)
		(layer "In13.Cu")
		(net "M_H_CPU1_SB_DQS_DN<6>")
	)
	(segment
		(start 159.629602 -294.46601)
		(end 159.629602 -294.239696)
		(width 0.16002)
		(layer "In13.Cu")
		(net "M_H_CPU1_SB_DQS_DN<6>")
	)
	(segment
		(start 149.993096 -281.818334)
		(end 147.673314 -281.818334)
		(width 0.16002)
		(layer "In13.Cu")
		(net "M_H_CPU1_SB_DQS_DN<6>")
	)
	(segment
		(start 158.47441 -292.904926)
		(end 158.47441 -290.299648)
		(width 0.16002)
		(layer "In13.Cu")
		(net "M_H_CPU1_SB_DQS_DN<6>")
	)
	(segment
		(start 140.46327 -281.701494)
		(end 140.454888 -281.70632)
		(width 0.09525)
		(layer "In13.Cu")
		(net "M_H_CPU1_SB_DQS_DN<6>")
	)
	(segment
		(start 158.63443 -293.064946)
		(end 158.47441 -292.904926)
		(width 0.16002)
		(layer "In13.Cu")
		(net "M_H_CPU1_SB_DQS_DN<6>")
	)
	(segment
		(start 137.274554 -281.70632)
		(end 137.266172 -281.701494)
		(width 0.09525)
		(layer "In13.Cu")
		(net "M_H_CPU1_SB_DQS_DN<6>")
	)
	(segment
		(start 163.448746 -295.486582)
		(end 163.111688 -295.82364)
		(width 0.16002)
		(layer "In13.Cu")
		(net "M_H_CPU1_SB_DQS_DN<6>")
	)
	(segment
		(start 134.889494 -281.668474)
		(end 134.788656 -281.641804)
		(width 0.09525)
		(layer "In13.Cu")
		(net "M_H_CPU1_SB_DQS_DN<6>")
	)
	(segment
		(start 144.797018 -281.708352)
		(end 144.78508 -281.701494)
		(width 0.09525)
		(layer "In13.Cu")
		(net "M_H_CPU1_SB_DQS_DN<6>")
	)
	(segment
		(start 164.645848 -296.34942)
		(end 164.485828 -296.1894)
		(width 0.16002)
		(layer "In13.Cu")
		(net "M_H_CPU1_SB_DQS_DN<6>")
	)
	(segment
		(start 144.241012 -281.69108)
		(end 144.222978 -281.701494)
		(width 0.09525)
		(layer "In13.Cu")
		(net "M_H_CPU1_SB_DQS_DN<6>")
	)
	(segment
		(start 135.763254 -281.701494)
		(end 135.754872 -281.70632)
		(width 0.09525)
		(layer "In13.Cu")
		(net "M_H_CPU1_SB_DQS_DN<6>")
	)
	(segment
		(start 158.860744 -293.064946)
		(end 158.63443 -293.064946)
		(width 0.16002)
		(layer "In13.Cu")
		(net "M_H_CPU1_SB_DQS_DN<6>")
	)
	(segment
		(start 162.951668 -296.34942)
		(end 161.513012 -296.34942)
		(width 0.16002)
		(layer "In13.Cu")
		(net "M_H_CPU1_SB_DQS_DN<6>")
	)
	(segment
		(start 147.59051 -281.877516)
		(end 146.893026 -281.877516)
		(width 0.09525)
		(layer "In13.Cu")
		(net "M_H_CPU1_SB_DQS_DN<6>")
	)
	(segment
		(start 138.214608 -281.70632)
		(end 138.206226 -281.701494)
		(width 0.09525)
		(layer "In13.Cu")
		(net "M_H_CPU1_SB_DQS_DN<6>")
	)
	(segment
		(start 147.673314 -281.818334)
		(end 147.649692 -281.818334)
		(width 0.09525)
		(layer "In13.Cu")
		(net "M_H_CPU1_SB_DQS_DN<6>")
	)
	(segment
		(start 171.97197 -295.085262)
		(end 171.690284 -295.366948)
		(width 0.16002)
		(layer "In13.Cu")
		(net "M_H_CPU1_SB_DQS_DN<6>")
	)
	(segment
		(start 160.549336 -292.843458)
		(end 160.054036 -292.348158)
		(width 0.16002)
		(layer "In13.Cu")
		(net "M_H_CPU1_SB_DQS_DN<6>")
	)
	(segment
		(start 169.844212 -295.142158)
		(end 166.789608 -295.142158)
		(width 0.16002)
		(layer "In13.Cu")
		(net "M_H_CPU1_SB_DQS_DN<6>")
	)
	(segment
		(start 165.081712 -296.34942)
		(end 164.645848 -296.34942)
		(width 0.16002)
		(layer "In13.Cu")
		(net "M_H_CPU1_SB_DQS_DN<6>")
	)
	(segment
		(start 165.435534 -295.995598)
		(end 165.081712 -296.34942)
		(width 0.16002)
		(layer "In13.Cu")
		(net "M_H_CPU1_SB_DQS_DN<6>")
	)
	(segment
		(start 164.14877 -295.486582)
		(end 163.448746 -295.486582)
		(width 0.16002)
		(layer "In13.Cu")
		(net "M_H_CPU1_SB_DQS_DN<6>")
	)
	(segment
		(start 141.97457 -281.70632)
		(end 141.966188 -281.701494)
		(width 0.09525)
		(layer "In13.Cu")
		(net "M_H_CPU1_SB_DQS_DN<6>")
	)
	(segment
		(start 159.629602 -294.239696)
		(end 160.549336 -293.319962)
		(width 0.16002)
		(layer "In13.Cu")
		(net "M_H_CPU1_SB_DQS_DN<6>")
	)
	(segment
		(start 145.694146 -281.625548)
		(end 145.693892 -281.625294)
		(width 0.09525)
		(layer "In13.Cu")
		(net "M_H_CPU1_SB_DQS_DN<6>")
	)
	(segment
		(start 160.549336 -293.319962)
		(end 160.549336 -292.843458)
		(width 0.16002)
		(layer "In13.Cu")
		(net "M_H_CPU1_SB_DQS_DN<6>")
	)
	(segment
		(start 163.111688 -295.82364)
		(end 163.111688 -296.1894)
		(width 0.16002)
		(layer "In13.Cu")
		(net "M_H_CPU1_SB_DQS_DN<6>")
	)
	(segment
		(start 146.48561 -281.625548)
		(end 145.694146 -281.625548)
		(width 0.09525)
		(layer "In13.Cu")
		(net "M_H_CPU1_SB_DQS_DN<6>")
	)
	(segment
		(start 159.577532 -292.348158)
		(end 158.860744 -293.064946)
		(width 0.16002)
		(layer "In13.Cu")
		(net "M_H_CPU1_SB_DQS_DN<6>")
	)
	(segment
		(start 145.693892 -281.625294)
		(end 145.444718 -281.625294)
		(width 0.09525)
		(layer "In13.Cu")
		(net "M_H_CPU1_SB_DQS_DN<6>")
	)
	(segment
		(start 164.485828 -296.1894)
		(end 164.485828 -295.82364)
		(width 0.16002)
		(layer "In13.Cu")
		(net "M_H_CPU1_SB_DQS_DN<6>")
	)
	(segment
		(start 166.789608 -295.142158)
		(end 165.936168 -295.995598)
		(width 0.16002)
		(layer "In13.Cu")
		(net "M_H_CPU1_SB_DQS_DN<6>")
	)
	(segment
		(start 147.649692 -281.818334)
		(end 147.59051 -281.877516)
		(width 0.09525)
		(layer "In13.Cu")
		(net "M_H_CPU1_SB_DQS_DN<6>")
	)
	(segment
		(start 134.788656 -281.641804)
		(end 134.634732 -281.376374)
		(width 0.09525)
		(layer "In13.Cu")
		(net "M_H_CPU1_SB_DQS_DN<6>")
	)
	(segment
		(start 144.222978 -281.701494)
		(end 144.21104 -281.708352)
		(width 0.09525)
		(layer "In13.Cu")
		(net "M_H_CPU1_SB_DQS_DN<6>")
	)
	(segment
		(start 136.703308 -281.701494)
		(end 136.694926 -281.70632)
		(width 0.09525)
		(layer "In13.Cu")
		(net "M_H_CPU1_SB_DQS_DN<6>")
	)
	(segment
		(start 165.936168 -295.995598)
		(end 165.435534 -295.995598)
		(width 0.16002)
		(layer "In13.Cu")
		(net "M_H_CPU1_SB_DQS_DN<6>")
	)
	(segment
		(start 170.069002 -295.366948)
		(end 169.844212 -295.142158)
		(width 0.16002)
		(layer "In13.Cu")
		(net "M_H_CPU1_SB_DQS_DN<6>")
	)
	(arc
		(start 141.026134 -281.701494)
		(mid 140.744702 -281.625739)
		(end 140.46327 -281.701494)
		(width 0.09525)
		(layer "In13.Cu")
		(net "M_H_CPU1_SB_DQS_DN<6>")
	)
	(arc
		(start 145.444718 -281.625294)
		(mid 145.298559 -281.644665)
		(end 145.162524 -281.701494)
		(width 0.09525)
		(layer "In13.Cu")
		(net "M_H_CPU1_SB_DQS_DN<6>")
	)
	(arc
		(start 145.162524 -281.701494)
		(mid 144.980654 -281.752359)
		(end 144.797018 -281.708352)
		(width 0.09525)
		(layer "In13.Cu")
		(net "M_H_CPU1_SB_DQS_DN<6>")
	)
	(arc
		(start 137.643362 -281.701494)
		(mid 137.459587 -281.752266)
		(end 137.274554 -281.70632)
		(width 0.09525)
		(layer "In13.Cu")
		(net "M_H_CPU1_SB_DQS_DN<6>")
	)
	(arc
		(start 140.454888 -281.70632)
		(mid 140.269856 -281.752234)
		(end 140.08608 -281.701494)
		(width 0.09525)
		(layer "In13.Cu")
		(net "M_H_CPU1_SB_DQS_DN<6>")
	)
	(arc
		(start 134.909814 -281.6606)
		(mid 134.899615 -281.664437)
		(end 134.889494 -281.668474)
		(width 0.09525)
		(layer "In13.Cu")
		(net "M_H_CPU1_SB_DQS_DN<6>")
	)
	(arc
		(start 143.283178 -281.701494)
		(mid 143.09471 -281.752171)
		(end 142.906242 -281.701494)
		(width 0.09525)
		(layer "In13.Cu")
		(net "M_H_CPU1_SB_DQS_DN<6>")
	)
	(arc
		(start 138.206226 -281.701494)
		(mid 137.924794 -281.625739)
		(end 137.643362 -281.701494)
		(width 0.09525)
		(layer "In13.Cu")
		(net "M_H_CPU1_SB_DQS_DN<6>")
	)
	(arc
		(start 141.394942 -281.70632)
		(mid 141.20991 -281.752234)
		(end 141.026134 -281.701494)
		(width 0.09525)
		(layer "In13.Cu")
		(net "M_H_CPU1_SB_DQS_DN<6>")
	)
	(arc
		(start 142.343378 -281.701494)
		(mid 142.159603 -281.752266)
		(end 141.97457 -281.70632)
		(width 0.09525)
		(layer "In13.Cu")
		(net "M_H_CPU1_SB_DQS_DN<6>")
	)
	(arc
		(start 146.721576 -281.706066)
		(mid 146.610271 -281.646241)
		(end 146.48561 -281.625548)
		(width 0.09525)
		(layer "In13.Cu")
		(net "M_H_CPU1_SB_DQS_DN<6>")
	)
	(arc
		(start 136.326118 -281.701494)
		(mid 136.044686 -281.625739)
		(end 135.763254 -281.701494)
		(width 0.09525)
		(layer "In13.Cu")
		(net "M_H_CPU1_SB_DQS_DN<6>")
	)
	(arc
		(start 135.386064 -281.701494)
		(mid 135.15252 -281.627788)
		(end 134.909814 -281.6606)
		(width 0.09525)
		(layer "In13.Cu")
		(net "M_H_CPU1_SB_DQS_DN<6>")
	)
	(arc
		(start 139.523216 -281.701494)
		(mid 139.334748 -281.752171)
		(end 139.14628 -281.701494)
		(width 0.09525)
		(layer "In13.Cu")
		(net "M_H_CPU1_SB_DQS_DN<6>")
	)
	(arc
		(start 144.21104 -281.708352)
		(mid 144.027659 -281.752183)
		(end 143.846042 -281.701494)
		(width 0.09525)
		(layer "In13.Cu")
		(net "M_H_CPU1_SB_DQS_DN<6>")
	)
	(arc
		(start 143.846042 -281.701494)
		(mid 143.56461 -281.625739)
		(end 143.283178 -281.701494)
		(width 0.09525)
		(layer "In13.Cu")
		(net "M_H_CPU1_SB_DQS_DN<6>")
	)
	(arc
		(start 135.754872 -281.70632)
		(mid 135.56984 -281.752234)
		(end 135.386064 -281.701494)
		(width 0.09525)
		(layer "In13.Cu")
		(net "M_H_CPU1_SB_DQS_DN<6>")
	)
	(arc
		(start 139.14628 -281.701494)
		(mid 138.864848 -281.625739)
		(end 138.583416 -281.701494)
		(width 0.09525)
		(layer "In13.Cu")
		(net "M_H_CPU1_SB_DQS_DN<6>")
	)
	(arc
		(start 141.966188 -281.701494)
		(mid 141.684756 -281.625739)
		(end 141.403324 -281.701494)
		(width 0.09525)
		(layer "In13.Cu")
		(net "M_H_CPU1_SB_DQS_DN<6>")
	)
	(arc
		(start 140.08608 -281.701494)
		(mid 139.804648 -281.625739)
		(end 139.523216 -281.701494)
		(width 0.09525)
		(layer "In13.Cu")
		(net "M_H_CPU1_SB_DQS_DN<6>")
	)
	(arc
		(start 137.266172 -281.701494)
		(mid 136.98474 -281.625739)
		(end 136.703308 -281.701494)
		(width 0.09525)
		(layer "In13.Cu")
		(net "M_H_CPU1_SB_DQS_DN<6>")
	)
	(arc
		(start 142.906242 -281.701494)
		(mid 142.62481 -281.625739)
		(end 142.343378 -281.701494)
		(width 0.09525)
		(layer "In13.Cu")
		(net "M_H_CPU1_SB_DQS_DN<6>")
	)
	(arc
		(start 136.694926 -281.70632)
		(mid 136.509894 -281.752234)
		(end 136.326118 -281.701494)
		(width 0.09525)
		(layer "In13.Cu")
		(net "M_H_CPU1_SB_DQS_DN<6>")
	)
	(arc
		(start 138.583416 -281.701494)
		(mid 138.399641 -281.752266)
		(end 138.214608 -281.70632)
		(width 0.09525)
		(layer "In13.Cu")
		(net "M_H_CPU1_SB_DQS_DN<6>")
	)
	(arc
		(start 144.78508 -281.701494)
		(mid 144.514392 -281.625842)
		(end 144.241012 -281.69108)
		(width 0.09525)
		(layer "In13.Cu")
		(net "M_H_CPU1_SB_DQS_DN<6>")
	)
	(segment
		(start 134.16788 -276.2504)
		(end 134.634732 -276.516338)
		(width 0.12954)
		(layer "F.Cu")
		(net "M_H_CPU1_SB_DQS_DN<5>")
	)
	(segment
		(start 158.319724 -281.589734)
		(end 158.453328 -281.45613)
		(width 0.16002)
		(layer "In13.Cu")
		(net "M_H_CPU1_SB_DQS_DN<5>")
	)
	(segment
		(start 165.936168 -286.645604)
		(end 164.994082 -286.645604)
		(width 0.16002)
		(layer "In13.Cu")
		(net "M_H_CPU1_SB_DQS_DN<5>")
	)
	(segment
		(start 157.480762 -280.483564)
		(end 157.347158 -280.617168)
		(width 0.16002)
		(layer "In13.Cu")
		(net "M_H_CPU1_SB_DQS_DN<5>")
	)
	(segment
		(start 158.99765 -282.000452)
		(end 158.864046 -282.134056)
		(width 0.16002)
		(layer "In13.Cu")
		(net "M_H_CPU1_SB_DQS_DN<5>")
	)
	(segment
		(start 161.487104 -284.489906)
		(end 161.487104 -284.013402)
		(width 0.16002)
		(layer "In13.Cu")
		(net "M_H_CPU1_SB_DQS_DN<5>")
	)
	(segment
		(start 135.763254 -276.841458)
		(end 135.754872 -276.846284)
		(width 0.09525)
		(layer "In13.Cu")
		(net "M_H_CPU1_SB_DQS_DN<5>")
	)
	(segment
		(start 147.83054 -275.7932)
		(end 147.771358 -275.852382)
		(width 0.09525)
		(layer "In13.Cu")
		(net "M_H_CPU1_SB_DQS_DN<5>")
	)
	(segment
		(start 134.788656 -276.781768)
		(end 134.634732 -276.516338)
		(width 0.09525)
		(layer "In13.Cu")
		(net "M_H_CPU1_SB_DQS_DN<5>")
	)
	(segment
		(start 161.487104 -284.013402)
		(end 160.991042 -283.51734)
		(width 0.16002)
		(layer "In13.Cu")
		(net "M_H_CPU1_SB_DQS_DN<5>")
	)
	(segment
		(start 171.709842 -285.996888)
		(end 170.254168 -285.996888)
		(width 0.16002)
		(layer "In13.Cu")
		(net "M_H_CPU1_SB_DQS_DN<5>")
	)
	(segment
		(start 159.970216 -282.496514)
		(end 159.474154 -282.000452)
		(width 0.16002)
		(layer "In13.Cu")
		(net "M_H_CPU1_SB_DQS_DN<5>")
	)
	(segment
		(start 171.97197 -285.735268)
		(end 171.709842 -285.996888)
		(width 0.16002)
		(layer "In13.Cu")
		(net "M_H_CPU1_SB_DQS_DN<5>")
	)
	(segment
		(start 144.241012 -276.831044)
		(end 144.222978 -276.841458)
		(width 0.09525)
		(layer "In13.Cu")
		(net "M_H_CPU1_SB_DQS_DN<5>")
	)
	(segment
		(start 134.889494 -276.808438)
		(end 134.788656 -276.781768)
		(width 0.09525)
		(layer "In13.Cu")
		(net "M_H_CPU1_SB_DQS_DN<5>")
	)
	(segment
		(start 159.836612 -283.106622)
		(end 159.970216 -282.973018)
		(width 0.16002)
		(layer "In13.Cu")
		(net "M_H_CPU1_SB_DQS_DN<5>")
	)
	(segment
		(start 163.882324 -285.533846)
		(end 163.023296 -285.533846)
		(width 0.16002)
		(layer "In13.Cu")
		(net "M_H_CPU1_SB_DQS_DN<5>")
	)
	(segment
		(start 152.29713 -275.7932)
		(end 147.854162 -275.7932)
		(width 0.16002)
		(layer "In13.Cu")
		(net "M_H_CPU1_SB_DQS_DN<5>")
	)
	(segment
		(start 163.023296 -285.533846)
		(end 162.534092 -285.044642)
		(width 0.16002)
		(layer "In13.Cu")
		(net "M_H_CPU1_SB_DQS_DN<5>")
	)
	(segment
		(start 155.60421 -279.10028)
		(end 152.29713 -275.7932)
		(width 0.16002)
		(layer "In13.Cu")
		(net "M_H_CPU1_SB_DQS_DN<5>")
	)
	(segment
		(start 145.701766 -276.548596)
		(end 145.287746 -276.78761)
		(width 0.09525)
		(layer "In13.Cu")
		(net "M_H_CPU1_SB_DQS_DN<5>")
	)
	(segment
		(start 159.474154 -282.000452)
		(end 158.99765 -282.000452)
		(width 0.16002)
		(layer "In13.Cu")
		(net "M_H_CPU1_SB_DQS_DN<5>")
	)
	(segment
		(start 138.214608 -276.846284)
		(end 138.206226 -276.841458)
		(width 0.09525)
		(layer "In13.Cu")
		(net "M_H_CPU1_SB_DQS_DN<5>")
	)
	(segment
		(start 164.994082 -286.645604)
		(end 163.882324 -285.533846)
		(width 0.16002)
		(layer "In13.Cu")
		(net "M_H_CPU1_SB_DQS_DN<5>")
	)
	(segment
		(start 156.802836 -280.298906)
		(end 156.802836 -280.072846)
		(width 0.16002)
		(layer "In13.Cu")
		(net "M_H_CPU1_SB_DQS_DN<5>")
	)
	(segment
		(start 155.83027 -279.10028)
		(end 155.60421 -279.10028)
		(width 0.16002)
		(layer "In13.Cu")
		(net "M_H_CPU1_SB_DQS_DN<5>")
	)
	(segment
		(start 147.54479 -275.852382)
		(end 147.370292 -275.677884)
		(width 0.09525)
		(layer "In13.Cu")
		(net "M_H_CPU1_SB_DQS_DN<5>")
	)
	(segment
		(start 156.93644 -279.462738)
		(end 156.440378 -278.966676)
		(width 0.16002)
		(layer "In13.Cu")
		(net "M_H_CPU1_SB_DQS_DN<5>")
	)
	(segment
		(start 156.440378 -278.966676)
		(end 155.963874 -278.966676)
		(width 0.16002)
		(layer "In13.Cu")
		(net "M_H_CPU1_SB_DQS_DN<5>")
	)
	(segment
		(start 136.703308 -276.841458)
		(end 136.694926 -276.846284)
		(width 0.09525)
		(layer "In13.Cu")
		(net "M_H_CPU1_SB_DQS_DN<5>")
	)
	(segment
		(start 140.46327 -276.841458)
		(end 140.454888 -276.846284)
		(width 0.09525)
		(layer "In13.Cu")
		(net "M_H_CPU1_SB_DQS_DN<5>")
	)
	(segment
		(start 161.3535 -284.62351)
		(end 161.487104 -284.489906)
		(width 0.16002)
		(layer "In13.Cu")
		(net "M_H_CPU1_SB_DQS_DN<5>")
	)
	(segment
		(start 147.771358 -275.852382)
		(end 147.54479 -275.852382)
		(width 0.09525)
		(layer "In13.Cu")
		(net "M_H_CPU1_SB_DQS_DN<5>")
	)
	(segment
		(start 159.836612 -283.332682)
		(end 159.836612 -283.106622)
		(width 0.16002)
		(layer "In13.Cu")
		(net "M_H_CPU1_SB_DQS_DN<5>")
	)
	(segment
		(start 145.715736 -276.541738)
		(end 145.701766 -276.548596)
		(width 0.09525)
		(layer "In13.Cu")
		(net "M_H_CPU1_SB_DQS_DN<5>")
	)
	(segment
		(start 158.637986 -282.134056)
		(end 158.319724 -281.815794)
		(width 0.16002)
		(layer "In13.Cu")
		(net "M_H_CPU1_SB_DQS_DN<5>")
	)
	(segment
		(start 158.864046 -282.134056)
		(end 158.637986 -282.134056)
		(width 0.16002)
		(layer "In13.Cu")
		(net "M_H_CPU1_SB_DQS_DN<5>")
	)
	(segment
		(start 159.970216 -282.973018)
		(end 159.970216 -282.496514)
		(width 0.16002)
		(layer "In13.Cu")
		(net "M_H_CPU1_SB_DQS_DN<5>")
	)
	(segment
		(start 147.370292 -275.677884)
		(end 146.704558 -275.677884)
		(width 0.09525)
		(layer "In13.Cu")
		(net "M_H_CPU1_SB_DQS_DN<5>")
	)
	(segment
		(start 147.854162 -275.7932)
		(end 147.83054 -275.7932)
		(width 0.09525)
		(layer "In13.Cu")
		(net "M_H_CPU1_SB_DQS_DN<5>")
	)
	(segment
		(start 137.274554 -276.846284)
		(end 137.266172 -276.841458)
		(width 0.09525)
		(layer "In13.Cu")
		(net "M_H_CPU1_SB_DQS_DN<5>")
	)
	(segment
		(start 156.93644 -279.939242)
		(end 156.93644 -279.462738)
		(width 0.16002)
		(layer "In13.Cu")
		(net "M_H_CPU1_SB_DQS_DN<5>")
	)
	(segment
		(start 161.3535 -284.84957)
		(end 161.3535 -284.62351)
		(width 0.16002)
		(layer "In13.Cu")
		(net "M_H_CPU1_SB_DQS_DN<5>")
	)
	(segment
		(start 158.453328 -280.979626)
		(end 157.957266 -280.483564)
		(width 0.16002)
		(layer "In13.Cu")
		(net "M_H_CPU1_SB_DQS_DN<5>")
	)
	(segment
		(start 146.704558 -275.677884)
		(end 146.164046 -276.218396)
		(width 0.09525)
		(layer "In13.Cu")
		(net "M_H_CPU1_SB_DQS_DN<5>")
	)
	(segment
		(start 170.254168 -285.996888)
		(end 170.049444 -285.792164)
		(width 0.16002)
		(layer "In13.Cu")
		(net "M_H_CPU1_SB_DQS_DN<5>")
	)
	(segment
		(start 141.403324 -276.841458)
		(end 141.394942 -276.846284)
		(width 0.09525)
		(layer "In13.Cu")
		(net "M_H_CPU1_SB_DQS_DN<5>")
	)
	(segment
		(start 160.154874 -283.650944)
		(end 159.836612 -283.332682)
		(width 0.16002)
		(layer "In13.Cu")
		(net "M_H_CPU1_SB_DQS_DN<5>")
	)
	(segment
		(start 157.121098 -280.617168)
		(end 156.802836 -280.298906)
		(width 0.16002)
		(layer "In13.Cu")
		(net "M_H_CPU1_SB_DQS_DN<5>")
	)
	(segment
		(start 160.991042 -283.51734)
		(end 160.514538 -283.51734)
		(width 0.16002)
		(layer "In13.Cu")
		(net "M_H_CPU1_SB_DQS_DN<5>")
	)
	(segment
		(start 170.049444 -285.792164)
		(end 166.789608 -285.792164)
		(width 0.16002)
		(layer "In13.Cu")
		(net "M_H_CPU1_SB_DQS_DN<5>")
	)
	(segment
		(start 156.802836 -280.072846)
		(end 156.93644 -279.939242)
		(width 0.16002)
		(layer "In13.Cu")
		(net "M_H_CPU1_SB_DQS_DN<5>")
	)
	(segment
		(start 158.319724 -281.815794)
		(end 158.319724 -281.589734)
		(width 0.16002)
		(layer "In13.Cu")
		(net "M_H_CPU1_SB_DQS_DN<5>")
	)
	(segment
		(start 160.380934 -283.650944)
		(end 160.154874 -283.650944)
		(width 0.16002)
		(layer "In13.Cu")
		(net "M_H_CPU1_SB_DQS_DN<5>")
	)
	(segment
		(start 144.222978 -276.841458)
		(end 144.21104 -276.848316)
		(width 0.09525)
		(layer "In13.Cu")
		(net "M_H_CPU1_SB_DQS_DN<5>")
	)
	(segment
		(start 157.347158 -280.617168)
		(end 157.121098 -280.617168)
		(width 0.16002)
		(layer "In13.Cu")
		(net "M_H_CPU1_SB_DQS_DN<5>")
	)
	(segment
		(start 157.957266 -280.483564)
		(end 157.480762 -280.483564)
		(width 0.16002)
		(layer "In13.Cu")
		(net "M_H_CPU1_SB_DQS_DN<5>")
	)
	(segment
		(start 161.548572 -285.044642)
		(end 161.3535 -284.84957)
		(width 0.16002)
		(layer "In13.Cu")
		(net "M_H_CPU1_SB_DQS_DN<5>")
	)
	(segment
		(start 160.514538 -283.51734)
		(end 160.380934 -283.650944)
		(width 0.16002)
		(layer "In13.Cu")
		(net "M_H_CPU1_SB_DQS_DN<5>")
	)
	(segment
		(start 144.797018 -276.848316)
		(end 144.78508 -276.841458)
		(width 0.09525)
		(layer "In13.Cu")
		(net "M_H_CPU1_SB_DQS_DN<5>")
	)
	(segment
		(start 166.789608 -285.792164)
		(end 165.936168 -286.645604)
		(width 0.16002)
		(layer "In13.Cu")
		(net "M_H_CPU1_SB_DQS_DN<5>")
	)
	(segment
		(start 162.534092 -285.044642)
		(end 161.548572 -285.044642)
		(width 0.16002)
		(layer "In13.Cu")
		(net "M_H_CPU1_SB_DQS_DN<5>")
	)
	(segment
		(start 155.963874 -278.966676)
		(end 155.83027 -279.10028)
		(width 0.16002)
		(layer "In13.Cu")
		(net "M_H_CPU1_SB_DQS_DN<5>")
	)
	(segment
		(start 158.453328 -281.45613)
		(end 158.453328 -280.979626)
		(width 0.16002)
		(layer "In13.Cu")
		(net "M_H_CPU1_SB_DQS_DN<5>")
	)
	(segment
		(start 141.97457 -276.846284)
		(end 141.966188 -276.841458)
		(width 0.09525)
		(layer "In13.Cu")
		(net "M_H_CPU1_SB_DQS_DN<5>")
	)
	(arc
		(start 136.694926 -276.846284)
		(mid 136.509894 -276.892198)
		(end 136.326118 -276.841458)
		(width 0.09525)
		(layer "In13.Cu")
		(net "M_H_CPU1_SB_DQS_DN<5>")
	)
	(arc
		(start 145.287746 -276.78761)
		(mid 145.223499 -276.810728)
		(end 145.162524 -276.841458)
		(width 0.09525)
		(layer "In13.Cu")
		(net "M_H_CPU1_SB_DQS_DN<5>")
	)
	(arc
		(start 141.966188 -276.841458)
		(mid 141.684756 -276.765703)
		(end 141.403324 -276.841458)
		(width 0.09525)
		(layer "In13.Cu")
		(net "M_H_CPU1_SB_DQS_DN<5>")
	)
	(arc
		(start 140.454888 -276.846284)
		(mid 140.269856 -276.892198)
		(end 140.08608 -276.841458)
		(width 0.09525)
		(layer "In13.Cu")
		(net "M_H_CPU1_SB_DQS_DN<5>")
	)
	(arc
		(start 140.08608 -276.841458)
		(mid 139.804648 -276.765703)
		(end 139.523216 -276.841458)
		(width 0.09525)
		(layer "In13.Cu")
		(net "M_H_CPU1_SB_DQS_DN<5>")
	)
	(arc
		(start 141.026134 -276.841458)
		(mid 140.744702 -276.765703)
		(end 140.46327 -276.841458)
		(width 0.09525)
		(layer "In13.Cu")
		(net "M_H_CPU1_SB_DQS_DN<5>")
	)
	(arc
		(start 135.386064 -276.841458)
		(mid 135.15252 -276.767752)
		(end 134.909814 -276.800564)
		(width 0.09525)
		(layer "In13.Cu")
		(net "M_H_CPU1_SB_DQS_DN<5>")
	)
	(arc
		(start 141.394942 -276.846284)
		(mid 141.20991 -276.892198)
		(end 141.026134 -276.841458)
		(width 0.09525)
		(layer "In13.Cu")
		(net "M_H_CPU1_SB_DQS_DN<5>")
	)
	(arc
		(start 145.162524 -276.841458)
		(mid 144.980654 -276.892323)
		(end 144.797018 -276.848316)
		(width 0.09525)
		(layer "In13.Cu")
		(net "M_H_CPU1_SB_DQS_DN<5>")
	)
	(arc
		(start 143.846042 -276.841458)
		(mid 143.56461 -276.765703)
		(end 143.283178 -276.841458)
		(width 0.09525)
		(layer "In13.Cu")
		(net "M_H_CPU1_SB_DQS_DN<5>")
	)
	(arc
		(start 137.266172 -276.841458)
		(mid 136.98474 -276.765703)
		(end 136.703308 -276.841458)
		(width 0.09525)
		(layer "In13.Cu")
		(net "M_H_CPU1_SB_DQS_DN<5>")
	)
	(arc
		(start 139.523216 -276.841458)
		(mid 139.334748 -276.892135)
		(end 139.14628 -276.841458)
		(width 0.09525)
		(layer "In13.Cu")
		(net "M_H_CPU1_SB_DQS_DN<5>")
	)
	(arc
		(start 134.909814 -276.800564)
		(mid 134.899615 -276.804401)
		(end 134.889494 -276.808438)
		(width 0.09525)
		(layer "In13.Cu")
		(net "M_H_CPU1_SB_DQS_DN<5>")
	)
	(arc
		(start 136.326118 -276.841458)
		(mid 136.044686 -276.765703)
		(end 135.763254 -276.841458)
		(width 0.09525)
		(layer "In13.Cu")
		(net "M_H_CPU1_SB_DQS_DN<5>")
	)
	(arc
		(start 142.343378 -276.841458)
		(mid 142.159603 -276.89223)
		(end 141.97457 -276.846284)
		(width 0.09525)
		(layer "In13.Cu")
		(net "M_H_CPU1_SB_DQS_DN<5>")
	)
	(arc
		(start 144.78508 -276.841458)
		(mid 144.514392 -276.765806)
		(end 144.241012 -276.831044)
		(width 0.09525)
		(layer "In13.Cu")
		(net "M_H_CPU1_SB_DQS_DN<5>")
	)
	(arc
		(start 139.14628 -276.841458)
		(mid 138.864848 -276.765703)
		(end 138.583416 -276.841458)
		(width 0.09525)
		(layer "In13.Cu")
		(net "M_H_CPU1_SB_DQS_DN<5>")
	)
	(arc
		(start 138.583416 -276.841458)
		(mid 138.399641 -276.89223)
		(end 138.214608 -276.846284)
		(width 0.09525)
		(layer "In13.Cu")
		(net "M_H_CPU1_SB_DQS_DN<5>")
	)
	(arc
		(start 137.643362 -276.841458)
		(mid 137.459587 -276.89223)
		(end 137.274554 -276.846284)
		(width 0.09525)
		(layer "In13.Cu")
		(net "M_H_CPU1_SB_DQS_DN<5>")
	)
	(arc
		(start 143.283178 -276.841458)
		(mid 143.09471 -276.892135)
		(end 142.906242 -276.841458)
		(width 0.09525)
		(layer "In13.Cu")
		(net "M_H_CPU1_SB_DQS_DN<5>")
	)
	(arc
		(start 146.164046 -276.218396)
		(mid 145.952923 -276.398136)
		(end 145.715736 -276.541738)
		(width 0.09525)
		(layer "In13.Cu")
		(net "M_H_CPU1_SB_DQS_DN<5>")
	)
	(arc
		(start 135.754872 -276.846284)
		(mid 135.56984 -276.892198)
		(end 135.386064 -276.841458)
		(width 0.09525)
		(layer "In13.Cu")
		(net "M_H_CPU1_SB_DQS_DN<5>")
	)
	(arc
		(start 144.21104 -276.848316)
		(mid 144.027659 -276.892147)
		(end 143.846042 -276.841458)
		(width 0.09525)
		(layer "In13.Cu")
		(net "M_H_CPU1_SB_DQS_DN<5>")
	)
	(arc
		(start 138.206226 -276.841458)
		(mid 137.924794 -276.765703)
		(end 137.643362 -276.841458)
		(width 0.09525)
		(layer "In13.Cu")
		(net "M_H_CPU1_SB_DQS_DN<5>")
	)
	(arc
		(start 142.906242 -276.841458)
		(mid 142.62481 -276.765703)
		(end 142.343378 -276.841458)
		(width 0.09525)
		(layer "In13.Cu")
		(net "M_H_CPU1_SB_DQS_DN<5>")
	)
	(segment
		(start 134.16788 -271.390364)
		(end 134.634732 -271.656302)
		(width 0.12954)
		(layer "F.Cu")
		(net "M_H_CPU1_SB_DQS_DN<4>")
	)
	(segment
		(start 162.366706 -275.362416)
		(end 162.617404 -275.111718)
		(width 0.16002)
		(layer "In13.Cu")
		(net "M_H_CPU1_SB_DQS_DN<4>")
	)
	(segment
		(start 166.888922 -276.342856)
		(end 165.936168 -277.29561)
		(width 0.16002)
		(layer "In13.Cu")
		(net "M_H_CPU1_SB_DQS_DN<4>")
	)
	(segment
		(start 160.849818 -274.071588)
		(end 160.849818 -273.845528)
		(width 0.16002)
		(layer "In13.Cu")
		(net "M_H_CPU1_SB_DQS_DN<4>")
	)
	(segment
		(start 162.617404 -275.111718)
		(end 162.617404 -274.635214)
		(width 0.16002)
		(layer "In13.Cu")
		(net "M_H_CPU1_SB_DQS_DN<4>")
	)
	(segment
		(start 141.403324 -271.981422)
		(end 141.394942 -271.986248)
		(width 0.09525)
		(layer "In13.Cu")
		(net "M_H_CPU1_SB_DQS_DN<4>")
	)
	(segment
		(start 146.942556 -270.41348)
		(end 146.408648 -270.41348)
		(width 0.09525)
		(layer "In13.Cu")
		(net "M_H_CPU1_SB_DQS_DN<4>")
	)
	(segment
		(start 138.214608 -271.986248)
		(end 138.206226 -271.981422)
		(width 0.09525)
		(layer "In13.Cu")
		(net "M_H_CPU1_SB_DQS_DN<4>")
	)
	(segment
		(start 146.408648 -270.41348)
		(end 144.916652 -271.905476)
		(width 0.09525)
		(layer "In13.Cu")
		(net "M_H_CPU1_SB_DQS_DN<4>")
	)
	(segment
		(start 169.097452 -276.672548)
		(end 168.642284 -277.127716)
		(width 0.16002)
		(layer "In13.Cu")
		(net "M_H_CPU1_SB_DQS_DN<4>")
	)
	(segment
		(start 162.91179 -275.9075)
		(end 162.68573 -275.9075)
		(width 0.16002)
		(layer "In13.Cu")
		(net "M_H_CPU1_SB_DQS_DN<4>")
	)
	(segment
		(start 161.6456 -274.139914)
		(end 161.394902 -274.390612)
		(width 0.16002)
		(layer "In13.Cu")
		(net "M_H_CPU1_SB_DQS_DN<4>")
	)
	(segment
		(start 137.274554 -271.986248)
		(end 137.266172 -271.981422)
		(width 0.09525)
		(layer "In13.Cu")
		(net "M_H_CPU1_SB_DQS_DN<4>")
	)
	(segment
		(start 171.97197 -276.385274)
		(end 171.684696 -276.672548)
		(width 0.16002)
		(layer "In13.Cu")
		(net "M_H_CPU1_SB_DQS_DN<4>")
	)
	(segment
		(start 162.122104 -274.139914)
		(end 161.6456 -274.139914)
		(width 0.16002)
		(layer "In13.Cu")
		(net "M_H_CPU1_SB_DQS_DN<4>")
	)
	(segment
		(start 134.788656 -271.921732)
		(end 134.634732 -271.656302)
		(width 0.09525)
		(layer "In13.Cu")
		(net "M_H_CPU1_SB_DQS_DN<4>")
	)
	(segment
		(start 140.46327 -271.981422)
		(end 140.454888 -271.986248)
		(width 0.09525)
		(layer "In13.Cu")
		(net "M_H_CPU1_SB_DQS_DN<4>")
	)
	(segment
		(start 156.922724 -270.144494)
		(end 147.810474 -270.144494)
		(width 0.16002)
		(layer "In13.Cu")
		(net "M_H_CPU1_SB_DQS_DN<4>")
	)
	(segment
		(start 170.786044 -277.127716)
		(end 170.294554 -277.127716)
		(width 0.16002)
		(layer "In13.Cu")
		(net "M_H_CPU1_SB_DQS_DN<4>")
	)
	(segment
		(start 168.150794 -277.127716)
		(end 167.365934 -276.342856)
		(width 0.16002)
		(layer "In13.Cu")
		(net "M_H_CPU1_SB_DQS_DN<4>")
	)
	(segment
		(start 163.162488 -275.656802)
		(end 162.91179 -275.9075)
		(width 0.16002)
		(layer "In13.Cu")
		(net "M_H_CPU1_SB_DQS_DN<4>")
	)
	(segment
		(start 170.294554 -277.127716)
		(end 169.839386 -276.672548)
		(width 0.16002)
		(layer "In13.Cu")
		(net "M_H_CPU1_SB_DQS_DN<4>")
	)
	(segment
		(start 147.786852 -270.144494)
		(end 147.72767 -270.203676)
		(width 0.09525)
		(layer "In13.Cu")
		(net "M_H_CPU1_SB_DQS_DN<4>")
	)
	(segment
		(start 162.617404 -274.635214)
		(end 162.122104 -274.139914)
		(width 0.16002)
		(layer "In13.Cu")
		(net "M_H_CPU1_SB_DQS_DN<4>")
	)
	(segment
		(start 171.684696 -276.672548)
		(end 171.241212 -276.672548)
		(width 0.16002)
		(layer "In13.Cu")
		(net "M_H_CPU1_SB_DQS_DN<4>")
	)
	(segment
		(start 169.839386 -276.672548)
		(end 169.097452 -276.672548)
		(width 0.16002)
		(layer "In13.Cu")
		(net "M_H_CPU1_SB_DQS_DN<4>")
	)
	(segment
		(start 159.496252 -272.718022)
		(end 156.922724 -270.144494)
		(width 0.16002)
		(layer "In13.Cu")
		(net "M_H_CPU1_SB_DQS_DN<4>")
	)
	(segment
		(start 147.15236 -270.203676)
		(end 146.942556 -270.41348)
		(width 0.09525)
		(layer "In13.Cu")
		(net "M_H_CPU1_SB_DQS_DN<4>")
	)
	(segment
		(start 134.889494 -271.948402)
		(end 134.788656 -271.921732)
		(width 0.09525)
		(layer "In13.Cu")
		(net "M_H_CPU1_SB_DQS_DN<4>")
	)
	(segment
		(start 161.394902 -274.390612)
		(end 161.168842 -274.390612)
		(width 0.16002)
		(layer "In13.Cu")
		(net "M_H_CPU1_SB_DQS_DN<4>")
	)
	(segment
		(start 168.642284 -277.127716)
		(end 168.150794 -277.127716)
		(width 0.16002)
		(layer "In13.Cu")
		(net "M_H_CPU1_SB_DQS_DN<4>")
	)
	(segment
		(start 143.854424 -271.986248)
		(end 143.846042 -271.981422)
		(width 0.09525)
		(layer "In13.Cu")
		(net "M_H_CPU1_SB_DQS_DN<4>")
	)
	(segment
		(start 163.638992 -275.656802)
		(end 163.162488 -275.656802)
		(width 0.16002)
		(layer "In13.Cu")
		(net "M_H_CPU1_SB_DQS_DN<4>")
	)
	(segment
		(start 160.849818 -273.845528)
		(end 161.100516 -273.59483)
		(width 0.16002)
		(layer "In13.Cu")
		(net "M_H_CPU1_SB_DQS_DN<4>")
	)
	(segment
		(start 161.100516 -273.118326)
		(end 160.700212 -272.718022)
		(width 0.16002)
		(layer "In13.Cu")
		(net "M_H_CPU1_SB_DQS_DN<4>")
	)
	(segment
		(start 147.810474 -270.144494)
		(end 147.786852 -270.144494)
		(width 0.09525)
		(layer "In13.Cu")
		(net "M_H_CPU1_SB_DQS_DN<4>")
	)
	(segment
		(start 171.241212 -276.672548)
		(end 170.786044 -277.127716)
		(width 0.16002)
		(layer "In13.Cu")
		(net "M_H_CPU1_SB_DQS_DN<4>")
	)
	(segment
		(start 147.72767 -270.203676)
		(end 147.15236 -270.203676)
		(width 0.09525)
		(layer "In13.Cu")
		(net "M_H_CPU1_SB_DQS_DN<4>")
	)
	(segment
		(start 136.703308 -271.981422)
		(end 136.694926 -271.986248)
		(width 0.09525)
		(layer "In13.Cu")
		(net "M_H_CPU1_SB_DQS_DN<4>")
	)
	(segment
		(start 144.916652 -271.905476)
		(end 144.505426 -271.905476)
		(width 0.09525)
		(layer "In13.Cu")
		(net "M_H_CPU1_SB_DQS_DN<4>")
	)
	(segment
		(start 162.366706 -275.588476)
		(end 162.366706 -275.362416)
		(width 0.16002)
		(layer "In13.Cu")
		(net "M_H_CPU1_SB_DQS_DN<4>")
	)
	(segment
		(start 141.97457 -271.986248)
		(end 141.966188 -271.981422)
		(width 0.09525)
		(layer "In13.Cu")
		(net "M_H_CPU1_SB_DQS_DN<4>")
	)
	(segment
		(start 161.168842 -274.390612)
		(end 160.849818 -274.071588)
		(width 0.16002)
		(layer "In13.Cu")
		(net "M_H_CPU1_SB_DQS_DN<4>")
	)
	(segment
		(start 160.700212 -272.718022)
		(end 159.496252 -272.718022)
		(width 0.16002)
		(layer "In13.Cu")
		(net "M_H_CPU1_SB_DQS_DN<4>")
	)
	(segment
		(start 161.100516 -273.59483)
		(end 161.100516 -273.118326)
		(width 0.16002)
		(layer "In13.Cu")
		(net "M_H_CPU1_SB_DQS_DN<4>")
	)
	(segment
		(start 167.365934 -276.342856)
		(end 166.888922 -276.342856)
		(width 0.16002)
		(layer "In13.Cu")
		(net "M_H_CPU1_SB_DQS_DN<4>")
	)
	(segment
		(start 165.2778 -277.29561)
		(end 163.638992 -275.656802)
		(width 0.16002)
		(layer "In13.Cu")
		(net "M_H_CPU1_SB_DQS_DN<4>")
	)
	(segment
		(start 165.936168 -277.29561)
		(end 165.2778 -277.29561)
		(width 0.16002)
		(layer "In13.Cu")
		(net "M_H_CPU1_SB_DQS_DN<4>")
	)
	(segment
		(start 135.763254 -271.981422)
		(end 135.754872 -271.986248)
		(width 0.09525)
		(layer "In13.Cu")
		(net "M_H_CPU1_SB_DQS_DN<4>")
	)
	(segment
		(start 162.68573 -275.9075)
		(end 162.366706 -275.588476)
		(width 0.16002)
		(layer "In13.Cu")
		(net "M_H_CPU1_SB_DQS_DN<4>")
	)
	(arc
		(start 138.206226 -271.981422)
		(mid 137.924794 -271.905667)
		(end 137.643362 -271.981422)
		(width 0.09525)
		(layer "In13.Cu")
		(net "M_H_CPU1_SB_DQS_DN<4>")
	)
	(arc
		(start 141.026134 -271.981422)
		(mid 140.744702 -271.905667)
		(end 140.46327 -271.981422)
		(width 0.09525)
		(layer "In13.Cu")
		(net "M_H_CPU1_SB_DQS_DN<4>")
	)
	(arc
		(start 137.266172 -271.981422)
		(mid 136.98474 -271.905667)
		(end 136.703308 -271.981422)
		(width 0.09525)
		(layer "In13.Cu")
		(net "M_H_CPU1_SB_DQS_DN<4>")
	)
	(arc
		(start 142.906242 -271.981422)
		(mid 142.62481 -271.905667)
		(end 142.343378 -271.981422)
		(width 0.09525)
		(layer "In13.Cu")
		(net "M_H_CPU1_SB_DQS_DN<4>")
	)
	(arc
		(start 135.386064 -271.981422)
		(mid 135.15252 -271.907716)
		(end 134.909814 -271.940528)
		(width 0.09525)
		(layer "In13.Cu")
		(net "M_H_CPU1_SB_DQS_DN<4>")
	)
	(arc
		(start 141.966188 -271.981422)
		(mid 141.684756 -271.905667)
		(end 141.403324 -271.981422)
		(width 0.09525)
		(layer "In13.Cu")
		(net "M_H_CPU1_SB_DQS_DN<4>")
	)
	(arc
		(start 144.505426 -271.905476)
		(mid 144.359566 -271.924835)
		(end 144.22374 -271.981422)
		(width 0.09525)
		(layer "In13.Cu")
		(net "M_H_CPU1_SB_DQS_DN<4>")
	)
	(arc
		(start 142.343378 -271.981422)
		(mid 142.159603 -272.032194)
		(end 141.97457 -271.986248)
		(width 0.09525)
		(layer "In13.Cu")
		(net "M_H_CPU1_SB_DQS_DN<4>")
	)
	(arc
		(start 136.694926 -271.986248)
		(mid 136.509894 -272.032162)
		(end 136.326118 -271.981422)
		(width 0.09525)
		(layer "In13.Cu")
		(net "M_H_CPU1_SB_DQS_DN<4>")
	)
	(arc
		(start 140.08608 -271.981422)
		(mid 139.804648 -271.905667)
		(end 139.523216 -271.981422)
		(width 0.09525)
		(layer "In13.Cu")
		(net "M_H_CPU1_SB_DQS_DN<4>")
	)
	(arc
		(start 143.283178 -271.981422)
		(mid 143.09471 -272.032099)
		(end 142.906242 -271.981422)
		(width 0.09525)
		(layer "In13.Cu")
		(net "M_H_CPU1_SB_DQS_DN<4>")
	)
	(arc
		(start 136.326118 -271.981422)
		(mid 136.044686 -271.905667)
		(end 135.763254 -271.981422)
		(width 0.09525)
		(layer "In13.Cu")
		(net "M_H_CPU1_SB_DQS_DN<4>")
	)
	(arc
		(start 139.523216 -271.981422)
		(mid 139.334748 -272.032099)
		(end 139.14628 -271.981422)
		(width 0.09525)
		(layer "In13.Cu")
		(net "M_H_CPU1_SB_DQS_DN<4>")
	)
	(arc
		(start 135.754872 -271.986248)
		(mid 135.56984 -272.032162)
		(end 135.386064 -271.981422)
		(width 0.09525)
		(layer "In13.Cu")
		(net "M_H_CPU1_SB_DQS_DN<4>")
	)
	(arc
		(start 139.14628 -271.981422)
		(mid 138.864848 -271.905667)
		(end 138.583416 -271.981422)
		(width 0.09525)
		(layer "In13.Cu")
		(net "M_H_CPU1_SB_DQS_DN<4>")
	)
	(arc
		(start 140.454888 -271.986248)
		(mid 140.269856 -272.032162)
		(end 140.08608 -271.981422)
		(width 0.09525)
		(layer "In13.Cu")
		(net "M_H_CPU1_SB_DQS_DN<4>")
	)
	(arc
		(start 134.909814 -271.940528)
		(mid 134.899615 -271.944365)
		(end 134.889494 -271.948402)
		(width 0.09525)
		(layer "In13.Cu")
		(net "M_H_CPU1_SB_DQS_DN<4>")
	)
	(arc
		(start 137.643362 -271.981422)
		(mid 137.459587 -272.032194)
		(end 137.274554 -271.986248)
		(width 0.09525)
		(layer "In13.Cu")
		(net "M_H_CPU1_SB_DQS_DN<4>")
	)
	(arc
		(start 144.22374 -271.981422)
		(mid 144.039711 -272.032321)
		(end 143.854424 -271.986248)
		(width 0.09525)
		(layer "In13.Cu")
		(net "M_H_CPU1_SB_DQS_DN<4>")
	)
	(arc
		(start 143.846042 -271.981422)
		(mid 143.56461 -271.905667)
		(end 143.283178 -271.981422)
		(width 0.09525)
		(layer "In13.Cu")
		(net "M_H_CPU1_SB_DQS_DN<4>")
	)
	(arc
		(start 138.583416 -271.981422)
		(mid 138.399641 -272.032194)
		(end 138.214608 -271.986248)
		(width 0.09525)
		(layer "In13.Cu")
		(net "M_H_CPU1_SB_DQS_DN<4>")
	)
	(arc
		(start 141.394942 -271.986248)
		(mid 141.20991 -272.032162)
		(end 141.026134 -271.981422)
		(width 0.09525)
		(layer "In13.Cu")
		(net "M_H_CPU1_SB_DQS_DN<4>")
	)
	(segment
		(start 136.047988 -290.830254)
		(end 136.51484 -291.096192)
		(width 0.12954)
		(layer "F.Cu")
		(net "M_H_CPU1_SB_DQS_DN<3>")
	)
	(segment
		(start 165.380924 -313.707526)
		(end 166.112444 -313.707526)
		(width 0.16002)
		(layer "In13.Cu")
		(net "M_H_CPU1_SB_DQS_DN<3>")
	)
	(segment
		(start 147.033488 -293.798752)
		(end 147.033234 -293.881556)
		(width 0.09525)
		(layer "In13.Cu")
		(net "M_H_CPU1_SB_DQS_DN<3>")
	)
	(segment
		(start 170.384978 -313.36234)
		(end 172.29201 -313.36234)
		(width 0.16002)
		(layer "In13.Cu")
		(net "M_H_CPU1_SB_DQS_DN<3>")
	)
	(segment
		(start 164.138102 -313.785504)
		(end 164.552376 -313.37123)
		(width 0.16002)
		(layer "In13.Cu")
		(net "M_H_CPU1_SB_DQS_DN<3>")
	)
	(segment
		(start 168.793922 -313.384184)
		(end 169.25544 -312.922666)
		(width 0.16002)
		(layer "In13.Cu")
		(net "M_H_CPU1_SB_DQS_DN<3>")
	)
	(segment
		(start 175.761396 -313.474608)
		(end 176.072038 -313.78525)
		(width 0.16002)
		(layer "In13.Cu")
		(net "M_H_CPU1_SB_DQS_DN<3>")
	)
	(segment
		(start 169.945304 -312.922666)
		(end 170.384978 -313.36234)
		(width 0.16002)
		(layer "In13.Cu")
		(net "M_H_CPU1_SB_DQS_DN<3>")
	)
	(segment
		(start 165.044628 -313.37123)
		(end 165.380924 -313.707526)
		(width 0.16002)
		(layer "In13.Cu")
		(net "M_H_CPU1_SB_DQS_DN<3>")
	)
	(segment
		(start 144.78381 -290.771072)
		(end 144.802606 -290.76015)
		(width 0.09525)
		(layer "In13.Cu")
		(net "M_H_CPU1_SB_DQS_DN<3>")
	)
	(segment
		(start 145.498566 -291.088826)
		(end 146.33194 -293.077646)
		(width 0.09525)
		(layer "In13.Cu")
		(net "M_H_CPU1_SB_DQS_DN<3>")
	)
	(segment
		(start 163.0426 -313.37123)
		(end 163.456874 -313.785504)
		(width 0.16002)
		(layer "In13.Cu")
		(net "M_H_CPU1_SB_DQS_DN<3>")
	)
	(segment
		(start 136.694926 -290.766246)
		(end 136.703308 -290.771072)
		(width 0.09525)
		(layer "In13.Cu")
		(net "M_H_CPU1_SB_DQS_DN<3>")
	)
	(segment
		(start 144.205706 -290.76142)
		(end 144.22247 -290.771072)
		(width 0.09525)
		(layer "In13.Cu")
		(net "M_H_CPU1_SB_DQS_DN<3>")
	)
	(segment
		(start 172.29201 -313.36234)
		(end 172.627036 -313.697366)
		(width 0.16002)
		(layer "In13.Cu")
		(net "M_H_CPU1_SB_DQS_DN<3>")
	)
	(segment
		(start 145.498312 -291.088318)
		(end 145.498566 -291.088826)
		(width 0.09525)
		(layer "In13.Cu")
		(net "M_H_CPU1_SB_DQS_DN<3>")
	)
	(segment
		(start 167.69842 -312.922666)
		(end 168.159938 -313.384184)
		(width 0.16002)
		(layer "In13.Cu")
		(net "M_H_CPU1_SB_DQS_DN<3>")
	)
	(segment
		(start 173.86935 -313.474608)
		(end 175.761396 -313.474608)
		(width 0.16002)
		(layer "In13.Cu")
		(net "M_H_CPU1_SB_DQS_DN<3>")
	)
	(segment
		(start 147.033234 -293.881556)
		(end 147.049998 -293.89832)
		(width 0.09525)
		(layer "In13.Cu")
		(net "M_H_CPU1_SB_DQS_DN<3>")
	)
	(segment
		(start 146.34591 -293.111174)
		(end 147.033488 -293.798752)
		(width 0.09525)
		(layer "In13.Cu")
		(net "M_H_CPU1_SB_DQS_DN<3>")
	)
	(segment
		(start 146.33194 -293.077646)
		(end 146.34591 -293.111174)
		(width 0.09525)
		(layer "In13.Cu")
		(net "M_H_CPU1_SB_DQS_DN<3>")
	)
	(segment
		(start 145.240502 -290.830508)
		(end 145.498312 -291.088318)
		(width 0.09525)
		(layer "In13.Cu")
		(net "M_H_CPU1_SB_DQS_DN<3>")
	)
	(segment
		(start 172.627036 -313.697366)
		(end 173.646592 -313.697366)
		(width 0.16002)
		(layer "In13.Cu")
		(net "M_H_CPU1_SB_DQS_DN<3>")
	)
	(segment
		(start 160.138364 -313.37123)
		(end 163.0426 -313.37123)
		(width 0.16002)
		(layer "In13.Cu")
		(net "M_H_CPU1_SB_DQS_DN<3>")
	)
	(segment
		(start 144.22247 -290.771072)
		(end 144.24787 -290.785804)
		(width 0.09525)
		(layer "In13.Cu")
		(net "M_H_CPU1_SB_DQS_DN<3>")
	)
	(segment
		(start 166.112444 -313.707526)
		(end 166.897304 -312.922666)
		(width 0.16002)
		(layer "In13.Cu")
		(net "M_H_CPU1_SB_DQS_DN<3>")
	)
	(segment
		(start 147.96643 -294.814752)
		(end 147.96643 -301.199296)
		(width 0.16002)
		(layer "In13.Cu")
		(net "M_H_CPU1_SB_DQS_DN<3>")
	)
	(segment
		(start 138.206226 -290.771072)
		(end 138.214608 -290.766246)
		(width 0.09525)
		(layer "In13.Cu")
		(net "M_H_CPU1_SB_DQS_DN<3>")
	)
	(segment
		(start 166.897304 -312.922666)
		(end 167.69842 -312.922666)
		(width 0.16002)
		(layer "In13.Cu")
		(net "M_H_CPU1_SB_DQS_DN<3>")
	)
	(segment
		(start 136.51484 -291.096192)
		(end 136.360916 -290.830762)
		(width 0.09525)
		(layer "In13.Cu")
		(net "M_H_CPU1_SB_DQS_DN<3>")
	)
	(segment
		(start 147.96643 -301.199296)
		(end 160.138364 -313.37123)
		(width 0.16002)
		(layer "In13.Cu")
		(net "M_H_CPU1_SB_DQS_DN<3>")
	)
	(segment
		(start 164.552376 -313.37123)
		(end 165.044628 -313.37123)
		(width 0.16002)
		(layer "In13.Cu")
		(net "M_H_CPU1_SB_DQS_DN<3>")
	)
	(segment
		(start 136.360916 -290.830762)
		(end 136.384284 -290.743894)
		(width 0.09525)
		(layer "In13.Cu")
		(net "M_H_CPU1_SB_DQS_DN<3>")
	)
	(segment
		(start 163.456874 -313.785504)
		(end 164.138102 -313.785504)
		(width 0.16002)
		(layer "In13.Cu")
		(net "M_H_CPU1_SB_DQS_DN<3>")
	)
	(segment
		(start 147.049998 -293.89832)
		(end 147.96643 -294.814752)
		(width 0.16002)
		(layer "In13.Cu")
		(net "M_H_CPU1_SB_DQS_DN<3>")
	)
	(segment
		(start 141.966188 -290.771072)
		(end 141.97457 -290.766246)
		(width 0.09525)
		(layer "In13.Cu")
		(net "M_H_CPU1_SB_DQS_DN<3>")
	)
	(segment
		(start 141.394942 -290.766246)
		(end 141.403324 -290.771072)
		(width 0.09525)
		(layer "In13.Cu")
		(net "M_H_CPU1_SB_DQS_DN<3>")
	)
	(segment
		(start 169.25544 -312.922666)
		(end 169.945304 -312.922666)
		(width 0.16002)
		(layer "In13.Cu")
		(net "M_H_CPU1_SB_DQS_DN<3>")
	)
	(segment
		(start 168.159938 -313.384184)
		(end 168.793922 -313.384184)
		(width 0.16002)
		(layer "In13.Cu")
		(net "M_H_CPU1_SB_DQS_DN<3>")
	)
	(segment
		(start 173.646592 -313.697366)
		(end 173.86935 -313.474608)
		(width 0.16002)
		(layer "In13.Cu")
		(net "M_H_CPU1_SB_DQS_DN<3>")
	)
	(segment
		(start 140.454888 -290.766246)
		(end 140.46327 -290.771072)
		(width 0.09525)
		(layer "In13.Cu")
		(net "M_H_CPU1_SB_DQS_DN<3>")
	)
	(segment
		(start 137.266172 -290.771072)
		(end 137.274554 -290.766246)
		(width 0.09525)
		(layer "In13.Cu")
		(net "M_H_CPU1_SB_DQS_DN<3>")
	)
	(arc
		(start 136.384284 -290.743894)
		(mid 136.542034 -290.721375)
		(end 136.694926 -290.766246)
		(width 0.09525)
		(layer "In13.Cu")
		(net "M_H_CPU1_SB_DQS_DN<3>")
	)
	(arc
		(start 140.08608 -290.771072)
		(mid 140.269855 -290.7203)
		(end 140.454888 -290.766246)
		(width 0.09525)
		(layer "In13.Cu")
		(net "M_H_CPU1_SB_DQS_DN<3>")
	)
	(arc
		(start 141.403324 -290.771072)
		(mid 141.684756 -290.846827)
		(end 141.966188 -290.771072)
		(width 0.09525)
		(layer "In13.Cu")
		(net "M_H_CPU1_SB_DQS_DN<3>")
	)
	(arc
		(start 137.274554 -290.766246)
		(mid 137.459586 -290.720332)
		(end 137.643362 -290.771072)
		(width 0.09525)
		(layer "In13.Cu")
		(net "M_H_CPU1_SB_DQS_DN<3>")
	)
	(arc
		(start 142.343378 -290.771072)
		(mid 142.62481 -290.846827)
		(end 142.906242 -290.771072)
		(width 0.09525)
		(layer "In13.Cu")
		(net "M_H_CPU1_SB_DQS_DN<3>")
	)
	(arc
		(start 143.846042 -290.771072)
		(mid 144.024648 -290.720404)
		(end 144.205706 -290.76142)
		(width 0.09525)
		(layer "In13.Cu")
		(net "M_H_CPU1_SB_DQS_DN<3>")
	)
	(arc
		(start 144.802606 -290.76015)
		(mid 144.983701 -290.719918)
		(end 145.162016 -290.771072)
		(width 0.09525)
		(layer "In13.Cu")
		(net "M_H_CPU1_SB_DQS_DN<3>")
	)
	(arc
		(start 136.703308 -290.771072)
		(mid 136.98474 -290.846827)
		(end 137.266172 -290.771072)
		(width 0.09525)
		(layer "In13.Cu")
		(net "M_H_CPU1_SB_DQS_DN<3>")
	)
	(arc
		(start 138.583416 -290.771072)
		(mid 138.864848 -290.846827)
		(end 139.14628 -290.771072)
		(width 0.09525)
		(layer "In13.Cu")
		(net "M_H_CPU1_SB_DQS_DN<3>")
	)
	(arc
		(start 139.14628 -290.771072)
		(mid 139.334748 -290.720395)
		(end 139.523216 -290.771072)
		(width 0.09525)
		(layer "In13.Cu")
		(net "M_H_CPU1_SB_DQS_DN<3>")
	)
	(arc
		(start 141.026134 -290.771072)
		(mid 141.209909 -290.7203)
		(end 141.394942 -290.766246)
		(width 0.09525)
		(layer "In13.Cu")
		(net "M_H_CPU1_SB_DQS_DN<3>")
	)
	(arc
		(start 140.46327 -290.771072)
		(mid 140.744702 -290.846827)
		(end 141.026134 -290.771072)
		(width 0.09525)
		(layer "In13.Cu")
		(net "M_H_CPU1_SB_DQS_DN<3>")
	)
	(arc
		(start 144.24787 -290.785804)
		(mid 144.517724 -290.846683)
		(end 144.78381 -290.771072)
		(width 0.09525)
		(layer "In13.Cu")
		(net "M_H_CPU1_SB_DQS_DN<3>")
	)
	(arc
		(start 143.283178 -290.771072)
		(mid 143.56461 -290.846827)
		(end 143.846042 -290.771072)
		(width 0.09525)
		(layer "In13.Cu")
		(net "M_H_CPU1_SB_DQS_DN<3>")
	)
	(arc
		(start 137.643362 -290.771072)
		(mid 137.924794 -290.846827)
		(end 138.206226 -290.771072)
		(width 0.09525)
		(layer "In13.Cu")
		(net "M_H_CPU1_SB_DQS_DN<3>")
	)
	(arc
		(start 139.523216 -290.771072)
		(mid 139.804648 -290.846827)
		(end 140.08608 -290.771072)
		(width 0.09525)
		(layer "In13.Cu")
		(net "M_H_CPU1_SB_DQS_DN<3>")
	)
	(arc
		(start 138.214608 -290.766246)
		(mid 138.39964 -290.720332)
		(end 138.583416 -290.771072)
		(width 0.09525)
		(layer "In13.Cu")
		(net "M_H_CPU1_SB_DQS_DN<3>")
	)
	(arc
		(start 142.906242 -290.771072)
		(mid 143.09471 -290.720395)
		(end 143.283178 -290.771072)
		(width 0.09525)
		(layer "In13.Cu")
		(net "M_H_CPU1_SB_DQS_DN<3>")
	)
	(arc
		(start 145.162016 -290.771072)
		(mid 145.203216 -290.798206)
		(end 145.240502 -290.830508)
		(width 0.09525)
		(layer "In13.Cu")
		(net "M_H_CPU1_SB_DQS_DN<3>")
	)
	(arc
		(start 141.97457 -290.766246)
		(mid 142.159602 -290.720332)
		(end 142.343378 -290.771072)
		(width 0.09525)
		(layer "In13.Cu")
		(net "M_H_CPU1_SB_DQS_DN<3>")
	)
	(segment
		(start 136.047988 -285.970472)
		(end 136.51484 -286.23641)
		(width 0.12954)
		(layer "F.Cu")
		(net "M_H_CPU1_SB_DQS_DN<2>")
	)
	(segment
		(start 168.542208 -303.572672)
		(end 169.945304 -303.572672)
		(width 0.16002)
		(layer "In13.Cu")
		(net "M_H_CPU1_SB_DQS_DN<2>")
	)
	(segment
		(start 138.206226 -285.91129)
		(end 138.214608 -285.906464)
		(width 0.09525)
		(layer "In13.Cu")
		(net "M_H_CPU1_SB_DQS_DN<2>")
	)
	(segment
		(start 172.29201 -304.012346)
		(end 172.627036 -304.347372)
		(width 0.16002)
		(layer "In13.Cu")
		(net "M_H_CPU1_SB_DQS_DN<2>")
	)
	(segment
		(start 147.884134 -286.92475)
		(end 148.067268 -286.92475)
		(width 0.16002)
		(layer "In13.Cu")
		(net "M_H_CPU1_SB_DQS_DN<2>")
	)
	(segment
		(start 174.783242 -303.569624)
		(end 175.391826 -304.178208)
		(width 0.16002)
		(layer "In13.Cu")
		(net "M_H_CPU1_SB_DQS_DN<2>")
	)
	(segment
		(start 155.4099 -298.847256)
		(end 155.4099 -299.32376)
		(width 0.16002)
		(layer "In13.Cu")
		(net "M_H_CPU1_SB_DQS_DN<2>")
	)
	(segment
		(start 153.50363 -292.361112)
		(end 153.50363 -296.28973)
		(width 0.16002)
		(layer "In13.Cu")
		(net "M_H_CPU1_SB_DQS_DN<2>")
	)
	(segment
		(start 147.860512 -286.92475)
		(end 147.884134 -286.92475)
		(width 0.09525)
		(layer "In13.Cu")
		(net "M_H_CPU1_SB_DQS_DN<2>")
	)
	(segment
		(start 175.81499 -304.178208)
		(end 176.072038 -304.435256)
		(width 0.16002)
		(layer "In13.Cu")
		(net "M_H_CPU1_SB_DQS_DN<2>")
	)
	(segment
		(start 148.067268 -286.92475)
		(end 153.50363 -292.361112)
		(width 0.16002)
		(layer "In13.Cu")
		(net "M_H_CPU1_SB_DQS_DN<2>")
	)
	(segment
		(start 155.078176 -298.090336)
		(end 155.304236 -298.090336)
		(width 0.16002)
		(layer "In13.Cu")
		(net "M_H_CPU1_SB_DQS_DN<2>")
	)
	(segment
		(start 154.389074 -298.302934)
		(end 154.865578 -298.302934)
		(width 0.16002)
		(layer "In13.Cu")
		(net "M_H_CPU1_SB_DQS_DN<2>")
	)
	(segment
		(start 167.785288 -303.572672)
		(end 167.924988 -303.712372)
		(width 0.16002)
		(layer "In13.Cu")
		(net "M_H_CPU1_SB_DQS_DN<2>")
	)
	(segment
		(start 144.205706 -285.901638)
		(end 144.24787 -285.926022)
		(width 0.09525)
		(layer "In13.Cu")
		(net "M_H_CPU1_SB_DQS_DN<2>")
	)
	(segment
		(start 144.78381 -285.91129)
		(end 144.802606 -285.900368)
		(width 0.09525)
		(layer "In13.Cu")
		(net "M_H_CPU1_SB_DQS_DN<2>")
	)
	(segment
		(start 147.801584 -286.865822)
		(end 147.860512 -286.92475)
		(width 0.09525)
		(layer "In13.Cu")
		(net "M_H_CPU1_SB_DQS_DN<2>")
	)
	(segment
		(start 167.924988 -303.712372)
		(end 168.402508 -303.712372)
		(width 0.16002)
		(layer "In13.Cu")
		(net "M_H_CPU1_SB_DQS_DN<2>")
	)
	(segment
		(start 146.778472 -286.563054)
		(end 147.320508 -286.563054)
		(width 0.09525)
		(layer "In13.Cu")
		(net "M_H_CPU1_SB_DQS_DN<2>")
	)
	(segment
		(start 175.391826 -304.178208)
		(end 175.81499 -304.178208)
		(width 0.16002)
		(layer "In13.Cu")
		(net "M_H_CPU1_SB_DQS_DN<2>")
	)
	(segment
		(start 153.893012 -297.330368)
		(end 153.893012 -297.806872)
		(width 0.16002)
		(layer "In13.Cu")
		(net "M_H_CPU1_SB_DQS_DN<2>")
	)
	(segment
		(start 140.454888 -285.906464)
		(end 140.46327 -285.91129)
		(width 0.09525)
		(layer "In13.Cu")
		(net "M_H_CPU1_SB_DQS_DN<2>")
	)
	(segment
		(start 136.51484 -286.23641)
		(end 136.360916 -285.97098)
		(width 0.09525)
		(layer "In13.Cu")
		(net "M_H_CPU1_SB_DQS_DN<2>")
	)
	(segment
		(start 146.203162 -285.987744)
		(end 146.778472 -286.563054)
		(width 0.09525)
		(layer "In13.Cu")
		(net "M_H_CPU1_SB_DQS_DN<2>")
	)
	(segment
		(start 168.402508 -303.712372)
		(end 168.542208 -303.572672)
		(width 0.16002)
		(layer "In13.Cu")
		(net "M_H_CPU1_SB_DQS_DN<2>")
	)
	(segment
		(start 155.905962 -299.819822)
		(end 156.382466 -299.819822)
		(width 0.16002)
		(layer "In13.Cu")
		(net "M_H_CPU1_SB_DQS_DN<2>")
	)
	(segment
		(start 156.595064 -299.607224)
		(end 156.821124 -299.607224)
		(width 0.16002)
		(layer "In13.Cu")
		(net "M_H_CPU1_SB_DQS_DN<2>")
	)
	(segment
		(start 156.382466 -299.819822)
		(end 156.595064 -299.607224)
		(width 0.16002)
		(layer "In13.Cu")
		(net "M_H_CPU1_SB_DQS_DN<2>")
	)
	(segment
		(start 154.10561 -296.89171)
		(end 154.10561 -297.11777)
		(width 0.16002)
		(layer "In13.Cu")
		(net "M_H_CPU1_SB_DQS_DN<2>")
	)
	(segment
		(start 163.123118 -304.02149)
		(end 163.45916 -304.357532)
		(width 0.16002)
		(layer "In13.Cu")
		(net "M_H_CPU1_SB_DQS_DN<2>")
	)
	(segment
		(start 147.623276 -286.865822)
		(end 147.801584 -286.865822)
		(width 0.09525)
		(layer "In13.Cu")
		(net "M_H_CPU1_SB_DQS_DN<2>")
	)
	(segment
		(start 153.50363 -296.28973)
		(end 154.10561 -296.89171)
		(width 0.16002)
		(layer "In13.Cu")
		(net "M_H_CPU1_SB_DQS_DN<2>")
	)
	(segment
		(start 172.627036 -304.347372)
		(end 173.778926 -304.347372)
		(width 0.16002)
		(layer "In13.Cu")
		(net "M_H_CPU1_SB_DQS_DN<2>")
	)
	(segment
		(start 153.893012 -297.806872)
		(end 154.389074 -298.302934)
		(width 0.16002)
		(layer "In13.Cu")
		(net "M_H_CPU1_SB_DQS_DN<2>")
	)
	(segment
		(start 147.320508 -286.563054)
		(end 147.623276 -286.865822)
		(width 0.09525)
		(layer "In13.Cu")
		(net "M_H_CPU1_SB_DQS_DN<2>")
	)
	(segment
		(start 173.778926 -304.347372)
		(end 174.556674 -303.569624)
		(width 0.16002)
		(layer "In13.Cu")
		(net "M_H_CPU1_SB_DQS_DN<2>")
	)
	(segment
		(start 154.865578 -298.302934)
		(end 155.078176 -298.090336)
		(width 0.16002)
		(layer "In13.Cu")
		(net "M_H_CPU1_SB_DQS_DN<2>")
	)
	(segment
		(start 166.897304 -303.572672)
		(end 167.785288 -303.572672)
		(width 0.16002)
		(layer "In13.Cu")
		(net "M_H_CPU1_SB_DQS_DN<2>")
	)
	(segment
		(start 141.966188 -285.91129)
		(end 141.97457 -285.906464)
		(width 0.09525)
		(layer "In13.Cu")
		(net "M_H_CPU1_SB_DQS_DN<2>")
	)
	(segment
		(start 155.304236 -298.090336)
		(end 155.622498 -298.408598)
		(width 0.16002)
		(layer "In13.Cu")
		(net "M_H_CPU1_SB_DQS_DN<2>")
	)
	(segment
		(start 155.622498 -298.408598)
		(end 155.622498 -298.634658)
		(width 0.16002)
		(layer "In13.Cu")
		(net "M_H_CPU1_SB_DQS_DN<2>")
	)
	(segment
		(start 156.821124 -299.607224)
		(end 161.23539 -304.02149)
		(width 0.16002)
		(layer "In13.Cu")
		(net "M_H_CPU1_SB_DQS_DN<2>")
	)
	(segment
		(start 141.394942 -285.906464)
		(end 141.403324 -285.91129)
		(width 0.09525)
		(layer "In13.Cu")
		(net "M_H_CPU1_SB_DQS_DN<2>")
	)
	(segment
		(start 136.360916 -285.97098)
		(end 136.384284 -285.884112)
		(width 0.09525)
		(layer "In13.Cu")
		(net "M_H_CPU1_SB_DQS_DN<2>")
	)
	(segment
		(start 154.10561 -297.11777)
		(end 153.893012 -297.330368)
		(width 0.16002)
		(layer "In13.Cu")
		(net "M_H_CPU1_SB_DQS_DN<2>")
	)
	(segment
		(start 155.4099 -299.32376)
		(end 155.905962 -299.819822)
		(width 0.16002)
		(layer "In13.Cu")
		(net "M_H_CPU1_SB_DQS_DN<2>")
	)
	(segment
		(start 145.444718 -285.987744)
		(end 146.203162 -285.987744)
		(width 0.09525)
		(layer "In13.Cu")
		(net "M_H_CPU1_SB_DQS_DN<2>")
	)
	(segment
		(start 161.23539 -304.02149)
		(end 163.123118 -304.02149)
		(width 0.16002)
		(layer "In13.Cu")
		(net "M_H_CPU1_SB_DQS_DN<2>")
	)
	(segment
		(start 166.112444 -304.357532)
		(end 166.897304 -303.572672)
		(width 0.16002)
		(layer "In13.Cu")
		(net "M_H_CPU1_SB_DQS_DN<2>")
	)
	(segment
		(start 169.945304 -303.572672)
		(end 170.384978 -304.012346)
		(width 0.16002)
		(layer "In13.Cu")
		(net "M_H_CPU1_SB_DQS_DN<2>")
	)
	(segment
		(start 137.266172 -285.91129)
		(end 137.274554 -285.906464)
		(width 0.09525)
		(layer "In13.Cu")
		(net "M_H_CPU1_SB_DQS_DN<2>")
	)
	(segment
		(start 155.622498 -298.634658)
		(end 155.4099 -298.847256)
		(width 0.16002)
		(layer "In13.Cu")
		(net "M_H_CPU1_SB_DQS_DN<2>")
	)
	(segment
		(start 163.45916 -304.357532)
		(end 166.112444 -304.357532)
		(width 0.16002)
		(layer "In13.Cu")
		(net "M_H_CPU1_SB_DQS_DN<2>")
	)
	(segment
		(start 136.694926 -285.906464)
		(end 136.703308 -285.91129)
		(width 0.09525)
		(layer "In13.Cu")
		(net "M_H_CPU1_SB_DQS_DN<2>")
	)
	(segment
		(start 174.556674 -303.569624)
		(end 174.783242 -303.569624)
		(width 0.16002)
		(layer "In13.Cu")
		(net "M_H_CPU1_SB_DQS_DN<2>")
	)
	(segment
		(start 170.384978 -304.012346)
		(end 172.29201 -304.012346)
		(width 0.16002)
		(layer "In13.Cu")
		(net "M_H_CPU1_SB_DQS_DN<2>")
	)
	(arc
		(start 139.523216 -285.91129)
		(mid 139.804648 -285.987045)
		(end 140.08608 -285.91129)
		(width 0.09525)
		(layer "In13.Cu")
		(net "M_H_CPU1_SB_DQS_DN<2>")
	)
	(arc
		(start 143.283178 -285.91129)
		(mid 143.56461 -285.987045)
		(end 143.846042 -285.91129)
		(width 0.09525)
		(layer "In13.Cu")
		(net "M_H_CPU1_SB_DQS_DN<2>")
	)
	(arc
		(start 139.14628 -285.91129)
		(mid 139.334748 -285.860613)
		(end 139.523216 -285.91129)
		(width 0.09525)
		(layer "In13.Cu")
		(net "M_H_CPU1_SB_DQS_DN<2>")
	)
	(arc
		(start 141.97457 -285.906464)
		(mid 142.159602 -285.86055)
		(end 142.343378 -285.91129)
		(width 0.09525)
		(layer "In13.Cu")
		(net "M_H_CPU1_SB_DQS_DN<2>")
	)
	(arc
		(start 143.846042 -285.91129)
		(mid 144.024648 -285.860622)
		(end 144.205706 -285.901638)
		(width 0.09525)
		(layer "In13.Cu")
		(net "M_H_CPU1_SB_DQS_DN<2>")
	)
	(arc
		(start 142.343378 -285.91129)
		(mid 142.62481 -285.987045)
		(end 142.906242 -285.91129)
		(width 0.09525)
		(layer "In13.Cu")
		(net "M_H_CPU1_SB_DQS_DN<2>")
	)
	(arc
		(start 142.906242 -285.91129)
		(mid 143.09471 -285.860613)
		(end 143.283178 -285.91129)
		(width 0.09525)
		(layer "In13.Cu")
		(net "M_H_CPU1_SB_DQS_DN<2>")
	)
	(arc
		(start 140.08608 -285.91129)
		(mid 140.269855 -285.860518)
		(end 140.454888 -285.906464)
		(width 0.09525)
		(layer "In13.Cu")
		(net "M_H_CPU1_SB_DQS_DN<2>")
	)
	(arc
		(start 144.802606 -285.900368)
		(mid 144.983701 -285.860136)
		(end 145.162016 -285.91129)
		(width 0.09525)
		(layer "In13.Cu")
		(net "M_H_CPU1_SB_DQS_DN<2>")
	)
	(arc
		(start 136.703308 -285.91129)
		(mid 136.98474 -285.987045)
		(end 137.266172 -285.91129)
		(width 0.09525)
		(layer "In13.Cu")
		(net "M_H_CPU1_SB_DQS_DN<2>")
	)
	(arc
		(start 137.274554 -285.906464)
		(mid 137.459586 -285.86055)
		(end 137.643362 -285.91129)
		(width 0.09525)
		(layer "In13.Cu")
		(net "M_H_CPU1_SB_DQS_DN<2>")
	)
	(arc
		(start 136.384284 -285.884112)
		(mid 136.542034 -285.861593)
		(end 136.694926 -285.906464)
		(width 0.09525)
		(layer "In13.Cu")
		(net "M_H_CPU1_SB_DQS_DN<2>")
	)
	(arc
		(start 138.214608 -285.906464)
		(mid 138.39964 -285.86055)
		(end 138.583416 -285.91129)
		(width 0.09525)
		(layer "In13.Cu")
		(net "M_H_CPU1_SB_DQS_DN<2>")
	)
	(arc
		(start 137.643362 -285.91129)
		(mid 137.924794 -285.987045)
		(end 138.206226 -285.91129)
		(width 0.09525)
		(layer "In13.Cu")
		(net "M_H_CPU1_SB_DQS_DN<2>")
	)
	(arc
		(start 145.162016 -285.91129)
		(mid 145.298297 -285.968249)
		(end 145.444718 -285.987744)
		(width 0.09525)
		(layer "In13.Cu")
		(net "M_H_CPU1_SB_DQS_DN<2>")
	)
	(arc
		(start 144.24787 -285.926022)
		(mid 144.517724 -285.986901)
		(end 144.78381 -285.91129)
		(width 0.09525)
		(layer "In13.Cu")
		(net "M_H_CPU1_SB_DQS_DN<2>")
	)
	(arc
		(start 140.46327 -285.91129)
		(mid 140.744702 -285.987045)
		(end 141.026134 -285.91129)
		(width 0.09525)
		(layer "In13.Cu")
		(net "M_H_CPU1_SB_DQS_DN<2>")
	)
	(arc
		(start 141.026134 -285.91129)
		(mid 141.209909 -285.860518)
		(end 141.394942 -285.906464)
		(width 0.09525)
		(layer "In13.Cu")
		(net "M_H_CPU1_SB_DQS_DN<2>")
	)
	(arc
		(start 138.583416 -285.91129)
		(mid 138.864848 -285.987045)
		(end 139.14628 -285.91129)
		(width 0.09525)
		(layer "In13.Cu")
		(net "M_H_CPU1_SB_DQS_DN<2>")
	)
	(arc
		(start 141.403324 -285.91129)
		(mid 141.684756 -285.987045)
		(end 141.966188 -285.91129)
		(width 0.09525)
		(layer "In13.Cu")
		(net "M_H_CPU1_SB_DQS_DN<2>")
	)
	(segment
		(start 136.047988 -281.110436)
		(end 136.51484 -281.376374)
		(width 0.12954)
		(layer "F.Cu")
		(net "M_H_CPU1_SB_DQS_DN<1>")
	)
	(segment
		(start 147.79244 -281.159712)
		(end 147.768818 -281.159712)
		(width 0.09525)
		(layer "In13.Cu")
		(net "M_H_CPU1_SB_DQS_DN<1>")
	)
	(segment
		(start 172.627036 -294.997378)
		(end 172.29201 -294.662352)
		(width 0.16002)
		(layer "In13.Cu")
		(net "M_H_CPU1_SB_DQS_DN<1>")
	)
	(segment
		(start 145.72996 -281.127454)
		(end 145.444718 -281.127454)
		(width 0.09525)
		(layer "In13.Cu")
		(net "M_H_CPU1_SB_DQS_DN<1>")
	)
	(segment
		(start 147.531836 -281.100784)
		(end 147.153122 -280.72207)
		(width 0.09525)
		(layer "In13.Cu")
		(net "M_H_CPU1_SB_DQS_DN<1>")
	)
	(segment
		(start 150.135844 -281.159712)
		(end 147.79244 -281.159712)
		(width 0.16002)
		(layer "In13.Cu")
		(net "M_H_CPU1_SB_DQS_DN<1>")
	)
	(segment
		(start 147.70989 -281.100784)
		(end 147.531836 -281.100784)
		(width 0.09525)
		(layer "In13.Cu")
		(net "M_H_CPU1_SB_DQS_DN<1>")
	)
	(segment
		(start 166.897304 -294.222678)
		(end 166.112444 -295.007538)
		(width 0.16002)
		(layer "In13.Cu")
		(net "M_H_CPU1_SB_DQS_DN<1>")
	)
	(segment
		(start 174.960026 -294.997378)
		(end 172.627036 -294.997378)
		(width 0.16002)
		(layer "In13.Cu")
		(net "M_H_CPU1_SB_DQS_DN<1>")
	)
	(segment
		(start 161.115756 -292.608508)
		(end 160.288986 -291.781738)
		(width 0.16002)
		(layer "In13.Cu")
		(net "M_H_CPU1_SB_DQS_DN<1>")
	)
	(segment
		(start 159.04083 -291.091874)
		(end 159.04083 -290.064698)
		(width 0.16002)
		(layer "In13.Cu")
		(net "M_H_CPU1_SB_DQS_DN<1>")
	)
	(segment
		(start 161.115756 -293.89578)
		(end 161.115756 -292.608508)
		(width 0.16002)
		(layer "In13.Cu")
		(net "M_H_CPU1_SB_DQS_DN<1>")
	)
	(segment
		(start 160.288986 -291.781738)
		(end 159.730694 -291.781738)
		(width 0.16002)
		(layer "In13.Cu")
		(net "M_H_CPU1_SB_DQS_DN<1>")
	)
	(segment
		(start 136.384284 -281.024076)
		(end 136.360916 -281.110944)
		(width 0.09525)
		(layer "In13.Cu")
		(net "M_H_CPU1_SB_DQS_DN<1>")
	)
	(segment
		(start 144.79905 -281.042872)
		(end 144.784572 -281.051254)
		(width 0.09525)
		(layer "In13.Cu")
		(net "M_H_CPU1_SB_DQS_DN<1>")
	)
	(segment
		(start 140.46327 -281.051254)
		(end 140.454888 -281.046428)
		(width 0.09525)
		(layer "In13.Cu")
		(net "M_H_CPU1_SB_DQS_DN<1>")
	)
	(segment
		(start 176.072038 -295.085262)
		(end 175.766984 -294.780208)
		(width 0.16002)
		(layer "In13.Cu")
		(net "M_H_CPU1_SB_DQS_DN<1>")
	)
	(segment
		(start 136.360916 -281.110944)
		(end 136.51484 -281.376374)
		(width 0.09525)
		(layer "In13.Cu")
		(net "M_H_CPU1_SB_DQS_DN<1>")
	)
	(segment
		(start 147.153122 -280.72207)
		(end 146.213576 -280.72207)
		(width 0.09525)
		(layer "In13.Cu")
		(net "M_H_CPU1_SB_DQS_DN<1>")
	)
	(segment
		(start 146.079718 -280.777696)
		(end 145.72996 -281.127454)
		(width 0.09525)
		(layer "In13.Cu")
		(net "M_H_CPU1_SB_DQS_DN<1>")
	)
	(segment
		(start 175.177196 -294.780208)
		(end 174.960026 -294.997378)
		(width 0.16002)
		(layer "In13.Cu")
		(net "M_H_CPU1_SB_DQS_DN<1>")
	)
	(segment
		(start 161.911284 -295.469818)
		(end 161.434526 -295.469818)
		(width 0.16002)
		(layer "In13.Cu")
		(net "M_H_CPU1_SB_DQS_DN<1>")
	)
	(segment
		(start 175.766984 -294.780208)
		(end 175.177196 -294.780208)
		(width 0.16002)
		(layer "In13.Cu")
		(net "M_H_CPU1_SB_DQS_DN<1>")
	)
	(segment
		(start 144.243552 -281.063446)
		(end 144.208246 -281.042872)
		(width 0.09525)
		(layer "In13.Cu")
		(net "M_H_CPU1_SB_DQS_DN<1>")
	)
	(segment
		(start 137.274554 -281.046428)
		(end 137.266172 -281.051254)
		(width 0.09525)
		(layer "In13.Cu")
		(net "M_H_CPU1_SB_DQS_DN<1>")
	)
	(segment
		(start 164.898578 -294.762174)
		(end 162.618928 -294.762174)
		(width 0.16002)
		(layer "In13.Cu")
		(net "M_H_CPU1_SB_DQS_DN<1>")
	)
	(segment
		(start 172.29201 -294.662352)
		(end 170.384978 -294.662352)
		(width 0.16002)
		(layer "In13.Cu")
		(net "M_H_CPU1_SB_DQS_DN<1>")
	)
	(segment
		(start 159.730694 -291.781738)
		(end 159.04083 -291.091874)
		(width 0.16002)
		(layer "In13.Cu")
		(net "M_H_CPU1_SB_DQS_DN<1>")
	)
	(segment
		(start 141.403324 -281.051254)
		(end 141.394942 -281.046428)
		(width 0.09525)
		(layer "In13.Cu")
		(net "M_H_CPU1_SB_DQS_DN<1>")
	)
	(segment
		(start 162.618928 -294.762174)
		(end 161.911284 -295.469818)
		(width 0.16002)
		(layer "In13.Cu")
		(net "M_H_CPU1_SB_DQS_DN<1>")
	)
	(segment
		(start 169.945304 -294.222678)
		(end 166.897304 -294.222678)
		(width 0.16002)
		(layer "In13.Cu")
		(net "M_H_CPU1_SB_DQS_DN<1>")
	)
	(segment
		(start 160.726374 -294.285162)
		(end 161.115756 -293.89578)
		(width 0.16002)
		(layer "In13.Cu")
		(net "M_H_CPU1_SB_DQS_DN<1>")
	)
	(segment
		(start 170.384978 -294.662352)
		(end 169.945304 -294.222678)
		(width 0.16002)
		(layer "In13.Cu")
		(net "M_H_CPU1_SB_DQS_DN<1>")
	)
	(segment
		(start 165.143942 -295.007538)
		(end 164.898578 -294.762174)
		(width 0.16002)
		(layer "In13.Cu")
		(net "M_H_CPU1_SB_DQS_DN<1>")
	)
	(segment
		(start 136.703308 -281.051254)
		(end 136.694926 -281.046428)
		(width 0.09525)
		(layer "In13.Cu")
		(net "M_H_CPU1_SB_DQS_DN<1>")
	)
	(segment
		(start 138.214608 -281.046428)
		(end 138.206226 -281.051254)
		(width 0.09525)
		(layer "In13.Cu")
		(net "M_H_CPU1_SB_DQS_DN<1>")
	)
	(segment
		(start 161.434526 -295.469818)
		(end 160.726374 -294.761666)
		(width 0.16002)
		(layer "In13.Cu")
		(net "M_H_CPU1_SB_DQS_DN<1>")
	)
	(segment
		(start 160.726374 -294.761666)
		(end 160.726374 -294.285162)
		(width 0.16002)
		(layer "In13.Cu")
		(net "M_H_CPU1_SB_DQS_DN<1>")
	)
	(segment
		(start 141.97457 -281.046428)
		(end 141.966188 -281.051254)
		(width 0.09525)
		(layer "In13.Cu")
		(net "M_H_CPU1_SB_DQS_DN<1>")
	)
	(segment
		(start 147.768818 -281.159712)
		(end 147.70989 -281.100784)
		(width 0.09525)
		(layer "In13.Cu")
		(net "M_H_CPU1_SB_DQS_DN<1>")
	)
	(segment
		(start 166.112444 -295.007538)
		(end 165.143942 -295.007538)
		(width 0.16002)
		(layer "In13.Cu")
		(net "M_H_CPU1_SB_DQS_DN<1>")
	)
	(segment
		(start 159.04083 -290.064698)
		(end 150.135844 -281.159712)
		(width 0.16002)
		(layer "In13.Cu")
		(net "M_H_CPU1_SB_DQS_DN<1>")
	)
	(arc
		(start 138.206226 -281.051254)
		(mid 137.924794 -281.127009)
		(end 137.643362 -281.051254)
		(width 0.09525)
		(layer "In13.Cu")
		(net "M_H_CPU1_SB_DQS_DN<1>")
	)
	(arc
		(start 145.444718 -281.127454)
		(mid 145.298453 -281.108054)
		(end 145.16227 -281.051254)
		(width 0.09525)
		(layer "In13.Cu")
		(net "M_H_CPU1_SB_DQS_DN<1>")
	)
	(arc
		(start 142.343378 -281.051254)
		(mid 142.159603 -281.000482)
		(end 141.97457 -281.046428)
		(width 0.09525)
		(layer "In13.Cu")
		(net "M_H_CPU1_SB_DQS_DN<1>")
	)
	(arc
		(start 140.454888 -281.046428)
		(mid 140.269856 -281.000514)
		(end 140.08608 -281.051254)
		(width 0.09525)
		(layer "In13.Cu")
		(net "M_H_CPU1_SB_DQS_DN<1>")
	)
	(arc
		(start 139.14628 -281.051254)
		(mid 138.864848 -281.127009)
		(end 138.583416 -281.051254)
		(width 0.09525)
		(layer "In13.Cu")
		(net "M_H_CPU1_SB_DQS_DN<1>")
	)
	(arc
		(start 142.906242 -281.051254)
		(mid 142.62481 -281.127009)
		(end 142.343378 -281.051254)
		(width 0.09525)
		(layer "In13.Cu")
		(net "M_H_CPU1_SB_DQS_DN<1>")
	)
	(arc
		(start 137.643362 -281.051254)
		(mid 137.459587 -281.000482)
		(end 137.274554 -281.046428)
		(width 0.09525)
		(layer "In13.Cu")
		(net "M_H_CPU1_SB_DQS_DN<1>")
	)
	(arc
		(start 140.08608 -281.051254)
		(mid 139.804648 -281.127009)
		(end 139.523216 -281.051254)
		(width 0.09525)
		(layer "In13.Cu")
		(net "M_H_CPU1_SB_DQS_DN<1>")
	)
	(arc
		(start 145.16227 -281.051254)
		(mid 144.981737 -281.000295)
		(end 144.79905 -281.042872)
		(width 0.09525)
		(layer "In13.Cu")
		(net "M_H_CPU1_SB_DQS_DN<1>")
	)
	(arc
		(start 141.026134 -281.051254)
		(mid 140.744702 -281.127009)
		(end 140.46327 -281.051254)
		(width 0.09525)
		(layer "In13.Cu")
		(net "M_H_CPU1_SB_DQS_DN<1>")
	)
	(arc
		(start 141.394942 -281.046428)
		(mid 141.20991 -281.000514)
		(end 141.026134 -281.051254)
		(width 0.09525)
		(layer "In13.Cu")
		(net "M_H_CPU1_SB_DQS_DN<1>")
	)
	(arc
		(start 138.583416 -281.051254)
		(mid 138.399641 -281.000482)
		(end 138.214608 -281.046428)
		(width 0.09525)
		(layer "In13.Cu")
		(net "M_H_CPU1_SB_DQS_DN<1>")
	)
	(arc
		(start 139.523216 -281.051254)
		(mid 139.334748 -281.000577)
		(end 139.14628 -281.051254)
		(width 0.09525)
		(layer "In13.Cu")
		(net "M_H_CPU1_SB_DQS_DN<1>")
	)
	(arc
		(start 144.784572 -281.051254)
		(mid 144.515618 -281.126992)
		(end 144.243552 -281.063446)
		(width 0.09525)
		(layer "In13.Cu")
		(net "M_H_CPU1_SB_DQS_DN<1>")
	)
	(arc
		(start 137.266172 -281.051254)
		(mid 136.98474 -281.127009)
		(end 136.703308 -281.051254)
		(width 0.09525)
		(layer "In13.Cu")
		(net "M_H_CPU1_SB_DQS_DN<1>")
	)
	(arc
		(start 144.208246 -281.042872)
		(mid 144.026068 -281.00055)
		(end 143.846042 -281.051254)
		(width 0.09525)
		(layer "In13.Cu")
		(net "M_H_CPU1_SB_DQS_DN<1>")
	)
	(arc
		(start 136.694926 -281.046428)
		(mid 136.542031 -281.0016)
		(end 136.384284 -281.024076)
		(width 0.09525)
		(layer "In13.Cu")
		(net "M_H_CPU1_SB_DQS_DN<1>")
	)
	(arc
		(start 141.966188 -281.051254)
		(mid 141.684756 -281.127009)
		(end 141.403324 -281.051254)
		(width 0.09525)
		(layer "In13.Cu")
		(net "M_H_CPU1_SB_DQS_DN<1>")
	)
	(arc
		(start 143.846042 -281.051254)
		(mid 143.56461 -281.127009)
		(end 143.283178 -281.051254)
		(width 0.09525)
		(layer "In13.Cu")
		(net "M_H_CPU1_SB_DQS_DN<1>")
	)
	(arc
		(start 146.213576 -280.72207)
		(mid 146.141132 -280.736592)
		(end 146.079718 -280.777696)
		(width 0.09525)
		(layer "In13.Cu")
		(net "M_H_CPU1_SB_DQS_DN<1>")
	)
	(arc
		(start 143.283178 -281.051254)
		(mid 143.09471 -281.000577)
		(end 142.906242 -281.051254)
		(width 0.09525)
		(layer "In13.Cu")
		(net "M_H_CPU1_SB_DQS_DN<1>")
	)
	(segment
		(start 136.047988 -276.2504)
		(end 136.51484 -276.516338)
		(width 0.12954)
		(layer "F.Cu")
		(net "M_H_CPU1_SB_DQS_DN<0>")
	)
	(segment
		(start 168.426384 -284.171136)
		(end 168.875964 -284.171136)
		(width 0.16002)
		(layer "In13.Cu")
		(net "M_H_CPU1_SB_DQS_DN<0>")
	)
	(segment
		(start 173.835568 -285.458408)
		(end 174.345346 -285.458408)
		(width 0.16002)
		(layer "In13.Cu")
		(net "M_H_CPU1_SB_DQS_DN<0>")
	)
	(segment
		(start 146.761454 -275.181568)
		(end 147.360132 -275.181568)
		(width 0.09525)
		(layer "In13.Cu")
		(net "M_H_CPU1_SB_DQS_DN<0>")
	)
	(segment
		(start 173.004988 -285.647384)
		(end 173.646592 -285.647384)
		(width 0.16002)
		(layer "In13.Cu")
		(net "M_H_CPU1_SB_DQS_DN<0>")
	)
	(segment
		(start 175.795178 -285.458408)
		(end 176.072038 -285.735268)
		(width 0.16002)
		(layer "In13.Cu")
		(net "M_H_CPU1_SB_DQS_DN<0>")
	)
	(segment
		(start 156.182568 -277.891748)
		(end 163.211764 -284.920944)
		(width 0.16002)
		(layer "In13.Cu")
		(net "M_H_CPU1_SB_DQS_DN<0>")
	)
	(segment
		(start 138.206226 -276.191218)
		(end 138.214608 -276.186392)
		(width 0.09525)
		(layer "In13.Cu")
		(net "M_H_CPU1_SB_DQS_DN<0>")
	)
	(segment
		(start 141.966188 -276.191218)
		(end 141.97457 -276.186392)
		(width 0.09525)
		(layer "In13.Cu")
		(net "M_H_CPU1_SB_DQS_DN<0>")
	)
	(segment
		(start 164.822124 -284.920944)
		(end 165.558724 -285.657544)
		(width 0.16002)
		(layer "In13.Cu")
		(net "M_H_CPU1_SB_DQS_DN<0>")
	)
	(segment
		(start 147.694396 -275.140928)
		(end 147.753578 -275.20011)
		(width 0.09525)
		(layer "In13.Cu")
		(net "M_H_CPU1_SB_DQS_DN<0>")
	)
	(segment
		(start 174.345346 -285.458408)
		(end 174.485046 -285.598108)
		(width 0.16002)
		(layer "In13.Cu")
		(net "M_H_CPU1_SB_DQS_DN<0>")
	)
	(segment
		(start 136.694926 -276.186392)
		(end 136.703308 -276.191218)
		(width 0.09525)
		(layer "In13.Cu")
		(net "M_H_CPU1_SB_DQS_DN<0>")
	)
	(segment
		(start 169.035984 -284.535626)
		(end 169.373042 -284.872684)
		(width 0.16002)
		(layer "In13.Cu")
		(net "M_H_CPU1_SB_DQS_DN<0>")
	)
	(segment
		(start 167.929306 -284.872684)
		(end 168.266364 -284.535626)
		(width 0.16002)
		(layer "In13.Cu")
		(net "M_H_CPU1_SB_DQS_DN<0>")
	)
	(segment
		(start 168.266364 -284.331156)
		(end 168.426384 -284.171136)
		(width 0.16002)
		(layer "In13.Cu")
		(net "M_H_CPU1_SB_DQS_DN<0>")
	)
	(segment
		(start 166.112444 -285.657544)
		(end 166.897304 -284.872684)
		(width 0.16002)
		(layer "In13.Cu")
		(net "M_H_CPU1_SB_DQS_DN<0>")
	)
	(segment
		(start 175.102266 -285.458408)
		(end 175.795178 -285.458408)
		(width 0.16002)
		(layer "In13.Cu")
		(net "M_H_CPU1_SB_DQS_DN<0>")
	)
	(segment
		(start 147.753578 -275.20011)
		(end 147.7772 -275.20011)
		(width 0.09525)
		(layer "In13.Cu")
		(net "M_H_CPU1_SB_DQS_DN<0>")
	)
	(segment
		(start 169.035984 -284.331156)
		(end 169.035984 -284.535626)
		(width 0.16002)
		(layer "In13.Cu")
		(net "M_H_CPU1_SB_DQS_DN<0>")
	)
	(segment
		(start 168.875964 -284.171136)
		(end 169.035984 -284.331156)
		(width 0.16002)
		(layer "In13.Cu")
		(net "M_H_CPU1_SB_DQS_DN<0>")
	)
	(segment
		(start 169.373042 -284.872684)
		(end 169.752772 -284.872684)
		(width 0.16002)
		(layer "In13.Cu")
		(net "M_H_CPU1_SB_DQS_DN<0>")
	)
	(segment
		(start 152.50541 -275.20011)
		(end 155.197048 -277.891748)
		(width 0.16002)
		(layer "In13.Cu")
		(net "M_H_CPU1_SB_DQS_DN<0>")
	)
	(segment
		(start 163.211764 -284.920944)
		(end 164.822124 -284.920944)
		(width 0.16002)
		(layer "In13.Cu")
		(net "M_H_CPU1_SB_DQS_DN<0>")
	)
	(segment
		(start 169.752772 -284.872684)
		(end 170.159426 -285.041086)
		(width 0.16002)
		(layer "In13.Cu")
		(net "M_H_CPU1_SB_DQS_DN<0>")
	)
	(segment
		(start 136.51484 -276.516338)
		(end 136.360916 -276.250908)
		(width 0.09525)
		(layer "In13.Cu")
		(net "M_H_CPU1_SB_DQS_DN<0>")
	)
	(segment
		(start 144.784572 -276.191218)
		(end 144.797526 -276.183852)
		(width 0.09525)
		(layer "In13.Cu")
		(net "M_H_CPU1_SB_DQS_DN<0>")
	)
	(segment
		(start 144.208246 -276.182836)
		(end 144.243552 -276.20341)
		(width 0.09525)
		(layer "In13.Cu")
		(net "M_H_CPU1_SB_DQS_DN<0>")
	)
	(segment
		(start 147.400772 -275.140928)
		(end 147.694396 -275.140928)
		(width 0.09525)
		(layer "In13.Cu")
		(net "M_H_CPU1_SB_DQS_DN<0>")
	)
	(segment
		(start 165.558724 -285.657544)
		(end 166.112444 -285.657544)
		(width 0.16002)
		(layer "In13.Cu")
		(net "M_H_CPU1_SB_DQS_DN<0>")
	)
	(segment
		(start 172.39869 -285.041086)
		(end 173.004988 -285.647384)
		(width 0.16002)
		(layer "In13.Cu")
		(net "M_H_CPU1_SB_DQS_DN<0>")
	)
	(segment
		(start 147.360132 -275.181568)
		(end 147.400772 -275.140928)
		(width 0.09525)
		(layer "In13.Cu")
		(net "M_H_CPU1_SB_DQS_DN<0>")
	)
	(segment
		(start 141.394942 -276.186392)
		(end 141.403324 -276.191218)
		(width 0.09525)
		(layer "In13.Cu")
		(net "M_H_CPU1_SB_DQS_DN<0>")
	)
	(segment
		(start 166.897304 -284.872684)
		(end 167.929306 -284.872684)
		(width 0.16002)
		(layer "In13.Cu")
		(net "M_H_CPU1_SB_DQS_DN<0>")
	)
	(segment
		(start 140.454888 -276.186392)
		(end 140.46327 -276.191218)
		(width 0.09525)
		(layer "In13.Cu")
		(net "M_H_CPU1_SB_DQS_DN<0>")
	)
	(segment
		(start 145.839942 -276.10308)
		(end 146.761454 -275.181568)
		(width 0.09525)
		(layer "In13.Cu")
		(net "M_H_CPU1_SB_DQS_DN<0>")
	)
	(segment
		(start 155.197048 -277.891748)
		(end 156.182568 -277.891748)
		(width 0.16002)
		(layer "In13.Cu")
		(net "M_H_CPU1_SB_DQS_DN<0>")
	)
	(segment
		(start 136.360916 -276.250908)
		(end 136.384284 -276.16404)
		(width 0.09525)
		(layer "In13.Cu")
		(net "M_H_CPU1_SB_DQS_DN<0>")
	)
	(segment
		(start 144.797526 -276.183852)
		(end 144.79905 -276.182836)
		(width 0.09525)
		(layer "In13.Cu")
		(net "M_H_CPU1_SB_DQS_DN<0>")
	)
	(segment
		(start 170.159426 -285.041086)
		(end 172.39869 -285.041086)
		(width 0.16002)
		(layer "In13.Cu")
		(net "M_H_CPU1_SB_DQS_DN<0>")
	)
	(segment
		(start 147.7772 -275.20011)
		(end 152.50541 -275.20011)
		(width 0.16002)
		(layer "In13.Cu")
		(net "M_H_CPU1_SB_DQS_DN<0>")
	)
	(segment
		(start 173.646592 -285.647384)
		(end 173.835568 -285.458408)
		(width 0.16002)
		(layer "In13.Cu")
		(net "M_H_CPU1_SB_DQS_DN<0>")
	)
	(segment
		(start 137.266172 -276.191218)
		(end 137.274554 -276.186392)
		(width 0.09525)
		(layer "In13.Cu")
		(net "M_H_CPU1_SB_DQS_DN<0>")
	)
	(segment
		(start 174.962566 -285.598108)
		(end 175.102266 -285.458408)
		(width 0.16002)
		(layer "In13.Cu")
		(net "M_H_CPU1_SB_DQS_DN<0>")
	)
	(segment
		(start 168.266364 -284.535626)
		(end 168.266364 -284.331156)
		(width 0.16002)
		(layer "In13.Cu")
		(net "M_H_CPU1_SB_DQS_DN<0>")
	)
	(segment
		(start 174.485046 -285.598108)
		(end 174.962566 -285.598108)
		(width 0.16002)
		(layer "In13.Cu")
		(net "M_H_CPU1_SB_DQS_DN<0>")
	)
	(arc
		(start 142.343378 -276.191218)
		(mid 142.62481 -276.266973)
		(end 142.906242 -276.191218)
		(width 0.09525)
		(layer "In13.Cu")
		(net "M_H_CPU1_SB_DQS_DN<0>")
	)
	(arc
		(start 143.283178 -276.191218)
		(mid 143.56461 -276.266973)
		(end 143.846042 -276.191218)
		(width 0.09525)
		(layer "In13.Cu")
		(net "M_H_CPU1_SB_DQS_DN<0>")
	)
	(arc
		(start 142.906242 -276.191218)
		(mid 143.09471 -276.140541)
		(end 143.283178 -276.191218)
		(width 0.09525)
		(layer "In13.Cu")
		(net "M_H_CPU1_SB_DQS_DN<0>")
	)
	(arc
		(start 141.026134 -276.191218)
		(mid 141.209909 -276.140446)
		(end 141.394942 -276.186392)
		(width 0.09525)
		(layer "In13.Cu")
		(net "M_H_CPU1_SB_DQS_DN<0>")
	)
	(arc
		(start 137.274554 -276.186392)
		(mid 137.459586 -276.140478)
		(end 137.643362 -276.191218)
		(width 0.09525)
		(layer "In13.Cu")
		(net "M_H_CPU1_SB_DQS_DN<0>")
	)
	(arc
		(start 145.16227 -276.191218)
		(mid 145.51613 -276.262534)
		(end 145.839942 -276.10308)
		(width 0.09525)
		(layer "In13.Cu")
		(net "M_H_CPU1_SB_DQS_DN<0>")
	)
	(arc
		(start 140.08608 -276.191218)
		(mid 140.269855 -276.140446)
		(end 140.454888 -276.186392)
		(width 0.09525)
		(layer "In13.Cu")
		(net "M_H_CPU1_SB_DQS_DN<0>")
	)
	(arc
		(start 139.523216 -276.191218)
		(mid 139.804648 -276.266973)
		(end 140.08608 -276.191218)
		(width 0.09525)
		(layer "In13.Cu")
		(net "M_H_CPU1_SB_DQS_DN<0>")
	)
	(arc
		(start 144.79905 -276.182836)
		(mid 144.981736 -276.140279)
		(end 145.16227 -276.191218)
		(width 0.09525)
		(layer "In13.Cu")
		(net "M_H_CPU1_SB_DQS_DN<0>")
	)
	(arc
		(start 141.403324 -276.191218)
		(mid 141.684756 -276.266973)
		(end 141.966188 -276.191218)
		(width 0.09525)
		(layer "In13.Cu")
		(net "M_H_CPU1_SB_DQS_DN<0>")
	)
	(arc
		(start 143.846042 -276.191218)
		(mid 144.026068 -276.140514)
		(end 144.208246 -276.182836)
		(width 0.09525)
		(layer "In13.Cu")
		(net "M_H_CPU1_SB_DQS_DN<0>")
	)
	(arc
		(start 140.46327 -276.191218)
		(mid 140.744702 -276.266973)
		(end 141.026134 -276.191218)
		(width 0.09525)
		(layer "In13.Cu")
		(net "M_H_CPU1_SB_DQS_DN<0>")
	)
	(arc
		(start 138.214608 -276.186392)
		(mid 138.39964 -276.140478)
		(end 138.583416 -276.191218)
		(width 0.09525)
		(layer "In13.Cu")
		(net "M_H_CPU1_SB_DQS_DN<0>")
	)
	(arc
		(start 136.703308 -276.191218)
		(mid 136.98474 -276.266973)
		(end 137.266172 -276.191218)
		(width 0.09525)
		(layer "In13.Cu")
		(net "M_H_CPU1_SB_DQS_DN<0>")
	)
	(arc
		(start 141.97457 -276.186392)
		(mid 142.159602 -276.140478)
		(end 142.343378 -276.191218)
		(width 0.09525)
		(layer "In13.Cu")
		(net "M_H_CPU1_SB_DQS_DN<0>")
	)
	(arc
		(start 139.14628 -276.191218)
		(mid 139.334748 -276.140541)
		(end 139.523216 -276.191218)
		(width 0.09525)
		(layer "In13.Cu")
		(net "M_H_CPU1_SB_DQS_DN<0>")
	)
	(arc
		(start 144.243552 -276.20341)
		(mid 144.515615 -276.266848)
		(end 144.784572 -276.191218)
		(width 0.09525)
		(layer "In13.Cu")
		(net "M_H_CPU1_SB_DQS_DN<0>")
	)
	(arc
		(start 137.643362 -276.191218)
		(mid 137.924794 -276.266973)
		(end 138.206226 -276.191218)
		(width 0.09525)
		(layer "In13.Cu")
		(net "M_H_CPU1_SB_DQS_DN<0>")
	)
	(arc
		(start 138.583416 -276.191218)
		(mid 138.864848 -276.266973)
		(end 139.14628 -276.191218)
		(width 0.09525)
		(layer "In13.Cu")
		(net "M_H_CPU1_SB_DQS_DN<0>")
	)
	(arc
		(start 136.384284 -276.16404)
		(mid 136.542034 -276.141521)
		(end 136.694926 -276.186392)
		(width 0.09525)
		(layer "In13.Cu")
		(net "M_H_CPU1_SB_DQS_DN<0>")
	)
	(segment
		(start 134.16788 -279.490424)
		(end 134.634732 -279.756362)
		(width 0.10668)
		(layer "F.Cu")
		(net "M_H_CPU1_SB_DQ<9>")
	)
	(segment
		(start 136.693402 -280.083768)
		(end 136.701784 -280.078942)
		(width 0.0889)
		(layer "In13.Cu")
		(net "M_H_CPU1_SB_DQ<9>")
	)
	(segment
		(start 134.788656 -280.021792)
		(end 134.884668 -280.047192)
		(width 0.0889)
		(layer "In13.Cu")
		(net "M_H_CPU1_SB_DQ<9>")
	)
	(segment
		(start 135.753348 -280.083768)
		(end 135.76173 -280.078942)
		(width 0.0889)
		(layer "In13.Cu")
		(net "M_H_CPU1_SB_DQ<9>")
	)
	(segment
		(start 150.575772 -279.745694)
		(end 160.35147 -289.521392)
		(width 0.14478)
		(layer "In13.Cu")
		(net "M_H_CPU1_SB_DQ<9>")
	)
	(segment
		(start 172.547026 -292.960298)
		(end 172.971968 -292.535356)
		(width 0.14478)
		(layer "In13.Cu")
		(net "M_H_CPU1_SB_DQ<9>")
	)
	(segment
		(start 147.827238 -279.745694)
		(end 150.575772 -279.745694)
		(width 0.14478)
		(layer "In13.Cu")
		(net "M_H_CPU1_SB_DQ<9>")
	)
	(segment
		(start 174.094648 -292.390576)
		(end 174.239428 -292.535356)
		(width 0.14478)
		(layer "In13.Cu")
		(net "M_H_CPU1_SB_DQ<9>")
	)
	(segment
		(start 145.330926 -279.928066)
		(end 147.18919 -279.928066)
		(width 0.0889)
		(layer "In13.Cu")
		(net "M_H_CPU1_SB_DQ<9>")
	)
	(segment
		(start 166.336472 -292.559994)
		(end 166.786052 -292.110414)
		(width 0.14478)
		(layer "In13.Cu")
		(net "M_H_CPU1_SB_DQ<9>")
	)
	(segment
		(start 172.971968 -292.535356)
		(end 173.398688 -292.535356)
		(width 0.14478)
		(layer "In13.Cu")
		(net "M_H_CPU1_SB_DQ<9>")
	)
	(segment
		(start 174.094648 -291.954458)
		(end 174.094648 -292.390576)
		(width 0.14478)
		(layer "In13.Cu")
		(net "M_H_CPU1_SB_DQ<9>")
	)
	(segment
		(start 173.543468 -292.390576)
		(end 173.543468 -291.954458)
		(width 0.14478)
		(layer "In13.Cu")
		(net "M_H_CPU1_SB_DQ<9>")
	)
	(segment
		(start 140.453364 -280.083768)
		(end 140.461746 -280.078942)
		(width 0.0889)
		(layer "In13.Cu")
		(net "M_H_CPU1_SB_DQ<9>")
	)
	(segment
		(start 163.33724 -292.960298)
		(end 164.776658 -292.960298)
		(width 0.14478)
		(layer "In13.Cu")
		(net "M_H_CPU1_SB_DQ<9>")
	)
	(segment
		(start 173.949868 -291.809678)
		(end 174.094648 -291.954458)
		(width 0.14478)
		(layer "In13.Cu")
		(net "M_H_CPU1_SB_DQ<9>")
	)
	(segment
		(start 137.267696 -280.078942)
		(end 137.276078 -280.083768)
		(width 0.0889)
		(layer "In13.Cu")
		(net "M_H_CPU1_SB_DQ<9>")
	)
	(segment
		(start 147.18919 -279.928066)
		(end 147.371562 -279.745694)
		(width 0.0889)
		(layer "In13.Cu")
		(net "M_H_CPU1_SB_DQ<9>")
	)
	(segment
		(start 174.790608 -291.809678)
		(end 175.052228 -291.809678)
		(width 0.14478)
		(layer "In13.Cu")
		(net "M_H_CPU1_SB_DQ<9>")
	)
	(segment
		(start 170.617896 -292.960298)
		(end 172.547026 -292.960298)
		(width 0.14478)
		(layer "In13.Cu")
		(net "M_H_CPU1_SB_DQ<9>")
	)
	(segment
		(start 175.341788 -292.535356)
		(end 176.072038 -292.535356)
		(width 0.14478)
		(layer "In13.Cu")
		(net "M_H_CPU1_SB_DQ<9>")
	)
	(segment
		(start 174.645828 -291.954458)
		(end 174.790608 -291.809678)
		(width 0.14478)
		(layer "In13.Cu")
		(net "M_H_CPU1_SB_DQ<9>")
	)
	(segment
		(start 174.645828 -292.390576)
		(end 174.645828 -291.954458)
		(width 0.14478)
		(layer "In13.Cu")
		(net "M_H_CPU1_SB_DQ<9>")
	)
	(segment
		(start 169.768012 -292.110414)
		(end 170.617896 -292.960298)
		(width 0.14478)
		(layer "In13.Cu")
		(net "M_H_CPU1_SB_DQ<9>")
	)
	(segment
		(start 165.176962 -292.559994)
		(end 166.336472 -292.559994)
		(width 0.14478)
		(layer "In13.Cu")
		(net "M_H_CPU1_SB_DQ<9>")
	)
	(segment
		(start 174.501048 -292.535356)
		(end 174.645828 -292.390576)
		(width 0.14478)
		(layer "In13.Cu")
		(net "M_H_CPU1_SB_DQ<9>")
	)
	(segment
		(start 160.35147 -289.974528)
		(end 163.33724 -292.960298)
		(width 0.14478)
		(layer "In13.Cu")
		(net "M_H_CPU1_SB_DQ<9>")
	)
	(segment
		(start 175.052228 -291.809678)
		(end 175.197008 -291.954458)
		(width 0.14478)
		(layer "In13.Cu")
		(net "M_H_CPU1_SB_DQ<9>")
	)
	(segment
		(start 173.543468 -291.954458)
		(end 173.688248 -291.809678)
		(width 0.14478)
		(layer "In13.Cu")
		(net "M_H_CPU1_SB_DQ<9>")
	)
	(segment
		(start 138.20775 -280.078942)
		(end 138.216132 -280.083768)
		(width 0.0889)
		(layer "In13.Cu")
		(net "M_H_CPU1_SB_DQ<9>")
	)
	(segment
		(start 134.634732 -279.756362)
		(end 134.788656 -280.021792)
		(width 0.0889)
		(layer "In13.Cu")
		(net "M_H_CPU1_SB_DQ<9>")
	)
	(segment
		(start 145.135092 -280.07691)
		(end 145.250662 -279.96134)
		(width 0.0889)
		(layer "In13.Cu")
		(net "M_H_CPU1_SB_DQ<9>")
	)
	(segment
		(start 144.213326 -280.083768)
		(end 144.221708 -280.078942)
		(width 0.0889)
		(layer "In13.Cu")
		(net "M_H_CPU1_SB_DQ<9>")
	)
	(segment
		(start 141.393418 -280.083768)
		(end 141.4018 -280.078942)
		(width 0.0889)
		(layer "In13.Cu")
		(net "M_H_CPU1_SB_DQ<9>")
	)
	(segment
		(start 141.967712 -280.078942)
		(end 141.976094 -280.083768)
		(width 0.0889)
		(layer "In13.Cu")
		(net "M_H_CPU1_SB_DQ<9>")
	)
	(segment
		(start 160.35147 -289.521392)
		(end 160.35147 -289.974528)
		(width 0.14478)
		(layer "In13.Cu")
		(net "M_H_CPU1_SB_DQ<9>")
	)
	(segment
		(start 173.398688 -292.535356)
		(end 173.543468 -292.390576)
		(width 0.14478)
		(layer "In13.Cu")
		(net "M_H_CPU1_SB_DQ<9>")
	)
	(segment
		(start 173.688248 -291.809678)
		(end 173.949868 -291.809678)
		(width 0.14478)
		(layer "In13.Cu")
		(net "M_H_CPU1_SB_DQ<9>")
	)
	(segment
		(start 147.371562 -279.745694)
		(end 147.827238 -279.745694)
		(width 0.0889)
		(layer "In13.Cu")
		(net "M_H_CPU1_SB_DQ<9>")
	)
	(segment
		(start 174.239428 -292.535356)
		(end 174.501048 -292.535356)
		(width 0.14478)
		(layer "In13.Cu")
		(net "M_H_CPU1_SB_DQ<9>")
	)
	(segment
		(start 166.786052 -292.110414)
		(end 169.768012 -292.110414)
		(width 0.14478)
		(layer "In13.Cu")
		(net "M_H_CPU1_SB_DQ<9>")
	)
	(segment
		(start 144.221708 -280.078942)
		(end 144.232122 -280.072846)
		(width 0.0889)
		(layer "In13.Cu")
		(net "M_H_CPU1_SB_DQ<9>")
	)
	(segment
		(start 175.197008 -291.954458)
		(end 175.197008 -292.390576)
		(width 0.14478)
		(layer "In13.Cu")
		(net "M_H_CPU1_SB_DQ<9>")
	)
	(segment
		(start 144.787366 -280.078942)
		(end 144.795748 -280.083768)
		(width 0.0889)
		(layer "In13.Cu")
		(net "M_H_CPU1_SB_DQ<9>")
	)
	(segment
		(start 175.197008 -292.390576)
		(end 175.341788 -292.535356)
		(width 0.14478)
		(layer "In13.Cu")
		(net "M_H_CPU1_SB_DQ<9>")
	)
	(segment
		(start 164.776658 -292.960298)
		(end 165.176962 -292.559994)
		(width 0.14478)
		(layer "In13.Cu")
		(net "M_H_CPU1_SB_DQ<9>")
	)
	(arc
		(start 145.250662 -279.96134)
		(mid 145.287473 -279.93668)
		(end 145.330926 -279.928066)
		(width 0.0889)
		(layer "In13.Cu")
		(net "M_H_CPU1_SB_DQ<9>")
	)
	(arc
		(start 141.4018 -280.078942)
		(mid 141.684756 -280.002765)
		(end 141.967712 -280.078942)
		(width 0.0889)
		(layer "In13.Cu")
		(net "M_H_CPU1_SB_DQ<9>")
	)
	(arc
		(start 137.276078 -280.083768)
		(mid 137.459586 -280.129262)
		(end 137.641838 -280.078942)
		(width 0.0889)
		(layer "In13.Cu")
		(net "M_H_CPU1_SB_DQ<9>")
	)
	(arc
		(start 143.281654 -280.078942)
		(mid 143.56461 -280.002765)
		(end 143.847566 -280.078942)
		(width 0.0889)
		(layer "In13.Cu")
		(net "M_H_CPU1_SB_DQ<9>")
	)
	(arc
		(start 140.461746 -280.078942)
		(mid 140.744702 -280.002765)
		(end 141.027658 -280.078942)
		(width 0.0889)
		(layer "In13.Cu")
		(net "M_H_CPU1_SB_DQ<9>")
	)
	(arc
		(start 136.701784 -280.078942)
		(mid 136.98474 -280.002765)
		(end 137.267696 -280.078942)
		(width 0.0889)
		(layer "In13.Cu")
		(net "M_H_CPU1_SB_DQ<9>")
	)
	(arc
		(start 143.847566 -280.078942)
		(mid 144.029817 -280.129292)
		(end 144.213326 -280.083768)
		(width 0.0889)
		(layer "In13.Cu")
		(net "M_H_CPU1_SB_DQ<9>")
	)
	(arc
		(start 138.581892 -280.078942)
		(mid 138.864848 -280.002765)
		(end 139.147804 -280.078942)
		(width 0.0889)
		(layer "In13.Cu")
		(net "M_H_CPU1_SB_DQ<9>")
	)
	(arc
		(start 137.641838 -280.078942)
		(mid 137.924794 -280.002765)
		(end 138.20775 -280.078942)
		(width 0.0889)
		(layer "In13.Cu")
		(net "M_H_CPU1_SB_DQ<9>")
	)
	(arc
		(start 139.147804 -280.078942)
		(mid 139.334748 -280.129197)
		(end 139.521692 -280.078942)
		(width 0.0889)
		(layer "In13.Cu")
		(net "M_H_CPU1_SB_DQ<9>")
	)
	(arc
		(start 145.057368 -280.12009)
		(mid 145.099278 -280.103987)
		(end 145.135092 -280.07691)
		(width 0.0889)
		(layer "In13.Cu")
		(net "M_H_CPU1_SB_DQ<9>")
	)
	(arc
		(start 141.027658 -280.078942)
		(mid 141.209909 -280.129292)
		(end 141.393418 -280.083768)
		(width 0.0889)
		(layer "In13.Cu")
		(net "M_H_CPU1_SB_DQ<9>")
	)
	(arc
		(start 142.907766 -280.078942)
		(mid 143.09471 -280.129197)
		(end 143.281654 -280.078942)
		(width 0.0889)
		(layer "In13.Cu")
		(net "M_H_CPU1_SB_DQ<9>")
	)
	(arc
		(start 135.76173 -280.078942)
		(mid 136.044686 -280.002765)
		(end 136.327642 -280.078942)
		(width 0.0889)
		(layer "In13.Cu")
		(net "M_H_CPU1_SB_DQ<9>")
	)
	(arc
		(start 142.341854 -280.078942)
		(mid 142.62481 -280.002765)
		(end 142.907766 -280.078942)
		(width 0.0889)
		(layer "In13.Cu")
		(net "M_H_CPU1_SB_DQ<9>")
	)
	(arc
		(start 144.795748 -280.083768)
		(mid 144.923236 -280.125869)
		(end 145.057368 -280.12009)
		(width 0.0889)
		(layer "In13.Cu")
		(net "M_H_CPU1_SB_DQ<9>")
	)
	(arc
		(start 140.087604 -280.078942)
		(mid 140.269855 -280.129292)
		(end 140.453364 -280.083768)
		(width 0.0889)
		(layer "In13.Cu")
		(net "M_H_CPU1_SB_DQ<9>")
	)
	(arc
		(start 144.232122 -280.072846)
		(mid 144.510554 -280.002748)
		(end 144.787366 -280.078942)
		(width 0.0889)
		(layer "In13.Cu")
		(net "M_H_CPU1_SB_DQ<9>")
	)
	(arc
		(start 139.521692 -280.078942)
		(mid 139.804648 -280.002765)
		(end 140.087604 -280.078942)
		(width 0.0889)
		(layer "In13.Cu")
		(net "M_H_CPU1_SB_DQ<9>")
	)
	(arc
		(start 136.327642 -280.078942)
		(mid 136.509893 -280.129292)
		(end 136.693402 -280.083768)
		(width 0.0889)
		(layer "In13.Cu")
		(net "M_H_CPU1_SB_DQ<9>")
	)
	(arc
		(start 134.884668 -280.047192)
		(mid 135.139876 -280.003715)
		(end 135.387588 -280.078942)
		(width 0.0889)
		(layer "In13.Cu")
		(net "M_H_CPU1_SB_DQ<9>")
	)
	(arc
		(start 135.387588 -280.078942)
		(mid 135.569839 -280.129292)
		(end 135.753348 -280.083768)
		(width 0.0889)
		(layer "In13.Cu")
		(net "M_H_CPU1_SB_DQ<9>")
	)
	(arc
		(start 138.216132 -280.083768)
		(mid 138.39964 -280.129262)
		(end 138.581892 -280.078942)
		(width 0.0889)
		(layer "In13.Cu")
		(net "M_H_CPU1_SB_DQ<9>")
	)
	(arc
		(start 141.976094 -280.083768)
		(mid 142.159602 -280.129262)
		(end 142.341854 -280.078942)
		(width 0.0889)
		(layer "In13.Cu")
		(net "M_H_CPU1_SB_DQ<9>")
	)
	(segment
		(start 135.577834 -278.680418)
		(end 136.044686 -278.946356)
		(width 0.10668)
		(layer "F.Cu")
		(net "M_H_CPU1_SB_DQ<8>")
	)
	(segment
		(start 173.634654 -291.124894)
		(end 173.489874 -291.269674)
		(width 0.14478)
		(layer "In13.Cu")
		(net "M_H_CPU1_SB_DQ<8>")
	)
	(segment
		(start 146.243294 -278.652224)
		(end 145.619724 -279.275794)
		(width 0.0889)
		(layer "In13.Cu")
		(net "M_H_CPU1_SB_DQ<8>")
	)
	(segment
		(start 173.634654 -290.228528)
		(end 173.634654 -291.124894)
		(width 0.14478)
		(layer "In13.Cu")
		(net "M_H_CPU1_SB_DQ<8>")
	)
	(segment
		(start 172.296582 -291.260276)
		(end 170.52036 -291.260276)
		(width 0.14478)
		(layer "In13.Cu")
		(net "M_H_CPU1_SB_DQ<8>")
	)
	(segment
		(start 175.706278 -290.835334)
		(end 175.127158 -290.256214)
		(width 0.14478)
		(layer "In13.Cu")
		(net "M_H_CPU1_SB_DQ<8>")
	)
	(segment
		(start 174.737014 -291.124894)
		(end 174.592234 -291.269674)
		(width 0.14478)
		(layer "In13.Cu")
		(net "M_H_CPU1_SB_DQ<8>")
	)
	(segment
		(start 136.29513 -279.237186)
		(end 136.198864 -279.211786)
		(width 0.0889)
		(layer "In13.Cu")
		(net "M_H_CPU1_SB_DQ<8>")
	)
	(segment
		(start 176.072038 -290.835334)
		(end 175.706278 -290.835334)
		(width 0.14478)
		(layer "In13.Cu")
		(net "M_H_CPU1_SB_DQ<8>")
	)
	(segment
		(start 142.811754 -279.268936)
		(end 142.803372 -279.273762)
		(width 0.0889)
		(layer "In13.Cu")
		(net "M_H_CPU1_SB_DQ<8>")
	)
	(segment
		(start 173.083474 -291.124894)
		(end 173.083474 -290.980114)
		(width 0.14478)
		(layer "In13.Cu")
		(net "M_H_CPU1_SB_DQ<8>")
	)
	(segment
		(start 173.489874 -291.269674)
		(end 173.228254 -291.269674)
		(width 0.14478)
		(layer "In13.Cu")
		(net "M_H_CPU1_SB_DQ<8>")
	)
	(segment
		(start 172.721524 -290.835334)
		(end 172.296582 -291.260276)
		(width 0.14478)
		(layer "In13.Cu")
		(net "M_H_CPU1_SB_DQ<8>")
	)
	(segment
		(start 151.209248 -278.61133)
		(end 147.985226 -278.61133)
		(width 0.14478)
		(layer "In13.Cu")
		(net "M_H_CPU1_SB_DQ<8>")
	)
	(segment
		(start 169.931334 -290.67125)
		(end 166.832026 -290.67125)
		(width 0.14478)
		(layer "In13.Cu")
		(net "M_H_CPU1_SB_DQ<8>")
	)
	(segment
		(start 173.228254 -291.269674)
		(end 173.083474 -291.124894)
		(width 0.14478)
		(layer "In13.Cu")
		(net "M_H_CPU1_SB_DQ<8>")
	)
	(segment
		(start 166.832026 -290.67125)
		(end 166.243 -291.260276)
		(width 0.14478)
		(layer "In13.Cu")
		(net "M_H_CPU1_SB_DQ<8>")
	)
	(segment
		(start 139.626086 -279.273762)
		(end 139.617704 -279.268936)
		(width 0.0889)
		(layer "In13.Cu")
		(net "M_H_CPU1_SB_DQ<8>")
	)
	(segment
		(start 174.041054 -290.083748)
		(end 173.779434 -290.083748)
		(width 0.14478)
		(layer "In13.Cu")
		(net "M_H_CPU1_SB_DQ<8>")
	)
	(segment
		(start 174.330614 -291.269674)
		(end 174.185834 -291.124894)
		(width 0.14478)
		(layer "In13.Cu")
		(net "M_H_CPU1_SB_DQ<8>")
	)
	(segment
		(start 166.243 -291.260276)
		(end 163.858194 -291.260276)
		(width 0.14478)
		(layer "In13.Cu")
		(net "M_H_CPU1_SB_DQ<8>")
	)
	(segment
		(start 163.858194 -291.260276)
		(end 151.209248 -278.61133)
		(width 0.14478)
		(layer "In13.Cu")
		(net "M_H_CPU1_SB_DQ<8>")
	)
	(segment
		(start 144.317466 -279.268936)
		(end 144.307052 -279.26284)
		(width 0.0889)
		(layer "In13.Cu")
		(net "M_H_CPU1_SB_DQ<8>")
	)
	(segment
		(start 139.044426 -279.273254)
		(end 139.04341 -279.273762)
		(width 0.0889)
		(layer "In13.Cu")
		(net "M_H_CPU1_SB_DQ<8>")
	)
	(segment
		(start 175.127158 -290.256214)
		(end 174.881794 -290.256214)
		(width 0.14478)
		(layer "In13.Cu")
		(net "M_H_CPU1_SB_DQ<8>")
	)
	(segment
		(start 173.779434 -290.083748)
		(end 173.634654 -290.228528)
		(width 0.14478)
		(layer "In13.Cu")
		(net "M_H_CPU1_SB_DQ<8>")
	)
	(segment
		(start 144.701768 -279.26284)
		(end 144.691354 -279.268936)
		(width 0.0889)
		(layer "In13.Cu")
		(net "M_H_CPU1_SB_DQ<8>")
	)
	(segment
		(start 147.21205 -278.652224)
		(end 146.243294 -278.652224)
		(width 0.0889)
		(layer "In13.Cu")
		(net "M_H_CPU1_SB_DQ<8>")
	)
	(segment
		(start 138.111738 -279.268936)
		(end 138.103356 -279.273762)
		(width 0.0889)
		(layer "In13.Cu")
		(net "M_H_CPU1_SB_DQ<8>")
	)
	(segment
		(start 140.56614 -279.273762)
		(end 140.557758 -279.268936)
		(width 0.0889)
		(layer "In13.Cu")
		(net "M_H_CPU1_SB_DQ<8>")
	)
	(segment
		(start 147.985226 -278.61133)
		(end 147.252944 -278.61133)
		(width 0.0889)
		(layer "In13.Cu")
		(net "M_H_CPU1_SB_DQ<8>")
	)
	(segment
		(start 174.881794 -290.256214)
		(end 174.737014 -290.400994)
		(width 0.14478)
		(layer "In13.Cu")
		(net "M_H_CPU1_SB_DQ<8>")
	)
	(segment
		(start 170.52036 -291.260276)
		(end 169.931334 -290.67125)
		(width 0.14478)
		(layer "In13.Cu")
		(net "M_H_CPU1_SB_DQ<8>")
	)
	(segment
		(start 174.185834 -290.228528)
		(end 174.041054 -290.083748)
		(width 0.14478)
		(layer "In13.Cu")
		(net "M_H_CPU1_SB_DQ<8>")
	)
	(segment
		(start 174.185834 -291.124894)
		(end 174.185834 -290.228528)
		(width 0.14478)
		(layer "In13.Cu")
		(net "M_H_CPU1_SB_DQ<8>")
	)
	(segment
		(start 174.592234 -291.269674)
		(end 174.330614 -291.269674)
		(width 0.14478)
		(layer "In13.Cu")
		(net "M_H_CPU1_SB_DQ<8>")
	)
	(segment
		(start 172.938694 -290.835334)
		(end 172.721524 -290.835334)
		(width 0.14478)
		(layer "In13.Cu")
		(net "M_H_CPU1_SB_DQ<8>")
	)
	(segment
		(start 143.386048 -279.273762)
		(end 143.377666 -279.268936)
		(width 0.0889)
		(layer "In13.Cu")
		(net "M_H_CPU1_SB_DQ<8>")
	)
	(segment
		(start 139.051792 -279.268936)
		(end 139.044426 -279.273254)
		(width 0.0889)
		(layer "In13.Cu")
		(net "M_H_CPU1_SB_DQ<8>")
	)
	(segment
		(start 147.252944 -278.61133)
		(end 147.21205 -278.652224)
		(width 0.0889)
		(layer "In13.Cu")
		(net "M_H_CPU1_SB_DQ<8>")
	)
	(segment
		(start 173.083474 -290.980114)
		(end 172.938694 -290.835334)
		(width 0.14478)
		(layer "In13.Cu")
		(net "M_H_CPU1_SB_DQ<8>")
	)
	(segment
		(start 136.198864 -279.211786)
		(end 136.044686 -278.946356)
		(width 0.0889)
		(layer "In13.Cu")
		(net "M_H_CPU1_SB_DQ<8>")
	)
	(segment
		(start 174.737014 -290.400994)
		(end 174.737014 -291.124894)
		(width 0.14478)
		(layer "In13.Cu")
		(net "M_H_CPU1_SB_DQ<8>")
	)
	(arc
		(start 139.617704 -279.268936)
		(mid 139.334748 -279.192759)
		(end 139.051792 -279.268936)
		(width 0.0889)
		(layer "In13.Cu")
		(net "M_H_CPU1_SB_DQ<8>")
	)
	(arc
		(start 142.437612 -279.268936)
		(mid 142.154656 -279.192759)
		(end 141.8717 -279.268936)
		(width 0.0889)
		(layer "In13.Cu")
		(net "M_H_CPU1_SB_DQ<8>")
	)
	(arc
		(start 139.04341 -279.273762)
		(mid 138.859902 -279.319256)
		(end 138.67765 -279.268936)
		(width 0.0889)
		(layer "In13.Cu")
		(net "M_H_CPU1_SB_DQ<8>")
	)
	(arc
		(start 142.803372 -279.273762)
		(mid 142.619864 -279.319256)
		(end 142.437612 -279.268936)
		(width 0.0889)
		(layer "In13.Cu")
		(net "M_H_CPU1_SB_DQ<8>")
	)
	(arc
		(start 143.377666 -279.268936)
		(mid 143.09471 -279.192759)
		(end 142.811754 -279.268936)
		(width 0.0889)
		(layer "In13.Cu")
		(net "M_H_CPU1_SB_DQ<8>")
	)
	(arc
		(start 141.497812 -279.268936)
		(mid 141.214856 -279.192759)
		(end 140.9319 -279.268936)
		(width 0.0889)
		(layer "In13.Cu")
		(net "M_H_CPU1_SB_DQ<8>")
	)
	(arc
		(start 141.8717 -279.268936)
		(mid 141.684756 -279.319191)
		(end 141.497812 -279.268936)
		(width 0.0889)
		(layer "In13.Cu")
		(net "M_H_CPU1_SB_DQ<8>")
	)
	(arc
		(start 137.171684 -279.268936)
		(mid 136.98474 -279.319191)
		(end 136.797796 -279.268936)
		(width 0.0889)
		(layer "In13.Cu")
		(net "M_H_CPU1_SB_DQ<8>")
	)
	(arc
		(start 137.737596 -279.268936)
		(mid 137.45464 -279.192759)
		(end 137.171684 -279.268936)
		(width 0.0889)
		(layer "In13.Cu")
		(net "M_H_CPU1_SB_DQ<8>")
	)
	(arc
		(start 145.619724 -279.275794)
		(mid 145.437723 -279.319327)
		(end 145.25752 -279.268936)
		(width 0.0889)
		(layer "In13.Cu")
		(net "M_H_CPU1_SB_DQ<8>")
	)
	(arc
		(start 145.25752 -279.268936)
		(mid 144.980453 -279.192665)
		(end 144.701768 -279.26284)
		(width 0.0889)
		(layer "In13.Cu")
		(net "M_H_CPU1_SB_DQ<8>")
	)
	(arc
		(start 144.691354 -279.268936)
		(mid 144.50441 -279.319191)
		(end 144.317466 -279.268936)
		(width 0.0889)
		(layer "In13.Cu")
		(net "M_H_CPU1_SB_DQ<8>")
	)
	(arc
		(start 136.797796 -279.268936)
		(mid 136.5502 -279.193758)
		(end 136.29513 -279.237186)
		(width 0.0889)
		(layer "In13.Cu")
		(net "M_H_CPU1_SB_DQ<8>")
	)
	(arc
		(start 138.67765 -279.268936)
		(mid 138.394694 -279.192759)
		(end 138.111738 -279.268936)
		(width 0.0889)
		(layer "In13.Cu")
		(net "M_H_CPU1_SB_DQ<8>")
	)
	(arc
		(start 139.991846 -279.268936)
		(mid 139.809595 -279.319286)
		(end 139.626086 -279.273762)
		(width 0.0889)
		(layer "In13.Cu")
		(net "M_H_CPU1_SB_DQ<8>")
	)
	(arc
		(start 138.103356 -279.273762)
		(mid 137.919848 -279.319256)
		(end 137.737596 -279.268936)
		(width 0.0889)
		(layer "In13.Cu")
		(net "M_H_CPU1_SB_DQ<8>")
	)
	(arc
		(start 140.557758 -279.268936)
		(mid 140.274802 -279.192759)
		(end 139.991846 -279.268936)
		(width 0.0889)
		(layer "In13.Cu")
		(net "M_H_CPU1_SB_DQ<8>")
	)
	(arc
		(start 140.9319 -279.268936)
		(mid 140.749649 -279.319286)
		(end 140.56614 -279.273762)
		(width 0.0889)
		(layer "In13.Cu")
		(net "M_H_CPU1_SB_DQ<8>")
	)
	(arc
		(start 144.307052 -279.26284)
		(mid 144.02862 -279.192742)
		(end 143.751808 -279.268936)
		(width 0.0889)
		(layer "In13.Cu")
		(net "M_H_CPU1_SB_DQ<8>")
	)
	(arc
		(start 143.751808 -279.268936)
		(mid 143.569557 -279.319286)
		(end 143.386048 -279.273762)
		(width 0.0889)
		(layer "In13.Cu")
		(net "M_H_CPU1_SB_DQ<8>")
	)
	(segment
		(start 134.63778 -278.680418)
		(end 135.104632 -278.946356)
		(width 0.10668)
		(layer "F.Cu")
		(net "M_H_CPU1_SB_DQ<7>")
	)
	(segment
		(start 134.950708 -278.680926)
		(end 135.104632 -278.946356)
		(width 0.0889)
		(layer "In13.Cu")
		(net "M_H_CPU1_SB_DQ<7>")
	)
	(segment
		(start 170.183556 -289.812984)
		(end 170.102276 -290.009072)
		(width 0.14478)
		(layer "In13.Cu")
		(net "M_H_CPU1_SB_DQ<7>")
	)
	(segment
		(start 143.386048 -278.61895)
		(end 143.377666 -278.623776)
		(width 0.0889)
		(layer "In13.Cu")
		(net "M_H_CPU1_SB_DQ<7>")
	)
	(segment
		(start 171.625768 -290.010088)
		(end 171.480988 -290.154868)
		(width 0.14478)
		(layer "In13.Cu")
		(net "M_H_CPU1_SB_DQ<7>")
	)
	(segment
		(start 164.463984 -290.27501)
		(end 164.463984 -290.275264)
		(width 0.14478)
		(layer "In13.Cu")
		(net "M_H_CPU1_SB_DQ<7>")
	)
	(segment
		(start 147.22856 -278.236172)
		(end 145.956782 -278.236172)
		(width 0.0889)
		(layer "In13.Cu")
		(net "M_H_CPU1_SB_DQ<7>")
	)
	(segment
		(start 171.074588 -290.709096)
		(end 170.929808 -290.564316)
		(width 0.14478)
		(layer "In13.Cu")
		(net "M_H_CPU1_SB_DQ<7>")
	)
	(segment
		(start 165.949122 -289.922712)
		(end 165.949122 -290.127436)
		(width 0.14478)
		(layer "In13.Cu")
		(net "M_H_CPU1_SB_DQ<7>")
	)
	(segment
		(start 148.019516 -278.05507)
		(end 147.409662 -278.05507)
		(width 0.0889)
		(layer "In13.Cu")
		(net "M_H_CPU1_SB_DQ<7>")
	)
	(segment
		(start 170.372532 -289.734752)
		(end 170.183556 -289.812984)
		(width 0.14478)
		(layer "In13.Cu")
		(net "M_H_CPU1_SB_DQ<7>")
	)
	(segment
		(start 166.76497 -289.95878)
		(end 166.560246 -289.95878)
		(width 0.14478)
		(layer "In13.Cu")
		(net "M_H_CPU1_SB_DQ<7>")
	)
	(segment
		(start 171.97197 -289.98545)
		(end 171.947332 -290.010088)
		(width 0.14478)
		(layer "In13.Cu")
		(net "M_H_CPU1_SB_DQ<7>")
	)
	(segment
		(start 140.56614 -278.61895)
		(end 140.557758 -278.623776)
		(width 0.0889)
		(layer "In13.Cu")
		(net "M_H_CPU1_SB_DQ<7>")
	)
	(segment
		(start 144.692624 -278.623776)
		(end 144.684242 -278.61895)
		(width 0.0889)
		(layer "In13.Cu")
		(net "M_H_CPU1_SB_DQ<7>")
	)
	(segment
		(start 165.949122 -290.127436)
		(end 166.170356 -290.34867)
		(width 0.14478)
		(layer "In13.Cu")
		(net "M_H_CPU1_SB_DQ<7>")
	)
	(segment
		(start 171.480988 -290.564316)
		(end 171.336208 -290.709096)
		(width 0.14478)
		(layer "In13.Cu")
		(net "M_H_CPU1_SB_DQ<7>")
	)
	(segment
		(start 166.042086 -290.681664)
		(end 165.150546 -290.681664)
		(width 0.14478)
		(layer "In13.Cu")
		(net "M_H_CPU1_SB_DQ<7>")
	)
	(segment
		(start 169.596054 -289.413188)
		(end 169.1894 -289.244786)
		(width 0.14478)
		(layer "In13.Cu")
		(net "M_H_CPU1_SB_DQ<7>")
	)
	(segment
		(start 166.560246 -289.95878)
		(end 166.339012 -289.737546)
		(width 0.14478)
		(layer "In13.Cu")
		(net "M_H_CPU1_SB_DQ<7>")
	)
	(segment
		(start 169.593006 -289.797998)
		(end 169.674286 -289.60191)
		(width 0.14478)
		(layer "In13.Cu")
		(net "M_H_CPU1_SB_DQ<7>")
	)
	(segment
		(start 166.134288 -289.737546)
		(end 165.949122 -289.922712)
		(width 0.14478)
		(layer "In13.Cu")
		(net "M_H_CPU1_SB_DQ<7>")
	)
	(segment
		(start 168.150032 -289.244786)
		(end 167.478964 -289.244786)
		(width 0.14478)
		(layer "In13.Cu")
		(net "M_H_CPU1_SB_DQ<7>")
	)
	(segment
		(start 147.409662 -278.05507)
		(end 147.22856 -278.236172)
		(width 0.0889)
		(layer "In13.Cu")
		(net "M_H_CPU1_SB_DQ<7>")
	)
	(segment
		(start 139.617958 -278.623776)
		(end 139.617704 -278.623776)
		(width 0.0889)
		(layer "In13.Cu")
		(net "M_H_CPU1_SB_DQ<7>")
	)
	(segment
		(start 164.328602 -290.410646)
		(end 163.78809 -290.410646)
		(width 0.14478)
		(layer "In13.Cu")
		(net "M_H_CPU1_SB_DQ<7>")
	)
	(segment
		(start 151.432514 -278.05507)
		(end 148.019516 -278.05507)
		(width 0.14478)
		(layer "In13.Cu")
		(net "M_H_CPU1_SB_DQ<7>")
	)
	(segment
		(start 143.762222 -278.629872)
		(end 143.751808 -278.623776)
		(width 0.0889)
		(layer "In13.Cu")
		(net "M_H_CPU1_SB_DQ<7>")
	)
	(segment
		(start 165.150546 -290.681664)
		(end 165.015164 -290.546282)
		(width 0.14478)
		(layer "In13.Cu")
		(net "M_H_CPU1_SB_DQ<7>")
	)
	(segment
		(start 165.015164 -290.546282)
		(end 165.015164 -290.27501)
		(width 0.14478)
		(layer "In13.Cu")
		(net "M_H_CPU1_SB_DQ<7>")
	)
	(segment
		(start 170.929808 -290.564316)
		(end 170.929808 -290.154868)
		(width 0.14478)
		(layer "In13.Cu")
		(net "M_H_CPU1_SB_DQ<7>")
	)
	(segment
		(start 166.170356 -290.34867)
		(end 166.170356 -290.553394)
		(width 0.14478)
		(layer "In13.Cu")
		(net "M_H_CPU1_SB_DQ<7>")
	)
	(segment
		(start 170.929808 -290.154868)
		(end 170.606974 -289.832034)
		(width 0.14478)
		(layer "In13.Cu")
		(net "M_H_CPU1_SB_DQ<7>")
	)
	(segment
		(start 169.9133 -290.087304)
		(end 169.671238 -289.986974)
		(width 0.14478)
		(layer "In13.Cu")
		(net "M_H_CPU1_SB_DQ<7>")
	)
	(segment
		(start 169.671238 -289.986974)
		(end 169.593006 -289.797998)
		(width 0.14478)
		(layer "In13.Cu")
		(net "M_H_CPU1_SB_DQ<7>")
	)
	(segment
		(start 166.339012 -289.737546)
		(end 166.134288 -289.737546)
		(width 0.14478)
		(layer "In13.Cu")
		(net "M_H_CPU1_SB_DQ<7>")
	)
	(segment
		(start 135.866124 -278.61895)
		(end 135.857742 -278.623776)
		(width 0.0889)
		(layer "In13.Cu")
		(net "M_H_CPU1_SB_DQ<7>")
	)
	(segment
		(start 171.336208 -290.709096)
		(end 171.074588 -290.709096)
		(width 0.14478)
		(layer "In13.Cu")
		(net "M_H_CPU1_SB_DQ<7>")
	)
	(segment
		(start 168.428924 -289.523678)
		(end 168.150032 -289.244786)
		(width 0.14478)
		(layer "In13.Cu")
		(net "M_H_CPU1_SB_DQ<7>")
	)
	(segment
		(start 163.78809 -290.410646)
		(end 151.432514 -278.05507)
		(width 0.14478)
		(layer "In13.Cu")
		(net "M_H_CPU1_SB_DQ<7>")
	)
	(segment
		(start 164.879782 -290.139628)
		(end 164.599366 -290.139628)
		(width 0.14478)
		(layer "In13.Cu")
		(net "M_H_CPU1_SB_DQ<7>")
	)
	(segment
		(start 166.170356 -290.553394)
		(end 166.042086 -290.681664)
		(width 0.14478)
		(layer "In13.Cu")
		(net "M_H_CPU1_SB_DQ<7>")
	)
	(segment
		(start 165.015164 -290.27501)
		(end 164.879782 -290.139628)
		(width 0.14478)
		(layer "In13.Cu")
		(net "M_H_CPU1_SB_DQ<7>")
	)
	(segment
		(start 167.478964 -289.244786)
		(end 166.76497 -289.95878)
		(width 0.14478)
		(layer "In13.Cu")
		(net "M_H_CPU1_SB_DQ<7>")
	)
	(segment
		(start 138.111738 -278.623776)
		(end 138.103356 -278.61895)
		(width 0.0889)
		(layer "In13.Cu")
		(net "M_H_CPU1_SB_DQ<7>")
	)
	(segment
		(start 171.480988 -290.154868)
		(end 171.480988 -290.564316)
		(width 0.14478)
		(layer "In13.Cu")
		(net "M_H_CPU1_SB_DQ<7>")
	)
	(segment
		(start 169.674286 -289.60191)
		(end 169.596054 -289.413188)
		(width 0.14478)
		(layer "In13.Cu")
		(net "M_H_CPU1_SB_DQ<7>")
	)
	(segment
		(start 168.980104 -289.244786)
		(end 168.701212 -289.523678)
		(width 0.14478)
		(layer "In13.Cu")
		(net "M_H_CPU1_SB_DQ<7>")
	)
	(segment
		(start 134.97306 -278.597614)
		(end 134.950708 -278.680926)
		(width 0.0889)
		(layer "In13.Cu")
		(net "M_H_CPU1_SB_DQ<7>")
	)
	(segment
		(start 169.1894 -289.244786)
		(end 168.980104 -289.244786)
		(width 0.14478)
		(layer "In13.Cu")
		(net "M_H_CPU1_SB_DQ<7>")
	)
	(segment
		(start 168.701212 -289.523678)
		(end 168.428924 -289.523678)
		(width 0.14478)
		(layer "In13.Cu")
		(net "M_H_CPU1_SB_DQ<7>")
	)
	(segment
		(start 145.956782 -278.236172)
		(end 145.25244 -278.627332)
		(width 0.0889)
		(layer "In13.Cu")
		(net "M_H_CPU1_SB_DQ<7>")
	)
	(segment
		(start 139.051792 -278.623776)
		(end 139.04341 -278.61895)
		(width 0.0889)
		(layer "In13.Cu")
		(net "M_H_CPU1_SB_DQ<7>")
	)
	(segment
		(start 142.811754 -278.623776)
		(end 142.803372 -278.61895)
		(width 0.0889)
		(layer "In13.Cu")
		(net "M_H_CPU1_SB_DQ<7>")
	)
	(segment
		(start 171.947332 -290.010088)
		(end 171.625768 -290.010088)
		(width 0.14478)
		(layer "In13.Cu")
		(net "M_H_CPU1_SB_DQ<7>")
	)
	(segment
		(start 164.463984 -290.275264)
		(end 164.328602 -290.410646)
		(width 0.14478)
		(layer "In13.Cu")
		(net "M_H_CPU1_SB_DQ<7>")
	)
	(segment
		(start 170.102276 -290.009072)
		(end 169.9133 -290.087304)
		(width 0.14478)
		(layer "In13.Cu")
		(net "M_H_CPU1_SB_DQ<7>")
	)
	(segment
		(start 164.599366 -290.139628)
		(end 164.463984 -290.27501)
		(width 0.14478)
		(layer "In13.Cu")
		(net "M_H_CPU1_SB_DQ<7>")
	)
	(segment
		(start 170.606974 -289.832034)
		(end 170.372532 -289.734752)
		(width 0.14478)
		(layer "In13.Cu")
		(net "M_H_CPU1_SB_DQ<7>")
	)
	(arc
		(start 136.797796 -278.623776)
		(mid 136.51484 -278.699953)
		(end 136.231884 -278.623776)
		(width 0.0889)
		(layer "In13.Cu")
		(net "M_H_CPU1_SB_DQ<7>")
	)
	(arc
		(start 139.04341 -278.61895)
		(mid 138.859902 -278.573456)
		(end 138.67765 -278.623776)
		(width 0.0889)
		(layer "In13.Cu")
		(net "M_H_CPU1_SB_DQ<7>")
	)
	(arc
		(start 135.857742 -278.623776)
		(mid 135.574786 -278.699953)
		(end 135.29183 -278.623776)
		(width 0.0889)
		(layer "In13.Cu")
		(net "M_H_CPU1_SB_DQ<7>")
	)
	(arc
		(start 145.25244 -278.627332)
		(mid 144.972051 -278.700001)
		(end 144.692624 -278.623776)
		(width 0.0889)
		(layer "In13.Cu")
		(net "M_H_CPU1_SB_DQ<7>")
	)
	(arc
		(start 143.751808 -278.623776)
		(mid 143.569557 -278.573426)
		(end 143.386048 -278.61895)
		(width 0.0889)
		(layer "In13.Cu")
		(net "M_H_CPU1_SB_DQ<7>")
	)
	(arc
		(start 139.617704 -278.623776)
		(mid 139.334748 -278.699953)
		(end 139.051792 -278.623776)
		(width 0.0889)
		(layer "In13.Cu")
		(net "M_H_CPU1_SB_DQ<7>")
	)
	(arc
		(start 135.29183 -278.623776)
		(mid 135.135392 -278.574805)
		(end 134.97306 -278.597614)
		(width 0.0889)
		(layer "In13.Cu")
		(net "M_H_CPU1_SB_DQ<7>")
	)
	(arc
		(start 137.171684 -278.623776)
		(mid 136.98474 -278.573521)
		(end 136.797796 -278.623776)
		(width 0.0889)
		(layer "In13.Cu")
		(net "M_H_CPU1_SB_DQ<7>")
	)
	(arc
		(start 144.317974 -278.623776)
		(mid 144.040907 -278.700047)
		(end 143.762222 -278.629872)
		(width 0.0889)
		(layer "In13.Cu")
		(net "M_H_CPU1_SB_DQ<7>")
	)
	(arc
		(start 138.103356 -278.61895)
		(mid 137.919848 -278.573456)
		(end 137.737596 -278.623776)
		(width 0.0889)
		(layer "In13.Cu")
		(net "M_H_CPU1_SB_DQ<7>")
	)
	(arc
		(start 143.377666 -278.623776)
		(mid 143.09471 -278.699953)
		(end 142.811754 -278.623776)
		(width 0.0889)
		(layer "In13.Cu")
		(net "M_H_CPU1_SB_DQ<7>")
	)
	(arc
		(start 142.437612 -278.623776)
		(mid 142.154656 -278.699953)
		(end 141.8717 -278.623776)
		(width 0.0889)
		(layer "In13.Cu")
		(net "M_H_CPU1_SB_DQ<7>")
	)
	(arc
		(start 141.8717 -278.623776)
		(mid 141.684756 -278.573521)
		(end 141.497812 -278.623776)
		(width 0.0889)
		(layer "In13.Cu")
		(net "M_H_CPU1_SB_DQ<7>")
	)
	(arc
		(start 142.803372 -278.61895)
		(mid 142.619864 -278.573456)
		(end 142.437612 -278.623776)
		(width 0.0889)
		(layer "In13.Cu")
		(net "M_H_CPU1_SB_DQ<7>")
	)
	(arc
		(start 140.9319 -278.623776)
		(mid 140.749649 -278.573426)
		(end 140.56614 -278.61895)
		(width 0.0889)
		(layer "In13.Cu")
		(net "M_H_CPU1_SB_DQ<7>")
	)
	(arc
		(start 137.737596 -278.623776)
		(mid 137.45464 -278.699953)
		(end 137.171684 -278.623776)
		(width 0.0889)
		(layer "In13.Cu")
		(net "M_H_CPU1_SB_DQ<7>")
	)
	(arc
		(start 141.497812 -278.623776)
		(mid 141.214856 -278.699953)
		(end 140.9319 -278.623776)
		(width 0.0889)
		(layer "In13.Cu")
		(net "M_H_CPU1_SB_DQ<7>")
	)
	(arc
		(start 144.684242 -278.61895)
		(mid 144.50048 -278.573334)
		(end 144.317974 -278.623776)
		(width 0.0889)
		(layer "In13.Cu")
		(net "M_H_CPU1_SB_DQ<7>")
	)
	(arc
		(start 138.67765 -278.623776)
		(mid 138.394694 -278.699953)
		(end 138.111738 -278.623776)
		(width 0.0889)
		(layer "In13.Cu")
		(net "M_H_CPU1_SB_DQ<7>")
	)
	(arc
		(start 139.991846 -278.623776)
		(mid 139.804902 -278.573452)
		(end 139.617958 -278.623776)
		(width 0.0889)
		(layer "In13.Cu")
		(net "M_H_CPU1_SB_DQ<7>")
	)
	(arc
		(start 140.557758 -278.623776)
		(mid 140.274802 -278.699953)
		(end 139.991846 -278.623776)
		(width 0.0889)
		(layer "In13.Cu")
		(net "M_H_CPU1_SB_DQ<7>")
	)
	(arc
		(start 136.231884 -278.623776)
		(mid 136.049633 -278.573426)
		(end 135.866124 -278.61895)
		(width 0.0889)
		(layer "In13.Cu")
		(net "M_H_CPU1_SB_DQ<7>")
	)
	(segment
		(start 136.047988 -277.870412)
		(end 136.51484 -278.13635)
		(width 0.10668)
		(layer "F.Cu")
		(net "M_H_CPU1_SB_DQ<6>")
	)
	(segment
		(start 146.037046 -277.318724)
		(end 146.037046 -277.395686)
		(width 0.0889)
		(layer "In13.Cu")
		(net "M_H_CPU1_SB_DQ<6>")
	)
	(segment
		(start 162.846258 -287.991804)
		(end 163.02228 -287.815782)
		(width 0.14478)
		(layer "In13.Cu")
		(net "M_H_CPU1_SB_DQ<6>")
	)
	(segment
		(start 161.471864 -286.822134)
		(end 151.79548 -277.14575)
		(width 0.14478)
		(layer "In13.Cu")
		(net "M_H_CPU1_SB_DQ<6>")
	)
	(segment
		(start 140.461746 -277.81377)
		(end 140.453364 -277.808944)
		(width 0.0889)
		(layer "In13.Cu")
		(net "M_H_CPU1_SB_DQ<6>")
	)
	(segment
		(start 170.95343 -287.825434)
		(end 170.80865 -287.970214)
		(width 0.14478)
		(layer "In13.Cu")
		(net "M_H_CPU1_SB_DQ<6>")
	)
	(segment
		(start 162.057334 -286.646112)
		(end 161.85261 -286.646112)
		(width 0.14478)
		(layer "In13.Cu")
		(net "M_H_CPU1_SB_DQ<6>")
	)
	(segment
		(start 170.25747 -287.970214)
		(end 170.11269 -287.825434)
		(width 0.14478)
		(layer "In13.Cu")
		(net "M_H_CPU1_SB_DQ<6>")
	)
	(segment
		(start 168.163494 -287.47085)
		(end 167.901874 -287.47085)
		(width 0.14478)
		(layer "In13.Cu")
		(net "M_H_CPU1_SB_DQ<6>")
	)
	(segment
		(start 169.56151 -288.285428)
		(end 169.361358 -288.285428)
		(width 0.14478)
		(layer "In13.Cu")
		(net "M_H_CPU1_SB_DQ<6>")
	)
	(segment
		(start 136.360662 -277.87092)
		(end 136.51484 -278.13635)
		(width 0.0889)
		(layer "In13.Cu")
		(net "M_H_CPU1_SB_DQ<6>")
	)
	(segment
		(start 136.701784 -277.81377)
		(end 136.693402 -277.808944)
		(width 0.0889)
		(layer "In13.Cu")
		(net "M_H_CPU1_SB_DQ<6>")
	)
	(segment
		(start 171.21505 -287.825434)
		(end 170.95343 -287.825434)
		(width 0.14478)
		(layer "In13.Cu")
		(net "M_H_CPU1_SB_DQ<6>")
	)
	(segment
		(start 163.948618 -288.483294)
		(end 163.948618 -288.565844)
		(width 0.14478)
		(layer "In13.Cu")
		(net "M_H_CPU1_SB_DQ<6>")
	)
	(segment
		(start 162.066478 -287.212024)
		(end 162.2425 -287.036002)
		(width 0.14478)
		(layer "In13.Cu")
		(net "M_H_CPU1_SB_DQ<6>")
	)
	(segment
		(start 165.602158 -288.565844)
		(end 165.602158 -288.483294)
		(width 0.14478)
		(layer "In13.Cu")
		(net "M_H_CPU1_SB_DQ<6>")
	)
	(segment
		(start 167.901874 -287.47085)
		(end 167.757094 -287.61563)
		(width 0.14478)
		(layer "In13.Cu")
		(net "M_H_CPU1_SB_DQ<6>")
	)
	(segment
		(start 138.216132 -277.808944)
		(end 138.20775 -277.81377)
		(width 0.0889)
		(layer "In13.Cu")
		(net "M_H_CPU1_SB_DQ<6>")
	)
	(segment
		(start 165.746938 -288.710624)
		(end 165.602158 -288.565844)
		(width 0.14478)
		(layer "In13.Cu")
		(net "M_H_CPU1_SB_DQ<6>")
	)
	(segment
		(start 166.150036 -288.710624)
		(end 165.746938 -288.710624)
		(width 0.14478)
		(layer "In13.Cu")
		(net "M_H_CPU1_SB_DQ<6>")
	)
	(segment
		(start 151.79548 -277.14575)
		(end 147.998434 -277.14575)
		(width 0.14478)
		(layer "In13.Cu")
		(net "M_H_CPU1_SB_DQ<6>")
	)
	(segment
		(start 165.050978 -288.565844)
		(end 164.906198 -288.710624)
		(width 0.14478)
		(layer "In13.Cu")
		(net "M_H_CPU1_SB_DQ<6>")
	)
	(segment
		(start 168.453054 -287.860486)
		(end 168.308274 -287.715706)
		(width 0.14478)
		(layer "In13.Cu")
		(net "M_H_CPU1_SB_DQ<6>")
	)
	(segment
		(start 165.050978 -288.483294)
		(end 165.050978 -288.565844)
		(width 0.14478)
		(layer "In13.Cu")
		(net "M_H_CPU1_SB_DQ<6>")
	)
	(segment
		(start 163.948618 -288.565844)
		(end 163.803838 -288.710624)
		(width 0.14478)
		(layer "In13.Cu")
		(net "M_H_CPU1_SB_DQ<6>")
	)
	(segment
		(start 170.80865 -288.600642)
		(end 170.66387 -288.745422)
		(width 0.14478)
		(layer "In13.Cu")
		(net "M_H_CPU1_SB_DQ<6>")
	)
	(segment
		(start 170.66387 -288.745422)
		(end 170.40225 -288.745422)
		(width 0.14478)
		(layer "In13.Cu")
		(net "M_H_CPU1_SB_DQ<6>")
	)
	(segment
		(start 169.70629 -288.140648)
		(end 169.56151 -288.285428)
		(width 0.14478)
		(layer "In13.Cu")
		(net "M_H_CPU1_SB_DQ<6>")
	)
	(segment
		(start 164.499798 -288.483294)
		(end 164.355018 -288.338514)
		(width 0.14478)
		(layer "In13.Cu")
		(net "M_H_CPU1_SB_DQ<6>")
	)
	(segment
		(start 165.195758 -288.338514)
		(end 165.050978 -288.483294)
		(width 0.14478)
		(layer "In13.Cu")
		(net "M_H_CPU1_SB_DQ<6>")
	)
	(segment
		(start 165.457378 -288.338514)
		(end 165.195758 -288.338514)
		(width 0.14478)
		(layer "In13.Cu")
		(net "M_H_CPU1_SB_DQ<6>")
	)
	(segment
		(start 161.676588 -286.822134)
		(end 161.471864 -286.822134)
		(width 0.14478)
		(layer "In13.Cu")
		(net "M_H_CPU1_SB_DQ<6>")
	)
	(segment
		(start 161.85261 -286.646112)
		(end 161.676588 -286.822134)
		(width 0.14478)
		(layer "In13.Cu")
		(net "M_H_CPU1_SB_DQ<6>")
	)
	(segment
		(start 163.803838 -288.710624)
		(end 163.360354 -288.710624)
		(width 0.14478)
		(layer "In13.Cu")
		(net "M_H_CPU1_SB_DQ<6>")
	)
	(segment
		(start 144.220946 -277.814024)
		(end 144.20088 -277.802594)
		(width 0.0889)
		(layer "In13.Cu")
		(net "M_H_CPU1_SB_DQ<6>")
	)
	(segment
		(start 167.000174 -287.860486)
		(end 166.150036 -288.710624)
		(width 0.14478)
		(layer "In13.Cu")
		(net "M_H_CPU1_SB_DQ<6>")
	)
	(segment
		(start 169.85107 -287.825434)
		(end 169.70629 -287.970214)
		(width 0.14478)
		(layer "In13.Cu")
		(net "M_H_CPU1_SB_DQ<6>")
	)
	(segment
		(start 170.80865 -287.970214)
		(end 170.80865 -288.600642)
		(width 0.14478)
		(layer "In13.Cu")
		(net "M_H_CPU1_SB_DQ<6>")
	)
	(segment
		(start 170.25747 -288.600642)
		(end 170.25747 -287.970214)
		(width 0.14478)
		(layer "In13.Cu")
		(net "M_H_CPU1_SB_DQ<6>")
	)
	(segment
		(start 169.361358 -288.285428)
		(end 168.936416 -287.860486)
		(width 0.14478)
		(layer "In13.Cu")
		(net "M_H_CPU1_SB_DQ<6>")
	)
	(segment
		(start 170.11269 -287.825434)
		(end 169.85107 -287.825434)
		(width 0.14478)
		(layer "In13.Cu")
		(net "M_H_CPU1_SB_DQ<6>")
	)
	(segment
		(start 171.97197 -288.285428)
		(end 171.50461 -288.285428)
		(width 0.14478)
		(layer "In13.Cu")
		(net "M_H_CPU1_SB_DQ<6>")
	)
	(segment
		(start 164.355018 -288.338514)
		(end 164.093398 -288.338514)
		(width 0.14478)
		(layer "In13.Cu")
		(net "M_H_CPU1_SB_DQ<6>")
	)
	(segment
		(start 171.50461 -288.285428)
		(end 171.35983 -288.140648)
		(width 0.14478)
		(layer "In13.Cu")
		(net "M_H_CPU1_SB_DQ<6>")
	)
	(segment
		(start 164.906198 -288.710624)
		(end 164.644578 -288.710624)
		(width 0.14478)
		(layer "In13.Cu")
		(net "M_H_CPU1_SB_DQ<6>")
	)
	(segment
		(start 162.63239 -287.425892)
		(end 162.456368 -287.601914)
		(width 0.14478)
		(layer "In13.Cu")
		(net "M_H_CPU1_SB_DQ<6>")
	)
	(segment
		(start 167.612314 -287.860486)
		(end 167.000174 -287.860486)
		(width 0.14478)
		(layer "In13.Cu")
		(net "M_H_CPU1_SB_DQ<6>")
	)
	(segment
		(start 170.40225 -288.745422)
		(end 170.25747 -288.600642)
		(width 0.14478)
		(layer "In13.Cu")
		(net "M_H_CPU1_SB_DQ<6>")
	)
	(segment
		(start 141.4018 -277.81377)
		(end 141.393418 -277.808944)
		(width 0.0889)
		(layer "In13.Cu")
		(net "M_H_CPU1_SB_DQ<6>")
	)
	(segment
		(start 167.757094 -287.715706)
		(end 167.612314 -287.860486)
		(width 0.14478)
		(layer "In13.Cu")
		(net "M_H_CPU1_SB_DQ<6>")
	)
	(segment
		(start 171.35983 -287.970214)
		(end 171.21505 -287.825434)
		(width 0.14478)
		(layer "In13.Cu")
		(net "M_H_CPU1_SB_DQ<6>")
	)
	(segment
		(start 162.2425 -286.831278)
		(end 162.057334 -286.646112)
		(width 0.14478)
		(layer "In13.Cu")
		(net "M_H_CPU1_SB_DQ<6>")
	)
	(segment
		(start 163.360354 -288.710624)
		(end 162.846258 -288.196528)
		(width 0.14478)
		(layer "In13.Cu")
		(net "M_H_CPU1_SB_DQ<6>")
	)
	(segment
		(start 163.02228 -287.815782)
		(end 163.02228 -287.611058)
		(width 0.14478)
		(layer "In13.Cu")
		(net "M_H_CPU1_SB_DQ<6>")
	)
	(segment
		(start 163.02228 -287.611058)
		(end 162.837114 -287.425892)
		(width 0.14478)
		(layer "In13.Cu")
		(net "M_H_CPU1_SB_DQ<6>")
	)
	(segment
		(start 162.846258 -288.196528)
		(end 162.846258 -287.991804)
		(width 0.14478)
		(layer "In13.Cu")
		(net "M_H_CPU1_SB_DQ<6>")
	)
	(segment
		(start 168.308274 -287.715706)
		(end 168.308274 -287.61563)
		(width 0.14478)
		(layer "In13.Cu")
		(net "M_H_CPU1_SB_DQ<6>")
	)
	(segment
		(start 171.35983 -288.140648)
		(end 171.35983 -287.970214)
		(width 0.14478)
		(layer "In13.Cu")
		(net "M_H_CPU1_SB_DQ<6>")
	)
	(segment
		(start 162.066478 -287.416748)
		(end 162.066478 -287.212024)
		(width 0.14478)
		(layer "In13.Cu")
		(net "M_H_CPU1_SB_DQ<6>")
	)
	(segment
		(start 136.383014 -277.787608)
		(end 136.360662 -277.87092)
		(width 0.0889)
		(layer "In13.Cu")
		(net "M_H_CPU1_SB_DQ<6>")
	)
	(segment
		(start 162.456368 -287.601914)
		(end 162.251644 -287.601914)
		(width 0.14478)
		(layer "In13.Cu")
		(net "M_H_CPU1_SB_DQ<6>")
	)
	(segment
		(start 162.837114 -287.425892)
		(end 162.63239 -287.425892)
		(width 0.14478)
		(layer "In13.Cu")
		(net "M_H_CPU1_SB_DQ<6>")
	)
	(segment
		(start 137.276078 -277.808944)
		(end 137.267696 -277.81377)
		(width 0.0889)
		(layer "In13.Cu")
		(net "M_H_CPU1_SB_DQ<6>")
	)
	(segment
		(start 164.499798 -288.565844)
		(end 164.499798 -288.483294)
		(width 0.14478)
		(layer "In13.Cu")
		(net "M_H_CPU1_SB_DQ<6>")
	)
	(segment
		(start 168.936416 -287.860486)
		(end 168.453054 -287.860486)
		(width 0.14478)
		(layer "In13.Cu")
		(net "M_H_CPU1_SB_DQ<6>")
	)
	(segment
		(start 162.251644 -287.601914)
		(end 162.066478 -287.416748)
		(width 0.14478)
		(layer "In13.Cu")
		(net "M_H_CPU1_SB_DQ<6>")
	)
	(segment
		(start 162.2425 -287.036002)
		(end 162.2425 -286.831278)
		(width 0.14478)
		(layer "In13.Cu")
		(net "M_H_CPU1_SB_DQ<6>")
	)
	(segment
		(start 147.998434 -277.14575)
		(end 146.21002 -277.14575)
		(width 0.0889)
		(layer "In13.Cu")
		(net "M_H_CPU1_SB_DQ<6>")
	)
	(segment
		(start 141.976094 -277.808944)
		(end 141.967712 -277.81377)
		(width 0.0889)
		(layer "In13.Cu")
		(net "M_H_CPU1_SB_DQ<6>")
	)
	(segment
		(start 165.602158 -288.483294)
		(end 165.457378 -288.338514)
		(width 0.14478)
		(layer "In13.Cu")
		(net "M_H_CPU1_SB_DQ<6>")
	)
	(segment
		(start 144.242536 -277.82647)
		(end 144.220946 -277.814024)
		(width 0.0889)
		(layer "In13.Cu")
		(net "M_H_CPU1_SB_DQ<6>")
	)
	(segment
		(start 164.644578 -288.710624)
		(end 164.499798 -288.565844)
		(width 0.14478)
		(layer "In13.Cu")
		(net "M_H_CPU1_SB_DQ<6>")
	)
	(segment
		(start 169.70629 -287.970214)
		(end 169.70629 -288.140648)
		(width 0.14478)
		(layer "In13.Cu")
		(net "M_H_CPU1_SB_DQ<6>")
	)
	(segment
		(start 164.093398 -288.338514)
		(end 163.948618 -288.483294)
		(width 0.14478)
		(layer "In13.Cu")
		(net "M_H_CPU1_SB_DQ<6>")
	)
	(segment
		(start 146.21002 -277.14575)
		(end 146.037046 -277.318724)
		(width 0.0889)
		(layer "In13.Cu")
		(net "M_H_CPU1_SB_DQ<6>")
	)
	(segment
		(start 167.757094 -287.61563)
		(end 167.757094 -287.715706)
		(width 0.14478)
		(layer "In13.Cu")
		(net "M_H_CPU1_SB_DQ<6>")
	)
	(segment
		(start 168.308274 -287.61563)
		(end 168.163494 -287.47085)
		(width 0.14478)
		(layer "In13.Cu")
		(net "M_H_CPU1_SB_DQ<6>")
	)
	(segment
		(start 144.80413 -277.802848)
		(end 144.785334 -277.81377)
		(width 0.0889)
		(layer "In13.Cu")
		(net "M_H_CPU1_SB_DQ<6>")
	)
	(arc
		(start 146.037046 -277.395686)
		(mid 145.987102 -277.5771)
		(end 145.878804 -277.730966)
		(width 0.0889)
		(layer "In13.Cu")
		(net "M_H_CPU1_SB_DQ<6>")
	)
	(arc
		(start 143.281654 -277.81377)
		(mid 143.09471 -277.763515)
		(end 142.907766 -277.81377)
		(width 0.0889)
		(layer "In13.Cu")
		(net "M_H_CPU1_SB_DQ<6>")
	)
	(arc
		(start 141.027658 -277.81377)
		(mid 140.744702 -277.889947)
		(end 140.461746 -277.81377)
		(width 0.0889)
		(layer "In13.Cu")
		(net "M_H_CPU1_SB_DQ<6>")
	)
	(arc
		(start 139.521692 -277.81377)
		(mid 139.334748 -277.763515)
		(end 139.147804 -277.81377)
		(width 0.0889)
		(layer "In13.Cu")
		(net "M_H_CPU1_SB_DQ<6>")
	)
	(arc
		(start 142.341854 -277.81377)
		(mid 142.159603 -277.76342)
		(end 141.976094 -277.808944)
		(width 0.0889)
		(layer "In13.Cu")
		(net "M_H_CPU1_SB_DQ<6>")
	)
	(arc
		(start 138.581892 -277.81377)
		(mid 138.399641 -277.76342)
		(end 138.216132 -277.808944)
		(width 0.0889)
		(layer "In13.Cu")
		(net "M_H_CPU1_SB_DQ<6>")
	)
	(arc
		(start 141.393418 -277.808944)
		(mid 141.20991 -277.76345)
		(end 141.027658 -277.81377)
		(width 0.0889)
		(layer "In13.Cu")
		(net "M_H_CPU1_SB_DQ<6>")
	)
	(arc
		(start 138.20775 -277.81377)
		(mid 137.924794 -277.889947)
		(end 137.641838 -277.81377)
		(width 0.0889)
		(layer "In13.Cu")
		(net "M_H_CPU1_SB_DQ<6>")
	)
	(arc
		(start 137.267696 -277.81377)
		(mid 136.98474 -277.889947)
		(end 136.701784 -277.81377)
		(width 0.0889)
		(layer "In13.Cu")
		(net "M_H_CPU1_SB_DQ<6>")
	)
	(arc
		(start 143.847566 -277.81377)
		(mid 143.56461 -277.889947)
		(end 143.281654 -277.81377)
		(width 0.0889)
		(layer "In13.Cu")
		(net "M_H_CPU1_SB_DQ<6>")
	)
	(arc
		(start 140.087604 -277.81377)
		(mid 139.804648 -277.889947)
		(end 139.521692 -277.81377)
		(width 0.0889)
		(layer "In13.Cu")
		(net "M_H_CPU1_SB_DQ<6>")
	)
	(arc
		(start 145.444718 -277.897082)
		(mid 145.297517 -277.872782)
		(end 145.160492 -277.81377)
		(width 0.0889)
		(layer "In13.Cu")
		(net "M_H_CPU1_SB_DQ<6>")
	)
	(arc
		(start 145.160492 -277.81377)
		(mid 144.983701 -277.763051)
		(end 144.80413 -277.802848)
		(width 0.0889)
		(layer "In13.Cu")
		(net "M_H_CPU1_SB_DQ<6>")
	)
	(arc
		(start 139.147804 -277.81377)
		(mid 138.864848 -277.889947)
		(end 138.581892 -277.81377)
		(width 0.0889)
		(layer "In13.Cu")
		(net "M_H_CPU1_SB_DQ<6>")
	)
	(arc
		(start 142.907766 -277.81377)
		(mid 142.62481 -277.889947)
		(end 142.341854 -277.81377)
		(width 0.0889)
		(layer "In13.Cu")
		(net "M_H_CPU1_SB_DQ<6>")
	)
	(arc
		(start 144.785334 -277.81377)
		(mid 144.515565 -277.889793)
		(end 144.242536 -277.82647)
		(width 0.0889)
		(layer "In13.Cu")
		(net "M_H_CPU1_SB_DQ<6>")
	)
	(arc
		(start 141.967712 -277.81377)
		(mid 141.684756 -277.889947)
		(end 141.4018 -277.81377)
		(width 0.0889)
		(layer "In13.Cu")
		(net "M_H_CPU1_SB_DQ<6>")
	)
	(arc
		(start 144.20088 -277.802594)
		(mid 144.022802 -277.76361)
		(end 143.847566 -277.81377)
		(width 0.0889)
		(layer "In13.Cu")
		(net "M_H_CPU1_SB_DQ<6>")
	)
	(arc
		(start 140.453364 -277.808944)
		(mid 140.269856 -277.76345)
		(end 140.087604 -277.81377)
		(width 0.0889)
		(layer "In13.Cu")
		(net "M_H_CPU1_SB_DQ<6>")
	)
	(arc
		(start 145.878804 -277.730966)
		(mid 145.678929 -277.858896)
		(end 145.444718 -277.897082)
		(width 0.0889)
		(layer "In13.Cu")
		(net "M_H_CPU1_SB_DQ<6>")
	)
	(arc
		(start 137.641838 -277.81377)
		(mid 137.459587 -277.76342)
		(end 137.276078 -277.808944)
		(width 0.0889)
		(layer "In13.Cu")
		(net "M_H_CPU1_SB_DQ<6>")
	)
	(arc
		(start 136.693402 -277.808944)
		(mid 136.540532 -277.764303)
		(end 136.383014 -277.787608)
		(width 0.0889)
		(layer "In13.Cu")
		(net "M_H_CPU1_SB_DQ<6>")
	)
	(segment
		(start 134.16788 -277.870412)
		(end 134.634732 -278.13635)
		(width 0.10668)
		(layer "F.Cu")
		(net "M_H_CPU1_SB_DQ<5>")
	)
	(segment
		(start 171.126912 -289.560508)
		(end 169.0751 -288.710624)
		(width 0.14478)
		(layer "In13.Cu")
		(net "M_H_CPU1_SB_DQ<5>")
	)
	(segment
		(start 147.92833 -277.60041)
		(end 147.362672 -277.60041)
		(width 0.0889)
		(layer "In13.Cu")
		(net "M_H_CPU1_SB_DQ<5>")
	)
	(segment
		(start 141.4018 -278.45893)
		(end 141.393418 -278.463756)
		(width 0.0889)
		(layer "In13.Cu")
		(net "M_H_CPU1_SB_DQ<5>")
	)
	(segment
		(start 169.0751 -288.710624)
		(end 167.438324 -288.710624)
		(width 0.14478)
		(layer "In13.Cu")
		(net "M_H_CPU1_SB_DQ<5>")
	)
	(segment
		(start 144.788382 -278.45893)
		(end 144.777968 -278.452834)
		(width 0.0889)
		(layer "In13.Cu")
		(net "M_H_CPU1_SB_DQ<5>")
	)
	(segment
		(start 135.76173 -278.45893)
		(end 135.753348 -278.463756)
		(width 0.0889)
		(layer "In13.Cu")
		(net "M_H_CPU1_SB_DQ<5>")
	)
	(segment
		(start 141.976094 -278.463756)
		(end 141.967712 -278.45893)
		(width 0.0889)
		(layer "In13.Cu")
		(net "M_H_CPU1_SB_DQ<5>")
	)
	(segment
		(start 134.788656 -278.40178)
		(end 134.634732 -278.13635)
		(width 0.0889)
		(layer "In13.Cu")
		(net "M_H_CPU1_SB_DQ<5>")
	)
	(segment
		(start 146.763486 -277.511764)
		(end 145.146014 -278.468074)
		(width 0.0889)
		(layer "In13.Cu")
		(net "M_H_CPU1_SB_DQ<5>")
	)
	(segment
		(start 147.362672 -277.60041)
		(end 147.274026 -277.511764)
		(width 0.0889)
		(layer "In13.Cu")
		(net "M_H_CPU1_SB_DQ<5>")
	)
	(segment
		(start 143.855948 -278.463756)
		(end 143.847566 -278.45893)
		(width 0.0889)
		(layer "In13.Cu")
		(net "M_H_CPU1_SB_DQ<5>")
	)
	(segment
		(start 151.614124 -277.60041)
		(end 147.92833 -277.60041)
		(width 0.14478)
		(layer "In13.Cu")
		(net "M_H_CPU1_SB_DQ<5>")
	)
	(segment
		(start 140.461746 -278.45893)
		(end 140.453364 -278.463756)
		(width 0.0889)
		(layer "In13.Cu")
		(net "M_H_CPU1_SB_DQ<5>")
	)
	(segment
		(start 165.386512 -289.560508)
		(end 163.574222 -289.560508)
		(width 0.14478)
		(layer "In13.Cu")
		(net "M_H_CPU1_SB_DQ<5>")
	)
	(segment
		(start 147.274026 -277.511764)
		(end 146.763486 -277.511764)
		(width 0.0889)
		(layer "In13.Cu")
		(net "M_H_CPU1_SB_DQ<5>")
	)
	(segment
		(start 137.276078 -278.463756)
		(end 137.267696 -278.45893)
		(width 0.0889)
		(layer "In13.Cu")
		(net "M_H_CPU1_SB_DQ<5>")
	)
	(segment
		(start 136.701784 -278.45893)
		(end 136.693402 -278.463756)
		(width 0.0889)
		(layer "In13.Cu")
		(net "M_H_CPU1_SB_DQ<5>")
	)
	(segment
		(start 172.945298 -289.560508)
		(end 171.126912 -289.560508)
		(width 0.14478)
		(layer "In13.Cu")
		(net "M_H_CPU1_SB_DQ<5>")
	)
	(segment
		(start 163.574222 -289.560508)
		(end 151.614124 -277.60041)
		(width 0.14478)
		(layer "In13.Cu")
		(net "M_H_CPU1_SB_DQ<5>")
	)
	(segment
		(start 167.438324 -288.710624)
		(end 165.386512 -289.560508)
		(width 0.14478)
		(layer "In13.Cu")
		(net "M_H_CPU1_SB_DQ<5>")
	)
	(segment
		(start 134.884668 -278.42718)
		(end 134.788656 -278.40178)
		(width 0.0889)
		(layer "In13.Cu")
		(net "M_H_CPU1_SB_DQ<5>")
	)
	(segment
		(start 138.216132 -278.463756)
		(end 138.20775 -278.45893)
		(width 0.0889)
		(layer "In13.Cu")
		(net "M_H_CPU1_SB_DQ<5>")
	)
	(segment
		(start 176.072038 -289.135312)
		(end 172.945298 -289.560508)
		(width 0.14478)
		(layer "In13.Cu")
		(net "M_H_CPU1_SB_DQ<5>")
	)
	(arc
		(start 143.847566 -278.45893)
		(mid 143.56461 -278.382753)
		(end 143.281654 -278.45893)
		(width 0.0889)
		(layer "In13.Cu")
		(net "M_H_CPU1_SB_DQ<5>")
	)
	(arc
		(start 141.967712 -278.45893)
		(mid 141.684756 -278.382753)
		(end 141.4018 -278.45893)
		(width 0.0889)
		(layer "In13.Cu")
		(net "M_H_CPU1_SB_DQ<5>")
	)
	(arc
		(start 137.267696 -278.45893)
		(mid 136.98474 -278.382753)
		(end 136.701784 -278.45893)
		(width 0.0889)
		(layer "In13.Cu")
		(net "M_H_CPU1_SB_DQ<5>")
	)
	(arc
		(start 145.146014 -278.468074)
		(mid 144.966032 -278.509174)
		(end 144.788382 -278.45893)
		(width 0.0889)
		(layer "In13.Cu")
		(net "M_H_CPU1_SB_DQ<5>")
	)
	(arc
		(start 144.777968 -278.452834)
		(mid 144.499282 -278.382614)
		(end 144.222216 -278.45893)
		(width 0.0889)
		(layer "In13.Cu")
		(net "M_H_CPU1_SB_DQ<5>")
	)
	(arc
		(start 135.387588 -278.45893)
		(mid 135.139875 -278.38371)
		(end 134.884668 -278.42718)
		(width 0.0889)
		(layer "In13.Cu")
		(net "M_H_CPU1_SB_DQ<5>")
	)
	(arc
		(start 136.327642 -278.45893)
		(mid 136.044686 -278.382753)
		(end 135.76173 -278.45893)
		(width 0.0889)
		(layer "In13.Cu")
		(net "M_H_CPU1_SB_DQ<5>")
	)
	(arc
		(start 143.281654 -278.45893)
		(mid 143.09471 -278.509185)
		(end 142.907766 -278.45893)
		(width 0.0889)
		(layer "In13.Cu")
		(net "M_H_CPU1_SB_DQ<5>")
	)
	(arc
		(start 136.693402 -278.463756)
		(mid 136.509894 -278.50925)
		(end 136.327642 -278.45893)
		(width 0.0889)
		(layer "In13.Cu")
		(net "M_H_CPU1_SB_DQ<5>")
	)
	(arc
		(start 142.907766 -278.45893)
		(mid 142.62481 -278.382753)
		(end 142.341854 -278.45893)
		(width 0.0889)
		(layer "In13.Cu")
		(net "M_H_CPU1_SB_DQ<5>")
	)
	(arc
		(start 141.027658 -278.45893)
		(mid 140.744702 -278.382753)
		(end 140.461746 -278.45893)
		(width 0.0889)
		(layer "In13.Cu")
		(net "M_H_CPU1_SB_DQ<5>")
	)
	(arc
		(start 138.581892 -278.45893)
		(mid 138.399641 -278.50928)
		(end 138.216132 -278.463756)
		(width 0.0889)
		(layer "In13.Cu")
		(net "M_H_CPU1_SB_DQ<5>")
	)
	(arc
		(start 139.147804 -278.45893)
		(mid 138.864848 -278.382753)
		(end 138.581892 -278.45893)
		(width 0.0889)
		(layer "In13.Cu")
		(net "M_H_CPU1_SB_DQ<5>")
	)
	(arc
		(start 140.453364 -278.463756)
		(mid 140.269856 -278.50925)
		(end 140.087604 -278.45893)
		(width 0.0889)
		(layer "In13.Cu")
		(net "M_H_CPU1_SB_DQ<5>")
	)
	(arc
		(start 138.20775 -278.45893)
		(mid 137.924794 -278.382753)
		(end 137.641838 -278.45893)
		(width 0.0889)
		(layer "In13.Cu")
		(net "M_H_CPU1_SB_DQ<5>")
	)
	(arc
		(start 144.222216 -278.45893)
		(mid 144.039711 -278.509407)
		(end 143.855948 -278.463756)
		(width 0.0889)
		(layer "In13.Cu")
		(net "M_H_CPU1_SB_DQ<5>")
	)
	(arc
		(start 142.341854 -278.45893)
		(mid 142.159603 -278.50928)
		(end 141.976094 -278.463756)
		(width 0.0889)
		(layer "In13.Cu")
		(net "M_H_CPU1_SB_DQ<5>")
	)
	(arc
		(start 137.641838 -278.45893)
		(mid 137.459587 -278.50928)
		(end 137.276078 -278.463756)
		(width 0.0889)
		(layer "In13.Cu")
		(net "M_H_CPU1_SB_DQ<5>")
	)
	(arc
		(start 141.393418 -278.463756)
		(mid 141.20991 -278.50925)
		(end 141.027658 -278.45893)
		(width 0.0889)
		(layer "In13.Cu")
		(net "M_H_CPU1_SB_DQ<5>")
	)
	(arc
		(start 140.087604 -278.45893)
		(mid 139.804648 -278.382753)
		(end 139.521692 -278.45893)
		(width 0.0889)
		(layer "In13.Cu")
		(net "M_H_CPU1_SB_DQ<5>")
	)
	(arc
		(start 135.753348 -278.463756)
		(mid 135.56984 -278.50925)
		(end 135.387588 -278.45893)
		(width 0.0889)
		(layer "In13.Cu")
		(net "M_H_CPU1_SB_DQ<5>")
	)
	(arc
		(start 139.521692 -278.45893)
		(mid 139.334748 -278.509185)
		(end 139.147804 -278.45893)
		(width 0.0889)
		(layer "In13.Cu")
		(net "M_H_CPU1_SB_DQ<5>")
	)
	(segment
		(start 135.577834 -277.060406)
		(end 136.044686 -277.326344)
		(width 0.10668)
		(layer "F.Cu")
		(net "M_H_CPU1_SB_DQ<4>")
	)
	(segment
		(start 171.052998 -287.010602)
		(end 167.092884 -287.010602)
		(width 0.14478)
		(layer "In13.Cu")
		(net "M_H_CPU1_SB_DQ<4>")
	)
	(segment
		(start 136.198864 -277.591774)
		(end 136.044686 -277.326344)
		(width 0.0889)
		(layer "In13.Cu")
		(net "M_H_CPU1_SB_DQ<4>")
	)
	(segment
		(start 144.71269 -277.635208)
		(end 144.689322 -277.648924)
		(width 0.0889)
		(layer "In13.Cu")
		(net "M_H_CPU1_SB_DQ<4>")
	)
	(segment
		(start 147.370546 -276.711664)
		(end 146.247866 -276.711664)
		(width 0.0889)
		(layer "In13.Cu")
		(net "M_H_CPU1_SB_DQ<4>")
	)
	(segment
		(start 145.680938 -277.611332)
		(end 145.630646 -277.64867)
		(width 0.0889)
		(layer "In13.Cu")
		(net "M_H_CPU1_SB_DQ<4>")
	)
	(segment
		(start 145.805906 -277.425658)
		(end 145.76298 -277.52929)
		(width 0.0889)
		(layer "In13.Cu")
		(net "M_H_CPU1_SB_DQ<4>")
	)
	(segment
		(start 140.56614 -277.65375)
		(end 140.557758 -277.648924)
		(width 0.0889)
		(layer "In13.Cu")
		(net "M_H_CPU1_SB_DQ<4>")
	)
	(segment
		(start 143.386048 -277.65375)
		(end 143.377666 -277.648924)
		(width 0.0889)
		(layer "In13.Cu")
		(net "M_H_CPU1_SB_DQ<4>")
	)
	(segment
		(start 174.508668 -287.870138)
		(end 174.247048 -287.870138)
		(width 0.14478)
		(layer "In13.Cu")
		(net "M_H_CPU1_SB_DQ<4>")
	)
	(segment
		(start 173.957488 -288.30143)
		(end 173.695868 -288.30143)
		(width 0.14478)
		(layer "In13.Cu")
		(net "M_H_CPU1_SB_DQ<4>")
	)
	(segment
		(start 173.406308 -287.870138)
		(end 173.128178 -287.870138)
		(width 0.14478)
		(layer "In13.Cu")
		(net "M_H_CPU1_SB_DQ<4>")
	)
	(segment
		(start 167.092884 -287.010602)
		(end 166.243 -287.860486)
		(width 0.14478)
		(layer "In13.Cu")
		(net "M_H_CPU1_SB_DQ<4>")
	)
	(segment
		(start 139.051792 -277.648924)
		(end 139.04341 -277.65375)
		(width 0.0889)
		(layer "In13.Cu")
		(net "M_H_CPU1_SB_DQ<4>")
	)
	(segment
		(start 175.059848 -288.30143)
		(end 174.798228 -288.30143)
		(width 0.14478)
		(layer "In13.Cu")
		(net "M_H_CPU1_SB_DQ<4>")
	)
	(segment
		(start 144.334484 -277.659084)
		(end 144.316196 -277.64867)
		(width 0.0889)
		(layer "In13.Cu")
		(net "M_H_CPU1_SB_DQ<4>")
	)
	(segment
		(start 151.976836 -276.69109)
		(end 148.053552 -276.69109)
		(width 0.14478)
		(layer "In13.Cu")
		(net "M_H_CPU1_SB_DQ<4>")
	)
	(segment
		(start 174.247048 -287.870138)
		(end 174.102268 -288.014918)
		(width 0.14478)
		(layer "In13.Cu")
		(net "M_H_CPU1_SB_DQ<4>")
	)
	(segment
		(start 146.247866 -276.711664)
		(end 145.805906 -277.153624)
		(width 0.0889)
		(layer "In13.Cu")
		(net "M_H_CPU1_SB_DQ<4>")
	)
	(segment
		(start 148.053552 -276.69109)
		(end 147.39112 -276.69109)
		(width 0.0889)
		(layer "In13.Cu")
		(net "M_H_CPU1_SB_DQ<4>")
	)
	(segment
		(start 174.653448 -288.15665)
		(end 174.653448 -288.014918)
		(width 0.14478)
		(layer "In13.Cu")
		(net "M_H_CPU1_SB_DQ<4>")
	)
	(segment
		(start 173.128178 -287.870138)
		(end 171.052998 -287.010602)
		(width 0.14478)
		(layer "In13.Cu")
		(net "M_H_CPU1_SB_DQ<4>")
	)
	(segment
		(start 147.39112 -276.69109)
		(end 147.370546 -276.711664)
		(width 0.0889)
		(layer "In13.Cu")
		(net "M_H_CPU1_SB_DQ<4>")
	)
	(segment
		(start 174.102268 -288.014918)
		(end 174.102268 -288.15665)
		(width 0.14478)
		(layer "In13.Cu")
		(net "M_H_CPU1_SB_DQ<4>")
	)
	(segment
		(start 173.551088 -288.15665)
		(end 173.551088 -288.014918)
		(width 0.14478)
		(layer "In13.Cu")
		(net "M_H_CPU1_SB_DQ<4>")
	)
	(segment
		(start 138.111738 -277.648924)
		(end 138.103356 -277.65375)
		(width 0.0889)
		(layer "In13.Cu")
		(net "M_H_CPU1_SB_DQ<4>")
	)
	(segment
		(start 166.243 -287.860486)
		(end 164.131752 -287.860486)
		(width 0.14478)
		(layer "In13.Cu")
		(net "M_H_CPU1_SB_DQ<4>")
	)
	(segment
		(start 174.102268 -288.15665)
		(end 173.957488 -288.30143)
		(width 0.14478)
		(layer "In13.Cu")
		(net "M_H_CPU1_SB_DQ<4>")
	)
	(segment
		(start 139.626086 -277.65375)
		(end 139.617704 -277.648924)
		(width 0.0889)
		(layer "In13.Cu")
		(net "M_H_CPU1_SB_DQ<4>")
	)
	(segment
		(start 175.204628 -288.15665)
		(end 175.059848 -288.30143)
		(width 0.14478)
		(layer "In13.Cu")
		(net "M_H_CPU1_SB_DQ<4>")
	)
	(segment
		(start 144.316196 -277.64867)
		(end 144.294606 -277.636224)
		(width 0.0889)
		(layer "In13.Cu")
		(net "M_H_CPU1_SB_DQ<4>")
	)
	(segment
		(start 162.467798 -286.196532)
		(end 161.482278 -286.196532)
		(width 0.14478)
		(layer "In13.Cu")
		(net "M_H_CPU1_SB_DQ<4>")
	)
	(segment
		(start 175.204628 -288.014918)
		(end 175.204628 -288.15665)
		(width 0.14478)
		(layer "In13.Cu")
		(net "M_H_CPU1_SB_DQ<4>")
	)
	(segment
		(start 176.072038 -287.43529)
		(end 175.63719 -287.870138)
		(width 0.14478)
		(layer "In13.Cu")
		(net "M_H_CPU1_SB_DQ<4>")
	)
	(segment
		(start 145.805906 -277.153624)
		(end 145.805906 -277.425658)
		(width 0.0889)
		(layer "In13.Cu")
		(net "M_H_CPU1_SB_DQ<4>")
	)
	(segment
		(start 161.482278 -286.196532)
		(end 151.976836 -276.69109)
		(width 0.14478)
		(layer "In13.Cu")
		(net "M_H_CPU1_SB_DQ<4>")
	)
	(segment
		(start 145.630646 -277.64867)
		(end 145.603214 -277.664418)
		(width 0.0889)
		(layer "In13.Cu")
		(net "M_H_CPU1_SB_DQ<4>")
	)
	(segment
		(start 142.811754 -277.648924)
		(end 142.803372 -277.65375)
		(width 0.0889)
		(layer "In13.Cu")
		(net "M_H_CPU1_SB_DQ<4>")
	)
	(segment
		(start 174.653448 -288.014918)
		(end 174.508668 -287.870138)
		(width 0.14478)
		(layer "In13.Cu")
		(net "M_H_CPU1_SB_DQ<4>")
	)
	(segment
		(start 174.798228 -288.30143)
		(end 174.653448 -288.15665)
		(width 0.14478)
		(layer "In13.Cu")
		(net "M_H_CPU1_SB_DQ<4>")
	)
	(segment
		(start 173.551088 -288.014918)
		(end 173.406308 -287.870138)
		(width 0.14478)
		(layer "In13.Cu")
		(net "M_H_CPU1_SB_DQ<4>")
	)
	(segment
		(start 175.349408 -287.870138)
		(end 175.204628 -288.014918)
		(width 0.14478)
		(layer "In13.Cu")
		(net "M_H_CPU1_SB_DQ<4>")
	)
	(segment
		(start 175.63719 -287.870138)
		(end 175.349408 -287.870138)
		(width 0.14478)
		(layer "In13.Cu")
		(net "M_H_CPU1_SB_DQ<4>")
	)
	(segment
		(start 136.29513 -277.617174)
		(end 136.198864 -277.591774)
		(width 0.0889)
		(layer "In13.Cu")
		(net "M_H_CPU1_SB_DQ<4>")
	)
	(segment
		(start 173.695868 -288.30143)
		(end 173.551088 -288.15665)
		(width 0.14478)
		(layer "In13.Cu")
		(net "M_H_CPU1_SB_DQ<4>")
	)
	(segment
		(start 164.131752 -287.860486)
		(end 162.467798 -286.196532)
		(width 0.14478)
		(layer "In13.Cu")
		(net "M_H_CPU1_SB_DQ<4>")
	)
	(segment
		(start 145.76298 -277.52929)
		(end 145.680938 -277.611332)
		(width 0.0889)
		(layer "In13.Cu")
		(net "M_H_CPU1_SB_DQ<4>")
	)
	(arc
		(start 145.256504 -277.648924)
		(mid 144.986347 -277.572162)
		(end 144.71269 -277.635208)
		(width 0.0889)
		(layer "In13.Cu")
		(net "M_H_CPU1_SB_DQ<4>")
	)
	(arc
		(start 144.689322 -277.648924)
		(mid 144.513202 -277.698902)
		(end 144.334484 -277.659084)
		(width 0.0889)
		(layer "In13.Cu")
		(net "M_H_CPU1_SB_DQ<4>")
	)
	(arc
		(start 141.8717 -277.648924)
		(mid 141.684756 -277.699179)
		(end 141.497812 -277.648924)
		(width 0.0889)
		(layer "In13.Cu")
		(net "M_H_CPU1_SB_DQ<4>")
	)
	(arc
		(start 138.103356 -277.65375)
		(mid 137.919848 -277.699244)
		(end 137.737596 -277.648924)
		(width 0.0889)
		(layer "In13.Cu")
		(net "M_H_CPU1_SB_DQ<4>")
	)
	(arc
		(start 141.497812 -277.648924)
		(mid 141.214856 -277.572747)
		(end 140.9319 -277.648924)
		(width 0.0889)
		(layer "In13.Cu")
		(net "M_H_CPU1_SB_DQ<4>")
	)
	(arc
		(start 143.377666 -277.648924)
		(mid 143.09471 -277.572747)
		(end 142.811754 -277.648924)
		(width 0.0889)
		(layer "In13.Cu")
		(net "M_H_CPU1_SB_DQ<4>")
	)
	(arc
		(start 139.617704 -277.648924)
		(mid 139.334748 -277.572747)
		(end 139.051792 -277.648924)
		(width 0.0889)
		(layer "In13.Cu")
		(net "M_H_CPU1_SB_DQ<4>")
	)
	(arc
		(start 138.67765 -277.648924)
		(mid 138.394694 -277.572747)
		(end 138.111738 -277.648924)
		(width 0.0889)
		(layer "In13.Cu")
		(net "M_H_CPU1_SB_DQ<4>")
	)
	(arc
		(start 139.991846 -277.648924)
		(mid 139.809595 -277.699274)
		(end 139.626086 -277.65375)
		(width 0.0889)
		(layer "In13.Cu")
		(net "M_H_CPU1_SB_DQ<4>")
	)
	(arc
		(start 140.9319 -277.648924)
		(mid 140.749649 -277.699274)
		(end 140.56614 -277.65375)
		(width 0.0889)
		(layer "In13.Cu")
		(net "M_H_CPU1_SB_DQ<4>")
	)
	(arc
		(start 142.803372 -277.65375)
		(mid 142.619864 -277.699244)
		(end 142.437612 -277.648924)
		(width 0.0889)
		(layer "In13.Cu")
		(net "M_H_CPU1_SB_DQ<4>")
	)
	(arc
		(start 142.437612 -277.648924)
		(mid 142.154656 -277.572747)
		(end 141.8717 -277.648924)
		(width 0.0889)
		(layer "In13.Cu")
		(net "M_H_CPU1_SB_DQ<4>")
	)
	(arc
		(start 139.04341 -277.65375)
		(mid 138.859902 -277.699244)
		(end 138.67765 -277.648924)
		(width 0.0889)
		(layer "In13.Cu")
		(net "M_H_CPU1_SB_DQ<4>")
	)
	(arc
		(start 145.603214 -277.664418)
		(mid 145.427963 -277.699351)
		(end 145.256504 -277.648924)
		(width 0.0889)
		(layer "In13.Cu")
		(net "M_H_CPU1_SB_DQ<4>")
	)
	(arc
		(start 144.294606 -277.636224)
		(mid 144.021577 -277.572905)
		(end 143.751808 -277.648924)
		(width 0.0889)
		(layer "In13.Cu")
		(net "M_H_CPU1_SB_DQ<4>")
	)
	(arc
		(start 137.737596 -277.648924)
		(mid 137.45464 -277.572747)
		(end 137.171684 -277.648924)
		(width 0.0889)
		(layer "In13.Cu")
		(net "M_H_CPU1_SB_DQ<4>")
	)
	(arc
		(start 143.751808 -277.648924)
		(mid 143.569557 -277.699274)
		(end 143.386048 -277.65375)
		(width 0.0889)
		(layer "In13.Cu")
		(net "M_H_CPU1_SB_DQ<4>")
	)
	(arc
		(start 140.557758 -277.648924)
		(mid 140.274802 -277.572747)
		(end 139.991846 -277.648924)
		(width 0.0889)
		(layer "In13.Cu")
		(net "M_H_CPU1_SB_DQ<4>")
	)
	(arc
		(start 137.171684 -277.648924)
		(mid 136.98474 -277.699179)
		(end 136.797796 -277.648924)
		(width 0.0889)
		(layer "In13.Cu")
		(net "M_H_CPU1_SB_DQ<4>")
	)
	(arc
		(start 136.797796 -277.648924)
		(mid 136.5502 -277.573746)
		(end 136.29513 -277.617174)
		(width 0.0889)
		(layer "In13.Cu")
		(net "M_H_CPU1_SB_DQ<4>")
	)
	(segment
		(start 134.63778 -275.440394)
		(end 135.104632 -275.706332)
		(width 0.10668)
		(layer "F.Cu")
		(net "M_H_CPU1_SB_DQ<3>")
	)
	(segment
		(start 143.377666 -275.383752)
		(end 143.386048 -275.378926)
		(width 0.0889)
		(layer "In13.Cu")
		(net "M_H_CPU1_SB_DQ<3>")
	)
	(segment
		(start 135.104632 -275.706332)
		(end 134.950708 -275.440902)
		(width 0.0889)
		(layer "In13.Cu")
		(net "M_H_CPU1_SB_DQ<3>")
	)
	(segment
		(start 170.27144 -283.610304)
		(end 170.460416 -283.532072)
		(width 0.14478)
		(layer "In13.Cu")
		(net "M_H_CPU1_SB_DQ<3>")
	)
	(segment
		(start 147.440142 -274.303744)
		(end 147.96262 -274.303744)
		(width 0.0889)
		(layer "In13.Cu")
		(net "M_H_CPU1_SB_DQ<3>")
	)
	(segment
		(start 155.397708 -276.640544)
		(end 155.397708 -276.869144)
		(width 0.14478)
		(layer "In13.Cu")
		(net "M_H_CPU1_SB_DQ<3>")
	)
	(segment
		(start 146.015202 -275.077428)
		(end 146.834606 -274.258024)
		(width 0.0889)
		(layer "In13.Cu")
		(net "M_H_CPU1_SB_DQ<3>")
	)
	(segment
		(start 154.098752 -274.818348)
		(end 153.837132 -275.079968)
		(width 0.14478)
		(layer "In13.Cu")
		(net "M_H_CPU1_SB_DQ<3>")
	)
	(segment
		(start 155.659328 -276.378924)
		(end 155.397708 -276.640544)
		(width 0.14478)
		(layer "In13.Cu")
		(net "M_H_CPU1_SB_DQ<3>")
	)
	(segment
		(start 145.392648 -275.343366)
		(end 145.490946 -275.316442)
		(width 0.0889)
		(layer "In13.Cu")
		(net "M_H_CPU1_SB_DQ<3>")
	)
	(segment
		(start 156.049472 -276.769068)
		(end 156.278072 -276.769068)
		(width 0.14478)
		(layer "In13.Cu")
		(net "M_H_CPU1_SB_DQ<3>")
	)
	(segment
		(start 155.497784 -275.98878)
		(end 155.659328 -276.150324)
		(width 0.14478)
		(layer "In13.Cu")
		(net "M_H_CPU1_SB_DQ<3>")
	)
	(segment
		(start 170.702478 -283.632402)
		(end 170.78071 -283.821378)
		(width 0.14478)
		(layer "In13.Cu")
		(net "M_H_CPU1_SB_DQ<3>")
	)
	(segment
		(start 135.857742 -275.383752)
		(end 135.866124 -275.378926)
		(width 0.0889)
		(layer "In13.Cu")
		(net "M_H_CPU1_SB_DQ<3>")
	)
	(segment
		(start 169.76217 -283.39923)
		(end 169.67708 -283.604716)
		(width 0.14478)
		(layer "In13.Cu")
		(net "M_H_CPU1_SB_DQ<3>")
	)
	(segment
		(start 143.751808 -275.383752)
		(end 143.762222 -275.389848)
		(width 0.0889)
		(layer "In13.Cu")
		(net "M_H_CPU1_SB_DQ<3>")
	)
	(segment
		(start 167.012366 -283.21)
		(end 169.683684 -283.21)
		(width 0.14478)
		(layer "In13.Cu")
		(net "M_H_CPU1_SB_DQ<3>")
	)
	(segment
		(start 154.488896 -275.208492)
		(end 154.717496 -275.208492)
		(width 0.14478)
		(layer "In13.Cu")
		(net "M_H_CPU1_SB_DQ<3>")
	)
	(segment
		(start 153.837132 -275.079968)
		(end 153.837132 -275.308568)
		(width 0.14478)
		(layer "In13.Cu")
		(net "M_H_CPU1_SB_DQ<3>")
	)
	(segment
		(start 147.394422 -274.258024)
		(end 147.440142 -274.303744)
		(width 0.0889)
		(layer "In13.Cu")
		(net "M_H_CPU1_SB_DQ<3>")
	)
	(segment
		(start 154.61742 -276.088856)
		(end 154.778964 -276.2504)
		(width 0.14478)
		(layer "In13.Cu")
		(net "M_H_CPU1_SB_DQ<3>")
	)
	(segment
		(start 156.278072 -276.769068)
		(end 163.568888 -284.059884)
		(width 0.14478)
		(layer "In13.Cu")
		(net "M_H_CPU1_SB_DQ<3>")
	)
	(segment
		(start 134.950708 -275.440902)
		(end 134.97306 -275.35759)
		(width 0.0889)
		(layer "In13.Cu")
		(net "M_H_CPU1_SB_DQ<3>")
	)
	(segment
		(start 146.834606 -274.258024)
		(end 147.394422 -274.258024)
		(width 0.0889)
		(layer "In13.Cu")
		(net "M_H_CPU1_SB_DQ<3>")
	)
	(segment
		(start 153.812748 -274.303744)
		(end 154.098752 -274.589748)
		(width 0.14478)
		(layer "In13.Cu")
		(net "M_H_CPU1_SB_DQ<3>")
	)
	(segment
		(start 171.072302 -284.180026)
		(end 171.261278 -284.101794)
		(width 0.14478)
		(layer "In13.Cu")
		(net "M_H_CPU1_SB_DQ<3>")
	)
	(segment
		(start 170.752008 -283.89072)
		(end 170.83024 -284.079696)
		(width 0.14478)
		(layer "In13.Cu")
		(net "M_H_CPU1_SB_DQ<3>")
	)
	(segment
		(start 139.04341 -275.378926)
		(end 139.051792 -275.383752)
		(width 0.0889)
		(layer "In13.Cu")
		(net "M_H_CPU1_SB_DQ<3>")
	)
	(segment
		(start 154.87904 -275.370036)
		(end 154.87904 -275.598636)
		(width 0.14478)
		(layer "In13.Cu")
		(net "M_H_CPU1_SB_DQ<3>")
	)
	(segment
		(start 170.18635 -283.81579)
		(end 170.27144 -283.610304)
		(width 0.14478)
		(layer "In13.Cu")
		(net "M_H_CPU1_SB_DQ<3>")
	)
	(segment
		(start 155.659328 -276.150324)
		(end 155.659328 -276.378924)
		(width 0.14478)
		(layer "In13.Cu")
		(net "M_H_CPU1_SB_DQ<3>")
	)
	(segment
		(start 170.78071 -283.821378)
		(end 170.752008 -283.89072)
		(width 0.14478)
		(layer "In13.Cu")
		(net "M_H_CPU1_SB_DQ<3>")
	)
	(segment
		(start 155.269184 -275.98878)
		(end 155.497784 -275.98878)
		(width 0.14478)
		(layer "In13.Cu")
		(net "M_H_CPU1_SB_DQ<3>")
	)
	(segment
		(start 163.568888 -284.059884)
		(end 166.162482 -284.059884)
		(width 0.14478)
		(layer "In13.Cu")
		(net "M_H_CPU1_SB_DQ<3>")
	)
	(segment
		(start 154.717496 -275.208492)
		(end 154.87904 -275.370036)
		(width 0.14478)
		(layer "In13.Cu")
		(net "M_H_CPU1_SB_DQ<3>")
	)
	(segment
		(start 154.098752 -274.589748)
		(end 154.098752 -274.818348)
		(width 0.14478)
		(layer "In13.Cu")
		(net "M_H_CPU1_SB_DQ<3>")
	)
	(segment
		(start 169.755312 -283.793692)
		(end 169.997374 -283.894022)
		(width 0.14478)
		(layer "In13.Cu")
		(net "M_H_CPU1_SB_DQ<3>")
	)
	(segment
		(start 169.997374 -283.894022)
		(end 170.18635 -283.81579)
		(width 0.14478)
		(layer "In13.Cu")
		(net "M_H_CPU1_SB_DQ<3>")
	)
	(segment
		(start 140.557758 -275.383752)
		(end 140.56614 -275.378926)
		(width 0.0889)
		(layer "In13.Cu")
		(net "M_H_CPU1_SB_DQ<3>")
	)
	(segment
		(start 145.931382 -275.133562)
		(end 146.015202 -275.077428)
		(width 0.0889)
		(layer "In13.Cu")
		(net "M_H_CPU1_SB_DQ<3>")
	)
	(segment
		(start 139.617704 -275.383752)
		(end 139.626086 -275.378926)
		(width 0.0889)
		(layer "In13.Cu")
		(net "M_H_CPU1_SB_DQ<3>")
	)
	(segment
		(start 166.162482 -284.059884)
		(end 167.012366 -283.21)
		(width 0.14478)
		(layer "In13.Cu")
		(net "M_H_CPU1_SB_DQ<3>")
	)
	(segment
		(start 138.103356 -275.378926)
		(end 138.111738 -275.383752)
		(width 0.0889)
		(layer "In13.Cu")
		(net "M_H_CPU1_SB_DQ<3>")
	)
	(segment
		(start 154.87904 -275.598636)
		(end 154.61742 -275.860256)
		(width 0.14478)
		(layer "In13.Cu")
		(net "M_H_CPU1_SB_DQ<3>")
	)
	(segment
		(start 169.67708 -283.604716)
		(end 169.755312 -283.793692)
		(width 0.14478)
		(layer "In13.Cu")
		(net "M_H_CPU1_SB_DQ<3>")
	)
	(segment
		(start 154.61742 -275.860256)
		(end 154.61742 -276.088856)
		(width 0.14478)
		(layer "In13.Cu")
		(net "M_H_CPU1_SB_DQ<3>")
	)
	(segment
		(start 155.007564 -276.2504)
		(end 155.269184 -275.98878)
		(width 0.14478)
		(layer "In13.Cu")
		(net "M_H_CPU1_SB_DQ<3>")
	)
	(segment
		(start 144.684242 -275.378926)
		(end 144.692624 -275.383752)
		(width 0.0889)
		(layer "In13.Cu")
		(net "M_H_CPU1_SB_DQ<3>")
	)
	(segment
		(start 169.683684 -283.21)
		(end 169.76217 -283.39923)
		(width 0.14478)
		(layer "In13.Cu")
		(net "M_H_CPU1_SB_DQ<3>")
	)
	(segment
		(start 155.397708 -276.869144)
		(end 155.559252 -277.030688)
		(width 0.14478)
		(layer "In13.Cu")
		(net "M_H_CPU1_SB_DQ<3>")
	)
	(segment
		(start 171.947332 -284.059884)
		(end 171.97197 -284.035246)
		(width 0.14478)
		(layer "In13.Cu")
		(net "M_H_CPU1_SB_DQ<3>")
	)
	(segment
		(start 153.837132 -275.308568)
		(end 153.998676 -275.470112)
		(width 0.14478)
		(layer "In13.Cu")
		(net "M_H_CPU1_SB_DQ<3>")
	)
	(segment
		(start 170.83024 -284.079696)
		(end 171.072302 -284.180026)
		(width 0.14478)
		(layer "In13.Cu")
		(net "M_H_CPU1_SB_DQ<3>")
	)
	(segment
		(start 145.490946 -275.316442)
		(end 145.931382 -275.133562)
		(width 0.0889)
		(layer "In13.Cu")
		(net "M_H_CPU1_SB_DQ<3>")
	)
	(segment
		(start 171.735496 -284.059884)
		(end 171.947332 -284.059884)
		(width 0.14478)
		(layer "In13.Cu")
		(net "M_H_CPU1_SB_DQ<3>")
	)
	(segment
		(start 154.778964 -276.2504)
		(end 155.007564 -276.2504)
		(width 0.14478)
		(layer "In13.Cu")
		(net "M_H_CPU1_SB_DQ<3>")
	)
	(segment
		(start 171.261278 -284.101794)
		(end 171.28998 -284.032452)
		(width 0.14478)
		(layer "In13.Cu")
		(net "M_H_CPU1_SB_DQ<3>")
	)
	(segment
		(start 170.460416 -283.532072)
		(end 170.702478 -283.632402)
		(width 0.14478)
		(layer "In13.Cu")
		(net "M_H_CPU1_SB_DQ<3>")
	)
	(segment
		(start 155.559252 -277.030688)
		(end 155.787852 -277.030688)
		(width 0.14478)
		(layer "In13.Cu")
		(net "M_H_CPU1_SB_DQ<3>")
	)
	(segment
		(start 147.96262 -274.303744)
		(end 153.812748 -274.303744)
		(width 0.14478)
		(layer "In13.Cu")
		(net "M_H_CPU1_SB_DQ<3>")
	)
	(segment
		(start 171.28998 -284.032452)
		(end 171.47921 -283.953966)
		(width 0.14478)
		(layer "In13.Cu")
		(net "M_H_CPU1_SB_DQ<3>")
	)
	(segment
		(start 171.47921 -283.953966)
		(end 171.735496 -284.059884)
		(width 0.14478)
		(layer "In13.Cu")
		(net "M_H_CPU1_SB_DQ<3>")
	)
	(segment
		(start 153.998676 -275.470112)
		(end 154.227276 -275.470112)
		(width 0.14478)
		(layer "In13.Cu")
		(net "M_H_CPU1_SB_DQ<3>")
	)
	(segment
		(start 145.25244 -275.387308)
		(end 145.392648 -275.343366)
		(width 0.0889)
		(layer "In13.Cu")
		(net "M_H_CPU1_SB_DQ<3>")
	)
	(segment
		(start 154.227276 -275.470112)
		(end 154.488896 -275.208492)
		(width 0.14478)
		(layer "In13.Cu")
		(net "M_H_CPU1_SB_DQ<3>")
	)
	(segment
		(start 142.803372 -275.378926)
		(end 142.811754 -275.383752)
		(width 0.0889)
		(layer "In13.Cu")
		(net "M_H_CPU1_SB_DQ<3>")
	)
	(segment
		(start 155.787852 -277.030688)
		(end 156.049472 -276.769068)
		(width 0.14478)
		(layer "In13.Cu")
		(net "M_H_CPU1_SB_DQ<3>")
	)
	(arc
		(start 138.67765 -275.383752)
		(mid 138.859901 -275.333402)
		(end 139.04341 -275.378926)
		(width 0.0889)
		(layer "In13.Cu")
		(net "M_H_CPU1_SB_DQ<3>")
	)
	(arc
		(start 137.171684 -275.383752)
		(mid 137.45464 -275.459929)
		(end 137.737596 -275.383752)
		(width 0.0889)
		(layer "In13.Cu")
		(net "M_H_CPU1_SB_DQ<3>")
	)
	(arc
		(start 142.437612 -275.383752)
		(mid 142.619863 -275.333402)
		(end 142.803372 -275.378926)
		(width 0.0889)
		(layer "In13.Cu")
		(net "M_H_CPU1_SB_DQ<3>")
	)
	(arc
		(start 138.111738 -275.383752)
		(mid 138.394694 -275.459929)
		(end 138.67765 -275.383752)
		(width 0.0889)
		(layer "In13.Cu")
		(net "M_H_CPU1_SB_DQ<3>")
	)
	(arc
		(start 141.8717 -275.383752)
		(mid 142.154656 -275.459929)
		(end 142.437612 -275.383752)
		(width 0.0889)
		(layer "In13.Cu")
		(net "M_H_CPU1_SB_DQ<3>")
	)
	(arc
		(start 139.991846 -275.383752)
		(mid 140.274802 -275.459929)
		(end 140.557758 -275.383752)
		(width 0.0889)
		(layer "In13.Cu")
		(net "M_H_CPU1_SB_DQ<3>")
	)
	(arc
		(start 139.626086 -275.378926)
		(mid 139.809594 -275.333432)
		(end 139.991846 -275.383752)
		(width 0.0889)
		(layer "In13.Cu")
		(net "M_H_CPU1_SB_DQ<3>")
	)
	(arc
		(start 142.811754 -275.383752)
		(mid 143.09471 -275.459929)
		(end 143.377666 -275.383752)
		(width 0.0889)
		(layer "In13.Cu")
		(net "M_H_CPU1_SB_DQ<3>")
	)
	(arc
		(start 140.56614 -275.378926)
		(mid 140.749648 -275.333432)
		(end 140.9319 -275.383752)
		(width 0.0889)
		(layer "In13.Cu")
		(net "M_H_CPU1_SB_DQ<3>")
	)
	(arc
		(start 134.97306 -275.35759)
		(mid 135.135392 -275.334772)
		(end 135.29183 -275.383752)
		(width 0.0889)
		(layer "In13.Cu")
		(net "M_H_CPU1_SB_DQ<3>")
	)
	(arc
		(start 136.231884 -275.383752)
		(mid 136.51484 -275.459929)
		(end 136.797796 -275.383752)
		(width 0.0889)
		(layer "In13.Cu")
		(net "M_H_CPU1_SB_DQ<3>")
	)
	(arc
		(start 137.737596 -275.383752)
		(mid 137.919847 -275.333402)
		(end 138.103356 -275.378926)
		(width 0.0889)
		(layer "In13.Cu")
		(net "M_H_CPU1_SB_DQ<3>")
	)
	(arc
		(start 135.29183 -275.383752)
		(mid 135.574786 -275.459929)
		(end 135.857742 -275.383752)
		(width 0.0889)
		(layer "In13.Cu")
		(net "M_H_CPU1_SB_DQ<3>")
	)
	(arc
		(start 143.386048 -275.378926)
		(mid 143.569556 -275.333432)
		(end 143.751808 -275.383752)
		(width 0.0889)
		(layer "In13.Cu")
		(net "M_H_CPU1_SB_DQ<3>")
	)
	(arc
		(start 140.9319 -275.383752)
		(mid 141.214856 -275.459929)
		(end 141.497812 -275.383752)
		(width 0.0889)
		(layer "In13.Cu")
		(net "M_H_CPU1_SB_DQ<3>")
	)
	(arc
		(start 141.497812 -275.383752)
		(mid 141.684756 -275.333497)
		(end 141.8717 -275.383752)
		(width 0.0889)
		(layer "In13.Cu")
		(net "M_H_CPU1_SB_DQ<3>")
	)
	(arc
		(start 136.797796 -275.383752)
		(mid 136.98474 -275.333497)
		(end 137.171684 -275.383752)
		(width 0.0889)
		(layer "In13.Cu")
		(net "M_H_CPU1_SB_DQ<3>")
	)
	(arc
		(start 135.866124 -275.378926)
		(mid 136.049632 -275.333432)
		(end 136.231884 -275.383752)
		(width 0.0889)
		(layer "In13.Cu")
		(net "M_H_CPU1_SB_DQ<3>")
	)
	(arc
		(start 143.762222 -275.389848)
		(mid 144.040908 -275.460068)
		(end 144.317974 -275.383752)
		(width 0.0889)
		(layer "In13.Cu")
		(net "M_H_CPU1_SB_DQ<3>")
	)
	(arc
		(start 139.051792 -275.383752)
		(mid 139.334748 -275.459929)
		(end 139.617704 -275.383752)
		(width 0.0889)
		(layer "In13.Cu")
		(net "M_H_CPU1_SB_DQ<3>")
	)
	(arc
		(start 144.692624 -275.383752)
		(mid 144.972052 -275.459918)
		(end 145.25244 -275.387308)
		(width 0.0889)
		(layer "In13.Cu")
		(net "M_H_CPU1_SB_DQ<3>")
	)
	(arc
		(start 144.317974 -275.383752)
		(mid 144.500479 -275.333275)
		(end 144.684242 -275.378926)
		(width 0.0889)
		(layer "In13.Cu")
		(net "M_H_CPU1_SB_DQ<3>")
	)
	(segment
		(start 134.63778 -293.260272)
		(end 135.104632 -293.52621)
		(width 0.10668)
		(layer "F.Cu")
		(net "M_H_CPU1_SB_DQ<31>")
	)
	(segment
		(start 142.811754 -293.20363)
		(end 142.803372 -293.198804)
		(width 0.0889)
		(layer "In13.Cu")
		(net "M_H_CPU1_SB_DQ<31>")
	)
	(segment
		(start 171.271438 -318.460374)
		(end 171.126658 -318.605154)
		(width 0.14478)
		(layer "In13.Cu")
		(net "M_H_CPU1_SB_DQ<31>")
	)
	(segment
		(start 140.56614 -293.198804)
		(end 140.557758 -293.20363)
		(width 0.0889)
		(layer "In13.Cu")
		(net "M_H_CPU1_SB_DQ<31>")
	)
	(segment
		(start 171.126658 -318.913256)
		(end 170.981878 -319.058036)
		(width 0.14478)
		(layer "In13.Cu")
		(net "M_H_CPU1_SB_DQ<31>")
	)
	(segment
		(start 169.066718 -318.460374)
		(end 168.921938 -318.605154)
		(width 0.14478)
		(layer "In13.Cu")
		(net "M_H_CPU1_SB_DQ<31>")
	)
	(segment
		(start 171.97197 -318.035432)
		(end 171.547028 -318.460374)
		(width 0.14478)
		(layer "In13.Cu")
		(net "M_H_CPU1_SB_DQ<31>")
	)
	(segment
		(start 169.879518 -319.058036)
		(end 169.617898 -319.058036)
		(width 0.14478)
		(layer "In13.Cu")
		(net "M_H_CPU1_SB_DQ<31>")
	)
	(segment
		(start 170.024298 -318.913256)
		(end 169.879518 -319.058036)
		(width 0.14478)
		(layer "In13.Cu")
		(net "M_H_CPU1_SB_DQ<31>")
	)
	(segment
		(start 135.866124 -293.198804)
		(end 135.857742 -293.20363)
		(width 0.0889)
		(layer "In13.Cu")
		(net "M_H_CPU1_SB_DQ<31>")
	)
	(segment
		(start 168.921938 -318.605154)
		(end 168.921938 -318.913256)
		(width 0.14478)
		(layer "In13.Cu")
		(net "M_H_CPU1_SB_DQ<31>")
	)
	(segment
		(start 139.051792 -293.20363)
		(end 139.04341 -293.198804)
		(width 0.0889)
		(layer "In13.Cu")
		(net "M_H_CPU1_SB_DQ<31>")
	)
	(segment
		(start 145.349214 -296.154602)
		(end 145.349214 -295.956228)
		(width 0.0889)
		(layer "In13.Cu")
		(net "M_H_CPU1_SB_DQ<31>")
	)
	(segment
		(start 169.328338 -318.460374)
		(end 169.066718 -318.460374)
		(width 0.14478)
		(layer "In13.Cu")
		(net "M_H_CPU1_SB_DQ<31>")
	)
	(segment
		(start 168.225978 -318.460374)
		(end 163.462462 -318.460374)
		(width 0.14478)
		(layer "In13.Cu")
		(net "M_H_CPU1_SB_DQ<31>")
	)
	(segment
		(start 161.64814 -318.09944)
		(end 159.036766 -317.017908)
		(width 0.14478)
		(layer "In13.Cu")
		(net "M_H_CPU1_SB_DQ<31>")
	)
	(segment
		(start 168.777158 -319.058036)
		(end 168.515538 -319.058036)
		(width 0.14478)
		(layer "In13.Cu")
		(net "M_H_CPU1_SB_DQ<31>")
	)
	(segment
		(start 168.370758 -318.913256)
		(end 168.370758 -318.605154)
		(width 0.14478)
		(layer "In13.Cu")
		(net "M_H_CPU1_SB_DQ<31>")
	)
	(segment
		(start 168.515538 -319.058036)
		(end 168.370758 -318.913256)
		(width 0.14478)
		(layer "In13.Cu")
		(net "M_H_CPU1_SB_DQ<31>")
	)
	(segment
		(start 168.370758 -318.605154)
		(end 168.225978 -318.460374)
		(width 0.14478)
		(layer "In13.Cu")
		(net "M_H_CPU1_SB_DQ<31>")
	)
	(segment
		(start 169.473118 -318.605154)
		(end 169.328338 -318.460374)
		(width 0.14478)
		(layer "In13.Cu")
		(net "M_H_CPU1_SB_DQ<31>")
	)
	(segment
		(start 170.720258 -319.058036)
		(end 170.575478 -318.913256)
		(width 0.14478)
		(layer "In13.Cu")
		(net "M_H_CPU1_SB_DQ<31>")
	)
	(segment
		(start 144.724374 -294.842692)
		(end 144.652492 -294.800782)
		(width 0.0889)
		(layer "In13.Cu")
		(net "M_H_CPU1_SB_DQ<31>")
	)
	(segment
		(start 163.462462 -318.460374)
		(end 161.64814 -318.09944)
		(width 0.14478)
		(layer "In13.Cu")
		(net "M_H_CPU1_SB_DQ<31>")
	)
	(segment
		(start 134.97306 -293.177468)
		(end 134.950708 -293.26078)
		(width 0.0889)
		(layer "In13.Cu")
		(net "M_H_CPU1_SB_DQ<31>")
	)
	(segment
		(start 171.547028 -318.460374)
		(end 171.271438 -318.460374)
		(width 0.14478)
		(layer "In13.Cu")
		(net "M_H_CPU1_SB_DQ<31>")
	)
	(segment
		(start 170.575478 -318.605154)
		(end 170.430698 -318.460374)
		(width 0.14478)
		(layer "In13.Cu")
		(net "M_H_CPU1_SB_DQ<31>")
	)
	(segment
		(start 145.11528 -303.096422)
		(end 145.11528 -296.388536)
		(width 0.14478)
		(layer "In13.Cu")
		(net "M_H_CPU1_SB_DQ<31>")
	)
	(segment
		(start 170.430698 -318.460374)
		(end 170.169078 -318.460374)
		(width 0.14478)
		(layer "In13.Cu")
		(net "M_H_CPU1_SB_DQ<31>")
	)
	(segment
		(start 170.169078 -318.460374)
		(end 170.024298 -318.605154)
		(width 0.14478)
		(layer "In13.Cu")
		(net "M_H_CPU1_SB_DQ<31>")
	)
	(segment
		(start 144.252188 -294.031416)
		(end 144.182592 -293.990776)
		(width 0.0889)
		(layer "In13.Cu")
		(net "M_H_CPU1_SB_DQ<31>")
	)
	(segment
		(start 139.626086 -293.198804)
		(end 139.617704 -293.20363)
		(width 0.0889)
		(layer "In13.Cu")
		(net "M_H_CPU1_SB_DQ<31>")
	)
	(segment
		(start 138.111738 -293.20363)
		(end 138.103356 -293.198804)
		(width 0.0889)
		(layer "In13.Cu")
		(net "M_H_CPU1_SB_DQ<31>")
	)
	(segment
		(start 170.575478 -318.913256)
		(end 170.575478 -318.605154)
		(width 0.14478)
		(layer "In13.Cu")
		(net "M_H_CPU1_SB_DQ<31>")
	)
	(segment
		(start 159.036766 -317.017908)
		(end 145.11528 -303.096422)
		(width 0.14478)
		(layer "In13.Cu")
		(net "M_H_CPU1_SB_DQ<31>")
	)
	(segment
		(start 145.11528 -296.388536)
		(end 145.349214 -296.154602)
		(width 0.0889)
		(layer "In13.Cu")
		(net "M_H_CPU1_SB_DQ<31>")
	)
	(segment
		(start 134.950708 -293.26078)
		(end 135.104632 -293.52621)
		(width 0.0889)
		(layer "In13.Cu")
		(net "M_H_CPU1_SB_DQ<31>")
	)
	(segment
		(start 170.024298 -318.605154)
		(end 170.024298 -318.913256)
		(width 0.14478)
		(layer "In13.Cu")
		(net "M_H_CPU1_SB_DQ<31>")
	)
	(segment
		(start 170.981878 -319.058036)
		(end 170.720258 -319.058036)
		(width 0.14478)
		(layer "In13.Cu")
		(net "M_H_CPU1_SB_DQ<31>")
	)
	(segment
		(start 169.617898 -319.058036)
		(end 169.473118 -318.913256)
		(width 0.14478)
		(layer "In13.Cu")
		(net "M_H_CPU1_SB_DQ<31>")
	)
	(segment
		(start 143.386048 -293.198804)
		(end 143.377666 -293.20363)
		(width 0.0889)
		(layer "In13.Cu")
		(net "M_H_CPU1_SB_DQ<31>")
	)
	(segment
		(start 145.191226 -295.650666)
		(end 145.122646 -295.610788)
		(width 0.0889)
		(layer "In13.Cu")
		(net "M_H_CPU1_SB_DQ<31>")
	)
	(segment
		(start 169.473118 -318.913256)
		(end 169.473118 -318.605154)
		(width 0.14478)
		(layer "In13.Cu")
		(net "M_H_CPU1_SB_DQ<31>")
	)
	(segment
		(start 168.921938 -318.913256)
		(end 168.777158 -319.058036)
		(width 0.14478)
		(layer "In13.Cu")
		(net "M_H_CPU1_SB_DQ<31>")
	)
	(segment
		(start 143.782288 -293.22141)
		(end 143.751808 -293.20363)
		(width 0.0889)
		(layer "In13.Cu")
		(net "M_H_CPU1_SB_DQ<31>")
	)
	(segment
		(start 171.126658 -318.605154)
		(end 171.126658 -318.913256)
		(width 0.14478)
		(layer "In13.Cu")
		(net "M_H_CPU1_SB_DQ<31>")
	)
	(arc
		(start 142.437612 -293.20363)
		(mid 142.154656 -293.279807)
		(end 141.8717 -293.20363)
		(width 0.0889)
		(layer "In13.Cu")
		(net "M_H_CPU1_SB_DQ<31>")
	)
	(arc
		(start 144.652492 -294.800782)
		(mid 144.473679 -294.598432)
		(end 144.40916 -294.336216)
		(width 0.0889)
		(layer "In13.Cu")
		(net "M_H_CPU1_SB_DQ<31>")
	)
	(arc
		(start 140.9319 -293.20363)
		(mid 140.749649 -293.15328)
		(end 140.56614 -293.198804)
		(width 0.0889)
		(layer "In13.Cu")
		(net "M_H_CPU1_SB_DQ<31>")
	)
	(arc
		(start 138.67765 -293.20363)
		(mid 138.394694 -293.279807)
		(end 138.111738 -293.20363)
		(width 0.0889)
		(layer "In13.Cu")
		(net "M_H_CPU1_SB_DQ<31>")
	)
	(arc
		(start 141.497812 -293.20363)
		(mid 141.214856 -293.279807)
		(end 140.9319 -293.20363)
		(width 0.0889)
		(layer "In13.Cu")
		(net "M_H_CPU1_SB_DQ<31>")
	)
	(arc
		(start 144.182592 -293.990776)
		(mid 144.003779 -293.788426)
		(end 143.93926 -293.52621)
		(width 0.0889)
		(layer "In13.Cu")
		(net "M_H_CPU1_SB_DQ<31>")
	)
	(arc
		(start 136.797796 -293.20363)
		(mid 136.51484 -293.279807)
		(end 136.231884 -293.20363)
		(width 0.0889)
		(layer "In13.Cu")
		(net "M_H_CPU1_SB_DQ<31>")
	)
	(arc
		(start 142.803372 -293.198804)
		(mid 142.619864 -293.15331)
		(end 142.437612 -293.20363)
		(width 0.0889)
		(layer "In13.Cu")
		(net "M_H_CPU1_SB_DQ<31>")
	)
	(arc
		(start 135.857742 -293.20363)
		(mid 135.574786 -293.279807)
		(end 135.29183 -293.20363)
		(width 0.0889)
		(layer "In13.Cu")
		(net "M_H_CPU1_SB_DQ<31>")
	)
	(arc
		(start 145.349214 -295.956228)
		(mid 145.307374 -295.784242)
		(end 145.191226 -295.650666)
		(width 0.0889)
		(layer "In13.Cu")
		(net "M_H_CPU1_SB_DQ<31>")
	)
	(arc
		(start 137.171684 -293.20363)
		(mid 136.98474 -293.153375)
		(end 136.797796 -293.20363)
		(width 0.0889)
		(layer "In13.Cu")
		(net "M_H_CPU1_SB_DQ<31>")
	)
	(arc
		(start 136.231884 -293.20363)
		(mid 136.049633 -293.15328)
		(end 135.866124 -293.198804)
		(width 0.0889)
		(layer "In13.Cu")
		(net "M_H_CPU1_SB_DQ<31>")
	)
	(arc
		(start 144.879314 -295.146222)
		(mid 144.838348 -294.975816)
		(end 144.724374 -294.842692)
		(width 0.0889)
		(layer "In13.Cu")
		(net "M_H_CPU1_SB_DQ<31>")
	)
	(arc
		(start 135.29183 -293.20363)
		(mid 135.135392 -293.154659)
		(end 134.97306 -293.177468)
		(width 0.0889)
		(layer "In13.Cu")
		(net "M_H_CPU1_SB_DQ<31>")
	)
	(arc
		(start 139.04341 -293.198804)
		(mid 138.859902 -293.15331)
		(end 138.67765 -293.20363)
		(width 0.0889)
		(layer "In13.Cu")
		(net "M_H_CPU1_SB_DQ<31>")
	)
	(arc
		(start 145.122646 -295.610788)
		(mid 144.943833 -295.408438)
		(end 144.879314 -295.146222)
		(width 0.0889)
		(layer "In13.Cu")
		(net "M_H_CPU1_SB_DQ<31>")
	)
	(arc
		(start 139.991846 -293.20363)
		(mid 139.809595 -293.15328)
		(end 139.626086 -293.198804)
		(width 0.0889)
		(layer "In13.Cu")
		(net "M_H_CPU1_SB_DQ<31>")
	)
	(arc
		(start 143.751808 -293.20363)
		(mid 143.569557 -293.15328)
		(end 143.386048 -293.198804)
		(width 0.0889)
		(layer "In13.Cu")
		(net "M_H_CPU1_SB_DQ<31>")
	)
	(arc
		(start 137.737596 -293.20363)
		(mid 137.45464 -293.279807)
		(end 137.171684 -293.20363)
		(width 0.0889)
		(layer "In13.Cu")
		(net "M_H_CPU1_SB_DQ<31>")
	)
	(arc
		(start 144.40916 -294.336216)
		(mid 144.367611 -294.164794)
		(end 144.252188 -294.031416)
		(width 0.0889)
		(layer "In13.Cu")
		(net "M_H_CPU1_SB_DQ<31>")
	)
	(arc
		(start 143.377666 -293.20363)
		(mid 143.09471 -293.279807)
		(end 142.811754 -293.20363)
		(width 0.0889)
		(layer "In13.Cu")
		(net "M_H_CPU1_SB_DQ<31>")
	)
	(arc
		(start 143.93926 -293.52621)
		(mid 143.897711 -293.354788)
		(end 143.782288 -293.22141)
		(width 0.0889)
		(layer "In13.Cu")
		(net "M_H_CPU1_SB_DQ<31>")
	)
	(arc
		(start 139.617704 -293.20363)
		(mid 139.334748 -293.279807)
		(end 139.051792 -293.20363)
		(width 0.0889)
		(layer "In13.Cu")
		(net "M_H_CPU1_SB_DQ<31>")
	)
	(arc
		(start 141.8717 -293.20363)
		(mid 141.684756 -293.153375)
		(end 141.497812 -293.20363)
		(width 0.0889)
		(layer "In13.Cu")
		(net "M_H_CPU1_SB_DQ<31>")
	)
	(arc
		(start 140.557758 -293.20363)
		(mid 140.274802 -293.279807)
		(end 139.991846 -293.20363)
		(width 0.0889)
		(layer "In13.Cu")
		(net "M_H_CPU1_SB_DQ<31>")
	)
	(arc
		(start 138.103356 -293.198804)
		(mid 137.919848 -293.15331)
		(end 137.737596 -293.20363)
		(width 0.0889)
		(layer "In13.Cu")
		(net "M_H_CPU1_SB_DQ<31>")
	)
	(segment
		(start 136.047988 -292.450266)
		(end 136.51484 -292.716204)
		(width 0.10668)
		(layer "F.Cu")
		(net "M_H_CPU1_SB_DQ<30>")
	)
	(segment
		(start 171.547028 -316.760352)
		(end 171.112434 -316.760352)
		(width 0.14478)
		(layer "In13.Cu")
		(net "M_H_CPU1_SB_DQ<30>")
	)
	(segment
		(start 149.52853 -305.416966)
		(end 149.366986 -305.255422)
		(width 0.14478)
		(layer "In13.Cu")
		(net "M_H_CPU1_SB_DQ<30>")
	)
	(segment
		(start 147.786344 -304.4952)
		(end 147.786344 -304.2666)
		(width 0.14478)
		(layer "In13.Cu")
		(net "M_H_CPU1_SB_DQ<30>")
	)
	(segment
		(start 136.383014 -292.367462)
		(end 136.360662 -292.450774)
		(width 0.0889)
		(layer "In13.Cu")
		(net "M_H_CPU1_SB_DQ<30>")
	)
	(segment
		(start 169.314114 -316.906656)
		(end 169.314114 -316.905132)
		(width 0.14478)
		(layer "In13.Cu")
		(net "M_H_CPU1_SB_DQ<30>")
	)
	(segment
		(start 150.147274 -306.03571)
		(end 149.918674 -306.03571)
		(width 0.14478)
		(layer "In13.Cu")
		(net "M_H_CPU1_SB_DQ<30>")
	)
	(segment
		(start 148.728176 -305.437032)
		(end 148.566632 -305.275488)
		(width 0.14478)
		(layer "In13.Cu")
		(net "M_H_CPU1_SB_DQ<30>")
	)
	(segment
		(start 150.127208 -306.607464)
		(end 150.308818 -306.425854)
		(width 0.14478)
		(layer "In13.Cu")
		(net "M_H_CPU1_SB_DQ<30>")
	)
	(segment
		(start 144.722342 -293.22141)
		(end 144.652746 -293.18077)
		(width 0.0889)
		(layer "In13.Cu")
		(net "M_H_CPU1_SB_DQ<30>")
	)
	(segment
		(start 141.4018 -292.393624)
		(end 141.393418 -292.388798)
		(width 0.0889)
		(layer "In13.Cu")
		(net "M_H_CPU1_SB_DQ<30>")
	)
	(segment
		(start 151.089106 -307.206142)
		(end 151.089106 -306.977542)
		(width 0.14478)
		(layer "In13.Cu")
		(net "M_H_CPU1_SB_DQ<30>")
	)
	(segment
		(start 149.918674 -306.03571)
		(end 149.737064 -306.21732)
		(width 0.14478)
		(layer "In13.Cu")
		(net "M_H_CPU1_SB_DQ<30>")
	)
	(segment
		(start 149.52853 -305.645566)
		(end 149.52853 -305.416966)
		(width 0.14478)
		(layer "In13.Cu")
		(net "M_H_CPU1_SB_DQ<30>")
	)
	(segment
		(start 148.748242 -304.865278)
		(end 148.748242 -304.636678)
		(width 0.14478)
		(layer "In13.Cu")
		(net "M_H_CPU1_SB_DQ<30>")
	)
	(segment
		(start 169.865294 -316.905132)
		(end 169.865294 -316.906656)
		(width 0.14478)
		(layer "In13.Cu")
		(net "M_H_CPU1_SB_DQ<30>")
	)
	(segment
		(start 147.967954 -304.08499)
		(end 147.967954 -303.85639)
		(width 0.14478)
		(layer "In13.Cu")
		(net "M_H_CPU1_SB_DQ<30>")
	)
	(segment
		(start 168.066974 -316.760352)
		(end 160.871916 -316.760352)
		(width 0.14478)
		(layer "In13.Cu")
		(net "M_H_CPU1_SB_DQ<30>")
	)
	(segment
		(start 145.192242 -294.031416)
		(end 145.122646 -293.990776)
		(width 0.0889)
		(layer "In13.Cu")
		(net "M_H_CPU1_SB_DQ<30>")
	)
	(segment
		(start 170.416474 -316.905132)
		(end 170.271694 -316.760352)
		(width 0.14478)
		(layer "In13.Cu")
		(net "M_H_CPU1_SB_DQ<30>")
	)
	(segment
		(start 146.0246 -296.358818)
		(end 146.0246 -295.648888)
		(width 0.0889)
		(layer "In13.Cu")
		(net "M_H_CPU1_SB_DQ<30>")
	)
	(segment
		(start 168.618154 -317.051436)
		(end 168.356534 -317.051436)
		(width 0.14478)
		(layer "In13.Cu")
		(net "M_H_CPU1_SB_DQ<30>")
	)
	(segment
		(start 145.819368 -295.443656)
		(end 145.819368 -295.146222)
		(width 0.0889)
		(layer "In13.Cu")
		(net "M_H_CPU1_SB_DQ<30>")
	)
	(segment
		(start 150.927562 -306.815998)
		(end 150.698962 -306.815998)
		(width 0.14478)
		(layer "In13.Cu")
		(net "M_H_CPU1_SB_DQ<30>")
	)
	(segment
		(start 149.366986 -305.255422)
		(end 149.138386 -305.255422)
		(width 0.14478)
		(layer "In13.Cu")
		(net "M_H_CPU1_SB_DQ<30>")
	)
	(segment
		(start 150.308818 -306.425854)
		(end 150.308818 -306.197254)
		(width 0.14478)
		(layer "In13.Cu")
		(net "M_H_CPU1_SB_DQ<30>")
	)
	(segment
		(start 168.762934 -316.905132)
		(end 168.762934 -316.906656)
		(width 0.14478)
		(layer "In13.Cu")
		(net "M_H_CPU1_SB_DQ<30>")
	)
	(segment
		(start 168.211754 -316.905132)
		(end 168.066974 -316.760352)
		(width 0.14478)
		(layer "In13.Cu")
		(net "M_H_CPU1_SB_DQ<30>")
	)
	(segment
		(start 149.34692 -305.827176)
		(end 149.52853 -305.645566)
		(width 0.14478)
		(layer "In13.Cu")
		(net "M_H_CPU1_SB_DQ<30>")
	)
	(segment
		(start 170.416474 -316.906656)
		(end 170.416474 -316.905132)
		(width 0.14478)
		(layer "In13.Cu")
		(net "M_H_CPU1_SB_DQ<30>")
	)
	(segment
		(start 170.561254 -317.051436)
		(end 170.416474 -316.906656)
		(width 0.14478)
		(layer "In13.Cu")
		(net "M_H_CPU1_SB_DQ<30>")
	)
	(segment
		(start 148.566632 -305.046888)
		(end 148.748242 -304.865278)
		(width 0.14478)
		(layer "In13.Cu")
		(net "M_H_CPU1_SB_DQ<30>")
	)
	(segment
		(start 148.566632 -305.275488)
		(end 148.566632 -305.046888)
		(width 0.14478)
		(layer "In13.Cu")
		(net "M_H_CPU1_SB_DQ<30>")
	)
	(segment
		(start 150.127208 -306.836064)
		(end 150.127208 -306.607464)
		(width 0.14478)
		(layer "In13.Cu")
		(net "M_H_CPU1_SB_DQ<30>")
	)
	(segment
		(start 170.010074 -316.760352)
		(end 169.865294 -316.905132)
		(width 0.14478)
		(layer "In13.Cu")
		(net "M_H_CPU1_SB_DQ<30>")
	)
	(segment
		(start 151.06904 -307.777896)
		(end 150.907496 -307.616352)
		(width 0.14478)
		(layer "In13.Cu")
		(net "M_H_CPU1_SB_DQ<30>")
	)
	(segment
		(start 150.288752 -306.997608)
		(end 150.127208 -306.836064)
		(width 0.14478)
		(layer "In13.Cu")
		(net "M_H_CPU1_SB_DQ<30>")
	)
	(segment
		(start 148.176488 -304.656744)
		(end 147.947888 -304.656744)
		(width 0.14478)
		(layer "In13.Cu")
		(net "M_H_CPU1_SB_DQ<30>")
	)
	(segment
		(start 136.701784 -292.393624)
		(end 136.693402 -292.388798)
		(width 0.0889)
		(layer "In13.Cu")
		(net "M_H_CPU1_SB_DQ<30>")
	)
	(segment
		(start 148.956776 -305.437032)
		(end 148.728176 -305.437032)
		(width 0.14478)
		(layer "In13.Cu")
		(net "M_H_CPU1_SB_DQ<30>")
	)
	(segment
		(start 137.276078 -292.388798)
		(end 137.267696 -292.393624)
		(width 0.0889)
		(layer "In13.Cu")
		(net "M_H_CPU1_SB_DQ<30>")
	)
	(segment
		(start 147.947888 -304.656744)
		(end 147.786344 -304.4952)
		(width 0.14478)
		(layer "In13.Cu")
		(net "M_H_CPU1_SB_DQ<30>")
	)
	(segment
		(start 169.458894 -317.051436)
		(end 169.314114 -316.906656)
		(width 0.14478)
		(layer "In13.Cu")
		(net "M_H_CPU1_SB_DQ<30>")
	)
	(segment
		(start 140.461746 -292.393624)
		(end 140.453364 -292.388798)
		(width 0.0889)
		(layer "In13.Cu")
		(net "M_H_CPU1_SB_DQ<30>")
	)
	(segment
		(start 171.112434 -316.760352)
		(end 170.967654 -316.905132)
		(width 0.14478)
		(layer "In13.Cu")
		(net "M_H_CPU1_SB_DQ<30>")
	)
	(segment
		(start 149.737064 -306.21732)
		(end 149.508464 -306.21732)
		(width 0.14478)
		(layer "In13.Cu")
		(net "M_H_CPU1_SB_DQ<30>")
	)
	(segment
		(start 169.720514 -317.051436)
		(end 169.458894 -317.051436)
		(width 0.14478)
		(layer "In13.Cu")
		(net "M_H_CPU1_SB_DQ<30>")
	)
	(segment
		(start 150.907496 -307.387752)
		(end 151.089106 -307.206142)
		(width 0.14478)
		(layer "In13.Cu")
		(net "M_H_CPU1_SB_DQ<30>")
	)
	(segment
		(start 141.976094 -292.388798)
		(end 141.967712 -292.393624)
		(width 0.0889)
		(layer "In13.Cu")
		(net "M_H_CPU1_SB_DQ<30>")
	)
	(segment
		(start 170.967654 -316.905132)
		(end 170.967654 -316.906656)
		(width 0.14478)
		(layer "In13.Cu")
		(net "M_H_CPU1_SB_DQ<30>")
	)
	(segment
		(start 136.360662 -292.450774)
		(end 136.51484 -292.716204)
		(width 0.0889)
		(layer "In13.Cu")
		(net "M_H_CPU1_SB_DQ<30>")
	)
	(segment
		(start 160.871916 -316.760352)
		(end 151.70785 -307.596286)
		(width 0.14478)
		(layer "In13.Cu")
		(net "M_H_CPU1_SB_DQ<30>")
	)
	(segment
		(start 151.47925 -307.596286)
		(end 151.29764 -307.777896)
		(width 0.14478)
		(layer "In13.Cu")
		(net "M_H_CPU1_SB_DQ<30>")
	)
	(segment
		(start 150.698962 -306.815998)
		(end 150.517352 -306.997608)
		(width 0.14478)
		(layer "In13.Cu")
		(net "M_H_CPU1_SB_DQ<30>")
	)
	(segment
		(start 168.762934 -316.906656)
		(end 168.618154 -317.051436)
		(width 0.14478)
		(layer "In13.Cu")
		(net "M_H_CPU1_SB_DQ<30>")
	)
	(segment
		(start 138.216132 -292.388798)
		(end 138.20775 -292.393624)
		(width 0.0889)
		(layer "In13.Cu")
		(net "M_H_CPU1_SB_DQ<30>")
	)
	(segment
		(start 146.0246 -301.913036)
		(end 146.0246 -296.358818)
		(width 0.14478)
		(layer "In13.Cu")
		(net "M_H_CPU1_SB_DQ<30>")
	)
	(segment
		(start 168.356534 -317.051436)
		(end 168.211754 -316.906656)
		(width 0.14478)
		(layer "In13.Cu")
		(net "M_H_CPU1_SB_DQ<30>")
	)
	(segment
		(start 147.786344 -304.2666)
		(end 147.967954 -304.08499)
		(width 0.14478)
		(layer "In13.Cu")
		(net "M_H_CPU1_SB_DQ<30>")
	)
	(segment
		(start 169.169334 -316.760352)
		(end 168.907714 -316.760352)
		(width 0.14478)
		(layer "In13.Cu")
		(net "M_H_CPU1_SB_DQ<30>")
	)
	(segment
		(start 150.517352 -306.997608)
		(end 150.288752 -306.997608)
		(width 0.14478)
		(layer "In13.Cu")
		(net "M_H_CPU1_SB_DQ<30>")
	)
	(segment
		(start 170.822874 -317.051436)
		(end 170.561254 -317.051436)
		(width 0.14478)
		(layer "In13.Cu")
		(net "M_H_CPU1_SB_DQ<30>")
	)
	(segment
		(start 149.138386 -305.255422)
		(end 148.956776 -305.437032)
		(width 0.14478)
		(layer "In13.Cu")
		(net "M_H_CPU1_SB_DQ<30>")
	)
	(segment
		(start 168.211754 -316.906656)
		(end 168.211754 -316.905132)
		(width 0.14478)
		(layer "In13.Cu")
		(net "M_H_CPU1_SB_DQ<30>")
	)
	(segment
		(start 148.748242 -304.636678)
		(end 148.586698 -304.475134)
		(width 0.14478)
		(layer "In13.Cu")
		(net "M_H_CPU1_SB_DQ<30>")
	)
	(segment
		(start 144.252442 -292.411404)
		(end 144.221962 -292.393624)
		(width 0.0889)
		(layer "In13.Cu")
		(net "M_H_CPU1_SB_DQ<30>")
	)
	(segment
		(start 151.70785 -307.596286)
		(end 151.47925 -307.596286)
		(width 0.14478)
		(layer "In13.Cu")
		(net "M_H_CPU1_SB_DQ<30>")
	)
	(segment
		(start 168.907714 -316.760352)
		(end 168.762934 -316.905132)
		(width 0.14478)
		(layer "In13.Cu")
		(net "M_H_CPU1_SB_DQ<30>")
	)
	(segment
		(start 171.97197 -316.33541)
		(end 171.547028 -316.760352)
		(width 0.14478)
		(layer "In13.Cu")
		(net "M_H_CPU1_SB_DQ<30>")
	)
	(segment
		(start 148.358098 -304.475134)
		(end 148.176488 -304.656744)
		(width 0.14478)
		(layer "In13.Cu")
		(net "M_H_CPU1_SB_DQ<30>")
	)
	(segment
		(start 150.308818 -306.197254)
		(end 150.147274 -306.03571)
		(width 0.14478)
		(layer "In13.Cu")
		(net "M_H_CPU1_SB_DQ<30>")
	)
	(segment
		(start 151.089106 -306.977542)
		(end 150.927562 -306.815998)
		(width 0.14478)
		(layer "In13.Cu")
		(net "M_H_CPU1_SB_DQ<30>")
	)
	(segment
		(start 145.663412 -294.84193)
		(end 145.592546 -294.800782)
		(width 0.0889)
		(layer "In13.Cu")
		(net "M_H_CPU1_SB_DQ<30>")
	)
	(segment
		(start 170.967654 -316.906656)
		(end 170.822874 -317.051436)
		(width 0.14478)
		(layer "In13.Cu")
		(net "M_H_CPU1_SB_DQ<30>")
	)
	(segment
		(start 150.907496 -307.616352)
		(end 150.907496 -307.387752)
		(width 0.14478)
		(layer "In13.Cu")
		(net "M_H_CPU1_SB_DQ<30>")
	)
	(segment
		(start 149.34692 -306.055776)
		(end 149.34692 -305.827176)
		(width 0.14478)
		(layer "In13.Cu")
		(net "M_H_CPU1_SB_DQ<30>")
	)
	(segment
		(start 148.586698 -304.475134)
		(end 148.358098 -304.475134)
		(width 0.14478)
		(layer "In13.Cu")
		(net "M_H_CPU1_SB_DQ<30>")
	)
	(segment
		(start 147.967954 -303.85639)
		(end 146.0246 -301.913036)
		(width 0.14478)
		(layer "In13.Cu")
		(net "M_H_CPU1_SB_DQ<30>")
	)
	(segment
		(start 170.271694 -316.760352)
		(end 170.010074 -316.760352)
		(width 0.14478)
		(layer "In13.Cu")
		(net "M_H_CPU1_SB_DQ<30>")
	)
	(segment
		(start 169.314114 -316.905132)
		(end 169.169334 -316.760352)
		(width 0.14478)
		(layer "In13.Cu")
		(net "M_H_CPU1_SB_DQ<30>")
	)
	(segment
		(start 151.29764 -307.777896)
		(end 151.06904 -307.777896)
		(width 0.14478)
		(layer "In13.Cu")
		(net "M_H_CPU1_SB_DQ<30>")
	)
	(segment
		(start 146.0246 -295.648888)
		(end 145.819368 -295.443656)
		(width 0.0889)
		(layer "In13.Cu")
		(net "M_H_CPU1_SB_DQ<30>")
	)
	(segment
		(start 169.865294 -316.906656)
		(end 169.720514 -317.051436)
		(width 0.14478)
		(layer "In13.Cu")
		(net "M_H_CPU1_SB_DQ<30>")
	)
	(segment
		(start 149.508464 -306.21732)
		(end 149.34692 -306.055776)
		(width 0.14478)
		(layer "In13.Cu")
		(net "M_H_CPU1_SB_DQ<30>")
	)
	(arc
		(start 145.819368 -295.146222)
		(mid 145.778113 -294.975251)
		(end 145.663412 -294.84193)
		(width 0.0889)
		(layer "In13.Cu")
		(net "M_H_CPU1_SB_DQ<30>")
	)
	(arc
		(start 141.967712 -292.393624)
		(mid 141.684756 -292.469801)
		(end 141.4018 -292.393624)
		(width 0.0889)
		(layer "In13.Cu")
		(net "M_H_CPU1_SB_DQ<30>")
	)
	(arc
		(start 141.393418 -292.388798)
		(mid 141.20991 -292.343304)
		(end 141.027658 -292.393624)
		(width 0.0889)
		(layer "In13.Cu")
		(net "M_H_CPU1_SB_DQ<30>")
	)
	(arc
		(start 144.879314 -293.52621)
		(mid 144.837765 -293.354788)
		(end 144.722342 -293.22141)
		(width 0.0889)
		(layer "In13.Cu")
		(net "M_H_CPU1_SB_DQ<30>")
	)
	(arc
		(start 136.693402 -292.388798)
		(mid 136.540532 -292.344157)
		(end 136.383014 -292.367462)
		(width 0.0889)
		(layer "In13.Cu")
		(net "M_H_CPU1_SB_DQ<30>")
	)
	(arc
		(start 138.20775 -292.393624)
		(mid 137.924794 -292.469801)
		(end 137.641838 -292.393624)
		(width 0.0889)
		(layer "In13.Cu")
		(net "M_H_CPU1_SB_DQ<30>")
	)
	(arc
		(start 143.281654 -292.393624)
		(mid 143.09471 -292.343369)
		(end 142.907766 -292.393624)
		(width 0.0889)
		(layer "In13.Cu")
		(net "M_H_CPU1_SB_DQ<30>")
	)
	(arc
		(start 142.341854 -292.393624)
		(mid 142.159603 -292.343274)
		(end 141.976094 -292.388798)
		(width 0.0889)
		(layer "In13.Cu")
		(net "M_H_CPU1_SB_DQ<30>")
	)
	(arc
		(start 143.847566 -292.393624)
		(mid 143.56461 -292.469801)
		(end 143.281654 -292.393624)
		(width 0.0889)
		(layer "In13.Cu")
		(net "M_H_CPU1_SB_DQ<30>")
	)
	(arc
		(start 145.592546 -294.800782)
		(mid 145.413733 -294.598432)
		(end 145.349214 -294.336216)
		(width 0.0889)
		(layer "In13.Cu")
		(net "M_H_CPU1_SB_DQ<30>")
	)
	(arc
		(start 145.122646 -293.990776)
		(mid 144.943833 -293.788426)
		(end 144.879314 -293.52621)
		(width 0.0889)
		(layer "In13.Cu")
		(net "M_H_CPU1_SB_DQ<30>")
	)
	(arc
		(start 137.641838 -292.393624)
		(mid 137.459587 -292.343274)
		(end 137.276078 -292.388798)
		(width 0.0889)
		(layer "In13.Cu")
		(net "M_H_CPU1_SB_DQ<30>")
	)
	(arc
		(start 142.907766 -292.393624)
		(mid 142.62481 -292.469801)
		(end 142.341854 -292.393624)
		(width 0.0889)
		(layer "In13.Cu")
		(net "M_H_CPU1_SB_DQ<30>")
	)
	(arc
		(start 144.652746 -293.18077)
		(mid 144.473933 -292.97842)
		(end 144.409414 -292.716204)
		(width 0.0889)
		(layer "In13.Cu")
		(net "M_H_CPU1_SB_DQ<30>")
	)
	(arc
		(start 141.027658 -292.393624)
		(mid 140.744702 -292.469801)
		(end 140.461746 -292.393624)
		(width 0.0889)
		(layer "In13.Cu")
		(net "M_H_CPU1_SB_DQ<30>")
	)
	(arc
		(start 139.147804 -292.393624)
		(mid 138.864848 -292.469801)
		(end 138.581892 -292.393624)
		(width 0.0889)
		(layer "In13.Cu")
		(net "M_H_CPU1_SB_DQ<30>")
	)
	(arc
		(start 144.409414 -292.716204)
		(mid 144.367865 -292.544782)
		(end 144.252442 -292.411404)
		(width 0.0889)
		(layer "In13.Cu")
		(net "M_H_CPU1_SB_DQ<30>")
	)
	(arc
		(start 144.221962 -292.393624)
		(mid 144.034764 -292.343242)
		(end 143.847566 -292.393624)
		(width 0.0889)
		(layer "In13.Cu")
		(net "M_H_CPU1_SB_DQ<30>")
	)
	(arc
		(start 140.453364 -292.388798)
		(mid 140.269856 -292.343304)
		(end 140.087604 -292.393624)
		(width 0.0889)
		(layer "In13.Cu")
		(net "M_H_CPU1_SB_DQ<30>")
	)
	(arc
		(start 137.267696 -292.393624)
		(mid 136.98474 -292.469801)
		(end 136.701784 -292.393624)
		(width 0.0889)
		(layer "In13.Cu")
		(net "M_H_CPU1_SB_DQ<30>")
	)
	(arc
		(start 145.349214 -294.336216)
		(mid 145.307665 -294.164794)
		(end 145.192242 -294.031416)
		(width 0.0889)
		(layer "In13.Cu")
		(net "M_H_CPU1_SB_DQ<30>")
	)
	(arc
		(start 139.521692 -292.393624)
		(mid 139.334748 -292.343369)
		(end 139.147804 -292.393624)
		(width 0.0889)
		(layer "In13.Cu")
		(net "M_H_CPU1_SB_DQ<30>")
	)
	(arc
		(start 140.087604 -292.393624)
		(mid 139.804648 -292.469801)
		(end 139.521692 -292.393624)
		(width 0.0889)
		(layer "In13.Cu")
		(net "M_H_CPU1_SB_DQ<30>")
	)
	(arc
		(start 138.581892 -292.393624)
		(mid 138.399641 -292.343274)
		(end 138.216132 -292.388798)
		(width 0.0889)
		(layer "In13.Cu")
		(net "M_H_CPU1_SB_DQ<30>")
	)
	(segment
		(start 136.047988 -274.630388)
		(end 136.51484 -274.896326)
		(width 0.10668)
		(layer "F.Cu")
		(net "M_H_CPU1_SB_DQ<2>")
	)
	(segment
		(start 161.7345 -280.576528)
		(end 161.530284 -280.576782)
		(width 0.14478)
		(layer "In13.Cu")
		(net "M_H_CPU1_SB_DQ<2>")
	)
	(segment
		(start 136.360662 -274.630896)
		(end 136.51484 -274.896326)
		(width 0.0889)
		(layer "In13.Cu")
		(net "M_H_CPU1_SB_DQ<2>")
	)
	(segment
		(start 162.904424 -281.746198)
		(end 163.143184 -281.507438)
		(width 0.14478)
		(layer "In13.Cu")
		(net "M_H_CPU1_SB_DQ<2>")
	)
	(segment
		(start 164.163248 -282.539186)
		(end 164.163248 -282.61564)
		(width 0.14478)
		(layer "In13.Cu")
		(net "M_H_CPU1_SB_DQ<2>")
	)
	(segment
		(start 171.97197 -282.335224)
		(end 171.97197 -282.36545)
		(width 0.14478)
		(layer "In13.Cu")
		(net "M_H_CPU1_SB_DQ<2>")
	)
	(segment
		(start 165.961568 -282.76042)
		(end 165.816788 -282.61564)
		(width 0.14478)
		(layer "In13.Cu")
		(net "M_H_CPU1_SB_DQ<2>")
	)
	(segment
		(start 141.4018 -274.573746)
		(end 141.393418 -274.56892)
		(width 0.0889)
		(layer "In13.Cu")
		(net "M_H_CPU1_SB_DQ<2>")
	)
	(segment
		(start 171.97197 -282.36545)
		(end 171.577 -282.76042)
		(width 0.14478)
		(layer "In13.Cu")
		(net "M_H_CPU1_SB_DQ<2>")
	)
	(segment
		(start 160.565084 -279.406858)
		(end 160.803844 -279.168098)
		(width 0.14478)
		(layer "In13.Cu")
		(net "M_H_CPU1_SB_DQ<2>")
	)
	(segment
		(start 145.81886 -274.583144)
		(end 145.640044 -274.650454)
		(width 0.0889)
		(layer "In13.Cu")
		(net "M_H_CPU1_SB_DQ<2>")
	)
	(segment
		(start 168.16197 -281.53614)
		(end 168.01719 -281.68092)
		(width 0.14478)
		(layer "In13.Cu")
		(net "M_H_CPU1_SB_DQ<2>")
	)
	(segment
		(start 161.58337 -279.743154)
		(end 161.398204 -279.557988)
		(width 0.14478)
		(layer "In13.Cu")
		(net "M_H_CPU1_SB_DQ<2>")
	)
	(segment
		(start 161.344864 -280.186638)
		(end 161.583624 -279.947878)
		(width 0.14478)
		(layer "In13.Cu")
		(net "M_H_CPU1_SB_DQ<2>")
	)
	(segment
		(start 162.957764 -281.117548)
		(end 162.75304 -281.117548)
		(width 0.14478)
		(layer "In13.Cu")
		(net "M_H_CPU1_SB_DQ<2>")
	)
	(segment
		(start 160.750504 -279.797002)
		(end 160.565084 -279.611582)
		(width 0.14478)
		(layer "In13.Cu")
		(net "M_H_CPU1_SB_DQ<2>")
	)
	(segment
		(start 161.97326 -280.337768)
		(end 161.7345 -280.576528)
		(width 0.14478)
		(layer "In13.Cu")
		(net "M_H_CPU1_SB_DQ<2>")
	)
	(segment
		(start 160.803844 -279.168098)
		(end 160.80359 -278.963374)
		(width 0.14478)
		(layer "In13.Cu")
		(net "M_H_CPU1_SB_DQ<2>")
	)
	(segment
		(start 161.344864 -280.391362)
		(end 161.344864 -280.186638)
		(width 0.14478)
		(layer "In13.Cu")
		(net "M_H_CPU1_SB_DQ<2>")
	)
	(segment
		(start 161.398204 -279.557988)
		(end 161.19348 -279.557988)
		(width 0.14478)
		(layer "In13.Cu")
		(net "M_H_CPU1_SB_DQ<2>")
	)
	(segment
		(start 162.124644 -281.171142)
		(end 162.124644 -280.966418)
		(width 0.14478)
		(layer "In13.Cu")
		(net "M_H_CPU1_SB_DQ<2>")
	)
	(segment
		(start 170.18254 -281.910282)
		(end 169.81551 -281.910282)
		(width 0.14478)
		(layer "In13.Cu")
		(net "M_H_CPU1_SB_DQ<2>")
	)
	(segment
		(start 164.714428 -282.539186)
		(end 164.569648 -282.394406)
		(width 0.14478)
		(layer "In13.Cu")
		(net "M_H_CPU1_SB_DQ<2>")
	)
	(segment
		(start 164.308028 -282.394406)
		(end 164.163248 -282.539186)
		(width 0.14478)
		(layer "In13.Cu")
		(net "M_H_CPU1_SB_DQ<2>")
	)
	(segment
		(start 160.80359 -278.963374)
		(end 160.618424 -278.778208)
		(width 0.14478)
		(layer "In13.Cu")
		(net "M_H_CPU1_SB_DQ<2>")
	)
	(segment
		(start 165.816788 -282.539186)
		(end 165.672008 -282.394406)
		(width 0.14478)
		(layer "In13.Cu")
		(net "M_H_CPU1_SB_DQ<2>")
	)
	(segment
		(start 162.363404 -280.727658)
		(end 162.36315 -280.522934)
		(width 0.14478)
		(layer "In13.Cu")
		(net "M_H_CPU1_SB_DQ<2>")
	)
	(segment
		(start 168.01719 -281.68092)
		(end 168.01719 -281.765502)
		(width 0.14478)
		(layer "In13.Cu")
		(net "M_H_CPU1_SB_DQ<2>")
	)
	(segment
		(start 162.75304 -281.117548)
		(end 162.51428 -281.356308)
		(width 0.14478)
		(layer "In13.Cu")
		(net "M_H_CPU1_SB_DQ<2>")
	)
	(segment
		(start 169.81551 -281.910282)
		(end 169.67073 -281.765502)
		(width 0.14478)
		(layer "In13.Cu")
		(net "M_H_CPU1_SB_DQ<2>")
	)
	(segment
		(start 137.276078 -274.56892)
		(end 137.267696 -274.573746)
		(width 0.0889)
		(layer "In13.Cu")
		(net "M_H_CPU1_SB_DQ<2>")
	)
	(segment
		(start 161.583624 -279.947878)
		(end 161.58337 -279.743154)
		(width 0.14478)
		(layer "In13.Cu")
		(net "M_H_CPU1_SB_DQ<2>")
	)
	(segment
		(start 138.216132 -274.56892)
		(end 138.20775 -274.573746)
		(width 0.0889)
		(layer "In13.Cu")
		(net "M_H_CPU1_SB_DQ<2>")
	)
	(segment
		(start 164.163248 -282.61564)
		(end 164.018468 -282.76042)
		(width 0.14478)
		(layer "In13.Cu")
		(net "M_H_CPU1_SB_DQ<2>")
	)
	(segment
		(start 145.640044 -274.650454)
		(end 145.444718 -274.650454)
		(width 0.0889)
		(layer "In13.Cu")
		(net "M_H_CPU1_SB_DQ<2>")
	)
	(segment
		(start 162.36315 -280.522934)
		(end 162.177984 -280.337768)
		(width 0.14478)
		(layer "In13.Cu")
		(net "M_H_CPU1_SB_DQ<2>")
	)
	(segment
		(start 171.032678 -282.76042)
		(end 170.18254 -281.910282)
		(width 0.14478)
		(layer "In13.Cu")
		(net "M_H_CPU1_SB_DQ<2>")
	)
	(segment
		(start 164.859208 -282.76042)
		(end 164.714428 -282.61564)
		(width 0.14478)
		(layer "In13.Cu")
		(net "M_H_CPU1_SB_DQ<2>")
	)
	(segment
		(start 167.000174 -281.910282)
		(end 166.150036 -282.76042)
		(width 0.14478)
		(layer "In13.Cu")
		(net "M_H_CPU1_SB_DQ<2>")
	)
	(segment
		(start 165.672008 -282.394406)
		(end 165.410388 -282.394406)
		(width 0.14478)
		(layer "In13.Cu")
		(net "M_H_CPU1_SB_DQ<2>")
	)
	(segment
		(start 169.26433 -281.53614)
		(end 169.11955 -281.68092)
		(width 0.14478)
		(layer "In13.Cu")
		(net "M_H_CPU1_SB_DQ<2>")
	)
	(segment
		(start 162.904424 -281.950922)
		(end 162.904424 -281.746198)
		(width 0.14478)
		(layer "In13.Cu")
		(net "M_H_CPU1_SB_DQ<2>")
	)
	(segment
		(start 169.11955 -281.765502)
		(end 168.97477 -281.910282)
		(width 0.14478)
		(layer "In13.Cu")
		(net "M_H_CPU1_SB_DQ<2>")
	)
	(segment
		(start 165.120828 -282.76042)
		(end 164.859208 -282.76042)
		(width 0.14478)
		(layer "In13.Cu")
		(net "M_H_CPU1_SB_DQ<2>")
	)
	(segment
		(start 164.018468 -282.76042)
		(end 163.713922 -282.76042)
		(width 0.14478)
		(layer "In13.Cu")
		(net "M_H_CPU1_SB_DQ<2>")
	)
	(segment
		(start 167.87241 -281.910282)
		(end 167.000174 -281.910282)
		(width 0.14478)
		(layer "In13.Cu")
		(net "M_H_CPU1_SB_DQ<2>")
	)
	(segment
		(start 168.97477 -281.910282)
		(end 168.71315 -281.910282)
		(width 0.14478)
		(layer "In13.Cu")
		(net "M_H_CPU1_SB_DQ<2>")
	)
	(segment
		(start 169.67073 -281.68092)
		(end 169.52595 -281.53614)
		(width 0.14478)
		(layer "In13.Cu")
		(net "M_H_CPU1_SB_DQ<2>")
	)
	(segment
		(start 168.56837 -281.765502)
		(end 168.56837 -281.68092)
		(width 0.14478)
		(layer "In13.Cu")
		(net "M_H_CPU1_SB_DQ<2>")
	)
	(segment
		(start 160.4137 -278.778208)
		(end 160.17494 -279.016968)
		(width 0.14478)
		(layer "In13.Cu")
		(net "M_H_CPU1_SB_DQ<2>")
	)
	(segment
		(start 146.75612 -273.645884)
		(end 145.81886 -274.583144)
		(width 0.0889)
		(layer "In13.Cu")
		(net "M_H_CPU1_SB_DQ<2>")
	)
	(segment
		(start 163.143184 -281.507438)
		(end 163.14293 -281.302714)
		(width 0.14478)
		(layer "In13.Cu")
		(net "M_H_CPU1_SB_DQ<2>")
	)
	(segment
		(start 166.150036 -282.76042)
		(end 165.961568 -282.76042)
		(width 0.14478)
		(layer "In13.Cu")
		(net "M_H_CPU1_SB_DQ<2>")
	)
	(segment
		(start 144.242536 -274.586446)
		(end 144.220946 -274.574)
		(width 0.0889)
		(layer "In13.Cu")
		(net "M_H_CPU1_SB_DQ<2>")
	)
	(segment
		(start 163.14293 -281.302714)
		(end 162.957764 -281.117548)
		(width 0.14478)
		(layer "In13.Cu")
		(net "M_H_CPU1_SB_DQ<2>")
	)
	(segment
		(start 154.347926 -273.394424)
		(end 148.048218 -273.394424)
		(width 0.14478)
		(layer "In13.Cu")
		(net "M_H_CPU1_SB_DQ<2>")
	)
	(segment
		(start 160.565084 -279.611582)
		(end 160.565084 -279.406858)
		(width 0.14478)
		(layer "In13.Cu")
		(net "M_H_CPU1_SB_DQ<2>")
	)
	(segment
		(start 144.80413 -274.562824)
		(end 144.785334 -274.573746)
		(width 0.0889)
		(layer "In13.Cu")
		(net "M_H_CPU1_SB_DQ<2>")
	)
	(segment
		(start 165.816788 -282.61564)
		(end 165.816788 -282.539186)
		(width 0.14478)
		(layer "In13.Cu")
		(net "M_H_CPU1_SB_DQ<2>")
	)
	(segment
		(start 165.265608 -282.61564)
		(end 165.120828 -282.76042)
		(width 0.14478)
		(layer "In13.Cu")
		(net "M_H_CPU1_SB_DQ<2>")
	)
	(segment
		(start 136.383014 -274.547584)
		(end 136.360662 -274.630896)
		(width 0.0889)
		(layer "In13.Cu")
		(net "M_H_CPU1_SB_DQ<2>")
	)
	(segment
		(start 136.701784 -274.573746)
		(end 136.693402 -274.56892)
		(width 0.0889)
		(layer "In13.Cu")
		(net "M_H_CPU1_SB_DQ<2>")
	)
	(segment
		(start 160.618424 -278.778208)
		(end 160.4137 -278.778208)
		(width 0.14478)
		(layer "In13.Cu")
		(net "M_H_CPU1_SB_DQ<2>")
	)
	(segment
		(start 140.461746 -274.573746)
		(end 140.453364 -274.56892)
		(width 0.0889)
		(layer "In13.Cu")
		(net "M_H_CPU1_SB_DQ<2>")
	)
	(segment
		(start 169.67073 -281.765502)
		(end 169.67073 -281.68092)
		(width 0.14478)
		(layer "In13.Cu")
		(net "M_H_CPU1_SB_DQ<2>")
	)
	(segment
		(start 165.265608 -282.539186)
		(end 165.265608 -282.61564)
		(width 0.14478)
		(layer "In13.Cu")
		(net "M_H_CPU1_SB_DQ<2>")
	)
	(segment
		(start 141.976094 -274.56892)
		(end 141.967712 -274.573746)
		(width 0.0889)
		(layer "In13.Cu")
		(net "M_H_CPU1_SB_DQ<2>")
	)
	(segment
		(start 168.56837 -281.68092)
		(end 168.42359 -281.53614)
		(width 0.14478)
		(layer "In13.Cu")
		(net "M_H_CPU1_SB_DQ<2>")
	)
	(segment
		(start 168.71315 -281.910282)
		(end 168.56837 -281.765502)
		(width 0.14478)
		(layer "In13.Cu")
		(net "M_H_CPU1_SB_DQ<2>")
	)
	(segment
		(start 162.51428 -281.356308)
		(end 162.310064 -281.356562)
		(width 0.14478)
		(layer "In13.Cu")
		(net "M_H_CPU1_SB_DQ<2>")
	)
	(segment
		(start 162.124644 -280.966418)
		(end 162.363404 -280.727658)
		(width 0.14478)
		(layer "In13.Cu")
		(net "M_H_CPU1_SB_DQ<2>")
	)
	(segment
		(start 169.11955 -281.68092)
		(end 169.11955 -281.765502)
		(width 0.14478)
		(layer "In13.Cu")
		(net "M_H_CPU1_SB_DQ<2>")
	)
	(segment
		(start 164.569648 -282.394406)
		(end 164.308028 -282.394406)
		(width 0.14478)
		(layer "In13.Cu")
		(net "M_H_CPU1_SB_DQ<2>")
	)
	(segment
		(start 147.297648 -273.645884)
		(end 146.75612 -273.645884)
		(width 0.0889)
		(layer "In13.Cu")
		(net "M_H_CPU1_SB_DQ<2>")
	)
	(segment
		(start 160.17494 -279.016968)
		(end 159.970724 -279.017222)
		(width 0.14478)
		(layer "In13.Cu")
		(net "M_H_CPU1_SB_DQ<2>")
	)
	(segment
		(start 162.177984 -280.337768)
		(end 161.97326 -280.337768)
		(width 0.14478)
		(layer "In13.Cu")
		(net "M_H_CPU1_SB_DQ<2>")
	)
	(segment
		(start 168.01719 -281.765502)
		(end 167.87241 -281.910282)
		(width 0.14478)
		(layer "In13.Cu")
		(net "M_H_CPU1_SB_DQ<2>")
	)
	(segment
		(start 144.220946 -274.574)
		(end 144.20088 -274.56257)
		(width 0.0889)
		(layer "In13.Cu")
		(net "M_H_CPU1_SB_DQ<2>")
	)
	(segment
		(start 162.310064 -281.356562)
		(end 162.124644 -281.171142)
		(width 0.14478)
		(layer "In13.Cu")
		(net "M_H_CPU1_SB_DQ<2>")
	)
	(segment
		(start 163.713922 -282.76042)
		(end 162.904424 -281.950922)
		(width 0.14478)
		(layer "In13.Cu")
		(net "M_H_CPU1_SB_DQ<2>")
	)
	(segment
		(start 171.577 -282.76042)
		(end 171.032678 -282.76042)
		(width 0.14478)
		(layer "In13.Cu")
		(net "M_H_CPU1_SB_DQ<2>")
	)
	(segment
		(start 160.95472 -279.796748)
		(end 160.750504 -279.797002)
		(width 0.14478)
		(layer "In13.Cu")
		(net "M_H_CPU1_SB_DQ<2>")
	)
	(segment
		(start 164.714428 -282.61564)
		(end 164.714428 -282.539186)
		(width 0.14478)
		(layer "In13.Cu")
		(net "M_H_CPU1_SB_DQ<2>")
	)
	(segment
		(start 168.42359 -281.53614)
		(end 168.16197 -281.53614)
		(width 0.14478)
		(layer "In13.Cu")
		(net "M_H_CPU1_SB_DQ<2>")
	)
	(segment
		(start 161.530284 -280.576782)
		(end 161.344864 -280.391362)
		(width 0.14478)
		(layer "In13.Cu")
		(net "M_H_CPU1_SB_DQ<2>")
	)
	(segment
		(start 161.19348 -279.557988)
		(end 160.95472 -279.796748)
		(width 0.14478)
		(layer "In13.Cu")
		(net "M_H_CPU1_SB_DQ<2>")
	)
	(segment
		(start 147.549108 -273.394424)
		(end 147.297648 -273.645884)
		(width 0.0889)
		(layer "In13.Cu")
		(net "M_H_CPU1_SB_DQ<2>")
	)
	(segment
		(start 148.048218 -273.394424)
		(end 147.549108 -273.394424)
		(width 0.0889)
		(layer "In13.Cu")
		(net "M_H_CPU1_SB_DQ<2>")
	)
	(segment
		(start 165.410388 -282.394406)
		(end 165.265608 -282.539186)
		(width 0.14478)
		(layer "In13.Cu")
		(net "M_H_CPU1_SB_DQ<2>")
	)
	(segment
		(start 169.52595 -281.53614)
		(end 169.26433 -281.53614)
		(width 0.14478)
		(layer "In13.Cu")
		(net "M_H_CPU1_SB_DQ<2>")
	)
	(segment
		(start 159.970724 -279.017222)
		(end 154.347926 -273.394424)
		(width 0.14478)
		(layer "In13.Cu")
		(net "M_H_CPU1_SB_DQ<2>")
	)
	(arc
		(start 136.693402 -274.56892)
		(mid 136.540532 -274.524279)
		(end 136.383014 -274.547584)
		(width 0.0889)
		(layer "In13.Cu")
		(net "M_H_CPU1_SB_DQ<2>")
	)
	(arc
		(start 139.147804 -274.573746)
		(mid 138.864848 -274.649923)
		(end 138.581892 -274.573746)
		(width 0.0889)
		(layer "In13.Cu")
		(net "M_H_CPU1_SB_DQ<2>")
	)
	(arc
		(start 139.521692 -274.573746)
		(mid 139.334748 -274.523491)
		(end 139.147804 -274.573746)
		(width 0.0889)
		(layer "In13.Cu")
		(net "M_H_CPU1_SB_DQ<2>")
	)
	(arc
		(start 142.907766 -274.573746)
		(mid 142.62481 -274.649923)
		(end 142.341854 -274.573746)
		(width 0.0889)
		(layer "In13.Cu")
		(net "M_H_CPU1_SB_DQ<2>")
	)
	(arc
		(start 138.581892 -274.573746)
		(mid 138.399641 -274.523396)
		(end 138.216132 -274.56892)
		(width 0.0889)
		(layer "In13.Cu")
		(net "M_H_CPU1_SB_DQ<2>")
	)
	(arc
		(start 140.087604 -274.573746)
		(mid 139.804648 -274.649923)
		(end 139.521692 -274.573746)
		(width 0.0889)
		(layer "In13.Cu")
		(net "M_H_CPU1_SB_DQ<2>")
	)
	(arc
		(start 137.641838 -274.573746)
		(mid 137.459587 -274.523396)
		(end 137.276078 -274.56892)
		(width 0.0889)
		(layer "In13.Cu")
		(net "M_H_CPU1_SB_DQ<2>")
	)
	(arc
		(start 145.444718 -274.650454)
		(mid 145.297509 -274.630977)
		(end 145.160492 -274.573746)
		(width 0.0889)
		(layer "In13.Cu")
		(net "M_H_CPU1_SB_DQ<2>")
	)
	(arc
		(start 140.453364 -274.56892)
		(mid 140.269856 -274.523426)
		(end 140.087604 -274.573746)
		(width 0.0889)
		(layer "In13.Cu")
		(net "M_H_CPU1_SB_DQ<2>")
	)
	(arc
		(start 141.027658 -274.573746)
		(mid 140.744702 -274.649923)
		(end 140.461746 -274.573746)
		(width 0.0889)
		(layer "In13.Cu")
		(net "M_H_CPU1_SB_DQ<2>")
	)
	(arc
		(start 145.160492 -274.573746)
		(mid 144.983701 -274.523027)
		(end 144.80413 -274.562824)
		(width 0.0889)
		(layer "In13.Cu")
		(net "M_H_CPU1_SB_DQ<2>")
	)
	(arc
		(start 142.341854 -274.573746)
		(mid 142.159603 -274.523396)
		(end 141.976094 -274.56892)
		(width 0.0889)
		(layer "In13.Cu")
		(net "M_H_CPU1_SB_DQ<2>")
	)
	(arc
		(start 141.967712 -274.573746)
		(mid 141.684756 -274.649923)
		(end 141.4018 -274.573746)
		(width 0.0889)
		(layer "In13.Cu")
		(net "M_H_CPU1_SB_DQ<2>")
	)
	(arc
		(start 143.281654 -274.573746)
		(mid 143.09471 -274.523491)
		(end 142.907766 -274.573746)
		(width 0.0889)
		(layer "In13.Cu")
		(net "M_H_CPU1_SB_DQ<2>")
	)
	(arc
		(start 144.20088 -274.56257)
		(mid 144.022802 -274.523586)
		(end 143.847566 -274.573746)
		(width 0.0889)
		(layer "In13.Cu")
		(net "M_H_CPU1_SB_DQ<2>")
	)
	(arc
		(start 143.847566 -274.573746)
		(mid 143.56461 -274.649923)
		(end 143.281654 -274.573746)
		(width 0.0889)
		(layer "In13.Cu")
		(net "M_H_CPU1_SB_DQ<2>")
	)
	(arc
		(start 141.393418 -274.56892)
		(mid 141.20991 -274.523426)
		(end 141.027658 -274.573746)
		(width 0.0889)
		(layer "In13.Cu")
		(net "M_H_CPU1_SB_DQ<2>")
	)
	(arc
		(start 138.20775 -274.573746)
		(mid 137.924794 -274.649923)
		(end 137.641838 -274.573746)
		(width 0.0889)
		(layer "In13.Cu")
		(net "M_H_CPU1_SB_DQ<2>")
	)
	(arc
		(start 137.267696 -274.573746)
		(mid 136.98474 -274.649923)
		(end 136.701784 -274.573746)
		(width 0.0889)
		(layer "In13.Cu")
		(net "M_H_CPU1_SB_DQ<2>")
	)
	(arc
		(start 144.785334 -274.573746)
		(mid 144.515565 -274.649769)
		(end 144.242536 -274.586446)
		(width 0.0889)
		(layer "In13.Cu")
		(net "M_H_CPU1_SB_DQ<2>")
	)
	(segment
		(start 134.16788 -292.450266)
		(end 134.634732 -292.716204)
		(width 0.10668)
		(layer "F.Cu")
		(net "M_H_CPU1_SB_DQ<29>")
	)
	(segment
		(start 150.88235 -308.227476)
		(end 151.70277 -308.227476)
		(width 0.14478)
		(layer "In13.Cu")
		(net "M_H_CPU1_SB_DQ<29>")
	)
	(segment
		(start 160.692338 -317.213742)
		(end 161.650172 -317.61049)
		(width 0.14478)
		(layer "In13.Cu")
		(net "M_H_CPU1_SB_DQ<29>")
	)
	(segment
		(start 145.56994 -302.915066)
		(end 150.88235 -308.227476)
		(width 0.14478)
		(layer "In13.Cu")
		(net "M_H_CPU1_SB_DQ<29>")
	)
	(segment
		(start 141.393418 -293.04361)
		(end 141.4018 -293.038784)
		(width 0.0889)
		(layer "In13.Cu")
		(net "M_H_CPU1_SB_DQ<29>")
	)
	(segment
		(start 144.756886 -294.641016)
		(end 144.826482 -294.681656)
		(width 0.0889)
		(layer "In13.Cu")
		(net "M_H_CPU1_SB_DQ<29>")
	)
	(segment
		(start 160.6169 -317.141352)
		(end 160.692338 -317.213742)
		(width 0.14478)
		(layer "In13.Cu")
		(net "M_H_CPU1_SB_DQ<29>")
	)
	(segment
		(start 145.56994 -295.853104)
		(end 145.56994 -296.18559)
		(width 0.0889)
		(layer "In13.Cu")
		(net "M_H_CPU1_SB_DQ<29>")
	)
	(segment
		(start 138.20775 -293.038784)
		(end 138.216132 -293.04361)
		(width 0.0889)
		(layer "In13.Cu")
		(net "M_H_CPU1_SB_DQ<29>")
	)
	(segment
		(start 137.267696 -293.038784)
		(end 137.276078 -293.04361)
		(width 0.0889)
		(layer "In13.Cu")
		(net "M_H_CPU1_SB_DQ<29>")
	)
	(segment
		(start 136.693402 -293.04361)
		(end 136.701784 -293.038784)
		(width 0.0889)
		(layer "In13.Cu")
		(net "M_H_CPU1_SB_DQ<29>")
	)
	(segment
		(start 135.753348 -293.04361)
		(end 135.76173 -293.038784)
		(width 0.0889)
		(layer "In13.Cu")
		(net "M_H_CPU1_SB_DQ<29>")
	)
	(segment
		(start 161.650172 -317.61049)
		(end 172.978572 -317.61049)
		(width 0.14478)
		(layer "In13.Cu")
		(net "M_H_CPU1_SB_DQ<29>")
	)
	(segment
		(start 172.978572 -317.61049)
		(end 176.072038 -317.185294)
		(width 0.14478)
		(layer "In13.Cu")
		(net "M_H_CPU1_SB_DQ<29>")
	)
	(segment
		(start 140.453364 -293.04361)
		(end 140.461746 -293.038784)
		(width 0.0889)
		(layer "In13.Cu")
		(net "M_H_CPU1_SB_DQ<29>")
	)
	(segment
		(start 143.847566 -293.038784)
		(end 143.886682 -293.061644)
		(width 0.0889)
		(layer "In13.Cu")
		(net "M_H_CPU1_SB_DQ<29>")
	)
	(segment
		(start 145.492978 -295.682162)
		(end 145.56994 -295.853104)
		(width 0.0889)
		(layer "In13.Cu")
		(net "M_H_CPU1_SB_DQ<29>")
	)
	(segment
		(start 145.179542 -295.399968)
		(end 145.386044 -295.55059)
		(width 0.0889)
		(layer "In13.Cu")
		(net "M_H_CPU1_SB_DQ<29>")
	)
	(segment
		(start 134.634732 -292.716204)
		(end 134.788656 -292.981634)
		(width 0.0889)
		(layer "In13.Cu")
		(net "M_H_CPU1_SB_DQ<29>")
	)
	(segment
		(start 134.788656 -292.981634)
		(end 134.884668 -293.007034)
		(width 0.0889)
		(layer "In13.Cu")
		(net "M_H_CPU1_SB_DQ<29>")
	)
	(segment
		(start 151.70277 -308.227476)
		(end 160.6169 -317.141352)
		(width 0.14478)
		(layer "In13.Cu")
		(net "M_H_CPU1_SB_DQ<29>")
	)
	(segment
		(start 141.967712 -293.038784)
		(end 141.976094 -293.04361)
		(width 0.0889)
		(layer "In13.Cu")
		(net "M_H_CPU1_SB_DQ<29>")
	)
	(segment
		(start 145.56994 -296.18559)
		(end 145.56994 -302.915066)
		(width 0.14478)
		(layer "In13.Cu")
		(net "M_H_CPU1_SB_DQ<29>")
	)
	(segment
		(start 144.286986 -293.83101)
		(end 144.356582 -293.87165)
		(width 0.0889)
		(layer "In13.Cu")
		(net "M_H_CPU1_SB_DQ<29>")
	)
	(arc
		(start 142.341854 -293.038784)
		(mid 142.62481 -292.962607)
		(end 142.907766 -293.038784)
		(width 0.0889)
		(layer "In13.Cu")
		(net "M_H_CPU1_SB_DQ<29>")
	)
	(arc
		(start 136.701784 -293.038784)
		(mid 136.98474 -292.962607)
		(end 137.267696 -293.038784)
		(width 0.0889)
		(layer "In13.Cu")
		(net "M_H_CPU1_SB_DQ<29>")
	)
	(arc
		(start 135.76173 -293.038784)
		(mid 136.044686 -292.962607)
		(end 136.327642 -293.038784)
		(width 0.0889)
		(layer "In13.Cu")
		(net "M_H_CPU1_SB_DQ<29>")
	)
	(arc
		(start 141.027658 -293.038784)
		(mid 141.209909 -293.089134)
		(end 141.393418 -293.04361)
		(width 0.0889)
		(layer "In13.Cu")
		(net "M_H_CPU1_SB_DQ<29>")
	)
	(arc
		(start 143.886682 -293.061644)
		(mid 144.065495 -293.263994)
		(end 144.130014 -293.52621)
		(width 0.0889)
		(layer "In13.Cu")
		(net "M_H_CPU1_SB_DQ<29>")
	)
	(arc
		(start 141.4018 -293.038784)
		(mid 141.684756 -292.962607)
		(end 141.967712 -293.038784)
		(width 0.0889)
		(layer "In13.Cu")
		(net "M_H_CPU1_SB_DQ<29>")
	)
	(arc
		(start 135.387588 -293.038784)
		(mid 135.569839 -293.089134)
		(end 135.753348 -293.04361)
		(width 0.0889)
		(layer "In13.Cu")
		(net "M_H_CPU1_SB_DQ<29>")
	)
	(arc
		(start 145.069814 -295.146222)
		(mid 145.082732 -295.243281)
		(end 145.12036 -295.333674)
		(width 0.0889)
		(layer "In13.Cu")
		(net "M_H_CPU1_SB_DQ<29>")
	)
	(arc
		(start 143.281654 -293.038784)
		(mid 143.56461 -292.962607)
		(end 143.847566 -293.038784)
		(width 0.0889)
		(layer "In13.Cu")
		(net "M_H_CPU1_SB_DQ<29>")
	)
	(arc
		(start 134.884668 -293.007034)
		(mid 135.139876 -292.963557)
		(end 135.387588 -293.038784)
		(width 0.0889)
		(layer "In13.Cu")
		(net "M_H_CPU1_SB_DQ<29>")
	)
	(arc
		(start 137.641838 -293.038784)
		(mid 137.924794 -292.962607)
		(end 138.20775 -293.038784)
		(width 0.0889)
		(layer "In13.Cu")
		(net "M_H_CPU1_SB_DQ<29>")
	)
	(arc
		(start 145.386044 -295.55059)
		(mid 145.448062 -295.609421)
		(end 145.492978 -295.682162)
		(width 0.0889)
		(layer "In13.Cu")
		(net "M_H_CPU1_SB_DQ<29>")
	)
	(arc
		(start 144.130014 -293.52621)
		(mid 144.171563 -293.697632)
		(end 144.286986 -293.83101)
		(width 0.0889)
		(layer "In13.Cu")
		(net "M_H_CPU1_SB_DQ<29>")
	)
	(arc
		(start 142.907766 -293.038784)
		(mid 143.09471 -293.089039)
		(end 143.281654 -293.038784)
		(width 0.0889)
		(layer "In13.Cu")
		(net "M_H_CPU1_SB_DQ<29>")
	)
	(arc
		(start 144.599914 -294.336216)
		(mid 144.641463 -294.507638)
		(end 144.756886 -294.641016)
		(width 0.0889)
		(layer "In13.Cu")
		(net "M_H_CPU1_SB_DQ<29>")
	)
	(arc
		(start 138.216132 -293.04361)
		(mid 138.39964 -293.089104)
		(end 138.581892 -293.038784)
		(width 0.0889)
		(layer "In13.Cu")
		(net "M_H_CPU1_SB_DQ<29>")
	)
	(arc
		(start 145.12036 -295.333674)
		(mid 145.146494 -295.369906)
		(end 145.179542 -295.399968)
		(width 0.0889)
		(layer "In13.Cu")
		(net "M_H_CPU1_SB_DQ<29>")
	)
	(arc
		(start 144.356582 -293.87165)
		(mid 144.535395 -294.074)
		(end 144.599914 -294.336216)
		(width 0.0889)
		(layer "In13.Cu")
		(net "M_H_CPU1_SB_DQ<29>")
	)
	(arc
		(start 137.276078 -293.04361)
		(mid 137.459586 -293.089104)
		(end 137.641838 -293.038784)
		(width 0.0889)
		(layer "In13.Cu")
		(net "M_H_CPU1_SB_DQ<29>")
	)
	(arc
		(start 144.826482 -294.681656)
		(mid 145.005295 -294.884006)
		(end 145.069814 -295.146222)
		(width 0.0889)
		(layer "In13.Cu")
		(net "M_H_CPU1_SB_DQ<29>")
	)
	(arc
		(start 140.087604 -293.038784)
		(mid 140.269855 -293.089134)
		(end 140.453364 -293.04361)
		(width 0.0889)
		(layer "In13.Cu")
		(net "M_H_CPU1_SB_DQ<29>")
	)
	(arc
		(start 139.147804 -293.038784)
		(mid 139.334748 -293.089039)
		(end 139.521692 -293.038784)
		(width 0.0889)
		(layer "In13.Cu")
		(net "M_H_CPU1_SB_DQ<29>")
	)
	(arc
		(start 141.976094 -293.04361)
		(mid 142.159602 -293.089104)
		(end 142.341854 -293.038784)
		(width 0.0889)
		(layer "In13.Cu")
		(net "M_H_CPU1_SB_DQ<29>")
	)
	(arc
		(start 140.461746 -293.038784)
		(mid 140.744702 -292.962607)
		(end 141.027658 -293.038784)
		(width 0.0889)
		(layer "In13.Cu")
		(net "M_H_CPU1_SB_DQ<29>")
	)
	(arc
		(start 139.521692 -293.038784)
		(mid 139.804648 -292.962607)
		(end 140.087604 -293.038784)
		(width 0.0889)
		(layer "In13.Cu")
		(net "M_H_CPU1_SB_DQ<29>")
	)
	(arc
		(start 138.581892 -293.038784)
		(mid 138.864848 -292.962607)
		(end 139.147804 -293.038784)
		(width 0.0889)
		(layer "In13.Cu")
		(net "M_H_CPU1_SB_DQ<29>")
	)
	(arc
		(start 136.327642 -293.038784)
		(mid 136.509893 -293.089134)
		(end 136.693402 -293.04361)
		(width 0.0889)
		(layer "In13.Cu")
		(net "M_H_CPU1_SB_DQ<29>")
	)
	(segment
		(start 135.577834 -291.64026)
		(end 136.044686 -291.906198)
		(width 0.10668)
		(layer "F.Cu")
		(net "M_H_CPU1_SB_DQ<28>")
	)
	(segment
		(start 169.948606 -315.525912)
		(end 169.948606 -315.77534)
		(width 0.14478)
		(layer "In13.Cu")
		(net "M_H_CPU1_SB_DQ<28>")
	)
	(segment
		(start 176.072038 -315.485272)
		(end 174.00524 -315.485272)
		(width 0.14478)
		(layer "In13.Cu")
		(net "M_H_CPU1_SB_DQ<28>")
	)
	(segment
		(start 143.386048 -292.233604)
		(end 143.377666 -292.228778)
		(width 0.0889)
		(layer "In13.Cu")
		(net "M_H_CPU1_SB_DQ<28>")
	)
	(segment
		(start 173.570392 -315.92012)
		(end 171.746926 -315.92012)
		(width 0.14478)
		(layer "In13.Cu")
		(net "M_H_CPU1_SB_DQ<28>")
	)
	(segment
		(start 139.051792 -292.228778)
		(end 139.04341 -292.233604)
		(width 0.0889)
		(layer "In13.Cu")
		(net "M_H_CPU1_SB_DQ<28>")
	)
	(segment
		(start 145.296636 -293.87165)
		(end 145.22704 -293.83101)
		(width 0.0889)
		(layer "In13.Cu")
		(net "M_H_CPU1_SB_DQ<28>")
	)
	(segment
		(start 138.111738 -292.228778)
		(end 138.103356 -292.233604)
		(width 0.0889)
		(layer "In13.Cu")
		(net "M_H_CPU1_SB_DQ<28>")
	)
	(segment
		(start 136.29513 -292.197028)
		(end 136.198864 -292.171628)
		(width 0.0889)
		(layer "In13.Cu")
		(net "M_H_CPU1_SB_DQ<28>")
	)
	(segment
		(start 170.644566 -315.92012)
		(end 170.499786 -315.77534)
		(width 0.14478)
		(layer "In13.Cu")
		(net "M_H_CPU1_SB_DQ<28>")
	)
	(segment
		(start 146.47926 -301.731426)
		(end 146.47926 -295.995598)
		(width 0.14478)
		(layer "In13.Cu")
		(net "M_H_CPU1_SB_DQ<28>")
	)
	(segment
		(start 171.050966 -315.525912)
		(end 171.050966 -315.77534)
		(width 0.14478)
		(layer "In13.Cu")
		(net "M_H_CPU1_SB_DQ<28>")
	)
	(segment
		(start 169.803826 -315.92012)
		(end 160.667954 -315.92012)
		(width 0.14478)
		(layer "In13.Cu")
		(net "M_H_CPU1_SB_DQ<28>")
	)
	(segment
		(start 169.948606 -315.77534)
		(end 169.803826 -315.92012)
		(width 0.14478)
		(layer "In13.Cu")
		(net "M_H_CPU1_SB_DQ<28>")
	)
	(segment
		(start 170.906186 -315.92012)
		(end 170.644566 -315.92012)
		(width 0.14478)
		(layer "In13.Cu")
		(net "M_H_CPU1_SB_DQ<28>")
	)
	(segment
		(start 146.47926 -295.615614)
		(end 146.009868 -295.146222)
		(width 0.0889)
		(layer "In13.Cu")
		(net "M_H_CPU1_SB_DQ<28>")
	)
	(segment
		(start 170.499786 -315.77534)
		(end 170.499786 -315.525912)
		(width 0.14478)
		(layer "In13.Cu")
		(net "M_H_CPU1_SB_DQ<28>")
	)
	(segment
		(start 171.602146 -315.525912)
		(end 171.457366 -315.381132)
		(width 0.14478)
		(layer "In13.Cu")
		(net "M_H_CPU1_SB_DQ<28>")
	)
	(segment
		(start 160.667954 -315.92012)
		(end 146.47926 -301.731426)
		(width 0.14478)
		(layer "In13.Cu")
		(net "M_H_CPU1_SB_DQ<28>")
	)
	(segment
		(start 171.746926 -315.92012)
		(end 171.602146 -315.77534)
		(width 0.14478)
		(layer "In13.Cu")
		(net "M_H_CPU1_SB_DQ<28>")
	)
	(segment
		(start 146.47926 -295.995598)
		(end 146.47926 -295.615614)
		(width 0.0889)
		(layer "In13.Cu")
		(net "M_H_CPU1_SB_DQ<28>")
	)
	(segment
		(start 170.093386 -315.381132)
		(end 169.948606 -315.525912)
		(width 0.14478)
		(layer "In13.Cu")
		(net "M_H_CPU1_SB_DQ<28>")
	)
	(segment
		(start 171.457366 -315.381132)
		(end 171.195746 -315.381132)
		(width 0.14478)
		(layer "In13.Cu")
		(net "M_H_CPU1_SB_DQ<28>")
	)
	(segment
		(start 136.198864 -292.171628)
		(end 136.044686 -291.906198)
		(width 0.0889)
		(layer "In13.Cu")
		(net "M_H_CPU1_SB_DQ<28>")
	)
	(segment
		(start 144.826736 -293.061644)
		(end 144.75714 -293.021004)
		(width 0.0889)
		(layer "In13.Cu")
		(net "M_H_CPU1_SB_DQ<28>")
	)
	(segment
		(start 142.811754 -292.228778)
		(end 142.803372 -292.233604)
		(width 0.0889)
		(layer "In13.Cu")
		(net "M_H_CPU1_SB_DQ<28>")
	)
	(segment
		(start 171.050966 -315.77534)
		(end 170.906186 -315.92012)
		(width 0.14478)
		(layer "In13.Cu")
		(net "M_H_CPU1_SB_DQ<28>")
	)
	(segment
		(start 171.602146 -315.77534)
		(end 171.602146 -315.525912)
		(width 0.14478)
		(layer "In13.Cu")
		(net "M_H_CPU1_SB_DQ<28>")
	)
	(segment
		(start 170.355006 -315.381132)
		(end 170.093386 -315.381132)
		(width 0.14478)
		(layer "In13.Cu")
		(net "M_H_CPU1_SB_DQ<28>")
	)
	(segment
		(start 174.00524 -315.485272)
		(end 173.570392 -315.92012)
		(width 0.14478)
		(layer "In13.Cu")
		(net "M_H_CPU1_SB_DQ<28>")
	)
	(segment
		(start 145.763996 -294.679878)
		(end 145.695924 -294.640508)
		(width 0.0889)
		(layer "In13.Cu")
		(net "M_H_CPU1_SB_DQ<28>")
	)
	(segment
		(start 144.356836 -292.251638)
		(end 144.31772 -292.228778)
		(width 0.0889)
		(layer "In13.Cu")
		(net "M_H_CPU1_SB_DQ<28>")
	)
	(segment
		(start 170.499786 -315.525912)
		(end 170.355006 -315.381132)
		(width 0.14478)
		(layer "In13.Cu")
		(net "M_H_CPU1_SB_DQ<28>")
	)
	(segment
		(start 171.195746 -315.381132)
		(end 171.050966 -315.525912)
		(width 0.14478)
		(layer "In13.Cu")
		(net "M_H_CPU1_SB_DQ<28>")
	)
	(segment
		(start 140.56614 -292.233604)
		(end 140.557758 -292.228778)
		(width 0.0889)
		(layer "In13.Cu")
		(net "M_H_CPU1_SB_DQ<28>")
	)
	(segment
		(start 139.626086 -292.233604)
		(end 139.617704 -292.228778)
		(width 0.0889)
		(layer "In13.Cu")
		(net "M_H_CPU1_SB_DQ<28>")
	)
	(arc
		(start 139.991846 -292.228778)
		(mid 139.809595 -292.279128)
		(end 139.626086 -292.233604)
		(width 0.0889)
		(layer "In13.Cu")
		(net "M_H_CPU1_SB_DQ<28>")
	)
	(arc
		(start 141.497812 -292.228778)
		(mid 141.214856 -292.152601)
		(end 140.9319 -292.228778)
		(width 0.0889)
		(layer "In13.Cu")
		(net "M_H_CPU1_SB_DQ<28>")
	)
	(arc
		(start 140.557758 -292.228778)
		(mid 140.274802 -292.152601)
		(end 139.991846 -292.228778)
		(width 0.0889)
		(layer "In13.Cu")
		(net "M_H_CPU1_SB_DQ<28>")
	)
	(arc
		(start 144.600168 -292.716204)
		(mid 144.535653 -292.453985)
		(end 144.356836 -292.251638)
		(width 0.0889)
		(layer "In13.Cu")
		(net "M_H_CPU1_SB_DQ<28>")
	)
	(arc
		(start 138.67765 -292.228778)
		(mid 138.394694 -292.152601)
		(end 138.111738 -292.228778)
		(width 0.0889)
		(layer "In13.Cu")
		(net "M_H_CPU1_SB_DQ<28>")
	)
	(arc
		(start 139.04341 -292.233604)
		(mid 138.859902 -292.279098)
		(end 138.67765 -292.228778)
		(width 0.0889)
		(layer "In13.Cu")
		(net "M_H_CPU1_SB_DQ<28>")
	)
	(arc
		(start 143.377666 -292.228778)
		(mid 143.09471 -292.152601)
		(end 142.811754 -292.228778)
		(width 0.0889)
		(layer "In13.Cu")
		(net "M_H_CPU1_SB_DQ<28>")
	)
	(arc
		(start 140.9319 -292.228778)
		(mid 140.749649 -292.279128)
		(end 140.56614 -292.233604)
		(width 0.0889)
		(layer "In13.Cu")
		(net "M_H_CPU1_SB_DQ<28>")
	)
	(arc
		(start 139.617704 -292.228778)
		(mid 139.334748 -292.152601)
		(end 139.051792 -292.228778)
		(width 0.0889)
		(layer "In13.Cu")
		(net "M_H_CPU1_SB_DQ<28>")
	)
	(arc
		(start 137.737596 -292.228778)
		(mid 137.45464 -292.152601)
		(end 137.171684 -292.228778)
		(width 0.0889)
		(layer "In13.Cu")
		(net "M_H_CPU1_SB_DQ<28>")
	)
	(arc
		(start 144.31772 -292.228778)
		(mid 144.034764 -292.152601)
		(end 143.751808 -292.228778)
		(width 0.0889)
		(layer "In13.Cu")
		(net "M_H_CPU1_SB_DQ<28>")
	)
	(arc
		(start 144.75714 -293.021004)
		(mid 144.641713 -292.887628)
		(end 144.600168 -292.716204)
		(width 0.0889)
		(layer "In13.Cu")
		(net "M_H_CPU1_SB_DQ<28>")
	)
	(arc
		(start 145.22704 -293.83101)
		(mid 145.111613 -293.697634)
		(end 145.070068 -293.52621)
		(width 0.0889)
		(layer "In13.Cu")
		(net "M_H_CPU1_SB_DQ<28>")
	)
	(arc
		(start 145.695924 -294.640508)
		(mid 145.581248 -294.507174)
		(end 145.539968 -294.336216)
		(width 0.0889)
		(layer "In13.Cu")
		(net "M_H_CPU1_SB_DQ<28>")
	)
	(arc
		(start 143.751808 -292.228778)
		(mid 143.569557 -292.279128)
		(end 143.386048 -292.233604)
		(width 0.0889)
		(layer "In13.Cu")
		(net "M_H_CPU1_SB_DQ<28>")
	)
	(arc
		(start 137.171684 -292.228778)
		(mid 136.98474 -292.279033)
		(end 136.797796 -292.228778)
		(width 0.0889)
		(layer "In13.Cu")
		(net "M_H_CPU1_SB_DQ<28>")
	)
	(arc
		(start 138.103356 -292.233604)
		(mid 137.919848 -292.279098)
		(end 137.737596 -292.228778)
		(width 0.0889)
		(layer "In13.Cu")
		(net "M_H_CPU1_SB_DQ<28>")
	)
	(arc
		(start 145.070068 -293.52621)
		(mid 145.005553 -293.263991)
		(end 144.826736 -293.061644)
		(width 0.0889)
		(layer "In13.Cu")
		(net "M_H_CPU1_SB_DQ<28>")
	)
	(arc
		(start 145.539968 -294.336216)
		(mid 145.475453 -294.073997)
		(end 145.296636 -293.87165)
		(width 0.0889)
		(layer "In13.Cu")
		(net "M_H_CPU1_SB_DQ<28>")
	)
	(arc
		(start 142.437612 -292.228778)
		(mid 142.154656 -292.152601)
		(end 141.8717 -292.228778)
		(width 0.0889)
		(layer "In13.Cu")
		(net "M_H_CPU1_SB_DQ<28>")
	)
	(arc
		(start 136.797796 -292.228778)
		(mid 136.5502 -292.1536)
		(end 136.29513 -292.197028)
		(width 0.0889)
		(layer "In13.Cu")
		(net "M_H_CPU1_SB_DQ<28>")
	)
	(arc
		(start 146.009868 -295.146222)
		(mid 145.944632 -294.882631)
		(end 145.763996 -294.679878)
		(width 0.0889)
		(layer "In13.Cu")
		(net "M_H_CPU1_SB_DQ<28>")
	)
	(arc
		(start 142.803372 -292.233604)
		(mid 142.619864 -292.279098)
		(end 142.437612 -292.228778)
		(width 0.0889)
		(layer "In13.Cu")
		(net "M_H_CPU1_SB_DQ<28>")
	)
	(arc
		(start 141.8717 -292.228778)
		(mid 141.684756 -292.279033)
		(end 141.497812 -292.228778)
		(width 0.0889)
		(layer "In13.Cu")
		(net "M_H_CPU1_SB_DQ<28>")
	)
	(segment
		(start 134.63778 -290.020248)
		(end 135.104632 -290.286186)
		(width 0.10668)
		(layer "F.Cu")
		(net "M_H_CPU1_SB_DQ<27>")
	)
	(segment
		(start 162.78225 -312.48858)
		(end 163.04387 -312.48858)
		(width 0.14478)
		(layer "In13.Cu")
		(net "M_H_CPU1_SB_DQ<27>")
	)
	(segment
		(start 165.24859 -312.48858)
		(end 165.39337 -312.3438)
		(width 0.14478)
		(layer "In13.Cu")
		(net "M_H_CPU1_SB_DQ<27>")
	)
	(segment
		(start 166.788338 -311.660286)
		(end 167.585136 -311.660286)
		(width 0.14478)
		(layer "In13.Cu")
		(net "M_H_CPU1_SB_DQ<27>")
	)
	(segment
		(start 147.236942 -292.848284)
		(end 148.82749 -294.438832)
		(width 0.14478)
		(layer "In13.Cu")
		(net "M_H_CPU1_SB_DQ<27>")
	)
	(segment
		(start 162.08629 -312.254646)
		(end 162.23107 -312.109866)
		(width 0.14478)
		(layer "In13.Cu")
		(net "M_H_CPU1_SB_DQ<27>")
	)
	(segment
		(start 160.57753 -312.48858)
		(end 160.83915 -312.48858)
		(width 0.14478)
		(layer "In13.Cu")
		(net "M_H_CPU1_SB_DQ<27>")
	)
	(segment
		(start 167.729916 -311.515506)
		(end 167.729916 -311.48528)
		(width 0.14478)
		(layer "In13.Cu")
		(net "M_H_CPU1_SB_DQ<27>")
	)
	(segment
		(start 161.67989 -312.48858)
		(end 161.94151 -312.48858)
		(width 0.14478)
		(layer "In13.Cu")
		(net "M_H_CPU1_SB_DQ<27>")
	)
	(segment
		(start 146.931126 -292.848284)
		(end 147.236942 -292.848284)
		(width 0.0889)
		(layer "In13.Cu")
		(net "M_H_CPU1_SB_DQ<27>")
	)
	(segment
		(start 163.59505 -312.109866)
		(end 163.73983 -312.254646)
		(width 0.14478)
		(layer "In13.Cu")
		(net "M_H_CPU1_SB_DQ<27>")
	)
	(segment
		(start 160.43275 -312.3438)
		(end 160.57753 -312.48858)
		(width 0.14478)
		(layer "In13.Cu")
		(net "M_H_CPU1_SB_DQ<27>")
	)
	(segment
		(start 163.18865 -312.254646)
		(end 163.33343 -312.109866)
		(width 0.14478)
		(layer "In13.Cu")
		(net "M_H_CPU1_SB_DQ<27>")
	)
	(segment
		(start 145.932906 -290.211764)
		(end 145.932906 -291.042852)
		(width 0.0889)
		(layer "In13.Cu")
		(net "M_H_CPU1_SB_DQ<27>")
	)
	(segment
		(start 163.73983 -312.3438)
		(end 163.88461 -312.48858)
		(width 0.14478)
		(layer "In13.Cu")
		(net "M_H_CPU1_SB_DQ<27>")
	)
	(segment
		(start 168.425876 -311.980072)
		(end 168.687496 -311.980072)
		(width 0.14478)
		(layer "In13.Cu")
		(net "M_H_CPU1_SB_DQ<27>")
	)
	(segment
		(start 161.53511 -312.3438)
		(end 161.67989 -312.48858)
		(width 0.14478)
		(layer "In13.Cu")
		(net "M_H_CPU1_SB_DQ<27>")
	)
	(segment
		(start 140.557758 -289.963606)
		(end 140.56614 -289.95878)
		(width 0.0889)
		(layer "In13.Cu")
		(net "M_H_CPU1_SB_DQ<27>")
	)
	(segment
		(start 146.503898 -292.421056)
		(end 146.931126 -292.848284)
		(width 0.0889)
		(layer "In13.Cu")
		(net "M_H_CPU1_SB_DQ<27>")
	)
	(segment
		(start 163.04387 -312.48858)
		(end 163.18865 -312.3438)
		(width 0.14478)
		(layer "In13.Cu")
		(net "M_H_CPU1_SB_DQ<27>")
	)
	(segment
		(start 145.932906 -291.042852)
		(end 146.503898 -292.421056)
		(width 0.0889)
		(layer "In13.Cu")
		(net "M_H_CPU1_SB_DQ<27>")
	)
	(segment
		(start 168.977056 -311.3405)
		(end 169.238676 -311.3405)
		(width 0.14478)
		(layer "In13.Cu")
		(net "M_H_CPU1_SB_DQ<27>")
	)
	(segment
		(start 164.43579 -312.109866)
		(end 164.69741 -312.109866)
		(width 0.14478)
		(layer "In13.Cu")
		(net "M_H_CPU1_SB_DQ<27>")
	)
	(segment
		(start 162.08629 -312.3438)
		(end 162.08629 -312.254646)
		(width 0.14478)
		(layer "In13.Cu")
		(net "M_H_CPU1_SB_DQ<27>")
	)
	(segment
		(start 167.585136 -311.660286)
		(end 167.729916 -311.515506)
		(width 0.14478)
		(layer "In13.Cu")
		(net "M_H_CPU1_SB_DQ<27>")
	)
	(segment
		(start 168.832276 -311.835292)
		(end 168.832276 -311.48528)
		(width 0.14478)
		(layer "In13.Cu")
		(net "M_H_CPU1_SB_DQ<27>")
	)
	(segment
		(start 168.832276 -311.48528)
		(end 168.977056 -311.3405)
		(width 0.14478)
		(layer "In13.Cu")
		(net "M_H_CPU1_SB_DQ<27>")
	)
	(segment
		(start 164.69741 -312.109866)
		(end 164.84219 -312.254646)
		(width 0.14478)
		(layer "In13.Cu")
		(net "M_H_CPU1_SB_DQ<27>")
	)
	(segment
		(start 162.23107 -312.109866)
		(end 162.49269 -312.109866)
		(width 0.14478)
		(layer "In13.Cu")
		(net "M_H_CPU1_SB_DQ<27>")
	)
	(segment
		(start 160.98393 -312.3438)
		(end 160.98393 -312.254646)
		(width 0.14478)
		(layer "In13.Cu")
		(net "M_H_CPU1_SB_DQ<27>")
	)
	(segment
		(start 167.729916 -311.48528)
		(end 167.874696 -311.3405)
		(width 0.14478)
		(layer "In13.Cu")
		(net "M_H_CPU1_SB_DQ<27>")
	)
	(segment
		(start 166.338758 -312.109866)
		(end 166.788338 -311.660286)
		(width 0.14478)
		(layer "In13.Cu")
		(net "M_H_CPU1_SB_DQ<27>")
	)
	(segment
		(start 160.43275 -312.254646)
		(end 160.43275 -312.3438)
		(width 0.14478)
		(layer "In13.Cu")
		(net "M_H_CPU1_SB_DQ<27>")
	)
	(segment
		(start 168.281096 -311.835292)
		(end 168.425876 -311.980072)
		(width 0.14478)
		(layer "In13.Cu")
		(net "M_H_CPU1_SB_DQ<27>")
	)
	(segment
		(start 170.03268 -311.660286)
		(end 170.872912 -312.500518)
		(width 0.14478)
		(layer "In13.Cu")
		(net "M_H_CPU1_SB_DQ<27>")
	)
	(segment
		(start 170.872912 -312.500518)
		(end 171.55668 -312.500518)
		(width 0.14478)
		(layer "In13.Cu")
		(net "M_H_CPU1_SB_DQ<27>")
	)
	(segment
		(start 164.84219 -312.254646)
		(end 164.84219 -312.3438)
		(width 0.14478)
		(layer "In13.Cu")
		(net "M_H_CPU1_SB_DQ<27>")
	)
	(segment
		(start 169.528236 -311.660286)
		(end 170.03268 -311.660286)
		(width 0.14478)
		(layer "In13.Cu")
		(net "M_H_CPU1_SB_DQ<27>")
	)
	(segment
		(start 160.09493 -312.109866)
		(end 160.28797 -312.109866)
		(width 0.14478)
		(layer "In13.Cu")
		(net "M_H_CPU1_SB_DQ<27>")
	)
	(segment
		(start 142.803372 -289.95878)
		(end 142.811754 -289.963606)
		(width 0.0889)
		(layer "In13.Cu")
		(net "M_H_CPU1_SB_DQ<27>")
	)
	(segment
		(start 148.82749 -300.842426)
		(end 160.09493 -312.109866)
		(width 0.14478)
		(layer "In13.Cu")
		(net "M_H_CPU1_SB_DQ<27>")
	)
	(segment
		(start 144.88668 -289.884358)
		(end 145.6055 -289.884358)
		(width 0.0889)
		(layer "In13.Cu")
		(net "M_H_CPU1_SB_DQ<27>")
	)
	(segment
		(start 164.84219 -312.3438)
		(end 164.98697 -312.48858)
		(width 0.14478)
		(layer "In13.Cu")
		(net "M_H_CPU1_SB_DQ<27>")
	)
	(segment
		(start 163.33343 -312.109866)
		(end 163.59505 -312.109866)
		(width 0.14478)
		(layer "In13.Cu")
		(net "M_H_CPU1_SB_DQ<27>")
	)
	(segment
		(start 161.39033 -312.109866)
		(end 161.53511 -312.254646)
		(width 0.14478)
		(layer "In13.Cu")
		(net "M_H_CPU1_SB_DQ<27>")
	)
	(segment
		(start 161.53511 -312.254646)
		(end 161.53511 -312.3438)
		(width 0.14478)
		(layer "In13.Cu")
		(net "M_H_CPU1_SB_DQ<27>")
	)
	(segment
		(start 143.377666 -289.963606)
		(end 143.386048 -289.95878)
		(width 0.0889)
		(layer "In13.Cu")
		(net "M_H_CPU1_SB_DQ<27>")
	)
	(segment
		(start 138.103356 -289.95878)
		(end 138.111738 -289.963606)
		(width 0.0889)
		(layer "In13.Cu")
		(net "M_H_CPU1_SB_DQ<27>")
	)
	(segment
		(start 169.383456 -311.48528)
		(end 169.383456 -311.515506)
		(width 0.14478)
		(layer "In13.Cu")
		(net "M_H_CPU1_SB_DQ<27>")
	)
	(segment
		(start 171.55668 -312.500518)
		(end 171.97197 -312.085228)
		(width 0.14478)
		(layer "In13.Cu")
		(net "M_H_CPU1_SB_DQ<27>")
	)
	(segment
		(start 164.14623 -312.48858)
		(end 164.29101 -312.3438)
		(width 0.14478)
		(layer "In13.Cu")
		(net "M_H_CPU1_SB_DQ<27>")
	)
	(segment
		(start 164.29101 -312.254646)
		(end 164.43579 -312.109866)
		(width 0.14478)
		(layer "In13.Cu")
		(net "M_H_CPU1_SB_DQ<27>")
	)
	(segment
		(start 144.034764 -290.039806)
		(end 144.731232 -290.039806)
		(width 0.0889)
		(layer "In13.Cu")
		(net "M_H_CPU1_SB_DQ<27>")
	)
	(segment
		(start 168.281096 -311.48528)
		(end 168.281096 -311.835292)
		(width 0.14478)
		(layer "In13.Cu")
		(net "M_H_CPU1_SB_DQ<27>")
	)
	(segment
		(start 164.29101 -312.3438)
		(end 164.29101 -312.254646)
		(width 0.14478)
		(layer "In13.Cu")
		(net "M_H_CPU1_SB_DQ<27>")
	)
	(segment
		(start 165.39337 -312.254646)
		(end 165.53815 -312.109866)
		(width 0.14478)
		(layer "In13.Cu")
		(net "M_H_CPU1_SB_DQ<27>")
	)
	(segment
		(start 160.28797 -312.109866)
		(end 160.43275 -312.254646)
		(width 0.14478)
		(layer "In13.Cu")
		(net "M_H_CPU1_SB_DQ<27>")
	)
	(segment
		(start 134.950708 -290.020756)
		(end 134.97306 -289.937444)
		(width 0.0889)
		(layer "In13.Cu")
		(net "M_H_CPU1_SB_DQ<27>")
	)
	(segment
		(start 163.73983 -312.254646)
		(end 163.73983 -312.3438)
		(width 0.14478)
		(layer "In13.Cu")
		(net "M_H_CPU1_SB_DQ<27>")
	)
	(segment
		(start 160.98393 -312.254646)
		(end 161.12871 -312.109866)
		(width 0.14478)
		(layer "In13.Cu")
		(net "M_H_CPU1_SB_DQ<27>")
	)
	(segment
		(start 163.18865 -312.3438)
		(end 163.18865 -312.254646)
		(width 0.14478)
		(layer "In13.Cu")
		(net "M_H_CPU1_SB_DQ<27>")
	)
	(segment
		(start 160.83915 -312.48858)
		(end 160.98393 -312.3438)
		(width 0.14478)
		(layer "In13.Cu")
		(net "M_H_CPU1_SB_DQ<27>")
	)
	(segment
		(start 148.82749 -294.438832)
		(end 148.82749 -300.842426)
		(width 0.14478)
		(layer "In13.Cu")
		(net "M_H_CPU1_SB_DQ<27>")
	)
	(segment
		(start 162.63747 -312.254646)
		(end 162.63747 -312.3438)
		(width 0.14478)
		(layer "In13.Cu")
		(net "M_H_CPU1_SB_DQ<27>")
	)
	(segment
		(start 135.857742 -289.963606)
		(end 135.866124 -289.95878)
		(width 0.0889)
		(layer "In13.Cu")
		(net "M_H_CPU1_SB_DQ<27>")
	)
	(segment
		(start 162.63747 -312.3438)
		(end 162.78225 -312.48858)
		(width 0.14478)
		(layer "In13.Cu")
		(net "M_H_CPU1_SB_DQ<27>")
	)
	(segment
		(start 161.94151 -312.48858)
		(end 162.08629 -312.3438)
		(width 0.14478)
		(layer "In13.Cu")
		(net "M_H_CPU1_SB_DQ<27>")
	)
	(segment
		(start 139.617704 -289.963606)
		(end 139.626086 -289.95878)
		(width 0.0889)
		(layer "In13.Cu")
		(net "M_H_CPU1_SB_DQ<27>")
	)
	(segment
		(start 169.383456 -311.515506)
		(end 169.528236 -311.660286)
		(width 0.14478)
		(layer "In13.Cu")
		(net "M_H_CPU1_SB_DQ<27>")
	)
	(segment
		(start 163.88461 -312.48858)
		(end 164.14623 -312.48858)
		(width 0.14478)
		(layer "In13.Cu")
		(net "M_H_CPU1_SB_DQ<27>")
	)
	(segment
		(start 165.53815 -312.109866)
		(end 166.338758 -312.109866)
		(width 0.14478)
		(layer "In13.Cu")
		(net "M_H_CPU1_SB_DQ<27>")
	)
	(segment
		(start 169.238676 -311.3405)
		(end 169.383456 -311.48528)
		(width 0.14478)
		(layer "In13.Cu")
		(net "M_H_CPU1_SB_DQ<27>")
	)
	(segment
		(start 168.687496 -311.980072)
		(end 168.832276 -311.835292)
		(width 0.14478)
		(layer "In13.Cu")
		(net "M_H_CPU1_SB_DQ<27>")
	)
	(segment
		(start 135.104632 -290.286186)
		(end 134.950708 -290.020756)
		(width 0.0889)
		(layer "In13.Cu")
		(net "M_H_CPU1_SB_DQ<27>")
	)
	(segment
		(start 161.12871 -312.109866)
		(end 161.39033 -312.109866)
		(width 0.14478)
		(layer "In13.Cu")
		(net "M_H_CPU1_SB_DQ<27>")
	)
	(segment
		(start 144.731232 -290.039806)
		(end 144.88668 -289.884358)
		(width 0.0889)
		(layer "In13.Cu")
		(net "M_H_CPU1_SB_DQ<27>")
	)
	(segment
		(start 167.874696 -311.3405)
		(end 168.136316 -311.3405)
		(width 0.14478)
		(layer "In13.Cu")
		(net "M_H_CPU1_SB_DQ<27>")
	)
	(segment
		(start 145.6055 -289.884358)
		(end 145.932906 -290.211764)
		(width 0.0889)
		(layer "In13.Cu")
		(net "M_H_CPU1_SB_DQ<27>")
	)
	(segment
		(start 139.04341 -289.95878)
		(end 139.051792 -289.963606)
		(width 0.0889)
		(layer "In13.Cu")
		(net "M_H_CPU1_SB_DQ<27>")
	)
	(segment
		(start 165.39337 -312.3438)
		(end 165.39337 -312.254646)
		(width 0.14478)
		(layer "In13.Cu")
		(net "M_H_CPU1_SB_DQ<27>")
	)
	(segment
		(start 162.49269 -312.109866)
		(end 162.63747 -312.254646)
		(width 0.14478)
		(layer "In13.Cu")
		(net "M_H_CPU1_SB_DQ<27>")
	)
	(segment
		(start 164.98697 -312.48858)
		(end 165.24859 -312.48858)
		(width 0.14478)
		(layer "In13.Cu")
		(net "M_H_CPU1_SB_DQ<27>")
	)
	(segment
		(start 168.136316 -311.3405)
		(end 168.281096 -311.48528)
		(width 0.14478)
		(layer "In13.Cu")
		(net "M_H_CPU1_SB_DQ<27>")
	)
	(arc
		(start 135.29183 -289.963606)
		(mid 135.574786 -290.039783)
		(end 135.857742 -289.963606)
		(width 0.0889)
		(layer "In13.Cu")
		(net "M_H_CPU1_SB_DQ<27>")
	)
	(arc
		(start 141.8717 -289.963606)
		(mid 142.154656 -290.039783)
		(end 142.437612 -289.963606)
		(width 0.0889)
		(layer "In13.Cu")
		(net "M_H_CPU1_SB_DQ<27>")
	)
	(arc
		(start 135.866124 -289.95878)
		(mid 136.049632 -289.913286)
		(end 136.231884 -289.963606)
		(width 0.0889)
		(layer "In13.Cu")
		(net "M_H_CPU1_SB_DQ<27>")
	)
	(arc
		(start 138.111738 -289.963606)
		(mid 138.394694 -290.039783)
		(end 138.67765 -289.963606)
		(width 0.0889)
		(layer "In13.Cu")
		(net "M_H_CPU1_SB_DQ<27>")
	)
	(arc
		(start 139.991846 -289.963606)
		(mid 140.274802 -290.039783)
		(end 140.557758 -289.963606)
		(width 0.0889)
		(layer "In13.Cu")
		(net "M_H_CPU1_SB_DQ<27>")
	)
	(arc
		(start 138.67765 -289.963606)
		(mid 138.859901 -289.913256)
		(end 139.04341 -289.95878)
		(width 0.0889)
		(layer "In13.Cu")
		(net "M_H_CPU1_SB_DQ<27>")
	)
	(arc
		(start 134.97306 -289.937444)
		(mid 135.135392 -289.914626)
		(end 135.29183 -289.963606)
		(width 0.0889)
		(layer "In13.Cu")
		(net "M_H_CPU1_SB_DQ<27>")
	)
	(arc
		(start 136.797796 -289.963606)
		(mid 136.98474 -289.913351)
		(end 137.171684 -289.963606)
		(width 0.0889)
		(layer "In13.Cu")
		(net "M_H_CPU1_SB_DQ<27>")
	)
	(arc
		(start 143.386048 -289.95878)
		(mid 143.569556 -289.913286)
		(end 143.751808 -289.963606)
		(width 0.0889)
		(layer "In13.Cu")
		(net "M_H_CPU1_SB_DQ<27>")
	)
	(arc
		(start 143.751808 -289.963606)
		(mid 143.888244 -290.020431)
		(end 144.034764 -290.039806)
		(width 0.0889)
		(layer "In13.Cu")
		(net "M_H_CPU1_SB_DQ<27>")
	)
	(arc
		(start 142.437612 -289.963606)
		(mid 142.619863 -289.913256)
		(end 142.803372 -289.95878)
		(width 0.0889)
		(layer "In13.Cu")
		(net "M_H_CPU1_SB_DQ<27>")
	)
	(arc
		(start 142.811754 -289.963606)
		(mid 143.09471 -290.039783)
		(end 143.377666 -289.963606)
		(width 0.0889)
		(layer "In13.Cu")
		(net "M_H_CPU1_SB_DQ<27>")
	)
	(arc
		(start 136.231884 -289.963606)
		(mid 136.51484 -290.039783)
		(end 136.797796 -289.963606)
		(width 0.0889)
		(layer "In13.Cu")
		(net "M_H_CPU1_SB_DQ<27>")
	)
	(arc
		(start 139.626086 -289.95878)
		(mid 139.809594 -289.913286)
		(end 139.991846 -289.963606)
		(width 0.0889)
		(layer "In13.Cu")
		(net "M_H_CPU1_SB_DQ<27>")
	)
	(arc
		(start 137.171684 -289.963606)
		(mid 137.45464 -290.039783)
		(end 137.737596 -289.963606)
		(width 0.0889)
		(layer "In13.Cu")
		(net "M_H_CPU1_SB_DQ<27>")
	)
	(arc
		(start 139.051792 -289.963606)
		(mid 139.334748 -290.039783)
		(end 139.617704 -289.963606)
		(width 0.0889)
		(layer "In13.Cu")
		(net "M_H_CPU1_SB_DQ<27>")
	)
	(arc
		(start 137.737596 -289.963606)
		(mid 137.919847 -289.913256)
		(end 138.103356 -289.95878)
		(width 0.0889)
		(layer "In13.Cu")
		(net "M_H_CPU1_SB_DQ<27>")
	)
	(arc
		(start 140.56614 -289.95878)
		(mid 140.749648 -289.913286)
		(end 140.9319 -289.963606)
		(width 0.0889)
		(layer "In13.Cu")
		(net "M_H_CPU1_SB_DQ<27>")
	)
	(arc
		(start 140.9319 -289.963606)
		(mid 141.214856 -290.039783)
		(end 141.497812 -289.963606)
		(width 0.0889)
		(layer "In13.Cu")
		(net "M_H_CPU1_SB_DQ<27>")
	)
	(arc
		(start 141.497812 -289.963606)
		(mid 141.684756 -289.913351)
		(end 141.8717 -289.963606)
		(width 0.0889)
		(layer "In13.Cu")
		(net "M_H_CPU1_SB_DQ<27>")
	)
	(segment
		(start 136.047988 -289.210242)
		(end 136.51484 -289.47618)
		(width 0.10668)
		(layer "F.Cu")
		(net "M_H_CPU1_SB_DQ<26>")
	)
	(segment
		(start 156.555186 -307.29809)
		(end 156.783786 -307.29809)
		(width 0.14478)
		(layer "In13.Cu")
		(net "M_H_CPU1_SB_DQ<26>")
	)
	(segment
		(start 168.918128 -309.960264)
		(end 169.198798 -309.679594)
		(width 0.14478)
		(layer "In13.Cu")
		(net "M_H_CPU1_SB_DQ<26>")
	)
	(segment
		(start 160.781746 -310.507126)
		(end 161.030158 -310.507126)
		(width 0.14478)
		(layer "In13.Cu")
		(net "M_H_CPU1_SB_DQ<26>")
	)
	(segment
		(start 161.581592 -310.810402)
		(end 161.884868 -310.507126)
		(width 0.14478)
		(layer "In13.Cu")
		(net "M_H_CPU1_SB_DQ<26>")
	)
	(segment
		(start 165.193472 -310.507126)
		(end 165.44163 -310.507126)
		(width 0.14478)
		(layer "In13.Cu")
		(net "M_H_CPU1_SB_DQ<26>")
	)
	(segment
		(start 170.18254 -309.960264)
		(end 171.032678 -310.810402)
		(width 0.14478)
		(layer "In13.Cu")
		(net "M_H_CPU1_SB_DQ<26>")
	)
	(segment
		(start 162.987736 -310.507126)
		(end 163.235894 -310.507126)
		(width 0.14478)
		(layer "In13.Cu")
		(net "M_H_CPU1_SB_DQ<26>")
	)
	(segment
		(start 164.642038 -310.810402)
		(end 164.890196 -310.810402)
		(width 0.14478)
		(layer "In13.Cu")
		(net "M_H_CPU1_SB_DQ<26>")
	)
	(segment
		(start 158.734506 -309.24881)
		(end 158.734506 -309.47741)
		(width 0.14478)
		(layer "In13.Cu")
		(net "M_H_CPU1_SB_DQ<26>")
	)
	(segment
		(start 146.357086 -290.941252)
		(end 146.514566 -291.321236)
		(width 0.0889)
		(layer "In13.Cu")
		(net "M_H_CPU1_SB_DQ<26>")
	)
	(segment
		(start 159.514794 -310.257698)
		(end 160.067498 -310.810402)
		(width 0.14478)
		(layer "In13.Cu")
		(net "M_H_CPU1_SB_DQ<26>")
	)
	(segment
		(start 163.53917 -310.810402)
		(end 163.787328 -310.810402)
		(width 0.14478)
		(layer "In13.Cu")
		(net "M_H_CPU1_SB_DQ<26>")
	)
	(segment
		(start 136.51484 -289.47618)
		(end 136.360662 -289.21075)
		(width 0.0889)
		(layer "In13.Cu")
		(net "M_H_CPU1_SB_DQ<26>")
	)
	(segment
		(start 156.546296 -306.755292)
		(end 156.393642 -306.907946)
		(width 0.14478)
		(layer "In13.Cu")
		(net "M_H_CPU1_SB_DQ<26>")
	)
	(segment
		(start 156.156152 -306.365148)
		(end 156.384752 -306.365148)
		(width 0.14478)
		(layer "In13.Cu")
		(net "M_H_CPU1_SB_DQ<26>")
	)
	(segment
		(start 144.701514 -289.28695)
		(end 145.594578 -289.28695)
		(width 0.0889)
		(layer "In13.Cu")
		(net "M_H_CPU1_SB_DQ<26>")
	)
	(segment
		(start 159.667448 -309.647844)
		(end 159.667448 -309.876444)
		(width 0.14478)
		(layer "In13.Cu")
		(net "M_H_CPU1_SB_DQ<26>")
	)
	(segment
		(start 149.72665 -300.469554)
		(end 155.774898 -306.517802)
		(width 0.14478)
		(layer "In13.Cu")
		(net "M_H_CPU1_SB_DQ<26>")
	)
	(segment
		(start 169.198798 -309.679594)
		(end 169.469308 -309.679594)
		(width 0.14478)
		(layer "In13.Cu")
		(net "M_H_CPU1_SB_DQ<26>")
	)
	(segment
		(start 161.884868 -310.507126)
		(end 162.133026 -310.507126)
		(width 0.14478)
		(layer "In13.Cu")
		(net "M_H_CPU1_SB_DQ<26>")
	)
	(segment
		(start 161.333434 -310.810402)
		(end 161.581592 -310.810402)
		(width 0.14478)
		(layer "In13.Cu")
		(net "M_H_CPU1_SB_DQ<26>")
	)
	(segment
		(start 136.693402 -289.148774)
		(end 136.701784 -289.1536)
		(width 0.0889)
		(layer "In13.Cu")
		(net "M_H_CPU1_SB_DQ<26>")
	)
	(segment
		(start 156.393642 -307.136546)
		(end 156.555186 -307.29809)
		(width 0.14478)
		(layer "In13.Cu")
		(net "M_H_CPU1_SB_DQ<26>")
	)
	(segment
		(start 145.594578 -289.28695)
		(end 146.357086 -290.049458)
		(width 0.0889)
		(layer "In13.Cu")
		(net "M_H_CPU1_SB_DQ<26>")
	)
	(segment
		(start 162.436302 -310.810402)
		(end 162.68446 -310.810402)
		(width 0.14478)
		(layer "In13.Cu")
		(net "M_H_CPU1_SB_DQ<26>")
	)
	(segment
		(start 158.734506 -309.47741)
		(end 158.89605 -309.638954)
		(width 0.14478)
		(layer "In13.Cu")
		(net "M_H_CPU1_SB_DQ<26>")
	)
	(segment
		(start 158.106872 -308.087268)
		(end 158.106872 -308.315868)
		(width 0.14478)
		(layer "In13.Cu")
		(net "M_H_CPU1_SB_DQ<26>")
	)
	(segment
		(start 156.393642 -306.907946)
		(end 156.393642 -307.136546)
		(width 0.14478)
		(layer "In13.Cu")
		(net "M_H_CPU1_SB_DQ<26>")
	)
	(segment
		(start 156.546296 -306.526692)
		(end 156.546296 -306.755292)
		(width 0.14478)
		(layer "In13.Cu")
		(net "M_H_CPU1_SB_DQ<26>")
	)
	(segment
		(start 165.44163 -310.507126)
		(end 165.744906 -310.810402)
		(width 0.14478)
		(layer "In13.Cu")
		(net "M_H_CPU1_SB_DQ<26>")
	)
	(segment
		(start 157.564074 -308.078378)
		(end 157.716728 -307.925724)
		(width 0.14478)
		(layer "In13.Cu")
		(net "M_H_CPU1_SB_DQ<26>")
	)
	(segment
		(start 147.89785 -292.222682)
		(end 149.72665 -294.051482)
		(width 0.14478)
		(layer "In13.Cu")
		(net "M_H_CPU1_SB_DQ<26>")
	)
	(segment
		(start 171.97197 -310.415432)
		(end 171.97197 -310.385206)
		(width 0.14478)
		(layer "In13.Cu")
		(net "M_H_CPU1_SB_DQ<26>")
	)
	(segment
		(start 157.16504 -307.145436)
		(end 157.326584 -307.30698)
		(width 0.14478)
		(layer "In13.Cu")
		(net "M_H_CPU1_SB_DQ<26>")
	)
	(segment
		(start 158.497016 -308.706012)
		(end 158.725616 -308.706012)
		(width 0.14478)
		(layer "In13.Cu")
		(net "M_H_CPU1_SB_DQ<26>")
	)
	(segment
		(start 156.003498 -306.517802)
		(end 156.156152 -306.365148)
		(width 0.14478)
		(layer "In13.Cu")
		(net "M_H_CPU1_SB_DQ<26>")
	)
	(segment
		(start 162.68446 -310.810402)
		(end 162.987736 -310.507126)
		(width 0.14478)
		(layer "In13.Cu")
		(net "M_H_CPU1_SB_DQ<26>")
	)
	(segment
		(start 157.17393 -307.916834)
		(end 157.335474 -308.078378)
		(width 0.14478)
		(layer "In13.Cu")
		(net "M_H_CPU1_SB_DQ<26>")
	)
	(segment
		(start 157.17393 -307.688234)
		(end 157.17393 -307.916834)
		(width 0.14478)
		(layer "In13.Cu")
		(net "M_H_CPU1_SB_DQ<26>")
	)
	(segment
		(start 171.032678 -310.810402)
		(end 171.577 -310.810402)
		(width 0.14478)
		(layer "In13.Cu")
		(net "M_H_CPU1_SB_DQ<26>")
	)
	(segment
		(start 158.88716 -308.867556)
		(end 158.88716 -309.096156)
		(width 0.14478)
		(layer "In13.Cu")
		(net "M_H_CPU1_SB_DQ<26>")
	)
	(segment
		(start 159.514794 -310.029098)
		(end 159.514794 -310.257698)
		(width 0.14478)
		(layer "In13.Cu")
		(net "M_H_CPU1_SB_DQ<26>")
	)
	(segment
		(start 157.716728 -307.925724)
		(end 157.945328 -307.925724)
		(width 0.14478)
		(layer "In13.Cu")
		(net "M_H_CPU1_SB_DQ<26>")
	)
	(segment
		(start 159.667448 -309.876444)
		(end 159.514794 -310.029098)
		(width 0.14478)
		(layer "In13.Cu")
		(net "M_H_CPU1_SB_DQ<26>")
	)
	(segment
		(start 160.067498 -310.810402)
		(end 160.47847 -310.810402)
		(width 0.14478)
		(layer "In13.Cu")
		(net "M_H_CPU1_SB_DQ<26>")
	)
	(segment
		(start 158.106872 -308.315868)
		(end 157.954218 -308.468522)
		(width 0.14478)
		(layer "In13.Cu")
		(net "M_H_CPU1_SB_DQ<26>")
	)
	(segment
		(start 160.47847 -310.810402)
		(end 160.781746 -310.507126)
		(width 0.14478)
		(layer "In13.Cu")
		(net "M_H_CPU1_SB_DQ<26>")
	)
	(segment
		(start 147.443952 -291.768784)
		(end 147.89785 -292.222682)
		(width 0.0889)
		(layer "In13.Cu")
		(net "M_H_CPU1_SB_DQ<26>")
	)
	(segment
		(start 157.335474 -308.078378)
		(end 157.564074 -308.078378)
		(width 0.14478)
		(layer "In13.Cu")
		(net "M_H_CPU1_SB_DQ<26>")
	)
	(segment
		(start 157.326584 -307.30698)
		(end 157.326584 -307.53558)
		(width 0.14478)
		(layer "In13.Cu")
		(net "M_H_CPU1_SB_DQ<26>")
	)
	(segment
		(start 141.393418 -289.148774)
		(end 141.4018 -289.1536)
		(width 0.0889)
		(layer "In13.Cu")
		(net "M_H_CPU1_SB_DQ<26>")
	)
	(segment
		(start 164.338762 -310.507126)
		(end 164.642038 -310.810402)
		(width 0.14478)
		(layer "In13.Cu")
		(net "M_H_CPU1_SB_DQ<26>")
	)
	(segment
		(start 163.787328 -310.810402)
		(end 164.090604 -310.507126)
		(width 0.14478)
		(layer "In13.Cu")
		(net "M_H_CPU1_SB_DQ<26>")
	)
	(segment
		(start 163.235894 -310.507126)
		(end 163.53917 -310.810402)
		(width 0.14478)
		(layer "In13.Cu")
		(net "M_H_CPU1_SB_DQ<26>")
	)
	(segment
		(start 167.815768 -309.960264)
		(end 168.096438 -309.679594)
		(width 0.14478)
		(layer "In13.Cu")
		(net "M_H_CPU1_SB_DQ<26>")
	)
	(segment
		(start 165.744906 -310.810402)
		(end 166.150036 -310.810402)
		(width 0.14478)
		(layer "In13.Cu")
		(net "M_H_CPU1_SB_DQ<26>")
	)
	(segment
		(start 164.890196 -310.810402)
		(end 165.193472 -310.507126)
		(width 0.14478)
		(layer "In13.Cu")
		(net "M_H_CPU1_SB_DQ<26>")
	)
	(segment
		(start 168.647618 -309.960264)
		(end 168.918128 -309.960264)
		(width 0.14478)
		(layer "In13.Cu")
		(net "M_H_CPU1_SB_DQ<26>")
	)
	(segment
		(start 157.954218 -308.697122)
		(end 158.115762 -308.858666)
		(width 0.14478)
		(layer "In13.Cu")
		(net "M_H_CPU1_SB_DQ<26>")
	)
	(segment
		(start 147.183856 -291.768784)
		(end 147.443952 -291.768784)
		(width 0.0889)
		(layer "In13.Cu")
		(net "M_H_CPU1_SB_DQ<26>")
	)
	(segment
		(start 157.326584 -307.53558)
		(end 157.17393 -307.688234)
		(width 0.14478)
		(layer "In13.Cu")
		(net "M_H_CPU1_SB_DQ<26>")
	)
	(segment
		(start 149.72665 -294.051482)
		(end 149.72665 -300.469554)
		(width 0.14478)
		(layer "In13.Cu")
		(net "M_H_CPU1_SB_DQ<26>")
	)
	(segment
		(start 159.12465 -309.638954)
		(end 159.277304 -309.4863)
		(width 0.14478)
		(layer "In13.Cu")
		(net "M_H_CPU1_SB_DQ<26>")
	)
	(segment
		(start 156.384752 -306.365148)
		(end 156.546296 -306.526692)
		(width 0.14478)
		(layer "In13.Cu")
		(net "M_H_CPU1_SB_DQ<26>")
	)
	(segment
		(start 168.366948 -309.679594)
		(end 168.647618 -309.960264)
		(width 0.14478)
		(layer "In13.Cu")
		(net "M_H_CPU1_SB_DQ<26>")
	)
	(segment
		(start 140.453364 -289.148774)
		(end 140.461746 -289.1536)
		(width 0.0889)
		(layer "In13.Cu")
		(net "M_H_CPU1_SB_DQ<26>")
	)
	(segment
		(start 158.115762 -308.858666)
		(end 158.344362 -308.858666)
		(width 0.14478)
		(layer "In13.Cu")
		(net "M_H_CPU1_SB_DQ<26>")
	)
	(segment
		(start 159.505904 -309.4863)
		(end 159.667448 -309.647844)
		(width 0.14478)
		(layer "In13.Cu")
		(net "M_H_CPU1_SB_DQ<26>")
	)
	(segment
		(start 137.267696 -289.1536)
		(end 137.276078 -289.148774)
		(width 0.0889)
		(layer "In13.Cu")
		(net "M_H_CPU1_SB_DQ<26>")
	)
	(segment
		(start 167.000174 -309.960264)
		(end 167.815768 -309.960264)
		(width 0.14478)
		(layer "In13.Cu")
		(net "M_H_CPU1_SB_DQ<26>")
	)
	(segment
		(start 146.514566 -291.321236)
		(end 147.183856 -291.768784)
		(width 0.0889)
		(layer "In13.Cu")
		(net "M_H_CPU1_SB_DQ<26>")
	)
	(segment
		(start 156.783786 -307.29809)
		(end 156.93644 -307.145436)
		(width 0.14478)
		(layer "In13.Cu")
		(net "M_H_CPU1_SB_DQ<26>")
	)
	(segment
		(start 158.88716 -309.096156)
		(end 158.734506 -309.24881)
		(width 0.14478)
		(layer "In13.Cu")
		(net "M_H_CPU1_SB_DQ<26>")
	)
	(segment
		(start 164.090604 -310.507126)
		(end 164.338762 -310.507126)
		(width 0.14478)
		(layer "In13.Cu")
		(net "M_H_CPU1_SB_DQ<26>")
	)
	(segment
		(start 157.945328 -307.925724)
		(end 158.106872 -308.087268)
		(width 0.14478)
		(layer "In13.Cu")
		(net "M_H_CPU1_SB_DQ<26>")
	)
	(segment
		(start 161.030158 -310.507126)
		(end 161.333434 -310.810402)
		(width 0.14478)
		(layer "In13.Cu")
		(net "M_H_CPU1_SB_DQ<26>")
	)
	(segment
		(start 141.967712 -289.1536)
		(end 141.976094 -289.148774)
		(width 0.0889)
		(layer "In13.Cu")
		(net "M_H_CPU1_SB_DQ<26>")
	)
	(segment
		(start 162.133026 -310.507126)
		(end 162.436302 -310.810402)
		(width 0.14478)
		(layer "In13.Cu")
		(net "M_H_CPU1_SB_DQ<26>")
	)
	(segment
		(start 158.725616 -308.706012)
		(end 158.88716 -308.867556)
		(width 0.14478)
		(layer "In13.Cu")
		(net "M_H_CPU1_SB_DQ<26>")
	)
	(segment
		(start 138.20775 -289.1536)
		(end 138.216132 -289.148774)
		(width 0.0889)
		(layer "In13.Cu")
		(net "M_H_CPU1_SB_DQ<26>")
	)
	(segment
		(start 171.577 -310.810402)
		(end 171.97197 -310.415432)
		(width 0.14478)
		(layer "In13.Cu")
		(net "M_H_CPU1_SB_DQ<26>")
	)
	(segment
		(start 159.277304 -309.4863)
		(end 159.505904 -309.4863)
		(width 0.14478)
		(layer "In13.Cu")
		(net "M_H_CPU1_SB_DQ<26>")
	)
	(segment
		(start 158.344362 -308.858666)
		(end 158.497016 -308.706012)
		(width 0.14478)
		(layer "In13.Cu")
		(net "M_H_CPU1_SB_DQ<26>")
	)
	(segment
		(start 169.749978 -309.960264)
		(end 170.18254 -309.960264)
		(width 0.14478)
		(layer "In13.Cu")
		(net "M_H_CPU1_SB_DQ<26>")
	)
	(segment
		(start 156.93644 -307.145436)
		(end 157.16504 -307.145436)
		(width 0.14478)
		(layer "In13.Cu")
		(net "M_H_CPU1_SB_DQ<26>")
	)
	(segment
		(start 146.357086 -290.049458)
		(end 146.357086 -290.941252)
		(width 0.0889)
		(layer "In13.Cu")
		(net "M_H_CPU1_SB_DQ<26>")
	)
	(segment
		(start 166.150036 -310.810402)
		(end 167.000174 -309.960264)
		(width 0.14478)
		(layer "In13.Cu")
		(net "M_H_CPU1_SB_DQ<26>")
	)
	(segment
		(start 157.954218 -308.468522)
		(end 157.954218 -308.697122)
		(width 0.14478)
		(layer "In13.Cu")
		(net "M_H_CPU1_SB_DQ<26>")
	)
	(segment
		(start 169.469308 -309.679594)
		(end 169.749978 -309.960264)
		(width 0.14478)
		(layer "In13.Cu")
		(net "M_H_CPU1_SB_DQ<26>")
	)
	(segment
		(start 136.360662 -289.21075)
		(end 136.383014 -289.127438)
		(width 0.0889)
		(layer "In13.Cu")
		(net "M_H_CPU1_SB_DQ<26>")
	)
	(segment
		(start 158.89605 -309.638954)
		(end 159.12465 -309.638954)
		(width 0.14478)
		(layer "In13.Cu")
		(net "M_H_CPU1_SB_DQ<26>")
	)
	(segment
		(start 168.096438 -309.679594)
		(end 168.366948 -309.679594)
		(width 0.14478)
		(layer "In13.Cu")
		(net "M_H_CPU1_SB_DQ<26>")
	)
	(segment
		(start 155.774898 -306.517802)
		(end 156.003498 -306.517802)
		(width 0.14478)
		(layer "In13.Cu")
		(net "M_H_CPU1_SB_DQ<26>")
	)
	(arc
		(start 141.976094 -289.148774)
		(mid 142.159602 -289.10328)
		(end 142.341854 -289.1536)
		(width 0.0889)
		(layer "In13.Cu")
		(net "M_H_CPU1_SB_DQ<26>")
	)
	(arc
		(start 143.281654 -289.1536)
		(mid 143.56461 -289.229777)
		(end 143.847566 -289.1536)
		(width 0.0889)
		(layer "In13.Cu")
		(net "M_H_CPU1_SB_DQ<26>")
	)
	(arc
		(start 137.276078 -289.148774)
		(mid 137.459586 -289.10328)
		(end 137.641838 -289.1536)
		(width 0.0889)
		(layer "In13.Cu")
		(net "M_H_CPU1_SB_DQ<26>")
	)
	(arc
		(start 136.383014 -289.127438)
		(mid 136.540524 -289.10424)
		(end 136.693402 -289.148774)
		(width 0.0889)
		(layer "In13.Cu")
		(net "M_H_CPU1_SB_DQ<26>")
	)
	(arc
		(start 140.087604 -289.1536)
		(mid 140.269855 -289.10325)
		(end 140.453364 -289.148774)
		(width 0.0889)
		(layer "In13.Cu")
		(net "M_H_CPU1_SB_DQ<26>")
	)
	(arc
		(start 136.701784 -289.1536)
		(mid 136.98474 -289.229777)
		(end 137.267696 -289.1536)
		(width 0.0889)
		(layer "In13.Cu")
		(net "M_H_CPU1_SB_DQ<26>")
	)
	(arc
		(start 140.461746 -289.1536)
		(mid 140.744702 -289.229777)
		(end 141.027658 -289.1536)
		(width 0.0889)
		(layer "In13.Cu")
		(net "M_H_CPU1_SB_DQ<26>")
	)
	(arc
		(start 144.20088 -289.142424)
		(mid 144.444623 -289.237462)
		(end 144.701514 -289.28695)
		(width 0.0889)
		(layer "In13.Cu")
		(net "M_H_CPU1_SB_DQ<26>")
	)
	(arc
		(start 142.341854 -289.1536)
		(mid 142.62481 -289.229777)
		(end 142.907766 -289.1536)
		(width 0.0889)
		(layer "In13.Cu")
		(net "M_H_CPU1_SB_DQ<26>")
	)
	(arc
		(start 142.907766 -289.1536)
		(mid 143.09471 -289.103345)
		(end 143.281654 -289.1536)
		(width 0.0889)
		(layer "In13.Cu")
		(net "M_H_CPU1_SB_DQ<26>")
	)
	(arc
		(start 141.027658 -289.1536)
		(mid 141.209909 -289.10325)
		(end 141.393418 -289.148774)
		(width 0.0889)
		(layer "In13.Cu")
		(net "M_H_CPU1_SB_DQ<26>")
	)
	(arc
		(start 137.641838 -289.1536)
		(mid 137.924794 -289.229777)
		(end 138.20775 -289.1536)
		(width 0.0889)
		(layer "In13.Cu")
		(net "M_H_CPU1_SB_DQ<26>")
	)
	(arc
		(start 139.521692 -289.1536)
		(mid 139.804648 -289.229777)
		(end 140.087604 -289.1536)
		(width 0.0889)
		(layer "In13.Cu")
		(net "M_H_CPU1_SB_DQ<26>")
	)
	(arc
		(start 141.4018 -289.1536)
		(mid 141.684756 -289.229777)
		(end 141.967712 -289.1536)
		(width 0.0889)
		(layer "In13.Cu")
		(net "M_H_CPU1_SB_DQ<26>")
	)
	(arc
		(start 139.147804 -289.1536)
		(mid 139.334748 -289.103345)
		(end 139.521692 -289.1536)
		(width 0.0889)
		(layer "In13.Cu")
		(net "M_H_CPU1_SB_DQ<26>")
	)
	(arc
		(start 143.847566 -289.1536)
		(mid 144.022805 -289.103529)
		(end 144.20088 -289.142424)
		(width 0.0889)
		(layer "In13.Cu")
		(net "M_H_CPU1_SB_DQ<26>")
	)
	(arc
		(start 138.581892 -289.1536)
		(mid 138.864848 -289.229777)
		(end 139.147804 -289.1536)
		(width 0.0889)
		(layer "In13.Cu")
		(net "M_H_CPU1_SB_DQ<26>")
	)
	(arc
		(start 138.216132 -289.148774)
		(mid 138.39964 -289.10328)
		(end 138.581892 -289.1536)
		(width 0.0889)
		(layer "In13.Cu")
		(net "M_H_CPU1_SB_DQ<26>")
	)
	(segment
		(start 134.16788 -289.210242)
		(end 134.634732 -289.47618)
		(width 0.10668)
		(layer "F.Cu")
		(net "M_H_CPU1_SB_DQ<25>")
	)
	(segment
		(start 140.453364 -289.803586)
		(end 140.461746 -289.79876)
		(width 0.0889)
		(layer "In13.Cu")
		(net "M_H_CPU1_SB_DQ<25>")
	)
	(segment
		(start 149.27707 -294.245284)
		(end 149.27707 -300.65599)
		(width 0.14478)
		(layer "In13.Cu")
		(net "M_H_CPU1_SB_DQ<25>")
	)
	(segment
		(start 146.35734 -291.486336)
		(end 147.305776 -292.119812)
		(width 0.0889)
		(layer "In13.Cu")
		(net "M_H_CPU1_SB_DQ<25>")
	)
	(segment
		(start 144.563084 -289.849306)
		(end 144.79778 -289.61461)
		(width 0.0889)
		(layer "In13.Cu")
		(net "M_H_CPU1_SB_DQ<25>")
	)
	(segment
		(start 167.32504 -310.810402)
		(end 169.19448 -310.810402)
		(width 0.14478)
		(layer "In13.Cu")
		(net "M_H_CPU1_SB_DQ<25>")
	)
	(segment
		(start 137.267696 -289.79876)
		(end 137.276078 -289.803586)
		(width 0.0889)
		(layer "In13.Cu")
		(net "M_H_CPU1_SB_DQ<25>")
	)
	(segment
		(start 173.20641 -311.660286)
		(end 176.072038 -311.235344)
		(width 0.14478)
		(layer "In13.Cu")
		(net "M_H_CPU1_SB_DQ<25>")
	)
	(segment
		(start 160.281366 -311.660286)
		(end 165.273228 -311.660286)
		(width 0.14478)
		(layer "In13.Cu")
		(net "M_H_CPU1_SB_DQ<25>")
	)
	(segment
		(start 141.967712 -289.79876)
		(end 141.976094 -289.803586)
		(width 0.0889)
		(layer "In13.Cu")
		(net "M_H_CPU1_SB_DQ<25>")
	)
	(segment
		(start 145.62328 -289.61461)
		(end 146.136106 -290.127436)
		(width 0.0889)
		(layer "In13.Cu")
		(net "M_H_CPU1_SB_DQ<25>")
	)
	(segment
		(start 147.305776 -292.119812)
		(end 147.482814 -292.451028)
		(width 0.0889)
		(layer "In13.Cu")
		(net "M_H_CPU1_SB_DQ<25>")
	)
	(segment
		(start 134.788656 -289.74161)
		(end 134.884668 -289.76701)
		(width 0.0889)
		(layer "In13.Cu")
		(net "M_H_CPU1_SB_DQ<25>")
	)
	(segment
		(start 171.246292 -311.660286)
		(end 173.20641 -311.660286)
		(width 0.14478)
		(layer "In13.Cu")
		(net "M_H_CPU1_SB_DQ<25>")
	)
	(segment
		(start 169.19448 -310.810402)
		(end 171.246292 -311.660286)
		(width 0.14478)
		(layer "In13.Cu")
		(net "M_H_CPU1_SB_DQ<25>")
	)
	(segment
		(start 147.883626 -292.85184)
		(end 149.27707 -294.245284)
		(width 0.14478)
		(layer "In13.Cu")
		(net "M_H_CPU1_SB_DQ<25>")
	)
	(segment
		(start 134.634732 -289.47618)
		(end 134.788656 -289.74161)
		(width 0.0889)
		(layer "In13.Cu")
		(net "M_H_CPU1_SB_DQ<25>")
	)
	(segment
		(start 135.753348 -289.803586)
		(end 135.76173 -289.79876)
		(width 0.0889)
		(layer "In13.Cu")
		(net "M_H_CPU1_SB_DQ<25>")
	)
	(segment
		(start 138.20775 -289.79876)
		(end 138.216132 -289.803586)
		(width 0.0889)
		(layer "In13.Cu")
		(net "M_H_CPU1_SB_DQ<25>")
	)
	(segment
		(start 136.693402 -289.803586)
		(end 136.701784 -289.79876)
		(width 0.0889)
		(layer "In13.Cu")
		(net "M_H_CPU1_SB_DQ<25>")
	)
	(segment
		(start 141.393418 -289.803586)
		(end 141.4018 -289.79876)
		(width 0.0889)
		(layer "In13.Cu")
		(net "M_H_CPU1_SB_DQ<25>")
	)
	(segment
		(start 165.273228 -311.660286)
		(end 167.32504 -310.810402)
		(width 0.14478)
		(layer "In13.Cu")
		(net "M_H_CPU1_SB_DQ<25>")
	)
	(segment
		(start 146.136106 -290.127436)
		(end 146.136106 -290.952428)
		(width 0.0889)
		(layer "In13.Cu")
		(net "M_H_CPU1_SB_DQ<25>")
	)
	(segment
		(start 146.136106 -290.952428)
		(end 146.35734 -291.486336)
		(width 0.0889)
		(layer "In13.Cu")
		(net "M_H_CPU1_SB_DQ<25>")
	)
	(segment
		(start 144.79778 -289.61461)
		(end 145.62328 -289.61461)
		(width 0.0889)
		(layer "In13.Cu")
		(net "M_H_CPU1_SB_DQ<25>")
	)
	(segment
		(start 147.482814 -292.451028)
		(end 147.883626 -292.85184)
		(width 0.0889)
		(layer "In13.Cu")
		(net "M_H_CPU1_SB_DQ<25>")
	)
	(segment
		(start 144.034764 -289.849306)
		(end 144.563084 -289.849306)
		(width 0.0889)
		(layer "In13.Cu")
		(net "M_H_CPU1_SB_DQ<25>")
	)
	(segment
		(start 149.27707 -300.65599)
		(end 160.281366 -311.660286)
		(width 0.14478)
		(layer "In13.Cu")
		(net "M_H_CPU1_SB_DQ<25>")
	)
	(arc
		(start 141.027658 -289.79876)
		(mid 141.209909 -289.84911)
		(end 141.393418 -289.803586)
		(width 0.0889)
		(layer "In13.Cu")
		(net "M_H_CPU1_SB_DQ<25>")
	)
	(arc
		(start 142.907766 -289.79876)
		(mid 143.09471 -289.849015)
		(end 143.281654 -289.79876)
		(width 0.0889)
		(layer "In13.Cu")
		(net "M_H_CPU1_SB_DQ<25>")
	)
	(arc
		(start 134.884668 -289.76701)
		(mid 135.139876 -289.723533)
		(end 135.387588 -289.79876)
		(width 0.0889)
		(layer "In13.Cu")
		(net "M_H_CPU1_SB_DQ<25>")
	)
	(arc
		(start 138.581892 -289.79876)
		(mid 138.864848 -289.722583)
		(end 139.147804 -289.79876)
		(width 0.0889)
		(layer "In13.Cu")
		(net "M_H_CPU1_SB_DQ<25>")
	)
	(arc
		(start 135.387588 -289.79876)
		(mid 135.569839 -289.84911)
		(end 135.753348 -289.803586)
		(width 0.0889)
		(layer "In13.Cu")
		(net "M_H_CPU1_SB_DQ<25>")
	)
	(arc
		(start 137.276078 -289.803586)
		(mid 137.459586 -289.84908)
		(end 137.641838 -289.79876)
		(width 0.0889)
		(layer "In13.Cu")
		(net "M_H_CPU1_SB_DQ<25>")
	)
	(arc
		(start 140.461746 -289.79876)
		(mid 140.744702 -289.722583)
		(end 141.027658 -289.79876)
		(width 0.0889)
		(layer "In13.Cu")
		(net "M_H_CPU1_SB_DQ<25>")
	)
	(arc
		(start 141.4018 -289.79876)
		(mid 141.684756 -289.722583)
		(end 141.967712 -289.79876)
		(width 0.0889)
		(layer "In13.Cu")
		(net "M_H_CPU1_SB_DQ<25>")
	)
	(arc
		(start 141.976094 -289.803586)
		(mid 142.159602 -289.84908)
		(end 142.341854 -289.79876)
		(width 0.0889)
		(layer "In13.Cu")
		(net "M_H_CPU1_SB_DQ<25>")
	)
	(arc
		(start 139.521692 -289.79876)
		(mid 139.804648 -289.722583)
		(end 140.087604 -289.79876)
		(width 0.0889)
		(layer "In13.Cu")
		(net "M_H_CPU1_SB_DQ<25>")
	)
	(arc
		(start 137.641838 -289.79876)
		(mid 137.924794 -289.722583)
		(end 138.20775 -289.79876)
		(width 0.0889)
		(layer "In13.Cu")
		(net "M_H_CPU1_SB_DQ<25>")
	)
	(arc
		(start 139.147804 -289.79876)
		(mid 139.334748 -289.849015)
		(end 139.521692 -289.79876)
		(width 0.0889)
		(layer "In13.Cu")
		(net "M_H_CPU1_SB_DQ<25>")
	)
	(arc
		(start 143.281654 -289.79876)
		(mid 143.56461 -289.722583)
		(end 143.847566 -289.79876)
		(width 0.0889)
		(layer "In13.Cu")
		(net "M_H_CPU1_SB_DQ<25>")
	)
	(arc
		(start 135.76173 -289.79876)
		(mid 136.044686 -289.722583)
		(end 136.327642 -289.79876)
		(width 0.0889)
		(layer "In13.Cu")
		(net "M_H_CPU1_SB_DQ<25>")
	)
	(arc
		(start 138.216132 -289.803586)
		(mid 138.39964 -289.84908)
		(end 138.581892 -289.79876)
		(width 0.0889)
		(layer "In13.Cu")
		(net "M_H_CPU1_SB_DQ<25>")
	)
	(arc
		(start 142.341854 -289.79876)
		(mid 142.62481 -289.722583)
		(end 142.907766 -289.79876)
		(width 0.0889)
		(layer "In13.Cu")
		(net "M_H_CPU1_SB_DQ<25>")
	)
	(arc
		(start 136.327642 -289.79876)
		(mid 136.509893 -289.84911)
		(end 136.693402 -289.803586)
		(width 0.0889)
		(layer "In13.Cu")
		(net "M_H_CPU1_SB_DQ<25>")
	)
	(arc
		(start 143.847566 -289.79876)
		(mid 143.937822 -289.836413)
		(end 144.034764 -289.849306)
		(width 0.0889)
		(layer "In13.Cu")
		(net "M_H_CPU1_SB_DQ<25>")
	)
	(arc
		(start 140.087604 -289.79876)
		(mid 140.269855 -289.84911)
		(end 140.453364 -289.803586)
		(width 0.0889)
		(layer "In13.Cu")
		(net "M_H_CPU1_SB_DQ<25>")
	)
	(arc
		(start 136.701784 -289.79876)
		(mid 136.98474 -289.722583)
		(end 137.267696 -289.79876)
		(width 0.0889)
		(layer "In13.Cu")
		(net "M_H_CPU1_SB_DQ<25>")
	)
	(segment
		(start 135.577834 -288.400236)
		(end 136.044686 -288.666174)
		(width 0.10668)
		(layer "F.Cu")
		(net "M_H_CPU1_SB_DQ<24>")
	)
	(segment
		(start 170.117516 -309.11038)
		(end 170.9674 -309.960264)
		(width 0.14478)
		(layer "In13.Cu")
		(net "M_H_CPU1_SB_DQ<24>")
	)
	(segment
		(start 144.615154 -289.043364)
		(end 145.643092 -289.043364)
		(width 0.0889)
		(layer "In13.Cu")
		(net "M_H_CPU1_SB_DQ<24>")
	)
	(segment
		(start 136.044686 -288.666174)
		(end 136.198864 -288.931604)
		(width 0.0889)
		(layer "In13.Cu")
		(net "M_H_CPU1_SB_DQ<24>")
	)
	(segment
		(start 154.879294 -304.781204)
		(end 155.050744 -304.609754)
		(width 0.14478)
		(layer "In13.Cu")
		(net "M_H_CPU1_SB_DQ<24>")
	)
	(segment
		(start 154.67457 -304.781204)
		(end 154.879294 -304.781204)
		(width 0.14478)
		(layer "In13.Cu")
		(net "M_H_CPU1_SB_DQ<24>")
	)
	(segment
		(start 155.44038 -304.999644)
		(end 155.26893 -305.171094)
		(width 0.14478)
		(layer "In13.Cu")
		(net "M_H_CPU1_SB_DQ<24>")
	)
	(segment
		(start 144.294606 -288.976054)
		(end 144.513808 -289.033458)
		(width 0.0889)
		(layer "In13.Cu")
		(net "M_H_CPU1_SB_DQ<24>")
	)
	(segment
		(start 150.17623 -293.857934)
		(end 150.17623 -300.282864)
		(width 0.14478)
		(layer "In13.Cu")
		(net "M_H_CPU1_SB_DQ<24>")
	)
	(segment
		(start 146.603466 -291.004244)
		(end 146.953986 -291.354764)
		(width 0.0889)
		(layer "In13.Cu")
		(net "M_H_CPU1_SB_DQ<24>")
	)
	(segment
		(start 136.198864 -288.931604)
		(end 136.29513 -288.957004)
		(width 0.0889)
		(layer "In13.Cu")
		(net "M_H_CPU1_SB_DQ<24>")
	)
	(segment
		(start 174.211996 -309.535322)
		(end 176.072038 -309.535322)
		(width 0.14478)
		(layer "In13.Cu")
		(net "M_H_CPU1_SB_DQ<24>")
	)
	(segment
		(start 139.04341 -288.99358)
		(end 139.051792 -288.988754)
		(width 0.0889)
		(layer "In13.Cu")
		(net "M_H_CPU1_SB_DQ<24>")
	)
	(segment
		(start 154.6606 -304.01514)
		(end 154.6606 -304.219864)
		(width 0.14478)
		(layer "In13.Cu")
		(net "M_H_CPU1_SB_DQ<24>")
	)
	(segment
		(start 154.270964 -303.829974)
		(end 154.47518 -303.82972)
		(width 0.14478)
		(layer "In13.Cu")
		(net "M_H_CPU1_SB_DQ<24>")
	)
	(segment
		(start 155.25496 -304.6095)
		(end 155.44038 -304.79492)
		(width 0.14478)
		(layer "In13.Cu")
		(net "M_H_CPU1_SB_DQ<24>")
	)
	(segment
		(start 160.681162 -309.960264)
		(end 166.243 -309.960264)
		(width 0.14478)
		(layer "In13.Cu")
		(net "M_H_CPU1_SB_DQ<24>")
	)
	(segment
		(start 155.26893 -305.171094)
		(end 155.269184 -305.375818)
		(width 0.14478)
		(layer "In13.Cu")
		(net "M_H_CPU1_SB_DQ<24>")
	)
	(segment
		(start 154.6606 -304.219864)
		(end 154.48915 -304.391314)
		(width 0.14478)
		(layer "In13.Cu")
		(net "M_H_CPU1_SB_DQ<24>")
	)
	(segment
		(start 143.377666 -288.988754)
		(end 143.386048 -288.99358)
		(width 0.0889)
		(layer "In13.Cu")
		(net "M_H_CPU1_SB_DQ<24>")
	)
	(segment
		(start 156.306266 -305.585368)
		(end 160.681162 -309.960264)
		(width 0.14478)
		(layer "In13.Cu")
		(net "M_H_CPU1_SB_DQ<24>")
	)
	(segment
		(start 155.269184 -305.375818)
		(end 155.478734 -305.585368)
		(width 0.14478)
		(layer "In13.Cu")
		(net "M_H_CPU1_SB_DQ<24>")
	)
	(segment
		(start 154.099514 -304.001424)
		(end 154.270964 -303.829974)
		(width 0.14478)
		(layer "In13.Cu")
		(net "M_H_CPU1_SB_DQ<24>")
	)
	(segment
		(start 147.67306 -291.354764)
		(end 147.894548 -291.576252)
		(width 0.0889)
		(layer "In13.Cu")
		(net "M_H_CPU1_SB_DQ<24>")
	)
	(segment
		(start 144.513808 -289.033458)
		(end 144.615154 -289.043364)
		(width 0.0889)
		(layer "In13.Cu")
		(net "M_H_CPU1_SB_DQ<24>")
	)
	(segment
		(start 150.17623 -300.282864)
		(end 153.89479 -304.001424)
		(width 0.14478)
		(layer "In13.Cu")
		(net "M_H_CPU1_SB_DQ<24>")
	)
	(segment
		(start 166.243 -309.960264)
		(end 167.092884 -309.11038)
		(width 0.14478)
		(layer "In13.Cu")
		(net "M_H_CPU1_SB_DQ<24>")
	)
	(segment
		(start 146.603466 -290.003738)
		(end 146.603466 -291.004244)
		(width 0.0889)
		(layer "In13.Cu")
		(net "M_H_CPU1_SB_DQ<24>")
	)
	(segment
		(start 154.48915 -304.391314)
		(end 154.489404 -304.596038)
		(width 0.14478)
		(layer "In13.Cu")
		(net "M_H_CPU1_SB_DQ<24>")
	)
	(segment
		(start 173.787054 -309.960264)
		(end 174.211996 -309.535322)
		(width 0.14478)
		(layer "In13.Cu")
		(net "M_H_CPU1_SB_DQ<24>")
	)
	(segment
		(start 146.953986 -291.354764)
		(end 147.67306 -291.354764)
		(width 0.0889)
		(layer "In13.Cu")
		(net "M_H_CPU1_SB_DQ<24>")
	)
	(segment
		(start 142.803372 -288.99358)
		(end 142.811754 -288.988754)
		(width 0.0889)
		(layer "In13.Cu")
		(net "M_H_CPU1_SB_DQ<24>")
	)
	(segment
		(start 155.478734 -305.585368)
		(end 156.306266 -305.585368)
		(width 0.14478)
		(layer "In13.Cu")
		(net "M_H_CPU1_SB_DQ<24>")
	)
	(segment
		(start 153.89479 -304.001424)
		(end 154.099514 -304.001424)
		(width 0.14478)
		(layer "In13.Cu")
		(net "M_H_CPU1_SB_DQ<24>")
	)
	(segment
		(start 139.617704 -288.988754)
		(end 139.626086 -288.99358)
		(width 0.0889)
		(layer "In13.Cu")
		(net "M_H_CPU1_SB_DQ<24>")
	)
	(segment
		(start 155.050744 -304.609754)
		(end 155.25496 -304.6095)
		(width 0.14478)
		(layer "In13.Cu")
		(net "M_H_CPU1_SB_DQ<24>")
	)
	(segment
		(start 138.103356 -288.99358)
		(end 138.111738 -288.988754)
		(width 0.0889)
		(layer "In13.Cu")
		(net "M_H_CPU1_SB_DQ<24>")
	)
	(segment
		(start 140.557758 -288.988754)
		(end 140.56614 -288.99358)
		(width 0.0889)
		(layer "In13.Cu")
		(net "M_H_CPU1_SB_DQ<24>")
	)
	(segment
		(start 154.489404 -304.596038)
		(end 154.67457 -304.781204)
		(width 0.14478)
		(layer "In13.Cu")
		(net "M_H_CPU1_SB_DQ<24>")
	)
	(segment
		(start 147.894548 -291.576252)
		(end 150.17623 -293.857934)
		(width 0.14478)
		(layer "In13.Cu")
		(net "M_H_CPU1_SB_DQ<24>")
	)
	(segment
		(start 167.092884 -309.11038)
		(end 170.117516 -309.11038)
		(width 0.14478)
		(layer "In13.Cu")
		(net "M_H_CPU1_SB_DQ<24>")
	)
	(segment
		(start 154.47518 -303.82972)
		(end 154.6606 -304.01514)
		(width 0.14478)
		(layer "In13.Cu")
		(net "M_H_CPU1_SB_DQ<24>")
	)
	(segment
		(start 155.44038 -304.79492)
		(end 155.44038 -304.999644)
		(width 0.14478)
		(layer "In13.Cu")
		(net "M_H_CPU1_SB_DQ<24>")
	)
	(segment
		(start 145.643092 -289.043364)
		(end 146.603466 -290.003738)
		(width 0.0889)
		(layer "In13.Cu")
		(net "M_H_CPU1_SB_DQ<24>")
	)
	(segment
		(start 170.9674 -309.960264)
		(end 173.787054 -309.960264)
		(width 0.14478)
		(layer "In13.Cu")
		(net "M_H_CPU1_SB_DQ<24>")
	)
	(arc
		(start 138.111738 -288.988754)
		(mid 138.394694 -288.912577)
		(end 138.67765 -288.988754)
		(width 0.0889)
		(layer "In13.Cu")
		(net "M_H_CPU1_SB_DQ<24>")
	)
	(arc
		(start 136.797796 -288.988754)
		(mid 136.98474 -289.039009)
		(end 137.171684 -288.988754)
		(width 0.0889)
		(layer "In13.Cu")
		(net "M_H_CPU1_SB_DQ<24>")
	)
	(arc
		(start 141.497812 -288.988754)
		(mid 141.684756 -289.039009)
		(end 141.8717 -288.988754)
		(width 0.0889)
		(layer "In13.Cu")
		(net "M_H_CPU1_SB_DQ<24>")
	)
	(arc
		(start 139.991846 -288.988754)
		(mid 140.274802 -288.912577)
		(end 140.557758 -288.988754)
		(width 0.0889)
		(layer "In13.Cu")
		(net "M_H_CPU1_SB_DQ<24>")
	)
	(arc
		(start 139.626086 -288.99358)
		(mid 139.809594 -289.039074)
		(end 139.991846 -288.988754)
		(width 0.0889)
		(layer "In13.Cu")
		(net "M_H_CPU1_SB_DQ<24>")
	)
	(arc
		(start 141.8717 -288.988754)
		(mid 142.154656 -288.912577)
		(end 142.437612 -288.988754)
		(width 0.0889)
		(layer "In13.Cu")
		(net "M_H_CPU1_SB_DQ<24>")
	)
	(arc
		(start 138.67765 -288.988754)
		(mid 138.859901 -289.039104)
		(end 139.04341 -288.99358)
		(width 0.0889)
		(layer "In13.Cu")
		(net "M_H_CPU1_SB_DQ<24>")
	)
	(arc
		(start 140.9319 -288.988754)
		(mid 141.214856 -288.912577)
		(end 141.497812 -288.988754)
		(width 0.0889)
		(layer "In13.Cu")
		(net "M_H_CPU1_SB_DQ<24>")
	)
	(arc
		(start 136.29513 -288.957004)
		(mid 136.550195 -288.913653)
		(end 136.797796 -288.988754)
		(width 0.0889)
		(layer "In13.Cu")
		(net "M_H_CPU1_SB_DQ<24>")
	)
	(arc
		(start 143.751808 -288.988754)
		(mid 144.021577 -288.912731)
		(end 144.294606 -288.976054)
		(width 0.0889)
		(layer "In13.Cu")
		(net "M_H_CPU1_SB_DQ<24>")
	)
	(arc
		(start 139.051792 -288.988754)
		(mid 139.334748 -288.912577)
		(end 139.617704 -288.988754)
		(width 0.0889)
		(layer "In13.Cu")
		(net "M_H_CPU1_SB_DQ<24>")
	)
	(arc
		(start 142.437612 -288.988754)
		(mid 142.619863 -289.039104)
		(end 142.803372 -288.99358)
		(width 0.0889)
		(layer "In13.Cu")
		(net "M_H_CPU1_SB_DQ<24>")
	)
	(arc
		(start 143.386048 -288.99358)
		(mid 143.569556 -289.039074)
		(end 143.751808 -288.988754)
		(width 0.0889)
		(layer "In13.Cu")
		(net "M_H_CPU1_SB_DQ<24>")
	)
	(arc
		(start 142.811754 -288.988754)
		(mid 143.09471 -288.912577)
		(end 143.377666 -288.988754)
		(width 0.0889)
		(layer "In13.Cu")
		(net "M_H_CPU1_SB_DQ<24>")
	)
	(arc
		(start 137.737596 -288.988754)
		(mid 137.919847 -289.039104)
		(end 138.103356 -288.99358)
		(width 0.0889)
		(layer "In13.Cu")
		(net "M_H_CPU1_SB_DQ<24>")
	)
	(arc
		(start 137.171684 -288.988754)
		(mid 137.45464 -288.912577)
		(end 137.737596 -288.988754)
		(width 0.0889)
		(layer "In13.Cu")
		(net "M_H_CPU1_SB_DQ<24>")
	)
	(arc
		(start 140.56614 -288.99358)
		(mid 140.749648 -289.039074)
		(end 140.9319 -288.988754)
		(width 0.0889)
		(layer "In13.Cu")
		(net "M_H_CPU1_SB_DQ<24>")
	)
	(segment
		(start 134.63778 -288.400236)
		(end 135.104632 -288.666174)
		(width 0.10668)
		(layer "F.Cu")
		(net "M_H_CPU1_SB_DQ<23>")
	)
	(segment
		(start 139.04341 -288.339022)
		(end 139.051792 -288.343848)
		(width 0.0889)
		(layer "In13.Cu")
		(net "M_H_CPU1_SB_DQ<23>")
	)
	(segment
		(start 165.691058 -309.110634)
		(end 166.150036 -309.110634)
		(width 0.14478)
		(layer "In13.Cu")
		(net "M_H_CPU1_SB_DQ<23>")
	)
	(segment
		(start 160.749742 -308.349396)
		(end 160.749742 -308.55412)
		(width 0.14478)
		(layer "In13.Cu")
		(net "M_H_CPU1_SB_DQ<23>")
	)
	(segment
		(start 160.688274 -309.110634)
		(end 161.543238 -309.110634)
		(width 0.14478)
		(layer "In13.Cu")
		(net "M_H_CPU1_SB_DQ<23>")
	)
	(segment
		(start 171.947332 -308.710076)
		(end 171.97197 -308.685438)
		(width 0.14478)
		(layer "In13.Cu")
		(net "M_H_CPU1_SB_DQ<23>")
	)
	(segment
		(start 163.892738 -308.900576)
		(end 164.037518 -308.755796)
		(width 0.14478)
		(layer "In13.Cu")
		(net "M_H_CPU1_SB_DQ<23>")
	)
	(segment
		(start 166.150036 -309.110634)
		(end 167.000174 -308.260496)
		(width 0.14478)
		(layer "In13.Cu")
		(net "M_H_CPU1_SB_DQ<23>")
	)
	(segment
		(start 139.617704 -288.343848)
		(end 139.626086 -288.339022)
		(width 0.0889)
		(layer "In13.Cu")
		(net "M_H_CPU1_SB_DQ<23>")
	)
	(segment
		(start 170.63212 -308.710076)
		(end 171.947332 -308.710076)
		(width 0.14478)
		(layer "In13.Cu")
		(net "M_H_CPU1_SB_DQ<23>")
	)
	(segment
		(start 162.790378 -308.797198)
		(end 162.935158 -308.652418)
		(width 0.14478)
		(layer "In13.Cu")
		(net "M_H_CPU1_SB_DQ<23>")
	)
	(segment
		(start 144.6149 -288.23793)
		(end 145.534634 -288.23793)
		(width 0.0889)
		(layer "In13.Cu")
		(net "M_H_CPU1_SB_DQ<23>")
	)
	(segment
		(start 170.18254 -308.260496)
		(end 170.63212 -308.710076)
		(width 0.14478)
		(layer "In13.Cu")
		(net "M_H_CPU1_SB_DQ<23>")
	)
	(segment
		(start 160.749742 -308.55412)
		(end 160.543494 -308.760368)
		(width 0.14478)
		(layer "In13.Cu")
		(net "M_H_CPU1_SB_DQ<23>")
	)
	(segment
		(start 163.341558 -308.797198)
		(end 163.341558 -308.965854)
		(width 0.14478)
		(layer "In13.Cu")
		(net "M_H_CPU1_SB_DQ<23>")
	)
	(segment
		(start 160.359852 -308.16423)
		(end 160.564576 -308.16423)
		(width 0.14478)
		(layer "In13.Cu")
		(net "M_H_CPU1_SB_DQ<23>")
	)
	(segment
		(start 162.645598 -309.11038)
		(end 162.790378 -308.9656)
		(width 0.14478)
		(layer "In13.Cu")
		(net "M_H_CPU1_SB_DQ<23>")
	)
	(segment
		(start 162.790378 -308.9656)
		(end 162.790378 -308.797198)
		(width 0.14478)
		(layer "In13.Cu")
		(net "M_H_CPU1_SB_DQ<23>")
	)
	(segment
		(start 165.401498 -308.755796)
		(end 165.546278 -308.900576)
		(width 0.14478)
		(layer "In13.Cu")
		(net "M_H_CPU1_SB_DQ<23>")
	)
	(segment
		(start 135.104632 -288.666174)
		(end 134.950708 -288.400744)
		(width 0.0889)
		(layer "In13.Cu")
		(net "M_H_CPU1_SB_DQ<23>")
	)
	(segment
		(start 138.103356 -288.339022)
		(end 138.111738 -288.343848)
		(width 0.0889)
		(layer "In13.Cu")
		(net "M_H_CPU1_SB_DQ<23>")
	)
	(segment
		(start 161.688018 -308.577996)
		(end 161.832798 -308.433216)
		(width 0.14478)
		(layer "In13.Cu")
		(net "M_H_CPU1_SB_DQ<23>")
	)
	(segment
		(start 167.000174 -308.260496)
		(end 170.18254 -308.260496)
		(width 0.14478)
		(layer "In13.Cu")
		(net "M_H_CPU1_SB_DQ<23>")
	)
	(segment
		(start 162.239198 -308.577996)
		(end 162.239198 -308.9656)
		(width 0.14478)
		(layer "In13.Cu")
		(net "M_H_CPU1_SB_DQ<23>")
	)
	(segment
		(start 164.995098 -308.900576)
		(end 165.139878 -308.755796)
		(width 0.14478)
		(layer "In13.Cu")
		(net "M_H_CPU1_SB_DQ<23>")
	)
	(segment
		(start 162.935158 -308.652418)
		(end 163.196778 -308.652418)
		(width 0.14478)
		(layer "In13.Cu")
		(net "M_H_CPU1_SB_DQ<23>")
	)
	(segment
		(start 163.747958 -309.110634)
		(end 163.892738 -308.965854)
		(width 0.14478)
		(layer "In13.Cu")
		(net "M_H_CPU1_SB_DQ<23>")
	)
	(segment
		(start 134.950708 -288.400744)
		(end 134.97306 -288.317686)
		(width 0.0889)
		(layer "In13.Cu")
		(net "M_H_CPU1_SB_DQ<23>")
	)
	(segment
		(start 150.72741 -299.226986)
		(end 159.870902 -308.370478)
		(width 0.14478)
		(layer "In13.Cu")
		(net "M_H_CPU1_SB_DQ<23>")
	)
	(segment
		(start 160.543494 -308.965854)
		(end 160.688274 -309.110634)
		(width 0.14478)
		(layer "In13.Cu")
		(net "M_H_CPU1_SB_DQ<23>")
	)
	(segment
		(start 142.803372 -288.339022)
		(end 142.811754 -288.343848)
		(width 0.0889)
		(layer "In13.Cu")
		(net "M_H_CPU1_SB_DQ<23>")
	)
	(segment
		(start 163.486338 -309.110634)
		(end 163.747958 -309.110634)
		(width 0.14478)
		(layer "In13.Cu")
		(net "M_H_CPU1_SB_DQ<23>")
	)
	(segment
		(start 159.870902 -308.370478)
		(end 160.153604 -308.370478)
		(width 0.14478)
		(layer "In13.Cu")
		(net "M_H_CPU1_SB_DQ<23>")
	)
	(segment
		(start 165.546278 -308.965854)
		(end 165.691058 -309.110634)
		(width 0.14478)
		(layer "In13.Cu")
		(net "M_H_CPU1_SB_DQ<23>")
	)
	(segment
		(start 145.534634 -288.23793)
		(end 146.016726 -288.720022)
		(width 0.0889)
		(layer "In13.Cu")
		(net "M_H_CPU1_SB_DQ<23>")
	)
	(segment
		(start 164.299138 -308.755796)
		(end 164.443918 -308.900576)
		(width 0.14478)
		(layer "In13.Cu")
		(net "M_H_CPU1_SB_DQ<23>")
	)
	(segment
		(start 160.564576 -308.16423)
		(end 160.749742 -308.349396)
		(width 0.14478)
		(layer "In13.Cu")
		(net "M_H_CPU1_SB_DQ<23>")
	)
	(segment
		(start 164.850318 -309.110634)
		(end 164.995098 -308.965854)
		(width 0.14478)
		(layer "In13.Cu")
		(net "M_H_CPU1_SB_DQ<23>")
	)
	(segment
		(start 146.016726 -288.720022)
		(end 146.016726 -289.112198)
		(width 0.0889)
		(layer "In13.Cu")
		(net "M_H_CPU1_SB_DQ<23>")
	)
	(segment
		(start 147.078446 -290.173918)
		(end 147.27936 -290.173918)
		(width 0.0889)
		(layer "In13.Cu")
		(net "M_H_CPU1_SB_DQ<23>")
	)
	(segment
		(start 147.889468 -290.784026)
		(end 150.72741 -293.621968)
		(width 0.14478)
		(layer "In13.Cu")
		(net "M_H_CPU1_SB_DQ<23>")
	)
	(segment
		(start 143.377666 -288.343848)
		(end 143.386048 -288.339022)
		(width 0.0889)
		(layer "In13.Cu")
		(net "M_H_CPU1_SB_DQ<23>")
	)
	(segment
		(start 162.094418 -308.433216)
		(end 162.239198 -308.577996)
		(width 0.14478)
		(layer "In13.Cu")
		(net "M_H_CPU1_SB_DQ<23>")
	)
	(segment
		(start 163.892738 -308.965854)
		(end 163.892738 -308.900576)
		(width 0.14478)
		(layer "In13.Cu")
		(net "M_H_CPU1_SB_DQ<23>")
	)
	(segment
		(start 163.196778 -308.652418)
		(end 163.341558 -308.797198)
		(width 0.14478)
		(layer "In13.Cu")
		(net "M_H_CPU1_SB_DQ<23>")
	)
	(segment
		(start 165.546278 -308.900576)
		(end 165.546278 -308.965854)
		(width 0.14478)
		(layer "In13.Cu")
		(net "M_H_CPU1_SB_DQ<23>")
	)
	(segment
		(start 162.239198 -308.9656)
		(end 162.383978 -309.11038)
		(width 0.14478)
		(layer "In13.Cu")
		(net "M_H_CPU1_SB_DQ<23>")
	)
	(segment
		(start 161.543238 -309.110634)
		(end 161.688018 -308.965854)
		(width 0.14478)
		(layer "In13.Cu")
		(net "M_H_CPU1_SB_DQ<23>")
	)
	(segment
		(start 161.832798 -308.433216)
		(end 162.094418 -308.433216)
		(width 0.14478)
		(layer "In13.Cu")
		(net "M_H_CPU1_SB_DQ<23>")
	)
	(segment
		(start 165.139878 -308.755796)
		(end 165.401498 -308.755796)
		(width 0.14478)
		(layer "In13.Cu")
		(net "M_H_CPU1_SB_DQ<23>")
	)
	(segment
		(start 160.543494 -308.760368)
		(end 160.543494 -308.965854)
		(width 0.14478)
		(layer "In13.Cu")
		(net "M_H_CPU1_SB_DQ<23>")
	)
	(segment
		(start 164.443918 -308.900576)
		(end 164.443918 -308.965854)
		(width 0.14478)
		(layer "In13.Cu")
		(net "M_H_CPU1_SB_DQ<23>")
	)
	(segment
		(start 147.27936 -290.173918)
		(end 147.889468 -290.784026)
		(width 0.0889)
		(layer "In13.Cu")
		(net "M_H_CPU1_SB_DQ<23>")
	)
	(segment
		(start 164.588698 -309.110634)
		(end 164.850318 -309.110634)
		(width 0.14478)
		(layer "In13.Cu")
		(net "M_H_CPU1_SB_DQ<23>")
	)
	(segment
		(start 164.995098 -308.965854)
		(end 164.995098 -308.900576)
		(width 0.14478)
		(layer "In13.Cu")
		(net "M_H_CPU1_SB_DQ<23>")
	)
	(segment
		(start 161.688018 -308.965854)
		(end 161.688018 -308.577996)
		(width 0.14478)
		(layer "In13.Cu")
		(net "M_H_CPU1_SB_DQ<23>")
	)
	(segment
		(start 162.383978 -309.11038)
		(end 162.645598 -309.11038)
		(width 0.14478)
		(layer "In13.Cu")
		(net "M_H_CPU1_SB_DQ<23>")
	)
	(segment
		(start 163.341558 -308.965854)
		(end 163.486338 -309.110634)
		(width 0.14478)
		(layer "In13.Cu")
		(net "M_H_CPU1_SB_DQ<23>")
	)
	(segment
		(start 150.72741 -293.621968)
		(end 150.72741 -299.226986)
		(width 0.14478)
		(layer "In13.Cu")
		(net "M_H_CPU1_SB_DQ<23>")
	)
	(segment
		(start 164.443918 -308.965854)
		(end 164.588698 -309.110634)
		(width 0.14478)
		(layer "In13.Cu")
		(net "M_H_CPU1_SB_DQ<23>")
	)
	(segment
		(start 160.153604 -308.370478)
		(end 160.359852 -308.16423)
		(width 0.14478)
		(layer "In13.Cu")
		(net "M_H_CPU1_SB_DQ<23>")
	)
	(segment
		(start 140.557758 -288.343848)
		(end 140.56614 -288.339022)
		(width 0.0889)
		(layer "In13.Cu")
		(net "M_H_CPU1_SB_DQ<23>")
	)
	(segment
		(start 146.016726 -289.112198)
		(end 147.078446 -290.173918)
		(width 0.0889)
		(layer "In13.Cu")
		(net "M_H_CPU1_SB_DQ<23>")
	)
	(segment
		(start 135.857742 -288.343848)
		(end 135.866124 -288.339022)
		(width 0.0889)
		(layer "In13.Cu")
		(net "M_H_CPU1_SB_DQ<23>")
	)
	(segment
		(start 164.037518 -308.755796)
		(end 164.299138 -308.755796)
		(width 0.14478)
		(layer "In13.Cu")
		(net "M_H_CPU1_SB_DQ<23>")
	)
	(arc
		(start 144.034764 -288.420048)
		(mid 144.338787 -288.373445)
		(end 144.6149 -288.23793)
		(width 0.0889)
		(layer "In13.Cu")
		(net "M_H_CPU1_SB_DQ<23>")
	)
	(arc
		(start 135.29183 -288.343848)
		(mid 135.574786 -288.420025)
		(end 135.857742 -288.343848)
		(width 0.0889)
		(layer "In13.Cu")
		(net "M_H_CPU1_SB_DQ<23>")
	)
	(arc
		(start 137.737596 -288.343848)
		(mid 137.919847 -288.293464)
		(end 138.103356 -288.339022)
		(width 0.0889)
		(layer "In13.Cu")
		(net "M_H_CPU1_SB_DQ<23>")
	)
	(arc
		(start 136.797796 -288.343848)
		(mid 136.98474 -288.293559)
		(end 137.171684 -288.343848)
		(width 0.0889)
		(layer "In13.Cu")
		(net "M_H_CPU1_SB_DQ<23>")
	)
	(arc
		(start 138.67765 -288.343848)
		(mid 138.859901 -288.293464)
		(end 139.04341 -288.339022)
		(width 0.0889)
		(layer "In13.Cu")
		(net "M_H_CPU1_SB_DQ<23>")
	)
	(arc
		(start 143.751808 -288.343848)
		(mid 143.888244 -288.400673)
		(end 144.034764 -288.420048)
		(width 0.0889)
		(layer "In13.Cu")
		(net "M_H_CPU1_SB_DQ<23>")
	)
	(arc
		(start 139.626086 -288.339022)
		(mid 139.809594 -288.293497)
		(end 139.991846 -288.343848)
		(width 0.0889)
		(layer "In13.Cu")
		(net "M_H_CPU1_SB_DQ<23>")
	)
	(arc
		(start 138.111738 -288.343848)
		(mid 138.394694 -288.420025)
		(end 138.67765 -288.343848)
		(width 0.0889)
		(layer "In13.Cu")
		(net "M_H_CPU1_SB_DQ<23>")
	)
	(arc
		(start 143.386048 -288.339022)
		(mid 143.569556 -288.293497)
		(end 143.751808 -288.343848)
		(width 0.0889)
		(layer "In13.Cu")
		(net "M_H_CPU1_SB_DQ<23>")
	)
	(arc
		(start 141.8717 -288.343848)
		(mid 142.154656 -288.420025)
		(end 142.437612 -288.343848)
		(width 0.0889)
		(layer "In13.Cu")
		(net "M_H_CPU1_SB_DQ<23>")
	)
	(arc
		(start 136.231884 -288.343848)
		(mid 136.51484 -288.420025)
		(end 136.797796 -288.343848)
		(width 0.0889)
		(layer "In13.Cu")
		(net "M_H_CPU1_SB_DQ<23>")
	)
	(arc
		(start 142.811754 -288.343848)
		(mid 143.09471 -288.420025)
		(end 143.377666 -288.343848)
		(width 0.0889)
		(layer "In13.Cu")
		(net "M_H_CPU1_SB_DQ<23>")
	)
	(arc
		(start 139.051792 -288.343848)
		(mid 139.334748 -288.420025)
		(end 139.617704 -288.343848)
		(width 0.0889)
		(layer "In13.Cu")
		(net "M_H_CPU1_SB_DQ<23>")
	)
	(arc
		(start 142.437612 -288.343848)
		(mid 142.619863 -288.293464)
		(end 142.803372 -288.339022)
		(width 0.0889)
		(layer "In13.Cu")
		(net "M_H_CPU1_SB_DQ<23>")
	)
	(arc
		(start 139.991846 -288.343848)
		(mid 140.274802 -288.420025)
		(end 140.557758 -288.343848)
		(width 0.0889)
		(layer "In13.Cu")
		(net "M_H_CPU1_SB_DQ<23>")
	)
	(arc
		(start 135.866124 -288.339022)
		(mid 136.049632 -288.293497)
		(end 136.231884 -288.343848)
		(width 0.0889)
		(layer "In13.Cu")
		(net "M_H_CPU1_SB_DQ<23>")
	)
	(arc
		(start 134.97306 -288.317686)
		(mid 135.135392 -288.294852)
		(end 135.29183 -288.343848)
		(width 0.0889)
		(layer "In13.Cu")
		(net "M_H_CPU1_SB_DQ<23>")
	)
	(arc
		(start 137.171684 -288.343848)
		(mid 137.45464 -288.420025)
		(end 137.737596 -288.343848)
		(width 0.0889)
		(layer "In13.Cu")
		(net "M_H_CPU1_SB_DQ<23>")
	)
	(arc
		(start 140.9319 -288.343848)
		(mid 141.214856 -288.420025)
		(end 141.497812 -288.343848)
		(width 0.0889)
		(layer "In13.Cu")
		(net "M_H_CPU1_SB_DQ<23>")
	)
	(arc
		(start 141.497812 -288.343848)
		(mid 141.684756 -288.293559)
		(end 141.8717 -288.343848)
		(width 0.0889)
		(layer "In13.Cu")
		(net "M_H_CPU1_SB_DQ<23>")
	)
	(arc
		(start 140.56614 -288.339022)
		(mid 140.749648 -288.293497)
		(end 140.9319 -288.343848)
		(width 0.0889)
		(layer "In13.Cu")
		(net "M_H_CPU1_SB_DQ<23>")
	)
	(segment
		(start 136.047988 -287.590484)
		(end 136.51484 -287.856422)
		(width 0.10668)
		(layer "F.Cu")
		(net "M_H_CPU1_SB_DQ<22>")
	)
	(segment
		(start 153.815288 -300.691804)
		(end 153.831544 -300.675548)
		(width 0.14478)
		(layer "In13.Cu")
		(net "M_H_CPU1_SB_DQ<22>")
	)
	(segment
		(start 155.764992 -302.641254)
		(end 155.764992 -302.845978)
		(width 0.14478)
		(layer "In13.Cu")
		(net "M_H_CPU1_SB_DQ<22>")
	)
	(segment
		(start 158.120334 -304.759614)
		(end 158.120588 -304.964338)
		(width 0.14478)
		(layer "In13.Cu")
		(net "M_H_CPU1_SB_DQ<22>")
	)
	(segment
		(start 158.120588 -304.964338)
		(end 158.104332 -304.980594)
		(width 0.14478)
		(layer "In13.Cu")
		(net "M_H_CPU1_SB_DQ<22>")
	)
	(segment
		(start 152.662128 -299.505878)
		(end 152.645872 -299.522134)
		(width 0.14478)
		(layer "In13.Cu")
		(net "M_H_CPU1_SB_DQ<22>")
	)
	(segment
		(start 152.661874 -299.301154)
		(end 152.662128 -299.505878)
		(width 0.14478)
		(layer "In13.Cu")
		(net "M_H_CPU1_SB_DQ<22>")
	)
	(segment
		(start 155.170632 -302.251618)
		(end 155.374848 -302.251364)
		(width 0.14478)
		(layer "In13.Cu")
		(net "M_H_CPU1_SB_DQ<22>")
	)
	(segment
		(start 156.375608 -303.014888)
		(end 156.560774 -303.200054)
		(width 0.14478)
		(layer "In13.Cu")
		(net "M_H_CPU1_SB_DQ<22>")
	)
	(segment
		(start 159.290004 -306.134008)
		(end 159.494728 -306.134008)
		(width 0.14478)
		(layer "In13.Cu")
		(net "M_H_CPU1_SB_DQ<22>")
	)
	(segment
		(start 163.094924 -306.959508)
		(end 163.094924 -306.801266)
		(width 0.14478)
		(layer "In13.Cu")
		(net "M_H_CPU1_SB_DQ<22>")
	)
	(segment
		(start 151.62657 -293.234872)
		(end 151.62657 -298.707556)
		(width 0.14478)
		(layer "In13.Cu")
		(net "M_H_CPU1_SB_DQ<22>")
	)
	(segment
		(start 153.035508 -299.912024)
		(end 153.051764 -299.895768)
		(width 0.14478)
		(layer "In13.Cu")
		(net "M_H_CPU1_SB_DQ<22>")
	)
	(segment
		(start 159.663892 -306.744878)
		(end 160.023302 -307.104288)
		(width 0.14478)
		(layer "In13.Cu")
		(net "M_H_CPU1_SB_DQ<22>")
	)
	(segment
		(start 156.544772 -303.625758)
		(end 156.730192 -303.811178)
		(width 0.14478)
		(layer "In13.Cu")
		(net "M_H_CPU1_SB_DQ<22>")
	)
	(segment
		(start 153.051764 -299.895768)
		(end 153.256488 -299.895768)
		(width 0.14478)
		(layer "In13.Cu")
		(net "M_H_CPU1_SB_DQ<22>")
	)
	(segment
		(start 163.646104 -306.959508)
		(end 163.790884 -307.104288)
		(width 0.14478)
		(layer "In13.Cu")
		(net "M_H_CPU1_SB_DQ<22>")
	)
	(segment
		(start 138.20775 -287.533842)
		(end 138.216132 -287.529016)
		(width 0.0889)
		(layer "In13.Cu")
		(net "M_H_CPU1_SB_DQ<22>")
	)
	(segment
		(start 152.645872 -299.726858)
		(end 152.831292 -299.912278)
		(width 0.14478)
		(layer "In13.Cu")
		(net "M_H_CPU1_SB_DQ<22>")
	)
	(segment
		(start 162.543744 -306.801266)
		(end 162.543744 -306.959508)
		(width 0.14478)
		(layer "In13.Cu")
		(net "M_H_CPU1_SB_DQ<22>")
	)
	(segment
		(start 171.97197 -307.066442)
		(end 171.97197 -306.985416)
		(width 0.14478)
		(layer "In13.Cu")
		(net "M_H_CPU1_SB_DQ<22>")
	)
	(segment
		(start 159.069532 -306.150518)
		(end 159.273748 -306.150264)
		(width 0.14478)
		(layer "In13.Cu")
		(net "M_H_CPU1_SB_DQ<22>")
	)
	(segment
		(start 155.001468 -301.845218)
		(end 154.985212 -301.861474)
		(width 0.14478)
		(layer "In13.Cu")
		(net "M_H_CPU1_SB_DQ<22>")
	)
	(segment
		(start 154.221688 -301.065438)
		(end 154.205432 -301.081694)
		(width 0.14478)
		(layer "In13.Cu")
		(net "M_H_CPU1_SB_DQ<22>")
	)
	(segment
		(start 157.730444 -304.574448)
		(end 157.935168 -304.574448)
		(width 0.14478)
		(layer "In13.Cu")
		(net "M_H_CPU1_SB_DQ<22>")
	)
	(segment
		(start 160.890204 -306.801266)
		(end 161.034984 -306.656486)
		(width 0.14478)
		(layer "In13.Cu")
		(net "M_H_CPU1_SB_DQ<22>")
	)
	(segment
		(start 161.034984 -306.656486)
		(end 161.296604 -306.656486)
		(width 0.14478)
		(layer "In13.Cu")
		(net "M_H_CPU1_SB_DQ<22>")
	)
	(segment
		(start 161.992564 -306.959508)
		(end 161.992564 -306.801266)
		(width 0.14478)
		(layer "In13.Cu")
		(net "M_H_CPU1_SB_DQ<22>")
	)
	(segment
		(start 154.036268 -300.675548)
		(end 154.221434 -300.860714)
		(width 0.14478)
		(layer "In13.Cu")
		(net "M_H_CPU1_SB_DQ<22>")
	)
	(segment
		(start 156.560774 -303.200054)
		(end 156.561028 -303.404778)
		(width 0.14478)
		(layer "In13.Cu")
		(net "M_H_CPU1_SB_DQ<22>")
	)
	(segment
		(start 154.985212 -301.861474)
		(end 154.985212 -302.066198)
		(width 0.14478)
		(layer "In13.Cu")
		(net "M_H_CPU1_SB_DQ<22>")
	)
	(segment
		(start 159.273748 -306.150264)
		(end 159.290004 -306.134008)
		(width 0.14478)
		(layer "In13.Cu")
		(net "M_H_CPU1_SB_DQ<22>")
	)
	(segment
		(start 156.561028 -303.404778)
		(end 156.544772 -303.421034)
		(width 0.14478)
		(layer "In13.Cu")
		(net "M_H_CPU1_SB_DQ<22>")
	)
	(segment
		(start 158.714948 -305.354228)
		(end 158.900114 -305.539394)
		(width 0.14478)
		(layer "In13.Cu")
		(net "M_H_CPU1_SB_DQ<22>")
	)
	(segment
		(start 155.780994 -302.420274)
		(end 155.781248 -302.624998)
		(width 0.14478)
		(layer "In13.Cu")
		(net "M_H_CPU1_SB_DQ<22>")
	)
	(segment
		(start 154.205432 -301.286418)
		(end 154.390852 -301.471838)
		(width 0.14478)
		(layer "In13.Cu")
		(net "M_H_CPU1_SB_DQ<22>")
	)
	(segment
		(start 161.586164 -307.104288)
		(end 161.847784 -307.104288)
		(width 0.14478)
		(layer "In13.Cu")
		(net "M_H_CPU1_SB_DQ<22>")
	)
	(segment
		(start 153.425652 -300.301914)
		(end 153.425652 -300.506638)
		(width 0.14478)
		(layer "In13.Cu")
		(net "M_H_CPU1_SB_DQ<22>")
	)
	(segment
		(start 163.790884 -307.104288)
		(end 166.45636 -307.104288)
		(width 0.14478)
		(layer "In13.Cu")
		(net "M_H_CPU1_SB_DQ<22>")
	)
	(segment
		(start 155.781248 -302.624998)
		(end 155.764992 -302.641254)
		(width 0.14478)
		(layer "In13.Cu")
		(net "M_H_CPU1_SB_DQ<22>")
	)
	(segment
		(start 155.595828 -302.235108)
		(end 155.780994 -302.420274)
		(width 0.14478)
		(layer "In13.Cu")
		(net "M_H_CPU1_SB_DQ<22>")
	)
	(segment
		(start 145.09369 -287.641284)
		(end 145.643346 -287.641284)
		(width 0.0889)
		(layer "In13.Cu")
		(net "M_H_CPU1_SB_DQ<22>")
	)
	(segment
		(start 152.831292 -299.912278)
		(end 153.035508 -299.912024)
		(width 0.14478)
		(layer "In13.Cu")
		(net "M_H_CPU1_SB_DQ<22>")
	)
	(segment
		(start 154.595068 -301.471584)
		(end 154.611324 -301.455328)
		(width 0.14478)
		(layer "In13.Cu")
		(net "M_H_CPU1_SB_DQ<22>")
	)
	(segment
		(start 146.377406 -288.375344)
		(end 146.767042 -288.375344)
		(width 0.0889)
		(layer "In13.Cu")
		(net "M_H_CPU1_SB_DQ<22>")
	)
	(segment
		(start 159.663892 -306.540154)
		(end 159.663892 -306.744878)
		(width 0.14478)
		(layer "In13.Cu")
		(net "M_H_CPU1_SB_DQ<22>")
	)
	(segment
		(start 157.935168 -304.574448)
		(end 158.120334 -304.759614)
		(width 0.14478)
		(layer "In13.Cu")
		(net "M_H_CPU1_SB_DQ<22>")
	)
	(segment
		(start 145.643346 -287.641284)
		(end 146.377406 -288.375344)
		(width 0.0889)
		(layer "In13.Cu")
		(net "M_H_CPU1_SB_DQ<22>")
	)
	(segment
		(start 161.441384 -306.801266)
		(end 161.441384 -306.959508)
		(width 0.14478)
		(layer "In13.Cu")
		(net "M_H_CPU1_SB_DQ<22>")
	)
	(segment
		(start 157.714188 -304.590704)
		(end 157.730444 -304.574448)
		(width 0.14478)
		(layer "In13.Cu")
		(net "M_H_CPU1_SB_DQ<22>")
	)
	(segment
		(start 158.900114 -305.539394)
		(end 158.900368 -305.744118)
		(width 0.14478)
		(layer "In13.Cu")
		(net "M_H_CPU1_SB_DQ<22>")
	)
	(segment
		(start 156.170884 -303.014888)
		(end 156.375608 -303.014888)
		(width 0.14478)
		(layer "In13.Cu")
		(net "M_H_CPU1_SB_DQ<22>")
	)
	(segment
		(start 157.340554 -303.979834)
		(end 157.340808 -304.184558)
		(width 0.14478)
		(layer "In13.Cu")
		(net "M_H_CPU1_SB_DQ<22>")
	)
	(segment
		(start 155.764992 -302.845978)
		(end 155.950412 -303.031398)
		(width 0.14478)
		(layer "In13.Cu")
		(net "M_H_CPU1_SB_DQ<22>")
	)
	(segment
		(start 160.023302 -307.104288)
		(end 160.745424 -307.104288)
		(width 0.14478)
		(layer "In13.Cu")
		(net "M_H_CPU1_SB_DQ<22>")
	)
	(segment
		(start 157.324552 -304.405538)
		(end 157.509972 -304.590958)
		(width 0.14478)
		(layer "In13.Cu")
		(net "M_H_CPU1_SB_DQ<22>")
	)
	(segment
		(start 151.62657 -298.707556)
		(end 152.051512 -299.132498)
		(width 0.14478)
		(layer "In13.Cu")
		(net "M_H_CPU1_SB_DQ<22>")
	)
	(segment
		(start 136.51484 -287.856422)
		(end 136.360662 -287.590992)
		(width 0.0889)
		(layer "In13.Cu")
		(net "M_H_CPU1_SB_DQ<22>")
	)
	(segment
		(start 158.900368 -305.744118)
		(end 158.884112 -305.760374)
		(width 0.14478)
		(layer "In13.Cu")
		(net "M_H_CPU1_SB_DQ<22>")
	)
	(segment
		(start 160.890204 -306.959508)
		(end 160.890204 -306.801266)
		(width 0.14478)
		(layer "In13.Cu")
		(net "M_H_CPU1_SB_DQ<22>")
	)
	(segment
		(start 153.256488 -299.895768)
		(end 153.441654 -300.080934)
		(width 0.14478)
		(layer "In13.Cu")
		(net "M_H_CPU1_SB_DQ<22>")
	)
	(segment
		(start 156.154628 -303.031144)
		(end 156.170884 -303.014888)
		(width 0.14478)
		(layer "In13.Cu")
		(net "M_H_CPU1_SB_DQ<22>")
	)
	(segment
		(start 152.645872 -299.522134)
		(end 152.645872 -299.726858)
		(width 0.14478)
		(layer "In13.Cu")
		(net "M_H_CPU1_SB_DQ<22>")
	)
	(segment
		(start 161.441384 -306.959508)
		(end 161.586164 -307.104288)
		(width 0.14478)
		(layer "In13.Cu")
		(net "M_H_CPU1_SB_DQ<22>")
	)
	(segment
		(start 155.950412 -303.031398)
		(end 156.154628 -303.031144)
		(width 0.14478)
		(layer "In13.Cu")
		(net "M_H_CPU1_SB_DQ<22>")
	)
	(segment
		(start 157.155388 -303.794668)
		(end 157.340554 -303.979834)
		(width 0.14478)
		(layer "In13.Cu")
		(net "M_H_CPU1_SB_DQ<22>")
	)
	(segment
		(start 153.441908 -300.285658)
		(end 153.425652 -300.301914)
		(width 0.14478)
		(layer "In13.Cu")
		(net "M_H_CPU1_SB_DQ<22>")
	)
	(segment
		(start 136.360662 -287.590992)
		(end 136.383014 -287.50768)
		(width 0.0889)
		(layer "In13.Cu")
		(net "M_H_CPU1_SB_DQ<22>")
	)
	(segment
		(start 137.267696 -287.533842)
		(end 137.276078 -287.529016)
		(width 0.0889)
		(layer "In13.Cu")
		(net "M_H_CPU1_SB_DQ<22>")
	)
	(segment
		(start 152.476708 -299.115988)
		(end 152.661874 -299.301154)
		(width 0.14478)
		(layer "In13.Cu")
		(net "M_H_CPU1_SB_DQ<22>")
	)
	(segment
		(start 156.950664 -303.794668)
		(end 157.155388 -303.794668)
		(width 0.14478)
		(layer "In13.Cu")
		(net "M_H_CPU1_SB_DQ<22>")
	)
	(segment
		(start 161.847784 -307.104288)
		(end 161.992564 -306.959508)
		(width 0.14478)
		(layer "In13.Cu")
		(net "M_H_CPU1_SB_DQ<22>")
	)
	(segment
		(start 155.001214 -301.640494)
		(end 155.001468 -301.845218)
		(width 0.14478)
		(layer "In13.Cu")
		(net "M_H_CPU1_SB_DQ<22>")
	)
	(segment
		(start 154.611324 -301.455328)
		(end 154.816048 -301.455328)
		(width 0.14478)
		(layer "In13.Cu")
		(net "M_H_CPU1_SB_DQ<22>")
	)
	(segment
		(start 154.816048 -301.455328)
		(end 155.001214 -301.640494)
		(width 0.14478)
		(layer "In13.Cu")
		(net "M_H_CPU1_SB_DQ<22>")
	)
	(segment
		(start 158.493968 -305.370484)
		(end 158.510224 -305.354228)
		(width 0.14478)
		(layer "In13.Cu")
		(net "M_H_CPU1_SB_DQ<22>")
	)
	(segment
		(start 154.390852 -301.471838)
		(end 154.595068 -301.471584)
		(width 0.14478)
		(layer "In13.Cu")
		(net "M_H_CPU1_SB_DQ<22>")
	)
	(segment
		(start 156.544772 -303.421034)
		(end 156.544772 -303.625758)
		(width 0.14478)
		(layer "In13.Cu")
		(net "M_H_CPU1_SB_DQ<22>")
	)
	(segment
		(start 158.289752 -305.370738)
		(end 158.493968 -305.370484)
		(width 0.14478)
		(layer "In13.Cu")
		(net "M_H_CPU1_SB_DQ<22>")
	)
	(segment
		(start 166.45636 -307.104288)
		(end 167.000174 -306.560474)
		(width 0.14478)
		(layer "In13.Cu")
		(net "M_H_CPU1_SB_DQ<22>")
	)
	(segment
		(start 163.646104 -306.801266)
		(end 163.646104 -306.959508)
		(width 0.14478)
		(layer "In13.Cu")
		(net "M_H_CPU1_SB_DQ<22>")
	)
	(segment
		(start 152.255728 -299.132244)
		(end 152.271984 -299.115988)
		(width 0.14478)
		(layer "In13.Cu")
		(net "M_H_CPU1_SB_DQ<22>")
	)
	(segment
		(start 159.679894 -306.319174)
		(end 159.680148 -306.523898)
		(width 0.14478)
		(layer "In13.Cu")
		(net "M_H_CPU1_SB_DQ<22>")
	)
	(segment
		(start 170.701462 -307.410612)
		(end 171.6278 -307.410612)
		(width 0.14478)
		(layer "In13.Cu")
		(net "M_H_CPU1_SB_DQ<22>")
	)
	(segment
		(start 158.884112 -305.965098)
		(end 159.069532 -306.150518)
		(width 0.14478)
		(layer "In13.Cu")
		(net "M_H_CPU1_SB_DQ<22>")
	)
	(segment
		(start 169.851324 -306.560474)
		(end 170.701462 -307.410612)
		(width 0.14478)
		(layer "In13.Cu")
		(net "M_H_CPU1_SB_DQ<22>")
	)
	(segment
		(start 162.137344 -306.656486)
		(end 162.398964 -306.656486)
		(width 0.14478)
		(layer "In13.Cu")
		(net "M_H_CPU1_SB_DQ<22>")
	)
	(segment
		(start 160.745424 -307.104288)
		(end 160.890204 -306.959508)
		(width 0.14478)
		(layer "In13.Cu")
		(net "M_H_CPU1_SB_DQ<22>")
	)
	(segment
		(start 155.374848 -302.251364)
		(end 155.391104 -302.235108)
		(width 0.14478)
		(layer "In13.Cu")
		(net "M_H_CPU1_SB_DQ<22>")
	)
	(segment
		(start 152.271984 -299.115988)
		(end 152.476708 -299.115988)
		(width 0.14478)
		(layer "In13.Cu")
		(net "M_H_CPU1_SB_DQ<22>")
	)
	(segment
		(start 161.992564 -306.801266)
		(end 162.137344 -306.656486)
		(width 0.14478)
		(layer "In13.Cu")
		(net "M_H_CPU1_SB_DQ<22>")
	)
	(segment
		(start 158.104332 -304.980594)
		(end 158.104332 -305.185318)
		(width 0.14478)
		(layer "In13.Cu")
		(net "M_H_CPU1_SB_DQ<22>")
	)
	(segment
		(start 154.205432 -301.081694)
		(end 154.205432 -301.286418)
		(width 0.14478)
		(layer "In13.Cu")
		(net "M_H_CPU1_SB_DQ<22>")
	)
	(segment
		(start 156.730192 -303.811178)
		(end 156.934408 -303.810924)
		(width 0.14478)
		(layer "In13.Cu")
		(net "M_H_CPU1_SB_DQ<22>")
	)
	(segment
		(start 156.934408 -303.810924)
		(end 156.950664 -303.794668)
		(width 0.14478)
		(layer "In13.Cu")
		(net "M_H_CPU1_SB_DQ<22>")
	)
	(segment
		(start 162.398964 -306.656486)
		(end 162.543744 -306.801266)
		(width 0.14478)
		(layer "In13.Cu")
		(net "M_H_CPU1_SB_DQ<22>")
	)
	(segment
		(start 141.393418 -287.529016)
		(end 141.4018 -287.533842)
		(width 0.0889)
		(layer "In13.Cu")
		(net "M_H_CPU1_SB_DQ<22>")
	)
	(segment
		(start 152.051512 -299.132498)
		(end 152.255728 -299.132244)
		(width 0.14478)
		(layer "In13.Cu")
		(net "M_H_CPU1_SB_DQ<22>")
	)
	(segment
		(start 159.494728 -306.134008)
		(end 159.679894 -306.319174)
		(width 0.14478)
		(layer "In13.Cu")
		(net "M_H_CPU1_SB_DQ<22>")
	)
	(segment
		(start 158.104332 -305.185318)
		(end 158.289752 -305.370738)
		(width 0.14478)
		(layer "In13.Cu")
		(net "M_H_CPU1_SB_DQ<22>")
	)
	(segment
		(start 153.611072 -300.692058)
		(end 153.815288 -300.691804)
		(width 0.14478)
		(layer "In13.Cu")
		(net "M_H_CPU1_SB_DQ<22>")
	)
	(segment
		(start 162.950144 -307.104288)
		(end 163.094924 -306.959508)
		(width 0.14478)
		(layer "In13.Cu")
		(net "M_H_CPU1_SB_DQ<22>")
	)
	(segment
		(start 153.441654 -300.080934)
		(end 153.441908 -300.285658)
		(width 0.14478)
		(layer "In13.Cu")
		(net "M_H_CPU1_SB_DQ<22>")
	)
	(segment
		(start 155.391104 -302.235108)
		(end 155.595828 -302.235108)
		(width 0.14478)
		(layer "In13.Cu")
		(net "M_H_CPU1_SB_DQ<22>")
	)
	(segment
		(start 159.680148 -306.523898)
		(end 159.663892 -306.540154)
		(width 0.14478)
		(layer "In13.Cu")
		(net "M_H_CPU1_SB_DQ<22>")
	)
	(segment
		(start 157.509972 -304.590958)
		(end 157.714188 -304.590704)
		(width 0.14478)
		(layer "In13.Cu")
		(net "M_H_CPU1_SB_DQ<22>")
	)
	(segment
		(start 154.221434 -300.860714)
		(end 154.221688 -301.065438)
		(width 0.14478)
		(layer "In13.Cu")
		(net "M_H_CPU1_SB_DQ<22>")
	)
	(segment
		(start 163.094924 -306.801266)
		(end 163.239704 -306.656486)
		(width 0.14478)
		(layer "In13.Cu")
		(net "M_H_CPU1_SB_DQ<22>")
	)
	(segment
		(start 141.967712 -287.533842)
		(end 141.976094 -287.529016)
		(width 0.0889)
		(layer "In13.Cu")
		(net "M_H_CPU1_SB_DQ<22>")
	)
	(segment
		(start 163.239704 -306.656486)
		(end 163.501324 -306.656486)
		(width 0.14478)
		(layer "In13.Cu")
		(net "M_H_CPU1_SB_DQ<22>")
	)
	(segment
		(start 163.501324 -306.656486)
		(end 163.646104 -306.801266)
		(width 0.14478)
		(layer "In13.Cu")
		(net "M_H_CPU1_SB_DQ<22>")
	)
	(segment
		(start 153.831544 -300.675548)
		(end 154.036268 -300.675548)
		(width 0.14478)
		(layer "In13.Cu")
		(net "M_H_CPU1_SB_DQ<22>")
	)
	(segment
		(start 136.693402 -287.529016)
		(end 136.701784 -287.533842)
		(width 0.0889)
		(layer "In13.Cu")
		(net "M_H_CPU1_SB_DQ<22>")
	)
	(segment
		(start 157.340808 -304.184558)
		(end 157.324552 -304.200814)
		(width 0.14478)
		(layer "In13.Cu")
		(net "M_H_CPU1_SB_DQ<22>")
	)
	(segment
		(start 146.767042 -288.375344)
		(end 147.589748 -289.19805)
		(width 0.0889)
		(layer "In13.Cu")
		(net "M_H_CPU1_SB_DQ<22>")
	)
	(segment
		(start 153.425652 -300.506638)
		(end 153.611072 -300.692058)
		(width 0.14478)
		(layer "In13.Cu")
		(net "M_H_CPU1_SB_DQ<22>")
	)
	(segment
		(start 162.688524 -307.104288)
		(end 162.950144 -307.104288)
		(width 0.14478)
		(layer "In13.Cu")
		(net "M_H_CPU1_SB_DQ<22>")
	)
	(segment
		(start 162.543744 -306.959508)
		(end 162.688524 -307.104288)
		(width 0.14478)
		(layer "In13.Cu")
		(net "M_H_CPU1_SB_DQ<22>")
	)
	(segment
		(start 144.727422 -287.483042)
		(end 145.09369 -287.641284)
		(width 0.0889)
		(layer "In13.Cu")
		(net "M_H_CPU1_SB_DQ<22>")
	)
	(segment
		(start 167.000174 -306.560474)
		(end 169.851324 -306.560474)
		(width 0.14478)
		(layer "In13.Cu")
		(net "M_H_CPU1_SB_DQ<22>")
	)
	(segment
		(start 171.6278 -307.410612)
		(end 171.97197 -307.066442)
		(width 0.14478)
		(layer "In13.Cu")
		(net "M_H_CPU1_SB_DQ<22>")
	)
	(segment
		(start 161.296604 -306.656486)
		(end 161.441384 -306.801266)
		(width 0.14478)
		(layer "In13.Cu")
		(net "M_H_CPU1_SB_DQ<22>")
	)
	(segment
		(start 158.884112 -305.760374)
		(end 158.884112 -305.965098)
		(width 0.14478)
		(layer "In13.Cu")
		(net "M_H_CPU1_SB_DQ<22>")
	)
	(segment
		(start 158.510224 -305.354228)
		(end 158.714948 -305.354228)
		(width 0.14478)
		(layer "In13.Cu")
		(net "M_H_CPU1_SB_DQ<22>")
	)
	(segment
		(start 140.453364 -287.529016)
		(end 140.461746 -287.533842)
		(width 0.0889)
		(layer "In13.Cu")
		(net "M_H_CPU1_SB_DQ<22>")
	)
	(segment
		(start 147.589748 -289.19805)
		(end 151.62657 -293.234872)
		(width 0.14478)
		(layer "In13.Cu")
		(net "M_H_CPU1_SB_DQ<22>")
	)
	(segment
		(start 157.324552 -304.200814)
		(end 157.324552 -304.405538)
		(width 0.14478)
		(layer "In13.Cu")
		(net "M_H_CPU1_SB_DQ<22>")
	)
	(segment
		(start 154.985212 -302.066198)
		(end 155.170632 -302.251618)
		(width 0.14478)
		(layer "In13.Cu")
		(net "M_H_CPU1_SB_DQ<22>")
	)
	(segment
		(start 144.034764 -287.483042)
		(end 144.727422 -287.483042)
		(width 0.0889)
		(layer "In13.Cu")
		(net "M_H_CPU1_SB_DQ<22>")
	)
	(arc
		(start 138.581892 -287.533842)
		(mid 138.864848 -287.609985)
		(end 139.147804 -287.533842)
		(width 0.0889)
		(layer "In13.Cu")
		(net "M_H_CPU1_SB_DQ<22>")
	)
	(arc
		(start 142.341854 -287.533842)
		(mid 142.62481 -287.609985)
		(end 142.907766 -287.533842)
		(width 0.0889)
		(layer "In13.Cu")
		(net "M_H_CPU1_SB_DQ<22>")
	)
	(arc
		(start 140.461746 -287.533842)
		(mid 140.744702 -287.609985)
		(end 141.027658 -287.533842)
		(width 0.0889)
		(layer "In13.Cu")
		(net "M_H_CPU1_SB_DQ<22>")
	)
	(arc
		(start 137.276078 -287.529016)
		(mid 137.459586 -287.483522)
		(end 137.641838 -287.533842)
		(width 0.0889)
		(layer "In13.Cu")
		(net "M_H_CPU1_SB_DQ<22>")
	)
	(arc
		(start 143.847566 -287.533842)
		(mid 143.937806 -287.496065)
		(end 144.034764 -287.483042)
		(width 0.0889)
		(layer "In13.Cu")
		(net "M_H_CPU1_SB_DQ<22>")
	)
	(arc
		(start 142.907766 -287.533842)
		(mid 143.09471 -287.483587)
		(end 143.281654 -287.533842)
		(width 0.0889)
		(layer "In13.Cu")
		(net "M_H_CPU1_SB_DQ<22>")
	)
	(arc
		(start 136.701784 -287.533842)
		(mid 136.98474 -287.609985)
		(end 137.267696 -287.533842)
		(width 0.0889)
		(layer "In13.Cu")
		(net "M_H_CPU1_SB_DQ<22>")
	)
	(arc
		(start 139.521692 -287.533842)
		(mid 139.804648 -287.609985)
		(end 140.087604 -287.533842)
		(width 0.0889)
		(layer "In13.Cu")
		(net "M_H_CPU1_SB_DQ<22>")
	)
	(arc
		(start 138.216132 -287.529016)
		(mid 138.39964 -287.483522)
		(end 138.581892 -287.533842)
		(width 0.0889)
		(layer "In13.Cu")
		(net "M_H_CPU1_SB_DQ<22>")
	)
	(arc
		(start 143.281654 -287.533842)
		(mid 143.56461 -287.609985)
		(end 143.847566 -287.533842)
		(width 0.0889)
		(layer "In13.Cu")
		(net "M_H_CPU1_SB_DQ<22>")
	)
	(arc
		(start 141.4018 -287.533842)
		(mid 141.684756 -287.609985)
		(end 141.967712 -287.533842)
		(width 0.0889)
		(layer "In13.Cu")
		(net "M_H_CPU1_SB_DQ<22>")
	)
	(arc
		(start 136.383014 -287.50768)
		(mid 136.540524 -287.484482)
		(end 136.693402 -287.529016)
		(width 0.0889)
		(layer "In13.Cu")
		(net "M_H_CPU1_SB_DQ<22>")
	)
	(arc
		(start 141.976094 -287.529016)
		(mid 142.159602 -287.483522)
		(end 142.341854 -287.533842)
		(width 0.0889)
		(layer "In13.Cu")
		(net "M_H_CPU1_SB_DQ<22>")
	)
	(arc
		(start 137.641838 -287.533842)
		(mid 137.924794 -287.609985)
		(end 138.20775 -287.533842)
		(width 0.0889)
		(layer "In13.Cu")
		(net "M_H_CPU1_SB_DQ<22>")
	)
	(arc
		(start 139.147804 -287.533842)
		(mid 139.334748 -287.483587)
		(end 139.521692 -287.533842)
		(width 0.0889)
		(layer "In13.Cu")
		(net "M_H_CPU1_SB_DQ<22>")
	)
	(arc
		(start 140.087604 -287.533842)
		(mid 140.269855 -287.483492)
		(end 140.453364 -287.529016)
		(width 0.0889)
		(layer "In13.Cu")
		(net "M_H_CPU1_SB_DQ<22>")
	)
	(arc
		(start 141.027658 -287.533842)
		(mid 141.209909 -287.483492)
		(end 141.393418 -287.529016)
		(width 0.0889)
		(layer "In13.Cu")
		(net "M_H_CPU1_SB_DQ<22>")
	)
	(segment
		(start 134.16788 -287.590484)
		(end 134.634732 -287.856422)
		(width 0.10668)
		(layer "F.Cu")
		(net "M_H_CPU1_SB_DQ<21>")
	)
	(segment
		(start 138.216132 -288.183574)
		(end 138.20775 -288.178748)
		(width 0.0889)
		(layer "In13.Cu")
		(net "M_H_CPU1_SB_DQ<21>")
	)
	(segment
		(start 135.76173 -288.178748)
		(end 135.753348 -288.183574)
		(width 0.0889)
		(layer "In13.Cu")
		(net "M_H_CPU1_SB_DQ<21>")
	)
	(segment
		(start 173.152054 -308.260496)
		(end 171.538392 -308.260496)
		(width 0.14478)
		(layer "In13.Cu")
		(net "M_H_CPU1_SB_DQ<21>")
	)
	(segment
		(start 151.17699 -293.42842)
		(end 147.866354 -290.117784)
		(width 0.14478)
		(layer "In13.Cu")
		(net "M_H_CPU1_SB_DQ<21>")
	)
	(segment
		(start 165.443916 -308.260496)
		(end 163.531042 -308.260496)
		(width 0.14478)
		(layer "In13.Cu")
		(net "M_H_CPU1_SB_DQ<21>")
	)
	(segment
		(start 169.48658 -307.410612)
		(end 167.495728 -307.410612)
		(width 0.14478)
		(layer "In13.Cu")
		(net "M_H_CPU1_SB_DQ<21>")
	)
	(segment
		(start 171.538392 -308.260496)
		(end 169.48658 -307.410612)
		(width 0.14478)
		(layer "In13.Cu")
		(net "M_H_CPU1_SB_DQ<21>")
	)
	(segment
		(start 134.788656 -288.121852)
		(end 134.634732 -287.856422)
		(width 0.0889)
		(layer "In13.Cu")
		(net "M_H_CPU1_SB_DQ<21>")
	)
	(segment
		(start 137.276078 -288.183574)
		(end 137.267696 -288.178748)
		(width 0.0889)
		(layer "In13.Cu")
		(net "M_H_CPU1_SB_DQ<21>")
	)
	(segment
		(start 141.976094 -288.183574)
		(end 141.967712 -288.178748)
		(width 0.0889)
		(layer "In13.Cu")
		(net "M_H_CPU1_SB_DQ<21>")
	)
	(segment
		(start 147.589494 -289.840924)
		(end 147.119086 -289.840924)
		(width 0.0889)
		(layer "In13.Cu")
		(net "M_H_CPU1_SB_DQ<21>")
	)
	(segment
		(start 146.280886 -288.657284)
		(end 145.587212 -287.96361)
		(width 0.0889)
		(layer "In13.Cu")
		(net "M_H_CPU1_SB_DQ<21>")
	)
	(segment
		(start 147.866354 -290.117784)
		(end 147.589494 -289.840924)
		(width 0.0889)
		(layer "In13.Cu")
		(net "M_H_CPU1_SB_DQ<21>")
	)
	(segment
		(start 145.587212 -287.96361)
		(end 144.58442 -287.96361)
		(width 0.0889)
		(layer "In13.Cu")
		(net "M_H_CPU1_SB_DQ<21>")
	)
	(segment
		(start 140.461746 -288.178748)
		(end 140.453364 -288.183574)
		(width 0.0889)
		(layer "In13.Cu")
		(net "M_H_CPU1_SB_DQ<21>")
	)
	(segment
		(start 141.4018 -288.178748)
		(end 141.393418 -288.183574)
		(width 0.0889)
		(layer "In13.Cu")
		(net "M_H_CPU1_SB_DQ<21>")
	)
	(segment
		(start 159.892492 -307.53685)
		(end 159.518858 -307.382164)
		(width 0.14478)
		(layer "In13.Cu")
		(net "M_H_CPU1_SB_DQ<21>")
	)
	(segment
		(start 159.518858 -307.382164)
		(end 151.17699 -299.040296)
		(width 0.14478)
		(layer "In13.Cu")
		(net "M_H_CPU1_SB_DQ<21>")
	)
	(segment
		(start 136.701784 -288.178748)
		(end 136.693402 -288.183574)
		(width 0.0889)
		(layer "In13.Cu")
		(net "M_H_CPU1_SB_DQ<21>")
	)
	(segment
		(start 163.531042 -308.260496)
		(end 159.892492 -307.53685)
		(width 0.14478)
		(layer "In13.Cu")
		(net "M_H_CPU1_SB_DQ<21>")
	)
	(segment
		(start 151.17699 -299.040296)
		(end 151.17699 -293.42842)
		(width 0.14478)
		(layer "In13.Cu")
		(net "M_H_CPU1_SB_DQ<21>")
	)
	(segment
		(start 146.280886 -289.002724)
		(end 146.280886 -288.657284)
		(width 0.0889)
		(layer "In13.Cu")
		(net "M_H_CPU1_SB_DQ<21>")
	)
	(segment
		(start 134.884414 -288.147252)
		(end 134.788656 -288.121852)
		(width 0.0889)
		(layer "In13.Cu")
		(net "M_H_CPU1_SB_DQ<21>")
	)
	(segment
		(start 147.119086 -289.840924)
		(end 146.280886 -289.002724)
		(width 0.0889)
		(layer "In13.Cu")
		(net "M_H_CPU1_SB_DQ<21>")
	)
	(segment
		(start 176.072038 -307.8353)
		(end 173.152054 -308.260496)
		(width 0.14478)
		(layer "In13.Cu")
		(net "M_H_CPU1_SB_DQ<21>")
	)
	(segment
		(start 144.58442 -287.96361)
		(end 144.460976 -288.087054)
		(width 0.0889)
		(layer "In13.Cu")
		(net "M_H_CPU1_SB_DQ<21>")
	)
	(segment
		(start 167.495728 -307.410612)
		(end 165.443916 -308.260496)
		(width 0.14478)
		(layer "In13.Cu")
		(net "M_H_CPU1_SB_DQ<21>")
	)
	(arc
		(start 137.267696 -288.178748)
		(mid 136.98474 -288.102571)
		(end 136.701784 -288.178748)
		(width 0.0889)
		(layer "In13.Cu")
		(net "M_H_CPU1_SB_DQ<21>")
	)
	(arc
		(start 143.847566 -288.178748)
		(mid 143.56461 -288.102571)
		(end 143.281654 -288.178748)
		(width 0.0889)
		(layer "In13.Cu")
		(net "M_H_CPU1_SB_DQ<21>")
	)
	(arc
		(start 142.907766 -288.178748)
		(mid 142.62481 -288.102571)
		(end 142.341854 -288.178748)
		(width 0.0889)
		(layer "In13.Cu")
		(net "M_H_CPU1_SB_DQ<21>")
	)
	(arc
		(start 141.967712 -288.178748)
		(mid 141.684756 -288.102571)
		(end 141.4018 -288.178748)
		(width 0.0889)
		(layer "In13.Cu")
		(net "M_H_CPU1_SB_DQ<21>")
	)
	(arc
		(start 135.753348 -288.183574)
		(mid 135.56984 -288.229099)
		(end 135.387588 -288.178748)
		(width 0.0889)
		(layer "In13.Cu")
		(net "M_H_CPU1_SB_DQ<21>")
	)
	(arc
		(start 136.693402 -288.183574)
		(mid 136.509894 -288.229099)
		(end 136.327642 -288.178748)
		(width 0.0889)
		(layer "In13.Cu")
		(net "M_H_CPU1_SB_DQ<21>")
	)
	(arc
		(start 138.20775 -288.178748)
		(mid 137.924794 -288.102571)
		(end 137.641838 -288.178748)
		(width 0.0889)
		(layer "In13.Cu")
		(net "M_H_CPU1_SB_DQ<21>")
	)
	(arc
		(start 141.393418 -288.183574)
		(mid 141.20991 -288.229099)
		(end 141.027658 -288.178748)
		(width 0.0889)
		(layer "In13.Cu")
		(net "M_H_CPU1_SB_DQ<21>")
	)
	(arc
		(start 143.281654 -288.178748)
		(mid 143.09471 -288.229037)
		(end 142.907766 -288.178748)
		(width 0.0889)
		(layer "In13.Cu")
		(net "M_H_CPU1_SB_DQ<21>")
	)
	(arc
		(start 144.460976 -288.087054)
		(mid 144.259465 -288.192982)
		(end 144.034764 -288.229548)
		(width 0.0889)
		(layer "In13.Cu")
		(net "M_H_CPU1_SB_DQ<21>")
	)
	(arc
		(start 138.581892 -288.178748)
		(mid 138.399641 -288.229132)
		(end 138.216132 -288.183574)
		(width 0.0889)
		(layer "In13.Cu")
		(net "M_H_CPU1_SB_DQ<21>")
	)
	(arc
		(start 140.087604 -288.178748)
		(mid 139.804648 -288.102571)
		(end 139.521692 -288.178748)
		(width 0.0889)
		(layer "In13.Cu")
		(net "M_H_CPU1_SB_DQ<21>")
	)
	(arc
		(start 136.327642 -288.178748)
		(mid 136.044686 -288.102571)
		(end 135.76173 -288.178748)
		(width 0.0889)
		(layer "In13.Cu")
		(net "M_H_CPU1_SB_DQ<21>")
	)
	(arc
		(start 141.027658 -288.178748)
		(mid 140.744702 -288.102571)
		(end 140.461746 -288.178748)
		(width 0.0889)
		(layer "In13.Cu")
		(net "M_H_CPU1_SB_DQ<21>")
	)
	(arc
		(start 135.387588 -288.178748)
		(mid 135.139728 -288.103665)
		(end 134.884414 -288.147252)
		(width 0.0889)
		(layer "In13.Cu")
		(net "M_H_CPU1_SB_DQ<21>")
	)
	(arc
		(start 139.521692 -288.178748)
		(mid 139.334748 -288.229037)
		(end 139.147804 -288.178748)
		(width 0.0889)
		(layer "In13.Cu")
		(net "M_H_CPU1_SB_DQ<21>")
	)
	(arc
		(start 144.034764 -288.229548)
		(mid 143.937811 -288.216517)
		(end 143.847566 -288.178748)
		(width 0.0889)
		(layer "In13.Cu")
		(net "M_H_CPU1_SB_DQ<21>")
	)
	(arc
		(start 139.147804 -288.178748)
		(mid 138.864848 -288.102571)
		(end 138.581892 -288.178748)
		(width 0.0889)
		(layer "In13.Cu")
		(net "M_H_CPU1_SB_DQ<21>")
	)
	(arc
		(start 140.453364 -288.183574)
		(mid 140.269856 -288.229099)
		(end 140.087604 -288.178748)
		(width 0.0889)
		(layer "In13.Cu")
		(net "M_H_CPU1_SB_DQ<21>")
	)
	(arc
		(start 137.641838 -288.178748)
		(mid 137.459587 -288.229132)
		(end 137.276078 -288.183574)
		(width 0.0889)
		(layer "In13.Cu")
		(net "M_H_CPU1_SB_DQ<21>")
	)
	(arc
		(start 142.341854 -288.178748)
		(mid 142.159603 -288.229132)
		(end 141.976094 -288.183574)
		(width 0.0889)
		(layer "In13.Cu")
		(net "M_H_CPU1_SB_DQ<21>")
	)
	(segment
		(start 135.577834 -286.780478)
		(end 136.044686 -287.046162)
		(width 0.10668)
		(layer "F.Cu")
		(net "M_H_CPU1_SB_DQ<20>")
	)
	(segment
		(start 175.30699 -306.716938)
		(end 175.30699 -306.280058)
		(width 0.14478)
		(layer "In13.Cu")
		(net "M_H_CPU1_SB_DQ<20>")
	)
	(segment
		(start 145.15084 -287.417764)
		(end 145.823686 -287.417764)
		(width 0.0889)
		(layer "In13.Cu")
		(net "M_H_CPU1_SB_DQ<20>")
	)
	(segment
		(start 145.823686 -287.417764)
		(end 146.481546 -288.075624)
		(width 0.0889)
		(layer "In13.Cu")
		(net "M_H_CPU1_SB_DQ<20>")
	)
	(segment
		(start 174.75581 -306.716938)
		(end 174.90059 -306.861718)
		(width 0.14478)
		(layer "In13.Cu")
		(net "M_H_CPU1_SB_DQ<20>")
	)
	(segment
		(start 169.75074 -305.71059)
		(end 170.610276 -306.570126)
		(width 0.14478)
		(layer "In13.Cu")
		(net "M_H_CPU1_SB_DQ<20>")
	)
	(segment
		(start 164.813996 -306.560474)
		(end 166.243 -306.560474)
		(width 0.14478)
		(layer "In13.Cu")
		(net "M_H_CPU1_SB_DQ<20>")
	)
	(segment
		(start 144.833594 -287.292542)
		(end 145.15084 -287.417764)
		(width 0.0889)
		(layer "In13.Cu")
		(net "M_H_CPU1_SB_DQ<20>")
	)
	(segment
		(start 146.481546 -288.075624)
		(end 147.117816 -288.075624)
		(width 0.0889)
		(layer "In13.Cu")
		(net "M_H_CPU1_SB_DQ<20>")
	)
	(segment
		(start 143.377666 -287.368742)
		(end 143.386048 -287.373568)
		(width 0.0889)
		(layer "In13.Cu")
		(net "M_H_CPU1_SB_DQ<20>")
	)
	(segment
		(start 170.610276 -306.570126)
		(end 173.777402 -306.570126)
		(width 0.14478)
		(layer "In13.Cu")
		(net "M_H_CPU1_SB_DQ<20>")
	)
	(segment
		(start 136.198864 -287.311592)
		(end 136.29513 -287.336992)
		(width 0.0889)
		(layer "In13.Cu")
		(net "M_H_CPU1_SB_DQ<20>")
	)
	(segment
		(start 174.90059 -306.861718)
		(end 175.16221 -306.861718)
		(width 0.14478)
		(layer "In13.Cu")
		(net "M_H_CPU1_SB_DQ<20>")
	)
	(segment
		(start 140.557758 -287.368742)
		(end 140.56614 -287.373568)
		(width 0.0889)
		(layer "In13.Cu")
		(net "M_H_CPU1_SB_DQ<20>")
	)
	(segment
		(start 144.03451 -287.292542)
		(end 144.833594 -287.292542)
		(width 0.0889)
		(layer "In13.Cu")
		(net "M_H_CPU1_SB_DQ<20>")
	)
	(segment
		(start 173.777402 -306.570126)
		(end 174.21225 -306.135278)
		(width 0.14478)
		(layer "In13.Cu")
		(net "M_H_CPU1_SB_DQ<20>")
	)
	(segment
		(start 175.16221 -306.861718)
		(end 175.30699 -306.716938)
		(width 0.14478)
		(layer "In13.Cu")
		(net "M_H_CPU1_SB_DQ<20>")
	)
	(segment
		(start 174.21225 -306.135278)
		(end 174.61103 -306.135278)
		(width 0.14478)
		(layer "In13.Cu")
		(net "M_H_CPU1_SB_DQ<20>")
	)
	(segment
		(start 175.30699 -306.280058)
		(end 175.45177 -306.135278)
		(width 0.14478)
		(layer "In13.Cu")
		(net "M_H_CPU1_SB_DQ<20>")
	)
	(segment
		(start 152.07615 -298.056046)
		(end 160.221422 -306.201318)
		(width 0.14478)
		(layer "In13.Cu")
		(net "M_H_CPU1_SB_DQ<20>")
	)
	(segment
		(start 164.45484 -306.201318)
		(end 164.813996 -306.560474)
		(width 0.14478)
		(layer "In13.Cu")
		(net "M_H_CPU1_SB_DQ<20>")
	)
	(segment
		(start 166.243 -306.560474)
		(end 167.092884 -305.71059)
		(width 0.14478)
		(layer "In13.Cu")
		(net "M_H_CPU1_SB_DQ<20>")
	)
	(segment
		(start 160.221422 -306.201318)
		(end 164.45484 -306.201318)
		(width 0.14478)
		(layer "In13.Cu")
		(net "M_H_CPU1_SB_DQ<20>")
	)
	(segment
		(start 139.617704 -287.368742)
		(end 139.626086 -287.373568)
		(width 0.0889)
		(layer "In13.Cu")
		(net "M_H_CPU1_SB_DQ<20>")
	)
	(segment
		(start 139.04341 -287.373568)
		(end 139.051792 -287.368742)
		(width 0.0889)
		(layer "In13.Cu")
		(net "M_H_CPU1_SB_DQ<20>")
	)
	(segment
		(start 136.044686 -287.046162)
		(end 136.198864 -287.311592)
		(width 0.0889)
		(layer "In13.Cu")
		(net "M_H_CPU1_SB_DQ<20>")
	)
	(segment
		(start 175.45177 -306.135278)
		(end 176.072038 -306.135278)
		(width 0.14478)
		(layer "In13.Cu")
		(net "M_H_CPU1_SB_DQ<20>")
	)
	(segment
		(start 167.092884 -305.71059)
		(end 169.75074 -305.71059)
		(width 0.14478)
		(layer "In13.Cu")
		(net "M_H_CPU1_SB_DQ<20>")
	)
	(segment
		(start 142.803372 -287.373568)
		(end 142.811754 -287.368742)
		(width 0.0889)
		(layer "In13.Cu")
		(net "M_H_CPU1_SB_DQ<20>")
	)
	(segment
		(start 147.761198 -288.719006)
		(end 152.07615 -293.033958)
		(width 0.14478)
		(layer "In13.Cu")
		(net "M_H_CPU1_SB_DQ<20>")
	)
	(segment
		(start 152.07615 -293.033958)
		(end 152.07615 -298.056046)
		(width 0.14478)
		(layer "In13.Cu")
		(net "M_H_CPU1_SB_DQ<20>")
	)
	(segment
		(start 147.117816 -288.075624)
		(end 147.761198 -288.719006)
		(width 0.0889)
		(layer "In13.Cu")
		(net "M_H_CPU1_SB_DQ<20>")
	)
	(segment
		(start 174.61103 -306.135278)
		(end 174.75581 -306.280058)
		(width 0.14478)
		(layer "In13.Cu")
		(net "M_H_CPU1_SB_DQ<20>")
	)
	(segment
		(start 138.103356 -287.373568)
		(end 138.111738 -287.368742)
		(width 0.0889)
		(layer "In13.Cu")
		(net "M_H_CPU1_SB_DQ<20>")
	)
	(segment
		(start 174.75581 -306.280058)
		(end 174.75581 -306.716938)
		(width 0.14478)
		(layer "In13.Cu")
		(net "M_H_CPU1_SB_DQ<20>")
	)
	(arc
		(start 137.737596 -287.368742)
		(mid 137.919847 -287.419092)
		(end 138.103356 -287.373568)
		(width 0.0889)
		(layer "In13.Cu")
		(net "M_H_CPU1_SB_DQ<20>")
	)
	(arc
		(start 139.991846 -287.368742)
		(mid 140.274802 -287.292599)
		(end 140.557758 -287.368742)
		(width 0.0889)
		(layer "In13.Cu")
		(net "M_H_CPU1_SB_DQ<20>")
	)
	(arc
		(start 143.751808 -287.368742)
		(mid 143.858142 -287.320978)
		(end 143.972026 -287.296098)
		(width 0.0889)
		(layer "In13.Cu")
		(net "M_H_CPU1_SB_DQ<20>")
	)
	(arc
		(start 136.29513 -287.336992)
		(mid 136.550195 -287.293661)
		(end 136.797796 -287.368742)
		(width 0.0889)
		(layer "In13.Cu")
		(net "M_H_CPU1_SB_DQ<20>")
	)
	(arc
		(start 140.9319 -287.368742)
		(mid 141.214856 -287.292599)
		(end 141.497812 -287.368742)
		(width 0.0889)
		(layer "In13.Cu")
		(net "M_H_CPU1_SB_DQ<20>")
	)
	(arc
		(start 141.8717 -287.368742)
		(mid 142.154656 -287.292599)
		(end 142.437612 -287.368742)
		(width 0.0889)
		(layer "In13.Cu")
		(net "M_H_CPU1_SB_DQ<20>")
	)
	(arc
		(start 139.626086 -287.373568)
		(mid 139.809594 -287.419062)
		(end 139.991846 -287.368742)
		(width 0.0889)
		(layer "In13.Cu")
		(net "M_H_CPU1_SB_DQ<20>")
	)
	(arc
		(start 143.386048 -287.373568)
		(mid 143.569556 -287.419062)
		(end 143.751808 -287.368742)
		(width 0.0889)
		(layer "In13.Cu")
		(net "M_H_CPU1_SB_DQ<20>")
	)
	(arc
		(start 142.811754 -287.368742)
		(mid 143.09471 -287.292599)
		(end 143.377666 -287.368742)
		(width 0.0889)
		(layer "In13.Cu")
		(net "M_H_CPU1_SB_DQ<20>")
	)
	(arc
		(start 138.67765 -287.368742)
		(mid 138.859901 -287.419092)
		(end 139.04341 -287.373568)
		(width 0.0889)
		(layer "In13.Cu")
		(net "M_H_CPU1_SB_DQ<20>")
	)
	(arc
		(start 142.437612 -287.368742)
		(mid 142.619863 -287.419092)
		(end 142.803372 -287.373568)
		(width 0.0889)
		(layer "In13.Cu")
		(net "M_H_CPU1_SB_DQ<20>")
	)
	(arc
		(start 140.56614 -287.373568)
		(mid 140.749648 -287.419062)
		(end 140.9319 -287.368742)
		(width 0.0889)
		(layer "In13.Cu")
		(net "M_H_CPU1_SB_DQ<20>")
	)
	(arc
		(start 139.051792 -287.368742)
		(mid 139.334748 -287.292599)
		(end 139.617704 -287.368742)
		(width 0.0889)
		(layer "In13.Cu")
		(net "M_H_CPU1_SB_DQ<20>")
	)
	(arc
		(start 138.111738 -287.368742)
		(mid 138.394694 -287.292599)
		(end 138.67765 -287.368742)
		(width 0.0889)
		(layer "In13.Cu")
		(net "M_H_CPU1_SB_DQ<20>")
	)
	(arc
		(start 141.497812 -287.368742)
		(mid 141.684756 -287.418997)
		(end 141.8717 -287.368742)
		(width 0.0889)
		(layer "In13.Cu")
		(net "M_H_CPU1_SB_DQ<20>")
	)
	(arc
		(start 143.972026 -287.296098)
		(mid 144.003219 -287.29345)
		(end 144.03451 -287.292542)
		(width 0.0889)
		(layer "In13.Cu")
		(net "M_H_CPU1_SB_DQ<20>")
	)
	(arc
		(start 136.797796 -287.368742)
		(mid 136.98474 -287.418997)
		(end 137.171684 -287.368742)
		(width 0.0889)
		(layer "In13.Cu")
		(net "M_H_CPU1_SB_DQ<20>")
	)
	(arc
		(start 137.171684 -287.368742)
		(mid 137.45464 -287.292599)
		(end 137.737596 -287.368742)
		(width 0.0889)
		(layer "In13.Cu")
		(net "M_H_CPU1_SB_DQ<20>")
	)
	(segment
		(start 134.16788 -274.630388)
		(end 134.634732 -274.896326)
		(width 0.10668)
		(layer "F.Cu")
		(net "M_H_CPU1_SB_DQ<1>")
	)
	(segment
		(start 169.773346 -282.76042)
		(end 171.825158 -283.610304)
		(width 0.14478)
		(layer "In13.Cu")
		(net "M_H_CPU1_SB_DQ<1>")
	)
	(segment
		(start 154.166316 -273.849084)
		(end 163.927536 -283.610304)
		(width 0.14478)
		(layer "In13.Cu")
		(net "M_H_CPU1_SB_DQ<1>")
	)
	(segment
		(start 147.337526 -274.009104)
		(end 147.497546 -273.849084)
		(width 0.0889)
		(layer "In13.Cu")
		(net "M_H_CPU1_SB_DQ<1>")
	)
	(segment
		(start 135.753348 -275.223732)
		(end 135.76173 -275.218906)
		(width 0.0889)
		(layer "In13.Cu")
		(net "M_H_CPU1_SB_DQ<1>")
	)
	(segment
		(start 134.634732 -274.896326)
		(end 134.788656 -275.161756)
		(width 0.0889)
		(layer "In13.Cu")
		(net "M_H_CPU1_SB_DQ<1>")
	)
	(segment
		(start 134.788656 -275.161756)
		(end 134.884668 -275.187156)
		(width 0.0889)
		(layer "In13.Cu")
		(net "M_H_CPU1_SB_DQ<1>")
	)
	(segment
		(start 141.393418 -275.223732)
		(end 141.4018 -275.218906)
		(width 0.0889)
		(layer "In13.Cu")
		(net "M_H_CPU1_SB_DQ<1>")
	)
	(segment
		(start 145.42897 -275.114766)
		(end 145.734532 -274.98802)
		(width 0.0889)
		(layer "In13.Cu")
		(net "M_H_CPU1_SB_DQ<1>")
	)
	(segment
		(start 171.825158 -283.610304)
		(end 172.983906 -283.610304)
		(width 0.14478)
		(layer "In13.Cu")
		(net "M_H_CPU1_SB_DQ<1>")
	)
	(segment
		(start 173.994572 -283.185362)
		(end 176.072038 -283.185362)
		(width 0.14478)
		(layer "In13.Cu")
		(net "M_H_CPU1_SB_DQ<1>")
	)
	(segment
		(start 147.497546 -273.849084)
		(end 148.060918 -273.849084)
		(width 0.0889)
		(layer "In13.Cu")
		(net "M_H_CPU1_SB_DQ<1>")
	)
	(segment
		(start 143.847566 -275.218906)
		(end 143.855948 -275.223732)
		(width 0.0889)
		(layer "In13.Cu")
		(net "M_H_CPU1_SB_DQ<1>")
	)
	(segment
		(start 138.20775 -275.218906)
		(end 138.216132 -275.223732)
		(width 0.0889)
		(layer "In13.Cu")
		(net "M_H_CPU1_SB_DQ<1>")
	)
	(segment
		(start 144.777968 -275.21281)
		(end 144.788382 -275.218906)
		(width 0.0889)
		(layer "In13.Cu")
		(net "M_H_CPU1_SB_DQ<1>")
	)
	(segment
		(start 165.975792 -283.610304)
		(end 166.825676 -282.76042)
		(width 0.14478)
		(layer "In13.Cu")
		(net "M_H_CPU1_SB_DQ<1>")
	)
	(segment
		(start 141.967712 -275.218906)
		(end 141.976094 -275.223732)
		(width 0.0889)
		(layer "In13.Cu")
		(net "M_H_CPU1_SB_DQ<1>")
	)
	(segment
		(start 145.824448 -274.927822)
		(end 146.743166 -274.009104)
		(width 0.0889)
		(layer "In13.Cu")
		(net "M_H_CPU1_SB_DQ<1>")
	)
	(segment
		(start 145.734532 -274.98802)
		(end 145.824448 -274.927822)
		(width 0.0889)
		(layer "In13.Cu")
		(net "M_H_CPU1_SB_DQ<1>")
	)
	(segment
		(start 148.060918 -273.849084)
		(end 154.166316 -273.849084)
		(width 0.14478)
		(layer "In13.Cu")
		(net "M_H_CPU1_SB_DQ<1>")
	)
	(segment
		(start 140.453364 -275.223732)
		(end 140.461746 -275.218906)
		(width 0.0889)
		(layer "In13.Cu")
		(net "M_H_CPU1_SB_DQ<1>")
	)
	(segment
		(start 136.693402 -275.223732)
		(end 136.701784 -275.218906)
		(width 0.0889)
		(layer "In13.Cu")
		(net "M_H_CPU1_SB_DQ<1>")
	)
	(segment
		(start 166.825676 -282.76042)
		(end 169.773346 -282.76042)
		(width 0.14478)
		(layer "In13.Cu")
		(net "M_H_CPU1_SB_DQ<1>")
	)
	(segment
		(start 173.983904 -283.19603)
		(end 173.994572 -283.185362)
		(width 0.14478)
		(layer "In13.Cu")
		(net "M_H_CPU1_SB_DQ<1>")
	)
	(segment
		(start 172.983906 -283.610304)
		(end 173.983904 -283.19603)
		(width 0.14478)
		(layer "In13.Cu")
		(net "M_H_CPU1_SB_DQ<1>")
	)
	(segment
		(start 137.267696 -275.218906)
		(end 137.276078 -275.223732)
		(width 0.0889)
		(layer "In13.Cu")
		(net "M_H_CPU1_SB_DQ<1>")
	)
	(segment
		(start 163.927536 -283.610304)
		(end 165.975792 -283.610304)
		(width 0.14478)
		(layer "In13.Cu")
		(net "M_H_CPU1_SB_DQ<1>")
	)
	(segment
		(start 146.743166 -274.009104)
		(end 147.337526 -274.009104)
		(width 0.0889)
		(layer "In13.Cu")
		(net "M_H_CPU1_SB_DQ<1>")
	)
	(arc
		(start 137.641838 -275.218906)
		(mid 137.924794 -275.142729)
		(end 138.20775 -275.218906)
		(width 0.0889)
		(layer "In13.Cu")
		(net "M_H_CPU1_SB_DQ<1>")
	)
	(arc
		(start 143.281654 -275.218906)
		(mid 143.56461 -275.142729)
		(end 143.847566 -275.218906)
		(width 0.0889)
		(layer "In13.Cu")
		(net "M_H_CPU1_SB_DQ<1>")
	)
	(arc
		(start 138.581892 -275.218906)
		(mid 138.864848 -275.142729)
		(end 139.147804 -275.218906)
		(width 0.0889)
		(layer "In13.Cu")
		(net "M_H_CPU1_SB_DQ<1>")
	)
	(arc
		(start 135.387588 -275.218906)
		(mid 135.569839 -275.269256)
		(end 135.753348 -275.223732)
		(width 0.0889)
		(layer "In13.Cu")
		(net "M_H_CPU1_SB_DQ<1>")
	)
	(arc
		(start 145.158714 -275.213318)
		(mid 145.234478 -275.174902)
		(end 145.31594 -275.150834)
		(width 0.0889)
		(layer "In13.Cu")
		(net "M_H_CPU1_SB_DQ<1>")
	)
	(arc
		(start 141.027658 -275.218906)
		(mid 141.209909 -275.269256)
		(end 141.393418 -275.223732)
		(width 0.0889)
		(layer "In13.Cu")
		(net "M_H_CPU1_SB_DQ<1>")
	)
	(arc
		(start 141.976094 -275.223732)
		(mid 142.159602 -275.269226)
		(end 142.341854 -275.218906)
		(width 0.0889)
		(layer "In13.Cu")
		(net "M_H_CPU1_SB_DQ<1>")
	)
	(arc
		(start 142.341854 -275.218906)
		(mid 142.62481 -275.142729)
		(end 142.907766 -275.218906)
		(width 0.0889)
		(layer "In13.Cu")
		(net "M_H_CPU1_SB_DQ<1>")
	)
	(arc
		(start 144.222216 -275.218906)
		(mid 144.499283 -275.142635)
		(end 144.777968 -275.21281)
		(width 0.0889)
		(layer "In13.Cu")
		(net "M_H_CPU1_SB_DQ<1>")
	)
	(arc
		(start 140.087604 -275.218906)
		(mid 140.269855 -275.269256)
		(end 140.453364 -275.223732)
		(width 0.0889)
		(layer "In13.Cu")
		(net "M_H_CPU1_SB_DQ<1>")
	)
	(arc
		(start 141.4018 -275.218906)
		(mid 141.684756 -275.142729)
		(end 141.967712 -275.218906)
		(width 0.0889)
		(layer "In13.Cu")
		(net "M_H_CPU1_SB_DQ<1>")
	)
	(arc
		(start 137.276078 -275.223732)
		(mid 137.459586 -275.269226)
		(end 137.641838 -275.218906)
		(width 0.0889)
		(layer "In13.Cu")
		(net "M_H_CPU1_SB_DQ<1>")
	)
	(arc
		(start 144.788382 -275.218906)
		(mid 144.974334 -275.267858)
		(end 145.158714 -275.213318)
		(width 0.0889)
		(layer "In13.Cu")
		(net "M_H_CPU1_SB_DQ<1>")
	)
	(arc
		(start 143.855948 -275.223732)
		(mid 144.03971 -275.269348)
		(end 144.222216 -275.218906)
		(width 0.0889)
		(layer "In13.Cu")
		(net "M_H_CPU1_SB_DQ<1>")
	)
	(arc
		(start 142.907766 -275.218906)
		(mid 143.09471 -275.269161)
		(end 143.281654 -275.218906)
		(width 0.0889)
		(layer "In13.Cu")
		(net "M_H_CPU1_SB_DQ<1>")
	)
	(arc
		(start 145.31594 -275.150834)
		(mid 145.373468 -275.135974)
		(end 145.42897 -275.114766)
		(width 0.0889)
		(layer "In13.Cu")
		(net "M_H_CPU1_SB_DQ<1>")
	)
	(arc
		(start 139.521692 -275.218906)
		(mid 139.804648 -275.142729)
		(end 140.087604 -275.218906)
		(width 0.0889)
		(layer "In13.Cu")
		(net "M_H_CPU1_SB_DQ<1>")
	)
	(arc
		(start 136.327642 -275.218906)
		(mid 136.509893 -275.269256)
		(end 136.693402 -275.223732)
		(width 0.0889)
		(layer "In13.Cu")
		(net "M_H_CPU1_SB_DQ<1>")
	)
	(arc
		(start 140.461746 -275.218906)
		(mid 140.744702 -275.142729)
		(end 141.027658 -275.218906)
		(width 0.0889)
		(layer "In13.Cu")
		(net "M_H_CPU1_SB_DQ<1>")
	)
	(arc
		(start 134.884668 -275.187156)
		(mid 135.139876 -275.143679)
		(end 135.387588 -275.218906)
		(width 0.0889)
		(layer "In13.Cu")
		(net "M_H_CPU1_SB_DQ<1>")
	)
	(arc
		(start 136.701784 -275.218906)
		(mid 136.98474 -275.142729)
		(end 137.267696 -275.218906)
		(width 0.0889)
		(layer "In13.Cu")
		(net "M_H_CPU1_SB_DQ<1>")
	)
	(arc
		(start 135.76173 -275.218906)
		(mid 136.044686 -275.142729)
		(end 136.327642 -275.218906)
		(width 0.0889)
		(layer "In13.Cu")
		(net "M_H_CPU1_SB_DQ<1>")
	)
	(arc
		(start 138.216132 -275.223732)
		(mid 138.39964 -275.269226)
		(end 138.581892 -275.218906)
		(width 0.0889)
		(layer "In13.Cu")
		(net "M_H_CPU1_SB_DQ<1>")
	)
	(arc
		(start 139.147804 -275.218906)
		(mid 139.334748 -275.269161)
		(end 139.521692 -275.218906)
		(width 0.0889)
		(layer "In13.Cu")
		(net "M_H_CPU1_SB_DQ<1>")
	)
	(segment
		(start 134.63778 -285.160466)
		(end 135.104632 -285.426404)
		(width 0.10668)
		(layer "F.Cu")
		(net "M_H_CPU1_SB_DQ<19>")
	)
	(segment
		(start 169.065702 -302.054768)
		(end 169.065702 -302.554894)
		(width 0.14478)
		(layer "In13.Cu")
		(net "M_H_CPU1_SB_DQ<19>")
	)
	(segment
		(start 163.196778 -302.764952)
		(end 163.341558 -302.909732)
		(width 0.14478)
		(layer "In13.Cu")
		(net "M_H_CPU1_SB_DQ<19>")
	)
	(segment
		(start 145.347944 -285.050484)
		(end 146.178778 -285.050484)
		(width 0.0889)
		(layer "In13.Cu")
		(net "M_H_CPU1_SB_DQ<19>")
	)
	(segment
		(start 163.747958 -303.16043)
		(end 163.892738 -303.01565)
		(width 0.14478)
		(layer "In13.Cu")
		(net "M_H_CPU1_SB_DQ<19>")
	)
	(segment
		(start 169.616882 -302.054768)
		(end 169.761662 -301.909988)
		(width 0.14478)
		(layer "In13.Cu")
		(net "M_H_CPU1_SB_DQ<19>")
	)
	(segment
		(start 162.790378 -302.909732)
		(end 162.935158 -302.764952)
		(width 0.14478)
		(layer "In13.Cu")
		(net "M_H_CPU1_SB_DQ<19>")
	)
	(segment
		(start 139.617704 -285.103824)
		(end 139.626086 -285.098998)
		(width 0.0889)
		(layer "In13.Cu")
		(net "M_H_CPU1_SB_DQ<19>")
	)
	(segment
		(start 162.790378 -303.01565)
		(end 162.790378 -302.909732)
		(width 0.14478)
		(layer "In13.Cu")
		(net "M_H_CPU1_SB_DQ<19>")
	)
	(segment
		(start 147.657566 -285.977584)
		(end 147.850098 -285.977584)
		(width 0.0889)
		(layer "In13.Cu")
		(net "M_H_CPU1_SB_DQ<19>")
	)
	(segment
		(start 145.276316 -285.093664)
		(end 145.347944 -285.050484)
		(width 0.0889)
		(layer "In13.Cu")
		(net "M_H_CPU1_SB_DQ<19>")
	)
	(segment
		(start 166.08044 -303.16043)
		(end 167.330882 -301.909988)
		(width 0.14478)
		(layer "In13.Cu")
		(net "M_H_CPU1_SB_DQ<19>")
	)
	(segment
		(start 169.065702 -302.554894)
		(end 169.22242 -302.711612)
		(width 0.14478)
		(layer "In13.Cu")
		(net "M_H_CPU1_SB_DQ<19>")
	)
	(segment
		(start 164.443918 -302.909732)
		(end 164.443918 -303.351692)
		(width 0.14478)
		(layer "In13.Cu")
		(net "M_H_CPU1_SB_DQ<19>")
	)
	(segment
		(start 140.557758 -285.103824)
		(end 140.56614 -285.098998)
		(width 0.0889)
		(layer "In13.Cu")
		(net "M_H_CPU1_SB_DQ<19>")
	)
	(segment
		(start 162.645598 -303.16043)
		(end 162.790378 -303.01565)
		(width 0.14478)
		(layer "In13.Cu")
		(net "M_H_CPU1_SB_DQ<19>")
	)
	(segment
		(start 165.546278 -302.909732)
		(end 165.546278 -303.01565)
		(width 0.14478)
		(layer "In13.Cu")
		(net "M_H_CPU1_SB_DQ<19>")
	)
	(segment
		(start 164.299138 -302.764952)
		(end 164.443918 -302.909732)
		(width 0.14478)
		(layer "In13.Cu")
		(net "M_H_CPU1_SB_DQ<19>")
	)
	(segment
		(start 139.04341 -285.098998)
		(end 139.051792 -285.103824)
		(width 0.0889)
		(layer "In13.Cu")
		(net "M_H_CPU1_SB_DQ<19>")
	)
	(segment
		(start 167.963342 -302.054768)
		(end 167.963342 -302.554894)
		(width 0.14478)
		(layer "In13.Cu")
		(net "M_H_CPU1_SB_DQ<19>")
	)
	(segment
		(start 163.341558 -302.909732)
		(end 163.341558 -303.01565)
		(width 0.14478)
		(layer "In13.Cu")
		(net "M_H_CPU1_SB_DQ<19>")
	)
	(segment
		(start 164.850318 -303.496472)
		(end 164.995098 -303.351692)
		(width 0.14478)
		(layer "In13.Cu")
		(net "M_H_CPU1_SB_DQ<19>")
	)
	(segment
		(start 145.25244 -285.10738)
		(end 145.258028 -285.104078)
		(width 0.0889)
		(layer "In13.Cu")
		(net "M_H_CPU1_SB_DQ<19>")
	)
	(segment
		(start 146.178778 -285.050484)
		(end 146.668998 -285.540704)
		(width 0.0889)
		(layer "In13.Cu")
		(net "M_H_CPU1_SB_DQ<19>")
	)
	(segment
		(start 169.93108 -301.909988)
		(end 171.171616 -303.150524)
		(width 0.14478)
		(layer "In13.Cu")
		(net "M_H_CPU1_SB_DQ<19>")
	)
	(segment
		(start 164.995098 -303.351692)
		(end 164.995098 -302.909732)
		(width 0.14478)
		(layer "In13.Cu")
		(net "M_H_CPU1_SB_DQ<19>")
	)
	(segment
		(start 168.920922 -301.909988)
		(end 169.065702 -302.054768)
		(width 0.14478)
		(layer "In13.Cu")
		(net "M_H_CPU1_SB_DQ<19>")
	)
	(segment
		(start 169.761662 -301.909988)
		(end 169.93108 -301.909988)
		(width 0.14478)
		(layer "In13.Cu")
		(net "M_H_CPU1_SB_DQ<19>")
	)
	(segment
		(start 171.55668 -303.150524)
		(end 171.97197 -302.735234)
		(width 0.14478)
		(layer "In13.Cu")
		(net "M_H_CPU1_SB_DQ<19>")
	)
	(segment
		(start 168.659302 -301.909988)
		(end 168.920922 -301.909988)
		(width 0.14478)
		(layer "In13.Cu")
		(net "M_H_CPU1_SB_DQ<19>")
	)
	(segment
		(start 164.443918 -303.351692)
		(end 164.588698 -303.496472)
		(width 0.14478)
		(layer "In13.Cu")
		(net "M_H_CPU1_SB_DQ<19>")
	)
	(segment
		(start 142.803372 -285.098998)
		(end 142.811754 -285.103824)
		(width 0.0889)
		(layer "In13.Cu")
		(net "M_H_CPU1_SB_DQ<19>")
	)
	(segment
		(start 167.818562 -301.909988)
		(end 167.963342 -302.054768)
		(width 0.14478)
		(layer "In13.Cu")
		(net "M_H_CPU1_SB_DQ<19>")
	)
	(segment
		(start 143.751808 -285.103824)
		(end 143.762222 -285.10992)
		(width 0.0889)
		(layer "In13.Cu")
		(net "M_H_CPU1_SB_DQ<19>")
	)
	(segment
		(start 148.338286 -285.977584)
		(end 154.36469 -292.003988)
		(width 0.14478)
		(layer "In13.Cu")
		(net "M_H_CPU1_SB_DQ<19>")
	)
	(segment
		(start 134.950708 -285.160974)
		(end 134.97306 -285.077662)
		(width 0.0889)
		(layer "In13.Cu")
		(net "M_H_CPU1_SB_DQ<19>")
	)
	(segment
		(start 165.139878 -302.764952)
		(end 165.401498 -302.764952)
		(width 0.14478)
		(layer "In13.Cu")
		(net "M_H_CPU1_SB_DQ<19>")
	)
	(segment
		(start 135.857742 -285.103824)
		(end 135.866124 -285.098998)
		(width 0.0889)
		(layer "In13.Cu")
		(net "M_H_CPU1_SB_DQ<19>")
	)
	(segment
		(start 169.22242 -302.711612)
		(end 169.460164 -302.711612)
		(width 0.14478)
		(layer "In13.Cu")
		(net "M_H_CPU1_SB_DQ<19>")
	)
	(segment
		(start 162.935158 -302.764952)
		(end 163.196778 -302.764952)
		(width 0.14478)
		(layer "In13.Cu")
		(net "M_H_CPU1_SB_DQ<19>")
	)
	(segment
		(start 138.103356 -285.098998)
		(end 138.111738 -285.103824)
		(width 0.0889)
		(layer "In13.Cu")
		(net "M_H_CPU1_SB_DQ<19>")
	)
	(segment
		(start 154.36469 -295.932606)
		(end 161.592514 -303.16043)
		(width 0.14478)
		(layer "In13.Cu")
		(net "M_H_CPU1_SB_DQ<19>")
	)
	(segment
		(start 168.514522 -302.054768)
		(end 168.659302 -301.909988)
		(width 0.14478)
		(layer "In13.Cu")
		(net "M_H_CPU1_SB_DQ<19>")
	)
	(segment
		(start 147.220686 -285.540704)
		(end 147.657566 -285.977584)
		(width 0.0889)
		(layer "In13.Cu")
		(net "M_H_CPU1_SB_DQ<19>")
	)
	(segment
		(start 147.850098 -285.977584)
		(end 148.338286 -285.977584)
		(width 0.14478)
		(layer "In13.Cu")
		(net "M_H_CPU1_SB_DQ<19>")
	)
	(segment
		(start 169.460164 -302.711612)
		(end 169.616882 -302.554894)
		(width 0.14478)
		(layer "In13.Cu")
		(net "M_H_CPU1_SB_DQ<19>")
	)
	(segment
		(start 164.995098 -302.909732)
		(end 165.139878 -302.764952)
		(width 0.14478)
		(layer "In13.Cu")
		(net "M_H_CPU1_SB_DQ<19>")
	)
	(segment
		(start 163.341558 -303.01565)
		(end 163.486338 -303.16043)
		(width 0.14478)
		(layer "In13.Cu")
		(net "M_H_CPU1_SB_DQ<19>")
	)
	(segment
		(start 167.330882 -301.909988)
		(end 167.818562 -301.909988)
		(width 0.14478)
		(layer "In13.Cu")
		(net "M_H_CPU1_SB_DQ<19>")
	)
	(segment
		(start 168.514522 -302.554894)
		(end 168.514522 -302.054768)
		(width 0.14478)
		(layer "In13.Cu")
		(net "M_H_CPU1_SB_DQ<19>")
	)
	(segment
		(start 169.616882 -302.554894)
		(end 169.616882 -302.054768)
		(width 0.14478)
		(layer "In13.Cu")
		(net "M_H_CPU1_SB_DQ<19>")
	)
	(segment
		(start 165.691058 -303.16043)
		(end 166.08044 -303.16043)
		(width 0.14478)
		(layer "In13.Cu")
		(net "M_H_CPU1_SB_DQ<19>")
	)
	(segment
		(start 168.12006 -302.711612)
		(end 168.357804 -302.711612)
		(width 0.14478)
		(layer "In13.Cu")
		(net "M_H_CPU1_SB_DQ<19>")
	)
	(segment
		(start 161.592514 -303.16043)
		(end 162.645598 -303.16043)
		(width 0.14478)
		(layer "In13.Cu")
		(net "M_H_CPU1_SB_DQ<19>")
	)
	(segment
		(start 165.546278 -303.01565)
		(end 165.691058 -303.16043)
		(width 0.14478)
		(layer "In13.Cu")
		(net "M_H_CPU1_SB_DQ<19>")
	)
	(segment
		(start 135.104632 -285.426404)
		(end 134.950708 -285.160974)
		(width 0.0889)
		(layer "In13.Cu")
		(net "M_H_CPU1_SB_DQ<19>")
	)
	(segment
		(start 168.357804 -302.711612)
		(end 168.514522 -302.554894)
		(width 0.14478)
		(layer "In13.Cu")
		(net "M_H_CPU1_SB_DQ<19>")
	)
	(segment
		(start 171.171616 -303.150524)
		(end 171.55668 -303.150524)
		(width 0.14478)
		(layer "In13.Cu")
		(net "M_H_CPU1_SB_DQ<19>")
	)
	(segment
		(start 143.377666 -285.103824)
		(end 143.386048 -285.098998)
		(width 0.0889)
		(layer "In13.Cu")
		(net "M_H_CPU1_SB_DQ<19>")
	)
	(segment
		(start 163.892738 -303.01565)
		(end 163.892738 -302.909732)
		(width 0.14478)
		(layer "In13.Cu")
		(net "M_H_CPU1_SB_DQ<19>")
	)
	(segment
		(start 165.401498 -302.764952)
		(end 165.546278 -302.909732)
		(width 0.14478)
		(layer "In13.Cu")
		(net "M_H_CPU1_SB_DQ<19>")
	)
	(segment
		(start 164.037518 -302.764952)
		(end 164.299138 -302.764952)
		(width 0.14478)
		(layer "In13.Cu")
		(net "M_H_CPU1_SB_DQ<19>")
	)
	(segment
		(start 146.668998 -285.540704)
		(end 147.220686 -285.540704)
		(width 0.0889)
		(layer "In13.Cu")
		(net "M_H_CPU1_SB_DQ<19>")
	)
	(segment
		(start 145.258028 -285.104078)
		(end 145.276316 -285.093664)
		(width 0.0889)
		(layer "In13.Cu")
		(net "M_H_CPU1_SB_DQ<19>")
	)
	(segment
		(start 163.892738 -302.909732)
		(end 164.037518 -302.764952)
		(width 0.14478)
		(layer "In13.Cu")
		(net "M_H_CPU1_SB_DQ<19>")
	)
	(segment
		(start 167.963342 -302.554894)
		(end 168.12006 -302.711612)
		(width 0.14478)
		(layer "In13.Cu")
		(net "M_H_CPU1_SB_DQ<19>")
	)
	(segment
		(start 163.486338 -303.16043)
		(end 163.747958 -303.16043)
		(width 0.14478)
		(layer "In13.Cu")
		(net "M_H_CPU1_SB_DQ<19>")
	)
	(segment
		(start 144.684242 -285.098998)
		(end 144.692624 -285.103824)
		(width 0.0889)
		(layer "In13.Cu")
		(net "M_H_CPU1_SB_DQ<19>")
	)
	(segment
		(start 164.588698 -303.496472)
		(end 164.850318 -303.496472)
		(width 0.14478)
		(layer "In13.Cu")
		(net "M_H_CPU1_SB_DQ<19>")
	)
	(segment
		(start 154.36469 -292.003988)
		(end 154.36469 -295.932606)
		(width 0.14478)
		(layer "In13.Cu")
		(net "M_H_CPU1_SB_DQ<19>")
	)
	(arc
		(start 140.56614 -285.098998)
		(mid 140.749648 -285.053504)
		(end 140.9319 -285.103824)
		(width 0.0889)
		(layer "In13.Cu")
		(net "M_H_CPU1_SB_DQ<19>")
	)
	(arc
		(start 135.866124 -285.098998)
		(mid 136.049632 -285.053504)
		(end 136.231884 -285.103824)
		(width 0.0889)
		(layer "In13.Cu")
		(net "M_H_CPU1_SB_DQ<19>")
	)
	(arc
		(start 136.231884 -285.103824)
		(mid 136.51484 -285.180001)
		(end 136.797796 -285.103824)
		(width 0.0889)
		(layer "In13.Cu")
		(net "M_H_CPU1_SB_DQ<19>")
	)
	(arc
		(start 142.811754 -285.103824)
		(mid 143.09471 -285.180001)
		(end 143.377666 -285.103824)
		(width 0.0889)
		(layer "In13.Cu")
		(net "M_H_CPU1_SB_DQ<19>")
	)
	(arc
		(start 139.991846 -285.103824)
		(mid 140.274802 -285.180001)
		(end 140.557758 -285.103824)
		(width 0.0889)
		(layer "In13.Cu")
		(net "M_H_CPU1_SB_DQ<19>")
	)
	(arc
		(start 138.111738 -285.103824)
		(mid 138.394694 -285.180001)
		(end 138.67765 -285.103824)
		(width 0.0889)
		(layer "In13.Cu")
		(net "M_H_CPU1_SB_DQ<19>")
	)
	(arc
		(start 143.386048 -285.098998)
		(mid 143.569556 -285.053504)
		(end 143.751808 -285.103824)
		(width 0.0889)
		(layer "In13.Cu")
		(net "M_H_CPU1_SB_DQ<19>")
	)
	(arc
		(start 140.9319 -285.103824)
		(mid 141.214856 -285.180001)
		(end 141.497812 -285.103824)
		(width 0.0889)
		(layer "In13.Cu")
		(net "M_H_CPU1_SB_DQ<19>")
	)
	(arc
		(start 135.29183 -285.103824)
		(mid 135.574786 -285.180001)
		(end 135.857742 -285.103824)
		(width 0.0889)
		(layer "In13.Cu")
		(net "M_H_CPU1_SB_DQ<19>")
	)
	(arc
		(start 134.97306 -285.077662)
		(mid 135.135392 -285.054844)
		(end 135.29183 -285.103824)
		(width 0.0889)
		(layer "In13.Cu")
		(net "M_H_CPU1_SB_DQ<19>")
	)
	(arc
		(start 141.8717 -285.103824)
		(mid 142.154656 -285.180001)
		(end 142.437612 -285.103824)
		(width 0.0889)
		(layer "In13.Cu")
		(net "M_H_CPU1_SB_DQ<19>")
	)
	(arc
		(start 142.437612 -285.103824)
		(mid 142.619863 -285.053474)
		(end 142.803372 -285.098998)
		(width 0.0889)
		(layer "In13.Cu")
		(net "M_H_CPU1_SB_DQ<19>")
	)
	(arc
		(start 138.67765 -285.103824)
		(mid 138.859901 -285.053474)
		(end 139.04341 -285.098998)
		(width 0.0889)
		(layer "In13.Cu")
		(net "M_H_CPU1_SB_DQ<19>")
	)
	(arc
		(start 137.171684 -285.103824)
		(mid 137.45464 -285.180001)
		(end 137.737596 -285.103824)
		(width 0.0889)
		(layer "In13.Cu")
		(net "M_H_CPU1_SB_DQ<19>")
	)
	(arc
		(start 139.051792 -285.103824)
		(mid 139.334748 -285.180001)
		(end 139.617704 -285.103824)
		(width 0.0889)
		(layer "In13.Cu")
		(net "M_H_CPU1_SB_DQ<19>")
	)
	(arc
		(start 143.762222 -285.10992)
		(mid 144.040908 -285.18014)
		(end 144.317974 -285.103824)
		(width 0.0889)
		(layer "In13.Cu")
		(net "M_H_CPU1_SB_DQ<19>")
	)
	(arc
		(start 141.497812 -285.103824)
		(mid 141.684756 -285.053569)
		(end 141.8717 -285.103824)
		(width 0.0889)
		(layer "In13.Cu")
		(net "M_H_CPU1_SB_DQ<19>")
	)
	(arc
		(start 136.797796 -285.103824)
		(mid 136.98474 -285.053569)
		(end 137.171684 -285.103824)
		(width 0.0889)
		(layer "In13.Cu")
		(net "M_H_CPU1_SB_DQ<19>")
	)
	(arc
		(start 137.737596 -285.103824)
		(mid 137.919847 -285.053474)
		(end 138.103356 -285.098998)
		(width 0.0889)
		(layer "In13.Cu")
		(net "M_H_CPU1_SB_DQ<19>")
	)
	(arc
		(start 144.317974 -285.103824)
		(mid 144.500479 -285.053347)
		(end 144.684242 -285.098998)
		(width 0.0889)
		(layer "In13.Cu")
		(net "M_H_CPU1_SB_DQ<19>")
	)
	(arc
		(start 144.692624 -285.103824)
		(mid 144.972052 -285.17999)
		(end 145.25244 -285.10738)
		(width 0.0889)
		(layer "In13.Cu")
		(net "M_H_CPU1_SB_DQ<19>")
	)
	(arc
		(start 139.626086 -285.098998)
		(mid 139.809594 -285.053504)
		(end 139.991846 -285.103824)
		(width 0.0889)
		(layer "In13.Cu")
		(net "M_H_CPU1_SB_DQ<19>")
	)
	(segment
		(start 136.047988 -284.35046)
		(end 136.51484 -284.616398)
		(width 0.10668)
		(layer "F.Cu")
		(net "M_H_CPU1_SB_DQ<18>")
	)
	(segment
		(start 155.26385 -291.631116)
		(end 148.700998 -285.068264)
		(width 0.14478)
		(layer "In13.Cu")
		(net "M_H_CPU1_SB_DQ<18>")
	)
	(segment
		(start 136.701784 -284.293818)
		(end 136.693402 -284.288992)
		(width 0.0889)
		(layer "In13.Cu")
		(net "M_H_CPU1_SB_DQ<18>")
	)
	(segment
		(start 161.197036 -301.49292)
		(end 161.052256 -301.34814)
		(width 0.14478)
		(layer "In13.Cu")
		(net "M_H_CPU1_SB_DQ<18>")
	)
	(segment
		(start 163.256976 -301.715932)
		(end 163.256976 -301.20463)
		(width 0.14478)
		(layer "In13.Cu")
		(net "M_H_CPU1_SB_DQ<18>")
	)
	(segment
		(start 161.603436 -301.20463)
		(end 161.603436 -301.34814)
		(width 0.14478)
		(layer "In13.Cu")
		(net "M_H_CPU1_SB_DQ<18>")
	)
	(segment
		(start 168.38422 -300.46549)
		(end 168.23944 -300.61027)
		(width 0.14478)
		(layer "In13.Cu")
		(net "M_H_CPU1_SB_DQ<18>")
	)
	(segment
		(start 164.765736 -301.476918)
		(end 164.504116 -301.476918)
		(width 0.14478)
		(layer "In13.Cu")
		(net "M_H_CPU1_SB_DQ<18>")
	)
	(segment
		(start 161.458656 -301.49292)
		(end 161.197036 -301.49292)
		(width 0.14478)
		(layer "In13.Cu")
		(net "M_H_CPU1_SB_DQ<18>")
	)
	(segment
		(start 169.89298 -300.209966)
		(end 169.63136 -300.209966)
		(width 0.14478)
		(layer "In13.Cu")
		(net "M_H_CPU1_SB_DQ<18>")
	)
	(segment
		(start 155.26385 -295.559734)
		(end 155.26385 -291.631116)
		(width 0.14478)
		(layer "In13.Cu")
		(net "M_H_CPU1_SB_DQ<18>")
	)
	(segment
		(start 160.763966 -301.05985)
		(end 155.26385 -295.559734)
		(width 0.14478)
		(layer "In13.Cu")
		(net "M_H_CPU1_SB_DQ<18>")
	)
	(segment
		(start 168.529 -300.209966)
		(end 168.38422 -300.354746)
		(width 0.14478)
		(layer "In13.Cu")
		(net "M_H_CPU1_SB_DQ<18>")
	)
	(segment
		(start 144.220946 -284.294072)
		(end 144.20088 -284.282642)
		(width 0.0889)
		(layer "In13.Cu")
		(net "M_H_CPU1_SB_DQ<18>")
	)
	(segment
		(start 168.9354 -300.354746)
		(end 168.79062 -300.209966)
		(width 0.14478)
		(layer "In13.Cu")
		(net "M_H_CPU1_SB_DQ<18>")
	)
	(segment
		(start 144.80413 -284.282896)
		(end 144.785334 -284.293818)
		(width 0.0889)
		(layer "In13.Cu")
		(net "M_H_CPU1_SB_DQ<18>")
	)
	(segment
		(start 170.03776 -300.354746)
		(end 169.89298 -300.209966)
		(width 0.14478)
		(layer "In13.Cu")
		(net "M_H_CPU1_SB_DQ<18>")
	)
	(segment
		(start 167.000174 -300.61027)
		(end 166.550594 -301.05985)
		(width 0.14478)
		(layer "In13.Cu")
		(net "M_H_CPU1_SB_DQ<18>")
	)
	(segment
		(start 168.9354 -300.866048)
		(end 168.9354 -300.354746)
		(width 0.14478)
		(layer "In13.Cu")
		(net "M_H_CPU1_SB_DQ<18>")
	)
	(segment
		(start 169.63136 -300.209966)
		(end 169.48658 -300.354746)
		(width 0.14478)
		(layer "In13.Cu")
		(net "M_H_CPU1_SB_DQ<18>")
	)
	(segment
		(start 162.154616 -301.715932)
		(end 162.154616 -301.20463)
		(width 0.14478)
		(layer "In13.Cu")
		(net "M_H_CPU1_SB_DQ<18>")
	)
	(segment
		(start 140.461746 -284.293818)
		(end 140.453364 -284.288992)
		(width 0.0889)
		(layer "In13.Cu")
		(net "M_H_CPU1_SB_DQ<18>")
	)
	(segment
		(start 162.561016 -301.860712)
		(end 162.299396 -301.860712)
		(width 0.14478)
		(layer "In13.Cu")
		(net "M_H_CPU1_SB_DQ<18>")
	)
	(segment
		(start 162.705796 -301.20463)
		(end 162.705796 -301.715932)
		(width 0.14478)
		(layer "In13.Cu")
		(net "M_H_CPU1_SB_DQ<18>")
	)
	(segment
		(start 164.910516 -301.332138)
		(end 164.765736 -301.476918)
		(width 0.14478)
		(layer "In13.Cu")
		(net "M_H_CPU1_SB_DQ<18>")
	)
	(segment
		(start 165.868096 -301.860712)
		(end 165.606476 -301.860712)
		(width 0.14478)
		(layer "In13.Cu")
		(net "M_H_CPU1_SB_DQ<18>")
	)
	(segment
		(start 166.012876 -301.20463)
		(end 166.012876 -301.715932)
		(width 0.14478)
		(layer "In13.Cu")
		(net "M_H_CPU1_SB_DQ<18>")
	)
	(segment
		(start 169.3418 -301.010828)
		(end 169.08018 -301.010828)
		(width 0.14478)
		(layer "In13.Cu")
		(net "M_H_CPU1_SB_DQ<18>")
	)
	(segment
		(start 168.23944 -300.61027)
		(end 167.97782 -300.61027)
		(width 0.14478)
		(layer "In13.Cu")
		(net "M_H_CPU1_SB_DQ<18>")
	)
	(segment
		(start 138.216132 -284.288992)
		(end 138.20775 -284.293818)
		(width 0.0889)
		(layer "In13.Cu")
		(net "M_H_CPU1_SB_DQ<18>")
	)
	(segment
		(start 169.08018 -301.010828)
		(end 168.9354 -300.866048)
		(width 0.14478)
		(layer "In13.Cu")
		(net "M_H_CPU1_SB_DQ<18>")
	)
	(segment
		(start 144.242536 -284.306518)
		(end 144.220946 -284.294072)
		(width 0.0889)
		(layer "In13.Cu")
		(net "M_H_CPU1_SB_DQ<18>")
	)
	(segment
		(start 147.528026 -284.959044)
		(end 146.79041 -284.959044)
		(width 0.0889)
		(layer "In13.Cu")
		(net "M_H_CPU1_SB_DQ<18>")
	)
	(segment
		(start 164.214556 -301.05985)
		(end 163.952936 -301.05985)
		(width 0.14478)
		(layer "In13.Cu")
		(net "M_H_CPU1_SB_DQ<18>")
	)
	(segment
		(start 167.13708 -300.61027)
		(end 167.000174 -300.61027)
		(width 0.14478)
		(layer "In13.Cu")
		(net "M_H_CPU1_SB_DQ<18>")
	)
	(segment
		(start 167.68826 -300.273466)
		(end 167.42664 -300.273466)
		(width 0.14478)
		(layer "In13.Cu")
		(net "M_H_CPU1_SB_DQ<18>")
	)
	(segment
		(start 162.154616 -301.20463)
		(end 162.009836 -301.05985)
		(width 0.14478)
		(layer "In13.Cu")
		(net "M_H_CPU1_SB_DQ<18>")
	)
	(segment
		(start 163.808156 -301.715932)
		(end 163.663376 -301.860712)
		(width 0.14478)
		(layer "In13.Cu")
		(net "M_H_CPU1_SB_DQ<18>")
	)
	(segment
		(start 166.550594 -301.05985)
		(end 166.157656 -301.05985)
		(width 0.14478)
		(layer "In13.Cu")
		(net "M_H_CPU1_SB_DQ<18>")
	)
	(segment
		(start 168.38422 -300.354746)
		(end 168.38422 -300.46549)
		(width 0.14478)
		(layer "In13.Cu")
		(net "M_H_CPU1_SB_DQ<18>")
	)
	(segment
		(start 136.360662 -284.350968)
		(end 136.51484 -284.616398)
		(width 0.0889)
		(layer "In13.Cu")
		(net "M_H_CPU1_SB_DQ<18>")
	)
	(segment
		(start 167.97782 -300.61027)
		(end 167.83304 -300.46549)
		(width 0.14478)
		(layer "In13.Cu")
		(net "M_H_CPU1_SB_DQ<18>")
	)
	(segment
		(start 162.299396 -301.860712)
		(end 162.154616 -301.715932)
		(width 0.14478)
		(layer "In13.Cu")
		(net "M_H_CPU1_SB_DQ<18>")
	)
	(segment
		(start 162.850576 -301.05985)
		(end 162.705796 -301.20463)
		(width 0.14478)
		(layer "In13.Cu")
		(net "M_H_CPU1_SB_DQ<18>")
	)
	(segment
		(start 167.28186 -300.418246)
		(end 167.28186 -300.46549)
		(width 0.14478)
		(layer "In13.Cu")
		(net "M_H_CPU1_SB_DQ<18>")
	)
	(segment
		(start 163.663376 -301.860712)
		(end 163.401756 -301.860712)
		(width 0.14478)
		(layer "In13.Cu")
		(net "M_H_CPU1_SB_DQ<18>")
	)
	(segment
		(start 148.700998 -285.068264)
		(end 147.912836 -285.068264)
		(width 0.14478)
		(layer "In13.Cu")
		(net "M_H_CPU1_SB_DQ<18>")
	)
	(segment
		(start 169.48658 -300.866048)
		(end 169.3418 -301.010828)
		(width 0.14478)
		(layer "In13.Cu")
		(net "M_H_CPU1_SB_DQ<18>")
	)
	(segment
		(start 167.42664 -300.273466)
		(end 167.28186 -300.418246)
		(width 0.14478)
		(layer "In13.Cu")
		(net "M_H_CPU1_SB_DQ<18>")
	)
	(segment
		(start 161.748216 -301.05985)
		(end 161.603436 -301.20463)
		(width 0.14478)
		(layer "In13.Cu")
		(net "M_H_CPU1_SB_DQ<18>")
	)
	(segment
		(start 161.052256 -301.20463)
		(end 160.907476 -301.05985)
		(width 0.14478)
		(layer "In13.Cu")
		(net "M_H_CPU1_SB_DQ<18>")
	)
	(segment
		(start 164.910516 -301.20463)
		(end 164.910516 -301.332138)
		(width 0.14478)
		(layer "In13.Cu")
		(net "M_H_CPU1_SB_DQ<18>")
	)
	(segment
		(start 161.603436 -301.34814)
		(end 161.458656 -301.49292)
		(width 0.14478)
		(layer "In13.Cu")
		(net "M_H_CPU1_SB_DQ<18>")
	)
	(segment
		(start 164.359336 -301.332138)
		(end 164.359336 -301.20463)
		(width 0.14478)
		(layer "In13.Cu")
		(net "M_H_CPU1_SB_DQ<18>")
	)
	(segment
		(start 136.383014 -284.267656)
		(end 136.360662 -284.350968)
		(width 0.0889)
		(layer "In13.Cu")
		(net "M_H_CPU1_SB_DQ<18>")
	)
	(segment
		(start 163.952936 -301.05985)
		(end 163.808156 -301.20463)
		(width 0.14478)
		(layer "In13.Cu")
		(net "M_H_CPU1_SB_DQ<18>")
	)
	(segment
		(start 147.912836 -285.068264)
		(end 147.637246 -285.068264)
		(width 0.0889)
		(layer "In13.Cu")
		(net "M_H_CPU1_SB_DQ<18>")
	)
	(segment
		(start 163.256976 -301.20463)
		(end 163.112196 -301.05985)
		(width 0.14478)
		(layer "In13.Cu")
		(net "M_H_CPU1_SB_DQ<18>")
	)
	(segment
		(start 168.79062 -300.209966)
		(end 168.529 -300.209966)
		(width 0.14478)
		(layer "In13.Cu")
		(net "M_H_CPU1_SB_DQ<18>")
	)
	(segment
		(start 169.48658 -300.354746)
		(end 169.48658 -300.866048)
		(width 0.14478)
		(layer "In13.Cu")
		(net "M_H_CPU1_SB_DQ<18>")
	)
	(segment
		(start 167.83304 -300.418246)
		(end 167.68826 -300.273466)
		(width 0.14478)
		(layer "In13.Cu")
		(net "M_H_CPU1_SB_DQ<18>")
	)
	(segment
		(start 165.606476 -301.860712)
		(end 165.461696 -301.715932)
		(width 0.14478)
		(layer "In13.Cu")
		(net "M_H_CPU1_SB_DQ<18>")
	)
	(segment
		(start 164.504116 -301.476918)
		(end 164.359336 -301.332138)
		(width 0.14478)
		(layer "In13.Cu")
		(net "M_H_CPU1_SB_DQ<18>")
	)
	(segment
		(start 147.637246 -285.068264)
		(end 147.528026 -284.959044)
		(width 0.0889)
		(layer "In13.Cu")
		(net "M_H_CPU1_SB_DQ<18>")
	)
	(segment
		(start 163.808156 -301.20463)
		(end 163.808156 -301.715932)
		(width 0.14478)
		(layer "In13.Cu")
		(net "M_H_CPU1_SB_DQ<18>")
	)
	(segment
		(start 166.157656 -301.05985)
		(end 166.012876 -301.20463)
		(width 0.14478)
		(layer "In13.Cu")
		(net "M_H_CPU1_SB_DQ<18>")
	)
	(segment
		(start 170.03776 -300.46549)
		(end 170.03776 -300.354746)
		(width 0.14478)
		(layer "In13.Cu")
		(net "M_H_CPU1_SB_DQ<18>")
	)
	(segment
		(start 141.4018 -284.293818)
		(end 141.393418 -284.288992)
		(width 0.0889)
		(layer "In13.Cu")
		(net "M_H_CPU1_SB_DQ<18>")
	)
	(segment
		(start 165.055296 -301.05985)
		(end 164.910516 -301.20463)
		(width 0.14478)
		(layer "In13.Cu")
		(net "M_H_CPU1_SB_DQ<18>")
	)
	(segment
		(start 171.6024 -301.460408)
		(end 171.032678 -301.460408)
		(width 0.14478)
		(layer "In13.Cu")
		(net "M_H_CPU1_SB_DQ<18>")
	)
	(segment
		(start 166.012876 -301.715932)
		(end 165.868096 -301.860712)
		(width 0.14478)
		(layer "In13.Cu")
		(net "M_H_CPU1_SB_DQ<18>")
	)
	(segment
		(start 164.359336 -301.20463)
		(end 164.214556 -301.05985)
		(width 0.14478)
		(layer "In13.Cu")
		(net "M_H_CPU1_SB_DQ<18>")
	)
	(segment
		(start 171.032678 -301.460408)
		(end 170.03776 -300.46549)
		(width 0.14478)
		(layer "In13.Cu")
		(net "M_H_CPU1_SB_DQ<18>")
	)
	(segment
		(start 162.705796 -301.715932)
		(end 162.561016 -301.860712)
		(width 0.14478)
		(layer "In13.Cu")
		(net "M_H_CPU1_SB_DQ<18>")
	)
	(segment
		(start 146.201892 -284.370526)
		(end 145.444718 -284.370526)
		(width 0.0889)
		(layer "In13.Cu")
		(net "M_H_CPU1_SB_DQ<18>")
	)
	(segment
		(start 163.112196 -301.05985)
		(end 162.850576 -301.05985)
		(width 0.14478)
		(layer "In13.Cu")
		(net "M_H_CPU1_SB_DQ<18>")
	)
	(segment
		(start 171.97197 -301.035212)
		(end 171.97197 -301.090838)
		(width 0.14478)
		(layer "In13.Cu")
		(net "M_H_CPU1_SB_DQ<18>")
	)
	(segment
		(start 165.461696 -301.20463)
		(end 165.316916 -301.05985)
		(width 0.14478)
		(layer "In13.Cu")
		(net "M_H_CPU1_SB_DQ<18>")
	)
	(segment
		(start 163.401756 -301.860712)
		(end 163.256976 -301.715932)
		(width 0.14478)
		(layer "In13.Cu")
		(net "M_H_CPU1_SB_DQ<18>")
	)
	(segment
		(start 165.316916 -301.05985)
		(end 165.055296 -301.05985)
		(width 0.14478)
		(layer "In13.Cu")
		(net "M_H_CPU1_SB_DQ<18>")
	)
	(segment
		(start 137.276078 -284.288992)
		(end 137.267696 -284.293818)
		(width 0.0889)
		(layer "In13.Cu")
		(net "M_H_CPU1_SB_DQ<18>")
	)
	(segment
		(start 161.052256 -301.34814)
		(end 161.052256 -301.20463)
		(width 0.14478)
		(layer "In13.Cu")
		(net "M_H_CPU1_SB_DQ<18>")
	)
	(segment
		(start 160.907476 -301.05985)
		(end 160.763966 -301.05985)
		(width 0.14478)
		(layer "In13.Cu")
		(net "M_H_CPU1_SB_DQ<18>")
	)
	(segment
		(start 162.009836 -301.05985)
		(end 161.748216 -301.05985)
		(width 0.14478)
		(layer "In13.Cu")
		(net "M_H_CPU1_SB_DQ<18>")
	)
	(segment
		(start 167.83304 -300.46549)
		(end 167.83304 -300.418246)
		(width 0.14478)
		(layer "In13.Cu")
		(net "M_H_CPU1_SB_DQ<18>")
	)
	(segment
		(start 141.976094 -284.288992)
		(end 141.967712 -284.293818)
		(width 0.0889)
		(layer "In13.Cu")
		(net "M_H_CPU1_SB_DQ<18>")
	)
	(segment
		(start 146.79041 -284.959044)
		(end 146.201892 -284.370526)
		(width 0.0889)
		(layer "In13.Cu")
		(net "M_H_CPU1_SB_DQ<18>")
	)
	(segment
		(start 165.461696 -301.715932)
		(end 165.461696 -301.20463)
		(width 0.14478)
		(layer "In13.Cu")
		(net "M_H_CPU1_SB_DQ<18>")
	)
	(segment
		(start 167.28186 -300.46549)
		(end 167.13708 -300.61027)
		(width 0.14478)
		(layer "In13.Cu")
		(net "M_H_CPU1_SB_DQ<18>")
	)
	(segment
		(start 171.97197 -301.090838)
		(end 171.6024 -301.460408)
		(width 0.14478)
		(layer "In13.Cu")
		(net "M_H_CPU1_SB_DQ<18>")
	)
	(arc
		(start 145.160492 -284.293818)
		(mid 144.983701 -284.243099)
		(end 144.80413 -284.282896)
		(width 0.0889)
		(layer "In13.Cu")
		(net "M_H_CPU1_SB_DQ<18>")
	)
	(arc
		(start 138.581892 -284.293818)
		(mid 138.399641 -284.243468)
		(end 138.216132 -284.288992)
		(width 0.0889)
		(layer "In13.Cu")
		(net "M_H_CPU1_SB_DQ<18>")
	)
	(arc
		(start 145.444718 -284.370526)
		(mid 145.297509 -284.351049)
		(end 145.160492 -284.293818)
		(width 0.0889)
		(layer "In13.Cu")
		(net "M_H_CPU1_SB_DQ<18>")
	)
	(arc
		(start 144.785334 -284.293818)
		(mid 144.515565 -284.369841)
		(end 144.242536 -284.306518)
		(width 0.0889)
		(layer "In13.Cu")
		(net "M_H_CPU1_SB_DQ<18>")
	)
	(arc
		(start 143.281654 -284.293818)
		(mid 143.09471 -284.243563)
		(end 142.907766 -284.293818)
		(width 0.0889)
		(layer "In13.Cu")
		(net "M_H_CPU1_SB_DQ<18>")
	)
	(arc
		(start 138.20775 -284.293818)
		(mid 137.924794 -284.369995)
		(end 137.641838 -284.293818)
		(width 0.0889)
		(layer "In13.Cu")
		(net "M_H_CPU1_SB_DQ<18>")
	)
	(arc
		(start 140.453364 -284.288992)
		(mid 140.269856 -284.243498)
		(end 140.087604 -284.293818)
		(width 0.0889)
		(layer "In13.Cu")
		(net "M_H_CPU1_SB_DQ<18>")
	)
	(arc
		(start 139.521692 -284.293818)
		(mid 139.334748 -284.243563)
		(end 139.147804 -284.293818)
		(width 0.0889)
		(layer "In13.Cu")
		(net "M_H_CPU1_SB_DQ<18>")
	)
	(arc
		(start 141.027658 -284.293818)
		(mid 140.744702 -284.369995)
		(end 140.461746 -284.293818)
		(width 0.0889)
		(layer "In13.Cu")
		(net "M_H_CPU1_SB_DQ<18>")
	)
	(arc
		(start 141.967712 -284.293818)
		(mid 141.684756 -284.369995)
		(end 141.4018 -284.293818)
		(width 0.0889)
		(layer "In13.Cu")
		(net "M_H_CPU1_SB_DQ<18>")
	)
	(arc
		(start 141.393418 -284.288992)
		(mid 141.20991 -284.243498)
		(end 141.027658 -284.293818)
		(width 0.0889)
		(layer "In13.Cu")
		(net "M_H_CPU1_SB_DQ<18>")
	)
	(arc
		(start 142.341854 -284.293818)
		(mid 142.159603 -284.243468)
		(end 141.976094 -284.288992)
		(width 0.0889)
		(layer "In13.Cu")
		(net "M_H_CPU1_SB_DQ<18>")
	)
	(arc
		(start 137.267696 -284.293818)
		(mid 136.98474 -284.369995)
		(end 136.701784 -284.293818)
		(width 0.0889)
		(layer "In13.Cu")
		(net "M_H_CPU1_SB_DQ<18>")
	)
	(arc
		(start 140.087604 -284.293818)
		(mid 139.804648 -284.369995)
		(end 139.521692 -284.293818)
		(width 0.0889)
		(layer "In13.Cu")
		(net "M_H_CPU1_SB_DQ<18>")
	)
	(arc
		(start 143.847566 -284.293818)
		(mid 143.56461 -284.369995)
		(end 143.281654 -284.293818)
		(width 0.0889)
		(layer "In13.Cu")
		(net "M_H_CPU1_SB_DQ<18>")
	)
	(arc
		(start 137.641838 -284.293818)
		(mid 137.459587 -284.243468)
		(end 137.276078 -284.288992)
		(width 0.0889)
		(layer "In13.Cu")
		(net "M_H_CPU1_SB_DQ<18>")
	)
	(arc
		(start 136.693402 -284.288992)
		(mid 136.540532 -284.244351)
		(end 136.383014 -284.267656)
		(width 0.0889)
		(layer "In13.Cu")
		(net "M_H_CPU1_SB_DQ<18>")
	)
	(arc
		(start 142.907766 -284.293818)
		(mid 142.62481 -284.369995)
		(end 142.341854 -284.293818)
		(width 0.0889)
		(layer "In13.Cu")
		(net "M_H_CPU1_SB_DQ<18>")
	)
	(arc
		(start 139.147804 -284.293818)
		(mid 138.864848 -284.369995)
		(end 138.581892 -284.293818)
		(width 0.0889)
		(layer "In13.Cu")
		(net "M_H_CPU1_SB_DQ<18>")
	)
	(arc
		(start 144.20088 -284.282642)
		(mid 144.022802 -284.243658)
		(end 143.847566 -284.293818)
		(width 0.0889)
		(layer "In13.Cu")
		(net "M_H_CPU1_SB_DQ<18>")
	)
	(segment
		(start 134.16788 -284.35046)
		(end 134.634732 -284.616398)
		(width 0.10668)
		(layer "F.Cu")
		(net "M_H_CPU1_SB_DQ<17>")
	)
	(segment
		(start 175.001174 -301.921164)
		(end 175.001174 -301.74057)
		(width 0.14478)
		(layer "In13.Cu")
		(net "M_H_CPU1_SB_DQ<17>")
	)
	(segment
		(start 147.85594 -285.522924)
		(end 148.519642 -285.522924)
		(width 0.14478)
		(layer "In13.Cu")
		(net "M_H_CPU1_SB_DQ<17>")
	)
	(segment
		(start 174.043594 -301.59579)
		(end 174.305214 -301.59579)
		(width 0.14478)
		(layer "In13.Cu")
		(net "M_H_CPU1_SB_DQ<17>")
	)
	(segment
		(start 145.146014 -284.948122)
		(end 145.318988 -284.844744)
		(width 0.0889)
		(layer "In13.Cu")
		(net "M_H_CPU1_SB_DQ<17>")
	)
	(segment
		(start 137.267696 -284.938978)
		(end 137.276078 -284.943804)
		(width 0.0889)
		(layer "In13.Cu")
		(net "M_H_CPU1_SB_DQ<17>")
	)
	(segment
		(start 161.378392 -302.310292)
		(end 166.243 -302.310292)
		(width 0.14478)
		(layer "In13.Cu")
		(net "M_H_CPU1_SB_DQ<17>")
	)
	(segment
		(start 141.967712 -284.938978)
		(end 141.976094 -284.943804)
		(width 0.0889)
		(layer "In13.Cu")
		(net "M_H_CPU1_SB_DQ<17>")
	)
	(segment
		(start 173.754034 -302.030384)
		(end 173.898814 -301.885604)
		(width 0.14478)
		(layer "In13.Cu")
		(net "M_H_CPU1_SB_DQ<17>")
	)
	(segment
		(start 154.81427 -295.74617)
		(end 161.378392 -302.310292)
		(width 0.14478)
		(layer "In13.Cu")
		(net "M_H_CPU1_SB_DQ<17>")
	)
	(segment
		(start 144.777968 -284.932882)
		(end 144.788382 -284.938978)
		(width 0.0889)
		(layer "In13.Cu")
		(net "M_H_CPU1_SB_DQ<17>")
	)
	(segment
		(start 135.753348 -284.943804)
		(end 135.76173 -284.938978)
		(width 0.0889)
		(layer "In13.Cu")
		(net "M_H_CPU1_SB_DQ<17>")
	)
	(segment
		(start 147.6248 -285.522924)
		(end 147.85594 -285.522924)
		(width 0.0889)
		(layer "In13.Cu")
		(net "M_H_CPU1_SB_DQ<17>")
	)
	(segment
		(start 170.117516 -301.460408)
		(end 170.9674 -302.310292)
		(width 0.14478)
		(layer "In13.Cu")
		(net "M_H_CPU1_SB_DQ<17>")
	)
	(segment
		(start 146.303492 -284.844744)
		(end 146.687032 -285.228284)
		(width 0.0889)
		(layer "In13.Cu")
		(net "M_H_CPU1_SB_DQ<17>")
	)
	(segment
		(start 145.318988 -284.844744)
		(end 146.303492 -284.844744)
		(width 0.0889)
		(layer "In13.Cu")
		(net "M_H_CPU1_SB_DQ<17>")
	)
	(segment
		(start 170.9674 -302.310292)
		(end 172.617384 -302.310292)
		(width 0.14478)
		(layer "In13.Cu")
		(net "M_H_CPU1_SB_DQ<17>")
	)
	(segment
		(start 141.393418 -284.943804)
		(end 141.4018 -284.938978)
		(width 0.0889)
		(layer "In13.Cu")
		(net "M_H_CPU1_SB_DQ<17>")
	)
	(segment
		(start 147.33016 -285.228284)
		(end 147.6248 -285.522924)
		(width 0.0889)
		(layer "In13.Cu")
		(net "M_H_CPU1_SB_DQ<17>")
	)
	(segment
		(start 175.697134 -301.88535)
		(end 176.072038 -301.88535)
		(width 0.14478)
		(layer "In13.Cu")
		(net "M_H_CPU1_SB_DQ<17>")
	)
	(segment
		(start 167.092884 -301.460408)
		(end 170.117516 -301.460408)
		(width 0.14478)
		(layer "In13.Cu")
		(net "M_H_CPU1_SB_DQ<17>")
	)
	(segment
		(start 134.634732 -284.616398)
		(end 134.788656 -284.881828)
		(width 0.0889)
		(layer "In13.Cu")
		(net "M_H_CPU1_SB_DQ<17>")
	)
	(segment
		(start 173.898814 -301.74057)
		(end 174.043594 -301.59579)
		(width 0.14478)
		(layer "In13.Cu")
		(net "M_H_CPU1_SB_DQ<17>")
	)
	(segment
		(start 166.243 -302.310292)
		(end 167.092884 -301.460408)
		(width 0.14478)
		(layer "In13.Cu")
		(net "M_H_CPU1_SB_DQ<17>")
	)
	(segment
		(start 138.20775 -284.938978)
		(end 138.216132 -284.943804)
		(width 0.0889)
		(layer "In13.Cu")
		(net "M_H_CPU1_SB_DQ<17>")
	)
	(segment
		(start 174.305214 -301.59579)
		(end 174.449994 -301.74057)
		(width 0.14478)
		(layer "In13.Cu")
		(net "M_H_CPU1_SB_DQ<17>")
	)
	(segment
		(start 134.788656 -284.881828)
		(end 134.884668 -284.907228)
		(width 0.0889)
		(layer "In13.Cu")
		(net "M_H_CPU1_SB_DQ<17>")
	)
	(segment
		(start 140.453364 -284.943804)
		(end 140.461746 -284.938978)
		(width 0.0889)
		(layer "In13.Cu")
		(net "M_H_CPU1_SB_DQ<17>")
	)
	(segment
		(start 148.519642 -285.522924)
		(end 154.81427 -291.817552)
		(width 0.14478)
		(layer "In13.Cu")
		(net "M_H_CPU1_SB_DQ<17>")
	)
	(segment
		(start 174.856394 -302.065944)
		(end 175.001174 -301.921164)
		(width 0.14478)
		(layer "In13.Cu")
		(net "M_H_CPU1_SB_DQ<17>")
	)
	(segment
		(start 172.897292 -302.030384)
		(end 173.754034 -302.030384)
		(width 0.14478)
		(layer "In13.Cu")
		(net "M_H_CPU1_SB_DQ<17>")
	)
	(segment
		(start 174.594774 -302.065944)
		(end 174.856394 -302.065944)
		(width 0.14478)
		(layer "In13.Cu")
		(net "M_H_CPU1_SB_DQ<17>")
	)
	(segment
		(start 172.617384 -302.310292)
		(end 172.897292 -302.030384)
		(width 0.14478)
		(layer "In13.Cu")
		(net "M_H_CPU1_SB_DQ<17>")
	)
	(segment
		(start 173.898814 -301.885604)
		(end 173.898814 -301.74057)
		(width 0.14478)
		(layer "In13.Cu")
		(net "M_H_CPU1_SB_DQ<17>")
	)
	(segment
		(start 143.847566 -284.938978)
		(end 143.855948 -284.943804)
		(width 0.0889)
		(layer "In13.Cu")
		(net "M_H_CPU1_SB_DQ<17>")
	)
	(segment
		(start 175.001174 -301.74057)
		(end 175.145954 -301.59579)
		(width 0.14478)
		(layer "In13.Cu")
		(net "M_H_CPU1_SB_DQ<17>")
	)
	(segment
		(start 175.145954 -301.59579)
		(end 175.407574 -301.59579)
		(width 0.14478)
		(layer "In13.Cu")
		(net "M_H_CPU1_SB_DQ<17>")
	)
	(segment
		(start 175.407574 -301.59579)
		(end 175.697134 -301.88535)
		(width 0.14478)
		(layer "In13.Cu")
		(net "M_H_CPU1_SB_DQ<17>")
	)
	(segment
		(start 174.449994 -301.921164)
		(end 174.594774 -302.065944)
		(width 0.14478)
		(layer "In13.Cu")
		(net "M_H_CPU1_SB_DQ<17>")
	)
	(segment
		(start 154.81427 -291.817552)
		(end 154.81427 -295.74617)
		(width 0.14478)
		(layer "In13.Cu")
		(net "M_H_CPU1_SB_DQ<17>")
	)
	(segment
		(start 146.687032 -285.228284)
		(end 147.33016 -285.228284)
		(width 0.0889)
		(layer "In13.Cu")
		(net "M_H_CPU1_SB_DQ<17>")
	)
	(segment
		(start 136.693402 -284.943804)
		(end 136.701784 -284.938978)
		(width 0.0889)
		(layer "In13.Cu")
		(net "M_H_CPU1_SB_DQ<17>")
	)
	(segment
		(start 174.449994 -301.74057)
		(end 174.449994 -301.921164)
		(width 0.14478)
		(layer "In13.Cu")
		(net "M_H_CPU1_SB_DQ<17>")
	)
	(arc
		(start 142.907766 -284.938978)
		(mid 143.09471 -284.989233)
		(end 143.281654 -284.938978)
		(width 0.0889)
		(layer "In13.Cu")
		(net "M_H_CPU1_SB_DQ<17>")
	)
	(arc
		(start 140.461746 -284.938978)
		(mid 140.744702 -284.862801)
		(end 141.027658 -284.938978)
		(width 0.0889)
		(layer "In13.Cu")
		(net "M_H_CPU1_SB_DQ<17>")
	)
	(arc
		(start 141.027658 -284.938978)
		(mid 141.209909 -284.989328)
		(end 141.393418 -284.943804)
		(width 0.0889)
		(layer "In13.Cu")
		(net "M_H_CPU1_SB_DQ<17>")
	)
	(arc
		(start 134.884668 -284.907228)
		(mid 135.139876 -284.863751)
		(end 135.387588 -284.938978)
		(width 0.0889)
		(layer "In13.Cu")
		(net "M_H_CPU1_SB_DQ<17>")
	)
	(arc
		(start 138.581892 -284.938978)
		(mid 138.864848 -284.862801)
		(end 139.147804 -284.938978)
		(width 0.0889)
		(layer "In13.Cu")
		(net "M_H_CPU1_SB_DQ<17>")
	)
	(arc
		(start 135.76173 -284.938978)
		(mid 136.044686 -284.862801)
		(end 136.327642 -284.938978)
		(width 0.0889)
		(layer "In13.Cu")
		(net "M_H_CPU1_SB_DQ<17>")
	)
	(arc
		(start 143.855948 -284.943804)
		(mid 144.03971 -284.98942)
		(end 144.222216 -284.938978)
		(width 0.0889)
		(layer "In13.Cu")
		(net "M_H_CPU1_SB_DQ<17>")
	)
	(arc
		(start 137.641838 -284.938978)
		(mid 137.924794 -284.862801)
		(end 138.20775 -284.938978)
		(width 0.0889)
		(layer "In13.Cu")
		(net "M_H_CPU1_SB_DQ<17>")
	)
	(arc
		(start 141.4018 -284.938978)
		(mid 141.684756 -284.862801)
		(end 141.967712 -284.938978)
		(width 0.0889)
		(layer "In13.Cu")
		(net "M_H_CPU1_SB_DQ<17>")
	)
	(arc
		(start 135.387588 -284.938978)
		(mid 135.569839 -284.989328)
		(end 135.753348 -284.943804)
		(width 0.0889)
		(layer "In13.Cu")
		(net "M_H_CPU1_SB_DQ<17>")
	)
	(arc
		(start 144.222216 -284.938978)
		(mid 144.499283 -284.862707)
		(end 144.777968 -284.932882)
		(width 0.0889)
		(layer "In13.Cu")
		(net "M_H_CPU1_SB_DQ<17>")
	)
	(arc
		(start 139.521692 -284.938978)
		(mid 139.804648 -284.862801)
		(end 140.087604 -284.938978)
		(width 0.0889)
		(layer "In13.Cu")
		(net "M_H_CPU1_SB_DQ<17>")
	)
	(arc
		(start 136.327642 -284.938978)
		(mid 136.509893 -284.989328)
		(end 136.693402 -284.943804)
		(width 0.0889)
		(layer "In13.Cu")
		(net "M_H_CPU1_SB_DQ<17>")
	)
	(arc
		(start 137.276078 -284.943804)
		(mid 137.459586 -284.989298)
		(end 137.641838 -284.938978)
		(width 0.0889)
		(layer "In13.Cu")
		(net "M_H_CPU1_SB_DQ<17>")
	)
	(arc
		(start 136.701784 -284.938978)
		(mid 136.98474 -284.862801)
		(end 137.267696 -284.938978)
		(width 0.0889)
		(layer "In13.Cu")
		(net "M_H_CPU1_SB_DQ<17>")
	)
	(arc
		(start 142.341854 -284.938978)
		(mid 142.62481 -284.862801)
		(end 142.907766 -284.938978)
		(width 0.0889)
		(layer "In13.Cu")
		(net "M_H_CPU1_SB_DQ<17>")
	)
	(arc
		(start 140.087604 -284.938978)
		(mid 140.269855 -284.989328)
		(end 140.453364 -284.943804)
		(width 0.0889)
		(layer "In13.Cu")
		(net "M_H_CPU1_SB_DQ<17>")
	)
	(arc
		(start 139.147804 -284.938978)
		(mid 139.334748 -284.989233)
		(end 139.521692 -284.938978)
		(width 0.0889)
		(layer "In13.Cu")
		(net "M_H_CPU1_SB_DQ<17>")
	)
	(arc
		(start 138.216132 -284.943804)
		(mid 138.39964 -284.989298)
		(end 138.581892 -284.938978)
		(width 0.0889)
		(layer "In13.Cu")
		(net "M_H_CPU1_SB_DQ<17>")
	)
	(arc
		(start 143.281654 -284.938978)
		(mid 143.56461 -284.862801)
		(end 143.847566 -284.938978)
		(width 0.0889)
		(layer "In13.Cu")
		(net "M_H_CPU1_SB_DQ<17>")
	)
	(arc
		(start 144.788382 -284.938978)
		(mid 144.966032 -284.989238)
		(end 145.146014 -284.948122)
		(width 0.0889)
		(layer "In13.Cu")
		(net "M_H_CPU1_SB_DQ<17>")
	)
	(arc
		(start 141.976094 -284.943804)
		(mid 142.159602 -284.989298)
		(end 142.341854 -284.938978)
		(width 0.0889)
		(layer "In13.Cu")
		(net "M_H_CPU1_SB_DQ<17>")
	)
	(segment
		(start 135.577834 -283.540454)
		(end 136.044686 -283.806392)
		(width 0.10668)
		(layer "F.Cu")
		(net "M_H_CPU1_SB_DQ<16>")
	)
	(segment
		(start 147.86737 -284.613604)
		(end 147.373086 -284.613604)
		(width 0.0889)
		(layer "In13.Cu")
		(net "M_H_CPU1_SB_DQ<16>")
	)
	(segment
		(start 175.33493 -300.330108)
		(end 175.33493 -300.660816)
		(width 0.14478)
		(layer "In13.Cu")
		(net "M_H_CPU1_SB_DQ<16>")
	)
	(segment
		(start 166.243 -300.61027)
		(end 160.950402 -300.61027)
		(width 0.14478)
		(layer "In13.Cu")
		(net "M_H_CPU1_SB_DQ<16>")
	)
	(segment
		(start 148.882354 -284.613604)
		(end 147.86737 -284.613604)
		(width 0.14478)
		(layer "In13.Cu")
		(net "M_H_CPU1_SB_DQ<16>")
	)
	(segment
		(start 174.92853 -300.805596)
		(end 174.78375 -300.660816)
		(width 0.14478)
		(layer "In13.Cu")
		(net "M_H_CPU1_SB_DQ<16>")
	)
	(segment
		(start 144.334484 -284.139132)
		(end 144.316196 -284.128718)
		(width 0.0889)
		(layer "In13.Cu")
		(net "M_H_CPU1_SB_DQ<16>")
	)
	(segment
		(start 174.37735 -300.058328)
		(end 174.23257 -300.203108)
		(width 0.14478)
		(layer "In13.Cu")
		(net "M_H_CPU1_SB_DQ<16>")
	)
	(segment
		(start 142.811754 -284.128972)
		(end 142.803372 -284.133798)
		(width 0.0889)
		(layer "In13.Cu")
		(net "M_H_CPU1_SB_DQ<16>")
	)
	(segment
		(start 138.111738 -284.128972)
		(end 138.103356 -284.133798)
		(width 0.0889)
		(layer "In13.Cu")
		(net "M_H_CPU1_SB_DQ<16>")
	)
	(segment
		(start 145.444972 -284.180026)
		(end 145.444718 -284.179772)
		(width 0.0889)
		(layer "In13.Cu")
		(net "M_H_CPU1_SB_DQ<16>")
	)
	(segment
		(start 174.78375 -300.660816)
		(end 174.78375 -300.203108)
		(width 0.14478)
		(layer "In13.Cu")
		(net "M_H_CPU1_SB_DQ<16>")
	)
	(segment
		(start 155.71343 -291.44468)
		(end 148.882354 -284.613604)
		(width 0.14478)
		(layer "In13.Cu")
		(net "M_H_CPU1_SB_DQ<16>")
	)
	(segment
		(start 173.53661 -300.058328)
		(end 173.27499 -300.058328)
		(width 0.14478)
		(layer "In13.Cu")
		(net "M_H_CPU1_SB_DQ<16>")
	)
	(segment
		(start 170.977052 -300.619922)
		(end 170.117516 -299.760386)
		(width 0.14478)
		(layer "In13.Cu")
		(net "M_H_CPU1_SB_DQ<16>")
	)
	(segment
		(start 144.71269 -284.115256)
		(end 144.689322 -284.128972)
		(width 0.0889)
		(layer "In13.Cu")
		(net "M_H_CPU1_SB_DQ<16>")
	)
	(segment
		(start 174.63897 -300.058328)
		(end 174.37735 -300.058328)
		(width 0.14478)
		(layer "In13.Cu")
		(net "M_H_CPU1_SB_DQ<16>")
	)
	(segment
		(start 173.13021 -300.203108)
		(end 173.13021 -300.660816)
		(width 0.14478)
		(layer "In13.Cu")
		(net "M_H_CPU1_SB_DQ<16>")
	)
	(segment
		(start 136.29513 -284.097222)
		(end 136.198864 -284.071822)
		(width 0.0889)
		(layer "In13.Cu")
		(net "M_H_CPU1_SB_DQ<16>")
	)
	(segment
		(start 147.258786 -284.727904)
		(end 146.895566 -284.727904)
		(width 0.0889)
		(layer "In13.Cu")
		(net "M_H_CPU1_SB_DQ<16>")
	)
	(segment
		(start 173.13021 -300.660816)
		(end 172.98543 -300.805596)
		(width 0.14478)
		(layer "In13.Cu")
		(net "M_H_CPU1_SB_DQ<16>")
	)
	(segment
		(start 139.626086 -284.133798)
		(end 139.617704 -284.128972)
		(width 0.0889)
		(layer "In13.Cu")
		(net "M_H_CPU1_SB_DQ<16>")
	)
	(segment
		(start 167.092884 -299.760386)
		(end 166.243 -300.61027)
		(width 0.14478)
		(layer "In13.Cu")
		(net "M_H_CPU1_SB_DQ<16>")
	)
	(segment
		(start 174.78375 -300.203108)
		(end 174.63897 -300.058328)
		(width 0.14478)
		(layer "In13.Cu")
		(net "M_H_CPU1_SB_DQ<16>")
	)
	(segment
		(start 170.117516 -299.760386)
		(end 167.092884 -299.760386)
		(width 0.14478)
		(layer "In13.Cu")
		(net "M_H_CPU1_SB_DQ<16>")
	)
	(segment
		(start 173.68139 -300.660816)
		(end 173.68139 -300.203108)
		(width 0.14478)
		(layer "In13.Cu")
		(net "M_H_CPU1_SB_DQ<16>")
	)
	(segment
		(start 139.051792 -284.128972)
		(end 139.04341 -284.133798)
		(width 0.0889)
		(layer "In13.Cu")
		(net "M_H_CPU1_SB_DQ<16>")
	)
	(segment
		(start 146.895566 -284.727904)
		(end 146.347688 -284.180026)
		(width 0.0889)
		(layer "In13.Cu")
		(net "M_H_CPU1_SB_DQ<16>")
	)
	(segment
		(start 174.08779 -300.805596)
		(end 173.82617 -300.805596)
		(width 0.14478)
		(layer "In13.Cu")
		(net "M_H_CPU1_SB_DQ<16>")
	)
	(segment
		(start 143.386048 -284.133798)
		(end 143.377666 -284.128972)
		(width 0.0889)
		(layer "In13.Cu")
		(net "M_H_CPU1_SB_DQ<16>")
	)
	(segment
		(start 146.347688 -284.180026)
		(end 145.444972 -284.180026)
		(width 0.0889)
		(layer "In13.Cu")
		(net "M_H_CPU1_SB_DQ<16>")
	)
	(segment
		(start 172.98543 -300.805596)
		(end 172.72381 -300.805596)
		(width 0.14478)
		(layer "In13.Cu")
		(net "M_H_CPU1_SB_DQ<16>")
	)
	(segment
		(start 136.198864 -284.071822)
		(end 136.044686 -283.806392)
		(width 0.0889)
		(layer "In13.Cu")
		(net "M_H_CPU1_SB_DQ<16>")
	)
	(segment
		(start 173.82617 -300.805596)
		(end 173.68139 -300.660816)
		(width 0.14478)
		(layer "In13.Cu")
		(net "M_H_CPU1_SB_DQ<16>")
	)
	(segment
		(start 176.072038 -300.185328)
		(end 175.47971 -300.185328)
		(width 0.14478)
		(layer "In13.Cu")
		(net "M_H_CPU1_SB_DQ<16>")
	)
	(segment
		(start 174.23257 -300.660816)
		(end 174.08779 -300.805596)
		(width 0.14478)
		(layer "In13.Cu")
		(net "M_H_CPU1_SB_DQ<16>")
	)
	(segment
		(start 160.950402 -300.61027)
		(end 155.71343 -295.373298)
		(width 0.14478)
		(layer "In13.Cu")
		(net "M_H_CPU1_SB_DQ<16>")
	)
	(segment
		(start 175.19015 -300.805596)
		(end 174.92853 -300.805596)
		(width 0.14478)
		(layer "In13.Cu")
		(net "M_H_CPU1_SB_DQ<16>")
	)
	(segment
		(start 172.72381 -300.805596)
		(end 172.538136 -300.619922)
		(width 0.14478)
		(layer "In13.Cu")
		(net "M_H_CPU1_SB_DQ<16>")
	)
	(segment
		(start 175.33493 -300.660816)
		(end 175.19015 -300.805596)
		(width 0.14478)
		(layer "In13.Cu")
		(net "M_H_CPU1_SB_DQ<16>")
	)
	(segment
		(start 175.47971 -300.185328)
		(end 175.33493 -300.330108)
		(width 0.14478)
		(layer "In13.Cu")
		(net "M_H_CPU1_SB_DQ<16>")
	)
	(segment
		(start 144.316196 -284.128718)
		(end 144.294606 -284.116272)
		(width 0.0889)
		(layer "In13.Cu")
		(net "M_H_CPU1_SB_DQ<16>")
	)
	(segment
		(start 173.27499 -300.058328)
		(end 173.13021 -300.203108)
		(width 0.14478)
		(layer "In13.Cu")
		(net "M_H_CPU1_SB_DQ<16>")
	)
	(segment
		(start 140.56614 -284.133798)
		(end 140.557758 -284.128972)
		(width 0.0889)
		(layer "In13.Cu")
		(net "M_H_CPU1_SB_DQ<16>")
	)
	(segment
		(start 155.71343 -295.373298)
		(end 155.71343 -291.44468)
		(width 0.14478)
		(layer "In13.Cu")
		(net "M_H_CPU1_SB_DQ<16>")
	)
	(segment
		(start 147.373086 -284.613604)
		(end 147.258786 -284.727904)
		(width 0.0889)
		(layer "In13.Cu")
		(net "M_H_CPU1_SB_DQ<16>")
	)
	(segment
		(start 173.68139 -300.203108)
		(end 173.53661 -300.058328)
		(width 0.14478)
		(layer "In13.Cu")
		(net "M_H_CPU1_SB_DQ<16>")
	)
	(segment
		(start 174.23257 -300.203108)
		(end 174.23257 -300.660816)
		(width 0.14478)
		(layer "In13.Cu")
		(net "M_H_CPU1_SB_DQ<16>")
	)
	(segment
		(start 172.538136 -300.619922)
		(end 170.977052 -300.619922)
		(width 0.14478)
		(layer "In13.Cu")
		(net "M_H_CPU1_SB_DQ<16>")
	)
	(arc
		(start 142.803372 -284.133798)
		(mid 142.619864 -284.179292)
		(end 142.437612 -284.128972)
		(width 0.0889)
		(layer "In13.Cu")
		(net "M_H_CPU1_SB_DQ<16>")
	)
	(arc
		(start 144.294606 -284.116272)
		(mid 144.021577 -284.052953)
		(end 143.751808 -284.128972)
		(width 0.0889)
		(layer "In13.Cu")
		(net "M_H_CPU1_SB_DQ<16>")
	)
	(arc
		(start 145.444718 -284.179772)
		(mid 145.34723 -284.166889)
		(end 145.256504 -284.128972)
		(width 0.0889)
		(layer "In13.Cu")
		(net "M_H_CPU1_SB_DQ<16>")
	)
	(arc
		(start 144.689322 -284.128972)
		(mid 144.513202 -284.17895)
		(end 144.334484 -284.139132)
		(width 0.0889)
		(layer "In13.Cu")
		(net "M_H_CPU1_SB_DQ<16>")
	)
	(arc
		(start 137.171684 -284.128972)
		(mid 136.98474 -284.179227)
		(end 136.797796 -284.128972)
		(width 0.0889)
		(layer "In13.Cu")
		(net "M_H_CPU1_SB_DQ<16>")
	)
	(arc
		(start 143.377666 -284.128972)
		(mid 143.09471 -284.052795)
		(end 142.811754 -284.128972)
		(width 0.0889)
		(layer "In13.Cu")
		(net "M_H_CPU1_SB_DQ<16>")
	)
	(arc
		(start 140.9319 -284.128972)
		(mid 140.749649 -284.179322)
		(end 140.56614 -284.133798)
		(width 0.0889)
		(layer "In13.Cu")
		(net "M_H_CPU1_SB_DQ<16>")
	)
	(arc
		(start 139.617704 -284.128972)
		(mid 139.334748 -284.052795)
		(end 139.051792 -284.128972)
		(width 0.0889)
		(layer "In13.Cu")
		(net "M_H_CPU1_SB_DQ<16>")
	)
	(arc
		(start 141.497812 -284.128972)
		(mid 141.214856 -284.052795)
		(end 140.9319 -284.128972)
		(width 0.0889)
		(layer "In13.Cu")
		(net "M_H_CPU1_SB_DQ<16>")
	)
	(arc
		(start 142.437612 -284.128972)
		(mid 142.154656 -284.052795)
		(end 141.8717 -284.128972)
		(width 0.0889)
		(layer "In13.Cu")
		(net "M_H_CPU1_SB_DQ<16>")
	)
	(arc
		(start 139.991846 -284.128972)
		(mid 139.809595 -284.179322)
		(end 139.626086 -284.133798)
		(width 0.0889)
		(layer "In13.Cu")
		(net "M_H_CPU1_SB_DQ<16>")
	)
	(arc
		(start 138.67765 -284.128972)
		(mid 138.394694 -284.052795)
		(end 138.111738 -284.128972)
		(width 0.0889)
		(layer "In13.Cu")
		(net "M_H_CPU1_SB_DQ<16>")
	)
	(arc
		(start 137.737596 -284.128972)
		(mid 137.45464 -284.052795)
		(end 137.171684 -284.128972)
		(width 0.0889)
		(layer "In13.Cu")
		(net "M_H_CPU1_SB_DQ<16>")
	)
	(arc
		(start 138.103356 -284.133798)
		(mid 137.919848 -284.179292)
		(end 137.737596 -284.128972)
		(width 0.0889)
		(layer "In13.Cu")
		(net "M_H_CPU1_SB_DQ<16>")
	)
	(arc
		(start 145.256504 -284.128972)
		(mid 144.986347 -284.05221)
		(end 144.71269 -284.115256)
		(width 0.0889)
		(layer "In13.Cu")
		(net "M_H_CPU1_SB_DQ<16>")
	)
	(arc
		(start 143.751808 -284.128972)
		(mid 143.569557 -284.179322)
		(end 143.386048 -284.133798)
		(width 0.0889)
		(layer "In13.Cu")
		(net "M_H_CPU1_SB_DQ<16>")
	)
	(arc
		(start 139.04341 -284.133798)
		(mid 138.859902 -284.179292)
		(end 138.67765 -284.128972)
		(width 0.0889)
		(layer "In13.Cu")
		(net "M_H_CPU1_SB_DQ<16>")
	)
	(arc
		(start 140.557758 -284.128972)
		(mid 140.274802 -284.052795)
		(end 139.991846 -284.128972)
		(width 0.0889)
		(layer "In13.Cu")
		(net "M_H_CPU1_SB_DQ<16>")
	)
	(arc
		(start 136.797796 -284.128972)
		(mid 136.5502 -284.053794)
		(end 136.29513 -284.097222)
		(width 0.0889)
		(layer "In13.Cu")
		(net "M_H_CPU1_SB_DQ<16>")
	)
	(arc
		(start 141.8717 -284.128972)
		(mid 141.684756 -284.179227)
		(end 141.497812 -284.128972)
		(width 0.0889)
		(layer "In13.Cu")
		(net "M_H_CPU1_SB_DQ<16>")
	)
	(segment
		(start 134.63778 -283.540454)
		(end 135.104632 -283.806392)
		(width 0.10668)
		(layer "F.Cu")
		(net "M_H_CPU1_SB_DQ<15>")
	)
	(segment
		(start 139.617704 -283.483812)
		(end 139.626086 -283.478986)
		(width 0.0889)
		(layer "In13.Cu")
		(net "M_H_CPU1_SB_DQ<15>")
	)
	(segment
		(start 162.664394 -299.531532)
		(end 162.809174 -299.386752)
		(width 0.14478)
		(layer "In13.Cu")
		(net "M_H_CPU1_SB_DQ<15>")
	)
	(segment
		(start 162.257994 -300.05909)
		(end 162.519614 -300.05909)
		(width 0.14478)
		(layer "In13.Cu")
		(net "M_H_CPU1_SB_DQ<15>")
	)
	(segment
		(start 142.803372 -283.478986)
		(end 142.811754 -283.483812)
		(width 0.0889)
		(layer "In13.Cu")
		(net "M_H_CPU1_SB_DQ<15>")
	)
	(segment
		(start 162.664394 -299.91431)
		(end 162.664394 -299.531532)
		(width 0.14478)
		(layer "In13.Cu")
		(net "M_H_CPU1_SB_DQ<15>")
	)
	(segment
		(start 156.26461 -291.21608)
		(end 156.26461 -295.144698)
		(width 0.14478)
		(layer "In13.Cu")
		(net "M_H_CPU1_SB_DQ<15>")
	)
	(segment
		(start 164.724334 -299.76064)
		(end 164.869114 -299.61586)
		(width 0.14478)
		(layer "In13.Cu")
		(net "M_H_CPU1_SB_DQ<15>")
	)
	(segment
		(start 147.644866 -284.057344)
		(end 147.84451 -284.057344)
		(width 0.0889)
		(layer "In13.Cu")
		(net "M_H_CPU1_SB_DQ<15>")
	)
	(segment
		(start 134.950708 -283.540962)
		(end 134.97306 -283.45765)
		(width 0.0889)
		(layer "In13.Cu")
		(net "M_H_CPU1_SB_DQ<15>")
	)
	(segment
		(start 143.751808 -283.483812)
		(end 143.762222 -283.489908)
		(width 0.0889)
		(layer "In13.Cu")
		(net "M_H_CPU1_SB_DQ<15>")
	)
	(segment
		(start 164.173154 -299.386752)
		(end 164.317934 -299.531532)
		(width 0.14478)
		(layer "In13.Cu")
		(net "M_H_CPU1_SB_DQ<15>")
	)
	(segment
		(start 163.070794 -299.386752)
		(end 163.215574 -299.531532)
		(width 0.14478)
		(layer "In13.Cu")
		(net "M_H_CPU1_SB_DQ<15>")
	)
	(segment
		(start 164.869114 -299.61586)
		(end 164.869114 -299.531532)
		(width 0.14478)
		(layer "In13.Cu")
		(net "M_H_CPU1_SB_DQ<15>")
	)
	(segment
		(start 143.377666 -283.483812)
		(end 143.386048 -283.478986)
		(width 0.0889)
		(layer "In13.Cu")
		(net "M_H_CPU1_SB_DQ<15>")
	)
	(segment
		(start 171.5516 -299.76064)
		(end 171.97197 -299.34027)
		(width 0.14478)
		(layer "In13.Cu")
		(net "M_H_CPU1_SB_DQ<15>")
	)
	(segment
		(start 140.557758 -283.483812)
		(end 140.56614 -283.478986)
		(width 0.0889)
		(layer "In13.Cu")
		(net "M_H_CPU1_SB_DQ<15>")
	)
	(segment
		(start 145.51787 -283.412946)
		(end 146.179286 -283.412946)
		(width 0.0889)
		(layer "In13.Cu")
		(net "M_H_CPU1_SB_DQ<15>")
	)
	(segment
		(start 162.809174 -299.386752)
		(end 163.070794 -299.386752)
		(width 0.14478)
		(layer "In13.Cu")
		(net "M_H_CPU1_SB_DQ<15>")
	)
	(segment
		(start 167.000174 -298.910502)
		(end 170.18254 -298.910502)
		(width 0.14478)
		(layer "In13.Cu")
		(net "M_H_CPU1_SB_DQ<15>")
	)
	(segment
		(start 171.032678 -299.76064)
		(end 171.5516 -299.76064)
		(width 0.14478)
		(layer "In13.Cu")
		(net "M_H_CPU1_SB_DQ<15>")
	)
	(segment
		(start 147.275042 -283.68752)
		(end 147.644866 -284.057344)
		(width 0.0889)
		(layer "In13.Cu")
		(net "M_H_CPU1_SB_DQ<15>")
	)
	(segment
		(start 161.562034 -299.504862)
		(end 161.706814 -299.360082)
		(width 0.14478)
		(layer "In13.Cu")
		(net "M_H_CPU1_SB_DQ<15>")
	)
	(segment
		(start 163.215574 -299.91431)
		(end 163.360354 -300.05909)
		(width 0.14478)
		(layer "In13.Cu")
		(net "M_H_CPU1_SB_DQ<15>")
	)
	(segment
		(start 163.911534 -299.386752)
		(end 164.173154 -299.386752)
		(width 0.14478)
		(layer "In13.Cu")
		(net "M_H_CPU1_SB_DQ<15>")
	)
	(segment
		(start 165.565074 -299.76064)
		(end 166.150036 -299.76064)
		(width 0.14478)
		(layer "In13.Cu")
		(net "M_H_CPU1_SB_DQ<15>")
	)
	(segment
		(start 163.360354 -300.05909)
		(end 163.621974 -300.05909)
		(width 0.14478)
		(layer "In13.Cu")
		(net "M_H_CPU1_SB_DQ<15>")
	)
	(segment
		(start 166.150036 -299.76064)
		(end 167.000174 -298.910502)
		(width 0.14478)
		(layer "In13.Cu")
		(net "M_H_CPU1_SB_DQ<15>")
	)
	(segment
		(start 164.869114 -299.531532)
		(end 165.013894 -299.386752)
		(width 0.14478)
		(layer "In13.Cu")
		(net "M_H_CPU1_SB_DQ<15>")
	)
	(segment
		(start 135.104632 -283.806392)
		(end 134.950708 -283.540962)
		(width 0.0889)
		(layer "In13.Cu")
		(net "M_H_CPU1_SB_DQ<15>")
	)
	(segment
		(start 165.420294 -299.531532)
		(end 165.420294 -299.61586)
		(width 0.14478)
		(layer "In13.Cu")
		(net "M_H_CPU1_SB_DQ<15>")
	)
	(segment
		(start 171.97197 -299.34027)
		(end 171.97197 -299.335444)
		(width 0.14478)
		(layer "In13.Cu")
		(net "M_H_CPU1_SB_DQ<15>")
	)
	(segment
		(start 146.179286 -283.412946)
		(end 146.45386 -283.68752)
		(width 0.0889)
		(layer "In13.Cu")
		(net "M_H_CPU1_SB_DQ<15>")
	)
	(segment
		(start 146.45386 -283.68752)
		(end 147.275042 -283.68752)
		(width 0.0889)
		(layer "In13.Cu")
		(net "M_H_CPU1_SB_DQ<15>")
	)
	(segment
		(start 164.317934 -299.531532)
		(end 164.317934 -299.61586)
		(width 0.14478)
		(layer "In13.Cu")
		(net "M_H_CPU1_SB_DQ<15>")
	)
	(segment
		(start 165.013894 -299.386752)
		(end 165.275514 -299.386752)
		(width 0.14478)
		(layer "In13.Cu")
		(net "M_H_CPU1_SB_DQ<15>")
	)
	(segment
		(start 163.621974 -300.05909)
		(end 163.766754 -299.91431)
		(width 0.14478)
		(layer "In13.Cu")
		(net "M_H_CPU1_SB_DQ<15>")
	)
	(segment
		(start 162.113214 -299.504862)
		(end 162.113214 -299.91431)
		(width 0.14478)
		(layer "In13.Cu")
		(net "M_H_CPU1_SB_DQ<15>")
	)
	(segment
		(start 163.766754 -299.91431)
		(end 163.766754 -299.531532)
		(width 0.14478)
		(layer "In13.Cu")
		(net "M_H_CPU1_SB_DQ<15>")
	)
	(segment
		(start 164.462714 -299.76064)
		(end 164.724334 -299.76064)
		(width 0.14478)
		(layer "In13.Cu")
		(net "M_H_CPU1_SB_DQ<15>")
	)
	(segment
		(start 156.26461 -295.144698)
		(end 160.880552 -299.76064)
		(width 0.14478)
		(layer "In13.Cu")
		(net "M_H_CPU1_SB_DQ<15>")
	)
	(segment
		(start 165.275514 -299.386752)
		(end 165.420294 -299.531532)
		(width 0.14478)
		(layer "In13.Cu")
		(net "M_H_CPU1_SB_DQ<15>")
	)
	(segment
		(start 161.706814 -299.360082)
		(end 161.968434 -299.360082)
		(width 0.14478)
		(layer "In13.Cu")
		(net "M_H_CPU1_SB_DQ<15>")
	)
	(segment
		(start 163.215574 -299.531532)
		(end 163.215574 -299.91431)
		(width 0.14478)
		(layer "In13.Cu")
		(net "M_H_CPU1_SB_DQ<15>")
	)
	(segment
		(start 163.766754 -299.531532)
		(end 163.911534 -299.386752)
		(width 0.14478)
		(layer "In13.Cu")
		(net "M_H_CPU1_SB_DQ<15>")
	)
	(segment
		(start 161.417254 -299.76064)
		(end 161.562034 -299.61586)
		(width 0.14478)
		(layer "In13.Cu")
		(net "M_H_CPU1_SB_DQ<15>")
	)
	(segment
		(start 161.562034 -299.61586)
		(end 161.562034 -299.504862)
		(width 0.14478)
		(layer "In13.Cu")
		(net "M_H_CPU1_SB_DQ<15>")
	)
	(segment
		(start 160.880552 -299.76064)
		(end 161.417254 -299.76064)
		(width 0.14478)
		(layer "In13.Cu")
		(net "M_H_CPU1_SB_DQ<15>")
	)
	(segment
		(start 162.519614 -300.05909)
		(end 162.664394 -299.91431)
		(width 0.14478)
		(layer "In13.Cu")
		(net "M_H_CPU1_SB_DQ<15>")
	)
	(segment
		(start 170.18254 -298.910502)
		(end 171.032678 -299.76064)
		(width 0.14478)
		(layer "In13.Cu")
		(net "M_H_CPU1_SB_DQ<15>")
	)
	(segment
		(start 162.113214 -299.91431)
		(end 162.257994 -300.05909)
		(width 0.14478)
		(layer "In13.Cu")
		(net "M_H_CPU1_SB_DQ<15>")
	)
	(segment
		(start 139.04341 -283.478986)
		(end 139.051792 -283.483812)
		(width 0.0889)
		(layer "In13.Cu")
		(net "M_H_CPU1_SB_DQ<15>")
	)
	(segment
		(start 144.684242 -283.478986)
		(end 144.692624 -283.483812)
		(width 0.0889)
		(layer "In13.Cu")
		(net "M_H_CPU1_SB_DQ<15>")
	)
	(segment
		(start 147.84451 -284.057344)
		(end 149.105874 -284.057344)
		(width 0.14478)
		(layer "In13.Cu")
		(net "M_H_CPU1_SB_DQ<15>")
	)
	(segment
		(start 138.103356 -283.478986)
		(end 138.111738 -283.483812)
		(width 0.0889)
		(layer "In13.Cu")
		(net "M_H_CPU1_SB_DQ<15>")
	)
	(segment
		(start 164.317934 -299.61586)
		(end 164.462714 -299.76064)
		(width 0.14478)
		(layer "In13.Cu")
		(net "M_H_CPU1_SB_DQ<15>")
	)
	(segment
		(start 165.420294 -299.61586)
		(end 165.565074 -299.76064)
		(width 0.14478)
		(layer "In13.Cu")
		(net "M_H_CPU1_SB_DQ<15>")
	)
	(segment
		(start 161.968434 -299.360082)
		(end 162.113214 -299.504862)
		(width 0.14478)
		(layer "In13.Cu")
		(net "M_H_CPU1_SB_DQ<15>")
	)
	(segment
		(start 135.857742 -283.483812)
		(end 135.866124 -283.478986)
		(width 0.0889)
		(layer "In13.Cu")
		(net "M_H_CPU1_SB_DQ<15>")
	)
	(segment
		(start 149.105874 -284.057344)
		(end 156.26461 -291.21608)
		(width 0.14478)
		(layer "In13.Cu")
		(net "M_H_CPU1_SB_DQ<15>")
	)
	(arc
		(start 140.56614 -283.478986)
		(mid 140.749648 -283.433492)
		(end 140.9319 -283.483812)
		(width 0.0889)
		(layer "In13.Cu")
		(net "M_H_CPU1_SB_DQ<15>")
	)
	(arc
		(start 145.25244 -283.487368)
		(mid 145.380037 -283.431903)
		(end 145.51787 -283.412946)
		(width 0.0889)
		(layer "In13.Cu")
		(net "M_H_CPU1_SB_DQ<15>")
	)
	(arc
		(start 134.97306 -283.45765)
		(mid 135.135392 -283.434832)
		(end 135.29183 -283.483812)
		(width 0.0889)
		(layer "In13.Cu")
		(net "M_H_CPU1_SB_DQ<15>")
	)
	(arc
		(start 141.497812 -283.483812)
		(mid 141.684756 -283.433557)
		(end 141.8717 -283.483812)
		(width 0.0889)
		(layer "In13.Cu")
		(net "M_H_CPU1_SB_DQ<15>")
	)
	(arc
		(start 135.866124 -283.478986)
		(mid 136.049632 -283.433492)
		(end 136.231884 -283.483812)
		(width 0.0889)
		(layer "In13.Cu")
		(net "M_H_CPU1_SB_DQ<15>")
	)
	(arc
		(start 137.171684 -283.483812)
		(mid 137.45464 -283.559989)
		(end 137.737596 -283.483812)
		(width 0.0889)
		(layer "In13.Cu")
		(net "M_H_CPU1_SB_DQ<15>")
	)
	(arc
		(start 142.437612 -283.483812)
		(mid 142.619863 -283.433462)
		(end 142.803372 -283.478986)
		(width 0.0889)
		(layer "In13.Cu")
		(net "M_H_CPU1_SB_DQ<15>")
	)
	(arc
		(start 135.29183 -283.483812)
		(mid 135.574786 -283.559989)
		(end 135.857742 -283.483812)
		(width 0.0889)
		(layer "In13.Cu")
		(net "M_H_CPU1_SB_DQ<15>")
	)
	(arc
		(start 138.111738 -283.483812)
		(mid 138.394694 -283.559989)
		(end 138.67765 -283.483812)
		(width 0.0889)
		(layer "In13.Cu")
		(net "M_H_CPU1_SB_DQ<15>")
	)
	(arc
		(start 144.317974 -283.483812)
		(mid 144.500479 -283.433335)
		(end 144.684242 -283.478986)
		(width 0.0889)
		(layer "In13.Cu")
		(net "M_H_CPU1_SB_DQ<15>")
	)
	(arc
		(start 142.811754 -283.483812)
		(mid 143.09471 -283.559989)
		(end 143.377666 -283.483812)
		(width 0.0889)
		(layer "In13.Cu")
		(net "M_H_CPU1_SB_DQ<15>")
	)
	(arc
		(start 144.692624 -283.483812)
		(mid 144.972052 -283.559978)
		(end 145.25244 -283.487368)
		(width 0.0889)
		(layer "In13.Cu")
		(net "M_H_CPU1_SB_DQ<15>")
	)
	(arc
		(start 141.8717 -283.483812)
		(mid 142.154656 -283.559989)
		(end 142.437612 -283.483812)
		(width 0.0889)
		(layer "In13.Cu")
		(net "M_H_CPU1_SB_DQ<15>")
	)
	(arc
		(start 139.626086 -283.478986)
		(mid 139.809594 -283.433492)
		(end 139.991846 -283.483812)
		(width 0.0889)
		(layer "In13.Cu")
		(net "M_H_CPU1_SB_DQ<15>")
	)
	(arc
		(start 139.991846 -283.483812)
		(mid 140.274802 -283.559989)
		(end 140.557758 -283.483812)
		(width 0.0889)
		(layer "In13.Cu")
		(net "M_H_CPU1_SB_DQ<15>")
	)
	(arc
		(start 137.737596 -283.483812)
		(mid 137.919847 -283.433462)
		(end 138.103356 -283.478986)
		(width 0.0889)
		(layer "In13.Cu")
		(net "M_H_CPU1_SB_DQ<15>")
	)
	(arc
		(start 138.67765 -283.483812)
		(mid 138.859901 -283.433462)
		(end 139.04341 -283.478986)
		(width 0.0889)
		(layer "In13.Cu")
		(net "M_H_CPU1_SB_DQ<15>")
	)
	(arc
		(start 143.762222 -283.489908)
		(mid 144.040908 -283.560128)
		(end 144.317974 -283.483812)
		(width 0.0889)
		(layer "In13.Cu")
		(net "M_H_CPU1_SB_DQ<15>")
	)
	(arc
		(start 140.9319 -283.483812)
		(mid 141.214856 -283.559989)
		(end 141.497812 -283.483812)
		(width 0.0889)
		(layer "In13.Cu")
		(net "M_H_CPU1_SB_DQ<15>")
	)
	(arc
		(start 136.797796 -283.483812)
		(mid 136.98474 -283.433557)
		(end 137.171684 -283.483812)
		(width 0.0889)
		(layer "In13.Cu")
		(net "M_H_CPU1_SB_DQ<15>")
	)
	(arc
		(start 143.386048 -283.478986)
		(mid 143.569556 -283.433492)
		(end 143.751808 -283.483812)
		(width 0.0889)
		(layer "In13.Cu")
		(net "M_H_CPU1_SB_DQ<15>")
	)
	(arc
		(start 139.051792 -283.483812)
		(mid 139.334748 -283.559989)
		(end 139.617704 -283.483812)
		(width 0.0889)
		(layer "In13.Cu")
		(net "M_H_CPU1_SB_DQ<15>")
	)
	(arc
		(start 136.231884 -283.483812)
		(mid 136.51484 -283.559989)
		(end 136.797796 -283.483812)
		(width 0.0889)
		(layer "In13.Cu")
		(net "M_H_CPU1_SB_DQ<15>")
	)
	(segment
		(start 136.047988 -282.730448)
		(end 136.51484 -282.996386)
		(width 0.10668)
		(layer "F.Cu")
		(net "M_H_CPU1_SB_DQ<14>")
	)
	(segment
		(start 136.360662 -282.730956)
		(end 136.383014 -282.647644)
		(width 0.0889)
		(layer "In13.Cu")
		(net "M_H_CPU1_SB_DQ<14>")
	)
	(segment
		(start 168.943274 -297.21048)
		(end 169.204894 -297.21048)
		(width 0.14478)
		(layer "In13.Cu")
		(net "M_H_CPU1_SB_DQ<14>")
	)
	(segment
		(start 158.935928 -296.5323)
		(end 159.121094 -296.717466)
		(width 0.14478)
		(layer "In13.Cu")
		(net "M_H_CPU1_SB_DQ<14>")
	)
	(segment
		(start 167.696134 -297.0657)
		(end 167.840914 -297.21048)
		(width 0.14478)
		(layer "In13.Cu")
		(net "M_H_CPU1_SB_DQ<14>")
	)
	(segment
		(start 169.204894 -297.21048)
		(end 169.349674 -297.0657)
		(width 0.14478)
		(layer "In13.Cu")
		(net "M_H_CPU1_SB_DQ<14>")
	)
	(segment
		(start 158.794196 -295.689528)
		(end 158.99892 -295.689528)
		(width 0.14478)
		(layer "In13.Cu")
		(net "M_H_CPU1_SB_DQ<14>")
	)
	(segment
		(start 159.715708 -297.31208)
		(end 159.900874 -297.497246)
		(width 0.14478)
		(layer "In13.Cu")
		(net "M_H_CPU1_SB_DQ<14>")
	)
	(segment
		(start 158.935928 -296.327576)
		(end 158.935928 -296.5323)
		(width 0.14478)
		(layer "In13.Cu")
		(net "M_H_CPU1_SB_DQ<14>")
	)
	(segment
		(start 149.468586 -283.148024)
		(end 157.16377 -290.843208)
		(width 0.14478)
		(layer "In13.Cu")
		(net "M_H_CPU1_SB_DQ<14>")
	)
	(segment
		(start 171.176442 -298.060618)
		(end 171.5516 -298.060618)
		(width 0.14478)
		(layer "In13.Cu")
		(net "M_H_CPU1_SB_DQ<14>")
	)
	(segment
		(start 157.561534 -295.157906)
		(end 157.766258 -295.157906)
		(width 0.14478)
		(layer "In13.Cu")
		(net "M_H_CPU1_SB_DQ<14>")
	)
	(segment
		(start 168.798494 -296.993818)
		(end 168.798494 -297.0657)
		(width 0.14478)
		(layer "In13.Cu")
		(net "M_H_CPU1_SB_DQ<14>")
	)
	(segment
		(start 170.326304 -297.21048)
		(end 171.176442 -298.060618)
		(width 0.14478)
		(layer "In13.Cu")
		(net "M_H_CPU1_SB_DQ<14>")
	)
	(segment
		(start 168.247314 -296.993818)
		(end 168.392094 -296.849038)
		(width 0.14478)
		(layer "In13.Cu")
		(net "M_H_CPU1_SB_DQ<14>")
	)
	(segment
		(start 167.696134 -296.993818)
		(end 167.696134 -297.0657)
		(width 0.14478)
		(layer "In13.Cu")
		(net "M_H_CPU1_SB_DQ<14>")
	)
	(segment
		(start 159.963866 -296.654474)
		(end 159.963866 -296.859198)
		(width 0.14478)
		(layer "In13.Cu")
		(net "M_H_CPU1_SB_DQ<14>")
	)
	(segment
		(start 158.404306 -295.299638)
		(end 158.156148 -295.547796)
		(width 0.14478)
		(layer "In13.Cu")
		(net "M_H_CPU1_SB_DQ<14>")
	)
	(segment
		(start 157.376368 -294.768016)
		(end 157.376368 -294.97274)
		(width 0.14478)
		(layer "In13.Cu")
		(net "M_H_CPU1_SB_DQ<14>")
	)
	(segment
		(start 138.20775 -282.673806)
		(end 138.216132 -282.66898)
		(width 0.0889)
		(layer "In13.Cu")
		(net "M_H_CPU1_SB_DQ<14>")
	)
	(segment
		(start 160.105598 -297.497246)
		(end 160.353756 -297.249088)
		(width 0.14478)
		(layer "In13.Cu")
		(net "M_H_CPU1_SB_DQ<14>")
	)
	(segment
		(start 160.353756 -297.249088)
		(end 160.55848 -297.249088)
		(width 0.14478)
		(layer "In13.Cu")
		(net "M_H_CPU1_SB_DQ<14>")
	)
	(segment
		(start 158.404306 -295.094914)
		(end 158.404306 -295.299638)
		(width 0.14478)
		(layer "In13.Cu")
		(net "M_H_CPU1_SB_DQ<14>")
	)
	(segment
		(start 169.756074 -296.849038)
		(end 169.900854 -296.993818)
		(width 0.14478)
		(layer "In13.Cu")
		(net "M_H_CPU1_SB_DQ<14>")
	)
	(segment
		(start 157.766258 -295.157906)
		(end 158.014416 -294.909748)
		(width 0.14478)
		(layer "In13.Cu")
		(net "M_H_CPU1_SB_DQ<14>")
	)
	(segment
		(start 159.121094 -296.717466)
		(end 159.325818 -296.717466)
		(width 0.14478)
		(layer "In13.Cu")
		(net "M_H_CPU1_SB_DQ<14>")
	)
	(segment
		(start 159.184086 -296.079418)
		(end 158.935928 -296.327576)
		(width 0.14478)
		(layer "In13.Cu")
		(net "M_H_CPU1_SB_DQ<14>")
	)
	(segment
		(start 169.900854 -296.993818)
		(end 169.900854 -297.0657)
		(width 0.14478)
		(layer "In13.Cu")
		(net "M_H_CPU1_SB_DQ<14>")
	)
	(segment
		(start 159.573976 -296.469308)
		(end 159.7787 -296.469308)
		(width 0.14478)
		(layer "In13.Cu")
		(net "M_H_CPU1_SB_DQ<14>")
	)
	(segment
		(start 147.816062 -283.148024)
		(end 149.468586 -283.148024)
		(width 0.14478)
		(layer "In13.Cu")
		(net "M_H_CPU1_SB_DQ<14>")
	)
	(segment
		(start 144.20088 -282.66263)
		(end 144.220946 -282.67406)
		(width 0.0889)
		(layer "In13.Cu")
		(net "M_H_CPU1_SB_DQ<14>")
	)
	(segment
		(start 158.21914 -294.909748)
		(end 158.404306 -295.094914)
		(width 0.14478)
		(layer "In13.Cu")
		(net "M_H_CPU1_SB_DQ<14>")
	)
	(segment
		(start 168.798494 -297.0657)
		(end 168.943274 -297.21048)
		(width 0.14478)
		(layer "In13.Cu")
		(net "M_H_CPU1_SB_DQ<14>")
	)
	(segment
		(start 168.102534 -297.21048)
		(end 168.247314 -297.0657)
		(width 0.14478)
		(layer "In13.Cu")
		(net "M_H_CPU1_SB_DQ<14>")
	)
	(segment
		(start 159.184086 -295.874694)
		(end 159.184086 -296.079418)
		(width 0.14478)
		(layer "In13.Cu")
		(net "M_H_CPU1_SB_DQ<14>")
	)
	(segment
		(start 170.045634 -297.21048)
		(end 170.326304 -297.21048)
		(width 0.14478)
		(layer "In13.Cu")
		(net "M_H_CPU1_SB_DQ<14>")
	)
	(segment
		(start 167.289734 -296.849038)
		(end 167.551354 -296.849038)
		(width 0.14478)
		(layer "In13.Cu")
		(net "M_H_CPU1_SB_DQ<14>")
	)
	(segment
		(start 158.546038 -295.937686)
		(end 158.794196 -295.689528)
		(width 0.14478)
		(layer "In13.Cu")
		(net "M_H_CPU1_SB_DQ<14>")
	)
	(segment
		(start 169.349674 -297.0657)
		(end 169.349674 -296.993818)
		(width 0.14478)
		(layer "In13.Cu")
		(net "M_H_CPU1_SB_DQ<14>")
	)
	(segment
		(start 146.195796 -282.750514)
		(end 146.593306 -283.148024)
		(width 0.0889)
		(layer "In13.Cu")
		(net "M_H_CPU1_SB_DQ<14>")
	)
	(segment
		(start 158.156148 -295.547796)
		(end 158.156148 -295.75252)
		(width 0.14478)
		(layer "In13.Cu")
		(net "M_H_CPU1_SB_DQ<14>")
	)
	(segment
		(start 167.144954 -297.0657)
		(end 167.144954 -296.993818)
		(width 0.14478)
		(layer "In13.Cu")
		(net "M_H_CPU1_SB_DQ<14>")
	)
	(segment
		(start 145.444718 -282.750514)
		(end 146.195796 -282.750514)
		(width 0.0889)
		(layer "In13.Cu")
		(net "M_H_CPU1_SB_DQ<14>")
	)
	(segment
		(start 169.349674 -296.993818)
		(end 169.494454 -296.849038)
		(width 0.14478)
		(layer "In13.Cu")
		(net "M_H_CPU1_SB_DQ<14>")
	)
	(segment
		(start 168.653714 -296.849038)
		(end 168.798494 -296.993818)
		(width 0.14478)
		(layer "In13.Cu")
		(net "M_H_CPU1_SB_DQ<14>")
	)
	(segment
		(start 158.341314 -295.937686)
		(end 158.546038 -295.937686)
		(width 0.14478)
		(layer "In13.Cu")
		(net "M_H_CPU1_SB_DQ<14>")
	)
	(segment
		(start 166.222426 -297.988228)
		(end 167.144954 -297.0657)
		(width 0.14478)
		(layer "In13.Cu")
		(net "M_H_CPU1_SB_DQ<14>")
	)
	(segment
		(start 137.267696 -282.673806)
		(end 137.276078 -282.66898)
		(width 0.0889)
		(layer "In13.Cu")
		(net "M_H_CPU1_SB_DQ<14>")
	)
	(segment
		(start 157.376368 -294.97274)
		(end 157.561534 -295.157906)
		(width 0.14478)
		(layer "In13.Cu")
		(net "M_H_CPU1_SB_DQ<14>")
	)
	(segment
		(start 167.551354 -296.849038)
		(end 167.696134 -296.993818)
		(width 0.14478)
		(layer "In13.Cu")
		(net "M_H_CPU1_SB_DQ<14>")
	)
	(segment
		(start 168.247314 -297.0657)
		(end 168.247314 -296.993818)
		(width 0.14478)
		(layer "In13.Cu")
		(net "M_H_CPU1_SB_DQ<14>")
	)
	(segment
		(start 136.693402 -282.66898)
		(end 136.701784 -282.673806)
		(width 0.0889)
		(layer "In13.Cu")
		(net "M_H_CPU1_SB_DQ<14>")
	)
	(segment
		(start 159.963866 -296.859198)
		(end 159.715708 -297.107356)
		(width 0.14478)
		(layer "In13.Cu")
		(net "M_H_CPU1_SB_DQ<14>")
	)
	(segment
		(start 159.7787 -296.469308)
		(end 159.963866 -296.654474)
		(width 0.14478)
		(layer "In13.Cu")
		(net "M_H_CPU1_SB_DQ<14>")
	)
	(segment
		(start 159.900874 -297.497246)
		(end 160.105598 -297.497246)
		(width 0.14478)
		(layer "In13.Cu")
		(net "M_H_CPU1_SB_DQ<14>")
	)
	(segment
		(start 160.55848 -297.249088)
		(end 161.29762 -297.988228)
		(width 0.14478)
		(layer "In13.Cu")
		(net "M_H_CPU1_SB_DQ<14>")
	)
	(segment
		(start 141.967712 -282.673806)
		(end 141.976094 -282.66898)
		(width 0.0889)
		(layer "In13.Cu")
		(net "M_H_CPU1_SB_DQ<14>")
	)
	(segment
		(start 168.392094 -296.849038)
		(end 168.653714 -296.849038)
		(width 0.14478)
		(layer "In13.Cu")
		(net "M_H_CPU1_SB_DQ<14>")
	)
	(segment
		(start 171.97197 -297.640248)
		(end 171.97197 -297.635422)
		(width 0.14478)
		(layer "In13.Cu")
		(net "M_H_CPU1_SB_DQ<14>")
	)
	(segment
		(start 157.16377 -290.843208)
		(end 157.16377 -293.854378)
		(width 0.14478)
		(layer "In13.Cu")
		(net "M_H_CPU1_SB_DQ<14>")
	)
	(segment
		(start 141.393418 -282.66898)
		(end 141.4018 -282.673806)
		(width 0.0889)
		(layer "In13.Cu")
		(net "M_H_CPU1_SB_DQ<14>")
	)
	(segment
		(start 159.715708 -297.107356)
		(end 159.715708 -297.31208)
		(width 0.14478)
		(layer "In13.Cu")
		(net "M_H_CPU1_SB_DQ<14>")
	)
	(segment
		(start 158.014416 -294.909748)
		(end 158.21914 -294.909748)
		(width 0.14478)
		(layer "In13.Cu")
		(net "M_H_CPU1_SB_DQ<14>")
	)
	(segment
		(start 169.494454 -296.849038)
		(end 169.756074 -296.849038)
		(width 0.14478)
		(layer "In13.Cu")
		(net "M_H_CPU1_SB_DQ<14>")
	)
	(segment
		(start 158.99892 -295.689528)
		(end 159.184086 -295.874694)
		(width 0.14478)
		(layer "In13.Cu")
		(net "M_H_CPU1_SB_DQ<14>")
	)
	(segment
		(start 140.453364 -282.66898)
		(end 140.461746 -282.673806)
		(width 0.0889)
		(layer "In13.Cu")
		(net "M_H_CPU1_SB_DQ<14>")
	)
	(segment
		(start 167.144954 -296.993818)
		(end 167.289734 -296.849038)
		(width 0.14478)
		(layer "In13.Cu")
		(net "M_H_CPU1_SB_DQ<14>")
	)
	(segment
		(start 158.156148 -295.75252)
		(end 158.341314 -295.937686)
		(width 0.14478)
		(layer "In13.Cu")
		(net "M_H_CPU1_SB_DQ<14>")
	)
	(segment
		(start 169.900854 -297.0657)
		(end 170.045634 -297.21048)
		(width 0.14478)
		(layer "In13.Cu")
		(net "M_H_CPU1_SB_DQ<14>")
	)
	(segment
		(start 157.16377 -293.854378)
		(end 157.624526 -294.315134)
		(width 0.14478)
		(layer "In13.Cu")
		(net "M_H_CPU1_SB_DQ<14>")
	)
	(segment
		(start 146.593306 -283.148024)
		(end 147.816062 -283.148024)
		(width 0.0889)
		(layer "In13.Cu")
		(net "M_H_CPU1_SB_DQ<14>")
	)
	(segment
		(start 157.624526 -294.315134)
		(end 157.624526 -294.519858)
		(width 0.14478)
		(layer "In13.Cu")
		(net "M_H_CPU1_SB_DQ<14>")
	)
	(segment
		(start 144.220946 -282.67406)
		(end 144.242536 -282.686506)
		(width 0.0889)
		(layer "In13.Cu")
		(net "M_H_CPU1_SB_DQ<14>")
	)
	(segment
		(start 161.29762 -297.988228)
		(end 166.222426 -297.988228)
		(width 0.14478)
		(layer "In13.Cu")
		(net "M_H_CPU1_SB_DQ<14>")
	)
	(segment
		(start 167.840914 -297.21048)
		(end 168.102534 -297.21048)
		(width 0.14478)
		(layer "In13.Cu")
		(net "M_H_CPU1_SB_DQ<14>")
	)
	(segment
		(start 171.5516 -298.060618)
		(end 171.97197 -297.640248)
		(width 0.14478)
		(layer "In13.Cu")
		(net "M_H_CPU1_SB_DQ<14>")
	)
	(segment
		(start 136.51484 -282.996386)
		(end 136.360662 -282.730956)
		(width 0.0889)
		(layer "In13.Cu")
		(net "M_H_CPU1_SB_DQ<14>")
	)
	(segment
		(start 157.624526 -294.519858)
		(end 157.376368 -294.768016)
		(width 0.14478)
		(layer "In13.Cu")
		(net "M_H_CPU1_SB_DQ<14>")
	)
	(segment
		(start 144.785334 -282.673806)
		(end 144.80413 -282.662884)
		(width 0.0889)
		(layer "In13.Cu")
		(net "M_H_CPU1_SB_DQ<14>")
	)
	(segment
		(start 159.325818 -296.717466)
		(end 159.573976 -296.469308)
		(width 0.14478)
		(layer "In13.Cu")
		(net "M_H_CPU1_SB_DQ<14>")
	)
	(arc
		(start 136.383014 -282.647644)
		(mid 136.540524 -282.624446)
		(end 136.693402 -282.66898)
		(width 0.0889)
		(layer "In13.Cu")
		(net "M_H_CPU1_SB_DQ<14>")
	)
	(arc
		(start 145.160492 -282.673806)
		(mid 145.297514 -282.731017)
		(end 145.444718 -282.750514)
		(width 0.0889)
		(layer "In13.Cu")
		(net "M_H_CPU1_SB_DQ<14>")
	)
	(arc
		(start 143.281654 -282.673806)
		(mid 143.56461 -282.749983)
		(end 143.847566 -282.673806)
		(width 0.0889)
		(layer "In13.Cu")
		(net "M_H_CPU1_SB_DQ<14>")
	)
	(arc
		(start 142.341854 -282.673806)
		(mid 142.62481 -282.749983)
		(end 142.907766 -282.673806)
		(width 0.0889)
		(layer "In13.Cu")
		(net "M_H_CPU1_SB_DQ<14>")
	)
	(arc
		(start 139.147804 -282.673806)
		(mid 139.334748 -282.623551)
		(end 139.521692 -282.673806)
		(width 0.0889)
		(layer "In13.Cu")
		(net "M_H_CPU1_SB_DQ<14>")
	)
	(arc
		(start 140.461746 -282.673806)
		(mid 140.744702 -282.749983)
		(end 141.027658 -282.673806)
		(width 0.0889)
		(layer "In13.Cu")
		(net "M_H_CPU1_SB_DQ<14>")
	)
	(arc
		(start 144.242536 -282.686506)
		(mid 144.515565 -282.749825)
		(end 144.785334 -282.673806)
		(width 0.0889)
		(layer "In13.Cu")
		(net "M_H_CPU1_SB_DQ<14>")
	)
	(arc
		(start 142.907766 -282.673806)
		(mid 143.09471 -282.623551)
		(end 143.281654 -282.673806)
		(width 0.0889)
		(layer "In13.Cu")
		(net "M_H_CPU1_SB_DQ<14>")
	)
	(arc
		(start 143.847566 -282.673806)
		(mid 144.022805 -282.623735)
		(end 144.20088 -282.66263)
		(width 0.0889)
		(layer "In13.Cu")
		(net "M_H_CPU1_SB_DQ<14>")
	)
	(arc
		(start 138.216132 -282.66898)
		(mid 138.39964 -282.623486)
		(end 138.581892 -282.673806)
		(width 0.0889)
		(layer "In13.Cu")
		(net "M_H_CPU1_SB_DQ<14>")
	)
	(arc
		(start 141.4018 -282.673806)
		(mid 141.684756 -282.749983)
		(end 141.967712 -282.673806)
		(width 0.0889)
		(layer "In13.Cu")
		(net "M_H_CPU1_SB_DQ<14>")
	)
	(arc
		(start 141.976094 -282.66898)
		(mid 142.159602 -282.623486)
		(end 142.341854 -282.673806)
		(width 0.0889)
		(layer "In13.Cu")
		(net "M_H_CPU1_SB_DQ<14>")
	)
	(arc
		(start 136.701784 -282.673806)
		(mid 136.98474 -282.749983)
		(end 137.267696 -282.673806)
		(width 0.0889)
		(layer "In13.Cu")
		(net "M_H_CPU1_SB_DQ<14>")
	)
	(arc
		(start 140.087604 -282.673806)
		(mid 140.269855 -282.623456)
		(end 140.453364 -282.66898)
		(width 0.0889)
		(layer "In13.Cu")
		(net "M_H_CPU1_SB_DQ<14>")
	)
	(arc
		(start 139.521692 -282.673806)
		(mid 139.804648 -282.749983)
		(end 140.087604 -282.673806)
		(width 0.0889)
		(layer "In13.Cu")
		(net "M_H_CPU1_SB_DQ<14>")
	)
	(arc
		(start 137.641838 -282.673806)
		(mid 137.924794 -282.749983)
		(end 138.20775 -282.673806)
		(width 0.0889)
		(layer "In13.Cu")
		(net "M_H_CPU1_SB_DQ<14>")
	)
	(arc
		(start 141.027658 -282.673806)
		(mid 141.209909 -282.623456)
		(end 141.393418 -282.66898)
		(width 0.0889)
		(layer "In13.Cu")
		(net "M_H_CPU1_SB_DQ<14>")
	)
	(arc
		(start 137.276078 -282.66898)
		(mid 137.459586 -282.623486)
		(end 137.641838 -282.673806)
		(width 0.0889)
		(layer "In13.Cu")
		(net "M_H_CPU1_SB_DQ<14>")
	)
	(arc
		(start 144.80413 -282.662884)
		(mid 144.983701 -282.623067)
		(end 145.160492 -282.673806)
		(width 0.0889)
		(layer "In13.Cu")
		(net "M_H_CPU1_SB_DQ<14>")
	)
	(arc
		(start 138.581892 -282.673806)
		(mid 138.864848 -282.749983)
		(end 139.147804 -282.673806)
		(width 0.0889)
		(layer "In13.Cu")
		(net "M_H_CPU1_SB_DQ<14>")
	)
	(segment
		(start 134.16788 -282.730448)
		(end 134.634732 -282.996386)
		(width 0.10668)
		(layer "F.Cu")
		(net "M_H_CPU1_SB_DQ<13>")
	)
	(segment
		(start 156.71419 -294.958262)
		(end 156.71419 -291.029644)
		(width 0.14478)
		(layer "In13.Cu")
		(net "M_H_CPU1_SB_DQ<13>")
	)
	(segment
		(start 140.461746 -283.318966)
		(end 140.453364 -283.323792)
		(width 0.0889)
		(layer "In13.Cu")
		(net "M_H_CPU1_SB_DQ<13>")
	)
	(segment
		(start 138.216132 -283.323792)
		(end 138.20775 -283.318966)
		(width 0.0889)
		(layer "In13.Cu")
		(net "M_H_CPU1_SB_DQ<13>")
	)
	(segment
		(start 146.489166 -283.407104)
		(end 146.274028 -283.191966)
		(width 0.0889)
		(layer "In13.Cu")
		(net "M_H_CPU1_SB_DQ<13>")
	)
	(segment
		(start 137.276078 -283.323792)
		(end 137.267696 -283.318966)
		(width 0.0889)
		(layer "In13.Cu")
		(net "M_H_CPU1_SB_DQ<13>")
	)
	(segment
		(start 146.274028 -283.191966)
		(end 145.620994 -283.191966)
		(width 0.0889)
		(layer "In13.Cu")
		(net "M_H_CPU1_SB_DQ<13>")
	)
	(segment
		(start 141.4018 -283.318966)
		(end 141.393418 -283.323792)
		(width 0.0889)
		(layer "In13.Cu")
		(net "M_H_CPU1_SB_DQ<13>")
	)
	(segment
		(start 136.701784 -283.318966)
		(end 136.693402 -283.323792)
		(width 0.0889)
		(layer "In13.Cu")
		(net "M_H_CPU1_SB_DQ<13>")
	)
	(segment
		(start 170.580304 -298.460922)
		(end 166.754302 -298.460922)
		(width 0.14478)
		(layer "In13.Cu")
		(net "M_H_CPU1_SB_DQ<13>")
	)
	(segment
		(start 134.788656 -283.261816)
		(end 134.634732 -282.996386)
		(width 0.0889)
		(layer "In13.Cu")
		(net "M_H_CPU1_SB_DQ<13>")
	)
	(segment
		(start 147.378166 -283.407104)
		(end 146.489166 -283.407104)
		(width 0.0889)
		(layer "In13.Cu")
		(net "M_H_CPU1_SB_DQ<13>")
	)
	(segment
		(start 141.976094 -283.323792)
		(end 141.967712 -283.318966)
		(width 0.0889)
		(layer "In13.Cu")
		(net "M_H_CPU1_SB_DQ<13>")
	)
	(segment
		(start 160.66643 -298.910502)
		(end 156.71419 -294.958262)
		(width 0.14478)
		(layer "In13.Cu")
		(net "M_H_CPU1_SB_DQ<13>")
	)
	(segment
		(start 173.202854 -298.910502)
		(end 171.665646 -298.910502)
		(width 0.14478)
		(layer "In13.Cu")
		(net "M_H_CPU1_SB_DQ<13>")
	)
	(segment
		(start 147.573746 -283.602684)
		(end 147.378166 -283.407104)
		(width 0.0889)
		(layer "In13.Cu")
		(net "M_H_CPU1_SB_DQ<13>")
	)
	(segment
		(start 143.855948 -283.323792)
		(end 143.847566 -283.318966)
		(width 0.0889)
		(layer "In13.Cu")
		(net "M_H_CPU1_SB_DQ<13>")
	)
	(segment
		(start 166.754302 -298.460922)
		(end 165.66896 -298.910502)
		(width 0.14478)
		(layer "In13.Cu")
		(net "M_H_CPU1_SB_DQ<13>")
	)
	(segment
		(start 147.895818 -283.602684)
		(end 147.573746 -283.602684)
		(width 0.0889)
		(layer "In13.Cu")
		(net "M_H_CPU1_SB_DQ<13>")
	)
	(segment
		(start 176.072038 -298.485306)
		(end 173.202854 -298.910502)
		(width 0.14478)
		(layer "In13.Cu")
		(net "M_H_CPU1_SB_DQ<13>")
	)
	(segment
		(start 149.28723 -283.602684)
		(end 147.895818 -283.602684)
		(width 0.14478)
		(layer "In13.Cu")
		(net "M_H_CPU1_SB_DQ<13>")
	)
	(segment
		(start 144.788382 -283.318966)
		(end 144.777968 -283.31287)
		(width 0.0889)
		(layer "In13.Cu")
		(net "M_H_CPU1_SB_DQ<13>")
	)
	(segment
		(start 165.66896 -298.910502)
		(end 160.66643 -298.910502)
		(width 0.14478)
		(layer "In13.Cu")
		(net "M_H_CPU1_SB_DQ<13>")
	)
	(segment
		(start 135.76173 -283.318966)
		(end 135.753348 -283.323792)
		(width 0.0889)
		(layer "In13.Cu")
		(net "M_H_CPU1_SB_DQ<13>")
	)
	(segment
		(start 171.665646 -298.910502)
		(end 170.580304 -298.460922)
		(width 0.14478)
		(layer "In13.Cu")
		(net "M_H_CPU1_SB_DQ<13>")
	)
	(segment
		(start 134.884668 -283.287216)
		(end 134.788656 -283.261816)
		(width 0.0889)
		(layer "In13.Cu")
		(net "M_H_CPU1_SB_DQ<13>")
	)
	(segment
		(start 156.71419 -291.029644)
		(end 149.28723 -283.602684)
		(width 0.14478)
		(layer "In13.Cu")
		(net "M_H_CPU1_SB_DQ<13>")
	)
	(arc
		(start 140.453364 -283.323792)
		(mid 140.269856 -283.369286)
		(end 140.087604 -283.318966)
		(width 0.0889)
		(layer "In13.Cu")
		(net "M_H_CPU1_SB_DQ<13>")
	)
	(arc
		(start 137.267696 -283.318966)
		(mid 136.98474 -283.242789)
		(end 136.701784 -283.318966)
		(width 0.0889)
		(layer "In13.Cu")
		(net "M_H_CPU1_SB_DQ<13>")
	)
	(arc
		(start 143.281654 -283.318966)
		(mid 143.09471 -283.369221)
		(end 142.907766 -283.318966)
		(width 0.0889)
		(layer "In13.Cu")
		(net "M_H_CPU1_SB_DQ<13>")
	)
	(arc
		(start 144.777968 -283.31287)
		(mid 144.499282 -283.24265)
		(end 144.222216 -283.318966)
		(width 0.0889)
		(layer "In13.Cu")
		(net "M_H_CPU1_SB_DQ<13>")
	)
	(arc
		(start 142.907766 -283.318966)
		(mid 142.62481 -283.242789)
		(end 142.341854 -283.318966)
		(width 0.0889)
		(layer "In13.Cu")
		(net "M_H_CPU1_SB_DQ<13>")
	)
	(arc
		(start 138.20775 -283.318966)
		(mid 137.924794 -283.242789)
		(end 137.641838 -283.318966)
		(width 0.0889)
		(layer "In13.Cu")
		(net "M_H_CPU1_SB_DQ<13>")
	)
	(arc
		(start 135.387588 -283.318966)
		(mid 135.139875 -283.243746)
		(end 134.884668 -283.287216)
		(width 0.0889)
		(layer "In13.Cu")
		(net "M_H_CPU1_SB_DQ<13>")
	)
	(arc
		(start 135.753348 -283.323792)
		(mid 135.56984 -283.369286)
		(end 135.387588 -283.318966)
		(width 0.0889)
		(layer "In13.Cu")
		(net "M_H_CPU1_SB_DQ<13>")
	)
	(arc
		(start 145.146014 -283.32811)
		(mid 144.966032 -283.36921)
		(end 144.788382 -283.318966)
		(width 0.0889)
		(layer "In13.Cu")
		(net "M_H_CPU1_SB_DQ<13>")
	)
	(arc
		(start 137.641838 -283.318966)
		(mid 137.459587 -283.369316)
		(end 137.276078 -283.323792)
		(width 0.0889)
		(layer "In13.Cu")
		(net "M_H_CPU1_SB_DQ<13>")
	)
	(arc
		(start 136.327642 -283.318966)
		(mid 136.044686 -283.242789)
		(end 135.76173 -283.318966)
		(width 0.0889)
		(layer "In13.Cu")
		(net "M_H_CPU1_SB_DQ<13>")
	)
	(arc
		(start 141.967712 -283.318966)
		(mid 141.684756 -283.242789)
		(end 141.4018 -283.318966)
		(width 0.0889)
		(layer "In13.Cu")
		(net "M_H_CPU1_SB_DQ<13>")
	)
	(arc
		(start 136.693402 -283.323792)
		(mid 136.509894 -283.369286)
		(end 136.327642 -283.318966)
		(width 0.0889)
		(layer "In13.Cu")
		(net "M_H_CPU1_SB_DQ<13>")
	)
	(arc
		(start 139.521692 -283.318966)
		(mid 139.334748 -283.369221)
		(end 139.147804 -283.318966)
		(width 0.0889)
		(layer "In13.Cu")
		(net "M_H_CPU1_SB_DQ<13>")
	)
	(arc
		(start 144.222216 -283.318966)
		(mid 144.039711 -283.369443)
		(end 143.855948 -283.323792)
		(width 0.0889)
		(layer "In13.Cu")
		(net "M_H_CPU1_SB_DQ<13>")
	)
	(arc
		(start 141.393418 -283.323792)
		(mid 141.20991 -283.369286)
		(end 141.027658 -283.318966)
		(width 0.0889)
		(layer "In13.Cu")
		(net "M_H_CPU1_SB_DQ<13>")
	)
	(arc
		(start 140.087604 -283.318966)
		(mid 139.804648 -283.242789)
		(end 139.521692 -283.318966)
		(width 0.0889)
		(layer "In13.Cu")
		(net "M_H_CPU1_SB_DQ<13>")
	)
	(arc
		(start 139.147804 -283.318966)
		(mid 138.864848 -283.242789)
		(end 138.581892 -283.318966)
		(width 0.0889)
		(layer "In13.Cu")
		(net "M_H_CPU1_SB_DQ<13>")
	)
	(arc
		(start 141.027658 -283.318966)
		(mid 140.744702 -283.242789)
		(end 140.461746 -283.318966)
		(width 0.0889)
		(layer "In13.Cu")
		(net "M_H_CPU1_SB_DQ<13>")
	)
	(arc
		(start 138.581892 -283.318966)
		(mid 138.399641 -283.369316)
		(end 138.216132 -283.323792)
		(width 0.0889)
		(layer "In13.Cu")
		(net "M_H_CPU1_SB_DQ<13>")
	)
	(arc
		(start 142.341854 -283.318966)
		(mid 142.159603 -283.369316)
		(end 141.976094 -283.323792)
		(width 0.0889)
		(layer "In13.Cu")
		(net "M_H_CPU1_SB_DQ<13>")
	)
	(arc
		(start 143.847566 -283.318966)
		(mid 143.56461 -283.242789)
		(end 143.281654 -283.318966)
		(width 0.0889)
		(layer "In13.Cu")
		(net "M_H_CPU1_SB_DQ<13>")
	)
	(arc
		(start 145.620994 -283.191966)
		(mid 145.37393 -283.226657)
		(end 145.146014 -283.32811)
		(width 0.0889)
		(layer "In13.Cu")
		(net "M_H_CPU1_SB_DQ<13>")
	)
	(segment
		(start 135.577834 -281.920442)
		(end 136.044686 -282.18638)
		(width 0.10668)
		(layer "F.Cu")
		(net "M_H_CPU1_SB_DQ<12>")
	)
	(segment
		(start 143.386048 -282.513786)
		(end 143.377666 -282.50896)
		(width 0.0889)
		(layer "In13.Cu")
		(net "M_H_CPU1_SB_DQ<12>")
	)
	(segment
		(start 165.5953 -297.48353)
		(end 165.31717 -297.48353)
		(width 0.14478)
		(layer "In13.Cu")
		(net "M_H_CPU1_SB_DQ<12>")
	)
	(segment
		(start 136.198864 -282.45181)
		(end 136.044686 -282.18638)
		(width 0.0889)
		(layer "In13.Cu")
		(net "M_H_CPU1_SB_DQ<12>")
	)
	(segment
		(start 161.156142 -297.21048)
		(end 157.61335 -293.667688)
		(width 0.14478)
		(layer "In13.Cu")
		(net "M_H_CPU1_SB_DQ<12>")
	)
	(segment
		(start 136.29513 -282.47721)
		(end 136.198864 -282.45181)
		(width 0.0889)
		(layer "In13.Cu")
		(net "M_H_CPU1_SB_DQ<12>")
	)
	(segment
		(start 157.61335 -293.667688)
		(end 157.61335 -290.656772)
		(width 0.14478)
		(layer "In13.Cu")
		(net "M_H_CPU1_SB_DQ<12>")
	)
	(segment
		(start 164.21481 -297.48353)
		(end 163.94176 -297.21048)
		(width 0.14478)
		(layer "In13.Cu")
		(net "M_H_CPU1_SB_DQ<12>")
	)
	(segment
		(start 144.334484 -282.51912)
		(end 144.316196 -282.508706)
		(width 0.0889)
		(layer "In13.Cu")
		(net "M_H_CPU1_SB_DQ<12>")
	)
	(segment
		(start 165.31717 -297.48353)
		(end 165.04412 -297.21048)
		(width 0.14478)
		(layer "In13.Cu")
		(net "M_H_CPU1_SB_DQ<12>")
	)
	(segment
		(start 170.790616 -296.360596)
		(end 167.092884 -296.360596)
		(width 0.14478)
		(layer "In13.Cu")
		(net "M_H_CPU1_SB_DQ<12>")
	)
	(segment
		(start 149.649942 -282.693364)
		(end 147.895818 -282.693364)
		(width 0.14478)
		(layer "In13.Cu")
		(net "M_H_CPU1_SB_DQ<12>")
	)
	(segment
		(start 165.04412 -297.21048)
		(end 164.76599 -297.21048)
		(width 0.14478)
		(layer "In13.Cu")
		(net "M_H_CPU1_SB_DQ<12>")
	)
	(segment
		(start 142.811754 -282.50896)
		(end 142.803372 -282.513786)
		(width 0.0889)
		(layer "In13.Cu")
		(net "M_H_CPU1_SB_DQ<12>")
	)
	(segment
		(start 161.73704 -297.21048)
		(end 161.156142 -297.21048)
		(width 0.14478)
		(layer "In13.Cu")
		(net "M_H_CPU1_SB_DQ<12>")
	)
	(segment
		(start 147.895818 -282.693364)
		(end 147.617434 -282.693364)
		(width 0.0889)
		(layer "In13.Cu")
		(net "M_H_CPU1_SB_DQ<12>")
	)
	(segment
		(start 164.76599 -297.21048)
		(end 164.49294 -297.48353)
		(width 0.14478)
		(layer "In13.Cu")
		(net "M_H_CPU1_SB_DQ<12>")
	)
	(segment
		(start 164.49294 -297.48353)
		(end 164.21481 -297.48353)
		(width 0.14478)
		(layer "In13.Cu")
		(net "M_H_CPU1_SB_DQ<12>")
	)
	(segment
		(start 144.71269 -282.495244)
		(end 144.689322 -282.50896)
		(width 0.0889)
		(layer "In13.Cu")
		(net "M_H_CPU1_SB_DQ<12>")
	)
	(segment
		(start 146.506438 -282.350464)
		(end 146.296888 -282.560014)
		(width 0.0889)
		(layer "In13.Cu")
		(net "M_H_CPU1_SB_DQ<12>")
	)
	(segment
		(start 138.111738 -282.50896)
		(end 138.103356 -282.513786)
		(width 0.0889)
		(layer "In13.Cu")
		(net "M_H_CPU1_SB_DQ<12>")
	)
	(segment
		(start 147.274534 -282.350464)
		(end 146.506438 -282.350464)
		(width 0.0889)
		(layer "In13.Cu")
		(net "M_H_CPU1_SB_DQ<12>")
	)
	(segment
		(start 176.072038 -296.785284)
		(end 173.885352 -297.220132)
		(width 0.14478)
		(layer "In13.Cu")
		(net "M_H_CPU1_SB_DQ<12>")
	)
	(segment
		(start 146.296888 -282.560014)
		(end 145.444972 -282.560014)
		(width 0.0889)
		(layer "In13.Cu")
		(net "M_H_CPU1_SB_DQ<12>")
	)
	(segment
		(start 163.39058 -297.48353)
		(end 163.11245 -297.48353)
		(width 0.14478)
		(layer "In13.Cu")
		(net "M_H_CPU1_SB_DQ<12>")
	)
	(segment
		(start 144.316196 -282.508706)
		(end 144.294606 -282.49626)
		(width 0.0889)
		(layer "In13.Cu")
		(net "M_H_CPU1_SB_DQ<12>")
	)
	(segment
		(start 139.051792 -282.50896)
		(end 139.04341 -282.513786)
		(width 0.0889)
		(layer "In13.Cu")
		(net "M_H_CPU1_SB_DQ<12>")
	)
	(segment
		(start 139.626086 -282.513786)
		(end 139.617704 -282.50896)
		(width 0.0889)
		(layer "In13.Cu")
		(net "M_H_CPU1_SB_DQ<12>")
	)
	(segment
		(start 173.885352 -297.220132)
		(end 172.865796 -297.220132)
		(width 0.14478)
		(layer "In13.Cu")
		(net "M_H_CPU1_SB_DQ<12>")
	)
	(segment
		(start 140.56614 -282.513786)
		(end 140.557758 -282.50896)
		(width 0.0889)
		(layer "In13.Cu")
		(net "M_H_CPU1_SB_DQ<12>")
	)
	(segment
		(start 162.01009 -297.48353)
		(end 161.73704 -297.21048)
		(width 0.14478)
		(layer "In13.Cu")
		(net "M_H_CPU1_SB_DQ<12>")
	)
	(segment
		(start 145.444972 -282.560014)
		(end 145.444718 -282.55976)
		(width 0.0889)
		(layer "In13.Cu")
		(net "M_H_CPU1_SB_DQ<12>")
	)
	(segment
		(start 163.11245 -297.48353)
		(end 162.8394 -297.21048)
		(width 0.14478)
		(layer "In13.Cu")
		(net "M_H_CPU1_SB_DQ<12>")
	)
	(segment
		(start 166.243 -297.21048)
		(end 165.86835 -297.21048)
		(width 0.14478)
		(layer "In13.Cu")
		(net "M_H_CPU1_SB_DQ<12>")
	)
	(segment
		(start 165.86835 -297.21048)
		(end 165.5953 -297.48353)
		(width 0.14478)
		(layer "In13.Cu")
		(net "M_H_CPU1_SB_DQ<12>")
	)
	(segment
		(start 163.66363 -297.21048)
		(end 163.39058 -297.48353)
		(width 0.14478)
		(layer "In13.Cu")
		(net "M_H_CPU1_SB_DQ<12>")
	)
	(segment
		(start 167.092884 -296.360596)
		(end 166.243 -297.21048)
		(width 0.14478)
		(layer "In13.Cu")
		(net "M_H_CPU1_SB_DQ<12>")
	)
	(segment
		(start 147.617434 -282.693364)
		(end 147.274534 -282.350464)
		(width 0.0889)
		(layer "In13.Cu")
		(net "M_H_CPU1_SB_DQ<12>")
	)
	(segment
		(start 172.865796 -297.220132)
		(end 170.790616 -296.360596)
		(width 0.14478)
		(layer "In13.Cu")
		(net "M_H_CPU1_SB_DQ<12>")
	)
	(segment
		(start 162.28822 -297.48353)
		(end 162.01009 -297.48353)
		(width 0.14478)
		(layer "In13.Cu")
		(net "M_H_CPU1_SB_DQ<12>")
	)
	(segment
		(start 162.8394 -297.21048)
		(end 162.56127 -297.21048)
		(width 0.14478)
		(layer "In13.Cu")
		(net "M_H_CPU1_SB_DQ<12>")
	)
	(segment
		(start 163.94176 -297.21048)
		(end 163.66363 -297.21048)
		(width 0.14478)
		(layer "In13.Cu")
		(net "M_H_CPU1_SB_DQ<12>")
	)
	(segment
		(start 162.56127 -297.21048)
		(end 162.28822 -297.48353)
		(width 0.14478)
		(layer "In13.Cu")
		(net "M_H_CPU1_SB_DQ<12>")
	)
	(segment
		(start 157.61335 -290.656772)
		(end 149.649942 -282.693364)
		(width 0.14478)
		(layer "In13.Cu")
		(net "M_H_CPU1_SB_DQ<12>")
	)
	(arc
		(start 137.737596 -282.50896)
		(mid 137.45464 -282.432783)
		(end 137.171684 -282.50896)
		(width 0.0889)
		(layer "In13.Cu")
		(net "M_H_CPU1_SB_DQ<12>")
	)
	(arc
		(start 142.437612 -282.50896)
		(mid 142.154656 -282.432783)
		(end 141.8717 -282.50896)
		(width 0.0889)
		(layer "In13.Cu")
		(net "M_H_CPU1_SB_DQ<12>")
	)
	(arc
		(start 145.256504 -282.50896)
		(mid 144.986347 -282.432198)
		(end 144.71269 -282.495244)
		(width 0.0889)
		(layer "In13.Cu")
		(net "M_H_CPU1_SB_DQ<12>")
	)
	(arc
		(start 136.797796 -282.50896)
		(mid 136.5502 -282.433782)
		(end 136.29513 -282.47721)
		(width 0.0889)
		(layer "In13.Cu")
		(net "M_H_CPU1_SB_DQ<12>")
	)
	(arc
		(start 139.991846 -282.50896)
		(mid 139.809595 -282.55931)
		(end 139.626086 -282.513786)
		(width 0.0889)
		(layer "In13.Cu")
		(net "M_H_CPU1_SB_DQ<12>")
	)
	(arc
		(start 143.751808 -282.50896)
		(mid 143.569557 -282.55931)
		(end 143.386048 -282.513786)
		(width 0.0889)
		(layer "In13.Cu")
		(net "M_H_CPU1_SB_DQ<12>")
	)
	(arc
		(start 137.171684 -282.50896)
		(mid 136.98474 -282.559215)
		(end 136.797796 -282.50896)
		(width 0.0889)
		(layer "In13.Cu")
		(net "M_H_CPU1_SB_DQ<12>")
	)
	(arc
		(start 142.803372 -282.513786)
		(mid 142.619864 -282.55928)
		(end 142.437612 -282.50896)
		(width 0.0889)
		(layer "In13.Cu")
		(net "M_H_CPU1_SB_DQ<12>")
	)
	(arc
		(start 140.557758 -282.50896)
		(mid 140.274802 -282.432783)
		(end 139.991846 -282.50896)
		(width 0.0889)
		(layer "In13.Cu")
		(net "M_H_CPU1_SB_DQ<12>")
	)
	(arc
		(start 141.497812 -282.50896)
		(mid 141.214856 -282.432783)
		(end 140.9319 -282.50896)
		(width 0.0889)
		(layer "In13.Cu")
		(net "M_H_CPU1_SB_DQ<12>")
	)
	(arc
		(start 144.689322 -282.50896)
		(mid 144.513202 -282.558938)
		(end 144.334484 -282.51912)
		(width 0.0889)
		(layer "In13.Cu")
		(net "M_H_CPU1_SB_DQ<12>")
	)
	(arc
		(start 145.444718 -282.55976)
		(mid 145.34723 -282.546877)
		(end 145.256504 -282.50896)
		(width 0.0889)
		(layer "In13.Cu")
		(net "M_H_CPU1_SB_DQ<12>")
	)
	(arc
		(start 138.67765 -282.50896)
		(mid 138.394694 -282.432783)
		(end 138.111738 -282.50896)
		(width 0.0889)
		(layer "In13.Cu")
		(net "M_H_CPU1_SB_DQ<12>")
	)
	(arc
		(start 140.9319 -282.50896)
		(mid 140.749649 -282.55931)
		(end 140.56614 -282.513786)
		(width 0.0889)
		(layer "In13.Cu")
		(net "M_H_CPU1_SB_DQ<12>")
	)
	(arc
		(start 139.04341 -282.513786)
		(mid 138.859902 -282.55928)
		(end 138.67765 -282.50896)
		(width 0.0889)
		(layer "In13.Cu")
		(net "M_H_CPU1_SB_DQ<12>")
	)
	(arc
		(start 144.294606 -282.49626)
		(mid 144.021577 -282.432941)
		(end 143.751808 -282.50896)
		(width 0.0889)
		(layer "In13.Cu")
		(net "M_H_CPU1_SB_DQ<12>")
	)
	(arc
		(start 138.103356 -282.513786)
		(mid 137.919848 -282.55928)
		(end 137.737596 -282.50896)
		(width 0.0889)
		(layer "In13.Cu")
		(net "M_H_CPU1_SB_DQ<12>")
	)
	(arc
		(start 139.617704 -282.50896)
		(mid 139.334748 -282.432783)
		(end 139.051792 -282.50896)
		(width 0.0889)
		(layer "In13.Cu")
		(net "M_H_CPU1_SB_DQ<12>")
	)
	(arc
		(start 141.8717 -282.50896)
		(mid 141.684756 -282.559215)
		(end 141.497812 -282.50896)
		(width 0.0889)
		(layer "In13.Cu")
		(net "M_H_CPU1_SB_DQ<12>")
	)
	(arc
		(start 143.377666 -282.50896)
		(mid 143.09471 -282.432783)
		(end 142.811754 -282.50896)
		(width 0.0889)
		(layer "In13.Cu")
		(net "M_H_CPU1_SB_DQ<12>")
	)
	(segment
		(start 134.63778 -280.30043)
		(end 135.104632 -280.566368)
		(width 0.10668)
		(layer "F.Cu")
		(net "M_H_CPU1_SB_DQ<11>")
	)
	(segment
		(start 164.33165 -293.727378)
		(end 164.18687 -293.872158)
		(width 0.14478)
		(layer "In13.Cu")
		(net "M_H_CPU1_SB_DQ<11>")
	)
	(segment
		(start 134.97306 -280.217626)
		(end 134.950708 -280.300938)
		(width 0.0889)
		(layer "In13.Cu")
		(net "M_H_CPU1_SB_DQ<11>")
	)
	(segment
		(start 166.930578 -292.960298)
		(end 166.480998 -293.409878)
		(width 0.14478)
		(layer "In13.Cu")
		(net "M_H_CPU1_SB_DQ<11>")
	)
	(segment
		(start 167.91432 -293.2049)
		(end 167.91432 -292.715696)
		(width 0.14478)
		(layer "In13.Cu")
		(net "M_H_CPU1_SB_DQ<11>")
	)
	(segment
		(start 164.18687 -293.872158)
		(end 163.92525 -293.872158)
		(width 0.14478)
		(layer "In13.Cu")
		(net "M_H_CPU1_SB_DQ<11>")
	)
	(segment
		(start 166.082726 -293.265098)
		(end 166.082726 -293.154354)
		(width 0.14478)
		(layer "In13.Cu")
		(net "M_H_CPU1_SB_DQ<11>")
	)
	(segment
		(start 166.082726 -293.154354)
		(end 165.937946 -293.009574)
		(width 0.14478)
		(layer "In13.Cu")
		(net "M_H_CPU1_SB_DQ<11>")
	)
	(segment
		(start 169.01668 -292.704774)
		(end 168.8719 -292.559994)
		(width 0.14478)
		(layer "In13.Cu")
		(net "M_H_CPU1_SB_DQ<11>")
	)
	(segment
		(start 169.42308 -293.34968)
		(end 169.16146 -293.34968)
		(width 0.14478)
		(layer "In13.Cu")
		(net "M_H_CPU1_SB_DQ<11>")
	)
	(segment
		(start 144.317466 -280.243788)
		(end 144.307052 -280.249884)
		(width 0.0889)
		(layer "In13.Cu")
		(net "M_H_CPU1_SB_DQ<11>")
	)
	(segment
		(start 162.026092 -293.721028)
		(end 162.026092 -293.516304)
		(width 0.14478)
		(layer "In13.Cu")
		(net "M_H_CPU1_SB_DQ<11>")
	)
	(segment
		(start 164.47643 -293.409878)
		(end 164.33165 -293.554658)
		(width 0.14478)
		(layer "In13.Cu")
		(net "M_H_CPU1_SB_DQ<11>")
	)
	(segment
		(start 169.56786 -293.2049)
		(end 169.42308 -293.34968)
		(width 0.14478)
		(layer "In13.Cu")
		(net "M_H_CPU1_SB_DQ<11>")
	)
	(segment
		(start 162.531552 -293.010844)
		(end 162.531806 -292.806628)
		(width 0.14478)
		(layer "In13.Cu")
		(net "M_H_CPU1_SB_DQ<11>")
	)
	(segment
		(start 166.480998 -293.409878)
		(end 166.227506 -293.409878)
		(width 0.14478)
		(layer "In13.Cu")
		(net "M_H_CPU1_SB_DQ<11>")
	)
	(segment
		(start 140.56614 -280.238962)
		(end 140.557758 -280.243788)
		(width 0.0889)
		(layer "In13.Cu")
		(net "M_H_CPU1_SB_DQ<11>")
	)
	(segment
		(start 144.701768 -280.249884)
		(end 144.691354 -280.243788)
		(width 0.0889)
		(layer "In13.Cu")
		(net "M_H_CPU1_SB_DQ<11>")
	)
	(segment
		(start 165.937946 -293.009574)
		(end 165.676326 -293.009574)
		(width 0.14478)
		(layer "In13.Cu")
		(net "M_H_CPU1_SB_DQ<11>")
	)
	(segment
		(start 163.78047 -293.727378)
		(end 163.78047 -293.554658)
		(width 0.14478)
		(layer "In13.Cu")
		(net "M_H_CPU1_SB_DQ<11>")
	)
	(segment
		(start 171.97197 -293.38524)
		(end 171.97197 -293.65575)
		(width 0.14478)
		(layer "In13.Cu")
		(net "M_H_CPU1_SB_DQ<11>")
	)
	(segment
		(start 170.774868 -293.80053)
		(end 169.934636 -292.960298)
		(width 0.14478)
		(layer "In13.Cu")
		(net "M_H_CPU1_SB_DQ<11>")
	)
	(segment
		(start 167.76954 -292.570916)
		(end 167.50792 -292.570916)
		(width 0.14478)
		(layer "In13.Cu")
		(net "M_H_CPU1_SB_DQ<11>")
	)
	(segment
		(start 167.36314 -292.815518)
		(end 167.21836 -292.960298)
		(width 0.14478)
		(layer "In13.Cu")
		(net "M_H_CPU1_SB_DQ<11>")
	)
	(segment
		(start 168.32072 -293.34968)
		(end 168.0591 -293.34968)
		(width 0.14478)
		(layer "In13.Cu")
		(net "M_H_CPU1_SB_DQ<11>")
	)
	(segment
		(start 147.816062 -280.200354)
		(end 147.808696 -280.192988)
		(width 0.0889)
		(layer "In13.Cu")
		(net "M_H_CPU1_SB_DQ<11>")
	)
	(segment
		(start 164.980366 -293.745412)
		(end 164.980366 -293.554658)
		(width 0.14478)
		(layer "In13.Cu")
		(net "M_H_CPU1_SB_DQ<11>")
	)
	(segment
		(start 164.835586 -293.409878)
		(end 164.47643 -293.409878)
		(width 0.14478)
		(layer "In13.Cu")
		(net "M_H_CPU1_SB_DQ<11>")
	)
	(segment
		(start 168.61028 -292.559994)
		(end 168.4655 -292.704774)
		(width 0.14478)
		(layer "In13.Cu")
		(net "M_H_CPU1_SB_DQ<11>")
	)
	(segment
		(start 166.227506 -293.409878)
		(end 166.082726 -293.265098)
		(width 0.14478)
		(layer "In13.Cu")
		(net "M_H_CPU1_SB_DQ<11>")
	)
	(segment
		(start 162.531806 -292.806628)
		(end 159.90189 -290.176712)
		(width 0.14478)
		(layer "In13.Cu")
		(net "M_H_CPU1_SB_DQ<11>")
	)
	(segment
		(start 163.63569 -293.409878)
		(end 163.135056 -293.409878)
		(width 0.14478)
		(layer "In13.Cu")
		(net "M_H_CPU1_SB_DQ<11>")
	)
	(segment
		(start 168.4655 -293.2049)
		(end 168.32072 -293.34968)
		(width 0.14478)
		(layer "In13.Cu")
		(net "M_H_CPU1_SB_DQ<11>")
	)
	(segment
		(start 167.36314 -292.715696)
		(end 167.36314 -292.815518)
		(width 0.14478)
		(layer "In13.Cu")
		(net "M_H_CPU1_SB_DQ<11>")
	)
	(segment
		(start 164.33165 -293.554658)
		(end 164.33165 -293.727378)
		(width 0.14478)
		(layer "In13.Cu")
		(net "M_H_CPU1_SB_DQ<11>")
	)
	(segment
		(start 139.051792 -280.243788)
		(end 139.04341 -280.238962)
		(width 0.0889)
		(layer "In13.Cu")
		(net "M_H_CPU1_SB_DQ<11>")
	)
	(segment
		(start 165.676326 -293.009574)
		(end 165.531546 -293.154354)
		(width 0.14478)
		(layer "In13.Cu")
		(net "M_H_CPU1_SB_DQ<11>")
	)
	(segment
		(start 167.21836 -292.960298)
		(end 166.930578 -292.960298)
		(width 0.14478)
		(layer "In13.Cu")
		(net "M_H_CPU1_SB_DQ<11>")
	)
	(segment
		(start 165.386766 -293.890192)
		(end 165.125146 -293.890192)
		(width 0.14478)
		(layer "In13.Cu")
		(net "M_H_CPU1_SB_DQ<11>")
	)
	(segment
		(start 168.8719 -292.559994)
		(end 168.61028 -292.559994)
		(width 0.14478)
		(layer "In13.Cu")
		(net "M_H_CPU1_SB_DQ<11>")
	)
	(segment
		(start 142.811754 -280.243788)
		(end 142.803372 -280.238962)
		(width 0.0889)
		(layer "In13.Cu")
		(net "M_H_CPU1_SB_DQ<11>")
	)
	(segment
		(start 138.111738 -280.243788)
		(end 138.103356 -280.238962)
		(width 0.0889)
		(layer "In13.Cu")
		(net "M_H_CPU1_SB_DQ<11>")
	)
	(segment
		(start 164.980366 -293.554658)
		(end 164.835586 -293.409878)
		(width 0.14478)
		(layer "In13.Cu")
		(net "M_H_CPU1_SB_DQ<11>")
	)
	(segment
		(start 139.626086 -280.238962)
		(end 139.617704 -280.243788)
		(width 0.0889)
		(layer "In13.Cu")
		(net "M_H_CPU1_SB_DQ<11>")
	)
	(segment
		(start 143.386048 -280.238962)
		(end 143.377666 -280.243788)
		(width 0.0889)
		(layer "In13.Cu")
		(net "M_H_CPU1_SB_DQ<11>")
	)
	(segment
		(start 169.56786 -293.105078)
		(end 169.56786 -293.2049)
		(width 0.14478)
		(layer "In13.Cu")
		(net "M_H_CPU1_SB_DQ<11>")
	)
	(segment
		(start 163.126166 -293.400988)
		(end 162.921442 -293.400988)
		(width 0.14478)
		(layer "In13.Cu")
		(net "M_H_CPU1_SB_DQ<11>")
	)
	(segment
		(start 169.934636 -292.960298)
		(end 169.71264 -292.960298)
		(width 0.14478)
		(layer "In13.Cu")
		(net "M_H_CPU1_SB_DQ<11>")
	)
	(segment
		(start 163.78047 -293.554658)
		(end 163.63569 -293.409878)
		(width 0.14478)
		(layer "In13.Cu")
		(net "M_H_CPU1_SB_DQ<11>")
	)
	(segment
		(start 168.4655 -292.704774)
		(end 168.4655 -293.2049)
		(width 0.14478)
		(layer "In13.Cu")
		(net "M_H_CPU1_SB_DQ<11>")
	)
	(segment
		(start 134.950708 -280.300938)
		(end 135.104632 -280.566368)
		(width 0.0889)
		(layer "In13.Cu")
		(net "M_H_CPU1_SB_DQ<11>")
	)
	(segment
		(start 165.531546 -293.154354)
		(end 165.531546 -293.745412)
		(width 0.14478)
		(layer "In13.Cu")
		(net "M_H_CPU1_SB_DQ<11>")
	)
	(segment
		(start 169.01668 -293.2049)
		(end 169.01668 -292.704774)
		(width 0.14478)
		(layer "In13.Cu")
		(net "M_H_CPU1_SB_DQ<11>")
	)
	(segment
		(start 165.125146 -293.890192)
		(end 164.980366 -293.745412)
		(width 0.14478)
		(layer "In13.Cu")
		(net "M_H_CPU1_SB_DQ<11>")
	)
	(segment
		(start 162.026092 -293.516304)
		(end 162.531552 -293.010844)
		(width 0.14478)
		(layer "In13.Cu")
		(net "M_H_CPU1_SB_DQ<11>")
	)
	(segment
		(start 162.921442 -293.400988)
		(end 162.415982 -293.906448)
		(width 0.14478)
		(layer "In13.Cu")
		(net "M_H_CPU1_SB_DQ<11>")
	)
	(segment
		(start 147.808696 -280.192988)
		(end 145.30832 -280.192988)
		(width 0.0889)
		(layer "In13.Cu")
		(net "M_H_CPU1_SB_DQ<11>")
	)
	(segment
		(start 171.82719 -293.80053)
		(end 170.774868 -293.80053)
		(width 0.14478)
		(layer "In13.Cu")
		(net "M_H_CPU1_SB_DQ<11>")
	)
	(segment
		(start 150.394416 -280.200354)
		(end 147.816062 -280.200354)
		(width 0.14478)
		(layer "In13.Cu")
		(net "M_H_CPU1_SB_DQ<11>")
	)
	(segment
		(start 162.415982 -293.906448)
		(end 162.211258 -293.906194)
		(width 0.14478)
		(layer "In13.Cu")
		(net "M_H_CPU1_SB_DQ<11>")
	)
	(segment
		(start 169.71264 -292.960298)
		(end 169.56786 -293.105078)
		(width 0.14478)
		(layer "In13.Cu")
		(net "M_H_CPU1_SB_DQ<11>")
	)
	(segment
		(start 162.211258 -293.906194)
		(end 162.026092 -293.721028)
		(width 0.14478)
		(layer "In13.Cu")
		(net "M_H_CPU1_SB_DQ<11>")
	)
	(segment
		(start 135.866124 -280.238962)
		(end 135.857742 -280.243788)
		(width 0.0889)
		(layer "In13.Cu")
		(net "M_H_CPU1_SB_DQ<11>")
	)
	(segment
		(start 167.91432 -292.715696)
		(end 167.76954 -292.570916)
		(width 0.14478)
		(layer "In13.Cu")
		(net "M_H_CPU1_SB_DQ<11>")
	)
	(segment
		(start 159.90189 -289.707828)
		(end 150.394416 -280.200354)
		(width 0.14478)
		(layer "In13.Cu")
		(net "M_H_CPU1_SB_DQ<11>")
	)
	(segment
		(start 159.90189 -290.176712)
		(end 159.90189 -289.707828)
		(width 0.14478)
		(layer "In13.Cu")
		(net "M_H_CPU1_SB_DQ<11>")
	)
	(segment
		(start 163.135056 -293.409878)
		(end 163.126166 -293.400988)
		(width 0.14478)
		(layer "In13.Cu")
		(net "M_H_CPU1_SB_DQ<11>")
	)
	(segment
		(start 167.50792 -292.570916)
		(end 167.36314 -292.715696)
		(width 0.14478)
		(layer "In13.Cu")
		(net "M_H_CPU1_SB_DQ<11>")
	)
	(segment
		(start 171.97197 -293.65575)
		(end 171.82719 -293.80053)
		(width 0.14478)
		(layer "In13.Cu")
		(net "M_H_CPU1_SB_DQ<11>")
	)
	(segment
		(start 145.30832 -280.192988)
		(end 145.25752 -280.243788)
		(width 0.0889)
		(layer "In13.Cu")
		(net "M_H_CPU1_SB_DQ<11>")
	)
	(segment
		(start 165.531546 -293.745412)
		(end 165.386766 -293.890192)
		(width 0.14478)
		(layer "In13.Cu")
		(net "M_H_CPU1_SB_DQ<11>")
	)
	(segment
		(start 163.92525 -293.872158)
		(end 163.78047 -293.727378)
		(width 0.14478)
		(layer "In13.Cu")
		(net "M_H_CPU1_SB_DQ<11>")
	)
	(segment
		(start 169.16146 -293.34968)
		(end 169.01668 -293.2049)
		(width 0.14478)
		(layer "In13.Cu")
		(net "M_H_CPU1_SB_DQ<11>")
	)
	(segment
		(start 168.0591 -293.34968)
		(end 167.91432 -293.2049)
		(width 0.14478)
		(layer "In13.Cu")
		(net "M_H_CPU1_SB_DQ<11>")
	)
	(arc
		(start 139.04341 -280.238962)
		(mid 138.859902 -280.193468)
		(end 138.67765 -280.243788)
		(width 0.0889)
		(layer "In13.Cu")
		(net "M_H_CPU1_SB_DQ<11>")
	)
	(arc
		(start 138.67765 -280.243788)
		(mid 138.394694 -280.319965)
		(end 138.111738 -280.243788)
		(width 0.0889)
		(layer "In13.Cu")
		(net "M_H_CPU1_SB_DQ<11>")
	)
	(arc
		(start 135.29183 -280.243788)
		(mid 135.135392 -280.194817)
		(end 134.97306 -280.217626)
		(width 0.0889)
		(layer "In13.Cu")
		(net "M_H_CPU1_SB_DQ<11>")
	)
	(arc
		(start 141.497812 -280.243788)
		(mid 141.214856 -280.319965)
		(end 140.9319 -280.243788)
		(width 0.0889)
		(layer "In13.Cu")
		(net "M_H_CPU1_SB_DQ<11>")
	)
	(arc
		(start 142.437612 -280.243788)
		(mid 142.154656 -280.319965)
		(end 141.8717 -280.243788)
		(width 0.0889)
		(layer "In13.Cu")
		(net "M_H_CPU1_SB_DQ<11>")
	)
	(arc
		(start 145.25752 -280.243788)
		(mid 144.980453 -280.320059)
		(end 144.701768 -280.249884)
		(width 0.0889)
		(layer "In13.Cu")
		(net "M_H_CPU1_SB_DQ<11>")
	)
	(arc
		(start 137.171684 -280.243788)
		(mid 136.98474 -280.193533)
		(end 136.797796 -280.243788)
		(width 0.0889)
		(layer "In13.Cu")
		(net "M_H_CPU1_SB_DQ<11>")
	)
	(arc
		(start 143.377666 -280.243788)
		(mid 143.09471 -280.319965)
		(end 142.811754 -280.243788)
		(width 0.0889)
		(layer "In13.Cu")
		(net "M_H_CPU1_SB_DQ<11>")
	)
	(arc
		(start 137.737596 -280.243788)
		(mid 137.45464 -280.319965)
		(end 137.171684 -280.243788)
		(width 0.0889)
		(layer "In13.Cu")
		(net "M_H_CPU1_SB_DQ<11>")
	)
	(arc
		(start 140.557758 -280.243788)
		(mid 140.274802 -280.319965)
		(end 139.991846 -280.243788)
		(width 0.0889)
		(layer "In13.Cu")
		(net "M_H_CPU1_SB_DQ<11>")
	)
	(arc
		(start 139.991846 -280.243788)
		(mid 139.809595 -280.193438)
		(end 139.626086 -280.238962)
		(width 0.0889)
		(layer "In13.Cu")
		(net "M_H_CPU1_SB_DQ<11>")
	)
	(arc
		(start 144.307052 -280.249884)
		(mid 144.02862 -280.319982)
		(end 143.751808 -280.243788)
		(width 0.0889)
		(layer "In13.Cu")
		(net "M_H_CPU1_SB_DQ<11>")
	)
	(arc
		(start 144.691354 -280.243788)
		(mid 144.50441 -280.193533)
		(end 144.317466 -280.243788)
		(width 0.0889)
		(layer "In13.Cu")
		(net "M_H_CPU1_SB_DQ<11>")
	)
	(arc
		(start 143.751808 -280.243788)
		(mid 143.569557 -280.193438)
		(end 143.386048 -280.238962)
		(width 0.0889)
		(layer "In13.Cu")
		(net "M_H_CPU1_SB_DQ<11>")
	)
	(arc
		(start 138.103356 -280.238962)
		(mid 137.919848 -280.193468)
		(end 137.737596 -280.243788)
		(width 0.0889)
		(layer "In13.Cu")
		(net "M_H_CPU1_SB_DQ<11>")
	)
	(arc
		(start 136.231884 -280.243788)
		(mid 136.049633 -280.193438)
		(end 135.866124 -280.238962)
		(width 0.0889)
		(layer "In13.Cu")
		(net "M_H_CPU1_SB_DQ<11>")
	)
	(arc
		(start 136.797796 -280.243788)
		(mid 136.51484 -280.319965)
		(end 136.231884 -280.243788)
		(width 0.0889)
		(layer "In13.Cu")
		(net "M_H_CPU1_SB_DQ<11>")
	)
	(arc
		(start 141.8717 -280.243788)
		(mid 141.684756 -280.193533)
		(end 141.497812 -280.243788)
		(width 0.0889)
		(layer "In13.Cu")
		(net "M_H_CPU1_SB_DQ<11>")
	)
	(arc
		(start 139.617704 -280.243788)
		(mid 139.334748 -280.319965)
		(end 139.051792 -280.243788)
		(width 0.0889)
		(layer "In13.Cu")
		(net "M_H_CPU1_SB_DQ<11>")
	)
	(arc
		(start 135.857742 -280.243788)
		(mid 135.574786 -280.319965)
		(end 135.29183 -280.243788)
		(width 0.0889)
		(layer "In13.Cu")
		(net "M_H_CPU1_SB_DQ<11>")
	)
	(arc
		(start 140.9319 -280.243788)
		(mid 140.749649 -280.193438)
		(end 140.56614 -280.238962)
		(width 0.0889)
		(layer "In13.Cu")
		(net "M_H_CPU1_SB_DQ<11>")
	)
	(arc
		(start 142.803372 -280.238962)
		(mid 142.619864 -280.193468)
		(end 142.437612 -280.243788)
		(width 0.0889)
		(layer "In13.Cu")
		(net "M_H_CPU1_SB_DQ<11>")
	)
	(segment
		(start 136.047988 -279.490424)
		(end 136.51484 -279.756362)
		(width 0.10668)
		(layer "F.Cu")
		(net "M_H_CPU1_SB_DQ<10>")
	)
	(segment
		(start 161.10204 -289.344862)
		(end 161.306764 -289.344862)
		(width 0.14478)
		(layer "In13.Cu")
		(net "M_H_CPU1_SB_DQ<10>")
	)
	(segment
		(start 154.47391 -282.512008)
		(end 154.47391 -282.716732)
		(width 0.14478)
		(layer "In13.Cu")
		(net "M_H_CPU1_SB_DQ<10>")
	)
	(segment
		(start 154.08402 -282.326842)
		(end 154.288744 -282.326842)
		(width 0.14478)
		(layer "In13.Cu")
		(net "M_H_CPU1_SB_DQ<10>")
	)
	(segment
		(start 165.114224 -291.810186)
		(end 165.414452 -292.110414)
		(width 0.14478)
		(layer "In13.Cu")
		(net "M_H_CPU1_SB_DQ<10>")
	)
	(segment
		(start 155.068524 -283.106622)
		(end 155.25369 -283.291788)
		(width 0.14478)
		(layer "In13.Cu")
		(net "M_H_CPU1_SB_DQ<10>")
	)
	(segment
		(start 155.848304 -283.886402)
		(end 156.03347 -284.071568)
		(width 0.14478)
		(layer "In13.Cu")
		(net "M_H_CPU1_SB_DQ<10>")
	)
	(segment
		(start 153.844498 -282.36164)
		(end 154.049222 -282.36164)
		(width 0.14478)
		(layer "In13.Cu")
		(net "M_H_CPU1_SB_DQ<10>")
	)
	(segment
		(start 146.45132 -278.913844)
		(end 147.29587 -278.913844)
		(width 0.0889)
		(layer "In13.Cu")
		(net "M_H_CPU1_SB_DQ<10>")
	)
	(segment
		(start 151.319992 -279.63241)
		(end 151.319992 -279.837134)
		(width 0.14478)
		(layer "In13.Cu")
		(net "M_H_CPU1_SB_DQ<10>")
	)
	(segment
		(start 170.570144 -292.049962)
		(end 171.607226 -292.049962)
		(width 0.14478)
		(layer "In13.Cu")
		(net "M_H_CPU1_SB_DQ<10>")
	)
	(segment
		(start 153.69413 -281.936952)
		(end 153.659332 -281.97175)
		(width 0.14478)
		(layer "In13.Cu")
		(net "M_H_CPU1_SB_DQ<10>")
	)
	(segment
		(start 159.897572 -288.20999)
		(end 159.897572 -288.414714)
		(width 0.14478)
		(layer "In13.Cu")
		(net "M_H_CPU1_SB_DQ<10>")
	)
	(segment
		(start 159.15259 -287.190688)
		(end 159.15259 -287.395412)
		(width 0.14478)
		(layer "In13.Cu")
		(net "M_H_CPU1_SB_DQ<10>")
	)
	(segment
		(start 155.998672 -284.515814)
		(end 156.183838 -284.70098)
		(width 0.14478)
		(layer "In13.Cu")
		(net "M_H_CPU1_SB_DQ<10>")
	)
	(segment
		(start 159.747204 -287.785302)
		(end 159.93237 -287.970468)
		(width 0.14478)
		(layer "In13.Cu")
		(net "M_H_CPU1_SB_DQ<10>")
	)
	(segment
		(start 156.03347 -284.071568)
		(end 156.03347 -284.276292)
		(width 0.14478)
		(layer "In13.Cu")
		(net "M_H_CPU1_SB_DQ<10>")
	)
	(segment
		(start 156.03347 -284.276292)
		(end 155.998672 -284.31109)
		(width 0.14478)
		(layer "In13.Cu")
		(net "M_H_CPU1_SB_DQ<10>")
	)
	(segment
		(start 144.213326 -279.428956)
		(end 144.221708 -279.433782)
		(width 0.0889)
		(layer "In13.Cu")
		(net "M_H_CPU1_SB_DQ<10>")
	)
	(segment
		(start 162.187128 -291.17417)
		(end 162.391852 -291.17417)
		(width 0.14478)
		(layer "In13.Cu")
		(net "M_H_CPU1_SB_DQ<10>")
	)
	(segment
		(start 162.001962 -290.989004)
		(end 162.187128 -291.17417)
		(width 0.14478)
		(layer "In13.Cu")
		(net "M_H_CPU1_SB_DQ<10>")
	)
	(segment
		(start 136.693402 -279.428956)
		(end 136.701784 -279.433782)
		(width 0.0889)
		(layer "In13.Cu")
		(net "M_H_CPU1_SB_DQ<10>")
	)
	(segment
		(start 151.505158 -280.0223)
		(end 151.709882 -280.0223)
		(width 0.14478)
		(layer "In13.Cu")
		(net "M_H_CPU1_SB_DQ<10>")
	)
	(segment
		(start 160.71215 -288.954972)
		(end 160.677352 -288.98977)
		(width 0.14478)
		(layer "In13.Cu")
		(net "M_H_CPU1_SB_DQ<10>")
	)
	(segment
		(start 156.183838 -284.70098)
		(end 156.388562 -284.70098)
		(width 0.14478)
		(layer "In13.Cu")
		(net "M_H_CPU1_SB_DQ<10>")
	)
	(segment
		(start 156.42336 -284.666182)
		(end 156.628084 -284.666182)
		(width 0.14478)
		(layer "In13.Cu")
		(net "M_H_CPU1_SB_DQ<10>")
	)
	(segment
		(start 153.064718 -281.58186)
		(end 153.269442 -281.58186)
		(width 0.14478)
		(layer "In13.Cu")
		(net "M_H_CPU1_SB_DQ<10>")
	)
	(segment
		(start 158.37281 -286.615632)
		(end 158.338012 -286.65043)
		(width 0.14478)
		(layer "In13.Cu")
		(net "M_H_CPU1_SB_DQ<10>")
	)
	(segment
		(start 154.8638 -283.106622)
		(end 155.068524 -283.106622)
		(width 0.14478)
		(layer "In13.Cu")
		(net "M_H_CPU1_SB_DQ<10>")
	)
	(segment
		(start 154.049222 -282.36164)
		(end 154.08402 -282.326842)
		(width 0.14478)
		(layer "In13.Cu")
		(net "M_H_CPU1_SB_DQ<10>")
	)
	(segment
		(start 141.393418 -279.428956)
		(end 141.4018 -279.433782)
		(width 0.0889)
		(layer "In13.Cu")
		(net "M_H_CPU1_SB_DQ<10>")
	)
	(segment
		(start 159.302958 -287.8201)
		(end 159.507682 -287.8201)
		(width 0.14478)
		(layer "In13.Cu")
		(net "M_H_CPU1_SB_DQ<10>")
	)
	(segment
		(start 162.27171 -290.514532)
		(end 162.001962 -290.78428)
		(width 0.14478)
		(layer "In13.Cu")
		(net "M_H_CPU1_SB_DQ<10>")
	)
	(segment
		(start 153.69413 -281.732228)
		(end 153.69413 -281.936952)
		(width 0.14478)
		(layer "In13.Cu")
		(net "M_H_CPU1_SB_DQ<10>")
	)
	(segment
		(start 162.27171 -290.309808)
		(end 162.27171 -290.514532)
		(width 0.14478)
		(layer "In13.Cu")
		(net "M_H_CPU1_SB_DQ<10>")
	)
	(segment
		(start 164.56279 -292.110414)
		(end 164.863018 -291.810186)
		(width 0.14478)
		(layer "In13.Cu")
		(net "M_H_CPU1_SB_DQ<10>")
	)
	(segment
		(start 171.607226 -292.049962)
		(end 171.97197 -291.685218)
		(width 0.14478)
		(layer "In13.Cu")
		(net "M_H_CPU1_SB_DQ<10>")
	)
	(segment
		(start 161.88182 -290.124642)
		(end 162.086544 -290.124642)
		(width 0.14478)
		(layer "In13.Cu")
		(net "M_H_CPU1_SB_DQ<10>")
	)
	(segment
		(start 160.082738 -288.59988)
		(end 160.287462 -288.59988)
		(width 0.14478)
		(layer "In13.Cu")
		(net "M_H_CPU1_SB_DQ<10>")
	)
	(segment
		(start 163.646104 -291.684202)
		(end 164.072316 -292.110414)
		(width 0.14478)
		(layer "In13.Cu")
		(net "M_H_CPU1_SB_DQ<10>")
	)
	(segment
		(start 138.20775 -279.433782)
		(end 138.216132 -279.428956)
		(width 0.0889)
		(layer "In13.Cu")
		(net "M_H_CPU1_SB_DQ<10>")
	)
	(segment
		(start 147.922488 -279.06599)
		(end 151.027892 -279.06599)
		(width 0.14478)
		(layer "In13.Cu")
		(net "M_H_CPU1_SB_DQ<10>")
	)
	(segment
		(start 157.743398 -286.26054)
		(end 157.948122 -286.26054)
		(width 0.14478)
		(layer "In13.Cu")
		(net "M_H_CPU1_SB_DQ<10>")
	)
	(segment
		(start 151.35479 -279.597612)
		(end 151.319992 -279.63241)
		(width 0.14478)
		(layer "In13.Cu")
		(net "M_H_CPU1_SB_DQ<10>")
	)
	(segment
		(start 152.13457 -280.377392)
		(end 152.099772 -280.41219)
		(width 0.14478)
		(layer "In13.Cu")
		(net "M_H_CPU1_SB_DQ<10>")
	)
	(segment
		(start 136.51484 -279.756362)
		(end 136.360662 -279.490932)
		(width 0.0889)
		(layer "In13.Cu")
		(net "M_H_CPU1_SB_DQ<10>")
	)
	(segment
		(start 151.319992 -279.837134)
		(end 151.505158 -280.0223)
		(width 0.14478)
		(layer "In13.Cu")
		(net "M_H_CPU1_SB_DQ<10>")
	)
	(segment
		(start 153.508964 -281.547062)
		(end 153.69413 -281.732228)
		(width 0.14478)
		(layer "In13.Cu")
		(net "M_H_CPU1_SB_DQ<10>")
	)
	(segment
		(start 154.439112 -282.75153)
		(end 154.439112 -282.956254)
		(width 0.14478)
		(layer "In13.Cu")
		(net "M_H_CPU1_SB_DQ<10>")
	)
	(segment
		(start 160.862518 -289.37966)
		(end 161.067242 -289.37966)
		(width 0.14478)
		(layer "In13.Cu")
		(net "M_H_CPU1_SB_DQ<10>")
	)
	(segment
		(start 162.866324 -290.904422)
		(end 163.05149 -291.089588)
		(width 0.14478)
		(layer "In13.Cu")
		(net "M_H_CPU1_SB_DQ<10>")
	)
	(segment
		(start 152.489662 -280.80208)
		(end 152.52446 -280.767282)
		(width 0.14478)
		(layer "In13.Cu")
		(net "M_H_CPU1_SB_DQ<10>")
	)
	(segment
		(start 163.05149 -291.294312)
		(end 162.781742 -291.56406)
		(width 0.14478)
		(layer "In13.Cu")
		(net "M_H_CPU1_SB_DQ<10>")
	)
	(segment
		(start 161.612072 -290.39439)
		(end 161.88182 -290.124642)
		(width 0.14478)
		(layer "In13.Cu")
		(net "M_H_CPU1_SB_DQ<10>")
	)
	(segment
		(start 154.47391 -282.716732)
		(end 154.439112 -282.75153)
		(width 0.14478)
		(layer "In13.Cu")
		(net "M_H_CPU1_SB_DQ<10>")
	)
	(segment
		(start 157.168342 -285.48076)
		(end 157.20314 -285.445962)
		(width 0.14478)
		(layer "In13.Cu")
		(net "M_H_CPU1_SB_DQ<10>")
	)
	(segment
		(start 161.067242 -289.37966)
		(end 161.10204 -289.344862)
		(width 0.14478)
		(layer "In13.Cu")
		(net "M_H_CPU1_SB_DQ<10>")
	)
	(segment
		(start 158.338012 -286.855154)
		(end 158.523178 -287.04032)
		(width 0.14478)
		(layer "In13.Cu")
		(net "M_H_CPU1_SB_DQ<10>")
	)
	(segment
		(start 158.523178 -287.04032)
		(end 158.727902 -287.04032)
		(width 0.14478)
		(layer "In13.Cu")
		(net "M_H_CPU1_SB_DQ<10>")
	)
	(segment
		(start 151.027892 -279.06599)
		(end 151.35479 -279.392888)
		(width 0.14478)
		(layer "In13.Cu")
		(net "M_H_CPU1_SB_DQ<10>")
	)
	(segment
		(start 162.001962 -290.78428)
		(end 162.001962 -290.989004)
		(width 0.14478)
		(layer "In13.Cu")
		(net "M_H_CPU1_SB_DQ<10>")
	)
	(segment
		(start 155.404058 -283.9212)
		(end 155.608782 -283.9212)
		(width 0.14478)
		(layer "In13.Cu")
		(net "M_H_CPU1_SB_DQ<10>")
	)
	(segment
		(start 155.608782 -283.9212)
		(end 155.64358 -283.886402)
		(width 0.14478)
		(layer "In13.Cu")
		(net "M_H_CPU1_SB_DQ<10>")
	)
	(segment
		(start 152.099772 -280.41219)
		(end 152.099772 -280.616914)
		(width 0.14478)
		(layer "In13.Cu")
		(net "M_H_CPU1_SB_DQ<10>")
	)
	(segment
		(start 141.967712 -279.433782)
		(end 141.976094 -279.428956)
		(width 0.0889)
		(layer "In13.Cu")
		(net "M_H_CPU1_SB_DQ<10>")
	)
	(segment
		(start 157.98292 -286.225742)
		(end 158.187644 -286.225742)
		(width 0.14478)
		(layer "In13.Cu")
		(net "M_H_CPU1_SB_DQ<10>")
	)
	(segment
		(start 163.171632 -291.95395)
		(end 163.44138 -291.684202)
		(width 0.14478)
		(layer "In13.Cu")
		(net "M_H_CPU1_SB_DQ<10>")
	)
	(segment
		(start 153.269442 -281.58186)
		(end 153.30424 -281.547062)
		(width 0.14478)
		(layer "In13.Cu")
		(net "M_H_CPU1_SB_DQ<10>")
	)
	(segment
		(start 163.44138 -291.684202)
		(end 163.646104 -291.684202)
		(width 0.14478)
		(layer "In13.Cu")
		(net "M_H_CPU1_SB_DQ<10>")
	)
	(segment
		(start 153.30424 -281.547062)
		(end 153.508964 -281.547062)
		(width 0.14478)
		(layer "In13.Cu")
		(net "M_H_CPU1_SB_DQ<10>")
	)
	(segment
		(start 161.222182 -290.209224)
		(end 161.407348 -290.39439)
		(width 0.14478)
		(layer "In13.Cu")
		(net "M_H_CPU1_SB_DQ<10>")
	)
	(segment
		(start 159.507682 -287.8201)
		(end 159.54248 -287.785302)
		(width 0.14478)
		(layer "In13.Cu")
		(net "M_H_CPU1_SB_DQ<10>")
	)
	(segment
		(start 159.93237 -288.175192)
		(end 159.897572 -288.20999)
		(width 0.14478)
		(layer "In13.Cu")
		(net "M_H_CPU1_SB_DQ<10>")
	)
	(segment
		(start 158.338012 -286.65043)
		(end 158.338012 -286.855154)
		(width 0.14478)
		(layer "In13.Cu")
		(net "M_H_CPU1_SB_DQ<10>")
	)
	(segment
		(start 156.778452 -285.09087)
		(end 156.778452 -285.295594)
		(width 0.14478)
		(layer "In13.Cu")
		(net "M_H_CPU1_SB_DQ<10>")
	)
	(segment
		(start 161.407348 -290.39439)
		(end 161.612072 -290.39439)
		(width 0.14478)
		(layer "In13.Cu")
		(net "M_H_CPU1_SB_DQ<10>")
	)
	(segment
		(start 160.32226 -288.565082)
		(end 160.526984 -288.565082)
		(width 0.14478)
		(layer "In13.Cu")
		(net "M_H_CPU1_SB_DQ<10>")
	)
	(segment
		(start 162.781742 -291.56406)
		(end 162.781742 -291.768784)
		(width 0.14478)
		(layer "In13.Cu")
		(net "M_H_CPU1_SB_DQ<10>")
	)
	(segment
		(start 145.712688 -279.442418)
		(end 145.86585 -279.442418)
		(width 0.0889)
		(layer "In13.Cu")
		(net "M_H_CPU1_SB_DQ<10>")
	)
	(segment
		(start 151.74468 -279.987502)
		(end 151.949404 -279.987502)
		(width 0.14478)
		(layer "In13.Cu")
		(net "M_H_CPU1_SB_DQ<10>")
	)
	(segment
		(start 154.624278 -283.14142)
		(end 154.829002 -283.14142)
		(width 0.14478)
		(layer "In13.Cu")
		(net "M_H_CPU1_SB_DQ<10>")
	)
	(segment
		(start 147.448016 -279.06599)
		(end 147.922488 -279.06599)
		(width 0.0889)
		(layer "In13.Cu")
		(net "M_H_CPU1_SB_DQ<10>")
	)
	(segment
		(start 153.659332 -281.97175)
		(end 153.659332 -282.176474)
		(width 0.14478)
		(layer "In13.Cu")
		(net "M_H_CPU1_SB_DQ<10>")
	)
	(segment
		(start 162.6616 -290.904422)
		(end 162.866324 -290.904422)
		(width 0.14478)
		(layer "In13.Cu")
		(net "M_H_CPU1_SB_DQ<10>")
	)
	(segment
		(start 156.778452 -285.295594)
		(end 156.963618 -285.48076)
		(width 0.14478)
		(layer "In13.Cu")
		(net "M_H_CPU1_SB_DQ<10>")
	)
	(segment
		(start 155.25369 -283.496512)
		(end 155.218892 -283.53131)
		(width 0.14478)
		(layer "In13.Cu")
		(net "M_H_CPU1_SB_DQ<10>")
	)
	(segment
		(start 157.20314 -285.445962)
		(end 157.407864 -285.445962)
		(width 0.14478)
		(layer "In13.Cu")
		(net "M_H_CPU1_SB_DQ<10>")
	)
	(segment
		(start 152.879552 -281.19197)
		(end 152.879552 -281.396694)
		(width 0.14478)
		(layer "In13.Cu")
		(net "M_H_CPU1_SB_DQ<10>")
	)
	(segment
		(start 152.91435 -281.157172)
		(end 152.879552 -281.19197)
		(width 0.14478)
		(layer "In13.Cu")
		(net "M_H_CPU1_SB_DQ<10>")
	)
	(segment
		(start 162.086544 -290.124642)
		(end 162.27171 -290.309808)
		(width 0.14478)
		(layer "In13.Cu")
		(net "M_H_CPU1_SB_DQ<10>")
	)
	(segment
		(start 157.59303 -285.835852)
		(end 157.558232 -285.87065)
		(width 0.14478)
		(layer "In13.Cu")
		(net "M_H_CPU1_SB_DQ<10>")
	)
	(segment
		(start 161.49193 -289.734752)
		(end 161.222182 -290.0045)
		(width 0.14478)
		(layer "In13.Cu")
		(net "M_H_CPU1_SB_DQ<10>")
	)
	(segment
		(start 169.780458 -291.260276)
		(end 170.570144 -292.049962)
		(width 0.14478)
		(layer "In13.Cu")
		(net "M_H_CPU1_SB_DQ<10>")
	)
	(segment
		(start 152.099772 -280.616914)
		(end 152.284938 -280.80208)
		(width 0.14478)
		(layer "In13.Cu")
		(net "M_H_CPU1_SB_DQ<10>")
	)
	(segment
		(start 160.287462 -288.59988)
		(end 160.32226 -288.565082)
		(width 0.14478)
		(layer "In13.Cu")
		(net "M_H_CPU1_SB_DQ<10>")
	)
	(segment
		(start 157.558232 -285.87065)
		(end 157.558232 -286.075374)
		(width 0.14478)
		(layer "In13.Cu")
		(net "M_H_CPU1_SB_DQ<10>")
	)
	(segment
		(start 162.391852 -291.17417)
		(end 162.6616 -290.904422)
		(width 0.14478)
		(layer "In13.Cu")
		(net "M_H_CPU1_SB_DQ<10>")
	)
	(segment
		(start 154.829002 -283.14142)
		(end 154.8638 -283.106622)
		(width 0.14478)
		(layer "In13.Cu")
		(net "M_H_CPU1_SB_DQ<10>")
	)
	(segment
		(start 151.35479 -279.392888)
		(end 151.35479 -279.597612)
		(width 0.14478)
		(layer "In13.Cu")
		(net "M_H_CPU1_SB_DQ<10>")
	)
	(segment
		(start 144.787366 -279.433782)
		(end 144.795748 -279.428956)
		(width 0.0889)
		(layer "In13.Cu")
		(net "M_H_CPU1_SB_DQ<10>")
	)
	(segment
		(start 163.05149 -291.089588)
		(end 163.05149 -291.294312)
		(width 0.14478)
		(layer "In13.Cu")
		(net "M_H_CPU1_SB_DQ<10>")
	)
	(segment
		(start 137.267696 -279.433782)
		(end 137.276078 -279.428956)
		(width 0.0889)
		(layer "In13.Cu")
		(net "M_H_CPU1_SB_DQ<10>")
	)
	(segment
		(start 158.37281 -286.410908)
		(end 158.37281 -286.615632)
		(width 0.14478)
		(layer "In13.Cu")
		(net "M_H_CPU1_SB_DQ<10>")
	)
	(segment
		(start 136.360662 -279.490932)
		(end 136.383014 -279.40762)
		(width 0.0889)
		(layer "In13.Cu")
		(net "M_H_CPU1_SB_DQ<10>")
	)
	(segment
		(start 155.25369 -283.291788)
		(end 155.25369 -283.496512)
		(width 0.14478)
		(layer "In13.Cu")
		(net "M_H_CPU1_SB_DQ<10>")
	)
	(segment
		(start 161.49193 -289.530028)
		(end 161.49193 -289.734752)
		(width 0.14478)
		(layer "In13.Cu")
		(net "M_H_CPU1_SB_DQ<10>")
	)
	(segment
		(start 151.949404 -279.987502)
		(end 152.13457 -280.172668)
		(width 0.14478)
		(layer "In13.Cu")
		(net "M_H_CPU1_SB_DQ<10>")
	)
	(segment
		(start 156.81325 -284.851348)
		(end 156.81325 -285.056072)
		(width 0.14478)
		(layer "In13.Cu")
		(net "M_H_CPU1_SB_DQ<10>")
	)
	(segment
		(start 158.727902 -287.04032)
		(end 158.7627 -287.005522)
		(width 0.14478)
		(layer "In13.Cu")
		(net "M_H_CPU1_SB_DQ<10>")
	)
	(segment
		(start 159.15259 -287.395412)
		(end 159.117792 -287.43021)
		(width 0.14478)
		(layer "In13.Cu")
		(net "M_H_CPU1_SB_DQ<10>")
	)
	(segment
		(start 160.677352 -289.194494)
		(end 160.862518 -289.37966)
		(width 0.14478)
		(layer "In13.Cu")
		(net "M_H_CPU1_SB_DQ<10>")
	)
	(segment
		(start 160.526984 -288.565082)
		(end 160.71215 -288.750248)
		(width 0.14478)
		(layer "In13.Cu")
		(net "M_H_CPU1_SB_DQ<10>")
	)
	(segment
		(start 161.222182 -290.0045)
		(end 161.222182 -290.209224)
		(width 0.14478)
		(layer "In13.Cu")
		(net "M_H_CPU1_SB_DQ<10>")
	)
	(segment
		(start 167.000174 -291.260276)
		(end 169.780458 -291.260276)
		(width 0.14478)
		(layer "In13.Cu")
		(net "M_H_CPU1_SB_DQ<10>")
	)
	(segment
		(start 152.879552 -281.396694)
		(end 153.064718 -281.58186)
		(width 0.14478)
		(layer "In13.Cu")
		(net "M_H_CPU1_SB_DQ<10>")
	)
	(segment
		(start 151.709882 -280.0223)
		(end 151.74468 -279.987502)
		(width 0.14478)
		(layer "In13.Cu")
		(net "M_H_CPU1_SB_DQ<10>")
	)
	(segment
		(start 156.628084 -284.666182)
		(end 156.81325 -284.851348)
		(width 0.14478)
		(layer "In13.Cu")
		(net "M_H_CPU1_SB_DQ<10>")
	)
	(segment
		(start 153.659332 -282.176474)
		(end 153.844498 -282.36164)
		(width 0.14478)
		(layer "In13.Cu")
		(net "M_H_CPU1_SB_DQ<10>")
	)
	(segment
		(start 160.71215 -288.750248)
		(end 160.71215 -288.954972)
		(width 0.14478)
		(layer "In13.Cu")
		(net "M_H_CPU1_SB_DQ<10>")
	)
	(segment
		(start 155.218892 -283.736034)
		(end 155.404058 -283.9212)
		(width 0.14478)
		(layer "In13.Cu")
		(net "M_H_CPU1_SB_DQ<10>")
	)
	(segment
		(start 152.91435 -280.952448)
		(end 152.91435 -281.157172)
		(width 0.14478)
		(layer "In13.Cu")
		(net "M_H_CPU1_SB_DQ<10>")
	)
	(segment
		(start 156.963618 -285.48076)
		(end 157.168342 -285.48076)
		(width 0.14478)
		(layer "In13.Cu")
		(net "M_H_CPU1_SB_DQ<10>")
	)
	(segment
		(start 162.966908 -291.95395)
		(end 163.171632 -291.95395)
		(width 0.14478)
		(layer "In13.Cu")
		(net "M_H_CPU1_SB_DQ<10>")
	)
	(segment
		(start 152.729184 -280.767282)
		(end 152.91435 -280.952448)
		(width 0.14478)
		(layer "In13.Cu")
		(net "M_H_CPU1_SB_DQ<10>")
	)
	(segment
		(start 159.117792 -287.634934)
		(end 159.302958 -287.8201)
		(width 0.14478)
		(layer "In13.Cu")
		(net "M_H_CPU1_SB_DQ<10>")
	)
	(segment
		(start 158.967424 -287.005522)
		(end 159.15259 -287.190688)
		(width 0.14478)
		(layer "In13.Cu")
		(net "M_H_CPU1_SB_DQ<10>")
	)
	(segment
		(start 159.897572 -288.414714)
		(end 160.082738 -288.59988)
		(width 0.14478)
		(layer "In13.Cu")
		(net "M_H_CPU1_SB_DQ<10>")
	)
	(segment
		(start 144.221708 -279.433782)
		(end 144.232122 -279.439878)
		(width 0.0889)
		(layer "In13.Cu")
		(net "M_H_CPU1_SB_DQ<10>")
	)
	(segment
		(start 154.288744 -282.326842)
		(end 154.47391 -282.512008)
		(width 0.14478)
		(layer "In13.Cu")
		(net "M_H_CPU1_SB_DQ<10>")
	)
	(segment
		(start 158.187644 -286.225742)
		(end 158.37281 -286.410908)
		(width 0.14478)
		(layer "In13.Cu")
		(net "M_H_CPU1_SB_DQ<10>")
	)
	(segment
		(start 157.407864 -285.445962)
		(end 157.59303 -285.631128)
		(width 0.14478)
		(layer "In13.Cu")
		(net "M_H_CPU1_SB_DQ<10>")
	)
	(segment
		(start 158.7627 -287.005522)
		(end 158.967424 -287.005522)
		(width 0.14478)
		(layer "In13.Cu")
		(net "M_H_CPU1_SB_DQ<10>")
	)
	(segment
		(start 157.558232 -286.075374)
		(end 157.743398 -286.26054)
		(width 0.14478)
		(layer "In13.Cu")
		(net "M_H_CPU1_SB_DQ<10>")
	)
	(segment
		(start 165.414452 -292.110414)
		(end 166.150036 -292.110414)
		(width 0.14478)
		(layer "In13.Cu")
		(net "M_H_CPU1_SB_DQ<10>")
	)
	(segment
		(start 147.29587 -278.913844)
		(end 147.448016 -279.06599)
		(width 0.0889)
		(layer "In13.Cu")
		(net "M_H_CPU1_SB_DQ<10>")
	)
	(segment
		(start 164.863018 -291.810186)
		(end 165.114224 -291.810186)
		(width 0.14478)
		(layer "In13.Cu")
		(net "M_H_CPU1_SB_DQ<10>")
	)
	(segment
		(start 159.117792 -287.43021)
		(end 159.117792 -287.634934)
		(width 0.14478)
		(layer "In13.Cu")
		(net "M_H_CPU1_SB_DQ<10>")
	)
	(segment
		(start 159.93237 -287.970468)
		(end 159.93237 -288.175192)
		(width 0.14478)
		(layer "In13.Cu")
		(net "M_H_CPU1_SB_DQ<10>")
	)
	(segment
		(start 145.86585 -279.442418)
		(end 146.35988 -278.95169)
		(width 0.0889)
		(layer "In13.Cu")
		(net "M_H_CPU1_SB_DQ<10>")
	)
	(segment
		(start 157.948122 -286.26054)
		(end 157.98292 -286.225742)
		(width 0.14478)
		(layer "In13.Cu")
		(net "M_H_CPU1_SB_DQ<10>")
	)
	(segment
		(start 154.439112 -282.956254)
		(end 154.624278 -283.14142)
		(width 0.14478)
		(layer "In13.Cu")
		(net "M_H_CPU1_SB_DQ<10>")
	)
	(segment
		(start 156.81325 -285.056072)
		(end 156.778452 -285.09087)
		(width 0.14478)
		(layer "In13.Cu")
		(net "M_H_CPU1_SB_DQ<10>")
	)
	(segment
		(start 161.306764 -289.344862)
		(end 161.49193 -289.530028)
		(width 0.14478)
		(layer "In13.Cu")
		(net "M_H_CPU1_SB_DQ<10>")
	)
	(segment
		(start 155.218892 -283.53131)
		(end 155.218892 -283.736034)
		(width 0.14478)
		(layer "In13.Cu")
		(net "M_H_CPU1_SB_DQ<10>")
	)
	(segment
		(start 155.64358 -283.886402)
		(end 155.848304 -283.886402)
		(width 0.14478)
		(layer "In13.Cu")
		(net "M_H_CPU1_SB_DQ<10>")
	)
	(segment
		(start 155.998672 -284.31109)
		(end 155.998672 -284.515814)
		(width 0.14478)
		(layer "In13.Cu")
		(net "M_H_CPU1_SB_DQ<10>")
	)
	(segment
		(start 156.388562 -284.70098)
		(end 156.42336 -284.666182)
		(width 0.14478)
		(layer "In13.Cu")
		(net "M_H_CPU1_SB_DQ<10>")
	)
	(segment
		(start 162.781742 -291.768784)
		(end 162.966908 -291.95395)
		(width 0.14478)
		(layer "In13.Cu")
		(net "M_H_CPU1_SB_DQ<10>")
	)
	(segment
		(start 166.150036 -292.110414)
		(end 167.000174 -291.260276)
		(width 0.14478)
		(layer "In13.Cu")
		(net "M_H_CPU1_SB_DQ<10>")
	)
	(segment
		(start 160.677352 -288.98977)
		(end 160.677352 -289.194494)
		(width 0.14478)
		(layer "In13.Cu")
		(net "M_H_CPU1_SB_DQ<10>")
	)
	(segment
		(start 140.453364 -279.428956)
		(end 140.461746 -279.433782)
		(width 0.0889)
		(layer "In13.Cu")
		(net "M_H_CPU1_SB_DQ<10>")
	)
	(segment
		(start 152.284938 -280.80208)
		(end 152.489662 -280.80208)
		(width 0.14478)
		(layer "In13.Cu")
		(net "M_H_CPU1_SB_DQ<10>")
	)
	(segment
		(start 164.072316 -292.110414)
		(end 164.56279 -292.110414)
		(width 0.14478)
		(layer "In13.Cu")
		(net "M_H_CPU1_SB_DQ<10>")
	)
	(segment
		(start 159.54248 -287.785302)
		(end 159.747204 -287.785302)
		(width 0.14478)
		(layer "In13.Cu")
		(net "M_H_CPU1_SB_DQ<10>")
	)
	(segment
		(start 152.52446 -280.767282)
		(end 152.729184 -280.767282)
		(width 0.14478)
		(layer "In13.Cu")
		(net "M_H_CPU1_SB_DQ<10>")
	)
	(segment
		(start 152.13457 -280.172668)
		(end 152.13457 -280.377392)
		(width 0.14478)
		(layer "In13.Cu")
		(net "M_H_CPU1_SB_DQ<10>")
	)
	(segment
		(start 157.59303 -285.631128)
		(end 157.59303 -285.835852)
		(width 0.14478)
		(layer "In13.Cu")
		(net "M_H_CPU1_SB_DQ<10>")
	)
	(arc
		(start 136.383014 -279.40762)
		(mid 136.540524 -279.384422)
		(end 136.693402 -279.428956)
		(width 0.0889)
		(layer "In13.Cu")
		(net "M_H_CPU1_SB_DQ<10>")
	)
	(arc
		(start 137.276078 -279.428956)
		(mid 137.459586 -279.383462)
		(end 137.641838 -279.433782)
		(width 0.0889)
		(layer "In13.Cu")
		(net "M_H_CPU1_SB_DQ<10>")
	)
	(arc
		(start 142.907766 -279.433782)
		(mid 143.09471 -279.383527)
		(end 143.281654 -279.433782)
		(width 0.0889)
		(layer "In13.Cu")
		(net "M_H_CPU1_SB_DQ<10>")
	)
	(arc
		(start 145.161508 -279.433782)
		(mid 145.43596 -279.510018)
		(end 145.712688 -279.442418)
		(width 0.0889)
		(layer "In13.Cu")
		(net "M_H_CPU1_SB_DQ<10>")
	)
	(arc
		(start 140.087604 -279.433782)
		(mid 140.269855 -279.383432)
		(end 140.453364 -279.428956)
		(width 0.0889)
		(layer "In13.Cu")
		(net "M_H_CPU1_SB_DQ<10>")
	)
	(arc
		(start 143.281654 -279.433782)
		(mid 143.56461 -279.509959)
		(end 143.847566 -279.433782)
		(width 0.0889)
		(layer "In13.Cu")
		(net "M_H_CPU1_SB_DQ<10>")
	)
	(arc
		(start 141.976094 -279.428956)
		(mid 142.159602 -279.383462)
		(end 142.341854 -279.433782)
		(width 0.0889)
		(layer "In13.Cu")
		(net "M_H_CPU1_SB_DQ<10>")
	)
	(arc
		(start 138.581892 -279.433782)
		(mid 138.864848 -279.509959)
		(end 139.147804 -279.433782)
		(width 0.0889)
		(layer "In13.Cu")
		(net "M_H_CPU1_SB_DQ<10>")
	)
	(arc
		(start 140.461746 -279.433782)
		(mid 140.744702 -279.509959)
		(end 141.027658 -279.433782)
		(width 0.0889)
		(layer "In13.Cu")
		(net "M_H_CPU1_SB_DQ<10>")
	)
	(arc
		(start 144.232122 -279.439878)
		(mid 144.510554 -279.509976)
		(end 144.787366 -279.433782)
		(width 0.0889)
		(layer "In13.Cu")
		(net "M_H_CPU1_SB_DQ<10>")
	)
	(arc
		(start 139.147804 -279.433782)
		(mid 139.334748 -279.383527)
		(end 139.521692 -279.433782)
		(width 0.0889)
		(layer "In13.Cu")
		(net "M_H_CPU1_SB_DQ<10>")
	)
	(arc
		(start 137.641838 -279.433782)
		(mid 137.924794 -279.509959)
		(end 138.20775 -279.433782)
		(width 0.0889)
		(layer "In13.Cu")
		(net "M_H_CPU1_SB_DQ<10>")
	)
	(arc
		(start 136.701784 -279.433782)
		(mid 136.98474 -279.509959)
		(end 137.267696 -279.433782)
		(width 0.0889)
		(layer "In13.Cu")
		(net "M_H_CPU1_SB_DQ<10>")
	)
	(arc
		(start 141.4018 -279.433782)
		(mid 141.684756 -279.509959)
		(end 141.967712 -279.433782)
		(width 0.0889)
		(layer "In13.Cu")
		(net "M_H_CPU1_SB_DQ<10>")
	)
	(arc
		(start 146.35988 -278.95169)
		(mid 146.401833 -278.923658)
		(end 146.45132 -278.913844)
		(width 0.0889)
		(layer "In13.Cu")
		(net "M_H_CPU1_SB_DQ<10>")
	)
	(arc
		(start 144.795748 -279.428956)
		(mid 144.979256 -279.383462)
		(end 145.161508 -279.433782)
		(width 0.0889)
		(layer "In13.Cu")
		(net "M_H_CPU1_SB_DQ<10>")
	)
	(arc
		(start 141.027658 -279.433782)
		(mid 141.209909 -279.383432)
		(end 141.393418 -279.428956)
		(width 0.0889)
		(layer "In13.Cu")
		(net "M_H_CPU1_SB_DQ<10>")
	)
	(arc
		(start 138.216132 -279.428956)
		(mid 138.39964 -279.383462)
		(end 138.581892 -279.433782)
		(width 0.0889)
		(layer "In13.Cu")
		(net "M_H_CPU1_SB_DQ<10>")
	)
	(arc
		(start 143.847566 -279.433782)
		(mid 144.029817 -279.383432)
		(end 144.213326 -279.428956)
		(width 0.0889)
		(layer "In13.Cu")
		(net "M_H_CPU1_SB_DQ<10>")
	)
	(arc
		(start 139.521692 -279.433782)
		(mid 139.804648 -279.509959)
		(end 140.087604 -279.433782)
		(width 0.0889)
		(layer "In13.Cu")
		(net "M_H_CPU1_SB_DQ<10>")
	)
	(arc
		(start 142.341854 -279.433782)
		(mid 142.62481 -279.509959)
		(end 142.907766 -279.433782)
		(width 0.0889)
		(layer "In13.Cu")
		(net "M_H_CPU1_SB_DQ<10>")
	)
	(segment
		(start 135.577834 -273.820382)
		(end 136.044686 -274.08632)
		(width 0.10668)
		(layer "F.Cu")
		(net "M_H_CPU1_SB_DQ<0>")
	)
	(segment
		(start 172.436282 -281.910282)
		(end 170.9674 -281.910282)
		(width 0.14478)
		(layer "In13.Cu")
		(net "M_H_CPU1_SB_DQ<0>")
	)
	(segment
		(start 139.626086 -274.413726)
		(end 139.617704 -274.4089)
		(width 0.0889)
		(layer "In13.Cu")
		(net "M_H_CPU1_SB_DQ<0>")
	)
	(segment
		(start 146.717258 -273.394424)
		(end 145.706084 -274.405598)
		(width 0.0889)
		(layer "In13.Cu")
		(net "M_H_CPU1_SB_DQ<0>")
	)
	(segment
		(start 165.629844 -281.910282)
		(end 164.200586 -281.910282)
		(width 0.14478)
		(layer "In13.Cu")
		(net "M_H_CPU1_SB_DQ<0>")
	)
	(segment
		(start 147.168616 -273.394424)
		(end 146.717258 -273.394424)
		(width 0.0889)
		(layer "In13.Cu")
		(net "M_H_CPU1_SB_DQ<0>")
	)
	(segment
		(start 143.386048 -274.413726)
		(end 143.377666 -274.4089)
		(width 0.0889)
		(layer "In13.Cu")
		(net "M_H_CPU1_SB_DQ<0>")
	)
	(segment
		(start 175.344074 -281.8765)
		(end 175.199294 -282.02128)
		(width 0.14478)
		(layer "In13.Cu")
		(net "M_H_CPU1_SB_DQ<0>")
	)
	(segment
		(start 167.681656 -281.060398)
		(end 165.629844 -281.910282)
		(width 0.14478)
		(layer "In13.Cu")
		(net "M_H_CPU1_SB_DQ<0>")
	)
	(segment
		(start 145.589498 -274.459954)
		(end 145.444972 -274.459954)
		(width 0.0889)
		(layer "In13.Cu")
		(net "M_H_CPU1_SB_DQ<0>")
	)
	(segment
		(start 145.706084 -274.405598)
		(end 145.589498 -274.459954)
		(width 0.0889)
		(layer "In13.Cu")
		(net "M_H_CPU1_SB_DQ<0>")
	)
	(segment
		(start 163.78555 -280.936954)
		(end 161.026094 -278.177498)
		(width 0.14478)
		(layer "In13.Cu")
		(net "M_H_CPU1_SB_DQ<0>")
	)
	(segment
		(start 160.06699 -278.177498)
		(end 154.829256 -272.939764)
		(width 0.14478)
		(layer "In13.Cu")
		(net "M_H_CPU1_SB_DQ<0>")
	)
	(segment
		(start 172.861224 -281.48534)
		(end 172.436282 -281.910282)
		(width 0.14478)
		(layer "In13.Cu")
		(net "M_H_CPU1_SB_DQ<0>")
	)
	(segment
		(start 174.792894 -281.8765)
		(end 174.792894 -281.63012)
		(width 0.14478)
		(layer "In13.Cu")
		(net "M_H_CPU1_SB_DQ<0>")
	)
	(segment
		(start 139.051792 -274.4089)
		(end 139.04341 -274.413726)
		(width 0.0889)
		(layer "In13.Cu")
		(net "M_H_CPU1_SB_DQ<0>")
	)
	(segment
		(start 136.29513 -274.37715)
		(end 136.198864 -274.35175)
		(width 0.0889)
		(layer "In13.Cu")
		(net "M_H_CPU1_SB_DQ<0>")
	)
	(segment
		(start 170.9674 -281.910282)
		(end 170.117516 -281.060398)
		(width 0.14478)
		(layer "In13.Cu")
		(net "M_H_CPU1_SB_DQ<0>")
	)
	(segment
		(start 142.811754 -274.4089)
		(end 142.803372 -274.413726)
		(width 0.0889)
		(layer "In13.Cu")
		(net "M_H_CPU1_SB_DQ<0>")
	)
	(segment
		(start 147.623276 -272.939764)
		(end 147.168616 -273.394424)
		(width 0.0889)
		(layer "In13.Cu")
		(net "M_H_CPU1_SB_DQ<0>")
	)
	(segment
		(start 175.344074 -281.63012)
		(end 175.344074 -281.8765)
		(width 0.14478)
		(layer "In13.Cu")
		(net "M_H_CPU1_SB_DQ<0>")
	)
	(segment
		(start 174.792894 -281.63012)
		(end 174.648114 -281.48534)
		(width 0.14478)
		(layer "In13.Cu")
		(net "M_H_CPU1_SB_DQ<0>")
	)
	(segment
		(start 174.648114 -281.48534)
		(end 172.861224 -281.48534)
		(width 0.14478)
		(layer "In13.Cu")
		(net "M_H_CPU1_SB_DQ<0>")
	)
	(segment
		(start 176.072038 -281.48534)
		(end 175.488854 -281.48534)
		(width 0.14478)
		(layer "In13.Cu")
		(net "M_H_CPU1_SB_DQ<0>")
	)
	(segment
		(start 148.047964 -272.939764)
		(end 147.623276 -272.939764)
		(width 0.0889)
		(layer "In13.Cu")
		(net "M_H_CPU1_SB_DQ<0>")
	)
	(segment
		(start 144.334484 -274.41906)
		(end 144.316196 -274.408646)
		(width 0.0889)
		(layer "In13.Cu")
		(net "M_H_CPU1_SB_DQ<0>")
	)
	(segment
		(start 136.198864 -274.35175)
		(end 136.044686 -274.08632)
		(width 0.0889)
		(layer "In13.Cu")
		(net "M_H_CPU1_SB_DQ<0>")
	)
	(segment
		(start 170.117516 -281.060398)
		(end 167.681656 -281.060398)
		(width 0.14478)
		(layer "In13.Cu")
		(net "M_H_CPU1_SB_DQ<0>")
	)
	(segment
		(start 174.937674 -282.02128)
		(end 174.792894 -281.8765)
		(width 0.14478)
		(layer "In13.Cu")
		(net "M_H_CPU1_SB_DQ<0>")
	)
	(segment
		(start 163.78555 -281.495246)
		(end 163.78555 -280.936954)
		(width 0.14478)
		(layer "In13.Cu")
		(net "M_H_CPU1_SB_DQ<0>")
	)
	(segment
		(start 144.71269 -274.395184)
		(end 144.689322 -274.4089)
		(width 0.0889)
		(layer "In13.Cu")
		(net "M_H_CPU1_SB_DQ<0>")
	)
	(segment
		(start 161.026094 -278.177498)
		(end 160.06699 -278.177498)
		(width 0.14478)
		(layer "In13.Cu")
		(net "M_H_CPU1_SB_DQ<0>")
	)
	(segment
		(start 144.316196 -274.408646)
		(end 144.294606 -274.3962)
		(width 0.0889)
		(layer "In13.Cu")
		(net "M_H_CPU1_SB_DQ<0>")
	)
	(segment
		(start 138.111738 -274.4089)
		(end 138.103356 -274.413726)
		(width 0.0889)
		(layer "In13.Cu")
		(net "M_H_CPU1_SB_DQ<0>")
	)
	(segment
		(start 175.199294 -282.02128)
		(end 174.937674 -282.02128)
		(width 0.14478)
		(layer "In13.Cu")
		(net "M_H_CPU1_SB_DQ<0>")
	)
	(segment
		(start 164.200586 -281.910282)
		(end 163.78555 -281.495246)
		(width 0.14478)
		(layer "In13.Cu")
		(net "M_H_CPU1_SB_DQ<0>")
	)
	(segment
		(start 140.56614 -274.413726)
		(end 140.557758 -274.4089)
		(width 0.0889)
		(layer "In13.Cu")
		(net "M_H_CPU1_SB_DQ<0>")
	)
	(segment
		(start 145.444972 -274.459954)
		(end 145.444718 -274.4597)
		(width 0.0889)
		(layer "In13.Cu")
		(net "M_H_CPU1_SB_DQ<0>")
	)
	(segment
		(start 154.829256 -272.939764)
		(end 148.047964 -272.939764)
		(width 0.14478)
		(layer "In13.Cu")
		(net "M_H_CPU1_SB_DQ<0>")
	)
	(segment
		(start 175.488854 -281.48534)
		(end 175.344074 -281.63012)
		(width 0.14478)
		(layer "In13.Cu")
		(net "M_H_CPU1_SB_DQ<0>")
	)
	(arc
		(start 140.557758 -274.4089)
		(mid 140.274802 -274.332723)
		(end 139.991846 -274.4089)
		(width 0.0889)
		(layer "In13.Cu")
		(net "M_H_CPU1_SB_DQ<0>")
	)
	(arc
		(start 138.103356 -274.413726)
		(mid 137.919848 -274.45922)
		(end 137.737596 -274.4089)
		(width 0.0889)
		(layer "In13.Cu")
		(net "M_H_CPU1_SB_DQ<0>")
	)
	(arc
		(start 144.689322 -274.4089)
		(mid 144.513202 -274.458878)
		(end 144.334484 -274.41906)
		(width 0.0889)
		(layer "In13.Cu")
		(net "M_H_CPU1_SB_DQ<0>")
	)
	(arc
		(start 145.444718 -274.4597)
		(mid 145.34723 -274.446817)
		(end 145.256504 -274.4089)
		(width 0.0889)
		(layer "In13.Cu")
		(net "M_H_CPU1_SB_DQ<0>")
	)
	(arc
		(start 144.294606 -274.3962)
		(mid 144.021577 -274.332881)
		(end 143.751808 -274.4089)
		(width 0.0889)
		(layer "In13.Cu")
		(net "M_H_CPU1_SB_DQ<0>")
	)
	(arc
		(start 141.8717 -274.4089)
		(mid 141.684756 -274.459155)
		(end 141.497812 -274.4089)
		(width 0.0889)
		(layer "In13.Cu")
		(net "M_H_CPU1_SB_DQ<0>")
	)
	(arc
		(start 143.751808 -274.4089)
		(mid 143.569557 -274.45925)
		(end 143.386048 -274.413726)
		(width 0.0889)
		(layer "In13.Cu")
		(net "M_H_CPU1_SB_DQ<0>")
	)
	(arc
		(start 142.803372 -274.413726)
		(mid 142.619864 -274.45922)
		(end 142.437612 -274.4089)
		(width 0.0889)
		(layer "In13.Cu")
		(net "M_H_CPU1_SB_DQ<0>")
	)
	(arc
		(start 141.497812 -274.4089)
		(mid 141.214856 -274.332723)
		(end 140.9319 -274.4089)
		(width 0.0889)
		(layer "In13.Cu")
		(net "M_H_CPU1_SB_DQ<0>")
	)
	(arc
		(start 139.617704 -274.4089)
		(mid 139.334748 -274.332723)
		(end 139.051792 -274.4089)
		(width 0.0889)
		(layer "In13.Cu")
		(net "M_H_CPU1_SB_DQ<0>")
	)
	(arc
		(start 139.04341 -274.413726)
		(mid 138.859902 -274.45922)
		(end 138.67765 -274.4089)
		(width 0.0889)
		(layer "In13.Cu")
		(net "M_H_CPU1_SB_DQ<0>")
	)
	(arc
		(start 137.737596 -274.4089)
		(mid 137.45464 -274.332723)
		(end 137.171684 -274.4089)
		(width 0.0889)
		(layer "In13.Cu")
		(net "M_H_CPU1_SB_DQ<0>")
	)
	(arc
		(start 140.9319 -274.4089)
		(mid 140.749649 -274.45925)
		(end 140.56614 -274.413726)
		(width 0.0889)
		(layer "In13.Cu")
		(net "M_H_CPU1_SB_DQ<0>")
	)
	(arc
		(start 145.256504 -274.4089)
		(mid 144.986347 -274.332138)
		(end 144.71269 -274.395184)
		(width 0.0889)
		(layer "In13.Cu")
		(net "M_H_CPU1_SB_DQ<0>")
	)
	(arc
		(start 137.171684 -274.4089)
		(mid 136.98474 -274.459155)
		(end 136.797796 -274.4089)
		(width 0.0889)
		(layer "In13.Cu")
		(net "M_H_CPU1_SB_DQ<0>")
	)
	(arc
		(start 136.797796 -274.4089)
		(mid 136.5502 -274.333722)
		(end 136.29513 -274.37715)
		(width 0.0889)
		(layer "In13.Cu")
		(net "M_H_CPU1_SB_DQ<0>")
	)
	(arc
		(start 139.991846 -274.4089)
		(mid 139.809595 -274.45925)
		(end 139.626086 -274.413726)
		(width 0.0889)
		(layer "In13.Cu")
		(net "M_H_CPU1_SB_DQ<0>")
	)
	(arc
		(start 138.67765 -274.4089)
		(mid 138.394694 -274.332723)
		(end 138.111738 -274.4089)
		(width 0.0889)
		(layer "In13.Cu")
		(net "M_H_CPU1_SB_DQ<0>")
	)
	(arc
		(start 143.377666 -274.4089)
		(mid 143.09471 -274.332723)
		(end 142.811754 -274.4089)
		(width 0.0889)
		(layer "In13.Cu")
		(net "M_H_CPU1_SB_DQ<0>")
	)
	(arc
		(start 142.437612 -274.4089)
		(mid 142.154656 -274.332723)
		(end 141.8717 -274.4089)
		(width 0.0889)
		(layer "In13.Cu")
		(net "M_H_CPU1_SB_DQ<0>")
	)
	(segment
		(start 136.047988 -266.530328)
		(end 136.51484 -266.796266)
		(width 0.10668)
		(layer "F.Cu")
		(net "M_H_CPU1_SB_CS_N<1>")
	)
	(segment
		(start 169.096182 -267.912088)
		(end 168.951402 -268.056868)
		(width 0.14478)
		(layer "In13.Cu")
		(net "M_H_CPU1_SB_CS_N<1>")
	)
	(segment
		(start 171.951396 -268.735302)
		(end 171.5262 -269.160498)
		(width 0.14478)
		(layer "In13.Cu")
		(net "M_H_CPU1_SB_CS_N<1>")
	)
	(segment
		(start 166.97579 -268.31036)
		(end 166.125652 -269.160498)
		(width 0.14478)
		(layer "In13.Cu")
		(net "M_H_CPU1_SB_CS_N<1>")
	)
	(segment
		(start 136.701784 -266.473686)
		(end 136.694418 -266.469368)
		(width 0.0889)
		(layer "In13.Cu")
		(net "M_H_CPU1_SB_CS_N<1>")
	)
	(segment
		(start 169.647362 -268.31036)
		(end 169.502582 -268.16558)
		(width 0.14478)
		(layer "In13.Cu")
		(net "M_H_CPU1_SB_CS_N<1>")
	)
	(segment
		(start 146.237706 -265.703304)
		(end 145.516346 -266.424664)
		(width 0.0889)
		(layer "In13.Cu")
		(net "M_H_CPU1_SB_CS_N<1>")
	)
	(segment
		(start 148.025104 -265.703304)
		(end 146.237706 -265.703304)
		(width 0.0889)
		(layer "In13.Cu")
		(net "M_H_CPU1_SB_CS_N<1>")
	)
	(segment
		(start 138.216132 -266.46886)
		(end 138.20775 -266.473686)
		(width 0.0889)
		(layer "In13.Cu")
		(net "M_H_CPU1_SB_CS_N<1>")
	)
	(segment
		(start 141.976094 -266.46886)
		(end 141.967712 -266.473686)
		(width 0.0889)
		(layer "In13.Cu")
		(net "M_H_CPU1_SB_CS_N<1>")
	)
	(segment
		(start 137.276078 -266.46886)
		(end 137.267696 -266.473686)
		(width 0.0889)
		(layer "In13.Cu")
		(net "M_H_CPU1_SB_CS_N<1>")
	)
	(segment
		(start 169.357802 -267.912088)
		(end 169.096182 -267.912088)
		(width 0.14478)
		(layer "In13.Cu")
		(net "M_H_CPU1_SB_CS_N<1>")
	)
	(segment
		(start 168.400222 -268.16558)
		(end 168.400222 -268.056868)
		(width 0.14478)
		(layer "In13.Cu")
		(net "M_H_CPU1_SB_CS_N<1>")
	)
	(segment
		(start 167.704262 -268.31036)
		(end 166.97579 -268.31036)
		(width 0.14478)
		(layer "In13.Cu")
		(net "M_H_CPU1_SB_CS_N<1>")
	)
	(segment
		(start 167.849042 -268.056868)
		(end 167.849042 -268.16558)
		(width 0.14478)
		(layer "In13.Cu")
		(net "M_H_CPU1_SB_CS_N<1>")
	)
	(segment
		(start 141.4018 -266.473686)
		(end 141.393418 -266.46886)
		(width 0.0889)
		(layer "In13.Cu")
		(net "M_H_CPU1_SB_CS_N<1>")
	)
	(segment
		(start 161.02203 -265.703304)
		(end 148.025104 -265.703304)
		(width 0.14478)
		(layer "In13.Cu")
		(net "M_H_CPU1_SB_CS_N<1>")
	)
	(segment
		(start 167.993822 -267.912088)
		(end 167.849042 -268.056868)
		(width 0.14478)
		(layer "In13.Cu")
		(net "M_H_CPU1_SB_CS_N<1>")
	)
	(segment
		(start 144.220946 -266.47394)
		(end 144.20088 -266.46251)
		(width 0.0889)
		(layer "In13.Cu")
		(net "M_H_CPU1_SB_CS_N<1>")
	)
	(segment
		(start 168.255442 -267.912088)
		(end 167.993822 -267.912088)
		(width 0.14478)
		(layer "In13.Cu")
		(net "M_H_CPU1_SB_CS_N<1>")
	)
	(segment
		(start 169.502582 -268.056868)
		(end 169.357802 -267.912088)
		(width 0.14478)
		(layer "In13.Cu")
		(net "M_H_CPU1_SB_CS_N<1>")
	)
	(segment
		(start 145.516346 -266.424664)
		(end 145.034254 -266.424664)
		(width 0.0889)
		(layer "In13.Cu")
		(net "M_H_CPU1_SB_CS_N<1>")
	)
	(segment
		(start 171.032678 -269.160498)
		(end 170.18254 -268.31036)
		(width 0.14478)
		(layer "In13.Cu")
		(net "M_H_CPU1_SB_CS_N<1>")
	)
	(segment
		(start 164.479224 -269.160498)
		(end 161.02203 -265.703304)
		(width 0.14478)
		(layer "In13.Cu")
		(net "M_H_CPU1_SB_CS_N<1>")
	)
	(segment
		(start 171.5262 -269.160498)
		(end 171.032678 -269.160498)
		(width 0.14478)
		(layer "In13.Cu")
		(net "M_H_CPU1_SB_CS_N<1>")
	)
	(segment
		(start 167.849042 -268.16558)
		(end 167.704262 -268.31036)
		(width 0.14478)
		(layer "In13.Cu")
		(net "M_H_CPU1_SB_CS_N<1>")
	)
	(segment
		(start 140.461746 -266.473686)
		(end 140.453364 -266.46886)
		(width 0.0889)
		(layer "In13.Cu")
		(net "M_H_CPU1_SB_CS_N<1>")
	)
	(segment
		(start 170.18254 -268.31036)
		(end 169.647362 -268.31036)
		(width 0.14478)
		(layer "In13.Cu")
		(net "M_H_CPU1_SB_CS_N<1>")
	)
	(segment
		(start 166.125652 -269.160498)
		(end 164.479224 -269.160498)
		(width 0.14478)
		(layer "In13.Cu")
		(net "M_H_CPU1_SB_CS_N<1>")
	)
	(segment
		(start 136.694418 -266.469368)
		(end 136.693402 -266.46886)
		(width 0.0889)
		(layer "In13.Cu")
		(net "M_H_CPU1_SB_CS_N<1>")
	)
	(segment
		(start 168.951402 -268.16558)
		(end 168.806622 -268.31036)
		(width 0.14478)
		(layer "In13.Cu")
		(net "M_H_CPU1_SB_CS_N<1>")
	)
	(segment
		(start 169.502582 -268.16558)
		(end 169.502582 -268.056868)
		(width 0.14478)
		(layer "In13.Cu")
		(net "M_H_CPU1_SB_CS_N<1>")
	)
	(segment
		(start 136.360662 -266.530836)
		(end 136.51484 -266.796266)
		(width 0.0889)
		(layer "In13.Cu")
		(net "M_H_CPU1_SB_CS_N<1>")
	)
	(segment
		(start 168.951402 -268.056868)
		(end 168.951402 -268.16558)
		(width 0.14478)
		(layer "In13.Cu")
		(net "M_H_CPU1_SB_CS_N<1>")
	)
	(segment
		(start 144.242536 -266.486386)
		(end 144.220946 -266.47394)
		(width 0.0889)
		(layer "In13.Cu")
		(net "M_H_CPU1_SB_CS_N<1>")
	)
	(segment
		(start 136.383014 -266.447524)
		(end 136.360662 -266.530836)
		(width 0.0889)
		(layer "In13.Cu")
		(net "M_H_CPU1_SB_CS_N<1>")
	)
	(segment
		(start 171.97197 -268.735302)
		(end 171.951396 -268.735302)
		(width 0.14478)
		(layer "In13.Cu")
		(net "M_H_CPU1_SB_CS_N<1>")
	)
	(segment
		(start 168.400222 -268.056868)
		(end 168.255442 -267.912088)
		(width 0.14478)
		(layer "In13.Cu")
		(net "M_H_CPU1_SB_CS_N<1>")
	)
	(segment
		(start 168.545002 -268.31036)
		(end 168.400222 -268.16558)
		(width 0.14478)
		(layer "In13.Cu")
		(net "M_H_CPU1_SB_CS_N<1>")
	)
	(segment
		(start 168.806622 -268.31036)
		(end 168.545002 -268.31036)
		(width 0.14478)
		(layer "In13.Cu")
		(net "M_H_CPU1_SB_CS_N<1>")
	)
	(arc
		(start 141.967712 -266.473686)
		(mid 141.684756 -266.549863)
		(end 141.4018 -266.473686)
		(width 0.0889)
		(layer "In13.Cu")
		(net "M_H_CPU1_SB_CS_N<1>")
	)
	(arc
		(start 138.581892 -266.473686)
		(mid 138.399641 -266.423336)
		(end 138.216132 -266.46886)
		(width 0.0889)
		(layer "In13.Cu")
		(net "M_H_CPU1_SB_CS_N<1>")
	)
	(arc
		(start 144.20088 -266.46251)
		(mid 144.022802 -266.423526)
		(end 143.847566 -266.473686)
		(width 0.0889)
		(layer "In13.Cu")
		(net "M_H_CPU1_SB_CS_N<1>")
	)
	(arc
		(start 142.341854 -266.473686)
		(mid 142.159603 -266.423336)
		(end 141.976094 -266.46886)
		(width 0.0889)
		(layer "In13.Cu")
		(net "M_H_CPU1_SB_CS_N<1>")
	)
	(arc
		(start 139.521692 -266.473686)
		(mid 139.334748 -266.423397)
		(end 139.147804 -266.473686)
		(width 0.0889)
		(layer "In13.Cu")
		(net "M_H_CPU1_SB_CS_N<1>")
	)
	(arc
		(start 141.393418 -266.46886)
		(mid 141.20991 -266.423366)
		(end 141.027658 -266.473686)
		(width 0.0889)
		(layer "In13.Cu")
		(net "M_H_CPU1_SB_CS_N<1>")
	)
	(arc
		(start 143.281654 -266.473686)
		(mid 143.09471 -266.423431)
		(end 142.907766 -266.473686)
		(width 0.0889)
		(layer "In13.Cu")
		(net "M_H_CPU1_SB_CS_N<1>")
	)
	(arc
		(start 137.267696 -266.473686)
		(mid 136.98474 -266.549863)
		(end 136.701784 -266.473686)
		(width 0.0889)
		(layer "In13.Cu")
		(net "M_H_CPU1_SB_CS_N<1>")
	)
	(arc
		(start 141.027658 -266.473686)
		(mid 140.744702 -266.549863)
		(end 140.461746 -266.473686)
		(width 0.0889)
		(layer "In13.Cu")
		(net "M_H_CPU1_SB_CS_N<1>")
	)
	(arc
		(start 144.785334 -266.473686)
		(mid 144.515565 -266.549709)
		(end 144.242536 -266.486386)
		(width 0.0889)
		(layer "In13.Cu")
		(net "M_H_CPU1_SB_CS_N<1>")
	)
	(arc
		(start 136.693402 -266.46886)
		(mid 136.540532 -266.424219)
		(end 136.383014 -266.447524)
		(width 0.0889)
		(layer "In13.Cu")
		(net "M_H_CPU1_SB_CS_N<1>")
	)
	(arc
		(start 140.087604 -266.473686)
		(mid 139.804648 -266.549863)
		(end 139.521692 -266.473686)
		(width 0.0889)
		(layer "In13.Cu")
		(net "M_H_CPU1_SB_CS_N<1>")
	)
	(arc
		(start 139.147804 -266.473686)
		(mid 138.864848 -266.549863)
		(end 138.581892 -266.473686)
		(width 0.0889)
		(layer "In13.Cu")
		(net "M_H_CPU1_SB_CS_N<1>")
	)
	(arc
		(start 142.907766 -266.473686)
		(mid 142.62481 -266.549863)
		(end 142.341854 -266.473686)
		(width 0.0889)
		(layer "In13.Cu")
		(net "M_H_CPU1_SB_CS_N<1>")
	)
	(arc
		(start 145.034254 -266.424664)
		(mid 144.905683 -266.428326)
		(end 144.785334 -266.473686)
		(width 0.0889)
		(layer "In13.Cu")
		(net "M_H_CPU1_SB_CS_N<1>")
	)
	(arc
		(start 140.453364 -266.46886)
		(mid 140.269856 -266.423366)
		(end 140.087604 -266.473686)
		(width 0.0889)
		(layer "In13.Cu")
		(net "M_H_CPU1_SB_CS_N<1>")
	)
	(arc
		(start 143.847566 -266.473686)
		(mid 143.56461 -266.549863)
		(end 143.281654 -266.473686)
		(width 0.0889)
		(layer "In13.Cu")
		(net "M_H_CPU1_SB_CS_N<1>")
	)
	(arc
		(start 137.641838 -266.473686)
		(mid 137.459587 -266.423336)
		(end 137.276078 -266.46886)
		(width 0.0889)
		(layer "In13.Cu")
		(net "M_H_CPU1_SB_CS_N<1>")
	)
	(arc
		(start 138.20775 -266.473686)
		(mid 137.924794 -266.549863)
		(end 137.641838 -266.473686)
		(width 0.0889)
		(layer "In13.Cu")
		(net "M_H_CPU1_SB_CS_N<1>")
	)
	(segment
		(start 134.63778 -265.720322)
		(end 135.104632 -265.98626)
		(width 0.10668)
		(layer "F.Cu")
		(net "M_H_CPU1_SB_CS_N<0>")
	)
	(segment
		(start 161.203386 -265.248644)
		(end 164.265102 -268.31036)
		(width 0.14478)
		(layer "In13.Cu")
		(net "M_H_CPU1_SB_CS_N<0>")
	)
	(segment
		(start 171.794424 -268.31036)
		(end 172.12691 -268.31036)
		(width 0.0889)
		(layer "In13.Cu")
		(net "M_H_CPU1_SB_CS_N<0>")
	)
	(segment
		(start 134.950708 -265.72083)
		(end 134.97306 -265.637518)
		(width 0.0889)
		(layer "In13.Cu")
		(net "M_H_CPU1_SB_CS_N<0>")
	)
	(segment
		(start 172.12691 -268.31036)
		(end 173.787054 -268.31036)
		(width 0.14478)
		(layer "In13.Cu")
		(net "M_H_CPU1_SB_CS_N<0>")
	)
	(segment
		(start 145.25244 -265.667236)
		(end 145.960084 -265.274044)
		(width 0.0889)
		(layer "In13.Cu")
		(net "M_H_CPU1_SB_CS_N<0>")
	)
	(segment
		(start 135.857742 -265.66368)
		(end 135.866124 -265.658854)
		(width 0.0889)
		(layer "In13.Cu")
		(net "M_H_CPU1_SB_CS_N<0>")
	)
	(segment
		(start 143.377666 -265.66368)
		(end 143.386048 -265.658854)
		(width 0.0889)
		(layer "In13.Cu")
		(net "M_H_CPU1_SB_CS_N<0>")
	)
	(segment
		(start 166.243 -268.31036)
		(end 167.092884 -267.460476)
		(width 0.14478)
		(layer "In13.Cu")
		(net "M_H_CPU1_SB_CS_N<0>")
	)
	(segment
		(start 143.751808 -265.66368)
		(end 143.762222 -265.669776)
		(width 0.0889)
		(layer "In13.Cu")
		(net "M_H_CPU1_SB_CS_N<0>")
	)
	(segment
		(start 164.265102 -268.31036)
		(end 166.243 -268.31036)
		(width 0.14478)
		(layer "In13.Cu")
		(net "M_H_CPU1_SB_CS_N<0>")
	)
	(segment
		(start 148.036788 -265.248644)
		(end 161.203386 -265.248644)
		(width 0.14478)
		(layer "In13.Cu")
		(net "M_H_CPU1_SB_CS_N<0>")
	)
	(segment
		(start 167.092884 -267.460476)
		(end 170.117516 -267.460476)
		(width 0.14478)
		(layer "In13.Cu")
		(net "M_H_CPU1_SB_CS_N<0>")
	)
	(segment
		(start 147.262088 -265.248644)
		(end 148.036788 -265.248644)
		(width 0.0889)
		(layer "In13.Cu")
		(net "M_H_CPU1_SB_CS_N<0>")
	)
	(segment
		(start 144.684242 -265.658854)
		(end 144.692624 -265.66368)
		(width 0.0889)
		(layer "In13.Cu")
		(net "M_H_CPU1_SB_CS_N<0>")
	)
	(segment
		(start 170.117516 -267.460476)
		(end 170.9674 -268.31036)
		(width 0.14478)
		(layer "In13.Cu")
		(net "M_H_CPU1_SB_CS_N<0>")
	)
	(segment
		(start 140.557758 -265.66368)
		(end 140.56614 -265.658854)
		(width 0.0889)
		(layer "In13.Cu")
		(net "M_H_CPU1_SB_CS_N<0>")
	)
	(segment
		(start 170.9674 -268.31036)
		(end 171.794424 -268.31036)
		(width 0.14478)
		(layer "In13.Cu")
		(net "M_H_CPU1_SB_CS_N<0>")
	)
	(segment
		(start 174.211996 -267.885418)
		(end 176.072038 -267.885418)
		(width 0.14478)
		(layer "In13.Cu")
		(net "M_H_CPU1_SB_CS_N<0>")
	)
	(segment
		(start 173.787054 -268.31036)
		(end 174.211996 -267.885418)
		(width 0.14478)
		(layer "In13.Cu")
		(net "M_H_CPU1_SB_CS_N<0>")
	)
	(segment
		(start 145.960084 -265.274044)
		(end 147.236688 -265.274044)
		(width 0.0889)
		(layer "In13.Cu")
		(net "M_H_CPU1_SB_CS_N<0>")
	)
	(segment
		(start 147.236688 -265.274044)
		(end 147.262088 -265.248644)
		(width 0.0889)
		(layer "In13.Cu")
		(net "M_H_CPU1_SB_CS_N<0>")
	)
	(segment
		(start 138.103356 -265.658854)
		(end 138.111738 -265.66368)
		(width 0.0889)
		(layer "In13.Cu")
		(net "M_H_CPU1_SB_CS_N<0>")
	)
	(segment
		(start 142.803372 -265.658854)
		(end 142.811754 -265.66368)
		(width 0.0889)
		(layer "In13.Cu")
		(net "M_H_CPU1_SB_CS_N<0>")
	)
	(segment
		(start 139.617704 -265.66368)
		(end 139.626086 -265.658854)
		(width 0.0889)
		(layer "In13.Cu")
		(net "M_H_CPU1_SB_CS_N<0>")
	)
	(segment
		(start 135.104632 -265.98626)
		(end 134.950708 -265.72083)
		(width 0.0889)
		(layer "In13.Cu")
		(net "M_H_CPU1_SB_CS_N<0>")
	)
	(segment
		(start 139.04341 -265.658854)
		(end 139.051792 -265.66368)
		(width 0.0889)
		(layer "In13.Cu")
		(net "M_H_CPU1_SB_CS_N<0>")
	)
	(arc
		(start 141.497812 -265.66368)
		(mid 141.684756 -265.613425)
		(end 141.8717 -265.66368)
		(width 0.0889)
		(layer "In13.Cu")
		(net "M_H_CPU1_SB_CS_N<0>")
	)
	(arc
		(start 140.56614 -265.658854)
		(mid 140.749648 -265.61336)
		(end 140.9319 -265.66368)
		(width 0.0889)
		(layer "In13.Cu")
		(net "M_H_CPU1_SB_CS_N<0>")
	)
	(arc
		(start 137.737596 -265.66368)
		(mid 137.919847 -265.61333)
		(end 138.103356 -265.658854)
		(width 0.0889)
		(layer "In13.Cu")
		(net "M_H_CPU1_SB_CS_N<0>")
	)
	(arc
		(start 143.762222 -265.669776)
		(mid 144.040908 -265.739996)
		(end 144.317974 -265.66368)
		(width 0.0889)
		(layer "In13.Cu")
		(net "M_H_CPU1_SB_CS_N<0>")
	)
	(arc
		(start 135.29183 -265.66368)
		(mid 135.574786 -265.739857)
		(end 135.857742 -265.66368)
		(width 0.0889)
		(layer "In13.Cu")
		(net "M_H_CPU1_SB_CS_N<0>")
	)
	(arc
		(start 136.231884 -265.66368)
		(mid 136.51484 -265.739857)
		(end 136.797796 -265.66368)
		(width 0.0889)
		(layer "In13.Cu")
		(net "M_H_CPU1_SB_CS_N<0>")
	)
	(arc
		(start 143.386048 -265.658854)
		(mid 143.569556 -265.61336)
		(end 143.751808 -265.66368)
		(width 0.0889)
		(layer "In13.Cu")
		(net "M_H_CPU1_SB_CS_N<0>")
	)
	(arc
		(start 135.866124 -265.658854)
		(mid 136.049632 -265.61336)
		(end 136.231884 -265.66368)
		(width 0.0889)
		(layer "In13.Cu")
		(net "M_H_CPU1_SB_CS_N<0>")
	)
	(arc
		(start 139.051792 -265.66368)
		(mid 139.334748 -265.739857)
		(end 139.617704 -265.66368)
		(width 0.0889)
		(layer "In13.Cu")
		(net "M_H_CPU1_SB_CS_N<0>")
	)
	(arc
		(start 136.797796 -265.66368)
		(mid 136.98474 -265.613425)
		(end 137.171684 -265.66368)
		(width 0.0889)
		(layer "In13.Cu")
		(net "M_H_CPU1_SB_CS_N<0>")
	)
	(arc
		(start 142.437612 -265.66368)
		(mid 142.619863 -265.61333)
		(end 142.803372 -265.658854)
		(width 0.0889)
		(layer "In13.Cu")
		(net "M_H_CPU1_SB_CS_N<0>")
	)
	(arc
		(start 141.8717 -265.66368)
		(mid 142.154656 -265.739857)
		(end 142.437612 -265.66368)
		(width 0.0889)
		(layer "In13.Cu")
		(net "M_H_CPU1_SB_CS_N<0>")
	)
	(arc
		(start 138.111738 -265.66368)
		(mid 138.394694 -265.739857)
		(end 138.67765 -265.66368)
		(width 0.0889)
		(layer "In13.Cu")
		(net "M_H_CPU1_SB_CS_N<0>")
	)
	(arc
		(start 139.991846 -265.66368)
		(mid 140.274802 -265.739857)
		(end 140.557758 -265.66368)
		(width 0.0889)
		(layer "In13.Cu")
		(net "M_H_CPU1_SB_CS_N<0>")
	)
	(arc
		(start 137.171684 -265.66368)
		(mid 137.45464 -265.739857)
		(end 137.737596 -265.66368)
		(width 0.0889)
		(layer "In13.Cu")
		(net "M_H_CPU1_SB_CS_N<0>")
	)
	(arc
		(start 140.9319 -265.66368)
		(mid 141.214856 -265.739857)
		(end 141.497812 -265.66368)
		(width 0.0889)
		(layer "In13.Cu")
		(net "M_H_CPU1_SB_CS_N<0>")
	)
	(arc
		(start 138.67765 -265.66368)
		(mid 138.859901 -265.61333)
		(end 139.04341 -265.658854)
		(width 0.0889)
		(layer "In13.Cu")
		(net "M_H_CPU1_SB_CS_N<0>")
	)
	(arc
		(start 144.692624 -265.66368)
		(mid 144.972052 -265.739846)
		(end 145.25244 -265.667236)
		(width 0.0889)
		(layer "In13.Cu")
		(net "M_H_CPU1_SB_CS_N<0>")
	)
	(arc
		(start 144.317974 -265.66368)
		(mid 144.500479 -265.613203)
		(end 144.684242 -265.658854)
		(width 0.0889)
		(layer "In13.Cu")
		(net "M_H_CPU1_SB_CS_N<0>")
	)
	(arc
		(start 139.626086 -265.658854)
		(mid 139.809594 -265.61336)
		(end 139.991846 -265.66368)
		(width 0.0889)
		(layer "In13.Cu")
		(net "M_H_CPU1_SB_CS_N<0>")
	)
	(arc
		(start 142.811754 -265.66368)
		(mid 143.09471 -265.739857)
		(end 143.377666 -265.66368)
		(width 0.0889)
		(layer "In13.Cu")
		(net "M_H_CPU1_SB_CS_N<0>")
	)
	(arc
		(start 134.97306 -265.637518)
		(mid 135.135392 -265.6147)
		(end 135.29183 -265.66368)
		(width 0.0889)
		(layer "In13.Cu")
		(net "M_H_CPU1_SB_CS_N<0>")
	)
	(segment
		(start 134.63778 -270.580358)
		(end 135.104632 -270.846296)
		(width 0.10668)
		(layer "F.Cu")
		(net "M_H_CPU1_SB_CB<7>")
	)
	(segment
		(start 157.500574 -268.680184)
		(end 160.110932 -271.290542)
		(width 0.14478)
		(layer "In13.Cu")
		(net "M_H_CPU1_SB_CB<7>")
	)
	(segment
		(start 144.75714 -269.73149)
		(end 144.757902 -269.730982)
		(width 0.0889)
		(layer "In13.Cu")
		(net "M_H_CPU1_SB_CB<7>")
	)
	(segment
		(start 168.397936 -273.410426)
		(end 168.659556 -273.410426)
		(width 0.14478)
		(layer "In13.Cu")
		(net "M_H_CPU1_SB_CB<7>")
	)
	(segment
		(start 147.451064 -268.680184)
		(end 148.026882 -268.680184)
		(width 0.0889)
		(layer "In13.Cu")
		(net "M_H_CPU1_SB_CB<7>")
	)
	(segment
		(start 169.355516 -274.2057)
		(end 169.355516 -273.555206)
		(width 0.14478)
		(layer "In13.Cu")
		(net "M_H_CPU1_SB_CB<7>")
	)
	(segment
		(start 135.857742 -270.523716)
		(end 135.866124 -270.51889)
		(width 0.0889)
		(layer "In13.Cu")
		(net "M_H_CPU1_SB_CB<7>")
	)
	(segment
		(start 140.557758 -270.523716)
		(end 140.56614 -270.51889)
		(width 0.0889)
		(layer "In13.Cu")
		(net "M_H_CPU1_SB_CB<7>")
	)
	(segment
		(start 169.500296 -273.410426)
		(end 169.929048 -273.410426)
		(width 0.14478)
		(layer "In13.Cu")
		(net "M_H_CPU1_SB_CB<7>")
	)
	(segment
		(start 142.803372 -270.51889)
		(end 142.811754 -270.523716)
		(width 0.0889)
		(layer "In13.Cu")
		(net "M_H_CPU1_SB_CB<7>")
	)
	(segment
		(start 167.092884 -273.410426)
		(end 167.557196 -273.410426)
		(width 0.14478)
		(layer "In13.Cu")
		(net "M_H_CPU1_SB_CB<7>")
	)
	(segment
		(start 167.846756 -274.35048)
		(end 168.108376 -274.35048)
		(width 0.14478)
		(layer "In13.Cu")
		(net "M_H_CPU1_SB_CB<7>")
	)
	(segment
		(start 168.108376 -274.35048)
		(end 168.253156 -274.2057)
		(width 0.14478)
		(layer "In13.Cu")
		(net "M_H_CPU1_SB_CB<7>")
	)
	(segment
		(start 144.31772 -270.523716)
		(end 144.356836 -270.500856)
		(width 0.0889)
		(layer "In13.Cu")
		(net "M_H_CPU1_SB_CB<7>")
	)
	(segment
		(start 147.293584 -268.837664)
		(end 147.451064 -268.680184)
		(width 0.0889)
		(layer "In13.Cu")
		(net "M_H_CPU1_SB_CB<7>")
	)
	(segment
		(start 167.701976 -274.2057)
		(end 167.846756 -274.35048)
		(width 0.14478)
		(layer "In13.Cu")
		(net "M_H_CPU1_SB_CB<7>")
	)
	(segment
		(start 161.295588 -271.290542)
		(end 164.255704 -274.250658)
		(width 0.14478)
		(layer "In13.Cu")
		(net "M_H_CPU1_SB_CB<7>")
	)
	(segment
		(start 164.255704 -274.250658)
		(end 166.252652 -274.250658)
		(width 0.14478)
		(layer "In13.Cu")
		(net "M_H_CPU1_SB_CB<7>")
	)
	(segment
		(start 166.252652 -274.250658)
		(end 167.092884 -273.410426)
		(width 0.14478)
		(layer "In13.Cu")
		(net "M_H_CPU1_SB_CB<7>")
	)
	(segment
		(start 168.804336 -273.555206)
		(end 168.804336 -274.2057)
		(width 0.14478)
		(layer "In13.Cu")
		(net "M_H_CPU1_SB_CB<7>")
	)
	(segment
		(start 168.253156 -273.555206)
		(end 168.397936 -273.410426)
		(width 0.14478)
		(layer "In13.Cu")
		(net "M_H_CPU1_SB_CB<7>")
	)
	(segment
		(start 139.04341 -270.51889)
		(end 139.051792 -270.523716)
		(width 0.0889)
		(layer "In13.Cu")
		(net "M_H_CPU1_SB_CB<7>")
	)
	(segment
		(start 169.355516 -273.555206)
		(end 169.500296 -273.410426)
		(width 0.14478)
		(layer "In13.Cu")
		(net "M_H_CPU1_SB_CB<7>")
	)
	(segment
		(start 143.377666 -270.523716)
		(end 143.386048 -270.51889)
		(width 0.0889)
		(layer "In13.Cu")
		(net "M_H_CPU1_SB_CB<7>")
	)
	(segment
		(start 170.778932 -274.26031)
		(end 171.5262 -274.26031)
		(width 0.14478)
		(layer "In13.Cu")
		(net "M_H_CPU1_SB_CB<7>")
	)
	(segment
		(start 167.701976 -273.555206)
		(end 167.701976 -274.2057)
		(width 0.14478)
		(layer "In13.Cu")
		(net "M_H_CPU1_SB_CB<7>")
	)
	(segment
		(start 167.557196 -273.410426)
		(end 167.701976 -273.555206)
		(width 0.14478)
		(layer "In13.Cu")
		(net "M_H_CPU1_SB_CB<7>")
	)
	(segment
		(start 138.103356 -270.51889)
		(end 138.111738 -270.523716)
		(width 0.0889)
		(layer "In13.Cu")
		(net "M_H_CPU1_SB_CB<7>")
	)
	(segment
		(start 139.617704 -270.523716)
		(end 139.626086 -270.51889)
		(width 0.0889)
		(layer "In13.Cu")
		(net "M_H_CPU1_SB_CB<7>")
	)
	(segment
		(start 146.639534 -268.837664)
		(end 147.293584 -268.837664)
		(width 0.0889)
		(layer "In13.Cu")
		(net "M_H_CPU1_SB_CB<7>")
	)
	(segment
		(start 134.950708 -270.580866)
		(end 134.97306 -270.497554)
		(width 0.0889)
		(layer "In13.Cu")
		(net "M_H_CPU1_SB_CB<7>")
	)
	(segment
		(start 145.15338 -269.708884)
		(end 145.161762 -269.71371)
		(width 0.0889)
		(layer "In13.Cu")
		(net "M_H_CPU1_SB_CB<7>")
	)
	(segment
		(start 168.804336 -274.2057)
		(end 168.949116 -274.35048)
		(width 0.14478)
		(layer "In13.Cu")
		(net "M_H_CPU1_SB_CB<7>")
	)
	(segment
		(start 144.757902 -269.730982)
		(end 144.78762 -269.71371)
		(width 0.0889)
		(layer "In13.Cu")
		(net "M_H_CPU1_SB_CB<7>")
	)
	(segment
		(start 135.104632 -270.846296)
		(end 134.950708 -270.580866)
		(width 0.0889)
		(layer "In13.Cu")
		(net "M_H_CPU1_SB_CB<7>")
	)
	(segment
		(start 148.026882 -268.680184)
		(end 157.500574 -268.680184)
		(width 0.14478)
		(layer "In13.Cu")
		(net "M_H_CPU1_SB_CB<7>")
	)
	(segment
		(start 168.949116 -274.35048)
		(end 169.210736 -274.35048)
		(width 0.14478)
		(layer "In13.Cu")
		(net "M_H_CPU1_SB_CB<7>")
	)
	(segment
		(start 169.210736 -274.35048)
		(end 169.355516 -274.2057)
		(width 0.14478)
		(layer "In13.Cu")
		(net "M_H_CPU1_SB_CB<7>")
	)
	(segment
		(start 168.253156 -274.2057)
		(end 168.253156 -273.555206)
		(width 0.14478)
		(layer "In13.Cu")
		(net "M_H_CPU1_SB_CB<7>")
	)
	(segment
		(start 168.659556 -273.410426)
		(end 168.804336 -273.555206)
		(width 0.14478)
		(layer "In13.Cu")
		(net "M_H_CPU1_SB_CB<7>")
	)
	(segment
		(start 160.110932 -271.290542)
		(end 161.295588 -271.290542)
		(width 0.14478)
		(layer "In13.Cu")
		(net "M_H_CPU1_SB_CB<7>")
	)
	(segment
		(start 171.5262 -274.26031)
		(end 171.951142 -274.685252)
		(width 0.14478)
		(layer "In13.Cu")
		(net "M_H_CPU1_SB_CB<7>")
	)
	(segment
		(start 145.850356 -269.626842)
		(end 146.639534 -268.837664)
		(width 0.0889)
		(layer "In13.Cu")
		(net "M_H_CPU1_SB_CB<7>")
	)
	(segment
		(start 171.951142 -274.685252)
		(end 171.97197 -274.685252)
		(width 0.14478)
		(layer "In13.Cu")
		(net "M_H_CPU1_SB_CB<7>")
	)
	(segment
		(start 169.929048 -273.410426)
		(end 170.778932 -274.26031)
		(width 0.14478)
		(layer "In13.Cu")
		(net "M_H_CPU1_SB_CB<7>")
	)
	(arc
		(start 138.67765 -270.523716)
		(mid 138.859901 -270.473366)
		(end 139.04341 -270.51889)
		(width 0.0889)
		(layer "In13.Cu")
		(net "M_H_CPU1_SB_CB<7>")
	)
	(arc
		(start 134.97306 -270.497554)
		(mid 135.135392 -270.474736)
		(end 135.29183 -270.523716)
		(width 0.0889)
		(layer "In13.Cu")
		(net "M_H_CPU1_SB_CB<7>")
	)
	(arc
		(start 144.78762 -269.71371)
		(mid 144.969871 -269.66336)
		(end 145.15338 -269.708884)
		(width 0.0889)
		(layer "In13.Cu")
		(net "M_H_CPU1_SB_CB<7>")
	)
	(arc
		(start 140.56614 -270.51889)
		(mid 140.749648 -270.473396)
		(end 140.9319 -270.523716)
		(width 0.0889)
		(layer "In13.Cu")
		(net "M_H_CPU1_SB_CB<7>")
	)
	(arc
		(start 135.866124 -270.51889)
		(mid 136.049632 -270.473396)
		(end 136.231884 -270.523716)
		(width 0.0889)
		(layer "In13.Cu")
		(net "M_H_CPU1_SB_CB<7>")
	)
	(arc
		(start 142.437612 -270.523716)
		(mid 142.619863 -270.473366)
		(end 142.803372 -270.51889)
		(width 0.0889)
		(layer "In13.Cu")
		(net "M_H_CPU1_SB_CB<7>")
	)
	(arc
		(start 144.356836 -270.500856)
		(mid 144.535649 -270.298506)
		(end 144.600168 -270.03629)
		(width 0.0889)
		(layer "In13.Cu")
		(net "M_H_CPU1_SB_CB<7>")
	)
	(arc
		(start 145.727674 -269.71371)
		(mid 145.7927 -269.675481)
		(end 145.850356 -269.626842)
		(width 0.0889)
		(layer "In13.Cu")
		(net "M_H_CPU1_SB_CB<7>")
	)
	(arc
		(start 143.751808 -270.523716)
		(mid 144.034764 -270.599893)
		(end 144.31772 -270.523716)
		(width 0.0889)
		(layer "In13.Cu")
		(net "M_H_CPU1_SB_CB<7>")
	)
	(arc
		(start 136.797796 -270.523716)
		(mid 136.98474 -270.473461)
		(end 137.171684 -270.523716)
		(width 0.0889)
		(layer "In13.Cu")
		(net "M_H_CPU1_SB_CB<7>")
	)
	(arc
		(start 144.600168 -270.03629)
		(mid 144.641717 -269.864868)
		(end 144.75714 -269.73149)
		(width 0.0889)
		(layer "In13.Cu")
		(net "M_H_CPU1_SB_CB<7>")
	)
	(arc
		(start 137.171684 -270.523716)
		(mid 137.45464 -270.599893)
		(end 137.737596 -270.523716)
		(width 0.0889)
		(layer "In13.Cu")
		(net "M_H_CPU1_SB_CB<7>")
	)
	(arc
		(start 142.811754 -270.523716)
		(mid 143.09471 -270.599893)
		(end 143.377666 -270.523716)
		(width 0.0889)
		(layer "In13.Cu")
		(net "M_H_CPU1_SB_CB<7>")
	)
	(arc
		(start 141.8717 -270.523716)
		(mid 142.154656 -270.599893)
		(end 142.437612 -270.523716)
		(width 0.0889)
		(layer "In13.Cu")
		(net "M_H_CPU1_SB_CB<7>")
	)
	(arc
		(start 137.737596 -270.523716)
		(mid 137.919847 -270.473366)
		(end 138.103356 -270.51889)
		(width 0.0889)
		(layer "In13.Cu")
		(net "M_H_CPU1_SB_CB<7>")
	)
	(arc
		(start 139.991846 -270.523716)
		(mid 140.274802 -270.599893)
		(end 140.557758 -270.523716)
		(width 0.0889)
		(layer "In13.Cu")
		(net "M_H_CPU1_SB_CB<7>")
	)
	(arc
		(start 145.161762 -269.71371)
		(mid 145.444718 -269.789887)
		(end 145.727674 -269.71371)
		(width 0.0889)
		(layer "In13.Cu")
		(net "M_H_CPU1_SB_CB<7>")
	)
	(arc
		(start 135.29183 -270.523716)
		(mid 135.574786 -270.599893)
		(end 135.857742 -270.523716)
		(width 0.0889)
		(layer "In13.Cu")
		(net "M_H_CPU1_SB_CB<7>")
	)
	(arc
		(start 138.111738 -270.523716)
		(mid 138.394694 -270.599893)
		(end 138.67765 -270.523716)
		(width 0.0889)
		(layer "In13.Cu")
		(net "M_H_CPU1_SB_CB<7>")
	)
	(arc
		(start 141.497812 -270.523716)
		(mid 141.684756 -270.473461)
		(end 141.8717 -270.523716)
		(width 0.0889)
		(layer "In13.Cu")
		(net "M_H_CPU1_SB_CB<7>")
	)
	(arc
		(start 140.9319 -270.523716)
		(mid 141.214856 -270.599893)
		(end 141.497812 -270.523716)
		(width 0.0889)
		(layer "In13.Cu")
		(net "M_H_CPU1_SB_CB<7>")
	)
	(arc
		(start 139.051792 -270.523716)
		(mid 139.334748 -270.599893)
		(end 139.617704 -270.523716)
		(width 0.0889)
		(layer "In13.Cu")
		(net "M_H_CPU1_SB_CB<7>")
	)
	(arc
		(start 136.231884 -270.523716)
		(mid 136.51484 -270.599893)
		(end 136.797796 -270.523716)
		(width 0.0889)
		(layer "In13.Cu")
		(net "M_H_CPU1_SB_CB<7>")
	)
	(arc
		(start 143.386048 -270.51889)
		(mid 143.569556 -270.473396)
		(end 143.751808 -270.523716)
		(width 0.0889)
		(layer "In13.Cu")
		(net "M_H_CPU1_SB_CB<7>")
	)
	(arc
		(start 139.626086 -270.51889)
		(mid 139.809594 -270.473396)
		(end 139.991846 -270.523716)
		(width 0.0889)
		(layer "In13.Cu")
		(net "M_H_CPU1_SB_CB<7>")
	)
	(segment
		(start 136.047988 -269.770352)
		(end 136.51484 -270.03629)
		(width 0.10668)
		(layer "F.Cu")
		(net "M_H_CPU1_SB_CB<6>")
	)
	(segment
		(start 144.326102 -268.898878)
		(end 144.31772 -268.903704)
		(width 0.0889)
		(layer "In13.Cu")
		(net "M_H_CPU1_SB_CB<6>")
	)
	(segment
		(start 136.360662 -269.77086)
		(end 136.51484 -270.03629)
		(width 0.0889)
		(layer "In13.Cu")
		(net "M_H_CPU1_SB_CB<6>")
	)
	(segment
		(start 170.551856 -272.560288)
		(end 169.701972 -271.710404)
		(width 0.14478)
		(layer "In13.Cu")
		(net "M_H_CPU1_SB_CB<6>")
	)
	(segment
		(start 136.383014 -269.687548)
		(end 136.360662 -269.77086)
		(width 0.0889)
		(layer "In13.Cu")
		(net "M_H_CPU1_SB_CB<6>")
	)
	(segment
		(start 159.075628 -267.922248)
		(end 159.075628 -268.150848)
		(width 0.14478)
		(layer "In13.Cu")
		(net "M_H_CPU1_SB_CB<6>")
	)
	(segment
		(start 167.092884 -271.710404)
		(end 166.243 -272.560288)
		(width 0.14478)
		(layer "In13.Cu")
		(net "M_H_CPU1_SB_CB<6>")
	)
	(segment
		(start 164.265356 -272.560288)
		(end 159.465772 -267.760704)
		(width 0.14478)
		(layer "In13.Cu")
		(net "M_H_CPU1_SB_CB<6>")
	)
	(segment
		(start 159.465772 -267.760704)
		(end 159.237172 -267.760704)
		(width 0.14478)
		(layer "In13.Cu")
		(net "M_H_CPU1_SB_CB<6>")
	)
	(segment
		(start 144.31772 -268.903704)
		(end 144.28597 -268.921992)
		(width 0.0889)
		(layer "In13.Cu")
		(net "M_H_CPU1_SB_CB<6>")
	)
	(segment
		(start 146.138646 -268.436344)
		(end 145.751804 -268.436344)
		(width 0.0889)
		(layer "In13.Cu")
		(net "M_H_CPU1_SB_CB<6>")
	)
	(segment
		(start 141.976094 -269.708884)
		(end 141.967712 -269.71371)
		(width 0.0889)
		(layer "In13.Cu")
		(net "M_H_CPU1_SB_CB<6>")
	)
	(segment
		(start 148.056854 -267.770864)
		(end 146.804126 -267.770864)
		(width 0.0889)
		(layer "In13.Cu")
		(net "M_H_CPU1_SB_CB<6>")
	)
	(segment
		(start 169.701972 -271.710404)
		(end 167.092884 -271.710404)
		(width 0.14478)
		(layer "In13.Cu")
		(net "M_H_CPU1_SB_CB<6>")
	)
	(segment
		(start 171.97197 -272.98523)
		(end 171.547028 -272.560288)
		(width 0.14478)
		(layer "In13.Cu")
		(net "M_H_CPU1_SB_CB<6>")
	)
	(segment
		(start 140.461746 -269.71371)
		(end 140.453364 -269.708884)
		(width 0.0889)
		(layer "In13.Cu")
		(net "M_H_CPU1_SB_CB<6>")
	)
	(segment
		(start 171.547028 -272.560288)
		(end 170.551856 -272.560288)
		(width 0.14478)
		(layer "In13.Cu")
		(net "M_H_CPU1_SB_CB<6>")
	)
	(segment
		(start 166.243 -272.560288)
		(end 164.265356 -272.560288)
		(width 0.14478)
		(layer "In13.Cu")
		(net "M_H_CPU1_SB_CB<6>")
	)
	(segment
		(start 159.075628 -268.150848)
		(end 160.759394 -269.834614)
		(width 0.14478)
		(layer "In13.Cu")
		(net "M_H_CPU1_SB_CB<6>")
	)
	(segment
		(start 160.759394 -270.063214)
		(end 160.59785 -270.224758)
		(width 0.14478)
		(layer "In13.Cu")
		(net "M_H_CPU1_SB_CB<6>")
	)
	(segment
		(start 160.36925 -270.224758)
		(end 157.915356 -267.770864)
		(width 0.14478)
		(layer "In13.Cu")
		(net "M_H_CPU1_SB_CB<6>")
	)
	(segment
		(start 136.701784 -269.71371)
		(end 136.693402 -269.708884)
		(width 0.0889)
		(layer "In13.Cu")
		(net "M_H_CPU1_SB_CB<6>")
	)
	(segment
		(start 160.759394 -269.834614)
		(end 160.759394 -270.063214)
		(width 0.14478)
		(layer "In13.Cu")
		(net "M_H_CPU1_SB_CB<6>")
	)
	(segment
		(start 145.751804 -268.436344)
		(end 145.373344 -268.814804)
		(width 0.0889)
		(layer "In13.Cu")
		(net "M_H_CPU1_SB_CB<6>")
	)
	(segment
		(start 141.4018 -269.71371)
		(end 141.393418 -269.708884)
		(width 0.0889)
		(layer "In13.Cu")
		(net "M_H_CPU1_SB_CB<6>")
	)
	(segment
		(start 137.276078 -269.708884)
		(end 137.267696 -269.71371)
		(width 0.0889)
		(layer "In13.Cu")
		(net "M_H_CPU1_SB_CB<6>")
	)
	(segment
		(start 143.886682 -269.69085)
		(end 143.847566 -269.71371)
		(width 0.0889)
		(layer "In13.Cu")
		(net "M_H_CPU1_SB_CB<6>")
	)
	(segment
		(start 146.804126 -267.770864)
		(end 146.138646 -268.436344)
		(width 0.0889)
		(layer "In13.Cu")
		(net "M_H_CPU1_SB_CB<6>")
	)
	(segment
		(start 160.59785 -270.224758)
		(end 160.36925 -270.224758)
		(width 0.14478)
		(layer "In13.Cu")
		(net "M_H_CPU1_SB_CB<6>")
	)
	(segment
		(start 159.237172 -267.760704)
		(end 159.075628 -267.922248)
		(width 0.14478)
		(layer "In13.Cu")
		(net "M_H_CPU1_SB_CB<6>")
	)
	(segment
		(start 138.216132 -269.708884)
		(end 138.20775 -269.71371)
		(width 0.0889)
		(layer "In13.Cu")
		(net "M_H_CPU1_SB_CB<6>")
	)
	(segment
		(start 157.915356 -267.770864)
		(end 148.056854 -267.770864)
		(width 0.14478)
		(layer "In13.Cu")
		(net "M_H_CPU1_SB_CB<6>")
	)
	(arc
		(start 138.20775 -269.71371)
		(mid 137.924794 -269.789887)
		(end 137.641838 -269.71371)
		(width 0.0889)
		(layer "In13.Cu")
		(net "M_H_CPU1_SB_CB<6>")
	)
	(arc
		(start 142.907766 -269.71371)
		(mid 142.62481 -269.789887)
		(end 142.341854 -269.71371)
		(width 0.0889)
		(layer "In13.Cu")
		(net "M_H_CPU1_SB_CB<6>")
	)
	(arc
		(start 139.521692 -269.71371)
		(mid 139.334748 -269.663455)
		(end 139.147804 -269.71371)
		(width 0.0889)
		(layer "In13.Cu")
		(net "M_H_CPU1_SB_CB<6>")
	)
	(arc
		(start 140.453364 -269.708884)
		(mid 140.269856 -269.66339)
		(end 140.087604 -269.71371)
		(width 0.0889)
		(layer "In13.Cu")
		(net "M_H_CPU1_SB_CB<6>")
	)
	(arc
		(start 142.341854 -269.71371)
		(mid 142.159603 -269.66336)
		(end 141.976094 -269.708884)
		(width 0.0889)
		(layer "In13.Cu")
		(net "M_H_CPU1_SB_CB<6>")
	)
	(arc
		(start 141.967712 -269.71371)
		(mid 141.684756 -269.789887)
		(end 141.4018 -269.71371)
		(width 0.0889)
		(layer "In13.Cu")
		(net "M_H_CPU1_SB_CB<6>")
	)
	(arc
		(start 141.393418 -269.708884)
		(mid 141.20991 -269.66339)
		(end 141.027658 -269.71371)
		(width 0.0889)
		(layer "In13.Cu")
		(net "M_H_CPU1_SB_CB<6>")
	)
	(arc
		(start 145.373344 -268.814804)
		(mid 145.318445 -268.863006)
		(end 145.257774 -268.903704)
		(width 0.0889)
		(layer "In13.Cu")
		(net "M_H_CPU1_SB_CB<6>")
	)
	(arc
		(start 144.28597 -268.921992)
		(mid 144.171294 -269.055326)
		(end 144.130014 -269.226284)
		(width 0.0889)
		(layer "In13.Cu")
		(net "M_H_CPU1_SB_CB<6>")
	)
	(arc
		(start 143.847566 -269.71371)
		(mid 143.56461 -269.789887)
		(end 143.281654 -269.71371)
		(width 0.0889)
		(layer "In13.Cu")
		(net "M_H_CPU1_SB_CB<6>")
	)
	(arc
		(start 144.691862 -268.903704)
		(mid 144.509611 -268.853354)
		(end 144.326102 -268.898878)
		(width 0.0889)
		(layer "In13.Cu")
		(net "M_H_CPU1_SB_CB<6>")
	)
	(arc
		(start 144.130014 -269.226284)
		(mid 144.065499 -269.488503)
		(end 143.886682 -269.69085)
		(width 0.0889)
		(layer "In13.Cu")
		(net "M_H_CPU1_SB_CB<6>")
	)
	(arc
		(start 141.027658 -269.71371)
		(mid 140.744702 -269.789887)
		(end 140.461746 -269.71371)
		(width 0.0889)
		(layer "In13.Cu")
		(net "M_H_CPU1_SB_CB<6>")
	)
	(arc
		(start 140.087604 -269.71371)
		(mid 139.804648 -269.789887)
		(end 139.521692 -269.71371)
		(width 0.0889)
		(layer "In13.Cu")
		(net "M_H_CPU1_SB_CB<6>")
	)
	(arc
		(start 137.641838 -269.71371)
		(mid 137.459587 -269.66336)
		(end 137.276078 -269.708884)
		(width 0.0889)
		(layer "In13.Cu")
		(net "M_H_CPU1_SB_CB<6>")
	)
	(arc
		(start 145.257774 -268.903704)
		(mid 144.974818 -268.979881)
		(end 144.691862 -268.903704)
		(width 0.0889)
		(layer "In13.Cu")
		(net "M_H_CPU1_SB_CB<6>")
	)
	(arc
		(start 143.281654 -269.71371)
		(mid 143.09471 -269.663455)
		(end 142.907766 -269.71371)
		(width 0.0889)
		(layer "In13.Cu")
		(net "M_H_CPU1_SB_CB<6>")
	)
	(arc
		(start 137.267696 -269.71371)
		(mid 136.98474 -269.789887)
		(end 136.701784 -269.71371)
		(width 0.0889)
		(layer "In13.Cu")
		(net "M_H_CPU1_SB_CB<6>")
	)
	(arc
		(start 138.581892 -269.71371)
		(mid 138.399641 -269.66336)
		(end 138.216132 -269.708884)
		(width 0.0889)
		(layer "In13.Cu")
		(net "M_H_CPU1_SB_CB<6>")
	)
	(arc
		(start 136.693402 -269.708884)
		(mid 136.540532 -269.664243)
		(end 136.383014 -269.687548)
		(width 0.0889)
		(layer "In13.Cu")
		(net "M_H_CPU1_SB_CB<6>")
	)
	(arc
		(start 139.147804 -269.71371)
		(mid 138.864848 -269.789887)
		(end 138.581892 -269.71371)
		(width 0.0889)
		(layer "In13.Cu")
		(net "M_H_CPU1_SB_CB<6>")
	)
	(segment
		(start 134.16788 -269.770352)
		(end 134.634732 -270.03629)
		(width 0.10668)
		(layer "F.Cu")
		(net "M_H_CPU1_SB_CB<5>")
	)
	(segment
		(start 136.701784 -270.35887)
		(end 136.693402 -270.363696)
		(width 0.0889)
		(layer "In13.Cu")
		(net "M_H_CPU1_SB_CB<5>")
	)
	(segment
		(start 166.150036 -273.410426)
		(end 164.479478 -273.410426)
		(width 0.14478)
		(layer "In13.Cu")
		(net "M_H_CPU1_SB_CB<5>")
	)
	(segment
		(start 176.072038 -273.835368)
		(end 173.5074 -273.410426)
		(width 0.14478)
		(layer "In13.Cu")
		(net "M_H_CPU1_SB_CB<5>")
	)
	(segment
		(start 164.479478 -273.410426)
		(end 161.910014 -270.840962)
		(width 0.14478)
		(layer "In13.Cu")
		(net "M_H_CPU1_SB_CB<5>")
	)
	(segment
		(start 134.884668 -270.32712)
		(end 134.788656 -270.30172)
		(width 0.0889)
		(layer "In13.Cu")
		(net "M_H_CPU1_SB_CB<5>")
	)
	(segment
		(start 147.502626 -268.225524)
		(end 147.139406 -268.588744)
		(width 0.0889)
		(layer "In13.Cu")
		(net "M_H_CPU1_SB_CB<5>")
	)
	(segment
		(start 144.221708 -270.35887)
		(end 144.213326 -270.363696)
		(width 0.0889)
		(layer "In13.Cu")
		(net "M_H_CPU1_SB_CB<5>")
	)
	(segment
		(start 140.461746 -270.35887)
		(end 140.453364 -270.363696)
		(width 0.0889)
		(layer "In13.Cu")
		(net "M_H_CPU1_SB_CB<5>")
	)
	(segment
		(start 169.815764 -272.560288)
		(end 167.000174 -272.560288)
		(width 0.14478)
		(layer "In13.Cu")
		(net "M_H_CPU1_SB_CB<5>")
	)
	(segment
		(start 157.682184 -268.225524)
		(end 148.06676 -268.225524)
		(width 0.14478)
		(layer "In13.Cu")
		(net "M_H_CPU1_SB_CB<5>")
	)
	(segment
		(start 173.5074 -273.410426)
		(end 170.665902 -273.410426)
		(width 0.14478)
		(layer "In13.Cu")
		(net "M_H_CPU1_SB_CB<5>")
	)
	(segment
		(start 138.216132 -270.363696)
		(end 138.20775 -270.35887)
		(width 0.0889)
		(layer "In13.Cu")
		(net "M_H_CPU1_SB_CB<5>")
	)
	(segment
		(start 146.592036 -268.588744)
		(end 145.631916 -269.548864)
		(width 0.0889)
		(layer "In13.Cu")
		(net "M_H_CPU1_SB_CB<5>")
	)
	(segment
		(start 134.788656 -270.30172)
		(end 134.634732 -270.03629)
		(width 0.0889)
		(layer "In13.Cu")
		(net "M_H_CPU1_SB_CB<5>")
	)
	(segment
		(start 160.297622 -270.840962)
		(end 157.682184 -268.225524)
		(width 0.14478)
		(layer "In13.Cu")
		(net "M_H_CPU1_SB_CB<5>")
	)
	(segment
		(start 137.276078 -270.363696)
		(end 137.267696 -270.35887)
		(width 0.0889)
		(layer "In13.Cu")
		(net "M_H_CPU1_SB_CB<5>")
	)
	(segment
		(start 167.000174 -272.560288)
		(end 166.150036 -273.410426)
		(width 0.14478)
		(layer "In13.Cu")
		(net "M_H_CPU1_SB_CB<5>")
	)
	(segment
		(start 147.139406 -268.588744)
		(end 146.592036 -268.588744)
		(width 0.0889)
		(layer "In13.Cu")
		(net "M_H_CPU1_SB_CB<5>")
	)
	(segment
		(start 170.665902 -273.410426)
		(end 169.815764 -272.560288)
		(width 0.14478)
		(layer "In13.Cu")
		(net "M_H_CPU1_SB_CB<5>")
	)
	(segment
		(start 141.976094 -270.363696)
		(end 141.967712 -270.35887)
		(width 0.0889)
		(layer "In13.Cu")
		(net "M_H_CPU1_SB_CB<5>")
	)
	(segment
		(start 135.76173 -270.35887)
		(end 135.753348 -270.363696)
		(width 0.0889)
		(layer "In13.Cu")
		(net "M_H_CPU1_SB_CB<5>")
	)
	(segment
		(start 148.06676 -268.225524)
		(end 147.502626 -268.225524)
		(width 0.0889)
		(layer "In13.Cu")
		(net "M_H_CPU1_SB_CB<5>")
	)
	(segment
		(start 144.691862 -269.548864)
		(end 144.652746 -269.571724)
		(width 0.0889)
		(layer "In13.Cu")
		(net "M_H_CPU1_SB_CB<5>")
	)
	(segment
		(start 141.4018 -270.35887)
		(end 141.393418 -270.363696)
		(width 0.0889)
		(layer "In13.Cu")
		(net "M_H_CPU1_SB_CB<5>")
	)
	(segment
		(start 144.253458 -270.340582)
		(end 144.221708 -270.35887)
		(width 0.0889)
		(layer "In13.Cu")
		(net "M_H_CPU1_SB_CB<5>")
	)
	(segment
		(start 145.266156 -269.55369)
		(end 145.257774 -269.548864)
		(width 0.0889)
		(layer "In13.Cu")
		(net "M_H_CPU1_SB_CB<5>")
	)
	(segment
		(start 161.910014 -270.840962)
		(end 160.297622 -270.840962)
		(width 0.14478)
		(layer "In13.Cu")
		(net "M_H_CPU1_SB_CB<5>")
	)
	(arc
		(start 145.257774 -269.548864)
		(mid 144.974818 -269.472687)
		(end 144.691862 -269.548864)
		(width 0.0889)
		(layer "In13.Cu")
		(net "M_H_CPU1_SB_CB<5>")
	)
	(arc
		(start 137.267696 -270.35887)
		(mid 136.98474 -270.282693)
		(end 136.701784 -270.35887)
		(width 0.0889)
		(layer "In13.Cu")
		(net "M_H_CPU1_SB_CB<5>")
	)
	(arc
		(start 142.907766 -270.35887)
		(mid 142.62481 -270.282693)
		(end 142.341854 -270.35887)
		(width 0.0889)
		(layer "In13.Cu")
		(net "M_H_CPU1_SB_CB<5>")
	)
	(arc
		(start 141.027658 -270.35887)
		(mid 140.744702 -270.282693)
		(end 140.461746 -270.35887)
		(width 0.0889)
		(layer "In13.Cu")
		(net "M_H_CPU1_SB_CB<5>")
	)
	(arc
		(start 144.213326 -270.363696)
		(mid 144.029818 -270.40919)
		(end 143.847566 -270.35887)
		(width 0.0889)
		(layer "In13.Cu")
		(net "M_H_CPU1_SB_CB<5>")
	)
	(arc
		(start 145.631916 -269.548864)
		(mid 145.449665 -269.599214)
		(end 145.266156 -269.55369)
		(width 0.0889)
		(layer "In13.Cu")
		(net "M_H_CPU1_SB_CB<5>")
	)
	(arc
		(start 136.327642 -270.35887)
		(mid 136.044686 -270.282693)
		(end 135.76173 -270.35887)
		(width 0.0889)
		(layer "In13.Cu")
		(net "M_H_CPU1_SB_CB<5>")
	)
	(arc
		(start 144.652746 -269.571724)
		(mid 144.473933 -269.774074)
		(end 144.409414 -270.03629)
		(width 0.0889)
		(layer "In13.Cu")
		(net "M_H_CPU1_SB_CB<5>")
	)
	(arc
		(start 140.087604 -270.35887)
		(mid 139.804648 -270.282693)
		(end 139.521692 -270.35887)
		(width 0.0889)
		(layer "In13.Cu")
		(net "M_H_CPU1_SB_CB<5>")
	)
	(arc
		(start 140.453364 -270.363696)
		(mid 140.269856 -270.40919)
		(end 140.087604 -270.35887)
		(width 0.0889)
		(layer "In13.Cu")
		(net "M_H_CPU1_SB_CB<5>")
	)
	(arc
		(start 135.753348 -270.363696)
		(mid 135.56984 -270.40919)
		(end 135.387588 -270.35887)
		(width 0.0889)
		(layer "In13.Cu")
		(net "M_H_CPU1_SB_CB<5>")
	)
	(arc
		(start 135.387588 -270.35887)
		(mid 135.139875 -270.28365)
		(end 134.884668 -270.32712)
		(width 0.0889)
		(layer "In13.Cu")
		(net "M_H_CPU1_SB_CB<5>")
	)
	(arc
		(start 141.967712 -270.35887)
		(mid 141.684756 -270.282693)
		(end 141.4018 -270.35887)
		(width 0.0889)
		(layer "In13.Cu")
		(net "M_H_CPU1_SB_CB<5>")
	)
	(arc
		(start 144.409414 -270.03629)
		(mid 144.368159 -270.207261)
		(end 144.253458 -270.340582)
		(width 0.0889)
		(layer "In13.Cu")
		(net "M_H_CPU1_SB_CB<5>")
	)
	(arc
		(start 138.20775 -270.35887)
		(mid 137.924794 -270.282693)
		(end 137.641838 -270.35887)
		(width 0.0889)
		(layer "In13.Cu")
		(net "M_H_CPU1_SB_CB<5>")
	)
	(arc
		(start 137.641838 -270.35887)
		(mid 137.459587 -270.40922)
		(end 137.276078 -270.363696)
		(width 0.0889)
		(layer "In13.Cu")
		(net "M_H_CPU1_SB_CB<5>")
	)
	(arc
		(start 139.147804 -270.35887)
		(mid 138.864848 -270.282693)
		(end 138.581892 -270.35887)
		(width 0.0889)
		(layer "In13.Cu")
		(net "M_H_CPU1_SB_CB<5>")
	)
	(arc
		(start 143.847566 -270.35887)
		(mid 143.56461 -270.282693)
		(end 143.281654 -270.35887)
		(width 0.0889)
		(layer "In13.Cu")
		(net "M_H_CPU1_SB_CB<5>")
	)
	(arc
		(start 141.393418 -270.363696)
		(mid 141.20991 -270.40919)
		(end 141.027658 -270.35887)
		(width 0.0889)
		(layer "In13.Cu")
		(net "M_H_CPU1_SB_CB<5>")
	)
	(arc
		(start 136.693402 -270.363696)
		(mid 136.509894 -270.40919)
		(end 136.327642 -270.35887)
		(width 0.0889)
		(layer "In13.Cu")
		(net "M_H_CPU1_SB_CB<5>")
	)
	(arc
		(start 139.521692 -270.35887)
		(mid 139.334748 -270.409125)
		(end 139.147804 -270.35887)
		(width 0.0889)
		(layer "In13.Cu")
		(net "M_H_CPU1_SB_CB<5>")
	)
	(arc
		(start 143.281654 -270.35887)
		(mid 143.09471 -270.409125)
		(end 142.907766 -270.35887)
		(width 0.0889)
		(layer "In13.Cu")
		(net "M_H_CPU1_SB_CB<5>")
	)
	(arc
		(start 138.581892 -270.35887)
		(mid 138.399641 -270.40922)
		(end 138.216132 -270.363696)
		(width 0.0889)
		(layer "In13.Cu")
		(net "M_H_CPU1_SB_CB<5>")
	)
	(arc
		(start 142.341854 -270.35887)
		(mid 142.159603 -270.40922)
		(end 141.976094 -270.363696)
		(width 0.0889)
		(layer "In13.Cu")
		(net "M_H_CPU1_SB_CB<5>")
	)
	(segment
		(start 135.577834 -268.960346)
		(end 136.044686 -269.226284)
		(width 0.10668)
		(layer "F.Cu")
		(net "M_H_CPU1_SB_CB<4>")
	)
	(segment
		(start 173.828964 -271.71015)
		(end 175.646842 -271.71015)
		(width 0.14478)
		(layer "In13.Cu")
		(net "M_H_CPU1_SB_CB<4>")
	)
	(segment
		(start 173.684184 -272.331434)
		(end 173.684184 -271.85493)
		(width 0.14478)
		(layer "In13.Cu")
		(net "M_H_CPU1_SB_CB<4>")
	)
	(segment
		(start 173.684184 -271.85493)
		(end 173.828964 -271.71015)
		(width 0.14478)
		(layer "In13.Cu")
		(net "M_H_CPU1_SB_CB<4>")
	)
	(segment
		(start 147.992084 -267.311124)
		(end 159.942276 -267.311124)
		(width 0.14478)
		(layer "In13.Cu")
		(net "M_H_CPU1_SB_CB<4>")
	)
	(segment
		(start 139.04341 -269.55369)
		(end 139.051792 -269.548864)
		(width 0.0889)
		(layer "In13.Cu")
		(net "M_H_CPU1_SB_CB<4>")
	)
	(segment
		(start 173.539404 -272.476214)
		(end 173.684184 -272.331434)
		(width 0.14478)
		(layer "In13.Cu")
		(net "M_H_CPU1_SB_CB<4>")
	)
	(segment
		(start 159.942276 -267.311124)
		(end 164.341302 -271.71015)
		(width 0.14478)
		(layer "In13.Cu")
		(net "M_H_CPU1_SB_CB<4>")
	)
	(segment
		(start 140.557758 -269.548864)
		(end 140.56614 -269.55369)
		(width 0.0889)
		(layer "In13.Cu")
		(net "M_H_CPU1_SB_CB<4>")
	)
	(segment
		(start 145.725642 -268.192758)
		(end 146.070066 -268.192758)
		(width 0.0889)
		(layer "In13.Cu")
		(net "M_H_CPU1_SB_CB<4>")
	)
	(segment
		(start 172.988224 -271.71015)
		(end 173.133004 -271.85493)
		(width 0.14478)
		(layer "In13.Cu")
		(net "M_H_CPU1_SB_CB<4>")
	)
	(segment
		(start 136.044686 -269.226284)
		(end 136.198864 -269.491714)
		(width 0.0889)
		(layer "In13.Cu")
		(net "M_H_CPU1_SB_CB<4>")
	)
	(segment
		(start 166.3573 -271.71015)
		(end 167.207184 -270.860266)
		(width 0.14478)
		(layer "In13.Cu")
		(net "M_H_CPU1_SB_CB<4>")
	)
	(segment
		(start 146.9517 -267.311124)
		(end 147.992084 -267.311124)
		(width 0.0889)
		(layer "In13.Cu")
		(net "M_H_CPU1_SB_CB<4>")
	)
	(segment
		(start 146.070066 -268.192758)
		(end 146.9517 -267.311124)
		(width 0.0889)
		(layer "In13.Cu")
		(net "M_H_CPU1_SB_CB<4>")
	)
	(segment
		(start 170.540172 -271.71015)
		(end 172.988224 -271.71015)
		(width 0.14478)
		(layer "In13.Cu")
		(net "M_H_CPU1_SB_CB<4>")
	)
	(segment
		(start 136.198864 -269.491714)
		(end 136.29513 -269.517114)
		(width 0.0889)
		(layer "In13.Cu")
		(net "M_H_CPU1_SB_CB<4>")
	)
	(segment
		(start 145.23847 -268.67993)
		(end 145.725642 -268.192758)
		(width 0.0889)
		(layer "In13.Cu")
		(net "M_H_CPU1_SB_CB<4>")
	)
	(segment
		(start 143.377666 -269.548864)
		(end 143.386048 -269.55369)
		(width 0.0889)
		(layer "In13.Cu")
		(net "M_H_CPU1_SB_CB<4>")
	)
	(segment
		(start 173.133004 -271.85493)
		(end 173.133004 -272.331434)
		(width 0.14478)
		(layer "In13.Cu")
		(net "M_H_CPU1_SB_CB<4>")
	)
	(segment
		(start 142.803372 -269.55369)
		(end 142.811754 -269.548864)
		(width 0.0889)
		(layer "In13.Cu")
		(net "M_H_CPU1_SB_CB<4>")
	)
	(segment
		(start 167.207184 -270.860266)
		(end 169.690288 -270.860266)
		(width 0.14478)
		(layer "In13.Cu")
		(net "M_H_CPU1_SB_CB<4>")
	)
	(segment
		(start 143.751808 -269.548864)
		(end 143.782288 -269.531084)
		(width 0.0889)
		(layer "In13.Cu")
		(net "M_H_CPU1_SB_CB<4>")
	)
	(segment
		(start 169.690288 -270.860266)
		(end 170.540172 -271.71015)
		(width 0.14478)
		(layer "In13.Cu")
		(net "M_H_CPU1_SB_CB<4>")
	)
	(segment
		(start 144.182592 -268.761718)
		(end 144.221708 -268.738858)
		(width 0.0889)
		(layer "In13.Cu")
		(net "M_H_CPU1_SB_CB<4>")
	)
	(segment
		(start 175.646842 -271.71015)
		(end 176.072038 -272.135346)
		(width 0.14478)
		(layer "In13.Cu")
		(net "M_H_CPU1_SB_CB<4>")
	)
	(segment
		(start 139.617704 -269.548864)
		(end 139.626086 -269.55369)
		(width 0.0889)
		(layer "In13.Cu")
		(net "M_H_CPU1_SB_CB<4>")
	)
	(segment
		(start 164.341302 -271.71015)
		(end 166.3573 -271.71015)
		(width 0.14478)
		(layer "In13.Cu")
		(net "M_H_CPU1_SB_CB<4>")
	)
	(segment
		(start 173.133004 -272.331434)
		(end 173.277784 -272.476214)
		(width 0.14478)
		(layer "In13.Cu")
		(net "M_H_CPU1_SB_CB<4>")
	)
	(segment
		(start 138.103356 -269.55369)
		(end 138.111738 -269.548864)
		(width 0.0889)
		(layer "In13.Cu")
		(net "M_H_CPU1_SB_CB<4>")
	)
	(segment
		(start 173.277784 -272.476214)
		(end 173.539404 -272.476214)
		(width 0.14478)
		(layer "In13.Cu")
		(net "M_H_CPU1_SB_CB<4>")
	)
	(arc
		(start 143.386048 -269.55369)
		(mid 143.569556 -269.599184)
		(end 143.751808 -269.548864)
		(width 0.0889)
		(layer "In13.Cu")
		(net "M_H_CPU1_SB_CB<4>")
	)
	(arc
		(start 143.782288 -269.531084)
		(mid 143.897715 -269.397708)
		(end 143.93926 -269.226284)
		(width 0.0889)
		(layer "In13.Cu")
		(net "M_H_CPU1_SB_CB<4>")
	)
	(arc
		(start 140.56614 -269.55369)
		(mid 140.749648 -269.599184)
		(end 140.9319 -269.548864)
		(width 0.0889)
		(layer "In13.Cu")
		(net "M_H_CPU1_SB_CB<4>")
	)
	(arc
		(start 136.797796 -269.548864)
		(mid 136.98474 -269.599119)
		(end 137.171684 -269.548864)
		(width 0.0889)
		(layer "In13.Cu")
		(net "M_H_CPU1_SB_CB<4>")
	)
	(arc
		(start 143.93926 -269.226284)
		(mid 144.003775 -268.964065)
		(end 144.182592 -268.761718)
		(width 0.0889)
		(layer "In13.Cu")
		(net "M_H_CPU1_SB_CB<4>")
	)
	(arc
		(start 140.9319 -269.548864)
		(mid 141.214856 -269.472687)
		(end 141.497812 -269.548864)
		(width 0.0889)
		(layer "In13.Cu")
		(net "M_H_CPU1_SB_CB<4>")
	)
	(arc
		(start 141.8717 -269.548864)
		(mid 142.154656 -269.472687)
		(end 142.437612 -269.548864)
		(width 0.0889)
		(layer "In13.Cu")
		(net "M_H_CPU1_SB_CB<4>")
	)
	(arc
		(start 141.497812 -269.548864)
		(mid 141.684756 -269.599119)
		(end 141.8717 -269.548864)
		(width 0.0889)
		(layer "In13.Cu")
		(net "M_H_CPU1_SB_CB<4>")
	)
	(arc
		(start 139.991846 -269.548864)
		(mid 140.274802 -269.472687)
		(end 140.557758 -269.548864)
		(width 0.0889)
		(layer "In13.Cu")
		(net "M_H_CPU1_SB_CB<4>")
	)
	(arc
		(start 144.78762 -268.738858)
		(mid 145.023089 -268.786103)
		(end 145.23847 -268.67993)
		(width 0.0889)
		(layer "In13.Cu")
		(net "M_H_CPU1_SB_CB<4>")
	)
	(arc
		(start 137.737596 -269.548864)
		(mid 137.919847 -269.599214)
		(end 138.103356 -269.55369)
		(width 0.0889)
		(layer "In13.Cu")
		(net "M_H_CPU1_SB_CB<4>")
	)
	(arc
		(start 144.221708 -268.738858)
		(mid 144.504664 -268.662681)
		(end 144.78762 -268.738858)
		(width 0.0889)
		(layer "In13.Cu")
		(net "M_H_CPU1_SB_CB<4>")
	)
	(arc
		(start 142.437612 -269.548864)
		(mid 142.619863 -269.599214)
		(end 142.803372 -269.55369)
		(width 0.0889)
		(layer "In13.Cu")
		(net "M_H_CPU1_SB_CB<4>")
	)
	(arc
		(start 136.29513 -269.517114)
		(mid 136.550195 -269.473763)
		(end 136.797796 -269.548864)
		(width 0.0889)
		(layer "In13.Cu")
		(net "M_H_CPU1_SB_CB<4>")
	)
	(arc
		(start 142.811754 -269.548864)
		(mid 143.09471 -269.472687)
		(end 143.377666 -269.548864)
		(width 0.0889)
		(layer "In13.Cu")
		(net "M_H_CPU1_SB_CB<4>")
	)
	(arc
		(start 138.111738 -269.548864)
		(mid 138.394694 -269.472687)
		(end 138.67765 -269.548864)
		(width 0.0889)
		(layer "In13.Cu")
		(net "M_H_CPU1_SB_CB<4>")
	)
	(arc
		(start 139.626086 -269.55369)
		(mid 139.809594 -269.599184)
		(end 139.991846 -269.548864)
		(width 0.0889)
		(layer "In13.Cu")
		(net "M_H_CPU1_SB_CB<4>")
	)
	(arc
		(start 137.171684 -269.548864)
		(mid 137.45464 -269.472687)
		(end 137.737596 -269.548864)
		(width 0.0889)
		(layer "In13.Cu")
		(net "M_H_CPU1_SB_CB<4>")
	)
	(arc
		(start 138.67765 -269.548864)
		(mid 138.859901 -269.599214)
		(end 139.04341 -269.55369)
		(width 0.0889)
		(layer "In13.Cu")
		(net "M_H_CPU1_SB_CB<4>")
	)
	(arc
		(start 139.051792 -269.548864)
		(mid 139.334748 -269.472687)
		(end 139.617704 -269.548864)
		(width 0.0889)
		(layer "In13.Cu")
		(net "M_H_CPU1_SB_CB<4>")
	)
	(segment
		(start 134.63778 -273.820382)
		(end 135.104632 -274.08632)
		(width 0.10668)
		(layer "F.Cu")
		(net "M_H_CPU1_SB_CB<3>")
	)
	(segment
		(start 147.348702 -272.492724)
		(end 146.974052 -272.492724)
		(width 0.0889)
		(layer "In13.Cu")
		(net "M_H_CPU1_SB_CB<3>")
	)
	(segment
		(start 158.735014 -276.065742)
		(end 155.052776 -272.383504)
		(width 0.14478)
		(layer "In13.Cu")
		(net "M_H_CPU1_SB_CB<3>")
	)
	(segment
		(start 171.032678 -281.060398)
		(end 170.18254 -280.21026)
		(width 0.14478)
		(layer "In13.Cu")
		(net "M_H_CPU1_SB_CB<3>")
	)
	(segment
		(start 160.52419 -277.626318)
		(end 160.29559 -277.626318)
		(width 0.14478)
		(layer "In13.Cu")
		(net "M_H_CPU1_SB_CB<3>")
	)
	(segment
		(start 160.775142 -277.375366)
		(end 160.52419 -277.626318)
		(width 0.14478)
		(layer "In13.Cu")
		(net "M_H_CPU1_SB_CB<3>")
	)
	(segment
		(start 134.97306 -273.737578)
		(end 134.950708 -273.82089)
		(width 0.0889)
		(layer "In13.Cu")
		(net "M_H_CPU1_SB_CB<3>")
	)
	(segment
		(start 160.384998 -276.756622)
		(end 160.223454 -276.595078)
		(width 0.14478)
		(layer "In13.Cu")
		(net "M_H_CPU1_SB_CB<3>")
	)
	(segment
		(start 158.963614 -276.065742)
		(end 158.735014 -276.065742)
		(width 0.14478)
		(layer "In13.Cu")
		(net "M_H_CPU1_SB_CB<3>")
	)
	(segment
		(start 171.97197 -280.635202)
		(end 171.546774 -281.060398)
		(width 0.14478)
		(layer "In13.Cu")
		(net "M_H_CPU1_SB_CB<3>")
	)
	(segment
		(start 159.214566 -275.81479)
		(end 158.963614 -276.065742)
		(width 0.14478)
		(layer "In13.Cu")
		(net "M_H_CPU1_SB_CB<3>")
	)
	(segment
		(start 170.18254 -280.21026)
		(end 167.000174 -280.21026)
		(width 0.14478)
		(layer "In13.Cu")
		(net "M_H_CPU1_SB_CB<3>")
	)
	(segment
		(start 155.052776 -272.383504)
		(end 148.025104 -272.383504)
		(width 0.14478)
		(layer "In13.Cu")
		(net "M_H_CPU1_SB_CB<3>")
	)
	(segment
		(start 159.443166 -275.81479)
		(end 159.214566 -275.81479)
		(width 0.14478)
		(layer "In13.Cu")
		(net "M_H_CPU1_SB_CB<3>")
	)
	(segment
		(start 147.457922 -272.383504)
		(end 147.348702 -272.492724)
		(width 0.0889)
		(layer "In13.Cu")
		(net "M_H_CPU1_SB_CB<3>")
	)
	(segment
		(start 160.134046 -277.464774)
		(end 160.134046 -277.236174)
		(width 0.14478)
		(layer "In13.Cu")
		(net "M_H_CPU1_SB_CB<3>")
	)
	(segment
		(start 159.515302 -276.84603)
		(end 159.353758 -276.684486)
		(width 0.14478)
		(layer "In13.Cu")
		(net "M_H_CPU1_SB_CB<3>")
	)
	(segment
		(start 138.111738 -273.76374)
		(end 138.103356 -273.758914)
		(width 0.0889)
		(layer "In13.Cu")
		(net "M_H_CPU1_SB_CB<3>")
	)
	(segment
		(start 134.950708 -273.82089)
		(end 135.104632 -274.08632)
		(width 0.0889)
		(layer "In13.Cu")
		(net "M_H_CPU1_SB_CB<3>")
	)
	(segment
		(start 160.134046 -277.236174)
		(end 160.384998 -276.985222)
		(width 0.14478)
		(layer "In13.Cu")
		(net "M_H_CPU1_SB_CB<3>")
	)
	(segment
		(start 159.60471 -276.204934)
		(end 159.60471 -275.976334)
		(width 0.14478)
		(layer "In13.Cu")
		(net "M_H_CPU1_SB_CB<3>")
	)
	(segment
		(start 161.003742 -277.375366)
		(end 160.775142 -277.375366)
		(width 0.14478)
		(layer "In13.Cu")
		(net "M_H_CPU1_SB_CB<3>")
	)
	(segment
		(start 160.384998 -276.985222)
		(end 160.384998 -276.756622)
		(width 0.14478)
		(layer "In13.Cu")
		(net "M_H_CPU1_SB_CB<3>")
	)
	(segment
		(start 159.60471 -275.976334)
		(end 159.443166 -275.81479)
		(width 0.14478)
		(layer "In13.Cu")
		(net "M_H_CPU1_SB_CB<3>")
	)
	(segment
		(start 135.866124 -273.758914)
		(end 135.857742 -273.76374)
		(width 0.0889)
		(layer "In13.Cu")
		(net "M_H_CPU1_SB_CB<3>")
	)
	(segment
		(start 140.56614 -273.758914)
		(end 140.557758 -273.76374)
		(width 0.0889)
		(layer "In13.Cu")
		(net "M_H_CPU1_SB_CB<3>")
	)
	(segment
		(start 166.150036 -281.060398)
		(end 164.688774 -281.060398)
		(width 0.14478)
		(layer "In13.Cu")
		(net "M_H_CPU1_SB_CB<3>")
	)
	(segment
		(start 159.353758 -276.455886)
		(end 159.60471 -276.204934)
		(width 0.14478)
		(layer "In13.Cu")
		(net "M_H_CPU1_SB_CB<3>")
	)
	(segment
		(start 143.386048 -273.758914)
		(end 143.377666 -273.76374)
		(width 0.0889)
		(layer "In13.Cu")
		(net "M_H_CPU1_SB_CB<3>")
	)
	(segment
		(start 146.974052 -272.492724)
		(end 145.92173 -273.545046)
		(width 0.0889)
		(layer "In13.Cu")
		(net "M_H_CPU1_SB_CB<3>")
	)
	(segment
		(start 159.994854 -276.595078)
		(end 159.743902 -276.84603)
		(width 0.14478)
		(layer "In13.Cu")
		(net "M_H_CPU1_SB_CB<3>")
	)
	(segment
		(start 160.223454 -276.595078)
		(end 159.994854 -276.595078)
		(width 0.14478)
		(layer "In13.Cu")
		(net "M_H_CPU1_SB_CB<3>")
	)
	(segment
		(start 164.688774 -281.060398)
		(end 161.003742 -277.375366)
		(width 0.14478)
		(layer "In13.Cu")
		(net "M_H_CPU1_SB_CB<3>")
	)
	(segment
		(start 171.546774 -281.060398)
		(end 171.032678 -281.060398)
		(width 0.14478)
		(layer "In13.Cu")
		(net "M_H_CPU1_SB_CB<3>")
	)
	(segment
		(start 139.626086 -273.758914)
		(end 139.617704 -273.76374)
		(width 0.0889)
		(layer "In13.Cu")
		(net "M_H_CPU1_SB_CB<3>")
	)
	(segment
		(start 143.762222 -273.769836)
		(end 143.751808 -273.76374)
		(width 0.0889)
		(layer "In13.Cu")
		(net "M_H_CPU1_SB_CB<3>")
	)
	(segment
		(start 144.692624 -273.76374)
		(end 144.684242 -273.758914)
		(width 0.0889)
		(layer "In13.Cu")
		(net "M_H_CPU1_SB_CB<3>")
	)
	(segment
		(start 142.811754 -273.76374)
		(end 142.803372 -273.758914)
		(width 0.0889)
		(layer "In13.Cu")
		(net "M_H_CPU1_SB_CB<3>")
	)
	(segment
		(start 159.743902 -276.84603)
		(end 159.515302 -276.84603)
		(width 0.14478)
		(layer "In13.Cu")
		(net "M_H_CPU1_SB_CB<3>")
	)
	(segment
		(start 167.000174 -280.21026)
		(end 166.150036 -281.060398)
		(width 0.14478)
		(layer "In13.Cu")
		(net "M_H_CPU1_SB_CB<3>")
	)
	(segment
		(start 139.051792 -273.76374)
		(end 139.04341 -273.758914)
		(width 0.0889)
		(layer "In13.Cu")
		(net "M_H_CPU1_SB_CB<3>")
	)
	(segment
		(start 160.29559 -277.626318)
		(end 160.134046 -277.464774)
		(width 0.14478)
		(layer "In13.Cu")
		(net "M_H_CPU1_SB_CB<3>")
	)
	(segment
		(start 159.353758 -276.684486)
		(end 159.353758 -276.455886)
		(width 0.14478)
		(layer "In13.Cu")
		(net "M_H_CPU1_SB_CB<3>")
	)
	(segment
		(start 148.025104 -272.383504)
		(end 147.457922 -272.383504)
		(width 0.0889)
		(layer "In13.Cu")
		(net "M_H_CPU1_SB_CB<3>")
	)
	(arc
		(start 142.437612 -273.76374)
		(mid 142.154656 -273.839917)
		(end 141.8717 -273.76374)
		(width 0.0889)
		(layer "In13.Cu")
		(net "M_H_CPU1_SB_CB<3>")
	)
	(arc
		(start 135.29183 -273.76374)
		(mid 135.135392 -273.714769)
		(end 134.97306 -273.737578)
		(width 0.0889)
		(layer "In13.Cu")
		(net "M_H_CPU1_SB_CB<3>")
	)
	(arc
		(start 141.8717 -273.76374)
		(mid 141.684756 -273.713485)
		(end 141.497812 -273.76374)
		(width 0.0889)
		(layer "In13.Cu")
		(net "M_H_CPU1_SB_CB<3>")
	)
	(arc
		(start 135.857742 -273.76374)
		(mid 135.574786 -273.839917)
		(end 135.29183 -273.76374)
		(width 0.0889)
		(layer "In13.Cu")
		(net "M_H_CPU1_SB_CB<3>")
	)
	(arc
		(start 137.171684 -273.76374)
		(mid 136.98474 -273.713485)
		(end 136.797796 -273.76374)
		(width 0.0889)
		(layer "In13.Cu")
		(net "M_H_CPU1_SB_CB<3>")
	)
	(arc
		(start 142.803372 -273.758914)
		(mid 142.619864 -273.71342)
		(end 142.437612 -273.76374)
		(width 0.0889)
		(layer "In13.Cu")
		(net "M_H_CPU1_SB_CB<3>")
	)
	(arc
		(start 145.25244 -273.767296)
		(mid 144.972051 -273.839965)
		(end 144.692624 -273.76374)
		(width 0.0889)
		(layer "In13.Cu")
		(net "M_H_CPU1_SB_CB<3>")
	)
	(arc
		(start 139.04341 -273.758914)
		(mid 138.859902 -273.71342)
		(end 138.67765 -273.76374)
		(width 0.0889)
		(layer "In13.Cu")
		(net "M_H_CPU1_SB_CB<3>")
	)
	(arc
		(start 139.991846 -273.76374)
		(mid 139.809595 -273.71339)
		(end 139.626086 -273.758914)
		(width 0.0889)
		(layer "In13.Cu")
		(net "M_H_CPU1_SB_CB<3>")
	)
	(arc
		(start 136.231884 -273.76374)
		(mid 136.049633 -273.71339)
		(end 135.866124 -273.758914)
		(width 0.0889)
		(layer "In13.Cu")
		(net "M_H_CPU1_SB_CB<3>")
	)
	(arc
		(start 144.317974 -273.76374)
		(mid 144.040907 -273.840011)
		(end 143.762222 -273.769836)
		(width 0.0889)
		(layer "In13.Cu")
		(net "M_H_CPU1_SB_CB<3>")
	)
	(arc
		(start 145.92173 -273.545046)
		(mid 145.697569 -273.669755)
		(end 145.444718 -273.71294)
		(width 0.0889)
		(layer "In13.Cu")
		(net "M_H_CPU1_SB_CB<3>")
	)
	(arc
		(start 138.67765 -273.76374)
		(mid 138.394694 -273.839917)
		(end 138.111738 -273.76374)
		(width 0.0889)
		(layer "In13.Cu")
		(net "M_H_CPU1_SB_CB<3>")
	)
	(arc
		(start 139.617704 -273.76374)
		(mid 139.334748 -273.839917)
		(end 139.051792 -273.76374)
		(width 0.0889)
		(layer "In13.Cu")
		(net "M_H_CPU1_SB_CB<3>")
	)
	(arc
		(start 143.751808 -273.76374)
		(mid 143.569557 -273.71339)
		(end 143.386048 -273.758914)
		(width 0.0889)
		(layer "In13.Cu")
		(net "M_H_CPU1_SB_CB<3>")
	)
	(arc
		(start 137.737596 -273.76374)
		(mid 137.45464 -273.839917)
		(end 137.171684 -273.76374)
		(width 0.0889)
		(layer "In13.Cu")
		(net "M_H_CPU1_SB_CB<3>")
	)
	(arc
		(start 143.377666 -273.76374)
		(mid 143.09471 -273.839917)
		(end 142.811754 -273.76374)
		(width 0.0889)
		(layer "In13.Cu")
		(net "M_H_CPU1_SB_CB<3>")
	)
	(arc
		(start 141.497812 -273.76374)
		(mid 141.214856 -273.839917)
		(end 140.9319 -273.76374)
		(width 0.0889)
		(layer "In13.Cu")
		(net "M_H_CPU1_SB_CB<3>")
	)
	(arc
		(start 145.444718 -273.71294)
		(mid 145.344864 -273.726983)
		(end 145.25244 -273.767296)
		(width 0.0889)
		(layer "In13.Cu")
		(net "M_H_CPU1_SB_CB<3>")
	)
	(arc
		(start 136.797796 -273.76374)
		(mid 136.51484 -273.839917)
		(end 136.231884 -273.76374)
		(width 0.0889)
		(layer "In13.Cu")
		(net "M_H_CPU1_SB_CB<3>")
	)
	(arc
		(start 138.103356 -273.758914)
		(mid 137.919848 -273.71342)
		(end 137.737596 -273.76374)
		(width 0.0889)
		(layer "In13.Cu")
		(net "M_H_CPU1_SB_CB<3>")
	)
	(arc
		(start 144.684242 -273.758914)
		(mid 144.50048 -273.713298)
		(end 144.317974 -273.76374)
		(width 0.0889)
		(layer "In13.Cu")
		(net "M_H_CPU1_SB_CB<3>")
	)
	(arc
		(start 140.9319 -273.76374)
		(mid 140.749649 -273.71339)
		(end 140.56614 -273.758914)
		(width 0.0889)
		(layer "In13.Cu")
		(net "M_H_CPU1_SB_CB<3>")
	)
	(arc
		(start 140.557758 -273.76374)
		(mid 140.274802 -273.839917)
		(end 139.991846 -273.76374)
		(width 0.0889)
		(layer "In13.Cu")
		(net "M_H_CPU1_SB_CB<3>")
	)
	(segment
		(start 136.047988 -273.010376)
		(end 136.51484 -273.276314)
		(width 0.10668)
		(layer "F.Cu")
		(net "M_H_CPU1_SB_CB<2>")
	)
	(segment
		(start 136.383014 -272.927572)
		(end 136.360662 -273.010884)
		(width 0.0889)
		(layer "In13.Cu")
		(net "M_H_CPU1_SB_CB<2>")
	)
	(segment
		(start 147.009358 -271.756124)
		(end 145.925032 -272.84045)
		(width 0.0889)
		(layer "In13.Cu")
		(net "M_H_CPU1_SB_CB<2>")
	)
	(segment
		(start 171.547028 -279.360376)
		(end 170.736006 -279.360376)
		(width 0.14478)
		(layer "In13.Cu")
		(net "M_H_CPU1_SB_CB<2>")
	)
	(segment
		(start 159.497522 -274.576286)
		(end 159.268922 -274.576286)
		(width 0.14478)
		(layer "In13.Cu")
		(net "M_H_CPU1_SB_CB<2>")
	)
	(segment
		(start 156.276548 -272.335244)
		(end 156.276548 -272.106644)
		(width 0.14478)
		(layer "In13.Cu")
		(net "M_H_CPU1_SB_CB<2>")
	)
	(segment
		(start 169.885868 -278.510238)
		(end 167.000174 -278.510238)
		(width 0.14478)
		(layer "In13.Cu")
		(net "M_H_CPU1_SB_CB<2>")
	)
	(segment
		(start 171.97197 -278.935434)
		(end 171.547028 -279.360376)
		(width 0.14478)
		(layer "In13.Cu")
		(net "M_H_CPU1_SB_CB<2>")
	)
	(segment
		(start 141.4018 -272.953734)
		(end 141.393418 -272.948908)
		(width 0.0889)
		(layer "In13.Cu")
		(net "M_H_CPU1_SB_CB<2>")
	)
	(segment
		(start 157.156658 -272.235422)
		(end 156.928058 -272.235422)
		(width 0.14478)
		(layer "In13.Cu")
		(net "M_H_CPU1_SB_CB<2>")
	)
	(segment
		(start 158.09849 -273.405854)
		(end 158.09849 -273.177254)
		(width 0.14478)
		(layer "In13.Cu")
		(net "M_H_CPU1_SB_CB<2>")
	)
	(segment
		(start 156.666692 -272.496788)
		(end 156.438092 -272.496788)
		(width 0.14478)
		(layer "In13.Cu")
		(net "M_H_CPU1_SB_CB<2>")
	)
	(segment
		(start 157.837124 -273.89582)
		(end 157.837124 -273.66722)
		(width 0.14478)
		(layer "In13.Cu")
		(net "M_H_CPU1_SB_CB<2>")
	)
	(segment
		(start 156.928058 -272.235422)
		(end 156.666692 -272.496788)
		(width 0.14478)
		(layer "In13.Cu")
		(net "M_H_CPU1_SB_CB<2>")
	)
	(segment
		(start 144.220946 -272.953988)
		(end 144.20088 -272.942558)
		(width 0.0889)
		(layer "In13.Cu")
		(net "M_H_CPU1_SB_CB<2>")
	)
	(segment
		(start 170.736006 -279.360376)
		(end 169.885868 -278.510238)
		(width 0.14478)
		(layer "In13.Cu")
		(net "M_H_CPU1_SB_CB<2>")
	)
	(segment
		(start 140.461746 -272.953734)
		(end 140.453364 -272.948908)
		(width 0.0889)
		(layer "In13.Cu")
		(net "M_H_CPU1_SB_CB<2>")
	)
	(segment
		(start 138.216132 -272.948908)
		(end 138.20775 -272.953734)
		(width 0.0889)
		(layer "In13.Cu")
		(net "M_H_CPU1_SB_CB<2>")
	)
	(segment
		(start 156.438092 -272.496788)
		(end 156.276548 -272.335244)
		(width 0.14478)
		(layer "In13.Cu")
		(net "M_H_CPU1_SB_CB<2>")
	)
	(segment
		(start 157.936946 -273.01571)
		(end 157.708346 -273.01571)
		(width 0.14478)
		(layer "In13.Cu")
		(net "M_H_CPU1_SB_CB<2>")
	)
	(segment
		(start 158.227268 -274.057364)
		(end 157.998668 -274.057364)
		(width 0.14478)
		(layer "In13.Cu")
		(net "M_H_CPU1_SB_CB<2>")
	)
	(segment
		(start 157.998668 -274.057364)
		(end 157.837124 -273.89582)
		(width 0.14478)
		(layer "In13.Cu")
		(net "M_H_CPU1_SB_CB<2>")
	)
	(segment
		(start 157.21838 -273.277076)
		(end 157.056836 -273.115532)
		(width 0.14478)
		(layer "In13.Cu")
		(net "M_H_CPU1_SB_CB<2>")
	)
	(segment
		(start 157.318202 -272.625566)
		(end 157.318202 -272.396966)
		(width 0.14478)
		(layer "In13.Cu")
		(net "M_H_CPU1_SB_CB<2>")
	)
	(segment
		(start 158.617412 -274.676108)
		(end 158.617412 -274.447508)
		(width 0.14478)
		(layer "In13.Cu")
		(net "M_H_CPU1_SB_CB<2>")
	)
	(segment
		(start 144.242536 -272.966434)
		(end 144.220946 -272.953988)
		(width 0.0889)
		(layer "In13.Cu")
		(net "M_H_CPU1_SB_CB<2>")
	)
	(segment
		(start 144.80413 -272.942812)
		(end 144.785334 -272.953734)
		(width 0.0889)
		(layer "In13.Cu")
		(net "M_H_CPU1_SB_CB<2>")
	)
	(segment
		(start 157.44698 -273.277076)
		(end 157.21838 -273.277076)
		(width 0.14478)
		(layer "In13.Cu")
		(net "M_H_CPU1_SB_CB<2>")
	)
	(segment
		(start 157.318202 -272.396966)
		(end 157.156658 -272.235422)
		(width 0.14478)
		(layer "In13.Cu")
		(net "M_H_CPU1_SB_CB<2>")
	)
	(segment
		(start 158.878778 -273.957542)
		(end 158.717234 -273.795998)
		(width 0.14478)
		(layer "In13.Cu")
		(net "M_H_CPU1_SB_CB<2>")
	)
	(segment
		(start 157.837124 -273.66722)
		(end 158.09849 -273.405854)
		(width 0.14478)
		(layer "In13.Cu")
		(net "M_H_CPU1_SB_CB<2>")
	)
	(segment
		(start 158.717234 -273.795998)
		(end 158.488634 -273.795998)
		(width 0.14478)
		(layer "In13.Cu")
		(net "M_H_CPU1_SB_CB<2>")
	)
	(segment
		(start 162.217862 -277.296626)
		(end 159.497522 -274.576286)
		(width 0.14478)
		(layer "In13.Cu")
		(net "M_H_CPU1_SB_CB<2>")
	)
	(segment
		(start 156.537914 -271.845278)
		(end 156.537914 -271.616678)
		(width 0.14478)
		(layer "In13.Cu")
		(net "M_H_CPU1_SB_CB<2>")
	)
	(segment
		(start 147.996656 -271.474184)
		(end 147.476718 -271.474184)
		(width 0.0889)
		(layer "In13.Cu")
		(net "M_H_CPU1_SB_CB<2>")
	)
	(segment
		(start 136.701784 -272.953734)
		(end 136.693402 -272.948908)
		(width 0.0889)
		(layer "In13.Cu")
		(net "M_H_CPU1_SB_CB<2>")
	)
	(segment
		(start 158.488634 -273.795998)
		(end 158.227268 -274.057364)
		(width 0.14478)
		(layer "In13.Cu")
		(net "M_H_CPU1_SB_CB<2>")
	)
	(segment
		(start 137.276078 -272.948908)
		(end 137.267696 -272.953734)
		(width 0.0889)
		(layer "In13.Cu")
		(net "M_H_CPU1_SB_CB<2>")
	)
	(segment
		(start 156.276548 -272.106644)
		(end 156.537914 -271.845278)
		(width 0.14478)
		(layer "In13.Cu")
		(net "M_H_CPU1_SB_CB<2>")
	)
	(segment
		(start 159.268922 -274.576286)
		(end 159.007556 -274.837652)
		(width 0.14478)
		(layer "In13.Cu")
		(net "M_H_CPU1_SB_CB<2>")
	)
	(segment
		(start 165.226492 -279.360376)
		(end 163.162742 -277.296626)
		(width 0.14478)
		(layer "In13.Cu")
		(net "M_H_CPU1_SB_CB<2>")
	)
	(segment
		(start 136.360662 -273.010884)
		(end 136.51484 -273.276314)
		(width 0.0889)
		(layer "In13.Cu")
		(net "M_H_CPU1_SB_CB<2>")
	)
	(segment
		(start 141.976094 -272.948908)
		(end 141.967712 -272.953734)
		(width 0.0889)
		(layer "In13.Cu")
		(net "M_H_CPU1_SB_CB<2>")
	)
	(segment
		(start 157.056836 -272.886932)
		(end 157.318202 -272.625566)
		(width 0.14478)
		(layer "In13.Cu")
		(net "M_H_CPU1_SB_CB<2>")
	)
	(segment
		(start 157.056836 -273.115532)
		(end 157.056836 -272.886932)
		(width 0.14478)
		(layer "In13.Cu")
		(net "M_H_CPU1_SB_CB<2>")
	)
	(segment
		(start 166.150036 -279.360376)
		(end 165.226492 -279.360376)
		(width 0.14478)
		(layer "In13.Cu")
		(net "M_H_CPU1_SB_CB<2>")
	)
	(segment
		(start 159.007556 -274.837652)
		(end 158.778956 -274.837652)
		(width 0.14478)
		(layer "In13.Cu")
		(net "M_H_CPU1_SB_CB<2>")
	)
	(segment
		(start 147.194778 -271.756124)
		(end 147.009358 -271.756124)
		(width 0.0889)
		(layer "In13.Cu")
		(net "M_H_CPU1_SB_CB<2>")
	)
	(segment
		(start 147.476718 -271.474184)
		(end 147.194778 -271.756124)
		(width 0.0889)
		(layer "In13.Cu")
		(net "M_H_CPU1_SB_CB<2>")
	)
	(segment
		(start 156.39542 -271.474184)
		(end 147.996656 -271.474184)
		(width 0.14478)
		(layer "In13.Cu")
		(net "M_H_CPU1_SB_CB<2>")
	)
	(segment
		(start 158.617412 -274.447508)
		(end 158.878778 -274.186142)
		(width 0.14478)
		(layer "In13.Cu")
		(net "M_H_CPU1_SB_CB<2>")
	)
	(segment
		(start 158.878778 -274.186142)
		(end 158.878778 -273.957542)
		(width 0.14478)
		(layer "In13.Cu")
		(net "M_H_CPU1_SB_CB<2>")
	)
	(segment
		(start 158.778956 -274.837652)
		(end 158.617412 -274.676108)
		(width 0.14478)
		(layer "In13.Cu")
		(net "M_H_CPU1_SB_CB<2>")
	)
	(segment
		(start 167.000174 -278.510238)
		(end 166.150036 -279.360376)
		(width 0.14478)
		(layer "In13.Cu")
		(net "M_H_CPU1_SB_CB<2>")
	)
	(segment
		(start 158.09849 -273.177254)
		(end 157.936946 -273.01571)
		(width 0.14478)
		(layer "In13.Cu")
		(net "M_H_CPU1_SB_CB<2>")
	)
	(segment
		(start 157.708346 -273.01571)
		(end 157.44698 -273.277076)
		(width 0.14478)
		(layer "In13.Cu")
		(net "M_H_CPU1_SB_CB<2>")
	)
	(segment
		(start 156.537914 -271.616678)
		(end 156.39542 -271.474184)
		(width 0.14478)
		(layer "In13.Cu")
		(net "M_H_CPU1_SB_CB<2>")
	)
	(segment
		(start 163.162742 -277.296626)
		(end 162.217862 -277.296626)
		(width 0.14478)
		(layer "In13.Cu")
		(net "M_H_CPU1_SB_CB<2>")
	)
	(arc
		(start 142.341854 -272.953734)
		(mid 142.159603 -272.903384)
		(end 141.976094 -272.948908)
		(width 0.0889)
		(layer "In13.Cu")
		(net "M_H_CPU1_SB_CB<2>")
	)
	(arc
		(start 137.267696 -272.953734)
		(mid 136.98474 -273.029911)
		(end 136.701784 -272.953734)
		(width 0.0889)
		(layer "In13.Cu")
		(net "M_H_CPU1_SB_CB<2>")
	)
	(arc
		(start 143.281654 -272.953734)
		(mid 143.09471 -272.903479)
		(end 142.907766 -272.953734)
		(width 0.0889)
		(layer "In13.Cu")
		(net "M_H_CPU1_SB_CB<2>")
	)
	(arc
		(start 145.925032 -272.84045)
		(mid 145.818539 -272.9218)
		(end 145.6944 -272.972276)
		(width 0.0889)
		(layer "In13.Cu")
		(net "M_H_CPU1_SB_CB<2>")
	)
	(arc
		(start 144.20088 -272.942558)
		(mid 144.022802 -272.903574)
		(end 143.847566 -272.953734)
		(width 0.0889)
		(layer "In13.Cu")
		(net "M_H_CPU1_SB_CB<2>")
	)
	(arc
		(start 145.6944 -272.972276)
		(mid 145.425115 -273.030188)
		(end 145.160492 -272.953734)
		(width 0.0889)
		(layer "In13.Cu")
		(net "M_H_CPU1_SB_CB<2>")
	)
	(arc
		(start 141.027658 -272.953734)
		(mid 140.744702 -273.029911)
		(end 140.461746 -272.953734)
		(width 0.0889)
		(layer "In13.Cu")
		(net "M_H_CPU1_SB_CB<2>")
	)
	(arc
		(start 140.087604 -272.953734)
		(mid 139.804648 -273.029911)
		(end 139.521692 -272.953734)
		(width 0.0889)
		(layer "In13.Cu")
		(net "M_H_CPU1_SB_CB<2>")
	)
	(arc
		(start 138.581892 -272.953734)
		(mid 138.399641 -272.903384)
		(end 138.216132 -272.948908)
		(width 0.0889)
		(layer "In13.Cu")
		(net "M_H_CPU1_SB_CB<2>")
	)
	(arc
		(start 145.160492 -272.953734)
		(mid 144.983701 -272.903015)
		(end 144.80413 -272.942812)
		(width 0.0889)
		(layer "In13.Cu")
		(net "M_H_CPU1_SB_CB<2>")
	)
	(arc
		(start 142.907766 -272.953734)
		(mid 142.62481 -273.029911)
		(end 142.341854 -272.953734)
		(width 0.0889)
		(layer "In13.Cu")
		(net "M_H_CPU1_SB_CB<2>")
	)
	(arc
		(start 140.453364 -272.948908)
		(mid 140.269856 -272.903414)
		(end 140.087604 -272.953734)
		(width 0.0889)
		(layer "In13.Cu")
		(net "M_H_CPU1_SB_CB<2>")
	)
	(arc
		(start 143.847566 -272.953734)
		(mid 143.56461 -273.029911)
		(end 143.281654 -272.953734)
		(width 0.0889)
		(layer "In13.Cu")
		(net "M_H_CPU1_SB_CB<2>")
	)
	(arc
		(start 141.967712 -272.953734)
		(mid 141.684756 -273.029911)
		(end 141.4018 -272.953734)
		(width 0.0889)
		(layer "In13.Cu")
		(net "M_H_CPU1_SB_CB<2>")
	)
	(arc
		(start 139.521692 -272.953734)
		(mid 139.334748 -272.903479)
		(end 139.147804 -272.953734)
		(width 0.0889)
		(layer "In13.Cu")
		(net "M_H_CPU1_SB_CB<2>")
	)
	(arc
		(start 141.393418 -272.948908)
		(mid 141.20991 -272.903414)
		(end 141.027658 -272.953734)
		(width 0.0889)
		(layer "In13.Cu")
		(net "M_H_CPU1_SB_CB<2>")
	)
	(arc
		(start 138.20775 -272.953734)
		(mid 137.924794 -273.029911)
		(end 137.641838 -272.953734)
		(width 0.0889)
		(layer "In13.Cu")
		(net "M_H_CPU1_SB_CB<2>")
	)
	(arc
		(start 144.785334 -272.953734)
		(mid 144.515565 -273.029757)
		(end 144.242536 -272.966434)
		(width 0.0889)
		(layer "In13.Cu")
		(net "M_H_CPU1_SB_CB<2>")
	)
	(arc
		(start 136.693402 -272.948908)
		(mid 136.540532 -272.904267)
		(end 136.383014 -272.927572)
		(width 0.0889)
		(layer "In13.Cu")
		(net "M_H_CPU1_SB_CB<2>")
	)
	(arc
		(start 139.147804 -272.953734)
		(mid 138.864848 -273.029911)
		(end 138.581892 -272.953734)
		(width 0.0889)
		(layer "In13.Cu")
		(net "M_H_CPU1_SB_CB<2>")
	)
	(arc
		(start 137.641838 -272.953734)
		(mid 137.459587 -272.903384)
		(end 137.276078 -272.948908)
		(width 0.0889)
		(layer "In13.Cu")
		(net "M_H_CPU1_SB_CB<2>")
	)
	(segment
		(start 134.16788 -273.010376)
		(end 134.634732 -273.276314)
		(width 0.10668)
		(layer "F.Cu")
		(net "M_H_CPU1_SB_CB<1>")
	)
	(segment
		(start 145.444464 -273.522186)
		(end 145.44421 -273.522186)
		(width 0.0889)
		(layer "In13.Cu")
		(net "M_H_CPU1_SB_CB<1>")
	)
	(segment
		(start 158.59252 -275.287232)
		(end 155.234132 -271.928844)
		(width 0.14478)
		(layer "In13.Cu")
		(net "M_H_CPU1_SB_CB<1>")
	)
	(segment
		(start 141.976094 -273.60372)
		(end 141.967712 -273.598894)
		(width 0.0889)
		(layer "In13.Cu")
		(net "M_H_CPU1_SB_CB<1>")
	)
	(segment
		(start 144.788382 -273.598894)
		(end 144.777968 -273.592798)
		(width 0.0889)
		(layer "In13.Cu")
		(net "M_H_CPU1_SB_CB<1>")
	)
	(segment
		(start 165.040056 -279.809956)
		(end 163.981892 -278.751792)
		(width 0.14478)
		(layer "In13.Cu")
		(net "M_H_CPU1_SB_CB<1>")
	)
	(segment
		(start 140.461746 -273.598894)
		(end 140.453364 -273.60372)
		(width 0.0889)
		(layer "In13.Cu")
		(net "M_H_CPU1_SB_CB<1>")
	)
	(segment
		(start 138.216132 -273.60372)
		(end 138.20775 -273.598894)
		(width 0.0889)
		(layer "In13.Cu")
		(net "M_H_CPU1_SB_CB<1>")
	)
	(segment
		(start 162.368738 -278.083518)
		(end 159.572452 -275.287232)
		(width 0.14478)
		(layer "In13.Cu")
		(net "M_H_CPU1_SB_CB<1>")
	)
	(segment
		(start 147.047204 -272.149824)
		(end 145.79473 -273.402298)
		(width 0.0889)
		(layer "In13.Cu")
		(net "M_H_CPU1_SB_CB<1>")
	)
	(segment
		(start 148.025104 -271.928844)
		(end 147.455128 -271.928844)
		(width 0.0889)
		(layer "In13.Cu")
		(net "M_H_CPU1_SB_CB<1>")
	)
	(segment
		(start 134.788656 -273.541744)
		(end 134.634732 -273.276314)
		(width 0.0889)
		(layer "In13.Cu")
		(net "M_H_CPU1_SB_CB<1>")
	)
	(segment
		(start 171.53636 -280.21026)
		(end 169.484548 -279.360376)
		(width 0.14478)
		(layer "In13.Cu")
		(net "M_H_CPU1_SB_CB<1>")
	)
	(segment
		(start 172.99559 -280.21026)
		(end 171.53636 -280.21026)
		(width 0.14478)
		(layer "In13.Cu")
		(net "M_H_CPU1_SB_CB<1>")
	)
	(segment
		(start 137.276078 -273.60372)
		(end 137.267696 -273.598894)
		(width 0.0889)
		(layer "In13.Cu")
		(net "M_H_CPU1_SB_CB<1>")
	)
	(segment
		(start 135.76173 -273.598894)
		(end 135.753348 -273.60372)
		(width 0.0889)
		(layer "In13.Cu")
		(net "M_H_CPU1_SB_CB<1>")
	)
	(segment
		(start 167.421052 -279.360376)
		(end 166.335456 -279.809956)
		(width 0.14478)
		(layer "In13.Cu")
		(net "M_H_CPU1_SB_CB<1>")
	)
	(segment
		(start 163.981892 -278.751792)
		(end 162.368738 -278.083518)
		(width 0.14478)
		(layer "In13.Cu")
		(net "M_H_CPU1_SB_CB<1>")
	)
	(segment
		(start 134.884668 -273.567144)
		(end 134.788656 -273.541744)
		(width 0.0889)
		(layer "In13.Cu")
		(net "M_H_CPU1_SB_CB<1>")
	)
	(segment
		(start 136.701784 -273.598894)
		(end 136.693402 -273.60372)
		(width 0.0889)
		(layer "In13.Cu")
		(net "M_H_CPU1_SB_CB<1>")
	)
	(segment
		(start 143.855948 -273.60372)
		(end 143.847566 -273.598894)
		(width 0.0889)
		(layer "In13.Cu")
		(net "M_H_CPU1_SB_CB<1>")
	)
	(segment
		(start 147.455128 -271.928844)
		(end 147.234148 -272.149824)
		(width 0.0889)
		(layer "In13.Cu")
		(net "M_H_CPU1_SB_CB<1>")
	)
	(segment
		(start 169.484548 -279.360376)
		(end 167.421052 -279.360376)
		(width 0.14478)
		(layer "In13.Cu")
		(net "M_H_CPU1_SB_CB<1>")
	)
	(segment
		(start 147.234148 -272.149824)
		(end 147.047204 -272.149824)
		(width 0.0889)
		(layer "In13.Cu")
		(net "M_H_CPU1_SB_CB<1>")
	)
	(segment
		(start 141.4018 -273.598894)
		(end 141.393418 -273.60372)
		(width 0.0889)
		(layer "In13.Cu")
		(net "M_H_CPU1_SB_CB<1>")
	)
	(segment
		(start 159.572452 -275.287232)
		(end 158.59252 -275.287232)
		(width 0.14478)
		(layer "In13.Cu")
		(net "M_H_CPU1_SB_CB<1>")
	)
	(segment
		(start 176.072038 -279.785318)
		(end 172.99559 -280.21026)
		(width 0.14478)
		(layer "In13.Cu")
		(net "M_H_CPU1_SB_CB<1>")
	)
	(segment
		(start 166.335456 -279.809956)
		(end 165.040056 -279.809956)
		(width 0.14478)
		(layer "In13.Cu")
		(net "M_H_CPU1_SB_CB<1>")
	)
	(segment
		(start 155.234132 -271.928844)
		(end 148.025104 -271.928844)
		(width 0.14478)
		(layer "In13.Cu")
		(net "M_H_CPU1_SB_CB<1>")
	)
	(arc
		(start 141.967712 -273.598894)
		(mid 141.684756 -273.522717)
		(end 141.4018 -273.598894)
		(width 0.0889)
		(layer "In13.Cu")
		(net "M_H_CPU1_SB_CB<1>")
	)
	(arc
		(start 137.641838 -273.598894)
		(mid 137.459587 -273.649244)
		(end 137.276078 -273.60372)
		(width 0.0889)
		(layer "In13.Cu")
		(net "M_H_CPU1_SB_CB<1>")
	)
	(arc
		(start 138.20775 -273.598894)
		(mid 137.924794 -273.522717)
		(end 137.641838 -273.598894)
		(width 0.0889)
		(layer "In13.Cu")
		(net "M_H_CPU1_SB_CB<1>")
	)
	(arc
		(start 141.393418 -273.60372)
		(mid 141.20991 -273.649214)
		(end 141.027658 -273.598894)
		(width 0.0889)
		(layer "In13.Cu")
		(net "M_H_CPU1_SB_CB<1>")
	)
	(arc
		(start 145.368264 -273.52752)
		(mid 145.252871 -273.556)
		(end 145.146014 -273.608038)
		(width 0.0889)
		(layer "In13.Cu")
		(net "M_H_CPU1_SB_CB<1>")
	)
	(arc
		(start 143.847566 -273.598894)
		(mid 143.56461 -273.522717)
		(end 143.281654 -273.598894)
		(width 0.0889)
		(layer "In13.Cu")
		(net "M_H_CPU1_SB_CB<1>")
	)
	(arc
		(start 144.777968 -273.592798)
		(mid 144.499282 -273.522578)
		(end 144.222216 -273.598894)
		(width 0.0889)
		(layer "In13.Cu")
		(net "M_H_CPU1_SB_CB<1>")
	)
	(arc
		(start 145.79473 -273.402298)
		(mid 145.629581 -273.491406)
		(end 145.444464 -273.522186)
		(width 0.0889)
		(layer "In13.Cu")
		(net "M_H_CPU1_SB_CB<1>")
	)
	(arc
		(start 139.521692 -273.598894)
		(mid 139.334748 -273.649149)
		(end 139.147804 -273.598894)
		(width 0.0889)
		(layer "In13.Cu")
		(net "M_H_CPU1_SB_CB<1>")
	)
	(arc
		(start 135.753348 -273.60372)
		(mid 135.56984 -273.649214)
		(end 135.387588 -273.598894)
		(width 0.0889)
		(layer "In13.Cu")
		(net "M_H_CPU1_SB_CB<1>")
	)
	(arc
		(start 143.281654 -273.598894)
		(mid 143.09471 -273.649149)
		(end 142.907766 -273.598894)
		(width 0.0889)
		(layer "In13.Cu")
		(net "M_H_CPU1_SB_CB<1>")
	)
	(arc
		(start 136.693402 -273.60372)
		(mid 136.509894 -273.649214)
		(end 136.327642 -273.598894)
		(width 0.0889)
		(layer "In13.Cu")
		(net "M_H_CPU1_SB_CB<1>")
	)
	(arc
		(start 144.222216 -273.598894)
		(mid 144.039711 -273.649371)
		(end 143.855948 -273.60372)
		(width 0.0889)
		(layer "In13.Cu")
		(net "M_H_CPU1_SB_CB<1>")
	)
	(arc
		(start 145.44421 -273.522186)
		(mid 145.406148 -273.523576)
		(end 145.368264 -273.52752)
		(width 0.0889)
		(layer "In13.Cu")
		(net "M_H_CPU1_SB_CB<1>")
	)
	(arc
		(start 138.581892 -273.598894)
		(mid 138.399641 -273.649244)
		(end 138.216132 -273.60372)
		(width 0.0889)
		(layer "In13.Cu")
		(net "M_H_CPU1_SB_CB<1>")
	)
	(arc
		(start 145.146014 -273.608038)
		(mid 144.966032 -273.649138)
		(end 144.788382 -273.598894)
		(width 0.0889)
		(layer "In13.Cu")
		(net "M_H_CPU1_SB_CB<1>")
	)
	(arc
		(start 140.087604 -273.598894)
		(mid 139.804648 -273.522717)
		(end 139.521692 -273.598894)
		(width 0.0889)
		(layer "In13.Cu")
		(net "M_H_CPU1_SB_CB<1>")
	)
	(arc
		(start 140.453364 -273.60372)
		(mid 140.269856 -273.649214)
		(end 140.087604 -273.598894)
		(width 0.0889)
		(layer "In13.Cu")
		(net "M_H_CPU1_SB_CB<1>")
	)
	(arc
		(start 141.027658 -273.598894)
		(mid 140.744702 -273.522717)
		(end 140.461746 -273.598894)
		(width 0.0889)
		(layer "In13.Cu")
		(net "M_H_CPU1_SB_CB<1>")
	)
	(arc
		(start 136.327642 -273.598894)
		(mid 136.044686 -273.522717)
		(end 135.76173 -273.598894)
		(width 0.0889)
		(layer "In13.Cu")
		(net "M_H_CPU1_SB_CB<1>")
	)
	(arc
		(start 135.387588 -273.598894)
		(mid 135.139875 -273.523674)
		(end 134.884668 -273.567144)
		(width 0.0889)
		(layer "In13.Cu")
		(net "M_H_CPU1_SB_CB<1>")
	)
	(arc
		(start 137.267696 -273.598894)
		(mid 136.98474 -273.522717)
		(end 136.701784 -273.598894)
		(width 0.0889)
		(layer "In13.Cu")
		(net "M_H_CPU1_SB_CB<1>")
	)
	(arc
		(start 139.147804 -273.598894)
		(mid 138.864848 -273.522717)
		(end 138.581892 -273.598894)
		(width 0.0889)
		(layer "In13.Cu")
		(net "M_H_CPU1_SB_CB<1>")
	)
	(arc
		(start 142.907766 -273.598894)
		(mid 142.62481 -273.522717)
		(end 142.341854 -273.598894)
		(width 0.0889)
		(layer "In13.Cu")
		(net "M_H_CPU1_SB_CB<1>")
	)
	(arc
		(start 142.341854 -273.598894)
		(mid 142.159603 -273.649244)
		(end 141.976094 -273.60372)
		(width 0.0889)
		(layer "In13.Cu")
		(net "M_H_CPU1_SB_CB<1>")
	)
	(segment
		(start 135.577834 -272.20037)
		(end 136.044686 -272.466308)
		(width 0.10668)
		(layer "F.Cu")
		(net "M_H_CPU1_SB_CB<0>")
	)
	(segment
		(start 140.56614 -272.793714)
		(end 140.557758 -272.788888)
		(width 0.0889)
		(layer "In13.Cu")
		(net "M_H_CPU1_SB_CB<0>")
	)
	(segment
		(start 156.579824 -271.019524)
		(end 147.854162 -271.019524)
		(width 0.14478)
		(layer "In13.Cu")
		(net "M_H_CPU1_SB_CB<0>")
	)
	(segment
		(start 139.626086 -272.793714)
		(end 139.617704 -272.788888)
		(width 0.0889)
		(layer "In13.Cu")
		(net "M_H_CPU1_SB_CB<0>")
	)
	(segment
		(start 147.702016 -270.867378)
		(end 147.022312 -270.867378)
		(width 0.0889)
		(layer "In13.Cu")
		(net "M_H_CPU1_SB_CB<0>")
	)
	(segment
		(start 142.811754 -272.788888)
		(end 142.803372 -272.793714)
		(width 0.0889)
		(layer "In13.Cu")
		(net "M_H_CPU1_SB_CB<0>")
	)
	(segment
		(start 146.644106 -271.245584)
		(end 146.644106 -271.789398)
		(width 0.0889)
		(layer "In13.Cu")
		(net "M_H_CPU1_SB_CB<0>")
	)
	(segment
		(start 144.334484 -272.799048)
		(end 144.316196 -272.788634)
		(width 0.0889)
		(layer "In13.Cu")
		(net "M_H_CPU1_SB_CB<0>")
	)
	(segment
		(start 144.71269 -272.775172)
		(end 144.689322 -272.788888)
		(width 0.0889)
		(layer "In13.Cu")
		(net "M_H_CPU1_SB_CB<0>")
	)
	(segment
		(start 162.407346 -276.847046)
		(end 156.579824 -271.019524)
		(width 0.14478)
		(layer "In13.Cu")
		(net "M_H_CPU1_SB_CB<0>")
	)
	(segment
		(start 176.072038 -278.085296)
		(end 173.777402 -278.520144)
		(width 0.14478)
		(layer "In13.Cu")
		(net "M_H_CPU1_SB_CB<0>")
	)
	(segment
		(start 166.692834 -278.060658)
		(end 166.243 -278.510492)
		(width 0.14478)
		(layer "In13.Cu")
		(net "M_H_CPU1_SB_CB<0>")
	)
	(segment
		(start 165.012624 -278.510492)
		(end 163.349178 -276.847046)
		(width 0.14478)
		(layer "In13.Cu")
		(net "M_H_CPU1_SB_CB<0>")
	)
	(segment
		(start 136.29513 -272.757138)
		(end 136.198864 -272.731738)
		(width 0.0889)
		(layer "In13.Cu")
		(net "M_H_CPU1_SB_CB<0>")
	)
	(segment
		(start 145.630646 -272.788634)
		(end 145.603214 -272.804382)
		(width 0.0889)
		(layer "In13.Cu")
		(net "M_H_CPU1_SB_CB<0>")
	)
	(segment
		(start 136.198864 -272.731738)
		(end 136.044686 -272.466308)
		(width 0.0889)
		(layer "In13.Cu")
		(net "M_H_CPU1_SB_CB<0>")
	)
	(segment
		(start 170.610276 -278.520144)
		(end 170.15079 -278.060658)
		(width 0.14478)
		(layer "In13.Cu")
		(net "M_H_CPU1_SB_CB<0>")
	)
	(segment
		(start 143.386048 -272.793714)
		(end 143.377666 -272.788888)
		(width 0.0889)
		(layer "In13.Cu")
		(net "M_H_CPU1_SB_CB<0>")
	)
	(segment
		(start 139.051792 -272.788888)
		(end 139.04341 -272.793714)
		(width 0.0889)
		(layer "In13.Cu")
		(net "M_H_CPU1_SB_CB<0>")
	)
	(segment
		(start 147.854162 -271.019524)
		(end 147.702016 -270.867378)
		(width 0.14478)
		(layer "In13.Cu")
		(net "M_H_CPU1_SB_CB<0>")
	)
	(segment
		(start 170.15079 -278.060658)
		(end 166.692834 -278.060658)
		(width 0.14478)
		(layer "In13.Cu")
		(net "M_H_CPU1_SB_CB<0>")
	)
	(segment
		(start 138.111738 -272.788888)
		(end 138.103356 -272.793714)
		(width 0.0889)
		(layer "In13.Cu")
		(net "M_H_CPU1_SB_CB<0>")
	)
	(segment
		(start 163.349178 -276.847046)
		(end 162.407346 -276.847046)
		(width 0.14478)
		(layer "In13.Cu")
		(net "M_H_CPU1_SB_CB<0>")
	)
	(segment
		(start 144.316196 -272.788634)
		(end 144.294606 -272.776188)
		(width 0.0889)
		(layer "In13.Cu")
		(net "M_H_CPU1_SB_CB<0>")
	)
	(segment
		(start 146.644106 -271.789398)
		(end 145.708116 -272.725388)
		(width 0.0889)
		(layer "In13.Cu")
		(net "M_H_CPU1_SB_CB<0>")
	)
	(segment
		(start 166.243 -278.510492)
		(end 165.012624 -278.510492)
		(width 0.14478)
		(layer "In13.Cu")
		(net "M_H_CPU1_SB_CB<0>")
	)
	(segment
		(start 147.022312 -270.867378)
		(end 146.644106 -271.245584)
		(width 0.0889)
		(layer "In13.Cu")
		(net "M_H_CPU1_SB_CB<0>")
	)
	(segment
		(start 173.777402 -278.520144)
		(end 170.610276 -278.520144)
		(width 0.14478)
		(layer "In13.Cu")
		(net "M_H_CPU1_SB_CB<0>")
	)
	(arc
		(start 137.737596 -272.788888)
		(mid 137.45464 -272.712711)
		(end 137.171684 -272.788888)
		(width 0.0889)
		(layer "In13.Cu")
		(net "M_H_CPU1_SB_CB<0>")
	)
	(arc
		(start 138.103356 -272.793714)
		(mid 137.919848 -272.839208)
		(end 137.737596 -272.788888)
		(width 0.0889)
		(layer "In13.Cu")
		(net "M_H_CPU1_SB_CB<0>")
	)
	(arc
		(start 145.708116 -272.725388)
		(mid 145.670975 -272.758964)
		(end 145.630646 -272.788634)
		(width 0.0889)
		(layer "In13.Cu")
		(net "M_H_CPU1_SB_CB<0>")
	)
	(arc
		(start 138.67765 -272.788888)
		(mid 138.394694 -272.712711)
		(end 138.111738 -272.788888)
		(width 0.0889)
		(layer "In13.Cu")
		(net "M_H_CPU1_SB_CB<0>")
	)
	(arc
		(start 140.557758 -272.788888)
		(mid 140.274802 -272.712711)
		(end 139.991846 -272.788888)
		(width 0.0889)
		(layer "In13.Cu")
		(net "M_H_CPU1_SB_CB<0>")
	)
	(arc
		(start 144.294606 -272.776188)
		(mid 144.021577 -272.712869)
		(end 143.751808 -272.788888)
		(width 0.0889)
		(layer "In13.Cu")
		(net "M_H_CPU1_SB_CB<0>")
	)
	(arc
		(start 139.991846 -272.788888)
		(mid 139.809595 -272.839238)
		(end 139.626086 -272.793714)
		(width 0.0889)
		(layer "In13.Cu")
		(net "M_H_CPU1_SB_CB<0>")
	)
	(arc
		(start 144.689322 -272.788888)
		(mid 144.513202 -272.838866)
		(end 144.334484 -272.799048)
		(width 0.0889)
		(layer "In13.Cu")
		(net "M_H_CPU1_SB_CB<0>")
	)
	(arc
		(start 136.797796 -272.788888)
		(mid 136.5502 -272.71371)
		(end 136.29513 -272.757138)
		(width 0.0889)
		(layer "In13.Cu")
		(net "M_H_CPU1_SB_CB<0>")
	)
	(arc
		(start 143.377666 -272.788888)
		(mid 143.09471 -272.712711)
		(end 142.811754 -272.788888)
		(width 0.0889)
		(layer "In13.Cu")
		(net "M_H_CPU1_SB_CB<0>")
	)
	(arc
		(start 142.437612 -272.788888)
		(mid 142.154656 -272.712711)
		(end 141.8717 -272.788888)
		(width 0.0889)
		(layer "In13.Cu")
		(net "M_H_CPU1_SB_CB<0>")
	)
	(arc
		(start 143.751808 -272.788888)
		(mid 143.569557 -272.839238)
		(end 143.386048 -272.793714)
		(width 0.0889)
		(layer "In13.Cu")
		(net "M_H_CPU1_SB_CB<0>")
	)
	(arc
		(start 139.617704 -272.788888)
		(mid 139.334748 -272.712711)
		(end 139.051792 -272.788888)
		(width 0.0889)
		(layer "In13.Cu")
		(net "M_H_CPU1_SB_CB<0>")
	)
	(arc
		(start 140.9319 -272.788888)
		(mid 140.749649 -272.839238)
		(end 140.56614 -272.793714)
		(width 0.0889)
		(layer "In13.Cu")
		(net "M_H_CPU1_SB_CB<0>")
	)
	(arc
		(start 139.04341 -272.793714)
		(mid 138.859902 -272.839208)
		(end 138.67765 -272.788888)
		(width 0.0889)
		(layer "In13.Cu")
		(net "M_H_CPU1_SB_CB<0>")
	)
	(arc
		(start 137.171684 -272.788888)
		(mid 136.98474 -272.839143)
		(end 136.797796 -272.788888)
		(width 0.0889)
		(layer "In13.Cu")
		(net "M_H_CPU1_SB_CB<0>")
	)
	(arc
		(start 142.803372 -272.793714)
		(mid 142.619864 -272.839208)
		(end 142.437612 -272.788888)
		(width 0.0889)
		(layer "In13.Cu")
		(net "M_H_CPU1_SB_CB<0>")
	)
	(arc
		(start 141.497812 -272.788888)
		(mid 141.214856 -272.712711)
		(end 140.9319 -272.788888)
		(width 0.0889)
		(layer "In13.Cu")
		(net "M_H_CPU1_SB_CB<0>")
	)
	(arc
		(start 145.256504 -272.788888)
		(mid 144.986347 -272.712126)
		(end 144.71269 -272.775172)
		(width 0.0889)
		(layer "In13.Cu")
		(net "M_H_CPU1_SB_CB<0>")
	)
	(arc
		(start 141.8717 -272.788888)
		(mid 141.684756 -272.839143)
		(end 141.497812 -272.788888)
		(width 0.0889)
		(layer "In13.Cu")
		(net "M_H_CPU1_SB_CB<0>")
	)
	(arc
		(start 145.603214 -272.804382)
		(mid 145.427963 -272.839315)
		(end 145.256504 -272.788888)
		(width 0.0889)
		(layer "In13.Cu")
		(net "M_H_CPU1_SB_CB<0>")
	)
	(segment
		(start 135.577834 -264.10031)
		(end 136.044686 -264.366248)
		(width 0.10668)
		(layer "F.Cu")
		(net "M_H_CPU1_SB_CA<6>")
	)
	(segment
		(start 147.774152 -264.268204)
		(end 147.845272 -264.339324)
		(width 0.0889)
		(layer "In13.Cu")
		(net "M_H_CPU1_SB_CA<6>")
	)
	(segment
		(start 147.845272 -264.339324)
		(end 161.994088 -264.339324)
		(width 0.14478)
		(layer "In13.Cu")
		(net "M_H_CPU1_SB_CA<6>")
	)
	(segment
		(start 139.617704 -264.688828)
		(end 139.626086 -264.693654)
		(width 0.0889)
		(layer "In13.Cu")
		(net "M_H_CPU1_SB_CA<6>")
	)
	(segment
		(start 146.018504 -264.320274)
		(end 146.114262 -264.28065)
		(width 0.0889)
		(layer "In13.Cu")
		(net "M_H_CPU1_SB_CA<6>")
	)
	(segment
		(start 144.316196 -264.688574)
		(end 144.334484 -264.698988)
		(width 0.0889)
		(layer "In13.Cu")
		(net "M_H_CPU1_SB_CA<6>")
	)
	(segment
		(start 170.117516 -265.760454)
		(end 170.9674 -266.610338)
		(width 0.14478)
		(layer "In13.Cu")
		(net "M_H_CPU1_SB_CA<6>")
	)
	(segment
		(start 170.9674 -266.610338)
		(end 173.787054 -266.610338)
		(width 0.14478)
		(layer "In13.Cu")
		(net "M_H_CPU1_SB_CA<6>")
	)
	(segment
		(start 136.044686 -264.366248)
		(end 136.198864 -264.631678)
		(width 0.0889)
		(layer "In13.Cu")
		(net "M_H_CPU1_SB_CA<6>")
	)
	(segment
		(start 144.294606 -264.676128)
		(end 144.316196 -264.688574)
		(width 0.0889)
		(layer "In13.Cu")
		(net "M_H_CPU1_SB_CA<6>")
	)
	(segment
		(start 142.803372 -264.693654)
		(end 142.811754 -264.688828)
		(width 0.0889)
		(layer "In13.Cu")
		(net "M_H_CPU1_SB_CA<6>")
	)
	(segment
		(start 139.04341 -264.693654)
		(end 139.044426 -264.693146)
		(width 0.0889)
		(layer "In13.Cu")
		(net "M_H_CPU1_SB_CA<6>")
	)
	(segment
		(start 145.630646 -264.688574)
		(end 145.959322 -264.359898)
		(width 0.0889)
		(layer "In13.Cu")
		(net "M_H_CPU1_SB_CA<6>")
	)
	(segment
		(start 136.198864 -264.631678)
		(end 136.29513 -264.657078)
		(width 0.0889)
		(layer "In13.Cu")
		(net "M_H_CPU1_SB_CA<6>")
	)
	(segment
		(start 140.557758 -264.688828)
		(end 140.56614 -264.693654)
		(width 0.0889)
		(layer "In13.Cu")
		(net "M_H_CPU1_SB_CA<6>")
	)
	(segment
		(start 161.994088 -264.339324)
		(end 164.265102 -266.610338)
		(width 0.14478)
		(layer "In13.Cu")
		(net "M_H_CPU1_SB_CA<6>")
	)
	(segment
		(start 166.243 -266.610338)
		(end 167.092884 -265.760454)
		(width 0.14478)
		(layer "In13.Cu")
		(net "M_H_CPU1_SB_CA<6>")
	)
	(segment
		(start 175.923702 -266.185396)
		(end 176.072038 -266.185396)
		(width 0.14478)
		(layer "In13.Cu")
		(net "M_H_CPU1_SB_CA<6>")
	)
	(segment
		(start 173.787054 -266.610338)
		(end 175.923702 -266.185396)
		(width 0.14478)
		(layer "In13.Cu")
		(net "M_H_CPU1_SB_CA<6>")
	)
	(segment
		(start 139.044426 -264.693146)
		(end 139.051792 -264.688828)
		(width 0.0889)
		(layer "In13.Cu")
		(net "M_H_CPU1_SB_CA<6>")
	)
	(segment
		(start 145.603214 -264.704322)
		(end 145.630646 -264.688574)
		(width 0.0889)
		(layer "In13.Cu")
		(net "M_H_CPU1_SB_CA<6>")
	)
	(segment
		(start 146.177254 -264.268204)
		(end 147.774152 -264.268204)
		(width 0.0889)
		(layer "In13.Cu")
		(net "M_H_CPU1_SB_CA<6>")
	)
	(segment
		(start 167.092884 -265.760454)
		(end 170.117516 -265.760454)
		(width 0.14478)
		(layer "In13.Cu")
		(net "M_H_CPU1_SB_CA<6>")
	)
	(segment
		(start 145.959322 -264.359898)
		(end 146.018504 -264.320274)
		(width 0.0889)
		(layer "In13.Cu")
		(net "M_H_CPU1_SB_CA<6>")
	)
	(segment
		(start 143.377666 -264.688828)
		(end 143.386048 -264.693654)
		(width 0.0889)
		(layer "In13.Cu")
		(net "M_H_CPU1_SB_CA<6>")
	)
	(segment
		(start 144.689322 -264.688828)
		(end 144.71269 -264.675112)
		(width 0.0889)
		(layer "In13.Cu")
		(net "M_H_CPU1_SB_CA<6>")
	)
	(segment
		(start 164.265102 -266.610338)
		(end 166.243 -266.610338)
		(width 0.14478)
		(layer "In13.Cu")
		(net "M_H_CPU1_SB_CA<6>")
	)
	(segment
		(start 146.114262 -264.28065)
		(end 146.177254 -264.268204)
		(width 0.0889)
		(layer "In13.Cu")
		(net "M_H_CPU1_SB_CA<6>")
	)
	(segment
		(start 138.103356 -264.693654)
		(end 138.111738 -264.688828)
		(width 0.0889)
		(layer "In13.Cu")
		(net "M_H_CPU1_SB_CA<6>")
	)
	(arc
		(start 143.386048 -264.693654)
		(mid 143.569556 -264.739148)
		(end 143.751808 -264.688828)
		(width 0.0889)
		(layer "In13.Cu")
		(net "M_H_CPU1_SB_CA<6>")
	)
	(arc
		(start 142.437612 -264.688828)
		(mid 142.619863 -264.739178)
		(end 142.803372 -264.693654)
		(width 0.0889)
		(layer "In13.Cu")
		(net "M_H_CPU1_SB_CA<6>")
	)
	(arc
		(start 139.051792 -264.688828)
		(mid 139.334748 -264.612651)
		(end 139.617704 -264.688828)
		(width 0.0889)
		(layer "In13.Cu")
		(net "M_H_CPU1_SB_CA<6>")
	)
	(arc
		(start 139.991846 -264.688828)
		(mid 140.274802 -264.612651)
		(end 140.557758 -264.688828)
		(width 0.0889)
		(layer "In13.Cu")
		(net "M_H_CPU1_SB_CA<6>")
	)
	(arc
		(start 144.334484 -264.698988)
		(mid 144.513205 -264.738911)
		(end 144.689322 -264.688828)
		(width 0.0889)
		(layer "In13.Cu")
		(net "M_H_CPU1_SB_CA<6>")
	)
	(arc
		(start 137.737596 -264.688828)
		(mid 137.919847 -264.739178)
		(end 138.103356 -264.693654)
		(width 0.0889)
		(layer "In13.Cu")
		(net "M_H_CPU1_SB_CA<6>")
	)
	(arc
		(start 145.256504 -264.688828)
		(mid 145.427959 -264.739345)
		(end 145.603214 -264.704322)
		(width 0.0889)
		(layer "In13.Cu")
		(net "M_H_CPU1_SB_CA<6>")
	)
	(arc
		(start 141.497812 -264.688828)
		(mid 141.684756 -264.739083)
		(end 141.8717 -264.688828)
		(width 0.0889)
		(layer "In13.Cu")
		(net "M_H_CPU1_SB_CA<6>")
	)
	(arc
		(start 141.8717 -264.688828)
		(mid 142.154656 -264.612651)
		(end 142.437612 -264.688828)
		(width 0.0889)
		(layer "In13.Cu")
		(net "M_H_CPU1_SB_CA<6>")
	)
	(arc
		(start 137.171684 -264.688828)
		(mid 137.45464 -264.612651)
		(end 137.737596 -264.688828)
		(width 0.0889)
		(layer "In13.Cu")
		(net "M_H_CPU1_SB_CA<6>")
	)
	(arc
		(start 144.71269 -264.675112)
		(mid 144.986344 -264.612169)
		(end 145.256504 -264.688828)
		(width 0.0889)
		(layer "In13.Cu")
		(net "M_H_CPU1_SB_CA<6>")
	)
	(arc
		(start 136.29513 -264.657078)
		(mid 136.550195 -264.613727)
		(end 136.797796 -264.688828)
		(width 0.0889)
		(layer "In13.Cu")
		(net "M_H_CPU1_SB_CA<6>")
	)
	(arc
		(start 139.626086 -264.693654)
		(mid 139.809594 -264.739148)
		(end 139.991846 -264.688828)
		(width 0.0889)
		(layer "In13.Cu")
		(net "M_H_CPU1_SB_CA<6>")
	)
	(arc
		(start 142.811754 -264.688828)
		(mid 143.09471 -264.612651)
		(end 143.377666 -264.688828)
		(width 0.0889)
		(layer "In13.Cu")
		(net "M_H_CPU1_SB_CA<6>")
	)
	(arc
		(start 140.56614 -264.693654)
		(mid 140.749648 -264.739148)
		(end 140.9319 -264.688828)
		(width 0.0889)
		(layer "In13.Cu")
		(net "M_H_CPU1_SB_CA<6>")
	)
	(arc
		(start 138.111738 -264.688828)
		(mid 138.394694 -264.612651)
		(end 138.67765 -264.688828)
		(width 0.0889)
		(layer "In13.Cu")
		(net "M_H_CPU1_SB_CA<6>")
	)
	(arc
		(start 136.797796 -264.688828)
		(mid 136.98474 -264.739083)
		(end 137.171684 -264.688828)
		(width 0.0889)
		(layer "In13.Cu")
		(net "M_H_CPU1_SB_CA<6>")
	)
	(arc
		(start 143.751808 -264.688828)
		(mid 144.021577 -264.612805)
		(end 144.294606 -264.676128)
		(width 0.0889)
		(layer "In13.Cu")
		(net "M_H_CPU1_SB_CA<6>")
	)
	(arc
		(start 140.9319 -264.688828)
		(mid 141.214856 -264.612651)
		(end 141.497812 -264.688828)
		(width 0.0889)
		(layer "In13.Cu")
		(net "M_H_CPU1_SB_CA<6>")
	)
	(arc
		(start 138.67765 -264.688828)
		(mid 138.859901 -264.739178)
		(end 139.04341 -264.693654)
		(width 0.0889)
		(layer "In13.Cu")
		(net "M_H_CPU1_SB_CA<6>")
	)
	(segment
		(start 134.63778 -264.10031)
		(end 135.104632 -264.366248)
		(width 0.10668)
		(layer "F.Cu")
		(net "M_H_CPU1_SB_CA<5>")
	)
	(segment
		(start 139.04341 -264.038842)
		(end 139.044426 -264.03935)
		(width 0.0889)
		(layer "In13.Cu")
		(net "M_H_CPU1_SB_CA<5>")
	)
	(segment
		(start 144.684242 -264.038842)
		(end 144.692624 -264.043668)
		(width 0.0889)
		(layer "In13.Cu")
		(net "M_H_CPU1_SB_CA<5>")
	)
	(segment
		(start 134.950708 -264.100818)
		(end 134.97306 -264.017506)
		(width 0.0889)
		(layer "In13.Cu")
		(net "M_H_CPU1_SB_CA<5>")
	)
	(segment
		(start 168.00576 -264.533888)
		(end 168.15054 -264.678668)
		(width 0.14478)
		(layer "In13.Cu")
		(net "M_H_CPU1_SB_CA<5>")
	)
	(segment
		(start 169.39768 -264.910316)
		(end 170.18254 -264.910316)
		(width 0.14478)
		(layer "In13.Cu")
		(net "M_H_CPU1_SB_CA<5>")
	)
	(segment
		(start 168.8465 -264.533888)
		(end 169.10812 -264.533888)
		(width 0.14478)
		(layer "In13.Cu")
		(net "M_H_CPU1_SB_CA<5>")
	)
	(segment
		(start 168.70172 -264.678668)
		(end 168.8465 -264.533888)
		(width 0.14478)
		(layer "In13.Cu")
		(net "M_H_CPU1_SB_CA<5>")
	)
	(segment
		(start 162.603434 -263.884664)
		(end 164.479224 -265.760454)
		(width 0.14478)
		(layer "In13.Cu")
		(net "M_H_CPU1_SB_CA<5>")
	)
	(segment
		(start 169.2529 -264.678668)
		(end 169.2529 -264.765536)
		(width 0.14478)
		(layer "In13.Cu")
		(net "M_H_CPU1_SB_CA<5>")
	)
	(segment
		(start 139.044426 -264.03935)
		(end 139.051792 -264.043668)
		(width 0.0889)
		(layer "In13.Cu")
		(net "M_H_CPU1_SB_CA<5>")
	)
	(segment
		(start 143.751808 -264.043668)
		(end 143.762222 -264.049764)
		(width 0.0889)
		(layer "In13.Cu")
		(net "M_H_CPU1_SB_CA<5>")
	)
	(segment
		(start 147.2692 -263.992868)
		(end 147.377404 -263.884664)
		(width 0.0889)
		(layer "In13.Cu")
		(net "M_H_CPU1_SB_CA<5>")
	)
	(segment
		(start 171.032678 -265.760454)
		(end 171.5516 -265.760454)
		(width 0.14478)
		(layer "In13.Cu")
		(net "M_H_CPU1_SB_CA<5>")
	)
	(segment
		(start 167.74414 -264.533888)
		(end 168.00576 -264.533888)
		(width 0.14478)
		(layer "In13.Cu")
		(net "M_H_CPU1_SB_CA<5>")
	)
	(segment
		(start 168.15054 -264.765536)
		(end 168.29532 -264.910316)
		(width 0.14478)
		(layer "In13.Cu")
		(net "M_H_CPU1_SB_CA<5>")
	)
	(segment
		(start 167.59936 -264.678668)
		(end 167.74414 -264.533888)
		(width 0.14478)
		(layer "In13.Cu")
		(net "M_H_CPU1_SB_CA<5>")
	)
	(segment
		(start 147.377404 -263.884664)
		(end 147.973796 -263.884664)
		(width 0.0889)
		(layer "In13.Cu")
		(net "M_H_CPU1_SB_CA<5>")
	)
	(segment
		(start 143.377666 -264.043668)
		(end 143.386048 -264.038842)
		(width 0.0889)
		(layer "In13.Cu")
		(net "M_H_CPU1_SB_CA<5>")
	)
	(segment
		(start 169.10812 -264.533888)
		(end 169.2529 -264.678668)
		(width 0.14478)
		(layer "In13.Cu")
		(net "M_H_CPU1_SB_CA<5>")
	)
	(segment
		(start 135.104632 -264.366248)
		(end 134.950708 -264.100818)
		(width 0.0889)
		(layer "In13.Cu")
		(net "M_H_CPU1_SB_CA<5>")
	)
	(segment
		(start 171.5516 -265.760454)
		(end 171.97197 -265.340084)
		(width 0.14478)
		(layer "In13.Cu")
		(net "M_H_CPU1_SB_CA<5>")
	)
	(segment
		(start 168.15054 -264.678668)
		(end 168.15054 -264.765536)
		(width 0.14478)
		(layer "In13.Cu")
		(net "M_H_CPU1_SB_CA<5>")
	)
	(segment
		(start 147.973796 -263.884664)
		(end 162.603434 -263.884664)
		(width 0.14478)
		(layer "In13.Cu")
		(net "M_H_CPU1_SB_CA<5>")
	)
	(segment
		(start 139.617704 -264.043668)
		(end 139.626086 -264.038842)
		(width 0.0889)
		(layer "In13.Cu")
		(net "M_H_CPU1_SB_CA<5>")
	)
	(segment
		(start 142.803372 -264.038842)
		(end 142.811754 -264.043668)
		(width 0.0889)
		(layer "In13.Cu")
		(net "M_H_CPU1_SB_CA<5>")
	)
	(segment
		(start 164.479224 -265.760454)
		(end 166.150036 -265.760454)
		(width 0.14478)
		(layer "In13.Cu")
		(net "M_H_CPU1_SB_CA<5>")
	)
	(segment
		(start 169.2529 -264.765536)
		(end 169.39768 -264.910316)
		(width 0.14478)
		(layer "In13.Cu")
		(net "M_H_CPU1_SB_CA<5>")
	)
	(segment
		(start 166.150036 -265.760454)
		(end 167.000174 -264.910316)
		(width 0.14478)
		(layer "In13.Cu")
		(net "M_H_CPU1_SB_CA<5>")
	)
	(segment
		(start 168.70172 -264.765536)
		(end 168.70172 -264.678668)
		(width 0.14478)
		(layer "In13.Cu")
		(net "M_H_CPU1_SB_CA<5>")
	)
	(segment
		(start 167.59936 -264.765536)
		(end 167.59936 -264.678668)
		(width 0.14478)
		(layer "In13.Cu")
		(net "M_H_CPU1_SB_CA<5>")
	)
	(segment
		(start 167.000174 -264.910316)
		(end 167.45458 -264.910316)
		(width 0.14478)
		(layer "In13.Cu")
		(net "M_H_CPU1_SB_CA<5>")
	)
	(segment
		(start 168.55694 -264.910316)
		(end 168.70172 -264.765536)
		(width 0.14478)
		(layer "In13.Cu")
		(net "M_H_CPU1_SB_CA<5>")
	)
	(segment
		(start 171.97197 -265.340084)
		(end 171.97197 -265.335258)
		(width 0.14478)
		(layer "In13.Cu")
		(net "M_H_CPU1_SB_CA<5>")
	)
	(segment
		(start 167.45458 -264.910316)
		(end 167.59936 -264.765536)
		(width 0.14478)
		(layer "In13.Cu")
		(net "M_H_CPU1_SB_CA<5>")
	)
	(segment
		(start 170.18254 -264.910316)
		(end 171.032678 -265.760454)
		(width 0.14478)
		(layer "In13.Cu")
		(net "M_H_CPU1_SB_CA<5>")
	)
	(segment
		(start 145.444718 -263.992868)
		(end 147.2692 -263.992868)
		(width 0.0889)
		(layer "In13.Cu")
		(net "M_H_CPU1_SB_CA<5>")
	)
	(segment
		(start 138.103356 -264.038842)
		(end 138.111738 -264.043668)
		(width 0.0889)
		(layer "In13.Cu")
		(net "M_H_CPU1_SB_CA<5>")
	)
	(segment
		(start 140.557758 -264.043668)
		(end 140.56614 -264.038842)
		(width 0.0889)
		(layer "In13.Cu")
		(net "M_H_CPU1_SB_CA<5>")
	)
	(segment
		(start 168.29532 -264.910316)
		(end 168.55694 -264.910316)
		(width 0.14478)
		(layer "In13.Cu")
		(net "M_H_CPU1_SB_CA<5>")
	)
	(segment
		(start 135.857742 -264.043668)
		(end 135.866124 -264.038842)
		(width 0.0889)
		(layer "In13.Cu")
		(net "M_H_CPU1_SB_CA<5>")
	)
	(arc
		(start 137.737596 -264.043668)
		(mid 137.919847 -263.993318)
		(end 138.103356 -264.038842)
		(width 0.0889)
		(layer "In13.Cu")
		(net "M_H_CPU1_SB_CA<5>")
	)
	(arc
		(start 138.67765 -264.043668)
		(mid 138.859901 -263.993318)
		(end 139.04341 -264.038842)
		(width 0.0889)
		(layer "In13.Cu")
		(net "M_H_CPU1_SB_CA<5>")
	)
	(arc
		(start 134.97306 -264.017506)
		(mid 135.135392 -263.994688)
		(end 135.29183 -264.043668)
		(width 0.0889)
		(layer "In13.Cu")
		(net "M_H_CPU1_SB_CA<5>")
	)
	(arc
		(start 141.497812 -264.043668)
		(mid 141.684756 -263.993413)
		(end 141.8717 -264.043668)
		(width 0.0889)
		(layer "In13.Cu")
		(net "M_H_CPU1_SB_CA<5>")
	)
	(arc
		(start 140.56614 -264.038842)
		(mid 140.749648 -263.993348)
		(end 140.9319 -264.043668)
		(width 0.0889)
		(layer "In13.Cu")
		(net "M_H_CPU1_SB_CA<5>")
	)
	(arc
		(start 135.29183 -264.043668)
		(mid 135.574786 -264.119845)
		(end 135.857742 -264.043668)
		(width 0.0889)
		(layer "In13.Cu")
		(net "M_H_CPU1_SB_CA<5>")
	)
	(arc
		(start 144.692624 -264.043668)
		(mid 144.972052 -264.119834)
		(end 145.25244 -264.047224)
		(width 0.0889)
		(layer "In13.Cu")
		(net "M_H_CPU1_SB_CA<5>")
	)
	(arc
		(start 145.25244 -264.047224)
		(mid 145.344872 -264.006942)
		(end 145.444718 -263.992868)
		(width 0.0889)
		(layer "In13.Cu")
		(net "M_H_CPU1_SB_CA<5>")
	)
	(arc
		(start 137.171684 -264.043668)
		(mid 137.45464 -264.119845)
		(end 137.737596 -264.043668)
		(width 0.0889)
		(layer "In13.Cu")
		(net "M_H_CPU1_SB_CA<5>")
	)
	(arc
		(start 139.991846 -264.043668)
		(mid 140.274802 -264.119845)
		(end 140.557758 -264.043668)
		(width 0.0889)
		(layer "In13.Cu")
		(net "M_H_CPU1_SB_CA<5>")
	)
	(arc
		(start 139.051792 -264.043668)
		(mid 139.334748 -264.119845)
		(end 139.617704 -264.043668)
		(width 0.0889)
		(layer "In13.Cu")
		(net "M_H_CPU1_SB_CA<5>")
	)
	(arc
		(start 136.797796 -264.043668)
		(mid 136.98474 -263.993413)
		(end 137.171684 -264.043668)
		(width 0.0889)
		(layer "In13.Cu")
		(net "M_H_CPU1_SB_CA<5>")
	)
	(arc
		(start 143.386048 -264.038842)
		(mid 143.569556 -263.993348)
		(end 143.751808 -264.043668)
		(width 0.0889)
		(layer "In13.Cu")
		(net "M_H_CPU1_SB_CA<5>")
	)
	(arc
		(start 136.231884 -264.043668)
		(mid 136.51484 -264.119845)
		(end 136.797796 -264.043668)
		(width 0.0889)
		(layer "In13.Cu")
		(net "M_H_CPU1_SB_CA<5>")
	)
	(arc
		(start 139.626086 -264.038842)
		(mid 139.809594 -263.993348)
		(end 139.991846 -264.043668)
		(width 0.0889)
		(layer "In13.Cu")
		(net "M_H_CPU1_SB_CA<5>")
	)
	(arc
		(start 144.317974 -264.043668)
		(mid 144.500479 -263.993191)
		(end 144.684242 -264.038842)
		(width 0.0889)
		(layer "In13.Cu")
		(net "M_H_CPU1_SB_CA<5>")
	)
	(arc
		(start 138.111738 -264.043668)
		(mid 138.394694 -264.119845)
		(end 138.67765 -264.043668)
		(width 0.0889)
		(layer "In13.Cu")
		(net "M_H_CPU1_SB_CA<5>")
	)
	(arc
		(start 142.811754 -264.043668)
		(mid 143.09471 -264.119845)
		(end 143.377666 -264.043668)
		(width 0.0889)
		(layer "In13.Cu")
		(net "M_H_CPU1_SB_CA<5>")
	)
	(arc
		(start 142.437612 -264.043668)
		(mid 142.619863 -263.993318)
		(end 142.803372 -264.038842)
		(width 0.0889)
		(layer "In13.Cu")
		(net "M_H_CPU1_SB_CA<5>")
	)
	(arc
		(start 141.8717 -264.043668)
		(mid 142.154656 -264.119845)
		(end 142.437612 -264.043668)
		(width 0.0889)
		(layer "In13.Cu")
		(net "M_H_CPU1_SB_CA<5>")
	)
	(arc
		(start 143.762222 -264.049764)
		(mid 144.040908 -264.119984)
		(end 144.317974 -264.043668)
		(width 0.0889)
		(layer "In13.Cu")
		(net "M_H_CPU1_SB_CA<5>")
	)
	(arc
		(start 140.9319 -264.043668)
		(mid 141.214856 -264.119845)
		(end 141.497812 -264.043668)
		(width 0.0889)
		(layer "In13.Cu")
		(net "M_H_CPU1_SB_CA<5>")
	)
	(arc
		(start 135.866124 -264.038842)
		(mid 136.049632 -263.993348)
		(end 136.231884 -264.043668)
		(width 0.0889)
		(layer "In13.Cu")
		(net "M_H_CPU1_SB_CA<5>")
	)
	(segment
		(start 134.16788 -263.290304)
		(end 134.634732 -263.556242)
		(width 0.10668)
		(layer "F.Cu")
		(net "M_H_CPU1_SB_CA<4>")
	)
	(segment
		(start 162.78479 -263.430004)
		(end 164.265102 -264.910316)
		(width 0.14478)
		(layer "In13.Cu")
		(net "M_H_CPU1_SB_CA<4>")
	)
	(segment
		(start 145.44421 -263.802368)
		(end 147.08759 -263.802368)
		(width 0.0889)
		(layer "In13.Cu")
		(net "M_H_CPU1_SB_CA<4>")
	)
	(segment
		(start 147.08759 -263.802368)
		(end 147.459954 -263.430004)
		(width 0.0889)
		(layer "In13.Cu")
		(net "M_H_CPU1_SB_CA<4>")
	)
	(segment
		(start 143.847566 -263.878822)
		(end 143.855948 -263.883648)
		(width 0.0889)
		(layer "In13.Cu")
		(net "M_H_CPU1_SB_CA<4>")
	)
	(segment
		(start 141.393418 -263.883648)
		(end 141.4018 -263.878822)
		(width 0.0889)
		(layer "In13.Cu")
		(net "M_H_CPU1_SB_CA<4>")
	)
	(segment
		(start 141.967712 -263.878822)
		(end 141.976094 -263.883648)
		(width 0.0889)
		(layer "In13.Cu")
		(net "M_H_CPU1_SB_CA<4>")
	)
	(segment
		(start 140.453364 -263.883648)
		(end 140.461746 -263.878822)
		(width 0.0889)
		(layer "In13.Cu")
		(net "M_H_CPU1_SB_CA<4>")
	)
	(segment
		(start 134.788656 -263.821672)
		(end 134.884668 -263.847072)
		(width 0.0889)
		(layer "In13.Cu")
		(net "M_H_CPU1_SB_CA<4>")
	)
	(segment
		(start 148.002244 -263.430004)
		(end 162.78479 -263.430004)
		(width 0.14478)
		(layer "In13.Cu")
		(net "M_H_CPU1_SB_CA<4>")
	)
	(segment
		(start 147.459954 -263.430004)
		(end 148.002244 -263.430004)
		(width 0.0889)
		(layer "In13.Cu")
		(net "M_H_CPU1_SB_CA<4>")
	)
	(segment
		(start 167.092884 -264.060432)
		(end 170.117516 -264.060432)
		(width 0.14478)
		(layer "In13.Cu")
		(net "M_H_CPU1_SB_CA<4>")
	)
	(segment
		(start 137.267696 -263.878822)
		(end 137.276078 -263.883648)
		(width 0.0889)
		(layer "In13.Cu")
		(net "M_H_CPU1_SB_CA<4>")
	)
	(segment
		(start 175.923702 -264.485374)
		(end 176.072038 -264.485374)
		(width 0.14478)
		(layer "In13.Cu")
		(net "M_H_CPU1_SB_CA<4>")
	)
	(segment
		(start 170.117516 -264.060432)
		(end 170.9674 -264.910316)
		(width 0.14478)
		(layer "In13.Cu")
		(net "M_H_CPU1_SB_CA<4>")
	)
	(segment
		(start 166.243 -264.910316)
		(end 167.092884 -264.060432)
		(width 0.14478)
		(layer "In13.Cu")
		(net "M_H_CPU1_SB_CA<4>")
	)
	(segment
		(start 170.9674 -264.910316)
		(end 173.787054 -264.910316)
		(width 0.14478)
		(layer "In13.Cu")
		(net "M_H_CPU1_SB_CA<4>")
	)
	(segment
		(start 173.787054 -264.910316)
		(end 175.923702 -264.485374)
		(width 0.14478)
		(layer "In13.Cu")
		(net "M_H_CPU1_SB_CA<4>")
	)
	(segment
		(start 144.777968 -263.872726)
		(end 144.788382 -263.878822)
		(width 0.0889)
		(layer "In13.Cu")
		(net "M_H_CPU1_SB_CA<4>")
	)
	(segment
		(start 135.753348 -263.883648)
		(end 135.76173 -263.878822)
		(width 0.0889)
		(layer "In13.Cu")
		(net "M_H_CPU1_SB_CA<4>")
	)
	(segment
		(start 138.20775 -263.878822)
		(end 138.216132 -263.883648)
		(width 0.0889)
		(layer "In13.Cu")
		(net "M_H_CPU1_SB_CA<4>")
	)
	(segment
		(start 164.265102 -264.910316)
		(end 166.243 -264.910316)
		(width 0.14478)
		(layer "In13.Cu")
		(net "M_H_CPU1_SB_CA<4>")
	)
	(segment
		(start 134.634732 -263.556242)
		(end 134.788656 -263.821672)
		(width 0.0889)
		(layer "In13.Cu")
		(net "M_H_CPU1_SB_CA<4>")
	)
	(segment
		(start 136.693402 -263.883648)
		(end 136.701784 -263.878822)
		(width 0.0889)
		(layer "In13.Cu")
		(net "M_H_CPU1_SB_CA<4>")
	)
	(arc
		(start 145.146014 -263.887966)
		(mid 145.289108 -263.824249)
		(end 145.44421 -263.802368)
		(width 0.0889)
		(layer "In13.Cu")
		(net "M_H_CPU1_SB_CA<4>")
	)
	(arc
		(start 136.327642 -263.878822)
		(mid 136.509893 -263.929172)
		(end 136.693402 -263.883648)
		(width 0.0889)
		(layer "In13.Cu")
		(net "M_H_CPU1_SB_CA<4>")
	)
	(arc
		(start 144.788382 -263.878822)
		(mid 144.966032 -263.929082)
		(end 145.146014 -263.887966)
		(width 0.0889)
		(layer "In13.Cu")
		(net "M_H_CPU1_SB_CA<4>")
	)
	(arc
		(start 143.855948 -263.883648)
		(mid 144.03971 -263.929264)
		(end 144.222216 -263.878822)
		(width 0.0889)
		(layer "In13.Cu")
		(net "M_H_CPU1_SB_CA<4>")
	)
	(arc
		(start 141.4018 -263.878822)
		(mid 141.684756 -263.802645)
		(end 141.967712 -263.878822)
		(width 0.0889)
		(layer "In13.Cu")
		(net "M_H_CPU1_SB_CA<4>")
	)
	(arc
		(start 142.341854 -263.878822)
		(mid 142.62481 -263.802645)
		(end 142.907766 -263.878822)
		(width 0.0889)
		(layer "In13.Cu")
		(net "M_H_CPU1_SB_CA<4>")
	)
	(arc
		(start 144.222216 -263.878822)
		(mid 144.499283 -263.802551)
		(end 144.777968 -263.872726)
		(width 0.0889)
		(layer "In13.Cu")
		(net "M_H_CPU1_SB_CA<4>")
	)
	(arc
		(start 143.281654 -263.878822)
		(mid 143.56461 -263.802645)
		(end 143.847566 -263.878822)
		(width 0.0889)
		(layer "In13.Cu")
		(net "M_H_CPU1_SB_CA<4>")
	)
	(arc
		(start 135.76173 -263.878822)
		(mid 136.044686 -263.802645)
		(end 136.327642 -263.878822)
		(width 0.0889)
		(layer "In13.Cu")
		(net "M_H_CPU1_SB_CA<4>")
	)
	(arc
		(start 134.884668 -263.847072)
		(mid 135.139876 -263.803595)
		(end 135.387588 -263.878822)
		(width 0.0889)
		(layer "In13.Cu")
		(net "M_H_CPU1_SB_CA<4>")
	)
	(arc
		(start 140.461746 -263.878822)
		(mid 140.744702 -263.802645)
		(end 141.027658 -263.878822)
		(width 0.0889)
		(layer "In13.Cu")
		(net "M_H_CPU1_SB_CA<4>")
	)
	(arc
		(start 140.087604 -263.878822)
		(mid 140.269855 -263.929172)
		(end 140.453364 -263.883648)
		(width 0.0889)
		(layer "In13.Cu")
		(net "M_H_CPU1_SB_CA<4>")
	)
	(arc
		(start 141.976094 -263.883648)
		(mid 142.159602 -263.929142)
		(end 142.341854 -263.878822)
		(width 0.0889)
		(layer "In13.Cu")
		(net "M_H_CPU1_SB_CA<4>")
	)
	(arc
		(start 142.907766 -263.878822)
		(mid 143.09471 -263.929077)
		(end 143.281654 -263.878822)
		(width 0.0889)
		(layer "In13.Cu")
		(net "M_H_CPU1_SB_CA<4>")
	)
	(arc
		(start 135.387588 -263.878822)
		(mid 135.569839 -263.929172)
		(end 135.753348 -263.883648)
		(width 0.0889)
		(layer "In13.Cu")
		(net "M_H_CPU1_SB_CA<4>")
	)
	(arc
		(start 139.521692 -263.878822)
		(mid 139.804648 -263.802645)
		(end 140.087604 -263.878822)
		(width 0.0889)
		(layer "In13.Cu")
		(net "M_H_CPU1_SB_CA<4>")
	)
	(arc
		(start 139.147804 -263.878822)
		(mid 139.334748 -263.929077)
		(end 139.521692 -263.878822)
		(width 0.0889)
		(layer "In13.Cu")
		(net "M_H_CPU1_SB_CA<4>")
	)
	(arc
		(start 137.276078 -263.883648)
		(mid 137.459586 -263.929142)
		(end 137.641838 -263.878822)
		(width 0.0889)
		(layer "In13.Cu")
		(net "M_H_CPU1_SB_CA<4>")
	)
	(arc
		(start 137.641838 -263.878822)
		(mid 137.924794 -263.802645)
		(end 138.20775 -263.878822)
		(width 0.0889)
		(layer "In13.Cu")
		(net "M_H_CPU1_SB_CA<4>")
	)
	(arc
		(start 138.216132 -263.883648)
		(mid 138.39964 -263.929142)
		(end 138.581892 -263.878822)
		(width 0.0889)
		(layer "In13.Cu")
		(net "M_H_CPU1_SB_CA<4>")
	)
	(arc
		(start 141.027658 -263.878822)
		(mid 141.209909 -263.929172)
		(end 141.393418 -263.883648)
		(width 0.0889)
		(layer "In13.Cu")
		(net "M_H_CPU1_SB_CA<4>")
	)
	(arc
		(start 136.701784 -263.878822)
		(mid 136.98474 -263.802645)
		(end 137.267696 -263.878822)
		(width 0.0889)
		(layer "In13.Cu")
		(net "M_H_CPU1_SB_CA<4>")
	)
	(arc
		(start 138.581892 -263.878822)
		(mid 138.864848 -263.802645)
		(end 139.147804 -263.878822)
		(width 0.0889)
		(layer "In13.Cu")
		(net "M_H_CPU1_SB_CA<4>")
	)
	(segment
		(start 136.047988 -263.290304)
		(end 136.51484 -263.556242)
		(width 0.10668)
		(layer "F.Cu")
		(net "M_H_CPU1_SB_CA<3>")
	)
	(segment
		(start 158.526734 -262.442706)
		(end 158.298388 -262.442706)
		(width 0.14478)
		(layer "In13.Cu")
		(net "M_H_CPU1_SB_CA<3>")
	)
	(segment
		(start 138.216132 -263.228836)
		(end 138.20775 -263.233662)
		(width 0.0889)
		(layer "In13.Cu")
		(net "M_H_CPU1_SB_CA<3>")
	)
	(segment
		(start 171.97197 -263.635236)
		(end 171.97197 -263.665462)
		(width 0.14478)
		(layer "In13.Cu")
		(net "M_H_CPU1_SB_CA<3>")
	)
	(segment
		(start 159.239712 -262.8138)
		(end 159.078168 -262.975344)
		(width 0.14478)
		(layer "In13.Cu")
		(net "M_H_CPU1_SB_CA<3>")
	)
	(segment
		(start 164.0586 -264.060432)
		(end 162.973512 -262.975344)
		(width 0.14478)
		(layer "In13.Cu")
		(net "M_H_CPU1_SB_CA<3>")
	)
	(segment
		(start 148.009864 -262.975344)
		(end 147.348194 -262.975344)
		(width 0.0889)
		(layer "In13.Cu")
		(net "M_H_CPU1_SB_CA<3>")
	)
	(segment
		(start 157.033976 -262.8138)
		(end 156.872432 -262.975344)
		(width 0.14478)
		(layer "In13.Cu")
		(net "M_H_CPU1_SB_CA<3>")
	)
	(segment
		(start 140.461746 -263.233662)
		(end 140.453364 -263.228836)
		(width 0.0889)
		(layer "In13.Cu")
		(net "M_H_CPU1_SB_CA<3>")
	)
	(segment
		(start 157.423866 -262.442706)
		(end 157.19552 -262.442706)
		(width 0.14478)
		(layer "In13.Cu")
		(net "M_H_CPU1_SB_CA<3>")
	)
	(segment
		(start 166.150036 -264.060432)
		(end 164.0586 -264.060432)
		(width 0.14478)
		(layer "In13.Cu")
		(net "M_H_CPU1_SB_CA<3>")
	)
	(segment
		(start 144.242536 -263.246362)
		(end 144.220946 -263.233916)
		(width 0.0889)
		(layer "In13.Cu")
		(net "M_H_CPU1_SB_CA<3>")
	)
	(segment
		(start 159.791146 -262.60425)
		(end 159.629602 -262.442706)
		(width 0.14478)
		(layer "In13.Cu")
		(net "M_H_CPU1_SB_CA<3>")
	)
	(segment
		(start 146.527012 -262.924544)
		(end 146.141186 -263.31037)
		(width 0.0889)
		(layer "In13.Cu")
		(net "M_H_CPU1_SB_CA<3>")
	)
	(segment
		(start 136.360662 -263.290812)
		(end 136.51484 -263.556242)
		(width 0.0889)
		(layer "In13.Cu")
		(net "M_H_CPU1_SB_CA<3>")
	)
	(segment
		(start 157.58541 -262.60425)
		(end 157.423866 -262.442706)
		(width 0.14478)
		(layer "In13.Cu")
		(net "M_H_CPU1_SB_CA<3>")
	)
	(segment
		(start 158.136844 -262.8138)
		(end 157.9753 -262.975344)
		(width 0.14478)
		(layer "In13.Cu")
		(net "M_H_CPU1_SB_CA<3>")
	)
	(segment
		(start 158.688278 -262.60425)
		(end 158.526734 -262.442706)
		(width 0.14478)
		(layer "In13.Cu")
		(net "M_H_CPU1_SB_CA<3>")
	)
	(segment
		(start 144.80413 -263.22274)
		(end 144.785334 -263.233662)
		(width 0.0889)
		(layer "In13.Cu")
		(net "M_H_CPU1_SB_CA<3>")
	)
	(segment
		(start 156.872432 -262.975344)
		(end 148.009864 -262.975344)
		(width 0.14478)
		(layer "In13.Cu")
		(net "M_H_CPU1_SB_CA<3>")
	)
	(segment
		(start 159.791146 -262.8138)
		(end 159.791146 -262.60425)
		(width 0.14478)
		(layer "In13.Cu")
		(net "M_H_CPU1_SB_CA<3>")
	)
	(segment
		(start 167.000174 -263.210294)
		(end 166.150036 -264.060432)
		(width 0.14478)
		(layer "In13.Cu")
		(net "M_H_CPU1_SB_CA<3>")
	)
	(segment
		(start 158.298388 -262.442706)
		(end 158.136844 -262.60425)
		(width 0.14478)
		(layer "In13.Cu")
		(net "M_H_CPU1_SB_CA<3>")
	)
	(segment
		(start 159.239712 -262.60425)
		(end 159.239712 -262.8138)
		(width 0.14478)
		(layer "In13.Cu")
		(net "M_H_CPU1_SB_CA<3>")
	)
	(segment
		(start 157.9753 -262.975344)
		(end 157.746954 -262.975344)
		(width 0.14478)
		(layer "In13.Cu")
		(net "M_H_CPU1_SB_CA<3>")
	)
	(segment
		(start 136.383014 -263.2075)
		(end 136.360662 -263.290812)
		(width 0.0889)
		(layer "In13.Cu")
		(net "M_H_CPU1_SB_CA<3>")
	)
	(segment
		(start 144.220946 -263.233916)
		(end 144.20088 -263.222486)
		(width 0.0889)
		(layer "In13.Cu")
		(net "M_H_CPU1_SB_CA<3>")
	)
	(segment
		(start 136.701784 -263.233662)
		(end 136.693402 -263.228836)
		(width 0.0889)
		(layer "In13.Cu")
		(net "M_H_CPU1_SB_CA<3>")
	)
	(segment
		(start 157.033976 -262.60425)
		(end 157.033976 -262.8138)
		(width 0.14478)
		(layer "In13.Cu")
		(net "M_H_CPU1_SB_CA<3>")
	)
	(segment
		(start 159.078168 -262.975344)
		(end 158.849822 -262.975344)
		(width 0.14478)
		(layer "In13.Cu")
		(net "M_H_CPU1_SB_CA<3>")
	)
	(segment
		(start 157.19552 -262.442706)
		(end 157.033976 -262.60425)
		(width 0.14478)
		(layer "In13.Cu")
		(net "M_H_CPU1_SB_CA<3>")
	)
	(segment
		(start 158.849822 -262.975344)
		(end 158.688278 -262.8138)
		(width 0.14478)
		(layer "In13.Cu")
		(net "M_H_CPU1_SB_CA<3>")
	)
	(segment
		(start 141.4018 -263.233662)
		(end 141.393418 -263.228836)
		(width 0.0889)
		(layer "In13.Cu")
		(net "M_H_CPU1_SB_CA<3>")
	)
	(segment
		(start 158.136844 -262.60425)
		(end 158.136844 -262.8138)
		(width 0.14478)
		(layer "In13.Cu")
		(net "M_H_CPU1_SB_CA<3>")
	)
	(segment
		(start 170.18254 -263.210294)
		(end 167.000174 -263.210294)
		(width 0.14478)
		(layer "In13.Cu")
		(net "M_H_CPU1_SB_CA<3>")
	)
	(segment
		(start 159.629602 -262.442706)
		(end 159.401256 -262.442706)
		(width 0.14478)
		(layer "In13.Cu")
		(net "M_H_CPU1_SB_CA<3>")
	)
	(segment
		(start 147.297394 -262.924544)
		(end 146.527012 -262.924544)
		(width 0.0889)
		(layer "In13.Cu")
		(net "M_H_CPU1_SB_CA<3>")
	)
	(segment
		(start 171.032678 -264.060432)
		(end 170.18254 -263.210294)
		(width 0.14478)
		(layer "In13.Cu")
		(net "M_H_CPU1_SB_CA<3>")
	)
	(segment
		(start 162.973512 -262.975344)
		(end 159.95269 -262.975344)
		(width 0.14478)
		(layer "In13.Cu")
		(net "M_H_CPU1_SB_CA<3>")
	)
	(segment
		(start 159.95269 -262.975344)
		(end 159.791146 -262.8138)
		(width 0.14478)
		(layer "In13.Cu")
		(net "M_H_CPU1_SB_CA<3>")
	)
	(segment
		(start 158.688278 -262.8138)
		(end 158.688278 -262.60425)
		(width 0.14478)
		(layer "In13.Cu")
		(net "M_H_CPU1_SB_CA<3>")
	)
	(segment
		(start 159.401256 -262.442706)
		(end 159.239712 -262.60425)
		(width 0.14478)
		(layer "In13.Cu")
		(net "M_H_CPU1_SB_CA<3>")
	)
	(segment
		(start 157.746954 -262.975344)
		(end 157.58541 -262.8138)
		(width 0.14478)
		(layer "In13.Cu")
		(net "M_H_CPU1_SB_CA<3>")
	)
	(segment
		(start 171.577 -264.060432)
		(end 171.032678 -264.060432)
		(width 0.14478)
		(layer "In13.Cu")
		(net "M_H_CPU1_SB_CA<3>")
	)
	(segment
		(start 147.348194 -262.975344)
		(end 147.297394 -262.924544)
		(width 0.0889)
		(layer "In13.Cu")
		(net "M_H_CPU1_SB_CA<3>")
	)
	(segment
		(start 146.141186 -263.31037)
		(end 145.444718 -263.31037)
		(width 0.0889)
		(layer "In13.Cu")
		(net "M_H_CPU1_SB_CA<3>")
	)
	(segment
		(start 157.58541 -262.8138)
		(end 157.58541 -262.60425)
		(width 0.14478)
		(layer "In13.Cu")
		(net "M_H_CPU1_SB_CA<3>")
	)
	(segment
		(start 137.276078 -263.228836)
		(end 137.267696 -263.233662)
		(width 0.0889)
		(layer "In13.Cu")
		(net "M_H_CPU1_SB_CA<3>")
	)
	(segment
		(start 141.976094 -263.228836)
		(end 141.967712 -263.233662)
		(width 0.0889)
		(layer "In13.Cu")
		(net "M_H_CPU1_SB_CA<3>")
	)
	(segment
		(start 171.97197 -263.665462)
		(end 171.577 -264.060432)
		(width 0.14478)
		(layer "In13.Cu")
		(net "M_H_CPU1_SB_CA<3>")
	)
	(arc
		(start 138.581892 -263.233662)
		(mid 138.399641 -263.183312)
		(end 138.216132 -263.228836)
		(width 0.0889)
		(layer "In13.Cu")
		(net "M_H_CPU1_SB_CA<3>")
	)
	(arc
		(start 144.20088 -263.222486)
		(mid 144.022802 -263.183502)
		(end 143.847566 -263.233662)
		(width 0.0889)
		(layer "In13.Cu")
		(net "M_H_CPU1_SB_CA<3>")
	)
	(arc
		(start 137.267696 -263.233662)
		(mid 136.98474 -263.309839)
		(end 136.701784 -263.233662)
		(width 0.0889)
		(layer "In13.Cu")
		(net "M_H_CPU1_SB_CA<3>")
	)
	(arc
		(start 136.693402 -263.228836)
		(mid 136.540532 -263.184195)
		(end 136.383014 -263.2075)
		(width 0.0889)
		(layer "In13.Cu")
		(net "M_H_CPU1_SB_CA<3>")
	)
	(arc
		(start 145.444718 -263.31037)
		(mid 145.297509 -263.290893)
		(end 145.160492 -263.233662)
		(width 0.0889)
		(layer "In13.Cu")
		(net "M_H_CPU1_SB_CA<3>")
	)
	(arc
		(start 141.393418 -263.228836)
		(mid 141.20991 -263.183342)
		(end 141.027658 -263.233662)
		(width 0.0889)
		(layer "In13.Cu")
		(net "M_H_CPU1_SB_CA<3>")
	)
	(arc
		(start 139.521692 -263.233662)
		(mid 139.334748 -263.183407)
		(end 139.147804 -263.233662)
		(width 0.0889)
		(layer "In13.Cu")
		(net "M_H_CPU1_SB_CA<3>")
	)
	(arc
		(start 143.847566 -263.233662)
		(mid 143.56461 -263.309839)
		(end 143.281654 -263.233662)
		(width 0.0889)
		(layer "In13.Cu")
		(net "M_H_CPU1_SB_CA<3>")
	)
	(arc
		(start 139.147804 -263.233662)
		(mid 138.864848 -263.309839)
		(end 138.581892 -263.233662)
		(width 0.0889)
		(layer "In13.Cu")
		(net "M_H_CPU1_SB_CA<3>")
	)
	(arc
		(start 137.641838 -263.233662)
		(mid 137.459587 -263.183312)
		(end 137.276078 -263.228836)
		(width 0.0889)
		(layer "In13.Cu")
		(net "M_H_CPU1_SB_CA<3>")
	)
	(arc
		(start 143.281654 -263.233662)
		(mid 143.09471 -263.183407)
		(end 142.907766 -263.233662)
		(width 0.0889)
		(layer "In13.Cu")
		(net "M_H_CPU1_SB_CA<3>")
	)
	(arc
		(start 144.785334 -263.233662)
		(mid 144.515565 -263.309685)
		(end 144.242536 -263.246362)
		(width 0.0889)
		(layer "In13.Cu")
		(net "M_H_CPU1_SB_CA<3>")
	)
	(arc
		(start 142.341854 -263.233662)
		(mid 142.159603 -263.183312)
		(end 141.976094 -263.228836)
		(width 0.0889)
		(layer "In13.Cu")
		(net "M_H_CPU1_SB_CA<3>")
	)
	(arc
		(start 140.453364 -263.228836)
		(mid 140.269856 -263.183342)
		(end 140.087604 -263.233662)
		(width 0.0889)
		(layer "In13.Cu")
		(net "M_H_CPU1_SB_CA<3>")
	)
	(arc
		(start 138.20775 -263.233662)
		(mid 137.924794 -263.309839)
		(end 137.641838 -263.233662)
		(width 0.0889)
		(layer "In13.Cu")
		(net "M_H_CPU1_SB_CA<3>")
	)
	(arc
		(start 141.027658 -263.233662)
		(mid 140.744702 -263.309839)
		(end 140.461746 -263.233662)
		(width 0.0889)
		(layer "In13.Cu")
		(net "M_H_CPU1_SB_CA<3>")
	)
	(arc
		(start 145.160492 -263.233662)
		(mid 144.983701 -263.182943)
		(end 144.80413 -263.22274)
		(width 0.0889)
		(layer "In13.Cu")
		(net "M_H_CPU1_SB_CA<3>")
	)
	(arc
		(start 141.967712 -263.233662)
		(mid 141.684756 -263.309839)
		(end 141.4018 -263.233662)
		(width 0.0889)
		(layer "In13.Cu")
		(net "M_H_CPU1_SB_CA<3>")
	)
	(arc
		(start 142.907766 -263.233662)
		(mid 142.62481 -263.309839)
		(end 142.341854 -263.233662)
		(width 0.0889)
		(layer "In13.Cu")
		(net "M_H_CPU1_SB_CA<3>")
	)
	(arc
		(start 140.087604 -263.233662)
		(mid 139.804648 -263.309839)
		(end 139.521692 -263.233662)
		(width 0.0889)
		(layer "In13.Cu")
		(net "M_H_CPU1_SB_CA<3>")
	)
	(segment
		(start 135.577834 -262.480298)
		(end 136.044686 -262.746236)
		(width 0.10668)
		(layer "F.Cu")
		(net "M_H_CPU1_SB_CA<2>")
	)
	(segment
		(start 173.935898 -263.210294)
		(end 176.072038 -262.785352)
		(width 0.14478)
		(layer "In13.Cu")
		(net "M_H_CPU1_SB_CA<2>")
	)
	(segment
		(start 147.370038 -262.520684)
		(end 148.016468 -262.520684)
		(width 0.0889)
		(layer "In13.Cu")
		(net "M_H_CPU1_SB_CA<2>")
	)
	(segment
		(start 164.14877 -263.210294)
		(end 166.243 -263.210294)
		(width 0.14478)
		(layer "In13.Cu")
		(net "M_H_CPU1_SB_CA<2>")
	)
	(segment
		(start 146.042126 -263.11987)
		(end 146.440652 -262.721344)
		(width 0.0889)
		(layer "In13.Cu")
		(net "M_H_CPU1_SB_CA<2>")
	)
	(segment
		(start 167.092884 -262.36041)
		(end 170.117516 -262.36041)
		(width 0.14478)
		(layer "In13.Cu")
		(net "M_H_CPU1_SB_CA<2>")
	)
	(segment
		(start 144.689322 -263.068816)
		(end 144.71269 -263.0551)
		(width 0.0889)
		(layer "In13.Cu")
		(net "M_H_CPU1_SB_CA<2>")
	)
	(segment
		(start 145.444718 -263.119616)
		(end 145.444972 -263.11987)
		(width 0.0889)
		(layer "In13.Cu")
		(net "M_H_CPU1_SB_CA<2>")
	)
	(segment
		(start 144.316196 -263.068562)
		(end 144.334484 -263.078976)
		(width 0.0889)
		(layer "In13.Cu")
		(net "M_H_CPU1_SB_CA<2>")
	)
	(segment
		(start 139.044426 -263.073134)
		(end 139.051792 -263.068816)
		(width 0.0889)
		(layer "In13.Cu")
		(net "M_H_CPU1_SB_CA<2>")
	)
	(segment
		(start 163.46424 -262.525764)
		(end 164.14877 -263.210294)
		(width 0.14478)
		(layer "In13.Cu")
		(net "M_H_CPU1_SB_CA<2>")
	)
	(segment
		(start 146.440652 -262.721344)
		(end 147.169378 -262.721344)
		(width 0.0889)
		(layer "In13.Cu")
		(net "M_H_CPU1_SB_CA<2>")
	)
	(segment
		(start 144.294606 -263.056116)
		(end 144.316196 -263.068562)
		(width 0.0889)
		(layer "In13.Cu")
		(net "M_H_CPU1_SB_CA<2>")
	)
	(segment
		(start 148.016468 -262.520684)
		(end 156.25445 -262.520684)
		(width 0.14478)
		(layer "In13.Cu")
		(net "M_H_CPU1_SB_CA<2>")
	)
	(segment
		(start 138.103356 -263.073642)
		(end 138.111738 -263.068816)
		(width 0.0889)
		(layer "In13.Cu")
		(net "M_H_CPU1_SB_CA<2>")
	)
	(segment
		(start 136.198864 -263.011666)
		(end 136.29513 -263.037066)
		(width 0.0889)
		(layer "In13.Cu")
		(net "M_H_CPU1_SB_CA<2>")
	)
	(segment
		(start 160.06699 -261.993126)
		(end 160.599628 -262.525764)
		(width 0.14478)
		(layer "In13.Cu")
		(net "M_H_CPU1_SB_CA<2>")
	)
	(segment
		(start 145.444972 -263.11987)
		(end 146.042126 -263.11987)
		(width 0.0889)
		(layer "In13.Cu")
		(net "M_H_CPU1_SB_CA<2>")
	)
	(segment
		(start 142.803372 -263.073642)
		(end 142.811754 -263.068816)
		(width 0.0889)
		(layer "In13.Cu")
		(net "M_H_CPU1_SB_CA<2>")
	)
	(segment
		(start 170.117516 -262.36041)
		(end 170.9674 -263.210294)
		(width 0.14478)
		(layer "In13.Cu")
		(net "M_H_CPU1_SB_CA<2>")
	)
	(segment
		(start 156.25445 -262.520684)
		(end 156.782008 -261.993126)
		(width 0.14478)
		(layer "In13.Cu")
		(net "M_H_CPU1_SB_CA<2>")
	)
	(segment
		(start 166.243 -263.210294)
		(end 167.092884 -262.36041)
		(width 0.14478)
		(layer "In13.Cu")
		(net "M_H_CPU1_SB_CA<2>")
	)
	(segment
		(start 136.044686 -262.746236)
		(end 136.198864 -263.011666)
		(width 0.0889)
		(layer "In13.Cu")
		(net "M_H_CPU1_SB_CA<2>")
	)
	(segment
		(start 140.557758 -263.068816)
		(end 140.56614 -263.073642)
		(width 0.0889)
		(layer "In13.Cu")
		(net "M_H_CPU1_SB_CA<2>")
	)
	(segment
		(start 156.782008 -261.993126)
		(end 160.06699 -261.993126)
		(width 0.14478)
		(layer "In13.Cu")
		(net "M_H_CPU1_SB_CA<2>")
	)
	(segment
		(start 147.169378 -262.721344)
		(end 147.370038 -262.520684)
		(width 0.0889)
		(layer "In13.Cu")
		(net "M_H_CPU1_SB_CA<2>")
	)
	(segment
		(start 170.9674 -263.210294)
		(end 173.935898 -263.210294)
		(width 0.14478)
		(layer "In13.Cu")
		(net "M_H_CPU1_SB_CA<2>")
	)
	(segment
		(start 139.617704 -263.068816)
		(end 139.626086 -263.073642)
		(width 0.0889)
		(layer "In13.Cu")
		(net "M_H_CPU1_SB_CA<2>")
	)
	(segment
		(start 143.377666 -263.068816)
		(end 143.386048 -263.073642)
		(width 0.0889)
		(layer "In13.Cu")
		(net "M_H_CPU1_SB_CA<2>")
	)
	(segment
		(start 139.04341 -263.073642)
		(end 139.044426 -263.073134)
		(width 0.0889)
		(layer "In13.Cu")
		(net "M_H_CPU1_SB_CA<2>")
	)
	(segment
		(start 160.599628 -262.525764)
		(end 163.46424 -262.525764)
		(width 0.14478)
		(layer "In13.Cu")
		(net "M_H_CPU1_SB_CA<2>")
	)
	(arc
		(start 140.56614 -263.073642)
		(mid 140.749648 -263.119136)
		(end 140.9319 -263.068816)
		(width 0.0889)
		(layer "In13.Cu")
		(net "M_H_CPU1_SB_CA<2>")
	)
	(arc
		(start 144.334484 -263.078976)
		(mid 144.513205 -263.118899)
		(end 144.689322 -263.068816)
		(width 0.0889)
		(layer "In13.Cu")
		(net "M_H_CPU1_SB_CA<2>")
	)
	(arc
		(start 138.67765 -263.068816)
		(mid 138.859901 -263.119166)
		(end 139.04341 -263.073642)
		(width 0.0889)
		(layer "In13.Cu")
		(net "M_H_CPU1_SB_CA<2>")
	)
	(arc
		(start 136.29513 -263.037066)
		(mid 136.550195 -262.993715)
		(end 136.797796 -263.068816)
		(width 0.0889)
		(layer "In13.Cu")
		(net "M_H_CPU1_SB_CA<2>")
	)
	(arc
		(start 142.437612 -263.068816)
		(mid 142.619863 -263.119166)
		(end 142.803372 -263.073642)
		(width 0.0889)
		(layer "In13.Cu")
		(net "M_H_CPU1_SB_CA<2>")
	)
	(arc
		(start 144.71269 -263.0551)
		(mid 144.986344 -262.992157)
		(end 145.256504 -263.068816)
		(width 0.0889)
		(layer "In13.Cu")
		(net "M_H_CPU1_SB_CA<2>")
	)
	(arc
		(start 139.626086 -263.073642)
		(mid 139.809594 -263.119136)
		(end 139.991846 -263.068816)
		(width 0.0889)
		(layer "In13.Cu")
		(net "M_H_CPU1_SB_CA<2>")
	)
	(arc
		(start 136.797796 -263.068816)
		(mid 136.98474 -263.119071)
		(end 137.171684 -263.068816)
		(width 0.0889)
		(layer "In13.Cu")
		(net "M_H_CPU1_SB_CA<2>")
	)
	(arc
		(start 138.111738 -263.068816)
		(mid 138.394694 -262.992639)
		(end 138.67765 -263.068816)
		(width 0.0889)
		(layer "In13.Cu")
		(net "M_H_CPU1_SB_CA<2>")
	)
	(arc
		(start 143.751808 -263.068816)
		(mid 144.021577 -262.992793)
		(end 144.294606 -263.056116)
		(width 0.0889)
		(layer "In13.Cu")
		(net "M_H_CPU1_SB_CA<2>")
	)
	(arc
		(start 141.8717 -263.068816)
		(mid 142.154656 -262.992639)
		(end 142.437612 -263.068816)
		(width 0.0889)
		(layer "In13.Cu")
		(net "M_H_CPU1_SB_CA<2>")
	)
	(arc
		(start 140.9319 -263.068816)
		(mid 141.214856 -262.992639)
		(end 141.497812 -263.068816)
		(width 0.0889)
		(layer "In13.Cu")
		(net "M_H_CPU1_SB_CA<2>")
	)
	(arc
		(start 143.386048 -263.073642)
		(mid 143.569556 -263.119136)
		(end 143.751808 -263.068816)
		(width 0.0889)
		(layer "In13.Cu")
		(net "M_H_CPU1_SB_CA<2>")
	)
	(arc
		(start 137.171684 -263.068816)
		(mid 137.45464 -262.992639)
		(end 137.737596 -263.068816)
		(width 0.0889)
		(layer "In13.Cu")
		(net "M_H_CPU1_SB_CA<2>")
	)
	(arc
		(start 142.811754 -263.068816)
		(mid 143.09471 -262.992639)
		(end 143.377666 -263.068816)
		(width 0.0889)
		(layer "In13.Cu")
		(net "M_H_CPU1_SB_CA<2>")
	)
	(arc
		(start 145.256504 -263.068816)
		(mid 145.347239 -263.1067)
		(end 145.444718 -263.119616)
		(width 0.0889)
		(layer "In13.Cu")
		(net "M_H_CPU1_SB_CA<2>")
	)
	(arc
		(start 139.991846 -263.068816)
		(mid 140.274802 -262.992639)
		(end 140.557758 -263.068816)
		(width 0.0889)
		(layer "In13.Cu")
		(net "M_H_CPU1_SB_CA<2>")
	)
	(arc
		(start 139.051792 -263.068816)
		(mid 139.334748 -262.992639)
		(end 139.617704 -263.068816)
		(width 0.0889)
		(layer "In13.Cu")
		(net "M_H_CPU1_SB_CA<2>")
	)
	(arc
		(start 141.497812 -263.068816)
		(mid 141.684756 -263.119071)
		(end 141.8717 -263.068816)
		(width 0.0889)
		(layer "In13.Cu")
		(net "M_H_CPU1_SB_CA<2>")
	)
	(arc
		(start 137.737596 -263.068816)
		(mid 137.919847 -263.119166)
		(end 138.103356 -263.073642)
		(width 0.0889)
		(layer "In13.Cu")
		(net "M_H_CPU1_SB_CA<2>")
	)
	(segment
		(start 134.63778 -262.480298)
		(end 135.104632 -262.746236)
		(width 0.10668)
		(layer "F.Cu")
		(net "M_H_CPU1_SB_CA<1>")
	)
	(segment
		(start 160.950656 -261.716266)
		(end 161.313876 -261.716266)
		(width 0.14478)
		(layer "In13.Cu")
		(net "M_H_CPU1_SB_CA<1>")
	)
	(segment
		(start 170.18254 -261.510272)
		(end 171.032678 -262.36041)
		(width 0.14478)
		(layer "In13.Cu")
		(net "M_H_CPU1_SB_CA<1>")
	)
	(segment
		(start 145.444718 -262.372856)
		(end 147.178268 -262.372856)
		(width 0.0889)
		(layer "In13.Cu")
		(net "M_H_CPU1_SB_CA<1>")
	)
	(segment
		(start 139.04341 -262.41883)
		(end 139.044426 -262.419338)
		(width 0.0889)
		(layer "In13.Cu")
		(net "M_H_CPU1_SB_CA<1>")
	)
	(segment
		(start 147.178268 -262.372856)
		(end 147.4851 -262.066024)
		(width 0.0889)
		(layer "In13.Cu")
		(net "M_H_CPU1_SB_CA<1>")
	)
	(segment
		(start 162.88639 -261.109968)
		(end 164.136832 -262.36041)
		(width 0.14478)
		(layer "In13.Cu")
		(net "M_H_CPU1_SB_CA<1>")
	)
	(segment
		(start 148.019262 -262.066024)
		(end 155.786074 -262.066024)
		(width 0.14478)
		(layer "In13.Cu")
		(net "M_H_CPU1_SB_CA<1>")
	)
	(segment
		(start 135.104632 -262.746236)
		(end 134.950708 -262.480806)
		(width 0.0889)
		(layer "In13.Cu")
		(net "M_H_CPU1_SB_CA<1>")
	)
	(segment
		(start 160.805876 -261.571486)
		(end 160.950656 -261.716266)
		(width 0.14478)
		(layer "In13.Cu")
		(net "M_H_CPU1_SB_CA<1>")
	)
	(segment
		(start 139.044426 -262.419338)
		(end 139.051792 -262.423656)
		(width 0.0889)
		(layer "In13.Cu")
		(net "M_H_CPU1_SB_CA<1>")
	)
	(segment
		(start 144.684242 -262.41883)
		(end 144.692624 -262.423656)
		(width 0.0889)
		(layer "In13.Cu")
		(net "M_H_CPU1_SB_CA<1>")
	)
	(segment
		(start 167.000174 -261.510272)
		(end 170.18254 -261.510272)
		(width 0.14478)
		(layer "In13.Cu")
		(net "M_H_CPU1_SB_CA<1>")
	)
	(segment
		(start 171.5516 -262.36041)
		(end 171.97197 -261.94004)
		(width 0.14478)
		(layer "In13.Cu")
		(net "M_H_CPU1_SB_CA<1>")
	)
	(segment
		(start 161.603436 -261.109968)
		(end 162.88639 -261.109968)
		(width 0.14478)
		(layer "In13.Cu")
		(net "M_H_CPU1_SB_CA<1>")
	)
	(segment
		(start 143.377666 -262.423656)
		(end 143.386048 -262.41883)
		(width 0.0889)
		(layer "In13.Cu")
		(net "M_H_CPU1_SB_CA<1>")
	)
	(segment
		(start 140.557758 -262.423656)
		(end 140.56614 -262.41883)
		(width 0.0889)
		(layer "In13.Cu")
		(net "M_H_CPU1_SB_CA<1>")
	)
	(segment
		(start 161.458656 -261.571486)
		(end 161.458656 -261.254748)
		(width 0.14478)
		(layer "In13.Cu")
		(net "M_H_CPU1_SB_CA<1>")
	)
	(segment
		(start 161.458656 -261.254748)
		(end 161.603436 -261.109968)
		(width 0.14478)
		(layer "In13.Cu")
		(net "M_H_CPU1_SB_CA<1>")
	)
	(segment
		(start 156.74213 -261.109968)
		(end 160.661096 -261.109968)
		(width 0.14478)
		(layer "In13.Cu")
		(net "M_H_CPU1_SB_CA<1>")
	)
	(segment
		(start 161.313876 -261.716266)
		(end 161.458656 -261.571486)
		(width 0.14478)
		(layer "In13.Cu")
		(net "M_H_CPU1_SB_CA<1>")
	)
	(segment
		(start 155.786074 -262.066024)
		(end 156.74213 -261.109968)
		(width 0.14478)
		(layer "In13.Cu")
		(net "M_H_CPU1_SB_CA<1>")
	)
	(segment
		(start 171.032678 -262.36041)
		(end 171.5516 -262.36041)
		(width 0.14478)
		(layer "In13.Cu")
		(net "M_H_CPU1_SB_CA<1>")
	)
	(segment
		(start 160.661096 -261.109968)
		(end 160.805876 -261.254748)
		(width 0.14478)
		(layer "In13.Cu")
		(net "M_H_CPU1_SB_CA<1>")
	)
	(segment
		(start 139.617704 -262.423656)
		(end 139.626086 -262.41883)
		(width 0.0889)
		(layer "In13.Cu")
		(net "M_H_CPU1_SB_CA<1>")
	)
	(segment
		(start 147.4851 -262.066024)
		(end 148.019262 -262.066024)
		(width 0.0889)
		(layer "In13.Cu")
		(net "M_H_CPU1_SB_CA<1>")
	)
	(segment
		(start 138.103356 -262.41883)
		(end 138.111738 -262.423656)
		(width 0.0889)
		(layer "In13.Cu")
		(net "M_H_CPU1_SB_CA<1>")
	)
	(segment
		(start 135.857742 -262.423656)
		(end 135.866124 -262.41883)
		(width 0.0889)
		(layer "In13.Cu")
		(net "M_H_CPU1_SB_CA<1>")
	)
	(segment
		(start 171.97197 -261.94004)
		(end 171.97197 -261.935214)
		(width 0.14478)
		(layer "In13.Cu")
		(net "M_H_CPU1_SB_CA<1>")
	)
	(segment
		(start 166.150036 -262.36041)
		(end 167.000174 -261.510272)
		(width 0.14478)
		(layer "In13.Cu")
		(net "M_H_CPU1_SB_CA<1>")
	)
	(segment
		(start 164.136832 -262.36041)
		(end 166.150036 -262.36041)
		(width 0.14478)
		(layer "In13.Cu")
		(net "M_H_CPU1_SB_CA<1>")
	)
	(segment
		(start 160.805876 -261.254748)
		(end 160.805876 -261.571486)
		(width 0.14478)
		(layer "In13.Cu")
		(net "M_H_CPU1_SB_CA<1>")
	)
	(segment
		(start 142.803372 -262.41883)
		(end 142.811754 -262.423656)
		(width 0.0889)
		(layer "In13.Cu")
		(net "M_H_CPU1_SB_CA<1>")
	)
	(segment
		(start 143.751808 -262.423656)
		(end 143.762222 -262.429752)
		(width 0.0889)
		(layer "In13.Cu")
		(net "M_H_CPU1_SB_CA<1>")
	)
	(segment
		(start 134.950708 -262.480806)
		(end 134.97306 -262.397494)
		(width 0.0889)
		(layer "In13.Cu")
		(net "M_H_CPU1_SB_CA<1>")
	)
	(arc
		(start 143.386048 -262.41883)
		(mid 143.569556 -262.373336)
		(end 143.751808 -262.423656)
		(width 0.0889)
		(layer "In13.Cu")
		(net "M_H_CPU1_SB_CA<1>")
	)
	(arc
		(start 137.171684 -262.423656)
		(mid 137.45464 -262.499833)
		(end 137.737596 -262.423656)
		(width 0.0889)
		(layer "In13.Cu")
		(net "M_H_CPU1_SB_CA<1>")
	)
	(arc
		(start 136.231884 -262.423656)
		(mid 136.51484 -262.499833)
		(end 136.797796 -262.423656)
		(width 0.0889)
		(layer "In13.Cu")
		(net "M_H_CPU1_SB_CA<1>")
	)
	(arc
		(start 141.497812 -262.423656)
		(mid 141.684756 -262.373401)
		(end 141.8717 -262.423656)
		(width 0.0889)
		(layer "In13.Cu")
		(net "M_H_CPU1_SB_CA<1>")
	)
	(arc
		(start 141.8717 -262.423656)
		(mid 142.154656 -262.499833)
		(end 142.437612 -262.423656)
		(width 0.0889)
		(layer "In13.Cu")
		(net "M_H_CPU1_SB_CA<1>")
	)
	(arc
		(start 140.56614 -262.41883)
		(mid 140.749648 -262.373336)
		(end 140.9319 -262.423656)
		(width 0.0889)
		(layer "In13.Cu")
		(net "M_H_CPU1_SB_CA<1>")
	)
	(arc
		(start 136.797796 -262.423656)
		(mid 136.98474 -262.373401)
		(end 137.171684 -262.423656)
		(width 0.0889)
		(layer "In13.Cu")
		(net "M_H_CPU1_SB_CA<1>")
	)
	(arc
		(start 144.317974 -262.423656)
		(mid 144.500479 -262.373179)
		(end 144.684242 -262.41883)
		(width 0.0889)
		(layer "In13.Cu")
		(net "M_H_CPU1_SB_CA<1>")
	)
	(arc
		(start 135.29183 -262.423656)
		(mid 135.574786 -262.499833)
		(end 135.857742 -262.423656)
		(width 0.0889)
		(layer "In13.Cu")
		(net "M_H_CPU1_SB_CA<1>")
	)
	(arc
		(start 139.051792 -262.423656)
		(mid 139.334748 -262.499833)
		(end 139.617704 -262.423656)
		(width 0.0889)
		(layer "In13.Cu")
		(net "M_H_CPU1_SB_CA<1>")
	)
	(arc
		(start 144.692624 -262.423656)
		(mid 144.972052 -262.499822)
		(end 145.25244 -262.427212)
		(width 0.0889)
		(layer "In13.Cu")
		(net "M_H_CPU1_SB_CA<1>")
	)
	(arc
		(start 138.67765 -262.423656)
		(mid 138.859901 -262.373306)
		(end 139.04341 -262.41883)
		(width 0.0889)
		(layer "In13.Cu")
		(net "M_H_CPU1_SB_CA<1>")
	)
	(arc
		(start 142.437612 -262.423656)
		(mid 142.619863 -262.373306)
		(end 142.803372 -262.41883)
		(width 0.0889)
		(layer "In13.Cu")
		(net "M_H_CPU1_SB_CA<1>")
	)
	(arc
		(start 139.626086 -262.41883)
		(mid 139.809594 -262.373336)
		(end 139.991846 -262.423656)
		(width 0.0889)
		(layer "In13.Cu")
		(net "M_H_CPU1_SB_CA<1>")
	)
	(arc
		(start 140.9319 -262.423656)
		(mid 141.214856 -262.499833)
		(end 141.497812 -262.423656)
		(width 0.0889)
		(layer "In13.Cu")
		(net "M_H_CPU1_SB_CA<1>")
	)
	(arc
		(start 142.811754 -262.423656)
		(mid 143.09471 -262.499833)
		(end 143.377666 -262.423656)
		(width 0.0889)
		(layer "In13.Cu")
		(net "M_H_CPU1_SB_CA<1>")
	)
	(arc
		(start 139.991846 -262.423656)
		(mid 140.274802 -262.499833)
		(end 140.557758 -262.423656)
		(width 0.0889)
		(layer "In13.Cu")
		(net "M_H_CPU1_SB_CA<1>")
	)
	(arc
		(start 135.866124 -262.41883)
		(mid 136.049632 -262.373336)
		(end 136.231884 -262.423656)
		(width 0.0889)
		(layer "In13.Cu")
		(net "M_H_CPU1_SB_CA<1>")
	)
	(arc
		(start 138.111738 -262.423656)
		(mid 138.394694 -262.499833)
		(end 138.67765 -262.423656)
		(width 0.0889)
		(layer "In13.Cu")
		(net "M_H_CPU1_SB_CA<1>")
	)
	(arc
		(start 134.97306 -262.397494)
		(mid 135.135392 -262.374676)
		(end 135.29183 -262.423656)
		(width 0.0889)
		(layer "In13.Cu")
		(net "M_H_CPU1_SB_CA<1>")
	)
	(arc
		(start 145.25244 -262.427212)
		(mid 145.344872 -262.38693)
		(end 145.444718 -262.372856)
		(width 0.0889)
		(layer "In13.Cu")
		(net "M_H_CPU1_SB_CA<1>")
	)
	(arc
		(start 143.762222 -262.429752)
		(mid 144.040908 -262.499972)
		(end 144.317974 -262.423656)
		(width 0.0889)
		(layer "In13.Cu")
		(net "M_H_CPU1_SB_CA<1>")
	)
	(arc
		(start 137.737596 -262.423656)
		(mid 137.919847 -262.373306)
		(end 138.103356 -262.41883)
		(width 0.0889)
		(layer "In13.Cu")
		(net "M_H_CPU1_SB_CA<1>")
	)
	(segment
		(start 134.16788 -261.670292)
		(end 134.634732 -261.93623)
		(width 0.10668)
		(layer "F.Cu")
		(net "M_H_CPU1_SB_CA<0>")
	)
	(segment
		(start 138.20775 -262.25881)
		(end 138.216132 -262.263636)
		(width 0.0889)
		(layer "In13.Cu")
		(net "M_H_CPU1_SB_CA<0>")
	)
	(segment
		(start 145.582132 -262.142986)
		(end 147.102068 -262.142986)
		(width 0.0889)
		(layer "In13.Cu")
		(net "M_H_CPU1_SB_CA<0>")
	)
	(segment
		(start 134.788656 -262.20166)
		(end 134.884668 -262.22706)
		(width 0.0889)
		(layer "In13.Cu")
		(net "M_H_CPU1_SB_CA<0>")
	)
	(segment
		(start 147.63369 -261.611364)
		(end 148.028152 -261.611364)
		(width 0.0889)
		(layer "In13.Cu")
		(net "M_H_CPU1_SB_CA<0>")
	)
	(segment
		(start 144.777968 -262.252714)
		(end 144.788382 -262.25881)
		(width 0.0889)
		(layer "In13.Cu")
		(net "M_H_CPU1_SB_CA<0>")
	)
	(segment
		(start 147.102068 -262.142986)
		(end 147.63369 -261.611364)
		(width 0.0889)
		(layer "In13.Cu")
		(net "M_H_CPU1_SB_CA<0>")
	)
	(segment
		(start 173.049692 -261.08533)
		(end 176.072038 -261.08533)
		(width 0.14478)
		(layer "In13.Cu")
		(net "M_H_CPU1_SB_CA<0>")
	)
	(segment
		(start 143.847566 -262.25881)
		(end 143.855948 -262.263636)
		(width 0.0889)
		(layer "In13.Cu")
		(net "M_H_CPU1_SB_CA<0>")
	)
	(segment
		(start 136.693402 -262.263636)
		(end 136.701784 -262.25881)
		(width 0.0889)
		(layer "In13.Cu")
		(net "M_H_CPU1_SB_CA<0>")
	)
	(segment
		(start 148.028152 -261.611364)
		(end 155.604718 -261.611364)
		(width 0.14478)
		(layer "In13.Cu")
		(net "M_H_CPU1_SB_CA<0>")
	)
	(segment
		(start 155.604718 -261.611364)
		(end 156.555694 -260.660388)
		(width 0.14478)
		(layer "In13.Cu")
		(net "M_H_CPU1_SB_CA<0>")
	)
	(segment
		(start 156.555694 -260.660388)
		(end 168.734486 -260.660388)
		(width 0.14478)
		(layer "In13.Cu")
		(net "M_H_CPU1_SB_CA<0>")
	)
	(segment
		(start 137.267696 -262.25881)
		(end 137.276078 -262.263636)
		(width 0.0889)
		(layer "In13.Cu")
		(net "M_H_CPU1_SB_CA<0>")
	)
	(segment
		(start 134.634732 -261.93623)
		(end 134.788656 -262.20166)
		(width 0.0889)
		(layer "In13.Cu")
		(net "M_H_CPU1_SB_CA<0>")
	)
	(segment
		(start 140.453364 -262.263636)
		(end 140.461746 -262.25881)
		(width 0.0889)
		(layer "In13.Cu")
		(net "M_H_CPU1_SB_CA<0>")
	)
	(segment
		(start 135.753348 -262.263636)
		(end 135.76173 -262.25881)
		(width 0.0889)
		(layer "In13.Cu")
		(net "M_H_CPU1_SB_CA<0>")
	)
	(segment
		(start 141.967712 -262.25881)
		(end 141.976094 -262.263636)
		(width 0.0889)
		(layer "In13.Cu")
		(net "M_H_CPU1_SB_CA<0>")
	)
	(segment
		(start 168.734486 -260.660388)
		(end 173.049692 -261.08533)
		(width 0.14478)
		(layer "In13.Cu")
		(net "M_H_CPU1_SB_CA<0>")
	)
	(segment
		(start 141.393418 -262.263636)
		(end 141.4018 -262.25881)
		(width 0.0889)
		(layer "In13.Cu")
		(net "M_H_CPU1_SB_CA<0>")
	)
	(arc
		(start 142.907766 -262.25881)
		(mid 143.09471 -262.309065)
		(end 143.281654 -262.25881)
		(width 0.0889)
		(layer "In13.Cu")
		(net "M_H_CPU1_SB_CA<0>")
	)
	(arc
		(start 135.387588 -262.25881)
		(mid 135.569839 -262.30916)
		(end 135.753348 -262.263636)
		(width 0.0889)
		(layer "In13.Cu")
		(net "M_H_CPU1_SB_CA<0>")
	)
	(arc
		(start 143.855948 -262.263636)
		(mid 144.03971 -262.309252)
		(end 144.222216 -262.25881)
		(width 0.0889)
		(layer "In13.Cu")
		(net "M_H_CPU1_SB_CA<0>")
	)
	(arc
		(start 134.884668 -262.22706)
		(mid 135.139876 -262.183583)
		(end 135.387588 -262.25881)
		(width 0.0889)
		(layer "In13.Cu")
		(net "M_H_CPU1_SB_CA<0>")
	)
	(arc
		(start 141.976094 -262.263636)
		(mid 142.159602 -262.30913)
		(end 142.341854 -262.25881)
		(width 0.0889)
		(layer "In13.Cu")
		(net "M_H_CPU1_SB_CA<0>")
	)
	(arc
		(start 141.4018 -262.25881)
		(mid 141.684756 -262.182633)
		(end 141.967712 -262.25881)
		(width 0.0889)
		(layer "In13.Cu")
		(net "M_H_CPU1_SB_CA<0>")
	)
	(arc
		(start 138.581892 -262.25881)
		(mid 138.864848 -262.182633)
		(end 139.147804 -262.25881)
		(width 0.0889)
		(layer "In13.Cu")
		(net "M_H_CPU1_SB_CA<0>")
	)
	(arc
		(start 139.521692 -262.25881)
		(mid 139.804648 -262.182633)
		(end 140.087604 -262.25881)
		(width 0.0889)
		(layer "In13.Cu")
		(net "M_H_CPU1_SB_CA<0>")
	)
	(arc
		(start 144.222216 -262.25881)
		(mid 144.499283 -262.182539)
		(end 144.777968 -262.252714)
		(width 0.0889)
		(layer "In13.Cu")
		(net "M_H_CPU1_SB_CA<0>")
	)
	(arc
		(start 144.788382 -262.25881)
		(mid 144.966032 -262.30907)
		(end 145.146014 -262.267954)
		(width 0.0889)
		(layer "In13.Cu")
		(net "M_H_CPU1_SB_CA<0>")
	)
	(arc
		(start 141.027658 -262.25881)
		(mid 141.209909 -262.30916)
		(end 141.393418 -262.263636)
		(width 0.0889)
		(layer "In13.Cu")
		(net "M_H_CPU1_SB_CA<0>")
	)
	(arc
		(start 142.341854 -262.25881)
		(mid 142.62481 -262.182633)
		(end 142.907766 -262.25881)
		(width 0.0889)
		(layer "In13.Cu")
		(net "M_H_CPU1_SB_CA<0>")
	)
	(arc
		(start 136.327642 -262.25881)
		(mid 136.509893 -262.30916)
		(end 136.693402 -262.263636)
		(width 0.0889)
		(layer "In13.Cu")
		(net "M_H_CPU1_SB_CA<0>")
	)
	(arc
		(start 143.281654 -262.25881)
		(mid 143.56461 -262.182633)
		(end 143.847566 -262.25881)
		(width 0.0889)
		(layer "In13.Cu")
		(net "M_H_CPU1_SB_CA<0>")
	)
	(arc
		(start 137.641838 -262.25881)
		(mid 137.924794 -262.182633)
		(end 138.20775 -262.25881)
		(width 0.0889)
		(layer "In13.Cu")
		(net "M_H_CPU1_SB_CA<0>")
	)
	(arc
		(start 139.147804 -262.25881)
		(mid 139.334748 -262.309065)
		(end 139.521692 -262.25881)
		(width 0.0889)
		(layer "In13.Cu")
		(net "M_H_CPU1_SB_CA<0>")
	)
	(arc
		(start 145.146014 -262.267954)
		(mid 145.355297 -262.174844)
		(end 145.582132 -262.142986)
		(width 0.0889)
		(layer "In13.Cu")
		(net "M_H_CPU1_SB_CA<0>")
	)
	(arc
		(start 140.461746 -262.25881)
		(mid 140.744702 -262.182633)
		(end 141.027658 -262.25881)
		(width 0.0889)
		(layer "In13.Cu")
		(net "M_H_CPU1_SB_CA<0>")
	)
	(arc
		(start 138.216132 -262.263636)
		(mid 138.39964 -262.30913)
		(end 138.581892 -262.25881)
		(width 0.0889)
		(layer "In13.Cu")
		(net "M_H_CPU1_SB_CA<0>")
	)
	(arc
		(start 135.76173 -262.25881)
		(mid 136.044686 -262.182633)
		(end 136.327642 -262.25881)
		(width 0.0889)
		(layer "In13.Cu")
		(net "M_H_CPU1_SB_CA<0>")
	)
	(arc
		(start 136.701784 -262.25881)
		(mid 136.98474 -262.182633)
		(end 137.267696 -262.25881)
		(width 0.0889)
		(layer "In13.Cu")
		(net "M_H_CPU1_SB_CA<0>")
	)
	(arc
		(start 140.087604 -262.25881)
		(mid 140.269855 -262.30916)
		(end 140.453364 -262.263636)
		(width 0.0889)
		(layer "In13.Cu")
		(net "M_H_CPU1_SB_CA<0>")
	)
	(arc
		(start 137.276078 -262.263636)
		(mid 137.459586 -262.30913)
		(end 137.641838 -262.25881)
		(width 0.0889)
		(layer "In13.Cu")
		(net "M_H_CPU1_SB_CA<0>")
	)
	(segment
		(start 134.16788 -266.530328)
		(end 134.634732 -266.796266)
		(width 0.10668)
		(layer "F.Cu")
		(net "M_H_CPU1_SA_RSP<0>")
	)
	(segment
		(start 140.461746 -267.118846)
		(end 140.453364 -267.123672)
		(width 0.0889)
		(layer "In13.Cu")
		(net "M_H_CPU1_SA_RSP<0>")
	)
	(segment
		(start 136.701784 -267.118846)
		(end 136.693402 -267.123672)
		(width 0.0889)
		(layer "In13.Cu")
		(net "M_H_CPU1_SA_RSP<0>")
	)
	(segment
		(start 160.41878 -266.143994)
		(end 147.93849 -266.143994)
		(width 0.11684)
		(layer "In13.Cu")
		(net "M_H_CPU1_SA_RSP<0>")
	)
	(segment
		(start 147.93849 -266.143994)
		(end 146.135598 -266.143994)
		(width 0.0889)
		(layer "In13.Cu")
		(net "M_H_CPU1_SA_RSP<0>")
	)
	(segment
		(start 134.485888 -267.052552)
		(end 134.634732 -266.796266)
		(width 0.0889)
		(layer "In13.Cu")
		(net "M_H_CPU1_SA_RSP<0>")
	)
	(segment
		(start 169.825416 -269.160498)
		(end 167.47871 -269.160498)
		(width 0.11684)
		(layer "In13.Cu")
		(net "M_H_CPU1_SA_RSP<0>")
	)
	(segment
		(start 137.276078 -267.123672)
		(end 137.267696 -267.118846)
		(width 0.0889)
		(layer "In13.Cu")
		(net "M_H_CPU1_SA_RSP<0>")
	)
	(segment
		(start 141.976094 -267.123672)
		(end 141.967712 -267.118846)
		(width 0.0889)
		(layer "In13.Cu")
		(net "M_H_CPU1_SA_RSP<0>")
	)
	(segment
		(start 143.855948 -267.123672)
		(end 143.847566 -267.118846)
		(width 0.0889)
		(layer "In13.Cu")
		(net "M_H_CPU1_SA_RSP<0>")
	)
	(segment
		(start 141.4018 -267.118846)
		(end 141.393418 -267.123672)
		(width 0.0889)
		(layer "In13.Cu")
		(net "M_H_CPU1_SA_RSP<0>")
	)
	(segment
		(start 165.426136 -270.010636)
		(end 164.285422 -270.010636)
		(width 0.11684)
		(layer "In13.Cu")
		(net "M_H_CPU1_SA_RSP<0>")
	)
	(segment
		(start 173.964854 -269.58544)
		(end 172.938186 -270.010636)
		(width 0.11684)
		(layer "In13.Cu")
		(net "M_H_CPU1_SA_RSP<0>")
	)
	(segment
		(start 164.285422 -270.010636)
		(end 160.41878 -266.143994)
		(width 0.11684)
		(layer "In13.Cu")
		(net "M_H_CPU1_SA_RSP<0>")
	)
	(segment
		(start 171.87799 -270.010636)
		(end 169.825416 -269.160498)
		(width 0.11684)
		(layer "In13.Cu")
		(net "M_H_CPU1_SA_RSP<0>")
	)
	(segment
		(start 134.509256 -267.140436)
		(end 134.485888 -267.052552)
		(width 0.0889)
		(layer "In13.Cu")
		(net "M_H_CPU1_SA_RSP<0>")
	)
	(segment
		(start 134.829296 -267.107162)
		(end 134.818628 -267.113258)
		(width 0.0889)
		(layer "In13.Cu")
		(net "M_H_CPU1_SA_RSP<0>")
	)
	(segment
		(start 176.072038 -269.58544)
		(end 173.964854 -269.58544)
		(width 0.11684)
		(layer "In13.Cu")
		(net "M_H_CPU1_SA_RSP<0>")
	)
	(segment
		(start 145.12163 -267.157962)
		(end 144.855184 -267.157962)
		(width 0.0889)
		(layer "In13.Cu")
		(net "M_H_CPU1_SA_RSP<0>")
	)
	(segment
		(start 172.938186 -270.010636)
		(end 171.87799 -270.010636)
		(width 0.11684)
		(layer "In13.Cu")
		(net "M_H_CPU1_SA_RSP<0>")
	)
	(segment
		(start 138.216132 -267.123672)
		(end 138.20775 -267.118846)
		(width 0.0889)
		(layer "In13.Cu")
		(net "M_H_CPU1_SA_RSP<0>")
	)
	(segment
		(start 167.47871 -269.160498)
		(end 165.426136 -270.010636)
		(width 0.11684)
		(layer "In13.Cu")
		(net "M_H_CPU1_SA_RSP<0>")
	)
	(segment
		(start 135.400542 -267.118592)
		(end 135.39089 -267.113258)
		(width 0.0889)
		(layer "In13.Cu")
		(net "M_H_CPU1_SA_RSP<0>")
	)
	(segment
		(start 144.855184 -267.157962)
		(end 144.777968 -267.11275)
		(width 0.0889)
		(layer "In13.Cu")
		(net "M_H_CPU1_SA_RSP<0>")
	)
	(segment
		(start 146.135598 -266.143994)
		(end 145.12163 -267.157962)
		(width 0.0889)
		(layer "In13.Cu")
		(net "M_H_CPU1_SA_RSP<0>")
	)
	(arc
		(start 139.147804 -267.118846)
		(mid 138.864848 -267.042669)
		(end 138.581892 -267.118846)
		(width 0.0889)
		(layer "In13.Cu")
		(net "M_H_CPU1_SA_RSP<0>")
	)
	(arc
		(start 144.222216 -267.118846)
		(mid 144.039711 -267.169323)
		(end 143.855948 -267.123672)
		(width 0.0889)
		(layer "In13.Cu")
		(net "M_H_CPU1_SA_RSP<0>")
	)
	(arc
		(start 142.341854 -267.118846)
		(mid 142.159603 -267.169196)
		(end 141.976094 -267.123672)
		(width 0.0889)
		(layer "In13.Cu")
		(net "M_H_CPU1_SA_RSP<0>")
	)
	(arc
		(start 134.818628 -267.113258)
		(mid 134.666969 -267.161212)
		(end 134.509256 -267.140436)
		(width 0.0889)
		(layer "In13.Cu")
		(net "M_H_CPU1_SA_RSP<0>")
	)
	(arc
		(start 136.693402 -267.123672)
		(mid 136.509894 -267.169166)
		(end 136.327642 -267.118846)
		(width 0.0889)
		(layer "In13.Cu")
		(net "M_H_CPU1_SA_RSP<0>")
	)
	(arc
		(start 144.777968 -267.11275)
		(mid 144.499282 -267.04253)
		(end 144.222216 -267.118846)
		(width 0.0889)
		(layer "In13.Cu")
		(net "M_H_CPU1_SA_RSP<0>")
	)
	(arc
		(start 141.027658 -267.118846)
		(mid 140.744702 -267.042669)
		(end 140.461746 -267.118846)
		(width 0.0889)
		(layer "In13.Cu")
		(net "M_H_CPU1_SA_RSP<0>")
	)
	(arc
		(start 143.281654 -267.118846)
		(mid 143.09471 -267.169101)
		(end 142.907766 -267.118846)
		(width 0.0889)
		(layer "In13.Cu")
		(net "M_H_CPU1_SA_RSP<0>")
	)
	(arc
		(start 142.907766 -267.118846)
		(mid 142.62481 -267.042669)
		(end 142.341854 -267.118846)
		(width 0.0889)
		(layer "In13.Cu")
		(net "M_H_CPU1_SA_RSP<0>")
	)
	(arc
		(start 143.847566 -267.118846)
		(mid 143.56461 -267.042669)
		(end 143.281654 -267.118846)
		(width 0.0889)
		(layer "In13.Cu")
		(net "M_H_CPU1_SA_RSP<0>")
	)
	(arc
		(start 136.327642 -267.118846)
		(mid 136.044686 -267.042669)
		(end 135.76173 -267.118846)
		(width 0.0889)
		(layer "In13.Cu")
		(net "M_H_CPU1_SA_RSP<0>")
	)
	(arc
		(start 135.39089 -267.113258)
		(mid 135.110886 -267.036213)
		(end 134.829296 -267.107162)
		(width 0.0889)
		(layer "In13.Cu")
		(net "M_H_CPU1_SA_RSP<0>")
	)
	(arc
		(start 141.393418 -267.123672)
		(mid 141.20991 -267.169166)
		(end 141.027658 -267.118846)
		(width 0.0889)
		(layer "In13.Cu")
		(net "M_H_CPU1_SA_RSP<0>")
	)
	(arc
		(start 135.76173 -267.118846)
		(mid 135.581107 -267.167296)
		(end 135.400542 -267.118592)
		(width 0.0889)
		(layer "In13.Cu")
		(net "M_H_CPU1_SA_RSP<0>")
	)
	(arc
		(start 138.20775 -267.118846)
		(mid 137.924794 -267.042669)
		(end 137.641838 -267.118846)
		(width 0.0889)
		(layer "In13.Cu")
		(net "M_H_CPU1_SA_RSP<0>")
	)
	(arc
		(start 139.521692 -267.118846)
		(mid 139.334748 -267.169101)
		(end 139.147804 -267.118846)
		(width 0.0889)
		(layer "In13.Cu")
		(net "M_H_CPU1_SA_RSP<0>")
	)
	(arc
		(start 141.967712 -267.118846)
		(mid 141.684756 -267.042669)
		(end 141.4018 -267.118846)
		(width 0.0889)
		(layer "In13.Cu")
		(net "M_H_CPU1_SA_RSP<0>")
	)
	(arc
		(start 138.581892 -267.118846)
		(mid 138.399641 -267.169196)
		(end 138.216132 -267.123672)
		(width 0.0889)
		(layer "In13.Cu")
		(net "M_H_CPU1_SA_RSP<0>")
	)
	(arc
		(start 140.087604 -267.118846)
		(mid 139.804648 -267.042669)
		(end 139.521692 -267.118846)
		(width 0.0889)
		(layer "In13.Cu")
		(net "M_H_CPU1_SA_RSP<0>")
	)
	(arc
		(start 137.641838 -267.118846)
		(mid 137.459587 -267.169196)
		(end 137.276078 -267.123672)
		(width 0.0889)
		(layer "In13.Cu")
		(net "M_H_CPU1_SA_RSP<0>")
	)
	(arc
		(start 140.453364 -267.123672)
		(mid 140.269856 -267.169166)
		(end 140.087604 -267.118846)
		(width 0.0889)
		(layer "In13.Cu")
		(net "M_H_CPU1_SA_RSP<0>")
	)
	(arc
		(start 137.267696 -267.118846)
		(mid 136.98474 -267.042703)
		(end 136.701784 -267.118846)
		(width 0.0889)
		(layer "In13.Cu")
		(net "M_H_CPU1_SA_RSP<0>")
	)
	(segment
		(start 133.867906 -256.09042)
		(end 134.334758 -255.824482)
		(width 0.10668)
		(layer "F.Cu")
		(net "M_H_CPU1_SA_PAR")
	)
	(segment
		(start 145.57121 -255.584706)
		(end 145.150586 -255.584706)
		(width 0.0889)
		(layer "In13.Cu")
		(net "M_H_CPU1_SA_PAR")
	)
	(segment
		(start 167.181784 -255.743964)
		(end 156.218128 -255.743964)
		(width 0.14478)
		(layer "In13.Cu")
		(net "M_H_CPU1_SA_PAR")
	)
	(segment
		(start 170.931332 -253.010416)
		(end 169.291 -254.650748)
		(width 0.14478)
		(layer "In13.Cu")
		(net "M_H_CPU1_SA_PAR")
	)
	(segment
		(start 141.101826 -255.501902)
		(end 141.093444 -255.497076)
		(width 0.0889)
		(layer "In13.Cu")
		(net "M_H_CPU1_SA_PAR")
	)
	(segment
		(start 135.461756 -255.501902)
		(end 135.453374 -255.497076)
		(width 0.0889)
		(layer "In13.Cu")
		(net "M_H_CPU1_SA_PAR")
	)
	(segment
		(start 134.584694 -255.533652)
		(end 134.488682 -255.559052)
		(width 0.0889)
		(layer "In13.Cu")
		(net "M_H_CPU1_SA_PAR")
	)
	(segment
		(start 172.99432 -253.010416)
		(end 170.931332 -253.010416)
		(width 0.14478)
		(layer "In13.Cu")
		(net "M_H_CPU1_SA_PAR")
	)
	(segment
		(start 136.40181 -255.501902)
		(end 136.393428 -255.497076)
		(width 0.0889)
		(layer "In13.Cu")
		(net "M_H_CPU1_SA_PAR")
	)
	(segment
		(start 137.916158 -255.497076)
		(end 137.907776 -255.501902)
		(width 0.0889)
		(layer "In13.Cu")
		(net "M_H_CPU1_SA_PAR")
	)
	(segment
		(start 144.488662 -255.501902)
		(end 144.47393 -255.510538)
		(width 0.0889)
		(layer "In13.Cu")
		(net "M_H_CPU1_SA_PAR")
	)
	(segment
		(start 143.555974 -255.497076)
		(end 143.547592 -255.501902)
		(width 0.0889)
		(layer "In13.Cu")
		(net "M_H_CPU1_SA_PAR")
	)
	(segment
		(start 155.63977 -255.165606)
		(end 152.069546 -255.165606)
		(width 0.14478)
		(layer "In13.Cu")
		(net "M_H_CPU1_SA_PAR")
	)
	(segment
		(start 152.069546 -255.165606)
		(end 150.609808 -256.625344)
		(width 0.14478)
		(layer "In13.Cu")
		(net "M_H_CPU1_SA_PAR")
	)
	(segment
		(start 156.218128 -255.743964)
		(end 155.63977 -255.165606)
		(width 0.14478)
		(layer "In13.Cu")
		(net "M_H_CPU1_SA_PAR")
	)
	(segment
		(start 136.976104 -255.497076)
		(end 136.967722 -255.501902)
		(width 0.0889)
		(layer "In13.Cu")
		(net "M_H_CPU1_SA_PAR")
	)
	(segment
		(start 141.67612 -255.497076)
		(end 141.667738 -255.501902)
		(width 0.0889)
		(layer "In13.Cu")
		(net "M_H_CPU1_SA_PAR")
	)
	(segment
		(start 150.609808 -256.625344)
		(end 147.724368 -256.625344)
		(width 0.14478)
		(layer "In13.Cu")
		(net "M_H_CPU1_SA_PAR")
	)
	(segment
		(start 147.724368 -256.625344)
		(end 146.611848 -256.625344)
		(width 0.0889)
		(layer "In13.Cu")
		(net "M_H_CPU1_SA_PAR")
	)
	(segment
		(start 146.611848 -256.625344)
		(end 145.57121 -255.584706)
		(width 0.0889)
		(layer "In13.Cu")
		(net "M_H_CPU1_SA_PAR")
	)
	(segment
		(start 168.275 -254.650748)
		(end 167.181784 -255.743964)
		(width 0.14478)
		(layer "In13.Cu")
		(net "M_H_CPU1_SA_PAR")
	)
	(segment
		(start 144.862296 -255.502156)
		(end 144.84858 -255.494282)
		(width 0.0889)
		(layer "In13.Cu")
		(net "M_H_CPU1_SA_PAR")
	)
	(segment
		(start 134.488682 -255.559052)
		(end 134.334758 -255.824482)
		(width 0.0889)
		(layer "In13.Cu")
		(net "M_H_CPU1_SA_PAR")
	)
	(segment
		(start 169.291 -254.650748)
		(end 168.275 -254.650748)
		(width 0.14478)
		(layer "In13.Cu")
		(net "M_H_CPU1_SA_PAR")
	)
	(segment
		(start 176.072038 -254.285242)
		(end 172.99432 -253.010416)
		(width 0.14478)
		(layer "In13.Cu")
		(net "M_H_CPU1_SA_PAR")
	)
	(segment
		(start 144.878044 -255.5113)
		(end 144.862296 -255.502156)
		(width 0.0889)
		(layer "In13.Cu")
		(net "M_H_CPU1_SA_PAR")
	)
	(segment
		(start 140.161772 -255.501902)
		(end 140.15339 -255.497076)
		(width 0.0889)
		(layer "In13.Cu")
		(net "M_H_CPU1_SA_PAR")
	)
	(arc
		(start 142.98168 -255.501902)
		(mid 142.794736 -255.451647)
		(end 142.607792 -255.501902)
		(width 0.0889)
		(layer "In13.Cu")
		(net "M_H_CPU1_SA_PAR")
	)
	(arc
		(start 140.727684 -255.501902)
		(mid 140.444728 -255.578079)
		(end 140.161772 -255.501902)
		(width 0.0889)
		(layer "In13.Cu")
		(net "M_H_CPU1_SA_PAR")
	)
	(arc
		(start 136.027668 -255.501902)
		(mid 135.744712 -255.578079)
		(end 135.461756 -255.501902)
		(width 0.0889)
		(layer "In13.Cu")
		(net "M_H_CPU1_SA_PAR")
	)
	(arc
		(start 142.04188 -255.501902)
		(mid 141.859629 -255.451552)
		(end 141.67612 -255.497076)
		(width 0.0889)
		(layer "In13.Cu")
		(net "M_H_CPU1_SA_PAR")
	)
	(arc
		(start 142.607792 -255.501902)
		(mid 142.324836 -255.578079)
		(end 142.04188 -255.501902)
		(width 0.0889)
		(layer "In13.Cu")
		(net "M_H_CPU1_SA_PAR")
	)
	(arc
		(start 137.341864 -255.501902)
		(mid 137.159613 -255.451552)
		(end 136.976104 -255.497076)
		(width 0.0889)
		(layer "In13.Cu")
		(net "M_H_CPU1_SA_PAR")
	)
	(arc
		(start 139.221718 -255.501902)
		(mid 139.034774 -255.451647)
		(end 138.84783 -255.501902)
		(width 0.0889)
		(layer "In13.Cu")
		(net "M_H_CPU1_SA_PAR")
	)
	(arc
		(start 139.78763 -255.501902)
		(mid 139.504674 -255.578079)
		(end 139.221718 -255.501902)
		(width 0.0889)
		(layer "In13.Cu")
		(net "M_H_CPU1_SA_PAR")
	)
	(arc
		(start 137.907776 -255.501902)
		(mid 137.62482 -255.578079)
		(end 137.341864 -255.501902)
		(width 0.0889)
		(layer "In13.Cu")
		(net "M_H_CPU1_SA_PAR")
	)
	(arc
		(start 144.84858 -255.494282)
		(mid 144.66765 -255.451804)
		(end 144.488662 -255.501902)
		(width 0.0889)
		(layer "In13.Cu")
		(net "M_H_CPU1_SA_PAR")
	)
	(arc
		(start 140.15339 -255.497076)
		(mid 139.969882 -255.451582)
		(end 139.78763 -255.501902)
		(width 0.0889)
		(layer "In13.Cu")
		(net "M_H_CPU1_SA_PAR")
	)
	(arc
		(start 136.393428 -255.497076)
		(mid 136.20992 -255.451582)
		(end 136.027668 -255.501902)
		(width 0.0889)
		(layer "In13.Cu")
		(net "M_H_CPU1_SA_PAR")
	)
	(arc
		(start 138.84783 -255.501902)
		(mid 138.564874 -255.578079)
		(end 138.281918 -255.501902)
		(width 0.0889)
		(layer "In13.Cu")
		(net "M_H_CPU1_SA_PAR")
	)
	(arc
		(start 141.093444 -255.497076)
		(mid 140.909936 -255.451582)
		(end 140.727684 -255.501902)
		(width 0.0889)
		(layer "In13.Cu")
		(net "M_H_CPU1_SA_PAR")
	)
	(arc
		(start 135.087614 -255.501902)
		(mid 134.839901 -255.577122)
		(end 134.584694 -255.533652)
		(width 0.0889)
		(layer "In13.Cu")
		(net "M_H_CPU1_SA_PAR")
	)
	(arc
		(start 141.667738 -255.501902)
		(mid 141.384782 -255.578079)
		(end 141.101826 -255.501902)
		(width 0.0889)
		(layer "In13.Cu")
		(net "M_H_CPU1_SA_PAR")
	)
	(arc
		(start 144.47393 -255.510538)
		(mid 144.196947 -255.578342)
		(end 143.922242 -255.501902)
		(width 0.0889)
		(layer "In13.Cu")
		(net "M_H_CPU1_SA_PAR")
	)
	(arc
		(start 143.922242 -255.501902)
		(mid 143.739737 -255.451425)
		(end 143.555974 -255.497076)
		(width 0.0889)
		(layer "In13.Cu")
		(net "M_H_CPU1_SA_PAR")
	)
	(arc
		(start 135.453374 -255.497076)
		(mid 135.269866 -255.451582)
		(end 135.087614 -255.501902)
		(width 0.0889)
		(layer "In13.Cu")
		(net "M_H_CPU1_SA_PAR")
	)
	(arc
		(start 143.547592 -255.501902)
		(mid 143.264636 -255.578079)
		(end 142.98168 -255.501902)
		(width 0.0889)
		(layer "In13.Cu")
		(net "M_H_CPU1_SA_PAR")
	)
	(arc
		(start 145.150586 -255.584706)
		(mid 145.009456 -255.566038)
		(end 144.878044 -255.5113)
		(width 0.0889)
		(layer "In13.Cu")
		(net "M_H_CPU1_SA_PAR")
	)
	(arc
		(start 136.967722 -255.501902)
		(mid 136.684766 -255.578079)
		(end 136.40181 -255.501902)
		(width 0.0889)
		(layer "In13.Cu")
		(net "M_H_CPU1_SA_PAR")
	)
	(arc
		(start 138.281918 -255.501902)
		(mid 138.099667 -255.451552)
		(end 137.916158 -255.497076)
		(width 0.0889)
		(layer "In13.Cu")
		(net "M_H_CPU1_SA_PAR")
	)
	(segment
		(start 133.867906 -247.99036)
		(end 134.334758 -247.724422)
		(width 0.12954)
		(layer "F.Cu")
		(net "M_H_CPU1_SA_DQS_DP<9>")
	)
	(segment
		(start 161.696908 -242.92306)
		(end 161.471102 -242.92306)
		(width 0.16002)
		(layer "In13.Cu")
		(net "M_H_CPU1_SA_DQS_DP<9>")
	)
	(segment
		(start 162.843972 -241.55019)
		(end 162.597084 -241.797078)
		(width 0.16002)
		(layer "In13.Cu")
		(net "M_H_CPU1_SA_DQS_DP<9>")
	)
	(segment
		(start 162.597084 -242.023392)
		(end 162.69081 -242.117372)
		(width 0.16002)
		(layer "In13.Cu")
		(net "M_H_CPU1_SA_DQS_DP<9>")
	)
	(segment
		(start 161.224214 -243.396262)
		(end 161.31794 -243.490242)
		(width 0.16002)
		(layer "In13.Cu")
		(net "M_H_CPU1_SA_DQS_DP<9>")
	)
	(segment
		(start 161.790888 -243.01704)
		(end 161.696908 -242.92306)
		(width 0.16002)
		(layer "In13.Cu")
		(net "M_H_CPU1_SA_DQS_DP<9>")
	)
	(segment
		(start 162.597084 -241.797078)
		(end 162.597084 -242.023392)
		(width 0.16002)
		(layer "In13.Cu")
		(net "M_H_CPU1_SA_DQS_DP<9>")
	)
	(segment
		(start 161.224214 -243.169948)
		(end 161.224214 -243.396262)
		(width 0.16002)
		(layer "In13.Cu")
		(net "M_H_CPU1_SA_DQS_DP<9>")
	)
	(segment
		(start 137.914634 -247.394476)
		(end 137.906252 -247.399302)
		(width 0.09525)
		(layer "In13.Cu")
		(net "M_H_CPU1_SA_DQS_DP<9>")
	)
	(segment
		(start 135.46328 -247.399302)
		(end 135.454898 -247.394476)
		(width 0.09525)
		(layer "In13.Cu")
		(net "M_H_CPU1_SA_DQS_DP<9>")
	)
	(segment
		(start 146.033744 -247.609614)
		(end 145.882106 -247.45823)
		(width 0.09525)
		(layer "In13.Cu")
		(net "M_H_CPU1_SA_DQS_DP<9>")
	)
	(segment
		(start 136.97458 -247.394476)
		(end 136.966198 -247.399302)
		(width 0.09525)
		(layer "In13.Cu")
		(net "M_H_CPU1_SA_DQS_DP<9>")
	)
	(segment
		(start 147.895564 -247.104916)
		(end 147.836636 -247.045988)
		(width 0.09525)
		(layer "In13.Cu")
		(net "M_H_CPU1_SA_DQS_DP<9>")
	)
	(segment
		(start 161.31794 -243.490242)
		(end 161.31794 -243.966492)
		(width 0.16002)
		(layer "In13.Cu")
		(net "M_H_CPU1_SA_DQS_DP<9>")
	)
	(segment
		(start 158.478474 -246.142002)
		(end 158.5722 -246.235982)
		(width 0.16002)
		(layer "In13.Cu")
		(net "M_H_CPU1_SA_DQS_DP<9>")
	)
	(segment
		(start 158.725362 -245.6688)
		(end 158.478474 -245.915688)
		(width 0.16002)
		(layer "In13.Cu")
		(net "M_H_CPU1_SA_DQS_DP<9>")
	)
	(segment
		(start 160.894522 -244.38991)
		(end 160.418018 -244.38991)
		(width 0.16002)
		(layer "In13.Cu")
		(net "M_H_CPU1_SA_DQS_DP<9>")
	)
	(segment
		(start 141.674596 -247.394476)
		(end 141.666214 -247.399302)
		(width 0.09525)
		(layer "In13.Cu")
		(net "M_H_CPU1_SA_DQS_DP<9>")
	)
	(segment
		(start 146.938746 -247.609614)
		(end 146.033744 -247.609614)
		(width 0.09525)
		(layer "In13.Cu")
		(net "M_H_CPU1_SA_DQS_DP<9>")
	)
	(segment
		(start 159.94507 -245.339362)
		(end 159.521652 -245.76278)
		(width 0.16002)
		(layer "In13.Cu")
		(net "M_H_CPU1_SA_DQS_DP<9>")
	)
	(segment
		(start 170.537886 -240.198148)
		(end 168.332404 -240.198148)
		(width 0.16002)
		(layer "In13.Cu")
		(net "M_H_CPU1_SA_DQS_DP<9>")
	)
	(segment
		(start 166.928546 -239.397286)
		(end 166.16553 -240.160302)
		(width 0.16002)
		(layer "In13.Cu")
		(net "M_H_CPU1_SA_DQS_DP<9>")
	)
	(segment
		(start 158.5722 -246.235982)
		(end 158.5722 -246.712232)
		(width 0.16002)
		(layer "In13.Cu")
		(net "M_H_CPU1_SA_DQS_DP<9>")
	)
	(segment
		(start 144.86382 -247.399302)
		(end 144.855438 -247.394476)
		(width 0.09525)
		(layer "In13.Cu")
		(net "M_H_CPU1_SA_DQS_DP<9>")
	)
	(segment
		(start 158.951168 -245.6688)
		(end 158.725362 -245.6688)
		(width 0.16002)
		(layer "In13.Cu")
		(net "M_H_CPU1_SA_DQS_DP<9>")
	)
	(segment
		(start 136.403334 -247.399302)
		(end 136.394952 -247.394476)
		(width 0.09525)
		(layer "In13.Cu")
		(net "M_H_CPU1_SA_DQS_DP<9>")
	)
	(segment
		(start 171.722542 -239.586008)
		(end 171.150026 -239.586008)
		(width 0.16002)
		(layer "In13.Cu")
		(net "M_H_CPU1_SA_DQS_DP<9>")
	)
	(segment
		(start 159.045148 -245.76278)
		(end 158.951168 -245.6688)
		(width 0.16002)
		(layer "In13.Cu")
		(net "M_H_CPU1_SA_DQS_DP<9>")
	)
	(segment
		(start 161.31794 -243.966492)
		(end 160.894522 -244.38991)
		(width 0.16002)
		(layer "In13.Cu")
		(net "M_H_CPU1_SA_DQS_DP<9>")
	)
	(segment
		(start 144.884648 -247.411494)
		(end 144.86382 -247.399302)
		(width 0.09525)
		(layer "In13.Cu")
		(net "M_H_CPU1_SA_DQS_DP<9>")
	)
	(segment
		(start 160.418018 -244.38991)
		(end 160.324038 -244.29593)
		(width 0.16002)
		(layer "In13.Cu")
		(net "M_H_CPU1_SA_DQS_DP<9>")
	)
	(segment
		(start 160.098232 -244.29593)
		(end 159.851344 -244.542818)
		(width 0.16002)
		(layer "In13.Cu")
		(net "M_H_CPU1_SA_DQS_DP<9>")
	)
	(segment
		(start 147.836636 -247.045988)
		(end 147.502372 -247.045988)
		(width 0.09525)
		(layer "In13.Cu")
		(net "M_H_CPU1_SA_DQS_DP<9>")
	)
	(segment
		(start 163.163758 -241.64417)
		(end 163.069778 -241.55019)
		(width 0.16002)
		(layer "In13.Cu")
		(net "M_H_CPU1_SA_DQS_DP<9>")
	)
	(segment
		(start 143.55445 -247.394476)
		(end 143.546068 -247.399302)
		(width 0.09525)
		(layer "In13.Cu")
		(net "M_H_CPU1_SA_DQS_DP<9>")
	)
	(segment
		(start 171.150026 -239.586008)
		(end 170.537886 -240.198148)
		(width 0.16002)
		(layer "In13.Cu")
		(net "M_H_CPU1_SA_DQS_DP<9>")
	)
	(segment
		(start 162.69081 -242.117372)
		(end 162.69081 -242.593622)
		(width 0.16002)
		(layer "In13.Cu")
		(net "M_H_CPU1_SA_DQS_DP<9>")
	)
	(segment
		(start 158.179516 -247.104916)
		(end 147.919186 -247.104916)
		(width 0.16002)
		(layer "In13.Cu")
		(net "M_H_CPU1_SA_DQS_DP<9>")
	)
	(segment
		(start 167.531542 -239.397286)
		(end 166.928546 -239.397286)
		(width 0.16002)
		(layer "In13.Cu")
		(net "M_H_CPU1_SA_DQS_DP<9>")
	)
	(segment
		(start 134.58952 -247.432322)
		(end 134.488682 -247.458992)
		(width 0.09525)
		(layer "In13.Cu")
		(net "M_H_CPU1_SA_DQS_DP<9>")
	)
	(segment
		(start 160.324038 -244.29593)
		(end 160.098232 -244.29593)
		(width 0.16002)
		(layer "In13.Cu")
		(net "M_H_CPU1_SA_DQS_DP<9>")
	)
	(segment
		(start 163.069778 -241.55019)
		(end 162.843972 -241.55019)
		(width 0.16002)
		(layer "In13.Cu")
		(net "M_H_CPU1_SA_DQS_DP<9>")
	)
	(segment
		(start 144.487138 -247.399302)
		(end 144.472406 -247.407938)
		(width 0.09525)
		(layer "In13.Cu")
		(net "M_H_CPU1_SA_DQS_DP<9>")
	)
	(segment
		(start 171.97197 -239.835436)
		(end 171.722542 -239.586008)
		(width 0.16002)
		(layer "In13.Cu")
		(net "M_H_CPU1_SA_DQS_DP<9>")
	)
	(segment
		(start 158.5722 -246.712232)
		(end 158.179516 -247.104916)
		(width 0.16002)
		(layer "In13.Cu")
		(net "M_H_CPU1_SA_DQS_DP<9>")
	)
	(segment
		(start 158.478474 -245.915688)
		(end 158.478474 -246.142002)
		(width 0.16002)
		(layer "In13.Cu")
		(net "M_H_CPU1_SA_DQS_DP<9>")
	)
	(segment
		(start 159.851344 -244.769132)
		(end 159.94507 -244.863112)
		(width 0.16002)
		(layer "In13.Cu")
		(net "M_H_CPU1_SA_DQS_DP<9>")
	)
	(segment
		(start 166.16553 -240.160302)
		(end 165.12413 -240.160302)
		(width 0.16002)
		(layer "In13.Cu")
		(net "M_H_CPU1_SA_DQS_DP<9>")
	)
	(segment
		(start 159.94507 -244.863112)
		(end 159.94507 -245.339362)
		(width 0.16002)
		(layer "In13.Cu")
		(net "M_H_CPU1_SA_DQS_DP<9>")
	)
	(segment
		(start 134.488682 -247.458992)
		(end 134.334758 -247.724422)
		(width 0.09525)
		(layer "In13.Cu")
		(net "M_H_CPU1_SA_DQS_DP<9>")
	)
	(segment
		(start 168.332404 -240.198148)
		(end 167.531542 -239.397286)
		(width 0.16002)
		(layer "In13.Cu")
		(net "M_H_CPU1_SA_DQS_DP<9>")
	)
	(segment
		(start 147.919186 -247.104916)
		(end 147.895564 -247.104916)
		(width 0.09525)
		(layer "In13.Cu")
		(net "M_H_CPU1_SA_DQS_DP<9>")
	)
	(segment
		(start 165.12413 -240.160302)
		(end 163.640262 -241.64417)
		(width 0.16002)
		(layer "In13.Cu")
		(net "M_H_CPU1_SA_DQS_DP<9>")
	)
	(segment
		(start 162.267392 -243.01704)
		(end 161.790888 -243.01704)
		(width 0.16002)
		(layer "In13.Cu")
		(net "M_H_CPU1_SA_DQS_DP<9>")
	)
	(segment
		(start 159.851344 -244.542818)
		(end 159.851344 -244.769132)
		(width 0.16002)
		(layer "In13.Cu")
		(net "M_H_CPU1_SA_DQS_DP<9>")
	)
	(segment
		(start 163.640262 -241.64417)
		(end 163.163758 -241.64417)
		(width 0.16002)
		(layer "In13.Cu")
		(net "M_H_CPU1_SA_DQS_DP<9>")
	)
	(segment
		(start 140.163296 -247.399302)
		(end 140.154914 -247.394476)
		(width 0.09525)
		(layer "In13.Cu")
		(net "M_H_CPU1_SA_DQS_DP<9>")
	)
	(segment
		(start 147.502372 -247.045988)
		(end 146.938746 -247.609614)
		(width 0.09525)
		(layer "In13.Cu")
		(net "M_H_CPU1_SA_DQS_DP<9>")
	)
	(segment
		(start 159.521652 -245.76278)
		(end 159.045148 -245.76278)
		(width 0.16002)
		(layer "In13.Cu")
		(net "M_H_CPU1_SA_DQS_DP<9>")
	)
	(segment
		(start 141.10335 -247.399302)
		(end 141.094968 -247.394476)
		(width 0.09525)
		(layer "In13.Cu")
		(net "M_H_CPU1_SA_DQS_DP<9>")
	)
	(segment
		(start 162.69081 -242.593622)
		(end 162.267392 -243.01704)
		(width 0.16002)
		(layer "In13.Cu")
		(net "M_H_CPU1_SA_DQS_DP<9>")
	)
	(segment
		(start 161.471102 -242.92306)
		(end 161.224214 -243.169948)
		(width 0.16002)
		(layer "In13.Cu")
		(net "M_H_CPU1_SA_DQS_DP<9>")
	)
	(arc
		(start 145.426684 -247.399302)
		(mid 145.157251 -247.475173)
		(end 144.884648 -247.411494)
		(width 0.09525)
		(layer "In13.Cu")
		(net "M_H_CPU1_SA_DQS_DP<9>")
	)
	(arc
		(start 138.283442 -247.399302)
		(mid 138.099667 -247.34853)
		(end 137.914634 -247.394476)
		(width 0.09525)
		(layer "In13.Cu")
		(net "M_H_CPU1_SA_DQS_DP<9>")
	)
	(arc
		(start 140.72616 -247.399302)
		(mid 140.444728 -247.475057)
		(end 140.163296 -247.399302)
		(width 0.09525)
		(layer "In13.Cu")
		(net "M_H_CPU1_SA_DQS_DP<9>")
	)
	(arc
		(start 140.154914 -247.394476)
		(mid 139.969882 -247.348562)
		(end 139.786106 -247.399302)
		(width 0.09525)
		(layer "In13.Cu")
		(net "M_H_CPU1_SA_DQS_DP<9>")
	)
	(arc
		(start 142.043404 -247.399302)
		(mid 141.859629 -247.34853)
		(end 141.674596 -247.394476)
		(width 0.09525)
		(layer "In13.Cu")
		(net "M_H_CPU1_SA_DQS_DP<9>")
	)
	(arc
		(start 139.223242 -247.399302)
		(mid 139.034774 -247.348625)
		(end 138.846306 -247.399302)
		(width 0.09525)
		(layer "In13.Cu")
		(net "M_H_CPU1_SA_DQS_DP<9>")
	)
	(arc
		(start 135.08609 -247.399302)
		(mid 134.852546 -247.473008)
		(end 134.60984 -247.440196)
		(width 0.09525)
		(layer "In13.Cu")
		(net "M_H_CPU1_SA_DQS_DP<9>")
	)
	(arc
		(start 145.796 -247.394476)
		(mid 145.610714 -247.34844)
		(end 145.426684 -247.399302)
		(width 0.09525)
		(layer "In13.Cu")
		(net "M_H_CPU1_SA_DQS_DP<9>")
	)
	(arc
		(start 137.343388 -247.399302)
		(mid 137.159613 -247.34853)
		(end 136.97458 -247.394476)
		(width 0.09525)
		(layer "In13.Cu")
		(net "M_H_CPU1_SA_DQS_DP<9>")
	)
	(arc
		(start 136.026144 -247.399302)
		(mid 135.744712 -247.475057)
		(end 135.46328 -247.399302)
		(width 0.09525)
		(layer "In13.Cu")
		(net "M_H_CPU1_SA_DQS_DP<9>")
	)
	(arc
		(start 138.846306 -247.399302)
		(mid 138.564874 -247.475057)
		(end 138.283442 -247.399302)
		(width 0.09525)
		(layer "In13.Cu")
		(net "M_H_CPU1_SA_DQS_DP<9>")
	)
	(arc
		(start 136.966198 -247.399302)
		(mid 136.684766 -247.475057)
		(end 136.403334 -247.399302)
		(width 0.09525)
		(layer "In13.Cu")
		(net "M_H_CPU1_SA_DQS_DP<9>")
	)
	(arc
		(start 135.454898 -247.394476)
		(mid 135.269866 -247.348562)
		(end 135.08609 -247.399302)
		(width 0.09525)
		(layer "In13.Cu")
		(net "M_H_CPU1_SA_DQS_DP<9>")
	)
	(arc
		(start 137.906252 -247.399302)
		(mid 137.62482 -247.475057)
		(end 137.343388 -247.399302)
		(width 0.09525)
		(layer "In13.Cu")
		(net "M_H_CPU1_SA_DQS_DP<9>")
	)
	(arc
		(start 144.472406 -247.407938)
		(mid 144.196947 -247.475323)
		(end 143.923766 -247.399302)
		(width 0.09525)
		(layer "In13.Cu")
		(net "M_H_CPU1_SA_DQS_DP<9>")
	)
	(arc
		(start 143.546068 -247.399302)
		(mid 143.264636 -247.475057)
		(end 142.983204 -247.399302)
		(width 0.09525)
		(layer "In13.Cu")
		(net "M_H_CPU1_SA_DQS_DP<9>")
	)
	(arc
		(start 134.60984 -247.440196)
		(mid 134.599641 -247.436359)
		(end 134.58952 -247.432322)
		(width 0.09525)
		(layer "In13.Cu")
		(net "M_H_CPU1_SA_DQS_DP<9>")
	)
	(arc
		(start 145.86585 -247.44299)
		(mid 145.832293 -247.416765)
		(end 145.796 -247.394476)
		(width 0.09525)
		(layer "In13.Cu")
		(net "M_H_CPU1_SA_DQS_DP<9>")
	)
	(arc
		(start 143.923766 -247.399302)
		(mid 143.739737 -247.348403)
		(end 143.55445 -247.394476)
		(width 0.09525)
		(layer "In13.Cu")
		(net "M_H_CPU1_SA_DQS_DP<9>")
	)
	(arc
		(start 142.606268 -247.399302)
		(mid 142.324836 -247.475057)
		(end 142.043404 -247.399302)
		(width 0.09525)
		(layer "In13.Cu")
		(net "M_H_CPU1_SA_DQS_DP<9>")
	)
	(arc
		(start 139.786106 -247.399302)
		(mid 139.504674 -247.475057)
		(end 139.223242 -247.399302)
		(width 0.09525)
		(layer "In13.Cu")
		(net "M_H_CPU1_SA_DQS_DP<9>")
	)
	(arc
		(start 136.394952 -247.394476)
		(mid 136.20992 -247.348562)
		(end 136.026144 -247.399302)
		(width 0.09525)
		(layer "In13.Cu")
		(net "M_H_CPU1_SA_DQS_DP<9>")
	)
	(arc
		(start 145.882106 -247.45823)
		(mid 145.874089 -247.450491)
		(end 145.86585 -247.44299)
		(width 0.09525)
		(layer "In13.Cu")
		(net "M_H_CPU1_SA_DQS_DP<9>")
	)
	(arc
		(start 142.983204 -247.399302)
		(mid 142.794736 -247.348625)
		(end 142.606268 -247.399302)
		(width 0.09525)
		(layer "In13.Cu")
		(net "M_H_CPU1_SA_DQS_DP<9>")
	)
	(arc
		(start 141.666214 -247.399302)
		(mid 141.384782 -247.475057)
		(end 141.10335 -247.399302)
		(width 0.09525)
		(layer "In13.Cu")
		(net "M_H_CPU1_SA_DQS_DP<9>")
	)
	(arc
		(start 144.855438 -247.394476)
		(mid 144.67066 -247.348683)
		(end 144.487138 -247.399302)
		(width 0.09525)
		(layer "In13.Cu")
		(net "M_H_CPU1_SA_DQS_DP<9>")
	)
	(arc
		(start 141.094968 -247.394476)
		(mid 140.909936 -247.348562)
		(end 140.72616 -247.399302)
		(width 0.09525)
		(layer "In13.Cu")
		(net "M_H_CPU1_SA_DQS_DP<9>")
	)
	(segment
		(start 133.867906 -243.130324)
		(end 134.334758 -242.864386)
		(width 0.12954)
		(layer "F.Cu")
		(net "M_H_CPU1_SA_DQS_DP<8>")
	)
	(segment
		(start 140.163296 -242.539266)
		(end 140.154914 -242.53444)
		(width 0.09525)
		(layer "In13.Cu")
		(net "M_H_CPU1_SA_DQS_DP<8>")
	)
	(segment
		(start 162.656012 -230.742998)
		(end 162.429952 -230.742998)
		(width 0.16002)
		(layer "In13.Cu")
		(net "M_H_CPU1_SA_DQS_DP<8>")
	)
	(segment
		(start 162.183064 -231.215946)
		(end 162.512756 -231.545638)
		(width 0.16002)
		(layer "In13.Cu")
		(net "M_H_CPU1_SA_DQS_DP<8>")
	)
	(segment
		(start 162.089338 -232.44556)
		(end 161.612834 -232.44556)
		(width 0.16002)
		(layer "In13.Cu")
		(net "M_H_CPU1_SA_DQS_DP<8>")
	)
	(segment
		(start 147.597368 -241.444018)
		(end 146.88693 -242.154456)
		(width 0.09525)
		(layer "In13.Cu")
		(net "M_H_CPU1_SA_DQS_DP<8>")
	)
	(segment
		(start 134.488682 -242.598956)
		(end 134.334758 -242.864386)
		(width 0.09525)
		(layer "In13.Cu")
		(net "M_H_CPU1_SA_DQS_DP<8>")
	)
	(segment
		(start 162.429952 -230.742998)
		(end 162.183064 -230.989886)
		(width 0.16002)
		(layer "In13.Cu")
		(net "M_H_CPU1_SA_DQS_DP<8>")
	)
	(segment
		(start 146.88693 -242.154456)
		(end 146.38528 -242.154456)
		(width 0.09525)
		(layer "In13.Cu")
		(net "M_H_CPU1_SA_DQS_DP<8>")
	)
	(segment
		(start 147.847558 -241.502946)
		(end 147.823936 -241.502946)
		(width 0.09525)
		(layer "In13.Cu")
		(net "M_H_CPU1_SA_DQS_DP<8>")
	)
	(segment
		(start 136.97458 -242.53444)
		(end 136.966198 -242.539266)
		(width 0.09525)
		(layer "In13.Cu")
		(net "M_H_CPU1_SA_DQS_DP<8>")
	)
	(segment
		(start 137.914634 -242.53444)
		(end 137.906252 -242.539266)
		(width 0.09525)
		(layer "In13.Cu")
		(net "M_H_CPU1_SA_DQS_DP<8>")
	)
	(segment
		(start 159.011366 -235.523532)
		(end 158.108142 -235.523532)
		(width 0.16002)
		(layer "In13.Cu")
		(net "M_H_CPU1_SA_DQS_DP<8>")
	)
	(segment
		(start 145.92427 -242.615466)
		(end 144.20596 -242.615466)
		(width 0.09525)
		(layer "In13.Cu")
		(net "M_H_CPU1_SA_DQS_DP<8>")
	)
	(segment
		(start 152.128728 -241.502946)
		(end 147.847558 -241.502946)
		(width 0.16002)
		(layer "In13.Cu")
		(net "M_H_CPU1_SA_DQS_DP<8>")
	)
	(segment
		(start 161.283142 -232.115868)
		(end 161.057082 -232.115868)
		(width 0.16002)
		(layer "In13.Cu")
		(net "M_H_CPU1_SA_DQS_DP<8>")
	)
	(segment
		(start 159.767016 -234.291378)
		(end 159.767016 -234.767882)
		(width 0.16002)
		(layer "In13.Cu")
		(net "M_H_CPU1_SA_DQS_DP<8>")
	)
	(segment
		(start 171.674536 -230.188008)
		(end 170.01363 -230.188008)
		(width 0.16002)
		(layer "In13.Cu")
		(net "M_H_CPU1_SA_DQS_DP<8>")
	)
	(segment
		(start 159.910272 -233.488738)
		(end 159.684212 -233.488738)
		(width 0.16002)
		(layer "In13.Cu")
		(net "M_H_CPU1_SA_DQS_DP<8>")
	)
	(segment
		(start 166.93515 -230.040688)
		(end 166.16553 -230.810308)
		(width 0.16002)
		(layer "In13.Cu")
		(net "M_H_CPU1_SA_DQS_DP<8>")
	)
	(segment
		(start 161.612834 -232.44556)
		(end 161.283142 -232.115868)
		(width 0.16002)
		(layer "In13.Cu")
		(net "M_H_CPU1_SA_DQS_DP<8>")
	)
	(segment
		(start 169.86631 -230.040688)
		(end 166.93515 -230.040688)
		(width 0.16002)
		(layer "In13.Cu")
		(net "M_H_CPU1_SA_DQS_DP<8>")
	)
	(segment
		(start 166.16553 -230.810308)
		(end 163.72459 -230.810308)
		(width 0.16002)
		(layer "In13.Cu")
		(net "M_H_CPU1_SA_DQS_DP<8>")
	)
	(segment
		(start 159.767016 -234.767882)
		(end 159.011366 -235.523532)
		(width 0.16002)
		(layer "In13.Cu")
		(net "M_H_CPU1_SA_DQS_DP<8>")
	)
	(segment
		(start 147.765008 -241.444018)
		(end 147.597368 -241.444018)
		(width 0.09525)
		(layer "In13.Cu")
		(net "M_H_CPU1_SA_DQS_DP<8>")
	)
	(segment
		(start 162.512756 -231.545638)
		(end 162.512756 -232.022142)
		(width 0.16002)
		(layer "In13.Cu")
		(net "M_H_CPU1_SA_DQS_DP<8>")
	)
	(segment
		(start 160.716468 -233.81843)
		(end 160.239964 -233.81843)
		(width 0.16002)
		(layer "In13.Cu")
		(net "M_H_CPU1_SA_DQS_DP<8>")
	)
	(segment
		(start 159.684212 -233.488738)
		(end 159.437324 -233.735626)
		(width 0.16002)
		(layer "In13.Cu")
		(net "M_H_CPU1_SA_DQS_DP<8>")
	)
	(segment
		(start 162.985704 -231.07269)
		(end 162.656012 -230.742998)
		(width 0.16002)
		(layer "In13.Cu")
		(net "M_H_CPU1_SA_DQS_DP<8>")
	)
	(segment
		(start 160.239964 -233.81843)
		(end 159.910272 -233.488738)
		(width 0.16002)
		(layer "In13.Cu")
		(net "M_H_CPU1_SA_DQS_DP<8>")
	)
	(segment
		(start 141.674596 -242.53444)
		(end 141.666214 -242.539266)
		(width 0.09525)
		(layer "In13.Cu")
		(net "M_H_CPU1_SA_DQS_DP<8>")
	)
	(segment
		(start 143.55445 -242.53444)
		(end 143.546068 -242.539266)
		(width 0.09525)
		(layer "In13.Cu")
		(net "M_H_CPU1_SA_DQS_DP<8>")
	)
	(segment
		(start 141.10335 -242.539266)
		(end 141.094968 -242.53444)
		(width 0.09525)
		(layer "In13.Cu")
		(net "M_H_CPU1_SA_DQS_DP<8>")
	)
	(segment
		(start 170.01363 -230.188008)
		(end 169.86631 -230.040688)
		(width 0.16002)
		(layer "In13.Cu")
		(net "M_H_CPU1_SA_DQS_DP<8>")
	)
	(segment
		(start 161.139886 -232.918508)
		(end 161.139886 -233.395012)
		(width 0.16002)
		(layer "In13.Cu")
		(net "M_H_CPU1_SA_DQS_DP<8>")
	)
	(segment
		(start 171.97197 -230.485442)
		(end 171.674536 -230.188008)
		(width 0.16002)
		(layer "In13.Cu")
		(net "M_H_CPU1_SA_DQS_DP<8>")
	)
	(segment
		(start 136.403334 -242.539266)
		(end 136.394952 -242.53444)
		(width 0.09525)
		(layer "In13.Cu")
		(net "M_H_CPU1_SA_DQS_DP<8>")
	)
	(segment
		(start 147.823936 -241.502946)
		(end 147.765008 -241.444018)
		(width 0.09525)
		(layer "In13.Cu")
		(net "M_H_CPU1_SA_DQS_DP<8>")
	)
	(segment
		(start 163.462208 -231.07269)
		(end 162.985704 -231.07269)
		(width 0.16002)
		(layer "In13.Cu")
		(net "M_H_CPU1_SA_DQS_DP<8>")
	)
	(segment
		(start 163.72459 -230.810308)
		(end 163.462208 -231.07269)
		(width 0.16002)
		(layer "In13.Cu")
		(net "M_H_CPU1_SA_DQS_DP<8>")
	)
	(segment
		(start 135.46328 -242.539266)
		(end 135.454898 -242.53444)
		(width 0.09525)
		(layer "In13.Cu")
		(net "M_H_CPU1_SA_DQS_DP<8>")
	)
	(segment
		(start 158.108142 -235.523532)
		(end 152.128728 -241.502946)
		(width 0.16002)
		(layer "In13.Cu")
		(net "M_H_CPU1_SA_DQS_DP<8>")
	)
	(segment
		(start 161.139886 -233.395012)
		(end 160.716468 -233.81843)
		(width 0.16002)
		(layer "In13.Cu")
		(net "M_H_CPU1_SA_DQS_DP<8>")
	)
	(segment
		(start 161.057082 -232.115868)
		(end 160.810194 -232.362756)
		(width 0.16002)
		(layer "In13.Cu")
		(net "M_H_CPU1_SA_DQS_DP<8>")
	)
	(segment
		(start 146.38528 -242.154456)
		(end 145.92427 -242.615466)
		(width 0.09525)
		(layer "In13.Cu")
		(net "M_H_CPU1_SA_DQS_DP<8>")
	)
	(segment
		(start 160.810194 -232.362756)
		(end 160.810194 -232.588816)
		(width 0.16002)
		(layer "In13.Cu")
		(net "M_H_CPU1_SA_DQS_DP<8>")
	)
	(segment
		(start 159.437324 -233.735626)
		(end 159.437324 -233.961686)
		(width 0.16002)
		(layer "In13.Cu")
		(net "M_H_CPU1_SA_DQS_DP<8>")
	)
	(segment
		(start 162.512756 -232.022142)
		(end 162.089338 -232.44556)
		(width 0.16002)
		(layer "In13.Cu")
		(net "M_H_CPU1_SA_DQS_DP<8>")
	)
	(segment
		(start 160.810194 -232.588816)
		(end 161.139886 -232.918508)
		(width 0.16002)
		(layer "In13.Cu")
		(net "M_H_CPU1_SA_DQS_DP<8>")
	)
	(segment
		(start 134.58952 -242.572286)
		(end 134.488682 -242.598956)
		(width 0.09525)
		(layer "In13.Cu")
		(net "M_H_CPU1_SA_DQS_DP<8>")
	)
	(segment
		(start 162.183064 -230.989886)
		(end 162.183064 -231.215946)
		(width 0.16002)
		(layer "In13.Cu")
		(net "M_H_CPU1_SA_DQS_DP<8>")
	)
	(segment
		(start 159.437324 -233.961686)
		(end 159.767016 -234.291378)
		(width 0.16002)
		(layer "In13.Cu")
		(net "M_H_CPU1_SA_DQS_DP<8>")
	)
	(arc
		(start 139.786106 -242.539266)
		(mid 139.504674 -242.615021)
		(end 139.223242 -242.539266)
		(width 0.09525)
		(layer "In13.Cu")
		(net "M_H_CPU1_SA_DQS_DP<8>")
	)
	(arc
		(start 136.966198 -242.539266)
		(mid 136.684766 -242.615021)
		(end 136.403334 -242.539266)
		(width 0.09525)
		(layer "In13.Cu")
		(net "M_H_CPU1_SA_DQS_DP<8>")
	)
	(arc
		(start 143.546068 -242.539266)
		(mid 143.264636 -242.615021)
		(end 142.983204 -242.539266)
		(width 0.09525)
		(layer "In13.Cu")
		(net "M_H_CPU1_SA_DQS_DP<8>")
	)
	(arc
		(start 137.906252 -242.539266)
		(mid 137.62482 -242.615021)
		(end 137.343388 -242.539266)
		(width 0.09525)
		(layer "In13.Cu")
		(net "M_H_CPU1_SA_DQS_DP<8>")
	)
	(arc
		(start 139.223242 -242.539266)
		(mid 139.034774 -242.488589)
		(end 138.846306 -242.539266)
		(width 0.09525)
		(layer "In13.Cu")
		(net "M_H_CPU1_SA_DQS_DP<8>")
	)
	(arc
		(start 142.983204 -242.539266)
		(mid 142.794736 -242.488589)
		(end 142.606268 -242.539266)
		(width 0.09525)
		(layer "In13.Cu")
		(net "M_H_CPU1_SA_DQS_DP<8>")
	)
	(arc
		(start 143.923766 -242.539266)
		(mid 143.739737 -242.488367)
		(end 143.55445 -242.53444)
		(width 0.09525)
		(layer "In13.Cu")
		(net "M_H_CPU1_SA_DQS_DP<8>")
	)
	(arc
		(start 136.026144 -242.539266)
		(mid 135.744712 -242.615021)
		(end 135.46328 -242.539266)
		(width 0.09525)
		(layer "In13.Cu")
		(net "M_H_CPU1_SA_DQS_DP<8>")
	)
	(arc
		(start 137.343388 -242.539266)
		(mid 137.159613 -242.488494)
		(end 136.97458 -242.53444)
		(width 0.09525)
		(layer "In13.Cu")
		(net "M_H_CPU1_SA_DQS_DP<8>")
	)
	(arc
		(start 141.666214 -242.539266)
		(mid 141.384782 -242.615021)
		(end 141.10335 -242.539266)
		(width 0.09525)
		(layer "In13.Cu")
		(net "M_H_CPU1_SA_DQS_DP<8>")
	)
	(arc
		(start 136.394952 -242.53444)
		(mid 136.20992 -242.488526)
		(end 136.026144 -242.539266)
		(width 0.09525)
		(layer "In13.Cu")
		(net "M_H_CPU1_SA_DQS_DP<8>")
	)
	(arc
		(start 134.60984 -242.58016)
		(mid 134.599641 -242.576323)
		(end 134.58952 -242.572286)
		(width 0.09525)
		(layer "In13.Cu")
		(net "M_H_CPU1_SA_DQS_DP<8>")
	)
	(arc
		(start 144.20596 -242.615466)
		(mid 144.059801 -242.596095)
		(end 143.923766 -242.539266)
		(width 0.09525)
		(layer "In13.Cu")
		(net "M_H_CPU1_SA_DQS_DP<8>")
	)
	(arc
		(start 138.283442 -242.539266)
		(mid 138.099667 -242.488494)
		(end 137.914634 -242.53444)
		(width 0.09525)
		(layer "In13.Cu")
		(net "M_H_CPU1_SA_DQS_DP<8>")
	)
	(arc
		(start 141.094968 -242.53444)
		(mid 140.909936 -242.488526)
		(end 140.72616 -242.539266)
		(width 0.09525)
		(layer "In13.Cu")
		(net "M_H_CPU1_SA_DQS_DP<8>")
	)
	(arc
		(start 140.154914 -242.53444)
		(mid 139.969882 -242.488526)
		(end 139.786106 -242.539266)
		(width 0.09525)
		(layer "In13.Cu")
		(net "M_H_CPU1_SA_DQS_DP<8>")
	)
	(arc
		(start 142.043404 -242.539266)
		(mid 141.859629 -242.488494)
		(end 141.674596 -242.53444)
		(width 0.09525)
		(layer "In13.Cu")
		(net "M_H_CPU1_SA_DQS_DP<8>")
	)
	(arc
		(start 138.846306 -242.539266)
		(mid 138.564874 -242.615021)
		(end 138.283442 -242.539266)
		(width 0.09525)
		(layer "In13.Cu")
		(net "M_H_CPU1_SA_DQS_DP<8>")
	)
	(arc
		(start 135.08609 -242.539266)
		(mid 134.852546 -242.612972)
		(end 134.60984 -242.58016)
		(width 0.09525)
		(layer "In13.Cu")
		(net "M_H_CPU1_SA_DQS_DP<8>")
	)
	(arc
		(start 140.72616 -242.539266)
		(mid 140.444728 -242.615021)
		(end 140.163296 -242.539266)
		(width 0.09525)
		(layer "In13.Cu")
		(net "M_H_CPU1_SA_DQS_DP<8>")
	)
	(arc
		(start 135.454898 -242.53444)
		(mid 135.269866 -242.488526)
		(end 135.08609 -242.539266)
		(width 0.09525)
		(layer "In13.Cu")
		(net "M_H_CPU1_SA_DQS_DP<8>")
	)
	(arc
		(start 142.606268 -242.539266)
		(mid 142.324836 -242.615021)
		(end 142.043404 -242.539266)
		(width 0.09525)
		(layer "In13.Cu")
		(net "M_H_CPU1_SA_DQS_DP<8>")
	)
	(segment
		(start 133.867906 -238.270288)
		(end 134.334758 -238.00435)
		(width 0.12954)
		(layer "F.Cu")
		(net "M_H_CPU1_SA_DQS_DP<7>")
	)
	(segment
		(start 164.128958 -220.812106)
		(end 163.852352 -220.812106)
		(width 0.16002)
		(layer "In13.Cu")
		(net "M_H_CPU1_SA_DQS_DP<7>")
	)
	(segment
		(start 144.49425 -237.674404)
		(end 144.485868 -237.67923)
		(width 0.09525)
		(layer "In13.Cu")
		(net "M_H_CPU1_SA_DQS_DP<7>")
	)
	(segment
		(start 136.403334 -237.67923)
		(end 136.394952 -237.674404)
		(width 0.09525)
		(layer "In13.Cu")
		(net "M_H_CPU1_SA_DQS_DP<7>")
	)
	(segment
		(start 156.355034 -228.779324)
		(end 149.370034 -235.764324)
		(width 0.16002)
		(layer "In13.Cu")
		(net "M_H_CPU1_SA_DQS_DP<7>")
	)
	(segment
		(start 159.54248 -223.82861)
		(end 159.359854 -223.645984)
		(width 0.16002)
		(layer "In13.Cu")
		(net "M_H_CPU1_SA_DQS_DP<7>")
	)
	(segment
		(start 165.281102 -221.851474)
		(end 164.66185 -221.851474)
		(width 0.16002)
		(layer "In13.Cu")
		(net "M_H_CPU1_SA_DQS_DP<7>")
	)
	(segment
		(start 171.728384 -220.891608)
		(end 171.456858 -220.891608)
		(width 0.16002)
		(layer "In13.Cu")
		(net "M_H_CPU1_SA_DQS_DP<7>")
	)
	(segment
		(start 140.163296 -237.67923)
		(end 140.154914 -237.674404)
		(width 0.09525)
		(layer "In13.Cu")
		(net "M_H_CPU1_SA_DQS_DP<7>")
	)
	(segment
		(start 171.456858 -220.891608)
		(end 170.800776 -221.54769)
		(width 0.16002)
		(layer "In13.Cu")
		(net "M_H_CPU1_SA_DQS_DP<7>")
	)
	(segment
		(start 134.488682 -237.73892)
		(end 134.334758 -238.00435)
		(width 0.09525)
		(layer "In13.Cu")
		(net "M_H_CPU1_SA_DQS_DP<7>")
	)
	(segment
		(start 141.674596 -237.674404)
		(end 141.666214 -237.67923)
		(width 0.09525)
		(layer "In13.Cu")
		(net "M_H_CPU1_SA_DQS_DP<7>")
	)
	(segment
		(start 146.585686 -236.278166)
		(end 146.347688 -236.516164)
		(width 0.09525)
		(layer "In13.Cu")
		(net "M_H_CPU1_SA_DQS_DP<7>")
	)
	(segment
		(start 143.923258 -237.67923)
		(end 143.914876 -237.674404)
		(width 0.09525)
		(layer "In13.Cu")
		(net "M_H_CPU1_SA_DQS_DP<7>")
	)
	(segment
		(start 169.05859 -221.00159)
		(end 168.257474 -220.200474)
		(width 0.16002)
		(layer "In13.Cu")
		(net "M_H_CPU1_SA_DQS_DP<7>")
	)
	(segment
		(start 164.324792 -221.00794)
		(end 164.128958 -220.812106)
		(width 0.16002)
		(layer "In13.Cu")
		(net "M_H_CPU1_SA_DQS_DP<7>")
	)
	(segment
		(start 143.933672 -237.685326)
		(end 143.923258 -237.67923)
		(width 0.09525)
		(layer "In13.Cu")
		(net "M_H_CPU1_SA_DQS_DP<7>")
	)
	(segment
		(start 165.672262 -221.460314)
		(end 165.281102 -221.851474)
		(width 0.16002)
		(layer "In13.Cu")
		(net "M_H_CPU1_SA_DQS_DP<7>")
	)
	(segment
		(start 141.10335 -237.67923)
		(end 141.094968 -237.674404)
		(width 0.09525)
		(layer "In13.Cu")
		(net "M_H_CPU1_SA_DQS_DP<7>")
	)
	(segment
		(start 160.018984 -223.82861)
		(end 159.54248 -223.82861)
		(width 0.16002)
		(layer "In13.Cu")
		(net "M_H_CPU1_SA_DQS_DP<7>")
	)
	(segment
		(start 146.347688 -236.516164)
		(end 146.347688 -236.78388)
		(width 0.09525)
		(layer "In13.Cu")
		(net "M_H_CPU1_SA_DQS_DP<7>")
	)
	(segment
		(start 164.66185 -221.851474)
		(end 164.324792 -221.514416)
		(width 0.16002)
		(layer "In13.Cu")
		(net "M_H_CPU1_SA_DQS_DP<7>")
	)
	(segment
		(start 146.347688 -236.78388)
		(end 145.540984 -237.590584)
		(width 0.09525)
		(layer "In13.Cu")
		(net "M_H_CPU1_SA_DQS_DP<7>")
	)
	(segment
		(start 147.836636 -235.705396)
		(end 147.51812 -235.705396)
		(width 0.09525)
		(layer "In13.Cu")
		(net "M_H_CPU1_SA_DQS_DP<7>")
	)
	(segment
		(start 170.800776 -221.54769)
		(end 170.324018 -221.54769)
		(width 0.16002)
		(layer "In13.Cu")
		(net "M_H_CPU1_SA_DQS_DP<7>")
	)
	(segment
		(start 145.425922 -237.67923)
		(end 145.424652 -237.679992)
		(width 0.09525)
		(layer "In13.Cu")
		(net "M_H_CPU1_SA_DQS_DP<7>")
	)
	(segment
		(start 160.442402 -222.928688)
		(end 160.442402 -223.405192)
		(width 0.16002)
		(layer "In13.Cu")
		(net "M_H_CPU1_SA_DQS_DP<7>")
	)
	(segment
		(start 171.97197 -221.135194)
		(end 171.728384 -220.891608)
		(width 0.16002)
		(layer "In13.Cu")
		(net "M_H_CPU1_SA_DQS_DP<7>")
	)
	(segment
		(start 164.324792 -221.514416)
		(end 164.324792 -221.00794)
		(width 0.16002)
		(layer "In13.Cu")
		(net "M_H_CPU1_SA_DQS_DP<7>")
	)
	(segment
		(start 168.257474 -220.200474)
		(end 167.42537 -220.200474)
		(width 0.16002)
		(layer "In13.Cu")
		(net "M_H_CPU1_SA_DQS_DP<7>")
	)
	(segment
		(start 147.51812 -235.705396)
		(end 146.94535 -236.278166)
		(width 0.09525)
		(layer "In13.Cu")
		(net "M_H_CPU1_SA_DQS_DP<7>")
	)
	(segment
		(start 136.97458 -237.674404)
		(end 136.966198 -237.67923)
		(width 0.09525)
		(layer "In13.Cu")
		(net "M_H_CPU1_SA_DQS_DP<7>")
	)
	(segment
		(start 169.777918 -221.00159)
		(end 169.05859 -221.00159)
		(width 0.16002)
		(layer "In13.Cu")
		(net "M_H_CPU1_SA_DQS_DP<7>")
	)
	(segment
		(start 147.895564 -235.764324)
		(end 147.836636 -235.705396)
		(width 0.09525)
		(layer "In13.Cu")
		(net "M_H_CPU1_SA_DQS_DP<7>")
	)
	(segment
		(start 170.324018 -221.54769)
		(end 169.777918 -221.00159)
		(width 0.16002)
		(layer "In13.Cu")
		(net "M_H_CPU1_SA_DQS_DP<7>")
	)
	(segment
		(start 166.16553 -221.460314)
		(end 165.672262 -221.460314)
		(width 0.16002)
		(layer "In13.Cu")
		(net "M_H_CPU1_SA_DQS_DP<7>")
	)
	(segment
		(start 159.359854 -223.645984)
		(end 159.133794 -223.645984)
		(width 0.16002)
		(layer "In13.Cu")
		(net "M_H_CPU1_SA_DQS_DP<7>")
	)
	(segment
		(start 163.656518 -221.00794)
		(end 163.656518 -221.514416)
		(width 0.16002)
		(layer "In13.Cu")
		(net "M_H_CPU1_SA_DQS_DP<7>")
	)
	(segment
		(start 159.133794 -223.645984)
		(end 156.355034 -226.424744)
		(width 0.16002)
		(layer "In13.Cu")
		(net "M_H_CPU1_SA_DQS_DP<7>")
	)
	(segment
		(start 145.420588 -237.682278)
		(end 145.41119 -237.687866)
		(width 0.09525)
		(layer "In13.Cu")
		(net "M_H_CPU1_SA_DQS_DP<7>")
	)
	(segment
		(start 160.928304 -221.851474)
		(end 160.259776 -222.520002)
		(width 0.16002)
		(layer "In13.Cu")
		(net "M_H_CPU1_SA_DQS_DP<7>")
	)
	(segment
		(start 160.442402 -223.405192)
		(end 160.018984 -223.82861)
		(width 0.16002)
		(layer "In13.Cu")
		(net "M_H_CPU1_SA_DQS_DP<7>")
	)
	(segment
		(start 137.914634 -237.674404)
		(end 137.906252 -237.67923)
		(width 0.09525)
		(layer "In13.Cu")
		(net "M_H_CPU1_SA_DQS_DP<7>")
	)
	(segment
		(start 145.424652 -237.679992)
		(end 145.420588 -237.682278)
		(width 0.09525)
		(layer "In13.Cu")
		(net "M_H_CPU1_SA_DQS_DP<7>")
	)
	(segment
		(start 146.94535 -236.278166)
		(end 146.585686 -236.278166)
		(width 0.09525)
		(layer "In13.Cu")
		(net "M_H_CPU1_SA_DQS_DP<7>")
	)
	(segment
		(start 149.370034 -235.764324)
		(end 147.919186 -235.764324)
		(width 0.16002)
		(layer "In13.Cu")
		(net "M_H_CPU1_SA_DQS_DP<7>")
	)
	(segment
		(start 147.919186 -235.764324)
		(end 147.895564 -235.764324)
		(width 0.09525)
		(layer "In13.Cu")
		(net "M_H_CPU1_SA_DQS_DP<7>")
	)
	(segment
		(start 163.31946 -221.851474)
		(end 160.928304 -221.851474)
		(width 0.16002)
		(layer "In13.Cu")
		(net "M_H_CPU1_SA_DQS_DP<7>")
	)
	(segment
		(start 135.46328 -237.67923)
		(end 135.454898 -237.674404)
		(width 0.09525)
		(layer "In13.Cu")
		(net "M_H_CPU1_SA_DQS_DP<7>")
	)
	(segment
		(start 156.355034 -226.424744)
		(end 156.355034 -228.779324)
		(width 0.16002)
		(layer "In13.Cu")
		(net "M_H_CPU1_SA_DQS_DP<7>")
	)
	(segment
		(start 134.58952 -237.71225)
		(end 134.488682 -237.73892)
		(width 0.09525)
		(layer "In13.Cu")
		(net "M_H_CPU1_SA_DQS_DP<7>")
	)
	(segment
		(start 163.656518 -221.514416)
		(end 163.31946 -221.851474)
		(width 0.16002)
		(layer "In13.Cu")
		(net "M_H_CPU1_SA_DQS_DP<7>")
	)
	(segment
		(start 160.259776 -222.520002)
		(end 160.259776 -222.746062)
		(width 0.16002)
		(layer "In13.Cu")
		(net "M_H_CPU1_SA_DQS_DP<7>")
	)
	(segment
		(start 163.852352 -220.812106)
		(end 163.656518 -221.00794)
		(width 0.16002)
		(layer "In13.Cu")
		(net "M_H_CPU1_SA_DQS_DP<7>")
	)
	(segment
		(start 167.42537 -220.200474)
		(end 166.16553 -221.460314)
		(width 0.16002)
		(layer "In13.Cu")
		(net "M_H_CPU1_SA_DQS_DP<7>")
	)
	(segment
		(start 160.259776 -222.746062)
		(end 160.442402 -222.928688)
		(width 0.16002)
		(layer "In13.Cu")
		(net "M_H_CPU1_SA_DQS_DP<7>")
	)
	(arc
		(start 136.394952 -237.674404)
		(mid 136.20992 -237.62849)
		(end 136.026144 -237.67923)
		(width 0.09525)
		(layer "In13.Cu")
		(net "M_H_CPU1_SA_DQS_DP<7>")
	)
	(arc
		(start 145.540984 -237.590584)
		(mid 145.486336 -237.638649)
		(end 145.425922 -237.67923)
		(width 0.09525)
		(layer "In13.Cu")
		(net "M_H_CPU1_SA_DQS_DP<7>")
	)
	(arc
		(start 140.72616 -237.67923)
		(mid 140.444728 -237.754985)
		(end 140.163296 -237.67923)
		(width 0.09525)
		(layer "In13.Cu")
		(net "M_H_CPU1_SA_DQS_DP<7>")
	)
	(arc
		(start 139.223242 -237.67923)
		(mid 139.034774 -237.628553)
		(end 138.846306 -237.67923)
		(width 0.09525)
		(layer "In13.Cu")
		(net "M_H_CPU1_SA_DQS_DP<7>")
	)
	(arc
		(start 139.786106 -237.67923)
		(mid 139.504674 -237.754985)
		(end 139.223242 -237.67923)
		(width 0.09525)
		(layer "In13.Cu")
		(net "M_H_CPU1_SA_DQS_DP<7>")
	)
	(arc
		(start 135.454898 -237.674404)
		(mid 135.269866 -237.62849)
		(end 135.08609 -237.67923)
		(width 0.09525)
		(layer "In13.Cu")
		(net "M_H_CPU1_SA_DQS_DP<7>")
	)
	(arc
		(start 142.043404 -237.67923)
		(mid 141.859629 -237.628458)
		(end 141.674596 -237.674404)
		(width 0.09525)
		(layer "In13.Cu")
		(net "M_H_CPU1_SA_DQS_DP<7>")
	)
	(arc
		(start 143.914876 -237.674404)
		(mid 143.729844 -237.62849)
		(end 143.546068 -237.67923)
		(width 0.09525)
		(layer "In13.Cu")
		(net "M_H_CPU1_SA_DQS_DP<7>")
	)
	(arc
		(start 144.485868 -237.67923)
		(mid 144.210579 -237.754951)
		(end 143.933672 -237.685326)
		(width 0.09525)
		(layer "In13.Cu")
		(net "M_H_CPU1_SA_DQS_DP<7>")
	)
	(arc
		(start 136.966198 -237.67923)
		(mid 136.684766 -237.754985)
		(end 136.403334 -237.67923)
		(width 0.09525)
		(layer "In13.Cu")
		(net "M_H_CPU1_SA_DQS_DP<7>")
	)
	(arc
		(start 141.666214 -237.67923)
		(mid 141.384782 -237.754985)
		(end 141.10335 -237.67923)
		(width 0.09525)
		(layer "In13.Cu")
		(net "M_H_CPU1_SA_DQS_DP<7>")
	)
	(arc
		(start 138.283442 -237.67923)
		(mid 138.099667 -237.628458)
		(end 137.914634 -237.674404)
		(width 0.09525)
		(layer "In13.Cu")
		(net "M_H_CPU1_SA_DQS_DP<7>")
	)
	(arc
		(start 143.546068 -237.67923)
		(mid 143.264636 -237.754985)
		(end 142.983204 -237.67923)
		(width 0.09525)
		(layer "In13.Cu")
		(net "M_H_CPU1_SA_DQS_DP<7>")
	)
	(arc
		(start 137.906252 -237.67923)
		(mid 137.62482 -237.754985)
		(end 137.343388 -237.67923)
		(width 0.09525)
		(layer "In13.Cu")
		(net "M_H_CPU1_SA_DQS_DP<7>")
	)
	(arc
		(start 144.863058 -237.67923)
		(mid 144.679283 -237.628458)
		(end 144.49425 -237.674404)
		(width 0.09525)
		(layer "In13.Cu")
		(net "M_H_CPU1_SA_DQS_DP<7>")
	)
	(arc
		(start 142.983204 -237.67923)
		(mid 142.794736 -237.628553)
		(end 142.606268 -237.67923)
		(width 0.09525)
		(layer "In13.Cu")
		(net "M_H_CPU1_SA_DQS_DP<7>")
	)
	(arc
		(start 137.343388 -237.67923)
		(mid 137.159613 -237.628458)
		(end 136.97458 -237.674404)
		(width 0.09525)
		(layer "In13.Cu")
		(net "M_H_CPU1_SA_DQS_DP<7>")
	)
	(arc
		(start 136.026144 -237.67923)
		(mid 135.744712 -237.754985)
		(end 135.46328 -237.67923)
		(width 0.09525)
		(layer "In13.Cu")
		(net "M_H_CPU1_SA_DQS_DP<7>")
	)
	(arc
		(start 140.154914 -237.674404)
		(mid 139.969882 -237.62849)
		(end 139.786106 -237.67923)
		(width 0.09525)
		(layer "In13.Cu")
		(net "M_H_CPU1_SA_DQS_DP<7>")
	)
	(arc
		(start 134.60984 -237.720124)
		(mid 134.599641 -237.716287)
		(end 134.58952 -237.71225)
		(width 0.09525)
		(layer "In13.Cu")
		(net "M_H_CPU1_SA_DQS_DP<7>")
	)
	(arc
		(start 138.846306 -237.67923)
		(mid 138.564874 -237.754985)
		(end 138.283442 -237.67923)
		(width 0.09525)
		(layer "In13.Cu")
		(net "M_H_CPU1_SA_DQS_DP<7>")
	)
	(arc
		(start 142.606268 -237.67923)
		(mid 142.324836 -237.754985)
		(end 142.043404 -237.67923)
		(width 0.09525)
		(layer "In13.Cu")
		(net "M_H_CPU1_SA_DQS_DP<7>")
	)
	(arc
		(start 135.08609 -237.67923)
		(mid 134.852546 -237.752936)
		(end 134.60984 -237.720124)
		(width 0.09525)
		(layer "In13.Cu")
		(net "M_H_CPU1_SA_DQS_DP<7>")
	)
	(arc
		(start 141.094968 -237.674404)
		(mid 140.909936 -237.62849)
		(end 140.72616 -237.67923)
		(width 0.09525)
		(layer "In13.Cu")
		(net "M_H_CPU1_SA_DQS_DP<7>")
	)
	(arc
		(start 145.41119 -237.687866)
		(mid 145.135985 -237.75513)
		(end 144.863058 -237.67923)
		(width 0.09525)
		(layer "In13.Cu")
		(net "M_H_CPU1_SA_DQS_DP<7>")
	)
	(segment
		(start 133.867906 -233.410252)
		(end 134.334758 -233.144314)
		(width 0.12954)
		(layer "F.Cu")
		(net "M_H_CPU1_SA_DQS_DP<6>")
	)
	(segment
		(start 140.163296 -232.819194)
		(end 140.154914 -232.814368)
		(width 0.09525)
		(layer "In13.Cu")
		(net "M_H_CPU1_SA_DQS_DP<6>")
	)
	(segment
		(start 162.06216 -211.601558)
		(end 161.90214 -211.441538)
		(width 0.16002)
		(layer "In13.Cu")
		(net "M_H_CPU1_SA_DQS_DP<6>")
	)
	(segment
		(start 147.801584 -228.853238)
		(end 147.164806 -229.490016)
		(width 0.09525)
		(layer "In13.Cu")
		(net "M_H_CPU1_SA_DQS_DP<6>")
	)
	(segment
		(start 141.674596 -232.814368)
		(end 141.666214 -232.819194)
		(width 0.09525)
		(layer "In13.Cu")
		(net "M_H_CPU1_SA_DQS_DP<6>")
	)
	(segment
		(start 146.828764 -229.490016)
		(end 146.286474 -230.032306)
		(width 0.09525)
		(layer "In13.Cu")
		(net "M_H_CPU1_SA_DQS_DP<6>")
	)
	(segment
		(start 160.560766 -212.724746)
		(end 150.817834 -222.467678)
		(width 0.16002)
		(layer "In13.Cu")
		(net "M_H_CPU1_SA_DQS_DP<6>")
	)
	(segment
		(start 161.55416 -211.441538)
		(end 161.39414 -211.601558)
		(width 0.16002)
		(layer "In13.Cu")
		(net "M_H_CPU1_SA_DQS_DP<6>")
	)
	(segment
		(start 137.914634 -232.814368)
		(end 137.906252 -232.819194)
		(width 0.09525)
		(layer "In13.Cu")
		(net "M_H_CPU1_SA_DQS_DP<6>")
	)
	(segment
		(start 165.73881 -212.11032)
		(end 165.124384 -212.724746)
		(width 0.16002)
		(layer "In13.Cu")
		(net "M_H_CPU1_SA_DQS_DP<6>")
	)
	(segment
		(start 168.39692 -211.45754)
		(end 168.28008 -211.3407)
		(width 0.16002)
		(layer "In13.Cu")
		(net "M_H_CPU1_SA_DQS_DP<6>")
	)
	(segment
		(start 166.16553 -212.11032)
		(end 165.73881 -212.11032)
		(width 0.16002)
		(layer "In13.Cu")
		(net "M_H_CPU1_SA_DQS_DP<6>")
	)
	(segment
		(start 150.817834 -222.467678)
		(end 150.817834 -225.920808)
		(width 0.16002)
		(layer "In13.Cu")
		(net "M_H_CPU1_SA_DQS_DP<6>")
	)
	(segment
		(start 168.99382 -211.3407)
		(end 168.87698 -211.45754)
		(width 0.16002)
		(layer "In13.Cu")
		(net "M_H_CPU1_SA_DQS_DP<6>")
	)
	(segment
		(start 163.3347 -212.387688)
		(end 162.997642 -212.724746)
		(width 0.16002)
		(layer "In13.Cu")
		(net "M_H_CPU1_SA_DQS_DP<6>")
	)
	(segment
		(start 171.97197 -211.7852)
		(end 171.705778 -211.519008)
		(width 0.16002)
		(layer "In13.Cu")
		(net "M_H_CPU1_SA_DQS_DP<6>")
	)
	(segment
		(start 161.057082 -212.724746)
		(end 160.560766 -212.724746)
		(width 0.16002)
		(layer "In13.Cu")
		(net "M_H_CPU1_SA_DQS_DP<6>")
	)
	(segment
		(start 146.286474 -230.032306)
		(end 146.286474 -230.66502)
		(width 0.09525)
		(layer "In13.Cu")
		(net "M_H_CPU1_SA_DQS_DP<6>")
	)
	(segment
		(start 164.00272 -211.601558)
		(end 163.8427 -211.441538)
		(width 0.16002)
		(layer "In13.Cu")
		(net "M_H_CPU1_SA_DQS_DP<6>")
	)
	(segment
		(start 147.885404 -228.853238)
		(end 147.801584 -228.853238)
		(width 0.09525)
		(layer "In13.Cu")
		(net "M_H_CPU1_SA_DQS_DP<6>")
	)
	(segment
		(start 161.39414 -212.387688)
		(end 161.057082 -212.724746)
		(width 0.16002)
		(layer "In13.Cu")
		(net "M_H_CPU1_SA_DQS_DP<6>")
	)
	(segment
		(start 162.399218 -212.724746)
		(end 162.06216 -212.387688)
		(width 0.16002)
		(layer "In13.Cu")
		(net "M_H_CPU1_SA_DQS_DP<6>")
	)
	(segment
		(start 163.8427 -211.441538)
		(end 163.49472 -211.441538)
		(width 0.16002)
		(layer "In13.Cu")
		(net "M_H_CPU1_SA_DQS_DP<6>")
	)
	(segment
		(start 166.93515 -211.3407)
		(end 166.16553 -212.11032)
		(width 0.16002)
		(layer "In13.Cu")
		(net "M_H_CPU1_SA_DQS_DP<6>")
	)
	(segment
		(start 168.87698 -211.45754)
		(end 168.39692 -211.45754)
		(width 0.16002)
		(layer "In13.Cu")
		(net "M_H_CPU1_SA_DQS_DP<6>")
	)
	(segment
		(start 147.902168 -228.836474)
		(end 147.885404 -228.853238)
		(width 0.09525)
		(layer "In13.Cu")
		(net "M_H_CPU1_SA_DQS_DP<6>")
	)
	(segment
		(start 134.488682 -232.878884)
		(end 134.334758 -233.144314)
		(width 0.09525)
		(layer "In13.Cu")
		(net "M_H_CPU1_SA_DQS_DP<6>")
	)
	(segment
		(start 162.06216 -212.387688)
		(end 162.06216 -211.601558)
		(width 0.16002)
		(layer "In13.Cu")
		(net "M_H_CPU1_SA_DQS_DP<6>")
	)
	(segment
		(start 171.705778 -211.519008)
		(end 170.044618 -211.519008)
		(width 0.16002)
		(layer "In13.Cu")
		(net "M_H_CPU1_SA_DQS_DP<6>")
	)
	(segment
		(start 147.164806 -229.490016)
		(end 146.828764 -229.490016)
		(width 0.09525)
		(layer "In13.Cu")
		(net "M_H_CPU1_SA_DQS_DP<6>")
	)
	(segment
		(start 165.124384 -212.724746)
		(end 164.339778 -212.724746)
		(width 0.16002)
		(layer "In13.Cu")
		(net "M_H_CPU1_SA_DQS_DP<6>")
	)
	(segment
		(start 161.90214 -211.441538)
		(end 161.55416 -211.441538)
		(width 0.16002)
		(layer "In13.Cu")
		(net "M_H_CPU1_SA_DQS_DP<6>")
	)
	(segment
		(start 164.00272 -212.387688)
		(end 164.00272 -211.601558)
		(width 0.16002)
		(layer "In13.Cu")
		(net "M_H_CPU1_SA_DQS_DP<6>")
	)
	(segment
		(start 164.339778 -212.724746)
		(end 164.00272 -212.387688)
		(width 0.16002)
		(layer "In13.Cu")
		(net "M_H_CPU1_SA_DQS_DP<6>")
	)
	(segment
		(start 150.817834 -225.920808)
		(end 147.902168 -228.836474)
		(width 0.16002)
		(layer "In13.Cu")
		(net "M_H_CPU1_SA_DQS_DP<6>")
	)
	(segment
		(start 168.28008 -211.3407)
		(end 166.93515 -211.3407)
		(width 0.16002)
		(layer "In13.Cu")
		(net "M_H_CPU1_SA_DQS_DP<6>")
	)
	(segment
		(start 169.86631 -211.3407)
		(end 168.99382 -211.3407)
		(width 0.16002)
		(layer "In13.Cu")
		(net "M_H_CPU1_SA_DQS_DP<6>")
	)
	(segment
		(start 162.997642 -212.724746)
		(end 162.399218 -212.724746)
		(width 0.16002)
		(layer "In13.Cu")
		(net "M_H_CPU1_SA_DQS_DP<6>")
	)
	(segment
		(start 135.46328 -232.819194)
		(end 135.454898 -232.814368)
		(width 0.09525)
		(layer "In13.Cu")
		(net "M_H_CPU1_SA_DQS_DP<6>")
	)
	(segment
		(start 163.3347 -211.601558)
		(end 163.3347 -212.387688)
		(width 0.16002)
		(layer "In13.Cu")
		(net "M_H_CPU1_SA_DQS_DP<6>")
	)
	(segment
		(start 163.49472 -211.441538)
		(end 163.3347 -211.601558)
		(width 0.16002)
		(layer "In13.Cu")
		(net "M_H_CPU1_SA_DQS_DP<6>")
	)
	(segment
		(start 136.403334 -232.819194)
		(end 136.394952 -232.814368)
		(width 0.09525)
		(layer "In13.Cu")
		(net "M_H_CPU1_SA_DQS_DP<6>")
	)
	(segment
		(start 146.286474 -230.66502)
		(end 144.183608 -232.767886)
		(width 0.09525)
		(layer "In13.Cu")
		(net "M_H_CPU1_SA_DQS_DP<6>")
	)
	(segment
		(start 144.183608 -232.767886)
		(end 143.73479 -232.767886)
		(width 0.09525)
		(layer "In13.Cu")
		(net "M_H_CPU1_SA_DQS_DP<6>")
	)
	(segment
		(start 136.97458 -232.814368)
		(end 136.966198 -232.819194)
		(width 0.09525)
		(layer "In13.Cu")
		(net "M_H_CPU1_SA_DQS_DP<6>")
	)
	(segment
		(start 141.10335 -232.819194)
		(end 141.094968 -232.814368)
		(width 0.09525)
		(layer "In13.Cu")
		(net "M_H_CPU1_SA_DQS_DP<6>")
	)
	(segment
		(start 161.39414 -211.601558)
		(end 161.39414 -212.387688)
		(width 0.16002)
		(layer "In13.Cu")
		(net "M_H_CPU1_SA_DQS_DP<6>")
	)
	(segment
		(start 134.58952 -232.852214)
		(end 134.488682 -232.878884)
		(width 0.09525)
		(layer "In13.Cu")
		(net "M_H_CPU1_SA_DQS_DP<6>")
	)
	(segment
		(start 170.044618 -211.519008)
		(end 169.86631 -211.3407)
		(width 0.16002)
		(layer "In13.Cu")
		(net "M_H_CPU1_SA_DQS_DP<6>")
	)
	(arc
		(start 140.72616 -232.819194)
		(mid 140.444728 -232.894949)
		(end 140.163296 -232.819194)
		(width 0.09525)
		(layer "In13.Cu")
		(net "M_H_CPU1_SA_DQS_DP<6>")
	)
	(arc
		(start 140.154914 -232.814368)
		(mid 139.969882 -232.768454)
		(end 139.786106 -232.819194)
		(width 0.09525)
		(layer "In13.Cu")
		(net "M_H_CPU1_SA_DQS_DP<6>")
	)
	(arc
		(start 138.283442 -232.819194)
		(mid 138.099667 -232.768422)
		(end 137.914634 -232.814368)
		(width 0.09525)
		(layer "In13.Cu")
		(net "M_H_CPU1_SA_DQS_DP<6>")
	)
	(arc
		(start 136.026144 -232.819194)
		(mid 135.744712 -232.894949)
		(end 135.46328 -232.819194)
		(width 0.09525)
		(layer "In13.Cu")
		(net "M_H_CPU1_SA_DQS_DP<6>")
	)
	(arc
		(start 143.546068 -232.819194)
		(mid 143.264636 -232.894949)
		(end 142.983204 -232.819194)
		(width 0.09525)
		(layer "In13.Cu")
		(net "M_H_CPU1_SA_DQS_DP<6>")
	)
	(arc
		(start 141.666214 -232.819194)
		(mid 141.384782 -232.894949)
		(end 141.10335 -232.819194)
		(width 0.09525)
		(layer "In13.Cu")
		(net "M_H_CPU1_SA_DQS_DP<6>")
	)
	(arc
		(start 139.223242 -232.819194)
		(mid 139.034774 -232.768517)
		(end 138.846306 -232.819194)
		(width 0.09525)
		(layer "In13.Cu")
		(net "M_H_CPU1_SA_DQS_DP<6>")
	)
	(arc
		(start 136.966198 -232.819194)
		(mid 136.684766 -232.894949)
		(end 136.403334 -232.819194)
		(width 0.09525)
		(layer "In13.Cu")
		(net "M_H_CPU1_SA_DQS_DP<6>")
	)
	(arc
		(start 142.043404 -232.819194)
		(mid 141.859629 -232.768422)
		(end 141.674596 -232.814368)
		(width 0.09525)
		(layer "In13.Cu")
		(net "M_H_CPU1_SA_DQS_DP<6>")
	)
	(arc
		(start 139.786106 -232.819194)
		(mid 139.504674 -232.894949)
		(end 139.223242 -232.819194)
		(width 0.09525)
		(layer "In13.Cu")
		(net "M_H_CPU1_SA_DQS_DP<6>")
	)
	(arc
		(start 142.606268 -232.819194)
		(mid 142.324836 -232.894949)
		(end 142.043404 -232.819194)
		(width 0.09525)
		(layer "In13.Cu")
		(net "M_H_CPU1_SA_DQS_DP<6>")
	)
	(arc
		(start 137.343388 -232.819194)
		(mid 137.159613 -232.768422)
		(end 136.97458 -232.814368)
		(width 0.09525)
		(layer "In13.Cu")
		(net "M_H_CPU1_SA_DQS_DP<6>")
	)
	(arc
		(start 138.846306 -232.819194)
		(mid 138.564874 -232.894949)
		(end 138.283442 -232.819194)
		(width 0.09525)
		(layer "In13.Cu")
		(net "M_H_CPU1_SA_DQS_DP<6>")
	)
	(arc
		(start 135.08609 -232.819194)
		(mid 134.852546 -232.8929)
		(end 134.60984 -232.860088)
		(width 0.09525)
		(layer "In13.Cu")
		(net "M_H_CPU1_SA_DQS_DP<6>")
	)
	(arc
		(start 135.454898 -232.814368)
		(mid 135.269866 -232.768454)
		(end 135.08609 -232.819194)
		(width 0.09525)
		(layer "In13.Cu")
		(net "M_H_CPU1_SA_DQS_DP<6>")
	)
	(arc
		(start 141.094968 -232.814368)
		(mid 140.909936 -232.768454)
		(end 140.72616 -232.819194)
		(width 0.09525)
		(layer "In13.Cu")
		(net "M_H_CPU1_SA_DQS_DP<6>")
	)
	(arc
		(start 134.60984 -232.860088)
		(mid 134.599641 -232.856251)
		(end 134.58952 -232.852214)
		(width 0.09525)
		(layer "In13.Cu")
		(net "M_H_CPU1_SA_DQS_DP<6>")
	)
	(arc
		(start 143.73479 -232.767886)
		(mid 143.637044 -232.781081)
		(end 143.546068 -232.819194)
		(width 0.09525)
		(layer "In13.Cu")
		(net "M_H_CPU1_SA_DQS_DP<6>")
	)
	(arc
		(start 137.906252 -232.819194)
		(mid 137.62482 -232.894949)
		(end 137.343388 -232.819194)
		(width 0.09525)
		(layer "In13.Cu")
		(net "M_H_CPU1_SA_DQS_DP<6>")
	)
	(arc
		(start 142.983204 -232.819194)
		(mid 142.794736 -232.768517)
		(end 142.606268 -232.819194)
		(width 0.09525)
		(layer "In13.Cu")
		(net "M_H_CPU1_SA_DQS_DP<6>")
	)
	(arc
		(start 136.394952 -232.814368)
		(mid 136.20992 -232.768454)
		(end 136.026144 -232.819194)
		(width 0.09525)
		(layer "In13.Cu")
		(net "M_H_CPU1_SA_DQS_DP<6>")
	)
	(segment
		(start 133.867906 -228.55047)
		(end 134.334758 -228.284532)
		(width 0.12954)
		(layer "F.Cu")
		(net "M_H_CPU1_SA_DQS_DP<5>")
	)
	(segment
		(start 158.84271 -204.510132)
		(end 158.84271 -204.986636)
		(width 0.16002)
		(layer "In13.Cu")
		(net "M_H_CPU1_SA_DQS_DP<5>")
	)
	(segment
		(start 155.98648 -206.919322)
		(end 155.98648 -207.145382)
		(width 0.16002)
		(layer "In13.Cu")
		(net "M_H_CPU1_SA_DQS_DP<5>")
	)
	(segment
		(start 154.61361 -208.518252)
		(end 154.7241 -208.628742)
		(width 0.16002)
		(layer "In13.Cu")
		(net "M_H_CPU1_SA_DQS_DP<5>")
	)
	(segment
		(start 157.606238 -205.299564)
		(end 157.35935 -205.546452)
		(width 0.16002)
		(layer "In13.Cu")
		(net "M_H_CPU1_SA_DQS_DP<5>")
	)
	(segment
		(start 154.7241 -208.628742)
		(end 154.7241 -209.105246)
		(width 0.16002)
		(layer "In13.Cu")
		(net "M_H_CPU1_SA_DQS_DP<5>")
	)
	(segment
		(start 168.19245 -201.990706)
		(end 168.07561 -202.107546)
		(width 0.16002)
		(layer "In13.Cu")
		(net "M_H_CPU1_SA_DQS_DP<5>")
	)
	(segment
		(start 161.06902 -202.760326)
		(end 159.792162 -204.037184)
		(width 0.16002)
		(layer "In13.Cu")
		(net "M_H_CPU1_SA_DQS_DP<5>")
	)
	(segment
		(start 169.86631 -201.990706)
		(end 169.38625 -201.990706)
		(width 0.16002)
		(layer "In13.Cu")
		(net "M_H_CPU1_SA_DQS_DP<5>")
	)
	(segment
		(start 144.016222 -223.909382)
		(end 143.98371 -223.928178)
		(width 0.09525)
		(layer "In13.Cu")
		(net "M_H_CPU1_SA_DQS_DP<5>")
	)
	(segment
		(start 171.708572 -202.171808)
		(end 170.047412 -202.171808)
		(width 0.16002)
		(layer "In13.Cu")
		(net "M_H_CPU1_SA_DQS_DP<5>")
	)
	(segment
		(start 159.205168 -203.926694)
		(end 158.979108 -203.926694)
		(width 0.16002)
		(layer "In13.Cu")
		(net "M_H_CPU1_SA_DQS_DP<5>")
	)
	(segment
		(start 169.26941 -202.107546)
		(end 168.78935 -202.107546)
		(width 0.16002)
		(layer "In13.Cu")
		(net "M_H_CPU1_SA_DQS_DP<5>")
	)
	(segment
		(start 143.076168 -225.529394)
		(end 143.043656 -225.54819)
		(width 0.09525)
		(layer "In13.Cu")
		(net "M_H_CPU1_SA_DQS_DP<5>")
	)
	(segment
		(start 167.59555 -202.107546)
		(end 167.47871 -201.990706)
		(width 0.16002)
		(layer "In13.Cu")
		(net "M_H_CPU1_SA_DQS_DP<5>")
	)
	(segment
		(start 152.340818 -210.791044)
		(end 152.114758 -210.791044)
		(width 0.16002)
		(layer "In13.Cu")
		(net "M_H_CPU1_SA_DQS_DP<5>")
	)
	(segment
		(start 158.84271 -204.986636)
		(end 158.419292 -205.410054)
		(width 0.16002)
		(layer "In13.Cu")
		(net "M_H_CPU1_SA_DQS_DP<5>")
	)
	(segment
		(start 167.47871 -201.990706)
		(end 166.93515 -201.990706)
		(width 0.16002)
		(layer "In13.Cu")
		(net "M_H_CPU1_SA_DQS_DP<5>")
	)
	(segment
		(start 145.278348 -221.35719)
		(end 145.280634 -221.359476)
		(width 0.09525)
		(layer "In13.Cu")
		(net "M_H_CPU1_SA_DQS_DP<5>")
	)
	(segment
		(start 156.569918 -206.782924)
		(end 156.459428 -206.672434)
		(width 0.16002)
		(layer "In13.Cu")
		(net "M_H_CPU1_SA_DQS_DP<5>")
	)
	(segment
		(start 158.979108 -203.926694)
		(end 158.73222 -204.173582)
		(width 0.16002)
		(layer "In13.Cu")
		(net "M_H_CPU1_SA_DQS_DP<5>")
	)
	(segment
		(start 151.97836 -211.374482)
		(end 151.97836 -211.850986)
		(width 0.16002)
		(layer "In13.Cu")
		(net "M_H_CPU1_SA_DQS_DP<5>")
	)
	(segment
		(start 158.419292 -205.410054)
		(end 157.942788 -205.410054)
		(width 0.16002)
		(layer "In13.Cu")
		(net "M_H_CPU1_SA_DQS_DP<5>")
	)
	(segment
		(start 145.26768 -221.667832)
		(end 145.26768 -221.977458)
		(width 0.09525)
		(layer "In13.Cu")
		(net "M_H_CPU1_SA_DQS_DP<5>")
	)
	(segment
		(start 153.35123 -210.001612)
		(end 153.35123 -210.478116)
		(width 0.16002)
		(layer "In13.Cu")
		(net "M_H_CPU1_SA_DQS_DP<5>")
	)
	(segment
		(start 137.914634 -227.954586)
		(end 137.906252 -227.959412)
		(width 0.09525)
		(layer "In13.Cu")
		(net "M_H_CPU1_SA_DQS_DP<5>")
	)
	(segment
		(start 142.64132 -226.318826)
		(end 142.606268 -226.3394)
		(width 0.09525)
		(layer "In13.Cu")
		(net "M_H_CPU1_SA_DQS_DP<5>")
	)
	(segment
		(start 145.221706 -221.442026)
		(end 145.221706 -221.621858)
		(width 0.09525)
		(layer "In13.Cu")
		(net "M_H_CPU1_SA_DQS_DP<5>")
	)
	(segment
		(start 144.518126 -223.080834)
		(end 144.486122 -223.099376)
		(width 0.09525)
		(layer "In13.Cu")
		(net "M_H_CPU1_SA_DQS_DP<5>")
	)
	(segment
		(start 157.942788 -205.410054)
		(end 157.832298 -205.299564)
		(width 0.16002)
		(layer "In13.Cu")
		(net "M_H_CPU1_SA_DQS_DP<5>")
	)
	(segment
		(start 156.09697 -207.255872)
		(end 156.09697 -207.732376)
		(width 0.16002)
		(layer "In13.Cu")
		(net "M_H_CPU1_SA_DQS_DP<5>")
	)
	(segment
		(start 145.280634 -221.359476)
		(end 145.280634 -221.383098)
		(width 0.09525)
		(layer "In13.Cu")
		(net "M_H_CPU1_SA_DQS_DP<5>")
	)
	(segment
		(start 153.35123 -210.478116)
		(end 152.927812 -210.901534)
		(width 0.16002)
		(layer "In13.Cu")
		(net "M_H_CPU1_SA_DQS_DP<5>")
	)
	(segment
		(start 135.46328 -227.959412)
		(end 135.454898 -227.954586)
		(width 0.09525)
		(layer "In13.Cu")
		(net "M_H_CPU1_SA_DQS_DP<5>")
	)
	(segment
		(start 151.86787 -211.263992)
		(end 151.97836 -211.374482)
		(width 0.16002)
		(layer "In13.Cu")
		(net "M_H_CPU1_SA_DQS_DP<5>")
	)
	(segment
		(start 152.114758 -210.791044)
		(end 151.86787 -211.037932)
		(width 0.16002)
		(layer "In13.Cu")
		(net "M_H_CPU1_SA_DQS_DP<5>")
	)
	(segment
		(start 154.61361 -208.292192)
		(end 154.61361 -208.518252)
		(width 0.16002)
		(layer "In13.Cu")
		(net "M_H_CPU1_SA_DQS_DP<5>")
	)
	(segment
		(start 142.136114 -227.149406)
		(end 142.104618 -227.167694)
		(width 0.09525)
		(layer "In13.Cu")
		(net "M_H_CPU1_SA_DQS_DP<5>")
	)
	(segment
		(start 145.26768 -221.977458)
		(end 144.955768 -222.28937)
		(width 0.09525)
		(layer "In13.Cu")
		(net "M_H_CPU1_SA_DQS_DP<5>")
	)
	(segment
		(start 155.98648 -207.145382)
		(end 156.09697 -207.255872)
		(width 0.16002)
		(layer "In13.Cu")
		(net "M_H_CPU1_SA_DQS_DP<5>")
	)
	(segment
		(start 144.486122 -223.099376)
		(end 144.454626 -223.117664)
		(width 0.09525)
		(layer "In13.Cu")
		(net "M_H_CPU1_SA_DQS_DP<5>")
	)
	(segment
		(start 145.280634 -221.383098)
		(end 145.221706 -221.442026)
		(width 0.09525)
		(layer "In13.Cu")
		(net "M_H_CPU1_SA_DQS_DP<5>")
	)
	(segment
		(start 144.054322 -223.887284)
		(end 144.016222 -223.909382)
		(width 0.09525)
		(layer "In13.Cu")
		(net "M_H_CPU1_SA_DQS_DP<5>")
	)
	(segment
		(start 153.713688 -209.418174)
		(end 153.487628 -209.418174)
		(width 0.16002)
		(layer "In13.Cu")
		(net "M_H_CPU1_SA_DQS_DP<5>")
	)
	(segment
		(start 155.197048 -208.155794)
		(end 155.086558 -208.045304)
		(width 0.16002)
		(layer "In13.Cu")
		(net "M_H_CPU1_SA_DQS_DP<5>")
	)
	(segment
		(start 157.35935 -205.546452)
		(end 157.35935 -205.772512)
		(width 0.16002)
		(layer "In13.Cu")
		(net "M_H_CPU1_SA_DQS_DP<5>")
	)
	(segment
		(start 159.792162 -204.037184)
		(end 159.315658 -204.037184)
		(width 0.16002)
		(layer "In13.Cu")
		(net "M_H_CPU1_SA_DQS_DP<5>")
	)
	(segment
		(start 166.93515 -201.990706)
		(end 166.16553 -202.760326)
		(width 0.16002)
		(layer "In13.Cu")
		(net "M_H_CPU1_SA_DQS_DP<5>")
	)
	(segment
		(start 157.832298 -205.299564)
		(end 157.606238 -205.299564)
		(width 0.16002)
		(layer "In13.Cu")
		(net "M_H_CPU1_SA_DQS_DP<5>")
	)
	(segment
		(start 168.78935 -202.107546)
		(end 168.67251 -201.990706)
		(width 0.16002)
		(layer "In13.Cu")
		(net "M_H_CPU1_SA_DQS_DP<5>")
	)
	(segment
		(start 153.24074 -209.891122)
		(end 153.35123 -210.001612)
		(width 0.16002)
		(layer "In13.Cu")
		(net "M_H_CPU1_SA_DQS_DP<5>")
	)
	(segment
		(start 155.673552 -208.155794)
		(end 155.197048 -208.155794)
		(width 0.16002)
		(layer "In13.Cu")
		(net "M_H_CPU1_SA_DQS_DP<5>")
	)
	(segment
		(start 157.046422 -206.782924)
		(end 156.569918 -206.782924)
		(width 0.16002)
		(layer "In13.Cu")
		(net "M_H_CPU1_SA_DQS_DP<5>")
	)
	(segment
		(start 159.315658 -204.037184)
		(end 159.205168 -203.926694)
		(width 0.16002)
		(layer "In13.Cu")
		(net "M_H_CPU1_SA_DQS_DP<5>")
	)
	(segment
		(start 170.047412 -202.171808)
		(end 169.86631 -201.990706)
		(width 0.16002)
		(layer "In13.Cu")
		(net "M_H_CPU1_SA_DQS_DP<5>")
	)
	(segment
		(start 141.10335 -227.959412)
		(end 141.094968 -227.954586)
		(width 0.09525)
		(layer "In13.Cu")
		(net "M_H_CPU1_SA_DQS_DP<5>")
	)
	(segment
		(start 154.860498 -208.045304)
		(end 154.61361 -208.292192)
		(width 0.16002)
		(layer "In13.Cu")
		(net "M_H_CPU1_SA_DQS_DP<5>")
	)
	(segment
		(start 145.221706 -221.621858)
		(end 145.26768 -221.667832)
		(width 0.09525)
		(layer "In13.Cu")
		(net "M_H_CPU1_SA_DQS_DP<5>")
	)
	(segment
		(start 157.46984 -206.359506)
		(end 157.046422 -206.782924)
		(width 0.16002)
		(layer "In13.Cu")
		(net "M_H_CPU1_SA_DQS_DP<5>")
	)
	(segment
		(start 141.704314 -227.937314)
		(end 141.666214 -227.959412)
		(width 0.09525)
		(layer "In13.Cu")
		(net "M_H_CPU1_SA_DQS_DP<5>")
	)
	(segment
		(start 153.824178 -209.528664)
		(end 153.713688 -209.418174)
		(width 0.16002)
		(layer "In13.Cu")
		(net "M_H_CPU1_SA_DQS_DP<5>")
	)
	(segment
		(start 144.955768 -222.28937)
		(end 144.924272 -222.307658)
		(width 0.09525)
		(layer "In13.Cu")
		(net "M_H_CPU1_SA_DQS_DP<5>")
	)
	(segment
		(start 143.546068 -224.719388)
		(end 143.514572 -224.737676)
		(width 0.09525)
		(layer "In13.Cu")
		(net "M_H_CPU1_SA_DQS_DP<5>")
	)
	(segment
		(start 154.300682 -209.528664)
		(end 153.824178 -209.528664)
		(width 0.16002)
		(layer "In13.Cu")
		(net "M_H_CPU1_SA_DQS_DP<5>")
	)
	(segment
		(start 136.403334 -227.959412)
		(end 136.394952 -227.954586)
		(width 0.09525)
		(layer "In13.Cu")
		(net "M_H_CPU1_SA_DQS_DP<5>")
	)
	(segment
		(start 157.35935 -205.772512)
		(end 157.46984 -205.883002)
		(width 0.16002)
		(layer "In13.Cu")
		(net "M_H_CPU1_SA_DQS_DP<5>")
	)
	(segment
		(start 142.174214 -227.127308)
		(end 142.136114 -227.149406)
		(width 0.09525)
		(layer "In13.Cu")
		(net "M_H_CPU1_SA_DQS_DP<5>")
	)
	(segment
		(start 152.451308 -210.901534)
		(end 152.340818 -210.791044)
		(width 0.16002)
		(layer "In13.Cu")
		(net "M_H_CPU1_SA_DQS_DP<5>")
	)
	(segment
		(start 152.927812 -210.901534)
		(end 152.451308 -210.901534)
		(width 0.16002)
		(layer "In13.Cu")
		(net "M_H_CPU1_SA_DQS_DP<5>")
	)
	(segment
		(start 145.278348 -218.550998)
		(end 145.278348 -221.35719)
		(width 0.16002)
		(layer "In13.Cu")
		(net "M_H_CPU1_SA_DQS_DP<5>")
	)
	(segment
		(start 134.488682 -228.019102)
		(end 134.334758 -228.284532)
		(width 0.09525)
		(layer "In13.Cu")
		(net "M_H_CPU1_SA_DQS_DP<5>")
	)
	(segment
		(start 156.09697 -207.732376)
		(end 155.673552 -208.155794)
		(width 0.16002)
		(layer "In13.Cu")
		(net "M_H_CPU1_SA_DQS_DP<5>")
	)
	(segment
		(start 140.163296 -227.959412)
		(end 140.154914 -227.954586)
		(width 0.09525)
		(layer "In13.Cu")
		(net "M_H_CPU1_SA_DQS_DP<5>")
	)
	(segment
		(start 136.97458 -227.954586)
		(end 136.966198 -227.959412)
		(width 0.09525)
		(layer "In13.Cu")
		(net "M_H_CPU1_SA_DQS_DP<5>")
	)
	(segment
		(start 154.7241 -209.105246)
		(end 154.300682 -209.528664)
		(width 0.16002)
		(layer "In13.Cu")
		(net "M_H_CPU1_SA_DQS_DP<5>")
	)
	(segment
		(start 158.73222 -204.173582)
		(end 158.73222 -204.399642)
		(width 0.16002)
		(layer "In13.Cu")
		(net "M_H_CPU1_SA_DQS_DP<5>")
	)
	(segment
		(start 143.584168 -224.69729)
		(end 143.546068 -224.719388)
		(width 0.09525)
		(layer "In13.Cu")
		(net "M_H_CPU1_SA_DQS_DP<5>")
	)
	(segment
		(start 156.459428 -206.672434)
		(end 156.233368 -206.672434)
		(width 0.16002)
		(layer "In13.Cu")
		(net "M_H_CPU1_SA_DQS_DP<5>")
	)
	(segment
		(start 153.487628 -209.418174)
		(end 153.24074 -209.665062)
		(width 0.16002)
		(layer "In13.Cu")
		(net "M_H_CPU1_SA_DQS_DP<5>")
	)
	(segment
		(start 158.73222 -204.399642)
		(end 158.84271 -204.510132)
		(width 0.16002)
		(layer "In13.Cu")
		(net "M_H_CPU1_SA_DQS_DP<5>")
	)
	(segment
		(start 168.07561 -202.107546)
		(end 167.59555 -202.107546)
		(width 0.16002)
		(layer "In13.Cu")
		(net "M_H_CPU1_SA_DQS_DP<5>")
	)
	(segment
		(start 134.58952 -227.992432)
		(end 134.488682 -228.019102)
		(width 0.09525)
		(layer "In13.Cu")
		(net "M_H_CPU1_SA_DQS_DP<5>")
	)
	(segment
		(start 151.86787 -211.037932)
		(end 151.86787 -211.263992)
		(width 0.16002)
		(layer "In13.Cu")
		(net "M_H_CPU1_SA_DQS_DP<5>")
	)
	(segment
		(start 171.97197 -202.435206)
		(end 171.708572 -202.171808)
		(width 0.16002)
		(layer "In13.Cu")
		(net "M_H_CPU1_SA_DQS_DP<5>")
	)
	(segment
		(start 151.97836 -211.850986)
		(end 145.278348 -218.550998)
		(width 0.16002)
		(layer "In13.Cu")
		(net "M_H_CPU1_SA_DQS_DP<5>")
	)
	(segment
		(start 156.233368 -206.672434)
		(end 155.98648 -206.919322)
		(width 0.16002)
		(layer "In13.Cu")
		(net "M_H_CPU1_SA_DQS_DP<5>")
	)
	(segment
		(start 157.46984 -205.883002)
		(end 157.46984 -206.359506)
		(width 0.16002)
		(layer "In13.Cu")
		(net "M_H_CPU1_SA_DQS_DP<5>")
	)
	(segment
		(start 142.606268 -226.3394)
		(end 142.573756 -226.358196)
		(width 0.09525)
		(layer "In13.Cu")
		(net "M_H_CPU1_SA_DQS_DP<5>")
	)
	(segment
		(start 168.67251 -201.990706)
		(end 168.19245 -201.990706)
		(width 0.16002)
		(layer "In13.Cu")
		(net "M_H_CPU1_SA_DQS_DP<5>")
	)
	(segment
		(start 155.086558 -208.045304)
		(end 154.860498 -208.045304)
		(width 0.16002)
		(layer "In13.Cu")
		(net "M_H_CPU1_SA_DQS_DP<5>")
	)
	(segment
		(start 169.38625 -201.990706)
		(end 169.26941 -202.107546)
		(width 0.16002)
		(layer "In13.Cu")
		(net "M_H_CPU1_SA_DQS_DP<5>")
	)
	(segment
		(start 166.16553 -202.760326)
		(end 161.06902 -202.760326)
		(width 0.16002)
		(layer "In13.Cu")
		(net "M_H_CPU1_SA_DQS_DP<5>")
	)
	(segment
		(start 143.114268 -225.507296)
		(end 143.076168 -225.529394)
		(width 0.09525)
		(layer "In13.Cu")
		(net "M_H_CPU1_SA_DQS_DP<5>")
	)
	(segment
		(start 153.24074 -209.665062)
		(end 153.24074 -209.891122)
		(width 0.16002)
		(layer "In13.Cu")
		(net "M_H_CPU1_SA_DQS_DP<5>")
	)
	(arc
		(start 144.766538 -222.61449)
		(mid 144.700555 -222.87867)
		(end 144.518126 -223.080834)
		(width 0.09525)
		(layer "In13.Cu")
		(net "M_H_CPU1_SA_DQS_DP<5>")
	)
	(arc
		(start 138.846306 -227.959412)
		(mid 138.564874 -228.035167)
		(end 138.283442 -227.959412)
		(width 0.09525)
		(layer "In13.Cu")
		(net "M_H_CPU1_SA_DQS_DP<5>")
	)
	(arc
		(start 144.454626 -223.117664)
		(mid 144.338828 -223.252058)
		(end 144.297146 -223.424496)
		(width 0.09525)
		(layer "In13.Cu")
		(net "M_H_CPU1_SA_DQS_DP<5>")
	)
	(arc
		(start 135.454898 -227.954586)
		(mid 135.269866 -227.908672)
		(end 135.08609 -227.959412)
		(width 0.09525)
		(layer "In13.Cu")
		(net "M_H_CPU1_SA_DQS_DP<5>")
	)
	(arc
		(start 141.947138 -227.474526)
		(mid 141.882741 -227.735832)
		(end 141.704314 -227.937314)
		(width 0.09525)
		(layer "In13.Cu")
		(net "M_H_CPU1_SA_DQS_DP<5>")
	)
	(arc
		(start 138.283442 -227.959412)
		(mid 138.099667 -227.90864)
		(end 137.914634 -227.954586)
		(width 0.09525)
		(layer "In13.Cu")
		(net "M_H_CPU1_SA_DQS_DP<5>")
	)
	(arc
		(start 142.104618 -227.167694)
		(mid 141.98882 -227.302088)
		(end 141.947138 -227.474526)
		(width 0.09525)
		(layer "In13.Cu")
		(net "M_H_CPU1_SA_DQS_DP<5>")
	)
	(arc
		(start 136.026144 -227.959412)
		(mid 135.744712 -228.035167)
		(end 135.46328 -227.959412)
		(width 0.09525)
		(layer "In13.Cu")
		(net "M_H_CPU1_SA_DQS_DP<5>")
	)
	(arc
		(start 144.924272 -222.307658)
		(mid 144.808248 -222.441979)
		(end 144.766538 -222.61449)
		(width 0.09525)
		(layer "In13.Cu")
		(net "M_H_CPU1_SA_DQS_DP<5>")
	)
	(arc
		(start 136.394952 -227.954586)
		(mid 136.20992 -227.908672)
		(end 136.026144 -227.959412)
		(width 0.09525)
		(layer "In13.Cu")
		(net "M_H_CPU1_SA_DQS_DP<5>")
	)
	(arc
		(start 139.786106 -227.959412)
		(mid 139.504674 -228.035167)
		(end 139.223242 -227.959412)
		(width 0.09525)
		(layer "In13.Cu")
		(net "M_H_CPU1_SA_DQS_DP<5>")
	)
	(arc
		(start 134.60984 -228.000306)
		(mid 134.599641 -227.996469)
		(end 134.58952 -227.992432)
		(width 0.09525)
		(layer "In13.Cu")
		(net "M_H_CPU1_SA_DQS_DP<5>")
	)
	(arc
		(start 135.08609 -227.959412)
		(mid 134.852546 -228.033118)
		(end 134.60984 -228.000306)
		(width 0.09525)
		(layer "In13.Cu")
		(net "M_H_CPU1_SA_DQS_DP<5>")
	)
	(arc
		(start 137.906252 -227.959412)
		(mid 137.62482 -228.035167)
		(end 137.343388 -227.959412)
		(width 0.09525)
		(layer "In13.Cu")
		(net "M_H_CPU1_SA_DQS_DP<5>")
	)
	(arc
		(start 140.72616 -227.959412)
		(mid 140.444728 -228.035167)
		(end 140.163296 -227.959412)
		(width 0.09525)
		(layer "In13.Cu")
		(net "M_H_CPU1_SA_DQS_DP<5>")
	)
	(arc
		(start 144.297146 -223.424496)
		(mid 144.232749 -223.685802)
		(end 144.054322 -223.887284)
		(width 0.09525)
		(layer "In13.Cu")
		(net "M_H_CPU1_SA_DQS_DP<5>")
	)
	(arc
		(start 141.094968 -227.954586)
		(mid 140.909936 -227.908672)
		(end 140.72616 -227.959412)
		(width 0.09525)
		(layer "In13.Cu")
		(net "M_H_CPU1_SA_DQS_DP<5>")
	)
	(arc
		(start 143.826992 -224.234502)
		(mid 143.762595 -224.495808)
		(end 143.584168 -224.69729)
		(width 0.09525)
		(layer "In13.Cu")
		(net "M_H_CPU1_SA_DQS_DP<5>")
	)
	(arc
		(start 143.514572 -224.737676)
		(mid 143.398774 -224.87207)
		(end 143.357092 -225.044508)
		(width 0.09525)
		(layer "In13.Cu")
		(net "M_H_CPU1_SA_DQS_DP<5>")
	)
	(arc
		(start 142.573756 -226.358196)
		(mid 142.458482 -226.492474)
		(end 142.417038 -226.66452)
		(width 0.09525)
		(layer "In13.Cu")
		(net "M_H_CPU1_SA_DQS_DP<5>")
	)
	(arc
		(start 141.666214 -227.959412)
		(mid 141.384782 -228.035167)
		(end 141.10335 -227.959412)
		(width 0.09525)
		(layer "In13.Cu")
		(net "M_H_CPU1_SA_DQS_DP<5>")
	)
	(arc
		(start 142.417038 -226.66452)
		(mid 142.352641 -226.925826)
		(end 142.174214 -227.127308)
		(width 0.09525)
		(layer "In13.Cu")
		(net "M_H_CPU1_SA_DQS_DP<5>")
	)
	(arc
		(start 139.223242 -227.959412)
		(mid 139.034774 -227.908735)
		(end 138.846306 -227.959412)
		(width 0.09525)
		(layer "In13.Cu")
		(net "M_H_CPU1_SA_DQS_DP<5>")
	)
	(arc
		(start 140.154914 -227.954586)
		(mid 139.969882 -227.908672)
		(end 139.786106 -227.959412)
		(width 0.09525)
		(layer "In13.Cu")
		(net "M_H_CPU1_SA_DQS_DP<5>")
	)
	(arc
		(start 136.966198 -227.959412)
		(mid 136.684766 -228.035167)
		(end 136.403334 -227.959412)
		(width 0.09525)
		(layer "In13.Cu")
		(net "M_H_CPU1_SA_DQS_DP<5>")
	)
	(arc
		(start 143.357092 -225.044508)
		(mid 143.292695 -225.305814)
		(end 143.114268 -225.507296)
		(width 0.09525)
		(layer "In13.Cu")
		(net "M_H_CPU1_SA_DQS_DP<5>")
	)
	(arc
		(start 137.343388 -227.959412)
		(mid 137.159613 -227.90864)
		(end 136.97458 -227.954586)
		(width 0.09525)
		(layer "In13.Cu")
		(net "M_H_CPU1_SA_DQS_DP<5>")
	)
	(arc
		(start 143.043656 -225.54819)
		(mid 142.928382 -225.682468)
		(end 142.886938 -225.854514)
		(width 0.09525)
		(layer "In13.Cu")
		(net "M_H_CPU1_SA_DQS_DP<5>")
	)
	(arc
		(start 143.98371 -223.928178)
		(mid 143.868436 -224.062456)
		(end 143.826992 -224.234502)
		(width 0.09525)
		(layer "In13.Cu")
		(net "M_H_CPU1_SA_DQS_DP<5>")
	)
	(arc
		(start 142.886938 -225.854514)
		(mid 142.821691 -226.117117)
		(end 142.64132 -226.318826)
		(width 0.09525)
		(layer "In13.Cu")
		(net "M_H_CPU1_SA_DQS_DP<5>")
	)
	(segment
		(start 135.748014 -246.370348)
		(end 136.214866 -246.10441)
		(width 0.12954)
		(layer "F.Cu")
		(net "M_H_CPU1_SA_DQS_DP<4>")
	)
	(segment
		(start 146.377914 -246.753126)
		(end 146.106134 -246.481346)
		(width 0.09525)
		(layer "In13.Cu")
		(net "M_H_CPU1_SA_DQS_DP<4>")
	)
	(segment
		(start 146.106134 -246.481346)
		(end 145.616168 -246.481346)
		(width 0.09525)
		(layer "In13.Cu")
		(net "M_H_CPU1_SA_DQS_DP<4>")
	)
	(segment
		(start 173.676056 -238.445548)
		(end 173.505622 -238.615982)
		(width 0.16002)
		(layer "In13.Cu")
		(net "M_H_CPU1_SA_DQS_DP<4>")
	)
	(segment
		(start 156.803852 -245.933976)
		(end 147.858226 -245.933976)
		(width 0.16002)
		(layer "In13.Cu")
		(net "M_H_CPU1_SA_DQS_DP<4>")
	)
	(segment
		(start 165.02507 -238.603282)
		(end 163.517834 -240.110518)
		(width 0.16002)
		(layer "In13.Cu")
		(net "M_H_CPU1_SA_DQS_DP<4>")
	)
	(segment
		(start 141.674596 -246.434356)
		(end 141.666214 -246.42953)
		(width 0.09525)
		(layer "In13.Cu")
		(net "M_H_CPU1_SA_DQS_DP<4>")
	)
	(segment
		(start 170.13047 -237.729522)
		(end 166.88181 -237.729522)
		(width 0.16002)
		(layer "In13.Cu")
		(net "M_H_CPU1_SA_DQS_DP<4>")
	)
	(segment
		(start 147.834604 -245.933976)
		(end 147.775422 -245.993158)
		(width 0.09525)
		(layer "In13.Cu")
		(net "M_H_CPU1_SA_DQS_DP<4>")
	)
	(segment
		(start 136.08431 -246.456708)
		(end 136.060942 -246.36984)
		(width 0.09525)
		(layer "In13.Cu")
		(net "M_H_CPU1_SA_DQS_DP<4>")
	)
	(segment
		(start 147.858226 -245.933976)
		(end 147.834604 -245.933976)
		(width 0.09525)
		(layer "In13.Cu")
		(net "M_H_CPU1_SA_DQS_DP<4>")
	)
	(segment
		(start 172.568616 -238.260128)
		(end 170.661076 -238.260128)
		(width 0.16002)
		(layer "In13.Cu")
		(net "M_H_CPU1_SA_DQS_DP<4>")
	)
	(segment
		(start 143.55445 -246.434356)
		(end 143.546068 -246.42953)
		(width 0.09525)
		(layer "In13.Cu")
		(net "M_H_CPU1_SA_DQS_DP<4>")
	)
	(segment
		(start 176.072038 -238.135414)
		(end 175.761904 -238.445548)
		(width 0.16002)
		(layer "In13.Cu")
		(net "M_H_CPU1_SA_DQS_DP<4>")
	)
	(segment
		(start 147.59813 -245.993158)
		(end 146.895312 -246.753126)
		(width 0.09525)
		(layer "In13.Cu")
		(net "M_H_CPU1_SA_DQS_DP<4>")
	)
	(segment
		(start 175.761904 -238.445548)
		(end 173.676056 -238.445548)
		(width 0.16002)
		(layer "In13.Cu")
		(net "M_H_CPU1_SA_DQS_DP<4>")
	)
	(segment
		(start 136.97458 -246.434356)
		(end 136.966198 -246.42953)
		(width 0.09525)
		(layer "In13.Cu")
		(net "M_H_CPU1_SA_DQS_DP<4>")
	)
	(segment
		(start 140.163296 -246.42953)
		(end 140.154914 -246.434356)
		(width 0.09525)
		(layer "In13.Cu")
		(net "M_H_CPU1_SA_DQS_DP<4>")
	)
	(segment
		(start 166.00805 -238.603282)
		(end 165.02507 -238.603282)
		(width 0.16002)
		(layer "In13.Cu")
		(net "M_H_CPU1_SA_DQS_DP<4>")
	)
	(segment
		(start 146.895312 -246.753126)
		(end 146.377914 -246.753126)
		(width 0.09525)
		(layer "In13.Cu")
		(net "M_H_CPU1_SA_DQS_DP<4>")
	)
	(segment
		(start 166.88181 -237.729522)
		(end 166.00805 -238.603282)
		(width 0.16002)
		(layer "In13.Cu")
		(net "M_H_CPU1_SA_DQS_DP<4>")
	)
	(segment
		(start 170.661076 -238.260128)
		(end 170.13047 -237.729522)
		(width 0.16002)
		(layer "In13.Cu")
		(net "M_H_CPU1_SA_DQS_DP<4>")
	)
	(segment
		(start 144.486884 -246.42953)
		(end 144.47647 -246.423434)
		(width 0.09525)
		(layer "In13.Cu")
		(net "M_H_CPU1_SA_DQS_DP<4>")
	)
	(segment
		(start 144.884648 -246.417338)
		(end 144.851882 -246.436388)
		(width 0.09525)
		(layer "In13.Cu")
		(net "M_H_CPU1_SA_DQS_DP<4>")
	)
	(segment
		(start 136.060942 -246.36984)
		(end 136.214866 -246.10441)
		(width 0.09525)
		(layer "In13.Cu")
		(net "M_H_CPU1_SA_DQS_DP<4>")
	)
	(segment
		(start 136.403334 -246.42953)
		(end 136.394952 -246.434356)
		(width 0.09525)
		(layer "In13.Cu")
		(net "M_H_CPU1_SA_DQS_DP<4>")
	)
	(segment
		(start 141.10335 -246.42953)
		(end 141.094968 -246.434356)
		(width 0.09525)
		(layer "In13.Cu")
		(net "M_H_CPU1_SA_DQS_DP<4>")
	)
	(segment
		(start 173.505622 -238.615982)
		(end 172.92447 -238.615982)
		(width 0.16002)
		(layer "In13.Cu")
		(net "M_H_CPU1_SA_DQS_DP<4>")
	)
	(segment
		(start 137.914634 -246.434356)
		(end 137.906252 -246.42953)
		(width 0.09525)
		(layer "In13.Cu")
		(net "M_H_CPU1_SA_DQS_DP<4>")
	)
	(segment
		(start 147.775422 -245.993158)
		(end 147.59813 -245.993158)
		(width 0.09525)
		(layer "In13.Cu")
		(net "M_H_CPU1_SA_DQS_DP<4>")
	)
	(segment
		(start 162.62731 -240.110518)
		(end 156.803852 -245.933976)
		(width 0.16002)
		(layer "In13.Cu")
		(net "M_H_CPU1_SA_DQS_DP<4>")
	)
	(segment
		(start 163.517834 -240.110518)
		(end 162.62731 -240.110518)
		(width 0.16002)
		(layer "In13.Cu")
		(net "M_H_CPU1_SA_DQS_DP<4>")
	)
	(segment
		(start 172.92447 -238.615982)
		(end 172.568616 -238.260128)
		(width 0.16002)
		(layer "In13.Cu")
		(net "M_H_CPU1_SA_DQS_DP<4>")
	)
	(arc
		(start 139.786106 -246.42953)
		(mid 139.504674 -246.353775)
		(end 139.223242 -246.42953)
		(width 0.09525)
		(layer "In13.Cu")
		(net "M_H_CPU1_SA_DQS_DP<4>")
	)
	(arc
		(start 142.043404 -246.42953)
		(mid 141.859629 -246.480302)
		(end 141.674596 -246.434356)
		(width 0.09525)
		(layer "In13.Cu")
		(net "M_H_CPU1_SA_DQS_DP<4>")
	)
	(arc
		(start 136.394952 -246.434356)
		(mid 136.242057 -246.479184)
		(end 136.08431 -246.456708)
		(width 0.09525)
		(layer "In13.Cu")
		(net "M_H_CPU1_SA_DQS_DP<4>")
	)
	(arc
		(start 144.851882 -246.436388)
		(mid 144.668501 -246.480219)
		(end 144.486884 -246.42953)
		(width 0.09525)
		(layer "In13.Cu")
		(net "M_H_CPU1_SA_DQS_DP<4>")
	)
	(arc
		(start 142.606268 -246.42953)
		(mid 142.324836 -246.353775)
		(end 142.043404 -246.42953)
		(width 0.09525)
		(layer "In13.Cu")
		(net "M_H_CPU1_SA_DQS_DP<4>")
	)
	(arc
		(start 138.846306 -246.42953)
		(mid 138.564874 -246.353775)
		(end 138.283442 -246.42953)
		(width 0.09525)
		(layer "In13.Cu")
		(net "M_H_CPU1_SA_DQS_DP<4>")
	)
	(arc
		(start 140.154914 -246.434356)
		(mid 139.969882 -246.48027)
		(end 139.786106 -246.42953)
		(width 0.09525)
		(layer "In13.Cu")
		(net "M_H_CPU1_SA_DQS_DP<4>")
	)
	(arc
		(start 137.906252 -246.42953)
		(mid 137.62482 -246.353775)
		(end 137.343388 -246.42953)
		(width 0.09525)
		(layer "In13.Cu")
		(net "M_H_CPU1_SA_DQS_DP<4>")
	)
	(arc
		(start 145.426684 -246.42953)
		(mid 145.157251 -246.353659)
		(end 144.884648 -246.417338)
		(width 0.09525)
		(layer "In13.Cu")
		(net "M_H_CPU1_SA_DQS_DP<4>")
	)
	(arc
		(start 136.966198 -246.42953)
		(mid 136.684766 -246.353775)
		(end 136.403334 -246.42953)
		(width 0.09525)
		(layer "In13.Cu")
		(net "M_H_CPU1_SA_DQS_DP<4>")
	)
	(arc
		(start 143.546068 -246.42953)
		(mid 143.264636 -246.353775)
		(end 142.983204 -246.42953)
		(width 0.09525)
		(layer "In13.Cu")
		(net "M_H_CPU1_SA_DQS_DP<4>")
	)
	(arc
		(start 141.094968 -246.434356)
		(mid 140.909936 -246.48027)
		(end 140.72616 -246.42953)
		(width 0.09525)
		(layer "In13.Cu")
		(net "M_H_CPU1_SA_DQS_DP<4>")
	)
	(arc
		(start 138.283442 -246.42953)
		(mid 138.099667 -246.480302)
		(end 137.914634 -246.434356)
		(width 0.09525)
		(layer "In13.Cu")
		(net "M_H_CPU1_SA_DQS_DP<4>")
	)
	(arc
		(start 144.47647 -246.423434)
		(mid 144.199308 -246.353634)
		(end 143.923766 -246.42953)
		(width 0.09525)
		(layer "In13.Cu")
		(net "M_H_CPU1_SA_DQS_DP<4>")
	)
	(arc
		(start 137.343388 -246.42953)
		(mid 137.159613 -246.480302)
		(end 136.97458 -246.434356)
		(width 0.09525)
		(layer "In13.Cu")
		(net "M_H_CPU1_SA_DQS_DP<4>")
	)
	(arc
		(start 140.72616 -246.42953)
		(mid 140.444728 -246.353775)
		(end 140.163296 -246.42953)
		(width 0.09525)
		(layer "In13.Cu")
		(net "M_H_CPU1_SA_DQS_DP<4>")
	)
	(arc
		(start 145.616168 -246.481346)
		(mid 145.518002 -246.467978)
		(end 145.426684 -246.42953)
		(width 0.09525)
		(layer "In13.Cu")
		(net "M_H_CPU1_SA_DQS_DP<4>")
	)
	(arc
		(start 142.983204 -246.42953)
		(mid 142.794736 -246.480207)
		(end 142.606268 -246.42953)
		(width 0.09525)
		(layer "In13.Cu")
		(net "M_H_CPU1_SA_DQS_DP<4>")
	)
	(arc
		(start 139.223242 -246.42953)
		(mid 139.034774 -246.480207)
		(end 138.846306 -246.42953)
		(width 0.09525)
		(layer "In13.Cu")
		(net "M_H_CPU1_SA_DQS_DP<4>")
	)
	(arc
		(start 141.666214 -246.42953)
		(mid 141.384782 -246.353775)
		(end 141.10335 -246.42953)
		(width 0.09525)
		(layer "In13.Cu")
		(net "M_H_CPU1_SA_DQS_DP<4>")
	)
	(arc
		(start 143.923766 -246.42953)
		(mid 143.739737 -246.480429)
		(end 143.55445 -246.434356)
		(width 0.09525)
		(layer "In13.Cu")
		(net "M_H_CPU1_SA_DQS_DP<4>")
	)
	(segment
		(start 135.748014 -241.510312)
		(end 136.214866 -241.244374)
		(width 0.12954)
		(layer "F.Cu")
		(net "M_H_CPU1_SA_DQS_DP<3>")
	)
	(segment
		(start 172.92447 -229.265988)
		(end 173.505622 -229.265988)
		(width 0.16002)
		(layer "In13.Cu")
		(net "M_H_CPU1_SA_DQS_DP<3>")
	)
	(segment
		(start 170.661076 -228.910134)
		(end 172.568616 -228.910134)
		(width 0.16002)
		(layer "In13.Cu")
		(net "M_H_CPU1_SA_DQS_DP<3>")
	)
	(segment
		(start 143.546068 -241.569494)
		(end 143.55445 -241.57432)
		(width 0.09525)
		(layer "In13.Cu")
		(net "M_H_CPU1_SA_DQS_DP<3>")
	)
	(segment
		(start 147.363434 -240.356136)
		(end 147.82927 -240.356136)
		(width 0.09525)
		(layer "In13.Cu")
		(net "M_H_CPU1_SA_DQS_DP<3>")
	)
	(segment
		(start 147.888452 -240.296954)
		(end 147.912074 -240.296954)
		(width 0.09525)
		(layer "In13.Cu")
		(net "M_H_CPU1_SA_DQS_DP<3>")
	)
	(segment
		(start 145.144744 -241.493802)
		(end 145.794222 -241.493802)
		(width 0.09525)
		(layer "In13.Cu")
		(net "M_H_CPU1_SA_DQS_DP<3>")
	)
	(segment
		(start 158.04769 -233.443272)
		(end 162.237674 -229.253288)
		(width 0.16002)
		(layer "In13.Cu")
		(net "M_H_CPU1_SA_DQS_DP<3>")
	)
	(segment
		(start 136.394952 -241.57432)
		(end 136.403334 -241.569494)
		(width 0.09525)
		(layer "In13.Cu")
		(net "M_H_CPU1_SA_DQS_DP<3>")
	)
	(segment
		(start 166.00805 -229.253288)
		(end 166.88181 -228.379528)
		(width 0.16002)
		(layer "In13.Cu")
		(net "M_H_CPU1_SA_DQS_DP<3>")
	)
	(segment
		(start 172.568616 -228.910134)
		(end 172.92447 -229.265988)
		(width 0.16002)
		(layer "In13.Cu")
		(net "M_H_CPU1_SA_DQS_DP<3>")
	)
	(segment
		(start 145.794222 -241.493802)
		(end 146.36496 -240.923064)
		(width 0.09525)
		(layer "In13.Cu")
		(net "M_H_CPU1_SA_DQS_DP<3>")
	)
	(segment
		(start 170.13047 -228.379528)
		(end 170.661076 -228.910134)
		(width 0.16002)
		(layer "In13.Cu")
		(net "M_H_CPU1_SA_DQS_DP<3>")
	)
	(segment
		(start 144.47647 -241.563398)
		(end 144.486884 -241.569494)
		(width 0.09525)
		(layer "In13.Cu")
		(net "M_H_CPU1_SA_DQS_DP<3>")
	)
	(segment
		(start 147.912074 -240.296954)
		(end 151.67864 -240.296954)
		(width 0.16002)
		(layer "In13.Cu")
		(net "M_H_CPU1_SA_DQS_DP<3>")
	)
	(segment
		(start 147.82927 -240.356136)
		(end 147.888452 -240.296954)
		(width 0.09525)
		(layer "In13.Cu")
		(net "M_H_CPU1_SA_DQS_DP<3>")
	)
	(segment
		(start 136.966198 -241.569494)
		(end 136.97458 -241.57432)
		(width 0.09525)
		(layer "In13.Cu")
		(net "M_H_CPU1_SA_DQS_DP<3>")
	)
	(segment
		(start 146.36496 -240.923064)
		(end 146.796506 -240.923064)
		(width 0.09525)
		(layer "In13.Cu")
		(net "M_H_CPU1_SA_DQS_DP<3>")
	)
	(segment
		(start 166.88181 -228.379528)
		(end 170.13047 -228.379528)
		(width 0.16002)
		(layer "In13.Cu")
		(net "M_H_CPU1_SA_DQS_DP<3>")
	)
	(segment
		(start 141.094968 -241.57432)
		(end 141.10335 -241.569494)
		(width 0.09525)
		(layer "In13.Cu")
		(net "M_H_CPU1_SA_DQS_DP<3>")
	)
	(segment
		(start 174.57547 -229.047548)
		(end 174.71517 -228.907848)
		(width 0.16002)
		(layer "In13.Cu")
		(net "M_H_CPU1_SA_DQS_DP<3>")
	)
	(segment
		(start 136.214866 -241.244374)
		(end 136.060942 -241.509804)
		(width 0.09525)
		(layer "In13.Cu")
		(net "M_H_CPU1_SA_DQS_DP<3>")
	)
	(segment
		(start 175.80991 -229.047548)
		(end 176.072038 -228.78542)
		(width 0.16002)
		(layer "In13.Cu")
		(net "M_H_CPU1_SA_DQS_DP<3>")
	)
	(segment
		(start 151.67864 -240.296954)
		(end 158.04769 -233.927904)
		(width 0.16002)
		(layer "In13.Cu")
		(net "M_H_CPU1_SA_DQS_DP<3>")
	)
	(segment
		(start 146.796506 -240.923064)
		(end 147.363434 -240.356136)
		(width 0.09525)
		(layer "In13.Cu")
		(net "M_H_CPU1_SA_DQS_DP<3>")
	)
	(segment
		(start 174.71517 -228.907848)
		(end 175.19269 -228.907848)
		(width 0.16002)
		(layer "In13.Cu")
		(net "M_H_CPU1_SA_DQS_DP<3>")
	)
	(segment
		(start 140.154914 -241.57432)
		(end 140.163296 -241.569494)
		(width 0.09525)
		(layer "In13.Cu")
		(net "M_H_CPU1_SA_DQS_DP<3>")
	)
	(segment
		(start 141.666214 -241.569494)
		(end 141.674596 -241.57432)
		(width 0.09525)
		(layer "In13.Cu")
		(net "M_H_CPU1_SA_DQS_DP<3>")
	)
	(segment
		(start 173.505622 -229.265988)
		(end 173.724062 -229.047548)
		(width 0.16002)
		(layer "In13.Cu")
		(net "M_H_CPU1_SA_DQS_DP<3>")
	)
	(segment
		(start 162.237674 -229.253288)
		(end 166.00805 -229.253288)
		(width 0.16002)
		(layer "In13.Cu")
		(net "M_H_CPU1_SA_DQS_DP<3>")
	)
	(segment
		(start 175.19269 -228.907848)
		(end 175.33239 -229.047548)
		(width 0.16002)
		(layer "In13.Cu")
		(net "M_H_CPU1_SA_DQS_DP<3>")
	)
	(segment
		(start 173.724062 -229.047548)
		(end 174.57547 -229.047548)
		(width 0.16002)
		(layer "In13.Cu")
		(net "M_H_CPU1_SA_DQS_DP<3>")
	)
	(segment
		(start 136.060942 -241.509804)
		(end 136.08431 -241.596672)
		(width 0.09525)
		(layer "In13.Cu")
		(net "M_H_CPU1_SA_DQS_DP<3>")
	)
	(segment
		(start 175.33239 -229.047548)
		(end 175.80991 -229.047548)
		(width 0.16002)
		(layer "In13.Cu")
		(net "M_H_CPU1_SA_DQS_DP<3>")
	)
	(segment
		(start 137.906252 -241.569494)
		(end 137.914634 -241.57432)
		(width 0.09525)
		(layer "In13.Cu")
		(net "M_H_CPU1_SA_DQS_DP<3>")
	)
	(segment
		(start 158.04769 -233.927904)
		(end 158.04769 -233.443272)
		(width 0.16002)
		(layer "In13.Cu")
		(net "M_H_CPU1_SA_DQS_DP<3>")
	)
	(arc
		(start 144.486884 -241.569494)
		(mid 144.6685 -241.620231)
		(end 144.851882 -241.576352)
		(width 0.09525)
		(layer "In13.Cu")
		(net "M_H_CPU1_SA_DQS_DP<3>")
	)
	(arc
		(start 142.043404 -241.569494)
		(mid 142.324836 -241.493739)
		(end 142.606268 -241.569494)
		(width 0.09525)
		(layer "In13.Cu")
		(net "M_H_CPU1_SA_DQS_DP<3>")
	)
	(arc
		(start 137.343388 -241.569494)
		(mid 137.62482 -241.493739)
		(end 137.906252 -241.569494)
		(width 0.09525)
		(layer "In13.Cu")
		(net "M_H_CPU1_SA_DQS_DP<3>")
	)
	(arc
		(start 142.606268 -241.569494)
		(mid 142.794736 -241.620171)
		(end 142.983204 -241.569494)
		(width 0.09525)
		(layer "In13.Cu")
		(net "M_H_CPU1_SA_DQS_DP<3>")
	)
	(arc
		(start 143.923766 -241.569494)
		(mid 144.199309 -241.493645)
		(end 144.47647 -241.563398)
		(width 0.09525)
		(layer "In13.Cu")
		(net "M_H_CPU1_SA_DQS_DP<3>")
	)
	(arc
		(start 136.97458 -241.57432)
		(mid 137.159612 -241.620234)
		(end 137.343388 -241.569494)
		(width 0.09525)
		(layer "In13.Cu")
		(net "M_H_CPU1_SA_DQS_DP<3>")
	)
	(arc
		(start 140.72616 -241.569494)
		(mid 140.909935 -241.620266)
		(end 141.094968 -241.57432)
		(width 0.09525)
		(layer "In13.Cu")
		(net "M_H_CPU1_SA_DQS_DP<3>")
	)
	(arc
		(start 142.983204 -241.569494)
		(mid 143.264636 -241.493739)
		(end 143.546068 -241.569494)
		(width 0.09525)
		(layer "In13.Cu")
		(net "M_H_CPU1_SA_DQS_DP<3>")
	)
	(arc
		(start 141.10335 -241.569494)
		(mid 141.384782 -241.493739)
		(end 141.666214 -241.569494)
		(width 0.09525)
		(layer "In13.Cu")
		(net "M_H_CPU1_SA_DQS_DP<3>")
	)
	(arc
		(start 140.163296 -241.569494)
		(mid 140.444728 -241.493739)
		(end 140.72616 -241.569494)
		(width 0.09525)
		(layer "In13.Cu")
		(net "M_H_CPU1_SA_DQS_DP<3>")
	)
	(arc
		(start 139.223242 -241.569494)
		(mid 139.504674 -241.493739)
		(end 139.786106 -241.569494)
		(width 0.09525)
		(layer "In13.Cu")
		(net "M_H_CPU1_SA_DQS_DP<3>")
	)
	(arc
		(start 138.283442 -241.569494)
		(mid 138.564874 -241.493739)
		(end 138.846306 -241.569494)
		(width 0.09525)
		(layer "In13.Cu")
		(net "M_H_CPU1_SA_DQS_DP<3>")
	)
	(arc
		(start 137.914634 -241.57432)
		(mid 138.099666 -241.620234)
		(end 138.283442 -241.569494)
		(width 0.09525)
		(layer "In13.Cu")
		(net "M_H_CPU1_SA_DQS_DP<3>")
	)
	(arc
		(start 144.851882 -241.576352)
		(mid 144.992608 -241.514841)
		(end 145.144744 -241.493802)
		(width 0.09525)
		(layer "In13.Cu")
		(net "M_H_CPU1_SA_DQS_DP<3>")
	)
	(arc
		(start 141.674596 -241.57432)
		(mid 141.859628 -241.620234)
		(end 142.043404 -241.569494)
		(width 0.09525)
		(layer "In13.Cu")
		(net "M_H_CPU1_SA_DQS_DP<3>")
	)
	(arc
		(start 143.55445 -241.57432)
		(mid 143.739736 -241.620356)
		(end 143.923766 -241.569494)
		(width 0.09525)
		(layer "In13.Cu")
		(net "M_H_CPU1_SA_DQS_DP<3>")
	)
	(arc
		(start 136.08431 -241.596672)
		(mid 136.24206 -241.619191)
		(end 136.394952 -241.57432)
		(width 0.09525)
		(layer "In13.Cu")
		(net "M_H_CPU1_SA_DQS_DP<3>")
	)
	(arc
		(start 138.846306 -241.569494)
		(mid 139.034774 -241.620171)
		(end 139.223242 -241.569494)
		(width 0.09525)
		(layer "In13.Cu")
		(net "M_H_CPU1_SA_DQS_DP<3>")
	)
	(arc
		(start 139.786106 -241.569494)
		(mid 139.969881 -241.620266)
		(end 140.154914 -241.57432)
		(width 0.09525)
		(layer "In13.Cu")
		(net "M_H_CPU1_SA_DQS_DP<3>")
	)
	(arc
		(start 136.403334 -241.569494)
		(mid 136.684766 -241.493739)
		(end 136.966198 -241.569494)
		(width 0.09525)
		(layer "In13.Cu")
		(net "M_H_CPU1_SA_DQS_DP<3>")
	)
	(segment
		(start 135.748014 -236.650276)
		(end 136.214866 -236.384338)
		(width 0.12954)
		(layer "F.Cu")
		(net "M_H_CPU1_SA_DQS_DP<2>")
	)
	(segment
		(start 137.914634 -236.714284)
		(end 137.906252 -236.709458)
		(width 0.09525)
		(layer "In13.Cu")
		(net "M_H_CPU1_SA_DQS_DP<2>")
	)
	(segment
		(start 143.933672 -236.703362)
		(end 143.914876 -236.714284)
		(width 0.09525)
		(layer "In13.Cu")
		(net "M_H_CPU1_SA_DQS_DP<2>")
	)
	(segment
		(start 142.96898 -236.71784)
		(end 142.955264 -236.72419)
		(width 0.09525)
		(layer "In13.Cu")
		(net "M_H_CPU1_SA_DQS_DP<2>")
	)
	(segment
		(start 160.386522 -220.680534)
		(end 155.184094 -225.882962)
		(width 0.16002)
		(layer "In13.Cu")
		(net "M_H_CPU1_SA_DQS_DP<2>")
	)
	(segment
		(start 142.983204 -236.709458)
		(end 142.96898 -236.71784)
		(width 0.09525)
		(layer "In13.Cu")
		(net "M_H_CPU1_SA_DQS_DP<2>")
	)
	(segment
		(start 162.327844 -220.680534)
		(end 161.850324 -220.680534)
		(width 0.16002)
		(layer "In13.Cu")
		(net "M_H_CPU1_SA_DQS_DP<2>")
	)
	(segment
		(start 172.92447 -219.915994)
		(end 172.568616 -219.56014)
		(width 0.16002)
		(layer "In13.Cu")
		(net "M_H_CPU1_SA_DQS_DP<2>")
	)
	(segment
		(start 140.163296 -236.709458)
		(end 140.154914 -236.714284)
		(width 0.09525)
		(layer "In13.Cu")
		(net "M_H_CPU1_SA_DQS_DP<2>")
	)
	(segment
		(start 163.428172 -219.580206)
		(end 162.327844 -220.680534)
		(width 0.16002)
		(layer "In13.Cu")
		(net "M_H_CPU1_SA_DQS_DP<2>")
	)
	(segment
		(start 172.568616 -219.56014)
		(end 170.661076 -219.56014)
		(width 0.16002)
		(layer "In13.Cu")
		(net "M_H_CPU1_SA_DQS_DP<2>")
	)
	(segment
		(start 173.505622 -219.915994)
		(end 172.92447 -219.915994)
		(width 0.16002)
		(layer "In13.Cu")
		(net "M_H_CPU1_SA_DQS_DP<2>")
	)
	(segment
		(start 164.970206 -219.580206)
		(end 163.428172 -219.580206)
		(width 0.16002)
		(layer "In13.Cu")
		(net "M_H_CPU1_SA_DQS_DP<2>")
	)
	(segment
		(start 166.88181 -219.029534)
		(end 166.00805 -219.903294)
		(width 0.16002)
		(layer "In13.Cu")
		(net "M_H_CPU1_SA_DQS_DP<2>")
	)
	(segment
		(start 146.86153 -235.481876)
		(end 146.500596 -235.481876)
		(width 0.09525)
		(layer "In13.Cu")
		(net "M_H_CPU1_SA_DQS_DP<2>")
	)
	(segment
		(start 174.13605 -219.285566)
		(end 173.505622 -219.915994)
		(width 0.16002)
		(layer "In13.Cu")
		(net "M_H_CPU1_SA_DQS_DP<2>")
	)
	(segment
		(start 161.710624 -220.540834)
		(end 161.233104 -220.540834)
		(width 0.16002)
		(layer "In13.Cu")
		(net "M_H_CPU1_SA_DQS_DP<2>")
	)
	(segment
		(start 174.817532 -219.285566)
		(end 174.13605 -219.285566)
		(width 0.16002)
		(layer "In13.Cu")
		(net "M_H_CPU1_SA_DQS_DP<2>")
	)
	(segment
		(start 176.072038 -219.435426)
		(end 175.807116 -219.700348)
		(width 0.16002)
		(layer "In13.Cu")
		(net "M_H_CPU1_SA_DQS_DP<2>")
	)
	(segment
		(start 146.500596 -235.481876)
		(end 145.412206 -236.570266)
		(width 0.09525)
		(layer "In13.Cu")
		(net "M_H_CPU1_SA_DQS_DP<2>")
	)
	(segment
		(start 136.97458 -236.714284)
		(end 136.966198 -236.709458)
		(width 0.09525)
		(layer "In13.Cu")
		(net "M_H_CPU1_SA_DQS_DP<2>")
	)
	(segment
		(start 144.49425 -236.714284)
		(end 144.485868 -236.709458)
		(width 0.09525)
		(layer "In13.Cu")
		(net "M_H_CPU1_SA_DQS_DP<2>")
	)
	(segment
		(start 166.00805 -219.903294)
		(end 165.293294 -219.903294)
		(width 0.16002)
		(layer "In13.Cu")
		(net "M_H_CPU1_SA_DQS_DP<2>")
	)
	(segment
		(start 145.412206 -236.570266)
		(end 145.1991 -236.570266)
		(width 0.09525)
		(layer "In13.Cu")
		(net "M_H_CPU1_SA_DQS_DP<2>")
	)
	(segment
		(start 175.232314 -219.700348)
		(end 174.817532 -219.285566)
		(width 0.16002)
		(layer "In13.Cu")
		(net "M_H_CPU1_SA_DQS_DP<2>")
	)
	(segment
		(start 147.90928 -234.567476)
		(end 147.885658 -234.567476)
		(width 0.09525)
		(layer "In13.Cu")
		(net "M_H_CPU1_SA_DQS_DP<2>")
	)
	(segment
		(start 170.13047 -219.029534)
		(end 166.88181 -219.029534)
		(width 0.16002)
		(layer "In13.Cu")
		(net "M_H_CPU1_SA_DQS_DP<2>")
	)
	(segment
		(start 136.060942 -236.649768)
		(end 136.214866 -236.384338)
		(width 0.09525)
		(layer "In13.Cu")
		(net "M_H_CPU1_SA_DQS_DP<2>")
	)
	(segment
		(start 161.093404 -220.680534)
		(end 160.386522 -220.680534)
		(width 0.16002)
		(layer "In13.Cu")
		(net "M_H_CPU1_SA_DQS_DP<2>")
	)
	(segment
		(start 147.826476 -234.626658)
		(end 147.569428 -234.626658)
		(width 0.09525)
		(layer "In13.Cu")
		(net "M_H_CPU1_SA_DQS_DP<2>")
	)
	(segment
		(start 141.674596 -236.714284)
		(end 141.666214 -236.709458)
		(width 0.09525)
		(layer "In13.Cu")
		(net "M_H_CPU1_SA_DQS_DP<2>")
	)
	(segment
		(start 148.909786 -234.567476)
		(end 147.90928 -234.567476)
		(width 0.16002)
		(layer "In13.Cu")
		(net "M_H_CPU1_SA_DQS_DP<2>")
	)
	(segment
		(start 170.661076 -219.56014)
		(end 170.13047 -219.029534)
		(width 0.16002)
		(layer "In13.Cu")
		(net "M_H_CPU1_SA_DQS_DP<2>")
	)
	(segment
		(start 145.1991 -236.570266)
		(end 144.863058 -236.709458)
		(width 0.09525)
		(layer "In13.Cu")
		(net "M_H_CPU1_SA_DQS_DP<2>")
	)
	(segment
		(start 155.184094 -228.293168)
		(end 148.909786 -234.567476)
		(width 0.16002)
		(layer "In13.Cu")
		(net "M_H_CPU1_SA_DQS_DP<2>")
	)
	(segment
		(start 161.850324 -220.680534)
		(end 161.710624 -220.540834)
		(width 0.16002)
		(layer "In13.Cu")
		(net "M_H_CPU1_SA_DQS_DP<2>")
	)
	(segment
		(start 147.569428 -234.626658)
		(end 146.86153 -235.481876)
		(width 0.09525)
		(layer "In13.Cu")
		(net "M_H_CPU1_SA_DQS_DP<2>")
	)
	(segment
		(start 165.293294 -219.903294)
		(end 164.970206 -219.580206)
		(width 0.16002)
		(layer "In13.Cu")
		(net "M_H_CPU1_SA_DQS_DP<2>")
	)
	(segment
		(start 136.08431 -236.736636)
		(end 136.060942 -236.649768)
		(width 0.09525)
		(layer "In13.Cu")
		(net "M_H_CPU1_SA_DQS_DP<2>")
	)
	(segment
		(start 161.233104 -220.540834)
		(end 161.093404 -220.680534)
		(width 0.16002)
		(layer "In13.Cu")
		(net "M_H_CPU1_SA_DQS_DP<2>")
	)
	(segment
		(start 147.885658 -234.567476)
		(end 147.826476 -234.626658)
		(width 0.09525)
		(layer "In13.Cu")
		(net "M_H_CPU1_SA_DQS_DP<2>")
	)
	(segment
		(start 141.10335 -236.709458)
		(end 141.094968 -236.714284)
		(width 0.09525)
		(layer "In13.Cu")
		(net "M_H_CPU1_SA_DQS_DP<2>")
	)
	(segment
		(start 155.184094 -225.882962)
		(end 155.184094 -228.293168)
		(width 0.16002)
		(layer "In13.Cu")
		(net "M_H_CPU1_SA_DQS_DP<2>")
	)
	(segment
		(start 136.403334 -236.709458)
		(end 136.394952 -236.714284)
		(width 0.09525)
		(layer "In13.Cu")
		(net "M_H_CPU1_SA_DQS_DP<2>")
	)
	(segment
		(start 175.807116 -219.700348)
		(end 175.232314 -219.700348)
		(width 0.16002)
		(layer "In13.Cu")
		(net "M_H_CPU1_SA_DQS_DP<2>")
	)
	(arc
		(start 144.863058 -236.709458)
		(mid 144.679283 -236.76023)
		(end 144.49425 -236.714284)
		(width 0.09525)
		(layer "In13.Cu")
		(net "M_H_CPU1_SA_DQS_DP<2>")
	)
	(arc
		(start 137.906252 -236.709458)
		(mid 137.62482 -236.633703)
		(end 137.343388 -236.709458)
		(width 0.09525)
		(layer "In13.Cu")
		(net "M_H_CPU1_SA_DQS_DP<2>")
	)
	(arc
		(start 136.966198 -236.709458)
		(mid 136.684766 -236.633703)
		(end 136.403334 -236.709458)
		(width 0.09525)
		(layer "In13.Cu")
		(net "M_H_CPU1_SA_DQS_DP<2>")
	)
	(arc
		(start 138.283442 -236.709458)
		(mid 138.099667 -236.76023)
		(end 137.914634 -236.714284)
		(width 0.09525)
		(layer "In13.Cu")
		(net "M_H_CPU1_SA_DQS_DP<2>")
	)
	(arc
		(start 139.786106 -236.709458)
		(mid 139.504674 -236.633703)
		(end 139.223242 -236.709458)
		(width 0.09525)
		(layer "In13.Cu")
		(net "M_H_CPU1_SA_DQS_DP<2>")
	)
	(arc
		(start 141.094968 -236.714284)
		(mid 140.909936 -236.760198)
		(end 140.72616 -236.709458)
		(width 0.09525)
		(layer "In13.Cu")
		(net "M_H_CPU1_SA_DQS_DP<2>")
	)
	(arc
		(start 140.154914 -236.714284)
		(mid 139.969882 -236.760198)
		(end 139.786106 -236.709458)
		(width 0.09525)
		(layer "In13.Cu")
		(net "M_H_CPU1_SA_DQS_DP<2>")
	)
	(arc
		(start 137.343388 -236.709458)
		(mid 137.159613 -236.76023)
		(end 136.97458 -236.714284)
		(width 0.09525)
		(layer "In13.Cu")
		(net "M_H_CPU1_SA_DQS_DP<2>")
	)
	(arc
		(start 136.394952 -236.714284)
		(mid 136.242057 -236.759112)
		(end 136.08431 -236.736636)
		(width 0.09525)
		(layer "In13.Cu")
		(net "M_H_CPU1_SA_DQS_DP<2>")
	)
	(arc
		(start 141.666214 -236.709458)
		(mid 141.384782 -236.633703)
		(end 141.10335 -236.709458)
		(width 0.09525)
		(layer "In13.Cu")
		(net "M_H_CPU1_SA_DQS_DP<2>")
	)
	(arc
		(start 144.485868 -236.709458)
		(mid 144.210579 -236.633737)
		(end 143.933672 -236.703362)
		(width 0.09525)
		(layer "In13.Cu")
		(net "M_H_CPU1_SA_DQS_DP<2>")
	)
	(arc
		(start 143.546068 -236.709458)
		(mid 143.264636 -236.633703)
		(end 142.983204 -236.709458)
		(width 0.09525)
		(layer "In13.Cu")
		(net "M_H_CPU1_SA_DQS_DP<2>")
	)
	(arc
		(start 143.914876 -236.714284)
		(mid 143.729844 -236.760198)
		(end 143.546068 -236.709458)
		(width 0.09525)
		(layer "In13.Cu")
		(net "M_H_CPU1_SA_DQS_DP<2>")
	)
	(arc
		(start 139.223242 -236.709458)
		(mid 139.034774 -236.760135)
		(end 138.846306 -236.709458)
		(width 0.09525)
		(layer "In13.Cu")
		(net "M_H_CPU1_SA_DQS_DP<2>")
	)
	(arc
		(start 140.72616 -236.709458)
		(mid 140.444728 -236.633703)
		(end 140.163296 -236.709458)
		(width 0.09525)
		(layer "In13.Cu")
		(net "M_H_CPU1_SA_DQS_DP<2>")
	)
	(arc
		(start 142.043404 -236.709458)
		(mid 141.859629 -236.76023)
		(end 141.674596 -236.714284)
		(width 0.09525)
		(layer "In13.Cu")
		(net "M_H_CPU1_SA_DQS_DP<2>")
	)
	(arc
		(start 142.955264 -236.72419)
		(mid 142.778942 -236.759863)
		(end 142.606268 -236.709458)
		(width 0.09525)
		(layer "In13.Cu")
		(net "M_H_CPU1_SA_DQS_DP<2>")
	)
	(arc
		(start 142.606268 -236.709458)
		(mid 142.324836 -236.633703)
		(end 142.043404 -236.709458)
		(width 0.09525)
		(layer "In13.Cu")
		(net "M_H_CPU1_SA_DQS_DP<2>")
	)
	(arc
		(start 138.846306 -236.709458)
		(mid 138.564874 -236.633703)
		(end 138.283442 -236.709458)
		(width 0.09525)
		(layer "In13.Cu")
		(net "M_H_CPU1_SA_DQS_DP<2>")
	)
	(segment
		(start 135.748014 -231.79024)
		(end 136.214866 -231.524302)
		(width 0.12954)
		(layer "F.Cu")
		(net "M_H_CPU1_SA_DQS_DP<1>")
	)
	(segment
		(start 147.443444 -227.529136)
		(end 147.42668 -227.5459)
		(width 0.09525)
		(layer "In13.Cu")
		(net "M_H_CPU1_SA_DQS_DP<1>")
	)
	(segment
		(start 166.00805 -210.5533)
		(end 165.404546 -210.5533)
		(width 0.16002)
		(layer "In13.Cu")
		(net "M_H_CPU1_SA_DQS_DP<1>")
	)
	(segment
		(start 144.460468 -231.3305)
		(end 144.000728 -231.79024)
		(width 0.09525)
		(layer "In13.Cu")
		(net "M_H_CPU1_SA_DQS_DP<1>")
	)
	(segment
		(start 149.646894 -221.69247)
		(end 149.646894 -225.325686)
		(width 0.16002)
		(layer "In13.Cu")
		(net "M_H_CPU1_SA_DQS_DP<1>")
	)
	(segment
		(start 145.307812 -230.117904)
		(end 144.95018 -230.117904)
		(width 0.09525)
		(layer "In13.Cu")
		(net "M_H_CPU1_SA_DQS_DP<1>")
	)
	(segment
		(start 136.060942 -231.789732)
		(end 136.214866 -231.524302)
		(width 0.09525)
		(layer "In13.Cu")
		(net "M_H_CPU1_SA_DQS_DP<1>")
	)
	(segment
		(start 165.404546 -210.5533)
		(end 165.099492 -210.248246)
		(width 0.16002)
		(layer "In13.Cu")
		(net "M_H_CPU1_SA_DQS_DP<1>")
	)
	(segment
		(start 176.072038 -210.085432)
		(end 175.801782 -210.355688)
		(width 0.16002)
		(layer "In13.Cu")
		(net "M_H_CPU1_SA_DQS_DP<1>")
	)
	(segment
		(start 166.88181 -209.67954)
		(end 166.00805 -210.5533)
		(width 0.16002)
		(layer "In13.Cu")
		(net "M_H_CPU1_SA_DQS_DP<1>")
	)
	(segment
		(start 137.914634 -231.854248)
		(end 137.906252 -231.849422)
		(width 0.09525)
		(layer "In13.Cu")
		(net "M_H_CPU1_SA_DQS_DP<1>")
	)
	(segment
		(start 173.505622 -210.566)
		(end 172.92447 -210.566)
		(width 0.16002)
		(layer "In13.Cu")
		(net "M_H_CPU1_SA_DQS_DP<1>")
	)
	(segment
		(start 147.42668 -227.62972)
		(end 147.070318 -227.986082)
		(width 0.09525)
		(layer "In13.Cu")
		(net "M_H_CPU1_SA_DQS_DP<1>")
	)
	(segment
		(start 144.95018 -230.117904)
		(end 144.460468 -230.607616)
		(width 0.09525)
		(layer "In13.Cu")
		(net "M_H_CPU1_SA_DQS_DP<1>")
	)
	(segment
		(start 147.070318 -227.986082)
		(end 147.070318 -228.355398)
		(width 0.09525)
		(layer "In13.Cu")
		(net "M_H_CPU1_SA_DQS_DP<1>")
	)
	(segment
		(start 149.646894 -225.325686)
		(end 147.443444 -227.529136)
		(width 0.16002)
		(layer "In13.Cu")
		(net "M_H_CPU1_SA_DQS_DP<1>")
	)
	(segment
		(start 165.099492 -210.248246)
		(end 161.091118 -210.248246)
		(width 0.16002)
		(layer "In13.Cu")
		(net "M_H_CPU1_SA_DQS_DP<1>")
	)
	(segment
		(start 173.715934 -210.355688)
		(end 173.505622 -210.566)
		(width 0.16002)
		(layer "In13.Cu")
		(net "M_H_CPU1_SA_DQS_DP<1>")
	)
	(segment
		(start 172.568616 -210.210146)
		(end 170.661076 -210.210146)
		(width 0.16002)
		(layer "In13.Cu")
		(net "M_H_CPU1_SA_DQS_DP<1>")
	)
	(segment
		(start 147.070318 -228.355398)
		(end 145.307812 -230.117904)
		(width 0.09525)
		(layer "In13.Cu")
		(net "M_H_CPU1_SA_DQS_DP<1>")
	)
	(segment
		(start 147.42668 -227.5459)
		(end 147.42668 -227.62972)
		(width 0.09525)
		(layer "In13.Cu")
		(net "M_H_CPU1_SA_DQS_DP<1>")
	)
	(segment
		(start 144.460468 -230.607616)
		(end 144.460468 -231.3305)
		(width 0.09525)
		(layer "In13.Cu")
		(net "M_H_CPU1_SA_DQS_DP<1>")
	)
	(segment
		(start 141.10335 -231.849422)
		(end 141.094968 -231.854248)
		(width 0.09525)
		(layer "In13.Cu")
		(net "M_H_CPU1_SA_DQS_DP<1>")
	)
	(segment
		(start 172.92447 -210.566)
		(end 172.568616 -210.210146)
		(width 0.16002)
		(layer "In13.Cu")
		(net "M_H_CPU1_SA_DQS_DP<1>")
	)
	(segment
		(start 161.091118 -210.248246)
		(end 149.646894 -221.69247)
		(width 0.16002)
		(layer "In13.Cu")
		(net "M_H_CPU1_SA_DQS_DP<1>")
	)
	(segment
		(start 141.674596 -231.854248)
		(end 141.666214 -231.849422)
		(width 0.09525)
		(layer "In13.Cu")
		(net "M_H_CPU1_SA_DQS_DP<1>")
	)
	(segment
		(start 170.661076 -210.210146)
		(end 170.13047 -209.67954)
		(width 0.16002)
		(layer "In13.Cu")
		(net "M_H_CPU1_SA_DQS_DP<1>")
	)
	(segment
		(start 175.801782 -210.355688)
		(end 173.715934 -210.355688)
		(width 0.16002)
		(layer "In13.Cu")
		(net "M_H_CPU1_SA_DQS_DP<1>")
	)
	(segment
		(start 136.08431 -231.8766)
		(end 136.060942 -231.789732)
		(width 0.09525)
		(layer "In13.Cu")
		(net "M_H_CPU1_SA_DQS_DP<1>")
	)
	(segment
		(start 136.97458 -231.854248)
		(end 136.966198 -231.849422)
		(width 0.09525)
		(layer "In13.Cu")
		(net "M_H_CPU1_SA_DQS_DP<1>")
	)
	(segment
		(start 140.163296 -231.849422)
		(end 140.154914 -231.854248)
		(width 0.09525)
		(layer "In13.Cu")
		(net "M_H_CPU1_SA_DQS_DP<1>")
	)
	(segment
		(start 136.403334 -231.849422)
		(end 136.394952 -231.854248)
		(width 0.09525)
		(layer "In13.Cu")
		(net "M_H_CPU1_SA_DQS_DP<1>")
	)
	(segment
		(start 143.923258 -231.849422)
		(end 143.914876 -231.854248)
		(width 0.09525)
		(layer "In13.Cu")
		(net "M_H_CPU1_SA_DQS_DP<1>")
	)
	(segment
		(start 170.13047 -209.67954)
		(end 166.88181 -209.67954)
		(width 0.16002)
		(layer "In13.Cu")
		(net "M_H_CPU1_SA_DQS_DP<1>")
	)
	(arc
		(start 139.786106 -231.849422)
		(mid 139.504674 -231.773667)
		(end 139.223242 -231.849422)
		(width 0.09525)
		(layer "In13.Cu")
		(net "M_H_CPU1_SA_DQS_DP<1>")
	)
	(arc
		(start 142.606268 -231.849422)
		(mid 142.324836 -231.773667)
		(end 142.043404 -231.849422)
		(width 0.09525)
		(layer "In13.Cu")
		(net "M_H_CPU1_SA_DQS_DP<1>")
	)
	(arc
		(start 141.666214 -231.849422)
		(mid 141.384782 -231.773667)
		(end 141.10335 -231.849422)
		(width 0.09525)
		(layer "In13.Cu")
		(net "M_H_CPU1_SA_DQS_DP<1>")
	)
	(arc
		(start 137.906252 -231.849422)
		(mid 137.62482 -231.773667)
		(end 137.343388 -231.849422)
		(width 0.09525)
		(layer "In13.Cu")
		(net "M_H_CPU1_SA_DQS_DP<1>")
	)
	(arc
		(start 141.094968 -231.854248)
		(mid 140.909936 -231.900162)
		(end 140.72616 -231.849422)
		(width 0.09525)
		(layer "In13.Cu")
		(net "M_H_CPU1_SA_DQS_DP<1>")
	)
	(arc
		(start 138.846306 -231.849422)
		(mid 138.564874 -231.773667)
		(end 138.283442 -231.849422)
		(width 0.09525)
		(layer "In13.Cu")
		(net "M_H_CPU1_SA_DQS_DP<1>")
	)
	(arc
		(start 139.223242 -231.849422)
		(mid 139.034774 -231.900099)
		(end 138.846306 -231.849422)
		(width 0.09525)
		(layer "In13.Cu")
		(net "M_H_CPU1_SA_DQS_DP<1>")
	)
	(arc
		(start 142.983204 -231.849422)
		(mid 142.794736 -231.900099)
		(end 142.606268 -231.849422)
		(width 0.09525)
		(layer "In13.Cu")
		(net "M_H_CPU1_SA_DQS_DP<1>")
	)
	(arc
		(start 144.000728 -231.79024)
		(mid 143.96391 -231.822339)
		(end 143.923258 -231.849422)
		(width 0.09525)
		(layer "In13.Cu")
		(net "M_H_CPU1_SA_DQS_DP<1>")
	)
	(arc
		(start 143.546068 -231.849422)
		(mid 143.264636 -231.773667)
		(end 142.983204 -231.849422)
		(width 0.09525)
		(layer "In13.Cu")
		(net "M_H_CPU1_SA_DQS_DP<1>")
	)
	(arc
		(start 143.914876 -231.854248)
		(mid 143.729844 -231.900162)
		(end 143.546068 -231.849422)
		(width 0.09525)
		(layer "In13.Cu")
		(net "M_H_CPU1_SA_DQS_DP<1>")
	)
	(arc
		(start 140.72616 -231.849422)
		(mid 140.444728 -231.773667)
		(end 140.163296 -231.849422)
		(width 0.09525)
		(layer "In13.Cu")
		(net "M_H_CPU1_SA_DQS_DP<1>")
	)
	(arc
		(start 137.343388 -231.849422)
		(mid 137.159613 -231.900194)
		(end 136.97458 -231.854248)
		(width 0.09525)
		(layer "In13.Cu")
		(net "M_H_CPU1_SA_DQS_DP<1>")
	)
	(arc
		(start 136.966198 -231.849422)
		(mid 136.684766 -231.773667)
		(end 136.403334 -231.849422)
		(width 0.09525)
		(layer "In13.Cu")
		(net "M_H_CPU1_SA_DQS_DP<1>")
	)
	(arc
		(start 138.283442 -231.849422)
		(mid 138.099667 -231.900194)
		(end 137.914634 -231.854248)
		(width 0.09525)
		(layer "In13.Cu")
		(net "M_H_CPU1_SA_DQS_DP<1>")
	)
	(arc
		(start 140.154914 -231.854248)
		(mid 139.969882 -231.900162)
		(end 139.786106 -231.849422)
		(width 0.09525)
		(layer "In13.Cu")
		(net "M_H_CPU1_SA_DQS_DP<1>")
	)
	(arc
		(start 136.394952 -231.854248)
		(mid 136.242057 -231.899076)
		(end 136.08431 -231.8766)
		(width 0.09525)
		(layer "In13.Cu")
		(net "M_H_CPU1_SA_DQS_DP<1>")
	)
	(arc
		(start 142.043404 -231.849422)
		(mid 141.859629 -231.900194)
		(end 141.674596 -231.854248)
		(width 0.09525)
		(layer "In13.Cu")
		(net "M_H_CPU1_SA_DQS_DP<1>")
	)
	(segment
		(start 135.748014 -226.930458)
		(end 136.214866 -226.66452)
		(width 0.12954)
		(layer "F.Cu")
		(net "M_H_CPU1_SA_DQS_DP<0>")
	)
	(segment
		(start 150.69693 -210.552538)
		(end 150.69693 -211.250022)
		(width 0.16002)
		(layer "In13.Cu")
		(net "M_H_CPU1_SA_DQS_DP<0>")
	)
	(segment
		(start 136.97458 -226.994466)
		(end 136.966198 -226.98964)
		(width 0.09525)
		(layer "In13.Cu")
		(net "M_H_CPU1_SA_DQS_DP<0>")
	)
	(segment
		(start 142.545816 -224.540826)
		(end 142.475204 -224.58172)
		(width 0.09525)
		(layer "In13.Cu")
		(net "M_H_CPU1_SA_DQS_DP<0>")
	)
	(segment
		(start 144.053814 -221.198186)
		(end 144.112234 -221.256606)
		(width 0.09525)
		(layer "In13.Cu")
		(net "M_H_CPU1_SA_DQS_DP<0>")
	)
	(segment
		(start 141.605762 -226.160838)
		(end 141.538198 -226.200208)
		(width 0.09525)
		(layer "In13.Cu")
		(net "M_H_CPU1_SA_DQS_DP<0>")
	)
	(segment
		(start 164.71646 -201.589386)
		(end 162.421824 -201.589386)
		(width 0.16002)
		(layer "In13.Cu")
		(net "M_H_CPU1_SA_DQS_DP<0>")
	)
	(segment
		(start 170.13047 -200.329546)
		(end 166.88181 -200.329546)
		(width 0.16002)
		(layer "In13.Cu")
		(net "M_H_CPU1_SA_DQS_DP<0>")
	)
	(segment
		(start 143.484854 -222.921322)
		(end 143.415258 -222.961708)
		(width 0.09525)
		(layer "In13.Cu")
		(net "M_H_CPU1_SA_DQS_DP<0>")
	)
	(segment
		(start 137.914634 -226.994466)
		(end 137.906252 -226.98964)
		(width 0.09525)
		(layer "In13.Cu")
		(net "M_H_CPU1_SA_DQS_DP<0>")
	)
	(segment
		(start 144.053814 -217.893138)
		(end 144.053814 -221.174564)
		(width 0.16002)
		(layer "In13.Cu")
		(net "M_H_CPU1_SA_DQS_DP<0>")
	)
	(segment
		(start 176.072038 -200.735438)
		(end 175.798988 -201.008488)
		(width 0.16002)
		(layer "In13.Cu")
		(net "M_H_CPU1_SA_DQS_DP<0>")
	)
	(segment
		(start 173.71314 -201.008488)
		(end 173.505622 -201.216006)
		(width 0.16002)
		(layer "In13.Cu")
		(net "M_H_CPU1_SA_DQS_DP<0>")
	)
	(segment
		(start 166.00805 -201.203306)
		(end 165.10254 -201.203306)
		(width 0.16002)
		(layer "In13.Cu")
		(net "M_H_CPU1_SA_DQS_DP<0>")
	)
	(segment
		(start 160.829244 -201.589386)
		(end 159.660082 -201.589386)
		(width 0.16002)
		(layer "In13.Cu")
		(net "M_H_CPU1_SA_DQS_DP<0>")
	)
	(segment
		(start 136.08431 -227.016818)
		(end 136.060942 -226.92995)
		(width 0.09525)
		(layer "In13.Cu")
		(net "M_H_CPU1_SA_DQS_DP<0>")
	)
	(segment
		(start 175.798988 -201.008488)
		(end 173.71314 -201.008488)
		(width 0.16002)
		(layer "In13.Cu")
		(net "M_H_CPU1_SA_DQS_DP<0>")
	)
	(segment
		(start 172.568616 -200.860152)
		(end 170.661076 -200.860152)
		(width 0.16002)
		(layer "In13.Cu")
		(net "M_H_CPU1_SA_DQS_DP<0>")
	)
	(segment
		(start 166.88181 -200.329546)
		(end 166.00805 -201.203306)
		(width 0.16002)
		(layer "In13.Cu")
		(net "M_H_CPU1_SA_DQS_DP<0>")
	)
	(segment
		(start 150.69693 -211.250022)
		(end 144.053814 -217.893138)
		(width 0.16002)
		(layer "In13.Cu")
		(net "M_H_CPU1_SA_DQS_DP<0>")
	)
	(segment
		(start 160.989264 -201.258424)
		(end 160.989264 -201.429366)
		(width 0.16002)
		(layer "In13.Cu")
		(net "M_H_CPU1_SA_DQS_DP<0>")
	)
	(segment
		(start 161.924746 -200.921366)
		(end 161.326322 -200.921366)
		(width 0.16002)
		(layer "In13.Cu")
		(net "M_H_CPU1_SA_DQS_DP<0>")
	)
	(segment
		(start 143.015716 -223.73082)
		(end 142.948152 -223.77019)
		(width 0.09525)
		(layer "In13.Cu")
		(net "M_H_CPU1_SA_DQS_DP<0>")
	)
	(segment
		(start 172.92447 -201.216006)
		(end 172.568616 -200.860152)
		(width 0.16002)
		(layer "In13.Cu")
		(net "M_H_CPU1_SA_DQS_DP<0>")
	)
	(segment
		(start 140.163296 -226.98964)
		(end 140.154914 -226.994466)
		(width 0.09525)
		(layer "In13.Cu")
		(net "M_H_CPU1_SA_DQS_DP<0>")
	)
	(segment
		(start 162.261804 -201.258424)
		(end 161.924746 -200.921366)
		(width 0.16002)
		(layer "In13.Cu")
		(net "M_H_CPU1_SA_DQS_DP<0>")
	)
	(segment
		(start 144.112234 -221.256606)
		(end 144.112234 -221.804484)
		(width 0.09525)
		(layer "In13.Cu")
		(net "M_H_CPU1_SA_DQS_DP<0>")
	)
	(segment
		(start 144.053814 -221.174564)
		(end 144.053814 -221.198186)
		(width 0.09525)
		(layer "In13.Cu")
		(net "M_H_CPU1_SA_DQS_DP<0>")
	)
	(segment
		(start 165.10254 -201.203306)
		(end 164.71646 -201.589386)
		(width 0.16002)
		(layer "In13.Cu")
		(net "M_H_CPU1_SA_DQS_DP<0>")
	)
	(segment
		(start 136.403334 -226.98964)
		(end 136.394952 -226.994466)
		(width 0.09525)
		(layer "In13.Cu")
		(net "M_H_CPU1_SA_DQS_DP<0>")
	)
	(segment
		(start 141.135862 -226.970844)
		(end 141.094968 -226.994466)
		(width 0.09525)
		(layer "In13.Cu")
		(net "M_H_CPU1_SA_DQS_DP<0>")
	)
	(segment
		(start 142.0749 -225.35134)
		(end 142.005304 -225.391726)
		(width 0.09525)
		(layer "In13.Cu")
		(net "M_H_CPU1_SA_DQS_DP<0>")
	)
	(segment
		(start 162.421824 -201.589386)
		(end 162.261804 -201.429366)
		(width 0.16002)
		(layer "In13.Cu")
		(net "M_H_CPU1_SA_DQS_DP<0>")
	)
	(segment
		(start 159.660082 -201.589386)
		(end 150.69693 -210.552538)
		(width 0.16002)
		(layer "In13.Cu")
		(net "M_H_CPU1_SA_DQS_DP<0>")
	)
	(segment
		(start 161.326322 -200.921366)
		(end 160.989264 -201.258424)
		(width 0.16002)
		(layer "In13.Cu")
		(net "M_H_CPU1_SA_DQS_DP<0>")
	)
	(segment
		(start 143.956786 -222.110046)
		(end 143.886428 -222.15094)
		(width 0.09525)
		(layer "In13.Cu")
		(net "M_H_CPU1_SA_DQS_DP<0>")
	)
	(segment
		(start 136.060942 -226.92995)
		(end 136.214866 -226.66452)
		(width 0.09525)
		(layer "In13.Cu")
		(net "M_H_CPU1_SA_DQS_DP<0>")
	)
	(segment
		(start 162.261804 -201.429366)
		(end 162.261804 -201.258424)
		(width 0.16002)
		(layer "In13.Cu")
		(net "M_H_CPU1_SA_DQS_DP<0>")
	)
	(segment
		(start 160.989264 -201.429366)
		(end 160.829244 -201.589386)
		(width 0.16002)
		(layer "In13.Cu")
		(net "M_H_CPU1_SA_DQS_DP<0>")
	)
	(segment
		(start 170.661076 -200.860152)
		(end 170.13047 -200.329546)
		(width 0.16002)
		(layer "In13.Cu")
		(net "M_H_CPU1_SA_DQS_DP<0>")
	)
	(segment
		(start 173.505622 -201.216006)
		(end 172.92447 -201.216006)
		(width 0.16002)
		(layer "In13.Cu")
		(net "M_H_CPU1_SA_DQS_DP<0>")
	)
	(arc
		(start 143.886428 -222.15094)
		(mid 143.707056 -222.352535)
		(end 143.642334 -222.61449)
		(width 0.09525)
		(layer "In13.Cu")
		(net "M_H_CPU1_SA_DQS_DP<0>")
	)
	(arc
		(start 137.906252 -226.98964)
		(mid 137.62482 -226.913885)
		(end 137.343388 -226.98964)
		(width 0.09525)
		(layer "In13.Cu")
		(net "M_H_CPU1_SA_DQS_DP<0>")
	)
	(arc
		(start 136.966198 -226.98964)
		(mid 136.684766 -226.913885)
		(end 136.403334 -226.98964)
		(width 0.09525)
		(layer "In13.Cu")
		(net "M_H_CPU1_SA_DQS_DP<0>")
	)
	(arc
		(start 141.538198 -226.200208)
		(mid 141.357807 -226.401907)
		(end 141.29258 -226.66452)
		(width 0.09525)
		(layer "In13.Cu")
		(net "M_H_CPU1_SA_DQS_DP<0>")
	)
	(arc
		(start 140.72616 -226.98964)
		(mid 140.444728 -226.913885)
		(end 140.163296 -226.98964)
		(width 0.09525)
		(layer "In13.Cu")
		(net "M_H_CPU1_SA_DQS_DP<0>")
	)
	(arc
		(start 138.283442 -226.98964)
		(mid 138.099667 -227.040412)
		(end 137.914634 -226.994466)
		(width 0.09525)
		(layer "In13.Cu")
		(net "M_H_CPU1_SA_DQS_DP<0>")
	)
	(arc
		(start 143.415258 -222.961708)
		(mid 143.236808 -223.163178)
		(end 143.172434 -223.424496)
		(width 0.09525)
		(layer "In13.Cu")
		(net "M_H_CPU1_SA_DQS_DP<0>")
	)
	(arc
		(start 137.343388 -226.98964)
		(mid 137.159613 -227.040412)
		(end 136.97458 -226.994466)
		(width 0.09525)
		(layer "In13.Cu")
		(net "M_H_CPU1_SA_DQS_DP<0>")
	)
	(arc
		(start 136.394952 -226.994466)
		(mid 136.242057 -227.039294)
		(end 136.08431 -227.016818)
		(width 0.09525)
		(layer "In13.Cu")
		(net "M_H_CPU1_SA_DQS_DP<0>")
	)
	(arc
		(start 142.948152 -223.77019)
		(mid 142.767761 -223.971889)
		(end 142.702534 -224.234502)
		(width 0.09525)
		(layer "In13.Cu")
		(net "M_H_CPU1_SA_DQS_DP<0>")
	)
	(arc
		(start 141.76248 -225.854514)
		(mid 141.721023 -226.026554)
		(end 141.605762 -226.160838)
		(width 0.09525)
		(layer "In13.Cu")
		(net "M_H_CPU1_SA_DQS_DP<0>")
	)
	(arc
		(start 139.223242 -226.98964)
		(mid 139.034774 -227.040317)
		(end 138.846306 -226.98964)
		(width 0.09525)
		(layer "In13.Cu")
		(net "M_H_CPU1_SA_DQS_DP<0>")
	)
	(arc
		(start 143.642334 -222.61449)
		(mid 143.600669 -222.786937)
		(end 143.484854 -222.921322)
		(width 0.09525)
		(layer "In13.Cu")
		(net "M_H_CPU1_SA_DQS_DP<0>")
	)
	(arc
		(start 139.786106 -226.98964)
		(mid 139.504674 -226.913885)
		(end 139.223242 -226.98964)
		(width 0.09525)
		(layer "In13.Cu")
		(net "M_H_CPU1_SA_DQS_DP<0>")
	)
	(arc
		(start 141.29258 -226.66452)
		(mid 141.251123 -226.83656)
		(end 141.135862 -226.970844)
		(width 0.09525)
		(layer "In13.Cu")
		(net "M_H_CPU1_SA_DQS_DP<0>")
	)
	(arc
		(start 142.475204 -224.58172)
		(mid 142.296754 -224.78319)
		(end 142.23238 -225.044508)
		(width 0.09525)
		(layer "In13.Cu")
		(net "M_H_CPU1_SA_DQS_DP<0>")
	)
	(arc
		(start 142.702534 -224.234502)
		(mid 142.661077 -224.406542)
		(end 142.545816 -224.540826)
		(width 0.09525)
		(layer "In13.Cu")
		(net "M_H_CPU1_SA_DQS_DP<0>")
	)
	(arc
		(start 142.23238 -225.044508)
		(mid 142.190715 -225.216955)
		(end 142.0749 -225.35134)
		(width 0.09525)
		(layer "In13.Cu")
		(net "M_H_CPU1_SA_DQS_DP<0>")
	)
	(arc
		(start 138.846306 -226.98964)
		(mid 138.564874 -226.913885)
		(end 138.283442 -226.98964)
		(width 0.09525)
		(layer "In13.Cu")
		(net "M_H_CPU1_SA_DQS_DP<0>")
	)
	(arc
		(start 142.005304 -225.391726)
		(mid 141.826854 -225.593196)
		(end 141.76248 -225.854514)
		(width 0.09525)
		(layer "In13.Cu")
		(net "M_H_CPU1_SA_DQS_DP<0>")
	)
	(arc
		(start 143.172434 -223.424496)
		(mid 143.130977 -223.596536)
		(end 143.015716 -223.73082)
		(width 0.09525)
		(layer "In13.Cu")
		(net "M_H_CPU1_SA_DQS_DP<0>")
	)
	(arc
		(start 141.094968 -226.994466)
		(mid 140.909936 -227.04038)
		(end 140.72616 -226.98964)
		(width 0.09525)
		(layer "In13.Cu")
		(net "M_H_CPU1_SA_DQS_DP<0>")
	)
	(arc
		(start 140.154914 -226.994466)
		(mid 139.969882 -227.04038)
		(end 139.786106 -226.98964)
		(width 0.09525)
		(layer "In13.Cu")
		(net "M_H_CPU1_SA_DQS_DP<0>")
	)
	(arc
		(start 144.112234 -221.804484)
		(mid 144.071132 -221.97589)
		(end 143.956786 -222.110046)
		(width 0.09525)
		(layer "In13.Cu")
		(net "M_H_CPU1_SA_DQS_DP<0>")
	)
	(segment
		(start 134.337806 -247.180354)
		(end 134.804658 -246.914416)
		(width 0.12954)
		(layer "F.Cu")
		(net "M_H_CPU1_SA_DQS_DN<9>")
	)
	(segment
		(start 159.64281 -245.21414)
		(end 159.39643 -245.46052)
		(width 0.16002)
		(layer "In13.Cu")
		(net "M_H_CPU1_SA_DQS_DN<9>")
	)
	(segment
		(start 147.836382 -246.861838)
		(end 147.425918 -246.861838)
		(width 0.09525)
		(layer "In13.Cu")
		(net "M_H_CPU1_SA_DQS_DN<9>")
	)
	(segment
		(start 166.803324 -239.095026)
		(end 166.040308 -239.858042)
		(width 0.16002)
		(layer "In13.Cu")
		(net "M_H_CPU1_SA_DQS_DN<9>")
	)
	(segment
		(start 162.294824 -242.14836)
		(end 162.38855 -242.24234)
		(width 0.16002)
		(layer "In13.Cu")
		(net "M_H_CPU1_SA_DQS_DN<9>")
	)
	(segment
		(start 138.753342 -247.239536)
		(end 138.74496 -247.244362)
		(width 0.09525)
		(layer "In13.Cu")
		(net "M_H_CPU1_SA_DQS_DN<9>")
	)
	(segment
		(start 140.264642 -247.244362)
		(end 140.25626 -247.239536)
		(width 0.09525)
		(layer "In13.Cu")
		(net "M_H_CPU1_SA_DQS_DN<9>")
	)
	(segment
		(start 161.34588 -242.6208)
		(end 160.921954 -243.044726)
		(width 0.16002)
		(layer "In13.Cu")
		(net "M_H_CPU1_SA_DQS_DN<9>")
	)
	(segment
		(start 160.44926 -243.99367)
		(end 159.97301 -243.99367)
		(width 0.16002)
		(layer "In13.Cu")
		(net "M_H_CPU1_SA_DQS_DN<9>")
	)
	(segment
		(start 160.921954 -243.52123)
		(end 161.01568 -243.61521)
		(width 0.16002)
		(layer "In13.Cu")
		(net "M_H_CPU1_SA_DQS_DN<9>")
	)
	(segment
		(start 144.971008 -247.247918)
		(end 144.95653 -247.239536)
		(width 0.09525)
		(layer "In13.Cu")
		(net "M_H_CPU1_SA_DQS_DN<9>")
	)
	(segment
		(start 166.040308 -239.858042)
		(end 164.998908 -239.858042)
		(width 0.16002)
		(layer "In13.Cu")
		(net "M_H_CPU1_SA_DQS_DN<9>")
	)
	(segment
		(start 160.921954 -243.044726)
		(end 160.921954 -243.52123)
		(width 0.16002)
		(layer "In13.Cu")
		(net "M_H_CPU1_SA_DQS_DN<9>")
	)
	(segment
		(start 170.412664 -239.895888)
		(end 168.457626 -239.895888)
		(width 0.16002)
		(layer "In13.Cu")
		(net "M_H_CPU1_SA_DQS_DN<9>")
	)
	(segment
		(start 134.650734 -247.179846)
		(end 134.804658 -246.914416)
		(width 0.09525)
		(layer "In13.Cu")
		(net "M_H_CPU1_SA_DQS_DN<9>")
	)
	(segment
		(start 159.17037 -245.46052)
		(end 159.07639 -245.36654)
		(width 0.16002)
		(layer "In13.Cu")
		(net "M_H_CPU1_SA_DQS_DN<9>")
	)
	(segment
		(start 171.024804 -239.283748)
		(end 170.412664 -239.895888)
		(width 0.16002)
		(layer "In13.Cu")
		(net "M_H_CPU1_SA_DQS_DN<9>")
	)
	(segment
		(start 158.054294 -246.802656)
		(end 147.919186 -246.802656)
		(width 0.16002)
		(layer "In13.Cu")
		(net "M_H_CPU1_SA_DQS_DN<9>")
	)
	(segment
		(start 135.564626 -247.244362)
		(end 135.556244 -247.239536)
		(width 0.09525)
		(layer "In13.Cu")
		(net "M_H_CPU1_SA_DQS_DN<9>")
	)
	(segment
		(start 144.394174 -247.239536)
		(end 144.382236 -247.246394)
		(width 0.09525)
		(layer "In13.Cu")
		(net "M_H_CPU1_SA_DQS_DN<9>")
	)
	(segment
		(start 146.110198 -247.425464)
		(end 146.012408 -247.327674)
		(width 0.09525)
		(layer "In13.Cu")
		(net "M_H_CPU1_SA_DQS_DN<9>")
	)
	(segment
		(start 163.28898 -241.34191)
		(end 163.195 -241.24793)
		(width 0.16002)
		(layer "In13.Cu")
		(net "M_H_CPU1_SA_DQS_DN<9>")
	)
	(segment
		(start 171.97197 -238.985298)
		(end 171.67352 -239.283748)
		(width 0.16002)
		(layer "In13.Cu")
		(net "M_H_CPU1_SA_DQS_DN<9>")
	)
	(segment
		(start 158.26994 -246.58701)
		(end 158.054294 -246.802656)
		(width 0.16002)
		(layer "In13.Cu")
		(net "M_H_CPU1_SA_DQS_DN<9>")
	)
	(segment
		(start 163.195 -241.24793)
		(end 162.71875 -241.24793)
		(width 0.16002)
		(layer "In13.Cu")
		(net "M_H_CPU1_SA_DQS_DN<9>")
	)
	(segment
		(start 142.513304 -247.239536)
		(end 142.504922 -247.244362)
		(width 0.09525)
		(layer "In13.Cu")
		(net "M_H_CPU1_SA_DQS_DN<9>")
	)
	(segment
		(start 143.08455 -247.244362)
		(end 143.076168 -247.239536)
		(width 0.09525)
		(layer "In13.Cu")
		(net "M_H_CPU1_SA_DQS_DN<9>")
	)
	(segment
		(start 171.67352 -239.283748)
		(end 171.024804 -239.283748)
		(width 0.16002)
		(layer "In13.Cu")
		(net "M_H_CPU1_SA_DQS_DN<9>")
	)
	(segment
		(start 160.7693 -244.08765)
		(end 160.54324 -244.08765)
		(width 0.16002)
		(layer "In13.Cu")
		(net "M_H_CPU1_SA_DQS_DN<9>")
	)
	(segment
		(start 159.97301 -243.99367)
		(end 159.549084 -244.417596)
		(width 0.16002)
		(layer "In13.Cu")
		(net "M_H_CPU1_SA_DQS_DN<9>")
	)
	(segment
		(start 159.39643 -245.46052)
		(end 159.17037 -245.46052)
		(width 0.16002)
		(layer "In13.Cu")
		(net "M_H_CPU1_SA_DQS_DN<9>")
	)
	(segment
		(start 143.46809 -247.2309)
		(end 143.453358 -247.239536)
		(width 0.09525)
		(layer "In13.Cu")
		(net "M_H_CPU1_SA_DQS_DN<9>")
	)
	(segment
		(start 147.895564 -246.802656)
		(end 147.836382 -246.861838)
		(width 0.09525)
		(layer "In13.Cu")
		(net "M_H_CPU1_SA_DQS_DN<9>")
	)
	(segment
		(start 147.919186 -246.802656)
		(end 147.895564 -246.802656)
		(width 0.09525)
		(layer "In13.Cu")
		(net "M_H_CPU1_SA_DQS_DN<9>")
	)
	(segment
		(start 134.674102 -247.266714)
		(end 134.650734 -247.179846)
		(width 0.09525)
		(layer "In13.Cu")
		(net "M_H_CPU1_SA_DQS_DN<9>")
	)
	(segment
		(start 159.07639 -245.36654)
		(end 158.60014 -245.36654)
		(width 0.16002)
		(layer "In13.Cu")
		(net "M_H_CPU1_SA_DQS_DN<9>")
	)
	(segment
		(start 161.82213 -242.6208)
		(end 161.34588 -242.6208)
		(width 0.16002)
		(layer "In13.Cu")
		(net "M_H_CPU1_SA_DQS_DN<9>")
	)
	(segment
		(start 167.656764 -239.095026)
		(end 166.803324 -239.095026)
		(width 0.16002)
		(layer "In13.Cu")
		(net "M_H_CPU1_SA_DQS_DN<9>")
	)
	(segment
		(start 162.71875 -241.24793)
		(end 162.294824 -241.671856)
		(width 0.16002)
		(layer "In13.Cu")
		(net "M_H_CPU1_SA_DQS_DN<9>")
	)
	(segment
		(start 139.324588 -247.244362)
		(end 139.316206 -247.239536)
		(width 0.09525)
		(layer "In13.Cu")
		(net "M_H_CPU1_SA_DQS_DN<9>")
	)
	(segment
		(start 158.60014 -245.36654)
		(end 158.176214 -245.790466)
		(width 0.16002)
		(layer "In13.Cu")
		(net "M_H_CPU1_SA_DQS_DN<9>")
	)
	(segment
		(start 144.95653 -247.239536)
		(end 144.941798 -247.2309)
		(width 0.09525)
		(layer "In13.Cu")
		(net "M_H_CPU1_SA_DQS_DN<9>")
	)
	(segment
		(start 163.51504 -241.34191)
		(end 163.28898 -241.34191)
		(width 0.16002)
		(layer "In13.Cu")
		(net "M_H_CPU1_SA_DQS_DN<9>")
	)
	(segment
		(start 158.176214 -245.790466)
		(end 158.176214 -246.26697)
		(width 0.16002)
		(layer "In13.Cu")
		(net "M_H_CPU1_SA_DQS_DN<9>")
	)
	(segment
		(start 158.176214 -246.26697)
		(end 158.26994 -246.36095)
		(width 0.16002)
		(layer "In13.Cu")
		(net "M_H_CPU1_SA_DQS_DN<9>")
	)
	(segment
		(start 158.26994 -246.36095)
		(end 158.26994 -246.58701)
		(width 0.16002)
		(layer "In13.Cu")
		(net "M_H_CPU1_SA_DQS_DN<9>")
	)
	(segment
		(start 164.998908 -239.858042)
		(end 163.51504 -241.34191)
		(width 0.16002)
		(layer "In13.Cu")
		(net "M_H_CPU1_SA_DQS_DN<9>")
	)
	(segment
		(start 160.54324 -244.08765)
		(end 160.44926 -243.99367)
		(width 0.16002)
		(layer "In13.Cu")
		(net "M_H_CPU1_SA_DQS_DN<9>")
	)
	(segment
		(start 147.425918 -246.861838)
		(end 146.862292 -247.425464)
		(width 0.09525)
		(layer "In13.Cu")
		(net "M_H_CPU1_SA_DQS_DN<9>")
	)
	(segment
		(start 161.01568 -243.61521)
		(end 161.01568 -243.84127)
		(width 0.16002)
		(layer "In13.Cu")
		(net "M_H_CPU1_SA_DQS_DN<9>")
	)
	(segment
		(start 162.294824 -241.671856)
		(end 162.294824 -242.14836)
		(width 0.16002)
		(layer "In13.Cu")
		(net "M_H_CPU1_SA_DQS_DN<9>")
	)
	(segment
		(start 159.549084 -244.417596)
		(end 159.549084 -244.8941)
		(width 0.16002)
		(layer "In13.Cu")
		(net "M_H_CPU1_SA_DQS_DN<9>")
	)
	(segment
		(start 137.813288 -247.239536)
		(end 137.804906 -247.244362)
		(width 0.09525)
		(layer "In13.Cu")
		(net "M_H_CPU1_SA_DQS_DN<9>")
	)
	(segment
		(start 162.38855 -242.4684)
		(end 162.14217 -242.71478)
		(width 0.16002)
		(layer "In13.Cu")
		(net "M_H_CPU1_SA_DQS_DN<9>")
	)
	(segment
		(start 161.01568 -243.84127)
		(end 160.7693 -244.08765)
		(width 0.16002)
		(layer "In13.Cu")
		(net "M_H_CPU1_SA_DQS_DN<9>")
	)
	(segment
		(start 168.457626 -239.895888)
		(end 167.656764 -239.095026)
		(width 0.16002)
		(layer "In13.Cu")
		(net "M_H_CPU1_SA_DQS_DN<9>")
	)
	(segment
		(start 162.38855 -242.24234)
		(end 162.38855 -242.4684)
		(width 0.16002)
		(layer "In13.Cu")
		(net "M_H_CPU1_SA_DQS_DN<9>")
	)
	(segment
		(start 162.14217 -242.71478)
		(end 161.91611 -242.71478)
		(width 0.16002)
		(layer "In13.Cu")
		(net "M_H_CPU1_SA_DQS_DN<9>")
	)
	(segment
		(start 146.862292 -247.425464)
		(end 146.110198 -247.425464)
		(width 0.09525)
		(layer "In13.Cu")
		(net "M_H_CPU1_SA_DQS_DN<9>")
	)
	(segment
		(start 161.91611 -242.71478)
		(end 161.82213 -242.6208)
		(width 0.16002)
		(layer "In13.Cu")
		(net "M_H_CPU1_SA_DQS_DN<9>")
	)
	(segment
		(start 159.549084 -244.8941)
		(end 159.64281 -244.98808)
		(width 0.16002)
		(layer "In13.Cu")
		(net "M_H_CPU1_SA_DQS_DN<9>")
	)
	(segment
		(start 159.64281 -244.98808)
		(end 159.64281 -245.21414)
		(width 0.16002)
		(layer "In13.Cu")
		(net "M_H_CPU1_SA_DQS_DN<9>")
	)
	(arc
		(start 144.01673 -247.239536)
		(mid 143.743548 -247.163594)
		(end 143.46809 -247.2309)
		(width 0.09525)
		(layer "In13.Cu")
		(net "M_H_CPU1_SA_DQS_DN<9>")
	)
	(arc
		(start 144.941798 -247.2309)
		(mid 144.666847 -247.163757)
		(end 144.394174 -247.239536)
		(width 0.09525)
		(layer "In13.Cu")
		(net "M_H_CPU1_SA_DQS_DN<9>")
	)
	(arc
		(start 139.693396 -247.239536)
		(mid 139.509621 -247.290308)
		(end 139.324588 -247.244362)
		(width 0.09525)
		(layer "In13.Cu")
		(net "M_H_CPU1_SA_DQS_DN<9>")
	)
	(arc
		(start 141.196314 -247.239536)
		(mid 140.914882 -247.163781)
		(end 140.63345 -247.239536)
		(width 0.09525)
		(layer "In13.Cu")
		(net "M_H_CPU1_SA_DQS_DN<9>")
	)
	(arc
		(start 139.316206 -247.239536)
		(mid 139.034774 -247.163781)
		(end 138.753342 -247.239536)
		(width 0.09525)
		(layer "In13.Cu")
		(net "M_H_CPU1_SA_DQS_DN<9>")
	)
	(arc
		(start 138.74496 -247.244362)
		(mid 138.559928 -247.290276)
		(end 138.376152 -247.239536)
		(width 0.09525)
		(layer "In13.Cu")
		(net "M_H_CPU1_SA_DQS_DN<9>")
	)
	(arc
		(start 138.376152 -247.239536)
		(mid 138.09472 -247.163781)
		(end 137.813288 -247.239536)
		(width 0.09525)
		(layer "In13.Cu")
		(net "M_H_CPU1_SA_DQS_DN<9>")
	)
	(arc
		(start 140.25626 -247.239536)
		(mid 139.974828 -247.163781)
		(end 139.693396 -247.239536)
		(width 0.09525)
		(layer "In13.Cu")
		(net "M_H_CPU1_SA_DQS_DN<9>")
	)
	(arc
		(start 136.496298 -247.239536)
		(mid 136.214866 -247.163781)
		(end 135.933434 -247.239536)
		(width 0.09525)
		(layer "In13.Cu")
		(net "M_H_CPU1_SA_DQS_DN<9>")
	)
	(arc
		(start 146.012408 -247.327674)
		(mid 145.951933 -247.275367)
		(end 145.884646 -247.23217)
		(width 0.09525)
		(layer "In13.Cu")
		(net "M_H_CPU1_SA_DQS_DN<9>")
	)
	(arc
		(start 140.63345 -247.239536)
		(mid 140.449675 -247.290308)
		(end 140.264642 -247.244362)
		(width 0.09525)
		(layer "In13.Cu")
		(net "M_H_CPU1_SA_DQS_DN<9>")
	)
	(arc
		(start 142.136114 -247.239536)
		(mid 141.854682 -247.163781)
		(end 141.57325 -247.239536)
		(width 0.09525)
		(layer "In13.Cu")
		(net "M_H_CPU1_SA_DQS_DN<9>")
	)
	(arc
		(start 145.884646 -247.23217)
		(mid 145.608209 -247.163521)
		(end 145.33372 -247.239536)
		(width 0.09525)
		(layer "In13.Cu")
		(net "M_H_CPU1_SA_DQS_DN<9>")
	)
	(arc
		(start 135.933434 -247.239536)
		(mid 135.749659 -247.290308)
		(end 135.564626 -247.244362)
		(width 0.09525)
		(layer "In13.Cu")
		(net "M_H_CPU1_SA_DQS_DN<9>")
	)
	(arc
		(start 141.57325 -247.239536)
		(mid 141.384782 -247.290213)
		(end 141.196314 -247.239536)
		(width 0.09525)
		(layer "In13.Cu")
		(net "M_H_CPU1_SA_DQS_DN<9>")
	)
	(arc
		(start 137.436098 -247.239536)
		(mid 137.154666 -247.163781)
		(end 136.873234 -247.239536)
		(width 0.09525)
		(layer "In13.Cu")
		(net "M_H_CPU1_SA_DQS_DN<9>")
	)
	(arc
		(start 135.556244 -247.239536)
		(mid 135.274812 -247.163781)
		(end 134.99338 -247.239536)
		(width 0.09525)
		(layer "In13.Cu")
		(net "M_H_CPU1_SA_DQS_DN<9>")
	)
	(arc
		(start 134.99338 -247.239536)
		(mid 134.836782 -247.288825)
		(end 134.674102 -247.266714)
		(width 0.09525)
		(layer "In13.Cu")
		(net "M_H_CPU1_SA_DQS_DN<9>")
	)
	(arc
		(start 137.804906 -247.244362)
		(mid 137.619874 -247.290276)
		(end 137.436098 -247.239536)
		(width 0.09525)
		(layer "In13.Cu")
		(net "M_H_CPU1_SA_DQS_DN<9>")
	)
	(arc
		(start 143.453358 -247.239536)
		(mid 143.269583 -247.290308)
		(end 143.08455 -247.244362)
		(width 0.09525)
		(layer "In13.Cu")
		(net "M_H_CPU1_SA_DQS_DN<9>")
	)
	(arc
		(start 143.076168 -247.239536)
		(mid 142.794736 -247.163781)
		(end 142.513304 -247.239536)
		(width 0.09525)
		(layer "In13.Cu")
		(net "M_H_CPU1_SA_DQS_DN<9>")
	)
	(arc
		(start 136.873234 -247.239536)
		(mid 136.684766 -247.290213)
		(end 136.496298 -247.239536)
		(width 0.09525)
		(layer "In13.Cu")
		(net "M_H_CPU1_SA_DQS_DN<9>")
	)
	(arc
		(start 142.504922 -247.244362)
		(mid 142.31989 -247.290276)
		(end 142.136114 -247.239536)
		(width 0.09525)
		(layer "In13.Cu")
		(net "M_H_CPU1_SA_DQS_DN<9>")
	)
	(arc
		(start 145.33372 -247.239536)
		(mid 145.153441 -247.290367)
		(end 144.971008 -247.247918)
		(width 0.09525)
		(layer "In13.Cu")
		(net "M_H_CPU1_SA_DQS_DN<9>")
	)
	(arc
		(start 144.382236 -247.246394)
		(mid 144.198601 -247.290344)
		(end 144.01673 -247.239536)
		(width 0.09525)
		(layer "In13.Cu")
		(net "M_H_CPU1_SA_DQS_DN<9>")
	)
	(segment
		(start 134.337806 -242.320318)
		(end 134.804658 -242.05438)
		(width 0.12954)
		(layer "F.Cu")
		(net "M_H_CPU1_SA_DQS_DN<8>")
	)
	(segment
		(start 147.823936 -241.200686)
		(end 147.764754 -241.259868)
		(width 0.09525)
		(layer "In13.Cu")
		(net "M_H_CPU1_SA_DQS_DN<8>")
	)
	(segment
		(start 159.464756 -234.64266)
		(end 158.886144 -235.221272)
		(width 0.16002)
		(layer "In13.Cu")
		(net "M_H_CPU1_SA_DQS_DN<8>")
	)
	(segment
		(start 147.764754 -241.259868)
		(end 147.520914 -241.259868)
		(width 0.09525)
		(layer "In13.Cu")
		(net "M_H_CPU1_SA_DQS_DN<8>")
	)
	(segment
		(start 134.650734 -242.31981)
		(end 134.804658 -242.05438)
		(width 0.09525)
		(layer "In13.Cu")
		(net "M_H_CPU1_SA_DQS_DN<8>")
	)
	(segment
		(start 168.700958 -229.738428)
		(end 168.561258 -229.598728)
		(width 0.16002)
		(layer "In13.Cu")
		(net "M_H_CPU1_SA_DQS_DN<8>")
	)
	(segment
		(start 161.880804 -230.864664)
		(end 161.880804 -231.341168)
		(width 0.16002)
		(layer "In13.Cu")
		(net "M_H_CPU1_SA_DQS_DN<8>")
	)
	(segment
		(start 168.561258 -229.598728)
		(end 168.083738 -229.598728)
		(width 0.16002)
		(layer "In13.Cu")
		(net "M_H_CPU1_SA_DQS_DN<8>")
	)
	(segment
		(start 158.886144 -235.221272)
		(end 157.98292 -235.221272)
		(width 0.16002)
		(layer "In13.Cu")
		(net "M_H_CPU1_SA_DQS_DN<8>")
	)
	(segment
		(start 140.264642 -242.384326)
		(end 140.25626 -242.3795)
		(width 0.09525)
		(layer "In13.Cu")
		(net "M_H_CPU1_SA_DQS_DN<8>")
	)
	(segment
		(start 143.46809 -242.370864)
		(end 143.453358 -242.3795)
		(width 0.09525)
		(layer "In13.Cu")
		(net "M_H_CPU1_SA_DQS_DN<8>")
	)
	(segment
		(start 160.591246 -233.51617)
		(end 160.365186 -233.51617)
		(width 0.16002)
		(layer "In13.Cu")
		(net "M_H_CPU1_SA_DQS_DN<8>")
	)
	(segment
		(start 157.98292 -235.221272)
		(end 152.003506 -241.200686)
		(width 0.16002)
		(layer "In13.Cu")
		(net "M_H_CPU1_SA_DQS_DN<8>")
	)
	(segment
		(start 159.55899 -233.186478)
		(end 159.135064 -233.610404)
		(width 0.16002)
		(layer "In13.Cu")
		(net "M_H_CPU1_SA_DQS_DN<8>")
	)
	(segment
		(start 146.308826 -241.970306)
		(end 145.847816 -242.431316)
		(width 0.09525)
		(layer "In13.Cu")
		(net "M_H_CPU1_SA_DQS_DN<8>")
	)
	(segment
		(start 163.110926 -230.77043)
		(end 162.781234 -230.440738)
		(width 0.16002)
		(layer "In13.Cu")
		(net "M_H_CPU1_SA_DQS_DN<8>")
	)
	(segment
		(start 162.30473 -230.440738)
		(end 161.880804 -230.864664)
		(width 0.16002)
		(layer "In13.Cu")
		(net "M_H_CPU1_SA_DQS_DN<8>")
	)
	(segment
		(start 161.964116 -232.1433)
		(end 161.738056 -232.1433)
		(width 0.16002)
		(layer "In13.Cu")
		(net "M_H_CPU1_SA_DQS_DN<8>")
	)
	(segment
		(start 161.408364 -231.813608)
		(end 160.93186 -231.813608)
		(width 0.16002)
		(layer "In13.Cu")
		(net "M_H_CPU1_SA_DQS_DN<8>")
	)
	(segment
		(start 170.138852 -229.885748)
		(end 169.991532 -229.738428)
		(width 0.16002)
		(layer "In13.Cu")
		(net "M_H_CPU1_SA_DQS_DN<8>")
	)
	(segment
		(start 163.336986 -230.77043)
		(end 163.110926 -230.77043)
		(width 0.16002)
		(layer "In13.Cu")
		(net "M_H_CPU1_SA_DQS_DN<8>")
	)
	(segment
		(start 138.753342 -242.3795)
		(end 138.74496 -242.384326)
		(width 0.09525)
		(layer "In13.Cu")
		(net "M_H_CPU1_SA_DQS_DN<8>")
	)
	(segment
		(start 171.97197 -229.635304)
		(end 171.721526 -229.885748)
		(width 0.16002)
		(layer "In13.Cu")
		(net "M_H_CPU1_SA_DQS_DN<8>")
	)
	(segment
		(start 162.210496 -231.67086)
		(end 162.210496 -231.89692)
		(width 0.16002)
		(layer "In13.Cu")
		(net "M_H_CPU1_SA_DQS_DN<8>")
	)
	(segment
		(start 143.08455 -242.384326)
		(end 143.076168 -242.3795)
		(width 0.09525)
		(layer "In13.Cu")
		(net "M_H_CPU1_SA_DQS_DN<8>")
	)
	(segment
		(start 161.738056 -232.1433)
		(end 161.408364 -231.813608)
		(width 0.16002)
		(layer "In13.Cu")
		(net "M_H_CPU1_SA_DQS_DN<8>")
	)
	(segment
		(start 159.464756 -234.4166)
		(end 159.464756 -234.64266)
		(width 0.16002)
		(layer "In13.Cu")
		(net "M_H_CPU1_SA_DQS_DN<8>")
	)
	(segment
		(start 160.93186 -231.813608)
		(end 160.507934 -232.237534)
		(width 0.16002)
		(layer "In13.Cu")
		(net "M_H_CPU1_SA_DQS_DN<8>")
	)
	(segment
		(start 161.880804 -231.341168)
		(end 162.210496 -231.67086)
		(width 0.16002)
		(layer "In13.Cu")
		(net "M_H_CPU1_SA_DQS_DN<8>")
	)
	(segment
		(start 139.324588 -242.384326)
		(end 139.316206 -242.3795)
		(width 0.09525)
		(layer "In13.Cu")
		(net "M_H_CPU1_SA_DQS_DN<8>")
	)
	(segment
		(start 160.365186 -233.51617)
		(end 160.035494 -233.186478)
		(width 0.16002)
		(layer "In13.Cu")
		(net "M_H_CPU1_SA_DQS_DN<8>")
	)
	(segment
		(start 168.083738 -229.598728)
		(end 167.944038 -229.738428)
		(width 0.16002)
		(layer "In13.Cu")
		(net "M_H_CPU1_SA_DQS_DN<8>")
	)
	(segment
		(start 152.003506 -241.200686)
		(end 147.847558 -241.200686)
		(width 0.16002)
		(layer "In13.Cu")
		(net "M_H_CPU1_SA_DQS_DN<8>")
	)
	(segment
		(start 167.944038 -229.738428)
		(end 166.809928 -229.738428)
		(width 0.16002)
		(layer "In13.Cu")
		(net "M_H_CPU1_SA_DQS_DN<8>")
	)
	(segment
		(start 160.507934 -232.714038)
		(end 160.837626 -233.04373)
		(width 0.16002)
		(layer "In13.Cu")
		(net "M_H_CPU1_SA_DQS_DN<8>")
	)
	(segment
		(start 163.599368 -230.508048)
		(end 163.336986 -230.77043)
		(width 0.16002)
		(layer "In13.Cu")
		(net "M_H_CPU1_SA_DQS_DN<8>")
	)
	(segment
		(start 166.040308 -230.508048)
		(end 163.599368 -230.508048)
		(width 0.16002)
		(layer "In13.Cu")
		(net "M_H_CPU1_SA_DQS_DN<8>")
	)
	(segment
		(start 162.781234 -230.440738)
		(end 162.30473 -230.440738)
		(width 0.16002)
		(layer "In13.Cu")
		(net "M_H_CPU1_SA_DQS_DN<8>")
	)
	(segment
		(start 147.520914 -241.259868)
		(end 146.810476 -241.970306)
		(width 0.09525)
		(layer "In13.Cu")
		(net "M_H_CPU1_SA_DQS_DN<8>")
	)
	(segment
		(start 147.847558 -241.200686)
		(end 147.823936 -241.200686)
		(width 0.09525)
		(layer "In13.Cu")
		(net "M_H_CPU1_SA_DQS_DN<8>")
	)
	(segment
		(start 160.035494 -233.186478)
		(end 159.55899 -233.186478)
		(width 0.16002)
		(layer "In13.Cu")
		(net "M_H_CPU1_SA_DQS_DN<8>")
	)
	(segment
		(start 134.674102 -242.406678)
		(end 134.650734 -242.31981)
		(width 0.09525)
		(layer "In13.Cu")
		(net "M_H_CPU1_SA_DQS_DN<8>")
	)
	(segment
		(start 166.809928 -229.738428)
		(end 166.040308 -230.508048)
		(width 0.16002)
		(layer "In13.Cu")
		(net "M_H_CPU1_SA_DQS_DN<8>")
	)
	(segment
		(start 162.210496 -231.89692)
		(end 161.964116 -232.1433)
		(width 0.16002)
		(layer "In13.Cu")
		(net "M_H_CPU1_SA_DQS_DN<8>")
	)
	(segment
		(start 160.837626 -233.04373)
		(end 160.837626 -233.26979)
		(width 0.16002)
		(layer "In13.Cu")
		(net "M_H_CPU1_SA_DQS_DN<8>")
	)
	(segment
		(start 135.564626 -242.384326)
		(end 135.556244 -242.3795)
		(width 0.09525)
		(layer "In13.Cu")
		(net "M_H_CPU1_SA_DQS_DN<8>")
	)
	(segment
		(start 145.847816 -242.431316)
		(end 144.20596 -242.431316)
		(width 0.09525)
		(layer "In13.Cu")
		(net "M_H_CPU1_SA_DQS_DN<8>")
	)
	(segment
		(start 159.135064 -233.610404)
		(end 159.135064 -234.086908)
		(width 0.16002)
		(layer "In13.Cu")
		(net "M_H_CPU1_SA_DQS_DN<8>")
	)
	(segment
		(start 171.721526 -229.885748)
		(end 170.138852 -229.885748)
		(width 0.16002)
		(layer "In13.Cu")
		(net "M_H_CPU1_SA_DQS_DN<8>")
	)
	(segment
		(start 142.513304 -242.3795)
		(end 142.504922 -242.384326)
		(width 0.09525)
		(layer "In13.Cu")
		(net "M_H_CPU1_SA_DQS_DN<8>")
	)
	(segment
		(start 160.837626 -233.26979)
		(end 160.591246 -233.51617)
		(width 0.16002)
		(layer "In13.Cu")
		(net "M_H_CPU1_SA_DQS_DN<8>")
	)
	(segment
		(start 146.810476 -241.970306)
		(end 146.308826 -241.970306)
		(width 0.09525)
		(layer "In13.Cu")
		(net "M_H_CPU1_SA_DQS_DN<8>")
	)
	(segment
		(start 137.813288 -242.3795)
		(end 137.804906 -242.384326)
		(width 0.09525)
		(layer "In13.Cu")
		(net "M_H_CPU1_SA_DQS_DN<8>")
	)
	(segment
		(start 169.991532 -229.738428)
		(end 168.700958 -229.738428)
		(width 0.16002)
		(layer "In13.Cu")
		(net "M_H_CPU1_SA_DQS_DN<8>")
	)
	(segment
		(start 160.507934 -232.237534)
		(end 160.507934 -232.714038)
		(width 0.16002)
		(layer "In13.Cu")
		(net "M_H_CPU1_SA_DQS_DN<8>")
	)
	(segment
		(start 159.135064 -234.086908)
		(end 159.464756 -234.4166)
		(width 0.16002)
		(layer "In13.Cu")
		(net "M_H_CPU1_SA_DQS_DN<8>")
	)
	(arc
		(start 144.01673 -242.3795)
		(mid 143.743548 -242.303558)
		(end 143.46809 -242.370864)
		(width 0.09525)
		(layer "In13.Cu")
		(net "M_H_CPU1_SA_DQS_DN<8>")
	)
	(arc
		(start 143.453358 -242.3795)
		(mid 143.269583 -242.430272)
		(end 143.08455 -242.384326)
		(width 0.09525)
		(layer "In13.Cu")
		(net "M_H_CPU1_SA_DQS_DN<8>")
	)
	(arc
		(start 137.804906 -242.384326)
		(mid 137.619874 -242.43024)
		(end 137.436098 -242.3795)
		(width 0.09525)
		(layer "In13.Cu")
		(net "M_H_CPU1_SA_DQS_DN<8>")
	)
	(arc
		(start 144.20596 -242.431316)
		(mid 144.107926 -242.417915)
		(end 144.01673 -242.3795)
		(width 0.09525)
		(layer "In13.Cu")
		(net "M_H_CPU1_SA_DQS_DN<8>")
	)
	(arc
		(start 141.57325 -242.3795)
		(mid 141.384782 -242.430177)
		(end 141.196314 -242.3795)
		(width 0.09525)
		(layer "In13.Cu")
		(net "M_H_CPU1_SA_DQS_DN<8>")
	)
	(arc
		(start 136.496298 -242.3795)
		(mid 136.214866 -242.303745)
		(end 135.933434 -242.3795)
		(width 0.09525)
		(layer "In13.Cu")
		(net "M_H_CPU1_SA_DQS_DN<8>")
	)
	(arc
		(start 140.25626 -242.3795)
		(mid 139.974828 -242.303745)
		(end 139.693396 -242.3795)
		(width 0.09525)
		(layer "In13.Cu")
		(net "M_H_CPU1_SA_DQS_DN<8>")
	)
	(arc
		(start 136.873234 -242.3795)
		(mid 136.684766 -242.430177)
		(end 136.496298 -242.3795)
		(width 0.09525)
		(layer "In13.Cu")
		(net "M_H_CPU1_SA_DQS_DN<8>")
	)
	(arc
		(start 141.196314 -242.3795)
		(mid 140.914882 -242.303745)
		(end 140.63345 -242.3795)
		(width 0.09525)
		(layer "In13.Cu")
		(net "M_H_CPU1_SA_DQS_DN<8>")
	)
	(arc
		(start 135.933434 -242.3795)
		(mid 135.749659 -242.430272)
		(end 135.564626 -242.384326)
		(width 0.09525)
		(layer "In13.Cu")
		(net "M_H_CPU1_SA_DQS_DN<8>")
	)
	(arc
		(start 137.436098 -242.3795)
		(mid 137.154666 -242.303745)
		(end 136.873234 -242.3795)
		(width 0.09525)
		(layer "In13.Cu")
		(net "M_H_CPU1_SA_DQS_DN<8>")
	)
	(arc
		(start 139.693396 -242.3795)
		(mid 139.509621 -242.430272)
		(end 139.324588 -242.384326)
		(width 0.09525)
		(layer "In13.Cu")
		(net "M_H_CPU1_SA_DQS_DN<8>")
	)
	(arc
		(start 139.316206 -242.3795)
		(mid 139.034774 -242.303745)
		(end 138.753342 -242.3795)
		(width 0.09525)
		(layer "In13.Cu")
		(net "M_H_CPU1_SA_DQS_DN<8>")
	)
	(arc
		(start 134.99338 -242.3795)
		(mid 134.836782 -242.428789)
		(end 134.674102 -242.406678)
		(width 0.09525)
		(layer "In13.Cu")
		(net "M_H_CPU1_SA_DQS_DN<8>")
	)
	(arc
		(start 142.136114 -242.3795)
		(mid 141.854682 -242.303745)
		(end 141.57325 -242.3795)
		(width 0.09525)
		(layer "In13.Cu")
		(net "M_H_CPU1_SA_DQS_DN<8>")
	)
	(arc
		(start 140.63345 -242.3795)
		(mid 140.449675 -242.430272)
		(end 140.264642 -242.384326)
		(width 0.09525)
		(layer "In13.Cu")
		(net "M_H_CPU1_SA_DQS_DN<8>")
	)
	(arc
		(start 142.504922 -242.384326)
		(mid 142.31989 -242.43024)
		(end 142.136114 -242.3795)
		(width 0.09525)
		(layer "In13.Cu")
		(net "M_H_CPU1_SA_DQS_DN<8>")
	)
	(arc
		(start 143.076168 -242.3795)
		(mid 142.794736 -242.303745)
		(end 142.513304 -242.3795)
		(width 0.09525)
		(layer "In13.Cu")
		(net "M_H_CPU1_SA_DQS_DN<8>")
	)
	(arc
		(start 138.74496 -242.384326)
		(mid 138.559928 -242.43024)
		(end 138.376152 -242.3795)
		(width 0.09525)
		(layer "In13.Cu")
		(net "M_H_CPU1_SA_DQS_DN<8>")
	)
	(arc
		(start 138.376152 -242.3795)
		(mid 138.09472 -242.303745)
		(end 137.813288 -242.3795)
		(width 0.09525)
		(layer "In13.Cu")
		(net "M_H_CPU1_SA_DQS_DN<8>")
	)
	(arc
		(start 135.556244 -242.3795)
		(mid 135.274812 -242.303745)
		(end 134.99338 -242.3795)
		(width 0.09525)
		(layer "In13.Cu")
		(net "M_H_CPU1_SA_DQS_DN<8>")
	)
	(segment
		(start 134.337806 -237.460282)
		(end 134.804658 -237.194344)
		(width 0.12954)
		(layer "F.Cu")
		(net "M_H_CPU1_SA_DQS_DN<7>")
	)
	(segment
		(start 167.300148 -219.898214)
		(end 166.040308 -221.158054)
		(width 0.16002)
		(layer "In13.Cu")
		(net "M_H_CPU1_SA_DQS_DN<7>")
	)
	(segment
		(start 149.244812 -235.462064)
		(end 147.919186 -235.462064)
		(width 0.16002)
		(layer "In13.Cu")
		(net "M_H_CPU1_SA_DQS_DN<7>")
	)
	(segment
		(start 159.893762 -223.52635)
		(end 159.667702 -223.52635)
		(width 0.16002)
		(layer "In13.Cu")
		(net "M_H_CPU1_SA_DQS_DN<7>")
	)
	(segment
		(start 137.813288 -237.519464)
		(end 137.804906 -237.52429)
		(width 0.09525)
		(layer "In13.Cu")
		(net "M_H_CPU1_SA_DQS_DN<7>")
	)
	(segment
		(start 170.675554 -221.24543)
		(end 170.44924 -221.24543)
		(width 0.16002)
		(layer "In13.Cu")
		(net "M_H_CPU1_SA_DQS_DN<7>")
	)
	(segment
		(start 164.627052 -220.882718)
		(end 164.25418 -220.509846)
		(width 0.16002)
		(layer "In13.Cu")
		(net "M_H_CPU1_SA_DQS_DN<7>")
	)
	(segment
		(start 159.008572 -223.343724)
		(end 156.052774 -226.299522)
		(width 0.16002)
		(layer "In13.Cu")
		(net "M_H_CPU1_SA_DQS_DN<7>")
	)
	(segment
		(start 163.72713 -220.509846)
		(end 163.354258 -220.882718)
		(width 0.16002)
		(layer "In13.Cu")
		(net "M_H_CPU1_SA_DQS_DN<7>")
	)
	(segment
		(start 138.753342 -237.519464)
		(end 138.74496 -237.52429)
		(width 0.09525)
		(layer "In13.Cu")
		(net "M_H_CPU1_SA_DQS_DN<7>")
	)
	(segment
		(start 163.354258 -220.882718)
		(end 163.354258 -221.389194)
		(width 0.16002)
		(layer "In13.Cu")
		(net "M_H_CPU1_SA_DQS_DN<7>")
	)
	(segment
		(start 147.441666 -235.521246)
		(end 146.868896 -236.094016)
		(width 0.09525)
		(layer "In13.Cu")
		(net "M_H_CPU1_SA_DQS_DN<7>")
	)
	(segment
		(start 146.163538 -236.707426)
		(end 145.410428 -237.460282)
		(width 0.09525)
		(layer "In13.Cu")
		(net "M_H_CPU1_SA_DQS_DN<7>")
	)
	(segment
		(start 147.895564 -235.462064)
		(end 147.836382 -235.521246)
		(width 0.09525)
		(layer "In13.Cu")
		(net "M_H_CPU1_SA_DQS_DN<7>")
	)
	(segment
		(start 164.787072 -221.549214)
		(end 164.627052 -221.389194)
		(width 0.16002)
		(layer "In13.Cu")
		(net "M_H_CPU1_SA_DQS_DN<7>")
	)
	(segment
		(start 164.627052 -221.389194)
		(end 164.627052 -220.882718)
		(width 0.16002)
		(layer "In13.Cu")
		(net "M_H_CPU1_SA_DQS_DN<7>")
	)
	(segment
		(start 145.327116 -237.522766)
		(end 145.32102 -237.526322)
		(width 0.09525)
		(layer "In13.Cu")
		(net "M_H_CPU1_SA_DQS_DN<7>")
	)
	(segment
		(start 156.052774 -228.654102)
		(end 149.244812 -235.462064)
		(width 0.16002)
		(layer "In13.Cu")
		(net "M_H_CPU1_SA_DQS_DN<7>")
	)
	(segment
		(start 160.803082 -221.549214)
		(end 159.957516 -222.39478)
		(width 0.16002)
		(layer "In13.Cu")
		(net "M_H_CPU1_SA_DQS_DN<7>")
	)
	(segment
		(start 169.183812 -220.69933)
		(end 168.382696 -219.898214)
		(width 0.16002)
		(layer "In13.Cu")
		(net "M_H_CPU1_SA_DQS_DN<7>")
	)
	(segment
		(start 171.97197 -220.28531)
		(end 171.667932 -220.589348)
		(width 0.16002)
		(layer "In13.Cu")
		(net "M_H_CPU1_SA_DQS_DN<7>")
	)
	(segment
		(start 169.90314 -220.69933)
		(end 169.183812 -220.69933)
		(width 0.16002)
		(layer "In13.Cu")
		(net "M_H_CPU1_SA_DQS_DN<7>")
	)
	(segment
		(start 146.163538 -236.43971)
		(end 146.163538 -236.707426)
		(width 0.09525)
		(layer "In13.Cu")
		(net "M_H_CPU1_SA_DQS_DN<7>")
	)
	(segment
		(start 142.513304 -237.519464)
		(end 142.505938 -237.523782)
		(width 0.09525)
		(layer "In13.Cu")
		(net "M_H_CPU1_SA_DQS_DN<7>")
	)
	(segment
		(start 135.564626 -237.52429)
		(end 135.556244 -237.519464)
		(width 0.09525)
		(layer "In13.Cu")
		(net "M_H_CPU1_SA_DQS_DN<7>")
	)
	(segment
		(start 146.868896 -236.094016)
		(end 146.509232 -236.094016)
		(width 0.09525)
		(layer "In13.Cu")
		(net "M_H_CPU1_SA_DQS_DN<7>")
	)
	(segment
		(start 159.957516 -222.871284)
		(end 160.140142 -223.05391)
		(width 0.16002)
		(layer "In13.Cu")
		(net "M_H_CPU1_SA_DQS_DN<7>")
	)
	(segment
		(start 165.15588 -221.549214)
		(end 164.787072 -221.549214)
		(width 0.16002)
		(layer "In13.Cu")
		(net "M_H_CPU1_SA_DQS_DN<7>")
	)
	(segment
		(start 163.354258 -221.389194)
		(end 163.194238 -221.549214)
		(width 0.16002)
		(layer "In13.Cu")
		(net "M_H_CPU1_SA_DQS_DN<7>")
	)
	(segment
		(start 145.332958 -237.519464)
		(end 145.327116 -237.522766)
		(width 0.09525)
		(layer "In13.Cu")
		(net "M_H_CPU1_SA_DQS_DN<7>")
	)
	(segment
		(start 144.403318 -237.513368)
		(end 144.392904 -237.519464)
		(width 0.09525)
		(layer "In13.Cu")
		(net "M_H_CPU1_SA_DQS_DN<7>")
	)
	(segment
		(start 143.08455 -237.52429)
		(end 143.076168 -237.519464)
		(width 0.09525)
		(layer "In13.Cu")
		(net "M_H_CPU1_SA_DQS_DN<7>")
	)
	(segment
		(start 147.919186 -235.462064)
		(end 147.895564 -235.462064)
		(width 0.09525)
		(layer "In13.Cu")
		(net "M_H_CPU1_SA_DQS_DN<7>")
	)
	(segment
		(start 147.836382 -235.521246)
		(end 147.441666 -235.521246)
		(width 0.09525)
		(layer "In13.Cu")
		(net "M_H_CPU1_SA_DQS_DN<7>")
	)
	(segment
		(start 159.485076 -223.343724)
		(end 159.008572 -223.343724)
		(width 0.16002)
		(layer "In13.Cu")
		(net "M_H_CPU1_SA_DQS_DN<7>")
	)
	(segment
		(start 134.674102 -237.546642)
		(end 134.650734 -237.459774)
		(width 0.09525)
		(layer "In13.Cu")
		(net "M_H_CPU1_SA_DQS_DN<7>")
	)
	(segment
		(start 146.509232 -236.094016)
		(end 146.163538 -236.43971)
		(width 0.09525)
		(layer "In13.Cu")
		(net "M_H_CPU1_SA_DQS_DN<7>")
	)
	(segment
		(start 171.667932 -220.589348)
		(end 171.331636 -220.589348)
		(width 0.16002)
		(layer "In13.Cu")
		(net "M_H_CPU1_SA_DQS_DN<7>")
	)
	(segment
		(start 165.54704 -221.158054)
		(end 165.15588 -221.549214)
		(width 0.16002)
		(layer "In13.Cu")
		(net "M_H_CPU1_SA_DQS_DN<7>")
	)
	(segment
		(start 159.667702 -223.52635)
		(end 159.485076 -223.343724)
		(width 0.16002)
		(layer "In13.Cu")
		(net "M_H_CPU1_SA_DQS_DN<7>")
	)
	(segment
		(start 139.324588 -237.52429)
		(end 139.316206 -237.519464)
		(width 0.09525)
		(layer "In13.Cu")
		(net "M_H_CPU1_SA_DQS_DN<7>")
	)
	(segment
		(start 156.052774 -226.299522)
		(end 156.052774 -228.654102)
		(width 0.16002)
		(layer "In13.Cu")
		(net "M_H_CPU1_SA_DQS_DN<7>")
	)
	(segment
		(start 166.040308 -221.158054)
		(end 165.54704 -221.158054)
		(width 0.16002)
		(layer "In13.Cu")
		(net "M_H_CPU1_SA_DQS_DN<7>")
	)
	(segment
		(start 170.44924 -221.24543)
		(end 169.90314 -220.69933)
		(width 0.16002)
		(layer "In13.Cu")
		(net "M_H_CPU1_SA_DQS_DN<7>")
	)
	(segment
		(start 168.382696 -219.898214)
		(end 167.300148 -219.898214)
		(width 0.16002)
		(layer "In13.Cu")
		(net "M_H_CPU1_SA_DQS_DN<7>")
	)
	(segment
		(start 164.25418 -220.509846)
		(end 163.72713 -220.509846)
		(width 0.16002)
		(layer "In13.Cu")
		(net "M_H_CPU1_SA_DQS_DN<7>")
	)
	(segment
		(start 171.331636 -220.589348)
		(end 170.675554 -221.24543)
		(width 0.16002)
		(layer "In13.Cu")
		(net "M_H_CPU1_SA_DQS_DN<7>")
	)
	(segment
		(start 163.194238 -221.549214)
		(end 160.803082 -221.549214)
		(width 0.16002)
		(layer "In13.Cu")
		(net "M_H_CPU1_SA_DQS_DN<7>")
	)
	(segment
		(start 160.140142 -223.27997)
		(end 159.893762 -223.52635)
		(width 0.16002)
		(layer "In13.Cu")
		(net "M_H_CPU1_SA_DQS_DN<7>")
	)
	(segment
		(start 144.015968 -237.519464)
		(end 144.005554 -237.513368)
		(width 0.09525)
		(layer "In13.Cu")
		(net "M_H_CPU1_SA_DQS_DN<7>")
	)
	(segment
		(start 134.650734 -237.459774)
		(end 134.804658 -237.194344)
		(width 0.09525)
		(layer "In13.Cu")
		(net "M_H_CPU1_SA_DQS_DN<7>")
	)
	(segment
		(start 159.957516 -222.39478)
		(end 159.957516 -222.871284)
		(width 0.16002)
		(layer "In13.Cu")
		(net "M_H_CPU1_SA_DQS_DN<7>")
	)
	(segment
		(start 145.333212 -237.519718)
		(end 145.332958 -237.519464)
		(width 0.09525)
		(layer "In13.Cu")
		(net "M_H_CPU1_SA_DQS_DN<7>")
	)
	(segment
		(start 160.140142 -223.05391)
		(end 160.140142 -223.27997)
		(width 0.16002)
		(layer "In13.Cu")
		(net "M_H_CPU1_SA_DQS_DN<7>")
	)
	(segment
		(start 142.505938 -237.523782)
		(end 142.504922 -237.52429)
		(width 0.09525)
		(layer "In13.Cu")
		(net "M_H_CPU1_SA_DQS_DN<7>")
	)
	(segment
		(start 140.264642 -237.52429)
		(end 140.25626 -237.519464)
		(width 0.09525)
		(layer "In13.Cu")
		(net "M_H_CPU1_SA_DQS_DN<7>")
	)
	(arc
		(start 138.74496 -237.52429)
		(mid 138.559928 -237.570204)
		(end 138.376152 -237.519464)
		(width 0.09525)
		(layer "In13.Cu")
		(net "M_H_CPU1_SA_DQS_DN<7>")
	)
	(arc
		(start 143.453358 -237.519464)
		(mid 143.269583 -237.570236)
		(end 143.08455 -237.52429)
		(width 0.09525)
		(layer "In13.Cu")
		(net "M_H_CPU1_SA_DQS_DN<7>")
	)
	(arc
		(start 137.804906 -237.52429)
		(mid 137.619874 -237.570204)
		(end 137.436098 -237.519464)
		(width 0.09525)
		(layer "In13.Cu")
		(net "M_H_CPU1_SA_DQS_DN<7>")
	)
	(arc
		(start 141.57325 -237.519464)
		(mid 141.384782 -237.570141)
		(end 141.196314 -237.519464)
		(width 0.09525)
		(layer "In13.Cu")
		(net "M_H_CPU1_SA_DQS_DN<7>")
	)
	(arc
		(start 136.873234 -237.519464)
		(mid 136.684766 -237.570141)
		(end 136.496298 -237.519464)
		(width 0.09525)
		(layer "In13.Cu")
		(net "M_H_CPU1_SA_DQS_DN<7>")
	)
	(arc
		(start 142.136114 -237.519464)
		(mid 141.854682 -237.443709)
		(end 141.57325 -237.519464)
		(width 0.09525)
		(layer "In13.Cu")
		(net "M_H_CPU1_SA_DQS_DN<7>")
	)
	(arc
		(start 140.63345 -237.519464)
		(mid 140.449675 -237.570236)
		(end 140.264642 -237.52429)
		(width 0.09525)
		(layer "In13.Cu")
		(net "M_H_CPU1_SA_DQS_DN<7>")
	)
	(arc
		(start 139.693396 -237.519464)
		(mid 139.509621 -237.570236)
		(end 139.324588 -237.52429)
		(width 0.09525)
		(layer "In13.Cu")
		(net "M_H_CPU1_SA_DQS_DN<7>")
	)
	(arc
		(start 135.556244 -237.519464)
		(mid 135.274812 -237.443709)
		(end 134.99338 -237.519464)
		(width 0.09525)
		(layer "In13.Cu")
		(net "M_H_CPU1_SA_DQS_DN<7>")
	)
	(arc
		(start 144.956022 -237.519464)
		(mid 144.680479 -237.443615)
		(end 144.403318 -237.513368)
		(width 0.09525)
		(layer "In13.Cu")
		(net "M_H_CPU1_SA_DQS_DN<7>")
	)
	(arc
		(start 135.933434 -237.519464)
		(mid 135.749659 -237.570236)
		(end 135.564626 -237.52429)
		(width 0.09525)
		(layer "In13.Cu")
		(net "M_H_CPU1_SA_DQS_DN<7>")
	)
	(arc
		(start 137.436098 -237.519464)
		(mid 137.154666 -237.443709)
		(end 136.873234 -237.519464)
		(width 0.09525)
		(layer "In13.Cu")
		(net "M_H_CPU1_SA_DQS_DN<7>")
	)
	(arc
		(start 145.410428 -237.460282)
		(mid 145.373765 -237.492529)
		(end 145.333212 -237.519718)
		(width 0.09525)
		(layer "In13.Cu")
		(net "M_H_CPU1_SA_DQS_DN<7>")
	)
	(arc
		(start 136.496298 -237.519464)
		(mid 136.214866 -237.443709)
		(end 135.933434 -237.519464)
		(width 0.09525)
		(layer "In13.Cu")
		(net "M_H_CPU1_SA_DQS_DN<7>")
	)
	(arc
		(start 140.25626 -237.519464)
		(mid 139.974828 -237.443709)
		(end 139.693396 -237.519464)
		(width 0.09525)
		(layer "In13.Cu")
		(net "M_H_CPU1_SA_DQS_DN<7>")
	)
	(arc
		(start 144.392904 -237.519464)
		(mid 144.204436 -237.570141)
		(end 144.015968 -237.519464)
		(width 0.09525)
		(layer "In13.Cu")
		(net "M_H_CPU1_SA_DQS_DN<7>")
	)
	(arc
		(start 138.376152 -237.519464)
		(mid 138.09472 -237.443709)
		(end 137.813288 -237.519464)
		(width 0.09525)
		(layer "In13.Cu")
		(net "M_H_CPU1_SA_DQS_DN<7>")
	)
	(arc
		(start 142.504922 -237.52429)
		(mid 142.31989 -237.570204)
		(end 142.136114 -237.519464)
		(width 0.09525)
		(layer "In13.Cu")
		(net "M_H_CPU1_SA_DQS_DN<7>")
	)
	(arc
		(start 143.076168 -237.519464)
		(mid 142.794736 -237.443709)
		(end 142.513304 -237.519464)
		(width 0.09525)
		(layer "In13.Cu")
		(net "M_H_CPU1_SA_DQS_DN<7>")
	)
	(arc
		(start 139.316206 -237.519464)
		(mid 139.034774 -237.443709)
		(end 138.753342 -237.519464)
		(width 0.09525)
		(layer "In13.Cu")
		(net "M_H_CPU1_SA_DQS_DN<7>")
	)
	(arc
		(start 141.196314 -237.519464)
		(mid 140.914882 -237.443709)
		(end 140.63345 -237.519464)
		(width 0.09525)
		(layer "In13.Cu")
		(net "M_H_CPU1_SA_DQS_DN<7>")
	)
	(arc
		(start 134.99338 -237.519464)
		(mid 134.836782 -237.568753)
		(end 134.674102 -237.546642)
		(width 0.09525)
		(layer "In13.Cu")
		(net "M_H_CPU1_SA_DQS_DN<7>")
	)
	(arc
		(start 145.32102 -237.526322)
		(mid 145.137639 -237.570153)
		(end 144.956022 -237.519464)
		(width 0.09525)
		(layer "In13.Cu")
		(net "M_H_CPU1_SA_DQS_DN<7>")
	)
	(arc
		(start 144.005554 -237.513368)
		(mid 143.728646 -237.443691)
		(end 143.453358 -237.519464)
		(width 0.09525)
		(layer "In13.Cu")
		(net "M_H_CPU1_SA_DQS_DN<7>")
	)
	(segment
		(start 134.337806 -232.600246)
		(end 134.804658 -232.334308)
		(width 0.12954)
		(layer "F.Cu")
		(net "M_H_CPU1_SA_DQS_DN<6>")
	)
	(segment
		(start 140.264642 -232.664254)
		(end 140.25626 -232.659428)
		(width 0.09525)
		(layer "In13.Cu")
		(net "M_H_CPU1_SA_DQS_DN<6>")
	)
	(segment
		(start 162.87242 -212.422486)
		(end 162.52444 -212.422486)
		(width 0.16002)
		(layer "In13.Cu")
		(net "M_H_CPU1_SA_DQS_DN<6>")
	)
	(segment
		(start 143.08455 -232.664254)
		(end 143.076168 -232.659428)
		(width 0.09525)
		(layer "In13.Cu")
		(net "M_H_CPU1_SA_DQS_DN<6>")
	)
	(segment
		(start 171.690538 -211.216748)
		(end 170.16984 -211.216748)
		(width 0.16002)
		(layer "In13.Cu")
		(net "M_H_CPU1_SA_DQS_DN<6>")
	)
	(segment
		(start 147.671536 -228.639624)
		(end 147.671536 -228.722428)
		(width 0.09525)
		(layer "In13.Cu")
		(net "M_H_CPU1_SA_DQS_DN<6>")
	)
	(segment
		(start 146.102324 -230.588566)
		(end 144.107154 -232.583736)
		(width 0.09525)
		(layer "In13.Cu")
		(net "M_H_CPU1_SA_DQS_DN<6>")
	)
	(segment
		(start 150.515574 -225.795586)
		(end 147.6883 -228.62286)
		(width 0.16002)
		(layer "In13.Cu")
		(net "M_H_CPU1_SA_DQS_DN<6>")
	)
	(segment
		(start 165.613588 -211.80806)
		(end 164.999162 -212.422486)
		(width 0.16002)
		(layer "In13.Cu")
		(net "M_H_CPU1_SA_DQS_DN<6>")
	)
	(segment
		(start 147.6883 -228.62286)
		(end 147.671536 -228.639624)
		(width 0.09525)
		(layer "In13.Cu")
		(net "M_H_CPU1_SA_DQS_DN<6>")
	)
	(segment
		(start 134.650734 -232.599738)
		(end 134.804658 -232.334308)
		(width 0.09525)
		(layer "In13.Cu")
		(net "M_H_CPU1_SA_DQS_DN<6>")
	)
	(segment
		(start 137.813288 -232.659428)
		(end 137.804906 -232.664254)
		(width 0.09525)
		(layer "In13.Cu")
		(net "M_H_CPU1_SA_DQS_DN<6>")
	)
	(segment
		(start 166.809928 -211.03844)
		(end 166.040308 -211.80806)
		(width 0.16002)
		(layer "In13.Cu")
		(net "M_H_CPU1_SA_DQS_DN<6>")
	)
	(segment
		(start 135.564626 -232.664254)
		(end 135.556244 -232.659428)
		(width 0.09525)
		(layer "In13.Cu")
		(net "M_H_CPU1_SA_DQS_DN<6>")
	)
	(segment
		(start 164.30498 -212.262466)
		(end 164.30498 -211.476336)
		(width 0.16002)
		(layer "In13.Cu")
		(net "M_H_CPU1_SA_DQS_DN<6>")
	)
	(segment
		(start 139.324588 -232.664254)
		(end 139.316206 -232.659428)
		(width 0.09525)
		(layer "In13.Cu")
		(net "M_H_CPU1_SA_DQS_DN<6>")
	)
	(segment
		(start 147.671536 -228.722428)
		(end 147.088352 -229.305866)
		(width 0.09525)
		(layer "In13.Cu")
		(net "M_H_CPU1_SA_DQS_DN<6>")
	)
	(segment
		(start 162.52444 -212.422486)
		(end 162.36442 -212.262466)
		(width 0.16002)
		(layer "In13.Cu")
		(net "M_H_CPU1_SA_DQS_DN<6>")
	)
	(segment
		(start 144.107154 -232.583736)
		(end 143.73479 -232.583736)
		(width 0.09525)
		(layer "In13.Cu")
		(net "M_H_CPU1_SA_DQS_DN<6>")
	)
	(segment
		(start 162.027362 -211.139278)
		(end 161.428938 -211.139278)
		(width 0.16002)
		(layer "In13.Cu")
		(net "M_H_CPU1_SA_DQS_DN<6>")
	)
	(segment
		(start 162.36442 -212.262466)
		(end 162.36442 -211.476336)
		(width 0.16002)
		(layer "In13.Cu")
		(net "M_H_CPU1_SA_DQS_DN<6>")
	)
	(segment
		(start 162.36442 -211.476336)
		(end 162.027362 -211.139278)
		(width 0.16002)
		(layer "In13.Cu")
		(net "M_H_CPU1_SA_DQS_DN<6>")
	)
	(segment
		(start 146.75231 -229.305866)
		(end 146.102324 -229.955852)
		(width 0.09525)
		(layer "In13.Cu")
		(net "M_H_CPU1_SA_DQS_DN<6>")
	)
	(segment
		(start 163.03244 -211.476336)
		(end 163.03244 -212.262466)
		(width 0.16002)
		(layer "In13.Cu")
		(net "M_H_CPU1_SA_DQS_DN<6>")
	)
	(segment
		(start 164.30498 -211.476336)
		(end 163.967922 -211.139278)
		(width 0.16002)
		(layer "In13.Cu")
		(net "M_H_CPU1_SA_DQS_DN<6>")
	)
	(segment
		(start 171.97197 -210.935316)
		(end 171.690538 -211.216748)
		(width 0.16002)
		(layer "In13.Cu")
		(net "M_H_CPU1_SA_DQS_DN<6>")
	)
	(segment
		(start 146.102324 -229.955852)
		(end 146.102324 -230.588566)
		(width 0.09525)
		(layer "In13.Cu")
		(net "M_H_CPU1_SA_DQS_DN<6>")
	)
	(segment
		(start 147.088352 -229.305866)
		(end 146.75231 -229.305866)
		(width 0.09525)
		(layer "In13.Cu")
		(net "M_H_CPU1_SA_DQS_DN<6>")
	)
	(segment
		(start 161.09188 -212.262466)
		(end 160.93186 -212.422486)
		(width 0.16002)
		(layer "In13.Cu")
		(net "M_H_CPU1_SA_DQS_DN<6>")
	)
	(segment
		(start 142.513304 -232.659428)
		(end 142.504922 -232.664254)
		(width 0.09525)
		(layer "In13.Cu")
		(net "M_H_CPU1_SA_DQS_DN<6>")
	)
	(segment
		(start 138.753342 -232.659428)
		(end 138.74496 -232.664254)
		(width 0.09525)
		(layer "In13.Cu")
		(net "M_H_CPU1_SA_DQS_DN<6>")
	)
	(segment
		(start 161.09188 -211.476336)
		(end 161.09188 -212.262466)
		(width 0.16002)
		(layer "In13.Cu")
		(net "M_H_CPU1_SA_DQS_DN<6>")
	)
	(segment
		(start 161.428938 -211.139278)
		(end 161.09188 -211.476336)
		(width 0.16002)
		(layer "In13.Cu")
		(net "M_H_CPU1_SA_DQS_DN<6>")
	)
	(segment
		(start 160.435544 -212.422486)
		(end 150.515574 -222.342456)
		(width 0.16002)
		(layer "In13.Cu")
		(net "M_H_CPU1_SA_DQS_DN<6>")
	)
	(segment
		(start 166.040308 -211.80806)
		(end 165.613588 -211.80806)
		(width 0.16002)
		(layer "In13.Cu")
		(net "M_H_CPU1_SA_DQS_DN<6>")
	)
	(segment
		(start 134.674102 -232.686606)
		(end 134.650734 -232.599738)
		(width 0.09525)
		(layer "In13.Cu")
		(net "M_H_CPU1_SA_DQS_DN<6>")
	)
	(segment
		(start 163.03244 -212.262466)
		(end 162.87242 -212.422486)
		(width 0.16002)
		(layer "In13.Cu")
		(net "M_H_CPU1_SA_DQS_DN<6>")
	)
	(segment
		(start 170.16984 -211.216748)
		(end 169.991532 -211.03844)
		(width 0.16002)
		(layer "In13.Cu")
		(net "M_H_CPU1_SA_DQS_DN<6>")
	)
	(segment
		(start 169.991532 -211.03844)
		(end 166.809928 -211.03844)
		(width 0.16002)
		(layer "In13.Cu")
		(net "M_H_CPU1_SA_DQS_DN<6>")
	)
	(segment
		(start 163.369498 -211.139278)
		(end 163.03244 -211.476336)
		(width 0.16002)
		(layer "In13.Cu")
		(net "M_H_CPU1_SA_DQS_DN<6>")
	)
	(segment
		(start 150.515574 -222.342456)
		(end 150.515574 -225.795586)
		(width 0.16002)
		(layer "In13.Cu")
		(net "M_H_CPU1_SA_DQS_DN<6>")
	)
	(segment
		(start 164.465 -212.422486)
		(end 164.30498 -212.262466)
		(width 0.16002)
		(layer "In13.Cu")
		(net "M_H_CPU1_SA_DQS_DN<6>")
	)
	(segment
		(start 164.999162 -212.422486)
		(end 164.465 -212.422486)
		(width 0.16002)
		(layer "In13.Cu")
		(net "M_H_CPU1_SA_DQS_DN<6>")
	)
	(segment
		(start 163.967922 -211.139278)
		(end 163.369498 -211.139278)
		(width 0.16002)
		(layer "In13.Cu")
		(net "M_H_CPU1_SA_DQS_DN<6>")
	)
	(segment
		(start 160.93186 -212.422486)
		(end 160.435544 -212.422486)
		(width 0.16002)
		(layer "In13.Cu")
		(net "M_H_CPU1_SA_DQS_DN<6>")
	)
	(arc
		(start 135.933434 -232.659428)
		(mid 135.749659 -232.7102)
		(end 135.564626 -232.664254)
		(width 0.09525)
		(layer "In13.Cu")
		(net "M_H_CPU1_SA_DQS_DN<6>")
	)
	(arc
		(start 139.693396 -232.659428)
		(mid 139.509621 -232.7102)
		(end 139.324588 -232.664254)
		(width 0.09525)
		(layer "In13.Cu")
		(net "M_H_CPU1_SA_DQS_DN<6>")
	)
	(arc
		(start 136.873234 -232.659428)
		(mid 136.684766 -232.710105)
		(end 136.496298 -232.659428)
		(width 0.09525)
		(layer "In13.Cu")
		(net "M_H_CPU1_SA_DQS_DN<6>")
	)
	(arc
		(start 140.25626 -232.659428)
		(mid 139.974828 -232.583673)
		(end 139.693396 -232.659428)
		(width 0.09525)
		(layer "In13.Cu")
		(net "M_H_CPU1_SA_DQS_DN<6>")
	)
	(arc
		(start 139.316206 -232.659428)
		(mid 139.034774 -232.583673)
		(end 138.753342 -232.659428)
		(width 0.09525)
		(layer "In13.Cu")
		(net "M_H_CPU1_SA_DQS_DN<6>")
	)
	(arc
		(start 138.376152 -232.659428)
		(mid 138.09472 -232.583673)
		(end 137.813288 -232.659428)
		(width 0.09525)
		(layer "In13.Cu")
		(net "M_H_CPU1_SA_DQS_DN<6>")
	)
	(arc
		(start 138.74496 -232.664254)
		(mid 138.559928 -232.710168)
		(end 138.376152 -232.659428)
		(width 0.09525)
		(layer "In13.Cu")
		(net "M_H_CPU1_SA_DQS_DN<6>")
	)
	(arc
		(start 141.57325 -232.659428)
		(mid 141.384782 -232.710105)
		(end 141.196314 -232.659428)
		(width 0.09525)
		(layer "In13.Cu")
		(net "M_H_CPU1_SA_DQS_DN<6>")
	)
	(arc
		(start 143.453358 -232.659428)
		(mid 143.269583 -232.7102)
		(end 143.08455 -232.664254)
		(width 0.09525)
		(layer "In13.Cu")
		(net "M_H_CPU1_SA_DQS_DN<6>")
	)
	(arc
		(start 137.804906 -232.664254)
		(mid 137.619874 -232.710168)
		(end 137.436098 -232.659428)
		(width 0.09525)
		(layer "In13.Cu")
		(net "M_H_CPU1_SA_DQS_DN<6>")
	)
	(arc
		(start 141.196314 -232.659428)
		(mid 140.914882 -232.583673)
		(end 140.63345 -232.659428)
		(width 0.09525)
		(layer "In13.Cu")
		(net "M_H_CPU1_SA_DQS_DN<6>")
	)
	(arc
		(start 136.496298 -232.659428)
		(mid 136.214866 -232.583673)
		(end 135.933434 -232.659428)
		(width 0.09525)
		(layer "In13.Cu")
		(net "M_H_CPU1_SA_DQS_DN<6>")
	)
	(arc
		(start 142.504922 -232.664254)
		(mid 142.31989 -232.710168)
		(end 142.136114 -232.659428)
		(width 0.09525)
		(layer "In13.Cu")
		(net "M_H_CPU1_SA_DQS_DN<6>")
	)
	(arc
		(start 143.73479 -232.583736)
		(mid 143.589082 -232.603004)
		(end 143.453358 -232.659428)
		(width 0.09525)
		(layer "In13.Cu")
		(net "M_H_CPU1_SA_DQS_DN<6>")
	)
	(arc
		(start 143.076168 -232.659428)
		(mid 142.794736 -232.583673)
		(end 142.513304 -232.659428)
		(width 0.09525)
		(layer "In13.Cu")
		(net "M_H_CPU1_SA_DQS_DN<6>")
	)
	(arc
		(start 135.556244 -232.659428)
		(mid 135.274812 -232.583673)
		(end 134.99338 -232.659428)
		(width 0.09525)
		(layer "In13.Cu")
		(net "M_H_CPU1_SA_DQS_DN<6>")
	)
	(arc
		(start 137.436098 -232.659428)
		(mid 137.154666 -232.583673)
		(end 136.873234 -232.659428)
		(width 0.09525)
		(layer "In13.Cu")
		(net "M_H_CPU1_SA_DQS_DN<6>")
	)
	(arc
		(start 134.99338 -232.659428)
		(mid 134.836782 -232.708717)
		(end 134.674102 -232.686606)
		(width 0.09525)
		(layer "In13.Cu")
		(net "M_H_CPU1_SA_DQS_DN<6>")
	)
	(arc
		(start 140.63345 -232.659428)
		(mid 140.449675 -232.7102)
		(end 140.264642 -232.664254)
		(width 0.09525)
		(layer "In13.Cu")
		(net "M_H_CPU1_SA_DQS_DN<6>")
	)
	(arc
		(start 142.136114 -232.659428)
		(mid 141.854682 -232.583673)
		(end 141.57325 -232.659428)
		(width 0.09525)
		(layer "In13.Cu")
		(net "M_H_CPU1_SA_DQS_DN<6>")
	)
	(segment
		(start 134.337806 -227.740464)
		(end 134.804658 -227.474526)
		(width 0.12954)
		(layer "F.Cu")
		(net "M_H_CPU1_SA_DQS_DN<5>")
	)
	(segment
		(start 144.422622 -222.922846)
		(end 144.393412 -222.93961)
		(width 0.09525)
		(layer "In13.Cu")
		(net "M_H_CPU1_SA_DQS_DN<5>")
	)
	(segment
		(start 156.58465 -206.370174)
		(end 156.108146 -206.370174)
		(width 0.16002)
		(layer "In13.Cu")
		(net "M_H_CPU1_SA_DQS_DN<5>")
	)
	(segment
		(start 156.69514 -206.480664)
		(end 156.58465 -206.370174)
		(width 0.16002)
		(layer "In13.Cu")
		(net "M_H_CPU1_SA_DQS_DN<5>")
	)
	(segment
		(start 144.976088 -221.35719)
		(end 144.978374 -221.359476)
		(width 0.16002)
		(layer "In13.Cu")
		(net "M_H_CPU1_SA_DQS_DN<5>")
	)
	(segment
		(start 145.037556 -221.698312)
		(end 145.08353 -221.744286)
		(width 0.09525)
		(layer "In13.Cu")
		(net "M_H_CPU1_SA_DQS_DN<5>")
	)
	(segment
		(start 159.33039 -203.624434)
		(end 158.853886 -203.624434)
		(width 0.16002)
		(layer "In13.Cu")
		(net "M_H_CPU1_SA_DQS_DN<5>")
	)
	(segment
		(start 157.05709 -205.42123)
		(end 157.05709 -205.897734)
		(width 0.16002)
		(layer "In13.Cu")
		(net "M_H_CPU1_SA_DQS_DN<5>")
	)
	(segment
		(start 134.674102 -227.826824)
		(end 134.650734 -227.739956)
		(width 0.09525)
		(layer "In13.Cu")
		(net "M_H_CPU1_SA_DQS_DN<5>")
	)
	(segment
		(start 158.06801 -205.107794)
		(end 157.95752 -204.997304)
		(width 0.16002)
		(layer "In13.Cu")
		(net "M_H_CPU1_SA_DQS_DN<5>")
	)
	(segment
		(start 137.813288 -227.799646)
		(end 137.804906 -227.804472)
		(width 0.09525)
		(layer "In13.Cu")
		(net "M_H_CPU1_SA_DQS_DN<5>")
	)
	(segment
		(start 155.79471 -207.381094)
		(end 155.79471 -207.607154)
		(width 0.16002)
		(layer "In13.Cu")
		(net "M_H_CPU1_SA_DQS_DN<5>")
	)
	(segment
		(start 145.08353 -221.744286)
		(end 145.08353 -221.901004)
		(width 0.09525)
		(layer "In13.Cu")
		(net "M_H_CPU1_SA_DQS_DN<5>")
	)
	(segment
		(start 171.687744 -201.869548)
		(end 170.172634 -201.869548)
		(width 0.16002)
		(layer "In13.Cu")
		(net "M_H_CPU1_SA_DQS_DN<5>")
	)
	(segment
		(start 155.54833 -207.853534)
		(end 155.32227 -207.853534)
		(width 0.16002)
		(layer "In13.Cu")
		(net "M_H_CPU1_SA_DQS_DN<5>")
	)
	(segment
		(start 153.9494 -209.226404)
		(end 153.83891 -209.115914)
		(width 0.16002)
		(layer "In13.Cu")
		(net "M_H_CPU1_SA_DQS_DN<5>")
	)
	(segment
		(start 155.21178 -207.743044)
		(end 154.735276 -207.743044)
		(width 0.16002)
		(layer "In13.Cu")
		(net "M_H_CPU1_SA_DQS_DN<5>")
	)
	(segment
		(start 142.513304 -226.179634)
		(end 142.475204 -226.201732)
		(width 0.09525)
		(layer "In13.Cu")
		(net "M_H_CPU1_SA_DQS_DN<5>")
	)
	(segment
		(start 157.05709 -205.897734)
		(end 157.16758 -206.008224)
		(width 0.16002)
		(layer "In13.Cu")
		(net "M_H_CPU1_SA_DQS_DN<5>")
	)
	(segment
		(start 138.753342 -227.799646)
		(end 138.74496 -227.804472)
		(width 0.09525)
		(layer "In13.Cu")
		(net "M_H_CPU1_SA_DQS_DN<5>")
	)
	(segment
		(start 155.32227 -207.853534)
		(end 155.21178 -207.743044)
		(width 0.16002)
		(layer "In13.Cu")
		(net "M_H_CPU1_SA_DQS_DN<5>")
	)
	(segment
		(start 166.809928 -201.688446)
		(end 166.040308 -202.458066)
		(width 0.16002)
		(layer "In13.Cu")
		(net "M_H_CPU1_SA_DQS_DN<5>")
	)
	(segment
		(start 141.605762 -227.78085)
		(end 141.57325 -227.799646)
		(width 0.09525)
		(layer "In13.Cu")
		(net "M_H_CPU1_SA_DQS_DN<5>")
	)
	(segment
		(start 139.324588 -227.804472)
		(end 139.316206 -227.799646)
		(width 0.09525)
		(layer "In13.Cu")
		(net "M_H_CPU1_SA_DQS_DN<5>")
	)
	(segment
		(start 157.16758 -206.234284)
		(end 156.9212 -206.480664)
		(width 0.16002)
		(layer "In13.Cu")
		(net "M_H_CPU1_SA_DQS_DN<5>")
	)
	(segment
		(start 151.6761 -211.725764)
		(end 144.976088 -218.425776)
		(width 0.16002)
		(layer "In13.Cu")
		(net "M_H_CPU1_SA_DQS_DN<5>")
	)
	(segment
		(start 158.42996 -204.524864)
		(end 158.54045 -204.635354)
		(width 0.16002)
		(layer "In13.Cu")
		(net "M_H_CPU1_SA_DQS_DN<5>")
	)
	(segment
		(start 143.453358 -224.559622)
		(end 143.415258 -224.58172)
		(width 0.09525)
		(layer "In13.Cu")
		(net "M_H_CPU1_SA_DQS_DN<5>")
	)
	(segment
		(start 142.545816 -226.160838)
		(end 142.513304 -226.179634)
		(width 0.09525)
		(layer "In13.Cu")
		(net "M_H_CPU1_SA_DQS_DN<5>")
	)
	(segment
		(start 157.95752 -204.997304)
		(end 157.481016 -204.997304)
		(width 0.16002)
		(layer "In13.Cu")
		(net "M_H_CPU1_SA_DQS_DN<5>")
	)
	(segment
		(start 154.17546 -209.226404)
		(end 153.9494 -209.226404)
		(width 0.16002)
		(layer "In13.Cu")
		(net "M_H_CPU1_SA_DQS_DN<5>")
	)
	(segment
		(start 158.42996 -204.04836)
		(end 158.42996 -204.524864)
		(width 0.16002)
		(layer "In13.Cu")
		(net "M_H_CPU1_SA_DQS_DN<5>")
	)
	(segment
		(start 153.362406 -209.115914)
		(end 152.93848 -209.53984)
		(width 0.16002)
		(layer "In13.Cu")
		(net "M_H_CPU1_SA_DQS_DN<5>")
	)
	(segment
		(start 171.97197 -201.585322)
		(end 171.687744 -201.869548)
		(width 0.16002)
		(layer "In13.Cu")
		(net "M_H_CPU1_SA_DQS_DN<5>")
	)
	(segment
		(start 142.043404 -226.98964)
		(end 142.005304 -227.011738)
		(width 0.09525)
		(layer "In13.Cu")
		(net "M_H_CPU1_SA_DQS_DN<5>")
	)
	(segment
		(start 144.393412 -222.93961)
		(end 144.355312 -222.961708)
		(width 0.09525)
		(layer "In13.Cu")
		(net "M_H_CPU1_SA_DQS_DN<5>")
	)
	(segment
		(start 158.54045 -204.861414)
		(end 158.29407 -205.107794)
		(width 0.16002)
		(layer "In13.Cu")
		(net "M_H_CPU1_SA_DQS_DN<5>")
	)
	(segment
		(start 154.31135 -208.16697)
		(end 154.31135 -208.643474)
		(width 0.16002)
		(layer "In13.Cu")
		(net "M_H_CPU1_SA_DQS_DN<5>")
	)
	(segment
		(start 143.95577 -223.73082)
		(end 143.923258 -223.749616)
		(width 0.09525)
		(layer "In13.Cu")
		(net "M_H_CPU1_SA_DQS_DN<5>")
	)
	(segment
		(start 145.08353 -221.901004)
		(end 144.848834 -222.1357)
		(width 0.09525)
		(layer "In13.Cu")
		(net "M_H_CPU1_SA_DQS_DN<5>")
	)
	(segment
		(start 157.16758 -206.008224)
		(end 157.16758 -206.234284)
		(width 0.16002)
		(layer "In13.Cu")
		(net "M_H_CPU1_SA_DQS_DN<5>")
	)
	(segment
		(start 155.68422 -206.7941)
		(end 155.68422 -207.270604)
		(width 0.16002)
		(layer "In13.Cu")
		(net "M_H_CPU1_SA_DQS_DN<5>")
	)
	(segment
		(start 144.978374 -221.359476)
		(end 144.978374 -221.383098)
		(width 0.09525)
		(layer "In13.Cu")
		(net "M_H_CPU1_SA_DQS_DN<5>")
	)
	(segment
		(start 144.582388 -222.61449)
		(end 144.582134 -222.61449)
		(width 0.09525)
		(layer "In13.Cu")
		(net "M_H_CPU1_SA_DQS_DN<5>")
	)
	(segment
		(start 170.172634 -201.869548)
		(end 169.991532 -201.688446)
		(width 0.16002)
		(layer "In13.Cu")
		(net "M_H_CPU1_SA_DQS_DN<5>")
	)
	(segment
		(start 145.037556 -221.44228)
		(end 145.037556 -221.698312)
		(width 0.09525)
		(layer "In13.Cu")
		(net "M_H_CPU1_SA_DQS_DN<5>")
	)
	(segment
		(start 158.853886 -203.624434)
		(end 158.42996 -204.04836)
		(width 0.16002)
		(layer "In13.Cu")
		(net "M_H_CPU1_SA_DQS_DN<5>")
	)
	(segment
		(start 153.04897 -210.352894)
		(end 152.80259 -210.599274)
		(width 0.16002)
		(layer "In13.Cu")
		(net "M_H_CPU1_SA_DQS_DN<5>")
	)
	(segment
		(start 158.54045 -204.635354)
		(end 158.54045 -204.861414)
		(width 0.16002)
		(layer "In13.Cu")
		(net "M_H_CPU1_SA_DQS_DN<5>")
	)
	(segment
		(start 157.481016 -204.997304)
		(end 157.05709 -205.42123)
		(width 0.16002)
		(layer "In13.Cu")
		(net "M_H_CPU1_SA_DQS_DN<5>")
	)
	(segment
		(start 156.9212 -206.480664)
		(end 156.69514 -206.480664)
		(width 0.16002)
		(layer "In13.Cu")
		(net "M_H_CPU1_SA_DQS_DN<5>")
	)
	(segment
		(start 143.484854 -224.541334)
		(end 143.453358 -224.559622)
		(width 0.09525)
		(layer "In13.Cu")
		(net "M_H_CPU1_SA_DQS_DN<5>")
	)
	(segment
		(start 153.83891 -209.115914)
		(end 153.362406 -209.115914)
		(width 0.16002)
		(layer "In13.Cu")
		(net "M_H_CPU1_SA_DQS_DN<5>")
	)
	(segment
		(start 134.650734 -227.739956)
		(end 134.804658 -227.474526)
		(width 0.09525)
		(layer "In13.Cu")
		(net "M_H_CPU1_SA_DQS_DN<5>")
	)
	(segment
		(start 166.040308 -202.458066)
		(end 160.943798 -202.458066)
		(width 0.16002)
		(layer "In13.Cu")
		(net "M_H_CPU1_SA_DQS_DN<5>")
	)
	(segment
		(start 142.983204 -225.369628)
		(end 142.948152 -225.390202)
		(width 0.09525)
		(layer "In13.Cu")
		(net "M_H_CPU1_SA_DQS_DN<5>")
	)
	(segment
		(start 160.943798 -202.458066)
		(end 159.66694 -203.734924)
		(width 0.16002)
		(layer "In13.Cu")
		(net "M_H_CPU1_SA_DQS_DN<5>")
	)
	(segment
		(start 155.79471 -207.607154)
		(end 155.54833 -207.853534)
		(width 0.16002)
		(layer "In13.Cu")
		(net "M_H_CPU1_SA_DQS_DN<5>")
	)
	(segment
		(start 159.66694 -203.734924)
		(end 159.44088 -203.734924)
		(width 0.16002)
		(layer "In13.Cu")
		(net "M_H_CPU1_SA_DQS_DN<5>")
	)
	(segment
		(start 143.015716 -225.350832)
		(end 142.983204 -225.369628)
		(width 0.09525)
		(layer "In13.Cu")
		(net "M_H_CPU1_SA_DQS_DN<5>")
	)
	(segment
		(start 159.44088 -203.734924)
		(end 159.33039 -203.624434)
		(width 0.16002)
		(layer "In13.Cu")
		(net "M_H_CPU1_SA_DQS_DN<5>")
	)
	(segment
		(start 143.923258 -223.749616)
		(end 143.885158 -223.771714)
		(width 0.09525)
		(layer "In13.Cu")
		(net "M_H_CPU1_SA_DQS_DN<5>")
	)
	(segment
		(start 151.989536 -210.488784)
		(end 151.56561 -210.91271)
		(width 0.16002)
		(layer "In13.Cu")
		(net "M_H_CPU1_SA_DQS_DN<5>")
	)
	(segment
		(start 144.848834 -222.1357)
		(end 144.824958 -222.15221)
		(width 0.09525)
		(layer "In13.Cu")
		(net "M_H_CPU1_SA_DQS_DN<5>")
	)
	(segment
		(start 152.80259 -210.599274)
		(end 152.57653 -210.599274)
		(width 0.16002)
		(layer "In13.Cu")
		(net "M_H_CPU1_SA_DQS_DN<5>")
	)
	(segment
		(start 154.42184 -208.753964)
		(end 154.42184 -208.980024)
		(width 0.16002)
		(layer "In13.Cu")
		(net "M_H_CPU1_SA_DQS_DN<5>")
	)
	(segment
		(start 151.56561 -210.91271)
		(end 151.56561 -211.389214)
		(width 0.16002)
		(layer "In13.Cu")
		(net "M_H_CPU1_SA_DQS_DN<5>")
	)
	(segment
		(start 169.991532 -201.688446)
		(end 166.809928 -201.688446)
		(width 0.16002)
		(layer "In13.Cu")
		(net "M_H_CPU1_SA_DQS_DN<5>")
	)
	(segment
		(start 142.0749 -226.971352)
		(end 142.043404 -226.98964)
		(width 0.09525)
		(layer "In13.Cu")
		(net "M_H_CPU1_SA_DQS_DN<5>")
	)
	(segment
		(start 153.04897 -210.126834)
		(end 153.04897 -210.352894)
		(width 0.16002)
		(layer "In13.Cu")
		(net "M_H_CPU1_SA_DQS_DN<5>")
	)
	(segment
		(start 154.735276 -207.743044)
		(end 154.31135 -208.16697)
		(width 0.16002)
		(layer "In13.Cu")
		(net "M_H_CPU1_SA_DQS_DN<5>")
	)
	(segment
		(start 135.564626 -227.804472)
		(end 135.556244 -227.799646)
		(width 0.09525)
		(layer "In13.Cu")
		(net "M_H_CPU1_SA_DQS_DN<5>")
	)
	(segment
		(start 144.976088 -218.425776)
		(end 144.976088 -221.35719)
		(width 0.16002)
		(layer "In13.Cu")
		(net "M_H_CPU1_SA_DQS_DN<5>")
	)
	(segment
		(start 152.93848 -209.53984)
		(end 152.93848 -210.016344)
		(width 0.16002)
		(layer "In13.Cu")
		(net "M_H_CPU1_SA_DQS_DN<5>")
	)
	(segment
		(start 152.46604 -210.488784)
		(end 151.989536 -210.488784)
		(width 0.16002)
		(layer "In13.Cu")
		(net "M_H_CPU1_SA_DQS_DN<5>")
	)
	(segment
		(start 144.978374 -221.383098)
		(end 145.037556 -221.44228)
		(width 0.09525)
		(layer "In13.Cu")
		(net "M_H_CPU1_SA_DQS_DN<5>")
	)
	(segment
		(start 156.108146 -206.370174)
		(end 155.68422 -206.7941)
		(width 0.16002)
		(layer "In13.Cu")
		(net "M_H_CPU1_SA_DQS_DN<5>")
	)
	(segment
		(start 154.42184 -208.980024)
		(end 154.17546 -209.226404)
		(width 0.16002)
		(layer "In13.Cu")
		(net "M_H_CPU1_SA_DQS_DN<5>")
	)
	(segment
		(start 158.29407 -205.107794)
		(end 158.06801 -205.107794)
		(width 0.16002)
		(layer "In13.Cu")
		(net "M_H_CPU1_SA_DQS_DN<5>")
	)
	(segment
		(start 155.68422 -207.270604)
		(end 155.79471 -207.381094)
		(width 0.16002)
		(layer "In13.Cu")
		(net "M_H_CPU1_SA_DQS_DN<5>")
	)
	(segment
		(start 154.31135 -208.643474)
		(end 154.42184 -208.753964)
		(width 0.16002)
		(layer "In13.Cu")
		(net "M_H_CPU1_SA_DQS_DN<5>")
	)
	(segment
		(start 151.6761 -211.499704)
		(end 151.6761 -211.725764)
		(width 0.16002)
		(layer "In13.Cu")
		(net "M_H_CPU1_SA_DQS_DN<5>")
	)
	(segment
		(start 152.57653 -210.599274)
		(end 152.46604 -210.488784)
		(width 0.16002)
		(layer "In13.Cu")
		(net "M_H_CPU1_SA_DQS_DN<5>")
	)
	(segment
		(start 151.56561 -211.389214)
		(end 151.6761 -211.499704)
		(width 0.16002)
		(layer "In13.Cu")
		(net "M_H_CPU1_SA_DQS_DN<5>")
	)
	(segment
		(start 152.93848 -210.016344)
		(end 153.04897 -210.126834)
		(width 0.16002)
		(layer "In13.Cu")
		(net "M_H_CPU1_SA_DQS_DN<5>")
	)
	(segment
		(start 140.264642 -227.804472)
		(end 140.25626 -227.799646)
		(width 0.09525)
		(layer "In13.Cu")
		(net "M_H_CPU1_SA_DQS_DN<5>")
	)
	(arc
		(start 139.316206 -227.799646)
		(mid 139.034774 -227.723891)
		(end 138.753342 -227.799646)
		(width 0.09525)
		(layer "In13.Cu")
		(net "M_H_CPU1_SA_DQS_DN<5>")
	)
	(arc
		(start 140.25626 -227.799646)
		(mid 139.974828 -227.723891)
		(end 139.693396 -227.799646)
		(width 0.09525)
		(layer "In13.Cu")
		(net "M_H_CPU1_SA_DQS_DN<5>")
	)
	(arc
		(start 136.496298 -227.799646)
		(mid 136.214866 -227.723891)
		(end 135.933434 -227.799646)
		(width 0.09525)
		(layer "In13.Cu")
		(net "M_H_CPU1_SA_DQS_DN<5>")
	)
	(arc
		(start 135.556244 -227.799646)
		(mid 135.274812 -227.723891)
		(end 134.99338 -227.799646)
		(width 0.09525)
		(layer "In13.Cu")
		(net "M_H_CPU1_SA_DQS_DN<5>")
	)
	(arc
		(start 138.74496 -227.804472)
		(mid 138.559928 -227.850386)
		(end 138.376152 -227.799646)
		(width 0.09525)
		(layer "In13.Cu")
		(net "M_H_CPU1_SA_DQS_DN<5>")
	)
	(arc
		(start 144.112488 -223.424496)
		(mid 144.071031 -223.596536)
		(end 143.95577 -223.73082)
		(width 0.09525)
		(layer "In13.Cu")
		(net "M_H_CPU1_SA_DQS_DN<5>")
	)
	(arc
		(start 139.693396 -227.799646)
		(mid 139.509621 -227.850418)
		(end 139.324588 -227.804472)
		(width 0.09525)
		(layer "In13.Cu")
		(net "M_H_CPU1_SA_DQS_DN<5>")
	)
	(arc
		(start 144.824958 -222.15221)
		(mid 144.646733 -222.353468)
		(end 144.582388 -222.61449)
		(width 0.09525)
		(layer "In13.Cu")
		(net "M_H_CPU1_SA_DQS_DN<5>")
	)
	(arc
		(start 143.172434 -225.044508)
		(mid 143.130977 -225.216548)
		(end 143.015716 -225.350832)
		(width 0.09525)
		(layer "In13.Cu")
		(net "M_H_CPU1_SA_DQS_DN<5>")
	)
	(arc
		(start 143.642334 -224.234502)
		(mid 143.600669 -224.406949)
		(end 143.484854 -224.541334)
		(width 0.09525)
		(layer "In13.Cu")
		(net "M_H_CPU1_SA_DQS_DN<5>")
	)
	(arc
		(start 140.63345 -227.799646)
		(mid 140.449675 -227.850418)
		(end 140.264642 -227.804472)
		(width 0.09525)
		(layer "In13.Cu")
		(net "M_H_CPU1_SA_DQS_DN<5>")
	)
	(arc
		(start 143.415258 -224.58172)
		(mid 143.236808 -224.78319)
		(end 143.172434 -225.044508)
		(width 0.09525)
		(layer "In13.Cu")
		(net "M_H_CPU1_SA_DQS_DN<5>")
	)
	(arc
		(start 142.23238 -226.66452)
		(mid 142.190715 -226.836967)
		(end 142.0749 -226.971352)
		(width 0.09525)
		(layer "In13.Cu")
		(net "M_H_CPU1_SA_DQS_DN<5>")
	)
	(arc
		(start 137.804906 -227.804472)
		(mid 137.619874 -227.850386)
		(end 137.436098 -227.799646)
		(width 0.09525)
		(layer "In13.Cu")
		(net "M_H_CPU1_SA_DQS_DN<5>")
	)
	(arc
		(start 135.933434 -227.799646)
		(mid 135.749659 -227.850418)
		(end 135.564626 -227.804472)
		(width 0.09525)
		(layer "In13.Cu")
		(net "M_H_CPU1_SA_DQS_DN<5>")
	)
	(arc
		(start 144.355312 -222.961708)
		(mid 144.176862 -223.163178)
		(end 144.112488 -223.424496)
		(width 0.09525)
		(layer "In13.Cu")
		(net "M_H_CPU1_SA_DQS_DN<5>")
	)
	(arc
		(start 142.948152 -225.390202)
		(mid 142.767761 -225.591901)
		(end 142.702534 -225.854514)
		(width 0.09525)
		(layer "In13.Cu")
		(net "M_H_CPU1_SA_DQS_DN<5>")
	)
	(arc
		(start 136.873234 -227.799646)
		(mid 136.684766 -227.850323)
		(end 136.496298 -227.799646)
		(width 0.09525)
		(layer "In13.Cu")
		(net "M_H_CPU1_SA_DQS_DN<5>")
	)
	(arc
		(start 143.885158 -223.771714)
		(mid 143.706708 -223.973184)
		(end 143.642334 -224.234502)
		(width 0.09525)
		(layer "In13.Cu")
		(net "M_H_CPU1_SA_DQS_DN<5>")
	)
	(arc
		(start 141.57325 -227.799646)
		(mid 141.384782 -227.850323)
		(end 141.196314 -227.799646)
		(width 0.09525)
		(layer "In13.Cu")
		(net "M_H_CPU1_SA_DQS_DN<5>")
	)
	(arc
		(start 141.196314 -227.799646)
		(mid 140.914882 -227.723891)
		(end 140.63345 -227.799646)
		(width 0.09525)
		(layer "In13.Cu")
		(net "M_H_CPU1_SA_DQS_DN<5>")
	)
	(arc
		(start 142.702534 -225.854514)
		(mid 142.661077 -226.026554)
		(end 142.545816 -226.160838)
		(width 0.09525)
		(layer "In13.Cu")
		(net "M_H_CPU1_SA_DQS_DN<5>")
	)
	(arc
		(start 144.582134 -222.61449)
		(mid 144.539887 -222.788065)
		(end 144.422622 -222.922846)
		(width 0.09525)
		(layer "In13.Cu")
		(net "M_H_CPU1_SA_DQS_DN<5>")
	)
	(arc
		(start 141.76248 -227.474526)
		(mid 141.721023 -227.646566)
		(end 141.605762 -227.78085)
		(width 0.09525)
		(layer "In13.Cu")
		(net "M_H_CPU1_SA_DQS_DN<5>")
	)
	(arc
		(start 137.436098 -227.799646)
		(mid 137.154666 -227.723891)
		(end 136.873234 -227.799646)
		(width 0.09525)
		(layer "In13.Cu")
		(net "M_H_CPU1_SA_DQS_DN<5>")
	)
	(arc
		(start 138.376152 -227.799646)
		(mid 138.09472 -227.723891)
		(end 137.813288 -227.799646)
		(width 0.09525)
		(layer "In13.Cu")
		(net "M_H_CPU1_SA_DQS_DN<5>")
	)
	(arc
		(start 134.99338 -227.799646)
		(mid 134.836782 -227.848935)
		(end 134.674102 -227.826824)
		(width 0.09525)
		(layer "In13.Cu")
		(net "M_H_CPU1_SA_DQS_DN<5>")
	)
	(arc
		(start 142.005304 -227.011738)
		(mid 141.826854 -227.213208)
		(end 141.76248 -227.474526)
		(width 0.09525)
		(layer "In13.Cu")
		(net "M_H_CPU1_SA_DQS_DN<5>")
	)
	(arc
		(start 142.475204 -226.201732)
		(mid 142.296754 -226.403202)
		(end 142.23238 -226.66452)
		(width 0.09525)
		(layer "In13.Cu")
		(net "M_H_CPU1_SA_DQS_DN<5>")
	)
	(segment
		(start 135.27786 -247.180354)
		(end 135.744712 -246.914416)
		(width 0.12954)
		(layer "F.Cu")
		(net "M_H_CPU1_SA_DQS_DN<4>")
	)
	(segment
		(start 176.072038 -238.985298)
		(end 175.834548 -238.747808)
		(width 0.16002)
		(layer "In13.Cu")
		(net "M_H_CPU1_SA_DQS_DN<4>")
	)
	(segment
		(start 172.799248 -238.918242)
		(end 172.443394 -238.562388)
		(width 0.16002)
		(layer "In13.Cu")
		(net "M_H_CPU1_SA_DQS_DN<4>")
	)
	(segment
		(start 135.898636 -246.648986)
		(end 135.744712 -246.914416)
		(width 0.09525)
		(layer "In13.Cu")
		(net "M_H_CPU1_SA_DQS_DN<4>")
	)
	(segment
		(start 144.971008 -246.580914)
		(end 144.941798 -246.597932)
		(width 0.09525)
		(layer "In13.Cu")
		(net "M_H_CPU1_SA_DQS_DN<4>")
	)
	(segment
		(start 143.463772 -246.595392)
		(end 143.453358 -246.589296)
		(width 0.09525)
		(layer "In13.Cu")
		(net "M_H_CPU1_SA_DQS_DN<4>")
	)
	(segment
		(start 147.834604 -246.236236)
		(end 147.775676 -246.177308)
		(width 0.09525)
		(layer "In13.Cu")
		(net "M_H_CPU1_SA_DQS_DN<4>")
	)
	(segment
		(start 147.775676 -246.177308)
		(end 147.678902 -246.177308)
		(width 0.09525)
		(layer "In13.Cu")
		(net "M_H_CPU1_SA_DQS_DN<4>")
	)
	(segment
		(start 137.813288 -246.589296)
		(end 137.804906 -246.58447)
		(width 0.09525)
		(layer "In13.Cu")
		(net "M_H_CPU1_SA_DQS_DN<4>")
	)
	(segment
		(start 163.643056 -240.412778)
		(end 162.752532 -240.412778)
		(width 0.16002)
		(layer "In13.Cu")
		(net "M_H_CPU1_SA_DQS_DN<4>")
	)
	(segment
		(start 138.753342 -246.589296)
		(end 138.74496 -246.58447)
		(width 0.09525)
		(layer "In13.Cu")
		(net "M_H_CPU1_SA_DQS_DN<4>")
	)
	(segment
		(start 139.324588 -246.58447)
		(end 139.316206 -246.589296)
		(width 0.09525)
		(layer "In13.Cu")
		(net "M_H_CPU1_SA_DQS_DN<4>")
	)
	(segment
		(start 142.513304 -246.589296)
		(end 142.504922 -246.58447)
		(width 0.09525)
		(layer "In13.Cu")
		(net "M_H_CPU1_SA_DQS_DN<4>")
	)
	(segment
		(start 175.834548 -238.747808)
		(end 173.801278 -238.747808)
		(width 0.16002)
		(layer "In13.Cu")
		(net "M_H_CPU1_SA_DQS_DN<4>")
	)
	(segment
		(start 156.929074 -246.236236)
		(end 147.858226 -246.236236)
		(width 0.16002)
		(layer "In13.Cu")
		(net "M_H_CPU1_SA_DQS_DN<4>")
	)
	(segment
		(start 172.443394 -238.562388)
		(end 170.535854 -238.562388)
		(width 0.16002)
		(layer "In13.Cu")
		(net "M_H_CPU1_SA_DQS_DN<4>")
	)
	(segment
		(start 165.150292 -238.905542)
		(end 163.643056 -240.412778)
		(width 0.16002)
		(layer "In13.Cu")
		(net "M_H_CPU1_SA_DQS_DN<4>")
	)
	(segment
		(start 173.630844 -238.918242)
		(end 172.799248 -238.918242)
		(width 0.16002)
		(layer "In13.Cu")
		(net "M_H_CPU1_SA_DQS_DN<4>")
	)
	(segment
		(start 162.752532 -240.412778)
		(end 156.929074 -246.236236)
		(width 0.16002)
		(layer "In13.Cu")
		(net "M_H_CPU1_SA_DQS_DN<4>")
	)
	(segment
		(start 147.858226 -246.236236)
		(end 147.834604 -246.236236)
		(width 0.09525)
		(layer "In13.Cu")
		(net "M_H_CPU1_SA_DQS_DN<4>")
	)
	(segment
		(start 147.678902 -246.177308)
		(end 146.976084 -246.937276)
		(width 0.09525)
		(layer "In13.Cu")
		(net "M_H_CPU1_SA_DQS_DN<4>")
	)
	(segment
		(start 173.801278 -238.747808)
		(end 173.630844 -238.918242)
		(width 0.16002)
		(layer "In13.Cu")
		(net "M_H_CPU1_SA_DQS_DN<4>")
	)
	(segment
		(start 170.535854 -238.562388)
		(end 170.005248 -238.031782)
		(width 0.16002)
		(layer "In13.Cu")
		(net "M_H_CPU1_SA_DQS_DN<4>")
	)
	(segment
		(start 140.264642 -246.58447)
		(end 140.25626 -246.589296)
		(width 0.09525)
		(layer "In13.Cu")
		(net "M_H_CPU1_SA_DQS_DN<4>")
	)
	(segment
		(start 170.005248 -238.031782)
		(end 167.007032 -238.031782)
		(width 0.16002)
		(layer "In13.Cu")
		(net "M_H_CPU1_SA_DQS_DN<4>")
	)
	(segment
		(start 167.007032 -238.031782)
		(end 166.133272 -238.905542)
		(width 0.16002)
		(layer "In13.Cu")
		(net "M_H_CPU1_SA_DQS_DN<4>")
	)
	(segment
		(start 144.394174 -246.589296)
		(end 144.385792 -246.58447)
		(width 0.09525)
		(layer "In13.Cu")
		(net "M_H_CPU1_SA_DQS_DN<4>")
	)
	(segment
		(start 146.02968 -246.665496)
		(end 145.615914 -246.665496)
		(width 0.09525)
		(layer "In13.Cu")
		(net "M_H_CPU1_SA_DQS_DN<4>")
	)
	(segment
		(start 146.976084 -246.937276)
		(end 146.30146 -246.937276)
		(width 0.09525)
		(layer "In13.Cu")
		(net "M_H_CPU1_SA_DQS_DN<4>")
	)
	(segment
		(start 135.999474 -246.622316)
		(end 135.898636 -246.648986)
		(width 0.09525)
		(layer "In13.Cu")
		(net "M_H_CPU1_SA_DQS_DN<4>")
	)
	(segment
		(start 146.30146 -246.937276)
		(end 146.02968 -246.665496)
		(width 0.09525)
		(layer "In13.Cu")
		(net "M_H_CPU1_SA_DQS_DN<4>")
	)
	(segment
		(start 166.133272 -238.905542)
		(end 165.150292 -238.905542)
		(width 0.16002)
		(layer "In13.Cu")
		(net "M_H_CPU1_SA_DQS_DN<4>")
	)
	(segment
		(start 143.08455 -246.58447)
		(end 143.076168 -246.589296)
		(width 0.09525)
		(layer "In13.Cu")
		(net "M_H_CPU1_SA_DQS_DN<4>")
	)
	(arc
		(start 143.076168 -246.589296)
		(mid 142.794736 -246.665051)
		(end 142.513304 -246.589296)
		(width 0.09525)
		(layer "In13.Cu")
		(net "M_H_CPU1_SA_DQS_DN<4>")
	)
	(arc
		(start 137.436098 -246.589296)
		(mid 137.154666 -246.665051)
		(end 136.873234 -246.589296)
		(width 0.09525)
		(layer "In13.Cu")
		(net "M_H_CPU1_SA_DQS_DN<4>")
	)
	(arc
		(start 138.376152 -246.589296)
		(mid 138.09472 -246.665051)
		(end 137.813288 -246.589296)
		(width 0.09525)
		(layer "In13.Cu")
		(net "M_H_CPU1_SA_DQS_DN<4>")
	)
	(arc
		(start 140.63345 -246.589296)
		(mid 140.449675 -246.538524)
		(end 140.264642 -246.58447)
		(width 0.09525)
		(layer "In13.Cu")
		(net "M_H_CPU1_SA_DQS_DN<4>")
	)
	(arc
		(start 141.196314 -246.589296)
		(mid 140.914882 -246.665051)
		(end 140.63345 -246.589296)
		(width 0.09525)
		(layer "In13.Cu")
		(net "M_H_CPU1_SA_DQS_DN<4>")
	)
	(arc
		(start 141.57325 -246.589296)
		(mid 141.384782 -246.538619)
		(end 141.196314 -246.589296)
		(width 0.09525)
		(layer "In13.Cu")
		(net "M_H_CPU1_SA_DQS_DN<4>")
	)
	(arc
		(start 136.496298 -246.589296)
		(mid 136.262784 -246.663139)
		(end 136.020048 -246.630444)
		(width 0.09525)
		(layer "In13.Cu")
		(net "M_H_CPU1_SA_DQS_DN<4>")
	)
	(arc
		(start 145.615914 -246.665496)
		(mid 145.469755 -246.646125)
		(end 145.33372 -246.589296)
		(width 0.09525)
		(layer "In13.Cu")
		(net "M_H_CPU1_SA_DQS_DN<4>")
	)
	(arc
		(start 139.316206 -246.589296)
		(mid 139.034774 -246.665051)
		(end 138.753342 -246.589296)
		(width 0.09525)
		(layer "In13.Cu")
		(net "M_H_CPU1_SA_DQS_DN<4>")
	)
	(arc
		(start 136.020048 -246.630444)
		(mid 136.00972 -246.626484)
		(end 135.999474 -246.622316)
		(width 0.09525)
		(layer "In13.Cu")
		(net "M_H_CPU1_SA_DQS_DN<4>")
	)
	(arc
		(start 140.25626 -246.589296)
		(mid 139.974828 -246.665051)
		(end 139.693396 -246.589296)
		(width 0.09525)
		(layer "In13.Cu")
		(net "M_H_CPU1_SA_DQS_DN<4>")
	)
	(arc
		(start 144.385792 -246.58447)
		(mid 144.200506 -246.538434)
		(end 144.016476 -246.589296)
		(width 0.09525)
		(layer "In13.Cu")
		(net "M_H_CPU1_SA_DQS_DN<4>")
	)
	(arc
		(start 142.504922 -246.58447)
		(mid 142.31989 -246.538556)
		(end 142.136114 -246.589296)
		(width 0.09525)
		(layer "In13.Cu")
		(net "M_H_CPU1_SA_DQS_DN<4>")
	)
	(arc
		(start 143.453358 -246.589296)
		(mid 143.269583 -246.538524)
		(end 143.08455 -246.58447)
		(width 0.09525)
		(layer "In13.Cu")
		(net "M_H_CPU1_SA_DQS_DN<4>")
	)
	(arc
		(start 142.136114 -246.589296)
		(mid 141.854682 -246.665051)
		(end 141.57325 -246.589296)
		(width 0.09525)
		(layer "In13.Cu")
		(net "M_H_CPU1_SA_DQS_DN<4>")
	)
	(arc
		(start 144.941798 -246.597932)
		(mid 144.666847 -246.665075)
		(end 144.394174 -246.589296)
		(width 0.09525)
		(layer "In13.Cu")
		(net "M_H_CPU1_SA_DQS_DN<4>")
	)
	(arc
		(start 145.33372 -246.589296)
		(mid 145.153441 -246.538465)
		(end 144.971008 -246.580914)
		(width 0.09525)
		(layer "In13.Cu")
		(net "M_H_CPU1_SA_DQS_DN<4>")
	)
	(arc
		(start 137.804906 -246.58447)
		(mid 137.619874 -246.538556)
		(end 137.436098 -246.589296)
		(width 0.09525)
		(layer "In13.Cu")
		(net "M_H_CPU1_SA_DQS_DN<4>")
	)
	(arc
		(start 138.74496 -246.58447)
		(mid 138.559928 -246.538556)
		(end 138.376152 -246.589296)
		(width 0.09525)
		(layer "In13.Cu")
		(net "M_H_CPU1_SA_DQS_DN<4>")
	)
	(arc
		(start 139.693396 -246.589296)
		(mid 139.509621 -246.538524)
		(end 139.324588 -246.58447)
		(width 0.09525)
		(layer "In13.Cu")
		(net "M_H_CPU1_SA_DQS_DN<4>")
	)
	(arc
		(start 136.873234 -246.589296)
		(mid 136.684766 -246.538619)
		(end 136.496298 -246.589296)
		(width 0.09525)
		(layer "In13.Cu")
		(net "M_H_CPU1_SA_DQS_DN<4>")
	)
	(arc
		(start 144.016476 -246.589296)
		(mid 143.740933 -246.665145)
		(end 143.463772 -246.595392)
		(width 0.09525)
		(layer "In13.Cu")
		(net "M_H_CPU1_SA_DQS_DN<4>")
	)
	(segment
		(start 135.27786 -242.320318)
		(end 135.744712 -242.05438)
		(width 0.12954)
		(layer "F.Cu")
		(net "M_H_CPU1_SA_DQS_DN<3>")
	)
	(segment
		(start 170.535854 -229.212394)
		(end 172.443394 -229.212394)
		(width 0.16002)
		(layer "In13.Cu")
		(net "M_H_CPU1_SA_DQS_DN<3>")
	)
	(segment
		(start 172.443394 -229.212394)
		(end 172.799248 -229.568248)
		(width 0.16002)
		(layer "In13.Cu")
		(net "M_H_CPU1_SA_DQS_DN<3>")
	)
	(segment
		(start 145.870676 -241.677952)
		(end 146.441414 -241.107214)
		(width 0.09525)
		(layer "In13.Cu")
		(net "M_H_CPU1_SA_DQS_DN<3>")
	)
	(segment
		(start 151.803862 -240.599214)
		(end 158.34995 -234.053126)
		(width 0.16002)
		(layer "In13.Cu")
		(net "M_H_CPU1_SA_DQS_DN<3>")
	)
	(segment
		(start 162.362896 -229.555548)
		(end 166.133272 -229.555548)
		(width 0.16002)
		(layer "In13.Cu")
		(net "M_H_CPU1_SA_DQS_DN<3>")
	)
	(segment
		(start 140.25626 -241.72926)
		(end 140.264642 -241.724434)
		(width 0.09525)
		(layer "In13.Cu")
		(net "M_H_CPU1_SA_DQS_DN<3>")
	)
	(segment
		(start 146.87296 -241.107214)
		(end 147.439888 -240.540286)
		(width 0.09525)
		(layer "In13.Cu")
		(net "M_H_CPU1_SA_DQS_DN<3>")
	)
	(segment
		(start 147.439888 -240.540286)
		(end 147.829524 -240.540286)
		(width 0.09525)
		(layer "In13.Cu")
		(net "M_H_CPU1_SA_DQS_DN<3>")
	)
	(segment
		(start 144.385792 -241.724434)
		(end 144.394174 -241.72926)
		(width 0.09525)
		(layer "In13.Cu")
		(net "M_H_CPU1_SA_DQS_DN<3>")
	)
	(segment
		(start 137.804906 -241.724434)
		(end 137.813288 -241.72926)
		(width 0.09525)
		(layer "In13.Cu")
		(net "M_H_CPU1_SA_DQS_DN<3>")
	)
	(segment
		(start 142.504922 -241.724434)
		(end 142.513304 -241.72926)
		(width 0.09525)
		(layer "In13.Cu")
		(net "M_H_CPU1_SA_DQS_DN<3>")
	)
	(segment
		(start 135.898636 -241.78895)
		(end 135.999474 -241.76228)
		(width 0.09525)
		(layer "In13.Cu")
		(net "M_H_CPU1_SA_DQS_DN<3>")
	)
	(segment
		(start 158.34995 -234.053126)
		(end 158.34995 -233.568494)
		(width 0.16002)
		(layer "In13.Cu")
		(net "M_H_CPU1_SA_DQS_DN<3>")
	)
	(segment
		(start 173.849284 -229.349808)
		(end 175.786542 -229.349808)
		(width 0.16002)
		(layer "In13.Cu")
		(net "M_H_CPU1_SA_DQS_DN<3>")
	)
	(segment
		(start 172.799248 -229.568248)
		(end 173.630844 -229.568248)
		(width 0.16002)
		(layer "In13.Cu")
		(net "M_H_CPU1_SA_DQS_DN<3>")
	)
	(segment
		(start 166.133272 -229.555548)
		(end 167.007032 -228.681788)
		(width 0.16002)
		(layer "In13.Cu")
		(net "M_H_CPU1_SA_DQS_DN<3>")
	)
	(segment
		(start 135.744712 -242.05438)
		(end 135.898636 -241.78895)
		(width 0.09525)
		(layer "In13.Cu")
		(net "M_H_CPU1_SA_DQS_DN<3>")
	)
	(segment
		(start 170.005248 -228.681788)
		(end 170.535854 -229.212394)
		(width 0.16002)
		(layer "In13.Cu")
		(net "M_H_CPU1_SA_DQS_DN<3>")
	)
	(segment
		(start 138.74496 -241.724434)
		(end 138.753342 -241.72926)
		(width 0.09525)
		(layer "In13.Cu")
		(net "M_H_CPU1_SA_DQS_DN<3>")
	)
	(segment
		(start 147.912074 -240.599214)
		(end 151.803862 -240.599214)
		(width 0.16002)
		(layer "In13.Cu")
		(net "M_H_CPU1_SA_DQS_DN<3>")
	)
	(segment
		(start 167.007032 -228.681788)
		(end 170.005248 -228.681788)
		(width 0.16002)
		(layer "In13.Cu")
		(net "M_H_CPU1_SA_DQS_DN<3>")
	)
	(segment
		(start 147.888452 -240.599214)
		(end 147.912074 -240.599214)
		(width 0.09525)
		(layer "In13.Cu")
		(net "M_H_CPU1_SA_DQS_DN<3>")
	)
	(segment
		(start 145.144744 -241.677952)
		(end 145.870676 -241.677952)
		(width 0.09525)
		(layer "In13.Cu")
		(net "M_H_CPU1_SA_DQS_DN<3>")
	)
	(segment
		(start 143.076168 -241.72926)
		(end 143.08455 -241.724434)
		(width 0.09525)
		(layer "In13.Cu")
		(net "M_H_CPU1_SA_DQS_DN<3>")
	)
	(segment
		(start 139.316206 -241.72926)
		(end 139.324588 -241.724434)
		(width 0.09525)
		(layer "In13.Cu")
		(net "M_H_CPU1_SA_DQS_DN<3>")
	)
	(segment
		(start 146.441414 -241.107214)
		(end 146.87296 -241.107214)
		(width 0.09525)
		(layer "In13.Cu")
		(net "M_H_CPU1_SA_DQS_DN<3>")
	)
	(segment
		(start 143.453358 -241.72926)
		(end 143.463772 -241.735356)
		(width 0.09525)
		(layer "In13.Cu")
		(net "M_H_CPU1_SA_DQS_DN<3>")
	)
	(segment
		(start 147.829524 -240.540286)
		(end 147.888452 -240.599214)
		(width 0.09525)
		(layer "In13.Cu")
		(net "M_H_CPU1_SA_DQS_DN<3>")
	)
	(segment
		(start 173.630844 -229.568248)
		(end 173.849284 -229.349808)
		(width 0.16002)
		(layer "In13.Cu")
		(net "M_H_CPU1_SA_DQS_DN<3>")
	)
	(segment
		(start 175.786542 -229.349808)
		(end 176.072038 -229.635304)
		(width 0.16002)
		(layer "In13.Cu")
		(net "M_H_CPU1_SA_DQS_DN<3>")
	)
	(segment
		(start 158.34995 -233.568494)
		(end 162.362896 -229.555548)
		(width 0.16002)
		(layer "In13.Cu")
		(net "M_H_CPU1_SA_DQS_DN<3>")
	)
	(arc
		(start 139.324588 -241.724434)
		(mid 139.50962 -241.67852)
		(end 139.693396 -241.72926)
		(width 0.09525)
		(layer "In13.Cu")
		(net "M_H_CPU1_SA_DQS_DN<3>")
	)
	(arc
		(start 144.394174 -241.72926)
		(mid 144.666848 -241.804947)
		(end 144.941798 -241.737896)
		(width 0.09525)
		(layer "In13.Cu")
		(net "M_H_CPU1_SA_DQS_DN<3>")
	)
	(arc
		(start 140.63345 -241.72926)
		(mid 140.914882 -241.805015)
		(end 141.196314 -241.72926)
		(width 0.09525)
		(layer "In13.Cu")
		(net "M_H_CPU1_SA_DQS_DN<3>")
	)
	(arc
		(start 136.496298 -241.72926)
		(mid 136.684766 -241.678583)
		(end 136.873234 -241.72926)
		(width 0.09525)
		(layer "In13.Cu")
		(net "M_H_CPU1_SA_DQS_DN<3>")
	)
	(arc
		(start 142.136114 -241.72926)
		(mid 142.319889 -241.678488)
		(end 142.504922 -241.724434)
		(width 0.09525)
		(layer "In13.Cu")
		(net "M_H_CPU1_SA_DQS_DN<3>")
	)
	(arc
		(start 136.873234 -241.72926)
		(mid 137.154666 -241.805015)
		(end 137.436098 -241.72926)
		(width 0.09525)
		(layer "In13.Cu")
		(net "M_H_CPU1_SA_DQS_DN<3>")
	)
	(arc
		(start 139.693396 -241.72926)
		(mid 139.974828 -241.805015)
		(end 140.25626 -241.72926)
		(width 0.09525)
		(layer "In13.Cu")
		(net "M_H_CPU1_SA_DQS_DN<3>")
	)
	(arc
		(start 138.753342 -241.72926)
		(mid 139.034774 -241.805015)
		(end 139.316206 -241.72926)
		(width 0.09525)
		(layer "In13.Cu")
		(net "M_H_CPU1_SA_DQS_DN<3>")
	)
	(arc
		(start 140.264642 -241.724434)
		(mid 140.449674 -241.67852)
		(end 140.63345 -241.72926)
		(width 0.09525)
		(layer "In13.Cu")
		(net "M_H_CPU1_SA_DQS_DN<3>")
	)
	(arc
		(start 142.513304 -241.72926)
		(mid 142.794736 -241.805015)
		(end 143.076168 -241.72926)
		(width 0.09525)
		(layer "In13.Cu")
		(net "M_H_CPU1_SA_DQS_DN<3>")
	)
	(arc
		(start 144.941798 -241.737896)
		(mid 145.03897 -241.693365)
		(end 145.144744 -241.677952)
		(width 0.09525)
		(layer "In13.Cu")
		(net "M_H_CPU1_SA_DQS_DN<3>")
	)
	(arc
		(start 137.436098 -241.72926)
		(mid 137.619873 -241.678488)
		(end 137.804906 -241.724434)
		(width 0.09525)
		(layer "In13.Cu")
		(net "M_H_CPU1_SA_DQS_DN<3>")
	)
	(arc
		(start 138.376152 -241.72926)
		(mid 138.559927 -241.678488)
		(end 138.74496 -241.724434)
		(width 0.09525)
		(layer "In13.Cu")
		(net "M_H_CPU1_SA_DQS_DN<3>")
	)
	(arc
		(start 144.016476 -241.72926)
		(mid 144.200505 -241.678361)
		(end 144.385792 -241.724434)
		(width 0.09525)
		(layer "In13.Cu")
		(net "M_H_CPU1_SA_DQS_DN<3>")
	)
	(arc
		(start 137.813288 -241.72926)
		(mid 138.09472 -241.805015)
		(end 138.376152 -241.72926)
		(width 0.09525)
		(layer "In13.Cu")
		(net "M_H_CPU1_SA_DQS_DN<3>")
	)
	(arc
		(start 143.463772 -241.735356)
		(mid 143.740934 -241.805156)
		(end 144.016476 -241.72926)
		(width 0.09525)
		(layer "In13.Cu")
		(net "M_H_CPU1_SA_DQS_DN<3>")
	)
	(arc
		(start 143.08455 -241.724434)
		(mid 143.269582 -241.67852)
		(end 143.453358 -241.72926)
		(width 0.09525)
		(layer "In13.Cu")
		(net "M_H_CPU1_SA_DQS_DN<3>")
	)
	(arc
		(start 141.57325 -241.72926)
		(mid 141.854682 -241.805015)
		(end 142.136114 -241.72926)
		(width 0.09525)
		(layer "In13.Cu")
		(net "M_H_CPU1_SA_DQS_DN<3>")
	)
	(arc
		(start 136.020048 -241.770408)
		(mid 136.26279 -241.803178)
		(end 136.496298 -241.72926)
		(width 0.09525)
		(layer "In13.Cu")
		(net "M_H_CPU1_SA_DQS_DN<3>")
	)
	(arc
		(start 135.999474 -241.76228)
		(mid 136.009722 -241.766443)
		(end 136.020048 -241.770408)
		(width 0.09525)
		(layer "In13.Cu")
		(net "M_H_CPU1_SA_DQS_DN<3>")
	)
	(arc
		(start 141.196314 -241.72926)
		(mid 141.384782 -241.678583)
		(end 141.57325 -241.72926)
		(width 0.09525)
		(layer "In13.Cu")
		(net "M_H_CPU1_SA_DQS_DN<3>")
	)
	(segment
		(start 135.27786 -237.460282)
		(end 135.744712 -237.194344)
		(width 0.12954)
		(layer "F.Cu")
		(net "M_H_CPU1_SA_DQS_DN<2>")
	)
	(segment
		(start 144.393158 -236.869224)
		(end 144.392904 -236.869224)
		(width 0.09525)
		(layer "In13.Cu")
		(net "M_H_CPU1_SA_DQS_DN<2>")
	)
	(segment
		(start 145.48866 -236.754416)
		(end 145.23593 -236.754416)
		(width 0.09525)
		(layer "In13.Cu")
		(net "M_H_CPU1_SA_DQS_DN<2>")
	)
	(segment
		(start 143.08455 -236.864398)
		(end 143.053816 -236.881924)
		(width 0.09525)
		(layer "In13.Cu")
		(net "M_H_CPU1_SA_DQS_DN<2>")
	)
	(segment
		(start 170.535854 -219.8624)
		(end 170.005248 -219.331794)
		(width 0.16002)
		(layer "In13.Cu")
		(net "M_H_CPU1_SA_DQS_DN<2>")
	)
	(segment
		(start 175.789336 -220.002608)
		(end 175.107092 -220.002608)
		(width 0.16002)
		(layer "In13.Cu")
		(net "M_H_CPU1_SA_DQS_DN<2>")
	)
	(segment
		(start 147.82673 -234.810808)
		(end 147.656296 -234.810808)
		(width 0.09525)
		(layer "In13.Cu")
		(net "M_H_CPU1_SA_DQS_DN<2>")
	)
	(segment
		(start 139.324588 -236.864398)
		(end 139.316206 -236.869224)
		(width 0.09525)
		(layer "In13.Cu")
		(net "M_H_CPU1_SA_DQS_DN<2>")
	)
	(segment
		(start 144.403826 -236.875066)
		(end 144.393158 -236.869224)
		(width 0.09525)
		(layer "In13.Cu")
		(net "M_H_CPU1_SA_DQS_DN<2>")
	)
	(segment
		(start 146.57705 -235.666026)
		(end 145.48866 -236.754416)
		(width 0.09525)
		(layer "In13.Cu")
		(net "M_H_CPU1_SA_DQS_DN<2>")
	)
	(segment
		(start 147.656296 -234.810808)
		(end 146.948398 -235.666026)
		(width 0.09525)
		(layer "In13.Cu")
		(net "M_H_CPU1_SA_DQS_DN<2>")
	)
	(segment
		(start 147.90928 -234.869736)
		(end 147.885658 -234.869736)
		(width 0.09525)
		(layer "In13.Cu")
		(net "M_H_CPU1_SA_DQS_DN<2>")
	)
	(segment
		(start 155.486354 -226.008184)
		(end 155.486354 -228.41839)
		(width 0.16002)
		(layer "In13.Cu")
		(net "M_H_CPU1_SA_DQS_DN<2>")
	)
	(segment
		(start 167.007032 -219.331794)
		(end 166.133272 -220.205554)
		(width 0.16002)
		(layer "In13.Cu")
		(net "M_H_CPU1_SA_DQS_DN<2>")
	)
	(segment
		(start 172.443394 -219.8624)
		(end 170.535854 -219.8624)
		(width 0.16002)
		(layer "In13.Cu")
		(net "M_H_CPU1_SA_DQS_DN<2>")
	)
	(segment
		(start 146.948398 -235.666026)
		(end 146.57705 -235.666026)
		(width 0.09525)
		(layer "In13.Cu")
		(net "M_H_CPU1_SA_DQS_DN<2>")
	)
	(segment
		(start 155.486354 -228.41839)
		(end 149.035008 -234.869736)
		(width 0.16002)
		(layer "In13.Cu")
		(net "M_H_CPU1_SA_DQS_DN<2>")
	)
	(segment
		(start 174.261272 -219.587826)
		(end 173.630844 -220.218254)
		(width 0.16002)
		(layer "In13.Cu")
		(net "M_H_CPU1_SA_DQS_DN<2>")
	)
	(segment
		(start 138.753342 -236.869224)
		(end 138.74496 -236.864398)
		(width 0.09525)
		(layer "In13.Cu")
		(net "M_H_CPU1_SA_DQS_DN<2>")
	)
	(segment
		(start 165.168072 -220.205554)
		(end 164.844984 -219.882466)
		(width 0.16002)
		(layer "In13.Cu")
		(net "M_H_CPU1_SA_DQS_DN<2>")
	)
	(segment
		(start 162.453066 -220.982794)
		(end 160.511744 -220.982794)
		(width 0.16002)
		(layer "In13.Cu")
		(net "M_H_CPU1_SA_DQS_DN<2>")
	)
	(segment
		(start 140.264642 -236.864398)
		(end 140.25626 -236.869224)
		(width 0.09525)
		(layer "In13.Cu")
		(net "M_H_CPU1_SA_DQS_DN<2>")
	)
	(segment
		(start 135.898636 -236.928914)
		(end 135.744712 -237.194344)
		(width 0.09525)
		(layer "In13.Cu")
		(net "M_H_CPU1_SA_DQS_DN<2>")
	)
	(segment
		(start 149.035008 -234.869736)
		(end 147.90928 -234.869736)
		(width 0.16002)
		(layer "In13.Cu")
		(net "M_H_CPU1_SA_DQS_DN<2>")
	)
	(segment
		(start 175.107092 -220.002608)
		(end 174.69231 -219.587826)
		(width 0.16002)
		(layer "In13.Cu")
		(net "M_H_CPU1_SA_DQS_DN<2>")
	)
	(segment
		(start 145.23593 -236.754416)
		(end 144.94383 -236.875574)
		(width 0.09525)
		(layer "In13.Cu")
		(net "M_H_CPU1_SA_DQS_DN<2>")
	)
	(segment
		(start 144.015968 -236.869224)
		(end 144.005554 -236.87532)
		(width 0.09525)
		(layer "In13.Cu")
		(net "M_H_CPU1_SA_DQS_DN<2>")
	)
	(segment
		(start 166.133272 -220.205554)
		(end 165.168072 -220.205554)
		(width 0.16002)
		(layer "In13.Cu")
		(net "M_H_CPU1_SA_DQS_DN<2>")
	)
	(segment
		(start 143.053816 -236.881924)
		(end 143.034258 -236.891322)
		(width 0.09525)
		(layer "In13.Cu")
		(net "M_H_CPU1_SA_DQS_DN<2>")
	)
	(segment
		(start 160.511744 -220.982794)
		(end 155.486354 -226.008184)
		(width 0.16002)
		(layer "In13.Cu")
		(net "M_H_CPU1_SA_DQS_DN<2>")
	)
	(segment
		(start 135.999474 -236.902244)
		(end 135.898636 -236.928914)
		(width 0.09525)
		(layer "In13.Cu")
		(net "M_H_CPU1_SA_DQS_DN<2>")
	)
	(segment
		(start 147.885658 -234.869736)
		(end 147.82673 -234.810808)
		(width 0.09525)
		(layer "In13.Cu")
		(net "M_H_CPU1_SA_DQS_DN<2>")
	)
	(segment
		(start 170.005248 -219.331794)
		(end 167.007032 -219.331794)
		(width 0.16002)
		(layer "In13.Cu")
		(net "M_H_CPU1_SA_DQS_DN<2>")
	)
	(segment
		(start 172.799248 -220.218254)
		(end 172.443394 -219.8624)
		(width 0.16002)
		(layer "In13.Cu")
		(net "M_H_CPU1_SA_DQS_DN<2>")
	)
	(segment
		(start 163.553394 -219.882466)
		(end 162.453066 -220.982794)
		(width 0.16002)
		(layer "In13.Cu")
		(net "M_H_CPU1_SA_DQS_DN<2>")
	)
	(segment
		(start 176.072038 -220.28531)
		(end 175.789336 -220.002608)
		(width 0.16002)
		(layer "In13.Cu")
		(net "M_H_CPU1_SA_DQS_DN<2>")
	)
	(segment
		(start 137.813288 -236.869224)
		(end 137.804906 -236.864398)
		(width 0.09525)
		(layer "In13.Cu")
		(net "M_H_CPU1_SA_DQS_DN<2>")
	)
	(segment
		(start 142.513304 -236.869224)
		(end 142.504922 -236.864398)
		(width 0.09525)
		(layer "In13.Cu")
		(net "M_H_CPU1_SA_DQS_DN<2>")
	)
	(segment
		(start 164.844984 -219.882466)
		(end 163.553394 -219.882466)
		(width 0.16002)
		(layer "In13.Cu")
		(net "M_H_CPU1_SA_DQS_DN<2>")
	)
	(segment
		(start 174.69231 -219.587826)
		(end 174.261272 -219.587826)
		(width 0.16002)
		(layer "In13.Cu")
		(net "M_H_CPU1_SA_DQS_DN<2>")
	)
	(segment
		(start 173.630844 -220.218254)
		(end 172.799248 -220.218254)
		(width 0.16002)
		(layer "In13.Cu")
		(net "M_H_CPU1_SA_DQS_DN<2>")
	)
	(arc
		(start 140.25626 -236.869224)
		(mid 139.974828 -236.944979)
		(end 139.693396 -236.869224)
		(width 0.09525)
		(layer "In13.Cu")
		(net "M_H_CPU1_SA_DQS_DN<2>")
	)
	(arc
		(start 136.496298 -236.869224)
		(mid 136.262784 -236.943067)
		(end 136.020048 -236.910372)
		(width 0.09525)
		(layer "In13.Cu")
		(net "M_H_CPU1_SA_DQS_DN<2>")
	)
	(arc
		(start 138.376152 -236.869224)
		(mid 138.09472 -236.944979)
		(end 137.813288 -236.869224)
		(width 0.09525)
		(layer "In13.Cu")
		(net "M_H_CPU1_SA_DQS_DN<2>")
	)
	(arc
		(start 136.873234 -236.869224)
		(mid 136.684766 -236.818547)
		(end 136.496298 -236.869224)
		(width 0.09525)
		(layer "In13.Cu")
		(net "M_H_CPU1_SA_DQS_DN<2>")
	)
	(arc
		(start 141.57325 -236.869224)
		(mid 141.384782 -236.818547)
		(end 141.196314 -236.869224)
		(width 0.09525)
		(layer "In13.Cu")
		(net "M_H_CPU1_SA_DQS_DN<2>")
	)
	(arc
		(start 143.034258 -236.891322)
		(mid 142.771045 -236.944554)
		(end 142.513304 -236.869224)
		(width 0.09525)
		(layer "In13.Cu")
		(net "M_H_CPU1_SA_DQS_DN<2>")
	)
	(arc
		(start 137.436098 -236.869224)
		(mid 137.154666 -236.944979)
		(end 136.873234 -236.869224)
		(width 0.09525)
		(layer "In13.Cu")
		(net "M_H_CPU1_SA_DQS_DN<2>")
	)
	(arc
		(start 143.453358 -236.869224)
		(mid 143.269583 -236.818452)
		(end 143.08455 -236.864398)
		(width 0.09525)
		(layer "In13.Cu")
		(net "M_H_CPU1_SA_DQS_DN<2>")
	)
	(arc
		(start 144.406112 -236.876082)
		(mid 144.404968 -236.875575)
		(end 144.403826 -236.875066)
		(width 0.09525)
		(layer "In13.Cu")
		(net "M_H_CPU1_SA_DQS_DN<2>")
	)
	(arc
		(start 137.804906 -236.864398)
		(mid 137.619874 -236.818484)
		(end 137.436098 -236.869224)
		(width 0.09525)
		(layer "In13.Cu")
		(net "M_H_CPU1_SA_DQS_DN<2>")
	)
	(arc
		(start 142.504922 -236.864398)
		(mid 142.31989 -236.818484)
		(end 142.136114 -236.869224)
		(width 0.09525)
		(layer "In13.Cu")
		(net "M_H_CPU1_SA_DQS_DN<2>")
	)
	(arc
		(start 139.316206 -236.869224)
		(mid 139.034774 -236.944979)
		(end 138.753342 -236.869224)
		(width 0.09525)
		(layer "In13.Cu")
		(net "M_H_CPU1_SA_DQS_DN<2>")
	)
	(arc
		(start 144.392904 -236.869224)
		(mid 144.204436 -236.818547)
		(end 144.015968 -236.869224)
		(width 0.09525)
		(layer "In13.Cu")
		(net "M_H_CPU1_SA_DQS_DN<2>")
	)
	(arc
		(start 138.74496 -236.864398)
		(mid 138.559928 -236.818484)
		(end 138.376152 -236.869224)
		(width 0.09525)
		(layer "In13.Cu")
		(net "M_H_CPU1_SA_DQS_DN<2>")
	)
	(arc
		(start 136.020048 -236.910372)
		(mid 136.00972 -236.906412)
		(end 135.999474 -236.902244)
		(width 0.09525)
		(layer "In13.Cu")
		(net "M_H_CPU1_SA_DQS_DN<2>")
	)
	(arc
		(start 139.693396 -236.869224)
		(mid 139.509621 -236.818452)
		(end 139.324588 -236.864398)
		(width 0.09525)
		(layer "In13.Cu")
		(net "M_H_CPU1_SA_DQS_DN<2>")
	)
	(arc
		(start 144.94383 -236.875574)
		(mid 144.675046 -236.944519)
		(end 144.406112 -236.876082)
		(width 0.09525)
		(layer "In13.Cu")
		(net "M_H_CPU1_SA_DQS_DN<2>")
	)
	(arc
		(start 140.63345 -236.869224)
		(mid 140.449675 -236.818452)
		(end 140.264642 -236.864398)
		(width 0.09525)
		(layer "In13.Cu")
		(net "M_H_CPU1_SA_DQS_DN<2>")
	)
	(arc
		(start 142.136114 -236.869224)
		(mid 141.854682 -236.944979)
		(end 141.57325 -236.869224)
		(width 0.09525)
		(layer "In13.Cu")
		(net "M_H_CPU1_SA_DQS_DN<2>")
	)
	(arc
		(start 141.196314 -236.869224)
		(mid 140.914882 -236.944979)
		(end 140.63345 -236.869224)
		(width 0.09525)
		(layer "In13.Cu")
		(net "M_H_CPU1_SA_DQS_DN<2>")
	)
	(arc
		(start 144.005554 -236.87532)
		(mid 143.728646 -236.944997)
		(end 143.453358 -236.869224)
		(width 0.09525)
		(layer "In13.Cu")
		(net "M_H_CPU1_SA_DQS_DN<2>")
	)
	(segment
		(start 135.27786 -232.600246)
		(end 135.744712 -232.334308)
		(width 0.12954)
		(layer "F.Cu")
		(net "M_H_CPU1_SA_DQS_DN<1>")
	)
	(segment
		(start 166.133272 -210.85556)
		(end 165.279324 -210.85556)
		(width 0.16002)
		(layer "In13.Cu")
		(net "M_H_CPU1_SA_DQS_DN<1>")
	)
	(segment
		(start 144.644618 -230.68407)
		(end 144.644618 -231.406954)
		(width 0.09525)
		(layer "In13.Cu")
		(net "M_H_CPU1_SA_DQS_DN<1>")
	)
	(segment
		(start 165.279324 -210.85556)
		(end 164.97427 -210.550506)
		(width 0.16002)
		(layer "In13.Cu")
		(net "M_H_CPU1_SA_DQS_DN<1>")
	)
	(segment
		(start 149.949154 -225.450908)
		(end 147.657058 -227.743004)
		(width 0.16002)
		(layer "In13.Cu")
		(net "M_H_CPU1_SA_DQS_DN<1>")
	)
	(segment
		(start 142.513304 -232.009188)
		(end 142.505938 -232.00487)
		(width 0.09525)
		(layer "In13.Cu")
		(net "M_H_CPU1_SA_DQS_DN<1>")
	)
	(segment
		(start 164.97427 -210.550506)
		(end 161.21634 -210.550506)
		(width 0.16002)
		(layer "In13.Cu")
		(net "M_H_CPU1_SA_DQS_DN<1>")
	)
	(segment
		(start 144.644618 -231.406954)
		(end 144.13103 -231.920796)
		(width 0.09525)
		(layer "In13.Cu")
		(net "M_H_CPU1_SA_DQS_DN<1>")
	)
	(segment
		(start 175.79467 -210.657948)
		(end 173.841156 -210.657948)
		(width 0.16002)
		(layer "In13.Cu")
		(net "M_H_CPU1_SA_DQS_DN<1>")
	)
	(segment
		(start 147.254468 -228.062536)
		(end 147.254468 -228.431852)
		(width 0.09525)
		(layer "In13.Cu")
		(net "M_H_CPU1_SA_DQS_DN<1>")
	)
	(segment
		(start 139.324588 -232.004362)
		(end 139.316206 -232.009188)
		(width 0.09525)
		(layer "In13.Cu")
		(net "M_H_CPU1_SA_DQS_DN<1>")
	)
	(segment
		(start 149.949154 -221.817692)
		(end 149.949154 -225.450908)
		(width 0.16002)
		(layer "In13.Cu")
		(net "M_H_CPU1_SA_DQS_DN<1>")
	)
	(segment
		(start 138.753342 -232.009188)
		(end 138.74496 -232.004362)
		(width 0.09525)
		(layer "In13.Cu")
		(net "M_H_CPU1_SA_DQS_DN<1>")
	)
	(segment
		(start 135.898636 -232.068878)
		(end 135.744712 -232.334308)
		(width 0.09525)
		(layer "In13.Cu")
		(net "M_H_CPU1_SA_DQS_DN<1>")
	)
	(segment
		(start 135.999474 -232.042208)
		(end 135.898636 -232.068878)
		(width 0.09525)
		(layer "In13.Cu")
		(net "M_H_CPU1_SA_DQS_DN<1>")
	)
	(segment
		(start 147.254468 -228.431852)
		(end 145.384266 -230.302054)
		(width 0.09525)
		(layer "In13.Cu")
		(net "M_H_CPU1_SA_DQS_DN<1>")
	)
	(segment
		(start 172.799248 -210.86826)
		(end 172.443394 -210.512406)
		(width 0.16002)
		(layer "In13.Cu")
		(net "M_H_CPU1_SA_DQS_DN<1>")
	)
	(segment
		(start 167.007032 -209.9818)
		(end 166.133272 -210.85556)
		(width 0.16002)
		(layer "In13.Cu")
		(net "M_H_CPU1_SA_DQS_DN<1>")
	)
	(segment
		(start 137.813288 -232.009188)
		(end 137.804906 -232.004362)
		(width 0.09525)
		(layer "In13.Cu")
		(net "M_H_CPU1_SA_DQS_DN<1>")
	)
	(segment
		(start 172.443394 -210.512406)
		(end 170.535854 -210.512406)
		(width 0.16002)
		(layer "In13.Cu")
		(net "M_H_CPU1_SA_DQS_DN<1>")
	)
	(segment
		(start 145.026634 -230.302054)
		(end 144.644618 -230.68407)
		(width 0.09525)
		(layer "In13.Cu")
		(net "M_H_CPU1_SA_DQS_DN<1>")
	)
	(segment
		(start 170.005248 -209.9818)
		(end 167.007032 -209.9818)
		(width 0.16002)
		(layer "In13.Cu")
		(net "M_H_CPU1_SA_DQS_DN<1>")
	)
	(segment
		(start 144.015968 -232.009188)
		(end 144.005554 -232.015284)
		(width 0.09525)
		(layer "In13.Cu")
		(net "M_H_CPU1_SA_DQS_DN<1>")
	)
	(segment
		(start 147.657058 -227.743004)
		(end 147.640294 -227.759768)
		(width 0.09525)
		(layer "In13.Cu")
		(net "M_H_CPU1_SA_DQS_DN<1>")
	)
	(segment
		(start 161.21634 -210.550506)
		(end 149.949154 -221.817692)
		(width 0.16002)
		(layer "In13.Cu")
		(net "M_H_CPU1_SA_DQS_DN<1>")
	)
	(segment
		(start 176.072038 -210.935316)
		(end 175.79467 -210.657948)
		(width 0.16002)
		(layer "In13.Cu")
		(net "M_H_CPU1_SA_DQS_DN<1>")
	)
	(segment
		(start 147.557236 -227.759768)
		(end 147.254468 -228.062536)
		(width 0.09525)
		(layer "In13.Cu")
		(net "M_H_CPU1_SA_DQS_DN<1>")
	)
	(segment
		(start 140.264642 -232.004362)
		(end 140.25626 -232.009188)
		(width 0.09525)
		(layer "In13.Cu")
		(net "M_H_CPU1_SA_DQS_DN<1>")
	)
	(segment
		(start 173.841156 -210.657948)
		(end 173.630844 -210.86826)
		(width 0.16002)
		(layer "In13.Cu")
		(net "M_H_CPU1_SA_DQS_DN<1>")
	)
	(segment
		(start 173.630844 -210.86826)
		(end 172.799248 -210.86826)
		(width 0.16002)
		(layer "In13.Cu")
		(net "M_H_CPU1_SA_DQS_DN<1>")
	)
	(segment
		(start 145.384266 -230.302054)
		(end 145.026634 -230.302054)
		(width 0.09525)
		(layer "In13.Cu")
		(net "M_H_CPU1_SA_DQS_DN<1>")
	)
	(segment
		(start 143.08455 -232.004362)
		(end 143.076168 -232.009188)
		(width 0.09525)
		(layer "In13.Cu")
		(net "M_H_CPU1_SA_DQS_DN<1>")
	)
	(segment
		(start 142.505938 -232.00487)
		(end 142.504922 -232.004362)
		(width 0.09525)
		(layer "In13.Cu")
		(net "M_H_CPU1_SA_DQS_DN<1>")
	)
	(segment
		(start 147.640294 -227.759768)
		(end 147.557236 -227.759768)
		(width 0.09525)
		(layer "In13.Cu")
		(net "M_H_CPU1_SA_DQS_DN<1>")
	)
	(segment
		(start 170.535854 -210.512406)
		(end 170.005248 -209.9818)
		(width 0.16002)
		(layer "In13.Cu")
		(net "M_H_CPU1_SA_DQS_DN<1>")
	)
	(arc
		(start 143.076168 -232.009188)
		(mid 142.794736 -232.084943)
		(end 142.513304 -232.009188)
		(width 0.09525)
		(layer "In13.Cu")
		(net "M_H_CPU1_SA_DQS_DN<1>")
	)
	(arc
		(start 136.873234 -232.009188)
		(mid 136.684766 -231.958511)
		(end 136.496298 -232.009188)
		(width 0.09525)
		(layer "In13.Cu")
		(net "M_H_CPU1_SA_DQS_DN<1>")
	)
	(arc
		(start 143.453358 -232.009188)
		(mid 143.269583 -231.958416)
		(end 143.08455 -232.004362)
		(width 0.09525)
		(layer "In13.Cu")
		(net "M_H_CPU1_SA_DQS_DN<1>")
	)
	(arc
		(start 144.005554 -232.015284)
		(mid 143.728646 -232.084961)
		(end 143.453358 -232.009188)
		(width 0.09525)
		(layer "In13.Cu")
		(net "M_H_CPU1_SA_DQS_DN<1>")
	)
	(arc
		(start 137.804906 -232.004362)
		(mid 137.619874 -231.958448)
		(end 137.436098 -232.009188)
		(width 0.09525)
		(layer "In13.Cu")
		(net "M_H_CPU1_SA_DQS_DN<1>")
	)
	(arc
		(start 144.12468 -231.927146)
		(mid 144.072831 -231.97149)
		(end 144.015968 -232.009188)
		(width 0.09525)
		(layer "In13.Cu")
		(net "M_H_CPU1_SA_DQS_DN<1>")
	)
	(arc
		(start 141.196314 -232.009188)
		(mid 140.914882 -232.084943)
		(end 140.63345 -232.009188)
		(width 0.09525)
		(layer "In13.Cu")
		(net "M_H_CPU1_SA_DQS_DN<1>")
	)
	(arc
		(start 144.13103 -231.920796)
		(mid 144.127868 -231.923984)
		(end 144.12468 -231.927146)
		(width 0.09525)
		(layer "In13.Cu")
		(net "M_H_CPU1_SA_DQS_DN<1>")
	)
	(arc
		(start 139.316206 -232.009188)
		(mid 139.034774 -232.084943)
		(end 138.753342 -232.009188)
		(width 0.09525)
		(layer "In13.Cu")
		(net "M_H_CPU1_SA_DQS_DN<1>")
	)
	(arc
		(start 142.504922 -232.004362)
		(mid 142.31989 -231.958448)
		(end 142.136114 -232.009188)
		(width 0.09525)
		(layer "In13.Cu")
		(net "M_H_CPU1_SA_DQS_DN<1>")
	)
	(arc
		(start 140.63345 -232.009188)
		(mid 140.449675 -231.958416)
		(end 140.264642 -232.004362)
		(width 0.09525)
		(layer "In13.Cu")
		(net "M_H_CPU1_SA_DQS_DN<1>")
	)
	(arc
		(start 142.136114 -232.009188)
		(mid 141.854682 -232.084943)
		(end 141.57325 -232.009188)
		(width 0.09525)
		(layer "In13.Cu")
		(net "M_H_CPU1_SA_DQS_DN<1>")
	)
	(arc
		(start 136.020048 -232.050336)
		(mid 136.00972 -232.046376)
		(end 135.999474 -232.042208)
		(width 0.09525)
		(layer "In13.Cu")
		(net "M_H_CPU1_SA_DQS_DN<1>")
	)
	(arc
		(start 138.74496 -232.004362)
		(mid 138.559928 -231.958448)
		(end 138.376152 -232.009188)
		(width 0.09525)
		(layer "In13.Cu")
		(net "M_H_CPU1_SA_DQS_DN<1>")
	)
	(arc
		(start 138.376152 -232.009188)
		(mid 138.09472 -232.084943)
		(end 137.813288 -232.009188)
		(width 0.09525)
		(layer "In13.Cu")
		(net "M_H_CPU1_SA_DQS_DN<1>")
	)
	(arc
		(start 139.693396 -232.009188)
		(mid 139.509621 -231.958416)
		(end 139.324588 -232.004362)
		(width 0.09525)
		(layer "In13.Cu")
		(net "M_H_CPU1_SA_DQS_DN<1>")
	)
	(arc
		(start 136.496298 -232.009188)
		(mid 136.262784 -232.083031)
		(end 136.020048 -232.050336)
		(width 0.09525)
		(layer "In13.Cu")
		(net "M_H_CPU1_SA_DQS_DN<1>")
	)
	(arc
		(start 140.25626 -232.009188)
		(mid 139.974828 -232.084943)
		(end 139.693396 -232.009188)
		(width 0.09525)
		(layer "In13.Cu")
		(net "M_H_CPU1_SA_DQS_DN<1>")
	)
	(arc
		(start 141.57325 -232.009188)
		(mid 141.384782 -231.958511)
		(end 141.196314 -232.009188)
		(width 0.09525)
		(layer "In13.Cu")
		(net "M_H_CPU1_SA_DQS_DN<1>")
	)
	(arc
		(start 137.436098 -232.009188)
		(mid 137.154666 -232.084943)
		(end 136.873234 -232.009188)
		(width 0.09525)
		(layer "In13.Cu")
		(net "M_H_CPU1_SA_DQS_DN<1>")
	)
	(segment
		(start 135.27786 -227.740464)
		(end 135.744712 -227.474526)
		(width 0.12954)
		(layer "F.Cu")
		(net "M_H_CPU1_SA_DQS_DN<0>")
	)
	(segment
		(start 165.227762 -201.505566)
		(end 164.841682 -201.891646)
		(width 0.16002)
		(layer "In13.Cu")
		(net "M_H_CPU1_SA_DQS_DN<0>")
	)
	(segment
		(start 175.797464 -201.310748)
		(end 175.21428 -201.310748)
		(width 0.16002)
		(layer "In13.Cu")
		(net "M_H_CPU1_SA_DQS_DN<0>")
	)
	(segment
		(start 160.954466 -201.891646)
		(end 159.785304 -201.891646)
		(width 0.16002)
		(layer "In13.Cu")
		(net "M_H_CPU1_SA_DQS_DN<0>")
	)
	(segment
		(start 161.291524 -201.383646)
		(end 161.291524 -201.554588)
		(width 0.16002)
		(layer "In13.Cu")
		(net "M_H_CPU1_SA_DQS_DN<0>")
	)
	(segment
		(start 164.841682 -201.891646)
		(end 162.296602 -201.891646)
		(width 0.16002)
		(layer "In13.Cu")
		(net "M_H_CPU1_SA_DQS_DN<0>")
	)
	(segment
		(start 150.99919 -211.375244)
		(end 144.356074 -218.01836)
		(width 0.16002)
		(layer "In13.Cu")
		(net "M_H_CPU1_SA_DQS_DN<0>")
	)
	(segment
		(start 142.64132 -224.698814)
		(end 142.573756 -224.738184)
		(width 0.09525)
		(layer "In13.Cu")
		(net "M_H_CPU1_SA_DQS_DN<0>")
	)
	(segment
		(start 176.072038 -201.585322)
		(end 175.797464 -201.310748)
		(width 0.16002)
		(layer "In13.Cu")
		(net "M_H_CPU1_SA_DQS_DN<0>")
	)
	(segment
		(start 166.133272 -201.505566)
		(end 165.227762 -201.505566)
		(width 0.16002)
		(layer "In13.Cu")
		(net "M_H_CPU1_SA_DQS_DN<0>")
	)
	(segment
		(start 161.959544 -201.554588)
		(end 161.959544 -201.383646)
		(width 0.16002)
		(layer "In13.Cu")
		(net "M_H_CPU1_SA_DQS_DN<0>")
	)
	(segment
		(start 144.356074 -221.174564)
		(end 144.356074 -221.198186)
		(width 0.09525)
		(layer "In13.Cu")
		(net "M_H_CPU1_SA_DQS_DN<0>")
	)
	(segment
		(start 141.231366 -227.128832)
		(end 141.196314 -227.149406)
		(width 0.09525)
		(layer "In13.Cu")
		(net "M_H_CPU1_SA_DQS_DN<0>")
	)
	(segment
		(start 135.898636 -227.209096)
		(end 135.744712 -227.474526)
		(width 0.09525)
		(layer "In13.Cu")
		(net "M_H_CPU1_SA_DQS_DN<0>")
	)
	(segment
		(start 170.005248 -200.631806)
		(end 167.007032 -200.631806)
		(width 0.16002)
		(layer "In13.Cu")
		(net "M_H_CPU1_SA_DQS_DN<0>")
	)
	(segment
		(start 144.356074 -218.01836)
		(end 144.356074 -221.174564)
		(width 0.16002)
		(layer "In13.Cu")
		(net "M_H_CPU1_SA_DQS_DN<0>")
	)
	(segment
		(start 144.356074 -221.198186)
		(end 144.296384 -221.257876)
		(width 0.09525)
		(layer "In13.Cu")
		(net "M_H_CPU1_SA_DQS_DN<0>")
	)
	(segment
		(start 141.704314 -226.317302)
		(end 141.633702 -226.358196)
		(width 0.09525)
		(layer "In13.Cu")
		(net "M_H_CPU1_SA_DQS_DN<0>")
	)
	(segment
		(start 143.584168 -223.077278)
		(end 143.514572 -223.117664)
		(width 0.09525)
		(layer "In13.Cu")
		(net "M_H_CPU1_SA_DQS_DN<0>")
	)
	(segment
		(start 161.291524 -201.554588)
		(end 160.954466 -201.891646)
		(width 0.16002)
		(layer "In13.Cu")
		(net "M_H_CPU1_SA_DQS_DN<0>")
	)
	(segment
		(start 159.785304 -201.891646)
		(end 150.99919 -210.67776)
		(width 0.16002)
		(layer "In13.Cu")
		(net "M_H_CPU1_SA_DQS_DN<0>")
	)
	(segment
		(start 161.451544 -201.223626)
		(end 161.291524 -201.383646)
		(width 0.16002)
		(layer "In13.Cu")
		(net "M_H_CPU1_SA_DQS_DN<0>")
	)
	(segment
		(start 138.753342 -227.149406)
		(end 138.74496 -227.14458)
		(width 0.09525)
		(layer "In13.Cu")
		(net "M_H_CPU1_SA_DQS_DN<0>")
	)
	(segment
		(start 144.296384 -221.803976)
		(end 144.296892 -221.804484)
		(width 0.09525)
		(layer "In13.Cu")
		(net "M_H_CPU1_SA_DQS_DN<0>")
	)
	(segment
		(start 143.114268 -223.887284)
		(end 143.043656 -223.928178)
		(width 0.09525)
		(layer "In13.Cu")
		(net "M_H_CPU1_SA_DQS_DN<0>")
	)
	(segment
		(start 144.296384 -221.257876)
		(end 144.296384 -221.803976)
		(width 0.09525)
		(layer "In13.Cu")
		(net "M_H_CPU1_SA_DQS_DN<0>")
	)
	(segment
		(start 144.055338 -222.26651)
		(end 143.984472 -222.307658)
		(width 0.09525)
		(layer "In13.Cu")
		(net "M_H_CPU1_SA_DQS_DN<0>")
	)
	(segment
		(start 172.443394 -201.162412)
		(end 170.535854 -201.162412)
		(width 0.16002)
		(layer "In13.Cu")
		(net "M_H_CPU1_SA_DQS_DN<0>")
	)
	(segment
		(start 175.21428 -201.310748)
		(end 175.07458 -201.450448)
		(width 0.16002)
		(layer "In13.Cu")
		(net "M_H_CPU1_SA_DQS_DN<0>")
	)
	(segment
		(start 142.174214 -225.507296)
		(end 142.104618 -225.547682)
		(width 0.09525)
		(layer "In13.Cu")
		(net "M_H_CPU1_SA_DQS_DN<0>")
	)
	(segment
		(start 140.264642 -227.14458)
		(end 140.25626 -227.149406)
		(width 0.09525)
		(layer "In13.Cu")
		(net "M_H_CPU1_SA_DQS_DN<0>")
	)
	(segment
		(start 175.07458 -201.450448)
		(end 174.59706 -201.450448)
		(width 0.16002)
		(layer "In13.Cu")
		(net "M_H_CPU1_SA_DQS_DN<0>")
	)
	(segment
		(start 173.838362 -201.310748)
		(end 173.630844 -201.518266)
		(width 0.16002)
		(layer "In13.Cu")
		(net "M_H_CPU1_SA_DQS_DN<0>")
	)
	(segment
		(start 172.799248 -201.518266)
		(end 172.443394 -201.162412)
		(width 0.16002)
		(layer "In13.Cu")
		(net "M_H_CPU1_SA_DQS_DN<0>")
	)
	(segment
		(start 161.959544 -201.383646)
		(end 161.799524 -201.223626)
		(width 0.16002)
		(layer "In13.Cu")
		(net "M_H_CPU1_SA_DQS_DN<0>")
	)
	(segment
		(start 161.799524 -201.223626)
		(end 161.451544 -201.223626)
		(width 0.16002)
		(layer "In13.Cu")
		(net "M_H_CPU1_SA_DQS_DN<0>")
	)
	(segment
		(start 174.59706 -201.450448)
		(end 174.45736 -201.310748)
		(width 0.16002)
		(layer "In13.Cu")
		(net "M_H_CPU1_SA_DQS_DN<0>")
	)
	(segment
		(start 162.296602 -201.891646)
		(end 161.959544 -201.554588)
		(width 0.16002)
		(layer "In13.Cu")
		(net "M_H_CPU1_SA_DQS_DN<0>")
	)
	(segment
		(start 139.324588 -227.14458)
		(end 139.316206 -227.149406)
		(width 0.09525)
		(layer "In13.Cu")
		(net "M_H_CPU1_SA_DQS_DN<0>")
	)
	(segment
		(start 135.999474 -227.182426)
		(end 135.898636 -227.209096)
		(width 0.09525)
		(layer "In13.Cu")
		(net "M_H_CPU1_SA_DQS_DN<0>")
	)
	(segment
		(start 173.630844 -201.518266)
		(end 172.799248 -201.518266)
		(width 0.16002)
		(layer "In13.Cu")
		(net "M_H_CPU1_SA_DQS_DN<0>")
	)
	(segment
		(start 150.99919 -210.67776)
		(end 150.99919 -211.375244)
		(width 0.16002)
		(layer "In13.Cu")
		(net "M_H_CPU1_SA_DQS_DN<0>")
	)
	(segment
		(start 170.535854 -201.162412)
		(end 170.005248 -200.631806)
		(width 0.16002)
		(layer "In13.Cu")
		(net "M_H_CPU1_SA_DQS_DN<0>")
	)
	(segment
		(start 174.45736 -201.310748)
		(end 173.838362 -201.310748)
		(width 0.16002)
		(layer "In13.Cu")
		(net "M_H_CPU1_SA_DQS_DN<0>")
	)
	(segment
		(start 137.813288 -227.149406)
		(end 137.804906 -227.14458)
		(width 0.09525)
		(layer "In13.Cu")
		(net "M_H_CPU1_SA_DQS_DN<0>")
	)
	(segment
		(start 167.007032 -200.631806)
		(end 166.133272 -201.505566)
		(width 0.16002)
		(layer "In13.Cu")
		(net "M_H_CPU1_SA_DQS_DN<0>")
	)
	(arc
		(start 138.376152 -227.149406)
		(mid 138.09472 -227.225161)
		(end 137.813288 -227.149406)
		(width 0.09525)
		(layer "In13.Cu")
		(net "M_H_CPU1_SA_DQS_DN<0>")
	)
	(arc
		(start 142.104618 -225.547682)
		(mid 141.98882 -225.682076)
		(end 141.947138 -225.854514)
		(width 0.09525)
		(layer "In13.Cu")
		(net "M_H_CPU1_SA_DQS_DN<0>")
	)
	(arc
		(start 143.514572 -223.117664)
		(mid 143.398774 -223.252058)
		(end 143.357092 -223.424496)
		(width 0.09525)
		(layer "In13.Cu")
		(net "M_H_CPU1_SA_DQS_DN<0>")
	)
	(arc
		(start 139.693396 -227.149406)
		(mid 139.509621 -227.098634)
		(end 139.324588 -227.14458)
		(width 0.09525)
		(layer "In13.Cu")
		(net "M_H_CPU1_SA_DQS_DN<0>")
	)
	(arc
		(start 142.573756 -224.738184)
		(mid 142.458482 -224.872462)
		(end 142.417038 -225.044508)
		(width 0.09525)
		(layer "In13.Cu")
		(net "M_H_CPU1_SA_DQS_DN<0>")
	)
	(arc
		(start 141.476984 -226.66452)
		(mid 141.411737 -226.927123)
		(end 141.231366 -227.128832)
		(width 0.09525)
		(layer "In13.Cu")
		(net "M_H_CPU1_SA_DQS_DN<0>")
	)
	(arc
		(start 137.804906 -227.14458)
		(mid 137.619874 -227.098666)
		(end 137.436098 -227.149406)
		(width 0.09525)
		(layer "In13.Cu")
		(net "M_H_CPU1_SA_DQS_DN<0>")
	)
	(arc
		(start 143.357092 -223.424496)
		(mid 143.292695 -223.685802)
		(end 143.114268 -223.887284)
		(width 0.09525)
		(layer "In13.Cu")
		(net "M_H_CPU1_SA_DQS_DN<0>")
	)
	(arc
		(start 142.417038 -225.044508)
		(mid 142.352641 -225.305814)
		(end 142.174214 -225.507296)
		(width 0.09525)
		(layer "In13.Cu")
		(net "M_H_CPU1_SA_DQS_DN<0>")
	)
	(arc
		(start 136.020048 -227.190554)
		(mid 136.00972 -227.186594)
		(end 135.999474 -227.182426)
		(width 0.09525)
		(layer "In13.Cu")
		(net "M_H_CPU1_SA_DQS_DN<0>")
	)
	(arc
		(start 139.316206 -227.149406)
		(mid 139.034774 -227.225161)
		(end 138.753342 -227.149406)
		(width 0.09525)
		(layer "In13.Cu")
		(net "M_H_CPU1_SA_DQS_DN<0>")
	)
	(arc
		(start 143.984472 -222.307658)
		(mid 143.868674 -222.442052)
		(end 143.826992 -222.61449)
		(width 0.09525)
		(layer "In13.Cu")
		(net "M_H_CPU1_SA_DQS_DN<0>")
	)
	(arc
		(start 143.043656 -223.928178)
		(mid 142.928382 -224.062456)
		(end 142.886938 -224.234502)
		(width 0.09525)
		(layer "In13.Cu")
		(net "M_H_CPU1_SA_DQS_DN<0>")
	)
	(arc
		(start 142.886938 -224.234502)
		(mid 142.821691 -224.497105)
		(end 142.64132 -224.698814)
		(width 0.09525)
		(layer "In13.Cu")
		(net "M_H_CPU1_SA_DQS_DN<0>")
	)
	(arc
		(start 136.873234 -227.149406)
		(mid 136.684766 -227.098729)
		(end 136.496298 -227.149406)
		(width 0.09525)
		(layer "In13.Cu")
		(net "M_H_CPU1_SA_DQS_DN<0>")
	)
	(arc
		(start 140.63345 -227.149406)
		(mid 140.449675 -227.098634)
		(end 140.264642 -227.14458)
		(width 0.09525)
		(layer "In13.Cu")
		(net "M_H_CPU1_SA_DQS_DN<0>")
	)
	(arc
		(start 141.633702 -226.358196)
		(mid 141.518428 -226.492474)
		(end 141.476984 -226.66452)
		(width 0.09525)
		(layer "In13.Cu")
		(net "M_H_CPU1_SA_DQS_DN<0>")
	)
	(arc
		(start 143.826992 -222.61449)
		(mid 143.762595 -222.875796)
		(end 143.584168 -223.077278)
		(width 0.09525)
		(layer "In13.Cu")
		(net "M_H_CPU1_SA_DQS_DN<0>")
	)
	(arc
		(start 144.296892 -221.804484)
		(mid 144.232857 -222.065161)
		(end 144.055338 -222.26651)
		(width 0.09525)
		(layer "In13.Cu")
		(net "M_H_CPU1_SA_DQS_DN<0>")
	)
	(arc
		(start 140.25626 -227.149406)
		(mid 139.974828 -227.225161)
		(end 139.693396 -227.149406)
		(width 0.09525)
		(layer "In13.Cu")
		(net "M_H_CPU1_SA_DQS_DN<0>")
	)
	(arc
		(start 141.196314 -227.149406)
		(mid 140.914882 -227.225161)
		(end 140.63345 -227.149406)
		(width 0.09525)
		(layer "In13.Cu")
		(net "M_H_CPU1_SA_DQS_DN<0>")
	)
	(arc
		(start 141.947138 -225.854514)
		(mid 141.882741 -226.11582)
		(end 141.704314 -226.317302)
		(width 0.09525)
		(layer "In13.Cu")
		(net "M_H_CPU1_SA_DQS_DN<0>")
	)
	(arc
		(start 136.496298 -227.149406)
		(mid 136.262784 -227.223249)
		(end 136.020048 -227.190554)
		(width 0.09525)
		(layer "In13.Cu")
		(net "M_H_CPU1_SA_DQS_DN<0>")
	)
	(arc
		(start 137.436098 -227.149406)
		(mid 137.154666 -227.225161)
		(end 136.873234 -227.149406)
		(width 0.09525)
		(layer "In13.Cu")
		(net "M_H_CPU1_SA_DQS_DN<0>")
	)
	(arc
		(start 138.74496 -227.14458)
		(mid 138.559928 -227.098666)
		(end 138.376152 -227.149406)
		(width 0.09525)
		(layer "In13.Cu")
		(net "M_H_CPU1_SA_DQS_DN<0>")
	)
	(segment
		(start 134.337806 -230.980234)
		(end 134.804658 -230.71455)
		(width 0.10668)
		(layer "F.Cu")
		(net "M_H_CPU1_SA_DQ<9>")
	)
	(segment
		(start 140.257784 -231.036876)
		(end 140.266166 -231.041702)
		(width 0.0889)
		(layer "In13.Cu")
		(net "M_H_CPU1_SA_DQ<9>")
	)
	(segment
		(start 143.885412 -230.248206)
		(end 143.921988 -230.22687)
		(width 0.0889)
		(layer "In13.Cu")
		(net "M_H_CPU1_SA_DQ<9>")
	)
	(segment
		(start 166.620698 -208.360772)
		(end 170.531282 -208.360772)
		(width 0.14478)
		(layer "In13.Cu")
		(net "M_H_CPU1_SA_DQ<9>")
	)
	(segment
		(start 173.935644 -208.810352)
		(end 176.072038 -208.38541)
		(width 0.14478)
		(layer "In13.Cu")
		(net "M_H_CPU1_SA_DQ<9>")
	)
	(segment
		(start 161.102548 -208.810352)
		(end 165.535356 -208.810352)
		(width 0.14478)
		(layer "In13.Cu")
		(net "M_H_CPU1_SA_DQ<9>")
	)
	(segment
		(start 143.077692 -231.036876)
		(end 143.086074 -231.041702)
		(width 0.0889)
		(layer "In13.Cu")
		(net "M_H_CPU1_SA_DQ<9>")
	)
	(segment
		(start 145.057876 -228.649784)
		(end 145.122646 -228.649784)
		(width 0.0889)
		(layer "In13.Cu")
		(net "M_H_CPU1_SA_DQ<9>")
	)
	(segment
		(start 138.743436 -231.041702)
		(end 138.751818 -231.036876)
		(width 0.0889)
		(layer "In13.Cu")
		(net "M_H_CPU1_SA_DQ<9>")
	)
	(segment
		(start 134.650734 -230.97998)
		(end 134.673086 -231.063038)
		(width 0.0889)
		(layer "In13.Cu")
		(net "M_H_CPU1_SA_DQ<9>")
	)
	(segment
		(start 143.451834 -231.036876)
		(end 143.486378 -231.01681)
		(width 0.0889)
		(layer "In13.Cu")
		(net "M_H_CPU1_SA_DQ<9>")
	)
	(segment
		(start 142.503398 -231.041702)
		(end 142.51178 -231.036876)
		(width 0.0889)
		(layer "In13.Cu")
		(net "M_H_CPU1_SA_DQ<9>")
	)
	(segment
		(start 148.638514 -220.61297)
		(end 155.084272 -214.167212)
		(width 0.14478)
		(layer "In13.Cu")
		(net "M_H_CPU1_SA_DQ<9>")
	)
	(segment
		(start 147.04187 -226.73056)
		(end 147.04187 -226.483164)
		(width 0.0889)
		(layer "In13.Cu")
		(net "M_H_CPU1_SA_DQ<9>")
	)
	(segment
		(start 170.531282 -208.360772)
		(end 171.616624 -208.810352)
		(width 0.14478)
		(layer "In13.Cu")
		(net "M_H_CPU1_SA_DQ<9>")
	)
	(segment
		(start 144.10309 -229.60457)
		(end 145.057876 -228.649784)
		(width 0.0889)
		(layer "In13.Cu")
		(net "M_H_CPU1_SA_DQ<9>")
	)
	(segment
		(start 147.04187 -226.483164)
		(end 147.30349 -226.221544)
		(width 0.0889)
		(layer "In13.Cu")
		(net "M_H_CPU1_SA_DQ<9>")
	)
	(segment
		(start 139.31773 -231.036876)
		(end 139.326112 -231.041702)
		(width 0.0889)
		(layer "In13.Cu")
		(net "M_H_CPU1_SA_DQ<9>")
	)
	(segment
		(start 145.122646 -228.649784)
		(end 147.04187 -226.73056)
		(width 0.0889)
		(layer "In13.Cu")
		(net "M_H_CPU1_SA_DQ<9>")
	)
	(segment
		(start 165.535356 -208.810352)
		(end 166.620698 -208.360772)
		(width 0.14478)
		(layer "In13.Cu")
		(net "M_H_CPU1_SA_DQ<9>")
	)
	(segment
		(start 144.10309 -229.911656)
		(end 144.10309 -229.60457)
		(width 0.0889)
		(layer "In13.Cu")
		(net "M_H_CPU1_SA_DQ<9>")
	)
	(segment
		(start 135.557768 -231.036876)
		(end 135.56615 -231.041702)
		(width 0.0889)
		(layer "In13.Cu")
		(net "M_H_CPU1_SA_DQ<9>")
	)
	(segment
		(start 155.745688 -214.167212)
		(end 161.102548 -208.810352)
		(width 0.14478)
		(layer "In13.Cu")
		(net "M_H_CPU1_SA_DQ<9>")
	)
	(segment
		(start 147.30349 -226.221544)
		(end 148.638514 -224.88652)
		(width 0.14478)
		(layer "In13.Cu")
		(net "M_H_CPU1_SA_DQ<9>")
	)
	(segment
		(start 171.616624 -208.810352)
		(end 173.935644 -208.810352)
		(width 0.14478)
		(layer "In13.Cu")
		(net "M_H_CPU1_SA_DQ<9>")
	)
	(segment
		(start 155.084272 -214.167212)
		(end 155.745688 -214.167212)
		(width 0.14478)
		(layer "In13.Cu")
		(net "M_H_CPU1_SA_DQ<9>")
	)
	(segment
		(start 148.638514 -224.88652)
		(end 148.638514 -220.61297)
		(width 0.14478)
		(layer "In13.Cu")
		(net "M_H_CPU1_SA_DQ<9>")
	)
	(segment
		(start 137.803382 -231.041702)
		(end 137.811764 -231.036876)
		(width 0.0889)
		(layer "In13.Cu")
		(net "M_H_CPU1_SA_DQ<9>")
	)
	(segment
		(start 134.804658 -230.71455)
		(end 134.650734 -230.97998)
		(width 0.0889)
		(layer "In13.Cu")
		(net "M_H_CPU1_SA_DQ<9>")
	)
	(arc
		(start 142.51178 -231.036876)
		(mid 142.794736 -230.960699)
		(end 143.077692 -231.036876)
		(width 0.0889)
		(layer "In13.Cu")
		(net "M_H_CPU1_SA_DQ<9>")
	)
	(arc
		(start 143.921988 -230.22687)
		(mid 144.054547 -230.093408)
		(end 144.10309 -229.911656)
		(width 0.0889)
		(layer "In13.Cu")
		(net "M_H_CPU1_SA_DQ<9>")
	)
	(arc
		(start 140.631926 -231.036876)
		(mid 140.914882 -230.960699)
		(end 141.197838 -231.036876)
		(width 0.0889)
		(layer "In13.Cu")
		(net "M_H_CPU1_SA_DQ<9>")
	)
	(arc
		(start 140.266166 -231.041702)
		(mid 140.449674 -231.087227)
		(end 140.631926 -231.036876)
		(width 0.0889)
		(layer "In13.Cu")
		(net "M_H_CPU1_SA_DQ<9>")
	)
	(arc
		(start 138.751818 -231.036876)
		(mid 139.034774 -230.960699)
		(end 139.31773 -231.036876)
		(width 0.0889)
		(layer "In13.Cu")
		(net "M_H_CPU1_SA_DQ<9>")
	)
	(arc
		(start 138.377676 -231.036876)
		(mid 138.559927 -231.08726)
		(end 138.743436 -231.041702)
		(width 0.0889)
		(layer "In13.Cu")
		(net "M_H_CPU1_SA_DQ<9>")
	)
	(arc
		(start 143.486378 -231.01681)
		(mid 143.599043 -230.883969)
		(end 143.63954 -230.71455)
		(width 0.0889)
		(layer "In13.Cu")
		(net "M_H_CPU1_SA_DQ<9>")
	)
	(arc
		(start 134.673086 -231.063038)
		(mid 134.835418 -231.085872)
		(end 134.991856 -231.036876)
		(width 0.0889)
		(layer "In13.Cu")
		(net "M_H_CPU1_SA_DQ<9>")
	)
	(arc
		(start 135.56615 -231.041702)
		(mid 135.749658 -231.087227)
		(end 135.93191 -231.036876)
		(width 0.0889)
		(layer "In13.Cu")
		(net "M_H_CPU1_SA_DQ<9>")
	)
	(arc
		(start 136.87171 -231.036876)
		(mid 137.154666 -230.960699)
		(end 137.437622 -231.036876)
		(width 0.0889)
		(layer "In13.Cu")
		(net "M_H_CPU1_SA_DQ<9>")
	)
	(arc
		(start 143.63954 -230.71455)
		(mid 143.704776 -230.450959)
		(end 143.885412 -230.248206)
		(width 0.0889)
		(layer "In13.Cu")
		(net "M_H_CPU1_SA_DQ<9>")
	)
	(arc
		(start 137.437622 -231.036876)
		(mid 137.619873 -231.08726)
		(end 137.803382 -231.041702)
		(width 0.0889)
		(layer "In13.Cu")
		(net "M_H_CPU1_SA_DQ<9>")
	)
	(arc
		(start 134.991856 -231.036876)
		(mid 135.274812 -230.960699)
		(end 135.557768 -231.036876)
		(width 0.0889)
		(layer "In13.Cu")
		(net "M_H_CPU1_SA_DQ<9>")
	)
	(arc
		(start 135.93191 -231.036876)
		(mid 136.214866 -230.960699)
		(end 136.497822 -231.036876)
		(width 0.0889)
		(layer "In13.Cu")
		(net "M_H_CPU1_SA_DQ<9>")
	)
	(arc
		(start 143.086074 -231.041702)
		(mid 143.269582 -231.087227)
		(end 143.451834 -231.036876)
		(width 0.0889)
		(layer "In13.Cu")
		(net "M_H_CPU1_SA_DQ<9>")
	)
	(arc
		(start 142.137638 -231.036876)
		(mid 142.319889 -231.08726)
		(end 142.503398 -231.041702)
		(width 0.0889)
		(layer "In13.Cu")
		(net "M_H_CPU1_SA_DQ<9>")
	)
	(arc
		(start 139.691872 -231.036876)
		(mid 139.974828 -230.960699)
		(end 140.257784 -231.036876)
		(width 0.0889)
		(layer "In13.Cu")
		(net "M_H_CPU1_SA_DQ<9>")
	)
	(arc
		(start 141.197838 -231.036876)
		(mid 141.384782 -231.087165)
		(end 141.571726 -231.036876)
		(width 0.0889)
		(layer "In13.Cu")
		(net "M_H_CPU1_SA_DQ<9>")
	)
	(arc
		(start 137.811764 -231.036876)
		(mid 138.09472 -230.960699)
		(end 138.377676 -231.036876)
		(width 0.0889)
		(layer "In13.Cu")
		(net "M_H_CPU1_SA_DQ<9>")
	)
	(arc
		(start 139.326112 -231.041702)
		(mid 139.50962 -231.087227)
		(end 139.691872 -231.036876)
		(width 0.0889)
		(layer "In13.Cu")
		(net "M_H_CPU1_SA_DQ<9>")
	)
	(arc
		(start 136.497822 -231.036876)
		(mid 136.684766 -231.087165)
		(end 136.87171 -231.036876)
		(width 0.0889)
		(layer "In13.Cu")
		(net "M_H_CPU1_SA_DQ<9>")
	)
	(arc
		(start 141.571726 -231.036876)
		(mid 141.854682 -230.960699)
		(end 142.137638 -231.036876)
		(width 0.0889)
		(layer "In13.Cu")
		(net "M_H_CPU1_SA_DQ<9>")
	)
	(segment
		(start 135.748014 -230.170228)
		(end 136.214866 -229.90429)
		(width 0.10668)
		(layer "F.Cu")
		(net "M_H_CPU1_SA_DQ<8>")
	)
	(segment
		(start 137.907776 -230.22687)
		(end 137.916158 -230.231696)
		(width 0.0889)
		(layer "In13.Cu")
		(net "M_H_CPU1_SA_DQ<8>")
	)
	(segment
		(start 136.060688 -230.16972)
		(end 136.08304 -230.253032)
		(width 0.0889)
		(layer "In13.Cu")
		(net "M_H_CPU1_SA_DQ<8>")
	)
	(segment
		(start 147.739354 -220.179138)
		(end 160.774634 -207.143858)
		(width 0.14478)
		(layer "In13.Cu")
		(net "M_H_CPU1_SA_DQ<8>")
	)
	(segment
		(start 144.32788 -227.788216)
		(end 146.971766 -225.14433)
		(width 0.0889)
		(layer "In13.Cu")
		(net "M_H_CPU1_SA_DQ<8>")
	)
	(segment
		(start 136.967722 -230.22687)
		(end 136.976104 -230.231696)
		(width 0.0889)
		(layer "In13.Cu")
		(net "M_H_CPU1_SA_DQ<8>")
	)
	(segment
		(start 140.15339 -230.231696)
		(end 140.161772 -230.22687)
		(width 0.0889)
		(layer "In13.Cu")
		(net "M_H_CPU1_SA_DQ<8>")
	)
	(segment
		(start 147.739354 -223.947482)
		(end 147.739354 -220.179138)
		(width 0.14478)
		(layer "In13.Cu")
		(net "M_H_CPU1_SA_DQ<8>")
	)
	(segment
		(start 160.774634 -207.143858)
		(end 166.140892 -207.143858)
		(width 0.14478)
		(layer "In13.Cu")
		(net "M_H_CPU1_SA_DQ<8>")
	)
	(segment
		(start 143.73479 -229.338886)
		(end 143.73479 -229.332536)
		(width 0.0889)
		(layer "In13.Cu")
		(net "M_H_CPU1_SA_DQ<8>")
	)
	(segment
		(start 146.971766 -224.71507)
		(end 147.739354 -223.947482)
		(width 0.0889)
		(layer "In13.Cu")
		(net "M_H_CPU1_SA_DQ<8>")
	)
	(segment
		(start 173.935644 -207.11033)
		(end 176.072038 -206.685388)
		(width 0.14478)
		(layer "In13.Cu")
		(net "M_H_CPU1_SA_DQ<8>")
	)
	(segment
		(start 136.214866 -229.90429)
		(end 136.060688 -230.16972)
		(width 0.0889)
		(layer "In13.Cu")
		(net "M_H_CPU1_SA_DQ<8>")
	)
	(segment
		(start 166.140892 -207.143858)
		(end 167.024304 -206.260446)
		(width 0.14478)
		(layer "In13.Cu")
		(net "M_H_CPU1_SA_DQ<8>")
	)
	(segment
		(start 141.667738 -230.22687)
		(end 141.67612 -230.231696)
		(width 0.0889)
		(layer "In13.Cu")
		(net "M_H_CPU1_SA_DQ<8>")
	)
	(segment
		(start 146.971766 -225.14433)
		(end 146.971766 -224.71507)
		(width 0.0889)
		(layer "In13.Cu")
		(net "M_H_CPU1_SA_DQ<8>")
	)
	(segment
		(start 141.093444 -230.231696)
		(end 141.101826 -230.22687)
		(width 0.0889)
		(layer "In13.Cu")
		(net "M_H_CPU1_SA_DQ<8>")
	)
	(segment
		(start 167.024304 -206.260446)
		(end 169.776902 -206.260446)
		(width 0.14478)
		(layer "In13.Cu")
		(net "M_H_CPU1_SA_DQ<8>")
	)
	(segment
		(start 169.776902 -206.260446)
		(end 170.626786 -207.11033)
		(width 0.14478)
		(layer "In13.Cu")
		(net "M_H_CPU1_SA_DQ<8>")
	)
	(segment
		(start 142.98168 -230.22687)
		(end 143.01343 -230.208582)
		(width 0.0889)
		(layer "In13.Cu")
		(net "M_H_CPU1_SA_DQ<8>")
	)
	(segment
		(start 143.73479 -229.332536)
		(end 144.32788 -228.739446)
		(width 0.0889)
		(layer "In13.Cu")
		(net "M_H_CPU1_SA_DQ<8>")
	)
	(segment
		(start 136.393428 -230.231696)
		(end 136.40181 -230.22687)
		(width 0.0889)
		(layer "In13.Cu")
		(net "M_H_CPU1_SA_DQ<8>")
	)
	(segment
		(start 170.626786 -207.11033)
		(end 173.935644 -207.11033)
		(width 0.14478)
		(layer "In13.Cu")
		(net "M_H_CPU1_SA_DQ<8>")
	)
	(segment
		(start 144.32788 -228.739446)
		(end 144.32788 -227.788216)
		(width 0.0889)
		(layer "In13.Cu")
		(net "M_H_CPU1_SA_DQ<8>")
	)
	(arc
		(start 142.04188 -230.22687)
		(mid 142.324836 -230.150727)
		(end 142.607792 -230.22687)
		(width 0.0889)
		(layer "In13.Cu")
		(net "M_H_CPU1_SA_DQ<8>")
	)
	(arc
		(start 138.281918 -230.22687)
		(mid 138.564874 -230.150727)
		(end 138.84783 -230.22687)
		(width 0.0889)
		(layer "In13.Cu")
		(net "M_H_CPU1_SA_DQ<8>")
	)
	(arc
		(start 138.84783 -230.22687)
		(mid 139.034774 -230.277125)
		(end 139.221718 -230.22687)
		(width 0.0889)
		(layer "In13.Cu")
		(net "M_H_CPU1_SA_DQ<8>")
	)
	(arc
		(start 141.101826 -230.22687)
		(mid 141.384782 -230.150727)
		(end 141.667738 -230.22687)
		(width 0.0889)
		(layer "In13.Cu")
		(net "M_H_CPU1_SA_DQ<8>")
	)
	(arc
		(start 139.78763 -230.22687)
		(mid 139.969881 -230.27722)
		(end 140.15339 -230.231696)
		(width 0.0889)
		(layer "In13.Cu")
		(net "M_H_CPU1_SA_DQ<8>")
	)
	(arc
		(start 136.08304 -230.253032)
		(mid 136.24055 -230.27623)
		(end 136.393428 -230.231696)
		(width 0.0889)
		(layer "In13.Cu")
		(net "M_H_CPU1_SA_DQ<8>")
	)
	(arc
		(start 137.916158 -230.231696)
		(mid 138.099666 -230.27719)
		(end 138.281918 -230.22687)
		(width 0.0889)
		(layer "In13.Cu")
		(net "M_H_CPU1_SA_DQ<8>")
	)
	(arc
		(start 143.01343 -230.208582)
		(mid 143.128106 -230.075248)
		(end 143.169386 -229.90429)
		(width 0.0889)
		(layer "In13.Cu")
		(net "M_H_CPU1_SA_DQ<8>")
	)
	(arc
		(start 140.727684 -230.22687)
		(mid 140.909935 -230.27722)
		(end 141.093444 -230.231696)
		(width 0.0889)
		(layer "In13.Cu")
		(net "M_H_CPU1_SA_DQ<8>")
	)
	(arc
		(start 136.976104 -230.231696)
		(mid 137.159612 -230.27719)
		(end 137.341864 -230.22687)
		(width 0.0889)
		(layer "In13.Cu")
		(net "M_H_CPU1_SA_DQ<8>")
	)
	(arc
		(start 143.169386 -229.90429)
		(mid 143.233901 -229.642071)
		(end 143.412718 -229.439724)
		(width 0.0889)
		(layer "In13.Cu")
		(net "M_H_CPU1_SA_DQ<8>")
	)
	(arc
		(start 142.607792 -230.22687)
		(mid 142.794736 -230.277125)
		(end 142.98168 -230.22687)
		(width 0.0889)
		(layer "In13.Cu")
		(net "M_H_CPU1_SA_DQ<8>")
	)
	(arc
		(start 136.40181 -230.22687)
		(mid 136.684766 -230.150727)
		(end 136.967722 -230.22687)
		(width 0.0889)
		(layer "In13.Cu")
		(net "M_H_CPU1_SA_DQ<8>")
	)
	(arc
		(start 139.221718 -230.22687)
		(mid 139.504674 -230.150727)
		(end 139.78763 -230.22687)
		(width 0.0889)
		(layer "In13.Cu")
		(net "M_H_CPU1_SA_DQ<8>")
	)
	(arc
		(start 143.412718 -229.439724)
		(mid 143.566053 -229.3647)
		(end 143.73479 -229.338886)
		(width 0.0889)
		(layer "In13.Cu")
		(net "M_H_CPU1_SA_DQ<8>")
	)
	(arc
		(start 137.341864 -230.22687)
		(mid 137.62482 -230.150727)
		(end 137.907776 -230.22687)
		(width 0.0889)
		(layer "In13.Cu")
		(net "M_H_CPU1_SA_DQ<8>")
	)
	(arc
		(start 140.161772 -230.22687)
		(mid 140.444728 -230.150727)
		(end 140.727684 -230.22687)
		(width 0.0889)
		(layer "In13.Cu")
		(net "M_H_CPU1_SA_DQ<8>")
	)
	(arc
		(start 141.67612 -230.231696)
		(mid 141.859628 -230.27719)
		(end 142.04188 -230.22687)
		(width 0.0889)
		(layer "In13.Cu")
		(net "M_H_CPU1_SA_DQ<8>")
	)
	(segment
		(start 133.867906 -230.170228)
		(end 134.334758 -229.90429)
		(width 0.10668)
		(layer "F.Cu")
		(net "M_H_CPU1_SA_DQ<7>")
	)
	(segment
		(start 150.855934 -215.87714)
		(end 150.855934 -215.672416)
		(width 0.14478)
		(layer "In13.Cu")
		(net "M_H_CPU1_SA_DQ<7>")
	)
	(segment
		(start 162.332924 -206.260446)
		(end 162.477704 -206.405226)
		(width 0.14478)
		(layer "In13.Cu")
		(net "M_H_CPU1_SA_DQ<7>")
	)
	(segment
		(start 143.045942 -228.790246)
		(end 143.077692 -228.771958)
		(width 0.0889)
		(layer "In13.Cu")
		(net "M_H_CPU1_SA_DQ<7>")
	)
	(segment
		(start 149.991572 -217.147394)
		(end 150.176738 -216.962228)
		(width 0.14478)
		(layer "In13.Cu")
		(net "M_H_CPU1_SA_DQ<7>")
	)
	(segment
		(start 153.890472 -213.248494)
		(end 154.075638 -213.063328)
		(width 0.14478)
		(layer "In13.Cu")
		(net "M_H_CPU1_SA_DQ<7>")
	)
	(segment
		(start 151.0411 -215.48725)
		(end 151.245824 -215.48725)
		(width 0.14478)
		(layer "In13.Cu")
		(net "M_H_CPU1_SA_DQ<7>")
	)
	(segment
		(start 161.230564 -206.260446)
		(end 161.375344 -206.405226)
		(width 0.14478)
		(layer "In13.Cu")
		(net "M_H_CPU1_SA_DQ<7>")
	)
	(segment
		(start 152.805384 -213.92769)
		(end 152.905968 -214.028274)
		(width 0.14478)
		(layer "In13.Cu")
		(net "M_H_CPU1_SA_DQ<7>")
	)
	(segment
		(start 148.516594 -218.011756)
		(end 148.70176 -217.82659)
		(width 0.14478)
		(layer "In13.Cu")
		(net "M_H_CPU1_SA_DQ<7>")
	)
	(segment
		(start 154.94 -211.58835)
		(end 155.144724 -211.58835)
		(width 0.14478)
		(layer "In13.Cu")
		(net "M_H_CPU1_SA_DQ<7>")
	)
	(segment
		(start 141.667738 -229.581964)
		(end 141.67612 -229.577138)
		(width 0.0889)
		(layer "In13.Cu")
		(net "M_H_CPU1_SA_DQ<7>")
	)
	(segment
		(start 145.647664 -225.194368)
		(end 147.188174 -223.653858)
		(width 0.0889)
		(layer "In13.Cu")
		(net "M_H_CPU1_SA_DQ<7>")
	)
	(segment
		(start 148.906484 -217.82659)
		(end 149.007068 -217.927174)
		(width 0.14478)
		(layer "In13.Cu")
		(net "M_H_CPU1_SA_DQ<7>")
	)
	(segment
		(start 151.245824 -215.48725)
		(end 151.346408 -215.587834)
		(width 0.14478)
		(layer "In13.Cu")
		(net "M_H_CPU1_SA_DQ<7>")
	)
	(segment
		(start 153.685748 -213.248494)
		(end 153.890472 -213.248494)
		(width 0.14478)
		(layer "In13.Cu")
		(net "M_H_CPU1_SA_DQ<7>")
	)
	(segment
		(start 154.465528 -212.468714)
		(end 154.670252 -212.468714)
		(width 0.14478)
		(layer "In13.Cu")
		(net "M_H_CPU1_SA_DQ<7>")
	)
	(segment
		(start 154.855418 -212.078824)
		(end 154.754834 -211.97824)
		(width 0.14478)
		(layer "In13.Cu")
		(net "M_H_CPU1_SA_DQ<7>")
	)
	(segment
		(start 152.905968 -214.028274)
		(end 153.110692 -214.028274)
		(width 0.14478)
		(layer "In13.Cu")
		(net "M_H_CPU1_SA_DQ<7>")
	)
	(segment
		(start 152.330912 -214.808054)
		(end 152.516078 -214.622888)
		(width 0.14478)
		(layer "In13.Cu")
		(net "M_H_CPU1_SA_DQ<7>")
	)
	(segment
		(start 151.635714 -214.892636)
		(end 151.82088 -214.70747)
		(width 0.14478)
		(layer "In13.Cu")
		(net "M_H_CPU1_SA_DQ<7>")
	)
	(segment
		(start 162.622484 -206.576422)
		(end 162.884104 -206.576422)
		(width 0.14478)
		(layer "In13.Cu")
		(net "M_H_CPU1_SA_DQ<7>")
	)
	(segment
		(start 136.393428 -229.577138)
		(end 136.40181 -229.581964)
		(width 0.0889)
		(layer "In13.Cu")
		(net "M_H_CPU1_SA_DQ<7>")
	)
	(segment
		(start 162.477704 -206.405226)
		(end 162.477704 -206.431642)
		(width 0.14478)
		(layer "In13.Cu")
		(net "M_H_CPU1_SA_DQ<7>")
	)
	(segment
		(start 170.611038 -206.260446)
		(end 171.546774 -206.260446)
		(width 0.14478)
		(layer "In13.Cu")
		(net "M_H_CPU1_SA_DQ<7>")
	)
	(segment
		(start 154.855418 -212.283548)
		(end 154.855418 -212.078824)
		(width 0.14478)
		(layer "In13.Cu")
		(net "M_H_CPU1_SA_DQ<7>")
	)
	(segment
		(start 137.907776 -229.581964)
		(end 137.916158 -229.577138)
		(width 0.0889)
		(layer "In13.Cu")
		(net "M_H_CPU1_SA_DQ<7>")
	)
	(segment
		(start 150.26132 -216.26703)
		(end 150.466044 -216.26703)
		(width 0.14478)
		(layer "In13.Cu")
		(net "M_H_CPU1_SA_DQ<7>")
	)
	(segment
		(start 140.15339 -229.577138)
		(end 140.161772 -229.581964)
		(width 0.0889)
		(layer "In13.Cu")
		(net "M_H_CPU1_SA_DQ<7>")
	)
	(segment
		(start 149.48154 -217.04681)
		(end 149.686264 -217.04681)
		(width 0.14478)
		(layer "In13.Cu")
		(net "M_H_CPU1_SA_DQ<7>")
	)
	(segment
		(start 153.38044 -213.14791)
		(end 153.585164 -213.14791)
		(width 0.14478)
		(layer "In13.Cu")
		(net "M_H_CPU1_SA_DQ<7>")
	)
	(segment
		(start 154.670252 -212.468714)
		(end 154.855418 -212.283548)
		(width 0.14478)
		(layer "In13.Cu")
		(net "M_H_CPU1_SA_DQ<7>")
	)
	(segment
		(start 151.551132 -215.587834)
		(end 151.736298 -215.402668)
		(width 0.14478)
		(layer "In13.Cu")
		(net "M_H_CPU1_SA_DQ<7>")
	)
	(segment
		(start 151.346408 -215.587834)
		(end 151.551132 -215.587834)
		(width 0.14478)
		(layer "In13.Cu")
		(net "M_H_CPU1_SA_DQ<7>")
	)
	(segment
		(start 151.736298 -215.402668)
		(end 151.736298 -215.197944)
		(width 0.14478)
		(layer "In13.Cu")
		(net "M_H_CPU1_SA_DQ<7>")
	)
	(segment
		(start 150.771352 -216.367614)
		(end 150.956518 -216.182448)
		(width 0.14478)
		(layer "In13.Cu")
		(net "M_H_CPU1_SA_DQ<7>")
	)
	(segment
		(start 148.617178 -218.317064)
		(end 148.516594 -218.21648)
		(width 0.14478)
		(layer "In13.Cu")
		(net "M_H_CPU1_SA_DQ<7>")
	)
	(segment
		(start 145.647664 -226.075748)
		(end 145.647664 -225.194368)
		(width 0.0889)
		(layer "In13.Cu")
		(net "M_H_CPU1_SA_DQ<7>")
	)
	(segment
		(start 151.635714 -215.09736)
		(end 151.635714 -214.892636)
		(width 0.14478)
		(layer "In13.Cu")
		(net "M_H_CPU1_SA_DQ<7>")
	)
	(segment
		(start 134.488682 -229.63886)
		(end 134.58444 -229.61346)
		(width 0.0889)
		(layer "In13.Cu")
		(net "M_H_CPU1_SA_DQ<7>")
	)
	(segment
		(start 148.126704 -218.60637)
		(end 148.227288 -218.706954)
		(width 0.14478)
		(layer "In13.Cu")
		(net "M_H_CPU1_SA_DQ<7>")
	)
	(segment
		(start 166.065708 -206.260446)
		(end 166.915846 -205.410308)
		(width 0.14478)
		(layer "In13.Cu")
		(net "M_H_CPU1_SA_DQ<7>")
	)
	(segment
		(start 161.375344 -206.405226)
		(end 161.375344 -206.431642)
		(width 0.14478)
		(layer "In13.Cu")
		(net "M_H_CPU1_SA_DQ<7>")
	)
	(segment
		(start 150.176738 -216.962228)
		(end 150.176738 -216.757504)
		(width 0.14478)
		(layer "In13.Cu")
		(net "M_H_CPU1_SA_DQ<7>")
	)
	(segment
		(start 149.396958 -217.742008)
		(end 149.396958 -217.537284)
		(width 0.14478)
		(layer "In13.Cu")
		(net "M_H_CPU1_SA_DQ<7>")
	)
	(segment
		(start 142.607792 -229.581964)
		(end 142.644114 -229.560882)
		(width 0.0889)
		(layer "In13.Cu")
		(net "M_H_CPU1_SA_DQ<7>")
	)
	(segment
		(start 147.188174 -223.653858)
		(end 147.188174 -222.544894)
		(width 0.0889)
		(layer "In13.Cu")
		(net "M_H_CPU1_SA_DQ<7>")
	)
	(segment
		(start 147.188174 -219.950792)
		(end 147.837398 -219.301568)
		(width 0.14478)
		(layer "In13.Cu")
		(net "M_H_CPU1_SA_DQ<7>")
	)
	(segment
		(start 136.967722 -229.581964)
		(end 136.976104 -229.577138)
		(width 0.0889)
		(layer "In13.Cu")
		(net "M_H_CPU1_SA_DQ<7>")
	)
	(segment
		(start 163.028884 -206.405226)
		(end 163.173664 -206.260446)
		(width 0.14478)
		(layer "In13.Cu")
		(net "M_H_CPU1_SA_DQ<7>")
	)
	(segment
		(start 153.110692 -214.028274)
		(end 153.295858 -213.843108)
		(width 0.14478)
		(layer "In13.Cu")
		(net "M_H_CPU1_SA_DQ<7>")
	)
	(segment
		(start 150.956518 -216.182448)
		(end 150.956518 -215.977724)
		(width 0.14478)
		(layer "In13.Cu")
		(net "M_H_CPU1_SA_DQ<7>")
	)
	(segment
		(start 150.855934 -215.672416)
		(end 151.0411 -215.48725)
		(width 0.14478)
		(layer "In13.Cu")
		(net "M_H_CPU1_SA_DQ<7>")
	)
	(segment
		(start 147.837398 -219.096844)
		(end 147.736814 -218.99626)
		(width 0.14478)
		(layer "In13.Cu")
		(net "M_H_CPU1_SA_DQ<7>")
	)
	(segment
		(start 169.7609 -205.410308)
		(end 170.611038 -206.260446)
		(width 0.14478)
		(layer "In13.Cu")
		(net "M_H_CPU1_SA_DQ<7>")
	)
	(segment
		(start 162.071304 -206.260446)
		(end 162.332924 -206.260446)
		(width 0.14478)
		(layer "In13.Cu")
		(net "M_H_CPU1_SA_DQ<7>")
	)
	(segment
		(start 163.173664 -206.260446)
		(end 166.065708 -206.260446)
		(width 0.14478)
		(layer "In13.Cu")
		(net "M_H_CPU1_SA_DQ<7>")
	)
	(segment
		(start 153.295858 -213.843108)
		(end 153.295858 -213.638384)
		(width 0.14478)
		(layer "In13.Cu")
		(net "M_H_CPU1_SA_DQ<7>")
	)
	(segment
		(start 148.227288 -218.706954)
		(end 148.432012 -218.706954)
		(width 0.14478)
		(layer "In13.Cu")
		(net "M_H_CPU1_SA_DQ<7>")
	)
	(segment
		(start 171.546774 -206.260446)
		(end 171.97197 -205.83525)
		(width 0.14478)
		(layer "In13.Cu")
		(net "M_H_CPU1_SA_DQ<7>")
	)
	(segment
		(start 152.025604 -214.70747)
		(end 152.126188 -214.808054)
		(width 0.14478)
		(layer "In13.Cu")
		(net "M_H_CPU1_SA_DQ<7>")
	)
	(segment
		(start 153.195274 -213.5378)
		(end 153.195274 -213.333076)
		(width 0.14478)
		(layer "In13.Cu")
		(net "M_H_CPU1_SA_DQ<7>")
	)
	(segment
		(start 161.520124 -206.576422)
		(end 161.781744 -206.576422)
		(width 0.14478)
		(layer "In13.Cu")
		(net "M_H_CPU1_SA_DQ<7>")
	)
	(segment
		(start 154.16022 -212.36813)
		(end 154.364944 -212.36813)
		(width 0.14478)
		(layer "In13.Cu")
		(net "M_H_CPU1_SA_DQ<7>")
	)
	(segment
		(start 154.754834 -211.97824)
		(end 154.754834 -211.773516)
		(width 0.14478)
		(layer "In13.Cu")
		(net "M_H_CPU1_SA_DQ<7>")
	)
	(segment
		(start 149.686264 -217.04681)
		(end 149.786848 -217.147394)
		(width 0.14478)
		(layer "In13.Cu")
		(net "M_H_CPU1_SA_DQ<7>")
	)
	(segment
		(start 152.516078 -214.622888)
		(end 152.516078 -214.418164)
		(width 0.14478)
		(layer "In13.Cu")
		(net "M_H_CPU1_SA_DQ<7>")
	)
	(segment
		(start 143.077692 -228.771958)
		(end 143.116808 -228.749098)
		(width 0.0889)
		(layer "In13.Cu")
		(net "M_H_CPU1_SA_DQ<7>")
	)
	(segment
		(start 149.296374 -217.4367)
		(end 149.296374 -217.231976)
		(width 0.14478)
		(layer "In13.Cu")
		(net "M_H_CPU1_SA_DQ<7>")
	)
	(segment
		(start 150.176738 -216.757504)
		(end 150.076154 -216.65692)
		(width 0.14478)
		(layer "In13.Cu")
		(net "M_H_CPU1_SA_DQ<7>")
	)
	(segment
		(start 150.566628 -216.367614)
		(end 150.771352 -216.367614)
		(width 0.14478)
		(layer "In13.Cu")
		(net "M_H_CPU1_SA_DQ<7>")
	)
	(segment
		(start 143.811752 -227.91166)
		(end 145.647664 -226.075748)
		(width 0.0889)
		(layer "In13.Cu")
		(net "M_H_CPU1_SA_DQ<7>")
	)
	(segment
		(start 152.415494 -214.31758)
		(end 152.415494 -214.112856)
		(width 0.14478)
		(layer "In13.Cu")
		(net "M_H_CPU1_SA_DQ<7>")
	)
	(segment
		(start 149.786848 -217.147394)
		(end 149.991572 -217.147394)
		(width 0.14478)
		(layer "In13.Cu")
		(net "M_H_CPU1_SA_DQ<7>")
	)
	(segment
		(start 149.211792 -217.927174)
		(end 149.396958 -217.742008)
		(width 0.14478)
		(layer "In13.Cu")
		(net "M_H_CPU1_SA_DQ<7>")
	)
	(segment
		(start 147.736814 -218.99626)
		(end 147.736814 -218.791536)
		(width 0.14478)
		(layer "In13.Cu")
		(net "M_H_CPU1_SA_DQ<7>")
	)
	(segment
		(start 141.093444 -229.577138)
		(end 141.101826 -229.581964)
		(width 0.0889)
		(layer "In13.Cu")
		(net "M_H_CPU1_SA_DQ<7>")
	)
	(segment
		(start 152.126188 -214.808054)
		(end 152.330912 -214.808054)
		(width 0.14478)
		(layer "In13.Cu")
		(net "M_H_CPU1_SA_DQ<7>")
	)
	(segment
		(start 135.453374 -229.577138)
		(end 135.461756 -229.581964)
		(width 0.0889)
		(layer "In13.Cu")
		(net "M_H_CPU1_SA_DQ<7>")
	)
	(segment
		(start 154.075638 -212.858604)
		(end 153.975054 -212.75802)
		(width 0.14478)
		(layer "In13.Cu")
		(net "M_H_CPU1_SA_DQ<7>")
	)
	(segment
		(start 151.736298 -215.197944)
		(end 151.635714 -215.09736)
		(width 0.14478)
		(layer "In13.Cu")
		(net "M_H_CPU1_SA_DQ<7>")
	)
	(segment
		(start 160.87852 -206.260446)
		(end 161.230564 -206.260446)
		(width 0.14478)
		(layer "In13.Cu")
		(net "M_H_CPU1_SA_DQ<7>")
	)
	(segment
		(start 148.432012 -218.706954)
		(end 148.617178 -218.521788)
		(width 0.14478)
		(layer "In13.Cu")
		(net "M_H_CPU1_SA_DQ<7>")
	)
	(segment
		(start 147.736814 -218.791536)
		(end 147.92198 -218.60637)
		(width 0.14478)
		(layer "In13.Cu")
		(net "M_H_CPU1_SA_DQ<7>")
	)
	(segment
		(start 155.450032 -211.688934)
		(end 160.87852 -206.260446)
		(width 0.14478)
		(layer "In13.Cu")
		(net "M_H_CPU1_SA_DQ<7>")
	)
	(segment
		(start 154.754834 -211.773516)
		(end 154.94 -211.58835)
		(width 0.14478)
		(layer "In13.Cu")
		(net "M_H_CPU1_SA_DQ<7>")
	)
	(segment
		(start 155.245308 -211.688934)
		(end 155.450032 -211.688934)
		(width 0.14478)
		(layer "In13.Cu")
		(net "M_H_CPU1_SA_DQ<7>")
	)
	(segment
		(start 150.466044 -216.26703)
		(end 150.566628 -216.367614)
		(width 0.14478)
		(layer "In13.Cu")
		(net "M_H_CPU1_SA_DQ<7>")
	)
	(segment
		(start 147.188174 -222.544894)
		(end 147.188174 -219.950792)
		(width 0.14478)
		(layer "In13.Cu")
		(net "M_H_CPU1_SA_DQ<7>")
	)
	(segment
		(start 147.837398 -219.301568)
		(end 147.837398 -219.096844)
		(width 0.14478)
		(layer "In13.Cu")
		(net "M_H_CPU1_SA_DQ<7>")
	)
	(segment
		(start 148.516594 -218.21648)
		(end 148.516594 -218.011756)
		(width 0.14478)
		(layer "In13.Cu")
		(net "M_H_CPU1_SA_DQ<7>")
	)
	(segment
		(start 166.915846 -205.410308)
		(end 169.7609 -205.410308)
		(width 0.14478)
		(layer "In13.Cu")
		(net "M_H_CPU1_SA_DQ<7>")
	)
	(segment
		(start 147.92198 -218.60637)
		(end 148.126704 -218.60637)
		(width 0.14478)
		(layer "In13.Cu")
		(net "M_H_CPU1_SA_DQ<7>")
	)
	(segment
		(start 148.617178 -218.521788)
		(end 148.617178 -218.317064)
		(width 0.14478)
		(layer "In13.Cu")
		(net "M_H_CPU1_SA_DQ<7>")
	)
	(segment
		(start 151.82088 -214.70747)
		(end 152.025604 -214.70747)
		(width 0.14478)
		(layer "In13.Cu")
		(net "M_H_CPU1_SA_DQ<7>")
	)
	(segment
		(start 162.884104 -206.576422)
		(end 163.028884 -206.431642)
		(width 0.14478)
		(layer "In13.Cu")
		(net "M_H_CPU1_SA_DQ<7>")
	)
	(segment
		(start 143.73479 -227.91166)
		(end 143.811752 -227.91166)
		(width 0.0889)
		(layer "In13.Cu")
		(net "M_H_CPU1_SA_DQ<7>")
	)
	(segment
		(start 153.585164 -213.14791)
		(end 153.685748 -213.248494)
		(width 0.14478)
		(layer "In13.Cu")
		(net "M_H_CPU1_SA_DQ<7>")
	)
	(segment
		(start 154.075638 -213.063328)
		(end 154.075638 -212.858604)
		(width 0.14478)
		(layer "In13.Cu")
		(net "M_H_CPU1_SA_DQ<7>")
	)
	(segment
		(start 152.516078 -214.418164)
		(end 152.415494 -214.31758)
		(width 0.14478)
		(layer "In13.Cu")
		(net "M_H_CPU1_SA_DQ<7>")
	)
	(segment
		(start 149.007068 -217.927174)
		(end 149.211792 -217.927174)
		(width 0.14478)
		(layer "In13.Cu")
		(net "M_H_CPU1_SA_DQ<7>")
	)
	(segment
		(start 153.195274 -213.333076)
		(end 153.38044 -213.14791)
		(width 0.14478)
		(layer "In13.Cu")
		(net "M_H_CPU1_SA_DQ<7>")
	)
	(segment
		(start 154.364944 -212.36813)
		(end 154.465528 -212.468714)
		(width 0.14478)
		(layer "In13.Cu")
		(net "M_H_CPU1_SA_DQ<7>")
	)
	(segment
		(start 149.296374 -217.231976)
		(end 149.48154 -217.04681)
		(width 0.14478)
		(layer "In13.Cu")
		(net "M_H_CPU1_SA_DQ<7>")
	)
	(segment
		(start 161.926524 -206.431642)
		(end 161.926524 -206.405226)
		(width 0.14478)
		(layer "In13.Cu")
		(net "M_H_CPU1_SA_DQ<7>")
	)
	(segment
		(start 153.975054 -212.75802)
		(end 153.975054 -212.553296)
		(width 0.14478)
		(layer "In13.Cu")
		(net "M_H_CPU1_SA_DQ<7>")
	)
	(segment
		(start 161.926524 -206.405226)
		(end 162.071304 -206.260446)
		(width 0.14478)
		(layer "In13.Cu")
		(net "M_H_CPU1_SA_DQ<7>")
	)
	(segment
		(start 150.076154 -216.65692)
		(end 150.076154 -216.452196)
		(width 0.14478)
		(layer "In13.Cu")
		(net "M_H_CPU1_SA_DQ<7>")
	)
	(segment
		(start 163.028884 -206.431642)
		(end 163.028884 -206.405226)
		(width 0.14478)
		(layer "In13.Cu")
		(net "M_H_CPU1_SA_DQ<7>")
	)
	(segment
		(start 148.70176 -217.82659)
		(end 148.906484 -217.82659)
		(width 0.14478)
		(layer "In13.Cu")
		(net "M_H_CPU1_SA_DQ<7>")
	)
	(segment
		(start 150.956518 -215.977724)
		(end 150.855934 -215.87714)
		(width 0.14478)
		(layer "In13.Cu")
		(net "M_H_CPU1_SA_DQ<7>")
	)
	(segment
		(start 161.781744 -206.576422)
		(end 161.926524 -206.431642)
		(width 0.14478)
		(layer "In13.Cu")
		(net "M_H_CPU1_SA_DQ<7>")
	)
	(segment
		(start 152.415494 -214.112856)
		(end 152.60066 -213.92769)
		(width 0.14478)
		(layer "In13.Cu")
		(net "M_H_CPU1_SA_DQ<7>")
	)
	(segment
		(start 149.396958 -217.537284)
		(end 149.296374 -217.4367)
		(width 0.14478)
		(layer "In13.Cu")
		(net "M_H_CPU1_SA_DQ<7>")
	)
	(segment
		(start 150.076154 -216.452196)
		(end 150.26132 -216.26703)
		(width 0.14478)
		(layer "In13.Cu")
		(net "M_H_CPU1_SA_DQ<7>")
	)
	(segment
		(start 134.334758 -229.90429)
		(end 134.488682 -229.63886)
		(width 0.0889)
		(layer "In13.Cu")
		(net "M_H_CPU1_SA_DQ<7>")
	)
	(segment
		(start 161.375344 -206.431642)
		(end 161.520124 -206.576422)
		(width 0.14478)
		(layer "In13.Cu")
		(net "M_H_CPU1_SA_DQ<7>")
	)
	(segment
		(start 152.60066 -213.92769)
		(end 152.805384 -213.92769)
		(width 0.14478)
		(layer "In13.Cu")
		(net "M_H_CPU1_SA_DQ<7>")
	)
	(segment
		(start 153.975054 -212.553296)
		(end 154.16022 -212.36813)
		(width 0.14478)
		(layer "In13.Cu")
		(net "M_H_CPU1_SA_DQ<7>")
	)
	(segment
		(start 143.517112 -227.979732)
		(end 143.547592 -227.961952)
		(width 0.0889)
		(layer "In13.Cu")
		(net "M_H_CPU1_SA_DQ<7>")
	)
	(segment
		(start 155.144724 -211.58835)
		(end 155.245308 -211.688934)
		(width 0.14478)
		(layer "In13.Cu")
		(net "M_H_CPU1_SA_DQ<7>")
	)
	(segment
		(start 162.477704 -206.431642)
		(end 162.622484 -206.576422)
		(width 0.14478)
		(layer "In13.Cu")
		(net "M_H_CPU1_SA_DQ<7>")
	)
	(segment
		(start 153.295858 -213.638384)
		(end 153.195274 -213.5378)
		(width 0.14478)
		(layer "In13.Cu")
		(net "M_H_CPU1_SA_DQ<7>")
	)
	(arc
		(start 142.889986 -229.094538)
		(mid 142.931241 -228.923567)
		(end 143.045942 -228.790246)
		(width 0.0889)
		(layer "In13.Cu")
		(net "M_H_CPU1_SA_DQ<7>")
	)
	(arc
		(start 137.916158 -229.577138)
		(mid 138.099666 -229.531613)
		(end 138.281918 -229.581964)
		(width 0.0889)
		(layer "In13.Cu")
		(net "M_H_CPU1_SA_DQ<7>")
	)
	(arc
		(start 142.04188 -229.581964)
		(mid 142.324836 -229.658141)
		(end 142.607792 -229.581964)
		(width 0.0889)
		(layer "In13.Cu")
		(net "M_H_CPU1_SA_DQ<7>")
	)
	(arc
		(start 135.087614 -229.581964)
		(mid 135.269865 -229.53158)
		(end 135.453374 -229.577138)
		(width 0.0889)
		(layer "In13.Cu")
		(net "M_H_CPU1_SA_DQ<7>")
	)
	(arc
		(start 134.58444 -229.61346)
		(mid 134.839762 -229.65716)
		(end 135.087614 -229.581964)
		(width 0.0889)
		(layer "In13.Cu")
		(net "M_H_CPU1_SA_DQ<7>")
	)
	(arc
		(start 143.36014 -228.284532)
		(mid 143.401689 -228.11311)
		(end 143.517112 -227.979732)
		(width 0.0889)
		(layer "In13.Cu")
		(net "M_H_CPU1_SA_DQ<7>")
	)
	(arc
		(start 139.78763 -229.581964)
		(mid 139.969881 -229.53158)
		(end 140.15339 -229.577138)
		(width 0.0889)
		(layer "In13.Cu")
		(net "M_H_CPU1_SA_DQ<7>")
	)
	(arc
		(start 143.116808 -228.749098)
		(mid 143.295621 -228.546748)
		(end 143.36014 -228.284532)
		(width 0.0889)
		(layer "In13.Cu")
		(net "M_H_CPU1_SA_DQ<7>")
	)
	(arc
		(start 141.101826 -229.581964)
		(mid 141.384782 -229.658141)
		(end 141.667738 -229.581964)
		(width 0.0889)
		(layer "In13.Cu")
		(net "M_H_CPU1_SA_DQ<7>")
	)
	(arc
		(start 138.281918 -229.581964)
		(mid 138.564874 -229.658141)
		(end 138.84783 -229.581964)
		(width 0.0889)
		(layer "In13.Cu")
		(net "M_H_CPU1_SA_DQ<7>")
	)
	(arc
		(start 142.644114 -229.560882)
		(mid 142.824766 -229.358137)
		(end 142.889986 -229.094538)
		(width 0.0889)
		(layer "In13.Cu")
		(net "M_H_CPU1_SA_DQ<7>")
	)
	(arc
		(start 136.027668 -229.581964)
		(mid 136.209919 -229.53158)
		(end 136.393428 -229.577138)
		(width 0.0889)
		(layer "In13.Cu")
		(net "M_H_CPU1_SA_DQ<7>")
	)
	(arc
		(start 141.67612 -229.577138)
		(mid 141.859628 -229.531613)
		(end 142.04188 -229.581964)
		(width 0.0889)
		(layer "In13.Cu")
		(net "M_H_CPU1_SA_DQ<7>")
	)
	(arc
		(start 143.547592 -227.961952)
		(mid 143.637868 -227.924447)
		(end 143.73479 -227.91166)
		(width 0.0889)
		(layer "In13.Cu")
		(net "M_H_CPU1_SA_DQ<7>")
	)
	(arc
		(start 140.727684 -229.581964)
		(mid 140.909935 -229.53158)
		(end 141.093444 -229.577138)
		(width 0.0889)
		(layer "In13.Cu")
		(net "M_H_CPU1_SA_DQ<7>")
	)
	(arc
		(start 137.341864 -229.581964)
		(mid 137.62482 -229.658141)
		(end 137.907776 -229.581964)
		(width 0.0889)
		(layer "In13.Cu")
		(net "M_H_CPU1_SA_DQ<7>")
	)
	(arc
		(start 139.221718 -229.581964)
		(mid 139.504674 -229.658141)
		(end 139.78763 -229.581964)
		(width 0.0889)
		(layer "In13.Cu")
		(net "M_H_CPU1_SA_DQ<7>")
	)
	(arc
		(start 138.84783 -229.581964)
		(mid 139.034774 -229.531675)
		(end 139.221718 -229.581964)
		(width 0.0889)
		(layer "In13.Cu")
		(net "M_H_CPU1_SA_DQ<7>")
	)
	(arc
		(start 135.461756 -229.581964)
		(mid 135.744712 -229.658141)
		(end 136.027668 -229.581964)
		(width 0.0889)
		(layer "In13.Cu")
		(net "M_H_CPU1_SA_DQ<7>")
	)
	(arc
		(start 136.976104 -229.577138)
		(mid 137.159612 -229.531613)
		(end 137.341864 -229.581964)
		(width 0.0889)
		(layer "In13.Cu")
		(net "M_H_CPU1_SA_DQ<7>")
	)
	(arc
		(start 136.40181 -229.581964)
		(mid 136.684766 -229.658141)
		(end 136.967722 -229.581964)
		(width 0.0889)
		(layer "In13.Cu")
		(net "M_H_CPU1_SA_DQ<7>")
	)
	(arc
		(start 140.161772 -229.581964)
		(mid 140.444728 -229.658141)
		(end 140.727684 -229.581964)
		(width 0.0889)
		(layer "In13.Cu")
		(net "M_H_CPU1_SA_DQ<7>")
	)
	(segment
		(start 135.27786 -229.360476)
		(end 135.744712 -229.094538)
		(width 0.10668)
		(layer "F.Cu")
		(net "M_H_CPU1_SA_DQ<6>")
	)
	(segment
		(start 161.342832 -205.316582)
		(end 161.604452 -205.316582)
		(width 0.14478)
		(layer "In13.Cu")
		(net "M_H_CPU1_SA_DQ<6>")
	)
	(segment
		(start 155.485084 -210.166712)
		(end 155.38958 -210.071208)
		(width 0.14478)
		(layer "In13.Cu")
		(net "M_H_CPU1_SA_DQ<6>")
	)
	(segment
		(start 135.89889 -228.829108)
		(end 135.995156 -228.803708)
		(width 0.0889)
		(layer "In13.Cu")
		(net "M_H_CPU1_SA_DQ<6>")
	)
	(segment
		(start 155.574746 -209.681318)
		(end 155.77947 -209.681318)
		(width 0.14478)
		(layer "In13.Cu")
		(net "M_H_CPU1_SA_DQ<6>")
	)
	(segment
		(start 159.773874 -205.877922)
		(end 159.978598 -205.877922)
		(width 0.14478)
		(layer "In13.Cu")
		(net "M_H_CPU1_SA_DQ<6>")
	)
	(segment
		(start 144.017746 -225.531934)
		(end 144.056862 -225.509074)
		(width 0.0889)
		(layer "In13.Cu")
		(net "M_H_CPU1_SA_DQ<6>")
	)
	(segment
		(start 170.43908 -204.560424)
		(end 171.546774 -204.560424)
		(width 0.14478)
		(layer "In13.Cu")
		(net "M_H_CPU1_SA_DQ<6>")
	)
	(segment
		(start 162.851592 -205.171802)
		(end 162.851592 -204.705204)
		(width 0.14478)
		(layer "In13.Cu")
		(net "M_H_CPU1_SA_DQ<6>")
	)
	(segment
		(start 156.264864 -209.386932)
		(end 156.16936 -209.291428)
		(width 0.14478)
		(layer "In13.Cu")
		(net "M_H_CPU1_SA_DQ<6>")
	)
	(segment
		(start 157.914086 -207.341978)
		(end 158.11881 -207.341978)
		(width 0.14478)
		(layer "In13.Cu")
		(net "M_H_CPU1_SA_DQ<6>")
	)
	(segment
		(start 142.137638 -228.771958)
		(end 142.176754 -228.749098)
		(width 0.0889)
		(layer "In13.Cu")
		(net "M_H_CPU1_SA_DQ<6>")
	)
	(segment
		(start 158.5087 -206.747364)
		(end 158.693866 -206.562198)
		(width 0.14478)
		(layer "In13.Cu")
		(net "M_H_CPU1_SA_DQ<6>")
	)
	(segment
		(start 154.794966 -210.461098)
		(end 154.99969 -210.461098)
		(width 0.14478)
		(layer "In13.Cu")
		(net "M_H_CPU1_SA_DQ<6>")
	)
	(segment
		(start 160.69564 -204.560424)
		(end 161.053272 -204.560424)
		(width 0.14478)
		(layer "In13.Cu")
		(net "M_H_CPU1_SA_DQ<6>")
	)
	(segment
		(start 158.214314 -207.437482)
		(end 158.419038 -207.437482)
		(width 0.14478)
		(layer "In13.Cu")
		(net "M_H_CPU1_SA_DQ<6>")
	)
	(segment
		(start 157.33903 -208.121758)
		(end 157.434534 -208.217262)
		(width 0.14478)
		(layer "In13.Cu")
		(net "M_H_CPU1_SA_DQ<6>")
	)
	(segment
		(start 158.604204 -207.047592)
		(end 158.5087 -206.952088)
		(width 0.14478)
		(layer "In13.Cu")
		(net "M_H_CPU1_SA_DQ<6>")
	)
	(segment
		(start 156.16936 -209.291428)
		(end 156.16936 -209.086704)
		(width 0.14478)
		(layer "In13.Cu")
		(net "M_H_CPU1_SA_DQ<6>")
	)
	(segment
		(start 157.824424 -207.827372)
		(end 157.72892 -207.731868)
		(width 0.14478)
		(layer "In13.Cu")
		(net "M_H_CPU1_SA_DQ<6>")
	)
	(segment
		(start 161.198052 -205.171802)
		(end 161.342832 -205.316582)
		(width 0.14478)
		(layer "In13.Cu")
		(net "M_H_CPU1_SA_DQ<6>")
	)
	(segment
		(start 157.639258 -208.217262)
		(end 157.824424 -208.032096)
		(width 0.14478)
		(layer "In13.Cu")
		(net "M_H_CPU1_SA_DQ<6>")
	)
	(segment
		(start 158.604204 -207.252316)
		(end 158.604204 -207.047592)
		(width 0.14478)
		(layer "In13.Cu")
		(net "M_H_CPU1_SA_DQ<6>")
	)
	(segment
		(start 156.354526 -208.901538)
		(end 156.55925 -208.901538)
		(width 0.14478)
		(layer "In13.Cu")
		(net "M_H_CPU1_SA_DQ<6>")
	)
	(segment
		(start 156.264864 -209.591656)
		(end 156.264864 -209.386932)
		(width 0.14478)
		(layer "In13.Cu")
		(net "M_H_CPU1_SA_DQ<6>")
	)
	(segment
		(start 154.99969 -210.461098)
		(end 155.095194 -210.556602)
		(width 0.14478)
		(layer "In13.Cu")
		(net "M_H_CPU1_SA_DQ<6>")
	)
	(segment
		(start 157.044644 -208.811876)
		(end 157.044644 -208.607152)
		(width 0.14478)
		(layer "In13.Cu")
		(net "M_H_CPU1_SA_DQ<6>")
	)
	(segment
		(start 146.289014 -222.085408)
		(end 146.289014 -218.96705)
		(width 0.14478)
		(layer "In13.Cu")
		(net "M_H_CPU1_SA_DQ<6>")
	)
	(segment
		(start 162.155632 -204.560424)
		(end 162.300412 -204.705204)
		(width 0.14478)
		(layer "In13.Cu")
		(net "M_H_CPU1_SA_DQ<6>")
	)
	(segment
		(start 155.095194 -210.556602)
		(end 155.299918 -210.556602)
		(width 0.14478)
		(layer "In13.Cu")
		(net "M_H_CPU1_SA_DQ<6>")
	)
	(segment
		(start 158.89859 -206.562198)
		(end 158.994094 -206.657702)
		(width 0.14478)
		(layer "In13.Cu")
		(net "M_H_CPU1_SA_DQ<6>")
	)
	(segment
		(start 160.163764 -205.488032)
		(end 160.06826 -205.392528)
		(width 0.14478)
		(layer "In13.Cu")
		(net "M_H_CPU1_SA_DQ<6>")
	)
	(segment
		(start 160.163764 -205.692756)
		(end 160.163764 -205.488032)
		(width 0.14478)
		(layer "In13.Cu")
		(net "M_H_CPU1_SA_DQ<6>")
	)
	(segment
		(start 160.06826 -205.187804)
		(end 160.69564 -204.560424)
		(width 0.14478)
		(layer "In13.Cu")
		(net "M_H_CPU1_SA_DQ<6>")
	)
	(segment
		(start 157.72892 -207.527144)
		(end 157.914086 -207.341978)
		(width 0.14478)
		(layer "In13.Cu")
		(net "M_H_CPU1_SA_DQ<6>")
	)
	(segment
		(start 162.706812 -205.316582)
		(end 162.851592 -205.171802)
		(width 0.14478)
		(layer "In13.Cu")
		(net "M_H_CPU1_SA_DQ<6>")
	)
	(segment
		(start 159.28848 -205.967584)
		(end 159.473646 -205.782418)
		(width 0.14478)
		(layer "In13.Cu")
		(net "M_H_CPU1_SA_DQ<6>")
	)
	(segment
		(start 166.228014 -204.560424)
		(end 167.078152 -203.710286)
		(width 0.14478)
		(layer "In13.Cu")
		(net "M_H_CPU1_SA_DQ<6>")
	)
	(segment
		(start 158.693866 -206.562198)
		(end 158.89859 -206.562198)
		(width 0.14478)
		(layer "In13.Cu")
		(net "M_H_CPU1_SA_DQ<6>")
	)
	(segment
		(start 159.473646 -205.782418)
		(end 159.67837 -205.782418)
		(width 0.14478)
		(layer "In13.Cu")
		(net "M_H_CPU1_SA_DQ<6>")
	)
	(segment
		(start 145.684494 -222.960184)
		(end 146.289014 -222.355664)
		(width 0.0889)
		(layer "In13.Cu")
		(net "M_H_CPU1_SA_DQ<6>")
	)
	(segment
		(start 144.9578 -223.911922)
		(end 144.994122 -223.89084)
		(width 0.0889)
		(layer "In13.Cu")
		(net "M_H_CPU1_SA_DQ<6>")
	)
	(segment
		(start 155.38958 -210.071208)
		(end 155.38958 -209.866484)
		(width 0.14478)
		(layer "In13.Cu")
		(net "M_H_CPU1_SA_DQ<6>")
	)
	(segment
		(start 156.079698 -209.776822)
		(end 156.264864 -209.591656)
		(width 0.14478)
		(layer "In13.Cu")
		(net "M_H_CPU1_SA_DQ<6>")
	)
	(segment
		(start 145.392648 -223.122744)
		(end 145.428208 -223.10217)
		(width 0.0889)
		(layer "In13.Cu")
		(net "M_H_CPU1_SA_DQ<6>")
	)
	(segment
		(start 157.044644 -208.607152)
		(end 156.94914 -208.511648)
		(width 0.14478)
		(layer "In13.Cu")
		(net "M_H_CPU1_SA_DQ<6>")
	)
	(segment
		(start 161.604452 -205.316582)
		(end 161.749232 -205.171802)
		(width 0.14478)
		(layer "In13.Cu")
		(net "M_H_CPU1_SA_DQ<6>")
	)
	(segment
		(start 155.874974 -209.776822)
		(end 156.079698 -209.776822)
		(width 0.14478)
		(layer "In13.Cu")
		(net "M_H_CPU1_SA_DQ<6>")
	)
	(segment
		(start 142.607792 -227.961952)
		(end 142.644114 -227.94087)
		(width 0.0889)
		(layer "In13.Cu")
		(net "M_H_CPU1_SA_DQ<6>")
	)
	(segment
		(start 159.67837 -205.782418)
		(end 159.773874 -205.877922)
		(width 0.14478)
		(layer "In13.Cu")
		(net "M_H_CPU1_SA_DQ<6>")
	)
	(segment
		(start 155.299918 -210.556602)
		(end 155.485084 -210.371436)
		(width 0.14478)
		(layer "In13.Cu")
		(net "M_H_CPU1_SA_DQ<6>")
	)
	(segment
		(start 146.289014 -222.355664)
		(end 146.289014 -222.085408)
		(width 0.0889)
		(layer "In13.Cu")
		(net "M_H_CPU1_SA_DQ<6>")
	)
	(segment
		(start 157.824424 -208.032096)
		(end 157.824424 -207.827372)
		(width 0.14478)
		(layer "In13.Cu")
		(net "M_H_CPU1_SA_DQ<6>")
	)
	(segment
		(start 156.94914 -208.306924)
		(end 157.134306 -208.121758)
		(width 0.14478)
		(layer "In13.Cu")
		(net "M_H_CPU1_SA_DQ<6>")
	)
	(segment
		(start 155.38958 -209.866484)
		(end 155.574746 -209.681318)
		(width 0.14478)
		(layer "In13.Cu")
		(net "M_H_CPU1_SA_DQ<6>")
	)
	(segment
		(start 156.16936 -209.086704)
		(end 156.354526 -208.901538)
		(width 0.14478)
		(layer "In13.Cu")
		(net "M_H_CPU1_SA_DQ<6>")
	)
	(segment
		(start 159.383984 -206.472536)
		(end 159.383984 -206.267812)
		(width 0.14478)
		(layer "In13.Cu")
		(net "M_H_CPU1_SA_DQ<6>")
	)
	(segment
		(start 159.198818 -206.657702)
		(end 159.383984 -206.472536)
		(width 0.14478)
		(layer "In13.Cu")
		(net "M_H_CPU1_SA_DQ<6>")
	)
	(segment
		(start 139.31773 -228.771958)
		(end 139.326112 -228.767132)
		(width 0.0889)
		(layer "In13.Cu")
		(net "M_H_CPU1_SA_DQ<6>")
	)
	(segment
		(start 162.851592 -204.705204)
		(end 162.996372 -204.560424)
		(width 0.14478)
		(layer "In13.Cu")
		(net "M_H_CPU1_SA_DQ<6>")
	)
	(segment
		(start 146.289014 -218.96705)
		(end 154.794966 -210.461098)
		(width 0.14478)
		(layer "In13.Cu")
		(net "M_H_CPU1_SA_DQ<6>")
	)
	(segment
		(start 135.744712 -229.094538)
		(end 135.89889 -228.829108)
		(width 0.0889)
		(layer "In13.Cu")
		(net "M_H_CPU1_SA_DQ<6>")
	)
	(segment
		(start 171.546774 -204.560424)
		(end 171.97197 -204.135228)
		(width 0.14478)
		(layer "In13.Cu")
		(net "M_H_CPU1_SA_DQ<6>")
	)
	(segment
		(start 157.134306 -208.121758)
		(end 157.33903 -208.121758)
		(width 0.14478)
		(layer "In13.Cu")
		(net "M_H_CPU1_SA_DQ<6>")
	)
	(segment
		(start 142.576042 -227.98024)
		(end 142.607792 -227.961952)
		(width 0.0889)
		(layer "In13.Cu")
		(net "M_H_CPU1_SA_DQ<6>")
	)
	(segment
		(start 161.749232 -205.171802)
		(end 161.749232 -204.705204)
		(width 0.14478)
		(layer "In13.Cu")
		(net "M_H_CPU1_SA_DQ<6>")
	)
	(segment
		(start 160.06826 -205.392528)
		(end 160.06826 -205.187804)
		(width 0.14478)
		(layer "In13.Cu")
		(net "M_H_CPU1_SA_DQ<6>")
	)
	(segment
		(start 162.996372 -204.560424)
		(end 166.228014 -204.560424)
		(width 0.14478)
		(layer "In13.Cu")
		(net "M_H_CPU1_SA_DQ<6>")
	)
	(segment
		(start 158.5087 -206.952088)
		(end 158.5087 -206.747364)
		(width 0.14478)
		(layer "In13.Cu")
		(net "M_H_CPU1_SA_DQ<6>")
	)
	(segment
		(start 143.045942 -227.170234)
		(end 143.077692 -227.151946)
		(width 0.0889)
		(layer "In13.Cu")
		(net "M_H_CPU1_SA_DQ<6>")
	)
	(segment
		(start 145.428208 -223.10217)
		(end 145.684494 -222.960184)
		(width 0.0889)
		(layer "In13.Cu")
		(net "M_H_CPU1_SA_DQ<6>")
	)
	(segment
		(start 159.978598 -205.877922)
		(end 160.163764 -205.692756)
		(width 0.14478)
		(layer "In13.Cu")
		(net "M_H_CPU1_SA_DQ<6>")
	)
	(segment
		(start 144.457166 -224.739708)
		(end 144.487646 -224.721928)
		(width 0.0889)
		(layer "In13.Cu")
		(net "M_H_CPU1_SA_DQ<6>")
	)
	(segment
		(start 156.55925 -208.901538)
		(end 156.654754 -208.997042)
		(width 0.14478)
		(layer "In13.Cu")
		(net "M_H_CPU1_SA_DQ<6>")
	)
	(segment
		(start 140.257784 -228.771958)
		(end 140.266166 -228.767132)
		(width 0.0889)
		(layer "In13.Cu")
		(net "M_H_CPU1_SA_DQ<6>")
	)
	(segment
		(start 157.72892 -207.731868)
		(end 157.72892 -207.527144)
		(width 0.14478)
		(layer "In13.Cu")
		(net "M_H_CPU1_SA_DQ<6>")
	)
	(segment
		(start 161.053272 -204.560424)
		(end 161.198052 -204.705204)
		(width 0.14478)
		(layer "In13.Cu")
		(net "M_H_CPU1_SA_DQ<6>")
	)
	(segment
		(start 156.94914 -208.511648)
		(end 156.94914 -208.306924)
		(width 0.14478)
		(layer "In13.Cu")
		(net "M_H_CPU1_SA_DQ<6>")
	)
	(segment
		(start 161.894012 -204.560424)
		(end 162.155632 -204.560424)
		(width 0.14478)
		(layer "In13.Cu")
		(net "M_H_CPU1_SA_DQ<6>")
	)
	(segment
		(start 162.300412 -204.705204)
		(end 162.300412 -205.171802)
		(width 0.14478)
		(layer "In13.Cu")
		(net "M_H_CPU1_SA_DQ<6>")
	)
	(segment
		(start 156.654754 -208.997042)
		(end 156.859478 -208.997042)
		(width 0.14478)
		(layer "In13.Cu")
		(net "M_H_CPU1_SA_DQ<6>")
	)
	(segment
		(start 155.485084 -210.371436)
		(end 155.485084 -210.166712)
		(width 0.14478)
		(layer "In13.Cu")
		(net "M_H_CPU1_SA_DQ<6>")
	)
	(segment
		(start 157.434534 -208.217262)
		(end 157.639258 -208.217262)
		(width 0.14478)
		(layer "In13.Cu")
		(net "M_H_CPU1_SA_DQ<6>")
	)
	(segment
		(start 162.445192 -205.316582)
		(end 162.706812 -205.316582)
		(width 0.14478)
		(layer "In13.Cu")
		(net "M_H_CPU1_SA_DQ<6>")
	)
	(segment
		(start 143.517112 -226.35972)
		(end 143.547592 -226.34194)
		(width 0.0889)
		(layer "In13.Cu")
		(net "M_H_CPU1_SA_DQ<6>")
	)
	(segment
		(start 162.300412 -205.171802)
		(end 162.445192 -205.316582)
		(width 0.14478)
		(layer "In13.Cu")
		(net "M_H_CPU1_SA_DQ<6>")
	)
	(segment
		(start 143.547592 -226.34194)
		(end 143.586708 -226.31908)
		(width 0.0889)
		(layer "In13.Cu")
		(net "M_H_CPU1_SA_DQ<6>")
	)
	(segment
		(start 158.419038 -207.437482)
		(end 158.604204 -207.252316)
		(width 0.14478)
		(layer "In13.Cu")
		(net "M_H_CPU1_SA_DQ<6>")
	)
	(segment
		(start 167.078152 -203.710286)
		(end 169.588942 -203.710286)
		(width 0.14478)
		(layer "In13.Cu")
		(net "M_H_CPU1_SA_DQ<6>")
	)
	(segment
		(start 144.92605 -223.93021)
		(end 144.9578 -223.911922)
		(width 0.0889)
		(layer "In13.Cu")
		(net "M_H_CPU1_SA_DQ<6>")
	)
	(segment
		(start 156.859478 -208.997042)
		(end 157.044644 -208.811876)
		(width 0.14478)
		(layer "In13.Cu")
		(net "M_H_CPU1_SA_DQ<6>")
	)
	(segment
		(start 155.77947 -209.681318)
		(end 155.874974 -209.776822)
		(width 0.14478)
		(layer "In13.Cu")
		(net "M_H_CPU1_SA_DQ<6>")
	)
	(segment
		(start 144.487646 -224.721928)
		(end 144.526762 -224.699068)
		(width 0.0889)
		(layer "In13.Cu")
		(net "M_H_CPU1_SA_DQ<6>")
	)
	(segment
		(start 169.588942 -203.710286)
		(end 170.43908 -204.560424)
		(width 0.14478)
		(layer "In13.Cu")
		(net "M_H_CPU1_SA_DQ<6>")
	)
	(segment
		(start 137.803382 -228.767132)
		(end 137.811764 -228.771958)
		(width 0.0889)
		(layer "In13.Cu")
		(net "M_H_CPU1_SA_DQ<6>")
	)
	(segment
		(start 161.198052 -204.705204)
		(end 161.198052 -205.171802)
		(width 0.14478)
		(layer "In13.Cu")
		(net "M_H_CPU1_SA_DQ<6>")
	)
	(segment
		(start 143.985996 -225.550222)
		(end 144.017746 -225.531934)
		(width 0.0889)
		(layer "In13.Cu")
		(net "M_H_CPU1_SA_DQ<6>")
	)
	(segment
		(start 138.743436 -228.767132)
		(end 138.751818 -228.771958)
		(width 0.0889)
		(layer "In13.Cu")
		(net "M_H_CPU1_SA_DQ<6>")
	)
	(segment
		(start 161.749232 -204.705204)
		(end 161.894012 -204.560424)
		(width 0.14478)
		(layer "In13.Cu")
		(net "M_H_CPU1_SA_DQ<6>")
	)
	(segment
		(start 158.994094 -206.657702)
		(end 159.198818 -206.657702)
		(width 0.14478)
		(layer "In13.Cu")
		(net "M_H_CPU1_SA_DQ<6>")
	)
	(segment
		(start 158.11881 -207.341978)
		(end 158.214314 -207.437482)
		(width 0.14478)
		(layer "In13.Cu")
		(net "M_H_CPU1_SA_DQ<6>")
	)
	(segment
		(start 159.28848 -206.172308)
		(end 159.28848 -205.967584)
		(width 0.14478)
		(layer "In13.Cu")
		(net "M_H_CPU1_SA_DQ<6>")
	)
	(segment
		(start 143.077692 -227.151946)
		(end 143.116808 -227.129086)
		(width 0.0889)
		(layer "In13.Cu")
		(net "M_H_CPU1_SA_DQ<6>")
	)
	(segment
		(start 159.383984 -206.267812)
		(end 159.28848 -206.172308)
		(width 0.14478)
		(layer "In13.Cu")
		(net "M_H_CPU1_SA_DQ<6>")
	)
	(arc
		(start 140.266166 -228.767132)
		(mid 140.449674 -228.721638)
		(end 140.631926 -228.771958)
		(width 0.0889)
		(layer "In13.Cu")
		(net "M_H_CPU1_SA_DQ<6>")
	)
	(arc
		(start 139.691872 -228.771958)
		(mid 139.974828 -228.848135)
		(end 140.257784 -228.771958)
		(width 0.0889)
		(layer "In13.Cu")
		(net "M_H_CPU1_SA_DQ<6>")
	)
	(arc
		(start 141.571726 -228.771958)
		(mid 141.854682 -228.848135)
		(end 142.137638 -228.771958)
		(width 0.0889)
		(layer "In13.Cu")
		(net "M_H_CPU1_SA_DQ<6>")
	)
	(arc
		(start 143.36014 -226.66452)
		(mid 143.401689 -226.493098)
		(end 143.517112 -226.35972)
		(width 0.0889)
		(layer "In13.Cu")
		(net "M_H_CPU1_SA_DQ<6>")
	)
	(arc
		(start 142.889986 -227.474526)
		(mid 142.931241 -227.303555)
		(end 143.045942 -227.170234)
		(width 0.0889)
		(layer "In13.Cu")
		(net "M_H_CPU1_SA_DQ<6>")
	)
	(arc
		(start 136.87171 -228.771958)
		(mid 137.154666 -228.848135)
		(end 137.437622 -228.771958)
		(width 0.0889)
		(layer "In13.Cu")
		(net "M_H_CPU1_SA_DQ<6>")
	)
	(arc
		(start 144.526762 -224.699068)
		(mid 144.705575 -224.496718)
		(end 144.770094 -224.234502)
		(width 0.0889)
		(layer "In13.Cu")
		(net "M_H_CPU1_SA_DQ<6>")
	)
	(arc
		(start 142.420086 -228.284532)
		(mid 142.461341 -228.113561)
		(end 142.576042 -227.98024)
		(width 0.0889)
		(layer "In13.Cu")
		(net "M_H_CPU1_SA_DQ<6>")
	)
	(arc
		(start 143.586708 -226.31908)
		(mid 143.765521 -226.11673)
		(end 143.83004 -225.854514)
		(width 0.0889)
		(layer "In13.Cu")
		(net "M_H_CPU1_SA_DQ<6>")
	)
	(arc
		(start 136.497822 -228.771958)
		(mid 136.684766 -228.721703)
		(end 136.87171 -228.771958)
		(width 0.0889)
		(layer "In13.Cu")
		(net "M_H_CPU1_SA_DQ<6>")
	)
	(arc
		(start 143.116808 -227.129086)
		(mid 143.295621 -226.926736)
		(end 143.36014 -226.66452)
		(width 0.0889)
		(layer "In13.Cu")
		(net "M_H_CPU1_SA_DQ<6>")
	)
	(arc
		(start 145.239994 -223.424496)
		(mid 145.280323 -223.255404)
		(end 145.392648 -223.122744)
		(width 0.0889)
		(layer "In13.Cu")
		(net "M_H_CPU1_SA_DQ<6>")
	)
	(arc
		(start 144.300194 -225.044508)
		(mid 144.341743 -224.873086)
		(end 144.457166 -224.739708)
		(width 0.0889)
		(layer "In13.Cu")
		(net "M_H_CPU1_SA_DQ<6>")
	)
	(arc
		(start 144.994122 -223.89084)
		(mid 145.174774 -223.688095)
		(end 145.239994 -223.424496)
		(width 0.0889)
		(layer "In13.Cu")
		(net "M_H_CPU1_SA_DQ<6>")
	)
	(arc
		(start 138.751818 -228.771958)
		(mid 139.034774 -228.848135)
		(end 139.31773 -228.771958)
		(width 0.0889)
		(layer "In13.Cu")
		(net "M_H_CPU1_SA_DQ<6>")
	)
	(arc
		(start 142.176754 -228.749098)
		(mid 142.355567 -228.546748)
		(end 142.420086 -228.284532)
		(width 0.0889)
		(layer "In13.Cu")
		(net "M_H_CPU1_SA_DQ<6>")
	)
	(arc
		(start 137.437622 -228.771958)
		(mid 137.619873 -228.721608)
		(end 137.803382 -228.767132)
		(width 0.0889)
		(layer "In13.Cu")
		(net "M_H_CPU1_SA_DQ<6>")
	)
	(arc
		(start 142.644114 -227.94087)
		(mid 142.824766 -227.738125)
		(end 142.889986 -227.474526)
		(width 0.0889)
		(layer "In13.Cu")
		(net "M_H_CPU1_SA_DQ<6>")
	)
	(arc
		(start 144.770094 -224.234502)
		(mid 144.811349 -224.063531)
		(end 144.92605 -223.93021)
		(width 0.0889)
		(layer "In13.Cu")
		(net "M_H_CPU1_SA_DQ<6>")
	)
	(arc
		(start 140.631926 -228.771958)
		(mid 140.914882 -228.848135)
		(end 141.197838 -228.771958)
		(width 0.0889)
		(layer "In13.Cu")
		(net "M_H_CPU1_SA_DQ<6>")
	)
	(arc
		(start 141.197838 -228.771958)
		(mid 141.384782 -228.721703)
		(end 141.571726 -228.771958)
		(width 0.0889)
		(layer "In13.Cu")
		(net "M_H_CPU1_SA_DQ<6>")
	)
	(arc
		(start 143.83004 -225.854514)
		(mid 143.871295 -225.683543)
		(end 143.985996 -225.550222)
		(width 0.0889)
		(layer "In13.Cu")
		(net "M_H_CPU1_SA_DQ<6>")
	)
	(arc
		(start 135.995156 -228.803708)
		(mid 136.250221 -228.847059)
		(end 136.497822 -228.771958)
		(width 0.0889)
		(layer "In13.Cu")
		(net "M_H_CPU1_SA_DQ<6>")
	)
	(arc
		(start 138.377676 -228.771958)
		(mid 138.559927 -228.721608)
		(end 138.743436 -228.767132)
		(width 0.0889)
		(layer "In13.Cu")
		(net "M_H_CPU1_SA_DQ<6>")
	)
	(arc
		(start 137.811764 -228.771958)
		(mid 138.09472 -228.848135)
		(end 138.377676 -228.771958)
		(width 0.0889)
		(layer "In13.Cu")
		(net "M_H_CPU1_SA_DQ<6>")
	)
	(arc
		(start 139.326112 -228.767132)
		(mid 139.50962 -228.721638)
		(end 139.691872 -228.771958)
		(width 0.0889)
		(layer "In13.Cu")
		(net "M_H_CPU1_SA_DQ<6>")
	)
	(arc
		(start 144.056862 -225.509074)
		(mid 144.235675 -225.306724)
		(end 144.300194 -225.044508)
		(width 0.0889)
		(layer "In13.Cu")
		(net "M_H_CPU1_SA_DQ<6>")
	)
	(segment
		(start 134.337806 -229.360476)
		(end 134.804658 -229.094538)
		(width 0.10668)
		(layer "F.Cu")
		(net "M_H_CPU1_SA_DQ<5>")
	)
	(segment
		(start 139.326112 -229.42169)
		(end 139.31773 -229.416864)
		(width 0.0889)
		(layer "In13.Cu")
		(net "M_H_CPU1_SA_DQ<5>")
	)
	(segment
		(start 172.474382 -205.410308)
		(end 170.529504 -205.410308)
		(width 0.14478)
		(layer "In13.Cu")
		(net "M_H_CPU1_SA_DQ<5>")
	)
	(segment
		(start 160.69183 -205.810866)
		(end 155.363926 -211.13877)
		(width 0.14478)
		(layer "In13.Cu")
		(net "M_H_CPU1_SA_DQ<5>")
	)
	(segment
		(start 143.01343 -228.588824)
		(end 142.98168 -228.607112)
		(width 0.0889)
		(layer "In13.Cu")
		(net "M_H_CPU1_SA_DQ<5>")
	)
	(segment
		(start 175.139096 -205.260448)
		(end 174.862998 -205.260448)
		(width 0.14478)
		(layer "In13.Cu")
		(net "M_H_CPU1_SA_DQ<5>")
	)
	(segment
		(start 143.523716 -227.733606)
		(end 143.451834 -227.797106)
		(width 0.0889)
		(layer "In13.Cu")
		(net "M_H_CPU1_SA_DQ<5>")
	)
	(segment
		(start 170.529504 -205.410308)
		(end 169.67962 -204.560424)
		(width 0.14478)
		(layer "In13.Cu")
		(net "M_H_CPU1_SA_DQ<5>")
	)
	(segment
		(start 142.51178 -229.416864)
		(end 142.503398 -229.42169)
		(width 0.0889)
		(layer "In13.Cu")
		(net "M_H_CPU1_SA_DQ<5>")
	)
	(segment
		(start 140.266166 -229.42169)
		(end 140.257784 -229.416864)
		(width 0.0889)
		(layer "In13.Cu")
		(net "M_H_CPU1_SA_DQ<5>")
	)
	(segment
		(start 174.862998 -205.260448)
		(end 174.587916 -204.985366)
		(width 0.14478)
		(layer "In13.Cu")
		(net "M_H_CPU1_SA_DQ<5>")
	)
	(segment
		(start 154.75331 -211.13877)
		(end 146.738594 -219.153486)
		(width 0.14478)
		(layer "In13.Cu")
		(net "M_H_CPU1_SA_DQ<5>")
	)
	(segment
		(start 176.072038 -204.985366)
		(end 175.414178 -204.985366)
		(width 0.14478)
		(layer "In13.Cu")
		(net "M_H_CPU1_SA_DQ<5>")
	)
	(segment
		(start 175.414178 -204.985366)
		(end 175.139096 -205.260448)
		(width 0.14478)
		(layer "In13.Cu")
		(net "M_H_CPU1_SA_DQ<5>")
	)
	(segment
		(start 169.67962 -204.560424)
		(end 167.072056 -204.560424)
		(width 0.14478)
		(layer "In13.Cu")
		(net "M_H_CPU1_SA_DQ<5>")
	)
	(segment
		(start 174.587916 -204.985366)
		(end 172.899324 -204.985366)
		(width 0.14478)
		(layer "In13.Cu")
		(net "M_H_CPU1_SA_DQ<5>")
	)
	(segment
		(start 137.811764 -229.416864)
		(end 137.803382 -229.42169)
		(width 0.0889)
		(layer "In13.Cu")
		(net "M_H_CPU1_SA_DQ<5>")
	)
	(segment
		(start 144.714468 -226.542854)
		(end 143.523716 -227.733606)
		(width 0.0889)
		(layer "In13.Cu")
		(net "M_H_CPU1_SA_DQ<5>")
	)
	(segment
		(start 134.650734 -229.359968)
		(end 134.804658 -229.094538)
		(width 0.0889)
		(layer "In13.Cu")
		(net "M_H_CPU1_SA_DQ<5>")
	)
	(segment
		(start 165.821614 -205.810866)
		(end 160.69183 -205.810866)
		(width 0.14478)
		(layer "In13.Cu")
		(net "M_H_CPU1_SA_DQ<5>")
	)
	(segment
		(start 172.899324 -204.985366)
		(end 172.474382 -205.410308)
		(width 0.14478)
		(layer "In13.Cu")
		(net "M_H_CPU1_SA_DQ<5>")
	)
	(segment
		(start 142.98168 -228.607112)
		(end 142.945358 -228.628194)
		(width 0.0889)
		(layer "In13.Cu")
		(net "M_H_CPU1_SA_DQ<5>")
	)
	(segment
		(start 167.072056 -204.560424)
		(end 165.821614 -205.810866)
		(width 0.14478)
		(layer "In13.Cu")
		(net "M_H_CPU1_SA_DQ<5>")
	)
	(segment
		(start 146.738594 -222.067374)
		(end 146.738594 -222.678498)
		(width 0.0889)
		(layer "In13.Cu")
		(net "M_H_CPU1_SA_DQ<5>")
	)
	(segment
		(start 146.129248 -223.287844)
		(end 146.129248 -223.587564)
		(width 0.0889)
		(layer "In13.Cu")
		(net "M_H_CPU1_SA_DQ<5>")
	)
	(segment
		(start 145.595848 -224.644204)
		(end 144.714468 -225.525584)
		(width 0.0889)
		(layer "In13.Cu")
		(net "M_H_CPU1_SA_DQ<5>")
	)
	(segment
		(start 146.738594 -219.153486)
		(end 146.738594 -222.067374)
		(width 0.14478)
		(layer "In13.Cu")
		(net "M_H_CPU1_SA_DQ<5>")
	)
	(segment
		(start 145.595848 -224.120964)
		(end 145.595848 -224.644204)
		(width 0.0889)
		(layer "In13.Cu")
		(net "M_H_CPU1_SA_DQ<5>")
	)
	(segment
		(start 144.714468 -225.525584)
		(end 144.714468 -226.542854)
		(width 0.0889)
		(layer "In13.Cu")
		(net "M_H_CPU1_SA_DQ<5>")
	)
	(segment
		(start 146.129248 -223.587564)
		(end 145.595848 -224.120964)
		(width 0.0889)
		(layer "In13.Cu")
		(net "M_H_CPU1_SA_DQ<5>")
	)
	(segment
		(start 143.451834 -227.797106)
		(end 143.412718 -227.819966)
		(width 0.0889)
		(layer "In13.Cu")
		(net "M_H_CPU1_SA_DQ<5>")
	)
	(segment
		(start 155.363926 -211.13877)
		(end 154.75331 -211.13877)
		(width 0.14478)
		(layer "In13.Cu")
		(net "M_H_CPU1_SA_DQ<5>")
	)
	(segment
		(start 142.545308 -229.397306)
		(end 142.51178 -229.416864)
		(width 0.0889)
		(layer "In13.Cu")
		(net "M_H_CPU1_SA_DQ<5>")
	)
	(segment
		(start 138.751818 -229.416864)
		(end 138.743436 -229.42169)
		(width 0.0889)
		(layer "In13.Cu")
		(net "M_H_CPU1_SA_DQ<5>")
	)
	(segment
		(start 146.738594 -222.678498)
		(end 146.129248 -223.287844)
		(width 0.0889)
		(layer "In13.Cu")
		(net "M_H_CPU1_SA_DQ<5>")
	)
	(segment
		(start 135.56615 -229.42169)
		(end 135.557768 -229.416864)
		(width 0.0889)
		(layer "In13.Cu")
		(net "M_H_CPU1_SA_DQ<5>")
	)
	(segment
		(start 134.673086 -229.443026)
		(end 134.650734 -229.359968)
		(width 0.0889)
		(layer "In13.Cu")
		(net "M_H_CPU1_SA_DQ<5>")
	)
	(arc
		(start 140.257784 -229.416864)
		(mid 139.974828 -229.340687)
		(end 139.691872 -229.416864)
		(width 0.0889)
		(layer "In13.Cu")
		(net "M_H_CPU1_SA_DQ<5>")
	)
	(arc
		(start 142.137638 -229.416864)
		(mid 141.854682 -229.340687)
		(end 141.571726 -229.416864)
		(width 0.0889)
		(layer "In13.Cu")
		(net "M_H_CPU1_SA_DQ<5>")
	)
	(arc
		(start 139.691872 -229.416864)
		(mid 139.509621 -229.467248)
		(end 139.326112 -229.42169)
		(width 0.0889)
		(layer "In13.Cu")
		(net "M_H_CPU1_SA_DQ<5>")
	)
	(arc
		(start 134.991856 -229.416864)
		(mid 134.835418 -229.465869)
		(end 134.673086 -229.443026)
		(width 0.0889)
		(layer "In13.Cu")
		(net "M_H_CPU1_SA_DQ<5>")
	)
	(arc
		(start 141.571726 -229.416864)
		(mid 141.384782 -229.467153)
		(end 141.197838 -229.416864)
		(width 0.0889)
		(layer "In13.Cu")
		(net "M_H_CPU1_SA_DQ<5>")
	)
	(arc
		(start 143.412718 -227.819966)
		(mid 143.233905 -228.022316)
		(end 143.169386 -228.284532)
		(width 0.0889)
		(layer "In13.Cu")
		(net "M_H_CPU1_SA_DQ<5>")
	)
	(arc
		(start 138.743436 -229.42169)
		(mid 138.559928 -229.467215)
		(end 138.377676 -229.416864)
		(width 0.0889)
		(layer "In13.Cu")
		(net "M_H_CPU1_SA_DQ<5>")
	)
	(arc
		(start 138.377676 -229.416864)
		(mid 138.09472 -229.340687)
		(end 137.811764 -229.416864)
		(width 0.0889)
		(layer "In13.Cu")
		(net "M_H_CPU1_SA_DQ<5>")
	)
	(arc
		(start 143.169386 -228.284532)
		(mid 143.128131 -228.455503)
		(end 143.01343 -228.588824)
		(width 0.0889)
		(layer "In13.Cu")
		(net "M_H_CPU1_SA_DQ<5>")
	)
	(arc
		(start 135.93191 -229.416864)
		(mid 135.749659 -229.467248)
		(end 135.56615 -229.42169)
		(width 0.0889)
		(layer "In13.Cu")
		(net "M_H_CPU1_SA_DQ<5>")
	)
	(arc
		(start 142.945358 -228.628194)
		(mid 142.764706 -228.830939)
		(end 142.699486 -229.094538)
		(width 0.0889)
		(layer "In13.Cu")
		(net "M_H_CPU1_SA_DQ<5>")
	)
	(arc
		(start 142.699486 -229.094538)
		(mid 142.658724 -229.264422)
		(end 142.545308 -229.397306)
		(width 0.0889)
		(layer "In13.Cu")
		(net "M_H_CPU1_SA_DQ<5>")
	)
	(arc
		(start 136.87171 -229.416864)
		(mid 136.684766 -229.467153)
		(end 136.497822 -229.416864)
		(width 0.0889)
		(layer "In13.Cu")
		(net "M_H_CPU1_SA_DQ<5>")
	)
	(arc
		(start 140.631926 -229.416864)
		(mid 140.449675 -229.467248)
		(end 140.266166 -229.42169)
		(width 0.0889)
		(layer "In13.Cu")
		(net "M_H_CPU1_SA_DQ<5>")
	)
	(arc
		(start 136.497822 -229.416864)
		(mid 136.214866 -229.340687)
		(end 135.93191 -229.416864)
		(width 0.0889)
		(layer "In13.Cu")
		(net "M_H_CPU1_SA_DQ<5>")
	)
	(arc
		(start 141.197838 -229.416864)
		(mid 140.914882 -229.340687)
		(end 140.631926 -229.416864)
		(width 0.0889)
		(layer "In13.Cu")
		(net "M_H_CPU1_SA_DQ<5>")
	)
	(arc
		(start 139.31773 -229.416864)
		(mid 139.034774 -229.340687)
		(end 138.751818 -229.416864)
		(width 0.0889)
		(layer "In13.Cu")
		(net "M_H_CPU1_SA_DQ<5>")
	)
	(arc
		(start 137.437622 -229.416864)
		(mid 137.154666 -229.340687)
		(end 136.87171 -229.416864)
		(width 0.0889)
		(layer "In13.Cu")
		(net "M_H_CPU1_SA_DQ<5>")
	)
	(arc
		(start 135.557768 -229.416864)
		(mid 135.274812 -229.340687)
		(end 134.991856 -229.416864)
		(width 0.0889)
		(layer "In13.Cu")
		(net "M_H_CPU1_SA_DQ<5>")
	)
	(arc
		(start 137.803382 -229.42169)
		(mid 137.619874 -229.467215)
		(end 137.437622 -229.416864)
		(width 0.0889)
		(layer "In13.Cu")
		(net "M_H_CPU1_SA_DQ<5>")
	)
	(arc
		(start 142.503398 -229.42169)
		(mid 142.31989 -229.467215)
		(end 142.137638 -229.416864)
		(width 0.0889)
		(layer "In13.Cu")
		(net "M_H_CPU1_SA_DQ<5>")
	)
	(segment
		(start 135.748014 -228.55047)
		(end 136.214866 -228.284532)
		(width 0.10668)
		(layer "F.Cu")
		(net "M_H_CPU1_SA_DQ<4>")
	)
	(segment
		(start 165.929818 -204.110844)
		(end 160.509204 -204.110844)
		(width 0.14478)
		(layer "In13.Cu")
		(net "M_H_CPU1_SA_DQ<4>")
	)
	(segment
		(start 136.40181 -228.607112)
		(end 136.393428 -228.611938)
		(width 0.0889)
		(layer "In13.Cu")
		(net "M_H_CPU1_SA_DQ<4>")
	)
	(segment
		(start 142.98168 -226.9871)
		(end 142.945358 -227.008182)
		(width 0.0889)
		(layer "In13.Cu")
		(net "M_H_CPU1_SA_DQ<4>")
	)
	(segment
		(start 144.391888 -224.557082)
		(end 144.352772 -224.579942)
		(width 0.0889)
		(layer "In13.Cu")
		(net "M_H_CPU1_SA_DQ<4>")
	)
	(segment
		(start 176.072038 -203.285344)
		(end 175.572928 -203.285344)
		(width 0.14478)
		(layer "In13.Cu")
		(net "M_H_CPU1_SA_DQ<4>")
	)
	(segment
		(start 174.078138 -203.285344)
		(end 173.643544 -203.719938)
		(width 0.14478)
		(layer "In13.Cu")
		(net "M_H_CPU1_SA_DQ<4>")
	)
	(segment
		(start 167.18026 -202.860402)
		(end 165.929818 -204.110844)
		(width 0.14478)
		(layer "In13.Cu")
		(net "M_H_CPU1_SA_DQ<4>")
	)
	(segment
		(start 145.33245 -222.936816)
		(end 145.29435 -222.958914)
		(width 0.0889)
		(layer "In13.Cu")
		(net "M_H_CPU1_SA_DQ<4>")
	)
	(segment
		(start 142.51178 -227.797106)
		(end 142.472664 -227.819966)
		(width 0.0889)
		(layer "In13.Cu")
		(net "M_H_CPU1_SA_DQ<4>")
	)
	(segment
		(start 136.08304 -228.633274)
		(end 136.060688 -228.549962)
		(width 0.0889)
		(layer "In13.Cu")
		(net "M_H_CPU1_SA_DQ<4>")
	)
	(segment
		(start 175.572928 -203.285344)
		(end 175.428148 -203.430124)
		(width 0.14478)
		(layer "In13.Cu")
		(net "M_H_CPU1_SA_DQ<4>")
	)
	(segment
		(start 174.732188 -203.285344)
		(end 174.078138 -203.285344)
		(width 0.14478)
		(layer "In13.Cu")
		(net "M_H_CPU1_SA_DQ<4>")
	)
	(segment
		(start 141.67612 -228.611938)
		(end 141.667738 -228.607112)
		(width 0.0889)
		(layer "In13.Cu")
		(net "M_H_CPU1_SA_DQ<4>")
	)
	(segment
		(start 170.405552 -203.719938)
		(end 169.546016 -202.860402)
		(width 0.14478)
		(layer "In13.Cu")
		(net "M_H_CPU1_SA_DQ<4>")
	)
	(segment
		(start 173.643544 -203.719938)
		(end 170.405552 -203.719938)
		(width 0.14478)
		(layer "In13.Cu")
		(net "M_H_CPU1_SA_DQ<4>")
	)
	(segment
		(start 145.839434 -222.43796)
		(end 145.403824 -222.87357)
		(width 0.0889)
		(layer "In13.Cu")
		(net "M_H_CPU1_SA_DQ<4>")
	)
	(segment
		(start 142.54353 -227.778818)
		(end 142.51178 -227.797106)
		(width 0.0889)
		(layer "In13.Cu")
		(net "M_H_CPU1_SA_DQ<4>")
	)
	(segment
		(start 175.428148 -203.430124)
		(end 175.428148 -203.97724)
		(width 0.14478)
		(layer "In13.Cu")
		(net "M_H_CPU1_SA_DQ<4>")
	)
	(segment
		(start 142.07236 -228.589332)
		(end 142.04188 -228.607112)
		(width 0.0889)
		(layer "In13.Cu")
		(net "M_H_CPU1_SA_DQ<4>")
	)
	(segment
		(start 143.482314 -226.159314)
		(end 143.451834 -226.177094)
		(width 0.0889)
		(layer "In13.Cu")
		(net "M_H_CPU1_SA_DQ<4>")
	)
	(segment
		(start 143.451834 -226.177094)
		(end 143.412718 -226.199954)
		(width 0.0889)
		(layer "In13.Cu")
		(net "M_H_CPU1_SA_DQ<4>")
	)
	(segment
		(start 143.01343 -226.968812)
		(end 142.98168 -226.9871)
		(width 0.0889)
		(layer "In13.Cu")
		(net "M_H_CPU1_SA_DQ<4>")
	)
	(segment
		(start 175.428148 -203.97724)
		(end 175.283368 -204.12202)
		(width 0.14478)
		(layer "In13.Cu")
		(net "M_H_CPU1_SA_DQ<4>")
	)
	(segment
		(start 144.422368 -224.539302)
		(end 144.391888 -224.557082)
		(width 0.0889)
		(layer "In13.Cu")
		(net "M_H_CPU1_SA_DQ<4>")
	)
	(segment
		(start 144.861788 -223.747076)
		(end 144.822672 -223.769936)
		(width 0.0889)
		(layer "In13.Cu")
		(net "M_H_CPU1_SA_DQ<4>")
	)
	(segment
		(start 175.021748 -204.12202)
		(end 174.876968 -203.97724)
		(width 0.14478)
		(layer "In13.Cu")
		(net "M_H_CPU1_SA_DQ<4>")
	)
	(segment
		(start 141.101826 -228.607112)
		(end 141.093444 -228.611938)
		(width 0.0889)
		(layer "In13.Cu")
		(net "M_H_CPU1_SA_DQ<4>")
	)
	(segment
		(start 145.403824 -222.87357)
		(end 145.33245 -222.936816)
		(width 0.0889)
		(layer "In13.Cu")
		(net "M_H_CPU1_SA_DQ<4>")
	)
	(segment
		(start 174.876968 -203.430124)
		(end 174.732188 -203.285344)
		(width 0.14478)
		(layer "In13.Cu")
		(net "M_H_CPU1_SA_DQ<4>")
	)
	(segment
		(start 145.839434 -221.866206)
		(end 145.839434 -222.43796)
		(width 0.0889)
		(layer "In13.Cu")
		(net "M_H_CPU1_SA_DQ<4>")
	)
	(segment
		(start 136.976104 -228.611938)
		(end 136.967722 -228.607112)
		(width 0.0889)
		(layer "In13.Cu")
		(net "M_H_CPU1_SA_DQ<4>")
	)
	(segment
		(start 174.876968 -203.97724)
		(end 174.876968 -203.430124)
		(width 0.14478)
		(layer "In13.Cu")
		(net "M_H_CPU1_SA_DQ<4>")
	)
	(segment
		(start 169.546016 -202.860402)
		(end 167.18026 -202.860402)
		(width 0.14478)
		(layer "In13.Cu")
		(net "M_H_CPU1_SA_DQ<4>")
	)
	(segment
		(start 175.283368 -204.12202)
		(end 175.021748 -204.12202)
		(width 0.14478)
		(layer "In13.Cu")
		(net "M_H_CPU1_SA_DQ<4>")
	)
	(segment
		(start 136.060688 -228.549962)
		(end 136.214866 -228.284532)
		(width 0.0889)
		(layer "In13.Cu")
		(net "M_H_CPU1_SA_DQ<4>")
	)
	(segment
		(start 145.839434 -218.780614)
		(end 145.839434 -221.866206)
		(width 0.14478)
		(layer "In13.Cu")
		(net "M_H_CPU1_SA_DQ<4>")
	)
	(segment
		(start 137.916158 -228.611938)
		(end 137.907776 -228.607112)
		(width 0.0889)
		(layer "In13.Cu")
		(net "M_H_CPU1_SA_DQ<4>")
	)
	(segment
		(start 143.921734 -225.367088)
		(end 143.882618 -225.389948)
		(width 0.0889)
		(layer "In13.Cu")
		(net "M_H_CPU1_SA_DQ<4>")
	)
	(segment
		(start 160.509204 -204.110844)
		(end 145.839434 -218.780614)
		(width 0.14478)
		(layer "In13.Cu")
		(net "M_H_CPU1_SA_DQ<4>")
	)
	(segment
		(start 143.953484 -225.3488)
		(end 143.921734 -225.367088)
		(width 0.0889)
		(layer "In13.Cu")
		(net "M_H_CPU1_SA_DQ<4>")
	)
	(segment
		(start 140.161772 -228.607112)
		(end 140.15339 -228.611938)
		(width 0.0889)
		(layer "In13.Cu")
		(net "M_H_CPU1_SA_DQ<4>")
	)
	(segment
		(start 144.893538 -223.728788)
		(end 144.861788 -223.747076)
		(width 0.0889)
		(layer "In13.Cu")
		(net "M_H_CPU1_SA_DQ<4>")
	)
	(arc
		(start 143.882618 -225.389948)
		(mid 143.703805 -225.592298)
		(end 143.639286 -225.854514)
		(width 0.0889)
		(layer "In13.Cu")
		(net "M_H_CPU1_SA_DQ<4>")
	)
	(arc
		(start 142.229332 -228.284532)
		(mid 142.187783 -228.455954)
		(end 142.07236 -228.589332)
		(width 0.0889)
		(layer "In13.Cu")
		(net "M_H_CPU1_SA_DQ<4>")
	)
	(arc
		(start 145.29435 -222.958914)
		(mid 145.114465 -223.161483)
		(end 145.049494 -223.424496)
		(width 0.0889)
		(layer "In13.Cu")
		(net "M_H_CPU1_SA_DQ<4>")
	)
	(arc
		(start 137.341864 -228.607112)
		(mid 137.159613 -228.657462)
		(end 136.976104 -228.611938)
		(width 0.0889)
		(layer "In13.Cu")
		(net "M_H_CPU1_SA_DQ<4>")
	)
	(arc
		(start 144.10944 -225.044508)
		(mid 144.068185 -225.215479)
		(end 143.953484 -225.3488)
		(width 0.0889)
		(layer "In13.Cu")
		(net "M_H_CPU1_SA_DQ<4>")
	)
	(arc
		(start 138.281918 -228.607112)
		(mid 138.099667 -228.657462)
		(end 137.916158 -228.611938)
		(width 0.0889)
		(layer "In13.Cu")
		(net "M_H_CPU1_SA_DQ<4>")
	)
	(arc
		(start 142.472664 -227.819966)
		(mid 142.293851 -228.022316)
		(end 142.229332 -228.284532)
		(width 0.0889)
		(layer "In13.Cu")
		(net "M_H_CPU1_SA_DQ<4>")
	)
	(arc
		(start 136.393428 -228.611938)
		(mid 136.240558 -228.656579)
		(end 136.08304 -228.633274)
		(width 0.0889)
		(layer "In13.Cu")
		(net "M_H_CPU1_SA_DQ<4>")
	)
	(arc
		(start 143.412718 -226.199954)
		(mid 143.233905 -226.402304)
		(end 143.169386 -226.66452)
		(width 0.0889)
		(layer "In13.Cu")
		(net "M_H_CPU1_SA_DQ<4>")
	)
	(arc
		(start 144.822672 -223.769936)
		(mid 144.643859 -223.972286)
		(end 144.57934 -224.234502)
		(width 0.0889)
		(layer "In13.Cu")
		(net "M_H_CPU1_SA_DQ<4>")
	)
	(arc
		(start 139.221718 -228.607112)
		(mid 139.034774 -228.657367)
		(end 138.84783 -228.607112)
		(width 0.0889)
		(layer "In13.Cu")
		(net "M_H_CPU1_SA_DQ<4>")
	)
	(arc
		(start 140.15339 -228.611938)
		(mid 139.969882 -228.657432)
		(end 139.78763 -228.607112)
		(width 0.0889)
		(layer "In13.Cu")
		(net "M_H_CPU1_SA_DQ<4>")
	)
	(arc
		(start 144.352772 -224.579942)
		(mid 144.173959 -224.782292)
		(end 144.10944 -225.044508)
		(width 0.0889)
		(layer "In13.Cu")
		(net "M_H_CPU1_SA_DQ<4>")
	)
	(arc
		(start 143.639286 -225.854514)
		(mid 143.597737 -226.025936)
		(end 143.482314 -226.159314)
		(width 0.0889)
		(layer "In13.Cu")
		(net "M_H_CPU1_SA_DQ<4>")
	)
	(arc
		(start 140.727684 -228.607112)
		(mid 140.444728 -228.530935)
		(end 140.161772 -228.607112)
		(width 0.0889)
		(layer "In13.Cu")
		(net "M_H_CPU1_SA_DQ<4>")
	)
	(arc
		(start 137.907776 -228.607112)
		(mid 137.62482 -228.530935)
		(end 137.341864 -228.607112)
		(width 0.0889)
		(layer "In13.Cu")
		(net "M_H_CPU1_SA_DQ<4>")
	)
	(arc
		(start 143.169386 -226.66452)
		(mid 143.128131 -226.835491)
		(end 143.01343 -226.968812)
		(width 0.0889)
		(layer "In13.Cu")
		(net "M_H_CPU1_SA_DQ<4>")
	)
	(arc
		(start 141.667738 -228.607112)
		(mid 141.384782 -228.530935)
		(end 141.101826 -228.607112)
		(width 0.0889)
		(layer "In13.Cu")
		(net "M_H_CPU1_SA_DQ<4>")
	)
	(arc
		(start 142.699486 -227.474526)
		(mid 142.658231 -227.645497)
		(end 142.54353 -227.778818)
		(width 0.0889)
		(layer "In13.Cu")
		(net "M_H_CPU1_SA_DQ<4>")
	)
	(arc
		(start 144.57934 -224.234502)
		(mid 144.537791 -224.405924)
		(end 144.422368 -224.539302)
		(width 0.0889)
		(layer "In13.Cu")
		(net "M_H_CPU1_SA_DQ<4>")
	)
	(arc
		(start 139.78763 -228.607112)
		(mid 139.504674 -228.530935)
		(end 139.221718 -228.607112)
		(width 0.0889)
		(layer "In13.Cu")
		(net "M_H_CPU1_SA_DQ<4>")
	)
	(arc
		(start 145.049494 -223.424496)
		(mid 145.008239 -223.595467)
		(end 144.893538 -223.728788)
		(width 0.0889)
		(layer "In13.Cu")
		(net "M_H_CPU1_SA_DQ<4>")
	)
	(arc
		(start 136.967722 -228.607112)
		(mid 136.684766 -228.530935)
		(end 136.40181 -228.607112)
		(width 0.0889)
		(layer "In13.Cu")
		(net "M_H_CPU1_SA_DQ<4>")
	)
	(arc
		(start 141.093444 -228.611938)
		(mid 140.909936 -228.657432)
		(end 140.727684 -228.607112)
		(width 0.0889)
		(layer "In13.Cu")
		(net "M_H_CPU1_SA_DQ<4>")
	)
	(arc
		(start 142.04188 -228.607112)
		(mid 141.859629 -228.657462)
		(end 141.67612 -228.611938)
		(width 0.0889)
		(layer "In13.Cu")
		(net "M_H_CPU1_SA_DQ<4>")
	)
	(arc
		(start 138.84783 -228.607112)
		(mid 138.564874 -228.530935)
		(end 138.281918 -228.607112)
		(width 0.0889)
		(layer "In13.Cu")
		(net "M_H_CPU1_SA_DQ<4>")
	)
	(arc
		(start 142.945358 -227.008182)
		(mid 142.764706 -227.210927)
		(end 142.699486 -227.474526)
		(width 0.0889)
		(layer "In13.Cu")
		(net "M_H_CPU1_SA_DQ<4>")
	)
	(segment
		(start 133.867906 -226.930458)
		(end 134.334758 -226.66452)
		(width 0.10668)
		(layer "F.Cu")
		(net "M_H_CPU1_SA_DQ<3>")
	)
	(segment
		(start 153.07183 -206.924656)
		(end 153.256996 -206.73949)
		(width 0.14478)
		(layer "In13.Cu")
		(net "M_H_CPU1_SA_DQ<3>")
	)
	(segment
		(start 154.63139 -205.365096)
		(end 154.816556 -205.17993)
		(width 0.14478)
		(layer "In13.Cu")
		(net "M_H_CPU1_SA_DQ<3>")
	)
	(segment
		(start 157.935676 -202.06081)
		(end 158.1404 -202.06081)
		(width 0.14478)
		(layer "In13.Cu")
		(net "M_H_CPU1_SA_DQ<3>")
	)
	(segment
		(start 151.51227 -208.484216)
		(end 151.697436 -208.29905)
		(width 0.14478)
		(layer "In13.Cu")
		(net "M_H_CPU1_SA_DQ<3>")
	)
	(segment
		(start 156.376116 -203.62037)
		(end 156.58084 -203.62037)
		(width 0.14478)
		(layer "In13.Cu")
		(net "M_H_CPU1_SA_DQ<3>")
	)
	(segment
		(start 156.97073 -203.025756)
		(end 157.155896 -202.84059)
		(width 0.14478)
		(layer "In13.Cu")
		(net "M_H_CPU1_SA_DQ<3>")
	)
	(segment
		(start 141.667738 -224.721928)
		(end 141.706854 -224.699068)
		(width 0.0889)
		(layer "In13.Cu")
		(net "M_H_CPU1_SA_DQ<3>")
	)
	(segment
		(start 157.59176 -202.867006)
		(end 157.776926 -202.68184)
		(width 0.14478)
		(layer "In13.Cu")
		(net "M_H_CPU1_SA_DQ<3>")
	)
	(segment
		(start 153.098246 -207.36052)
		(end 153.098246 -207.155796)
		(width 0.14478)
		(layer "In13.Cu")
		(net "M_H_CPU1_SA_DQ<3>")
	)
	(segment
		(start 153.07183 -207.12938)
		(end 153.07183 -206.924656)
		(width 0.14478)
		(layer "In13.Cu")
		(net "M_H_CPU1_SA_DQ<3>")
	)
	(segment
		(start 150.13813 -211.018374)
		(end 150.13813 -210.320636)
		(width 0.14478)
		(layer "In13.Cu")
		(net "M_H_CPU1_SA_DQ<3>")
	)
	(segment
		(start 141.197838 -225.531934)
		(end 141.23416 -225.510852)
		(width 0.0889)
		(layer "In13.Cu")
		(net "M_H_CPU1_SA_DQ<3>")
	)
	(segment
		(start 141.635988 -224.740216)
		(end 141.667738 -224.721928)
		(width 0.0889)
		(layer "In13.Cu")
		(net "M_H_CPU1_SA_DQ<3>")
	)
	(segment
		(start 150.73249 -209.263996)
		(end 150.917656 -209.07883)
		(width 0.14478)
		(layer "In13.Cu")
		(net "M_H_CPU1_SA_DQ<3>")
	)
	(segment
		(start 171.97197 -200.10882)
		(end 171.97197 -199.8853)
		(width 0.14478)
		(layer "In13.Cu")
		(net "M_H_CPU1_SA_DQ<3>")
	)
	(segment
		(start 150.13813 -210.320636)
		(end 150.758906 -209.69986)
		(width 0.14478)
		(layer "In13.Cu")
		(net "M_H_CPU1_SA_DQ<3>")
	)
	(segment
		(start 160.138618 -200.320148)
		(end 166.05631 -200.320148)
		(width 0.14478)
		(layer "In13.Cu")
		(net "M_H_CPU1_SA_DQ<3>")
	)
	(segment
		(start 143.480028 -217.676476)
		(end 150.13813 -211.018374)
		(width 0.14478)
		(layer "In13.Cu")
		(net "M_H_CPU1_SA_DQ<3>")
	)
	(segment
		(start 156.97073 -203.23048)
		(end 156.97073 -203.025756)
		(width 0.14478)
		(layer "In13.Cu")
		(net "M_H_CPU1_SA_DQ<3>")
	)
	(segment
		(start 157.155896 -202.84059)
		(end 157.36062 -202.84059)
		(width 0.14478)
		(layer "In13.Cu")
		(net "M_H_CPU1_SA_DQ<3>")
	)
	(segment
		(start 154.657806 -205.80096)
		(end 154.657806 -205.596236)
		(width 0.14478)
		(layer "In13.Cu")
		(net "M_H_CPU1_SA_DQ<3>")
	)
	(segment
		(start 151.35352 -209.105246)
		(end 151.538686 -208.92008)
		(width 0.14478)
		(layer "In13.Cu")
		(net "M_H_CPU1_SA_DQ<3>")
	)
	(segment
		(start 166.9161 -199.460358)
		(end 170.199812 -199.460358)
		(width 0.14478)
		(layer "In13.Cu")
		(net "M_H_CPU1_SA_DQ<3>")
	)
	(segment
		(start 136.393428 -226.337114)
		(end 136.40181 -226.34194)
		(width 0.0889)
		(layer "In13.Cu")
		(net "M_H_CPU1_SA_DQ<3>")
	)
	(segment
		(start 153.488136 -206.765906)
		(end 153.69286 -206.765906)
		(width 0.14478)
		(layer "In13.Cu")
		(net "M_H_CPU1_SA_DQ<3>")
	)
	(segment
		(start 156.607256 -203.646786)
		(end 156.81198 -203.646786)
		(width 0.14478)
		(layer "In13.Cu")
		(net "M_H_CPU1_SA_DQ<3>")
	)
	(segment
		(start 155.047696 -205.206346)
		(end 155.25242 -205.206346)
		(width 0.14478)
		(layer "In13.Cu")
		(net "M_H_CPU1_SA_DQ<3>")
	)
	(segment
		(start 151.538686 -208.92008)
		(end 151.538686 -208.715356)
		(width 0.14478)
		(layer "In13.Cu")
		(net "M_H_CPU1_SA_DQ<3>")
	)
	(segment
		(start 156.217366 -204.036676)
		(end 156.19095 -204.01026)
		(width 0.14478)
		(layer "In13.Cu")
		(net "M_H_CPU1_SA_DQ<3>")
	)
	(segment
		(start 142.138146 -223.911922)
		(end 142.172944 -223.891602)
		(width 0.0889)
		(layer "In13.Cu")
		(net "M_H_CPU1_SA_DQ<3>")
	)
	(segment
		(start 150.73249 -209.46872)
		(end 150.73249 -209.263996)
		(width 0.14478)
		(layer "In13.Cu")
		(net "M_H_CPU1_SA_DQ<3>")
	)
	(segment
		(start 143.04772 -222.30969)
		(end 143.077946 -222.292164)
		(width 0.0889)
		(layer "In13.Cu")
		(net "M_H_CPU1_SA_DQ<3>")
	)
	(segment
		(start 151.697436 -208.29905)
		(end 151.90216 -208.29905)
		(width 0.14478)
		(layer "In13.Cu")
		(net "M_H_CPU1_SA_DQ<3>")
	)
	(segment
		(start 143.480028 -221.235524)
		(end 143.480028 -217.676476)
		(width 0.14478)
		(layer "In13.Cu")
		(net "M_H_CPU1_SA_DQ<3>")
	)
	(segment
		(start 153.85161 -206.144876)
		(end 154.036776 -205.95971)
		(width 0.14478)
		(layer "In13.Cu")
		(net "M_H_CPU1_SA_DQ<3>")
	)
	(segment
		(start 151.90216 -208.29905)
		(end 151.928576 -208.325466)
		(width 0.14478)
		(layer "In13.Cu")
		(net "M_H_CPU1_SA_DQ<3>")
	)
	(segment
		(start 140.727684 -226.34194)
		(end 140.7668 -226.31908)
		(width 0.0889)
		(layer "In13.Cu")
		(net "M_H_CPU1_SA_DQ<3>")
	)
	(segment
		(start 154.267916 -205.986126)
		(end 154.47264 -205.986126)
		(width 0.14478)
		(layer "In13.Cu")
		(net "M_H_CPU1_SA_DQ<3>")
	)
	(segment
		(start 156.19095 -204.01026)
		(end 156.19095 -203.805536)
		(width 0.14478)
		(layer "In13.Cu")
		(net "M_H_CPU1_SA_DQ<3>")
	)
	(segment
		(start 156.0322 -204.426566)
		(end 156.217366 -204.2414)
		(width 0.14478)
		(layer "In13.Cu")
		(net "M_H_CPU1_SA_DQ<3>")
	)
	(segment
		(start 171.7802 -200.30059)
		(end 171.97197 -200.10882)
		(width 0.14478)
		(layer "In13.Cu")
		(net "M_H_CPU1_SA_DQ<3>")
	)
	(segment
		(start 152.318466 -207.935576)
		(end 152.29205 -207.90916)
		(width 0.14478)
		(layer "In13.Cu")
		(net "M_H_CPU1_SA_DQ<3>")
	)
	(segment
		(start 154.816556 -205.17993)
		(end 155.02128 -205.17993)
		(width 0.14478)
		(layer "In13.Cu")
		(net "M_H_CPU1_SA_DQ<3>")
	)
	(segment
		(start 155.80106 -204.40015)
		(end 155.827476 -204.426566)
		(width 0.14478)
		(layer "In13.Cu")
		(net "M_H_CPU1_SA_DQ<3>")
	)
	(segment
		(start 135.453374 -226.337114)
		(end 135.461756 -226.34194)
		(width 0.0889)
		(layer "In13.Cu")
		(net "M_H_CPU1_SA_DQ<3>")
	)
	(segment
		(start 158.166816 -202.087226)
		(end 158.37154 -202.087226)
		(width 0.14478)
		(layer "In13.Cu")
		(net "M_H_CPU1_SA_DQ<3>")
	)
	(segment
		(start 143.077946 -222.292164)
		(end 143.11884 -222.268542)
		(width 0.0889)
		(layer "In13.Cu")
		(net "M_H_CPU1_SA_DQ<3>")
	)
	(segment
		(start 152.1333 -208.325466)
		(end 152.318466 -208.1403)
		(width 0.14478)
		(layer "In13.Cu")
		(net "M_H_CPU1_SA_DQ<3>")
	)
	(segment
		(start 154.47264 -205.986126)
		(end 154.657806 -205.80096)
		(width 0.14478)
		(layer "In13.Cu")
		(net "M_H_CPU1_SA_DQ<3>")
	)
	(segment
		(start 158.1404 -202.06081)
		(end 158.166816 -202.087226)
		(width 0.14478)
		(layer "In13.Cu")
		(net "M_H_CPU1_SA_DQ<3>")
	)
	(segment
		(start 143.361156 -221.537276)
		(end 143.480028 -221.418404)
		(width 0.0889)
		(layer "In13.Cu")
		(net "M_H_CPU1_SA_DQ<3>")
	)
	(segment
		(start 142.10538 -223.930972)
		(end 142.138146 -223.911922)
		(width 0.0889)
		(layer "In13.Cu")
		(net "M_H_CPU1_SA_DQ<3>")
	)
	(segment
		(start 157.387036 -202.867006)
		(end 157.59176 -202.867006)
		(width 0.14478)
		(layer "In13.Cu")
		(net "M_H_CPU1_SA_DQ<3>")
	)
	(segment
		(start 152.68194 -207.51927)
		(end 152.708356 -207.545686)
		(width 0.14478)
		(layer "In13.Cu")
		(net "M_H_CPU1_SA_DQ<3>")
	)
	(segment
		(start 157.75051 -202.245976)
		(end 157.935676 -202.06081)
		(width 0.14478)
		(layer "In13.Cu")
		(net "M_H_CPU1_SA_DQ<3>")
	)
	(segment
		(start 157.75051 -202.4507)
		(end 157.75051 -202.245976)
		(width 0.14478)
		(layer "In13.Cu")
		(net "M_H_CPU1_SA_DQ<3>")
	)
	(segment
		(start 153.85161 -206.3496)
		(end 153.85161 -206.144876)
		(width 0.14478)
		(layer "In13.Cu")
		(net "M_H_CPU1_SA_DQ<3>")
	)
	(segment
		(start 152.29205 -207.704436)
		(end 152.477216 -207.51927)
		(width 0.14478)
		(layer "In13.Cu")
		(net "M_H_CPU1_SA_DQ<3>")
	)
	(segment
		(start 156.997146 -203.256896)
		(end 156.97073 -203.23048)
		(width 0.14478)
		(layer "In13.Cu")
		(net "M_H_CPU1_SA_DQ<3>")
	)
	(segment
		(start 155.827476 -204.426566)
		(end 156.0322 -204.426566)
		(width 0.14478)
		(layer "In13.Cu")
		(net "M_H_CPU1_SA_DQ<3>")
	)
	(segment
		(start 154.657806 -205.596236)
		(end 154.63139 -205.56982)
		(width 0.14478)
		(layer "In13.Cu")
		(net "M_H_CPU1_SA_DQ<3>")
	)
	(segment
		(start 143.361156 -221.804484)
		(end 143.361156 -221.537276)
		(width 0.0889)
		(layer "In13.Cu")
		(net "M_H_CPU1_SA_DQ<3>")
	)
	(segment
		(start 152.318466 -208.1403)
		(end 152.318466 -207.935576)
		(width 0.14478)
		(layer "In13.Cu")
		(net "M_H_CPU1_SA_DQ<3>")
	)
	(segment
		(start 151.928576 -208.325466)
		(end 152.1333 -208.325466)
		(width 0.14478)
		(layer "In13.Cu")
		(net "M_H_CPU1_SA_DQ<3>")
	)
	(segment
		(start 157.36062 -202.84059)
		(end 157.387036 -202.867006)
		(width 0.14478)
		(layer "In13.Cu")
		(net "M_H_CPU1_SA_DQ<3>")
	)
	(segment
		(start 155.02128 -205.17993)
		(end 155.047696 -205.206346)
		(width 0.14478)
		(layer "In13.Cu")
		(net "M_H_CPU1_SA_DQ<3>")
	)
	(segment
		(start 141.166088 -225.550222)
		(end 141.197838 -225.531934)
		(width 0.0889)
		(layer "In13.Cu")
		(net "M_H_CPU1_SA_DQ<3>")
	)
	(segment
		(start 153.098246 -207.155796)
		(end 153.07183 -207.12938)
		(width 0.14478)
		(layer "In13.Cu")
		(net "M_H_CPU1_SA_DQ<3>")
	)
	(segment
		(start 171.040044 -200.30059)
		(end 171.7802 -200.30059)
		(width 0.14478)
		(layer "In13.Cu")
		(net "M_H_CPU1_SA_DQ<3>")
	)
	(segment
		(start 156.997146 -203.46162)
		(end 156.997146 -203.256896)
		(width 0.14478)
		(layer "In13.Cu")
		(net "M_H_CPU1_SA_DQ<3>")
	)
	(segment
		(start 134.334758 -226.66452)
		(end 134.488682 -226.39909)
		(width 0.0889)
		(layer "In13.Cu")
		(net "M_H_CPU1_SA_DQ<3>")
	)
	(segment
		(start 153.878026 -206.376016)
		(end 153.85161 -206.3496)
		(width 0.14478)
		(layer "In13.Cu")
		(net "M_H_CPU1_SA_DQ<3>")
	)
	(segment
		(start 142.575534 -223.120966)
		(end 142.608046 -223.10217)
		(width 0.0889)
		(layer "In13.Cu")
		(net "M_H_CPU1_SA_DQ<3>")
	)
	(segment
		(start 170.199812 -199.460358)
		(end 171.040044 -200.30059)
		(width 0.14478)
		(layer "In13.Cu")
		(net "M_H_CPU1_SA_DQ<3>")
	)
	(segment
		(start 140.15339 -226.337114)
		(end 140.161772 -226.34194)
		(width 0.0889)
		(layer "In13.Cu")
		(net "M_H_CPU1_SA_DQ<3>")
	)
	(segment
		(start 156.81198 -203.646786)
		(end 156.997146 -203.46162)
		(width 0.14478)
		(layer "In13.Cu")
		(net "M_H_CPU1_SA_DQ<3>")
	)
	(segment
		(start 150.917656 -209.07883)
		(end 151.12238 -209.07883)
		(width 0.14478)
		(layer "In13.Cu")
		(net "M_H_CPU1_SA_DQ<3>")
	)
	(segment
		(start 155.41117 -204.79004)
		(end 155.41117 -204.585316)
		(width 0.14478)
		(layer "In13.Cu")
		(net "M_H_CPU1_SA_DQ<3>")
	)
	(segment
		(start 156.58084 -203.62037)
		(end 156.607256 -203.646786)
		(width 0.14478)
		(layer "In13.Cu")
		(net "M_H_CPU1_SA_DQ<3>")
	)
	(segment
		(start 157.776926 -202.68184)
		(end 157.776926 -202.477116)
		(width 0.14478)
		(layer "In13.Cu")
		(net "M_H_CPU1_SA_DQ<3>")
	)
	(segment
		(start 152.708356 -207.545686)
		(end 152.91308 -207.545686)
		(width 0.14478)
		(layer "In13.Cu")
		(net "M_H_CPU1_SA_DQ<3>")
	)
	(segment
		(start 136.967722 -226.34194)
		(end 136.976104 -226.337114)
		(width 0.0889)
		(layer "In13.Cu")
		(net "M_H_CPU1_SA_DQ<3>")
	)
	(segment
		(start 156.217366 -204.2414)
		(end 156.217366 -204.036676)
		(width 0.14478)
		(layer "In13.Cu")
		(net "M_H_CPU1_SA_DQ<3>")
	)
	(segment
		(start 134.488682 -226.39909)
		(end 134.584694 -226.37369)
		(width 0.0889)
		(layer "In13.Cu")
		(net "M_H_CPU1_SA_DQ<3>")
	)
	(segment
		(start 153.256996 -206.73949)
		(end 153.46172 -206.73949)
		(width 0.14478)
		(layer "In13.Cu")
		(net "M_H_CPU1_SA_DQ<3>")
	)
	(segment
		(start 158.37154 -202.087226)
		(end 160.138618 -200.320148)
		(width 0.14478)
		(layer "In13.Cu")
		(net "M_H_CPU1_SA_DQ<3>")
	)
	(segment
		(start 155.596336 -204.40015)
		(end 155.80106 -204.40015)
		(width 0.14478)
		(layer "In13.Cu")
		(net "M_H_CPU1_SA_DQ<3>")
	)
	(segment
		(start 150.758906 -209.495136)
		(end 150.73249 -209.46872)
		(width 0.14478)
		(layer "In13.Cu")
		(net "M_H_CPU1_SA_DQ<3>")
	)
	(segment
		(start 151.148796 -209.105246)
		(end 151.35352 -209.105246)
		(width 0.14478)
		(layer "In13.Cu")
		(net "M_H_CPU1_SA_DQ<3>")
	)
	(segment
		(start 155.41117 -204.585316)
		(end 155.596336 -204.40015)
		(width 0.14478)
		(layer "In13.Cu")
		(net "M_H_CPU1_SA_DQ<3>")
	)
	(segment
		(start 152.477216 -207.51927)
		(end 152.68194 -207.51927)
		(width 0.14478)
		(layer "In13.Cu")
		(net "M_H_CPU1_SA_DQ<3>")
	)
	(segment
		(start 155.437586 -205.02118)
		(end 155.437586 -204.816456)
		(width 0.14478)
		(layer "In13.Cu")
		(net "M_H_CPU1_SA_DQ<3>")
	)
	(segment
		(start 151.51227 -208.68894)
		(end 151.51227 -208.484216)
		(width 0.14478)
		(layer "In13.Cu")
		(net "M_H_CPU1_SA_DQ<3>")
	)
	(segment
		(start 154.036776 -205.95971)
		(end 154.2415 -205.95971)
		(width 0.14478)
		(layer "In13.Cu")
		(net "M_H_CPU1_SA_DQ<3>")
	)
	(segment
		(start 151.538686 -208.715356)
		(end 151.51227 -208.68894)
		(width 0.14478)
		(layer "In13.Cu")
		(net "M_H_CPU1_SA_DQ<3>")
	)
	(segment
		(start 153.878026 -206.58074)
		(end 153.878026 -206.376016)
		(width 0.14478)
		(layer "In13.Cu")
		(net "M_H_CPU1_SA_DQ<3>")
	)
	(segment
		(start 157.776926 -202.477116)
		(end 157.75051 -202.4507)
		(width 0.14478)
		(layer "In13.Cu")
		(net "M_H_CPU1_SA_DQ<3>")
	)
	(segment
		(start 151.12238 -209.07883)
		(end 151.148796 -209.105246)
		(width 0.14478)
		(layer "In13.Cu")
		(net "M_H_CPU1_SA_DQ<3>")
	)
	(segment
		(start 137.907776 -226.34194)
		(end 137.916158 -226.337114)
		(width 0.0889)
		(layer "In13.Cu")
		(net "M_H_CPU1_SA_DQ<3>")
	)
	(segment
		(start 156.19095 -203.805536)
		(end 156.376116 -203.62037)
		(width 0.14478)
		(layer "In13.Cu")
		(net "M_H_CPU1_SA_DQ<3>")
	)
	(segment
		(start 153.46172 -206.73949)
		(end 153.488136 -206.765906)
		(width 0.14478)
		(layer "In13.Cu")
		(net "M_H_CPU1_SA_DQ<3>")
	)
	(segment
		(start 142.608046 -223.10217)
		(end 142.641574 -223.082612)
		(width 0.0889)
		(layer "In13.Cu")
		(net "M_H_CPU1_SA_DQ<3>")
	)
	(segment
		(start 150.758906 -209.69986)
		(end 150.758906 -209.495136)
		(width 0.14478)
		(layer "In13.Cu")
		(net "M_H_CPU1_SA_DQ<3>")
	)
	(segment
		(start 155.437586 -204.816456)
		(end 155.41117 -204.79004)
		(width 0.14478)
		(layer "In13.Cu")
		(net "M_H_CPU1_SA_DQ<3>")
	)
	(segment
		(start 166.05631 -200.320148)
		(end 166.9161 -199.460358)
		(width 0.14478)
		(layer "In13.Cu")
		(net "M_H_CPU1_SA_DQ<3>")
	)
	(segment
		(start 155.25242 -205.206346)
		(end 155.437586 -205.02118)
		(width 0.14478)
		(layer "In13.Cu")
		(net "M_H_CPU1_SA_DQ<3>")
	)
	(segment
		(start 152.91308 -207.545686)
		(end 153.098246 -207.36052)
		(width 0.14478)
		(layer "In13.Cu")
		(net "M_H_CPU1_SA_DQ<3>")
	)
	(segment
		(start 154.63139 -205.56982)
		(end 154.63139 -205.365096)
		(width 0.14478)
		(layer "In13.Cu")
		(net "M_H_CPU1_SA_DQ<3>")
	)
	(segment
		(start 153.69286 -206.765906)
		(end 153.878026 -206.58074)
		(width 0.14478)
		(layer "In13.Cu")
		(net "M_H_CPU1_SA_DQ<3>")
	)
	(segment
		(start 152.29205 -207.90916)
		(end 152.29205 -207.704436)
		(width 0.14478)
		(layer "In13.Cu")
		(net "M_H_CPU1_SA_DQ<3>")
	)
	(segment
		(start 143.480028 -221.418404)
		(end 143.480028 -221.235524)
		(width 0.0889)
		(layer "In13.Cu")
		(net "M_H_CPU1_SA_DQ<3>")
	)
	(segment
		(start 154.2415 -205.95971)
		(end 154.267916 -205.986126)
		(width 0.14478)
		(layer "In13.Cu")
		(net "M_H_CPU1_SA_DQ<3>")
	)
	(arc
		(start 141.23416 -225.510852)
		(mid 141.414812 -225.308107)
		(end 141.480032 -225.044508)
		(width 0.0889)
		(layer "In13.Cu")
		(net "M_H_CPU1_SA_DQ<3>")
	)
	(arc
		(start 142.172944 -223.891602)
		(mid 142.35468 -223.688787)
		(end 142.42034 -223.424496)
		(width 0.0889)
		(layer "In13.Cu")
		(net "M_H_CPU1_SA_DQ<3>")
	)
	(arc
		(start 140.161772 -226.34194)
		(mid 140.444728 -226.418117)
		(end 140.727684 -226.34194)
		(width 0.0889)
		(layer "In13.Cu")
		(net "M_H_CPU1_SA_DQ<3>")
	)
	(arc
		(start 141.706854 -224.699068)
		(mid 141.885667 -224.496718)
		(end 141.950186 -224.234502)
		(width 0.0889)
		(layer "In13.Cu")
		(net "M_H_CPU1_SA_DQ<3>")
	)
	(arc
		(start 140.7668 -226.31908)
		(mid 140.945613 -226.11673)
		(end 141.010132 -225.854514)
		(width 0.0889)
		(layer "In13.Cu")
		(net "M_H_CPU1_SA_DQ<3>")
	)
	(arc
		(start 136.976104 -226.337114)
		(mid 137.159612 -226.29162)
		(end 137.341864 -226.34194)
		(width 0.0889)
		(layer "In13.Cu")
		(net "M_H_CPU1_SA_DQ<3>")
	)
	(arc
		(start 135.087614 -226.34194)
		(mid 135.269865 -226.29159)
		(end 135.453374 -226.337114)
		(width 0.0889)
		(layer "In13.Cu")
		(net "M_H_CPU1_SA_DQ<3>")
	)
	(arc
		(start 139.78763 -226.34194)
		(mid 139.969881 -226.29159)
		(end 140.15339 -226.337114)
		(width 0.0889)
		(layer "In13.Cu")
		(net "M_H_CPU1_SA_DQ<3>")
	)
	(arc
		(start 136.027668 -226.34194)
		(mid 136.209919 -226.29159)
		(end 136.393428 -226.337114)
		(width 0.0889)
		(layer "In13.Cu")
		(net "M_H_CPU1_SA_DQ<3>")
	)
	(arc
		(start 141.010132 -225.854514)
		(mid 141.051387 -225.683543)
		(end 141.166088 -225.550222)
		(width 0.0889)
		(layer "In13.Cu")
		(net "M_H_CPU1_SA_DQ<3>")
	)
	(arc
		(start 139.221718 -226.34194)
		(mid 139.504674 -226.418117)
		(end 139.78763 -226.34194)
		(width 0.0889)
		(layer "In13.Cu")
		(net "M_H_CPU1_SA_DQ<3>")
	)
	(arc
		(start 143.11884 -222.268542)
		(mid 143.296964 -222.066252)
		(end 143.361156 -221.804484)
		(width 0.0889)
		(layer "In13.Cu")
		(net "M_H_CPU1_SA_DQ<3>")
	)
	(arc
		(start 142.42034 -223.424496)
		(mid 142.46139 -223.254046)
		(end 142.575534 -223.120966)
		(width 0.0889)
		(layer "In13.Cu")
		(net "M_H_CPU1_SA_DQ<3>")
	)
	(arc
		(start 142.890494 -222.61449)
		(mid 142.93211 -222.443001)
		(end 143.04772 -222.30969)
		(width 0.0889)
		(layer "In13.Cu")
		(net "M_H_CPU1_SA_DQ<3>")
	)
	(arc
		(start 138.84783 -226.34194)
		(mid 139.034774 -226.291685)
		(end 139.221718 -226.34194)
		(width 0.0889)
		(layer "In13.Cu")
		(net "M_H_CPU1_SA_DQ<3>")
	)
	(arc
		(start 141.950186 -224.234502)
		(mid 141.991236 -224.064052)
		(end 142.10538 -223.930972)
		(width 0.0889)
		(layer "In13.Cu")
		(net "M_H_CPU1_SA_DQ<3>")
	)
	(arc
		(start 137.341864 -226.34194)
		(mid 137.62482 -226.418117)
		(end 137.907776 -226.34194)
		(width 0.0889)
		(layer "In13.Cu")
		(net "M_H_CPU1_SA_DQ<3>")
	)
	(arc
		(start 141.480032 -225.044508)
		(mid 141.521287 -224.873537)
		(end 141.635988 -224.740216)
		(width 0.0889)
		(layer "In13.Cu")
		(net "M_H_CPU1_SA_DQ<3>")
	)
	(arc
		(start 137.916158 -226.337114)
		(mid 138.099666 -226.29162)
		(end 138.281918 -226.34194)
		(width 0.0889)
		(layer "In13.Cu")
		(net "M_H_CPU1_SA_DQ<3>")
	)
	(arc
		(start 142.641574 -223.082612)
		(mid 142.824394 -222.879584)
		(end 142.890494 -222.61449)
		(width 0.0889)
		(layer "In13.Cu")
		(net "M_H_CPU1_SA_DQ<3>")
	)
	(arc
		(start 138.281918 -226.34194)
		(mid 138.564874 -226.418117)
		(end 138.84783 -226.34194)
		(width 0.0889)
		(layer "In13.Cu")
		(net "M_H_CPU1_SA_DQ<3>")
	)
	(arc
		(start 134.584694 -226.37369)
		(mid 134.839902 -226.417167)
		(end 135.087614 -226.34194)
		(width 0.0889)
		(layer "In13.Cu")
		(net "M_H_CPU1_SA_DQ<3>")
	)
	(arc
		(start 135.461756 -226.34194)
		(mid 135.744712 -226.418117)
		(end 136.027668 -226.34194)
		(width 0.0889)
		(layer "In13.Cu")
		(net "M_H_CPU1_SA_DQ<3>")
	)
	(arc
		(start 136.40181 -226.34194)
		(mid 136.684766 -226.418117)
		(end 136.967722 -226.34194)
		(width 0.0889)
		(layer "In13.Cu")
		(net "M_H_CPU1_SA_DQ<3>")
	)
	(segment
		(start 133.867906 -244.750336)
		(end 134.334758 -244.484398)
		(width 0.10668)
		(layer "F.Cu")
		(net "M_H_CPU1_SA_DQ<31>")
	)
	(segment
		(start 157.282896 -240.872772)
		(end 157.09773 -241.057938)
		(width 0.14478)
		(layer "In13.Cu")
		(net "M_H_CPU1_SA_DQ<31>")
	)
	(segment
		(start 141.67612 -244.156992)
		(end 141.667738 -244.161818)
		(width 0.0889)
		(layer "In13.Cu")
		(net "M_H_CPU1_SA_DQ<31>")
	)
	(segment
		(start 163.131246 -234.819698)
		(end 163.040568 -234.72902)
		(width 0.14478)
		(layer "In13.Cu")
		(net "M_H_CPU1_SA_DQ<31>")
	)
	(segment
		(start 163.040568 -234.72902)
		(end 162.835844 -234.72902)
		(width 0.14478)
		(layer "In13.Cu")
		(net "M_H_CPU1_SA_DQ<31>")
	)
	(segment
		(start 160.402016 -237.548928)
		(end 160.402016 -237.753652)
		(width 0.14478)
		(layer "In13.Cu")
		(net "M_H_CPU1_SA_DQ<31>")
	)
	(segment
		(start 161.276284 -236.28858)
		(end 161.091118 -236.473746)
		(width 0.14478)
		(layer "In13.Cu")
		(net "M_H_CPU1_SA_DQ<31>")
	)
	(segment
		(start 147.92071 -243.438934)
		(end 147.631658 -243.438934)
		(width 0.0889)
		(layer "In13.Cu")
		(net "M_H_CPU1_SA_DQ<31>")
	)
	(segment
		(start 157.672786 -240.278158)
		(end 157.582108 -240.18748)
		(width 0.14478)
		(layer "In13.Cu")
		(net "M_H_CPU1_SA_DQ<31>")
	)
	(segment
		(start 158.65729 -239.498378)
		(end 158.452566 -239.498378)
		(width 0.14478)
		(layer "In13.Cu")
		(net "M_H_CPU1_SA_DQ<31>")
	)
	(segment
		(start 158.842456 -239.313212)
		(end 158.65729 -239.498378)
		(width 0.14478)
		(layer "In13.Cu")
		(net "M_H_CPU1_SA_DQ<31>")
	)
	(segment
		(start 156.893006 -241.057938)
		(end 156.802328 -240.96726)
		(width 0.14478)
		(layer "In13.Cu")
		(net "M_H_CPU1_SA_DQ<31>")
	)
	(segment
		(start 146.312128 -244.100604)
		(end 146.17446 -244.238272)
		(width 0.0889)
		(layer "In13.Cu")
		(net "M_H_CPU1_SA_DQ<31>")
	)
	(segment
		(start 158.452566 -239.498378)
		(end 158.361888 -239.4077)
		(width 0.14478)
		(layer "In13.Cu")
		(net "M_H_CPU1_SA_DQ<31>")
	)
	(segment
		(start 159.531558 -238.23803)
		(end 159.622236 -238.328708)
		(width 0.14478)
		(layer "In13.Cu")
		(net "M_H_CPU1_SA_DQ<31>")
	)
	(segment
		(start 170.611038 -234.310682)
		(end 169.7609 -233.460544)
		(width 0.14478)
		(layer "In13.Cu")
		(net "M_H_CPU1_SA_DQ<31>")
	)
	(segment
		(start 159.43707 -238.718598)
		(end 159.232346 -238.718598)
		(width 0.14478)
		(layer "In13.Cu")
		(net "M_H_CPU1_SA_DQ<31>")
	)
	(segment
		(start 160.99663 -237.159038)
		(end 160.791906 -237.159038)
		(width 0.14478)
		(layer "In13.Cu")
		(net "M_H_CPU1_SA_DQ<31>")
	)
	(segment
		(start 163.844986 -234.310682)
		(end 163.33597 -234.819698)
		(width 0.14478)
		(layer "In13.Cu")
		(net "M_H_CPU1_SA_DQ<31>")
	)
	(segment
		(start 161.181796 -236.973872)
		(end 160.99663 -237.159038)
		(width 0.14478)
		(layer "In13.Cu")
		(net "M_H_CPU1_SA_DQ<31>")
	)
	(segment
		(start 166.569136 -234.310682)
		(end 163.844986 -234.310682)
		(width 0.14478)
		(layer "In13.Cu")
		(net "M_H_CPU1_SA_DQ<31>")
	)
	(segment
		(start 156.503116 -241.652552)
		(end 154.716734 -243.438934)
		(width 0.14478)
		(layer "In13.Cu")
		(net "M_H_CPU1_SA_DQ<31>")
	)
	(segment
		(start 160.012126 -237.938818)
		(end 159.921448 -237.84814)
		(width 0.14478)
		(layer "In13.Cu")
		(net "M_H_CPU1_SA_DQ<31>")
	)
	(segment
		(start 157.282896 -240.668048)
		(end 157.282896 -240.872772)
		(width 0.14478)
		(layer "In13.Cu")
		(net "M_H_CPU1_SA_DQ<31>")
	)
	(segment
		(start 160.311338 -237.45825)
		(end 160.402016 -237.548928)
		(width 0.14478)
		(layer "In13.Cu")
		(net "M_H_CPU1_SA_DQ<31>")
	)
	(segment
		(start 158.751778 -239.01781)
		(end 158.842456 -239.108488)
		(width 0.14478)
		(layer "In13.Cu")
		(net "M_H_CPU1_SA_DQ<31>")
	)
	(segment
		(start 160.496504 -237.06836)
		(end 160.311338 -237.253526)
		(width 0.14478)
		(layer "In13.Cu")
		(net "M_H_CPU1_SA_DQ<31>")
	)
	(segment
		(start 158.062676 -239.888268)
		(end 158.062676 -240.092992)
		(width 0.14478)
		(layer "In13.Cu")
		(net "M_H_CPU1_SA_DQ<31>")
	)
	(segment
		(start 156.597604 -240.96726)
		(end 156.412438 -241.152426)
		(width 0.14478)
		(layer "In13.Cu")
		(net "M_H_CPU1_SA_DQ<31>")
	)
	(segment
		(start 135.461756 -244.161818)
		(end 135.453374 -244.156992)
		(width 0.0889)
		(layer "In13.Cu")
		(net "M_H_CPU1_SA_DQ<31>")
	)
	(segment
		(start 157.192218 -240.57737)
		(end 157.282896 -240.668048)
		(width 0.14478)
		(layer "In13.Cu")
		(net "M_H_CPU1_SA_DQ<31>")
	)
	(segment
		(start 136.976104 -244.156992)
		(end 136.967722 -244.161818)
		(width 0.0889)
		(layer "In13.Cu")
		(net "M_H_CPU1_SA_DQ<31>")
	)
	(segment
		(start 158.842456 -239.108488)
		(end 158.842456 -239.313212)
		(width 0.14478)
		(layer "In13.Cu")
		(net "M_H_CPU1_SA_DQ<31>")
	)
	(segment
		(start 167.419274 -233.460544)
		(end 166.569136 -234.310682)
		(width 0.14478)
		(layer "In13.Cu")
		(net "M_H_CPU1_SA_DQ<31>")
	)
	(segment
		(start 161.091118 -236.473746)
		(end 161.091118 -236.67847)
		(width 0.14478)
		(layer "In13.Cu")
		(net "M_H_CPU1_SA_DQ<31>")
	)
	(segment
		(start 171.97197 -233.885232)
		(end 171.54652 -234.310682)
		(width 0.14478)
		(layer "In13.Cu")
		(net "M_H_CPU1_SA_DQ<31>")
	)
	(segment
		(start 157.971998 -239.592866)
		(end 157.971998 -239.79759)
		(width 0.14478)
		(layer "In13.Cu")
		(net "M_H_CPU1_SA_DQ<31>")
	)
	(segment
		(start 162.351466 -235.599478)
		(end 162.260788 -235.5088)
		(width 0.14478)
		(layer "In13.Cu")
		(net "M_H_CPU1_SA_DQ<31>")
	)
	(segment
		(start 161.870898 -235.89869)
		(end 161.961576 -235.989368)
		(width 0.14478)
		(layer "In13.Cu")
		(net "M_H_CPU1_SA_DQ<31>")
	)
	(segment
		(start 171.54652 -234.310682)
		(end 170.611038 -234.310682)
		(width 0.14478)
		(layer "In13.Cu")
		(net "M_H_CPU1_SA_DQ<31>")
	)
	(segment
		(start 140.161772 -244.161818)
		(end 140.15339 -244.156992)
		(width 0.0889)
		(layer "In13.Cu")
		(net "M_H_CPU1_SA_DQ<31>")
	)
	(segment
		(start 162.056064 -235.5088)
		(end 161.870898 -235.693966)
		(width 0.14478)
		(layer "In13.Cu")
		(net "M_H_CPU1_SA_DQ<31>")
	)
	(segment
		(start 156.412438 -241.152426)
		(end 156.412438 -241.35715)
		(width 0.14478)
		(layer "In13.Cu")
		(net "M_H_CPU1_SA_DQ<31>")
	)
	(segment
		(start 159.716724 -237.84814)
		(end 159.531558 -238.033306)
		(width 0.14478)
		(layer "In13.Cu")
		(net "M_H_CPU1_SA_DQ<31>")
	)
	(segment
		(start 162.741356 -235.414312)
		(end 162.55619 -235.599478)
		(width 0.14478)
		(layer "In13.Cu")
		(net "M_H_CPU1_SA_DQ<31>")
	)
	(segment
		(start 134.584694 -244.193568)
		(end 134.488682 -244.218968)
		(width 0.0889)
		(layer "In13.Cu")
		(net "M_H_CPU1_SA_DQ<31>")
	)
	(segment
		(start 156.412438 -241.35715)
		(end 156.503116 -241.447828)
		(width 0.14478)
		(layer "In13.Cu")
		(net "M_H_CPU1_SA_DQ<31>")
	)
	(segment
		(start 147.631658 -243.438934)
		(end 146.969988 -244.100604)
		(width 0.0889)
		(layer "In13.Cu")
		(net "M_H_CPU1_SA_DQ<31>")
	)
	(segment
		(start 159.622236 -238.328708)
		(end 159.622236 -238.533432)
		(width 0.14478)
		(layer "In13.Cu")
		(net "M_H_CPU1_SA_DQ<31>")
	)
	(segment
		(start 156.802328 -240.96726)
		(end 156.597604 -240.96726)
		(width 0.14478)
		(layer "In13.Cu")
		(net "M_H_CPU1_SA_DQ<31>")
	)
	(segment
		(start 154.716734 -243.438934)
		(end 147.92071 -243.438934)
		(width 0.14478)
		(layer "In13.Cu")
		(net "M_H_CPU1_SA_DQ<31>")
	)
	(segment
		(start 160.701228 -237.06836)
		(end 160.496504 -237.06836)
		(width 0.14478)
		(layer "In13.Cu")
		(net "M_H_CPU1_SA_DQ<31>")
	)
	(segment
		(start 158.157164 -239.4077)
		(end 157.971998 -239.592866)
		(width 0.14478)
		(layer "In13.Cu")
		(net "M_H_CPU1_SA_DQ<31>")
	)
	(segment
		(start 161.961576 -236.194092)
		(end 161.77641 -236.379258)
		(width 0.14478)
		(layer "In13.Cu")
		(net "M_H_CPU1_SA_DQ<31>")
	)
	(segment
		(start 158.936944 -238.62792)
		(end 158.751778 -238.813086)
		(width 0.14478)
		(layer "In13.Cu")
		(net "M_H_CPU1_SA_DQ<31>")
	)
	(segment
		(start 162.260788 -235.5088)
		(end 162.056064 -235.5088)
		(width 0.14478)
		(layer "In13.Cu")
		(net "M_H_CPU1_SA_DQ<31>")
	)
	(segment
		(start 144.488662 -244.161818)
		(end 144.47393 -244.170454)
		(width 0.0889)
		(layer "In13.Cu")
		(net "M_H_CPU1_SA_DQ<31>")
	)
	(segment
		(start 134.488682 -244.218968)
		(end 134.334758 -244.484398)
		(width 0.0889)
		(layer "In13.Cu")
		(net "M_H_CPU1_SA_DQ<31>")
	)
	(segment
		(start 162.650678 -234.914186)
		(end 162.650678 -235.11891)
		(width 0.14478)
		(layer "In13.Cu")
		(net "M_H_CPU1_SA_DQ<31>")
	)
	(segment
		(start 163.33597 -234.819698)
		(end 163.131246 -234.819698)
		(width 0.14478)
		(layer "In13.Cu")
		(net "M_H_CPU1_SA_DQ<31>")
	)
	(segment
		(start 159.531558 -238.033306)
		(end 159.531558 -238.23803)
		(width 0.14478)
		(layer "In13.Cu")
		(net "M_H_CPU1_SA_DQ<31>")
	)
	(segment
		(start 169.7609 -233.460544)
		(end 167.419274 -233.460544)
		(width 0.14478)
		(layer "In13.Cu")
		(net "M_H_CPU1_SA_DQ<31>")
	)
	(segment
		(start 162.835844 -234.72902)
		(end 162.650678 -234.914186)
		(width 0.14478)
		(layer "In13.Cu")
		(net "M_H_CPU1_SA_DQ<31>")
	)
	(segment
		(start 157.87751 -240.278158)
		(end 157.672786 -240.278158)
		(width 0.14478)
		(layer "In13.Cu")
		(net "M_H_CPU1_SA_DQ<31>")
	)
	(segment
		(start 157.377384 -240.18748)
		(end 157.192218 -240.372646)
		(width 0.14478)
		(layer "In13.Cu")
		(net "M_H_CPU1_SA_DQ<31>")
	)
	(segment
		(start 162.650678 -235.11891)
		(end 162.741356 -235.209588)
		(width 0.14478)
		(layer "In13.Cu")
		(net "M_H_CPU1_SA_DQ<31>")
	)
	(segment
		(start 141.101826 -244.161818)
		(end 141.093444 -244.156992)
		(width 0.0889)
		(layer "In13.Cu")
		(net "M_H_CPU1_SA_DQ<31>")
	)
	(segment
		(start 158.062676 -240.092992)
		(end 157.87751 -240.278158)
		(width 0.14478)
		(layer "In13.Cu")
		(net "M_H_CPU1_SA_DQ<31>")
	)
	(segment
		(start 159.921448 -237.84814)
		(end 159.716724 -237.84814)
		(width 0.14478)
		(layer "In13.Cu")
		(net "M_H_CPU1_SA_DQ<31>")
	)
	(segment
		(start 146.17446 -244.238272)
		(end 145.144744 -244.238272)
		(width 0.0889)
		(layer "In13.Cu")
		(net "M_H_CPU1_SA_DQ<31>")
	)
	(segment
		(start 136.40181 -244.161818)
		(end 136.393428 -244.156992)
		(width 0.0889)
		(layer "In13.Cu")
		(net "M_H_CPU1_SA_DQ<31>")
	)
	(segment
		(start 162.55619 -235.599478)
		(end 162.351466 -235.599478)
		(width 0.14478)
		(layer "In13.Cu")
		(net "M_H_CPU1_SA_DQ<31>")
	)
	(segment
		(start 157.971998 -239.79759)
		(end 158.062676 -239.888268)
		(width 0.14478)
		(layer "In13.Cu")
		(net "M_H_CPU1_SA_DQ<31>")
	)
	(segment
		(start 160.402016 -237.753652)
		(end 160.21685 -237.938818)
		(width 0.14478)
		(layer "In13.Cu")
		(net "M_H_CPU1_SA_DQ<31>")
	)
	(segment
		(start 158.751778 -238.813086)
		(end 158.751778 -239.01781)
		(width 0.14478)
		(layer "In13.Cu")
		(net "M_H_CPU1_SA_DQ<31>")
	)
	(segment
		(start 161.181796 -236.769148)
		(end 161.181796 -236.973872)
		(width 0.14478)
		(layer "In13.Cu")
		(net "M_H_CPU1_SA_DQ<31>")
	)
	(segment
		(start 143.555974 -244.156992)
		(end 143.547592 -244.161818)
		(width 0.0889)
		(layer "In13.Cu")
		(net "M_H_CPU1_SA_DQ<31>")
	)
	(segment
		(start 160.791906 -237.159038)
		(end 160.701228 -237.06836)
		(width 0.14478)
		(layer "In13.Cu")
		(net "M_H_CPU1_SA_DQ<31>")
	)
	(segment
		(start 159.232346 -238.718598)
		(end 159.141668 -238.62792)
		(width 0.14478)
		(layer "In13.Cu")
		(net "M_H_CPU1_SA_DQ<31>")
	)
	(segment
		(start 161.961576 -235.989368)
		(end 161.961576 -236.194092)
		(width 0.14478)
		(layer "In13.Cu")
		(net "M_H_CPU1_SA_DQ<31>")
	)
	(segment
		(start 162.741356 -235.209588)
		(end 162.741356 -235.414312)
		(width 0.14478)
		(layer "In13.Cu")
		(net "M_H_CPU1_SA_DQ<31>")
	)
	(segment
		(start 159.141668 -238.62792)
		(end 158.936944 -238.62792)
		(width 0.14478)
		(layer "In13.Cu")
		(net "M_H_CPU1_SA_DQ<31>")
	)
	(segment
		(start 161.481008 -236.28858)
		(end 161.276284 -236.28858)
		(width 0.14478)
		(layer "In13.Cu")
		(net "M_H_CPU1_SA_DQ<31>")
	)
	(segment
		(start 159.622236 -238.533432)
		(end 159.43707 -238.718598)
		(width 0.14478)
		(layer "In13.Cu")
		(net "M_H_CPU1_SA_DQ<31>")
	)
	(segment
		(start 160.311338 -237.253526)
		(end 160.311338 -237.45825)
		(width 0.14478)
		(layer "In13.Cu")
		(net "M_H_CPU1_SA_DQ<31>")
	)
	(segment
		(start 158.361888 -239.4077)
		(end 158.157164 -239.4077)
		(width 0.14478)
		(layer "In13.Cu")
		(net "M_H_CPU1_SA_DQ<31>")
	)
	(segment
		(start 137.916158 -244.156992)
		(end 137.907776 -244.161818)
		(width 0.0889)
		(layer "In13.Cu")
		(net "M_H_CPU1_SA_DQ<31>")
	)
	(segment
		(start 156.503116 -241.447828)
		(end 156.503116 -241.652552)
		(width 0.14478)
		(layer "In13.Cu")
		(net "M_H_CPU1_SA_DQ<31>")
	)
	(segment
		(start 157.582108 -240.18748)
		(end 157.377384 -240.18748)
		(width 0.14478)
		(layer "In13.Cu")
		(net "M_H_CPU1_SA_DQ<31>")
	)
	(segment
		(start 161.571686 -236.379258)
		(end 161.481008 -236.28858)
		(width 0.14478)
		(layer "In13.Cu")
		(net "M_H_CPU1_SA_DQ<31>")
	)
	(segment
		(start 161.091118 -236.67847)
		(end 161.181796 -236.769148)
		(width 0.14478)
		(layer "In13.Cu")
		(net "M_H_CPU1_SA_DQ<31>")
	)
	(segment
		(start 146.969988 -244.100604)
		(end 146.312128 -244.100604)
		(width 0.0889)
		(layer "In13.Cu")
		(net "M_H_CPU1_SA_DQ<31>")
	)
	(segment
		(start 161.870898 -235.693966)
		(end 161.870898 -235.89869)
		(width 0.14478)
		(layer "In13.Cu")
		(net "M_H_CPU1_SA_DQ<31>")
	)
	(segment
		(start 157.192218 -240.372646)
		(end 157.192218 -240.57737)
		(width 0.14478)
		(layer "In13.Cu")
		(net "M_H_CPU1_SA_DQ<31>")
	)
	(segment
		(start 157.09773 -241.057938)
		(end 156.893006 -241.057938)
		(width 0.14478)
		(layer "In13.Cu")
		(net "M_H_CPU1_SA_DQ<31>")
	)
	(segment
		(start 160.21685 -237.938818)
		(end 160.012126 -237.938818)
		(width 0.14478)
		(layer "In13.Cu")
		(net "M_H_CPU1_SA_DQ<31>")
	)
	(segment
		(start 161.77641 -236.379258)
		(end 161.571686 -236.379258)
		(width 0.14478)
		(layer "In13.Cu")
		(net "M_H_CPU1_SA_DQ<31>")
	)
	(arc
		(start 143.922242 -244.161818)
		(mid 143.739737 -244.111341)
		(end 143.555974 -244.156992)
		(width 0.0889)
		(layer "In13.Cu")
		(net "M_H_CPU1_SA_DQ<31>")
	)
	(arc
		(start 142.98168 -244.161818)
		(mid 142.794736 -244.111563)
		(end 142.607792 -244.161818)
		(width 0.0889)
		(layer "In13.Cu")
		(net "M_H_CPU1_SA_DQ<31>")
	)
	(arc
		(start 135.453374 -244.156992)
		(mid 135.269866 -244.111498)
		(end 135.087614 -244.161818)
		(width 0.0889)
		(layer "In13.Cu")
		(net "M_H_CPU1_SA_DQ<31>")
	)
	(arc
		(start 144.47393 -244.170454)
		(mid 144.196947 -244.238258)
		(end 143.922242 -244.161818)
		(width 0.0889)
		(layer "In13.Cu")
		(net "M_H_CPU1_SA_DQ<31>")
	)
	(arc
		(start 136.393428 -244.156992)
		(mid 136.20992 -244.111498)
		(end 136.027668 -244.161818)
		(width 0.0889)
		(layer "In13.Cu")
		(net "M_H_CPU1_SA_DQ<31>")
	)
	(arc
		(start 138.84783 -244.161818)
		(mid 138.564874 -244.237995)
		(end 138.281918 -244.161818)
		(width 0.0889)
		(layer "In13.Cu")
		(net "M_H_CPU1_SA_DQ<31>")
	)
	(arc
		(start 145.144744 -244.238272)
		(mid 144.990812 -244.216845)
		(end 144.84858 -244.154198)
		(width 0.0889)
		(layer "In13.Cu")
		(net "M_H_CPU1_SA_DQ<31>")
	)
	(arc
		(start 137.907776 -244.161818)
		(mid 137.62482 -244.237995)
		(end 137.341864 -244.161818)
		(width 0.0889)
		(layer "In13.Cu")
		(net "M_H_CPU1_SA_DQ<31>")
	)
	(arc
		(start 137.341864 -244.161818)
		(mid 137.159613 -244.111468)
		(end 136.976104 -244.156992)
		(width 0.0889)
		(layer "In13.Cu")
		(net "M_H_CPU1_SA_DQ<31>")
	)
	(arc
		(start 139.221718 -244.161818)
		(mid 139.034774 -244.111563)
		(end 138.84783 -244.161818)
		(width 0.0889)
		(layer "In13.Cu")
		(net "M_H_CPU1_SA_DQ<31>")
	)
	(arc
		(start 144.84858 -244.154198)
		(mid 144.66765 -244.11172)
		(end 144.488662 -244.161818)
		(width 0.0889)
		(layer "In13.Cu")
		(net "M_H_CPU1_SA_DQ<31>")
	)
	(arc
		(start 141.667738 -244.161818)
		(mid 141.384782 -244.237995)
		(end 141.101826 -244.161818)
		(width 0.0889)
		(layer "In13.Cu")
		(net "M_H_CPU1_SA_DQ<31>")
	)
	(arc
		(start 140.15339 -244.156992)
		(mid 139.969882 -244.111498)
		(end 139.78763 -244.161818)
		(width 0.0889)
		(layer "In13.Cu")
		(net "M_H_CPU1_SA_DQ<31>")
	)
	(arc
		(start 138.281918 -244.161818)
		(mid 138.099667 -244.111468)
		(end 137.916158 -244.156992)
		(width 0.0889)
		(layer "In13.Cu")
		(net "M_H_CPU1_SA_DQ<31>")
	)
	(arc
		(start 136.967722 -244.161818)
		(mid 136.684766 -244.237995)
		(end 136.40181 -244.161818)
		(width 0.0889)
		(layer "In13.Cu")
		(net "M_H_CPU1_SA_DQ<31>")
	)
	(arc
		(start 136.027668 -244.161818)
		(mid 135.744712 -244.237995)
		(end 135.461756 -244.161818)
		(width 0.0889)
		(layer "In13.Cu")
		(net "M_H_CPU1_SA_DQ<31>")
	)
	(arc
		(start 135.087614 -244.161818)
		(mid 134.839901 -244.237038)
		(end 134.584694 -244.193568)
		(width 0.0889)
		(layer "In13.Cu")
		(net "M_H_CPU1_SA_DQ<31>")
	)
	(arc
		(start 141.093444 -244.156992)
		(mid 140.909936 -244.111498)
		(end 140.727684 -244.161818)
		(width 0.0889)
		(layer "In13.Cu")
		(net "M_H_CPU1_SA_DQ<31>")
	)
	(arc
		(start 139.78763 -244.161818)
		(mid 139.504674 -244.237995)
		(end 139.221718 -244.161818)
		(width 0.0889)
		(layer "In13.Cu")
		(net "M_H_CPU1_SA_DQ<31>")
	)
	(arc
		(start 142.04188 -244.161818)
		(mid 141.859629 -244.111468)
		(end 141.67612 -244.156992)
		(width 0.0889)
		(layer "In13.Cu")
		(net "M_H_CPU1_SA_DQ<31>")
	)
	(arc
		(start 140.727684 -244.161818)
		(mid 140.444728 -244.237995)
		(end 140.161772 -244.161818)
		(width 0.0889)
		(layer "In13.Cu")
		(net "M_H_CPU1_SA_DQ<31>")
	)
	(arc
		(start 142.607792 -244.161818)
		(mid 142.324836 -244.237995)
		(end 142.04188 -244.161818)
		(width 0.0889)
		(layer "In13.Cu")
		(net "M_H_CPU1_SA_DQ<31>")
	)
	(arc
		(start 143.547592 -244.161818)
		(mid 143.264636 -244.237995)
		(end 142.98168 -244.161818)
		(width 0.0889)
		(layer "In13.Cu")
		(net "M_H_CPU1_SA_DQ<31>")
	)
	(segment
		(start 135.27786 -243.94033)
		(end 135.744712 -243.674392)
		(width 0.10668)
		(layer "F.Cu")
		(net "M_H_CPU1_SA_DQ<30>")
	)
	(segment
		(start 154.89809 -240.558066)
		(end 155.102814 -240.558066)
		(width 0.14478)
		(layer "In13.Cu")
		(net "M_H_CPU1_SA_DQ<30>")
	)
	(segment
		(start 170.43908 -232.61066)
		(end 171.54652 -232.61066)
		(width 0.14478)
		(layer "In13.Cu")
		(net "M_H_CPU1_SA_DQ<30>")
	)
	(segment
		(start 155.521152 -240.77168)
		(end 155.706318 -240.586514)
		(width 0.14478)
		(layer "In13.Cu")
		(net "M_H_CPU1_SA_DQ<30>")
	)
	(segment
		(start 155.102814 -240.558066)
		(end 155.316428 -240.77168)
		(width 0.14478)
		(layer "In13.Cu")
		(net "M_H_CPU1_SA_DQ<30>")
	)
	(segment
		(start 157.080712 -239.21212)
		(end 157.265878 -239.026954)
		(width 0.14478)
		(layer "In13.Cu")
		(net "M_H_CPU1_SA_DQ<30>")
	)
	(segment
		(start 146.886168 -243.493544)
		(end 147.226528 -243.153184)
		(width 0.0889)
		(layer "In13.Cu")
		(net "M_H_CPU1_SA_DQ<30>")
	)
	(segment
		(start 153.933144 -241.523012)
		(end 154.11831 -241.337846)
		(width 0.14478)
		(layer "In13.Cu")
		(net "M_H_CPU1_SA_DQ<30>")
	)
	(segment
		(start 155.316428 -240.77168)
		(end 155.521152 -240.77168)
		(width 0.14478)
		(layer "In13.Cu")
		(net "M_H_CPU1_SA_DQ<30>")
	)
	(segment
		(start 155.492704 -239.963452)
		(end 155.67787 -239.778286)
		(width 0.14478)
		(layer "In13.Cu")
		(net "M_H_CPU1_SA_DQ<30>")
	)
	(segment
		(start 157.860492 -238.43234)
		(end 158.045658 -238.247174)
		(width 0.14478)
		(layer "In13.Cu")
		(net "M_H_CPU1_SA_DQ<30>")
	)
	(segment
		(start 154.146758 -242.146074)
		(end 154.146758 -241.94135)
		(width 0.14478)
		(layer "In13.Cu")
		(net "M_H_CPU1_SA_DQ<30>")
	)
	(segment
		(start 145.144744 -243.301012)
		(end 146.21256 -243.301012)
		(width 0.0889)
		(layer "In13.Cu")
		(net "M_H_CPU1_SA_DQ<30>")
	)
	(segment
		(start 157.052264 -238.403892)
		(end 157.23743 -238.218726)
		(width 0.14478)
		(layer "In13.Cu")
		(net "M_H_CPU1_SA_DQ<30>")
	)
	(segment
		(start 154.926538 -241.16157)
		(end 154.712924 -240.947956)
		(width 0.14478)
		(layer "In13.Cu")
		(net "M_H_CPU1_SA_DQ<30>")
	)
	(segment
		(start 156.300932 -239.9919)
		(end 156.486098 -239.806734)
		(width 0.14478)
		(layer "In13.Cu")
		(net "M_H_CPU1_SA_DQ<30>")
	)
	(segment
		(start 154.323034 -241.337846)
		(end 154.536648 -241.55146)
		(width 0.14478)
		(layer "In13.Cu")
		(net "M_H_CPU1_SA_DQ<30>")
	)
	(segment
		(start 142.503398 -243.346986)
		(end 142.51178 -243.351812)
		(width 0.0889)
		(layer "In13.Cu")
		(net "M_H_CPU1_SA_DQ<30>")
	)
	(segment
		(start 147.595082 -242.524534)
		(end 147.95627 -242.524534)
		(width 0.0889)
		(layer "In13.Cu")
		(net "M_H_CPU1_SA_DQ<30>")
	)
	(segment
		(start 154.741372 -241.55146)
		(end 154.926538 -241.366294)
		(width 0.14478)
		(layer "In13.Cu")
		(net "M_H_CPU1_SA_DQ<30>")
	)
	(segment
		(start 169.588942 -231.760522)
		(end 170.43908 -232.61066)
		(width 0.14478)
		(layer "In13.Cu")
		(net "M_H_CPU1_SA_DQ<30>")
	)
	(segment
		(start 158.221934 -237.438946)
		(end 158.435548 -237.65256)
		(width 0.14478)
		(layer "In13.Cu")
		(net "M_H_CPU1_SA_DQ<30>")
	)
	(segment
		(start 155.706318 -240.38179)
		(end 155.492704 -240.168176)
		(width 0.14478)
		(layer "In13.Cu")
		(net "M_H_CPU1_SA_DQ<30>")
	)
	(segment
		(start 158.640272 -237.65256)
		(end 163.682172 -232.61066)
		(width 0.14478)
		(layer "In13.Cu")
		(net "M_H_CPU1_SA_DQ<30>")
	)
	(segment
		(start 156.272484 -239.183672)
		(end 156.45765 -238.998506)
		(width 0.14478)
		(layer "In13.Cu")
		(net "M_H_CPU1_SA_DQ<30>")
	)
	(segment
		(start 156.272484 -239.388396)
		(end 156.272484 -239.183672)
		(width 0.14478)
		(layer "In13.Cu")
		(net "M_H_CPU1_SA_DQ<30>")
	)
	(segment
		(start 156.45765 -238.998506)
		(end 156.662374 -238.998506)
		(width 0.14478)
		(layer "In13.Cu")
		(net "M_H_CPU1_SA_DQ<30>")
	)
	(segment
		(start 158.01721 -237.438946)
		(end 158.221934 -237.438946)
		(width 0.14478)
		(layer "In13.Cu")
		(net "M_H_CPU1_SA_DQ<30>")
	)
	(segment
		(start 146.405092 -243.493544)
		(end 146.886168 -243.493544)
		(width 0.0889)
		(layer "In13.Cu")
		(net "M_H_CPU1_SA_DQ<30>")
	)
	(segment
		(start 144.384268 -243.346986)
		(end 144.39265 -243.351812)
		(width 0.0889)
		(layer "In13.Cu")
		(net "M_H_CPU1_SA_DQ<30>")
	)
	(segment
		(start 157.052264 -238.608616)
		(end 157.052264 -238.403892)
		(width 0.14478)
		(layer "In13.Cu")
		(net "M_H_CPU1_SA_DQ<30>")
	)
	(segment
		(start 146.21256 -243.301012)
		(end 146.405092 -243.493544)
		(width 0.0889)
		(layer "In13.Cu")
		(net "M_H_CPU1_SA_DQ<30>")
	)
	(segment
		(start 139.31773 -243.351812)
		(end 139.326112 -243.346986)
		(width 0.0889)
		(layer "In13.Cu")
		(net "M_H_CPU1_SA_DQ<30>")
	)
	(segment
		(start 157.832044 -237.828836)
		(end 157.832044 -237.624112)
		(width 0.14478)
		(layer "In13.Cu")
		(net "M_H_CPU1_SA_DQ<30>")
	)
	(segment
		(start 156.486098 -239.60201)
		(end 156.272484 -239.388396)
		(width 0.14478)
		(layer "In13.Cu")
		(net "M_H_CPU1_SA_DQ<30>")
	)
	(segment
		(start 153.768298 -242.524534)
		(end 154.146758 -242.146074)
		(width 0.14478)
		(layer "In13.Cu")
		(net "M_H_CPU1_SA_DQ<30>")
	)
	(segment
		(start 138.743436 -243.346986)
		(end 138.751818 -243.351812)
		(width 0.0889)
		(layer "In13.Cu")
		(net "M_H_CPU1_SA_DQ<30>")
	)
	(segment
		(start 167.832532 -231.760522)
		(end 169.588942 -231.760522)
		(width 0.14478)
		(layer "In13.Cu")
		(net "M_H_CPU1_SA_DQ<30>")
	)
	(segment
		(start 135.89889 -243.408962)
		(end 135.995156 -243.383562)
		(width 0.0889)
		(layer "In13.Cu")
		(net "M_H_CPU1_SA_DQ<30>")
	)
	(segment
		(start 155.882594 -239.778286)
		(end 156.096208 -239.9919)
		(width 0.14478)
		(layer "In13.Cu")
		(net "M_H_CPU1_SA_DQ<30>")
	)
	(segment
		(start 155.706318 -240.586514)
		(end 155.706318 -240.38179)
		(width 0.14478)
		(layer "In13.Cu")
		(net "M_H_CPU1_SA_DQ<30>")
	)
	(segment
		(start 137.803382 -243.346986)
		(end 137.811764 -243.351812)
		(width 0.0889)
		(layer "In13.Cu")
		(net "M_H_CPU1_SA_DQ<30>")
	)
	(segment
		(start 143.451834 -243.351812)
		(end 143.462248 -243.357908)
		(width 0.0889)
		(layer "In13.Cu")
		(net "M_H_CPU1_SA_DQ<30>")
	)
	(segment
		(start 154.712924 -240.743232)
		(end 154.89809 -240.558066)
		(width 0.14478)
		(layer "In13.Cu")
		(net "M_H_CPU1_SA_DQ<30>")
	)
	(segment
		(start 147.95627 -242.524534)
		(end 153.768298 -242.524534)
		(width 0.14478)
		(layer "In13.Cu")
		(net "M_H_CPU1_SA_DQ<30>")
	)
	(segment
		(start 166.982394 -232.61066)
		(end 167.832532 -231.760522)
		(width 0.14478)
		(layer "In13.Cu")
		(net "M_H_CPU1_SA_DQ<30>")
	)
	(segment
		(start 156.486098 -239.806734)
		(end 156.486098 -239.60201)
		(width 0.14478)
		(layer "In13.Cu")
		(net "M_H_CPU1_SA_DQ<30>")
	)
	(segment
		(start 147.226528 -242.893088)
		(end 147.595082 -242.524534)
		(width 0.0889)
		(layer "In13.Cu")
		(net "M_H_CPU1_SA_DQ<30>")
	)
	(segment
		(start 143.077692 -243.351812)
		(end 143.086074 -243.346986)
		(width 0.0889)
		(layer "In13.Cu")
		(net "M_H_CPU1_SA_DQ<30>")
	)
	(segment
		(start 157.832044 -237.624112)
		(end 158.01721 -237.438946)
		(width 0.14478)
		(layer "In13.Cu")
		(net "M_H_CPU1_SA_DQ<30>")
	)
	(segment
		(start 157.265878 -239.026954)
		(end 157.265878 -238.82223)
		(width 0.14478)
		(layer "In13.Cu")
		(net "M_H_CPU1_SA_DQ<30>")
	)
	(segment
		(start 155.67787 -239.778286)
		(end 155.882594 -239.778286)
		(width 0.14478)
		(layer "In13.Cu")
		(net "M_H_CPU1_SA_DQ<30>")
	)
	(segment
		(start 157.655768 -238.43234)
		(end 157.860492 -238.43234)
		(width 0.14478)
		(layer "In13.Cu")
		(net "M_H_CPU1_SA_DQ<30>")
	)
	(segment
		(start 156.662374 -238.998506)
		(end 156.875988 -239.21212)
		(width 0.14478)
		(layer "In13.Cu")
		(net "M_H_CPU1_SA_DQ<30>")
	)
	(segment
		(start 154.712924 -240.947956)
		(end 154.712924 -240.743232)
		(width 0.14478)
		(layer "In13.Cu")
		(net "M_H_CPU1_SA_DQ<30>")
	)
	(segment
		(start 157.23743 -238.218726)
		(end 157.442154 -238.218726)
		(width 0.14478)
		(layer "In13.Cu")
		(net "M_H_CPU1_SA_DQ<30>")
	)
	(segment
		(start 154.926538 -241.366294)
		(end 154.926538 -241.16157)
		(width 0.14478)
		(layer "In13.Cu")
		(net "M_H_CPU1_SA_DQ<30>")
	)
	(segment
		(start 147.226528 -243.153184)
		(end 147.226528 -242.893088)
		(width 0.0889)
		(layer "In13.Cu")
		(net "M_H_CPU1_SA_DQ<30>")
	)
	(segment
		(start 158.435548 -237.65256)
		(end 158.640272 -237.65256)
		(width 0.14478)
		(layer "In13.Cu")
		(net "M_H_CPU1_SA_DQ<30>")
	)
	(segment
		(start 157.442154 -238.218726)
		(end 157.655768 -238.43234)
		(width 0.14478)
		(layer "In13.Cu")
		(net "M_H_CPU1_SA_DQ<30>")
	)
	(segment
		(start 155.492704 -240.168176)
		(end 155.492704 -239.963452)
		(width 0.14478)
		(layer "In13.Cu")
		(net "M_H_CPU1_SA_DQ<30>")
	)
	(segment
		(start 171.54652 -232.61066)
		(end 171.97197 -232.18521)
		(width 0.14478)
		(layer "In13.Cu")
		(net "M_H_CPU1_SA_DQ<30>")
	)
	(segment
		(start 158.045658 -238.04245)
		(end 157.832044 -237.828836)
		(width 0.14478)
		(layer "In13.Cu")
		(net "M_H_CPU1_SA_DQ<30>")
	)
	(segment
		(start 156.096208 -239.9919)
		(end 156.300932 -239.9919)
		(width 0.14478)
		(layer "In13.Cu")
		(net "M_H_CPU1_SA_DQ<30>")
	)
	(segment
		(start 157.265878 -238.82223)
		(end 157.052264 -238.608616)
		(width 0.14478)
		(layer "In13.Cu")
		(net "M_H_CPU1_SA_DQ<30>")
	)
	(segment
		(start 140.257784 -243.351812)
		(end 140.266166 -243.346986)
		(width 0.0889)
		(layer "In13.Cu")
		(net "M_H_CPU1_SA_DQ<30>")
	)
	(segment
		(start 156.875988 -239.21212)
		(end 157.080712 -239.21212)
		(width 0.14478)
		(layer "In13.Cu")
		(net "M_H_CPU1_SA_DQ<30>")
	)
	(segment
		(start 163.682172 -232.61066)
		(end 166.982394 -232.61066)
		(width 0.14478)
		(layer "In13.Cu")
		(net "M_H_CPU1_SA_DQ<30>")
	)
	(segment
		(start 135.744712 -243.674392)
		(end 135.89889 -243.408962)
		(width 0.0889)
		(layer "In13.Cu")
		(net "M_H_CPU1_SA_DQ<30>")
	)
	(segment
		(start 158.045658 -238.247174)
		(end 158.045658 -238.04245)
		(width 0.14478)
		(layer "In13.Cu")
		(net "M_H_CPU1_SA_DQ<30>")
	)
	(segment
		(start 154.146758 -241.94135)
		(end 153.933144 -241.727736)
		(width 0.14478)
		(layer "In13.Cu")
		(net "M_H_CPU1_SA_DQ<30>")
	)
	(segment
		(start 153.933144 -241.727736)
		(end 153.933144 -241.523012)
		(width 0.14478)
		(layer "In13.Cu")
		(net "M_H_CPU1_SA_DQ<30>")
	)
	(segment
		(start 154.536648 -241.55146)
		(end 154.741372 -241.55146)
		(width 0.14478)
		(layer "In13.Cu")
		(net "M_H_CPU1_SA_DQ<30>")
	)
	(segment
		(start 154.11831 -241.337846)
		(end 154.323034 -241.337846)
		(width 0.14478)
		(layer "In13.Cu")
		(net "M_H_CPU1_SA_DQ<30>")
	)
	(arc
		(start 138.377676 -243.351812)
		(mid 138.559927 -243.301462)
		(end 138.743436 -243.346986)
		(width 0.0889)
		(layer "In13.Cu")
		(net "M_H_CPU1_SA_DQ<30>")
	)
	(arc
		(start 136.87171 -243.351812)
		(mid 137.154666 -243.427989)
		(end 137.437622 -243.351812)
		(width 0.0889)
		(layer "In13.Cu")
		(net "M_H_CPU1_SA_DQ<30>")
	)
	(arc
		(start 138.751818 -243.351812)
		(mid 139.034774 -243.427989)
		(end 139.31773 -243.351812)
		(width 0.0889)
		(layer "In13.Cu")
		(net "M_H_CPU1_SA_DQ<30>")
	)
	(arc
		(start 136.497822 -243.351812)
		(mid 136.684766 -243.301557)
		(end 136.87171 -243.351812)
		(width 0.0889)
		(layer "In13.Cu")
		(net "M_H_CPU1_SA_DQ<30>")
	)
	(arc
		(start 139.691872 -243.351812)
		(mid 139.974828 -243.427989)
		(end 140.257784 -243.351812)
		(width 0.0889)
		(layer "In13.Cu")
		(net "M_H_CPU1_SA_DQ<30>")
	)
	(arc
		(start 139.326112 -243.346986)
		(mid 139.50962 -243.301492)
		(end 139.691872 -243.351812)
		(width 0.0889)
		(layer "In13.Cu")
		(net "M_H_CPU1_SA_DQ<30>")
	)
	(arc
		(start 141.571726 -243.351812)
		(mid 141.854682 -243.427989)
		(end 142.137638 -243.351812)
		(width 0.0889)
		(layer "In13.Cu")
		(net "M_H_CPU1_SA_DQ<30>")
	)
	(arc
		(start 137.811764 -243.351812)
		(mid 138.09472 -243.427989)
		(end 138.377676 -243.351812)
		(width 0.0889)
		(layer "In13.Cu")
		(net "M_H_CPU1_SA_DQ<30>")
	)
	(arc
		(start 142.137638 -243.351812)
		(mid 142.319889 -243.301462)
		(end 142.503398 -243.346986)
		(width 0.0889)
		(layer "In13.Cu")
		(net "M_H_CPU1_SA_DQ<30>")
	)
	(arc
		(start 143.462248 -243.357908)
		(mid 143.740934 -243.428128)
		(end 144.018 -243.351812)
		(width 0.0889)
		(layer "In13.Cu")
		(net "M_H_CPU1_SA_DQ<30>")
	)
	(arc
		(start 140.266166 -243.346986)
		(mid 140.449674 -243.301492)
		(end 140.631926 -243.351812)
		(width 0.0889)
		(layer "In13.Cu")
		(net "M_H_CPU1_SA_DQ<30>")
	)
	(arc
		(start 144.952466 -243.355368)
		(mid 145.044898 -243.315086)
		(end 145.144744 -243.301012)
		(width 0.0889)
		(layer "In13.Cu")
		(net "M_H_CPU1_SA_DQ<30>")
	)
	(arc
		(start 137.437622 -243.351812)
		(mid 137.619873 -243.301462)
		(end 137.803382 -243.346986)
		(width 0.0889)
		(layer "In13.Cu")
		(net "M_H_CPU1_SA_DQ<30>")
	)
	(arc
		(start 143.086074 -243.346986)
		(mid 143.269582 -243.301492)
		(end 143.451834 -243.351812)
		(width 0.0889)
		(layer "In13.Cu")
		(net "M_H_CPU1_SA_DQ<30>")
	)
	(arc
		(start 140.631926 -243.351812)
		(mid 140.914882 -243.427989)
		(end 141.197838 -243.351812)
		(width 0.0889)
		(layer "In13.Cu")
		(net "M_H_CPU1_SA_DQ<30>")
	)
	(arc
		(start 142.51178 -243.351812)
		(mid 142.794736 -243.427989)
		(end 143.077692 -243.351812)
		(width 0.0889)
		(layer "In13.Cu")
		(net "M_H_CPU1_SA_DQ<30>")
	)
	(arc
		(start 144.39265 -243.351812)
		(mid 144.672078 -243.427978)
		(end 144.952466 -243.355368)
		(width 0.0889)
		(layer "In13.Cu")
		(net "M_H_CPU1_SA_DQ<30>")
	)
	(arc
		(start 141.197838 -243.351812)
		(mid 141.384782 -243.301557)
		(end 141.571726 -243.351812)
		(width 0.0889)
		(layer "In13.Cu")
		(net "M_H_CPU1_SA_DQ<30>")
	)
	(arc
		(start 144.018 -243.351812)
		(mid 144.200505 -243.301335)
		(end 144.384268 -243.346986)
		(width 0.0889)
		(layer "In13.Cu")
		(net "M_H_CPU1_SA_DQ<30>")
	)
	(arc
		(start 135.995156 -243.383562)
		(mid 136.250221 -243.426913)
		(end 136.497822 -243.351812)
		(width 0.0889)
		(layer "In13.Cu")
		(net "M_H_CPU1_SA_DQ<30>")
	)
	(segment
		(start 135.27786 -226.120452)
		(end 135.744712 -225.854514)
		(width 0.10668)
		(layer "F.Cu")
		(net "M_H_CPU1_SA_DQ<2>")
	)
	(segment
		(start 142.461488 -217.422984)
		(end 142.461488 -221.304104)
		(width 0.14478)
		(layer "In13.Cu")
		(net "M_H_CPU1_SA_DQ<2>")
	)
	(segment
		(start 163.072826 -199.274176)
		(end 163.072826 -198.755254)
		(width 0.14478)
		(layer "In13.Cu")
		(net "M_H_CPU1_SA_DQ<2>")
	)
	(segment
		(start 141.95044 -222.038926)
		(end 141.95044 -222.61449)
		(width 0.0889)
		(layer "In13.Cu")
		(net "M_H_CPU1_SA_DQ<2>")
	)
	(segment
		(start 163.217606 -199.418956)
		(end 163.072826 -199.274176)
		(width 0.14478)
		(layer "In13.Cu")
		(net "M_H_CPU1_SA_DQ<2>")
	)
	(segment
		(start 161.012886 -199.418956)
		(end 160.868106 -199.274176)
		(width 0.14478)
		(layer "In13.Cu")
		(net "M_H_CPU1_SA_DQ<2>")
	)
	(segment
		(start 161.970466 -198.755254)
		(end 161.825686 -198.610474)
		(width 0.14478)
		(layer "In13.Cu")
		(net "M_H_CPU1_SA_DQ<2>")
	)
	(segment
		(start 171.546774 -198.610474)
		(end 171.16552 -198.610474)
		(width 0.14478)
		(layer "In13.Cu")
		(net "M_H_CPU1_SA_DQ<2>")
	)
	(segment
		(start 161.419286 -199.274176)
		(end 161.274506 -199.418956)
		(width 0.14478)
		(layer "In13.Cu")
		(net "M_H_CPU1_SA_DQ<2>")
	)
	(segment
		(start 160.723326 -198.610474)
		(end 159.98317 -198.610474)
		(width 0.14478)
		(layer "In13.Cu")
		(net "M_H_CPU1_SA_DQ<2>")
	)
	(segment
		(start 142.461488 -221.527878)
		(end 141.95044 -222.038926)
		(width 0.0889)
		(layer "In13.Cu")
		(net "M_H_CPU1_SA_DQ<2>")
	)
	(segment
		(start 135.89889 -225.589084)
		(end 135.744712 -225.854514)
		(width 0.0889)
		(layer "In13.Cu")
		(net "M_H_CPU1_SA_DQ<2>")
	)
	(segment
		(start 140.727938 -224.721928)
		(end 140.696188 -224.740216)
		(width 0.0889)
		(layer "In13.Cu")
		(net "M_H_CPU1_SA_DQ<2>")
	)
	(segment
		(start 163.072826 -198.755254)
		(end 162.928046 -198.610474)
		(width 0.14478)
		(layer "In13.Cu")
		(net "M_H_CPU1_SA_DQ<2>")
	)
	(segment
		(start 138.751818 -225.531934)
		(end 138.743436 -225.527108)
		(width 0.0889)
		(layer "In13.Cu")
		(net "M_H_CPU1_SA_DQ<2>")
	)
	(segment
		(start 141.667992 -223.101916)
		(end 141.637512 -223.119696)
		(width 0.0889)
		(layer "In13.Cu")
		(net "M_H_CPU1_SA_DQ<2>")
	)
	(segment
		(start 171.16552 -198.610474)
		(end 170.315382 -197.760336)
		(width 0.14478)
		(layer "In13.Cu")
		(net "M_H_CPU1_SA_DQ<2>")
	)
	(segment
		(start 162.115246 -199.418956)
		(end 161.970466 -199.274176)
		(width 0.14478)
		(layer "In13.Cu")
		(net "M_H_CPU1_SA_DQ<2>")
	)
	(segment
		(start 159.98317 -198.610474)
		(end 149.23897 -209.354674)
		(width 0.14478)
		(layer "In13.Cu")
		(net "M_H_CPU1_SA_DQ<2>")
	)
	(segment
		(start 163.768786 -198.610474)
		(end 163.624006 -198.755254)
		(width 0.14478)
		(layer "In13.Cu")
		(net "M_H_CPU1_SA_DQ<2>")
	)
	(segment
		(start 162.521646 -199.274176)
		(end 162.376866 -199.418956)
		(width 0.14478)
		(layer "In13.Cu")
		(net "M_H_CPU1_SA_DQ<2>")
	)
	(segment
		(start 141.197838 -223.911922)
		(end 141.166088 -223.93021)
		(width 0.0889)
		(layer "In13.Cu")
		(net "M_H_CPU1_SA_DQ<2>")
	)
	(segment
		(start 163.624006 -199.274176)
		(end 163.479226 -199.418956)
		(width 0.14478)
		(layer "In13.Cu")
		(net "M_H_CPU1_SA_DQ<2>")
	)
	(segment
		(start 166.228014 -198.610474)
		(end 163.768786 -198.610474)
		(width 0.14478)
		(layer "In13.Cu")
		(net "M_H_CPU1_SA_DQ<2>")
	)
	(segment
		(start 140.76426 -224.700846)
		(end 140.727938 -224.721928)
		(width 0.0889)
		(layer "In13.Cu")
		(net "M_H_CPU1_SA_DQ<2>")
	)
	(segment
		(start 137.811764 -225.531934)
		(end 137.803382 -225.527108)
		(width 0.0889)
		(layer "In13.Cu")
		(net "M_H_CPU1_SA_DQ<2>")
	)
	(segment
		(start 149.23897 -210.645502)
		(end 142.461488 -217.422984)
		(width 0.14478)
		(layer "In13.Cu")
		(net "M_H_CPU1_SA_DQ<2>")
	)
	(segment
		(start 135.995156 -225.563684)
		(end 135.89889 -225.589084)
		(width 0.0889)
		(layer "In13.Cu")
		(net "M_H_CPU1_SA_DQ<2>")
	)
	(segment
		(start 139.326112 -225.527108)
		(end 139.31773 -225.531934)
		(width 0.0889)
		(layer "In13.Cu")
		(net "M_H_CPU1_SA_DQ<2>")
	)
	(segment
		(start 161.970466 -199.274176)
		(end 161.970466 -198.755254)
		(width 0.14478)
		(layer "In13.Cu")
		(net "M_H_CPU1_SA_DQ<2>")
	)
	(segment
		(start 162.928046 -198.610474)
		(end 162.666426 -198.610474)
		(width 0.14478)
		(layer "In13.Cu")
		(net "M_H_CPU1_SA_DQ<2>")
	)
	(segment
		(start 167.078152 -197.760336)
		(end 166.228014 -198.610474)
		(width 0.14478)
		(layer "In13.Cu")
		(net "M_H_CPU1_SA_DQ<2>")
	)
	(segment
		(start 162.376866 -199.418956)
		(end 162.115246 -199.418956)
		(width 0.14478)
		(layer "In13.Cu")
		(net "M_H_CPU1_SA_DQ<2>")
	)
	(segment
		(start 161.564066 -198.610474)
		(end 161.419286 -198.755254)
		(width 0.14478)
		(layer "In13.Cu")
		(net "M_H_CPU1_SA_DQ<2>")
	)
	(segment
		(start 142.461488 -221.304104)
		(end 142.461488 -221.527878)
		(width 0.0889)
		(layer "In13.Cu")
		(net "M_H_CPU1_SA_DQ<2>")
	)
	(segment
		(start 163.624006 -198.755254)
		(end 163.624006 -199.274176)
		(width 0.14478)
		(layer "In13.Cu")
		(net "M_H_CPU1_SA_DQ<2>")
	)
	(segment
		(start 141.708378 -223.078294)
		(end 141.667992 -223.101916)
		(width 0.0889)
		(layer "In13.Cu")
		(net "M_H_CPU1_SA_DQ<2>")
	)
	(segment
		(start 162.666426 -198.610474)
		(end 162.521646 -198.755254)
		(width 0.14478)
		(layer "In13.Cu")
		(net "M_H_CPU1_SA_DQ<2>")
	)
	(segment
		(start 171.97197 -198.185278)
		(end 171.546774 -198.610474)
		(width 0.14478)
		(layer "In13.Cu")
		(net "M_H_CPU1_SA_DQ<2>")
	)
	(segment
		(start 140.2969 -225.509074)
		(end 140.257784 -225.531934)
		(width 0.0889)
		(layer "In13.Cu")
		(net "M_H_CPU1_SA_DQ<2>")
	)
	(segment
		(start 160.868106 -198.755254)
		(end 160.723326 -198.610474)
		(width 0.14478)
		(layer "In13.Cu")
		(net "M_H_CPU1_SA_DQ<2>")
	)
	(segment
		(start 149.23897 -209.354674)
		(end 149.23897 -210.645502)
		(width 0.14478)
		(layer "In13.Cu")
		(net "M_H_CPU1_SA_DQ<2>")
	)
	(segment
		(start 170.315382 -197.760336)
		(end 167.078152 -197.760336)
		(width 0.14478)
		(layer "In13.Cu")
		(net "M_H_CPU1_SA_DQ<2>")
	)
	(segment
		(start 161.419286 -198.755254)
		(end 161.419286 -199.274176)
		(width 0.14478)
		(layer "In13.Cu")
		(net "M_H_CPU1_SA_DQ<2>")
	)
	(segment
		(start 162.521646 -198.755254)
		(end 162.521646 -199.274176)
		(width 0.14478)
		(layer "In13.Cu")
		(net "M_H_CPU1_SA_DQ<2>")
	)
	(segment
		(start 161.825686 -198.610474)
		(end 161.564066 -198.610474)
		(width 0.14478)
		(layer "In13.Cu")
		(net "M_H_CPU1_SA_DQ<2>")
	)
	(segment
		(start 160.868106 -199.274176)
		(end 160.868106 -198.755254)
		(width 0.14478)
		(layer "In13.Cu")
		(net "M_H_CPU1_SA_DQ<2>")
	)
	(segment
		(start 163.479226 -199.418956)
		(end 163.217606 -199.418956)
		(width 0.14478)
		(layer "In13.Cu")
		(net "M_H_CPU1_SA_DQ<2>")
	)
	(segment
		(start 141.238224 -223.8883)
		(end 141.197838 -223.911922)
		(width 0.0889)
		(layer "In13.Cu")
		(net "M_H_CPU1_SA_DQ<2>")
	)
	(segment
		(start 161.274506 -199.418956)
		(end 161.012886 -199.418956)
		(width 0.14478)
		(layer "In13.Cu")
		(net "M_H_CPU1_SA_DQ<2>")
	)
	(arc
		(start 139.691872 -225.531934)
		(mid 139.509621 -225.481584)
		(end 139.326112 -225.527108)
		(width 0.0889)
		(layer "In13.Cu")
		(net "M_H_CPU1_SA_DQ<2>")
	)
	(arc
		(start 141.637512 -223.119696)
		(mid 141.522085 -223.253072)
		(end 141.48054 -223.424496)
		(width 0.0889)
		(layer "In13.Cu")
		(net "M_H_CPU1_SA_DQ<2>")
	)
	(arc
		(start 136.497822 -225.531934)
		(mid 136.250226 -225.607112)
		(end 135.995156 -225.563684)
		(width 0.0889)
		(layer "In13.Cu")
		(net "M_H_CPU1_SA_DQ<2>")
	)
	(arc
		(start 139.31773 -225.531934)
		(mid 139.034774 -225.608111)
		(end 138.751818 -225.531934)
		(width 0.0889)
		(layer "In13.Cu")
		(net "M_H_CPU1_SA_DQ<2>")
	)
	(arc
		(start 141.95044 -222.61449)
		(mid 141.886287 -222.876079)
		(end 141.708378 -223.078294)
		(width 0.0889)
		(layer "In13.Cu")
		(net "M_H_CPU1_SA_DQ<2>")
	)
	(arc
		(start 137.803382 -225.527108)
		(mid 137.619874 -225.481614)
		(end 137.437622 -225.531934)
		(width 0.0889)
		(layer "In13.Cu")
		(net "M_H_CPU1_SA_DQ<2>")
	)
	(arc
		(start 138.377676 -225.531934)
		(mid 138.09472 -225.608111)
		(end 137.811764 -225.531934)
		(width 0.0889)
		(layer "In13.Cu")
		(net "M_H_CPU1_SA_DQ<2>")
	)
	(arc
		(start 140.540232 -225.044508)
		(mid 140.475717 -225.306727)
		(end 140.2969 -225.509074)
		(width 0.0889)
		(layer "In13.Cu")
		(net "M_H_CPU1_SA_DQ<2>")
	)
	(arc
		(start 140.696188 -224.740216)
		(mid 140.581512 -224.87355)
		(end 140.540232 -225.044508)
		(width 0.0889)
		(layer "In13.Cu")
		(net "M_H_CPU1_SA_DQ<2>")
	)
	(arc
		(start 137.437622 -225.531934)
		(mid 137.154666 -225.608111)
		(end 136.87171 -225.531934)
		(width 0.0889)
		(layer "In13.Cu")
		(net "M_H_CPU1_SA_DQ<2>")
	)
	(arc
		(start 140.257784 -225.531934)
		(mid 139.974828 -225.608111)
		(end 139.691872 -225.531934)
		(width 0.0889)
		(layer "In13.Cu")
		(net "M_H_CPU1_SA_DQ<2>")
	)
	(arc
		(start 141.166088 -223.93021)
		(mid 141.051412 -224.063544)
		(end 141.010132 -224.234502)
		(width 0.0889)
		(layer "In13.Cu")
		(net "M_H_CPU1_SA_DQ<2>")
	)
	(arc
		(start 138.743436 -225.527108)
		(mid 138.559928 -225.481614)
		(end 138.377676 -225.531934)
		(width 0.0889)
		(layer "In13.Cu")
		(net "M_H_CPU1_SA_DQ<2>")
	)
	(arc
		(start 136.87171 -225.531934)
		(mid 136.684766 -225.481679)
		(end 136.497822 -225.531934)
		(width 0.0889)
		(layer "In13.Cu")
		(net "M_H_CPU1_SA_DQ<2>")
	)
	(arc
		(start 141.010132 -224.234502)
		(mid 140.944896 -224.498093)
		(end 140.76426 -224.700846)
		(width 0.0889)
		(layer "In13.Cu")
		(net "M_H_CPU1_SA_DQ<2>")
	)
	(arc
		(start 141.48054 -223.424496)
		(mid 141.416247 -223.686101)
		(end 141.238224 -223.8883)
		(width 0.0889)
		(layer "In13.Cu")
		(net "M_H_CPU1_SA_DQ<2>")
	)
	(segment
		(start 134.337806 -243.94033)
		(end 134.804658 -243.674392)
		(width 0.10668)
		(layer "F.Cu")
		(net "M_H_CPU1_SA_DQ<29>")
	)
	(segment
		(start 134.804658 -243.674392)
		(end 134.650734 -243.939822)
		(width 0.0889)
		(layer "In13.Cu")
		(net "M_H_CPU1_SA_DQ<29>")
	)
	(segment
		(start 146.929348 -243.793264)
		(end 147.743418 -242.979194)
		(width 0.0889)
		(layer "In13.Cu")
		(net "M_H_CPU1_SA_DQ<29>")
	)
	(segment
		(start 143.451834 -243.996972)
		(end 143.466566 -243.988336)
		(width 0.0889)
		(layer "In13.Cu")
		(net "M_H_CPU1_SA_DQ<29>")
	)
	(segment
		(start 134.650734 -243.939822)
		(end 134.673086 -244.023134)
		(width 0.0889)
		(layer "In13.Cu")
		(net "M_H_CPU1_SA_DQ<29>")
	)
	(segment
		(start 142.503398 -244.001798)
		(end 142.51178 -243.996972)
		(width 0.0889)
		(layer "In13.Cu")
		(net "M_H_CPU1_SA_DQ<29>")
	)
	(segment
		(start 137.803382 -244.001798)
		(end 137.811764 -243.996972)
		(width 0.0889)
		(layer "In13.Cu")
		(net "M_H_CPU1_SA_DQ<29>")
	)
	(segment
		(start 135.557768 -243.996972)
		(end 135.56615 -244.001798)
		(width 0.0889)
		(layer "In13.Cu")
		(net "M_H_CPU1_SA_DQ<29>")
	)
	(segment
		(start 144.380966 -244.00383)
		(end 144.39265 -243.996972)
		(width 0.0889)
		(layer "In13.Cu")
		(net "M_H_CPU1_SA_DQ<29>")
	)
	(segment
		(start 166.775892 -233.460544)
		(end 167.625776 -232.61066)
		(width 0.14478)
		(layer "In13.Cu")
		(net "M_H_CPU1_SA_DQ<29>")
	)
	(segment
		(start 143.077692 -243.996972)
		(end 143.086074 -244.001798)
		(width 0.0889)
		(layer "In13.Cu")
		(net "M_H_CPU1_SA_DQ<29>")
	)
	(segment
		(start 174.216314 -233.035348)
		(end 176.072038 -233.035348)
		(width 0.14478)
		(layer "In13.Cu")
		(net "M_H_CPU1_SA_DQ<29>")
	)
	(segment
		(start 167.625776 -232.61066)
		(end 169.67962 -232.61066)
		(width 0.14478)
		(layer "In13.Cu")
		(net "M_H_CPU1_SA_DQ<29>")
	)
	(segment
		(start 145.929604 -244.047772)
		(end 146.184112 -243.793264)
		(width 0.0889)
		(layer "In13.Cu")
		(net "M_H_CPU1_SA_DQ<29>")
	)
	(segment
		(start 138.743436 -244.001798)
		(end 138.751818 -243.996972)
		(width 0.0889)
		(layer "In13.Cu")
		(net "M_H_CPU1_SA_DQ<29>")
	)
	(segment
		(start 169.67962 -232.61066)
		(end 170.529504 -233.460544)
		(width 0.14478)
		(layer "In13.Cu")
		(net "M_H_CPU1_SA_DQ<29>")
	)
	(segment
		(start 147.743418 -242.979194)
		(end 147.937982 -242.979194)
		(width 0.0889)
		(layer "In13.Cu")
		(net "M_H_CPU1_SA_DQ<29>")
	)
	(segment
		(start 147.937982 -242.979194)
		(end 153.949654 -242.979194)
		(width 0.14478)
		(layer "In13.Cu")
		(net "M_H_CPU1_SA_DQ<29>")
	)
	(segment
		(start 146.184112 -243.793264)
		(end 146.929348 -243.793264)
		(width 0.0889)
		(layer "In13.Cu")
		(net "M_H_CPU1_SA_DQ<29>")
	)
	(segment
		(start 145.144744 -244.047772)
		(end 145.929604 -244.047772)
		(width 0.0889)
		(layer "In13.Cu")
		(net "M_H_CPU1_SA_DQ<29>")
	)
	(segment
		(start 140.257784 -243.996972)
		(end 140.266166 -244.001798)
		(width 0.0889)
		(layer "In13.Cu")
		(net "M_H_CPU1_SA_DQ<29>")
	)
	(segment
		(start 163.468304 -233.460544)
		(end 166.775892 -233.460544)
		(width 0.14478)
		(layer "In13.Cu")
		(net "M_H_CPU1_SA_DQ<29>")
	)
	(segment
		(start 139.31773 -243.996972)
		(end 139.326112 -244.001798)
		(width 0.0889)
		(layer "In13.Cu")
		(net "M_H_CPU1_SA_DQ<29>")
	)
	(segment
		(start 153.949654 -242.979194)
		(end 163.468304 -233.460544)
		(width 0.14478)
		(layer "In13.Cu")
		(net "M_H_CPU1_SA_DQ<29>")
	)
	(segment
		(start 170.529504 -233.460544)
		(end 173.791118 -233.460544)
		(width 0.14478)
		(layer "In13.Cu")
		(net "M_H_CPU1_SA_DQ<29>")
	)
	(segment
		(start 173.791118 -233.460544)
		(end 174.216314 -233.035348)
		(width 0.14478)
		(layer "In13.Cu")
		(net "M_H_CPU1_SA_DQ<29>")
	)
	(arc
		(start 143.466566 -243.988336)
		(mid 143.743549 -243.920532)
		(end 144.018254 -243.996972)
		(width 0.0889)
		(layer "In13.Cu")
		(net "M_H_CPU1_SA_DQ<29>")
	)
	(arc
		(start 136.497822 -243.996972)
		(mid 136.684766 -244.047227)
		(end 136.87171 -243.996972)
		(width 0.0889)
		(layer "In13.Cu")
		(net "M_H_CPU1_SA_DQ<29>")
	)
	(arc
		(start 142.51178 -243.996972)
		(mid 142.794736 -243.920795)
		(end 143.077692 -243.996972)
		(width 0.0889)
		(layer "In13.Cu")
		(net "M_H_CPU1_SA_DQ<29>")
	)
	(arc
		(start 144.39265 -243.996972)
		(mid 144.672078 -243.920806)
		(end 144.952466 -243.993416)
		(width 0.0889)
		(layer "In13.Cu")
		(net "M_H_CPU1_SA_DQ<29>")
	)
	(arc
		(start 136.87171 -243.996972)
		(mid 137.154666 -243.920795)
		(end 137.437622 -243.996972)
		(width 0.0889)
		(layer "In13.Cu")
		(net "M_H_CPU1_SA_DQ<29>")
	)
	(arc
		(start 137.437622 -243.996972)
		(mid 137.619873 -244.047322)
		(end 137.803382 -244.001798)
		(width 0.0889)
		(layer "In13.Cu")
		(net "M_H_CPU1_SA_DQ<29>")
	)
	(arc
		(start 140.631926 -243.996972)
		(mid 140.914882 -243.920795)
		(end 141.197838 -243.996972)
		(width 0.0889)
		(layer "In13.Cu")
		(net "M_H_CPU1_SA_DQ<29>")
	)
	(arc
		(start 144.952466 -243.993416)
		(mid 145.044898 -244.033698)
		(end 145.144744 -244.047772)
		(width 0.0889)
		(layer "In13.Cu")
		(net "M_H_CPU1_SA_DQ<29>")
	)
	(arc
		(start 138.751818 -243.996972)
		(mid 139.034774 -243.920795)
		(end 139.31773 -243.996972)
		(width 0.0889)
		(layer "In13.Cu")
		(net "M_H_CPU1_SA_DQ<29>")
	)
	(arc
		(start 143.086074 -244.001798)
		(mid 143.269582 -244.047292)
		(end 143.451834 -243.996972)
		(width 0.0889)
		(layer "In13.Cu")
		(net "M_H_CPU1_SA_DQ<29>")
	)
	(arc
		(start 141.197838 -243.996972)
		(mid 141.384782 -244.047227)
		(end 141.571726 -243.996972)
		(width 0.0889)
		(layer "In13.Cu")
		(net "M_H_CPU1_SA_DQ<29>")
	)
	(arc
		(start 141.571726 -243.996972)
		(mid 141.854682 -243.920795)
		(end 142.137638 -243.996972)
		(width 0.0889)
		(layer "In13.Cu")
		(net "M_H_CPU1_SA_DQ<29>")
	)
	(arc
		(start 139.326112 -244.001798)
		(mid 139.50962 -244.047292)
		(end 139.691872 -243.996972)
		(width 0.0889)
		(layer "In13.Cu")
		(net "M_H_CPU1_SA_DQ<29>")
	)
	(arc
		(start 139.691872 -243.996972)
		(mid 139.974828 -243.920795)
		(end 140.257784 -243.996972)
		(width 0.0889)
		(layer "In13.Cu")
		(net "M_H_CPU1_SA_DQ<29>")
	)
	(arc
		(start 144.018254 -243.996972)
		(mid 144.198712 -244.047416)
		(end 144.380966 -244.00383)
		(width 0.0889)
		(layer "In13.Cu")
		(net "M_H_CPU1_SA_DQ<29>")
	)
	(arc
		(start 134.991856 -243.996972)
		(mid 135.274812 -243.920795)
		(end 135.557768 -243.996972)
		(width 0.0889)
		(layer "In13.Cu")
		(net "M_H_CPU1_SA_DQ<29>")
	)
	(arc
		(start 135.93191 -243.996972)
		(mid 136.214866 -243.920795)
		(end 136.497822 -243.996972)
		(width 0.0889)
		(layer "In13.Cu")
		(net "M_H_CPU1_SA_DQ<29>")
	)
	(arc
		(start 140.266166 -244.001798)
		(mid 140.449674 -244.047292)
		(end 140.631926 -243.996972)
		(width 0.0889)
		(layer "In13.Cu")
		(net "M_H_CPU1_SA_DQ<29>")
	)
	(arc
		(start 138.377676 -243.996972)
		(mid 138.559927 -244.047322)
		(end 138.743436 -244.001798)
		(width 0.0889)
		(layer "In13.Cu")
		(net "M_H_CPU1_SA_DQ<29>")
	)
	(arc
		(start 135.56615 -244.001798)
		(mid 135.749658 -244.047292)
		(end 135.93191 -243.996972)
		(width 0.0889)
		(layer "In13.Cu")
		(net "M_H_CPU1_SA_DQ<29>")
	)
	(arc
		(start 137.811764 -243.996972)
		(mid 138.09472 -243.920795)
		(end 138.377676 -243.996972)
		(width 0.0889)
		(layer "In13.Cu")
		(net "M_H_CPU1_SA_DQ<29>")
	)
	(arc
		(start 142.137638 -243.996972)
		(mid 142.319889 -244.047322)
		(end 142.503398 -244.001798)
		(width 0.0889)
		(layer "In13.Cu")
		(net "M_H_CPU1_SA_DQ<29>")
	)
	(arc
		(start 134.673086 -244.023134)
		(mid 134.835418 -244.045952)
		(end 134.991856 -243.996972)
		(width 0.0889)
		(layer "In13.Cu")
		(net "M_H_CPU1_SA_DQ<29>")
	)
	(segment
		(start 135.748014 -243.130324)
		(end 136.214866 -242.864386)
		(width 0.10668)
		(layer "F.Cu")
		(net "M_H_CPU1_SA_DQ<28>")
	)
	(segment
		(start 144.488408 -243.186966)
		(end 144.477994 -243.18087)
		(width 0.0889)
		(layer "In13.Cu")
		(net "M_H_CPU1_SA_DQ<28>")
	)
	(segment
		(start 175.232314 -231.62514)
		(end 175.232314 -231.412034)
		(width 0.14478)
		(layer "In13.Cu")
		(net "M_H_CPU1_SA_DQ<28>")
	)
	(segment
		(start 174.274734 -232.272586)
		(end 174.129954 -232.127806)
		(width 0.14478)
		(layer "In13.Cu")
		(net "M_H_CPU1_SA_DQ<28>")
	)
	(segment
		(start 174.129954 -232.127806)
		(end 174.129954 -231.9147)
		(width 0.14478)
		(layer "In13.Cu")
		(net "M_H_CPU1_SA_DQ<28>")
	)
	(segment
		(start 136.08304 -243.213128)
		(end 136.060688 -243.129816)
		(width 0.0889)
		(layer "In13.Cu")
		(net "M_H_CPU1_SA_DQ<28>")
	)
	(segment
		(start 174.825914 -231.267254)
		(end 174.681134 -231.412034)
		(width 0.14478)
		(layer "In13.Cu")
		(net "M_H_CPU1_SA_DQ<28>")
	)
	(segment
		(start 170.405552 -231.76992)
		(end 169.546016 -230.910384)
		(width 0.14478)
		(layer "In13.Cu")
		(net "M_H_CPU1_SA_DQ<28>")
	)
	(segment
		(start 137.916158 -243.191792)
		(end 137.907776 -243.186966)
		(width 0.0889)
		(layer "In13.Cu")
		(net "M_H_CPU1_SA_DQ<28>")
	)
	(segment
		(start 174.681134 -232.127806)
		(end 174.536354 -232.272586)
		(width 0.14478)
		(layer "In13.Cu")
		(net "M_H_CPU1_SA_DQ<28>")
	)
	(segment
		(start 158.053024 -236.369352)
		(end 152.352502 -242.069874)
		(width 0.14478)
		(layer "In13.Cu")
		(net "M_H_CPU1_SA_DQ<28>")
	)
	(segment
		(start 136.40181 -243.186966)
		(end 136.393428 -243.191792)
		(width 0.0889)
		(layer "In13.Cu")
		(net "M_H_CPU1_SA_DQ<28>")
	)
	(segment
		(start 147.591018 -242.069874)
		(end 147.486878 -242.174014)
		(width 0.14478)
		(layer "In13.Cu")
		(net "M_H_CPU1_SA_DQ<28>")
	)
	(segment
		(start 169.546016 -230.910384)
		(end 167.18026 -230.910384)
		(width 0.14478)
		(layer "In13.Cu")
		(net "M_H_CPU1_SA_DQ<28>")
	)
	(segment
		(start 141.101826 -243.186966)
		(end 141.093444 -243.191792)
		(width 0.0889)
		(layer "In13.Cu")
		(net "M_H_CPU1_SA_DQ<28>")
	)
	(segment
		(start 146.25955 -243.110512)
		(end 145.144744 -243.110512)
		(width 0.0889)
		(layer "In13.Cu")
		(net "M_H_CPU1_SA_DQ<28>")
	)
	(segment
		(start 175.637444 -231.76992)
		(end 175.377094 -231.76992)
		(width 0.14478)
		(layer "In13.Cu")
		(net "M_H_CPU1_SA_DQ<28>")
	)
	(segment
		(start 174.129954 -231.9147)
		(end 173.985174 -231.76992)
		(width 0.14478)
		(layer "In13.Cu")
		(net "M_H_CPU1_SA_DQ<28>")
	)
	(segment
		(start 152.352502 -242.069874)
		(end 147.591018 -242.069874)
		(width 0.14478)
		(layer "In13.Cu")
		(net "M_H_CPU1_SA_DQ<28>")
	)
	(segment
		(start 159.287464 -236.369352)
		(end 158.053024 -236.369352)
		(width 0.14478)
		(layer "In13.Cu")
		(net "M_H_CPU1_SA_DQ<28>")
	)
	(segment
		(start 136.976104 -243.191792)
		(end 136.967722 -243.186966)
		(width 0.0889)
		(layer "In13.Cu")
		(net "M_H_CPU1_SA_DQ<28>")
	)
	(segment
		(start 143.555974 -243.191792)
		(end 143.547592 -243.186966)
		(width 0.0889)
		(layer "In13.Cu")
		(net "M_H_CPU1_SA_DQ<28>")
	)
	(segment
		(start 146.735038 -242.635024)
		(end 146.25955 -243.110512)
		(width 0.0889)
		(layer "In13.Cu")
		(net "M_H_CPU1_SA_DQ<28>")
	)
	(segment
		(start 147.025868 -242.635024)
		(end 146.735038 -242.635024)
		(width 0.0889)
		(layer "In13.Cu")
		(net "M_H_CPU1_SA_DQ<28>")
	)
	(segment
		(start 176.072038 -231.335326)
		(end 175.637444 -231.76992)
		(width 0.14478)
		(layer "In13.Cu")
		(net "M_H_CPU1_SA_DQ<28>")
	)
	(segment
		(start 163.896548 -231.760268)
		(end 159.287464 -236.369352)
		(width 0.14478)
		(layer "In13.Cu")
		(net "M_H_CPU1_SA_DQ<28>")
	)
	(segment
		(start 140.161772 -243.186966)
		(end 140.15339 -243.191792)
		(width 0.0889)
		(layer "In13.Cu")
		(net "M_H_CPU1_SA_DQ<28>")
	)
	(segment
		(start 166.330376 -231.760268)
		(end 163.896548 -231.760268)
		(width 0.14478)
		(layer "In13.Cu")
		(net "M_H_CPU1_SA_DQ<28>")
	)
	(segment
		(start 167.18026 -230.910384)
		(end 166.330376 -231.760268)
		(width 0.14478)
		(layer "In13.Cu")
		(net "M_H_CPU1_SA_DQ<28>")
	)
	(segment
		(start 147.486878 -242.174014)
		(end 147.025868 -242.635024)
		(width 0.0889)
		(layer "In13.Cu")
		(net "M_H_CPU1_SA_DQ<28>")
	)
	(segment
		(start 175.377094 -231.76992)
		(end 175.232314 -231.62514)
		(width 0.14478)
		(layer "In13.Cu")
		(net "M_H_CPU1_SA_DQ<28>")
	)
	(segment
		(start 174.681134 -231.412034)
		(end 174.681134 -232.127806)
		(width 0.14478)
		(layer "In13.Cu")
		(net "M_H_CPU1_SA_DQ<28>")
	)
	(segment
		(start 141.67612 -243.191792)
		(end 141.667738 -243.186966)
		(width 0.0889)
		(layer "In13.Cu")
		(net "M_H_CPU1_SA_DQ<28>")
	)
	(segment
		(start 173.985174 -231.76992)
		(end 170.405552 -231.76992)
		(width 0.14478)
		(layer "In13.Cu")
		(net "M_H_CPU1_SA_DQ<28>")
	)
	(segment
		(start 175.087534 -231.267254)
		(end 174.825914 -231.267254)
		(width 0.14478)
		(layer "In13.Cu")
		(net "M_H_CPU1_SA_DQ<28>")
	)
	(segment
		(start 175.232314 -231.412034)
		(end 175.087534 -231.267254)
		(width 0.14478)
		(layer "In13.Cu")
		(net "M_H_CPU1_SA_DQ<28>")
	)
	(segment
		(start 174.536354 -232.272586)
		(end 174.274734 -232.272586)
		(width 0.14478)
		(layer "In13.Cu")
		(net "M_H_CPU1_SA_DQ<28>")
	)
	(segment
		(start 136.060688 -243.129816)
		(end 136.214866 -242.864386)
		(width 0.0889)
		(layer "In13.Cu")
		(net "M_H_CPU1_SA_DQ<28>")
	)
	(arc
		(start 138.84783 -243.186966)
		(mid 138.564874 -243.110789)
		(end 138.281918 -243.186966)
		(width 0.0889)
		(layer "In13.Cu")
		(net "M_H_CPU1_SA_DQ<28>")
	)
	(arc
		(start 136.967722 -243.186966)
		(mid 136.684766 -243.110789)
		(end 136.40181 -243.186966)
		(width 0.0889)
		(layer "In13.Cu")
		(net "M_H_CPU1_SA_DQ<28>")
	)
	(arc
		(start 137.907776 -243.186966)
		(mid 137.62482 -243.110789)
		(end 137.341864 -243.186966)
		(width 0.0889)
		(layer "In13.Cu")
		(net "M_H_CPU1_SA_DQ<28>")
	)
	(arc
		(start 143.547592 -243.186966)
		(mid 143.264636 -243.110789)
		(end 142.98168 -243.186966)
		(width 0.0889)
		(layer "In13.Cu")
		(net "M_H_CPU1_SA_DQ<28>")
	)
	(arc
		(start 145.144744 -243.110512)
		(mid 144.989383 -243.132337)
		(end 144.84604 -243.19611)
		(width 0.0889)
		(layer "In13.Cu")
		(net "M_H_CPU1_SA_DQ<28>")
	)
	(arc
		(start 140.727684 -243.186966)
		(mid 140.444728 -243.110789)
		(end 140.161772 -243.186966)
		(width 0.0889)
		(layer "In13.Cu")
		(net "M_H_CPU1_SA_DQ<28>")
	)
	(arc
		(start 140.15339 -243.191792)
		(mid 139.969882 -243.237286)
		(end 139.78763 -243.186966)
		(width 0.0889)
		(layer "In13.Cu")
		(net "M_H_CPU1_SA_DQ<28>")
	)
	(arc
		(start 136.393428 -243.191792)
		(mid 136.240558 -243.236433)
		(end 136.08304 -243.213128)
		(width 0.0889)
		(layer "In13.Cu")
		(net "M_H_CPU1_SA_DQ<28>")
	)
	(arc
		(start 142.98168 -243.186966)
		(mid 142.794736 -243.237221)
		(end 142.607792 -243.186966)
		(width 0.0889)
		(layer "In13.Cu")
		(net "M_H_CPU1_SA_DQ<28>")
	)
	(arc
		(start 139.221718 -243.186966)
		(mid 139.034774 -243.237221)
		(end 138.84783 -243.186966)
		(width 0.0889)
		(layer "In13.Cu")
		(net "M_H_CPU1_SA_DQ<28>")
	)
	(arc
		(start 142.607792 -243.186966)
		(mid 142.324836 -243.110789)
		(end 142.04188 -243.186966)
		(width 0.0889)
		(layer "In13.Cu")
		(net "M_H_CPU1_SA_DQ<28>")
	)
	(arc
		(start 143.922242 -243.186966)
		(mid 143.739737 -243.237443)
		(end 143.555974 -243.191792)
		(width 0.0889)
		(layer "In13.Cu")
		(net "M_H_CPU1_SA_DQ<28>")
	)
	(arc
		(start 141.667738 -243.186966)
		(mid 141.384782 -243.110789)
		(end 141.101826 -243.186966)
		(width 0.0889)
		(layer "In13.Cu")
		(net "M_H_CPU1_SA_DQ<28>")
	)
	(arc
		(start 144.84604 -243.19611)
		(mid 144.666058 -243.23721)
		(end 144.488408 -243.186966)
		(width 0.0889)
		(layer "In13.Cu")
		(net "M_H_CPU1_SA_DQ<28>")
	)
	(arc
		(start 139.78763 -243.186966)
		(mid 139.504674 -243.110789)
		(end 139.221718 -243.186966)
		(width 0.0889)
		(layer "In13.Cu")
		(net "M_H_CPU1_SA_DQ<28>")
	)
	(arc
		(start 144.477994 -243.18087)
		(mid 144.199308 -243.11065)
		(end 143.922242 -243.186966)
		(width 0.0889)
		(layer "In13.Cu")
		(net "M_H_CPU1_SA_DQ<28>")
	)
	(arc
		(start 141.093444 -243.191792)
		(mid 140.909936 -243.237286)
		(end 140.727684 -243.186966)
		(width 0.0889)
		(layer "In13.Cu")
		(net "M_H_CPU1_SA_DQ<28>")
	)
	(arc
		(start 142.04188 -243.186966)
		(mid 141.859629 -243.237316)
		(end 141.67612 -243.191792)
		(width 0.0889)
		(layer "In13.Cu")
		(net "M_H_CPU1_SA_DQ<28>")
	)
	(arc
		(start 137.341864 -243.186966)
		(mid 137.159613 -243.237316)
		(end 136.976104 -243.191792)
		(width 0.0889)
		(layer "In13.Cu")
		(net "M_H_CPU1_SA_DQ<28>")
	)
	(arc
		(start 138.281918 -243.186966)
		(mid 138.099667 -243.237316)
		(end 137.916158 -243.191792)
		(width 0.0889)
		(layer "In13.Cu")
		(net "M_H_CPU1_SA_DQ<28>")
	)
	(segment
		(start 133.867906 -241.510312)
		(end 134.334758 -241.244374)
		(width 0.10668)
		(layer "F.Cu")
		(net "M_H_CPU1_SA_DQ<27>")
	)
	(segment
		(start 144.985486 -240.983516)
		(end 145.128488 -241.011964)
		(width 0.0889)
		(layer "In13.Cu")
		(net "M_H_CPU1_SA_DQ<27>")
	)
	(segment
		(start 154.246072 -236.437932)
		(end 154.657044 -236.437932)
		(width 0.14478)
		(layer "In13.Cu")
		(net "M_H_CPU1_SA_DQ<27>")
	)
	(segment
		(start 152.685496 -237.998508)
		(end 153.096468 -237.998508)
		(width 0.14478)
		(layer "In13.Cu")
		(net "M_H_CPU1_SA_DQ<27>")
	)
	(segment
		(start 153.281126 -237.402878)
		(end 153.465784 -237.21822)
		(width 0.14478)
		(layer "In13.Cu")
		(net "M_H_CPU1_SA_DQ<27>")
	)
	(segment
		(start 168.210992 -227.79609)
		(end 168.496742 -227.51034)
		(width 0.14478)
		(layer "In13.Cu")
		(net "M_H_CPU1_SA_DQ<27>")
	)
	(segment
		(start 168.762172 -227.51034)
		(end 169.047922 -227.79609)
		(width 0.14478)
		(layer "In13.Cu")
		(net "M_H_CPU1_SA_DQ<27>")
	)
	(segment
		(start 150.97252 -239.711484)
		(end 151.12492 -239.559084)
		(width 0.14478)
		(layer "In13.Cu")
		(net "M_H_CPU1_SA_DQ<27>")
	)
	(segment
		(start 171.6024 -228.350572)
		(end 171.97197 -227.981002)
		(width 0.14478)
		(layer "In13.Cu")
		(net "M_H_CPU1_SA_DQ<27>")
	)
	(segment
		(start 136.967722 -240.921794)
		(end 136.976104 -240.916968)
		(width 0.0889)
		(layer "In13.Cu")
		(net "M_H_CPU1_SA_DQ<27>")
	)
	(segment
		(start 171.040044 -228.350572)
		(end 171.6024 -228.350572)
		(width 0.14478)
		(layer "In13.Cu")
		(net "M_H_CPU1_SA_DQ<27>")
	)
	(segment
		(start 164.407088 -228.360478)
		(end 164.682678 -228.636068)
		(width 0.14478)
		(layer "In13.Cu")
		(net "M_H_CPU1_SA_DQ<27>")
	)
	(segment
		(start 166.065708 -228.360478)
		(end 166.915846 -227.51034)
		(width 0.14478)
		(layer "In13.Cu")
		(net "M_H_CPU1_SA_DQ<27>")
	)
	(segment
		(start 151.12492 -239.559084)
		(end 151.535892 -239.559084)
		(width 0.14478)
		(layer "In13.Cu")
		(net "M_H_CPU1_SA_DQ<27>")
	)
	(segment
		(start 155.02636 -235.657644)
		(end 155.437332 -235.657644)
		(width 0.14478)
		(layer "In13.Cu")
		(net "M_H_CPU1_SA_DQ<27>")
	)
	(segment
		(start 151.535892 -239.559084)
		(end 151.72055 -239.374426)
		(width 0.14478)
		(layer "In13.Cu")
		(net "M_H_CPU1_SA_DQ<27>")
	)
	(segment
		(start 134.334758 -241.244374)
		(end 134.488682 -240.978944)
		(width 0.0889)
		(layer "In13.Cu")
		(net "M_H_CPU1_SA_DQ<27>")
	)
	(segment
		(start 170.199812 -227.51034)
		(end 171.040044 -228.350572)
		(width 0.14478)
		(layer "In13.Cu")
		(net "M_H_CPU1_SA_DQ<27>")
	)
	(segment
		(start 166.915846 -227.51034)
		(end 167.659812 -227.51034)
		(width 0.14478)
		(layer "In13.Cu")
		(net "M_H_CPU1_SA_DQ<27>")
	)
	(segment
		(start 143.547592 -240.921794)
		(end 143.555974 -240.916968)
		(width 0.0889)
		(layer "In13.Cu")
		(net "M_H_CPU1_SA_DQ<27>")
	)
	(segment
		(start 144.47393 -240.93043)
		(end 144.488662 -240.921794)
		(width 0.0889)
		(layer "In13.Cu")
		(net "M_H_CPU1_SA_DQ<27>")
	)
	(segment
		(start 155.437332 -235.657644)
		(end 155.62199 -235.472986)
		(width 0.14478)
		(layer "In13.Cu")
		(net "M_H_CPU1_SA_DQ<27>")
	)
	(segment
		(start 169.313352 -227.79609)
		(end 169.599102 -227.51034)
		(width 0.14478)
		(layer "In13.Cu")
		(net "M_H_CPU1_SA_DQ<27>")
	)
	(segment
		(start 153.281126 -237.81385)
		(end 153.281126 -237.402878)
		(width 0.14478)
		(layer "In13.Cu")
		(net "M_H_CPU1_SA_DQ<27>")
	)
	(segment
		(start 144.84858 -240.914174)
		(end 144.87017 -240.935764)
		(width 0.0889)
		(layer "In13.Cu")
		(net "M_H_CPU1_SA_DQ<27>")
	)
	(segment
		(start 153.096468 -237.998508)
		(end 153.281126 -237.81385)
		(width 0.14478)
		(layer "In13.Cu")
		(net "M_H_CPU1_SA_DQ<27>")
	)
	(segment
		(start 134.488682 -240.978944)
		(end 134.584694 -240.953544)
		(width 0.0889)
		(layer "In13.Cu")
		(net "M_H_CPU1_SA_DQ<27>")
	)
	(segment
		(start 141.093444 -240.916968)
		(end 141.101826 -240.921794)
		(width 0.0889)
		(layer "In13.Cu")
		(net "M_H_CPU1_SA_DQ<27>")
	)
	(segment
		(start 151.72055 -238.963454)
		(end 151.905208 -238.778796)
		(width 0.14478)
		(layer "In13.Cu")
		(net "M_H_CPU1_SA_DQ<27>")
	)
	(segment
		(start 145.887948 -241.011964)
		(end 146.228308 -240.671604)
		(width 0.0889)
		(layer "In13.Cu")
		(net "M_H_CPU1_SA_DQ<27>")
	)
	(segment
		(start 169.599102 -227.51034)
		(end 170.199812 -227.51034)
		(width 0.14478)
		(layer "In13.Cu")
		(net "M_H_CPU1_SA_DQ<27>")
	)
	(segment
		(start 155.62199 -235.062014)
		(end 155.806648 -234.877356)
		(width 0.14478)
		(layer "In13.Cu")
		(net "M_H_CPU1_SA_DQ<27>")
	)
	(segment
		(start 154.657044 -236.437932)
		(end 154.841702 -236.253274)
		(width 0.14478)
		(layer "In13.Cu")
		(net "M_H_CPU1_SA_DQ<27>")
	)
	(segment
		(start 147.937982 -239.711484)
		(end 150.97252 -239.711484)
		(width 0.14478)
		(layer "In13.Cu")
		(net "M_H_CPU1_SA_DQ<27>")
	)
	(segment
		(start 152.500838 -238.183166)
		(end 152.685496 -237.998508)
		(width 0.14478)
		(layer "In13.Cu")
		(net "M_H_CPU1_SA_DQ<27>")
	)
	(segment
		(start 157.182566 -233.91241)
		(end 157.182566 -233.501438)
		(width 0.14478)
		(layer "In13.Cu")
		(net "M_H_CPU1_SA_DQ<27>")
	)
	(segment
		(start 137.907776 -240.921794)
		(end 137.916158 -240.916968)
		(width 0.0889)
		(layer "In13.Cu")
		(net "M_H_CPU1_SA_DQ<27>")
	)
	(segment
		(start 164.682678 -228.636068)
		(end 164.958268 -228.636068)
		(width 0.14478)
		(layer "In13.Cu")
		(net "M_H_CPU1_SA_DQ<27>")
	)
	(segment
		(start 164.958268 -228.636068)
		(end 165.233858 -228.360478)
		(width 0.14478)
		(layer "In13.Cu")
		(net "M_H_CPU1_SA_DQ<27>")
	)
	(segment
		(start 154.061414 -237.033562)
		(end 154.061414 -236.62259)
		(width 0.14478)
		(layer "In13.Cu")
		(net "M_H_CPU1_SA_DQ<27>")
	)
	(segment
		(start 157.182566 -233.501438)
		(end 162.323526 -228.360478)
		(width 0.14478)
		(layer "In13.Cu")
		(net "M_H_CPU1_SA_DQ<27>")
	)
	(segment
		(start 163.580318 -228.636068)
		(end 163.855908 -228.636068)
		(width 0.14478)
		(layer "In13.Cu")
		(net "M_H_CPU1_SA_DQ<27>")
	)
	(segment
		(start 169.047922 -227.79609)
		(end 169.313352 -227.79609)
		(width 0.14478)
		(layer "In13.Cu")
		(net "M_H_CPU1_SA_DQ<27>")
	)
	(segment
		(start 167.659812 -227.51034)
		(end 167.945562 -227.79609)
		(width 0.14478)
		(layer "In13.Cu")
		(net "M_H_CPU1_SA_DQ<27>")
	)
	(segment
		(start 140.15339 -240.916968)
		(end 140.161772 -240.921794)
		(width 0.0889)
		(layer "In13.Cu")
		(net "M_H_CPU1_SA_DQ<27>")
	)
	(segment
		(start 136.393428 -240.916968)
		(end 136.40181 -240.921794)
		(width 0.0889)
		(layer "In13.Cu")
		(net "M_H_CPU1_SA_DQ<27>")
	)
	(segment
		(start 164.131498 -228.360478)
		(end 164.407088 -228.360478)
		(width 0.14478)
		(layer "In13.Cu")
		(net "M_H_CPU1_SA_DQ<27>")
	)
	(segment
		(start 146.228308 -240.671604)
		(end 146.623532 -240.671604)
		(width 0.0889)
		(layer "In13.Cu")
		(net "M_H_CPU1_SA_DQ<27>")
	)
	(segment
		(start 163.304728 -228.360478)
		(end 163.580318 -228.636068)
		(width 0.14478)
		(layer "In13.Cu")
		(net "M_H_CPU1_SA_DQ<27>")
	)
	(segment
		(start 156.21762 -234.877356)
		(end 156.402278 -234.692698)
		(width 0.14478)
		(layer "In13.Cu")
		(net "M_H_CPU1_SA_DQ<27>")
	)
	(segment
		(start 156.402278 -234.692698)
		(end 156.402278 -234.281726)
		(width 0.14478)
		(layer "In13.Cu")
		(net "M_H_CPU1_SA_DQ<27>")
	)
	(segment
		(start 163.855908 -228.636068)
		(end 164.131498 -228.360478)
		(width 0.14478)
		(layer "In13.Cu")
		(net "M_H_CPU1_SA_DQ<27>")
	)
	(segment
		(start 156.402278 -234.281726)
		(end 156.586936 -234.097068)
		(width 0.14478)
		(layer "In13.Cu")
		(net "M_H_CPU1_SA_DQ<27>")
	)
	(segment
		(start 154.841702 -235.842302)
		(end 155.02636 -235.657644)
		(width 0.14478)
		(layer "In13.Cu")
		(net "M_H_CPU1_SA_DQ<27>")
	)
	(segment
		(start 135.453374 -240.916968)
		(end 135.461756 -240.921794)
		(width 0.0889)
		(layer "In13.Cu")
		(net "M_H_CPU1_SA_DQ<27>")
	)
	(segment
		(start 155.806648 -234.877356)
		(end 156.21762 -234.877356)
		(width 0.14478)
		(layer "In13.Cu")
		(net "M_H_CPU1_SA_DQ<27>")
	)
	(segment
		(start 171.97197 -227.981002)
		(end 171.97197 -227.935282)
		(width 0.14478)
		(layer "In13.Cu")
		(net "M_H_CPU1_SA_DQ<27>")
	)
	(segment
		(start 154.841702 -236.253274)
		(end 154.841702 -235.842302)
		(width 0.14478)
		(layer "In13.Cu")
		(net "M_H_CPU1_SA_DQ<27>")
	)
	(segment
		(start 167.945562 -227.79609)
		(end 168.210992 -227.79609)
		(width 0.14478)
		(layer "In13.Cu")
		(net "M_H_CPU1_SA_DQ<27>")
	)
	(segment
		(start 151.905208 -238.778796)
		(end 152.31618 -238.778796)
		(width 0.14478)
		(layer "In13.Cu")
		(net "M_H_CPU1_SA_DQ<27>")
	)
	(segment
		(start 155.62199 -235.472986)
		(end 155.62199 -235.062014)
		(width 0.14478)
		(layer "In13.Cu")
		(net "M_H_CPU1_SA_DQ<27>")
	)
	(segment
		(start 152.500838 -238.594138)
		(end 152.500838 -238.183166)
		(width 0.14478)
		(layer "In13.Cu")
		(net "M_H_CPU1_SA_DQ<27>")
	)
	(segment
		(start 156.997908 -234.097068)
		(end 157.182566 -233.91241)
		(width 0.14478)
		(layer "In13.Cu")
		(net "M_H_CPU1_SA_DQ<27>")
	)
	(segment
		(start 147.583652 -239.711484)
		(end 147.937982 -239.711484)
		(width 0.0889)
		(layer "In13.Cu")
		(net "M_H_CPU1_SA_DQ<27>")
	)
	(segment
		(start 144.87017 -240.935764)
		(end 144.985486 -240.983516)
		(width 0.0889)
		(layer "In13.Cu")
		(net "M_H_CPU1_SA_DQ<27>")
	)
	(segment
		(start 153.465784 -237.21822)
		(end 153.876756 -237.21822)
		(width 0.14478)
		(layer "In13.Cu")
		(net "M_H_CPU1_SA_DQ<27>")
	)
	(segment
		(start 154.061414 -236.62259)
		(end 154.246072 -236.437932)
		(width 0.14478)
		(layer "In13.Cu")
		(net "M_H_CPU1_SA_DQ<27>")
	)
	(segment
		(start 165.233858 -228.360478)
		(end 166.065708 -228.360478)
		(width 0.14478)
		(layer "In13.Cu")
		(net "M_H_CPU1_SA_DQ<27>")
	)
	(segment
		(start 152.31618 -238.778796)
		(end 152.500838 -238.594138)
		(width 0.14478)
		(layer "In13.Cu")
		(net "M_H_CPU1_SA_DQ<27>")
	)
	(segment
		(start 146.623532 -240.671604)
		(end 147.583652 -239.711484)
		(width 0.0889)
		(layer "In13.Cu")
		(net "M_H_CPU1_SA_DQ<27>")
	)
	(segment
		(start 168.496742 -227.51034)
		(end 168.762172 -227.51034)
		(width 0.14478)
		(layer "In13.Cu")
		(net "M_H_CPU1_SA_DQ<27>")
	)
	(segment
		(start 162.323526 -228.360478)
		(end 163.304728 -228.360478)
		(width 0.14478)
		(layer "In13.Cu")
		(net "M_H_CPU1_SA_DQ<27>")
	)
	(segment
		(start 141.667738 -240.921794)
		(end 141.67612 -240.916968)
		(width 0.0889)
		(layer "In13.Cu")
		(net "M_H_CPU1_SA_DQ<27>")
	)
	(segment
		(start 156.586936 -234.097068)
		(end 156.997908 -234.097068)
		(width 0.14478)
		(layer "In13.Cu")
		(net "M_H_CPU1_SA_DQ<27>")
	)
	(segment
		(start 153.876756 -237.21822)
		(end 154.061414 -237.033562)
		(width 0.14478)
		(layer "In13.Cu")
		(net "M_H_CPU1_SA_DQ<27>")
	)
	(segment
		(start 151.72055 -239.374426)
		(end 151.72055 -238.963454)
		(width 0.14478)
		(layer "In13.Cu")
		(net "M_H_CPU1_SA_DQ<27>")
	)
	(segment
		(start 145.128488 -241.011964)
		(end 145.887948 -241.011964)
		(width 0.0889)
		(layer "In13.Cu")
		(net "M_H_CPU1_SA_DQ<27>")
	)
	(arc
		(start 134.584694 -240.953544)
		(mid 134.839902 -240.997021)
		(end 135.087614 -240.921794)
		(width 0.0889)
		(layer "In13.Cu")
		(net "M_H_CPU1_SA_DQ<27>")
	)
	(arc
		(start 139.78763 -240.921794)
		(mid 139.969881 -240.871444)
		(end 140.15339 -240.916968)
		(width 0.0889)
		(layer "In13.Cu")
		(net "M_H_CPU1_SA_DQ<27>")
	)
	(arc
		(start 135.461756 -240.921794)
		(mid 135.744712 -240.997971)
		(end 136.027668 -240.921794)
		(width 0.0889)
		(layer "In13.Cu")
		(net "M_H_CPU1_SA_DQ<27>")
	)
	(arc
		(start 138.84783 -240.921794)
		(mid 139.034774 -240.871539)
		(end 139.221718 -240.921794)
		(width 0.0889)
		(layer "In13.Cu")
		(net "M_H_CPU1_SA_DQ<27>")
	)
	(arc
		(start 140.161772 -240.921794)
		(mid 140.444728 -240.997971)
		(end 140.727684 -240.921794)
		(width 0.0889)
		(layer "In13.Cu")
		(net "M_H_CPU1_SA_DQ<27>")
	)
	(arc
		(start 143.555974 -240.916968)
		(mid 143.739736 -240.871352)
		(end 143.922242 -240.921794)
		(width 0.0889)
		(layer "In13.Cu")
		(net "M_H_CPU1_SA_DQ<27>")
	)
	(arc
		(start 136.40181 -240.921794)
		(mid 136.684766 -240.997971)
		(end 136.967722 -240.921794)
		(width 0.0889)
		(layer "In13.Cu")
		(net "M_H_CPU1_SA_DQ<27>")
	)
	(arc
		(start 142.04188 -240.921794)
		(mid 142.324836 -240.997971)
		(end 142.607792 -240.921794)
		(width 0.0889)
		(layer "In13.Cu")
		(net "M_H_CPU1_SA_DQ<27>")
	)
	(arc
		(start 137.916158 -240.916968)
		(mid 138.099666 -240.871474)
		(end 138.281918 -240.921794)
		(width 0.0889)
		(layer "In13.Cu")
		(net "M_H_CPU1_SA_DQ<27>")
	)
	(arc
		(start 139.221718 -240.921794)
		(mid 139.504674 -240.997971)
		(end 139.78763 -240.921794)
		(width 0.0889)
		(layer "In13.Cu")
		(net "M_H_CPU1_SA_DQ<27>")
	)
	(arc
		(start 137.341864 -240.921794)
		(mid 137.62482 -240.997971)
		(end 137.907776 -240.921794)
		(width 0.0889)
		(layer "In13.Cu")
		(net "M_H_CPU1_SA_DQ<27>")
	)
	(arc
		(start 138.281918 -240.921794)
		(mid 138.564874 -240.997971)
		(end 138.84783 -240.921794)
		(width 0.0889)
		(layer "In13.Cu")
		(net "M_H_CPU1_SA_DQ<27>")
	)
	(arc
		(start 141.101826 -240.921794)
		(mid 141.384782 -240.997971)
		(end 141.667738 -240.921794)
		(width 0.0889)
		(layer "In13.Cu")
		(net "M_H_CPU1_SA_DQ<27>")
	)
	(arc
		(start 141.67612 -240.916968)
		(mid 141.859628 -240.871474)
		(end 142.04188 -240.921794)
		(width 0.0889)
		(layer "In13.Cu")
		(net "M_H_CPU1_SA_DQ<27>")
	)
	(arc
		(start 142.98168 -240.921794)
		(mid 143.264636 -240.997971)
		(end 143.547592 -240.921794)
		(width 0.0889)
		(layer "In13.Cu")
		(net "M_H_CPU1_SA_DQ<27>")
	)
	(arc
		(start 135.087614 -240.921794)
		(mid 135.269865 -240.871444)
		(end 135.453374 -240.916968)
		(width 0.0889)
		(layer "In13.Cu")
		(net "M_H_CPU1_SA_DQ<27>")
	)
	(arc
		(start 140.727684 -240.921794)
		(mid 140.909935 -240.871444)
		(end 141.093444 -240.916968)
		(width 0.0889)
		(layer "In13.Cu")
		(net "M_H_CPU1_SA_DQ<27>")
	)
	(arc
		(start 136.976104 -240.916968)
		(mid 137.159612 -240.871474)
		(end 137.341864 -240.921794)
		(width 0.0889)
		(layer "In13.Cu")
		(net "M_H_CPU1_SA_DQ<27>")
	)
	(arc
		(start 144.488662 -240.921794)
		(mid 144.667649 -240.871624)
		(end 144.84858 -240.914174)
		(width 0.0889)
		(layer "In13.Cu")
		(net "M_H_CPU1_SA_DQ<27>")
	)
	(arc
		(start 136.027668 -240.921794)
		(mid 136.209919 -240.871444)
		(end 136.393428 -240.916968)
		(width 0.0889)
		(layer "In13.Cu")
		(net "M_H_CPU1_SA_DQ<27>")
	)
	(arc
		(start 143.922242 -240.921794)
		(mid 144.196948 -240.998158)
		(end 144.47393 -240.93043)
		(width 0.0889)
		(layer "In13.Cu")
		(net "M_H_CPU1_SA_DQ<27>")
	)
	(arc
		(start 142.607792 -240.921794)
		(mid 142.794736 -240.871539)
		(end 142.98168 -240.921794)
		(width 0.0889)
		(layer "In13.Cu")
		(net "M_H_CPU1_SA_DQ<27>")
	)
	(segment
		(start 135.27786 -240.700306)
		(end 135.744712 -240.434368)
		(width 0.10668)
		(layer "F.Cu")
		(net "M_H_CPU1_SA_DQ<26>")
	)
	(segment
		(start 162.121342 -226.615244)
		(end 161.916618 -226.615244)
		(width 0.14478)
		(layer "In13.Cu")
		(net "M_H_CPU1_SA_DQ<26>")
	)
	(segment
		(start 144.958054 -240.111788)
		(end 144.94764 -240.117884)
		(width 0.0889)
		(layer "In13.Cu")
		(net "M_H_CPU1_SA_DQ<26>")
	)
	(segment
		(start 159.782002 -228.954584)
		(end 159.577278 -228.954584)
		(width 0.14478)
		(layer "In13.Cu")
		(net "M_H_CPU1_SA_DQ<26>")
	)
	(segment
		(start 165.37559 -226.349306)
		(end 165.135306 -226.349306)
		(width 0.14478)
		(layer "In13.Cu")
		(net "M_H_CPU1_SA_DQ<26>")
	)
	(segment
		(start 146.558508 -239.251744)
		(end 145.637504 -240.172748)
		(width 0.0889)
		(layer "In13.Cu")
		(net "M_H_CPU1_SA_DQ<26>")
	)
	(segment
		(start 145.393156 -240.172748)
		(end 145.332196 -240.111788)
		(width 0.0889)
		(layer "In13.Cu")
		(net "M_H_CPU1_SA_DQ<26>")
	)
	(segment
		(start 143.462248 -240.117884)
		(end 143.451834 -240.111788)
		(width 0.0889)
		(layer "In13.Cu")
		(net "M_H_CPU1_SA_DQ<26>")
	)
	(segment
		(start 147.615148 -238.802164)
		(end 147.165568 -239.251744)
		(width 0.0889)
		(layer "In13.Cu")
		(net "M_H_CPU1_SA_DQ<26>")
	)
	(segment
		(start 160.010094 -229.182676)
		(end 159.782002 -228.954584)
		(width 0.14478)
		(layer "In13.Cu")
		(net "M_H_CPU1_SA_DQ<26>")
	)
	(segment
		(start 159.392112 -229.13975)
		(end 159.392112 -229.344474)
		(width 0.14478)
		(layer "In13.Cu")
		(net "M_H_CPU1_SA_DQ<26>")
	)
	(segment
		(start 162.737038 -226.660456)
		(end 162.554158 -226.843336)
		(width 0.14478)
		(layer "In13.Cu")
		(net "M_H_CPU1_SA_DQ<26>")
	)
	(segment
		(start 160.994598 -228.402896)
		(end 160.789874 -228.402896)
		(width 0.14478)
		(layer "In13.Cu")
		(net "M_H_CPU1_SA_DQ<26>")
	)
	(segment
		(start 161.959544 -227.233226)
		(end 161.959544 -227.43795)
		(width 0.14478)
		(layer "In13.Cu")
		(net "M_H_CPU1_SA_DQ<26>")
	)
	(segment
		(start 161.916618 -226.615244)
		(end 161.731452 -226.80041)
		(width 0.14478)
		(layer "In13.Cu")
		(net "M_H_CPU1_SA_DQ<26>")
	)
	(segment
		(start 147.945094 -238.802164)
		(end 147.615148 -238.802164)
		(width 0.0889)
		(layer "In13.Cu")
		(net "M_H_CPU1_SA_DQ<26>")
	)
	(segment
		(start 171.97197 -226.240086)
		(end 171.5516 -226.660456)
		(width 0.14478)
		(layer "In13.Cu")
		(net "M_H_CPU1_SA_DQ<26>")
	)
	(segment
		(start 161.341562 -227.395024)
		(end 161.136838 -227.395024)
		(width 0.14478)
		(layer "In13.Cu")
		(net "M_H_CPU1_SA_DQ<26>")
	)
	(segment
		(start 160.399984 -228.792786)
		(end 160.399984 -228.99751)
		(width 0.14478)
		(layer "In13.Cu")
		(net "M_H_CPU1_SA_DQ<26>")
	)
	(segment
		(start 164.032438 -226.349306)
		(end 163.721288 -226.660456)
		(width 0.14478)
		(layer "In13.Cu")
		(net "M_H_CPU1_SA_DQ<26>")
	)
	(segment
		(start 163.721288 -226.660456)
		(end 162.737038 -226.660456)
		(width 0.14478)
		(layer "In13.Cu")
		(net "M_H_CPU1_SA_DQ<26>")
	)
	(segment
		(start 160.171892 -228.564694)
		(end 160.399984 -228.792786)
		(width 0.14478)
		(layer "In13.Cu")
		(net "M_H_CPU1_SA_DQ<26>")
	)
	(segment
		(start 171.5516 -226.660456)
		(end 170.792394 -226.660456)
		(width 0.14478)
		(layer "In13.Cu")
		(net "M_H_CPU1_SA_DQ<26>")
	)
	(segment
		(start 164.824156 -226.660456)
		(end 164.583872 -226.660456)
		(width 0.14478)
		(layer "In13.Cu")
		(net "M_H_CPU1_SA_DQ<26>")
	)
	(segment
		(start 162.349434 -226.843336)
		(end 162.121342 -226.615244)
		(width 0.14478)
		(layer "In13.Cu")
		(net "M_H_CPU1_SA_DQ<26>")
	)
	(segment
		(start 144.972532 -240.103406)
		(end 144.958054 -240.111788)
		(width 0.0889)
		(layer "In13.Cu")
		(net "M_H_CPU1_SA_DQ<26>")
	)
	(segment
		(start 160.357058 -228.174804)
		(end 160.171892 -228.35997)
		(width 0.14478)
		(layer "In13.Cu")
		(net "M_H_CPU1_SA_DQ<26>")
	)
	(segment
		(start 161.774378 -227.623116)
		(end 161.569654 -227.623116)
		(width 0.14478)
		(layer "In13.Cu")
		(net "M_H_CPU1_SA_DQ<26>")
	)
	(segment
		(start 160.951672 -227.784914)
		(end 161.179764 -228.013006)
		(width 0.14478)
		(layer "In13.Cu")
		(net "M_H_CPU1_SA_DQ<26>")
	)
	(segment
		(start 135.995156 -240.143538)
		(end 135.89889 -240.168938)
		(width 0.0889)
		(layer "In13.Cu")
		(net "M_H_CPU1_SA_DQ<26>")
	)
	(segment
		(start 167.149526 -225.810318)
		(end 166.299388 -226.660456)
		(width 0.14478)
		(layer "In13.Cu")
		(net "M_H_CPU1_SA_DQ<26>")
	)
	(segment
		(start 164.272722 -226.349306)
		(end 164.032438 -226.349306)
		(width 0.14478)
		(layer "In13.Cu")
		(net "M_H_CPU1_SA_DQ<26>")
	)
	(segment
		(start 166.299388 -226.660456)
		(end 165.68674 -226.660456)
		(width 0.14478)
		(layer "In13.Cu")
		(net "M_H_CPU1_SA_DQ<26>")
	)
	(segment
		(start 135.89889 -240.168938)
		(end 135.744712 -240.434368)
		(width 0.0889)
		(layer "In13.Cu")
		(net "M_H_CPU1_SA_DQ<26>")
	)
	(segment
		(start 160.789874 -228.402896)
		(end 160.561782 -228.174804)
		(width 0.14478)
		(layer "In13.Cu")
		(net "M_H_CPU1_SA_DQ<26>")
	)
	(segment
		(start 161.179764 -228.21773)
		(end 160.994598 -228.402896)
		(width 0.14478)
		(layer "In13.Cu")
		(net "M_H_CPU1_SA_DQ<26>")
	)
	(segment
		(start 160.399984 -228.99751)
		(end 160.214818 -229.182676)
		(width 0.14478)
		(layer "In13.Cu")
		(net "M_H_CPU1_SA_DQ<26>")
	)
	(segment
		(start 171.97197 -226.23526)
		(end 171.97197 -226.240086)
		(width 0.14478)
		(layer "In13.Cu")
		(net "M_H_CPU1_SA_DQ<26>")
	)
	(segment
		(start 137.811764 -240.111788)
		(end 137.803382 -240.106962)
		(width 0.0889)
		(layer "In13.Cu")
		(net "M_H_CPU1_SA_DQ<26>")
	)
	(segment
		(start 160.214818 -229.182676)
		(end 160.010094 -229.182676)
		(width 0.14478)
		(layer "In13.Cu")
		(net "M_H_CPU1_SA_DQ<26>")
	)
	(segment
		(start 159.392112 -229.344474)
		(end 159.620204 -229.572566)
		(width 0.14478)
		(layer "In13.Cu")
		(net "M_H_CPU1_SA_DQ<26>")
	)
	(segment
		(start 161.731452 -227.005134)
		(end 161.959544 -227.233226)
		(width 0.14478)
		(layer "In13.Cu")
		(net "M_H_CPU1_SA_DQ<26>")
	)
	(segment
		(start 161.959544 -227.43795)
		(end 161.774378 -227.623116)
		(width 0.14478)
		(layer "In13.Cu")
		(net "M_H_CPU1_SA_DQ<26>")
	)
	(segment
		(start 161.731452 -226.80041)
		(end 161.731452 -227.005134)
		(width 0.14478)
		(layer "In13.Cu")
		(net "M_H_CPU1_SA_DQ<26>")
	)
	(segment
		(start 140.266166 -240.106962)
		(end 140.257784 -240.111788)
		(width 0.0889)
		(layer "In13.Cu")
		(net "M_H_CPU1_SA_DQ<26>")
	)
	(segment
		(start 159.577278 -228.954584)
		(end 159.392112 -229.13975)
		(width 0.14478)
		(layer "In13.Cu")
		(net "M_H_CPU1_SA_DQ<26>")
	)
	(segment
		(start 159.620204 -229.77729)
		(end 150.59533 -238.802164)
		(width 0.14478)
		(layer "In13.Cu")
		(net "M_H_CPU1_SA_DQ<26>")
	)
	(segment
		(start 170.792394 -226.660456)
		(end 169.942256 -225.810318)
		(width 0.14478)
		(layer "In13.Cu")
		(net "M_H_CPU1_SA_DQ<26>")
	)
	(segment
		(start 145.637504 -240.172748)
		(end 145.393156 -240.172748)
		(width 0.0889)
		(layer "In13.Cu")
		(net "M_H_CPU1_SA_DQ<26>")
	)
	(segment
		(start 165.68674 -226.660456)
		(end 165.37559 -226.349306)
		(width 0.14478)
		(layer "In13.Cu")
		(net "M_H_CPU1_SA_DQ<26>")
	)
	(segment
		(start 161.136838 -227.395024)
		(end 160.951672 -227.58019)
		(width 0.14478)
		(layer "In13.Cu")
		(net "M_H_CPU1_SA_DQ<26>")
	)
	(segment
		(start 169.942256 -225.810318)
		(end 167.149526 -225.810318)
		(width 0.14478)
		(layer "In13.Cu")
		(net "M_H_CPU1_SA_DQ<26>")
	)
	(segment
		(start 143.086074 -240.106962)
		(end 143.077692 -240.111788)
		(width 0.0889)
		(layer "In13.Cu")
		(net "M_H_CPU1_SA_DQ<26>")
	)
	(segment
		(start 161.179764 -228.013006)
		(end 161.179764 -228.21773)
		(width 0.14478)
		(layer "In13.Cu")
		(net "M_H_CPU1_SA_DQ<26>")
	)
	(segment
		(start 161.569654 -227.623116)
		(end 161.341562 -227.395024)
		(width 0.14478)
		(layer "In13.Cu")
		(net "M_H_CPU1_SA_DQ<26>")
	)
	(segment
		(start 160.171892 -228.35997)
		(end 160.171892 -228.564694)
		(width 0.14478)
		(layer "In13.Cu")
		(net "M_H_CPU1_SA_DQ<26>")
	)
	(segment
		(start 139.326112 -240.106962)
		(end 139.31773 -240.111788)
		(width 0.0889)
		(layer "In13.Cu")
		(net "M_H_CPU1_SA_DQ<26>")
	)
	(segment
		(start 138.751818 -240.111788)
		(end 138.743436 -240.106962)
		(width 0.0889)
		(layer "In13.Cu")
		(net "M_H_CPU1_SA_DQ<26>")
	)
	(segment
		(start 165.135306 -226.349306)
		(end 164.824156 -226.660456)
		(width 0.14478)
		(layer "In13.Cu")
		(net "M_H_CPU1_SA_DQ<26>")
	)
	(segment
		(start 160.951672 -227.58019)
		(end 160.951672 -227.784914)
		(width 0.14478)
		(layer "In13.Cu")
		(net "M_H_CPU1_SA_DQ<26>")
	)
	(segment
		(start 142.51178 -240.111788)
		(end 142.503398 -240.106962)
		(width 0.0889)
		(layer "In13.Cu")
		(net "M_H_CPU1_SA_DQ<26>")
	)
	(segment
		(start 162.554158 -226.843336)
		(end 162.349434 -226.843336)
		(width 0.14478)
		(layer "In13.Cu")
		(net "M_H_CPU1_SA_DQ<26>")
	)
	(segment
		(start 150.59533 -238.802164)
		(end 147.945094 -238.802164)
		(width 0.14478)
		(layer "In13.Cu")
		(net "M_H_CPU1_SA_DQ<26>")
	)
	(segment
		(start 147.165568 -239.251744)
		(end 146.558508 -239.251744)
		(width 0.0889)
		(layer "In13.Cu")
		(net "M_H_CPU1_SA_DQ<26>")
	)
	(segment
		(start 160.561782 -228.174804)
		(end 160.357058 -228.174804)
		(width 0.14478)
		(layer "In13.Cu")
		(net "M_H_CPU1_SA_DQ<26>")
	)
	(segment
		(start 164.583872 -226.660456)
		(end 164.272722 -226.349306)
		(width 0.14478)
		(layer "In13.Cu")
		(net "M_H_CPU1_SA_DQ<26>")
	)
	(segment
		(start 159.620204 -229.572566)
		(end 159.620204 -229.77729)
		(width 0.14478)
		(layer "In13.Cu")
		(net "M_H_CPU1_SA_DQ<26>")
	)
	(arc
		(start 139.691872 -240.111788)
		(mid 139.509621 -240.061438)
		(end 139.326112 -240.106962)
		(width 0.0889)
		(layer "In13.Cu")
		(net "M_H_CPU1_SA_DQ<26>")
	)
	(arc
		(start 138.377676 -240.111788)
		(mid 138.09472 -240.187965)
		(end 137.811764 -240.111788)
		(width 0.0889)
		(layer "In13.Cu")
		(net "M_H_CPU1_SA_DQ<26>")
	)
	(arc
		(start 138.743436 -240.106962)
		(mid 138.559928 -240.061468)
		(end 138.377676 -240.111788)
		(width 0.0889)
		(layer "In13.Cu")
		(net "M_H_CPU1_SA_DQ<26>")
	)
	(arc
		(start 143.077692 -240.111788)
		(mid 142.794736 -240.187965)
		(end 142.51178 -240.111788)
		(width 0.0889)
		(layer "In13.Cu")
		(net "M_H_CPU1_SA_DQ<26>")
	)
	(arc
		(start 139.31773 -240.111788)
		(mid 139.034774 -240.187965)
		(end 138.751818 -240.111788)
		(width 0.0889)
		(layer "In13.Cu")
		(net "M_H_CPU1_SA_DQ<26>")
	)
	(arc
		(start 145.332196 -240.111788)
		(mid 145.153441 -240.061379)
		(end 144.972532 -240.103406)
		(width 0.0889)
		(layer "In13.Cu")
		(net "M_H_CPU1_SA_DQ<26>")
	)
	(arc
		(start 141.571726 -240.111788)
		(mid 141.384782 -240.061533)
		(end 141.197838 -240.111788)
		(width 0.0889)
		(layer "In13.Cu")
		(net "M_H_CPU1_SA_DQ<26>")
	)
	(arc
		(start 137.803382 -240.106962)
		(mid 137.619874 -240.061468)
		(end 137.437622 -240.111788)
		(width 0.0889)
		(layer "In13.Cu")
		(net "M_H_CPU1_SA_DQ<26>")
	)
	(arc
		(start 137.437622 -240.111788)
		(mid 137.154666 -240.187965)
		(end 136.87171 -240.111788)
		(width 0.0889)
		(layer "In13.Cu")
		(net "M_H_CPU1_SA_DQ<26>")
	)
	(arc
		(start 141.197838 -240.111788)
		(mid 140.914882 -240.187965)
		(end 140.631926 -240.111788)
		(width 0.0889)
		(layer "In13.Cu")
		(net "M_H_CPU1_SA_DQ<26>")
	)
	(arc
		(start 142.137638 -240.111788)
		(mid 141.854682 -240.187965)
		(end 141.571726 -240.111788)
		(width 0.0889)
		(layer "In13.Cu")
		(net "M_H_CPU1_SA_DQ<26>")
	)
	(arc
		(start 144.392396 -240.111788)
		(mid 144.205198 -240.061406)
		(end 144.018 -240.111788)
		(width 0.0889)
		(layer "In13.Cu")
		(net "M_H_CPU1_SA_DQ<26>")
	)
	(arc
		(start 143.451834 -240.111788)
		(mid 143.269583 -240.061438)
		(end 143.086074 -240.106962)
		(width 0.0889)
		(layer "In13.Cu")
		(net "M_H_CPU1_SA_DQ<26>")
	)
	(arc
		(start 136.497822 -240.111788)
		(mid 136.250226 -240.186966)
		(end 135.995156 -240.143538)
		(width 0.0889)
		(layer "In13.Cu")
		(net "M_H_CPU1_SA_DQ<26>")
	)
	(arc
		(start 136.87171 -240.111788)
		(mid 136.684766 -240.061533)
		(end 136.497822 -240.111788)
		(width 0.0889)
		(layer "In13.Cu")
		(net "M_H_CPU1_SA_DQ<26>")
	)
	(arc
		(start 144.018 -240.111788)
		(mid 143.740933 -240.188059)
		(end 143.462248 -240.117884)
		(width 0.0889)
		(layer "In13.Cu")
		(net "M_H_CPU1_SA_DQ<26>")
	)
	(arc
		(start 142.503398 -240.106962)
		(mid 142.31989 -240.061468)
		(end 142.137638 -240.111788)
		(width 0.0889)
		(layer "In13.Cu")
		(net "M_H_CPU1_SA_DQ<26>")
	)
	(arc
		(start 144.94764 -240.117884)
		(mid 144.669208 -240.187982)
		(end 144.392396 -240.111788)
		(width 0.0889)
		(layer "In13.Cu")
		(net "M_H_CPU1_SA_DQ<26>")
	)
	(arc
		(start 140.631926 -240.111788)
		(mid 140.449675 -240.061438)
		(end 140.266166 -240.106962)
		(width 0.0889)
		(layer "In13.Cu")
		(net "M_H_CPU1_SA_DQ<26>")
	)
	(arc
		(start 140.257784 -240.111788)
		(mid 139.974828 -240.187965)
		(end 139.691872 -240.111788)
		(width 0.0889)
		(layer "In13.Cu")
		(net "M_H_CPU1_SA_DQ<26>")
	)
	(segment
		(start 134.337806 -240.700306)
		(end 134.804658 -240.434368)
		(width 0.10668)
		(layer "F.Cu")
		(net "M_H_CPU1_SA_DQ<25>")
	)
	(segment
		(start 143.077692 -240.756948)
		(end 143.086074 -240.761774)
		(width 0.0889)
		(layer "In13.Cu")
		(net "M_H_CPU1_SA_DQ<25>")
	)
	(segment
		(start 144.380966 -240.763806)
		(end 144.39265 -240.756948)
		(width 0.0889)
		(layer "In13.Cu")
		(net "M_H_CPU1_SA_DQ<25>")
	)
	(segment
		(start 144.958054 -240.756694)
		(end 144.976342 -240.767108)
		(width 0.0889)
		(layer "In13.Cu")
		(net "M_H_CPU1_SA_DQ<25>")
	)
	(segment
		(start 143.451834 -240.756948)
		(end 143.466566 -240.748312)
		(width 0.0889)
		(layer "In13.Cu")
		(net "M_H_CPU1_SA_DQ<25>")
	)
	(segment
		(start 134.650734 -240.699798)
		(end 134.673086 -240.78311)
		(width 0.0889)
		(layer "In13.Cu")
		(net "M_H_CPU1_SA_DQ<25>")
	)
	(segment
		(start 162.129978 -227.910898)
		(end 164.737542 -227.910898)
		(width 0.14478)
		(layer "In13.Cu")
		(net "M_H_CPU1_SA_DQ<25>")
	)
	(segment
		(start 145.667984 -240.756948)
		(end 146.385788 -240.039144)
		(width 0.0889)
		(layer "In13.Cu")
		(net "M_H_CPU1_SA_DQ<25>")
	)
	(segment
		(start 147.903438 -239.256824)
		(end 150.784052 -239.256824)
		(width 0.14478)
		(layer "In13.Cu")
		(net "M_H_CPU1_SA_DQ<25>")
	)
	(segment
		(start 164.737542 -227.910898)
		(end 166.789862 -227.06076)
		(width 0.14478)
		(layer "In13.Cu")
		(net "M_H_CPU1_SA_DQ<25>")
	)
	(segment
		(start 137.803382 -240.761774)
		(end 137.811764 -240.756948)
		(width 0.0889)
		(layer "In13.Cu")
		(net "M_H_CPU1_SA_DQ<25>")
	)
	(segment
		(start 140.257784 -240.756948)
		(end 140.266166 -240.761774)
		(width 0.0889)
		(layer "In13.Cu")
		(net "M_H_CPU1_SA_DQ<25>")
	)
	(segment
		(start 147.404328 -239.520984)
		(end 147.668488 -239.256824)
		(width 0.0889)
		(layer "In13.Cu")
		(net "M_H_CPU1_SA_DQ<25>")
	)
	(segment
		(start 170.289474 -227.06076)
		(end 171.374816 -227.51034)
		(width 0.14478)
		(layer "In13.Cu")
		(net "M_H_CPU1_SA_DQ<25>")
	)
	(segment
		(start 139.31773 -240.756948)
		(end 139.326112 -240.761774)
		(width 0.0889)
		(layer "In13.Cu")
		(net "M_H_CPU1_SA_DQ<25>")
	)
	(segment
		(start 150.784052 -239.256824)
		(end 162.129978 -227.910898)
		(width 0.14478)
		(layer "In13.Cu")
		(net "M_H_CPU1_SA_DQ<25>")
	)
	(segment
		(start 144.952466 -240.753392)
		(end 144.958054 -240.756694)
		(width 0.0889)
		(layer "In13.Cu")
		(net "M_H_CPU1_SA_DQ<25>")
	)
	(segment
		(start 142.503398 -240.761774)
		(end 142.51178 -240.756948)
		(width 0.0889)
		(layer "In13.Cu")
		(net "M_H_CPU1_SA_DQ<25>")
	)
	(segment
		(start 145.332196 -240.756948)
		(end 145.667984 -240.756948)
		(width 0.0889)
		(layer "In13.Cu")
		(net "M_H_CPU1_SA_DQ<25>")
	)
	(segment
		(start 173.935136 -227.51034)
		(end 176.072038 -227.085398)
		(width 0.14478)
		(layer "In13.Cu")
		(net "M_H_CPU1_SA_DQ<25>")
	)
	(segment
		(start 138.743436 -240.761774)
		(end 138.751818 -240.756948)
		(width 0.0889)
		(layer "In13.Cu")
		(net "M_H_CPU1_SA_DQ<25>")
	)
	(segment
		(start 171.374816 -227.51034)
		(end 173.935136 -227.51034)
		(width 0.14478)
		(layer "In13.Cu")
		(net "M_H_CPU1_SA_DQ<25>")
	)
	(segment
		(start 134.804658 -240.434368)
		(end 134.650734 -240.699798)
		(width 0.0889)
		(layer "In13.Cu")
		(net "M_H_CPU1_SA_DQ<25>")
	)
	(segment
		(start 147.668488 -239.256824)
		(end 147.903438 -239.256824)
		(width 0.0889)
		(layer "In13.Cu")
		(net "M_H_CPU1_SA_DQ<25>")
	)
	(segment
		(start 146.596608 -239.520984)
		(end 147.404328 -239.520984)
		(width 0.0889)
		(layer "In13.Cu")
		(net "M_H_CPU1_SA_DQ<25>")
	)
	(segment
		(start 166.789862 -227.06076)
		(end 170.289474 -227.06076)
		(width 0.14478)
		(layer "In13.Cu")
		(net "M_H_CPU1_SA_DQ<25>")
	)
	(segment
		(start 135.557768 -240.756948)
		(end 135.56615 -240.761774)
		(width 0.0889)
		(layer "In13.Cu")
		(net "M_H_CPU1_SA_DQ<25>")
	)
	(segment
		(start 146.385788 -239.731804)
		(end 146.596608 -239.520984)
		(width 0.0889)
		(layer "In13.Cu")
		(net "M_H_CPU1_SA_DQ<25>")
	)
	(segment
		(start 146.385788 -240.039144)
		(end 146.385788 -239.731804)
		(width 0.0889)
		(layer "In13.Cu")
		(net "M_H_CPU1_SA_DQ<25>")
	)
	(arc
		(start 142.51178 -240.756948)
		(mid 142.794736 -240.680771)
		(end 143.077692 -240.756948)
		(width 0.0889)
		(layer "In13.Cu")
		(net "M_H_CPU1_SA_DQ<25>")
	)
	(arc
		(start 136.87171 -240.756948)
		(mid 137.154666 -240.680771)
		(end 137.437622 -240.756948)
		(width 0.0889)
		(layer "In13.Cu")
		(net "M_H_CPU1_SA_DQ<25>")
	)
	(arc
		(start 141.197838 -240.756948)
		(mid 141.384782 -240.807203)
		(end 141.571726 -240.756948)
		(width 0.0889)
		(layer "In13.Cu")
		(net "M_H_CPU1_SA_DQ<25>")
	)
	(arc
		(start 143.466566 -240.748312)
		(mid 143.743549 -240.680508)
		(end 144.018254 -240.756948)
		(width 0.0889)
		(layer "In13.Cu")
		(net "M_H_CPU1_SA_DQ<25>")
	)
	(arc
		(start 141.571726 -240.756948)
		(mid 141.854682 -240.680771)
		(end 142.137638 -240.756948)
		(width 0.0889)
		(layer "In13.Cu")
		(net "M_H_CPU1_SA_DQ<25>")
	)
	(arc
		(start 144.976342 -240.767108)
		(mid 145.155571 -240.807261)
		(end 145.332196 -240.756948)
		(width 0.0889)
		(layer "In13.Cu")
		(net "M_H_CPU1_SA_DQ<25>")
	)
	(arc
		(start 138.377676 -240.756948)
		(mid 138.559927 -240.807298)
		(end 138.743436 -240.761774)
		(width 0.0889)
		(layer "In13.Cu")
		(net "M_H_CPU1_SA_DQ<25>")
	)
	(arc
		(start 135.93191 -240.756948)
		(mid 136.214866 -240.680771)
		(end 136.497822 -240.756948)
		(width 0.0889)
		(layer "In13.Cu")
		(net "M_H_CPU1_SA_DQ<25>")
	)
	(arc
		(start 139.691872 -240.756948)
		(mid 139.974828 -240.680771)
		(end 140.257784 -240.756948)
		(width 0.0889)
		(layer "In13.Cu")
		(net "M_H_CPU1_SA_DQ<25>")
	)
	(arc
		(start 144.018254 -240.756948)
		(mid 144.198712 -240.807392)
		(end 144.380966 -240.763806)
		(width 0.0889)
		(layer "In13.Cu")
		(net "M_H_CPU1_SA_DQ<25>")
	)
	(arc
		(start 137.437622 -240.756948)
		(mid 137.619873 -240.807298)
		(end 137.803382 -240.761774)
		(width 0.0889)
		(layer "In13.Cu")
		(net "M_H_CPU1_SA_DQ<25>")
	)
	(arc
		(start 138.751818 -240.756948)
		(mid 139.034774 -240.680771)
		(end 139.31773 -240.756948)
		(width 0.0889)
		(layer "In13.Cu")
		(net "M_H_CPU1_SA_DQ<25>")
	)
	(arc
		(start 144.39265 -240.756948)
		(mid 144.672078 -240.680782)
		(end 144.952466 -240.753392)
		(width 0.0889)
		(layer "In13.Cu")
		(net "M_H_CPU1_SA_DQ<25>")
	)
	(arc
		(start 136.497822 -240.756948)
		(mid 136.684766 -240.807203)
		(end 136.87171 -240.756948)
		(width 0.0889)
		(layer "In13.Cu")
		(net "M_H_CPU1_SA_DQ<25>")
	)
	(arc
		(start 140.631926 -240.756948)
		(mid 140.914882 -240.680771)
		(end 141.197838 -240.756948)
		(width 0.0889)
		(layer "In13.Cu")
		(net "M_H_CPU1_SA_DQ<25>")
	)
	(arc
		(start 139.326112 -240.761774)
		(mid 139.50962 -240.807268)
		(end 139.691872 -240.756948)
		(width 0.0889)
		(layer "In13.Cu")
		(net "M_H_CPU1_SA_DQ<25>")
	)
	(arc
		(start 142.137638 -240.756948)
		(mid 142.319889 -240.807298)
		(end 142.503398 -240.761774)
		(width 0.0889)
		(layer "In13.Cu")
		(net "M_H_CPU1_SA_DQ<25>")
	)
	(arc
		(start 134.673086 -240.78311)
		(mid 134.835418 -240.805928)
		(end 134.991856 -240.756948)
		(width 0.0889)
		(layer "In13.Cu")
		(net "M_H_CPU1_SA_DQ<25>")
	)
	(arc
		(start 135.56615 -240.761774)
		(mid 135.749658 -240.807268)
		(end 135.93191 -240.756948)
		(width 0.0889)
		(layer "In13.Cu")
		(net "M_H_CPU1_SA_DQ<25>")
	)
	(arc
		(start 143.086074 -240.761774)
		(mid 143.269582 -240.807268)
		(end 143.451834 -240.756948)
		(width 0.0889)
		(layer "In13.Cu")
		(net "M_H_CPU1_SA_DQ<25>")
	)
	(arc
		(start 140.266166 -240.761774)
		(mid 140.449674 -240.807268)
		(end 140.631926 -240.756948)
		(width 0.0889)
		(layer "In13.Cu")
		(net "M_H_CPU1_SA_DQ<25>")
	)
	(arc
		(start 134.991856 -240.756948)
		(mid 135.274812 -240.680771)
		(end 135.557768 -240.756948)
		(width 0.0889)
		(layer "In13.Cu")
		(net "M_H_CPU1_SA_DQ<25>")
	)
	(arc
		(start 137.811764 -240.756948)
		(mid 138.09472 -240.680771)
		(end 138.377676 -240.756948)
		(width 0.0889)
		(layer "In13.Cu")
		(net "M_H_CPU1_SA_DQ<25>")
	)
	(segment
		(start 135.748014 -239.8903)
		(end 136.214866 -239.624362)
		(width 0.10668)
		(layer "F.Cu")
		(net "M_H_CPU1_SA_DQ<24>")
	)
	(segment
		(start 137.907776 -239.946942)
		(end 137.916158 -239.951768)
		(width 0.0889)
		(layer "In13.Cu")
		(net "M_H_CPU1_SA_DQ<24>")
	)
	(segment
		(start 140.15339 -239.951768)
		(end 140.161772 -239.946942)
		(width 0.0889)
		(layer "In13.Cu")
		(net "M_H_CPU1_SA_DQ<24>")
	)
	(segment
		(start 144.47774 -239.940846)
		(end 144.488154 -239.946942)
		(width 0.0889)
		(layer "In13.Cu")
		(net "M_H_CPU1_SA_DQ<24>")
	)
	(segment
		(start 141.667738 -239.946942)
		(end 141.67612 -239.951768)
		(width 0.0889)
		(layer "In13.Cu")
		(net "M_H_CPU1_SA_DQ<24>")
	)
	(segment
		(start 169.776902 -224.960434)
		(end 170.626786 -225.810318)
		(width 0.14478)
		(layer "In13.Cu")
		(net "M_H_CPU1_SA_DQ<24>")
	)
	(segment
		(start 173.684946 -225.810318)
		(end 174.109888 -225.385376)
		(width 0.14478)
		(layer "In13.Cu")
		(net "M_H_CPU1_SA_DQ<24>")
	)
	(segment
		(start 158.813754 -229.05974)
		(end 162.063176 -225.810318)
		(width 0.14478)
		(layer "In13.Cu")
		(net "M_H_CPU1_SA_DQ<24>")
	)
	(segment
		(start 147.95881 -238.347504)
		(end 150.407878 -238.347504)
		(width 0.14478)
		(layer "In13.Cu")
		(net "M_H_CPU1_SA_DQ<24>")
	)
	(segment
		(start 144.862042 -239.946942)
		(end 144.876774 -239.938306)
		(width 0.0889)
		(layer "In13.Cu")
		(net "M_H_CPU1_SA_DQ<24>")
	)
	(segment
		(start 145.427954 -239.946942)
		(end 145.51787 -239.946942)
		(width 0.0889)
		(layer "In13.Cu")
		(net "M_H_CPU1_SA_DQ<24>")
	)
	(segment
		(start 136.393428 -239.951768)
		(end 136.40181 -239.946942)
		(width 0.0889)
		(layer "In13.Cu")
		(net "M_H_CPU1_SA_DQ<24>")
	)
	(segment
		(start 170.626786 -225.810318)
		(end 173.684946 -225.810318)
		(width 0.14478)
		(layer "In13.Cu")
		(net "M_H_CPU1_SA_DQ<24>")
	)
	(segment
		(start 158.813754 -229.941628)
		(end 158.813754 -229.05974)
		(width 0.14478)
		(layer "In13.Cu")
		(net "M_H_CPU1_SA_DQ<24>")
	)
	(segment
		(start 146.454368 -239.010444)
		(end 146.934428 -239.010444)
		(width 0.0889)
		(layer "In13.Cu")
		(net "M_H_CPU1_SA_DQ<24>")
	)
	(segment
		(start 136.214866 -239.624362)
		(end 136.060688 -239.889792)
		(width 0.0889)
		(layer "In13.Cu")
		(net "M_H_CPU1_SA_DQ<24>")
	)
	(segment
		(start 136.060688 -239.889792)
		(end 136.08304 -239.973104)
		(width 0.0889)
		(layer "In13.Cu")
		(net "M_H_CPU1_SA_DQ<24>")
	)
	(segment
		(start 167.024304 -224.960434)
		(end 169.776902 -224.960434)
		(width 0.14478)
		(layer "In13.Cu")
		(net "M_H_CPU1_SA_DQ<24>")
	)
	(segment
		(start 150.407878 -238.347504)
		(end 158.813754 -229.941628)
		(width 0.14478)
		(layer "In13.Cu")
		(net "M_H_CPU1_SA_DQ<24>")
	)
	(segment
		(start 147.597368 -238.347504)
		(end 147.95881 -238.347504)
		(width 0.0889)
		(layer "In13.Cu")
		(net "M_H_CPU1_SA_DQ<24>")
	)
	(segment
		(start 141.093444 -239.951768)
		(end 141.101826 -239.946942)
		(width 0.0889)
		(layer "In13.Cu")
		(net "M_H_CPU1_SA_DQ<24>")
	)
	(segment
		(start 174.109888 -225.385376)
		(end 176.072038 -225.385376)
		(width 0.14478)
		(layer "In13.Cu")
		(net "M_H_CPU1_SA_DQ<24>")
	)
	(segment
		(start 144.850358 -239.9538)
		(end 144.862042 -239.946942)
		(width 0.0889)
		(layer "In13.Cu")
		(net "M_H_CPU1_SA_DQ<24>")
	)
	(segment
		(start 145.51787 -239.946942)
		(end 146.454368 -239.010444)
		(width 0.0889)
		(layer "In13.Cu")
		(net "M_H_CPU1_SA_DQ<24>")
	)
	(segment
		(start 146.934428 -239.010444)
		(end 147.597368 -238.347504)
		(width 0.0889)
		(layer "In13.Cu")
		(net "M_H_CPU1_SA_DQ<24>")
	)
	(segment
		(start 162.063176 -225.810318)
		(end 166.17442 -225.810318)
		(width 0.14478)
		(layer "In13.Cu")
		(net "M_H_CPU1_SA_DQ<24>")
	)
	(segment
		(start 136.967722 -239.946942)
		(end 136.976104 -239.951768)
		(width 0.0889)
		(layer "In13.Cu")
		(net "M_H_CPU1_SA_DQ<24>")
	)
	(segment
		(start 166.17442 -225.810318)
		(end 167.024304 -224.960434)
		(width 0.14478)
		(layer "In13.Cu")
		(net "M_H_CPU1_SA_DQ<24>")
	)
	(arc
		(start 142.607792 -239.946942)
		(mid 142.794736 -239.997197)
		(end 142.98168 -239.946942)
		(width 0.0889)
		(layer "In13.Cu")
		(net "M_H_CPU1_SA_DQ<24>")
	)
	(arc
		(start 137.341864 -239.946942)
		(mid 137.62482 -239.870765)
		(end 137.907776 -239.946942)
		(width 0.0889)
		(layer "In13.Cu")
		(net "M_H_CPU1_SA_DQ<24>")
	)
	(arc
		(start 143.547592 -239.946942)
		(mid 143.73479 -239.997324)
		(end 143.921988 -239.946942)
		(width 0.0889)
		(layer "In13.Cu")
		(net "M_H_CPU1_SA_DQ<24>")
	)
	(arc
		(start 141.101826 -239.946942)
		(mid 141.384782 -239.870765)
		(end 141.667738 -239.946942)
		(width 0.0889)
		(layer "In13.Cu")
		(net "M_H_CPU1_SA_DQ<24>")
	)
	(arc
		(start 138.281918 -239.946942)
		(mid 138.564874 -239.870765)
		(end 138.84783 -239.946942)
		(width 0.0889)
		(layer "In13.Cu")
		(net "M_H_CPU1_SA_DQ<24>")
	)
	(arc
		(start 136.976104 -239.951768)
		(mid 137.159612 -239.997262)
		(end 137.341864 -239.946942)
		(width 0.0889)
		(layer "In13.Cu")
		(net "M_H_CPU1_SA_DQ<24>")
	)
	(arc
		(start 144.488154 -239.946942)
		(mid 144.668359 -239.997259)
		(end 144.850358 -239.9538)
		(width 0.0889)
		(layer "In13.Cu")
		(net "M_H_CPU1_SA_DQ<24>")
	)
	(arc
		(start 139.78763 -239.946942)
		(mid 139.969881 -239.997292)
		(end 140.15339 -239.951768)
		(width 0.0889)
		(layer "In13.Cu")
		(net "M_H_CPU1_SA_DQ<24>")
	)
	(arc
		(start 141.67612 -239.951768)
		(mid 141.859628 -239.997262)
		(end 142.04188 -239.946942)
		(width 0.0889)
		(layer "In13.Cu")
		(net "M_H_CPU1_SA_DQ<24>")
	)
	(arc
		(start 142.98168 -239.946942)
		(mid 143.264636 -239.870765)
		(end 143.547592 -239.946942)
		(width 0.0889)
		(layer "In13.Cu")
		(net "M_H_CPU1_SA_DQ<24>")
	)
	(arc
		(start 140.727684 -239.946942)
		(mid 140.909935 -239.997292)
		(end 141.093444 -239.951768)
		(width 0.0889)
		(layer "In13.Cu")
		(net "M_H_CPU1_SA_DQ<24>")
	)
	(arc
		(start 144.876774 -239.938306)
		(mid 145.153503 -239.870623)
		(end 145.427954 -239.946942)
		(width 0.0889)
		(layer "In13.Cu")
		(net "M_H_CPU1_SA_DQ<24>")
	)
	(arc
		(start 143.921988 -239.946942)
		(mid 144.199055 -239.870671)
		(end 144.47774 -239.940846)
		(width 0.0889)
		(layer "In13.Cu")
		(net "M_H_CPU1_SA_DQ<24>")
	)
	(arc
		(start 139.221718 -239.946942)
		(mid 139.504674 -239.870765)
		(end 139.78763 -239.946942)
		(width 0.0889)
		(layer "In13.Cu")
		(net "M_H_CPU1_SA_DQ<24>")
	)
	(arc
		(start 136.08304 -239.973104)
		(mid 136.24055 -239.996302)
		(end 136.393428 -239.951768)
		(width 0.0889)
		(layer "In13.Cu")
		(net "M_H_CPU1_SA_DQ<24>")
	)
	(arc
		(start 140.161772 -239.946942)
		(mid 140.444728 -239.870765)
		(end 140.727684 -239.946942)
		(width 0.0889)
		(layer "In13.Cu")
		(net "M_H_CPU1_SA_DQ<24>")
	)
	(arc
		(start 137.916158 -239.951768)
		(mid 138.099666 -239.997262)
		(end 138.281918 -239.946942)
		(width 0.0889)
		(layer "In13.Cu")
		(net "M_H_CPU1_SA_DQ<24>")
	)
	(arc
		(start 138.84783 -239.946942)
		(mid 139.034774 -239.997197)
		(end 139.221718 -239.946942)
		(width 0.0889)
		(layer "In13.Cu")
		(net "M_H_CPU1_SA_DQ<24>")
	)
	(arc
		(start 136.40181 -239.946942)
		(mid 136.684766 -239.870765)
		(end 136.967722 -239.946942)
		(width 0.0889)
		(layer "In13.Cu")
		(net "M_H_CPU1_SA_DQ<24>")
	)
	(arc
		(start 142.04188 -239.946942)
		(mid 142.324836 -239.870765)
		(end 142.607792 -239.946942)
		(width 0.0889)
		(layer "In13.Cu")
		(net "M_H_CPU1_SA_DQ<24>")
	)
	(segment
		(start 133.867906 -239.8903)
		(end 134.334758 -239.624362)
		(width 0.10668)
		(layer "F.Cu")
		(net "M_H_CPU1_SA_DQ<23>")
	)
	(segment
		(start 150.168102 -237.787434)
		(end 147.856194 -237.787434)
		(width 0.14478)
		(layer "In13.Cu")
		(net "M_H_CPU1_SA_DQ<23>")
	)
	(segment
		(start 158.757874 -227.561902)
		(end 159.042608 -227.846636)
		(width 0.14478)
		(layer "In13.Cu")
		(net "M_H_CPU1_SA_DQ<23>")
	)
	(segment
		(start 164.835078 -224.815654)
		(end 164.690298 -224.960434)
		(width 0.14478)
		(layer "In13.Cu")
		(net "M_H_CPU1_SA_DQ<23>")
	)
	(segment
		(start 159.637222 -227.456746)
		(end 159.432498 -227.456746)
		(width 0.14478)
		(layer "In13.Cu")
		(net "M_H_CPU1_SA_DQ<23>")
	)
	(segment
		(start 163.732718 -224.725992)
		(end 163.732718 -224.815654)
		(width 0.14478)
		(layer "In13.Cu")
		(net "M_H_CPU1_SA_DQ<23>")
	)
	(segment
		(start 164.139118 -224.581212)
		(end 163.877498 -224.581212)
		(width 0.14478)
		(layer "In13.Cu")
		(net "M_H_CPU1_SA_DQ<23>")
	)
	(segment
		(start 141.67612 -239.296956)
		(end 141.667738 -239.301782)
		(width 0.0889)
		(layer "In13.Cu")
		(net "M_H_CPU1_SA_DQ<23>")
	)
	(segment
		(start 135.461756 -239.301782)
		(end 135.453374 -239.296956)
		(width 0.0889)
		(layer "In13.Cu")
		(net "M_H_CPU1_SA_DQ<23>")
	)
	(segment
		(start 134.488682 -239.358932)
		(end 134.334758 -239.624362)
		(width 0.0889)
		(layer "In13.Cu")
		(net "M_H_CPU1_SA_DQ<23>")
	)
	(segment
		(start 140.161772 -239.301782)
		(end 140.15339 -239.296956)
		(width 0.0889)
		(layer "In13.Cu")
		(net "M_H_CPU1_SA_DQ<23>")
	)
	(segment
		(start 162.775138 -224.581212)
		(end 162.630358 -224.725992)
		(width 0.14478)
		(layer "In13.Cu")
		(net "M_H_CPU1_SA_DQ<23>")
	)
	(segment
		(start 146.840956 -238.675164)
		(end 146.395948 -238.675164)
		(width 0.0889)
		(layer "In13.Cu")
		(net "M_H_CPU1_SA_DQ<23>")
	)
	(segment
		(start 141.101826 -239.301782)
		(end 141.093444 -239.296956)
		(width 0.0889)
		(layer "In13.Cu")
		(net "M_H_CPU1_SA_DQ<23>")
	)
	(segment
		(start 144.861788 -239.301782)
		(end 144.853406 -239.296956)
		(width 0.0889)
		(layer "In13.Cu")
		(net "M_H_CPU1_SA_DQ<23>")
	)
	(segment
		(start 163.326318 -224.960434)
		(end 163.181538 -224.815654)
		(width 0.14478)
		(layer "In13.Cu")
		(net "M_H_CPU1_SA_DQ<23>")
	)
	(segment
		(start 158.652718 -228.236526)
		(end 158.652464 -228.236272)
		(width 0.14478)
		(layer "In13.Cu")
		(net "M_H_CPU1_SA_DQ<23>")
	)
	(segment
		(start 168.77919 -223.750886)
		(end 168.63441 -223.895666)
		(width 0.14478)
		(layer "In13.Cu")
		(net "M_H_CPU1_SA_DQ<23>")
	)
	(segment
		(start 168.63441 -223.965516)
		(end 168.48963 -224.110296)
		(width 0.14478)
		(layer "In13.Cu")
		(net "M_H_CPU1_SA_DQ<23>")
	)
	(segment
		(start 167.057832 -224.110296)
		(end 166.915846 -224.110296)
		(width 0.14478)
		(layer "In13.Cu")
		(net "M_H_CPU1_SA_DQ<23>")
	)
	(segment
		(start 160.602168 -226.4918)
		(end 160.417002 -226.676966)
		(width 0.14478)
		(layer "In13.Cu")
		(net "M_H_CPU1_SA_DQ<23>")
	)
	(segment
		(start 160.655254 -225.765106)
		(end 160.470088 -225.950272)
		(width 0.14478)
		(layer "In13.Cu")
		(net "M_H_CPU1_SA_DQ<23>")
	)
	(segment
		(start 167.609012 -224.394522)
		(end 167.342058 -224.394522)
		(width 0.14478)
		(layer "In13.Cu")
		(net "M_H_CPU1_SA_DQ<23>")
	)
	(segment
		(start 170.611038 -224.960434)
		(end 169.7609 -224.110296)
		(width 0.14478)
		(layer "In13.Cu")
		(net "M_H_CPU1_SA_DQ<23>")
	)
	(segment
		(start 159.822388 -227.066856)
		(end 159.822388 -227.27158)
		(width 0.14478)
		(layer "In13.Cu")
		(net "M_H_CPU1_SA_DQ<23>")
	)
	(segment
		(start 164.283898 -224.815654)
		(end 164.283898 -224.725992)
		(width 0.14478)
		(layer "In13.Cu")
		(net "M_H_CPU1_SA_DQ<23>")
	)
	(segment
		(start 158.857442 -228.236526)
		(end 158.652718 -228.236526)
		(width 0.14478)
		(layer "In13.Cu")
		(net "M_H_CPU1_SA_DQ<23>")
	)
	(segment
		(start 169.04081 -223.750886)
		(end 168.77919 -223.750886)
		(width 0.14478)
		(layer "In13.Cu")
		(net "M_H_CPU1_SA_DQ<23>")
	)
	(segment
		(start 162.133534 -224.960434)
		(end 161.196782 -225.897186)
		(width 0.14478)
		(layer "In13.Cu")
		(net "M_H_CPU1_SA_DQ<23>")
	)
	(segment
		(start 164.835078 -224.725992)
		(end 164.835078 -224.815654)
		(width 0.14478)
		(layer "In13.Cu")
		(net "M_H_CPU1_SA_DQ<23>")
	)
	(segment
		(start 159.822388 -227.27158)
		(end 159.637222 -227.456746)
		(width 0.14478)
		(layer "In13.Cu")
		(net "M_H_CPU1_SA_DQ<23>")
	)
	(segment
		(start 163.181538 -224.815654)
		(end 163.181538 -224.725992)
		(width 0.14478)
		(layer "In13.Cu")
		(net "M_H_CPU1_SA_DQ<23>")
	)
	(segment
		(start 147.728686 -237.787434)
		(end 146.840956 -238.675164)
		(width 0.0889)
		(layer "In13.Cu")
		(net "M_H_CPU1_SA_DQ<23>")
	)
	(segment
		(start 158.94304 -227.172012)
		(end 158.757874 -227.357178)
		(width 0.14478)
		(layer "In13.Cu")
		(net "M_H_CPU1_SA_DQ<23>")
	)
	(segment
		(start 147.856194 -237.787434)
		(end 147.728686 -237.787434)
		(width 0.0889)
		(layer "In13.Cu")
		(net "M_H_CPU1_SA_DQ<23>")
	)
	(segment
		(start 167.342058 -224.394522)
		(end 167.057832 -224.110296)
		(width 0.14478)
		(layer "In13.Cu")
		(net "M_H_CPU1_SA_DQ<23>")
	)
	(segment
		(start 165.241478 -224.581212)
		(end 164.979858 -224.581212)
		(width 0.14478)
		(layer "In13.Cu")
		(net "M_H_CPU1_SA_DQ<23>")
	)
	(segment
		(start 163.587938 -224.960434)
		(end 163.326318 -224.960434)
		(width 0.14478)
		(layer "In13.Cu")
		(net "M_H_CPU1_SA_DQ<23>")
	)
	(segment
		(start 169.7609 -224.110296)
		(end 169.33037 -224.110296)
		(width 0.14478)
		(layer "In13.Cu")
		(net "M_H_CPU1_SA_DQ<23>")
	)
	(segment
		(start 158.652464 -228.236272)
		(end 158.44774 -228.236272)
		(width 0.14478)
		(layer "In13.Cu")
		(net "M_H_CPU1_SA_DQ<23>")
	)
	(segment
		(start 164.979858 -224.581212)
		(end 164.835078 -224.725992)
		(width 0.14478)
		(layer "In13.Cu")
		(net "M_H_CPU1_SA_DQ<23>")
	)
	(segment
		(start 158.757874 -227.357178)
		(end 158.757874 -227.561902)
		(width 0.14478)
		(layer "In13.Cu")
		(net "M_H_CPU1_SA_DQ<23>")
	)
	(segment
		(start 166.065708 -224.960434)
		(end 165.531038 -224.960434)
		(width 0.14478)
		(layer "In13.Cu")
		(net "M_H_CPU1_SA_DQ<23>")
	)
	(segment
		(start 166.915846 -224.110296)
		(end 166.065708 -224.960434)
		(width 0.14478)
		(layer "In13.Cu")
		(net "M_H_CPU1_SA_DQ<23>")
	)
	(segment
		(start 165.531038 -224.960434)
		(end 165.386258 -224.815654)
		(width 0.14478)
		(layer "In13.Cu")
		(net "M_H_CPU1_SA_DQ<23>")
	)
	(segment
		(start 160.470088 -226.154996)
		(end 160.602168 -226.287076)
		(width 0.14478)
		(layer "In13.Cu")
		(net "M_H_CPU1_SA_DQ<23>")
	)
	(segment
		(start 160.417002 -226.676966)
		(end 160.212278 -226.676966)
		(width 0.14478)
		(layer "In13.Cu")
		(net "M_H_CPU1_SA_DQ<23>")
	)
	(segment
		(start 163.877498 -224.581212)
		(end 163.732718 -224.725992)
		(width 0.14478)
		(layer "In13.Cu")
		(net "M_H_CPU1_SA_DQ<23>")
	)
	(segment
		(start 162.485578 -224.960434)
		(end 162.133534 -224.960434)
		(width 0.14478)
		(layer "In13.Cu")
		(net "M_H_CPU1_SA_DQ<23>")
	)
	(segment
		(start 171.546774 -224.960434)
		(end 170.611038 -224.960434)
		(width 0.14478)
		(layer "In13.Cu")
		(net "M_H_CPU1_SA_DQ<23>")
	)
	(segment
		(start 171.97197 -224.535238)
		(end 171.546774 -224.960434)
		(width 0.14478)
		(layer "In13.Cu")
		(net "M_H_CPU1_SA_DQ<23>")
	)
	(segment
		(start 159.72282 -226.392232)
		(end 159.537654 -226.577398)
		(width 0.14478)
		(layer "In13.Cu")
		(net "M_H_CPU1_SA_DQ<23>")
	)
	(segment
		(start 169.33037 -224.110296)
		(end 169.18559 -223.965516)
		(width 0.14478)
		(layer "In13.Cu")
		(net "M_H_CPU1_SA_DQ<23>")
	)
	(segment
		(start 145.69313 -239.377982)
		(end 145.14449 -239.377982)
		(width 0.0889)
		(layer "In13.Cu")
		(net "M_H_CPU1_SA_DQ<23>")
	)
	(segment
		(start 168.63441 -223.895666)
		(end 168.63441 -223.965516)
		(width 0.14478)
		(layer "In13.Cu")
		(net "M_H_CPU1_SA_DQ<23>")
	)
	(segment
		(start 164.428678 -224.960434)
		(end 164.283898 -224.815654)
		(width 0.14478)
		(layer "In13.Cu")
		(net "M_H_CPU1_SA_DQ<23>")
	)
	(segment
		(start 169.18559 -223.965516)
		(end 169.18559 -223.895666)
		(width 0.14478)
		(layer "In13.Cu")
		(net "M_H_CPU1_SA_DQ<23>")
	)
	(segment
		(start 159.537654 -226.782122)
		(end 159.822388 -227.066856)
		(width 0.14478)
		(layer "In13.Cu")
		(net "M_H_CPU1_SA_DQ<23>")
	)
	(segment
		(start 165.386258 -224.725992)
		(end 165.241478 -224.581212)
		(width 0.14478)
		(layer "In13.Cu")
		(net "M_H_CPU1_SA_DQ<23>")
	)
	(segment
		(start 163.036758 -224.581212)
		(end 162.775138 -224.581212)
		(width 0.14478)
		(layer "In13.Cu")
		(net "M_H_CPU1_SA_DQ<23>")
	)
	(segment
		(start 160.859978 -225.765106)
		(end 160.655254 -225.765106)
		(width 0.14478)
		(layer "In13.Cu")
		(net "M_H_CPU1_SA_DQ<23>")
	)
	(segment
		(start 144.487646 -239.301782)
		(end 144.47774 -239.307878)
		(width 0.0889)
		(layer "In13.Cu")
		(net "M_H_CPU1_SA_DQ<23>")
	)
	(segment
		(start 160.470088 -225.950272)
		(end 160.470088 -226.154996)
		(width 0.14478)
		(layer "In13.Cu")
		(net "M_H_CPU1_SA_DQ<23>")
	)
	(segment
		(start 146.395948 -238.675164)
		(end 145.69313 -239.377982)
		(width 0.0889)
		(layer "In13.Cu")
		(net "M_H_CPU1_SA_DQ<23>")
	)
	(segment
		(start 160.602168 -226.287076)
		(end 160.602168 -226.4918)
		(width 0.14478)
		(layer "In13.Cu")
		(net "M_H_CPU1_SA_DQ<23>")
	)
	(segment
		(start 159.537654 -226.577398)
		(end 159.537654 -226.782122)
		(width 0.14478)
		(layer "In13.Cu")
		(net "M_H_CPU1_SA_DQ<23>")
	)
	(segment
		(start 163.732718 -224.815654)
		(end 163.587938 -224.960434)
		(width 0.14478)
		(layer "In13.Cu")
		(net "M_H_CPU1_SA_DQ<23>")
	)
	(segment
		(start 164.283898 -224.725992)
		(end 164.139118 -224.581212)
		(width 0.14478)
		(layer "In13.Cu")
		(net "M_H_CPU1_SA_DQ<23>")
	)
	(segment
		(start 164.690298 -224.960434)
		(end 164.428678 -224.960434)
		(width 0.14478)
		(layer "In13.Cu")
		(net "M_H_CPU1_SA_DQ<23>")
	)
	(segment
		(start 169.18559 -223.895666)
		(end 169.04081 -223.750886)
		(width 0.14478)
		(layer "In13.Cu")
		(net "M_H_CPU1_SA_DQ<23>")
	)
	(segment
		(start 159.927544 -226.392232)
		(end 159.72282 -226.392232)
		(width 0.14478)
		(layer "In13.Cu")
		(net "M_H_CPU1_SA_DQ<23>")
	)
	(segment
		(start 137.916158 -239.296956)
		(end 137.907776 -239.301782)
		(width 0.0889)
		(layer "In13.Cu")
		(net "M_H_CPU1_SA_DQ<23>")
	)
	(segment
		(start 159.147764 -227.172012)
		(end 158.94304 -227.172012)
		(width 0.14478)
		(layer "In13.Cu")
		(net "M_H_CPU1_SA_DQ<23>")
	)
	(segment
		(start 158.44774 -228.236272)
		(end 158.262574 -228.421438)
		(width 0.14478)
		(layer "In13.Cu")
		(net "M_H_CPU1_SA_DQ<23>")
	)
	(segment
		(start 167.893238 -224.110296)
		(end 167.609012 -224.394522)
		(width 0.14478)
		(layer "In13.Cu")
		(net "M_H_CPU1_SA_DQ<23>")
	)
	(segment
		(start 136.40181 -239.301782)
		(end 136.393428 -239.296956)
		(width 0.0889)
		(layer "In13.Cu")
		(net "M_H_CPU1_SA_DQ<23>")
	)
	(segment
		(start 162.630358 -224.815654)
		(end 162.485578 -224.960434)
		(width 0.14478)
		(layer "In13.Cu")
		(net "M_H_CPU1_SA_DQ<23>")
	)
	(segment
		(start 158.262574 -228.421438)
		(end 158.262574 -229.692962)
		(width 0.14478)
		(layer "In13.Cu")
		(net "M_H_CPU1_SA_DQ<23>")
	)
	(segment
		(start 168.48963 -224.110296)
		(end 167.893238 -224.110296)
		(width 0.14478)
		(layer "In13.Cu")
		(net "M_H_CPU1_SA_DQ<23>")
	)
	(segment
		(start 161.196782 -225.897186)
		(end 160.992058 -225.897186)
		(width 0.14478)
		(layer "In13.Cu")
		(net "M_H_CPU1_SA_DQ<23>")
	)
	(segment
		(start 165.386258 -224.815654)
		(end 165.386258 -224.725992)
		(width 0.14478)
		(layer "In13.Cu")
		(net "M_H_CPU1_SA_DQ<23>")
	)
	(segment
		(start 134.584694 -239.333532)
		(end 134.488682 -239.358932)
		(width 0.0889)
		(layer "In13.Cu")
		(net "M_H_CPU1_SA_DQ<23>")
	)
	(segment
		(start 159.042608 -228.05136)
		(end 158.857442 -228.236526)
		(width 0.14478)
		(layer "In13.Cu")
		(net "M_H_CPU1_SA_DQ<23>")
	)
	(segment
		(start 160.992058 -225.897186)
		(end 160.859978 -225.765106)
		(width 0.14478)
		(layer "In13.Cu")
		(net "M_H_CPU1_SA_DQ<23>")
	)
	(segment
		(start 160.212278 -226.676966)
		(end 159.927544 -226.392232)
		(width 0.14478)
		(layer "In13.Cu")
		(net "M_H_CPU1_SA_DQ<23>")
	)
	(segment
		(start 159.432498 -227.456746)
		(end 159.147764 -227.172012)
		(width 0.14478)
		(layer "In13.Cu")
		(net "M_H_CPU1_SA_DQ<23>")
	)
	(segment
		(start 158.262574 -229.692962)
		(end 150.168102 -237.787434)
		(width 0.14478)
		(layer "In13.Cu")
		(net "M_H_CPU1_SA_DQ<23>")
	)
	(segment
		(start 159.042608 -227.846636)
		(end 159.042608 -228.05136)
		(width 0.14478)
		(layer "In13.Cu")
		(net "M_H_CPU1_SA_DQ<23>")
	)
	(segment
		(start 163.181538 -224.725992)
		(end 163.036758 -224.581212)
		(width 0.14478)
		(layer "In13.Cu")
		(net "M_H_CPU1_SA_DQ<23>")
	)
	(segment
		(start 136.976104 -239.296956)
		(end 136.967722 -239.301782)
		(width 0.0889)
		(layer "In13.Cu")
		(net "M_H_CPU1_SA_DQ<23>")
	)
	(segment
		(start 162.630358 -224.725992)
		(end 162.630358 -224.815654)
		(width 0.14478)
		(layer "In13.Cu")
		(net "M_H_CPU1_SA_DQ<23>")
	)
	(arc
		(start 136.027668 -239.301782)
		(mid 135.744712 -239.377959)
		(end 135.461756 -239.301782)
		(width 0.0889)
		(layer "In13.Cu")
		(net "M_H_CPU1_SA_DQ<23>")
	)
	(arc
		(start 138.281918 -239.301782)
		(mid 138.099667 -239.251432)
		(end 137.916158 -239.296956)
		(width 0.0889)
		(layer "In13.Cu")
		(net "M_H_CPU1_SA_DQ<23>")
	)
	(arc
		(start 144.47774 -239.307878)
		(mid 144.199054 -239.378098)
		(end 143.921988 -239.301782)
		(width 0.0889)
		(layer "In13.Cu")
		(net "M_H_CPU1_SA_DQ<23>")
	)
	(arc
		(start 143.547592 -239.301782)
		(mid 143.264636 -239.377959)
		(end 142.98168 -239.301782)
		(width 0.0889)
		(layer "In13.Cu")
		(net "M_H_CPU1_SA_DQ<23>")
	)
	(arc
		(start 139.221718 -239.301782)
		(mid 139.034774 -239.251527)
		(end 138.84783 -239.301782)
		(width 0.0889)
		(layer "In13.Cu")
		(net "M_H_CPU1_SA_DQ<23>")
	)
	(arc
		(start 142.607792 -239.301782)
		(mid 142.324836 -239.377959)
		(end 142.04188 -239.301782)
		(width 0.0889)
		(layer "In13.Cu")
		(net "M_H_CPU1_SA_DQ<23>")
	)
	(arc
		(start 140.15339 -239.296956)
		(mid 139.969882 -239.251462)
		(end 139.78763 -239.301782)
		(width 0.0889)
		(layer "In13.Cu")
		(net "M_H_CPU1_SA_DQ<23>")
	)
	(arc
		(start 139.78763 -239.301782)
		(mid 139.504674 -239.377959)
		(end 139.221718 -239.301782)
		(width 0.0889)
		(layer "In13.Cu")
		(net "M_H_CPU1_SA_DQ<23>")
	)
	(arc
		(start 136.967722 -239.301782)
		(mid 136.684766 -239.377959)
		(end 136.40181 -239.301782)
		(width 0.0889)
		(layer "In13.Cu")
		(net "M_H_CPU1_SA_DQ<23>")
	)
	(arc
		(start 138.84783 -239.301782)
		(mid 138.564874 -239.377959)
		(end 138.281918 -239.301782)
		(width 0.0889)
		(layer "In13.Cu")
		(net "M_H_CPU1_SA_DQ<23>")
	)
	(arc
		(start 140.727684 -239.301782)
		(mid 140.444728 -239.377959)
		(end 140.161772 -239.301782)
		(width 0.0889)
		(layer "In13.Cu")
		(net "M_H_CPU1_SA_DQ<23>")
	)
	(arc
		(start 137.341864 -239.301782)
		(mid 137.159613 -239.251432)
		(end 136.976104 -239.296956)
		(width 0.0889)
		(layer "In13.Cu")
		(net "M_H_CPU1_SA_DQ<23>")
	)
	(arc
		(start 137.907776 -239.301782)
		(mid 137.62482 -239.377959)
		(end 137.341864 -239.301782)
		(width 0.0889)
		(layer "In13.Cu")
		(net "M_H_CPU1_SA_DQ<23>")
	)
	(arc
		(start 136.393428 -239.296956)
		(mid 136.20992 -239.251462)
		(end 136.027668 -239.301782)
		(width 0.0889)
		(layer "In13.Cu")
		(net "M_H_CPU1_SA_DQ<23>")
	)
	(arc
		(start 142.04188 -239.301782)
		(mid 141.859629 -239.251432)
		(end 141.67612 -239.296956)
		(width 0.0889)
		(layer "In13.Cu")
		(net "M_H_CPU1_SA_DQ<23>")
	)
	(arc
		(start 145.0975 -239.376204)
		(mid 144.975518 -239.352065)
		(end 144.861788 -239.301782)
		(width 0.0889)
		(layer "In13.Cu")
		(net "M_H_CPU1_SA_DQ<23>")
	)
	(arc
		(start 135.453374 -239.296956)
		(mid 135.269866 -239.251462)
		(end 135.087614 -239.301782)
		(width 0.0889)
		(layer "In13.Cu")
		(net "M_H_CPU1_SA_DQ<23>")
	)
	(arc
		(start 145.14449 -239.377982)
		(mid 145.120976 -239.377587)
		(end 145.0975 -239.376204)
		(width 0.0889)
		(layer "In13.Cu")
		(net "M_H_CPU1_SA_DQ<23>")
	)
	(arc
		(start 141.093444 -239.296956)
		(mid 140.909936 -239.251462)
		(end 140.727684 -239.301782)
		(width 0.0889)
		(layer "In13.Cu")
		(net "M_H_CPU1_SA_DQ<23>")
	)
	(arc
		(start 135.087614 -239.301782)
		(mid 134.839901 -239.377002)
		(end 134.584694 -239.333532)
		(width 0.0889)
		(layer "In13.Cu")
		(net "M_H_CPU1_SA_DQ<23>")
	)
	(arc
		(start 144.853406 -239.296956)
		(mid 144.669898 -239.251462)
		(end 144.487646 -239.301782)
		(width 0.0889)
		(layer "In13.Cu")
		(net "M_H_CPU1_SA_DQ<23>")
	)
	(arc
		(start 141.667738 -239.301782)
		(mid 141.384782 -239.377959)
		(end 141.101826 -239.301782)
		(width 0.0889)
		(layer "In13.Cu")
		(net "M_H_CPU1_SA_DQ<23>")
	)
	(arc
		(start 142.98168 -239.301782)
		(mid 142.794736 -239.251527)
		(end 142.607792 -239.301782)
		(width 0.0889)
		(layer "In13.Cu")
		(net "M_H_CPU1_SA_DQ<23>")
	)
	(arc
		(start 143.921988 -239.301782)
		(mid 143.73479 -239.2514)
		(end 143.547592 -239.301782)
		(width 0.0889)
		(layer "In13.Cu")
		(net "M_H_CPU1_SA_DQ<23>")
	)
	(segment
		(start 135.27786 -239.080294)
		(end 135.744712 -238.814356)
		(width 0.10668)
		(layer "F.Cu")
		(net "M_H_CPU1_SA_DQ<22>")
	)
	(segment
		(start 159.377126 -225.076258)
		(end 159.469074 -225.168206)
		(width 0.14478)
		(layer "In13.Cu")
		(net "M_H_CPU1_SA_DQ<22>")
	)
	(segment
		(start 135.744712 -238.814356)
		(end 135.89889 -238.548926)
		(width 0.0889)
		(layer "In13.Cu")
		(net "M_H_CPU1_SA_DQ<22>")
	)
	(segment
		(start 163.214812 -223.515936)
		(end 163.359592 -223.660716)
		(width 0.14478)
		(layer "In13.Cu")
		(net "M_H_CPU1_SA_DQ<22>")
	)
	(segment
		(start 158.894018 -225.947986)
		(end 159.079184 -225.76282)
		(width 0.14478)
		(layer "In13.Cu")
		(net "M_H_CPU1_SA_DQ<22>")
	)
	(segment
		(start 162.808412 -222.859854)
		(end 163.070032 -222.859854)
		(width 0.14478)
		(layer "In13.Cu")
		(net "M_H_CPU1_SA_DQ<22>")
	)
	(segment
		(start 165.131496 -222.859854)
		(end 165.276276 -223.004634)
		(width 0.14478)
		(layer "In13.Cu")
		(net "M_H_CPU1_SA_DQ<22>")
	)
	(segment
		(start 169.588942 -222.410274)
		(end 170.048174 -222.869506)
		(width 0.14478)
		(layer "In13.Cu")
		(net "M_H_CPU1_SA_DQ<22>")
	)
	(segment
		(start 139.31773 -238.491776)
		(end 139.326112 -238.48695)
		(width 0.0889)
		(layer "In13.Cu")
		(net "M_H_CPU1_SA_DQ<22>")
	)
	(segment
		(start 170.887898 -223.643444)
		(end 171.149518 -223.643444)
		(width 0.14478)
		(layer "In13.Cu")
		(net "M_H_CPU1_SA_DQ<22>")
	)
	(segment
		(start 144.384268 -238.48695)
		(end 144.39265 -238.491776)
		(width 0.0889)
		(layer "In13.Cu")
		(net "M_H_CPU1_SA_DQ<22>")
	)
	(segment
		(start 165.276276 -223.004634)
		(end 165.276276 -223.416622)
		(width 0.14478)
		(layer "In13.Cu")
		(net "M_H_CPU1_SA_DQ<22>")
	)
	(segment
		(start 143.077692 -238.491776)
		(end 143.086074 -238.48695)
		(width 0.0889)
		(layer "In13.Cu")
		(net "M_H_CPU1_SA_DQ<22>")
	)
	(segment
		(start 137.803382 -238.48695)
		(end 137.811764 -238.491776)
		(width 0.0889)
		(layer "In13.Cu")
		(net "M_H_CPU1_SA_DQ<22>")
	)
	(segment
		(start 163.214812 -223.004634)
		(end 163.214812 -223.515936)
		(width 0.14478)
		(layer "In13.Cu")
		(net "M_H_CPU1_SA_DQ<22>")
	)
	(segment
		(start 169.348912 -222.410274)
		(end 169.588942 -222.410274)
		(width 0.14478)
		(layer "In13.Cu")
		(net "M_H_CPU1_SA_DQ<22>")
	)
	(segment
		(start 158.392622 -225.856038)
		(end 158.597346 -225.856038)
		(width 0.14478)
		(layer "In13.Cu")
		(net "M_H_CPU1_SA_DQ<22>")
	)
	(segment
		(start 168.101772 -222.155258)
		(end 168.101772 -222.265494)
		(width 0.14478)
		(layer "In13.Cu")
		(net "M_H_CPU1_SA_DQ<22>")
	)
	(segment
		(start 159.976058 -224.865946)
		(end 160.95599 -224.865946)
		(width 0.14478)
		(layer "In13.Cu")
		(net "M_H_CPU1_SA_DQ<22>")
	)
	(segment
		(start 147.835366 -236.878114)
		(end 149.731222 -236.878114)
		(width 0.14478)
		(layer "In13.Cu")
		(net "M_H_CPU1_SA_DQ<22>")
	)
	(segment
		(start 159.673798 -225.168206)
		(end 159.976058 -224.865946)
		(width 0.14478)
		(layer "In13.Cu")
		(net "M_H_CPU1_SA_DQ<22>")
	)
	(segment
		(start 159.469074 -225.168206)
		(end 159.673798 -225.168206)
		(width 0.14478)
		(layer "In13.Cu")
		(net "M_H_CPU1_SA_DQ<22>")
	)
	(segment
		(start 158.299404 -226.337876)
		(end 158.207456 -226.245928)
		(width 0.14478)
		(layer "In13.Cu")
		(net "M_H_CPU1_SA_DQ<22>")
	)
	(segment
		(start 169.204132 -222.265494)
		(end 169.348912 -222.410274)
		(width 0.14478)
		(layer "In13.Cu")
		(net "M_H_CPU1_SA_DQ<22>")
	)
	(segment
		(start 158.987236 -225.261424)
		(end 159.172402 -225.076258)
		(width 0.14478)
		(layer "In13.Cu")
		(net "M_H_CPU1_SA_DQ<22>")
	)
	(segment
		(start 147.332192 -236.878114)
		(end 147.835366 -236.878114)
		(width 0.0889)
		(layer "In13.Cu")
		(net "M_H_CPU1_SA_DQ<22>")
	)
	(segment
		(start 157.817566 -226.635818)
		(end 157.909514 -226.727766)
		(width 0.14478)
		(layer "In13.Cu")
		(net "M_H_CPU1_SA_DQ<22>")
	)
	(segment
		(start 171.93768 -222.869506)
		(end 171.97197 -222.835216)
		(width 0.14478)
		(layer "In13.Cu")
		(net "M_H_CPU1_SA_DQ<22>")
	)
	(segment
		(start 157.612842 -226.635818)
		(end 157.817566 -226.635818)
		(width 0.14478)
		(layer "In13.Cu")
		(net "M_H_CPU1_SA_DQ<22>")
	)
	(segment
		(start 163.910772 -223.260412)
		(end 164.580316 -223.260412)
		(width 0.14478)
		(layer "In13.Cu")
		(net "M_H_CPU1_SA_DQ<22>")
	)
	(segment
		(start 167.956992 -222.010478)
		(end 168.101772 -222.155258)
		(width 0.14478)
		(layer "In13.Cu")
		(net "M_H_CPU1_SA_DQ<22>")
	)
	(segment
		(start 164.869876 -222.859854)
		(end 165.131496 -222.859854)
		(width 0.14478)
		(layer "In13.Cu")
		(net "M_H_CPU1_SA_DQ<22>")
	)
	(segment
		(start 143.451834 -238.491776)
		(end 143.462248 -238.497872)
		(width 0.0889)
		(layer "In13.Cu")
		(net "M_H_CPU1_SA_DQ<22>")
	)
	(segment
		(start 159.172402 -225.076258)
		(end 159.377126 -225.076258)
		(width 0.14478)
		(layer "In13.Cu")
		(net "M_H_CPU1_SA_DQ<22>")
	)
	(segment
		(start 170.743118 -223.498664)
		(end 170.887898 -223.643444)
		(width 0.14478)
		(layer "In13.Cu")
		(net "M_H_CPU1_SA_DQ<22>")
	)
	(segment
		(start 157.363414 -227.47859)
		(end 157.519624 -227.32238)
		(width 0.14478)
		(layer "In13.Cu")
		(net "M_H_CPU1_SA_DQ<22>")
	)
	(segment
		(start 162.663632 -223.004634)
		(end 162.808412 -222.859854)
		(width 0.14478)
		(layer "In13.Cu")
		(net "M_H_CPU1_SA_DQ<22>")
	)
	(segment
		(start 168.246552 -222.410274)
		(end 168.508172 -222.410274)
		(width 0.14478)
		(layer "In13.Cu")
		(net "M_H_CPU1_SA_DQ<22>")
	)
	(segment
		(start 158.207456 -226.245928)
		(end 158.207456 -226.041204)
		(width 0.14478)
		(layer "In13.Cu")
		(net "M_H_CPU1_SA_DQ<22>")
	)
	(segment
		(start 142.503398 -238.48695)
		(end 142.51178 -238.491776)
		(width 0.0889)
		(layer "In13.Cu")
		(net "M_H_CPU1_SA_DQ<22>")
	)
	(segment
		(start 158.597346 -225.856038)
		(end 158.689294 -225.947986)
		(width 0.14478)
		(layer "In13.Cu")
		(net "M_H_CPU1_SA_DQ<22>")
	)
	(segment
		(start 145.144744 -238.440976)
		(end 145.76933 -238.440976)
		(width 0.0889)
		(layer "In13.Cu")
		(net "M_H_CPU1_SA_DQ<22>")
	)
	(segment
		(start 168.101772 -222.265494)
		(end 168.246552 -222.410274)
		(width 0.14478)
		(layer "In13.Cu")
		(net "M_H_CPU1_SA_DQ<22>")
	)
	(segment
		(start 170.743118 -223.014286)
		(end 170.743118 -223.498664)
		(width 0.14478)
		(layer "In13.Cu")
		(net "M_H_CPU1_SA_DQ<22>")
	)
	(segment
		(start 167.405812 -222.410274)
		(end 167.550592 -222.265494)
		(width 0.14478)
		(layer "In13.Cu")
		(net "M_H_CPU1_SA_DQ<22>")
	)
	(segment
		(start 158.114238 -226.727766)
		(end 158.299404 -226.5426)
		(width 0.14478)
		(layer "In13.Cu")
		(net "M_H_CPU1_SA_DQ<22>")
	)
	(segment
		(start 138.743436 -238.48695)
		(end 138.751818 -238.491776)
		(width 0.0889)
		(layer "In13.Cu")
		(net "M_H_CPU1_SA_DQ<22>")
	)
	(segment
		(start 170.598338 -222.869506)
		(end 170.743118 -223.014286)
		(width 0.14478)
		(layer "In13.Cu")
		(net "M_H_CPU1_SA_DQ<22>")
	)
	(segment
		(start 169.204132 -222.155258)
		(end 169.204132 -222.265494)
		(width 0.14478)
		(layer "In13.Cu")
		(net "M_H_CPU1_SA_DQ<22>")
	)
	(segment
		(start 157.519624 -227.32238)
		(end 157.519624 -227.117656)
		(width 0.14478)
		(layer "In13.Cu")
		(net "M_H_CPU1_SA_DQ<22>")
	)
	(segment
		(start 163.765992 -223.515936)
		(end 163.765992 -223.405192)
		(width 0.14478)
		(layer "In13.Cu")
		(net "M_H_CPU1_SA_DQ<22>")
	)
	(segment
		(start 140.257784 -238.491776)
		(end 140.266166 -238.48695)
		(width 0.0889)
		(layer "In13.Cu")
		(net "M_H_CPU1_SA_DQ<22>")
	)
	(segment
		(start 163.070032 -222.859854)
		(end 163.214812 -223.004634)
		(width 0.14478)
		(layer "In13.Cu")
		(net "M_H_CPU1_SA_DQ<22>")
	)
	(segment
		(start 168.508172 -222.410274)
		(end 168.652952 -222.265494)
		(width 0.14478)
		(layer "In13.Cu")
		(net "M_H_CPU1_SA_DQ<22>")
	)
	(segment
		(start 171.149518 -223.643444)
		(end 171.294298 -223.498664)
		(width 0.14478)
		(layer "In13.Cu")
		(net "M_H_CPU1_SA_DQ<22>")
	)
	(segment
		(start 165.421056 -223.561402)
		(end 165.927024 -223.561402)
		(width 0.14478)
		(layer "In13.Cu")
		(net "M_H_CPU1_SA_DQ<22>")
	)
	(segment
		(start 159.079184 -225.76282)
		(end 159.079184 -225.558096)
		(width 0.14478)
		(layer "In13.Cu")
		(net "M_H_CPU1_SA_DQ<22>")
	)
	(segment
		(start 157.427676 -226.820984)
		(end 157.612842 -226.635818)
		(width 0.14478)
		(layer "In13.Cu")
		(net "M_H_CPU1_SA_DQ<22>")
	)
	(segment
		(start 158.689294 -225.947986)
		(end 158.894018 -225.947986)
		(width 0.14478)
		(layer "In13.Cu")
		(net "M_H_CPU1_SA_DQ<22>")
	)
	(segment
		(start 157.363414 -229.245922)
		(end 157.363414 -227.47859)
		(width 0.14478)
		(layer "In13.Cu")
		(net "M_H_CPU1_SA_DQ<22>")
	)
	(segment
		(start 169.059352 -222.010478)
		(end 169.204132 -222.155258)
		(width 0.14478)
		(layer "In13.Cu")
		(net "M_H_CPU1_SA_DQ<22>")
	)
	(segment
		(start 167.550592 -222.155258)
		(end 167.695372 -222.010478)
		(width 0.14478)
		(layer "In13.Cu")
		(net "M_H_CPU1_SA_DQ<22>")
	)
	(segment
		(start 171.439078 -222.869506)
		(end 171.93768 -222.869506)
		(width 0.14478)
		(layer "In13.Cu")
		(net "M_H_CPU1_SA_DQ<22>")
	)
	(segment
		(start 145.76933 -238.440976)
		(end 147.332192 -236.878114)
		(width 0.0889)
		(layer "In13.Cu")
		(net "M_H_CPU1_SA_DQ<22>")
	)
	(segment
		(start 167.695372 -222.010478)
		(end 167.956992 -222.010478)
		(width 0.14478)
		(layer "In13.Cu")
		(net "M_H_CPU1_SA_DQ<22>")
	)
	(segment
		(start 167.550592 -222.265494)
		(end 167.550592 -222.155258)
		(width 0.14478)
		(layer "In13.Cu")
		(net "M_H_CPU1_SA_DQ<22>")
	)
	(segment
		(start 164.725096 -223.004634)
		(end 164.869876 -222.859854)
		(width 0.14478)
		(layer "In13.Cu")
		(net "M_H_CPU1_SA_DQ<22>")
	)
	(segment
		(start 160.95599 -224.865946)
		(end 162.209226 -223.61271)
		(width 0.14478)
		(layer "In13.Cu")
		(net "M_H_CPU1_SA_DQ<22>")
	)
	(segment
		(start 158.299404 -226.5426)
		(end 158.299404 -226.337876)
		(width 0.14478)
		(layer "In13.Cu")
		(net "M_H_CPU1_SA_DQ<22>")
	)
	(segment
		(start 157.909514 -226.727766)
		(end 158.114238 -226.727766)
		(width 0.14478)
		(layer "In13.Cu")
		(net "M_H_CPU1_SA_DQ<22>")
	)
	(segment
		(start 168.797732 -222.010478)
		(end 169.059352 -222.010478)
		(width 0.14478)
		(layer "In13.Cu")
		(net "M_H_CPU1_SA_DQ<22>")
	)
	(segment
		(start 165.927024 -223.561402)
		(end 167.078152 -222.410274)
		(width 0.14478)
		(layer "In13.Cu")
		(net "M_H_CPU1_SA_DQ<22>")
	)
	(segment
		(start 162.663632 -223.46793)
		(end 162.663632 -223.004634)
		(width 0.14478)
		(layer "In13.Cu")
		(net "M_H_CPU1_SA_DQ<22>")
	)
	(segment
		(start 157.519624 -227.117656)
		(end 157.427676 -227.025708)
		(width 0.14478)
		(layer "In13.Cu")
		(net "M_H_CPU1_SA_DQ<22>")
	)
	(segment
		(start 135.89889 -238.548926)
		(end 135.995156 -238.523526)
		(width 0.0889)
		(layer "In13.Cu")
		(net "M_H_CPU1_SA_DQ<22>")
	)
	(segment
		(start 163.359592 -223.660716)
		(end 163.621212 -223.660716)
		(width 0.14478)
		(layer "In13.Cu")
		(net "M_H_CPU1_SA_DQ<22>")
	)
	(segment
		(start 158.987236 -225.466148)
		(end 158.987236 -225.261424)
		(width 0.14478)
		(layer "In13.Cu")
		(net "M_H_CPU1_SA_DQ<22>")
	)
	(segment
		(start 167.078152 -222.410274)
		(end 167.405812 -222.410274)
		(width 0.14478)
		(layer "In13.Cu")
		(net "M_H_CPU1_SA_DQ<22>")
	)
	(segment
		(start 170.048174 -222.869506)
		(end 170.598338 -222.869506)
		(width 0.14478)
		(layer "In13.Cu")
		(net "M_H_CPU1_SA_DQ<22>")
	)
	(segment
		(start 163.765992 -223.405192)
		(end 163.910772 -223.260412)
		(width 0.14478)
		(layer "In13.Cu")
		(net "M_H_CPU1_SA_DQ<22>")
	)
	(segment
		(start 168.652952 -222.155258)
		(end 168.797732 -222.010478)
		(width 0.14478)
		(layer "In13.Cu")
		(net "M_H_CPU1_SA_DQ<22>")
	)
	(segment
		(start 163.621212 -223.660716)
		(end 163.765992 -223.515936)
		(width 0.14478)
		(layer "In13.Cu")
		(net "M_H_CPU1_SA_DQ<22>")
	)
	(segment
		(start 162.209226 -223.61271)
		(end 162.518852 -223.61271)
		(width 0.14478)
		(layer "In13.Cu")
		(net "M_H_CPU1_SA_DQ<22>")
	)
	(segment
		(start 171.294298 -223.014286)
		(end 171.439078 -222.869506)
		(width 0.14478)
		(layer "In13.Cu")
		(net "M_H_CPU1_SA_DQ<22>")
	)
	(segment
		(start 162.518852 -223.61271)
		(end 162.663632 -223.46793)
		(width 0.14478)
		(layer "In13.Cu")
		(net "M_H_CPU1_SA_DQ<22>")
	)
	(segment
		(start 158.207456 -226.041204)
		(end 158.392622 -225.856038)
		(width 0.14478)
		(layer "In13.Cu")
		(net "M_H_CPU1_SA_DQ<22>")
	)
	(segment
		(start 149.731222 -236.878114)
		(end 157.363414 -229.245922)
		(width 0.14478)
		(layer "In13.Cu")
		(net "M_H_CPU1_SA_DQ<22>")
	)
	(segment
		(start 164.580316 -223.260412)
		(end 164.725096 -223.115632)
		(width 0.14478)
		(layer "In13.Cu")
		(net "M_H_CPU1_SA_DQ<22>")
	)
	(segment
		(start 168.652952 -222.265494)
		(end 168.652952 -222.155258)
		(width 0.14478)
		(layer "In13.Cu")
		(net "M_H_CPU1_SA_DQ<22>")
	)
	(segment
		(start 165.276276 -223.416622)
		(end 165.421056 -223.561402)
		(width 0.14478)
		(layer "In13.Cu")
		(net "M_H_CPU1_SA_DQ<22>")
	)
	(segment
		(start 164.725096 -223.115632)
		(end 164.725096 -223.004634)
		(width 0.14478)
		(layer "In13.Cu")
		(net "M_H_CPU1_SA_DQ<22>")
	)
	(segment
		(start 171.294298 -223.498664)
		(end 171.294298 -223.014286)
		(width 0.14478)
		(layer "In13.Cu")
		(net "M_H_CPU1_SA_DQ<22>")
	)
	(segment
		(start 157.427676 -227.025708)
		(end 157.427676 -226.820984)
		(width 0.14478)
		(layer "In13.Cu")
		(net "M_H_CPU1_SA_DQ<22>")
	)
	(segment
		(start 159.079184 -225.558096)
		(end 158.987236 -225.466148)
		(width 0.14478)
		(layer "In13.Cu")
		(net "M_H_CPU1_SA_DQ<22>")
	)
	(arc
		(start 144.018 -238.491776)
		(mid 144.200505 -238.441299)
		(end 144.384268 -238.48695)
		(width 0.0889)
		(layer "In13.Cu")
		(net "M_H_CPU1_SA_DQ<22>")
	)
	(arc
		(start 139.326112 -238.48695)
		(mid 139.50962 -238.441456)
		(end 139.691872 -238.491776)
		(width 0.0889)
		(layer "In13.Cu")
		(net "M_H_CPU1_SA_DQ<22>")
	)
	(arc
		(start 140.631926 -238.491776)
		(mid 140.914882 -238.567953)
		(end 141.197838 -238.491776)
		(width 0.0889)
		(layer "In13.Cu")
		(net "M_H_CPU1_SA_DQ<22>")
	)
	(arc
		(start 140.266166 -238.48695)
		(mid 140.449674 -238.441456)
		(end 140.631926 -238.491776)
		(width 0.0889)
		(layer "In13.Cu")
		(net "M_H_CPU1_SA_DQ<22>")
	)
	(arc
		(start 141.197838 -238.491776)
		(mid 141.384782 -238.441521)
		(end 141.571726 -238.491776)
		(width 0.0889)
		(layer "In13.Cu")
		(net "M_H_CPU1_SA_DQ<22>")
	)
	(arc
		(start 144.39265 -238.491776)
		(mid 144.672078 -238.567942)
		(end 144.952466 -238.495332)
		(width 0.0889)
		(layer "In13.Cu")
		(net "M_H_CPU1_SA_DQ<22>")
	)
	(arc
		(start 136.497822 -238.491776)
		(mid 136.684766 -238.441521)
		(end 136.87171 -238.491776)
		(width 0.0889)
		(layer "In13.Cu")
		(net "M_H_CPU1_SA_DQ<22>")
	)
	(arc
		(start 144.952466 -238.495332)
		(mid 145.044898 -238.45505)
		(end 145.144744 -238.440976)
		(width 0.0889)
		(layer "In13.Cu")
		(net "M_H_CPU1_SA_DQ<22>")
	)
	(arc
		(start 137.437622 -238.491776)
		(mid 137.619873 -238.441426)
		(end 137.803382 -238.48695)
		(width 0.0889)
		(layer "In13.Cu")
		(net "M_H_CPU1_SA_DQ<22>")
	)
	(arc
		(start 138.751818 -238.491776)
		(mid 139.034774 -238.567953)
		(end 139.31773 -238.491776)
		(width 0.0889)
		(layer "In13.Cu")
		(net "M_H_CPU1_SA_DQ<22>")
	)
	(arc
		(start 142.137638 -238.491776)
		(mid 142.319889 -238.441426)
		(end 142.503398 -238.48695)
		(width 0.0889)
		(layer "In13.Cu")
		(net "M_H_CPU1_SA_DQ<22>")
	)
	(arc
		(start 143.462248 -238.497872)
		(mid 143.740934 -238.568092)
		(end 144.018 -238.491776)
		(width 0.0889)
		(layer "In13.Cu")
		(net "M_H_CPU1_SA_DQ<22>")
	)
	(arc
		(start 142.51178 -238.491776)
		(mid 142.794736 -238.567953)
		(end 143.077692 -238.491776)
		(width 0.0889)
		(layer "In13.Cu")
		(net "M_H_CPU1_SA_DQ<22>")
	)
	(arc
		(start 136.87171 -238.491776)
		(mid 137.154666 -238.567953)
		(end 137.437622 -238.491776)
		(width 0.0889)
		(layer "In13.Cu")
		(net "M_H_CPU1_SA_DQ<22>")
	)
	(arc
		(start 139.691872 -238.491776)
		(mid 139.974828 -238.567953)
		(end 140.257784 -238.491776)
		(width 0.0889)
		(layer "In13.Cu")
		(net "M_H_CPU1_SA_DQ<22>")
	)
	(arc
		(start 143.086074 -238.48695)
		(mid 143.269582 -238.441456)
		(end 143.451834 -238.491776)
		(width 0.0889)
		(layer "In13.Cu")
		(net "M_H_CPU1_SA_DQ<22>")
	)
	(arc
		(start 141.571726 -238.491776)
		(mid 141.854682 -238.567953)
		(end 142.137638 -238.491776)
		(width 0.0889)
		(layer "In13.Cu")
		(net "M_H_CPU1_SA_DQ<22>")
	)
	(arc
		(start 138.377676 -238.491776)
		(mid 138.559927 -238.441426)
		(end 138.743436 -238.48695)
		(width 0.0889)
		(layer "In13.Cu")
		(net "M_H_CPU1_SA_DQ<22>")
	)
	(arc
		(start 135.995156 -238.523526)
		(mid 136.250221 -238.566877)
		(end 136.497822 -238.491776)
		(width 0.0889)
		(layer "In13.Cu")
		(net "M_H_CPU1_SA_DQ<22>")
	)
	(arc
		(start 137.811764 -238.491776)
		(mid 138.09472 -238.567953)
		(end 138.377676 -238.491776)
		(width 0.0889)
		(layer "In13.Cu")
		(net "M_H_CPU1_SA_DQ<22>")
	)
	(segment
		(start 134.337806 -239.080294)
		(end 134.804658 -238.814356)
		(width 0.10668)
		(layer "F.Cu")
		(net "M_H_CPU1_SA_DQ<21>")
	)
	(segment
		(start 157.812994 -229.433882)
		(end 157.812994 -227.665026)
		(width 0.14478)
		(layer "In13.Cu")
		(net "M_H_CPU1_SA_DQ<21>")
	)
	(segment
		(start 143.077692 -239.136936)
		(end 143.086074 -239.141762)
		(width 0.0889)
		(layer "In13.Cu")
		(net "M_H_CPU1_SA_DQ<21>")
	)
	(segment
		(start 169.67962 -223.260412)
		(end 170.529504 -224.110296)
		(width 0.14478)
		(layer "In13.Cu")
		(net "M_H_CPU1_SA_DQ<21>")
	)
	(segment
		(start 135.557768 -239.136936)
		(end 135.56615 -239.141762)
		(width 0.0889)
		(layer "In13.Cu")
		(net "M_H_CPU1_SA_DQ<21>")
	)
	(segment
		(start 147.866608 -237.332774)
		(end 149.914102 -237.332774)
		(width 0.14478)
		(layer "In13.Cu")
		(net "M_H_CPU1_SA_DQ<21>")
	)
	(segment
		(start 134.804658 -238.814356)
		(end 134.650734 -239.079786)
		(width 0.0889)
		(layer "In13.Cu")
		(net "M_H_CPU1_SA_DQ<21>")
	)
	(segment
		(start 140.257784 -239.136936)
		(end 140.266166 -239.141762)
		(width 0.0889)
		(layer "In13.Cu")
		(net "M_H_CPU1_SA_DQ<21>")
	)
	(segment
		(start 142.503398 -239.141762)
		(end 142.51178 -239.136936)
		(width 0.0889)
		(layer "In13.Cu")
		(net "M_H_CPU1_SA_DQ<21>")
	)
	(segment
		(start 170.529504 -224.110296)
		(end 173.791118 -224.110296)
		(width 0.14478)
		(layer "In13.Cu")
		(net "M_H_CPU1_SA_DQ<21>")
	)
	(segment
		(start 143.451834 -239.136936)
		(end 143.462248 -239.13084)
		(width 0.0889)
		(layer "In13.Cu")
		(net "M_H_CPU1_SA_DQ<21>")
	)
	(segment
		(start 144.38376 -239.141762)
		(end 144.391888 -239.136936)
		(width 0.0889)
		(layer "In13.Cu")
		(net "M_H_CPU1_SA_DQ<21>")
	)
	(segment
		(start 157.812994 -227.665026)
		(end 160.162494 -225.315526)
		(width 0.14478)
		(layer "In13.Cu")
		(net "M_H_CPU1_SA_DQ<21>")
	)
	(segment
		(start 145.322798 -239.187482)
		(end 147.177506 -237.332774)
		(width 0.0889)
		(layer "In13.Cu")
		(net "M_H_CPU1_SA_DQ<21>")
	)
	(segment
		(start 160.162494 -225.315526)
		(end 161.142426 -225.315526)
		(width 0.14478)
		(layer "In13.Cu")
		(net "M_H_CPU1_SA_DQ<21>")
	)
	(segment
		(start 138.743436 -239.141762)
		(end 138.751818 -239.136936)
		(width 0.0889)
		(layer "In13.Cu")
		(net "M_H_CPU1_SA_DQ<21>")
	)
	(segment
		(start 174.21606 -223.685354)
		(end 176.072038 -223.685354)
		(width 0.14478)
		(layer "In13.Cu")
		(net "M_H_CPU1_SA_DQ<21>")
	)
	(segment
		(start 149.914102 -237.332774)
		(end 157.812994 -229.433882)
		(width 0.14478)
		(layer "In13.Cu")
		(net "M_H_CPU1_SA_DQ<21>")
	)
	(segment
		(start 161.142426 -225.315526)
		(end 162.347656 -224.110296)
		(width 0.14478)
		(layer "In13.Cu")
		(net "M_H_CPU1_SA_DQ<21>")
	)
	(segment
		(start 137.803382 -239.141762)
		(end 137.811764 -239.136936)
		(width 0.0889)
		(layer "In13.Cu")
		(net "M_H_CPU1_SA_DQ<21>")
	)
	(segment
		(start 145.144744 -239.187482)
		(end 145.322798 -239.187482)
		(width 0.0889)
		(layer "In13.Cu")
		(net "M_H_CPU1_SA_DQ<21>")
	)
	(segment
		(start 167.072056 -223.260412)
		(end 169.67962 -223.260412)
		(width 0.14478)
		(layer "In13.Cu")
		(net "M_H_CPU1_SA_DQ<21>")
	)
	(segment
		(start 173.791118 -224.110296)
		(end 174.21606 -223.685354)
		(width 0.14478)
		(layer "In13.Cu")
		(net "M_H_CPU1_SA_DQ<21>")
	)
	(segment
		(start 162.347656 -224.110296)
		(end 166.222172 -224.110296)
		(width 0.14478)
		(layer "In13.Cu")
		(net "M_H_CPU1_SA_DQ<21>")
	)
	(segment
		(start 139.31773 -239.136936)
		(end 139.326112 -239.141762)
		(width 0.0889)
		(layer "In13.Cu")
		(net "M_H_CPU1_SA_DQ<21>")
	)
	(segment
		(start 134.650734 -239.079786)
		(end 134.673086 -239.163098)
		(width 0.0889)
		(layer "In13.Cu")
		(net "M_H_CPU1_SA_DQ<21>")
	)
	(segment
		(start 166.222172 -224.110296)
		(end 167.072056 -223.260412)
		(width 0.14478)
		(layer "In13.Cu")
		(net "M_H_CPU1_SA_DQ<21>")
	)
	(segment
		(start 147.177506 -237.332774)
		(end 147.866608 -237.332774)
		(width 0.0889)
		(layer "In13.Cu")
		(net "M_H_CPU1_SA_DQ<21>")
	)
	(arc
		(start 136.497822 -239.136936)
		(mid 136.684766 -239.187191)
		(end 136.87171 -239.136936)
		(width 0.0889)
		(layer "In13.Cu")
		(net "M_H_CPU1_SA_DQ<21>")
	)
	(arc
		(start 142.51178 -239.136936)
		(mid 142.794736 -239.060759)
		(end 143.077692 -239.136936)
		(width 0.0889)
		(layer "In13.Cu")
		(net "M_H_CPU1_SA_DQ<21>")
	)
	(arc
		(start 144.018 -239.136936)
		(mid 144.200251 -239.187286)
		(end 144.38376 -239.141762)
		(width 0.0889)
		(layer "In13.Cu")
		(net "M_H_CPU1_SA_DQ<21>")
	)
	(arc
		(start 140.631926 -239.136936)
		(mid 140.914882 -239.060759)
		(end 141.197838 -239.136936)
		(width 0.0889)
		(layer "In13.Cu")
		(net "M_H_CPU1_SA_DQ<21>")
	)
	(arc
		(start 140.266166 -239.141762)
		(mid 140.449674 -239.187256)
		(end 140.631926 -239.136936)
		(width 0.0889)
		(layer "In13.Cu")
		(net "M_H_CPU1_SA_DQ<21>")
	)
	(arc
		(start 137.811764 -239.136936)
		(mid 138.09472 -239.060759)
		(end 138.377676 -239.136936)
		(width 0.0889)
		(layer "In13.Cu")
		(net "M_H_CPU1_SA_DQ<21>")
	)
	(arc
		(start 139.691872 -239.136936)
		(mid 139.974828 -239.060759)
		(end 140.257784 -239.136936)
		(width 0.0889)
		(layer "In13.Cu")
		(net "M_H_CPU1_SA_DQ<21>")
	)
	(arc
		(start 137.437622 -239.136936)
		(mid 137.619873 -239.187286)
		(end 137.803382 -239.141762)
		(width 0.0889)
		(layer "In13.Cu")
		(net "M_H_CPU1_SA_DQ<21>")
	)
	(arc
		(start 136.87171 -239.136936)
		(mid 137.154666 -239.060759)
		(end 137.437622 -239.136936)
		(width 0.0889)
		(layer "In13.Cu")
		(net "M_H_CPU1_SA_DQ<21>")
	)
	(arc
		(start 134.673086 -239.163098)
		(mid 134.835418 -239.185916)
		(end 134.991856 -239.136936)
		(width 0.0889)
		(layer "In13.Cu")
		(net "M_H_CPU1_SA_DQ<21>")
	)
	(arc
		(start 142.137638 -239.136936)
		(mid 142.319889 -239.187286)
		(end 142.503398 -239.141762)
		(width 0.0889)
		(layer "In13.Cu")
		(net "M_H_CPU1_SA_DQ<21>")
	)
	(arc
		(start 141.197838 -239.136936)
		(mid 141.384782 -239.187191)
		(end 141.571726 -239.136936)
		(width 0.0889)
		(layer "In13.Cu")
		(net "M_H_CPU1_SA_DQ<21>")
	)
	(arc
		(start 135.93191 -239.136936)
		(mid 136.214866 -239.060759)
		(end 136.497822 -239.136936)
		(width 0.0889)
		(layer "In13.Cu")
		(net "M_H_CPU1_SA_DQ<21>")
	)
	(arc
		(start 144.391888 -239.136936)
		(mid 144.674844 -239.060759)
		(end 144.9578 -239.136936)
		(width 0.0889)
		(layer "In13.Cu")
		(net "M_H_CPU1_SA_DQ<21>")
	)
	(arc
		(start 144.9578 -239.136936)
		(mid 145.047933 -239.174556)
		(end 145.144744 -239.187482)
		(width 0.0889)
		(layer "In13.Cu")
		(net "M_H_CPU1_SA_DQ<21>")
	)
	(arc
		(start 138.751818 -239.136936)
		(mid 139.034774 -239.060759)
		(end 139.31773 -239.136936)
		(width 0.0889)
		(layer "In13.Cu")
		(net "M_H_CPU1_SA_DQ<21>")
	)
	(arc
		(start 134.991856 -239.136936)
		(mid 135.274812 -239.060759)
		(end 135.557768 -239.136936)
		(width 0.0889)
		(layer "In13.Cu")
		(net "M_H_CPU1_SA_DQ<21>")
	)
	(arc
		(start 143.462248 -239.13084)
		(mid 143.740934 -239.06062)
		(end 144.018 -239.136936)
		(width 0.0889)
		(layer "In13.Cu")
		(net "M_H_CPU1_SA_DQ<21>")
	)
	(arc
		(start 141.571726 -239.136936)
		(mid 141.854682 -239.060759)
		(end 142.137638 -239.136936)
		(width 0.0889)
		(layer "In13.Cu")
		(net "M_H_CPU1_SA_DQ<21>")
	)
	(arc
		(start 143.086074 -239.141762)
		(mid 143.269582 -239.187256)
		(end 143.451834 -239.136936)
		(width 0.0889)
		(layer "In13.Cu")
		(net "M_H_CPU1_SA_DQ<21>")
	)
	(arc
		(start 139.326112 -239.141762)
		(mid 139.50962 -239.187256)
		(end 139.691872 -239.136936)
		(width 0.0889)
		(layer "In13.Cu")
		(net "M_H_CPU1_SA_DQ<21>")
	)
	(arc
		(start 138.377676 -239.136936)
		(mid 138.559927 -239.187286)
		(end 138.743436 -239.141762)
		(width 0.0889)
		(layer "In13.Cu")
		(net "M_H_CPU1_SA_DQ<21>")
	)
	(arc
		(start 135.56615 -239.141762)
		(mid 135.749658 -239.187256)
		(end 135.93191 -239.136936)
		(width 0.0889)
		(layer "In13.Cu")
		(net "M_H_CPU1_SA_DQ<21>")
	)
	(segment
		(start 135.748014 -238.270288)
		(end 136.214866 -238.00435)
		(width 0.10668)
		(layer "F.Cu")
		(net "M_H_CPU1_SA_DQ<20>")
	)
	(segment
		(start 143.555974 -238.331756)
		(end 143.547592 -238.32693)
		(width 0.0889)
		(layer "In13.Cu")
		(net "M_H_CPU1_SA_DQ<20>")
	)
	(segment
		(start 137.916158 -238.331756)
		(end 137.907776 -238.32693)
		(width 0.0889)
		(layer "In13.Cu")
		(net "M_H_CPU1_SA_DQ<20>")
	)
	(segment
		(start 174.713646 -221.985332)
		(end 174.078138 -221.985332)
		(width 0.14478)
		(layer "In13.Cu")
		(net "M_H_CPU1_SA_DQ<20>")
	)
	(segment
		(start 173.643544 -222.419926)
		(end 170.405552 -222.419926)
		(width 0.14478)
		(layer "In13.Cu")
		(net "M_H_CPU1_SA_DQ<20>")
	)
	(segment
		(start 144.488408 -238.32693)
		(end 144.477994 -238.320834)
		(width 0.0889)
		(layer "In13.Cu")
		(net "M_H_CPU1_SA_DQ<20>")
	)
	(segment
		(start 147.856194 -236.423454)
		(end 147.499324 -236.423454)
		(width 0.0889)
		(layer "In13.Cu")
		(net "M_H_CPU1_SA_DQ<20>")
	)
	(segment
		(start 156.913834 -226.656646)
		(end 156.913834 -229.024942)
		(width 0.14478)
		(layer "In13.Cu")
		(net "M_H_CPU1_SA_DQ<20>")
	)
	(segment
		(start 147.499324 -236.423454)
		(end 145.672302 -238.250476)
		(width 0.0889)
		(layer "In13.Cu")
		(net "M_H_CPU1_SA_DQ<20>")
	)
	(segment
		(start 136.08304 -238.353092)
		(end 136.060688 -238.26978)
		(width 0.0889)
		(layer "In13.Cu")
		(net "M_H_CPU1_SA_DQ<20>")
	)
	(segment
		(start 141.101826 -238.32693)
		(end 141.093444 -238.331756)
		(width 0.0889)
		(layer "In13.Cu")
		(net "M_H_CPU1_SA_DQ<20>")
	)
	(segment
		(start 159.154114 -224.416366)
		(end 156.913834 -226.656646)
		(width 0.14478)
		(layer "In13.Cu")
		(net "M_H_CPU1_SA_DQ<20>")
	)
	(segment
		(start 140.161772 -238.32693)
		(end 140.15339 -238.331756)
		(width 0.0889)
		(layer "In13.Cu")
		(net "M_H_CPU1_SA_DQ<20>")
	)
	(segment
		(start 174.078138 -221.985332)
		(end 173.643544 -222.419926)
		(width 0.14478)
		(layer "In13.Cu")
		(net "M_H_CPU1_SA_DQ<20>")
	)
	(segment
		(start 149.515322 -236.423454)
		(end 147.856194 -236.423454)
		(width 0.14478)
		(layer "In13.Cu")
		(net "M_H_CPU1_SA_DQ<20>")
	)
	(segment
		(start 175.264826 -222.668338)
		(end 175.003206 -222.668338)
		(width 0.14478)
		(layer "In13.Cu")
		(net "M_H_CPU1_SA_DQ<20>")
	)
	(segment
		(start 136.40181 -238.32693)
		(end 136.393428 -238.331756)
		(width 0.0889)
		(layer "In13.Cu")
		(net "M_H_CPU1_SA_DQ<20>")
	)
	(segment
		(start 175.409606 -222.130112)
		(end 175.409606 -222.523558)
		(width 0.14478)
		(layer "In13.Cu")
		(net "M_H_CPU1_SA_DQ<20>")
	)
	(segment
		(start 136.976104 -238.331756)
		(end 136.967722 -238.32693)
		(width 0.0889)
		(layer "In13.Cu")
		(net "M_H_CPU1_SA_DQ<20>")
	)
	(segment
		(start 175.003206 -222.668338)
		(end 174.858426 -222.523558)
		(width 0.14478)
		(layer "In13.Cu")
		(net "M_H_CPU1_SA_DQ<20>")
	)
	(segment
		(start 169.546016 -221.56039)
		(end 167.18026 -221.56039)
		(width 0.14478)
		(layer "In13.Cu")
		(net "M_H_CPU1_SA_DQ<20>")
	)
	(segment
		(start 174.858426 -222.523558)
		(end 174.858426 -222.130112)
		(width 0.14478)
		(layer "In13.Cu")
		(net "M_H_CPU1_SA_DQ<20>")
	)
	(segment
		(start 175.409606 -222.523558)
		(end 175.264826 -222.668338)
		(width 0.14478)
		(layer "In13.Cu")
		(net "M_H_CPU1_SA_DQ<20>")
	)
	(segment
		(start 174.858426 -222.130112)
		(end 174.713646 -221.985332)
		(width 0.14478)
		(layer "In13.Cu")
		(net "M_H_CPU1_SA_DQ<20>")
	)
	(segment
		(start 176.072038 -221.985332)
		(end 175.554386 -221.985332)
		(width 0.14478)
		(layer "In13.Cu")
		(net "M_H_CPU1_SA_DQ<20>")
	)
	(segment
		(start 175.554386 -221.985332)
		(end 175.409606 -222.130112)
		(width 0.14478)
		(layer "In13.Cu")
		(net "M_H_CPU1_SA_DQ<20>")
	)
	(segment
		(start 156.913834 -229.024942)
		(end 149.515322 -236.423454)
		(width 0.14478)
		(layer "In13.Cu")
		(net "M_H_CPU1_SA_DQ<20>")
	)
	(segment
		(start 145.672302 -238.250476)
		(end 145.144744 -238.250476)
		(width 0.0889)
		(layer "In13.Cu")
		(net "M_H_CPU1_SA_DQ<20>")
	)
	(segment
		(start 167.18026 -221.56039)
		(end 166.330376 -222.410274)
		(width 0.14478)
		(layer "In13.Cu")
		(net "M_H_CPU1_SA_DQ<20>")
	)
	(segment
		(start 166.330376 -222.410274)
		(end 162.359594 -222.410274)
		(width 0.14478)
		(layer "In13.Cu")
		(net "M_H_CPU1_SA_DQ<20>")
	)
	(segment
		(start 170.405552 -222.419926)
		(end 169.546016 -221.56039)
		(width 0.14478)
		(layer "In13.Cu")
		(net "M_H_CPU1_SA_DQ<20>")
	)
	(segment
		(start 160.353502 -224.416366)
		(end 159.154114 -224.416366)
		(width 0.14478)
		(layer "In13.Cu")
		(net "M_H_CPU1_SA_DQ<20>")
	)
	(segment
		(start 162.359594 -222.410274)
		(end 160.353502 -224.416366)
		(width 0.14478)
		(layer "In13.Cu")
		(net "M_H_CPU1_SA_DQ<20>")
	)
	(segment
		(start 136.060688 -238.26978)
		(end 136.214866 -238.00435)
		(width 0.0889)
		(layer "In13.Cu")
		(net "M_H_CPU1_SA_DQ<20>")
	)
	(segment
		(start 141.67612 -238.331756)
		(end 141.667738 -238.32693)
		(width 0.0889)
		(layer "In13.Cu")
		(net "M_H_CPU1_SA_DQ<20>")
	)
	(arc
		(start 143.547592 -238.32693)
		(mid 143.264636 -238.250753)
		(end 142.98168 -238.32693)
		(width 0.0889)
		(layer "In13.Cu")
		(net "M_H_CPU1_SA_DQ<20>")
	)
	(arc
		(start 137.907776 -238.32693)
		(mid 137.62482 -238.250753)
		(end 137.341864 -238.32693)
		(width 0.0889)
		(layer "In13.Cu")
		(net "M_H_CPU1_SA_DQ<20>")
	)
	(arc
		(start 136.393428 -238.331756)
		(mid 136.240558 -238.376397)
		(end 136.08304 -238.353092)
		(width 0.0889)
		(layer "In13.Cu")
		(net "M_H_CPU1_SA_DQ<20>")
	)
	(arc
		(start 139.221718 -238.32693)
		(mid 139.034774 -238.377185)
		(end 138.84783 -238.32693)
		(width 0.0889)
		(layer "In13.Cu")
		(net "M_H_CPU1_SA_DQ<20>")
	)
	(arc
		(start 138.84783 -238.32693)
		(mid 138.564874 -238.250753)
		(end 138.281918 -238.32693)
		(width 0.0889)
		(layer "In13.Cu")
		(net "M_H_CPU1_SA_DQ<20>")
	)
	(arc
		(start 141.093444 -238.331756)
		(mid 140.909936 -238.37725)
		(end 140.727684 -238.32693)
		(width 0.0889)
		(layer "In13.Cu")
		(net "M_H_CPU1_SA_DQ<20>")
	)
	(arc
		(start 142.98168 -238.32693)
		(mid 142.794736 -238.377185)
		(end 142.607792 -238.32693)
		(width 0.0889)
		(layer "In13.Cu")
		(net "M_H_CPU1_SA_DQ<20>")
	)
	(arc
		(start 138.281918 -238.32693)
		(mid 138.099667 -238.37728)
		(end 137.916158 -238.331756)
		(width 0.0889)
		(layer "In13.Cu")
		(net "M_H_CPU1_SA_DQ<20>")
	)
	(arc
		(start 137.341864 -238.32693)
		(mid 137.159613 -238.37728)
		(end 136.976104 -238.331756)
		(width 0.0889)
		(layer "In13.Cu")
		(net "M_H_CPU1_SA_DQ<20>")
	)
	(arc
		(start 141.667738 -238.32693)
		(mid 141.384782 -238.250753)
		(end 141.101826 -238.32693)
		(width 0.0889)
		(layer "In13.Cu")
		(net "M_H_CPU1_SA_DQ<20>")
	)
	(arc
		(start 145.144744 -238.250476)
		(mid 144.989383 -238.272301)
		(end 144.84604 -238.336074)
		(width 0.0889)
		(layer "In13.Cu")
		(net "M_H_CPU1_SA_DQ<20>")
	)
	(arc
		(start 144.84604 -238.336074)
		(mid 144.666058 -238.377174)
		(end 144.488408 -238.32693)
		(width 0.0889)
		(layer "In13.Cu")
		(net "M_H_CPU1_SA_DQ<20>")
	)
	(arc
		(start 139.78763 -238.32693)
		(mid 139.504674 -238.250753)
		(end 139.221718 -238.32693)
		(width 0.0889)
		(layer "In13.Cu")
		(net "M_H_CPU1_SA_DQ<20>")
	)
	(arc
		(start 143.922242 -238.32693)
		(mid 143.739737 -238.377407)
		(end 143.555974 -238.331756)
		(width 0.0889)
		(layer "In13.Cu")
		(net "M_H_CPU1_SA_DQ<20>")
	)
	(arc
		(start 142.607792 -238.32693)
		(mid 142.324836 -238.250753)
		(end 142.04188 -238.32693)
		(width 0.0889)
		(layer "In13.Cu")
		(net "M_H_CPU1_SA_DQ<20>")
	)
	(arc
		(start 140.15339 -238.331756)
		(mid 139.969882 -238.37725)
		(end 139.78763 -238.32693)
		(width 0.0889)
		(layer "In13.Cu")
		(net "M_H_CPU1_SA_DQ<20>")
	)
	(arc
		(start 142.04188 -238.32693)
		(mid 141.859629 -238.37728)
		(end 141.67612 -238.331756)
		(width 0.0889)
		(layer "In13.Cu")
		(net "M_H_CPU1_SA_DQ<20>")
	)
	(arc
		(start 144.477994 -238.320834)
		(mid 144.199308 -238.250614)
		(end 143.922242 -238.32693)
		(width 0.0889)
		(layer "In13.Cu")
		(net "M_H_CPU1_SA_DQ<20>")
	)
	(arc
		(start 136.967722 -238.32693)
		(mid 136.684766 -238.250753)
		(end 136.40181 -238.32693)
		(width 0.0889)
		(layer "In13.Cu")
		(net "M_H_CPU1_SA_DQ<20>")
	)
	(arc
		(start 140.727684 -238.32693)
		(mid 140.444728 -238.250753)
		(end 140.161772 -238.32693)
		(width 0.0889)
		(layer "In13.Cu")
		(net "M_H_CPU1_SA_DQ<20>")
	)
	(segment
		(start 134.337806 -226.120452)
		(end 134.804658 -225.854514)
		(width 0.10668)
		(layer "F.Cu")
		(net "M_H_CPU1_SA_DQ<1>")
	)
	(segment
		(start 143.170402 -221.545658)
		(end 143.022828 -221.398084)
		(width 0.0889)
		(layer "In13.Cu")
		(net "M_H_CPU1_SA_DQ<1>")
	)
	(segment
		(start 171.766484 -199.460358)
		(end 173.938438 -199.460358)
		(width 0.14478)
		(layer "In13.Cu")
		(net "M_H_CPU1_SA_DQ<1>")
	)
	(segment
		(start 141.101826 -225.367088)
		(end 141.133576 -225.3488)
		(width 0.0889)
		(layer "In13.Cu")
		(net "M_H_CPU1_SA_DQ<1>")
	)
	(segment
		(start 166.68877 -199.010778)
		(end 170.681142 -199.010778)
		(width 0.14478)
		(layer "In13.Cu")
		(net "M_H_CPU1_SA_DQ<1>")
	)
	(segment
		(start 139.31773 -226.177094)
		(end 139.326112 -226.18192)
		(width 0.0889)
		(layer "In13.Cu")
		(net "M_H_CPU1_SA_DQ<1>")
	)
	(segment
		(start 142.947136 -222.14713)
		(end 142.982442 -222.12681)
		(width 0.0889)
		(layer "In13.Cu")
		(net "M_H_CPU1_SA_DQ<1>")
	)
	(segment
		(start 159.43326 -199.870568)
		(end 164.613082 -199.870568)
		(width 0.14478)
		(layer "In13.Cu")
		(net "M_H_CPU1_SA_DQ<1>")
	)
	(segment
		(start 149.68855 -209.615278)
		(end 159.43326 -199.870568)
		(width 0.14478)
		(layer "In13.Cu")
		(net "M_H_CPU1_SA_DQ<1>")
	)
	(segment
		(start 170.681142 -199.010778)
		(end 171.766484 -199.460358)
		(width 0.14478)
		(layer "In13.Cu")
		(net "M_H_CPU1_SA_DQ<1>")
	)
	(segment
		(start 173.938438 -199.460358)
		(end 176.07153 -199.036178)
		(width 0.14478)
		(layer "In13.Cu")
		(net "M_H_CPU1_SA_DQ<1>")
	)
	(segment
		(start 141.06271 -225.389948)
		(end 141.101826 -225.367088)
		(width 0.0889)
		(layer "In13.Cu")
		(net "M_H_CPU1_SA_DQ<1>")
	)
	(segment
		(start 176.07153 -199.036178)
		(end 176.072038 -199.035416)
		(width 0.14478)
		(layer "In13.Cu")
		(net "M_H_CPU1_SA_DQ<1>")
	)
	(segment
		(start 142.47876 -222.956374)
		(end 142.512288 -222.936816)
		(width 0.0889)
		(layer "In13.Cu")
		(net "M_H_CPU1_SA_DQ<1>")
	)
	(segment
		(start 134.804658 -225.854514)
		(end 134.650734 -226.119944)
		(width 0.0889)
		(layer "In13.Cu")
		(net "M_H_CPU1_SA_DQ<1>")
	)
	(segment
		(start 149.68855 -210.831938)
		(end 149.68855 -209.615278)
		(width 0.14478)
		(layer "In13.Cu")
		(net "M_H_CPU1_SA_DQ<1>")
	)
	(segment
		(start 141.571726 -224.557082)
		(end 141.603476 -224.538794)
		(width 0.0889)
		(layer "In13.Cu")
		(net "M_H_CPU1_SA_DQ<1>")
	)
	(segment
		(start 143.022828 -217.49766)
		(end 149.68855 -210.831938)
		(width 0.14478)
		(layer "In13.Cu")
		(net "M_H_CPU1_SA_DQ<1>")
	)
	(segment
		(start 140.257784 -226.177094)
		(end 140.266166 -226.18192)
		(width 0.0889)
		(layer "In13.Cu")
		(net "M_H_CPU1_SA_DQ<1>")
	)
	(segment
		(start 138.743436 -226.18192)
		(end 138.751818 -226.177094)
		(width 0.0889)
		(layer "In13.Cu")
		(net "M_H_CPU1_SA_DQ<1>")
	)
	(segment
		(start 140.631926 -226.177094)
		(end 140.662406 -226.159314)
		(width 0.0889)
		(layer "In13.Cu")
		(net "M_H_CPU1_SA_DQ<1>")
	)
	(segment
		(start 141.535404 -224.578164)
		(end 141.571726 -224.557082)
		(width 0.0889)
		(layer "In13.Cu")
		(net "M_H_CPU1_SA_DQ<1>")
	)
	(segment
		(start 142.512288 -222.936816)
		(end 142.542514 -222.91929)
		(width 0.0889)
		(layer "In13.Cu")
		(net "M_H_CPU1_SA_DQ<1>")
	)
	(segment
		(start 142.042134 -223.747076)
		(end 142.072868 -223.729296)
		(width 0.0889)
		(layer "In13.Cu")
		(net "M_H_CPU1_SA_DQ<1>")
	)
	(segment
		(start 143.022828 -221.398084)
		(end 143.022828 -221.288864)
		(width 0.0889)
		(layer "In13.Cu")
		(net "M_H_CPU1_SA_DQ<1>")
	)
	(segment
		(start 143.170402 -221.804484)
		(end 143.170402 -221.545658)
		(width 0.0889)
		(layer "In13.Cu")
		(net "M_H_CPU1_SA_DQ<1>")
	)
	(segment
		(start 142.982442 -222.12681)
		(end 143.016986 -222.106744)
		(width 0.0889)
		(layer "In13.Cu")
		(net "M_H_CPU1_SA_DQ<1>")
	)
	(segment
		(start 143.022828 -221.288864)
		(end 143.022828 -217.49766)
		(width 0.14478)
		(layer "In13.Cu")
		(net "M_H_CPU1_SA_DQ<1>")
	)
	(segment
		(start 137.803382 -226.18192)
		(end 137.811764 -226.177094)
		(width 0.0889)
		(layer "In13.Cu")
		(net "M_H_CPU1_SA_DQ<1>")
	)
	(segment
		(start 134.650734 -226.119944)
		(end 134.673086 -226.203256)
		(width 0.0889)
		(layer "In13.Cu")
		(net "M_H_CPU1_SA_DQ<1>")
	)
	(segment
		(start 164.613082 -199.870568)
		(end 166.68877 -199.010778)
		(width 0.14478)
		(layer "In13.Cu")
		(net "M_H_CPU1_SA_DQ<1>")
	)
	(segment
		(start 142.001748 -223.770698)
		(end 142.042134 -223.747076)
		(width 0.0889)
		(layer "In13.Cu")
		(net "M_H_CPU1_SA_DQ<1>")
	)
	(segment
		(start 135.557768 -226.177094)
		(end 135.56615 -226.18192)
		(width 0.0889)
		(layer "In13.Cu")
		(net "M_H_CPU1_SA_DQ<1>")
	)
	(arc
		(start 142.69974 -222.61449)
		(mid 142.765403 -222.350089)
		(end 142.947136 -222.14713)
		(width 0.0889)
		(layer "In13.Cu")
		(net "M_H_CPU1_SA_DQ<1>")
	)
	(arc
		(start 138.377676 -226.177094)
		(mid 138.559927 -226.227444)
		(end 138.743436 -226.18192)
		(width 0.0889)
		(layer "In13.Cu")
		(net "M_H_CPU1_SA_DQ<1>")
	)
	(arc
		(start 137.811764 -226.177094)
		(mid 138.09472 -226.100917)
		(end 138.377676 -226.177094)
		(width 0.0889)
		(layer "In13.Cu")
		(net "M_H_CPU1_SA_DQ<1>")
	)
	(arc
		(start 137.437622 -226.177094)
		(mid 137.619873 -226.227444)
		(end 137.803382 -226.18192)
		(width 0.0889)
		(layer "In13.Cu")
		(net "M_H_CPU1_SA_DQ<1>")
	)
	(arc
		(start 141.289532 -225.044508)
		(mid 141.354768 -224.780917)
		(end 141.535404 -224.578164)
		(width 0.0889)
		(layer "In13.Cu")
		(net "M_H_CPU1_SA_DQ<1>")
	)
	(arc
		(start 139.691872 -226.177094)
		(mid 139.974828 -226.100917)
		(end 140.257784 -226.177094)
		(width 0.0889)
		(layer "In13.Cu")
		(net "M_H_CPU1_SA_DQ<1>")
	)
	(arc
		(start 135.56615 -226.18192)
		(mid 135.749658 -226.227414)
		(end 135.93191 -226.177094)
		(width 0.0889)
		(layer "In13.Cu")
		(net "M_H_CPU1_SA_DQ<1>")
	)
	(arc
		(start 140.662406 -226.159314)
		(mid 140.777833 -226.025938)
		(end 140.819378 -225.854514)
		(width 0.0889)
		(layer "In13.Cu")
		(net "M_H_CPU1_SA_DQ<1>")
	)
	(arc
		(start 136.497822 -226.177094)
		(mid 136.684766 -226.227349)
		(end 136.87171 -226.177094)
		(width 0.0889)
		(layer "In13.Cu")
		(net "M_H_CPU1_SA_DQ<1>")
	)
	(arc
		(start 134.991856 -226.177094)
		(mid 135.274812 -226.100917)
		(end 135.557768 -226.177094)
		(width 0.0889)
		(layer "In13.Cu")
		(net "M_H_CPU1_SA_DQ<1>")
	)
	(arc
		(start 141.759432 -224.234502)
		(mid 141.823725 -223.972897)
		(end 142.001748 -223.770698)
		(width 0.0889)
		(layer "In13.Cu")
		(net "M_H_CPU1_SA_DQ<1>")
	)
	(arc
		(start 141.603476 -224.538794)
		(mid 141.718152 -224.40546)
		(end 141.759432 -224.234502)
		(width 0.0889)
		(layer "In13.Cu")
		(net "M_H_CPU1_SA_DQ<1>")
	)
	(arc
		(start 140.819378 -225.854514)
		(mid 140.883893 -225.592295)
		(end 141.06271 -225.389948)
		(width 0.0889)
		(layer "In13.Cu")
		(net "M_H_CPU1_SA_DQ<1>")
	)
	(arc
		(start 142.542514 -222.91929)
		(mid 142.658093 -222.785963)
		(end 142.69974 -222.61449)
		(width 0.0889)
		(layer "In13.Cu")
		(net "M_H_CPU1_SA_DQ<1>")
	)
	(arc
		(start 136.87171 -226.177094)
		(mid 137.154666 -226.100917)
		(end 137.437622 -226.177094)
		(width 0.0889)
		(layer "In13.Cu")
		(net "M_H_CPU1_SA_DQ<1>")
	)
	(arc
		(start 138.751818 -226.177094)
		(mid 139.034774 -226.100917)
		(end 139.31773 -226.177094)
		(width 0.0889)
		(layer "In13.Cu")
		(net "M_H_CPU1_SA_DQ<1>")
	)
	(arc
		(start 142.22984 -223.424496)
		(mid 142.295939 -223.159402)
		(end 142.47876 -222.956374)
		(width 0.0889)
		(layer "In13.Cu")
		(net "M_H_CPU1_SA_DQ<1>")
	)
	(arc
		(start 143.016986 -222.106744)
		(mid 143.129872 -221.973973)
		(end 143.170402 -221.804484)
		(width 0.0889)
		(layer "In13.Cu")
		(net "M_H_CPU1_SA_DQ<1>")
	)
	(arc
		(start 140.266166 -226.18192)
		(mid 140.449674 -226.227414)
		(end 140.631926 -226.177094)
		(width 0.0889)
		(layer "In13.Cu")
		(net "M_H_CPU1_SA_DQ<1>")
	)
	(arc
		(start 139.326112 -226.18192)
		(mid 139.50962 -226.227414)
		(end 139.691872 -226.177094)
		(width 0.0889)
		(layer "In13.Cu")
		(net "M_H_CPU1_SA_DQ<1>")
	)
	(arc
		(start 135.93191 -226.177094)
		(mid 136.214866 -226.100917)
		(end 136.497822 -226.177094)
		(width 0.0889)
		(layer "In13.Cu")
		(net "M_H_CPU1_SA_DQ<1>")
	)
	(arc
		(start 134.673086 -226.203256)
		(mid 134.835418 -226.226074)
		(end 134.991856 -226.177094)
		(width 0.0889)
		(layer "In13.Cu")
		(net "M_H_CPU1_SA_DQ<1>")
	)
	(arc
		(start 142.072868 -223.729296)
		(mid 142.188295 -223.59592)
		(end 142.22984 -223.424496)
		(width 0.0889)
		(layer "In13.Cu")
		(net "M_H_CPU1_SA_DQ<1>")
	)
	(arc
		(start 141.133576 -225.3488)
		(mid 141.248252 -225.215466)
		(end 141.289532 -225.044508)
		(width 0.0889)
		(layer "In13.Cu")
		(net "M_H_CPU1_SA_DQ<1>")
	)
	(segment
		(start 133.867906 -236.650276)
		(end 134.334758 -236.384338)
		(width 0.10668)
		(layer "F.Cu")
		(net "M_H_CPU1_SA_DQ<19>")
	)
	(segment
		(start 154.625294 -228.046026)
		(end 148.709126 -233.962194)
		(width 0.14478)
		(layer "In13.Cu")
		(net "M_H_CPU1_SA_DQ<19>")
	)
	(segment
		(start 163.186872 -219.031058)
		(end 162.982148 -219.031312)
		(width 0.14478)
		(layer "In13.Cu")
		(net "M_H_CPU1_SA_DQ<19>")
	)
	(segment
		(start 161.081212 -219.90304)
		(end 160.373568 -219.90304)
		(width 0.14478)
		(layer "In13.Cu")
		(net "M_H_CPU1_SA_DQ<19>")
	)
	(segment
		(start 170.02506 -218.305126)
		(end 170.02506 -218.310714)
		(width 0.14478)
		(layer "In13.Cu")
		(net "M_H_CPU1_SA_DQ<19>")
	)
	(segment
		(start 137.916158 -236.056932)
		(end 137.907776 -236.061758)
		(width 0.0889)
		(layer "In13.Cu")
		(net "M_H_CPU1_SA_DQ<19>")
	)
	(segment
		(start 166.331646 -218.744546)
		(end 165.579044 -218.744546)
		(width 0.14478)
		(layer "In13.Cu")
		(net "M_H_CPU1_SA_DQ<19>")
	)
	(segment
		(start 162.592258 -219.625672)
		(end 162.31489 -219.90304)
		(width 0.14478)
		(layer "In13.Cu")
		(net "M_H_CPU1_SA_DQ<19>")
	)
	(segment
		(start 168.37152 -218.310714)
		(end 168.37152 -218.305126)
		(width 0.14478)
		(layer "In13.Cu")
		(net "M_H_CPU1_SA_DQ<19>")
	)
	(segment
		(start 145.430748 -236.138212)
		(end 144.20596 -236.138212)
		(width 0.0889)
		(layer "In13.Cu")
		(net "M_H_CPU1_SA_DQ<19>")
	)
	(segment
		(start 169.88028 -218.455494)
		(end 169.61866 -218.455494)
		(width 0.14478)
		(layer "In13.Cu")
		(net "M_H_CPU1_SA_DQ<19>")
	)
	(segment
		(start 163.664392 -218.744546)
		(end 163.473384 -218.744546)
		(width 0.14478)
		(layer "In13.Cu")
		(net "M_H_CPU1_SA_DQ<19>")
	)
	(segment
		(start 161.370772 -219.351098)
		(end 161.225992 -219.495878)
		(width 0.14478)
		(layer "In13.Cu")
		(net "M_H_CPU1_SA_DQ<19>")
	)
	(segment
		(start 168.9227 -218.305126)
		(end 168.9227 -218.310714)
		(width 0.14478)
		(layer "In13.Cu")
		(net "M_H_CPU1_SA_DQ<19>")
	)
	(segment
		(start 146.9009 -234.578144)
		(end 146.645376 -234.578144)
		(width 0.0889)
		(layer "In13.Cu")
		(net "M_H_CPU1_SA_DQ<19>")
	)
	(segment
		(start 171.55668 -219.000578)
		(end 171.233084 -219.000578)
		(width 0.14478)
		(layer "In13.Cu")
		(net "M_H_CPU1_SA_DQ<19>")
	)
	(segment
		(start 148.709126 -233.962194)
		(end 147.828254 -233.962194)
		(width 0.14478)
		(layer "In13.Cu")
		(net "M_H_CPU1_SA_DQ<19>")
	)
	(segment
		(start 162.361372 -218.9861)
		(end 162.361626 -219.190316)
		(width 0.14478)
		(layer "In13.Cu")
		(net "M_H_CPU1_SA_DQ<19>")
	)
	(segment
		(start 164.766752 -218.744546)
		(end 164.476684 -218.744546)
		(width 0.14478)
		(layer "In13.Cu")
		(net "M_H_CPU1_SA_DQ<19>")
	)
	(segment
		(start 165.027864 -219.005658)
		(end 164.766752 -218.744546)
		(width 0.14478)
		(layer "In13.Cu")
		(net "M_H_CPU1_SA_DQ<19>")
	)
	(segment
		(start 165.317932 -219.005658)
		(end 165.027864 -219.005658)
		(width 0.14478)
		(layer "In13.Cu")
		(net "M_H_CPU1_SA_DQ<19>")
	)
	(segment
		(start 168.37152 -218.305126)
		(end 168.22674 -218.160346)
		(width 0.14478)
		(layer "In13.Cu")
		(net "M_H_CPU1_SA_DQ<19>")
	)
	(segment
		(start 134.488682 -236.118908)
		(end 134.334758 -236.384338)
		(width 0.0889)
		(layer "In13.Cu")
		(net "M_H_CPU1_SA_DQ<19>")
	)
	(segment
		(start 161.777172 -219.495878)
		(end 161.632392 -219.351098)
		(width 0.14478)
		(layer "In13.Cu")
		(net "M_H_CPU1_SA_DQ<19>")
	)
	(segment
		(start 147.828254 -233.962194)
		(end 147.51685 -233.962194)
		(width 0.0889)
		(layer "In13.Cu")
		(net "M_H_CPU1_SA_DQ<19>")
	)
	(segment
		(start 170.392852 -218.160346)
		(end 170.16984 -218.160346)
		(width 0.14478)
		(layer "In13.Cu")
		(net "M_H_CPU1_SA_DQ<19>")
	)
	(segment
		(start 154.625294 -225.651314)
		(end 154.625294 -228.046026)
		(width 0.14478)
		(layer "In13.Cu")
		(net "M_H_CPU1_SA_DQ<19>")
	)
	(segment
		(start 170.02506 -218.310714)
		(end 169.88028 -218.455494)
		(width 0.14478)
		(layer "In13.Cu")
		(net "M_H_CPU1_SA_DQ<19>")
	)
	(segment
		(start 162.982148 -219.031312)
		(end 162.751516 -218.80068)
		(width 0.14478)
		(layer "In13.Cu")
		(net "M_H_CPU1_SA_DQ<19>")
	)
	(segment
		(start 161.225992 -219.75826)
		(end 161.081212 -219.90304)
		(width 0.14478)
		(layer "In13.Cu")
		(net "M_H_CPU1_SA_DQ<19>")
	)
	(segment
		(start 136.40181 -236.061758)
		(end 136.393428 -236.056932)
		(width 0.0889)
		(layer "In13.Cu")
		(net "M_H_CPU1_SA_DQ<19>")
	)
	(segment
		(start 168.9227 -218.310714)
		(end 168.77792 -218.455494)
		(width 0.14478)
		(layer "In13.Cu")
		(net "M_H_CPU1_SA_DQ<19>")
	)
	(segment
		(start 161.225992 -219.495878)
		(end 161.225992 -219.75826)
		(width 0.14478)
		(layer "In13.Cu")
		(net "M_H_CPU1_SA_DQ<19>")
	)
	(segment
		(start 160.373568 -219.90304)
		(end 154.625294 -225.651314)
		(width 0.14478)
		(layer "In13.Cu")
		(net "M_H_CPU1_SA_DQ<19>")
	)
	(segment
		(start 141.67612 -236.056932)
		(end 141.667738 -236.061758)
		(width 0.0889)
		(layer "In13.Cu")
		(net "M_H_CPU1_SA_DQ<19>")
	)
	(segment
		(start 140.161772 -236.061758)
		(end 140.15339 -236.056932)
		(width 0.0889)
		(layer "In13.Cu")
		(net "M_H_CPU1_SA_DQ<19>")
	)
	(segment
		(start 162.546792 -218.80068)
		(end 162.361372 -218.9861)
		(width 0.14478)
		(layer "In13.Cu")
		(net "M_H_CPU1_SA_DQ<19>")
	)
	(segment
		(start 165.579044 -218.744546)
		(end 165.317932 -219.005658)
		(width 0.14478)
		(layer "In13.Cu")
		(net "M_H_CPU1_SA_DQ<19>")
	)
	(segment
		(start 169.61866 -218.455494)
		(end 169.47388 -218.310714)
		(width 0.14478)
		(layer "In13.Cu")
		(net "M_H_CPU1_SA_DQ<19>")
	)
	(segment
		(start 169.06748 -218.160346)
		(end 168.9227 -218.305126)
		(width 0.14478)
		(layer "In13.Cu")
		(net "M_H_CPU1_SA_DQ<19>")
	)
	(segment
		(start 161.921952 -219.90304)
		(end 161.777172 -219.75826)
		(width 0.14478)
		(layer "In13.Cu")
		(net "M_H_CPU1_SA_DQ<19>")
	)
	(segment
		(start 163.473384 -218.744546)
		(end 163.186872 -219.031058)
		(width 0.14478)
		(layer "In13.Cu")
		(net "M_H_CPU1_SA_DQ<19>")
	)
	(segment
		(start 141.101826 -236.061758)
		(end 141.093444 -236.056932)
		(width 0.0889)
		(layer "In13.Cu")
		(net "M_H_CPU1_SA_DQ<19>")
	)
	(segment
		(start 168.22674 -218.160346)
		(end 166.915846 -218.160346)
		(width 0.14478)
		(layer "In13.Cu")
		(net "M_H_CPU1_SA_DQ<19>")
	)
	(segment
		(start 162.361626 -219.190316)
		(end 162.592258 -219.420948)
		(width 0.14478)
		(layer "In13.Cu")
		(net "M_H_CPU1_SA_DQ<19>")
	)
	(segment
		(start 169.47388 -218.305126)
		(end 169.3291 -218.160346)
		(width 0.14478)
		(layer "In13.Cu")
		(net "M_H_CPU1_SA_DQ<19>")
	)
	(segment
		(start 169.47388 -218.310714)
		(end 169.47388 -218.305126)
		(width 0.14478)
		(layer "In13.Cu")
		(net "M_H_CPU1_SA_DQ<19>")
	)
	(segment
		(start 171.233084 -219.000578)
		(end 170.392852 -218.160346)
		(width 0.14478)
		(layer "In13.Cu")
		(net "M_H_CPU1_SA_DQ<19>")
	)
	(segment
		(start 169.3291 -218.160346)
		(end 169.06748 -218.160346)
		(width 0.14478)
		(layer "In13.Cu")
		(net "M_H_CPU1_SA_DQ<19>")
	)
	(segment
		(start 161.777172 -219.75826)
		(end 161.777172 -219.495878)
		(width 0.14478)
		(layer "In13.Cu")
		(net "M_H_CPU1_SA_DQ<19>")
	)
	(segment
		(start 134.584694 -236.093508)
		(end 134.488682 -236.118908)
		(width 0.0889)
		(layer "In13.Cu")
		(net "M_H_CPU1_SA_DQ<19>")
	)
	(segment
		(start 168.77792 -218.455494)
		(end 168.5163 -218.455494)
		(width 0.14478)
		(layer "In13.Cu")
		(net "M_H_CPU1_SA_DQ<19>")
	)
	(segment
		(start 168.5163 -218.455494)
		(end 168.37152 -218.310714)
		(width 0.14478)
		(layer "In13.Cu")
		(net "M_H_CPU1_SA_DQ<19>")
	)
	(segment
		(start 143.555974 -236.056932)
		(end 143.547592 -236.061758)
		(width 0.0889)
		(layer "In13.Cu")
		(net "M_H_CPU1_SA_DQ<19>")
	)
	(segment
		(start 146.357848 -235.211112)
		(end 145.430748 -236.138212)
		(width 0.0889)
		(layer "In13.Cu")
		(net "M_H_CPU1_SA_DQ<19>")
	)
	(segment
		(start 170.16984 -218.160346)
		(end 170.02506 -218.305126)
		(width 0.14478)
		(layer "In13.Cu")
		(net "M_H_CPU1_SA_DQ<19>")
	)
	(segment
		(start 162.751516 -218.80068)
		(end 162.546792 -218.80068)
		(width 0.14478)
		(layer "In13.Cu")
		(net "M_H_CPU1_SA_DQ<19>")
	)
	(segment
		(start 164.476684 -218.744546)
		(end 164.215572 -219.005658)
		(width 0.14478)
		(layer "In13.Cu")
		(net "M_H_CPU1_SA_DQ<19>")
	)
	(segment
		(start 162.31489 -219.90304)
		(end 161.921952 -219.90304)
		(width 0.14478)
		(layer "In13.Cu")
		(net "M_H_CPU1_SA_DQ<19>")
	)
	(segment
		(start 135.461756 -236.061758)
		(end 135.453374 -236.056932)
		(width 0.0889)
		(layer "In13.Cu")
		(net "M_H_CPU1_SA_DQ<19>")
	)
	(segment
		(start 146.357848 -234.865672)
		(end 146.357848 -235.211112)
		(width 0.0889)
		(layer "In13.Cu")
		(net "M_H_CPU1_SA_DQ<19>")
	)
	(segment
		(start 146.645376 -234.578144)
		(end 146.357848 -234.865672)
		(width 0.0889)
		(layer "In13.Cu")
		(net "M_H_CPU1_SA_DQ<19>")
	)
	(segment
		(start 164.215572 -219.005658)
		(end 163.925504 -219.005658)
		(width 0.14478)
		(layer "In13.Cu")
		(net "M_H_CPU1_SA_DQ<19>")
	)
	(segment
		(start 163.925504 -219.005658)
		(end 163.664392 -218.744546)
		(width 0.14478)
		(layer "In13.Cu")
		(net "M_H_CPU1_SA_DQ<19>")
	)
	(segment
		(start 166.915846 -218.160346)
		(end 166.331646 -218.744546)
		(width 0.14478)
		(layer "In13.Cu")
		(net "M_H_CPU1_SA_DQ<19>")
	)
	(segment
		(start 162.592258 -219.420948)
		(end 162.592258 -219.625672)
		(width 0.14478)
		(layer "In13.Cu")
		(net "M_H_CPU1_SA_DQ<19>")
	)
	(segment
		(start 171.97197 -218.585288)
		(end 171.55668 -219.000578)
		(width 0.14478)
		(layer "In13.Cu")
		(net "M_H_CPU1_SA_DQ<19>")
	)
	(segment
		(start 161.632392 -219.351098)
		(end 161.370772 -219.351098)
		(width 0.14478)
		(layer "In13.Cu")
		(net "M_H_CPU1_SA_DQ<19>")
	)
	(segment
		(start 147.51685 -233.962194)
		(end 146.9009 -234.578144)
		(width 0.0889)
		(layer "In13.Cu")
		(net "M_H_CPU1_SA_DQ<19>")
	)
	(segment
		(start 136.976104 -236.056932)
		(end 136.967722 -236.061758)
		(width 0.0889)
		(layer "In13.Cu")
		(net "M_H_CPU1_SA_DQ<19>")
	)
	(arc
		(start 141.667738 -236.061758)
		(mid 141.384782 -236.137935)
		(end 141.101826 -236.061758)
		(width 0.0889)
		(layer "In13.Cu")
		(net "M_H_CPU1_SA_DQ<19>")
	)
	(arc
		(start 140.727684 -236.061758)
		(mid 140.444728 -236.137935)
		(end 140.161772 -236.061758)
		(width 0.0889)
		(layer "In13.Cu")
		(net "M_H_CPU1_SA_DQ<19>")
	)
	(arc
		(start 142.04188 -236.061758)
		(mid 141.859629 -236.011408)
		(end 141.67612 -236.056932)
		(width 0.0889)
		(layer "In13.Cu")
		(net "M_H_CPU1_SA_DQ<19>")
	)
	(arc
		(start 143.547592 -236.061758)
		(mid 143.264636 -236.137935)
		(end 142.98168 -236.061758)
		(width 0.0889)
		(layer "In13.Cu")
		(net "M_H_CPU1_SA_DQ<19>")
	)
	(arc
		(start 144.20596 -236.138212)
		(mid 144.059029 -236.118801)
		(end 143.922242 -236.061758)
		(width 0.0889)
		(layer "In13.Cu")
		(net "M_H_CPU1_SA_DQ<19>")
	)
	(arc
		(start 139.78763 -236.061758)
		(mid 139.504674 -236.137935)
		(end 139.221718 -236.061758)
		(width 0.0889)
		(layer "In13.Cu")
		(net "M_H_CPU1_SA_DQ<19>")
	)
	(arc
		(start 140.15339 -236.056932)
		(mid 139.969882 -236.011438)
		(end 139.78763 -236.061758)
		(width 0.0889)
		(layer "In13.Cu")
		(net "M_H_CPU1_SA_DQ<19>")
	)
	(arc
		(start 135.453374 -236.056932)
		(mid 135.269866 -236.011438)
		(end 135.087614 -236.061758)
		(width 0.0889)
		(layer "In13.Cu")
		(net "M_H_CPU1_SA_DQ<19>")
	)
	(arc
		(start 138.281918 -236.061758)
		(mid 138.099667 -236.011408)
		(end 137.916158 -236.056932)
		(width 0.0889)
		(layer "In13.Cu")
		(net "M_H_CPU1_SA_DQ<19>")
	)
	(arc
		(start 136.393428 -236.056932)
		(mid 136.20992 -236.011438)
		(end 136.027668 -236.061758)
		(width 0.0889)
		(layer "In13.Cu")
		(net "M_H_CPU1_SA_DQ<19>")
	)
	(arc
		(start 142.607792 -236.061758)
		(mid 142.324836 -236.137935)
		(end 142.04188 -236.061758)
		(width 0.0889)
		(layer "In13.Cu")
		(net "M_H_CPU1_SA_DQ<19>")
	)
	(arc
		(start 135.087614 -236.061758)
		(mid 134.839901 -236.136978)
		(end 134.584694 -236.093508)
		(width 0.0889)
		(layer "In13.Cu")
		(net "M_H_CPU1_SA_DQ<19>")
	)
	(arc
		(start 136.967722 -236.061758)
		(mid 136.684766 -236.137935)
		(end 136.40181 -236.061758)
		(width 0.0889)
		(layer "In13.Cu")
		(net "M_H_CPU1_SA_DQ<19>")
	)
	(arc
		(start 136.027668 -236.061758)
		(mid 135.744712 -236.137935)
		(end 135.461756 -236.061758)
		(width 0.0889)
		(layer "In13.Cu")
		(net "M_H_CPU1_SA_DQ<19>")
	)
	(arc
		(start 143.922242 -236.061758)
		(mid 143.739737 -236.011281)
		(end 143.555974 -236.056932)
		(width 0.0889)
		(layer "In13.Cu")
		(net "M_H_CPU1_SA_DQ<19>")
	)
	(arc
		(start 137.341864 -236.061758)
		(mid 137.159613 -236.011408)
		(end 136.976104 -236.056932)
		(width 0.0889)
		(layer "In13.Cu")
		(net "M_H_CPU1_SA_DQ<19>")
	)
	(arc
		(start 137.907776 -236.061758)
		(mid 137.62482 -236.137935)
		(end 137.341864 -236.061758)
		(width 0.0889)
		(layer "In13.Cu")
		(net "M_H_CPU1_SA_DQ<19>")
	)
	(arc
		(start 142.98168 -236.061758)
		(mid 142.794736 -236.011503)
		(end 142.607792 -236.061758)
		(width 0.0889)
		(layer "In13.Cu")
		(net "M_H_CPU1_SA_DQ<19>")
	)
	(arc
		(start 139.221718 -236.061758)
		(mid 139.034774 -236.011503)
		(end 138.84783 -236.061758)
		(width 0.0889)
		(layer "In13.Cu")
		(net "M_H_CPU1_SA_DQ<19>")
	)
	(arc
		(start 138.84783 -236.061758)
		(mid 138.564874 -236.137935)
		(end 138.281918 -236.061758)
		(width 0.0889)
		(layer "In13.Cu")
		(net "M_H_CPU1_SA_DQ<19>")
	)
	(arc
		(start 141.093444 -236.056932)
		(mid 140.909936 -236.011438)
		(end 140.727684 -236.061758)
		(width 0.0889)
		(layer "In13.Cu")
		(net "M_H_CPU1_SA_DQ<19>")
	)
	(segment
		(start 135.27786 -235.84027)
		(end 135.744712 -235.574332)
		(width 0.10668)
		(layer "F.Cu")
		(net "M_H_CPU1_SA_DQ<18>")
	)
	(segment
		(start 143.955262 -235.28782)
		(end 144.942814 -234.890564)
		(width 0.0889)
		(layer "In13.Cu")
		(net "M_H_CPU1_SA_DQ<18>")
	)
	(segment
		(start 137.803382 -235.246926)
		(end 137.811764 -235.251752)
		(width 0.0889)
		(layer "In13.Cu")
		(net "M_H_CPU1_SA_DQ<18>")
	)
	(segment
		(start 159.263334 -219.536518)
		(end 159.468058 -219.536518)
		(width 0.14478)
		(layer "In13.Cu")
		(net "M_H_CPU1_SA_DQ<18>")
	)
	(segment
		(start 135.89889 -235.308902)
		(end 135.995156 -235.283502)
		(width 0.0889)
		(layer "In13.Cu")
		(net "M_H_CPU1_SA_DQ<18>")
	)
	(segment
		(start 166.995094 -216.460324)
		(end 169.942256 -216.460324)
		(width 0.14478)
		(layer "In13.Cu")
		(net "M_H_CPU1_SA_DQ<18>")
	)
	(segment
		(start 166.144956 -217.310462)
		(end 166.995094 -216.460324)
		(width 0.14478)
		(layer "In13.Cu")
		(net "M_H_CPU1_SA_DQ<18>")
	)
	(segment
		(start 158.789116 -219.637356)
		(end 158.974282 -219.45219)
		(width 0.14478)
		(layer "In13.Cu")
		(net "M_H_CPU1_SA_DQ<18>")
	)
	(segment
		(start 154.194764 -224.809812)
		(end 154.194764 -224.605088)
		(width 0.14478)
		(layer "In13.Cu")
		(net "M_H_CPU1_SA_DQ<18>")
	)
	(segment
		(start 158.789116 -219.84208)
		(end 158.789116 -219.637356)
		(width 0.14478)
		(layer "In13.Cu")
		(net "M_H_CPU1_SA_DQ<18>")
	)
	(segment
		(start 154.789378 -224.215198)
		(end 154.974544 -224.030032)
		(width 0.14478)
		(layer "In13.Cu")
		(net "M_H_CPU1_SA_DQ<18>")
	)
	(segment
		(start 154.974544 -223.825308)
		(end 154.890216 -223.74098)
		(width 0.14478)
		(layer "In13.Cu")
		(net "M_H_CPU1_SA_DQ<18>")
	)
	(segment
		(start 160.247838 -218.756738)
		(end 160.433004 -218.571572)
		(width 0.14478)
		(layer "In13.Cu")
		(net "M_H_CPU1_SA_DQ<18>")
	)
	(segment
		(start 157.313884 -221.690692)
		(end 157.313884 -221.485968)
		(width 0.14478)
		(layer "In13.Cu")
		(net "M_H_CPU1_SA_DQ<18>")
	)
	(segment
		(start 160.043114 -218.756738)
		(end 160.247838 -218.756738)
		(width 0.14478)
		(layer "In13.Cu")
		(net "M_H_CPU1_SA_DQ<18>")
	)
	(segment
		(start 160.433004 -218.366848)
		(end 160.348676 -218.28252)
		(width 0.14478)
		(layer "In13.Cu")
		(net "M_H_CPU1_SA_DQ<18>")
	)
	(segment
		(start 160.348676 -218.28252)
		(end 160.348676 -218.077796)
		(width 0.14478)
		(layer "In13.Cu")
		(net "M_H_CPU1_SA_DQ<18>")
	)
	(segment
		(start 159.568896 -219.0623)
		(end 159.568896 -218.857576)
		(width 0.14478)
		(layer "In13.Cu")
		(net "M_H_CPU1_SA_DQ<18>")
	)
	(segment
		(start 158.873444 -220.131132)
		(end 158.873444 -219.926408)
		(width 0.14478)
		(layer "In13.Cu")
		(net "M_H_CPU1_SA_DQ<18>")
	)
	(segment
		(start 157.229556 -221.40164)
		(end 157.229556 -221.196916)
		(width 0.14478)
		(layer "In13.Cu")
		(net "M_H_CPU1_SA_DQ<18>")
	)
	(segment
		(start 159.568896 -218.857576)
		(end 159.754062 -218.67241)
		(width 0.14478)
		(layer "In13.Cu")
		(net "M_H_CPU1_SA_DQ<18>")
	)
	(segment
		(start 158.688278 -220.316298)
		(end 158.873444 -220.131132)
		(width 0.14478)
		(layer "In13.Cu")
		(net "M_H_CPU1_SA_DQ<18>")
	)
	(segment
		(start 157.128718 -221.875858)
		(end 157.313884 -221.690692)
		(width 0.14478)
		(layer "In13.Cu")
		(net "M_H_CPU1_SA_DQ<18>")
	)
	(segment
		(start 155.754324 -223.045528)
		(end 155.669996 -222.9612)
		(width 0.14478)
		(layer "In13.Cu")
		(net "M_H_CPU1_SA_DQ<18>")
	)
	(segment
		(start 155.569158 -223.435418)
		(end 155.754324 -223.250252)
		(width 0.14478)
		(layer "In13.Cu")
		(net "M_H_CPU1_SA_DQ<18>")
	)
	(segment
		(start 140.257784 -235.251752)
		(end 140.266166 -235.246926)
		(width 0.0889)
		(layer "In13.Cu")
		(net "M_H_CPU1_SA_DQ<18>")
	)
	(segment
		(start 171.546774 -217.310462)
		(end 171.97197 -216.885266)
		(width 0.14478)
		(layer "In13.Cu")
		(net "M_H_CPU1_SA_DQ<18>")
	)
	(segment
		(start 157.414722 -221.01175)
		(end 157.619446 -221.01175)
		(width 0.14478)
		(layer "In13.Cu")
		(net "M_H_CPU1_SA_DQ<18>")
	)
	(segment
		(start 147.842224 -233.050334)
		(end 148.33473 -233.050334)
		(width 0.14478)
		(layer "In13.Cu")
		(net "M_H_CPU1_SA_DQ<18>")
	)
	(segment
		(start 157.703774 -221.096078)
		(end 157.908498 -221.096078)
		(width 0.14478)
		(layer "In13.Cu")
		(net "M_H_CPU1_SA_DQ<18>")
	)
	(segment
		(start 147.61083 -233.050334)
		(end 147.842224 -233.050334)
		(width 0.0889)
		(layer "In13.Cu")
		(net "M_H_CPU1_SA_DQ<18>")
	)
	(segment
		(start 153.726134 -227.65893)
		(end 153.726134 -225.278442)
		(width 0.14478)
		(layer "In13.Cu")
		(net "M_H_CPU1_SA_DQ<18>")
	)
	(segment
		(start 153.726134 -225.278442)
		(end 154.194764 -224.809812)
		(width 0.14478)
		(layer "In13.Cu")
		(net "M_H_CPU1_SA_DQ<18>")
	)
	(segment
		(start 158.194502 -220.23197)
		(end 158.399226 -220.23197)
		(width 0.14478)
		(layer "In13.Cu")
		(net "M_H_CPU1_SA_DQ<18>")
	)
	(segment
		(start 157.619446 -221.01175)
		(end 157.703774 -221.096078)
		(width 0.14478)
		(layer "In13.Cu")
		(net "M_H_CPU1_SA_DQ<18>")
	)
	(segment
		(start 155.280106 -223.35109)
		(end 155.364434 -223.435418)
		(width 0.14478)
		(layer "In13.Cu")
		(net "M_H_CPU1_SA_DQ<18>")
	)
	(segment
		(start 160.533842 -217.89263)
		(end 160.738566 -217.89263)
		(width 0.14478)
		(layer "In13.Cu")
		(net "M_H_CPU1_SA_DQ<18>")
	)
	(segment
		(start 160.348676 -218.077796)
		(end 160.533842 -217.89263)
		(width 0.14478)
		(layer "In13.Cu")
		(net "M_H_CPU1_SA_DQ<18>")
	)
	(segment
		(start 142.503398 -235.246926)
		(end 142.51178 -235.251752)
		(width 0.0889)
		(layer "In13.Cu")
		(net "M_H_CPU1_SA_DQ<18>")
	)
	(segment
		(start 154.890216 -223.74098)
		(end 154.890216 -223.536256)
		(width 0.14478)
		(layer "In13.Cu")
		(net "M_H_CPU1_SA_DQ<18>")
	)
	(segment
		(start 154.295602 -224.13087)
		(end 154.500326 -224.13087)
		(width 0.14478)
		(layer "In13.Cu")
		(net "M_H_CPU1_SA_DQ<18>")
	)
	(segment
		(start 155.669996 -222.9612)
		(end 155.669996 -222.756476)
		(width 0.14478)
		(layer "In13.Cu")
		(net "M_H_CPU1_SA_DQ<18>")
	)
	(segment
		(start 159.653224 -219.351352)
		(end 159.653224 -219.146628)
		(width 0.14478)
		(layer "In13.Cu")
		(net "M_H_CPU1_SA_DQ<18>")
	)
	(segment
		(start 160.433004 -218.571572)
		(end 160.433004 -218.366848)
		(width 0.14478)
		(layer "In13.Cu")
		(net "M_H_CPU1_SA_DQ<18>")
	)
	(segment
		(start 159.468058 -219.536518)
		(end 159.653224 -219.351352)
		(width 0.14478)
		(layer "In13.Cu")
		(net "M_H_CPU1_SA_DQ<18>")
	)
	(segment
		(start 157.908498 -221.096078)
		(end 158.093664 -220.910912)
		(width 0.14478)
		(layer "In13.Cu")
		(net "M_H_CPU1_SA_DQ<18>")
	)
	(segment
		(start 159.653224 -219.146628)
		(end 159.568896 -219.0623)
		(width 0.14478)
		(layer "In13.Cu")
		(net "M_H_CPU1_SA_DQ<18>")
	)
	(segment
		(start 155.669996 -222.756476)
		(end 155.855162 -222.57131)
		(width 0.14478)
		(layer "In13.Cu")
		(net "M_H_CPU1_SA_DQ<18>")
	)
	(segment
		(start 158.093664 -220.706188)
		(end 158.009336 -220.62186)
		(width 0.14478)
		(layer "In13.Cu")
		(net "M_H_CPU1_SA_DQ<18>")
	)
	(segment
		(start 154.194764 -224.605088)
		(end 154.110436 -224.52076)
		(width 0.14478)
		(layer "In13.Cu")
		(net "M_H_CPU1_SA_DQ<18>")
	)
	(segment
		(start 143.451834 -235.251752)
		(end 143.462248 -235.257848)
		(width 0.0889)
		(layer "In13.Cu")
		(net "M_H_CPU1_SA_DQ<18>")
	)
	(segment
		(start 154.110436 -224.316036)
		(end 154.295602 -224.13087)
		(width 0.14478)
		(layer "In13.Cu")
		(net "M_H_CPU1_SA_DQ<18>")
	)
	(segment
		(start 155.364434 -223.435418)
		(end 155.569158 -223.435418)
		(width 0.14478)
		(layer "In13.Cu")
		(net "M_H_CPU1_SA_DQ<18>")
	)
	(segment
		(start 170.792394 -217.310462)
		(end 171.546774 -217.310462)
		(width 0.14478)
		(layer "In13.Cu")
		(net "M_H_CPU1_SA_DQ<18>")
	)
	(segment
		(start 156.923994 -221.875858)
		(end 157.128718 -221.875858)
		(width 0.14478)
		(layer "In13.Cu")
		(net "M_H_CPU1_SA_DQ<18>")
	)
	(segment
		(start 143.077692 -235.251752)
		(end 143.086074 -235.246926)
		(width 0.0889)
		(layer "In13.Cu")
		(net "M_H_CPU1_SA_DQ<18>")
	)
	(segment
		(start 138.743436 -235.246926)
		(end 138.751818 -235.251752)
		(width 0.0889)
		(layer "In13.Cu")
		(net "M_H_CPU1_SA_DQ<18>")
	)
	(segment
		(start 156.348938 -222.655638)
		(end 156.534104 -222.470472)
		(width 0.14478)
		(layer "In13.Cu")
		(net "M_H_CPU1_SA_DQ<18>")
	)
	(segment
		(start 161.027618 -217.976958)
		(end 161.694114 -217.310462)
		(width 0.14478)
		(layer "In13.Cu")
		(net "M_H_CPU1_SA_DQ<18>")
	)
	(segment
		(start 158.009336 -220.417136)
		(end 158.194502 -220.23197)
		(width 0.14478)
		(layer "In13.Cu")
		(net "M_H_CPU1_SA_DQ<18>")
	)
	(segment
		(start 154.110436 -224.52076)
		(end 154.110436 -224.316036)
		(width 0.14478)
		(layer "In13.Cu")
		(net "M_H_CPU1_SA_DQ<18>")
	)
	(segment
		(start 156.839666 -221.79153)
		(end 156.923994 -221.875858)
		(width 0.14478)
		(layer "In13.Cu")
		(net "M_H_CPU1_SA_DQ<18>")
	)
	(segment
		(start 158.399226 -220.23197)
		(end 158.483554 -220.316298)
		(width 0.14478)
		(layer "In13.Cu")
		(net "M_H_CPU1_SA_DQ<18>")
	)
	(segment
		(start 158.483554 -220.316298)
		(end 158.688278 -220.316298)
		(width 0.14478)
		(layer "In13.Cu")
		(net "M_H_CPU1_SA_DQ<18>")
	)
	(segment
		(start 146.60372 -234.057444)
		(end 147.61083 -233.050334)
		(width 0.0889)
		(layer "In13.Cu")
		(net "M_H_CPU1_SA_DQ<18>")
	)
	(segment
		(start 135.744712 -235.574332)
		(end 135.89889 -235.308902)
		(width 0.0889)
		(layer "In13.Cu")
		(net "M_H_CPU1_SA_DQ<18>")
	)
	(segment
		(start 158.009336 -220.62186)
		(end 158.009336 -220.417136)
		(width 0.14478)
		(layer "In13.Cu")
		(net "M_H_CPU1_SA_DQ<18>")
	)
	(segment
		(start 158.093664 -220.910912)
		(end 158.093664 -220.706188)
		(width 0.14478)
		(layer "In13.Cu")
		(net "M_H_CPU1_SA_DQ<18>")
	)
	(segment
		(start 161.694114 -217.310462)
		(end 166.144956 -217.310462)
		(width 0.14478)
		(layer "In13.Cu")
		(net "M_H_CPU1_SA_DQ<18>")
	)
	(segment
		(start 157.229556 -221.196916)
		(end 157.414722 -221.01175)
		(width 0.14478)
		(layer "In13.Cu")
		(net "M_H_CPU1_SA_DQ<18>")
	)
	(segment
		(start 156.449776 -222.18142)
		(end 156.449776 -221.976696)
		(width 0.14478)
		(layer "In13.Cu")
		(net "M_H_CPU1_SA_DQ<18>")
	)
	(segment
		(start 158.974282 -219.45219)
		(end 159.179006 -219.45219)
		(width 0.14478)
		(layer "In13.Cu")
		(net "M_H_CPU1_SA_DQ<18>")
	)
	(segment
		(start 156.059886 -222.57131)
		(end 156.144214 -222.655638)
		(width 0.14478)
		(layer "In13.Cu")
		(net "M_H_CPU1_SA_DQ<18>")
	)
	(segment
		(start 154.584654 -224.215198)
		(end 154.789378 -224.215198)
		(width 0.14478)
		(layer "In13.Cu")
		(net "M_H_CPU1_SA_DQ<18>")
	)
	(segment
		(start 158.873444 -219.926408)
		(end 158.789116 -219.84208)
		(width 0.14478)
		(layer "In13.Cu")
		(net "M_H_CPU1_SA_DQ<18>")
	)
	(segment
		(start 159.754062 -218.67241)
		(end 159.958786 -218.67241)
		(width 0.14478)
		(layer "In13.Cu")
		(net "M_H_CPU1_SA_DQ<18>")
	)
	(segment
		(start 156.144214 -222.655638)
		(end 156.348938 -222.655638)
		(width 0.14478)
		(layer "In13.Cu")
		(net "M_H_CPU1_SA_DQ<18>")
	)
	(segment
		(start 139.31773 -235.251752)
		(end 139.326112 -235.246926)
		(width 0.0889)
		(layer "In13.Cu")
		(net "M_H_CPU1_SA_DQ<18>")
	)
	(segment
		(start 155.754324 -223.250252)
		(end 155.754324 -223.045528)
		(width 0.14478)
		(layer "In13.Cu")
		(net "M_H_CPU1_SA_DQ<18>")
	)
	(segment
		(start 160.738566 -217.89263)
		(end 160.822894 -217.976958)
		(width 0.14478)
		(layer "In13.Cu")
		(net "M_H_CPU1_SA_DQ<18>")
	)
	(segment
		(start 157.313884 -221.485968)
		(end 157.229556 -221.40164)
		(width 0.14478)
		(layer "In13.Cu")
		(net "M_H_CPU1_SA_DQ<18>")
	)
	(segment
		(start 155.075382 -223.35109)
		(end 155.280106 -223.35109)
		(width 0.14478)
		(layer "In13.Cu")
		(net "M_H_CPU1_SA_DQ<18>")
	)
	(segment
		(start 148.33473 -233.050334)
		(end 153.726134 -227.65893)
		(width 0.14478)
		(layer "In13.Cu")
		(net "M_H_CPU1_SA_DQ<18>")
	)
	(segment
		(start 156.449776 -221.976696)
		(end 156.634942 -221.79153)
		(width 0.14478)
		(layer "In13.Cu")
		(net "M_H_CPU1_SA_DQ<18>")
	)
	(segment
		(start 159.958786 -218.67241)
		(end 160.043114 -218.756738)
		(width 0.14478)
		(layer "In13.Cu")
		(net "M_H_CPU1_SA_DQ<18>")
	)
	(segment
		(start 156.534104 -222.470472)
		(end 156.534104 -222.265748)
		(width 0.14478)
		(layer "In13.Cu")
		(net "M_H_CPU1_SA_DQ<18>")
	)
	(segment
		(start 145.326608 -234.890564)
		(end 146.159728 -234.057444)
		(width 0.0889)
		(layer "In13.Cu")
		(net "M_H_CPU1_SA_DQ<18>")
	)
	(segment
		(start 144.942814 -234.890564)
		(end 145.326608 -234.890564)
		(width 0.0889)
		(layer "In13.Cu")
		(net "M_H_CPU1_SA_DQ<18>")
	)
	(segment
		(start 146.159728 -234.057444)
		(end 146.60372 -234.057444)
		(width 0.0889)
		(layer "In13.Cu")
		(net "M_H_CPU1_SA_DQ<18>")
	)
	(segment
		(start 156.534104 -222.265748)
		(end 156.449776 -222.18142)
		(width 0.14478)
		(layer "In13.Cu")
		(net "M_H_CPU1_SA_DQ<18>")
	)
	(segment
		(start 154.890216 -223.536256)
		(end 155.075382 -223.35109)
		(width 0.14478)
		(layer "In13.Cu")
		(net "M_H_CPU1_SA_DQ<18>")
	)
	(segment
		(start 156.634942 -221.79153)
		(end 156.839666 -221.79153)
		(width 0.14478)
		(layer "In13.Cu")
		(net "M_H_CPU1_SA_DQ<18>")
	)
	(segment
		(start 159.179006 -219.45219)
		(end 159.263334 -219.536518)
		(width 0.14478)
		(layer "In13.Cu")
		(net "M_H_CPU1_SA_DQ<18>")
	)
	(segment
		(start 169.942256 -216.460324)
		(end 170.792394 -217.310462)
		(width 0.14478)
		(layer "In13.Cu")
		(net "M_H_CPU1_SA_DQ<18>")
	)
	(segment
		(start 155.855162 -222.57131)
		(end 156.059886 -222.57131)
		(width 0.14478)
		(layer "In13.Cu")
		(net "M_H_CPU1_SA_DQ<18>")
	)
	(segment
		(start 154.500326 -224.13087)
		(end 154.584654 -224.215198)
		(width 0.14478)
		(layer "In13.Cu")
		(net "M_H_CPU1_SA_DQ<18>")
	)
	(segment
		(start 160.822894 -217.976958)
		(end 161.027618 -217.976958)
		(width 0.14478)
		(layer "In13.Cu")
		(net "M_H_CPU1_SA_DQ<18>")
	)
	(segment
		(start 154.974544 -224.030032)
		(end 154.974544 -223.825308)
		(width 0.14478)
		(layer "In13.Cu")
		(net "M_H_CPU1_SA_DQ<18>")
	)
	(arc
		(start 139.326112 -235.246926)
		(mid 139.50962 -235.201432)
		(end 139.691872 -235.251752)
		(width 0.0889)
		(layer "In13.Cu")
		(net "M_H_CPU1_SA_DQ<18>")
	)
	(arc
		(start 138.751818 -235.251752)
		(mid 139.034774 -235.327929)
		(end 139.31773 -235.251752)
		(width 0.0889)
		(layer "In13.Cu")
		(net "M_H_CPU1_SA_DQ<18>")
	)
	(arc
		(start 140.631926 -235.251752)
		(mid 140.914882 -235.327929)
		(end 141.197838 -235.251752)
		(width 0.0889)
		(layer "In13.Cu")
		(net "M_H_CPU1_SA_DQ<18>")
	)
	(arc
		(start 139.691872 -235.251752)
		(mid 139.974828 -235.327929)
		(end 140.257784 -235.251752)
		(width 0.0889)
		(layer "In13.Cu")
		(net "M_H_CPU1_SA_DQ<18>")
	)
	(arc
		(start 143.462248 -235.257848)
		(mid 143.705381 -235.328472)
		(end 143.955262 -235.28782)
		(width 0.0889)
		(layer "In13.Cu")
		(net "M_H_CPU1_SA_DQ<18>")
	)
	(arc
		(start 142.137638 -235.251752)
		(mid 142.319889 -235.201402)
		(end 142.503398 -235.246926)
		(width 0.0889)
		(layer "In13.Cu")
		(net "M_H_CPU1_SA_DQ<18>")
	)
	(arc
		(start 137.811764 -235.251752)
		(mid 138.09472 -235.327929)
		(end 138.377676 -235.251752)
		(width 0.0889)
		(layer "In13.Cu")
		(net "M_H_CPU1_SA_DQ<18>")
	)
	(arc
		(start 140.266166 -235.246926)
		(mid 140.449674 -235.201432)
		(end 140.631926 -235.251752)
		(width 0.0889)
		(layer "In13.Cu")
		(net "M_H_CPU1_SA_DQ<18>")
	)
	(arc
		(start 141.571726 -235.251752)
		(mid 141.854682 -235.327929)
		(end 142.137638 -235.251752)
		(width 0.0889)
		(layer "In13.Cu")
		(net "M_H_CPU1_SA_DQ<18>")
	)
	(arc
		(start 135.995156 -235.283502)
		(mid 136.250221 -235.326853)
		(end 136.497822 -235.251752)
		(width 0.0889)
		(layer "In13.Cu")
		(net "M_H_CPU1_SA_DQ<18>")
	)
	(arc
		(start 137.437622 -235.251752)
		(mid 137.619873 -235.201402)
		(end 137.803382 -235.246926)
		(width 0.0889)
		(layer "In13.Cu")
		(net "M_H_CPU1_SA_DQ<18>")
	)
	(arc
		(start 142.51178 -235.251752)
		(mid 142.794736 -235.327929)
		(end 143.077692 -235.251752)
		(width 0.0889)
		(layer "In13.Cu")
		(net "M_H_CPU1_SA_DQ<18>")
	)
	(arc
		(start 136.87171 -235.251752)
		(mid 137.154666 -235.327929)
		(end 137.437622 -235.251752)
		(width 0.0889)
		(layer "In13.Cu")
		(net "M_H_CPU1_SA_DQ<18>")
	)
	(arc
		(start 143.086074 -235.246926)
		(mid 143.269582 -235.201432)
		(end 143.451834 -235.251752)
		(width 0.0889)
		(layer "In13.Cu")
		(net "M_H_CPU1_SA_DQ<18>")
	)
	(arc
		(start 141.197838 -235.251752)
		(mid 141.384782 -235.201497)
		(end 141.571726 -235.251752)
		(width 0.0889)
		(layer "In13.Cu")
		(net "M_H_CPU1_SA_DQ<18>")
	)
	(arc
		(start 138.377676 -235.251752)
		(mid 138.559927 -235.201402)
		(end 138.743436 -235.246926)
		(width 0.0889)
		(layer "In13.Cu")
		(net "M_H_CPU1_SA_DQ<18>")
	)
	(arc
		(start 136.497822 -235.251752)
		(mid 136.684766 -235.201497)
		(end 136.87171 -235.251752)
		(width 0.0889)
		(layer "In13.Cu")
		(net "M_H_CPU1_SA_DQ<18>")
	)
	(segment
		(start 134.337806 -235.84027)
		(end 134.804658 -235.574332)
		(width 0.10668)
		(layer "F.Cu")
		(net "M_H_CPU1_SA_DQ<17>")
	)
	(segment
		(start 146.454368 -234.341924)
		(end 146.699732 -234.341924)
		(width 0.0889)
		(layer "In13.Cu")
		(net "M_H_CPU1_SA_DQ<17>")
	)
	(segment
		(start 134.650734 -235.839762)
		(end 134.673086 -235.923074)
		(width 0.0889)
		(layer "In13.Cu")
		(net "M_H_CPU1_SA_DQ<17>")
	)
	(segment
		(start 147.842224 -233.504994)
		(end 148.523198 -233.504994)
		(width 0.14478)
		(layer "In13.Cu")
		(net "M_H_CPU1_SA_DQ<17>")
	)
	(segment
		(start 173.935644 -218.160346)
		(end 176.072038 -217.735404)
		(width 0.14478)
		(layer "In13.Cu")
		(net "M_H_CPU1_SA_DQ<17>")
	)
	(segment
		(start 161.345626 -218.294966)
		(end 165.189916 -218.294966)
		(width 0.14478)
		(layer "In13.Cu")
		(net "M_H_CPU1_SA_DQ<17>")
	)
	(segment
		(start 139.31773 -235.896912)
		(end 139.326112 -235.901738)
		(width 0.0889)
		(layer "In13.Cu")
		(net "M_H_CPU1_SA_DQ<17>")
	)
	(segment
		(start 144.205706 -235.947712)
		(end 145.33372 -235.947712)
		(width 0.0889)
		(layer "In13.Cu")
		(net "M_H_CPU1_SA_DQ<17>")
	)
	(segment
		(start 146.154648 -235.126784)
		(end 146.154648 -234.641644)
		(width 0.0889)
		(layer "In13.Cu")
		(net "M_H_CPU1_SA_DQ<17>")
	)
	(segment
		(start 143.451834 -235.896912)
		(end 143.466566 -235.888276)
		(width 0.0889)
		(layer "In13.Cu")
		(net "M_H_CPU1_SA_DQ<17>")
	)
	(segment
		(start 142.503398 -235.901738)
		(end 142.51178 -235.896912)
		(width 0.0889)
		(layer "In13.Cu")
		(net "M_H_CPU1_SA_DQ<17>")
	)
	(segment
		(start 134.804658 -235.574332)
		(end 134.650734 -235.839762)
		(width 0.0889)
		(layer "In13.Cu")
		(net "M_H_CPU1_SA_DQ<17>")
	)
	(segment
		(start 145.33372 -235.947712)
		(end 146.154648 -235.126784)
		(width 0.0889)
		(layer "In13.Cu")
		(net "M_H_CPU1_SA_DQ<17>")
	)
	(segment
		(start 166.595552 -217.710766)
		(end 170.482514 -217.710766)
		(width 0.14478)
		(layer "In13.Cu")
		(net "M_H_CPU1_SA_DQ<17>")
	)
	(segment
		(start 146.154648 -234.641644)
		(end 146.454368 -234.341924)
		(width 0.0889)
		(layer "In13.Cu")
		(net "M_H_CPU1_SA_DQ<17>")
	)
	(segment
		(start 138.743436 -235.901738)
		(end 138.751818 -235.896912)
		(width 0.0889)
		(layer "In13.Cu")
		(net "M_H_CPU1_SA_DQ<17>")
	)
	(segment
		(start 146.699732 -234.341924)
		(end 147.536662 -233.504994)
		(width 0.0889)
		(layer "In13.Cu")
		(net "M_H_CPU1_SA_DQ<17>")
	)
	(segment
		(start 170.482514 -217.710766)
		(end 171.567856 -218.160346)
		(width 0.14478)
		(layer "In13.Cu")
		(net "M_H_CPU1_SA_DQ<17>")
	)
	(segment
		(start 154.175714 -225.464878)
		(end 161.345626 -218.294966)
		(width 0.14478)
		(layer "In13.Cu")
		(net "M_H_CPU1_SA_DQ<17>")
	)
	(segment
		(start 171.567856 -218.160346)
		(end 173.935644 -218.160346)
		(width 0.14478)
		(layer "In13.Cu")
		(net "M_H_CPU1_SA_DQ<17>")
	)
	(segment
		(start 147.536662 -233.504994)
		(end 147.842224 -233.504994)
		(width 0.0889)
		(layer "In13.Cu")
		(net "M_H_CPU1_SA_DQ<17>")
	)
	(segment
		(start 144.018254 -235.896912)
		(end 144.018 -235.896912)
		(width 0.0889)
		(layer "In13.Cu")
		(net "M_H_CPU1_SA_DQ<17>")
	)
	(segment
		(start 137.803382 -235.901738)
		(end 137.811764 -235.896912)
		(width 0.0889)
		(layer "In13.Cu")
		(net "M_H_CPU1_SA_DQ<17>")
	)
	(segment
		(start 143.077692 -235.896912)
		(end 143.086074 -235.901738)
		(width 0.0889)
		(layer "In13.Cu")
		(net "M_H_CPU1_SA_DQ<17>")
	)
	(segment
		(start 165.189916 -218.294966)
		(end 166.595552 -217.710766)
		(width 0.14478)
		(layer "In13.Cu")
		(net "M_H_CPU1_SA_DQ<17>")
	)
	(segment
		(start 154.175714 -227.852478)
		(end 154.175714 -225.464878)
		(width 0.14478)
		(layer "In13.Cu")
		(net "M_H_CPU1_SA_DQ<17>")
	)
	(segment
		(start 148.523198 -233.504994)
		(end 154.175714 -227.852478)
		(width 0.14478)
		(layer "In13.Cu")
		(net "M_H_CPU1_SA_DQ<17>")
	)
	(segment
		(start 140.257784 -235.896912)
		(end 140.266166 -235.901738)
		(width 0.0889)
		(layer "In13.Cu")
		(net "M_H_CPU1_SA_DQ<17>")
	)
	(segment
		(start 135.557768 -235.896912)
		(end 135.56615 -235.901738)
		(width 0.0889)
		(layer "In13.Cu")
		(net "M_H_CPU1_SA_DQ<17>")
	)
	(arc
		(start 139.691872 -235.896912)
		(mid 139.974828 -235.820735)
		(end 140.257784 -235.896912)
		(width 0.0889)
		(layer "In13.Cu")
		(net "M_H_CPU1_SA_DQ<17>")
	)
	(arc
		(start 137.811764 -235.896912)
		(mid 138.09472 -235.820735)
		(end 138.377676 -235.896912)
		(width 0.0889)
		(layer "In13.Cu")
		(net "M_H_CPU1_SA_DQ<17>")
	)
	(arc
		(start 136.87171 -235.896912)
		(mid 137.154666 -235.820735)
		(end 137.437622 -235.896912)
		(width 0.0889)
		(layer "In13.Cu")
		(net "M_H_CPU1_SA_DQ<17>")
	)
	(arc
		(start 134.673086 -235.923074)
		(mid 134.835418 -235.945892)
		(end 134.991856 -235.896912)
		(width 0.0889)
		(layer "In13.Cu")
		(net "M_H_CPU1_SA_DQ<17>")
	)
	(arc
		(start 144.018 -235.896912)
		(mid 144.10849 -235.93473)
		(end 144.205706 -235.947712)
		(width 0.0889)
		(layer "In13.Cu")
		(net "M_H_CPU1_SA_DQ<17>")
	)
	(arc
		(start 135.56615 -235.901738)
		(mid 135.749658 -235.947232)
		(end 135.93191 -235.896912)
		(width 0.0889)
		(layer "In13.Cu")
		(net "M_H_CPU1_SA_DQ<17>")
	)
	(arc
		(start 141.197838 -235.896912)
		(mid 141.384782 -235.947167)
		(end 141.571726 -235.896912)
		(width 0.0889)
		(layer "In13.Cu")
		(net "M_H_CPU1_SA_DQ<17>")
	)
	(arc
		(start 141.571726 -235.896912)
		(mid 141.854682 -235.820735)
		(end 142.137638 -235.896912)
		(width 0.0889)
		(layer "In13.Cu")
		(net "M_H_CPU1_SA_DQ<17>")
	)
	(arc
		(start 138.377676 -235.896912)
		(mid 138.559927 -235.947262)
		(end 138.743436 -235.901738)
		(width 0.0889)
		(layer "In13.Cu")
		(net "M_H_CPU1_SA_DQ<17>")
	)
	(arc
		(start 142.137638 -235.896912)
		(mid 142.319889 -235.947262)
		(end 142.503398 -235.901738)
		(width 0.0889)
		(layer "In13.Cu")
		(net "M_H_CPU1_SA_DQ<17>")
	)
	(arc
		(start 140.631926 -235.896912)
		(mid 140.914882 -235.820735)
		(end 141.197838 -235.896912)
		(width 0.0889)
		(layer "In13.Cu")
		(net "M_H_CPU1_SA_DQ<17>")
	)
	(arc
		(start 134.991856 -235.896912)
		(mid 135.274812 -235.820735)
		(end 135.557768 -235.896912)
		(width 0.0889)
		(layer "In13.Cu")
		(net "M_H_CPU1_SA_DQ<17>")
	)
	(arc
		(start 142.51178 -235.896912)
		(mid 142.794736 -235.820735)
		(end 143.077692 -235.896912)
		(width 0.0889)
		(layer "In13.Cu")
		(net "M_H_CPU1_SA_DQ<17>")
	)
	(arc
		(start 140.266166 -235.901738)
		(mid 140.449674 -235.947232)
		(end 140.631926 -235.896912)
		(width 0.0889)
		(layer "In13.Cu")
		(net "M_H_CPU1_SA_DQ<17>")
	)
	(arc
		(start 136.497822 -235.896912)
		(mid 136.684766 -235.947167)
		(end 136.87171 -235.896912)
		(width 0.0889)
		(layer "In13.Cu")
		(net "M_H_CPU1_SA_DQ<17>")
	)
	(arc
		(start 143.086074 -235.901738)
		(mid 143.269582 -235.947232)
		(end 143.451834 -235.896912)
		(width 0.0889)
		(layer "In13.Cu")
		(net "M_H_CPU1_SA_DQ<17>")
	)
	(arc
		(start 143.466566 -235.888276)
		(mid 143.743549 -235.820472)
		(end 144.018254 -235.896912)
		(width 0.0889)
		(layer "In13.Cu")
		(net "M_H_CPU1_SA_DQ<17>")
	)
	(arc
		(start 137.437622 -235.896912)
		(mid 137.619873 -235.947262)
		(end 137.803382 -235.901738)
		(width 0.0889)
		(layer "In13.Cu")
		(net "M_H_CPU1_SA_DQ<17>")
	)
	(arc
		(start 139.326112 -235.901738)
		(mid 139.50962 -235.947232)
		(end 139.691872 -235.896912)
		(width 0.0889)
		(layer "In13.Cu")
		(net "M_H_CPU1_SA_DQ<17>")
	)
	(arc
		(start 135.93191 -235.896912)
		(mid 136.214866 -235.820735)
		(end 136.497822 -235.896912)
		(width 0.0889)
		(layer "In13.Cu")
		(net "M_H_CPU1_SA_DQ<17>")
	)
	(arc
		(start 138.751818 -235.896912)
		(mid 139.034774 -235.820735)
		(end 139.31773 -235.896912)
		(width 0.0889)
		(layer "In13.Cu")
		(net "M_H_CPU1_SA_DQ<17>")
	)
	(segment
		(start 135.748014 -235.030264)
		(end 136.214866 -234.764326)
		(width 0.10668)
		(layer "F.Cu")
		(net "M_H_CPU1_SA_DQ<16>")
	)
	(segment
		(start 140.15339 -235.091732)
		(end 140.161772 -235.086906)
		(width 0.0889)
		(layer "In13.Cu")
		(net "M_H_CPU1_SA_DQ<16>")
	)
	(segment
		(start 136.967722 -235.086906)
		(end 136.976104 -235.091732)
		(width 0.0889)
		(layer "In13.Cu")
		(net "M_H_CPU1_SA_DQ<16>")
	)
	(segment
		(start 173.684946 -216.460324)
		(end 174.109888 -216.035382)
		(width 0.14478)
		(layer "In13.Cu")
		(net "M_H_CPU1_SA_DQ<16>")
	)
	(segment
		(start 137.907776 -235.086906)
		(end 137.916158 -235.091732)
		(width 0.0889)
		(layer "In13.Cu")
		(net "M_H_CPU1_SA_DQ<16>")
	)
	(segment
		(start 147.94611 -232.574084)
		(end 148.073872 -232.574084)
		(width 0.14478)
		(layer "In13.Cu")
		(net "M_H_CPU1_SA_DQ<16>")
	)
	(segment
		(start 153.276554 -227.371402)
		(end 153.276554 -224.513902)
		(width 0.14478)
		(layer "In13.Cu")
		(net "M_H_CPU1_SA_DQ<16>")
	)
	(segment
		(start 167.024304 -215.61044)
		(end 169.776902 -215.61044)
		(width 0.14478)
		(layer "In13.Cu")
		(net "M_H_CPU1_SA_DQ<16>")
	)
	(segment
		(start 143.547592 -235.086906)
		(end 143.555974 -235.091732)
		(width 0.0889)
		(layer "In13.Cu")
		(net "M_H_CPU1_SA_DQ<16>")
	)
	(segment
		(start 146.373088 -233.422444)
		(end 146.373088 -233.277156)
		(width 0.0889)
		(layer "In13.Cu")
		(net "M_H_CPU1_SA_DQ<16>")
	)
	(segment
		(start 169.776902 -215.61044)
		(end 170.626786 -216.460324)
		(width 0.14478)
		(layer "In13.Cu")
		(net "M_H_CPU1_SA_DQ<16>")
	)
	(segment
		(start 144.830546 -234.616244)
		(end 145.179288 -234.616244)
		(width 0.0889)
		(layer "In13.Cu")
		(net "M_H_CPU1_SA_DQ<16>")
	)
	(segment
		(start 166.17442 -216.460324)
		(end 167.024304 -215.61044)
		(width 0.14478)
		(layer "In13.Cu")
		(net "M_H_CPU1_SA_DQ<16>")
	)
	(segment
		(start 146.373088 -233.277156)
		(end 147.07616 -232.574084)
		(width 0.0889)
		(layer "In13.Cu")
		(net "M_H_CPU1_SA_DQ<16>")
	)
	(segment
		(start 136.393428 -235.091732)
		(end 136.40181 -235.086906)
		(width 0.0889)
		(layer "In13.Cu")
		(net "M_H_CPU1_SA_DQ<16>")
	)
	(segment
		(start 141.093444 -235.091732)
		(end 141.101826 -235.086906)
		(width 0.0889)
		(layer "In13.Cu")
		(net "M_H_CPU1_SA_DQ<16>")
	)
	(segment
		(start 136.214866 -234.764326)
		(end 136.060688 -235.029756)
		(width 0.0889)
		(layer "In13.Cu")
		(net "M_H_CPU1_SA_DQ<16>")
	)
	(segment
		(start 143.922242 -235.086906)
		(end 144.830546 -234.616244)
		(width 0.0889)
		(layer "In13.Cu")
		(net "M_H_CPU1_SA_DQ<16>")
	)
	(segment
		(start 141.667738 -235.086906)
		(end 141.67612 -235.091732)
		(width 0.0889)
		(layer "In13.Cu")
		(net "M_H_CPU1_SA_DQ<16>")
	)
	(segment
		(start 147.07616 -232.574084)
		(end 147.94611 -232.574084)
		(width 0.0889)
		(layer "In13.Cu")
		(net "M_H_CPU1_SA_DQ<16>")
	)
	(segment
		(start 153.276554 -224.513902)
		(end 161.330132 -216.460324)
		(width 0.14478)
		(layer "In13.Cu")
		(net "M_H_CPU1_SA_DQ<16>")
	)
	(segment
		(start 136.060688 -235.029756)
		(end 136.08304 -235.113068)
		(width 0.0889)
		(layer "In13.Cu")
		(net "M_H_CPU1_SA_DQ<16>")
	)
	(segment
		(start 145.179288 -234.616244)
		(end 146.373088 -233.422444)
		(width 0.0889)
		(layer "In13.Cu")
		(net "M_H_CPU1_SA_DQ<16>")
	)
	(segment
		(start 170.626786 -216.460324)
		(end 173.684946 -216.460324)
		(width 0.14478)
		(layer "In13.Cu")
		(net "M_H_CPU1_SA_DQ<16>")
	)
	(segment
		(start 148.073872 -232.574084)
		(end 153.276554 -227.371402)
		(width 0.14478)
		(layer "In13.Cu")
		(net "M_H_CPU1_SA_DQ<16>")
	)
	(segment
		(start 161.330132 -216.460324)
		(end 166.17442 -216.460324)
		(width 0.14478)
		(layer "In13.Cu")
		(net "M_H_CPU1_SA_DQ<16>")
	)
	(segment
		(start 174.109888 -216.035382)
		(end 176.072038 -216.035382)
		(width 0.14478)
		(layer "In13.Cu")
		(net "M_H_CPU1_SA_DQ<16>")
	)
	(arc
		(start 142.04188 -235.086906)
		(mid 142.324836 -235.010729)
		(end 142.607792 -235.086906)
		(width 0.0889)
		(layer "In13.Cu")
		(net "M_H_CPU1_SA_DQ<16>")
	)
	(arc
		(start 141.101826 -235.086906)
		(mid 141.384782 -235.010729)
		(end 141.667738 -235.086906)
		(width 0.0889)
		(layer "In13.Cu")
		(net "M_H_CPU1_SA_DQ<16>")
	)
	(arc
		(start 142.98168 -235.086906)
		(mid 143.264636 -235.010729)
		(end 143.547592 -235.086906)
		(width 0.0889)
		(layer "In13.Cu")
		(net "M_H_CPU1_SA_DQ<16>")
	)
	(arc
		(start 142.607792 -235.086906)
		(mid 142.794736 -235.137161)
		(end 142.98168 -235.086906)
		(width 0.0889)
		(layer "In13.Cu")
		(net "M_H_CPU1_SA_DQ<16>")
	)
	(arc
		(start 136.40181 -235.086906)
		(mid 136.684766 -235.010729)
		(end 136.967722 -235.086906)
		(width 0.0889)
		(layer "In13.Cu")
		(net "M_H_CPU1_SA_DQ<16>")
	)
	(arc
		(start 141.67612 -235.091732)
		(mid 141.859628 -235.137226)
		(end 142.04188 -235.086906)
		(width 0.0889)
		(layer "In13.Cu")
		(net "M_H_CPU1_SA_DQ<16>")
	)
	(arc
		(start 137.341864 -235.086906)
		(mid 137.62482 -235.010729)
		(end 137.907776 -235.086906)
		(width 0.0889)
		(layer "In13.Cu")
		(net "M_H_CPU1_SA_DQ<16>")
	)
	(arc
		(start 136.976104 -235.091732)
		(mid 137.159612 -235.137226)
		(end 137.341864 -235.086906)
		(width 0.0889)
		(layer "In13.Cu")
		(net "M_H_CPU1_SA_DQ<16>")
	)
	(arc
		(start 136.08304 -235.113068)
		(mid 136.24055 -235.136266)
		(end 136.393428 -235.091732)
		(width 0.0889)
		(layer "In13.Cu")
		(net "M_H_CPU1_SA_DQ<16>")
	)
	(arc
		(start 140.727684 -235.086906)
		(mid 140.909935 -235.137256)
		(end 141.093444 -235.091732)
		(width 0.0889)
		(layer "In13.Cu")
		(net "M_H_CPU1_SA_DQ<16>")
	)
	(arc
		(start 140.161772 -235.086906)
		(mid 140.444728 -235.010729)
		(end 140.727684 -235.086906)
		(width 0.0889)
		(layer "In13.Cu")
		(net "M_H_CPU1_SA_DQ<16>")
	)
	(arc
		(start 139.78763 -235.086906)
		(mid 139.969881 -235.137256)
		(end 140.15339 -235.091732)
		(width 0.0889)
		(layer "In13.Cu")
		(net "M_H_CPU1_SA_DQ<16>")
	)
	(arc
		(start 137.916158 -235.091732)
		(mid 138.099666 -235.137226)
		(end 138.281918 -235.086906)
		(width 0.0889)
		(layer "In13.Cu")
		(net "M_H_CPU1_SA_DQ<16>")
	)
	(arc
		(start 138.84783 -235.086906)
		(mid 139.034774 -235.137161)
		(end 139.221718 -235.086906)
		(width 0.0889)
		(layer "In13.Cu")
		(net "M_H_CPU1_SA_DQ<16>")
	)
	(arc
		(start 139.221718 -235.086906)
		(mid 139.504674 -235.010729)
		(end 139.78763 -235.086906)
		(width 0.0889)
		(layer "In13.Cu")
		(net "M_H_CPU1_SA_DQ<16>")
	)
	(arc
		(start 143.555974 -235.091732)
		(mid 143.739736 -235.137348)
		(end 143.922242 -235.086906)
		(width 0.0889)
		(layer "In13.Cu")
		(net "M_H_CPU1_SA_DQ<16>")
	)
	(arc
		(start 138.281918 -235.086906)
		(mid 138.564874 -235.010729)
		(end 138.84783 -235.086906)
		(width 0.0889)
		(layer "In13.Cu")
		(net "M_H_CPU1_SA_DQ<16>")
	)
	(segment
		(start 133.867906 -235.030264)
		(end 134.334758 -234.764326)
		(width 0.10668)
		(layer "F.Cu")
		(net "M_H_CPU1_SA_DQ<15>")
	)
	(segment
		(start 158.424626 -218.586304)
		(end 158.609792 -218.401138)
		(width 0.14478)
		(layer "In13.Cu")
		(net "M_H_CPU1_SA_DQ<15>")
	)
	(segment
		(start 135.453374 -234.43692)
		(end 135.461756 -234.441746)
		(width 0.0889)
		(layer "In13.Cu")
		(net "M_H_CPU1_SA_DQ<15>")
	)
	(segment
		(start 147.337526 -232.020364)
		(end 147.761706 -232.020364)
		(width 0.0889)
		(layer "In13.Cu")
		(net "M_H_CPU1_SA_DQ<15>")
	)
	(segment
		(start 156.865066 -220.145864)
		(end 157.050232 -219.960698)
		(width 0.14478)
		(layer "In13.Cu")
		(net "M_H_CPU1_SA_DQ<15>")
	)
	(segment
		(start 157.050232 -219.960698)
		(end 157.050232 -219.755974)
		(width 0.14478)
		(layer "In13.Cu")
		(net "M_H_CPU1_SA_DQ<15>")
	)
	(segment
		(start 160.45434 -216.142062)
		(end 160.559242 -216.246964)
		(width 0.14478)
		(layer "In13.Cu")
		(net "M_H_CPU1_SA_DQ<15>")
	)
	(segment
		(start 155.490672 -221.520258)
		(end 155.490672 -221.315534)
		(width 0.14478)
		(layer "In13.Cu")
		(net "M_H_CPU1_SA_DQ<15>")
	)
	(segment
		(start 153.931112 -223.079818)
		(end 153.931112 -222.875094)
		(width 0.14478)
		(layer "In13.Cu")
		(net "M_H_CPU1_SA_DQ<15>")
	)
	(segment
		(start 158.50489 -217.886788)
		(end 158.690056 -217.701622)
		(width 0.14478)
		(layer "In13.Cu")
		(net "M_H_CPU1_SA_DQ<15>")
	)
	(segment
		(start 153.82621 -222.770192)
		(end 153.82621 -222.565468)
		(width 0.14478)
		(layer "In13.Cu")
		(net "M_H_CPU1_SA_DQ<15>")
	)
	(segment
		(start 160.763966 -216.246964)
		(end 161.40049 -215.61044)
		(width 0.14478)
		(layer "In13.Cu")
		(net "M_H_CPU1_SA_DQ<15>")
	)
	(segment
		(start 157.644846 -219.366084)
		(end 157.830012 -219.180918)
		(width 0.14478)
		(layer "In13.Cu")
		(net "M_H_CPU1_SA_DQ<15>")
	)
	(segment
		(start 160.06445 -216.531952)
		(end 160.06445 -216.327228)
		(width 0.14478)
		(layer "In13.Cu")
		(net "M_H_CPU1_SA_DQ<15>")
	)
	(segment
		(start 154.2161 -222.380302)
		(end 154.321002 -222.485204)
		(width 0.14478)
		(layer "In13.Cu")
		(net "M_H_CPU1_SA_DQ<15>")
	)
	(segment
		(start 152.725374 -224.285556)
		(end 153.151332 -223.859598)
		(width 0.14478)
		(layer "In13.Cu")
		(net "M_H_CPU1_SA_DQ<15>")
	)
	(segment
		(start 141.667738 -234.441746)
		(end 141.67612 -234.43692)
		(width 0.0889)
		(layer "In13.Cu")
		(net "M_H_CPU1_SA_DQ<15>")
	)
	(segment
		(start 153.151332 -223.859598)
		(end 153.151332 -223.654874)
		(width 0.14478)
		(layer "In13.Cu")
		(net "M_H_CPU1_SA_DQ<15>")
	)
	(segment
		(start 157.440122 -219.366084)
		(end 157.644846 -219.366084)
		(width 0.14478)
		(layer "In13.Cu")
		(net "M_H_CPU1_SA_DQ<15>")
	)
	(segment
		(start 137.907776 -234.441746)
		(end 137.916158 -234.43692)
		(width 0.0889)
		(layer "In13.Cu")
		(net "M_H_CPU1_SA_DQ<15>")
	)
	(segment
		(start 141.093444 -234.43692)
		(end 141.101826 -234.441746)
		(width 0.0889)
		(layer "In13.Cu")
		(net "M_H_CPU1_SA_DQ<15>")
	)
	(segment
		(start 154.710892 -222.300038)
		(end 154.710892 -222.095314)
		(width 0.14478)
		(layer "In13.Cu")
		(net "M_H_CPU1_SA_DQ<15>")
	)
	(segment
		(start 154.99588 -221.600522)
		(end 155.100782 -221.705424)
		(width 0.14478)
		(layer "In13.Cu")
		(net "M_H_CPU1_SA_DQ<15>")
	)
	(segment
		(start 156.085286 -220.925644)
		(end 156.270452 -220.740478)
		(width 0.14478)
		(layer "In13.Cu")
		(net "M_H_CPU1_SA_DQ<15>")
	)
	(segment
		(start 153.541222 -223.264984)
		(end 153.745946 -223.264984)
		(width 0.14478)
		(layer "In13.Cu")
		(net "M_H_CPU1_SA_DQ<15>")
	)
	(segment
		(start 157.33522 -219.261182)
		(end 157.440122 -219.366084)
		(width 0.14478)
		(layer "In13.Cu")
		(net "M_H_CPU1_SA_DQ<15>")
	)
	(segment
		(start 154.791156 -221.600522)
		(end 154.99588 -221.600522)
		(width 0.14478)
		(layer "In13.Cu")
		(net "M_H_CPU1_SA_DQ<15>")
	)
	(segment
		(start 158.609792 -218.196414)
		(end 158.50489 -218.091512)
		(width 0.14478)
		(layer "In13.Cu")
		(net "M_H_CPU1_SA_DQ<15>")
	)
	(segment
		(start 171.97197 -215.19007)
		(end 171.97197 -215.185244)
		(width 0.14478)
		(layer "In13.Cu")
		(net "M_H_CPU1_SA_DQ<15>")
	)
	(segment
		(start 134.334758 -234.764326)
		(end 134.488682 -234.498896)
		(width 0.0889)
		(layer "In13.Cu")
		(net "M_H_CPU1_SA_DQ<15>")
	)
	(segment
		(start 155.77566 -220.820742)
		(end 155.880562 -220.925644)
		(width 0.14478)
		(layer "In13.Cu")
		(net "M_H_CPU1_SA_DQ<15>")
	)
	(segment
		(start 159.204406 -217.806524)
		(end 159.389572 -217.621358)
		(width 0.14478)
		(layer "In13.Cu")
		(net "M_H_CPU1_SA_DQ<15>")
	)
	(segment
		(start 158.609792 -218.401138)
		(end 158.609792 -218.196414)
		(width 0.14478)
		(layer "In13.Cu")
		(net "M_H_CPU1_SA_DQ<15>")
	)
	(segment
		(start 170.611038 -215.61044)
		(end 171.5516 -215.61044)
		(width 0.14478)
		(layer "In13.Cu")
		(net "M_H_CPU1_SA_DQ<15>")
	)
	(segment
		(start 159.67456 -216.921842)
		(end 159.779462 -217.026744)
		(width 0.14478)
		(layer "In13.Cu")
		(net "M_H_CPU1_SA_DQ<15>")
	)
	(segment
		(start 153.04643 -223.345248)
		(end 153.231596 -223.160082)
		(width 0.14478)
		(layer "In13.Cu")
		(net "M_H_CPU1_SA_DQ<15>")
	)
	(segment
		(start 136.393428 -234.43692)
		(end 136.40181 -234.441746)
		(width 0.0889)
		(layer "In13.Cu")
		(net "M_H_CPU1_SA_DQ<15>")
	)
	(segment
		(start 156.270452 -220.740478)
		(end 156.270452 -220.535754)
		(width 0.14478)
		(layer "In13.Cu")
		(net "M_H_CPU1_SA_DQ<15>")
	)
	(segment
		(start 160.559242 -216.246964)
		(end 160.763966 -216.246964)
		(width 0.14478)
		(layer "In13.Cu")
		(net "M_H_CPU1_SA_DQ<15>")
	)
	(segment
		(start 143.73479 -234.391454)
		(end 144.195038 -234.391454)
		(width 0.0889)
		(layer "In13.Cu")
		(net "M_H_CPU1_SA_DQ<15>")
	)
	(segment
		(start 155.490672 -221.315534)
		(end 155.38577 -221.210632)
		(width 0.14478)
		(layer "In13.Cu")
		(net "M_H_CPU1_SA_DQ<15>")
	)
	(segment
		(start 140.15339 -234.43692)
		(end 140.161772 -234.441746)
		(width 0.0889)
		(layer "In13.Cu")
		(net "M_H_CPU1_SA_DQ<15>")
	)
	(segment
		(start 159.469836 -216.921842)
		(end 159.67456 -216.921842)
		(width 0.14478)
		(layer "In13.Cu")
		(net "M_H_CPU1_SA_DQ<15>")
	)
	(segment
		(start 144.195038 -234.391454)
		(end 144.991328 -233.595164)
		(width 0.0889)
		(layer "In13.Cu")
		(net "M_H_CPU1_SA_DQ<15>")
	)
	(segment
		(start 160.249616 -216.142062)
		(end 160.45434 -216.142062)
		(width 0.14478)
		(layer "In13.Cu")
		(net "M_H_CPU1_SA_DQ<15>")
	)
	(segment
		(start 154.525726 -222.485204)
		(end 154.710892 -222.300038)
		(width 0.14478)
		(layer "In13.Cu")
		(net "M_H_CPU1_SA_DQ<15>")
	)
	(segment
		(start 157.830012 -219.180918)
		(end 157.830012 -218.976194)
		(width 0.14478)
		(layer "In13.Cu")
		(net "M_H_CPU1_SA_DQ<15>")
	)
	(segment
		(start 154.321002 -222.485204)
		(end 154.525726 -222.485204)
		(width 0.14478)
		(layer "In13.Cu")
		(net "M_H_CPU1_SA_DQ<15>")
	)
	(segment
		(start 147.761706 -232.020364)
		(end 152.725374 -227.056696)
		(width 0.14478)
		(layer "In13.Cu")
		(net "M_H_CPU1_SA_DQ<15>")
	)
	(segment
		(start 158.115 -218.481402)
		(end 158.219902 -218.586304)
		(width 0.14478)
		(layer "In13.Cu")
		(net "M_H_CPU1_SA_DQ<15>")
	)
	(segment
		(start 159.28467 -217.311732)
		(end 159.28467 -217.107008)
		(width 0.14478)
		(layer "In13.Cu")
		(net "M_H_CPU1_SA_DQ<15>")
	)
	(segment
		(start 154.60599 -221.785688)
		(end 154.791156 -221.600522)
		(width 0.14478)
		(layer "In13.Cu")
		(net "M_H_CPU1_SA_DQ<15>")
	)
	(segment
		(start 155.570936 -220.820742)
		(end 155.77566 -220.820742)
		(width 0.14478)
		(layer "In13.Cu")
		(net "M_H_CPU1_SA_DQ<15>")
	)
	(segment
		(start 157.72511 -218.871292)
		(end 157.72511 -218.666568)
		(width 0.14478)
		(layer "In13.Cu")
		(net "M_H_CPU1_SA_DQ<15>")
	)
	(segment
		(start 158.89478 -217.701622)
		(end 158.999682 -217.806524)
		(width 0.14478)
		(layer "In13.Cu")
		(net "M_H_CPU1_SA_DQ<15>")
	)
	(segment
		(start 153.745946 -223.264984)
		(end 153.931112 -223.079818)
		(width 0.14478)
		(layer "In13.Cu")
		(net "M_H_CPU1_SA_DQ<15>")
	)
	(segment
		(start 159.389572 -217.416634)
		(end 159.28467 -217.311732)
		(width 0.14478)
		(layer "In13.Cu")
		(net "M_H_CPU1_SA_DQ<15>")
	)
	(segment
		(start 158.999682 -217.806524)
		(end 159.204406 -217.806524)
		(width 0.14478)
		(layer "In13.Cu")
		(net "M_H_CPU1_SA_DQ<15>")
	)
	(segment
		(start 159.28467 -217.107008)
		(end 159.469836 -216.921842)
		(width 0.14478)
		(layer "In13.Cu")
		(net "M_H_CPU1_SA_DQ<15>")
	)
	(segment
		(start 169.7609 -214.760302)
		(end 170.611038 -215.61044)
		(width 0.14478)
		(layer "In13.Cu")
		(net "M_H_CPU1_SA_DQ<15>")
	)
	(segment
		(start 144.991328 -233.595164)
		(end 145.762726 -233.595164)
		(width 0.0889)
		(layer "In13.Cu")
		(net "M_H_CPU1_SA_DQ<15>")
	)
	(segment
		(start 159.779462 -217.026744)
		(end 159.984186 -217.026744)
		(width 0.14478)
		(layer "In13.Cu")
		(net "M_H_CPU1_SA_DQ<15>")
	)
	(segment
		(start 158.690056 -217.701622)
		(end 158.89478 -217.701622)
		(width 0.14478)
		(layer "In13.Cu")
		(net "M_H_CPU1_SA_DQ<15>")
	)
	(segment
		(start 156.94533 -219.446348)
		(end 157.130496 -219.261182)
		(width 0.14478)
		(layer "In13.Cu")
		(net "M_H_CPU1_SA_DQ<15>")
	)
	(segment
		(start 166.065708 -215.61044)
		(end 166.915846 -214.760302)
		(width 0.14478)
		(layer "In13.Cu")
		(net "M_H_CPU1_SA_DQ<15>")
	)
	(segment
		(start 156.94533 -219.651072)
		(end 156.94533 -219.446348)
		(width 0.14478)
		(layer "In13.Cu")
		(net "M_H_CPU1_SA_DQ<15>")
	)
	(segment
		(start 157.130496 -219.261182)
		(end 157.33522 -219.261182)
		(width 0.14478)
		(layer "In13.Cu")
		(net "M_H_CPU1_SA_DQ<15>")
	)
	(segment
		(start 171.5516 -215.61044)
		(end 171.97197 -215.19007)
		(width 0.14478)
		(layer "In13.Cu")
		(net "M_H_CPU1_SA_DQ<15>")
	)
	(segment
		(start 155.38577 -221.210632)
		(end 155.38577 -221.005908)
		(width 0.14478)
		(layer "In13.Cu")
		(net "M_H_CPU1_SA_DQ<15>")
	)
	(segment
		(start 166.915846 -214.760302)
		(end 169.7609 -214.760302)
		(width 0.14478)
		(layer "In13.Cu")
		(net "M_H_CPU1_SA_DQ<15>")
	)
	(segment
		(start 157.830012 -218.976194)
		(end 157.72511 -218.871292)
		(width 0.14478)
		(layer "In13.Cu")
		(net "M_H_CPU1_SA_DQ<15>")
	)
	(segment
		(start 152.725374 -227.056696)
		(end 152.725374 -224.285556)
		(width 0.14478)
		(layer "In13.Cu")
		(net "M_H_CPU1_SA_DQ<15>")
	)
	(segment
		(start 153.82621 -222.565468)
		(end 154.011376 -222.380302)
		(width 0.14478)
		(layer "In13.Cu")
		(net "M_H_CPU1_SA_DQ<15>")
	)
	(segment
		(start 157.910276 -218.481402)
		(end 158.115 -218.481402)
		(width 0.14478)
		(layer "In13.Cu")
		(net "M_H_CPU1_SA_DQ<15>")
	)
	(segment
		(start 154.60599 -221.990412)
		(end 154.60599 -221.785688)
		(width 0.14478)
		(layer "In13.Cu")
		(net "M_H_CPU1_SA_DQ<15>")
	)
	(segment
		(start 155.38577 -221.005908)
		(end 155.570936 -220.820742)
		(width 0.14478)
		(layer "In13.Cu")
		(net "M_H_CPU1_SA_DQ<15>")
	)
	(segment
		(start 160.169352 -216.841578)
		(end 160.169352 -216.636854)
		(width 0.14478)
		(layer "In13.Cu")
		(net "M_H_CPU1_SA_DQ<15>")
	)
	(segment
		(start 160.169352 -216.636854)
		(end 160.06445 -216.531952)
		(width 0.14478)
		(layer "In13.Cu")
		(net "M_H_CPU1_SA_DQ<15>")
	)
	(segment
		(start 156.16555 -220.430852)
		(end 156.16555 -220.226128)
		(width 0.14478)
		(layer "In13.Cu")
		(net "M_H_CPU1_SA_DQ<15>")
	)
	(segment
		(start 145.762726 -233.595164)
		(end 147.337526 -232.020364)
		(width 0.0889)
		(layer "In13.Cu")
		(net "M_H_CPU1_SA_DQ<15>")
	)
	(segment
		(start 134.488682 -234.498896)
		(end 134.584694 -234.473496)
		(width 0.0889)
		(layer "In13.Cu")
		(net "M_H_CPU1_SA_DQ<15>")
	)
	(segment
		(start 154.710892 -222.095314)
		(end 154.60599 -221.990412)
		(width 0.14478)
		(layer "In13.Cu")
		(net "M_H_CPU1_SA_DQ<15>")
	)
	(segment
		(start 153.04643 -223.549972)
		(end 153.04643 -223.345248)
		(width 0.14478)
		(layer "In13.Cu")
		(net "M_H_CPU1_SA_DQ<15>")
	)
	(segment
		(start 159.984186 -217.026744)
		(end 160.169352 -216.841578)
		(width 0.14478)
		(layer "In13.Cu")
		(net "M_H_CPU1_SA_DQ<15>")
	)
	(segment
		(start 159.389572 -217.621358)
		(end 159.389572 -217.416634)
		(width 0.14478)
		(layer "In13.Cu")
		(net "M_H_CPU1_SA_DQ<15>")
	)
	(segment
		(start 158.219902 -218.586304)
		(end 158.424626 -218.586304)
		(width 0.14478)
		(layer "In13.Cu")
		(net "M_H_CPU1_SA_DQ<15>")
	)
	(segment
		(start 160.06445 -216.327228)
		(end 160.249616 -216.142062)
		(width 0.14478)
		(layer "In13.Cu")
		(net "M_H_CPU1_SA_DQ<15>")
	)
	(segment
		(start 153.931112 -222.875094)
		(end 153.82621 -222.770192)
		(width 0.14478)
		(layer "In13.Cu")
		(net "M_H_CPU1_SA_DQ<15>")
	)
	(segment
		(start 161.40049 -215.61044)
		(end 166.065708 -215.61044)
		(width 0.14478)
		(layer "In13.Cu")
		(net "M_H_CPU1_SA_DQ<15>")
	)
	(segment
		(start 153.151332 -223.654874)
		(end 153.04643 -223.549972)
		(width 0.14478)
		(layer "In13.Cu")
		(net "M_H_CPU1_SA_DQ<15>")
	)
	(segment
		(start 136.967722 -234.441746)
		(end 136.976104 -234.43692)
		(width 0.0889)
		(layer "In13.Cu")
		(net "M_H_CPU1_SA_DQ<15>")
	)
	(segment
		(start 156.270452 -220.535754)
		(end 156.16555 -220.430852)
		(width 0.14478)
		(layer "In13.Cu")
		(net "M_H_CPU1_SA_DQ<15>")
	)
	(segment
		(start 153.43632 -223.160082)
		(end 153.541222 -223.264984)
		(width 0.14478)
		(layer "In13.Cu")
		(net "M_H_CPU1_SA_DQ<15>")
	)
	(segment
		(start 158.50489 -218.091512)
		(end 158.50489 -217.886788)
		(width 0.14478)
		(layer "In13.Cu")
		(net "M_H_CPU1_SA_DQ<15>")
	)
	(segment
		(start 157.72511 -218.666568)
		(end 157.910276 -218.481402)
		(width 0.14478)
		(layer "In13.Cu")
		(net "M_H_CPU1_SA_DQ<15>")
	)
	(segment
		(start 155.100782 -221.705424)
		(end 155.305506 -221.705424)
		(width 0.14478)
		(layer "In13.Cu")
		(net "M_H_CPU1_SA_DQ<15>")
	)
	(segment
		(start 155.880562 -220.925644)
		(end 156.085286 -220.925644)
		(width 0.14478)
		(layer "In13.Cu")
		(net "M_H_CPU1_SA_DQ<15>")
	)
	(segment
		(start 154.011376 -222.380302)
		(end 154.2161 -222.380302)
		(width 0.14478)
		(layer "In13.Cu")
		(net "M_H_CPU1_SA_DQ<15>")
	)
	(segment
		(start 157.050232 -219.755974)
		(end 156.94533 -219.651072)
		(width 0.14478)
		(layer "In13.Cu")
		(net "M_H_CPU1_SA_DQ<15>")
	)
	(segment
		(start 156.660342 -220.145864)
		(end 156.865066 -220.145864)
		(width 0.14478)
		(layer "In13.Cu")
		(net "M_H_CPU1_SA_DQ<15>")
	)
	(segment
		(start 153.231596 -223.160082)
		(end 153.43632 -223.160082)
		(width 0.14478)
		(layer "In13.Cu")
		(net "M_H_CPU1_SA_DQ<15>")
	)
	(segment
		(start 156.16555 -220.226128)
		(end 156.350716 -220.040962)
		(width 0.14478)
		(layer "In13.Cu")
		(net "M_H_CPU1_SA_DQ<15>")
	)
	(segment
		(start 155.305506 -221.705424)
		(end 155.490672 -221.520258)
		(width 0.14478)
		(layer "In13.Cu")
		(net "M_H_CPU1_SA_DQ<15>")
	)
	(segment
		(start 156.350716 -220.040962)
		(end 156.55544 -220.040962)
		(width 0.14478)
		(layer "In13.Cu")
		(net "M_H_CPU1_SA_DQ<15>")
	)
	(segment
		(start 156.55544 -220.040962)
		(end 156.660342 -220.145864)
		(width 0.14478)
		(layer "In13.Cu")
		(net "M_H_CPU1_SA_DQ<15>")
	)
	(arc
		(start 143.547592 -234.441746)
		(mid 143.637868 -234.404241)
		(end 143.73479 -234.391454)
		(width 0.0889)
		(layer "In13.Cu")
		(net "M_H_CPU1_SA_DQ<15>")
	)
	(arc
		(start 141.67612 -234.43692)
		(mid 141.859628 -234.391426)
		(end 142.04188 -234.441746)
		(width 0.0889)
		(layer "In13.Cu")
		(net "M_H_CPU1_SA_DQ<15>")
	)
	(arc
		(start 136.976104 -234.43692)
		(mid 137.159612 -234.391426)
		(end 137.341864 -234.441746)
		(width 0.0889)
		(layer "In13.Cu")
		(net "M_H_CPU1_SA_DQ<15>")
	)
	(arc
		(start 140.727684 -234.441746)
		(mid 140.909935 -234.391396)
		(end 141.093444 -234.43692)
		(width 0.0889)
		(layer "In13.Cu")
		(net "M_H_CPU1_SA_DQ<15>")
	)
	(arc
		(start 140.161772 -234.441746)
		(mid 140.444728 -234.517923)
		(end 140.727684 -234.441746)
		(width 0.0889)
		(layer "In13.Cu")
		(net "M_H_CPU1_SA_DQ<15>")
	)
	(arc
		(start 139.221718 -234.441746)
		(mid 139.504674 -234.517923)
		(end 139.78763 -234.441746)
		(width 0.0889)
		(layer "In13.Cu")
		(net "M_H_CPU1_SA_DQ<15>")
	)
	(arc
		(start 135.461756 -234.441746)
		(mid 135.744712 -234.517923)
		(end 136.027668 -234.441746)
		(width 0.0889)
		(layer "In13.Cu")
		(net "M_H_CPU1_SA_DQ<15>")
	)
	(arc
		(start 136.027668 -234.441746)
		(mid 136.209919 -234.391396)
		(end 136.393428 -234.43692)
		(width 0.0889)
		(layer "In13.Cu")
		(net "M_H_CPU1_SA_DQ<15>")
	)
	(arc
		(start 134.584694 -234.473496)
		(mid 134.839902 -234.516973)
		(end 135.087614 -234.441746)
		(width 0.0889)
		(layer "In13.Cu")
		(net "M_H_CPU1_SA_DQ<15>")
	)
	(arc
		(start 141.101826 -234.441746)
		(mid 141.384782 -234.517923)
		(end 141.667738 -234.441746)
		(width 0.0889)
		(layer "In13.Cu")
		(net "M_H_CPU1_SA_DQ<15>")
	)
	(arc
		(start 139.78763 -234.441746)
		(mid 139.969881 -234.391396)
		(end 140.15339 -234.43692)
		(width 0.0889)
		(layer "In13.Cu")
		(net "M_H_CPU1_SA_DQ<15>")
	)
	(arc
		(start 138.281918 -234.441746)
		(mid 138.564874 -234.517923)
		(end 138.84783 -234.441746)
		(width 0.0889)
		(layer "In13.Cu")
		(net "M_H_CPU1_SA_DQ<15>")
	)
	(arc
		(start 135.087614 -234.441746)
		(mid 135.269865 -234.391396)
		(end 135.453374 -234.43692)
		(width 0.0889)
		(layer "In13.Cu")
		(net "M_H_CPU1_SA_DQ<15>")
	)
	(arc
		(start 142.04188 -234.441746)
		(mid 142.324836 -234.517923)
		(end 142.607792 -234.441746)
		(width 0.0889)
		(layer "In13.Cu")
		(net "M_H_CPU1_SA_DQ<15>")
	)
	(arc
		(start 142.607792 -234.441746)
		(mid 142.794736 -234.391491)
		(end 142.98168 -234.441746)
		(width 0.0889)
		(layer "In13.Cu")
		(net "M_H_CPU1_SA_DQ<15>")
	)
	(arc
		(start 137.916158 -234.43692)
		(mid 138.099666 -234.391426)
		(end 138.281918 -234.441746)
		(width 0.0889)
		(layer "In13.Cu")
		(net "M_H_CPU1_SA_DQ<15>")
	)
	(arc
		(start 138.84783 -234.441746)
		(mid 139.034774 -234.391491)
		(end 139.221718 -234.441746)
		(width 0.0889)
		(layer "In13.Cu")
		(net "M_H_CPU1_SA_DQ<15>")
	)
	(arc
		(start 142.98168 -234.441746)
		(mid 143.264636 -234.517923)
		(end 143.547592 -234.441746)
		(width 0.0889)
		(layer "In13.Cu")
		(net "M_H_CPU1_SA_DQ<15>")
	)
	(arc
		(start 137.341864 -234.441746)
		(mid 137.62482 -234.517923)
		(end 137.907776 -234.441746)
		(width 0.0889)
		(layer "In13.Cu")
		(net "M_H_CPU1_SA_DQ<15>")
	)
	(arc
		(start 136.40181 -234.441746)
		(mid 136.684766 -234.517923)
		(end 136.967722 -234.441746)
		(width 0.0889)
		(layer "In13.Cu")
		(net "M_H_CPU1_SA_DQ<15>")
	)
	(segment
		(start 135.27786 -234.220258)
		(end 135.744712 -233.95432)
		(width 0.10668)
		(layer "F.Cu")
		(net "M_H_CPU1_SA_DQ<14>")
	)
	(segment
		(start 151.826214 -226.525582)
		(end 147.69338 -230.658416)
		(width 0.14478)
		(layer "In13.Cu")
		(net "M_H_CPU1_SA_DQ<14>")
	)
	(segment
		(start 142.51178 -233.63174)
		(end 142.503398 -233.626914)
		(width 0.0889)
		(layer "In13.Cu")
		(net "M_H_CPU1_SA_DQ<14>")
	)
	(segment
		(start 158.676848 -216.035128)
		(end 158.490666 -216.22131)
		(width 0.14478)
		(layer "In13.Cu")
		(net "M_H_CPU1_SA_DQ<14>")
	)
	(segment
		(start 165.50386 -214.512652)
		(end 165.35908 -214.367872)
		(width 0.14478)
		(layer "In13.Cu")
		(net "M_H_CPU1_SA_DQ<14>")
	)
	(segment
		(start 157.710886 -217.408506)
		(end 157.524704 -217.594688)
		(width 0.14478)
		(layer "In13.Cu")
		(net "M_H_CPU1_SA_DQ<14>")
	)
	(segment
		(start 158.304484 -216.814908)
		(end 157.897068 -216.814908)
		(width 0.14478)
		(layer "In13.Cu")
		(net "M_H_CPU1_SA_DQ<14>")
	)
	(segment
		(start 152.438608 -222.273368)
		(end 152.252426 -222.45955)
		(width 0.14478)
		(layer "In13.Cu")
		(net "M_H_CPU1_SA_DQ<14>")
	)
	(segment
		(start 157.897068 -216.814908)
		(end 157.710886 -217.00109)
		(width 0.14478)
		(layer "In13.Cu")
		(net "M_H_CPU1_SA_DQ<14>")
	)
	(segment
		(start 163.271454 -214.54999)
		(end 163.126674 -214.69477)
		(width 0.14478)
		(layer "In13.Cu")
		(net "M_H_CPU1_SA_DQ<14>")
	)
	(segment
		(start 162.313874 -213.910418)
		(end 162.169094 -214.055198)
		(width 0.14478)
		(layer "In13.Cu")
		(net "M_H_CPU1_SA_DQ<14>")
	)
	(segment
		(start 161.473134 -213.910418)
		(end 161.208974 -213.910418)
		(width 0.14478)
		(layer "In13.Cu")
		(net "M_H_CPU1_SA_DQ<14>")
	)
	(segment
		(start 162.169094 -214.54999)
		(end 162.024314 -214.69477)
		(width 0.14478)
		(layer "In13.Cu")
		(net "M_H_CPU1_SA_DQ<14>")
	)
	(segment
		(start 162.720274 -214.055198)
		(end 162.575494 -213.910418)
		(width 0.14478)
		(layer "In13.Cu")
		(net "M_H_CPU1_SA_DQ<14>")
	)
	(segment
		(start 165.91026 -214.055198)
		(end 165.91026 -214.367872)
		(width 0.14478)
		(layer "In13.Cu")
		(net "M_H_CPU1_SA_DQ<14>")
	)
	(segment
		(start 157.524704 -217.594688)
		(end 157.117288 -217.594688)
		(width 0.14478)
		(layer "In13.Cu")
		(net "M_H_CPU1_SA_DQ<14>")
	)
	(segment
		(start 153.811986 -220.89999)
		(end 153.811986 -221.307406)
		(width 0.14478)
		(layer "In13.Cu")
		(net "M_H_CPU1_SA_DQ<14>")
	)
	(segment
		(start 165.35908 -214.367872)
		(end 165.35908 -214.055198)
		(width 0.14478)
		(layer "In13.Cu")
		(net "M_H_CPU1_SA_DQ<14>")
	)
	(segment
		(start 157.117288 -217.594688)
		(end 156.931106 -217.78087)
		(width 0.14478)
		(layer "In13.Cu")
		(net "M_H_CPU1_SA_DQ<14>")
	)
	(segment
		(start 162.720274 -214.54999)
		(end 162.720274 -214.055198)
		(width 0.14478)
		(layer "In13.Cu")
		(net "M_H_CPU1_SA_DQ<14>")
	)
	(segment
		(start 157.710886 -217.00109)
		(end 157.710886 -217.408506)
		(width 0.14478)
		(layer "In13.Cu")
		(net "M_H_CPU1_SA_DQ<14>")
	)
	(segment
		(start 153.032206 -222.087186)
		(end 152.846024 -222.273368)
		(width 0.14478)
		(layer "In13.Cu")
		(net "M_H_CPU1_SA_DQ<14>")
	)
	(segment
		(start 140.266166 -233.626914)
		(end 140.257784 -233.63174)
		(width 0.0889)
		(layer "In13.Cu")
		(net "M_H_CPU1_SA_DQ<14>")
	)
	(segment
		(start 160.643824 -214.475568)
		(end 160.236408 -214.475568)
		(width 0.14478)
		(layer "In13.Cu")
		(net "M_H_CPU1_SA_DQ<14>")
	)
	(segment
		(start 161.762694 -214.69477)
		(end 161.617914 -214.54999)
		(width 0.14478)
		(layer "In13.Cu")
		(net "M_H_CPU1_SA_DQ<14>")
	)
	(segment
		(start 159.270446 -215.44153)
		(end 159.270446 -215.848946)
		(width 0.14478)
		(layer "In13.Cu")
		(net "M_H_CPU1_SA_DQ<14>")
	)
	(segment
		(start 159.084264 -216.035128)
		(end 158.676848 -216.035128)
		(width 0.14478)
		(layer "In13.Cu")
		(net "M_H_CPU1_SA_DQ<14>")
	)
	(segment
		(start 155.185364 -219.934028)
		(end 154.777948 -219.934028)
		(width 0.14478)
		(layer "In13.Cu")
		(net "M_H_CPU1_SA_DQ<14>")
	)
	(segment
		(start 153.218388 -221.493588)
		(end 153.032206 -221.67977)
		(width 0.14478)
		(layer "In13.Cu")
		(net "M_H_CPU1_SA_DQ<14>")
	)
	(segment
		(start 155.557728 -219.154248)
		(end 155.371546 -219.34043)
		(width 0.14478)
		(layer "In13.Cu")
		(net "M_H_CPU1_SA_DQ<14>")
	)
	(segment
		(start 161.617914 -214.055198)
		(end 161.473134 -213.910418)
		(width 0.14478)
		(layer "In13.Cu")
		(net "M_H_CPU1_SA_DQ<14>")
	)
	(segment
		(start 171.6786 -213.910418)
		(end 170.43908 -213.910418)
		(width 0.14478)
		(layer "In13.Cu")
		(net "M_H_CPU1_SA_DQ<14>")
	)
	(segment
		(start 146.324828 -231.665272)
		(end 146.324828 -232.188512)
		(width 0.0889)
		(layer "In13.Cu")
		(net "M_H_CPU1_SA_DQ<14>")
	)
	(segment
		(start 151.826214 -223.293178)
		(end 151.826214 -226.525582)
		(width 0.14478)
		(layer "In13.Cu")
		(net "M_H_CPU1_SA_DQ<14>")
	)
	(segment
		(start 156.151326 -218.56065)
		(end 156.151326 -218.968066)
		(width 0.14478)
		(layer "In13.Cu")
		(net "M_H_CPU1_SA_DQ<14>")
	)
	(segment
		(start 143.086074 -233.626914)
		(end 143.077692 -233.63174)
		(width 0.0889)
		(layer "In13.Cu")
		(net "M_H_CPU1_SA_DQ<14>")
	)
	(segment
		(start 171.97197 -213.485222)
		(end 171.97197 -213.617048)
		(width 0.14478)
		(layer "In13.Cu")
		(net "M_H_CPU1_SA_DQ<14>")
	)
	(segment
		(start 171.97197 -213.617048)
		(end 171.6786 -213.910418)
		(width 0.14478)
		(layer "In13.Cu")
		(net "M_H_CPU1_SA_DQ<14>")
	)
	(segment
		(start 162.024314 -214.69477)
		(end 161.762694 -214.69477)
		(width 0.14478)
		(layer "In13.Cu")
		(net "M_H_CPU1_SA_DQ<14>")
	)
	(segment
		(start 152.846024 -222.273368)
		(end 152.438608 -222.273368)
		(width 0.14478)
		(layer "In13.Cu")
		(net "M_H_CPU1_SA_DQ<14>")
	)
	(segment
		(start 146.324828 -232.188512)
		(end 145.494756 -233.018584)
		(width 0.0889)
		(layer "In13.Cu")
		(net "M_H_CPU1_SA_DQ<14>")
	)
	(segment
		(start 143.462248 -233.637836)
		(end 143.451834 -233.63174)
		(width 0.0889)
		(layer "In13.Cu")
		(net "M_H_CPU1_SA_DQ<14>")
	)
	(segment
		(start 161.617914 -214.54999)
		(end 161.617914 -214.055198)
		(width 0.14478)
		(layer "In13.Cu")
		(net "M_H_CPU1_SA_DQ<14>")
	)
	(segment
		(start 135.995156 -233.66349)
		(end 135.89889 -233.68889)
		(width 0.0889)
		(layer "In13.Cu")
		(net "M_H_CPU1_SA_DQ<14>")
	)
	(segment
		(start 153.625804 -221.493588)
		(end 153.218388 -221.493588)
		(width 0.14478)
		(layer "In13.Cu")
		(net "M_H_CPU1_SA_DQ<14>")
	)
	(segment
		(start 163.416234 -213.910418)
		(end 163.271454 -214.055198)
		(width 0.14478)
		(layer "In13.Cu")
		(net "M_H_CPU1_SA_DQ<14>")
	)
	(segment
		(start 162.575494 -213.910418)
		(end 162.313874 -213.910418)
		(width 0.14478)
		(layer "In13.Cu")
		(net "M_H_CPU1_SA_DQ<14>")
	)
	(segment
		(start 156.337508 -218.374468)
		(end 156.151326 -218.56065)
		(width 0.14478)
		(layer "In13.Cu")
		(net "M_H_CPU1_SA_DQ<14>")
	)
	(segment
		(start 166.228014 -213.910418)
		(end 166.05504 -213.910418)
		(width 0.14478)
		(layer "In13.Cu")
		(net "M_H_CPU1_SA_DQ<14>")
	)
	(segment
		(start 159.864044 -215.255348)
		(end 159.456628 -215.255348)
		(width 0.14478)
		(layer "In13.Cu")
		(net "M_H_CPU1_SA_DQ<14>")
	)
	(segment
		(start 145.494756 -233.018584)
		(end 144.655032 -233.018584)
		(width 0.0889)
		(layer "In13.Cu")
		(net "M_H_CPU1_SA_DQ<14>")
	)
	(segment
		(start 153.998168 -220.713808)
		(end 153.811986 -220.89999)
		(width 0.14478)
		(layer "In13.Cu")
		(net "M_H_CPU1_SA_DQ<14>")
	)
	(segment
		(start 160.236408 -214.475568)
		(end 160.050226 -214.66175)
		(width 0.14478)
		(layer "In13.Cu")
		(net "M_H_CPU1_SA_DQ<14>")
	)
	(segment
		(start 156.931106 -217.78087)
		(end 156.931106 -218.188286)
		(width 0.14478)
		(layer "In13.Cu")
		(net "M_H_CPU1_SA_DQ<14>")
	)
	(segment
		(start 170.43908 -213.910418)
		(end 169.588942 -213.06028)
		(width 0.14478)
		(layer "In13.Cu")
		(net "M_H_CPU1_SA_DQ<14>")
	)
	(segment
		(start 161.208974 -213.910418)
		(end 160.643824 -214.475568)
		(width 0.14478)
		(layer "In13.Cu")
		(net "M_H_CPU1_SA_DQ<14>")
	)
	(segment
		(start 167.078152 -213.06028)
		(end 166.228014 -213.910418)
		(width 0.14478)
		(layer "In13.Cu")
		(net "M_H_CPU1_SA_DQ<14>")
	)
	(segment
		(start 152.252426 -222.45955)
		(end 152.252426 -222.866966)
		(width 0.14478)
		(layer "In13.Cu")
		(net "M_H_CPU1_SA_DQ<14>")
	)
	(segment
		(start 154.591766 -220.527626)
		(end 154.405584 -220.713808)
		(width 0.14478)
		(layer "In13.Cu")
		(net "M_H_CPU1_SA_DQ<14>")
	)
	(segment
		(start 160.050226 -214.66175)
		(end 160.050226 -215.069166)
		(width 0.14478)
		(layer "In13.Cu")
		(net "M_H_CPU1_SA_DQ<14>")
	)
	(segment
		(start 146.749516 -231.240584)
		(end 146.324828 -231.665272)
		(width 0.0889)
		(layer "In13.Cu")
		(net "M_H_CPU1_SA_DQ<14>")
	)
	(segment
		(start 135.89889 -233.68889)
		(end 135.744712 -233.95432)
		(width 0.0889)
		(layer "In13.Cu")
		(net "M_H_CPU1_SA_DQ<14>")
	)
	(segment
		(start 139.326112 -233.626914)
		(end 139.31773 -233.63174)
		(width 0.0889)
		(layer "In13.Cu")
		(net "M_H_CPU1_SA_DQ<14>")
	)
	(segment
		(start 155.965144 -219.154248)
		(end 155.557728 -219.154248)
		(width 0.14478)
		(layer "In13.Cu")
		(net "M_H_CPU1_SA_DQ<14>")
	)
	(segment
		(start 144.074896 -233.59872)
		(end 144.018 -233.63174)
		(width 0.0889)
		(layer "In13.Cu")
		(net "M_H_CPU1_SA_DQ<14>")
	)
	(segment
		(start 163.126674 -214.69477)
		(end 162.865054 -214.69477)
		(width 0.14478)
		(layer "In13.Cu")
		(net "M_H_CPU1_SA_DQ<14>")
	)
	(segment
		(start 162.169094 -214.055198)
		(end 162.169094 -214.54999)
		(width 0.14478)
		(layer "In13.Cu")
		(net "M_H_CPU1_SA_DQ<14>")
	)
	(segment
		(start 165.35908 -214.055198)
		(end 165.2143 -213.910418)
		(width 0.14478)
		(layer "In13.Cu")
		(net "M_H_CPU1_SA_DQ<14>")
	)
	(segment
		(start 156.744924 -218.374468)
		(end 156.337508 -218.374468)
		(width 0.14478)
		(layer "In13.Cu")
		(net "M_H_CPU1_SA_DQ<14>")
	)
	(segment
		(start 158.490666 -216.628726)
		(end 158.304484 -216.814908)
		(width 0.14478)
		(layer "In13.Cu")
		(net "M_H_CPU1_SA_DQ<14>")
	)
	(segment
		(start 165.91026 -214.367872)
		(end 165.76548 -214.512652)
		(width 0.14478)
		(layer "In13.Cu")
		(net "M_H_CPU1_SA_DQ<14>")
	)
	(segment
		(start 160.050226 -215.069166)
		(end 159.864044 -215.255348)
		(width 0.14478)
		(layer "In13.Cu")
		(net "M_H_CPU1_SA_DQ<14>")
	)
	(segment
		(start 163.271454 -214.055198)
		(end 163.271454 -214.54999)
		(width 0.14478)
		(layer "In13.Cu")
		(net "M_H_CPU1_SA_DQ<14>")
	)
	(segment
		(start 138.751818 -233.63174)
		(end 138.743436 -233.626914)
		(width 0.0889)
		(layer "In13.Cu")
		(net "M_H_CPU1_SA_DQ<14>")
	)
	(segment
		(start 147.111212 -231.240584)
		(end 146.749516 -231.240584)
		(width 0.0889)
		(layer "In13.Cu")
		(net "M_H_CPU1_SA_DQ<14>")
	)
	(segment
		(start 147.69338 -230.658416)
		(end 147.111212 -231.240584)
		(width 0.0889)
		(layer "In13.Cu")
		(net "M_H_CPU1_SA_DQ<14>")
	)
	(segment
		(start 159.456628 -215.255348)
		(end 159.270446 -215.44153)
		(width 0.14478)
		(layer "In13.Cu")
		(net "M_H_CPU1_SA_DQ<14>")
	)
	(segment
		(start 169.588942 -213.06028)
		(end 167.078152 -213.06028)
		(width 0.14478)
		(layer "In13.Cu")
		(net "M_H_CPU1_SA_DQ<14>")
	)
	(segment
		(start 154.405584 -220.713808)
		(end 153.998168 -220.713808)
		(width 0.14478)
		(layer "In13.Cu")
		(net "M_H_CPU1_SA_DQ<14>")
	)
	(segment
		(start 152.252426 -222.866966)
		(end 151.826214 -223.293178)
		(width 0.14478)
		(layer "In13.Cu")
		(net "M_H_CPU1_SA_DQ<14>")
	)
	(segment
		(start 137.811764 -233.63174)
		(end 137.803382 -233.626914)
		(width 0.0889)
		(layer "In13.Cu")
		(net "M_H_CPU1_SA_DQ<14>")
	)
	(segment
		(start 153.811986 -221.307406)
		(end 153.625804 -221.493588)
		(width 0.14478)
		(layer "In13.Cu")
		(net "M_H_CPU1_SA_DQ<14>")
	)
	(segment
		(start 154.777948 -219.934028)
		(end 154.591766 -220.12021)
		(width 0.14478)
		(layer "In13.Cu")
		(net "M_H_CPU1_SA_DQ<14>")
	)
	(segment
		(start 155.371546 -219.747846)
		(end 155.185364 -219.934028)
		(width 0.14478)
		(layer "In13.Cu")
		(net "M_H_CPU1_SA_DQ<14>")
	)
	(segment
		(start 158.490666 -216.22131)
		(end 158.490666 -216.628726)
		(width 0.14478)
		(layer "In13.Cu")
		(net "M_H_CPU1_SA_DQ<14>")
	)
	(segment
		(start 154.591766 -220.12021)
		(end 154.591766 -220.527626)
		(width 0.14478)
		(layer "In13.Cu")
		(net "M_H_CPU1_SA_DQ<14>")
	)
	(segment
		(start 155.371546 -219.34043)
		(end 155.371546 -219.747846)
		(width 0.14478)
		(layer "In13.Cu")
		(net "M_H_CPU1_SA_DQ<14>")
	)
	(segment
		(start 159.270446 -215.848946)
		(end 159.084264 -216.035128)
		(width 0.14478)
		(layer "In13.Cu")
		(net "M_H_CPU1_SA_DQ<14>")
	)
	(segment
		(start 166.05504 -213.910418)
		(end 165.91026 -214.055198)
		(width 0.14478)
		(layer "In13.Cu")
		(net "M_H_CPU1_SA_DQ<14>")
	)
	(segment
		(start 165.76548 -214.512652)
		(end 165.50386 -214.512652)
		(width 0.14478)
		(layer "In13.Cu")
		(net "M_H_CPU1_SA_DQ<14>")
	)
	(segment
		(start 162.865054 -214.69477)
		(end 162.720274 -214.54999)
		(width 0.14478)
		(layer "In13.Cu")
		(net "M_H_CPU1_SA_DQ<14>")
	)
	(segment
		(start 144.655032 -233.018584)
		(end 144.074896 -233.59872)
		(width 0.0889)
		(layer "In13.Cu")
		(net "M_H_CPU1_SA_DQ<14>")
	)
	(segment
		(start 165.2143 -213.910418)
		(end 163.416234 -213.910418)
		(width 0.14478)
		(layer "In13.Cu")
		(net "M_H_CPU1_SA_DQ<14>")
	)
	(segment
		(start 156.151326 -218.968066)
		(end 155.965144 -219.154248)
		(width 0.14478)
		(layer "In13.Cu")
		(net "M_H_CPU1_SA_DQ<14>")
	)
	(segment
		(start 153.032206 -221.67977)
		(end 153.032206 -222.087186)
		(width 0.14478)
		(layer "In13.Cu")
		(net "M_H_CPU1_SA_DQ<14>")
	)
	(segment
		(start 156.931106 -218.188286)
		(end 156.744924 -218.374468)
		(width 0.14478)
		(layer "In13.Cu")
		(net "M_H_CPU1_SA_DQ<14>")
	)
	(arc
		(start 137.437622 -233.63174)
		(mid 137.154666 -233.707917)
		(end 136.87171 -233.63174)
		(width 0.0889)
		(layer "In13.Cu")
		(net "M_H_CPU1_SA_DQ<14>")
	)
	(arc
		(start 139.31773 -233.63174)
		(mid 139.034774 -233.707917)
		(end 138.751818 -233.63174)
		(width 0.0889)
		(layer "In13.Cu")
		(net "M_H_CPU1_SA_DQ<14>")
	)
	(arc
		(start 144.018 -233.63174)
		(mid 143.740933 -233.708011)
		(end 143.462248 -233.637836)
		(width 0.0889)
		(layer "In13.Cu")
		(net "M_H_CPU1_SA_DQ<14>")
	)
	(arc
		(start 138.377676 -233.63174)
		(mid 138.09472 -233.707917)
		(end 137.811764 -233.63174)
		(width 0.0889)
		(layer "In13.Cu")
		(net "M_H_CPU1_SA_DQ<14>")
	)
	(arc
		(start 136.87171 -233.63174)
		(mid 136.684766 -233.581485)
		(end 136.497822 -233.63174)
		(width 0.0889)
		(layer "In13.Cu")
		(net "M_H_CPU1_SA_DQ<14>")
	)
	(arc
		(start 136.497822 -233.63174)
		(mid 136.250226 -233.706918)
		(end 135.995156 -233.66349)
		(width 0.0889)
		(layer "In13.Cu")
		(net "M_H_CPU1_SA_DQ<14>")
	)
	(arc
		(start 143.077692 -233.63174)
		(mid 142.794736 -233.707917)
		(end 142.51178 -233.63174)
		(width 0.0889)
		(layer "In13.Cu")
		(net "M_H_CPU1_SA_DQ<14>")
	)
	(arc
		(start 140.631926 -233.63174)
		(mid 140.449675 -233.58139)
		(end 140.266166 -233.626914)
		(width 0.0889)
		(layer "In13.Cu")
		(net "M_H_CPU1_SA_DQ<14>")
	)
	(arc
		(start 139.691872 -233.63174)
		(mid 139.509621 -233.58139)
		(end 139.326112 -233.626914)
		(width 0.0889)
		(layer "In13.Cu")
		(net "M_H_CPU1_SA_DQ<14>")
	)
	(arc
		(start 141.571726 -233.63174)
		(mid 141.384782 -233.581485)
		(end 141.197838 -233.63174)
		(width 0.0889)
		(layer "In13.Cu")
		(net "M_H_CPU1_SA_DQ<14>")
	)
	(arc
		(start 140.257784 -233.63174)
		(mid 139.974828 -233.707917)
		(end 139.691872 -233.63174)
		(width 0.0889)
		(layer "In13.Cu")
		(net "M_H_CPU1_SA_DQ<14>")
	)
	(arc
		(start 137.803382 -233.626914)
		(mid 137.619874 -233.58142)
		(end 137.437622 -233.63174)
		(width 0.0889)
		(layer "In13.Cu")
		(net "M_H_CPU1_SA_DQ<14>")
	)
	(arc
		(start 138.743436 -233.626914)
		(mid 138.559928 -233.58142)
		(end 138.377676 -233.63174)
		(width 0.0889)
		(layer "In13.Cu")
		(net "M_H_CPU1_SA_DQ<14>")
	)
	(arc
		(start 142.503398 -233.626914)
		(mid 142.31989 -233.58142)
		(end 142.137638 -233.63174)
		(width 0.0889)
		(layer "In13.Cu")
		(net "M_H_CPU1_SA_DQ<14>")
	)
	(arc
		(start 141.197838 -233.63174)
		(mid 140.914882 -233.707917)
		(end 140.631926 -233.63174)
		(width 0.0889)
		(layer "In13.Cu")
		(net "M_H_CPU1_SA_DQ<14>")
	)
	(arc
		(start 142.137638 -233.63174)
		(mid 141.854682 -233.707917)
		(end 141.571726 -233.63174)
		(width 0.0889)
		(layer "In13.Cu")
		(net "M_H_CPU1_SA_DQ<14>")
	)
	(arc
		(start 143.451834 -233.63174)
		(mid 143.269583 -233.58139)
		(end 143.086074 -233.626914)
		(width 0.0889)
		(layer "In13.Cu")
		(net "M_H_CPU1_SA_DQ<14>")
	)
	(segment
		(start 134.337806 -234.220258)
		(end 134.804658 -233.95432)
		(width 0.10668)
		(layer "F.Cu")
		(net "M_H_CPU1_SA_DQ<13>")
	)
	(segment
		(start 173.947836 -214.905082)
		(end 173.947836 -215.002364)
		(width 0.14478)
		(layer "In13.Cu")
		(net "M_H_CPU1_SA_DQ<13>")
	)
	(segment
		(start 175.194976 -214.760302)
		(end 175.050196 -214.905082)
		(width 0.14478)
		(layer "In13.Cu")
		(net "M_H_CPU1_SA_DQ<13>")
	)
	(segment
		(start 173.541436 -215.147144)
		(end 173.396656 -215.002364)
		(width 0.14478)
		(layer "In13.Cu")
		(net "M_H_CPU1_SA_DQ<13>")
	)
	(segment
		(start 165.821614 -215.16086)
		(end 160.594548 -215.16086)
		(width 0.14478)
		(layer "In13.Cu")
		(net "M_H_CPU1_SA_DQ<13>")
	)
	(segment
		(start 147.95627 -231.114346)
		(end 147.39493 -231.675686)
		(width 0.0889)
		(layer "In13.Cu")
		(net "M_H_CPU1_SA_DQ<13>")
	)
	(segment
		(start 173.947836 -215.002364)
		(end 173.803056 -215.147144)
		(width 0.14478)
		(layer "In13.Cu")
		(net "M_H_CPU1_SA_DQ<13>")
	)
	(segment
		(start 143.466566 -234.268264)
		(end 143.451834 -234.2769)
		(width 0.0889)
		(layer "In13.Cu")
		(net "M_H_CPU1_SA_DQ<13>")
	)
	(segment
		(start 175.050196 -215.002364)
		(end 174.905416 -215.147144)
		(width 0.14478)
		(layer "In13.Cu")
		(net "M_H_CPU1_SA_DQ<13>")
	)
	(segment
		(start 152.275794 -223.479614)
		(end 152.275794 -226.794822)
		(width 0.14478)
		(layer "In13.Cu")
		(net "M_H_CPU1_SA_DQ<13>")
	)
	(segment
		(start 137.811764 -234.2769)
		(end 137.803382 -234.281726)
		(width 0.0889)
		(layer "In13.Cu")
		(net "M_H_CPU1_SA_DQ<13>")
	)
	(segment
		(start 142.51178 -234.2769)
		(end 142.503398 -234.281726)
		(width 0.0889)
		(layer "In13.Cu")
		(net "M_H_CPU1_SA_DQ<13>")
	)
	(segment
		(start 167.072056 -213.910418)
		(end 165.821614 -215.16086)
		(width 0.14478)
		(layer "In13.Cu")
		(net "M_H_CPU1_SA_DQ<13>")
	)
	(segment
		(start 134.650734 -234.21975)
		(end 134.804658 -233.95432)
		(width 0.0889)
		(layer "In13.Cu")
		(net "M_H_CPU1_SA_DQ<13>")
	)
	(segment
		(start 144.044162 -234.200446)
		(end 143.73479 -234.200446)
		(width 0.0889)
		(layer "In13.Cu")
		(net "M_H_CPU1_SA_DQ<13>")
	)
	(segment
		(start 173.396656 -215.002364)
		(end 173.396656 -214.905082)
		(width 0.14478)
		(layer "In13.Cu")
		(net "M_H_CPU1_SA_DQ<13>")
	)
	(segment
		(start 174.499016 -215.002364)
		(end 174.499016 -214.905082)
		(width 0.14478)
		(layer "In13.Cu")
		(net "M_H_CPU1_SA_DQ<13>")
	)
	(segment
		(start 147.39493 -231.675686)
		(end 147.389088 -231.675686)
		(width 0.0889)
		(layer "In13.Cu")
		(net "M_H_CPU1_SA_DQ<13>")
	)
	(segment
		(start 174.092616 -214.760302)
		(end 173.947836 -214.905082)
		(width 0.14478)
		(layer "In13.Cu")
		(net "M_H_CPU1_SA_DQ<13>")
	)
	(segment
		(start 152.275794 -226.794822)
		(end 147.95627 -231.114346)
		(width 0.14478)
		(layer "In13.Cu")
		(net "M_H_CPU1_SA_DQ<13>")
	)
	(segment
		(start 173.251876 -214.760302)
		(end 170.529504 -214.760302)
		(width 0.14478)
		(layer "In13.Cu")
		(net "M_H_CPU1_SA_DQ<13>")
	)
	(segment
		(start 175.050196 -214.905082)
		(end 175.050196 -215.002364)
		(width 0.14478)
		(layer "In13.Cu")
		(net "M_H_CPU1_SA_DQ<13>")
	)
	(segment
		(start 175.647096 -214.760302)
		(end 175.194976 -214.760302)
		(width 0.14478)
		(layer "In13.Cu")
		(net "M_H_CPU1_SA_DQ<13>")
	)
	(segment
		(start 176.072038 -214.33536)
		(end 175.647096 -214.760302)
		(width 0.14478)
		(layer "In13.Cu")
		(net "M_H_CPU1_SA_DQ<13>")
	)
	(segment
		(start 174.354236 -214.760302)
		(end 174.092616 -214.760302)
		(width 0.14478)
		(layer "In13.Cu")
		(net "M_H_CPU1_SA_DQ<13>")
	)
	(segment
		(start 174.643796 -215.147144)
		(end 174.499016 -215.002364)
		(width 0.14478)
		(layer "In13.Cu")
		(net "M_H_CPU1_SA_DQ<13>")
	)
	(segment
		(start 147.389088 -231.675686)
		(end 145.74647 -233.318304)
		(width 0.0889)
		(layer "In13.Cu")
		(net "M_H_CPU1_SA_DQ<13>")
	)
	(segment
		(start 170.529504 -214.760302)
		(end 169.67962 -213.910418)
		(width 0.14478)
		(layer "In13.Cu")
		(net "M_H_CPU1_SA_DQ<13>")
	)
	(segment
		(start 144.926304 -233.318304)
		(end 144.044162 -234.200446)
		(width 0.0889)
		(layer "In13.Cu")
		(net "M_H_CPU1_SA_DQ<13>")
	)
	(segment
		(start 174.905416 -215.147144)
		(end 174.643796 -215.147144)
		(width 0.14478)
		(layer "In13.Cu")
		(net "M_H_CPU1_SA_DQ<13>")
	)
	(segment
		(start 174.499016 -214.905082)
		(end 174.354236 -214.760302)
		(width 0.14478)
		(layer "In13.Cu")
		(net "M_H_CPU1_SA_DQ<13>")
	)
	(segment
		(start 140.266166 -234.281726)
		(end 140.257784 -234.2769)
		(width 0.0889)
		(layer "In13.Cu")
		(net "M_H_CPU1_SA_DQ<13>")
	)
	(segment
		(start 173.396656 -214.905082)
		(end 173.251876 -214.760302)
		(width 0.14478)
		(layer "In13.Cu")
		(net "M_H_CPU1_SA_DQ<13>")
	)
	(segment
		(start 145.74647 -233.318304)
		(end 144.926304 -233.318304)
		(width 0.0889)
		(layer "In13.Cu")
		(net "M_H_CPU1_SA_DQ<13>")
	)
	(segment
		(start 143.086074 -234.281726)
		(end 143.077692 -234.2769)
		(width 0.0889)
		(layer "In13.Cu")
		(net "M_H_CPU1_SA_DQ<13>")
	)
	(segment
		(start 169.67962 -213.910418)
		(end 167.072056 -213.910418)
		(width 0.14478)
		(layer "In13.Cu")
		(net "M_H_CPU1_SA_DQ<13>")
	)
	(segment
		(start 135.56615 -234.281726)
		(end 135.557768 -234.2769)
		(width 0.0889)
		(layer "In13.Cu")
		(net "M_H_CPU1_SA_DQ<13>")
	)
	(segment
		(start 173.803056 -215.147144)
		(end 173.541436 -215.147144)
		(width 0.14478)
		(layer "In13.Cu")
		(net "M_H_CPU1_SA_DQ<13>")
	)
	(segment
		(start 134.673086 -234.303062)
		(end 134.650734 -234.21975)
		(width 0.0889)
		(layer "In13.Cu")
		(net "M_H_CPU1_SA_DQ<13>")
	)
	(segment
		(start 138.751818 -234.2769)
		(end 138.743436 -234.281726)
		(width 0.0889)
		(layer "In13.Cu")
		(net "M_H_CPU1_SA_DQ<13>")
	)
	(segment
		(start 139.326112 -234.281726)
		(end 139.31773 -234.2769)
		(width 0.0889)
		(layer "In13.Cu")
		(net "M_H_CPU1_SA_DQ<13>")
	)
	(segment
		(start 160.594548 -215.16086)
		(end 152.275794 -223.479614)
		(width 0.14478)
		(layer "In13.Cu")
		(net "M_H_CPU1_SA_DQ<13>")
	)
	(arc
		(start 136.497822 -234.2769)
		(mid 136.214866 -234.200723)
		(end 135.93191 -234.2769)
		(width 0.0889)
		(layer "In13.Cu")
		(net "M_H_CPU1_SA_DQ<13>")
	)
	(arc
		(start 137.437622 -234.2769)
		(mid 137.154666 -234.200723)
		(end 136.87171 -234.2769)
		(width 0.0889)
		(layer "In13.Cu")
		(net "M_H_CPU1_SA_DQ<13>")
	)
	(arc
		(start 138.743436 -234.281726)
		(mid 138.559928 -234.32722)
		(end 138.377676 -234.2769)
		(width 0.0889)
		(layer "In13.Cu")
		(net "M_H_CPU1_SA_DQ<13>")
	)
	(arc
		(start 141.197838 -234.2769)
		(mid 140.914882 -234.200723)
		(end 140.631926 -234.2769)
		(width 0.0889)
		(layer "In13.Cu")
		(net "M_H_CPU1_SA_DQ<13>")
	)
	(arc
		(start 143.451834 -234.2769)
		(mid 143.269583 -234.32725)
		(end 143.086074 -234.281726)
		(width 0.0889)
		(layer "In13.Cu")
		(net "M_H_CPU1_SA_DQ<13>")
	)
	(arc
		(start 143.077692 -234.2769)
		(mid 142.794736 -234.200723)
		(end 142.51178 -234.2769)
		(width 0.0889)
		(layer "In13.Cu")
		(net "M_H_CPU1_SA_DQ<13>")
	)
	(arc
		(start 143.73479 -234.200446)
		(mid 143.596464 -234.217676)
		(end 143.466566 -234.268264)
		(width 0.0889)
		(layer "In13.Cu")
		(net "M_H_CPU1_SA_DQ<13>")
	)
	(arc
		(start 139.31773 -234.2769)
		(mid 139.034774 -234.200723)
		(end 138.751818 -234.2769)
		(width 0.0889)
		(layer "In13.Cu")
		(net "M_H_CPU1_SA_DQ<13>")
	)
	(arc
		(start 142.137638 -234.2769)
		(mid 141.854682 -234.200723)
		(end 141.571726 -234.2769)
		(width 0.0889)
		(layer "In13.Cu")
		(net "M_H_CPU1_SA_DQ<13>")
	)
	(arc
		(start 140.631926 -234.2769)
		(mid 140.449675 -234.32725)
		(end 140.266166 -234.281726)
		(width 0.0889)
		(layer "In13.Cu")
		(net "M_H_CPU1_SA_DQ<13>")
	)
	(arc
		(start 136.87171 -234.2769)
		(mid 136.684766 -234.327155)
		(end 136.497822 -234.2769)
		(width 0.0889)
		(layer "In13.Cu")
		(net "M_H_CPU1_SA_DQ<13>")
	)
	(arc
		(start 135.557768 -234.2769)
		(mid 135.274812 -234.200723)
		(end 134.991856 -234.2769)
		(width 0.0889)
		(layer "In13.Cu")
		(net "M_H_CPU1_SA_DQ<13>")
	)
	(arc
		(start 142.503398 -234.281726)
		(mid 142.31989 -234.32722)
		(end 142.137638 -234.2769)
		(width 0.0889)
		(layer "In13.Cu")
		(net "M_H_CPU1_SA_DQ<13>")
	)
	(arc
		(start 138.377676 -234.2769)
		(mid 138.09472 -234.200723)
		(end 137.811764 -234.2769)
		(width 0.0889)
		(layer "In13.Cu")
		(net "M_H_CPU1_SA_DQ<13>")
	)
	(arc
		(start 134.991856 -234.2769)
		(mid 134.835418 -234.325871)
		(end 134.673086 -234.303062)
		(width 0.0889)
		(layer "In13.Cu")
		(net "M_H_CPU1_SA_DQ<13>")
	)
	(arc
		(start 137.803382 -234.281726)
		(mid 137.619874 -234.32722)
		(end 137.437622 -234.2769)
		(width 0.0889)
		(layer "In13.Cu")
		(net "M_H_CPU1_SA_DQ<13>")
	)
	(arc
		(start 140.257784 -234.2769)
		(mid 139.974828 -234.200723)
		(end 139.691872 -234.2769)
		(width 0.0889)
		(layer "In13.Cu")
		(net "M_H_CPU1_SA_DQ<13>")
	)
	(arc
		(start 141.571726 -234.2769)
		(mid 141.384782 -234.327155)
		(end 141.197838 -234.2769)
		(width 0.0889)
		(layer "In13.Cu")
		(net "M_H_CPU1_SA_DQ<13>")
	)
	(arc
		(start 135.93191 -234.2769)
		(mid 135.749659 -234.32725)
		(end 135.56615 -234.281726)
		(width 0.0889)
		(layer "In13.Cu")
		(net "M_H_CPU1_SA_DQ<13>")
	)
	(arc
		(start 139.691872 -234.2769)
		(mid 139.509621 -234.32725)
		(end 139.326112 -234.281726)
		(width 0.0889)
		(layer "In13.Cu")
		(net "M_H_CPU1_SA_DQ<13>")
	)
	(segment
		(start 135.748014 -233.410252)
		(end 136.214866 -233.144314)
		(width 0.10668)
		(layer "F.Cu")
		(net "M_H_CPU1_SA_DQ<12>")
	)
	(segment
		(start 173.685962 -213.30412)
		(end 173.685962 -213.214712)
		(width 0.14478)
		(layer "In13.Cu")
		(net "M_H_CPU1_SA_DQ<12>")
	)
	(segment
		(start 169.546016 -212.210396)
		(end 167.18026 -212.210396)
		(width 0.14478)
		(layer "In13.Cu")
		(net "M_H_CPU1_SA_DQ<12>")
	)
	(segment
		(start 172.728382 -213.4489)
		(end 172.583602 -213.30412)
		(width 0.14478)
		(layer "In13.Cu")
		(net "M_H_CPU1_SA_DQ<12>")
	)
	(segment
		(start 147.245578 -230.368094)
		(end 146.050508 -231.563164)
		(width 0.0889)
		(layer "In13.Cu")
		(net "M_H_CPU1_SA_DQ<12>")
	)
	(segment
		(start 174.933102 -213.4489)
		(end 174.788322 -213.30412)
		(width 0.14478)
		(layer "In13.Cu")
		(net "M_H_CPU1_SA_DQ<12>")
	)
	(segment
		(start 174.092362 -213.4489)
		(end 173.830742 -213.4489)
		(width 0.14478)
		(layer "In13.Cu")
		(net "M_H_CPU1_SA_DQ<12>")
	)
	(segment
		(start 175.339502 -213.214712)
		(end 175.339502 -213.30412)
		(width 0.14478)
		(layer "In13.Cu")
		(net "M_H_CPU1_SA_DQ<12>")
	)
	(segment
		(start 140.161772 -233.466894)
		(end 140.15339 -233.47172)
		(width 0.0889)
		(layer "In13.Cu")
		(net "M_H_CPU1_SA_DQ<12>")
	)
	(segment
		(start 174.237142 -213.30412)
		(end 174.092362 -213.4489)
		(width 0.14478)
		(layer "In13.Cu")
		(net "M_H_CPU1_SA_DQ<12>")
	)
	(segment
		(start 174.643542 -213.069932)
		(end 174.381922 -213.069932)
		(width 0.14478)
		(layer "In13.Cu")
		(net "M_H_CPU1_SA_DQ<12>")
	)
	(segment
		(start 151.376634 -226.237038)
		(end 147.245578 -230.368094)
		(width 0.14478)
		(layer "In13.Cu")
		(net "M_H_CPU1_SA_DQ<12>")
	)
	(segment
		(start 151.376634 -222.699326)
		(end 151.376634 -226.237038)
		(width 0.14478)
		(layer "In13.Cu")
		(net "M_H_CPU1_SA_DQ<12>")
	)
	(segment
		(start 145.367248 -232.736644)
		(end 144.652492 -232.736644)
		(width 0.0889)
		(layer "In13.Cu")
		(net "M_H_CPU1_SA_DQ<12>")
	)
	(segment
		(start 172.583602 -213.30412)
		(end 172.583602 -213.214712)
		(width 0.14478)
		(layer "In13.Cu")
		(net "M_H_CPU1_SA_DQ<12>")
	)
	(segment
		(start 172.438822 -213.069932)
		(end 170.405552 -213.069932)
		(width 0.14478)
		(layer "In13.Cu")
		(net "M_H_CPU1_SA_DQ<12>")
	)
	(segment
		(start 141.101826 -233.466894)
		(end 141.093444 -233.47172)
		(width 0.0889)
		(layer "In13.Cu")
		(net "M_H_CPU1_SA_DQ<12>")
	)
	(segment
		(start 137.916158 -233.47172)
		(end 137.907776 -233.466894)
		(width 0.0889)
		(layer "In13.Cu")
		(net "M_H_CPU1_SA_DQ<12>")
	)
	(segment
		(start 173.830742 -213.4489)
		(end 173.685962 -213.30412)
		(width 0.14478)
		(layer "In13.Cu")
		(net "M_H_CPU1_SA_DQ<12>")
	)
	(segment
		(start 146.050508 -232.053384)
		(end 145.367248 -232.736644)
		(width 0.0889)
		(layer "In13.Cu")
		(net "M_H_CPU1_SA_DQ<12>")
	)
	(segment
		(start 174.381922 -213.069932)
		(end 174.237142 -213.214712)
		(width 0.14478)
		(layer "In13.Cu")
		(net "M_H_CPU1_SA_DQ<12>")
	)
	(segment
		(start 174.788322 -213.30412)
		(end 174.788322 -213.214712)
		(width 0.14478)
		(layer "In13.Cu")
		(net "M_H_CPU1_SA_DQ<12>")
	)
	(segment
		(start 146.050508 -231.563164)
		(end 146.050508 -232.053384)
		(width 0.0889)
		(layer "In13.Cu")
		(net "M_H_CPU1_SA_DQ<12>")
	)
	(segment
		(start 173.134782 -213.30412)
		(end 172.990002 -213.4489)
		(width 0.14478)
		(layer "In13.Cu")
		(net "M_H_CPU1_SA_DQ<12>")
	)
	(segment
		(start 174.237142 -213.214712)
		(end 174.237142 -213.30412)
		(width 0.14478)
		(layer "In13.Cu")
		(net "M_H_CPU1_SA_DQ<12>")
	)
	(segment
		(start 144.652492 -232.736644)
		(end 143.922242 -233.466894)
		(width 0.0889)
		(layer "In13.Cu")
		(net "M_H_CPU1_SA_DQ<12>")
	)
	(segment
		(start 173.279562 -213.069932)
		(end 173.134782 -213.214712)
		(width 0.14478)
		(layer "In13.Cu")
		(net "M_H_CPU1_SA_DQ<12>")
	)
	(segment
		(start 141.67612 -233.47172)
		(end 141.667738 -233.466894)
		(width 0.0889)
		(layer "In13.Cu")
		(net "M_H_CPU1_SA_DQ<12>")
	)
	(segment
		(start 172.583602 -213.214712)
		(end 172.438822 -213.069932)
		(width 0.14478)
		(layer "In13.Cu")
		(net "M_H_CPU1_SA_DQ<12>")
	)
	(segment
		(start 160.615122 -213.460838)
		(end 151.376634 -222.699326)
		(width 0.14478)
		(layer "In13.Cu")
		(net "M_H_CPU1_SA_DQ<12>")
	)
	(segment
		(start 174.788322 -213.214712)
		(end 174.643542 -213.069932)
		(width 0.14478)
		(layer "In13.Cu")
		(net "M_H_CPU1_SA_DQ<12>")
	)
	(segment
		(start 165.929818 -213.460838)
		(end 160.615122 -213.460838)
		(width 0.14478)
		(layer "In13.Cu")
		(net "M_H_CPU1_SA_DQ<12>")
	)
	(segment
		(start 175.194722 -213.4489)
		(end 174.933102 -213.4489)
		(width 0.14478)
		(layer "In13.Cu")
		(net "M_H_CPU1_SA_DQ<12>")
	)
	(segment
		(start 136.40181 -233.466894)
		(end 136.393428 -233.47172)
		(width 0.0889)
		(layer "In13.Cu")
		(net "M_H_CPU1_SA_DQ<12>")
	)
	(segment
		(start 136.060688 -233.409744)
		(end 136.214866 -233.144314)
		(width 0.0889)
		(layer "In13.Cu")
		(net "M_H_CPU1_SA_DQ<12>")
	)
	(segment
		(start 176.072038 -212.635338)
		(end 175.637444 -213.069932)
		(width 0.14478)
		(layer "In13.Cu")
		(net "M_H_CPU1_SA_DQ<12>")
	)
	(segment
		(start 173.685962 -213.214712)
		(end 173.541182 -213.069932)
		(width 0.14478)
		(layer "In13.Cu")
		(net "M_H_CPU1_SA_DQ<12>")
	)
	(segment
		(start 173.541182 -213.069932)
		(end 173.279562 -213.069932)
		(width 0.14478)
		(layer "In13.Cu")
		(net "M_H_CPU1_SA_DQ<12>")
	)
	(segment
		(start 173.134782 -213.214712)
		(end 173.134782 -213.30412)
		(width 0.14478)
		(layer "In13.Cu")
		(net "M_H_CPU1_SA_DQ<12>")
	)
	(segment
		(start 175.484282 -213.069932)
		(end 175.339502 -213.214712)
		(width 0.14478)
		(layer "In13.Cu")
		(net "M_H_CPU1_SA_DQ<12>")
	)
	(segment
		(start 143.555974 -233.47172)
		(end 143.547592 -233.466894)
		(width 0.0889)
		(layer "In13.Cu")
		(net "M_H_CPU1_SA_DQ<12>")
	)
	(segment
		(start 170.405552 -213.069932)
		(end 169.546016 -212.210396)
		(width 0.14478)
		(layer "In13.Cu")
		(net "M_H_CPU1_SA_DQ<12>")
	)
	(segment
		(start 175.637444 -213.069932)
		(end 175.484282 -213.069932)
		(width 0.14478)
		(layer "In13.Cu")
		(net "M_H_CPU1_SA_DQ<12>")
	)
	(segment
		(start 136.08304 -233.493056)
		(end 136.060688 -233.409744)
		(width 0.0889)
		(layer "In13.Cu")
		(net "M_H_CPU1_SA_DQ<12>")
	)
	(segment
		(start 167.18026 -212.210396)
		(end 165.929818 -213.460838)
		(width 0.14478)
		(layer "In13.Cu")
		(net "M_H_CPU1_SA_DQ<12>")
	)
	(segment
		(start 136.976104 -233.47172)
		(end 136.967722 -233.466894)
		(width 0.0889)
		(layer "In13.Cu")
		(net "M_H_CPU1_SA_DQ<12>")
	)
	(segment
		(start 172.990002 -213.4489)
		(end 172.728382 -213.4489)
		(width 0.14478)
		(layer "In13.Cu")
		(net "M_H_CPU1_SA_DQ<12>")
	)
	(segment
		(start 175.339502 -213.30412)
		(end 175.194722 -213.4489)
		(width 0.14478)
		(layer "In13.Cu")
		(net "M_H_CPU1_SA_DQ<12>")
	)
	(arc
		(start 143.547592 -233.466894)
		(mid 143.264636 -233.390717)
		(end 142.98168 -233.466894)
		(width 0.0889)
		(layer "In13.Cu")
		(net "M_H_CPU1_SA_DQ<12>")
	)
	(arc
		(start 142.04188 -233.466894)
		(mid 141.859629 -233.517244)
		(end 141.67612 -233.47172)
		(width 0.0889)
		(layer "In13.Cu")
		(net "M_H_CPU1_SA_DQ<12>")
	)
	(arc
		(start 140.15339 -233.47172)
		(mid 139.969882 -233.517214)
		(end 139.78763 -233.466894)
		(width 0.0889)
		(layer "In13.Cu")
		(net "M_H_CPU1_SA_DQ<12>")
	)
	(arc
		(start 137.341864 -233.466894)
		(mid 137.159613 -233.517244)
		(end 136.976104 -233.47172)
		(width 0.0889)
		(layer "In13.Cu")
		(net "M_H_CPU1_SA_DQ<12>")
	)
	(arc
		(start 139.221718 -233.466894)
		(mid 139.034774 -233.517149)
		(end 138.84783 -233.466894)
		(width 0.0889)
		(layer "In13.Cu")
		(net "M_H_CPU1_SA_DQ<12>")
	)
	(arc
		(start 136.393428 -233.47172)
		(mid 136.240558 -233.516361)
		(end 136.08304 -233.493056)
		(width 0.0889)
		(layer "In13.Cu")
		(net "M_H_CPU1_SA_DQ<12>")
	)
	(arc
		(start 139.78763 -233.466894)
		(mid 139.504674 -233.390717)
		(end 139.221718 -233.466894)
		(width 0.0889)
		(layer "In13.Cu")
		(net "M_H_CPU1_SA_DQ<12>")
	)
	(arc
		(start 141.093444 -233.47172)
		(mid 140.909936 -233.517214)
		(end 140.727684 -233.466894)
		(width 0.0889)
		(layer "In13.Cu")
		(net "M_H_CPU1_SA_DQ<12>")
	)
	(arc
		(start 138.84783 -233.466894)
		(mid 138.564874 -233.390717)
		(end 138.281918 -233.466894)
		(width 0.0889)
		(layer "In13.Cu")
		(net "M_H_CPU1_SA_DQ<12>")
	)
	(arc
		(start 142.98168 -233.466894)
		(mid 142.794736 -233.517149)
		(end 142.607792 -233.466894)
		(width 0.0889)
		(layer "In13.Cu")
		(net "M_H_CPU1_SA_DQ<12>")
	)
	(arc
		(start 143.922242 -233.466894)
		(mid 143.739737 -233.517371)
		(end 143.555974 -233.47172)
		(width 0.0889)
		(layer "In13.Cu")
		(net "M_H_CPU1_SA_DQ<12>")
	)
	(arc
		(start 137.907776 -233.466894)
		(mid 137.62482 -233.390717)
		(end 137.341864 -233.466894)
		(width 0.0889)
		(layer "In13.Cu")
		(net "M_H_CPU1_SA_DQ<12>")
	)
	(arc
		(start 141.667738 -233.466894)
		(mid 141.384782 -233.390717)
		(end 141.101826 -233.466894)
		(width 0.0889)
		(layer "In13.Cu")
		(net "M_H_CPU1_SA_DQ<12>")
	)
	(arc
		(start 140.727684 -233.466894)
		(mid 140.444728 -233.390717)
		(end 140.161772 -233.466894)
		(width 0.0889)
		(layer "In13.Cu")
		(net "M_H_CPU1_SA_DQ<12>")
	)
	(arc
		(start 142.607792 -233.466894)
		(mid 142.324836 -233.390717)
		(end 142.04188 -233.466894)
		(width 0.0889)
		(layer "In13.Cu")
		(net "M_H_CPU1_SA_DQ<12>")
	)
	(arc
		(start 136.967722 -233.466894)
		(mid 136.684766 -233.390717)
		(end 136.40181 -233.466894)
		(width 0.0889)
		(layer "In13.Cu")
		(net "M_H_CPU1_SA_DQ<12>")
	)
	(arc
		(start 138.281918 -233.466894)
		(mid 138.099667 -233.517244)
		(end 137.916158 -233.47172)
		(width 0.0889)
		(layer "In13.Cu")
		(net "M_H_CPU1_SA_DQ<12>")
	)
	(segment
		(start 133.867906 -231.79024)
		(end 134.334758 -231.524302)
		(width 0.10668)
		(layer "F.Cu")
		(net "M_H_CPU1_SA_DQ<11>")
	)
	(segment
		(start 150.13559 -219.864178)
		(end 150.320756 -219.679012)
		(width 0.14478)
		(layer "In13.Cu")
		(net "M_H_CPU1_SA_DQ<11>")
	)
	(segment
		(start 153.71445 -216.629742)
		(end 153.919174 -216.629742)
		(width 0.14478)
		(layer "In13.Cu")
		(net "M_H_CPU1_SA_DQ<11>")
	)
	(segment
		(start 151.30526 -218.899232)
		(end 151.37511 -218.969082)
		(width 0.14478)
		(layer "In13.Cu")
		(net "M_H_CPU1_SA_DQ<11>")
	)
	(segment
		(start 171.55668 -209.650584)
		(end 171.97197 -209.235294)
		(width 0.14478)
		(layer "In13.Cu")
		(net "M_H_CPU1_SA_DQ<11>")
	)
	(segment
		(start 143.547592 -231.201976)
		(end 143.586708 -231.179116)
		(width 0.0889)
		(layer "In13.Cu")
		(net "M_H_CPU1_SA_DQ<11>")
	)
	(segment
		(start 161.288984 -209.259932)
		(end 166.466266 -209.259932)
		(width 0.14478)
		(layer "In13.Cu")
		(net "M_H_CPU1_SA_DQ<11>")
	)
	(segment
		(start 151.765 -218.579192)
		(end 151.69515 -218.509342)
		(width 0.14478)
		(layer "In13.Cu")
		(net "M_H_CPU1_SA_DQ<11>")
	)
	(segment
		(start 166.915846 -208.810352)
		(end 170.199812 -208.810352)
		(width 0.14478)
		(layer "In13.Cu")
		(net "M_H_CPU1_SA_DQ<11>")
	)
	(segment
		(start 141.667738 -231.201976)
		(end 141.67612 -231.19715)
		(width 0.0889)
		(layer "In13.Cu")
		(net "M_H_CPU1_SA_DQ<11>")
	)
	(segment
		(start 149.7457 -220.458792)
		(end 149.81555 -220.528642)
		(width 0.14478)
		(layer "In13.Cu")
		(net "M_H_CPU1_SA_DQ<11>")
	)
	(segment
		(start 152.47493 -217.524838)
		(end 152.660096 -217.339672)
		(width 0.14478)
		(layer "In13.Cu")
		(net "M_H_CPU1_SA_DQ<11>")
	)
	(segment
		(start 155.478734 -215.070182)
		(end 161.288984 -209.259932)
		(width 0.14478)
		(layer "In13.Cu")
		(net "M_H_CPU1_SA_DQ<11>")
	)
	(segment
		(start 153.32456 -217.019632)
		(end 153.25471 -216.949782)
		(width 0.14478)
		(layer "In13.Cu")
		(net "M_H_CPU1_SA_DQ<11>")
	)
	(segment
		(start 154.42438 -215.780112)
		(end 154.49423 -215.849962)
		(width 0.14478)
		(layer "In13.Cu")
		(net "M_H_CPU1_SA_DQ<11>")
	)
	(segment
		(start 149.35581 -220.848682)
		(end 149.35581 -220.643958)
		(width 0.14478)
		(layer "In13.Cu")
		(net "M_H_CPU1_SA_DQ<11>")
	)
	(segment
		(start 143.98498 -230.41102)
		(end 144.39265 -230.182166)
		(width 0.0889)
		(layer "In13.Cu")
		(net "M_H_CPU1_SA_DQ<11>")
	)
	(segment
		(start 154.03449 -215.965278)
		(end 154.219656 -215.780112)
		(width 0.14478)
		(layer "In13.Cu")
		(net "M_H_CPU1_SA_DQ<11>")
	)
	(segment
		(start 152.47493 -217.729562)
		(end 152.47493 -217.524838)
		(width 0.14478)
		(layer "In13.Cu")
		(net "M_H_CPU1_SA_DQ<11>")
	)
	(segment
		(start 145.63471 -229.136702)
		(end 145.63471 -228.52634)
		(width 0.0889)
		(layer "In13.Cu")
		(net "M_H_CPU1_SA_DQ<11>")
	)
	(segment
		(start 145.63471 -228.52634)
		(end 147.586192 -226.574858)
		(width 0.0889)
		(layer "In13.Cu")
		(net "M_H_CPU1_SA_DQ<11>")
	)
	(segment
		(start 155.20416 -215.000332)
		(end 155.27401 -215.070182)
		(width 0.14478)
		(layer "In13.Cu")
		(net "M_H_CPU1_SA_DQ<11>")
	)
	(segment
		(start 152.15489 -218.189302)
		(end 152.359614 -218.189302)
		(width 0.14478)
		(layer "In13.Cu")
		(net "M_H_CPU1_SA_DQ<11>")
	)
	(segment
		(start 150.800054 -219.748862)
		(end 150.98522 -219.563696)
		(width 0.14478)
		(layer "In13.Cu")
		(net "M_H_CPU1_SA_DQ<11>")
	)
	(segment
		(start 153.919174 -216.629742)
		(end 154.10434 -216.444576)
		(width 0.14478)
		(layer "In13.Cu")
		(net "M_H_CPU1_SA_DQ<11>")
	)
	(segment
		(start 150.13559 -220.068902)
		(end 150.13559 -219.864178)
		(width 0.14478)
		(layer "In13.Cu")
		(net "M_H_CPU1_SA_DQ<11>")
	)
	(segment
		(start 150.98522 -219.563696)
		(end 150.98522 -219.358972)
		(width 0.14478)
		(layer "In13.Cu")
		(net "M_H_CPU1_SA_DQ<11>")
	)
	(segment
		(start 144.769332 -229.805484)
		(end 144.965928 -229.805484)
		(width 0.0889)
		(layer "In13.Cu")
		(net "M_H_CPU1_SA_DQ<11>")
	)
	(segment
		(start 151.37511 -218.969082)
		(end 151.579834 -218.969082)
		(width 0.14478)
		(layer "In13.Cu")
		(net "M_H_CPU1_SA_DQ<11>")
	)
	(segment
		(start 149.540976 -220.458792)
		(end 149.7457 -220.458792)
		(width 0.14478)
		(layer "In13.Cu")
		(net "M_H_CPU1_SA_DQ<11>")
	)
	(segment
		(start 154.999436 -215.000332)
		(end 155.20416 -215.000332)
		(width 0.14478)
		(layer "In13.Cu")
		(net "M_H_CPU1_SA_DQ<11>")
	)
	(segment
		(start 152.08504 -218.119452)
		(end 152.15489 -218.189302)
		(width 0.14478)
		(layer "In13.Cu")
		(net "M_H_CPU1_SA_DQ<11>")
	)
	(segment
		(start 140.15339 -231.19715)
		(end 140.161772 -231.201976)
		(width 0.0889)
		(layer "In13.Cu")
		(net "M_H_CPU1_SA_DQ<11>")
	)
	(segment
		(start 149.42566 -220.918532)
		(end 149.35581 -220.848682)
		(width 0.14478)
		(layer "In13.Cu")
		(net "M_H_CPU1_SA_DQ<11>")
	)
	(segment
		(start 150.20544 -220.343476)
		(end 150.20544 -220.138752)
		(width 0.14478)
		(layer "In13.Cu")
		(net "M_H_CPU1_SA_DQ<11>")
	)
	(segment
		(start 153.25471 -216.745058)
		(end 153.439876 -216.559892)
		(width 0.14478)
		(layer "In13.Cu")
		(net "M_H_CPU1_SA_DQ<11>")
	)
	(segment
		(start 152.660096 -217.339672)
		(end 152.86482 -217.339672)
		(width 0.14478)
		(layer "In13.Cu")
		(net "M_H_CPU1_SA_DQ<11>")
	)
	(segment
		(start 151.69515 -218.304618)
		(end 151.880316 -218.119452)
		(width 0.14478)
		(layer "In13.Cu")
		(net "M_H_CPU1_SA_DQ<11>")
	)
	(segment
		(start 144.965928 -229.805484)
		(end 145.63471 -229.136702)
		(width 0.0889)
		(layer "In13.Cu")
		(net "M_H_CPU1_SA_DQ<11>")
	)
	(segment
		(start 150.91537 -219.289122)
		(end 150.91537 -219.084398)
		(width 0.14478)
		(layer "In13.Cu")
		(net "M_H_CPU1_SA_DQ<11>")
	)
	(segment
		(start 144.39265 -230.182166)
		(end 144.769332 -229.805484)
		(width 0.0889)
		(layer "In13.Cu")
		(net "M_H_CPU1_SA_DQ<11>")
	)
	(segment
		(start 136.393428 -231.19715)
		(end 136.40181 -231.201976)
		(width 0.0889)
		(layer "In13.Cu")
		(net "M_H_CPU1_SA_DQ<11>")
	)
	(segment
		(start 154.698954 -215.849962)
		(end 154.88412 -215.664796)
		(width 0.14478)
		(layer "In13.Cu")
		(net "M_H_CPU1_SA_DQ<11>")
	)
	(segment
		(start 153.6446 -216.559892)
		(end 153.71445 -216.629742)
		(width 0.14478)
		(layer "In13.Cu")
		(net "M_H_CPU1_SA_DQ<11>")
	)
	(segment
		(start 150.020274 -220.528642)
		(end 150.20544 -220.343476)
		(width 0.14478)
		(layer "In13.Cu")
		(net "M_H_CPU1_SA_DQ<11>")
	)
	(segment
		(start 134.334758 -231.524302)
		(end 134.488682 -231.258872)
		(width 0.0889)
		(layer "In13.Cu")
		(net "M_H_CPU1_SA_DQ<11>")
	)
	(segment
		(start 137.907776 -231.201976)
		(end 137.916158 -231.19715)
		(width 0.0889)
		(layer "In13.Cu")
		(net "M_H_CPU1_SA_DQ<11>")
	)
	(segment
		(start 141.093444 -231.19715)
		(end 141.101826 -231.201976)
		(width 0.0889)
		(layer "In13.Cu")
		(net "M_H_CPU1_SA_DQ<11>")
	)
	(segment
		(start 152.86482 -217.339672)
		(end 152.93467 -217.409522)
		(width 0.14478)
		(layer "In13.Cu")
		(net "M_H_CPU1_SA_DQ<11>")
	)
	(segment
		(start 151.579834 -218.969082)
		(end 151.765 -218.783916)
		(width 0.14478)
		(layer "In13.Cu")
		(net "M_H_CPU1_SA_DQ<11>")
	)
	(segment
		(start 150.52548 -219.679012)
		(end 150.59533 -219.748862)
		(width 0.14478)
		(layer "In13.Cu")
		(net "M_H_CPU1_SA_DQ<11>")
	)
	(segment
		(start 153.139394 -217.409522)
		(end 153.32456 -217.224356)
		(width 0.14478)
		(layer "In13.Cu")
		(net "M_H_CPU1_SA_DQ<11>")
	)
	(segment
		(start 149.35581 -220.643958)
		(end 149.540976 -220.458792)
		(width 0.14478)
		(layer "In13.Cu")
		(net "M_H_CPU1_SA_DQ<11>")
	)
	(segment
		(start 151.765 -218.783916)
		(end 151.765 -218.579192)
		(width 0.14478)
		(layer "In13.Cu")
		(net "M_H_CPU1_SA_DQ<11>")
	)
	(segment
		(start 151.69515 -218.509342)
		(end 151.69515 -218.304618)
		(width 0.14478)
		(layer "In13.Cu")
		(net "M_H_CPU1_SA_DQ<11>")
	)
	(segment
		(start 154.10434 -216.444576)
		(end 154.10434 -216.239852)
		(width 0.14478)
		(layer "In13.Cu")
		(net "M_H_CPU1_SA_DQ<11>")
	)
	(segment
		(start 154.219656 -215.780112)
		(end 154.42438 -215.780112)
		(width 0.14478)
		(layer "In13.Cu")
		(net "M_H_CPU1_SA_DQ<11>")
	)
	(segment
		(start 154.81427 -215.390222)
		(end 154.81427 -215.185498)
		(width 0.14478)
		(layer "In13.Cu")
		(net "M_H_CPU1_SA_DQ<11>")
	)
	(segment
		(start 136.967722 -231.201976)
		(end 136.976104 -231.19715)
		(width 0.0889)
		(layer "In13.Cu")
		(net "M_H_CPU1_SA_DQ<11>")
	)
	(segment
		(start 153.25471 -216.949782)
		(end 153.25471 -216.745058)
		(width 0.14478)
		(layer "In13.Cu")
		(net "M_H_CPU1_SA_DQ<11>")
	)
	(segment
		(start 150.20544 -220.138752)
		(end 150.13559 -220.068902)
		(width 0.14478)
		(layer "In13.Cu")
		(net "M_H_CPU1_SA_DQ<11>")
	)
	(segment
		(start 150.320756 -219.679012)
		(end 150.52548 -219.679012)
		(width 0.14478)
		(layer "In13.Cu")
		(net "M_H_CPU1_SA_DQ<11>")
	)
	(segment
		(start 151.100536 -218.899232)
		(end 151.30526 -218.899232)
		(width 0.14478)
		(layer "In13.Cu")
		(net "M_H_CPU1_SA_DQ<11>")
	)
	(segment
		(start 152.93467 -217.409522)
		(end 153.139394 -217.409522)
		(width 0.14478)
		(layer "In13.Cu")
		(net "M_H_CPU1_SA_DQ<11>")
	)
	(segment
		(start 153.439876 -216.559892)
		(end 153.6446 -216.559892)
		(width 0.14478)
		(layer "In13.Cu")
		(net "M_H_CPU1_SA_DQ<11>")
	)
	(segment
		(start 149.42566 -221.123256)
		(end 149.42566 -220.918532)
		(width 0.14478)
		(layer "In13.Cu")
		(net "M_H_CPU1_SA_DQ<11>")
	)
	(segment
		(start 149.088094 -221.460822)
		(end 149.42566 -221.123256)
		(width 0.14478)
		(layer "In13.Cu")
		(net "M_H_CPU1_SA_DQ<11>")
	)
	(segment
		(start 147.586192 -226.574858)
		(end 149.088094 -225.072956)
		(width 0.14478)
		(layer "In13.Cu")
		(net "M_H_CPU1_SA_DQ<11>")
	)
	(segment
		(start 154.81427 -215.185498)
		(end 154.999436 -215.000332)
		(width 0.14478)
		(layer "In13.Cu")
		(net "M_H_CPU1_SA_DQ<11>")
	)
	(segment
		(start 152.359614 -218.189302)
		(end 152.54478 -218.004136)
		(width 0.14478)
		(layer "In13.Cu")
		(net "M_H_CPU1_SA_DQ<11>")
	)
	(segment
		(start 154.49423 -215.849962)
		(end 154.698954 -215.849962)
		(width 0.14478)
		(layer "In13.Cu")
		(net "M_H_CPU1_SA_DQ<11>")
	)
	(segment
		(start 150.98522 -219.358972)
		(end 150.91537 -219.289122)
		(width 0.14478)
		(layer "In13.Cu")
		(net "M_H_CPU1_SA_DQ<11>")
	)
	(segment
		(start 166.466266 -209.259932)
		(end 166.915846 -208.810352)
		(width 0.14478)
		(layer "In13.Cu")
		(net "M_H_CPU1_SA_DQ<11>")
	)
	(segment
		(start 154.10434 -216.239852)
		(end 154.03449 -216.170002)
		(width 0.14478)
		(layer "In13.Cu")
		(net "M_H_CPU1_SA_DQ<11>")
	)
	(segment
		(start 152.54478 -217.799412)
		(end 152.47493 -217.729562)
		(width 0.14478)
		(layer "In13.Cu")
		(net "M_H_CPU1_SA_DQ<11>")
	)
	(segment
		(start 154.88412 -215.460072)
		(end 154.81427 -215.390222)
		(width 0.14478)
		(layer "In13.Cu")
		(net "M_H_CPU1_SA_DQ<11>")
	)
	(segment
		(start 154.03449 -216.170002)
		(end 154.03449 -215.965278)
		(width 0.14478)
		(layer "In13.Cu")
		(net "M_H_CPU1_SA_DQ<11>")
	)
	(segment
		(start 153.32456 -217.224356)
		(end 153.32456 -217.019632)
		(width 0.14478)
		(layer "In13.Cu")
		(net "M_H_CPU1_SA_DQ<11>")
	)
	(segment
		(start 171.040044 -209.650584)
		(end 171.55668 -209.650584)
		(width 0.14478)
		(layer "In13.Cu")
		(net "M_H_CPU1_SA_DQ<11>")
	)
	(segment
		(start 150.59533 -219.748862)
		(end 150.800054 -219.748862)
		(width 0.14478)
		(layer "In13.Cu")
		(net "M_H_CPU1_SA_DQ<11>")
	)
	(segment
		(start 135.453374 -231.19715)
		(end 135.461756 -231.201976)
		(width 0.0889)
		(layer "In13.Cu")
		(net "M_H_CPU1_SA_DQ<11>")
	)
	(segment
		(start 151.880316 -218.119452)
		(end 152.08504 -218.119452)
		(width 0.14478)
		(layer "In13.Cu")
		(net "M_H_CPU1_SA_DQ<11>")
	)
	(segment
		(start 149.81555 -220.528642)
		(end 150.020274 -220.528642)
		(width 0.14478)
		(layer "In13.Cu")
		(net "M_H_CPU1_SA_DQ<11>")
	)
	(segment
		(start 154.88412 -215.664796)
		(end 154.88412 -215.460072)
		(width 0.14478)
		(layer "In13.Cu")
		(net "M_H_CPU1_SA_DQ<11>")
	)
	(segment
		(start 170.199812 -208.810352)
		(end 171.040044 -209.650584)
		(width 0.14478)
		(layer "In13.Cu")
		(net "M_H_CPU1_SA_DQ<11>")
	)
	(segment
		(start 152.54478 -218.004136)
		(end 152.54478 -217.799412)
		(width 0.14478)
		(layer "In13.Cu")
		(net "M_H_CPU1_SA_DQ<11>")
	)
	(segment
		(start 134.488682 -231.258872)
		(end 134.58444 -231.233472)
		(width 0.0889)
		(layer "In13.Cu")
		(net "M_H_CPU1_SA_DQ<11>")
	)
	(segment
		(start 149.088094 -225.072956)
		(end 149.088094 -221.460822)
		(width 0.14478)
		(layer "In13.Cu")
		(net "M_H_CPU1_SA_DQ<11>")
	)
	(segment
		(start 150.91537 -219.084398)
		(end 151.100536 -218.899232)
		(width 0.14478)
		(layer "In13.Cu")
		(net "M_H_CPU1_SA_DQ<11>")
	)
	(segment
		(start 155.27401 -215.070182)
		(end 155.478734 -215.070182)
		(width 0.14478)
		(layer "In13.Cu")
		(net "M_H_CPU1_SA_DQ<11>")
	)
	(arc
		(start 136.40181 -231.201976)
		(mid 136.684766 -231.278153)
		(end 136.967722 -231.201976)
		(width 0.0889)
		(layer "In13.Cu")
		(net "M_H_CPU1_SA_DQ<11>")
	)
	(arc
		(start 136.027668 -231.201976)
		(mid 136.209919 -231.151592)
		(end 136.393428 -231.19715)
		(width 0.0889)
		(layer "In13.Cu")
		(net "M_H_CPU1_SA_DQ<11>")
	)
	(arc
		(start 135.087614 -231.201976)
		(mid 135.269865 -231.151592)
		(end 135.453374 -231.19715)
		(width 0.0889)
		(layer "In13.Cu")
		(net "M_H_CPU1_SA_DQ<11>")
	)
	(arc
		(start 138.281918 -231.201976)
		(mid 138.564874 -231.278153)
		(end 138.84783 -231.201976)
		(width 0.0889)
		(layer "In13.Cu")
		(net "M_H_CPU1_SA_DQ<11>")
	)
	(arc
		(start 137.916158 -231.19715)
		(mid 138.099666 -231.151625)
		(end 138.281918 -231.201976)
		(width 0.0889)
		(layer "In13.Cu")
		(net "M_H_CPU1_SA_DQ<11>")
	)
	(arc
		(start 136.976104 -231.19715)
		(mid 137.159612 -231.151625)
		(end 137.341864 -231.201976)
		(width 0.0889)
		(layer "In13.Cu")
		(net "M_H_CPU1_SA_DQ<11>")
	)
	(arc
		(start 135.461756 -231.201976)
		(mid 135.744712 -231.278153)
		(end 136.027668 -231.201976)
		(width 0.0889)
		(layer "In13.Cu")
		(net "M_H_CPU1_SA_DQ<11>")
	)
	(arc
		(start 143.83004 -230.71455)
		(mid 143.871006 -230.544144)
		(end 143.98498 -230.41102)
		(width 0.0889)
		(layer "In13.Cu")
		(net "M_H_CPU1_SA_DQ<11>")
	)
	(arc
		(start 137.341864 -231.201976)
		(mid 137.62482 -231.278153)
		(end 137.907776 -231.201976)
		(width 0.0889)
		(layer "In13.Cu")
		(net "M_H_CPU1_SA_DQ<11>")
	)
	(arc
		(start 141.67612 -231.19715)
		(mid 141.859628 -231.151625)
		(end 142.04188 -231.201976)
		(width 0.0889)
		(layer "In13.Cu")
		(net "M_H_CPU1_SA_DQ<11>")
	)
	(arc
		(start 142.607792 -231.201976)
		(mid 142.794736 -231.151687)
		(end 142.98168 -231.201976)
		(width 0.0889)
		(layer "In13.Cu")
		(net "M_H_CPU1_SA_DQ<11>")
	)
	(arc
		(start 138.84783 -231.201976)
		(mid 139.034774 -231.151687)
		(end 139.221718 -231.201976)
		(width 0.0889)
		(layer "In13.Cu")
		(net "M_H_CPU1_SA_DQ<11>")
	)
	(arc
		(start 139.78763 -231.201976)
		(mid 139.969881 -231.151592)
		(end 140.15339 -231.19715)
		(width 0.0889)
		(layer "In13.Cu")
		(net "M_H_CPU1_SA_DQ<11>")
	)
	(arc
		(start 140.727684 -231.201976)
		(mid 140.909935 -231.151592)
		(end 141.093444 -231.19715)
		(width 0.0889)
		(layer "In13.Cu")
		(net "M_H_CPU1_SA_DQ<11>")
	)
	(arc
		(start 139.221718 -231.201976)
		(mid 139.504674 -231.278153)
		(end 139.78763 -231.201976)
		(width 0.0889)
		(layer "In13.Cu")
		(net "M_H_CPU1_SA_DQ<11>")
	)
	(arc
		(start 141.101826 -231.201976)
		(mid 141.384782 -231.278153)
		(end 141.667738 -231.201976)
		(width 0.0889)
		(layer "In13.Cu")
		(net "M_H_CPU1_SA_DQ<11>")
	)
	(arc
		(start 142.04188 -231.201976)
		(mid 142.324836 -231.278153)
		(end 142.607792 -231.201976)
		(width 0.0889)
		(layer "In13.Cu")
		(net "M_H_CPU1_SA_DQ<11>")
	)
	(arc
		(start 140.161772 -231.201976)
		(mid 140.444728 -231.278153)
		(end 140.727684 -231.201976)
		(width 0.0889)
		(layer "In13.Cu")
		(net "M_H_CPU1_SA_DQ<11>")
	)
	(arc
		(start 142.98168 -231.201976)
		(mid 143.264636 -231.278153)
		(end 143.547592 -231.201976)
		(width 0.0889)
		(layer "In13.Cu")
		(net "M_H_CPU1_SA_DQ<11>")
	)
	(arc
		(start 143.586708 -231.179116)
		(mid 143.765521 -230.976766)
		(end 143.83004 -230.71455)
		(width 0.0889)
		(layer "In13.Cu")
		(net "M_H_CPU1_SA_DQ<11>")
	)
	(arc
		(start 134.58444 -231.233472)
		(mid 134.839762 -231.277172)
		(end 135.087614 -231.201976)
		(width 0.0889)
		(layer "In13.Cu")
		(net "M_H_CPU1_SA_DQ<11>")
	)
	(segment
		(start 135.27786 -230.980234)
		(end 135.744712 -230.71455)
		(width 0.10668)
		(layer "F.Cu")
		(net "M_H_CPU1_SA_DQ<10>")
	)
	(segment
		(start 164.990526 -207.960468)
		(end 165.135306 -207.815688)
		(width 0.14478)
		(layer "In13.Cu")
		(net "M_H_CPU1_SA_DQ<10>")
	)
	(segment
		(start 164.439346 -207.61198)
		(end 164.584126 -207.75676)
		(width 0.14478)
		(layer "In13.Cu")
		(net "M_H_CPU1_SA_DQ<10>")
	)
	(segment
		(start 137.803382 -230.387144)
		(end 137.811764 -230.39197)
		(width 0.0889)
		(layer "In13.Cu")
		(net "M_H_CPU1_SA_DQ<10>")
	)
	(segment
		(start 159.725868 -209.489548)
		(end 159.911034 -209.304382)
		(width 0.14478)
		(layer "In13.Cu")
		(net "M_H_CPU1_SA_DQ<10>")
	)
	(segment
		(start 145.90395 -227.257102)
		(end 145.90395 -226.63658)
		(width 0.0889)
		(layer "In13.Cu")
		(net "M_H_CPU1_SA_DQ<10>")
	)
	(segment
		(start 165.831266 -207.960468)
		(end 166.299388 -207.960468)
		(width 0.14478)
		(layer "In13.Cu")
		(net "M_H_CPU1_SA_DQ<10>")
	)
	(segment
		(start 161.485326 -208.120488)
		(end 161.630106 -208.265268)
		(width 0.14478)
		(layer "In13.Cu")
		(net "M_H_CPU1_SA_DQ<10>")
	)
	(segment
		(start 147.75307 -224.78746)
		(end 148.188934 -224.351596)
		(width 0.14478)
		(layer "In13.Cu")
		(net "M_H_CPU1_SA_DQ<10>")
	)
	(segment
		(start 156.791914 -212.218778)
		(end 156.696664 -212.123528)
		(width 0.14478)
		(layer "In13.Cu")
		(net "M_H_CPU1_SA_DQ<10>")
	)
	(segment
		(start 157.386528 -211.828888)
		(end 157.571694 -211.643722)
		(width 0.14478)
		(layer "In13.Cu")
		(net "M_H_CPU1_SA_DQ<10>")
	)
	(segment
		(start 143.51508 -229.60076)
		(end 143.547592 -229.581964)
		(width 0.0889)
		(layer "In13.Cu")
		(net "M_H_CPU1_SA_DQ<10>")
	)
	(segment
		(start 164.584126 -207.75676)
		(end 164.584126 -207.815688)
		(width 0.14478)
		(layer "In13.Cu")
		(net "M_H_CPU1_SA_DQ<10>")
	)
	(segment
		(start 159.036004 -209.784188)
		(end 159.036004 -209.579464)
		(width 0.14478)
		(layer "In13.Cu")
		(net "M_H_CPU1_SA_DQ<10>")
	)
	(segment
		(start 148.188934 -224.351596)
		(end 148.188934 -220.426534)
		(width 0.14478)
		(layer "In13.Cu")
		(net "M_H_CPU1_SA_DQ<10>")
	)
	(segment
		(start 143.73479 -229.531672)
		(end 143.824706 -229.531672)
		(width 0.0889)
		(layer "In13.Cu")
		(net "M_H_CPU1_SA_DQ<10>")
	)
	(segment
		(start 138.743436 -230.387144)
		(end 138.751818 -230.39197)
		(width 0.0889)
		(layer "In13.Cu")
		(net "M_H_CPU1_SA_DQ<10>")
	)
	(segment
		(start 160.655 -207.960468)
		(end 161.340546 -207.960468)
		(width 0.14478)
		(layer "In13.Cu")
		(net "M_H_CPU1_SA_DQ<10>")
	)
	(segment
		(start 159.131254 -210.084162)
		(end 159.131254 -209.879438)
		(width 0.14478)
		(layer "In13.Cu")
		(net "M_H_CPU1_SA_DQ<10>")
	)
	(segment
		(start 162.036506 -208.105248)
		(end 162.181286 -207.960468)
		(width 0.14478)
		(layer "In13.Cu")
		(net "M_H_CPU1_SA_DQ<10>")
	)
	(segment
		(start 155.916884 -212.698584)
		(end 156.10205 -212.513418)
		(width 0.14478)
		(layer "In13.Cu")
		(net "M_H_CPU1_SA_DQ<10>")
	)
	(segment
		(start 144.582388 -228.578664)
		(end 145.90395 -227.257102)
		(width 0.0889)
		(layer "In13.Cu")
		(net "M_H_CPU1_SA_DQ<10>")
	)
	(segment
		(start 157.476444 -211.343748)
		(end 157.476444 -211.139024)
		(width 0.14478)
		(layer "In13.Cu")
		(net "M_H_CPU1_SA_DQ<10>")
	)
	(segment
		(start 159.911034 -209.099658)
		(end 159.815784 -209.004408)
		(width 0.14478)
		(layer "In13.Cu")
		(net "M_H_CPU1_SA_DQ<10>")
	)
	(segment
		(start 164.032946 -207.75676)
		(end 164.177726 -207.61198)
		(width 0.14478)
		(layer "In13.Cu")
		(net "M_H_CPU1_SA_DQ<10>")
	)
	(segment
		(start 156.402024 -212.608668)
		(end 156.606748 -212.608668)
		(width 0.14478)
		(layer "In13.Cu")
		(net "M_H_CPU1_SA_DQ<10>")
	)
	(segment
		(start 148.188934 -220.426534)
		(end 155.32227 -213.293198)
		(width 0.14478)
		(layer "In13.Cu")
		(net "M_H_CPU1_SA_DQ<10>")
	)
	(segment
		(start 156.88183 -211.733638)
		(end 157.086554 -211.733638)
		(width 0.14478)
		(layer "In13.Cu")
		(net "M_H_CPU1_SA_DQ<10>")
	)
	(segment
		(start 159.815784 -209.004408)
		(end 159.815784 -208.799684)
		(width 0.14478)
		(layer "In13.Cu")
		(net "M_H_CPU1_SA_DQ<10>")
	)
	(segment
		(start 156.306774 -212.513418)
		(end 156.402024 -212.608668)
		(width 0.14478)
		(layer "In13.Cu")
		(net "M_H_CPU1_SA_DQ<10>")
	)
	(segment
		(start 159.521144 -209.489548)
		(end 159.725868 -209.489548)
		(width 0.14478)
		(layer "In13.Cu")
		(net "M_H_CPU1_SA_DQ<10>")
	)
	(segment
		(start 158.646114 -210.174078)
		(end 158.741364 -210.269328)
		(width 0.14478)
		(layer "In13.Cu")
		(net "M_H_CPU1_SA_DQ<10>")
	)
	(segment
		(start 156.696664 -212.123528)
		(end 156.696664 -211.918804)
		(width 0.14478)
		(layer "In13.Cu")
		(net "M_H_CPU1_SA_DQ<10>")
	)
	(segment
		(start 165.686486 -207.75676)
		(end 165.686486 -207.815688)
		(width 0.14478)
		(layer "In13.Cu")
		(net "M_H_CPU1_SA_DQ<10>")
	)
	(segment
		(start 164.728906 -207.960468)
		(end 164.990526 -207.960468)
		(width 0.14478)
		(layer "In13.Cu")
		(net "M_H_CPU1_SA_DQ<10>")
	)
	(segment
		(start 165.135306 -207.75676)
		(end 165.280086 -207.61198)
		(width 0.14478)
		(layer "In13.Cu")
		(net "M_H_CPU1_SA_DQ<10>")
	)
	(segment
		(start 164.177726 -207.61198)
		(end 164.439346 -207.61198)
		(width 0.14478)
		(layer "In13.Cu")
		(net "M_H_CPU1_SA_DQ<10>")
	)
	(segment
		(start 157.476444 -211.139024)
		(end 157.66161 -210.953858)
		(width 0.14478)
		(layer "In13.Cu")
		(net "M_H_CPU1_SA_DQ<10>")
	)
	(segment
		(start 156.012134 -213.203282)
		(end 156.012134 -212.998558)
		(width 0.14478)
		(layer "In13.Cu")
		(net "M_H_CPU1_SA_DQ<10>")
	)
	(segment
		(start 144.582388 -228.77399)
		(end 144.582388 -228.578664)
		(width 0.0889)
		(layer "In13.Cu")
		(net "M_H_CPU1_SA_DQ<10>")
	)
	(segment
		(start 139.31773 -230.39197)
		(end 139.326112 -230.387144)
		(width 0.0889)
		(layer "In13.Cu")
		(net "M_H_CPU1_SA_DQ<10>")
	)
	(segment
		(start 135.89889 -230.44912)
		(end 135.995156 -230.42372)
		(width 0.0889)
		(layer "In13.Cu")
		(net "M_H_CPU1_SA_DQ<10>")
	)
	(segment
		(start 157.181804 -211.828888)
		(end 157.386528 -211.828888)
		(width 0.14478)
		(layer "In13.Cu")
		(net "M_H_CPU1_SA_DQ<10>")
	)
	(segment
		(start 155.32227 -213.293198)
		(end 155.526994 -213.293198)
		(width 0.14478)
		(layer "In13.Cu")
		(net "M_H_CPU1_SA_DQ<10>")
	)
	(segment
		(start 162.994086 -208.265268)
		(end 163.138866 -208.120488)
		(width 0.14478)
		(layer "In13.Cu")
		(net "M_H_CPU1_SA_DQ<10>")
	)
	(segment
		(start 163.283646 -207.960468)
		(end 163.888166 -207.960468)
		(width 0.14478)
		(layer "In13.Cu")
		(net "M_H_CPU1_SA_DQ<10>")
	)
	(segment
		(start 157.571694 -211.438998)
		(end 157.476444 -211.343748)
		(width 0.14478)
		(layer "In13.Cu")
		(net "M_H_CPU1_SA_DQ<10>")
	)
	(segment
		(start 156.012134 -212.998558)
		(end 155.916884 -212.903308)
		(width 0.14478)
		(layer "In13.Cu")
		(net "M_H_CPU1_SA_DQ<10>")
	)
	(segment
		(start 164.032946 -207.815688)
		(end 164.032946 -207.75676)
		(width 0.14478)
		(layer "In13.Cu")
		(net "M_H_CPU1_SA_DQ<10>")
	)
	(segment
		(start 156.606748 -212.608668)
		(end 156.791914 -212.423502)
		(width 0.14478)
		(layer "In13.Cu")
		(net "M_H_CPU1_SA_DQ<10>")
	)
	(segment
		(start 161.630106 -208.265268)
		(end 161.891726 -208.265268)
		(width 0.14478)
		(layer "In13.Cu")
		(net "M_H_CPU1_SA_DQ<10>")
	)
	(segment
		(start 142.503398 -230.387144)
		(end 142.51178 -230.39197)
		(width 0.0889)
		(layer "In13.Cu")
		(net "M_H_CPU1_SA_DQ<10>")
	)
	(segment
		(start 170.792394 -207.960468)
		(end 171.546774 -207.960468)
		(width 0.14478)
		(layer "In13.Cu")
		(net "M_H_CPU1_SA_DQ<10>")
	)
	(segment
		(start 155.622244 -213.388448)
		(end 155.826968 -213.388448)
		(width 0.14478)
		(layer "In13.Cu")
		(net "M_H_CPU1_SA_DQ<10>")
	)
	(segment
		(start 145.90395 -226.63658)
		(end 147.75307 -224.78746)
		(width 0.0889)
		(layer "In13.Cu")
		(net "M_H_CPU1_SA_DQ<10>")
	)
	(segment
		(start 159.911034 -209.304382)
		(end 159.911034 -209.099658)
		(width 0.14478)
		(layer "In13.Cu")
		(net "M_H_CPU1_SA_DQ<10>")
	)
	(segment
		(start 158.351474 -210.659218)
		(end 158.256224 -210.563968)
		(width 0.14478)
		(layer "In13.Cu")
		(net "M_H_CPU1_SA_DQ<10>")
	)
	(segment
		(start 155.526994 -213.293198)
		(end 155.622244 -213.388448)
		(width 0.14478)
		(layer "In13.Cu")
		(net "M_H_CPU1_SA_DQ<10>")
	)
	(segment
		(start 165.135306 -207.815688)
		(end 165.135306 -207.75676)
		(width 0.14478)
		(layer "In13.Cu")
		(net "M_H_CPU1_SA_DQ<10>")
	)
	(segment
		(start 166.299388 -207.960468)
		(end 167.149526 -207.11033)
		(width 0.14478)
		(layer "In13.Cu")
		(net "M_H_CPU1_SA_DQ<10>")
	)
	(segment
		(start 140.257784 -230.39197)
		(end 140.266166 -230.387144)
		(width 0.0889)
		(layer "In13.Cu")
		(net "M_H_CPU1_SA_DQ<10>")
	)
	(segment
		(start 156.10205 -212.513418)
		(end 156.306774 -212.513418)
		(width 0.14478)
		(layer "In13.Cu")
		(net "M_H_CPU1_SA_DQ<10>")
	)
	(segment
		(start 158.741364 -210.269328)
		(end 158.946088 -210.269328)
		(width 0.14478)
		(layer "In13.Cu")
		(net "M_H_CPU1_SA_DQ<10>")
	)
	(segment
		(start 157.571694 -211.643722)
		(end 157.571694 -211.438998)
		(width 0.14478)
		(layer "In13.Cu")
		(net "M_H_CPU1_SA_DQ<10>")
	)
	(segment
		(start 159.036004 -209.579464)
		(end 159.22117 -209.394298)
		(width 0.14478)
		(layer "In13.Cu")
		(net "M_H_CPU1_SA_DQ<10>")
	)
	(segment
		(start 162.442906 -207.960468)
		(end 162.587686 -208.105248)
		(width 0.14478)
		(layer "In13.Cu")
		(net "M_H_CPU1_SA_DQ<10>")
	)
	(segment
		(start 157.866334 -210.953858)
		(end 157.961584 -211.049108)
		(width 0.14478)
		(layer "In13.Cu")
		(net "M_H_CPU1_SA_DQ<10>")
	)
	(segment
		(start 158.166308 -211.049108)
		(end 158.351474 -210.863942)
		(width 0.14478)
		(layer "In13.Cu")
		(net "M_H_CPU1_SA_DQ<10>")
	)
	(segment
		(start 157.086554 -211.733638)
		(end 157.181804 -211.828888)
		(width 0.14478)
		(layer "In13.Cu")
		(net "M_H_CPU1_SA_DQ<10>")
	)
	(segment
		(start 156.696664 -211.918804)
		(end 156.88183 -211.733638)
		(width 0.14478)
		(layer "In13.Cu")
		(net "M_H_CPU1_SA_DQ<10>")
	)
	(segment
		(start 163.138866 -208.105248)
		(end 163.283646 -207.960468)
		(width 0.14478)
		(layer "In13.Cu")
		(net "M_H_CPU1_SA_DQ<10>")
	)
	(segment
		(start 165.280086 -207.61198)
		(end 165.541706 -207.61198)
		(width 0.14478)
		(layer "In13.Cu")
		(net "M_H_CPU1_SA_DQ<10>")
	)
	(segment
		(start 156.791914 -212.423502)
		(end 156.791914 -212.218778)
		(width 0.14478)
		(layer "In13.Cu")
		(net "M_H_CPU1_SA_DQ<10>")
	)
	(segment
		(start 162.036506 -208.120488)
		(end 162.036506 -208.105248)
		(width 0.14478)
		(layer "In13.Cu")
		(net "M_H_CPU1_SA_DQ<10>")
	)
	(segment
		(start 158.256224 -210.563968)
		(end 158.256224 -210.359244)
		(width 0.14478)
		(layer "In13.Cu")
		(net "M_H_CPU1_SA_DQ<10>")
	)
	(segment
		(start 161.891726 -208.265268)
		(end 162.036506 -208.120488)
		(width 0.14478)
		(layer "In13.Cu")
		(net "M_H_CPU1_SA_DQ<10>")
	)
	(segment
		(start 162.732466 -208.265268)
		(end 162.994086 -208.265268)
		(width 0.14478)
		(layer "In13.Cu")
		(net "M_H_CPU1_SA_DQ<10>")
	)
	(segment
		(start 164.584126 -207.815688)
		(end 164.728906 -207.960468)
		(width 0.14478)
		(layer "In13.Cu")
		(net "M_H_CPU1_SA_DQ<10>")
	)
	(segment
		(start 158.351474 -210.863942)
		(end 158.351474 -210.659218)
		(width 0.14478)
		(layer "In13.Cu")
		(net "M_H_CPU1_SA_DQ<10>")
	)
	(segment
		(start 169.942256 -207.11033)
		(end 170.792394 -207.960468)
		(width 0.14478)
		(layer "In13.Cu")
		(net "M_H_CPU1_SA_DQ<10>")
	)
	(segment
		(start 143.077692 -230.39197)
		(end 143.114268 -230.370634)
		(width 0.0889)
		(layer "In13.Cu")
		(net "M_H_CPU1_SA_DQ<10>")
	)
	(segment
		(start 162.587686 -208.120488)
		(end 162.732466 -208.265268)
		(width 0.14478)
		(layer "In13.Cu")
		(net "M_H_CPU1_SA_DQ<10>")
	)
	(segment
		(start 163.888166 -207.960468)
		(end 164.032946 -207.815688)
		(width 0.14478)
		(layer "In13.Cu")
		(net "M_H_CPU1_SA_DQ<10>")
	)
	(segment
		(start 161.340546 -207.960468)
		(end 161.485326 -208.105248)
		(width 0.14478)
		(layer "In13.Cu")
		(net "M_H_CPU1_SA_DQ<10>")
	)
	(segment
		(start 155.826968 -213.388448)
		(end 156.012134 -213.203282)
		(width 0.14478)
		(layer "In13.Cu")
		(net "M_H_CPU1_SA_DQ<10>")
	)
	(segment
		(start 162.181286 -207.960468)
		(end 162.442906 -207.960468)
		(width 0.14478)
		(layer "In13.Cu")
		(net "M_H_CPU1_SA_DQ<10>")
	)
	(segment
		(start 157.66161 -210.953858)
		(end 157.866334 -210.953858)
		(width 0.14478)
		(layer "In13.Cu")
		(net "M_H_CPU1_SA_DQ<10>")
	)
	(segment
		(start 157.961584 -211.049108)
		(end 158.166308 -211.049108)
		(width 0.14478)
		(layer "In13.Cu")
		(net "M_H_CPU1_SA_DQ<10>")
	)
	(segment
		(start 159.22117 -209.394298)
		(end 159.425894 -209.394298)
		(width 0.14478)
		(layer "In13.Cu")
		(net "M_H_CPU1_SA_DQ<10>")
	)
	(segment
		(start 161.485326 -208.105248)
		(end 161.485326 -208.120488)
		(width 0.14478)
		(layer "In13.Cu")
		(net "M_H_CPU1_SA_DQ<10>")
	)
	(segment
		(start 163.138866 -208.120488)
		(end 163.138866 -208.105248)
		(width 0.14478)
		(layer "In13.Cu")
		(net "M_H_CPU1_SA_DQ<10>")
	)
	(segment
		(start 162.587686 -208.105248)
		(end 162.587686 -208.120488)
		(width 0.14478)
		(layer "In13.Cu")
		(net "M_H_CPU1_SA_DQ<10>")
	)
	(segment
		(start 155.916884 -212.903308)
		(end 155.916884 -212.698584)
		(width 0.14478)
		(layer "In13.Cu")
		(net "M_H_CPU1_SA_DQ<10>")
	)
	(segment
		(start 167.149526 -207.11033)
		(end 169.942256 -207.11033)
		(width 0.14478)
		(layer "In13.Cu")
		(net "M_H_CPU1_SA_DQ<10>")
	)
	(segment
		(start 159.131254 -209.879438)
		(end 159.036004 -209.784188)
		(width 0.14478)
		(layer "In13.Cu")
		(net "M_H_CPU1_SA_DQ<10>")
	)
	(segment
		(start 165.686486 -207.815688)
		(end 165.831266 -207.960468)
		(width 0.14478)
		(layer "In13.Cu")
		(net "M_H_CPU1_SA_DQ<10>")
	)
	(segment
		(start 159.425894 -209.394298)
		(end 159.521144 -209.489548)
		(width 0.14478)
		(layer "In13.Cu")
		(net "M_H_CPU1_SA_DQ<10>")
	)
	(segment
		(start 171.546774 -207.960468)
		(end 171.97197 -207.535272)
		(width 0.14478)
		(layer "In13.Cu")
		(net "M_H_CPU1_SA_DQ<10>")
	)
	(segment
		(start 143.824706 -229.531672)
		(end 144.582388 -228.77399)
		(width 0.0889)
		(layer "In13.Cu")
		(net "M_H_CPU1_SA_DQ<10>")
	)
	(segment
		(start 158.256224 -210.359244)
		(end 158.44139 -210.174078)
		(width 0.14478)
		(layer "In13.Cu")
		(net "M_H_CPU1_SA_DQ<10>")
	)
	(segment
		(start 158.44139 -210.174078)
		(end 158.646114 -210.174078)
		(width 0.14478)
		(layer "In13.Cu")
		(net "M_H_CPU1_SA_DQ<10>")
	)
	(segment
		(start 165.541706 -207.61198)
		(end 165.686486 -207.75676)
		(width 0.14478)
		(layer "In13.Cu")
		(net "M_H_CPU1_SA_DQ<10>")
	)
	(segment
		(start 158.946088 -210.269328)
		(end 159.131254 -210.084162)
		(width 0.14478)
		(layer "In13.Cu")
		(net "M_H_CPU1_SA_DQ<10>")
	)
	(segment
		(start 135.744712 -230.71455)
		(end 135.89889 -230.44912)
		(width 0.0889)
		(layer "In13.Cu")
		(net "M_H_CPU1_SA_DQ<10>")
	)
	(segment
		(start 159.815784 -208.799684)
		(end 160.655 -207.960468)
		(width 0.14478)
		(layer "In13.Cu")
		(net "M_H_CPU1_SA_DQ<10>")
	)
	(arc
		(start 139.691872 -230.39197)
		(mid 139.974828 -230.468113)
		(end 140.257784 -230.39197)
		(width 0.0889)
		(layer "In13.Cu")
		(net "M_H_CPU1_SA_DQ<10>")
	)
	(arc
		(start 142.137638 -230.39197)
		(mid 142.319889 -230.34162)
		(end 142.503398 -230.387144)
		(width 0.0889)
		(layer "In13.Cu")
		(net "M_H_CPU1_SA_DQ<10>")
	)
	(arc
		(start 140.266166 -230.387144)
		(mid 140.449674 -230.34165)
		(end 140.631926 -230.39197)
		(width 0.0889)
		(layer "In13.Cu")
		(net "M_H_CPU1_SA_DQ<10>")
	)
	(arc
		(start 137.811764 -230.39197)
		(mid 138.09472 -230.468113)
		(end 138.377676 -230.39197)
		(width 0.0889)
		(layer "In13.Cu")
		(net "M_H_CPU1_SA_DQ<10>")
	)
	(arc
		(start 141.197838 -230.39197)
		(mid 141.384782 -230.341715)
		(end 141.571726 -230.39197)
		(width 0.0889)
		(layer "In13.Cu")
		(net "M_H_CPU1_SA_DQ<10>")
	)
	(arc
		(start 139.326112 -230.387144)
		(mid 139.50962 -230.34165)
		(end 139.691872 -230.39197)
		(width 0.0889)
		(layer "In13.Cu")
		(net "M_H_CPU1_SA_DQ<10>")
	)
	(arc
		(start 136.497822 -230.39197)
		(mid 136.684766 -230.341715)
		(end 136.87171 -230.39197)
		(width 0.0889)
		(layer "In13.Cu")
		(net "M_H_CPU1_SA_DQ<10>")
	)
	(arc
		(start 137.437622 -230.39197)
		(mid 137.619873 -230.34162)
		(end 137.803382 -230.387144)
		(width 0.0889)
		(layer "In13.Cu")
		(net "M_H_CPU1_SA_DQ<10>")
	)
	(arc
		(start 138.751818 -230.39197)
		(mid 139.034774 -230.468113)
		(end 139.31773 -230.39197)
		(width 0.0889)
		(layer "In13.Cu")
		(net "M_H_CPU1_SA_DQ<10>")
	)
	(arc
		(start 143.36014 -229.90429)
		(mid 143.401106 -229.733884)
		(end 143.51508 -229.60076)
		(width 0.0889)
		(layer "In13.Cu")
		(net "M_H_CPU1_SA_DQ<10>")
	)
	(arc
		(start 143.547592 -229.581964)
		(mid 143.637864 -229.544434)
		(end 143.73479 -229.531672)
		(width 0.0889)
		(layer "In13.Cu")
		(net "M_H_CPU1_SA_DQ<10>")
	)
	(arc
		(start 138.377676 -230.39197)
		(mid 138.559927 -230.34162)
		(end 138.743436 -230.387144)
		(width 0.0889)
		(layer "In13.Cu")
		(net "M_H_CPU1_SA_DQ<10>")
	)
	(arc
		(start 135.995156 -230.42372)
		(mid 136.250221 -230.467051)
		(end 136.497822 -230.39197)
		(width 0.0889)
		(layer "In13.Cu")
		(net "M_H_CPU1_SA_DQ<10>")
	)
	(arc
		(start 143.114268 -230.370634)
		(mid 143.29492 -230.167889)
		(end 143.36014 -229.90429)
		(width 0.0889)
		(layer "In13.Cu")
		(net "M_H_CPU1_SA_DQ<10>")
	)
	(arc
		(start 141.571726 -230.39197)
		(mid 141.854682 -230.468113)
		(end 142.137638 -230.39197)
		(width 0.0889)
		(layer "In13.Cu")
		(net "M_H_CPU1_SA_DQ<10>")
	)
	(arc
		(start 142.51178 -230.39197)
		(mid 142.794736 -230.468113)
		(end 143.077692 -230.39197)
		(width 0.0889)
		(layer "In13.Cu")
		(net "M_H_CPU1_SA_DQ<10>")
	)
	(arc
		(start 140.631926 -230.39197)
		(mid 140.914882 -230.468113)
		(end 141.197838 -230.39197)
		(width 0.0889)
		(layer "In13.Cu")
		(net "M_H_CPU1_SA_DQ<10>")
	)
	(arc
		(start 136.87171 -230.39197)
		(mid 137.154666 -230.468113)
		(end 137.437622 -230.39197)
		(width 0.0889)
		(layer "In13.Cu")
		(net "M_H_CPU1_SA_DQ<10>")
	)
	(segment
		(start 135.748014 -225.310446)
		(end 136.214866 -225.044508)
		(width 0.10668)
		(layer "F.Cu")
		(net "M_H_CPU1_SA_DQ<0>")
	)
	(segment
		(start 137.907776 -225.367088)
		(end 137.916158 -225.371914)
		(width 0.0889)
		(layer "In13.Cu")
		(net "M_H_CPU1_SA_DQ<0>")
	)
	(segment
		(start 141.759686 -222.61449)
		(end 141.753082 -222.607886)
		(width 0.0889)
		(layer "In13.Cu")
		(net "M_H_CPU1_SA_DQ<0>")
	)
	(segment
		(start 141.534388 -222.958914)
		(end 141.57198 -222.93707)
		(width 0.0889)
		(layer "In13.Cu")
		(net "M_H_CPU1_SA_DQ<0>")
	)
	(segment
		(start 160.20288 -197.754748)
		(end 165.37559 -197.754748)
		(width 0.14478)
		(layer "In13.Cu")
		(net "M_H_CPU1_SA_DQ<0>")
	)
	(segment
		(start 141.753082 -222.607886)
		(end 141.753082 -221.381066)
		(width 0.0889)
		(layer "In13.Cu")
		(net "M_H_CPU1_SA_DQ<0>")
	)
	(segment
		(start 141.10208 -223.747076)
		(end 141.13383 -223.728788)
		(width 0.0889)
		(layer "In13.Cu")
		(net "M_H_CPU1_SA_DQ<0>")
	)
	(segment
		(start 172.761656 -197.760336)
		(end 173.787562 -197.335394)
		(width 0.14478)
		(layer "In13.Cu")
		(net "M_H_CPU1_SA_DQ<0>")
	)
	(segment
		(start 140.15339 -225.371914)
		(end 140.161772 -225.367088)
		(width 0.0889)
		(layer "In13.Cu")
		(net "M_H_CPU1_SA_DQ<0>")
	)
	(segment
		(start 141.753082 -221.381066)
		(end 141.753082 -217.495374)
		(width 0.14478)
		(layer "In13.Cu")
		(net "M_H_CPU1_SA_DQ<0>")
	)
	(segment
		(start 140.631926 -224.557082)
		(end 140.663676 -224.538794)
		(width 0.0889)
		(layer "In13.Cu")
		(net "M_H_CPU1_SA_DQ<0>")
	)
	(segment
		(start 140.161772 -225.367088)
		(end 140.193522 -225.3488)
		(width 0.0889)
		(layer "In13.Cu")
		(net "M_H_CPU1_SA_DQ<0>")
	)
	(segment
		(start 136.967722 -225.367088)
		(end 136.976104 -225.371914)
		(width 0.0889)
		(layer "In13.Cu")
		(net "M_H_CPU1_SA_DQ<0>")
	)
	(segment
		(start 141.753082 -217.495374)
		(end 148.78939 -210.459066)
		(width 0.14478)
		(layer "In13.Cu")
		(net "M_H_CPU1_SA_DQ<0>")
	)
	(segment
		(start 141.064234 -223.76892)
		(end 141.10208 -223.747076)
		(width 0.0889)
		(layer "In13.Cu")
		(net "M_H_CPU1_SA_DQ<0>")
	)
	(segment
		(start 171.80687 -197.760336)
		(end 172.761656 -197.760336)
		(width 0.14478)
		(layer "In13.Cu")
		(net "M_H_CPU1_SA_DQ<0>")
	)
	(segment
		(start 167.41394 -196.910452)
		(end 169.755058 -196.910452)
		(width 0.14478)
		(layer "In13.Cu")
		(net "M_H_CPU1_SA_DQ<0>")
	)
	(segment
		(start 140.59281 -224.579942)
		(end 140.631926 -224.557082)
		(width 0.0889)
		(layer "In13.Cu")
		(net "M_H_CPU1_SA_DQ<0>")
	)
	(segment
		(start 173.787562 -197.335394)
		(end 176.072038 -197.335394)
		(width 0.14478)
		(layer "In13.Cu")
		(net "M_H_CPU1_SA_DQ<0>")
	)
	(segment
		(start 136.214866 -225.044508)
		(end 136.060688 -225.309938)
		(width 0.0889)
		(layer "In13.Cu")
		(net "M_H_CPU1_SA_DQ<0>")
	)
	(segment
		(start 136.060688 -225.309938)
		(end 136.08304 -225.39325)
		(width 0.0889)
		(layer "In13.Cu")
		(net "M_H_CPU1_SA_DQ<0>")
	)
	(segment
		(start 148.78939 -209.168238)
		(end 160.20288 -197.754748)
		(width 0.14478)
		(layer "In13.Cu")
		(net "M_H_CPU1_SA_DQ<0>")
	)
	(segment
		(start 136.393428 -225.371914)
		(end 136.40181 -225.367088)
		(width 0.0889)
		(layer "In13.Cu")
		(net "M_H_CPU1_SA_DQ<0>")
	)
	(segment
		(start 169.755058 -196.910452)
		(end 171.80687 -197.760336)
		(width 0.14478)
		(layer "In13.Cu")
		(net "M_H_CPU1_SA_DQ<0>")
	)
	(segment
		(start 141.57198 -222.93707)
		(end 141.604746 -222.91802)
		(width 0.0889)
		(layer "In13.Cu")
		(net "M_H_CPU1_SA_DQ<0>")
	)
	(segment
		(start 165.37559 -197.754748)
		(end 167.41394 -196.910452)
		(width 0.14478)
		(layer "In13.Cu")
		(net "M_H_CPU1_SA_DQ<0>")
	)
	(segment
		(start 148.78939 -210.459066)
		(end 148.78939 -209.168238)
		(width 0.14478)
		(layer "In13.Cu")
		(net "M_H_CPU1_SA_DQ<0>")
	)
	(arc
		(start 140.349478 -225.044508)
		(mid 140.413993 -224.782289)
		(end 140.59281 -224.579942)
		(width 0.0889)
		(layer "In13.Cu")
		(net "M_H_CPU1_SA_DQ<0>")
	)
	(arc
		(start 137.916158 -225.371914)
		(mid 138.099666 -225.417408)
		(end 138.281918 -225.367088)
		(width 0.0889)
		(layer "In13.Cu")
		(net "M_H_CPU1_SA_DQ<0>")
	)
	(arc
		(start 138.281918 -225.367088)
		(mid 138.564874 -225.290911)
		(end 138.84783 -225.367088)
		(width 0.0889)
		(layer "In13.Cu")
		(net "M_H_CPU1_SA_DQ<0>")
	)
	(arc
		(start 139.221718 -225.367088)
		(mid 139.504674 -225.290911)
		(end 139.78763 -225.367088)
		(width 0.0889)
		(layer "In13.Cu")
		(net "M_H_CPU1_SA_DQ<0>")
	)
	(arc
		(start 141.289786 -223.424496)
		(mid 141.354658 -223.161533)
		(end 141.534388 -222.958914)
		(width 0.0889)
		(layer "In13.Cu")
		(net "M_H_CPU1_SA_DQ<0>")
	)
	(arc
		(start 141.13383 -223.728788)
		(mid 141.248506 -223.595454)
		(end 141.289786 -223.424496)
		(width 0.0889)
		(layer "In13.Cu")
		(net "M_H_CPU1_SA_DQ<0>")
	)
	(arc
		(start 140.819632 -224.234502)
		(mid 140.884504 -223.971539)
		(end 141.064234 -223.76892)
		(width 0.0889)
		(layer "In13.Cu")
		(net "M_H_CPU1_SA_DQ<0>")
	)
	(arc
		(start 139.78763 -225.367088)
		(mid 139.969881 -225.417438)
		(end 140.15339 -225.371914)
		(width 0.0889)
		(layer "In13.Cu")
		(net "M_H_CPU1_SA_DQ<0>")
	)
	(arc
		(start 136.08304 -225.39325)
		(mid 136.24055 -225.416448)
		(end 136.393428 -225.371914)
		(width 0.0889)
		(layer "In13.Cu")
		(net "M_H_CPU1_SA_DQ<0>")
	)
	(arc
		(start 140.193522 -225.3488)
		(mid 140.308198 -225.215466)
		(end 140.349478 -225.044508)
		(width 0.0889)
		(layer "In13.Cu")
		(net "M_H_CPU1_SA_DQ<0>")
	)
	(arc
		(start 136.976104 -225.371914)
		(mid 137.159612 -225.417408)
		(end 137.341864 -225.367088)
		(width 0.0889)
		(layer "In13.Cu")
		(net "M_H_CPU1_SA_DQ<0>")
	)
	(arc
		(start 138.84783 -225.367088)
		(mid 139.034774 -225.417343)
		(end 139.221718 -225.367088)
		(width 0.0889)
		(layer "In13.Cu")
		(net "M_H_CPU1_SA_DQ<0>")
	)
	(arc
		(start 141.604746 -222.91802)
		(mid 141.718675 -222.784873)
		(end 141.759686 -222.61449)
		(width 0.0889)
		(layer "In13.Cu")
		(net "M_H_CPU1_SA_DQ<0>")
	)
	(arc
		(start 137.341864 -225.367088)
		(mid 137.62482 -225.290911)
		(end 137.907776 -225.367088)
		(width 0.0889)
		(layer "In13.Cu")
		(net "M_H_CPU1_SA_DQ<0>")
	)
	(arc
		(start 140.663676 -224.538794)
		(mid 140.778352 -224.40546)
		(end 140.819632 -224.234502)
		(width 0.0889)
		(layer "In13.Cu")
		(net "M_H_CPU1_SA_DQ<0>")
	)
	(arc
		(start 136.40181 -225.367088)
		(mid 136.684766 -225.290911)
		(end 136.967722 -225.367088)
		(width 0.0889)
		(layer "In13.Cu")
		(net "M_H_CPU1_SA_DQ<0>")
	)
	(segment
		(start 134.337806 -252.04039)
		(end 134.804658 -251.774452)
		(width 0.10668)
		(layer "F.Cu")
		(net "M_H_CPU1_SA_CS_N<1>")
	)
	(segment
		(start 137.437876 -252.097032)
		(end 137.437622 -252.097032)
		(width 0.0889)
		(layer "In13.Cu")
		(net "M_H_CPU1_SA_CS_N<1>")
	)
	(segment
		(start 147.136612 -251.997464)
		(end 145.555716 -251.997464)
		(width 0.0889)
		(layer "In13.Cu")
		(net "M_H_CPU1_SA_CS_N<1>")
	)
	(segment
		(start 171.703492 -246.903748)
		(end 170.4086 -246.903748)
		(width 0.14478)
		(layer "In13.Cu")
		(net "M_H_CPU1_SA_CS_N<1>")
	)
	(segment
		(start 150.332186 -251.568966)
		(end 149.986746 -251.914406)
		(width 0.14478)
		(layer "In13.Cu")
		(net "M_H_CPU1_SA_CS_N<1>")
	)
	(segment
		(start 171.97197 -246.63527)
		(end 171.703492 -246.903748)
		(width 0.14478)
		(layer "In13.Cu")
		(net "M_H_CPU1_SA_CS_N<1>")
	)
	(segment
		(start 136.87171 -252.097032)
		(end 136.863328 -252.101858)
		(width 0.0889)
		(layer "In13.Cu")
		(net "M_H_CPU1_SA_CS_N<1>")
	)
	(segment
		(start 163.834318 -248.760488)
		(end 161.02584 -251.568966)
		(width 0.14478)
		(layer "In13.Cu")
		(net "M_H_CPU1_SA_CS_N<1>")
	)
	(segment
		(start 145.555716 -251.997464)
		(end 145.332196 -252.097032)
		(width 0.0889)
		(layer "In13.Cu")
		(net "M_H_CPU1_SA_CS_N<1>")
	)
	(segment
		(start 134.958582 -252.039882)
		(end 134.804658 -251.774452)
		(width 0.0889)
		(layer "In13.Cu")
		(net "M_H_CPU1_SA_CS_N<1>")
	)
	(segment
		(start 144.976342 -252.107192)
		(end 144.958054 -252.096778)
		(width 0.0889)
		(layer "In13.Cu")
		(net "M_H_CPU1_SA_CS_N<1>")
	)
	(segment
		(start 147.59051 -251.914406)
		(end 147.21967 -251.914406)
		(width 0.0889)
		(layer "In13.Cu")
		(net "M_H_CPU1_SA_CS_N<1>")
	)
	(segment
		(start 139.326112 -252.101858)
		(end 139.31773 -252.097032)
		(width 0.0889)
		(layer "In13.Cu")
		(net "M_H_CPU1_SA_CS_N<1>")
	)
	(segment
		(start 149.986746 -251.914406)
		(end 147.59051 -251.914406)
		(width 0.14478)
		(layer "In13.Cu")
		(net "M_H_CPU1_SA_CS_N<1>")
	)
	(segment
		(start 138.386058 -252.101858)
		(end 138.377676 -252.097032)
		(width 0.0889)
		(layer "In13.Cu")
		(net "M_H_CPU1_SA_CS_N<1>")
	)
	(segment
		(start 143.086074 -252.101858)
		(end 143.077692 -252.097032)
		(width 0.0889)
		(layer "In13.Cu")
		(net "M_H_CPU1_SA_CS_N<1>")
	)
	(segment
		(start 170.4086 -246.903748)
		(end 169.4942 -247.818148)
		(width 0.14478)
		(layer "In13.Cu")
		(net "M_H_CPU1_SA_CS_N<1>")
	)
	(segment
		(start 161.02584 -251.568966)
		(end 150.332186 -251.568966)
		(width 0.14478)
		(layer "In13.Cu")
		(net "M_H_CPU1_SA_CS_N<1>")
	)
	(segment
		(start 167.79494 -247.818148)
		(end 166.8526 -248.760488)
		(width 0.14478)
		(layer "In13.Cu")
		(net "M_H_CPU1_SA_CS_N<1>")
	)
	(segment
		(start 144.39265 -252.097032)
		(end 144.380966 -252.10389)
		(width 0.0889)
		(layer "In13.Cu")
		(net "M_H_CPU1_SA_CS_N<1>")
	)
	(segment
		(start 140.266166 -252.101858)
		(end 140.257784 -252.097032)
		(width 0.0889)
		(layer "In13.Cu")
		(net "M_H_CPU1_SA_CS_N<1>")
	)
	(segment
		(start 166.8526 -248.760488)
		(end 163.834318 -248.760488)
		(width 0.14478)
		(layer "In13.Cu")
		(net "M_H_CPU1_SA_CS_N<1>")
	)
	(segment
		(start 147.21967 -251.914406)
		(end 147.136612 -251.997464)
		(width 0.0889)
		(layer "In13.Cu")
		(net "M_H_CPU1_SA_CS_N<1>")
	)
	(segment
		(start 169.4942 -247.818148)
		(end 167.79494 -247.818148)
		(width 0.14478)
		(layer "In13.Cu")
		(net "M_H_CPU1_SA_CS_N<1>")
	)
	(segment
		(start 142.51178 -252.097032)
		(end 142.503398 -252.101858)
		(width 0.0889)
		(layer "In13.Cu")
		(net "M_H_CPU1_SA_CS_N<1>")
	)
	(segment
		(start 135.054594 -252.065282)
		(end 134.958582 -252.039882)
		(width 0.0889)
		(layer "In13.Cu")
		(net "M_H_CPU1_SA_CS_N<1>")
	)
	(segment
		(start 144.958054 -252.096778)
		(end 144.952466 -252.093476)
		(width 0.0889)
		(layer "In13.Cu")
		(net "M_H_CPU1_SA_CS_N<1>")
	)
	(segment
		(start 135.931656 -252.097032)
		(end 135.923274 -252.101858)
		(width 0.0889)
		(layer "In13.Cu")
		(net "M_H_CPU1_SA_CS_N<1>")
	)
	(segment
		(start 143.466566 -252.088396)
		(end 143.451834 -252.097032)
		(width 0.0889)
		(layer "In13.Cu")
		(net "M_H_CPU1_SA_CS_N<1>")
	)
	(arc
		(start 142.503398 -252.101858)
		(mid 142.31989 -252.147352)
		(end 142.137638 -252.097032)
		(width 0.0889)
		(layer "In13.Cu")
		(net "M_H_CPU1_SA_CS_N<1>")
	)
	(arc
		(start 144.018254 -252.097032)
		(mid 143.743548 -252.020668)
		(end 143.466566 -252.088396)
		(width 0.0889)
		(layer "In13.Cu")
		(net "M_H_CPU1_SA_CS_N<1>")
	)
	(arc
		(start 142.137638 -252.097032)
		(mid 141.854682 -252.020855)
		(end 141.571726 -252.097032)
		(width 0.0889)
		(layer "In13.Cu")
		(net "M_H_CPU1_SA_CS_N<1>")
	)
	(arc
		(start 140.631926 -252.097032)
		(mid 140.449675 -252.147382)
		(end 140.266166 -252.101858)
		(width 0.0889)
		(layer "In13.Cu")
		(net "M_H_CPU1_SA_CS_N<1>")
	)
	(arc
		(start 137.437622 -252.097032)
		(mid 137.154666 -252.020855)
		(end 136.87171 -252.097032)
		(width 0.0889)
		(layer "In13.Cu")
		(net "M_H_CPU1_SA_CS_N<1>")
	)
	(arc
		(start 143.077692 -252.097032)
		(mid 142.794736 -252.020855)
		(end 142.51178 -252.097032)
		(width 0.0889)
		(layer "In13.Cu")
		(net "M_H_CPU1_SA_CS_N<1>")
	)
	(arc
		(start 135.557514 -252.097032)
		(mid 135.309801 -252.021812)
		(end 135.054594 -252.065282)
		(width 0.0889)
		(layer "In13.Cu")
		(net "M_H_CPU1_SA_CS_N<1>")
	)
	(arc
		(start 139.31773 -252.097032)
		(mid 139.034774 -252.020889)
		(end 138.751818 -252.097032)
		(width 0.0889)
		(layer "In13.Cu")
		(net "M_H_CPU1_SA_CS_N<1>")
	)
	(arc
		(start 138.751818 -252.097032)
		(mid 138.569567 -252.147382)
		(end 138.386058 -252.101858)
		(width 0.0889)
		(layer "In13.Cu")
		(net "M_H_CPU1_SA_CS_N<1>")
	)
	(arc
		(start 141.197838 -252.097032)
		(mid 140.914882 -252.020855)
		(end 140.631926 -252.097032)
		(width 0.0889)
		(layer "In13.Cu")
		(net "M_H_CPU1_SA_CS_N<1>")
	)
	(arc
		(start 140.257784 -252.097032)
		(mid 139.974828 -252.020855)
		(end 139.691872 -252.097032)
		(width 0.0889)
		(layer "In13.Cu")
		(net "M_H_CPU1_SA_CS_N<1>")
	)
	(arc
		(start 138.377676 -252.097032)
		(mid 138.09472 -252.020855)
		(end 137.811764 -252.097032)
		(width 0.0889)
		(layer "In13.Cu")
		(net "M_H_CPU1_SA_CS_N<1>")
	)
	(arc
		(start 135.923274 -252.101858)
		(mid 135.739766 -252.147352)
		(end 135.557514 -252.097032)
		(width 0.0889)
		(layer "In13.Cu")
		(net "M_H_CPU1_SA_CS_N<1>")
	)
	(arc
		(start 139.691872 -252.097032)
		(mid 139.509621 -252.147382)
		(end 139.326112 -252.101858)
		(width 0.0889)
		(layer "In13.Cu")
		(net "M_H_CPU1_SA_CS_N<1>")
	)
	(arc
		(start 136.863328 -252.101858)
		(mid 136.67982 -252.147352)
		(end 136.497568 -252.097032)
		(width 0.0889)
		(layer "In13.Cu")
		(net "M_H_CPU1_SA_CS_N<1>")
	)
	(arc
		(start 144.380966 -252.10389)
		(mid 144.198711 -252.147543)
		(end 144.018254 -252.097032)
		(width 0.0889)
		(layer "In13.Cu")
		(net "M_H_CPU1_SA_CS_N<1>")
	)
	(arc
		(start 143.451834 -252.097032)
		(mid 143.269583 -252.147382)
		(end 143.086074 -252.101858)
		(width 0.0889)
		(layer "In13.Cu")
		(net "M_H_CPU1_SA_CS_N<1>")
	)
	(arc
		(start 141.571726 -252.097032)
		(mid 141.384782 -252.147287)
		(end 141.197838 -252.097032)
		(width 0.0889)
		(layer "In13.Cu")
		(net "M_H_CPU1_SA_CS_N<1>")
	)
	(arc
		(start 137.811764 -252.097032)
		(mid 137.62482 -252.147356)
		(end 137.437876 -252.097032)
		(width 0.0889)
		(layer "In13.Cu")
		(net "M_H_CPU1_SA_CS_N<1>")
	)
	(arc
		(start 145.332196 -252.097032)
		(mid 145.155568 -252.147265)
		(end 144.976342 -252.107192)
		(width 0.0889)
		(layer "In13.Cu")
		(net "M_H_CPU1_SA_CS_N<1>")
	)
	(arc
		(start 144.952466 -252.093476)
		(mid 144.672077 -252.020807)
		(end 144.39265 -252.097032)
		(width 0.0889)
		(layer "In13.Cu")
		(net "M_H_CPU1_SA_CS_N<1>")
	)
	(arc
		(start 136.497568 -252.097032)
		(mid 136.214612 -252.020855)
		(end 135.931656 -252.097032)
		(width 0.0889)
		(layer "In13.Cu")
		(net "M_H_CPU1_SA_CS_N<1>")
	)
	(segment
		(start 135.748014 -251.230384)
		(end 136.214866 -250.964446)
		(width 0.10668)
		(layer "F.Cu")
		(net "M_H_CPU1_SA_CS_N<0>")
	)
	(segment
		(start 144.488408 -251.287026)
		(end 144.477994 -251.28093)
		(width 0.0889)
		(layer "In13.Cu")
		(net "M_H_CPU1_SA_CS_N<0>")
	)
	(segment
		(start 146.269456 -251.593604)
		(end 145.95729 -251.281438)
		(width 0.0889)
		(layer "In13.Cu")
		(net "M_H_CPU1_SA_CS_N<0>")
	)
	(segment
		(start 138.281918 -251.287026)
		(end 138.273536 -251.291852)
		(width 0.0889)
		(layer "In13.Cu")
		(net "M_H_CPU1_SA_CS_N<0>")
	)
	(segment
		(start 164.048186 -247.91035)
		(end 160.83915 -251.119386)
		(width 0.14478)
		(layer "In13.Cu")
		(net "M_H_CPU1_SA_CS_N<0>")
	)
	(segment
		(start 176.072038 -245.785386)
		(end 173.38802 -245.785386)
		(width 0.14478)
		(layer "In13.Cu")
		(net "M_H_CPU1_SA_CS_N<0>")
	)
	(segment
		(start 149.799548 -251.453904)
		(end 147.500848 -251.453904)
		(width 0.14478)
		(layer "In13.Cu")
		(net "M_H_CPU1_SA_CS_N<0>")
	)
	(segment
		(start 141.67612 -251.291852)
		(end 141.667738 -251.287026)
		(width 0.0889)
		(layer "In13.Cu")
		(net "M_H_CPU1_SA_CS_N<0>")
	)
	(segment
		(start 145.95729 -251.281438)
		(end 145.428208 -251.287026)
		(width 0.0889)
		(layer "In13.Cu")
		(net "M_H_CPU1_SA_CS_N<0>")
	)
	(segment
		(start 166.6494 -247.767348)
		(end 166.640002 -247.767348)
		(width 0.14478)
		(layer "In13.Cu")
		(net "M_H_CPU1_SA_CS_N<0>")
	)
	(segment
		(start 169.3418 -247.208548)
		(end 167.2082 -247.208548)
		(width 0.14478)
		(layer "In13.Cu")
		(net "M_H_CPU1_SA_CS_N<0>")
	)
	(segment
		(start 143.555974 -251.291852)
		(end 143.547592 -251.287026)
		(width 0.0889)
		(layer "In13.Cu")
		(net "M_H_CPU1_SA_CS_N<0>")
	)
	(segment
		(start 136.36879 -251.229876)
		(end 136.214866 -250.964446)
		(width 0.0889)
		(layer "In13.Cu")
		(net "M_H_CPU1_SA_CS_N<0>")
	)
	(segment
		(start 144.862296 -251.286772)
		(end 144.84604 -251.29617)
		(width 0.0889)
		(layer "In13.Cu")
		(net "M_H_CPU1_SA_CS_N<0>")
	)
	(segment
		(start 170.34002 -246.210328)
		(end 169.3418 -247.208548)
		(width 0.14478)
		(layer "In13.Cu")
		(net "M_H_CPU1_SA_CS_N<0>")
	)
	(segment
		(start 136.464802 -251.255276)
		(end 136.36879 -251.229876)
		(width 0.0889)
		(layer "In13.Cu")
		(net "M_H_CPU1_SA_CS_N<0>")
	)
	(segment
		(start 150.134066 -251.119386)
		(end 149.799548 -251.453904)
		(width 0.14478)
		(layer "In13.Cu")
		(net "M_H_CPU1_SA_CS_N<0>")
	)
	(segment
		(start 160.83915 -251.119386)
		(end 150.134066 -251.119386)
		(width 0.14478)
		(layer "In13.Cu")
		(net "M_H_CPU1_SA_CS_N<0>")
	)
	(segment
		(start 167.2082 -247.208548)
		(end 166.6494 -247.767348)
		(width 0.14478)
		(layer "In13.Cu")
		(net "M_H_CPU1_SA_CS_N<0>")
	)
	(segment
		(start 173.38802 -245.785386)
		(end 172.963078 -246.210328)
		(width 0.14478)
		(layer "In13.Cu")
		(net "M_H_CPU1_SA_CS_N<0>")
	)
	(segment
		(start 147.208748 -251.453904)
		(end 147.069048 -251.593604)
		(width 0.0889)
		(layer "In13.Cu")
		(net "M_H_CPU1_SA_CS_N<0>")
	)
	(segment
		(start 147.069048 -251.593604)
		(end 146.269456 -251.593604)
		(width 0.0889)
		(layer "In13.Cu")
		(net "M_H_CPU1_SA_CS_N<0>")
	)
	(segment
		(start 147.500848 -251.453904)
		(end 147.208748 -251.453904)
		(width 0.0889)
		(layer "In13.Cu")
		(net "M_H_CPU1_SA_CS_N<0>")
	)
	(segment
		(start 137.341864 -251.287026)
		(end 137.333482 -251.291852)
		(width 0.0889)
		(layer "In13.Cu")
		(net "M_H_CPU1_SA_CS_N<0>")
	)
	(segment
		(start 166.497 -247.91035)
		(end 164.048186 -247.91035)
		(width 0.14478)
		(layer "In13.Cu")
		(net "M_H_CPU1_SA_CS_N<0>")
	)
	(segment
		(start 144.878044 -251.277628)
		(end 144.862296 -251.286772)
		(width 0.0889)
		(layer "In13.Cu")
		(net "M_H_CPU1_SA_CS_N<0>")
	)
	(segment
		(start 172.963078 -246.210328)
		(end 170.34002 -246.210328)
		(width 0.14478)
		(layer "In13.Cu")
		(net "M_H_CPU1_SA_CS_N<0>")
	)
	(segment
		(start 140.161772 -251.287026)
		(end 140.15339 -251.291852)
		(width 0.0889)
		(layer "In13.Cu")
		(net "M_H_CPU1_SA_CS_N<0>")
	)
	(segment
		(start 141.101826 -251.287026)
		(end 141.093444 -251.291852)
		(width 0.0889)
		(layer "In13.Cu")
		(net "M_H_CPU1_SA_CS_N<0>")
	)
	(segment
		(start 166.640002 -247.767348)
		(end 166.497 -247.91035)
		(width 0.14478)
		(layer "In13.Cu")
		(net "M_H_CPU1_SA_CS_N<0>")
	)
	(arc
		(start 137.907776 -251.287026)
		(mid 137.62482 -251.210849)
		(end 137.341864 -251.287026)
		(width 0.0889)
		(layer "In13.Cu")
		(net "M_H_CPU1_SA_CS_N<0>")
	)
	(arc
		(start 142.98168 -251.287026)
		(mid 142.794736 -251.337281)
		(end 142.607792 -251.287026)
		(width 0.0889)
		(layer "In13.Cu")
		(net "M_H_CPU1_SA_CS_N<0>")
	)
	(arc
		(start 143.922242 -251.287026)
		(mid 143.739737 -251.337503)
		(end 143.555974 -251.291852)
		(width 0.0889)
		(layer "In13.Cu")
		(net "M_H_CPU1_SA_CS_N<0>")
	)
	(arc
		(start 136.967722 -251.287026)
		(mid 136.720009 -251.211806)
		(end 136.464802 -251.255276)
		(width 0.0889)
		(layer "In13.Cu")
		(net "M_H_CPU1_SA_CS_N<0>")
	)
	(arc
		(start 143.547592 -251.287026)
		(mid 143.264636 -251.210849)
		(end 142.98168 -251.287026)
		(width 0.0889)
		(layer "In13.Cu")
		(net "M_H_CPU1_SA_CS_N<0>")
	)
	(arc
		(start 138.273536 -251.291852)
		(mid 138.090028 -251.337346)
		(end 137.907776 -251.287026)
		(width 0.0889)
		(layer "In13.Cu")
		(net "M_H_CPU1_SA_CS_N<0>")
	)
	(arc
		(start 139.221718 -251.287026)
		(mid 139.034774 -251.337315)
		(end 138.84783 -251.287026)
		(width 0.0889)
		(layer "In13.Cu")
		(net "M_H_CPU1_SA_CS_N<0>")
	)
	(arc
		(start 140.15339 -251.291852)
		(mid 139.969882 -251.337346)
		(end 139.78763 -251.287026)
		(width 0.0889)
		(layer "In13.Cu")
		(net "M_H_CPU1_SA_CS_N<0>")
	)
	(arc
		(start 138.84783 -251.287026)
		(mid 138.564874 -251.210849)
		(end 138.281918 -251.287026)
		(width 0.0889)
		(layer "In13.Cu")
		(net "M_H_CPU1_SA_CS_N<0>")
	)
	(arc
		(start 144.477994 -251.28093)
		(mid 144.199308 -251.21071)
		(end 143.922242 -251.287026)
		(width 0.0889)
		(layer "In13.Cu")
		(net "M_H_CPU1_SA_CS_N<0>")
	)
	(arc
		(start 141.667738 -251.287026)
		(mid 141.384782 -251.210849)
		(end 141.101826 -251.287026)
		(width 0.0889)
		(layer "In13.Cu")
		(net "M_H_CPU1_SA_CS_N<0>")
	)
	(arc
		(start 144.84604 -251.29617)
		(mid 144.666058 -251.33727)
		(end 144.488408 -251.287026)
		(width 0.0889)
		(layer "In13.Cu")
		(net "M_H_CPU1_SA_CS_N<0>")
	)
	(arc
		(start 142.04188 -251.287026)
		(mid 141.859629 -251.337376)
		(end 141.67612 -251.291852)
		(width 0.0889)
		(layer "In13.Cu")
		(net "M_H_CPU1_SA_CS_N<0>")
	)
	(arc
		(start 145.428208 -251.287026)
		(mid 145.154353 -251.210676)
		(end 144.878044 -251.277628)
		(width 0.0889)
		(layer "In13.Cu")
		(net "M_H_CPU1_SA_CS_N<0>")
	)
	(arc
		(start 142.607792 -251.287026)
		(mid 142.324836 -251.210849)
		(end 142.04188 -251.287026)
		(width 0.0889)
		(layer "In13.Cu")
		(net "M_H_CPU1_SA_CS_N<0>")
	)
	(arc
		(start 137.333482 -251.291852)
		(mid 137.149974 -251.337346)
		(end 136.967722 -251.287026)
		(width 0.0889)
		(layer "In13.Cu")
		(net "M_H_CPU1_SA_CS_N<0>")
	)
	(arc
		(start 141.093444 -251.291852)
		(mid 140.909936 -251.337346)
		(end 140.727684 -251.287026)
		(width 0.0889)
		(layer "In13.Cu")
		(net "M_H_CPU1_SA_CS_N<0>")
	)
	(arc
		(start 140.727684 -251.287026)
		(mid 140.444728 -251.210849)
		(end 140.161772 -251.287026)
		(width 0.0889)
		(layer "In13.Cu")
		(net "M_H_CPU1_SA_CS_N<0>")
	)
	(arc
		(start 139.78763 -251.287026)
		(mid 139.504674 -251.210849)
		(end 139.221718 -251.287026)
		(width 0.0889)
		(layer "In13.Cu")
		(net "M_H_CPU1_SA_CS_N<0>")
	)
	(segment
		(start 133.867906 -249.610372)
		(end 134.334758 -249.344434)
		(width 0.10668)
		(layer "F.Cu")
		(net "M_H_CPU1_SA_CB<7>")
	)
	(segment
		(start 163.392612 -245.280434)
		(end 163.71316 -244.959886)
		(width 0.14478)
		(layer "In13.Cu")
		(net "M_H_CPU1_SA_CB<7>")
	)
	(segment
		(start 148.974048 -249.460004)
		(end 149.217126 -249.216926)
		(width 0.14478)
		(layer "In13.Cu")
		(net "M_H_CPU1_SA_CB<7>")
	)
	(segment
		(start 166.662608 -244.817138)
		(end 166.807388 -244.672358)
		(width 0.14478)
		(layer "In13.Cu")
		(net "M_H_CPU1_SA_CB<7>")
	)
	(segment
		(start 163.085272 -245.957344)
		(end 163.289996 -245.957344)
		(width 0.14478)
		(layer "In13.Cu")
		(net "M_H_CPU1_SA_CB<7>")
	)
	(segment
		(start 161.833052 -247.044718)
		(end 161.833052 -246.839994)
		(width 0.14478)
		(layer "In13.Cu")
		(net "M_H_CPU1_SA_CB<7>")
	)
	(segment
		(start 166.807388 -244.672358)
		(end 166.807388 -244.655086)
		(width 0.14478)
		(layer "In13.Cu")
		(net "M_H_CPU1_SA_CB<7>")
	)
	(segment
		(start 161.136076 -248.111264)
		(end 161.135822 -247.907048)
		(width 0.14478)
		(layer "In13.Cu")
		(net "M_H_CPU1_SA_CB<7>")
	)
	(segment
		(start 160.273492 -248.604278)
		(end 160.273492 -248.399554)
		(width 0.14478)
		(layer "In13.Cu")
		(net "M_H_CPU1_SA_CB<7>")
	)
	(segment
		(start 166.400988 -244.817138)
		(end 166.662608 -244.817138)
		(width 0.14478)
		(layer "In13.Cu")
		(net "M_H_CPU1_SA_CB<7>")
	)
	(segment
		(start 136.967722 -249.021854)
		(end 136.976104 -249.017028)
		(width 0.0889)
		(layer "In13.Cu")
		(net "M_H_CPU1_SA_CB<7>")
	)
	(segment
		(start 161.053272 -247.619774)
		(end 161.238438 -247.434608)
		(width 0.14478)
		(layer "In13.Cu")
		(net "M_H_CPU1_SA_CB<7>")
	)
	(segment
		(start 135.453374 -249.017028)
		(end 135.461756 -249.021854)
		(width 0.0889)
		(layer "In13.Cu")
		(net "M_H_CPU1_SA_CB<7>")
	)
	(segment
		(start 141.667738 -249.021854)
		(end 141.67612 -249.017028)
		(width 0.0889)
		(layer "In13.Cu")
		(net "M_H_CPU1_SA_CB<7>")
	)
	(segment
		(start 162.510216 -246.737124)
		(end 162.695636 -246.551704)
		(width 0.14478)
		(layer "In13.Cu")
		(net "M_H_CPU1_SA_CB<7>")
	)
	(segment
		(start 160.745932 -248.296684)
		(end 160.950656 -248.296684)
		(width 0.14478)
		(layer "In13.Cu")
		(net "M_H_CPU1_SA_CB<7>")
	)
	(segment
		(start 162.305492 -246.737124)
		(end 162.510216 -246.737124)
		(width 0.14478)
		(layer "In13.Cu")
		(net "M_H_CPU1_SA_CB<7>")
	)
	(segment
		(start 143.547592 -249.021854)
		(end 143.555974 -249.017028)
		(width 0.0889)
		(layer "In13.Cu")
		(net "M_H_CPU1_SA_CB<7>")
	)
	(segment
		(start 147.752054 -249.460004)
		(end 148.974048 -249.460004)
		(width 0.14478)
		(layer "In13.Cu")
		(net "M_H_CPU1_SA_CB<7>")
	)
	(segment
		(start 141.093444 -249.017028)
		(end 141.101826 -249.021854)
		(width 0.0889)
		(layer "In13.Cu")
		(net "M_H_CPU1_SA_CB<7>")
	)
	(segment
		(start 161.053272 -247.824498)
		(end 161.053272 -247.619774)
		(width 0.14478)
		(layer "In13.Cu")
		(net "M_H_CPU1_SA_CB<7>")
	)
	(segment
		(start 161.915602 -247.127268)
		(end 161.833052 -247.044718)
		(width 0.14478)
		(layer "In13.Cu")
		(net "M_H_CPU1_SA_CB<7>")
	)
	(segment
		(start 145.794476 -249.017028)
		(end 145.794476 -249.022362)
		(width 0.0889)
		(layer "In13.Cu")
		(net "M_H_CPU1_SA_CB<7>")
	)
	(segment
		(start 162.612832 -246.060214)
		(end 162.797998 -245.875048)
		(width 0.14478)
		(layer "In13.Cu")
		(net "M_H_CPU1_SA_CB<7>")
	)
	(segment
		(start 160.273492 -248.399554)
		(end 160.458658 -248.214388)
		(width 0.14478)
		(layer "In13.Cu")
		(net "M_H_CPU1_SA_CB<7>")
	)
	(segment
		(start 134.334758 -249.344434)
		(end 134.488682 -249.079004)
		(width 0.0889)
		(layer "In13.Cu")
		(net "M_H_CPU1_SA_CB<7>")
	)
	(segment
		(start 169.936922 -243.263928)
		(end 170.282108 -243.263928)
		(width 0.14478)
		(layer "In13.Cu")
		(net "M_H_CPU1_SA_CB<7>")
	)
	(segment
		(start 166.952168 -244.510306)
		(end 168.690544 -244.510306)
		(width 0.14478)
		(layer "In13.Cu")
		(net "M_H_CPU1_SA_CB<7>")
	)
	(segment
		(start 159.678878 -248.994168)
		(end 159.883602 -248.993914)
		(width 0.14478)
		(layer "In13.Cu")
		(net "M_H_CPU1_SA_CB<7>")
	)
	(segment
		(start 170.978068 -243.408708)
		(end 171.122848 -243.263928)
		(width 0.14478)
		(layer "In13.Cu")
		(net "M_H_CPU1_SA_CB<7>")
	)
	(segment
		(start 166.807388 -244.655086)
		(end 166.952168 -244.510306)
		(width 0.14478)
		(layer "In13.Cu")
		(net "M_H_CPU1_SA_CB<7>")
	)
	(segment
		(start 145.794476 -249.022362)
		(end 146.016218 -249.244104)
		(width 0.0889)
		(layer "In13.Cu")
		(net "M_H_CPU1_SA_CB<7>")
	)
	(segment
		(start 162.222942 -246.654574)
		(end 162.305492 -246.737124)
		(width 0.14478)
		(layer "In13.Cu")
		(net "M_H_CPU1_SA_CB<7>")
	)
	(segment
		(start 164.776912 -244.959886)
		(end 165.226492 -244.510306)
		(width 0.14478)
		(layer "In13.Cu")
		(net "M_H_CPU1_SA_CB<7>")
	)
	(segment
		(start 161.915856 -247.331484)
		(end 161.915602 -247.127268)
		(width 0.14478)
		(layer "In13.Cu")
		(net "M_H_CPU1_SA_CB<7>")
	)
	(segment
		(start 161.443162 -247.434354)
		(end 161.525712 -247.516904)
		(width 0.14478)
		(layer "In13.Cu")
		(net "M_H_CPU1_SA_CB<7>")
	)
	(segment
		(start 159.45612 -249.216926)
		(end 159.678878 -248.994168)
		(width 0.14478)
		(layer "In13.Cu")
		(net "M_H_CPU1_SA_CB<7>")
	)
	(segment
		(start 146.906488 -249.244104)
		(end 147.122388 -249.460004)
		(width 0.0889)
		(layer "In13.Cu")
		(net "M_H_CPU1_SA_CB<7>")
	)
	(segment
		(start 165.560248 -244.510306)
		(end 165.705028 -244.365526)
		(width 0.14478)
		(layer "In13.Cu")
		(net "M_H_CPU1_SA_CB<7>")
	)
	(segment
		(start 162.612832 -246.264938)
		(end 162.612832 -246.060214)
		(width 0.14478)
		(layer "In13.Cu")
		(net "M_H_CPU1_SA_CB<7>")
	)
	(segment
		(start 149.217126 -249.216926)
		(end 159.45612 -249.216926)
		(width 0.14478)
		(layer "In13.Cu")
		(net "M_H_CPU1_SA_CB<7>")
	)
	(segment
		(start 160.356296 -248.891044)
		(end 160.356042 -248.686828)
		(width 0.14478)
		(layer "In13.Cu")
		(net "M_H_CPU1_SA_CB<7>")
	)
	(segment
		(start 161.238438 -247.434608)
		(end 161.443162 -247.434354)
		(width 0.14478)
		(layer "In13.Cu")
		(net "M_H_CPU1_SA_CB<7>")
	)
	(segment
		(start 166.256208 -244.672358)
		(end 166.400988 -244.817138)
		(width 0.14478)
		(layer "In13.Cu")
		(net "M_H_CPU1_SA_CB<7>")
	)
	(segment
		(start 161.525712 -247.516904)
		(end 161.730436 -247.516904)
		(width 0.14478)
		(layer "In13.Cu")
		(net "M_H_CPU1_SA_CB<7>")
	)
	(segment
		(start 170.833288 -243.769896)
		(end 170.978068 -243.625116)
		(width 0.14478)
		(layer "In13.Cu")
		(net "M_H_CPU1_SA_CB<7>")
	)
	(segment
		(start 171.122848 -243.263928)
		(end 171.943268 -243.263928)
		(width 0.14478)
		(layer "In13.Cu")
		(net "M_H_CPU1_SA_CB<7>")
	)
	(segment
		(start 136.393428 -249.017028)
		(end 136.40181 -249.021854)
		(width 0.0889)
		(layer "In13.Cu")
		(net "M_H_CPU1_SA_CB<7>")
	)
	(segment
		(start 165.705028 -244.365526)
		(end 165.705028 -244.254782)
		(width 0.14478)
		(layer "In13.Cu")
		(net "M_H_CPU1_SA_CB<7>")
	)
	(segment
		(start 166.256208 -244.254782)
		(end 166.256208 -244.672358)
		(width 0.14478)
		(layer "In13.Cu")
		(net "M_H_CPU1_SA_CB<7>")
	)
	(segment
		(start 166.111428 -244.110002)
		(end 166.256208 -244.254782)
		(width 0.14478)
		(layer "In13.Cu")
		(net "M_H_CPU1_SA_CB<7>")
	)
	(segment
		(start 144.862296 -249.022108)
		(end 144.878044 -249.031252)
		(width 0.0889)
		(layer "In13.Cu")
		(net "M_H_CPU1_SA_CB<7>")
	)
	(segment
		(start 160.663382 -248.214134)
		(end 160.745932 -248.296684)
		(width 0.14478)
		(layer "In13.Cu")
		(net "M_H_CPU1_SA_CB<7>")
	)
	(segment
		(start 161.833052 -246.839994)
		(end 162.018218 -246.654828)
		(width 0.14478)
		(layer "In13.Cu")
		(net "M_H_CPU1_SA_CB<7>")
	)
	(segment
		(start 163.002722 -245.874794)
		(end 163.085272 -245.957344)
		(width 0.14478)
		(layer "In13.Cu")
		(net "M_H_CPU1_SA_CB<7>")
	)
	(segment
		(start 165.705028 -244.254782)
		(end 165.849808 -244.110002)
		(width 0.14478)
		(layer "In13.Cu")
		(net "M_H_CPU1_SA_CB<7>")
	)
	(segment
		(start 162.695636 -246.551704)
		(end 162.695382 -246.347488)
		(width 0.14478)
		(layer "In13.Cu")
		(net "M_H_CPU1_SA_CB<7>")
	)
	(segment
		(start 144.47393 -249.03049)
		(end 144.488662 -249.021854)
		(width 0.0889)
		(layer "In13.Cu")
		(net "M_H_CPU1_SA_CB<7>")
	)
	(segment
		(start 163.71316 -244.959886)
		(end 164.776912 -244.959886)
		(width 0.14478)
		(layer "In13.Cu")
		(net "M_H_CPU1_SA_CB<7>")
	)
	(segment
		(start 165.849808 -244.110002)
		(end 166.111428 -244.110002)
		(width 0.14478)
		(layer "In13.Cu")
		(net "M_H_CPU1_SA_CB<7>")
	)
	(segment
		(start 160.950656 -248.296684)
		(end 161.136076 -248.111264)
		(width 0.14478)
		(layer "In13.Cu")
		(net "M_H_CPU1_SA_CB<7>")
	)
	(segment
		(start 170.571668 -243.769896)
		(end 170.833288 -243.769896)
		(width 0.14478)
		(layer "In13.Cu")
		(net "M_H_CPU1_SA_CB<7>")
	)
	(segment
		(start 162.018218 -246.654828)
		(end 162.222942 -246.654574)
		(width 0.14478)
		(layer "In13.Cu")
		(net "M_H_CPU1_SA_CB<7>")
	)
	(segment
		(start 163.475162 -245.567708)
		(end 163.392612 -245.485158)
		(width 0.14478)
		(layer "In13.Cu")
		(net "M_H_CPU1_SA_CB<7>")
	)
	(segment
		(start 170.426888 -243.625116)
		(end 170.571668 -243.769896)
		(width 0.14478)
		(layer "In13.Cu")
		(net "M_H_CPU1_SA_CB<7>")
	)
	(segment
		(start 168.690544 -244.510306)
		(end 169.936922 -243.263928)
		(width 0.14478)
		(layer "In13.Cu")
		(net "M_H_CPU1_SA_CB<7>")
	)
	(segment
		(start 171.943268 -243.263928)
		(end 171.97197 -243.235226)
		(width 0.14478)
		(layer "In13.Cu")
		(net "M_H_CPU1_SA_CB<7>")
	)
	(segment
		(start 134.488682 -249.079004)
		(end 134.584694 -249.053604)
		(width 0.0889)
		(layer "In13.Cu")
		(net "M_H_CPU1_SA_CB<7>")
	)
	(segment
		(start 159.966152 -249.076464)
		(end 160.170876 -249.076464)
		(width 0.14478)
		(layer "In13.Cu")
		(net "M_H_CPU1_SA_CB<7>")
	)
	(segment
		(start 160.356042 -248.686828)
		(end 160.273492 -248.604278)
		(width 0.14478)
		(layer "In13.Cu")
		(net "M_H_CPU1_SA_CB<7>")
	)
	(segment
		(start 159.883602 -248.993914)
		(end 159.966152 -249.076464)
		(width 0.14478)
		(layer "In13.Cu")
		(net "M_H_CPU1_SA_CB<7>")
	)
	(segment
		(start 163.475416 -245.771924)
		(end 163.475162 -245.567708)
		(width 0.14478)
		(layer "In13.Cu")
		(net "M_H_CPU1_SA_CB<7>")
	)
	(segment
		(start 137.907776 -249.021854)
		(end 137.916158 -249.017028)
		(width 0.0889)
		(layer "In13.Cu")
		(net "M_H_CPU1_SA_CB<7>")
	)
	(segment
		(start 163.392612 -245.485158)
		(end 163.392612 -245.280434)
		(width 0.14478)
		(layer "In13.Cu")
		(net "M_H_CPU1_SA_CB<7>")
	)
	(segment
		(start 161.135822 -247.907048)
		(end 161.053272 -247.824498)
		(width 0.14478)
		(layer "In13.Cu")
		(net "M_H_CPU1_SA_CB<7>")
	)
	(segment
		(start 160.170876 -249.076464)
		(end 160.356296 -248.891044)
		(width 0.14478)
		(layer "In13.Cu")
		(net "M_H_CPU1_SA_CB<7>")
	)
	(segment
		(start 170.426888 -243.408708)
		(end 170.426888 -243.625116)
		(width 0.14478)
		(layer "In13.Cu")
		(net "M_H_CPU1_SA_CB<7>")
	)
	(segment
		(start 140.15339 -249.017028)
		(end 140.161772 -249.021854)
		(width 0.0889)
		(layer "In13.Cu")
		(net "M_H_CPU1_SA_CB<7>")
	)
	(segment
		(start 144.84858 -249.014234)
		(end 144.862296 -249.022108)
		(width 0.0889)
		(layer "In13.Cu")
		(net "M_H_CPU1_SA_CB<7>")
	)
	(segment
		(start 160.458658 -248.214388)
		(end 160.663382 -248.214134)
		(width 0.14478)
		(layer "In13.Cu")
		(net "M_H_CPU1_SA_CB<7>")
	)
	(segment
		(start 146.016218 -249.244104)
		(end 146.906488 -249.244104)
		(width 0.0889)
		(layer "In13.Cu")
		(net "M_H_CPU1_SA_CB<7>")
	)
	(segment
		(start 170.978068 -243.625116)
		(end 170.978068 -243.408708)
		(width 0.14478)
		(layer "In13.Cu")
		(net "M_H_CPU1_SA_CB<7>")
	)
	(segment
		(start 147.122388 -249.460004)
		(end 147.752054 -249.460004)
		(width 0.0889)
		(layer "In13.Cu")
		(net "M_H_CPU1_SA_CB<7>")
	)
	(segment
		(start 165.226492 -244.510306)
		(end 165.560248 -244.510306)
		(width 0.14478)
		(layer "In13.Cu")
		(net "M_H_CPU1_SA_CB<7>")
	)
	(segment
		(start 162.797998 -245.875048)
		(end 163.002722 -245.874794)
		(width 0.14478)
		(layer "In13.Cu")
		(net "M_H_CPU1_SA_CB<7>")
	)
	(segment
		(start 163.289996 -245.957344)
		(end 163.475416 -245.771924)
		(width 0.14478)
		(layer "In13.Cu")
		(net "M_H_CPU1_SA_CB<7>")
	)
	(segment
		(start 161.730436 -247.516904)
		(end 161.915856 -247.331484)
		(width 0.14478)
		(layer "In13.Cu")
		(net "M_H_CPU1_SA_CB<7>")
	)
	(segment
		(start 170.282108 -243.263928)
		(end 170.426888 -243.408708)
		(width 0.14478)
		(layer "In13.Cu")
		(net "M_H_CPU1_SA_CB<7>")
	)
	(segment
		(start 162.695382 -246.347488)
		(end 162.612832 -246.264938)
		(width 0.14478)
		(layer "In13.Cu")
		(net "M_H_CPU1_SA_CB<7>")
	)
	(arc
		(start 144.488662 -249.021854)
		(mid 144.667649 -248.971684)
		(end 144.84858 -249.014234)
		(width 0.0889)
		(layer "In13.Cu")
		(net "M_H_CPU1_SA_CB<7>")
	)
	(arc
		(start 138.84783 -249.021854)
		(mid 139.034774 -248.971599)
		(end 139.221718 -249.021854)
		(width 0.0889)
		(layer "In13.Cu")
		(net "M_H_CPU1_SA_CB<7>")
	)
	(arc
		(start 142.04188 -249.021854)
		(mid 142.324836 -249.098031)
		(end 142.607792 -249.021854)
		(width 0.0889)
		(layer "In13.Cu")
		(net "M_H_CPU1_SA_CB<7>")
	)
	(arc
		(start 134.584694 -249.053604)
		(mid 134.839902 -249.097081)
		(end 135.087614 -249.021854)
		(width 0.0889)
		(layer "In13.Cu")
		(net "M_H_CPU1_SA_CB<7>")
	)
	(arc
		(start 136.40181 -249.021854)
		(mid 136.684766 -249.098031)
		(end 136.967722 -249.021854)
		(width 0.0889)
		(layer "In13.Cu")
		(net "M_H_CPU1_SA_CB<7>")
	)
	(arc
		(start 141.101826 -249.021854)
		(mid 141.384782 -249.098031)
		(end 141.667738 -249.021854)
		(width 0.0889)
		(layer "In13.Cu")
		(net "M_H_CPU1_SA_CB<7>")
	)
	(arc
		(start 142.607792 -249.021854)
		(mid 142.794736 -248.971599)
		(end 142.98168 -249.021854)
		(width 0.0889)
		(layer "In13.Cu")
		(net "M_H_CPU1_SA_CB<7>")
	)
	(arc
		(start 142.98168 -249.021854)
		(mid 143.264636 -249.098031)
		(end 143.547592 -249.021854)
		(width 0.0889)
		(layer "In13.Cu")
		(net "M_H_CPU1_SA_CB<7>")
	)
	(arc
		(start 144.878044 -249.031252)
		(mid 145.154353 -249.098228)
		(end 145.428208 -249.021854)
		(width 0.0889)
		(layer "In13.Cu")
		(net "M_H_CPU1_SA_CB<7>")
	)
	(arc
		(start 135.087614 -249.021854)
		(mid 135.269865 -248.971504)
		(end 135.453374 -249.017028)
		(width 0.0889)
		(layer "In13.Cu")
		(net "M_H_CPU1_SA_CB<7>")
	)
	(arc
		(start 135.461756 -249.021854)
		(mid 135.744712 -249.098031)
		(end 136.027668 -249.021854)
		(width 0.0889)
		(layer "In13.Cu")
		(net "M_H_CPU1_SA_CB<7>")
	)
	(arc
		(start 139.221718 -249.021854)
		(mid 139.504674 -249.098031)
		(end 139.78763 -249.021854)
		(width 0.0889)
		(layer "In13.Cu")
		(net "M_H_CPU1_SA_CB<7>")
	)
	(arc
		(start 139.78763 -249.021854)
		(mid 139.969881 -248.971504)
		(end 140.15339 -249.017028)
		(width 0.0889)
		(layer "In13.Cu")
		(net "M_H_CPU1_SA_CB<7>")
	)
	(arc
		(start 143.555974 -249.017028)
		(mid 143.739736 -248.971412)
		(end 143.922242 -249.021854)
		(width 0.0889)
		(layer "In13.Cu")
		(net "M_H_CPU1_SA_CB<7>")
	)
	(arc
		(start 137.341864 -249.021854)
		(mid 137.62482 -249.098031)
		(end 137.907776 -249.021854)
		(width 0.0889)
		(layer "In13.Cu")
		(net "M_H_CPU1_SA_CB<7>")
	)
	(arc
		(start 136.976104 -249.017028)
		(mid 137.159612 -248.971534)
		(end 137.341864 -249.021854)
		(width 0.0889)
		(layer "In13.Cu")
		(net "M_H_CPU1_SA_CB<7>")
	)
	(arc
		(start 136.027668 -249.021854)
		(mid 136.209919 -248.971504)
		(end 136.393428 -249.017028)
		(width 0.0889)
		(layer "In13.Cu")
		(net "M_H_CPU1_SA_CB<7>")
	)
	(arc
		(start 138.281918 -249.021854)
		(mid 138.564874 -249.098031)
		(end 138.84783 -249.021854)
		(width 0.0889)
		(layer "In13.Cu")
		(net "M_H_CPU1_SA_CB<7>")
	)
	(arc
		(start 137.916158 -249.017028)
		(mid 138.099666 -248.971534)
		(end 138.281918 -249.021854)
		(width 0.0889)
		(layer "In13.Cu")
		(net "M_H_CPU1_SA_CB<7>")
	)
	(arc
		(start 140.727684 -249.021854)
		(mid 140.909935 -248.971504)
		(end 141.093444 -249.017028)
		(width 0.0889)
		(layer "In13.Cu")
		(net "M_H_CPU1_SA_CB<7>")
	)
	(arc
		(start 140.161772 -249.021854)
		(mid 140.444728 -249.098031)
		(end 140.727684 -249.021854)
		(width 0.0889)
		(layer "In13.Cu")
		(net "M_H_CPU1_SA_CB<7>")
	)
	(arc
		(start 141.67612 -249.017028)
		(mid 141.859628 -248.971534)
		(end 142.04188 -249.021854)
		(width 0.0889)
		(layer "In13.Cu")
		(net "M_H_CPU1_SA_CB<7>")
	)
	(arc
		(start 145.428208 -249.021854)
		(mid 145.610713 -248.971377)
		(end 145.794476 -249.017028)
		(width 0.0889)
		(layer "In13.Cu")
		(net "M_H_CPU1_SA_CB<7>")
	)
	(arc
		(start 143.922242 -249.021854)
		(mid 144.196948 -249.098218)
		(end 144.47393 -249.03049)
		(width 0.0889)
		(layer "In13.Cu")
		(net "M_H_CPU1_SA_CB<7>")
	)
	(segment
		(start 135.27786 -248.800366)
		(end 135.744712 -248.534428)
		(width 0.10668)
		(layer "F.Cu")
		(net "M_H_CPU1_SA_CB<6>")
	)
	(segment
		(start 147.79371 -248.543064)
		(end 147.239228 -248.543064)
		(width 0.0889)
		(layer "In13.Cu")
		(net "M_H_CPU1_SA_CB<6>")
	)
	(segment
		(start 167.467788 -242.828826)
		(end 167.467788 -242.284758)
		(width 0.14478)
		(layer "In13.Cu")
		(net "M_H_CPU1_SA_CB<6>")
	)
	(segment
		(start 166.365428 -242.284758)
		(end 166.220648 -242.139978)
		(width 0.14478)
		(layer "In13.Cu")
		(net "M_H_CPU1_SA_CB<6>")
	)
	(segment
		(start 142.51178 -248.211848)
		(end 142.503398 -248.207022)
		(width 0.0889)
		(layer "In13.Cu")
		(net "M_H_CPU1_SA_CB<6>")
	)
	(segment
		(start 169.73423 -241.679984)
		(end 169.58945 -241.535204)
		(width 0.14478)
		(layer "In13.Cu")
		(net "M_H_CPU1_SA_CB<6>")
	)
	(segment
		(start 138.751818 -248.211848)
		(end 138.743436 -248.207022)
		(width 0.0889)
		(layer "In13.Cu")
		(net "M_H_CPU1_SA_CB<6>")
	)
	(segment
		(start 170.83659 -241.679984)
		(end 170.69181 -241.535204)
		(width 0.14478)
		(layer "In13.Cu")
		(net "M_H_CPU1_SA_CB<6>")
	)
	(segment
		(start 170.28541 -242.166394)
		(end 170.14063 -242.311174)
		(width 0.14478)
		(layer "In13.Cu")
		(net "M_H_CPU1_SA_CB<6>")
	)
	(segment
		(start 166.510208 -242.973606)
		(end 166.365428 -242.828826)
		(width 0.14478)
		(layer "In13.Cu")
		(net "M_H_CPU1_SA_CB<6>")
	)
	(segment
		(start 144.958054 -248.212102)
		(end 144.952466 -248.215404)
		(width 0.0889)
		(layer "In13.Cu")
		(net "M_H_CPU1_SA_CB<6>")
	)
	(segment
		(start 167.323008 -242.139978)
		(end 167.061388 -242.139978)
		(width 0.14478)
		(layer "In13.Cu")
		(net "M_H_CPU1_SA_CB<6>")
	)
	(segment
		(start 147.155408 -248.626884)
		(end 146.098768 -248.626884)
		(width 0.0889)
		(layer "In13.Cu")
		(net "M_H_CPU1_SA_CB<6>")
	)
	(segment
		(start 165.260782 -242.139978)
		(end 159.23514 -248.16562)
		(width 0.14478)
		(layer "In13.Cu")
		(net "M_H_CPU1_SA_CB<6>")
	)
	(segment
		(start 143.086074 -248.207022)
		(end 143.077692 -248.211848)
		(width 0.0889)
		(layer "In13.Cu")
		(net "M_H_CPU1_SA_CB<6>")
	)
	(segment
		(start 170.43019 -241.535204)
		(end 170.28541 -241.679984)
		(width 0.14478)
		(layer "In13.Cu")
		(net "M_H_CPU1_SA_CB<6>")
	)
	(segment
		(start 170.98137 -242.311174)
		(end 170.83659 -242.166394)
		(width 0.14478)
		(layer "In13.Cu")
		(net "M_H_CPU1_SA_CB<6>")
	)
	(segment
		(start 169.73423 -242.166394)
		(end 169.73423 -241.679984)
		(width 0.14478)
		(layer "In13.Cu")
		(net "M_H_CPU1_SA_CB<6>")
	)
	(segment
		(start 166.916608 -242.284758)
		(end 166.916608 -242.828826)
		(width 0.14478)
		(layer "In13.Cu")
		(net "M_H_CPU1_SA_CB<6>")
	)
	(segment
		(start 166.220648 -242.139978)
		(end 165.260782 -242.139978)
		(width 0.14478)
		(layer "In13.Cu")
		(net "M_H_CPU1_SA_CB<6>")
	)
	(segment
		(start 147.239228 -248.543064)
		(end 147.155408 -248.626884)
		(width 0.0889)
		(layer "In13.Cu")
		(net "M_H_CPU1_SA_CB<6>")
	)
	(segment
		(start 170.28541 -241.679984)
		(end 170.28541 -242.166394)
		(width 0.14478)
		(layer "In13.Cu")
		(net "M_H_CPU1_SA_CB<6>")
	)
	(segment
		(start 159.23514 -248.16562)
		(end 148.960332 -248.16562)
		(width 0.14478)
		(layer "In13.Cu")
		(net "M_H_CPU1_SA_CB<6>")
	)
	(segment
		(start 170.69181 -241.535204)
		(end 170.43019 -241.535204)
		(width 0.14478)
		(layer "In13.Cu")
		(net "M_H_CPU1_SA_CB<6>")
	)
	(segment
		(start 139.326112 -248.207022)
		(end 139.31773 -248.211848)
		(width 0.0889)
		(layer "In13.Cu")
		(net "M_H_CPU1_SA_CB<6>")
	)
	(segment
		(start 144.976342 -248.201688)
		(end 144.958054 -248.212102)
		(width 0.0889)
		(layer "In13.Cu")
		(net "M_H_CPU1_SA_CB<6>")
	)
	(segment
		(start 167.612568 -242.973606)
		(end 167.467788 -242.828826)
		(width 0.14478)
		(layer "In13.Cu")
		(net "M_H_CPU1_SA_CB<6>")
	)
	(segment
		(start 167.467788 -242.284758)
		(end 167.323008 -242.139978)
		(width 0.14478)
		(layer "In13.Cu")
		(net "M_H_CPU1_SA_CB<6>")
	)
	(segment
		(start 137.811764 -248.211848)
		(end 137.803382 -248.207022)
		(width 0.0889)
		(layer "In13.Cu")
		(net "M_H_CPU1_SA_CB<6>")
	)
	(segment
		(start 145.956528 -248.484644)
		(end 145.725896 -248.484644)
		(width 0.0889)
		(layer "In13.Cu")
		(net "M_H_CPU1_SA_CB<6>")
	)
	(segment
		(start 168.018968 -242.828826)
		(end 167.874188 -242.973606)
		(width 0.14478)
		(layer "In13.Cu")
		(net "M_H_CPU1_SA_CB<6>")
	)
	(segment
		(start 169.87901 -242.311174)
		(end 169.73423 -242.166394)
		(width 0.14478)
		(layer "In13.Cu")
		(net "M_H_CPU1_SA_CB<6>")
	)
	(segment
		(start 171.38777 -241.679984)
		(end 171.38777 -242.166394)
		(width 0.14478)
		(layer "In13.Cu")
		(net "M_H_CPU1_SA_CB<6>")
	)
	(segment
		(start 171.24299 -242.311174)
		(end 170.98137 -242.311174)
		(width 0.14478)
		(layer "In13.Cu")
		(net "M_H_CPU1_SA_CB<6>")
	)
	(segment
		(start 145.725896 -248.484644)
		(end 145.52168 -248.280428)
		(width 0.0889)
		(layer "In13.Cu")
		(net "M_H_CPU1_SA_CB<6>")
	)
	(segment
		(start 135.89889 -248.268998)
		(end 135.744712 -248.534428)
		(width 0.0889)
		(layer "In13.Cu")
		(net "M_H_CPU1_SA_CB<6>")
	)
	(segment
		(start 140.266166 -248.207022)
		(end 140.257784 -248.211848)
		(width 0.0889)
		(layer "In13.Cu")
		(net "M_H_CPU1_SA_CB<6>")
	)
	(segment
		(start 171.38777 -242.166394)
		(end 171.24299 -242.311174)
		(width 0.14478)
		(layer "In13.Cu")
		(net "M_H_CPU1_SA_CB<6>")
	)
	(segment
		(start 171.53255 -241.535204)
		(end 171.38777 -241.679984)
		(width 0.14478)
		(layer "In13.Cu")
		(net "M_H_CPU1_SA_CB<6>")
	)
	(segment
		(start 168.510712 -242.139978)
		(end 168.163748 -242.139978)
		(width 0.14478)
		(layer "In13.Cu")
		(net "M_H_CPU1_SA_CB<6>")
	)
	(segment
		(start 167.874188 -242.973606)
		(end 167.612568 -242.973606)
		(width 0.14478)
		(layer "In13.Cu")
		(net "M_H_CPU1_SA_CB<6>")
	)
	(segment
		(start 135.995156 -248.243598)
		(end 135.89889 -248.268998)
		(width 0.0889)
		(layer "In13.Cu")
		(net "M_H_CPU1_SA_CB<6>")
	)
	(segment
		(start 169.58945 -241.535204)
		(end 169.115486 -241.535204)
		(width 0.14478)
		(layer "In13.Cu")
		(net "M_H_CPU1_SA_CB<6>")
	)
	(segment
		(start 148.582888 -248.543064)
		(end 147.79371 -248.543064)
		(width 0.14478)
		(layer "In13.Cu")
		(net "M_H_CPU1_SA_CB<6>")
	)
	(segment
		(start 170.14063 -242.311174)
		(end 169.87901 -242.311174)
		(width 0.14478)
		(layer "In13.Cu")
		(net "M_H_CPU1_SA_CB<6>")
	)
	(segment
		(start 166.771828 -242.973606)
		(end 166.510208 -242.973606)
		(width 0.14478)
		(layer "In13.Cu")
		(net "M_H_CPU1_SA_CB<6>")
	)
	(segment
		(start 170.83659 -242.166394)
		(end 170.83659 -241.679984)
		(width 0.14478)
		(layer "In13.Cu")
		(net "M_H_CPU1_SA_CB<6>")
	)
	(segment
		(start 166.365428 -242.828826)
		(end 166.365428 -242.284758)
		(width 0.14478)
		(layer "In13.Cu")
		(net "M_H_CPU1_SA_CB<6>")
	)
	(segment
		(start 143.462248 -248.217944)
		(end 143.451834 -248.211848)
		(width 0.0889)
		(layer "In13.Cu")
		(net "M_H_CPU1_SA_CB<6>")
	)
	(segment
		(start 169.115486 -241.535204)
		(end 168.510712 -242.139978)
		(width 0.14478)
		(layer "In13.Cu")
		(net "M_H_CPU1_SA_CB<6>")
	)
	(segment
		(start 166.916608 -242.828826)
		(end 166.771828 -242.973606)
		(width 0.14478)
		(layer "In13.Cu")
		(net "M_H_CPU1_SA_CB<6>")
	)
	(segment
		(start 171.97197 -241.535204)
		(end 171.53255 -241.535204)
		(width 0.14478)
		(layer "In13.Cu")
		(net "M_H_CPU1_SA_CB<6>")
	)
	(segment
		(start 148.960332 -248.16562)
		(end 148.582888 -248.543064)
		(width 0.14478)
		(layer "In13.Cu")
		(net "M_H_CPU1_SA_CB<6>")
	)
	(segment
		(start 144.39265 -248.211848)
		(end 144.384268 -248.207022)
		(width 0.0889)
		(layer "In13.Cu")
		(net "M_H_CPU1_SA_CB<6>")
	)
	(segment
		(start 167.061388 -242.139978)
		(end 166.916608 -242.284758)
		(width 0.14478)
		(layer "In13.Cu")
		(net "M_H_CPU1_SA_CB<6>")
	)
	(segment
		(start 168.163748 -242.139978)
		(end 168.018968 -242.284758)
		(width 0.14478)
		(layer "In13.Cu")
		(net "M_H_CPU1_SA_CB<6>")
	)
	(segment
		(start 168.018968 -242.284758)
		(end 168.018968 -242.828826)
		(width 0.14478)
		(layer "In13.Cu")
		(net "M_H_CPU1_SA_CB<6>")
	)
	(segment
		(start 146.098768 -248.626884)
		(end 145.956528 -248.484644)
		(width 0.0889)
		(layer "In13.Cu")
		(net "M_H_CPU1_SA_CB<6>")
	)
	(arc
		(start 142.503398 -248.207022)
		(mid 142.31989 -248.161528)
		(end 142.137638 -248.211848)
		(width 0.0889)
		(layer "In13.Cu")
		(net "M_H_CPU1_SA_CB<6>")
	)
	(arc
		(start 143.077692 -248.211848)
		(mid 142.794736 -248.288025)
		(end 142.51178 -248.211848)
		(width 0.0889)
		(layer "In13.Cu")
		(net "M_H_CPU1_SA_CB<6>")
	)
	(arc
		(start 144.384268 -248.207022)
		(mid 144.200506 -248.161406)
		(end 144.018 -248.211848)
		(width 0.0889)
		(layer "In13.Cu")
		(net "M_H_CPU1_SA_CB<6>")
	)
	(arc
		(start 139.31773 -248.211848)
		(mid 139.034774 -248.288025)
		(end 138.751818 -248.211848)
		(width 0.0889)
		(layer "In13.Cu")
		(net "M_H_CPU1_SA_CB<6>")
	)
	(arc
		(start 137.437622 -248.211848)
		(mid 137.154666 -248.288025)
		(end 136.87171 -248.211848)
		(width 0.0889)
		(layer "In13.Cu")
		(net "M_H_CPU1_SA_CB<6>")
	)
	(arc
		(start 138.377676 -248.211848)
		(mid 138.09472 -248.288025)
		(end 137.811764 -248.211848)
		(width 0.0889)
		(layer "In13.Cu")
		(net "M_H_CPU1_SA_CB<6>")
	)
	(arc
		(start 145.332196 -248.211848)
		(mid 145.155568 -248.161615)
		(end 144.976342 -248.201688)
		(width 0.0889)
		(layer "In13.Cu")
		(net "M_H_CPU1_SA_CB<6>")
	)
	(arc
		(start 145.52168 -248.280428)
		(mid 145.423842 -248.254687)
		(end 145.332196 -248.211848)
		(width 0.0889)
		(layer "In13.Cu")
		(net "M_H_CPU1_SA_CB<6>")
	)
	(arc
		(start 144.018 -248.211848)
		(mid 143.740933 -248.288119)
		(end 143.462248 -248.217944)
		(width 0.0889)
		(layer "In13.Cu")
		(net "M_H_CPU1_SA_CB<6>")
	)
	(arc
		(start 138.743436 -248.207022)
		(mid 138.559928 -248.161528)
		(end 138.377676 -248.211848)
		(width 0.0889)
		(layer "In13.Cu")
		(net "M_H_CPU1_SA_CB<6>")
	)
	(arc
		(start 136.87171 -248.211848)
		(mid 136.684766 -248.161593)
		(end 136.497822 -248.211848)
		(width 0.0889)
		(layer "In13.Cu")
		(net "M_H_CPU1_SA_CB<6>")
	)
	(arc
		(start 143.451834 -248.211848)
		(mid 143.269583 -248.161498)
		(end 143.086074 -248.207022)
		(width 0.0889)
		(layer "In13.Cu")
		(net "M_H_CPU1_SA_CB<6>")
	)
	(arc
		(start 141.571726 -248.211848)
		(mid 141.384782 -248.161593)
		(end 141.197838 -248.211848)
		(width 0.0889)
		(layer "In13.Cu")
		(net "M_H_CPU1_SA_CB<6>")
	)
	(arc
		(start 144.952466 -248.215404)
		(mid 144.672077 -248.288073)
		(end 144.39265 -248.211848)
		(width 0.0889)
		(layer "In13.Cu")
		(net "M_H_CPU1_SA_CB<6>")
	)
	(arc
		(start 140.631926 -248.211848)
		(mid 140.449675 -248.161498)
		(end 140.266166 -248.207022)
		(width 0.0889)
		(layer "In13.Cu")
		(net "M_H_CPU1_SA_CB<6>")
	)
	(arc
		(start 141.197838 -248.211848)
		(mid 140.914882 -248.288025)
		(end 140.631926 -248.211848)
		(width 0.0889)
		(layer "In13.Cu")
		(net "M_H_CPU1_SA_CB<6>")
	)
	(arc
		(start 139.691872 -248.211848)
		(mid 139.509621 -248.161498)
		(end 139.326112 -248.207022)
		(width 0.0889)
		(layer "In13.Cu")
		(net "M_H_CPU1_SA_CB<6>")
	)
	(arc
		(start 142.137638 -248.211848)
		(mid 141.854682 -248.288025)
		(end 141.571726 -248.211848)
		(width 0.0889)
		(layer "In13.Cu")
		(net "M_H_CPU1_SA_CB<6>")
	)
	(arc
		(start 136.497822 -248.211848)
		(mid 136.250226 -248.287026)
		(end 135.995156 -248.243598)
		(width 0.0889)
		(layer "In13.Cu")
		(net "M_H_CPU1_SA_CB<6>")
	)
	(arc
		(start 140.257784 -248.211848)
		(mid 139.974828 -248.288025)
		(end 139.691872 -248.211848)
		(width 0.0889)
		(layer "In13.Cu")
		(net "M_H_CPU1_SA_CB<6>")
	)
	(arc
		(start 137.803382 -248.207022)
		(mid 137.619874 -248.161528)
		(end 137.437622 -248.211848)
		(width 0.0889)
		(layer "In13.Cu")
		(net "M_H_CPU1_SA_CB<6>")
	)
	(segment
		(start 134.337806 -248.800366)
		(end 134.804658 -248.534428)
		(width 0.10668)
		(layer "F.Cu")
		(net "M_H_CPU1_SA_CB<5>")
	)
	(segment
		(start 138.743436 -248.861834)
		(end 138.751818 -248.857008)
		(width 0.0889)
		(layer "In13.Cu")
		(net "M_H_CPU1_SA_CB<5>")
	)
	(segment
		(start 140.257784 -248.857008)
		(end 140.266166 -248.861834)
		(width 0.0889)
		(layer "In13.Cu")
		(net "M_H_CPU1_SA_CB<5>")
	)
	(segment
		(start 149.016466 -248.767346)
		(end 159.26943 -248.767346)
		(width 0.14478)
		(layer "In13.Cu")
		(net "M_H_CPU1_SA_CB<5>")
	)
	(segment
		(start 148.781008 -249.002804)
		(end 149.016466 -248.767346)
		(width 0.14478)
		(layer "In13.Cu")
		(net "M_H_CPU1_SA_CB<5>")
	)
	(segment
		(start 144.958054 -248.856754)
		(end 144.976342 -248.867168)
		(width 0.0889)
		(layer "In13.Cu")
		(net "M_H_CPU1_SA_CB<5>")
	)
	(segment
		(start 137.803382 -248.861834)
		(end 137.811764 -248.857008)
		(width 0.0889)
		(layer "In13.Cu")
		(net "M_H_CPU1_SA_CB<5>")
	)
	(segment
		(start 159.26943 -248.767346)
		(end 163.52647 -244.510306)
		(width 0.14478)
		(layer "In13.Cu")
		(net "M_H_CPU1_SA_CB<5>")
	)
	(segment
		(start 145.883884 -248.848372)
		(end 146.056858 -248.941844)
		(width 0.0889)
		(layer "In13.Cu")
		(net "M_H_CPU1_SA_CB<5>")
	)
	(segment
		(start 143.077692 -248.857008)
		(end 143.086074 -248.861834)
		(width 0.0889)
		(layer "In13.Cu")
		(net "M_H_CPU1_SA_CB<5>")
	)
	(segment
		(start 169.672 -242.814348)
		(end 173.536356 -242.814348)
		(width 0.14478)
		(layer "In13.Cu")
		(net "M_H_CPU1_SA_CB<5>")
	)
	(segment
		(start 147.394168 -248.941844)
		(end 147.455128 -249.002804)
		(width 0.0889)
		(layer "In13.Cu")
		(net "M_H_CPU1_SA_CB<5>")
	)
	(segment
		(start 144.380966 -248.863866)
		(end 144.39265 -248.857008)
		(width 0.0889)
		(layer "In13.Cu")
		(net "M_H_CPU1_SA_CB<5>")
	)
	(segment
		(start 143.451834 -248.857008)
		(end 143.466566 -248.848372)
		(width 0.0889)
		(layer "In13.Cu")
		(net "M_H_CPU1_SA_CB<5>")
	)
	(segment
		(start 163.52647 -244.510306)
		(end 164.590476 -244.510306)
		(width 0.14478)
		(layer "In13.Cu")
		(net "M_H_CPU1_SA_CB<5>")
	)
	(segment
		(start 142.503398 -248.861834)
		(end 142.51178 -248.857008)
		(width 0.0889)
		(layer "In13.Cu")
		(net "M_H_CPU1_SA_CB<5>")
	)
	(segment
		(start 147.828254 -249.002804)
		(end 148.781008 -249.002804)
		(width 0.14478)
		(layer "In13.Cu")
		(net "M_H_CPU1_SA_CB<5>")
	)
	(segment
		(start 135.557768 -248.857008)
		(end 135.56615 -248.861834)
		(width 0.0889)
		(layer "In13.Cu")
		(net "M_H_CPU1_SA_CB<5>")
	)
	(segment
		(start 165.44036 -243.660422)
		(end 168.825926 -243.660422)
		(width 0.14478)
		(layer "In13.Cu")
		(net "M_H_CPU1_SA_CB<5>")
	)
	(segment
		(start 146.056858 -248.941844)
		(end 147.394168 -248.941844)
		(width 0.0889)
		(layer "In13.Cu")
		(net "M_H_CPU1_SA_CB<5>")
	)
	(segment
		(start 168.825926 -243.660422)
		(end 169.672 -242.814348)
		(width 0.14478)
		(layer "In13.Cu")
		(net "M_H_CPU1_SA_CB<5>")
	)
	(segment
		(start 139.31773 -248.857008)
		(end 139.326112 -248.861834)
		(width 0.0889)
		(layer "In13.Cu")
		(net "M_H_CPU1_SA_CB<5>")
	)
	(segment
		(start 134.804658 -248.534428)
		(end 134.650734 -248.799858)
		(width 0.0889)
		(layer "In13.Cu")
		(net "M_H_CPU1_SA_CB<5>")
	)
	(segment
		(start 164.590476 -244.510306)
		(end 165.44036 -243.660422)
		(width 0.14478)
		(layer "In13.Cu")
		(net "M_H_CPU1_SA_CB<5>")
	)
	(segment
		(start 134.650734 -248.799858)
		(end 134.673086 -248.88317)
		(width 0.0889)
		(layer "In13.Cu")
		(net "M_H_CPU1_SA_CB<5>")
	)
	(segment
		(start 144.952466 -248.853452)
		(end 144.958054 -248.856754)
		(width 0.0889)
		(layer "In13.Cu")
		(net "M_H_CPU1_SA_CB<5>")
	)
	(segment
		(start 173.536356 -242.814348)
		(end 173.965362 -242.385342)
		(width 0.14478)
		(layer "In13.Cu")
		(net "M_H_CPU1_SA_CB<5>")
	)
	(segment
		(start 173.965362 -242.385342)
		(end 176.072038 -242.385342)
		(width 0.14478)
		(layer "In13.Cu")
		(net "M_H_CPU1_SA_CB<5>")
	)
	(segment
		(start 147.455128 -249.002804)
		(end 147.828254 -249.002804)
		(width 0.0889)
		(layer "In13.Cu")
		(net "M_H_CPU1_SA_CB<5>")
	)
	(arc
		(start 140.266166 -248.861834)
		(mid 140.449674 -248.907328)
		(end 140.631926 -248.857008)
		(width 0.0889)
		(layer "In13.Cu")
		(net "M_H_CPU1_SA_CB<5>")
	)
	(arc
		(start 144.018254 -248.857008)
		(mid 144.198712 -248.907452)
		(end 144.380966 -248.863866)
		(width 0.0889)
		(layer "In13.Cu")
		(net "M_H_CPU1_SA_CB<5>")
	)
	(arc
		(start 142.137638 -248.857008)
		(mid 142.319889 -248.907358)
		(end 142.503398 -248.861834)
		(width 0.0889)
		(layer "In13.Cu")
		(net "M_H_CPU1_SA_CB<5>")
	)
	(arc
		(start 135.56615 -248.861834)
		(mid 135.749658 -248.907328)
		(end 135.93191 -248.857008)
		(width 0.0889)
		(layer "In13.Cu")
		(net "M_H_CPU1_SA_CB<5>")
	)
	(arc
		(start 136.497822 -248.857008)
		(mid 136.684766 -248.907263)
		(end 136.87171 -248.857008)
		(width 0.0889)
		(layer "In13.Cu")
		(net "M_H_CPU1_SA_CB<5>")
	)
	(arc
		(start 136.87171 -248.857008)
		(mid 137.154666 -248.780831)
		(end 137.437622 -248.857008)
		(width 0.0889)
		(layer "In13.Cu")
		(net "M_H_CPU1_SA_CB<5>")
	)
	(arc
		(start 141.197838 -248.857008)
		(mid 141.384782 -248.907263)
		(end 141.571726 -248.857008)
		(width 0.0889)
		(layer "In13.Cu")
		(net "M_H_CPU1_SA_CB<5>")
	)
	(arc
		(start 145.332196 -248.857008)
		(mid 145.606902 -248.780644)
		(end 145.883884 -248.848372)
		(width 0.0889)
		(layer "In13.Cu")
		(net "M_H_CPU1_SA_CB<5>")
	)
	(arc
		(start 138.751818 -248.857008)
		(mid 139.034774 -248.780831)
		(end 139.31773 -248.857008)
		(width 0.0889)
		(layer "In13.Cu")
		(net "M_H_CPU1_SA_CB<5>")
	)
	(arc
		(start 143.466566 -248.848372)
		(mid 143.743549 -248.780568)
		(end 144.018254 -248.857008)
		(width 0.0889)
		(layer "In13.Cu")
		(net "M_H_CPU1_SA_CB<5>")
	)
	(arc
		(start 144.39265 -248.857008)
		(mid 144.672078 -248.780842)
		(end 144.952466 -248.853452)
		(width 0.0889)
		(layer "In13.Cu")
		(net "M_H_CPU1_SA_CB<5>")
	)
	(arc
		(start 138.377676 -248.857008)
		(mid 138.559927 -248.907358)
		(end 138.743436 -248.861834)
		(width 0.0889)
		(layer "In13.Cu")
		(net "M_H_CPU1_SA_CB<5>")
	)
	(arc
		(start 140.631926 -248.857008)
		(mid 140.914882 -248.780831)
		(end 141.197838 -248.857008)
		(width 0.0889)
		(layer "In13.Cu")
		(net "M_H_CPU1_SA_CB<5>")
	)
	(arc
		(start 139.691872 -248.857008)
		(mid 139.974828 -248.780831)
		(end 140.257784 -248.857008)
		(width 0.0889)
		(layer "In13.Cu")
		(net "M_H_CPU1_SA_CB<5>")
	)
	(arc
		(start 142.51178 -248.857008)
		(mid 142.794736 -248.780831)
		(end 143.077692 -248.857008)
		(width 0.0889)
		(layer "In13.Cu")
		(net "M_H_CPU1_SA_CB<5>")
	)
	(arc
		(start 134.673086 -248.88317)
		(mid 134.835418 -248.905988)
		(end 134.991856 -248.857008)
		(width 0.0889)
		(layer "In13.Cu")
		(net "M_H_CPU1_SA_CB<5>")
	)
	(arc
		(start 134.991856 -248.857008)
		(mid 135.274812 -248.780831)
		(end 135.557768 -248.857008)
		(width 0.0889)
		(layer "In13.Cu")
		(net "M_H_CPU1_SA_CB<5>")
	)
	(arc
		(start 144.976342 -248.867168)
		(mid 145.155571 -248.907321)
		(end 145.332196 -248.857008)
		(width 0.0889)
		(layer "In13.Cu")
		(net "M_H_CPU1_SA_CB<5>")
	)
	(arc
		(start 139.326112 -248.861834)
		(mid 139.50962 -248.907328)
		(end 139.691872 -248.857008)
		(width 0.0889)
		(layer "In13.Cu")
		(net "M_H_CPU1_SA_CB<5>")
	)
	(arc
		(start 137.437622 -248.857008)
		(mid 137.619873 -248.907358)
		(end 137.803382 -248.861834)
		(width 0.0889)
		(layer "In13.Cu")
		(net "M_H_CPU1_SA_CB<5>")
	)
	(arc
		(start 143.086074 -248.861834)
		(mid 143.269582 -248.907328)
		(end 143.451834 -248.857008)
		(width 0.0889)
		(layer "In13.Cu")
		(net "M_H_CPU1_SA_CB<5>")
	)
	(arc
		(start 135.93191 -248.857008)
		(mid 136.214866 -248.780831)
		(end 136.497822 -248.857008)
		(width 0.0889)
		(layer "In13.Cu")
		(net "M_H_CPU1_SA_CB<5>")
	)
	(arc
		(start 137.811764 -248.857008)
		(mid 138.09472 -248.780831)
		(end 138.377676 -248.857008)
		(width 0.0889)
		(layer "In13.Cu")
		(net "M_H_CPU1_SA_CB<5>")
	)
	(arc
		(start 141.571726 -248.857008)
		(mid 141.854682 -248.780831)
		(end 142.137638 -248.857008)
		(width 0.0889)
		(layer "In13.Cu")
		(net "M_H_CPU1_SA_CB<5>")
	)
	(segment
		(start 135.748014 -247.99036)
		(end 136.214866 -247.724422)
		(width 0.10668)
		(layer "F.Cu")
		(net "M_H_CPU1_SA_CB<4>")
	)
	(segment
		(start 166.497508 -241.545618)
		(end 166.642288 -241.690398)
		(width 0.14478)
		(layer "In13.Cu")
		(net "M_H_CPU1_SA_CB<4>")
	)
	(segment
		(start 136.060688 -247.989852)
		(end 136.08304 -248.073164)
		(width 0.0889)
		(layer "In13.Cu")
		(net "M_H_CPU1_SA_CB<4>")
	)
	(segment
		(start 165.844728 -241.545618)
		(end 165.844728 -241.464846)
		(width 0.14478)
		(layer "In13.Cu")
		(net "M_H_CPU1_SA_CB<4>")
	)
	(segment
		(start 167.005508 -241.690398)
		(end 167.150288 -241.545618)
		(width 0.14478)
		(layer "In13.Cu")
		(net "M_H_CPU1_SA_CB<4>")
	)
	(segment
		(start 173.7995 -241.277648)
		(end 174.391828 -240.68532)
		(width 0.14478)
		(layer "In13.Cu")
		(net "M_H_CPU1_SA_CB<4>")
	)
	(segment
		(start 165.047168 -241.320066)
		(end 165.191948 -241.464846)
		(width 0.14478)
		(layer "In13.Cu")
		(net "M_H_CPU1_SA_CB<4>")
	)
	(segment
		(start 165.336728 -241.690398)
		(end 165.699948 -241.690398)
		(width 0.14478)
		(layer "In13.Cu")
		(net "M_H_CPU1_SA_CB<4>")
	)
	(segment
		(start 166.352728 -241.320066)
		(end 166.497508 -241.464846)
		(width 0.14478)
		(layer "In13.Cu")
		(net "M_H_CPU1_SA_CB<4>")
	)
	(segment
		(start 158.35884 -247.71604)
		(end 164.754814 -241.320066)
		(width 0.14478)
		(layer "In13.Cu")
		(net "M_H_CPU1_SA_CB<4>")
	)
	(segment
		(start 141.093444 -248.051828)
		(end 141.101826 -248.047002)
		(width 0.0889)
		(layer "In13.Cu")
		(net "M_H_CPU1_SA_CB<4>")
	)
	(segment
		(start 148.387308 -248.083324)
		(end 148.754592 -247.71604)
		(width 0.14478)
		(layer "In13.Cu")
		(net "M_H_CPU1_SA_CB<4>")
	)
	(segment
		(start 140.15339 -248.051828)
		(end 140.161772 -248.047002)
		(width 0.0889)
		(layer "In13.Cu")
		(net "M_H_CPU1_SA_CB<4>")
	)
	(segment
		(start 136.214866 -247.724422)
		(end 136.060688 -247.989852)
		(width 0.0889)
		(layer "In13.Cu")
		(net "M_H_CPU1_SA_CB<4>")
	)
	(segment
		(start 164.754814 -241.320066)
		(end 165.047168 -241.320066)
		(width 0.14478)
		(layer "In13.Cu")
		(net "M_H_CPU1_SA_CB<4>")
	)
	(segment
		(start 166.497508 -241.464846)
		(end 166.497508 -241.545618)
		(width 0.14478)
		(layer "In13.Cu")
		(net "M_H_CPU1_SA_CB<4>")
	)
	(segment
		(start 167.150288 -241.545618)
		(end 167.150288 -241.183414)
		(width 0.14478)
		(layer "In13.Cu")
		(net "M_H_CPU1_SA_CB<4>")
	)
	(segment
		(start 144.477994 -248.040906)
		(end 144.488408 -248.047002)
		(width 0.0889)
		(layer "In13.Cu")
		(net "M_H_CPU1_SA_CB<4>")
	)
	(segment
		(start 165.844728 -241.464846)
		(end 165.989508 -241.320066)
		(width 0.14478)
		(layer "In13.Cu")
		(net "M_H_CPU1_SA_CB<4>")
	)
	(segment
		(start 174.391828 -240.68532)
		(end 176.072038 -240.68532)
		(width 0.14478)
		(layer "In13.Cu")
		(net "M_H_CPU1_SA_CB<4>")
	)
	(segment
		(start 144.84604 -248.056146)
		(end 144.862296 -248.046748)
		(width 0.0889)
		(layer "In13.Cu")
		(net "M_H_CPU1_SA_CB<4>")
	)
	(segment
		(start 165.191948 -241.545618)
		(end 165.336728 -241.690398)
		(width 0.14478)
		(layer "In13.Cu")
		(net "M_H_CPU1_SA_CB<4>")
	)
	(segment
		(start 136.967722 -248.047002)
		(end 136.976104 -248.051828)
		(width 0.0889)
		(layer "In13.Cu")
		(net "M_H_CPU1_SA_CB<4>")
	)
	(segment
		(start 146.966178 -248.353834)
		(end 147.236688 -248.083324)
		(width 0.0889)
		(layer "In13.Cu")
		(net "M_H_CPU1_SA_CB<4>")
	)
	(segment
		(start 167.150288 -241.183414)
		(end 167.576754 -240.756948)
		(width 0.14478)
		(layer "In13.Cu")
		(net "M_H_CPU1_SA_CB<4>")
	)
	(segment
		(start 165.989508 -241.320066)
		(end 166.352728 -241.320066)
		(width 0.14478)
		(layer "In13.Cu")
		(net "M_H_CPU1_SA_CB<4>")
	)
	(segment
		(start 167.576754 -240.756948)
		(end 172.3644 -240.756948)
		(width 0.14478)
		(layer "In13.Cu")
		(net "M_H_CPU1_SA_CB<4>")
	)
	(segment
		(start 145.744946 -248.230644)
		(end 146.187668 -248.230644)
		(width 0.0889)
		(layer "In13.Cu")
		(net "M_H_CPU1_SA_CB<4>")
	)
	(segment
		(start 141.667738 -248.047002)
		(end 141.67612 -248.051828)
		(width 0.0889)
		(layer "In13.Cu")
		(net "M_H_CPU1_SA_CB<4>")
	)
	(segment
		(start 147.236688 -248.083324)
		(end 147.79371 -248.083324)
		(width 0.0889)
		(layer "In13.Cu")
		(net "M_H_CPU1_SA_CB<4>")
	)
	(segment
		(start 143.547592 -248.047002)
		(end 143.555974 -248.051828)
		(width 0.0889)
		(layer "In13.Cu")
		(net "M_H_CPU1_SA_CB<4>")
	)
	(segment
		(start 147.79371 -248.083324)
		(end 148.387308 -248.083324)
		(width 0.14478)
		(layer "In13.Cu")
		(net "M_H_CPU1_SA_CB<4>")
	)
	(segment
		(start 144.862296 -248.046748)
		(end 144.878044 -248.037604)
		(width 0.0889)
		(layer "In13.Cu")
		(net "M_H_CPU1_SA_CB<4>")
	)
	(segment
		(start 145.428208 -248.047002)
		(end 145.427954 -248.047002)
		(width 0.0889)
		(layer "In13.Cu")
		(net "M_H_CPU1_SA_CB<4>")
	)
	(segment
		(start 172.3644 -240.756948)
		(end 172.8851 -241.277648)
		(width 0.14478)
		(layer "In13.Cu")
		(net "M_H_CPU1_SA_CB<4>")
	)
	(segment
		(start 146.187668 -248.230644)
		(end 146.310858 -248.353834)
		(width 0.0889)
		(layer "In13.Cu")
		(net "M_H_CPU1_SA_CB<4>")
	)
	(segment
		(start 148.754592 -247.71604)
		(end 158.35884 -247.71604)
		(width 0.14478)
		(layer "In13.Cu")
		(net "M_H_CPU1_SA_CB<4>")
	)
	(segment
		(start 165.699948 -241.690398)
		(end 165.844728 -241.545618)
		(width 0.14478)
		(layer "In13.Cu")
		(net "M_H_CPU1_SA_CB<4>")
	)
	(segment
		(start 146.310858 -248.353834)
		(end 146.966178 -248.353834)
		(width 0.0889)
		(layer "In13.Cu")
		(net "M_H_CPU1_SA_CB<4>")
	)
	(segment
		(start 165.191948 -241.464846)
		(end 165.191948 -241.545618)
		(width 0.14478)
		(layer "In13.Cu")
		(net "M_H_CPU1_SA_CB<4>")
	)
	(segment
		(start 145.612104 -248.097802)
		(end 145.744946 -248.230644)
		(width 0.0889)
		(layer "In13.Cu")
		(net "M_H_CPU1_SA_CB<4>")
	)
	(segment
		(start 172.8851 -241.277648)
		(end 173.7995 -241.277648)
		(width 0.14478)
		(layer "In13.Cu")
		(net "M_H_CPU1_SA_CB<4>")
	)
	(segment
		(start 137.907776 -248.047002)
		(end 137.916158 -248.051828)
		(width 0.0889)
		(layer "In13.Cu")
		(net "M_H_CPU1_SA_CB<4>")
	)
	(segment
		(start 136.393428 -248.051828)
		(end 136.40181 -248.047002)
		(width 0.0889)
		(layer "In13.Cu")
		(net "M_H_CPU1_SA_CB<4>")
	)
	(segment
		(start 166.642288 -241.690398)
		(end 167.005508 -241.690398)
		(width 0.14478)
		(layer "In13.Cu")
		(net "M_H_CPU1_SA_CB<4>")
	)
	(arc
		(start 142.98168 -248.047002)
		(mid 143.264636 -247.970825)
		(end 143.547592 -248.047002)
		(width 0.0889)
		(layer "In13.Cu")
		(net "M_H_CPU1_SA_CB<4>")
	)
	(arc
		(start 143.555974 -248.051828)
		(mid 143.739736 -248.097444)
		(end 143.922242 -248.047002)
		(width 0.0889)
		(layer "In13.Cu")
		(net "M_H_CPU1_SA_CB<4>")
	)
	(arc
		(start 137.916158 -248.051828)
		(mid 138.099666 -248.097322)
		(end 138.281918 -248.047002)
		(width 0.0889)
		(layer "In13.Cu")
		(net "M_H_CPU1_SA_CB<4>")
	)
	(arc
		(start 140.161772 -248.047002)
		(mid 140.444728 -247.970825)
		(end 140.727684 -248.047002)
		(width 0.0889)
		(layer "In13.Cu")
		(net "M_H_CPU1_SA_CB<4>")
	)
	(arc
		(start 138.281918 -248.047002)
		(mid 138.564874 -247.970825)
		(end 138.84783 -248.047002)
		(width 0.0889)
		(layer "In13.Cu")
		(net "M_H_CPU1_SA_CB<4>")
	)
	(arc
		(start 138.84783 -248.047002)
		(mid 139.034774 -248.097257)
		(end 139.221718 -248.047002)
		(width 0.0889)
		(layer "In13.Cu")
		(net "M_H_CPU1_SA_CB<4>")
	)
	(arc
		(start 143.922242 -248.047002)
		(mid 144.199309 -247.970731)
		(end 144.477994 -248.040906)
		(width 0.0889)
		(layer "In13.Cu")
		(net "M_H_CPU1_SA_CB<4>")
	)
	(arc
		(start 142.04188 -248.047002)
		(mid 142.324836 -247.970825)
		(end 142.607792 -248.047002)
		(width 0.0889)
		(layer "In13.Cu")
		(net "M_H_CPU1_SA_CB<4>")
	)
	(arc
		(start 140.727684 -248.047002)
		(mid 140.909935 -248.097352)
		(end 141.093444 -248.051828)
		(width 0.0889)
		(layer "In13.Cu")
		(net "M_H_CPU1_SA_CB<4>")
	)
	(arc
		(start 136.976104 -248.051828)
		(mid 137.159612 -248.097322)
		(end 137.341864 -248.047002)
		(width 0.0889)
		(layer "In13.Cu")
		(net "M_H_CPU1_SA_CB<4>")
	)
	(arc
		(start 144.878044 -248.037604)
		(mid 145.154353 -247.970628)
		(end 145.428208 -248.047002)
		(width 0.0889)
		(layer "In13.Cu")
		(net "M_H_CPU1_SA_CB<4>")
	)
	(arc
		(start 144.488408 -248.047002)
		(mid 144.666058 -248.097262)
		(end 144.84604 -248.056146)
		(width 0.0889)
		(layer "In13.Cu")
		(net "M_H_CPU1_SA_CB<4>")
	)
	(arc
		(start 141.67612 -248.051828)
		(mid 141.859628 -248.097322)
		(end 142.04188 -248.047002)
		(width 0.0889)
		(layer "In13.Cu")
		(net "M_H_CPU1_SA_CB<4>")
	)
	(arc
		(start 139.221718 -248.047002)
		(mid 139.504674 -247.970825)
		(end 139.78763 -248.047002)
		(width 0.0889)
		(layer "In13.Cu")
		(net "M_H_CPU1_SA_CB<4>")
	)
	(arc
		(start 142.607792 -248.047002)
		(mid 142.794736 -248.097257)
		(end 142.98168 -248.047002)
		(width 0.0889)
		(layer "In13.Cu")
		(net "M_H_CPU1_SA_CB<4>")
	)
	(arc
		(start 139.78763 -248.047002)
		(mid 139.969881 -248.097352)
		(end 140.15339 -248.051828)
		(width 0.0889)
		(layer "In13.Cu")
		(net "M_H_CPU1_SA_CB<4>")
	)
	(arc
		(start 137.341864 -248.047002)
		(mid 137.62482 -247.970825)
		(end 137.907776 -248.047002)
		(width 0.0889)
		(layer "In13.Cu")
		(net "M_H_CPU1_SA_CB<4>")
	)
	(arc
		(start 141.101826 -248.047002)
		(mid 141.384782 -247.970825)
		(end 141.667738 -248.047002)
		(width 0.0889)
		(layer "In13.Cu")
		(net "M_H_CPU1_SA_CB<4>")
	)
	(arc
		(start 136.40181 -248.047002)
		(mid 136.684766 -247.970825)
		(end 136.967722 -248.047002)
		(width 0.0889)
		(layer "In13.Cu")
		(net "M_H_CPU1_SA_CB<4>")
	)
	(arc
		(start 136.08304 -248.073164)
		(mid 136.24055 -248.096362)
		(end 136.393428 -248.051828)
		(width 0.0889)
		(layer "In13.Cu")
		(net "M_H_CPU1_SA_CB<4>")
	)
	(arc
		(start 145.427954 -248.047002)
		(mid 145.516729 -248.084351)
		(end 145.612104 -248.097802)
		(width 0.0889)
		(layer "In13.Cu")
		(net "M_H_CPU1_SA_CB<4>")
	)
	(segment
		(start 133.867906 -246.370348)
		(end 134.334758 -246.10441)
		(width 0.10668)
		(layer "F.Cu")
		(net "M_H_CPU1_SA_CB<3>")
	)
	(segment
		(start 141.093444 -245.777004)
		(end 141.101826 -245.78183)
		(width 0.0889)
		(layer "In13.Cu")
		(net "M_H_CPU1_SA_CB<3>")
	)
	(segment
		(start 147.937982 -245.37162)
		(end 156.112464 -245.37162)
		(width 0.14478)
		(layer "In13.Cu")
		(net "M_H_CPU1_SA_CB<3>")
	)
	(segment
		(start 163.551616 -237.932468)
		(end 163.773612 -237.710472)
		(width 0.14478)
		(layer "In13.Cu")
		(net "M_H_CPU1_SA_CB<3>")
	)
	(segment
		(start 146.943572 -245.987824)
		(end 147.559776 -245.37162)
		(width 0.0889)
		(layer "In13.Cu")
		(net "M_H_CPU1_SA_CB<3>")
	)
	(segment
		(start 157.21584 -244.268244)
		(end 157.409896 -244.074188)
		(width 0.14478)
		(layer "In13.Cu")
		(net "M_H_CPU1_SA_CB<3>")
	)
	(segment
		(start 160.33496 -241.540792)
		(end 160.33496 -241.149124)
		(width 0.14478)
		(layer "In13.Cu")
		(net "M_H_CPU1_SA_CB<3>")
	)
	(segment
		(start 167.82923 -237.13694)
		(end 168.205404 -237.13694)
		(width 0.14478)
		(layer "In13.Cu")
		(net "M_H_CPU1_SA_CB<3>")
	)
	(segment
		(start 171.97197 -237.330996)
		(end 171.97197 -237.285276)
		(width 0.14478)
		(layer "In13.Cu")
		(net "M_H_CPU1_SA_CB<3>")
	)
	(segment
		(start 166.915846 -236.860334)
		(end 167.552624 -236.860334)
		(width 0.14478)
		(layer "In13.Cu")
		(net "M_H_CPU1_SA_CB<3>")
	)
	(segment
		(start 168.205404 -237.13694)
		(end 168.48201 -236.860334)
		(width 0.14478)
		(layer "In13.Cu")
		(net "M_H_CPU1_SA_CB<3>")
	)
	(segment
		(start 159.361124 -242.514628)
		(end 159.55518 -242.320572)
		(width 0.14478)
		(layer "In13.Cu")
		(net "M_H_CPU1_SA_CB<3>")
	)
	(segment
		(start 163.757356 -238.342932)
		(end 163.551616 -238.137192)
		(width 0.14478)
		(layer "In13.Cu")
		(net "M_H_CPU1_SA_CB<3>")
	)
	(segment
		(start 134.334758 -246.10441)
		(end 134.488682 -245.83898)
		(width 0.0889)
		(layer "In13.Cu")
		(net "M_H_CPU1_SA_CB<3>")
	)
	(segment
		(start 171.040044 -237.700566)
		(end 171.6024 -237.700566)
		(width 0.14478)
		(layer "In13.Cu")
		(net "M_H_CPU1_SA_CB<3>")
	)
	(segment
		(start 158.969456 -242.514628)
		(end 159.361124 -242.514628)
		(width 0.14478)
		(layer "In13.Cu")
		(net "M_H_CPU1_SA_CB<3>")
	)
	(segment
		(start 144.862296 -245.782084)
		(end 144.878044 -245.791228)
		(width 0.0889)
		(layer "In13.Cu")
		(net "M_H_CPU1_SA_CB<3>")
	)
	(segment
		(start 163.551616 -238.137192)
		(end 163.551616 -237.932468)
		(width 0.14478)
		(layer "In13.Cu")
		(net "M_H_CPU1_SA_CB<3>")
	)
	(segment
		(start 158.7754 -243.100352)
		(end 158.7754 -242.708684)
		(width 0.14478)
		(layer "In13.Cu")
		(net "M_H_CPU1_SA_CB<3>")
	)
	(segment
		(start 162.088576 -239.395508)
		(end 162.480244 -239.395508)
		(width 0.14478)
		(layer "In13.Cu")
		(net "M_H_CPU1_SA_CB<3>")
	)
	(segment
		(start 163.57219 -238.732822)
		(end 163.757356 -238.547656)
		(width 0.14478)
		(layer "In13.Cu")
		(net "M_H_CPU1_SA_CB<3>")
	)
	(segment
		(start 170.199812 -236.860334)
		(end 171.040044 -237.700566)
		(width 0.14478)
		(layer "In13.Cu")
		(net "M_H_CPU1_SA_CB<3>")
	)
	(segment
		(start 161.11474 -240.761012)
		(end 161.11474 -240.369344)
		(width 0.14478)
		(layer "In13.Cu")
		(net "M_H_CPU1_SA_CB<3>")
	)
	(segment
		(start 146.005296 -245.987824)
		(end 146.943572 -245.987824)
		(width 0.0889)
		(layer "In13.Cu")
		(net "M_H_CPU1_SA_CB<3>")
	)
	(segment
		(start 167.552624 -236.860334)
		(end 167.82923 -237.13694)
		(width 0.14478)
		(layer "In13.Cu")
		(net "M_H_CPU1_SA_CB<3>")
	)
	(segment
		(start 156.112464 -245.37162)
		(end 156.630116 -244.853968)
		(width 0.14478)
		(layer "In13.Cu")
		(net "M_H_CPU1_SA_CB<3>")
	)
	(segment
		(start 160.529016 -240.955068)
		(end 160.920684 -240.955068)
		(width 0.14478)
		(layer "In13.Cu")
		(net "M_H_CPU1_SA_CB<3>")
	)
	(segment
		(start 136.967722 -245.78183)
		(end 136.976104 -245.777004)
		(width 0.0889)
		(layer "In13.Cu")
		(net "M_H_CPU1_SA_CB<3>")
	)
	(segment
		(start 161.89452 -239.589564)
		(end 162.088576 -239.395508)
		(width 0.14478)
		(layer "In13.Cu")
		(net "M_H_CPU1_SA_CB<3>")
	)
	(segment
		(start 136.393428 -245.777004)
		(end 136.40181 -245.78183)
		(width 0.0889)
		(layer "In13.Cu")
		(net "M_H_CPU1_SA_CB<3>")
	)
	(segment
		(start 157.021784 -244.853968)
		(end 157.21584 -244.659912)
		(width 0.14478)
		(layer "In13.Cu")
		(net "M_H_CPU1_SA_CB<3>")
	)
	(segment
		(start 140.15339 -245.777004)
		(end 140.161772 -245.78183)
		(width 0.0889)
		(layer "In13.Cu")
		(net "M_H_CPU1_SA_CB<3>")
	)
	(segment
		(start 161.308796 -240.175288)
		(end 161.700464 -240.175288)
		(width 0.14478)
		(layer "In13.Cu")
		(net "M_H_CPU1_SA_CB<3>")
	)
	(segment
		(start 157.409896 -244.074188)
		(end 157.801564 -244.074188)
		(width 0.14478)
		(layer "In13.Cu")
		(net "M_H_CPU1_SA_CB<3>")
	)
	(segment
		(start 159.55518 -241.928904)
		(end 159.749236 -241.734848)
		(width 0.14478)
		(layer "In13.Cu")
		(net "M_H_CPU1_SA_CB<3>")
	)
	(segment
		(start 141.667738 -245.78183)
		(end 141.67612 -245.777004)
		(width 0.0889)
		(layer "In13.Cu")
		(net "M_H_CPU1_SA_CB<3>")
	)
	(segment
		(start 156.630116 -244.853968)
		(end 157.021784 -244.853968)
		(width 0.14478)
		(layer "In13.Cu")
		(net "M_H_CPU1_SA_CB<3>")
	)
	(segment
		(start 157.99562 -243.880132)
		(end 157.99562 -243.488464)
		(width 0.14478)
		(layer "In13.Cu")
		(net "M_H_CPU1_SA_CB<3>")
	)
	(segment
		(start 163.773612 -237.710472)
		(end 166.065708 -237.710472)
		(width 0.14478)
		(layer "In13.Cu")
		(net "M_H_CPU1_SA_CB<3>")
	)
	(segment
		(start 171.6024 -237.700566)
		(end 171.97197 -237.330996)
		(width 0.14478)
		(layer "In13.Cu")
		(net "M_H_CPU1_SA_CB<3>")
	)
	(segment
		(start 168.858184 -236.860334)
		(end 169.13479 -237.13694)
		(width 0.14478)
		(layer "In13.Cu")
		(net "M_H_CPU1_SA_CB<3>")
	)
	(segment
		(start 163.757356 -238.547656)
		(end 163.757356 -238.342932)
		(width 0.14478)
		(layer "In13.Cu")
		(net "M_H_CPU1_SA_CB<3>")
	)
	(segment
		(start 160.920684 -240.955068)
		(end 161.11474 -240.761012)
		(width 0.14478)
		(layer "In13.Cu")
		(net "M_H_CPU1_SA_CB<3>")
	)
	(segment
		(start 160.33496 -241.149124)
		(end 160.529016 -240.955068)
		(width 0.14478)
		(layer "In13.Cu")
		(net "M_H_CPU1_SA_CB<3>")
	)
	(segment
		(start 144.84858 -245.77421)
		(end 144.862296 -245.782084)
		(width 0.0889)
		(layer "In13.Cu")
		(net "M_H_CPU1_SA_CB<3>")
	)
	(segment
		(start 161.89452 -239.981232)
		(end 161.89452 -239.589564)
		(width 0.14478)
		(layer "In13.Cu")
		(net "M_H_CPU1_SA_CB<3>")
	)
	(segment
		(start 166.065708 -237.710472)
		(end 166.915846 -236.860334)
		(width 0.14478)
		(layer "In13.Cu")
		(net "M_H_CPU1_SA_CB<3>")
	)
	(segment
		(start 145.794476 -245.777004)
		(end 146.005296 -245.987824)
		(width 0.0889)
		(layer "In13.Cu")
		(net "M_H_CPU1_SA_CB<3>")
	)
	(segment
		(start 135.453374 -245.777004)
		(end 135.461756 -245.78183)
		(width 0.0889)
		(layer "In13.Cu")
		(net "M_H_CPU1_SA_CB<3>")
	)
	(segment
		(start 160.140904 -241.734848)
		(end 160.33496 -241.540792)
		(width 0.14478)
		(layer "In13.Cu")
		(net "M_H_CPU1_SA_CB<3>")
	)
	(segment
		(start 163.161726 -238.527082)
		(end 163.367466 -238.732822)
		(width 0.14478)
		(layer "In13.Cu")
		(net "M_H_CPU1_SA_CB<3>")
	)
	(segment
		(start 158.7754 -242.708684)
		(end 158.969456 -242.514628)
		(width 0.14478)
		(layer "In13.Cu")
		(net "M_H_CPU1_SA_CB<3>")
	)
	(segment
		(start 157.99562 -243.488464)
		(end 158.189676 -243.294408)
		(width 0.14478)
		(layer "In13.Cu")
		(net "M_H_CPU1_SA_CB<3>")
	)
	(segment
		(start 143.547592 -245.78183)
		(end 143.555974 -245.777004)
		(width 0.0889)
		(layer "In13.Cu")
		(net "M_H_CPU1_SA_CB<3>")
	)
	(segment
		(start 162.6743 -238.809784)
		(end 162.957002 -238.527082)
		(width 0.14478)
		(layer "In13.Cu")
		(net "M_H_CPU1_SA_CB<3>")
	)
	(segment
		(start 162.480244 -239.395508)
		(end 162.6743 -239.201452)
		(width 0.14478)
		(layer "In13.Cu")
		(net "M_H_CPU1_SA_CB<3>")
	)
	(segment
		(start 161.700464 -240.175288)
		(end 161.89452 -239.981232)
		(width 0.14478)
		(layer "In13.Cu")
		(net "M_H_CPU1_SA_CB<3>")
	)
	(segment
		(start 169.510964 -237.13694)
		(end 169.78757 -236.860334)
		(width 0.14478)
		(layer "In13.Cu")
		(net "M_H_CPU1_SA_CB<3>")
	)
	(segment
		(start 159.749236 -241.734848)
		(end 160.140904 -241.734848)
		(width 0.14478)
		(layer "In13.Cu")
		(net "M_H_CPU1_SA_CB<3>")
	)
	(segment
		(start 162.6743 -239.201452)
		(end 162.6743 -238.809784)
		(width 0.14478)
		(layer "In13.Cu")
		(net "M_H_CPU1_SA_CB<3>")
	)
	(segment
		(start 163.367466 -238.732822)
		(end 163.57219 -238.732822)
		(width 0.14478)
		(layer "In13.Cu")
		(net "M_H_CPU1_SA_CB<3>")
	)
	(segment
		(start 147.559776 -245.37162)
		(end 147.937982 -245.37162)
		(width 0.0889)
		(layer "In13.Cu")
		(net "M_H_CPU1_SA_CB<3>")
	)
	(segment
		(start 144.47393 -245.790466)
		(end 144.488662 -245.78183)
		(width 0.0889)
		(layer "In13.Cu")
		(net "M_H_CPU1_SA_CB<3>")
	)
	(segment
		(start 137.907776 -245.78183)
		(end 137.916158 -245.777004)
		(width 0.0889)
		(layer "In13.Cu")
		(net "M_H_CPU1_SA_CB<3>")
	)
	(segment
		(start 159.55518 -242.320572)
		(end 159.55518 -241.928904)
		(width 0.14478)
		(layer "In13.Cu")
		(net "M_H_CPU1_SA_CB<3>")
	)
	(segment
		(start 157.21584 -244.659912)
		(end 157.21584 -244.268244)
		(width 0.14478)
		(layer "In13.Cu")
		(net "M_H_CPU1_SA_CB<3>")
	)
	(segment
		(start 168.48201 -236.860334)
		(end 168.858184 -236.860334)
		(width 0.14478)
		(layer "In13.Cu")
		(net "M_H_CPU1_SA_CB<3>")
	)
	(segment
		(start 157.801564 -244.074188)
		(end 157.99562 -243.880132)
		(width 0.14478)
		(layer "In13.Cu")
		(net "M_H_CPU1_SA_CB<3>")
	)
	(segment
		(start 162.957002 -238.527082)
		(end 163.161726 -238.527082)
		(width 0.14478)
		(layer "In13.Cu")
		(net "M_H_CPU1_SA_CB<3>")
	)
	(segment
		(start 134.488682 -245.83898)
		(end 134.584694 -245.81358)
		(width 0.0889)
		(layer "In13.Cu")
		(net "M_H_CPU1_SA_CB<3>")
	)
	(segment
		(start 169.78757 -236.860334)
		(end 170.199812 -236.860334)
		(width 0.14478)
		(layer "In13.Cu")
		(net "M_H_CPU1_SA_CB<3>")
	)
	(segment
		(start 161.11474 -240.369344)
		(end 161.308796 -240.175288)
		(width 0.14478)
		(layer "In13.Cu")
		(net "M_H_CPU1_SA_CB<3>")
	)
	(segment
		(start 158.581344 -243.294408)
		(end 158.7754 -243.100352)
		(width 0.14478)
		(layer "In13.Cu")
		(net "M_H_CPU1_SA_CB<3>")
	)
	(segment
		(start 158.189676 -243.294408)
		(end 158.581344 -243.294408)
		(width 0.14478)
		(layer "In13.Cu")
		(net "M_H_CPU1_SA_CB<3>")
	)
	(segment
		(start 169.13479 -237.13694)
		(end 169.510964 -237.13694)
		(width 0.14478)
		(layer "In13.Cu")
		(net "M_H_CPU1_SA_CB<3>")
	)
	(arc
		(start 144.488662 -245.78183)
		(mid 144.667649 -245.73166)
		(end 144.84858 -245.77421)
		(width 0.0889)
		(layer "In13.Cu")
		(net "M_H_CPU1_SA_CB<3>")
	)
	(arc
		(start 139.78763 -245.78183)
		(mid 139.969881 -245.73148)
		(end 140.15339 -245.777004)
		(width 0.0889)
		(layer "In13.Cu")
		(net "M_H_CPU1_SA_CB<3>")
	)
	(arc
		(start 142.04188 -245.78183)
		(mid 142.324836 -245.858007)
		(end 142.607792 -245.78183)
		(width 0.0889)
		(layer "In13.Cu")
		(net "M_H_CPU1_SA_CB<3>")
	)
	(arc
		(start 140.727684 -245.78183)
		(mid 140.909935 -245.73148)
		(end 141.093444 -245.777004)
		(width 0.0889)
		(layer "In13.Cu")
		(net "M_H_CPU1_SA_CB<3>")
	)
	(arc
		(start 136.40181 -245.78183)
		(mid 136.684766 -245.858007)
		(end 136.967722 -245.78183)
		(width 0.0889)
		(layer "In13.Cu")
		(net "M_H_CPU1_SA_CB<3>")
	)
	(arc
		(start 143.555974 -245.777004)
		(mid 143.739736 -245.731388)
		(end 143.922242 -245.78183)
		(width 0.0889)
		(layer "In13.Cu")
		(net "M_H_CPU1_SA_CB<3>")
	)
	(arc
		(start 141.101826 -245.78183)
		(mid 141.384782 -245.858007)
		(end 141.667738 -245.78183)
		(width 0.0889)
		(layer "In13.Cu")
		(net "M_H_CPU1_SA_CB<3>")
	)
	(arc
		(start 134.584694 -245.81358)
		(mid 134.839902 -245.857057)
		(end 135.087614 -245.78183)
		(width 0.0889)
		(layer "In13.Cu")
		(net "M_H_CPU1_SA_CB<3>")
	)
	(arc
		(start 139.221718 -245.78183)
		(mid 139.504674 -245.858007)
		(end 139.78763 -245.78183)
		(width 0.0889)
		(layer "In13.Cu")
		(net "M_H_CPU1_SA_CB<3>")
	)
	(arc
		(start 144.878044 -245.791228)
		(mid 145.154353 -245.858204)
		(end 145.428208 -245.78183)
		(width 0.0889)
		(layer "In13.Cu")
		(net "M_H_CPU1_SA_CB<3>")
	)
	(arc
		(start 137.341864 -245.78183)
		(mid 137.62482 -245.858007)
		(end 137.907776 -245.78183)
		(width 0.0889)
		(layer "In13.Cu")
		(net "M_H_CPU1_SA_CB<3>")
	)
	(arc
		(start 141.67612 -245.777004)
		(mid 141.859628 -245.73151)
		(end 142.04188 -245.78183)
		(width 0.0889)
		(layer "In13.Cu")
		(net "M_H_CPU1_SA_CB<3>")
	)
	(arc
		(start 142.607792 -245.78183)
		(mid 142.794736 -245.731575)
		(end 142.98168 -245.78183)
		(width 0.0889)
		(layer "In13.Cu")
		(net "M_H_CPU1_SA_CB<3>")
	)
	(arc
		(start 137.916158 -245.777004)
		(mid 138.099666 -245.73151)
		(end 138.281918 -245.78183)
		(width 0.0889)
		(layer "In13.Cu")
		(net "M_H_CPU1_SA_CB<3>")
	)
	(arc
		(start 135.087614 -245.78183)
		(mid 135.269865 -245.73148)
		(end 135.453374 -245.777004)
		(width 0.0889)
		(layer "In13.Cu")
		(net "M_H_CPU1_SA_CB<3>")
	)
	(arc
		(start 140.161772 -245.78183)
		(mid 140.444728 -245.858007)
		(end 140.727684 -245.78183)
		(width 0.0889)
		(layer "In13.Cu")
		(net "M_H_CPU1_SA_CB<3>")
	)
	(arc
		(start 145.428208 -245.78183)
		(mid 145.610713 -245.731353)
		(end 145.794476 -245.777004)
		(width 0.0889)
		(layer "In13.Cu")
		(net "M_H_CPU1_SA_CB<3>")
	)
	(arc
		(start 136.976104 -245.777004)
		(mid 137.159612 -245.73151)
		(end 137.341864 -245.78183)
		(width 0.0889)
		(layer "In13.Cu")
		(net "M_H_CPU1_SA_CB<3>")
	)
	(arc
		(start 143.922242 -245.78183)
		(mid 144.196948 -245.858194)
		(end 144.47393 -245.790466)
		(width 0.0889)
		(layer "In13.Cu")
		(net "M_H_CPU1_SA_CB<3>")
	)
	(arc
		(start 136.027668 -245.78183)
		(mid 136.209919 -245.73148)
		(end 136.393428 -245.777004)
		(width 0.0889)
		(layer "In13.Cu")
		(net "M_H_CPU1_SA_CB<3>")
	)
	(arc
		(start 138.84783 -245.78183)
		(mid 139.034774 -245.731575)
		(end 139.221718 -245.78183)
		(width 0.0889)
		(layer "In13.Cu")
		(net "M_H_CPU1_SA_CB<3>")
	)
	(arc
		(start 142.98168 -245.78183)
		(mid 143.264636 -245.858007)
		(end 143.547592 -245.78183)
		(width 0.0889)
		(layer "In13.Cu")
		(net "M_H_CPU1_SA_CB<3>")
	)
	(arc
		(start 135.461756 -245.78183)
		(mid 135.744712 -245.858007)
		(end 136.027668 -245.78183)
		(width 0.0889)
		(layer "In13.Cu")
		(net "M_H_CPU1_SA_CB<3>")
	)
	(arc
		(start 138.281918 -245.78183)
		(mid 138.564874 -245.858007)
		(end 138.84783 -245.78183)
		(width 0.0889)
		(layer "In13.Cu")
		(net "M_H_CPU1_SA_CB<3>")
	)
	(segment
		(start 135.27786 -245.560342)
		(end 135.744712 -245.294404)
		(width 0.10668)
		(layer "F.Cu")
		(net "M_H_CPU1_SA_CB<2>")
	)
	(segment
		(start 158.399226 -241.608102)
		(end 158.398972 -241.812826)
		(width 0.14478)
		(layer "In13.Cu")
		(net "M_H_CPU1_SA_CB<2>")
	)
	(segment
		(start 159.568642 -240.438432)
		(end 159.453072 -240.322862)
		(width 0.14478)
		(layer "In13.Cu")
		(net "M_H_CPU1_SA_CB<2>")
	)
	(segment
		(start 157.893512 -241.882422)
		(end 157.689296 -241.882168)
		(width 0.14478)
		(layer "In13.Cu")
		(net "M_H_CPU1_SA_CB<2>")
	)
	(segment
		(start 159.178752 -241.033046)
		(end 158.993586 -241.218212)
		(width 0.14478)
		(layer "In13.Cu")
		(net "M_H_CPU1_SA_CB<2>")
	)
	(segment
		(start 171.6024 -236.010704)
		(end 170.792394 -236.010704)
		(width 0.14478)
		(layer "In13.Cu")
		(net "M_H_CPU1_SA_CB<2>")
	)
	(segment
		(start 159.958532 -240.253266)
		(end 159.773366 -240.438432)
		(width 0.14478)
		(layer "In13.Cu")
		(net "M_H_CPU1_SA_CB<2>")
	)
	(segment
		(start 157.619446 -242.387882)
		(end 157.619192 -242.592606)
		(width 0.14478)
		(layer "In13.Cu")
		(net "M_H_CPU1_SA_CB<2>")
	)
	(segment
		(start 159.248856 -240.322608)
		(end 159.063436 -240.508028)
		(width 0.14478)
		(layer "In13.Cu")
		(net "M_H_CPU1_SA_CB<2>")
	)
	(segment
		(start 167.149526 -235.160566)
		(end 166.28999 -236.020102)
		(width 0.14478)
		(layer "In13.Cu")
		(net "M_H_CPU1_SA_CB<2>")
	)
	(segment
		(start 139.326112 -244.966998)
		(end 139.31773 -244.971824)
		(width 0.0889)
		(layer "In13.Cu")
		(net "M_H_CPU1_SA_CB<2>")
	)
	(segment
		(start 135.89889 -245.028974)
		(end 135.744712 -245.294404)
		(width 0.0889)
		(layer "In13.Cu")
		(net "M_H_CPU1_SA_CB<2>")
	)
	(segment
		(start 156.724096 -243.052092)
		(end 156.839666 -243.167662)
		(width 0.14478)
		(layer "In13.Cu")
		(net "M_H_CPU1_SA_CB<2>")
	)
	(segment
		(start 155.944316 -243.831872)
		(end 156.059886 -243.947442)
		(width 0.14478)
		(layer "In13.Cu")
		(net "M_H_CPU1_SA_CB<2>")
	)
	(segment
		(start 158.993586 -241.218212)
		(end 158.788862 -241.218212)
		(width 0.14478)
		(layer "In13.Cu")
		(net "M_H_CPU1_SA_CB<2>")
	)
	(segment
		(start 156.059886 -243.947442)
		(end 156.059632 -244.152166)
		(width 0.14478)
		(layer "In13.Cu")
		(net "M_H_CPU1_SA_CB<2>")
	)
	(segment
		(start 155.944316 -243.627148)
		(end 155.944316 -243.831872)
		(width 0.14478)
		(layer "In13.Cu")
		(net "M_H_CPU1_SA_CB<2>")
	)
	(segment
		(start 157.619192 -242.592606)
		(end 157.434026 -242.777772)
		(width 0.14478)
		(layer "In13.Cu")
		(net "M_H_CPU1_SA_CB<2>")
	)
	(segment
		(start 157.229302 -242.777772)
		(end 157.113732 -242.662202)
		(width 0.14478)
		(layer "In13.Cu")
		(net "M_H_CPU1_SA_CB<2>")
	)
	(segment
		(start 158.283656 -241.492532)
		(end 158.399226 -241.608102)
		(width 0.14478)
		(layer "In13.Cu")
		(net "M_H_CPU1_SA_CB<2>")
	)
	(segment
		(start 156.059632 -244.152166)
		(end 155.749498 -244.4623)
		(width 0.14478)
		(layer "In13.Cu")
		(net "M_H_CPU1_SA_CB<2>")
	)
	(segment
		(start 171.97197 -235.585254)
		(end 171.97197 -235.641134)
		(width 0.14478)
		(layer "In13.Cu")
		(net "M_H_CPU1_SA_CB<2>")
	)
	(segment
		(start 147.692364 -244.4623)
		(end 146.94408 -245.210584)
		(width 0.0889)
		(layer "In13.Cu")
		(net "M_H_CPU1_SA_CB<2>")
	)
	(segment
		(start 156.839666 -243.167662)
		(end 156.839412 -243.372386)
		(width 0.14478)
		(layer "In13.Cu")
		(net "M_H_CPU1_SA_CB<2>")
	)
	(segment
		(start 159.843216 -239.932972)
		(end 159.958786 -240.048542)
		(width 0.14478)
		(layer "In13.Cu")
		(net "M_H_CPU1_SA_CB<2>")
	)
	(segment
		(start 156.839412 -243.372386)
		(end 156.654246 -243.557552)
		(width 0.14478)
		(layer "In13.Cu")
		(net "M_H_CPU1_SA_CB<2>")
	)
	(segment
		(start 156.909516 -242.661948)
		(end 156.724096 -242.847368)
		(width 0.14478)
		(layer "In13.Cu")
		(net "M_H_CPU1_SA_CB<2>")
	)
	(segment
		(start 164.191696 -236.020102)
		(end 160.553146 -239.658652)
		(width 0.14478)
		(layer "In13.Cu")
		(net "M_H_CPU1_SA_CB<2>")
	)
	(segment
		(start 170.792394 -236.010704)
		(end 169.942256 -235.160566)
		(width 0.14478)
		(layer "In13.Cu")
		(net "M_H_CPU1_SA_CB<2>")
	)
	(segment
		(start 158.788862 -241.218212)
		(end 158.673292 -241.102642)
		(width 0.14478)
		(layer "In13.Cu")
		(net "M_H_CPU1_SA_CB<2>")
	)
	(segment
		(start 158.213806 -241.997992)
		(end 158.009082 -241.997992)
		(width 0.14478)
		(layer "In13.Cu")
		(net "M_H_CPU1_SA_CB<2>")
	)
	(segment
		(start 146.013932 -244.921024)
		(end 145.144744 -244.921024)
		(width 0.0889)
		(layer "In13.Cu")
		(net "M_H_CPU1_SA_CB<2>")
	)
	(segment
		(start 156.449522 -243.557552)
		(end 156.333952 -243.441982)
		(width 0.14478)
		(layer "In13.Cu")
		(net "M_H_CPU1_SA_CB<2>")
	)
	(segment
		(start 157.689296 -241.882168)
		(end 157.503876 -242.067588)
		(width 0.14478)
		(layer "In13.Cu")
		(net "M_H_CPU1_SA_CB<2>")
	)
	(segment
		(start 157.113732 -242.662202)
		(end 156.909516 -242.661948)
		(width 0.14478)
		(layer "In13.Cu")
		(net "M_H_CPU1_SA_CB<2>")
	)
	(segment
		(start 171.97197 -235.641134)
		(end 171.6024 -236.010704)
		(width 0.14478)
		(layer "In13.Cu")
		(net "M_H_CPU1_SA_CB<2>")
	)
	(segment
		(start 143.086074 -244.966998)
		(end 143.077692 -244.971824)
		(width 0.0889)
		(layer "In13.Cu")
		(net "M_H_CPU1_SA_CB<2>")
	)
	(segment
		(start 160.232852 -239.543082)
		(end 160.028636 -239.542828)
		(width 0.14478)
		(layer "In13.Cu")
		(net "M_H_CPU1_SA_CB<2>")
	)
	(segment
		(start 169.942256 -235.160566)
		(end 167.149526 -235.160566)
		(width 0.14478)
		(layer "In13.Cu")
		(net "M_H_CPU1_SA_CB<2>")
	)
	(segment
		(start 159.958786 -240.048542)
		(end 159.958532 -240.253266)
		(width 0.14478)
		(layer "In13.Cu")
		(net "M_H_CPU1_SA_CB<2>")
	)
	(segment
		(start 156.333952 -243.441982)
		(end 156.129736 -243.441728)
		(width 0.14478)
		(layer "In13.Cu")
		(net "M_H_CPU1_SA_CB<2>")
	)
	(segment
		(start 158.283656 -241.287808)
		(end 158.283656 -241.492532)
		(width 0.14478)
		(layer "In13.Cu")
		(net "M_H_CPU1_SA_CB<2>")
	)
	(segment
		(start 157.434026 -242.777772)
		(end 157.229302 -242.777772)
		(width 0.14478)
		(layer "In13.Cu")
		(net "M_H_CPU1_SA_CB<2>")
	)
	(segment
		(start 158.398972 -241.812826)
		(end 158.213806 -241.997992)
		(width 0.14478)
		(layer "In13.Cu")
		(net "M_H_CPU1_SA_CB<2>")
	)
	(segment
		(start 158.009082 -241.997992)
		(end 157.893512 -241.882422)
		(width 0.14478)
		(layer "In13.Cu")
		(net "M_H_CPU1_SA_CB<2>")
	)
	(segment
		(start 137.811764 -244.971824)
		(end 137.803382 -244.966998)
		(width 0.0889)
		(layer "In13.Cu")
		(net "M_H_CPU1_SA_CB<2>")
	)
	(segment
		(start 159.453072 -240.322862)
		(end 159.248856 -240.322608)
		(width 0.14478)
		(layer "In13.Cu")
		(net "M_H_CPU1_SA_CB<2>")
	)
	(segment
		(start 159.843216 -239.728248)
		(end 159.843216 -239.932972)
		(width 0.14478)
		(layer "In13.Cu")
		(net "M_H_CPU1_SA_CB<2>")
	)
	(segment
		(start 147.913852 -244.4623)
		(end 147.692364 -244.4623)
		(width 0.0889)
		(layer "In13.Cu")
		(net "M_H_CPU1_SA_CB<2>")
	)
	(segment
		(start 158.673292 -241.102642)
		(end 158.469076 -241.102388)
		(width 0.14478)
		(layer "In13.Cu")
		(net "M_H_CPU1_SA_CB<2>")
	)
	(segment
		(start 160.348422 -239.658652)
		(end 160.232852 -239.543082)
		(width 0.14478)
		(layer "In13.Cu")
		(net "M_H_CPU1_SA_CB<2>")
	)
	(segment
		(start 157.503876 -242.272312)
		(end 157.619446 -242.387882)
		(width 0.14478)
		(layer "In13.Cu")
		(net "M_H_CPU1_SA_CB<2>")
	)
	(segment
		(start 160.553146 -239.658652)
		(end 160.348422 -239.658652)
		(width 0.14478)
		(layer "In13.Cu")
		(net "M_H_CPU1_SA_CB<2>")
	)
	(segment
		(start 159.773366 -240.438432)
		(end 159.568642 -240.438432)
		(width 0.14478)
		(layer "In13.Cu")
		(net "M_H_CPU1_SA_CB<2>")
	)
	(segment
		(start 160.028636 -239.542828)
		(end 159.843216 -239.728248)
		(width 0.14478)
		(layer "In13.Cu")
		(net "M_H_CPU1_SA_CB<2>")
	)
	(segment
		(start 157.503876 -242.067588)
		(end 157.503876 -242.272312)
		(width 0.14478)
		(layer "In13.Cu")
		(net "M_H_CPU1_SA_CB<2>")
	)
	(segment
		(start 142.51178 -244.971824)
		(end 142.503398 -244.966998)
		(width 0.0889)
		(layer "In13.Cu")
		(net "M_H_CPU1_SA_CB<2>")
	)
	(segment
		(start 158.469076 -241.102388)
		(end 158.283656 -241.287808)
		(width 0.14478)
		(layer "In13.Cu")
		(net "M_H_CPU1_SA_CB<2>")
	)
	(segment
		(start 140.266166 -244.966998)
		(end 140.257784 -244.971824)
		(width 0.0889)
		(layer "In13.Cu")
		(net "M_H_CPU1_SA_CB<2>")
	)
	(segment
		(start 144.39265 -244.971824)
		(end 144.384268 -244.966998)
		(width 0.0889)
		(layer "In13.Cu")
		(net "M_H_CPU1_SA_CB<2>")
	)
	(segment
		(start 159.063436 -240.508028)
		(end 159.063436 -240.712752)
		(width 0.14478)
		(layer "In13.Cu")
		(net "M_H_CPU1_SA_CB<2>")
	)
	(segment
		(start 159.179006 -240.828322)
		(end 159.178752 -241.033046)
		(width 0.14478)
		(layer "In13.Cu")
		(net "M_H_CPU1_SA_CB<2>")
	)
	(segment
		(start 159.063436 -240.712752)
		(end 159.179006 -240.828322)
		(width 0.14478)
		(layer "In13.Cu")
		(net "M_H_CPU1_SA_CB<2>")
	)
	(segment
		(start 156.724096 -242.847368)
		(end 156.724096 -243.052092)
		(width 0.14478)
		(layer "In13.Cu")
		(net "M_H_CPU1_SA_CB<2>")
	)
	(segment
		(start 135.995156 -245.003574)
		(end 135.89889 -245.028974)
		(width 0.0889)
		(layer "In13.Cu")
		(net "M_H_CPU1_SA_CB<2>")
	)
	(segment
		(start 166.28999 -236.020102)
		(end 164.191696 -236.020102)
		(width 0.14478)
		(layer "In13.Cu")
		(net "M_H_CPU1_SA_CB<2>")
	)
	(segment
		(start 138.751818 -244.971824)
		(end 138.743436 -244.966998)
		(width 0.0889)
		(layer "In13.Cu")
		(net "M_H_CPU1_SA_CB<2>")
	)
	(segment
		(start 143.462248 -244.97792)
		(end 143.451834 -244.971824)
		(width 0.0889)
		(layer "In13.Cu")
		(net "M_H_CPU1_SA_CB<2>")
	)
	(segment
		(start 155.749498 -244.4623)
		(end 147.913852 -244.4623)
		(width 0.14478)
		(layer "In13.Cu")
		(net "M_H_CPU1_SA_CB<2>")
	)
	(segment
		(start 156.654246 -243.557552)
		(end 156.449522 -243.557552)
		(width 0.14478)
		(layer "In13.Cu")
		(net "M_H_CPU1_SA_CB<2>")
	)
	(segment
		(start 146.94408 -245.210584)
		(end 146.303492 -245.210584)
		(width 0.0889)
		(layer "In13.Cu")
		(net "M_H_CPU1_SA_CB<2>")
	)
	(segment
		(start 156.129736 -243.441728)
		(end 155.944316 -243.627148)
		(width 0.14478)
		(layer "In13.Cu")
		(net "M_H_CPU1_SA_CB<2>")
	)
	(segment
		(start 146.303492 -245.210584)
		(end 146.013932 -244.921024)
		(width 0.0889)
		(layer "In13.Cu")
		(net "M_H_CPU1_SA_CB<2>")
	)
	(arc
		(start 143.077692 -244.971824)
		(mid 142.794736 -245.048001)
		(end 142.51178 -244.971824)
		(width 0.0889)
		(layer "In13.Cu")
		(net "M_H_CPU1_SA_CB<2>")
	)
	(arc
		(start 140.631926 -244.971824)
		(mid 140.449675 -244.921474)
		(end 140.266166 -244.966998)
		(width 0.0889)
		(layer "In13.Cu")
		(net "M_H_CPU1_SA_CB<2>")
	)
	(arc
		(start 143.451834 -244.971824)
		(mid 143.269583 -244.921474)
		(end 143.086074 -244.966998)
		(width 0.0889)
		(layer "In13.Cu")
		(net "M_H_CPU1_SA_CB<2>")
	)
	(arc
		(start 145.144744 -244.921024)
		(mid 145.04489 -244.935067)
		(end 144.952466 -244.97538)
		(width 0.0889)
		(layer "In13.Cu")
		(net "M_H_CPU1_SA_CB<2>")
	)
	(arc
		(start 144.952466 -244.97538)
		(mid 144.672077 -245.048049)
		(end 144.39265 -244.971824)
		(width 0.0889)
		(layer "In13.Cu")
		(net "M_H_CPU1_SA_CB<2>")
	)
	(arc
		(start 141.197838 -244.971824)
		(mid 140.914882 -245.048001)
		(end 140.631926 -244.971824)
		(width 0.0889)
		(layer "In13.Cu")
		(net "M_H_CPU1_SA_CB<2>")
	)
	(arc
		(start 136.497822 -244.971824)
		(mid 136.250226 -245.047002)
		(end 135.995156 -245.003574)
		(width 0.0889)
		(layer "In13.Cu")
		(net "M_H_CPU1_SA_CB<2>")
	)
	(arc
		(start 138.377676 -244.971824)
		(mid 138.09472 -245.048001)
		(end 137.811764 -244.971824)
		(width 0.0889)
		(layer "In13.Cu")
		(net "M_H_CPU1_SA_CB<2>")
	)
	(arc
		(start 144.018 -244.971824)
		(mid 143.740933 -245.048095)
		(end 143.462248 -244.97792)
		(width 0.0889)
		(layer "In13.Cu")
		(net "M_H_CPU1_SA_CB<2>")
	)
	(arc
		(start 137.803382 -244.966998)
		(mid 137.619874 -244.921504)
		(end 137.437622 -244.971824)
		(width 0.0889)
		(layer "In13.Cu")
		(net "M_H_CPU1_SA_CB<2>")
	)
	(arc
		(start 141.571726 -244.971824)
		(mid 141.384782 -244.921569)
		(end 141.197838 -244.971824)
		(width 0.0889)
		(layer "In13.Cu")
		(net "M_H_CPU1_SA_CB<2>")
	)
	(arc
		(start 139.31773 -244.971824)
		(mid 139.034774 -245.048001)
		(end 138.751818 -244.971824)
		(width 0.0889)
		(layer "In13.Cu")
		(net "M_H_CPU1_SA_CB<2>")
	)
	(arc
		(start 139.691872 -244.971824)
		(mid 139.509621 -244.921474)
		(end 139.326112 -244.966998)
		(width 0.0889)
		(layer "In13.Cu")
		(net "M_H_CPU1_SA_CB<2>")
	)
	(arc
		(start 142.137638 -244.971824)
		(mid 141.854682 -245.048001)
		(end 141.571726 -244.971824)
		(width 0.0889)
		(layer "In13.Cu")
		(net "M_H_CPU1_SA_CB<2>")
	)
	(arc
		(start 144.384268 -244.966998)
		(mid 144.200506 -244.921382)
		(end 144.018 -244.971824)
		(width 0.0889)
		(layer "In13.Cu")
		(net "M_H_CPU1_SA_CB<2>")
	)
	(arc
		(start 137.437622 -244.971824)
		(mid 137.154666 -245.048001)
		(end 136.87171 -244.971824)
		(width 0.0889)
		(layer "In13.Cu")
		(net "M_H_CPU1_SA_CB<2>")
	)
	(arc
		(start 138.743436 -244.966998)
		(mid 138.559928 -244.921504)
		(end 138.377676 -244.971824)
		(width 0.0889)
		(layer "In13.Cu")
		(net "M_H_CPU1_SA_CB<2>")
	)
	(arc
		(start 142.503398 -244.966998)
		(mid 142.31989 -244.921504)
		(end 142.137638 -244.971824)
		(width 0.0889)
		(layer "In13.Cu")
		(net "M_H_CPU1_SA_CB<2>")
	)
	(arc
		(start 140.257784 -244.971824)
		(mid 139.974828 -245.048001)
		(end 139.691872 -244.971824)
		(width 0.0889)
		(layer "In13.Cu")
		(net "M_H_CPU1_SA_CB<2>")
	)
	(arc
		(start 136.87171 -244.971824)
		(mid 136.684766 -244.921569)
		(end 136.497822 -244.971824)
		(width 0.0889)
		(layer "In13.Cu")
		(net "M_H_CPU1_SA_CB<2>")
	)
	(segment
		(start 134.337806 -245.560342)
		(end 134.804658 -245.294404)
		(width 0.10668)
		(layer "F.Cu")
		(net "M_H_CPU1_SA_CB<1>")
	)
	(segment
		(start 144.380966 -245.623842)
		(end 144.39265 -245.616984)
		(width 0.0889)
		(layer "In13.Cu")
		(net "M_H_CPU1_SA_CB<1>")
	)
	(segment
		(start 143.451834 -245.616984)
		(end 143.466566 -245.608348)
		(width 0.0889)
		(layer "In13.Cu")
		(net "M_H_CPU1_SA_CB<1>")
	)
	(segment
		(start 164.508434 -237.260892)
		(end 166.558214 -236.410754)
		(width 0.14478)
		(layer "In13.Cu")
		(net "M_H_CPU1_SA_CB<1>")
	)
	(segment
		(start 134.804658 -245.294404)
		(end 134.650734 -245.559834)
		(width 0.0889)
		(layer "In13.Cu")
		(net "M_H_CPU1_SA_CB<1>")
	)
	(segment
		(start 166.558214 -236.410754)
		(end 170.420284 -236.410754)
		(width 0.14478)
		(layer "In13.Cu")
		(net "M_H_CPU1_SA_CB<1>")
	)
	(segment
		(start 145.883884 -245.608348)
		(end 146.960844 -245.608348)
		(width 0.0889)
		(layer "In13.Cu")
		(net "M_H_CPU1_SA_CB<1>")
	)
	(segment
		(start 172.970952 -236.860588)
		(end 175.108616 -236.435392)
		(width 0.14478)
		(layer "In13.Cu")
		(net "M_H_CPU1_SA_CB<1>")
	)
	(segment
		(start 144.952466 -245.613428)
		(end 144.958054 -245.61673)
		(width 0.0889)
		(layer "In13.Cu")
		(net "M_H_CPU1_SA_CB<1>")
	)
	(segment
		(start 138.743436 -245.62181)
		(end 138.751818 -245.616984)
		(width 0.0889)
		(layer "In13.Cu")
		(net "M_H_CPU1_SA_CB<1>")
	)
	(segment
		(start 143.077692 -245.616984)
		(end 143.086074 -245.62181)
		(width 0.0889)
		(layer "In13.Cu")
		(net "M_H_CPU1_SA_CB<1>")
	)
	(segment
		(start 170.420284 -236.410754)
		(end 171.506388 -236.860588)
		(width 0.14478)
		(layer "In13.Cu")
		(net "M_H_CPU1_SA_CB<1>")
	)
	(segment
		(start 155.931108 -244.91696)
		(end 163.587176 -237.260892)
		(width 0.14478)
		(layer "In13.Cu")
		(net "M_H_CPU1_SA_CB<1>")
	)
	(segment
		(start 139.31773 -245.616984)
		(end 139.326112 -245.62181)
		(width 0.0889)
		(layer "In13.Cu")
		(net "M_H_CPU1_SA_CB<1>")
	)
	(segment
		(start 163.587176 -237.260892)
		(end 164.508434 -237.260892)
		(width 0.14478)
		(layer "In13.Cu")
		(net "M_H_CPU1_SA_CB<1>")
	)
	(segment
		(start 140.257784 -245.616984)
		(end 140.266166 -245.62181)
		(width 0.0889)
		(layer "In13.Cu")
		(net "M_H_CPU1_SA_CB<1>")
	)
	(segment
		(start 134.650734 -245.559834)
		(end 134.673086 -245.643146)
		(width 0.0889)
		(layer "In13.Cu")
		(net "M_H_CPU1_SA_CB<1>")
	)
	(segment
		(start 147.652232 -244.91696)
		(end 147.910296 -244.91696)
		(width 0.0889)
		(layer "In13.Cu")
		(net "M_H_CPU1_SA_CB<1>")
	)
	(segment
		(start 135.557768 -245.616984)
		(end 135.56615 -245.62181)
		(width 0.0889)
		(layer "In13.Cu")
		(net "M_H_CPU1_SA_CB<1>")
	)
	(segment
		(start 147.910296 -244.91696)
		(end 155.931108 -244.91696)
		(width 0.14478)
		(layer "In13.Cu")
		(net "M_H_CPU1_SA_CB<1>")
	)
	(segment
		(start 171.506388 -236.860588)
		(end 172.970952 -236.860588)
		(width 0.14478)
		(layer "In13.Cu")
		(net "M_H_CPU1_SA_CB<1>")
	)
	(segment
		(start 175.108616 -236.435392)
		(end 176.072038 -236.435392)
		(width 0.14478)
		(layer "In13.Cu")
		(net "M_H_CPU1_SA_CB<1>")
	)
	(segment
		(start 146.960844 -245.608348)
		(end 147.652232 -244.91696)
		(width 0.0889)
		(layer "In13.Cu")
		(net "M_H_CPU1_SA_CB<1>")
	)
	(segment
		(start 137.803382 -245.62181)
		(end 137.811764 -245.616984)
		(width 0.0889)
		(layer "In13.Cu")
		(net "M_H_CPU1_SA_CB<1>")
	)
	(segment
		(start 144.958054 -245.61673)
		(end 144.976342 -245.627144)
		(width 0.0889)
		(layer "In13.Cu")
		(net "M_H_CPU1_SA_CB<1>")
	)
	(segment
		(start 142.503398 -245.62181)
		(end 142.51178 -245.616984)
		(width 0.0889)
		(layer "In13.Cu")
		(net "M_H_CPU1_SA_CB<1>")
	)
	(arc
		(start 142.137638 -245.616984)
		(mid 142.319889 -245.667334)
		(end 142.503398 -245.62181)
		(width 0.0889)
		(layer "In13.Cu")
		(net "M_H_CPU1_SA_CB<1>")
	)
	(arc
		(start 137.811764 -245.616984)
		(mid 138.09472 -245.540807)
		(end 138.377676 -245.616984)
		(width 0.0889)
		(layer "In13.Cu")
		(net "M_H_CPU1_SA_CB<1>")
	)
	(arc
		(start 136.87171 -245.616984)
		(mid 137.154666 -245.540807)
		(end 137.437622 -245.616984)
		(width 0.0889)
		(layer "In13.Cu")
		(net "M_H_CPU1_SA_CB<1>")
	)
	(arc
		(start 138.377676 -245.616984)
		(mid 138.559927 -245.667334)
		(end 138.743436 -245.62181)
		(width 0.0889)
		(layer "In13.Cu")
		(net "M_H_CPU1_SA_CB<1>")
	)
	(arc
		(start 145.332196 -245.616984)
		(mid 145.606902 -245.54062)
		(end 145.883884 -245.608348)
		(width 0.0889)
		(layer "In13.Cu")
		(net "M_H_CPU1_SA_CB<1>")
	)
	(arc
		(start 135.93191 -245.616984)
		(mid 136.214866 -245.540807)
		(end 136.497822 -245.616984)
		(width 0.0889)
		(layer "In13.Cu")
		(net "M_H_CPU1_SA_CB<1>")
	)
	(arc
		(start 139.691872 -245.616984)
		(mid 139.974828 -245.540807)
		(end 140.257784 -245.616984)
		(width 0.0889)
		(layer "In13.Cu")
		(net "M_H_CPU1_SA_CB<1>")
	)
	(arc
		(start 139.326112 -245.62181)
		(mid 139.50962 -245.667304)
		(end 139.691872 -245.616984)
		(width 0.0889)
		(layer "In13.Cu")
		(net "M_H_CPU1_SA_CB<1>")
	)
	(arc
		(start 135.56615 -245.62181)
		(mid 135.749658 -245.667304)
		(end 135.93191 -245.616984)
		(width 0.0889)
		(layer "In13.Cu")
		(net "M_H_CPU1_SA_CB<1>")
	)
	(arc
		(start 140.266166 -245.62181)
		(mid 140.449674 -245.667304)
		(end 140.631926 -245.616984)
		(width 0.0889)
		(layer "In13.Cu")
		(net "M_H_CPU1_SA_CB<1>")
	)
	(arc
		(start 134.673086 -245.643146)
		(mid 134.835418 -245.665964)
		(end 134.991856 -245.616984)
		(width 0.0889)
		(layer "In13.Cu")
		(net "M_H_CPU1_SA_CB<1>")
	)
	(arc
		(start 140.631926 -245.616984)
		(mid 140.914882 -245.540807)
		(end 141.197838 -245.616984)
		(width 0.0889)
		(layer "In13.Cu")
		(net "M_H_CPU1_SA_CB<1>")
	)
	(arc
		(start 144.39265 -245.616984)
		(mid 144.672078 -245.540818)
		(end 144.952466 -245.613428)
		(width 0.0889)
		(layer "In13.Cu")
		(net "M_H_CPU1_SA_CB<1>")
	)
	(arc
		(start 137.437622 -245.616984)
		(mid 137.619873 -245.667334)
		(end 137.803382 -245.62181)
		(width 0.0889)
		(layer "In13.Cu")
		(net "M_H_CPU1_SA_CB<1>")
	)
	(arc
		(start 143.086074 -245.62181)
		(mid 143.269582 -245.667304)
		(end 143.451834 -245.616984)
		(width 0.0889)
		(layer "In13.Cu")
		(net "M_H_CPU1_SA_CB<1>")
	)
	(arc
		(start 142.51178 -245.616984)
		(mid 142.794736 -245.540807)
		(end 143.077692 -245.616984)
		(width 0.0889)
		(layer "In13.Cu")
		(net "M_H_CPU1_SA_CB<1>")
	)
	(arc
		(start 144.018254 -245.616984)
		(mid 144.198712 -245.667428)
		(end 144.380966 -245.623842)
		(width 0.0889)
		(layer "In13.Cu")
		(net "M_H_CPU1_SA_CB<1>")
	)
	(arc
		(start 143.466566 -245.608348)
		(mid 143.743549 -245.540544)
		(end 144.018254 -245.616984)
		(width 0.0889)
		(layer "In13.Cu")
		(net "M_H_CPU1_SA_CB<1>")
	)
	(arc
		(start 134.991856 -245.616984)
		(mid 135.274812 -245.540807)
		(end 135.557768 -245.616984)
		(width 0.0889)
		(layer "In13.Cu")
		(net "M_H_CPU1_SA_CB<1>")
	)
	(arc
		(start 141.197838 -245.616984)
		(mid 141.384782 -245.667239)
		(end 141.571726 -245.616984)
		(width 0.0889)
		(layer "In13.Cu")
		(net "M_H_CPU1_SA_CB<1>")
	)
	(arc
		(start 144.976342 -245.627144)
		(mid 145.155571 -245.667297)
		(end 145.332196 -245.616984)
		(width 0.0889)
		(layer "In13.Cu")
		(net "M_H_CPU1_SA_CB<1>")
	)
	(arc
		(start 138.751818 -245.616984)
		(mid 139.034774 -245.540807)
		(end 139.31773 -245.616984)
		(width 0.0889)
		(layer "In13.Cu")
		(net "M_H_CPU1_SA_CB<1>")
	)
	(arc
		(start 141.571726 -245.616984)
		(mid 141.854682 -245.540807)
		(end 142.137638 -245.616984)
		(width 0.0889)
		(layer "In13.Cu")
		(net "M_H_CPU1_SA_CB<1>")
	)
	(arc
		(start 136.497822 -245.616984)
		(mid 136.684766 -245.667239)
		(end 136.87171 -245.616984)
		(width 0.0889)
		(layer "In13.Cu")
		(net "M_H_CPU1_SA_CB<1>")
	)
	(segment
		(start 135.748014 -244.750336)
		(end 136.214866 -244.484398)
		(width 0.10668)
		(layer "F.Cu")
		(net "M_H_CPU1_SA_CB<0>")
	)
	(segment
		(start 147.702778 -243.995194)
		(end 147.493482 -243.995194)
		(width 0.0889)
		(layer "In13.Cu")
		(net "M_H_CPU1_SA_CB<0>")
	)
	(segment
		(start 147.493482 -243.995194)
		(end 147.098512 -244.390164)
		(width 0.0889)
		(layer "In13.Cu")
		(net "M_H_CPU1_SA_CB<0>")
	)
	(segment
		(start 141.67612 -244.811804)
		(end 141.667738 -244.806978)
		(width 0.0889)
		(layer "In13.Cu")
		(net "M_H_CPU1_SA_CB<0>")
	)
	(segment
		(start 136.08304 -244.83314)
		(end 136.060688 -244.749828)
		(width 0.0889)
		(layer "In13.Cu")
		(net "M_H_CPU1_SA_CB<0>")
	)
	(segment
		(start 146.479768 -244.390164)
		(end 146.139408 -244.730524)
		(width 0.0889)
		(layer "In13.Cu")
		(net "M_H_CPU1_SA_CB<0>")
	)
	(segment
		(start 169.776902 -234.310682)
		(end 167.356028 -234.310682)
		(width 0.14478)
		(layer "In13.Cu")
		(net "M_H_CPU1_SA_CB<0>")
	)
	(segment
		(start 144.488408 -244.806978)
		(end 144.477994 -244.800882)
		(width 0.0889)
		(layer "In13.Cu")
		(net "M_H_CPU1_SA_CB<0>")
	)
	(segment
		(start 166.096188 -235.570522)
		(end 163.364926 -235.570522)
		(width 0.14478)
		(layer "In13.Cu")
		(net "M_H_CPU1_SA_CB<0>")
	)
	(segment
		(start 170.626786 -235.160566)
		(end 169.776902 -234.310682)
		(width 0.14478)
		(layer "In13.Cu")
		(net "M_H_CPU1_SA_CB<0>")
	)
	(segment
		(start 146.139408 -244.730524)
		(end 145.144744 -244.730524)
		(width 0.0889)
		(layer "In13.Cu")
		(net "M_H_CPU1_SA_CB<0>")
	)
	(segment
		(start 143.555974 -244.811804)
		(end 143.547592 -244.806978)
		(width 0.0889)
		(layer "In13.Cu")
		(net "M_H_CPU1_SA_CB<0>")
	)
	(segment
		(start 163.364926 -235.570522)
		(end 154.940254 -243.995194)
		(width 0.14478)
		(layer "In13.Cu")
		(net "M_H_CPU1_SA_CB<0>")
	)
	(segment
		(start 136.40181 -244.806978)
		(end 136.393428 -244.811804)
		(width 0.0889)
		(layer "In13.Cu")
		(net "M_H_CPU1_SA_CB<0>")
	)
	(segment
		(start 136.060688 -244.749828)
		(end 136.214866 -244.484398)
		(width 0.0889)
		(layer "In13.Cu")
		(net "M_H_CPU1_SA_CB<0>")
	)
	(segment
		(start 176.072038 -234.73537)
		(end 173.684946 -235.160566)
		(width 0.14478)
		(layer "In13.Cu")
		(net "M_H_CPU1_SA_CB<0>")
	)
	(segment
		(start 147.098512 -244.390164)
		(end 146.479768 -244.390164)
		(width 0.0889)
		(layer "In13.Cu")
		(net "M_H_CPU1_SA_CB<0>")
	)
	(segment
		(start 141.101826 -244.806978)
		(end 141.093444 -244.811804)
		(width 0.0889)
		(layer "In13.Cu")
		(net "M_H_CPU1_SA_CB<0>")
	)
	(segment
		(start 137.916158 -244.811804)
		(end 137.907776 -244.806978)
		(width 0.0889)
		(layer "In13.Cu")
		(net "M_H_CPU1_SA_CB<0>")
	)
	(segment
		(start 167.356028 -234.310682)
		(end 166.096188 -235.570522)
		(width 0.14478)
		(layer "In13.Cu")
		(net "M_H_CPU1_SA_CB<0>")
	)
	(segment
		(start 173.684946 -235.160566)
		(end 170.626786 -235.160566)
		(width 0.14478)
		(layer "In13.Cu")
		(net "M_H_CPU1_SA_CB<0>")
	)
	(segment
		(start 154.940254 -243.995194)
		(end 147.702778 -243.995194)
		(width 0.14478)
		(layer "In13.Cu")
		(net "M_H_CPU1_SA_CB<0>")
	)
	(segment
		(start 140.161772 -244.806978)
		(end 140.15339 -244.811804)
		(width 0.0889)
		(layer "In13.Cu")
		(net "M_H_CPU1_SA_CB<0>")
	)
	(segment
		(start 136.976104 -244.811804)
		(end 136.967722 -244.806978)
		(width 0.0889)
		(layer "In13.Cu")
		(net "M_H_CPU1_SA_CB<0>")
	)
	(arc
		(start 142.607792 -244.806978)
		(mid 142.324836 -244.730801)
		(end 142.04188 -244.806978)
		(width 0.0889)
		(layer "In13.Cu")
		(net "M_H_CPU1_SA_CB<0>")
	)
	(arc
		(start 143.922242 -244.806978)
		(mid 143.739737 -244.857455)
		(end 143.555974 -244.811804)
		(width 0.0889)
		(layer "In13.Cu")
		(net "M_H_CPU1_SA_CB<0>")
	)
	(arc
		(start 141.093444 -244.811804)
		(mid 140.909936 -244.857298)
		(end 140.727684 -244.806978)
		(width 0.0889)
		(layer "In13.Cu")
		(net "M_H_CPU1_SA_CB<0>")
	)
	(arc
		(start 140.727684 -244.806978)
		(mid 140.444728 -244.730801)
		(end 140.161772 -244.806978)
		(width 0.0889)
		(layer "In13.Cu")
		(net "M_H_CPU1_SA_CB<0>")
	)
	(arc
		(start 137.907776 -244.806978)
		(mid 137.62482 -244.730801)
		(end 137.341864 -244.806978)
		(width 0.0889)
		(layer "In13.Cu")
		(net "M_H_CPU1_SA_CB<0>")
	)
	(arc
		(start 139.78763 -244.806978)
		(mid 139.504674 -244.730801)
		(end 139.221718 -244.806978)
		(width 0.0889)
		(layer "In13.Cu")
		(net "M_H_CPU1_SA_CB<0>")
	)
	(arc
		(start 142.04188 -244.806978)
		(mid 141.859629 -244.857328)
		(end 141.67612 -244.811804)
		(width 0.0889)
		(layer "In13.Cu")
		(net "M_H_CPU1_SA_CB<0>")
	)
	(arc
		(start 139.221718 -244.806978)
		(mid 139.034774 -244.857233)
		(end 138.84783 -244.806978)
		(width 0.0889)
		(layer "In13.Cu")
		(net "M_H_CPU1_SA_CB<0>")
	)
	(arc
		(start 137.341864 -244.806978)
		(mid 137.159613 -244.857328)
		(end 136.976104 -244.811804)
		(width 0.0889)
		(layer "In13.Cu")
		(net "M_H_CPU1_SA_CB<0>")
	)
	(arc
		(start 138.84783 -244.806978)
		(mid 138.564874 -244.730801)
		(end 138.281918 -244.806978)
		(width 0.0889)
		(layer "In13.Cu")
		(net "M_H_CPU1_SA_CB<0>")
	)
	(arc
		(start 145.144744 -244.730524)
		(mid 144.989383 -244.752349)
		(end 144.84604 -244.816122)
		(width 0.0889)
		(layer "In13.Cu")
		(net "M_H_CPU1_SA_CB<0>")
	)
	(arc
		(start 140.15339 -244.811804)
		(mid 139.969882 -244.857298)
		(end 139.78763 -244.806978)
		(width 0.0889)
		(layer "In13.Cu")
		(net "M_H_CPU1_SA_CB<0>")
	)
	(arc
		(start 144.477994 -244.800882)
		(mid 144.199308 -244.730662)
		(end 143.922242 -244.806978)
		(width 0.0889)
		(layer "In13.Cu")
		(net "M_H_CPU1_SA_CB<0>")
	)
	(arc
		(start 138.281918 -244.806978)
		(mid 138.099667 -244.857328)
		(end 137.916158 -244.811804)
		(width 0.0889)
		(layer "In13.Cu")
		(net "M_H_CPU1_SA_CB<0>")
	)
	(arc
		(start 144.84604 -244.816122)
		(mid 144.666058 -244.857222)
		(end 144.488408 -244.806978)
		(width 0.0889)
		(layer "In13.Cu")
		(net "M_H_CPU1_SA_CB<0>")
	)
	(arc
		(start 143.547592 -244.806978)
		(mid 143.264636 -244.730801)
		(end 142.98168 -244.806978)
		(width 0.0889)
		(layer "In13.Cu")
		(net "M_H_CPU1_SA_CB<0>")
	)
	(arc
		(start 136.393428 -244.811804)
		(mid 136.240558 -244.856445)
		(end 136.08304 -244.83314)
		(width 0.0889)
		(layer "In13.Cu")
		(net "M_H_CPU1_SA_CB<0>")
	)
	(arc
		(start 141.667738 -244.806978)
		(mid 141.384782 -244.730801)
		(end 141.101826 -244.806978)
		(width 0.0889)
		(layer "In13.Cu")
		(net "M_H_CPU1_SA_CB<0>")
	)
	(arc
		(start 136.967722 -244.806978)
		(mid 136.684766 -244.730801)
		(end 136.40181 -244.806978)
		(width 0.0889)
		(layer "In13.Cu")
		(net "M_H_CPU1_SA_CB<0>")
	)
	(arc
		(start 142.98168 -244.806978)
		(mid 142.794736 -244.857233)
		(end 142.607792 -244.806978)
		(width 0.0889)
		(layer "In13.Cu")
		(net "M_H_CPU1_SA_CB<0>")
	)
	(segment
		(start 134.337806 -255.280414)
		(end 134.804658 -255.014476)
		(width 0.10668)
		(layer "F.Cu")
		(net "M_H_CPU1_SA_CA<6>")
	)
	(segment
		(start 163.493958 -255.261364)
		(end 164.044884 -254.710438)
		(width 0.14478)
		(layer "In13.Cu")
		(net "M_H_CPU1_SA_CA<6>")
	)
	(segment
		(start 143.077692 -255.337056)
		(end 143.086074 -255.341882)
		(width 0.0889)
		(layer "In13.Cu")
		(net "M_H_CPU1_SA_CA<6>")
	)
	(segment
		(start 169.0116 -254.066548)
		(end 170.688 -252.390148)
		(width 0.14478)
		(layer "In13.Cu")
		(net "M_H_CPU1_SA_CA<6>")
	)
	(segment
		(start 138.743436 -255.341882)
		(end 138.751818 -255.337056)
		(width 0.0889)
		(layer "In13.Cu")
		(net "M_H_CPU1_SA_CA<6>")
	)
	(segment
		(start 150.866348 -255.698244)
		(end 151.848566 -254.716026)
		(width 0.14478)
		(layer "In13.Cu")
		(net "M_H_CPU1_SA_CA<6>")
	)
	(segment
		(start 140.257784 -255.337056)
		(end 140.266166 -255.341882)
		(width 0.0889)
		(layer "In13.Cu")
		(net "M_H_CPU1_SA_CA<6>")
	)
	(segment
		(start 144.958054 -255.336802)
		(end 144.976342 -255.347216)
		(width 0.0889)
		(layer "In13.Cu")
		(net "M_H_CPU1_SA_CA<6>")
	)
	(segment
		(start 137.803382 -255.341882)
		(end 137.811764 -255.337056)
		(width 0.0889)
		(layer "In13.Cu")
		(net "M_H_CPU1_SA_CA<6>")
	)
	(segment
		(start 134.650734 -255.279906)
		(end 134.673086 -255.363218)
		(width 0.0889)
		(layer "In13.Cu")
		(net "M_H_CPU1_SA_CA<6>")
	)
	(segment
		(start 147.554188 -255.698244)
		(end 150.866348 -255.698244)
		(width 0.14478)
		(layer "In13.Cu")
		(net "M_H_CPU1_SA_CA<6>")
	)
	(segment
		(start 155.82646 -254.716026)
		(end 156.371798 -255.261364)
		(width 0.14478)
		(layer "In13.Cu")
		(net "M_H_CPU1_SA_CA<6>")
	)
	(segment
		(start 139.31773 -255.337056)
		(end 139.326112 -255.341882)
		(width 0.0889)
		(layer "In13.Cu")
		(net "M_H_CPU1_SA_CA<6>")
	)
	(segment
		(start 167.386 -254.710438)
		(end 168.02989 -254.066548)
		(width 0.14478)
		(layer "In13.Cu")
		(net "M_H_CPU1_SA_CA<6>")
	)
	(segment
		(start 146.215608 -255.698244)
		(end 147.554188 -255.698244)
		(width 0.0889)
		(layer "In13.Cu")
		(net "M_H_CPU1_SA_CA<6>")
	)
	(segment
		(start 171.798742 -252.160278)
		(end 172.145452 -252.160278)
		(width 0.0889)
		(layer "In13.Cu")
		(net "M_H_CPU1_SA_CA<6>")
	)
	(segment
		(start 175.408844 -252.58522)
		(end 176.072038 -252.58522)
		(width 0.14478)
		(layer "In13.Cu")
		(net "M_H_CPU1_SA_CA<6>")
	)
	(segment
		(start 145.337784 -255.331468)
		(end 145.848832 -255.331468)
		(width 0.0889)
		(layer "In13.Cu")
		(net "M_H_CPU1_SA_CA<6>")
	)
	(segment
		(start 145.848832 -255.331468)
		(end 146.215608 -255.698244)
		(width 0.0889)
		(layer "In13.Cu")
		(net "M_H_CPU1_SA_CA<6>")
	)
	(segment
		(start 164.044884 -254.710438)
		(end 167.386 -254.710438)
		(width 0.14478)
		(layer "In13.Cu")
		(net "M_H_CPU1_SA_CA<6>")
	)
	(segment
		(start 168.02989 -254.066548)
		(end 169.0116 -254.066548)
		(width 0.14478)
		(layer "In13.Cu")
		(net "M_H_CPU1_SA_CA<6>")
	)
	(segment
		(start 151.848566 -254.716026)
		(end 155.82646 -254.716026)
		(width 0.14478)
		(layer "In13.Cu")
		(net "M_H_CPU1_SA_CA<6>")
	)
	(segment
		(start 171.562268 -252.390148)
		(end 171.734988 -252.217428)
		(width 0.14478)
		(layer "In13.Cu")
		(net "M_H_CPU1_SA_CA<6>")
	)
	(segment
		(start 144.952466 -255.3335)
		(end 144.958054 -255.336802)
		(width 0.0889)
		(layer "In13.Cu")
		(net "M_H_CPU1_SA_CA<6>")
	)
	(segment
		(start 142.503398 -255.341882)
		(end 142.51178 -255.337056)
		(width 0.0889)
		(layer "In13.Cu")
		(net "M_H_CPU1_SA_CA<6>")
	)
	(segment
		(start 171.741592 -252.217428)
		(end 171.798742 -252.160278)
		(width 0.0889)
		(layer "In13.Cu")
		(net "M_H_CPU1_SA_CA<6>")
	)
	(segment
		(start 170.688 -252.390148)
		(end 171.562268 -252.390148)
		(width 0.14478)
		(layer "In13.Cu")
		(net "M_H_CPU1_SA_CA<6>")
	)
	(segment
		(start 144.380966 -255.343914)
		(end 144.39265 -255.337056)
		(width 0.0889)
		(layer "In13.Cu")
		(net "M_H_CPU1_SA_CA<6>")
	)
	(segment
		(start 171.734988 -252.217428)
		(end 171.741592 -252.217428)
		(width 0.0889)
		(layer "In13.Cu")
		(net "M_H_CPU1_SA_CA<6>")
	)
	(segment
		(start 156.371798 -255.261364)
		(end 163.493958 -255.261364)
		(width 0.14478)
		(layer "In13.Cu")
		(net "M_H_CPU1_SA_CA<6>")
	)
	(segment
		(start 135.557768 -255.337056)
		(end 135.56615 -255.341882)
		(width 0.0889)
		(layer "In13.Cu")
		(net "M_H_CPU1_SA_CA<6>")
	)
	(segment
		(start 143.451834 -255.337056)
		(end 143.466566 -255.32842)
		(width 0.0889)
		(layer "In13.Cu")
		(net "M_H_CPU1_SA_CA<6>")
	)
	(segment
		(start 172.145452 -252.160278)
		(end 174.983902 -252.160278)
		(width 0.14478)
		(layer "In13.Cu")
		(net "M_H_CPU1_SA_CA<6>")
	)
	(segment
		(start 174.983902 -252.160278)
		(end 175.408844 -252.58522)
		(width 0.14478)
		(layer "In13.Cu")
		(net "M_H_CPU1_SA_CA<6>")
	)
	(segment
		(start 134.804658 -255.014476)
		(end 134.650734 -255.279906)
		(width 0.0889)
		(layer "In13.Cu")
		(net "M_H_CPU1_SA_CA<6>")
	)
	(segment
		(start 145.332196 -255.337056)
		(end 145.337784 -255.331468)
		(width 0.0889)
		(layer "In13.Cu")
		(net "M_H_CPU1_SA_CA<6>")
	)
	(arc
		(start 139.691872 -255.337056)
		(mid 139.974828 -255.260879)
		(end 140.257784 -255.337056)
		(width 0.0889)
		(layer "In13.Cu")
		(net "M_H_CPU1_SA_CA<6>")
	)
	(arc
		(start 135.93191 -255.337056)
		(mid 136.214866 -255.260879)
		(end 136.497822 -255.337056)
		(width 0.0889)
		(layer "In13.Cu")
		(net "M_H_CPU1_SA_CA<6>")
	)
	(arc
		(start 141.571726 -255.337056)
		(mid 141.854682 -255.260879)
		(end 142.137638 -255.337056)
		(width 0.0889)
		(layer "In13.Cu")
		(net "M_H_CPU1_SA_CA<6>")
	)
	(arc
		(start 137.437622 -255.337056)
		(mid 137.619873 -255.387406)
		(end 137.803382 -255.341882)
		(width 0.0889)
		(layer "In13.Cu")
		(net "M_H_CPU1_SA_CA<6>")
	)
	(arc
		(start 143.086074 -255.341882)
		(mid 143.269582 -255.387376)
		(end 143.451834 -255.337056)
		(width 0.0889)
		(layer "In13.Cu")
		(net "M_H_CPU1_SA_CA<6>")
	)
	(arc
		(start 144.976342 -255.347216)
		(mid 145.155571 -255.387369)
		(end 145.332196 -255.337056)
		(width 0.0889)
		(layer "In13.Cu")
		(net "M_H_CPU1_SA_CA<6>")
	)
	(arc
		(start 138.377676 -255.337056)
		(mid 138.559927 -255.387406)
		(end 138.743436 -255.341882)
		(width 0.0889)
		(layer "In13.Cu")
		(net "M_H_CPU1_SA_CA<6>")
	)
	(arc
		(start 136.497822 -255.337056)
		(mid 136.684766 -255.387311)
		(end 136.87171 -255.337056)
		(width 0.0889)
		(layer "In13.Cu")
		(net "M_H_CPU1_SA_CA<6>")
	)
	(arc
		(start 137.811764 -255.337056)
		(mid 138.09472 -255.260879)
		(end 138.377676 -255.337056)
		(width 0.0889)
		(layer "In13.Cu")
		(net "M_H_CPU1_SA_CA<6>")
	)
	(arc
		(start 140.631926 -255.337056)
		(mid 140.914882 -255.260879)
		(end 141.197838 -255.337056)
		(width 0.0889)
		(layer "In13.Cu")
		(net "M_H_CPU1_SA_CA<6>")
	)
	(arc
		(start 144.39265 -255.337056)
		(mid 144.672078 -255.26089)
		(end 144.952466 -255.3335)
		(width 0.0889)
		(layer "In13.Cu")
		(net "M_H_CPU1_SA_CA<6>")
	)
	(arc
		(start 138.751818 -255.337056)
		(mid 139.034774 -255.260879)
		(end 139.31773 -255.337056)
		(width 0.0889)
		(layer "In13.Cu")
		(net "M_H_CPU1_SA_CA<6>")
	)
	(arc
		(start 139.326112 -255.341882)
		(mid 139.50962 -255.387376)
		(end 139.691872 -255.337056)
		(width 0.0889)
		(layer "In13.Cu")
		(net "M_H_CPU1_SA_CA<6>")
	)
	(arc
		(start 144.018254 -255.337056)
		(mid 144.198712 -255.3875)
		(end 144.380966 -255.343914)
		(width 0.0889)
		(layer "In13.Cu")
		(net "M_H_CPU1_SA_CA<6>")
	)
	(arc
		(start 142.51178 -255.337056)
		(mid 142.794736 -255.260879)
		(end 143.077692 -255.337056)
		(width 0.0889)
		(layer "In13.Cu")
		(net "M_H_CPU1_SA_CA<6>")
	)
	(arc
		(start 134.673086 -255.363218)
		(mid 134.835418 -255.386036)
		(end 134.991856 -255.337056)
		(width 0.0889)
		(layer "In13.Cu")
		(net "M_H_CPU1_SA_CA<6>")
	)
	(arc
		(start 143.466566 -255.32842)
		(mid 143.743549 -255.260616)
		(end 144.018254 -255.337056)
		(width 0.0889)
		(layer "In13.Cu")
		(net "M_H_CPU1_SA_CA<6>")
	)
	(arc
		(start 134.991856 -255.337056)
		(mid 135.274812 -255.260879)
		(end 135.557768 -255.337056)
		(width 0.0889)
		(layer "In13.Cu")
		(net "M_H_CPU1_SA_CA<6>")
	)
	(arc
		(start 141.197838 -255.337056)
		(mid 141.384782 -255.387311)
		(end 141.571726 -255.337056)
		(width 0.0889)
		(layer "In13.Cu")
		(net "M_H_CPU1_SA_CA<6>")
	)
	(arc
		(start 136.87171 -255.337056)
		(mid 137.154666 -255.260879)
		(end 137.437622 -255.337056)
		(width 0.0889)
		(layer "In13.Cu")
		(net "M_H_CPU1_SA_CA<6>")
	)
	(arc
		(start 142.137638 -255.337056)
		(mid 142.319889 -255.387406)
		(end 142.503398 -255.341882)
		(width 0.0889)
		(layer "In13.Cu")
		(net "M_H_CPU1_SA_CA<6>")
	)
	(arc
		(start 135.56615 -255.341882)
		(mid 135.749658 -255.387376)
		(end 135.93191 -255.337056)
		(width 0.0889)
		(layer "In13.Cu")
		(net "M_H_CPU1_SA_CA<6>")
	)
	(arc
		(start 140.266166 -255.341882)
		(mid 140.449674 -255.387376)
		(end 140.631926 -255.337056)
		(width 0.0889)
		(layer "In13.Cu")
		(net "M_H_CPU1_SA_CA<6>")
	)
	(segment
		(start 135.27786 -255.280414)
		(end 135.744712 -255.014476)
		(width 0.10668)
		(layer "F.Cu")
		(net "M_H_CPU1_SA_CA<5>")
	)
	(segment
		(start 162.55111 -253.8603)
		(end 162.144964 -254.266446)
		(width 0.14478)
		(layer "In13.Cu")
		(net "M_H_CPU1_SA_CA<5>")
	)
	(segment
		(start 160.319466 -254.266446)
		(end 160.157922 -254.42799)
		(width 0.14478)
		(layer "In13.Cu")
		(net "M_H_CPU1_SA_CA<5>")
	)
	(segment
		(start 159.606488 -254.42799)
		(end 159.444944 -254.266446)
		(width 0.14478)
		(layer "In13.Cu")
		(net "M_H_CPU1_SA_CA<5>")
	)
	(segment
		(start 157.952186 -254.42799)
		(end 157.952186 -254.602742)
		(width 0.14478)
		(layer "In13.Cu")
		(net "M_H_CPU1_SA_CA<5>")
	)
	(segment
		(start 151.6253 -254.266446)
		(end 150.650702 -255.241044)
		(width 0.14478)
		(layer "In13.Cu")
		(net "M_H_CPU1_SA_CA<5>")
	)
	(segment
		(start 157.400752 -254.42799)
		(end 157.239208 -254.266446)
		(width 0.14478)
		(layer "In13.Cu")
		(net "M_H_CPU1_SA_CA<5>")
	)
	(segment
		(start 146.489928 -255.241044)
		(end 146.010122 -254.761238)
		(width 0.0889)
		(layer "In13.Cu")
		(net "M_H_CPU1_SA_CA<5>")
	)
	(segment
		(start 138.751818 -254.691896)
		(end 138.743436 -254.68707)
		(width 0.0889)
		(layer "In13.Cu")
		(net "M_H_CPU1_SA_CA<5>")
	)
	(segment
		(start 159.055054 -254.602742)
		(end 158.89351 -254.764286)
		(width 0.14478)
		(layer "In13.Cu")
		(net "M_H_CPU1_SA_CA<5>")
	)
	(segment
		(start 144.976342 -254.681736)
		(end 144.958054 -254.69215)
		(width 0.0889)
		(layer "In13.Cu")
		(net "M_H_CPU1_SA_CA<5>")
	)
	(segment
		(start 142.51178 -254.691896)
		(end 142.503398 -254.68707)
		(width 0.0889)
		(layer "In13.Cu")
		(net "M_H_CPU1_SA_CA<5>")
	)
	(segment
		(start 158.11373 -254.266446)
		(end 157.952186 -254.42799)
		(width 0.14478)
		(layer "In13.Cu")
		(net "M_H_CPU1_SA_CA<5>")
	)
	(segment
		(start 137.811764 -254.691896)
		(end 137.803382 -254.68707)
		(width 0.0889)
		(layer "In13.Cu")
		(net "M_H_CPU1_SA_CA<5>")
	)
	(segment
		(start 158.89351 -254.764286)
		(end 158.665164 -254.764286)
		(width 0.14478)
		(layer "In13.Cu")
		(net "M_H_CPU1_SA_CA<5>")
	)
	(segment
		(start 143.086074 -254.68707)
		(end 143.077692 -254.691896)
		(width 0.0889)
		(layer "In13.Cu")
		(net "M_H_CPU1_SA_CA<5>")
	)
	(segment
		(start 158.50362 -254.42799)
		(end 158.342076 -254.266446)
		(width 0.14478)
		(layer "In13.Cu")
		(net "M_H_CPU1_SA_CA<5>")
	)
	(segment
		(start 143.462248 -254.697992)
		(end 143.451834 -254.691896)
		(width 0.0889)
		(layer "In13.Cu")
		(net "M_H_CPU1_SA_CA<5>")
	)
	(segment
		(start 157.239208 -254.266446)
		(end 151.6253 -254.266446)
		(width 0.14478)
		(layer "In13.Cu")
		(net "M_H_CPU1_SA_CA<5>")
	)
	(segment
		(start 159.444944 -254.266446)
		(end 159.216598 -254.266446)
		(width 0.14478)
		(layer "In13.Cu")
		(net "M_H_CPU1_SA_CA<5>")
	)
	(segment
		(start 167.1828 -253.8603)
		(end 162.55111 -253.8603)
		(width 0.14478)
		(layer "In13.Cu")
		(net "M_H_CPU1_SA_CA<5>")
	)
	(segment
		(start 160.157922 -254.42799)
		(end 160.157922 -254.602742)
		(width 0.14478)
		(layer "In13.Cu")
		(net "M_H_CPU1_SA_CA<5>")
	)
	(segment
		(start 159.996378 -254.764286)
		(end 159.768032 -254.764286)
		(width 0.14478)
		(layer "In13.Cu")
		(net "M_H_CPU1_SA_CA<5>")
	)
	(segment
		(start 140.266166 -254.68707)
		(end 140.257784 -254.691896)
		(width 0.0889)
		(layer "In13.Cu")
		(net "M_H_CPU1_SA_CA<5>")
	)
	(segment
		(start 150.650702 -255.241044)
		(end 147.582128 -255.241044)
		(width 0.14478)
		(layer "In13.Cu")
		(net "M_H_CPU1_SA_CA<5>")
	)
	(segment
		(start 159.055054 -254.42799)
		(end 159.055054 -254.602742)
		(width 0.14478)
		(layer "In13.Cu")
		(net "M_H_CPU1_SA_CA<5>")
	)
	(segment
		(start 159.606488 -254.602742)
		(end 159.606488 -254.42799)
		(width 0.14478)
		(layer "In13.Cu")
		(net "M_H_CPU1_SA_CA<5>")
	)
	(segment
		(start 168.05529 -252.98781)
		(end 167.1828 -253.8603)
		(width 0.14478)
		(layer "In13.Cu")
		(net "M_H_CPU1_SA_CA<5>")
	)
	(segment
		(start 144.39265 -254.691896)
		(end 144.384268 -254.68707)
		(width 0.0889)
		(layer "In13.Cu")
		(net "M_H_CPU1_SA_CA<5>")
	)
	(segment
		(start 144.958054 -254.69215)
		(end 144.952466 -254.695452)
		(width 0.0889)
		(layer "In13.Cu")
		(net "M_H_CPU1_SA_CA<5>")
	)
	(segment
		(start 157.790642 -254.764286)
		(end 157.562296 -254.764286)
		(width 0.14478)
		(layer "In13.Cu")
		(net "M_H_CPU1_SA_CA<5>")
	)
	(segment
		(start 158.50362 -254.602742)
		(end 158.50362 -254.42799)
		(width 0.14478)
		(layer "In13.Cu")
		(net "M_H_CPU1_SA_CA<5>")
	)
	(segment
		(start 158.665164 -254.764286)
		(end 158.50362 -254.602742)
		(width 0.14478)
		(layer "In13.Cu")
		(net "M_H_CPU1_SA_CA<5>")
	)
	(segment
		(start 159.768032 -254.764286)
		(end 159.606488 -254.602742)
		(width 0.14478)
		(layer "In13.Cu")
		(net "M_H_CPU1_SA_CA<5>")
	)
	(segment
		(start 169.201592 -252.98781)
		(end 168.05529 -252.98781)
		(width 0.14478)
		(layer "In13.Cu")
		(net "M_H_CPU1_SA_CA<5>")
	)
	(segment
		(start 158.342076 -254.266446)
		(end 158.11373 -254.266446)
		(width 0.14478)
		(layer "In13.Cu")
		(net "M_H_CPU1_SA_CA<5>")
	)
	(segment
		(start 162.144964 -254.266446)
		(end 160.319466 -254.266446)
		(width 0.14478)
		(layer "In13.Cu")
		(net "M_H_CPU1_SA_CA<5>")
	)
	(segment
		(start 139.326112 -254.68707)
		(end 139.31773 -254.691896)
		(width 0.0889)
		(layer "In13.Cu")
		(net "M_H_CPU1_SA_CA<5>")
	)
	(segment
		(start 146.010122 -254.761238)
		(end 145.492724 -254.761238)
		(width 0.0889)
		(layer "In13.Cu")
		(net "M_H_CPU1_SA_CA<5>")
	)
	(segment
		(start 160.157922 -254.602742)
		(end 159.996378 -254.764286)
		(width 0.14478)
		(layer "In13.Cu")
		(net "M_H_CPU1_SA_CA<5>")
	)
	(segment
		(start 171.97197 -251.735336)
		(end 170.454066 -251.735336)
		(width 0.14478)
		(layer "In13.Cu")
		(net "M_H_CPU1_SA_CA<5>")
	)
	(segment
		(start 135.995156 -254.723646)
		(end 135.89889 -254.749046)
		(width 0.0889)
		(layer "In13.Cu")
		(net "M_H_CPU1_SA_CA<5>")
	)
	(segment
		(start 159.216598 -254.266446)
		(end 159.055054 -254.42799)
		(width 0.14478)
		(layer "In13.Cu")
		(net "M_H_CPU1_SA_CA<5>")
	)
	(segment
		(start 157.400752 -254.602742)
		(end 157.400752 -254.42799)
		(width 0.14478)
		(layer "In13.Cu")
		(net "M_H_CPU1_SA_CA<5>")
	)
	(segment
		(start 170.454066 -251.735336)
		(end 169.201592 -252.98781)
		(width 0.14478)
		(layer "In13.Cu")
		(net "M_H_CPU1_SA_CA<5>")
	)
	(segment
		(start 147.582128 -255.241044)
		(end 146.489928 -255.241044)
		(width 0.0889)
		(layer "In13.Cu")
		(net "M_H_CPU1_SA_CA<5>")
	)
	(segment
		(start 157.562296 -254.764286)
		(end 157.400752 -254.602742)
		(width 0.14478)
		(layer "In13.Cu")
		(net "M_H_CPU1_SA_CA<5>")
	)
	(segment
		(start 145.41627 -254.740664)
		(end 145.332196 -254.691896)
		(width 0.0889)
		(layer "In13.Cu")
		(net "M_H_CPU1_SA_CA<5>")
	)
	(segment
		(start 157.952186 -254.602742)
		(end 157.790642 -254.764286)
		(width 0.14478)
		(layer "In13.Cu")
		(net "M_H_CPU1_SA_CA<5>")
	)
	(segment
		(start 135.89889 -254.749046)
		(end 135.744712 -255.014476)
		(width 0.0889)
		(layer "In13.Cu")
		(net "M_H_CPU1_SA_CA<5>")
	)
	(arc
		(start 136.497822 -254.691896)
		(mid 136.250226 -254.767074)
		(end 135.995156 -254.723646)
		(width 0.0889)
		(layer "In13.Cu")
		(net "M_H_CPU1_SA_CA<5>")
	)
	(arc
		(start 141.571726 -254.691896)
		(mid 141.384782 -254.641641)
		(end 141.197838 -254.691896)
		(width 0.0889)
		(layer "In13.Cu")
		(net "M_H_CPU1_SA_CA<5>")
	)
	(arc
		(start 145.332196 -254.691896)
		(mid 145.155568 -254.641663)
		(end 144.976342 -254.681736)
		(width 0.0889)
		(layer "In13.Cu")
		(net "M_H_CPU1_SA_CA<5>")
	)
	(arc
		(start 144.018 -254.691896)
		(mid 143.740933 -254.768167)
		(end 143.462248 -254.697992)
		(width 0.0889)
		(layer "In13.Cu")
		(net "M_H_CPU1_SA_CA<5>")
	)
	(arc
		(start 142.503398 -254.68707)
		(mid 142.31989 -254.641576)
		(end 142.137638 -254.691896)
		(width 0.0889)
		(layer "In13.Cu")
		(net "M_H_CPU1_SA_CA<5>")
	)
	(arc
		(start 143.077692 -254.691896)
		(mid 142.794736 -254.768073)
		(end 142.51178 -254.691896)
		(width 0.0889)
		(layer "In13.Cu")
		(net "M_H_CPU1_SA_CA<5>")
	)
	(arc
		(start 142.137638 -254.691896)
		(mid 141.854682 -254.768073)
		(end 141.571726 -254.691896)
		(width 0.0889)
		(layer "In13.Cu")
		(net "M_H_CPU1_SA_CA<5>")
	)
	(arc
		(start 141.197838 -254.691896)
		(mid 140.914882 -254.768073)
		(end 140.631926 -254.691896)
		(width 0.0889)
		(layer "In13.Cu")
		(net "M_H_CPU1_SA_CA<5>")
	)
	(arc
		(start 144.384268 -254.68707)
		(mid 144.200506 -254.641454)
		(end 144.018 -254.691896)
		(width 0.0889)
		(layer "In13.Cu")
		(net "M_H_CPU1_SA_CA<5>")
	)
	(arc
		(start 145.492724 -254.761238)
		(mid 145.453136 -254.756006)
		(end 145.41627 -254.740664)
		(width 0.0889)
		(layer "In13.Cu")
		(net "M_H_CPU1_SA_CA<5>")
	)
	(arc
		(start 140.257784 -254.691896)
		(mid 139.974828 -254.768073)
		(end 139.691872 -254.691896)
		(width 0.0889)
		(layer "In13.Cu")
		(net "M_H_CPU1_SA_CA<5>")
	)
	(arc
		(start 136.87171 -254.691896)
		(mid 136.684766 -254.641641)
		(end 136.497822 -254.691896)
		(width 0.0889)
		(layer "In13.Cu")
		(net "M_H_CPU1_SA_CA<5>")
	)
	(arc
		(start 144.952466 -254.695452)
		(mid 144.672077 -254.768121)
		(end 144.39265 -254.691896)
		(width 0.0889)
		(layer "In13.Cu")
		(net "M_H_CPU1_SA_CA<5>")
	)
	(arc
		(start 138.743436 -254.68707)
		(mid 138.559928 -254.641576)
		(end 138.377676 -254.691896)
		(width 0.0889)
		(layer "In13.Cu")
		(net "M_H_CPU1_SA_CA<5>")
	)
	(arc
		(start 139.31773 -254.691896)
		(mid 139.034774 -254.768073)
		(end 138.751818 -254.691896)
		(width 0.0889)
		(layer "In13.Cu")
		(net "M_H_CPU1_SA_CA<5>")
	)
	(arc
		(start 137.437622 -254.691896)
		(mid 137.154666 -254.768073)
		(end 136.87171 -254.691896)
		(width 0.0889)
		(layer "In13.Cu")
		(net "M_H_CPU1_SA_CA<5>")
	)
	(arc
		(start 139.691872 -254.691896)
		(mid 139.509621 -254.641546)
		(end 139.326112 -254.68707)
		(width 0.0889)
		(layer "In13.Cu")
		(net "M_H_CPU1_SA_CA<5>")
	)
	(arc
		(start 137.803382 -254.68707)
		(mid 137.619874 -254.641576)
		(end 137.437622 -254.691896)
		(width 0.0889)
		(layer "In13.Cu")
		(net "M_H_CPU1_SA_CA<5>")
	)
	(arc
		(start 138.377676 -254.691896)
		(mid 138.09472 -254.768073)
		(end 137.811764 -254.691896)
		(width 0.0889)
		(layer "In13.Cu")
		(net "M_H_CPU1_SA_CA<5>")
	)
	(arc
		(start 140.631926 -254.691896)
		(mid 140.449675 -254.641546)
		(end 140.266166 -254.68707)
		(width 0.0889)
		(layer "In13.Cu")
		(net "M_H_CPU1_SA_CA<5>")
	)
	(arc
		(start 143.451834 -254.691896)
		(mid 143.269583 -254.641546)
		(end 143.086074 -254.68707)
		(width 0.0889)
		(layer "In13.Cu")
		(net "M_H_CPU1_SA_CA<5>")
	)
	(segment
		(start 135.748014 -254.470408)
		(end 136.214866 -254.20447)
		(width 0.10668)
		(layer "F.Cu")
		(net "M_H_CPU1_SA_CA<4>")
	)
	(segment
		(start 136.393428 -254.531876)
		(end 136.40181 -254.52705)
		(width 0.0889)
		(layer "In13.Cu")
		(net "M_H_CPU1_SA_CA<4>")
	)
	(segment
		(start 147.863052 -254.776224)
		(end 150.434548 -254.776224)
		(width 0.14478)
		(layer "In13.Cu")
		(net "M_H_CPU1_SA_CA<4>")
	)
	(segment
		(start 171.798742 -251.310394)
		(end 172.15739 -251.310394)
		(width 0.0889)
		(layer "In13.Cu")
		(net "M_H_CPU1_SA_CA<4>")
	)
	(segment
		(start 171.741592 -251.253244)
		(end 171.798742 -251.310394)
		(width 0.0889)
		(layer "In13.Cu")
		(net "M_H_CPU1_SA_CA<4>")
	)
	(segment
		(start 144.84604 -254.536194)
		(end 144.862296 -254.526796)
		(width 0.0889)
		(layer "In13.Cu")
		(net "M_H_CPU1_SA_CA<4>")
	)
	(segment
		(start 136.967722 -254.52705)
		(end 136.976104 -254.531876)
		(width 0.0889)
		(layer "In13.Cu")
		(net "M_H_CPU1_SA_CA<4>")
	)
	(segment
		(start 141.667738 -254.52705)
		(end 141.67612 -254.531876)
		(width 0.0889)
		(layer "In13.Cu")
		(net "M_H_CPU1_SA_CA<4>")
	)
	(segment
		(start 147.14855 -254.776224)
		(end 147.863052 -254.776224)
		(width 0.0889)
		(layer "In13.Cu")
		(net "M_H_CPU1_SA_CA<4>")
	)
	(segment
		(start 144.862296 -254.526796)
		(end 144.878044 -254.517652)
		(width 0.0889)
		(layer "In13.Cu")
		(net "M_H_CPU1_SA_CA<4>")
	)
	(segment
		(start 143.547592 -254.52705)
		(end 143.555974 -254.531876)
		(width 0.0889)
		(layer "In13.Cu")
		(net "M_H_CPU1_SA_CA<4>")
	)
	(segment
		(start 172.51426 -251.310394)
		(end 172.939456 -250.885198)
		(width 0.14478)
		(layer "In13.Cu")
		(net "M_H_CPU1_SA_CA<4>")
	)
	(segment
		(start 168.006268 -252.263148)
		(end 169.087546 -252.263148)
		(width 0.14478)
		(layer "In13.Cu")
		(net "M_H_CPU1_SA_CA<4>")
	)
	(segment
		(start 171.474892 -250.993148)
		(end 171.734988 -251.253244)
		(width 0.14478)
		(layer "In13.Cu")
		(net "M_H_CPU1_SA_CA<4>")
	)
	(segment
		(start 151.393906 -253.816866)
		(end 161.958274 -253.816866)
		(width 0.14478)
		(layer "In13.Cu")
		(net "M_H_CPU1_SA_CA<4>")
	)
	(segment
		(start 144.477994 -254.520954)
		(end 144.488408 -254.52705)
		(width 0.0889)
		(layer "In13.Cu")
		(net "M_H_CPU1_SA_CA<4>")
	)
	(segment
		(start 150.434548 -254.776224)
		(end 151.393906 -253.816866)
		(width 0.14478)
		(layer "In13.Cu")
		(net "M_H_CPU1_SA_CA<4>")
	)
	(segment
		(start 146.279108 -254.570484)
		(end 146.586448 -254.877824)
		(width 0.0889)
		(layer "In13.Cu")
		(net "M_H_CPU1_SA_CA<4>")
	)
	(segment
		(start 136.060688 -254.4699)
		(end 136.08304 -254.553212)
		(width 0.0889)
		(layer "In13.Cu")
		(net "M_H_CPU1_SA_CA<4>")
	)
	(segment
		(start 167.259 -253.010416)
		(end 168.006268 -252.263148)
		(width 0.14478)
		(layer "In13.Cu")
		(net "M_H_CPU1_SA_CA<4>")
	)
	(segment
		(start 136.214866 -254.20447)
		(end 136.060688 -254.4699)
		(width 0.0889)
		(layer "In13.Cu")
		(net "M_H_CPU1_SA_CA<4>")
	)
	(segment
		(start 145.589244 -254.570484)
		(end 146.279108 -254.570484)
		(width 0.0889)
		(layer "In13.Cu")
		(net "M_H_CPU1_SA_CA<4>")
	)
	(segment
		(start 169.087546 -252.263148)
		(end 170.357546 -250.993148)
		(width 0.14478)
		(layer "In13.Cu")
		(net "M_H_CPU1_SA_CA<4>")
	)
	(segment
		(start 171.734988 -251.253244)
		(end 171.741592 -251.253244)
		(width 0.0889)
		(layer "In13.Cu")
		(net "M_H_CPU1_SA_CA<4>")
	)
	(segment
		(start 137.907776 -254.52705)
		(end 137.916158 -254.531876)
		(width 0.0889)
		(layer "In13.Cu")
		(net "M_H_CPU1_SA_CA<4>")
	)
	(segment
		(start 141.093444 -254.531876)
		(end 141.101826 -254.52705)
		(width 0.0889)
		(layer "In13.Cu")
		(net "M_H_CPU1_SA_CA<4>")
	)
	(segment
		(start 162.764724 -253.010416)
		(end 167.259 -253.010416)
		(width 0.14478)
		(layer "In13.Cu")
		(net "M_H_CPU1_SA_CA<4>")
	)
	(segment
		(start 147.04695 -254.877824)
		(end 147.14855 -254.776224)
		(width 0.0889)
		(layer "In13.Cu")
		(net "M_H_CPU1_SA_CA<4>")
	)
	(segment
		(start 140.15339 -254.531876)
		(end 140.161772 -254.52705)
		(width 0.0889)
		(layer "In13.Cu")
		(net "M_H_CPU1_SA_CA<4>")
	)
	(segment
		(start 172.939456 -250.885198)
		(end 176.072038 -250.885198)
		(width 0.14478)
		(layer "In13.Cu")
		(net "M_H_CPU1_SA_CA<4>")
	)
	(segment
		(start 146.586448 -254.877824)
		(end 147.04695 -254.877824)
		(width 0.0889)
		(layer "In13.Cu")
		(net "M_H_CPU1_SA_CA<4>")
	)
	(segment
		(start 170.357546 -250.993148)
		(end 171.474892 -250.993148)
		(width 0.14478)
		(layer "In13.Cu")
		(net "M_H_CPU1_SA_CA<4>")
	)
	(segment
		(start 172.15739 -251.310394)
		(end 172.51426 -251.310394)
		(width 0.14478)
		(layer "In13.Cu")
		(net "M_H_CPU1_SA_CA<4>")
	)
	(segment
		(start 161.958274 -253.816866)
		(end 162.764724 -253.010416)
		(width 0.14478)
		(layer "In13.Cu")
		(net "M_H_CPU1_SA_CA<4>")
	)
	(arc
		(start 142.98168 -254.52705)
		(mid 143.264636 -254.450873)
		(end 143.547592 -254.52705)
		(width 0.0889)
		(layer "In13.Cu")
		(net "M_H_CPU1_SA_CA<4>")
	)
	(arc
		(start 144.878044 -254.517652)
		(mid 145.154353 -254.450676)
		(end 145.428208 -254.52705)
		(width 0.0889)
		(layer "In13.Cu")
		(net "M_H_CPU1_SA_CA<4>")
	)
	(arc
		(start 136.40181 -254.52705)
		(mid 136.684766 -254.450873)
		(end 136.967722 -254.52705)
		(width 0.0889)
		(layer "In13.Cu")
		(net "M_H_CPU1_SA_CA<4>")
	)
	(arc
		(start 137.916158 -254.531876)
		(mid 138.099666 -254.57737)
		(end 138.281918 -254.52705)
		(width 0.0889)
		(layer "In13.Cu")
		(net "M_H_CPU1_SA_CA<4>")
	)
	(arc
		(start 139.78763 -254.52705)
		(mid 139.969881 -254.5774)
		(end 140.15339 -254.531876)
		(width 0.0889)
		(layer "In13.Cu")
		(net "M_H_CPU1_SA_CA<4>")
	)
	(arc
		(start 144.488408 -254.52705)
		(mid 144.666058 -254.57731)
		(end 144.84604 -254.536194)
		(width 0.0889)
		(layer "In13.Cu")
		(net "M_H_CPU1_SA_CA<4>")
	)
	(arc
		(start 139.221718 -254.52705)
		(mid 139.504674 -254.450873)
		(end 139.78763 -254.52705)
		(width 0.0889)
		(layer "In13.Cu")
		(net "M_H_CPU1_SA_CA<4>")
	)
	(arc
		(start 136.08304 -254.553212)
		(mid 136.24055 -254.57641)
		(end 136.393428 -254.531876)
		(width 0.0889)
		(layer "In13.Cu")
		(net "M_H_CPU1_SA_CA<4>")
	)
	(arc
		(start 141.101826 -254.52705)
		(mid 141.384782 -254.450873)
		(end 141.667738 -254.52705)
		(width 0.0889)
		(layer "In13.Cu")
		(net "M_H_CPU1_SA_CA<4>")
	)
	(arc
		(start 142.607792 -254.52705)
		(mid 142.794736 -254.577305)
		(end 142.98168 -254.52705)
		(width 0.0889)
		(layer "In13.Cu")
		(net "M_H_CPU1_SA_CA<4>")
	)
	(arc
		(start 137.341864 -254.52705)
		(mid 137.62482 -254.450873)
		(end 137.907776 -254.52705)
		(width 0.0889)
		(layer "In13.Cu")
		(net "M_H_CPU1_SA_CA<4>")
	)
	(arc
		(start 145.428208 -254.52705)
		(mid 145.505854 -254.559405)
		(end 145.589244 -254.570484)
		(width 0.0889)
		(layer "In13.Cu")
		(net "M_H_CPU1_SA_CA<4>")
	)
	(arc
		(start 143.555974 -254.531876)
		(mid 143.739736 -254.577492)
		(end 143.922242 -254.52705)
		(width 0.0889)
		(layer "In13.Cu")
		(net "M_H_CPU1_SA_CA<4>")
	)
	(arc
		(start 136.976104 -254.531876)
		(mid 137.159612 -254.57737)
		(end 137.341864 -254.52705)
		(width 0.0889)
		(layer "In13.Cu")
		(net "M_H_CPU1_SA_CA<4>")
	)
	(arc
		(start 143.922242 -254.52705)
		(mid 144.199309 -254.450779)
		(end 144.477994 -254.520954)
		(width 0.0889)
		(layer "In13.Cu")
		(net "M_H_CPU1_SA_CA<4>")
	)
	(arc
		(start 138.84783 -254.52705)
		(mid 139.034774 -254.577305)
		(end 139.221718 -254.52705)
		(width 0.0889)
		(layer "In13.Cu")
		(net "M_H_CPU1_SA_CA<4>")
	)
	(arc
		(start 142.04188 -254.52705)
		(mid 142.324836 -254.450873)
		(end 142.607792 -254.52705)
		(width 0.0889)
		(layer "In13.Cu")
		(net "M_H_CPU1_SA_CA<4>")
	)
	(arc
		(start 140.161772 -254.52705)
		(mid 140.444728 -254.450873)
		(end 140.727684 -254.52705)
		(width 0.0889)
		(layer "In13.Cu")
		(net "M_H_CPU1_SA_CA<4>")
	)
	(arc
		(start 141.67612 -254.531876)
		(mid 141.859628 -254.57737)
		(end 142.04188 -254.52705)
		(width 0.0889)
		(layer "In13.Cu")
		(net "M_H_CPU1_SA_CA<4>")
	)
	(arc
		(start 138.281918 -254.52705)
		(mid 138.564874 -254.450873)
		(end 138.84783 -254.52705)
		(width 0.0889)
		(layer "In13.Cu")
		(net "M_H_CPU1_SA_CA<4>")
	)
	(arc
		(start 140.727684 -254.52705)
		(mid 140.909935 -254.5774)
		(end 141.093444 -254.531876)
		(width 0.0889)
		(layer "In13.Cu")
		(net "M_H_CPU1_SA_CA<4>")
	)
	(segment
		(start 133.867906 -254.470408)
		(end 134.334758 -254.20447)
		(width 0.10668)
		(layer "F.Cu")
		(net "M_H_CPU1_SA_CA<3>")
	)
	(segment
		(start 166.830502 -252.460506)
		(end 166.530274 -252.160278)
		(width 0.14478)
		(layer "In13.Cu")
		(net "M_H_CPU1_SA_CA<3>")
	)
	(segment
		(start 144.878044 -253.891288)
		(end 144.862296 -253.882144)
		(width 0.0889)
		(layer "In13.Cu")
		(net "M_H_CPU1_SA_CA<3>")
	)
	(segment
		(start 141.101826 -253.88189)
		(end 141.093444 -253.877064)
		(width 0.0889)
		(layer "In13.Cu")
		(net "M_H_CPU1_SA_CA<3>")
	)
	(segment
		(start 170.2054 -250.256548)
		(end 169.20083 -251.261118)
		(width 0.14478)
		(layer "In13.Cu")
		(net "M_H_CPU1_SA_CA<3>")
	)
	(segment
		(start 137.916158 -253.877064)
		(end 137.907776 -253.88189)
		(width 0.0889)
		(layer "In13.Cu")
		(net "M_H_CPU1_SA_CA<3>")
	)
	(segment
		(start 171.97197 -250.035314)
		(end 171.750736 -250.256548)
		(width 0.14478)
		(layer "In13.Cu")
		(net "M_H_CPU1_SA_CA<3>")
	)
	(segment
		(start 169.20083 -251.261118)
		(end 168.281096 -251.261118)
		(width 0.14478)
		(layer "In13.Cu")
		(net "M_H_CPU1_SA_CA<3>")
	)
	(segment
		(start 165.97884 -252.460506)
		(end 165.727634 -252.460506)
		(width 0.14478)
		(layer "In13.Cu")
		(net "M_H_CPU1_SA_CA<3>")
	)
	(segment
		(start 166.279068 -252.160278)
		(end 165.97884 -252.460506)
		(width 0.14478)
		(layer "In13.Cu")
		(net "M_H_CPU1_SA_CA<3>")
	)
	(segment
		(start 171.750736 -250.256548)
		(end 170.2054 -250.256548)
		(width 0.14478)
		(layer "In13.Cu")
		(net "M_H_CPU1_SA_CA<3>")
	)
	(segment
		(start 134.584694 -253.91364)
		(end 134.488682 -253.93904)
		(width 0.0889)
		(layer "In13.Cu")
		(net "M_H_CPU1_SA_CA<3>")
	)
	(segment
		(start 144.862296 -253.882144)
		(end 144.84858 -253.87427)
		(width 0.0889)
		(layer "In13.Cu")
		(net "M_H_CPU1_SA_CA<3>")
	)
	(segment
		(start 167.081708 -252.460506)
		(end 166.830502 -252.460506)
		(width 0.14478)
		(layer "In13.Cu")
		(net "M_H_CPU1_SA_CA<3>")
	)
	(segment
		(start 161.771838 -253.367286)
		(end 151.178006 -253.367286)
		(width 0.14478)
		(layer "In13.Cu")
		(net "M_H_CPU1_SA_CA<3>")
	)
	(segment
		(start 165.727634 -252.460506)
		(end 165.427406 -252.160278)
		(width 0.14478)
		(layer "In13.Cu")
		(net "M_H_CPU1_SA_CA<3>")
	)
	(segment
		(start 140.161772 -253.88189)
		(end 140.15339 -253.877064)
		(width 0.0889)
		(layer "In13.Cu")
		(net "M_H_CPU1_SA_CA<3>")
	)
	(segment
		(start 147.758912 -254.316484)
		(end 147.269708 -254.316484)
		(width 0.0889)
		(layer "In13.Cu")
		(net "M_H_CPU1_SA_CA<3>")
	)
	(segment
		(start 136.976104 -253.877064)
		(end 136.967722 -253.88189)
		(width 0.0889)
		(layer "In13.Cu")
		(net "M_H_CPU1_SA_CA<3>")
	)
	(segment
		(start 151.178006 -253.367286)
		(end 150.228808 -254.316484)
		(width 0.14478)
		(layer "In13.Cu")
		(net "M_H_CPU1_SA_CA<3>")
	)
	(segment
		(start 147.053808 -254.100584)
		(end 146.017996 -254.100584)
		(width 0.0889)
		(layer "In13.Cu")
		(net "M_H_CPU1_SA_CA<3>")
	)
	(segment
		(start 135.461756 -253.88189)
		(end 135.453374 -253.877064)
		(width 0.0889)
		(layer "In13.Cu")
		(net "M_H_CPU1_SA_CA<3>")
	)
	(segment
		(start 150.228808 -254.316484)
		(end 147.758912 -254.316484)
		(width 0.14478)
		(layer "In13.Cu")
		(net "M_H_CPU1_SA_CA<3>")
	)
	(segment
		(start 143.555974 -253.877064)
		(end 143.547592 -253.88189)
		(width 0.0889)
		(layer "In13.Cu")
		(net "M_H_CPU1_SA_CA<3>")
	)
	(segment
		(start 136.40181 -253.88189)
		(end 136.393428 -253.877064)
		(width 0.0889)
		(layer "In13.Cu")
		(net "M_H_CPU1_SA_CA<3>")
	)
	(segment
		(start 166.530274 -252.160278)
		(end 166.279068 -252.160278)
		(width 0.14478)
		(layer "In13.Cu")
		(net "M_H_CPU1_SA_CA<3>")
	)
	(segment
		(start 165.427406 -252.160278)
		(end 162.978846 -252.160278)
		(width 0.14478)
		(layer "In13.Cu")
		(net "M_H_CPU1_SA_CA<3>")
	)
	(segment
		(start 134.488682 -253.93904)
		(end 134.334758 -254.20447)
		(width 0.0889)
		(layer "In13.Cu")
		(net "M_H_CPU1_SA_CA<3>")
	)
	(segment
		(start 141.67612 -253.877064)
		(end 141.667738 -253.88189)
		(width 0.0889)
		(layer "In13.Cu")
		(net "M_H_CPU1_SA_CA<3>")
	)
	(segment
		(start 144.488662 -253.88189)
		(end 144.47393 -253.890526)
		(width 0.0889)
		(layer "In13.Cu")
		(net "M_H_CPU1_SA_CA<3>")
	)
	(segment
		(start 162.978846 -252.160278)
		(end 161.771838 -253.367286)
		(width 0.14478)
		(layer "In13.Cu")
		(net "M_H_CPU1_SA_CA<3>")
	)
	(segment
		(start 147.269708 -254.316484)
		(end 147.053808 -254.100584)
		(width 0.0889)
		(layer "In13.Cu")
		(net "M_H_CPU1_SA_CA<3>")
	)
	(segment
		(start 146.017996 -254.100584)
		(end 145.794476 -253.877064)
		(width 0.0889)
		(layer "In13.Cu")
		(net "M_H_CPU1_SA_CA<3>")
	)
	(segment
		(start 168.281096 -251.261118)
		(end 167.081708 -252.460506)
		(width 0.14478)
		(layer "In13.Cu")
		(net "M_H_CPU1_SA_CA<3>")
	)
	(arc
		(start 136.027668 -253.88189)
		(mid 135.744712 -253.958067)
		(end 135.461756 -253.88189)
		(width 0.0889)
		(layer "In13.Cu")
		(net "M_H_CPU1_SA_CA<3>")
	)
	(arc
		(start 135.087614 -253.88189)
		(mid 134.839901 -253.95711)
		(end 134.584694 -253.91364)
		(width 0.0889)
		(layer "In13.Cu")
		(net "M_H_CPU1_SA_CA<3>")
	)
	(arc
		(start 142.98168 -253.88189)
		(mid 142.794736 -253.831635)
		(end 142.607792 -253.88189)
		(width 0.0889)
		(layer "In13.Cu")
		(net "M_H_CPU1_SA_CA<3>")
	)
	(arc
		(start 140.15339 -253.877064)
		(mid 139.969882 -253.83157)
		(end 139.78763 -253.88189)
		(width 0.0889)
		(layer "In13.Cu")
		(net "M_H_CPU1_SA_CA<3>")
	)
	(arc
		(start 141.093444 -253.877064)
		(mid 140.909936 -253.83157)
		(end 140.727684 -253.88189)
		(width 0.0889)
		(layer "In13.Cu")
		(net "M_H_CPU1_SA_CA<3>")
	)
	(arc
		(start 143.922242 -253.88189)
		(mid 143.739737 -253.831413)
		(end 143.555974 -253.877064)
		(width 0.0889)
		(layer "In13.Cu")
		(net "M_H_CPU1_SA_CA<3>")
	)
	(arc
		(start 144.47393 -253.890526)
		(mid 144.196947 -253.95833)
		(end 143.922242 -253.88189)
		(width 0.0889)
		(layer "In13.Cu")
		(net "M_H_CPU1_SA_CA<3>")
	)
	(arc
		(start 136.967722 -253.88189)
		(mid 136.684766 -253.958067)
		(end 136.40181 -253.88189)
		(width 0.0889)
		(layer "In13.Cu")
		(net "M_H_CPU1_SA_CA<3>")
	)
	(arc
		(start 142.607792 -253.88189)
		(mid 142.324836 -253.958067)
		(end 142.04188 -253.88189)
		(width 0.0889)
		(layer "In13.Cu")
		(net "M_H_CPU1_SA_CA<3>")
	)
	(arc
		(start 144.84858 -253.87427)
		(mid 144.66765 -253.831792)
		(end 144.488662 -253.88189)
		(width 0.0889)
		(layer "In13.Cu")
		(net "M_H_CPU1_SA_CA<3>")
	)
	(arc
		(start 136.393428 -253.877064)
		(mid 136.20992 -253.83157)
		(end 136.027668 -253.88189)
		(width 0.0889)
		(layer "In13.Cu")
		(net "M_H_CPU1_SA_CA<3>")
	)
	(arc
		(start 139.78763 -253.88189)
		(mid 139.504674 -253.958067)
		(end 139.221718 -253.88189)
		(width 0.0889)
		(layer "In13.Cu")
		(net "M_H_CPU1_SA_CA<3>")
	)
	(arc
		(start 141.667738 -253.88189)
		(mid 141.384782 -253.958067)
		(end 141.101826 -253.88189)
		(width 0.0889)
		(layer "In13.Cu")
		(net "M_H_CPU1_SA_CA<3>")
	)
	(arc
		(start 142.04188 -253.88189)
		(mid 141.859629 -253.83154)
		(end 141.67612 -253.877064)
		(width 0.0889)
		(layer "In13.Cu")
		(net "M_H_CPU1_SA_CA<3>")
	)
	(arc
		(start 135.453374 -253.877064)
		(mid 135.269866 -253.83157)
		(end 135.087614 -253.88189)
		(width 0.0889)
		(layer "In13.Cu")
		(net "M_H_CPU1_SA_CA<3>")
	)
	(arc
		(start 145.428208 -253.88189)
		(mid 145.154353 -253.95824)
		(end 144.878044 -253.891288)
		(width 0.0889)
		(layer "In13.Cu")
		(net "M_H_CPU1_SA_CA<3>")
	)
	(arc
		(start 137.341864 -253.88189)
		(mid 137.159613 -253.83154)
		(end 136.976104 -253.877064)
		(width 0.0889)
		(layer "In13.Cu")
		(net "M_H_CPU1_SA_CA<3>")
	)
	(arc
		(start 139.221718 -253.88189)
		(mid 139.034774 -253.831635)
		(end 138.84783 -253.88189)
		(width 0.0889)
		(layer "In13.Cu")
		(net "M_H_CPU1_SA_CA<3>")
	)
	(arc
		(start 138.281918 -253.88189)
		(mid 138.099667 -253.83154)
		(end 137.916158 -253.877064)
		(width 0.0889)
		(layer "In13.Cu")
		(net "M_H_CPU1_SA_CA<3>")
	)
	(arc
		(start 140.727684 -253.88189)
		(mid 140.444728 -253.958067)
		(end 140.161772 -253.88189)
		(width 0.0889)
		(layer "In13.Cu")
		(net "M_H_CPU1_SA_CA<3>")
	)
	(arc
		(start 137.907776 -253.88189)
		(mid 137.62482 -253.958067)
		(end 137.341864 -253.88189)
		(width 0.0889)
		(layer "In13.Cu")
		(net "M_H_CPU1_SA_CA<3>")
	)
	(arc
		(start 145.794476 -253.877064)
		(mid 145.610714 -253.831448)
		(end 145.428208 -253.88189)
		(width 0.0889)
		(layer "In13.Cu")
		(net "M_H_CPU1_SA_CA<3>")
	)
	(arc
		(start 138.84783 -253.88189)
		(mid 138.564874 -253.958067)
		(end 138.281918 -253.88189)
		(width 0.0889)
		(layer "In13.Cu")
		(net "M_H_CPU1_SA_CA<3>")
	)
	(arc
		(start 143.547592 -253.88189)
		(mid 143.264636 -253.958067)
		(end 142.98168 -253.88189)
		(width 0.0889)
		(layer "In13.Cu")
		(net "M_H_CPU1_SA_CA<3>")
	)
	(segment
		(start 134.337806 -253.660402)
		(end 134.804658 -253.394464)
		(width 0.10668)
		(layer "F.Cu")
		(net "M_H_CPU1_SA_CA<2>")
	)
	(segment
		(start 170.11523 -249.610372)
		(end 168.9989 -250.726702)
		(width 0.14478)
		(layer "In13.Cu")
		(net "M_H_CPU1_SA_CA<2>")
	)
	(segment
		(start 134.650734 -253.659894)
		(end 134.804658 -253.394464)
		(width 0.0889)
		(layer "In13.Cu")
		(net "M_H_CPU1_SA_CA<2>")
	)
	(segment
		(start 147.287488 -253.859284)
		(end 147.213828 -253.785624)
		(width 0.0889)
		(layer "In13.Cu")
		(net "M_H_CPU1_SA_CA<2>")
	)
	(segment
		(start 143.466566 -253.708408)
		(end 143.451834 -253.717044)
		(width 0.0889)
		(layer "In13.Cu")
		(net "M_H_CPU1_SA_CA<2>")
	)
	(segment
		(start 176.072038 -249.18543)
		(end 173.849792 -249.18543)
		(width 0.14478)
		(layer "In13.Cu")
		(net "M_H_CPU1_SA_CA<2>")
	)
	(segment
		(start 163.192714 -251.310394)
		(end 161.585402 -252.917706)
		(width 0.14478)
		(layer "In13.Cu")
		(net "M_H_CPU1_SA_CA<2>")
	)
	(segment
		(start 140.266166 -253.72187)
		(end 140.257784 -253.717044)
		(width 0.0889)
		(layer "In13.Cu")
		(net "M_H_CPU1_SA_CA<2>")
	)
	(segment
		(start 173.849792 -249.18543)
		(end 173.42485 -249.610372)
		(width 0.14478)
		(layer "In13.Cu")
		(net "M_H_CPU1_SA_CA<2>")
	)
	(segment
		(start 161.585402 -252.917706)
		(end 150.954486 -252.917706)
		(width 0.14478)
		(layer "In13.Cu")
		(net "M_H_CPU1_SA_CA<2>")
	)
	(segment
		(start 168.9989 -250.726702)
		(end 167.868092 -250.726702)
		(width 0.14478)
		(layer "In13.Cu")
		(net "M_H_CPU1_SA_CA<2>")
	)
	(segment
		(start 139.326112 -253.72187)
		(end 139.31773 -253.717044)
		(width 0.0889)
		(layer "In13.Cu")
		(net "M_H_CPU1_SA_CA<2>")
	)
	(segment
		(start 143.086074 -253.72187)
		(end 143.077692 -253.717044)
		(width 0.0889)
		(layer "In13.Cu")
		(net "M_H_CPU1_SA_CA<2>")
	)
	(segment
		(start 134.673086 -253.743206)
		(end 134.650734 -253.659894)
		(width 0.0889)
		(layer "In13.Cu")
		(net "M_H_CPU1_SA_CA<2>")
	)
	(segment
		(start 142.51178 -253.717044)
		(end 142.503398 -253.72187)
		(width 0.0889)
		(layer "In13.Cu")
		(net "M_H_CPU1_SA_CA<2>")
	)
	(segment
		(start 146.025616 -253.791466)
		(end 145.883884 -253.708408)
		(width 0.0889)
		(layer "In13.Cu")
		(net "M_H_CPU1_SA_CA<2>")
	)
	(segment
		(start 144.39265 -253.717044)
		(end 144.380966 -253.723902)
		(width 0.0889)
		(layer "In13.Cu")
		(net "M_H_CPU1_SA_CA<2>")
	)
	(segment
		(start 167.2844 -251.310394)
		(end 163.192714 -251.310394)
		(width 0.14478)
		(layer "In13.Cu")
		(net "M_H_CPU1_SA_CA<2>")
	)
	(segment
		(start 135.56615 -253.72187)
		(end 135.557768 -253.717044)
		(width 0.0889)
		(layer "In13.Cu")
		(net "M_H_CPU1_SA_CA<2>")
	)
	(segment
		(start 144.958054 -253.71679)
		(end 144.952466 -253.713488)
		(width 0.0889)
		(layer "In13.Cu")
		(net "M_H_CPU1_SA_CA<2>")
	)
	(segment
		(start 138.751818 -253.717044)
		(end 138.743436 -253.72187)
		(width 0.0889)
		(layer "In13.Cu")
		(net "M_H_CPU1_SA_CA<2>")
	)
	(segment
		(start 147.213828 -253.785624)
		(end 146.031458 -253.785624)
		(width 0.0889)
		(layer "In13.Cu")
		(net "M_H_CPU1_SA_CA<2>")
	)
	(segment
		(start 167.868092 -250.726702)
		(end 167.2844 -251.310394)
		(width 0.14478)
		(layer "In13.Cu")
		(net "M_H_CPU1_SA_CA<2>")
	)
	(segment
		(start 147.724114 -253.859284)
		(end 147.287488 -253.859284)
		(width 0.0889)
		(layer "In13.Cu")
		(net "M_H_CPU1_SA_CA<2>")
	)
	(segment
		(start 144.976342 -253.727204)
		(end 144.958054 -253.71679)
		(width 0.0889)
		(layer "In13.Cu")
		(net "M_H_CPU1_SA_CA<2>")
	)
	(segment
		(start 137.811764 -253.717044)
		(end 137.803382 -253.72187)
		(width 0.0889)
		(layer "In13.Cu")
		(net "M_H_CPU1_SA_CA<2>")
	)
	(segment
		(start 150.954486 -252.917706)
		(end 150.012908 -253.859284)
		(width 0.14478)
		(layer "In13.Cu")
		(net "M_H_CPU1_SA_CA<2>")
	)
	(segment
		(start 146.031458 -253.785624)
		(end 146.025616 -253.791466)
		(width 0.0889)
		(layer "In13.Cu")
		(net "M_H_CPU1_SA_CA<2>")
	)
	(segment
		(start 150.012908 -253.859284)
		(end 147.724114 -253.859284)
		(width 0.14478)
		(layer "In13.Cu")
		(net "M_H_CPU1_SA_CA<2>")
	)
	(segment
		(start 173.42485 -249.610372)
		(end 170.11523 -249.610372)
		(width 0.14478)
		(layer "In13.Cu")
		(net "M_H_CPU1_SA_CA<2>")
	)
	(arc
		(start 143.077692 -253.717044)
		(mid 142.794736 -253.640867)
		(end 142.51178 -253.717044)
		(width 0.0889)
		(layer "In13.Cu")
		(net "M_H_CPU1_SA_CA<2>")
	)
	(arc
		(start 136.497822 -253.717044)
		(mid 136.214866 -253.640867)
		(end 135.93191 -253.717044)
		(width 0.0889)
		(layer "In13.Cu")
		(net "M_H_CPU1_SA_CA<2>")
	)
	(arc
		(start 144.952466 -253.713488)
		(mid 144.672077 -253.640819)
		(end 144.39265 -253.717044)
		(width 0.0889)
		(layer "In13.Cu")
		(net "M_H_CPU1_SA_CA<2>")
	)
	(arc
		(start 140.631926 -253.717044)
		(mid 140.449675 -253.767394)
		(end 140.266166 -253.72187)
		(width 0.0889)
		(layer "In13.Cu")
		(net "M_H_CPU1_SA_CA<2>")
	)
	(arc
		(start 143.451834 -253.717044)
		(mid 143.269583 -253.767394)
		(end 143.086074 -253.72187)
		(width 0.0889)
		(layer "In13.Cu")
		(net "M_H_CPU1_SA_CA<2>")
	)
	(arc
		(start 137.437622 -253.717044)
		(mid 137.154666 -253.640867)
		(end 136.87171 -253.717044)
		(width 0.0889)
		(layer "In13.Cu")
		(net "M_H_CPU1_SA_CA<2>")
	)
	(arc
		(start 142.137638 -253.717044)
		(mid 141.854682 -253.640867)
		(end 141.571726 -253.717044)
		(width 0.0889)
		(layer "In13.Cu")
		(net "M_H_CPU1_SA_CA<2>")
	)
	(arc
		(start 145.332196 -253.717044)
		(mid 145.155568 -253.767277)
		(end 144.976342 -253.727204)
		(width 0.0889)
		(layer "In13.Cu")
		(net "M_H_CPU1_SA_CA<2>")
	)
	(arc
		(start 139.691872 -253.717044)
		(mid 139.509621 -253.767394)
		(end 139.326112 -253.72187)
		(width 0.0889)
		(layer "In13.Cu")
		(net "M_H_CPU1_SA_CA<2>")
	)
	(arc
		(start 135.93191 -253.717044)
		(mid 135.749659 -253.767394)
		(end 135.56615 -253.72187)
		(width 0.0889)
		(layer "In13.Cu")
		(net "M_H_CPU1_SA_CA<2>")
	)
	(arc
		(start 144.018254 -253.717044)
		(mid 143.743548 -253.64068)
		(end 143.466566 -253.708408)
		(width 0.0889)
		(layer "In13.Cu")
		(net "M_H_CPU1_SA_CA<2>")
	)
	(arc
		(start 136.87171 -253.717044)
		(mid 136.684766 -253.767299)
		(end 136.497822 -253.717044)
		(width 0.0889)
		(layer "In13.Cu")
		(net "M_H_CPU1_SA_CA<2>")
	)
	(arc
		(start 142.503398 -253.72187)
		(mid 142.31989 -253.767364)
		(end 142.137638 -253.717044)
		(width 0.0889)
		(layer "In13.Cu")
		(net "M_H_CPU1_SA_CA<2>")
	)
	(arc
		(start 138.377676 -253.717044)
		(mid 138.09472 -253.640867)
		(end 137.811764 -253.717044)
		(width 0.0889)
		(layer "In13.Cu")
		(net "M_H_CPU1_SA_CA<2>")
	)
	(arc
		(start 145.883884 -253.708408)
		(mid 145.606901 -253.640604)
		(end 145.332196 -253.717044)
		(width 0.0889)
		(layer "In13.Cu")
		(net "M_H_CPU1_SA_CA<2>")
	)
	(arc
		(start 141.571726 -253.717044)
		(mid 141.384782 -253.767299)
		(end 141.197838 -253.717044)
		(width 0.0889)
		(layer "In13.Cu")
		(net "M_H_CPU1_SA_CA<2>")
	)
	(arc
		(start 139.31773 -253.717044)
		(mid 139.034774 -253.640867)
		(end 138.751818 -253.717044)
		(width 0.0889)
		(layer "In13.Cu")
		(net "M_H_CPU1_SA_CA<2>")
	)
	(arc
		(start 135.557768 -253.717044)
		(mid 135.274812 -253.640867)
		(end 134.991856 -253.717044)
		(width 0.0889)
		(layer "In13.Cu")
		(net "M_H_CPU1_SA_CA<2>")
	)
	(arc
		(start 137.803382 -253.72187)
		(mid 137.619874 -253.767364)
		(end 137.437622 -253.717044)
		(width 0.0889)
		(layer "In13.Cu")
		(net "M_H_CPU1_SA_CA<2>")
	)
	(arc
		(start 141.197838 -253.717044)
		(mid 140.914882 -253.640867)
		(end 140.631926 -253.717044)
		(width 0.0889)
		(layer "In13.Cu")
		(net "M_H_CPU1_SA_CA<2>")
	)
	(arc
		(start 144.380966 -253.723902)
		(mid 144.198711 -253.767555)
		(end 144.018254 -253.717044)
		(width 0.0889)
		(layer "In13.Cu")
		(net "M_H_CPU1_SA_CA<2>")
	)
	(arc
		(start 134.991856 -253.717044)
		(mid 134.835418 -253.766015)
		(end 134.673086 -253.743206)
		(width 0.0889)
		(layer "In13.Cu")
		(net "M_H_CPU1_SA_CA<2>")
	)
	(arc
		(start 140.257784 -253.717044)
		(mid 139.974828 -253.640867)
		(end 139.691872 -253.717044)
		(width 0.0889)
		(layer "In13.Cu")
		(net "M_H_CPU1_SA_CA<2>")
	)
	(arc
		(start 138.743436 -253.72187)
		(mid 138.559928 -253.767364)
		(end 138.377676 -253.717044)
		(width 0.0889)
		(layer "In13.Cu")
		(net "M_H_CPU1_SA_CA<2>")
	)
	(segment
		(start 135.27786 -253.660402)
		(end 135.744712 -253.394464)
		(width 0.10668)
		(layer "F.Cu")
		(net "M_H_CPU1_SA_CA<1>")
	)
	(segment
		(start 135.89889 -253.129034)
		(end 135.995156 -253.103634)
		(width 0.0889)
		(layer "In13.Cu")
		(net "M_H_CPU1_SA_CA<1>")
	)
	(segment
		(start 161.398966 -252.468126)
		(end 163.406836 -250.460256)
		(width 0.14478)
		(layer "In13.Cu")
		(net "M_H_CPU1_SA_CA<1>")
	)
	(segment
		(start 140.257784 -253.071884)
		(end 140.266166 -253.067058)
		(width 0.0889)
		(layer "In13.Cu")
		(net "M_H_CPU1_SA_CA<1>")
	)
	(segment
		(start 138.743436 -253.067058)
		(end 138.751818 -253.071884)
		(width 0.0889)
		(layer "In13.Cu")
		(net "M_H_CPU1_SA_CA<1>")
	)
	(segment
		(start 170.307 -248.605548)
		(end 171.701714 -248.605548)
		(width 0.14478)
		(layer "In13.Cu")
		(net "M_H_CPU1_SA_CA<1>")
	)
	(segment
		(start 143.451834 -253.071884)
		(end 143.462248 -253.07798)
		(width 0.0889)
		(layer "In13.Cu")
		(net "M_H_CPU1_SA_CA<1>")
	)
	(segment
		(start 144.384268 -253.067058)
		(end 144.39265 -253.071884)
		(width 0.0889)
		(layer "In13.Cu")
		(net "M_H_CPU1_SA_CA<1>")
	)
	(segment
		(start 166.864284 -250.605036)
		(end 167.009064 -250.460256)
		(width 0.14478)
		(layer "In13.Cu")
		(net "M_H_CPU1_SA_CA<1>")
	)
	(segment
		(start 146.380454 -253.397004)
		(end 147.13077 -253.397004)
		(width 0.0889)
		(layer "In13.Cu")
		(net "M_H_CPU1_SA_CA<1>")
	)
	(segment
		(start 166.864284 -250.700286)
		(end 166.864284 -250.605036)
		(width 0.14478)
		(layer "In13.Cu")
		(net "M_H_CPU1_SA_CA<1>")
	)
	(segment
		(start 166.313104 -250.700286)
		(end 166.457884 -250.845066)
		(width 0.14478)
		(layer "In13.Cu")
		(net "M_H_CPU1_SA_CA<1>")
	)
	(segment
		(start 166.457884 -250.845066)
		(end 166.719504 -250.845066)
		(width 0.14478)
		(layer "In13.Cu")
		(net "M_H_CPU1_SA_CA<1>")
	)
	(segment
		(start 165.065964 -250.460256)
		(end 165.210744 -250.605036)
		(width 0.14478)
		(layer "In13.Cu")
		(net "M_H_CPU1_SA_CA<1>")
	)
	(segment
		(start 167.422068 -250.460256)
		(end 168.298876 -249.583448)
		(width 0.14478)
		(layer "In13.Cu")
		(net "M_H_CPU1_SA_CA<1>")
	)
	(segment
		(start 167.009064 -250.460256)
		(end 167.422068 -250.460256)
		(width 0.14478)
		(layer "In13.Cu")
		(net "M_H_CPU1_SA_CA<1>")
	)
	(segment
		(start 169.3291 -249.583448)
		(end 170.307 -248.605548)
		(width 0.14478)
		(layer "In13.Cu")
		(net "M_H_CPU1_SA_CA<1>")
	)
	(segment
		(start 137.803382 -253.067058)
		(end 137.811764 -253.071884)
		(width 0.0889)
		(layer "In13.Cu")
		(net "M_H_CPU1_SA_CA<1>")
	)
	(segment
		(start 166.168324 -250.460256)
		(end 166.313104 -250.605036)
		(width 0.14478)
		(layer "In13.Cu")
		(net "M_H_CPU1_SA_CA<1>")
	)
	(segment
		(start 145.615914 -253.148338)
		(end 146.131788 -253.148338)
		(width 0.0889)
		(layer "In13.Cu")
		(net "M_H_CPU1_SA_CA<1>")
	)
	(segment
		(start 165.210744 -250.605036)
		(end 165.210744 -250.700286)
		(width 0.14478)
		(layer "In13.Cu")
		(net "M_H_CPU1_SA_CA<1>")
	)
	(segment
		(start 165.355524 -250.845066)
		(end 165.617144 -250.845066)
		(width 0.14478)
		(layer "In13.Cu")
		(net "M_H_CPU1_SA_CA<1>")
	)
	(segment
		(start 165.906704 -250.460256)
		(end 166.168324 -250.460256)
		(width 0.14478)
		(layer "In13.Cu")
		(net "M_H_CPU1_SA_CA<1>")
	)
	(segment
		(start 147.13077 -253.397004)
		(end 147.417028 -253.110746)
		(width 0.14478)
		(layer "In13.Cu")
		(net "M_H_CPU1_SA_CA<1>")
	)
	(segment
		(start 147.417028 -253.110746)
		(end 150.101046 -253.110746)
		(width 0.14478)
		(layer "In13.Cu")
		(net "M_H_CPU1_SA_CA<1>")
	)
	(segment
		(start 165.761924 -250.605036)
		(end 165.906704 -250.460256)
		(width 0.14478)
		(layer "In13.Cu")
		(net "M_H_CPU1_SA_CA<1>")
	)
	(segment
		(start 165.210744 -250.700286)
		(end 165.355524 -250.845066)
		(width 0.14478)
		(layer "In13.Cu")
		(net "M_H_CPU1_SA_CA<1>")
	)
	(segment
		(start 165.617144 -250.845066)
		(end 165.761924 -250.700286)
		(width 0.14478)
		(layer "In13.Cu")
		(net "M_H_CPU1_SA_CA<1>")
	)
	(segment
		(start 150.101046 -253.110746)
		(end 150.743666 -252.468126)
		(width 0.14478)
		(layer "In13.Cu")
		(net "M_H_CPU1_SA_CA<1>")
	)
	(segment
		(start 139.31773 -253.071884)
		(end 139.326112 -253.067058)
		(width 0.0889)
		(layer "In13.Cu")
		(net "M_H_CPU1_SA_CA<1>")
	)
	(segment
		(start 165.761924 -250.700286)
		(end 165.761924 -250.605036)
		(width 0.14478)
		(layer "In13.Cu")
		(net "M_H_CPU1_SA_CA<1>")
	)
	(segment
		(start 168.298876 -249.583448)
		(end 169.3291 -249.583448)
		(width 0.14478)
		(layer "In13.Cu")
		(net "M_H_CPU1_SA_CA<1>")
	)
	(segment
		(start 144.952466 -253.07544)
		(end 144.958054 -253.072138)
		(width 0.0889)
		(layer "In13.Cu")
		(net "M_H_CPU1_SA_CA<1>")
	)
	(segment
		(start 144.958054 -253.072138)
		(end 144.976342 -253.061724)
		(width 0.0889)
		(layer "In13.Cu")
		(net "M_H_CPU1_SA_CA<1>")
	)
	(segment
		(start 146.131788 -253.148338)
		(end 146.380454 -253.397004)
		(width 0.0889)
		(layer "In13.Cu")
		(net "M_H_CPU1_SA_CA<1>")
	)
	(segment
		(start 163.406836 -250.460256)
		(end 165.065964 -250.460256)
		(width 0.14478)
		(layer "In13.Cu")
		(net "M_H_CPU1_SA_CA<1>")
	)
	(segment
		(start 166.313104 -250.605036)
		(end 166.313104 -250.700286)
		(width 0.14478)
		(layer "In13.Cu")
		(net "M_H_CPU1_SA_CA<1>")
	)
	(segment
		(start 150.743666 -252.468126)
		(end 161.398966 -252.468126)
		(width 0.14478)
		(layer "In13.Cu")
		(net "M_H_CPU1_SA_CA<1>")
	)
	(segment
		(start 143.077692 -253.071884)
		(end 143.086074 -253.067058)
		(width 0.0889)
		(layer "In13.Cu")
		(net "M_H_CPU1_SA_CA<1>")
	)
	(segment
		(start 171.701714 -248.605548)
		(end 171.97197 -248.335292)
		(width 0.14478)
		(layer "In13.Cu")
		(net "M_H_CPU1_SA_CA<1>")
	)
	(segment
		(start 142.503398 -253.067058)
		(end 142.51178 -253.071884)
		(width 0.0889)
		(layer "In13.Cu")
		(net "M_H_CPU1_SA_CA<1>")
	)
	(segment
		(start 166.719504 -250.845066)
		(end 166.864284 -250.700286)
		(width 0.14478)
		(layer "In13.Cu")
		(net "M_H_CPU1_SA_CA<1>")
	)
	(segment
		(start 135.744712 -253.394464)
		(end 135.89889 -253.129034)
		(width 0.0889)
		(layer "In13.Cu")
		(net "M_H_CPU1_SA_CA<1>")
	)
	(arc
		(start 136.497822 -253.071884)
		(mid 136.684766 -253.021629)
		(end 136.87171 -253.071884)
		(width 0.0889)
		(layer "In13.Cu")
		(net "M_H_CPU1_SA_CA<1>")
	)
	(arc
		(start 141.197838 -253.071884)
		(mid 141.384782 -253.021629)
		(end 141.571726 -253.071884)
		(width 0.0889)
		(layer "In13.Cu")
		(net "M_H_CPU1_SA_CA<1>")
	)
	(arc
		(start 138.377676 -253.071884)
		(mid 138.559927 -253.021534)
		(end 138.743436 -253.067058)
		(width 0.0889)
		(layer "In13.Cu")
		(net "M_H_CPU1_SA_CA<1>")
	)
	(arc
		(start 138.751818 -253.071884)
		(mid 139.034774 -253.148061)
		(end 139.31773 -253.071884)
		(width 0.0889)
		(layer "In13.Cu")
		(net "M_H_CPU1_SA_CA<1>")
	)
	(arc
		(start 137.437622 -253.071884)
		(mid 137.619873 -253.021534)
		(end 137.803382 -253.067058)
		(width 0.0889)
		(layer "In13.Cu")
		(net "M_H_CPU1_SA_CA<1>")
	)
	(arc
		(start 139.326112 -253.067058)
		(mid 139.50962 -253.021564)
		(end 139.691872 -253.071884)
		(width 0.0889)
		(layer "In13.Cu")
		(net "M_H_CPU1_SA_CA<1>")
	)
	(arc
		(start 137.811764 -253.071884)
		(mid 138.09472 -253.148061)
		(end 138.377676 -253.071884)
		(width 0.0889)
		(layer "In13.Cu")
		(net "M_H_CPU1_SA_CA<1>")
	)
	(arc
		(start 145.332196 -253.071884)
		(mid 145.468989 -253.128906)
		(end 145.615914 -253.148338)
		(width 0.0889)
		(layer "In13.Cu")
		(net "M_H_CPU1_SA_CA<1>")
	)
	(arc
		(start 135.995156 -253.103634)
		(mid 136.250221 -253.146985)
		(end 136.497822 -253.071884)
		(width 0.0889)
		(layer "In13.Cu")
		(net "M_H_CPU1_SA_CA<1>")
	)
	(arc
		(start 143.086074 -253.067058)
		(mid 143.269582 -253.021564)
		(end 143.451834 -253.071884)
		(width 0.0889)
		(layer "In13.Cu")
		(net "M_H_CPU1_SA_CA<1>")
	)
	(arc
		(start 142.137638 -253.071884)
		(mid 142.319889 -253.021534)
		(end 142.503398 -253.067058)
		(width 0.0889)
		(layer "In13.Cu")
		(net "M_H_CPU1_SA_CA<1>")
	)
	(arc
		(start 142.51178 -253.071884)
		(mid 142.794736 -253.148061)
		(end 143.077692 -253.071884)
		(width 0.0889)
		(layer "In13.Cu")
		(net "M_H_CPU1_SA_CA<1>")
	)
	(arc
		(start 144.018 -253.071884)
		(mid 144.200505 -253.021407)
		(end 144.384268 -253.067058)
		(width 0.0889)
		(layer "In13.Cu")
		(net "M_H_CPU1_SA_CA<1>")
	)
	(arc
		(start 143.462248 -253.07798)
		(mid 143.740934 -253.1482)
		(end 144.018 -253.071884)
		(width 0.0889)
		(layer "In13.Cu")
		(net "M_H_CPU1_SA_CA<1>")
	)
	(arc
		(start 141.571726 -253.071884)
		(mid 141.854682 -253.148061)
		(end 142.137638 -253.071884)
		(width 0.0889)
		(layer "In13.Cu")
		(net "M_H_CPU1_SA_CA<1>")
	)
	(arc
		(start 140.266166 -253.067058)
		(mid 140.449674 -253.021564)
		(end 140.631926 -253.071884)
		(width 0.0889)
		(layer "In13.Cu")
		(net "M_H_CPU1_SA_CA<1>")
	)
	(arc
		(start 140.631926 -253.071884)
		(mid 140.914882 -253.148061)
		(end 141.197838 -253.071884)
		(width 0.0889)
		(layer "In13.Cu")
		(net "M_H_CPU1_SA_CA<1>")
	)
	(arc
		(start 139.691872 -253.071884)
		(mid 139.974828 -253.148061)
		(end 140.257784 -253.071884)
		(width 0.0889)
		(layer "In13.Cu")
		(net "M_H_CPU1_SA_CA<1>")
	)
	(arc
		(start 144.39265 -253.071884)
		(mid 144.672078 -253.14805)
		(end 144.952466 -253.07544)
		(width 0.0889)
		(layer "In13.Cu")
		(net "M_H_CPU1_SA_CA<1>")
	)
	(arc
		(start 136.87171 -253.071884)
		(mid 137.154666 -253.148061)
		(end 137.437622 -253.071884)
		(width 0.0889)
		(layer "In13.Cu")
		(net "M_H_CPU1_SA_CA<1>")
	)
	(arc
		(start 144.976342 -253.061724)
		(mid 145.155571 -253.021571)
		(end 145.332196 -253.071884)
		(width 0.0889)
		(layer "In13.Cu")
		(net "M_H_CPU1_SA_CA<1>")
	)
	(segment
		(start 135.748014 -252.850396)
		(end 136.214866 -252.584458)
		(width 0.10668)
		(layer "F.Cu")
		(net "M_H_CPU1_SA_CA<0>")
	)
	(segment
		(start 136.08304 -252.9332)
		(end 136.060688 -252.849888)
		(width 0.0889)
		(layer "In13.Cu")
		(net "M_H_CPU1_SA_CA<0>")
	)
	(segment
		(start 170.265344 -247.91035)
		(end 169.239946 -248.935748)
		(width 0.14478)
		(layer "In13.Cu")
		(net "M_H_CPU1_SA_CA<0>")
	)
	(segment
		(start 144.878044 -252.89764)
		(end 144.862296 -252.906784)
		(width 0.0889)
		(layer "In13.Cu")
		(net "M_H_CPU1_SA_CA<0>")
	)
	(segment
		(start 147.40763 -252.481334)
		(end 146.518884 -252.481334)
		(width 0.0889)
		(layer "In13.Cu")
		(net "M_H_CPU1_SA_CA<0>")
	)
	(segment
		(start 169.239946 -248.935748)
		(end 167.894 -248.935748)
		(width 0.14478)
		(layer "In13.Cu")
		(net "M_H_CPU1_SA_CA<0>")
	)
	(segment
		(start 141.67612 -252.911864)
		(end 141.667738 -252.907038)
		(width 0.0889)
		(layer "In13.Cu")
		(net "M_H_CPU1_SA_CA<0>")
	)
	(segment
		(start 140.161772 -252.907038)
		(end 140.15339 -252.911864)
		(width 0.0889)
		(layer "In13.Cu")
		(net "M_H_CPU1_SA_CA<0>")
	)
	(segment
		(start 167.219376 -249.610372)
		(end 163.620704 -249.610372)
		(width 0.14478)
		(layer "In13.Cu")
		(net "M_H_CPU1_SA_CA<0>")
	)
	(segment
		(start 145.427954 -252.907038)
		(end 145.428208 -252.907038)
		(width 0.0889)
		(layer "In13.Cu")
		(net "M_H_CPU1_SA_CA<0>")
	)
	(segment
		(start 136.976104 -252.911864)
		(end 136.967722 -252.907038)
		(width 0.0889)
		(layer "In13.Cu")
		(net "M_H_CPU1_SA_CA<0>")
	)
	(segment
		(start 150.080218 -252.481334)
		(end 147.40763 -252.481334)
		(width 0.14478)
		(layer "In13.Cu")
		(net "M_H_CPU1_SA_CA<0>")
	)
	(segment
		(start 146.04238 -252.957838)
		(end 145.61566 -252.957838)
		(width 0.0889)
		(layer "In13.Cu")
		(net "M_H_CPU1_SA_CA<0>")
	)
	(segment
		(start 176.072038 -247.485408)
		(end 174.414434 -247.485408)
		(width 0.14478)
		(layer "In13.Cu")
		(net "M_H_CPU1_SA_CA<0>")
	)
	(segment
		(start 174.414434 -247.485408)
		(end 173.989492 -247.91035)
		(width 0.14478)
		(layer "In13.Cu")
		(net "M_H_CPU1_SA_CA<0>")
	)
	(segment
		(start 136.060688 -252.849888)
		(end 136.214866 -252.584458)
		(width 0.0889)
		(layer "In13.Cu")
		(net "M_H_CPU1_SA_CA<0>")
	)
	(segment
		(start 141.101826 -252.907038)
		(end 141.093444 -252.911864)
		(width 0.0889)
		(layer "In13.Cu")
		(net "M_H_CPU1_SA_CA<0>")
	)
	(segment
		(start 136.40181 -252.907038)
		(end 136.393428 -252.911864)
		(width 0.0889)
		(layer "In13.Cu")
		(net "M_H_CPU1_SA_CA<0>")
	)
	(segment
		(start 144.862296 -252.906784)
		(end 144.84604 -252.916182)
		(width 0.0889)
		(layer "In13.Cu")
		(net "M_H_CPU1_SA_CA<0>")
	)
	(segment
		(start 173.989492 -247.91035)
		(end 170.265344 -247.91035)
		(width 0.14478)
		(layer "In13.Cu")
		(net "M_H_CPU1_SA_CA<0>")
	)
	(segment
		(start 144.488408 -252.907038)
		(end 144.477994 -252.900942)
		(width 0.0889)
		(layer "In13.Cu")
		(net "M_H_CPU1_SA_CA<0>")
	)
	(segment
		(start 137.916158 -252.911864)
		(end 137.907776 -252.907038)
		(width 0.0889)
		(layer "In13.Cu")
		(net "M_H_CPU1_SA_CA<0>")
	)
	(segment
		(start 146.518884 -252.481334)
		(end 146.04238 -252.957838)
		(width 0.0889)
		(layer "In13.Cu")
		(net "M_H_CPU1_SA_CA<0>")
	)
	(segment
		(start 163.620704 -249.610372)
		(end 161.21253 -252.018546)
		(width 0.14478)
		(layer "In13.Cu")
		(net "M_H_CPU1_SA_CA<0>")
	)
	(segment
		(start 161.21253 -252.018546)
		(end 150.543006 -252.018546)
		(width 0.14478)
		(layer "In13.Cu")
		(net "M_H_CPU1_SA_CA<0>")
	)
	(segment
		(start 167.894 -248.935748)
		(end 167.219376 -249.610372)
		(width 0.14478)
		(layer "In13.Cu")
		(net "M_H_CPU1_SA_CA<0>")
	)
	(segment
		(start 143.555974 -252.911864)
		(end 143.547592 -252.907038)
		(width 0.0889)
		(layer "In13.Cu")
		(net "M_H_CPU1_SA_CA<0>")
	)
	(segment
		(start 150.543006 -252.018546)
		(end 150.080218 -252.481334)
		(width 0.14478)
		(layer "In13.Cu")
		(net "M_H_CPU1_SA_CA<0>")
	)
	(arc
		(start 137.907776 -252.907038)
		(mid 137.62482 -252.830861)
		(end 137.341864 -252.907038)
		(width 0.0889)
		(layer "In13.Cu")
		(net "M_H_CPU1_SA_CA<0>")
	)
	(arc
		(start 142.04188 -252.907038)
		(mid 141.859629 -252.957388)
		(end 141.67612 -252.911864)
		(width 0.0889)
		(layer "In13.Cu")
		(net "M_H_CPU1_SA_CA<0>")
	)
	(arc
		(start 139.221718 -252.907038)
		(mid 139.034774 -252.957293)
		(end 138.84783 -252.907038)
		(width 0.0889)
		(layer "In13.Cu")
		(net "M_H_CPU1_SA_CA<0>")
	)
	(arc
		(start 139.78763 -252.907038)
		(mid 139.504674 -252.830861)
		(end 139.221718 -252.907038)
		(width 0.0889)
		(layer "In13.Cu")
		(net "M_H_CPU1_SA_CA<0>")
	)
	(arc
		(start 137.341864 -252.907038)
		(mid 137.159613 -252.957388)
		(end 136.976104 -252.911864)
		(width 0.0889)
		(layer "In13.Cu")
		(net "M_H_CPU1_SA_CA<0>")
	)
	(arc
		(start 136.967722 -252.907038)
		(mid 136.684766 -252.830861)
		(end 136.40181 -252.907038)
		(width 0.0889)
		(layer "In13.Cu")
		(net "M_H_CPU1_SA_CA<0>")
	)
	(arc
		(start 142.607792 -252.907038)
		(mid 142.324836 -252.830861)
		(end 142.04188 -252.907038)
		(width 0.0889)
		(layer "In13.Cu")
		(net "M_H_CPU1_SA_CA<0>")
	)
	(arc
		(start 143.922242 -252.907038)
		(mid 143.739737 -252.957515)
		(end 143.555974 -252.911864)
		(width 0.0889)
		(layer "In13.Cu")
		(net "M_H_CPU1_SA_CA<0>")
	)
	(arc
		(start 136.393428 -252.911864)
		(mid 136.240558 -252.956505)
		(end 136.08304 -252.9332)
		(width 0.0889)
		(layer "In13.Cu")
		(net "M_H_CPU1_SA_CA<0>")
	)
	(arc
		(start 145.428208 -252.907038)
		(mid 145.154353 -252.830688)
		(end 144.878044 -252.89764)
		(width 0.0889)
		(layer "In13.Cu")
		(net "M_H_CPU1_SA_CA<0>")
	)
	(arc
		(start 144.477994 -252.900942)
		(mid 144.199308 -252.830722)
		(end 143.922242 -252.907038)
		(width 0.0889)
		(layer "In13.Cu")
		(net "M_H_CPU1_SA_CA<0>")
	)
	(arc
		(start 141.667738 -252.907038)
		(mid 141.384782 -252.830861)
		(end 141.101826 -252.907038)
		(width 0.0889)
		(layer "In13.Cu")
		(net "M_H_CPU1_SA_CA<0>")
	)
	(arc
		(start 138.281918 -252.907038)
		(mid 138.099667 -252.957388)
		(end 137.916158 -252.911864)
		(width 0.0889)
		(layer "In13.Cu")
		(net "M_H_CPU1_SA_CA<0>")
	)
	(arc
		(start 142.98168 -252.907038)
		(mid 142.794736 -252.957293)
		(end 142.607792 -252.907038)
		(width 0.0889)
		(layer "In13.Cu")
		(net "M_H_CPU1_SA_CA<0>")
	)
	(arc
		(start 144.84604 -252.916182)
		(mid 144.666058 -252.957282)
		(end 144.488408 -252.907038)
		(width 0.0889)
		(layer "In13.Cu")
		(net "M_H_CPU1_SA_CA<0>")
	)
	(arc
		(start 143.547592 -252.907038)
		(mid 143.264636 -252.830861)
		(end 142.98168 -252.907038)
		(width 0.0889)
		(layer "In13.Cu")
		(net "M_H_CPU1_SA_CA<0>")
	)
	(arc
		(start 138.84783 -252.907038)
		(mid 138.564874 -252.830861)
		(end 138.281918 -252.907038)
		(width 0.0889)
		(layer "In13.Cu")
		(net "M_H_CPU1_SA_CA<0>")
	)
	(arc
		(start 140.15339 -252.911864)
		(mid 139.969882 -252.957358)
		(end 139.78763 -252.907038)
		(width 0.0889)
		(layer "In13.Cu")
		(net "M_H_CPU1_SA_CA<0>")
	)
	(arc
		(start 141.093444 -252.911864)
		(mid 140.909936 -252.957358)
		(end 140.727684 -252.907038)
		(width 0.0889)
		(layer "In13.Cu")
		(net "M_H_CPU1_SA_CA<0>")
	)
	(arc
		(start 145.61566 -252.957838)
		(mid 145.518435 -252.944889)
		(end 145.427954 -252.907038)
		(width 0.0889)
		(layer "In13.Cu")
		(net "M_H_CPU1_SA_CA<0>")
	)
	(arc
		(start 140.727684 -252.907038)
		(mid 140.444728 -252.830861)
		(end 140.161772 -252.907038)
		(width 0.0889)
		(layer "In13.Cu")
		(net "M_H_CPU1_SA_CA<0>")
	)
	(segment
		(start 133.867906 -251.230384)
		(end 134.334758 -250.964446)
		(width 0.10668)
		(layer "F.Cu")
		(net "M_H_CPU1_RESET_N")
	)
	(segment
		(start 134.488682 -250.699016)
		(end 134.334758 -250.964446)
		(width 0.0889)
		(layer "In13.Cu")
		(net "M_H_CPU1_RESET_N")
	)
	(segment
		(start 134.584694 -250.673616)
		(end 134.488682 -250.699016)
		(width 0.0889)
		(layer "In13.Cu")
		(net "M_H_CPU1_RESET_N")
	)
	(segment
		(start 170.275758 -245.227348)
		(end 169.292778 -246.210328)
		(width 0.11684)
		(layer "In13.Cu")
		(net "M_H_CPU1_RESET_N")
	)
	(segment
		(start 147.35302 -250.724416)
		(end 145.16735 -250.724416)
		(width 0.0889)
		(layer "In13.Cu")
		(net "M_H_CPU1_RESET_N")
	)
	(segment
		(start 171.97197 -244.935248)
		(end 171.67987 -245.227348)
		(width 0.11684)
		(layer "In13.Cu")
		(net "M_H_CPU1_RESET_N")
	)
	(segment
		(start 135.461756 -250.641866)
		(end 135.453374 -250.63704)
		(width 0.0889)
		(layer "In13.Cu")
		(net "M_H_CPU1_RESET_N")
	)
	(segment
		(start 163.850574 -247.060466)
		(end 160.532064 -250.378976)
		(width 0.11684)
		(layer "In13.Cu")
		(net "M_H_CPU1_RESET_N")
	)
	(segment
		(start 149.82698 -250.378976)
		(end 149.529292 -250.676664)
		(width 0.11684)
		(layer "In13.Cu")
		(net "M_H_CPU1_RESET_N")
	)
	(segment
		(start 147.636484 -250.676664)
		(end 147.400772 -250.676664)
		(width 0.0889)
		(layer "In13.Cu")
		(net "M_H_CPU1_RESET_N")
	)
	(segment
		(start 141.101826 -250.641866)
		(end 141.093444 -250.63704)
		(width 0.0889)
		(layer "In13.Cu")
		(net "M_H_CPU1_RESET_N")
	)
	(segment
		(start 147.400772 -250.676664)
		(end 147.35302 -250.724416)
		(width 0.0889)
		(layer "In13.Cu")
		(net "M_H_CPU1_RESET_N")
	)
	(segment
		(start 140.161772 -250.641866)
		(end 140.15339 -250.63704)
		(width 0.0889)
		(layer "In13.Cu")
		(net "M_H_CPU1_RESET_N")
	)
	(segment
		(start 169.292778 -246.210328)
		(end 167.155876 -246.210328)
		(width 0.11684)
		(layer "In13.Cu")
		(net "M_H_CPU1_RESET_N")
	)
	(segment
		(start 166.305738 -247.060466)
		(end 163.850574 -247.060466)
		(width 0.11684)
		(layer "In13.Cu")
		(net "M_H_CPU1_RESET_N")
	)
	(segment
		(start 144.488662 -250.641866)
		(end 144.47393 -250.650502)
		(width 0.0889)
		(layer "In13.Cu")
		(net "M_H_CPU1_RESET_N")
	)
	(segment
		(start 136.976104 -250.63704)
		(end 136.967722 -250.641866)
		(width 0.0889)
		(layer "In13.Cu")
		(net "M_H_CPU1_RESET_N")
	)
	(segment
		(start 141.67612 -250.63704)
		(end 141.667738 -250.641866)
		(width 0.0889)
		(layer "In13.Cu")
		(net "M_H_CPU1_RESET_N")
	)
	(segment
		(start 136.40181 -250.641866)
		(end 136.393428 -250.63704)
		(width 0.0889)
		(layer "In13.Cu")
		(net "M_H_CPU1_RESET_N")
	)
	(segment
		(start 167.155876 -246.210328)
		(end 166.305738 -247.060466)
		(width 0.11684)
		(layer "In13.Cu")
		(net "M_H_CPU1_RESET_N")
	)
	(segment
		(start 149.529292 -250.676664)
		(end 147.636484 -250.676664)
		(width 0.11684)
		(layer "In13.Cu")
		(net "M_H_CPU1_RESET_N")
	)
	(segment
		(start 160.532064 -250.378976)
		(end 149.82698 -250.378976)
		(width 0.11684)
		(layer "In13.Cu")
		(net "M_H_CPU1_RESET_N")
	)
	(segment
		(start 171.67987 -245.227348)
		(end 170.275758 -245.227348)
		(width 0.11684)
		(layer "In13.Cu")
		(net "M_H_CPU1_RESET_N")
	)
	(segment
		(start 143.555974 -250.63704)
		(end 143.547592 -250.641866)
		(width 0.0889)
		(layer "In13.Cu")
		(net "M_H_CPU1_RESET_N")
	)
	(segment
		(start 144.862296 -250.64212)
		(end 144.84858 -250.634246)
		(width 0.0889)
		(layer "In13.Cu")
		(net "M_H_CPU1_RESET_N")
	)
	(segment
		(start 144.878044 -250.651264)
		(end 144.862296 -250.64212)
		(width 0.0889)
		(layer "In13.Cu")
		(net "M_H_CPU1_RESET_N")
	)
	(segment
		(start 137.916158 -250.63704)
		(end 137.907776 -250.641866)
		(width 0.0889)
		(layer "In13.Cu")
		(net "M_H_CPU1_RESET_N")
	)
	(arc
		(start 140.727684 -250.641866)
		(mid 140.444728 -250.718043)
		(end 140.161772 -250.641866)
		(width 0.0889)
		(layer "In13.Cu")
		(net "M_H_CPU1_RESET_N")
	)
	(arc
		(start 144.84858 -250.634246)
		(mid 144.66765 -250.591768)
		(end 144.488662 -250.641866)
		(width 0.0889)
		(layer "In13.Cu")
		(net "M_H_CPU1_RESET_N")
	)
	(arc
		(start 137.341864 -250.641866)
		(mid 137.159613 -250.591516)
		(end 136.976104 -250.63704)
		(width 0.0889)
		(layer "In13.Cu")
		(net "M_H_CPU1_RESET_N")
	)
	(arc
		(start 138.281918 -250.641866)
		(mid 138.099667 -250.591516)
		(end 137.916158 -250.63704)
		(width 0.0889)
		(layer "In13.Cu")
		(net "M_H_CPU1_RESET_N")
	)
	(arc
		(start 136.967722 -250.641866)
		(mid 136.684766 -250.718043)
		(end 136.40181 -250.641866)
		(width 0.0889)
		(layer "In13.Cu")
		(net "M_H_CPU1_RESET_N")
	)
	(arc
		(start 143.922242 -250.641866)
		(mid 143.739737 -250.591389)
		(end 143.555974 -250.63704)
		(width 0.0889)
		(layer "In13.Cu")
		(net "M_H_CPU1_RESET_N")
	)
	(arc
		(start 135.087614 -250.641866)
		(mid 134.839901 -250.717086)
		(end 134.584694 -250.673616)
		(width 0.0889)
		(layer "In13.Cu")
		(net "M_H_CPU1_RESET_N")
	)
	(arc
		(start 137.907776 -250.641866)
		(mid 137.62482 -250.718043)
		(end 137.341864 -250.641866)
		(width 0.0889)
		(layer "In13.Cu")
		(net "M_H_CPU1_RESET_N")
	)
	(arc
		(start 141.667738 -250.641866)
		(mid 141.384782 -250.718043)
		(end 141.101826 -250.641866)
		(width 0.0889)
		(layer "In13.Cu")
		(net "M_H_CPU1_RESET_N")
	)
	(arc
		(start 142.607792 -250.641866)
		(mid 142.324836 -250.718043)
		(end 142.04188 -250.641866)
		(width 0.0889)
		(layer "In13.Cu")
		(net "M_H_CPU1_RESET_N")
	)
	(arc
		(start 140.15339 -250.63704)
		(mid 139.969882 -250.591546)
		(end 139.78763 -250.641866)
		(width 0.0889)
		(layer "In13.Cu")
		(net "M_H_CPU1_RESET_N")
	)
	(arc
		(start 135.453374 -250.63704)
		(mid 135.269866 -250.591546)
		(end 135.087614 -250.641866)
		(width 0.0889)
		(layer "In13.Cu")
		(net "M_H_CPU1_RESET_N")
	)
	(arc
		(start 142.98168 -250.641866)
		(mid 142.794736 -250.591611)
		(end 142.607792 -250.641866)
		(width 0.0889)
		(layer "In13.Cu")
		(net "M_H_CPU1_RESET_N")
	)
	(arc
		(start 141.093444 -250.63704)
		(mid 140.909936 -250.591546)
		(end 140.727684 -250.641866)
		(width 0.0889)
		(layer "In13.Cu")
		(net "M_H_CPU1_RESET_N")
	)
	(arc
		(start 139.221718 -250.641866)
		(mid 139.034774 -250.591611)
		(end 138.84783 -250.641866)
		(width 0.0889)
		(layer "In13.Cu")
		(net "M_H_CPU1_RESET_N")
	)
	(arc
		(start 143.547592 -250.641866)
		(mid 143.264636 -250.718043)
		(end 142.98168 -250.641866)
		(width 0.0889)
		(layer "In13.Cu")
		(net "M_H_CPU1_RESET_N")
	)
	(arc
		(start 138.84783 -250.641866)
		(mid 138.564874 -250.718043)
		(end 138.281918 -250.641866)
		(width 0.0889)
		(layer "In13.Cu")
		(net "M_H_CPU1_RESET_N")
	)
	(arc
		(start 136.027668 -250.641866)
		(mid 135.744712 -250.718043)
		(end 135.461756 -250.641866)
		(width 0.0889)
		(layer "In13.Cu")
		(net "M_H_CPU1_RESET_N")
	)
	(arc
		(start 136.393428 -250.63704)
		(mid 136.20992 -250.591546)
		(end 136.027668 -250.641866)
		(width 0.0889)
		(layer "In13.Cu")
		(net "M_H_CPU1_RESET_N")
	)
	(arc
		(start 139.78763 -250.641866)
		(mid 139.504674 -250.718043)
		(end 139.221718 -250.641866)
		(width 0.0889)
		(layer "In13.Cu")
		(net "M_H_CPU1_RESET_N")
	)
	(arc
		(start 142.04188 -250.641866)
		(mid 141.859629 -250.591516)
		(end 141.67612 -250.63704)
		(width 0.0889)
		(layer "In13.Cu")
		(net "M_H_CPU1_RESET_N")
	)
	(arc
		(start 144.47393 -250.650502)
		(mid 144.196947 -250.718306)
		(end 143.922242 -250.641866)
		(width 0.0889)
		(layer "In13.Cu")
		(net "M_H_CPU1_RESET_N")
	)
	(arc
		(start 145.16735 -250.724416)
		(mid 145.017566 -250.708124)
		(end 144.878044 -250.651264)
		(width 0.0889)
		(layer "In13.Cu")
		(net "M_H_CPU1_RESET_N")
	)
	(segment
		(start 135.748014 -256.09042)
		(end 136.214866 -255.824482)
		(width 0.14732)
		(layer "F.Cu")
		(net "M_H_CPU1_CLK_DP<0>")
	)
	(segment
		(start 165.697916 -256.798064)
		(end 166.034974 -256.461006)
		(width 0.16002)
		(layer "In13.Cu")
		(net "M_H_CPU1_CLK_DP<0>")
	)
	(segment
		(start 164.928296 -257.353054)
		(end 165.088316 -257.513074)
		(width 0.16002)
		(layer "In13.Cu")
		(net "M_H_CPU1_CLK_DP<0>")
	)
	(segment
		(start 166.034974 -256.461006)
		(end 166.734998 -256.461006)
		(width 0.16002)
		(layer "In13.Cu")
		(net "M_H_CPU1_CLK_DP<0>")
	)
	(segment
		(start 144.86382 -256.149602)
		(end 144.884648 -256.13741)
		(width 0.09525)
		(layer "In13.Cu")
		(net "M_H_CPU1_CLK_DP<0>")
	)
	(segment
		(start 145.541238 -256.237994)
		(end 146.675602 -257.372358)
		(width 0.09525)
		(layer "In13.Cu")
		(net "M_H_CPU1_CLK_DP<0>")
	)
	(segment
		(start 167.072056 -256.798064)
		(end 167.072056 -257.353054)
		(width 0.16002)
		(layer "In13.Cu")
		(net "M_H_CPU1_CLK_DP<0>")
	)
	(segment
		(start 167.681656 -257.513074)
		(end 167.841676 -257.353054)
		(width 0.16002)
		(layer "In13.Cu")
		(net "M_H_CPU1_CLK_DP<0>")
	)
	(segment
		(start 141.094968 -256.154428)
		(end 141.10335 -256.149602)
		(width 0.09525)
		(layer "In13.Cu")
		(net "M_H_CPU1_CLK_DP<0>")
	)
	(segment
		(start 155.94457 -256.461006)
		(end 164.591238 -256.461006)
		(width 0.16002)
		(layer "In13.Cu")
		(net "M_H_CPU1_CLK_DP<0>")
	)
	(segment
		(start 136.214866 -255.824482)
		(end 136.060942 -256.089912)
		(width 0.09525)
		(layer "In13.Cu")
		(net "M_H_CPU1_CLK_DP<0>")
	)
	(segment
		(start 167.841676 -256.798064)
		(end 168.178734 -256.461006)
		(width 0.16002)
		(layer "In13.Cu")
		(net "M_H_CPU1_CLK_DP<0>")
	)
	(segment
		(start 150.89378 -257.313176)
		(end 152.38095 -255.826006)
		(width 0.16002)
		(layer "In13.Cu")
		(net "M_H_CPU1_CLK_DP<0>")
	)
	(segment
		(start 171.72178 -253.685548)
		(end 171.97197 -253.435358)
		(width 0.16002)
		(layer "In13.Cu")
		(net "M_H_CPU1_CLK_DP<0>")
	)
	(segment
		(start 166.734998 -256.461006)
		(end 167.072056 -256.798064)
		(width 0.16002)
		(layer "In13.Cu")
		(net "M_H_CPU1_CLK_DP<0>")
	)
	(segment
		(start 167.841676 -257.353054)
		(end 167.841676 -256.798064)
		(width 0.16002)
		(layer "In13.Cu")
		(net "M_H_CPU1_CLK_DP<0>")
	)
	(segment
		(start 140.154914 -256.154428)
		(end 140.163296 -256.149602)
		(width 0.09525)
		(layer "In13.Cu")
		(net "M_H_CPU1_CLK_DP<0>")
	)
	(segment
		(start 167.232076 -257.513074)
		(end 167.681656 -257.513074)
		(width 0.16002)
		(layer "In13.Cu")
		(net "M_H_CPU1_CLK_DP<0>")
	)
	(segment
		(start 147.79879 -257.313176)
		(end 150.89378 -257.313176)
		(width 0.16002)
		(layer "In13.Cu")
		(net "M_H_CPU1_CLK_DP<0>")
	)
	(segment
		(start 137.906252 -256.149602)
		(end 137.914634 -256.154428)
		(width 0.09525)
		(layer "In13.Cu")
		(net "M_H_CPU1_CLK_DP<0>")
	)
	(segment
		(start 168.859708 -256.12344)
		(end 168.859708 -255.925828)
		(width 0.16002)
		(layer "In13.Cu")
		(net "M_H_CPU1_CLK_DP<0>")
	)
	(segment
		(start 169.197528 -255.588008)
		(end 169.39514 -255.588008)
		(width 0.16002)
		(layer "In13.Cu")
		(net "M_H_CPU1_CLK_DP<0>")
	)
	(segment
		(start 136.966198 -256.149602)
		(end 136.97458 -256.154428)
		(width 0.09525)
		(layer "In13.Cu")
		(net "M_H_CPU1_CLK_DP<0>")
	)
	(segment
		(start 169.39514 -255.588008)
		(end 171.2976 -253.685548)
		(width 0.16002)
		(layer "In13.Cu")
		(net "M_H_CPU1_CLK_DP<0>")
	)
	(segment
		(start 143.914876 -256.154428)
		(end 143.923258 -256.149602)
		(width 0.09525)
		(layer "In13.Cu")
		(net "M_H_CPU1_CLK_DP<0>")
	)
	(segment
		(start 165.537896 -257.513074)
		(end 165.697916 -257.353054)
		(width 0.16002)
		(layer "In13.Cu")
		(net "M_H_CPU1_CLK_DP<0>")
	)
	(segment
		(start 165.088316 -257.513074)
		(end 165.537896 -257.513074)
		(width 0.16002)
		(layer "In13.Cu")
		(net "M_H_CPU1_CLK_DP<0>")
	)
	(segment
		(start 167.072056 -257.353054)
		(end 167.232076 -257.513074)
		(width 0.16002)
		(layer "In13.Cu")
		(net "M_H_CPU1_CLK_DP<0>")
	)
	(segment
		(start 168.178734 -256.461006)
		(end 168.522142 -256.461006)
		(width 0.16002)
		(layer "In13.Cu")
		(net "M_H_CPU1_CLK_DP<0>")
	)
	(segment
		(start 165.697916 -257.353054)
		(end 165.697916 -256.798064)
		(width 0.16002)
		(layer "In13.Cu")
		(net "M_H_CPU1_CLK_DP<0>")
	)
	(segment
		(start 146.675602 -257.372358)
		(end 147.715986 -257.372358)
		(width 0.09525)
		(layer "In13.Cu")
		(net "M_H_CPU1_CLK_DP<0>")
	)
	(segment
		(start 152.38095 -255.826006)
		(end 155.30957 -255.826006)
		(width 0.16002)
		(layer "In13.Cu")
		(net "M_H_CPU1_CLK_DP<0>")
	)
	(segment
		(start 155.30957 -255.826006)
		(end 155.94457 -256.461006)
		(width 0.16002)
		(layer "In13.Cu")
		(net "M_H_CPU1_CLK_DP<0>")
	)
	(segment
		(start 144.849342 -256.157984)
		(end 144.86382 -256.149602)
		(width 0.09525)
		(layer "In13.Cu")
		(net "M_H_CPU1_CLK_DP<0>")
	)
	(segment
		(start 168.859708 -255.925828)
		(end 169.197528 -255.588008)
		(width 0.16002)
		(layer "In13.Cu")
		(net "M_H_CPU1_CLK_DP<0>")
	)
	(segment
		(start 136.394952 -256.154428)
		(end 136.403334 -256.149602)
		(width 0.09525)
		(layer "In13.Cu")
		(net "M_H_CPU1_CLK_DP<0>")
	)
	(segment
		(start 136.060942 -256.089912)
		(end 136.08431 -256.17678)
		(width 0.09525)
		(layer "In13.Cu")
		(net "M_H_CPU1_CLK_DP<0>")
	)
	(segment
		(start 147.715986 -257.372358)
		(end 147.775168 -257.313176)
		(width 0.09525)
		(layer "In13.Cu")
		(net "M_H_CPU1_CLK_DP<0>")
	)
	(segment
		(start 164.591238 -256.461006)
		(end 164.928296 -256.798064)
		(width 0.16002)
		(layer "In13.Cu")
		(net "M_H_CPU1_CLK_DP<0>")
	)
	(segment
		(start 164.928296 -256.798064)
		(end 164.928296 -257.353054)
		(width 0.16002)
		(layer "In13.Cu")
		(net "M_H_CPU1_CLK_DP<0>")
	)
	(segment
		(start 171.2976 -253.685548)
		(end 171.72178 -253.685548)
		(width 0.16002)
		(layer "In13.Cu")
		(net "M_H_CPU1_CLK_DP<0>")
	)
	(segment
		(start 168.522142 -256.461006)
		(end 168.859708 -256.12344)
		(width 0.16002)
		(layer "In13.Cu")
		(net "M_H_CPU1_CLK_DP<0>")
	)
	(segment
		(start 143.923258 -256.149602)
		(end 143.93799 -256.140966)
		(width 0.09525)
		(layer "In13.Cu")
		(net "M_H_CPU1_CLK_DP<0>")
	)
	(segment
		(start 141.666214 -256.149602)
		(end 141.674596 -256.154428)
		(width 0.09525)
		(layer "In13.Cu")
		(net "M_H_CPU1_CLK_DP<0>")
	)
	(segment
		(start 147.775168 -257.313176)
		(end 147.79879 -257.313176)
		(width 0.09525)
		(layer "In13.Cu")
		(net "M_H_CPU1_CLK_DP<0>")
	)
	(arc
		(start 144.884648 -256.13741)
		(mid 145.157253 -256.073614)
		(end 145.426684 -256.149602)
		(width 0.09525)
		(layer "In13.Cu")
		(net "M_H_CPU1_CLK_DP<0>")
	)
	(arc
		(start 138.846306 -256.149602)
		(mid 139.034774 -256.200279)
		(end 139.223242 -256.149602)
		(width 0.09525)
		(layer "In13.Cu")
		(net "M_H_CPU1_CLK_DP<0>")
	)
	(arc
		(start 145.426684 -256.149602)
		(mid 145.486819 -256.190093)
		(end 145.541238 -256.237994)
		(width 0.09525)
		(layer "In13.Cu")
		(net "M_H_CPU1_CLK_DP<0>")
	)
	(arc
		(start 136.08431 -256.17678)
		(mid 136.24206 -256.199299)
		(end 136.394952 -256.154428)
		(width 0.09525)
		(layer "In13.Cu")
		(net "M_H_CPU1_CLK_DP<0>")
	)
	(arc
		(start 137.343388 -256.149602)
		(mid 137.62482 -256.073847)
		(end 137.906252 -256.149602)
		(width 0.09525)
		(layer "In13.Cu")
		(net "M_H_CPU1_CLK_DP<0>")
	)
	(arc
		(start 141.10335 -256.149602)
		(mid 141.384782 -256.073847)
		(end 141.666214 -256.149602)
		(width 0.09525)
		(layer "In13.Cu")
		(net "M_H_CPU1_CLK_DP<0>")
	)
	(arc
		(start 139.786106 -256.149602)
		(mid 139.969881 -256.200374)
		(end 140.154914 -256.154428)
		(width 0.09525)
		(layer "In13.Cu")
		(net "M_H_CPU1_CLK_DP<0>")
	)
	(arc
		(start 142.983204 -256.149602)
		(mid 143.264636 -256.073847)
		(end 143.546068 -256.149602)
		(width 0.09525)
		(layer "In13.Cu")
		(net "M_H_CPU1_CLK_DP<0>")
	)
	(arc
		(start 141.674596 -256.154428)
		(mid 141.859628 -256.200342)
		(end 142.043404 -256.149602)
		(width 0.09525)
		(layer "In13.Cu")
		(net "M_H_CPU1_CLK_DP<0>")
	)
	(arc
		(start 137.914634 -256.154428)
		(mid 138.099666 -256.200342)
		(end 138.283442 -256.149602)
		(width 0.09525)
		(layer "In13.Cu")
		(net "M_H_CPU1_CLK_DP<0>")
	)
	(arc
		(start 140.72616 -256.149602)
		(mid 140.909935 -256.200374)
		(end 141.094968 -256.154428)
		(width 0.09525)
		(layer "In13.Cu")
		(net "M_H_CPU1_CLK_DP<0>")
	)
	(arc
		(start 143.546068 -256.149602)
		(mid 143.729843 -256.200374)
		(end 143.914876 -256.154428)
		(width 0.09525)
		(layer "In13.Cu")
		(net "M_H_CPU1_CLK_DP<0>")
	)
	(arc
		(start 142.043404 -256.149602)
		(mid 142.324836 -256.073847)
		(end 142.606268 -256.149602)
		(width 0.09525)
		(layer "In13.Cu")
		(net "M_H_CPU1_CLK_DP<0>")
	)
	(arc
		(start 136.97458 -256.154428)
		(mid 137.159612 -256.200342)
		(end 137.343388 -256.149602)
		(width 0.09525)
		(layer "In13.Cu")
		(net "M_H_CPU1_CLK_DP<0>")
	)
	(arc
		(start 140.163296 -256.149602)
		(mid 140.444728 -256.073847)
		(end 140.72616 -256.149602)
		(width 0.09525)
		(layer "In13.Cu")
		(net "M_H_CPU1_CLK_DP<0>")
	)
	(arc
		(start 136.403334 -256.149602)
		(mid 136.684766 -256.073847)
		(end 136.966198 -256.149602)
		(width 0.09525)
		(layer "In13.Cu")
		(net "M_H_CPU1_CLK_DP<0>")
	)
	(arc
		(start 139.223242 -256.149602)
		(mid 139.504674 -256.073847)
		(end 139.786106 -256.149602)
		(width 0.09525)
		(layer "In13.Cu")
		(net "M_H_CPU1_CLK_DP<0>")
	)
	(arc
		(start 143.93799 -256.140966)
		(mid 144.213449 -256.073581)
		(end 144.48663 -256.149602)
		(width 0.09525)
		(layer "In13.Cu")
		(net "M_H_CPU1_CLK_DP<0>")
	)
	(arc
		(start 138.283442 -256.149602)
		(mid 138.564874 -256.073847)
		(end 138.846306 -256.149602)
		(width 0.09525)
		(layer "In13.Cu")
		(net "M_H_CPU1_CLK_DP<0>")
	)
	(arc
		(start 144.48663 -256.149602)
		(mid 144.666909 -256.200433)
		(end 144.849342 -256.157984)
		(width 0.09525)
		(layer "In13.Cu")
		(net "M_H_CPU1_CLK_DP<0>")
	)
	(arc
		(start 142.606268 -256.149602)
		(mid 142.794736 -256.200279)
		(end 142.983204 -256.149602)
		(width 0.09525)
		(layer "In13.Cu")
		(net "M_H_CPU1_CLK_DP<0>")
	)
	(segment
		(start 135.27786 -256.900426)
		(end 135.744712 -256.634488)
		(width 0.14732)
		(layer "F.Cu")
		(net "M_H_CPU1_CLK_DN<0>")
	)
	(segment
		(start 151.019002 -257.615436)
		(end 152.506172 -256.128266)
		(width 0.16002)
		(layer "In13.Cu")
		(net "M_H_CPU1_CLK_DN<0>")
	)
	(segment
		(start 145.410936 -256.368296)
		(end 146.599148 -257.556508)
		(width 0.09525)
		(layer "In13.Cu")
		(net "M_H_CPU1_CLK_DN<0>")
	)
	(segment
		(start 166.609776 -256.763266)
		(end 166.769796 -256.923286)
		(width 0.16002)
		(layer "In13.Cu")
		(net "M_H_CPU1_CLK_DN<0>")
	)
	(segment
		(start 171.422822 -253.987808)
		(end 171.674536 -253.987808)
		(width 0.16002)
		(layer "In13.Cu")
		(net "M_H_CPU1_CLK_DN<0>")
	)
	(segment
		(start 138.74496 -256.304542)
		(end 138.753342 -256.309368)
		(width 0.09525)
		(layer "In13.Cu")
		(net "M_H_CPU1_CLK_DN<0>")
	)
	(segment
		(start 155.819348 -256.763266)
		(end 164.466016 -256.763266)
		(width 0.16002)
		(layer "In13.Cu")
		(net "M_H_CPU1_CLK_DN<0>")
	)
	(segment
		(start 166.769796 -256.923286)
		(end 166.769796 -257.478276)
		(width 0.16002)
		(layer "In13.Cu")
		(net "M_H_CPU1_CLK_DN<0>")
	)
	(segment
		(start 142.504922 -256.304542)
		(end 142.513304 -256.309368)
		(width 0.09525)
		(layer "In13.Cu")
		(net "M_H_CPU1_CLK_DN<0>")
	)
	(segment
		(start 168.143936 -256.923286)
		(end 168.303956 -256.763266)
		(width 0.16002)
		(layer "In13.Cu")
		(net "M_H_CPU1_CLK_DN<0>")
	)
	(segment
		(start 146.599148 -257.556508)
		(end 147.71624 -257.556508)
		(width 0.09525)
		(layer "In13.Cu")
		(net "M_H_CPU1_CLK_DN<0>")
	)
	(segment
		(start 152.506172 -256.128266)
		(end 155.184348 -256.128266)
		(width 0.16002)
		(layer "In13.Cu")
		(net "M_H_CPU1_CLK_DN<0>")
	)
	(segment
		(start 139.316206 -256.309368)
		(end 139.324588 -256.304542)
		(width 0.09525)
		(layer "In13.Cu")
		(net "M_H_CPU1_CLK_DN<0>")
	)
	(segment
		(start 164.626036 -256.923286)
		(end 164.626036 -257.478276)
		(width 0.16002)
		(layer "In13.Cu")
		(net "M_H_CPU1_CLK_DN<0>")
	)
	(segment
		(start 166.769796 -257.478276)
		(end 167.106854 -257.815334)
		(width 0.16002)
		(layer "In13.Cu")
		(net "M_H_CPU1_CLK_DN<0>")
	)
	(segment
		(start 135.898636 -256.369058)
		(end 135.999474 -256.342388)
		(width 0.09525)
		(layer "In13.Cu")
		(net "M_H_CPU1_CLK_DN<0>")
	)
	(segment
		(start 143.076168 -256.309368)
		(end 143.08455 -256.304542)
		(width 0.09525)
		(layer "In13.Cu")
		(net "M_H_CPU1_CLK_DN<0>")
	)
	(segment
		(start 164.626036 -257.478276)
		(end 164.963094 -257.815334)
		(width 0.16002)
		(layer "In13.Cu")
		(net "M_H_CPU1_CLK_DN<0>")
	)
	(segment
		(start 167.106854 -257.815334)
		(end 167.806878 -257.815334)
		(width 0.16002)
		(layer "In13.Cu")
		(net "M_H_CPU1_CLK_DN<0>")
	)
	(segment
		(start 144.935702 -256.32156)
		(end 144.971008 -256.300986)
		(width 0.09525)
		(layer "In13.Cu")
		(net "M_H_CPU1_CLK_DN<0>")
	)
	(segment
		(start 171.674536 -253.987808)
		(end 171.97197 -254.285242)
		(width 0.16002)
		(layer "In13.Cu")
		(net "M_H_CPU1_CLK_DN<0>")
	)
	(segment
		(start 165.663118 -257.815334)
		(end 166.000176 -257.478276)
		(width 0.16002)
		(layer "In13.Cu")
		(net "M_H_CPU1_CLK_DN<0>")
	)
	(segment
		(start 168.647364 -256.763266)
		(end 171.422822 -253.987808)
		(width 0.16002)
		(layer "In13.Cu")
		(net "M_H_CPU1_CLK_DN<0>")
	)
	(segment
		(start 164.963094 -257.815334)
		(end 165.663118 -257.815334)
		(width 0.16002)
		(layer "In13.Cu")
		(net "M_H_CPU1_CLK_DN<0>")
	)
	(segment
		(start 164.466016 -256.763266)
		(end 164.626036 -256.923286)
		(width 0.16002)
		(layer "In13.Cu")
		(net "M_H_CPU1_CLK_DN<0>")
	)
	(segment
		(start 155.184348 -256.128266)
		(end 155.819348 -256.763266)
		(width 0.16002)
		(layer "In13.Cu")
		(net "M_H_CPU1_CLK_DN<0>")
	)
	(segment
		(start 166.160196 -256.763266)
		(end 166.609776 -256.763266)
		(width 0.16002)
		(layer "In13.Cu")
		(net "M_H_CPU1_CLK_DN<0>")
	)
	(segment
		(start 147.775168 -257.615436)
		(end 147.79879 -257.615436)
		(width 0.09525)
		(layer "In13.Cu")
		(net "M_H_CPU1_CLK_DN<0>")
	)
	(segment
		(start 166.000176 -256.923286)
		(end 166.160196 -256.763266)
		(width 0.16002)
		(layer "In13.Cu")
		(net "M_H_CPU1_CLK_DN<0>")
	)
	(segment
		(start 168.303956 -256.763266)
		(end 168.647364 -256.763266)
		(width 0.16002)
		(layer "In13.Cu")
		(net "M_H_CPU1_CLK_DN<0>")
	)
	(segment
		(start 135.744712 -256.634488)
		(end 135.898636 -256.369058)
		(width 0.09525)
		(layer "In13.Cu")
		(net "M_H_CPU1_CLK_DN<0>")
	)
	(segment
		(start 168.143936 -257.478276)
		(end 168.143936 -256.923286)
		(width 0.16002)
		(layer "In13.Cu")
		(net "M_H_CPU1_CLK_DN<0>")
	)
	(segment
		(start 147.71624 -257.556508)
		(end 147.775168 -257.615436)
		(width 0.09525)
		(layer "In13.Cu")
		(net "M_H_CPU1_CLK_DN<0>")
	)
	(segment
		(start 166.000176 -257.478276)
		(end 166.000176 -256.923286)
		(width 0.16002)
		(layer "In13.Cu")
		(net "M_H_CPU1_CLK_DN<0>")
	)
	(segment
		(start 137.804906 -256.304542)
		(end 137.813288 -256.309368)
		(width 0.09525)
		(layer "In13.Cu")
		(net "M_H_CPU1_CLK_DN<0>")
	)
	(segment
		(start 140.25626 -256.309368)
		(end 140.264642 -256.304542)
		(width 0.09525)
		(layer "In13.Cu")
		(net "M_H_CPU1_CLK_DN<0>")
	)
	(segment
		(start 144.016222 -256.309368)
		(end 144.02816 -256.30251)
		(width 0.09525)
		(layer "In13.Cu")
		(net "M_H_CPU1_CLK_DN<0>")
	)
	(segment
		(start 147.79879 -257.615436)
		(end 151.019002 -257.615436)
		(width 0.16002)
		(layer "In13.Cu")
		(net "M_H_CPU1_CLK_DN<0>")
	)
	(segment
		(start 167.806878 -257.815334)
		(end 168.143936 -257.478276)
		(width 0.16002)
		(layer "In13.Cu")
		(net "M_H_CPU1_CLK_DN<0>")
	)
	(arc
		(start 136.020048 -256.350516)
		(mid 136.26279 -256.383286)
		(end 136.496298 -256.309368)
		(width 0.09525)
		(layer "In13.Cu")
		(net "M_H_CPU1_CLK_DN<0>")
	)
	(arc
		(start 142.136114 -256.309368)
		(mid 142.319889 -256.258596)
		(end 142.504922 -256.304542)
		(width 0.09525)
		(layer "In13.Cu")
		(net "M_H_CPU1_CLK_DN<0>")
	)
	(arc
		(start 139.693396 -256.309368)
		(mid 139.974828 -256.385123)
		(end 140.25626 -256.309368)
		(width 0.09525)
		(layer "In13.Cu")
		(net "M_H_CPU1_CLK_DN<0>")
	)
	(arc
		(start 139.324588 -256.304542)
		(mid 139.50962 -256.258628)
		(end 139.693396 -256.309368)
		(width 0.09525)
		(layer "In13.Cu")
		(net "M_H_CPU1_CLK_DN<0>")
	)
	(arc
		(start 136.496298 -256.309368)
		(mid 136.684766 -256.258691)
		(end 136.873234 -256.309368)
		(width 0.09525)
		(layer "In13.Cu")
		(net "M_H_CPU1_CLK_DN<0>")
	)
	(arc
		(start 144.971008 -256.300986)
		(mid 145.15344 -256.258546)
		(end 145.33372 -256.309368)
		(width 0.09525)
		(layer "In13.Cu")
		(net "M_H_CPU1_CLK_DN<0>")
	)
	(arc
		(start 136.873234 -256.309368)
		(mid 137.154666 -256.385123)
		(end 137.436098 -256.309368)
		(width 0.09525)
		(layer "In13.Cu")
		(net "M_H_CPU1_CLK_DN<0>")
	)
	(arc
		(start 143.08455 -256.304542)
		(mid 143.269582 -256.258628)
		(end 143.453358 -256.309368)
		(width 0.09525)
		(layer "In13.Cu")
		(net "M_H_CPU1_CLK_DN<0>")
	)
	(arc
		(start 140.63345 -256.309368)
		(mid 140.914882 -256.385123)
		(end 141.196314 -256.309368)
		(width 0.09525)
		(layer "In13.Cu")
		(net "M_H_CPU1_CLK_DN<0>")
	)
	(arc
		(start 138.753342 -256.309368)
		(mid 139.034774 -256.385123)
		(end 139.316206 -256.309368)
		(width 0.09525)
		(layer "In13.Cu")
		(net "M_H_CPU1_CLK_DN<0>")
	)
	(arc
		(start 138.376152 -256.309368)
		(mid 138.559927 -256.258596)
		(end 138.74496 -256.304542)
		(width 0.09525)
		(layer "In13.Cu")
		(net "M_H_CPU1_CLK_DN<0>")
	)
	(arc
		(start 143.453358 -256.309368)
		(mid 143.73479 -256.385123)
		(end 144.016222 -256.309368)
		(width 0.09525)
		(layer "In13.Cu")
		(net "M_H_CPU1_CLK_DN<0>")
	)
	(arc
		(start 135.999474 -256.342388)
		(mid 136.009722 -256.346551)
		(end 136.020048 -256.350516)
		(width 0.09525)
		(layer "In13.Cu")
		(net "M_H_CPU1_CLK_DN<0>")
	)
	(arc
		(start 140.264642 -256.304542)
		(mid 140.449674 -256.258628)
		(end 140.63345 -256.309368)
		(width 0.09525)
		(layer "In13.Cu")
		(net "M_H_CPU1_CLK_DN<0>")
	)
	(arc
		(start 137.813288 -256.309368)
		(mid 138.09472 -256.385123)
		(end 138.376152 -256.309368)
		(width 0.09525)
		(layer "In13.Cu")
		(net "M_H_CPU1_CLK_DN<0>")
	)
	(arc
		(start 145.33372 -256.309368)
		(mid 145.374244 -256.336323)
		(end 145.410936 -256.368296)
		(width 0.09525)
		(layer "In13.Cu")
		(net "M_H_CPU1_CLK_DN<0>")
	)
	(arc
		(start 141.196314 -256.309368)
		(mid 141.384782 -256.258691)
		(end 141.57325 -256.309368)
		(width 0.09525)
		(layer "In13.Cu")
		(net "M_H_CPU1_CLK_DN<0>")
	)
	(arc
		(start 141.57325 -256.309368)
		(mid 141.854682 -256.385123)
		(end 142.136114 -256.309368)
		(width 0.09525)
		(layer "In13.Cu")
		(net "M_H_CPU1_CLK_DN<0>")
	)
	(arc
		(start 144.02816 -256.30251)
		(mid 144.211795 -256.25856)
		(end 144.393666 -256.309368)
		(width 0.09525)
		(layer "In13.Cu")
		(net "M_H_CPU1_CLK_DN<0>")
	)
	(arc
		(start 142.513304 -256.309368)
		(mid 142.794736 -256.385123)
		(end 143.076168 -256.309368)
		(width 0.09525)
		(layer "In13.Cu")
		(net "M_H_CPU1_CLK_DN<0>")
	)
	(arc
		(start 144.393666 -256.309368)
		(mid 144.663099 -256.385239)
		(end 144.935702 -256.32156)
		(width 0.09525)
		(layer "In13.Cu")
		(net "M_H_CPU1_CLK_DN<0>")
	)
	(arc
		(start 137.436098 -256.309368)
		(mid 137.619873 -256.258596)
		(end 137.804906 -256.304542)
		(width 0.09525)
		(layer "In13.Cu")
		(net "M_H_CPU1_CLK_DN<0>")
	)
	(segment
		(start 134.337806 -250.420378)
		(end 134.804658 -250.15444)
		(width 0.10668)
		(layer "F.Cu")
		(net "M_H_CPU1_ALERT_R_N")
	)
	(segment
		(start 137.803382 -250.481846)
		(end 137.811764 -250.47702)
		(width 0.0889)
		(layer "In13.Cu")
		(net "M_H_CPU1_ALERT_R_N")
	)
	(segment
		(start 142.503398 -250.481846)
		(end 142.51178 -250.47702)
		(width 0.0889)
		(layer "In13.Cu")
		(net "M_H_CPU1_ALERT_R_N")
	)
	(segment
		(start 138.743436 -250.481846)
		(end 138.751818 -250.47702)
		(width 0.0889)
		(layer "In13.Cu")
		(net "M_H_CPU1_ALERT_R_N")
	)
	(segment
		(start 160.357312 -249.957336)
		(end 164.10432 -246.210328)
		(width 0.11684)
		(layer "In13.Cu")
		(net "M_H_CPU1_ALERT_R_N")
	)
	(segment
		(start 149.576536 -249.957336)
		(end 160.357312 -249.957336)
		(width 0.11684)
		(layer "In13.Cu")
		(net "M_H_CPU1_ALERT_R_N")
	)
	(segment
		(start 143.077692 -250.47702)
		(end 143.086074 -250.481846)
		(width 0.0889)
		(layer "In13.Cu")
		(net "M_H_CPU1_ALERT_R_N")
	)
	(segment
		(start 143.451834 -250.47702)
		(end 143.466566 -250.468384)
		(width 0.0889)
		(layer "In13.Cu")
		(net "M_H_CPU1_ALERT_R_N")
	)
	(segment
		(start 140.257784 -250.47702)
		(end 140.266166 -250.481846)
		(width 0.0889)
		(layer "In13.Cu")
		(net "M_H_CPU1_ALERT_R_N")
	)
	(segment
		(start 166.637716 -245.557548)
		(end 169.037 -245.557548)
		(width 0.11684)
		(layer "In13.Cu")
		(net "M_H_CPU1_ALERT_R_N")
	)
	(segment
		(start 139.31773 -250.47702)
		(end 139.326112 -250.481846)
		(width 0.0889)
		(layer "In13.Cu")
		(net "M_H_CPU1_ALERT_R_N")
	)
	(segment
		(start 144.952466 -250.473464)
		(end 144.958054 -250.476766)
		(width 0.0889)
		(layer "In13.Cu")
		(net "M_H_CPU1_ALERT_R_N")
	)
	(segment
		(start 165.984936 -246.210328)
		(end 166.637716 -245.557548)
		(width 0.11684)
		(layer "In13.Cu")
		(net "M_H_CPU1_ALERT_R_N")
	)
	(segment
		(start 144.958054 -250.476766)
		(end 144.976342 -250.48718)
		(width 0.0889)
		(layer "In13.Cu")
		(net "M_H_CPU1_ALERT_R_N")
	)
	(segment
		(start 134.650734 -250.41987)
		(end 134.673086 -250.503182)
		(width 0.0889)
		(layer "In13.Cu")
		(net "M_H_CPU1_ALERT_R_N")
	)
	(segment
		(start 144.380966 -250.483878)
		(end 144.39265 -250.47702)
		(width 0.0889)
		(layer "In13.Cu")
		(net "M_H_CPU1_ALERT_R_N")
	)
	(segment
		(start 147.47875 -250.210066)
		(end 149.323806 -250.210066)
		(width 0.11684)
		(layer "In13.Cu")
		(net "M_H_CPU1_ALERT_R_N")
	)
	(segment
		(start 173.721776 -244.085364)
		(end 174.675038 -244.085364)
		(width 0.11684)
		(layer "In13.Cu")
		(net "M_H_CPU1_ALERT_R_N")
	)
	(segment
		(start 169.037 -245.557548)
		(end 170.084242 -244.510306)
		(width 0.11684)
		(layer "In13.Cu")
		(net "M_H_CPU1_ALERT_R_N")
	)
	(segment
		(start 134.804658 -250.15444)
		(end 134.650734 -250.41987)
		(width 0.0889)
		(layer "In13.Cu")
		(net "M_H_CPU1_ALERT_R_N")
	)
	(segment
		(start 170.084242 -244.510306)
		(end 173.296834 -244.510306)
		(width 0.11684)
		(layer "In13.Cu")
		(net "M_H_CPU1_ALERT_R_N")
	)
	(segment
		(start 147.15744 -250.376944)
		(end 147.324318 -250.210066)
		(width 0.0889)
		(layer "In13.Cu")
		(net "M_H_CPU1_ALERT_R_N")
	)
	(segment
		(start 135.557768 -250.47702)
		(end 135.56615 -250.481846)
		(width 0.0889)
		(layer "In13.Cu")
		(net "M_H_CPU1_ALERT_R_N")
	)
	(segment
		(start 149.323806 -250.210066)
		(end 149.576536 -249.957336)
		(width 0.11684)
		(layer "In13.Cu")
		(net "M_H_CPU1_ALERT_R_N")
	)
	(segment
		(start 147.324318 -250.210066)
		(end 147.47875 -250.210066)
		(width 0.0889)
		(layer "In13.Cu")
		(net "M_H_CPU1_ALERT_R_N")
	)
	(segment
		(start 164.10432 -246.210328)
		(end 165.984936 -246.210328)
		(width 0.11684)
		(layer "In13.Cu")
		(net "M_H_CPU1_ALERT_R_N")
	)
	(segment
		(start 145.678906 -250.376944)
		(end 147.15744 -250.376944)
		(width 0.0889)
		(layer "In13.Cu")
		(net "M_H_CPU1_ALERT_R_N")
	)
	(segment
		(start 173.296834 -244.510306)
		(end 173.721776 -244.085364)
		(width 0.11684)
		(layer "In13.Cu")
		(net "M_H_CPU1_ALERT_R_N")
	)
	(arc
		(start 143.086074 -250.481846)
		(mid 143.269582 -250.52734)
		(end 143.451834 -250.47702)
		(width 0.0889)
		(layer "In13.Cu")
		(net "M_H_CPU1_ALERT_R_N")
	)
	(arc
		(start 138.377676 -250.47702)
		(mid 138.559927 -250.52737)
		(end 138.743436 -250.481846)
		(width 0.0889)
		(layer "In13.Cu")
		(net "M_H_CPU1_ALERT_R_N")
	)
	(arc
		(start 144.976342 -250.48718)
		(mid 145.155571 -250.527333)
		(end 145.332196 -250.47702)
		(width 0.0889)
		(layer "In13.Cu")
		(net "M_H_CPU1_ALERT_R_N")
	)
	(arc
		(start 136.87171 -250.47702)
		(mid 137.154666 -250.400843)
		(end 137.437622 -250.47702)
		(width 0.0889)
		(layer "In13.Cu")
		(net "M_H_CPU1_ALERT_R_N")
	)
	(arc
		(start 143.466566 -250.468384)
		(mid 143.743549 -250.40058)
		(end 144.018254 -250.47702)
		(width 0.0889)
		(layer "In13.Cu")
		(net "M_H_CPU1_ALERT_R_N")
	)
	(arc
		(start 144.39265 -250.47702)
		(mid 144.672078 -250.400854)
		(end 144.952466 -250.473464)
		(width 0.0889)
		(layer "In13.Cu")
		(net "M_H_CPU1_ALERT_R_N")
	)
	(arc
		(start 142.137638 -250.47702)
		(mid 142.319889 -250.52737)
		(end 142.503398 -250.481846)
		(width 0.0889)
		(layer "In13.Cu")
		(net "M_H_CPU1_ALERT_R_N")
	)
	(arc
		(start 138.751818 -250.47702)
		(mid 139.034774 -250.400843)
		(end 139.31773 -250.47702)
		(width 0.0889)
		(layer "In13.Cu")
		(net "M_H_CPU1_ALERT_R_N")
	)
	(arc
		(start 137.437622 -250.47702)
		(mid 137.619873 -250.52737)
		(end 137.803382 -250.481846)
		(width 0.0889)
		(layer "In13.Cu")
		(net "M_H_CPU1_ALERT_R_N")
	)
	(arc
		(start 137.811764 -250.47702)
		(mid 138.09472 -250.400843)
		(end 138.377676 -250.47702)
		(width 0.0889)
		(layer "In13.Cu")
		(net "M_H_CPU1_ALERT_R_N")
	)
	(arc
		(start 145.332196 -250.47702)
		(mid 145.499396 -250.405661)
		(end 145.678906 -250.376944)
		(width 0.0889)
		(layer "In13.Cu")
		(net "M_H_CPU1_ALERT_R_N")
	)
	(arc
		(start 140.266166 -250.481846)
		(mid 140.449674 -250.52734)
		(end 140.631926 -250.47702)
		(width 0.0889)
		(layer "In13.Cu")
		(net "M_H_CPU1_ALERT_R_N")
	)
	(arc
		(start 135.56615 -250.481846)
		(mid 135.749658 -250.52734)
		(end 135.93191 -250.47702)
		(width 0.0889)
		(layer "In13.Cu")
		(net "M_H_CPU1_ALERT_R_N")
	)
	(arc
		(start 139.326112 -250.481846)
		(mid 139.50962 -250.52734)
		(end 139.691872 -250.47702)
		(width 0.0889)
		(layer "In13.Cu")
		(net "M_H_CPU1_ALERT_R_N")
	)
	(arc
		(start 142.51178 -250.47702)
		(mid 142.794736 -250.400843)
		(end 143.077692 -250.47702)
		(width 0.0889)
		(layer "In13.Cu")
		(net "M_H_CPU1_ALERT_R_N")
	)
	(arc
		(start 136.497822 -250.47702)
		(mid 136.684766 -250.527275)
		(end 136.87171 -250.47702)
		(width 0.0889)
		(layer "In13.Cu")
		(net "M_H_CPU1_ALERT_R_N")
	)
	(arc
		(start 144.018254 -250.47702)
		(mid 144.198712 -250.527464)
		(end 144.380966 -250.483878)
		(width 0.0889)
		(layer "In13.Cu")
		(net "M_H_CPU1_ALERT_R_N")
	)
	(arc
		(start 139.691872 -250.47702)
		(mid 139.974828 -250.400843)
		(end 140.257784 -250.47702)
		(width 0.0889)
		(layer "In13.Cu")
		(net "M_H_CPU1_ALERT_R_N")
	)
	(arc
		(start 134.673086 -250.503182)
		(mid 134.835418 -250.526)
		(end 134.991856 -250.47702)
		(width 0.0889)
		(layer "In13.Cu")
		(net "M_H_CPU1_ALERT_R_N")
	)
	(arc
		(start 141.197838 -250.47702)
		(mid 141.384782 -250.527275)
		(end 141.571726 -250.47702)
		(width 0.0889)
		(layer "In13.Cu")
		(net "M_H_CPU1_ALERT_R_N")
	)
	(arc
		(start 141.571726 -250.47702)
		(mid 141.854682 -250.400843)
		(end 142.137638 -250.47702)
		(width 0.0889)
		(layer "In13.Cu")
		(net "M_H_CPU1_ALERT_R_N")
	)
	(arc
		(start 140.631926 -250.47702)
		(mid 140.914882 -250.400843)
		(end 141.197838 -250.47702)
		(width 0.0889)
		(layer "In13.Cu")
		(net "M_H_CPU1_ALERT_R_N")
	)
	(arc
		(start 135.93191 -250.47702)
		(mid 136.214866 -250.400843)
		(end 136.497822 -250.47702)
		(width 0.0889)
		(layer "In13.Cu")
		(net "M_H_CPU1_ALERT_R_N")
	)
	(arc
		(start 134.991856 -250.47702)
		(mid 135.274812 -250.400843)
		(end 135.557768 -250.47702)
		(width 0.0889)
		(layer "In13.Cu")
		(net "M_H_CPU1_ALERT_R_N")
	)
	(via
		(at 176.072038 -244.085364)
		(size 0.4826)
		(drill 0.254)
		(layers "F.Cu" "B.Cu")
		(net "M_H_CPU1_ALERT_N")
	)
	(segment
		(start 175.475138 -244.085364)
		(end 176.072038 -244.085364)
		(width 0.10668)
		(layer "B.Cu")
		(net "M_H_CPU1_ALERT_N")
	)
	(segment
		(start 383.517902 -267.34008)
		(end 383.984754 -267.606018)
		(width 0.10668)
		(layer "F.Cu")
		(net "M_H_CPU0_SB_RSP<0>")
	)
	(segment
		(start 424.012106 -270.43507)
		(end 421.660574 -270.43507)
		(width 0.11684)
		(layer "In13.Cu")
		(net "M_H_CPU0_SB_RSP<0>")
	)
	(segment
		(start 415.20999 -270.010128)
		(end 413.157416 -270.860266)
		(width 0.11684)
		(layer "In13.Cu")
		(net "M_H_CPU0_SB_RSP<0>")
	)
	(segment
		(start 386.059426 -267.916914)
		(end 386.048758 -267.92301)
		(width 0.0889)
		(layer "In13.Cu")
		(net "M_H_CPU0_SB_RSP<0>")
	)
	(segment
		(start 395.169898 -266.89431)
		(end 394.604748 -266.89431)
		(width 0.0889)
		(layer "In13.Cu")
		(net "M_H_CPU0_SB_RSP<0>")
	)
	(segment
		(start 412.478982 -270.860266)
		(end 408.189176 -266.57046)
		(width 0.11684)
		(layer "In13.Cu")
		(net "M_H_CPU0_SB_RSP<0>")
	)
	(segment
		(start 383.859278 -267.950188)
		(end 383.83591 -267.862304)
		(width 0.0889)
		(layer "In13.Cu")
		(net "M_H_CPU0_SB_RSP<0>")
	)
	(segment
		(start 395.493748 -266.57046)
		(end 395.169898 -266.89431)
		(width 0.0889)
		(layer "In13.Cu")
		(net "M_H_CPU0_SB_RSP<0>")
	)
	(segment
		(start 392.652758 -267.914882)
		(end 392.62939 -267.928598)
		(width 0.0889)
		(layer "In13.Cu")
		(net "M_H_CPU0_SB_RSP<0>")
	)
	(segment
		(start 391.326116 -267.933424)
		(end 391.317734 -267.928598)
		(width 0.0889)
		(layer "In13.Cu")
		(net "M_H_CPU0_SB_RSP<0>")
	)
	(segment
		(start 408.189176 -266.57046)
		(end 395.713458 -266.57046)
		(width 0.11684)
		(layer "In13.Cu")
		(net "M_H_CPU0_SB_RSP<0>")
	)
	(segment
		(start 420.63416 -270.860266)
		(end 419.63721 -270.860266)
		(width 0.11684)
		(layer "In13.Cu")
		(net "M_H_CPU0_SB_RSP<0>")
	)
	(segment
		(start 413.157416 -270.860266)
		(end 412.478982 -270.860266)
		(width 0.11684)
		(layer "In13.Cu")
		(net "M_H_CPU0_SB_RSP<0>")
	)
	(segment
		(start 393.570714 -267.928344)
		(end 393.543282 -267.944092)
		(width 0.0889)
		(layer "In13.Cu")
		(net "M_H_CPU0_SB_RSP<0>")
	)
	(segment
		(start 395.713458 -266.57046)
		(end 395.493748 -266.57046)
		(width 0.0889)
		(layer "In13.Cu")
		(net "M_H_CPU0_SB_RSP<0>")
	)
	(segment
		(start 419.63721 -270.860266)
		(end 417.584636 -270.010128)
		(width 0.11684)
		(layer "In13.Cu")
		(net "M_H_CPU0_SB_RSP<0>")
	)
	(segment
		(start 392.274552 -267.938758)
		(end 392.256264 -267.928344)
		(width 0.0889)
		(layer "In13.Cu")
		(net "M_H_CPU0_SB_RSP<0>")
	)
	(segment
		(start 421.660574 -270.43507)
		(end 420.63416 -270.860266)
		(width 0.11684)
		(layer "In13.Cu")
		(net "M_H_CPU0_SB_RSP<0>")
	)
	(segment
		(start 417.584636 -270.010128)
		(end 415.20999 -270.010128)
		(width 0.11684)
		(layer "In13.Cu")
		(net "M_H_CPU0_SB_RSP<0>")
	)
	(segment
		(start 383.83591 -267.862304)
		(end 383.984754 -267.606018)
		(width 0.0889)
		(layer "In13.Cu")
		(net "M_H_CPU0_SB_RSP<0>")
	)
	(segment
		(start 385.119372 -267.916914)
		(end 385.108704 -267.92301)
		(width 0.0889)
		(layer "In13.Cu")
		(net "M_H_CPU0_SB_RSP<0>")
	)
	(segment
		(start 390.751822 -267.928598)
		(end 390.74344 -267.933424)
		(width 0.0889)
		(layer "In13.Cu")
		(net "M_H_CPU0_SB_RSP<0>")
	)
	(segment
		(start 388.506208 -267.933424)
		(end 388.497826 -267.928598)
		(width 0.0889)
		(layer "In13.Cu")
		(net "M_H_CPU0_SB_RSP<0>")
	)
	(segment
		(start 387.557772 -267.928598)
		(end 387.54812 -267.92301)
		(width 0.0889)
		(layer "In13.Cu")
		(net "M_H_CPU0_SB_RSP<0>")
	)
	(segment
		(start 394.604748 -266.89431)
		(end 393.570714 -267.928344)
		(width 0.0889)
		(layer "In13.Cu")
		(net "M_H_CPU0_SB_RSP<0>")
	)
	(segment
		(start 392.256264 -267.928344)
		(end 392.234674 -267.915898)
		(width 0.0889)
		(layer "In13.Cu")
		(net "M_H_CPU0_SB_RSP<0>")
	)
	(segment
		(start 384.179318 -267.916914)
		(end 384.16865 -267.92301)
		(width 0.0889)
		(layer "In13.Cu")
		(net "M_H_CPU0_SB_RSP<0>")
	)
	(segment
		(start 387.566154 -267.933424)
		(end 387.557772 -267.928598)
		(width 0.0889)
		(layer "In13.Cu")
		(net "M_H_CPU0_SB_RSP<0>")
	)
	(arc
		(start 393.543282 -267.944092)
		(mid 393.368031 -267.979025)
		(end 393.196572 -267.928598)
		(width 0.0889)
		(layer "In13.Cu")
		(net "M_H_CPU0_SB_RSP<0>")
	)
	(arc
		(start 386.62102 -267.92301)
		(mid 386.341016 -267.845965)
		(end 386.059426 -267.916914)
		(width 0.0889)
		(layer "In13.Cu")
		(net "M_H_CPU0_SB_RSP<0>")
	)
	(arc
		(start 391.691876 -267.928598)
		(mid 391.509625 -267.978948)
		(end 391.326116 -267.933424)
		(width 0.0889)
		(layer "In13.Cu")
		(net "M_H_CPU0_SB_RSP<0>")
	)
	(arc
		(start 384.16865 -267.92301)
		(mid 384.016991 -267.970964)
		(end 383.859278 -267.950188)
		(width 0.0889)
		(layer "In13.Cu")
		(net "M_H_CPU0_SB_RSP<0>")
	)
	(arc
		(start 388.871968 -267.928598)
		(mid 388.689717 -267.978948)
		(end 388.506208 -267.933424)
		(width 0.0889)
		(layer "In13.Cu")
		(net "M_H_CPU0_SB_RSP<0>")
	)
	(arc
		(start 388.497826 -267.928598)
		(mid 388.21487 -267.852421)
		(end 387.931914 -267.928598)
		(width 0.0889)
		(layer "In13.Cu")
		(net "M_H_CPU0_SB_RSP<0>")
	)
	(arc
		(start 386.048758 -267.92301)
		(mid 385.864862 -267.97249)
		(end 385.680966 -267.92301)
		(width 0.0889)
		(layer "In13.Cu")
		(net "M_H_CPU0_SB_RSP<0>")
	)
	(arc
		(start 385.108704 -267.92301)
		(mid 384.924808 -267.97249)
		(end 384.740912 -267.92301)
		(width 0.0889)
		(layer "In13.Cu")
		(net "M_H_CPU0_SB_RSP<0>")
	)
	(arc
		(start 386.988812 -267.92301)
		(mid 386.804916 -267.97249)
		(end 386.62102 -267.92301)
		(width 0.0889)
		(layer "In13.Cu")
		(net "M_H_CPU0_SB_RSP<0>")
	)
	(arc
		(start 387.54812 -267.92301)
		(mid 387.268466 -267.84777)
		(end 386.988812 -267.92301)
		(width 0.0889)
		(layer "In13.Cu")
		(net "M_H_CPU0_SB_RSP<0>")
	)
	(arc
		(start 393.196572 -267.928598)
		(mid 392.926415 -267.851836)
		(end 392.652758 -267.914882)
		(width 0.0889)
		(layer "In13.Cu")
		(net "M_H_CPU0_SB_RSP<0>")
	)
	(arc
		(start 392.234674 -267.915898)
		(mid 391.961645 -267.852579)
		(end 391.691876 -267.928598)
		(width 0.0889)
		(layer "In13.Cu")
		(net "M_H_CPU0_SB_RSP<0>")
	)
	(arc
		(start 384.740912 -267.92301)
		(mid 384.460908 -267.845965)
		(end 384.179318 -267.916914)
		(width 0.0889)
		(layer "In13.Cu")
		(net "M_H_CPU0_SB_RSP<0>")
	)
	(arc
		(start 389.811768 -267.928598)
		(mid 389.624824 -267.978853)
		(end 389.43788 -267.928598)
		(width 0.0889)
		(layer "In13.Cu")
		(net "M_H_CPU0_SB_RSP<0>")
	)
	(arc
		(start 391.317734 -267.928598)
		(mid 391.034778 -267.852421)
		(end 390.751822 -267.928598)
		(width 0.0889)
		(layer "In13.Cu")
		(net "M_H_CPU0_SB_RSP<0>")
	)
	(arc
		(start 390.74344 -267.933424)
		(mid 390.559932 -267.978918)
		(end 390.37768 -267.928598)
		(width 0.0889)
		(layer "In13.Cu")
		(net "M_H_CPU0_SB_RSP<0>")
	)
	(arc
		(start 385.680966 -267.92301)
		(mid 385.400962 -267.845965)
		(end 385.119372 -267.916914)
		(width 0.0889)
		(layer "In13.Cu")
		(net "M_H_CPU0_SB_RSP<0>")
	)
	(arc
		(start 392.62939 -267.928598)
		(mid 392.45327 -267.978576)
		(end 392.274552 -267.938758)
		(width 0.0889)
		(layer "In13.Cu")
		(net "M_H_CPU0_SB_RSP<0>")
	)
	(arc
		(start 387.931914 -267.928598)
		(mid 387.749663 -267.978948)
		(end 387.566154 -267.933424)
		(width 0.0889)
		(layer "In13.Cu")
		(net "M_H_CPU0_SB_RSP<0>")
	)
	(arc
		(start 389.43788 -267.928598)
		(mid 389.154924 -267.852421)
		(end 388.871968 -267.928598)
		(width 0.0889)
		(layer "In13.Cu")
		(net "M_H_CPU0_SB_RSP<0>")
	)
	(arc
		(start 390.37768 -267.928598)
		(mid 390.094724 -267.852421)
		(end 389.811768 -267.928598)
		(width 0.0889)
		(layer "In13.Cu")
		(net "M_H_CPU0_SB_RSP<0>")
	)
	(segment
		(start 382.107948 -264.910062)
		(end 382.5748 -265.176)
		(width 0.10668)
		(layer "F.Cu")
		(net "M_H_CPU0_SB_PAR")
	)
	(segment
		(start 392.72845 -265.49858)
		(end 392.718036 -265.492484)
		(width 0.0889)
		(layer "In13.Cu")
		(net "M_H_CPU0_SB_PAR")
	)
	(segment
		(start 385.216146 -265.503406)
		(end 385.207764 -265.49858)
		(width 0.0889)
		(layer "In13.Cu")
		(net "M_H_CPU0_SB_PAR")
	)
	(segment
		(start 394.049504 -264.544302)
		(end 393.086082 -265.507724)
		(width 0.0889)
		(layer "In13.Cu")
		(net "M_H_CPU0_SB_PAR")
	)
	(segment
		(start 418.122608 -266.610084)
		(end 414.940242 -266.610084)
		(width 0.14478)
		(layer "In13.Cu")
		(net "M_H_CPU0_SB_PAR")
	)
	(segment
		(start 384.641852 -265.49858)
		(end 384.63347 -265.503406)
		(width 0.0889)
		(layer "In13.Cu")
		(net "M_H_CPU0_SB_PAR")
	)
	(segment
		(start 414.940242 -266.610084)
		(end 414.090104 -267.460222)
		(width 0.14478)
		(layer "In13.Cu")
		(net "M_H_CPU0_SB_PAR")
	)
	(segment
		(start 386.1562 -265.503406)
		(end 386.147818 -265.49858)
		(width 0.0889)
		(layer "In13.Cu")
		(net "M_H_CPU0_SB_PAR")
	)
	(segment
		(start 395.953742 -264.79373)
		(end 395.47292 -264.79373)
		(width 0.0889)
		(layer "In13.Cu")
		(net "M_H_CPU0_SB_PAR")
	)
	(segment
		(start 395.47292 -264.79373)
		(end 395.223492 -264.544302)
		(width 0.0889)
		(layer "In13.Cu")
		(net "M_H_CPU0_SB_PAR")
	)
	(segment
		(start 391.796016 -265.503406)
		(end 391.787634 -265.49858)
		(width 0.0889)
		(layer "In13.Cu")
		(net "M_H_CPU0_SB_PAR")
	)
	(segment
		(start 389.341868 -265.49858)
		(end 389.333486 -265.503406)
		(width 0.0889)
		(layer "In13.Cu")
		(net "M_H_CPU0_SB_PAR")
	)
	(segment
		(start 382.824736 -265.46683)
		(end 382.728724 -265.44143)
		(width 0.0889)
		(layer "In13.Cu")
		(net "M_H_CPU0_SB_PAR")
	)
	(segment
		(start 418.972746 -267.460222)
		(end 418.122608 -266.610084)
		(width 0.14478)
		(layer "In13.Cu")
		(net "M_H_CPU0_SB_PAR")
	)
	(segment
		(start 412.419292 -267.460222)
		(end 409.7528 -264.79373)
		(width 0.14478)
		(layer "In13.Cu")
		(net "M_H_CPU0_SB_PAR")
	)
	(segment
		(start 419.912038 -267.035026)
		(end 419.486842 -267.460222)
		(width 0.14478)
		(layer "In13.Cu")
		(net "M_H_CPU0_SB_PAR")
	)
	(segment
		(start 383.701798 -265.49858)
		(end 383.693416 -265.503406)
		(width 0.0889)
		(layer "In13.Cu")
		(net "M_H_CPU0_SB_PAR")
	)
	(segment
		(start 419.486842 -267.460222)
		(end 418.972746 -267.460222)
		(width 0.14478)
		(layer "In13.Cu")
		(net "M_H_CPU0_SB_PAR")
	)
	(segment
		(start 409.7528 -264.79373)
		(end 395.953742 -264.79373)
		(width 0.14478)
		(layer "In13.Cu")
		(net "M_H_CPU0_SB_PAR")
	)
	(segment
		(start 395.223492 -264.544302)
		(end 394.049504 -264.544302)
		(width 0.0889)
		(layer "In13.Cu")
		(net "M_H_CPU0_SB_PAR")
	)
	(segment
		(start 382.728724 -265.44143)
		(end 382.5748 -265.176)
		(width 0.0889)
		(layer "In13.Cu")
		(net "M_H_CPU0_SB_PAR")
	)
	(segment
		(start 389.916162 -265.503406)
		(end 389.90778 -265.49858)
		(width 0.0889)
		(layer "In13.Cu")
		(net "M_H_CPU0_SB_PAR")
	)
	(segment
		(start 388.401814 -265.49858)
		(end 388.393432 -265.503406)
		(width 0.0889)
		(layer "In13.Cu")
		(net "M_H_CPU0_SB_PAR")
	)
	(segment
		(start 414.090104 -267.460222)
		(end 412.419292 -267.460222)
		(width 0.14478)
		(layer "In13.Cu")
		(net "M_H_CPU0_SB_PAR")
	)
	(arc
		(start 392.718036 -265.492484)
		(mid 392.43935 -265.422264)
		(end 392.162284 -265.49858)
		(width 0.0889)
		(layer "In13.Cu")
		(net "M_H_CPU0_SB_PAR")
	)
	(arc
		(start 387.46176 -265.49858)
		(mid 387.274816 -265.548835)
		(end 387.087872 -265.49858)
		(width 0.0889)
		(layer "In13.Cu")
		(net "M_H_CPU0_SB_PAR")
	)
	(arc
		(start 390.281922 -265.49858)
		(mid 390.099671 -265.54893)
		(end 389.916162 -265.503406)
		(width 0.0889)
		(layer "In13.Cu")
		(net "M_H_CPU0_SB_PAR")
	)
	(arc
		(start 390.847834 -265.49858)
		(mid 390.564878 -265.422403)
		(end 390.281922 -265.49858)
		(width 0.0889)
		(layer "In13.Cu")
		(net "M_H_CPU0_SB_PAR")
	)
	(arc
		(start 384.63347 -265.503406)
		(mid 384.449962 -265.5489)
		(end 384.26771 -265.49858)
		(width 0.0889)
		(layer "In13.Cu")
		(net "M_H_CPU0_SB_PAR")
	)
	(arc
		(start 391.787634 -265.49858)
		(mid 391.504678 -265.422403)
		(end 391.221722 -265.49858)
		(width 0.0889)
		(layer "In13.Cu")
		(net "M_H_CPU0_SB_PAR")
	)
	(arc
		(start 392.162284 -265.49858)
		(mid 391.979779 -265.549057)
		(end 391.796016 -265.503406)
		(width 0.0889)
		(layer "In13.Cu")
		(net "M_H_CPU0_SB_PAR")
	)
	(arc
		(start 383.327656 -265.49858)
		(mid 383.079943 -265.42336)
		(end 382.824736 -265.46683)
		(width 0.0889)
		(layer "In13.Cu")
		(net "M_H_CPU0_SB_PAR")
	)
	(arc
		(start 389.90778 -265.49858)
		(mid 389.624824 -265.422403)
		(end 389.341868 -265.49858)
		(width 0.0889)
		(layer "In13.Cu")
		(net "M_H_CPU0_SB_PAR")
	)
	(arc
		(start 393.086082 -265.507724)
		(mid 392.9061 -265.548824)
		(end 392.72845 -265.49858)
		(width 0.0889)
		(layer "In13.Cu")
		(net "M_H_CPU0_SB_PAR")
	)
	(arc
		(start 385.207764 -265.49858)
		(mid 384.924808 -265.422403)
		(end 384.641852 -265.49858)
		(width 0.0889)
		(layer "In13.Cu")
		(net "M_H_CPU0_SB_PAR")
	)
	(arc
		(start 388.393432 -265.503406)
		(mid 388.209924 -265.5489)
		(end 388.027672 -265.49858)
		(width 0.0889)
		(layer "In13.Cu")
		(net "M_H_CPU0_SB_PAR")
	)
	(arc
		(start 386.52196 -265.49858)
		(mid 386.339709 -265.54893)
		(end 386.1562 -265.503406)
		(width 0.0889)
		(layer "In13.Cu")
		(net "M_H_CPU0_SB_PAR")
	)
	(arc
		(start 384.26771 -265.49858)
		(mid 383.984754 -265.422403)
		(end 383.701798 -265.49858)
		(width 0.0889)
		(layer "In13.Cu")
		(net "M_H_CPU0_SB_PAR")
	)
	(arc
		(start 388.967726 -265.49858)
		(mid 388.68477 -265.422403)
		(end 388.401814 -265.49858)
		(width 0.0889)
		(layer "In13.Cu")
		(net "M_H_CPU0_SB_PAR")
	)
	(arc
		(start 386.147818 -265.49858)
		(mid 385.864862 -265.422403)
		(end 385.581906 -265.49858)
		(width 0.0889)
		(layer "In13.Cu")
		(net "M_H_CPU0_SB_PAR")
	)
	(arc
		(start 391.221722 -265.49858)
		(mid 391.034778 -265.548835)
		(end 390.847834 -265.49858)
		(width 0.0889)
		(layer "In13.Cu")
		(net "M_H_CPU0_SB_PAR")
	)
	(arc
		(start 388.027672 -265.49858)
		(mid 387.744716 -265.422403)
		(end 387.46176 -265.49858)
		(width 0.0889)
		(layer "In13.Cu")
		(net "M_H_CPU0_SB_PAR")
	)
	(arc
		(start 387.087872 -265.49858)
		(mid 386.804916 -265.422403)
		(end 386.52196 -265.49858)
		(width 0.0889)
		(layer "In13.Cu")
		(net "M_H_CPU0_SB_PAR")
	)
	(arc
		(start 385.581906 -265.49858)
		(mid 385.399655 -265.54893)
		(end 385.216146 -265.503406)
		(width 0.0889)
		(layer "In13.Cu")
		(net "M_H_CPU0_SB_PAR")
	)
	(arc
		(start 383.693416 -265.503406)
		(mid 383.509908 -265.5489)
		(end 383.327656 -265.49858)
		(width 0.0889)
		(layer "In13.Cu")
		(net "M_H_CPU0_SB_PAR")
	)
	(arc
		(start 389.333486 -265.503406)
		(mid 389.149978 -265.5489)
		(end 388.967726 -265.49858)
		(width 0.0889)
		(layer "In13.Cu")
		(net "M_H_CPU0_SB_PAR")
	)
	(segment
		(start 383.517902 -270.580104)
		(end 383.984754 -270.846042)
		(width 0.12954)
		(layer "F.Cu")
		(net "M_H_CPU0_SB_DQS_DP<9>")
	)
	(segment
		(start 392.253978 -271.1704)
		(end 392.255502 -271.171416)
		(width 0.09525)
		(layer "In13.Cu")
		(net "M_H_CPU0_SB_DQS_DP<9>")
	)
	(segment
		(start 383.984754 -270.846042)
		(end 384.138678 -271.111472)
		(width 0.09525)
		(layer "In13.Cu")
		(net "M_H_CPU0_SB_DQS_DP<9>")
	)
	(segment
		(start 420.3573 -275.65985)
		(end 420.692326 -275.994876)
		(width 0.16002)
		(layer "In13.Cu")
		(net "M_H_CPU0_SB_DQS_DP<9>")
	)
	(segment
		(start 414.285176 -274.809966)
		(end 414.695386 -275.220176)
		(width 0.16002)
		(layer "In13.Cu")
		(net "M_H_CPU0_SB_DQS_DP<9>")
	)
	(segment
		(start 393.064238 -270.38427)
		(end 393.085828 -270.372078)
		(width 0.09525)
		(layer "In13.Cu")
		(net "M_H_CPU0_SB_DQS_DP<9>")
	)
	(segment
		(start 394.555218 -269.17269)
		(end 395.221206 -269.17269)
		(width 0.09525)
		(layer "In13.Cu")
		(net "M_H_CPU0_SB_DQS_DP<9>")
	)
	(segment
		(start 395.742668 -269.2527)
		(end 405.200104 -269.2527)
		(width 0.16002)
		(layer "In13.Cu")
		(net "M_H_CPU0_SB_DQS_DP<9>")
	)
	(segment
		(start 388.48538 -271.16532)
		(end 388.49554 -271.171416)
		(width 0.09525)
		(layer "In13.Cu")
		(net "M_H_CPU0_SB_DQS_DP<9>")
	)
	(segment
		(start 392.230102 -271.157446)
		(end 392.241278 -271.163288)
		(width 0.09525)
		(layer "In13.Cu")
		(net "M_H_CPU0_SB_DQS_DP<9>")
	)
	(segment
		(start 411.964886 -274.809966)
		(end 414.285176 -274.809966)
		(width 0.16002)
		(layer "In13.Cu")
		(net "M_H_CPU0_SB_DQS_DP<9>")
	)
	(segment
		(start 389.425434 -271.16532)
		(end 389.435594 -271.171416)
		(width 0.09525)
		(layer "In13.Cu")
		(net "M_H_CPU0_SB_DQS_DP<9>")
	)
	(segment
		(start 416.515804 -275.68144)
		(end 416.977068 -275.220176)
		(width 0.16002)
		(layer "In13.Cu")
		(net "M_H_CPU0_SB_DQS_DP<9>")
	)
	(segment
		(start 385.113784 -271.171416)
		(end 385.114038 -271.171416)
		(width 0.09525)
		(layer "In13.Cu")
		(net "M_H_CPU0_SB_DQS_DP<9>")
	)
	(segment
		(start 389.8138 -271.171416)
		(end 389.814054 -271.171416)
		(width 0.09525)
		(layer "In13.Cu")
		(net "M_H_CPU0_SB_DQS_DP<9>")
	)
	(segment
		(start 395.719046 -269.2527)
		(end 395.742668 -269.2527)
		(width 0.09525)
		(layer "In13.Cu")
		(net "M_H_CPU0_SB_DQS_DP<9>")
	)
	(segment
		(start 384.138678 -271.111472)
		(end 384.239516 -271.138142)
		(width 0.09525)
		(layer "In13.Cu")
		(net "M_H_CPU0_SB_DQS_DP<9>")
	)
	(segment
		(start 421.61968 -275.836634)
		(end 422.017952 -275.836634)
		(width 0.16002)
		(layer "In13.Cu")
		(net "M_H_CPU0_SB_DQS_DP<9>")
	)
	(segment
		(start 414.695386 -275.220176)
		(end 415.569146 -275.220176)
		(width 0.16002)
		(layer "In13.Cu")
		(net "M_H_CPU0_SB_DQS_DP<9>")
	)
	(segment
		(start 422.96461 -276.278594)
		(end 423.40657 -275.836634)
		(width 0.16002)
		(layer "In13.Cu")
		(net "M_H_CPU0_SB_DQS_DP<9>")
	)
	(segment
		(start 415.569146 -275.220176)
		(end 416.03041 -275.68144)
		(width 0.16002)
		(layer "In13.Cu")
		(net "M_H_CPU0_SB_DQS_DP<9>")
	)
	(segment
		(start 416.977068 -275.220176)
		(end 418.010594 -275.220176)
		(width 0.16002)
		(layer "In13.Cu")
		(net "M_H_CPU0_SB_DQS_DP<9>")
	)
	(segment
		(start 393.606274 -270.121634)
		(end 394.555218 -269.17269)
		(width 0.09525)
		(layer "In13.Cu")
		(net "M_H_CPU0_SB_DQS_DP<9>")
	)
	(segment
		(start 409.004008 -271.849088)
		(end 411.964886 -274.809966)
		(width 0.16002)
		(layer "In13.Cu")
		(net "M_H_CPU0_SB_DQS_DP<9>")
	)
	(segment
		(start 418.010594 -275.220176)
		(end 418.450268 -275.65985)
		(width 0.16002)
		(layer "In13.Cu")
		(net "M_H_CPU0_SB_DQS_DP<9>")
	)
	(segment
		(start 423.710608 -275.836634)
		(end 424.012106 -275.535136)
		(width 0.16002)
		(layer "In13.Cu")
		(net "M_H_CPU0_SB_DQS_DP<9>")
	)
	(segment
		(start 392.633708 -271.171416)
		(end 392.664696 -271.153382)
		(width 0.09525)
		(layer "In13.Cu")
		(net "M_H_CPU0_SB_DQS_DP<9>")
	)
	(segment
		(start 388.49554 -271.171416)
		(end 388.495794 -271.171416)
		(width 0.09525)
		(layer "In13.Cu")
		(net "M_H_CPU0_SB_DQS_DP<9>")
	)
	(segment
		(start 392.2522 -271.169384)
		(end 392.253978 -271.1704)
		(width 0.09525)
		(layer "In13.Cu")
		(net "M_H_CPU0_SB_DQS_DP<9>")
	)
	(segment
		(start 392.255502 -271.171416)
		(end 392.255756 -271.171416)
		(width 0.09525)
		(layer "In13.Cu")
		(net "M_H_CPU0_SB_DQS_DP<9>")
	)
	(segment
		(start 423.40657 -275.836634)
		(end 423.710608 -275.836634)
		(width 0.16002)
		(layer "In13.Cu")
		(net "M_H_CPU0_SB_DQS_DP<9>")
	)
	(segment
		(start 395.360144 -269.311628)
		(end 395.660118 -269.311628)
		(width 0.09525)
		(layer "In13.Cu")
		(net "M_H_CPU0_SB_DQS_DP<9>")
	)
	(segment
		(start 420.692326 -275.994876)
		(end 421.461438 -275.994876)
		(width 0.16002)
		(layer "In13.Cu")
		(net "M_H_CPU0_SB_DQS_DP<9>")
	)
	(segment
		(start 422.017952 -275.836634)
		(end 422.459912 -276.278594)
		(width 0.16002)
		(layer "In13.Cu")
		(net "M_H_CPU0_SB_DQS_DP<9>")
	)
	(segment
		(start 416.03041 -275.68144)
		(end 416.515804 -275.68144)
		(width 0.16002)
		(layer "In13.Cu")
		(net "M_H_CPU0_SB_DQS_DP<9>")
	)
	(segment
		(start 385.114038 -271.171416)
		(end 385.124198 -271.16532)
		(width 0.09525)
		(layer "In13.Cu")
		(net "M_H_CPU0_SB_DQS_DP<9>")
	)
	(segment
		(start 395.221206 -269.17269)
		(end 395.360144 -269.311628)
		(width 0.09525)
		(layer "In13.Cu")
		(net "M_H_CPU0_SB_DQS_DP<9>")
	)
	(segment
		(start 407.796492 -271.849088)
		(end 409.004008 -271.849088)
		(width 0.16002)
		(layer "In13.Cu")
		(net "M_H_CPU0_SB_DQS_DP<9>")
	)
	(segment
		(start 389.814054 -271.171416)
		(end 389.824214 -271.16532)
		(width 0.09525)
		(layer "In13.Cu")
		(net "M_H_CPU0_SB_DQS_DP<9>")
	)
	(segment
		(start 392.241278 -271.163288)
		(end 392.2522 -271.169384)
		(width 0.09525)
		(layer "In13.Cu")
		(net "M_H_CPU0_SB_DQS_DP<9>")
	)
	(segment
		(start 384.725418 -271.16532)
		(end 384.735578 -271.171416)
		(width 0.09525)
		(layer "In13.Cu")
		(net "M_H_CPU0_SB_DQS_DP<9>")
	)
	(segment
		(start 421.461438 -275.994876)
		(end 421.61968 -275.836634)
		(width 0.16002)
		(layer "In13.Cu")
		(net "M_H_CPU0_SB_DQS_DP<9>")
	)
	(segment
		(start 384.239516 -271.138142)
		(end 384.238754 -271.138904)
		(width 0.09525)
		(layer "In13.Cu")
		(net "M_H_CPU0_SB_DQS_DP<9>")
	)
	(segment
		(start 393.603226 -270.124936)
		(end 393.606274 -270.121634)
		(width 0.09525)
		(layer "In13.Cu")
		(net "M_H_CPU0_SB_DQS_DP<9>")
	)
	(segment
		(start 386.054092 -271.171416)
		(end 386.064252 -271.16532)
		(width 0.09525)
		(layer "In13.Cu")
		(net "M_H_CPU0_SB_DQS_DP<9>")
	)
	(segment
		(start 395.660118 -269.311628)
		(end 395.719046 -269.2527)
		(width 0.09525)
		(layer "In13.Cu")
		(net "M_H_CPU0_SB_DQS_DP<9>")
	)
	(segment
		(start 405.200104 -269.2527)
		(end 407.796492 -271.849088)
		(width 0.16002)
		(layer "In13.Cu")
		(net "M_H_CPU0_SB_DQS_DP<9>")
	)
	(segment
		(start 386.053838 -271.171416)
		(end 386.054092 -271.171416)
		(width 0.09525)
		(layer "In13.Cu")
		(net "M_H_CPU0_SB_DQS_DP<9>")
	)
	(segment
		(start 418.450268 -275.65985)
		(end 420.3573 -275.65985)
		(width 0.16002)
		(layer "In13.Cu")
		(net "M_H_CPU0_SB_DQS_DP<9>")
	)
	(segment
		(start 422.459912 -276.278594)
		(end 422.96461 -276.278594)
		(width 0.16002)
		(layer "In13.Cu")
		(net "M_H_CPU0_SB_DQS_DP<9>")
	)
	(arc
		(start 392.822938 -270.846042)
		(mid 392.886837 -270.585495)
		(end 393.064238 -270.38427)
		(width 0.09525)
		(layer "In13.Cu")
		(net "M_H_CPU0_SB_DQS_DP<9>")
	)
	(arc
		(start 386.61594 -271.171416)
		(mid 386.804916 -271.222313)
		(end 386.993892 -271.171416)
		(width 0.09525)
		(layer "In13.Cu")
		(net "M_H_CPU0_SB_DQS_DP<9>")
	)
	(arc
		(start 391.315702 -271.171416)
		(mid 391.504678 -271.222313)
		(end 391.693654 -271.171416)
		(width 0.09525)
		(layer "In13.Cu")
		(net "M_H_CPU0_SB_DQS_DP<9>")
	)
	(arc
		(start 389.435594 -271.171416)
		(mid 389.624714 -271.222441)
		(end 389.8138 -271.171416)
		(width 0.09525)
		(layer "In13.Cu")
		(net "M_H_CPU0_SB_DQS_DP<9>")
	)
	(arc
		(start 384.238754 -271.138904)
		(mid 384.249381 -271.134734)
		(end 384.26009 -271.130776)
		(width 0.09525)
		(layer "In13.Cu")
		(net "M_H_CPU0_SB_DQS_DP<9>")
	)
	(arc
		(start 385.124198 -271.16532)
		(mid 385.400852 -271.095734)
		(end 385.675886 -271.171416)
		(width 0.09525)
		(layer "In13.Cu")
		(net "M_H_CPU0_SB_DQS_DP<9>")
	)
	(arc
		(start 385.675886 -271.171416)
		(mid 385.864862 -271.222313)
		(end 386.053838 -271.171416)
		(width 0.09525)
		(layer "In13.Cu")
		(net "M_H_CPU0_SB_DQS_DP<9>")
	)
	(arc
		(start 388.873746 -271.171416)
		(mid 389.148781 -271.095788)
		(end 389.425434 -271.16532)
		(width 0.09525)
		(layer "In13.Cu")
		(net "M_H_CPU0_SB_DQS_DP<9>")
	)
	(arc
		(start 392.664696 -271.153382)
		(mid 392.780961 -271.018844)
		(end 392.822938 -270.846042)
		(width 0.09525)
		(layer "In13.Cu")
		(net "M_H_CPU0_SB_DQS_DP<9>")
	)
	(arc
		(start 389.824214 -271.16532)
		(mid 390.100868 -271.095734)
		(end 390.375902 -271.171416)
		(width 0.09525)
		(layer "In13.Cu")
		(net "M_H_CPU0_SB_DQS_DP<9>")
	)
	(arc
		(start 393.085828 -270.372078)
		(mid 393.094668 -270.366535)
		(end 393.103608 -270.361156)
		(width 0.09525)
		(layer "In13.Cu")
		(net "M_H_CPU0_SB_DQS_DP<9>")
	)
	(arc
		(start 390.753854 -271.171416)
		(mid 391.034778 -271.095882)
		(end 391.315702 -271.171416)
		(width 0.09525)
		(layer "In13.Cu")
		(net "M_H_CPU0_SB_DQS_DP<9>")
	)
	(arc
		(start 384.26009 -271.130776)
		(mid 384.496536 -271.097253)
		(end 384.725418 -271.16532)
		(width 0.09525)
		(layer "In13.Cu")
		(net "M_H_CPU0_SB_DQS_DP<9>")
	)
	(arc
		(start 391.693654 -271.171416)
		(mid 391.960085 -271.096069)
		(end 392.230102 -271.157446)
		(width 0.09525)
		(layer "In13.Cu")
		(net "M_H_CPU0_SB_DQS_DP<9>")
	)
	(arc
		(start 392.255756 -271.171416)
		(mid 392.444732 -271.222313)
		(end 392.633708 -271.171416)
		(width 0.09525)
		(layer "In13.Cu")
		(net "M_H_CPU0_SB_DQS_DP<9>")
	)
	(arc
		(start 387.55574 -271.171416)
		(mid 387.744716 -271.222313)
		(end 387.933692 -271.171416)
		(width 0.09525)
		(layer "In13.Cu")
		(net "M_H_CPU0_SB_DQS_DP<9>")
	)
	(arc
		(start 393.29487 -270.292576)
		(mid 393.463322 -270.235009)
		(end 393.603226 -270.124936)
		(width 0.09525)
		(layer "In13.Cu")
		(net "M_H_CPU0_SB_DQS_DP<9>")
	)
	(arc
		(start 387.933692 -271.171416)
		(mid 388.208727 -271.095788)
		(end 388.48538 -271.16532)
		(width 0.09525)
		(layer "In13.Cu")
		(net "M_H_CPU0_SB_DQS_DP<9>")
	)
	(arc
		(start 393.103608 -270.361156)
		(mid 393.196106 -270.31813)
		(end 393.29487 -270.292576)
		(width 0.09525)
		(layer "In13.Cu")
		(net "M_H_CPU0_SB_DQS_DP<9>")
	)
	(arc
		(start 386.993892 -271.171416)
		(mid 387.274816 -271.095882)
		(end 387.55574 -271.171416)
		(width 0.09525)
		(layer "In13.Cu")
		(net "M_H_CPU0_SB_DQS_DP<9>")
	)
	(arc
		(start 386.064252 -271.16532)
		(mid 386.340906 -271.095734)
		(end 386.61594 -271.171416)
		(width 0.09525)
		(layer "In13.Cu")
		(net "M_H_CPU0_SB_DQS_DP<9>")
	)
	(arc
		(start 384.735578 -271.171416)
		(mid 384.924698 -271.222441)
		(end 385.113784 -271.171416)
		(width 0.09525)
		(layer "In13.Cu")
		(net "M_H_CPU0_SB_DQS_DP<9>")
	)
	(arc
		(start 388.495794 -271.171416)
		(mid 388.68477 -271.222313)
		(end 388.873746 -271.171416)
		(width 0.09525)
		(layer "In13.Cu")
		(net "M_H_CPU0_SB_DQS_DP<9>")
	)
	(arc
		(start 390.375902 -271.171416)
		(mid 390.564878 -271.222313)
		(end 390.753854 -271.171416)
		(width 0.09525)
		(layer "In13.Cu")
		(net "M_H_CPU0_SB_DQS_DP<9>")
	)
	(segment
		(start 382.577848 -291.640006)
		(end 383.0447 -291.905944)
		(width 0.12954)
		(layer "F.Cu")
		(net "M_H_CPU0_SB_DQS_DP<8>")
	)
	(segment
		(start 419.57752 -314.300616)
		(end 417.797234 -314.300616)
		(width 0.16002)
		(layer "In13.Cu")
		(net "M_H_CPU0_SB_DQS_DP<8>")
	)
	(segment
		(start 409.659328 -314.261754)
		(end 409.499308 -314.421774)
		(width 0.16002)
		(layer "In13.Cu")
		(net "M_H_CPU0_SB_DQS_DP<8>")
	)
	(segment
		(start 390.753346 -291.580824)
		(end 390.744964 -291.575998)
		(width 0.09525)
		(layer "In13.Cu")
		(net "M_H_CPU0_SB_DQS_DP<8>")
	)
	(segment
		(start 409.499308 -314.881514)
		(end 409.16225 -315.218572)
		(width 0.16002)
		(layer "In13.Cu")
		(net "M_H_CPU0_SB_DQS_DP<8>")
	)
	(segment
		(start 414.001458 -314.997592)
		(end 412.476696 -314.997592)
		(width 0.16002)
		(layer "In13.Cu")
		(net "M_H_CPU0_SB_DQS_DP<8>")
	)
	(segment
		(start 393.762484 -293.525956)
		(end 393.762992 -293.525448)
		(width 0.09525)
		(layer "In13.Cu")
		(net "M_H_CPU0_SB_DQS_DP<8>")
	)
	(segment
		(start 392.822684 -291.905944)
		(end 392.82243 -291.905944)
		(width 0.09525)
		(layer "In13.Cu")
		(net "M_H_CPU0_SB_DQS_DP<8>")
	)
	(segment
		(start 394.014706 -293.994332)
		(end 394.013944 -293.993824)
		(width 0.09525)
		(layer "In13.Cu")
		(net "M_H_CPU0_SB_DQS_DP<8>")
	)
	(segment
		(start 392.264646 -291.575998)
		(end 392.256264 -291.580824)
		(width 0.09525)
		(layer "In13.Cu")
		(net "M_H_CPU0_SB_DQS_DP<8>")
	)
	(segment
		(start 382.890776 -291.640514)
		(end 383.0447 -291.905944)
		(width 0.09525)
		(layer "In13.Cu")
		(net "M_H_CPU0_SB_DQS_DP<8>")
	)
	(segment
		(start 417.637214 -314.98667)
		(end 417.300156 -315.323728)
		(width 0.16002)
		(layer "In13.Cu")
		(net "M_H_CPU0_SB_DQS_DP<8>")
	)
	(segment
		(start 394.798042 -295.125394)
		(end 394.232384 -294.560244)
		(width 0.09525)
		(layer "In13.Cu")
		(net "M_H_CPU0_SB_DQS_DP<8>")
	)
	(segment
		(start 392.66495 -291.599112)
		(end 392.633454 -291.580824)
		(width 0.09525)
		(layer "In13.Cu")
		(net "M_H_CPU0_SB_DQS_DP<8>")
	)
	(segment
		(start 395.002258 -295.411906)
		(end 394.81506 -295.22547)
		(width 0.16002)
		(layer "In13.Cu")
		(net "M_H_CPU0_SB_DQS_DP<8>")
	)
	(segment
		(start 393.543536 -292.877494)
		(end 393.00023 -292.334188)
		(width 0.09525)
		(layer "In13.Cu")
		(net "M_H_CPU0_SB_DQS_DP<8>")
	)
	(segment
		(start 386.05333 -291.580824)
		(end 386.044948 -291.575998)
		(width 0.09525)
		(layer "In13.Cu")
		(net "M_H_CPU0_SB_DQS_DP<8>")
	)
	(segment
		(start 382.914144 -291.553646)
		(end 382.890776 -291.640514)
		(width 0.09525)
		(layer "In13.Cu")
		(net "M_H_CPU0_SB_DQS_DP<8>")
	)
	(segment
		(start 394.81506 -295.22547)
		(end 394.798296 -295.208706)
		(width 0.09525)
		(layer "In13.Cu")
		(net "M_H_CPU0_SB_DQS_DP<8>")
	)
	(segment
		(start 394.798296 -295.208706)
		(end 394.798042 -295.125394)
		(width 0.09525)
		(layer "In13.Cu")
		(net "M_H_CPU0_SB_DQS_DP<8>")
	)
	(segment
		(start 393.762992 -293.525448)
		(end 393.762992 -293.40683)
		(width 0.09525)
		(layer "In13.Cu")
		(net "M_H_CPU0_SB_DQS_DP<8>")
	)
	(segment
		(start 409.16225 -315.218572)
		(end 408.69743 -315.218572)
		(width 0.16002)
		(layer "In13.Cu")
		(net "M_H_CPU0_SB_DQS_DP<8>")
	)
	(segment
		(start 416.175698 -315.323728)
		(end 415.83864 -314.98667)
		(width 0.16002)
		(layer "In13.Cu")
		(net "M_H_CPU0_SB_DQS_DP<8>")
	)
	(segment
		(start 409.499308 -314.421774)
		(end 409.499308 -314.881514)
		(width 0.16002)
		(layer "In13.Cu")
		(net "M_H_CPU0_SB_DQS_DP<8>")
	)
	(segment
		(start 383.804668 -291.575998)
		(end 383.796286 -291.580824)
		(width 0.09525)
		(layer "In13.Cu")
		(net "M_H_CPU0_SB_DQS_DP<8>")
	)
	(segment
		(start 417.300156 -315.323728)
		(end 416.175698 -315.323728)
		(width 0.16002)
		(layer "In13.Cu")
		(net "M_H_CPU0_SB_DQS_DP<8>")
	)
	(segment
		(start 391.324592 -291.575998)
		(end 391.31621 -291.580824)
		(width 0.09525)
		(layer "In13.Cu")
		(net "M_H_CPU0_SB_DQS_DP<8>")
	)
	(segment
		(start 392.822938 -291.906198)
		(end 392.822684 -291.905944)
		(width 0.09525)
		(layer "In13.Cu")
		(net "M_H_CPU0_SB_DQS_DP<8>")
	)
	(segment
		(start 393.762992 -293.40683)
		(end 393.762738 -293.407084)
		(width 0.09525)
		(layer "In13.Cu")
		(net "M_H_CPU0_SB_DQS_DP<8>")
	)
	(segment
		(start 408.69743 -315.218572)
		(end 395.002258 -301.5234)
		(width 0.16002)
		(layer "In13.Cu")
		(net "M_H_CPU0_SB_DQS_DP<8>")
	)
	(segment
		(start 394.074904 -294.02913)
		(end 394.014706 -293.994332)
		(width 0.09525)
		(layer "In13.Cu")
		(net "M_H_CPU0_SB_DQS_DP<8>")
	)
	(segment
		(start 410.167328 -314.421774)
		(end 410.007308 -314.261754)
		(width 0.16002)
		(layer "In13.Cu")
		(net "M_H_CPU0_SB_DQS_DP<8>")
	)
	(segment
		(start 388.504684 -291.575998)
		(end 388.496302 -291.580824)
		(width 0.09525)
		(layer "In13.Cu")
		(net "M_H_CPU0_SB_DQS_DP<8>")
	)
	(segment
		(start 412.164784 -314.68568)
		(end 411.59557 -314.68568)
		(width 0.16002)
		(layer "In13.Cu")
		(net "M_H_CPU0_SB_DQS_DP<8>")
	)
	(segment
		(start 386.993384 -291.580824)
		(end 386.985002 -291.575998)
		(width 0.09525)
		(layer "In13.Cu")
		(net "M_H_CPU0_SB_DQS_DP<8>")
	)
	(segment
		(start 410.167328 -314.881514)
		(end 410.167328 -314.421774)
		(width 0.16002)
		(layer "In13.Cu")
		(net "M_H_CPU0_SB_DQS_DP<8>")
	)
	(segment
		(start 419.912038 -314.635134)
		(end 419.57752 -314.300616)
		(width 0.16002)
		(layer "In13.Cu")
		(net "M_H_CPU0_SB_DQS_DP<8>")
	)
	(segment
		(start 417.637214 -314.460636)
		(end 417.637214 -314.98667)
		(width 0.16002)
		(layer "In13.Cu")
		(net "M_H_CPU0_SB_DQS_DP<8>")
	)
	(segment
		(start 414.964626 -314.034424)
		(end 414.001458 -314.997592)
		(width 0.16002)
		(layer "In13.Cu")
		(net "M_H_CPU0_SB_DQS_DP<8>")
	)
	(segment
		(start 410.504386 -315.218572)
		(end 410.167328 -314.881514)
		(width 0.16002)
		(layer "In13.Cu")
		(net "M_H_CPU0_SB_DQS_DP<8>")
	)
	(segment
		(start 412.476696 -314.997592)
		(end 412.164784 -314.68568)
		(width 0.16002)
		(layer "In13.Cu")
		(net "M_H_CPU0_SB_DQS_DP<8>")
	)
	(segment
		(start 411.062678 -315.218572)
		(end 410.504386 -315.218572)
		(width 0.16002)
		(layer "In13.Cu")
		(net "M_H_CPU0_SB_DQS_DP<8>")
	)
	(segment
		(start 411.59557 -314.68568)
		(end 411.062678 -315.218572)
		(width 0.16002)
		(layer "In13.Cu")
		(net "M_H_CPU0_SB_DQS_DP<8>")
	)
	(segment
		(start 415.83864 -314.98667)
		(end 415.83864 -314.497974)
		(width 0.16002)
		(layer "In13.Cu")
		(net "M_H_CPU0_SB_DQS_DP<8>")
	)
	(segment
		(start 415.83864 -314.497974)
		(end 415.37509 -314.034424)
		(width 0.16002)
		(layer "In13.Cu")
		(net "M_H_CPU0_SB_DQS_DP<8>")
	)
	(segment
		(start 394.232384 -294.560244)
		(end 394.232384 -294.335962)
		(width 0.09525)
		(layer "In13.Cu")
		(net "M_H_CPU0_SB_DQS_DP<8>")
	)
	(segment
		(start 387.56463 -291.575998)
		(end 387.556248 -291.580824)
		(width 0.09525)
		(layer "In13.Cu")
		(net "M_H_CPU0_SB_DQS_DP<8>")
	)
	(segment
		(start 395.002258 -301.5234)
		(end 395.002258 -295.411906)
		(width 0.16002)
		(layer "In13.Cu")
		(net "M_H_CPU0_SB_DQS_DP<8>")
	)
	(segment
		(start 417.797234 -314.300616)
		(end 417.637214 -314.460636)
		(width 0.16002)
		(layer "In13.Cu")
		(net "M_H_CPU0_SB_DQS_DP<8>")
	)
	(segment
		(start 415.37509 -314.034424)
		(end 414.964626 -314.034424)
		(width 0.16002)
		(layer "In13.Cu")
		(net "M_H_CPU0_SB_DQS_DP<8>")
	)
	(segment
		(start 394.013944 -293.993824)
		(end 394.005308 -293.988744)
		(width 0.09525)
		(layer "In13.Cu")
		(net "M_H_CPU0_SB_DQS_DP<8>")
	)
	(segment
		(start 410.007308 -314.261754)
		(end 409.659328 -314.261754)
		(width 0.16002)
		(layer "In13.Cu")
		(net "M_H_CPU0_SB_DQS_DP<8>")
	)
	(arc
		(start 392.256264 -291.580824)
		(mid 391.974832 -291.656579)
		(end 391.6934 -291.580824)
		(width 0.09525)
		(layer "In13.Cu")
		(net "M_H_CPU0_SB_DQS_DP<8>")
	)
	(arc
		(start 386.616194 -291.580824)
		(mid 386.334762 -291.656579)
		(end 386.05333 -291.580824)
		(width 0.09525)
		(layer "In13.Cu")
		(net "M_H_CPU0_SB_DQS_DP<8>")
	)
	(arc
		(start 393.00023 -292.334188)
		(mid 392.868995 -292.137825)
		(end 392.822938 -291.906198)
		(width 0.09525)
		(layer "In13.Cu")
		(net "M_H_CPU0_SB_DQS_DP<8>")
	)
	(arc
		(start 392.82243 -291.905944)
		(mid 392.780765 -291.733497)
		(end 392.66495 -291.599112)
		(width 0.09525)
		(layer "In13.Cu")
		(net "M_H_CPU0_SB_DQS_DP<8>")
	)
	(arc
		(start 390.744964 -291.575998)
		(mid 390.559932 -291.530084)
		(end 390.376156 -291.580824)
		(width 0.09525)
		(layer "In13.Cu")
		(net "M_H_CPU0_SB_DQS_DP<8>")
	)
	(arc
		(start 387.556248 -291.580824)
		(mid 387.274816 -291.656579)
		(end 386.993384 -291.580824)
		(width 0.09525)
		(layer "In13.Cu")
		(net "M_H_CPU0_SB_DQS_DP<8>")
	)
	(arc
		(start 392.633454 -291.580824)
		(mid 392.449679 -291.530052)
		(end 392.264646 -291.575998)
		(width 0.09525)
		(layer "In13.Cu")
		(net "M_H_CPU0_SB_DQS_DP<8>")
	)
	(arc
		(start 383.233422 -291.580824)
		(mid 383.076824 -291.531535)
		(end 382.914144 -291.553646)
		(width 0.09525)
		(layer "In13.Cu")
		(net "M_H_CPU0_SB_DQS_DP<8>")
	)
	(arc
		(start 389.813292 -291.580824)
		(mid 389.624824 -291.530147)
		(end 389.436356 -291.580824)
		(width 0.09525)
		(layer "In13.Cu")
		(net "M_H_CPU0_SB_DQS_DP<8>")
	)
	(arc
		(start 391.6934 -291.580824)
		(mid 391.509625 -291.530052)
		(end 391.324592 -291.575998)
		(width 0.09525)
		(layer "In13.Cu")
		(net "M_H_CPU0_SB_DQS_DP<8>")
	)
	(arc
		(start 390.376156 -291.580824)
		(mid 390.094724 -291.656579)
		(end 389.813292 -291.580824)
		(width 0.09525)
		(layer "In13.Cu")
		(net "M_H_CPU0_SB_DQS_DP<8>")
	)
	(arc
		(start 394.005308 -293.988744)
		(mid 393.826858 -293.787274)
		(end 393.762484 -293.525956)
		(width 0.09525)
		(layer "In13.Cu")
		(net "M_H_CPU0_SB_DQS_DP<8>")
	)
	(arc
		(start 389.436356 -291.580824)
		(mid 389.154924 -291.656579)
		(end 388.873492 -291.580824)
		(width 0.09525)
		(layer "In13.Cu")
		(net "M_H_CPU0_SB_DQS_DP<8>")
	)
	(arc
		(start 387.933438 -291.580824)
		(mid 387.749663 -291.530052)
		(end 387.56463 -291.575998)
		(width 0.09525)
		(layer "In13.Cu")
		(net "M_H_CPU0_SB_DQS_DP<8>")
	)
	(arc
		(start 394.232384 -294.335962)
		(mid 394.190719 -294.163515)
		(end 394.074904 -294.02913)
		(width 0.09525)
		(layer "In13.Cu")
		(net "M_H_CPU0_SB_DQS_DP<8>")
	)
	(arc
		(start 385.113276 -291.580824)
		(mid 384.924808 -291.530147)
		(end 384.73634 -291.580824)
		(width 0.09525)
		(layer "In13.Cu")
		(net "M_H_CPU0_SB_DQS_DP<8>")
	)
	(arc
		(start 385.67614 -291.580824)
		(mid 385.394708 -291.656579)
		(end 385.113276 -291.580824)
		(width 0.09525)
		(layer "In13.Cu")
		(net "M_H_CPU0_SB_DQS_DP<8>")
	)
	(arc
		(start 388.496302 -291.580824)
		(mid 388.21487 -291.656579)
		(end 387.933438 -291.580824)
		(width 0.09525)
		(layer "In13.Cu")
		(net "M_H_CPU0_SB_DQS_DP<8>")
	)
	(arc
		(start 393.762738 -293.407084)
		(mid 393.705838 -293.120466)
		(end 393.543536 -292.877494)
		(width 0.09525)
		(layer "In13.Cu")
		(net "M_H_CPU0_SB_DQS_DP<8>")
	)
	(arc
		(start 383.796286 -291.580824)
		(mid 383.514854 -291.656579)
		(end 383.233422 -291.580824)
		(width 0.09525)
		(layer "In13.Cu")
		(net "M_H_CPU0_SB_DQS_DP<8>")
	)
	(arc
		(start 384.173476 -291.580824)
		(mid 383.989701 -291.530052)
		(end 383.804668 -291.575998)
		(width 0.09525)
		(layer "In13.Cu")
		(net "M_H_CPU0_SB_DQS_DP<8>")
	)
	(arc
		(start 384.73634 -291.580824)
		(mid 384.454908 -291.656579)
		(end 384.173476 -291.580824)
		(width 0.09525)
		(layer "In13.Cu")
		(net "M_H_CPU0_SB_DQS_DP<8>")
	)
	(arc
		(start 391.31621 -291.580824)
		(mid 391.034778 -291.656579)
		(end 390.753346 -291.580824)
		(width 0.09525)
		(layer "In13.Cu")
		(net "M_H_CPU0_SB_DQS_DP<8>")
	)
	(arc
		(start 388.873492 -291.580824)
		(mid 388.689717 -291.530052)
		(end 388.504684 -291.575998)
		(width 0.09525)
		(layer "In13.Cu")
		(net "M_H_CPU0_SB_DQS_DP<8>")
	)
	(arc
		(start 386.044948 -291.575998)
		(mid 385.859916 -291.530084)
		(end 385.67614 -291.580824)
		(width 0.09525)
		(layer "In13.Cu")
		(net "M_H_CPU0_SB_DQS_DP<8>")
	)
	(arc
		(start 386.985002 -291.575998)
		(mid 386.79997 -291.530084)
		(end 386.616194 -291.580824)
		(width 0.09525)
		(layer "In13.Cu")
		(net "M_H_CPU0_SB_DQS_DP<8>")
	)
	(segment
		(start 382.577848 -286.780224)
		(end 383.0447 -287.045908)
		(width 0.12954)
		(layer "F.Cu")
		(net "M_H_CPU0_SB_DQS_DP<7>")
	)
	(segment
		(start 409.828746 -305.06543)
		(end 409.988766 -304.90541)
		(width 0.16002)
		(layer "In13.Cu")
		(net "M_H_CPU0_SB_DQS_DP<7>")
	)
	(segment
		(start 419.643052 -305.016154)
		(end 419.912038 -305.28514)
		(width 0.16002)
		(layer "In13.Cu")
		(net "M_H_CPU0_SB_DQS_DP<7>")
	)
	(segment
		(start 386.044948 -286.715962)
		(end 386.05333 -286.720788)
		(width 0.09525)
		(layer "In13.Cu")
		(net "M_H_CPU0_SB_DQS_DP<7>")
	)
	(segment
		(start 406.599644 -302.711358)
		(end 406.599644 -302.937418)
		(width 0.16002)
		(layer "In13.Cu")
		(net "M_H_CPU0_SB_DQS_DP<7>")
	)
	(segment
		(start 400.575018 -297.824144)
		(end 403.843744 -301.09287)
		(width 0.16002)
		(layer "In13.Cu")
		(net "M_H_CPU0_SB_DQS_DP<7>")
	)
	(segment
		(start 404.865332 -301.637954)
		(end 404.865332 -302.114458)
		(width 0.16002)
		(layer "In13.Cu")
		(net "M_H_CPU0_SB_DQS_DP<7>")
	)
	(segment
		(start 388.496302 -286.720788)
		(end 388.504684 -286.715962)
		(width 0.09525)
		(layer "In13.Cu")
		(net "M_H_CPU0_SB_DQS_DP<7>")
	)
	(segment
		(start 405.360632 -302.609758)
		(end 405.837136 -302.609758)
		(width 0.16002)
		(layer "In13.Cu")
		(net "M_H_CPU0_SB_DQS_DP<7>")
	)
	(segment
		(start 383.796286 -286.720788)
		(end 383.804668 -286.715962)
		(width 0.09525)
		(layer "In13.Cu")
		(net "M_H_CPU0_SB_DQS_DP<7>")
	)
	(segment
		(start 408.091894 -304.39741)
		(end 407.860754 -304.62855)
		(width 0.16002)
		(layer "In13.Cu")
		(net "M_H_CPU0_SB_DQS_DP<7>")
	)
	(segment
		(start 404.537672 -300.875446)
		(end 404.763732 -300.875446)
		(width 0.16002)
		(layer "In13.Cu")
		(net "M_H_CPU0_SB_DQS_DP<7>")
	)
	(segment
		(start 409.988766 -304.90541)
		(end 410.438346 -304.90541)
		(width 0.16002)
		(layer "In13.Cu")
		(net "M_H_CPU0_SB_DQS_DP<7>")
	)
	(segment
		(start 395.628622 -287.720532)
		(end 395.628622 -287.803336)
		(width 0.09525)
		(layer "In13.Cu")
		(net "M_H_CPU0_SB_DQS_DP<7>")
	)
	(segment
		(start 417.659058 -304.794158)
		(end 417.881054 -305.016154)
		(width 0.16002)
		(layer "In13.Cu")
		(net "M_H_CPU0_SB_DQS_DP<7>")
	)
	(segment
		(start 417.881054 -305.016154)
		(end 419.643052 -305.016154)
		(width 0.16002)
		(layer "In13.Cu")
		(net "M_H_CPU0_SB_DQS_DP<7>")
	)
	(segment
		(start 405.082756 -301.19447)
		(end 405.082756 -301.42053)
		(width 0.16002)
		(layer "In13.Cu")
		(net "M_H_CPU0_SB_DQS_DP<7>")
	)
	(segment
		(start 408.091894 -304.17135)
		(end 408.091894 -304.39741)
		(width 0.16002)
		(layer "In13.Cu")
		(net "M_H_CPU0_SB_DQS_DP<7>")
	)
	(segment
		(start 407.54681 -303.852326)
		(end 407.77287 -303.852326)
		(width 0.16002)
		(layer "In13.Cu")
		(net "M_H_CPU0_SB_DQS_DP<7>")
	)
	(segment
		(start 387.556248 -286.720788)
		(end 387.56463 -286.715962)
		(width 0.09525)
		(layer "In13.Cu")
		(net "M_H_CPU0_SB_DQS_DP<7>")
	)
	(segment
		(start 408.397964 -305.642264)
		(end 409.491688 -305.642264)
		(width 0.16002)
		(layer "In13.Cu")
		(net "M_H_CPU0_SB_DQS_DP<7>")
	)
	(segment
		(start 406.05456 -302.392334)
		(end 406.28062 -302.392334)
		(width 0.16002)
		(layer "In13.Cu")
		(net "M_H_CPU0_SB_DQS_DP<7>")
	)
	(segment
		(start 405.082756 -301.42053)
		(end 404.865332 -301.637954)
		(width 0.16002)
		(layer "In13.Cu")
		(net "M_H_CPU0_SB_DQS_DP<7>")
	)
	(segment
		(start 386.985002 -286.715962)
		(end 386.993384 -286.720788)
		(width 0.09525)
		(layer "In13.Cu")
		(net "M_H_CPU0_SB_DQS_DP<7>")
	)
	(segment
		(start 407.860754 -305.105054)
		(end 408.397964 -305.642264)
		(width 0.16002)
		(layer "In13.Cu")
		(net "M_H_CPU0_SB_DQS_DP<7>")
	)
	(segment
		(start 390.744964 -286.715962)
		(end 390.753346 -286.720788)
		(width 0.09525)
		(layer "In13.Cu")
		(net "M_H_CPU0_SB_DQS_DP<7>")
	)
	(segment
		(start 391.31621 -286.720788)
		(end 391.324592 -286.715962)
		(width 0.09525)
		(layer "In13.Cu")
		(net "M_H_CPU0_SB_DQS_DP<7>")
	)
	(segment
		(start 395.645386 -287.8201)
		(end 400.575018 -292.749732)
		(width 0.16002)
		(layer "In13.Cu")
		(net "M_H_CPU0_SB_DQS_DP<7>")
	)
	(segment
		(start 404.763732 -300.875446)
		(end 405.082756 -301.19447)
		(width 0.16002)
		(layer "In13.Cu")
		(net "M_H_CPU0_SB_DQS_DP<7>")
	)
	(segment
		(start 407.31567 -304.083466)
		(end 407.54681 -303.852326)
		(width 0.16002)
		(layer "In13.Cu")
		(net "M_H_CPU0_SB_DQS_DP<7>")
	)
	(segment
		(start 395.628622 -287.803336)
		(end 395.645386 -287.8201)
		(width 0.09525)
		(layer "In13.Cu")
		(net "M_H_CPU0_SB_DQS_DP<7>")
	)
	(segment
		(start 410.598366 -305.06543)
		(end 410.598366 -305.305206)
		(width 0.16002)
		(layer "In13.Cu")
		(net "M_H_CPU0_SB_DQS_DP<7>")
	)
	(segment
		(start 410.438346 -304.90541)
		(end 410.598366 -305.06543)
		(width 0.16002)
		(layer "In13.Cu")
		(net "M_H_CPU0_SB_DQS_DP<7>")
	)
	(segment
		(start 404.865332 -302.114458)
		(end 405.360632 -302.609758)
		(width 0.16002)
		(layer "In13.Cu")
		(net "M_H_CPU0_SB_DQS_DP<7>")
	)
	(segment
		(start 382.890776 -286.780478)
		(end 382.914144 -286.69361)
		(width 0.09525)
		(layer "In13.Cu")
		(net "M_H_CPU0_SB_DQS_DP<7>")
	)
	(segment
		(start 414.854898 -304.794158)
		(end 417.659058 -304.794158)
		(width 0.16002)
		(layer "In13.Cu")
		(net "M_H_CPU0_SB_DQS_DP<7>")
	)
	(segment
		(start 394.513816 -287.165542)
		(end 395.183868 -287.165542)
		(width 0.09525)
		(layer "In13.Cu")
		(net "M_H_CPU0_SB_DQS_DP<7>")
	)
	(segment
		(start 392.445494 -286.66948)
		(end 394.017754 -286.66948)
		(width 0.09525)
		(layer "In13.Cu")
		(net "M_H_CPU0_SB_DQS_DP<7>")
	)
	(segment
		(start 407.860754 -304.62855)
		(end 407.860754 -305.105054)
		(width 0.16002)
		(layer "In13.Cu")
		(net "M_H_CPU0_SB_DQS_DP<7>")
	)
	(segment
		(start 404.320248 -301.09287)
		(end 404.537672 -300.875446)
		(width 0.16002)
		(layer "In13.Cu")
		(net "M_H_CPU0_SB_DQS_DP<7>")
	)
	(segment
		(start 410.935424 -305.642264)
		(end 414.006792 -305.642264)
		(width 0.16002)
		(layer "In13.Cu")
		(net "M_H_CPU0_SB_DQS_DP<7>")
	)
	(segment
		(start 403.843744 -301.09287)
		(end 404.320248 -301.09287)
		(width 0.16002)
		(layer "In13.Cu")
		(net "M_H_CPU0_SB_DQS_DP<7>")
	)
	(segment
		(start 409.491688 -305.642264)
		(end 409.828746 -305.305206)
		(width 0.16002)
		(layer "In13.Cu")
		(net "M_H_CPU0_SB_DQS_DP<7>")
	)
	(segment
		(start 392.256518 -286.720788)
		(end 392.256518 -286.720534)
		(width 0.09525)
		(layer "In13.Cu")
		(net "M_H_CPU0_SB_DQS_DP<7>")
	)
	(segment
		(start 395.414246 -287.39592)
		(end 395.414246 -287.505902)
		(width 0.09525)
		(layer "In13.Cu")
		(net "M_H_CPU0_SB_DQS_DP<7>")
	)
	(segment
		(start 407.77287 -303.852326)
		(end 408.091894 -304.17135)
		(width 0.16002)
		(layer "In13.Cu")
		(net "M_H_CPU0_SB_DQS_DP<7>")
	)
	(segment
		(start 383.0447 -287.045908)
		(end 382.890776 -286.780478)
		(width 0.09525)
		(layer "In13.Cu")
		(net "M_H_CPU0_SB_DQS_DP<7>")
	)
	(segment
		(start 410.598366 -305.305206)
		(end 410.935424 -305.642264)
		(width 0.16002)
		(layer "In13.Cu")
		(net "M_H_CPU0_SB_DQS_DP<7>")
	)
	(segment
		(start 391.6934 -286.720788)
		(end 391.703814 -286.726884)
		(width 0.09525)
		(layer "In13.Cu")
		(net "M_H_CPU0_SB_DQS_DP<7>")
	)
	(segment
		(start 409.828746 -305.305206)
		(end 409.828746 -305.06543)
		(width 0.16002)
		(layer "In13.Cu")
		(net "M_H_CPU0_SB_DQS_DP<7>")
	)
	(segment
		(start 405.837136 -302.609758)
		(end 406.05456 -302.392334)
		(width 0.16002)
		(layer "In13.Cu")
		(net "M_H_CPU0_SB_DQS_DP<7>")
	)
	(segment
		(start 394.017754 -286.66948)
		(end 394.513816 -287.165542)
		(width 0.09525)
		(layer "In13.Cu")
		(net "M_H_CPU0_SB_DQS_DP<7>")
	)
	(segment
		(start 406.599644 -302.937418)
		(end 406.38476 -303.152302)
		(width 0.16002)
		(layer "In13.Cu")
		(net "M_H_CPU0_SB_DQS_DP<7>")
	)
	(segment
		(start 400.575018 -292.749732)
		(end 400.575018 -297.824144)
		(width 0.16002)
		(layer "In13.Cu")
		(net "M_H_CPU0_SB_DQS_DP<7>")
	)
	(segment
		(start 414.006792 -305.642264)
		(end 414.854898 -304.794158)
		(width 0.16002)
		(layer "In13.Cu")
		(net "M_H_CPU0_SB_DQS_DP<7>")
	)
	(segment
		(start 395.183868 -287.165542)
		(end 395.414246 -287.39592)
		(width 0.09525)
		(layer "In13.Cu")
		(net "M_H_CPU0_SB_DQS_DP<7>")
	)
	(segment
		(start 406.38476 -303.152302)
		(end 406.38476 -303.62906)
		(width 0.16002)
		(layer "In13.Cu")
		(net "M_H_CPU0_SB_DQS_DP<7>")
	)
	(segment
		(start 406.839166 -304.083466)
		(end 407.31567 -304.083466)
		(width 0.16002)
		(layer "In13.Cu")
		(net "M_H_CPU0_SB_DQS_DP<7>")
	)
	(segment
		(start 395.414246 -287.505902)
		(end 395.628622 -287.720532)
		(width 0.09525)
		(layer "In13.Cu")
		(net "M_H_CPU0_SB_DQS_DP<7>")
	)
	(segment
		(start 406.28062 -302.392334)
		(end 406.599644 -302.711358)
		(width 0.16002)
		(layer "In13.Cu")
		(net "M_H_CPU0_SB_DQS_DP<7>")
	)
	(segment
		(start 406.38476 -303.62906)
		(end 406.839166 -304.083466)
		(width 0.16002)
		(layer "In13.Cu")
		(net "M_H_CPU0_SB_DQS_DP<7>")
	)
	(arc
		(start 384.73634 -286.720788)
		(mid 384.924808 -286.670111)
		(end 385.113276 -286.720788)
		(width 0.09525)
		(layer "In13.Cu")
		(net "M_H_CPU0_SB_DQS_DP<7>")
	)
	(arc
		(start 392.256518 -286.720534)
		(mid 392.347636 -286.682547)
		(end 392.445494 -286.66948)
		(width 0.09525)
		(layer "In13.Cu")
		(net "M_H_CPU0_SB_DQS_DP<7>")
	)
	(arc
		(start 388.504684 -286.715962)
		(mid 388.689716 -286.670048)
		(end 388.873492 -286.720788)
		(width 0.09525)
		(layer "In13.Cu")
		(net "M_H_CPU0_SB_DQS_DP<7>")
	)
	(arc
		(start 382.914144 -286.69361)
		(mid 383.076826 -286.671478)
		(end 383.233422 -286.720788)
		(width 0.09525)
		(layer "In13.Cu")
		(net "M_H_CPU0_SB_DQS_DP<7>")
	)
	(arc
		(start 384.173476 -286.720788)
		(mid 384.454908 -286.796577)
		(end 384.73634 -286.720788)
		(width 0.09525)
		(layer "In13.Cu")
		(net "M_H_CPU0_SB_DQS_DP<7>")
	)
	(arc
		(start 387.56463 -286.715962)
		(mid 387.749662 -286.670048)
		(end 387.933438 -286.720788)
		(width 0.09525)
		(layer "In13.Cu")
		(net "M_H_CPU0_SB_DQS_DP<7>")
	)
	(arc
		(start 390.376156 -286.720788)
		(mid 390.559931 -286.670016)
		(end 390.744964 -286.715962)
		(width 0.09525)
		(layer "In13.Cu")
		(net "M_H_CPU0_SB_DQS_DP<7>")
	)
	(arc
		(start 386.993384 -286.720788)
		(mid 387.274816 -286.796577)
		(end 387.556248 -286.720788)
		(width 0.09525)
		(layer "In13.Cu")
		(net "M_H_CPU0_SB_DQS_DP<7>")
	)
	(arc
		(start 385.113276 -286.720788)
		(mid 385.394708 -286.796577)
		(end 385.67614 -286.720788)
		(width 0.09525)
		(layer "In13.Cu")
		(net "M_H_CPU0_SB_DQS_DP<7>")
	)
	(arc
		(start 389.436356 -286.720788)
		(mid 389.624824 -286.670111)
		(end 389.813292 -286.720788)
		(width 0.09525)
		(layer "In13.Cu")
		(net "M_H_CPU0_SB_DQS_DP<7>")
	)
	(arc
		(start 386.616194 -286.720788)
		(mid 386.799969 -286.670016)
		(end 386.985002 -286.715962)
		(width 0.09525)
		(layer "In13.Cu")
		(net "M_H_CPU0_SB_DQS_DP<7>")
	)
	(arc
		(start 388.873492 -286.720788)
		(mid 389.154924 -286.796577)
		(end 389.436356 -286.720788)
		(width 0.09525)
		(layer "In13.Cu")
		(net "M_H_CPU0_SB_DQS_DP<7>")
	)
	(arc
		(start 390.753346 -286.720788)
		(mid 391.034778 -286.796577)
		(end 391.31621 -286.720788)
		(width 0.09525)
		(layer "In13.Cu")
		(net "M_H_CPU0_SB_DQS_DP<7>")
	)
	(arc
		(start 383.233422 -286.720788)
		(mid 383.514854 -286.796577)
		(end 383.796286 -286.720788)
		(width 0.09525)
		(layer "In13.Cu")
		(net "M_H_CPU0_SB_DQS_DP<7>")
	)
	(arc
		(start 389.813292 -286.720788)
		(mid 390.094724 -286.796577)
		(end 390.376156 -286.720788)
		(width 0.09525)
		(layer "In13.Cu")
		(net "M_H_CPU0_SB_DQS_DP<7>")
	)
	(arc
		(start 383.804668 -286.715962)
		(mid 383.9897 -286.670048)
		(end 384.173476 -286.720788)
		(width 0.09525)
		(layer "In13.Cu")
		(net "M_H_CPU0_SB_DQS_DP<7>")
	)
	(arc
		(start 391.324592 -286.715962)
		(mid 391.509624 -286.670048)
		(end 391.6934 -286.720788)
		(width 0.09525)
		(layer "In13.Cu")
		(net "M_H_CPU0_SB_DQS_DP<7>")
	)
	(arc
		(start 391.703814 -286.726884)
		(mid 391.980976 -286.796716)
		(end 392.256518 -286.720788)
		(width 0.09525)
		(layer "In13.Cu")
		(net "M_H_CPU0_SB_DQS_DP<7>")
	)
	(arc
		(start 385.67614 -286.720788)
		(mid 385.859915 -286.670016)
		(end 386.044948 -286.715962)
		(width 0.09525)
		(layer "In13.Cu")
		(net "M_H_CPU0_SB_DQS_DP<7>")
	)
	(arc
		(start 386.05333 -286.720788)
		(mid 386.334762 -286.796577)
		(end 386.616194 -286.720788)
		(width 0.09525)
		(layer "In13.Cu")
		(net "M_H_CPU0_SB_DQS_DP<7>")
	)
	(arc
		(start 387.933438 -286.720788)
		(mid 388.21487 -286.796577)
		(end 388.496302 -286.720788)
		(width 0.09525)
		(layer "In13.Cu")
		(net "M_H_CPU0_SB_DQS_DP<7>")
	)
	(segment
		(start 382.577848 -281.920188)
		(end 383.0447 -282.186126)
		(width 0.12954)
		(layer "F.Cu")
		(net "M_H_CPU0_SB_DQS_DP<6>")
	)
	(segment
		(start 393.557506 -281.80919)
		(end 393.38504 -281.80919)
		(width 0.09525)
		(layer "In13.Cu")
		(net "M_H_CPU0_SB_DQS_DP<6>")
	)
	(segment
		(start 393.55776 -281.809444)
		(end 393.557506 -281.80919)
		(width 0.09525)
		(layer "In13.Cu")
		(net "M_H_CPU0_SB_DQS_DP<6>")
	)
	(segment
		(start 407.642822 -292.650164)
		(end 406.926034 -293.366952)
		(width 0.16002)
		(layer "In13.Cu")
		(net "M_H_CPU0_SB_DQS_DP<6>")
	)
	(segment
		(start 417.883848 -295.668954)
		(end 417.659058 -295.444164)
		(width 0.16002)
		(layer "In13.Cu")
		(net "M_H_CPU0_SB_DQS_DP<6>")
	)
	(segment
		(start 406.449276 -293.366952)
		(end 406.112218 -293.029894)
		(width 0.16002)
		(layer "In13.Cu")
		(net "M_H_CPU0_SB_DQS_DP<6>")
	)
	(segment
		(start 409.327858 -296.651426)
		(end 407.26741 -294.590978)
		(width 0.16002)
		(layer "In13.Cu")
		(net "M_H_CPU0_SB_DQS_DP<6>")
	)
	(segment
		(start 408.187144 -293.194486)
		(end 408.187144 -292.968426)
		(width 0.16002)
		(layer "In13.Cu")
		(net "M_H_CPU0_SB_DQS_DP<6>")
	)
	(segment
		(start 411.514036 -295.788588)
		(end 411.354016 -295.948608)
		(width 0.16002)
		(layer "In13.Cu")
		(net "M_H_CPU0_SB_DQS_DP<6>")
	)
	(segment
		(start 408.187144 -292.968426)
		(end 407.868882 -292.650164)
		(width 0.16002)
		(layer "In13.Cu")
		(net "M_H_CPU0_SB_DQS_DP<6>")
	)
	(segment
		(start 392.263884 -281.85618)
		(end 392.255502 -281.861006)
		(width 0.09525)
		(layer "In13.Cu")
		(net "M_H_CPU0_SB_DQS_DP<6>")
	)
	(segment
		(start 406.112218 -293.029894)
		(end 406.112218 -290.424616)
		(width 0.16002)
		(layer "In13.Cu")
		(net "M_H_CPU0_SB_DQS_DP<6>")
	)
	(segment
		(start 417.659058 -295.444164)
		(end 414.854898 -295.444164)
		(width 0.16002)
		(layer "In13.Cu")
		(net "M_H_CPU0_SB_DQS_DP<6>")
	)
	(segment
		(start 414.854898 -295.444164)
		(end 414.001458 -296.297604)
		(width 0.16002)
		(layer "In13.Cu")
		(net "M_H_CPU0_SB_DQS_DP<6>")
	)
	(segment
		(start 382.890776 -281.920696)
		(end 383.0447 -282.186126)
		(width 0.09525)
		(layer "In13.Cu")
		(net "M_H_CPU0_SB_DQS_DP<6>")
	)
	(segment
		(start 395.58976 -282.12034)
		(end 395.530832 -282.061412)
		(width 0.09525)
		(layer "In13.Cu")
		(net "M_H_CPU0_SB_DQS_DP<6>")
	)
	(segment
		(start 392.650218 -281.87142)
		(end 392.632184 -281.861006)
		(width 0.09525)
		(layer "In13.Cu")
		(net "M_H_CPU0_SB_DQS_DP<6>")
	)
	(segment
		(start 412.460694 -296.651426)
		(end 412.123636 -296.314368)
		(width 0.16002)
		(layer "In13.Cu")
		(net "M_H_CPU0_SB_DQS_DP<6>")
	)
	(segment
		(start 407.26741 -294.590978)
		(end 407.26741 -294.11422)
		(width 0.16002)
		(layer "In13.Cu")
		(net "M_H_CPU0_SB_DQS_DP<6>")
	)
	(segment
		(start 397.807942 -282.12034)
		(end 395.613382 -282.12034)
		(width 0.16002)
		(layer "In13.Cu")
		(net "M_H_CPU0_SB_DQS_DP<6>")
	)
	(segment
		(start 406.926034 -293.366952)
		(end 406.449276 -293.366952)
		(width 0.16002)
		(layer "In13.Cu")
		(net "M_H_CPU0_SB_DQS_DP<6>")
	)
	(segment
		(start 411.354016 -295.948608)
		(end 411.354016 -296.314368)
		(width 0.16002)
		(layer "In13.Cu")
		(net "M_H_CPU0_SB_DQS_DP<6>")
	)
	(segment
		(start 407.868882 -292.650164)
		(end 407.642822 -292.650164)
		(width 0.16002)
		(layer "In13.Cu")
		(net "M_H_CPU0_SB_DQS_DP<6>")
	)
	(segment
		(start 406.112218 -290.424616)
		(end 397.807942 -282.12034)
		(width 0.16002)
		(layer "In13.Cu")
		(net "M_H_CPU0_SB_DQS_DP<6>")
	)
	(segment
		(start 386.993384 -281.861006)
		(end 386.985002 -281.85618)
		(width 0.09525)
		(layer "In13.Cu")
		(net "M_H_CPU0_SB_DQS_DP<6>")
	)
	(segment
		(start 419.912038 -295.935146)
		(end 419.645846 -295.668954)
		(width 0.16002)
		(layer "In13.Cu")
		(net "M_H_CPU0_SB_DQS_DP<6>")
	)
	(segment
		(start 412.123636 -295.948608)
		(end 411.963616 -295.788588)
		(width 0.16002)
		(layer "In13.Cu")
		(net "M_H_CPU0_SB_DQS_DP<6>")
	)
	(segment
		(start 388.504684 -281.85618)
		(end 388.496302 -281.861006)
		(width 0.09525)
		(layer "In13.Cu")
		(net "M_H_CPU0_SB_DQS_DP<6>")
	)
	(segment
		(start 394.75664 -282.061412)
		(end 394.540994 -281.845766)
		(width 0.09525)
		(layer "In13.Cu")
		(net "M_H_CPU0_SB_DQS_DP<6>")
	)
	(segment
		(start 391.324592 -281.85618)
		(end 391.31621 -281.861006)
		(width 0.09525)
		(layer "In13.Cu")
		(net "M_H_CPU0_SB_DQS_DP<6>")
	)
	(segment
		(start 394.425932 -281.809444)
		(end 393.55776 -281.809444)
		(width 0.09525)
		(layer "In13.Cu")
		(net "M_H_CPU0_SB_DQS_DP<6>")
	)
	(segment
		(start 392.255502 -281.861006)
		(end 392.237468 -281.87142)
		(width 0.09525)
		(layer "In13.Cu")
		(net "M_H_CPU0_SB_DQS_DP<6>")
	)
	(segment
		(start 382.914144 -281.833828)
		(end 382.890776 -281.920696)
		(width 0.09525)
		(layer "In13.Cu")
		(net "M_H_CPU0_SB_DQS_DP<6>")
	)
	(segment
		(start 413.500824 -296.297604)
		(end 413.147002 -296.651426)
		(width 0.16002)
		(layer "In13.Cu")
		(net "M_H_CPU0_SB_DQS_DP<6>")
	)
	(segment
		(start 407.26741 -294.11422)
		(end 408.187144 -293.194486)
		(width 0.16002)
		(layer "In13.Cu")
		(net "M_H_CPU0_SB_DQS_DP<6>")
	)
	(segment
		(start 395.613382 -282.12034)
		(end 395.58976 -282.12034)
		(width 0.09525)
		(layer "In13.Cu")
		(net "M_H_CPU0_SB_DQS_DP<6>")
	)
	(segment
		(start 411.963616 -295.788588)
		(end 411.514036 -295.788588)
		(width 0.16002)
		(layer "In13.Cu")
		(net "M_H_CPU0_SB_DQS_DP<6>")
	)
	(segment
		(start 395.530832 -282.061412)
		(end 394.75664 -282.061412)
		(width 0.09525)
		(layer "In13.Cu")
		(net "M_H_CPU0_SB_DQS_DP<6>")
	)
	(segment
		(start 413.147002 -296.651426)
		(end 412.460694 -296.651426)
		(width 0.16002)
		(layer "In13.Cu")
		(net "M_H_CPU0_SB_DQS_DP<6>")
	)
	(segment
		(start 414.001458 -296.297604)
		(end 413.500824 -296.297604)
		(width 0.16002)
		(layer "In13.Cu")
		(net "M_H_CPU0_SB_DQS_DP<6>")
	)
	(segment
		(start 419.645846 -295.668954)
		(end 417.883848 -295.668954)
		(width 0.16002)
		(layer "In13.Cu")
		(net "M_H_CPU0_SB_DQS_DP<6>")
	)
	(segment
		(start 411.016958 -296.651426)
		(end 409.327858 -296.651426)
		(width 0.16002)
		(layer "In13.Cu")
		(net "M_H_CPU0_SB_DQS_DP<6>")
	)
	(segment
		(start 411.354016 -296.314368)
		(end 411.016958 -296.651426)
		(width 0.16002)
		(layer "In13.Cu")
		(net "M_H_CPU0_SB_DQS_DP<6>")
	)
	(segment
		(start 383.804668 -281.85618)
		(end 383.796286 -281.861006)
		(width 0.09525)
		(layer "In13.Cu")
		(net "M_H_CPU0_SB_DQS_DP<6>")
	)
	(segment
		(start 412.123636 -296.314368)
		(end 412.123636 -295.948608)
		(width 0.16002)
		(layer "In13.Cu")
		(net "M_H_CPU0_SB_DQS_DP<6>")
	)
	(segment
		(start 390.753346 -281.861006)
		(end 390.744964 -281.85618)
		(width 0.09525)
		(layer "In13.Cu")
		(net "M_H_CPU0_SB_DQS_DP<6>")
	)
	(segment
		(start 387.56463 -281.85618)
		(end 387.556248 -281.861006)
		(width 0.09525)
		(layer "In13.Cu")
		(net "M_H_CPU0_SB_DQS_DP<6>")
	)
	(segment
		(start 386.05333 -281.861006)
		(end 386.044948 -281.85618)
		(width 0.09525)
		(layer "In13.Cu")
		(net "M_H_CPU0_SB_DQS_DP<6>")
	)
	(arc
		(start 389.436356 -281.861006)
		(mid 389.154924 -281.936761)
		(end 388.873492 -281.861006)
		(width 0.09525)
		(layer "In13.Cu")
		(net "M_H_CPU0_SB_DQS_DP<6>")
	)
	(arc
		(start 386.616194 -281.861006)
		(mid 386.334762 -281.936761)
		(end 386.05333 -281.861006)
		(width 0.09525)
		(layer "In13.Cu")
		(net "M_H_CPU0_SB_DQS_DP<6>")
	)
	(arc
		(start 383.233422 -281.861006)
		(mid 383.076824 -281.811717)
		(end 382.914144 -281.833828)
		(width 0.09525)
		(layer "In13.Cu")
		(net "M_H_CPU0_SB_DQS_DP<6>")
	)
	(arc
		(start 391.31621 -281.861006)
		(mid 391.034778 -281.936761)
		(end 390.753346 -281.861006)
		(width 0.09525)
		(layer "In13.Cu")
		(net "M_H_CPU0_SB_DQS_DP<6>")
	)
	(arc
		(start 388.873492 -281.861006)
		(mid 388.689717 -281.810234)
		(end 388.504684 -281.85618)
		(width 0.09525)
		(layer "In13.Cu")
		(net "M_H_CPU0_SB_DQS_DP<6>")
	)
	(arc
		(start 385.67614 -281.861006)
		(mid 385.394708 -281.936761)
		(end 385.113276 -281.861006)
		(width 0.09525)
		(layer "In13.Cu")
		(net "M_H_CPU0_SB_DQS_DP<6>")
	)
	(arc
		(start 384.73634 -281.861006)
		(mid 384.454908 -281.936761)
		(end 384.173476 -281.861006)
		(width 0.09525)
		(layer "In13.Cu")
		(net "M_H_CPU0_SB_DQS_DP<6>")
	)
	(arc
		(start 387.556248 -281.861006)
		(mid 387.274816 -281.936761)
		(end 386.993384 -281.861006)
		(width 0.09525)
		(layer "In13.Cu")
		(net "M_H_CPU0_SB_DQS_DP<6>")
	)
	(arc
		(start 392.237468 -281.87142)
		(mid 391.964088 -281.936641)
		(end 391.6934 -281.861006)
		(width 0.09525)
		(layer "In13.Cu")
		(net "M_H_CPU0_SB_DQS_DP<6>")
	)
	(arc
		(start 393.19581 -281.861006)
		(mid 392.92436 -281.937041)
		(end 392.650218 -281.87142)
		(width 0.09525)
		(layer "In13.Cu")
		(net "M_H_CPU0_SB_DQS_DP<6>")
	)
	(arc
		(start 391.6934 -281.861006)
		(mid 391.509625 -281.810234)
		(end 391.324592 -281.85618)
		(width 0.09525)
		(layer "In13.Cu")
		(net "M_H_CPU0_SB_DQS_DP<6>")
	)
	(arc
		(start 383.796286 -281.861006)
		(mid 383.514854 -281.936761)
		(end 383.233422 -281.861006)
		(width 0.09525)
		(layer "In13.Cu")
		(net "M_H_CPU0_SB_DQS_DP<6>")
	)
	(arc
		(start 386.985002 -281.85618)
		(mid 386.79997 -281.810266)
		(end 386.616194 -281.861006)
		(width 0.09525)
		(layer "In13.Cu")
		(net "M_H_CPU0_SB_DQS_DP<6>")
	)
	(arc
		(start 384.173476 -281.861006)
		(mid 383.989701 -281.810234)
		(end 383.804668 -281.85618)
		(width 0.09525)
		(layer "In13.Cu")
		(net "M_H_CPU0_SB_DQS_DP<6>")
	)
	(arc
		(start 394.540994 -281.845766)
		(mid 394.486247 -281.818769)
		(end 394.425932 -281.809444)
		(width 0.09525)
		(layer "In13.Cu")
		(net "M_H_CPU0_SB_DQS_DP<6>")
	)
	(arc
		(start 388.496302 -281.861006)
		(mid 388.21487 -281.936761)
		(end 387.933438 -281.861006)
		(width 0.09525)
		(layer "In13.Cu")
		(net "M_H_CPU0_SB_DQS_DP<6>")
	)
	(arc
		(start 393.38504 -281.80919)
		(mid 393.28698 -281.82253)
		(end 393.19581 -281.861006)
		(width 0.09525)
		(layer "In13.Cu")
		(net "M_H_CPU0_SB_DQS_DP<6>")
	)
	(arc
		(start 392.632184 -281.861006)
		(mid 392.448663 -281.810362)
		(end 392.263884 -281.85618)
		(width 0.09525)
		(layer "In13.Cu")
		(net "M_H_CPU0_SB_DQS_DP<6>")
	)
	(arc
		(start 387.933438 -281.861006)
		(mid 387.749663 -281.810234)
		(end 387.56463 -281.85618)
		(width 0.09525)
		(layer "In13.Cu")
		(net "M_H_CPU0_SB_DQS_DP<6>")
	)
	(arc
		(start 390.376156 -281.861006)
		(mid 390.094724 -281.936761)
		(end 389.813292 -281.861006)
		(width 0.09525)
		(layer "In13.Cu")
		(net "M_H_CPU0_SB_DQS_DP<6>")
	)
	(arc
		(start 386.044948 -281.85618)
		(mid 385.859916 -281.810266)
		(end 385.67614 -281.861006)
		(width 0.09525)
		(layer "In13.Cu")
		(net "M_H_CPU0_SB_DQS_DP<6>")
	)
	(arc
		(start 390.744964 -281.85618)
		(mid 390.559932 -281.810266)
		(end 390.376156 -281.861006)
		(width 0.09525)
		(layer "In13.Cu")
		(net "M_H_CPU0_SB_DQS_DP<6>")
	)
	(arc
		(start 389.813292 -281.861006)
		(mid 389.624824 -281.810329)
		(end 389.436356 -281.861006)
		(width 0.09525)
		(layer "In13.Cu")
		(net "M_H_CPU0_SB_DQS_DP<6>")
	)
	(arc
		(start 385.113276 -281.861006)
		(mid 384.924808 -281.810329)
		(end 384.73634 -281.861006)
		(width 0.09525)
		(layer "In13.Cu")
		(net "M_H_CPU0_SB_DQS_DP<6>")
	)
	(segment
		(start 382.577848 -277.060152)
		(end 383.0447 -277.32609)
		(width 0.12954)
		(layer "F.Cu")
		(net "M_H_CPU0_SB_DQS_DP<5>")
	)
	(segment
		(start 410.838142 -285.835852)
		(end 410.348938 -285.346648)
		(width 0.16002)
		(layer "In13.Cu")
		(net "M_H_CPU0_SB_DQS_DP<5>")
	)
	(segment
		(start 405.772112 -280.78557)
		(end 405.546052 -280.78557)
		(width 0.16002)
		(layer "In13.Cu")
		(net "M_H_CPU0_SB_DQS_DP<5>")
	)
	(segment
		(start 414.854898 -286.09417)
		(end 414.001458 -286.94761)
		(width 0.16002)
		(layer "In13.Cu")
		(net "M_H_CPU0_SB_DQS_DP<5>")
	)
	(segment
		(start 407.06294 -282.302458)
		(end 406.929336 -282.436062)
		(width 0.16002)
		(layer "In13.Cu")
		(net "M_H_CPU0_SB_DQS_DP<5>")
	)
	(segment
		(start 409.363418 -285.346648)
		(end 408.991308 -284.974538)
		(width 0.16002)
		(layer "In13.Cu")
		(net "M_H_CPU0_SB_DQS_DP<5>")
	)
	(segment
		(start 382.890776 -277.06066)
		(end 383.0447 -277.32609)
		(width 0.09525)
		(layer "In13.Cu")
		(net "M_H_CPU0_SB_DQS_DP<5>")
	)
	(segment
		(start 408.579828 -283.819346)
		(end 408.446224 -283.95295)
		(width 0.16002)
		(layer "In13.Cu")
		(net "M_H_CPU0_SB_DQS_DP<5>")
	)
	(segment
		(start 404.029164 -279.268682)
		(end 403.89556 -279.402286)
		(width 0.16002)
		(layer "In13.Cu")
		(net "M_H_CPU0_SB_DQS_DP<5>")
	)
	(segment
		(start 382.914144 -276.973792)
		(end 382.890776 -277.06066)
		(width 0.09525)
		(layer "In13.Cu")
		(net "M_H_CPU0_SB_DQS_DP<5>")
	)
	(segment
		(start 408.446224 -283.95295)
		(end 407.96972 -283.95295)
		(width 0.16002)
		(layer "In13.Cu")
		(net "M_H_CPU0_SB_DQS_DP<5>")
	)
	(segment
		(start 388.504684 -276.996144)
		(end 388.496302 -277.00097)
		(width 0.09525)
		(layer "In13.Cu")
		(net "M_H_CPU0_SB_DQS_DP<5>")
	)
	(segment
		(start 395.71168 -276.036278)
		(end 395.408404 -276.036278)
		(width 0.09525)
		(layer "In13.Cu")
		(net "M_H_CPU0_SB_DQS_DP<5>")
	)
	(segment
		(start 403.419056 -279.402286)
		(end 400.111976 -276.095206)
		(width 0.16002)
		(layer "In13.Cu")
		(net "M_H_CPU0_SB_DQS_DP<5>")
	)
	(segment
		(start 414.001458 -286.94761)
		(end 412.808928 -286.94761)
		(width 0.16002)
		(layer "In13.Cu")
		(net "M_H_CPU0_SB_DQS_DP<5>")
	)
	(segment
		(start 395.79423 -276.095206)
		(end 395.770608 -276.095206)
		(width 0.09525)
		(layer "In13.Cu")
		(net "M_H_CPU0_SB_DQS_DP<5>")
	)
	(segment
		(start 419.62578 -286.298894)
		(end 418.069014 -286.298894)
		(width 0.16002)
		(layer "In13.Cu")
		(net "M_H_CPU0_SB_DQS_DP<5>")
	)
	(segment
		(start 404.440644 -279.94737)
		(end 404.574248 -279.813766)
		(width 0.16002)
		(layer "In13.Cu")
		(net "M_H_CPU0_SB_DQS_DP<5>")
	)
	(segment
		(start 393.728702 -276.710902)
		(end 393.300712 -276.958044)
		(width 0.09525)
		(layer "In13.Cu")
		(net "M_H_CPU0_SB_DQS_DP<5>")
	)
	(segment
		(start 405.412448 -280.919174)
		(end 404.935944 -280.919174)
		(width 0.16002)
		(layer "In13.Cu")
		(net "M_H_CPU0_SB_DQS_DP<5>")
	)
	(segment
		(start 417.86429 -286.09417)
		(end 414.854898 -286.09417)
		(width 0.16002)
		(layer "In13.Cu")
		(net "M_H_CPU0_SB_DQS_DP<5>")
	)
	(segment
		(start 404.574248 -279.587706)
		(end 404.255224 -279.268682)
		(width 0.16002)
		(layer "In13.Cu")
		(net "M_H_CPU0_SB_DQS_DP<5>")
	)
	(segment
		(start 390.753346 -277.00097)
		(end 390.744964 -276.996144)
		(width 0.09525)
		(layer "In13.Cu")
		(net "M_H_CPU0_SB_DQS_DP<5>")
	)
	(segment
		(start 409.124912 -284.13837)
		(end 408.805888 -283.819346)
		(width 0.16002)
		(layer "In13.Cu")
		(net "M_H_CPU0_SB_DQS_DP<5>")
	)
	(segment
		(start 409.124912 -284.36443)
		(end 409.124912 -284.13837)
		(width 0.16002)
		(layer "In13.Cu")
		(net "M_H_CPU0_SB_DQS_DP<5>")
	)
	(segment
		(start 405.957532 -281.464258)
		(end 406.091136 -281.330654)
		(width 0.16002)
		(layer "In13.Cu")
		(net "M_H_CPU0_SB_DQS_DP<5>")
	)
	(segment
		(start 387.56463 -276.996144)
		(end 387.556248 -277.00097)
		(width 0.09525)
		(layer "In13.Cu")
		(net "M_H_CPU0_SB_DQS_DP<5>")
	)
	(segment
		(start 408.991308 -284.974538)
		(end 408.991308 -284.498034)
		(width 0.16002)
		(layer "In13.Cu")
		(net "M_H_CPU0_SB_DQS_DP<5>")
	)
	(segment
		(start 395.770608 -276.095206)
		(end 395.71168 -276.036278)
		(width 0.09525)
		(layer "In13.Cu")
		(net "M_H_CPU0_SB_DQS_DP<5>")
	)
	(segment
		(start 419.912038 -286.585152)
		(end 419.62578 -286.298894)
		(width 0.16002)
		(layer "In13.Cu")
		(net "M_H_CPU0_SB_DQS_DP<5>")
	)
	(segment
		(start 406.091136 -281.330654)
		(end 406.091136 -281.104594)
		(width 0.16002)
		(layer "In13.Cu")
		(net "M_H_CPU0_SB_DQS_DP<5>")
	)
	(segment
		(start 407.608024 -282.847542)
		(end 407.608024 -282.621482)
		(width 0.16002)
		(layer "In13.Cu")
		(net "M_H_CPU0_SB_DQS_DP<5>")
	)
	(segment
		(start 392.650218 -277.011384)
		(end 392.632184 -277.00097)
		(width 0.09525)
		(layer "In13.Cu")
		(net "M_H_CPU0_SB_DQS_DP<5>")
	)
	(segment
		(start 392.263884 -276.996144)
		(end 392.255502 -277.00097)
		(width 0.09525)
		(layer "In13.Cu")
		(net "M_H_CPU0_SB_DQS_DP<5>")
	)
	(segment
		(start 408.805888 -283.819346)
		(end 408.579828 -283.819346)
		(width 0.16002)
		(layer "In13.Cu")
		(net "M_H_CPU0_SB_DQS_DP<5>")
	)
	(segment
		(start 386.05333 -277.00097)
		(end 386.044948 -276.996144)
		(width 0.09525)
		(layer "In13.Cu")
		(net "M_H_CPU0_SB_DQS_DP<5>")
	)
	(segment
		(start 407.96972 -283.95295)
		(end 407.47442 -283.45765)
		(width 0.16002)
		(layer "In13.Cu")
		(net "M_H_CPU0_SB_DQS_DP<5>")
	)
	(segment
		(start 418.069014 -286.298894)
		(end 417.86429 -286.09417)
		(width 0.16002)
		(layer "In13.Cu")
		(net "M_H_CPU0_SB_DQS_DP<5>")
	)
	(segment
		(start 391.324592 -276.996144)
		(end 391.31621 -277.00097)
		(width 0.09525)
		(layer "In13.Cu")
		(net "M_H_CPU0_SB_DQS_DP<5>")
	)
	(segment
		(start 400.111976 -276.095206)
		(end 395.79423 -276.095206)
		(width 0.16002)
		(layer "In13.Cu")
		(net "M_H_CPU0_SB_DQS_DP<5>")
	)
	(segment
		(start 404.255224 -279.268682)
		(end 404.029164 -279.268682)
		(width 0.16002)
		(layer "In13.Cu")
		(net "M_H_CPU0_SB_DQS_DP<5>")
	)
	(segment
		(start 407.289 -282.302458)
		(end 407.06294 -282.302458)
		(width 0.16002)
		(layer "In13.Cu")
		(net "M_H_CPU0_SB_DQS_DP<5>")
	)
	(segment
		(start 394.72108 -275.86178)
		(end 394.234416 -276.348444)
		(width 0.09525)
		(layer "In13.Cu")
		(net "M_H_CPU0_SB_DQS_DP<5>")
	)
	(segment
		(start 408.991308 -284.498034)
		(end 409.124912 -284.36443)
		(width 0.16002)
		(layer "In13.Cu")
		(net "M_H_CPU0_SB_DQS_DP<5>")
	)
	(segment
		(start 395.408404 -276.036278)
		(end 395.233906 -275.86178)
		(width 0.09525)
		(layer "In13.Cu")
		(net "M_H_CPU0_SB_DQS_DP<5>")
	)
	(segment
		(start 412.808928 -286.94761)
		(end 411.69717 -285.835852)
		(width 0.16002)
		(layer "In13.Cu")
		(net "M_H_CPU0_SB_DQS_DP<5>")
	)
	(segment
		(start 404.574248 -279.813766)
		(end 404.574248 -279.587706)
		(width 0.16002)
		(layer "In13.Cu")
		(net "M_H_CPU0_SB_DQS_DP<5>")
	)
	(segment
		(start 407.608024 -282.621482)
		(end 407.289 -282.302458)
		(width 0.16002)
		(layer "In13.Cu")
		(net "M_H_CPU0_SB_DQS_DP<5>")
	)
	(segment
		(start 406.929336 -282.436062)
		(end 406.452832 -282.436062)
		(width 0.16002)
		(layer "In13.Cu")
		(net "M_H_CPU0_SB_DQS_DP<5>")
	)
	(segment
		(start 404.935944 -280.919174)
		(end 404.440644 -280.423874)
		(width 0.16002)
		(layer "In13.Cu")
		(net "M_H_CPU0_SB_DQS_DP<5>")
	)
	(segment
		(start 406.452832 -282.436062)
		(end 405.957532 -281.940762)
		(width 0.16002)
		(layer "In13.Cu")
		(net "M_H_CPU0_SB_DQS_DP<5>")
	)
	(segment
		(start 404.440644 -280.423874)
		(end 404.440644 -279.94737)
		(width 0.16002)
		(layer "In13.Cu")
		(net "M_H_CPU0_SB_DQS_DP<5>")
	)
	(segment
		(start 392.255502 -277.00097)
		(end 392.237468 -277.011384)
		(width 0.09525)
		(layer "In13.Cu")
		(net "M_H_CPU0_SB_DQS_DP<5>")
	)
	(segment
		(start 407.47442 -283.45765)
		(end 407.47442 -282.981146)
		(width 0.16002)
		(layer "In13.Cu")
		(net "M_H_CPU0_SB_DQS_DP<5>")
	)
	(segment
		(start 395.233906 -275.86178)
		(end 394.72108 -275.86178)
		(width 0.09525)
		(layer "In13.Cu")
		(net "M_H_CPU0_SB_DQS_DP<5>")
	)
	(segment
		(start 411.69717 -285.835852)
		(end 410.838142 -285.835852)
		(width 0.16002)
		(layer "In13.Cu")
		(net "M_H_CPU0_SB_DQS_DP<5>")
	)
	(segment
		(start 386.993384 -277.00097)
		(end 386.985002 -276.996144)
		(width 0.09525)
		(layer "In13.Cu")
		(net "M_H_CPU0_SB_DQS_DP<5>")
	)
	(segment
		(start 410.348938 -285.346648)
		(end 409.363418 -285.346648)
		(width 0.16002)
		(layer "In13.Cu")
		(net "M_H_CPU0_SB_DQS_DP<5>")
	)
	(segment
		(start 383.804668 -276.996144)
		(end 383.796286 -277.00097)
		(width 0.09525)
		(layer "In13.Cu")
		(net "M_H_CPU0_SB_DQS_DP<5>")
	)
	(segment
		(start 406.091136 -281.104594)
		(end 405.772112 -280.78557)
		(width 0.16002)
		(layer "In13.Cu")
		(net "M_H_CPU0_SB_DQS_DP<5>")
	)
	(segment
		(start 393.300712 -276.958044)
		(end 393.27963 -276.964394)
		(width 0.09525)
		(layer "In13.Cu")
		(net "M_H_CPU0_SB_DQS_DP<5>")
	)
	(segment
		(start 393.737592 -276.706584)
		(end 393.728702 -276.710902)
		(width 0.09525)
		(layer "In13.Cu")
		(net "M_H_CPU0_SB_DQS_DP<5>")
	)
	(segment
		(start 407.47442 -282.981146)
		(end 407.608024 -282.847542)
		(width 0.16002)
		(layer "In13.Cu")
		(net "M_H_CPU0_SB_DQS_DP<5>")
	)
	(segment
		(start 405.957532 -281.940762)
		(end 405.957532 -281.464258)
		(width 0.16002)
		(layer "In13.Cu")
		(net "M_H_CPU0_SB_DQS_DP<5>")
	)
	(segment
		(start 403.89556 -279.402286)
		(end 403.419056 -279.402286)
		(width 0.16002)
		(layer "In13.Cu")
		(net "M_H_CPU0_SB_DQS_DP<5>")
	)
	(segment
		(start 405.546052 -280.78557)
		(end 405.412448 -280.919174)
		(width 0.16002)
		(layer "In13.Cu")
		(net "M_H_CPU0_SB_DQS_DP<5>")
	)
	(arc
		(start 384.173476 -277.00097)
		(mid 383.989701 -276.950198)
		(end 383.804668 -276.996144)
		(width 0.09525)
		(layer "In13.Cu")
		(net "M_H_CPU0_SB_DQS_DP<5>")
	)
	(arc
		(start 390.744964 -276.996144)
		(mid 390.559932 -276.95023)
		(end 390.376156 -277.00097)
		(width 0.09525)
		(layer "In13.Cu")
		(net "M_H_CPU0_SB_DQS_DP<5>")
	)
	(arc
		(start 390.376156 -277.00097)
		(mid 390.094724 -277.076725)
		(end 389.813292 -277.00097)
		(width 0.09525)
		(layer "In13.Cu")
		(net "M_H_CPU0_SB_DQS_DP<5>")
	)
	(arc
		(start 391.31621 -277.00097)
		(mid 391.034778 -277.076725)
		(end 390.753346 -277.00097)
		(width 0.09525)
		(layer "In13.Cu")
		(net "M_H_CPU0_SB_DQS_DP<5>")
	)
	(arc
		(start 386.044948 -276.996144)
		(mid 385.859916 -276.95023)
		(end 385.67614 -277.00097)
		(width 0.09525)
		(layer "In13.Cu")
		(net "M_H_CPU0_SB_DQS_DP<5>")
	)
	(arc
		(start 386.616194 -277.00097)
		(mid 386.334762 -277.076725)
		(end 386.05333 -277.00097)
		(width 0.09525)
		(layer "In13.Cu")
		(net "M_H_CPU0_SB_DQS_DP<5>")
	)
	(arc
		(start 384.73634 -277.00097)
		(mid 384.454908 -277.076725)
		(end 384.173476 -277.00097)
		(width 0.09525)
		(layer "In13.Cu")
		(net "M_H_CPU0_SB_DQS_DP<5>")
	)
	(arc
		(start 393.27963 -276.964394)
		(mid 393.23651 -276.979756)
		(end 393.195556 -277.000208)
		(width 0.09525)
		(layer "In13.Cu")
		(net "M_H_CPU0_SB_DQS_DP<5>")
	)
	(arc
		(start 385.113276 -277.00097)
		(mid 384.924808 -276.950293)
		(end 384.73634 -277.00097)
		(width 0.09525)
		(layer "In13.Cu")
		(net "M_H_CPU0_SB_DQS_DP<5>")
	)
	(arc
		(start 391.6934 -277.00097)
		(mid 391.509625 -276.950198)
		(end 391.324592 -276.996144)
		(width 0.09525)
		(layer "In13.Cu")
		(net "M_H_CPU0_SB_DQS_DP<5>")
	)
	(arc
		(start 394.234416 -276.348444)
		(mid 394.000446 -276.547546)
		(end 393.737592 -276.706584)
		(width 0.09525)
		(layer "In13.Cu")
		(net "M_H_CPU0_SB_DQS_DP<5>")
	)
	(arc
		(start 388.873492 -277.00097)
		(mid 388.689717 -276.950198)
		(end 388.504684 -276.996144)
		(width 0.09525)
		(layer "In13.Cu")
		(net "M_H_CPU0_SB_DQS_DP<5>")
	)
	(arc
		(start 383.233422 -277.00097)
		(mid 383.076824 -276.951681)
		(end 382.914144 -276.973792)
		(width 0.09525)
		(layer "In13.Cu")
		(net "M_H_CPU0_SB_DQS_DP<5>")
	)
	(arc
		(start 385.67614 -277.00097)
		(mid 385.394708 -277.076725)
		(end 385.113276 -277.00097)
		(width 0.09525)
		(layer "In13.Cu")
		(net "M_H_CPU0_SB_DQS_DP<5>")
	)
	(arc
		(start 387.556248 -277.00097)
		(mid 387.274816 -277.076725)
		(end 386.993384 -277.00097)
		(width 0.09525)
		(layer "In13.Cu")
		(net "M_H_CPU0_SB_DQS_DP<5>")
	)
	(arc
		(start 386.985002 -276.996144)
		(mid 386.79997 -276.95023)
		(end 386.616194 -277.00097)
		(width 0.09525)
		(layer "In13.Cu")
		(net "M_H_CPU0_SB_DQS_DP<5>")
	)
	(arc
		(start 392.632184 -277.00097)
		(mid 392.448663 -276.950326)
		(end 392.263884 -276.996144)
		(width 0.09525)
		(layer "In13.Cu")
		(net "M_H_CPU0_SB_DQS_DP<5>")
	)
	(arc
		(start 387.933438 -277.00097)
		(mid 387.749663 -276.950198)
		(end 387.56463 -276.996144)
		(width 0.09525)
		(layer "In13.Cu")
		(net "M_H_CPU0_SB_DQS_DP<5>")
	)
	(arc
		(start 388.496302 -277.00097)
		(mid 388.21487 -277.076725)
		(end 387.933438 -277.00097)
		(width 0.09525)
		(layer "In13.Cu")
		(net "M_H_CPU0_SB_DQS_DP<5>")
	)
	(arc
		(start 392.237468 -277.011384)
		(mid 391.964088 -277.076605)
		(end 391.6934 -277.00097)
		(width 0.09525)
		(layer "In13.Cu")
		(net "M_H_CPU0_SB_DQS_DP<5>")
	)
	(arc
		(start 393.195556 -277.000208)
		(mid 393.195682 -277.000589)
		(end 393.19581 -277.00097)
		(width 0.09525)
		(layer "In13.Cu")
		(net "M_H_CPU0_SB_DQS_DP<5>")
	)
	(arc
		(start 389.436356 -277.00097)
		(mid 389.154924 -277.076725)
		(end 388.873492 -277.00097)
		(width 0.09525)
		(layer "In13.Cu")
		(net "M_H_CPU0_SB_DQS_DP<5>")
	)
	(arc
		(start 383.796286 -277.00097)
		(mid 383.514854 -277.076725)
		(end 383.233422 -277.00097)
		(width 0.09525)
		(layer "In13.Cu")
		(net "M_H_CPU0_SB_DQS_DP<5>")
	)
	(arc
		(start 389.813292 -277.00097)
		(mid 389.624824 -276.950293)
		(end 389.436356 -277.00097)
		(width 0.09525)
		(layer "In13.Cu")
		(net "M_H_CPU0_SB_DQS_DP<5>")
	)
	(arc
		(start 393.19581 -277.00097)
		(mid 392.92436 -277.077005)
		(end 392.650218 -277.011384)
		(width 0.09525)
		(layer "In13.Cu")
		(net "M_H_CPU0_SB_DQS_DP<5>")
	)
	(segment
		(start 382.577848 -272.200116)
		(end 383.0447 -272.466054)
		(width 0.12954)
		(layer "F.Cu")
		(net "M_H_CPU0_SB_DQS_DP<4>")
	)
	(segment
		(start 395.72692 -270.4465)
		(end 395.667992 -270.387572)
		(width 0.09525)
		(layer "In13.Cu")
		(net "M_H_CPU0_SB_DQS_DP<4>")
	)
	(segment
		(start 414.001458 -277.597616)
		(end 413.092646 -277.597616)
		(width 0.16002)
		(layer "In13.Cu")
		(net "M_H_CPU0_SB_DQS_DP<4>")
	)
	(segment
		(start 387.56463 -272.136108)
		(end 387.556248 -272.140934)
		(width 0.09525)
		(layer "In13.Cu")
		(net "M_H_CPU0_SB_DQS_DP<4>")
	)
	(segment
		(start 383.804668 -272.136108)
		(end 383.796286 -272.140934)
		(width 0.09525)
		(layer "In13.Cu")
		(net "M_H_CPU0_SB_DQS_DP<4>")
	)
	(segment
		(start 409.93695 -274.44192)
		(end 409.71089 -274.44192)
		(width 0.16002)
		(layer "In13.Cu")
		(net "M_H_CPU0_SB_DQS_DP<4>")
	)
	(segment
		(start 412.184342 -276.689312)
		(end 411.453838 -275.958808)
		(width 0.16002)
		(layer "In13.Cu")
		(net "M_H_CPU0_SB_DQS_DP<4>")
	)
	(segment
		(start 404.73757 -270.4465)
		(end 395.750542 -270.4465)
		(width 0.16002)
		(layer "In13.Cu")
		(net "M_H_CPU0_SB_DQS_DP<4>")
	)
	(segment
		(start 413.092646 -277.597616)
		(end 412.720028 -277.224998)
		(width 0.16002)
		(layer "In13.Cu")
		(net "M_H_CPU0_SB_DQS_DP<4>")
	)
	(segment
		(start 388.504684 -272.136108)
		(end 388.496302 -272.140934)
		(width 0.09525)
		(layer "In13.Cu")
		(net "M_H_CPU0_SB_DQS_DP<4>")
	)
	(segment
		(start 414.954212 -276.644862)
		(end 414.001458 -277.597616)
		(width 0.16002)
		(layer "In13.Cu")
		(net "M_H_CPU0_SB_DQS_DP<4>")
	)
	(segment
		(start 394.42517 -270.597376)
		(end 392.933174 -272.089372)
		(width 0.09525)
		(layer "In13.Cu")
		(net "M_H_CPU0_SB_DQS_DP<4>")
	)
	(segment
		(start 418.851334 -277.429722)
		(end 418.1094 -277.429722)
		(width 0.16002)
		(layer "In13.Cu")
		(net "M_H_CPU0_SB_DQS_DP<4>")
	)
	(segment
		(start 395.168882 -270.387572)
		(end 394.959078 -270.597376)
		(width 0.09525)
		(layer "In13.Cu")
		(net "M_H_CPU0_SB_DQS_DP<4>")
	)
	(segment
		(start 382.914144 -272.113756)
		(end 382.890776 -272.200624)
		(width 0.09525)
		(layer "In13.Cu")
		(net "M_H_CPU0_SB_DQS_DP<4>")
	)
	(segment
		(start 408.515058 -273.020028)
		(end 407.311098 -273.020028)
		(width 0.16002)
		(layer "In13.Cu")
		(net "M_H_CPU0_SB_DQS_DP<4>")
	)
	(segment
		(start 412.720028 -277.224998)
		(end 412.522416 -277.224998)
		(width 0.16002)
		(layer "In13.Cu")
		(net "M_H_CPU0_SB_DQS_DP<4>")
	)
	(segment
		(start 415.96564 -277.429722)
		(end 415.18078 -276.644862)
		(width 0.16002)
		(layer "In13.Cu")
		(net "M_H_CPU0_SB_DQS_DP<4>")
	)
	(segment
		(start 412.522416 -277.224998)
		(end 412.184342 -276.886924)
		(width 0.16002)
		(layer "In13.Cu")
		(net "M_H_CPU0_SB_DQS_DP<4>")
	)
	(segment
		(start 408.487626 -274.196556)
		(end 408.487626 -273.720052)
		(width 0.16002)
		(layer "In13.Cu")
		(net "M_H_CPU0_SB_DQS_DP<4>")
	)
	(segment
		(start 408.983688 -274.692618)
		(end 408.487626 -274.196556)
		(width 0.16002)
		(layer "In13.Cu")
		(net "M_H_CPU0_SB_DQS_DP<4>")
	)
	(segment
		(start 390.753346 -272.140934)
		(end 390.744964 -272.136108)
		(width 0.09525)
		(layer "In13.Cu")
		(net "M_H_CPU0_SB_DQS_DP<4>")
	)
	(segment
		(start 419.306502 -276.974554)
		(end 418.851334 -277.429722)
		(width 0.16002)
		(layer "In13.Cu")
		(net "M_H_CPU0_SB_DQS_DP<4>")
	)
	(segment
		(start 412.184342 -276.886924)
		(end 412.184342 -276.689312)
		(width 0.16002)
		(layer "In13.Cu")
		(net "M_H_CPU0_SB_DQS_DP<4>")
	)
	(segment
		(start 411.453838 -275.958808)
		(end 411.227778 -275.958808)
		(width 0.16002)
		(layer "In13.Cu")
		(net "M_H_CPU0_SB_DQS_DP<4>")
	)
	(segment
		(start 417.162742 -276.974554)
		(end 416.707574 -277.429722)
		(width 0.16002)
		(layer "In13.Cu")
		(net "M_H_CPU0_SB_DQS_DP<4>")
	)
	(segment
		(start 415.18078 -276.644862)
		(end 414.954212 -276.644862)
		(width 0.16002)
		(layer "In13.Cu")
		(net "M_H_CPU0_SB_DQS_DP<4>")
	)
	(segment
		(start 395.667992 -270.387572)
		(end 395.168882 -270.387572)
		(width 0.09525)
		(layer "In13.Cu")
		(net "M_H_CPU0_SB_DQS_DP<4>")
	)
	(segment
		(start 407.311098 -273.020028)
		(end 404.73757 -270.4465)
		(width 0.16002)
		(layer "In13.Cu")
		(net "M_H_CPU0_SB_DQS_DP<4>")
	)
	(segment
		(start 408.738324 -273.469354)
		(end 408.738324 -273.243294)
		(width 0.16002)
		(layer "In13.Cu")
		(net "M_H_CPU0_SB_DQS_DP<4>")
	)
	(segment
		(start 386.05333 -272.140934)
		(end 386.044948 -272.136108)
		(width 0.09525)
		(layer "In13.Cu")
		(net "M_H_CPU0_SB_DQS_DP<4>")
	)
	(segment
		(start 382.890776 -272.200624)
		(end 383.0447 -272.466054)
		(width 0.09525)
		(layer "In13.Cu")
		(net "M_H_CPU0_SB_DQS_DP<4>")
	)
	(segment
		(start 394.959078 -270.597376)
		(end 394.42517 -270.597376)
		(width 0.09525)
		(layer "In13.Cu")
		(net "M_H_CPU0_SB_DQS_DP<4>")
	)
	(segment
		(start 395.750542 -270.4465)
		(end 395.72692 -270.4465)
		(width 0.09525)
		(layer "In13.Cu")
		(net "M_H_CPU0_SB_DQS_DP<4>")
	)
	(segment
		(start 386.993384 -272.140934)
		(end 386.985002 -272.136108)
		(width 0.09525)
		(layer "In13.Cu")
		(net "M_H_CPU0_SB_DQS_DP<4>")
	)
	(segment
		(start 408.487626 -273.720052)
		(end 408.738324 -273.469354)
		(width 0.16002)
		(layer "In13.Cu")
		(net "M_H_CPU0_SB_DQS_DP<4>")
	)
	(segment
		(start 419.651434 -276.974554)
		(end 419.306502 -276.974554)
		(width 0.16002)
		(layer "In13.Cu")
		(net "M_H_CPU0_SB_DQS_DP<4>")
	)
	(segment
		(start 410.255212 -274.986242)
		(end 410.255212 -274.760182)
		(width 0.16002)
		(layer "In13.Cu")
		(net "M_H_CPU0_SB_DQS_DP<4>")
	)
	(segment
		(start 418.1094 -277.429722)
		(end 417.654232 -276.974554)
		(width 0.16002)
		(layer "In13.Cu")
		(net "M_H_CPU0_SB_DQS_DP<4>")
	)
	(segment
		(start 410.004514 -275.713444)
		(end 410.004514 -275.23694)
		(width 0.16002)
		(layer "In13.Cu")
		(net "M_H_CPU0_SB_DQS_DP<4>")
	)
	(segment
		(start 417.654232 -276.974554)
		(end 417.162742 -276.974554)
		(width 0.16002)
		(layer "In13.Cu")
		(net "M_H_CPU0_SB_DQS_DP<4>")
	)
	(segment
		(start 410.500576 -276.209506)
		(end 410.004514 -275.713444)
		(width 0.16002)
		(layer "In13.Cu")
		(net "M_H_CPU0_SB_DQS_DP<4>")
	)
	(segment
		(start 419.912038 -277.235158)
		(end 419.651434 -276.974554)
		(width 0.16002)
		(layer "In13.Cu")
		(net "M_H_CPU0_SB_DQS_DP<4>")
	)
	(segment
		(start 392.933174 -272.089372)
		(end 392.445494 -272.089372)
		(width 0.09525)
		(layer "In13.Cu")
		(net "M_H_CPU0_SB_DQS_DP<4>")
	)
	(segment
		(start 391.324592 -272.136108)
		(end 391.31621 -272.140934)
		(width 0.09525)
		(layer "In13.Cu")
		(net "M_H_CPU0_SB_DQS_DP<4>")
	)
	(segment
		(start 410.004514 -275.23694)
		(end 410.255212 -274.986242)
		(width 0.16002)
		(layer "In13.Cu")
		(net "M_H_CPU0_SB_DQS_DP<4>")
	)
	(segment
		(start 408.738324 -273.243294)
		(end 408.515058 -273.020028)
		(width 0.16002)
		(layer "In13.Cu")
		(net "M_H_CPU0_SB_DQS_DP<4>")
	)
	(segment
		(start 409.71089 -274.44192)
		(end 409.460192 -274.692618)
		(width 0.16002)
		(layer "In13.Cu")
		(net "M_H_CPU0_SB_DQS_DP<4>")
	)
	(segment
		(start 410.97708 -276.209506)
		(end 410.500576 -276.209506)
		(width 0.16002)
		(layer "In13.Cu")
		(net "M_H_CPU0_SB_DQS_DP<4>")
	)
	(segment
		(start 411.227778 -275.958808)
		(end 410.97708 -276.209506)
		(width 0.16002)
		(layer "In13.Cu")
		(net "M_H_CPU0_SB_DQS_DP<4>")
	)
	(segment
		(start 416.707574 -277.429722)
		(end 415.96564 -277.429722)
		(width 0.16002)
		(layer "In13.Cu")
		(net "M_H_CPU0_SB_DQS_DP<4>")
	)
	(segment
		(start 391.703814 -272.14703)
		(end 391.6934 -272.140934)
		(width 0.09525)
		(layer "In13.Cu")
		(net "M_H_CPU0_SB_DQS_DP<4>")
	)
	(segment
		(start 410.255212 -274.760182)
		(end 409.93695 -274.44192)
		(width 0.16002)
		(layer "In13.Cu")
		(net "M_H_CPU0_SB_DQS_DP<4>")
	)
	(segment
		(start 409.460192 -274.692618)
		(end 408.983688 -274.692618)
		(width 0.16002)
		(layer "In13.Cu")
		(net "M_H_CPU0_SB_DQS_DP<4>")
	)
	(arc
		(start 383.796286 -272.140934)
		(mid 383.514854 -272.216689)
		(end 383.233422 -272.140934)
		(width 0.09525)
		(layer "In13.Cu")
		(net "M_H_CPU0_SB_DQS_DP<4>")
	)
	(arc
		(start 387.556248 -272.140934)
		(mid 387.274816 -272.216689)
		(end 386.993384 -272.140934)
		(width 0.09525)
		(layer "In13.Cu")
		(net "M_H_CPU0_SB_DQS_DP<4>")
	)
	(arc
		(start 391.6934 -272.140934)
		(mid 391.509625 -272.090162)
		(end 391.324592 -272.136108)
		(width 0.09525)
		(layer "In13.Cu")
		(net "M_H_CPU0_SB_DQS_DP<4>")
	)
	(arc
		(start 385.67614 -272.140934)
		(mid 385.394708 -272.216689)
		(end 385.113276 -272.140934)
		(width 0.09525)
		(layer "In13.Cu")
		(net "M_H_CPU0_SB_DQS_DP<4>")
	)
	(arc
		(start 389.436356 -272.140934)
		(mid 389.154924 -272.216689)
		(end 388.873492 -272.140934)
		(width 0.09525)
		(layer "In13.Cu")
		(net "M_H_CPU0_SB_DQS_DP<4>")
	)
	(arc
		(start 383.233422 -272.140934)
		(mid 383.076824 -272.091645)
		(end 382.914144 -272.113756)
		(width 0.09525)
		(layer "In13.Cu")
		(net "M_H_CPU0_SB_DQS_DP<4>")
	)
	(arc
		(start 386.985002 -272.136108)
		(mid 386.79997 -272.090194)
		(end 386.616194 -272.140934)
		(width 0.09525)
		(layer "In13.Cu")
		(net "M_H_CPU0_SB_DQS_DP<4>")
	)
	(arc
		(start 385.113276 -272.140934)
		(mid 384.924808 -272.090257)
		(end 384.73634 -272.140934)
		(width 0.09525)
		(layer "In13.Cu")
		(net "M_H_CPU0_SB_DQS_DP<4>")
	)
	(arc
		(start 391.31621 -272.140934)
		(mid 391.034778 -272.216689)
		(end 390.753346 -272.140934)
		(width 0.09525)
		(layer "In13.Cu")
		(net "M_H_CPU0_SB_DQS_DP<4>")
	)
	(arc
		(start 384.73634 -272.140934)
		(mid 384.454908 -272.216689)
		(end 384.173476 -272.140934)
		(width 0.09525)
		(layer "In13.Cu")
		(net "M_H_CPU0_SB_DQS_DP<4>")
	)
	(arc
		(start 388.873492 -272.140934)
		(mid 388.689717 -272.090162)
		(end 388.504684 -272.136108)
		(width 0.09525)
		(layer "In13.Cu")
		(net "M_H_CPU0_SB_DQS_DP<4>")
	)
	(arc
		(start 389.813292 -272.140934)
		(mid 389.624824 -272.090257)
		(end 389.436356 -272.140934)
		(width 0.09525)
		(layer "In13.Cu")
		(net "M_H_CPU0_SB_DQS_DP<4>")
	)
	(arc
		(start 386.044948 -272.136108)
		(mid 385.859916 -272.090194)
		(end 385.67614 -272.140934)
		(width 0.09525)
		(layer "In13.Cu")
		(net "M_H_CPU0_SB_DQS_DP<4>")
	)
	(arc
		(start 392.445494 -272.089372)
		(mid 392.347597 -272.102658)
		(end 392.256518 -272.140934)
		(width 0.09525)
		(layer "In13.Cu")
		(net "M_H_CPU0_SB_DQS_DP<4>")
	)
	(arc
		(start 390.744964 -272.136108)
		(mid 390.559932 -272.090194)
		(end 390.376156 -272.140934)
		(width 0.09525)
		(layer "In13.Cu")
		(net "M_H_CPU0_SB_DQS_DP<4>")
	)
	(arc
		(start 384.173476 -272.140934)
		(mid 383.989701 -272.090162)
		(end 383.804668 -272.136108)
		(width 0.09525)
		(layer "In13.Cu")
		(net "M_H_CPU0_SB_DQS_DP<4>")
	)
	(arc
		(start 388.496302 -272.140934)
		(mid 388.21487 -272.216689)
		(end 387.933438 -272.140934)
		(width 0.09525)
		(layer "In13.Cu")
		(net "M_H_CPU0_SB_DQS_DP<4>")
	)
	(arc
		(start 387.933438 -272.140934)
		(mid 387.749663 -272.090162)
		(end 387.56463 -272.136108)
		(width 0.09525)
		(layer "In13.Cu")
		(net "M_H_CPU0_SB_DQS_DP<4>")
	)
	(arc
		(start 392.256518 -272.140934)
		(mid 391.980975 -272.216783)
		(end 391.703814 -272.14703)
		(width 0.09525)
		(layer "In13.Cu")
		(net "M_H_CPU0_SB_DQS_DP<4>")
	)
	(arc
		(start 390.376156 -272.140934)
		(mid 390.094724 -272.216689)
		(end 389.813292 -272.140934)
		(width 0.09525)
		(layer "In13.Cu")
		(net "M_H_CPU0_SB_DQS_DP<4>")
	)
	(arc
		(start 386.616194 -272.140934)
		(mid 386.334762 -272.216689)
		(end 386.05333 -272.140934)
		(width 0.09525)
		(layer "In13.Cu")
		(net "M_H_CPU0_SB_DQS_DP<4>")
	)
	(segment
		(start 383.517902 -290.019994)
		(end 383.984754 -290.285932)
		(width 0.12954)
		(layer "F.Cu")
		(net "M_H_CPU0_SB_DQS_DP<3>")
	)
	(segment
		(start 395.20368 -293.684198)
		(end 396.208758 -294.689276)
		(width 0.16002)
		(layer "In13.Cu")
		(net "M_H_CPU0_SB_DQS_DP<3>")
	)
	(segment
		(start 421.684196 -313.172094)
		(end 423.775124 -313.172094)
		(width 0.16002)
		(layer "In13.Cu")
		(net "M_H_CPU0_SB_DQS_DP<3>")
	)
	(segment
		(start 383.984754 -290.285932)
		(end 384.138678 -290.551362)
		(width 0.09525)
		(layer "In13.Cu")
		(net "M_H_CPU0_SB_DQS_DP<3>")
	)
	(segment
		(start 415.76371 -312.620152)
		(end 416.225228 -313.08167)
		(width 0.16002)
		(layer "In13.Cu")
		(net "M_H_CPU0_SB_DQS_DP<3>")
	)
	(segment
		(start 417.070286 -312.620152)
		(end 418.010594 -312.620152)
		(width 0.16002)
		(layer "In13.Cu")
		(net "M_H_CPU0_SB_DQS_DP<3>")
	)
	(segment
		(start 408.203654 -313.068716)
		(end 411.10789 -313.068716)
		(width 0.16002)
		(layer "In13.Cu")
		(net "M_H_CPU0_SB_DQS_DP<3>")
	)
	(segment
		(start 395.186916 -293.667434)
		(end 395.20368 -293.684198)
		(width 0.09525)
		(layer "In13.Cu")
		(net "M_H_CPU0_SB_DQS_DP<3>")
	)
	(segment
		(start 411.952948 -313.48299)
		(end 412.367222 -313.068716)
		(width 0.16002)
		(layer "In13.Cu")
		(net "M_H_CPU0_SB_DQS_DP<3>")
	)
	(segment
		(start 418.010594 -312.620152)
		(end 418.450268 -313.059826)
		(width 0.16002)
		(layer "In13.Cu")
		(net "M_H_CPU0_SB_DQS_DP<3>")
	)
	(segment
		(start 411.522164 -313.48299)
		(end 411.952948 -313.48299)
		(width 0.16002)
		(layer "In13.Cu")
		(net "M_H_CPU0_SB_DQS_DP<3>")
	)
	(segment
		(start 396.208758 -301.07382)
		(end 408.203654 -313.068716)
		(width 0.16002)
		(layer "In13.Cu")
		(net "M_H_CPU0_SB_DQS_DP<3>")
	)
	(segment
		(start 423.775124 -313.172094)
		(end 424.012106 -312.935112)
		(width 0.16002)
		(layer "In13.Cu")
		(net "M_H_CPU0_SB_DQS_DP<3>")
	)
	(segment
		(start 390.744964 -290.615878)
		(end 390.753346 -290.611052)
		(width 0.09525)
		(layer "In13.Cu")
		(net "M_H_CPU0_SB_DQS_DP<3>")
	)
	(segment
		(start 391.31621 -290.611052)
		(end 391.324592 -290.615878)
		(width 0.09525)
		(layer "In13.Cu")
		(net "M_H_CPU0_SB_DQS_DP<3>")
	)
	(segment
		(start 394.441934 -293.006272)
		(end 395.103096 -293.667434)
		(width 0.09525)
		(layer "In13.Cu")
		(net "M_H_CPU0_SB_DQS_DP<3>")
	)
	(segment
		(start 386.044948 -290.615878)
		(end 386.05333 -290.611052)
		(width 0.09525)
		(layer "In13.Cu")
		(net "M_H_CPU0_SB_DQS_DP<3>")
	)
	(segment
		(start 384.138678 -290.551362)
		(end 384.239516 -290.578032)
		(width 0.09525)
		(layer "In13.Cu")
		(net "M_H_CPU0_SB_DQS_DP<3>")
	)
	(segment
		(start 393.310872 -290.699952)
		(end 393.594336 -290.983416)
		(width 0.09525)
		(layer "In13.Cu")
		(net "M_H_CPU0_SB_DQS_DP<3>")
	)
	(segment
		(start 416.225228 -313.08167)
		(end 416.608768 -313.08167)
		(width 0.16002)
		(layer "In13.Cu")
		(net "M_H_CPU0_SB_DQS_DP<3>")
	)
	(segment
		(start 387.556248 -290.611052)
		(end 387.56463 -290.615878)
		(width 0.09525)
		(layer "In13.Cu")
		(net "M_H_CPU0_SB_DQS_DP<3>")
	)
	(segment
		(start 413.446214 -313.405012)
		(end 413.92729 -313.405012)
		(width 0.16002)
		(layer "In13.Cu")
		(net "M_H_CPU0_SB_DQS_DP<3>")
	)
	(segment
		(start 393.594336 -290.983416)
		(end 393.594336 -290.983162)
		(width 0.09525)
		(layer "In13.Cu")
		(net "M_H_CPU0_SB_DQS_DP<3>")
	)
	(segment
		(start 386.985002 -290.615878)
		(end 386.993384 -290.611052)
		(width 0.09525)
		(layer "In13.Cu")
		(net "M_H_CPU0_SB_DQS_DP<3>")
	)
	(segment
		(start 392.22934 -290.59632)
		(end 392.269218 -290.619434)
		(width 0.09525)
		(layer "In13.Cu")
		(net "M_H_CPU0_SB_DQS_DP<3>")
	)
	(segment
		(start 414.71215 -312.620152)
		(end 415.76371 -312.620152)
		(width 0.16002)
		(layer "In13.Cu")
		(net "M_H_CPU0_SB_DQS_DP<3>")
	)
	(segment
		(start 396.208758 -294.689276)
		(end 396.208758 -301.07382)
		(width 0.16002)
		(layer "In13.Cu")
		(net "M_H_CPU0_SB_DQS_DP<3>")
	)
	(segment
		(start 393.594336 -290.983162)
		(end 394.441934 -293.006272)
		(width 0.09525)
		(layer "In13.Cu")
		(net "M_H_CPU0_SB_DQS_DP<3>")
	)
	(segment
		(start 388.496302 -290.611052)
		(end 388.504684 -290.615878)
		(width 0.09525)
		(layer "In13.Cu")
		(net "M_H_CPU0_SB_DQS_DP<3>")
	)
	(segment
		(start 420.692326 -313.394852)
		(end 421.461438 -313.394852)
		(width 0.16002)
		(layer "In13.Cu")
		(net "M_H_CPU0_SB_DQS_DP<3>")
	)
	(segment
		(start 411.10789 -313.068716)
		(end 411.522164 -313.48299)
		(width 0.16002)
		(layer "In13.Cu")
		(net "M_H_CPU0_SB_DQS_DP<3>")
	)
	(segment
		(start 395.103096 -293.667434)
		(end 395.186916 -293.667434)
		(width 0.09525)
		(layer "In13.Cu")
		(net "M_H_CPU0_SB_DQS_DP<3>")
	)
	(segment
		(start 413.92729 -313.405012)
		(end 414.71215 -312.620152)
		(width 0.16002)
		(layer "In13.Cu")
		(net "M_H_CPU0_SB_DQS_DP<3>")
	)
	(segment
		(start 392.630914 -290.611052)
		(end 392.654282 -290.59759)
		(width 0.09525)
		(layer "In13.Cu")
		(net "M_H_CPU0_SB_DQS_DP<3>")
	)
	(segment
		(start 421.461438 -313.394852)
		(end 421.684196 -313.172094)
		(width 0.16002)
		(layer "In13.Cu")
		(net "M_H_CPU0_SB_DQS_DP<3>")
	)
	(segment
		(start 412.367222 -313.068716)
		(end 413.109918 -313.068716)
		(width 0.16002)
		(layer "In13.Cu")
		(net "M_H_CPU0_SB_DQS_DP<3>")
	)
	(segment
		(start 416.608768 -313.08167)
		(end 417.070286 -312.620152)
		(width 0.16002)
		(layer "In13.Cu")
		(net "M_H_CPU0_SB_DQS_DP<3>")
	)
	(segment
		(start 413.109918 -313.068716)
		(end 413.446214 -313.405012)
		(width 0.16002)
		(layer "In13.Cu")
		(net "M_H_CPU0_SB_DQS_DP<3>")
	)
	(segment
		(start 420.3573 -313.059826)
		(end 420.692326 -313.394852)
		(width 0.16002)
		(layer "In13.Cu")
		(net "M_H_CPU0_SB_DQS_DP<3>")
	)
	(segment
		(start 418.450268 -313.059826)
		(end 420.3573 -313.059826)
		(width 0.16002)
		(layer "In13.Cu")
		(net "M_H_CPU0_SB_DQS_DP<3>")
	)
	(arc
		(start 392.269218 -290.619434)
		(mid 392.451143 -290.661639)
		(end 392.630914 -290.611052)
		(width 0.09525)
		(layer "In13.Cu")
		(net "M_H_CPU0_SB_DQS_DP<3>")
	)
	(arc
		(start 390.376156 -290.611052)
		(mid 390.559931 -290.661824)
		(end 390.744964 -290.615878)
		(width 0.09525)
		(layer "In13.Cu")
		(net "M_H_CPU0_SB_DQS_DP<3>")
	)
	(arc
		(start 384.26009 -290.569904)
		(mid 384.502832 -290.537134)
		(end 384.73634 -290.611052)
		(width 0.09525)
		(layer "In13.Cu")
		(net "M_H_CPU0_SB_DQS_DP<3>")
	)
	(arc
		(start 391.6934 -290.611052)
		(mid 391.959487 -290.535507)
		(end 392.22934 -290.59632)
		(width 0.09525)
		(layer "In13.Cu")
		(net "M_H_CPU0_SB_DQS_DP<3>")
	)
	(arc
		(start 386.05333 -290.611052)
		(mid 386.334762 -290.535297)
		(end 386.616194 -290.611052)
		(width 0.09525)
		(layer "In13.Cu")
		(net "M_H_CPU0_SB_DQS_DP<3>")
	)
	(arc
		(start 391.324592 -290.615878)
		(mid 391.509624 -290.661792)
		(end 391.6934 -290.611052)
		(width 0.09525)
		(layer "In13.Cu")
		(net "M_H_CPU0_SB_DQS_DP<3>")
	)
	(arc
		(start 387.933438 -290.611052)
		(mid 388.21487 -290.535297)
		(end 388.496302 -290.611052)
		(width 0.09525)
		(layer "In13.Cu")
		(net "M_H_CPU0_SB_DQS_DP<3>")
	)
	(arc
		(start 386.993384 -290.611052)
		(mid 387.274816 -290.535297)
		(end 387.556248 -290.611052)
		(width 0.09525)
		(layer "In13.Cu")
		(net "M_H_CPU0_SB_DQS_DP<3>")
	)
	(arc
		(start 384.73634 -290.611052)
		(mid 384.924808 -290.661729)
		(end 385.113276 -290.611052)
		(width 0.09525)
		(layer "In13.Cu")
		(net "M_H_CPU0_SB_DQS_DP<3>")
	)
	(arc
		(start 385.113276 -290.611052)
		(mid 385.394708 -290.535297)
		(end 385.67614 -290.611052)
		(width 0.09525)
		(layer "In13.Cu")
		(net "M_H_CPU0_SB_DQS_DP<3>")
	)
	(arc
		(start 385.67614 -290.611052)
		(mid 385.859915 -290.661824)
		(end 386.044948 -290.615878)
		(width 0.09525)
		(layer "In13.Cu")
		(net "M_H_CPU0_SB_DQS_DP<3>")
	)
	(arc
		(start 388.873492 -290.611052)
		(mid 389.154924 -290.535297)
		(end 389.436356 -290.611052)
		(width 0.09525)
		(layer "In13.Cu")
		(net "M_H_CPU0_SB_DQS_DP<3>")
	)
	(arc
		(start 386.616194 -290.611052)
		(mid 386.799969 -290.661824)
		(end 386.985002 -290.615878)
		(width 0.09525)
		(layer "In13.Cu")
		(net "M_H_CPU0_SB_DQS_DP<3>")
	)
	(arc
		(start 384.239516 -290.578032)
		(mid 384.249764 -290.573869)
		(end 384.26009 -290.569904)
		(width 0.09525)
		(layer "In13.Cu")
		(net "M_H_CPU0_SB_DQS_DP<3>")
	)
	(arc
		(start 393.195048 -290.611052)
		(mid 393.255868 -290.651713)
		(end 393.310872 -290.699952)
		(width 0.09525)
		(layer "In13.Cu")
		(net "M_H_CPU0_SB_DQS_DP<3>")
	)
	(arc
		(start 388.504684 -290.615878)
		(mid 388.689716 -290.661792)
		(end 388.873492 -290.611052)
		(width 0.09525)
		(layer "In13.Cu")
		(net "M_H_CPU0_SB_DQS_DP<3>")
	)
	(arc
		(start 389.436356 -290.611052)
		(mid 389.624824 -290.661729)
		(end 389.813292 -290.611052)
		(width 0.09525)
		(layer "In13.Cu")
		(net "M_H_CPU0_SB_DQS_DP<3>")
	)
	(arc
		(start 387.56463 -290.615878)
		(mid 387.749662 -290.661792)
		(end 387.933438 -290.611052)
		(width 0.09525)
		(layer "In13.Cu")
		(net "M_H_CPU0_SB_DQS_DP<3>")
	)
	(arc
		(start 392.654282 -290.59759)
		(mid 392.926383 -290.534912)
		(end 393.195048 -290.611052)
		(width 0.09525)
		(layer "In13.Cu")
		(net "M_H_CPU0_SB_DQS_DP<3>")
	)
	(arc
		(start 389.813292 -290.611052)
		(mid 390.094724 -290.535297)
		(end 390.376156 -290.611052)
		(width 0.09525)
		(layer "In13.Cu")
		(net "M_H_CPU0_SB_DQS_DP<3>")
	)
	(arc
		(start 390.753346 -290.611052)
		(mid 391.034778 -290.535297)
		(end 391.31621 -290.611052)
		(width 0.09525)
		(layer "In13.Cu")
		(net "M_H_CPU0_SB_DQS_DP<3>")
	)
	(segment
		(start 383.517902 -285.160212)
		(end 383.984754 -285.42615)
		(width 0.12954)
		(layer "F.Cu")
		(net "M_H_CPU0_SB_DQS_DP<2>")
	)
	(segment
		(start 423.72153 -303.875694)
		(end 424.012106 -303.585118)
		(width 0.16002)
		(layer "In13.Cu")
		(net "M_H_CPU0_SB_DQS_DP<2>")
	)
	(segment
		(start 409.30068 -303.718976)
		(end 411.188408 -303.718976)
		(width 0.16002)
		(layer "In13.Cu")
		(net "M_H_CPU0_SB_DQS_DP<2>")
	)
	(segment
		(start 395.639798 -286.681418)
		(end 395.741398 -286.681418)
		(width 0.09525)
		(layer "In13.Cu")
		(net "M_H_CPU0_SB_DQS_DP<2>")
	)
	(segment
		(start 403.864826 -298.283122)
		(end 403.864826 -298.759626)
		(width 0.16002)
		(layer "In13.Cu")
		(net "M_H_CPU0_SB_DQS_DP<2>")
	)
	(segment
		(start 396.132558 -286.622236)
		(end 401.745958 -292.235636)
		(width 0.16002)
		(layer "In13.Cu")
		(net "M_H_CPU0_SB_DQS_DP<2>")
	)
	(segment
		(start 423.457116 -303.875694)
		(end 423.72153 -303.875694)
		(width 0.16002)
		(layer "In13.Cu")
		(net "M_H_CPU0_SB_DQS_DP<2>")
	)
	(segment
		(start 395.824202 -286.622236)
		(end 396.132558 -286.622236)
		(width 0.16002)
		(layer "In13.Cu")
		(net "M_H_CPU0_SB_DQS_DP<2>")
	)
	(segment
		(start 420.3573 -303.709832)
		(end 420.692326 -304.044858)
		(width 0.16002)
		(layer "In13.Cu")
		(net "M_H_CPU0_SB_DQS_DP<2>")
	)
	(segment
		(start 404.40991 -299.30471)
		(end 404.886414 -299.30471)
		(width 0.16002)
		(layer "In13.Cu")
		(net "M_H_CPU0_SB_DQS_DP<2>")
	)
	(segment
		(start 403.864826 -298.759626)
		(end 403.652228 -298.972224)
		(width 0.16002)
		(layer "In13.Cu")
		(net "M_H_CPU0_SB_DQS_DP<2>")
	)
	(segment
		(start 411.188408 -303.718976)
		(end 411.52445 -304.055018)
		(width 0.16002)
		(layer "In13.Cu")
		(net "M_H_CPU0_SB_DQS_DP<2>")
	)
	(segment
		(start 392.22934 -285.736538)
		(end 392.269218 -285.759652)
		(width 0.09525)
		(layer "In13.Cu")
		(net "M_H_CPU0_SB_DQS_DP<2>")
	)
	(segment
		(start 402.347938 -296.766234)
		(end 402.347938 -297.242738)
		(width 0.16002)
		(layer "In13.Cu")
		(net "M_H_CPU0_SB_DQS_DP<2>")
	)
	(segment
		(start 404.197312 -299.517308)
		(end 404.40991 -299.30471)
		(width 0.16002)
		(layer "In13.Cu")
		(net "M_H_CPU0_SB_DQS_DP<2>")
	)
	(segment
		(start 388.496302 -285.75127)
		(end 388.504684 -285.756096)
		(width 0.09525)
		(layer "In13.Cu")
		(net "M_H_CPU0_SB_DQS_DP<2>")
	)
	(segment
		(start 390.744964 -285.756096)
		(end 390.753346 -285.75127)
		(width 0.09525)
		(layer "In13.Cu")
		(net "M_H_CPU0_SB_DQS_DP<2>")
	)
	(segment
		(start 414.71215 -303.270158)
		(end 418.010594 -303.270158)
		(width 0.16002)
		(layer "In13.Cu")
		(net "M_H_CPU0_SB_DQS_DP<2>")
	)
	(segment
		(start 395.33703 -286.37865)
		(end 395.639798 -286.681418)
		(width 0.09525)
		(layer "In13.Cu")
		(net "M_H_CPU0_SB_DQS_DP<2>")
	)
	(segment
		(start 401.745958 -292.235636)
		(end 401.745958 -296.164254)
		(width 0.16002)
		(layer "In13.Cu")
		(net "M_H_CPU0_SB_DQS_DP<2>")
	)
	(segment
		(start 411.52445 -304.055018)
		(end 413.92729 -304.055018)
		(width 0.16002)
		(layer "In13.Cu")
		(net "M_H_CPU0_SB_DQS_DP<2>")
	)
	(segment
		(start 394.219684 -285.80334)
		(end 394.794994 -286.37865)
		(width 0.09525)
		(layer "In13.Cu")
		(net "M_H_CPU0_SB_DQS_DP<2>")
	)
	(segment
		(start 404.886414 -299.30471)
		(end 409.30068 -303.718976)
		(width 0.16002)
		(layer "In13.Cu")
		(net "M_H_CPU0_SB_DQS_DP<2>")
	)
	(segment
		(start 403.971252 -299.517308)
		(end 404.197312 -299.517308)
		(width 0.16002)
		(layer "In13.Cu")
		(net "M_H_CPU0_SB_DQS_DP<2>")
	)
	(segment
		(start 403.652228 -298.972224)
		(end 403.652228 -299.198284)
		(width 0.16002)
		(layer "In13.Cu")
		(net "M_H_CPU0_SB_DQS_DP<2>")
	)
	(segment
		(start 403.369526 -297.787822)
		(end 403.864826 -298.283122)
		(width 0.16002)
		(layer "In13.Cu")
		(net "M_H_CPU0_SB_DQS_DP<2>")
	)
	(segment
		(start 418.450268 -303.709832)
		(end 420.3573 -303.709832)
		(width 0.16002)
		(layer "In13.Cu")
		(net "M_H_CPU0_SB_DQS_DP<2>")
	)
	(segment
		(start 395.80058 -286.622236)
		(end 395.824202 -286.622236)
		(width 0.09525)
		(layer "In13.Cu")
		(net "M_H_CPU0_SB_DQS_DP<2>")
	)
	(segment
		(start 401.745958 -296.164254)
		(end 402.347938 -296.766234)
		(width 0.16002)
		(layer "In13.Cu")
		(net "M_H_CPU0_SB_DQS_DP<2>")
	)
	(segment
		(start 395.741398 -286.681418)
		(end 395.80058 -286.622236)
		(width 0.09525)
		(layer "In13.Cu")
		(net "M_H_CPU0_SB_DQS_DP<2>")
	)
	(segment
		(start 402.680424 -298.00042)
		(end 402.893022 -297.787822)
		(width 0.16002)
		(layer "In13.Cu")
		(net "M_H_CPU0_SB_DQS_DP<2>")
	)
	(segment
		(start 422.848532 -303.26711)
		(end 423.457116 -303.875694)
		(width 0.16002)
		(layer "In13.Cu")
		(net "M_H_CPU0_SB_DQS_DP<2>")
	)
	(segment
		(start 386.044948 -285.756096)
		(end 386.05333 -285.75127)
		(width 0.09525)
		(layer "In13.Cu")
		(net "M_H_CPU0_SB_DQS_DP<2>")
	)
	(segment
		(start 384.138678 -285.69158)
		(end 384.239516 -285.71825)
		(width 0.09525)
		(layer "In13.Cu")
		(net "M_H_CPU0_SB_DQS_DP<2>")
	)
	(segment
		(start 420.692326 -304.044858)
		(end 421.593772 -304.044858)
		(width 0.16002)
		(layer "In13.Cu")
		(net "M_H_CPU0_SB_DQS_DP<2>")
	)
	(segment
		(start 402.13534 -297.455336)
		(end 402.13534 -297.681396)
		(width 0.16002)
		(layer "In13.Cu")
		(net "M_H_CPU0_SB_DQS_DP<2>")
	)
	(segment
		(start 383.984754 -285.42615)
		(end 384.138678 -285.69158)
		(width 0.09525)
		(layer "In13.Cu")
		(net "M_H_CPU0_SB_DQS_DP<2>")
	)
	(segment
		(start 386.985002 -285.756096)
		(end 386.993384 -285.75127)
		(width 0.09525)
		(layer "In13.Cu")
		(net "M_H_CPU0_SB_DQS_DP<2>")
	)
	(segment
		(start 403.652228 -299.198284)
		(end 403.971252 -299.517308)
		(width 0.16002)
		(layer "In13.Cu")
		(net "M_H_CPU0_SB_DQS_DP<2>")
	)
	(segment
		(start 391.31621 -285.75127)
		(end 391.324592 -285.756096)
		(width 0.09525)
		(layer "In13.Cu")
		(net "M_H_CPU0_SB_DQS_DP<2>")
	)
	(segment
		(start 418.010594 -303.270158)
		(end 418.450268 -303.709832)
		(width 0.16002)
		(layer "In13.Cu")
		(net "M_H_CPU0_SB_DQS_DP<2>")
	)
	(segment
		(start 422.37152 -303.26711)
		(end 422.848532 -303.26711)
		(width 0.16002)
		(layer "In13.Cu")
		(net "M_H_CPU0_SB_DQS_DP<2>")
	)
	(segment
		(start 402.893022 -297.787822)
		(end 403.369526 -297.787822)
		(width 0.16002)
		(layer "In13.Cu")
		(net "M_H_CPU0_SB_DQS_DP<2>")
	)
	(segment
		(start 393.384786 -285.80334)
		(end 394.219684 -285.80334)
		(width 0.09525)
		(layer "In13.Cu")
		(net "M_H_CPU0_SB_DQS_DP<2>")
	)
	(segment
		(start 387.556248 -285.75127)
		(end 387.56463 -285.756096)
		(width 0.09525)
		(layer "In13.Cu")
		(net "M_H_CPU0_SB_DQS_DP<2>")
	)
	(segment
		(start 402.13534 -297.681396)
		(end 402.454364 -298.00042)
		(width 0.16002)
		(layer "In13.Cu")
		(net "M_H_CPU0_SB_DQS_DP<2>")
	)
	(segment
		(start 402.347938 -297.242738)
		(end 402.13534 -297.455336)
		(width 0.16002)
		(layer "In13.Cu")
		(net "M_H_CPU0_SB_DQS_DP<2>")
	)
	(segment
		(start 413.92729 -304.055018)
		(end 414.71215 -303.270158)
		(width 0.16002)
		(layer "In13.Cu")
		(net "M_H_CPU0_SB_DQS_DP<2>")
	)
	(segment
		(start 394.794994 -286.37865)
		(end 395.33703 -286.37865)
		(width 0.09525)
		(layer "In13.Cu")
		(net "M_H_CPU0_SB_DQS_DP<2>")
	)
	(segment
		(start 392.630914 -285.75127)
		(end 392.654282 -285.737808)
		(width 0.09525)
		(layer "In13.Cu")
		(net "M_H_CPU0_SB_DQS_DP<2>")
	)
	(segment
		(start 421.593772 -304.044858)
		(end 422.37152 -303.26711)
		(width 0.16002)
		(layer "In13.Cu")
		(net "M_H_CPU0_SB_DQS_DP<2>")
	)
	(segment
		(start 402.454364 -298.00042)
		(end 402.680424 -298.00042)
		(width 0.16002)
		(layer "In13.Cu")
		(net "M_H_CPU0_SB_DQS_DP<2>")
	)
	(arc
		(start 386.993384 -285.75127)
		(mid 387.274816 -285.675515)
		(end 387.556248 -285.75127)
		(width 0.09525)
		(layer "In13.Cu")
		(net "M_H_CPU0_SB_DQS_DP<2>")
	)
	(arc
		(start 391.6934 -285.75127)
		(mid 391.959487 -285.675725)
		(end 392.22934 -285.736538)
		(width 0.09525)
		(layer "In13.Cu")
		(net "M_H_CPU0_SB_DQS_DP<2>")
	)
	(arc
		(start 391.324592 -285.756096)
		(mid 391.509624 -285.80201)
		(end 391.6934 -285.75127)
		(width 0.09525)
		(layer "In13.Cu")
		(net "M_H_CPU0_SB_DQS_DP<2>")
	)
	(arc
		(start 385.113276 -285.75127)
		(mid 385.394708 -285.675515)
		(end 385.67614 -285.75127)
		(width 0.09525)
		(layer "In13.Cu")
		(net "M_H_CPU0_SB_DQS_DP<2>")
	)
	(arc
		(start 386.616194 -285.75127)
		(mid 386.799969 -285.802042)
		(end 386.985002 -285.756096)
		(width 0.09525)
		(layer "In13.Cu")
		(net "M_H_CPU0_SB_DQS_DP<2>")
	)
	(arc
		(start 392.269218 -285.759652)
		(mid 392.451143 -285.801857)
		(end 392.630914 -285.75127)
		(width 0.09525)
		(layer "In13.Cu")
		(net "M_H_CPU0_SB_DQS_DP<2>")
	)
	(arc
		(start 393.195048 -285.75127)
		(mid 393.28646 -285.78989)
		(end 393.384786 -285.80334)
		(width 0.09525)
		(layer "In13.Cu")
		(net "M_H_CPU0_SB_DQS_DP<2>")
	)
	(arc
		(start 388.504684 -285.756096)
		(mid 388.689716 -285.80201)
		(end 388.873492 -285.75127)
		(width 0.09525)
		(layer "In13.Cu")
		(net "M_H_CPU0_SB_DQS_DP<2>")
	)
	(arc
		(start 387.56463 -285.756096)
		(mid 387.749662 -285.80201)
		(end 387.933438 -285.75127)
		(width 0.09525)
		(layer "In13.Cu")
		(net "M_H_CPU0_SB_DQS_DP<2>")
	)
	(arc
		(start 384.26009 -285.710122)
		(mid 384.502832 -285.677352)
		(end 384.73634 -285.75127)
		(width 0.09525)
		(layer "In13.Cu")
		(net "M_H_CPU0_SB_DQS_DP<2>")
	)
	(arc
		(start 387.933438 -285.75127)
		(mid 388.21487 -285.675515)
		(end 388.496302 -285.75127)
		(width 0.09525)
		(layer "In13.Cu")
		(net "M_H_CPU0_SB_DQS_DP<2>")
	)
	(arc
		(start 390.376156 -285.75127)
		(mid 390.559931 -285.802042)
		(end 390.744964 -285.756096)
		(width 0.09525)
		(layer "In13.Cu")
		(net "M_H_CPU0_SB_DQS_DP<2>")
	)
	(arc
		(start 388.873492 -285.75127)
		(mid 389.154924 -285.675515)
		(end 389.436356 -285.75127)
		(width 0.09525)
		(layer "In13.Cu")
		(net "M_H_CPU0_SB_DQS_DP<2>")
	)
	(arc
		(start 384.73634 -285.75127)
		(mid 384.924808 -285.801947)
		(end 385.113276 -285.75127)
		(width 0.09525)
		(layer "In13.Cu")
		(net "M_H_CPU0_SB_DQS_DP<2>")
	)
	(arc
		(start 390.753346 -285.75127)
		(mid 391.034778 -285.675515)
		(end 391.31621 -285.75127)
		(width 0.09525)
		(layer "In13.Cu")
		(net "M_H_CPU0_SB_DQS_DP<2>")
	)
	(arc
		(start 389.436356 -285.75127)
		(mid 389.624824 -285.801947)
		(end 389.813292 -285.75127)
		(width 0.09525)
		(layer "In13.Cu")
		(net "M_H_CPU0_SB_DQS_DP<2>")
	)
	(arc
		(start 392.654282 -285.737808)
		(mid 392.926383 -285.67513)
		(end 393.195048 -285.75127)
		(width 0.09525)
		(layer "In13.Cu")
		(net "M_H_CPU0_SB_DQS_DP<2>")
	)
	(arc
		(start 385.67614 -285.75127)
		(mid 385.859915 -285.802042)
		(end 386.044948 -285.756096)
		(width 0.09525)
		(layer "In13.Cu")
		(net "M_H_CPU0_SB_DQS_DP<2>")
	)
	(arc
		(start 386.05333 -285.75127)
		(mid 386.334762 -285.675515)
		(end 386.616194 -285.75127)
		(width 0.09525)
		(layer "In13.Cu")
		(net "M_H_CPU0_SB_DQS_DP<2>")
	)
	(arc
		(start 389.813292 -285.75127)
		(mid 390.094724 -285.675515)
		(end 390.376156 -285.75127)
		(width 0.09525)
		(layer "In13.Cu")
		(net "M_H_CPU0_SB_DQS_DP<2>")
	)
	(arc
		(start 384.239516 -285.71825)
		(mid 384.249764 -285.714087)
		(end 384.26009 -285.710122)
		(width 0.09525)
		(layer "In13.Cu")
		(net "M_H_CPU0_SB_DQS_DP<2>")
	)
	(segment
		(start 383.517902 -280.300176)
		(end 383.984754 -280.566114)
		(width 0.12954)
		(layer "F.Cu")
		(net "M_H_CPU0_SB_DQS_DP<1>")
	)
	(segment
		(start 420.692326 -294.694864)
		(end 420.3573 -294.359838)
		(width 0.16002)
		(layer "In13.Cu")
		(net "M_H_CPU0_SB_DQS_DP<1>")
	)
	(segment
		(start 410.433774 -294.45966)
		(end 409.72613 -295.167304)
		(width 0.16002)
		(layer "In13.Cu")
		(net "M_H_CPU0_SB_DQS_DP<1>")
	)
	(segment
		(start 423.769536 -294.477694)
		(end 422.992042 -294.477694)
		(width 0.16002)
		(layer "In13.Cu")
		(net "M_H_CPU0_SB_DQS_DP<1>")
	)
	(segment
		(start 391.324592 -280.89606)
		(end 391.31621 -280.891234)
		(width 0.09525)
		(layer "In13.Cu")
		(net "M_H_CPU0_SB_DQS_DP<1>")
	)
	(segment
		(start 388.504684 -280.89606)
		(end 388.496302 -280.891234)
		(width 0.09525)
		(layer "In13.Cu")
		(net "M_H_CPU0_SB_DQS_DP<1>")
	)
	(segment
		(start 398.201134 -280.857198)
		(end 395.732508 -280.857198)
		(width 0.16002)
		(layer "In13.Cu")
		(net "M_H_CPU0_SB_DQS_DP<1>")
	)
	(segment
		(start 418.450268 -294.359838)
		(end 418.010594 -293.920164)
		(width 0.16002)
		(layer "In13.Cu")
		(net "M_H_CPU0_SB_DQS_DP<1>")
	)
	(segment
		(start 408.968702 -294.63619)
		(end 408.968702 -294.41013)
		(width 0.16002)
		(layer "In13.Cu")
		(net "M_H_CPU0_SB_DQS_DP<1>")
	)
	(segment
		(start 422.992042 -294.477694)
		(end 422.774872 -294.694864)
		(width 0.16002)
		(layer "In13.Cu")
		(net "M_H_CPU0_SB_DQS_DP<1>")
	)
	(segment
		(start 407.795984 -291.479224)
		(end 407.283158 -290.966398)
		(width 0.16002)
		(layer "In13.Cu")
		(net "M_H_CPU0_SB_DQS_DP<1>")
	)
	(segment
		(start 395.169644 -280.537666)
		(end 394.153644 -280.537666)
		(width 0.09525)
		(layer "In13.Cu")
		(net "M_H_CPU0_SB_DQS_DP<1>")
	)
	(segment
		(start 395.708886 -280.857198)
		(end 395.649704 -280.91638)
		(width 0.09525)
		(layer "In13.Cu")
		(net "M_H_CPU0_SB_DQS_DP<1>")
	)
	(segment
		(start 407.283158 -289.939222)
		(end 398.201134 -280.857198)
		(width 0.16002)
		(layer "In13.Cu")
		(net "M_H_CPU0_SB_DQS_DP<1>")
	)
	(segment
		(start 414.71215 -293.920164)
		(end 413.92729 -294.705024)
		(width 0.16002)
		(layer "In13.Cu")
		(net "M_H_CPU0_SB_DQS_DP<1>")
	)
	(segment
		(start 386.993384 -280.891234)
		(end 386.985002 -280.89606)
		(width 0.09525)
		(layer "In13.Cu")
		(net "M_H_CPU0_SB_DQS_DP<1>")
	)
	(segment
		(start 422.774872 -294.694864)
		(end 420.692326 -294.694864)
		(width 0.16002)
		(layer "In13.Cu")
		(net "M_H_CPU0_SB_DQS_DP<1>")
	)
	(segment
		(start 392.267186 -280.898092)
		(end 392.23442 -280.879042)
		(width 0.09525)
		(layer "In13.Cu")
		(net "M_H_CPU0_SB_DQS_DP<1>")
	)
	(segment
		(start 424.012106 -294.235124)
		(end 423.769536 -294.477694)
		(width 0.16002)
		(layer "In13.Cu")
		(net "M_H_CPU0_SB_DQS_DP<1>")
	)
	(segment
		(start 384.239516 -280.858214)
		(end 384.138678 -280.831544)
		(width 0.09525)
		(layer "In13.Cu")
		(net "M_H_CPU0_SB_DQS_DP<1>")
	)
	(segment
		(start 387.56463 -280.89606)
		(end 387.556248 -280.891234)
		(width 0.09525)
		(layer "In13.Cu")
		(net "M_H_CPU0_SB_DQS_DP<1>")
	)
	(segment
		(start 408.354276 -291.479224)
		(end 407.795984 -291.479224)
		(width 0.16002)
		(layer "In13.Cu")
		(net "M_H_CPU0_SB_DQS_DP<1>")
	)
	(segment
		(start 413.209232 -294.705024)
		(end 412.963868 -294.45966)
		(width 0.16002)
		(layer "In13.Cu")
		(net "M_H_CPU0_SB_DQS_DP<1>")
	)
	(segment
		(start 395.548358 -280.91638)
		(end 395.169644 -280.537666)
		(width 0.09525)
		(layer "In13.Cu")
		(net "M_H_CPU0_SB_DQS_DP<1>")
	)
	(segment
		(start 386.05333 -280.891234)
		(end 386.044948 -280.89606)
		(width 0.09525)
		(layer "In13.Cu")
		(net "M_H_CPU0_SB_DQS_DP<1>")
	)
	(segment
		(start 409.72613 -295.167304)
		(end 409.499816 -295.167304)
		(width 0.16002)
		(layer "In13.Cu")
		(net "M_H_CPU0_SB_DQS_DP<1>")
	)
	(segment
		(start 412.963868 -294.45966)
		(end 410.433774 -294.45966)
		(width 0.16002)
		(layer "In13.Cu")
		(net "M_H_CPU0_SB_DQS_DP<1>")
	)
	(segment
		(start 409.358084 -294.020748)
		(end 409.358084 -292.483032)
		(width 0.16002)
		(layer "In13.Cu")
		(net "M_H_CPU0_SB_DQS_DP<1>")
	)
	(segment
		(start 409.358084 -292.483032)
		(end 408.354276 -291.479224)
		(width 0.16002)
		(layer "In13.Cu")
		(net "M_H_CPU0_SB_DQS_DP<1>")
	)
	(segment
		(start 413.92729 -294.705024)
		(end 413.209232 -294.705024)
		(width 0.16002)
		(layer "In13.Cu")
		(net "M_H_CPU0_SB_DQS_DP<1>")
	)
	(segment
		(start 408.968702 -294.41013)
		(end 409.358084 -294.020748)
		(width 0.16002)
		(layer "In13.Cu")
		(net "M_H_CPU0_SB_DQS_DP<1>")
	)
	(segment
		(start 393.593574 -280.94305)
		(end 393.384786 -280.94305)
		(width 0.09525)
		(layer "In13.Cu")
		(net "M_H_CPU0_SB_DQS_DP<1>")
	)
	(segment
		(start 395.732508 -280.857198)
		(end 395.708886 -280.857198)
		(width 0.09525)
		(layer "In13.Cu")
		(net "M_H_CPU0_SB_DQS_DP<1>")
	)
	(segment
		(start 420.3573 -294.359838)
		(end 418.450268 -294.359838)
		(width 0.16002)
		(layer "In13.Cu")
		(net "M_H_CPU0_SB_DQS_DP<1>")
	)
	(segment
		(start 395.649704 -280.91638)
		(end 395.548358 -280.91638)
		(width 0.09525)
		(layer "In13.Cu")
		(net "M_H_CPU0_SB_DQS_DP<1>")
	)
	(segment
		(start 418.010594 -293.920164)
		(end 414.71215 -293.920164)
		(width 0.16002)
		(layer "In13.Cu")
		(net "M_H_CPU0_SB_DQS_DP<1>")
	)
	(segment
		(start 390.753346 -280.891234)
		(end 390.744964 -280.89606)
		(width 0.09525)
		(layer "In13.Cu")
		(net "M_H_CPU0_SB_DQS_DP<1>")
	)
	(segment
		(start 407.283158 -290.966398)
		(end 407.283158 -289.939222)
		(width 0.16002)
		(layer "In13.Cu")
		(net "M_H_CPU0_SB_DQS_DP<1>")
	)
	(segment
		(start 384.138678 -280.831544)
		(end 383.984754 -280.566114)
		(width 0.09525)
		(layer "In13.Cu")
		(net "M_H_CPU0_SB_DQS_DP<1>")
	)
	(segment
		(start 392.652504 -280.879042)
		(end 392.631676 -280.891234)
		(width 0.09525)
		(layer "In13.Cu")
		(net "M_H_CPU0_SB_DQS_DP<1>")
	)
	(segment
		(start 409.499816 -295.167304)
		(end 408.968702 -294.63619)
		(width 0.16002)
		(layer "In13.Cu")
		(net "M_H_CPU0_SB_DQS_DP<1>")
	)
	(segment
		(start 393.889484 -280.64714)
		(end 393.593574 -280.94305)
		(width 0.09525)
		(layer "In13.Cu")
		(net "M_H_CPU0_SB_DQS_DP<1>")
	)
	(arc
		(start 386.985002 -280.89606)
		(mid 386.79997 -280.941974)
		(end 386.616194 -280.891234)
		(width 0.09525)
		(layer "In13.Cu")
		(net "M_H_CPU0_SB_DQS_DP<1>")
	)
	(arc
		(start 393.384786 -280.94305)
		(mid 393.286752 -280.929649)
		(end 393.195556 -280.891234)
		(width 0.09525)
		(layer "In13.Cu")
		(net "M_H_CPU0_SB_DQS_DP<1>")
	)
	(arc
		(start 393.195556 -280.891234)
		(mid 392.925615 -280.815108)
		(end 392.652504 -280.879042)
		(width 0.09525)
		(layer "In13.Cu")
		(net "M_H_CPU0_SB_DQS_DP<1>")
	)
	(arc
		(start 390.376156 -280.891234)
		(mid 390.094724 -280.815479)
		(end 389.813292 -280.891234)
		(width 0.09525)
		(layer "In13.Cu")
		(net "M_H_CPU0_SB_DQS_DP<1>")
	)
	(arc
		(start 392.631676 -280.891234)
		(mid 392.450314 -280.941844)
		(end 392.267186 -280.898092)
		(width 0.09525)
		(layer "In13.Cu")
		(net "M_H_CPU0_SB_DQS_DP<1>")
	)
	(arc
		(start 390.744964 -280.89606)
		(mid 390.559932 -280.941974)
		(end 390.376156 -280.891234)
		(width 0.09525)
		(layer "In13.Cu")
		(net "M_H_CPU0_SB_DQS_DP<1>")
	)
	(arc
		(start 387.556248 -280.891234)
		(mid 387.274816 -280.815479)
		(end 386.993384 -280.891234)
		(width 0.09525)
		(layer "In13.Cu")
		(net "M_H_CPU0_SB_DQS_DP<1>")
	)
	(arc
		(start 391.31621 -280.891234)
		(mid 391.034778 -280.815479)
		(end 390.753346 -280.891234)
		(width 0.09525)
		(layer "In13.Cu")
		(net "M_H_CPU0_SB_DQS_DP<1>")
	)
	(arc
		(start 391.6934 -280.891234)
		(mid 391.509625 -280.942006)
		(end 391.324592 -280.89606)
		(width 0.09525)
		(layer "In13.Cu")
		(net "M_H_CPU0_SB_DQS_DP<1>")
	)
	(arc
		(start 384.73634 -280.891234)
		(mid 384.502826 -280.817391)
		(end 384.26009 -280.850086)
		(width 0.09525)
		(layer "In13.Cu")
		(net "M_H_CPU0_SB_DQS_DP<1>")
	)
	(arc
		(start 385.67614 -280.891234)
		(mid 385.394708 -280.815479)
		(end 385.113276 -280.891234)
		(width 0.09525)
		(layer "In13.Cu")
		(net "M_H_CPU0_SB_DQS_DP<1>")
	)
	(arc
		(start 384.26009 -280.850086)
		(mid 384.249762 -280.854046)
		(end 384.239516 -280.858214)
		(width 0.09525)
		(layer "In13.Cu")
		(net "M_H_CPU0_SB_DQS_DP<1>")
	)
	(arc
		(start 392.23442 -280.879042)
		(mid 391.962357 -280.815604)
		(end 391.6934 -280.891234)
		(width 0.09525)
		(layer "In13.Cu")
		(net "M_H_CPU0_SB_DQS_DP<1>")
	)
	(arc
		(start 386.044948 -280.89606)
		(mid 385.859916 -280.941974)
		(end 385.67614 -280.891234)
		(width 0.09525)
		(layer "In13.Cu")
		(net "M_H_CPU0_SB_DQS_DP<1>")
	)
	(arc
		(start 394.153644 -280.537666)
		(mid 394.010675 -280.566122)
		(end 393.889484 -280.64714)
		(width 0.09525)
		(layer "In13.Cu")
		(net "M_H_CPU0_SB_DQS_DP<1>")
	)
	(arc
		(start 388.873492 -280.891234)
		(mid 388.689717 -280.942006)
		(end 388.504684 -280.89606)
		(width 0.09525)
		(layer "In13.Cu")
		(net "M_H_CPU0_SB_DQS_DP<1>")
	)
	(arc
		(start 386.616194 -280.891234)
		(mid 386.334762 -280.815479)
		(end 386.05333 -280.891234)
		(width 0.09525)
		(layer "In13.Cu")
		(net "M_H_CPU0_SB_DQS_DP<1>")
	)
	(arc
		(start 389.436356 -280.891234)
		(mid 389.154924 -280.815479)
		(end 388.873492 -280.891234)
		(width 0.09525)
		(layer "In13.Cu")
		(net "M_H_CPU0_SB_DQS_DP<1>")
	)
	(arc
		(start 385.113276 -280.891234)
		(mid 384.924808 -280.941911)
		(end 384.73634 -280.891234)
		(width 0.09525)
		(layer "In13.Cu")
		(net "M_H_CPU0_SB_DQS_DP<1>")
	)
	(arc
		(start 387.933438 -280.891234)
		(mid 387.749663 -280.942006)
		(end 387.56463 -280.89606)
		(width 0.09525)
		(layer "In13.Cu")
		(net "M_H_CPU0_SB_DQS_DP<1>")
	)
	(arc
		(start 388.496302 -280.891234)
		(mid 388.21487 -280.815479)
		(end 387.933438 -280.891234)
		(width 0.09525)
		(layer "In13.Cu")
		(net "M_H_CPU0_SB_DQS_DP<1>")
	)
	(arc
		(start 389.813292 -280.891234)
		(mid 389.624824 -280.941911)
		(end 389.436356 -280.891234)
		(width 0.09525)
		(layer "In13.Cu")
		(net "M_H_CPU0_SB_DQS_DP<1>")
	)
	(segment
		(start 383.517902 -275.44014)
		(end 383.984754 -275.706078)
		(width 0.12954)
		(layer "F.Cu")
		(net "M_H_CPU0_SB_DQS_DP<0>")
	)
	(segment
		(start 414.71215 -284.57017)
		(end 415.744152 -284.57017)
		(width 0.16002)
		(layer "In13.Cu")
		(net "M_H_CPU0_SB_DQS_DP<0>")
	)
	(segment
		(start 420.46398 -284.738572)
		(end 421.070278 -285.34487)
		(width 0.16002)
		(layer "In13.Cu")
		(net "M_H_CPU0_SB_DQS_DP<0>")
	)
	(segment
		(start 393.649708 -275.972524)
		(end 394.625068 -274.997164)
		(width 0.09525)
		(layer "In13.Cu")
		(net "M_H_CPU0_SB_DQS_DP<0>")
	)
	(segment
		(start 417.278312 -284.41015)
		(end 417.438332 -284.57017)
		(width 0.16002)
		(layer "In13.Cu")
		(net "M_H_CPU0_SB_DQS_DP<0>")
	)
	(segment
		(start 386.985002 -276.036024)
		(end 386.993384 -276.031198)
		(width 0.09525)
		(layer "In13.Cu")
		(net "M_H_CPU0_SB_DQS_DP<0>")
	)
	(segment
		(start 386.044948 -276.036024)
		(end 386.05333 -276.031198)
		(width 0.09525)
		(layer "In13.Cu")
		(net "M_H_CPU0_SB_DQS_DP<0>")
	)
	(segment
		(start 421.650414 -285.155894)
		(end 423.741342 -285.155894)
		(width 0.16002)
		(layer "In13.Cu")
		(net "M_H_CPU0_SB_DQS_DP<0>")
	)
	(segment
		(start 394.625068 -274.997164)
		(end 395.223746 -274.997164)
		(width 0.09525)
		(layer "In13.Cu")
		(net "M_H_CPU0_SB_DQS_DP<0>")
	)
	(segment
		(start 400.5707 -274.897596)
		(end 403.262338 -277.589234)
		(width 0.16002)
		(layer "In13.Cu")
		(net "M_H_CPU0_SB_DQS_DP<0>")
	)
	(segment
		(start 383.984754 -275.706078)
		(end 384.138678 -275.971508)
		(width 0.09525)
		(layer "In13.Cu")
		(net "M_H_CPU0_SB_DQS_DP<0>")
	)
	(segment
		(start 413.624014 -285.35503)
		(end 413.92729 -285.35503)
		(width 0.16002)
		(layer "In13.Cu")
		(net "M_H_CPU0_SB_DQS_DP<0>")
	)
	(segment
		(start 384.138678 -275.971508)
		(end 384.239516 -275.998178)
		(width 0.09525)
		(layer "In13.Cu")
		(net "M_H_CPU0_SB_DQS_DP<0>")
	)
	(segment
		(start 411.277054 -284.61843)
		(end 412.887414 -284.61843)
		(width 0.16002)
		(layer "In13.Cu")
		(net "M_H_CPU0_SB_DQS_DP<0>")
	)
	(segment
		(start 404.247858 -277.589234)
		(end 411.277054 -284.61843)
		(width 0.16002)
		(layer "In13.Cu")
		(net "M_H_CPU0_SB_DQS_DP<0>")
	)
	(segment
		(start 392.23442 -276.019006)
		(end 392.267186 -276.038056)
		(width 0.09525)
		(layer "In13.Cu")
		(net "M_H_CPU0_SB_DQS_DP<0>")
	)
	(segment
		(start 392.652504 -276.019006)
		(end 392.654028 -276.01926)
		(width 0.09525)
		(layer "In13.Cu")
		(net "M_H_CPU0_SB_DQS_DP<0>")
	)
	(segment
		(start 417.438332 -284.57017)
		(end 417.753038 -284.57017)
		(width 0.16002)
		(layer "In13.Cu")
		(net "M_H_CPU0_SB_DQS_DP<0>")
	)
	(segment
		(start 395.693646 -274.897596)
		(end 395.717268 -274.897596)
		(width 0.09525)
		(layer "In13.Cu")
		(net "M_H_CPU0_SB_DQS_DP<0>")
	)
	(segment
		(start 416.941254 -283.868622)
		(end 417.278312 -284.20568)
		(width 0.16002)
		(layer "In13.Cu")
		(net "M_H_CPU0_SB_DQS_DP<0>")
	)
	(segment
		(start 421.070278 -285.34487)
		(end 421.461438 -285.34487)
		(width 0.16002)
		(layer "In13.Cu")
		(net "M_H_CPU0_SB_DQS_DP<0>")
	)
	(segment
		(start 415.744152 -284.57017)
		(end 415.904172 -284.41015)
		(width 0.16002)
		(layer "In13.Cu")
		(net "M_H_CPU0_SB_DQS_DP<0>")
	)
	(segment
		(start 415.904172 -284.41015)
		(end 415.904172 -284.20568)
		(width 0.16002)
		(layer "In13.Cu")
		(net "M_H_CPU0_SB_DQS_DP<0>")
	)
	(segment
		(start 421.461438 -285.34487)
		(end 421.650414 -285.155894)
		(width 0.16002)
		(layer "In13.Cu")
		(net "M_H_CPU0_SB_DQS_DP<0>")
	)
	(segment
		(start 417.278312 -284.20568)
		(end 417.278312 -284.41015)
		(width 0.16002)
		(layer "In13.Cu")
		(net "M_H_CPU0_SB_DQS_DP<0>")
	)
	(segment
		(start 395.223746 -274.997164)
		(end 395.264386 -274.956524)
		(width 0.09525)
		(layer "In13.Cu")
		(net "M_H_CPU0_SB_DQS_DP<0>")
	)
	(segment
		(start 423.741342 -285.155894)
		(end 424.012106 -284.88513)
		(width 0.16002)
		(layer "In13.Cu")
		(net "M_H_CPU0_SB_DQS_DP<0>")
	)
	(segment
		(start 403.262338 -277.589234)
		(end 404.247858 -277.589234)
		(width 0.16002)
		(layer "In13.Cu")
		(net "M_H_CPU0_SB_DQS_DP<0>")
	)
	(segment
		(start 416.24123 -283.868622)
		(end 416.941254 -283.868622)
		(width 0.16002)
		(layer "In13.Cu")
		(net "M_H_CPU0_SB_DQS_DP<0>")
	)
	(segment
		(start 390.744964 -276.036024)
		(end 390.753346 -276.031198)
		(width 0.09525)
		(layer "In13.Cu")
		(net "M_H_CPU0_SB_DQS_DP<0>")
	)
	(segment
		(start 391.31621 -276.031198)
		(end 391.324592 -276.036024)
		(width 0.09525)
		(layer "In13.Cu")
		(net "M_H_CPU0_SB_DQS_DP<0>")
	)
	(segment
		(start 395.717268 -274.897596)
		(end 400.5707 -274.897596)
		(width 0.16002)
		(layer "In13.Cu")
		(net "M_H_CPU0_SB_DQS_DP<0>")
	)
	(segment
		(start 415.904172 -284.20568)
		(end 416.24123 -283.868622)
		(width 0.16002)
		(layer "In13.Cu")
		(net "M_H_CPU0_SB_DQS_DP<0>")
	)
	(segment
		(start 387.556248 -276.031198)
		(end 387.56463 -276.036024)
		(width 0.09525)
		(layer "In13.Cu")
		(net "M_H_CPU0_SB_DQS_DP<0>")
	)
	(segment
		(start 392.631676 -276.031198)
		(end 392.652504 -276.019006)
		(width 0.09525)
		(layer "In13.Cu")
		(net "M_H_CPU0_SB_DQS_DP<0>")
	)
	(segment
		(start 418.159692 -284.738572)
		(end 420.46398 -284.738572)
		(width 0.16002)
		(layer "In13.Cu")
		(net "M_H_CPU0_SB_DQS_DP<0>")
	)
	(segment
		(start 395.264386 -274.956524)
		(end 395.634718 -274.956524)
		(width 0.09525)
		(layer "In13.Cu")
		(net "M_H_CPU0_SB_DQS_DP<0>")
	)
	(segment
		(start 395.634718 -274.956524)
		(end 395.693646 -274.897596)
		(width 0.09525)
		(layer "In13.Cu")
		(net "M_H_CPU0_SB_DQS_DP<0>")
	)
	(segment
		(start 413.92729 -285.35503)
		(end 414.71215 -284.57017)
		(width 0.16002)
		(layer "In13.Cu")
		(net "M_H_CPU0_SB_DQS_DP<0>")
	)
	(segment
		(start 388.496302 -276.031198)
		(end 388.504684 -276.036024)
		(width 0.09525)
		(layer "In13.Cu")
		(net "M_H_CPU0_SB_DQS_DP<0>")
	)
	(segment
		(start 417.753038 -284.57017)
		(end 418.159692 -284.738572)
		(width 0.16002)
		(layer "In13.Cu")
		(net "M_H_CPU0_SB_DQS_DP<0>")
	)
	(segment
		(start 412.887414 -284.61843)
		(end 413.624014 -285.35503)
		(width 0.16002)
		(layer "In13.Cu")
		(net "M_H_CPU0_SB_DQS_DP<0>")
	)
	(arc
		(start 386.993384 -276.031198)
		(mid 387.274816 -275.955443)
		(end 387.556248 -276.031198)
		(width 0.09525)
		(layer "In13.Cu")
		(net "M_H_CPU0_SB_DQS_DP<0>")
	)
	(arc
		(start 385.67614 -276.031198)
		(mid 385.859915 -276.08197)
		(end 386.044948 -276.036024)
		(width 0.09525)
		(layer "In13.Cu")
		(net "M_H_CPU0_SB_DQS_DP<0>")
	)
	(arc
		(start 388.873492 -276.031198)
		(mid 389.154924 -275.955443)
		(end 389.436356 -276.031198)
		(width 0.09525)
		(layer "In13.Cu")
		(net "M_H_CPU0_SB_DQS_DP<0>")
	)
	(arc
		(start 386.05333 -276.031198)
		(mid 386.334762 -275.955443)
		(end 386.616194 -276.031198)
		(width 0.09525)
		(layer "In13.Cu")
		(net "M_H_CPU0_SB_DQS_DP<0>")
	)
	(arc
		(start 391.6934 -276.031198)
		(mid 391.962354 -275.95546)
		(end 392.23442 -276.019006)
		(width 0.09525)
		(layer "In13.Cu")
		(net "M_H_CPU0_SB_DQS_DP<0>")
	)
	(arc
		(start 384.73634 -276.031198)
		(mid 384.924808 -276.081875)
		(end 385.113276 -276.031198)
		(width 0.09525)
		(layer "In13.Cu")
		(net "M_H_CPU0_SB_DQS_DP<0>")
	)
	(arc
		(start 393.195048 -276.031452)
		(mid 393.432384 -276.079294)
		(end 393.649708 -275.972524)
		(width 0.09525)
		(layer "In13.Cu")
		(net "M_H_CPU0_SB_DQS_DP<0>")
	)
	(arc
		(start 389.436356 -276.031198)
		(mid 389.624824 -276.081875)
		(end 389.813292 -276.031198)
		(width 0.09525)
		(layer "In13.Cu")
		(net "M_H_CPU0_SB_DQS_DP<0>")
	)
	(arc
		(start 389.813292 -276.031198)
		(mid 390.094724 -275.955443)
		(end 390.376156 -276.031198)
		(width 0.09525)
		(layer "In13.Cu")
		(net "M_H_CPU0_SB_DQS_DP<0>")
	)
	(arc
		(start 387.933438 -276.031198)
		(mid 388.21487 -275.955443)
		(end 388.496302 -276.031198)
		(width 0.09525)
		(layer "In13.Cu")
		(net "M_H_CPU0_SB_DQS_DP<0>")
	)
	(arc
		(start 392.267186 -276.038056)
		(mid 392.450313 -276.081768)
		(end 392.631676 -276.031198)
		(width 0.09525)
		(layer "In13.Cu")
		(net "M_H_CPU0_SB_DQS_DP<0>")
	)
	(arc
		(start 387.56463 -276.036024)
		(mid 387.749662 -276.081938)
		(end 387.933438 -276.031198)
		(width 0.09525)
		(layer "In13.Cu")
		(net "M_H_CPU0_SB_DQS_DP<0>")
	)
	(arc
		(start 386.616194 -276.031198)
		(mid 386.799969 -276.08197)
		(end 386.985002 -276.036024)
		(width 0.09525)
		(layer "In13.Cu")
		(net "M_H_CPU0_SB_DQS_DP<0>")
	)
	(arc
		(start 390.753346 -276.031198)
		(mid 391.034778 -275.955443)
		(end 391.31621 -276.031198)
		(width 0.09525)
		(layer "In13.Cu")
		(net "M_H_CPU0_SB_DQS_DP<0>")
	)
	(arc
		(start 390.376156 -276.031198)
		(mid 390.559931 -276.08197)
		(end 390.744964 -276.036024)
		(width 0.09525)
		(layer "In13.Cu")
		(net "M_H_CPU0_SB_DQS_DP<0>")
	)
	(arc
		(start 384.239516 -275.998178)
		(mid 384.249764 -275.994015)
		(end 384.26009 -275.99005)
		(width 0.09525)
		(layer "In13.Cu")
		(net "M_H_CPU0_SB_DQS_DP<0>")
	)
	(arc
		(start 385.113276 -276.031198)
		(mid 385.394708 -275.955443)
		(end 385.67614 -276.031198)
		(width 0.09525)
		(layer "In13.Cu")
		(net "M_H_CPU0_SB_DQS_DP<0>")
	)
	(arc
		(start 392.654028 -276.01926)
		(mid 392.926091 -275.955793)
		(end 393.195048 -276.031452)
		(width 0.09525)
		(layer "In13.Cu")
		(net "M_H_CPU0_SB_DQS_DP<0>")
	)
	(arc
		(start 384.26009 -275.99005)
		(mid 384.502832 -275.95728)
		(end 384.73634 -276.031198)
		(width 0.09525)
		(layer "In13.Cu")
		(net "M_H_CPU0_SB_DQS_DP<0>")
	)
	(arc
		(start 391.324592 -276.036024)
		(mid 391.509624 -276.081938)
		(end 391.6934 -276.031198)
		(width 0.09525)
		(layer "In13.Cu")
		(net "M_H_CPU0_SB_DQS_DP<0>")
	)
	(arc
		(start 388.504684 -276.036024)
		(mid 388.689716 -276.081938)
		(end 388.873492 -276.031198)
		(width 0.09525)
		(layer "In13.Cu")
		(net "M_H_CPU0_SB_DQS_DP<0>")
	)
	(segment
		(start 383.988056 -271.39011)
		(end 384.454908 -271.656048)
		(width 0.12954)
		(layer "F.Cu")
		(net "M_H_CPU0_SB_DQS_DN<9>")
	)
	(segment
		(start 395.719046 -269.55496)
		(end 395.742668 -269.55496)
		(width 0.09525)
		(layer "In13.Cu")
		(net "M_H_CPU0_SB_DQS_DN<9>")
	)
	(segment
		(start 392.145774 -271.321276)
		(end 392.15314 -271.325086)
		(width 0.09525)
		(layer "In13.Cu")
		(net "M_H_CPU0_SB_DQS_DN<9>")
	)
	(segment
		(start 417.885372 -275.522436)
		(end 418.325046 -275.96211)
		(width 0.16002)
		(layer "In13.Cu")
		(net "M_H_CPU0_SB_DQS_DN<9>")
	)
	(segment
		(start 392.726164 -271.330928)
		(end 392.764264 -271.30883)
		(width 0.09525)
		(layer "In13.Cu")
		(net "M_H_CPU0_SB_DQS_DN<9>")
	)
	(segment
		(start 393.196318 -270.520922)
		(end 393.196318 -270.520414)
		(width 0.09525)
		(layer "In13.Cu")
		(net "M_H_CPU0_SB_DQS_DN<9>")
	)
	(segment
		(start 414.570164 -275.522436)
		(end 415.443924 -275.522436)
		(width 0.16002)
		(layer "In13.Cu")
		(net "M_H_CPU0_SB_DQS_DN<9>")
	)
	(segment
		(start 388.394956 -271.326102)
		(end 388.403338 -271.330928)
		(width 0.09525)
		(layer "In13.Cu")
		(net "M_H_CPU0_SB_DQS_DN<9>")
	)
	(segment
		(start 423.089832 -276.580854)
		(end 423.531792 -276.138894)
		(width 0.16002)
		(layer "In13.Cu")
		(net "M_H_CPU0_SB_DQS_DN<9>")
	)
	(segment
		(start 393.163806 -270.539718)
		(end 393.176506 -270.532606)
		(width 0.09525)
		(layer "In13.Cu")
		(net "M_H_CPU0_SB_DQS_DN<9>")
	)
	(segment
		(start 384.634994 -271.326102)
		(end 384.643376 -271.330928)
		(width 0.09525)
		(layer "In13.Cu")
		(net "M_H_CPU0_SB_DQS_DN<9>")
	)
	(segment
		(start 395.144752 -269.35684)
		(end 395.28369 -269.495778)
		(width 0.09525)
		(layer "In13.Cu")
		(net "M_H_CPU0_SB_DQS_DN<9>")
	)
	(segment
		(start 384.454908 -271.656048)
		(end 384.300984 -271.390618)
		(width 0.09525)
		(layer "In13.Cu")
		(net "M_H_CPU0_SB_DQS_DN<9>")
	)
	(segment
		(start 412.317184 -275.112226)
		(end 412.456884 -275.251926)
		(width 0.16002)
		(layer "In13.Cu")
		(net "M_H_CPU0_SB_DQS_DN<9>")
	)
	(segment
		(start 415.443924 -275.522436)
		(end 415.905188 -275.9837)
		(width 0.16002)
		(layer "In13.Cu")
		(net "M_H_CPU0_SB_DQS_DN<9>")
	)
	(segment
		(start 421.58666 -276.297136)
		(end 421.744902 -276.138894)
		(width 0.16002)
		(layer "In13.Cu")
		(net "M_H_CPU0_SB_DQS_DN<9>")
	)
	(segment
		(start 394.631672 -269.35684)
		(end 395.144752 -269.35684)
		(width 0.09525)
		(layer "In13.Cu")
		(net "M_H_CPU0_SB_DQS_DN<9>")
	)
	(segment
		(start 423.76598 -276.138894)
		(end 424.012106 -276.38502)
		(width 0.16002)
		(layer "In13.Cu")
		(net "M_H_CPU0_SB_DQS_DN<9>")
	)
	(segment
		(start 389.33501 -271.326102)
		(end 389.343392 -271.330928)
		(width 0.09525)
		(layer "In13.Cu")
		(net "M_H_CPU0_SB_DQS_DN<9>")
	)
	(segment
		(start 411.839664 -275.112226)
		(end 412.317184 -275.112226)
		(width 0.16002)
		(layer "In13.Cu")
		(net "M_H_CPU0_SB_DQS_DN<9>")
	)
	(segment
		(start 416.641026 -275.9837)
		(end 417.10229 -275.522436)
		(width 0.16002)
		(layer "In13.Cu")
		(net "M_H_CPU0_SB_DQS_DN<9>")
	)
	(segment
		(start 405.074882 -269.55496)
		(end 407.67127 -272.151348)
		(width 0.16002)
		(layer "In13.Cu")
		(net "M_H_CPU0_SB_DQS_DN<9>")
	)
	(segment
		(start 395.659864 -269.495778)
		(end 395.719046 -269.55496)
		(width 0.09525)
		(layer "In13.Cu")
		(net "M_H_CPU0_SB_DQS_DN<9>")
	)
	(segment
		(start 417.10229 -275.522436)
		(end 417.885372 -275.522436)
		(width 0.16002)
		(layer "In13.Cu")
		(net "M_H_CPU0_SB_DQS_DN<9>")
	)
	(segment
		(start 395.28369 -269.495778)
		(end 395.659864 -269.495778)
		(width 0.09525)
		(layer "In13.Cu")
		(net "M_H_CPU0_SB_DQS_DN<9>")
	)
	(segment
		(start 420.232078 -275.96211)
		(end 420.567104 -276.297136)
		(width 0.16002)
		(layer "In13.Cu")
		(net "M_H_CPU0_SB_DQS_DN<9>")
	)
	(segment
		(start 421.89273 -276.138894)
		(end 422.33469 -276.580854)
		(width 0.16002)
		(layer "In13.Cu")
		(net "M_H_CPU0_SB_DQS_DN<9>")
	)
	(segment
		(start 418.325046 -275.96211)
		(end 420.232078 -275.96211)
		(width 0.16002)
		(layer "In13.Cu")
		(net "M_H_CPU0_SB_DQS_DN<9>")
	)
	(segment
		(start 415.905188 -275.9837)
		(end 416.641026 -275.9837)
		(width 0.16002)
		(layer "In13.Cu")
		(net "M_H_CPU0_SB_DQS_DN<9>")
	)
	(segment
		(start 386.146294 -271.330928)
		(end 386.154676 -271.326102)
		(width 0.09525)
		(layer "In13.Cu")
		(net "M_H_CPU0_SB_DQS_DN<9>")
	)
	(segment
		(start 423.531792 -276.138894)
		(end 423.76598 -276.138894)
		(width 0.16002)
		(layer "In13.Cu")
		(net "M_H_CPU0_SB_DQS_DN<9>")
	)
	(segment
		(start 393.176506 -270.532606)
		(end 393.196318 -270.520922)
		(width 0.09525)
		(layer "In13.Cu")
		(net "M_H_CPU0_SB_DQS_DN<9>")
	)
	(segment
		(start 408.878786 -272.151348)
		(end 411.839664 -275.112226)
		(width 0.16002)
		(layer "In13.Cu")
		(net "M_H_CPU0_SB_DQS_DN<9>")
	)
	(segment
		(start 393.739878 -270.248888)
		(end 394.631672 -269.35684)
		(width 0.09525)
		(layer "In13.Cu")
		(net "M_H_CPU0_SB_DQS_DN<9>")
	)
	(segment
		(start 384.300984 -271.390618)
		(end 384.324352 -271.30375)
		(width 0.09525)
		(layer "In13.Cu")
		(net "M_H_CPU0_SB_DQS_DN<9>")
	)
	(segment
		(start 412.934404 -275.251926)
		(end 413.074104 -275.112226)
		(width 0.16002)
		(layer "In13.Cu")
		(net "M_H_CPU0_SB_DQS_DN<9>")
	)
	(segment
		(start 392.16203 -271.330166)
		(end 392.1633 -271.330928)
		(width 0.09525)
		(layer "In13.Cu")
		(net "M_H_CPU0_SB_DQS_DN<9>")
	)
	(segment
		(start 385.20624 -271.330928)
		(end 385.214622 -271.326102)
		(width 0.09525)
		(layer "In13.Cu")
		(net "M_H_CPU0_SB_DQS_DN<9>")
	)
	(segment
		(start 395.742668 -269.55496)
		(end 405.074882 -269.55496)
		(width 0.16002)
		(layer "In13.Cu")
		(net "M_H_CPU0_SB_DQS_DN<9>")
	)
	(segment
		(start 420.567104 -276.297136)
		(end 421.58666 -276.297136)
		(width 0.16002)
		(layer "In13.Cu")
		(net "M_H_CPU0_SB_DQS_DN<9>")
	)
	(segment
		(start 392.15314 -271.325086)
		(end 392.16203 -271.330166)
		(width 0.09525)
		(layer "In13.Cu")
		(net "M_H_CPU0_SB_DQS_DN<9>")
	)
	(segment
		(start 412.456884 -275.251926)
		(end 412.934404 -275.251926)
		(width 0.16002)
		(layer "In13.Cu")
		(net "M_H_CPU0_SB_DQS_DN<9>")
	)
	(segment
		(start 422.33469 -276.580854)
		(end 423.089832 -276.580854)
		(width 0.16002)
		(layer "In13.Cu")
		(net "M_H_CPU0_SB_DQS_DN<9>")
	)
	(segment
		(start 407.67127 -272.151348)
		(end 408.878786 -272.151348)
		(width 0.16002)
		(layer "In13.Cu")
		(net "M_H_CPU0_SB_DQS_DN<9>")
	)
	(segment
		(start 389.906256 -271.330928)
		(end 389.914638 -271.326102)
		(width 0.09525)
		(layer "In13.Cu")
		(net "M_H_CPU0_SB_DQS_DN<9>")
	)
	(segment
		(start 414.159954 -275.112226)
		(end 414.570164 -275.522436)
		(width 0.16002)
		(layer "In13.Cu")
		(net "M_H_CPU0_SB_DQS_DN<9>")
	)
	(segment
		(start 421.744902 -276.138894)
		(end 421.89273 -276.138894)
		(width 0.16002)
		(layer "In13.Cu")
		(net "M_H_CPU0_SB_DQS_DN<9>")
	)
	(segment
		(start 413.074104 -275.112226)
		(end 414.159954 -275.112226)
		(width 0.16002)
		(layer "In13.Cu")
		(net "M_H_CPU0_SB_DQS_DN<9>")
	)
	(arc
		(start 384.643376 -271.330928)
		(mid 384.924808 -271.406683)
		(end 385.20624 -271.330928)
		(width 0.09525)
		(layer "In13.Cu")
		(net "M_H_CPU0_SB_DQS_DN<9>")
	)
	(arc
		(start 386.154676 -271.326102)
		(mid 386.339708 -271.280188)
		(end 386.523484 -271.330928)
		(width 0.09525)
		(layer "In13.Cu")
		(net "M_H_CPU0_SB_DQS_DN<9>")
	)
	(arc
		(start 389.343392 -271.330928)
		(mid 389.624824 -271.406683)
		(end 389.906256 -271.330928)
		(width 0.09525)
		(layer "In13.Cu")
		(net "M_H_CPU0_SB_DQS_DN<9>")
	)
	(arc
		(start 384.324352 -271.30375)
		(mid 384.482102 -271.281231)
		(end 384.634994 -271.326102)
		(width 0.09525)
		(layer "In13.Cu")
		(net "M_H_CPU0_SB_DQS_DN<9>")
	)
	(arc
		(start 393.324334 -270.47444)
		(mid 393.551289 -270.39701)
		(end 393.739878 -270.248888)
		(width 0.09525)
		(layer "In13.Cu")
		(net "M_H_CPU0_SB_DQS_DN<9>")
	)
	(arc
		(start 391.78611 -271.330928)
		(mid 391.964716 -271.28026)
		(end 392.145774 -271.321276)
		(width 0.09525)
		(layer "In13.Cu")
		(net "M_H_CPU0_SB_DQS_DN<9>")
	)
	(arc
		(start 388.966202 -271.330928)
		(mid 389.149977 -271.280156)
		(end 389.33501 -271.326102)
		(width 0.09525)
		(layer "In13.Cu")
		(net "M_H_CPU0_SB_DQS_DN<9>")
	)
	(arc
		(start 387.463284 -271.330928)
		(mid 387.744716 -271.406683)
		(end 388.026148 -271.330928)
		(width 0.09525)
		(layer "In13.Cu")
		(net "M_H_CPU0_SB_DQS_DN<9>")
	)
	(arc
		(start 385.214622 -271.326102)
		(mid 385.399654 -271.280188)
		(end 385.58343 -271.330928)
		(width 0.09525)
		(layer "In13.Cu")
		(net "M_H_CPU0_SB_DQS_DN<9>")
	)
	(arc
		(start 392.1633 -271.330928)
		(mid 392.444732 -271.406683)
		(end 392.726164 -271.330928)
		(width 0.09525)
		(layer "In13.Cu")
		(net "M_H_CPU0_SB_DQS_DN<9>")
	)
	(arc
		(start 390.84631 -271.330928)
		(mid 391.034778 -271.280251)
		(end 391.223246 -271.330928)
		(width 0.09525)
		(layer "In13.Cu")
		(net "M_H_CPU0_SB_DQS_DN<9>")
	)
	(arc
		(start 387.086348 -271.330928)
		(mid 387.274816 -271.280251)
		(end 387.463284 -271.330928)
		(width 0.09525)
		(layer "In13.Cu")
		(net "M_H_CPU0_SB_DQS_DN<9>")
	)
	(arc
		(start 385.58343 -271.330928)
		(mid 385.864862 -271.406683)
		(end 386.146294 -271.330928)
		(width 0.09525)
		(layer "In13.Cu")
		(net "M_H_CPU0_SB_DQS_DN<9>")
	)
	(arc
		(start 390.283446 -271.330928)
		(mid 390.564878 -271.406683)
		(end 390.84631 -271.330928)
		(width 0.09525)
		(layer "In13.Cu")
		(net "M_H_CPU0_SB_DQS_DN<9>")
	)
	(arc
		(start 386.523484 -271.330928)
		(mid 386.804916 -271.406683)
		(end 387.086348 -271.330928)
		(width 0.09525)
		(layer "In13.Cu")
		(net "M_H_CPU0_SB_DQS_DN<9>")
	)
	(arc
		(start 388.403338 -271.330928)
		(mid 388.68477 -271.406683)
		(end 388.966202 -271.330928)
		(width 0.09525)
		(layer "In13.Cu")
		(net "M_H_CPU0_SB_DQS_DN<9>")
	)
	(arc
		(start 393.196318 -270.520414)
		(mid 393.258227 -270.491577)
		(end 393.324334 -270.47444)
		(width 0.09525)
		(layer "In13.Cu")
		(net "M_H_CPU0_SB_DQS_DN<9>")
	)
	(arc
		(start 388.026148 -271.330928)
		(mid 388.209923 -271.280156)
		(end 388.394956 -271.326102)
		(width 0.09525)
		(layer "In13.Cu")
		(net "M_H_CPU0_SB_DQS_DN<9>")
	)
	(arc
		(start 392.764264 -271.30883)
		(mid 392.942714 -271.10736)
		(end 393.007088 -270.846042)
		(width 0.09525)
		(layer "In13.Cu")
		(net "M_H_CPU0_SB_DQS_DN<9>")
	)
	(arc
		(start 393.007088 -270.846042)
		(mid 393.048545 -270.674002)
		(end 393.163806 -270.539718)
		(width 0.09525)
		(layer "In13.Cu")
		(net "M_H_CPU0_SB_DQS_DN<9>")
	)
	(arc
		(start 389.914638 -271.326102)
		(mid 390.09967 -271.280188)
		(end 390.283446 -271.330928)
		(width 0.09525)
		(layer "In13.Cu")
		(net "M_H_CPU0_SB_DQS_DN<9>")
	)
	(arc
		(start 391.223246 -271.330928)
		(mid 391.504678 -271.406683)
		(end 391.78611 -271.330928)
		(width 0.09525)
		(layer "In13.Cu")
		(net "M_H_CPU0_SB_DQS_DN<9>")
	)
	(segment
		(start 382.107948 -290.83)
		(end 382.5748 -291.095938)
		(width 0.12954)
		(layer "F.Cu")
		(net "M_H_CPU0_SB_DQS_DN<8>")
	)
	(segment
		(start 412.290006 -314.38342)
		(end 411.470348 -314.38342)
		(width 0.16002)
		(layer "In13.Cu")
		(net "M_H_CPU0_SB_DQS_DN<8>")
	)
	(segment
		(start 394.92809 -294.994584)
		(end 394.416534 -294.48379)
		(width 0.09525)
		(layer "In13.Cu")
		(net "M_H_CPU0_SB_DQS_DN<8>")
	)
	(segment
		(start 413.876236 -314.695332)
		(end 412.601918 -314.695332)
		(width 0.16002)
		(layer "In13.Cu")
		(net "M_H_CPU0_SB_DQS_DN<8>")
	)
	(segment
		(start 419.698678 -313.998356)
		(end 417.672012 -313.998356)
		(width 0.16002)
		(layer "In13.Cu")
		(net "M_H_CPU0_SB_DQS_DN<8>")
	)
	(segment
		(start 416.1409 -314.372752)
		(end 415.500312 -313.732164)
		(width 0.16002)
		(layer "In13.Cu")
		(net "M_H_CPU0_SB_DQS_DN<8>")
	)
	(segment
		(start 392.1633 -291.421058)
		(end 392.154918 -291.425884)
		(width 0.09525)
		(layer "In13.Cu")
		(net "M_H_CPU0_SB_DQS_DN<8>")
	)
	(segment
		(start 385.214622 -291.425884)
		(end 385.20624 -291.421058)
		(width 0.09525)
		(layer "In13.Cu")
		(net "M_H_CPU0_SB_DQS_DN<8>")
	)
	(segment
		(start 394.10894 -293.835328)
		(end 394.107416 -293.834312)
		(width 0.09525)
		(layer "In13.Cu")
		(net "M_H_CPU0_SB_DQS_DN<8>")
	)
	(segment
		(start 394.107416 -293.834312)
		(end 394.1064 -293.833804)
		(width 0.09525)
		(layer "In13.Cu")
		(net "M_H_CPU0_SB_DQS_DN<8>")
	)
	(segment
		(start 411.470348 -314.38342)
		(end 410.937456 -314.916312)
		(width 0.16002)
		(layer "In13.Cu")
		(net "M_H_CPU0_SB_DQS_DN<8>")
	)
	(segment
		(start 393.673838 -292.747192)
		(end 393.130532 -292.203886)
		(width 0.09525)
		(layer "In13.Cu")
		(net "M_H_CPU0_SB_DQS_DN<8>")
	)
	(segment
		(start 416.30092 -315.021468)
		(end 416.1409 -314.861448)
		(width 0.16002)
		(layer "In13.Cu")
		(net "M_H_CPU0_SB_DQS_DN<8>")
	)
	(segment
		(start 408.822652 -314.916312)
		(end 395.304518 -301.398178)
		(width 0.16002)
		(layer "In13.Cu")
		(net "M_H_CPU0_SB_DQS_DN<8>")
	)
	(segment
		(start 410.469588 -314.296552)
		(end 410.13253 -313.959494)
		(width 0.16002)
		(layer "In13.Cu")
		(net "M_H_CPU0_SB_DQS_DN<8>")
	)
	(segment
		(start 389.343392 -291.421058)
		(end 389.33501 -291.425884)
		(width 0.09525)
		(layer "In13.Cu")
		(net "M_H_CPU0_SB_DQS_DN<8>")
	)
	(segment
		(start 410.469588 -314.756292)
		(end 410.469588 -314.296552)
		(width 0.16002)
		(layer "In13.Cu")
		(net "M_H_CPU0_SB_DQS_DN<8>")
	)
	(segment
		(start 394.416534 -294.48379)
		(end 394.416534 -294.335962)
		(width 0.09525)
		(layer "In13.Cu")
		(net "M_H_CPU0_SB_DQS_DN<8>")
	)
	(segment
		(start 394.120878 -293.842186)
		(end 394.10894 -293.835328)
		(width 0.09525)
		(layer "In13.Cu")
		(net "M_H_CPU0_SB_DQS_DN<8>")
	)
	(segment
		(start 395.304518 -295.286176)
		(end 395.028166 -295.01084)
		(width 0.16002)
		(layer "In13.Cu")
		(net "M_H_CPU0_SB_DQS_DN<8>")
	)
	(segment
		(start 393.947142 -293.525956)
		(end 393.947142 -293.407084)
		(width 0.09525)
		(layer "In13.Cu")
		(net "M_H_CPU0_SB_DQS_DN<8>")
	)
	(segment
		(start 417.174934 -315.021468)
		(end 416.30092 -315.021468)
		(width 0.16002)
		(layer "In13.Cu")
		(net "M_H_CPU0_SB_DQS_DN<8>")
	)
	(segment
		(start 395.011402 -294.994076)
		(end 394.92809 -294.994584)
		(width 0.09525)
		(layer "In13.Cu")
		(net "M_H_CPU0_SB_DQS_DN<8>")
	)
	(segment
		(start 383.703322 -291.421058)
		(end 383.69494 -291.425884)
		(width 0.09525)
		(layer "In13.Cu")
		(net "M_H_CPU0_SB_DQS_DN<8>")
	)
	(segment
		(start 410.629608 -314.916312)
		(end 410.469588 -314.756292)
		(width 0.16002)
		(layer "In13.Cu")
		(net "M_H_CPU0_SB_DQS_DN<8>")
	)
	(segment
		(start 395.304518 -301.398178)
		(end 395.304518 -295.286176)
		(width 0.16002)
		(layer "In13.Cu")
		(net "M_H_CPU0_SB_DQS_DN<8>")
	)
	(segment
		(start 394.1064 -293.833804)
		(end 394.104876 -293.832788)
		(width 0.09525)
		(layer "In13.Cu")
		(net "M_H_CPU0_SB_DQS_DN<8>")
	)
	(segment
		(start 410.13253 -313.959494)
		(end 409.534106 -313.959494)
		(width 0.16002)
		(layer "In13.Cu")
		(net "M_H_CPU0_SB_DQS_DN<8>")
	)
	(segment
		(start 409.534106 -313.959494)
		(end 409.197048 -314.296552)
		(width 0.16002)
		(layer "In13.Cu")
		(net "M_H_CPU0_SB_DQS_DN<8>")
	)
	(segment
		(start 382.728724 -291.361368)
		(end 382.5748 -291.095938)
		(width 0.09525)
		(layer "In13.Cu")
		(net "M_H_CPU0_SB_DQS_DN<8>")
	)
	(segment
		(start 384.643376 -291.421058)
		(end 384.634994 -291.425884)
		(width 0.09525)
		(layer "In13.Cu")
		(net "M_H_CPU0_SB_DQS_DN<8>")
	)
	(segment
		(start 392.764264 -291.443156)
		(end 392.726164 -291.421058)
		(width 0.09525)
		(layer "In13.Cu")
		(net "M_H_CPU0_SB_DQS_DN<8>")
	)
	(segment
		(start 382.829562 -291.388038)
		(end 382.728724 -291.361368)
		(width 0.09525)
		(layer "In13.Cu")
		(net "M_H_CPU0_SB_DQS_DN<8>")
	)
	(segment
		(start 388.403338 -291.421058)
		(end 388.394956 -291.425884)
		(width 0.09525)
		(layer "In13.Cu")
		(net "M_H_CPU0_SB_DQS_DN<8>")
	)
	(segment
		(start 410.937456 -314.916312)
		(end 410.629608 -314.916312)
		(width 0.16002)
		(layer "In13.Cu")
		(net "M_H_CPU0_SB_DQS_DN<8>")
	)
	(segment
		(start 395.028166 -295.01084)
		(end 395.011402 -294.994076)
		(width 0.09525)
		(layer "In13.Cu")
		(net "M_H_CPU0_SB_DQS_DN<8>")
	)
	(segment
		(start 416.1409 -314.861448)
		(end 416.1409 -314.372752)
		(width 0.16002)
		(layer "In13.Cu")
		(net "M_H_CPU0_SB_DQS_DN<8>")
	)
	(segment
		(start 389.914638 -291.425884)
		(end 389.906256 -291.421058)
		(width 0.09525)
		(layer "In13.Cu")
		(net "M_H_CPU0_SB_DQS_DN<8>")
	)
	(segment
		(start 417.334954 -314.861448)
		(end 417.174934 -315.021468)
		(width 0.16002)
		(layer "In13.Cu")
		(net "M_H_CPU0_SB_DQS_DN<8>")
	)
	(segment
		(start 394.104876 -293.832788)
		(end 394.104622 -293.832788)
		(width 0.09525)
		(layer "In13.Cu")
		(net "M_H_CPU0_SB_DQS_DN<8>")
	)
	(segment
		(start 412.601918 -314.695332)
		(end 412.290006 -314.38342)
		(width 0.16002)
		(layer "In13.Cu")
		(net "M_H_CPU0_SB_DQS_DN<8>")
	)
	(segment
		(start 419.912038 -313.784996)
		(end 419.698678 -313.998356)
		(width 0.16002)
		(layer "In13.Cu")
		(net "M_H_CPU0_SB_DQS_DN<8>")
	)
	(segment
		(start 409.197048 -314.296552)
		(end 409.197048 -314.756292)
		(width 0.16002)
		(layer "In13.Cu")
		(net "M_H_CPU0_SB_DQS_DN<8>")
	)
	(segment
		(start 414.839404 -313.732164)
		(end 413.876236 -314.695332)
		(width 0.16002)
		(layer "In13.Cu")
		(net "M_H_CPU0_SB_DQS_DN<8>")
	)
	(segment
		(start 417.672012 -313.998356)
		(end 417.334954 -314.335414)
		(width 0.16002)
		(layer "In13.Cu")
		(net "M_H_CPU0_SB_DQS_DN<8>")
	)
	(segment
		(start 415.500312 -313.732164)
		(end 414.839404 -313.732164)
		(width 0.16002)
		(layer "In13.Cu")
		(net "M_H_CPU0_SB_DQS_DN<8>")
	)
	(segment
		(start 409.197048 -314.756292)
		(end 409.037028 -314.916312)
		(width 0.16002)
		(layer "In13.Cu")
		(net "M_H_CPU0_SB_DQS_DN<8>")
	)
	(segment
		(start 409.037028 -314.916312)
		(end 408.822652 -314.916312)
		(width 0.16002)
		(layer "In13.Cu")
		(net "M_H_CPU0_SB_DQS_DN<8>")
	)
	(segment
		(start 394.174726 -293.87419)
		(end 394.120878 -293.842186)
		(width 0.09525)
		(layer "In13.Cu")
		(net "M_H_CPU0_SB_DQS_DN<8>")
	)
	(segment
		(start 417.334954 -314.335414)
		(end 417.334954 -314.861448)
		(width 0.16002)
		(layer "In13.Cu")
		(net "M_H_CPU0_SB_DQS_DN<8>")
	)
	(segment
		(start 386.154676 -291.425884)
		(end 386.146294 -291.421058)
		(width 0.09525)
		(layer "In13.Cu")
		(net "M_H_CPU0_SB_DQS_DN<8>")
	)
	(arc
		(start 391.78611 -291.421058)
		(mid 391.504678 -291.345303)
		(end 391.223246 -291.421058)
		(width 0.09525)
		(layer "In13.Cu")
		(net "M_H_CPU0_SB_DQS_DN<8>")
	)
	(arc
		(start 393.130532 -292.203886)
		(mid 393.039194 -292.067189)
		(end 393.007088 -291.905944)
		(width 0.09525)
		(layer "In13.Cu")
		(net "M_H_CPU0_SB_DQS_DN<8>")
	)
	(arc
		(start 392.154918 -291.425884)
		(mid 391.969886 -291.471798)
		(end 391.78611 -291.421058)
		(width 0.09525)
		(layer "In13.Cu")
		(net "M_H_CPU0_SB_DQS_DN<8>")
	)
	(arc
		(start 383.326132 -291.421058)
		(mid 383.092588 -291.347352)
		(end 382.849882 -291.380164)
		(width 0.09525)
		(layer "In13.Cu")
		(net "M_H_CPU0_SB_DQS_DN<8>")
	)
	(arc
		(start 384.634994 -291.425884)
		(mid 384.449962 -291.471798)
		(end 384.266186 -291.421058)
		(width 0.09525)
		(layer "In13.Cu")
		(net "M_H_CPU0_SB_DQS_DN<8>")
	)
	(arc
		(start 385.20624 -291.421058)
		(mid 384.924808 -291.345303)
		(end 384.643376 -291.421058)
		(width 0.09525)
		(layer "In13.Cu")
		(net "M_H_CPU0_SB_DQS_DN<8>")
	)
	(arc
		(start 389.906256 -291.421058)
		(mid 389.624824 -291.345303)
		(end 389.343392 -291.421058)
		(width 0.09525)
		(layer "In13.Cu")
		(net "M_H_CPU0_SB_DQS_DN<8>")
	)
	(arc
		(start 390.84631 -291.421058)
		(mid 390.564878 -291.345303)
		(end 390.283446 -291.421058)
		(width 0.09525)
		(layer "In13.Cu")
		(net "M_H_CPU0_SB_DQS_DN<8>")
	)
	(arc
		(start 393.947142 -293.407084)
		(mid 393.876107 -293.049965)
		(end 393.673838 -292.747192)
		(width 0.09525)
		(layer "In13.Cu")
		(net "M_H_CPU0_SB_DQS_DN<8>")
	)
	(arc
		(start 388.026148 -291.421058)
		(mid 387.744716 -291.345303)
		(end 387.463284 -291.421058)
		(width 0.09525)
		(layer "In13.Cu")
		(net "M_H_CPU0_SB_DQS_DN<8>")
	)
	(arc
		(start 386.146294 -291.421058)
		(mid 385.864862 -291.345303)
		(end 385.58343 -291.421058)
		(width 0.09525)
		(layer "In13.Cu")
		(net "M_H_CPU0_SB_DQS_DN<8>")
	)
	(arc
		(start 391.223246 -291.421058)
		(mid 391.034778 -291.471735)
		(end 390.84631 -291.421058)
		(width 0.09525)
		(layer "In13.Cu")
		(net "M_H_CPU0_SB_DQS_DN<8>")
	)
	(arc
		(start 387.463284 -291.421058)
		(mid 387.274816 -291.471735)
		(end 387.086348 -291.421058)
		(width 0.09525)
		(layer "In13.Cu")
		(net "M_H_CPU0_SB_DQS_DN<8>")
	)
	(arc
		(start 385.58343 -291.421058)
		(mid 385.399655 -291.47183)
		(end 385.214622 -291.425884)
		(width 0.09525)
		(layer "In13.Cu")
		(net "M_H_CPU0_SB_DQS_DN<8>")
	)
	(arc
		(start 383.69494 -291.425884)
		(mid 383.509908 -291.471798)
		(end 383.326132 -291.421058)
		(width 0.09525)
		(layer "In13.Cu")
		(net "M_H_CPU0_SB_DQS_DN<8>")
	)
	(arc
		(start 386.523484 -291.421058)
		(mid 386.339709 -291.47183)
		(end 386.154676 -291.425884)
		(width 0.09525)
		(layer "In13.Cu")
		(net "M_H_CPU0_SB_DQS_DN<8>")
	)
	(arc
		(start 389.33501 -291.425884)
		(mid 389.149978 -291.471798)
		(end 388.966202 -291.421058)
		(width 0.09525)
		(layer "In13.Cu")
		(net "M_H_CPU0_SB_DQS_DN<8>")
	)
	(arc
		(start 393.007088 -291.905944)
		(mid 392.942691 -291.644638)
		(end 392.764264 -291.443156)
		(width 0.09525)
		(layer "In13.Cu")
		(net "M_H_CPU0_SB_DQS_DN<8>")
	)
	(arc
		(start 382.849882 -291.380164)
		(mid 382.839683 -291.384001)
		(end 382.829562 -291.388038)
		(width 0.09525)
		(layer "In13.Cu")
		(net "M_H_CPU0_SB_DQS_DN<8>")
	)
	(arc
		(start 388.966202 -291.421058)
		(mid 388.68477 -291.345303)
		(end 388.403338 -291.421058)
		(width 0.09525)
		(layer "In13.Cu")
		(net "M_H_CPU0_SB_DQS_DN<8>")
	)
	(arc
		(start 388.394956 -291.425884)
		(mid 388.209924 -291.471798)
		(end 388.026148 -291.421058)
		(width 0.09525)
		(layer "In13.Cu")
		(net "M_H_CPU0_SB_DQS_DN<8>")
	)
	(arc
		(start 387.086348 -291.421058)
		(mid 386.804916 -291.345303)
		(end 386.523484 -291.421058)
		(width 0.09525)
		(layer "In13.Cu")
		(net "M_H_CPU0_SB_DQS_DN<8>")
	)
	(arc
		(start 392.726164 -291.421058)
		(mid 392.444732 -291.345303)
		(end 392.1633 -291.421058)
		(width 0.09525)
		(layer "In13.Cu")
		(net "M_H_CPU0_SB_DQS_DN<8>")
	)
	(arc
		(start 384.266186 -291.421058)
		(mid 383.984754 -291.345303)
		(end 383.703322 -291.421058)
		(width 0.09525)
		(layer "In13.Cu")
		(net "M_H_CPU0_SB_DQS_DN<8>")
	)
	(arc
		(start 394.416534 -294.335962)
		(mid 394.352426 -294.075333)
		(end 394.174726 -293.87419)
		(width 0.09525)
		(layer "In13.Cu")
		(net "M_H_CPU0_SB_DQS_DN<8>")
	)
	(arc
		(start 390.283446 -291.421058)
		(mid 390.099671 -291.47183)
		(end 389.914638 -291.425884)
		(width 0.09525)
		(layer "In13.Cu")
		(net "M_H_CPU0_SB_DQS_DN<8>")
	)
	(arc
		(start 394.104622 -293.832788)
		(mid 393.988824 -293.698394)
		(end 393.947142 -293.525956)
		(width 0.09525)
		(layer "In13.Cu")
		(net "M_H_CPU0_SB_DQS_DN<8>")
	)
	(segment
		(start 382.107948 -285.970218)
		(end 382.5748 -286.236156)
		(width 0.12954)
		(layer "F.Cu")
		(net "M_H_CPU0_SB_DQS_DN<7>")
	)
	(segment
		(start 405.485854 -302.307498)
		(end 405.711914 -302.307498)
		(width 0.16002)
		(layer "In13.Cu")
		(net "M_H_CPU0_SB_DQS_DN<7>")
	)
	(segment
		(start 389.906256 -286.561276)
		(end 389.914638 -286.566102)
		(width 0.09525)
		(layer "In13.Cu")
		(net "M_H_CPU0_SB_DQS_DN<7>")
	)
	(segment
		(start 405.385016 -301.069248)
		(end 405.385016 -301.545752)
		(width 0.16002)
		(layer "In13.Cu")
		(net "M_H_CPU0_SB_DQS_DN<7>")
	)
	(segment
		(start 410.563568 -304.60315)
		(end 410.900626 -304.940208)
		(width 0.16002)
		(layer "In13.Cu")
		(net "M_H_CPU0_SB_DQS_DN<7>")
	)
	(segment
		(start 404.888954 -300.573186)
		(end 405.385016 -301.069248)
		(width 0.16002)
		(layer "In13.Cu")
		(net "M_H_CPU0_SB_DQS_DN<7>")
	)
	(segment
		(start 404.195026 -300.79061)
		(end 404.41245 -300.573186)
		(width 0.16002)
		(layer "In13.Cu")
		(net "M_H_CPU0_SB_DQS_DN<7>")
	)
	(segment
		(start 410.900626 -305.179984)
		(end 411.060646 -305.340004)
		(width 0.16002)
		(layer "In13.Cu")
		(net "M_H_CPU0_SB_DQS_DN<7>")
	)
	(segment
		(start 407.898092 -303.550066)
		(end 408.394154 -304.046128)
		(width 0.16002)
		(layer "In13.Cu")
		(net "M_H_CPU0_SB_DQS_DN<7>")
	)
	(segment
		(start 406.901904 -303.06264)
		(end 406.68702 -303.277524)
		(width 0.16002)
		(layer "In13.Cu")
		(net "M_H_CPU0_SB_DQS_DN<7>")
	)
	(segment
		(start 418.006276 -304.713894)
		(end 419.633146 -304.713894)
		(width 0.16002)
		(layer "In13.Cu")
		(net "M_H_CPU0_SB_DQS_DN<7>")
	)
	(segment
		(start 394.094208 -286.48533)
		(end 394.59027 -286.981392)
		(width 0.09525)
		(layer "In13.Cu")
		(net "M_H_CPU0_SB_DQS_DN<7>")
	)
	(segment
		(start 388.394956 -286.566102)
		(end 388.403338 -286.561276)
		(width 0.09525)
		(layer "In13.Cu")
		(net "M_H_CPU0_SB_DQS_DN<7>")
	)
	(segment
		(start 405.711914 -302.307498)
		(end 405.929338 -302.090074)
		(width 0.16002)
		(layer "In13.Cu")
		(net "M_H_CPU0_SB_DQS_DN<7>")
	)
	(segment
		(start 409.863544 -304.60315)
		(end 410.563568 -304.60315)
		(width 0.16002)
		(layer "In13.Cu")
		(net "M_H_CPU0_SB_DQS_DN<7>")
	)
	(segment
		(start 405.167592 -301.763176)
		(end 405.167592 -301.989236)
		(width 0.16002)
		(layer "In13.Cu")
		(net "M_H_CPU0_SB_DQS_DN<7>")
	)
	(segment
		(start 409.366466 -305.340004)
		(end 409.526486 -305.179984)
		(width 0.16002)
		(layer "In13.Cu")
		(net "M_H_CPU0_SB_DQS_DN<7>")
	)
	(segment
		(start 395.75867 -287.589722)
		(end 395.84249 -287.589722)
		(width 0.09525)
		(layer "In13.Cu")
		(net "M_H_CPU0_SB_DQS_DN<7>")
	)
	(segment
		(start 383.69494 -286.566102)
		(end 383.703322 -286.561276)
		(width 0.09525)
		(layer "In13.Cu")
		(net "M_H_CPU0_SB_DQS_DN<7>")
	)
	(segment
		(start 386.146294 -286.561276)
		(end 386.154676 -286.566102)
		(width 0.09525)
		(layer "In13.Cu")
		(net "M_H_CPU0_SB_DQS_DN<7>")
	)
	(segment
		(start 391.78611 -286.561276)
		(end 391.794492 -286.566102)
		(width 0.09525)
		(layer "In13.Cu")
		(net "M_H_CPU0_SB_DQS_DN<7>")
	)
	(segment
		(start 385.20624 -286.561276)
		(end 385.214622 -286.566102)
		(width 0.09525)
		(layer "In13.Cu")
		(net "M_H_CPU0_SB_DQS_DN<7>")
	)
	(segment
		(start 408.394154 -304.046128)
		(end 408.394154 -304.522632)
		(width 0.16002)
		(layer "In13.Cu")
		(net "M_H_CPU0_SB_DQS_DN<7>")
	)
	(segment
		(start 406.901904 -302.586136)
		(end 406.901904 -303.06264)
		(width 0.16002)
		(layer "In13.Cu")
		(net "M_H_CPU0_SB_DQS_DN<7>")
	)
	(segment
		(start 414.729676 -304.491898)
		(end 417.78428 -304.491898)
		(width 0.16002)
		(layer "In13.Cu")
		(net "M_H_CPU0_SB_DQS_DN<7>")
	)
	(segment
		(start 395.84249 -287.589722)
		(end 395.859254 -287.606486)
		(width 0.09525)
		(layer "In13.Cu")
		(net "M_H_CPU0_SB_DQS_DN<7>")
	)
	(segment
		(start 382.5748 -286.236156)
		(end 382.728724 -286.501586)
		(width 0.09525)
		(layer "In13.Cu")
		(net "M_H_CPU0_SB_DQS_DN<7>")
	)
	(segment
		(start 408.163014 -304.979832)
		(end 408.523186 -305.340004)
		(width 0.16002)
		(layer "In13.Cu")
		(net "M_H_CPU0_SB_DQS_DN<7>")
	)
	(segment
		(start 406.964388 -303.781206)
		(end 407.190448 -303.781206)
		(width 0.16002)
		(layer "In13.Cu")
		(net "M_H_CPU0_SB_DQS_DN<7>")
	)
	(segment
		(start 392.445748 -286.48533)
		(end 394.094208 -286.48533)
		(width 0.09525)
		(layer "In13.Cu")
		(net "M_H_CPU0_SB_DQS_DN<7>")
	)
	(segment
		(start 400.877278 -292.62451)
		(end 400.877278 -297.698922)
		(width 0.16002)
		(layer "In13.Cu")
		(net "M_H_CPU0_SB_DQS_DN<7>")
	)
	(segment
		(start 417.78428 -304.491898)
		(end 418.006276 -304.713894)
		(width 0.16002)
		(layer "In13.Cu")
		(net "M_H_CPU0_SB_DQS_DN<7>")
	)
	(segment
		(start 419.633146 -304.713894)
		(end 419.912038 -304.435002)
		(width 0.16002)
		(layer "In13.Cu")
		(net "M_H_CPU0_SB_DQS_DN<7>")
	)
	(segment
		(start 408.163014 -304.753772)
		(end 408.163014 -304.979832)
		(width 0.16002)
		(layer "In13.Cu")
		(net "M_H_CPU0_SB_DQS_DN<7>")
	)
	(segment
		(start 406.405842 -302.090074)
		(end 406.901904 -302.586136)
		(width 0.16002)
		(layer "In13.Cu")
		(net "M_H_CPU0_SB_DQS_DN<7>")
	)
	(segment
		(start 394.59027 -286.981392)
		(end 395.260322 -286.981392)
		(width 0.09525)
		(layer "In13.Cu")
		(net "M_H_CPU0_SB_DQS_DN<7>")
	)
	(segment
		(start 405.385016 -301.545752)
		(end 405.167592 -301.763176)
		(width 0.16002)
		(layer "In13.Cu")
		(net "M_H_CPU0_SB_DQS_DN<7>")
	)
	(segment
		(start 389.33501 -286.566102)
		(end 389.343392 -286.561276)
		(width 0.09525)
		(layer "In13.Cu")
		(net "M_H_CPU0_SB_DQS_DN<7>")
	)
	(segment
		(start 405.929338 -302.090074)
		(end 406.405842 -302.090074)
		(width 0.16002)
		(layer "In13.Cu")
		(net "M_H_CPU0_SB_DQS_DN<7>")
	)
	(segment
		(start 403.968966 -300.79061)
		(end 404.195026 -300.79061)
		(width 0.16002)
		(layer "In13.Cu")
		(net "M_H_CPU0_SB_DQS_DN<7>")
	)
	(segment
		(start 395.859254 -287.606486)
		(end 400.877278 -292.62451)
		(width 0.16002)
		(layer "In13.Cu")
		(net "M_H_CPU0_SB_DQS_DN<7>")
	)
	(segment
		(start 405.167592 -301.989236)
		(end 405.485854 -302.307498)
		(width 0.16002)
		(layer "In13.Cu")
		(net "M_H_CPU0_SB_DQS_DN<7>")
	)
	(segment
		(start 406.68702 -303.503838)
		(end 406.964388 -303.781206)
		(width 0.16002)
		(layer "In13.Cu")
		(net "M_H_CPU0_SB_DQS_DN<7>")
	)
	(segment
		(start 384.634994 -286.566102)
		(end 384.643376 -286.561276)
		(width 0.09525)
		(layer "In13.Cu")
		(net "M_H_CPU0_SB_DQS_DN<7>")
	)
	(segment
		(start 406.68702 -303.277524)
		(end 406.68702 -303.503838)
		(width 0.16002)
		(layer "In13.Cu")
		(net "M_H_CPU0_SB_DQS_DN<7>")
	)
	(segment
		(start 411.060646 -305.340004)
		(end 413.88157 -305.340004)
		(width 0.16002)
		(layer "In13.Cu")
		(net "M_H_CPU0_SB_DQS_DN<7>")
	)
	(segment
		(start 409.526486 -304.940208)
		(end 409.863544 -304.60315)
		(width 0.16002)
		(layer "In13.Cu")
		(net "M_H_CPU0_SB_DQS_DN<7>")
	)
	(segment
		(start 407.421588 -303.550066)
		(end 407.898092 -303.550066)
		(width 0.16002)
		(layer "In13.Cu")
		(net "M_H_CPU0_SB_DQS_DN<7>")
	)
	(segment
		(start 407.190448 -303.781206)
		(end 407.421588 -303.550066)
		(width 0.16002)
		(layer "In13.Cu")
		(net "M_H_CPU0_SB_DQS_DN<7>")
	)
	(segment
		(start 413.88157 -305.340004)
		(end 414.729676 -304.491898)
		(width 0.16002)
		(layer "In13.Cu")
		(net "M_H_CPU0_SB_DQS_DN<7>")
	)
	(segment
		(start 395.598396 -287.319466)
		(end 395.598396 -287.429448)
		(width 0.09525)
		(layer "In13.Cu")
		(net "M_H_CPU0_SB_DQS_DN<7>")
	)
	(segment
		(start 382.728724 -286.501586)
		(end 382.829562 -286.528256)
		(width 0.09525)
		(layer "In13.Cu")
		(net "M_H_CPU0_SB_DQS_DN<7>")
	)
	(segment
		(start 408.523186 -305.340004)
		(end 409.366466 -305.340004)
		(width 0.16002)
		(layer "In13.Cu")
		(net "M_H_CPU0_SB_DQS_DN<7>")
	)
	(segment
		(start 395.598396 -287.429448)
		(end 395.75867 -287.589722)
		(width 0.09525)
		(layer "In13.Cu")
		(net "M_H_CPU0_SB_DQS_DN<7>")
	)
	(segment
		(start 404.41245 -300.573186)
		(end 404.888954 -300.573186)
		(width 0.16002)
		(layer "In13.Cu")
		(net "M_H_CPU0_SB_DQS_DN<7>")
	)
	(segment
		(start 409.526486 -305.179984)
		(end 409.526486 -304.940208)
		(width 0.16002)
		(layer "In13.Cu")
		(net "M_H_CPU0_SB_DQS_DN<7>")
	)
	(segment
		(start 395.260322 -286.981392)
		(end 395.598396 -287.319466)
		(width 0.09525)
		(layer "In13.Cu")
		(net "M_H_CPU0_SB_DQS_DN<7>")
	)
	(segment
		(start 400.877278 -297.698922)
		(end 403.968966 -300.79061)
		(width 0.16002)
		(layer "In13.Cu")
		(net "M_H_CPU0_SB_DQS_DN<7>")
	)
	(segment
		(start 410.900626 -304.940208)
		(end 410.900626 -305.179984)
		(width 0.16002)
		(layer "In13.Cu")
		(net "M_H_CPU0_SB_DQS_DN<7>")
	)
	(segment
		(start 408.394154 -304.522632)
		(end 408.163014 -304.753772)
		(width 0.16002)
		(layer "In13.Cu")
		(net "M_H_CPU0_SB_DQS_DN<7>")
	)
	(arc
		(start 386.154676 -286.566102)
		(mid 386.339708 -286.612016)
		(end 386.523484 -286.561276)
		(width 0.09525)
		(layer "In13.Cu")
		(net "M_H_CPU0_SB_DQS_DN<7>")
	)
	(arc
		(start 384.266186 -286.561276)
		(mid 384.449961 -286.612048)
		(end 384.634994 -286.566102)
		(width 0.09525)
		(layer "In13.Cu")
		(net "M_H_CPU0_SB_DQS_DN<7>")
	)
	(arc
		(start 382.849882 -286.520128)
		(mid 383.092624 -286.487343)
		(end 383.326132 -286.561276)
		(width 0.09525)
		(layer "In13.Cu")
		(net "M_H_CPU0_SB_DQS_DN<7>")
	)
	(arc
		(start 385.58343 -286.561276)
		(mid 385.864862 -286.485487)
		(end 386.146294 -286.561276)
		(width 0.09525)
		(layer "In13.Cu")
		(net "M_H_CPU0_SB_DQS_DN<7>")
	)
	(arc
		(start 383.326132 -286.561276)
		(mid 383.509907 -286.612048)
		(end 383.69494 -286.566102)
		(width 0.09525)
		(layer "In13.Cu")
		(net "M_H_CPU0_SB_DQS_DN<7>")
	)
	(arc
		(start 382.829562 -286.528256)
		(mid 382.839683 -286.524094)
		(end 382.849882 -286.520128)
		(width 0.09525)
		(layer "In13.Cu")
		(net "M_H_CPU0_SB_DQS_DN<7>")
	)
	(arc
		(start 391.223246 -286.561276)
		(mid 391.504678 -286.485487)
		(end 391.78611 -286.561276)
		(width 0.09525)
		(layer "In13.Cu")
		(net "M_H_CPU0_SB_DQS_DN<7>")
	)
	(arc
		(start 390.283446 -286.561276)
		(mid 390.564878 -286.485487)
		(end 390.84631 -286.561276)
		(width 0.09525)
		(layer "In13.Cu")
		(net "M_H_CPU0_SB_DQS_DN<7>")
	)
	(arc
		(start 387.086348 -286.561276)
		(mid 387.274816 -286.611953)
		(end 387.463284 -286.561276)
		(width 0.09525)
		(layer "In13.Cu")
		(net "M_H_CPU0_SB_DQS_DN<7>")
	)
	(arc
		(start 388.966202 -286.561276)
		(mid 389.149977 -286.612048)
		(end 389.33501 -286.566102)
		(width 0.09525)
		(layer "In13.Cu")
		(net "M_H_CPU0_SB_DQS_DN<7>")
	)
	(arc
		(start 392.163808 -286.561276)
		(mid 392.299745 -286.504602)
		(end 392.445748 -286.48533)
		(width 0.09525)
		(layer "In13.Cu")
		(net "M_H_CPU0_SB_DQS_DN<7>")
	)
	(arc
		(start 389.914638 -286.566102)
		(mid 390.09967 -286.612016)
		(end 390.283446 -286.561276)
		(width 0.09525)
		(layer "In13.Cu")
		(net "M_H_CPU0_SB_DQS_DN<7>")
	)
	(arc
		(start 390.84631 -286.561276)
		(mid 391.034778 -286.611953)
		(end 391.223246 -286.561276)
		(width 0.09525)
		(layer "In13.Cu")
		(net "M_H_CPU0_SB_DQS_DN<7>")
	)
	(arc
		(start 386.523484 -286.561276)
		(mid 386.804916 -286.485487)
		(end 387.086348 -286.561276)
		(width 0.09525)
		(layer "In13.Cu")
		(net "M_H_CPU0_SB_DQS_DN<7>")
	)
	(arc
		(start 383.703322 -286.561276)
		(mid 383.984754 -286.485487)
		(end 384.266186 -286.561276)
		(width 0.09525)
		(layer "In13.Cu")
		(net "M_H_CPU0_SB_DQS_DN<7>")
	)
	(arc
		(start 391.794492 -286.566102)
		(mid 391.979778 -286.612138)
		(end 392.163808 -286.561276)
		(width 0.09525)
		(layer "In13.Cu")
		(net "M_H_CPU0_SB_DQS_DN<7>")
	)
	(arc
		(start 388.026148 -286.561276)
		(mid 388.209923 -286.612048)
		(end 388.394956 -286.566102)
		(width 0.09525)
		(layer "In13.Cu")
		(net "M_H_CPU0_SB_DQS_DN<7>")
	)
	(arc
		(start 384.643376 -286.561276)
		(mid 384.924808 -286.485487)
		(end 385.20624 -286.561276)
		(width 0.09525)
		(layer "In13.Cu")
		(net "M_H_CPU0_SB_DQS_DN<7>")
	)
	(arc
		(start 389.343392 -286.561276)
		(mid 389.624824 -286.485487)
		(end 389.906256 -286.561276)
		(width 0.09525)
		(layer "In13.Cu")
		(net "M_H_CPU0_SB_DQS_DN<7>")
	)
	(arc
		(start 385.214622 -286.566102)
		(mid 385.399654 -286.612016)
		(end 385.58343 -286.561276)
		(width 0.09525)
		(layer "In13.Cu")
		(net "M_H_CPU0_SB_DQS_DN<7>")
	)
	(arc
		(start 388.403338 -286.561276)
		(mid 388.68477 -286.485487)
		(end 388.966202 -286.561276)
		(width 0.09525)
		(layer "In13.Cu")
		(net "M_H_CPU0_SB_DQS_DN<7>")
	)
	(arc
		(start 387.463284 -286.561276)
		(mid 387.744716 -286.485487)
		(end 388.026148 -286.561276)
		(width 0.09525)
		(layer "In13.Cu")
		(net "M_H_CPU0_SB_DQS_DN<7>")
	)
	(segment
		(start 382.107948 -281.110182)
		(end 382.5748 -281.37612)
		(width 0.12954)
		(layer "F.Cu")
		(net "M_H_CPU0_SB_DQS_DN<6>")
	)
	(segment
		(start 382.728724 -281.64155)
		(end 382.5748 -281.37612)
		(width 0.09525)
		(layer "In13.Cu")
		(net "M_H_CPU0_SB_DQS_DN<6>")
	)
	(segment
		(start 409.45308 -296.349166)
		(end 407.56967 -294.465756)
		(width 0.16002)
		(layer "In13.Cu")
		(net "M_H_CPU0_SB_DQS_DN<6>")
	)
	(segment
		(start 386.154676 -281.706066)
		(end 386.146294 -281.70124)
		(width 0.09525)
		(layer "In13.Cu")
		(net "M_H_CPU0_SB_DQS_DN<6>")
	)
	(segment
		(start 412.585916 -296.349166)
		(end 412.425896 -296.189146)
		(width 0.16002)
		(layer "In13.Cu")
		(net "M_H_CPU0_SB_DQS_DN<6>")
	)
	(segment
		(start 389.343392 -281.70124)
		(end 389.33501 -281.706066)
		(width 0.09525)
		(layer "In13.Cu")
		(net "M_H_CPU0_SB_DQS_DN<6>")
	)
	(segment
		(start 407.994104 -292.347904)
		(end 407.5176 -292.347904)
		(width 0.16002)
		(layer "In13.Cu")
		(net "M_H_CPU0_SB_DQS_DN<6>")
	)
	(segment
		(start 382.829562 -281.66822)
		(end 382.728724 -281.64155)
		(width 0.09525)
		(layer "In13.Cu")
		(net "M_H_CPU0_SB_DQS_DN<6>")
	)
	(segment
		(start 393.63396 -281.62504)
		(end 393.384786 -281.62504)
		(width 0.09525)
		(layer "In13.Cu")
		(net "M_H_CPU0_SB_DQS_DN<6>")
	)
	(segment
		(start 407.56967 -294.465756)
		(end 407.56967 -294.239442)
		(width 0.16002)
		(layer "In13.Cu")
		(net "M_H_CPU0_SB_DQS_DN<6>")
	)
	(segment
		(start 408.489404 -293.319708)
		(end 408.489404 -292.843204)
		(width 0.16002)
		(layer "In13.Cu")
		(net "M_H_CPU0_SB_DQS_DN<6>")
	)
	(segment
		(start 394.425678 -281.625294)
		(end 393.634214 -281.625294)
		(width 0.09525)
		(layer "In13.Cu")
		(net "M_H_CPU0_SB_DQS_DN<6>")
	)
	(segment
		(start 407.5176 -292.347904)
		(end 406.800812 -293.064692)
		(width 0.16002)
		(layer "In13.Cu")
		(net "M_H_CPU0_SB_DQS_DN<6>")
	)
	(segment
		(start 413.876236 -295.995344)
		(end 413.375602 -295.995344)
		(width 0.16002)
		(layer "In13.Cu")
		(net "M_H_CPU0_SB_DQS_DN<6>")
	)
	(segment
		(start 411.051756 -295.823386)
		(end 411.051756 -296.189146)
		(width 0.16002)
		(layer "In13.Cu")
		(net "M_H_CPU0_SB_DQS_DN<6>")
	)
	(segment
		(start 392.737086 -281.708098)
		(end 392.725148 -281.70124)
		(width 0.09525)
		(layer "In13.Cu")
		(net "M_H_CPU0_SB_DQS_DN<6>")
	)
	(segment
		(start 392.18108 -281.690826)
		(end 392.163046 -281.70124)
		(width 0.09525)
		(layer "In13.Cu")
		(net "M_H_CPU0_SB_DQS_DN<6>")
	)
	(segment
		(start 414.729676 -295.141904)
		(end 413.876236 -295.995344)
		(width 0.16002)
		(layer "In13.Cu")
		(net "M_H_CPU0_SB_DQS_DN<6>")
	)
	(segment
		(start 413.375602 -295.995344)
		(end 413.02178 -296.349166)
		(width 0.16002)
		(layer "In13.Cu")
		(net "M_H_CPU0_SB_DQS_DN<6>")
	)
	(segment
		(start 392.163046 -281.70124)
		(end 392.151108 -281.708098)
		(width 0.09525)
		(layer "In13.Cu")
		(net "M_H_CPU0_SB_DQS_DN<6>")
	)
	(segment
		(start 419.630352 -295.366694)
		(end 418.00907 -295.366694)
		(width 0.16002)
		(layer "In13.Cu")
		(net "M_H_CPU0_SB_DQS_DN<6>")
	)
	(segment
		(start 412.425896 -296.189146)
		(end 412.425896 -295.823386)
		(width 0.16002)
		(layer "In13.Cu")
		(net "M_H_CPU0_SB_DQS_DN<6>")
	)
	(segment
		(start 385.214622 -281.706066)
		(end 385.20624 -281.70124)
		(width 0.09525)
		(layer "In13.Cu")
		(net "M_H_CPU0_SB_DQS_DN<6>")
	)
	(segment
		(start 388.403338 -281.70124)
		(end 388.394956 -281.706066)
		(width 0.09525)
		(layer "In13.Cu")
		(net "M_H_CPU0_SB_DQS_DN<6>")
	)
	(segment
		(start 395.530578 -281.877262)
		(end 394.833094 -281.877262)
		(width 0.09525)
		(layer "In13.Cu")
		(net "M_H_CPU0_SB_DQS_DN<6>")
	)
	(segment
		(start 412.088838 -295.486328)
		(end 411.388814 -295.486328)
		(width 0.16002)
		(layer "In13.Cu")
		(net "M_H_CPU0_SB_DQS_DN<6>")
	)
	(segment
		(start 417.78428 -295.141904)
		(end 414.729676 -295.141904)
		(width 0.16002)
		(layer "In13.Cu")
		(net "M_H_CPU0_SB_DQS_DN<6>")
	)
	(segment
		(start 406.800812 -293.064692)
		(end 406.574498 -293.064692)
		(width 0.16002)
		(layer "In13.Cu")
		(net "M_H_CPU0_SB_DQS_DN<6>")
	)
	(segment
		(start 389.914638 -281.706066)
		(end 389.906256 -281.70124)
		(width 0.09525)
		(layer "In13.Cu")
		(net "M_H_CPU0_SB_DQS_DN<6>")
	)
	(segment
		(start 406.414478 -290.299394)
		(end 397.933164 -281.81808)
		(width 0.16002)
		(layer "In13.Cu")
		(net "M_H_CPU0_SB_DQS_DN<6>")
	)
	(segment
		(start 397.933164 -281.81808)
		(end 395.613382 -281.81808)
		(width 0.16002)
		(layer "In13.Cu")
		(net "M_H_CPU0_SB_DQS_DN<6>")
	)
	(segment
		(start 418.00907 -295.366694)
		(end 417.78428 -295.141904)
		(width 0.16002)
		(layer "In13.Cu")
		(net "M_H_CPU0_SB_DQS_DN<6>")
	)
	(segment
		(start 394.833094 -281.877262)
		(end 394.661644 -281.705812)
		(width 0.09525)
		(layer "In13.Cu")
		(net "M_H_CPU0_SB_DQS_DN<6>")
	)
	(segment
		(start 384.643376 -281.70124)
		(end 384.634994 -281.706066)
		(width 0.09525)
		(layer "In13.Cu")
		(net "M_H_CPU0_SB_DQS_DN<6>")
	)
	(segment
		(start 395.613382 -281.81808)
		(end 395.58976 -281.81808)
		(width 0.09525)
		(layer "In13.Cu")
		(net "M_H_CPU0_SB_DQS_DN<6>")
	)
	(segment
		(start 393.634214 -281.625294)
		(end 393.63396 -281.62504)
		(width 0.09525)
		(layer "In13.Cu")
		(net "M_H_CPU0_SB_DQS_DN<6>")
	)
	(segment
		(start 406.414478 -292.904672)
		(end 406.414478 -290.299394)
		(width 0.16002)
		(layer "In13.Cu")
		(net "M_H_CPU0_SB_DQS_DN<6>")
	)
	(segment
		(start 411.051756 -296.189146)
		(end 410.891736 -296.349166)
		(width 0.16002)
		(layer "In13.Cu")
		(net "M_H_CPU0_SB_DQS_DN<6>")
	)
	(segment
		(start 383.703322 -281.70124)
		(end 383.69494 -281.706066)
		(width 0.09525)
		(layer "In13.Cu")
		(net "M_H_CPU0_SB_DQS_DN<6>")
	)
	(segment
		(start 410.891736 -296.349166)
		(end 409.45308 -296.349166)
		(width 0.16002)
		(layer "In13.Cu")
		(net "M_H_CPU0_SB_DQS_DN<6>")
	)
	(segment
		(start 395.58976 -281.81808)
		(end 395.530578 -281.877262)
		(width 0.09525)
		(layer "In13.Cu")
		(net "M_H_CPU0_SB_DQS_DN<6>")
	)
	(segment
		(start 406.574498 -293.064692)
		(end 406.414478 -292.904672)
		(width 0.16002)
		(layer "In13.Cu")
		(net "M_H_CPU0_SB_DQS_DN<6>")
	)
	(segment
		(start 411.388814 -295.486328)
		(end 411.051756 -295.823386)
		(width 0.16002)
		(layer "In13.Cu")
		(net "M_H_CPU0_SB_DQS_DN<6>")
	)
	(segment
		(start 407.56967 -294.239442)
		(end 408.489404 -293.319708)
		(width 0.16002)
		(layer "In13.Cu")
		(net "M_H_CPU0_SB_DQS_DN<6>")
	)
	(segment
		(start 413.02178 -296.349166)
		(end 412.585916 -296.349166)
		(width 0.16002)
		(layer "In13.Cu")
		(net "M_H_CPU0_SB_DQS_DN<6>")
	)
	(segment
		(start 412.425896 -295.823386)
		(end 412.088838 -295.486328)
		(width 0.16002)
		(layer "In13.Cu")
		(net "M_H_CPU0_SB_DQS_DN<6>")
	)
	(segment
		(start 408.489404 -292.843204)
		(end 407.994104 -292.347904)
		(width 0.16002)
		(layer "In13.Cu")
		(net "M_H_CPU0_SB_DQS_DN<6>")
	)
	(segment
		(start 419.912038 -295.085008)
		(end 419.630352 -295.366694)
		(width 0.16002)
		(layer "In13.Cu")
		(net "M_H_CPU0_SB_DQS_DN<6>")
	)
	(arc
		(start 394.661644 -281.705812)
		(mid 394.550339 -281.645987)
		(end 394.425678 -281.625294)
		(width 0.09525)
		(layer "In13.Cu")
		(net "M_H_CPU0_SB_DQS_DN<6>")
	)
	(arc
		(start 387.463284 -281.70124)
		(mid 387.274816 -281.751917)
		(end 387.086348 -281.70124)
		(width 0.09525)
		(layer "In13.Cu")
		(net "M_H_CPU0_SB_DQS_DN<6>")
	)
	(arc
		(start 389.906256 -281.70124)
		(mid 389.624824 -281.625485)
		(end 389.343392 -281.70124)
		(width 0.09525)
		(layer "In13.Cu")
		(net "M_H_CPU0_SB_DQS_DN<6>")
	)
	(arc
		(start 392.151108 -281.708098)
		(mid 391.967727 -281.751929)
		(end 391.78611 -281.70124)
		(width 0.09525)
		(layer "In13.Cu")
		(net "M_H_CPU0_SB_DQS_DN<6>")
	)
	(arc
		(start 391.78611 -281.70124)
		(mid 391.504678 -281.625485)
		(end 391.223246 -281.70124)
		(width 0.09525)
		(layer "In13.Cu")
		(net "M_H_CPU0_SB_DQS_DN<6>")
	)
	(arc
		(start 385.20624 -281.70124)
		(mid 384.924808 -281.625485)
		(end 384.643376 -281.70124)
		(width 0.09525)
		(layer "In13.Cu")
		(net "M_H_CPU0_SB_DQS_DN<6>")
	)
	(arc
		(start 386.523484 -281.70124)
		(mid 386.339709 -281.752012)
		(end 386.154676 -281.706066)
		(width 0.09525)
		(layer "In13.Cu")
		(net "M_H_CPU0_SB_DQS_DN<6>")
	)
	(arc
		(start 388.394956 -281.706066)
		(mid 388.209924 -281.75198)
		(end 388.026148 -281.70124)
		(width 0.09525)
		(layer "In13.Cu")
		(net "M_H_CPU0_SB_DQS_DN<6>")
	)
	(arc
		(start 384.634994 -281.706066)
		(mid 384.449962 -281.75198)
		(end 384.266186 -281.70124)
		(width 0.09525)
		(layer "In13.Cu")
		(net "M_H_CPU0_SB_DQS_DN<6>")
	)
	(arc
		(start 385.58343 -281.70124)
		(mid 385.399655 -281.752012)
		(end 385.214622 -281.706066)
		(width 0.09525)
		(layer "In13.Cu")
		(net "M_H_CPU0_SB_DQS_DN<6>")
	)
	(arc
		(start 389.33501 -281.706066)
		(mid 389.149978 -281.75198)
		(end 388.966202 -281.70124)
		(width 0.09525)
		(layer "In13.Cu")
		(net "M_H_CPU0_SB_DQS_DN<6>")
	)
	(arc
		(start 392.725148 -281.70124)
		(mid 392.45446 -281.625588)
		(end 392.18108 -281.690826)
		(width 0.09525)
		(layer "In13.Cu")
		(net "M_H_CPU0_SB_DQS_DN<6>")
	)
	(arc
		(start 388.966202 -281.70124)
		(mid 388.68477 -281.625485)
		(end 388.403338 -281.70124)
		(width 0.09525)
		(layer "In13.Cu")
		(net "M_H_CPU0_SB_DQS_DN<6>")
	)
	(arc
		(start 390.84631 -281.70124)
		(mid 390.564878 -281.625485)
		(end 390.283446 -281.70124)
		(width 0.09525)
		(layer "In13.Cu")
		(net "M_H_CPU0_SB_DQS_DN<6>")
	)
	(arc
		(start 386.146294 -281.70124)
		(mid 385.864862 -281.625485)
		(end 385.58343 -281.70124)
		(width 0.09525)
		(layer "In13.Cu")
		(net "M_H_CPU0_SB_DQS_DN<6>")
	)
	(arc
		(start 388.026148 -281.70124)
		(mid 387.744716 -281.625485)
		(end 387.463284 -281.70124)
		(width 0.09525)
		(layer "In13.Cu")
		(net "M_H_CPU0_SB_DQS_DN<6>")
	)
	(arc
		(start 383.326132 -281.70124)
		(mid 383.092588 -281.627534)
		(end 382.849882 -281.660346)
		(width 0.09525)
		(layer "In13.Cu")
		(net "M_H_CPU0_SB_DQS_DN<6>")
	)
	(arc
		(start 387.086348 -281.70124)
		(mid 386.804916 -281.625485)
		(end 386.523484 -281.70124)
		(width 0.09525)
		(layer "In13.Cu")
		(net "M_H_CPU0_SB_DQS_DN<6>")
	)
	(arc
		(start 382.849882 -281.660346)
		(mid 382.839683 -281.664183)
		(end 382.829562 -281.66822)
		(width 0.09525)
		(layer "In13.Cu")
		(net "M_H_CPU0_SB_DQS_DN<6>")
	)
	(arc
		(start 393.384786 -281.62504)
		(mid 393.238627 -281.644411)
		(end 393.102592 -281.70124)
		(width 0.09525)
		(layer "In13.Cu")
		(net "M_H_CPU0_SB_DQS_DN<6>")
	)
	(arc
		(start 384.266186 -281.70124)
		(mid 383.984754 -281.625485)
		(end 383.703322 -281.70124)
		(width 0.09525)
		(layer "In13.Cu")
		(net "M_H_CPU0_SB_DQS_DN<6>")
	)
	(arc
		(start 383.69494 -281.706066)
		(mid 383.509908 -281.75198)
		(end 383.326132 -281.70124)
		(width 0.09525)
		(layer "In13.Cu")
		(net "M_H_CPU0_SB_DQS_DN<6>")
	)
	(arc
		(start 391.223246 -281.70124)
		(mid 391.034778 -281.751917)
		(end 390.84631 -281.70124)
		(width 0.09525)
		(layer "In13.Cu")
		(net "M_H_CPU0_SB_DQS_DN<6>")
	)
	(arc
		(start 390.283446 -281.70124)
		(mid 390.099671 -281.752012)
		(end 389.914638 -281.706066)
		(width 0.09525)
		(layer "In13.Cu")
		(net "M_H_CPU0_SB_DQS_DN<6>")
	)
	(arc
		(start 393.102592 -281.70124)
		(mid 392.920722 -281.752105)
		(end 392.737086 -281.708098)
		(width 0.09525)
		(layer "In13.Cu")
		(net "M_H_CPU0_SB_DQS_DN<6>")
	)
	(segment
		(start 382.107948 -276.250146)
		(end 382.5748 -276.516084)
		(width 0.12954)
		(layer "F.Cu")
		(net "M_H_CPU0_SB_DQS_DN<5>")
	)
	(segment
		(start 417.989512 -285.79191)
		(end 414.729676 -285.79191)
		(width 0.16002)
		(layer "In13.Cu")
		(net "M_H_CPU0_SB_DQS_DN<5>")
	)
	(segment
		(start 395.484858 -275.852128)
		(end 395.31036 -275.67763)
		(width 0.09525)
		(layer "In13.Cu")
		(net "M_H_CPU0_SB_DQS_DN<5>")
	)
	(segment
		(start 382.728724 -276.781514)
		(end 382.5748 -276.516084)
		(width 0.09525)
		(layer "In13.Cu")
		(net "M_H_CPU0_SB_DQS_DN<5>")
	)
	(segment
		(start 406.259792 -281.81554)
		(end 406.259792 -281.58948)
		(width 0.16002)
		(layer "In13.Cu")
		(net "M_H_CPU0_SB_DQS_DN<5>")
	)
	(segment
		(start 407.910284 -282.972764)
		(end 407.910284 -282.49626)
		(width 0.16002)
		(layer "In13.Cu")
		(net "M_H_CPU0_SB_DQS_DN<5>")
	)
	(segment
		(start 403.544278 -279.100026)
		(end 400.237198 -275.792946)
		(width 0.16002)
		(layer "In13.Cu")
		(net "M_H_CPU0_SB_DQS_DN<5>")
	)
	(segment
		(start 395.770608 -275.792946)
		(end 395.711426 -275.852128)
		(width 0.09525)
		(layer "In13.Cu")
		(net "M_H_CPU0_SB_DQS_DN<5>")
	)
	(segment
		(start 404.876508 -279.462484)
		(end 404.380446 -278.966422)
		(width 0.16002)
		(layer "In13.Cu")
		(net "M_H_CPU0_SB_DQS_DN<5>")
	)
	(segment
		(start 386.154676 -276.84603)
		(end 386.146294 -276.841204)
		(width 0.09525)
		(layer "In13.Cu")
		(net "M_H_CPU0_SB_DQS_DN<5>")
	)
	(segment
		(start 419.64991 -285.996634)
		(end 418.194236 -285.996634)
		(width 0.16002)
		(layer "In13.Cu")
		(net "M_H_CPU0_SB_DQS_DN<5>")
	)
	(segment
		(start 409.427172 -284.489652)
		(end 409.427172 -284.013148)
		(width 0.16002)
		(layer "In13.Cu")
		(net "M_H_CPU0_SB_DQS_DN<5>")
	)
	(segment
		(start 414.729676 -285.79191)
		(end 413.876236 -286.64535)
		(width 0.16002)
		(layer "In13.Cu")
		(net "M_H_CPU0_SB_DQS_DN<5>")
	)
	(segment
		(start 384.643376 -276.841204)
		(end 384.634994 -276.84603)
		(width 0.09525)
		(layer "In13.Cu")
		(net "M_H_CPU0_SB_DQS_DN<5>")
	)
	(segment
		(start 405.287226 -280.616914)
		(end 405.061166 -280.616914)
		(width 0.16002)
		(layer "In13.Cu")
		(net "M_H_CPU0_SB_DQS_DN<5>")
	)
	(segment
		(start 409.427172 -284.013148)
		(end 408.93111 -283.517086)
		(width 0.16002)
		(layer "In13.Cu")
		(net "M_H_CPU0_SB_DQS_DN<5>")
	)
	(segment
		(start 395.711426 -275.852128)
		(end 395.484858 -275.852128)
		(width 0.09525)
		(layer "In13.Cu")
		(net "M_H_CPU0_SB_DQS_DN<5>")
	)
	(segment
		(start 403.770338 -279.100026)
		(end 403.544278 -279.100026)
		(width 0.16002)
		(layer "In13.Cu")
		(net "M_H_CPU0_SB_DQS_DN<5>")
	)
	(segment
		(start 404.380446 -278.966422)
		(end 403.903942 -278.966422)
		(width 0.16002)
		(layer "In13.Cu")
		(net "M_H_CPU0_SB_DQS_DN<5>")
	)
	(segment
		(start 409.293568 -284.623256)
		(end 409.427172 -284.489652)
		(width 0.16002)
		(layer "In13.Cu")
		(net "M_H_CPU0_SB_DQS_DN<5>")
	)
	(segment
		(start 408.454606 -283.517086)
		(end 408.321002 -283.65069)
		(width 0.16002)
		(layer "In13.Cu")
		(net "M_H_CPU0_SB_DQS_DN<5>")
	)
	(segment
		(start 406.937718 -282.000198)
		(end 406.804114 -282.133802)
		(width 0.16002)
		(layer "In13.Cu")
		(net "M_H_CPU0_SB_DQS_DN<5>")
	)
	(segment
		(start 406.259792 -281.58948)
		(end 406.393396 -281.455876)
		(width 0.16002)
		(layer "In13.Cu")
		(net "M_H_CPU0_SB_DQS_DN<5>")
	)
	(segment
		(start 405.061166 -280.616914)
		(end 404.742904 -280.298652)
		(width 0.16002)
		(layer "In13.Cu")
		(net "M_H_CPU0_SB_DQS_DN<5>")
	)
	(segment
		(start 405.897334 -280.48331)
		(end 405.42083 -280.48331)
		(width 0.16002)
		(layer "In13.Cu")
		(net "M_H_CPU0_SB_DQS_DN<5>")
	)
	(segment
		(start 383.703322 -276.841204)
		(end 383.69494 -276.84603)
		(width 0.09525)
		(layer "In13.Cu")
		(net "M_H_CPU0_SB_DQS_DN<5>")
	)
	(segment
		(start 408.094942 -283.65069)
		(end 407.77668 -283.332428)
		(width 0.16002)
		(layer "In13.Cu")
		(net "M_H_CPU0_SB_DQS_DN<5>")
	)
	(segment
		(start 406.804114 -282.133802)
		(end 406.578054 -282.133802)
		(width 0.16002)
		(layer "In13.Cu")
		(net "M_H_CPU0_SB_DQS_DN<5>")
	)
	(segment
		(start 406.578054 -282.133802)
		(end 406.259792 -281.81554)
		(width 0.16002)
		(layer "In13.Cu")
		(net "M_H_CPU0_SB_DQS_DN<5>")
	)
	(segment
		(start 404.742904 -280.072592)
		(end 404.876508 -279.938988)
		(width 0.16002)
		(layer "In13.Cu")
		(net "M_H_CPU0_SB_DQS_DN<5>")
	)
	(segment
		(start 382.829562 -276.808184)
		(end 382.728724 -276.781514)
		(width 0.09525)
		(layer "In13.Cu")
		(net "M_H_CPU0_SB_DQS_DN<5>")
	)
	(segment
		(start 409.293568 -284.849316)
		(end 409.293568 -284.623256)
		(width 0.16002)
		(layer "In13.Cu")
		(net "M_H_CPU0_SB_DQS_DN<5>")
	)
	(segment
		(start 385.214622 -276.84603)
		(end 385.20624 -276.841204)
		(width 0.09525)
		(layer "In13.Cu")
		(net "M_H_CPU0_SB_DQS_DN<5>")
	)
	(segment
		(start 408.93111 -283.517086)
		(end 408.454606 -283.517086)
		(width 0.16002)
		(layer "In13.Cu")
		(net "M_H_CPU0_SB_DQS_DN<5>")
	)
	(segment
		(start 411.822392 -285.533592)
		(end 410.963364 -285.533592)
		(width 0.16002)
		(layer "In13.Cu")
		(net "M_H_CPU0_SB_DQS_DN<5>")
	)
	(segment
		(start 406.393396 -280.979372)
		(end 405.897334 -280.48331)
		(width 0.16002)
		(layer "In13.Cu")
		(net "M_H_CPU0_SB_DQS_DN<5>")
	)
	(segment
		(start 413.876236 -286.64535)
		(end 412.93415 -286.64535)
		(width 0.16002)
		(layer "In13.Cu")
		(net "M_H_CPU0_SB_DQS_DN<5>")
	)
	(segment
		(start 395.79423 -275.792946)
		(end 395.770608 -275.792946)
		(width 0.09525)
		(layer "In13.Cu")
		(net "M_H_CPU0_SB_DQS_DN<5>")
	)
	(segment
		(start 412.93415 -286.64535)
		(end 411.822392 -285.533592)
		(width 0.16002)
		(layer "In13.Cu")
		(net "M_H_CPU0_SB_DQS_DN<5>")
	)
	(segment
		(start 405.42083 -280.48331)
		(end 405.287226 -280.616914)
		(width 0.16002)
		(layer "In13.Cu")
		(net "M_H_CPU0_SB_DQS_DN<5>")
	)
	(segment
		(start 418.194236 -285.996634)
		(end 417.989512 -285.79191)
		(width 0.16002)
		(layer "In13.Cu")
		(net "M_H_CPU0_SB_DQS_DN<5>")
	)
	(segment
		(start 389.343392 -276.841204)
		(end 389.33501 -276.84603)
		(width 0.09525)
		(layer "In13.Cu")
		(net "M_H_CPU0_SB_DQS_DN<5>")
	)
	(segment
		(start 392.737086 -276.848062)
		(end 392.725148 -276.841204)
		(width 0.09525)
		(layer "In13.Cu")
		(net "M_H_CPU0_SB_DQS_DN<5>")
	)
	(segment
		(start 392.163046 -276.841204)
		(end 392.151108 -276.848062)
		(width 0.09525)
		(layer "In13.Cu")
		(net "M_H_CPU0_SB_DQS_DN<5>")
	)
	(segment
		(start 404.742904 -280.298652)
		(end 404.742904 -280.072592)
		(width 0.16002)
		(layer "In13.Cu")
		(net "M_H_CPU0_SB_DQS_DN<5>")
	)
	(segment
		(start 410.963364 -285.533592)
		(end 410.47416 -285.044388)
		(width 0.16002)
		(layer "In13.Cu")
		(net "M_H_CPU0_SB_DQS_DN<5>")
	)
	(segment
		(start 400.237198 -275.792946)
		(end 395.79423 -275.792946)
		(width 0.16002)
		(layer "In13.Cu")
		(net "M_H_CPU0_SB_DQS_DN<5>")
	)
	(segment
		(start 407.414222 -282.000198)
		(end 406.937718 -282.000198)
		(width 0.16002)
		(layer "In13.Cu")
		(net "M_H_CPU0_SB_DQS_DN<5>")
	)
	(segment
		(start 393.641834 -276.548342)
		(end 393.227814 -276.787356)
		(width 0.09525)
		(layer "In13.Cu")
		(net "M_H_CPU0_SB_DQS_DN<5>")
	)
	(segment
		(start 407.910284 -282.49626)
		(end 407.414222 -282.000198)
		(width 0.16002)
		(layer "In13.Cu")
		(net "M_H_CPU0_SB_DQS_DN<5>")
	)
	(segment
		(start 403.903942 -278.966422)
		(end 403.770338 -279.100026)
		(width 0.16002)
		(layer "In13.Cu")
		(net "M_H_CPU0_SB_DQS_DN<5>")
	)
	(segment
		(start 388.403338 -276.841204)
		(end 388.394956 -276.84603)
		(width 0.09525)
		(layer "In13.Cu")
		(net "M_H_CPU0_SB_DQS_DN<5>")
	)
	(segment
		(start 409.48864 -285.044388)
		(end 409.293568 -284.849316)
		(width 0.16002)
		(layer "In13.Cu")
		(net "M_H_CPU0_SB_DQS_DN<5>")
	)
	(segment
		(start 407.77668 -283.332428)
		(end 407.77668 -283.106368)
		(width 0.16002)
		(layer "In13.Cu")
		(net "M_H_CPU0_SB_DQS_DN<5>")
	)
	(segment
		(start 393.655804 -276.541484)
		(end 393.641834 -276.548342)
		(width 0.09525)
		(layer "In13.Cu")
		(net "M_H_CPU0_SB_DQS_DN<5>")
	)
	(segment
		(start 407.77668 -283.106368)
		(end 407.910284 -282.972764)
		(width 0.16002)
		(layer "In13.Cu")
		(net "M_H_CPU0_SB_DQS_DN<5>")
	)
	(segment
		(start 394.644626 -275.67763)
		(end 394.104114 -276.218142)
		(width 0.09525)
		(layer "In13.Cu")
		(net "M_H_CPU0_SB_DQS_DN<5>")
	)
	(segment
		(start 404.876508 -279.938988)
		(end 404.876508 -279.462484)
		(width 0.16002)
		(layer "In13.Cu")
		(net "M_H_CPU0_SB_DQS_DN<5>")
	)
	(segment
		(start 395.31036 -275.67763)
		(end 394.644626 -275.67763)
		(width 0.09525)
		(layer "In13.Cu")
		(net "M_H_CPU0_SB_DQS_DN<5>")
	)
	(segment
		(start 419.912038 -285.735014)
		(end 419.64991 -285.996634)
		(width 0.16002)
		(layer "In13.Cu")
		(net "M_H_CPU0_SB_DQS_DN<5>")
	)
	(segment
		(start 410.47416 -285.044388)
		(end 409.48864 -285.044388)
		(width 0.16002)
		(layer "In13.Cu")
		(net "M_H_CPU0_SB_DQS_DN<5>")
	)
	(segment
		(start 406.393396 -281.455876)
		(end 406.393396 -280.979372)
		(width 0.16002)
		(layer "In13.Cu")
		(net "M_H_CPU0_SB_DQS_DN<5>")
	)
	(segment
		(start 389.914638 -276.84603)
		(end 389.906256 -276.841204)
		(width 0.09525)
		(layer "In13.Cu")
		(net "M_H_CPU0_SB_DQS_DN<5>")
	)
	(segment
		(start 408.321002 -283.65069)
		(end 408.094942 -283.65069)
		(width 0.16002)
		(layer "In13.Cu")
		(net "M_H_CPU0_SB_DQS_DN<5>")
	)
	(segment
		(start 392.18108 -276.83079)
		(end 392.163046 -276.841204)
		(width 0.09525)
		(layer "In13.Cu")
		(net "M_H_CPU0_SB_DQS_DN<5>")
	)
	(arc
		(start 388.966202 -276.841204)
		(mid 388.68477 -276.765449)
		(end 388.403338 -276.841204)
		(width 0.09525)
		(layer "In13.Cu")
		(net "M_H_CPU0_SB_DQS_DN<5>")
	)
	(arc
		(start 390.283446 -276.841204)
		(mid 390.099671 -276.891976)
		(end 389.914638 -276.84603)
		(width 0.09525)
		(layer "In13.Cu")
		(net "M_H_CPU0_SB_DQS_DN<5>")
	)
	(arc
		(start 382.849882 -276.80031)
		(mid 382.839683 -276.804147)
		(end 382.829562 -276.808184)
		(width 0.09525)
		(layer "In13.Cu")
		(net "M_H_CPU0_SB_DQS_DN<5>")
	)
	(arc
		(start 387.086348 -276.841204)
		(mid 386.804916 -276.765449)
		(end 386.523484 -276.841204)
		(width 0.09525)
		(layer "In13.Cu")
		(net "M_H_CPU0_SB_DQS_DN<5>")
	)
	(arc
		(start 391.223246 -276.841204)
		(mid 391.034778 -276.891881)
		(end 390.84631 -276.841204)
		(width 0.09525)
		(layer "In13.Cu")
		(net "M_H_CPU0_SB_DQS_DN<5>")
	)
	(arc
		(start 388.394956 -276.84603)
		(mid 388.209924 -276.891944)
		(end 388.026148 -276.841204)
		(width 0.09525)
		(layer "In13.Cu")
		(net "M_H_CPU0_SB_DQS_DN<5>")
	)
	(arc
		(start 384.266186 -276.841204)
		(mid 383.984754 -276.765449)
		(end 383.703322 -276.841204)
		(width 0.09525)
		(layer "In13.Cu")
		(net "M_H_CPU0_SB_DQS_DN<5>")
	)
	(arc
		(start 386.146294 -276.841204)
		(mid 385.864862 -276.765449)
		(end 385.58343 -276.841204)
		(width 0.09525)
		(layer "In13.Cu")
		(net "M_H_CPU0_SB_DQS_DN<5>")
	)
	(arc
		(start 383.69494 -276.84603)
		(mid 383.509908 -276.891944)
		(end 383.326132 -276.841204)
		(width 0.09525)
		(layer "In13.Cu")
		(net "M_H_CPU0_SB_DQS_DN<5>")
	)
	(arc
		(start 392.151108 -276.848062)
		(mid 391.967727 -276.891893)
		(end 391.78611 -276.841204)
		(width 0.09525)
		(layer "In13.Cu")
		(net "M_H_CPU0_SB_DQS_DN<5>")
	)
	(arc
		(start 394.104114 -276.218142)
		(mid 393.892991 -276.397882)
		(end 393.655804 -276.541484)
		(width 0.09525)
		(layer "In13.Cu")
		(net "M_H_CPU0_SB_DQS_DN<5>")
	)
	(arc
		(start 388.026148 -276.841204)
		(mid 387.744716 -276.765449)
		(end 387.463284 -276.841204)
		(width 0.09525)
		(layer "In13.Cu")
		(net "M_H_CPU0_SB_DQS_DN<5>")
	)
	(arc
		(start 390.84631 -276.841204)
		(mid 390.564878 -276.765449)
		(end 390.283446 -276.841204)
		(width 0.09525)
		(layer "In13.Cu")
		(net "M_H_CPU0_SB_DQS_DN<5>")
	)
	(arc
		(start 393.102592 -276.841204)
		(mid 392.920722 -276.892069)
		(end 392.737086 -276.848062)
		(width 0.09525)
		(layer "In13.Cu")
		(net "M_H_CPU0_SB_DQS_DN<5>")
	)
	(arc
		(start 383.326132 -276.841204)
		(mid 383.092588 -276.767498)
		(end 382.849882 -276.80031)
		(width 0.09525)
		(layer "In13.Cu")
		(net "M_H_CPU0_SB_DQS_DN<5>")
	)
	(arc
		(start 391.78611 -276.841204)
		(mid 391.504678 -276.765449)
		(end 391.223246 -276.841204)
		(width 0.09525)
		(layer "In13.Cu")
		(net "M_H_CPU0_SB_DQS_DN<5>")
	)
	(arc
		(start 393.227814 -276.787356)
		(mid 393.163567 -276.810474)
		(end 393.102592 -276.841204)
		(width 0.09525)
		(layer "In13.Cu")
		(net "M_H_CPU0_SB_DQS_DN<5>")
	)
	(arc
		(start 389.33501 -276.84603)
		(mid 389.149978 -276.891944)
		(end 388.966202 -276.841204)
		(width 0.09525)
		(layer "In13.Cu")
		(net "M_H_CPU0_SB_DQS_DN<5>")
	)
	(arc
		(start 387.463284 -276.841204)
		(mid 387.274816 -276.891881)
		(end 387.086348 -276.841204)
		(width 0.09525)
		(layer "In13.Cu")
		(net "M_H_CPU0_SB_DQS_DN<5>")
	)
	(arc
		(start 386.523484 -276.841204)
		(mid 386.339709 -276.891976)
		(end 386.154676 -276.84603)
		(width 0.09525)
		(layer "In13.Cu")
		(net "M_H_CPU0_SB_DQS_DN<5>")
	)
	(arc
		(start 384.634994 -276.84603)
		(mid 384.449962 -276.891944)
		(end 384.266186 -276.841204)
		(width 0.09525)
		(layer "In13.Cu")
		(net "M_H_CPU0_SB_DQS_DN<5>")
	)
	(arc
		(start 392.725148 -276.841204)
		(mid 392.45446 -276.765552)
		(end 392.18108 -276.83079)
		(width 0.09525)
		(layer "In13.Cu")
		(net "M_H_CPU0_SB_DQS_DN<5>")
	)
	(arc
		(start 385.58343 -276.841204)
		(mid 385.399655 -276.891976)
		(end 385.214622 -276.84603)
		(width 0.09525)
		(layer "In13.Cu")
		(net "M_H_CPU0_SB_DQS_DN<5>")
	)
	(arc
		(start 385.20624 -276.841204)
		(mid 384.924808 -276.765449)
		(end 384.643376 -276.841204)
		(width 0.09525)
		(layer "In13.Cu")
		(net "M_H_CPU0_SB_DQS_DN<5>")
	)
	(arc
		(start 389.906256 -276.841204)
		(mid 389.624824 -276.765449)
		(end 389.343392 -276.841204)
		(width 0.09525)
		(layer "In13.Cu")
		(net "M_H_CPU0_SB_DQS_DN<5>")
	)
	(segment
		(start 382.107948 -271.39011)
		(end 382.5748 -271.656048)
		(width 0.12954)
		(layer "F.Cu")
		(net "M_H_CPU0_SB_DQS_DN<4>")
	)
	(segment
		(start 409.040584 -273.118072)
		(end 408.64028 -272.717768)
		(width 0.16002)
		(layer "In13.Cu")
		(net "M_H_CPU0_SB_DQS_DN<4>")
	)
	(segment
		(start 413.876236 -277.295356)
		(end 413.217868 -277.295356)
		(width 0.16002)
		(layer "In13.Cu")
		(net "M_H_CPU0_SB_DQS_DN<4>")
	)
	(segment
		(start 410.062172 -274.13966)
		(end 409.585668 -274.13966)
		(width 0.16002)
		(layer "In13.Cu")
		(net "M_H_CPU0_SB_DQS_DN<4>")
	)
	(segment
		(start 383.703322 -271.981168)
		(end 383.69494 -271.985994)
		(width 0.09525)
		(layer "In13.Cu")
		(net "M_H_CPU0_SB_DQS_DN<4>")
	)
	(segment
		(start 410.851858 -275.907246)
		(end 410.625798 -275.907246)
		(width 0.16002)
		(layer "In13.Cu")
		(net "M_H_CPU0_SB_DQS_DN<4>")
	)
	(segment
		(start 389.343392 -271.981168)
		(end 389.33501 -271.985994)
		(width 0.09525)
		(layer "In13.Cu")
		(net "M_H_CPU0_SB_DQS_DN<4>")
	)
	(segment
		(start 417.03752 -276.672294)
		(end 416.582352 -277.127462)
		(width 0.16002)
		(layer "In13.Cu")
		(net "M_H_CPU0_SB_DQS_DN<4>")
	)
	(segment
		(start 410.625798 -275.907246)
		(end 410.306774 -275.588222)
		(width 0.16002)
		(layer "In13.Cu")
		(net "M_H_CPU0_SB_DQS_DN<4>")
	)
	(segment
		(start 419.624764 -276.672294)
		(end 419.18128 -276.672294)
		(width 0.16002)
		(layer "In13.Cu")
		(net "M_H_CPU0_SB_DQS_DN<4>")
	)
	(segment
		(start 410.306774 -275.362162)
		(end 410.557472 -275.111464)
		(width 0.16002)
		(layer "In13.Cu")
		(net "M_H_CPU0_SB_DQS_DN<4>")
	)
	(segment
		(start 389.914638 -271.985994)
		(end 389.906256 -271.981168)
		(width 0.09525)
		(layer "In13.Cu")
		(net "M_H_CPU0_SB_DQS_DN<4>")
	)
	(segment
		(start 410.557472 -274.63496)
		(end 410.062172 -274.13966)
		(width 0.16002)
		(layer "In13.Cu")
		(net "M_H_CPU0_SB_DQS_DN<4>")
	)
	(segment
		(start 418.726112 -277.127462)
		(end 418.234622 -277.127462)
		(width 0.16002)
		(layer "In13.Cu")
		(net "M_H_CPU0_SB_DQS_DN<4>")
	)
	(segment
		(start 408.64028 -272.717768)
		(end 407.43632 -272.717768)
		(width 0.16002)
		(layer "In13.Cu")
		(net "M_H_CPU0_SB_DQS_DN<4>")
	)
	(segment
		(start 408.789886 -274.071334)
		(end 408.789886 -273.845274)
		(width 0.16002)
		(layer "In13.Cu")
		(net "M_H_CPU0_SB_DQS_DN<4>")
	)
	(segment
		(start 382.728724 -271.921478)
		(end 382.5748 -271.656048)
		(width 0.09525)
		(layer "In13.Cu")
		(net "M_H_CPU0_SB_DQS_DN<4>")
	)
	(segment
		(start 382.829562 -271.948148)
		(end 382.728724 -271.921478)
		(width 0.09525)
		(layer "In13.Cu")
		(net "M_H_CPU0_SB_DQS_DN<4>")
	)
	(segment
		(start 409.040584 -273.594576)
		(end 409.040584 -273.118072)
		(width 0.16002)
		(layer "In13.Cu")
		(net "M_H_CPU0_SB_DQS_DN<4>")
	)
	(segment
		(start 395.750542 -270.14424)
		(end 395.72692 -270.14424)
		(width 0.09525)
		(layer "In13.Cu")
		(net "M_H_CPU0_SB_DQS_DN<4>")
	)
	(segment
		(start 384.643376 -271.981168)
		(end 384.634994 -271.985994)
		(width 0.09525)
		(layer "In13.Cu")
		(net "M_H_CPU0_SB_DQS_DN<4>")
	)
	(segment
		(start 407.43632 -272.717768)
		(end 404.862792 -270.14424)
		(width 0.16002)
		(layer "In13.Cu")
		(net "M_H_CPU0_SB_DQS_DN<4>")
	)
	(segment
		(start 419.18128 -276.672294)
		(end 418.726112 -277.127462)
		(width 0.16002)
		(layer "In13.Cu")
		(net "M_H_CPU0_SB_DQS_DN<4>")
	)
	(segment
		(start 409.585668 -274.13966)
		(end 409.33497 -274.390358)
		(width 0.16002)
		(layer "In13.Cu")
		(net "M_H_CPU0_SB_DQS_DN<4>")
	)
	(segment
		(start 411.102556 -275.656548)
		(end 410.851858 -275.907246)
		(width 0.16002)
		(layer "In13.Cu")
		(net "M_H_CPU0_SB_DQS_DN<4>")
	)
	(segment
		(start 386.154676 -271.985994)
		(end 386.146294 -271.981168)
		(width 0.09525)
		(layer "In13.Cu")
		(net "M_H_CPU0_SB_DQS_DN<4>")
	)
	(segment
		(start 394.348716 -270.413226)
		(end 392.85672 -271.905222)
		(width 0.09525)
		(layer "In13.Cu")
		(net "M_H_CPU0_SB_DQS_DN<4>")
	)
	(segment
		(start 408.789886 -273.845274)
		(end 409.040584 -273.594576)
		(width 0.16002)
		(layer "In13.Cu")
		(net "M_H_CPU0_SB_DQS_DN<4>")
	)
	(segment
		(start 416.582352 -277.127462)
		(end 416.090862 -277.127462)
		(width 0.16002)
		(layer "In13.Cu")
		(net "M_H_CPU0_SB_DQS_DN<4>")
	)
	(segment
		(start 395.092428 -270.203422)
		(end 394.882624 -270.413226)
		(width 0.09525)
		(layer "In13.Cu")
		(net "M_H_CPU0_SB_DQS_DN<4>")
	)
	(segment
		(start 395.667738 -270.203422)
		(end 395.092428 -270.203422)
		(width 0.09525)
		(layer "In13.Cu")
		(net "M_H_CPU0_SB_DQS_DN<4>")
	)
	(segment
		(start 410.306774 -275.588222)
		(end 410.306774 -275.362162)
		(width 0.16002)
		(layer "In13.Cu")
		(net "M_H_CPU0_SB_DQS_DN<4>")
	)
	(segment
		(start 392.85672 -271.905222)
		(end 392.445494 -271.905222)
		(width 0.09525)
		(layer "In13.Cu")
		(net "M_H_CPU0_SB_DQS_DN<4>")
	)
	(segment
		(start 391.794492 -271.985994)
		(end 391.78611 -271.981168)
		(width 0.09525)
		(layer "In13.Cu")
		(net "M_H_CPU0_SB_DQS_DN<4>")
	)
	(segment
		(start 385.214622 -271.985994)
		(end 385.20624 -271.981168)
		(width 0.09525)
		(layer "In13.Cu")
		(net "M_H_CPU0_SB_DQS_DN<4>")
	)
	(segment
		(start 404.862792 -270.14424)
		(end 395.750542 -270.14424)
		(width 0.16002)
		(layer "In13.Cu")
		(net "M_H_CPU0_SB_DQS_DN<4>")
	)
	(segment
		(start 417.779454 -276.672294)
		(end 417.03752 -276.672294)
		(width 0.16002)
		(layer "In13.Cu")
		(net "M_H_CPU0_SB_DQS_DN<4>")
	)
	(segment
		(start 395.72692 -270.14424)
		(end 395.667738 -270.203422)
		(width 0.09525)
		(layer "In13.Cu")
		(net "M_H_CPU0_SB_DQS_DN<4>")
	)
	(segment
		(start 415.306002 -276.342602)
		(end 414.82899 -276.342602)
		(width 0.16002)
		(layer "In13.Cu")
		(net "M_H_CPU0_SB_DQS_DN<4>")
	)
	(segment
		(start 410.557472 -275.111464)
		(end 410.557472 -274.63496)
		(width 0.16002)
		(layer "In13.Cu")
		(net "M_H_CPU0_SB_DQS_DN<4>")
	)
	(segment
		(start 388.403338 -271.981168)
		(end 388.394956 -271.985994)
		(width 0.09525)
		(layer "In13.Cu")
		(net "M_H_CPU0_SB_DQS_DN<4>")
	)
	(segment
		(start 416.090862 -277.127462)
		(end 415.306002 -276.342602)
		(width 0.16002)
		(layer "In13.Cu")
		(net "M_H_CPU0_SB_DQS_DN<4>")
	)
	(segment
		(start 394.882624 -270.413226)
		(end 394.348716 -270.413226)
		(width 0.09525)
		(layer "In13.Cu")
		(net "M_H_CPU0_SB_DQS_DN<4>")
	)
	(segment
		(start 418.234622 -277.127462)
		(end 417.779454 -276.672294)
		(width 0.16002)
		(layer "In13.Cu")
		(net "M_H_CPU0_SB_DQS_DN<4>")
	)
	(segment
		(start 413.217868 -277.295356)
		(end 411.57906 -275.656548)
		(width 0.16002)
		(layer "In13.Cu")
		(net "M_H_CPU0_SB_DQS_DN<4>")
	)
	(segment
		(start 409.33497 -274.390358)
		(end 409.10891 -274.390358)
		(width 0.16002)
		(layer "In13.Cu")
		(net "M_H_CPU0_SB_DQS_DN<4>")
	)
	(segment
		(start 414.82899 -276.342602)
		(end 413.876236 -277.295356)
		(width 0.16002)
		(layer "In13.Cu")
		(net "M_H_CPU0_SB_DQS_DN<4>")
	)
	(segment
		(start 409.10891 -274.390358)
		(end 408.789886 -274.071334)
		(width 0.16002)
		(layer "In13.Cu")
		(net "M_H_CPU0_SB_DQS_DN<4>")
	)
	(segment
		(start 419.912038 -276.38502)
		(end 419.624764 -276.672294)
		(width 0.16002)
		(layer "In13.Cu")
		(net "M_H_CPU0_SB_DQS_DN<4>")
	)
	(segment
		(start 411.57906 -275.656548)
		(end 411.102556 -275.656548)
		(width 0.16002)
		(layer "In13.Cu")
		(net "M_H_CPU0_SB_DQS_DN<4>")
	)
	(arc
		(start 388.394956 -271.985994)
		(mid 388.209924 -272.031908)
		(end 388.026148 -271.981168)
		(width 0.09525)
		(layer "In13.Cu")
		(net "M_H_CPU0_SB_DQS_DN<4>")
	)
	(arc
		(start 385.58343 -271.981168)
		(mid 385.399655 -272.03194)
		(end 385.214622 -271.985994)
		(width 0.09525)
		(layer "In13.Cu")
		(net "M_H_CPU0_SB_DQS_DN<4>")
	)
	(arc
		(start 390.283446 -271.981168)
		(mid 390.099671 -272.03194)
		(end 389.914638 -271.985994)
		(width 0.09525)
		(layer "In13.Cu")
		(net "M_H_CPU0_SB_DQS_DN<4>")
	)
	(arc
		(start 387.086348 -271.981168)
		(mid 386.804916 -271.905413)
		(end 386.523484 -271.981168)
		(width 0.09525)
		(layer "In13.Cu")
		(net "M_H_CPU0_SB_DQS_DN<4>")
	)
	(arc
		(start 387.463284 -271.981168)
		(mid 387.274816 -272.031845)
		(end 387.086348 -271.981168)
		(width 0.09525)
		(layer "In13.Cu")
		(net "M_H_CPU0_SB_DQS_DN<4>")
	)
	(arc
		(start 388.966202 -271.981168)
		(mid 388.68477 -271.905413)
		(end 388.403338 -271.981168)
		(width 0.09525)
		(layer "In13.Cu")
		(net "M_H_CPU0_SB_DQS_DN<4>")
	)
	(arc
		(start 382.849882 -271.940274)
		(mid 382.839683 -271.944111)
		(end 382.829562 -271.948148)
		(width 0.09525)
		(layer "In13.Cu")
		(net "M_H_CPU0_SB_DQS_DN<4>")
	)
	(arc
		(start 391.78611 -271.981168)
		(mid 391.504678 -271.905413)
		(end 391.223246 -271.981168)
		(width 0.09525)
		(layer "In13.Cu")
		(net "M_H_CPU0_SB_DQS_DN<4>")
	)
	(arc
		(start 386.523484 -271.981168)
		(mid 386.339709 -272.03194)
		(end 386.154676 -271.985994)
		(width 0.09525)
		(layer "In13.Cu")
		(net "M_H_CPU0_SB_DQS_DN<4>")
	)
	(arc
		(start 388.026148 -271.981168)
		(mid 387.744716 -271.905413)
		(end 387.463284 -271.981168)
		(width 0.09525)
		(layer "In13.Cu")
		(net "M_H_CPU0_SB_DQS_DN<4>")
	)
	(arc
		(start 386.146294 -271.981168)
		(mid 385.864862 -271.905413)
		(end 385.58343 -271.981168)
		(width 0.09525)
		(layer "In13.Cu")
		(net "M_H_CPU0_SB_DQS_DN<4>")
	)
	(arc
		(start 383.326132 -271.981168)
		(mid 383.092588 -271.907462)
		(end 382.849882 -271.940274)
		(width 0.09525)
		(layer "In13.Cu")
		(net "M_H_CPU0_SB_DQS_DN<4>")
	)
	(arc
		(start 389.906256 -271.981168)
		(mid 389.624824 -271.905413)
		(end 389.343392 -271.981168)
		(width 0.09525)
		(layer "In13.Cu")
		(net "M_H_CPU0_SB_DQS_DN<4>")
	)
	(arc
		(start 391.223246 -271.981168)
		(mid 391.034778 -272.031845)
		(end 390.84631 -271.981168)
		(width 0.09525)
		(layer "In13.Cu")
		(net "M_H_CPU0_SB_DQS_DN<4>")
	)
	(arc
		(start 392.163808 -271.981168)
		(mid 391.979779 -272.032067)
		(end 391.794492 -271.985994)
		(width 0.09525)
		(layer "In13.Cu")
		(net "M_H_CPU0_SB_DQS_DN<4>")
	)
	(arc
		(start 384.266186 -271.981168)
		(mid 383.984754 -271.905413)
		(end 383.703322 -271.981168)
		(width 0.09525)
		(layer "In13.Cu")
		(net "M_H_CPU0_SB_DQS_DN<4>")
	)
	(arc
		(start 383.69494 -271.985994)
		(mid 383.509908 -272.031908)
		(end 383.326132 -271.981168)
		(width 0.09525)
		(layer "In13.Cu")
		(net "M_H_CPU0_SB_DQS_DN<4>")
	)
	(arc
		(start 385.20624 -271.981168)
		(mid 384.924808 -271.905413)
		(end 384.643376 -271.981168)
		(width 0.09525)
		(layer "In13.Cu")
		(net "M_H_CPU0_SB_DQS_DN<4>")
	)
	(arc
		(start 390.84631 -271.981168)
		(mid 390.564878 -271.905413)
		(end 390.283446 -271.981168)
		(width 0.09525)
		(layer "In13.Cu")
		(net "M_H_CPU0_SB_DQS_DN<4>")
	)
	(arc
		(start 384.634994 -271.985994)
		(mid 384.449962 -272.031908)
		(end 384.266186 -271.981168)
		(width 0.09525)
		(layer "In13.Cu")
		(net "M_H_CPU0_SB_DQS_DN<4>")
	)
	(arc
		(start 392.445494 -271.905222)
		(mid 392.299634 -271.924581)
		(end 392.163808 -271.981168)
		(width 0.09525)
		(layer "In13.Cu")
		(net "M_H_CPU0_SB_DQS_DN<4>")
	)
	(arc
		(start 389.33501 -271.985994)
		(mid 389.149978 -272.031908)
		(end 388.966202 -271.981168)
		(width 0.09525)
		(layer "In13.Cu")
		(net "M_H_CPU0_SB_DQS_DN<4>")
	)
	(segment
		(start 383.988056 -290.83)
		(end 384.454908 -291.095938)
		(width 0.12954)
		(layer "F.Cu")
		(net "M_H_CPU0_SB_DQS_DN<3>")
	)
	(segment
		(start 420.567104 -313.697112)
		(end 420.232078 -313.362086)
		(width 0.16002)
		(layer "In13.Cu")
		(net "M_H_CPU0_SB_DQS_DN<3>")
	)
	(segment
		(start 412.984696 -313.370976)
		(end 412.492444 -313.370976)
		(width 0.16002)
		(layer "In13.Cu")
		(net "M_H_CPU0_SB_DQS_DN<3>")
	)
	(segment
		(start 421.58666 -313.697112)
		(end 420.567104 -313.697112)
		(width 0.16002)
		(layer "In13.Cu")
		(net "M_H_CPU0_SB_DQS_DN<3>")
	)
	(segment
		(start 417.195508 -312.922412)
		(end 416.73399 -313.38393)
		(width 0.16002)
		(layer "In13.Cu")
		(net "M_H_CPU0_SB_DQS_DN<3>")
	)
	(segment
		(start 410.982668 -313.370976)
		(end 408.078432 -313.370976)
		(width 0.16002)
		(layer "In13.Cu")
		(net "M_H_CPU0_SB_DQS_DN<3>")
	)
	(segment
		(start 408.078432 -313.370976)
		(end 395.906498 -301.199042)
		(width 0.16002)
		(layer "In13.Cu")
		(net "M_H_CPU0_SB_DQS_DN<3>")
	)
	(segment
		(start 392.162538 -290.770818)
		(end 392.145774 -290.761166)
		(width 0.09525)
		(layer "In13.Cu")
		(net "M_H_CPU0_SB_DQS_DN<3>")
	)
	(segment
		(start 394.285978 -293.11092)
		(end 393.43838 -291.088064)
		(width 0.09525)
		(layer "In13.Cu")
		(net "M_H_CPU0_SB_DQS_DN<3>")
	)
	(segment
		(start 385.214622 -290.765992)
		(end 385.20624 -290.770818)
		(width 0.09525)
		(layer "In13.Cu")
		(net "M_H_CPU0_SB_DQS_DN<3>")
	)
	(segment
		(start 412.07817 -313.78525)
		(end 411.396942 -313.78525)
		(width 0.16002)
		(layer "In13.Cu")
		(net "M_H_CPU0_SB_DQS_DN<3>")
	)
	(segment
		(start 394.973302 -293.881302)
		(end 394.973556 -293.798498)
		(width 0.09525)
		(layer "In13.Cu")
		(net "M_H_CPU0_SB_DQS_DN<3>")
	)
	(segment
		(start 384.324352 -290.74364)
		(end 384.300984 -290.830508)
		(width 0.09525)
		(layer "In13.Cu")
		(net "M_H_CPU0_SB_DQS_DN<3>")
	)
	(segment
		(start 386.154676 -290.765992)
		(end 386.146294 -290.770818)
		(width 0.09525)
		(layer "In13.Cu")
		(net "M_H_CPU0_SB_DQS_DN<3>")
	)
	(segment
		(start 421.809418 -313.474354)
		(end 421.58666 -313.697112)
		(width 0.16002)
		(layer "In13.Cu")
		(net "M_H_CPU0_SB_DQS_DN<3>")
	)
	(segment
		(start 414.837372 -312.922412)
		(end 414.052512 -313.707272)
		(width 0.16002)
		(layer "In13.Cu")
		(net "M_H_CPU0_SB_DQS_DN<3>")
	)
	(segment
		(start 395.906498 -301.199042)
		(end 395.906498 -294.814498)
		(width 0.16002)
		(layer "In13.Cu")
		(net "M_H_CPU0_SB_DQS_DN<3>")
	)
	(segment
		(start 394.973556 -293.798498)
		(end 394.285978 -293.11092)
		(width 0.09525)
		(layer "In13.Cu")
		(net "M_H_CPU0_SB_DQS_DN<3>")
	)
	(segment
		(start 389.343392 -290.770818)
		(end 389.33501 -290.765992)
		(width 0.09525)
		(layer "In13.Cu")
		(net "M_H_CPU0_SB_DQS_DN<3>")
	)
	(segment
		(start 392.187938 -290.78555)
		(end 392.162538 -290.770818)
		(width 0.09525)
		(layer "In13.Cu")
		(net "M_H_CPU0_SB_DQS_DN<3>")
	)
	(segment
		(start 384.643376 -290.770818)
		(end 384.634994 -290.765992)
		(width 0.09525)
		(layer "In13.Cu")
		(net "M_H_CPU0_SB_DQS_DN<3>")
	)
	(segment
		(start 424.012106 -313.784996)
		(end 423.701464 -313.474354)
		(width 0.16002)
		(layer "In13.Cu")
		(net "M_H_CPU0_SB_DQS_DN<3>")
	)
	(segment
		(start 411.396942 -313.78525)
		(end 410.982668 -313.370976)
		(width 0.16002)
		(layer "In13.Cu")
		(net "M_H_CPU0_SB_DQS_DN<3>")
	)
	(segment
		(start 388.403338 -290.770818)
		(end 388.394956 -290.765992)
		(width 0.09525)
		(layer "In13.Cu")
		(net "M_H_CPU0_SB_DQS_DN<3>")
	)
	(segment
		(start 412.492444 -313.370976)
		(end 412.07817 -313.78525)
		(width 0.16002)
		(layer "In13.Cu")
		(net "M_H_CPU0_SB_DQS_DN<3>")
	)
	(segment
		(start 384.300984 -290.830508)
		(end 384.454908 -291.095938)
		(width 0.09525)
		(layer "In13.Cu")
		(net "M_H_CPU0_SB_DQS_DN<3>")
	)
	(segment
		(start 416.100006 -313.38393)
		(end 415.638488 -312.922412)
		(width 0.16002)
		(layer "In13.Cu")
		(net "M_H_CPU0_SB_DQS_DN<3>")
	)
	(segment
		(start 416.73399 -313.38393)
		(end 416.100006 -313.38393)
		(width 0.16002)
		(layer "In13.Cu")
		(net "M_H_CPU0_SB_DQS_DN<3>")
	)
	(segment
		(start 417.885372 -312.922412)
		(end 417.195508 -312.922412)
		(width 0.16002)
		(layer "In13.Cu")
		(net "M_H_CPU0_SB_DQS_DN<3>")
	)
	(segment
		(start 393.43838 -291.088064)
		(end 393.18057 -290.830254)
		(width 0.09525)
		(layer "In13.Cu")
		(net "M_H_CPU0_SB_DQS_DN<3>")
	)
	(segment
		(start 418.325046 -313.362086)
		(end 417.885372 -312.922412)
		(width 0.16002)
		(layer "In13.Cu")
		(net "M_H_CPU0_SB_DQS_DN<3>")
	)
	(segment
		(start 394.990066 -293.898066)
		(end 394.973302 -293.881302)
		(width 0.09525)
		(layer "In13.Cu")
		(net "M_H_CPU0_SB_DQS_DN<3>")
	)
	(segment
		(start 395.906498 -294.814498)
		(end 394.990066 -293.898066)
		(width 0.16002)
		(layer "In13.Cu")
		(net "M_H_CPU0_SB_DQS_DN<3>")
	)
	(segment
		(start 392.742674 -290.759896)
		(end 392.723878 -290.770818)
		(width 0.09525)
		(layer "In13.Cu")
		(net "M_H_CPU0_SB_DQS_DN<3>")
	)
	(segment
		(start 413.320992 -313.707272)
		(end 412.984696 -313.370976)
		(width 0.16002)
		(layer "In13.Cu")
		(net "M_H_CPU0_SB_DQS_DN<3>")
	)
	(segment
		(start 414.052512 -313.707272)
		(end 413.320992 -313.707272)
		(width 0.16002)
		(layer "In13.Cu")
		(net "M_H_CPU0_SB_DQS_DN<3>")
	)
	(segment
		(start 415.638488 -312.922412)
		(end 414.837372 -312.922412)
		(width 0.16002)
		(layer "In13.Cu")
		(net "M_H_CPU0_SB_DQS_DN<3>")
	)
	(segment
		(start 423.701464 -313.474354)
		(end 421.809418 -313.474354)
		(width 0.16002)
		(layer "In13.Cu")
		(net "M_H_CPU0_SB_DQS_DN<3>")
	)
	(segment
		(start 389.914638 -290.765992)
		(end 389.906256 -290.770818)
		(width 0.09525)
		(layer "In13.Cu")
		(net "M_H_CPU0_SB_DQS_DN<3>")
	)
	(segment
		(start 420.232078 -313.362086)
		(end 418.325046 -313.362086)
		(width 0.16002)
		(layer "In13.Cu")
		(net "M_H_CPU0_SB_DQS_DN<3>")
	)
	(arc
		(start 393.18057 -290.830254)
		(mid 393.143284 -290.797952)
		(end 393.102084 -290.770818)
		(width 0.09525)
		(layer "In13.Cu")
		(net "M_H_CPU0_SB_DQS_DN<3>")
	)
	(arc
		(start 386.146294 -290.770818)
		(mid 385.864862 -290.846573)
		(end 385.58343 -290.770818)
		(width 0.09525)
		(layer "In13.Cu")
		(net "M_H_CPU0_SB_DQS_DN<3>")
	)
	(arc
		(start 387.086348 -290.770818)
		(mid 386.804916 -290.846573)
		(end 386.523484 -290.770818)
		(width 0.09525)
		(layer "In13.Cu")
		(net "M_H_CPU0_SB_DQS_DN<3>")
	)
	(arc
		(start 390.84631 -290.770818)
		(mid 390.564878 -290.846573)
		(end 390.283446 -290.770818)
		(width 0.09525)
		(layer "In13.Cu")
		(net "M_H_CPU0_SB_DQS_DN<3>")
	)
	(arc
		(start 389.33501 -290.765992)
		(mid 389.149978 -290.720078)
		(end 388.966202 -290.770818)
		(width 0.09525)
		(layer "In13.Cu")
		(net "M_H_CPU0_SB_DQS_DN<3>")
	)
	(arc
		(start 391.223246 -290.770818)
		(mid 391.034778 -290.720141)
		(end 390.84631 -290.770818)
		(width 0.09525)
		(layer "In13.Cu")
		(net "M_H_CPU0_SB_DQS_DN<3>")
	)
	(arc
		(start 391.78611 -290.770818)
		(mid 391.504678 -290.846573)
		(end 391.223246 -290.770818)
		(width 0.09525)
		(layer "In13.Cu")
		(net "M_H_CPU0_SB_DQS_DN<3>")
	)
	(arc
		(start 393.102084 -290.770818)
		(mid 392.923769 -290.719676)
		(end 392.742674 -290.759896)
		(width 0.09525)
		(layer "In13.Cu")
		(net "M_H_CPU0_SB_DQS_DN<3>")
	)
	(arc
		(start 385.58343 -290.770818)
		(mid 385.399655 -290.720046)
		(end 385.214622 -290.765992)
		(width 0.09525)
		(layer "In13.Cu")
		(net "M_H_CPU0_SB_DQS_DN<3>")
	)
	(arc
		(start 388.394956 -290.765992)
		(mid 388.209924 -290.720078)
		(end 388.026148 -290.770818)
		(width 0.09525)
		(layer "In13.Cu")
		(net "M_H_CPU0_SB_DQS_DN<3>")
	)
	(arc
		(start 392.145774 -290.761166)
		(mid 391.964717 -290.720184)
		(end 391.78611 -290.770818)
		(width 0.09525)
		(layer "In13.Cu")
		(net "M_H_CPU0_SB_DQS_DN<3>")
	)
	(arc
		(start 388.026148 -290.770818)
		(mid 387.744716 -290.846573)
		(end 387.463284 -290.770818)
		(width 0.09525)
		(layer "In13.Cu")
		(net "M_H_CPU0_SB_DQS_DN<3>")
	)
	(arc
		(start 390.283446 -290.770818)
		(mid 390.099671 -290.720046)
		(end 389.914638 -290.765992)
		(width 0.09525)
		(layer "In13.Cu")
		(net "M_H_CPU0_SB_DQS_DN<3>")
	)
	(arc
		(start 386.523484 -290.770818)
		(mid 386.339709 -290.720046)
		(end 386.154676 -290.765992)
		(width 0.09525)
		(layer "In13.Cu")
		(net "M_H_CPU0_SB_DQS_DN<3>")
	)
	(arc
		(start 387.463284 -290.770818)
		(mid 387.274816 -290.720141)
		(end 387.086348 -290.770818)
		(width 0.09525)
		(layer "In13.Cu")
		(net "M_H_CPU0_SB_DQS_DN<3>")
	)
	(arc
		(start 389.906256 -290.770818)
		(mid 389.624824 -290.846573)
		(end 389.343392 -290.770818)
		(width 0.09525)
		(layer "In13.Cu")
		(net "M_H_CPU0_SB_DQS_DN<3>")
	)
	(arc
		(start 392.723878 -290.770818)
		(mid 392.457791 -290.846363)
		(end 392.187938 -290.78555)
		(width 0.09525)
		(layer "In13.Cu")
		(net "M_H_CPU0_SB_DQS_DN<3>")
	)
	(arc
		(start 384.634994 -290.765992)
		(mid 384.482099 -290.721164)
		(end 384.324352 -290.74364)
		(width 0.09525)
		(layer "In13.Cu")
		(net "M_H_CPU0_SB_DQS_DN<3>")
	)
	(arc
		(start 388.966202 -290.770818)
		(mid 388.68477 -290.846573)
		(end 388.403338 -290.770818)
		(width 0.09525)
		(layer "In13.Cu")
		(net "M_H_CPU0_SB_DQS_DN<3>")
	)
	(arc
		(start 385.20624 -290.770818)
		(mid 384.924808 -290.846573)
		(end 384.643376 -290.770818)
		(width 0.09525)
		(layer "In13.Cu")
		(net "M_H_CPU0_SB_DQS_DN<3>")
	)
	(segment
		(start 383.988056 -285.970218)
		(end 384.454908 -286.236156)
		(width 0.12954)
		(layer "F.Cu")
		(net "M_H_CPU0_SB_DQS_DN<2>")
	)
	(segment
		(start 403.349968 -299.323506)
		(end 403.84603 -299.819568)
		(width 0.16002)
		(layer "In13.Cu")
		(net "M_H_CPU0_SB_DQS_DN<2>")
	)
	(segment
		(start 404.322534 -299.819568)
		(end 404.535132 -299.60697)
		(width 0.16002)
		(layer "In13.Cu")
		(net "M_H_CPU0_SB_DQS_DN<2>")
	)
	(segment
		(start 423.755058 -304.177954)
		(end 424.012106 -304.435002)
		(width 0.16002)
		(layer "In13.Cu")
		(net "M_H_CPU0_SB_DQS_DN<2>")
	)
	(segment
		(start 395.824202 -286.924496)
		(end 396.007336 -286.924496)
		(width 0.16002)
		(layer "In13.Cu")
		(net "M_H_CPU0_SB_DQS_DN<2>")
	)
	(segment
		(start 415.865056 -303.712118)
		(end 416.342576 -303.712118)
		(width 0.16002)
		(layer "In13.Cu")
		(net "M_H_CPU0_SB_DQS_DN<2>")
	)
	(segment
		(start 418.325046 -304.012092)
		(end 420.232078 -304.012092)
		(width 0.16002)
		(layer "In13.Cu")
		(net "M_H_CPU0_SB_DQS_DN<2>")
	)
	(segment
		(start 414.052512 -304.357278)
		(end 414.837372 -303.572418)
		(width 0.16002)
		(layer "In13.Cu")
		(net "M_H_CPU0_SB_DQS_DN<2>")
	)
	(segment
		(start 417.885372 -303.572418)
		(end 418.325046 -304.012092)
		(width 0.16002)
		(layer "In13.Cu")
		(net "M_H_CPU0_SB_DQS_DN<2>")
	)
	(segment
		(start 389.906256 -285.911036)
		(end 389.914638 -285.90621)
		(width 0.09525)
		(layer "In13.Cu")
		(net "M_H_CPU0_SB_DQS_DN<2>")
	)
	(segment
		(start 403.562566 -298.634404)
		(end 403.349968 -298.847002)
		(width 0.16002)
		(layer "In13.Cu")
		(net "M_H_CPU0_SB_DQS_DN<2>")
	)
	(segment
		(start 389.33501 -285.90621)
		(end 389.343392 -285.911036)
		(width 0.09525)
		(layer "In13.Cu")
		(net "M_H_CPU0_SB_DQS_DN<2>")
	)
	(segment
		(start 402.805646 -298.30268)
		(end 403.018244 -298.090082)
		(width 0.16002)
		(layer "In13.Cu")
		(net "M_H_CPU0_SB_DQS_DN<2>")
	)
	(segment
		(start 403.349968 -298.847002)
		(end 403.349968 -299.323506)
		(width 0.16002)
		(layer "In13.Cu")
		(net "M_H_CPU0_SB_DQS_DN<2>")
	)
	(segment
		(start 416.342576 -303.712118)
		(end 416.482276 -303.572418)
		(width 0.16002)
		(layer "In13.Cu")
		(net "M_H_CPU0_SB_DQS_DN<2>")
	)
	(segment
		(start 395.741652 -286.865568)
		(end 395.80058 -286.924496)
		(width 0.09525)
		(layer "In13.Cu")
		(net "M_H_CPU0_SB_DQS_DN<2>")
	)
	(segment
		(start 403.244304 -298.090082)
		(end 403.562566 -298.408344)
		(width 0.16002)
		(layer "In13.Cu")
		(net "M_H_CPU0_SB_DQS_DN<2>")
	)
	(segment
		(start 422.72331 -303.56937)
		(end 423.331894 -304.177954)
		(width 0.16002)
		(layer "In13.Cu")
		(net "M_H_CPU0_SB_DQS_DN<2>")
	)
	(segment
		(start 384.300984 -285.970726)
		(end 384.324352 -285.883858)
		(width 0.09525)
		(layer "In13.Cu")
		(net "M_H_CPU0_SB_DQS_DN<2>")
	)
	(segment
		(start 401.443698 -296.289476)
		(end 402.045678 -296.891456)
		(width 0.16002)
		(layer "In13.Cu")
		(net "M_H_CPU0_SB_DQS_DN<2>")
	)
	(segment
		(start 414.837372 -303.572418)
		(end 415.725356 -303.572418)
		(width 0.16002)
		(layer "In13.Cu")
		(net "M_H_CPU0_SB_DQS_DN<2>")
	)
	(segment
		(start 388.394956 -285.90621)
		(end 388.403338 -285.911036)
		(width 0.09525)
		(layer "In13.Cu")
		(net "M_H_CPU0_SB_DQS_DN<2>")
	)
	(segment
		(start 421.718994 -304.347118)
		(end 422.496742 -303.56937)
		(width 0.16002)
		(layer "In13.Cu")
		(net "M_H_CPU0_SB_DQS_DN<2>")
	)
	(segment
		(start 384.634994 -285.90621)
		(end 384.643376 -285.911036)
		(width 0.09525)
		(layer "In13.Cu")
		(net "M_H_CPU0_SB_DQS_DN<2>")
	)
	(segment
		(start 395.563344 -286.865568)
		(end 395.741652 -286.865568)
		(width 0.09525)
		(layer "In13.Cu")
		(net "M_H_CPU0_SB_DQS_DN<2>")
	)
	(segment
		(start 409.175458 -304.021236)
		(end 411.063186 -304.021236)
		(width 0.16002)
		(layer "In13.Cu")
		(net "M_H_CPU0_SB_DQS_DN<2>")
	)
	(segment
		(start 394.14323 -285.98749)
		(end 394.71854 -286.5628)
		(width 0.09525)
		(layer "In13.Cu")
		(net "M_H_CPU0_SB_DQS_DN<2>")
	)
	(segment
		(start 394.71854 -286.5628)
		(end 395.260576 -286.5628)
		(width 0.09525)
		(layer "In13.Cu")
		(net "M_H_CPU0_SB_DQS_DN<2>")
	)
	(segment
		(start 401.83308 -297.806618)
		(end 402.329142 -298.30268)
		(width 0.16002)
		(layer "In13.Cu")
		(net "M_H_CPU0_SB_DQS_DN<2>")
	)
	(segment
		(start 392.723878 -285.911036)
		(end 392.742674 -285.900114)
		(width 0.09525)
		(layer "In13.Cu")
		(net "M_H_CPU0_SB_DQS_DN<2>")
	)
	(segment
		(start 384.454908 -286.236156)
		(end 384.300984 -285.970726)
		(width 0.09525)
		(layer "In13.Cu")
		(net "M_H_CPU0_SB_DQS_DN<2>")
	)
	(segment
		(start 403.018244 -298.090082)
		(end 403.244304 -298.090082)
		(width 0.16002)
		(layer "In13.Cu")
		(net "M_H_CPU0_SB_DQS_DN<2>")
	)
	(segment
		(start 386.146294 -285.911036)
		(end 386.154676 -285.90621)
		(width 0.09525)
		(layer "In13.Cu")
		(net "M_H_CPU0_SB_DQS_DN<2>")
	)
	(segment
		(start 395.80058 -286.924496)
		(end 395.824202 -286.924496)
		(width 0.09525)
		(layer "In13.Cu")
		(net "M_H_CPU0_SB_DQS_DN<2>")
	)
	(segment
		(start 401.443698 -292.360858)
		(end 401.443698 -296.289476)
		(width 0.16002)
		(layer "In13.Cu")
		(net "M_H_CPU0_SB_DQS_DN<2>")
	)
	(segment
		(start 392.145774 -285.901384)
		(end 392.187938 -285.925768)
		(width 0.09525)
		(layer "In13.Cu")
		(net "M_H_CPU0_SB_DQS_DN<2>")
	)
	(segment
		(start 403.562566 -298.408344)
		(end 403.562566 -298.634404)
		(width 0.16002)
		(layer "In13.Cu")
		(net "M_H_CPU0_SB_DQS_DN<2>")
	)
	(segment
		(start 402.045678 -297.117516)
		(end 401.83308 -297.330114)
		(width 0.16002)
		(layer "In13.Cu")
		(net "M_H_CPU0_SB_DQS_DN<2>")
	)
	(segment
		(start 396.007336 -286.924496)
		(end 401.443698 -292.360858)
		(width 0.16002)
		(layer "In13.Cu")
		(net "M_H_CPU0_SB_DQS_DN<2>")
	)
	(segment
		(start 393.384786 -285.98749)
		(end 394.14323 -285.98749)
		(width 0.09525)
		(layer "In13.Cu")
		(net "M_H_CPU0_SB_DQS_DN<2>")
	)
	(segment
		(start 415.725356 -303.572418)
		(end 415.865056 -303.712118)
		(width 0.16002)
		(layer "In13.Cu")
		(net "M_H_CPU0_SB_DQS_DN<2>")
	)
	(segment
		(start 395.260576 -286.5628)
		(end 395.563344 -286.865568)
		(width 0.09525)
		(layer "In13.Cu")
		(net "M_H_CPU0_SB_DQS_DN<2>")
	)
	(segment
		(start 422.496742 -303.56937)
		(end 422.72331 -303.56937)
		(width 0.16002)
		(layer "In13.Cu")
		(net "M_H_CPU0_SB_DQS_DN<2>")
	)
	(segment
		(start 401.83308 -297.330114)
		(end 401.83308 -297.806618)
		(width 0.16002)
		(layer "In13.Cu")
		(net "M_H_CPU0_SB_DQS_DN<2>")
	)
	(segment
		(start 402.045678 -296.891456)
		(end 402.045678 -297.117516)
		(width 0.16002)
		(layer "In13.Cu")
		(net "M_H_CPU0_SB_DQS_DN<2>")
	)
	(segment
		(start 402.329142 -298.30268)
		(end 402.805646 -298.30268)
		(width 0.16002)
		(layer "In13.Cu")
		(net "M_H_CPU0_SB_DQS_DN<2>")
	)
	(segment
		(start 416.482276 -303.572418)
		(end 417.885372 -303.572418)
		(width 0.16002)
		(layer "In13.Cu")
		(net "M_H_CPU0_SB_DQS_DN<2>")
	)
	(segment
		(start 420.567104 -304.347118)
		(end 421.718994 -304.347118)
		(width 0.16002)
		(layer "In13.Cu")
		(net "M_H_CPU0_SB_DQS_DN<2>")
	)
	(segment
		(start 423.331894 -304.177954)
		(end 423.755058 -304.177954)
		(width 0.16002)
		(layer "In13.Cu")
		(net "M_H_CPU0_SB_DQS_DN<2>")
	)
	(segment
		(start 411.063186 -304.021236)
		(end 411.399228 -304.357278)
		(width 0.16002)
		(layer "In13.Cu")
		(net "M_H_CPU0_SB_DQS_DN<2>")
	)
	(segment
		(start 385.20624 -285.911036)
		(end 385.214622 -285.90621)
		(width 0.09525)
		(layer "In13.Cu")
		(net "M_H_CPU0_SB_DQS_DN<2>")
	)
	(segment
		(start 403.84603 -299.819568)
		(end 404.322534 -299.819568)
		(width 0.16002)
		(layer "In13.Cu")
		(net "M_H_CPU0_SB_DQS_DN<2>")
	)
	(segment
		(start 404.535132 -299.60697)
		(end 404.761192 -299.60697)
		(width 0.16002)
		(layer "In13.Cu")
		(net "M_H_CPU0_SB_DQS_DN<2>")
	)
	(segment
		(start 404.761192 -299.60697)
		(end 409.175458 -304.021236)
		(width 0.16002)
		(layer "In13.Cu")
		(net "M_H_CPU0_SB_DQS_DN<2>")
	)
	(segment
		(start 420.232078 -304.012092)
		(end 420.567104 -304.347118)
		(width 0.16002)
		(layer "In13.Cu")
		(net "M_H_CPU0_SB_DQS_DN<2>")
	)
	(segment
		(start 411.399228 -304.357278)
		(end 414.052512 -304.357278)
		(width 0.16002)
		(layer "In13.Cu")
		(net "M_H_CPU0_SB_DQS_DN<2>")
	)
	(arc
		(start 385.214622 -285.90621)
		(mid 385.399654 -285.860296)
		(end 385.58343 -285.911036)
		(width 0.09525)
		(layer "In13.Cu")
		(net "M_H_CPU0_SB_DQS_DN<2>")
	)
	(arc
		(start 384.643376 -285.911036)
		(mid 384.924808 -285.986791)
		(end 385.20624 -285.911036)
		(width 0.09525)
		(layer "In13.Cu")
		(net "M_H_CPU0_SB_DQS_DN<2>")
	)
	(arc
		(start 392.742674 -285.900114)
		(mid 392.923769 -285.859882)
		(end 393.102084 -285.911036)
		(width 0.09525)
		(layer "In13.Cu")
		(net "M_H_CPU0_SB_DQS_DN<2>")
	)
	(arc
		(start 390.283446 -285.911036)
		(mid 390.564878 -285.986791)
		(end 390.84631 -285.911036)
		(width 0.09525)
		(layer "In13.Cu")
		(net "M_H_CPU0_SB_DQS_DN<2>")
	)
	(arc
		(start 388.403338 -285.911036)
		(mid 388.68477 -285.986791)
		(end 388.966202 -285.911036)
		(width 0.09525)
		(layer "In13.Cu")
		(net "M_H_CPU0_SB_DQS_DN<2>")
	)
	(arc
		(start 386.154676 -285.90621)
		(mid 386.339708 -285.860296)
		(end 386.523484 -285.911036)
		(width 0.09525)
		(layer "In13.Cu")
		(net "M_H_CPU0_SB_DQS_DN<2>")
	)
	(arc
		(start 388.026148 -285.911036)
		(mid 388.209923 -285.860264)
		(end 388.394956 -285.90621)
		(width 0.09525)
		(layer "In13.Cu")
		(net "M_H_CPU0_SB_DQS_DN<2>")
	)
	(arc
		(start 384.324352 -285.883858)
		(mid 384.482102 -285.861339)
		(end 384.634994 -285.90621)
		(width 0.09525)
		(layer "In13.Cu")
		(net "M_H_CPU0_SB_DQS_DN<2>")
	)
	(arc
		(start 391.78611 -285.911036)
		(mid 391.964716 -285.860368)
		(end 392.145774 -285.901384)
		(width 0.09525)
		(layer "In13.Cu")
		(net "M_H_CPU0_SB_DQS_DN<2>")
	)
	(arc
		(start 386.523484 -285.911036)
		(mid 386.804916 -285.986791)
		(end 387.086348 -285.911036)
		(width 0.09525)
		(layer "In13.Cu")
		(net "M_H_CPU0_SB_DQS_DN<2>")
	)
	(arc
		(start 389.343392 -285.911036)
		(mid 389.624824 -285.986791)
		(end 389.906256 -285.911036)
		(width 0.09525)
		(layer "In13.Cu")
		(net "M_H_CPU0_SB_DQS_DN<2>")
	)
	(arc
		(start 388.966202 -285.911036)
		(mid 389.149977 -285.860264)
		(end 389.33501 -285.90621)
		(width 0.09525)
		(layer "In13.Cu")
		(net "M_H_CPU0_SB_DQS_DN<2>")
	)
	(arc
		(start 391.223246 -285.911036)
		(mid 391.504678 -285.986791)
		(end 391.78611 -285.911036)
		(width 0.09525)
		(layer "In13.Cu")
		(net "M_H_CPU0_SB_DQS_DN<2>")
	)
	(arc
		(start 390.84631 -285.911036)
		(mid 391.034778 -285.860359)
		(end 391.223246 -285.911036)
		(width 0.09525)
		(layer "In13.Cu")
		(net "M_H_CPU0_SB_DQS_DN<2>")
	)
	(arc
		(start 385.58343 -285.911036)
		(mid 385.864862 -285.986791)
		(end 386.146294 -285.911036)
		(width 0.09525)
		(layer "In13.Cu")
		(net "M_H_CPU0_SB_DQS_DN<2>")
	)
	(arc
		(start 392.187938 -285.925768)
		(mid 392.457792 -285.986647)
		(end 392.723878 -285.911036)
		(width 0.09525)
		(layer "In13.Cu")
		(net "M_H_CPU0_SB_DQS_DN<2>")
	)
	(arc
		(start 389.914638 -285.90621)
		(mid 390.09967 -285.860296)
		(end 390.283446 -285.911036)
		(width 0.09525)
		(layer "In13.Cu")
		(net "M_H_CPU0_SB_DQS_DN<2>")
	)
	(arc
		(start 387.086348 -285.911036)
		(mid 387.274816 -285.860359)
		(end 387.463284 -285.911036)
		(width 0.09525)
		(layer "In13.Cu")
		(net "M_H_CPU0_SB_DQS_DN<2>")
	)
	(arc
		(start 393.102084 -285.911036)
		(mid 393.238365 -285.967995)
		(end 393.384786 -285.98749)
		(width 0.09525)
		(layer "In13.Cu")
		(net "M_H_CPU0_SB_DQS_DN<2>")
	)
	(arc
		(start 387.463284 -285.911036)
		(mid 387.744716 -285.986791)
		(end 388.026148 -285.911036)
		(width 0.09525)
		(layer "In13.Cu")
		(net "M_H_CPU0_SB_DQS_DN<2>")
	)
	(segment
		(start 383.988056 -281.110182)
		(end 384.454908 -281.37612)
		(width 0.12954)
		(layer "F.Cu")
		(net "M_H_CPU0_SB_DQS_DN<1>")
	)
	(segment
		(start 422.900094 -294.997124)
		(end 420.567104 -294.997124)
		(width 0.16002)
		(layer "In13.Cu")
		(net "M_H_CPU0_SB_DQS_DN<1>")
	)
	(segment
		(start 385.214622 -281.046174)
		(end 385.20624 -281.051)
		(width 0.09525)
		(layer "In13.Cu")
		(net "M_H_CPU0_SB_DQS_DN<1>")
	)
	(segment
		(start 392.18362 -281.063192)
		(end 392.148314 -281.042618)
		(width 0.09525)
		(layer "In13.Cu")
		(net "M_H_CPU0_SB_DQS_DN<1>")
	)
	(segment
		(start 414.837372 -294.222424)
		(end 414.052512 -295.007284)
		(width 0.16002)
		(layer "In13.Cu")
		(net "M_H_CPU0_SB_DQS_DN<1>")
	)
	(segment
		(start 406.980898 -291.09162)
		(end 406.980898 -290.064444)
		(width 0.16002)
		(layer "In13.Cu")
		(net "M_H_CPU0_SB_DQS_DN<1>")
	)
	(segment
		(start 395.471904 -281.10053)
		(end 395.09319 -280.721816)
		(width 0.09525)
		(layer "In13.Cu")
		(net "M_H_CPU0_SB_DQS_DN<1>")
	)
	(segment
		(start 408.229054 -291.781484)
		(end 407.670762 -291.781484)
		(width 0.16002)
		(layer "In13.Cu")
		(net "M_H_CPU0_SB_DQS_DN<1>")
	)
	(segment
		(start 414.052512 -295.007284)
		(end 413.08401 -295.007284)
		(width 0.16002)
		(layer "In13.Cu")
		(net "M_H_CPU0_SB_DQS_DN<1>")
	)
	(segment
		(start 423.117264 -294.779954)
		(end 422.900094 -294.997124)
		(width 0.16002)
		(layer "In13.Cu")
		(net "M_H_CPU0_SB_DQS_DN<1>")
	)
	(segment
		(start 423.707052 -294.779954)
		(end 423.117264 -294.779954)
		(width 0.16002)
		(layer "In13.Cu")
		(net "M_H_CPU0_SB_DQS_DN<1>")
	)
	(segment
		(start 409.851352 -295.469564)
		(end 409.374594 -295.469564)
		(width 0.16002)
		(layer "In13.Cu")
		(net "M_H_CPU0_SB_DQS_DN<1>")
	)
	(segment
		(start 395.09319 -280.721816)
		(end 394.153644 -280.721816)
		(width 0.09525)
		(layer "In13.Cu")
		(net "M_H_CPU0_SB_DQS_DN<1>")
	)
	(segment
		(start 384.300984 -281.11069)
		(end 384.454908 -281.37612)
		(width 0.09525)
		(layer "In13.Cu")
		(net "M_H_CPU0_SB_DQS_DN<1>")
	)
	(segment
		(start 424.012106 -295.085008)
		(end 423.707052 -294.779954)
		(width 0.16002)
		(layer "In13.Cu")
		(net "M_H_CPU0_SB_DQS_DN<1>")
	)
	(segment
		(start 420.567104 -294.997124)
		(end 420.232078 -294.662098)
		(width 0.16002)
		(layer "In13.Cu")
		(net "M_H_CPU0_SB_DQS_DN<1>")
	)
	(segment
		(start 384.643376 -281.051)
		(end 384.634994 -281.046174)
		(width 0.09525)
		(layer "In13.Cu")
		(net "M_H_CPU0_SB_DQS_DN<1>")
	)
	(segment
		(start 409.055824 -293.895526)
		(end 409.055824 -292.608254)
		(width 0.16002)
		(layer "In13.Cu")
		(net "M_H_CPU0_SB_DQS_DN<1>")
	)
	(segment
		(start 410.558996 -294.76192)
		(end 409.851352 -295.469564)
		(width 0.16002)
		(layer "In13.Cu")
		(net "M_H_CPU0_SB_DQS_DN<1>")
	)
	(segment
		(start 389.914638 -281.046174)
		(end 389.906256 -281.051)
		(width 0.09525)
		(layer "In13.Cu")
		(net "M_H_CPU0_SB_DQS_DN<1>")
	)
	(segment
		(start 408.666442 -294.761412)
		(end 408.666442 -294.284908)
		(width 0.16002)
		(layer "In13.Cu")
		(net "M_H_CPU0_SB_DQS_DN<1>")
	)
	(segment
		(start 384.324352 -281.023822)
		(end 384.300984 -281.11069)
		(width 0.09525)
		(layer "In13.Cu")
		(net "M_H_CPU0_SB_DQS_DN<1>")
	)
	(segment
		(start 409.374594 -295.469564)
		(end 408.666442 -294.761412)
		(width 0.16002)
		(layer "In13.Cu")
		(net "M_H_CPU0_SB_DQS_DN<1>")
	)
	(segment
		(start 406.980898 -290.064444)
		(end 398.075912 -281.159458)
		(width 0.16002)
		(layer "In13.Cu")
		(net "M_H_CPU0_SB_DQS_DN<1>")
	)
	(segment
		(start 408.666442 -294.284908)
		(end 409.055824 -293.895526)
		(width 0.16002)
		(layer "In13.Cu")
		(net "M_H_CPU0_SB_DQS_DN<1>")
	)
	(segment
		(start 417.885372 -294.222424)
		(end 414.837372 -294.222424)
		(width 0.16002)
		(layer "In13.Cu")
		(net "M_H_CPU0_SB_DQS_DN<1>")
	)
	(segment
		(start 395.649958 -281.10053)
		(end 395.471904 -281.10053)
		(width 0.09525)
		(layer "In13.Cu")
		(net "M_H_CPU0_SB_DQS_DN<1>")
	)
	(segment
		(start 412.838646 -294.76192)
		(end 410.558996 -294.76192)
		(width 0.16002)
		(layer "In13.Cu")
		(net "M_H_CPU0_SB_DQS_DN<1>")
	)
	(segment
		(start 413.08401 -295.007284)
		(end 412.838646 -294.76192)
		(width 0.16002)
		(layer "In13.Cu")
		(net "M_H_CPU0_SB_DQS_DN<1>")
	)
	(segment
		(start 409.055824 -292.608254)
		(end 408.229054 -291.781484)
		(width 0.16002)
		(layer "In13.Cu")
		(net "M_H_CPU0_SB_DQS_DN<1>")
	)
	(segment
		(start 395.732508 -281.159458)
		(end 395.708886 -281.159458)
		(width 0.09525)
		(layer "In13.Cu")
		(net "M_H_CPU0_SB_DQS_DN<1>")
	)
	(segment
		(start 407.670762 -291.781484)
		(end 406.980898 -291.09162)
		(width 0.16002)
		(layer "In13.Cu")
		(net "M_H_CPU0_SB_DQS_DN<1>")
	)
	(segment
		(start 395.708886 -281.159458)
		(end 395.649958 -281.10053)
		(width 0.09525)
		(layer "In13.Cu")
		(net "M_H_CPU0_SB_DQS_DN<1>")
	)
	(segment
		(start 392.739118 -281.042618)
		(end 392.72464 -281.051)
		(width 0.09525)
		(layer "In13.Cu")
		(net "M_H_CPU0_SB_DQS_DN<1>")
	)
	(segment
		(start 389.343392 -281.051)
		(end 389.33501 -281.046174)
		(width 0.09525)
		(layer "In13.Cu")
		(net "M_H_CPU0_SB_DQS_DN<1>")
	)
	(segment
		(start 394.019786 -280.777442)
		(end 393.670028 -281.1272)
		(width 0.09525)
		(layer "In13.Cu")
		(net "M_H_CPU0_SB_DQS_DN<1>")
	)
	(segment
		(start 418.325046 -294.662098)
		(end 417.885372 -294.222424)
		(width 0.16002)
		(layer "In13.Cu")
		(net "M_H_CPU0_SB_DQS_DN<1>")
	)
	(segment
		(start 393.670028 -281.1272)
		(end 393.384786 -281.1272)
		(width 0.09525)
		(layer "In13.Cu")
		(net "M_H_CPU0_SB_DQS_DN<1>")
	)
	(segment
		(start 398.075912 -281.159458)
		(end 395.732508 -281.159458)
		(width 0.16002)
		(layer "In13.Cu")
		(net "M_H_CPU0_SB_DQS_DN<1>")
	)
	(segment
		(start 388.403338 -281.051)
		(end 388.394956 -281.046174)
		(width 0.09525)
		(layer "In13.Cu")
		(net "M_H_CPU0_SB_DQS_DN<1>")
	)
	(segment
		(start 386.154676 -281.046174)
		(end 386.146294 -281.051)
		(width 0.09525)
		(layer "In13.Cu")
		(net "M_H_CPU0_SB_DQS_DN<1>")
	)
	(segment
		(start 420.232078 -294.662098)
		(end 418.325046 -294.662098)
		(width 0.16002)
		(layer "In13.Cu")
		(net "M_H_CPU0_SB_DQS_DN<1>")
	)
	(arc
		(start 387.463284 -281.051)
		(mid 387.274816 -281.000323)
		(end 387.086348 -281.051)
		(width 0.09525)
		(layer "In13.Cu")
		(net "M_H_CPU0_SB_DQS_DN<1>")
	)
	(arc
		(start 392.148314 -281.042618)
		(mid 391.966136 -281.000296)
		(end 391.78611 -281.051)
		(width 0.09525)
		(layer "In13.Cu")
		(net "M_H_CPU0_SB_DQS_DN<1>")
	)
	(arc
		(start 389.33501 -281.046174)
		(mid 389.149978 -281.00026)
		(end 388.966202 -281.051)
		(width 0.09525)
		(layer "In13.Cu")
		(net "M_H_CPU0_SB_DQS_DN<1>")
	)
	(arc
		(start 393.102338 -281.051)
		(mid 392.921805 -281.000041)
		(end 392.739118 -281.042618)
		(width 0.09525)
		(layer "In13.Cu")
		(net "M_H_CPU0_SB_DQS_DN<1>")
	)
	(arc
		(start 388.026148 -281.051)
		(mid 387.744716 -281.126755)
		(end 387.463284 -281.051)
		(width 0.09525)
		(layer "In13.Cu")
		(net "M_H_CPU0_SB_DQS_DN<1>")
	)
	(arc
		(start 390.283446 -281.051)
		(mid 390.099671 -281.000228)
		(end 389.914638 -281.046174)
		(width 0.09525)
		(layer "In13.Cu")
		(net "M_H_CPU0_SB_DQS_DN<1>")
	)
	(arc
		(start 389.906256 -281.051)
		(mid 389.624824 -281.126755)
		(end 389.343392 -281.051)
		(width 0.09525)
		(layer "In13.Cu")
		(net "M_H_CPU0_SB_DQS_DN<1>")
	)
	(arc
		(start 393.384786 -281.1272)
		(mid 393.238521 -281.1078)
		(end 393.102338 -281.051)
		(width 0.09525)
		(layer "In13.Cu")
		(net "M_H_CPU0_SB_DQS_DN<1>")
	)
	(arc
		(start 391.223246 -281.051)
		(mid 391.034778 -281.000323)
		(end 390.84631 -281.051)
		(width 0.09525)
		(layer "In13.Cu")
		(net "M_H_CPU0_SB_DQS_DN<1>")
	)
	(arc
		(start 384.634994 -281.046174)
		(mid 384.482099 -281.001346)
		(end 384.324352 -281.023822)
		(width 0.09525)
		(layer "In13.Cu")
		(net "M_H_CPU0_SB_DQS_DN<1>")
	)
	(arc
		(start 387.086348 -281.051)
		(mid 386.804916 -281.126755)
		(end 386.523484 -281.051)
		(width 0.09525)
		(layer "In13.Cu")
		(net "M_H_CPU0_SB_DQS_DN<1>")
	)
	(arc
		(start 391.78611 -281.051)
		(mid 391.504678 -281.126755)
		(end 391.223246 -281.051)
		(width 0.09525)
		(layer "In13.Cu")
		(net "M_H_CPU0_SB_DQS_DN<1>")
	)
	(arc
		(start 388.966202 -281.051)
		(mid 388.68477 -281.126755)
		(end 388.403338 -281.051)
		(width 0.09525)
		(layer "In13.Cu")
		(net "M_H_CPU0_SB_DQS_DN<1>")
	)
	(arc
		(start 390.84631 -281.051)
		(mid 390.564878 -281.126755)
		(end 390.283446 -281.051)
		(width 0.09525)
		(layer "In13.Cu")
		(net "M_H_CPU0_SB_DQS_DN<1>")
	)
	(arc
		(start 394.153644 -280.721816)
		(mid 394.0812 -280.736338)
		(end 394.019786 -280.777442)
		(width 0.09525)
		(layer "In13.Cu")
		(net "M_H_CPU0_SB_DQS_DN<1>")
	)
	(arc
		(start 385.58343 -281.051)
		(mid 385.399655 -281.000228)
		(end 385.214622 -281.046174)
		(width 0.09525)
		(layer "In13.Cu")
		(net "M_H_CPU0_SB_DQS_DN<1>")
	)
	(arc
		(start 386.523484 -281.051)
		(mid 386.339709 -281.000228)
		(end 386.154676 -281.046174)
		(width 0.09525)
		(layer "In13.Cu")
		(net "M_H_CPU0_SB_DQS_DN<1>")
	)
	(arc
		(start 386.146294 -281.051)
		(mid 385.864862 -281.126755)
		(end 385.58343 -281.051)
		(width 0.09525)
		(layer "In13.Cu")
		(net "M_H_CPU0_SB_DQS_DN<1>")
	)
	(arc
		(start 388.394956 -281.046174)
		(mid 388.209924 -281.00026)
		(end 388.026148 -281.051)
		(width 0.09525)
		(layer "In13.Cu")
		(net "M_H_CPU0_SB_DQS_DN<1>")
	)
	(arc
		(start 385.20624 -281.051)
		(mid 384.924808 -281.126755)
		(end 384.643376 -281.051)
		(width 0.09525)
		(layer "In13.Cu")
		(net "M_H_CPU0_SB_DQS_DN<1>")
	)
	(arc
		(start 392.72464 -281.051)
		(mid 392.455686 -281.126738)
		(end 392.18362 -281.063192)
		(width 0.09525)
		(layer "In13.Cu")
		(net "M_H_CPU0_SB_DQS_DN<1>")
	)
	(segment
		(start 383.988056 -276.250146)
		(end 384.454908 -276.516084)
		(width 0.12954)
		(layer "F.Cu")
		(net "M_H_CPU0_SB_DQS_DN<0>")
	)
	(segment
		(start 416.206432 -284.330902)
		(end 416.366452 -284.170882)
		(width 0.16002)
		(layer "In13.Cu")
		(net "M_H_CPU0_SB_DQS_DN<0>")
	)
	(segment
		(start 395.634464 -275.140674)
		(end 395.693646 -275.199856)
		(width 0.09525)
		(layer "In13.Cu")
		(net "M_H_CPU0_SB_DQS_DN<0>")
	)
	(segment
		(start 388.394956 -276.186138)
		(end 388.403338 -276.190964)
		(width 0.09525)
		(layer "In13.Cu")
		(net "M_H_CPU0_SB_DQS_DN<0>")
	)
	(segment
		(start 384.300984 -276.250654)
		(end 384.324352 -276.163786)
		(width 0.09525)
		(layer "In13.Cu")
		(net "M_H_CPU0_SB_DQS_DN<0>")
	)
	(segment
		(start 420.945056 -285.64713)
		(end 421.58666 -285.64713)
		(width 0.16002)
		(layer "In13.Cu")
		(net "M_H_CPU0_SB_DQS_DN<0>")
	)
	(segment
		(start 395.717268 -275.199856)
		(end 400.445478 -275.199856)
		(width 0.16002)
		(layer "In13.Cu")
		(net "M_H_CPU0_SB_DQS_DN<0>")
	)
	(segment
		(start 418.099494 -285.040832)
		(end 420.338758 -285.040832)
		(width 0.16002)
		(layer "In13.Cu")
		(net "M_H_CPU0_SB_DQS_DN<0>")
	)
	(segment
		(start 393.78001 -276.102826)
		(end 394.701522 -275.181314)
		(width 0.09525)
		(layer "In13.Cu")
		(net "M_H_CPU0_SB_DQS_DN<0>")
	)
	(segment
		(start 420.338758 -285.040832)
		(end 420.945056 -285.64713)
		(width 0.16002)
		(layer "In13.Cu")
		(net "M_H_CPU0_SB_DQS_DN<0>")
	)
	(segment
		(start 416.366452 -284.170882)
		(end 416.816032 -284.170882)
		(width 0.16002)
		(layer "In13.Cu")
		(net "M_H_CPU0_SB_DQS_DN<0>")
	)
	(segment
		(start 389.33501 -276.186138)
		(end 389.343392 -276.190964)
		(width 0.09525)
		(layer "In13.Cu")
		(net "M_H_CPU0_SB_DQS_DN<0>")
	)
	(segment
		(start 415.869374 -284.87243)
		(end 416.206432 -284.535372)
		(width 0.16002)
		(layer "In13.Cu")
		(net "M_H_CPU0_SB_DQS_DN<0>")
	)
	(segment
		(start 404.122636 -277.891494)
		(end 411.151832 -284.92069)
		(width 0.16002)
		(layer "In13.Cu")
		(net "M_H_CPU0_SB_DQS_DN<0>")
	)
	(segment
		(start 392.737594 -276.183598)
		(end 392.739118 -276.182582)
		(width 0.09525)
		(layer "In13.Cu")
		(net "M_H_CPU0_SB_DQS_DN<0>")
	)
	(segment
		(start 400.445478 -275.199856)
		(end 403.137116 -277.891494)
		(width 0.16002)
		(layer "In13.Cu")
		(net "M_H_CPU0_SB_DQS_DN<0>")
	)
	(segment
		(start 384.454908 -276.516084)
		(end 384.300984 -276.250654)
		(width 0.09525)
		(layer "In13.Cu")
		(net "M_H_CPU0_SB_DQS_DN<0>")
	)
	(segment
		(start 421.58666 -285.64713)
		(end 421.775636 -285.458154)
		(width 0.16002)
		(layer "In13.Cu")
		(net "M_H_CPU0_SB_DQS_DN<0>")
	)
	(segment
		(start 394.701522 -275.181314)
		(end 395.3002 -275.181314)
		(width 0.09525)
		(layer "In13.Cu")
		(net "M_H_CPU0_SB_DQS_DN<0>")
	)
	(segment
		(start 417.69284 -284.87243)
		(end 418.099494 -285.040832)
		(width 0.16002)
		(layer "In13.Cu")
		(net "M_H_CPU0_SB_DQS_DN<0>")
	)
	(segment
		(start 416.206432 -284.535372)
		(end 416.206432 -284.330902)
		(width 0.16002)
		(layer "In13.Cu")
		(net "M_H_CPU0_SB_DQS_DN<0>")
	)
	(segment
		(start 422.902634 -285.597854)
		(end 423.042334 -285.458154)
		(width 0.16002)
		(layer "In13.Cu")
		(net "M_H_CPU0_SB_DQS_DN<0>")
	)
	(segment
		(start 386.146294 -276.190964)
		(end 386.154676 -276.186138)
		(width 0.09525)
		(layer "In13.Cu")
		(net "M_H_CPU0_SB_DQS_DN<0>")
	)
	(segment
		(start 417.31311 -284.87243)
		(end 417.69284 -284.87243)
		(width 0.16002)
		(layer "In13.Cu")
		(net "M_H_CPU0_SB_DQS_DN<0>")
	)
	(segment
		(start 422.285414 -285.458154)
		(end 422.425114 -285.597854)
		(width 0.16002)
		(layer "In13.Cu")
		(net "M_H_CPU0_SB_DQS_DN<0>")
	)
	(segment
		(start 411.151832 -284.92069)
		(end 412.762192 -284.92069)
		(width 0.16002)
		(layer "In13.Cu")
		(net "M_H_CPU0_SB_DQS_DN<0>")
	)
	(segment
		(start 414.052512 -285.65729)
		(end 414.837372 -284.87243)
		(width 0.16002)
		(layer "In13.Cu")
		(net "M_H_CPU0_SB_DQS_DN<0>")
	)
	(segment
		(start 403.137116 -277.891494)
		(end 404.122636 -277.891494)
		(width 0.16002)
		(layer "In13.Cu")
		(net "M_H_CPU0_SB_DQS_DN<0>")
	)
	(segment
		(start 384.634994 -276.186138)
		(end 384.643376 -276.190964)
		(width 0.09525)
		(layer "In13.Cu")
		(net "M_H_CPU0_SB_DQS_DN<0>")
	)
	(segment
		(start 423.042334 -285.458154)
		(end 423.735246 -285.458154)
		(width 0.16002)
		(layer "In13.Cu")
		(net "M_H_CPU0_SB_DQS_DN<0>")
	)
	(segment
		(start 412.762192 -284.92069)
		(end 413.498792 -285.65729)
		(width 0.16002)
		(layer "In13.Cu")
		(net "M_H_CPU0_SB_DQS_DN<0>")
	)
	(segment
		(start 421.775636 -285.458154)
		(end 422.285414 -285.458154)
		(width 0.16002)
		(layer "In13.Cu")
		(net "M_H_CPU0_SB_DQS_DN<0>")
	)
	(segment
		(start 395.3002 -275.181314)
		(end 395.34084 -275.140674)
		(width 0.09525)
		(layer "In13.Cu")
		(net "M_H_CPU0_SB_DQS_DN<0>")
	)
	(segment
		(start 423.735246 -285.458154)
		(end 424.012106 -285.735014)
		(width 0.16002)
		(layer "In13.Cu")
		(net "M_H_CPU0_SB_DQS_DN<0>")
	)
	(segment
		(start 392.72464 -276.190964)
		(end 392.737594 -276.183598)
		(width 0.09525)
		(layer "In13.Cu")
		(net "M_H_CPU0_SB_DQS_DN<0>")
	)
	(segment
		(start 416.976052 -284.330902)
		(end 416.976052 -284.535372)
		(width 0.16002)
		(layer "In13.Cu")
		(net "M_H_CPU0_SB_DQS_DN<0>")
	)
	(segment
		(start 395.693646 -275.199856)
		(end 395.717268 -275.199856)
		(width 0.09525)
		(layer "In13.Cu")
		(net "M_H_CPU0_SB_DQS_DN<0>")
	)
	(segment
		(start 389.906256 -276.190964)
		(end 389.914638 -276.186138)
		(width 0.09525)
		(layer "In13.Cu")
		(net "M_H_CPU0_SB_DQS_DN<0>")
	)
	(segment
		(start 414.837372 -284.87243)
		(end 415.869374 -284.87243)
		(width 0.16002)
		(layer "In13.Cu")
		(net "M_H_CPU0_SB_DQS_DN<0>")
	)
	(segment
		(start 413.498792 -285.65729)
		(end 414.052512 -285.65729)
		(width 0.16002)
		(layer "In13.Cu")
		(net "M_H_CPU0_SB_DQS_DN<0>")
	)
	(segment
		(start 395.34084 -275.140674)
		(end 395.634464 -275.140674)
		(width 0.09525)
		(layer "In13.Cu")
		(net "M_H_CPU0_SB_DQS_DN<0>")
	)
	(segment
		(start 385.20624 -276.190964)
		(end 385.214622 -276.186138)
		(width 0.09525)
		(layer "In13.Cu")
		(net "M_H_CPU0_SB_DQS_DN<0>")
	)
	(segment
		(start 416.976052 -284.535372)
		(end 417.31311 -284.87243)
		(width 0.16002)
		(layer "In13.Cu")
		(net "M_H_CPU0_SB_DQS_DN<0>")
	)
	(segment
		(start 392.148314 -276.182582)
		(end 392.18362 -276.203156)
		(width 0.09525)
		(layer "In13.Cu")
		(net "M_H_CPU0_SB_DQS_DN<0>")
	)
	(segment
		(start 422.425114 -285.597854)
		(end 422.902634 -285.597854)
		(width 0.16002)
		(layer "In13.Cu")
		(net "M_H_CPU0_SB_DQS_DN<0>")
	)
	(segment
		(start 416.816032 -284.170882)
		(end 416.976052 -284.330902)
		(width 0.16002)
		(layer "In13.Cu")
		(net "M_H_CPU0_SB_DQS_DN<0>")
	)
	(arc
		(start 385.214622 -276.186138)
		(mid 385.399654 -276.140224)
		(end 385.58343 -276.190964)
		(width 0.09525)
		(layer "In13.Cu")
		(net "M_H_CPU0_SB_DQS_DN<0>")
	)
	(arc
		(start 391.223246 -276.190964)
		(mid 391.504678 -276.266719)
		(end 391.78611 -276.190964)
		(width 0.09525)
		(layer "In13.Cu")
		(net "M_H_CPU0_SB_DQS_DN<0>")
	)
	(arc
		(start 389.343392 -276.190964)
		(mid 389.624824 -276.266719)
		(end 389.906256 -276.190964)
		(width 0.09525)
		(layer "In13.Cu")
		(net "M_H_CPU0_SB_DQS_DN<0>")
	)
	(arc
		(start 384.643376 -276.190964)
		(mid 384.924808 -276.266719)
		(end 385.20624 -276.190964)
		(width 0.09525)
		(layer "In13.Cu")
		(net "M_H_CPU0_SB_DQS_DN<0>")
	)
	(arc
		(start 388.026148 -276.190964)
		(mid 388.209923 -276.140192)
		(end 388.394956 -276.186138)
		(width 0.09525)
		(layer "In13.Cu")
		(net "M_H_CPU0_SB_DQS_DN<0>")
	)
	(arc
		(start 390.283446 -276.190964)
		(mid 390.564878 -276.266719)
		(end 390.84631 -276.190964)
		(width 0.09525)
		(layer "In13.Cu")
		(net "M_H_CPU0_SB_DQS_DN<0>")
	)
	(arc
		(start 390.84631 -276.190964)
		(mid 391.034778 -276.140287)
		(end 391.223246 -276.190964)
		(width 0.09525)
		(layer "In13.Cu")
		(net "M_H_CPU0_SB_DQS_DN<0>")
	)
	(arc
		(start 387.463284 -276.190964)
		(mid 387.744716 -276.266719)
		(end 388.026148 -276.190964)
		(width 0.09525)
		(layer "In13.Cu")
		(net "M_H_CPU0_SB_DQS_DN<0>")
	)
	(arc
		(start 388.403338 -276.190964)
		(mid 388.68477 -276.266719)
		(end 388.966202 -276.190964)
		(width 0.09525)
		(layer "In13.Cu")
		(net "M_H_CPU0_SB_DQS_DN<0>")
	)
	(arc
		(start 391.78611 -276.190964)
		(mid 391.966136 -276.14026)
		(end 392.148314 -276.182582)
		(width 0.09525)
		(layer "In13.Cu")
		(net "M_H_CPU0_SB_DQS_DN<0>")
	)
	(arc
		(start 386.154676 -276.186138)
		(mid 386.339708 -276.140224)
		(end 386.523484 -276.190964)
		(width 0.09525)
		(layer "In13.Cu")
		(net "M_H_CPU0_SB_DQS_DN<0>")
	)
	(arc
		(start 385.58343 -276.190964)
		(mid 385.864862 -276.266719)
		(end 386.146294 -276.190964)
		(width 0.09525)
		(layer "In13.Cu")
		(net "M_H_CPU0_SB_DQS_DN<0>")
	)
	(arc
		(start 392.18362 -276.203156)
		(mid 392.455683 -276.266594)
		(end 392.72464 -276.190964)
		(width 0.09525)
		(layer "In13.Cu")
		(net "M_H_CPU0_SB_DQS_DN<0>")
	)
	(arc
		(start 393.102338 -276.190964)
		(mid 393.456198 -276.26228)
		(end 393.78001 -276.102826)
		(width 0.09525)
		(layer "In13.Cu")
		(net "M_H_CPU0_SB_DQS_DN<0>")
	)
	(arc
		(start 389.914638 -276.186138)
		(mid 390.09967 -276.140224)
		(end 390.283446 -276.190964)
		(width 0.09525)
		(layer "In13.Cu")
		(net "M_H_CPU0_SB_DQS_DN<0>")
	)
	(arc
		(start 387.086348 -276.190964)
		(mid 387.274816 -276.140287)
		(end 387.463284 -276.190964)
		(width 0.09525)
		(layer "In13.Cu")
		(net "M_H_CPU0_SB_DQS_DN<0>")
	)
	(arc
		(start 384.324352 -276.163786)
		(mid 384.482102 -276.141267)
		(end 384.634994 -276.186138)
		(width 0.09525)
		(layer "In13.Cu")
		(net "M_H_CPU0_SB_DQS_DN<0>")
	)
	(arc
		(start 386.523484 -276.190964)
		(mid 386.804916 -276.266719)
		(end 387.086348 -276.190964)
		(width 0.09525)
		(layer "In13.Cu")
		(net "M_H_CPU0_SB_DQS_DN<0>")
	)
	(arc
		(start 392.739118 -276.182582)
		(mid 392.921804 -276.140025)
		(end 393.102338 -276.190964)
		(width 0.09525)
		(layer "In13.Cu")
		(net "M_H_CPU0_SB_DQS_DN<0>")
	)
	(arc
		(start 388.966202 -276.190964)
		(mid 389.149977 -276.140192)
		(end 389.33501 -276.186138)
		(width 0.09525)
		(layer "In13.Cu")
		(net "M_H_CPU0_SB_DQS_DN<0>")
	)
	(segment
		(start 382.107948 -279.49017)
		(end 382.5748 -279.756108)
		(width 0.10668)
		(layer "F.Cu")
		(net "M_H_CPU0_SB_DQ<9>")
	)
	(segment
		(start 421.483536 -292.390322)
		(end 421.483536 -291.954204)
		(width 0.14478)
		(layer "In13.Cu")
		(net "M_H_CPU0_SB_DQ<9>")
	)
	(segment
		(start 418.557964 -292.960044)
		(end 420.487094 -292.960044)
		(width 0.14478)
		(layer "In13.Cu")
		(net "M_H_CPU0_SB_DQ<9>")
	)
	(segment
		(start 393.270994 -279.927812)
		(end 395.129258 -279.927812)
		(width 0.0889)
		(layer "In13.Cu")
		(net "M_H_CPU0_SB_DQ<9>")
	)
	(segment
		(start 385.207764 -280.078688)
		(end 385.216146 -280.083514)
		(width 0.0889)
		(layer "In13.Cu")
		(net "M_H_CPU0_SB_DQ<9>")
	)
	(segment
		(start 392.727434 -280.078688)
		(end 392.735816 -280.083514)
		(width 0.0889)
		(layer "In13.Cu")
		(net "M_H_CPU0_SB_DQ<9>")
	)
	(segment
		(start 423.281856 -292.535102)
		(end 424.012106 -292.535102)
		(width 0.14478)
		(layer "In13.Cu")
		(net "M_H_CPU0_SB_DQ<9>")
	)
	(segment
		(start 386.147818 -280.078688)
		(end 386.1562 -280.083514)
		(width 0.0889)
		(layer "In13.Cu")
		(net "M_H_CPU0_SB_DQ<9>")
	)
	(segment
		(start 388.393432 -280.083514)
		(end 388.401814 -280.078688)
		(width 0.0889)
		(layer "In13.Cu")
		(net "M_H_CPU0_SB_DQ<9>")
	)
	(segment
		(start 408.291538 -289.521138)
		(end 408.291538 -289.974274)
		(width 0.14478)
		(layer "In13.Cu")
		(net "M_H_CPU0_SB_DQ<9>")
	)
	(segment
		(start 382.5748 -279.756108)
		(end 382.728724 -280.021538)
		(width 0.0889)
		(layer "In13.Cu")
		(net "M_H_CPU0_SB_DQ<9>")
	)
	(segment
		(start 389.90778 -280.078688)
		(end 389.916162 -280.083514)
		(width 0.0889)
		(layer "In13.Cu")
		(net "M_H_CPU0_SB_DQ<9>")
	)
	(segment
		(start 422.441116 -292.535102)
		(end 422.585896 -292.390322)
		(width 0.14478)
		(layer "In13.Cu")
		(net "M_H_CPU0_SB_DQ<9>")
	)
	(segment
		(start 393.07516 -280.076656)
		(end 393.19073 -279.961086)
		(width 0.0889)
		(layer "In13.Cu")
		(net "M_H_CPU0_SB_DQ<9>")
	)
	(segment
		(start 422.034716 -291.954204)
		(end 422.034716 -292.390322)
		(width 0.14478)
		(layer "In13.Cu")
		(net "M_H_CPU0_SB_DQ<9>")
	)
	(segment
		(start 422.034716 -292.390322)
		(end 422.179496 -292.535102)
		(width 0.14478)
		(layer "In13.Cu")
		(net "M_H_CPU0_SB_DQ<9>")
	)
	(segment
		(start 421.889936 -291.809424)
		(end 422.034716 -291.954204)
		(width 0.14478)
		(layer "In13.Cu")
		(net "M_H_CPU0_SB_DQ<9>")
	)
	(segment
		(start 422.992296 -291.809424)
		(end 423.137076 -291.954204)
		(width 0.14478)
		(layer "In13.Cu")
		(net "M_H_CPU0_SB_DQ<9>")
	)
	(segment
		(start 411.277308 -292.960044)
		(end 412.716726 -292.960044)
		(width 0.14478)
		(layer "In13.Cu")
		(net "M_H_CPU0_SB_DQ<9>")
	)
	(segment
		(start 420.487094 -292.960044)
		(end 420.912036 -292.535102)
		(width 0.14478)
		(layer "In13.Cu")
		(net "M_H_CPU0_SB_DQ<9>")
	)
	(segment
		(start 384.63347 -280.083514)
		(end 384.641852 -280.078688)
		(width 0.0889)
		(layer "In13.Cu")
		(net "M_H_CPU0_SB_DQ<9>")
	)
	(segment
		(start 395.31163 -279.74544)
		(end 395.767306 -279.74544)
		(width 0.0889)
		(layer "In13.Cu")
		(net "M_H_CPU0_SB_DQ<9>")
	)
	(segment
		(start 395.767306 -279.74544)
		(end 398.51584 -279.74544)
		(width 0.14478)
		(layer "In13.Cu")
		(net "M_H_CPU0_SB_DQ<9>")
	)
	(segment
		(start 417.70808 -292.11016)
		(end 418.557964 -292.960044)
		(width 0.14478)
		(layer "In13.Cu")
		(net "M_H_CPU0_SB_DQ<9>")
	)
	(segment
		(start 421.483536 -291.954204)
		(end 421.628316 -291.809424)
		(width 0.14478)
		(layer "In13.Cu")
		(net "M_H_CPU0_SB_DQ<9>")
	)
	(segment
		(start 383.693416 -280.083514)
		(end 383.701798 -280.078688)
		(width 0.0889)
		(layer "In13.Cu")
		(net "M_H_CPU0_SB_DQ<9>")
	)
	(segment
		(start 422.585896 -291.954204)
		(end 422.730676 -291.809424)
		(width 0.14478)
		(layer "In13.Cu")
		(net "M_H_CPU0_SB_DQ<9>")
	)
	(segment
		(start 413.11703 -292.55974)
		(end 414.27654 -292.55974)
		(width 0.14478)
		(layer "In13.Cu")
		(net "M_H_CPU0_SB_DQ<9>")
	)
	(segment
		(start 423.137076 -291.954204)
		(end 423.137076 -292.390322)
		(width 0.14478)
		(layer "In13.Cu")
		(net "M_H_CPU0_SB_DQ<9>")
	)
	(segment
		(start 420.912036 -292.535102)
		(end 421.338756 -292.535102)
		(width 0.14478)
		(layer "In13.Cu")
		(net "M_H_CPU0_SB_DQ<9>")
	)
	(segment
		(start 398.51584 -279.74544)
		(end 408.291538 -289.521138)
		(width 0.14478)
		(layer "In13.Cu")
		(net "M_H_CPU0_SB_DQ<9>")
	)
	(segment
		(start 408.291538 -289.974274)
		(end 411.277308 -292.960044)
		(width 0.14478)
		(layer "In13.Cu")
		(net "M_H_CPU0_SB_DQ<9>")
	)
	(segment
		(start 422.179496 -292.535102)
		(end 422.441116 -292.535102)
		(width 0.14478)
		(layer "In13.Cu")
		(net "M_H_CPU0_SB_DQ<9>")
	)
	(segment
		(start 422.730676 -291.809424)
		(end 422.992296 -291.809424)
		(width 0.14478)
		(layer "In13.Cu")
		(net "M_H_CPU0_SB_DQ<9>")
	)
	(segment
		(start 414.72612 -292.11016)
		(end 417.70808 -292.11016)
		(width 0.14478)
		(layer "In13.Cu")
		(net "M_H_CPU0_SB_DQ<9>")
	)
	(segment
		(start 421.628316 -291.809424)
		(end 421.889936 -291.809424)
		(width 0.14478)
		(layer "In13.Cu")
		(net "M_H_CPU0_SB_DQ<9>")
	)
	(segment
		(start 392.161776 -280.078688)
		(end 392.17219 -280.072592)
		(width 0.0889)
		(layer "In13.Cu")
		(net "M_H_CPU0_SB_DQ<9>")
	)
	(segment
		(start 395.129258 -279.927812)
		(end 395.31163 -279.74544)
		(width 0.0889)
		(layer "In13.Cu")
		(net "M_H_CPU0_SB_DQ<9>")
	)
	(segment
		(start 412.716726 -292.960044)
		(end 413.11703 -292.55974)
		(width 0.14478)
		(layer "In13.Cu")
		(net "M_H_CPU0_SB_DQ<9>")
	)
	(segment
		(start 389.333486 -280.083514)
		(end 389.341868 -280.078688)
		(width 0.0889)
		(layer "In13.Cu")
		(net "M_H_CPU0_SB_DQ<9>")
	)
	(segment
		(start 414.27654 -292.55974)
		(end 414.72612 -292.11016)
		(width 0.14478)
		(layer "In13.Cu")
		(net "M_H_CPU0_SB_DQ<9>")
	)
	(segment
		(start 392.153394 -280.083514)
		(end 392.161776 -280.078688)
		(width 0.0889)
		(layer "In13.Cu")
		(net "M_H_CPU0_SB_DQ<9>")
	)
	(segment
		(start 422.585896 -292.390322)
		(end 422.585896 -291.954204)
		(width 0.14478)
		(layer "In13.Cu")
		(net "M_H_CPU0_SB_DQ<9>")
	)
	(segment
		(start 421.338756 -292.535102)
		(end 421.483536 -292.390322)
		(width 0.14478)
		(layer "In13.Cu")
		(net "M_H_CPU0_SB_DQ<9>")
	)
	(segment
		(start 423.137076 -292.390322)
		(end 423.281856 -292.535102)
		(width 0.14478)
		(layer "In13.Cu")
		(net "M_H_CPU0_SB_DQ<9>")
	)
	(segment
		(start 382.728724 -280.021538)
		(end 382.824736 -280.046938)
		(width 0.0889)
		(layer "In13.Cu")
		(net "M_H_CPU0_SB_DQ<9>")
	)
	(arc
		(start 388.027672 -280.078688)
		(mid 388.209923 -280.129038)
		(end 388.393432 -280.083514)
		(width 0.0889)
		(layer "In13.Cu")
		(net "M_H_CPU0_SB_DQ<9>")
	)
	(arc
		(start 383.327656 -280.078688)
		(mid 383.509907 -280.129038)
		(end 383.693416 -280.083514)
		(width 0.0889)
		(layer "In13.Cu")
		(net "M_H_CPU0_SB_DQ<9>")
	)
	(arc
		(start 385.581906 -280.078688)
		(mid 385.864862 -280.002511)
		(end 386.147818 -280.078688)
		(width 0.0889)
		(layer "In13.Cu")
		(net "M_H_CPU0_SB_DQ<9>")
	)
	(arc
		(start 389.341868 -280.078688)
		(mid 389.624824 -280.002511)
		(end 389.90778 -280.078688)
		(width 0.0889)
		(layer "In13.Cu")
		(net "M_H_CPU0_SB_DQ<9>")
	)
	(arc
		(start 384.641852 -280.078688)
		(mid 384.924808 -280.002511)
		(end 385.207764 -280.078688)
		(width 0.0889)
		(layer "In13.Cu")
		(net "M_H_CPU0_SB_DQ<9>")
	)
	(arc
		(start 390.281922 -280.078688)
		(mid 390.564878 -280.002511)
		(end 390.847834 -280.078688)
		(width 0.0889)
		(layer "In13.Cu")
		(net "M_H_CPU0_SB_DQ<9>")
	)
	(arc
		(start 386.52196 -280.078688)
		(mid 386.804916 -280.002511)
		(end 387.087872 -280.078688)
		(width 0.0889)
		(layer "In13.Cu")
		(net "M_H_CPU0_SB_DQ<9>")
	)
	(arc
		(start 382.824736 -280.046938)
		(mid 383.079944 -280.003461)
		(end 383.327656 -280.078688)
		(width 0.0889)
		(layer "In13.Cu")
		(net "M_H_CPU0_SB_DQ<9>")
	)
	(arc
		(start 388.401814 -280.078688)
		(mid 388.68477 -280.002511)
		(end 388.967726 -280.078688)
		(width 0.0889)
		(layer "In13.Cu")
		(net "M_H_CPU0_SB_DQ<9>")
	)
	(arc
		(start 391.787634 -280.078688)
		(mid 391.969885 -280.129038)
		(end 392.153394 -280.083514)
		(width 0.0889)
		(layer "In13.Cu")
		(net "M_H_CPU0_SB_DQ<9>")
	)
	(arc
		(start 388.967726 -280.078688)
		(mid 389.149977 -280.129038)
		(end 389.333486 -280.083514)
		(width 0.0889)
		(layer "In13.Cu")
		(net "M_H_CPU0_SB_DQ<9>")
	)
	(arc
		(start 391.221722 -280.078688)
		(mid 391.504678 -280.002511)
		(end 391.787634 -280.078688)
		(width 0.0889)
		(layer "In13.Cu")
		(net "M_H_CPU0_SB_DQ<9>")
	)
	(arc
		(start 392.17219 -280.072592)
		(mid 392.450622 -280.002494)
		(end 392.727434 -280.078688)
		(width 0.0889)
		(layer "In13.Cu")
		(net "M_H_CPU0_SB_DQ<9>")
	)
	(arc
		(start 387.46176 -280.078688)
		(mid 387.744716 -280.002511)
		(end 388.027672 -280.078688)
		(width 0.0889)
		(layer "In13.Cu")
		(net "M_H_CPU0_SB_DQ<9>")
	)
	(arc
		(start 392.735816 -280.083514)
		(mid 392.863304 -280.125615)
		(end 392.997436 -280.119836)
		(width 0.0889)
		(layer "In13.Cu")
		(net "M_H_CPU0_SB_DQ<9>")
	)
	(arc
		(start 392.997436 -280.119836)
		(mid 393.039346 -280.103733)
		(end 393.07516 -280.076656)
		(width 0.0889)
		(layer "In13.Cu")
		(net "M_H_CPU0_SB_DQ<9>")
	)
	(arc
		(start 390.847834 -280.078688)
		(mid 391.034778 -280.128943)
		(end 391.221722 -280.078688)
		(width 0.0889)
		(layer "In13.Cu")
		(net "M_H_CPU0_SB_DQ<9>")
	)
	(arc
		(start 389.916162 -280.083514)
		(mid 390.09967 -280.129008)
		(end 390.281922 -280.078688)
		(width 0.0889)
		(layer "In13.Cu")
		(net "M_H_CPU0_SB_DQ<9>")
	)
	(arc
		(start 387.087872 -280.078688)
		(mid 387.274816 -280.128943)
		(end 387.46176 -280.078688)
		(width 0.0889)
		(layer "In13.Cu")
		(net "M_H_CPU0_SB_DQ<9>")
	)
	(arc
		(start 384.26771 -280.078688)
		(mid 384.449961 -280.129038)
		(end 384.63347 -280.083514)
		(width 0.0889)
		(layer "In13.Cu")
		(net "M_H_CPU0_SB_DQ<9>")
	)
	(arc
		(start 386.1562 -280.083514)
		(mid 386.339708 -280.129008)
		(end 386.52196 -280.078688)
		(width 0.0889)
		(layer "In13.Cu")
		(net "M_H_CPU0_SB_DQ<9>")
	)
	(arc
		(start 385.216146 -280.083514)
		(mid 385.399654 -280.129008)
		(end 385.581906 -280.078688)
		(width 0.0889)
		(layer "In13.Cu")
		(net "M_H_CPU0_SB_DQ<9>")
	)
	(arc
		(start 393.19073 -279.961086)
		(mid 393.227541 -279.936426)
		(end 393.270994 -279.927812)
		(width 0.0889)
		(layer "In13.Cu")
		(net "M_H_CPU0_SB_DQ<9>")
	)
	(arc
		(start 383.701798 -280.078688)
		(mid 383.984754 -280.002511)
		(end 384.26771 -280.078688)
		(width 0.0889)
		(layer "In13.Cu")
		(net "M_H_CPU0_SB_DQ<9>")
	)
	(segment
		(start 383.517902 -278.680164)
		(end 383.984754 -278.946102)
		(width 0.10668)
		(layer "F.Cu")
		(net "M_H_CPU0_SB_DQ<8>")
	)
	(segment
		(start 422.677082 -290.40074)
		(end 422.677082 -291.12464)
		(width 0.14478)
		(layer "In13.Cu")
		(net "M_H_CPU0_SB_DQ<8>")
	)
	(segment
		(start 394.183362 -278.65197)
		(end 393.559792 -279.27554)
		(width 0.0889)
		(layer "In13.Cu")
		(net "M_H_CPU0_SB_DQ<8>")
	)
	(segment
		(start 421.023542 -291.12464)
		(end 421.023542 -290.97986)
		(width 0.14478)
		(layer "In13.Cu")
		(net "M_H_CPU0_SB_DQ<8>")
	)
	(segment
		(start 421.719502 -290.083494)
		(end 421.574722 -290.228274)
		(width 0.14478)
		(layer "In13.Cu")
		(net "M_H_CPU0_SB_DQ<8>")
	)
	(segment
		(start 421.168322 -291.26942)
		(end 421.023542 -291.12464)
		(width 0.14478)
		(layer "In13.Cu")
		(net "M_H_CPU0_SB_DQ<8>")
	)
	(segment
		(start 414.772094 -290.670996)
		(end 414.183068 -291.260022)
		(width 0.14478)
		(layer "In13.Cu")
		(net "M_H_CPU0_SB_DQ<8>")
	)
	(segment
		(start 421.023542 -290.97986)
		(end 420.878762 -290.83508)
		(width 0.14478)
		(layer "In13.Cu")
		(net "M_H_CPU0_SB_DQ<8>")
	)
	(segment
		(start 387.566154 -279.273508)
		(end 387.557772 -279.268682)
		(width 0.0889)
		(layer "In13.Cu")
		(net "M_H_CPU0_SB_DQ<8>")
	)
	(segment
		(start 386.99186 -279.268682)
		(end 386.984494 -279.273)
		(width 0.0889)
		(layer "In13.Cu")
		(net "M_H_CPU0_SB_DQ<8>")
	)
	(segment
		(start 386.051806 -279.268682)
		(end 386.043424 -279.273508)
		(width 0.0889)
		(layer "In13.Cu")
		(net "M_H_CPU0_SB_DQ<8>")
	)
	(segment
		(start 392.641836 -279.262586)
		(end 392.631422 -279.268682)
		(width 0.0889)
		(layer "In13.Cu")
		(net "M_H_CPU0_SB_DQ<8>")
	)
	(segment
		(start 414.183068 -291.260022)
		(end 411.798262 -291.260022)
		(width 0.14478)
		(layer "In13.Cu")
		(net "M_H_CPU0_SB_DQ<8>")
	)
	(segment
		(start 422.532302 -291.26942)
		(end 422.270682 -291.26942)
		(width 0.14478)
		(layer "In13.Cu")
		(net "M_H_CPU0_SB_DQ<8>")
	)
	(segment
		(start 388.506208 -279.273508)
		(end 388.497826 -279.268682)
		(width 0.0889)
		(layer "In13.Cu")
		(net "M_H_CPU0_SB_DQ<8>")
	)
	(segment
		(start 422.125902 -290.228274)
		(end 421.981122 -290.083494)
		(width 0.14478)
		(layer "In13.Cu")
		(net "M_H_CPU0_SB_DQ<8>")
	)
	(segment
		(start 420.878762 -290.83508)
		(end 420.661592 -290.83508)
		(width 0.14478)
		(layer "In13.Cu")
		(net "M_H_CPU0_SB_DQ<8>")
	)
	(segment
		(start 386.984494 -279.273)
		(end 386.983478 -279.273508)
		(width 0.0889)
		(layer "In13.Cu")
		(net "M_H_CPU0_SB_DQ<8>")
	)
	(segment
		(start 421.574722 -290.228274)
		(end 421.574722 -291.12464)
		(width 0.14478)
		(layer "In13.Cu")
		(net "M_H_CPU0_SB_DQ<8>")
	)
	(segment
		(start 423.646346 -290.83508)
		(end 423.067226 -290.25596)
		(width 0.14478)
		(layer "In13.Cu")
		(net "M_H_CPU0_SB_DQ<8>")
	)
	(segment
		(start 420.23665 -291.260022)
		(end 418.460428 -291.260022)
		(width 0.14478)
		(layer "In13.Cu")
		(net "M_H_CPU0_SB_DQ<8>")
	)
	(segment
		(start 395.925294 -278.611076)
		(end 395.193012 -278.611076)
		(width 0.0889)
		(layer "In13.Cu")
		(net "M_H_CPU0_SB_DQ<8>")
	)
	(segment
		(start 422.125902 -291.12464)
		(end 422.125902 -290.228274)
		(width 0.14478)
		(layer "In13.Cu")
		(net "M_H_CPU0_SB_DQ<8>")
	)
	(segment
		(start 423.067226 -290.25596)
		(end 422.821862 -290.25596)
		(width 0.14478)
		(layer "In13.Cu")
		(net "M_H_CPU0_SB_DQ<8>")
	)
	(segment
		(start 390.751822 -279.268682)
		(end 390.74344 -279.273508)
		(width 0.0889)
		(layer "In13.Cu")
		(net "M_H_CPU0_SB_DQ<8>")
	)
	(segment
		(start 420.661592 -290.83508)
		(end 420.23665 -291.260022)
		(width 0.14478)
		(layer "In13.Cu")
		(net "M_H_CPU0_SB_DQ<8>")
	)
	(segment
		(start 384.235198 -279.236932)
		(end 384.138932 -279.211532)
		(width 0.0889)
		(layer "In13.Cu")
		(net "M_H_CPU0_SB_DQ<8>")
	)
	(segment
		(start 395.193012 -278.611076)
		(end 395.152118 -278.65197)
		(width 0.0889)
		(layer "In13.Cu")
		(net "M_H_CPU0_SB_DQ<8>")
	)
	(segment
		(start 422.677082 -291.12464)
		(end 422.532302 -291.26942)
		(width 0.14478)
		(layer "In13.Cu")
		(net "M_H_CPU0_SB_DQ<8>")
	)
	(segment
		(start 395.152118 -278.65197)
		(end 394.183362 -278.65197)
		(width 0.0889)
		(layer "In13.Cu")
		(net "M_H_CPU0_SB_DQ<8>")
	)
	(segment
		(start 391.326116 -279.273508)
		(end 391.317734 -279.268682)
		(width 0.0889)
		(layer "In13.Cu")
		(net "M_H_CPU0_SB_DQ<8>")
	)
	(segment
		(start 421.429942 -291.26942)
		(end 421.168322 -291.26942)
		(width 0.14478)
		(layer "In13.Cu")
		(net "M_H_CPU0_SB_DQ<8>")
	)
	(segment
		(start 411.798262 -291.260022)
		(end 399.149316 -278.611076)
		(width 0.14478)
		(layer "In13.Cu")
		(net "M_H_CPU0_SB_DQ<8>")
	)
	(segment
		(start 421.574722 -291.12464)
		(end 421.429942 -291.26942)
		(width 0.14478)
		(layer "In13.Cu")
		(net "M_H_CPU0_SB_DQ<8>")
	)
	(segment
		(start 399.149316 -278.611076)
		(end 395.925294 -278.611076)
		(width 0.14478)
		(layer "In13.Cu")
		(net "M_H_CPU0_SB_DQ<8>")
	)
	(segment
		(start 424.012106 -290.83508)
		(end 423.646346 -290.83508)
		(width 0.14478)
		(layer "In13.Cu")
		(net "M_H_CPU0_SB_DQ<8>")
	)
	(segment
		(start 418.460428 -291.260022)
		(end 417.871402 -290.670996)
		(width 0.14478)
		(layer "In13.Cu")
		(net "M_H_CPU0_SB_DQ<8>")
	)
	(segment
		(start 422.821862 -290.25596)
		(end 422.677082 -290.40074)
		(width 0.14478)
		(layer "In13.Cu")
		(net "M_H_CPU0_SB_DQ<8>")
	)
	(segment
		(start 384.138932 -279.211532)
		(end 383.984754 -278.946102)
		(width 0.0889)
		(layer "In13.Cu")
		(net "M_H_CPU0_SB_DQ<8>")
	)
	(segment
		(start 392.257534 -279.268682)
		(end 392.24712 -279.262586)
		(width 0.0889)
		(layer "In13.Cu")
		(net "M_H_CPU0_SB_DQ<8>")
	)
	(segment
		(start 422.270682 -291.26942)
		(end 422.125902 -291.12464)
		(width 0.14478)
		(layer "In13.Cu")
		(net "M_H_CPU0_SB_DQ<8>")
	)
	(segment
		(start 421.981122 -290.083494)
		(end 421.719502 -290.083494)
		(width 0.14478)
		(layer "In13.Cu")
		(net "M_H_CPU0_SB_DQ<8>")
	)
	(segment
		(start 417.871402 -290.670996)
		(end 414.772094 -290.670996)
		(width 0.14478)
		(layer "In13.Cu")
		(net "M_H_CPU0_SB_DQ<8>")
	)
	(arc
		(start 385.111752 -279.268682)
		(mid 384.924808 -279.318937)
		(end 384.737864 -279.268682)
		(width 0.0889)
		(layer "In13.Cu")
		(net "M_H_CPU0_SB_DQ<8>")
	)
	(arc
		(start 385.677664 -279.268682)
		(mid 385.394708 -279.192505)
		(end 385.111752 -279.268682)
		(width 0.0889)
		(layer "In13.Cu")
		(net "M_H_CPU0_SB_DQ<8>")
	)
	(arc
		(start 390.74344 -279.273508)
		(mid 390.559932 -279.319002)
		(end 390.37768 -279.268682)
		(width 0.0889)
		(layer "In13.Cu")
		(net "M_H_CPU0_SB_DQ<8>")
	)
	(arc
		(start 393.559792 -279.27554)
		(mid 393.377791 -279.319073)
		(end 393.197588 -279.268682)
		(width 0.0889)
		(layer "In13.Cu")
		(net "M_H_CPU0_SB_DQ<8>")
	)
	(arc
		(start 390.37768 -279.268682)
		(mid 390.094724 -279.192505)
		(end 389.811768 -279.268682)
		(width 0.0889)
		(layer "In13.Cu")
		(net "M_H_CPU0_SB_DQ<8>")
	)
	(arc
		(start 389.811768 -279.268682)
		(mid 389.624824 -279.318937)
		(end 389.43788 -279.268682)
		(width 0.0889)
		(layer "In13.Cu")
		(net "M_H_CPU0_SB_DQ<8>")
	)
	(arc
		(start 386.983478 -279.273508)
		(mid 386.79997 -279.319002)
		(end 386.617718 -279.268682)
		(width 0.0889)
		(layer "In13.Cu")
		(net "M_H_CPU0_SB_DQ<8>")
	)
	(arc
		(start 386.043424 -279.273508)
		(mid 385.859916 -279.319002)
		(end 385.677664 -279.268682)
		(width 0.0889)
		(layer "In13.Cu")
		(net "M_H_CPU0_SB_DQ<8>")
	)
	(arc
		(start 384.737864 -279.268682)
		(mid 384.490268 -279.193504)
		(end 384.235198 -279.236932)
		(width 0.0889)
		(layer "In13.Cu")
		(net "M_H_CPU0_SB_DQ<8>")
	)
	(arc
		(start 388.871968 -279.268682)
		(mid 388.689717 -279.319032)
		(end 388.506208 -279.273508)
		(width 0.0889)
		(layer "In13.Cu")
		(net "M_H_CPU0_SB_DQ<8>")
	)
	(arc
		(start 393.197588 -279.268682)
		(mid 392.920521 -279.192411)
		(end 392.641836 -279.262586)
		(width 0.0889)
		(layer "In13.Cu")
		(net "M_H_CPU0_SB_DQ<8>")
	)
	(arc
		(start 392.24712 -279.262586)
		(mid 391.968688 -279.192488)
		(end 391.691876 -279.268682)
		(width 0.0889)
		(layer "In13.Cu")
		(net "M_H_CPU0_SB_DQ<8>")
	)
	(arc
		(start 387.557772 -279.268682)
		(mid 387.274816 -279.192505)
		(end 386.99186 -279.268682)
		(width 0.0889)
		(layer "In13.Cu")
		(net "M_H_CPU0_SB_DQ<8>")
	)
	(arc
		(start 388.497826 -279.268682)
		(mid 388.21487 -279.192505)
		(end 387.931914 -279.268682)
		(width 0.0889)
		(layer "In13.Cu")
		(net "M_H_CPU0_SB_DQ<8>")
	)
	(arc
		(start 387.931914 -279.268682)
		(mid 387.749663 -279.319032)
		(end 387.566154 -279.273508)
		(width 0.0889)
		(layer "In13.Cu")
		(net "M_H_CPU0_SB_DQ<8>")
	)
	(arc
		(start 391.691876 -279.268682)
		(mid 391.509625 -279.319032)
		(end 391.326116 -279.273508)
		(width 0.0889)
		(layer "In13.Cu")
		(net "M_H_CPU0_SB_DQ<8>")
	)
	(arc
		(start 389.43788 -279.268682)
		(mid 389.154924 -279.192505)
		(end 388.871968 -279.268682)
		(width 0.0889)
		(layer "In13.Cu")
		(net "M_H_CPU0_SB_DQ<8>")
	)
	(arc
		(start 391.317734 -279.268682)
		(mid 391.034778 -279.192505)
		(end 390.751822 -279.268682)
		(width 0.0889)
		(layer "In13.Cu")
		(net "M_H_CPU0_SB_DQ<8>")
	)
	(arc
		(start 392.631422 -279.268682)
		(mid 392.444478 -279.318937)
		(end 392.257534 -279.268682)
		(width 0.0889)
		(layer "In13.Cu")
		(net "M_H_CPU0_SB_DQ<8>")
	)
	(arc
		(start 386.617718 -279.268682)
		(mid 386.334762 -279.192505)
		(end 386.051806 -279.268682)
		(width 0.0889)
		(layer "In13.Cu")
		(net "M_H_CPU0_SB_DQ<8>")
	)
	(segment
		(start 382.577848 -278.680164)
		(end 383.0447 -278.946102)
		(width 0.10668)
		(layer "F.Cu")
		(net "M_H_CPU0_SB_DQ<7>")
	)
	(segment
		(start 413.982154 -290.68141)
		(end 413.090614 -290.68141)
		(width 0.14478)
		(layer "In13.Cu")
		(net "M_H_CPU0_SB_DQ<7>")
	)
	(segment
		(start 416.920172 -289.244532)
		(end 416.64128 -289.523424)
		(width 0.14478)
		(layer "In13.Cu")
		(net "M_H_CPU0_SB_DQ<7>")
	)
	(segment
		(start 411.728158 -290.410392)
		(end 399.372582 -278.054816)
		(width 0.14478)
		(layer "In13.Cu")
		(net "M_H_CPU0_SB_DQ<7>")
	)
	(segment
		(start 416.368992 -289.523424)
		(end 416.0901 -289.244532)
		(width 0.14478)
		(layer "In13.Cu")
		(net "M_H_CPU0_SB_DQ<7>")
	)
	(segment
		(start 395.168628 -278.235918)
		(end 393.89685 -278.235918)
		(width 0.0889)
		(layer "In13.Cu")
		(net "M_H_CPU0_SB_DQ<7>")
	)
	(segment
		(start 412.404052 -290.274756)
		(end 412.404052 -290.27501)
		(width 0.14478)
		(layer "In13.Cu")
		(net "M_H_CPU0_SB_DQ<7>")
	)
	(segment
		(start 386.99186 -278.623522)
		(end 386.983478 -278.618696)
		(width 0.0889)
		(layer "In13.Cu")
		(net "M_H_CPU0_SB_DQ<7>")
	)
	(segment
		(start 419.421056 -290.564062)
		(end 419.276276 -290.708842)
		(width 0.14478)
		(layer "In13.Cu")
		(net "M_H_CPU0_SB_DQ<7>")
	)
	(segment
		(start 383.806192 -278.618696)
		(end 383.79781 -278.623522)
		(width 0.0889)
		(layer "In13.Cu")
		(net "M_H_CPU0_SB_DQ<7>")
	)
	(segment
		(start 414.110424 -290.348416)
		(end 414.110424 -290.55314)
		(width 0.14478)
		(layer "In13.Cu")
		(net "M_H_CPU0_SB_DQ<7>")
	)
	(segment
		(start 414.500314 -289.958526)
		(end 414.27908 -289.737292)
		(width 0.14478)
		(layer "In13.Cu")
		(net "M_H_CPU0_SB_DQ<7>")
	)
	(segment
		(start 418.123624 -289.81273)
		(end 418.042344 -290.008818)
		(width 0.14478)
		(layer "In13.Cu")
		(net "M_H_CPU0_SB_DQ<7>")
	)
	(segment
		(start 412.539434 -290.139374)
		(end 412.404052 -290.274756)
		(width 0.14478)
		(layer "In13.Cu")
		(net "M_H_CPU0_SB_DQ<7>")
	)
	(segment
		(start 412.81985 -290.139374)
		(end 412.539434 -290.139374)
		(width 0.14478)
		(layer "In13.Cu")
		(net "M_H_CPU0_SB_DQ<7>")
	)
	(segment
		(start 412.955232 -290.274756)
		(end 412.81985 -290.139374)
		(width 0.14478)
		(layer "In13.Cu")
		(net "M_H_CPU0_SB_DQ<7>")
	)
	(segment
		(start 412.955232 -290.546028)
		(end 412.955232 -290.274756)
		(width 0.14478)
		(layer "In13.Cu")
		(net "M_H_CPU0_SB_DQ<7>")
	)
	(segment
		(start 416.0901 -289.244532)
		(end 415.419032 -289.244532)
		(width 0.14478)
		(layer "In13.Cu")
		(net "M_H_CPU0_SB_DQ<7>")
	)
	(segment
		(start 417.611306 -289.98672)
		(end 417.533074 -289.797744)
		(width 0.14478)
		(layer "In13.Cu")
		(net "M_H_CPU0_SB_DQ<7>")
	)
	(segment
		(start 418.547042 -289.83178)
		(end 418.3126 -289.734498)
		(width 0.14478)
		(layer "In13.Cu")
		(net "M_H_CPU0_SB_DQ<7>")
	)
	(segment
		(start 387.558026 -278.623522)
		(end 387.557772 -278.623522)
		(width 0.0889)
		(layer "In13.Cu")
		(net "M_H_CPU0_SB_DQ<7>")
	)
	(segment
		(start 391.70229 -278.629618)
		(end 391.691876 -278.623522)
		(width 0.0889)
		(layer "In13.Cu")
		(net "M_H_CPU0_SB_DQ<7>")
	)
	(segment
		(start 417.129468 -289.244532)
		(end 416.920172 -289.244532)
		(width 0.14478)
		(layer "In13.Cu")
		(net "M_H_CPU0_SB_DQ<7>")
	)
	(segment
		(start 419.565836 -290.009834)
		(end 419.421056 -290.154614)
		(width 0.14478)
		(layer "In13.Cu")
		(net "M_H_CPU0_SB_DQ<7>")
	)
	(segment
		(start 413.88919 -289.922458)
		(end 413.88919 -290.127182)
		(width 0.14478)
		(layer "In13.Cu")
		(net "M_H_CPU0_SB_DQ<7>")
	)
	(segment
		(start 399.372582 -278.054816)
		(end 395.959584 -278.054816)
		(width 0.14478)
		(layer "In13.Cu")
		(net "M_H_CPU0_SB_DQ<7>")
	)
	(segment
		(start 418.869876 -290.154614)
		(end 418.547042 -289.83178)
		(width 0.14478)
		(layer "In13.Cu")
		(net "M_H_CPU0_SB_DQ<7>")
	)
	(segment
		(start 414.705038 -289.958526)
		(end 414.500314 -289.958526)
		(width 0.14478)
		(layer "In13.Cu")
		(net "M_H_CPU0_SB_DQ<7>")
	)
	(segment
		(start 382.913128 -278.59736)
		(end 382.890776 -278.680672)
		(width 0.0889)
		(layer "In13.Cu")
		(net "M_H_CPU0_SB_DQ<7>")
	)
	(segment
		(start 412.26867 -290.410392)
		(end 411.728158 -290.410392)
		(width 0.14478)
		(layer "In13.Cu")
		(net "M_H_CPU0_SB_DQ<7>")
	)
	(segment
		(start 414.110424 -290.55314)
		(end 413.982154 -290.68141)
		(width 0.14478)
		(layer "In13.Cu")
		(net "M_H_CPU0_SB_DQ<7>")
	)
	(segment
		(start 395.959584 -278.054816)
		(end 395.34973 -278.054816)
		(width 0.0889)
		(layer "In13.Cu")
		(net "M_H_CPU0_SB_DQ<7>")
	)
	(segment
		(start 419.421056 -290.154614)
		(end 419.421056 -290.564062)
		(width 0.14478)
		(layer "In13.Cu")
		(net "M_H_CPU0_SB_DQ<7>")
	)
	(segment
		(start 417.614354 -289.601656)
		(end 417.536122 -289.412934)
		(width 0.14478)
		(layer "In13.Cu")
		(net "M_H_CPU0_SB_DQ<7>")
	)
	(segment
		(start 419.276276 -290.708842)
		(end 419.014656 -290.708842)
		(width 0.14478)
		(layer "In13.Cu")
		(net "M_H_CPU0_SB_DQ<7>")
	)
	(segment
		(start 388.506208 -278.618696)
		(end 388.497826 -278.623522)
		(width 0.0889)
		(layer "In13.Cu")
		(net "M_H_CPU0_SB_DQ<7>")
	)
	(segment
		(start 419.8874 -290.009834)
		(end 419.565836 -290.009834)
		(width 0.14478)
		(layer "In13.Cu")
		(net "M_H_CPU0_SB_DQ<7>")
	)
	(segment
		(start 413.88919 -290.127182)
		(end 414.110424 -290.348416)
		(width 0.14478)
		(layer "In13.Cu")
		(net "M_H_CPU0_SB_DQ<7>")
	)
	(segment
		(start 390.751822 -278.623522)
		(end 390.74344 -278.618696)
		(width 0.0889)
		(layer "In13.Cu")
		(net "M_H_CPU0_SB_DQ<7>")
	)
	(segment
		(start 382.890776 -278.680672)
		(end 383.0447 -278.946102)
		(width 0.0889)
		(layer "In13.Cu")
		(net "M_H_CPU0_SB_DQ<7>")
	)
	(segment
		(start 415.419032 -289.244532)
		(end 414.705038 -289.958526)
		(width 0.14478)
		(layer "In13.Cu")
		(net "M_H_CPU0_SB_DQ<7>")
	)
	(segment
		(start 392.632692 -278.623522)
		(end 392.62431 -278.618696)
		(width 0.0889)
		(layer "In13.Cu")
		(net "M_H_CPU0_SB_DQ<7>")
	)
	(segment
		(start 413.090614 -290.68141)
		(end 412.955232 -290.546028)
		(width 0.14478)
		(layer "In13.Cu")
		(net "M_H_CPU0_SB_DQ<7>")
	)
	(segment
		(start 417.536122 -289.412934)
		(end 417.129468 -289.244532)
		(width 0.14478)
		(layer "In13.Cu")
		(net "M_H_CPU0_SB_DQ<7>")
	)
	(segment
		(start 391.326116 -278.618696)
		(end 391.317734 -278.623522)
		(width 0.0889)
		(layer "In13.Cu")
		(net "M_H_CPU0_SB_DQ<7>")
	)
	(segment
		(start 414.074356 -289.737292)
		(end 413.88919 -289.922458)
		(width 0.14478)
		(layer "In13.Cu")
		(net "M_H_CPU0_SB_DQ<7>")
	)
	(segment
		(start 386.051806 -278.623522)
		(end 386.043424 -278.618696)
		(width 0.0889)
		(layer "In13.Cu")
		(net "M_H_CPU0_SB_DQ<7>")
	)
	(segment
		(start 418.869876 -290.564062)
		(end 418.869876 -290.154614)
		(width 0.14478)
		(layer "In13.Cu")
		(net "M_H_CPU0_SB_DQ<7>")
	)
	(segment
		(start 417.853368 -290.08705)
		(end 417.611306 -289.98672)
		(width 0.14478)
		(layer "In13.Cu")
		(net "M_H_CPU0_SB_DQ<7>")
	)
	(segment
		(start 414.27908 -289.737292)
		(end 414.074356 -289.737292)
		(width 0.14478)
		(layer "In13.Cu")
		(net "M_H_CPU0_SB_DQ<7>")
	)
	(segment
		(start 417.533074 -289.797744)
		(end 417.614354 -289.601656)
		(width 0.14478)
		(layer "In13.Cu")
		(net "M_H_CPU0_SB_DQ<7>")
	)
	(segment
		(start 419.014656 -290.708842)
		(end 418.869876 -290.564062)
		(width 0.14478)
		(layer "In13.Cu")
		(net "M_H_CPU0_SB_DQ<7>")
	)
	(segment
		(start 418.3126 -289.734498)
		(end 418.123624 -289.81273)
		(width 0.14478)
		(layer "In13.Cu")
		(net "M_H_CPU0_SB_DQ<7>")
	)
	(segment
		(start 412.404052 -290.27501)
		(end 412.26867 -290.410392)
		(width 0.14478)
		(layer "In13.Cu")
		(net "M_H_CPU0_SB_DQ<7>")
	)
	(segment
		(start 419.912038 -289.985196)
		(end 419.8874 -290.009834)
		(width 0.14478)
		(layer "In13.Cu")
		(net "M_H_CPU0_SB_DQ<7>")
	)
	(segment
		(start 393.89685 -278.235918)
		(end 393.192508 -278.627078)
		(width 0.0889)
		(layer "In13.Cu")
		(net "M_H_CPU0_SB_DQ<7>")
	)
	(segment
		(start 395.34973 -278.054816)
		(end 395.168628 -278.235918)
		(width 0.0889)
		(layer "In13.Cu")
		(net "M_H_CPU0_SB_DQ<7>")
	)
	(segment
		(start 416.64128 -289.523424)
		(end 416.368992 -289.523424)
		(width 0.14478)
		(layer "In13.Cu")
		(net "M_H_CPU0_SB_DQ<7>")
	)
	(segment
		(start 418.042344 -290.008818)
		(end 417.853368 -290.08705)
		(width 0.14478)
		(layer "In13.Cu")
		(net "M_H_CPU0_SB_DQ<7>")
	)
	(arc
		(start 384.171952 -278.623522)
		(mid 383.989701 -278.573172)
		(end 383.806192 -278.618696)
		(width 0.0889)
		(layer "In13.Cu")
		(net "M_H_CPU0_SB_DQ<7>")
	)
	(arc
		(start 390.74344 -278.618696)
		(mid 390.559932 -278.573202)
		(end 390.37768 -278.623522)
		(width 0.0889)
		(layer "In13.Cu")
		(net "M_H_CPU0_SB_DQ<7>")
	)
	(arc
		(start 387.931914 -278.623522)
		(mid 387.74497 -278.573198)
		(end 387.558026 -278.623522)
		(width 0.0889)
		(layer "In13.Cu")
		(net "M_H_CPU0_SB_DQ<7>")
	)
	(arc
		(start 389.811768 -278.623522)
		(mid 389.624824 -278.573267)
		(end 389.43788 -278.623522)
		(width 0.0889)
		(layer "In13.Cu")
		(net "M_H_CPU0_SB_DQ<7>")
	)
	(arc
		(start 388.871968 -278.623522)
		(mid 388.689717 -278.573172)
		(end 388.506208 -278.618696)
		(width 0.0889)
		(layer "In13.Cu")
		(net "M_H_CPU0_SB_DQ<7>")
	)
	(arc
		(start 385.111752 -278.623522)
		(mid 384.924808 -278.573267)
		(end 384.737864 -278.623522)
		(width 0.0889)
		(layer "In13.Cu")
		(net "M_H_CPU0_SB_DQ<7>")
	)
	(arc
		(start 385.677664 -278.623522)
		(mid 385.394708 -278.699699)
		(end 385.111752 -278.623522)
		(width 0.0889)
		(layer "In13.Cu")
		(net "M_H_CPU0_SB_DQ<7>")
	)
	(arc
		(start 392.258042 -278.623522)
		(mid 391.980975 -278.699793)
		(end 391.70229 -278.629618)
		(width 0.0889)
		(layer "In13.Cu")
		(net "M_H_CPU0_SB_DQ<7>")
	)
	(arc
		(start 389.43788 -278.623522)
		(mid 389.154924 -278.699699)
		(end 388.871968 -278.623522)
		(width 0.0889)
		(layer "In13.Cu")
		(net "M_H_CPU0_SB_DQ<7>")
	)
	(arc
		(start 391.691876 -278.623522)
		(mid 391.509625 -278.573172)
		(end 391.326116 -278.618696)
		(width 0.0889)
		(layer "In13.Cu")
		(net "M_H_CPU0_SB_DQ<7>")
	)
	(arc
		(start 386.617718 -278.623522)
		(mid 386.334762 -278.699699)
		(end 386.051806 -278.623522)
		(width 0.0889)
		(layer "In13.Cu")
		(net "M_H_CPU0_SB_DQ<7>")
	)
	(arc
		(start 388.497826 -278.623522)
		(mid 388.21487 -278.699699)
		(end 387.931914 -278.623522)
		(width 0.0889)
		(layer "In13.Cu")
		(net "M_H_CPU0_SB_DQ<7>")
	)
	(arc
		(start 383.79781 -278.623522)
		(mid 383.514854 -278.699699)
		(end 383.231898 -278.623522)
		(width 0.0889)
		(layer "In13.Cu")
		(net "M_H_CPU0_SB_DQ<7>")
	)
	(arc
		(start 386.043424 -278.618696)
		(mid 385.859916 -278.573202)
		(end 385.677664 -278.623522)
		(width 0.0889)
		(layer "In13.Cu")
		(net "M_H_CPU0_SB_DQ<7>")
	)
	(arc
		(start 383.231898 -278.623522)
		(mid 383.07546 -278.574551)
		(end 382.913128 -278.59736)
		(width 0.0889)
		(layer "In13.Cu")
		(net "M_H_CPU0_SB_DQ<7>")
	)
	(arc
		(start 384.737864 -278.623522)
		(mid 384.454908 -278.699699)
		(end 384.171952 -278.623522)
		(width 0.0889)
		(layer "In13.Cu")
		(net "M_H_CPU0_SB_DQ<7>")
	)
	(arc
		(start 391.317734 -278.623522)
		(mid 391.034778 -278.699699)
		(end 390.751822 -278.623522)
		(width 0.0889)
		(layer "In13.Cu")
		(net "M_H_CPU0_SB_DQ<7>")
	)
	(arc
		(start 390.37768 -278.623522)
		(mid 390.094724 -278.699699)
		(end 389.811768 -278.623522)
		(width 0.0889)
		(layer "In13.Cu")
		(net "M_H_CPU0_SB_DQ<7>")
	)
	(arc
		(start 386.983478 -278.618696)
		(mid 386.79997 -278.573202)
		(end 386.617718 -278.623522)
		(width 0.0889)
		(layer "In13.Cu")
		(net "M_H_CPU0_SB_DQ<7>")
	)
	(arc
		(start 392.62431 -278.618696)
		(mid 392.440548 -278.57308)
		(end 392.258042 -278.623522)
		(width 0.0889)
		(layer "In13.Cu")
		(net "M_H_CPU0_SB_DQ<7>")
	)
	(arc
		(start 393.192508 -278.627078)
		(mid 392.912119 -278.699747)
		(end 392.632692 -278.623522)
		(width 0.0889)
		(layer "In13.Cu")
		(net "M_H_CPU0_SB_DQ<7>")
	)
	(arc
		(start 387.557772 -278.623522)
		(mid 387.274816 -278.699699)
		(end 386.99186 -278.623522)
		(width 0.0889)
		(layer "In13.Cu")
		(net "M_H_CPU0_SB_DQ<7>")
	)
	(segment
		(start 383.988056 -277.870158)
		(end 384.454908 -278.136096)
		(width 0.10668)
		(layer "F.Cu")
		(net "M_H_CPU0_SB_DQ<6>")
	)
	(segment
		(start 415.841942 -287.470596)
		(end 415.697162 -287.615376)
		(width 0.14478)
		(layer "In13.Cu")
		(net "M_H_CPU0_SB_DQ<6>")
	)
	(segment
		(start 415.697162 -287.715452)
		(end 415.552382 -287.860232)
		(width 0.14478)
		(layer "In13.Cu")
		(net "M_H_CPU0_SB_DQ<6>")
	)
	(segment
		(start 413.397446 -288.33826)
		(end 413.135826 -288.33826)
		(width 0.14478)
		(layer "In13.Cu")
		(net "M_H_CPU0_SB_DQ<6>")
	)
	(segment
		(start 416.876484 -287.860232)
		(end 416.393122 -287.860232)
		(width 0.14478)
		(layer "In13.Cu")
		(net "M_H_CPU0_SB_DQ<6>")
	)
	(segment
		(start 392.744198 -277.802594)
		(end 392.725402 -277.813516)
		(width 0.0889)
		(layer "In13.Cu")
		(net "M_H_CPU0_SB_DQ<6>")
	)
	(segment
		(start 414.090104 -288.71037)
		(end 413.687006 -288.71037)
		(width 0.14478)
		(layer "In13.Cu")
		(net "M_H_CPU0_SB_DQ<6>")
	)
	(segment
		(start 413.135826 -288.33826)
		(end 412.991046 -288.48304)
		(width 0.14478)
		(layer "In13.Cu")
		(net "M_H_CPU0_SB_DQ<6>")
	)
	(segment
		(start 411.300422 -288.71037)
		(end 410.786326 -288.196274)
		(width 0.14478)
		(layer "In13.Cu")
		(net "M_H_CPU0_SB_DQ<6>")
	)
	(segment
		(start 410.962348 -287.815528)
		(end 410.962348 -287.610804)
		(width 0.14478)
		(layer "In13.Cu")
		(net "M_H_CPU0_SB_DQ<6>")
	)
	(segment
		(start 419.912038 -288.285174)
		(end 419.444678 -288.285174)
		(width 0.14478)
		(layer "In13.Cu")
		(net "M_H_CPU0_SB_DQ<6>")
	)
	(segment
		(start 410.006546 -287.21177)
		(end 410.182568 -287.035748)
		(width 0.14478)
		(layer "In13.Cu")
		(net "M_H_CPU0_SB_DQ<6>")
	)
	(segment
		(start 384.30073 -277.870666)
		(end 384.454908 -278.136096)
		(width 0.0889)
		(layer "In13.Cu")
		(net "M_H_CPU0_SB_DQ<6>")
	)
	(segment
		(start 418.748718 -288.600388)
		(end 418.603938 -288.745168)
		(width 0.14478)
		(layer "In13.Cu")
		(net "M_H_CPU0_SB_DQ<6>")
	)
	(segment
		(start 412.584646 -288.71037)
		(end 412.439866 -288.56559)
		(width 0.14478)
		(layer "In13.Cu")
		(net "M_H_CPU0_SB_DQ<6>")
	)
	(segment
		(start 417.791138 -287.82518)
		(end 417.646358 -287.96996)
		(width 0.14478)
		(layer "In13.Cu")
		(net "M_H_CPU0_SB_DQ<6>")
	)
	(segment
		(start 384.641852 -277.813516)
		(end 384.63347 -277.80869)
		(width 0.0889)
		(layer "In13.Cu")
		(net "M_H_CPU0_SB_DQ<6>")
	)
	(segment
		(start 410.182568 -287.035748)
		(end 410.182568 -286.831024)
		(width 0.14478)
		(layer "In13.Cu")
		(net "M_H_CPU0_SB_DQ<6>")
	)
	(segment
		(start 386.1562 -277.80869)
		(end 386.147818 -277.813516)
		(width 0.0889)
		(layer "In13.Cu")
		(net "M_H_CPU0_SB_DQ<6>")
	)
	(segment
		(start 395.938502 -277.145496)
		(end 394.150088 -277.145496)
		(width 0.0889)
		(layer "In13.Cu")
		(net "M_H_CPU0_SB_DQ<6>")
	)
	(segment
		(start 416.393122 -287.860232)
		(end 416.248342 -287.715452)
		(width 0.14478)
		(layer "In13.Cu")
		(net "M_H_CPU0_SB_DQ<6>")
	)
	(segment
		(start 415.697162 -287.615376)
		(end 415.697162 -287.715452)
		(width 0.14478)
		(layer "In13.Cu")
		(net "M_H_CPU0_SB_DQ<6>")
	)
	(segment
		(start 418.893498 -287.82518)
		(end 418.748718 -287.96996)
		(width 0.14478)
		(layer "In13.Cu")
		(net "M_H_CPU0_SB_DQ<6>")
	)
	(segment
		(start 413.542226 -288.48304)
		(end 413.397446 -288.33826)
		(width 0.14478)
		(layer "In13.Cu")
		(net "M_H_CPU0_SB_DQ<6>")
	)
	(segment
		(start 385.216146 -277.80869)
		(end 385.207764 -277.813516)
		(width 0.0889)
		(layer "In13.Cu")
		(net "M_H_CPU0_SB_DQ<6>")
	)
	(segment
		(start 412.295086 -288.33826)
		(end 412.033466 -288.33826)
		(width 0.14478)
		(layer "In13.Cu")
		(net "M_H_CPU0_SB_DQ<6>")
	)
	(segment
		(start 411.888686 -288.48304)
		(end 411.888686 -288.56559)
		(width 0.14478)
		(layer "In13.Cu")
		(net "M_H_CPU0_SB_DQ<6>")
	)
	(segment
		(start 412.439866 -288.48304)
		(end 412.295086 -288.33826)
		(width 0.14478)
		(layer "In13.Cu")
		(net "M_H_CPU0_SB_DQ<6>")
	)
	(segment
		(start 389.916162 -277.80869)
		(end 389.90778 -277.813516)
		(width 0.0889)
		(layer "In13.Cu")
		(net "M_H_CPU0_SB_DQ<6>")
	)
	(segment
		(start 410.962348 -287.610804)
		(end 410.777182 -287.425638)
		(width 0.14478)
		(layer "In13.Cu")
		(net "M_H_CPU0_SB_DQ<6>")
	)
	(segment
		(start 417.301426 -288.285174)
		(end 416.876484 -287.860232)
		(width 0.14478)
		(layer "In13.Cu")
		(net "M_H_CPU0_SB_DQ<6>")
	)
	(segment
		(start 392.161014 -277.81377)
		(end 392.140948 -277.80234)
		(width 0.0889)
		(layer "In13.Cu")
		(net "M_H_CPU0_SB_DQ<6>")
	)
	(segment
		(start 416.103562 -287.470596)
		(end 415.841942 -287.470596)
		(width 0.14478)
		(layer "In13.Cu")
		(net "M_H_CPU0_SB_DQ<6>")
	)
	(segment
		(start 412.439866 -288.56559)
		(end 412.439866 -288.48304)
		(width 0.14478)
		(layer "In13.Cu")
		(net "M_H_CPU0_SB_DQ<6>")
	)
	(segment
		(start 392.182604 -277.826216)
		(end 392.161014 -277.81377)
		(width 0.0889)
		(layer "In13.Cu")
		(net "M_H_CPU0_SB_DQ<6>")
	)
	(segment
		(start 394.150088 -277.145496)
		(end 393.977114 -277.31847)
		(width 0.0889)
		(layer "In13.Cu")
		(net "M_H_CPU0_SB_DQ<6>")
	)
	(segment
		(start 418.197538 -288.600388)
		(end 418.197538 -287.96996)
		(width 0.14478)
		(layer "In13.Cu")
		(net "M_H_CPU0_SB_DQ<6>")
	)
	(segment
		(start 418.748718 -287.96996)
		(end 418.748718 -288.600388)
		(width 0.14478)
		(layer "In13.Cu")
		(net "M_H_CPU0_SB_DQ<6>")
	)
	(segment
		(start 410.777182 -287.425638)
		(end 410.572458 -287.425638)
		(width 0.14478)
		(layer "In13.Cu")
		(net "M_H_CPU0_SB_DQ<6>")
	)
	(segment
		(start 411.888686 -288.56559)
		(end 411.743906 -288.71037)
		(width 0.14478)
		(layer "In13.Cu")
		(net "M_H_CPU0_SB_DQ<6>")
	)
	(segment
		(start 412.033466 -288.33826)
		(end 411.888686 -288.48304)
		(width 0.14478)
		(layer "In13.Cu")
		(net "M_H_CPU0_SB_DQ<6>")
	)
	(segment
		(start 410.006546 -287.416494)
		(end 410.006546 -287.21177)
		(width 0.14478)
		(layer "In13.Cu")
		(net "M_H_CPU0_SB_DQ<6>")
	)
	(segment
		(start 417.646358 -287.96996)
		(end 417.646358 -288.140394)
		(width 0.14478)
		(layer "In13.Cu")
		(net "M_H_CPU0_SB_DQ<6>")
	)
	(segment
		(start 411.743906 -288.71037)
		(end 411.300422 -288.71037)
		(width 0.14478)
		(layer "In13.Cu")
		(net "M_H_CPU0_SB_DQ<6>")
	)
	(segment
		(start 389.341868 -277.813516)
		(end 389.333486 -277.80869)
		(width 0.0889)
		(layer "In13.Cu")
		(net "M_H_CPU0_SB_DQ<6>")
	)
	(segment
		(start 410.572458 -287.425638)
		(end 410.396436 -287.60166)
		(width 0.14478)
		(layer "In13.Cu")
		(net "M_H_CPU0_SB_DQ<6>")
	)
	(segment
		(start 417.501578 -288.285174)
		(end 417.301426 -288.285174)
		(width 0.14478)
		(layer "In13.Cu")
		(net "M_H_CPU0_SB_DQ<6>")
	)
	(segment
		(start 412.991046 -288.56559)
		(end 412.846266 -288.71037)
		(width 0.14478)
		(layer "In13.Cu")
		(net "M_H_CPU0_SB_DQ<6>")
	)
	(segment
		(start 410.786326 -287.99155)
		(end 410.962348 -287.815528)
		(width 0.14478)
		(layer "In13.Cu")
		(net "M_H_CPU0_SB_DQ<6>")
	)
	(segment
		(start 399.735548 -277.145496)
		(end 395.938502 -277.145496)
		(width 0.14478)
		(layer "In13.Cu")
		(net "M_H_CPU0_SB_DQ<6>")
	)
	(segment
		(start 419.299898 -288.140394)
		(end 419.299898 -287.96996)
		(width 0.14478)
		(layer "In13.Cu")
		(net "M_H_CPU0_SB_DQ<6>")
	)
	(segment
		(start 384.323082 -277.787354)
		(end 384.30073 -277.870666)
		(width 0.0889)
		(layer "In13.Cu")
		(net "M_H_CPU0_SB_DQ<6>")
	)
	(segment
		(start 409.616656 -286.82188)
		(end 409.411932 -286.82188)
		(width 0.14478)
		(layer "In13.Cu")
		(net "M_H_CPU0_SB_DQ<6>")
	)
	(segment
		(start 419.299898 -287.96996)
		(end 419.155118 -287.82518)
		(width 0.14478)
		(layer "In13.Cu")
		(net "M_H_CPU0_SB_DQ<6>")
	)
	(segment
		(start 419.444678 -288.285174)
		(end 419.299898 -288.140394)
		(width 0.14478)
		(layer "In13.Cu")
		(net "M_H_CPU0_SB_DQ<6>")
	)
	(segment
		(start 409.792678 -286.645858)
		(end 409.616656 -286.82188)
		(width 0.14478)
		(layer "In13.Cu")
		(net "M_H_CPU0_SB_DQ<6>")
	)
	(segment
		(start 410.396436 -287.60166)
		(end 410.191712 -287.60166)
		(width 0.14478)
		(layer "In13.Cu")
		(net "M_H_CPU0_SB_DQ<6>")
	)
	(segment
		(start 412.991046 -288.48304)
		(end 412.991046 -288.56559)
		(width 0.14478)
		(layer "In13.Cu")
		(net "M_H_CPU0_SB_DQ<6>")
	)
	(segment
		(start 413.542226 -288.56559)
		(end 413.542226 -288.48304)
		(width 0.14478)
		(layer "In13.Cu")
		(net "M_H_CPU0_SB_DQ<6>")
	)
	(segment
		(start 409.997402 -286.645858)
		(end 409.792678 -286.645858)
		(width 0.14478)
		(layer "In13.Cu")
		(net "M_H_CPU0_SB_DQ<6>")
	)
	(segment
		(start 416.248342 -287.615376)
		(end 416.103562 -287.470596)
		(width 0.14478)
		(layer "In13.Cu")
		(net "M_H_CPU0_SB_DQ<6>")
	)
	(segment
		(start 415.552382 -287.860232)
		(end 414.940242 -287.860232)
		(width 0.14478)
		(layer "In13.Cu")
		(net "M_H_CPU0_SB_DQ<6>")
	)
	(segment
		(start 419.155118 -287.82518)
		(end 418.893498 -287.82518)
		(width 0.14478)
		(layer "In13.Cu")
		(net "M_H_CPU0_SB_DQ<6>")
	)
	(segment
		(start 413.687006 -288.71037)
		(end 413.542226 -288.56559)
		(width 0.14478)
		(layer "In13.Cu")
		(net "M_H_CPU0_SB_DQ<6>")
	)
	(segment
		(start 418.197538 -287.96996)
		(end 418.052758 -287.82518)
		(width 0.14478)
		(layer "In13.Cu")
		(net "M_H_CPU0_SB_DQ<6>")
	)
	(segment
		(start 410.786326 -288.196274)
		(end 410.786326 -287.99155)
		(width 0.14478)
		(layer "In13.Cu")
		(net "M_H_CPU0_SB_DQ<6>")
	)
	(segment
		(start 418.052758 -287.82518)
		(end 417.791138 -287.82518)
		(width 0.14478)
		(layer "In13.Cu")
		(net "M_H_CPU0_SB_DQ<6>")
	)
	(segment
		(start 409.411932 -286.82188)
		(end 399.735548 -277.145496)
		(width 0.14478)
		(layer "In13.Cu")
		(net "M_H_CPU0_SB_DQ<6>")
	)
	(segment
		(start 417.646358 -288.140394)
		(end 417.501578 -288.285174)
		(width 0.14478)
		(layer "In13.Cu")
		(net "M_H_CPU0_SB_DQ<6>")
	)
	(segment
		(start 414.940242 -287.860232)
		(end 414.090104 -288.71037)
		(width 0.14478)
		(layer "In13.Cu")
		(net "M_H_CPU0_SB_DQ<6>")
	)
	(segment
		(start 416.248342 -287.715452)
		(end 416.248342 -287.615376)
		(width 0.14478)
		(layer "In13.Cu")
		(net "M_H_CPU0_SB_DQ<6>")
	)
	(segment
		(start 412.846266 -288.71037)
		(end 412.584646 -288.71037)
		(width 0.14478)
		(layer "In13.Cu")
		(net "M_H_CPU0_SB_DQ<6>")
	)
	(segment
		(start 410.182568 -286.831024)
		(end 409.997402 -286.645858)
		(width 0.14478)
		(layer "In13.Cu")
		(net "M_H_CPU0_SB_DQ<6>")
	)
	(segment
		(start 418.342318 -288.745168)
		(end 418.197538 -288.600388)
		(width 0.14478)
		(layer "In13.Cu")
		(net "M_H_CPU0_SB_DQ<6>")
	)
	(segment
		(start 410.191712 -287.60166)
		(end 410.006546 -287.416494)
		(width 0.14478)
		(layer "In13.Cu")
		(net "M_H_CPU0_SB_DQ<6>")
	)
	(segment
		(start 388.401814 -277.813516)
		(end 388.393432 -277.80869)
		(width 0.0889)
		(layer "In13.Cu")
		(net "M_H_CPU0_SB_DQ<6>")
	)
	(segment
		(start 418.603938 -288.745168)
		(end 418.342318 -288.745168)
		(width 0.14478)
		(layer "In13.Cu")
		(net "M_H_CPU0_SB_DQ<6>")
	)
	(segment
		(start 393.977114 -277.31847)
		(end 393.977114 -277.395432)
		(width 0.0889)
		(layer "In13.Cu")
		(net "M_H_CPU0_SB_DQ<6>")
	)
	(arc
		(start 393.818872 -277.730712)
		(mid 393.618997 -277.858642)
		(end 393.384786 -277.896828)
		(width 0.0889)
		(layer "In13.Cu")
		(net "M_H_CPU0_SB_DQ<6>")
	)
	(arc
		(start 390.847834 -277.813516)
		(mid 390.564878 -277.889693)
		(end 390.281922 -277.813516)
		(width 0.0889)
		(layer "In13.Cu")
		(net "M_H_CPU0_SB_DQ<6>")
	)
	(arc
		(start 393.384786 -277.896828)
		(mid 393.237585 -277.872528)
		(end 393.10056 -277.813516)
		(width 0.0889)
		(layer "In13.Cu")
		(net "M_H_CPU0_SB_DQ<6>")
	)
	(arc
		(start 392.140948 -277.80234)
		(mid 391.96287 -277.763356)
		(end 391.787634 -277.813516)
		(width 0.0889)
		(layer "In13.Cu")
		(net "M_H_CPU0_SB_DQ<6>")
	)
	(arc
		(start 391.787634 -277.813516)
		(mid 391.504678 -277.889693)
		(end 391.221722 -277.813516)
		(width 0.0889)
		(layer "In13.Cu")
		(net "M_H_CPU0_SB_DQ<6>")
	)
	(arc
		(start 393.10056 -277.813516)
		(mid 392.923769 -277.762797)
		(end 392.744198 -277.802594)
		(width 0.0889)
		(layer "In13.Cu")
		(net "M_H_CPU0_SB_DQ<6>")
	)
	(arc
		(start 392.725402 -277.813516)
		(mid 392.455633 -277.889539)
		(end 392.182604 -277.826216)
		(width 0.0889)
		(layer "In13.Cu")
		(net "M_H_CPU0_SB_DQ<6>")
	)
	(arc
		(start 387.46176 -277.813516)
		(mid 387.274816 -277.763261)
		(end 387.087872 -277.813516)
		(width 0.0889)
		(layer "In13.Cu")
		(net "M_H_CPU0_SB_DQ<6>")
	)
	(arc
		(start 391.221722 -277.813516)
		(mid 391.034778 -277.763261)
		(end 390.847834 -277.813516)
		(width 0.0889)
		(layer "In13.Cu")
		(net "M_H_CPU0_SB_DQ<6>")
	)
	(arc
		(start 386.52196 -277.813516)
		(mid 386.339709 -277.763166)
		(end 386.1562 -277.80869)
		(width 0.0889)
		(layer "In13.Cu")
		(net "M_H_CPU0_SB_DQ<6>")
	)
	(arc
		(start 389.90778 -277.813516)
		(mid 389.624824 -277.889693)
		(end 389.341868 -277.813516)
		(width 0.0889)
		(layer "In13.Cu")
		(net "M_H_CPU0_SB_DQ<6>")
	)
	(arc
		(start 388.027672 -277.813516)
		(mid 387.744716 -277.889693)
		(end 387.46176 -277.813516)
		(width 0.0889)
		(layer "In13.Cu")
		(net "M_H_CPU0_SB_DQ<6>")
	)
	(arc
		(start 385.207764 -277.813516)
		(mid 384.924808 -277.889693)
		(end 384.641852 -277.813516)
		(width 0.0889)
		(layer "In13.Cu")
		(net "M_H_CPU0_SB_DQ<6>")
	)
	(arc
		(start 388.967726 -277.813516)
		(mid 388.68477 -277.889693)
		(end 388.401814 -277.813516)
		(width 0.0889)
		(layer "In13.Cu")
		(net "M_H_CPU0_SB_DQ<6>")
	)
	(arc
		(start 389.333486 -277.80869)
		(mid 389.149978 -277.763196)
		(end 388.967726 -277.813516)
		(width 0.0889)
		(layer "In13.Cu")
		(net "M_H_CPU0_SB_DQ<6>")
	)
	(arc
		(start 387.087872 -277.813516)
		(mid 386.804916 -277.889693)
		(end 386.52196 -277.813516)
		(width 0.0889)
		(layer "In13.Cu")
		(net "M_H_CPU0_SB_DQ<6>")
	)
	(arc
		(start 386.147818 -277.813516)
		(mid 385.864862 -277.889693)
		(end 385.581906 -277.813516)
		(width 0.0889)
		(layer "In13.Cu")
		(net "M_H_CPU0_SB_DQ<6>")
	)
	(arc
		(start 393.977114 -277.395432)
		(mid 393.92717 -277.576846)
		(end 393.818872 -277.730712)
		(width 0.0889)
		(layer "In13.Cu")
		(net "M_H_CPU0_SB_DQ<6>")
	)
	(arc
		(start 384.63347 -277.80869)
		(mid 384.4806 -277.764049)
		(end 384.323082 -277.787354)
		(width 0.0889)
		(layer "In13.Cu")
		(net "M_H_CPU0_SB_DQ<6>")
	)
	(arc
		(start 385.581906 -277.813516)
		(mid 385.399655 -277.763166)
		(end 385.216146 -277.80869)
		(width 0.0889)
		(layer "In13.Cu")
		(net "M_H_CPU0_SB_DQ<6>")
	)
	(arc
		(start 388.393432 -277.80869)
		(mid 388.209924 -277.763196)
		(end 388.027672 -277.813516)
		(width 0.0889)
		(layer "In13.Cu")
		(net "M_H_CPU0_SB_DQ<6>")
	)
	(arc
		(start 390.281922 -277.813516)
		(mid 390.099671 -277.763166)
		(end 389.916162 -277.80869)
		(width 0.0889)
		(layer "In13.Cu")
		(net "M_H_CPU0_SB_DQ<6>")
	)
	(segment
		(start 382.107948 -277.870158)
		(end 382.5748 -278.136096)
		(width 0.10668)
		(layer "F.Cu")
		(net "M_H_CPU0_SB_DQ<5>")
	)
	(segment
		(start 386.1562 -278.463502)
		(end 386.147818 -278.458676)
		(width 0.0889)
		(layer "In13.Cu")
		(net "M_H_CPU0_SB_DQ<5>")
	)
	(segment
		(start 411.51429 -289.560254)
		(end 399.554192 -277.600156)
		(width 0.14478)
		(layer "In13.Cu")
		(net "M_H_CPU0_SB_DQ<5>")
	)
	(segment
		(start 384.641852 -278.458676)
		(end 384.63347 -278.463502)
		(width 0.0889)
		(layer "In13.Cu")
		(net "M_H_CPU0_SB_DQ<5>")
	)
	(segment
		(start 420.885366 -289.560254)
		(end 419.06698 -289.560254)
		(width 0.14478)
		(layer "In13.Cu")
		(net "M_H_CPU0_SB_DQ<5>")
	)
	(segment
		(start 382.728724 -278.401526)
		(end 382.5748 -278.136096)
		(width 0.0889)
		(layer "In13.Cu")
		(net "M_H_CPU0_SB_DQ<5>")
	)
	(segment
		(start 417.015168 -288.71037)
		(end 415.378392 -288.71037)
		(width 0.14478)
		(layer "In13.Cu")
		(net "M_H_CPU0_SB_DQ<5>")
	)
	(segment
		(start 385.216146 -278.463502)
		(end 385.207764 -278.458676)
		(width 0.0889)
		(layer "In13.Cu")
		(net "M_H_CPU0_SB_DQ<5>")
	)
	(segment
		(start 383.701798 -278.458676)
		(end 383.693416 -278.463502)
		(width 0.0889)
		(layer "In13.Cu")
		(net "M_H_CPU0_SB_DQ<5>")
	)
	(segment
		(start 389.341868 -278.458676)
		(end 389.333486 -278.463502)
		(width 0.0889)
		(layer "In13.Cu")
		(net "M_H_CPU0_SB_DQ<5>")
	)
	(segment
		(start 419.06698 -289.560254)
		(end 417.015168 -288.71037)
		(width 0.14478)
		(layer "In13.Cu")
		(net "M_H_CPU0_SB_DQ<5>")
	)
	(segment
		(start 413.32658 -289.560254)
		(end 411.51429 -289.560254)
		(width 0.14478)
		(layer "In13.Cu")
		(net "M_H_CPU0_SB_DQ<5>")
	)
	(segment
		(start 424.012106 -289.135058)
		(end 420.885366 -289.560254)
		(width 0.14478)
		(layer "In13.Cu")
		(net "M_H_CPU0_SB_DQ<5>")
	)
	(segment
		(start 391.796016 -278.463502)
		(end 391.787634 -278.458676)
		(width 0.0889)
		(layer "In13.Cu")
		(net "M_H_CPU0_SB_DQ<5>")
	)
	(segment
		(start 399.554192 -277.600156)
		(end 395.868398 -277.600156)
		(width 0.14478)
		(layer "In13.Cu")
		(net "M_H_CPU0_SB_DQ<5>")
	)
	(segment
		(start 395.30274 -277.600156)
		(end 395.214094 -277.51151)
		(width 0.0889)
		(layer "In13.Cu")
		(net "M_H_CPU0_SB_DQ<5>")
	)
	(segment
		(start 392.72845 -278.458676)
		(end 392.718036 -278.45258)
		(width 0.0889)
		(layer "In13.Cu")
		(net "M_H_CPU0_SB_DQ<5>")
	)
	(segment
		(start 388.401814 -278.458676)
		(end 388.393432 -278.463502)
		(width 0.0889)
		(layer "In13.Cu")
		(net "M_H_CPU0_SB_DQ<5>")
	)
	(segment
		(start 382.824736 -278.426926)
		(end 382.728724 -278.401526)
		(width 0.0889)
		(layer "In13.Cu")
		(net "M_H_CPU0_SB_DQ<5>")
	)
	(segment
		(start 394.703554 -277.51151)
		(end 393.086082 -278.46782)
		(width 0.0889)
		(layer "In13.Cu")
		(net "M_H_CPU0_SB_DQ<5>")
	)
	(segment
		(start 389.916162 -278.463502)
		(end 389.90778 -278.458676)
		(width 0.0889)
		(layer "In13.Cu")
		(net "M_H_CPU0_SB_DQ<5>")
	)
	(segment
		(start 395.214094 -277.51151)
		(end 394.703554 -277.51151)
		(width 0.0889)
		(layer "In13.Cu")
		(net "M_H_CPU0_SB_DQ<5>")
	)
	(segment
		(start 415.378392 -288.71037)
		(end 413.32658 -289.560254)
		(width 0.14478)
		(layer "In13.Cu")
		(net "M_H_CPU0_SB_DQ<5>")
	)
	(segment
		(start 395.868398 -277.600156)
		(end 395.30274 -277.600156)
		(width 0.0889)
		(layer "In13.Cu")
		(net "M_H_CPU0_SB_DQ<5>")
	)
	(arc
		(start 384.26771 -278.458676)
		(mid 383.984754 -278.382499)
		(end 383.701798 -278.458676)
		(width 0.0889)
		(layer "In13.Cu")
		(net "M_H_CPU0_SB_DQ<5>")
	)
	(arc
		(start 393.086082 -278.46782)
		(mid 392.9061 -278.50892)
		(end 392.72845 -278.458676)
		(width 0.0889)
		(layer "In13.Cu")
		(net "M_H_CPU0_SB_DQ<5>")
	)
	(arc
		(start 391.787634 -278.458676)
		(mid 391.504678 -278.382499)
		(end 391.221722 -278.458676)
		(width 0.0889)
		(layer "In13.Cu")
		(net "M_H_CPU0_SB_DQ<5>")
	)
	(arc
		(start 388.967726 -278.458676)
		(mid 388.68477 -278.382499)
		(end 388.401814 -278.458676)
		(width 0.0889)
		(layer "In13.Cu")
		(net "M_H_CPU0_SB_DQ<5>")
	)
	(arc
		(start 387.46176 -278.458676)
		(mid 387.274816 -278.508931)
		(end 387.087872 -278.458676)
		(width 0.0889)
		(layer "In13.Cu")
		(net "M_H_CPU0_SB_DQ<5>")
	)
	(arc
		(start 390.847834 -278.458676)
		(mid 390.564878 -278.382499)
		(end 390.281922 -278.458676)
		(width 0.0889)
		(layer "In13.Cu")
		(net "M_H_CPU0_SB_DQ<5>")
	)
	(arc
		(start 386.52196 -278.458676)
		(mid 386.339709 -278.509026)
		(end 386.1562 -278.463502)
		(width 0.0889)
		(layer "In13.Cu")
		(net "M_H_CPU0_SB_DQ<5>")
	)
	(arc
		(start 385.581906 -278.458676)
		(mid 385.399655 -278.509026)
		(end 385.216146 -278.463502)
		(width 0.0889)
		(layer "In13.Cu")
		(net "M_H_CPU0_SB_DQ<5>")
	)
	(arc
		(start 387.087872 -278.458676)
		(mid 386.804916 -278.382499)
		(end 386.52196 -278.458676)
		(width 0.0889)
		(layer "In13.Cu")
		(net "M_H_CPU0_SB_DQ<5>")
	)
	(arc
		(start 389.90778 -278.458676)
		(mid 389.624824 -278.382499)
		(end 389.341868 -278.458676)
		(width 0.0889)
		(layer "In13.Cu")
		(net "M_H_CPU0_SB_DQ<5>")
	)
	(arc
		(start 388.393432 -278.463502)
		(mid 388.209924 -278.508996)
		(end 388.027672 -278.458676)
		(width 0.0889)
		(layer "In13.Cu")
		(net "M_H_CPU0_SB_DQ<5>")
	)
	(arc
		(start 392.718036 -278.45258)
		(mid 392.43935 -278.38236)
		(end 392.162284 -278.458676)
		(width 0.0889)
		(layer "In13.Cu")
		(net "M_H_CPU0_SB_DQ<5>")
	)
	(arc
		(start 392.162284 -278.458676)
		(mid 391.979779 -278.509153)
		(end 391.796016 -278.463502)
		(width 0.0889)
		(layer "In13.Cu")
		(net "M_H_CPU0_SB_DQ<5>")
	)
	(arc
		(start 385.207764 -278.458676)
		(mid 384.924808 -278.382499)
		(end 384.641852 -278.458676)
		(width 0.0889)
		(layer "In13.Cu")
		(net "M_H_CPU0_SB_DQ<5>")
	)
	(arc
		(start 388.027672 -278.458676)
		(mid 387.744716 -278.382499)
		(end 387.46176 -278.458676)
		(width 0.0889)
		(layer "In13.Cu")
		(net "M_H_CPU0_SB_DQ<5>")
	)
	(arc
		(start 391.221722 -278.458676)
		(mid 391.034778 -278.508931)
		(end 390.847834 -278.458676)
		(width 0.0889)
		(layer "In13.Cu")
		(net "M_H_CPU0_SB_DQ<5>")
	)
	(arc
		(start 390.281922 -278.458676)
		(mid 390.099671 -278.509026)
		(end 389.916162 -278.463502)
		(width 0.0889)
		(layer "In13.Cu")
		(net "M_H_CPU0_SB_DQ<5>")
	)
	(arc
		(start 389.333486 -278.463502)
		(mid 389.149978 -278.508996)
		(end 388.967726 -278.458676)
		(width 0.0889)
		(layer "In13.Cu")
		(net "M_H_CPU0_SB_DQ<5>")
	)
	(arc
		(start 386.147818 -278.458676)
		(mid 385.864862 -278.382499)
		(end 385.581906 -278.458676)
		(width 0.0889)
		(layer "In13.Cu")
		(net "M_H_CPU0_SB_DQ<5>")
	)
	(arc
		(start 383.693416 -278.463502)
		(mid 383.509908 -278.508996)
		(end 383.327656 -278.458676)
		(width 0.0889)
		(layer "In13.Cu")
		(net "M_H_CPU0_SB_DQ<5>")
	)
	(arc
		(start 383.327656 -278.458676)
		(mid 383.079943 -278.383456)
		(end 382.824736 -278.426926)
		(width 0.0889)
		(layer "In13.Cu")
		(net "M_H_CPU0_SB_DQ<5>")
	)
	(arc
		(start 384.63347 -278.463502)
		(mid 384.449962 -278.508996)
		(end 384.26771 -278.458676)
		(width 0.0889)
		(layer "In13.Cu")
		(net "M_H_CPU0_SB_DQ<5>")
	)
	(segment
		(start 383.517902 -277.060152)
		(end 383.984754 -277.32609)
		(width 0.10668)
		(layer "F.Cu")
		(net "M_H_CPU0_SB_DQ<4>")
	)
	(segment
		(start 386.99186 -277.64867)
		(end 386.983478 -277.653496)
		(width 0.0889)
		(layer "In13.Cu")
		(net "M_H_CPU0_SB_DQ<4>")
	)
	(segment
		(start 392.274552 -277.65883)
		(end 392.256264 -277.648416)
		(width 0.0889)
		(layer "In13.Cu")
		(net "M_H_CPU0_SB_DQ<4>")
	)
	(segment
		(start 395.331188 -276.690836)
		(end 395.310614 -276.71141)
		(width 0.0889)
		(layer "In13.Cu")
		(net "M_H_CPU0_SB_DQ<4>")
	)
	(segment
		(start 424.012106 -287.435036)
		(end 423.577258 -287.869884)
		(width 0.14478)
		(layer "In13.Cu")
		(net "M_H_CPU0_SB_DQ<4>")
	)
	(segment
		(start 392.652758 -277.634954)
		(end 392.62939 -277.64867)
		(width 0.0889)
		(layer "In13.Cu")
		(net "M_H_CPU0_SB_DQ<4>")
	)
	(segment
		(start 409.422346 -286.196278)
		(end 399.916904 -276.690836)
		(width 0.14478)
		(layer "In13.Cu")
		(net "M_H_CPU0_SB_DQ<4>")
	)
	(segment
		(start 399.916904 -276.690836)
		(end 395.99362 -276.690836)
		(width 0.14478)
		(layer "In13.Cu")
		(net "M_H_CPU0_SB_DQ<4>")
	)
	(segment
		(start 421.491156 -288.014664)
		(end 421.346376 -287.869884)
		(width 0.14478)
		(layer "In13.Cu")
		(net "M_H_CPU0_SB_DQ<4>")
	)
	(segment
		(start 423.144696 -288.156396)
		(end 422.999916 -288.301176)
		(width 0.14478)
		(layer "In13.Cu")
		(net "M_H_CPU0_SB_DQ<4>")
	)
	(segment
		(start 422.042336 -288.156396)
		(end 421.897556 -288.301176)
		(width 0.14478)
		(layer "In13.Cu")
		(net "M_H_CPU0_SB_DQ<4>")
	)
	(segment
		(start 393.570714 -277.648416)
		(end 393.543282 -277.664164)
		(width 0.0889)
		(layer "In13.Cu")
		(net "M_H_CPU0_SB_DQ<4>")
	)
	(segment
		(start 421.068246 -287.869884)
		(end 418.993066 -287.010348)
		(width 0.14478)
		(layer "In13.Cu")
		(net "M_H_CPU0_SB_DQ<4>")
	)
	(segment
		(start 388.506208 -277.653496)
		(end 388.497826 -277.64867)
		(width 0.0889)
		(layer "In13.Cu")
		(net "M_H_CPU0_SB_DQ<4>")
	)
	(segment
		(start 423.144696 -288.014664)
		(end 423.144696 -288.156396)
		(width 0.14478)
		(layer "In13.Cu")
		(net "M_H_CPU0_SB_DQ<4>")
	)
	(segment
		(start 414.183068 -287.860232)
		(end 412.07182 -287.860232)
		(width 0.14478)
		(layer "In13.Cu")
		(net "M_H_CPU0_SB_DQ<4>")
	)
	(segment
		(start 422.999916 -288.301176)
		(end 422.738296 -288.301176)
		(width 0.14478)
		(layer "In13.Cu")
		(net "M_H_CPU0_SB_DQ<4>")
	)
	(segment
		(start 421.346376 -287.869884)
		(end 421.068246 -287.869884)
		(width 0.14478)
		(layer "In13.Cu")
		(net "M_H_CPU0_SB_DQ<4>")
	)
	(segment
		(start 410.407866 -286.196278)
		(end 409.422346 -286.196278)
		(width 0.14478)
		(layer "In13.Cu")
		(net "M_H_CPU0_SB_DQ<4>")
	)
	(segment
		(start 384.235198 -277.61692)
		(end 384.138932 -277.59152)
		(width 0.0889)
		(layer "In13.Cu")
		(net "M_H_CPU0_SB_DQ<4>")
	)
	(segment
		(start 393.745974 -277.15337)
		(end 393.745974 -277.425404)
		(width 0.0889)
		(layer "In13.Cu")
		(net "M_H_CPU0_SB_DQ<4>")
	)
	(segment
		(start 422.593516 -288.156396)
		(end 422.593516 -288.014664)
		(width 0.14478)
		(layer "In13.Cu")
		(net "M_H_CPU0_SB_DQ<4>")
	)
	(segment
		(start 393.703048 -277.529036)
		(end 393.621006 -277.611078)
		(width 0.0889)
		(layer "In13.Cu")
		(net "M_H_CPU0_SB_DQ<4>")
	)
	(segment
		(start 422.593516 -288.014664)
		(end 422.448736 -287.869884)
		(width 0.14478)
		(layer "In13.Cu")
		(net "M_H_CPU0_SB_DQ<4>")
	)
	(segment
		(start 393.621006 -277.611078)
		(end 393.570714 -277.648416)
		(width 0.0889)
		(layer "In13.Cu")
		(net "M_H_CPU0_SB_DQ<4>")
	)
	(segment
		(start 390.751822 -277.64867)
		(end 390.74344 -277.653496)
		(width 0.0889)
		(layer "In13.Cu")
		(net "M_H_CPU0_SB_DQ<4>")
	)
	(segment
		(start 415.032952 -287.010348)
		(end 414.183068 -287.860232)
		(width 0.14478)
		(layer "In13.Cu")
		(net "M_H_CPU0_SB_DQ<4>")
	)
	(segment
		(start 412.07182 -287.860232)
		(end 410.407866 -286.196278)
		(width 0.14478)
		(layer "In13.Cu")
		(net "M_H_CPU0_SB_DQ<4>")
	)
	(segment
		(start 384.138932 -277.59152)
		(end 383.984754 -277.32609)
		(width 0.0889)
		(layer "In13.Cu")
		(net "M_H_CPU0_SB_DQ<4>")
	)
	(segment
		(start 421.897556 -288.301176)
		(end 421.635936 -288.301176)
		(width 0.14478)
		(layer "In13.Cu")
		(net "M_H_CPU0_SB_DQ<4>")
	)
	(segment
		(start 421.491156 -288.156396)
		(end 421.491156 -288.014664)
		(width 0.14478)
		(layer "In13.Cu")
		(net "M_H_CPU0_SB_DQ<4>")
	)
	(segment
		(start 422.448736 -287.869884)
		(end 422.187116 -287.869884)
		(width 0.14478)
		(layer "In13.Cu")
		(net "M_H_CPU0_SB_DQ<4>")
	)
	(segment
		(start 422.187116 -287.869884)
		(end 422.042336 -288.014664)
		(width 0.14478)
		(layer "In13.Cu")
		(net "M_H_CPU0_SB_DQ<4>")
	)
	(segment
		(start 392.256264 -277.648416)
		(end 392.234674 -277.63597)
		(width 0.0889)
		(layer "In13.Cu")
		(net "M_H_CPU0_SB_DQ<4>")
	)
	(segment
		(start 386.051806 -277.64867)
		(end 386.043424 -277.653496)
		(width 0.0889)
		(layer "In13.Cu")
		(net "M_H_CPU0_SB_DQ<4>")
	)
	(segment
		(start 395.310614 -276.71141)
		(end 394.187934 -276.71141)
		(width 0.0889)
		(layer "In13.Cu")
		(net "M_H_CPU0_SB_DQ<4>")
	)
	(segment
		(start 393.745974 -277.425404)
		(end 393.703048 -277.529036)
		(width 0.0889)
		(layer "In13.Cu")
		(net "M_H_CPU0_SB_DQ<4>")
	)
	(segment
		(start 423.289476 -287.869884)
		(end 423.144696 -288.014664)
		(width 0.14478)
		(layer "In13.Cu")
		(net "M_H_CPU0_SB_DQ<4>")
	)
	(segment
		(start 423.577258 -287.869884)
		(end 423.289476 -287.869884)
		(width 0.14478)
		(layer "In13.Cu")
		(net "M_H_CPU0_SB_DQ<4>")
	)
	(segment
		(start 394.187934 -276.71141)
		(end 393.745974 -277.15337)
		(width 0.0889)
		(layer "In13.Cu")
		(net "M_H_CPU0_SB_DQ<4>")
	)
	(segment
		(start 395.99362 -276.690836)
		(end 395.331188 -276.690836)
		(width 0.0889)
		(layer "In13.Cu")
		(net "M_H_CPU0_SB_DQ<4>")
	)
	(segment
		(start 391.326116 -277.653496)
		(end 391.317734 -277.64867)
		(width 0.0889)
		(layer "In13.Cu")
		(net "M_H_CPU0_SB_DQ<4>")
	)
	(segment
		(start 422.042336 -288.014664)
		(end 422.042336 -288.156396)
		(width 0.14478)
		(layer "In13.Cu")
		(net "M_H_CPU0_SB_DQ<4>")
	)
	(segment
		(start 418.993066 -287.010348)
		(end 415.032952 -287.010348)
		(width 0.14478)
		(layer "In13.Cu")
		(net "M_H_CPU0_SB_DQ<4>")
	)
	(segment
		(start 387.566154 -277.653496)
		(end 387.557772 -277.64867)
		(width 0.0889)
		(layer "In13.Cu")
		(net "M_H_CPU0_SB_DQ<4>")
	)
	(segment
		(start 421.635936 -288.301176)
		(end 421.491156 -288.156396)
		(width 0.14478)
		(layer "In13.Cu")
		(net "M_H_CPU0_SB_DQ<4>")
	)
	(segment
		(start 422.738296 -288.301176)
		(end 422.593516 -288.156396)
		(width 0.14478)
		(layer "In13.Cu")
		(net "M_H_CPU0_SB_DQ<4>")
	)
	(arc
		(start 391.691876 -277.64867)
		(mid 391.509625 -277.69902)
		(end 391.326116 -277.653496)
		(width 0.0889)
		(layer "In13.Cu")
		(net "M_H_CPU0_SB_DQ<4>")
	)
	(arc
		(start 384.737864 -277.64867)
		(mid 384.490268 -277.573492)
		(end 384.235198 -277.61692)
		(width 0.0889)
		(layer "In13.Cu")
		(net "M_H_CPU0_SB_DQ<4>")
	)
	(arc
		(start 387.931914 -277.64867)
		(mid 387.749663 -277.69902)
		(end 387.566154 -277.653496)
		(width 0.0889)
		(layer "In13.Cu")
		(net "M_H_CPU0_SB_DQ<4>")
	)
	(arc
		(start 386.043424 -277.653496)
		(mid 385.859916 -277.69899)
		(end 385.677664 -277.64867)
		(width 0.0889)
		(layer "In13.Cu")
		(net "M_H_CPU0_SB_DQ<4>")
	)
	(arc
		(start 387.557772 -277.64867)
		(mid 387.274816 -277.572493)
		(end 386.99186 -277.64867)
		(width 0.0889)
		(layer "In13.Cu")
		(net "M_H_CPU0_SB_DQ<4>")
	)
	(arc
		(start 390.37768 -277.64867)
		(mid 390.094724 -277.572493)
		(end 389.811768 -277.64867)
		(width 0.0889)
		(layer "In13.Cu")
		(net "M_H_CPU0_SB_DQ<4>")
	)
	(arc
		(start 393.196572 -277.64867)
		(mid 392.926415 -277.571908)
		(end 392.652758 -277.634954)
		(width 0.0889)
		(layer "In13.Cu")
		(net "M_H_CPU0_SB_DQ<4>")
	)
	(arc
		(start 386.983478 -277.653496)
		(mid 386.79997 -277.69899)
		(end 386.617718 -277.64867)
		(width 0.0889)
		(layer "In13.Cu")
		(net "M_H_CPU0_SB_DQ<4>")
	)
	(arc
		(start 386.617718 -277.64867)
		(mid 386.334762 -277.572493)
		(end 386.051806 -277.64867)
		(width 0.0889)
		(layer "In13.Cu")
		(net "M_H_CPU0_SB_DQ<4>")
	)
	(arc
		(start 391.317734 -277.64867)
		(mid 391.034778 -277.572493)
		(end 390.751822 -277.64867)
		(width 0.0889)
		(layer "In13.Cu")
		(net "M_H_CPU0_SB_DQ<4>")
	)
	(arc
		(start 392.62939 -277.64867)
		(mid 392.45327 -277.698648)
		(end 392.274552 -277.65883)
		(width 0.0889)
		(layer "In13.Cu")
		(net "M_H_CPU0_SB_DQ<4>")
	)
	(arc
		(start 392.234674 -277.63597)
		(mid 391.961645 -277.572651)
		(end 391.691876 -277.64867)
		(width 0.0889)
		(layer "In13.Cu")
		(net "M_H_CPU0_SB_DQ<4>")
	)
	(arc
		(start 388.871968 -277.64867)
		(mid 388.689717 -277.69902)
		(end 388.506208 -277.653496)
		(width 0.0889)
		(layer "In13.Cu")
		(net "M_H_CPU0_SB_DQ<4>")
	)
	(arc
		(start 385.677664 -277.64867)
		(mid 385.394708 -277.572493)
		(end 385.111752 -277.64867)
		(width 0.0889)
		(layer "In13.Cu")
		(net "M_H_CPU0_SB_DQ<4>")
	)
	(arc
		(start 389.811768 -277.64867)
		(mid 389.624824 -277.698925)
		(end 389.43788 -277.64867)
		(width 0.0889)
		(layer "In13.Cu")
		(net "M_H_CPU0_SB_DQ<4>")
	)
	(arc
		(start 385.111752 -277.64867)
		(mid 384.924808 -277.698925)
		(end 384.737864 -277.64867)
		(width 0.0889)
		(layer "In13.Cu")
		(net "M_H_CPU0_SB_DQ<4>")
	)
	(arc
		(start 388.497826 -277.64867)
		(mid 388.21487 -277.572493)
		(end 387.931914 -277.64867)
		(width 0.0889)
		(layer "In13.Cu")
		(net "M_H_CPU0_SB_DQ<4>")
	)
	(arc
		(start 393.543282 -277.664164)
		(mid 393.368031 -277.699097)
		(end 393.196572 -277.64867)
		(width 0.0889)
		(layer "In13.Cu")
		(net "M_H_CPU0_SB_DQ<4>")
	)
	(arc
		(start 390.74344 -277.653496)
		(mid 390.559932 -277.69899)
		(end 390.37768 -277.64867)
		(width 0.0889)
		(layer "In13.Cu")
		(net "M_H_CPU0_SB_DQ<4>")
	)
	(arc
		(start 389.43788 -277.64867)
		(mid 389.154924 -277.572493)
		(end 388.871968 -277.64867)
		(width 0.0889)
		(layer "In13.Cu")
		(net "M_H_CPU0_SB_DQ<4>")
	)
	(segment
		(start 382.577848 -275.44014)
		(end 383.0447 -275.706078)
		(width 0.10668)
		(layer "F.Cu")
		(net "M_H_CPU0_SB_DQ<3>")
	)
	(segment
		(start 417.937442 -283.893768)
		(end 418.126418 -283.815536)
		(width 0.14478)
		(layer "In13.Cu")
		(net "M_H_CPU0_SB_DQ<3>")
	)
	(segment
		(start 388.497826 -275.383498)
		(end 388.506208 -275.378672)
		(width 0.0889)
		(layer "In13.Cu")
		(net "M_H_CPU0_SB_DQ<3>")
	)
	(segment
		(start 403.98954 -276.768814)
		(end 404.21814 -276.768814)
		(width 0.14478)
		(layer "In13.Cu")
		(net "M_H_CPU0_SB_DQ<3>")
	)
	(segment
		(start 403.337776 -276.86889)
		(end 403.49932 -277.030434)
		(width 0.14478)
		(layer "In13.Cu")
		(net "M_H_CPU0_SB_DQ<3>")
	)
	(segment
		(start 402.03882 -274.818094)
		(end 401.7772 -275.079714)
		(width 0.14478)
		(layer "In13.Cu")
		(net "M_H_CPU0_SB_DQ<3>")
	)
	(segment
		(start 419.675564 -284.05963)
		(end 419.8874 -284.05963)
		(width 0.14478)
		(layer "In13.Cu")
		(net "M_H_CPU0_SB_DQ<3>")
	)
	(segment
		(start 392.62431 -275.378672)
		(end 392.632692 -275.383498)
		(width 0.0889)
		(layer "In13.Cu")
		(net "M_H_CPU0_SB_DQ<3>")
	)
	(segment
		(start 418.642546 -283.632148)
		(end 418.720778 -283.821124)
		(width 0.14478)
		(layer "In13.Cu")
		(net "M_H_CPU0_SB_DQ<3>")
	)
	(segment
		(start 393.192508 -275.387054)
		(end 393.332716 -275.343112)
		(width 0.0889)
		(layer "In13.Cu")
		(net "M_H_CPU0_SB_DQ<3>")
	)
	(segment
		(start 402.428964 -275.208238)
		(end 402.657564 -275.208238)
		(width 0.14478)
		(layer "In13.Cu")
		(net "M_H_CPU0_SB_DQ<3>")
	)
	(segment
		(start 417.617148 -283.604462)
		(end 417.69538 -283.793438)
		(width 0.14478)
		(layer "In13.Cu")
		(net "M_H_CPU0_SB_DQ<3>")
	)
	(segment
		(start 418.770308 -284.079442)
		(end 419.01237 -284.179772)
		(width 0.14478)
		(layer "In13.Cu")
		(net "M_H_CPU0_SB_DQ<3>")
	)
	(segment
		(start 403.49932 -277.030434)
		(end 403.72792 -277.030434)
		(width 0.14478)
		(layer "In13.Cu")
		(net "M_H_CPU0_SB_DQ<3>")
	)
	(segment
		(start 419.201346 -284.10154)
		(end 419.230048 -284.032198)
		(width 0.14478)
		(layer "In13.Cu")
		(net "M_H_CPU0_SB_DQ<3>")
	)
	(segment
		(start 386.043424 -275.378672)
		(end 386.051806 -275.383498)
		(width 0.0889)
		(layer "In13.Cu")
		(net "M_H_CPU0_SB_DQ<3>")
	)
	(segment
		(start 414.10255 -284.05963)
		(end 414.952434 -283.209746)
		(width 0.14478)
		(layer "In13.Cu")
		(net "M_H_CPU0_SB_DQ<3>")
	)
	(segment
		(start 402.819108 -275.369782)
		(end 402.819108 -275.598382)
		(width 0.14478)
		(layer "In13.Cu")
		(net "M_H_CPU0_SB_DQ<3>")
	)
	(segment
		(start 404.21814 -276.768814)
		(end 411.508956 -284.05963)
		(width 0.14478)
		(layer "In13.Cu")
		(net "M_H_CPU0_SB_DQ<3>")
	)
	(segment
		(start 393.332716 -275.343112)
		(end 393.431014 -275.316188)
		(width 0.0889)
		(layer "In13.Cu")
		(net "M_H_CPU0_SB_DQ<3>")
	)
	(segment
		(start 402.03882 -274.589494)
		(end 402.03882 -274.818094)
		(width 0.14478)
		(layer "In13.Cu")
		(net "M_H_CPU0_SB_DQ<3>")
	)
	(segment
		(start 403.437852 -275.988526)
		(end 403.599396 -276.15007)
		(width 0.14478)
		(layer "In13.Cu")
		(net "M_H_CPU0_SB_DQ<3>")
	)
	(segment
		(start 387.557772 -275.383498)
		(end 387.566154 -275.378672)
		(width 0.0889)
		(layer "In13.Cu")
		(net "M_H_CPU0_SB_DQ<3>")
	)
	(segment
		(start 402.657564 -275.208238)
		(end 402.819108 -275.369782)
		(width 0.14478)
		(layer "In13.Cu")
		(net "M_H_CPU0_SB_DQ<3>")
	)
	(segment
		(start 395.33449 -274.25777)
		(end 395.38021 -274.30349)
		(width 0.0889)
		(layer "In13.Cu")
		(net "M_H_CPU0_SB_DQ<3>")
	)
	(segment
		(start 402.167344 -275.469858)
		(end 402.428964 -275.208238)
		(width 0.14478)
		(layer "In13.Cu")
		(net "M_H_CPU0_SB_DQ<3>")
	)
	(segment
		(start 418.692076 -283.890466)
		(end 418.770308 -284.079442)
		(width 0.14478)
		(layer "In13.Cu")
		(net "M_H_CPU0_SB_DQ<3>")
	)
	(segment
		(start 393.87145 -275.133308)
		(end 393.95527 -275.077174)
		(width 0.0889)
		(layer "In13.Cu")
		(net "M_H_CPU0_SB_DQ<3>")
	)
	(segment
		(start 418.211508 -283.61005)
		(end 418.400484 -283.531818)
		(width 0.14478)
		(layer "In13.Cu")
		(net "M_H_CPU0_SB_DQ<3>")
	)
	(segment
		(start 417.623752 -283.209746)
		(end 417.702238 -283.398976)
		(width 0.14478)
		(layer "In13.Cu")
		(net "M_H_CPU0_SB_DQ<3>")
	)
	(segment
		(start 401.752816 -274.30349)
		(end 402.03882 -274.589494)
		(width 0.14478)
		(layer "In13.Cu")
		(net "M_H_CPU0_SB_DQ<3>")
	)
	(segment
		(start 419.01237 -284.179772)
		(end 419.201346 -284.10154)
		(width 0.14478)
		(layer "In13.Cu")
		(net "M_H_CPU0_SB_DQ<3>")
	)
	(segment
		(start 403.209252 -275.988526)
		(end 403.437852 -275.988526)
		(width 0.14478)
		(layer "In13.Cu")
		(net "M_H_CPU0_SB_DQ<3>")
	)
	(segment
		(start 391.691876 -275.383498)
		(end 391.70229 -275.389594)
		(width 0.0889)
		(layer "In13.Cu")
		(net "M_H_CPU0_SB_DQ<3>")
	)
	(segment
		(start 401.7772 -275.079714)
		(end 401.7772 -275.308314)
		(width 0.14478)
		(layer "In13.Cu")
		(net "M_H_CPU0_SB_DQ<3>")
	)
	(segment
		(start 402.557488 -276.088602)
		(end 402.719032 -276.250146)
		(width 0.14478)
		(layer "In13.Cu")
		(net "M_H_CPU0_SB_DQ<3>")
	)
	(segment
		(start 403.72792 -277.030434)
		(end 403.98954 -276.768814)
		(width 0.14478)
		(layer "In13.Cu")
		(net "M_H_CPU0_SB_DQ<3>")
	)
	(segment
		(start 394.774674 -274.25777)
		(end 395.33449 -274.25777)
		(width 0.0889)
		(layer "In13.Cu")
		(net "M_H_CPU0_SB_DQ<3>")
	)
	(segment
		(start 403.599396 -276.15007)
		(end 403.599396 -276.37867)
		(width 0.14478)
		(layer "In13.Cu")
		(net "M_H_CPU0_SB_DQ<3>")
	)
	(segment
		(start 391.317734 -275.383498)
		(end 391.326116 -275.378672)
		(width 0.0889)
		(layer "In13.Cu")
		(net "M_H_CPU0_SB_DQ<3>")
	)
	(segment
		(start 382.890776 -275.440648)
		(end 382.913128 -275.357336)
		(width 0.0889)
		(layer "In13.Cu")
		(net "M_H_CPU0_SB_DQ<3>")
	)
	(segment
		(start 419.8874 -284.05963)
		(end 419.912038 -284.034992)
		(width 0.14478)
		(layer "In13.Cu")
		(net "M_H_CPU0_SB_DQ<3>")
	)
	(segment
		(start 403.337776 -276.64029)
		(end 403.337776 -276.86889)
		(width 0.14478)
		(layer "In13.Cu")
		(net "M_H_CPU0_SB_DQ<3>")
	)
	(segment
		(start 417.69538 -283.793438)
		(end 417.937442 -283.893768)
		(width 0.14478)
		(layer "In13.Cu")
		(net "M_H_CPU0_SB_DQ<3>")
	)
	(segment
		(start 402.719032 -276.250146)
		(end 402.947632 -276.250146)
		(width 0.14478)
		(layer "In13.Cu")
		(net "M_H_CPU0_SB_DQ<3>")
	)
	(segment
		(start 393.95527 -275.077174)
		(end 394.774674 -274.25777)
		(width 0.0889)
		(layer "In13.Cu")
		(net "M_H_CPU0_SB_DQ<3>")
	)
	(segment
		(start 418.126418 -283.815536)
		(end 418.211508 -283.61005)
		(width 0.14478)
		(layer "In13.Cu")
		(net "M_H_CPU0_SB_DQ<3>")
	)
	(segment
		(start 402.947632 -276.250146)
		(end 403.209252 -275.988526)
		(width 0.14478)
		(layer "In13.Cu")
		(net "M_H_CPU0_SB_DQ<3>")
	)
	(segment
		(start 411.508956 -284.05963)
		(end 414.10255 -284.05963)
		(width 0.14478)
		(layer "In13.Cu")
		(net "M_H_CPU0_SB_DQ<3>")
	)
	(segment
		(start 403.599396 -276.37867)
		(end 403.337776 -276.64029)
		(width 0.14478)
		(layer "In13.Cu")
		(net "M_H_CPU0_SB_DQ<3>")
	)
	(segment
		(start 402.557488 -275.860002)
		(end 402.557488 -276.088602)
		(width 0.14478)
		(layer "In13.Cu")
		(net "M_H_CPU0_SB_DQ<3>")
	)
	(segment
		(start 414.952434 -283.209746)
		(end 417.623752 -283.209746)
		(width 0.14478)
		(layer "In13.Cu")
		(net "M_H_CPU0_SB_DQ<3>")
	)
	(segment
		(start 419.419278 -283.953712)
		(end 419.675564 -284.05963)
		(width 0.14478)
		(layer "In13.Cu")
		(net "M_H_CPU0_SB_DQ<3>")
	)
	(segment
		(start 401.7772 -275.308314)
		(end 401.938744 -275.469858)
		(width 0.14478)
		(layer "In13.Cu")
		(net "M_H_CPU0_SB_DQ<3>")
	)
	(segment
		(start 383.0447 -275.706078)
		(end 382.890776 -275.440648)
		(width 0.0889)
		(layer "In13.Cu")
		(net "M_H_CPU0_SB_DQ<3>")
	)
	(segment
		(start 393.431014 -275.316188)
		(end 393.87145 -275.133308)
		(width 0.0889)
		(layer "In13.Cu")
		(net "M_H_CPU0_SB_DQ<3>")
	)
	(segment
		(start 390.74344 -275.378672)
		(end 390.751822 -275.383498)
		(width 0.0889)
		(layer "In13.Cu")
		(net "M_H_CPU0_SB_DQ<3>")
	)
	(segment
		(start 395.38021 -274.30349)
		(end 395.902688 -274.30349)
		(width 0.0889)
		(layer "In13.Cu")
		(net "M_H_CPU0_SB_DQ<3>")
	)
	(segment
		(start 418.400484 -283.531818)
		(end 418.642546 -283.632148)
		(width 0.14478)
		(layer "In13.Cu")
		(net "M_H_CPU0_SB_DQ<3>")
	)
	(segment
		(start 386.983478 -275.378672)
		(end 386.99186 -275.383498)
		(width 0.0889)
		(layer "In13.Cu")
		(net "M_H_CPU0_SB_DQ<3>")
	)
	(segment
		(start 402.819108 -275.598382)
		(end 402.557488 -275.860002)
		(width 0.14478)
		(layer "In13.Cu")
		(net "M_H_CPU0_SB_DQ<3>")
	)
	(segment
		(start 418.720778 -283.821124)
		(end 418.692076 -283.890466)
		(width 0.14478)
		(layer "In13.Cu")
		(net "M_H_CPU0_SB_DQ<3>")
	)
	(segment
		(start 417.702238 -283.398976)
		(end 417.617148 -283.604462)
		(width 0.14478)
		(layer "In13.Cu")
		(net "M_H_CPU0_SB_DQ<3>")
	)
	(segment
		(start 395.902688 -274.30349)
		(end 401.752816 -274.30349)
		(width 0.14478)
		(layer "In13.Cu")
		(net "M_H_CPU0_SB_DQ<3>")
	)
	(segment
		(start 401.938744 -275.469858)
		(end 402.167344 -275.469858)
		(width 0.14478)
		(layer "In13.Cu")
		(net "M_H_CPU0_SB_DQ<3>")
	)
	(segment
		(start 383.79781 -275.383498)
		(end 383.806192 -275.378672)
		(width 0.0889)
		(layer "In13.Cu")
		(net "M_H_CPU0_SB_DQ<3>")
	)
	(segment
		(start 419.230048 -284.032198)
		(end 419.419278 -283.953712)
		(width 0.14478)
		(layer "In13.Cu")
		(net "M_H_CPU0_SB_DQ<3>")
	)
	(arc
		(start 383.231898 -275.383498)
		(mid 383.514854 -275.459675)
		(end 383.79781 -275.383498)
		(width 0.0889)
		(layer "In13.Cu")
		(net "M_H_CPU0_SB_DQ<3>")
	)
	(arc
		(start 388.506208 -275.378672)
		(mid 388.689716 -275.333178)
		(end 388.871968 -275.383498)
		(width 0.0889)
		(layer "In13.Cu")
		(net "M_H_CPU0_SB_DQ<3>")
	)
	(arc
		(start 390.751822 -275.383498)
		(mid 391.034778 -275.459675)
		(end 391.317734 -275.383498)
		(width 0.0889)
		(layer "In13.Cu")
		(net "M_H_CPU0_SB_DQ<3>")
	)
	(arc
		(start 392.632692 -275.383498)
		(mid 392.91212 -275.459664)
		(end 393.192508 -275.387054)
		(width 0.0889)
		(layer "In13.Cu")
		(net "M_H_CPU0_SB_DQ<3>")
	)
	(arc
		(start 389.811768 -275.383498)
		(mid 390.094724 -275.459675)
		(end 390.37768 -275.383498)
		(width 0.0889)
		(layer "In13.Cu")
		(net "M_H_CPU0_SB_DQ<3>")
	)
	(arc
		(start 392.258042 -275.383498)
		(mid 392.440547 -275.333021)
		(end 392.62431 -275.378672)
		(width 0.0889)
		(layer "In13.Cu")
		(net "M_H_CPU0_SB_DQ<3>")
	)
	(arc
		(start 386.051806 -275.383498)
		(mid 386.334762 -275.459675)
		(end 386.617718 -275.383498)
		(width 0.0889)
		(layer "In13.Cu")
		(net "M_H_CPU0_SB_DQ<3>")
	)
	(arc
		(start 385.677664 -275.383498)
		(mid 385.859915 -275.333148)
		(end 386.043424 -275.378672)
		(width 0.0889)
		(layer "In13.Cu")
		(net "M_H_CPU0_SB_DQ<3>")
	)
	(arc
		(start 386.617718 -275.383498)
		(mid 386.799969 -275.333148)
		(end 386.983478 -275.378672)
		(width 0.0889)
		(layer "In13.Cu")
		(net "M_H_CPU0_SB_DQ<3>")
	)
	(arc
		(start 388.871968 -275.383498)
		(mid 389.154924 -275.459675)
		(end 389.43788 -275.383498)
		(width 0.0889)
		(layer "In13.Cu")
		(net "M_H_CPU0_SB_DQ<3>")
	)
	(arc
		(start 384.171952 -275.383498)
		(mid 384.454908 -275.459675)
		(end 384.737864 -275.383498)
		(width 0.0889)
		(layer "In13.Cu")
		(net "M_H_CPU0_SB_DQ<3>")
	)
	(arc
		(start 385.111752 -275.383498)
		(mid 385.394708 -275.459675)
		(end 385.677664 -275.383498)
		(width 0.0889)
		(layer "In13.Cu")
		(net "M_H_CPU0_SB_DQ<3>")
	)
	(arc
		(start 389.43788 -275.383498)
		(mid 389.624824 -275.333243)
		(end 389.811768 -275.383498)
		(width 0.0889)
		(layer "In13.Cu")
		(net "M_H_CPU0_SB_DQ<3>")
	)
	(arc
		(start 391.326116 -275.378672)
		(mid 391.509624 -275.333178)
		(end 391.691876 -275.383498)
		(width 0.0889)
		(layer "In13.Cu")
		(net "M_H_CPU0_SB_DQ<3>")
	)
	(arc
		(start 387.566154 -275.378672)
		(mid 387.749662 -275.333178)
		(end 387.931914 -275.383498)
		(width 0.0889)
		(layer "In13.Cu")
		(net "M_H_CPU0_SB_DQ<3>")
	)
	(arc
		(start 382.913128 -275.357336)
		(mid 383.07546 -275.334518)
		(end 383.231898 -275.383498)
		(width 0.0889)
		(layer "In13.Cu")
		(net "M_H_CPU0_SB_DQ<3>")
	)
	(arc
		(start 391.70229 -275.389594)
		(mid 391.980976 -275.459814)
		(end 392.258042 -275.383498)
		(width 0.0889)
		(layer "In13.Cu")
		(net "M_H_CPU0_SB_DQ<3>")
	)
	(arc
		(start 387.931914 -275.383498)
		(mid 388.21487 -275.459675)
		(end 388.497826 -275.383498)
		(width 0.0889)
		(layer "In13.Cu")
		(net "M_H_CPU0_SB_DQ<3>")
	)
	(arc
		(start 386.99186 -275.383498)
		(mid 387.274816 -275.459675)
		(end 387.557772 -275.383498)
		(width 0.0889)
		(layer "In13.Cu")
		(net "M_H_CPU0_SB_DQ<3>")
	)
	(arc
		(start 384.737864 -275.383498)
		(mid 384.924808 -275.333243)
		(end 385.111752 -275.383498)
		(width 0.0889)
		(layer "In13.Cu")
		(net "M_H_CPU0_SB_DQ<3>")
	)
	(arc
		(start 390.37768 -275.383498)
		(mid 390.559931 -275.333148)
		(end 390.74344 -275.378672)
		(width 0.0889)
		(layer "In13.Cu")
		(net "M_H_CPU0_SB_DQ<3>")
	)
	(arc
		(start 383.806192 -275.378672)
		(mid 383.9897 -275.333178)
		(end 384.171952 -275.383498)
		(width 0.0889)
		(layer "In13.Cu")
		(net "M_H_CPU0_SB_DQ<3>")
	)
	(segment
		(start 382.577848 -293.260018)
		(end 383.0447 -293.525956)
		(width 0.10668)
		(layer "F.Cu")
		(net "M_H_CPU0_SB_DQ<31>")
	)
	(segment
		(start 391.722356 -293.221156)
		(end 391.691876 -293.203376)
		(width 0.0889)
		(layer "In13.Cu")
		(net "M_H_CPU0_SB_DQ<31>")
	)
	(segment
		(start 417.413186 -318.913002)
		(end 417.413186 -318.6049)
		(width 0.14478)
		(layer "In13.Cu")
		(net "M_H_CPU0_SB_DQ<31>")
	)
	(segment
		(start 386.99186 -293.203376)
		(end 386.983478 -293.19855)
		(width 0.0889)
		(layer "In13.Cu")
		(net "M_H_CPU0_SB_DQ<31>")
	)
	(segment
		(start 406.976834 -317.017654)
		(end 393.055348 -303.096168)
		(width 0.14478)
		(layer "In13.Cu")
		(net "M_H_CPU0_SB_DQ<31>")
	)
	(segment
		(start 417.964366 -318.913002)
		(end 417.819586 -319.057782)
		(width 0.14478)
		(layer "In13.Cu")
		(net "M_H_CPU0_SB_DQ<31>")
	)
	(segment
		(start 419.211506 -318.46012)
		(end 419.066726 -318.6049)
		(width 0.14478)
		(layer "In13.Cu")
		(net "M_H_CPU0_SB_DQ<31>")
	)
	(segment
		(start 417.268406 -318.46012)
		(end 417.006786 -318.46012)
		(width 0.14478)
		(layer "In13.Cu")
		(net "M_H_CPU0_SB_DQ<31>")
	)
	(segment
		(start 393.289282 -296.154348)
		(end 393.289282 -295.955974)
		(width 0.0889)
		(layer "In13.Cu")
		(net "M_H_CPU0_SB_DQ<31>")
	)
	(segment
		(start 416.166046 -318.46012)
		(end 411.40253 -318.46012)
		(width 0.14478)
		(layer "In13.Cu")
		(net "M_H_CPU0_SB_DQ<31>")
	)
	(segment
		(start 416.310826 -318.913002)
		(end 416.310826 -318.6049)
		(width 0.14478)
		(layer "In13.Cu")
		(net "M_H_CPU0_SB_DQ<31>")
	)
	(segment
		(start 411.40253 -318.46012)
		(end 409.588208 -318.099186)
		(width 0.14478)
		(layer "In13.Cu")
		(net "M_H_CPU0_SB_DQ<31>")
	)
	(segment
		(start 417.964366 -318.6049)
		(end 417.964366 -318.913002)
		(width 0.14478)
		(layer "In13.Cu")
		(net "M_H_CPU0_SB_DQ<31>")
	)
	(segment
		(start 382.890776 -293.260526)
		(end 383.0447 -293.525956)
		(width 0.0889)
		(layer "In13.Cu")
		(net "M_H_CPU0_SB_DQ<31>")
	)
	(segment
		(start 393.055348 -303.096168)
		(end 393.055348 -296.388282)
		(width 0.14478)
		(layer "In13.Cu")
		(net "M_H_CPU0_SB_DQ<31>")
	)
	(segment
		(start 416.717226 -319.057782)
		(end 416.455606 -319.057782)
		(width 0.14478)
		(layer "In13.Cu")
		(net "M_H_CPU0_SB_DQ<31>")
	)
	(segment
		(start 419.066726 -318.913002)
		(end 418.921946 -319.057782)
		(width 0.14478)
		(layer "In13.Cu")
		(net "M_H_CPU0_SB_DQ<31>")
	)
	(segment
		(start 416.455606 -319.057782)
		(end 416.310826 -318.913002)
		(width 0.14478)
		(layer "In13.Cu")
		(net "M_H_CPU0_SB_DQ<31>")
	)
	(segment
		(start 393.055348 -296.388282)
		(end 393.289282 -296.154348)
		(width 0.0889)
		(layer "In13.Cu")
		(net "M_H_CPU0_SB_DQ<31>")
	)
	(segment
		(start 386.051806 -293.203376)
		(end 386.043424 -293.19855)
		(width 0.0889)
		(layer "In13.Cu")
		(net "M_H_CPU0_SB_DQ<31>")
	)
	(segment
		(start 417.413186 -318.6049)
		(end 417.268406 -318.46012)
		(width 0.14478)
		(layer "In13.Cu")
		(net "M_H_CPU0_SB_DQ<31>")
	)
	(segment
		(start 391.326116 -293.19855)
		(end 391.317734 -293.203376)
		(width 0.0889)
		(layer "In13.Cu")
		(net "M_H_CPU0_SB_DQ<31>")
	)
	(segment
		(start 419.066726 -318.6049)
		(end 419.066726 -318.913002)
		(width 0.14478)
		(layer "In13.Cu")
		(net "M_H_CPU0_SB_DQ<31>")
	)
	(segment
		(start 418.109146 -318.46012)
		(end 417.964366 -318.6049)
		(width 0.14478)
		(layer "In13.Cu")
		(net "M_H_CPU0_SB_DQ<31>")
	)
	(segment
		(start 387.566154 -293.19855)
		(end 387.557772 -293.203376)
		(width 0.0889)
		(layer "In13.Cu")
		(net "M_H_CPU0_SB_DQ<31>")
	)
	(segment
		(start 417.006786 -318.46012)
		(end 416.862006 -318.6049)
		(width 0.14478)
		(layer "In13.Cu")
		(net "M_H_CPU0_SB_DQ<31>")
	)
	(segment
		(start 418.370766 -318.46012)
		(end 418.109146 -318.46012)
		(width 0.14478)
		(layer "In13.Cu")
		(net "M_H_CPU0_SB_DQ<31>")
	)
	(segment
		(start 419.912038 -318.035178)
		(end 419.487096 -318.46012)
		(width 0.14478)
		(layer "In13.Cu")
		(net "M_H_CPU0_SB_DQ<31>")
	)
	(segment
		(start 416.862006 -318.6049)
		(end 416.862006 -318.913002)
		(width 0.14478)
		(layer "In13.Cu")
		(net "M_H_CPU0_SB_DQ<31>")
	)
	(segment
		(start 392.192256 -294.031162)
		(end 392.12266 -293.990522)
		(width 0.0889)
		(layer "In13.Cu")
		(net "M_H_CPU0_SB_DQ<31>")
	)
	(segment
		(start 390.751822 -293.203376)
		(end 390.74344 -293.19855)
		(width 0.0889)
		(layer "In13.Cu")
		(net "M_H_CPU0_SB_DQ<31>")
	)
	(segment
		(start 393.131294 -295.650412)
		(end 393.062714 -295.610534)
		(width 0.0889)
		(layer "In13.Cu")
		(net "M_H_CPU0_SB_DQ<31>")
	)
	(segment
		(start 416.310826 -318.6049)
		(end 416.166046 -318.46012)
		(width 0.14478)
		(layer "In13.Cu")
		(net "M_H_CPU0_SB_DQ<31>")
	)
	(segment
		(start 392.664442 -294.842438)
		(end 392.59256 -294.800528)
		(width 0.0889)
		(layer "In13.Cu")
		(net "M_H_CPU0_SB_DQ<31>")
	)
	(segment
		(start 418.660326 -319.057782)
		(end 418.515546 -318.913002)
		(width 0.14478)
		(layer "In13.Cu")
		(net "M_H_CPU0_SB_DQ<31>")
	)
	(segment
		(start 419.487096 -318.46012)
		(end 419.211506 -318.46012)
		(width 0.14478)
		(layer "In13.Cu")
		(net "M_H_CPU0_SB_DQ<31>")
	)
	(segment
		(start 418.515546 -318.913002)
		(end 418.515546 -318.6049)
		(width 0.14478)
		(layer "In13.Cu")
		(net "M_H_CPU0_SB_DQ<31>")
	)
	(segment
		(start 417.557966 -319.057782)
		(end 417.413186 -318.913002)
		(width 0.14478)
		(layer "In13.Cu")
		(net "M_H_CPU0_SB_DQ<31>")
	)
	(segment
		(start 388.506208 -293.19855)
		(end 388.497826 -293.203376)
		(width 0.0889)
		(layer "In13.Cu")
		(net "M_H_CPU0_SB_DQ<31>")
	)
	(segment
		(start 417.819586 -319.057782)
		(end 417.557966 -319.057782)
		(width 0.14478)
		(layer "In13.Cu")
		(net "M_H_CPU0_SB_DQ<31>")
	)
	(segment
		(start 409.588208 -318.099186)
		(end 406.976834 -317.017654)
		(width 0.14478)
		(layer "In13.Cu")
		(net "M_H_CPU0_SB_DQ<31>")
	)
	(segment
		(start 383.806192 -293.19855)
		(end 383.79781 -293.203376)
		(width 0.0889)
		(layer "In13.Cu")
		(net "M_H_CPU0_SB_DQ<31>")
	)
	(segment
		(start 418.921946 -319.057782)
		(end 418.660326 -319.057782)
		(width 0.14478)
		(layer "In13.Cu")
		(net "M_H_CPU0_SB_DQ<31>")
	)
	(segment
		(start 418.515546 -318.6049)
		(end 418.370766 -318.46012)
		(width 0.14478)
		(layer "In13.Cu")
		(net "M_H_CPU0_SB_DQ<31>")
	)
	(segment
		(start 382.913128 -293.177214)
		(end 382.890776 -293.260526)
		(width 0.0889)
		(layer "In13.Cu")
		(net "M_H_CPU0_SB_DQ<31>")
	)
	(segment
		(start 416.862006 -318.913002)
		(end 416.717226 -319.057782)
		(width 0.14478)
		(layer "In13.Cu")
		(net "M_H_CPU0_SB_DQ<31>")
	)
	(arc
		(start 391.691876 -293.203376)
		(mid 391.509625 -293.153026)
		(end 391.326116 -293.19855)
		(width 0.0889)
		(layer "In13.Cu")
		(net "M_H_CPU0_SB_DQ<31>")
	)
	(arc
		(start 386.983478 -293.19855)
		(mid 386.79997 -293.153056)
		(end 386.617718 -293.203376)
		(width 0.0889)
		(layer "In13.Cu")
		(net "M_H_CPU0_SB_DQ<31>")
	)
	(arc
		(start 392.349228 -294.335962)
		(mid 392.307679 -294.16454)
		(end 392.192256 -294.031162)
		(width 0.0889)
		(layer "In13.Cu")
		(net "M_H_CPU0_SB_DQ<31>")
	)
	(arc
		(start 393.289282 -295.955974)
		(mid 393.247442 -295.783988)
		(end 393.131294 -295.650412)
		(width 0.0889)
		(layer "In13.Cu")
		(net "M_H_CPU0_SB_DQ<31>")
	)
	(arc
		(start 388.871968 -293.203376)
		(mid 388.689717 -293.153026)
		(end 388.506208 -293.19855)
		(width 0.0889)
		(layer "In13.Cu")
		(net "M_H_CPU0_SB_DQ<31>")
	)
	(arc
		(start 389.43788 -293.203376)
		(mid 389.154924 -293.279553)
		(end 388.871968 -293.203376)
		(width 0.0889)
		(layer "In13.Cu")
		(net "M_H_CPU0_SB_DQ<31>")
	)
	(arc
		(start 387.931914 -293.203376)
		(mid 387.749663 -293.153026)
		(end 387.566154 -293.19855)
		(width 0.0889)
		(layer "In13.Cu")
		(net "M_H_CPU0_SB_DQ<31>")
	)
	(arc
		(start 390.74344 -293.19855)
		(mid 390.559932 -293.153056)
		(end 390.37768 -293.203376)
		(width 0.0889)
		(layer "In13.Cu")
		(net "M_H_CPU0_SB_DQ<31>")
	)
	(arc
		(start 392.12266 -293.990522)
		(mid 391.943847 -293.788172)
		(end 391.879328 -293.525956)
		(width 0.0889)
		(layer "In13.Cu")
		(net "M_H_CPU0_SB_DQ<31>")
	)
	(arc
		(start 385.111752 -293.203376)
		(mid 384.924808 -293.153121)
		(end 384.737864 -293.203376)
		(width 0.0889)
		(layer "In13.Cu")
		(net "M_H_CPU0_SB_DQ<31>")
	)
	(arc
		(start 383.79781 -293.203376)
		(mid 383.514854 -293.279553)
		(end 383.231898 -293.203376)
		(width 0.0889)
		(layer "In13.Cu")
		(net "M_H_CPU0_SB_DQ<31>")
	)
	(arc
		(start 391.317734 -293.203376)
		(mid 391.034778 -293.279553)
		(end 390.751822 -293.203376)
		(width 0.0889)
		(layer "In13.Cu")
		(net "M_H_CPU0_SB_DQ<31>")
	)
	(arc
		(start 391.879328 -293.525956)
		(mid 391.837779 -293.354534)
		(end 391.722356 -293.221156)
		(width 0.0889)
		(layer "In13.Cu")
		(net "M_H_CPU0_SB_DQ<31>")
	)
	(arc
		(start 383.231898 -293.203376)
		(mid 383.07546 -293.154405)
		(end 382.913128 -293.177214)
		(width 0.0889)
		(layer "In13.Cu")
		(net "M_H_CPU0_SB_DQ<31>")
	)
	(arc
		(start 388.497826 -293.203376)
		(mid 388.21487 -293.279553)
		(end 387.931914 -293.203376)
		(width 0.0889)
		(layer "In13.Cu")
		(net "M_H_CPU0_SB_DQ<31>")
	)
	(arc
		(start 392.819382 -295.145968)
		(mid 392.778416 -294.975562)
		(end 392.664442 -294.842438)
		(width 0.0889)
		(layer "In13.Cu")
		(net "M_H_CPU0_SB_DQ<31>")
	)
	(arc
		(start 384.171952 -293.203376)
		(mid 383.989701 -293.153026)
		(end 383.806192 -293.19855)
		(width 0.0889)
		(layer "In13.Cu")
		(net "M_H_CPU0_SB_DQ<31>")
	)
	(arc
		(start 389.811768 -293.203376)
		(mid 389.624824 -293.153121)
		(end 389.43788 -293.203376)
		(width 0.0889)
		(layer "In13.Cu")
		(net "M_H_CPU0_SB_DQ<31>")
	)
	(arc
		(start 384.737864 -293.203376)
		(mid 384.454908 -293.279553)
		(end 384.171952 -293.203376)
		(width 0.0889)
		(layer "In13.Cu")
		(net "M_H_CPU0_SB_DQ<31>")
	)
	(arc
		(start 386.043424 -293.19855)
		(mid 385.859916 -293.153056)
		(end 385.677664 -293.203376)
		(width 0.0889)
		(layer "In13.Cu")
		(net "M_H_CPU0_SB_DQ<31>")
	)
	(arc
		(start 386.617718 -293.203376)
		(mid 386.334762 -293.279553)
		(end 386.051806 -293.203376)
		(width 0.0889)
		(layer "In13.Cu")
		(net "M_H_CPU0_SB_DQ<31>")
	)
	(arc
		(start 390.37768 -293.203376)
		(mid 390.094724 -293.279553)
		(end 389.811768 -293.203376)
		(width 0.0889)
		(layer "In13.Cu")
		(net "M_H_CPU0_SB_DQ<31>")
	)
	(arc
		(start 387.557772 -293.203376)
		(mid 387.274816 -293.279553)
		(end 386.99186 -293.203376)
		(width 0.0889)
		(layer "In13.Cu")
		(net "M_H_CPU0_SB_DQ<31>")
	)
	(arc
		(start 385.677664 -293.203376)
		(mid 385.394708 -293.279553)
		(end 385.111752 -293.203376)
		(width 0.0889)
		(layer "In13.Cu")
		(net "M_H_CPU0_SB_DQ<31>")
	)
	(arc
		(start 392.59256 -294.800528)
		(mid 392.413747 -294.598178)
		(end 392.349228 -294.335962)
		(width 0.0889)
		(layer "In13.Cu")
		(net "M_H_CPU0_SB_DQ<31>")
	)
	(arc
		(start 393.062714 -295.610534)
		(mid 392.883901 -295.408184)
		(end 392.819382 -295.145968)
		(width 0.0889)
		(layer "In13.Cu")
		(net "M_H_CPU0_SB_DQ<31>")
	)
	(segment
		(start 383.988056 -292.450012)
		(end 384.454908 -292.71595)
		(width 0.10668)
		(layer "F.Cu")
		(net "M_H_CPU0_SB_DQ<30>")
	)
	(segment
		(start 397.286988 -306.055522)
		(end 397.286988 -305.826922)
		(width 0.14478)
		(layer "In13.Cu")
		(net "M_H_CPU0_SB_DQ<30>")
	)
	(segment
		(start 398.248886 -306.4256)
		(end 398.248886 -306.197)
		(width 0.14478)
		(layer "In13.Cu")
		(net "M_H_CPU0_SB_DQ<30>")
	)
	(segment
		(start 399.029174 -306.977288)
		(end 398.86763 -306.815744)
		(width 0.14478)
		(layer "In13.Cu")
		(net "M_H_CPU0_SB_DQ<30>")
	)
	(segment
		(start 419.052502 -316.760098)
		(end 418.907722 -316.904878)
		(width 0.14478)
		(layer "In13.Cu")
		(net "M_H_CPU0_SB_DQ<30>")
	)
	(segment
		(start 392.19251 -292.41115)
		(end 392.16203 -292.39337)
		(width 0.0889)
		(layer "In13.Cu")
		(net "M_H_CPU0_SB_DQ<30>")
	)
	(segment
		(start 399.647918 -307.596032)
		(end 399.419318 -307.596032)
		(width 0.14478)
		(layer "In13.Cu")
		(net "M_H_CPU0_SB_DQ<30>")
	)
	(segment
		(start 398.248886 -306.197)
		(end 398.087342 -306.035456)
		(width 0.14478)
		(layer "In13.Cu")
		(net "M_H_CPU0_SB_DQ<30>")
	)
	(segment
		(start 398.847564 -307.616098)
		(end 398.847564 -307.387498)
		(width 0.14478)
		(layer "In13.Cu")
		(net "M_H_CPU0_SB_DQ<30>")
	)
	(segment
		(start 395.726412 -304.266346)
		(end 395.908022 -304.084736)
		(width 0.14478)
		(layer "In13.Cu")
		(net "M_H_CPU0_SB_DQ<30>")
	)
	(segment
		(start 396.68831 -304.865024)
		(end 396.68831 -304.636424)
		(width 0.14478)
		(layer "In13.Cu")
		(net "M_H_CPU0_SB_DQ<30>")
	)
	(segment
		(start 396.116556 -304.65649)
		(end 395.887956 -304.65649)
		(width 0.14478)
		(layer "In13.Cu")
		(net "M_H_CPU0_SB_DQ<30>")
	)
	(segment
		(start 396.5067 -305.046634)
		(end 396.68831 -304.865024)
		(width 0.14478)
		(layer "In13.Cu")
		(net "M_H_CPU0_SB_DQ<30>")
	)
	(segment
		(start 396.668244 -305.436778)
		(end 396.5067 -305.275234)
		(width 0.14478)
		(layer "In13.Cu")
		(net "M_H_CPU0_SB_DQ<30>")
	)
	(segment
		(start 393.964668 -296.358564)
		(end 393.964668 -295.648634)
		(width 0.0889)
		(layer "In13.Cu")
		(net "M_H_CPU0_SB_DQ<30>")
	)
	(segment
		(start 418.501322 -317.051182)
		(end 418.356542 -316.906402)
		(width 0.14478)
		(layer "In13.Cu")
		(net "M_H_CPU0_SB_DQ<30>")
	)
	(segment
		(start 417.660582 -317.051182)
		(end 417.398962 -317.051182)
		(width 0.14478)
		(layer "In13.Cu")
		(net "M_H_CPU0_SB_DQ<30>")
	)
	(segment
		(start 397.307054 -305.255168)
		(end 397.078454 -305.255168)
		(width 0.14478)
		(layer "In13.Cu")
		(net "M_H_CPU0_SB_DQ<30>")
	)
	(segment
		(start 416.151822 -316.906402)
		(end 416.151822 -316.904878)
		(width 0.14478)
		(layer "In13.Cu")
		(net "M_H_CPU0_SB_DQ<30>")
	)
	(segment
		(start 385.216146 -292.388544)
		(end 385.207764 -292.39337)
		(width 0.0889)
		(layer "In13.Cu")
		(net "M_H_CPU0_SB_DQ<30>")
	)
	(segment
		(start 397.468598 -305.416712)
		(end 397.307054 -305.255168)
		(width 0.14478)
		(layer "In13.Cu")
		(net "M_H_CPU0_SB_DQ<30>")
	)
	(segment
		(start 398.86763 -306.815744)
		(end 398.63903 -306.815744)
		(width 0.14478)
		(layer "In13.Cu")
		(net "M_H_CPU0_SB_DQ<30>")
	)
	(segment
		(start 395.887956 -304.65649)
		(end 395.726412 -304.494946)
		(width 0.14478)
		(layer "In13.Cu")
		(net "M_H_CPU0_SB_DQ<30>")
	)
	(segment
		(start 389.341868 -292.39337)
		(end 389.333486 -292.388544)
		(width 0.0889)
		(layer "In13.Cu")
		(net "M_H_CPU0_SB_DQ<30>")
	)
	(segment
		(start 397.448532 -306.217066)
		(end 397.286988 -306.055522)
		(width 0.14478)
		(layer "In13.Cu")
		(net "M_H_CPU0_SB_DQ<30>")
	)
	(segment
		(start 395.726412 -304.494946)
		(end 395.726412 -304.266346)
		(width 0.14478)
		(layer "In13.Cu")
		(net "M_H_CPU0_SB_DQ<30>")
	)
	(segment
		(start 396.298166 -304.47488)
		(end 396.116556 -304.65649)
		(width 0.14478)
		(layer "In13.Cu")
		(net "M_H_CPU0_SB_DQ<30>")
	)
	(segment
		(start 396.68831 -304.636424)
		(end 396.526766 -304.47488)
		(width 0.14478)
		(layer "In13.Cu")
		(net "M_H_CPU0_SB_DQ<30>")
	)
	(segment
		(start 393.964668 -295.648634)
		(end 393.759436 -295.443402)
		(width 0.0889)
		(layer "In13.Cu")
		(net "M_H_CPU0_SB_DQ<30>")
	)
	(segment
		(start 386.1562 -292.388544)
		(end 386.147818 -292.39337)
		(width 0.0889)
		(layer "In13.Cu")
		(net "M_H_CPU0_SB_DQ<30>")
	)
	(segment
		(start 418.356542 -316.906402)
		(end 418.356542 -316.904878)
		(width 0.14478)
		(layer "In13.Cu")
		(net "M_H_CPU0_SB_DQ<30>")
	)
	(segment
		(start 396.5067 -305.275234)
		(end 396.5067 -305.046634)
		(width 0.14478)
		(layer "In13.Cu")
		(net "M_H_CPU0_SB_DQ<30>")
	)
	(segment
		(start 398.067276 -306.83581)
		(end 398.067276 -306.60721)
		(width 0.14478)
		(layer "In13.Cu")
		(net "M_H_CPU0_SB_DQ<30>")
	)
	(segment
		(start 416.151822 -316.904878)
		(end 416.007042 -316.760098)
		(width 0.14478)
		(layer "In13.Cu")
		(net "M_H_CPU0_SB_DQ<30>")
	)
	(segment
		(start 418.762942 -317.051182)
		(end 418.501322 -317.051182)
		(width 0.14478)
		(layer "In13.Cu")
		(net "M_H_CPU0_SB_DQ<30>")
	)
	(segment
		(start 416.007042 -316.760098)
		(end 408.811984 -316.760098)
		(width 0.14478)
		(layer "In13.Cu")
		(net "M_H_CPU0_SB_DQ<30>")
	)
	(segment
		(start 389.916162 -292.388544)
		(end 389.90778 -292.39337)
		(width 0.0889)
		(layer "In13.Cu")
		(net "M_H_CPU0_SB_DQ<30>")
	)
	(segment
		(start 397.078454 -305.255168)
		(end 396.896844 -305.436778)
		(width 0.14478)
		(layer "In13.Cu")
		(net "M_H_CPU0_SB_DQ<30>")
	)
	(segment
		(start 399.009108 -307.777642)
		(end 398.847564 -307.616098)
		(width 0.14478)
		(layer "In13.Cu")
		(net "M_H_CPU0_SB_DQ<30>")
	)
	(segment
		(start 398.847564 -307.387498)
		(end 399.029174 -307.205888)
		(width 0.14478)
		(layer "In13.Cu")
		(net "M_H_CPU0_SB_DQ<30>")
	)
	(segment
		(start 384.641852 -292.39337)
		(end 384.63347 -292.388544)
		(width 0.0889)
		(layer "In13.Cu")
		(net "M_H_CPU0_SB_DQ<30>")
	)
	(segment
		(start 417.254182 -316.906402)
		(end 417.254182 -316.904878)
		(width 0.14478)
		(layer "In13.Cu")
		(net "M_H_CPU0_SB_DQ<30>")
	)
	(segment
		(start 396.526766 -304.47488)
		(end 396.298166 -304.47488)
		(width 0.14478)
		(layer "In13.Cu")
		(net "M_H_CPU0_SB_DQ<30>")
	)
	(segment
		(start 416.296602 -317.051182)
		(end 416.151822 -316.906402)
		(width 0.14478)
		(layer "In13.Cu")
		(net "M_H_CPU0_SB_DQ<30>")
	)
	(segment
		(start 396.896844 -305.436778)
		(end 396.668244 -305.436778)
		(width 0.14478)
		(layer "In13.Cu")
		(net "M_H_CPU0_SB_DQ<30>")
	)
	(segment
		(start 393.60348 -294.841676)
		(end 393.532614 -294.800528)
		(width 0.0889)
		(layer "In13.Cu")
		(net "M_H_CPU0_SB_DQ<30>")
	)
	(segment
		(start 399.029174 -307.205888)
		(end 399.029174 -306.977288)
		(width 0.14478)
		(layer "In13.Cu")
		(net "M_H_CPU0_SB_DQ<30>")
	)
	(segment
		(start 418.211762 -316.760098)
		(end 417.950142 -316.760098)
		(width 0.14478)
		(layer "In13.Cu")
		(net "M_H_CPU0_SB_DQ<30>")
	)
	(segment
		(start 392.66241 -293.221156)
		(end 392.592814 -293.180516)
		(width 0.0889)
		(layer "In13.Cu")
		(net "M_H_CPU0_SB_DQ<30>")
	)
	(segment
		(start 395.908022 -303.856136)
		(end 393.964668 -301.912782)
		(width 0.14478)
		(layer "In13.Cu")
		(net "M_H_CPU0_SB_DQ<30>")
	)
	(segment
		(start 418.907722 -316.906402)
		(end 418.762942 -317.051182)
		(width 0.14478)
		(layer "In13.Cu")
		(net "M_H_CPU0_SB_DQ<30>")
	)
	(segment
		(start 395.908022 -304.084736)
		(end 395.908022 -303.856136)
		(width 0.14478)
		(layer "In13.Cu")
		(net "M_H_CPU0_SB_DQ<30>")
	)
	(segment
		(start 416.558222 -317.051182)
		(end 416.296602 -317.051182)
		(width 0.14478)
		(layer "In13.Cu")
		(net "M_H_CPU0_SB_DQ<30>")
	)
	(segment
		(start 417.805362 -316.904878)
		(end 417.805362 -316.906402)
		(width 0.14478)
		(layer "In13.Cu")
		(net "M_H_CPU0_SB_DQ<30>")
	)
	(segment
		(start 399.237708 -307.777642)
		(end 399.009108 -307.777642)
		(width 0.14478)
		(layer "In13.Cu")
		(net "M_H_CPU0_SB_DQ<30>")
	)
	(segment
		(start 417.950142 -316.760098)
		(end 417.805362 -316.904878)
		(width 0.14478)
		(layer "In13.Cu")
		(net "M_H_CPU0_SB_DQ<30>")
	)
	(segment
		(start 398.087342 -306.035456)
		(end 397.858742 -306.035456)
		(width 0.14478)
		(layer "In13.Cu")
		(net "M_H_CPU0_SB_DQ<30>")
	)
	(segment
		(start 418.907722 -316.904878)
		(end 418.907722 -316.906402)
		(width 0.14478)
		(layer "In13.Cu")
		(net "M_H_CPU0_SB_DQ<30>")
	)
	(segment
		(start 419.912038 -316.335156)
		(end 419.487096 -316.760098)
		(width 0.14478)
		(layer "In13.Cu")
		(net "M_H_CPU0_SB_DQ<30>")
	)
	(segment
		(start 384.30073 -292.45052)
		(end 384.454908 -292.71595)
		(width 0.0889)
		(layer "In13.Cu")
		(net "M_H_CPU0_SB_DQ<30>")
	)
	(segment
		(start 397.286988 -305.826922)
		(end 397.468598 -305.645312)
		(width 0.14478)
		(layer "In13.Cu")
		(net "M_H_CPU0_SB_DQ<30>")
	)
	(segment
		(start 398.22882 -306.997354)
		(end 398.067276 -306.83581)
		(width 0.14478)
		(layer "In13.Cu")
		(net "M_H_CPU0_SB_DQ<30>")
	)
	(segment
		(start 397.677132 -306.217066)
		(end 397.448532 -306.217066)
		(width 0.14478)
		(layer "In13.Cu")
		(net "M_H_CPU0_SB_DQ<30>")
	)
	(segment
		(start 416.703002 -316.906402)
		(end 416.558222 -317.051182)
		(width 0.14478)
		(layer "In13.Cu")
		(net "M_H_CPU0_SB_DQ<30>")
	)
	(segment
		(start 393.13231 -294.031162)
		(end 393.062714 -293.990522)
		(width 0.0889)
		(layer "In13.Cu")
		(net "M_H_CPU0_SB_DQ<30>")
	)
	(segment
		(start 416.847782 -316.760098)
		(end 416.703002 -316.904878)
		(width 0.14478)
		(layer "In13.Cu")
		(net "M_H_CPU0_SB_DQ<30>")
	)
	(segment
		(start 398.067276 -306.60721)
		(end 398.248886 -306.4256)
		(width 0.14478)
		(layer "In13.Cu")
		(net "M_H_CPU0_SB_DQ<30>")
	)
	(segment
		(start 393.964668 -301.912782)
		(end 393.964668 -296.358564)
		(width 0.14478)
		(layer "In13.Cu")
		(net "M_H_CPU0_SB_DQ<30>")
	)
	(segment
		(start 384.323082 -292.367208)
		(end 384.30073 -292.45052)
		(width 0.0889)
		(layer "In13.Cu")
		(net "M_H_CPU0_SB_DQ<30>")
	)
	(segment
		(start 419.487096 -316.760098)
		(end 419.052502 -316.760098)
		(width 0.14478)
		(layer "In13.Cu")
		(net "M_H_CPU0_SB_DQ<30>")
	)
	(segment
		(start 417.805362 -316.906402)
		(end 417.660582 -317.051182)
		(width 0.14478)
		(layer "In13.Cu")
		(net "M_H_CPU0_SB_DQ<30>")
	)
	(segment
		(start 398.63903 -306.815744)
		(end 398.45742 -306.997354)
		(width 0.14478)
		(layer "In13.Cu")
		(net "M_H_CPU0_SB_DQ<30>")
	)
	(segment
		(start 397.858742 -306.035456)
		(end 397.677132 -306.217066)
		(width 0.14478)
		(layer "In13.Cu")
		(net "M_H_CPU0_SB_DQ<30>")
	)
	(segment
		(start 398.45742 -306.997354)
		(end 398.22882 -306.997354)
		(width 0.14478)
		(layer "In13.Cu")
		(net "M_H_CPU0_SB_DQ<30>")
	)
	(segment
		(start 416.703002 -316.904878)
		(end 416.703002 -316.906402)
		(width 0.14478)
		(layer "In13.Cu")
		(net "M_H_CPU0_SB_DQ<30>")
	)
	(segment
		(start 399.419318 -307.596032)
		(end 399.237708 -307.777642)
		(width 0.14478)
		(layer "In13.Cu")
		(net "M_H_CPU0_SB_DQ<30>")
	)
	(segment
		(start 408.811984 -316.760098)
		(end 399.647918 -307.596032)
		(width 0.14478)
		(layer "In13.Cu")
		(net "M_H_CPU0_SB_DQ<30>")
	)
	(segment
		(start 417.254182 -316.904878)
		(end 417.109402 -316.760098)
		(width 0.14478)
		(layer "In13.Cu")
		(net "M_H_CPU0_SB_DQ<30>")
	)
	(segment
		(start 417.398962 -317.051182)
		(end 417.254182 -316.906402)
		(width 0.14478)
		(layer "In13.Cu")
		(net "M_H_CPU0_SB_DQ<30>")
	)
	(segment
		(start 388.401814 -292.39337)
		(end 388.393432 -292.388544)
		(width 0.0889)
		(layer "In13.Cu")
		(net "M_H_CPU0_SB_DQ<30>")
	)
	(segment
		(start 417.109402 -316.760098)
		(end 416.847782 -316.760098)
		(width 0.14478)
		(layer "In13.Cu")
		(net "M_H_CPU0_SB_DQ<30>")
	)
	(segment
		(start 418.356542 -316.904878)
		(end 418.211762 -316.760098)
		(width 0.14478)
		(layer "In13.Cu")
		(net "M_H_CPU0_SB_DQ<30>")
	)
	(segment
		(start 393.759436 -295.443402)
		(end 393.759436 -295.145968)
		(width 0.0889)
		(layer "In13.Cu")
		(net "M_H_CPU0_SB_DQ<30>")
	)
	(segment
		(start 397.468598 -305.645312)
		(end 397.468598 -305.416712)
		(width 0.14478)
		(layer "In13.Cu")
		(net "M_H_CPU0_SB_DQ<30>")
	)
	(arc
		(start 389.90778 -292.39337)
		(mid 389.624824 -292.469547)
		(end 389.341868 -292.39337)
		(width 0.0889)
		(layer "In13.Cu")
		(net "M_H_CPU0_SB_DQ<30>")
	)
	(arc
		(start 384.63347 -292.388544)
		(mid 384.4806 -292.343903)
		(end 384.323082 -292.367208)
		(width 0.0889)
		(layer "In13.Cu")
		(net "M_H_CPU0_SB_DQ<30>")
	)
	(arc
		(start 387.087872 -292.39337)
		(mid 386.804916 -292.469547)
		(end 386.52196 -292.39337)
		(width 0.0889)
		(layer "In13.Cu")
		(net "M_H_CPU0_SB_DQ<30>")
	)
	(arc
		(start 388.967726 -292.39337)
		(mid 388.68477 -292.469547)
		(end 388.401814 -292.39337)
		(width 0.0889)
		(layer "In13.Cu")
		(net "M_H_CPU0_SB_DQ<30>")
	)
	(arc
		(start 388.393432 -292.388544)
		(mid 388.209924 -292.34305)
		(end 388.027672 -292.39337)
		(width 0.0889)
		(layer "In13.Cu")
		(net "M_H_CPU0_SB_DQ<30>")
	)
	(arc
		(start 389.333486 -292.388544)
		(mid 389.149978 -292.34305)
		(end 388.967726 -292.39337)
		(width 0.0889)
		(layer "In13.Cu")
		(net "M_H_CPU0_SB_DQ<30>")
	)
	(arc
		(start 386.52196 -292.39337)
		(mid 386.339709 -292.34302)
		(end 386.1562 -292.388544)
		(width 0.0889)
		(layer "In13.Cu")
		(net "M_H_CPU0_SB_DQ<30>")
	)
	(arc
		(start 392.349482 -292.71595)
		(mid 392.307933 -292.544528)
		(end 392.19251 -292.41115)
		(width 0.0889)
		(layer "In13.Cu")
		(net "M_H_CPU0_SB_DQ<30>")
	)
	(arc
		(start 385.207764 -292.39337)
		(mid 384.924808 -292.469547)
		(end 384.641852 -292.39337)
		(width 0.0889)
		(layer "In13.Cu")
		(net "M_H_CPU0_SB_DQ<30>")
	)
	(arc
		(start 390.847834 -292.39337)
		(mid 390.564878 -292.469547)
		(end 390.281922 -292.39337)
		(width 0.0889)
		(layer "In13.Cu")
		(net "M_H_CPU0_SB_DQ<30>")
	)
	(arc
		(start 393.532614 -294.800528)
		(mid 393.353801 -294.598178)
		(end 393.289282 -294.335962)
		(width 0.0889)
		(layer "In13.Cu")
		(net "M_H_CPU0_SB_DQ<30>")
	)
	(arc
		(start 385.581906 -292.39337)
		(mid 385.399655 -292.34302)
		(end 385.216146 -292.388544)
		(width 0.0889)
		(layer "In13.Cu")
		(net "M_H_CPU0_SB_DQ<30>")
	)
	(arc
		(start 391.221722 -292.39337)
		(mid 391.034778 -292.343115)
		(end 390.847834 -292.39337)
		(width 0.0889)
		(layer "In13.Cu")
		(net "M_H_CPU0_SB_DQ<30>")
	)
	(arc
		(start 390.281922 -292.39337)
		(mid 390.099671 -292.34302)
		(end 389.916162 -292.388544)
		(width 0.0889)
		(layer "In13.Cu")
		(net "M_H_CPU0_SB_DQ<30>")
	)
	(arc
		(start 393.759436 -295.145968)
		(mid 393.718181 -294.974997)
		(end 393.60348 -294.841676)
		(width 0.0889)
		(layer "In13.Cu")
		(net "M_H_CPU0_SB_DQ<30>")
	)
	(arc
		(start 392.592814 -293.180516)
		(mid 392.414001 -292.978166)
		(end 392.349482 -292.71595)
		(width 0.0889)
		(layer "In13.Cu")
		(net "M_H_CPU0_SB_DQ<30>")
	)
	(arc
		(start 393.289282 -294.335962)
		(mid 393.247733 -294.16454)
		(end 393.13231 -294.031162)
		(width 0.0889)
		(layer "In13.Cu")
		(net "M_H_CPU0_SB_DQ<30>")
	)
	(arc
		(start 387.46176 -292.39337)
		(mid 387.274816 -292.343115)
		(end 387.087872 -292.39337)
		(width 0.0889)
		(layer "In13.Cu")
		(net "M_H_CPU0_SB_DQ<30>")
	)
	(arc
		(start 386.147818 -292.39337)
		(mid 385.864862 -292.469547)
		(end 385.581906 -292.39337)
		(width 0.0889)
		(layer "In13.Cu")
		(net "M_H_CPU0_SB_DQ<30>")
	)
	(arc
		(start 391.787634 -292.39337)
		(mid 391.504678 -292.469547)
		(end 391.221722 -292.39337)
		(width 0.0889)
		(layer "In13.Cu")
		(net "M_H_CPU0_SB_DQ<30>")
	)
	(arc
		(start 392.819382 -293.525956)
		(mid 392.777833 -293.354534)
		(end 392.66241 -293.221156)
		(width 0.0889)
		(layer "In13.Cu")
		(net "M_H_CPU0_SB_DQ<30>")
	)
	(arc
		(start 388.027672 -292.39337)
		(mid 387.744716 -292.469547)
		(end 387.46176 -292.39337)
		(width 0.0889)
		(layer "In13.Cu")
		(net "M_H_CPU0_SB_DQ<30>")
	)
	(arc
		(start 393.062714 -293.990522)
		(mid 392.883901 -293.788172)
		(end 392.819382 -293.525956)
		(width 0.0889)
		(layer "In13.Cu")
		(net "M_H_CPU0_SB_DQ<30>")
	)
	(arc
		(start 392.16203 -292.39337)
		(mid 391.974832 -292.342988)
		(end 391.787634 -292.39337)
		(width 0.0889)
		(layer "In13.Cu")
		(net "M_H_CPU0_SB_DQ<30>")
	)
	(segment
		(start 383.988056 -274.630134)
		(end 384.454908 -274.896072)
		(width 0.10668)
		(layer "F.Cu")
		(net "M_H_CPU0_SB_DQ<2>")
	)
	(segment
		(start 388.401814 -274.573492)
		(end 388.393432 -274.568666)
		(width 0.0889)
		(layer "In13.Cu")
		(net "M_H_CPU0_SB_DQ<2>")
	)
	(segment
		(start 395.489176 -273.39417)
		(end 395.237716 -273.64563)
		(width 0.0889)
		(layer "In13.Cu")
		(net "M_H_CPU0_SB_DQ<2>")
	)
	(segment
		(start 413.205676 -282.538932)
		(end 413.205676 -282.615386)
		(width 0.14478)
		(layer "In13.Cu")
		(net "M_H_CPU0_SB_DQ<2>")
	)
	(segment
		(start 417.610798 -281.765248)
		(end 417.610798 -281.680666)
		(width 0.14478)
		(layer "In13.Cu")
		(net "M_H_CPU0_SB_DQ<2>")
	)
	(segment
		(start 417.059618 -281.765248)
		(end 416.914838 -281.910028)
		(width 0.14478)
		(layer "In13.Cu")
		(net "M_H_CPU0_SB_DQ<2>")
	)
	(segment
		(start 410.118052 -280.337514)
		(end 409.913328 -280.337514)
		(width 0.14478)
		(layer "In13.Cu")
		(net "M_H_CPU0_SB_DQ<2>")
	)
	(segment
		(start 410.844492 -281.745944)
		(end 411.083252 -281.507184)
		(width 0.14478)
		(layer "In13.Cu")
		(net "M_H_CPU0_SB_DQ<2>")
	)
	(segment
		(start 409.674568 -280.576274)
		(end 409.470352 -280.576528)
		(width 0.14478)
		(layer "In13.Cu")
		(net "M_H_CPU0_SB_DQ<2>")
	)
	(segment
		(start 395.237716 -273.64563)
		(end 394.696188 -273.64563)
		(width 0.0889)
		(layer "In13.Cu")
		(net "M_H_CPU0_SB_DQ<2>")
	)
	(segment
		(start 384.641852 -274.573492)
		(end 384.63347 -274.568666)
		(width 0.0889)
		(layer "In13.Cu")
		(net "M_H_CPU0_SB_DQ<2>")
	)
	(segment
		(start 408.690572 -279.796748)
		(end 408.505152 -279.611328)
		(width 0.14478)
		(layer "In13.Cu")
		(net "M_H_CPU0_SB_DQ<2>")
	)
	(segment
		(start 392.161014 -274.573746)
		(end 392.140948 -274.562316)
		(width 0.0889)
		(layer "In13.Cu")
		(net "M_H_CPU0_SB_DQ<2>")
	)
	(segment
		(start 412.799276 -282.760166)
		(end 412.654496 -282.615386)
		(width 0.14478)
		(layer "In13.Cu")
		(net "M_H_CPU0_SB_DQ<2>")
	)
	(segment
		(start 414.940242 -281.910028)
		(end 414.090104 -282.760166)
		(width 0.14478)
		(layer "In13.Cu")
		(net "M_H_CPU0_SB_DQ<2>")
	)
	(segment
		(start 411.083252 -281.507184)
		(end 411.082998 -281.30246)
		(width 0.14478)
		(layer "In13.Cu")
		(net "M_H_CPU0_SB_DQ<2>")
	)
	(segment
		(start 407.910792 -279.016968)
		(end 402.287994 -273.39417)
		(width 0.14478)
		(layer "In13.Cu")
		(net "M_H_CPU0_SB_DQ<2>")
	)
	(segment
		(start 412.248096 -282.394152)
		(end 412.103316 -282.538932)
		(width 0.14478)
		(layer "In13.Cu")
		(net "M_H_CPU0_SB_DQ<2>")
	)
	(segment
		(start 416.914838 -281.910028)
		(end 416.653218 -281.910028)
		(width 0.14478)
		(layer "In13.Cu")
		(net "M_H_CPU0_SB_DQ<2>")
	)
	(segment
		(start 417.610798 -281.680666)
		(end 417.466018 -281.535886)
		(width 0.14478)
		(layer "In13.Cu")
		(net "M_H_CPU0_SB_DQ<2>")
	)
	(segment
		(start 414.090104 -282.760166)
		(end 413.901636 -282.760166)
		(width 0.14478)
		(layer "In13.Cu")
		(net "M_H_CPU0_SB_DQ<2>")
	)
	(segment
		(start 413.756856 -282.538932)
		(end 413.612076 -282.394152)
		(width 0.14478)
		(layer "In13.Cu")
		(net "M_H_CPU0_SB_DQ<2>")
	)
	(segment
		(start 418.122608 -281.910028)
		(end 417.755578 -281.910028)
		(width 0.14478)
		(layer "In13.Cu")
		(net "M_H_CPU0_SB_DQ<2>")
	)
	(segment
		(start 408.505152 -279.611328)
		(end 408.505152 -279.406604)
		(width 0.14478)
		(layer "In13.Cu")
		(net "M_H_CPU0_SB_DQ<2>")
	)
	(segment
		(start 413.205676 -282.615386)
		(end 413.060896 -282.760166)
		(width 0.14478)
		(layer "In13.Cu")
		(net "M_H_CPU0_SB_DQ<2>")
	)
	(segment
		(start 394.696188 -273.64563)
		(end 393.758928 -274.58289)
		(width 0.0889)
		(layer "In13.Cu")
		(net "M_H_CPU0_SB_DQ<2>")
	)
	(segment
		(start 418.972746 -282.760166)
		(end 418.122608 -281.910028)
		(width 0.14478)
		(layer "In13.Cu")
		(net "M_H_CPU0_SB_DQ<2>")
	)
	(segment
		(start 419.912038 -282.33497)
		(end 419.912038 -282.365196)
		(width 0.14478)
		(layer "In13.Cu")
		(net "M_H_CPU0_SB_DQ<2>")
	)
	(segment
		(start 412.509716 -282.394152)
		(end 412.248096 -282.394152)
		(width 0.14478)
		(layer "In13.Cu")
		(net "M_H_CPU0_SB_DQ<2>")
	)
	(segment
		(start 410.064712 -281.170888)
		(end 410.064712 -280.966164)
		(width 0.14478)
		(layer "In13.Cu")
		(net "M_H_CPU0_SB_DQ<2>")
	)
	(segment
		(start 393.580112 -274.6502)
		(end 393.384786 -274.6502)
		(width 0.0889)
		(layer "In13.Cu")
		(net "M_H_CPU0_SB_DQ<2>")
	)
	(segment
		(start 416.508438 -281.765248)
		(end 416.508438 -281.680666)
		(width 0.14478)
		(layer "In13.Cu")
		(net "M_H_CPU0_SB_DQ<2>")
	)
	(segment
		(start 409.338272 -279.557734)
		(end 409.133548 -279.557734)
		(width 0.14478)
		(layer "In13.Cu")
		(net "M_H_CPU0_SB_DQ<2>")
	)
	(segment
		(start 413.756856 -282.615386)
		(end 413.756856 -282.538932)
		(width 0.14478)
		(layer "In13.Cu")
		(net "M_H_CPU0_SB_DQ<2>")
	)
	(segment
		(start 409.284932 -280.391108)
		(end 409.284932 -280.186384)
		(width 0.14478)
		(layer "In13.Cu")
		(net "M_H_CPU0_SB_DQ<2>")
	)
	(segment
		(start 409.913328 -280.337514)
		(end 409.674568 -280.576274)
		(width 0.14478)
		(layer "In13.Cu")
		(net "M_H_CPU0_SB_DQ<2>")
	)
	(segment
		(start 413.901636 -282.760166)
		(end 413.756856 -282.615386)
		(width 0.14478)
		(layer "In13.Cu")
		(net "M_H_CPU0_SB_DQ<2>")
	)
	(segment
		(start 408.894788 -279.796494)
		(end 408.690572 -279.796748)
		(width 0.14478)
		(layer "In13.Cu")
		(net "M_H_CPU0_SB_DQ<2>")
	)
	(segment
		(start 408.353768 -278.777954)
		(end 408.115008 -279.016714)
		(width 0.14478)
		(layer "In13.Cu")
		(net "M_H_CPU0_SB_DQ<2>")
	)
	(segment
		(start 409.133548 -279.557734)
		(end 408.894788 -279.796494)
		(width 0.14478)
		(layer "In13.Cu")
		(net "M_H_CPU0_SB_DQ<2>")
	)
	(segment
		(start 419.912038 -282.365196)
		(end 419.517068 -282.760166)
		(width 0.14478)
		(layer "In13.Cu")
		(net "M_H_CPU0_SB_DQ<2>")
	)
	(segment
		(start 416.363658 -281.535886)
		(end 416.102038 -281.535886)
		(width 0.14478)
		(layer "In13.Cu")
		(net "M_H_CPU0_SB_DQ<2>")
	)
	(segment
		(start 416.102038 -281.535886)
		(end 415.957258 -281.680666)
		(width 0.14478)
		(layer "In13.Cu")
		(net "M_H_CPU0_SB_DQ<2>")
	)
	(segment
		(start 384.323082 -274.54733)
		(end 384.30073 -274.630642)
		(width 0.0889)
		(layer "In13.Cu")
		(net "M_H_CPU0_SB_DQ<2>")
	)
	(segment
		(start 413.350456 -282.394152)
		(end 413.205676 -282.538932)
		(width 0.14478)
		(layer "In13.Cu")
		(net "M_H_CPU0_SB_DQ<2>")
	)
	(segment
		(start 417.466018 -281.535886)
		(end 417.204398 -281.535886)
		(width 0.14478)
		(layer "In13.Cu")
		(net "M_H_CPU0_SB_DQ<2>")
	)
	(segment
		(start 409.470352 -280.576528)
		(end 409.284932 -280.391108)
		(width 0.14478)
		(layer "In13.Cu")
		(net "M_H_CPU0_SB_DQ<2>")
	)
	(segment
		(start 410.303472 -280.727404)
		(end 410.303218 -280.52268)
		(width 0.14478)
		(layer "In13.Cu")
		(net "M_H_CPU0_SB_DQ<2>")
	)
	(segment
		(start 417.059618 -281.680666)
		(end 417.059618 -281.765248)
		(width 0.14478)
		(layer "In13.Cu")
		(net "M_H_CPU0_SB_DQ<2>")
	)
	(segment
		(start 417.204398 -281.535886)
		(end 417.059618 -281.680666)
		(width 0.14478)
		(layer "In13.Cu")
		(net "M_H_CPU0_SB_DQ<2>")
	)
	(segment
		(start 410.844492 -281.950668)
		(end 410.844492 -281.745944)
		(width 0.14478)
		(layer "In13.Cu")
		(net "M_H_CPU0_SB_DQ<2>")
	)
	(segment
		(start 410.454348 -281.356054)
		(end 410.250132 -281.356308)
		(width 0.14478)
		(layer "In13.Cu")
		(net "M_H_CPU0_SB_DQ<2>")
	)
	(segment
		(start 389.341868 -274.573492)
		(end 389.333486 -274.568666)
		(width 0.0889)
		(layer "In13.Cu")
		(net "M_H_CPU0_SB_DQ<2>")
	)
	(segment
		(start 386.1562 -274.568666)
		(end 386.147818 -274.573492)
		(width 0.0889)
		(layer "In13.Cu")
		(net "M_H_CPU0_SB_DQ<2>")
	)
	(segment
		(start 402.287994 -273.39417)
		(end 395.988286 -273.39417)
		(width 0.14478)
		(layer "In13.Cu")
		(net "M_H_CPU0_SB_DQ<2>")
	)
	(segment
		(start 412.103316 -282.615386)
		(end 411.958536 -282.760166)
		(width 0.14478)
		(layer "In13.Cu")
		(net "M_H_CPU0_SB_DQ<2>")
	)
	(segment
		(start 413.612076 -282.394152)
		(end 413.350456 -282.394152)
		(width 0.14478)
		(layer "In13.Cu")
		(net "M_H_CPU0_SB_DQ<2>")
	)
	(segment
		(start 410.897832 -281.117294)
		(end 410.693108 -281.117294)
		(width 0.14478)
		(layer "In13.Cu")
		(net "M_H_CPU0_SB_DQ<2>")
	)
	(segment
		(start 411.65399 -282.760166)
		(end 410.844492 -281.950668)
		(width 0.14478)
		(layer "In13.Cu")
		(net "M_H_CPU0_SB_DQ<2>")
	)
	(segment
		(start 395.988286 -273.39417)
		(end 395.489176 -273.39417)
		(width 0.0889)
		(layer "In13.Cu")
		(net "M_H_CPU0_SB_DQ<2>")
	)
	(segment
		(start 415.957258 -281.765248)
		(end 415.812478 -281.910028)
		(width 0.14478)
		(layer "In13.Cu")
		(net "M_H_CPU0_SB_DQ<2>")
	)
	(segment
		(start 392.744198 -274.56257)
		(end 392.725402 -274.573492)
		(width 0.0889)
		(layer "In13.Cu")
		(net "M_H_CPU0_SB_DQ<2>")
	)
	(segment
		(start 409.523438 -279.7429)
		(end 409.338272 -279.557734)
		(width 0.14478)
		(layer "In13.Cu")
		(net "M_H_CPU0_SB_DQ<2>")
	)
	(segment
		(start 389.916162 -274.568666)
		(end 389.90778 -274.573492)
		(width 0.0889)
		(layer "In13.Cu")
		(net "M_H_CPU0_SB_DQ<2>")
	)
	(segment
		(start 393.758928 -274.58289)
		(end 393.580112 -274.6502)
		(width 0.0889)
		(layer "In13.Cu")
		(net "M_H_CPU0_SB_DQ<2>")
	)
	(segment
		(start 412.654496 -282.615386)
		(end 412.654496 -282.538932)
		(width 0.14478)
		(layer "In13.Cu")
		(net "M_H_CPU0_SB_DQ<2>")
	)
	(segment
		(start 416.653218 -281.910028)
		(end 416.508438 -281.765248)
		(width 0.14478)
		(layer "In13.Cu")
		(net "M_H_CPU0_SB_DQ<2>")
	)
	(segment
		(start 408.558492 -278.777954)
		(end 408.353768 -278.777954)
		(width 0.14478)
		(layer "In13.Cu")
		(net "M_H_CPU0_SB_DQ<2>")
	)
	(segment
		(start 410.693108 -281.117294)
		(end 410.454348 -281.356054)
		(width 0.14478)
		(layer "In13.Cu")
		(net "M_H_CPU0_SB_DQ<2>")
	)
	(segment
		(start 408.505152 -279.406604)
		(end 408.743912 -279.167844)
		(width 0.14478)
		(layer "In13.Cu")
		(net "M_H_CPU0_SB_DQ<2>")
	)
	(segment
		(start 408.743658 -278.96312)
		(end 408.558492 -278.777954)
		(width 0.14478)
		(layer "In13.Cu")
		(net "M_H_CPU0_SB_DQ<2>")
	)
	(segment
		(start 415.957258 -281.680666)
		(end 415.957258 -281.765248)
		(width 0.14478)
		(layer "In13.Cu")
		(net "M_H_CPU0_SB_DQ<2>")
	)
	(segment
		(start 413.060896 -282.760166)
		(end 412.799276 -282.760166)
		(width 0.14478)
		(layer "In13.Cu")
		(net "M_H_CPU0_SB_DQ<2>")
	)
	(segment
		(start 409.523692 -279.947624)
		(end 409.523438 -279.7429)
		(width 0.14478)
		(layer "In13.Cu")
		(net "M_H_CPU0_SB_DQ<2>")
	)
	(segment
		(start 408.743912 -279.167844)
		(end 408.743658 -278.96312)
		(width 0.14478)
		(layer "In13.Cu")
		(net "M_H_CPU0_SB_DQ<2>")
	)
	(segment
		(start 409.284932 -280.186384)
		(end 409.523692 -279.947624)
		(width 0.14478)
		(layer "In13.Cu")
		(net "M_H_CPU0_SB_DQ<2>")
	)
	(segment
		(start 384.30073 -274.630642)
		(end 384.454908 -274.896072)
		(width 0.0889)
		(layer "In13.Cu")
		(net "M_H_CPU0_SB_DQ<2>")
	)
	(segment
		(start 410.250132 -281.356308)
		(end 410.064712 -281.170888)
		(width 0.14478)
		(layer "In13.Cu")
		(net "M_H_CPU0_SB_DQ<2>")
	)
	(segment
		(start 415.812478 -281.910028)
		(end 414.940242 -281.910028)
		(width 0.14478)
		(layer "In13.Cu")
		(net "M_H_CPU0_SB_DQ<2>")
	)
	(segment
		(start 410.064712 -280.966164)
		(end 410.303472 -280.727404)
		(width 0.14478)
		(layer "In13.Cu")
		(net "M_H_CPU0_SB_DQ<2>")
	)
	(segment
		(start 419.517068 -282.760166)
		(end 418.972746 -282.760166)
		(width 0.14478)
		(layer "In13.Cu")
		(net "M_H_CPU0_SB_DQ<2>")
	)
	(segment
		(start 416.508438 -281.680666)
		(end 416.363658 -281.535886)
		(width 0.14478)
		(layer "In13.Cu")
		(net "M_H_CPU0_SB_DQ<2>")
	)
	(segment
		(start 412.103316 -282.538932)
		(end 412.103316 -282.615386)
		(width 0.14478)
		(layer "In13.Cu")
		(net "M_H_CPU0_SB_DQ<2>")
	)
	(segment
		(start 408.115008 -279.016714)
		(end 407.910792 -279.016968)
		(width 0.14478)
		(layer "In13.Cu")
		(net "M_H_CPU0_SB_DQ<2>")
	)
	(segment
		(start 417.755578 -281.910028)
		(end 417.610798 -281.765248)
		(width 0.14478)
		(layer "In13.Cu")
		(net "M_H_CPU0_SB_DQ<2>")
	)
	(segment
		(start 410.303218 -280.52268)
		(end 410.118052 -280.337514)
		(width 0.14478)
		(layer "In13.Cu")
		(net "M_H_CPU0_SB_DQ<2>")
	)
	(segment
		(start 392.182604 -274.586192)
		(end 392.161014 -274.573746)
		(width 0.0889)
		(layer "In13.Cu")
		(net "M_H_CPU0_SB_DQ<2>")
	)
	(segment
		(start 411.958536 -282.760166)
		(end 411.65399 -282.760166)
		(width 0.14478)
		(layer "In13.Cu")
		(net "M_H_CPU0_SB_DQ<2>")
	)
	(segment
		(start 412.654496 -282.538932)
		(end 412.509716 -282.394152)
		(width 0.14478)
		(layer "In13.Cu")
		(net "M_H_CPU0_SB_DQ<2>")
	)
	(segment
		(start 385.216146 -274.568666)
		(end 385.207764 -274.573492)
		(width 0.0889)
		(layer "In13.Cu")
		(net "M_H_CPU0_SB_DQ<2>")
	)
	(segment
		(start 411.082998 -281.30246)
		(end 410.897832 -281.117294)
		(width 0.14478)
		(layer "In13.Cu")
		(net "M_H_CPU0_SB_DQ<2>")
	)
	(arc
		(start 391.787634 -274.573492)
		(mid 391.504678 -274.649669)
		(end 391.221722 -274.573492)
		(width 0.0889)
		(layer "In13.Cu")
		(net "M_H_CPU0_SB_DQ<2>")
	)
	(arc
		(start 385.581906 -274.573492)
		(mid 385.399655 -274.523142)
		(end 385.216146 -274.568666)
		(width 0.0889)
		(layer "In13.Cu")
		(net "M_H_CPU0_SB_DQ<2>")
	)
	(arc
		(start 386.52196 -274.573492)
		(mid 386.339709 -274.523142)
		(end 386.1562 -274.568666)
		(width 0.0889)
		(layer "In13.Cu")
		(net "M_H_CPU0_SB_DQ<2>")
	)
	(arc
		(start 392.140948 -274.562316)
		(mid 391.96287 -274.523332)
		(end 391.787634 -274.573492)
		(width 0.0889)
		(layer "In13.Cu")
		(net "M_H_CPU0_SB_DQ<2>")
	)
	(arc
		(start 388.967726 -274.573492)
		(mid 388.68477 -274.649669)
		(end 388.401814 -274.573492)
		(width 0.0889)
		(layer "In13.Cu")
		(net "M_H_CPU0_SB_DQ<2>")
	)
	(arc
		(start 385.207764 -274.573492)
		(mid 384.924808 -274.649669)
		(end 384.641852 -274.573492)
		(width 0.0889)
		(layer "In13.Cu")
		(net "M_H_CPU0_SB_DQ<2>")
	)
	(arc
		(start 389.333486 -274.568666)
		(mid 389.149978 -274.523172)
		(end 388.967726 -274.573492)
		(width 0.0889)
		(layer "In13.Cu")
		(net "M_H_CPU0_SB_DQ<2>")
	)
	(arc
		(start 388.027672 -274.573492)
		(mid 387.744716 -274.649669)
		(end 387.46176 -274.573492)
		(width 0.0889)
		(layer "In13.Cu")
		(net "M_H_CPU0_SB_DQ<2>")
	)
	(arc
		(start 393.10056 -274.573492)
		(mid 392.923769 -274.522773)
		(end 392.744198 -274.56257)
		(width 0.0889)
		(layer "In13.Cu")
		(net "M_H_CPU0_SB_DQ<2>")
	)
	(arc
		(start 386.147818 -274.573492)
		(mid 385.864862 -274.649669)
		(end 385.581906 -274.573492)
		(width 0.0889)
		(layer "In13.Cu")
		(net "M_H_CPU0_SB_DQ<2>")
	)
	(arc
		(start 387.46176 -274.573492)
		(mid 387.274816 -274.523237)
		(end 387.087872 -274.573492)
		(width 0.0889)
		(layer "In13.Cu")
		(net "M_H_CPU0_SB_DQ<2>")
	)
	(arc
		(start 384.63347 -274.568666)
		(mid 384.4806 -274.524025)
		(end 384.323082 -274.54733)
		(width 0.0889)
		(layer "In13.Cu")
		(net "M_H_CPU0_SB_DQ<2>")
	)
	(arc
		(start 392.725402 -274.573492)
		(mid 392.455633 -274.649515)
		(end 392.182604 -274.586192)
		(width 0.0889)
		(layer "In13.Cu")
		(net "M_H_CPU0_SB_DQ<2>")
	)
	(arc
		(start 389.90778 -274.573492)
		(mid 389.624824 -274.649669)
		(end 389.341868 -274.573492)
		(width 0.0889)
		(layer "In13.Cu")
		(net "M_H_CPU0_SB_DQ<2>")
	)
	(arc
		(start 388.393432 -274.568666)
		(mid 388.209924 -274.523172)
		(end 388.027672 -274.573492)
		(width 0.0889)
		(layer "In13.Cu")
		(net "M_H_CPU0_SB_DQ<2>")
	)
	(arc
		(start 387.087872 -274.573492)
		(mid 386.804916 -274.649669)
		(end 386.52196 -274.573492)
		(width 0.0889)
		(layer "In13.Cu")
		(net "M_H_CPU0_SB_DQ<2>")
	)
	(arc
		(start 393.384786 -274.6502)
		(mid 393.237577 -274.630723)
		(end 393.10056 -274.573492)
		(width 0.0889)
		(layer "In13.Cu")
		(net "M_H_CPU0_SB_DQ<2>")
	)
	(arc
		(start 390.847834 -274.573492)
		(mid 390.564878 -274.649669)
		(end 390.281922 -274.573492)
		(width 0.0889)
		(layer "In13.Cu")
		(net "M_H_CPU0_SB_DQ<2>")
	)
	(arc
		(start 391.221722 -274.573492)
		(mid 391.034778 -274.523237)
		(end 390.847834 -274.573492)
		(width 0.0889)
		(layer "In13.Cu")
		(net "M_H_CPU0_SB_DQ<2>")
	)
	(arc
		(start 390.281922 -274.573492)
		(mid 390.099671 -274.523142)
		(end 389.916162 -274.568666)
		(width 0.0889)
		(layer "In13.Cu")
		(net "M_H_CPU0_SB_DQ<2>")
	)
	(segment
		(start 382.107948 -292.450012)
		(end 382.5748 -292.71595)
		(width 0.10668)
		(layer "F.Cu")
		(net "M_H_CPU0_SB_DQ<29>")
	)
	(segment
		(start 392.696954 -294.640762)
		(end 392.76655 -294.681402)
		(width 0.0889)
		(layer "In13.Cu")
		(net "M_H_CPU0_SB_DQ<29>")
	)
	(segment
		(start 382.728724 -292.98138)
		(end 382.824736 -293.00678)
		(width 0.0889)
		(layer "In13.Cu")
		(net "M_H_CPU0_SB_DQ<29>")
	)
	(segment
		(start 398.822418 -308.227222)
		(end 399.642838 -308.227222)
		(width 0.14478)
		(layer "In13.Cu")
		(net "M_H_CPU0_SB_DQ<29>")
	)
	(segment
		(start 393.11961 -295.399714)
		(end 393.326112 -295.550336)
		(width 0.0889)
		(layer "In13.Cu")
		(net "M_H_CPU0_SB_DQ<29>")
	)
	(segment
		(start 393.510008 -302.914812)
		(end 398.822418 -308.227222)
		(width 0.14478)
		(layer "In13.Cu")
		(net "M_H_CPU0_SB_DQ<29>")
	)
	(segment
		(start 393.433046 -295.681908)
		(end 393.510008 -295.85285)
		(width 0.0889)
		(layer "In13.Cu")
		(net "M_H_CPU0_SB_DQ<29>")
	)
	(segment
		(start 392.227054 -293.830756)
		(end 392.29665 -293.871396)
		(width 0.0889)
		(layer "In13.Cu")
		(net "M_H_CPU0_SB_DQ<29>")
	)
	(segment
		(start 408.556968 -317.141098)
		(end 408.632406 -317.213488)
		(width 0.14478)
		(layer "In13.Cu")
		(net "M_H_CPU0_SB_DQ<29>")
	)
	(segment
		(start 391.787634 -293.03853)
		(end 391.82675 -293.06139)
		(width 0.0889)
		(layer "In13.Cu")
		(net "M_H_CPU0_SB_DQ<29>")
	)
	(segment
		(start 408.632406 -317.213488)
		(end 409.59024 -317.610236)
		(width 0.14478)
		(layer "In13.Cu")
		(net "M_H_CPU0_SB_DQ<29>")
	)
	(segment
		(start 386.147818 -293.03853)
		(end 386.1562 -293.043356)
		(width 0.0889)
		(layer "In13.Cu")
		(net "M_H_CPU0_SB_DQ<29>")
	)
	(segment
		(start 384.63347 -293.043356)
		(end 384.641852 -293.03853)
		(width 0.0889)
		(layer "In13.Cu")
		(net "M_H_CPU0_SB_DQ<29>")
	)
	(segment
		(start 383.693416 -293.043356)
		(end 383.701798 -293.03853)
		(width 0.0889)
		(layer "In13.Cu")
		(net "M_H_CPU0_SB_DQ<29>")
	)
	(segment
		(start 382.5748 -292.71595)
		(end 382.728724 -292.98138)
		(width 0.0889)
		(layer "In13.Cu")
		(net "M_H_CPU0_SB_DQ<29>")
	)
	(segment
		(start 385.207764 -293.03853)
		(end 385.216146 -293.043356)
		(width 0.0889)
		(layer "In13.Cu")
		(net "M_H_CPU0_SB_DQ<29>")
	)
	(segment
		(start 388.393432 -293.043356)
		(end 388.401814 -293.03853)
		(width 0.0889)
		(layer "In13.Cu")
		(net "M_H_CPU0_SB_DQ<29>")
	)
	(segment
		(start 389.90778 -293.03853)
		(end 389.916162 -293.043356)
		(width 0.0889)
		(layer "In13.Cu")
		(net "M_H_CPU0_SB_DQ<29>")
	)
	(segment
		(start 409.59024 -317.610236)
		(end 420.91864 -317.610236)
		(width 0.14478)
		(layer "In13.Cu")
		(net "M_H_CPU0_SB_DQ<29>")
	)
	(segment
		(start 389.333486 -293.043356)
		(end 389.341868 -293.03853)
		(width 0.0889)
		(layer "In13.Cu")
		(net "M_H_CPU0_SB_DQ<29>")
	)
	(segment
		(start 393.510008 -296.185336)
		(end 393.510008 -302.914812)
		(width 0.14478)
		(layer "In13.Cu")
		(net "M_H_CPU0_SB_DQ<29>")
	)
	(segment
		(start 420.91864 -317.610236)
		(end 424.012106 -317.18504)
		(width 0.14478)
		(layer "In13.Cu")
		(net "M_H_CPU0_SB_DQ<29>")
	)
	(segment
		(start 399.642838 -308.227222)
		(end 408.556968 -317.141098)
		(width 0.14478)
		(layer "In13.Cu")
		(net "M_H_CPU0_SB_DQ<29>")
	)
	(segment
		(start 393.510008 -295.85285)
		(end 393.510008 -296.185336)
		(width 0.0889)
		(layer "In13.Cu")
		(net "M_H_CPU0_SB_DQ<29>")
	)
	(arc
		(start 383.327656 -293.03853)
		(mid 383.509907 -293.08888)
		(end 383.693416 -293.043356)
		(width 0.0889)
		(layer "In13.Cu")
		(net "M_H_CPU0_SB_DQ<29>")
	)
	(arc
		(start 392.539982 -294.335962)
		(mid 392.581531 -294.507384)
		(end 392.696954 -294.640762)
		(width 0.0889)
		(layer "In13.Cu")
		(net "M_H_CPU0_SB_DQ<29>")
	)
	(arc
		(start 384.26771 -293.03853)
		(mid 384.449961 -293.08888)
		(end 384.63347 -293.043356)
		(width 0.0889)
		(layer "In13.Cu")
		(net "M_H_CPU0_SB_DQ<29>")
	)
	(arc
		(start 393.009882 -295.145968)
		(mid 393.0228 -295.243027)
		(end 393.060428 -295.33342)
		(width 0.0889)
		(layer "In13.Cu")
		(net "M_H_CPU0_SB_DQ<29>")
	)
	(arc
		(start 386.52196 -293.03853)
		(mid 386.804916 -292.962353)
		(end 387.087872 -293.03853)
		(width 0.0889)
		(layer "In13.Cu")
		(net "M_H_CPU0_SB_DQ<29>")
	)
	(arc
		(start 388.027672 -293.03853)
		(mid 388.209923 -293.08888)
		(end 388.393432 -293.043356)
		(width 0.0889)
		(layer "In13.Cu")
		(net "M_H_CPU0_SB_DQ<29>")
	)
	(arc
		(start 387.46176 -293.03853)
		(mid 387.744716 -292.962353)
		(end 388.027672 -293.03853)
		(width 0.0889)
		(layer "In13.Cu")
		(net "M_H_CPU0_SB_DQ<29>")
	)
	(arc
		(start 385.216146 -293.043356)
		(mid 385.399654 -293.08885)
		(end 385.581906 -293.03853)
		(width 0.0889)
		(layer "In13.Cu")
		(net "M_H_CPU0_SB_DQ<29>")
	)
	(arc
		(start 393.060428 -295.33342)
		(mid 393.086562 -295.369652)
		(end 393.11961 -295.399714)
		(width 0.0889)
		(layer "In13.Cu")
		(net "M_H_CPU0_SB_DQ<29>")
	)
	(arc
		(start 385.581906 -293.03853)
		(mid 385.864862 -292.962353)
		(end 386.147818 -293.03853)
		(width 0.0889)
		(layer "In13.Cu")
		(net "M_H_CPU0_SB_DQ<29>")
	)
	(arc
		(start 390.281922 -293.03853)
		(mid 390.564878 -292.962353)
		(end 390.847834 -293.03853)
		(width 0.0889)
		(layer "In13.Cu")
		(net "M_H_CPU0_SB_DQ<29>")
	)
	(arc
		(start 388.967726 -293.03853)
		(mid 389.149977 -293.08888)
		(end 389.333486 -293.043356)
		(width 0.0889)
		(layer "In13.Cu")
		(net "M_H_CPU0_SB_DQ<29>")
	)
	(arc
		(start 392.29665 -293.871396)
		(mid 392.475463 -294.073746)
		(end 392.539982 -294.335962)
		(width 0.0889)
		(layer "In13.Cu")
		(net "M_H_CPU0_SB_DQ<29>")
	)
	(arc
		(start 386.1562 -293.043356)
		(mid 386.339708 -293.08885)
		(end 386.52196 -293.03853)
		(width 0.0889)
		(layer "In13.Cu")
		(net "M_H_CPU0_SB_DQ<29>")
	)
	(arc
		(start 392.76655 -294.681402)
		(mid 392.945363 -294.883752)
		(end 393.009882 -295.145968)
		(width 0.0889)
		(layer "In13.Cu")
		(net "M_H_CPU0_SB_DQ<29>")
	)
	(arc
		(start 391.221722 -293.03853)
		(mid 391.504678 -292.962353)
		(end 391.787634 -293.03853)
		(width 0.0889)
		(layer "In13.Cu")
		(net "M_H_CPU0_SB_DQ<29>")
	)
	(arc
		(start 389.916162 -293.043356)
		(mid 390.09967 -293.08885)
		(end 390.281922 -293.03853)
		(width 0.0889)
		(layer "In13.Cu")
		(net "M_H_CPU0_SB_DQ<29>")
	)
	(arc
		(start 390.847834 -293.03853)
		(mid 391.034778 -293.088785)
		(end 391.221722 -293.03853)
		(width 0.0889)
		(layer "In13.Cu")
		(net "M_H_CPU0_SB_DQ<29>")
	)
	(arc
		(start 387.087872 -293.03853)
		(mid 387.274816 -293.088785)
		(end 387.46176 -293.03853)
		(width 0.0889)
		(layer "In13.Cu")
		(net "M_H_CPU0_SB_DQ<29>")
	)
	(arc
		(start 388.401814 -293.03853)
		(mid 388.68477 -292.962353)
		(end 388.967726 -293.03853)
		(width 0.0889)
		(layer "In13.Cu")
		(net "M_H_CPU0_SB_DQ<29>")
	)
	(arc
		(start 393.326112 -295.550336)
		(mid 393.38813 -295.609167)
		(end 393.433046 -295.681908)
		(width 0.0889)
		(layer "In13.Cu")
		(net "M_H_CPU0_SB_DQ<29>")
	)
	(arc
		(start 391.82675 -293.06139)
		(mid 392.005563 -293.26374)
		(end 392.070082 -293.525956)
		(width 0.0889)
		(layer "In13.Cu")
		(net "M_H_CPU0_SB_DQ<29>")
	)
	(arc
		(start 383.701798 -293.03853)
		(mid 383.984754 -292.962353)
		(end 384.26771 -293.03853)
		(width 0.0889)
		(layer "In13.Cu")
		(net "M_H_CPU0_SB_DQ<29>")
	)
	(arc
		(start 392.070082 -293.525956)
		(mid 392.111631 -293.697378)
		(end 392.227054 -293.830756)
		(width 0.0889)
		(layer "In13.Cu")
		(net "M_H_CPU0_SB_DQ<29>")
	)
	(arc
		(start 382.824736 -293.00678)
		(mid 383.079944 -292.963303)
		(end 383.327656 -293.03853)
		(width 0.0889)
		(layer "In13.Cu")
		(net "M_H_CPU0_SB_DQ<29>")
	)
	(arc
		(start 389.341868 -293.03853)
		(mid 389.624824 -292.962353)
		(end 389.90778 -293.03853)
		(width 0.0889)
		(layer "In13.Cu")
		(net "M_H_CPU0_SB_DQ<29>")
	)
	(arc
		(start 384.641852 -293.03853)
		(mid 384.924808 -292.962353)
		(end 385.207764 -293.03853)
		(width 0.0889)
		(layer "In13.Cu")
		(net "M_H_CPU0_SB_DQ<29>")
	)
	(segment
		(start 383.517902 -291.640006)
		(end 383.984754 -291.905944)
		(width 0.10668)
		(layer "F.Cu")
		(net "M_H_CPU0_SB_DQ<28>")
	)
	(segment
		(start 418.991034 -315.775086)
		(end 418.846254 -315.919866)
		(width 0.14478)
		(layer "In13.Cu")
		(net "M_H_CPU0_SB_DQ<28>")
	)
	(segment
		(start 384.138932 -292.171374)
		(end 383.984754 -291.905944)
		(width 0.0889)
		(layer "In13.Cu")
		(net "M_H_CPU0_SB_DQ<28>")
	)
	(segment
		(start 418.846254 -315.919866)
		(end 418.584634 -315.919866)
		(width 0.14478)
		(layer "In13.Cu")
		(net "M_H_CPU0_SB_DQ<28>")
	)
	(segment
		(start 417.888674 -315.775086)
		(end 417.743894 -315.919866)
		(width 0.14478)
		(layer "In13.Cu")
		(net "M_H_CPU0_SB_DQ<28>")
	)
	(segment
		(start 419.397434 -315.380878)
		(end 419.135814 -315.380878)
		(width 0.14478)
		(layer "In13.Cu")
		(net "M_H_CPU0_SB_DQ<28>")
	)
	(segment
		(start 419.135814 -315.380878)
		(end 418.991034 -315.525658)
		(width 0.14478)
		(layer "In13.Cu")
		(net "M_H_CPU0_SB_DQ<28>")
	)
	(segment
		(start 418.584634 -315.919866)
		(end 418.439854 -315.775086)
		(width 0.14478)
		(layer "In13.Cu")
		(net "M_H_CPU0_SB_DQ<28>")
	)
	(segment
		(start 388.506208 -292.23335)
		(end 388.497826 -292.228524)
		(width 0.0889)
		(layer "In13.Cu")
		(net "M_H_CPU0_SB_DQ<28>")
	)
	(segment
		(start 393.704064 -294.679624)
		(end 393.635992 -294.640254)
		(width 0.0889)
		(layer "In13.Cu")
		(net "M_H_CPU0_SB_DQ<28>")
	)
	(segment
		(start 417.743894 -315.919866)
		(end 408.608022 -315.919866)
		(width 0.14478)
		(layer "In13.Cu")
		(net "M_H_CPU0_SB_DQ<28>")
	)
	(segment
		(start 421.945308 -315.485018)
		(end 421.51046 -315.919866)
		(width 0.14478)
		(layer "In13.Cu")
		(net "M_H_CPU0_SB_DQ<28>")
	)
	(segment
		(start 394.419328 -295.61536)
		(end 393.949936 -295.145968)
		(width 0.0889)
		(layer "In13.Cu")
		(net "M_H_CPU0_SB_DQ<28>")
	)
	(segment
		(start 419.686994 -315.919866)
		(end 419.542214 -315.775086)
		(width 0.14478)
		(layer "In13.Cu")
		(net "M_H_CPU0_SB_DQ<28>")
	)
	(segment
		(start 418.439854 -315.525658)
		(end 418.295074 -315.380878)
		(width 0.14478)
		(layer "In13.Cu")
		(net "M_H_CPU0_SB_DQ<28>")
	)
	(segment
		(start 393.236704 -293.871396)
		(end 393.167108 -293.830756)
		(width 0.0889)
		(layer "In13.Cu")
		(net "M_H_CPU0_SB_DQ<28>")
	)
	(segment
		(start 392.296904 -292.251384)
		(end 392.257788 -292.228524)
		(width 0.0889)
		(layer "In13.Cu")
		(net "M_H_CPU0_SB_DQ<28>")
	)
	(segment
		(start 418.991034 -315.525658)
		(end 418.991034 -315.775086)
		(width 0.14478)
		(layer "In13.Cu")
		(net "M_H_CPU0_SB_DQ<28>")
	)
	(segment
		(start 418.295074 -315.380878)
		(end 418.033454 -315.380878)
		(width 0.14478)
		(layer "In13.Cu")
		(net "M_H_CPU0_SB_DQ<28>")
	)
	(segment
		(start 419.542214 -315.525658)
		(end 419.397434 -315.380878)
		(width 0.14478)
		(layer "In13.Cu")
		(net "M_H_CPU0_SB_DQ<28>")
	)
	(segment
		(start 386.051806 -292.228524)
		(end 386.043424 -292.23335)
		(width 0.0889)
		(layer "In13.Cu")
		(net "M_H_CPU0_SB_DQ<28>")
	)
	(segment
		(start 419.542214 -315.775086)
		(end 419.542214 -315.525658)
		(width 0.14478)
		(layer "In13.Cu")
		(net "M_H_CPU0_SB_DQ<28>")
	)
	(segment
		(start 392.766804 -293.06139)
		(end 392.697208 -293.02075)
		(width 0.0889)
		(layer "In13.Cu")
		(net "M_H_CPU0_SB_DQ<28>")
	)
	(segment
		(start 386.99186 -292.228524)
		(end 386.983478 -292.23335)
		(width 0.0889)
		(layer "In13.Cu")
		(net "M_H_CPU0_SB_DQ<28>")
	)
	(segment
		(start 408.608022 -315.919866)
		(end 394.419328 -301.731172)
		(width 0.14478)
		(layer "In13.Cu")
		(net "M_H_CPU0_SB_DQ<28>")
	)
	(segment
		(start 394.419328 -301.731172)
		(end 394.419328 -295.995344)
		(width 0.14478)
		(layer "In13.Cu")
		(net "M_H_CPU0_SB_DQ<28>")
	)
	(segment
		(start 417.888674 -315.525658)
		(end 417.888674 -315.775086)
		(width 0.14478)
		(layer "In13.Cu")
		(net "M_H_CPU0_SB_DQ<28>")
	)
	(segment
		(start 387.566154 -292.23335)
		(end 387.557772 -292.228524)
		(width 0.0889)
		(layer "In13.Cu")
		(net "M_H_CPU0_SB_DQ<28>")
	)
	(segment
		(start 418.033454 -315.380878)
		(end 417.888674 -315.525658)
		(width 0.14478)
		(layer "In13.Cu")
		(net "M_H_CPU0_SB_DQ<28>")
	)
	(segment
		(start 418.439854 -315.775086)
		(end 418.439854 -315.525658)
		(width 0.14478)
		(layer "In13.Cu")
		(net "M_H_CPU0_SB_DQ<28>")
	)
	(segment
		(start 424.012106 -315.485018)
		(end 421.945308 -315.485018)
		(width 0.14478)
		(layer "In13.Cu")
		(net "M_H_CPU0_SB_DQ<28>")
	)
	(segment
		(start 391.326116 -292.23335)
		(end 391.317734 -292.228524)
		(width 0.0889)
		(layer "In13.Cu")
		(net "M_H_CPU0_SB_DQ<28>")
	)
	(segment
		(start 390.751822 -292.228524)
		(end 390.74344 -292.23335)
		(width 0.0889)
		(layer "In13.Cu")
		(net "M_H_CPU0_SB_DQ<28>")
	)
	(segment
		(start 394.419328 -295.995344)
		(end 394.419328 -295.61536)
		(width 0.0889)
		(layer "In13.Cu")
		(net "M_H_CPU0_SB_DQ<28>")
	)
	(segment
		(start 421.51046 -315.919866)
		(end 419.686994 -315.919866)
		(width 0.14478)
		(layer "In13.Cu")
		(net "M_H_CPU0_SB_DQ<28>")
	)
	(segment
		(start 384.235198 -292.196774)
		(end 384.138932 -292.171374)
		(width 0.0889)
		(layer "In13.Cu")
		(net "M_H_CPU0_SB_DQ<28>")
	)
	(arc
		(start 388.871968 -292.228524)
		(mid 388.689717 -292.278874)
		(end 388.506208 -292.23335)
		(width 0.0889)
		(layer "In13.Cu")
		(net "M_H_CPU0_SB_DQ<28>")
	)
	(arc
		(start 386.043424 -292.23335)
		(mid 385.859916 -292.278844)
		(end 385.677664 -292.228524)
		(width 0.0889)
		(layer "In13.Cu")
		(net "M_H_CPU0_SB_DQ<28>")
	)
	(arc
		(start 386.617718 -292.228524)
		(mid 386.334762 -292.152347)
		(end 386.051806 -292.228524)
		(width 0.0889)
		(layer "In13.Cu")
		(net "M_H_CPU0_SB_DQ<28>")
	)
	(arc
		(start 388.497826 -292.228524)
		(mid 388.21487 -292.152347)
		(end 387.931914 -292.228524)
		(width 0.0889)
		(layer "In13.Cu")
		(net "M_H_CPU0_SB_DQ<28>")
	)
	(arc
		(start 385.677664 -292.228524)
		(mid 385.394708 -292.152347)
		(end 385.111752 -292.228524)
		(width 0.0889)
		(layer "In13.Cu")
		(net "M_H_CPU0_SB_DQ<28>")
	)
	(arc
		(start 386.983478 -292.23335)
		(mid 386.79997 -292.278844)
		(end 386.617718 -292.228524)
		(width 0.0889)
		(layer "In13.Cu")
		(net "M_H_CPU0_SB_DQ<28>")
	)
	(arc
		(start 390.74344 -292.23335)
		(mid 390.559932 -292.278844)
		(end 390.37768 -292.228524)
		(width 0.0889)
		(layer "In13.Cu")
		(net "M_H_CPU0_SB_DQ<28>")
	)
	(arc
		(start 393.010136 -293.525956)
		(mid 392.945621 -293.263737)
		(end 392.766804 -293.06139)
		(width 0.0889)
		(layer "In13.Cu")
		(net "M_H_CPU0_SB_DQ<28>")
	)
	(arc
		(start 387.931914 -292.228524)
		(mid 387.749663 -292.278874)
		(end 387.566154 -292.23335)
		(width 0.0889)
		(layer "In13.Cu")
		(net "M_H_CPU0_SB_DQ<28>")
	)
	(arc
		(start 393.167108 -293.830756)
		(mid 393.051681 -293.69738)
		(end 393.010136 -293.525956)
		(width 0.0889)
		(layer "In13.Cu")
		(net "M_H_CPU0_SB_DQ<28>")
	)
	(arc
		(start 389.811768 -292.228524)
		(mid 389.624824 -292.278779)
		(end 389.43788 -292.228524)
		(width 0.0889)
		(layer "In13.Cu")
		(net "M_H_CPU0_SB_DQ<28>")
	)
	(arc
		(start 392.540236 -292.71595)
		(mid 392.475721 -292.453731)
		(end 392.296904 -292.251384)
		(width 0.0889)
		(layer "In13.Cu")
		(net "M_H_CPU0_SB_DQ<28>")
	)
	(arc
		(start 385.111752 -292.228524)
		(mid 384.924808 -292.278779)
		(end 384.737864 -292.228524)
		(width 0.0889)
		(layer "In13.Cu")
		(net "M_H_CPU0_SB_DQ<28>")
	)
	(arc
		(start 392.697208 -293.02075)
		(mid 392.581781 -292.887374)
		(end 392.540236 -292.71595)
		(width 0.0889)
		(layer "In13.Cu")
		(net "M_H_CPU0_SB_DQ<28>")
	)
	(arc
		(start 389.43788 -292.228524)
		(mid 389.154924 -292.152347)
		(end 388.871968 -292.228524)
		(width 0.0889)
		(layer "In13.Cu")
		(net "M_H_CPU0_SB_DQ<28>")
	)
	(arc
		(start 392.257788 -292.228524)
		(mid 391.974832 -292.152347)
		(end 391.691876 -292.228524)
		(width 0.0889)
		(layer "In13.Cu")
		(net "M_H_CPU0_SB_DQ<28>")
	)
	(arc
		(start 393.949936 -295.145968)
		(mid 393.8847 -294.882377)
		(end 393.704064 -294.679624)
		(width 0.0889)
		(layer "In13.Cu")
		(net "M_H_CPU0_SB_DQ<28>")
	)
	(arc
		(start 391.317734 -292.228524)
		(mid 391.034778 -292.152347)
		(end 390.751822 -292.228524)
		(width 0.0889)
		(layer "In13.Cu")
		(net "M_H_CPU0_SB_DQ<28>")
	)
	(arc
		(start 390.37768 -292.228524)
		(mid 390.094724 -292.152347)
		(end 389.811768 -292.228524)
		(width 0.0889)
		(layer "In13.Cu")
		(net "M_H_CPU0_SB_DQ<28>")
	)
	(arc
		(start 393.635992 -294.640254)
		(mid 393.521316 -294.50692)
		(end 393.480036 -294.335962)
		(width 0.0889)
		(layer "In13.Cu")
		(net "M_H_CPU0_SB_DQ<28>")
	)
	(arc
		(start 391.691876 -292.228524)
		(mid 391.509625 -292.278874)
		(end 391.326116 -292.23335)
		(width 0.0889)
		(layer "In13.Cu")
		(net "M_H_CPU0_SB_DQ<28>")
	)
	(arc
		(start 393.480036 -294.335962)
		(mid 393.415521 -294.073743)
		(end 393.236704 -293.871396)
		(width 0.0889)
		(layer "In13.Cu")
		(net "M_H_CPU0_SB_DQ<28>")
	)
	(arc
		(start 387.557772 -292.228524)
		(mid 387.274816 -292.152347)
		(end 386.99186 -292.228524)
		(width 0.0889)
		(layer "In13.Cu")
		(net "M_H_CPU0_SB_DQ<28>")
	)
	(arc
		(start 384.737864 -292.228524)
		(mid 384.490268 -292.153346)
		(end 384.235198 -292.196774)
		(width 0.0889)
		(layer "In13.Cu")
		(net "M_H_CPU0_SB_DQ<28>")
	)
	(segment
		(start 382.577848 -290.019994)
		(end 383.0447 -290.285932)
		(width 0.10668)
		(layer "F.Cu")
		(net "M_H_CPU0_SB_DQ<27>")
	)
	(segment
		(start 410.026358 -312.254392)
		(end 410.171138 -312.109612)
		(width 0.14478)
		(layer "In13.Cu")
		(net "M_H_CPU0_SB_DQ<27>")
	)
	(segment
		(start 417.972748 -311.660032)
		(end 418.81298 -312.500264)
		(width 0.14478)
		(layer "In13.Cu")
		(net "M_H_CPU0_SB_DQ<27>")
	)
	(segment
		(start 415.814764 -311.340246)
		(end 416.076384 -311.340246)
		(width 0.14478)
		(layer "In13.Cu")
		(net "M_H_CPU0_SB_DQ<27>")
	)
	(segment
		(start 393.872974 -291.042598)
		(end 394.443966 -292.420802)
		(width 0.0889)
		(layer "In13.Cu")
		(net "M_H_CPU0_SB_DQ<27>")
	)
	(segment
		(start 416.627564 -311.979818)
		(end 416.772344 -311.835038)
		(width 0.14478)
		(layer "In13.Cu")
		(net "M_H_CPU0_SB_DQ<27>")
	)
	(segment
		(start 408.779218 -312.488326)
		(end 408.923998 -312.343546)
		(width 0.14478)
		(layer "In13.Cu")
		(net "M_H_CPU0_SB_DQ<27>")
	)
	(segment
		(start 408.923998 -312.343546)
		(end 408.923998 -312.254392)
		(width 0.14478)
		(layer "In13.Cu")
		(net "M_H_CPU0_SB_DQ<27>")
	)
	(segment
		(start 412.086298 -312.488326)
		(end 412.231078 -312.343546)
		(width 0.14478)
		(layer "In13.Cu")
		(net "M_H_CPU0_SB_DQ<27>")
	)
	(segment
		(start 410.577538 -312.343546)
		(end 410.722318 -312.488326)
		(width 0.14478)
		(layer "In13.Cu")
		(net "M_H_CPU0_SB_DQ<27>")
	)
	(segment
		(start 387.557772 -289.963352)
		(end 387.566154 -289.958526)
		(width 0.0889)
		(layer "In13.Cu")
		(net "M_H_CPU0_SB_DQ<27>")
	)
	(segment
		(start 393.872974 -290.21151)
		(end 393.872974 -291.042598)
		(width 0.0889)
		(layer "In13.Cu")
		(net "M_H_CPU0_SB_DQ<27>")
	)
	(segment
		(start 416.772344 -311.485026)
		(end 416.917124 -311.340246)
		(width 0.14478)
		(layer "In13.Cu")
		(net "M_H_CPU0_SB_DQ<27>")
	)
	(segment
		(start 419.496748 -312.500264)
		(end 419.912038 -312.084974)
		(width 0.14478)
		(layer "In13.Cu")
		(net "M_H_CPU0_SB_DQ<27>")
	)
	(segment
		(start 412.375858 -312.109612)
		(end 412.637478 -312.109612)
		(width 0.14478)
		(layer "In13.Cu")
		(net "M_H_CPU0_SB_DQ<27>")
	)
	(segment
		(start 413.478218 -312.109612)
		(end 414.278826 -312.109612)
		(width 0.14478)
		(layer "In13.Cu")
		(net "M_H_CPU0_SB_DQ<27>")
	)
	(segment
		(start 395.17701 -292.84803)
		(end 396.767558 -294.438578)
		(width 0.14478)
		(layer "In13.Cu")
		(net "M_H_CPU0_SB_DQ<27>")
	)
	(segment
		(start 415.669984 -311.485026)
		(end 415.814764 -311.340246)
		(width 0.14478)
		(layer "In13.Cu")
		(net "M_H_CPU0_SB_DQ<27>")
	)
	(segment
		(start 386.983478 -289.958526)
		(end 386.99186 -289.963352)
		(width 0.0889)
		(layer "In13.Cu")
		(net "M_H_CPU0_SB_DQ<27>")
	)
	(segment
		(start 410.722318 -312.488326)
		(end 410.983938 -312.488326)
		(width 0.14478)
		(layer "In13.Cu")
		(net "M_H_CPU0_SB_DQ<27>")
	)
	(segment
		(start 416.772344 -311.835038)
		(end 416.772344 -311.485026)
		(width 0.14478)
		(layer "In13.Cu")
		(net "M_H_CPU0_SB_DQ<27>")
	)
	(segment
		(start 411.128718 -312.254392)
		(end 411.273498 -312.109612)
		(width 0.14478)
		(layer "In13.Cu")
		(net "M_H_CPU0_SB_DQ<27>")
	)
	(segment
		(start 411.128718 -312.343546)
		(end 411.128718 -312.254392)
		(width 0.14478)
		(layer "In13.Cu")
		(net "M_H_CPU0_SB_DQ<27>")
	)
	(segment
		(start 414.278826 -312.109612)
		(end 414.728406 -311.660032)
		(width 0.14478)
		(layer "In13.Cu")
		(net "M_H_CPU0_SB_DQ<27>")
	)
	(segment
		(start 415.669984 -311.515252)
		(end 415.669984 -311.485026)
		(width 0.14478)
		(layer "In13.Cu")
		(net "M_H_CPU0_SB_DQ<27>")
	)
	(segment
		(start 383.79781 -289.963352)
		(end 383.806192 -289.958526)
		(width 0.0889)
		(layer "In13.Cu")
		(net "M_H_CPU0_SB_DQ<27>")
	)
	(segment
		(start 394.443966 -292.420802)
		(end 394.871194 -292.84803)
		(width 0.0889)
		(layer "In13.Cu")
		(net "M_H_CPU0_SB_DQ<27>")
	)
	(segment
		(start 411.679898 -312.254392)
		(end 411.679898 -312.343546)
		(width 0.14478)
		(layer "In13.Cu")
		(net "M_H_CPU0_SB_DQ<27>")
	)
	(segment
		(start 414.728406 -311.660032)
		(end 415.525204 -311.660032)
		(width 0.14478)
		(layer "In13.Cu")
		(net "M_H_CPU0_SB_DQ<27>")
	)
	(segment
		(start 416.365944 -311.979818)
		(end 416.627564 -311.979818)
		(width 0.14478)
		(layer "In13.Cu")
		(net "M_H_CPU0_SB_DQ<27>")
	)
	(segment
		(start 410.983938 -312.488326)
		(end 411.128718 -312.343546)
		(width 0.14478)
		(layer "In13.Cu")
		(net "M_H_CPU0_SB_DQ<27>")
	)
	(segment
		(start 416.221164 -311.485026)
		(end 416.221164 -311.835038)
		(width 0.14478)
		(layer "In13.Cu")
		(net "M_H_CPU0_SB_DQ<27>")
	)
	(segment
		(start 413.188658 -312.488326)
		(end 413.333438 -312.343546)
		(width 0.14478)
		(layer "In13.Cu")
		(net "M_H_CPU0_SB_DQ<27>")
	)
	(segment
		(start 410.026358 -312.343546)
		(end 410.026358 -312.254392)
		(width 0.14478)
		(layer "In13.Cu")
		(net "M_H_CPU0_SB_DQ<27>")
	)
	(segment
		(start 396.767558 -294.438578)
		(end 396.767558 -300.842172)
		(width 0.14478)
		(layer "In13.Cu")
		(net "M_H_CPU0_SB_DQ<27>")
	)
	(segment
		(start 412.637478 -312.109612)
		(end 412.782258 -312.254392)
		(width 0.14478)
		(layer "In13.Cu")
		(net "M_H_CPU0_SB_DQ<27>")
	)
	(segment
		(start 416.221164 -311.835038)
		(end 416.365944 -311.979818)
		(width 0.14478)
		(layer "In13.Cu")
		(net "M_H_CPU0_SB_DQ<27>")
	)
	(segment
		(start 396.767558 -300.842172)
		(end 408.034998 -312.109612)
		(width 0.14478)
		(layer "In13.Cu")
		(net "M_H_CPU0_SB_DQ<27>")
	)
	(segment
		(start 413.333438 -312.254392)
		(end 413.478218 -312.109612)
		(width 0.14478)
		(layer "In13.Cu")
		(net "M_H_CPU0_SB_DQ<27>")
	)
	(segment
		(start 409.330398 -312.109612)
		(end 409.475178 -312.254392)
		(width 0.14478)
		(layer "In13.Cu")
		(net "M_H_CPU0_SB_DQ<27>")
	)
	(segment
		(start 417.323524 -311.485026)
		(end 417.323524 -311.515252)
		(width 0.14478)
		(layer "In13.Cu")
		(net "M_H_CPU0_SB_DQ<27>")
	)
	(segment
		(start 409.619958 -312.488326)
		(end 409.881578 -312.488326)
		(width 0.14478)
		(layer "In13.Cu")
		(net "M_H_CPU0_SB_DQ<27>")
	)
	(segment
		(start 411.273498 -312.109612)
		(end 411.535118 -312.109612)
		(width 0.14478)
		(layer "In13.Cu")
		(net "M_H_CPU0_SB_DQ<27>")
	)
	(segment
		(start 417.178744 -311.340246)
		(end 417.323524 -311.485026)
		(width 0.14478)
		(layer "In13.Cu")
		(net "M_H_CPU0_SB_DQ<27>")
	)
	(segment
		(start 392.826748 -289.884104)
		(end 393.545568 -289.884104)
		(width 0.0889)
		(layer "In13.Cu")
		(net "M_H_CPU0_SB_DQ<27>")
	)
	(segment
		(start 411.824678 -312.488326)
		(end 412.086298 -312.488326)
		(width 0.14478)
		(layer "In13.Cu")
		(net "M_H_CPU0_SB_DQ<27>")
	)
	(segment
		(start 410.171138 -312.109612)
		(end 410.432758 -312.109612)
		(width 0.14478)
		(layer "In13.Cu")
		(net "M_H_CPU0_SB_DQ<27>")
	)
	(segment
		(start 417.323524 -311.515252)
		(end 417.468304 -311.660032)
		(width 0.14478)
		(layer "In13.Cu")
		(net "M_H_CPU0_SB_DQ<27>")
	)
	(segment
		(start 392.6713 -290.039552)
		(end 392.826748 -289.884104)
		(width 0.0889)
		(layer "In13.Cu")
		(net "M_H_CPU0_SB_DQ<27>")
	)
	(segment
		(start 409.475178 -312.343546)
		(end 409.619958 -312.488326)
		(width 0.14478)
		(layer "In13.Cu")
		(net "M_H_CPU0_SB_DQ<27>")
	)
	(segment
		(start 409.068778 -312.109612)
		(end 409.330398 -312.109612)
		(width 0.14478)
		(layer "In13.Cu")
		(net "M_H_CPU0_SB_DQ<27>")
	)
	(segment
		(start 408.372818 -312.254392)
		(end 408.372818 -312.343546)
		(width 0.14478)
		(layer "In13.Cu")
		(net "M_H_CPU0_SB_DQ<27>")
	)
	(segment
		(start 393.545568 -289.884104)
		(end 393.872974 -290.21151)
		(width 0.0889)
		(layer "In13.Cu")
		(net "M_H_CPU0_SB_DQ<27>")
	)
	(segment
		(start 412.927038 -312.488326)
		(end 413.188658 -312.488326)
		(width 0.14478)
		(layer "In13.Cu")
		(net "M_H_CPU0_SB_DQ<27>")
	)
	(segment
		(start 409.881578 -312.488326)
		(end 410.026358 -312.343546)
		(width 0.14478)
		(layer "In13.Cu")
		(net "M_H_CPU0_SB_DQ<27>")
	)
	(segment
		(start 415.525204 -311.660032)
		(end 415.669984 -311.515252)
		(width 0.14478)
		(layer "In13.Cu")
		(net "M_H_CPU0_SB_DQ<27>")
	)
	(segment
		(start 388.497826 -289.963352)
		(end 388.506208 -289.958526)
		(width 0.0889)
		(layer "In13.Cu")
		(net "M_H_CPU0_SB_DQ<27>")
	)
	(segment
		(start 410.432758 -312.109612)
		(end 410.577538 -312.254392)
		(width 0.14478)
		(layer "In13.Cu")
		(net "M_H_CPU0_SB_DQ<27>")
	)
	(segment
		(start 394.871194 -292.84803)
		(end 395.17701 -292.84803)
		(width 0.0889)
		(layer "In13.Cu")
		(net "M_H_CPU0_SB_DQ<27>")
	)
	(segment
		(start 412.231078 -312.254392)
		(end 412.375858 -312.109612)
		(width 0.14478)
		(layer "In13.Cu")
		(net "M_H_CPU0_SB_DQ<27>")
	)
	(segment
		(start 416.076384 -311.340246)
		(end 416.221164 -311.485026)
		(width 0.14478)
		(layer "In13.Cu")
		(net "M_H_CPU0_SB_DQ<27>")
	)
	(segment
		(start 408.034998 -312.109612)
		(end 408.228038 -312.109612)
		(width 0.14478)
		(layer "In13.Cu")
		(net "M_H_CPU0_SB_DQ<27>")
	)
	(segment
		(start 408.372818 -312.343546)
		(end 408.517598 -312.488326)
		(width 0.14478)
		(layer "In13.Cu")
		(net "M_H_CPU0_SB_DQ<27>")
	)
	(segment
		(start 382.890776 -290.020502)
		(end 382.913128 -289.93719)
		(width 0.0889)
		(layer "In13.Cu")
		(net "M_H_CPU0_SB_DQ<27>")
	)
	(segment
		(start 412.231078 -312.343546)
		(end 412.231078 -312.254392)
		(width 0.14478)
		(layer "In13.Cu")
		(net "M_H_CPU0_SB_DQ<27>")
	)
	(segment
		(start 418.81298 -312.500264)
		(end 419.496748 -312.500264)
		(width 0.14478)
		(layer "In13.Cu")
		(net "M_H_CPU0_SB_DQ<27>")
	)
	(segment
		(start 409.475178 -312.254392)
		(end 409.475178 -312.343546)
		(width 0.14478)
		(layer "In13.Cu")
		(net "M_H_CPU0_SB_DQ<27>")
	)
	(segment
		(start 412.782258 -312.254392)
		(end 412.782258 -312.343546)
		(width 0.14478)
		(layer "In13.Cu")
		(net "M_H_CPU0_SB_DQ<27>")
	)
	(segment
		(start 408.517598 -312.488326)
		(end 408.779218 -312.488326)
		(width 0.14478)
		(layer "In13.Cu")
		(net "M_H_CPU0_SB_DQ<27>")
	)
	(segment
		(start 417.468304 -311.660032)
		(end 417.972748 -311.660032)
		(width 0.14478)
		(layer "In13.Cu")
		(net "M_H_CPU0_SB_DQ<27>")
	)
	(segment
		(start 390.74344 -289.958526)
		(end 390.751822 -289.963352)
		(width 0.0889)
		(layer "In13.Cu")
		(net "M_H_CPU0_SB_DQ<27>")
	)
	(segment
		(start 410.577538 -312.254392)
		(end 410.577538 -312.343546)
		(width 0.14478)
		(layer "In13.Cu")
		(net "M_H_CPU0_SB_DQ<27>")
	)
	(segment
		(start 413.333438 -312.343546)
		(end 413.333438 -312.254392)
		(width 0.14478)
		(layer "In13.Cu")
		(net "M_H_CPU0_SB_DQ<27>")
	)
	(segment
		(start 411.679898 -312.343546)
		(end 411.824678 -312.488326)
		(width 0.14478)
		(layer "In13.Cu")
		(net "M_H_CPU0_SB_DQ<27>")
	)
	(segment
		(start 391.317734 -289.963352)
		(end 391.326116 -289.958526)
		(width 0.0889)
		(layer "In13.Cu")
		(net "M_H_CPU0_SB_DQ<27>")
	)
	(segment
		(start 416.917124 -311.340246)
		(end 417.178744 -311.340246)
		(width 0.14478)
		(layer "In13.Cu")
		(net "M_H_CPU0_SB_DQ<27>")
	)
	(segment
		(start 383.0447 -290.285932)
		(end 382.890776 -290.020502)
		(width 0.0889)
		(layer "In13.Cu")
		(net "M_H_CPU0_SB_DQ<27>")
	)
	(segment
		(start 408.228038 -312.109612)
		(end 408.372818 -312.254392)
		(width 0.14478)
		(layer "In13.Cu")
		(net "M_H_CPU0_SB_DQ<27>")
	)
	(segment
		(start 411.535118 -312.109612)
		(end 411.679898 -312.254392)
		(width 0.14478)
		(layer "In13.Cu")
		(net "M_H_CPU0_SB_DQ<27>")
	)
	(segment
		(start 412.782258 -312.343546)
		(end 412.927038 -312.488326)
		(width 0.14478)
		(layer "In13.Cu")
		(net "M_H_CPU0_SB_DQ<27>")
	)
	(segment
		(start 386.043424 -289.958526)
		(end 386.051806 -289.963352)
		(width 0.0889)
		(layer "In13.Cu")
		(net "M_H_CPU0_SB_DQ<27>")
	)
	(segment
		(start 391.974832 -290.039552)
		(end 392.6713 -290.039552)
		(width 0.0889)
		(layer "In13.Cu")
		(net "M_H_CPU0_SB_DQ<27>")
	)
	(segment
		(start 408.923998 -312.254392)
		(end 409.068778 -312.109612)
		(width 0.14478)
		(layer "In13.Cu")
		(net "M_H_CPU0_SB_DQ<27>")
	)
	(arc
		(start 389.43788 -289.963352)
		(mid 389.624824 -289.913097)
		(end 389.811768 -289.963352)
		(width 0.0889)
		(layer "In13.Cu")
		(net "M_H_CPU0_SB_DQ<27>")
	)
	(arc
		(start 390.37768 -289.963352)
		(mid 390.559931 -289.913002)
		(end 390.74344 -289.958526)
		(width 0.0889)
		(layer "In13.Cu")
		(net "M_H_CPU0_SB_DQ<27>")
	)
	(arc
		(start 391.691876 -289.963352)
		(mid 391.828312 -290.020177)
		(end 391.974832 -290.039552)
		(width 0.0889)
		(layer "In13.Cu")
		(net "M_H_CPU0_SB_DQ<27>")
	)
	(arc
		(start 384.171952 -289.963352)
		(mid 384.454908 -290.039529)
		(end 384.737864 -289.963352)
		(width 0.0889)
		(layer "In13.Cu")
		(net "M_H_CPU0_SB_DQ<27>")
	)
	(arc
		(start 387.566154 -289.958526)
		(mid 387.749662 -289.913032)
		(end 387.931914 -289.963352)
		(width 0.0889)
		(layer "In13.Cu")
		(net "M_H_CPU0_SB_DQ<27>")
	)
	(arc
		(start 388.506208 -289.958526)
		(mid 388.689716 -289.913032)
		(end 388.871968 -289.963352)
		(width 0.0889)
		(layer "In13.Cu")
		(net "M_H_CPU0_SB_DQ<27>")
	)
	(arc
		(start 384.737864 -289.963352)
		(mid 384.924808 -289.913097)
		(end 385.111752 -289.963352)
		(width 0.0889)
		(layer "In13.Cu")
		(net "M_H_CPU0_SB_DQ<27>")
	)
	(arc
		(start 390.751822 -289.963352)
		(mid 391.034778 -290.039529)
		(end 391.317734 -289.963352)
		(width 0.0889)
		(layer "In13.Cu")
		(net "M_H_CPU0_SB_DQ<27>")
	)
	(arc
		(start 383.231898 -289.963352)
		(mid 383.514854 -290.039529)
		(end 383.79781 -289.963352)
		(width 0.0889)
		(layer "In13.Cu")
		(net "M_H_CPU0_SB_DQ<27>")
	)
	(arc
		(start 385.677664 -289.963352)
		(mid 385.859915 -289.913002)
		(end 386.043424 -289.958526)
		(width 0.0889)
		(layer "In13.Cu")
		(net "M_H_CPU0_SB_DQ<27>")
	)
	(arc
		(start 386.051806 -289.963352)
		(mid 386.334762 -290.039529)
		(end 386.617718 -289.963352)
		(width 0.0889)
		(layer "In13.Cu")
		(net "M_H_CPU0_SB_DQ<27>")
	)
	(arc
		(start 386.99186 -289.963352)
		(mid 387.274816 -290.039529)
		(end 387.557772 -289.963352)
		(width 0.0889)
		(layer "In13.Cu")
		(net "M_H_CPU0_SB_DQ<27>")
	)
	(arc
		(start 389.811768 -289.963352)
		(mid 390.094724 -290.039529)
		(end 390.37768 -289.963352)
		(width 0.0889)
		(layer "In13.Cu")
		(net "M_H_CPU0_SB_DQ<27>")
	)
	(arc
		(start 387.931914 -289.963352)
		(mid 388.21487 -290.039529)
		(end 388.497826 -289.963352)
		(width 0.0889)
		(layer "In13.Cu")
		(net "M_H_CPU0_SB_DQ<27>")
	)
	(arc
		(start 388.871968 -289.963352)
		(mid 389.154924 -290.039529)
		(end 389.43788 -289.963352)
		(width 0.0889)
		(layer "In13.Cu")
		(net "M_H_CPU0_SB_DQ<27>")
	)
	(arc
		(start 383.806192 -289.958526)
		(mid 383.9897 -289.913032)
		(end 384.171952 -289.963352)
		(width 0.0889)
		(layer "In13.Cu")
		(net "M_H_CPU0_SB_DQ<27>")
	)
	(arc
		(start 385.111752 -289.963352)
		(mid 385.394708 -290.039529)
		(end 385.677664 -289.963352)
		(width 0.0889)
		(layer "In13.Cu")
		(net "M_H_CPU0_SB_DQ<27>")
	)
	(arc
		(start 386.617718 -289.963352)
		(mid 386.799969 -289.913002)
		(end 386.983478 -289.958526)
		(width 0.0889)
		(layer "In13.Cu")
		(net "M_H_CPU0_SB_DQ<27>")
	)
	(arc
		(start 382.913128 -289.93719)
		(mid 383.07546 -289.914372)
		(end 383.231898 -289.963352)
		(width 0.0889)
		(layer "In13.Cu")
		(net "M_H_CPU0_SB_DQ<27>")
	)
	(arc
		(start 391.326116 -289.958526)
		(mid 391.509624 -289.913032)
		(end 391.691876 -289.963352)
		(width 0.0889)
		(layer "In13.Cu")
		(net "M_H_CPU0_SB_DQ<27>")
	)
	(segment
		(start 383.988056 -289.209988)
		(end 384.454908 -289.475926)
		(width 0.10668)
		(layer "F.Cu")
		(net "M_H_CPU0_SB_DQ<26>")
	)
	(segment
		(start 405.504142 -308.078124)
		(end 405.275542 -308.078124)
		(width 0.14478)
		(layer "In13.Cu")
		(net "M_H_CPU0_SB_DQ<26>")
	)
	(segment
		(start 412.27883 -310.506872)
		(end 412.030672 -310.506872)
		(width 0.14478)
		(layer "In13.Cu")
		(net "M_H_CPU0_SB_DQ<26>")
	)
	(segment
		(start 404.486364 -306.526438)
		(end 404.32482 -306.364894)
		(width 0.14478)
		(layer "In13.Cu")
		(net "M_H_CPU0_SB_DQ<26>")
	)
	(segment
		(start 405.885396 -307.92547)
		(end 405.656796 -307.92547)
		(width 0.14478)
		(layer "In13.Cu")
		(net "M_H_CPU0_SB_DQ<26>")
	)
	(segment
		(start 415.755836 -309.96001)
		(end 414.940242 -309.96001)
		(width 0.14478)
		(layer "In13.Cu")
		(net "M_H_CPU0_SB_DQ<26>")
	)
	(segment
		(start 393.534646 -289.286696)
		(end 392.641582 -289.286696)
		(width 0.0889)
		(layer "In13.Cu")
		(net "M_H_CPU0_SB_DQ<26>")
	)
	(segment
		(start 407.607516 -309.87619)
		(end 407.607516 -309.64759)
		(width 0.14478)
		(layer "In13.Cu")
		(net "M_H_CPU0_SB_DQ<26>")
	)
	(segment
		(start 414.090104 -310.810148)
		(end 413.684974 -310.810148)
		(width 0.14478)
		(layer "In13.Cu")
		(net "M_H_CPU0_SB_DQ<26>")
	)
	(segment
		(start 413.381698 -310.506872)
		(end 413.13354 -310.506872)
		(width 0.14478)
		(layer "In13.Cu")
		(net "M_H_CPU0_SB_DQ<26>")
	)
	(segment
		(start 384.30073 -289.210496)
		(end 384.454908 -289.475926)
		(width 0.0889)
		(layer "In13.Cu")
		(net "M_H_CPU0_SB_DQ<26>")
	)
	(segment
		(start 406.827228 -309.095902)
		(end 406.827228 -308.867302)
		(width 0.14478)
		(layer "In13.Cu")
		(net "M_H_CPU0_SB_DQ<26>")
	)
	(segment
		(start 410.624528 -310.810148)
		(end 410.37637 -310.810148)
		(width 0.14478)
		(layer "In13.Cu")
		(net "M_H_CPU0_SB_DQ<26>")
	)
	(segment
		(start 404.33371 -306.907692)
		(end 404.486364 -306.755038)
		(width 0.14478)
		(layer "In13.Cu")
		(net "M_H_CPU0_SB_DQ<26>")
	)
	(segment
		(start 407.064718 -309.6387)
		(end 406.836118 -309.6387)
		(width 0.14478)
		(layer "In13.Cu")
		(net "M_H_CPU0_SB_DQ<26>")
	)
	(segment
		(start 405.113998 -307.68798)
		(end 405.266652 -307.535326)
		(width 0.14478)
		(layer "In13.Cu")
		(net "M_H_CPU0_SB_DQ<26>")
	)
	(segment
		(start 403.943566 -306.517548)
		(end 403.714966 -306.517548)
		(width 0.14478)
		(layer "In13.Cu")
		(net "M_H_CPU0_SB_DQ<26>")
	)
	(segment
		(start 405.266652 -307.535326)
		(end 405.266652 -307.306726)
		(width 0.14478)
		(layer "In13.Cu")
		(net "M_H_CPU0_SB_DQ<26>")
	)
	(segment
		(start 405.113998 -307.91658)
		(end 405.113998 -307.68798)
		(width 0.14478)
		(layer "In13.Cu")
		(net "M_H_CPU0_SB_DQ<26>")
	)
	(segment
		(start 418.122608 -309.96001)
		(end 417.690046 -309.96001)
		(width 0.14478)
		(layer "In13.Cu")
		(net "M_H_CPU0_SB_DQ<26>")
	)
	(segment
		(start 410.927804 -310.506872)
		(end 410.624528 -310.810148)
		(width 0.14478)
		(layer "In13.Cu")
		(net "M_H_CPU0_SB_DQ<26>")
	)
	(segment
		(start 406.674574 -309.248556)
		(end 406.827228 -309.095902)
		(width 0.14478)
		(layer "In13.Cu")
		(net "M_H_CPU0_SB_DQ<26>")
	)
	(segment
		(start 397.666718 -300.4693)
		(end 397.666718 -294.051228)
		(width 0.14478)
		(layer "In13.Cu")
		(net "M_H_CPU0_SB_DQ<26>")
	)
	(segment
		(start 409.52166 -310.810148)
		(end 409.273502 -310.810148)
		(width 0.14478)
		(layer "In13.Cu")
		(net "M_H_CPU0_SB_DQ<26>")
	)
	(segment
		(start 404.09622 -306.364894)
		(end 403.943566 -306.517548)
		(width 0.14478)
		(layer "In13.Cu")
		(net "M_H_CPU0_SB_DQ<26>")
	)
	(segment
		(start 404.495254 -307.297836)
		(end 404.33371 -307.136292)
		(width 0.14478)
		(layer "In13.Cu")
		(net "M_H_CPU0_SB_DQ<26>")
	)
	(segment
		(start 409.273502 -310.810148)
		(end 408.970226 -310.506872)
		(width 0.14478)
		(layer "In13.Cu")
		(net "M_H_CPU0_SB_DQ<26>")
	)
	(segment
		(start 404.32482 -306.364894)
		(end 404.09622 -306.364894)
		(width 0.14478)
		(layer "In13.Cu")
		(net "M_H_CPU0_SB_DQ<26>")
	)
	(segment
		(start 409.824936 -310.506872)
		(end 409.52166 -310.810148)
		(width 0.14478)
		(layer "In13.Cu")
		(net "M_H_CPU0_SB_DQ<26>")
	)
	(segment
		(start 395.38402 -291.76853)
		(end 395.123924 -291.76853)
		(width 0.0889)
		(layer "In13.Cu")
		(net "M_H_CPU0_SB_DQ<26>")
	)
	(segment
		(start 394.297154 -290.049204)
		(end 393.534646 -289.286696)
		(width 0.0889)
		(layer "In13.Cu")
		(net "M_H_CPU0_SB_DQ<26>")
	)
	(segment
		(start 404.33371 -307.136292)
		(end 404.33371 -306.907692)
		(width 0.14478)
		(layer "In13.Cu")
		(net "M_H_CPU0_SB_DQ<26>")
	)
	(segment
		(start 406.827228 -308.867302)
		(end 406.665684 -308.705758)
		(width 0.14478)
		(layer "In13.Cu")
		(net "M_H_CPU0_SB_DQ<26>")
	)
	(segment
		(start 406.05583 -308.858412)
		(end 405.894286 -308.696868)
		(width 0.14478)
		(layer "In13.Cu")
		(net "M_H_CPU0_SB_DQ<26>")
	)
	(segment
		(start 405.275542 -308.078124)
		(end 405.113998 -307.91658)
		(width 0.14478)
		(layer "In13.Cu")
		(net "M_H_CPU0_SB_DQ<26>")
	)
	(segment
		(start 403.714966 -306.517548)
		(end 397.666718 -300.4693)
		(width 0.14478)
		(layer "In13.Cu")
		(net "M_H_CPU0_SB_DQ<26>")
	)
	(segment
		(start 413.684974 -310.810148)
		(end 413.381698 -310.506872)
		(width 0.14478)
		(layer "In13.Cu")
		(net "M_H_CPU0_SB_DQ<26>")
	)
	(segment
		(start 419.517068 -310.810148)
		(end 418.972746 -310.810148)
		(width 0.14478)
		(layer "In13.Cu")
		(net "M_H_CPU0_SB_DQ<26>")
	)
	(segment
		(start 410.37637 -310.810148)
		(end 410.073094 -310.506872)
		(width 0.14478)
		(layer "In13.Cu")
		(net "M_H_CPU0_SB_DQ<26>")
	)
	(segment
		(start 405.105108 -307.145182)
		(end 404.876508 -307.145182)
		(width 0.14478)
		(layer "In13.Cu")
		(net "M_H_CPU0_SB_DQ<26>")
	)
	(segment
		(start 389.341868 -289.153346)
		(end 389.333486 -289.14852)
		(width 0.0889)
		(layer "In13.Cu")
		(net "M_H_CPU0_SB_DQ<26>")
	)
	(segment
		(start 408.721814 -310.506872)
		(end 408.418538 -310.810148)
		(width 0.14478)
		(layer "In13.Cu")
		(net "M_H_CPU0_SB_DQ<26>")
	)
	(segment
		(start 419.912038 -310.415178)
		(end 419.517068 -310.810148)
		(width 0.14478)
		(layer "In13.Cu")
		(net "M_H_CPU0_SB_DQ<26>")
	)
	(segment
		(start 406.665684 -308.705758)
		(end 406.437084 -308.705758)
		(width 0.14478)
		(layer "In13.Cu")
		(net "M_H_CPU0_SB_DQ<26>")
	)
	(segment
		(start 407.607516 -309.64759)
		(end 407.445972 -309.486046)
		(width 0.14478)
		(layer "In13.Cu")
		(net "M_H_CPU0_SB_DQ<26>")
	)
	(segment
		(start 405.894286 -308.696868)
		(end 405.894286 -308.468268)
		(width 0.14478)
		(layer "In13.Cu")
		(net "M_H_CPU0_SB_DQ<26>")
	)
	(segment
		(start 411.727396 -310.810148)
		(end 411.479238 -310.810148)
		(width 0.14478)
		(layer "In13.Cu")
		(net "M_H_CPU0_SB_DQ<26>")
	)
	(segment
		(start 405.656796 -307.92547)
		(end 405.504142 -308.078124)
		(width 0.14478)
		(layer "In13.Cu")
		(net "M_H_CPU0_SB_DQ<26>")
	)
	(segment
		(start 413.13354 -310.506872)
		(end 412.830264 -310.810148)
		(width 0.14478)
		(layer "In13.Cu")
		(net "M_H_CPU0_SB_DQ<26>")
	)
	(segment
		(start 385.216146 -289.14852)
		(end 385.207764 -289.153346)
		(width 0.0889)
		(layer "In13.Cu")
		(net "M_H_CPU0_SB_DQ<26>")
	)
	(segment
		(start 406.437084 -308.705758)
		(end 406.28443 -308.858412)
		(width 0.14478)
		(layer "In13.Cu")
		(net "M_H_CPU0_SB_DQ<26>")
	)
	(segment
		(start 412.830264 -310.810148)
		(end 412.582106 -310.810148)
		(width 0.14478)
		(layer "In13.Cu")
		(net "M_H_CPU0_SB_DQ<26>")
	)
	(segment
		(start 408.007566 -310.810148)
		(end 407.454862 -310.257444)
		(width 0.14478)
		(layer "In13.Cu")
		(net "M_H_CPU0_SB_DQ<26>")
	)
	(segment
		(start 404.486364 -306.755038)
		(end 404.486364 -306.526438)
		(width 0.14478)
		(layer "In13.Cu")
		(net "M_H_CPU0_SB_DQ<26>")
	)
	(segment
		(start 406.04694 -308.315614)
		(end 406.04694 -308.087014)
		(width 0.14478)
		(layer "In13.Cu")
		(net "M_H_CPU0_SB_DQ<26>")
	)
	(segment
		(start 416.587686 -309.96001)
		(end 416.307016 -309.67934)
		(width 0.14478)
		(layer "In13.Cu")
		(net "M_H_CPU0_SB_DQ<26>")
	)
	(segment
		(start 405.266652 -307.306726)
		(end 405.105108 -307.145182)
		(width 0.14478)
		(layer "In13.Cu")
		(net "M_H_CPU0_SB_DQ<26>")
	)
	(segment
		(start 406.04694 -308.087014)
		(end 405.885396 -307.92547)
		(width 0.14478)
		(layer "In13.Cu")
		(net "M_H_CPU0_SB_DQ<26>")
	)
	(segment
		(start 394.297154 -290.940998)
		(end 394.297154 -290.049204)
		(width 0.0889)
		(layer "In13.Cu")
		(net "M_H_CPU0_SB_DQ<26>")
	)
	(segment
		(start 407.454862 -310.257444)
		(end 407.454862 -310.028844)
		(width 0.14478)
		(layer "In13.Cu")
		(net "M_H_CPU0_SB_DQ<26>")
	)
	(segment
		(start 407.454862 -310.028844)
		(end 407.607516 -309.87619)
		(width 0.14478)
		(layer "In13.Cu")
		(net "M_H_CPU0_SB_DQ<26>")
	)
	(segment
		(start 412.030672 -310.506872)
		(end 411.727396 -310.810148)
		(width 0.14478)
		(layer "In13.Cu")
		(net "M_H_CPU0_SB_DQ<26>")
	)
	(segment
		(start 419.912038 -310.384952)
		(end 419.912038 -310.415178)
		(width 0.14478)
		(layer "In13.Cu")
		(net "M_H_CPU0_SB_DQ<26>")
	)
	(segment
		(start 412.582106 -310.810148)
		(end 412.27883 -310.506872)
		(width 0.14478)
		(layer "In13.Cu")
		(net "M_H_CPU0_SB_DQ<26>")
	)
	(segment
		(start 416.036506 -309.67934)
		(end 415.755836 -309.96001)
		(width 0.14478)
		(layer "In13.Cu")
		(net "M_H_CPU0_SB_DQ<26>")
	)
	(segment
		(start 395.123924 -291.76853)
		(end 394.454634 -291.320982)
		(width 0.0889)
		(layer "In13.Cu")
		(net "M_H_CPU0_SB_DQ<26>")
	)
	(segment
		(start 414.940242 -309.96001)
		(end 414.090104 -310.810148)
		(width 0.14478)
		(layer "In13.Cu")
		(net "M_H_CPU0_SB_DQ<26>")
	)
	(segment
		(start 408.418538 -310.810148)
		(end 408.007566 -310.810148)
		(width 0.14478)
		(layer "In13.Cu")
		(net "M_H_CPU0_SB_DQ<26>")
	)
	(segment
		(start 397.666718 -294.051228)
		(end 395.837918 -292.222428)
		(width 0.14478)
		(layer "In13.Cu")
		(net "M_H_CPU0_SB_DQ<26>")
	)
	(segment
		(start 404.723854 -307.297836)
		(end 404.495254 -307.297836)
		(width 0.14478)
		(layer "In13.Cu")
		(net "M_H_CPU0_SB_DQ<26>")
	)
	(segment
		(start 407.217372 -309.486046)
		(end 407.064718 -309.6387)
		(width 0.14478)
		(layer "In13.Cu")
		(net "M_H_CPU0_SB_DQ<26>")
	)
	(segment
		(start 395.837918 -292.222428)
		(end 395.38402 -291.76853)
		(width 0.0889)
		(layer "In13.Cu")
		(net "M_H_CPU0_SB_DQ<26>")
	)
	(segment
		(start 408.970226 -310.506872)
		(end 408.721814 -310.506872)
		(width 0.14478)
		(layer "In13.Cu")
		(net "M_H_CPU0_SB_DQ<26>")
	)
	(segment
		(start 417.690046 -309.96001)
		(end 417.409376 -309.67934)
		(width 0.14478)
		(layer "In13.Cu")
		(net "M_H_CPU0_SB_DQ<26>")
	)
	(segment
		(start 388.401814 -289.153346)
		(end 388.393432 -289.14852)
		(width 0.0889)
		(layer "In13.Cu")
		(net "M_H_CPU0_SB_DQ<26>")
	)
	(segment
		(start 407.445972 -309.486046)
		(end 407.217372 -309.486046)
		(width 0.14478)
		(layer "In13.Cu")
		(net "M_H_CPU0_SB_DQ<26>")
	)
	(segment
		(start 384.323082 -289.127184)
		(end 384.30073 -289.210496)
		(width 0.0889)
		(layer "In13.Cu")
		(net "M_H_CPU0_SB_DQ<26>")
	)
	(segment
		(start 410.073094 -310.506872)
		(end 409.824936 -310.506872)
		(width 0.14478)
		(layer "In13.Cu")
		(net "M_H_CPU0_SB_DQ<26>")
	)
	(segment
		(start 404.876508 -307.145182)
		(end 404.723854 -307.297836)
		(width 0.14478)
		(layer "In13.Cu")
		(net "M_H_CPU0_SB_DQ<26>")
	)
	(segment
		(start 411.479238 -310.810148)
		(end 411.175962 -310.506872)
		(width 0.14478)
		(layer "In13.Cu")
		(net "M_H_CPU0_SB_DQ<26>")
	)
	(segment
		(start 416.858196 -309.96001)
		(end 416.587686 -309.96001)
		(width 0.14478)
		(layer "In13.Cu")
		(net "M_H_CPU0_SB_DQ<26>")
	)
	(segment
		(start 386.1562 -289.14852)
		(end 386.147818 -289.153346)
		(width 0.0889)
		(layer "In13.Cu")
		(net "M_H_CPU0_SB_DQ<26>")
	)
	(segment
		(start 411.175962 -310.506872)
		(end 410.927804 -310.506872)
		(width 0.14478)
		(layer "In13.Cu")
		(net "M_H_CPU0_SB_DQ<26>")
	)
	(segment
		(start 416.307016 -309.67934)
		(end 416.036506 -309.67934)
		(width 0.14478)
		(layer "In13.Cu")
		(net "M_H_CPU0_SB_DQ<26>")
	)
	(segment
		(start 406.674574 -309.477156)
		(end 406.674574 -309.248556)
		(width 0.14478)
		(layer "In13.Cu")
		(net "M_H_CPU0_SB_DQ<26>")
	)
	(segment
		(start 417.138866 -309.67934)
		(end 416.858196 -309.96001)
		(width 0.14478)
		(layer "In13.Cu")
		(net "M_H_CPU0_SB_DQ<26>")
	)
	(segment
		(start 384.641852 -289.153346)
		(end 384.63347 -289.14852)
		(width 0.0889)
		(layer "In13.Cu")
		(net "M_H_CPU0_SB_DQ<26>")
	)
	(segment
		(start 406.836118 -309.6387)
		(end 406.674574 -309.477156)
		(width 0.14478)
		(layer "In13.Cu")
		(net "M_H_CPU0_SB_DQ<26>")
	)
	(segment
		(start 417.409376 -309.67934)
		(end 417.138866 -309.67934)
		(width 0.14478)
		(layer "In13.Cu")
		(net "M_H_CPU0_SB_DQ<26>")
	)
	(segment
		(start 418.972746 -310.810148)
		(end 418.122608 -309.96001)
		(width 0.14478)
		(layer "In13.Cu")
		(net "M_H_CPU0_SB_DQ<26>")
	)
	(segment
		(start 389.916162 -289.14852)
		(end 389.90778 -289.153346)
		(width 0.0889)
		(layer "In13.Cu")
		(net "M_H_CPU0_SB_DQ<26>")
	)
	(segment
		(start 406.28443 -308.858412)
		(end 406.05583 -308.858412)
		(width 0.14478)
		(layer "In13.Cu")
		(net "M_H_CPU0_SB_DQ<26>")
	)
	(segment
		(start 394.454634 -291.320982)
		(end 394.297154 -290.940998)
		(width 0.0889)
		(layer "In13.Cu")
		(net "M_H_CPU0_SB_DQ<26>")
	)
	(segment
		(start 405.894286 -308.468268)
		(end 406.04694 -308.315614)
		(width 0.14478)
		(layer "In13.Cu")
		(net "M_H_CPU0_SB_DQ<26>")
	)
	(arc
		(start 387.46176 -289.153346)
		(mid 387.274816 -289.103091)
		(end 387.087872 -289.153346)
		(width 0.0889)
		(layer "In13.Cu")
		(net "M_H_CPU0_SB_DQ<26>")
	)
	(arc
		(start 388.027672 -289.153346)
		(mid 387.744716 -289.229523)
		(end 387.46176 -289.153346)
		(width 0.0889)
		(layer "In13.Cu")
		(net "M_H_CPU0_SB_DQ<26>")
	)
	(arc
		(start 389.333486 -289.14852)
		(mid 389.149978 -289.103026)
		(end 388.967726 -289.153346)
		(width 0.0889)
		(layer "In13.Cu")
		(net "M_H_CPU0_SB_DQ<26>")
	)
	(arc
		(start 390.281922 -289.153346)
		(mid 390.099671 -289.102996)
		(end 389.916162 -289.14852)
		(width 0.0889)
		(layer "In13.Cu")
		(net "M_H_CPU0_SB_DQ<26>")
	)
	(arc
		(start 385.207764 -289.153346)
		(mid 384.924808 -289.229523)
		(end 384.641852 -289.153346)
		(width 0.0889)
		(layer "In13.Cu")
		(net "M_H_CPU0_SB_DQ<26>")
	)
	(arc
		(start 392.641582 -289.286696)
		(mid 392.384697 -289.237187)
		(end 392.140948 -289.14217)
		(width 0.0889)
		(layer "In13.Cu")
		(net "M_H_CPU0_SB_DQ<26>")
	)
	(arc
		(start 387.087872 -289.153346)
		(mid 386.804916 -289.229523)
		(end 386.52196 -289.153346)
		(width 0.0889)
		(layer "In13.Cu")
		(net "M_H_CPU0_SB_DQ<26>")
	)
	(arc
		(start 388.393432 -289.14852)
		(mid 388.209924 -289.103026)
		(end 388.027672 -289.153346)
		(width 0.0889)
		(layer "In13.Cu")
		(net "M_H_CPU0_SB_DQ<26>")
	)
	(arc
		(start 384.63347 -289.14852)
		(mid 384.4806 -289.103879)
		(end 384.323082 -289.127184)
		(width 0.0889)
		(layer "In13.Cu")
		(net "M_H_CPU0_SB_DQ<26>")
	)
	(arc
		(start 385.581906 -289.153346)
		(mid 385.399655 -289.102996)
		(end 385.216146 -289.14852)
		(width 0.0889)
		(layer "In13.Cu")
		(net "M_H_CPU0_SB_DQ<26>")
	)
	(arc
		(start 386.52196 -289.153346)
		(mid 386.339709 -289.102996)
		(end 386.1562 -289.14852)
		(width 0.0889)
		(layer "In13.Cu")
		(net "M_H_CPU0_SB_DQ<26>")
	)
	(arc
		(start 391.787634 -289.153346)
		(mid 391.504678 -289.229523)
		(end 391.221722 -289.153346)
		(width 0.0889)
		(layer "In13.Cu")
		(net "M_H_CPU0_SB_DQ<26>")
	)
	(arc
		(start 389.90778 -289.153346)
		(mid 389.624824 -289.229523)
		(end 389.341868 -289.153346)
		(width 0.0889)
		(layer "In13.Cu")
		(net "M_H_CPU0_SB_DQ<26>")
	)
	(arc
		(start 392.140948 -289.14217)
		(mid 391.96287 -289.103186)
		(end 391.787634 -289.153346)
		(width 0.0889)
		(layer "In13.Cu")
		(net "M_H_CPU0_SB_DQ<26>")
	)
	(arc
		(start 388.967726 -289.153346)
		(mid 388.68477 -289.229523)
		(end 388.401814 -289.153346)
		(width 0.0889)
		(layer "In13.Cu")
		(net "M_H_CPU0_SB_DQ<26>")
	)
	(arc
		(start 391.221722 -289.153346)
		(mid 391.034778 -289.103091)
		(end 390.847834 -289.153346)
		(width 0.0889)
		(layer "In13.Cu")
		(net "M_H_CPU0_SB_DQ<26>")
	)
	(arc
		(start 386.147818 -289.153346)
		(mid 385.864862 -289.229523)
		(end 385.581906 -289.153346)
		(width 0.0889)
		(layer "In13.Cu")
		(net "M_H_CPU0_SB_DQ<26>")
	)
	(arc
		(start 390.847834 -289.153346)
		(mid 390.564878 -289.229523)
		(end 390.281922 -289.153346)
		(width 0.0889)
		(layer "In13.Cu")
		(net "M_H_CPU0_SB_DQ<26>")
	)
	(segment
		(start 382.107948 -289.209988)
		(end 382.5748 -289.475926)
		(width 0.10668)
		(layer "F.Cu")
		(net "M_H_CPU0_SB_DQ<25>")
	)
	(segment
		(start 394.076174 -290.127182)
		(end 393.563348 -289.614356)
		(width 0.0889)
		(layer "In13.Cu")
		(net "M_H_CPU0_SB_DQ<25>")
	)
	(segment
		(start 395.245844 -292.119558)
		(end 394.297408 -291.486082)
		(width 0.0889)
		(layer "In13.Cu")
		(net "M_H_CPU0_SB_DQ<25>")
	)
	(segment
		(start 395.823694 -292.851586)
		(end 395.422882 -292.450774)
		(width 0.0889)
		(layer "In13.Cu")
		(net "M_H_CPU0_SB_DQ<25>")
	)
	(segment
		(start 397.217138 -294.24503)
		(end 395.823694 -292.851586)
		(width 0.14478)
		(layer "In13.Cu")
		(net "M_H_CPU0_SB_DQ<25>")
	)
	(segment
		(start 413.213296 -311.660032)
		(end 408.221434 -311.660032)
		(width 0.14478)
		(layer "In13.Cu")
		(net "M_H_CPU0_SB_DQ<25>")
	)
	(segment
		(start 417.134548 -310.810148)
		(end 415.265108 -310.810148)
		(width 0.14478)
		(layer "In13.Cu")
		(net "M_H_CPU0_SB_DQ<25>")
	)
	(segment
		(start 394.076174 -290.952174)
		(end 394.076174 -290.127182)
		(width 0.0889)
		(layer "In13.Cu")
		(net "M_H_CPU0_SB_DQ<25>")
	)
	(segment
		(start 393.563348 -289.614356)
		(end 392.737848 -289.614356)
		(width 0.0889)
		(layer "In13.Cu")
		(net "M_H_CPU0_SB_DQ<25>")
	)
	(segment
		(start 392.503152 -289.849052)
		(end 391.974832 -289.849052)
		(width 0.0889)
		(layer "In13.Cu")
		(net "M_H_CPU0_SB_DQ<25>")
	)
	(segment
		(start 386.1562 -289.803332)
		(end 386.147818 -289.798506)
		(width 0.0889)
		(layer "In13.Cu")
		(net "M_H_CPU0_SB_DQ<25>")
	)
	(segment
		(start 382.824736 -289.766756)
		(end 382.728724 -289.741356)
		(width 0.0889)
		(layer "In13.Cu")
		(net "M_H_CPU0_SB_DQ<25>")
	)
	(segment
		(start 382.728724 -289.741356)
		(end 382.5748 -289.475926)
		(width 0.0889)
		(layer "In13.Cu")
		(net "M_H_CPU0_SB_DQ<25>")
	)
	(segment
		(start 421.146478 -311.660032)
		(end 419.18636 -311.660032)
		(width 0.14478)
		(layer "In13.Cu")
		(net "M_H_CPU0_SB_DQ<25>")
	)
	(segment
		(start 397.217138 -300.655736)
		(end 397.217138 -294.24503)
		(width 0.14478)
		(layer "In13.Cu")
		(net "M_H_CPU0_SB_DQ<25>")
	)
	(segment
		(start 392.737848 -289.614356)
		(end 392.503152 -289.849052)
		(width 0.0889)
		(layer "In13.Cu")
		(net "M_H_CPU0_SB_DQ<25>")
	)
	(segment
		(start 385.216146 -289.803332)
		(end 385.207764 -289.798506)
		(width 0.0889)
		(layer "In13.Cu")
		(net "M_H_CPU0_SB_DQ<25>")
	)
	(segment
		(start 395.422882 -292.450774)
		(end 395.245844 -292.119558)
		(width 0.0889)
		(layer "In13.Cu")
		(net "M_H_CPU0_SB_DQ<25>")
	)
	(segment
		(start 408.221434 -311.660032)
		(end 397.217138 -300.655736)
		(width 0.14478)
		(layer "In13.Cu")
		(net "M_H_CPU0_SB_DQ<25>")
	)
	(segment
		(start 383.701798 -289.798506)
		(end 383.693416 -289.803332)
		(width 0.0889)
		(layer "In13.Cu")
		(net "M_H_CPU0_SB_DQ<25>")
	)
	(segment
		(start 415.265108 -310.810148)
		(end 413.213296 -311.660032)
		(width 0.14478)
		(layer "In13.Cu")
		(net "M_H_CPU0_SB_DQ<25>")
	)
	(segment
		(start 388.401814 -289.798506)
		(end 388.393432 -289.803332)
		(width 0.0889)
		(layer "In13.Cu")
		(net "M_H_CPU0_SB_DQ<25>")
	)
	(segment
		(start 384.641852 -289.798506)
		(end 384.63347 -289.803332)
		(width 0.0889)
		(layer "In13.Cu")
		(net "M_H_CPU0_SB_DQ<25>")
	)
	(segment
		(start 394.297408 -291.486082)
		(end 394.076174 -290.952174)
		(width 0.0889)
		(layer "In13.Cu")
		(net "M_H_CPU0_SB_DQ<25>")
	)
	(segment
		(start 389.916162 -289.803332)
		(end 389.90778 -289.798506)
		(width 0.0889)
		(layer "In13.Cu")
		(net "M_H_CPU0_SB_DQ<25>")
	)
	(segment
		(start 419.18636 -311.660032)
		(end 417.134548 -310.810148)
		(width 0.14478)
		(layer "In13.Cu")
		(net "M_H_CPU0_SB_DQ<25>")
	)
	(segment
		(start 424.012106 -311.23509)
		(end 421.146478 -311.660032)
		(width 0.14478)
		(layer "In13.Cu")
		(net "M_H_CPU0_SB_DQ<25>")
	)
	(segment
		(start 389.341868 -289.798506)
		(end 389.333486 -289.803332)
		(width 0.0889)
		(layer "In13.Cu")
		(net "M_H_CPU0_SB_DQ<25>")
	)
	(arc
		(start 391.221722 -289.798506)
		(mid 391.034778 -289.848761)
		(end 390.847834 -289.798506)
		(width 0.0889)
		(layer "In13.Cu")
		(net "M_H_CPU0_SB_DQ<25>")
	)
	(arc
		(start 389.333486 -289.803332)
		(mid 389.149978 -289.848826)
		(end 388.967726 -289.798506)
		(width 0.0889)
		(layer "In13.Cu")
		(net "M_H_CPU0_SB_DQ<25>")
	)
	(arc
		(start 388.027672 -289.798506)
		(mid 387.744716 -289.722329)
		(end 387.46176 -289.798506)
		(width 0.0889)
		(layer "In13.Cu")
		(net "M_H_CPU0_SB_DQ<25>")
	)
	(arc
		(start 383.693416 -289.803332)
		(mid 383.509908 -289.848826)
		(end 383.327656 -289.798506)
		(width 0.0889)
		(layer "In13.Cu")
		(net "M_H_CPU0_SB_DQ<25>")
	)
	(arc
		(start 385.207764 -289.798506)
		(mid 384.924808 -289.722329)
		(end 384.641852 -289.798506)
		(width 0.0889)
		(layer "In13.Cu")
		(net "M_H_CPU0_SB_DQ<25>")
	)
	(arc
		(start 389.90778 -289.798506)
		(mid 389.624824 -289.722329)
		(end 389.341868 -289.798506)
		(width 0.0889)
		(layer "In13.Cu")
		(net "M_H_CPU0_SB_DQ<25>")
	)
	(arc
		(start 387.087872 -289.798506)
		(mid 386.804916 -289.722329)
		(end 386.52196 -289.798506)
		(width 0.0889)
		(layer "In13.Cu")
		(net "M_H_CPU0_SB_DQ<25>")
	)
	(arc
		(start 386.52196 -289.798506)
		(mid 386.339709 -289.848856)
		(end 386.1562 -289.803332)
		(width 0.0889)
		(layer "In13.Cu")
		(net "M_H_CPU0_SB_DQ<25>")
	)
	(arc
		(start 388.393432 -289.803332)
		(mid 388.209924 -289.848826)
		(end 388.027672 -289.798506)
		(width 0.0889)
		(layer "In13.Cu")
		(net "M_H_CPU0_SB_DQ<25>")
	)
	(arc
		(start 391.787634 -289.798506)
		(mid 391.504678 -289.722329)
		(end 391.221722 -289.798506)
		(width 0.0889)
		(layer "In13.Cu")
		(net "M_H_CPU0_SB_DQ<25>")
	)
	(arc
		(start 384.26771 -289.798506)
		(mid 383.984754 -289.722329)
		(end 383.701798 -289.798506)
		(width 0.0889)
		(layer "In13.Cu")
		(net "M_H_CPU0_SB_DQ<25>")
	)
	(arc
		(start 384.63347 -289.803332)
		(mid 384.449962 -289.848826)
		(end 384.26771 -289.798506)
		(width 0.0889)
		(layer "In13.Cu")
		(net "M_H_CPU0_SB_DQ<25>")
	)
	(arc
		(start 385.581906 -289.798506)
		(mid 385.399655 -289.848856)
		(end 385.216146 -289.803332)
		(width 0.0889)
		(layer "In13.Cu")
		(net "M_H_CPU0_SB_DQ<25>")
	)
	(arc
		(start 383.327656 -289.798506)
		(mid 383.079943 -289.723286)
		(end 382.824736 -289.766756)
		(width 0.0889)
		(layer "In13.Cu")
		(net "M_H_CPU0_SB_DQ<25>")
	)
	(arc
		(start 387.46176 -289.798506)
		(mid 387.274816 -289.848761)
		(end 387.087872 -289.798506)
		(width 0.0889)
		(layer "In13.Cu")
		(net "M_H_CPU0_SB_DQ<25>")
	)
	(arc
		(start 386.147818 -289.798506)
		(mid 385.864862 -289.722329)
		(end 385.581906 -289.798506)
		(width 0.0889)
		(layer "In13.Cu")
		(net "M_H_CPU0_SB_DQ<25>")
	)
	(arc
		(start 391.974832 -289.849052)
		(mid 391.87789 -289.836161)
		(end 391.787634 -289.798506)
		(width 0.0889)
		(layer "In13.Cu")
		(net "M_H_CPU0_SB_DQ<25>")
	)
	(arc
		(start 390.281922 -289.798506)
		(mid 390.099671 -289.848856)
		(end 389.916162 -289.803332)
		(width 0.0889)
		(layer "In13.Cu")
		(net "M_H_CPU0_SB_DQ<25>")
	)
	(arc
		(start 388.967726 -289.798506)
		(mid 388.68477 -289.722329)
		(end 388.401814 -289.798506)
		(width 0.0889)
		(layer "In13.Cu")
		(net "M_H_CPU0_SB_DQ<25>")
	)
	(arc
		(start 390.847834 -289.798506)
		(mid 390.564878 -289.722329)
		(end 390.281922 -289.798506)
		(width 0.0889)
		(layer "In13.Cu")
		(net "M_H_CPU0_SB_DQ<25>")
	)
	(segment
		(start 383.517902 -288.399982)
		(end 383.984754 -288.66592)
		(width 0.10668)
		(layer "F.Cu")
		(net "M_H_CPU0_SB_DQ<24>")
	)
	(segment
		(start 402.600668 -304.014886)
		(end 402.415248 -303.829466)
		(width 0.14478)
		(layer "In13.Cu")
		(net "M_H_CPU0_SB_DQ<24>")
	)
	(segment
		(start 387.566154 -288.993326)
		(end 387.565138 -288.992818)
		(width 0.0889)
		(layer "In13.Cu")
		(net "M_H_CPU0_SB_DQ<24>")
	)
	(segment
		(start 424.012106 -309.535068)
		(end 422.152064 -309.535068)
		(width 0.14478)
		(layer "In13.Cu")
		(net "M_H_CPU0_SB_DQ<24>")
	)
	(segment
		(start 401.834858 -304.00117)
		(end 398.116298 -300.28261)
		(width 0.14478)
		(layer "In13.Cu")
		(net "M_H_CPU0_SB_DQ<24>")
	)
	(segment
		(start 394.543534 -291.00399)
		(end 394.543534 -290.003484)
		(width 0.0889)
		(layer "In13.Cu")
		(net "M_H_CPU0_SB_DQ<24>")
	)
	(segment
		(start 392.555222 -289.04311)
		(end 392.453876 -289.033204)
		(width 0.0889)
		(layer "In13.Cu")
		(net "M_H_CPU0_SB_DQ<24>")
	)
	(segment
		(start 415.032952 -309.110126)
		(end 414.183068 -309.96001)
		(width 0.14478)
		(layer "In13.Cu")
		(net "M_H_CPU0_SB_DQ<24>")
	)
	(segment
		(start 404.246334 -305.585114)
		(end 403.418802 -305.585114)
		(width 0.14478)
		(layer "In13.Cu")
		(net "M_H_CPU0_SB_DQ<24>")
	)
	(segment
		(start 402.429472 -304.595784)
		(end 402.429218 -304.39106)
		(width 0.14478)
		(layer "In13.Cu")
		(net "M_H_CPU0_SB_DQ<24>")
	)
	(segment
		(start 394.543534 -290.003484)
		(end 393.58316 -289.04311)
		(width 0.0889)
		(layer "In13.Cu")
		(net "M_H_CPU0_SB_DQ<24>")
	)
	(segment
		(start 384.138932 -288.93135)
		(end 383.984754 -288.66592)
		(width 0.0889)
		(layer "In13.Cu")
		(net "M_H_CPU0_SB_DQ<24>")
	)
	(segment
		(start 395.613128 -291.35451)
		(end 394.894054 -291.35451)
		(width 0.0889)
		(layer "In13.Cu")
		(net "M_H_CPU0_SB_DQ<24>")
	)
	(segment
		(start 398.116298 -300.28261)
		(end 398.116298 -293.85768)
		(width 0.14478)
		(layer "In13.Cu")
		(net "M_H_CPU0_SB_DQ<24>")
	)
	(segment
		(start 390.751822 -288.9885)
		(end 390.74344 -288.993326)
		(width 0.0889)
		(layer "In13.Cu")
		(net "M_H_CPU0_SB_DQ<24>")
	)
	(segment
		(start 386.99186 -288.9885)
		(end 386.983478 -288.993326)
		(width 0.0889)
		(layer "In13.Cu")
		(net "M_H_CPU0_SB_DQ<24>")
	)
	(segment
		(start 387.565138 -288.992818)
		(end 387.557772 -288.9885)
		(width 0.0889)
		(layer "In13.Cu")
		(net "M_H_CPU0_SB_DQ<24>")
	)
	(segment
		(start 393.58316 -289.04311)
		(end 392.555222 -289.04311)
		(width 0.0889)
		(layer "In13.Cu")
		(net "M_H_CPU0_SB_DQ<24>")
	)
	(segment
		(start 402.415248 -303.829466)
		(end 402.211032 -303.82972)
		(width 0.14478)
		(layer "In13.Cu")
		(net "M_H_CPU0_SB_DQ<24>")
	)
	(segment
		(start 403.380448 -304.99939)
		(end 403.380448 -304.794666)
		(width 0.14478)
		(layer "In13.Cu")
		(net "M_H_CPU0_SB_DQ<24>")
	)
	(segment
		(start 414.183068 -309.96001)
		(end 408.62123 -309.96001)
		(width 0.14478)
		(layer "In13.Cu")
		(net "M_H_CPU0_SB_DQ<24>")
	)
	(segment
		(start 391.326116 -288.993326)
		(end 391.317734 -288.9885)
		(width 0.0889)
		(layer "In13.Cu")
		(net "M_H_CPU0_SB_DQ<24>")
	)
	(segment
		(start 421.727122 -309.96001)
		(end 418.907468 -309.96001)
		(width 0.14478)
		(layer "In13.Cu")
		(net "M_H_CPU0_SB_DQ<24>")
	)
	(segment
		(start 402.429218 -304.39106)
		(end 402.600668 -304.21961)
		(width 0.14478)
		(layer "In13.Cu")
		(net "M_H_CPU0_SB_DQ<24>")
	)
	(segment
		(start 386.051806 -288.9885)
		(end 386.043424 -288.993326)
		(width 0.0889)
		(layer "In13.Cu")
		(net "M_H_CPU0_SB_DQ<24>")
	)
	(segment
		(start 402.600668 -304.21961)
		(end 402.600668 -304.014886)
		(width 0.14478)
		(layer "In13.Cu")
		(net "M_H_CPU0_SB_DQ<24>")
	)
	(segment
		(start 422.152064 -309.535068)
		(end 421.727122 -309.96001)
		(width 0.14478)
		(layer "In13.Cu")
		(net "M_H_CPU0_SB_DQ<24>")
	)
	(segment
		(start 418.057584 -309.110126)
		(end 415.032952 -309.110126)
		(width 0.14478)
		(layer "In13.Cu")
		(net "M_H_CPU0_SB_DQ<24>")
	)
	(segment
		(start 388.506208 -288.993326)
		(end 388.497826 -288.9885)
		(width 0.0889)
		(layer "In13.Cu")
		(net "M_H_CPU0_SB_DQ<24>")
	)
	(segment
		(start 402.990812 -304.6095)
		(end 402.819362 -304.78095)
		(width 0.14478)
		(layer "In13.Cu")
		(net "M_H_CPU0_SB_DQ<24>")
	)
	(segment
		(start 384.235198 -288.95675)
		(end 384.138932 -288.93135)
		(width 0.0889)
		(layer "In13.Cu")
		(net "M_H_CPU0_SB_DQ<24>")
	)
	(segment
		(start 418.907468 -309.96001)
		(end 418.057584 -309.110126)
		(width 0.14478)
		(layer "In13.Cu")
		(net "M_H_CPU0_SB_DQ<24>")
	)
	(segment
		(start 403.195028 -304.609246)
		(end 402.990812 -304.6095)
		(width 0.14478)
		(layer "In13.Cu")
		(net "M_H_CPU0_SB_DQ<24>")
	)
	(segment
		(start 402.614638 -304.78095)
		(end 402.429472 -304.595784)
		(width 0.14478)
		(layer "In13.Cu")
		(net "M_H_CPU0_SB_DQ<24>")
	)
	(segment
		(start 403.208998 -305.17084)
		(end 403.380448 -304.99939)
		(width 0.14478)
		(layer "In13.Cu")
		(net "M_H_CPU0_SB_DQ<24>")
	)
	(segment
		(start 408.62123 -309.96001)
		(end 404.246334 -305.585114)
		(width 0.14478)
		(layer "In13.Cu")
		(net "M_H_CPU0_SB_DQ<24>")
	)
	(segment
		(start 402.039582 -304.00117)
		(end 401.834858 -304.00117)
		(width 0.14478)
		(layer "In13.Cu")
		(net "M_H_CPU0_SB_DQ<24>")
	)
	(segment
		(start 403.380448 -304.794666)
		(end 403.195028 -304.609246)
		(width 0.14478)
		(layer "In13.Cu")
		(net "M_H_CPU0_SB_DQ<24>")
	)
	(segment
		(start 398.116298 -293.85768)
		(end 395.834616 -291.575998)
		(width 0.14478)
		(layer "In13.Cu")
		(net "M_H_CPU0_SB_DQ<24>")
	)
	(segment
		(start 394.894054 -291.35451)
		(end 394.543534 -291.00399)
		(width 0.0889)
		(layer "In13.Cu")
		(net "M_H_CPU0_SB_DQ<24>")
	)
	(segment
		(start 403.418802 -305.585114)
		(end 403.209252 -305.375564)
		(width 0.14478)
		(layer "In13.Cu")
		(net "M_H_CPU0_SB_DQ<24>")
	)
	(segment
		(start 403.209252 -305.375564)
		(end 403.208998 -305.17084)
		(width 0.14478)
		(layer "In13.Cu")
		(net "M_H_CPU0_SB_DQ<24>")
	)
	(segment
		(start 395.834616 -291.575998)
		(end 395.613128 -291.35451)
		(width 0.0889)
		(layer "In13.Cu")
		(net "M_H_CPU0_SB_DQ<24>")
	)
	(segment
		(start 402.819362 -304.78095)
		(end 402.614638 -304.78095)
		(width 0.14478)
		(layer "In13.Cu")
		(net "M_H_CPU0_SB_DQ<24>")
	)
	(segment
		(start 392.453876 -289.033204)
		(end 392.234674 -288.9758)
		(width 0.0889)
		(layer "In13.Cu")
		(net "M_H_CPU0_SB_DQ<24>")
	)
	(segment
		(start 402.211032 -303.82972)
		(end 402.039582 -304.00117)
		(width 0.14478)
		(layer "In13.Cu")
		(net "M_H_CPU0_SB_DQ<24>")
	)
	(arc
		(start 391.317734 -288.9885)
		(mid 391.034778 -288.912323)
		(end 390.751822 -288.9885)
		(width 0.0889)
		(layer "In13.Cu")
		(net "M_H_CPU0_SB_DQ<24>")
	)
	(arc
		(start 385.677664 -288.9885)
		(mid 385.394708 -288.912323)
		(end 385.111752 -288.9885)
		(width 0.0889)
		(layer "In13.Cu")
		(net "M_H_CPU0_SB_DQ<24>")
	)
	(arc
		(start 389.43788 -288.9885)
		(mid 389.154924 -288.912323)
		(end 388.871968 -288.9885)
		(width 0.0889)
		(layer "In13.Cu")
		(net "M_H_CPU0_SB_DQ<24>")
	)
	(arc
		(start 390.74344 -288.993326)
		(mid 390.559932 -289.03882)
		(end 390.37768 -288.9885)
		(width 0.0889)
		(layer "In13.Cu")
		(net "M_H_CPU0_SB_DQ<24>")
	)
	(arc
		(start 386.983478 -288.993326)
		(mid 386.79997 -289.03882)
		(end 386.617718 -288.9885)
		(width 0.0889)
		(layer "In13.Cu")
		(net "M_H_CPU0_SB_DQ<24>")
	)
	(arc
		(start 390.37768 -288.9885)
		(mid 390.094724 -288.912323)
		(end 389.811768 -288.9885)
		(width 0.0889)
		(layer "In13.Cu")
		(net "M_H_CPU0_SB_DQ<24>")
	)
	(arc
		(start 387.557772 -288.9885)
		(mid 387.274816 -288.912323)
		(end 386.99186 -288.9885)
		(width 0.0889)
		(layer "In13.Cu")
		(net "M_H_CPU0_SB_DQ<24>")
	)
	(arc
		(start 386.043424 -288.993326)
		(mid 385.859916 -289.03882)
		(end 385.677664 -288.9885)
		(width 0.0889)
		(layer "In13.Cu")
		(net "M_H_CPU0_SB_DQ<24>")
	)
	(arc
		(start 389.811768 -288.9885)
		(mid 389.624824 -289.038755)
		(end 389.43788 -288.9885)
		(width 0.0889)
		(layer "In13.Cu")
		(net "M_H_CPU0_SB_DQ<24>")
	)
	(arc
		(start 385.111752 -288.9885)
		(mid 384.924808 -289.038755)
		(end 384.737864 -288.9885)
		(width 0.0889)
		(layer "In13.Cu")
		(net "M_H_CPU0_SB_DQ<24>")
	)
	(arc
		(start 391.691876 -288.9885)
		(mid 391.509625 -289.03885)
		(end 391.326116 -288.993326)
		(width 0.0889)
		(layer "In13.Cu")
		(net "M_H_CPU0_SB_DQ<24>")
	)
	(arc
		(start 392.234674 -288.9758)
		(mid 391.961645 -288.912481)
		(end 391.691876 -288.9885)
		(width 0.0889)
		(layer "In13.Cu")
		(net "M_H_CPU0_SB_DQ<24>")
	)
	(arc
		(start 384.737864 -288.9885)
		(mid 384.490268 -288.913322)
		(end 384.235198 -288.95675)
		(width 0.0889)
		(layer "In13.Cu")
		(net "M_H_CPU0_SB_DQ<24>")
	)
	(arc
		(start 387.931914 -288.9885)
		(mid 387.749663 -289.03885)
		(end 387.566154 -288.993326)
		(width 0.0889)
		(layer "In13.Cu")
		(net "M_H_CPU0_SB_DQ<24>")
	)
	(arc
		(start 386.617718 -288.9885)
		(mid 386.334762 -288.912323)
		(end 386.051806 -288.9885)
		(width 0.0889)
		(layer "In13.Cu")
		(net "M_H_CPU0_SB_DQ<24>")
	)
	(arc
		(start 388.497826 -288.9885)
		(mid 388.21487 -288.912323)
		(end 387.931914 -288.9885)
		(width 0.0889)
		(layer "In13.Cu")
		(net "M_H_CPU0_SB_DQ<24>")
	)
	(arc
		(start 388.871968 -288.9885)
		(mid 388.689717 -289.03885)
		(end 388.506208 -288.993326)
		(width 0.0889)
		(layer "In13.Cu")
		(net "M_H_CPU0_SB_DQ<24>")
	)
	(segment
		(start 382.577848 -288.399982)
		(end 383.0447 -288.66592)
		(width 0.10668)
		(layer "F.Cu")
		(net "M_H_CPU0_SB_DQ<23>")
	)
	(segment
		(start 387.557772 -288.343594)
		(end 387.566154 -288.338768)
		(width 0.0889)
		(layer "In13.Cu")
		(net "M_H_CPU0_SB_DQ<23>")
	)
	(segment
		(start 409.628086 -308.9656)
		(end 409.628086 -308.577742)
		(width 0.14478)
		(layer "In13.Cu")
		(net "M_H_CPU0_SB_DQ<23>")
	)
	(segment
		(start 411.136846 -308.652164)
		(end 411.281626 -308.796944)
		(width 0.14478)
		(layer "In13.Cu")
		(net "M_H_CPU0_SB_DQ<23>")
	)
	(segment
		(start 410.324046 -309.110126)
		(end 410.585666 -309.110126)
		(width 0.14478)
		(layer "In13.Cu")
		(net "M_H_CPU0_SB_DQ<23>")
	)
	(segment
		(start 395.829536 -290.783772)
		(end 398.667478 -293.621714)
		(width 0.14478)
		(layer "In13.Cu")
		(net "M_H_CPU0_SB_DQ<23>")
	)
	(segment
		(start 386.983478 -288.338768)
		(end 386.99186 -288.343594)
		(width 0.0889)
		(layer "In13.Cu")
		(net "M_H_CPU0_SB_DQ<23>")
	)
	(segment
		(start 409.628086 -308.577742)
		(end 409.772866 -308.432962)
		(width 0.14478)
		(layer "In13.Cu")
		(net "M_H_CPU0_SB_DQ<23>")
	)
	(segment
		(start 408.504644 -308.163976)
		(end 408.68981 -308.349142)
		(width 0.14478)
		(layer "In13.Cu")
		(net "M_H_CPU0_SB_DQ<23>")
	)
	(segment
		(start 393.956794 -288.719768)
		(end 393.956794 -289.111944)
		(width 0.0889)
		(layer "In13.Cu")
		(net "M_H_CPU0_SB_DQ<23>")
	)
	(segment
		(start 408.68981 -308.349142)
		(end 408.68981 -308.553866)
		(width 0.14478)
		(layer "In13.Cu")
		(net "M_H_CPU0_SB_DQ<23>")
	)
	(segment
		(start 410.875226 -308.652164)
		(end 411.136846 -308.652164)
		(width 0.14478)
		(layer "In13.Cu")
		(net "M_H_CPU0_SB_DQ<23>")
	)
	(segment
		(start 411.832806 -308.9656)
		(end 411.832806 -308.900322)
		(width 0.14478)
		(layer "In13.Cu")
		(net "M_H_CPU0_SB_DQ<23>")
	)
	(segment
		(start 412.790386 -309.11038)
		(end 412.935166 -308.9656)
		(width 0.14478)
		(layer "In13.Cu")
		(net "M_H_CPU0_SB_DQ<23>")
	)
	(segment
		(start 411.426406 -309.11038)
		(end 411.688026 -309.11038)
		(width 0.14478)
		(layer "In13.Cu")
		(net "M_H_CPU0_SB_DQ<23>")
	)
	(segment
		(start 410.730446 -308.796944)
		(end 410.875226 -308.652164)
		(width 0.14478)
		(layer "In13.Cu")
		(net "M_H_CPU0_SB_DQ<23>")
	)
	(segment
		(start 408.628342 -309.11038)
		(end 409.483306 -309.11038)
		(width 0.14478)
		(layer "In13.Cu")
		(net "M_H_CPU0_SB_DQ<23>")
	)
	(segment
		(start 386.043424 -288.338768)
		(end 386.051806 -288.343594)
		(width 0.0889)
		(layer "In13.Cu")
		(net "M_H_CPU0_SB_DQ<23>")
	)
	(segment
		(start 409.772866 -308.432962)
		(end 410.034486 -308.432962)
		(width 0.14478)
		(layer "In13.Cu")
		(net "M_H_CPU0_SB_DQ<23>")
	)
	(segment
		(start 414.090104 -309.11038)
		(end 414.940242 -308.260242)
		(width 0.14478)
		(layer "In13.Cu")
		(net "M_H_CPU0_SB_DQ<23>")
	)
	(segment
		(start 413.486346 -308.9656)
		(end 413.631126 -309.11038)
		(width 0.14478)
		(layer "In13.Cu")
		(net "M_H_CPU0_SB_DQ<23>")
	)
	(segment
		(start 412.935166 -308.900322)
		(end 413.079946 -308.755542)
		(width 0.14478)
		(layer "In13.Cu")
		(net "M_H_CPU0_SB_DQ<23>")
	)
	(segment
		(start 412.383986 -308.9656)
		(end 412.528766 -309.11038)
		(width 0.14478)
		(layer "In13.Cu")
		(net "M_H_CPU0_SB_DQ<23>")
	)
	(segment
		(start 411.281626 -308.796944)
		(end 411.281626 -308.9656)
		(width 0.14478)
		(layer "In13.Cu")
		(net "M_H_CPU0_SB_DQ<23>")
	)
	(segment
		(start 412.383986 -308.900322)
		(end 412.383986 -308.9656)
		(width 0.14478)
		(layer "In13.Cu")
		(net "M_H_CPU0_SB_DQ<23>")
	)
	(segment
		(start 413.486346 -308.900322)
		(end 413.486346 -308.9656)
		(width 0.14478)
		(layer "In13.Cu")
		(net "M_H_CPU0_SB_DQ<23>")
	)
	(segment
		(start 413.079946 -308.755542)
		(end 413.341566 -308.755542)
		(width 0.14478)
		(layer "In13.Cu")
		(net "M_H_CPU0_SB_DQ<23>")
	)
	(segment
		(start 410.179266 -308.577742)
		(end 410.179266 -308.965346)
		(width 0.14478)
		(layer "In13.Cu")
		(net "M_H_CPU0_SB_DQ<23>")
	)
	(segment
		(start 390.74344 -288.338768)
		(end 390.751822 -288.343594)
		(width 0.0889)
		(layer "In13.Cu")
		(net "M_H_CPU0_SB_DQ<23>")
	)
	(segment
		(start 410.730446 -308.965346)
		(end 410.730446 -308.796944)
		(width 0.14478)
		(layer "In13.Cu")
		(net "M_H_CPU0_SB_DQ<23>")
	)
	(segment
		(start 418.572188 -308.709822)
		(end 419.8874 -308.709822)
		(width 0.14478)
		(layer "In13.Cu")
		(net "M_H_CPU0_SB_DQ<23>")
	)
	(segment
		(start 398.667478 -299.226732)
		(end 407.81097 -308.370224)
		(width 0.14478)
		(layer "In13.Cu")
		(net "M_H_CPU0_SB_DQ<23>")
	)
	(segment
		(start 412.239206 -308.755542)
		(end 412.383986 -308.900322)
		(width 0.14478)
		(layer "In13.Cu")
		(net "M_H_CPU0_SB_DQ<23>")
	)
	(segment
		(start 411.281626 -308.9656)
		(end 411.426406 -309.11038)
		(width 0.14478)
		(layer "In13.Cu")
		(net "M_H_CPU0_SB_DQ<23>")
	)
	(segment
		(start 392.554968 -288.237676)
		(end 393.474702 -288.237676)
		(width 0.0889)
		(layer "In13.Cu")
		(net "M_H_CPU0_SB_DQ<23>")
	)
	(segment
		(start 383.0447 -288.66592)
		(end 382.890776 -288.40049)
		(width 0.0889)
		(layer "In13.Cu")
		(net "M_H_CPU0_SB_DQ<23>")
	)
	(segment
		(start 382.890776 -288.40049)
		(end 382.913128 -288.317432)
		(width 0.0889)
		(layer "In13.Cu")
		(net "M_H_CPU0_SB_DQ<23>")
	)
	(segment
		(start 413.341566 -308.755542)
		(end 413.486346 -308.900322)
		(width 0.14478)
		(layer "In13.Cu")
		(net "M_H_CPU0_SB_DQ<23>")
	)
	(segment
		(start 411.688026 -309.11038)
		(end 411.832806 -308.9656)
		(width 0.14478)
		(layer "In13.Cu")
		(net "M_H_CPU0_SB_DQ<23>")
	)
	(segment
		(start 391.317734 -288.343594)
		(end 391.326116 -288.338768)
		(width 0.0889)
		(layer "In13.Cu")
		(net "M_H_CPU0_SB_DQ<23>")
	)
	(segment
		(start 395.018514 -290.173664)
		(end 395.219428 -290.173664)
		(width 0.0889)
		(layer "In13.Cu")
		(net "M_H_CPU0_SB_DQ<23>")
	)
	(segment
		(start 388.497826 -288.343594)
		(end 388.506208 -288.338768)
		(width 0.0889)
		(layer "In13.Cu")
		(net "M_H_CPU0_SB_DQ<23>")
	)
	(segment
		(start 395.219428 -290.173664)
		(end 395.829536 -290.783772)
		(width 0.0889)
		(layer "In13.Cu")
		(net "M_H_CPU0_SB_DQ<23>")
	)
	(segment
		(start 408.29992 -308.163976)
		(end 408.504644 -308.163976)
		(width 0.14478)
		(layer "In13.Cu")
		(net "M_H_CPU0_SB_DQ<23>")
	)
	(segment
		(start 408.483562 -308.760114)
		(end 408.483562 -308.9656)
		(width 0.14478)
		(layer "In13.Cu")
		(net "M_H_CPU0_SB_DQ<23>")
	)
	(segment
		(start 408.483562 -308.9656)
		(end 408.628342 -309.11038)
		(width 0.14478)
		(layer "In13.Cu")
		(net "M_H_CPU0_SB_DQ<23>")
	)
	(segment
		(start 413.631126 -309.11038)
		(end 414.090104 -309.11038)
		(width 0.14478)
		(layer "In13.Cu")
		(net "M_H_CPU0_SB_DQ<23>")
	)
	(segment
		(start 383.79781 -288.343594)
		(end 383.806192 -288.338768)
		(width 0.0889)
		(layer "In13.Cu")
		(net "M_H_CPU0_SB_DQ<23>")
	)
	(segment
		(start 410.034486 -308.432962)
		(end 410.179266 -308.577742)
		(width 0.14478)
		(layer "In13.Cu")
		(net "M_H_CPU0_SB_DQ<23>")
	)
	(segment
		(start 393.956794 -289.111944)
		(end 395.018514 -290.173664)
		(width 0.0889)
		(layer "In13.Cu")
		(net "M_H_CPU0_SB_DQ<23>")
	)
	(segment
		(start 408.68981 -308.553866)
		(end 408.483562 -308.760114)
		(width 0.14478)
		(layer "In13.Cu")
		(net "M_H_CPU0_SB_DQ<23>")
	)
	(segment
		(start 407.81097 -308.370224)
		(end 408.093672 -308.370224)
		(width 0.14478)
		(layer "In13.Cu")
		(net "M_H_CPU0_SB_DQ<23>")
	)
	(segment
		(start 409.483306 -309.11038)
		(end 409.628086 -308.9656)
		(width 0.14478)
		(layer "In13.Cu")
		(net "M_H_CPU0_SB_DQ<23>")
	)
	(segment
		(start 411.977586 -308.755542)
		(end 412.239206 -308.755542)
		(width 0.14478)
		(layer "In13.Cu")
		(net "M_H_CPU0_SB_DQ<23>")
	)
	(segment
		(start 419.8874 -308.709822)
		(end 419.912038 -308.685184)
		(width 0.14478)
		(layer "In13.Cu")
		(net "M_H_CPU0_SB_DQ<23>")
	)
	(segment
		(start 398.667478 -293.621714)
		(end 398.667478 -299.226732)
		(width 0.14478)
		(layer "In13.Cu")
		(net "M_H_CPU0_SB_DQ<23>")
	)
	(segment
		(start 418.122608 -308.260242)
		(end 418.572188 -308.709822)
		(width 0.14478)
		(layer "In13.Cu")
		(net "M_H_CPU0_SB_DQ<23>")
	)
	(segment
		(start 410.585666 -309.110126)
		(end 410.730446 -308.965346)
		(width 0.14478)
		(layer "In13.Cu")
		(net "M_H_CPU0_SB_DQ<23>")
	)
	(segment
		(start 408.093672 -308.370224)
		(end 408.29992 -308.163976)
		(width 0.14478)
		(layer "In13.Cu")
		(net "M_H_CPU0_SB_DQ<23>")
	)
	(segment
		(start 414.940242 -308.260242)
		(end 418.122608 -308.260242)
		(width 0.14478)
		(layer "In13.Cu")
		(net "M_H_CPU0_SB_DQ<23>")
	)
	(segment
		(start 410.179266 -308.965346)
		(end 410.324046 -309.110126)
		(width 0.14478)
		(layer "In13.Cu")
		(net "M_H_CPU0_SB_DQ<23>")
	)
	(segment
		(start 412.528766 -309.11038)
		(end 412.790386 -309.11038)
		(width 0.14478)
		(layer "In13.Cu")
		(net "M_H_CPU0_SB_DQ<23>")
	)
	(segment
		(start 393.474702 -288.237676)
		(end 393.956794 -288.719768)
		(width 0.0889)
		(layer "In13.Cu")
		(net "M_H_CPU0_SB_DQ<23>")
	)
	(segment
		(start 411.832806 -308.900322)
		(end 411.977586 -308.755542)
		(width 0.14478)
		(layer "In13.Cu")
		(net "M_H_CPU0_SB_DQ<23>")
	)
	(segment
		(start 412.935166 -308.9656)
		(end 412.935166 -308.900322)
		(width 0.14478)
		(layer "In13.Cu")
		(net "M_H_CPU0_SB_DQ<23>")
	)
	(arc
		(start 383.231898 -288.343594)
		(mid 383.514854 -288.419771)
		(end 383.79781 -288.343594)
		(width 0.0889)
		(layer "In13.Cu")
		(net "M_H_CPU0_SB_DQ<23>")
	)
	(arc
		(start 385.677664 -288.343594)
		(mid 385.859915 -288.29321)
		(end 386.043424 -288.338768)
		(width 0.0889)
		(layer "In13.Cu")
		(net "M_H_CPU0_SB_DQ<23>")
	)
	(arc
		(start 386.051806 -288.343594)
		(mid 386.334762 -288.419771)
		(end 386.617718 -288.343594)
		(width 0.0889)
		(layer "In13.Cu")
		(net "M_H_CPU0_SB_DQ<23>")
	)
	(arc
		(start 391.974832 -288.419794)
		(mid 392.278855 -288.373191)
		(end 392.554968 -288.237676)
		(width 0.0889)
		(layer "In13.Cu")
		(net "M_H_CPU0_SB_DQ<23>")
	)
	(arc
		(start 384.171952 -288.343594)
		(mid 384.454908 -288.419771)
		(end 384.737864 -288.343594)
		(width 0.0889)
		(layer "In13.Cu")
		(net "M_H_CPU0_SB_DQ<23>")
	)
	(arc
		(start 385.111752 -288.343594)
		(mid 385.394708 -288.419771)
		(end 385.677664 -288.343594)
		(width 0.0889)
		(layer "In13.Cu")
		(net "M_H_CPU0_SB_DQ<23>")
	)
	(arc
		(start 390.37768 -288.343594)
		(mid 390.559931 -288.29321)
		(end 390.74344 -288.338768)
		(width 0.0889)
		(layer "In13.Cu")
		(net "M_H_CPU0_SB_DQ<23>")
	)
	(arc
		(start 383.806192 -288.338768)
		(mid 383.9897 -288.293243)
		(end 384.171952 -288.343594)
		(width 0.0889)
		(layer "In13.Cu")
		(net "M_H_CPU0_SB_DQ<23>")
	)
	(arc
		(start 384.737864 -288.343594)
		(mid 384.924808 -288.293305)
		(end 385.111752 -288.343594)
		(width 0.0889)
		(layer "In13.Cu")
		(net "M_H_CPU0_SB_DQ<23>")
	)
	(arc
		(start 390.751822 -288.343594)
		(mid 391.034778 -288.419771)
		(end 391.317734 -288.343594)
		(width 0.0889)
		(layer "In13.Cu")
		(net "M_H_CPU0_SB_DQ<23>")
	)
	(arc
		(start 388.871968 -288.343594)
		(mid 389.154924 -288.419771)
		(end 389.43788 -288.343594)
		(width 0.0889)
		(layer "In13.Cu")
		(net "M_H_CPU0_SB_DQ<23>")
	)
	(arc
		(start 382.913128 -288.317432)
		(mid 383.07546 -288.294598)
		(end 383.231898 -288.343594)
		(width 0.0889)
		(layer "In13.Cu")
		(net "M_H_CPU0_SB_DQ<23>")
	)
	(arc
		(start 391.691876 -288.343594)
		(mid 391.828312 -288.400419)
		(end 391.974832 -288.419794)
		(width 0.0889)
		(layer "In13.Cu")
		(net "M_H_CPU0_SB_DQ<23>")
	)
	(arc
		(start 387.931914 -288.343594)
		(mid 388.21487 -288.419771)
		(end 388.497826 -288.343594)
		(width 0.0889)
		(layer "In13.Cu")
		(net "M_H_CPU0_SB_DQ<23>")
	)
	(arc
		(start 387.566154 -288.338768)
		(mid 387.749662 -288.293243)
		(end 387.931914 -288.343594)
		(width 0.0889)
		(layer "In13.Cu")
		(net "M_H_CPU0_SB_DQ<23>")
	)
	(arc
		(start 389.43788 -288.343594)
		(mid 389.624824 -288.293305)
		(end 389.811768 -288.343594)
		(width 0.0889)
		(layer "In13.Cu")
		(net "M_H_CPU0_SB_DQ<23>")
	)
	(arc
		(start 389.811768 -288.343594)
		(mid 390.094724 -288.419771)
		(end 390.37768 -288.343594)
		(width 0.0889)
		(layer "In13.Cu")
		(net "M_H_CPU0_SB_DQ<23>")
	)
	(arc
		(start 391.326116 -288.338768)
		(mid 391.509624 -288.293243)
		(end 391.691876 -288.343594)
		(width 0.0889)
		(layer "In13.Cu")
		(net "M_H_CPU0_SB_DQ<23>")
	)
	(arc
		(start 386.99186 -288.343594)
		(mid 387.274816 -288.419771)
		(end 387.557772 -288.343594)
		(width 0.0889)
		(layer "In13.Cu")
		(net "M_H_CPU0_SB_DQ<23>")
	)
	(arc
		(start 388.506208 -288.338768)
		(mid 388.689716 -288.293243)
		(end 388.871968 -288.343594)
		(width 0.0889)
		(layer "In13.Cu")
		(net "M_H_CPU0_SB_DQ<23>")
	)
	(arc
		(start 386.617718 -288.343594)
		(mid 386.799969 -288.29321)
		(end 386.983478 -288.338768)
		(width 0.0889)
		(layer "In13.Cu")
		(net "M_H_CPU0_SB_DQ<23>")
	)
	(segment
		(start 383.988056 -287.59023)
		(end 384.454908 -287.856168)
		(width 0.10668)
		(layer "F.Cu")
		(net "M_H_CPU0_SB_DQ<22>")
	)
	(segment
		(start 405.875236 -304.574194)
		(end 406.060402 -304.75936)
		(width 0.14478)
		(layer "In13.Cu")
		(net "M_H_CPU0_SB_DQ<22>")
	)
	(segment
		(start 394.317474 -288.37509)
		(end 394.70711 -288.37509)
		(width 0.0889)
		(layer "In13.Cu")
		(net "M_H_CPU0_SB_DQ<22>")
	)
	(segment
		(start 399.99158 -299.132244)
		(end 400.195796 -299.13199)
		(width 0.14478)
		(layer "In13.Cu")
		(net "M_H_CPU0_SB_DQ<22>")
	)
	(segment
		(start 386.147818 -287.533588)
		(end 386.1562 -287.528762)
		(width 0.0889)
		(layer "In13.Cu")
		(net "M_H_CPU0_SB_DQ<22>")
	)
	(segment
		(start 407.230072 -306.133754)
		(end 407.434796 -306.133754)
		(width 0.14478)
		(layer "In13.Cu")
		(net "M_H_CPU0_SB_DQ<22>")
	)
	(segment
		(start 391.974832 -287.482788)
		(end 392.66749 -287.482788)
		(width 0.0889)
		(layer "In13.Cu")
		(net "M_H_CPU0_SB_DQ<22>")
	)
	(segment
		(start 402.1455 -301.08144)
		(end 402.1455 -301.286164)
		(width 0.14478)
		(layer "In13.Cu")
		(net "M_H_CPU0_SB_DQ<22>")
	)
	(segment
		(start 409.526232 -307.104034)
		(end 409.787852 -307.104034)
		(width 0.14478)
		(layer "In13.Cu")
		(net "M_H_CPU0_SB_DQ<22>")
	)
	(segment
		(start 404.315676 -303.014634)
		(end 404.500842 -303.1998)
		(width 0.14478)
		(layer "In13.Cu")
		(net "M_H_CPU0_SB_DQ<22>")
	)
	(segment
		(start 409.932632 -306.801012)
		(end 410.077412 -306.656232)
		(width 0.14478)
		(layer "In13.Cu")
		(net "M_H_CPU0_SB_DQ<22>")
	)
	(segment
		(start 393.583414 -287.64103)
		(end 394.317474 -288.37509)
		(width 0.0889)
		(layer "In13.Cu")
		(net "M_H_CPU0_SB_DQ<22>")
	)
	(segment
		(start 409.381452 -306.959254)
		(end 409.526232 -307.104034)
		(width 0.14478)
		(layer "In13.Cu")
		(net "M_H_CPU0_SB_DQ<22>")
	)
	(segment
		(start 407.60396 -306.5399)
		(end 407.60396 -306.744624)
		(width 0.14478)
		(layer "In13.Cu")
		(net "M_H_CPU0_SB_DQ<22>")
	)
	(segment
		(start 403.1107 -302.251364)
		(end 403.314916 -302.25111)
		(width 0.14478)
		(layer "In13.Cu")
		(net "M_H_CPU0_SB_DQ<22>")
	)
	(segment
		(start 402.941536 -301.844964)
		(end 402.92528 -301.86122)
		(width 0.14478)
		(layer "In13.Cu")
		(net "M_H_CPU0_SB_DQ<22>")
	)
	(segment
		(start 401.196556 -299.895514)
		(end 401.381722 -300.08068)
		(width 0.14478)
		(layer "In13.Cu")
		(net "M_H_CPU0_SB_DQ<22>")
	)
	(segment
		(start 393.033758 -287.64103)
		(end 393.583414 -287.64103)
		(width 0.0889)
		(layer "In13.Cu")
		(net "M_H_CPU0_SB_DQ<22>")
	)
	(segment
		(start 406.82418 -305.76012)
		(end 406.82418 -305.964844)
		(width 0.14478)
		(layer "In13.Cu")
		(net "M_H_CPU0_SB_DQ<22>")
	)
	(segment
		(start 406.434036 -305.37023)
		(end 406.450292 -305.353974)
		(width 0.14478)
		(layer "In13.Cu")
		(net "M_H_CPU0_SB_DQ<22>")
	)
	(segment
		(start 400.195796 -299.13199)
		(end 400.212052 -299.115734)
		(width 0.14478)
		(layer "In13.Cu")
		(net "M_H_CPU0_SB_DQ<22>")
	)
	(segment
		(start 410.628592 -307.104034)
		(end 410.890212 -307.104034)
		(width 0.14478)
		(layer "In13.Cu")
		(net "M_H_CPU0_SB_DQ<22>")
	)
	(segment
		(start 401.55114 -300.691804)
		(end 401.755356 -300.69155)
		(width 0.14478)
		(layer "In13.Cu")
		(net "M_H_CPU0_SB_DQ<22>")
	)
	(segment
		(start 405.280876 -304.184304)
		(end 405.26462 -304.20056)
		(width 0.14478)
		(layer "In13.Cu")
		(net "M_H_CPU0_SB_DQ<22>")
	)
	(segment
		(start 407.0096 -306.150264)
		(end 407.213816 -306.15001)
		(width 0.14478)
		(layer "In13.Cu")
		(net "M_H_CPU0_SB_DQ<22>")
	)
	(segment
		(start 400.416776 -299.115734)
		(end 400.601942 -299.3009)
		(width 0.14478)
		(layer "In13.Cu")
		(net "M_H_CPU0_SB_DQ<22>")
	)
	(segment
		(start 409.381452 -306.801012)
		(end 409.381452 -306.959254)
		(width 0.14478)
		(layer "In13.Cu")
		(net "M_H_CPU0_SB_DQ<22>")
	)
	(segment
		(start 384.30073 -287.590738)
		(end 384.323082 -287.507426)
		(width 0.0889)
		(layer "In13.Cu")
		(net "M_H_CPU0_SB_DQ<22>")
	)
	(segment
		(start 401.381976 -300.285404)
		(end 401.36572 -300.30166)
		(width 0.14478)
		(layer "In13.Cu")
		(net "M_H_CPU0_SB_DQ<22>")
	)
	(segment
		(start 407.60396 -306.744624)
		(end 407.96337 -307.104034)
		(width 0.14478)
		(layer "In13.Cu")
		(net "M_H_CPU0_SB_DQ<22>")
	)
	(segment
		(start 401.976336 -300.675294)
		(end 402.161502 -300.86046)
		(width 0.14478)
		(layer "In13.Cu")
		(net "M_H_CPU0_SB_DQ<22>")
	)
	(segment
		(start 409.236672 -306.656232)
		(end 409.381452 -306.801012)
		(width 0.14478)
		(layer "In13.Cu")
		(net "M_H_CPU0_SB_DQ<22>")
	)
	(segment
		(start 406.450292 -305.353974)
		(end 406.655016 -305.353974)
		(width 0.14478)
		(layer "In13.Cu")
		(net "M_H_CPU0_SB_DQ<22>")
	)
	(segment
		(start 404.874476 -303.81067)
		(end 404.890732 -303.794414)
		(width 0.14478)
		(layer "In13.Cu")
		(net "M_H_CPU0_SB_DQ<22>")
	)
	(segment
		(start 400.58594 -299.726604)
		(end 400.77136 -299.912024)
		(width 0.14478)
		(layer "In13.Cu")
		(net "M_H_CPU0_SB_DQ<22>")
	)
	(segment
		(start 400.58594 -299.52188)
		(end 400.58594 -299.726604)
		(width 0.14478)
		(layer "In13.Cu")
		(net "M_H_CPU0_SB_DQ<22>")
	)
	(segment
		(start 402.92528 -301.86122)
		(end 402.92528 -302.065944)
		(width 0.14478)
		(layer "In13.Cu")
		(net "M_H_CPU0_SB_DQ<22>")
	)
	(segment
		(start 401.755356 -300.69155)
		(end 401.771612 -300.675294)
		(width 0.14478)
		(layer "In13.Cu")
		(net "M_H_CPU0_SB_DQ<22>")
	)
	(segment
		(start 401.771612 -300.675294)
		(end 401.976336 -300.675294)
		(width 0.14478)
		(layer "In13.Cu")
		(net "M_H_CPU0_SB_DQ<22>")
	)
	(segment
		(start 407.213816 -306.15001)
		(end 407.230072 -306.133754)
		(width 0.14478)
		(layer "In13.Cu")
		(net "M_H_CPU0_SB_DQ<22>")
	)
	(segment
		(start 404.094696 -303.03089)
		(end 404.110952 -303.014634)
		(width 0.14478)
		(layer "In13.Cu")
		(net "M_H_CPU0_SB_DQ<22>")
	)
	(segment
		(start 407.619962 -306.31892)
		(end 407.620216 -306.523644)
		(width 0.14478)
		(layer "In13.Cu")
		(net "M_H_CPU0_SB_DQ<22>")
	)
	(segment
		(start 403.70506 -302.641)
		(end 403.70506 -302.845724)
		(width 0.14478)
		(layer "In13.Cu")
		(net "M_H_CPU0_SB_DQ<22>")
	)
	(segment
		(start 389.90778 -287.533588)
		(end 389.916162 -287.528762)
		(width 0.0889)
		(layer "In13.Cu")
		(net "M_H_CPU0_SB_DQ<22>")
	)
	(segment
		(start 411.034992 -306.959254)
		(end 411.034992 -306.801012)
		(width 0.14478)
		(layer "In13.Cu")
		(net "M_H_CPU0_SB_DQ<22>")
	)
	(segment
		(start 417.791392 -306.56022)
		(end 418.64153 -307.410358)
		(width 0.14478)
		(layer "In13.Cu")
		(net "M_H_CPU0_SB_DQ<22>")
	)
	(segment
		(start 400.991832 -299.895514)
		(end 401.196556 -299.895514)
		(width 0.14478)
		(layer "In13.Cu")
		(net "M_H_CPU0_SB_DQ<22>")
	)
	(segment
		(start 404.67026 -303.810924)
		(end 404.874476 -303.81067)
		(width 0.14478)
		(layer "In13.Cu")
		(net "M_H_CPU0_SB_DQ<22>")
	)
	(segment
		(start 410.890212 -307.104034)
		(end 411.034992 -306.959254)
		(width 0.14478)
		(layer "In13.Cu")
		(net "M_H_CPU0_SB_DQ<22>")
	)
	(segment
		(start 401.36572 -300.30166)
		(end 401.36572 -300.506384)
		(width 0.14478)
		(layer "In13.Cu")
		(net "M_H_CPU0_SB_DQ<22>")
	)
	(segment
		(start 401.381722 -300.08068)
		(end 401.381976 -300.285404)
		(width 0.14478)
		(layer "In13.Cu")
		(net "M_H_CPU0_SB_DQ<22>")
	)
	(segment
		(start 411.034992 -306.801012)
		(end 411.179772 -306.656232)
		(width 0.14478)
		(layer "In13.Cu")
		(net "M_H_CPU0_SB_DQ<22>")
	)
	(segment
		(start 404.48484 -303.42078)
		(end 404.48484 -303.625504)
		(width 0.14478)
		(layer "In13.Cu")
		(net "M_H_CPU0_SB_DQ<22>")
	)
	(segment
		(start 407.434796 -306.133754)
		(end 407.619962 -306.31892)
		(width 0.14478)
		(layer "In13.Cu")
		(net "M_H_CPU0_SB_DQ<22>")
	)
	(segment
		(start 400.212052 -299.115734)
		(end 400.416776 -299.115734)
		(width 0.14478)
		(layer "In13.Cu")
		(net "M_H_CPU0_SB_DQ<22>")
	)
	(segment
		(start 402.92528 -302.065944)
		(end 403.1107 -302.251364)
		(width 0.14478)
		(layer "In13.Cu")
		(net "M_H_CPU0_SB_DQ<22>")
	)
	(segment
		(start 399.566638 -293.234618)
		(end 399.566638 -298.707302)
		(width 0.14478)
		(layer "In13.Cu")
		(net "M_H_CPU0_SB_DQ<22>")
	)
	(segment
		(start 414.396428 -307.104034)
		(end 414.940242 -306.56022)
		(width 0.14478)
		(layer "In13.Cu")
		(net "M_H_CPU0_SB_DQ<22>")
	)
	(segment
		(start 411.730952 -307.104034)
		(end 414.396428 -307.104034)
		(width 0.14478)
		(layer "In13.Cu")
		(net "M_H_CPU0_SB_DQ<22>")
	)
	(segment
		(start 402.1455 -301.286164)
		(end 402.33092 -301.471584)
		(width 0.14478)
		(layer "In13.Cu")
		(net "M_H_CPU0_SB_DQ<22>")
	)
	(segment
		(start 404.500842 -303.1998)
		(end 404.501096 -303.404524)
		(width 0.14478)
		(layer "In13.Cu")
		(net "M_H_CPU0_SB_DQ<22>")
	)
	(segment
		(start 419.912038 -307.066188)
		(end 419.912038 -306.985162)
		(width 0.14478)
		(layer "In13.Cu")
		(net "M_H_CPU0_SB_DQ<22>")
	)
	(segment
		(start 384.454908 -287.856168)
		(end 384.30073 -287.590738)
		(width 0.0889)
		(layer "In13.Cu")
		(net "M_H_CPU0_SB_DQ<22>")
	)
	(segment
		(start 406.0444 -305.185064)
		(end 406.22982 -305.370484)
		(width 0.14478)
		(layer "In13.Cu")
		(net "M_H_CPU0_SB_DQ<22>")
	)
	(segment
		(start 410.483812 -306.801012)
		(end 410.483812 -306.959254)
		(width 0.14478)
		(layer "In13.Cu")
		(net "M_H_CPU0_SB_DQ<22>")
	)
	(segment
		(start 408.830272 -306.801012)
		(end 408.975052 -306.656232)
		(width 0.14478)
		(layer "In13.Cu")
		(net "M_H_CPU0_SB_DQ<22>")
	)
	(segment
		(start 400.975576 -299.91177)
		(end 400.991832 -299.895514)
		(width 0.14478)
		(layer "In13.Cu")
		(net "M_H_CPU0_SB_DQ<22>")
	)
	(segment
		(start 409.787852 -307.104034)
		(end 409.932632 -306.959254)
		(width 0.14478)
		(layer "In13.Cu")
		(net "M_H_CPU0_SB_DQ<22>")
	)
	(segment
		(start 405.095456 -303.794414)
		(end 405.280622 -303.97958)
		(width 0.14478)
		(layer "In13.Cu")
		(net "M_H_CPU0_SB_DQ<22>")
	)
	(segment
		(start 400.602196 -299.505624)
		(end 400.58594 -299.52188)
		(width 0.14478)
		(layer "In13.Cu")
		(net "M_H_CPU0_SB_DQ<22>")
	)
	(segment
		(start 411.441392 -306.656232)
		(end 411.586172 -306.801012)
		(width 0.14478)
		(layer "In13.Cu")
		(net "M_H_CPU0_SB_DQ<22>")
	)
	(segment
		(start 407.96337 -307.104034)
		(end 408.685492 -307.104034)
		(width 0.14478)
		(layer "In13.Cu")
		(net "M_H_CPU0_SB_DQ<22>")
	)
	(segment
		(start 411.586172 -306.801012)
		(end 411.586172 -306.959254)
		(width 0.14478)
		(layer "In13.Cu")
		(net "M_H_CPU0_SB_DQ<22>")
	)
	(segment
		(start 405.45004 -304.590704)
		(end 405.654256 -304.59045)
		(width 0.14478)
		(layer "In13.Cu")
		(net "M_H_CPU0_SB_DQ<22>")
	)
	(segment
		(start 400.77136 -299.912024)
		(end 400.975576 -299.91177)
		(width 0.14478)
		(layer "In13.Cu")
		(net "M_H_CPU0_SB_DQ<22>")
	)
	(segment
		(start 388.393432 -287.528762)
		(end 388.401814 -287.533588)
		(width 0.0889)
		(layer "In13.Cu")
		(net "M_H_CPU0_SB_DQ<22>")
	)
	(segment
		(start 408.830272 -306.959254)
		(end 408.830272 -306.801012)
		(width 0.14478)
		(layer "In13.Cu")
		(net "M_H_CPU0_SB_DQ<22>")
	)
	(segment
		(start 406.22982 -305.370484)
		(end 406.434036 -305.37023)
		(width 0.14478)
		(layer "In13.Cu")
		(net "M_H_CPU0_SB_DQ<22>")
	)
	(segment
		(start 385.207764 -287.533588)
		(end 385.216146 -287.528762)
		(width 0.0889)
		(layer "In13.Cu")
		(net "M_H_CPU0_SB_DQ<22>")
	)
	(segment
		(start 405.280622 -303.97958)
		(end 405.280876 -304.184304)
		(width 0.14478)
		(layer "In13.Cu")
		(net "M_H_CPU0_SB_DQ<22>")
	)
	(segment
		(start 406.840182 -305.53914)
		(end 406.840436 -305.743864)
		(width 0.14478)
		(layer "In13.Cu")
		(net "M_H_CPU0_SB_DQ<22>")
	)
	(segment
		(start 402.161502 -300.86046)
		(end 402.161756 -301.065184)
		(width 0.14478)
		(layer "In13.Cu")
		(net "M_H_CPU0_SB_DQ<22>")
	)
	(segment
		(start 400.601942 -299.3009)
		(end 400.602196 -299.505624)
		(width 0.14478)
		(layer "In13.Cu")
		(net "M_H_CPU0_SB_DQ<22>")
	)
	(segment
		(start 402.161756 -301.065184)
		(end 402.1455 -301.08144)
		(width 0.14478)
		(layer "In13.Cu")
		(net "M_H_CPU0_SB_DQ<22>")
	)
	(segment
		(start 405.654256 -304.59045)
		(end 405.670512 -304.574194)
		(width 0.14478)
		(layer "In13.Cu")
		(net "M_H_CPU0_SB_DQ<22>")
	)
	(segment
		(start 410.077412 -306.656232)
		(end 410.339032 -306.656232)
		(width 0.14478)
		(layer "In13.Cu")
		(net "M_H_CPU0_SB_DQ<22>")
	)
	(segment
		(start 402.756116 -301.455074)
		(end 402.941282 -301.64024)
		(width 0.14478)
		(layer "In13.Cu")
		(net "M_H_CPU0_SB_DQ<22>")
	)
	(segment
		(start 405.26462 -304.405284)
		(end 405.45004 -304.590704)
		(width 0.14478)
		(layer "In13.Cu")
		(net "M_H_CPU0_SB_DQ<22>")
	)
	(segment
		(start 389.333486 -287.528762)
		(end 389.341868 -287.533588)
		(width 0.0889)
		(layer "In13.Cu")
		(net "M_H_CPU0_SB_DQ<22>")
	)
	(segment
		(start 402.551392 -301.455074)
		(end 402.756116 -301.455074)
		(width 0.14478)
		(layer "In13.Cu")
		(net "M_H_CPU0_SB_DQ<22>")
	)
	(segment
		(start 401.36572 -300.506384)
		(end 401.55114 -300.691804)
		(width 0.14478)
		(layer "In13.Cu")
		(net "M_H_CPU0_SB_DQ<22>")
	)
	(segment
		(start 394.70711 -288.37509)
		(end 395.529816 -289.197796)
		(width 0.0889)
		(layer "In13.Cu")
		(net "M_H_CPU0_SB_DQ<22>")
	)
	(segment
		(start 403.721062 -302.42002)
		(end 403.721316 -302.624744)
		(width 0.14478)
		(layer "In13.Cu")
		(net "M_H_CPU0_SB_DQ<22>")
	)
	(segment
		(start 403.70506 -302.845724)
		(end 403.89048 -303.031144)
		(width 0.14478)
		(layer "In13.Cu")
		(net "M_H_CPU0_SB_DQ<22>")
	)
	(segment
		(start 414.940242 -306.56022)
		(end 417.791392 -306.56022)
		(width 0.14478)
		(layer "In13.Cu")
		(net "M_H_CPU0_SB_DQ<22>")
	)
	(segment
		(start 408.685492 -307.104034)
		(end 408.830272 -306.959254)
		(width 0.14478)
		(layer "In13.Cu")
		(net "M_H_CPU0_SB_DQ<22>")
	)
	(segment
		(start 402.535136 -301.47133)
		(end 402.551392 -301.455074)
		(width 0.14478)
		(layer "In13.Cu")
		(net "M_H_CPU0_SB_DQ<22>")
	)
	(segment
		(start 395.529816 -289.197796)
		(end 399.566638 -293.234618)
		(width 0.14478)
		(layer "In13.Cu")
		(net "M_H_CPU0_SB_DQ<22>")
	)
	(segment
		(start 404.48484 -303.625504)
		(end 404.67026 -303.810924)
		(width 0.14478)
		(layer "In13.Cu")
		(net "M_H_CPU0_SB_DQ<22>")
	)
	(segment
		(start 392.66749 -287.482788)
		(end 393.033758 -287.64103)
		(width 0.0889)
		(layer "In13.Cu")
		(net "M_H_CPU0_SB_DQ<22>")
	)
	(segment
		(start 402.941282 -301.64024)
		(end 402.941536 -301.844964)
		(width 0.14478)
		(layer "In13.Cu")
		(net "M_H_CPU0_SB_DQ<22>")
	)
	(segment
		(start 403.721316 -302.624744)
		(end 403.70506 -302.641)
		(width 0.14478)
		(layer "In13.Cu")
		(net "M_H_CPU0_SB_DQ<22>")
	)
	(segment
		(start 408.975052 -306.656232)
		(end 409.236672 -306.656232)
		(width 0.14478)
		(layer "In13.Cu")
		(net "M_H_CPU0_SB_DQ<22>")
	)
	(segment
		(start 419.567868 -307.410358)
		(end 419.912038 -307.066188)
		(width 0.14478)
		(layer "In13.Cu")
		(net "M_H_CPU0_SB_DQ<22>")
	)
	(segment
		(start 406.840436 -305.743864)
		(end 406.82418 -305.76012)
		(width 0.14478)
		(layer "In13.Cu")
		(net "M_H_CPU0_SB_DQ<22>")
	)
	(segment
		(start 410.339032 -306.656232)
		(end 410.483812 -306.801012)
		(width 0.14478)
		(layer "In13.Cu")
		(net "M_H_CPU0_SB_DQ<22>")
	)
	(segment
		(start 405.670512 -304.574194)
		(end 405.875236 -304.574194)
		(width 0.14478)
		(layer "In13.Cu")
		(net "M_H_CPU0_SB_DQ<22>")
	)
	(segment
		(start 403.314916 -302.25111)
		(end 403.331172 -302.234854)
		(width 0.14478)
		(layer "In13.Cu")
		(net "M_H_CPU0_SB_DQ<22>")
	)
	(segment
		(start 406.655016 -305.353974)
		(end 406.840182 -305.53914)
		(width 0.14478)
		(layer "In13.Cu")
		(net "M_H_CPU0_SB_DQ<22>")
	)
	(segment
		(start 404.501096 -303.404524)
		(end 404.48484 -303.42078)
		(width 0.14478)
		(layer "In13.Cu")
		(net "M_H_CPU0_SB_DQ<22>")
	)
	(segment
		(start 409.932632 -306.959254)
		(end 409.932632 -306.801012)
		(width 0.14478)
		(layer "In13.Cu")
		(net "M_H_CPU0_SB_DQ<22>")
	)
	(segment
		(start 406.82418 -305.964844)
		(end 407.0096 -306.150264)
		(width 0.14478)
		(layer "In13.Cu")
		(net "M_H_CPU0_SB_DQ<22>")
	)
	(segment
		(start 404.110952 -303.014634)
		(end 404.315676 -303.014634)
		(width 0.14478)
		(layer "In13.Cu")
		(net "M_H_CPU0_SB_DQ<22>")
	)
	(segment
		(start 406.060656 -304.964084)
		(end 406.0444 -304.98034)
		(width 0.14478)
		(layer "In13.Cu")
		(net "M_H_CPU0_SB_DQ<22>")
	)
	(segment
		(start 404.890732 -303.794414)
		(end 405.095456 -303.794414)
		(width 0.14478)
		(layer "In13.Cu")
		(net "M_H_CPU0_SB_DQ<22>")
	)
	(segment
		(start 403.89048 -303.031144)
		(end 404.094696 -303.03089)
		(width 0.14478)
		(layer "In13.Cu")
		(net "M_H_CPU0_SB_DQ<22>")
	)
	(segment
		(start 410.483812 -306.959254)
		(end 410.628592 -307.104034)
		(width 0.14478)
		(layer "In13.Cu")
		(net "M_H_CPU0_SB_DQ<22>")
	)
	(segment
		(start 406.0444 -304.98034)
		(end 406.0444 -305.185064)
		(width 0.14478)
		(layer "In13.Cu")
		(net "M_H_CPU0_SB_DQ<22>")
	)
	(segment
		(start 399.566638 -298.707302)
		(end 399.99158 -299.132244)
		(width 0.14478)
		(layer "In13.Cu")
		(net "M_H_CPU0_SB_DQ<22>")
	)
	(segment
		(start 411.179772 -306.656232)
		(end 411.441392 -306.656232)
		(width 0.14478)
		(layer "In13.Cu")
		(net "M_H_CPU0_SB_DQ<22>")
	)
	(segment
		(start 402.33092 -301.471584)
		(end 402.535136 -301.47133)
		(width 0.14478)
		(layer "In13.Cu")
		(net "M_H_CPU0_SB_DQ<22>")
	)
	(segment
		(start 384.63347 -287.528762)
		(end 384.641852 -287.533588)
		(width 0.0889)
		(layer "In13.Cu")
		(net "M_H_CPU0_SB_DQ<22>")
	)
	(segment
		(start 407.620216 -306.523644)
		(end 407.60396 -306.5399)
		(width 0.14478)
		(layer "In13.Cu")
		(net "M_H_CPU0_SB_DQ<22>")
	)
	(segment
		(start 405.26462 -304.20056)
		(end 405.26462 -304.405284)
		(width 0.14478)
		(layer "In13.Cu")
		(net "M_H_CPU0_SB_DQ<22>")
	)
	(segment
		(start 403.331172 -302.234854)
		(end 403.535896 -302.234854)
		(width 0.14478)
		(layer "In13.Cu")
		(net "M_H_CPU0_SB_DQ<22>")
	)
	(segment
		(start 418.64153 -307.410358)
		(end 419.567868 -307.410358)
		(width 0.14478)
		(layer "In13.Cu")
		(net "M_H_CPU0_SB_DQ<22>")
	)
	(segment
		(start 411.586172 -306.959254)
		(end 411.730952 -307.104034)
		(width 0.14478)
		(layer "In13.Cu")
		(net "M_H_CPU0_SB_DQ<22>")
	)
	(segment
		(start 403.535896 -302.234854)
		(end 403.721062 -302.42002)
		(width 0.14478)
		(layer "In13.Cu")
		(net "M_H_CPU0_SB_DQ<22>")
	)
	(segment
		(start 406.060402 -304.75936)
		(end 406.060656 -304.964084)
		(width 0.14478)
		(layer "In13.Cu")
		(net "M_H_CPU0_SB_DQ<22>")
	)
	(arc
		(start 385.581906 -287.533588)
		(mid 385.864862 -287.609731)
		(end 386.147818 -287.533588)
		(width 0.0889)
		(layer "In13.Cu")
		(net "M_H_CPU0_SB_DQ<22>")
	)
	(arc
		(start 386.52196 -287.533588)
		(mid 386.804916 -287.609731)
		(end 387.087872 -287.533588)
		(width 0.0889)
		(layer "In13.Cu")
		(net "M_H_CPU0_SB_DQ<22>")
	)
	(arc
		(start 391.221722 -287.533588)
		(mid 391.504678 -287.609731)
		(end 391.787634 -287.533588)
		(width 0.0889)
		(layer "In13.Cu")
		(net "M_H_CPU0_SB_DQ<22>")
	)
	(arc
		(start 387.46176 -287.533588)
		(mid 387.744716 -287.609731)
		(end 388.027672 -287.533588)
		(width 0.0889)
		(layer "In13.Cu")
		(net "M_H_CPU0_SB_DQ<22>")
	)
	(arc
		(start 386.1562 -287.528762)
		(mid 386.339708 -287.483268)
		(end 386.52196 -287.533588)
		(width 0.0889)
		(layer "In13.Cu")
		(net "M_H_CPU0_SB_DQ<22>")
	)
	(arc
		(start 388.967726 -287.533588)
		(mid 389.149977 -287.483238)
		(end 389.333486 -287.528762)
		(width 0.0889)
		(layer "In13.Cu")
		(net "M_H_CPU0_SB_DQ<22>")
	)
	(arc
		(start 390.281922 -287.533588)
		(mid 390.564878 -287.609731)
		(end 390.847834 -287.533588)
		(width 0.0889)
		(layer "In13.Cu")
		(net "M_H_CPU0_SB_DQ<22>")
	)
	(arc
		(start 388.027672 -287.533588)
		(mid 388.209923 -287.483238)
		(end 388.393432 -287.528762)
		(width 0.0889)
		(layer "In13.Cu")
		(net "M_H_CPU0_SB_DQ<22>")
	)
	(arc
		(start 385.216146 -287.528762)
		(mid 385.399654 -287.483268)
		(end 385.581906 -287.533588)
		(width 0.0889)
		(layer "In13.Cu")
		(net "M_H_CPU0_SB_DQ<22>")
	)
	(arc
		(start 391.787634 -287.533588)
		(mid 391.877874 -287.495811)
		(end 391.974832 -287.482788)
		(width 0.0889)
		(layer "In13.Cu")
		(net "M_H_CPU0_SB_DQ<22>")
	)
	(arc
		(start 388.401814 -287.533588)
		(mid 388.68477 -287.609731)
		(end 388.967726 -287.533588)
		(width 0.0889)
		(layer "In13.Cu")
		(net "M_H_CPU0_SB_DQ<22>")
	)
	(arc
		(start 390.847834 -287.533588)
		(mid 391.034778 -287.483333)
		(end 391.221722 -287.533588)
		(width 0.0889)
		(layer "In13.Cu")
		(net "M_H_CPU0_SB_DQ<22>")
	)
	(arc
		(start 387.087872 -287.533588)
		(mid 387.274816 -287.483333)
		(end 387.46176 -287.533588)
		(width 0.0889)
		(layer "In13.Cu")
		(net "M_H_CPU0_SB_DQ<22>")
	)
	(arc
		(start 389.916162 -287.528762)
		(mid 390.09967 -287.483268)
		(end 390.281922 -287.533588)
		(width 0.0889)
		(layer "In13.Cu")
		(net "M_H_CPU0_SB_DQ<22>")
	)
	(arc
		(start 384.323082 -287.507426)
		(mid 384.480592 -287.484228)
		(end 384.63347 -287.528762)
		(width 0.0889)
		(layer "In13.Cu")
		(net "M_H_CPU0_SB_DQ<22>")
	)
	(arc
		(start 389.341868 -287.533588)
		(mid 389.624824 -287.609731)
		(end 389.90778 -287.533588)
		(width 0.0889)
		(layer "In13.Cu")
		(net "M_H_CPU0_SB_DQ<22>")
	)
	(arc
		(start 384.641852 -287.533588)
		(mid 384.924808 -287.609731)
		(end 385.207764 -287.533588)
		(width 0.0889)
		(layer "In13.Cu")
		(net "M_H_CPU0_SB_DQ<22>")
	)
	(segment
		(start 382.107948 -287.59023)
		(end 382.5748 -287.856168)
		(width 0.10668)
		(layer "F.Cu")
		(net "M_H_CPU0_SB_DQ<21>")
	)
	(segment
		(start 417.426648 -307.410358)
		(end 415.435796 -307.410358)
		(width 0.14478)
		(layer "In13.Cu")
		(net "M_H_CPU0_SB_DQ<21>")
	)
	(segment
		(start 388.401814 -288.178494)
		(end 388.393432 -288.18332)
		(width 0.0889)
		(layer "In13.Cu")
		(net "M_H_CPU0_SB_DQ<21>")
	)
	(segment
		(start 424.012106 -307.835046)
		(end 421.092122 -308.260242)
		(width 0.14478)
		(layer "In13.Cu")
		(net "M_H_CPU0_SB_DQ<21>")
	)
	(segment
		(start 385.216146 -288.18332)
		(end 385.207764 -288.178494)
		(width 0.0889)
		(layer "In13.Cu")
		(net "M_H_CPU0_SB_DQ<21>")
	)
	(segment
		(start 389.916162 -288.18332)
		(end 389.90778 -288.178494)
		(width 0.0889)
		(layer "In13.Cu")
		(net "M_H_CPU0_SB_DQ<21>")
	)
	(segment
		(start 395.806422 -290.11753)
		(end 395.529562 -289.84067)
		(width 0.0889)
		(layer "In13.Cu")
		(net "M_H_CPU0_SB_DQ<21>")
	)
	(segment
		(start 393.52728 -287.963356)
		(end 392.524488 -287.963356)
		(width 0.0889)
		(layer "In13.Cu")
		(net "M_H_CPU0_SB_DQ<21>")
	)
	(segment
		(start 389.341868 -288.178494)
		(end 389.333486 -288.18332)
		(width 0.0889)
		(layer "In13.Cu")
		(net "M_H_CPU0_SB_DQ<21>")
	)
	(segment
		(start 411.47111 -308.260242)
		(end 407.83256 -307.536596)
		(width 0.14478)
		(layer "In13.Cu")
		(net "M_H_CPU0_SB_DQ<21>")
	)
	(segment
		(start 394.220954 -288.65703)
		(end 393.52728 -287.963356)
		(width 0.0889)
		(layer "In13.Cu")
		(net "M_H_CPU0_SB_DQ<21>")
	)
	(segment
		(start 382.824482 -288.146998)
		(end 382.728724 -288.121598)
		(width 0.0889)
		(layer "In13.Cu")
		(net "M_H_CPU0_SB_DQ<21>")
	)
	(segment
		(start 384.641852 -288.178494)
		(end 384.63347 -288.18332)
		(width 0.0889)
		(layer "In13.Cu")
		(net "M_H_CPU0_SB_DQ<21>")
	)
	(segment
		(start 395.059154 -289.84067)
		(end 394.220954 -289.00247)
		(width 0.0889)
		(layer "In13.Cu")
		(net "M_H_CPU0_SB_DQ<21>")
	)
	(segment
		(start 382.728724 -288.121598)
		(end 382.5748 -287.856168)
		(width 0.0889)
		(layer "In13.Cu")
		(net "M_H_CPU0_SB_DQ<21>")
	)
	(segment
		(start 383.701798 -288.178494)
		(end 383.693416 -288.18332)
		(width 0.0889)
		(layer "In13.Cu")
		(net "M_H_CPU0_SB_DQ<21>")
	)
	(segment
		(start 413.383984 -308.260242)
		(end 411.47111 -308.260242)
		(width 0.14478)
		(layer "In13.Cu")
		(net "M_H_CPU0_SB_DQ<21>")
	)
	(segment
		(start 395.529562 -289.84067)
		(end 395.059154 -289.84067)
		(width 0.0889)
		(layer "In13.Cu")
		(net "M_H_CPU0_SB_DQ<21>")
	)
	(segment
		(start 407.458926 -307.38191)
		(end 399.117058 -299.040042)
		(width 0.14478)
		(layer "In13.Cu")
		(net "M_H_CPU0_SB_DQ<21>")
	)
	(segment
		(start 415.435796 -307.410358)
		(end 413.383984 -308.260242)
		(width 0.14478)
		(layer "In13.Cu")
		(net "M_H_CPU0_SB_DQ<21>")
	)
	(segment
		(start 399.117058 -293.428166)
		(end 395.806422 -290.11753)
		(width 0.14478)
		(layer "In13.Cu")
		(net "M_H_CPU0_SB_DQ<21>")
	)
	(segment
		(start 421.092122 -308.260242)
		(end 419.47846 -308.260242)
		(width 0.14478)
		(layer "In13.Cu")
		(net "M_H_CPU0_SB_DQ<21>")
	)
	(segment
		(start 419.47846 -308.260242)
		(end 417.426648 -307.410358)
		(width 0.14478)
		(layer "In13.Cu")
		(net "M_H_CPU0_SB_DQ<21>")
	)
	(segment
		(start 392.524488 -287.963356)
		(end 392.401044 -288.0868)
		(width 0.0889)
		(layer "In13.Cu")
		(net "M_H_CPU0_SB_DQ<21>")
	)
	(segment
		(start 399.117058 -299.040042)
		(end 399.117058 -293.428166)
		(width 0.14478)
		(layer "In13.Cu")
		(net "M_H_CPU0_SB_DQ<21>")
	)
	(segment
		(start 394.220954 -289.00247)
		(end 394.220954 -288.65703)
		(width 0.0889)
		(layer "In13.Cu")
		(net "M_H_CPU0_SB_DQ<21>")
	)
	(segment
		(start 407.83256 -307.536596)
		(end 407.458926 -307.38191)
		(width 0.14478)
		(layer "In13.Cu")
		(net "M_H_CPU0_SB_DQ<21>")
	)
	(segment
		(start 386.1562 -288.18332)
		(end 386.147818 -288.178494)
		(width 0.0889)
		(layer "In13.Cu")
		(net "M_H_CPU0_SB_DQ<21>")
	)
	(arc
		(start 385.207764 -288.178494)
		(mid 384.924808 -288.102317)
		(end 384.641852 -288.178494)
		(width 0.0889)
		(layer "In13.Cu")
		(net "M_H_CPU0_SB_DQ<21>")
	)
	(arc
		(start 391.787634 -288.178494)
		(mid 391.504678 -288.102317)
		(end 391.221722 -288.178494)
		(width 0.0889)
		(layer "In13.Cu")
		(net "M_H_CPU0_SB_DQ<21>")
	)
	(arc
		(start 391.221722 -288.178494)
		(mid 391.034778 -288.228783)
		(end 390.847834 -288.178494)
		(width 0.0889)
		(layer "In13.Cu")
		(net "M_H_CPU0_SB_DQ<21>")
	)
	(arc
		(start 387.087872 -288.178494)
		(mid 386.804916 -288.102317)
		(end 386.52196 -288.178494)
		(width 0.0889)
		(layer "In13.Cu")
		(net "M_H_CPU0_SB_DQ<21>")
	)
	(arc
		(start 392.401044 -288.0868)
		(mid 392.199533 -288.192728)
		(end 391.974832 -288.229294)
		(width 0.0889)
		(layer "In13.Cu")
		(net "M_H_CPU0_SB_DQ<21>")
	)
	(arc
		(start 386.147818 -288.178494)
		(mid 385.864862 -288.102317)
		(end 385.581906 -288.178494)
		(width 0.0889)
		(layer "In13.Cu")
		(net "M_H_CPU0_SB_DQ<21>")
	)
	(arc
		(start 384.63347 -288.18332)
		(mid 384.449962 -288.228845)
		(end 384.26771 -288.178494)
		(width 0.0889)
		(layer "In13.Cu")
		(net "M_H_CPU0_SB_DQ<21>")
	)
	(arc
		(start 388.967726 -288.178494)
		(mid 388.68477 -288.102317)
		(end 388.401814 -288.178494)
		(width 0.0889)
		(layer "In13.Cu")
		(net "M_H_CPU0_SB_DQ<21>")
	)
	(arc
		(start 389.90778 -288.178494)
		(mid 389.624824 -288.102317)
		(end 389.341868 -288.178494)
		(width 0.0889)
		(layer "In13.Cu")
		(net "M_H_CPU0_SB_DQ<21>")
	)
	(arc
		(start 383.693416 -288.18332)
		(mid 383.509908 -288.228845)
		(end 383.327656 -288.178494)
		(width 0.0889)
		(layer "In13.Cu")
		(net "M_H_CPU0_SB_DQ<21>")
	)
	(arc
		(start 389.333486 -288.18332)
		(mid 389.149978 -288.228845)
		(end 388.967726 -288.178494)
		(width 0.0889)
		(layer "In13.Cu")
		(net "M_H_CPU0_SB_DQ<21>")
	)
	(arc
		(start 390.281922 -288.178494)
		(mid 390.099671 -288.228878)
		(end 389.916162 -288.18332)
		(width 0.0889)
		(layer "In13.Cu")
		(net "M_H_CPU0_SB_DQ<21>")
	)
	(arc
		(start 387.46176 -288.178494)
		(mid 387.274816 -288.228783)
		(end 387.087872 -288.178494)
		(width 0.0889)
		(layer "In13.Cu")
		(net "M_H_CPU0_SB_DQ<21>")
	)
	(arc
		(start 385.581906 -288.178494)
		(mid 385.399655 -288.228878)
		(end 385.216146 -288.18332)
		(width 0.0889)
		(layer "In13.Cu")
		(net "M_H_CPU0_SB_DQ<21>")
	)
	(arc
		(start 390.847834 -288.178494)
		(mid 390.564878 -288.102317)
		(end 390.281922 -288.178494)
		(width 0.0889)
		(layer "In13.Cu")
		(net "M_H_CPU0_SB_DQ<21>")
	)
	(arc
		(start 386.52196 -288.178494)
		(mid 386.339709 -288.228878)
		(end 386.1562 -288.18332)
		(width 0.0889)
		(layer "In13.Cu")
		(net "M_H_CPU0_SB_DQ<21>")
	)
	(arc
		(start 383.327656 -288.178494)
		(mid 383.079796 -288.103411)
		(end 382.824482 -288.146998)
		(width 0.0889)
		(layer "In13.Cu")
		(net "M_H_CPU0_SB_DQ<21>")
	)
	(arc
		(start 391.974832 -288.229294)
		(mid 391.877879 -288.216263)
		(end 391.787634 -288.178494)
		(width 0.0889)
		(layer "In13.Cu")
		(net "M_H_CPU0_SB_DQ<21>")
	)
	(arc
		(start 388.393432 -288.18332)
		(mid 388.209924 -288.228845)
		(end 388.027672 -288.178494)
		(width 0.0889)
		(layer "In13.Cu")
		(net "M_H_CPU0_SB_DQ<21>")
	)
	(arc
		(start 388.027672 -288.178494)
		(mid 387.744716 -288.102317)
		(end 387.46176 -288.178494)
		(width 0.0889)
		(layer "In13.Cu")
		(net "M_H_CPU0_SB_DQ<21>")
	)
	(arc
		(start 384.26771 -288.178494)
		(mid 383.984754 -288.102317)
		(end 383.701798 -288.178494)
		(width 0.0889)
		(layer "In13.Cu")
		(net "M_H_CPU0_SB_DQ<21>")
	)
	(segment
		(start 383.517902 -286.780224)
		(end 383.984754 -287.045908)
		(width 0.10668)
		(layer "F.Cu")
		(net "M_H_CPU0_SB_DQ<20>")
	)
	(segment
		(start 386.043424 -287.373314)
		(end 386.051806 -287.368488)
		(width 0.0889)
		(layer "In13.Cu")
		(net "M_H_CPU0_SB_DQ<20>")
	)
	(segment
		(start 421.71747 -306.569872)
		(end 422.152318 -306.135024)
		(width 0.14478)
		(layer "In13.Cu")
		(net "M_H_CPU0_SB_DQ<20>")
	)
	(segment
		(start 388.497826 -287.368488)
		(end 388.506208 -287.373314)
		(width 0.0889)
		(layer "In13.Cu")
		(net "M_H_CPU0_SB_DQ<20>")
	)
	(segment
		(start 383.984754 -287.045908)
		(end 384.138932 -287.311338)
		(width 0.0889)
		(layer "In13.Cu")
		(net "M_H_CPU0_SB_DQ<20>")
	)
	(segment
		(start 412.754064 -306.56022)
		(end 414.183068 -306.56022)
		(width 0.14478)
		(layer "In13.Cu")
		(net "M_H_CPU0_SB_DQ<20>")
	)
	(segment
		(start 395.057884 -288.07537)
		(end 395.701266 -288.718752)
		(width 0.0889)
		(layer "In13.Cu")
		(net "M_H_CPU0_SB_DQ<20>")
	)
	(segment
		(start 400.016218 -293.033704)
		(end 400.016218 -298.055792)
		(width 0.14478)
		(layer "In13.Cu")
		(net "M_H_CPU0_SB_DQ<20>")
	)
	(segment
		(start 423.247058 -306.716684)
		(end 423.247058 -306.279804)
		(width 0.14478)
		(layer "In13.Cu")
		(net "M_H_CPU0_SB_DQ<20>")
	)
	(segment
		(start 423.247058 -306.279804)
		(end 423.391838 -306.135024)
		(width 0.14478)
		(layer "In13.Cu")
		(net "M_H_CPU0_SB_DQ<20>")
	)
	(segment
		(start 422.152318 -306.135024)
		(end 422.551098 -306.135024)
		(width 0.14478)
		(layer "In13.Cu")
		(net "M_H_CPU0_SB_DQ<20>")
	)
	(segment
		(start 422.695878 -306.716684)
		(end 422.840658 -306.861464)
		(width 0.14478)
		(layer "In13.Cu")
		(net "M_H_CPU0_SB_DQ<20>")
	)
	(segment
		(start 393.763754 -287.41751)
		(end 394.421614 -288.07537)
		(width 0.0889)
		(layer "In13.Cu")
		(net "M_H_CPU0_SB_DQ<20>")
	)
	(segment
		(start 386.983478 -287.373314)
		(end 386.99186 -287.368488)
		(width 0.0889)
		(layer "In13.Cu")
		(net "M_H_CPU0_SB_DQ<20>")
	)
	(segment
		(start 391.974578 -287.292288)
		(end 392.773662 -287.292288)
		(width 0.0889)
		(layer "In13.Cu")
		(net "M_H_CPU0_SB_DQ<20>")
	)
	(segment
		(start 415.032952 -305.710336)
		(end 417.690808 -305.710336)
		(width 0.14478)
		(layer "In13.Cu")
		(net "M_H_CPU0_SB_DQ<20>")
	)
	(segment
		(start 423.391838 -306.135024)
		(end 424.012106 -306.135024)
		(width 0.14478)
		(layer "In13.Cu")
		(net "M_H_CPU0_SB_DQ<20>")
	)
	(segment
		(start 395.701266 -288.718752)
		(end 400.016218 -293.033704)
		(width 0.14478)
		(layer "In13.Cu")
		(net "M_H_CPU0_SB_DQ<20>")
	)
	(segment
		(start 408.16149 -306.201064)
		(end 412.394908 -306.201064)
		(width 0.14478)
		(layer "In13.Cu")
		(net "M_H_CPU0_SB_DQ<20>")
	)
	(segment
		(start 394.421614 -288.07537)
		(end 395.057884 -288.07537)
		(width 0.0889)
		(layer "In13.Cu")
		(net "M_H_CPU0_SB_DQ<20>")
	)
	(segment
		(start 414.183068 -306.56022)
		(end 415.032952 -305.710336)
		(width 0.14478)
		(layer "In13.Cu")
		(net "M_H_CPU0_SB_DQ<20>")
	)
	(segment
		(start 422.695878 -306.279804)
		(end 422.695878 -306.716684)
		(width 0.14478)
		(layer "In13.Cu")
		(net "M_H_CPU0_SB_DQ<20>")
	)
	(segment
		(start 418.550344 -306.569872)
		(end 421.71747 -306.569872)
		(width 0.14478)
		(layer "In13.Cu")
		(net "M_H_CPU0_SB_DQ<20>")
	)
	(segment
		(start 393.090908 -287.41751)
		(end 393.763754 -287.41751)
		(width 0.0889)
		(layer "In13.Cu")
		(net "M_H_CPU0_SB_DQ<20>")
	)
	(segment
		(start 423.102278 -306.861464)
		(end 423.247058 -306.716684)
		(width 0.14478)
		(layer "In13.Cu")
		(net "M_H_CPU0_SB_DQ<20>")
	)
	(segment
		(start 417.690808 -305.710336)
		(end 418.550344 -306.569872)
		(width 0.14478)
		(layer "In13.Cu")
		(net "M_H_CPU0_SB_DQ<20>")
	)
	(segment
		(start 412.394908 -306.201064)
		(end 412.754064 -306.56022)
		(width 0.14478)
		(layer "In13.Cu")
		(net "M_H_CPU0_SB_DQ<20>")
	)
	(segment
		(start 387.557772 -287.368488)
		(end 387.566154 -287.373314)
		(width 0.0889)
		(layer "In13.Cu")
		(net "M_H_CPU0_SB_DQ<20>")
	)
	(segment
		(start 400.016218 -298.055792)
		(end 408.16149 -306.201064)
		(width 0.14478)
		(layer "In13.Cu")
		(net "M_H_CPU0_SB_DQ<20>")
	)
	(segment
		(start 422.551098 -306.135024)
		(end 422.695878 -306.279804)
		(width 0.14478)
		(layer "In13.Cu")
		(net "M_H_CPU0_SB_DQ<20>")
	)
	(segment
		(start 422.840658 -306.861464)
		(end 423.102278 -306.861464)
		(width 0.14478)
		(layer "In13.Cu")
		(net "M_H_CPU0_SB_DQ<20>")
	)
	(segment
		(start 391.317734 -287.368488)
		(end 391.326116 -287.373314)
		(width 0.0889)
		(layer "In13.Cu")
		(net "M_H_CPU0_SB_DQ<20>")
	)
	(segment
		(start 392.773662 -287.292288)
		(end 393.090908 -287.41751)
		(width 0.0889)
		(layer "In13.Cu")
		(net "M_H_CPU0_SB_DQ<20>")
	)
	(segment
		(start 384.138932 -287.311338)
		(end 384.235198 -287.336738)
		(width 0.0889)
		(layer "In13.Cu")
		(net "M_H_CPU0_SB_DQ<20>")
	)
	(segment
		(start 390.74344 -287.373314)
		(end 390.751822 -287.368488)
		(width 0.0889)
		(layer "In13.Cu")
		(net "M_H_CPU0_SB_DQ<20>")
	)
	(arc
		(start 386.617718 -287.368488)
		(mid 386.799969 -287.418838)
		(end 386.983478 -287.373314)
		(width 0.0889)
		(layer "In13.Cu")
		(net "M_H_CPU0_SB_DQ<20>")
	)
	(arc
		(start 389.811768 -287.368488)
		(mid 390.094724 -287.292345)
		(end 390.37768 -287.368488)
		(width 0.0889)
		(layer "In13.Cu")
		(net "M_H_CPU0_SB_DQ<20>")
	)
	(arc
		(start 390.751822 -287.368488)
		(mid 391.034778 -287.292345)
		(end 391.317734 -287.368488)
		(width 0.0889)
		(layer "In13.Cu")
		(net "M_H_CPU0_SB_DQ<20>")
	)
	(arc
		(start 388.506208 -287.373314)
		(mid 388.689716 -287.418808)
		(end 388.871968 -287.368488)
		(width 0.0889)
		(layer "In13.Cu")
		(net "M_H_CPU0_SB_DQ<20>")
	)
	(arc
		(start 388.871968 -287.368488)
		(mid 389.154924 -287.292345)
		(end 389.43788 -287.368488)
		(width 0.0889)
		(layer "In13.Cu")
		(net "M_H_CPU0_SB_DQ<20>")
	)
	(arc
		(start 385.111752 -287.368488)
		(mid 385.394708 -287.292345)
		(end 385.677664 -287.368488)
		(width 0.0889)
		(layer "In13.Cu")
		(net "M_H_CPU0_SB_DQ<20>")
	)
	(arc
		(start 384.737864 -287.368488)
		(mid 384.924808 -287.418743)
		(end 385.111752 -287.368488)
		(width 0.0889)
		(layer "In13.Cu")
		(net "M_H_CPU0_SB_DQ<20>")
	)
	(arc
		(start 386.99186 -287.368488)
		(mid 387.274816 -287.292345)
		(end 387.557772 -287.368488)
		(width 0.0889)
		(layer "In13.Cu")
		(net "M_H_CPU0_SB_DQ<20>")
	)
	(arc
		(start 391.691876 -287.368488)
		(mid 391.79821 -287.320724)
		(end 391.912094 -287.295844)
		(width 0.0889)
		(layer "In13.Cu")
		(net "M_H_CPU0_SB_DQ<20>")
	)
	(arc
		(start 391.326116 -287.373314)
		(mid 391.509624 -287.418808)
		(end 391.691876 -287.368488)
		(width 0.0889)
		(layer "In13.Cu")
		(net "M_H_CPU0_SB_DQ<20>")
	)
	(arc
		(start 384.235198 -287.336738)
		(mid 384.490263 -287.293407)
		(end 384.737864 -287.368488)
		(width 0.0889)
		(layer "In13.Cu")
		(net "M_H_CPU0_SB_DQ<20>")
	)
	(arc
		(start 387.931914 -287.368488)
		(mid 388.21487 -287.292345)
		(end 388.497826 -287.368488)
		(width 0.0889)
		(layer "In13.Cu")
		(net "M_H_CPU0_SB_DQ<20>")
	)
	(arc
		(start 385.677664 -287.368488)
		(mid 385.859915 -287.418838)
		(end 386.043424 -287.373314)
		(width 0.0889)
		(layer "In13.Cu")
		(net "M_H_CPU0_SB_DQ<20>")
	)
	(arc
		(start 386.051806 -287.368488)
		(mid 386.334762 -287.292345)
		(end 386.617718 -287.368488)
		(width 0.0889)
		(layer "In13.Cu")
		(net "M_H_CPU0_SB_DQ<20>")
	)
	(arc
		(start 390.37768 -287.368488)
		(mid 390.559931 -287.418838)
		(end 390.74344 -287.373314)
		(width 0.0889)
		(layer "In13.Cu")
		(net "M_H_CPU0_SB_DQ<20>")
	)
	(arc
		(start 387.566154 -287.373314)
		(mid 387.749662 -287.418808)
		(end 387.931914 -287.368488)
		(width 0.0889)
		(layer "In13.Cu")
		(net "M_H_CPU0_SB_DQ<20>")
	)
	(arc
		(start 389.43788 -287.368488)
		(mid 389.624824 -287.418743)
		(end 389.811768 -287.368488)
		(width 0.0889)
		(layer "In13.Cu")
		(net "M_H_CPU0_SB_DQ<20>")
	)
	(arc
		(start 391.912094 -287.295844)
		(mid 391.943287 -287.293196)
		(end 391.974578 -287.292288)
		(width 0.0889)
		(layer "In13.Cu")
		(net "M_H_CPU0_SB_DQ<20>")
	)
	(segment
		(start 382.107948 -274.630134)
		(end 382.5748 -274.896072)
		(width 0.10668)
		(layer "F.Cu")
		(net "M_H_CPU0_SB_DQ<1>")
	)
	(segment
		(start 396.000986 -273.84883)
		(end 402.106384 -273.84883)
		(width 0.14478)
		(layer "In13.Cu")
		(net "M_H_CPU0_SB_DQ<1>")
	)
	(segment
		(start 382.728724 -275.161502)
		(end 382.824736 -275.186902)
		(width 0.0889)
		(layer "In13.Cu")
		(net "M_H_CPU0_SB_DQ<1>")
	)
	(segment
		(start 421.923972 -283.195776)
		(end 421.93464 -283.185108)
		(width 0.14478)
		(layer "In13.Cu")
		(net "M_H_CPU0_SB_DQ<1>")
	)
	(segment
		(start 383.693416 -275.223478)
		(end 383.701798 -275.218652)
		(width 0.0889)
		(layer "In13.Cu")
		(net "M_H_CPU0_SB_DQ<1>")
	)
	(segment
		(start 393.764516 -274.927568)
		(end 394.683234 -274.00885)
		(width 0.0889)
		(layer "In13.Cu")
		(net "M_H_CPU0_SB_DQ<1>")
	)
	(segment
		(start 414.765744 -282.760166)
		(end 417.713414 -282.760166)
		(width 0.14478)
		(layer "In13.Cu")
		(net "M_H_CPU0_SB_DQ<1>")
	)
	(segment
		(start 420.923974 -283.61005)
		(end 421.923972 -283.195776)
		(width 0.14478)
		(layer "In13.Cu")
		(net "M_H_CPU0_SB_DQ<1>")
	)
	(segment
		(start 395.437614 -273.84883)
		(end 396.000986 -273.84883)
		(width 0.0889)
		(layer "In13.Cu")
		(net "M_H_CPU0_SB_DQ<1>")
	)
	(segment
		(start 402.106384 -273.84883)
		(end 411.867604 -283.61005)
		(width 0.14478)
		(layer "In13.Cu")
		(net "M_H_CPU0_SB_DQ<1>")
	)
	(segment
		(start 384.63347 -275.223478)
		(end 384.641852 -275.218652)
		(width 0.0889)
		(layer "In13.Cu")
		(net "M_H_CPU0_SB_DQ<1>")
	)
	(segment
		(start 421.93464 -283.185108)
		(end 424.012106 -283.185108)
		(width 0.14478)
		(layer "In13.Cu")
		(net "M_H_CPU0_SB_DQ<1>")
	)
	(segment
		(start 394.683234 -274.00885)
		(end 395.277594 -274.00885)
		(width 0.0889)
		(layer "In13.Cu")
		(net "M_H_CPU0_SB_DQ<1>")
	)
	(segment
		(start 389.333486 -275.223478)
		(end 389.341868 -275.218652)
		(width 0.0889)
		(layer "In13.Cu")
		(net "M_H_CPU0_SB_DQ<1>")
	)
	(segment
		(start 386.147818 -275.218652)
		(end 386.1562 -275.223478)
		(width 0.0889)
		(layer "In13.Cu")
		(net "M_H_CPU0_SB_DQ<1>")
	)
	(segment
		(start 391.787634 -275.218652)
		(end 391.796016 -275.223478)
		(width 0.0889)
		(layer "In13.Cu")
		(net "M_H_CPU0_SB_DQ<1>")
	)
	(segment
		(start 395.277594 -274.00885)
		(end 395.437614 -273.84883)
		(width 0.0889)
		(layer "In13.Cu")
		(net "M_H_CPU0_SB_DQ<1>")
	)
	(segment
		(start 419.765226 -283.61005)
		(end 420.923974 -283.61005)
		(width 0.14478)
		(layer "In13.Cu")
		(net "M_H_CPU0_SB_DQ<1>")
	)
	(segment
		(start 393.6746 -274.987766)
		(end 393.764516 -274.927568)
		(width 0.0889)
		(layer "In13.Cu")
		(net "M_H_CPU0_SB_DQ<1>")
	)
	(segment
		(start 392.718036 -275.212556)
		(end 392.72845 -275.218652)
		(width 0.0889)
		(layer "In13.Cu")
		(net "M_H_CPU0_SB_DQ<1>")
	)
	(segment
		(start 393.369038 -275.114512)
		(end 393.6746 -274.987766)
		(width 0.0889)
		(layer "In13.Cu")
		(net "M_H_CPU0_SB_DQ<1>")
	)
	(segment
		(start 385.207764 -275.218652)
		(end 385.216146 -275.223478)
		(width 0.0889)
		(layer "In13.Cu")
		(net "M_H_CPU0_SB_DQ<1>")
	)
	(segment
		(start 417.713414 -282.760166)
		(end 419.765226 -283.61005)
		(width 0.14478)
		(layer "In13.Cu")
		(net "M_H_CPU0_SB_DQ<1>")
	)
	(segment
		(start 411.867604 -283.61005)
		(end 413.91586 -283.61005)
		(width 0.14478)
		(layer "In13.Cu")
		(net "M_H_CPU0_SB_DQ<1>")
	)
	(segment
		(start 389.90778 -275.218652)
		(end 389.916162 -275.223478)
		(width 0.0889)
		(layer "In13.Cu")
		(net "M_H_CPU0_SB_DQ<1>")
	)
	(segment
		(start 382.5748 -274.896072)
		(end 382.728724 -275.161502)
		(width 0.0889)
		(layer "In13.Cu")
		(net "M_H_CPU0_SB_DQ<1>")
	)
	(segment
		(start 413.91586 -283.61005)
		(end 414.765744 -282.760166)
		(width 0.14478)
		(layer "In13.Cu")
		(net "M_H_CPU0_SB_DQ<1>")
	)
	(segment
		(start 388.393432 -275.223478)
		(end 388.401814 -275.218652)
		(width 0.0889)
		(layer "In13.Cu")
		(net "M_H_CPU0_SB_DQ<1>")
	)
	(arc
		(start 387.087872 -275.218652)
		(mid 387.274816 -275.268907)
		(end 387.46176 -275.218652)
		(width 0.0889)
		(layer "In13.Cu")
		(net "M_H_CPU0_SB_DQ<1>")
	)
	(arc
		(start 392.72845 -275.218652)
		(mid 392.914402 -275.267604)
		(end 393.098782 -275.213064)
		(width 0.0889)
		(layer "In13.Cu")
		(net "M_H_CPU0_SB_DQ<1>")
	)
	(arc
		(start 390.281922 -275.218652)
		(mid 390.564878 -275.142475)
		(end 390.847834 -275.218652)
		(width 0.0889)
		(layer "In13.Cu")
		(net "M_H_CPU0_SB_DQ<1>")
	)
	(arc
		(start 383.701798 -275.218652)
		(mid 383.984754 -275.142475)
		(end 384.26771 -275.218652)
		(width 0.0889)
		(layer "In13.Cu")
		(net "M_H_CPU0_SB_DQ<1>")
	)
	(arc
		(start 388.027672 -275.218652)
		(mid 388.209923 -275.269002)
		(end 388.393432 -275.223478)
		(width 0.0889)
		(layer "In13.Cu")
		(net "M_H_CPU0_SB_DQ<1>")
	)
	(arc
		(start 391.221722 -275.218652)
		(mid 391.504678 -275.142475)
		(end 391.787634 -275.218652)
		(width 0.0889)
		(layer "In13.Cu")
		(net "M_H_CPU0_SB_DQ<1>")
	)
	(arc
		(start 385.581906 -275.218652)
		(mid 385.864862 -275.142475)
		(end 386.147818 -275.218652)
		(width 0.0889)
		(layer "In13.Cu")
		(net "M_H_CPU0_SB_DQ<1>")
	)
	(arc
		(start 391.796016 -275.223478)
		(mid 391.979778 -275.269094)
		(end 392.162284 -275.218652)
		(width 0.0889)
		(layer "In13.Cu")
		(net "M_H_CPU0_SB_DQ<1>")
	)
	(arc
		(start 393.256008 -275.15058)
		(mid 393.313536 -275.13572)
		(end 393.369038 -275.114512)
		(width 0.0889)
		(layer "In13.Cu")
		(net "M_H_CPU0_SB_DQ<1>")
	)
	(arc
		(start 388.401814 -275.218652)
		(mid 388.68477 -275.142475)
		(end 388.967726 -275.218652)
		(width 0.0889)
		(layer "In13.Cu")
		(net "M_H_CPU0_SB_DQ<1>")
	)
	(arc
		(start 393.098782 -275.213064)
		(mid 393.174546 -275.174648)
		(end 393.256008 -275.15058)
		(width 0.0889)
		(layer "In13.Cu")
		(net "M_H_CPU0_SB_DQ<1>")
	)
	(arc
		(start 383.327656 -275.218652)
		(mid 383.509907 -275.269002)
		(end 383.693416 -275.223478)
		(width 0.0889)
		(layer "In13.Cu")
		(net "M_H_CPU0_SB_DQ<1>")
	)
	(arc
		(start 384.641852 -275.218652)
		(mid 384.924808 -275.142475)
		(end 385.207764 -275.218652)
		(width 0.0889)
		(layer "In13.Cu")
		(net "M_H_CPU0_SB_DQ<1>")
	)
	(arc
		(start 392.162284 -275.218652)
		(mid 392.439351 -275.142381)
		(end 392.718036 -275.212556)
		(width 0.0889)
		(layer "In13.Cu")
		(net "M_H_CPU0_SB_DQ<1>")
	)
	(arc
		(start 390.847834 -275.218652)
		(mid 391.034778 -275.268907)
		(end 391.221722 -275.218652)
		(width 0.0889)
		(layer "In13.Cu")
		(net "M_H_CPU0_SB_DQ<1>")
	)
	(arc
		(start 386.52196 -275.218652)
		(mid 386.804916 -275.142475)
		(end 387.087872 -275.218652)
		(width 0.0889)
		(layer "In13.Cu")
		(net "M_H_CPU0_SB_DQ<1>")
	)
	(arc
		(start 386.1562 -275.223478)
		(mid 386.339708 -275.268972)
		(end 386.52196 -275.218652)
		(width 0.0889)
		(layer "In13.Cu")
		(net "M_H_CPU0_SB_DQ<1>")
	)
	(arc
		(start 384.26771 -275.218652)
		(mid 384.449961 -275.269002)
		(end 384.63347 -275.223478)
		(width 0.0889)
		(layer "In13.Cu")
		(net "M_H_CPU0_SB_DQ<1>")
	)
	(arc
		(start 382.824736 -275.186902)
		(mid 383.079944 -275.143425)
		(end 383.327656 -275.218652)
		(width 0.0889)
		(layer "In13.Cu")
		(net "M_H_CPU0_SB_DQ<1>")
	)
	(arc
		(start 385.216146 -275.223478)
		(mid 385.399654 -275.268972)
		(end 385.581906 -275.218652)
		(width 0.0889)
		(layer "In13.Cu")
		(net "M_H_CPU0_SB_DQ<1>")
	)
	(arc
		(start 388.967726 -275.218652)
		(mid 389.149977 -275.269002)
		(end 389.333486 -275.223478)
		(width 0.0889)
		(layer "In13.Cu")
		(net "M_H_CPU0_SB_DQ<1>")
	)
	(arc
		(start 389.341868 -275.218652)
		(mid 389.624824 -275.142475)
		(end 389.90778 -275.218652)
		(width 0.0889)
		(layer "In13.Cu")
		(net "M_H_CPU0_SB_DQ<1>")
	)
	(arc
		(start 389.916162 -275.223478)
		(mid 390.09967 -275.268972)
		(end 390.281922 -275.218652)
		(width 0.0889)
		(layer "In13.Cu")
		(net "M_H_CPU0_SB_DQ<1>")
	)
	(arc
		(start 387.46176 -275.218652)
		(mid 387.744716 -275.142475)
		(end 388.027672 -275.218652)
		(width 0.0889)
		(layer "In13.Cu")
		(net "M_H_CPU0_SB_DQ<1>")
	)
	(segment
		(start 382.577848 -285.160212)
		(end 383.0447 -285.42615)
		(width 0.10668)
		(layer "F.Cu")
		(net "M_H_CPU0_SB_DQ<19>")
	)
	(segment
		(start 414.020508 -303.160176)
		(end 415.27095 -301.909734)
		(width 0.14478)
		(layer "In13.Cu")
		(net "M_H_CPU0_SB_DQ<19>")
	)
	(segment
		(start 393.198096 -285.103824)
		(end 393.216384 -285.09341)
		(width 0.0889)
		(layer "In13.Cu")
		(net "M_H_CPU0_SB_DQ<19>")
	)
	(segment
		(start 412.239206 -302.764698)
		(end 412.383986 -302.909478)
		(width 0.14478)
		(layer "In13.Cu")
		(net "M_H_CPU0_SB_DQ<19>")
	)
	(segment
		(start 392.62431 -285.098744)
		(end 392.632692 -285.10357)
		(width 0.0889)
		(layer "In13.Cu")
		(net "M_H_CPU0_SB_DQ<19>")
	)
	(segment
		(start 417.55695 -302.054514)
		(end 417.70173 -301.909734)
		(width 0.14478)
		(layer "In13.Cu")
		(net "M_H_CPU0_SB_DQ<19>")
	)
	(segment
		(start 387.557772 -285.10357)
		(end 387.566154 -285.098744)
		(width 0.0889)
		(layer "In13.Cu")
		(net "M_H_CPU0_SB_DQ<19>")
	)
	(segment
		(start 390.74344 -285.098744)
		(end 390.751822 -285.10357)
		(width 0.0889)
		(layer "In13.Cu")
		(net "M_H_CPU0_SB_DQ<19>")
	)
	(segment
		(start 413.079946 -302.764698)
		(end 413.341566 -302.764698)
		(width 0.14478)
		(layer "In13.Cu")
		(net "M_H_CPU0_SB_DQ<19>")
	)
	(segment
		(start 393.192508 -285.107126)
		(end 393.198096 -285.103824)
		(width 0.0889)
		(layer "In13.Cu")
		(net "M_H_CPU0_SB_DQ<19>")
	)
	(segment
		(start 388.497826 -285.10357)
		(end 388.506208 -285.098744)
		(width 0.0889)
		(layer "In13.Cu")
		(net "M_H_CPU0_SB_DQ<19>")
	)
	(segment
		(start 411.832806 -303.015396)
		(end 411.832806 -302.909478)
		(width 0.14478)
		(layer "In13.Cu")
		(net "M_H_CPU0_SB_DQ<19>")
	)
	(segment
		(start 416.86099 -301.909734)
		(end 417.00577 -302.054514)
		(width 0.14478)
		(layer "In13.Cu")
		(net "M_H_CPU0_SB_DQ<19>")
	)
	(segment
		(start 416.59937 -301.909734)
		(end 416.86099 -301.909734)
		(width 0.14478)
		(layer "In13.Cu")
		(net "M_H_CPU0_SB_DQ<19>")
	)
	(segment
		(start 415.27095 -301.909734)
		(end 415.75863 -301.909734)
		(width 0.14478)
		(layer "In13.Cu")
		(net "M_H_CPU0_SB_DQ<19>")
	)
	(segment
		(start 412.935166 -303.351438)
		(end 412.935166 -302.909478)
		(width 0.14478)
		(layer "In13.Cu")
		(net "M_H_CPU0_SB_DQ<19>")
	)
	(segment
		(start 413.486346 -303.015396)
		(end 413.631126 -303.160176)
		(width 0.14478)
		(layer "In13.Cu")
		(net "M_H_CPU0_SB_DQ<19>")
	)
	(segment
		(start 413.631126 -303.160176)
		(end 414.020508 -303.160176)
		(width 0.14478)
		(layer "In13.Cu")
		(net "M_H_CPU0_SB_DQ<19>")
	)
	(segment
		(start 393.288012 -285.05023)
		(end 394.118846 -285.05023)
		(width 0.0889)
		(layer "In13.Cu")
		(net "M_H_CPU0_SB_DQ<19>")
	)
	(segment
		(start 382.890776 -285.16072)
		(end 382.913128 -285.077408)
		(width 0.0889)
		(layer "In13.Cu")
		(net "M_H_CPU0_SB_DQ<19>")
	)
	(segment
		(start 416.45459 -302.054514)
		(end 416.59937 -301.909734)
		(width 0.14478)
		(layer "In13.Cu")
		(net "M_H_CPU0_SB_DQ<19>")
	)
	(segment
		(start 394.118846 -285.05023)
		(end 394.609066 -285.54045)
		(width 0.0889)
		(layer "In13.Cu")
		(net "M_H_CPU0_SB_DQ<19>")
	)
	(segment
		(start 419.496748 -303.15027)
		(end 419.912038 -302.73498)
		(width 0.14478)
		(layer "In13.Cu")
		(net "M_H_CPU0_SB_DQ<19>")
	)
	(segment
		(start 410.875226 -302.764698)
		(end 411.136846 -302.764698)
		(width 0.14478)
		(layer "In13.Cu")
		(net "M_H_CPU0_SB_DQ<19>")
	)
	(segment
		(start 411.136846 -302.764698)
		(end 411.281626 -302.909478)
		(width 0.14478)
		(layer "In13.Cu")
		(net "M_H_CPU0_SB_DQ<19>")
	)
	(segment
		(start 386.983478 -285.098744)
		(end 386.99186 -285.10357)
		(width 0.0889)
		(layer "In13.Cu")
		(net "M_H_CPU0_SB_DQ<19>")
	)
	(segment
		(start 396.278354 -285.97733)
		(end 402.304758 -292.003734)
		(width 0.14478)
		(layer "In13.Cu")
		(net "M_H_CPU0_SB_DQ<19>")
	)
	(segment
		(start 391.317734 -285.10357)
		(end 391.326116 -285.098744)
		(width 0.0889)
		(layer "In13.Cu")
		(net "M_H_CPU0_SB_DQ<19>")
	)
	(segment
		(start 419.111684 -303.15027)
		(end 419.496748 -303.15027)
		(width 0.14478)
		(layer "In13.Cu")
		(net "M_H_CPU0_SB_DQ<19>")
	)
	(segment
		(start 417.162488 -302.711358)
		(end 417.400232 -302.711358)
		(width 0.14478)
		(layer "In13.Cu")
		(net "M_H_CPU0_SB_DQ<19>")
	)
	(segment
		(start 417.70173 -301.909734)
		(end 417.871148 -301.909734)
		(width 0.14478)
		(layer "In13.Cu")
		(net "M_H_CPU0_SB_DQ<19>")
	)
	(segment
		(start 416.45459 -302.55464)
		(end 416.45459 -302.054514)
		(width 0.14478)
		(layer "In13.Cu")
		(net "M_H_CPU0_SB_DQ<19>")
	)
	(segment
		(start 412.383986 -302.909478)
		(end 412.383986 -303.351438)
		(width 0.14478)
		(layer "In13.Cu")
		(net "M_H_CPU0_SB_DQ<19>")
	)
	(segment
		(start 410.730446 -302.909478)
		(end 410.875226 -302.764698)
		(width 0.14478)
		(layer "In13.Cu")
		(net "M_H_CPU0_SB_DQ<19>")
	)
	(segment
		(start 416.060128 -302.711358)
		(end 416.297872 -302.711358)
		(width 0.14478)
		(layer "In13.Cu")
		(net "M_H_CPU0_SB_DQ<19>")
	)
	(segment
		(start 395.597634 -285.97733)
		(end 395.790166 -285.97733)
		(width 0.0889)
		(layer "In13.Cu")
		(net "M_H_CPU0_SB_DQ<19>")
	)
	(segment
		(start 386.043424 -285.098744)
		(end 386.051806 -285.10357)
		(width 0.0889)
		(layer "In13.Cu")
		(net "M_H_CPU0_SB_DQ<19>")
	)
	(segment
		(start 411.977586 -302.764698)
		(end 412.239206 -302.764698)
		(width 0.14478)
		(layer "In13.Cu")
		(net "M_H_CPU0_SB_DQ<19>")
	)
	(segment
		(start 393.216384 -285.09341)
		(end 393.288012 -285.05023)
		(width 0.0889)
		(layer "In13.Cu")
		(net "M_H_CPU0_SB_DQ<19>")
	)
	(segment
		(start 417.871148 -301.909734)
		(end 419.111684 -303.15027)
		(width 0.14478)
		(layer "In13.Cu")
		(net "M_H_CPU0_SB_DQ<19>")
	)
	(segment
		(start 394.609066 -285.54045)
		(end 395.160754 -285.54045)
		(width 0.0889)
		(layer "In13.Cu")
		(net "M_H_CPU0_SB_DQ<19>")
	)
	(segment
		(start 415.90341 -302.55464)
		(end 416.060128 -302.711358)
		(width 0.14478)
		(layer "In13.Cu")
		(net "M_H_CPU0_SB_DQ<19>")
	)
	(segment
		(start 411.688026 -303.160176)
		(end 411.832806 -303.015396)
		(width 0.14478)
		(layer "In13.Cu")
		(net "M_H_CPU0_SB_DQ<19>")
	)
	(segment
		(start 417.00577 -302.054514)
		(end 417.00577 -302.55464)
		(width 0.14478)
		(layer "In13.Cu")
		(net "M_H_CPU0_SB_DQ<19>")
	)
	(segment
		(start 417.00577 -302.55464)
		(end 417.162488 -302.711358)
		(width 0.14478)
		(layer "In13.Cu")
		(net "M_H_CPU0_SB_DQ<19>")
	)
	(segment
		(start 415.75863 -301.909734)
		(end 415.90341 -302.054514)
		(width 0.14478)
		(layer "In13.Cu")
		(net "M_H_CPU0_SB_DQ<19>")
	)
	(segment
		(start 391.691876 -285.10357)
		(end 391.70229 -285.109666)
		(width 0.0889)
		(layer "In13.Cu")
		(net "M_H_CPU0_SB_DQ<19>")
	)
	(segment
		(start 410.730446 -303.015396)
		(end 410.730446 -302.909478)
		(width 0.14478)
		(layer "In13.Cu")
		(net "M_H_CPU0_SB_DQ<19>")
	)
	(segment
		(start 417.400232 -302.711358)
		(end 417.55695 -302.55464)
		(width 0.14478)
		(layer "In13.Cu")
		(net "M_H_CPU0_SB_DQ<19>")
	)
	(segment
		(start 412.383986 -303.351438)
		(end 412.528766 -303.496218)
		(width 0.14478)
		(layer "In13.Cu")
		(net "M_H_CPU0_SB_DQ<19>")
	)
	(segment
		(start 395.790166 -285.97733)
		(end 396.278354 -285.97733)
		(width 0.14478)
		(layer "In13.Cu")
		(net "M_H_CPU0_SB_DQ<19>")
	)
	(segment
		(start 411.832806 -302.909478)
		(end 411.977586 -302.764698)
		(width 0.14478)
		(layer "In13.Cu")
		(net "M_H_CPU0_SB_DQ<19>")
	)
	(segment
		(start 413.341566 -302.764698)
		(end 413.486346 -302.909478)
		(width 0.14478)
		(layer "In13.Cu")
		(net "M_H_CPU0_SB_DQ<19>")
	)
	(segment
		(start 412.790386 -303.496218)
		(end 412.935166 -303.351438)
		(width 0.14478)
		(layer "In13.Cu")
		(net "M_H_CPU0_SB_DQ<19>")
	)
	(segment
		(start 411.426406 -303.160176)
		(end 411.688026 -303.160176)
		(width 0.14478)
		(layer "In13.Cu")
		(net "M_H_CPU0_SB_DQ<19>")
	)
	(segment
		(start 415.90341 -302.054514)
		(end 415.90341 -302.55464)
		(width 0.14478)
		(layer "In13.Cu")
		(net "M_H_CPU0_SB_DQ<19>")
	)
	(segment
		(start 413.486346 -302.909478)
		(end 413.486346 -303.015396)
		(width 0.14478)
		(layer "In13.Cu")
		(net "M_H_CPU0_SB_DQ<19>")
	)
	(segment
		(start 402.304758 -292.003734)
		(end 402.304758 -295.932352)
		(width 0.14478)
		(layer "In13.Cu")
		(net "M_H_CPU0_SB_DQ<19>")
	)
	(segment
		(start 383.0447 -285.42615)
		(end 382.890776 -285.16072)
		(width 0.0889)
		(layer "In13.Cu")
		(net "M_H_CPU0_SB_DQ<19>")
	)
	(segment
		(start 412.528766 -303.496218)
		(end 412.790386 -303.496218)
		(width 0.14478)
		(layer "In13.Cu")
		(net "M_H_CPU0_SB_DQ<19>")
	)
	(segment
		(start 383.79781 -285.10357)
		(end 383.806192 -285.098744)
		(width 0.0889)
		(layer "In13.Cu")
		(net "M_H_CPU0_SB_DQ<19>")
	)
	(segment
		(start 417.55695 -302.55464)
		(end 417.55695 -302.054514)
		(width 0.14478)
		(layer "In13.Cu")
		(net "M_H_CPU0_SB_DQ<19>")
	)
	(segment
		(start 411.281626 -303.015396)
		(end 411.426406 -303.160176)
		(width 0.14478)
		(layer "In13.Cu")
		(net "M_H_CPU0_SB_DQ<19>")
	)
	(segment
		(start 412.935166 -302.909478)
		(end 413.079946 -302.764698)
		(width 0.14478)
		(layer "In13.Cu")
		(net "M_H_CPU0_SB_DQ<19>")
	)
	(segment
		(start 395.160754 -285.54045)
		(end 395.597634 -285.97733)
		(width 0.0889)
		(layer "In13.Cu")
		(net "M_H_CPU0_SB_DQ<19>")
	)
	(segment
		(start 416.297872 -302.711358)
		(end 416.45459 -302.55464)
		(width 0.14478)
		(layer "In13.Cu")
		(net "M_H_CPU0_SB_DQ<19>")
	)
	(segment
		(start 409.532582 -303.160176)
		(end 410.585666 -303.160176)
		(width 0.14478)
		(layer "In13.Cu")
		(net "M_H_CPU0_SB_DQ<19>")
	)
	(segment
		(start 410.585666 -303.160176)
		(end 410.730446 -303.015396)
		(width 0.14478)
		(layer "In13.Cu")
		(net "M_H_CPU0_SB_DQ<19>")
	)
	(segment
		(start 402.304758 -295.932352)
		(end 409.532582 -303.160176)
		(width 0.14478)
		(layer "In13.Cu")
		(net "M_H_CPU0_SB_DQ<19>")
	)
	(segment
		(start 411.281626 -302.909478)
		(end 411.281626 -303.015396)
		(width 0.14478)
		(layer "In13.Cu")
		(net "M_H_CPU0_SB_DQ<19>")
	)
	(arc
		(start 388.871968 -285.10357)
		(mid 389.154924 -285.179747)
		(end 389.43788 -285.10357)
		(width 0.0889)
		(layer "In13.Cu")
		(net "M_H_CPU0_SB_DQ<19>")
	)
	(arc
		(start 384.737864 -285.10357)
		(mid 384.924808 -285.053315)
		(end 385.111752 -285.10357)
		(width 0.0889)
		(layer "In13.Cu")
		(net "M_H_CPU0_SB_DQ<19>")
	)
	(arc
		(start 392.632692 -285.10357)
		(mid 392.91212 -285.179736)
		(end 393.192508 -285.107126)
		(width 0.0889)
		(layer "In13.Cu")
		(net "M_H_CPU0_SB_DQ<19>")
	)
	(arc
		(start 382.913128 -285.077408)
		(mid 383.07546 -285.05459)
		(end 383.231898 -285.10357)
		(width 0.0889)
		(layer "In13.Cu")
		(net "M_H_CPU0_SB_DQ<19>")
	)
	(arc
		(start 391.326116 -285.098744)
		(mid 391.509624 -285.05325)
		(end 391.691876 -285.10357)
		(width 0.0889)
		(layer "In13.Cu")
		(net "M_H_CPU0_SB_DQ<19>")
	)
	(arc
		(start 385.677664 -285.10357)
		(mid 385.859915 -285.05322)
		(end 386.043424 -285.098744)
		(width 0.0889)
		(layer "In13.Cu")
		(net "M_H_CPU0_SB_DQ<19>")
	)
	(arc
		(start 390.751822 -285.10357)
		(mid 391.034778 -285.179747)
		(end 391.317734 -285.10357)
		(width 0.0889)
		(layer "In13.Cu")
		(net "M_H_CPU0_SB_DQ<19>")
	)
	(arc
		(start 384.171952 -285.10357)
		(mid 384.454908 -285.179747)
		(end 384.737864 -285.10357)
		(width 0.0889)
		(layer "In13.Cu")
		(net "M_H_CPU0_SB_DQ<19>")
	)
	(arc
		(start 392.258042 -285.10357)
		(mid 392.440547 -285.053093)
		(end 392.62431 -285.098744)
		(width 0.0889)
		(layer "In13.Cu")
		(net "M_H_CPU0_SB_DQ<19>")
	)
	(arc
		(start 389.43788 -285.10357)
		(mid 389.624824 -285.053315)
		(end 389.811768 -285.10357)
		(width 0.0889)
		(layer "In13.Cu")
		(net "M_H_CPU0_SB_DQ<19>")
	)
	(arc
		(start 390.37768 -285.10357)
		(mid 390.559931 -285.05322)
		(end 390.74344 -285.098744)
		(width 0.0889)
		(layer "In13.Cu")
		(net "M_H_CPU0_SB_DQ<19>")
	)
	(arc
		(start 388.506208 -285.098744)
		(mid 388.689716 -285.05325)
		(end 388.871968 -285.10357)
		(width 0.0889)
		(layer "In13.Cu")
		(net "M_H_CPU0_SB_DQ<19>")
	)
	(arc
		(start 386.99186 -285.10357)
		(mid 387.274816 -285.179747)
		(end 387.557772 -285.10357)
		(width 0.0889)
		(layer "In13.Cu")
		(net "M_H_CPU0_SB_DQ<19>")
	)
	(arc
		(start 387.931914 -285.10357)
		(mid 388.21487 -285.179747)
		(end 388.497826 -285.10357)
		(width 0.0889)
		(layer "In13.Cu")
		(net "M_H_CPU0_SB_DQ<19>")
	)
	(arc
		(start 389.811768 -285.10357)
		(mid 390.094724 -285.179747)
		(end 390.37768 -285.10357)
		(width 0.0889)
		(layer "In13.Cu")
		(net "M_H_CPU0_SB_DQ<19>")
	)
	(arc
		(start 386.617718 -285.10357)
		(mid 386.799969 -285.05322)
		(end 386.983478 -285.098744)
		(width 0.0889)
		(layer "In13.Cu")
		(net "M_H_CPU0_SB_DQ<19>")
	)
	(arc
		(start 385.111752 -285.10357)
		(mid 385.394708 -285.179747)
		(end 385.677664 -285.10357)
		(width 0.0889)
		(layer "In13.Cu")
		(net "M_H_CPU0_SB_DQ<19>")
	)
	(arc
		(start 383.231898 -285.10357)
		(mid 383.514854 -285.179747)
		(end 383.79781 -285.10357)
		(width 0.0889)
		(layer "In13.Cu")
		(net "M_H_CPU0_SB_DQ<19>")
	)
	(arc
		(start 386.051806 -285.10357)
		(mid 386.334762 -285.179747)
		(end 386.617718 -285.10357)
		(width 0.0889)
		(layer "In13.Cu")
		(net "M_H_CPU0_SB_DQ<19>")
	)
	(arc
		(start 387.566154 -285.098744)
		(mid 387.749662 -285.05325)
		(end 387.931914 -285.10357)
		(width 0.0889)
		(layer "In13.Cu")
		(net "M_H_CPU0_SB_DQ<19>")
	)
	(arc
		(start 383.806192 -285.098744)
		(mid 383.9897 -285.05325)
		(end 384.171952 -285.10357)
		(width 0.0889)
		(layer "In13.Cu")
		(net "M_H_CPU0_SB_DQ<19>")
	)
	(arc
		(start 391.70229 -285.109666)
		(mid 391.980976 -285.179886)
		(end 392.258042 -285.10357)
		(width 0.0889)
		(layer "In13.Cu")
		(net "M_H_CPU0_SB_DQ<19>")
	)
	(segment
		(start 383.988056 -284.350206)
		(end 384.454908 -284.616144)
		(width 0.10668)
		(layer "F.Cu")
		(net "M_H_CPU0_SB_DQ<18>")
	)
	(segment
		(start 416.730688 -300.209712)
		(end 416.469068 -300.209712)
		(width 0.14478)
		(layer "In13.Cu")
		(net "M_H_CPU0_SB_DQ<18>")
	)
	(segment
		(start 417.977828 -300.354492)
		(end 417.833048 -300.209712)
		(width 0.14478)
		(layer "In13.Cu")
		(net "M_H_CPU0_SB_DQ<18>")
	)
	(segment
		(start 412.850584 -301.331884)
		(end 412.705804 -301.476664)
		(width 0.14478)
		(layer "In13.Cu")
		(net "M_H_CPU0_SB_DQ<18>")
	)
	(segment
		(start 415.366708 -300.273212)
		(end 415.221928 -300.417992)
		(width 0.14478)
		(layer "In13.Cu")
		(net "M_H_CPU0_SB_DQ<18>")
	)
	(segment
		(start 384.30073 -284.350714)
		(end 384.454908 -284.616144)
		(width 0.0889)
		(layer "In13.Cu")
		(net "M_H_CPU0_SB_DQ<18>")
	)
	(segment
		(start 417.426648 -300.865794)
		(end 417.281868 -301.010574)
		(width 0.14478)
		(layer "In13.Cu")
		(net "M_H_CPU0_SB_DQ<18>")
	)
	(segment
		(start 412.299404 -301.204376)
		(end 412.154624 -301.059596)
		(width 0.14478)
		(layer "In13.Cu")
		(net "M_H_CPU0_SB_DQ<18>")
	)
	(segment
		(start 411.893004 -301.059596)
		(end 411.748224 -301.204376)
		(width 0.14478)
		(layer "In13.Cu")
		(net "M_H_CPU0_SB_DQ<18>")
	)
	(segment
		(start 411.197044 -301.204376)
		(end 411.052264 -301.059596)
		(width 0.14478)
		(layer "In13.Cu")
		(net "M_H_CPU0_SB_DQ<18>")
	)
	(segment
		(start 394.730478 -284.95879)
		(end 394.14196 -284.370272)
		(width 0.0889)
		(layer "In13.Cu")
		(net "M_H_CPU0_SB_DQ<18>")
	)
	(segment
		(start 409.543504 -301.347886)
		(end 409.398724 -301.492666)
		(width 0.14478)
		(layer "In13.Cu")
		(net "M_H_CPU0_SB_DQ<18>")
	)
	(segment
		(start 419.542468 -301.460154)
		(end 418.972746 -301.460154)
		(width 0.14478)
		(layer "In13.Cu")
		(net "M_H_CPU0_SB_DQ<18>")
	)
	(segment
		(start 411.052264 -301.059596)
		(end 410.790644 -301.059596)
		(width 0.14478)
		(layer "In13.Cu")
		(net "M_H_CPU0_SB_DQ<18>")
	)
	(segment
		(start 419.912038 -301.034958)
		(end 419.912038 -301.090584)
		(width 0.14478)
		(layer "In13.Cu")
		(net "M_H_CPU0_SB_DQ<18>")
	)
	(segment
		(start 416.875468 -300.865794)
		(end 416.875468 -300.354492)
		(width 0.14478)
		(layer "In13.Cu")
		(net "M_H_CPU0_SB_DQ<18>")
	)
	(segment
		(start 409.398724 -301.492666)
		(end 409.137104 -301.492666)
		(width 0.14478)
		(layer "In13.Cu")
		(net "M_H_CPU0_SB_DQ<18>")
	)
	(segment
		(start 412.444184 -301.476664)
		(end 412.299404 -301.331884)
		(width 0.14478)
		(layer "In13.Cu")
		(net "M_H_CPU0_SB_DQ<18>")
	)
	(segment
		(start 392.744198 -284.282642)
		(end 392.725402 -284.293564)
		(width 0.0889)
		(layer "In13.Cu")
		(net "M_H_CPU0_SB_DQ<18>")
	)
	(segment
		(start 386.1562 -284.288738)
		(end 386.147818 -284.293564)
		(width 0.0889)
		(layer "In13.Cu")
		(net "M_H_CPU0_SB_DQ<18>")
	)
	(segment
		(start 413.546544 -301.860458)
		(end 413.401764 -301.715678)
		(width 0.14478)
		(layer "In13.Cu")
		(net "M_H_CPU0_SB_DQ<18>")
	)
	(segment
		(start 411.748224 -301.715678)
		(end 411.603444 -301.860458)
		(width 0.14478)
		(layer "In13.Cu")
		(net "M_H_CPU0_SB_DQ<18>")
	)
	(segment
		(start 413.256984 -301.059596)
		(end 412.995364 -301.059596)
		(width 0.14478)
		(layer "In13.Cu")
		(net "M_H_CPU0_SB_DQ<18>")
	)
	(segment
		(start 408.847544 -301.059596)
		(end 408.704034 -301.059596)
		(width 0.14478)
		(layer "In13.Cu")
		(net "M_H_CPU0_SB_DQ<18>")
	)
	(segment
		(start 395.468094 -284.95879)
		(end 394.730478 -284.95879)
		(width 0.0889)
		(layer "In13.Cu")
		(net "M_H_CPU0_SB_DQ<18>")
	)
	(segment
		(start 403.203918 -295.55948)
		(end 403.203918 -291.630862)
		(width 0.14478)
		(layer "In13.Cu")
		(net "M_H_CPU0_SB_DQ<18>")
	)
	(segment
		(start 384.641852 -284.293564)
		(end 384.63347 -284.288738)
		(width 0.0889)
		(layer "In13.Cu")
		(net "M_H_CPU0_SB_DQ<18>")
	)
	(segment
		(start 416.875468 -300.354492)
		(end 416.730688 -300.209712)
		(width 0.14478)
		(layer "In13.Cu")
		(net "M_H_CPU0_SB_DQ<18>")
	)
	(segment
		(start 412.995364 -301.059596)
		(end 412.850584 -301.204376)
		(width 0.14478)
		(layer "In13.Cu")
		(net "M_H_CPU0_SB_DQ<18>")
	)
	(segment
		(start 414.490662 -301.059596)
		(end 414.097724 -301.059596)
		(width 0.14478)
		(layer "In13.Cu")
		(net "M_H_CPU0_SB_DQ<18>")
	)
	(segment
		(start 412.705804 -301.476664)
		(end 412.444184 -301.476664)
		(width 0.14478)
		(layer "In13.Cu")
		(net "M_H_CPU0_SB_DQ<18>")
	)
	(segment
		(start 410.501084 -301.860458)
		(end 410.239464 -301.860458)
		(width 0.14478)
		(layer "In13.Cu")
		(net "M_H_CPU0_SB_DQ<18>")
	)
	(segment
		(start 417.977828 -300.465236)
		(end 417.977828 -300.354492)
		(width 0.14478)
		(layer "In13.Cu")
		(net "M_H_CPU0_SB_DQ<18>")
	)
	(segment
		(start 415.221928 -300.417992)
		(end 415.221928 -300.465236)
		(width 0.14478)
		(layer "In13.Cu")
		(net "M_H_CPU0_SB_DQ<18>")
	)
	(segment
		(start 409.949904 -301.059596)
		(end 409.688284 -301.059596)
		(width 0.14478)
		(layer "In13.Cu")
		(net "M_H_CPU0_SB_DQ<18>")
	)
	(segment
		(start 392.182604 -284.306264)
		(end 392.161014 -284.293818)
		(width 0.0889)
		(layer "In13.Cu")
		(net "M_H_CPU0_SB_DQ<18>")
	)
	(segment
		(start 413.401764 -301.715678)
		(end 413.401764 -301.204376)
		(width 0.14478)
		(layer "In13.Cu")
		(net "M_H_CPU0_SB_DQ<18>")
	)
	(segment
		(start 388.401814 -284.293564)
		(end 388.393432 -284.288738)
		(width 0.0889)
		(layer "In13.Cu")
		(net "M_H_CPU0_SB_DQ<18>")
	)
	(segment
		(start 411.748224 -301.204376)
		(end 411.748224 -301.715678)
		(width 0.14478)
		(layer "In13.Cu")
		(net "M_H_CPU0_SB_DQ<18>")
	)
	(segment
		(start 395.577314 -285.06801)
		(end 395.468094 -284.95879)
		(width 0.0889)
		(layer "In13.Cu")
		(net "M_H_CPU0_SB_DQ<18>")
	)
	(segment
		(start 410.645864 -301.204376)
		(end 410.645864 -301.715678)
		(width 0.14478)
		(layer "In13.Cu")
		(net "M_H_CPU0_SB_DQ<18>")
	)
	(segment
		(start 414.097724 -301.059596)
		(end 413.952944 -301.204376)
		(width 0.14478)
		(layer "In13.Cu")
		(net "M_H_CPU0_SB_DQ<18>")
	)
	(segment
		(start 408.704034 -301.059596)
		(end 403.203918 -295.55948)
		(width 0.14478)
		(layer "In13.Cu")
		(net "M_H_CPU0_SB_DQ<18>")
	)
	(segment
		(start 412.154624 -301.059596)
		(end 411.893004 -301.059596)
		(width 0.14478)
		(layer "In13.Cu")
		(net "M_H_CPU0_SB_DQ<18>")
	)
	(segment
		(start 410.239464 -301.860458)
		(end 410.094684 -301.715678)
		(width 0.14478)
		(layer "In13.Cu")
		(net "M_H_CPU0_SB_DQ<18>")
	)
	(segment
		(start 413.808164 -301.860458)
		(end 413.546544 -301.860458)
		(width 0.14478)
		(layer "In13.Cu")
		(net "M_H_CPU0_SB_DQ<18>")
	)
	(segment
		(start 410.094684 -301.715678)
		(end 410.094684 -301.204376)
		(width 0.14478)
		(layer "In13.Cu")
		(net "M_H_CPU0_SB_DQ<18>")
	)
	(segment
		(start 418.972746 -301.460154)
		(end 417.977828 -300.465236)
		(width 0.14478)
		(layer "In13.Cu")
		(net "M_H_CPU0_SB_DQ<18>")
	)
	(segment
		(start 413.952944 -301.204376)
		(end 413.952944 -301.715678)
		(width 0.14478)
		(layer "In13.Cu")
		(net "M_H_CPU0_SB_DQ<18>")
	)
	(segment
		(start 408.992324 -301.347886)
		(end 408.992324 -301.204376)
		(width 0.14478)
		(layer "In13.Cu")
		(net "M_H_CPU0_SB_DQ<18>")
	)
	(segment
		(start 417.281868 -301.010574)
		(end 417.020248 -301.010574)
		(width 0.14478)
		(layer "In13.Cu")
		(net "M_H_CPU0_SB_DQ<18>")
	)
	(segment
		(start 385.216146 -284.288738)
		(end 385.207764 -284.293564)
		(width 0.0889)
		(layer "In13.Cu")
		(net "M_H_CPU0_SB_DQ<18>")
	)
	(segment
		(start 409.137104 -301.492666)
		(end 408.992324 -301.347886)
		(width 0.14478)
		(layer "In13.Cu")
		(net "M_H_CPU0_SB_DQ<18>")
	)
	(segment
		(start 411.603444 -301.860458)
		(end 411.341824 -301.860458)
		(width 0.14478)
		(layer "In13.Cu")
		(net "M_H_CPU0_SB_DQ<18>")
	)
	(segment
		(start 410.094684 -301.204376)
		(end 409.949904 -301.059596)
		(width 0.14478)
		(layer "In13.Cu")
		(net "M_H_CPU0_SB_DQ<18>")
	)
	(segment
		(start 394.14196 -284.370272)
		(end 393.384786 -284.370272)
		(width 0.0889)
		(layer "In13.Cu")
		(net "M_H_CPU0_SB_DQ<18>")
	)
	(segment
		(start 410.790644 -301.059596)
		(end 410.645864 -301.204376)
		(width 0.14478)
		(layer "In13.Cu")
		(net "M_H_CPU0_SB_DQ<18>")
	)
	(segment
		(start 395.852904 -285.06801)
		(end 395.577314 -285.06801)
		(width 0.0889)
		(layer "In13.Cu")
		(net "M_H_CPU0_SB_DQ<18>")
	)
	(segment
		(start 408.992324 -301.204376)
		(end 408.847544 -301.059596)
		(width 0.14478)
		(layer "In13.Cu")
		(net "M_H_CPU0_SB_DQ<18>")
	)
	(segment
		(start 419.912038 -301.090584)
		(end 419.542468 -301.460154)
		(width 0.14478)
		(layer "In13.Cu")
		(net "M_H_CPU0_SB_DQ<18>")
	)
	(segment
		(start 415.917888 -300.610016)
		(end 415.773108 -300.465236)
		(width 0.14478)
		(layer "In13.Cu")
		(net "M_H_CPU0_SB_DQ<18>")
	)
	(segment
		(start 416.324288 -300.354492)
		(end 416.324288 -300.465236)
		(width 0.14478)
		(layer "In13.Cu")
		(net "M_H_CPU0_SB_DQ<18>")
	)
	(segment
		(start 417.426648 -300.354492)
		(end 417.426648 -300.865794)
		(width 0.14478)
		(layer "In13.Cu")
		(net "M_H_CPU0_SB_DQ<18>")
	)
	(segment
		(start 412.299404 -301.331884)
		(end 412.299404 -301.204376)
		(width 0.14478)
		(layer "In13.Cu")
		(net "M_H_CPU0_SB_DQ<18>")
	)
	(segment
		(start 409.543504 -301.204376)
		(end 409.543504 -301.347886)
		(width 0.14478)
		(layer "In13.Cu")
		(net "M_H_CPU0_SB_DQ<18>")
	)
	(segment
		(start 392.161014 -284.293818)
		(end 392.140948 -284.282388)
		(width 0.0889)
		(layer "In13.Cu")
		(net "M_H_CPU0_SB_DQ<18>")
	)
	(segment
		(start 411.197044 -301.715678)
		(end 411.197044 -301.204376)
		(width 0.14478)
		(layer "In13.Cu")
		(net "M_H_CPU0_SB_DQ<18>")
	)
	(segment
		(start 415.773108 -300.417992)
		(end 415.628328 -300.273212)
		(width 0.14478)
		(layer "In13.Cu")
		(net "M_H_CPU0_SB_DQ<18>")
	)
	(segment
		(start 412.850584 -301.204376)
		(end 412.850584 -301.331884)
		(width 0.14478)
		(layer "In13.Cu")
		(net "M_H_CPU0_SB_DQ<18>")
	)
	(segment
		(start 416.324288 -300.465236)
		(end 416.179508 -300.610016)
		(width 0.14478)
		(layer "In13.Cu")
		(net "M_H_CPU0_SB_DQ<18>")
	)
	(segment
		(start 396.641066 -285.06801)
		(end 395.852904 -285.06801)
		(width 0.14478)
		(layer "In13.Cu")
		(net "M_H_CPU0_SB_DQ<18>")
	)
	(segment
		(start 417.571428 -300.209712)
		(end 417.426648 -300.354492)
		(width 0.14478)
		(layer "In13.Cu")
		(net "M_H_CPU0_SB_DQ<18>")
	)
	(segment
		(start 417.833048 -300.209712)
		(end 417.571428 -300.209712)
		(width 0.14478)
		(layer "In13.Cu")
		(net "M_H_CPU0_SB_DQ<18>")
	)
	(segment
		(start 413.952944 -301.715678)
		(end 413.808164 -301.860458)
		(width 0.14478)
		(layer "In13.Cu")
		(net "M_H_CPU0_SB_DQ<18>")
	)
	(segment
		(start 415.221928 -300.465236)
		(end 415.077148 -300.610016)
		(width 0.14478)
		(layer "In13.Cu")
		(net "M_H_CPU0_SB_DQ<18>")
	)
	(segment
		(start 415.628328 -300.273212)
		(end 415.366708 -300.273212)
		(width 0.14478)
		(layer "In13.Cu")
		(net "M_H_CPU0_SB_DQ<18>")
	)
	(segment
		(start 403.203918 -291.630862)
		(end 396.641066 -285.06801)
		(width 0.14478)
		(layer "In13.Cu")
		(net "M_H_CPU0_SB_DQ<18>")
	)
	(segment
		(start 389.341868 -284.293564)
		(end 389.333486 -284.288738)
		(width 0.0889)
		(layer "In13.Cu")
		(net "M_H_CPU0_SB_DQ<18>")
	)
	(segment
		(start 389.916162 -284.288738)
		(end 389.90778 -284.293564)
		(width 0.0889)
		(layer "In13.Cu")
		(net "M_H_CPU0_SB_DQ<18>")
	)
	(segment
		(start 414.940242 -300.610016)
		(end 414.490662 -301.059596)
		(width 0.14478)
		(layer "In13.Cu")
		(net "M_H_CPU0_SB_DQ<18>")
	)
	(segment
		(start 417.020248 -301.010574)
		(end 416.875468 -300.865794)
		(width 0.14478)
		(layer "In13.Cu")
		(net "M_H_CPU0_SB_DQ<18>")
	)
	(segment
		(start 416.469068 -300.209712)
		(end 416.324288 -300.354492)
		(width 0.14478)
		(layer "In13.Cu")
		(net "M_H_CPU0_SB_DQ<18>")
	)
	(segment
		(start 409.688284 -301.059596)
		(end 409.543504 -301.204376)
		(width 0.14478)
		(layer "In13.Cu")
		(net "M_H_CPU0_SB_DQ<18>")
	)
	(segment
		(start 416.179508 -300.610016)
		(end 415.917888 -300.610016)
		(width 0.14478)
		(layer "In13.Cu")
		(net "M_H_CPU0_SB_DQ<18>")
	)
	(segment
		(start 415.077148 -300.610016)
		(end 414.940242 -300.610016)
		(width 0.14478)
		(layer "In13.Cu")
		(net "M_H_CPU0_SB_DQ<18>")
	)
	(segment
		(start 410.645864 -301.715678)
		(end 410.501084 -301.860458)
		(width 0.14478)
		(layer "In13.Cu")
		(net "M_H_CPU0_SB_DQ<18>")
	)
	(segment
		(start 411.341824 -301.860458)
		(end 411.197044 -301.715678)
		(width 0.14478)
		(layer "In13.Cu")
		(net "M_H_CPU0_SB_DQ<18>")
	)
	(segment
		(start 415.773108 -300.465236)
		(end 415.773108 -300.417992)
		(width 0.14478)
		(layer "In13.Cu")
		(net "M_H_CPU0_SB_DQ<18>")
	)
	(segment
		(start 384.323082 -284.267402)
		(end 384.30073 -284.350714)
		(width 0.0889)
		(layer "In13.Cu")
		(net "M_H_CPU0_SB_DQ<18>")
	)
	(segment
		(start 413.401764 -301.204376)
		(end 413.256984 -301.059596)
		(width 0.14478)
		(layer "In13.Cu")
		(net "M_H_CPU0_SB_DQ<18>")
	)
	(arc
		(start 388.393432 -284.288738)
		(mid 388.209924 -284.243244)
		(end 388.027672 -284.293564)
		(width 0.0889)
		(layer "In13.Cu")
		(net "M_H_CPU0_SB_DQ<18>")
	)
	(arc
		(start 389.90778 -284.293564)
		(mid 389.624824 -284.369741)
		(end 389.341868 -284.293564)
		(width 0.0889)
		(layer "In13.Cu")
		(net "M_H_CPU0_SB_DQ<18>")
	)
	(arc
		(start 389.333486 -284.288738)
		(mid 389.149978 -284.243244)
		(end 388.967726 -284.293564)
		(width 0.0889)
		(layer "In13.Cu")
		(net "M_H_CPU0_SB_DQ<18>")
	)
	(arc
		(start 390.281922 -284.293564)
		(mid 390.099671 -284.243214)
		(end 389.916162 -284.288738)
		(width 0.0889)
		(layer "In13.Cu")
		(net "M_H_CPU0_SB_DQ<18>")
	)
	(arc
		(start 392.725402 -284.293564)
		(mid 392.455633 -284.369587)
		(end 392.182604 -284.306264)
		(width 0.0889)
		(layer "In13.Cu")
		(net "M_H_CPU0_SB_DQ<18>")
	)
	(arc
		(start 390.847834 -284.293564)
		(mid 390.564878 -284.369741)
		(end 390.281922 -284.293564)
		(width 0.0889)
		(layer "In13.Cu")
		(net "M_H_CPU0_SB_DQ<18>")
	)
	(arc
		(start 385.581906 -284.293564)
		(mid 385.399655 -284.243214)
		(end 385.216146 -284.288738)
		(width 0.0889)
		(layer "In13.Cu")
		(net "M_H_CPU0_SB_DQ<18>")
	)
	(arc
		(start 393.10056 -284.293564)
		(mid 392.923769 -284.242845)
		(end 392.744198 -284.282642)
		(width 0.0889)
		(layer "In13.Cu")
		(net "M_H_CPU0_SB_DQ<18>")
	)
	(arc
		(start 387.46176 -284.293564)
		(mid 387.274816 -284.243309)
		(end 387.087872 -284.293564)
		(width 0.0889)
		(layer "In13.Cu")
		(net "M_H_CPU0_SB_DQ<18>")
	)
	(arc
		(start 388.027672 -284.293564)
		(mid 387.744716 -284.369741)
		(end 387.46176 -284.293564)
		(width 0.0889)
		(layer "In13.Cu")
		(net "M_H_CPU0_SB_DQ<18>")
	)
	(arc
		(start 385.207764 -284.293564)
		(mid 384.924808 -284.369741)
		(end 384.641852 -284.293564)
		(width 0.0889)
		(layer "In13.Cu")
		(net "M_H_CPU0_SB_DQ<18>")
	)
	(arc
		(start 393.384786 -284.370272)
		(mid 393.237577 -284.350795)
		(end 393.10056 -284.293564)
		(width 0.0889)
		(layer "In13.Cu")
		(net "M_H_CPU0_SB_DQ<18>")
	)
	(arc
		(start 388.967726 -284.293564)
		(mid 388.68477 -284.369741)
		(end 388.401814 -284.293564)
		(width 0.0889)
		(layer "In13.Cu")
		(net "M_H_CPU0_SB_DQ<18>")
	)
	(arc
		(start 384.63347 -284.288738)
		(mid 384.4806 -284.244097)
		(end 384.323082 -284.267402)
		(width 0.0889)
		(layer "In13.Cu")
		(net "M_H_CPU0_SB_DQ<18>")
	)
	(arc
		(start 387.087872 -284.293564)
		(mid 386.804916 -284.369741)
		(end 386.52196 -284.293564)
		(width 0.0889)
		(layer "In13.Cu")
		(net "M_H_CPU0_SB_DQ<18>")
	)
	(arc
		(start 386.52196 -284.293564)
		(mid 386.339709 -284.243214)
		(end 386.1562 -284.288738)
		(width 0.0889)
		(layer "In13.Cu")
		(net "M_H_CPU0_SB_DQ<18>")
	)
	(arc
		(start 391.221722 -284.293564)
		(mid 391.034778 -284.243309)
		(end 390.847834 -284.293564)
		(width 0.0889)
		(layer "In13.Cu")
		(net "M_H_CPU0_SB_DQ<18>")
	)
	(arc
		(start 391.787634 -284.293564)
		(mid 391.504678 -284.369741)
		(end 391.221722 -284.293564)
		(width 0.0889)
		(layer "In13.Cu")
		(net "M_H_CPU0_SB_DQ<18>")
	)
	(arc
		(start 392.140948 -284.282388)
		(mid 391.96287 -284.243404)
		(end 391.787634 -284.293564)
		(width 0.0889)
		(layer "In13.Cu")
		(net "M_H_CPU0_SB_DQ<18>")
	)
	(arc
		(start 386.147818 -284.293564)
		(mid 385.864862 -284.369741)
		(end 385.581906 -284.293564)
		(width 0.0889)
		(layer "In13.Cu")
		(net "M_H_CPU0_SB_DQ<18>")
	)
	(segment
		(start 382.107948 -284.350206)
		(end 382.5748 -284.616144)
		(width 0.10668)
		(layer "F.Cu")
		(net "M_H_CPU0_SB_DQ<17>")
	)
	(segment
		(start 421.983662 -301.595536)
		(end 422.245282 -301.595536)
		(width 0.14478)
		(layer "In13.Cu")
		(net "M_H_CPU0_SB_DQ<17>")
	)
	(segment
		(start 422.390062 -301.92091)
		(end 422.534842 -302.06569)
		(width 0.14478)
		(layer "In13.Cu")
		(net "M_H_CPU0_SB_DQ<17>")
	)
	(segment
		(start 383.693416 -284.94355)
		(end 383.701798 -284.938724)
		(width 0.0889)
		(layer "In13.Cu")
		(net "M_H_CPU0_SB_DQ<17>")
	)
	(segment
		(start 388.393432 -284.94355)
		(end 388.401814 -284.938724)
		(width 0.0889)
		(layer "In13.Cu")
		(net "M_H_CPU0_SB_DQ<17>")
	)
	(segment
		(start 422.941242 -301.92091)
		(end 422.941242 -301.740316)
		(width 0.14478)
		(layer "In13.Cu")
		(net "M_H_CPU0_SB_DQ<17>")
	)
	(segment
		(start 393.259056 -284.84449)
		(end 394.24356 -284.84449)
		(width 0.0889)
		(layer "In13.Cu")
		(net "M_H_CPU0_SB_DQ<17>")
	)
	(segment
		(start 395.270228 -285.22803)
		(end 395.564868 -285.52267)
		(width 0.0889)
		(layer "In13.Cu")
		(net "M_H_CPU0_SB_DQ<17>")
	)
	(segment
		(start 389.333486 -284.94355)
		(end 389.341868 -284.938724)
		(width 0.0889)
		(layer "In13.Cu")
		(net "M_H_CPU0_SB_DQ<17>")
	)
	(segment
		(start 422.534842 -302.06569)
		(end 422.796462 -302.06569)
		(width 0.14478)
		(layer "In13.Cu")
		(net "M_H_CPU0_SB_DQ<17>")
	)
	(segment
		(start 420.557452 -302.310038)
		(end 420.83736 -302.03013)
		(width 0.14478)
		(layer "In13.Cu")
		(net "M_H_CPU0_SB_DQ<17>")
	)
	(segment
		(start 389.90778 -284.938724)
		(end 389.916162 -284.94355)
		(width 0.0889)
		(layer "In13.Cu")
		(net "M_H_CPU0_SB_DQ<17>")
	)
	(segment
		(start 395.796008 -285.52267)
		(end 396.45971 -285.52267)
		(width 0.14478)
		(layer "In13.Cu")
		(net "M_H_CPU0_SB_DQ<17>")
	)
	(segment
		(start 421.838882 -301.740316)
		(end 421.983662 -301.595536)
		(width 0.14478)
		(layer "In13.Cu")
		(net "M_H_CPU0_SB_DQ<17>")
	)
	(segment
		(start 422.245282 -301.595536)
		(end 422.390062 -301.740316)
		(width 0.14478)
		(layer "In13.Cu")
		(net "M_H_CPU0_SB_DQ<17>")
	)
	(segment
		(start 391.787634 -284.938724)
		(end 391.796016 -284.94355)
		(width 0.0889)
		(layer "In13.Cu")
		(net "M_H_CPU0_SB_DQ<17>")
	)
	(segment
		(start 393.086082 -284.947868)
		(end 393.259056 -284.84449)
		(width 0.0889)
		(layer "In13.Cu")
		(net "M_H_CPU0_SB_DQ<17>")
	)
	(segment
		(start 422.796462 -302.06569)
		(end 422.941242 -301.92091)
		(width 0.14478)
		(layer "In13.Cu")
		(net "M_H_CPU0_SB_DQ<17>")
	)
	(segment
		(start 396.45971 -285.52267)
		(end 402.754338 -291.817298)
		(width 0.14478)
		(layer "In13.Cu")
		(net "M_H_CPU0_SB_DQ<17>")
	)
	(segment
		(start 418.057584 -301.460154)
		(end 418.907468 -302.310038)
		(width 0.14478)
		(layer "In13.Cu")
		(net "M_H_CPU0_SB_DQ<17>")
	)
	(segment
		(start 395.564868 -285.52267)
		(end 395.796008 -285.52267)
		(width 0.0889)
		(layer "In13.Cu")
		(net "M_H_CPU0_SB_DQ<17>")
	)
	(segment
		(start 382.5748 -284.616144)
		(end 382.728724 -284.881574)
		(width 0.0889)
		(layer "In13.Cu")
		(net "M_H_CPU0_SB_DQ<17>")
	)
	(segment
		(start 414.183068 -302.310038)
		(end 415.032952 -301.460154)
		(width 0.14478)
		(layer "In13.Cu")
		(net "M_H_CPU0_SB_DQ<17>")
	)
	(segment
		(start 423.347642 -301.595536)
		(end 423.637202 -301.885096)
		(width 0.14478)
		(layer "In13.Cu")
		(net "M_H_CPU0_SB_DQ<17>")
	)
	(segment
		(start 418.907468 -302.310038)
		(end 420.557452 -302.310038)
		(width 0.14478)
		(layer "In13.Cu")
		(net "M_H_CPU0_SB_DQ<17>")
	)
	(segment
		(start 423.637202 -301.885096)
		(end 424.012106 -301.885096)
		(width 0.14478)
		(layer "In13.Cu")
		(net "M_H_CPU0_SB_DQ<17>")
	)
	(segment
		(start 394.6271 -285.22803)
		(end 395.270228 -285.22803)
		(width 0.0889)
		(layer "In13.Cu")
		(net "M_H_CPU0_SB_DQ<17>")
	)
	(segment
		(start 423.086022 -301.595536)
		(end 423.347642 -301.595536)
		(width 0.14478)
		(layer "In13.Cu")
		(net "M_H_CPU0_SB_DQ<17>")
	)
	(segment
		(start 402.754338 -295.745916)
		(end 409.31846 -302.310038)
		(width 0.14478)
		(layer "In13.Cu")
		(net "M_H_CPU0_SB_DQ<17>")
	)
	(segment
		(start 421.838882 -301.88535)
		(end 421.838882 -301.740316)
		(width 0.14478)
		(layer "In13.Cu")
		(net "M_H_CPU0_SB_DQ<17>")
	)
	(segment
		(start 422.941242 -301.740316)
		(end 423.086022 -301.595536)
		(width 0.14478)
		(layer "In13.Cu")
		(net "M_H_CPU0_SB_DQ<17>")
	)
	(segment
		(start 382.728724 -284.881574)
		(end 382.824736 -284.906974)
		(width 0.0889)
		(layer "In13.Cu")
		(net "M_H_CPU0_SB_DQ<17>")
	)
	(segment
		(start 394.24356 -284.84449)
		(end 394.6271 -285.22803)
		(width 0.0889)
		(layer "In13.Cu")
		(net "M_H_CPU0_SB_DQ<17>")
	)
	(segment
		(start 386.147818 -284.938724)
		(end 386.1562 -284.94355)
		(width 0.0889)
		(layer "In13.Cu")
		(net "M_H_CPU0_SB_DQ<17>")
	)
	(segment
		(start 420.83736 -302.03013)
		(end 421.694102 -302.03013)
		(width 0.14478)
		(layer "In13.Cu")
		(net "M_H_CPU0_SB_DQ<17>")
	)
	(segment
		(start 409.31846 -302.310038)
		(end 414.183068 -302.310038)
		(width 0.14478)
		(layer "In13.Cu")
		(net "M_H_CPU0_SB_DQ<17>")
	)
	(segment
		(start 415.032952 -301.460154)
		(end 418.057584 -301.460154)
		(width 0.14478)
		(layer "In13.Cu")
		(net "M_H_CPU0_SB_DQ<17>")
	)
	(segment
		(start 421.694102 -302.03013)
		(end 421.838882 -301.88535)
		(width 0.14478)
		(layer "In13.Cu")
		(net "M_H_CPU0_SB_DQ<17>")
	)
	(segment
		(start 402.754338 -291.817298)
		(end 402.754338 -295.745916)
		(width 0.14478)
		(layer "In13.Cu")
		(net "M_H_CPU0_SB_DQ<17>")
	)
	(segment
		(start 385.207764 -284.938724)
		(end 385.216146 -284.94355)
		(width 0.0889)
		(layer "In13.Cu")
		(net "M_H_CPU0_SB_DQ<17>")
	)
	(segment
		(start 392.718036 -284.932628)
		(end 392.72845 -284.938724)
		(width 0.0889)
		(layer "In13.Cu")
		(net "M_H_CPU0_SB_DQ<17>")
	)
	(segment
		(start 384.63347 -284.94355)
		(end 384.641852 -284.938724)
		(width 0.0889)
		(layer "In13.Cu")
		(net "M_H_CPU0_SB_DQ<17>")
	)
	(segment
		(start 422.390062 -301.740316)
		(end 422.390062 -301.92091)
		(width 0.14478)
		(layer "In13.Cu")
		(net "M_H_CPU0_SB_DQ<17>")
	)
	(arc
		(start 385.216146 -284.94355)
		(mid 385.399654 -284.989044)
		(end 385.581906 -284.938724)
		(width 0.0889)
		(layer "In13.Cu")
		(net "M_H_CPU0_SB_DQ<17>")
	)
	(arc
		(start 389.916162 -284.94355)
		(mid 390.09967 -284.989044)
		(end 390.281922 -284.938724)
		(width 0.0889)
		(layer "In13.Cu")
		(net "M_H_CPU0_SB_DQ<17>")
	)
	(arc
		(start 391.221722 -284.938724)
		(mid 391.504678 -284.862547)
		(end 391.787634 -284.938724)
		(width 0.0889)
		(layer "In13.Cu")
		(net "M_H_CPU0_SB_DQ<17>")
	)
	(arc
		(start 386.1562 -284.94355)
		(mid 386.339708 -284.989044)
		(end 386.52196 -284.938724)
		(width 0.0889)
		(layer "In13.Cu")
		(net "M_H_CPU0_SB_DQ<17>")
	)
	(arc
		(start 383.701798 -284.938724)
		(mid 383.984754 -284.862547)
		(end 384.26771 -284.938724)
		(width 0.0889)
		(layer "In13.Cu")
		(net "M_H_CPU0_SB_DQ<17>")
	)
	(arc
		(start 384.26771 -284.938724)
		(mid 384.449961 -284.989074)
		(end 384.63347 -284.94355)
		(width 0.0889)
		(layer "In13.Cu")
		(net "M_H_CPU0_SB_DQ<17>")
	)
	(arc
		(start 385.581906 -284.938724)
		(mid 385.864862 -284.862547)
		(end 386.147818 -284.938724)
		(width 0.0889)
		(layer "In13.Cu")
		(net "M_H_CPU0_SB_DQ<17>")
	)
	(arc
		(start 390.847834 -284.938724)
		(mid 391.034778 -284.988979)
		(end 391.221722 -284.938724)
		(width 0.0889)
		(layer "In13.Cu")
		(net "M_H_CPU0_SB_DQ<17>")
	)
	(arc
		(start 383.327656 -284.938724)
		(mid 383.509907 -284.989074)
		(end 383.693416 -284.94355)
		(width 0.0889)
		(layer "In13.Cu")
		(net "M_H_CPU0_SB_DQ<17>")
	)
	(arc
		(start 390.281922 -284.938724)
		(mid 390.564878 -284.862547)
		(end 390.847834 -284.938724)
		(width 0.0889)
		(layer "In13.Cu")
		(net "M_H_CPU0_SB_DQ<17>")
	)
	(arc
		(start 392.72845 -284.938724)
		(mid 392.9061 -284.988984)
		(end 393.086082 -284.947868)
		(width 0.0889)
		(layer "In13.Cu")
		(net "M_H_CPU0_SB_DQ<17>")
	)
	(arc
		(start 386.52196 -284.938724)
		(mid 386.804916 -284.862547)
		(end 387.087872 -284.938724)
		(width 0.0889)
		(layer "In13.Cu")
		(net "M_H_CPU0_SB_DQ<17>")
	)
	(arc
		(start 389.341868 -284.938724)
		(mid 389.624824 -284.862547)
		(end 389.90778 -284.938724)
		(width 0.0889)
		(layer "In13.Cu")
		(net "M_H_CPU0_SB_DQ<17>")
	)
	(arc
		(start 387.087872 -284.938724)
		(mid 387.274816 -284.988979)
		(end 387.46176 -284.938724)
		(width 0.0889)
		(layer "In13.Cu")
		(net "M_H_CPU0_SB_DQ<17>")
	)
	(arc
		(start 387.46176 -284.938724)
		(mid 387.744716 -284.862547)
		(end 388.027672 -284.938724)
		(width 0.0889)
		(layer "In13.Cu")
		(net "M_H_CPU0_SB_DQ<17>")
	)
	(arc
		(start 391.796016 -284.94355)
		(mid 391.979778 -284.989166)
		(end 392.162284 -284.938724)
		(width 0.0889)
		(layer "In13.Cu")
		(net "M_H_CPU0_SB_DQ<17>")
	)
	(arc
		(start 388.967726 -284.938724)
		(mid 389.149977 -284.989074)
		(end 389.333486 -284.94355)
		(width 0.0889)
		(layer "In13.Cu")
		(net "M_H_CPU0_SB_DQ<17>")
	)
	(arc
		(start 392.162284 -284.938724)
		(mid 392.439351 -284.862453)
		(end 392.718036 -284.932628)
		(width 0.0889)
		(layer "In13.Cu")
		(net "M_H_CPU0_SB_DQ<17>")
	)
	(arc
		(start 388.401814 -284.938724)
		(mid 388.68477 -284.862547)
		(end 388.967726 -284.938724)
		(width 0.0889)
		(layer "In13.Cu")
		(net "M_H_CPU0_SB_DQ<17>")
	)
	(arc
		(start 388.027672 -284.938724)
		(mid 388.209923 -284.989074)
		(end 388.393432 -284.94355)
		(width 0.0889)
		(layer "In13.Cu")
		(net "M_H_CPU0_SB_DQ<17>")
	)
	(arc
		(start 382.824736 -284.906974)
		(mid 383.079944 -284.863497)
		(end 383.327656 -284.938724)
		(width 0.0889)
		(layer "In13.Cu")
		(net "M_H_CPU0_SB_DQ<17>")
	)
	(arc
		(start 384.641852 -284.938724)
		(mid 384.924808 -284.862547)
		(end 385.207764 -284.938724)
		(width 0.0889)
		(layer "In13.Cu")
		(net "M_H_CPU0_SB_DQ<17>")
	)
	(segment
		(start 383.517902 -283.5402)
		(end 383.984754 -283.806138)
		(width 0.10668)
		(layer "F.Cu")
		(net "M_H_CPU0_SB_DQ<16>")
	)
	(segment
		(start 422.172638 -300.660562)
		(end 422.027858 -300.805342)
		(width 0.14478)
		(layer "In13.Cu")
		(net "M_H_CPU0_SB_DQ<16>")
	)
	(segment
		(start 386.051806 -284.128718)
		(end 386.043424 -284.133544)
		(width 0.0889)
		(layer "In13.Cu")
		(net "M_H_CPU0_SB_DQ<16>")
	)
	(segment
		(start 393.38504 -284.179772)
		(end 393.384786 -284.179518)
		(width 0.0889)
		(layer "In13.Cu")
		(net "M_H_CPU0_SB_DQ<16>")
	)
	(segment
		(start 422.723818 -300.202854)
		(end 422.579038 -300.058074)
		(width 0.14478)
		(layer "In13.Cu")
		(net "M_H_CPU0_SB_DQ<16>")
	)
	(segment
		(start 420.478204 -300.619668)
		(end 418.91712 -300.619668)
		(width 0.14478)
		(layer "In13.Cu")
		(net "M_H_CPU0_SB_DQ<16>")
	)
	(segment
		(start 390.751822 -284.128718)
		(end 390.74344 -284.133544)
		(width 0.0889)
		(layer "In13.Cu")
		(net "M_H_CPU0_SB_DQ<16>")
	)
	(segment
		(start 395.807438 -284.61335)
		(end 395.313154 -284.61335)
		(width 0.0889)
		(layer "In13.Cu")
		(net "M_H_CPU0_SB_DQ<16>")
	)
	(segment
		(start 421.070278 -300.202854)
		(end 421.070278 -300.660562)
		(width 0.14478)
		(layer "In13.Cu")
		(net "M_H_CPU0_SB_DQ<16>")
	)
	(segment
		(start 395.313154 -284.61335)
		(end 395.198854 -284.72765)
		(width 0.0889)
		(layer "In13.Cu")
		(net "M_H_CPU0_SB_DQ<16>")
	)
	(segment
		(start 422.723818 -300.660562)
		(end 422.723818 -300.202854)
		(width 0.14478)
		(layer "In13.Cu")
		(net "M_H_CPU0_SB_DQ<16>")
	)
	(segment
		(start 422.868598 -300.805342)
		(end 422.723818 -300.660562)
		(width 0.14478)
		(layer "In13.Cu")
		(net "M_H_CPU0_SB_DQ<16>")
	)
	(segment
		(start 392.256264 -284.128464)
		(end 392.234674 -284.116018)
		(width 0.0889)
		(layer "In13.Cu")
		(net "M_H_CPU0_SB_DQ<16>")
	)
	(segment
		(start 386.99186 -284.128718)
		(end 386.983478 -284.133544)
		(width 0.0889)
		(layer "In13.Cu")
		(net "M_H_CPU0_SB_DQ<16>")
	)
	(segment
		(start 422.027858 -300.805342)
		(end 421.766238 -300.805342)
		(width 0.14478)
		(layer "In13.Cu")
		(net "M_H_CPU0_SB_DQ<16>")
	)
	(segment
		(start 421.215058 -300.058074)
		(end 421.070278 -300.202854)
		(width 0.14478)
		(layer "In13.Cu")
		(net "M_H_CPU0_SB_DQ<16>")
	)
	(segment
		(start 403.653498 -295.373044)
		(end 403.653498 -291.444426)
		(width 0.14478)
		(layer "In13.Cu")
		(net "M_H_CPU0_SB_DQ<16>")
	)
	(segment
		(start 388.506208 -284.133544)
		(end 388.497826 -284.128718)
		(width 0.0889)
		(layer "In13.Cu")
		(net "M_H_CPU0_SB_DQ<16>")
	)
	(segment
		(start 420.663878 -300.805342)
		(end 420.478204 -300.619668)
		(width 0.14478)
		(layer "In13.Cu")
		(net "M_H_CPU0_SB_DQ<16>")
	)
	(segment
		(start 395.198854 -284.72765)
		(end 394.835634 -284.72765)
		(width 0.0889)
		(layer "In13.Cu")
		(net "M_H_CPU0_SB_DQ<16>")
	)
	(segment
		(start 421.621458 -300.202854)
		(end 421.476678 -300.058074)
		(width 0.14478)
		(layer "In13.Cu")
		(net "M_H_CPU0_SB_DQ<16>")
	)
	(segment
		(start 414.183068 -300.610016)
		(end 408.89047 -300.610016)
		(width 0.14478)
		(layer "In13.Cu")
		(net "M_H_CPU0_SB_DQ<16>")
	)
	(segment
		(start 418.057584 -299.760132)
		(end 415.032952 -299.760132)
		(width 0.14478)
		(layer "In13.Cu")
		(net "M_H_CPU0_SB_DQ<16>")
	)
	(segment
		(start 424.012106 -300.185074)
		(end 423.419778 -300.185074)
		(width 0.14478)
		(layer "In13.Cu")
		(net "M_H_CPU0_SB_DQ<16>")
	)
	(segment
		(start 422.172638 -300.202854)
		(end 422.172638 -300.660562)
		(width 0.14478)
		(layer "In13.Cu")
		(net "M_H_CPU0_SB_DQ<16>")
	)
	(segment
		(start 392.274552 -284.138878)
		(end 392.256264 -284.128464)
		(width 0.0889)
		(layer "In13.Cu")
		(net "M_H_CPU0_SB_DQ<16>")
	)
	(segment
		(start 415.032952 -299.760132)
		(end 414.183068 -300.610016)
		(width 0.14478)
		(layer "In13.Cu")
		(net "M_H_CPU0_SB_DQ<16>")
	)
	(segment
		(start 394.835634 -284.72765)
		(end 394.287756 -284.179772)
		(width 0.0889)
		(layer "In13.Cu")
		(net "M_H_CPU0_SB_DQ<16>")
	)
	(segment
		(start 421.621458 -300.660562)
		(end 421.621458 -300.202854)
		(width 0.14478)
		(layer "In13.Cu")
		(net "M_H_CPU0_SB_DQ<16>")
	)
	(segment
		(start 420.925498 -300.805342)
		(end 420.663878 -300.805342)
		(width 0.14478)
		(layer "In13.Cu")
		(net "M_H_CPU0_SB_DQ<16>")
	)
	(segment
		(start 392.652758 -284.115002)
		(end 392.62939 -284.128718)
		(width 0.0889)
		(layer "In13.Cu")
		(net "M_H_CPU0_SB_DQ<16>")
	)
	(segment
		(start 423.419778 -300.185074)
		(end 423.274998 -300.329854)
		(width 0.14478)
		(layer "In13.Cu")
		(net "M_H_CPU0_SB_DQ<16>")
	)
	(segment
		(start 423.130218 -300.805342)
		(end 422.868598 -300.805342)
		(width 0.14478)
		(layer "In13.Cu")
		(net "M_H_CPU0_SB_DQ<16>")
	)
	(segment
		(start 384.235198 -284.096968)
		(end 384.138932 -284.071568)
		(width 0.0889)
		(layer "In13.Cu")
		(net "M_H_CPU0_SB_DQ<16>")
	)
	(segment
		(start 396.822422 -284.61335)
		(end 395.807438 -284.61335)
		(width 0.14478)
		(layer "In13.Cu")
		(net "M_H_CPU0_SB_DQ<16>")
	)
	(segment
		(start 423.274998 -300.660562)
		(end 423.130218 -300.805342)
		(width 0.14478)
		(layer "In13.Cu")
		(net "M_H_CPU0_SB_DQ<16>")
	)
	(segment
		(start 421.476678 -300.058074)
		(end 421.215058 -300.058074)
		(width 0.14478)
		(layer "In13.Cu")
		(net "M_H_CPU0_SB_DQ<16>")
	)
	(segment
		(start 421.766238 -300.805342)
		(end 421.621458 -300.660562)
		(width 0.14478)
		(layer "In13.Cu")
		(net "M_H_CPU0_SB_DQ<16>")
	)
	(segment
		(start 391.326116 -284.133544)
		(end 391.317734 -284.128718)
		(width 0.0889)
		(layer "In13.Cu")
		(net "M_H_CPU0_SB_DQ<16>")
	)
	(segment
		(start 384.138932 -284.071568)
		(end 383.984754 -283.806138)
		(width 0.0889)
		(layer "In13.Cu")
		(net "M_H_CPU0_SB_DQ<16>")
	)
	(segment
		(start 408.89047 -300.610016)
		(end 403.653498 -295.373044)
		(width 0.14478)
		(layer "In13.Cu")
		(net "M_H_CPU0_SB_DQ<16>")
	)
	(segment
		(start 387.566154 -284.133544)
		(end 387.557772 -284.128718)
		(width 0.0889)
		(layer "In13.Cu")
		(net "M_H_CPU0_SB_DQ<16>")
	)
	(segment
		(start 418.91712 -300.619668)
		(end 418.057584 -299.760132)
		(width 0.14478)
		(layer "In13.Cu")
		(net "M_H_CPU0_SB_DQ<16>")
	)
	(segment
		(start 394.287756 -284.179772)
		(end 393.38504 -284.179772)
		(width 0.0889)
		(layer "In13.Cu")
		(net "M_H_CPU0_SB_DQ<16>")
	)
	(segment
		(start 421.070278 -300.660562)
		(end 420.925498 -300.805342)
		(width 0.14478)
		(layer "In13.Cu")
		(net "M_H_CPU0_SB_DQ<16>")
	)
	(segment
		(start 422.317418 -300.058074)
		(end 422.172638 -300.202854)
		(width 0.14478)
		(layer "In13.Cu")
		(net "M_H_CPU0_SB_DQ<16>")
	)
	(segment
		(start 422.579038 -300.058074)
		(end 422.317418 -300.058074)
		(width 0.14478)
		(layer "In13.Cu")
		(net "M_H_CPU0_SB_DQ<16>")
	)
	(segment
		(start 423.274998 -300.329854)
		(end 423.274998 -300.660562)
		(width 0.14478)
		(layer "In13.Cu")
		(net "M_H_CPU0_SB_DQ<16>")
	)
	(segment
		(start 403.653498 -291.444426)
		(end 396.822422 -284.61335)
		(width 0.14478)
		(layer "In13.Cu")
		(net "M_H_CPU0_SB_DQ<16>")
	)
	(arc
		(start 386.617718 -284.128718)
		(mid 386.334762 -284.052541)
		(end 386.051806 -284.128718)
		(width 0.0889)
		(layer "In13.Cu")
		(net "M_H_CPU0_SB_DQ<16>")
	)
	(arc
		(start 386.043424 -284.133544)
		(mid 385.859916 -284.179038)
		(end 385.677664 -284.128718)
		(width 0.0889)
		(layer "In13.Cu")
		(net "M_H_CPU0_SB_DQ<16>")
	)
	(arc
		(start 387.931914 -284.128718)
		(mid 387.749663 -284.179068)
		(end 387.566154 -284.133544)
		(width 0.0889)
		(layer "In13.Cu")
		(net "M_H_CPU0_SB_DQ<16>")
	)
	(arc
		(start 393.196572 -284.128718)
		(mid 392.926415 -284.051956)
		(end 392.652758 -284.115002)
		(width 0.0889)
		(layer "In13.Cu")
		(net "M_H_CPU0_SB_DQ<16>")
	)
	(arc
		(start 386.983478 -284.133544)
		(mid 386.79997 -284.179038)
		(end 386.617718 -284.128718)
		(width 0.0889)
		(layer "In13.Cu")
		(net "M_H_CPU0_SB_DQ<16>")
	)
	(arc
		(start 392.62939 -284.128718)
		(mid 392.45327 -284.178696)
		(end 392.274552 -284.138878)
		(width 0.0889)
		(layer "In13.Cu")
		(net "M_H_CPU0_SB_DQ<16>")
	)
	(arc
		(start 388.871968 -284.128718)
		(mid 388.689717 -284.179068)
		(end 388.506208 -284.133544)
		(width 0.0889)
		(layer "In13.Cu")
		(net "M_H_CPU0_SB_DQ<16>")
	)
	(arc
		(start 387.557772 -284.128718)
		(mid 387.274816 -284.052541)
		(end 386.99186 -284.128718)
		(width 0.0889)
		(layer "In13.Cu")
		(net "M_H_CPU0_SB_DQ<16>")
	)
	(arc
		(start 391.691876 -284.128718)
		(mid 391.509625 -284.179068)
		(end 391.326116 -284.133544)
		(width 0.0889)
		(layer "In13.Cu")
		(net "M_H_CPU0_SB_DQ<16>")
	)
	(arc
		(start 392.234674 -284.116018)
		(mid 391.961645 -284.052699)
		(end 391.691876 -284.128718)
		(width 0.0889)
		(layer "In13.Cu")
		(net "M_H_CPU0_SB_DQ<16>")
	)
	(arc
		(start 385.111752 -284.128718)
		(mid 384.924808 -284.178973)
		(end 384.737864 -284.128718)
		(width 0.0889)
		(layer "In13.Cu")
		(net "M_H_CPU0_SB_DQ<16>")
	)
	(arc
		(start 389.43788 -284.128718)
		(mid 389.154924 -284.052541)
		(end 388.871968 -284.128718)
		(width 0.0889)
		(layer "In13.Cu")
		(net "M_H_CPU0_SB_DQ<16>")
	)
	(arc
		(start 391.317734 -284.128718)
		(mid 391.034778 -284.052541)
		(end 390.751822 -284.128718)
		(width 0.0889)
		(layer "In13.Cu")
		(net "M_H_CPU0_SB_DQ<16>")
	)
	(arc
		(start 390.74344 -284.133544)
		(mid 390.559932 -284.179038)
		(end 390.37768 -284.128718)
		(width 0.0889)
		(layer "In13.Cu")
		(net "M_H_CPU0_SB_DQ<16>")
	)
	(arc
		(start 393.384786 -284.179518)
		(mid 393.287298 -284.166635)
		(end 393.196572 -284.128718)
		(width 0.0889)
		(layer "In13.Cu")
		(net "M_H_CPU0_SB_DQ<16>")
	)
	(arc
		(start 389.811768 -284.128718)
		(mid 389.624824 -284.178973)
		(end 389.43788 -284.128718)
		(width 0.0889)
		(layer "In13.Cu")
		(net "M_H_CPU0_SB_DQ<16>")
	)
	(arc
		(start 390.37768 -284.128718)
		(mid 390.094724 -284.052541)
		(end 389.811768 -284.128718)
		(width 0.0889)
		(layer "In13.Cu")
		(net "M_H_CPU0_SB_DQ<16>")
	)
	(arc
		(start 385.677664 -284.128718)
		(mid 385.394708 -284.052541)
		(end 385.111752 -284.128718)
		(width 0.0889)
		(layer "In13.Cu")
		(net "M_H_CPU0_SB_DQ<16>")
	)
	(arc
		(start 388.497826 -284.128718)
		(mid 388.21487 -284.052541)
		(end 387.931914 -284.128718)
		(width 0.0889)
		(layer "In13.Cu")
		(net "M_H_CPU0_SB_DQ<16>")
	)
	(arc
		(start 384.737864 -284.128718)
		(mid 384.490268 -284.05354)
		(end 384.235198 -284.096968)
		(width 0.0889)
		(layer "In13.Cu")
		(net "M_H_CPU0_SB_DQ<16>")
	)
	(segment
		(start 382.577848 -283.5402)
		(end 383.0447 -283.806138)
		(width 0.10668)
		(layer "F.Cu")
		(net "M_H_CPU0_SB_DQ<15>")
	)
	(segment
		(start 394.393928 -283.687266)
		(end 395.21511 -283.687266)
		(width 0.0889)
		(layer "In13.Cu")
		(net "M_H_CPU0_SB_DQ<15>")
	)
	(segment
		(start 408.82062 -299.760386)
		(end 409.357322 -299.760386)
		(width 0.14478)
		(layer "In13.Cu")
		(net "M_H_CPU0_SB_DQ<15>")
	)
	(segment
		(start 383.79781 -283.483558)
		(end 383.806192 -283.478732)
		(width 0.0889)
		(layer "In13.Cu")
		(net "M_H_CPU0_SB_DQ<15>")
	)
	(segment
		(start 418.122608 -298.910248)
		(end 418.972746 -299.760386)
		(width 0.14478)
		(layer "In13.Cu")
		(net "M_H_CPU0_SB_DQ<15>")
	)
	(segment
		(start 412.953962 -299.386498)
		(end 413.215582 -299.386498)
		(width 0.14478)
		(layer "In13.Cu")
		(net "M_H_CPU0_SB_DQ<15>")
	)
	(segment
		(start 390.74344 -283.478732)
		(end 390.751822 -283.483558)
		(width 0.0889)
		(layer "In13.Cu")
		(net "M_H_CPU0_SB_DQ<15>")
	)
	(segment
		(start 386.043424 -283.478732)
		(end 386.051806 -283.483558)
		(width 0.0889)
		(layer "In13.Cu")
		(net "M_H_CPU0_SB_DQ<15>")
	)
	(segment
		(start 404.204678 -291.215826)
		(end 404.204678 -295.144444)
		(width 0.14478)
		(layer "In13.Cu")
		(net "M_H_CPU0_SB_DQ<15>")
	)
	(segment
		(start 411.562042 -300.058836)
		(end 411.706822 -299.914056)
		(width 0.14478)
		(layer "In13.Cu")
		(net "M_H_CPU0_SB_DQ<15>")
	)
	(segment
		(start 411.155642 -299.531278)
		(end 411.155642 -299.914056)
		(width 0.14478)
		(layer "In13.Cu")
		(net "M_H_CPU0_SB_DQ<15>")
	)
	(segment
		(start 419.912038 -299.340016)
		(end 419.912038 -299.33519)
		(width 0.14478)
		(layer "In13.Cu")
		(net "M_H_CPU0_SB_DQ<15>")
	)
	(segment
		(start 383.0447 -283.806138)
		(end 382.890776 -283.540708)
		(width 0.0889)
		(layer "In13.Cu")
		(net "M_H_CPU0_SB_DQ<15>")
	)
	(segment
		(start 410.604462 -299.531278)
		(end 410.749242 -299.386498)
		(width 0.14478)
		(layer "In13.Cu")
		(net "M_H_CPU0_SB_DQ<15>")
	)
	(segment
		(start 411.300422 -300.058836)
		(end 411.562042 -300.058836)
		(width 0.14478)
		(layer "In13.Cu")
		(net "M_H_CPU0_SB_DQ<15>")
	)
	(segment
		(start 397.045942 -284.05709)
		(end 404.204678 -291.215826)
		(width 0.14478)
		(layer "In13.Cu")
		(net "M_H_CPU0_SB_DQ<15>")
	)
	(segment
		(start 392.62431 -283.478732)
		(end 392.632692 -283.483558)
		(width 0.0889)
		(layer "In13.Cu")
		(net "M_H_CPU0_SB_DQ<15>")
	)
	(segment
		(start 412.664402 -299.760386)
		(end 412.809182 -299.615606)
		(width 0.14478)
		(layer "In13.Cu")
		(net "M_H_CPU0_SB_DQ<15>")
	)
	(segment
		(start 411.010862 -299.386498)
		(end 411.155642 -299.531278)
		(width 0.14478)
		(layer "In13.Cu")
		(net "M_H_CPU0_SB_DQ<15>")
	)
	(segment
		(start 395.21511 -283.687266)
		(end 395.584934 -284.05709)
		(width 0.0889)
		(layer "In13.Cu")
		(net "M_H_CPU0_SB_DQ<15>")
	)
	(segment
		(start 409.502102 -299.504608)
		(end 409.646882 -299.359828)
		(width 0.14478)
		(layer "In13.Cu")
		(net "M_H_CPU0_SB_DQ<15>")
	)
	(segment
		(start 413.505142 -299.760386)
		(end 414.090104 -299.760386)
		(width 0.14478)
		(layer "In13.Cu")
		(net "M_H_CPU0_SB_DQ<15>")
	)
	(segment
		(start 410.459682 -300.058836)
		(end 410.604462 -299.914056)
		(width 0.14478)
		(layer "In13.Cu")
		(net "M_H_CPU0_SB_DQ<15>")
	)
	(segment
		(start 387.557772 -283.483558)
		(end 387.566154 -283.478732)
		(width 0.0889)
		(layer "In13.Cu")
		(net "M_H_CPU0_SB_DQ<15>")
	)
	(segment
		(start 413.215582 -299.386498)
		(end 413.360362 -299.531278)
		(width 0.14478)
		(layer "In13.Cu")
		(net "M_H_CPU0_SB_DQ<15>")
	)
	(segment
		(start 410.604462 -299.914056)
		(end 410.604462 -299.531278)
		(width 0.14478)
		(layer "In13.Cu")
		(net "M_H_CPU0_SB_DQ<15>")
	)
	(segment
		(start 394.119354 -283.412692)
		(end 394.393928 -283.687266)
		(width 0.0889)
		(layer "In13.Cu")
		(net "M_H_CPU0_SB_DQ<15>")
	)
	(segment
		(start 412.809182 -299.615606)
		(end 412.809182 -299.531278)
		(width 0.14478)
		(layer "In13.Cu")
		(net "M_H_CPU0_SB_DQ<15>")
	)
	(segment
		(start 409.502102 -299.615606)
		(end 409.502102 -299.504608)
		(width 0.14478)
		(layer "In13.Cu")
		(net "M_H_CPU0_SB_DQ<15>")
	)
	(segment
		(start 404.204678 -295.144444)
		(end 408.82062 -299.760386)
		(width 0.14478)
		(layer "In13.Cu")
		(net "M_H_CPU0_SB_DQ<15>")
	)
	(segment
		(start 412.809182 -299.531278)
		(end 412.953962 -299.386498)
		(width 0.14478)
		(layer "In13.Cu")
		(net "M_H_CPU0_SB_DQ<15>")
	)
	(segment
		(start 413.360362 -299.531278)
		(end 413.360362 -299.615606)
		(width 0.14478)
		(layer "In13.Cu")
		(net "M_H_CPU0_SB_DQ<15>")
	)
	(segment
		(start 410.053282 -299.914056)
		(end 410.198062 -300.058836)
		(width 0.14478)
		(layer "In13.Cu")
		(net "M_H_CPU0_SB_DQ<15>")
	)
	(segment
		(start 410.053282 -299.504608)
		(end 410.053282 -299.914056)
		(width 0.14478)
		(layer "In13.Cu")
		(net "M_H_CPU0_SB_DQ<15>")
	)
	(segment
		(start 418.972746 -299.760386)
		(end 419.491668 -299.760386)
		(width 0.14478)
		(layer "In13.Cu")
		(net "M_H_CPU0_SB_DQ<15>")
	)
	(segment
		(start 391.317734 -283.483558)
		(end 391.326116 -283.478732)
		(width 0.0889)
		(layer "In13.Cu")
		(net "M_H_CPU0_SB_DQ<15>")
	)
	(segment
		(start 412.402782 -299.760386)
		(end 412.664402 -299.760386)
		(width 0.14478)
		(layer "In13.Cu")
		(net "M_H_CPU0_SB_DQ<15>")
	)
	(segment
		(start 388.497826 -283.483558)
		(end 388.506208 -283.478732)
		(width 0.0889)
		(layer "In13.Cu")
		(net "M_H_CPU0_SB_DQ<15>")
	)
	(segment
		(start 395.784578 -284.05709)
		(end 397.045942 -284.05709)
		(width 0.14478)
		(layer "In13.Cu")
		(net "M_H_CPU0_SB_DQ<15>")
	)
	(segment
		(start 386.983478 -283.478732)
		(end 386.99186 -283.483558)
		(width 0.0889)
		(layer "In13.Cu")
		(net "M_H_CPU0_SB_DQ<15>")
	)
	(segment
		(start 413.360362 -299.615606)
		(end 413.505142 -299.760386)
		(width 0.14478)
		(layer "In13.Cu")
		(net "M_H_CPU0_SB_DQ<15>")
	)
	(segment
		(start 409.357322 -299.760386)
		(end 409.502102 -299.615606)
		(width 0.14478)
		(layer "In13.Cu")
		(net "M_H_CPU0_SB_DQ<15>")
	)
	(segment
		(start 391.691876 -283.483558)
		(end 391.70229 -283.489654)
		(width 0.0889)
		(layer "In13.Cu")
		(net "M_H_CPU0_SB_DQ<15>")
	)
	(segment
		(start 410.749242 -299.386498)
		(end 411.010862 -299.386498)
		(width 0.14478)
		(layer "In13.Cu")
		(net "M_H_CPU0_SB_DQ<15>")
	)
	(segment
		(start 410.198062 -300.058836)
		(end 410.459682 -300.058836)
		(width 0.14478)
		(layer "In13.Cu")
		(net "M_H_CPU0_SB_DQ<15>")
	)
	(segment
		(start 414.090104 -299.760386)
		(end 414.940242 -298.910248)
		(width 0.14478)
		(layer "In13.Cu")
		(net "M_H_CPU0_SB_DQ<15>")
	)
	(segment
		(start 409.908502 -299.359828)
		(end 410.053282 -299.504608)
		(width 0.14478)
		(layer "In13.Cu")
		(net "M_H_CPU0_SB_DQ<15>")
	)
	(segment
		(start 395.584934 -284.05709)
		(end 395.784578 -284.05709)
		(width 0.0889)
		(layer "In13.Cu")
		(net "M_H_CPU0_SB_DQ<15>")
	)
	(segment
		(start 412.113222 -299.386498)
		(end 412.258002 -299.531278)
		(width 0.14478)
		(layer "In13.Cu")
		(net "M_H_CPU0_SB_DQ<15>")
	)
	(segment
		(start 411.851602 -299.386498)
		(end 412.113222 -299.386498)
		(width 0.14478)
		(layer "In13.Cu")
		(net "M_H_CPU0_SB_DQ<15>")
	)
	(segment
		(start 414.940242 -298.910248)
		(end 418.122608 -298.910248)
		(width 0.14478)
		(layer "In13.Cu")
		(net "M_H_CPU0_SB_DQ<15>")
	)
	(segment
		(start 412.258002 -299.615606)
		(end 412.402782 -299.760386)
		(width 0.14478)
		(layer "In13.Cu")
		(net "M_H_CPU0_SB_DQ<15>")
	)
	(segment
		(start 393.457938 -283.412692)
		(end 394.119354 -283.412692)
		(width 0.0889)
		(layer "In13.Cu")
		(net "M_H_CPU0_SB_DQ<15>")
	)
	(segment
		(start 411.706822 -299.914056)
		(end 411.706822 -299.531278)
		(width 0.14478)
		(layer "In13.Cu")
		(net "M_H_CPU0_SB_DQ<15>")
	)
	(segment
		(start 419.491668 -299.760386)
		(end 419.912038 -299.340016)
		(width 0.14478)
		(layer "In13.Cu")
		(net "M_H_CPU0_SB_DQ<15>")
	)
	(segment
		(start 411.706822 -299.531278)
		(end 411.851602 -299.386498)
		(width 0.14478)
		(layer "In13.Cu")
		(net "M_H_CPU0_SB_DQ<15>")
	)
	(segment
		(start 412.258002 -299.531278)
		(end 412.258002 -299.615606)
		(width 0.14478)
		(layer "In13.Cu")
		(net "M_H_CPU0_SB_DQ<15>")
	)
	(segment
		(start 382.890776 -283.540708)
		(end 382.913128 -283.457396)
		(width 0.0889)
		(layer "In13.Cu")
		(net "M_H_CPU0_SB_DQ<15>")
	)
	(segment
		(start 411.155642 -299.914056)
		(end 411.300422 -300.058836)
		(width 0.14478)
		(layer "In13.Cu")
		(net "M_H_CPU0_SB_DQ<15>")
	)
	(segment
		(start 409.646882 -299.359828)
		(end 409.908502 -299.359828)
		(width 0.14478)
		(layer "In13.Cu")
		(net "M_H_CPU0_SB_DQ<15>")
	)
	(arc
		(start 384.171952 -283.483558)
		(mid 384.454908 -283.559735)
		(end 384.737864 -283.483558)
		(width 0.0889)
		(layer "In13.Cu")
		(net "M_H_CPU0_SB_DQ<15>")
	)
	(arc
		(start 391.70229 -283.489654)
		(mid 391.980976 -283.559874)
		(end 392.258042 -283.483558)
		(width 0.0889)
		(layer "In13.Cu")
		(net "M_H_CPU0_SB_DQ<15>")
	)
	(arc
		(start 385.677664 -283.483558)
		(mid 385.859915 -283.433208)
		(end 386.043424 -283.478732)
		(width 0.0889)
		(layer "In13.Cu")
		(net "M_H_CPU0_SB_DQ<15>")
	)
	(arc
		(start 393.192508 -283.487114)
		(mid 393.320105 -283.431649)
		(end 393.457938 -283.412692)
		(width 0.0889)
		(layer "In13.Cu")
		(net "M_H_CPU0_SB_DQ<15>")
	)
	(arc
		(start 384.737864 -283.483558)
		(mid 384.924808 -283.433303)
		(end 385.111752 -283.483558)
		(width 0.0889)
		(layer "In13.Cu")
		(net "M_H_CPU0_SB_DQ<15>")
	)
	(arc
		(start 386.99186 -283.483558)
		(mid 387.274816 -283.559735)
		(end 387.557772 -283.483558)
		(width 0.0889)
		(layer "In13.Cu")
		(net "M_H_CPU0_SB_DQ<15>")
	)
	(arc
		(start 388.506208 -283.478732)
		(mid 388.689716 -283.433238)
		(end 388.871968 -283.483558)
		(width 0.0889)
		(layer "In13.Cu")
		(net "M_H_CPU0_SB_DQ<15>")
	)
	(arc
		(start 388.871968 -283.483558)
		(mid 389.154924 -283.559735)
		(end 389.43788 -283.483558)
		(width 0.0889)
		(layer "In13.Cu")
		(net "M_H_CPU0_SB_DQ<15>")
	)
	(arc
		(start 390.751822 -283.483558)
		(mid 391.034778 -283.559735)
		(end 391.317734 -283.483558)
		(width 0.0889)
		(layer "In13.Cu")
		(net "M_H_CPU0_SB_DQ<15>")
	)
	(arc
		(start 390.37768 -283.483558)
		(mid 390.559931 -283.433208)
		(end 390.74344 -283.478732)
		(width 0.0889)
		(layer "In13.Cu")
		(net "M_H_CPU0_SB_DQ<15>")
	)
	(arc
		(start 392.258042 -283.483558)
		(mid 392.440547 -283.433081)
		(end 392.62431 -283.478732)
		(width 0.0889)
		(layer "In13.Cu")
		(net "M_H_CPU0_SB_DQ<15>")
	)
	(arc
		(start 392.632692 -283.483558)
		(mid 392.91212 -283.559724)
		(end 393.192508 -283.487114)
		(width 0.0889)
		(layer "In13.Cu")
		(net "M_H_CPU0_SB_DQ<15>")
	)
	(arc
		(start 387.931914 -283.483558)
		(mid 388.21487 -283.559735)
		(end 388.497826 -283.483558)
		(width 0.0889)
		(layer "In13.Cu")
		(net "M_H_CPU0_SB_DQ<15>")
	)
	(arc
		(start 383.231898 -283.483558)
		(mid 383.514854 -283.559735)
		(end 383.79781 -283.483558)
		(width 0.0889)
		(layer "In13.Cu")
		(net "M_H_CPU0_SB_DQ<15>")
	)
	(arc
		(start 386.617718 -283.483558)
		(mid 386.799969 -283.433208)
		(end 386.983478 -283.478732)
		(width 0.0889)
		(layer "In13.Cu")
		(net "M_H_CPU0_SB_DQ<15>")
	)
	(arc
		(start 389.43788 -283.483558)
		(mid 389.624824 -283.433303)
		(end 389.811768 -283.483558)
		(width 0.0889)
		(layer "In13.Cu")
		(net "M_H_CPU0_SB_DQ<15>")
	)
	(arc
		(start 391.326116 -283.478732)
		(mid 391.509624 -283.433238)
		(end 391.691876 -283.483558)
		(width 0.0889)
		(layer "In13.Cu")
		(net "M_H_CPU0_SB_DQ<15>")
	)
	(arc
		(start 387.566154 -283.478732)
		(mid 387.749662 -283.433238)
		(end 387.931914 -283.483558)
		(width 0.0889)
		(layer "In13.Cu")
		(net "M_H_CPU0_SB_DQ<15>")
	)
	(arc
		(start 382.913128 -283.457396)
		(mid 383.07546 -283.434578)
		(end 383.231898 -283.483558)
		(width 0.0889)
		(layer "In13.Cu")
		(net "M_H_CPU0_SB_DQ<15>")
	)
	(arc
		(start 386.051806 -283.483558)
		(mid 386.334762 -283.559735)
		(end 386.617718 -283.483558)
		(width 0.0889)
		(layer "In13.Cu")
		(net "M_H_CPU0_SB_DQ<15>")
	)
	(arc
		(start 383.806192 -283.478732)
		(mid 383.9897 -283.433238)
		(end 384.171952 -283.483558)
		(width 0.0889)
		(layer "In13.Cu")
		(net "M_H_CPU0_SB_DQ<15>")
	)
	(arc
		(start 389.811768 -283.483558)
		(mid 390.094724 -283.559735)
		(end 390.37768 -283.483558)
		(width 0.0889)
		(layer "In13.Cu")
		(net "M_H_CPU0_SB_DQ<15>")
	)
	(arc
		(start 385.111752 -283.483558)
		(mid 385.394708 -283.559735)
		(end 385.677664 -283.483558)
		(width 0.0889)
		(layer "In13.Cu")
		(net "M_H_CPU0_SB_DQ<15>")
	)
	(segment
		(start 383.988056 -282.730194)
		(end 384.454908 -282.996132)
		(width 0.10668)
		(layer "F.Cu")
		(net "M_H_CPU0_SB_DQ<14>")
	)
	(segment
		(start 397.408654 -283.14777)
		(end 405.103838 -290.842954)
		(width 0.14478)
		(layer "In13.Cu")
		(net "M_H_CPU0_SB_DQ<14>")
	)
	(segment
		(start 417.144962 -297.210226)
		(end 417.289742 -297.065446)
		(width 0.14478)
		(layer "In13.Cu")
		(net "M_H_CPU0_SB_DQ<14>")
	)
	(segment
		(start 416.883342 -297.210226)
		(end 417.144962 -297.210226)
		(width 0.14478)
		(layer "In13.Cu")
		(net "M_H_CPU0_SB_DQ<14>")
	)
	(segment
		(start 415.636202 -296.993564)
		(end 415.636202 -297.065446)
		(width 0.14478)
		(layer "In13.Cu")
		(net "M_H_CPU0_SB_DQ<14>")
	)
	(segment
		(start 416.187382 -297.065446)
		(end 416.187382 -296.993564)
		(width 0.14478)
		(layer "In13.Cu")
		(net "M_H_CPU0_SB_DQ<14>")
	)
	(segment
		(start 405.501602 -295.157652)
		(end 405.706326 -295.157652)
		(width 0.14478)
		(layer "In13.Cu")
		(net "M_H_CPU0_SB_DQ<14>")
	)
	(segment
		(start 418.266372 -297.210226)
		(end 419.11651 -298.060364)
		(width 0.14478)
		(layer "In13.Cu")
		(net "M_H_CPU0_SB_DQ<14>")
	)
	(segment
		(start 392.140948 -282.662376)
		(end 392.161014 -282.673806)
		(width 0.0889)
		(layer "In13.Cu")
		(net "M_H_CPU0_SB_DQ<14>")
	)
	(segment
		(start 405.316436 -294.767762)
		(end 405.316436 -294.972486)
		(width 0.14478)
		(layer "In13.Cu")
		(net "M_H_CPU0_SB_DQ<14>")
	)
	(segment
		(start 405.706326 -295.157652)
		(end 405.954484 -294.909494)
		(width 0.14478)
		(layer "In13.Cu")
		(net "M_H_CPU0_SB_DQ<14>")
	)
	(segment
		(start 392.161014 -282.673806)
		(end 392.182604 -282.686252)
		(width 0.0889)
		(layer "In13.Cu")
		(net "M_H_CPU0_SB_DQ<14>")
	)
	(segment
		(start 415.229802 -296.848784)
		(end 415.491422 -296.848784)
		(width 0.14478)
		(layer "In13.Cu")
		(net "M_H_CPU0_SB_DQ<14>")
	)
	(segment
		(start 392.725402 -282.673552)
		(end 392.744198 -282.66263)
		(width 0.0889)
		(layer "In13.Cu")
		(net "M_H_CPU0_SB_DQ<14>")
	)
	(segment
		(start 408.498548 -297.248834)
		(end 409.237688 -297.987974)
		(width 0.14478)
		(layer "In13.Cu")
		(net "M_H_CPU0_SB_DQ<14>")
	)
	(segment
		(start 385.207764 -282.673552)
		(end 385.216146 -282.668726)
		(width 0.0889)
		(layer "In13.Cu")
		(net "M_H_CPU0_SB_DQ<14>")
	)
	(segment
		(start 389.333486 -282.668726)
		(end 389.341868 -282.673552)
		(width 0.0889)
		(layer "In13.Cu")
		(net "M_H_CPU0_SB_DQ<14>")
	)
	(segment
		(start 389.90778 -282.673552)
		(end 389.916162 -282.668726)
		(width 0.0889)
		(layer "In13.Cu")
		(net "M_H_CPU0_SB_DQ<14>")
	)
	(segment
		(start 406.281382 -295.937432)
		(end 406.486106 -295.937432)
		(width 0.14478)
		(layer "In13.Cu")
		(net "M_H_CPU0_SB_DQ<14>")
	)
	(segment
		(start 417.289742 -296.993564)
		(end 417.434522 -296.848784)
		(width 0.14478)
		(layer "In13.Cu")
		(net "M_H_CPU0_SB_DQ<14>")
	)
	(segment
		(start 417.289742 -297.065446)
		(end 417.289742 -296.993564)
		(width 0.14478)
		(layer "In13.Cu")
		(net "M_H_CPU0_SB_DQ<14>")
	)
	(segment
		(start 407.903934 -296.65422)
		(end 407.903934 -296.858944)
		(width 0.14478)
		(layer "In13.Cu")
		(net "M_H_CPU0_SB_DQ<14>")
	)
	(segment
		(start 405.954484 -294.909494)
		(end 406.159208 -294.909494)
		(width 0.14478)
		(layer "In13.Cu")
		(net "M_H_CPU0_SB_DQ<14>")
	)
	(segment
		(start 407.718768 -296.469054)
		(end 407.903934 -296.65422)
		(width 0.14478)
		(layer "In13.Cu")
		(net "M_H_CPU0_SB_DQ<14>")
	)
	(segment
		(start 407.840942 -297.496992)
		(end 408.045666 -297.496992)
		(width 0.14478)
		(layer "In13.Cu")
		(net "M_H_CPU0_SB_DQ<14>")
	)
	(segment
		(start 419.491668 -298.060364)
		(end 419.912038 -297.639994)
		(width 0.14478)
		(layer "In13.Cu")
		(net "M_H_CPU0_SB_DQ<14>")
	)
	(segment
		(start 405.564594 -294.519604)
		(end 405.316436 -294.767762)
		(width 0.14478)
		(layer "In13.Cu")
		(net "M_H_CPU0_SB_DQ<14>")
	)
	(segment
		(start 393.384786 -282.75026)
		(end 394.135864 -282.75026)
		(width 0.0889)
		(layer "In13.Cu")
		(net "M_H_CPU0_SB_DQ<14>")
	)
	(segment
		(start 384.63347 -282.668726)
		(end 384.641852 -282.673552)
		(width 0.0889)
		(layer "In13.Cu")
		(net "M_H_CPU0_SB_DQ<14>")
	)
	(segment
		(start 408.293824 -297.248834)
		(end 408.498548 -297.248834)
		(width 0.14478)
		(layer "In13.Cu")
		(net "M_H_CPU0_SB_DQ<14>")
	)
	(segment
		(start 405.564594 -294.31488)
		(end 405.564594 -294.519604)
		(width 0.14478)
		(layer "In13.Cu")
		(net "M_H_CPU0_SB_DQ<14>")
	)
	(segment
		(start 406.734264 -295.689274)
		(end 406.938988 -295.689274)
		(width 0.14478)
		(layer "In13.Cu")
		(net "M_H_CPU0_SB_DQ<14>")
	)
	(segment
		(start 417.840922 -296.993564)
		(end 417.840922 -297.065446)
		(width 0.14478)
		(layer "In13.Cu")
		(net "M_H_CPU0_SB_DQ<14>")
	)
	(segment
		(start 406.096216 -295.752266)
		(end 406.281382 -295.937432)
		(width 0.14478)
		(layer "In13.Cu")
		(net "M_H_CPU0_SB_DQ<14>")
	)
	(segment
		(start 395.75613 -283.14777)
		(end 397.408654 -283.14777)
		(width 0.14478)
		(layer "In13.Cu")
		(net "M_H_CPU0_SB_DQ<14>")
	)
	(segment
		(start 384.454908 -282.996132)
		(end 384.30073 -282.730702)
		(width 0.0889)
		(layer "In13.Cu")
		(net "M_H_CPU0_SB_DQ<14>")
	)
	(segment
		(start 415.780982 -297.210226)
		(end 416.042602 -297.210226)
		(width 0.14478)
		(layer "In13.Cu")
		(net "M_H_CPU0_SB_DQ<14>")
	)
	(segment
		(start 417.840922 -297.065446)
		(end 417.985702 -297.210226)
		(width 0.14478)
		(layer "In13.Cu")
		(net "M_H_CPU0_SB_DQ<14>")
	)
	(segment
		(start 417.434522 -296.848784)
		(end 417.696142 -296.848784)
		(width 0.14478)
		(layer "In13.Cu")
		(net "M_H_CPU0_SB_DQ<14>")
	)
	(segment
		(start 407.655776 -297.107102)
		(end 407.655776 -297.311826)
		(width 0.14478)
		(layer "In13.Cu")
		(net "M_H_CPU0_SB_DQ<14>")
	)
	(segment
		(start 405.103838 -293.854124)
		(end 405.564594 -294.31488)
		(width 0.14478)
		(layer "In13.Cu")
		(net "M_H_CPU0_SB_DQ<14>")
	)
	(segment
		(start 384.30073 -282.730702)
		(end 384.323082 -282.64739)
		(width 0.0889)
		(layer "In13.Cu")
		(net "M_H_CPU0_SB_DQ<14>")
	)
	(segment
		(start 406.096216 -295.547542)
		(end 406.096216 -295.752266)
		(width 0.14478)
		(layer "In13.Cu")
		(net "M_H_CPU0_SB_DQ<14>")
	)
	(segment
		(start 407.265886 -296.717212)
		(end 407.514044 -296.469054)
		(width 0.14478)
		(layer "In13.Cu")
		(net "M_H_CPU0_SB_DQ<14>")
	)
	(segment
		(start 416.332162 -296.848784)
		(end 416.593782 -296.848784)
		(width 0.14478)
		(layer "In13.Cu")
		(net "M_H_CPU0_SB_DQ<14>")
	)
	(segment
		(start 416.593782 -296.848784)
		(end 416.738562 -296.993564)
		(width 0.14478)
		(layer "In13.Cu")
		(net "M_H_CPU0_SB_DQ<14>")
	)
	(segment
		(start 416.738562 -297.065446)
		(end 416.883342 -297.210226)
		(width 0.14478)
		(layer "In13.Cu")
		(net "M_H_CPU0_SB_DQ<14>")
	)
	(segment
		(start 394.533374 -283.14777)
		(end 395.75613 -283.14777)
		(width 0.0889)
		(layer "In13.Cu")
		(net "M_H_CPU0_SB_DQ<14>")
	)
	(segment
		(start 407.124154 -295.87444)
		(end 407.124154 -296.079164)
		(width 0.14478)
		(layer "In13.Cu")
		(net "M_H_CPU0_SB_DQ<14>")
	)
	(segment
		(start 394.135864 -282.75026)
		(end 394.533374 -283.14777)
		(width 0.0889)
		(layer "In13.Cu")
		(net "M_H_CPU0_SB_DQ<14>")
	)
	(segment
		(start 386.147818 -282.673552)
		(end 386.1562 -282.668726)
		(width 0.0889)
		(layer "In13.Cu")
		(net "M_H_CPU0_SB_DQ<14>")
	)
	(segment
		(start 407.655776 -297.311826)
		(end 407.840942 -297.496992)
		(width 0.14478)
		(layer "In13.Cu")
		(net "M_H_CPU0_SB_DQ<14>")
	)
	(segment
		(start 416.738562 -296.993564)
		(end 416.738562 -297.065446)
		(width 0.14478)
		(layer "In13.Cu")
		(net "M_H_CPU0_SB_DQ<14>")
	)
	(segment
		(start 417.985702 -297.210226)
		(end 418.266372 -297.210226)
		(width 0.14478)
		(layer "In13.Cu")
		(net "M_H_CPU0_SB_DQ<14>")
	)
	(segment
		(start 405.103838 -290.842954)
		(end 405.103838 -293.854124)
		(width 0.14478)
		(layer "In13.Cu")
		(net "M_H_CPU0_SB_DQ<14>")
	)
	(segment
		(start 419.912038 -297.639994)
		(end 419.912038 -297.635168)
		(width 0.14478)
		(layer "In13.Cu")
		(net "M_H_CPU0_SB_DQ<14>")
	)
	(segment
		(start 406.938988 -295.689274)
		(end 407.124154 -295.87444)
		(width 0.14478)
		(layer "In13.Cu")
		(net "M_H_CPU0_SB_DQ<14>")
	)
	(segment
		(start 417.696142 -296.848784)
		(end 417.840922 -296.993564)
		(width 0.14478)
		(layer "In13.Cu")
		(net "M_H_CPU0_SB_DQ<14>")
	)
	(segment
		(start 407.124154 -296.079164)
		(end 406.875996 -296.327322)
		(width 0.14478)
		(layer "In13.Cu")
		(net "M_H_CPU0_SB_DQ<14>")
	)
	(segment
		(start 416.187382 -296.993564)
		(end 416.332162 -296.848784)
		(width 0.14478)
		(layer "In13.Cu")
		(net "M_H_CPU0_SB_DQ<14>")
	)
	(segment
		(start 415.085022 -296.993564)
		(end 415.229802 -296.848784)
		(width 0.14478)
		(layer "In13.Cu")
		(net "M_H_CPU0_SB_DQ<14>")
	)
	(segment
		(start 406.875996 -296.532046)
		(end 407.061162 -296.717212)
		(width 0.14478)
		(layer "In13.Cu")
		(net "M_H_CPU0_SB_DQ<14>")
	)
	(segment
		(start 407.061162 -296.717212)
		(end 407.265886 -296.717212)
		(width 0.14478)
		(layer "In13.Cu")
		(net "M_H_CPU0_SB_DQ<14>")
	)
	(segment
		(start 408.045666 -297.496992)
		(end 408.293824 -297.248834)
		(width 0.14478)
		(layer "In13.Cu")
		(net "M_H_CPU0_SB_DQ<14>")
	)
	(segment
		(start 407.514044 -296.469054)
		(end 407.718768 -296.469054)
		(width 0.14478)
		(layer "In13.Cu")
		(net "M_H_CPU0_SB_DQ<14>")
	)
	(segment
		(start 407.903934 -296.858944)
		(end 407.655776 -297.107102)
		(width 0.14478)
		(layer "In13.Cu")
		(net "M_H_CPU0_SB_DQ<14>")
	)
	(segment
		(start 388.393432 -282.668726)
		(end 388.401814 -282.673552)
		(width 0.0889)
		(layer "In13.Cu")
		(net "M_H_CPU0_SB_DQ<14>")
	)
	(segment
		(start 416.042602 -297.210226)
		(end 416.187382 -297.065446)
		(width 0.14478)
		(layer "In13.Cu")
		(net "M_H_CPU0_SB_DQ<14>")
	)
	(segment
		(start 419.11651 -298.060364)
		(end 419.491668 -298.060364)
		(width 0.14478)
		(layer "In13.Cu")
		(net "M_H_CPU0_SB_DQ<14>")
	)
	(segment
		(start 406.344374 -295.299384)
		(end 406.096216 -295.547542)
		(width 0.14478)
		(layer "In13.Cu")
		(net "M_H_CPU0_SB_DQ<14>")
	)
	(segment
		(start 405.316436 -294.972486)
		(end 405.501602 -295.157652)
		(width 0.14478)
		(layer "In13.Cu")
		(net "M_H_CPU0_SB_DQ<14>")
	)
	(segment
		(start 414.162494 -297.987974)
		(end 415.085022 -297.065446)
		(width 0.14478)
		(layer "In13.Cu")
		(net "M_H_CPU0_SB_DQ<14>")
	)
	(segment
		(start 406.344374 -295.09466)
		(end 406.344374 -295.299384)
		(width 0.14478)
		(layer "In13.Cu")
		(net "M_H_CPU0_SB_DQ<14>")
	)
	(segment
		(start 415.491422 -296.848784)
		(end 415.636202 -296.993564)
		(width 0.14478)
		(layer "In13.Cu")
		(net "M_H_CPU0_SB_DQ<14>")
	)
	(segment
		(start 406.486106 -295.937432)
		(end 406.734264 -295.689274)
		(width 0.14478)
		(layer "In13.Cu")
		(net "M_H_CPU0_SB_DQ<14>")
	)
	(segment
		(start 415.085022 -297.065446)
		(end 415.085022 -296.993564)
		(width 0.14478)
		(layer "In13.Cu")
		(net "M_H_CPU0_SB_DQ<14>")
	)
	(segment
		(start 409.237688 -297.987974)
		(end 414.162494 -297.987974)
		(width 0.14478)
		(layer "In13.Cu")
		(net "M_H_CPU0_SB_DQ<14>")
	)
	(segment
		(start 406.159208 -294.909494)
		(end 406.344374 -295.09466)
		(width 0.14478)
		(layer "In13.Cu")
		(net "M_H_CPU0_SB_DQ<14>")
	)
	(segment
		(start 415.636202 -297.065446)
		(end 415.780982 -297.210226)
		(width 0.14478)
		(layer "In13.Cu")
		(net "M_H_CPU0_SB_DQ<14>")
	)
	(segment
		(start 406.875996 -296.327322)
		(end 406.875996 -296.532046)
		(width 0.14478)
		(layer "In13.Cu")
		(net "M_H_CPU0_SB_DQ<14>")
	)
	(arc
		(start 387.087872 -282.673552)
		(mid 387.274816 -282.623297)
		(end 387.46176 -282.673552)
		(width 0.0889)
		(layer "In13.Cu")
		(net "M_H_CPU0_SB_DQ<14>")
	)
	(arc
		(start 386.1562 -282.668726)
		(mid 386.339708 -282.623232)
		(end 386.52196 -282.673552)
		(width 0.0889)
		(layer "In13.Cu")
		(net "M_H_CPU0_SB_DQ<14>")
	)
	(arc
		(start 387.46176 -282.673552)
		(mid 387.744716 -282.749729)
		(end 388.027672 -282.673552)
		(width 0.0889)
		(layer "In13.Cu")
		(net "M_H_CPU0_SB_DQ<14>")
	)
	(arc
		(start 390.281922 -282.673552)
		(mid 390.564878 -282.749729)
		(end 390.847834 -282.673552)
		(width 0.0889)
		(layer "In13.Cu")
		(net "M_H_CPU0_SB_DQ<14>")
	)
	(arc
		(start 384.323082 -282.64739)
		(mid 384.480592 -282.624192)
		(end 384.63347 -282.668726)
		(width 0.0889)
		(layer "In13.Cu")
		(net "M_H_CPU0_SB_DQ<14>")
	)
	(arc
		(start 389.916162 -282.668726)
		(mid 390.09967 -282.623232)
		(end 390.281922 -282.673552)
		(width 0.0889)
		(layer "In13.Cu")
		(net "M_H_CPU0_SB_DQ<14>")
	)
	(arc
		(start 392.744198 -282.66263)
		(mid 392.923769 -282.622813)
		(end 393.10056 -282.673552)
		(width 0.0889)
		(layer "In13.Cu")
		(net "M_H_CPU0_SB_DQ<14>")
	)
	(arc
		(start 389.341868 -282.673552)
		(mid 389.624824 -282.749729)
		(end 389.90778 -282.673552)
		(width 0.0889)
		(layer "In13.Cu")
		(net "M_H_CPU0_SB_DQ<14>")
	)
	(arc
		(start 390.847834 -282.673552)
		(mid 391.034778 -282.623297)
		(end 391.221722 -282.673552)
		(width 0.0889)
		(layer "In13.Cu")
		(net "M_H_CPU0_SB_DQ<14>")
	)
	(arc
		(start 388.967726 -282.673552)
		(mid 389.149977 -282.623202)
		(end 389.333486 -282.668726)
		(width 0.0889)
		(layer "In13.Cu")
		(net "M_H_CPU0_SB_DQ<14>")
	)
	(arc
		(start 391.221722 -282.673552)
		(mid 391.504678 -282.749729)
		(end 391.787634 -282.673552)
		(width 0.0889)
		(layer "In13.Cu")
		(net "M_H_CPU0_SB_DQ<14>")
	)
	(arc
		(start 392.182604 -282.686252)
		(mid 392.455633 -282.749571)
		(end 392.725402 -282.673552)
		(width 0.0889)
		(layer "In13.Cu")
		(net "M_H_CPU0_SB_DQ<14>")
	)
	(arc
		(start 386.52196 -282.673552)
		(mid 386.804916 -282.749729)
		(end 387.087872 -282.673552)
		(width 0.0889)
		(layer "In13.Cu")
		(net "M_H_CPU0_SB_DQ<14>")
	)
	(arc
		(start 385.216146 -282.668726)
		(mid 385.399654 -282.623232)
		(end 385.581906 -282.673552)
		(width 0.0889)
		(layer "In13.Cu")
		(net "M_H_CPU0_SB_DQ<14>")
	)
	(arc
		(start 393.10056 -282.673552)
		(mid 393.237582 -282.730763)
		(end 393.384786 -282.75026)
		(width 0.0889)
		(layer "In13.Cu")
		(net "M_H_CPU0_SB_DQ<14>")
	)
	(arc
		(start 384.641852 -282.673552)
		(mid 384.924808 -282.749729)
		(end 385.207764 -282.673552)
		(width 0.0889)
		(layer "In13.Cu")
		(net "M_H_CPU0_SB_DQ<14>")
	)
	(arc
		(start 391.787634 -282.673552)
		(mid 391.962873 -282.623481)
		(end 392.140948 -282.662376)
		(width 0.0889)
		(layer "In13.Cu")
		(net "M_H_CPU0_SB_DQ<14>")
	)
	(arc
		(start 388.401814 -282.673552)
		(mid 388.68477 -282.749729)
		(end 388.967726 -282.673552)
		(width 0.0889)
		(layer "In13.Cu")
		(net "M_H_CPU0_SB_DQ<14>")
	)
	(arc
		(start 385.581906 -282.673552)
		(mid 385.864862 -282.749729)
		(end 386.147818 -282.673552)
		(width 0.0889)
		(layer "In13.Cu")
		(net "M_H_CPU0_SB_DQ<14>")
	)
	(arc
		(start 388.027672 -282.673552)
		(mid 388.209923 -282.623202)
		(end 388.393432 -282.668726)
		(width 0.0889)
		(layer "In13.Cu")
		(net "M_H_CPU0_SB_DQ<14>")
	)
	(segment
		(start 382.107948 -282.730194)
		(end 382.5748 -282.996132)
		(width 0.10668)
		(layer "F.Cu")
		(net "M_H_CPU0_SB_DQ<13>")
	)
	(segment
		(start 394.429234 -283.40685)
		(end 394.214096 -283.191712)
		(width 0.0889)
		(layer "In13.Cu")
		(net "M_H_CPU0_SB_DQ<13>")
	)
	(segment
		(start 397.227298 -283.60243)
		(end 395.835886 -283.60243)
		(width 0.14478)
		(layer "In13.Cu")
		(net "M_H_CPU0_SB_DQ<13>")
	)
	(segment
		(start 404.654258 -294.958008)
		(end 404.654258 -291.02939)
		(width 0.14478)
		(layer "In13.Cu")
		(net "M_H_CPU0_SB_DQ<13>")
	)
	(segment
		(start 391.796016 -283.323538)
		(end 391.787634 -283.318712)
		(width 0.0889)
		(layer "In13.Cu")
		(net "M_H_CPU0_SB_DQ<13>")
	)
	(segment
		(start 395.513814 -283.60243)
		(end 395.318234 -283.40685)
		(width 0.0889)
		(layer "In13.Cu")
		(net "M_H_CPU0_SB_DQ<13>")
	)
	(segment
		(start 413.609028 -298.910248)
		(end 408.606498 -298.910248)
		(width 0.14478)
		(layer "In13.Cu")
		(net "M_H_CPU0_SB_DQ<13>")
	)
	(segment
		(start 382.824736 -283.286962)
		(end 382.728724 -283.261562)
		(width 0.0889)
		(layer "In13.Cu")
		(net "M_H_CPU0_SB_DQ<13>")
	)
	(segment
		(start 419.605714 -298.910248)
		(end 418.520372 -298.460668)
		(width 0.14478)
		(layer "In13.Cu")
		(net "M_H_CPU0_SB_DQ<13>")
	)
	(segment
		(start 414.69437 -298.460668)
		(end 413.609028 -298.910248)
		(width 0.14478)
		(layer "In13.Cu")
		(net "M_H_CPU0_SB_DQ<13>")
	)
	(segment
		(start 395.318234 -283.40685)
		(end 394.429234 -283.40685)
		(width 0.0889)
		(layer "In13.Cu")
		(net "M_H_CPU0_SB_DQ<13>")
	)
	(segment
		(start 389.916162 -283.323538)
		(end 389.90778 -283.318712)
		(width 0.0889)
		(layer "In13.Cu")
		(net "M_H_CPU0_SB_DQ<13>")
	)
	(segment
		(start 388.401814 -283.318712)
		(end 388.393432 -283.323538)
		(width 0.0889)
		(layer "In13.Cu")
		(net "M_H_CPU0_SB_DQ<13>")
	)
	(segment
		(start 389.341868 -283.318712)
		(end 389.333486 -283.323538)
		(width 0.0889)
		(layer "In13.Cu")
		(net "M_H_CPU0_SB_DQ<13>")
	)
	(segment
		(start 392.72845 -283.318712)
		(end 392.718036 -283.312616)
		(width 0.0889)
		(layer "In13.Cu")
		(net "M_H_CPU0_SB_DQ<13>")
	)
	(segment
		(start 418.520372 -298.460668)
		(end 414.69437 -298.460668)
		(width 0.14478)
		(layer "In13.Cu")
		(net "M_H_CPU0_SB_DQ<13>")
	)
	(segment
		(start 386.1562 -283.323538)
		(end 386.147818 -283.318712)
		(width 0.0889)
		(layer "In13.Cu")
		(net "M_H_CPU0_SB_DQ<13>")
	)
	(segment
		(start 408.606498 -298.910248)
		(end 404.654258 -294.958008)
		(width 0.14478)
		(layer "In13.Cu")
		(net "M_H_CPU0_SB_DQ<13>")
	)
	(segment
		(start 424.012106 -298.485052)
		(end 421.142922 -298.910248)
		(width 0.14478)
		(layer "In13.Cu")
		(net "M_H_CPU0_SB_DQ<13>")
	)
	(segment
		(start 394.214096 -283.191712)
		(end 393.561062 -283.191712)
		(width 0.0889)
		(layer "In13.Cu")
		(net "M_H_CPU0_SB_DQ<13>")
	)
	(segment
		(start 382.728724 -283.261562)
		(end 382.5748 -282.996132)
		(width 0.0889)
		(layer "In13.Cu")
		(net "M_H_CPU0_SB_DQ<13>")
	)
	(segment
		(start 404.654258 -291.02939)
		(end 397.227298 -283.60243)
		(width 0.14478)
		(layer "In13.Cu")
		(net "M_H_CPU0_SB_DQ<13>")
	)
	(segment
		(start 384.641852 -283.318712)
		(end 384.63347 -283.323538)
		(width 0.0889)
		(layer "In13.Cu")
		(net "M_H_CPU0_SB_DQ<13>")
	)
	(segment
		(start 395.835886 -283.60243)
		(end 395.513814 -283.60243)
		(width 0.0889)
		(layer "In13.Cu")
		(net "M_H_CPU0_SB_DQ<13>")
	)
	(segment
		(start 383.701798 -283.318712)
		(end 383.693416 -283.323538)
		(width 0.0889)
		(layer "In13.Cu")
		(net "M_H_CPU0_SB_DQ<13>")
	)
	(segment
		(start 385.216146 -283.323538)
		(end 385.207764 -283.318712)
		(width 0.0889)
		(layer "In13.Cu")
		(net "M_H_CPU0_SB_DQ<13>")
	)
	(segment
		(start 421.142922 -298.910248)
		(end 419.605714 -298.910248)
		(width 0.14478)
		(layer "In13.Cu")
		(net "M_H_CPU0_SB_DQ<13>")
	)
	(arc
		(start 390.281922 -283.318712)
		(mid 390.099671 -283.369062)
		(end 389.916162 -283.323538)
		(width 0.0889)
		(layer "In13.Cu")
		(net "M_H_CPU0_SB_DQ<13>")
	)
	(arc
		(start 384.63347 -283.323538)
		(mid 384.449962 -283.369032)
		(end 384.26771 -283.318712)
		(width 0.0889)
		(layer "In13.Cu")
		(net "M_H_CPU0_SB_DQ<13>")
	)
	(arc
		(start 389.333486 -283.323538)
		(mid 389.149978 -283.369032)
		(end 388.967726 -283.318712)
		(width 0.0889)
		(layer "In13.Cu")
		(net "M_H_CPU0_SB_DQ<13>")
	)
	(arc
		(start 388.967726 -283.318712)
		(mid 388.68477 -283.242535)
		(end 388.401814 -283.318712)
		(width 0.0889)
		(layer "In13.Cu")
		(net "M_H_CPU0_SB_DQ<13>")
	)
	(arc
		(start 389.90778 -283.318712)
		(mid 389.624824 -283.242535)
		(end 389.341868 -283.318712)
		(width 0.0889)
		(layer "In13.Cu")
		(net "M_H_CPU0_SB_DQ<13>")
	)
	(arc
		(start 383.327656 -283.318712)
		(mid 383.079943 -283.243492)
		(end 382.824736 -283.286962)
		(width 0.0889)
		(layer "In13.Cu")
		(net "M_H_CPU0_SB_DQ<13>")
	)
	(arc
		(start 393.086082 -283.327856)
		(mid 392.9061 -283.368956)
		(end 392.72845 -283.318712)
		(width 0.0889)
		(layer "In13.Cu")
		(net "M_H_CPU0_SB_DQ<13>")
	)
	(arc
		(start 390.847834 -283.318712)
		(mid 390.564878 -283.242535)
		(end 390.281922 -283.318712)
		(width 0.0889)
		(layer "In13.Cu")
		(net "M_H_CPU0_SB_DQ<13>")
	)
	(arc
		(start 384.26771 -283.318712)
		(mid 383.984754 -283.242535)
		(end 383.701798 -283.318712)
		(width 0.0889)
		(layer "In13.Cu")
		(net "M_H_CPU0_SB_DQ<13>")
	)
	(arc
		(start 388.027672 -283.318712)
		(mid 387.744716 -283.242535)
		(end 387.46176 -283.318712)
		(width 0.0889)
		(layer "In13.Cu")
		(net "M_H_CPU0_SB_DQ<13>")
	)
	(arc
		(start 388.393432 -283.323538)
		(mid 388.209924 -283.369032)
		(end 388.027672 -283.318712)
		(width 0.0889)
		(layer "In13.Cu")
		(net "M_H_CPU0_SB_DQ<13>")
	)
	(arc
		(start 391.787634 -283.318712)
		(mid 391.504678 -283.242535)
		(end 391.221722 -283.318712)
		(width 0.0889)
		(layer "In13.Cu")
		(net "M_H_CPU0_SB_DQ<13>")
	)
	(arc
		(start 391.221722 -283.318712)
		(mid 391.034778 -283.368967)
		(end 390.847834 -283.318712)
		(width 0.0889)
		(layer "In13.Cu")
		(net "M_H_CPU0_SB_DQ<13>")
	)
	(arc
		(start 385.207764 -283.318712)
		(mid 384.924808 -283.242535)
		(end 384.641852 -283.318712)
		(width 0.0889)
		(layer "In13.Cu")
		(net "M_H_CPU0_SB_DQ<13>")
	)
	(arc
		(start 385.581906 -283.318712)
		(mid 385.399655 -283.369062)
		(end 385.216146 -283.323538)
		(width 0.0889)
		(layer "In13.Cu")
		(net "M_H_CPU0_SB_DQ<13>")
	)
	(arc
		(start 393.561062 -283.191712)
		(mid 393.313998 -283.226403)
		(end 393.086082 -283.327856)
		(width 0.0889)
		(layer "In13.Cu")
		(net "M_H_CPU0_SB_DQ<13>")
	)
	(arc
		(start 387.087872 -283.318712)
		(mid 386.804916 -283.242535)
		(end 386.52196 -283.318712)
		(width 0.0889)
		(layer "In13.Cu")
		(net "M_H_CPU0_SB_DQ<13>")
	)
	(arc
		(start 387.46176 -283.318712)
		(mid 387.274816 -283.368967)
		(end 387.087872 -283.318712)
		(width 0.0889)
		(layer "In13.Cu")
		(net "M_H_CPU0_SB_DQ<13>")
	)
	(arc
		(start 383.693416 -283.323538)
		(mid 383.509908 -283.369032)
		(end 383.327656 -283.318712)
		(width 0.0889)
		(layer "In13.Cu")
		(net "M_H_CPU0_SB_DQ<13>")
	)
	(arc
		(start 386.147818 -283.318712)
		(mid 385.864862 -283.242535)
		(end 385.581906 -283.318712)
		(width 0.0889)
		(layer "In13.Cu")
		(net "M_H_CPU0_SB_DQ<13>")
	)
	(arc
		(start 392.718036 -283.312616)
		(mid 392.43935 -283.242396)
		(end 392.162284 -283.318712)
		(width 0.0889)
		(layer "In13.Cu")
		(net "M_H_CPU0_SB_DQ<13>")
	)
	(arc
		(start 392.162284 -283.318712)
		(mid 391.979779 -283.369189)
		(end 391.796016 -283.323538)
		(width 0.0889)
		(layer "In13.Cu")
		(net "M_H_CPU0_SB_DQ<13>")
	)
	(arc
		(start 386.52196 -283.318712)
		(mid 386.339709 -283.369062)
		(end 386.1562 -283.323538)
		(width 0.0889)
		(layer "In13.Cu")
		(net "M_H_CPU0_SB_DQ<13>")
	)
	(segment
		(start 383.517902 -281.920188)
		(end 383.984754 -282.186126)
		(width 0.10668)
		(layer "F.Cu")
		(net "M_H_CPU0_SB_DQ<12>")
	)
	(segment
		(start 411.330648 -297.483276)
		(end 411.052518 -297.483276)
		(width 0.14478)
		(layer "In13.Cu")
		(net "M_H_CPU0_SB_DQ<12>")
	)
	(segment
		(start 415.032952 -296.360342)
		(end 414.183068 -297.210226)
		(width 0.14478)
		(layer "In13.Cu")
		(net "M_H_CPU0_SB_DQ<12>")
	)
	(segment
		(start 411.881828 -297.210226)
		(end 411.603698 -297.210226)
		(width 0.14478)
		(layer "In13.Cu")
		(net "M_H_CPU0_SB_DQ<12>")
	)
	(segment
		(start 409.950158 -297.483276)
		(end 409.677108 -297.210226)
		(width 0.14478)
		(layer "In13.Cu")
		(net "M_H_CPU0_SB_DQ<12>")
	)
	(segment
		(start 394.236956 -282.55976)
		(end 393.38504 -282.55976)
		(width 0.0889)
		(layer "In13.Cu")
		(net "M_H_CPU0_SB_DQ<12>")
	)
	(segment
		(start 421.82542 -297.219878)
		(end 420.805864 -297.219878)
		(width 0.14478)
		(layer "In13.Cu")
		(net "M_H_CPU0_SB_DQ<12>")
	)
	(segment
		(start 392.652758 -282.49499)
		(end 392.62939 -282.508706)
		(width 0.0889)
		(layer "In13.Cu")
		(net "M_H_CPU0_SB_DQ<12>")
	)
	(segment
		(start 387.566154 -282.513532)
		(end 387.557772 -282.508706)
		(width 0.0889)
		(layer "In13.Cu")
		(net "M_H_CPU0_SB_DQ<12>")
	)
	(segment
		(start 395.214602 -282.35021)
		(end 394.446506 -282.35021)
		(width 0.0889)
		(layer "In13.Cu")
		(net "M_H_CPU0_SB_DQ<12>")
	)
	(segment
		(start 392.274552 -282.518866)
		(end 392.256264 -282.508452)
		(width 0.0889)
		(layer "In13.Cu")
		(net "M_H_CPU0_SB_DQ<12>")
	)
	(segment
		(start 412.984188 -297.210226)
		(end 412.706058 -297.210226)
		(width 0.14478)
		(layer "In13.Cu")
		(net "M_H_CPU0_SB_DQ<12>")
	)
	(segment
		(start 411.603698 -297.210226)
		(end 411.330648 -297.483276)
		(width 0.14478)
		(layer "In13.Cu")
		(net "M_H_CPU0_SB_DQ<12>")
	)
	(segment
		(start 391.326116 -282.513532)
		(end 391.317734 -282.508706)
		(width 0.0889)
		(layer "In13.Cu")
		(net "M_H_CPU0_SB_DQ<12>")
	)
	(segment
		(start 392.256264 -282.508452)
		(end 392.234674 -282.496006)
		(width 0.0889)
		(layer "In13.Cu")
		(net "M_H_CPU0_SB_DQ<12>")
	)
	(segment
		(start 384.235198 -282.476956)
		(end 384.138932 -282.451556)
		(width 0.0889)
		(layer "In13.Cu")
		(net "M_H_CPU0_SB_DQ<12>")
	)
	(segment
		(start 409.09621 -297.210226)
		(end 405.553418 -293.667434)
		(width 0.14478)
		(layer "In13.Cu")
		(net "M_H_CPU0_SB_DQ<12>")
	)
	(segment
		(start 412.706058 -297.210226)
		(end 412.433008 -297.483276)
		(width 0.14478)
		(layer "In13.Cu")
		(net "M_H_CPU0_SB_DQ<12>")
	)
	(segment
		(start 412.154878 -297.483276)
		(end 411.881828 -297.210226)
		(width 0.14478)
		(layer "In13.Cu")
		(net "M_H_CPU0_SB_DQ<12>")
	)
	(segment
		(start 384.138932 -282.451556)
		(end 383.984754 -282.186126)
		(width 0.0889)
		(layer "In13.Cu")
		(net "M_H_CPU0_SB_DQ<12>")
	)
	(segment
		(start 410.779468 -297.210226)
		(end 410.501338 -297.210226)
		(width 0.14478)
		(layer "In13.Cu")
		(net "M_H_CPU0_SB_DQ<12>")
	)
	(segment
		(start 424.012106 -296.78503)
		(end 421.82542 -297.219878)
		(width 0.14478)
		(layer "In13.Cu")
		(net "M_H_CPU0_SB_DQ<12>")
	)
	(segment
		(start 420.805864 -297.219878)
		(end 418.730684 -296.360342)
		(width 0.14478)
		(layer "In13.Cu")
		(net "M_H_CPU0_SB_DQ<12>")
	)
	(segment
		(start 397.59001 -282.69311)
		(end 395.835886 -282.69311)
		(width 0.14478)
		(layer "In13.Cu")
		(net "M_H_CPU0_SB_DQ<12>")
	)
	(segment
		(start 413.535368 -297.483276)
		(end 413.257238 -297.483276)
		(width 0.14478)
		(layer "In13.Cu")
		(net "M_H_CPU0_SB_DQ<12>")
	)
	(segment
		(start 395.835886 -282.69311)
		(end 395.557502 -282.69311)
		(width 0.0889)
		(layer "In13.Cu")
		(net "M_H_CPU0_SB_DQ<12>")
	)
	(segment
		(start 386.99186 -282.508706)
		(end 386.983478 -282.513532)
		(width 0.0889)
		(layer "In13.Cu")
		(net "M_H_CPU0_SB_DQ<12>")
	)
	(segment
		(start 413.808418 -297.210226)
		(end 413.535368 -297.483276)
		(width 0.14478)
		(layer "In13.Cu")
		(net "M_H_CPU0_SB_DQ<12>")
	)
	(segment
		(start 405.553418 -293.667434)
		(end 405.553418 -290.656518)
		(width 0.14478)
		(layer "In13.Cu")
		(net "M_H_CPU0_SB_DQ<12>")
	)
	(segment
		(start 395.557502 -282.69311)
		(end 395.214602 -282.35021)
		(width 0.0889)
		(layer "In13.Cu")
		(net "M_H_CPU0_SB_DQ<12>")
	)
	(segment
		(start 418.730684 -296.360342)
		(end 415.032952 -296.360342)
		(width 0.14478)
		(layer "In13.Cu")
		(net "M_H_CPU0_SB_DQ<12>")
	)
	(segment
		(start 393.38504 -282.55976)
		(end 393.384786 -282.559506)
		(width 0.0889)
		(layer "In13.Cu")
		(net "M_H_CPU0_SB_DQ<12>")
	)
	(segment
		(start 390.751822 -282.508706)
		(end 390.74344 -282.513532)
		(width 0.0889)
		(layer "In13.Cu")
		(net "M_H_CPU0_SB_DQ<12>")
	)
	(segment
		(start 394.446506 -282.35021)
		(end 394.236956 -282.55976)
		(width 0.0889)
		(layer "In13.Cu")
		(net "M_H_CPU0_SB_DQ<12>")
	)
	(segment
		(start 410.501338 -297.210226)
		(end 410.228288 -297.483276)
		(width 0.14478)
		(layer "In13.Cu")
		(net "M_H_CPU0_SB_DQ<12>")
	)
	(segment
		(start 411.052518 -297.483276)
		(end 410.779468 -297.210226)
		(width 0.14478)
		(layer "In13.Cu")
		(net "M_H_CPU0_SB_DQ<12>")
	)
	(segment
		(start 386.051806 -282.508706)
		(end 386.043424 -282.513532)
		(width 0.0889)
		(layer "In13.Cu")
		(net "M_H_CPU0_SB_DQ<12>")
	)
	(segment
		(start 409.677108 -297.210226)
		(end 409.09621 -297.210226)
		(width 0.14478)
		(layer "In13.Cu")
		(net "M_H_CPU0_SB_DQ<12>")
	)
	(segment
		(start 405.553418 -290.656518)
		(end 397.59001 -282.69311)
		(width 0.14478)
		(layer "In13.Cu")
		(net "M_H_CPU0_SB_DQ<12>")
	)
	(segment
		(start 388.506208 -282.513532)
		(end 388.497826 -282.508706)
		(width 0.0889)
		(layer "In13.Cu")
		(net "M_H_CPU0_SB_DQ<12>")
	)
	(segment
		(start 410.228288 -297.483276)
		(end 409.950158 -297.483276)
		(width 0.14478)
		(layer "In13.Cu")
		(net "M_H_CPU0_SB_DQ<12>")
	)
	(segment
		(start 413.257238 -297.483276)
		(end 412.984188 -297.210226)
		(width 0.14478)
		(layer "In13.Cu")
		(net "M_H_CPU0_SB_DQ<12>")
	)
	(segment
		(start 414.183068 -297.210226)
		(end 413.808418 -297.210226)
		(width 0.14478)
		(layer "In13.Cu")
		(net "M_H_CPU0_SB_DQ<12>")
	)
	(segment
		(start 412.433008 -297.483276)
		(end 412.154878 -297.483276)
		(width 0.14478)
		(layer "In13.Cu")
		(net "M_H_CPU0_SB_DQ<12>")
	)
	(arc
		(start 386.617718 -282.508706)
		(mid 386.334762 -282.432529)
		(end 386.051806 -282.508706)
		(width 0.0889)
		(layer "In13.Cu")
		(net "M_H_CPU0_SB_DQ<12>")
	)
	(arc
		(start 389.43788 -282.508706)
		(mid 389.154924 -282.432529)
		(end 388.871968 -282.508706)
		(width 0.0889)
		(layer "In13.Cu")
		(net "M_H_CPU0_SB_DQ<12>")
	)
	(arc
		(start 387.557772 -282.508706)
		(mid 387.274816 -282.432529)
		(end 386.99186 -282.508706)
		(width 0.0889)
		(layer "In13.Cu")
		(net "M_H_CPU0_SB_DQ<12>")
	)
	(arc
		(start 384.737864 -282.508706)
		(mid 384.490268 -282.433528)
		(end 384.235198 -282.476956)
		(width 0.0889)
		(layer "In13.Cu")
		(net "M_H_CPU0_SB_DQ<12>")
	)
	(arc
		(start 387.931914 -282.508706)
		(mid 387.749663 -282.559056)
		(end 387.566154 -282.513532)
		(width 0.0889)
		(layer "In13.Cu")
		(net "M_H_CPU0_SB_DQ<12>")
	)
	(arc
		(start 393.384786 -282.559506)
		(mid 393.287298 -282.546623)
		(end 393.196572 -282.508706)
		(width 0.0889)
		(layer "In13.Cu")
		(net "M_H_CPU0_SB_DQ<12>")
	)
	(arc
		(start 386.983478 -282.513532)
		(mid 386.79997 -282.559026)
		(end 386.617718 -282.508706)
		(width 0.0889)
		(layer "In13.Cu")
		(net "M_H_CPU0_SB_DQ<12>")
	)
	(arc
		(start 385.677664 -282.508706)
		(mid 385.394708 -282.432529)
		(end 385.111752 -282.508706)
		(width 0.0889)
		(layer "In13.Cu")
		(net "M_H_CPU0_SB_DQ<12>")
	)
	(arc
		(start 389.811768 -282.508706)
		(mid 389.624824 -282.558961)
		(end 389.43788 -282.508706)
		(width 0.0889)
		(layer "In13.Cu")
		(net "M_H_CPU0_SB_DQ<12>")
	)
	(arc
		(start 385.111752 -282.508706)
		(mid 384.924808 -282.558961)
		(end 384.737864 -282.508706)
		(width 0.0889)
		(layer "In13.Cu")
		(net "M_H_CPU0_SB_DQ<12>")
	)
	(arc
		(start 386.043424 -282.513532)
		(mid 385.859916 -282.559026)
		(end 385.677664 -282.508706)
		(width 0.0889)
		(layer "In13.Cu")
		(net "M_H_CPU0_SB_DQ<12>")
	)
	(arc
		(start 391.691876 -282.508706)
		(mid 391.509625 -282.559056)
		(end 391.326116 -282.513532)
		(width 0.0889)
		(layer "In13.Cu")
		(net "M_H_CPU0_SB_DQ<12>")
	)
	(arc
		(start 390.37768 -282.508706)
		(mid 390.094724 -282.432529)
		(end 389.811768 -282.508706)
		(width 0.0889)
		(layer "In13.Cu")
		(net "M_H_CPU0_SB_DQ<12>")
	)
	(arc
		(start 388.871968 -282.508706)
		(mid 388.689717 -282.559056)
		(end 388.506208 -282.513532)
		(width 0.0889)
		(layer "In13.Cu")
		(net "M_H_CPU0_SB_DQ<12>")
	)
	(arc
		(start 391.317734 -282.508706)
		(mid 391.034778 -282.432529)
		(end 390.751822 -282.508706)
		(width 0.0889)
		(layer "In13.Cu")
		(net "M_H_CPU0_SB_DQ<12>")
	)
	(arc
		(start 392.62939 -282.508706)
		(mid 392.45327 -282.558684)
		(end 392.274552 -282.518866)
		(width 0.0889)
		(layer "In13.Cu")
		(net "M_H_CPU0_SB_DQ<12>")
	)
	(arc
		(start 388.497826 -282.508706)
		(mid 388.21487 -282.432529)
		(end 387.931914 -282.508706)
		(width 0.0889)
		(layer "In13.Cu")
		(net "M_H_CPU0_SB_DQ<12>")
	)
	(arc
		(start 390.74344 -282.513532)
		(mid 390.559932 -282.559026)
		(end 390.37768 -282.508706)
		(width 0.0889)
		(layer "In13.Cu")
		(net "M_H_CPU0_SB_DQ<12>")
	)
	(arc
		(start 392.234674 -282.496006)
		(mid 391.961645 -282.432687)
		(end 391.691876 -282.508706)
		(width 0.0889)
		(layer "In13.Cu")
		(net "M_H_CPU0_SB_DQ<12>")
	)
	(arc
		(start 393.196572 -282.508706)
		(mid 392.926415 -282.431944)
		(end 392.652758 -282.49499)
		(width 0.0889)
		(layer "In13.Cu")
		(net "M_H_CPU0_SB_DQ<12>")
	)
	(segment
		(start 382.577848 -280.300176)
		(end 383.0447 -280.566114)
		(width 0.10668)
		(layer "F.Cu")
		(net "M_H_CPU0_SB_DQ<11>")
	)
	(segment
		(start 414.022794 -293.1541)
		(end 413.878014 -293.00932)
		(width 0.14478)
		(layer "In13.Cu")
		(net "M_H_CPU0_SB_DQ<11>")
	)
	(segment
		(start 416.811968 -292.55974)
		(end 416.550348 -292.55974)
		(width 0.14478)
		(layer "In13.Cu")
		(net "M_H_CPU0_SB_DQ<11>")
	)
	(segment
		(start 391.326116 -280.238708)
		(end 391.317734 -280.243534)
		(width 0.0889)
		(layer "In13.Cu")
		(net "M_H_CPU0_SB_DQ<11>")
	)
	(segment
		(start 411.720538 -293.554404)
		(end 411.575758 -293.409624)
		(width 0.14478)
		(layer "In13.Cu")
		(net "M_H_CPU0_SB_DQ<11>")
	)
	(segment
		(start 415.303208 -292.815264)
		(end 415.158428 -292.960044)
		(width 0.14478)
		(layer "In13.Cu")
		(net "M_H_CPU0_SB_DQ<11>")
	)
	(segment
		(start 411.575758 -293.409624)
		(end 411.075124 -293.409624)
		(width 0.14478)
		(layer "In13.Cu")
		(net "M_H_CPU0_SB_DQ<11>")
	)
	(segment
		(start 417.507928 -293.204646)
		(end 417.363148 -293.349426)
		(width 0.14478)
		(layer "In13.Cu")
		(net "M_H_CPU0_SB_DQ<11>")
	)
	(segment
		(start 414.870646 -292.960044)
		(end 414.421066 -293.409624)
		(width 0.14478)
		(layer "In13.Cu")
		(net "M_H_CPU0_SB_DQ<11>")
	)
	(segment
		(start 414.167574 -293.409624)
		(end 414.022794 -293.264844)
		(width 0.14478)
		(layer "In13.Cu")
		(net "M_H_CPU0_SB_DQ<11>")
	)
	(segment
		(start 409.96616 -293.51605)
		(end 410.47162 -293.01059)
		(width 0.14478)
		(layer "In13.Cu")
		(net "M_H_CPU0_SB_DQ<11>")
	)
	(segment
		(start 415.303208 -292.715442)
		(end 415.303208 -292.815264)
		(width 0.14478)
		(layer "In13.Cu")
		(net "M_H_CPU0_SB_DQ<11>")
	)
	(segment
		(start 382.890776 -280.300684)
		(end 383.0447 -280.566114)
		(width 0.0889)
		(layer "In13.Cu")
		(net "M_H_CPU0_SB_DQ<11>")
	)
	(segment
		(start 413.878014 -293.00932)
		(end 413.616394 -293.00932)
		(width 0.14478)
		(layer "In13.Cu")
		(net "M_H_CPU0_SB_DQ<11>")
	)
	(segment
		(start 412.271718 -293.554404)
		(end 412.271718 -293.727124)
		(width 0.14478)
		(layer "In13.Cu")
		(net "M_H_CPU0_SB_DQ<11>")
	)
	(segment
		(start 386.051806 -280.243534)
		(end 386.043424 -280.238708)
		(width 0.0889)
		(layer "In13.Cu")
		(net "M_H_CPU0_SB_DQ<11>")
	)
	(segment
		(start 395.75613 -280.2001)
		(end 395.748764 -280.192734)
		(width 0.0889)
		(layer "In13.Cu")
		(net "M_H_CPU0_SB_DQ<11>")
	)
	(segment
		(start 419.912038 -293.655496)
		(end 419.767258 -293.800276)
		(width 0.14478)
		(layer "In13.Cu")
		(net "M_H_CPU0_SB_DQ<11>")
	)
	(segment
		(start 411.865318 -293.871904)
		(end 411.720538 -293.727124)
		(width 0.14478)
		(layer "In13.Cu")
		(net "M_H_CPU0_SB_DQ<11>")
	)
	(segment
		(start 390.751822 -280.243534)
		(end 390.74344 -280.238708)
		(width 0.0889)
		(layer "In13.Cu")
		(net "M_H_CPU0_SB_DQ<11>")
	)
	(segment
		(start 413.065214 -293.889938)
		(end 412.920434 -293.745158)
		(width 0.14478)
		(layer "In13.Cu")
		(net "M_H_CPU0_SB_DQ<11>")
	)
	(segment
		(start 417.363148 -293.349426)
		(end 417.101528 -293.349426)
		(width 0.14478)
		(layer "In13.Cu")
		(net "M_H_CPU0_SB_DQ<11>")
	)
	(segment
		(start 412.271718 -293.727124)
		(end 412.126938 -293.871904)
		(width 0.14478)
		(layer "In13.Cu")
		(net "M_H_CPU0_SB_DQ<11>")
	)
	(segment
		(start 410.151326 -293.90594)
		(end 409.96616 -293.720774)
		(width 0.14478)
		(layer "In13.Cu")
		(net "M_H_CPU0_SB_DQ<11>")
	)
	(segment
		(start 415.447988 -292.570662)
		(end 415.303208 -292.715442)
		(width 0.14478)
		(layer "In13.Cu")
		(net "M_H_CPU0_SB_DQ<11>")
	)
	(segment
		(start 392.641836 -280.24963)
		(end 392.631422 -280.243534)
		(width 0.0889)
		(layer "In13.Cu")
		(net "M_H_CPU0_SB_DQ<11>")
	)
	(segment
		(start 410.471874 -292.806374)
		(end 407.841958 -290.176458)
		(width 0.14478)
		(layer "In13.Cu")
		(net "M_H_CPU0_SB_DQ<11>")
	)
	(segment
		(start 412.775654 -293.409624)
		(end 412.416498 -293.409624)
		(width 0.14478)
		(layer "In13.Cu")
		(net "M_H_CPU0_SB_DQ<11>")
	)
	(segment
		(start 409.96616 -293.720774)
		(end 409.96616 -293.51605)
		(width 0.14478)
		(layer "In13.Cu")
		(net "M_H_CPU0_SB_DQ<11>")
	)
	(segment
		(start 416.405568 -293.204646)
		(end 416.260788 -293.349426)
		(width 0.14478)
		(layer "In13.Cu")
		(net "M_H_CPU0_SB_DQ<11>")
	)
	(segment
		(start 412.920434 -293.554404)
		(end 412.775654 -293.409624)
		(width 0.14478)
		(layer "In13.Cu")
		(net "M_H_CPU0_SB_DQ<11>")
	)
	(segment
		(start 413.471614 -293.745158)
		(end 413.326834 -293.889938)
		(width 0.14478)
		(layer "In13.Cu")
		(net "M_H_CPU0_SB_DQ<11>")
	)
	(segment
		(start 412.126938 -293.871904)
		(end 411.865318 -293.871904)
		(width 0.14478)
		(layer "In13.Cu")
		(net "M_H_CPU0_SB_DQ<11>")
	)
	(segment
		(start 416.405568 -292.70452)
		(end 416.405568 -293.204646)
		(width 0.14478)
		(layer "In13.Cu")
		(net "M_H_CPU0_SB_DQ<11>")
	)
	(segment
		(start 386.99186 -280.243534)
		(end 386.983478 -280.238708)
		(width 0.0889)
		(layer "In13.Cu")
		(net "M_H_CPU0_SB_DQ<11>")
	)
	(segment
		(start 388.506208 -280.238708)
		(end 388.497826 -280.243534)
		(width 0.0889)
		(layer "In13.Cu")
		(net "M_H_CPU0_SB_DQ<11>")
	)
	(segment
		(start 412.920434 -293.745158)
		(end 412.920434 -293.554404)
		(width 0.14478)
		(layer "In13.Cu")
		(net "M_H_CPU0_SB_DQ<11>")
	)
	(segment
		(start 415.999168 -293.349426)
		(end 415.854388 -293.204646)
		(width 0.14478)
		(layer "In13.Cu")
		(net "M_H_CPU0_SB_DQ<11>")
	)
	(segment
		(start 414.421066 -293.409624)
		(end 414.167574 -293.409624)
		(width 0.14478)
		(layer "In13.Cu")
		(net "M_H_CPU0_SB_DQ<11>")
	)
	(segment
		(start 387.566154 -280.238708)
		(end 387.557772 -280.243534)
		(width 0.0889)
		(layer "In13.Cu")
		(net "M_H_CPU0_SB_DQ<11>")
	)
	(segment
		(start 419.767258 -293.800276)
		(end 418.714936 -293.800276)
		(width 0.14478)
		(layer "In13.Cu")
		(net "M_H_CPU0_SB_DQ<11>")
	)
	(segment
		(start 407.841958 -289.707574)
		(end 398.334484 -280.2001)
		(width 0.14478)
		(layer "In13.Cu")
		(net "M_H_CPU0_SB_DQ<11>")
	)
	(segment
		(start 419.912038 -293.384986)
		(end 419.912038 -293.655496)
		(width 0.14478)
		(layer "In13.Cu")
		(net "M_H_CPU0_SB_DQ<11>")
	)
	(segment
		(start 417.507928 -293.104824)
		(end 417.507928 -293.204646)
		(width 0.14478)
		(layer "In13.Cu")
		(net "M_H_CPU0_SB_DQ<11>")
	)
	(segment
		(start 382.913128 -280.217372)
		(end 382.890776 -280.300684)
		(width 0.0889)
		(layer "In13.Cu")
		(net "M_H_CPU0_SB_DQ<11>")
	)
	(segment
		(start 383.806192 -280.238708)
		(end 383.79781 -280.243534)
		(width 0.0889)
		(layer "In13.Cu")
		(net "M_H_CPU0_SB_DQ<11>")
	)
	(segment
		(start 398.334484 -280.2001)
		(end 395.75613 -280.2001)
		(width 0.14478)
		(layer "In13.Cu")
		(net "M_H_CPU0_SB_DQ<11>")
	)
	(segment
		(start 415.854388 -293.204646)
		(end 415.854388 -292.715442)
		(width 0.14478)
		(layer "In13.Cu")
		(net "M_H_CPU0_SB_DQ<11>")
	)
	(segment
		(start 415.854388 -292.715442)
		(end 415.709608 -292.570662)
		(width 0.14478)
		(layer "In13.Cu")
		(net "M_H_CPU0_SB_DQ<11>")
	)
	(segment
		(start 414.022794 -293.264844)
		(end 414.022794 -293.1541)
		(width 0.14478)
		(layer "In13.Cu")
		(net "M_H_CPU0_SB_DQ<11>")
	)
	(segment
		(start 407.841958 -290.176458)
		(end 407.841958 -289.707574)
		(width 0.14478)
		(layer "In13.Cu")
		(net "M_H_CPU0_SB_DQ<11>")
	)
	(segment
		(start 416.550348 -292.55974)
		(end 416.405568 -292.70452)
		(width 0.14478)
		(layer "In13.Cu")
		(net "M_H_CPU0_SB_DQ<11>")
	)
	(segment
		(start 416.956748 -292.70452)
		(end 416.811968 -292.55974)
		(width 0.14478)
		(layer "In13.Cu")
		(net "M_H_CPU0_SB_DQ<11>")
	)
	(segment
		(start 413.471614 -293.1541)
		(end 413.471614 -293.745158)
		(width 0.14478)
		(layer "In13.Cu")
		(net "M_H_CPU0_SB_DQ<11>")
	)
	(segment
		(start 416.956748 -293.204646)
		(end 416.956748 -292.70452)
		(width 0.14478)
		(layer "In13.Cu")
		(net "M_H_CPU0_SB_DQ<11>")
	)
	(segment
		(start 395.748764 -280.192734)
		(end 393.248388 -280.192734)
		(width 0.0889)
		(layer "In13.Cu")
		(net "M_H_CPU0_SB_DQ<11>")
	)
	(segment
		(start 417.101528 -293.349426)
		(end 416.956748 -293.204646)
		(width 0.14478)
		(layer "In13.Cu")
		(net "M_H_CPU0_SB_DQ<11>")
	)
	(segment
		(start 418.714936 -293.800276)
		(end 417.874704 -292.960044)
		(width 0.14478)
		(layer "In13.Cu")
		(net "M_H_CPU0_SB_DQ<11>")
	)
	(segment
		(start 413.616394 -293.00932)
		(end 413.471614 -293.1541)
		(width 0.14478)
		(layer "In13.Cu")
		(net "M_H_CPU0_SB_DQ<11>")
	)
	(segment
		(start 412.416498 -293.409624)
		(end 412.271718 -293.554404)
		(width 0.14478)
		(layer "In13.Cu")
		(net "M_H_CPU0_SB_DQ<11>")
	)
	(segment
		(start 415.709608 -292.570662)
		(end 415.447988 -292.570662)
		(width 0.14478)
		(layer "In13.Cu")
		(net "M_H_CPU0_SB_DQ<11>")
	)
	(segment
		(start 411.720538 -293.727124)
		(end 411.720538 -293.554404)
		(width 0.14478)
		(layer "In13.Cu")
		(net "M_H_CPU0_SB_DQ<11>")
	)
	(segment
		(start 393.248388 -280.192734)
		(end 393.197588 -280.243534)
		(width 0.0889)
		(layer "In13.Cu")
		(net "M_H_CPU0_SB_DQ<11>")
	)
	(segment
		(start 413.326834 -293.889938)
		(end 413.065214 -293.889938)
		(width 0.14478)
		(layer "In13.Cu")
		(net "M_H_CPU0_SB_DQ<11>")
	)
	(segment
		(start 411.066234 -293.400734)
		(end 410.86151 -293.400734)
		(width 0.14478)
		(layer "In13.Cu")
		(net "M_H_CPU0_SB_DQ<11>")
	)
	(segment
		(start 410.86151 -293.400734)
		(end 410.35605 -293.906194)
		(width 0.14478)
		(layer "In13.Cu")
		(net "M_H_CPU0_SB_DQ<11>")
	)
	(segment
		(start 415.158428 -292.960044)
		(end 414.870646 -292.960044)
		(width 0.14478)
		(layer "In13.Cu")
		(net "M_H_CPU0_SB_DQ<11>")
	)
	(segment
		(start 410.35605 -293.906194)
		(end 410.151326 -293.90594)
		(width 0.14478)
		(layer "In13.Cu")
		(net "M_H_CPU0_SB_DQ<11>")
	)
	(segment
		(start 417.652708 -292.960044)
		(end 417.507928 -293.104824)
		(width 0.14478)
		(layer "In13.Cu")
		(net "M_H_CPU0_SB_DQ<11>")
	)
	(segment
		(start 410.47162 -293.01059)
		(end 410.471874 -292.806374)
		(width 0.14478)
		(layer "In13.Cu")
		(net "M_H_CPU0_SB_DQ<11>")
	)
	(segment
		(start 417.874704 -292.960044)
		(end 417.652708 -292.960044)
		(width 0.14478)
		(layer "In13.Cu")
		(net "M_H_CPU0_SB_DQ<11>")
	)
	(segment
		(start 416.260788 -293.349426)
		(end 415.999168 -293.349426)
		(width 0.14478)
		(layer "In13.Cu")
		(net "M_H_CPU0_SB_DQ<11>")
	)
	(segment
		(start 392.257534 -280.243534)
		(end 392.24712 -280.24963)
		(width 0.0889)
		(layer "In13.Cu")
		(net "M_H_CPU0_SB_DQ<11>")
	)
	(segment
		(start 411.075124 -293.409624)
		(end 411.066234 -293.400734)
		(width 0.14478)
		(layer "In13.Cu")
		(net "M_H_CPU0_SB_DQ<11>")
	)
	(arc
		(start 391.317734 -280.243534)
		(mid 391.034778 -280.319711)
		(end 390.751822 -280.243534)
		(width 0.0889)
		(layer "In13.Cu")
		(net "M_H_CPU0_SB_DQ<11>")
	)
	(arc
		(start 383.231898 -280.243534)
		(mid 383.07546 -280.194563)
		(end 382.913128 -280.217372)
		(width 0.0889)
		(layer "In13.Cu")
		(net "M_H_CPU0_SB_DQ<11>")
	)
	(arc
		(start 393.197588 -280.243534)
		(mid 392.920521 -280.319805)
		(end 392.641836 -280.24963)
		(width 0.0889)
		(layer "In13.Cu")
		(net "M_H_CPU0_SB_DQ<11>")
	)
	(arc
		(start 385.677664 -280.243534)
		(mid 385.394708 -280.319711)
		(end 385.111752 -280.243534)
		(width 0.0889)
		(layer "In13.Cu")
		(net "M_H_CPU0_SB_DQ<11>")
	)
	(arc
		(start 387.931914 -280.243534)
		(mid 387.749663 -280.193184)
		(end 387.566154 -280.238708)
		(width 0.0889)
		(layer "In13.Cu")
		(net "M_H_CPU0_SB_DQ<11>")
	)
	(arc
		(start 387.557772 -280.243534)
		(mid 387.274816 -280.319711)
		(end 386.99186 -280.243534)
		(width 0.0889)
		(layer "In13.Cu")
		(net "M_H_CPU0_SB_DQ<11>")
	)
	(arc
		(start 388.497826 -280.243534)
		(mid 388.21487 -280.319711)
		(end 387.931914 -280.243534)
		(width 0.0889)
		(layer "In13.Cu")
		(net "M_H_CPU0_SB_DQ<11>")
	)
	(arc
		(start 392.631422 -280.243534)
		(mid 392.444478 -280.193279)
		(end 392.257534 -280.243534)
		(width 0.0889)
		(layer "In13.Cu")
		(net "M_H_CPU0_SB_DQ<11>")
	)
	(arc
		(start 386.617718 -280.243534)
		(mid 386.334762 -280.319711)
		(end 386.051806 -280.243534)
		(width 0.0889)
		(layer "In13.Cu")
		(net "M_H_CPU0_SB_DQ<11>")
	)
	(arc
		(start 385.111752 -280.243534)
		(mid 384.924808 -280.193279)
		(end 384.737864 -280.243534)
		(width 0.0889)
		(layer "In13.Cu")
		(net "M_H_CPU0_SB_DQ<11>")
	)
	(arc
		(start 386.043424 -280.238708)
		(mid 385.859916 -280.193214)
		(end 385.677664 -280.243534)
		(width 0.0889)
		(layer "In13.Cu")
		(net "M_H_CPU0_SB_DQ<11>")
	)
	(arc
		(start 386.983478 -280.238708)
		(mid 386.79997 -280.193214)
		(end 386.617718 -280.243534)
		(width 0.0889)
		(layer "In13.Cu")
		(net "M_H_CPU0_SB_DQ<11>")
	)
	(arc
		(start 389.43788 -280.243534)
		(mid 389.154924 -280.319711)
		(end 388.871968 -280.243534)
		(width 0.0889)
		(layer "In13.Cu")
		(net "M_H_CPU0_SB_DQ<11>")
	)
	(arc
		(start 389.811768 -280.243534)
		(mid 389.624824 -280.193279)
		(end 389.43788 -280.243534)
		(width 0.0889)
		(layer "In13.Cu")
		(net "M_H_CPU0_SB_DQ<11>")
	)
	(arc
		(start 384.171952 -280.243534)
		(mid 383.989701 -280.193184)
		(end 383.806192 -280.238708)
		(width 0.0889)
		(layer "In13.Cu")
		(net "M_H_CPU0_SB_DQ<11>")
	)
	(arc
		(start 383.79781 -280.243534)
		(mid 383.514854 -280.319711)
		(end 383.231898 -280.243534)
		(width 0.0889)
		(layer "In13.Cu")
		(net "M_H_CPU0_SB_DQ<11>")
	)
	(arc
		(start 390.74344 -280.238708)
		(mid 390.559932 -280.193214)
		(end 390.37768 -280.243534)
		(width 0.0889)
		(layer "In13.Cu")
		(net "M_H_CPU0_SB_DQ<11>")
	)
	(arc
		(start 392.24712 -280.24963)
		(mid 391.968688 -280.319728)
		(end 391.691876 -280.243534)
		(width 0.0889)
		(layer "In13.Cu")
		(net "M_H_CPU0_SB_DQ<11>")
	)
	(arc
		(start 391.691876 -280.243534)
		(mid 391.509625 -280.193184)
		(end 391.326116 -280.238708)
		(width 0.0889)
		(layer "In13.Cu")
		(net "M_H_CPU0_SB_DQ<11>")
	)
	(arc
		(start 390.37768 -280.243534)
		(mid 390.094724 -280.319711)
		(end 389.811768 -280.243534)
		(width 0.0889)
		(layer "In13.Cu")
		(net "M_H_CPU0_SB_DQ<11>")
	)
	(arc
		(start 384.737864 -280.243534)
		(mid 384.454908 -280.319711)
		(end 384.171952 -280.243534)
		(width 0.0889)
		(layer "In13.Cu")
		(net "M_H_CPU0_SB_DQ<11>")
	)
	(arc
		(start 388.871968 -280.243534)
		(mid 388.689717 -280.193184)
		(end 388.506208 -280.238708)
		(width 0.0889)
		(layer "In13.Cu")
		(net "M_H_CPU0_SB_DQ<11>")
	)
	(segment
		(start 383.988056 -279.49017)
		(end 384.454908 -279.756108)
		(width 0.10668)
		(layer "F.Cu")
		(net "M_H_CPU0_SB_DQ<10>")
	)
	(segment
		(start 403.973538 -284.276038)
		(end 403.93874 -284.310836)
		(width 0.14478)
		(layer "In13.Cu")
		(net "M_H_CPU0_SB_DQ<10>")
	)
	(segment
		(start 402.564346 -283.141166)
		(end 402.76907 -283.141166)
		(width 0.14478)
		(layer "In13.Cu")
		(net "M_H_CPU0_SB_DQ<10>")
	)
	(segment
		(start 407.482548 -287.785048)
		(end 407.687272 -287.785048)
		(width 0.14478)
		(layer "In13.Cu")
		(net "M_H_CPU0_SB_DQ<10>")
	)
	(segment
		(start 402.024088 -282.326588)
		(end 402.228812 -282.326588)
		(width 0.14478)
		(layer "In13.Cu")
		(net "M_H_CPU0_SB_DQ<10>")
	)
	(segment
		(start 399.26006 -279.632156)
		(end 399.26006 -279.83688)
		(width 0.14478)
		(layer "In13.Cu")
		(net "M_H_CPU0_SB_DQ<10>")
	)
	(segment
		(start 407.44775 -287.819846)
		(end 407.482548 -287.785048)
		(width 0.14478)
		(layer "In13.Cu")
		(net "M_H_CPU0_SB_DQ<10>")
	)
	(segment
		(start 393.652756 -279.442164)
		(end 393.805918 -279.442164)
		(width 0.0889)
		(layer "In13.Cu")
		(net "M_H_CPU0_SB_DQ<10>")
	)
	(segment
		(start 404.71852 -285.090616)
		(end 404.71852 -285.29534)
		(width 0.14478)
		(layer "In13.Cu")
		(net "M_H_CPU0_SB_DQ<10>")
	)
	(segment
		(start 411.586172 -291.683948)
		(end 412.012384 -292.11016)
		(width 0.14478)
		(layer "In13.Cu")
		(net "M_H_CPU0_SB_DQ<10>")
	)
	(segment
		(start 400.854418 -280.952194)
		(end 400.854418 -281.156918)
		(width 0.14478)
		(layer "In13.Cu")
		(net "M_H_CPU0_SB_DQ<10>")
	)
	(segment
		(start 405.10841 -285.480506)
		(end 405.143208 -285.445708)
		(width 0.14478)
		(layer "In13.Cu")
		(net "M_H_CPU0_SB_DQ<10>")
	)
	(segment
		(start 405.4983 -286.07512)
		(end 405.683466 -286.260286)
		(width 0.14478)
		(layer "In13.Cu")
		(net "M_H_CPU0_SB_DQ<10>")
	)
	(segment
		(start 411.1117 -291.953696)
		(end 411.381448 -291.683948)
		(width 0.14478)
		(layer "In13.Cu")
		(net "M_H_CPU0_SB_DQ<10>")
	)
	(segment
		(start 386.147818 -279.433528)
		(end 386.1562 -279.428702)
		(width 0.0889)
		(layer "In13.Cu")
		(net "M_H_CPU0_SB_DQ<10>")
	)
	(segment
		(start 405.683466 -286.260286)
		(end 405.88819 -286.260286)
		(width 0.14478)
		(layer "In13.Cu")
		(net "M_H_CPU0_SB_DQ<10>")
	)
	(segment
		(start 399.294858 -279.597358)
		(end 399.26006 -279.632156)
		(width 0.14478)
		(layer "In13.Cu")
		(net "M_H_CPU0_SB_DQ<10>")
	)
	(segment
		(start 402.37918 -282.751276)
		(end 402.37918 -282.956)
		(width 0.14478)
		(layer "In13.Cu")
		(net "M_H_CPU0_SB_DQ<10>")
	)
	(segment
		(start 404.363428 -284.665928)
		(end 404.568152 -284.665928)
		(width 0.14478)
		(layer "In13.Cu")
		(net "M_H_CPU0_SB_DQ<10>")
	)
	(segment
		(start 384.30073 -279.490678)
		(end 384.323082 -279.407366)
		(width 0.0889)
		(layer "In13.Cu")
		(net "M_H_CPU0_SB_DQ<10>")
	)
	(segment
		(start 401.244308 -281.546808)
		(end 401.449032 -281.546808)
		(width 0.14478)
		(layer "In13.Cu")
		(net "M_H_CPU0_SB_DQ<10>")
	)
	(segment
		(start 407.872438 -287.970214)
		(end 407.872438 -288.174938)
		(width 0.14478)
		(layer "In13.Cu")
		(net "M_H_CPU0_SB_DQ<10>")
	)
	(segment
		(start 406.27808 -286.8549)
		(end 406.463246 -287.040066)
		(width 0.14478)
		(layer "In13.Cu")
		(net "M_H_CPU0_SB_DQ<10>")
	)
	(segment
		(start 389.90778 -279.433528)
		(end 389.916162 -279.428702)
		(width 0.0889)
		(layer "In13.Cu")
		(net "M_H_CPU0_SB_DQ<10>")
	)
	(segment
		(start 403.93874 -284.310836)
		(end 403.93874 -284.51556)
		(width 0.14478)
		(layer "In13.Cu")
		(net "M_H_CPU0_SB_DQ<10>")
	)
	(segment
		(start 400.074638 -280.172414)
		(end 400.074638 -280.377138)
		(width 0.14478)
		(layer "In13.Cu")
		(net "M_H_CPU0_SB_DQ<10>")
	)
	(segment
		(start 406.463246 -287.040066)
		(end 406.66797 -287.040066)
		(width 0.14478)
		(layer "In13.Cu")
		(net "M_H_CPU0_SB_DQ<10>")
	)
	(segment
		(start 407.243026 -287.819846)
		(end 407.44775 -287.819846)
		(width 0.14478)
		(layer "In13.Cu")
		(net "M_H_CPU0_SB_DQ<10>")
	)
	(segment
		(start 405.347932 -285.445708)
		(end 405.533098 -285.630874)
		(width 0.14478)
		(layer "In13.Cu")
		(net "M_H_CPU0_SB_DQ<10>")
	)
	(segment
		(start 410.906976 -291.953696)
		(end 411.1117 -291.953696)
		(width 0.14478)
		(layer "In13.Cu")
		(net "M_H_CPU0_SB_DQ<10>")
	)
	(segment
		(start 403.583648 -283.886148)
		(end 403.788372 -283.886148)
		(width 0.14478)
		(layer "In13.Cu")
		(net "M_H_CPU0_SB_DQ<10>")
	)
	(segment
		(start 409.431998 -289.529774)
		(end 409.431998 -289.734498)
		(width 0.14478)
		(layer "In13.Cu")
		(net "M_H_CPU0_SB_DQ<10>")
	)
	(segment
		(start 410.127196 -291.173916)
		(end 410.33192 -291.173916)
		(width 0.14478)
		(layer "In13.Cu")
		(net "M_H_CPU0_SB_DQ<10>")
	)
	(segment
		(start 409.94203 -290.784026)
		(end 409.94203 -290.98875)
		(width 0.14478)
		(layer "In13.Cu")
		(net "M_H_CPU0_SB_DQ<10>")
	)
	(segment
		(start 392.161776 -279.433528)
		(end 392.17219 -279.439624)
		(width 0.0889)
		(layer "In13.Cu")
		(net "M_H_CPU0_SB_DQ<10>")
	)
	(segment
		(start 408.022806 -288.599626)
		(end 408.22753 -288.599626)
		(width 0.14478)
		(layer "In13.Cu")
		(net "M_H_CPU0_SB_DQ<10>")
	)
	(segment
		(start 400.464528 -280.767028)
		(end 400.669252 -280.767028)
		(width 0.14478)
		(layer "In13.Cu")
		(net "M_H_CPU0_SB_DQ<10>")
	)
	(segment
		(start 402.37918 -282.956)
		(end 402.564346 -283.141166)
		(width 0.14478)
		(layer "In13.Cu")
		(net "M_H_CPU0_SB_DQ<10>")
	)
	(segment
		(start 407.05786 -287.429956)
		(end 407.05786 -287.63468)
		(width 0.14478)
		(layer "In13.Cu")
		(net "M_H_CPU0_SB_DQ<10>")
	)
	(segment
		(start 410.211778 -290.514278)
		(end 409.94203 -290.784026)
		(width 0.14478)
		(layer "In13.Cu")
		(net "M_H_CPU0_SB_DQ<10>")
	)
	(segment
		(start 404.903686 -285.480506)
		(end 405.10841 -285.480506)
		(width 0.14478)
		(layer "In13.Cu")
		(net "M_H_CPU0_SB_DQ<10>")
	)
	(segment
		(start 408.61742 -289.19424)
		(end 408.802586 -289.379406)
		(width 0.14478)
		(layer "In13.Cu")
		(net "M_H_CPU0_SB_DQ<10>")
	)
	(segment
		(start 408.652218 -288.749994)
		(end 408.652218 -288.954718)
		(width 0.14478)
		(layer "In13.Cu")
		(net "M_H_CPU0_SB_DQ<10>")
	)
	(segment
		(start 401.5994 -281.971496)
		(end 401.5994 -282.17622)
		(width 0.14478)
		(layer "In13.Cu")
		(net "M_H_CPU0_SB_DQ<10>")
	)
	(segment
		(start 405.922988 -286.225488)
		(end 406.127712 -286.225488)
		(width 0.14478)
		(layer "In13.Cu")
		(net "M_H_CPU0_SB_DQ<10>")
	)
	(segment
		(start 410.211778 -290.309554)
		(end 410.211778 -290.514278)
		(width 0.14478)
		(layer "In13.Cu")
		(net "M_H_CPU0_SB_DQ<10>")
	)
	(segment
		(start 407.687272 -287.785048)
		(end 407.872438 -287.970214)
		(width 0.14478)
		(layer "In13.Cu")
		(net "M_H_CPU0_SB_DQ<10>")
	)
	(segment
		(start 408.467052 -288.564828)
		(end 408.652218 -288.749994)
		(width 0.14478)
		(layer "In13.Cu")
		(net "M_H_CPU0_SB_DQ<10>")
	)
	(segment
		(start 395.862556 -279.065736)
		(end 398.96796 -279.065736)
		(width 0.14478)
		(layer "In13.Cu")
		(net "M_H_CPU0_SB_DQ<10>")
	)
	(segment
		(start 388.393432 -279.428702)
		(end 388.401814 -279.433528)
		(width 0.0889)
		(layer "In13.Cu")
		(net "M_H_CPU0_SB_DQ<10>")
	)
	(segment
		(start 413.35452 -292.11016)
		(end 414.090104 -292.11016)
		(width 0.14478)
		(layer "In13.Cu")
		(net "M_H_CPU0_SB_DQ<10>")
	)
	(segment
		(start 402.413978 -282.511754)
		(end 402.413978 -282.716478)
		(width 0.14478)
		(layer "In13.Cu")
		(net "M_H_CPU0_SB_DQ<10>")
	)
	(segment
		(start 400.225006 -280.801826)
		(end 400.42973 -280.801826)
		(width 0.14478)
		(layer "In13.Cu")
		(net "M_H_CPU0_SB_DQ<10>")
	)
	(segment
		(start 408.61742 -288.989516)
		(end 408.61742 -289.19424)
		(width 0.14478)
		(layer "In13.Cu")
		(net "M_H_CPU0_SB_DQ<10>")
	)
	(segment
		(start 412.012384 -292.11016)
		(end 412.502858 -292.11016)
		(width 0.14478)
		(layer "In13.Cu")
		(net "M_H_CPU0_SB_DQ<10>")
	)
	(segment
		(start 413.054292 -291.809932)
		(end 413.35452 -292.11016)
		(width 0.14478)
		(layer "In13.Cu")
		(net "M_H_CPU0_SB_DQ<10>")
	)
	(segment
		(start 410.991558 -291.294058)
		(end 410.72181 -291.563806)
		(width 0.14478)
		(layer "In13.Cu")
		(net "M_H_CPU0_SB_DQ<10>")
	)
	(segment
		(start 403.973538 -284.071314)
		(end 403.973538 -284.276038)
		(width 0.14478)
		(layer "In13.Cu")
		(net "M_H_CPU0_SB_DQ<10>")
	)
	(segment
		(start 401.98929 -282.361386)
		(end 402.024088 -282.326588)
		(width 0.14478)
		(layer "In13.Cu")
		(net "M_H_CPU0_SB_DQ<10>")
	)
	(segment
		(start 410.601668 -290.904168)
		(end 410.806392 -290.904168)
		(width 0.14478)
		(layer "In13.Cu")
		(net "M_H_CPU0_SB_DQ<10>")
	)
	(segment
		(start 395.235938 -278.91359)
		(end 395.388084 -279.065736)
		(width 0.0889)
		(layer "In13.Cu")
		(net "M_H_CPU0_SB_DQ<10>")
	)
	(segment
		(start 400.81962 -281.39644)
		(end 401.004786 -281.581606)
		(width 0.14478)
		(layer "In13.Cu")
		(net "M_H_CPU0_SB_DQ<10>")
	)
	(segment
		(start 403.193758 -283.291534)
		(end 403.193758 -283.496258)
		(width 0.14478)
		(layer "In13.Cu")
		(net "M_H_CPU0_SB_DQ<10>")
	)
	(segment
		(start 384.454908 -279.756108)
		(end 384.30073 -279.490678)
		(width 0.0889)
		(layer "In13.Cu")
		(net "M_H_CPU0_SB_DQ<10>")
	)
	(segment
		(start 389.333486 -279.428702)
		(end 389.341868 -279.433528)
		(width 0.0889)
		(layer "In13.Cu")
		(net "M_H_CPU0_SB_DQ<10>")
	)
	(segment
		(start 400.81962 -281.191716)
		(end 400.81962 -281.39644)
		(width 0.14478)
		(layer "In13.Cu")
		(net "M_H_CPU0_SB_DQ<10>")
	)
	(segment
		(start 403.93874 -284.51556)
		(end 404.123906 -284.700726)
		(width 0.14478)
		(layer "In13.Cu")
		(net "M_H_CPU0_SB_DQ<10>")
	)
	(segment
		(start 403.008592 -283.106368)
		(end 403.193758 -283.291534)
		(width 0.14478)
		(layer "In13.Cu")
		(net "M_H_CPU0_SB_DQ<10>")
	)
	(segment
		(start 398.96796 -279.065736)
		(end 399.294858 -279.392634)
		(width 0.14478)
		(layer "In13.Cu")
		(net "M_H_CPU0_SB_DQ<10>")
	)
	(segment
		(start 404.32863 -284.700726)
		(end 404.363428 -284.665928)
		(width 0.14478)
		(layer "In13.Cu")
		(net "M_H_CPU0_SB_DQ<10>")
	)
	(segment
		(start 406.127712 -286.225488)
		(end 406.312878 -286.410654)
		(width 0.14478)
		(layer "In13.Cu")
		(net "M_H_CPU0_SB_DQ<10>")
	)
	(segment
		(start 412.502858 -292.11016)
		(end 412.803086 -291.809932)
		(width 0.14478)
		(layer "In13.Cu")
		(net "M_H_CPU0_SB_DQ<10>")
	)
	(segment
		(start 409.16225 -290.20897)
		(end 409.347416 -290.394136)
		(width 0.14478)
		(layer "In13.Cu")
		(net "M_H_CPU0_SB_DQ<10>")
	)
	(segment
		(start 392.727434 -279.433528)
		(end 392.735816 -279.428702)
		(width 0.0889)
		(layer "In13.Cu")
		(net "M_H_CPU0_SB_DQ<10>")
	)
	(segment
		(start 402.76907 -283.141166)
		(end 402.803868 -283.106368)
		(width 0.14478)
		(layer "In13.Cu")
		(net "M_H_CPU0_SB_DQ<10>")
	)
	(segment
		(start 385.207764 -279.433528)
		(end 385.216146 -279.428702)
		(width 0.0889)
		(layer "In13.Cu")
		(net "M_H_CPU0_SB_DQ<10>")
	)
	(segment
		(start 402.413978 -282.716478)
		(end 402.37918 -282.751276)
		(width 0.14478)
		(layer "In13.Cu")
		(net "M_H_CPU0_SB_DQ<10>")
	)
	(segment
		(start 400.074638 -280.377138)
		(end 400.03984 -280.411936)
		(width 0.14478)
		(layer "In13.Cu")
		(net "M_H_CPU0_SB_DQ<10>")
	)
	(segment
		(start 414.090104 -292.11016)
		(end 414.940242 -291.260022)
		(width 0.14478)
		(layer "In13.Cu")
		(net "M_H_CPU0_SB_DQ<10>")
	)
	(segment
		(start 410.33192 -291.173916)
		(end 410.601668 -290.904168)
		(width 0.14478)
		(layer "In13.Cu")
		(net "M_H_CPU0_SB_DQ<10>")
	)
	(segment
		(start 395.388084 -279.065736)
		(end 395.862556 -279.065736)
		(width 0.0889)
		(layer "In13.Cu")
		(net "M_H_CPU0_SB_DQ<10>")
	)
	(segment
		(start 402.228812 -282.326588)
		(end 402.413978 -282.511754)
		(width 0.14478)
		(layer "In13.Cu")
		(net "M_H_CPU0_SB_DQ<10>")
	)
	(segment
		(start 406.66797 -287.040066)
		(end 406.702768 -287.005268)
		(width 0.14478)
		(layer "In13.Cu")
		(net "M_H_CPU0_SB_DQ<10>")
	)
	(segment
		(start 402.803868 -283.106368)
		(end 403.008592 -283.106368)
		(width 0.14478)
		(layer "In13.Cu")
		(net "M_H_CPU0_SB_DQ<10>")
	)
	(segment
		(start 405.143208 -285.445708)
		(end 405.347932 -285.445708)
		(width 0.14478)
		(layer "In13.Cu")
		(net "M_H_CPU0_SB_DQ<10>")
	)
	(segment
		(start 399.684748 -279.987248)
		(end 399.889472 -279.987248)
		(width 0.14478)
		(layer "In13.Cu")
		(net "M_H_CPU0_SB_DQ<10>")
	)
	(segment
		(start 409.16225 -290.004246)
		(end 409.16225 -290.20897)
		(width 0.14478)
		(layer "In13.Cu")
		(net "M_H_CPU0_SB_DQ<10>")
	)
	(segment
		(start 418.510212 -292.049708)
		(end 419.547294 -292.049708)
		(width 0.14478)
		(layer "In13.Cu")
		(net "M_H_CPU0_SB_DQ<10>")
	)
	(segment
		(start 401.634198 -281.936698)
		(end 401.5994 -281.971496)
		(width 0.14478)
		(layer "In13.Cu")
		(net "M_H_CPU0_SB_DQ<10>")
	)
	(segment
		(start 399.889472 -279.987248)
		(end 400.074638 -280.172414)
		(width 0.14478)
		(layer "In13.Cu")
		(net "M_H_CPU0_SB_DQ<10>")
	)
	(segment
		(start 400.669252 -280.767028)
		(end 400.854418 -280.952194)
		(width 0.14478)
		(layer "In13.Cu")
		(net "M_H_CPU0_SB_DQ<10>")
	)
	(segment
		(start 410.026612 -290.124388)
		(end 410.211778 -290.309554)
		(width 0.14478)
		(layer "In13.Cu")
		(net "M_H_CPU0_SB_DQ<10>")
	)
	(segment
		(start 393.805918 -279.442164)
		(end 394.299948 -278.951436)
		(width 0.0889)
		(layer "In13.Cu")
		(net "M_H_CPU0_SB_DQ<10>")
	)
	(segment
		(start 407.83764 -288.209736)
		(end 407.83764 -288.41446)
		(width 0.14478)
		(layer "In13.Cu")
		(net "M_H_CPU0_SB_DQ<10>")
	)
	(segment
		(start 410.72181 -291.76853)
		(end 410.906976 -291.953696)
		(width 0.14478)
		(layer "In13.Cu")
		(net "M_H_CPU0_SB_DQ<10>")
	)
	(segment
		(start 403.15896 -283.73578)
		(end 403.344126 -283.920946)
		(width 0.14478)
		(layer "In13.Cu")
		(net "M_H_CPU0_SB_DQ<10>")
	)
	(segment
		(start 400.03984 -280.411936)
		(end 400.03984 -280.61666)
		(width 0.14478)
		(layer "In13.Cu")
		(net "M_H_CPU0_SB_DQ<10>")
	)
	(segment
		(start 400.03984 -280.61666)
		(end 400.225006 -280.801826)
		(width 0.14478)
		(layer "In13.Cu")
		(net "M_H_CPU0_SB_DQ<10>")
	)
	(segment
		(start 405.88819 -286.260286)
		(end 405.922988 -286.225488)
		(width 0.14478)
		(layer "In13.Cu")
		(net "M_H_CPU0_SB_DQ<10>")
	)
	(segment
		(start 399.294858 -279.392634)
		(end 399.294858 -279.597358)
		(width 0.14478)
		(layer "In13.Cu")
		(net "M_H_CPU0_SB_DQ<10>")
	)
	(segment
		(start 406.27808 -286.650176)
		(end 406.27808 -286.8549)
		(width 0.14478)
		(layer "In13.Cu")
		(net "M_H_CPU0_SB_DQ<10>")
	)
	(segment
		(start 408.262328 -288.564828)
		(end 408.467052 -288.564828)
		(width 0.14478)
		(layer "In13.Cu")
		(net "M_H_CPU0_SB_DQ<10>")
	)
	(segment
		(start 384.63347 -279.428702)
		(end 384.641852 -279.433528)
		(width 0.0889)
		(layer "In13.Cu")
		(net "M_H_CPU0_SB_DQ<10>")
	)
	(segment
		(start 406.312878 -286.410654)
		(end 406.312878 -286.615378)
		(width 0.14478)
		(layer "In13.Cu")
		(net "M_H_CPU0_SB_DQ<10>")
	)
	(segment
		(start 409.94203 -290.98875)
		(end 410.127196 -291.173916)
		(width 0.14478)
		(layer "In13.Cu")
		(net "M_H_CPU0_SB_DQ<10>")
	)
	(segment
		(start 400.854418 -281.156918)
		(end 400.81962 -281.191716)
		(width 0.14478)
		(layer "In13.Cu")
		(net "M_H_CPU0_SB_DQ<10>")
	)
	(segment
		(start 401.20951 -281.581606)
		(end 401.244308 -281.546808)
		(width 0.14478)
		(layer "In13.Cu")
		(net "M_H_CPU0_SB_DQ<10>")
	)
	(segment
		(start 392.153394 -279.428702)
		(end 392.161776 -279.433528)
		(width 0.0889)
		(layer "In13.Cu")
		(net "M_H_CPU0_SB_DQ<10>")
	)
	(segment
		(start 404.123906 -284.700726)
		(end 404.32863 -284.700726)
		(width 0.14478)
		(layer "In13.Cu")
		(net "M_H_CPU0_SB_DQ<10>")
	)
	(segment
		(start 406.702768 -287.005268)
		(end 406.907492 -287.005268)
		(width 0.14478)
		(layer "In13.Cu")
		(net "M_H_CPU0_SB_DQ<10>")
	)
	(segment
		(start 400.42973 -280.801826)
		(end 400.464528 -280.767028)
		(width 0.14478)
		(layer "In13.Cu")
		(net "M_H_CPU0_SB_DQ<10>")
	)
	(segment
		(start 408.652218 -288.954718)
		(end 408.61742 -288.989516)
		(width 0.14478)
		(layer "In13.Cu")
		(net "M_H_CPU0_SB_DQ<10>")
	)
	(segment
		(start 407.092658 -287.190434)
		(end 407.092658 -287.395158)
		(width 0.14478)
		(layer "In13.Cu")
		(net "M_H_CPU0_SB_DQ<10>")
	)
	(segment
		(start 409.55214 -290.394136)
		(end 409.821888 -290.124388)
		(width 0.14478)
		(layer "In13.Cu")
		(net "M_H_CPU0_SB_DQ<10>")
	)
	(segment
		(start 401.784566 -282.361386)
		(end 401.98929 -282.361386)
		(width 0.14478)
		(layer "In13.Cu")
		(net "M_H_CPU0_SB_DQ<10>")
	)
	(segment
		(start 401.634198 -281.731974)
		(end 401.634198 -281.936698)
		(width 0.14478)
		(layer "In13.Cu")
		(net "M_H_CPU0_SB_DQ<10>")
	)
	(segment
		(start 405.533098 -285.630874)
		(end 405.533098 -285.835598)
		(width 0.14478)
		(layer "In13.Cu")
		(net "M_H_CPU0_SB_DQ<10>")
	)
	(segment
		(start 409.347416 -290.394136)
		(end 409.55214 -290.394136)
		(width 0.14478)
		(layer "In13.Cu")
		(net "M_H_CPU0_SB_DQ<10>")
	)
	(segment
		(start 401.449032 -281.546808)
		(end 401.634198 -281.731974)
		(width 0.14478)
		(layer "In13.Cu")
		(net "M_H_CPU0_SB_DQ<10>")
	)
	(segment
		(start 409.042108 -289.344608)
		(end 409.246832 -289.344608)
		(width 0.14478)
		(layer "In13.Cu")
		(net "M_H_CPU0_SB_DQ<10>")
	)
	(segment
		(start 409.431998 -289.734498)
		(end 409.16225 -290.004246)
		(width 0.14478)
		(layer "In13.Cu")
		(net "M_H_CPU0_SB_DQ<10>")
	)
	(segment
		(start 406.312878 -286.615378)
		(end 406.27808 -286.650176)
		(width 0.14478)
		(layer "In13.Cu")
		(net "M_H_CPU0_SB_DQ<10>")
	)
	(segment
		(start 403.193758 -283.496258)
		(end 403.15896 -283.531056)
		(width 0.14478)
		(layer "In13.Cu")
		(net "M_H_CPU0_SB_DQ<10>")
	)
	(segment
		(start 399.445226 -280.022046)
		(end 399.64995 -280.022046)
		(width 0.14478)
		(layer "In13.Cu")
		(net "M_H_CPU0_SB_DQ<10>")
	)
	(segment
		(start 409.00731 -289.379406)
		(end 409.042108 -289.344608)
		(width 0.14478)
		(layer "In13.Cu")
		(net "M_H_CPU0_SB_DQ<10>")
	)
	(segment
		(start 403.344126 -283.920946)
		(end 403.54885 -283.920946)
		(width 0.14478)
		(layer "In13.Cu")
		(net "M_H_CPU0_SB_DQ<10>")
	)
	(segment
		(start 417.720526 -291.260022)
		(end 418.510212 -292.049708)
		(width 0.14478)
		(layer "In13.Cu")
		(net "M_H_CPU0_SB_DQ<10>")
	)
	(segment
		(start 403.788372 -283.886148)
		(end 403.973538 -284.071314)
		(width 0.14478)
		(layer "In13.Cu")
		(net "M_H_CPU0_SB_DQ<10>")
	)
	(segment
		(start 404.71852 -285.29534)
		(end 404.903686 -285.480506)
		(width 0.14478)
		(layer "In13.Cu")
		(net "M_H_CPU0_SB_DQ<10>")
	)
	(segment
		(start 405.4983 -285.870396)
		(end 405.4983 -286.07512)
		(width 0.14478)
		(layer "In13.Cu")
		(net "M_H_CPU0_SB_DQ<10>")
	)
	(segment
		(start 404.753318 -284.851094)
		(end 404.753318 -285.055818)
		(width 0.14478)
		(layer "In13.Cu")
		(net "M_H_CPU0_SB_DQ<10>")
	)
	(segment
		(start 401.5994 -282.17622)
		(end 401.784566 -282.361386)
		(width 0.14478)
		(layer "In13.Cu")
		(net "M_H_CPU0_SB_DQ<10>")
	)
	(segment
		(start 394.391388 -278.91359)
		(end 395.235938 -278.91359)
		(width 0.0889)
		(layer "In13.Cu")
		(net "M_H_CPU0_SB_DQ<10>")
	)
	(segment
		(start 404.753318 -285.055818)
		(end 404.71852 -285.090616)
		(width 0.14478)
		(layer "In13.Cu")
		(net "M_H_CPU0_SB_DQ<10>")
	)
	(segment
		(start 404.568152 -284.665928)
		(end 404.753318 -284.851094)
		(width 0.14478)
		(layer "In13.Cu")
		(net "M_H_CPU0_SB_DQ<10>")
	)
	(segment
		(start 408.22753 -288.599626)
		(end 408.262328 -288.564828)
		(width 0.14478)
		(layer "In13.Cu")
		(net "M_H_CPU0_SB_DQ<10>")
	)
	(segment
		(start 410.72181 -291.563806)
		(end 410.72181 -291.76853)
		(width 0.14478)
		(layer "In13.Cu")
		(net "M_H_CPU0_SB_DQ<10>")
	)
	(segment
		(start 399.26006 -279.83688)
		(end 399.445226 -280.022046)
		(width 0.14478)
		(layer "In13.Cu")
		(net "M_H_CPU0_SB_DQ<10>")
	)
	(segment
		(start 409.246832 -289.344608)
		(end 409.431998 -289.529774)
		(width 0.14478)
		(layer "In13.Cu")
		(net "M_H_CPU0_SB_DQ<10>")
	)
	(segment
		(start 410.991558 -291.089334)
		(end 410.991558 -291.294058)
		(width 0.14478)
		(layer "In13.Cu")
		(net "M_H_CPU0_SB_DQ<10>")
	)
	(segment
		(start 414.940242 -291.260022)
		(end 417.720526 -291.260022)
		(width 0.14478)
		(layer "In13.Cu")
		(net "M_H_CPU0_SB_DQ<10>")
	)
	(segment
		(start 403.54885 -283.920946)
		(end 403.583648 -283.886148)
		(width 0.14478)
		(layer "In13.Cu")
		(net "M_H_CPU0_SB_DQ<10>")
	)
	(segment
		(start 407.05786 -287.63468)
		(end 407.243026 -287.819846)
		(width 0.14478)
		(layer "In13.Cu")
		(net "M_H_CPU0_SB_DQ<10>")
	)
	(segment
		(start 411.381448 -291.683948)
		(end 411.586172 -291.683948)
		(width 0.14478)
		(layer "In13.Cu")
		(net "M_H_CPU0_SB_DQ<10>")
	)
	(segment
		(start 419.547294 -292.049708)
		(end 419.912038 -291.684964)
		(width 0.14478)
		(layer "In13.Cu")
		(net "M_H_CPU0_SB_DQ<10>")
	)
	(segment
		(start 407.83764 -288.41446)
		(end 408.022806 -288.599626)
		(width 0.14478)
		(layer "In13.Cu")
		(net "M_H_CPU0_SB_DQ<10>")
	)
	(segment
		(start 412.803086 -291.809932)
		(end 413.054292 -291.809932)
		(width 0.14478)
		(layer "In13.Cu")
		(net "M_H_CPU0_SB_DQ<10>")
	)
	(segment
		(start 409.821888 -290.124388)
		(end 410.026612 -290.124388)
		(width 0.14478)
		(layer "In13.Cu")
		(net "M_H_CPU0_SB_DQ<10>")
	)
	(segment
		(start 408.802586 -289.379406)
		(end 409.00731 -289.379406)
		(width 0.14478)
		(layer "In13.Cu")
		(net "M_H_CPU0_SB_DQ<10>")
	)
	(segment
		(start 407.872438 -288.174938)
		(end 407.83764 -288.209736)
		(width 0.14478)
		(layer "In13.Cu")
		(net "M_H_CPU0_SB_DQ<10>")
	)
	(segment
		(start 410.806392 -290.904168)
		(end 410.991558 -291.089334)
		(width 0.14478)
		(layer "In13.Cu")
		(net "M_H_CPU0_SB_DQ<10>")
	)
	(segment
		(start 403.15896 -283.531056)
		(end 403.15896 -283.73578)
		(width 0.14478)
		(layer "In13.Cu")
		(net "M_H_CPU0_SB_DQ<10>")
	)
	(segment
		(start 406.907492 -287.005268)
		(end 407.092658 -287.190434)
		(width 0.14478)
		(layer "In13.Cu")
		(net "M_H_CPU0_SB_DQ<10>")
	)
	(segment
		(start 407.092658 -287.395158)
		(end 407.05786 -287.429956)
		(width 0.14478)
		(layer "In13.Cu")
		(net "M_H_CPU0_SB_DQ<10>")
	)
	(segment
		(start 399.64995 -280.022046)
		(end 399.684748 -279.987248)
		(width 0.14478)
		(layer "In13.Cu")
		(net "M_H_CPU0_SB_DQ<10>")
	)
	(segment
		(start 405.533098 -285.835598)
		(end 405.4983 -285.870396)
		(width 0.14478)
		(layer "In13.Cu")
		(net "M_H_CPU0_SB_DQ<10>")
	)
	(segment
		(start 401.004786 -281.581606)
		(end 401.20951 -281.581606)
		(width 0.14478)
		(layer "In13.Cu")
		(net "M_H_CPU0_SB_DQ<10>")
	)
	(arc
		(start 390.847834 -279.433528)
		(mid 391.034778 -279.383273)
		(end 391.221722 -279.433528)
		(width 0.0889)
		(layer "In13.Cu")
		(net "M_H_CPU0_SB_DQ<10>")
	)
	(arc
		(start 389.916162 -279.428702)
		(mid 390.09967 -279.383208)
		(end 390.281922 -279.433528)
		(width 0.0889)
		(layer "In13.Cu")
		(net "M_H_CPU0_SB_DQ<10>")
	)
	(arc
		(start 388.027672 -279.433528)
		(mid 388.209923 -279.383178)
		(end 388.393432 -279.428702)
		(width 0.0889)
		(layer "In13.Cu")
		(net "M_H_CPU0_SB_DQ<10>")
	)
	(arc
		(start 386.1562 -279.428702)
		(mid 386.339708 -279.383208)
		(end 386.52196 -279.433528)
		(width 0.0889)
		(layer "In13.Cu")
		(net "M_H_CPU0_SB_DQ<10>")
	)
	(arc
		(start 387.46176 -279.433528)
		(mid 387.744716 -279.509705)
		(end 388.027672 -279.433528)
		(width 0.0889)
		(layer "In13.Cu")
		(net "M_H_CPU0_SB_DQ<10>")
	)
	(arc
		(start 392.17219 -279.439624)
		(mid 392.450622 -279.509722)
		(end 392.727434 -279.433528)
		(width 0.0889)
		(layer "In13.Cu")
		(net "M_H_CPU0_SB_DQ<10>")
	)
	(arc
		(start 388.401814 -279.433528)
		(mid 388.68477 -279.509705)
		(end 388.967726 -279.433528)
		(width 0.0889)
		(layer "In13.Cu")
		(net "M_H_CPU0_SB_DQ<10>")
	)
	(arc
		(start 391.221722 -279.433528)
		(mid 391.504678 -279.509705)
		(end 391.787634 -279.433528)
		(width 0.0889)
		(layer "In13.Cu")
		(net "M_H_CPU0_SB_DQ<10>")
	)
	(arc
		(start 389.341868 -279.433528)
		(mid 389.624824 -279.509705)
		(end 389.90778 -279.433528)
		(width 0.0889)
		(layer "In13.Cu")
		(net "M_H_CPU0_SB_DQ<10>")
	)
	(arc
		(start 392.735816 -279.428702)
		(mid 392.919324 -279.383208)
		(end 393.101576 -279.433528)
		(width 0.0889)
		(layer "In13.Cu")
		(net "M_H_CPU0_SB_DQ<10>")
	)
	(arc
		(start 393.101576 -279.433528)
		(mid 393.376028 -279.509764)
		(end 393.652756 -279.442164)
		(width 0.0889)
		(layer "In13.Cu")
		(net "M_H_CPU0_SB_DQ<10>")
	)
	(arc
		(start 384.641852 -279.433528)
		(mid 384.924808 -279.509705)
		(end 385.207764 -279.433528)
		(width 0.0889)
		(layer "In13.Cu")
		(net "M_H_CPU0_SB_DQ<10>")
	)
	(arc
		(start 386.52196 -279.433528)
		(mid 386.804916 -279.509705)
		(end 387.087872 -279.433528)
		(width 0.0889)
		(layer "In13.Cu")
		(net "M_H_CPU0_SB_DQ<10>")
	)
	(arc
		(start 385.581906 -279.433528)
		(mid 385.864862 -279.509705)
		(end 386.147818 -279.433528)
		(width 0.0889)
		(layer "In13.Cu")
		(net "M_H_CPU0_SB_DQ<10>")
	)
	(arc
		(start 387.087872 -279.433528)
		(mid 387.274816 -279.383273)
		(end 387.46176 -279.433528)
		(width 0.0889)
		(layer "In13.Cu")
		(net "M_H_CPU0_SB_DQ<10>")
	)
	(arc
		(start 384.323082 -279.407366)
		(mid 384.480592 -279.384168)
		(end 384.63347 -279.428702)
		(width 0.0889)
		(layer "In13.Cu")
		(net "M_H_CPU0_SB_DQ<10>")
	)
	(arc
		(start 394.299948 -278.951436)
		(mid 394.341901 -278.923404)
		(end 394.391388 -278.91359)
		(width 0.0889)
		(layer "In13.Cu")
		(net "M_H_CPU0_SB_DQ<10>")
	)
	(arc
		(start 385.216146 -279.428702)
		(mid 385.399654 -279.383208)
		(end 385.581906 -279.433528)
		(width 0.0889)
		(layer "In13.Cu")
		(net "M_H_CPU0_SB_DQ<10>")
	)
	(arc
		(start 388.967726 -279.433528)
		(mid 389.149977 -279.383178)
		(end 389.333486 -279.428702)
		(width 0.0889)
		(layer "In13.Cu")
		(net "M_H_CPU0_SB_DQ<10>")
	)
	(arc
		(start 391.787634 -279.433528)
		(mid 391.969885 -279.383178)
		(end 392.153394 -279.428702)
		(width 0.0889)
		(layer "In13.Cu")
		(net "M_H_CPU0_SB_DQ<10>")
	)
	(arc
		(start 390.281922 -279.433528)
		(mid 390.564878 -279.509705)
		(end 390.847834 -279.433528)
		(width 0.0889)
		(layer "In13.Cu")
		(net "M_H_CPU0_SB_DQ<10>")
	)
	(segment
		(start 383.517902 -273.820128)
		(end 383.984754 -274.086066)
		(width 0.10668)
		(layer "F.Cu")
		(net "M_H_CPU0_SB_DQ<0>")
	)
	(segment
		(start 418.907468 -281.910028)
		(end 418.057584 -281.060144)
		(width 0.14478)
		(layer "In13.Cu")
		(net "M_H_CPU0_SB_DQ<0>")
	)
	(segment
		(start 386.051806 -274.408646)
		(end 386.043424 -274.413472)
		(width 0.0889)
		(layer "In13.Cu")
		(net "M_H_CPU0_SB_DQ<0>")
	)
	(segment
		(start 418.057584 -281.060144)
		(end 415.621724 -281.060144)
		(width 0.14478)
		(layer "In13.Cu")
		(net "M_H_CPU0_SB_DQ<0>")
	)
	(segment
		(start 395.108684 -273.39417)
		(end 394.657326 -273.39417)
		(width 0.0889)
		(layer "In13.Cu")
		(net "M_H_CPU0_SB_DQ<0>")
	)
	(segment
		(start 423.284142 -281.876246)
		(end 423.139362 -282.021026)
		(width 0.14478)
		(layer "In13.Cu")
		(net "M_H_CPU0_SB_DQ<0>")
	)
	(segment
		(start 408.007058 -278.177244)
		(end 402.769324 -272.93951)
		(width 0.14478)
		(layer "In13.Cu")
		(net "M_H_CPU0_SB_DQ<0>")
	)
	(segment
		(start 390.751822 -274.408646)
		(end 390.74344 -274.413472)
		(width 0.0889)
		(layer "In13.Cu")
		(net "M_H_CPU0_SB_DQ<0>")
	)
	(segment
		(start 411.725618 -280.9367)
		(end 408.966162 -278.177244)
		(width 0.14478)
		(layer "In13.Cu")
		(net "M_H_CPU0_SB_DQ<0>")
	)
	(segment
		(start 413.569912 -281.910028)
		(end 412.140654 -281.910028)
		(width 0.14478)
		(layer "In13.Cu")
		(net "M_H_CPU0_SB_DQ<0>")
	)
	(segment
		(start 394.657326 -273.39417)
		(end 393.646152 -274.405344)
		(width 0.0889)
		(layer "In13.Cu")
		(net "M_H_CPU0_SB_DQ<0>")
	)
	(segment
		(start 392.274552 -274.418806)
		(end 392.256264 -274.408392)
		(width 0.0889)
		(layer "In13.Cu")
		(net "M_H_CPU0_SB_DQ<0>")
	)
	(segment
		(start 420.37635 -281.910028)
		(end 418.907468 -281.910028)
		(width 0.14478)
		(layer "In13.Cu")
		(net "M_H_CPU0_SB_DQ<0>")
	)
	(segment
		(start 420.801292 -281.485086)
		(end 420.37635 -281.910028)
		(width 0.14478)
		(layer "In13.Cu")
		(net "M_H_CPU0_SB_DQ<0>")
	)
	(segment
		(start 422.588182 -281.485086)
		(end 420.801292 -281.485086)
		(width 0.14478)
		(layer "In13.Cu")
		(net "M_H_CPU0_SB_DQ<0>")
	)
	(segment
		(start 392.256264 -274.408392)
		(end 392.234674 -274.395946)
		(width 0.0889)
		(layer "In13.Cu")
		(net "M_H_CPU0_SB_DQ<0>")
	)
	(segment
		(start 393.38504 -274.4597)
		(end 393.384786 -274.459446)
		(width 0.0889)
		(layer "In13.Cu")
		(net "M_H_CPU0_SB_DQ<0>")
	)
	(segment
		(start 391.326116 -274.413472)
		(end 391.317734 -274.408646)
		(width 0.0889)
		(layer "In13.Cu")
		(net "M_H_CPU0_SB_DQ<0>")
	)
	(segment
		(start 384.235198 -274.376896)
		(end 384.138932 -274.351496)
		(width 0.0889)
		(layer "In13.Cu")
		(net "M_H_CPU0_SB_DQ<0>")
	)
	(segment
		(start 393.646152 -274.405344)
		(end 393.529566 -274.4597)
		(width 0.0889)
		(layer "In13.Cu")
		(net "M_H_CPU0_SB_DQ<0>")
	)
	(segment
		(start 402.769324 -272.93951)
		(end 395.988032 -272.93951)
		(width 0.14478)
		(layer "In13.Cu")
		(net "M_H_CPU0_SB_DQ<0>")
	)
	(segment
		(start 422.732962 -281.876246)
		(end 422.732962 -281.629866)
		(width 0.14478)
		(layer "In13.Cu")
		(net "M_H_CPU0_SB_DQ<0>")
	)
	(segment
		(start 424.012106 -281.485086)
		(end 423.428922 -281.485086)
		(width 0.14478)
		(layer "In13.Cu")
		(net "M_H_CPU0_SB_DQ<0>")
	)
	(segment
		(start 411.725618 -281.494992)
		(end 411.725618 -280.9367)
		(width 0.14478)
		(layer "In13.Cu")
		(net "M_H_CPU0_SB_DQ<0>")
	)
	(segment
		(start 422.877742 -282.021026)
		(end 422.732962 -281.876246)
		(width 0.14478)
		(layer "In13.Cu")
		(net "M_H_CPU0_SB_DQ<0>")
	)
	(segment
		(start 393.529566 -274.4597)
		(end 393.38504 -274.4597)
		(width 0.0889)
		(layer "In13.Cu")
		(net "M_H_CPU0_SB_DQ<0>")
	)
	(segment
		(start 395.988032 -272.93951)
		(end 395.563344 -272.93951)
		(width 0.0889)
		(layer "In13.Cu")
		(net "M_H_CPU0_SB_DQ<0>")
	)
	(segment
		(start 412.140654 -281.910028)
		(end 411.725618 -281.494992)
		(width 0.14478)
		(layer "In13.Cu")
		(net "M_H_CPU0_SB_DQ<0>")
	)
	(segment
		(start 423.284142 -281.629866)
		(end 423.284142 -281.876246)
		(width 0.14478)
		(layer "In13.Cu")
		(net "M_H_CPU0_SB_DQ<0>")
	)
	(segment
		(start 415.621724 -281.060144)
		(end 413.569912 -281.910028)
		(width 0.14478)
		(layer "In13.Cu")
		(net "M_H_CPU0_SB_DQ<0>")
	)
	(segment
		(start 423.139362 -282.021026)
		(end 422.877742 -282.021026)
		(width 0.14478)
		(layer "In13.Cu")
		(net "M_H_CPU0_SB_DQ<0>")
	)
	(segment
		(start 392.652758 -274.39493)
		(end 392.62939 -274.408646)
		(width 0.0889)
		(layer "In13.Cu")
		(net "M_H_CPU0_SB_DQ<0>")
	)
	(segment
		(start 386.99186 -274.408646)
		(end 386.983478 -274.413472)
		(width 0.0889)
		(layer "In13.Cu")
		(net "M_H_CPU0_SB_DQ<0>")
	)
	(segment
		(start 388.506208 -274.413472)
		(end 388.497826 -274.408646)
		(width 0.0889)
		(layer "In13.Cu")
		(net "M_H_CPU0_SB_DQ<0>")
	)
	(segment
		(start 423.428922 -281.485086)
		(end 423.284142 -281.629866)
		(width 0.14478)
		(layer "In13.Cu")
		(net "M_H_CPU0_SB_DQ<0>")
	)
	(segment
		(start 408.966162 -278.177244)
		(end 408.007058 -278.177244)
		(width 0.14478)
		(layer "In13.Cu")
		(net "M_H_CPU0_SB_DQ<0>")
	)
	(segment
		(start 395.563344 -272.93951)
		(end 395.108684 -273.39417)
		(width 0.0889)
		(layer "In13.Cu")
		(net "M_H_CPU0_SB_DQ<0>")
	)
	(segment
		(start 387.566154 -274.413472)
		(end 387.557772 -274.408646)
		(width 0.0889)
		(layer "In13.Cu")
		(net "M_H_CPU0_SB_DQ<0>")
	)
	(segment
		(start 422.732962 -281.629866)
		(end 422.588182 -281.485086)
		(width 0.14478)
		(layer "In13.Cu")
		(net "M_H_CPU0_SB_DQ<0>")
	)
	(segment
		(start 384.138932 -274.351496)
		(end 383.984754 -274.086066)
		(width 0.0889)
		(layer "In13.Cu")
		(net "M_H_CPU0_SB_DQ<0>")
	)
	(arc
		(start 388.871968 -274.408646)
		(mid 388.689717 -274.458996)
		(end 388.506208 -274.413472)
		(width 0.0889)
		(layer "In13.Cu")
		(net "M_H_CPU0_SB_DQ<0>")
	)
	(arc
		(start 389.811768 -274.408646)
		(mid 389.624824 -274.458901)
		(end 389.43788 -274.408646)
		(width 0.0889)
		(layer "In13.Cu")
		(net "M_H_CPU0_SB_DQ<0>")
	)
	(arc
		(start 385.111752 -274.408646)
		(mid 384.924808 -274.458901)
		(end 384.737864 -274.408646)
		(width 0.0889)
		(layer "In13.Cu")
		(net "M_H_CPU0_SB_DQ<0>")
	)
	(arc
		(start 387.557772 -274.408646)
		(mid 387.274816 -274.332469)
		(end 386.99186 -274.408646)
		(width 0.0889)
		(layer "In13.Cu")
		(net "M_H_CPU0_SB_DQ<0>")
	)
	(arc
		(start 390.74344 -274.413472)
		(mid 390.559932 -274.458966)
		(end 390.37768 -274.408646)
		(width 0.0889)
		(layer "In13.Cu")
		(net "M_H_CPU0_SB_DQ<0>")
	)
	(arc
		(start 393.196572 -274.408646)
		(mid 392.926415 -274.331884)
		(end 392.652758 -274.39493)
		(width 0.0889)
		(layer "In13.Cu")
		(net "M_H_CPU0_SB_DQ<0>")
	)
	(arc
		(start 386.983478 -274.413472)
		(mid 386.79997 -274.458966)
		(end 386.617718 -274.408646)
		(width 0.0889)
		(layer "In13.Cu")
		(net "M_H_CPU0_SB_DQ<0>")
	)
	(arc
		(start 384.737864 -274.408646)
		(mid 384.490268 -274.333468)
		(end 384.235198 -274.376896)
		(width 0.0889)
		(layer "In13.Cu")
		(net "M_H_CPU0_SB_DQ<0>")
	)
	(arc
		(start 393.384786 -274.459446)
		(mid 393.287298 -274.446563)
		(end 393.196572 -274.408646)
		(width 0.0889)
		(layer "In13.Cu")
		(net "M_H_CPU0_SB_DQ<0>")
	)
	(arc
		(start 386.043424 -274.413472)
		(mid 385.859916 -274.458966)
		(end 385.677664 -274.408646)
		(width 0.0889)
		(layer "In13.Cu")
		(net "M_H_CPU0_SB_DQ<0>")
	)
	(arc
		(start 392.62939 -274.408646)
		(mid 392.45327 -274.458624)
		(end 392.274552 -274.418806)
		(width 0.0889)
		(layer "In13.Cu")
		(net "M_H_CPU0_SB_DQ<0>")
	)
	(arc
		(start 388.497826 -274.408646)
		(mid 388.21487 -274.332469)
		(end 387.931914 -274.408646)
		(width 0.0889)
		(layer "In13.Cu")
		(net "M_H_CPU0_SB_DQ<0>")
	)
	(arc
		(start 387.931914 -274.408646)
		(mid 387.749663 -274.458996)
		(end 387.566154 -274.413472)
		(width 0.0889)
		(layer "In13.Cu")
		(net "M_H_CPU0_SB_DQ<0>")
	)
	(arc
		(start 392.234674 -274.395946)
		(mid 391.961645 -274.332627)
		(end 391.691876 -274.408646)
		(width 0.0889)
		(layer "In13.Cu")
		(net "M_H_CPU0_SB_DQ<0>")
	)
	(arc
		(start 386.617718 -274.408646)
		(mid 386.334762 -274.332469)
		(end 386.051806 -274.408646)
		(width 0.0889)
		(layer "In13.Cu")
		(net "M_H_CPU0_SB_DQ<0>")
	)
	(arc
		(start 391.317734 -274.408646)
		(mid 391.034778 -274.332469)
		(end 390.751822 -274.408646)
		(width 0.0889)
		(layer "In13.Cu")
		(net "M_H_CPU0_SB_DQ<0>")
	)
	(arc
		(start 391.691876 -274.408646)
		(mid 391.509625 -274.458996)
		(end 391.326116 -274.413472)
		(width 0.0889)
		(layer "In13.Cu")
		(net "M_H_CPU0_SB_DQ<0>")
	)
	(arc
		(start 390.37768 -274.408646)
		(mid 390.094724 -274.332469)
		(end 389.811768 -274.408646)
		(width 0.0889)
		(layer "In13.Cu")
		(net "M_H_CPU0_SB_DQ<0>")
	)
	(arc
		(start 385.677664 -274.408646)
		(mid 385.394708 -274.332469)
		(end 385.111752 -274.408646)
		(width 0.0889)
		(layer "In13.Cu")
		(net "M_H_CPU0_SB_DQ<0>")
	)
	(arc
		(start 389.43788 -274.408646)
		(mid 389.154924 -274.332469)
		(end 388.871968 -274.408646)
		(width 0.0889)
		(layer "In13.Cu")
		(net "M_H_CPU0_SB_DQ<0>")
	)
	(segment
		(start 383.988056 -266.530074)
		(end 384.454908 -266.796012)
		(width 0.10668)
		(layer "F.Cu")
		(net "M_H_CPU0_SB_CS_N<1>")
	)
	(segment
		(start 408.962098 -265.70305)
		(end 395.965172 -265.70305)
		(width 0.14478)
		(layer "In13.Cu")
		(net "M_H_CPU0_SB_CS_N<1>")
	)
	(segment
		(start 416.89147 -268.165326)
		(end 416.74669 -268.310106)
		(width 0.14478)
		(layer "In13.Cu")
		(net "M_H_CPU0_SB_CS_N<1>")
	)
	(segment
		(start 416.48507 -268.310106)
		(end 416.34029 -268.165326)
		(width 0.14478)
		(layer "In13.Cu")
		(net "M_H_CPU0_SB_CS_N<1>")
	)
	(segment
		(start 386.1562 -266.468606)
		(end 386.147818 -266.473432)
		(width 0.0889)
		(layer "In13.Cu")
		(net "M_H_CPU0_SB_CS_N<1>")
	)
	(segment
		(start 419.912038 -268.735048)
		(end 419.891464 -268.735048)
		(width 0.14478)
		(layer "In13.Cu")
		(net "M_H_CPU0_SB_CS_N<1>")
	)
	(segment
		(start 388.401814 -266.473432)
		(end 388.393432 -266.468606)
		(width 0.0889)
		(layer "In13.Cu")
		(net "M_H_CPU0_SB_CS_N<1>")
	)
	(segment
		(start 389.916162 -266.468606)
		(end 389.90778 -266.473432)
		(width 0.0889)
		(layer "In13.Cu")
		(net "M_H_CPU0_SB_CS_N<1>")
	)
	(segment
		(start 417.58743 -268.310106)
		(end 417.44265 -268.165326)
		(width 0.14478)
		(layer "In13.Cu")
		(net "M_H_CPU0_SB_CS_N<1>")
	)
	(segment
		(start 393.456414 -266.42441)
		(end 392.974322 -266.42441)
		(width 0.0889)
		(layer "In13.Cu")
		(net "M_H_CPU0_SB_CS_N<1>")
	)
	(segment
		(start 415.78911 -268.056614)
		(end 415.78911 -268.165326)
		(width 0.14478)
		(layer "In13.Cu")
		(net "M_H_CPU0_SB_CS_N<1>")
	)
	(segment
		(start 392.182604 -266.486132)
		(end 392.161014 -266.473686)
		(width 0.0889)
		(layer "In13.Cu")
		(net "M_H_CPU0_SB_CS_N<1>")
	)
	(segment
		(start 416.34029 -268.056614)
		(end 416.19551 -267.911834)
		(width 0.14478)
		(layer "In13.Cu")
		(net "M_H_CPU0_SB_CS_N<1>")
	)
	(segment
		(start 417.44265 -268.056614)
		(end 417.29787 -267.911834)
		(width 0.14478)
		(layer "In13.Cu")
		(net "M_H_CPU0_SB_CS_N<1>")
	)
	(segment
		(start 394.177774 -265.70305)
		(end 393.456414 -266.42441)
		(width 0.0889)
		(layer "In13.Cu")
		(net "M_H_CPU0_SB_CS_N<1>")
	)
	(segment
		(start 418.972746 -269.160244)
		(end 418.122608 -268.310106)
		(width 0.14478)
		(layer "In13.Cu")
		(net "M_H_CPU0_SB_CS_N<1>")
	)
	(segment
		(start 415.93389 -267.911834)
		(end 415.78911 -268.056614)
		(width 0.14478)
		(layer "In13.Cu")
		(net "M_H_CPU0_SB_CS_N<1>")
	)
	(segment
		(start 416.89147 -268.056614)
		(end 416.89147 -268.165326)
		(width 0.14478)
		(layer "In13.Cu")
		(net "M_H_CPU0_SB_CS_N<1>")
	)
	(segment
		(start 416.74669 -268.310106)
		(end 416.48507 -268.310106)
		(width 0.14478)
		(layer "In13.Cu")
		(net "M_H_CPU0_SB_CS_N<1>")
	)
	(segment
		(start 418.122608 -268.310106)
		(end 417.58743 -268.310106)
		(width 0.14478)
		(layer "In13.Cu")
		(net "M_H_CPU0_SB_CS_N<1>")
	)
	(segment
		(start 389.341868 -266.473432)
		(end 389.333486 -266.468606)
		(width 0.0889)
		(layer "In13.Cu")
		(net "M_H_CPU0_SB_CS_N<1>")
	)
	(segment
		(start 412.419292 -269.160244)
		(end 408.962098 -265.70305)
		(width 0.14478)
		(layer "In13.Cu")
		(net "M_H_CPU0_SB_CS_N<1>")
	)
	(segment
		(start 384.634486 -266.469114)
		(end 384.63347 -266.468606)
		(width 0.0889)
		(layer "In13.Cu")
		(net "M_H_CPU0_SB_CS_N<1>")
	)
	(segment
		(start 414.06572 -269.160244)
		(end 412.419292 -269.160244)
		(width 0.14478)
		(layer "In13.Cu")
		(net "M_H_CPU0_SB_CS_N<1>")
	)
	(segment
		(start 395.965172 -265.70305)
		(end 394.177774 -265.70305)
		(width 0.0889)
		(layer "In13.Cu")
		(net "M_H_CPU0_SB_CS_N<1>")
	)
	(segment
		(start 419.891464 -268.735048)
		(end 419.466268 -269.160244)
		(width 0.14478)
		(layer "In13.Cu")
		(net "M_H_CPU0_SB_CS_N<1>")
	)
	(segment
		(start 385.216146 -266.468606)
		(end 385.207764 -266.473432)
		(width 0.0889)
		(layer "In13.Cu")
		(net "M_H_CPU0_SB_CS_N<1>")
	)
	(segment
		(start 417.29787 -267.911834)
		(end 417.03625 -267.911834)
		(width 0.14478)
		(layer "In13.Cu")
		(net "M_H_CPU0_SB_CS_N<1>")
	)
	(segment
		(start 384.641852 -266.473432)
		(end 384.634486 -266.469114)
		(width 0.0889)
		(layer "In13.Cu")
		(net "M_H_CPU0_SB_CS_N<1>")
	)
	(segment
		(start 384.323082 -266.44727)
		(end 384.30073 -266.530582)
		(width 0.0889)
		(layer "In13.Cu")
		(net "M_H_CPU0_SB_CS_N<1>")
	)
	(segment
		(start 384.30073 -266.530582)
		(end 384.454908 -266.796012)
		(width 0.0889)
		(layer "In13.Cu")
		(net "M_H_CPU0_SB_CS_N<1>")
	)
	(segment
		(start 417.03625 -267.911834)
		(end 416.89147 -268.056614)
		(width 0.14478)
		(layer "In13.Cu")
		(net "M_H_CPU0_SB_CS_N<1>")
	)
	(segment
		(start 392.161014 -266.473686)
		(end 392.140948 -266.462256)
		(width 0.0889)
		(layer "In13.Cu")
		(net "M_H_CPU0_SB_CS_N<1>")
	)
	(segment
		(start 415.78911 -268.165326)
		(end 415.64433 -268.310106)
		(width 0.14478)
		(layer "In13.Cu")
		(net "M_H_CPU0_SB_CS_N<1>")
	)
	(segment
		(start 416.34029 -268.165326)
		(end 416.34029 -268.056614)
		(width 0.14478)
		(layer "In13.Cu")
		(net "M_H_CPU0_SB_CS_N<1>")
	)
	(segment
		(start 414.915858 -268.310106)
		(end 414.06572 -269.160244)
		(width 0.14478)
		(layer "In13.Cu")
		(net "M_H_CPU0_SB_CS_N<1>")
	)
	(segment
		(start 416.19551 -267.911834)
		(end 415.93389 -267.911834)
		(width 0.14478)
		(layer "In13.Cu")
		(net "M_H_CPU0_SB_CS_N<1>")
	)
	(segment
		(start 415.64433 -268.310106)
		(end 414.915858 -268.310106)
		(width 0.14478)
		(layer "In13.Cu")
		(net "M_H_CPU0_SB_CS_N<1>")
	)
	(segment
		(start 417.44265 -268.165326)
		(end 417.44265 -268.056614)
		(width 0.14478)
		(layer "In13.Cu")
		(net "M_H_CPU0_SB_CS_N<1>")
	)
	(segment
		(start 419.466268 -269.160244)
		(end 418.972746 -269.160244)
		(width 0.14478)
		(layer "In13.Cu")
		(net "M_H_CPU0_SB_CS_N<1>")
	)
	(arc
		(start 391.221722 -266.473432)
		(mid 391.034778 -266.423177)
		(end 390.847834 -266.473432)
		(width 0.0889)
		(layer "In13.Cu")
		(net "M_H_CPU0_SB_CS_N<1>")
	)
	(arc
		(start 390.281922 -266.473432)
		(mid 390.099671 -266.423082)
		(end 389.916162 -266.468606)
		(width 0.0889)
		(layer "In13.Cu")
		(net "M_H_CPU0_SB_CS_N<1>")
	)
	(arc
		(start 387.46176 -266.473432)
		(mid 387.274816 -266.423143)
		(end 387.087872 -266.473432)
		(width 0.0889)
		(layer "In13.Cu")
		(net "M_H_CPU0_SB_CS_N<1>")
	)
	(arc
		(start 392.974322 -266.42441)
		(mid 392.845751 -266.428072)
		(end 392.725402 -266.473432)
		(width 0.0889)
		(layer "In13.Cu")
		(net "M_H_CPU0_SB_CS_N<1>")
	)
	(arc
		(start 387.087872 -266.473432)
		(mid 386.804916 -266.549609)
		(end 386.52196 -266.473432)
		(width 0.0889)
		(layer "In13.Cu")
		(net "M_H_CPU0_SB_CS_N<1>")
	)
	(arc
		(start 388.967726 -266.473432)
		(mid 388.68477 -266.549609)
		(end 388.401814 -266.473432)
		(width 0.0889)
		(layer "In13.Cu")
		(net "M_H_CPU0_SB_CS_N<1>")
	)
	(arc
		(start 385.581906 -266.473432)
		(mid 385.399655 -266.423082)
		(end 385.216146 -266.468606)
		(width 0.0889)
		(layer "In13.Cu")
		(net "M_H_CPU0_SB_CS_N<1>")
	)
	(arc
		(start 388.393432 -266.468606)
		(mid 388.209924 -266.423112)
		(end 388.027672 -266.473432)
		(width 0.0889)
		(layer "In13.Cu")
		(net "M_H_CPU0_SB_CS_N<1>")
	)
	(arc
		(start 391.787634 -266.473432)
		(mid 391.504678 -266.549609)
		(end 391.221722 -266.473432)
		(width 0.0889)
		(layer "In13.Cu")
		(net "M_H_CPU0_SB_CS_N<1>")
	)
	(arc
		(start 386.147818 -266.473432)
		(mid 385.864862 -266.549609)
		(end 385.581906 -266.473432)
		(width 0.0889)
		(layer "In13.Cu")
		(net "M_H_CPU0_SB_CS_N<1>")
	)
	(arc
		(start 392.725402 -266.473432)
		(mid 392.455633 -266.549455)
		(end 392.182604 -266.486132)
		(width 0.0889)
		(layer "In13.Cu")
		(net "M_H_CPU0_SB_CS_N<1>")
	)
	(arc
		(start 386.52196 -266.473432)
		(mid 386.339709 -266.423082)
		(end 386.1562 -266.468606)
		(width 0.0889)
		(layer "In13.Cu")
		(net "M_H_CPU0_SB_CS_N<1>")
	)
	(arc
		(start 389.90778 -266.473432)
		(mid 389.624824 -266.549609)
		(end 389.341868 -266.473432)
		(width 0.0889)
		(layer "In13.Cu")
		(net "M_H_CPU0_SB_CS_N<1>")
	)
	(arc
		(start 388.027672 -266.473432)
		(mid 387.744716 -266.549609)
		(end 387.46176 -266.473432)
		(width 0.0889)
		(layer "In13.Cu")
		(net "M_H_CPU0_SB_CS_N<1>")
	)
	(arc
		(start 390.847834 -266.473432)
		(mid 390.564878 -266.549609)
		(end 390.281922 -266.473432)
		(width 0.0889)
		(layer "In13.Cu")
		(net "M_H_CPU0_SB_CS_N<1>")
	)
	(arc
		(start 389.333486 -266.468606)
		(mid 389.149978 -266.423112)
		(end 388.967726 -266.473432)
		(width 0.0889)
		(layer "In13.Cu")
		(net "M_H_CPU0_SB_CS_N<1>")
	)
	(arc
		(start 392.140948 -266.462256)
		(mid 391.96287 -266.423272)
		(end 391.787634 -266.473432)
		(width 0.0889)
		(layer "In13.Cu")
		(net "M_H_CPU0_SB_CS_N<1>")
	)
	(arc
		(start 384.63347 -266.468606)
		(mid 384.4806 -266.423965)
		(end 384.323082 -266.44727)
		(width 0.0889)
		(layer "In13.Cu")
		(net "M_H_CPU0_SB_CS_N<1>")
	)
	(arc
		(start 385.207764 -266.473432)
		(mid 384.924808 -266.549609)
		(end 384.641852 -266.473432)
		(width 0.0889)
		(layer "In13.Cu")
		(net "M_H_CPU0_SB_CS_N<1>")
	)
	(segment
		(start 382.577848 -265.720068)
		(end 383.0447 -265.986006)
		(width 0.10668)
		(layer "F.Cu")
		(net "M_H_CPU0_SB_CS_N<0>")
	)
	(segment
		(start 419.734492 -268.310106)
		(end 420.066978 -268.310106)
		(width 0.0889)
		(layer "In13.Cu")
		(net "M_H_CPU0_SB_CS_N<0>")
	)
	(segment
		(start 386.043424 -265.6586)
		(end 386.051806 -265.663426)
		(width 0.0889)
		(layer "In13.Cu")
		(net "M_H_CPU0_SB_CS_N<0>")
	)
	(segment
		(start 391.691876 -265.663426)
		(end 391.70229 -265.669522)
		(width 0.0889)
		(layer "In13.Cu")
		(net "M_H_CPU0_SB_CS_N<0>")
	)
	(segment
		(start 418.057584 -267.460222)
		(end 418.907468 -268.310106)
		(width 0.14478)
		(layer "In13.Cu")
		(net "M_H_CPU0_SB_CS_N<0>")
	)
	(segment
		(start 395.202156 -265.24839)
		(end 395.976856 -265.24839)
		(width 0.0889)
		(layer "In13.Cu")
		(net "M_H_CPU0_SB_CS_N<0>")
	)
	(segment
		(start 393.192508 -265.666982)
		(end 393.900152 -265.27379)
		(width 0.0889)
		(layer "In13.Cu")
		(net "M_H_CPU0_SB_CS_N<0>")
	)
	(segment
		(start 390.74344 -265.6586)
		(end 390.751822 -265.663426)
		(width 0.0889)
		(layer "In13.Cu")
		(net "M_H_CPU0_SB_CS_N<0>")
	)
	(segment
		(start 418.907468 -268.310106)
		(end 419.734492 -268.310106)
		(width 0.14478)
		(layer "In13.Cu")
		(net "M_H_CPU0_SB_CS_N<0>")
	)
	(segment
		(start 415.032952 -267.460222)
		(end 418.057584 -267.460222)
		(width 0.14478)
		(layer "In13.Cu")
		(net "M_H_CPU0_SB_CS_N<0>")
	)
	(segment
		(start 395.176756 -265.27379)
		(end 395.202156 -265.24839)
		(width 0.0889)
		(layer "In13.Cu")
		(net "M_H_CPU0_SB_CS_N<0>")
	)
	(segment
		(start 409.143454 -265.24839)
		(end 412.20517 -268.310106)
		(width 0.14478)
		(layer "In13.Cu")
		(net "M_H_CPU0_SB_CS_N<0>")
	)
	(segment
		(start 421.727122 -268.310106)
		(end 422.152064 -267.885164)
		(width 0.14478)
		(layer "In13.Cu")
		(net "M_H_CPU0_SB_CS_N<0>")
	)
	(segment
		(start 382.890776 -265.720576)
		(end 382.913128 -265.637264)
		(width 0.0889)
		(layer "In13.Cu")
		(net "M_H_CPU0_SB_CS_N<0>")
	)
	(segment
		(start 383.79781 -265.663426)
		(end 383.806192 -265.6586)
		(width 0.0889)
		(layer "In13.Cu")
		(net "M_H_CPU0_SB_CS_N<0>")
	)
	(segment
		(start 395.976856 -265.24839)
		(end 409.143454 -265.24839)
		(width 0.14478)
		(layer "In13.Cu")
		(net "M_H_CPU0_SB_CS_N<0>")
	)
	(segment
		(start 388.497826 -265.663426)
		(end 388.506208 -265.6586)
		(width 0.0889)
		(layer "In13.Cu")
		(net "M_H_CPU0_SB_CS_N<0>")
	)
	(segment
		(start 383.0447 -265.986006)
		(end 382.890776 -265.720576)
		(width 0.0889)
		(layer "In13.Cu")
		(net "M_H_CPU0_SB_CS_N<0>")
	)
	(segment
		(start 422.152064 -267.885164)
		(end 424.012106 -267.885164)
		(width 0.14478)
		(layer "In13.Cu")
		(net "M_H_CPU0_SB_CS_N<0>")
	)
	(segment
		(start 391.317734 -265.663426)
		(end 391.326116 -265.6586)
		(width 0.0889)
		(layer "In13.Cu")
		(net "M_H_CPU0_SB_CS_N<0>")
	)
	(segment
		(start 420.066978 -268.310106)
		(end 421.727122 -268.310106)
		(width 0.14478)
		(layer "In13.Cu")
		(net "M_H_CPU0_SB_CS_N<0>")
	)
	(segment
		(start 393.900152 -265.27379)
		(end 395.176756 -265.27379)
		(width 0.0889)
		(layer "In13.Cu")
		(net "M_H_CPU0_SB_CS_N<0>")
	)
	(segment
		(start 386.983478 -265.6586)
		(end 386.99186 -265.663426)
		(width 0.0889)
		(layer "In13.Cu")
		(net "M_H_CPU0_SB_CS_N<0>")
	)
	(segment
		(start 387.557772 -265.663426)
		(end 387.566154 -265.6586)
		(width 0.0889)
		(layer "In13.Cu")
		(net "M_H_CPU0_SB_CS_N<0>")
	)
	(segment
		(start 392.62431 -265.6586)
		(end 392.632692 -265.663426)
		(width 0.0889)
		(layer "In13.Cu")
		(net "M_H_CPU0_SB_CS_N<0>")
	)
	(segment
		(start 414.183068 -268.310106)
		(end 415.032952 -267.460222)
		(width 0.14478)
		(layer "In13.Cu")
		(net "M_H_CPU0_SB_CS_N<0>")
	)
	(segment
		(start 412.20517 -268.310106)
		(end 414.183068 -268.310106)
		(width 0.14478)
		(layer "In13.Cu")
		(net "M_H_CPU0_SB_CS_N<0>")
	)
	(arc
		(start 383.806192 -265.6586)
		(mid 383.9897 -265.613106)
		(end 384.171952 -265.663426)
		(width 0.0889)
		(layer "In13.Cu")
		(net "M_H_CPU0_SB_CS_N<0>")
	)
	(arc
		(start 383.231898 -265.663426)
		(mid 383.514854 -265.739603)
		(end 383.79781 -265.663426)
		(width 0.0889)
		(layer "In13.Cu")
		(net "M_H_CPU0_SB_CS_N<0>")
	)
	(arc
		(start 391.70229 -265.669522)
		(mid 391.980976 -265.739742)
		(end 392.258042 -265.663426)
		(width 0.0889)
		(layer "In13.Cu")
		(net "M_H_CPU0_SB_CS_N<0>")
	)
	(arc
		(start 385.111752 -265.663426)
		(mid 385.394708 -265.739603)
		(end 385.677664 -265.663426)
		(width 0.0889)
		(layer "In13.Cu")
		(net "M_H_CPU0_SB_CS_N<0>")
	)
	(arc
		(start 391.326116 -265.6586)
		(mid 391.509624 -265.613106)
		(end 391.691876 -265.663426)
		(width 0.0889)
		(layer "In13.Cu")
		(net "M_H_CPU0_SB_CS_N<0>")
	)
	(arc
		(start 386.99186 -265.663426)
		(mid 387.274816 -265.739603)
		(end 387.557772 -265.663426)
		(width 0.0889)
		(layer "In13.Cu")
		(net "M_H_CPU0_SB_CS_N<0>")
	)
	(arc
		(start 384.737864 -265.663426)
		(mid 384.924808 -265.613171)
		(end 385.111752 -265.663426)
		(width 0.0889)
		(layer "In13.Cu")
		(net "M_H_CPU0_SB_CS_N<0>")
	)
	(arc
		(start 390.37768 -265.663426)
		(mid 390.559931 -265.613076)
		(end 390.74344 -265.6586)
		(width 0.0889)
		(layer "In13.Cu")
		(net "M_H_CPU0_SB_CS_N<0>")
	)
	(arc
		(start 389.43788 -265.663426)
		(mid 389.624824 -265.613171)
		(end 389.811768 -265.663426)
		(width 0.0889)
		(layer "In13.Cu")
		(net "M_H_CPU0_SB_CS_N<0>")
	)
	(arc
		(start 384.171952 -265.663426)
		(mid 384.454908 -265.739603)
		(end 384.737864 -265.663426)
		(width 0.0889)
		(layer "In13.Cu")
		(net "M_H_CPU0_SB_CS_N<0>")
	)
	(arc
		(start 382.913128 -265.637264)
		(mid 383.07546 -265.614446)
		(end 383.231898 -265.663426)
		(width 0.0889)
		(layer "In13.Cu")
		(net "M_H_CPU0_SB_CS_N<0>")
	)
	(arc
		(start 387.931914 -265.663426)
		(mid 388.21487 -265.739603)
		(end 388.497826 -265.663426)
		(width 0.0889)
		(layer "In13.Cu")
		(net "M_H_CPU0_SB_CS_N<0>")
	)
	(arc
		(start 392.632692 -265.663426)
		(mid 392.91212 -265.739592)
		(end 393.192508 -265.666982)
		(width 0.0889)
		(layer "In13.Cu")
		(net "M_H_CPU0_SB_CS_N<0>")
	)
	(arc
		(start 386.617718 -265.663426)
		(mid 386.799969 -265.613076)
		(end 386.983478 -265.6586)
		(width 0.0889)
		(layer "In13.Cu")
		(net "M_H_CPU0_SB_CS_N<0>")
	)
	(arc
		(start 392.258042 -265.663426)
		(mid 392.440547 -265.612949)
		(end 392.62431 -265.6586)
		(width 0.0889)
		(layer "In13.Cu")
		(net "M_H_CPU0_SB_CS_N<0>")
	)
	(arc
		(start 388.506208 -265.6586)
		(mid 388.689716 -265.613106)
		(end 388.871968 -265.663426)
		(width 0.0889)
		(layer "In13.Cu")
		(net "M_H_CPU0_SB_CS_N<0>")
	)
	(arc
		(start 389.811768 -265.663426)
		(mid 390.094724 -265.739603)
		(end 390.37768 -265.663426)
		(width 0.0889)
		(layer "In13.Cu")
		(net "M_H_CPU0_SB_CS_N<0>")
	)
	(arc
		(start 390.751822 -265.663426)
		(mid 391.034778 -265.739603)
		(end 391.317734 -265.663426)
		(width 0.0889)
		(layer "In13.Cu")
		(net "M_H_CPU0_SB_CS_N<0>")
	)
	(arc
		(start 385.677664 -265.663426)
		(mid 385.859915 -265.613076)
		(end 386.043424 -265.6586)
		(width 0.0889)
		(layer "In13.Cu")
		(net "M_H_CPU0_SB_CS_N<0>")
	)
	(arc
		(start 388.871968 -265.663426)
		(mid 389.154924 -265.739603)
		(end 389.43788 -265.663426)
		(width 0.0889)
		(layer "In13.Cu")
		(net "M_H_CPU0_SB_CS_N<0>")
	)
	(arc
		(start 386.051806 -265.663426)
		(mid 386.334762 -265.739603)
		(end 386.617718 -265.663426)
		(width 0.0889)
		(layer "In13.Cu")
		(net "M_H_CPU0_SB_CS_N<0>")
	)
	(arc
		(start 387.566154 -265.6586)
		(mid 387.749662 -265.613106)
		(end 387.931914 -265.663426)
		(width 0.0889)
		(layer "In13.Cu")
		(net "M_H_CPU0_SB_CS_N<0>")
	)
	(segment
		(start 382.577848 -270.580104)
		(end 383.0447 -270.846042)
		(width 0.10668)
		(layer "F.Cu")
		(net "M_H_CPU0_SB_CB<7>")
	)
	(segment
		(start 388.497826 -270.523462)
		(end 388.506208 -270.518636)
		(width 0.0889)
		(layer "In13.Cu")
		(net "M_H_CPU0_SB_CB<7>")
	)
	(segment
		(start 419.466268 -274.260056)
		(end 419.89121 -274.684998)
		(width 0.14478)
		(layer "In13.Cu")
		(net "M_H_CPU0_SB_CB<7>")
	)
	(segment
		(start 416.193224 -273.554952)
		(end 416.338004 -273.410172)
		(width 0.14478)
		(layer "In13.Cu")
		(net "M_H_CPU0_SB_CB<7>")
	)
	(segment
		(start 395.96695 -268.67993)
		(end 405.440642 -268.67993)
		(width 0.14478)
		(layer "In13.Cu")
		(net "M_H_CPU0_SB_CB<7>")
	)
	(segment
		(start 415.786824 -274.350226)
		(end 416.048444 -274.350226)
		(width 0.14478)
		(layer "In13.Cu")
		(net "M_H_CPU0_SB_CB<7>")
	)
	(segment
		(start 416.889184 -274.350226)
		(end 417.150804 -274.350226)
		(width 0.14478)
		(layer "In13.Cu")
		(net "M_H_CPU0_SB_CB<7>")
	)
	(segment
		(start 417.295584 -273.554952)
		(end 417.440364 -273.410172)
		(width 0.14478)
		(layer "In13.Cu")
		(net "M_H_CPU0_SB_CB<7>")
	)
	(segment
		(start 383.0447 -270.846042)
		(end 382.890776 -270.580612)
		(width 0.0889)
		(layer "In13.Cu")
		(net "M_H_CPU0_SB_CB<7>")
	)
	(segment
		(start 415.032952 -273.410172)
		(end 415.497264 -273.410172)
		(width 0.14478)
		(layer "In13.Cu")
		(net "M_H_CPU0_SB_CB<7>")
	)
	(segment
		(start 405.440642 -268.67993)
		(end 408.051 -271.290288)
		(width 0.14478)
		(layer "In13.Cu")
		(net "M_H_CPU0_SB_CB<7>")
	)
	(segment
		(start 417.150804 -274.350226)
		(end 417.295584 -274.205446)
		(width 0.14478)
		(layer "In13.Cu")
		(net "M_H_CPU0_SB_CB<7>")
	)
	(segment
		(start 412.195772 -274.250404)
		(end 414.19272 -274.250404)
		(width 0.14478)
		(layer "In13.Cu")
		(net "M_H_CPU0_SB_CB<7>")
	)
	(segment
		(start 393.790424 -269.626588)
		(end 394.579602 -268.83741)
		(width 0.0889)
		(layer "In13.Cu")
		(net "M_H_CPU0_SB_CB<7>")
	)
	(segment
		(start 382.890776 -270.580612)
		(end 382.913128 -270.4973)
		(width 0.0889)
		(layer "In13.Cu")
		(net "M_H_CPU0_SB_CB<7>")
	)
	(segment
		(start 394.579602 -268.83741)
		(end 395.233652 -268.83741)
		(width 0.0889)
		(layer "In13.Cu")
		(net "M_H_CPU0_SB_CB<7>")
	)
	(segment
		(start 417.295584 -274.205446)
		(end 417.295584 -273.554952)
		(width 0.14478)
		(layer "In13.Cu")
		(net "M_H_CPU0_SB_CB<7>")
	)
	(segment
		(start 391.317734 -270.523462)
		(end 391.326116 -270.518636)
		(width 0.0889)
		(layer "In13.Cu")
		(net "M_H_CPU0_SB_CB<7>")
	)
	(segment
		(start 386.983478 -270.518636)
		(end 386.99186 -270.523462)
		(width 0.0889)
		(layer "In13.Cu")
		(net "M_H_CPU0_SB_CB<7>")
	)
	(segment
		(start 416.048444 -274.350226)
		(end 416.193224 -274.205446)
		(width 0.14478)
		(layer "In13.Cu")
		(net "M_H_CPU0_SB_CB<7>")
	)
	(segment
		(start 416.193224 -274.205446)
		(end 416.193224 -273.554952)
		(width 0.14478)
		(layer "In13.Cu")
		(net "M_H_CPU0_SB_CB<7>")
	)
	(segment
		(start 390.74344 -270.518636)
		(end 390.751822 -270.523462)
		(width 0.0889)
		(layer "In13.Cu")
		(net "M_H_CPU0_SB_CB<7>")
	)
	(segment
		(start 392.697208 -269.731236)
		(end 392.69797 -269.730728)
		(width 0.0889)
		(layer "In13.Cu")
		(net "M_H_CPU0_SB_CB<7>")
	)
	(segment
		(start 416.744404 -273.554952)
		(end 416.744404 -274.205446)
		(width 0.14478)
		(layer "In13.Cu")
		(net "M_H_CPU0_SB_CB<7>")
	)
	(segment
		(start 409.235656 -271.290288)
		(end 412.195772 -274.250404)
		(width 0.14478)
		(layer "In13.Cu")
		(net "M_H_CPU0_SB_CB<7>")
	)
	(segment
		(start 386.043424 -270.518636)
		(end 386.051806 -270.523462)
		(width 0.0889)
		(layer "In13.Cu")
		(net "M_H_CPU0_SB_CB<7>")
	)
	(segment
		(start 417.869116 -273.410172)
		(end 418.719 -274.260056)
		(width 0.14478)
		(layer "In13.Cu")
		(net "M_H_CPU0_SB_CB<7>")
	)
	(segment
		(start 395.391132 -268.67993)
		(end 395.96695 -268.67993)
		(width 0.0889)
		(layer "In13.Cu")
		(net "M_H_CPU0_SB_CB<7>")
	)
	(segment
		(start 392.69797 -269.730728)
		(end 392.727688 -269.713456)
		(width 0.0889)
		(layer "In13.Cu")
		(net "M_H_CPU0_SB_CB<7>")
	)
	(segment
		(start 415.642044 -273.554952)
		(end 415.642044 -274.205446)
		(width 0.14478)
		(layer "In13.Cu")
		(net "M_H_CPU0_SB_CB<7>")
	)
	(segment
		(start 383.79781 -270.523462)
		(end 383.806192 -270.518636)
		(width 0.0889)
		(layer "In13.Cu")
		(net "M_H_CPU0_SB_CB<7>")
	)
	(segment
		(start 417.440364 -273.410172)
		(end 417.869116 -273.410172)
		(width 0.14478)
		(layer "In13.Cu")
		(net "M_H_CPU0_SB_CB<7>")
	)
	(segment
		(start 395.233652 -268.83741)
		(end 395.391132 -268.67993)
		(width 0.0889)
		(layer "In13.Cu")
		(net "M_H_CPU0_SB_CB<7>")
	)
	(segment
		(start 414.19272 -274.250404)
		(end 415.032952 -273.410172)
		(width 0.14478)
		(layer "In13.Cu")
		(net "M_H_CPU0_SB_CB<7>")
	)
	(segment
		(start 408.051 -271.290288)
		(end 409.235656 -271.290288)
		(width 0.14478)
		(layer "In13.Cu")
		(net "M_H_CPU0_SB_CB<7>")
	)
	(segment
		(start 419.89121 -274.684998)
		(end 419.912038 -274.684998)
		(width 0.14478)
		(layer "In13.Cu")
		(net "M_H_CPU0_SB_CB<7>")
	)
	(segment
		(start 416.338004 -273.410172)
		(end 416.599624 -273.410172)
		(width 0.14478)
		(layer "In13.Cu")
		(net "M_H_CPU0_SB_CB<7>")
	)
	(segment
		(start 392.257788 -270.523462)
		(end 392.296904 -270.500602)
		(width 0.0889)
		(layer "In13.Cu")
		(net "M_H_CPU0_SB_CB<7>")
	)
	(segment
		(start 416.744404 -274.205446)
		(end 416.889184 -274.350226)
		(width 0.14478)
		(layer "In13.Cu")
		(net "M_H_CPU0_SB_CB<7>")
	)
	(segment
		(start 415.497264 -273.410172)
		(end 415.642044 -273.554952)
		(width 0.14478)
		(layer "In13.Cu")
		(net "M_H_CPU0_SB_CB<7>")
	)
	(segment
		(start 387.557772 -270.523462)
		(end 387.566154 -270.518636)
		(width 0.0889)
		(layer "In13.Cu")
		(net "M_H_CPU0_SB_CB<7>")
	)
	(segment
		(start 418.719 -274.260056)
		(end 419.466268 -274.260056)
		(width 0.14478)
		(layer "In13.Cu")
		(net "M_H_CPU0_SB_CB<7>")
	)
	(segment
		(start 415.642044 -274.205446)
		(end 415.786824 -274.350226)
		(width 0.14478)
		(layer "In13.Cu")
		(net "M_H_CPU0_SB_CB<7>")
	)
	(segment
		(start 416.599624 -273.410172)
		(end 416.744404 -273.554952)
		(width 0.14478)
		(layer "In13.Cu")
		(net "M_H_CPU0_SB_CB<7>")
	)
	(segment
		(start 393.093448 -269.70863)
		(end 393.10183 -269.713456)
		(width 0.0889)
		(layer "In13.Cu")
		(net "M_H_CPU0_SB_CB<7>")
	)
	(arc
		(start 383.231898 -270.523462)
		(mid 383.514854 -270.599639)
		(end 383.79781 -270.523462)
		(width 0.0889)
		(layer "In13.Cu")
		(net "M_H_CPU0_SB_CB<7>")
	)
	(arc
		(start 389.43788 -270.523462)
		(mid 389.624824 -270.473207)
		(end 389.811768 -270.523462)
		(width 0.0889)
		(layer "In13.Cu")
		(net "M_H_CPU0_SB_CB<7>")
	)
	(arc
		(start 390.37768 -270.523462)
		(mid 390.559931 -270.473112)
		(end 390.74344 -270.518636)
		(width 0.0889)
		(layer "In13.Cu")
		(net "M_H_CPU0_SB_CB<7>")
	)
	(arc
		(start 391.326116 -270.518636)
		(mid 391.509624 -270.473142)
		(end 391.691876 -270.523462)
		(width 0.0889)
		(layer "In13.Cu")
		(net "M_H_CPU0_SB_CB<7>")
	)
	(arc
		(start 383.806192 -270.518636)
		(mid 383.9897 -270.473142)
		(end 384.171952 -270.523462)
		(width 0.0889)
		(layer "In13.Cu")
		(net "M_H_CPU0_SB_CB<7>")
	)
	(arc
		(start 389.811768 -270.523462)
		(mid 390.094724 -270.599639)
		(end 390.37768 -270.523462)
		(width 0.0889)
		(layer "In13.Cu")
		(net "M_H_CPU0_SB_CB<7>")
	)
	(arc
		(start 388.871968 -270.523462)
		(mid 389.154924 -270.599639)
		(end 389.43788 -270.523462)
		(width 0.0889)
		(layer "In13.Cu")
		(net "M_H_CPU0_SB_CB<7>")
	)
	(arc
		(start 385.677664 -270.523462)
		(mid 385.859915 -270.473112)
		(end 386.043424 -270.518636)
		(width 0.0889)
		(layer "In13.Cu")
		(net "M_H_CPU0_SB_CB<7>")
	)
	(arc
		(start 393.667742 -269.713456)
		(mid 393.732768 -269.675227)
		(end 393.790424 -269.626588)
		(width 0.0889)
		(layer "In13.Cu")
		(net "M_H_CPU0_SB_CB<7>")
	)
	(arc
		(start 392.540236 -270.036036)
		(mid 392.581785 -269.864614)
		(end 392.697208 -269.731236)
		(width 0.0889)
		(layer "In13.Cu")
		(net "M_H_CPU0_SB_CB<7>")
	)
	(arc
		(start 386.99186 -270.523462)
		(mid 387.274816 -270.599639)
		(end 387.557772 -270.523462)
		(width 0.0889)
		(layer "In13.Cu")
		(net "M_H_CPU0_SB_CB<7>")
	)
	(arc
		(start 386.051806 -270.523462)
		(mid 386.334762 -270.599639)
		(end 386.617718 -270.523462)
		(width 0.0889)
		(layer "In13.Cu")
		(net "M_H_CPU0_SB_CB<7>")
	)
	(arc
		(start 392.727688 -269.713456)
		(mid 392.909939 -269.663106)
		(end 393.093448 -269.70863)
		(width 0.0889)
		(layer "In13.Cu")
		(net "M_H_CPU0_SB_CB<7>")
	)
	(arc
		(start 386.617718 -270.523462)
		(mid 386.799969 -270.473112)
		(end 386.983478 -270.518636)
		(width 0.0889)
		(layer "In13.Cu")
		(net "M_H_CPU0_SB_CB<7>")
	)
	(arc
		(start 384.171952 -270.523462)
		(mid 384.454908 -270.599639)
		(end 384.737864 -270.523462)
		(width 0.0889)
		(layer "In13.Cu")
		(net "M_H_CPU0_SB_CB<7>")
	)
	(arc
		(start 387.931914 -270.523462)
		(mid 388.21487 -270.599639)
		(end 388.497826 -270.523462)
		(width 0.0889)
		(layer "In13.Cu")
		(net "M_H_CPU0_SB_CB<7>")
	)
	(arc
		(start 393.10183 -269.713456)
		(mid 393.384786 -269.789633)
		(end 393.667742 -269.713456)
		(width 0.0889)
		(layer "In13.Cu")
		(net "M_H_CPU0_SB_CB<7>")
	)
	(arc
		(start 382.913128 -270.4973)
		(mid 383.07546 -270.474482)
		(end 383.231898 -270.523462)
		(width 0.0889)
		(layer "In13.Cu")
		(net "M_H_CPU0_SB_CB<7>")
	)
	(arc
		(start 387.566154 -270.518636)
		(mid 387.749662 -270.473142)
		(end 387.931914 -270.523462)
		(width 0.0889)
		(layer "In13.Cu")
		(net "M_H_CPU0_SB_CB<7>")
	)
	(arc
		(start 390.751822 -270.523462)
		(mid 391.034778 -270.599639)
		(end 391.317734 -270.523462)
		(width 0.0889)
		(layer "In13.Cu")
		(net "M_H_CPU0_SB_CB<7>")
	)
	(arc
		(start 385.111752 -270.523462)
		(mid 385.394708 -270.599639)
		(end 385.677664 -270.523462)
		(width 0.0889)
		(layer "In13.Cu")
		(net "M_H_CPU0_SB_CB<7>")
	)
	(arc
		(start 391.691876 -270.523462)
		(mid 391.974832 -270.599639)
		(end 392.257788 -270.523462)
		(width 0.0889)
		(layer "In13.Cu")
		(net "M_H_CPU0_SB_CB<7>")
	)
	(arc
		(start 392.296904 -270.500602)
		(mid 392.475717 -270.298252)
		(end 392.540236 -270.036036)
		(width 0.0889)
		(layer "In13.Cu")
		(net "M_H_CPU0_SB_CB<7>")
	)
	(arc
		(start 388.506208 -270.518636)
		(mid 388.689716 -270.473142)
		(end 388.871968 -270.523462)
		(width 0.0889)
		(layer "In13.Cu")
		(net "M_H_CPU0_SB_CB<7>")
	)
	(arc
		(start 384.737864 -270.523462)
		(mid 384.924808 -270.473207)
		(end 385.111752 -270.523462)
		(width 0.0889)
		(layer "In13.Cu")
		(net "M_H_CPU0_SB_CB<7>")
	)
	(segment
		(start 383.988056 -269.770098)
		(end 384.454908 -270.036036)
		(width 0.10668)
		(layer "F.Cu")
		(net "M_H_CPU0_SB_CB<6>")
	)
	(segment
		(start 405.855424 -267.77061)
		(end 395.996922 -267.77061)
		(width 0.14478)
		(layer "In13.Cu")
		(net "M_H_CPU0_SB_CB<6>")
	)
	(segment
		(start 408.537918 -270.224504)
		(end 408.309318 -270.224504)
		(width 0.14478)
		(layer "In13.Cu")
		(net "M_H_CPU0_SB_CB<6>")
	)
	(segment
		(start 419.487096 -272.560034)
		(end 418.491924 -272.560034)
		(width 0.14478)
		(layer "In13.Cu")
		(net "M_H_CPU0_SB_CB<6>")
	)
	(segment
		(start 407.015696 -268.150594)
		(end 408.699462 -269.83436)
		(width 0.14478)
		(layer "In13.Cu")
		(net "M_H_CPU0_SB_CB<6>")
	)
	(segment
		(start 415.032952 -271.71015)
		(end 414.183068 -272.560034)
		(width 0.14478)
		(layer "In13.Cu")
		(net "M_H_CPU0_SB_CB<6>")
	)
	(segment
		(start 407.40584 -267.76045)
		(end 407.17724 -267.76045)
		(width 0.14478)
		(layer "In13.Cu")
		(net "M_H_CPU0_SB_CB<6>")
	)
	(segment
		(start 417.64204 -271.71015)
		(end 415.032952 -271.71015)
		(width 0.14478)
		(layer "In13.Cu")
		(net "M_H_CPU0_SB_CB<6>")
	)
	(segment
		(start 412.205424 -272.560034)
		(end 407.40584 -267.76045)
		(width 0.14478)
		(layer "In13.Cu")
		(net "M_H_CPU0_SB_CB<6>")
	)
	(segment
		(start 384.30073 -269.770606)
		(end 384.454908 -270.036036)
		(width 0.0889)
		(layer "In13.Cu")
		(net "M_H_CPU0_SB_CB<6>")
	)
	(segment
		(start 418.491924 -272.560034)
		(end 417.64204 -271.71015)
		(width 0.14478)
		(layer "In13.Cu")
		(net "M_H_CPU0_SB_CB<6>")
	)
	(segment
		(start 393.691872 -268.43609)
		(end 393.313412 -268.81455)
		(width 0.0889)
		(layer "In13.Cu")
		(net "M_H_CPU0_SB_CB<6>")
	)
	(segment
		(start 408.699462 -269.83436)
		(end 408.699462 -270.06296)
		(width 0.14478)
		(layer "In13.Cu")
		(net "M_H_CPU0_SB_CB<6>")
	)
	(segment
		(start 391.82675 -269.690596)
		(end 391.787634 -269.713456)
		(width 0.0889)
		(layer "In13.Cu")
		(net "M_H_CPU0_SB_CB<6>")
	)
	(segment
		(start 394.078714 -268.43609)
		(end 393.691872 -268.43609)
		(width 0.0889)
		(layer "In13.Cu")
		(net "M_H_CPU0_SB_CB<6>")
	)
	(segment
		(start 419.912038 -272.984976)
		(end 419.487096 -272.560034)
		(width 0.14478)
		(layer "In13.Cu")
		(net "M_H_CPU0_SB_CB<6>")
	)
	(segment
		(start 386.1562 -269.70863)
		(end 386.147818 -269.713456)
		(width 0.0889)
		(layer "In13.Cu")
		(net "M_H_CPU0_SB_CB<6>")
	)
	(segment
		(start 394.744194 -267.77061)
		(end 394.078714 -268.43609)
		(width 0.0889)
		(layer "In13.Cu")
		(net "M_H_CPU0_SB_CB<6>")
	)
	(segment
		(start 389.916162 -269.70863)
		(end 389.90778 -269.713456)
		(width 0.0889)
		(layer "In13.Cu")
		(net "M_H_CPU0_SB_CB<6>")
	)
	(segment
		(start 407.015696 -267.921994)
		(end 407.015696 -268.150594)
		(width 0.14478)
		(layer "In13.Cu")
		(net "M_H_CPU0_SB_CB<6>")
	)
	(segment
		(start 408.309318 -270.224504)
		(end 405.855424 -267.77061)
		(width 0.14478)
		(layer "In13.Cu")
		(net "M_H_CPU0_SB_CB<6>")
	)
	(segment
		(start 385.216146 -269.70863)
		(end 385.207764 -269.713456)
		(width 0.0889)
		(layer "In13.Cu")
		(net "M_H_CPU0_SB_CB<6>")
	)
	(segment
		(start 389.341868 -269.713456)
		(end 389.333486 -269.70863)
		(width 0.0889)
		(layer "In13.Cu")
		(net "M_H_CPU0_SB_CB<6>")
	)
	(segment
		(start 392.257788 -268.90345)
		(end 392.226038 -268.921738)
		(width 0.0889)
		(layer "In13.Cu")
		(net "M_H_CPU0_SB_CB<6>")
	)
	(segment
		(start 407.17724 -267.76045)
		(end 407.015696 -267.921994)
		(width 0.14478)
		(layer "In13.Cu")
		(net "M_H_CPU0_SB_CB<6>")
	)
	(segment
		(start 414.183068 -272.560034)
		(end 412.205424 -272.560034)
		(width 0.14478)
		(layer "In13.Cu")
		(net "M_H_CPU0_SB_CB<6>")
	)
	(segment
		(start 384.641852 -269.713456)
		(end 384.63347 -269.70863)
		(width 0.0889)
		(layer "In13.Cu")
		(net "M_H_CPU0_SB_CB<6>")
	)
	(segment
		(start 392.26617 -268.898624)
		(end 392.257788 -268.90345)
		(width 0.0889)
		(layer "In13.Cu")
		(net "M_H_CPU0_SB_CB<6>")
	)
	(segment
		(start 408.699462 -270.06296)
		(end 408.537918 -270.224504)
		(width 0.14478)
		(layer "In13.Cu")
		(net "M_H_CPU0_SB_CB<6>")
	)
	(segment
		(start 395.996922 -267.77061)
		(end 394.744194 -267.77061)
		(width 0.0889)
		(layer "In13.Cu")
		(net "M_H_CPU0_SB_CB<6>")
	)
	(segment
		(start 388.401814 -269.713456)
		(end 388.393432 -269.70863)
		(width 0.0889)
		(layer "In13.Cu")
		(net "M_H_CPU0_SB_CB<6>")
	)
	(segment
		(start 384.323082 -269.687294)
		(end 384.30073 -269.770606)
		(width 0.0889)
		(layer "In13.Cu")
		(net "M_H_CPU0_SB_CB<6>")
	)
	(arc
		(start 386.147818 -269.713456)
		(mid 385.864862 -269.789633)
		(end 385.581906 -269.713456)
		(width 0.0889)
		(layer "In13.Cu")
		(net "M_H_CPU0_SB_CB<6>")
	)
	(arc
		(start 391.787634 -269.713456)
		(mid 391.504678 -269.789633)
		(end 391.221722 -269.713456)
		(width 0.0889)
		(layer "In13.Cu")
		(net "M_H_CPU0_SB_CB<6>")
	)
	(arc
		(start 387.46176 -269.713456)
		(mid 387.274816 -269.663201)
		(end 387.087872 -269.713456)
		(width 0.0889)
		(layer "In13.Cu")
		(net "M_H_CPU0_SB_CB<6>")
	)
	(arc
		(start 390.847834 -269.713456)
		(mid 390.564878 -269.789633)
		(end 390.281922 -269.713456)
		(width 0.0889)
		(layer "In13.Cu")
		(net "M_H_CPU0_SB_CB<6>")
	)
	(arc
		(start 392.63193 -268.90345)
		(mid 392.449679 -268.8531)
		(end 392.26617 -268.898624)
		(width 0.0889)
		(layer "In13.Cu")
		(net "M_H_CPU0_SB_CB<6>")
	)
	(arc
		(start 389.333486 -269.70863)
		(mid 389.149978 -269.663136)
		(end 388.967726 -269.713456)
		(width 0.0889)
		(layer "In13.Cu")
		(net "M_H_CPU0_SB_CB<6>")
	)
	(arc
		(start 388.393432 -269.70863)
		(mid 388.209924 -269.663136)
		(end 388.027672 -269.713456)
		(width 0.0889)
		(layer "In13.Cu")
		(net "M_H_CPU0_SB_CB<6>")
	)
	(arc
		(start 392.226038 -268.921738)
		(mid 392.111362 -269.055072)
		(end 392.070082 -269.22603)
		(width 0.0889)
		(layer "In13.Cu")
		(net "M_H_CPU0_SB_CB<6>")
	)
	(arc
		(start 390.281922 -269.713456)
		(mid 390.099671 -269.663106)
		(end 389.916162 -269.70863)
		(width 0.0889)
		(layer "In13.Cu")
		(net "M_H_CPU0_SB_CB<6>")
	)
	(arc
		(start 386.52196 -269.713456)
		(mid 386.339709 -269.663106)
		(end 386.1562 -269.70863)
		(width 0.0889)
		(layer "In13.Cu")
		(net "M_H_CPU0_SB_CB<6>")
	)
	(arc
		(start 385.207764 -269.713456)
		(mid 384.924808 -269.789633)
		(end 384.641852 -269.713456)
		(width 0.0889)
		(layer "In13.Cu")
		(net "M_H_CPU0_SB_CB<6>")
	)
	(arc
		(start 393.313412 -268.81455)
		(mid 393.258513 -268.862752)
		(end 393.197842 -268.90345)
		(width 0.0889)
		(layer "In13.Cu")
		(net "M_H_CPU0_SB_CB<6>")
	)
	(arc
		(start 388.027672 -269.713456)
		(mid 387.744716 -269.789633)
		(end 387.46176 -269.713456)
		(width 0.0889)
		(layer "In13.Cu")
		(net "M_H_CPU0_SB_CB<6>")
	)
	(arc
		(start 387.087872 -269.713456)
		(mid 386.804916 -269.789633)
		(end 386.52196 -269.713456)
		(width 0.0889)
		(layer "In13.Cu")
		(net "M_H_CPU0_SB_CB<6>")
	)
	(arc
		(start 392.070082 -269.22603)
		(mid 392.005567 -269.488249)
		(end 391.82675 -269.690596)
		(width 0.0889)
		(layer "In13.Cu")
		(net "M_H_CPU0_SB_CB<6>")
	)
	(arc
		(start 384.63347 -269.70863)
		(mid 384.4806 -269.663989)
		(end 384.323082 -269.687294)
		(width 0.0889)
		(layer "In13.Cu")
		(net "M_H_CPU0_SB_CB<6>")
	)
	(arc
		(start 389.90778 -269.713456)
		(mid 389.624824 -269.789633)
		(end 389.341868 -269.713456)
		(width 0.0889)
		(layer "In13.Cu")
		(net "M_H_CPU0_SB_CB<6>")
	)
	(arc
		(start 391.221722 -269.713456)
		(mid 391.034778 -269.663201)
		(end 390.847834 -269.713456)
		(width 0.0889)
		(layer "In13.Cu")
		(net "M_H_CPU0_SB_CB<6>")
	)
	(arc
		(start 385.581906 -269.713456)
		(mid 385.399655 -269.663106)
		(end 385.216146 -269.70863)
		(width 0.0889)
		(layer "In13.Cu")
		(net "M_H_CPU0_SB_CB<6>")
	)
	(arc
		(start 388.967726 -269.713456)
		(mid 388.68477 -269.789633)
		(end 388.401814 -269.713456)
		(width 0.0889)
		(layer "In13.Cu")
		(net "M_H_CPU0_SB_CB<6>")
	)
	(arc
		(start 393.197842 -268.90345)
		(mid 392.914886 -268.979627)
		(end 392.63193 -268.90345)
		(width 0.0889)
		(layer "In13.Cu")
		(net "M_H_CPU0_SB_CB<6>")
	)
	(segment
		(start 382.107948 -269.770098)
		(end 382.5748 -270.036036)
		(width 0.10668)
		(layer "F.Cu")
		(net "M_H_CPU0_SB_CB<5>")
	)
	(segment
		(start 394.532104 -268.58849)
		(end 393.571984 -269.54861)
		(width 0.0889)
		(layer "In13.Cu")
		(net "M_H_CPU0_SB_CB<5>")
	)
	(segment
		(start 414.940242 -272.560034)
		(end 414.090104 -273.410172)
		(width 0.14478)
		(layer "In13.Cu")
		(net "M_H_CPU0_SB_CB<5>")
	)
	(segment
		(start 393.206224 -269.553436)
		(end 393.197842 -269.54861)
		(width 0.0889)
		(layer "In13.Cu")
		(net "M_H_CPU0_SB_CB<5>")
	)
	(segment
		(start 388.401814 -270.358616)
		(end 388.393432 -270.363442)
		(width 0.0889)
		(layer "In13.Cu")
		(net "M_H_CPU0_SB_CB<5>")
	)
	(segment
		(start 383.701798 -270.358616)
		(end 383.693416 -270.363442)
		(width 0.0889)
		(layer "In13.Cu")
		(net "M_H_CPU0_SB_CB<5>")
	)
	(segment
		(start 392.63193 -269.54861)
		(end 392.592814 -269.57147)
		(width 0.0889)
		(layer "In13.Cu")
		(net "M_H_CPU0_SB_CB<5>")
	)
	(segment
		(start 409.850082 -270.840708)
		(end 408.23769 -270.840708)
		(width 0.14478)
		(layer "In13.Cu")
		(net "M_H_CPU0_SB_CB<5>")
	)
	(segment
		(start 414.090104 -273.410172)
		(end 412.419546 -273.410172)
		(width 0.14478)
		(layer "In13.Cu")
		(net "M_H_CPU0_SB_CB<5>")
	)
	(segment
		(start 389.916162 -270.363442)
		(end 389.90778 -270.358616)
		(width 0.0889)
		(layer "In13.Cu")
		(net "M_H_CPU0_SB_CB<5>")
	)
	(segment
		(start 395.079474 -268.58849)
		(end 394.532104 -268.58849)
		(width 0.0889)
		(layer "In13.Cu")
		(net "M_H_CPU0_SB_CB<5>")
	)
	(segment
		(start 421.447468 -273.410172)
		(end 418.60597 -273.410172)
		(width 0.14478)
		(layer "In13.Cu")
		(net "M_H_CPU0_SB_CB<5>")
	)
	(segment
		(start 392.161776 -270.358616)
		(end 392.153394 -270.363442)
		(width 0.0889)
		(layer "In13.Cu")
		(net "M_H_CPU0_SB_CB<5>")
	)
	(segment
		(start 412.419546 -273.410172)
		(end 409.850082 -270.840708)
		(width 0.14478)
		(layer "In13.Cu")
		(net "M_H_CPU0_SB_CB<5>")
	)
	(segment
		(start 384.641852 -270.358616)
		(end 384.63347 -270.363442)
		(width 0.0889)
		(layer "In13.Cu")
		(net "M_H_CPU0_SB_CB<5>")
	)
	(segment
		(start 389.341868 -270.358616)
		(end 389.333486 -270.363442)
		(width 0.0889)
		(layer "In13.Cu")
		(net "M_H_CPU0_SB_CB<5>")
	)
	(segment
		(start 418.60597 -273.410172)
		(end 417.755832 -272.560034)
		(width 0.14478)
		(layer "In13.Cu")
		(net "M_H_CPU0_SB_CB<5>")
	)
	(segment
		(start 405.622252 -268.22527)
		(end 396.006828 -268.22527)
		(width 0.14478)
		(layer "In13.Cu")
		(net "M_H_CPU0_SB_CB<5>")
	)
	(segment
		(start 382.728724 -270.301466)
		(end 382.5748 -270.036036)
		(width 0.0889)
		(layer "In13.Cu")
		(net "M_H_CPU0_SB_CB<5>")
	)
	(segment
		(start 382.824736 -270.326866)
		(end 382.728724 -270.301466)
		(width 0.0889)
		(layer "In13.Cu")
		(net "M_H_CPU0_SB_CB<5>")
	)
	(segment
		(start 396.006828 -268.22527)
		(end 395.442694 -268.22527)
		(width 0.0889)
		(layer "In13.Cu")
		(net "M_H_CPU0_SB_CB<5>")
	)
	(segment
		(start 395.442694 -268.22527)
		(end 395.079474 -268.58849)
		(width 0.0889)
		(layer "In13.Cu")
		(net "M_H_CPU0_SB_CB<5>")
	)
	(segment
		(start 408.23769 -270.840708)
		(end 405.622252 -268.22527)
		(width 0.14478)
		(layer "In13.Cu")
		(net "M_H_CPU0_SB_CB<5>")
	)
	(segment
		(start 424.012106 -273.835114)
		(end 421.447468 -273.410172)
		(width 0.14478)
		(layer "In13.Cu")
		(net "M_H_CPU0_SB_CB<5>")
	)
	(segment
		(start 386.1562 -270.363442)
		(end 386.147818 -270.358616)
		(width 0.0889)
		(layer "In13.Cu")
		(net "M_H_CPU0_SB_CB<5>")
	)
	(segment
		(start 392.193526 -270.340328)
		(end 392.161776 -270.358616)
		(width 0.0889)
		(layer "In13.Cu")
		(net "M_H_CPU0_SB_CB<5>")
	)
	(segment
		(start 385.216146 -270.363442)
		(end 385.207764 -270.358616)
		(width 0.0889)
		(layer "In13.Cu")
		(net "M_H_CPU0_SB_CB<5>")
	)
	(segment
		(start 417.755832 -272.560034)
		(end 414.940242 -272.560034)
		(width 0.14478)
		(layer "In13.Cu")
		(net "M_H_CPU0_SB_CB<5>")
	)
	(arc
		(start 385.581906 -270.358616)
		(mid 385.399655 -270.408966)
		(end 385.216146 -270.363442)
		(width 0.0889)
		(layer "In13.Cu")
		(net "M_H_CPU0_SB_CB<5>")
	)
	(arc
		(start 389.90778 -270.358616)
		(mid 389.624824 -270.282439)
		(end 389.341868 -270.358616)
		(width 0.0889)
		(layer "In13.Cu")
		(net "M_H_CPU0_SB_CB<5>")
	)
	(arc
		(start 390.847834 -270.358616)
		(mid 390.564878 -270.282439)
		(end 390.281922 -270.358616)
		(width 0.0889)
		(layer "In13.Cu")
		(net "M_H_CPU0_SB_CB<5>")
	)
	(arc
		(start 386.147818 -270.358616)
		(mid 385.864862 -270.282439)
		(end 385.581906 -270.358616)
		(width 0.0889)
		(layer "In13.Cu")
		(net "M_H_CPU0_SB_CB<5>")
	)
	(arc
		(start 390.281922 -270.358616)
		(mid 390.099671 -270.408966)
		(end 389.916162 -270.363442)
		(width 0.0889)
		(layer "In13.Cu")
		(net "M_H_CPU0_SB_CB<5>")
	)
	(arc
		(start 388.027672 -270.358616)
		(mid 387.744716 -270.282439)
		(end 387.46176 -270.358616)
		(width 0.0889)
		(layer "In13.Cu")
		(net "M_H_CPU0_SB_CB<5>")
	)
	(arc
		(start 384.63347 -270.363442)
		(mid 384.449962 -270.408936)
		(end 384.26771 -270.358616)
		(width 0.0889)
		(layer "In13.Cu")
		(net "M_H_CPU0_SB_CB<5>")
	)
	(arc
		(start 393.571984 -269.54861)
		(mid 393.389733 -269.59896)
		(end 393.206224 -269.553436)
		(width 0.0889)
		(layer "In13.Cu")
		(net "M_H_CPU0_SB_CB<5>")
	)
	(arc
		(start 383.327656 -270.358616)
		(mid 383.079943 -270.283396)
		(end 382.824736 -270.326866)
		(width 0.0889)
		(layer "In13.Cu")
		(net "M_H_CPU0_SB_CB<5>")
	)
	(arc
		(start 385.207764 -270.358616)
		(mid 384.924808 -270.282439)
		(end 384.641852 -270.358616)
		(width 0.0889)
		(layer "In13.Cu")
		(net "M_H_CPU0_SB_CB<5>")
	)
	(arc
		(start 384.26771 -270.358616)
		(mid 383.984754 -270.282439)
		(end 383.701798 -270.358616)
		(width 0.0889)
		(layer "In13.Cu")
		(net "M_H_CPU0_SB_CB<5>")
	)
	(arc
		(start 387.46176 -270.358616)
		(mid 387.274816 -270.408871)
		(end 387.087872 -270.358616)
		(width 0.0889)
		(layer "In13.Cu")
		(net "M_H_CPU0_SB_CB<5>")
	)
	(arc
		(start 392.349482 -270.036036)
		(mid 392.308227 -270.207007)
		(end 392.193526 -270.340328)
		(width 0.0889)
		(layer "In13.Cu")
		(net "M_H_CPU0_SB_CB<5>")
	)
	(arc
		(start 388.967726 -270.358616)
		(mid 388.68477 -270.282439)
		(end 388.401814 -270.358616)
		(width 0.0889)
		(layer "In13.Cu")
		(net "M_H_CPU0_SB_CB<5>")
	)
	(arc
		(start 387.087872 -270.358616)
		(mid 386.804916 -270.282439)
		(end 386.52196 -270.358616)
		(width 0.0889)
		(layer "In13.Cu")
		(net "M_H_CPU0_SB_CB<5>")
	)
	(arc
		(start 392.592814 -269.57147)
		(mid 392.414001 -269.77382)
		(end 392.349482 -270.036036)
		(width 0.0889)
		(layer "In13.Cu")
		(net "M_H_CPU0_SB_CB<5>")
	)
	(arc
		(start 386.52196 -270.358616)
		(mid 386.339709 -270.408966)
		(end 386.1562 -270.363442)
		(width 0.0889)
		(layer "In13.Cu")
		(net "M_H_CPU0_SB_CB<5>")
	)
	(arc
		(start 392.153394 -270.363442)
		(mid 391.969886 -270.408936)
		(end 391.787634 -270.358616)
		(width 0.0889)
		(layer "In13.Cu")
		(net "M_H_CPU0_SB_CB<5>")
	)
	(arc
		(start 383.693416 -270.363442)
		(mid 383.509908 -270.408936)
		(end 383.327656 -270.358616)
		(width 0.0889)
		(layer "In13.Cu")
		(net "M_H_CPU0_SB_CB<5>")
	)
	(arc
		(start 391.221722 -270.358616)
		(mid 391.034778 -270.408871)
		(end 390.847834 -270.358616)
		(width 0.0889)
		(layer "In13.Cu")
		(net "M_H_CPU0_SB_CB<5>")
	)
	(arc
		(start 391.787634 -270.358616)
		(mid 391.504678 -270.282439)
		(end 391.221722 -270.358616)
		(width 0.0889)
		(layer "In13.Cu")
		(net "M_H_CPU0_SB_CB<5>")
	)
	(arc
		(start 389.333486 -270.363442)
		(mid 389.149978 -270.408936)
		(end 388.967726 -270.358616)
		(width 0.0889)
		(layer "In13.Cu")
		(net "M_H_CPU0_SB_CB<5>")
	)
	(arc
		(start 393.197842 -269.54861)
		(mid 392.914886 -269.472433)
		(end 392.63193 -269.54861)
		(width 0.0889)
		(layer "In13.Cu")
		(net "M_H_CPU0_SB_CB<5>")
	)
	(arc
		(start 388.393432 -270.363442)
		(mid 388.209924 -270.408936)
		(end 388.027672 -270.358616)
		(width 0.0889)
		(layer "In13.Cu")
		(net "M_H_CPU0_SB_CB<5>")
	)
	(segment
		(start 383.517902 -268.960092)
		(end 383.984754 -269.22603)
		(width 0.10668)
		(layer "F.Cu")
		(net "M_H_CPU0_SB_CB<4>")
	)
	(segment
		(start 412.28137 -271.709896)
		(end 414.297368 -271.709896)
		(width 0.14478)
		(layer "In13.Cu")
		(net "M_H_CPU0_SB_CB<4>")
	)
	(segment
		(start 421.479472 -272.47596)
		(end 421.624252 -272.33118)
		(width 0.14478)
		(layer "In13.Cu")
		(net "M_H_CPU0_SB_CB<4>")
	)
	(segment
		(start 386.043424 -269.553436)
		(end 386.051806 -269.54861)
		(width 0.0889)
		(layer "In13.Cu")
		(net "M_H_CPU0_SB_CB<4>")
	)
	(segment
		(start 393.178538 -268.679676)
		(end 393.66571 -268.192504)
		(width 0.0889)
		(layer "In13.Cu")
		(net "M_H_CPU0_SB_CB<4>")
	)
	(segment
		(start 394.010134 -268.192504)
		(end 394.891768 -267.31087)
		(width 0.0889)
		(layer "In13.Cu")
		(net "M_H_CPU0_SB_CB<4>")
	)
	(segment
		(start 420.928292 -271.709896)
		(end 421.073072 -271.854676)
		(width 0.14478)
		(layer "In13.Cu")
		(net "M_H_CPU0_SB_CB<4>")
	)
	(segment
		(start 415.147252 -270.860012)
		(end 417.630356 -270.860012)
		(width 0.14478)
		(layer "In13.Cu")
		(net "M_H_CPU0_SB_CB<4>")
	)
	(segment
		(start 384.138932 -269.49146)
		(end 384.235198 -269.51686)
		(width 0.0889)
		(layer "In13.Cu")
		(net "M_H_CPU0_SB_CB<4>")
	)
	(segment
		(start 421.624252 -271.854676)
		(end 421.769032 -271.709896)
		(width 0.14478)
		(layer "In13.Cu")
		(net "M_H_CPU0_SB_CB<4>")
	)
	(segment
		(start 387.557772 -269.54861)
		(end 387.566154 -269.553436)
		(width 0.0889)
		(layer "In13.Cu")
		(net "M_H_CPU0_SB_CB<4>")
	)
	(segment
		(start 407.882344 -267.31087)
		(end 412.28137 -271.709896)
		(width 0.14478)
		(layer "In13.Cu")
		(net "M_H_CPU0_SB_CB<4>")
	)
	(segment
		(start 418.48024 -271.709896)
		(end 420.928292 -271.709896)
		(width 0.14478)
		(layer "In13.Cu")
		(net "M_H_CPU0_SB_CB<4>")
	)
	(segment
		(start 423.58691 -271.709896)
		(end 424.012106 -272.135092)
		(width 0.14478)
		(layer "In13.Cu")
		(net "M_H_CPU0_SB_CB<4>")
	)
	(segment
		(start 421.073072 -272.33118)
		(end 421.217852 -272.47596)
		(width 0.14478)
		(layer "In13.Cu")
		(net "M_H_CPU0_SB_CB<4>")
	)
	(segment
		(start 391.317734 -269.54861)
		(end 391.326116 -269.553436)
		(width 0.0889)
		(layer "In13.Cu")
		(net "M_H_CPU0_SB_CB<4>")
	)
	(segment
		(start 388.497826 -269.54861)
		(end 388.506208 -269.553436)
		(width 0.0889)
		(layer "In13.Cu")
		(net "M_H_CPU0_SB_CB<4>")
	)
	(segment
		(start 421.217852 -272.47596)
		(end 421.479472 -272.47596)
		(width 0.14478)
		(layer "In13.Cu")
		(net "M_H_CPU0_SB_CB<4>")
	)
	(segment
		(start 421.624252 -272.33118)
		(end 421.624252 -271.854676)
		(width 0.14478)
		(layer "In13.Cu")
		(net "M_H_CPU0_SB_CB<4>")
	)
	(segment
		(start 421.769032 -271.709896)
		(end 423.58691 -271.709896)
		(width 0.14478)
		(layer "In13.Cu")
		(net "M_H_CPU0_SB_CB<4>")
	)
	(segment
		(start 386.983478 -269.553436)
		(end 386.99186 -269.54861)
		(width 0.0889)
		(layer "In13.Cu")
		(net "M_H_CPU0_SB_CB<4>")
	)
	(segment
		(start 390.74344 -269.553436)
		(end 390.751822 -269.54861)
		(width 0.0889)
		(layer "In13.Cu")
		(net "M_H_CPU0_SB_CB<4>")
	)
	(segment
		(start 421.073072 -271.854676)
		(end 421.073072 -272.33118)
		(width 0.14478)
		(layer "In13.Cu")
		(net "M_H_CPU0_SB_CB<4>")
	)
	(segment
		(start 414.297368 -271.709896)
		(end 415.147252 -270.860012)
		(width 0.14478)
		(layer "In13.Cu")
		(net "M_H_CPU0_SB_CB<4>")
	)
	(segment
		(start 393.66571 -268.192504)
		(end 394.010134 -268.192504)
		(width 0.0889)
		(layer "In13.Cu")
		(net "M_H_CPU0_SB_CB<4>")
	)
	(segment
		(start 392.12266 -268.761464)
		(end 392.161776 -268.738604)
		(width 0.0889)
		(layer "In13.Cu")
		(net "M_H_CPU0_SB_CB<4>")
	)
	(segment
		(start 394.891768 -267.31087)
		(end 395.932152 -267.31087)
		(width 0.0889)
		(layer "In13.Cu")
		(net "M_H_CPU0_SB_CB<4>")
	)
	(segment
		(start 391.691876 -269.54861)
		(end 391.722356 -269.53083)
		(width 0.0889)
		(layer "In13.Cu")
		(net "M_H_CPU0_SB_CB<4>")
	)
	(segment
		(start 417.630356 -270.860012)
		(end 418.48024 -271.709896)
		(width 0.14478)
		(layer "In13.Cu")
		(net "M_H_CPU0_SB_CB<4>")
	)
	(segment
		(start 395.932152 -267.31087)
		(end 407.882344 -267.31087)
		(width 0.14478)
		(layer "In13.Cu")
		(net "M_H_CPU0_SB_CB<4>")
	)
	(segment
		(start 383.984754 -269.22603)
		(end 384.138932 -269.49146)
		(width 0.0889)
		(layer "In13.Cu")
		(net "M_H_CPU0_SB_CB<4>")
	)
	(arc
		(start 391.326116 -269.553436)
		(mid 391.509624 -269.59893)
		(end 391.691876 -269.54861)
		(width 0.0889)
		(layer "In13.Cu")
		(net "M_H_CPU0_SB_CB<4>")
	)
	(arc
		(start 384.737864 -269.54861)
		(mid 384.924808 -269.598865)
		(end 385.111752 -269.54861)
		(width 0.0889)
		(layer "In13.Cu")
		(net "M_H_CPU0_SB_CB<4>")
	)
	(arc
		(start 391.879328 -269.22603)
		(mid 391.943843 -268.963811)
		(end 392.12266 -268.761464)
		(width 0.0889)
		(layer "In13.Cu")
		(net "M_H_CPU0_SB_CB<4>")
	)
	(arc
		(start 387.566154 -269.553436)
		(mid 387.749662 -269.59893)
		(end 387.931914 -269.54861)
		(width 0.0889)
		(layer "In13.Cu")
		(net "M_H_CPU0_SB_CB<4>")
	)
	(arc
		(start 386.99186 -269.54861)
		(mid 387.274816 -269.472433)
		(end 387.557772 -269.54861)
		(width 0.0889)
		(layer "In13.Cu")
		(net "M_H_CPU0_SB_CB<4>")
	)
	(arc
		(start 386.617718 -269.54861)
		(mid 386.799969 -269.59896)
		(end 386.983478 -269.553436)
		(width 0.0889)
		(layer "In13.Cu")
		(net "M_H_CPU0_SB_CB<4>")
	)
	(arc
		(start 388.871968 -269.54861)
		(mid 389.154924 -269.472433)
		(end 389.43788 -269.54861)
		(width 0.0889)
		(layer "In13.Cu")
		(net "M_H_CPU0_SB_CB<4>")
	)
	(arc
		(start 385.111752 -269.54861)
		(mid 385.394708 -269.472433)
		(end 385.677664 -269.54861)
		(width 0.0889)
		(layer "In13.Cu")
		(net "M_H_CPU0_SB_CB<4>")
	)
	(arc
		(start 390.37768 -269.54861)
		(mid 390.559931 -269.59896)
		(end 390.74344 -269.553436)
		(width 0.0889)
		(layer "In13.Cu")
		(net "M_H_CPU0_SB_CB<4>")
	)
	(arc
		(start 386.051806 -269.54861)
		(mid 386.334762 -269.472433)
		(end 386.617718 -269.54861)
		(width 0.0889)
		(layer "In13.Cu")
		(net "M_H_CPU0_SB_CB<4>")
	)
	(arc
		(start 391.722356 -269.53083)
		(mid 391.837783 -269.397454)
		(end 391.879328 -269.22603)
		(width 0.0889)
		(layer "In13.Cu")
		(net "M_H_CPU0_SB_CB<4>")
	)
	(arc
		(start 385.677664 -269.54861)
		(mid 385.859915 -269.59896)
		(end 386.043424 -269.553436)
		(width 0.0889)
		(layer "In13.Cu")
		(net "M_H_CPU0_SB_CB<4>")
	)
	(arc
		(start 389.811768 -269.54861)
		(mid 390.094724 -269.472433)
		(end 390.37768 -269.54861)
		(width 0.0889)
		(layer "In13.Cu")
		(net "M_H_CPU0_SB_CB<4>")
	)
	(arc
		(start 388.506208 -269.553436)
		(mid 388.689716 -269.59893)
		(end 388.871968 -269.54861)
		(width 0.0889)
		(layer "In13.Cu")
		(net "M_H_CPU0_SB_CB<4>")
	)
	(arc
		(start 387.931914 -269.54861)
		(mid 388.21487 -269.472433)
		(end 388.497826 -269.54861)
		(width 0.0889)
		(layer "In13.Cu")
		(net "M_H_CPU0_SB_CB<4>")
	)
	(arc
		(start 389.43788 -269.54861)
		(mid 389.624824 -269.598865)
		(end 389.811768 -269.54861)
		(width 0.0889)
		(layer "In13.Cu")
		(net "M_H_CPU0_SB_CB<4>")
	)
	(arc
		(start 392.161776 -268.738604)
		(mid 392.444732 -268.662427)
		(end 392.727688 -268.738604)
		(width 0.0889)
		(layer "In13.Cu")
		(net "M_H_CPU0_SB_CB<4>")
	)
	(arc
		(start 392.727688 -268.738604)
		(mid 392.963157 -268.785849)
		(end 393.178538 -268.679676)
		(width 0.0889)
		(layer "In13.Cu")
		(net "M_H_CPU0_SB_CB<4>")
	)
	(arc
		(start 384.235198 -269.51686)
		(mid 384.490263 -269.473509)
		(end 384.737864 -269.54861)
		(width 0.0889)
		(layer "In13.Cu")
		(net "M_H_CPU0_SB_CB<4>")
	)
	(arc
		(start 390.751822 -269.54861)
		(mid 391.034778 -269.472433)
		(end 391.317734 -269.54861)
		(width 0.0889)
		(layer "In13.Cu")
		(net "M_H_CPU0_SB_CB<4>")
	)
	(segment
		(start 382.577848 -273.820128)
		(end 383.0447 -274.086066)
		(width 0.10668)
		(layer "F.Cu")
		(net "M_H_CPU0_SB_CB<3>")
	)
	(segment
		(start 419.912038 -280.634948)
		(end 419.486842 -281.060144)
		(width 0.14478)
		(layer "In13.Cu")
		(net "M_H_CPU0_SB_CB<3>")
	)
	(segment
		(start 414.940242 -280.210006)
		(end 414.090104 -281.060144)
		(width 0.14478)
		(layer "In13.Cu")
		(net "M_H_CPU0_SB_CB<3>")
	)
	(segment
		(start 408.325066 -276.756368)
		(end 408.163522 -276.594824)
		(width 0.14478)
		(layer "In13.Cu")
		(net "M_H_CPU0_SB_CB<3>")
	)
	(segment
		(start 408.464258 -277.626064)
		(end 408.235658 -277.626064)
		(width 0.14478)
		(layer "In13.Cu")
		(net "M_H_CPU0_SB_CB<3>")
	)
	(segment
		(start 408.71521 -277.375112)
		(end 408.464258 -277.626064)
		(width 0.14478)
		(layer "In13.Cu")
		(net "M_H_CPU0_SB_CB<3>")
	)
	(segment
		(start 419.486842 -281.060144)
		(end 418.972746 -281.060144)
		(width 0.14478)
		(layer "In13.Cu")
		(net "M_H_CPU0_SB_CB<3>")
	)
	(segment
		(start 406.903682 -276.065488)
		(end 406.675082 -276.065488)
		(width 0.14478)
		(layer "In13.Cu")
		(net "M_H_CPU0_SB_CB<3>")
	)
	(segment
		(start 402.992844 -272.38325)
		(end 395.965172 -272.38325)
		(width 0.14478)
		(layer "In13.Cu")
		(net "M_H_CPU0_SB_CB<3>")
	)
	(segment
		(start 407.68397 -276.845776)
		(end 407.45537 -276.845776)
		(width 0.14478)
		(layer "In13.Cu")
		(net "M_H_CPU0_SB_CB<3>")
	)
	(segment
		(start 407.45537 -276.845776)
		(end 407.293826 -276.684232)
		(width 0.14478)
		(layer "In13.Cu")
		(net "M_H_CPU0_SB_CB<3>")
	)
	(segment
		(start 412.628842 -281.060144)
		(end 408.94381 -277.375112)
		(width 0.14478)
		(layer "In13.Cu")
		(net "M_H_CPU0_SB_CB<3>")
	)
	(segment
		(start 408.325066 -276.984968)
		(end 408.325066 -276.756368)
		(width 0.14478)
		(layer "In13.Cu")
		(net "M_H_CPU0_SB_CB<3>")
	)
	(segment
		(start 408.235658 -277.626064)
		(end 408.074114 -277.46452)
		(width 0.14478)
		(layer "In13.Cu")
		(net "M_H_CPU0_SB_CB<3>")
	)
	(segment
		(start 386.051806 -273.763486)
		(end 386.043424 -273.75866)
		(width 0.0889)
		(layer "In13.Cu")
		(net "M_H_CPU0_SB_CB<3>")
	)
	(segment
		(start 388.506208 -273.75866)
		(end 388.497826 -273.763486)
		(width 0.0889)
		(layer "In13.Cu")
		(net "M_H_CPU0_SB_CB<3>")
	)
	(segment
		(start 408.163522 -276.594824)
		(end 407.934922 -276.594824)
		(width 0.14478)
		(layer "In13.Cu")
		(net "M_H_CPU0_SB_CB<3>")
	)
	(segment
		(start 395.39799 -272.38325)
		(end 395.28877 -272.49247)
		(width 0.0889)
		(layer "In13.Cu")
		(net "M_H_CPU0_SB_CB<3>")
	)
	(segment
		(start 407.154634 -275.814536)
		(end 406.903682 -276.065488)
		(width 0.14478)
		(layer "In13.Cu")
		(net "M_H_CPU0_SB_CB<3>")
	)
	(segment
		(start 408.074114 -277.23592)
		(end 408.325066 -276.984968)
		(width 0.14478)
		(layer "In13.Cu")
		(net "M_H_CPU0_SB_CB<3>")
	)
	(segment
		(start 392.632692 -273.763486)
		(end 392.62431 -273.75866)
		(width 0.0889)
		(layer "In13.Cu")
		(net "M_H_CPU0_SB_CB<3>")
	)
	(segment
		(start 382.890776 -273.820636)
		(end 383.0447 -274.086066)
		(width 0.0889)
		(layer "In13.Cu")
		(net "M_H_CPU0_SB_CB<3>")
	)
	(segment
		(start 408.94381 -277.375112)
		(end 408.71521 -277.375112)
		(width 0.14478)
		(layer "In13.Cu")
		(net "M_H_CPU0_SB_CB<3>")
	)
	(segment
		(start 391.326116 -273.75866)
		(end 391.317734 -273.763486)
		(width 0.0889)
		(layer "In13.Cu")
		(net "M_H_CPU0_SB_CB<3>")
	)
	(segment
		(start 407.934922 -276.594824)
		(end 407.68397 -276.845776)
		(width 0.14478)
		(layer "In13.Cu")
		(net "M_H_CPU0_SB_CB<3>")
	)
	(segment
		(start 383.806192 -273.75866)
		(end 383.79781 -273.763486)
		(width 0.0889)
		(layer "In13.Cu")
		(net "M_H_CPU0_SB_CB<3>")
	)
	(segment
		(start 418.972746 -281.060144)
		(end 418.122608 -280.210006)
		(width 0.14478)
		(layer "In13.Cu")
		(net "M_H_CPU0_SB_CB<3>")
	)
	(segment
		(start 407.544778 -275.97608)
		(end 407.383234 -275.814536)
		(width 0.14478)
		(layer "In13.Cu")
		(net "M_H_CPU0_SB_CB<3>")
	)
	(segment
		(start 418.122608 -280.210006)
		(end 414.940242 -280.210006)
		(width 0.14478)
		(layer "In13.Cu")
		(net "M_H_CPU0_SB_CB<3>")
	)
	(segment
		(start 395.965172 -272.38325)
		(end 395.39799 -272.38325)
		(width 0.0889)
		(layer "In13.Cu")
		(net "M_H_CPU0_SB_CB<3>")
	)
	(segment
		(start 382.913128 -273.737324)
		(end 382.890776 -273.820636)
		(width 0.0889)
		(layer "In13.Cu")
		(net "M_H_CPU0_SB_CB<3>")
	)
	(segment
		(start 407.383234 -275.814536)
		(end 407.154634 -275.814536)
		(width 0.14478)
		(layer "In13.Cu")
		(net "M_H_CPU0_SB_CB<3>")
	)
	(segment
		(start 387.566154 -273.75866)
		(end 387.557772 -273.763486)
		(width 0.0889)
		(layer "In13.Cu")
		(net "M_H_CPU0_SB_CB<3>")
	)
	(segment
		(start 394.91412 -272.49247)
		(end 393.861798 -273.544792)
		(width 0.0889)
		(layer "In13.Cu")
		(net "M_H_CPU0_SB_CB<3>")
	)
	(segment
		(start 407.293826 -276.455632)
		(end 407.544778 -276.20468)
		(width 0.14478)
		(layer "In13.Cu")
		(net "M_H_CPU0_SB_CB<3>")
	)
	(segment
		(start 406.675082 -276.065488)
		(end 402.992844 -272.38325)
		(width 0.14478)
		(layer "In13.Cu")
		(net "M_H_CPU0_SB_CB<3>")
	)
	(segment
		(start 395.28877 -272.49247)
		(end 394.91412 -272.49247)
		(width 0.0889)
		(layer "In13.Cu")
		(net "M_H_CPU0_SB_CB<3>")
	)
	(segment
		(start 407.293826 -276.684232)
		(end 407.293826 -276.455632)
		(width 0.14478)
		(layer "In13.Cu")
		(net "M_H_CPU0_SB_CB<3>")
	)
	(segment
		(start 390.751822 -273.763486)
		(end 390.74344 -273.75866)
		(width 0.0889)
		(layer "In13.Cu")
		(net "M_H_CPU0_SB_CB<3>")
	)
	(segment
		(start 391.70229 -273.769582)
		(end 391.691876 -273.763486)
		(width 0.0889)
		(layer "In13.Cu")
		(net "M_H_CPU0_SB_CB<3>")
	)
	(segment
		(start 407.544778 -276.20468)
		(end 407.544778 -275.97608)
		(width 0.14478)
		(layer "In13.Cu")
		(net "M_H_CPU0_SB_CB<3>")
	)
	(segment
		(start 386.99186 -273.763486)
		(end 386.983478 -273.75866)
		(width 0.0889)
		(layer "In13.Cu")
		(net "M_H_CPU0_SB_CB<3>")
	)
	(segment
		(start 414.090104 -281.060144)
		(end 412.628842 -281.060144)
		(width 0.14478)
		(layer "In13.Cu")
		(net "M_H_CPU0_SB_CB<3>")
	)
	(segment
		(start 408.074114 -277.46452)
		(end 408.074114 -277.23592)
		(width 0.14478)
		(layer "In13.Cu")
		(net "M_H_CPU0_SB_CB<3>")
	)
	(arc
		(start 384.737864 -273.763486)
		(mid 384.454908 -273.839663)
		(end 384.171952 -273.763486)
		(width 0.0889)
		(layer "In13.Cu")
		(net "M_H_CPU0_SB_CB<3>")
	)
	(arc
		(start 393.861798 -273.544792)
		(mid 393.637637 -273.669501)
		(end 393.384786 -273.712686)
		(width 0.0889)
		(layer "In13.Cu")
		(net "M_H_CPU0_SB_CB<3>")
	)
	(arc
		(start 388.497826 -273.763486)
		(mid 388.21487 -273.839663)
		(end 387.931914 -273.763486)
		(width 0.0889)
		(layer "In13.Cu")
		(net "M_H_CPU0_SB_CB<3>")
	)
	(arc
		(start 386.043424 -273.75866)
		(mid 385.859916 -273.713166)
		(end 385.677664 -273.763486)
		(width 0.0889)
		(layer "In13.Cu")
		(net "M_H_CPU0_SB_CB<3>")
	)
	(arc
		(start 392.62431 -273.75866)
		(mid 392.440548 -273.713044)
		(end 392.258042 -273.763486)
		(width 0.0889)
		(layer "In13.Cu")
		(net "M_H_CPU0_SB_CB<3>")
	)
	(arc
		(start 389.811768 -273.763486)
		(mid 389.624824 -273.713231)
		(end 389.43788 -273.763486)
		(width 0.0889)
		(layer "In13.Cu")
		(net "M_H_CPU0_SB_CB<3>")
	)
	(arc
		(start 383.231898 -273.763486)
		(mid 383.07546 -273.714515)
		(end 382.913128 -273.737324)
		(width 0.0889)
		(layer "In13.Cu")
		(net "M_H_CPU0_SB_CB<3>")
	)
	(arc
		(start 386.983478 -273.75866)
		(mid 386.79997 -273.713166)
		(end 386.617718 -273.763486)
		(width 0.0889)
		(layer "In13.Cu")
		(net "M_H_CPU0_SB_CB<3>")
	)
	(arc
		(start 389.43788 -273.763486)
		(mid 389.154924 -273.839663)
		(end 388.871968 -273.763486)
		(width 0.0889)
		(layer "In13.Cu")
		(net "M_H_CPU0_SB_CB<3>")
	)
	(arc
		(start 390.37768 -273.763486)
		(mid 390.094724 -273.839663)
		(end 389.811768 -273.763486)
		(width 0.0889)
		(layer "In13.Cu")
		(net "M_H_CPU0_SB_CB<3>")
	)
	(arc
		(start 392.258042 -273.763486)
		(mid 391.980975 -273.839757)
		(end 391.70229 -273.769582)
		(width 0.0889)
		(layer "In13.Cu")
		(net "M_H_CPU0_SB_CB<3>")
	)
	(arc
		(start 393.192508 -273.767042)
		(mid 392.912119 -273.839711)
		(end 392.632692 -273.763486)
		(width 0.0889)
		(layer "In13.Cu")
		(net "M_H_CPU0_SB_CB<3>")
	)
	(arc
		(start 387.557772 -273.763486)
		(mid 387.274816 -273.839663)
		(end 386.99186 -273.763486)
		(width 0.0889)
		(layer "In13.Cu")
		(net "M_H_CPU0_SB_CB<3>")
	)
	(arc
		(start 390.74344 -273.75866)
		(mid 390.559932 -273.713166)
		(end 390.37768 -273.763486)
		(width 0.0889)
		(layer "In13.Cu")
		(net "M_H_CPU0_SB_CB<3>")
	)
	(arc
		(start 391.691876 -273.763486)
		(mid 391.509625 -273.713136)
		(end 391.326116 -273.75866)
		(width 0.0889)
		(layer "In13.Cu")
		(net "M_H_CPU0_SB_CB<3>")
	)
	(arc
		(start 384.171952 -273.763486)
		(mid 383.989701 -273.713136)
		(end 383.806192 -273.75866)
		(width 0.0889)
		(layer "In13.Cu")
		(net "M_H_CPU0_SB_CB<3>")
	)
	(arc
		(start 387.931914 -273.763486)
		(mid 387.749663 -273.713136)
		(end 387.566154 -273.75866)
		(width 0.0889)
		(layer "In13.Cu")
		(net "M_H_CPU0_SB_CB<3>")
	)
	(arc
		(start 386.617718 -273.763486)
		(mid 386.334762 -273.839663)
		(end 386.051806 -273.763486)
		(width 0.0889)
		(layer "In13.Cu")
		(net "M_H_CPU0_SB_CB<3>")
	)
	(arc
		(start 385.111752 -273.763486)
		(mid 384.924808 -273.713231)
		(end 384.737864 -273.763486)
		(width 0.0889)
		(layer "In13.Cu")
		(net "M_H_CPU0_SB_CB<3>")
	)
	(arc
		(start 385.677664 -273.763486)
		(mid 385.394708 -273.839663)
		(end 385.111752 -273.763486)
		(width 0.0889)
		(layer "In13.Cu")
		(net "M_H_CPU0_SB_CB<3>")
	)
	(arc
		(start 383.79781 -273.763486)
		(mid 383.514854 -273.839663)
		(end 383.231898 -273.763486)
		(width 0.0889)
		(layer "In13.Cu")
		(net "M_H_CPU0_SB_CB<3>")
	)
	(arc
		(start 393.384786 -273.712686)
		(mid 393.284932 -273.726729)
		(end 393.192508 -273.767042)
		(width 0.0889)
		(layer "In13.Cu")
		(net "M_H_CPU0_SB_CB<3>")
	)
	(arc
		(start 391.317734 -273.763486)
		(mid 391.034778 -273.839663)
		(end 390.751822 -273.763486)
		(width 0.0889)
		(layer "In13.Cu")
		(net "M_H_CPU0_SB_CB<3>")
	)
	(arc
		(start 388.871968 -273.763486)
		(mid 388.689717 -273.713136)
		(end 388.506208 -273.75866)
		(width 0.0889)
		(layer "In13.Cu")
		(net "M_H_CPU0_SB_CB<3>")
	)
	(segment
		(start 383.988056 -273.010122)
		(end 384.454908 -273.27606)
		(width 0.10668)
		(layer "F.Cu")
		(net "M_H_CPU0_SB_CB<2>")
	)
	(segment
		(start 406.167336 -274.05711)
		(end 405.938736 -274.05711)
		(width 0.14478)
		(layer "In13.Cu")
		(net "M_H_CPU0_SB_CB<2>")
	)
	(segment
		(start 404.60676 -272.496534)
		(end 404.37816 -272.496534)
		(width 0.14478)
		(layer "In13.Cu")
		(net "M_H_CPU0_SB_CB<2>")
	)
	(segment
		(start 411.10281 -277.296372)
		(end 410.15793 -277.296372)
		(width 0.14478)
		(layer "In13.Cu")
		(net "M_H_CPU0_SB_CB<2>")
	)
	(segment
		(start 406.947624 -274.837398)
		(end 406.719024 -274.837398)
		(width 0.14478)
		(layer "In13.Cu")
		(net "M_H_CPU0_SB_CB<2>")
	)
	(segment
		(start 406.038558 -273.177)
		(end 405.877014 -273.015456)
		(width 0.14478)
		(layer "In13.Cu")
		(net "M_H_CPU0_SB_CB<2>")
	)
	(segment
		(start 395.416786 -271.47393)
		(end 395.134846 -271.75587)
		(width 0.0889)
		(layer "In13.Cu")
		(net "M_H_CPU0_SB_CB<2>")
	)
	(segment
		(start 405.777192 -273.895566)
		(end 405.777192 -273.666966)
		(width 0.14478)
		(layer "In13.Cu")
		(net "M_H_CPU0_SB_CB<2>")
	)
	(segment
		(start 405.25827 -272.625312)
		(end 405.25827 -272.396712)
		(width 0.14478)
		(layer "In13.Cu")
		(net "M_H_CPU0_SB_CB<2>")
	)
	(segment
		(start 389.341868 -272.95348)
		(end 389.333486 -272.948654)
		(width 0.0889)
		(layer "In13.Cu")
		(net "M_H_CPU0_SB_CB<2>")
	)
	(segment
		(start 395.936724 -271.47393)
		(end 395.416786 -271.47393)
		(width 0.0889)
		(layer "In13.Cu")
		(net "M_H_CPU0_SB_CB<2>")
	)
	(segment
		(start 392.744198 -272.942558)
		(end 392.725402 -272.95348)
		(width 0.0889)
		(layer "In13.Cu")
		(net "M_H_CPU0_SB_CB<2>")
	)
	(segment
		(start 395.134846 -271.75587)
		(end 394.949426 -271.75587)
		(width 0.0889)
		(layer "In13.Cu")
		(net "M_H_CPU0_SB_CB<2>")
	)
	(segment
		(start 407.43759 -274.576032)
		(end 407.20899 -274.576032)
		(width 0.14478)
		(layer "In13.Cu")
		(net "M_H_CPU0_SB_CB<2>")
	)
	(segment
		(start 405.777192 -273.666966)
		(end 406.038558 -273.4056)
		(width 0.14478)
		(layer "In13.Cu")
		(net "M_H_CPU0_SB_CB<2>")
	)
	(segment
		(start 404.216616 -272.10639)
		(end 404.477982 -271.845024)
		(width 0.14478)
		(layer "In13.Cu")
		(net "M_H_CPU0_SB_CB<2>")
	)
	(segment
		(start 414.940242 -278.509984)
		(end 414.090104 -279.360122)
		(width 0.14478)
		(layer "In13.Cu")
		(net "M_H_CPU0_SB_CB<2>")
	)
	(segment
		(start 406.55748 -274.675854)
		(end 406.55748 -274.447254)
		(width 0.14478)
		(layer "In13.Cu")
		(net "M_H_CPU0_SB_CB<2>")
	)
	(segment
		(start 404.477982 -271.616424)
		(end 404.335488 -271.47393)
		(width 0.14478)
		(layer "In13.Cu")
		(net "M_H_CPU0_SB_CB<2>")
	)
	(segment
		(start 413.16656 -279.360122)
		(end 411.10281 -277.296372)
		(width 0.14478)
		(layer "In13.Cu")
		(net "M_H_CPU0_SB_CB<2>")
	)
	(segment
		(start 392.182604 -272.96618)
		(end 392.161014 -272.953734)
		(width 0.0889)
		(layer "In13.Cu")
		(net "M_H_CPU0_SB_CB<2>")
	)
	(segment
		(start 417.825936 -278.509984)
		(end 414.940242 -278.509984)
		(width 0.14478)
		(layer "In13.Cu")
		(net "M_H_CPU0_SB_CB<2>")
	)
	(segment
		(start 405.387048 -273.276822)
		(end 405.158448 -273.276822)
		(width 0.14478)
		(layer "In13.Cu")
		(net "M_H_CPU0_SB_CB<2>")
	)
	(segment
		(start 404.335488 -271.47393)
		(end 395.936724 -271.47393)
		(width 0.14478)
		(layer "In13.Cu")
		(net "M_H_CPU0_SB_CB<2>")
	)
	(segment
		(start 405.648414 -273.015456)
		(end 405.387048 -273.276822)
		(width 0.14478)
		(layer "In13.Cu")
		(net "M_H_CPU0_SB_CB<2>")
	)
	(segment
		(start 404.216616 -272.33499)
		(end 404.216616 -272.10639)
		(width 0.14478)
		(layer "In13.Cu")
		(net "M_H_CPU0_SB_CB<2>")
	)
	(segment
		(start 414.090104 -279.360122)
		(end 413.16656 -279.360122)
		(width 0.14478)
		(layer "In13.Cu")
		(net "M_H_CPU0_SB_CB<2>")
	)
	(segment
		(start 419.912038 -278.93518)
		(end 419.487096 -279.360122)
		(width 0.14478)
		(layer "In13.Cu")
		(net "M_H_CPU0_SB_CB<2>")
	)
	(segment
		(start 394.949426 -271.75587)
		(end 393.8651 -272.840196)
		(width 0.0889)
		(layer "In13.Cu")
		(net "M_H_CPU0_SB_CB<2>")
	)
	(segment
		(start 406.818846 -274.185888)
		(end 406.818846 -273.957288)
		(width 0.14478)
		(layer "In13.Cu")
		(net "M_H_CPU0_SB_CB<2>")
	)
	(segment
		(start 389.916162 -272.948654)
		(end 389.90778 -272.95348)
		(width 0.0889)
		(layer "In13.Cu")
		(net "M_H_CPU0_SB_CB<2>")
	)
	(segment
		(start 406.719024 -274.837398)
		(end 406.55748 -274.675854)
		(width 0.14478)
		(layer "In13.Cu")
		(net "M_H_CPU0_SB_CB<2>")
	)
	(segment
		(start 406.55748 -274.447254)
		(end 406.818846 -274.185888)
		(width 0.14478)
		(layer "In13.Cu")
		(net "M_H_CPU0_SB_CB<2>")
	)
	(segment
		(start 405.158448 -273.276822)
		(end 404.996904 -273.115278)
		(width 0.14478)
		(layer "In13.Cu")
		(net "M_H_CPU0_SB_CB<2>")
	)
	(segment
		(start 405.877014 -273.015456)
		(end 405.648414 -273.015456)
		(width 0.14478)
		(layer "In13.Cu")
		(net "M_H_CPU0_SB_CB<2>")
	)
	(segment
		(start 384.641852 -272.95348)
		(end 384.63347 -272.948654)
		(width 0.0889)
		(layer "In13.Cu")
		(net "M_H_CPU0_SB_CB<2>")
	)
	(segment
		(start 404.37816 -272.496534)
		(end 404.216616 -272.33499)
		(width 0.14478)
		(layer "In13.Cu")
		(net "M_H_CPU0_SB_CB<2>")
	)
	(segment
		(start 406.818846 -273.957288)
		(end 406.657302 -273.795744)
		(width 0.14478)
		(layer "In13.Cu")
		(net "M_H_CPU0_SB_CB<2>")
	)
	(segment
		(start 405.25827 -272.396712)
		(end 405.096726 -272.235168)
		(width 0.14478)
		(layer "In13.Cu")
		(net "M_H_CPU0_SB_CB<2>")
	)
	(segment
		(start 384.30073 -273.01063)
		(end 384.454908 -273.27606)
		(width 0.0889)
		(layer "In13.Cu")
		(net "M_H_CPU0_SB_CB<2>")
	)
	(segment
		(start 406.428702 -273.795744)
		(end 406.167336 -274.05711)
		(width 0.14478)
		(layer "In13.Cu")
		(net "M_H_CPU0_SB_CB<2>")
	)
	(segment
		(start 385.216146 -272.948654)
		(end 385.207764 -272.95348)
		(width 0.0889)
		(layer "In13.Cu")
		(net "M_H_CPU0_SB_CB<2>")
	)
	(segment
		(start 410.15793 -277.296372)
		(end 407.43759 -274.576032)
		(width 0.14478)
		(layer "In13.Cu")
		(net "M_H_CPU0_SB_CB<2>")
	)
	(segment
		(start 386.1562 -272.948654)
		(end 386.147818 -272.95348)
		(width 0.0889)
		(layer "In13.Cu")
		(net "M_H_CPU0_SB_CB<2>")
	)
	(segment
		(start 419.487096 -279.360122)
		(end 418.676074 -279.360122)
		(width 0.14478)
		(layer "In13.Cu")
		(net "M_H_CPU0_SB_CB<2>")
	)
	(segment
		(start 407.20899 -274.576032)
		(end 406.947624 -274.837398)
		(width 0.14478)
		(layer "In13.Cu")
		(net "M_H_CPU0_SB_CB<2>")
	)
	(segment
		(start 405.938736 -274.05711)
		(end 405.777192 -273.895566)
		(width 0.14478)
		(layer "In13.Cu")
		(net "M_H_CPU0_SB_CB<2>")
	)
	(segment
		(start 405.096726 -272.235168)
		(end 404.868126 -272.235168)
		(width 0.14478)
		(layer "In13.Cu")
		(net "M_H_CPU0_SB_CB<2>")
	)
	(segment
		(start 388.401814 -272.95348)
		(end 388.393432 -272.948654)
		(width 0.0889)
		(layer "In13.Cu")
		(net "M_H_CPU0_SB_CB<2>")
	)
	(segment
		(start 406.657302 -273.795744)
		(end 406.428702 -273.795744)
		(width 0.14478)
		(layer "In13.Cu")
		(net "M_H_CPU0_SB_CB<2>")
	)
	(segment
		(start 418.676074 -279.360122)
		(end 417.825936 -278.509984)
		(width 0.14478)
		(layer "In13.Cu")
		(net "M_H_CPU0_SB_CB<2>")
	)
	(segment
		(start 404.996904 -272.886678)
		(end 405.25827 -272.625312)
		(width 0.14478)
		(layer "In13.Cu")
		(net "M_H_CPU0_SB_CB<2>")
	)
	(segment
		(start 404.477982 -271.845024)
		(end 404.477982 -271.616424)
		(width 0.14478)
		(layer "In13.Cu")
		(net "M_H_CPU0_SB_CB<2>")
	)
	(segment
		(start 404.996904 -273.115278)
		(end 404.996904 -272.886678)
		(width 0.14478)
		(layer "In13.Cu")
		(net "M_H_CPU0_SB_CB<2>")
	)
	(segment
		(start 384.323082 -272.927318)
		(end 384.30073 -273.01063)
		(width 0.0889)
		(layer "In13.Cu")
		(net "M_H_CPU0_SB_CB<2>")
	)
	(segment
		(start 404.868126 -272.235168)
		(end 404.60676 -272.496534)
		(width 0.14478)
		(layer "In13.Cu")
		(net "M_H_CPU0_SB_CB<2>")
	)
	(segment
		(start 406.038558 -273.4056)
		(end 406.038558 -273.177)
		(width 0.14478)
		(layer "In13.Cu")
		(net "M_H_CPU0_SB_CB<2>")
	)
	(segment
		(start 392.161014 -272.953734)
		(end 392.140948 -272.942304)
		(width 0.0889)
		(layer "In13.Cu")
		(net "M_H_CPU0_SB_CB<2>")
	)
	(arc
		(start 387.46176 -272.95348)
		(mid 387.274816 -272.903225)
		(end 387.087872 -272.95348)
		(width 0.0889)
		(layer "In13.Cu")
		(net "M_H_CPU0_SB_CB<2>")
	)
	(arc
		(start 392.140948 -272.942304)
		(mid 391.96287 -272.90332)
		(end 391.787634 -272.95348)
		(width 0.0889)
		(layer "In13.Cu")
		(net "M_H_CPU0_SB_CB<2>")
	)
	(arc
		(start 392.725402 -272.95348)
		(mid 392.455633 -273.029503)
		(end 392.182604 -272.96618)
		(width 0.0889)
		(layer "In13.Cu")
		(net "M_H_CPU0_SB_CB<2>")
	)
	(arc
		(start 390.281922 -272.95348)
		(mid 390.099671 -272.90313)
		(end 389.916162 -272.948654)
		(width 0.0889)
		(layer "In13.Cu")
		(net "M_H_CPU0_SB_CB<2>")
	)
	(arc
		(start 387.087872 -272.95348)
		(mid 386.804916 -273.029657)
		(end 386.52196 -272.95348)
		(width 0.0889)
		(layer "In13.Cu")
		(net "M_H_CPU0_SB_CB<2>")
	)
	(arc
		(start 393.10056 -272.95348)
		(mid 392.923769 -272.902761)
		(end 392.744198 -272.942558)
		(width 0.0889)
		(layer "In13.Cu")
		(net "M_H_CPU0_SB_CB<2>")
	)
	(arc
		(start 393.634468 -272.972022)
		(mid 393.365183 -273.029934)
		(end 393.10056 -272.95348)
		(width 0.0889)
		(layer "In13.Cu")
		(net "M_H_CPU0_SB_CB<2>")
	)
	(arc
		(start 388.967726 -272.95348)
		(mid 388.68477 -273.029657)
		(end 388.401814 -272.95348)
		(width 0.0889)
		(layer "In13.Cu")
		(net "M_H_CPU0_SB_CB<2>")
	)
	(arc
		(start 391.787634 -272.95348)
		(mid 391.504678 -273.029657)
		(end 391.221722 -272.95348)
		(width 0.0889)
		(layer "In13.Cu")
		(net "M_H_CPU0_SB_CB<2>")
	)
	(arc
		(start 389.333486 -272.948654)
		(mid 389.149978 -272.90316)
		(end 388.967726 -272.95348)
		(width 0.0889)
		(layer "In13.Cu")
		(net "M_H_CPU0_SB_CB<2>")
	)
	(arc
		(start 386.147818 -272.95348)
		(mid 385.864862 -273.029657)
		(end 385.581906 -272.95348)
		(width 0.0889)
		(layer "In13.Cu")
		(net "M_H_CPU0_SB_CB<2>")
	)
	(arc
		(start 385.581906 -272.95348)
		(mid 385.399655 -272.90313)
		(end 385.216146 -272.948654)
		(width 0.0889)
		(layer "In13.Cu")
		(net "M_H_CPU0_SB_CB<2>")
	)
	(arc
		(start 389.90778 -272.95348)
		(mid 389.624824 -273.029657)
		(end 389.341868 -272.95348)
		(width 0.0889)
		(layer "In13.Cu")
		(net "M_H_CPU0_SB_CB<2>")
	)
	(arc
		(start 388.027672 -272.95348)
		(mid 387.744716 -273.029657)
		(end 387.46176 -272.95348)
		(width 0.0889)
		(layer "In13.Cu")
		(net "M_H_CPU0_SB_CB<2>")
	)
	(arc
		(start 393.8651 -272.840196)
		(mid 393.758607 -272.921546)
		(end 393.634468 -272.972022)
		(width 0.0889)
		(layer "In13.Cu")
		(net "M_H_CPU0_SB_CB<2>")
	)
	(arc
		(start 390.847834 -272.95348)
		(mid 390.564878 -273.029657)
		(end 390.281922 -272.95348)
		(width 0.0889)
		(layer "In13.Cu")
		(net "M_H_CPU0_SB_CB<2>")
	)
	(arc
		(start 386.52196 -272.95348)
		(mid 386.339709 -272.90313)
		(end 386.1562 -272.948654)
		(width 0.0889)
		(layer "In13.Cu")
		(net "M_H_CPU0_SB_CB<2>")
	)
	(arc
		(start 384.63347 -272.948654)
		(mid 384.4806 -272.904013)
		(end 384.323082 -272.927318)
		(width 0.0889)
		(layer "In13.Cu")
		(net "M_H_CPU0_SB_CB<2>")
	)
	(arc
		(start 385.207764 -272.95348)
		(mid 384.924808 -273.029657)
		(end 384.641852 -272.95348)
		(width 0.0889)
		(layer "In13.Cu")
		(net "M_H_CPU0_SB_CB<2>")
	)
	(arc
		(start 388.393432 -272.948654)
		(mid 388.209924 -272.90316)
		(end 388.027672 -272.95348)
		(width 0.0889)
		(layer "In13.Cu")
		(net "M_H_CPU0_SB_CB<2>")
	)
	(arc
		(start 391.221722 -272.95348)
		(mid 391.034778 -272.903225)
		(end 390.847834 -272.95348)
		(width 0.0889)
		(layer "In13.Cu")
		(net "M_H_CPU0_SB_CB<2>")
	)
	(segment
		(start 382.107948 -273.010122)
		(end 382.5748 -273.27606)
		(width 0.10668)
		(layer "F.Cu")
		(net "M_H_CPU0_SB_CB<1>")
	)
	(segment
		(start 382.824736 -273.56689)
		(end 382.728724 -273.54149)
		(width 0.0889)
		(layer "In13.Cu")
		(net "M_H_CPU0_SB_CB<1>")
	)
	(segment
		(start 410.308806 -278.083264)
		(end 407.51252 -275.286978)
		(width 0.14478)
		(layer "In13.Cu")
		(net "M_H_CPU0_SB_CB<1>")
	)
	(segment
		(start 383.701798 -273.59864)
		(end 383.693416 -273.603466)
		(width 0.0889)
		(layer "In13.Cu")
		(net "M_H_CPU0_SB_CB<1>")
	)
	(segment
		(start 382.728724 -273.54149)
		(end 382.5748 -273.27606)
		(width 0.0889)
		(layer "In13.Cu")
		(net "M_H_CPU0_SB_CB<1>")
	)
	(segment
		(start 406.532588 -275.286978)
		(end 403.1742 -271.92859)
		(width 0.14478)
		(layer "In13.Cu")
		(net "M_H_CPU0_SB_CB<1>")
	)
	(segment
		(start 393.384532 -273.521932)
		(end 393.384278 -273.521932)
		(width 0.0889)
		(layer "In13.Cu")
		(net "M_H_CPU0_SB_CB<1>")
	)
	(segment
		(start 419.476428 -280.210006)
		(end 417.424616 -279.360122)
		(width 0.14478)
		(layer "In13.Cu")
		(net "M_H_CPU0_SB_CB<1>")
	)
	(segment
		(start 384.641852 -273.59864)
		(end 384.63347 -273.603466)
		(width 0.0889)
		(layer "In13.Cu")
		(net "M_H_CPU0_SB_CB<1>")
	)
	(segment
		(start 424.012106 -279.785064)
		(end 420.935658 -280.210006)
		(width 0.14478)
		(layer "In13.Cu")
		(net "M_H_CPU0_SB_CB<1>")
	)
	(segment
		(start 388.401814 -273.59864)
		(end 388.393432 -273.603466)
		(width 0.0889)
		(layer "In13.Cu")
		(net "M_H_CPU0_SB_CB<1>")
	)
	(segment
		(start 403.1742 -271.92859)
		(end 395.965172 -271.92859)
		(width 0.14478)
		(layer "In13.Cu")
		(net "M_H_CPU0_SB_CB<1>")
	)
	(segment
		(start 407.51252 -275.286978)
		(end 406.532588 -275.286978)
		(width 0.14478)
		(layer "In13.Cu")
		(net "M_H_CPU0_SB_CB<1>")
	)
	(segment
		(start 394.987272 -272.14957)
		(end 393.734798 -273.402044)
		(width 0.0889)
		(layer "In13.Cu")
		(net "M_H_CPU0_SB_CB<1>")
	)
	(segment
		(start 386.1562 -273.603466)
		(end 386.147818 -273.59864)
		(width 0.0889)
		(layer "In13.Cu")
		(net "M_H_CPU0_SB_CB<1>")
	)
	(segment
		(start 391.796016 -273.603466)
		(end 391.787634 -273.59864)
		(width 0.0889)
		(layer "In13.Cu")
		(net "M_H_CPU0_SB_CB<1>")
	)
	(segment
		(start 420.935658 -280.210006)
		(end 419.476428 -280.210006)
		(width 0.14478)
		(layer "In13.Cu")
		(net "M_H_CPU0_SB_CB<1>")
	)
	(segment
		(start 395.174216 -272.14957)
		(end 394.987272 -272.14957)
		(width 0.0889)
		(layer "In13.Cu")
		(net "M_H_CPU0_SB_CB<1>")
	)
	(segment
		(start 415.36112 -279.360122)
		(end 414.275524 -279.809702)
		(width 0.14478)
		(layer "In13.Cu")
		(net "M_H_CPU0_SB_CB<1>")
	)
	(segment
		(start 389.341868 -273.59864)
		(end 389.333486 -273.603466)
		(width 0.0889)
		(layer "In13.Cu")
		(net "M_H_CPU0_SB_CB<1>")
	)
	(segment
		(start 395.965172 -271.92859)
		(end 395.395196 -271.92859)
		(width 0.0889)
		(layer "In13.Cu")
		(net "M_H_CPU0_SB_CB<1>")
	)
	(segment
		(start 385.216146 -273.603466)
		(end 385.207764 -273.59864)
		(width 0.0889)
		(layer "In13.Cu")
		(net "M_H_CPU0_SB_CB<1>")
	)
	(segment
		(start 395.395196 -271.92859)
		(end 395.174216 -272.14957)
		(width 0.0889)
		(layer "In13.Cu")
		(net "M_H_CPU0_SB_CB<1>")
	)
	(segment
		(start 414.275524 -279.809702)
		(end 412.980124 -279.809702)
		(width 0.14478)
		(layer "In13.Cu")
		(net "M_H_CPU0_SB_CB<1>")
	)
	(segment
		(start 417.424616 -279.360122)
		(end 415.36112 -279.360122)
		(width 0.14478)
		(layer "In13.Cu")
		(net "M_H_CPU0_SB_CB<1>")
	)
	(segment
		(start 412.980124 -279.809702)
		(end 411.92196 -278.751538)
		(width 0.14478)
		(layer "In13.Cu")
		(net "M_H_CPU0_SB_CB<1>")
	)
	(segment
		(start 389.916162 -273.603466)
		(end 389.90778 -273.59864)
		(width 0.0889)
		(layer "In13.Cu")
		(net "M_H_CPU0_SB_CB<1>")
	)
	(segment
		(start 411.92196 -278.751538)
		(end 410.308806 -278.083264)
		(width 0.14478)
		(layer "In13.Cu")
		(net "M_H_CPU0_SB_CB<1>")
	)
	(segment
		(start 392.72845 -273.59864)
		(end 392.718036 -273.592544)
		(width 0.0889)
		(layer "In13.Cu")
		(net "M_H_CPU0_SB_CB<1>")
	)
	(arc
		(start 387.46176 -273.59864)
		(mid 387.274816 -273.648895)
		(end 387.087872 -273.59864)
		(width 0.0889)
		(layer "In13.Cu")
		(net "M_H_CPU0_SB_CB<1>")
	)
	(arc
		(start 393.734798 -273.402044)
		(mid 393.569649 -273.491152)
		(end 393.384532 -273.521932)
		(width 0.0889)
		(layer "In13.Cu")
		(net "M_H_CPU0_SB_CB<1>")
	)
	(arc
		(start 392.718036 -273.592544)
		(mid 392.43935 -273.522324)
		(end 392.162284 -273.59864)
		(width 0.0889)
		(layer "In13.Cu")
		(net "M_H_CPU0_SB_CB<1>")
	)
	(arc
		(start 388.027672 -273.59864)
		(mid 387.744716 -273.522463)
		(end 387.46176 -273.59864)
		(width 0.0889)
		(layer "In13.Cu")
		(net "M_H_CPU0_SB_CB<1>")
	)
	(arc
		(start 393.384278 -273.521932)
		(mid 393.346216 -273.523322)
		(end 393.308332 -273.527266)
		(width 0.0889)
		(layer "In13.Cu")
		(net "M_H_CPU0_SB_CB<1>")
	)
	(arc
		(start 389.333486 -273.603466)
		(mid 389.149978 -273.64896)
		(end 388.967726 -273.59864)
		(width 0.0889)
		(layer "In13.Cu")
		(net "M_H_CPU0_SB_CB<1>")
	)
	(arc
		(start 384.26771 -273.59864)
		(mid 383.984754 -273.522463)
		(end 383.701798 -273.59864)
		(width 0.0889)
		(layer "In13.Cu")
		(net "M_H_CPU0_SB_CB<1>")
	)
	(arc
		(start 389.90778 -273.59864)
		(mid 389.624824 -273.522463)
		(end 389.341868 -273.59864)
		(width 0.0889)
		(layer "In13.Cu")
		(net "M_H_CPU0_SB_CB<1>")
	)
	(arc
		(start 386.147818 -273.59864)
		(mid 385.864862 -273.522463)
		(end 385.581906 -273.59864)
		(width 0.0889)
		(layer "In13.Cu")
		(net "M_H_CPU0_SB_CB<1>")
	)
	(arc
		(start 392.162284 -273.59864)
		(mid 391.979779 -273.649117)
		(end 391.796016 -273.603466)
		(width 0.0889)
		(layer "In13.Cu")
		(net "M_H_CPU0_SB_CB<1>")
	)
	(arc
		(start 390.847834 -273.59864)
		(mid 390.564878 -273.522463)
		(end 390.281922 -273.59864)
		(width 0.0889)
		(layer "In13.Cu")
		(net "M_H_CPU0_SB_CB<1>")
	)
	(arc
		(start 393.308332 -273.527266)
		(mid 393.192939 -273.555746)
		(end 393.086082 -273.607784)
		(width 0.0889)
		(layer "In13.Cu")
		(net "M_H_CPU0_SB_CB<1>")
	)
	(arc
		(start 388.393432 -273.603466)
		(mid 388.209924 -273.64896)
		(end 388.027672 -273.59864)
		(width 0.0889)
		(layer "In13.Cu")
		(net "M_H_CPU0_SB_CB<1>")
	)
	(arc
		(start 390.281922 -273.59864)
		(mid 390.099671 -273.64899)
		(end 389.916162 -273.603466)
		(width 0.0889)
		(layer "In13.Cu")
		(net "M_H_CPU0_SB_CB<1>")
	)
	(arc
		(start 383.327656 -273.59864)
		(mid 383.079943 -273.52342)
		(end 382.824736 -273.56689)
		(width 0.0889)
		(layer "In13.Cu")
		(net "M_H_CPU0_SB_CB<1>")
	)
	(arc
		(start 383.693416 -273.603466)
		(mid 383.509908 -273.64896)
		(end 383.327656 -273.59864)
		(width 0.0889)
		(layer "In13.Cu")
		(net "M_H_CPU0_SB_CB<1>")
	)
	(arc
		(start 388.967726 -273.59864)
		(mid 388.68477 -273.522463)
		(end 388.401814 -273.59864)
		(width 0.0889)
		(layer "In13.Cu")
		(net "M_H_CPU0_SB_CB<1>")
	)
	(arc
		(start 391.221722 -273.59864)
		(mid 391.034778 -273.648895)
		(end 390.847834 -273.59864)
		(width 0.0889)
		(layer "In13.Cu")
		(net "M_H_CPU0_SB_CB<1>")
	)
	(arc
		(start 385.581906 -273.59864)
		(mid 385.399655 -273.64899)
		(end 385.216146 -273.603466)
		(width 0.0889)
		(layer "In13.Cu")
		(net "M_H_CPU0_SB_CB<1>")
	)
	(arc
		(start 386.52196 -273.59864)
		(mid 386.339709 -273.64899)
		(end 386.1562 -273.603466)
		(width 0.0889)
		(layer "In13.Cu")
		(net "M_H_CPU0_SB_CB<1>")
	)
	(arc
		(start 384.63347 -273.603466)
		(mid 384.449962 -273.64896)
		(end 384.26771 -273.59864)
		(width 0.0889)
		(layer "In13.Cu")
		(net "M_H_CPU0_SB_CB<1>")
	)
	(arc
		(start 391.787634 -273.59864)
		(mid 391.504678 -273.522463)
		(end 391.221722 -273.59864)
		(width 0.0889)
		(layer "In13.Cu")
		(net "M_H_CPU0_SB_CB<1>")
	)
	(arc
		(start 385.207764 -273.59864)
		(mid 384.924808 -273.522463)
		(end 384.641852 -273.59864)
		(width 0.0889)
		(layer "In13.Cu")
		(net "M_H_CPU0_SB_CB<1>")
	)
	(arc
		(start 393.086082 -273.607784)
		(mid 392.9061 -273.648884)
		(end 392.72845 -273.59864)
		(width 0.0889)
		(layer "In13.Cu")
		(net "M_H_CPU0_SB_CB<1>")
	)
	(arc
		(start 387.087872 -273.59864)
		(mid 386.804916 -273.522463)
		(end 386.52196 -273.59864)
		(width 0.0889)
		(layer "In13.Cu")
		(net "M_H_CPU0_SB_CB<1>")
	)
	(segment
		(start 383.517902 -272.200116)
		(end 383.984754 -272.466054)
		(width 0.10668)
		(layer "F.Cu")
		(net "M_H_CPU0_SB_CB<0>")
	)
	(segment
		(start 392.256264 -272.78838)
		(end 392.234674 -272.775934)
		(width 0.0889)
		(layer "In13.Cu")
		(net "M_H_CPU0_SB_CB<0>")
	)
	(segment
		(start 392.652758 -272.774918)
		(end 392.62939 -272.788634)
		(width 0.0889)
		(layer "In13.Cu")
		(net "M_H_CPU0_SB_CB<0>")
	)
	(segment
		(start 393.570714 -272.78838)
		(end 393.543282 -272.804128)
		(width 0.0889)
		(layer "In13.Cu")
		(net "M_H_CPU0_SB_CB<0>")
	)
	(segment
		(start 386.99186 -272.788634)
		(end 386.983478 -272.79346)
		(width 0.0889)
		(layer "In13.Cu")
		(net "M_H_CPU0_SB_CB<0>")
	)
	(segment
		(start 411.289246 -276.846792)
		(end 410.347414 -276.846792)
		(width 0.14478)
		(layer "In13.Cu")
		(net "M_H_CPU0_SB_CB<0>")
	)
	(segment
		(start 395.642084 -270.867124)
		(end 394.96238 -270.867124)
		(width 0.0889)
		(layer "In13.Cu")
		(net "M_H_CPU0_SB_CB<0>")
	)
	(segment
		(start 387.566154 -272.79346)
		(end 387.557772 -272.788634)
		(width 0.0889)
		(layer "In13.Cu")
		(net "M_H_CPU0_SB_CB<0>")
	)
	(segment
		(start 390.751822 -272.788634)
		(end 390.74344 -272.79346)
		(width 0.0889)
		(layer "In13.Cu")
		(net "M_H_CPU0_SB_CB<0>")
	)
	(segment
		(start 386.051806 -272.788634)
		(end 386.043424 -272.79346)
		(width 0.0889)
		(layer "In13.Cu")
		(net "M_H_CPU0_SB_CB<0>")
	)
	(segment
		(start 388.506208 -272.79346)
		(end 388.497826 -272.788634)
		(width 0.0889)
		(layer "In13.Cu")
		(net "M_H_CPU0_SB_CB<0>")
	)
	(segment
		(start 421.71747 -278.51989)
		(end 418.550344 -278.51989)
		(width 0.14478)
		(layer "In13.Cu")
		(net "M_H_CPU0_SB_CB<0>")
	)
	(segment
		(start 384.235198 -272.756884)
		(end 384.138932 -272.731484)
		(width 0.0889)
		(layer "In13.Cu")
		(net "M_H_CPU0_SB_CB<0>")
	)
	(segment
		(start 412.952692 -278.510238)
		(end 411.289246 -276.846792)
		(width 0.14478)
		(layer "In13.Cu")
		(net "M_H_CPU0_SB_CB<0>")
	)
	(segment
		(start 410.347414 -276.846792)
		(end 404.519892 -271.01927)
		(width 0.14478)
		(layer "In13.Cu")
		(net "M_H_CPU0_SB_CB<0>")
	)
	(segment
		(start 395.79423 -271.01927)
		(end 395.642084 -270.867124)
		(width 0.14478)
		(layer "In13.Cu")
		(net "M_H_CPU0_SB_CB<0>")
	)
	(segment
		(start 394.584174 -271.24533)
		(end 394.584174 -271.789144)
		(width 0.0889)
		(layer "In13.Cu")
		(net "M_H_CPU0_SB_CB<0>")
	)
	(segment
		(start 392.274552 -272.798794)
		(end 392.256264 -272.78838)
		(width 0.0889)
		(layer "In13.Cu")
		(net "M_H_CPU0_SB_CB<0>")
	)
	(segment
		(start 418.550344 -278.51989)
		(end 418.090858 -278.060404)
		(width 0.14478)
		(layer "In13.Cu")
		(net "M_H_CPU0_SB_CB<0>")
	)
	(segment
		(start 394.584174 -271.789144)
		(end 393.648184 -272.725134)
		(width 0.0889)
		(layer "In13.Cu")
		(net "M_H_CPU0_SB_CB<0>")
	)
	(segment
		(start 424.012106 -278.085042)
		(end 421.71747 -278.51989)
		(width 0.14478)
		(layer "In13.Cu")
		(net "M_H_CPU0_SB_CB<0>")
	)
	(segment
		(start 404.519892 -271.01927)
		(end 395.79423 -271.01927)
		(width 0.14478)
		(layer "In13.Cu")
		(net "M_H_CPU0_SB_CB<0>")
	)
	(segment
		(start 418.090858 -278.060404)
		(end 414.632902 -278.060404)
		(width 0.14478)
		(layer "In13.Cu")
		(net "M_H_CPU0_SB_CB<0>")
	)
	(segment
		(start 414.632902 -278.060404)
		(end 414.183068 -278.510238)
		(width 0.14478)
		(layer "In13.Cu")
		(net "M_H_CPU0_SB_CB<0>")
	)
	(segment
		(start 414.183068 -278.510238)
		(end 412.952692 -278.510238)
		(width 0.14478)
		(layer "In13.Cu")
		(net "M_H_CPU0_SB_CB<0>")
	)
	(segment
		(start 391.326116 -272.79346)
		(end 391.317734 -272.788634)
		(width 0.0889)
		(layer "In13.Cu")
		(net "M_H_CPU0_SB_CB<0>")
	)
	(segment
		(start 394.96238 -270.867124)
		(end 394.584174 -271.24533)
		(width 0.0889)
		(layer "In13.Cu")
		(net "M_H_CPU0_SB_CB<0>")
	)
	(segment
		(start 384.138932 -272.731484)
		(end 383.984754 -272.466054)
		(width 0.0889)
		(layer "In13.Cu")
		(net "M_H_CPU0_SB_CB<0>")
	)
	(arc
		(start 391.317734 -272.788634)
		(mid 391.034778 -272.712457)
		(end 390.751822 -272.788634)
		(width 0.0889)
		(layer "In13.Cu")
		(net "M_H_CPU0_SB_CB<0>")
	)
	(arc
		(start 387.557772 -272.788634)
		(mid 387.274816 -272.712457)
		(end 386.99186 -272.788634)
		(width 0.0889)
		(layer "In13.Cu")
		(net "M_H_CPU0_SB_CB<0>")
	)
	(arc
		(start 393.543282 -272.804128)
		(mid 393.368031 -272.839061)
		(end 393.196572 -272.788634)
		(width 0.0889)
		(layer "In13.Cu")
		(net "M_H_CPU0_SB_CB<0>")
	)
	(arc
		(start 390.74344 -272.79346)
		(mid 390.559932 -272.838954)
		(end 390.37768 -272.788634)
		(width 0.0889)
		(layer "In13.Cu")
		(net "M_H_CPU0_SB_CB<0>")
	)
	(arc
		(start 389.811768 -272.788634)
		(mid 389.624824 -272.838889)
		(end 389.43788 -272.788634)
		(width 0.0889)
		(layer "In13.Cu")
		(net "M_H_CPU0_SB_CB<0>")
	)
	(arc
		(start 393.648184 -272.725134)
		(mid 393.611043 -272.75871)
		(end 393.570714 -272.78838)
		(width 0.0889)
		(layer "In13.Cu")
		(net "M_H_CPU0_SB_CB<0>")
	)
	(arc
		(start 388.871968 -272.788634)
		(mid 388.689717 -272.838984)
		(end 388.506208 -272.79346)
		(width 0.0889)
		(layer "In13.Cu")
		(net "M_H_CPU0_SB_CB<0>")
	)
	(arc
		(start 391.691876 -272.788634)
		(mid 391.509625 -272.838984)
		(end 391.326116 -272.79346)
		(width 0.0889)
		(layer "In13.Cu")
		(net "M_H_CPU0_SB_CB<0>")
	)
	(arc
		(start 386.983478 -272.79346)
		(mid 386.79997 -272.838954)
		(end 386.617718 -272.788634)
		(width 0.0889)
		(layer "In13.Cu")
		(net "M_H_CPU0_SB_CB<0>")
	)
	(arc
		(start 390.37768 -272.788634)
		(mid 390.094724 -272.712457)
		(end 389.811768 -272.788634)
		(width 0.0889)
		(layer "In13.Cu")
		(net "M_H_CPU0_SB_CB<0>")
	)
	(arc
		(start 386.617718 -272.788634)
		(mid 386.334762 -272.712457)
		(end 386.051806 -272.788634)
		(width 0.0889)
		(layer "In13.Cu")
		(net "M_H_CPU0_SB_CB<0>")
	)
	(arc
		(start 389.43788 -272.788634)
		(mid 389.154924 -272.712457)
		(end 388.871968 -272.788634)
		(width 0.0889)
		(layer "In13.Cu")
		(net "M_H_CPU0_SB_CB<0>")
	)
	(arc
		(start 387.931914 -272.788634)
		(mid 387.749663 -272.838984)
		(end 387.566154 -272.79346)
		(width 0.0889)
		(layer "In13.Cu")
		(net "M_H_CPU0_SB_CB<0>")
	)
	(arc
		(start 384.737864 -272.788634)
		(mid 384.490268 -272.713456)
		(end 384.235198 -272.756884)
		(width 0.0889)
		(layer "In13.Cu")
		(net "M_H_CPU0_SB_CB<0>")
	)
	(arc
		(start 388.497826 -272.788634)
		(mid 388.21487 -272.712457)
		(end 387.931914 -272.788634)
		(width 0.0889)
		(layer "In13.Cu")
		(net "M_H_CPU0_SB_CB<0>")
	)
	(arc
		(start 385.111752 -272.788634)
		(mid 384.924808 -272.838889)
		(end 384.737864 -272.788634)
		(width 0.0889)
		(layer "In13.Cu")
		(net "M_H_CPU0_SB_CB<0>")
	)
	(arc
		(start 393.196572 -272.788634)
		(mid 392.926415 -272.711872)
		(end 392.652758 -272.774918)
		(width 0.0889)
		(layer "In13.Cu")
		(net "M_H_CPU0_SB_CB<0>")
	)
	(arc
		(start 392.62939 -272.788634)
		(mid 392.45327 -272.838612)
		(end 392.274552 -272.798794)
		(width 0.0889)
		(layer "In13.Cu")
		(net "M_H_CPU0_SB_CB<0>")
	)
	(arc
		(start 386.043424 -272.79346)
		(mid 385.859916 -272.838954)
		(end 385.677664 -272.788634)
		(width 0.0889)
		(layer "In13.Cu")
		(net "M_H_CPU0_SB_CB<0>")
	)
	(arc
		(start 392.234674 -272.775934)
		(mid 391.961645 -272.712615)
		(end 391.691876 -272.788634)
		(width 0.0889)
		(layer "In13.Cu")
		(net "M_H_CPU0_SB_CB<0>")
	)
	(arc
		(start 385.677664 -272.788634)
		(mid 385.394708 -272.712457)
		(end 385.111752 -272.788634)
		(width 0.0889)
		(layer "In13.Cu")
		(net "M_H_CPU0_SB_CB<0>")
	)
	(segment
		(start 383.517902 -264.100056)
		(end 383.984754 -264.365994)
		(width 0.10668)
		(layer "F.Cu")
		(net "M_H_CPU0_SB_CA<6>")
	)
	(segment
		(start 393.89939 -264.359644)
		(end 393.958572 -264.32002)
		(width 0.0889)
		(layer "In13.Cu")
		(net "M_H_CPU0_SB_CA<6>")
	)
	(segment
		(start 393.543282 -264.704068)
		(end 393.570714 -264.68832)
		(width 0.0889)
		(layer "In13.Cu")
		(net "M_H_CPU0_SB_CA<6>")
	)
	(segment
		(start 418.907468 -266.610084)
		(end 421.727122 -266.610084)
		(width 0.14478)
		(layer "In13.Cu")
		(net "M_H_CPU0_SB_CA<6>")
	)
	(segment
		(start 393.958572 -264.32002)
		(end 394.05433 -264.280396)
		(width 0.0889)
		(layer "In13.Cu")
		(net "M_H_CPU0_SB_CA<6>")
	)
	(segment
		(start 391.317734 -264.688574)
		(end 391.326116 -264.6934)
		(width 0.0889)
		(layer "In13.Cu")
		(net "M_H_CPU0_SB_CA<6>")
	)
	(segment
		(start 418.057584 -265.7602)
		(end 418.907468 -266.610084)
		(width 0.14478)
		(layer "In13.Cu")
		(net "M_H_CPU0_SB_CA<6>")
	)
	(segment
		(start 415.032952 -265.7602)
		(end 418.057584 -265.7602)
		(width 0.14478)
		(layer "In13.Cu")
		(net "M_H_CPU0_SB_CA<6>")
	)
	(segment
		(start 393.570714 -264.68832)
		(end 393.89939 -264.359644)
		(width 0.0889)
		(layer "In13.Cu")
		(net "M_H_CPU0_SB_CA<6>")
	)
	(segment
		(start 384.138932 -264.631424)
		(end 384.235198 -264.656824)
		(width 0.0889)
		(layer "In13.Cu")
		(net "M_H_CPU0_SB_CA<6>")
	)
	(segment
		(start 395.71422 -264.26795)
		(end 395.78534 -264.33907)
		(width 0.0889)
		(layer "In13.Cu")
		(net "M_H_CPU0_SB_CA<6>")
	)
	(segment
		(start 394.117322 -264.26795)
		(end 395.71422 -264.26795)
		(width 0.0889)
		(layer "In13.Cu")
		(net "M_H_CPU0_SB_CA<6>")
	)
	(segment
		(start 383.984754 -264.365994)
		(end 384.138932 -264.631424)
		(width 0.0889)
		(layer "In13.Cu")
		(net "M_H_CPU0_SB_CA<6>")
	)
	(segment
		(start 414.183068 -266.610084)
		(end 415.032952 -265.7602)
		(width 0.14478)
		(layer "In13.Cu")
		(net "M_H_CPU0_SB_CA<6>")
	)
	(segment
		(start 392.62939 -264.688574)
		(end 392.652758 -264.674858)
		(width 0.0889)
		(layer "In13.Cu")
		(net "M_H_CPU0_SB_CA<6>")
	)
	(segment
		(start 390.74344 -264.6934)
		(end 390.751822 -264.688574)
		(width 0.0889)
		(layer "In13.Cu")
		(net "M_H_CPU0_SB_CA<6>")
	)
	(segment
		(start 386.983478 -264.6934)
		(end 386.984494 -264.692892)
		(width 0.0889)
		(layer "In13.Cu")
		(net "M_H_CPU0_SB_CA<6>")
	)
	(segment
		(start 392.234674 -264.675874)
		(end 392.256264 -264.68832)
		(width 0.0889)
		(layer "In13.Cu")
		(net "M_H_CPU0_SB_CA<6>")
	)
	(segment
		(start 395.78534 -264.33907)
		(end 409.934156 -264.33907)
		(width 0.14478)
		(layer "In13.Cu")
		(net "M_H_CPU0_SB_CA<6>")
	)
	(segment
		(start 392.256264 -264.68832)
		(end 392.274552 -264.698734)
		(width 0.0889)
		(layer "In13.Cu")
		(net "M_H_CPU0_SB_CA<6>")
	)
	(segment
		(start 423.86377 -266.185142)
		(end 424.012106 -266.185142)
		(width 0.14478)
		(layer "In13.Cu")
		(net "M_H_CPU0_SB_CA<6>")
	)
	(segment
		(start 421.727122 -266.610084)
		(end 423.86377 -266.185142)
		(width 0.14478)
		(layer "In13.Cu")
		(net "M_H_CPU0_SB_CA<6>")
	)
	(segment
		(start 387.557772 -264.688574)
		(end 387.566154 -264.6934)
		(width 0.0889)
		(layer "In13.Cu")
		(net "M_H_CPU0_SB_CA<6>")
	)
	(segment
		(start 394.05433 -264.280396)
		(end 394.117322 -264.26795)
		(width 0.0889)
		(layer "In13.Cu")
		(net "M_H_CPU0_SB_CA<6>")
	)
	(segment
		(start 388.497826 -264.688574)
		(end 388.506208 -264.6934)
		(width 0.0889)
		(layer "In13.Cu")
		(net "M_H_CPU0_SB_CA<6>")
	)
	(segment
		(start 386.043424 -264.6934)
		(end 386.051806 -264.688574)
		(width 0.0889)
		(layer "In13.Cu")
		(net "M_H_CPU0_SB_CA<6>")
	)
	(segment
		(start 386.984494 -264.692892)
		(end 386.99186 -264.688574)
		(width 0.0889)
		(layer "In13.Cu")
		(net "M_H_CPU0_SB_CA<6>")
	)
	(segment
		(start 409.934156 -264.33907)
		(end 412.20517 -266.610084)
		(width 0.14478)
		(layer "In13.Cu")
		(net "M_H_CPU0_SB_CA<6>")
	)
	(segment
		(start 412.20517 -266.610084)
		(end 414.183068 -266.610084)
		(width 0.14478)
		(layer "In13.Cu")
		(net "M_H_CPU0_SB_CA<6>")
	)
	(arc
		(start 389.811768 -264.688574)
		(mid 390.094724 -264.612397)
		(end 390.37768 -264.688574)
		(width 0.0889)
		(layer "In13.Cu")
		(net "M_H_CPU0_SB_CA<6>")
	)
	(arc
		(start 387.566154 -264.6934)
		(mid 387.749662 -264.738894)
		(end 387.931914 -264.688574)
		(width 0.0889)
		(layer "In13.Cu")
		(net "M_H_CPU0_SB_CA<6>")
	)
	(arc
		(start 393.196572 -264.688574)
		(mid 393.368027 -264.739091)
		(end 393.543282 -264.704068)
		(width 0.0889)
		(layer "In13.Cu")
		(net "M_H_CPU0_SB_CA<6>")
	)
	(arc
		(start 384.235198 -264.656824)
		(mid 384.490263 -264.613473)
		(end 384.737864 -264.688574)
		(width 0.0889)
		(layer "In13.Cu")
		(net "M_H_CPU0_SB_CA<6>")
	)
	(arc
		(start 385.677664 -264.688574)
		(mid 385.859915 -264.738924)
		(end 386.043424 -264.6934)
		(width 0.0889)
		(layer "In13.Cu")
		(net "M_H_CPU0_SB_CA<6>")
	)
	(arc
		(start 385.111752 -264.688574)
		(mid 385.394708 -264.612397)
		(end 385.677664 -264.688574)
		(width 0.0889)
		(layer "In13.Cu")
		(net "M_H_CPU0_SB_CA<6>")
	)
	(arc
		(start 390.37768 -264.688574)
		(mid 390.559931 -264.738924)
		(end 390.74344 -264.6934)
		(width 0.0889)
		(layer "In13.Cu")
		(net "M_H_CPU0_SB_CA<6>")
	)
	(arc
		(start 386.617718 -264.688574)
		(mid 386.799969 -264.738924)
		(end 386.983478 -264.6934)
		(width 0.0889)
		(layer "In13.Cu")
		(net "M_H_CPU0_SB_CA<6>")
	)
	(arc
		(start 386.051806 -264.688574)
		(mid 386.334762 -264.612397)
		(end 386.617718 -264.688574)
		(width 0.0889)
		(layer "In13.Cu")
		(net "M_H_CPU0_SB_CA<6>")
	)
	(arc
		(start 391.326116 -264.6934)
		(mid 391.509624 -264.738894)
		(end 391.691876 -264.688574)
		(width 0.0889)
		(layer "In13.Cu")
		(net "M_H_CPU0_SB_CA<6>")
	)
	(arc
		(start 392.652758 -264.674858)
		(mid 392.926412 -264.611915)
		(end 393.196572 -264.688574)
		(width 0.0889)
		(layer "In13.Cu")
		(net "M_H_CPU0_SB_CA<6>")
	)
	(arc
		(start 388.871968 -264.688574)
		(mid 389.154924 -264.612397)
		(end 389.43788 -264.688574)
		(width 0.0889)
		(layer "In13.Cu")
		(net "M_H_CPU0_SB_CA<6>")
	)
	(arc
		(start 386.99186 -264.688574)
		(mid 387.274816 -264.612397)
		(end 387.557772 -264.688574)
		(width 0.0889)
		(layer "In13.Cu")
		(net "M_H_CPU0_SB_CA<6>")
	)
	(arc
		(start 388.506208 -264.6934)
		(mid 388.689716 -264.738894)
		(end 388.871968 -264.688574)
		(width 0.0889)
		(layer "In13.Cu")
		(net "M_H_CPU0_SB_CA<6>")
	)
	(arc
		(start 390.751822 -264.688574)
		(mid 391.034778 -264.612397)
		(end 391.317734 -264.688574)
		(width 0.0889)
		(layer "In13.Cu")
		(net "M_H_CPU0_SB_CA<6>")
	)
	(arc
		(start 387.931914 -264.688574)
		(mid 388.21487 -264.612397)
		(end 388.497826 -264.688574)
		(width 0.0889)
		(layer "In13.Cu")
		(net "M_H_CPU0_SB_CA<6>")
	)
	(arc
		(start 389.43788 -264.688574)
		(mid 389.624824 -264.738829)
		(end 389.811768 -264.688574)
		(width 0.0889)
		(layer "In13.Cu")
		(net "M_H_CPU0_SB_CA<6>")
	)
	(arc
		(start 392.274552 -264.698734)
		(mid 392.453273 -264.738657)
		(end 392.62939 -264.688574)
		(width 0.0889)
		(layer "In13.Cu")
		(net "M_H_CPU0_SB_CA<6>")
	)
	(arc
		(start 384.737864 -264.688574)
		(mid 384.924808 -264.738829)
		(end 385.111752 -264.688574)
		(width 0.0889)
		(layer "In13.Cu")
		(net "M_H_CPU0_SB_CA<6>")
	)
	(arc
		(start 391.691876 -264.688574)
		(mid 391.961645 -264.612551)
		(end 392.234674 -264.675874)
		(width 0.0889)
		(layer "In13.Cu")
		(net "M_H_CPU0_SB_CA<6>")
	)
	(segment
		(start 382.577848 -264.100056)
		(end 383.0447 -264.365994)
		(width 0.10668)
		(layer "F.Cu")
		(net "M_H_CPU0_SB_CA<5>")
	)
	(segment
		(start 412.419292 -265.7602)
		(end 414.090104 -265.7602)
		(width 0.14478)
		(layer "In13.Cu")
		(net "M_H_CPU0_SB_CA<5>")
	)
	(segment
		(start 414.940242 -264.910062)
		(end 415.394648 -264.910062)
		(width 0.14478)
		(layer "In13.Cu")
		(net "M_H_CPU0_SB_CA<5>")
	)
	(segment
		(start 415.539428 -264.678414)
		(end 415.684208 -264.533634)
		(width 0.14478)
		(layer "In13.Cu")
		(net "M_H_CPU0_SB_CA<5>")
	)
	(segment
		(start 415.394648 -264.910062)
		(end 415.539428 -264.765282)
		(width 0.14478)
		(layer "In13.Cu")
		(net "M_H_CPU0_SB_CA<5>")
	)
	(segment
		(start 383.0447 -264.365994)
		(end 382.890776 -264.100564)
		(width 0.0889)
		(layer "In13.Cu")
		(net "M_H_CPU0_SB_CA<5>")
	)
	(segment
		(start 416.641788 -264.678414)
		(end 416.786568 -264.533634)
		(width 0.14478)
		(layer "In13.Cu")
		(net "M_H_CPU0_SB_CA<5>")
	)
	(segment
		(start 386.983478 -264.038588)
		(end 386.984494 -264.039096)
		(width 0.0889)
		(layer "In13.Cu")
		(net "M_H_CPU0_SB_CA<5>")
	)
	(segment
		(start 386.043424 -264.038588)
		(end 386.051806 -264.043414)
		(width 0.0889)
		(layer "In13.Cu")
		(net "M_H_CPU0_SB_CA<5>")
	)
	(segment
		(start 416.090608 -264.765282)
		(end 416.235388 -264.910062)
		(width 0.14478)
		(layer "In13.Cu")
		(net "M_H_CPU0_SB_CA<5>")
	)
	(segment
		(start 388.497826 -264.043414)
		(end 388.506208 -264.038588)
		(width 0.0889)
		(layer "In13.Cu")
		(net "M_H_CPU0_SB_CA<5>")
	)
	(segment
		(start 419.491668 -265.7602)
		(end 419.912038 -265.33983)
		(width 0.14478)
		(layer "In13.Cu")
		(net "M_H_CPU0_SB_CA<5>")
	)
	(segment
		(start 415.945828 -264.533634)
		(end 416.090608 -264.678414)
		(width 0.14478)
		(layer "In13.Cu")
		(net "M_H_CPU0_SB_CA<5>")
	)
	(segment
		(start 416.235388 -264.910062)
		(end 416.497008 -264.910062)
		(width 0.14478)
		(layer "In13.Cu")
		(net "M_H_CPU0_SB_CA<5>")
	)
	(segment
		(start 386.984494 -264.039096)
		(end 386.99186 -264.043414)
		(width 0.0889)
		(layer "In13.Cu")
		(net "M_H_CPU0_SB_CA<5>")
	)
	(segment
		(start 383.79781 -264.043414)
		(end 383.806192 -264.038588)
		(width 0.0889)
		(layer "In13.Cu")
		(net "M_H_CPU0_SB_CA<5>")
	)
	(segment
		(start 415.684208 -264.533634)
		(end 415.945828 -264.533634)
		(width 0.14478)
		(layer "In13.Cu")
		(net "M_H_CPU0_SB_CA<5>")
	)
	(segment
		(start 382.890776 -264.100564)
		(end 382.913128 -264.017252)
		(width 0.0889)
		(layer "In13.Cu")
		(net "M_H_CPU0_SB_CA<5>")
	)
	(segment
		(start 391.691876 -264.043414)
		(end 391.70229 -264.04951)
		(width 0.0889)
		(layer "In13.Cu")
		(net "M_H_CPU0_SB_CA<5>")
	)
	(segment
		(start 390.74344 -264.038588)
		(end 390.751822 -264.043414)
		(width 0.0889)
		(layer "In13.Cu")
		(net "M_H_CPU0_SB_CA<5>")
	)
	(segment
		(start 387.557772 -264.043414)
		(end 387.566154 -264.038588)
		(width 0.0889)
		(layer "In13.Cu")
		(net "M_H_CPU0_SB_CA<5>")
	)
	(segment
		(start 395.317472 -263.88441)
		(end 395.913864 -263.88441)
		(width 0.0889)
		(layer "In13.Cu")
		(net "M_H_CPU0_SB_CA<5>")
	)
	(segment
		(start 417.192968 -264.765282)
		(end 417.337748 -264.910062)
		(width 0.14478)
		(layer "In13.Cu")
		(net "M_H_CPU0_SB_CA<5>")
	)
	(segment
		(start 417.337748 -264.910062)
		(end 418.122608 -264.910062)
		(width 0.14478)
		(layer "In13.Cu")
		(net "M_H_CPU0_SB_CA<5>")
	)
	(segment
		(start 419.912038 -265.33983)
		(end 419.912038 -265.335004)
		(width 0.14478)
		(layer "In13.Cu")
		(net "M_H_CPU0_SB_CA<5>")
	)
	(segment
		(start 410.543502 -263.88441)
		(end 412.419292 -265.7602)
		(width 0.14478)
		(layer "In13.Cu")
		(net "M_H_CPU0_SB_CA<5>")
	)
	(segment
		(start 392.62431 -264.038588)
		(end 392.632692 -264.043414)
		(width 0.0889)
		(layer "In13.Cu")
		(net "M_H_CPU0_SB_CA<5>")
	)
	(segment
		(start 418.972746 -265.7602)
		(end 419.491668 -265.7602)
		(width 0.14478)
		(layer "In13.Cu")
		(net "M_H_CPU0_SB_CA<5>")
	)
	(segment
		(start 416.497008 -264.910062)
		(end 416.641788 -264.765282)
		(width 0.14478)
		(layer "In13.Cu")
		(net "M_H_CPU0_SB_CA<5>")
	)
	(segment
		(start 393.384786 -263.992614)
		(end 395.209268 -263.992614)
		(width 0.0889)
		(layer "In13.Cu")
		(net "M_H_CPU0_SB_CA<5>")
	)
	(segment
		(start 415.539428 -264.765282)
		(end 415.539428 -264.678414)
		(width 0.14478)
		(layer "In13.Cu")
		(net "M_H_CPU0_SB_CA<5>")
	)
	(segment
		(start 395.209268 -263.992614)
		(end 395.317472 -263.88441)
		(width 0.0889)
		(layer "In13.Cu")
		(net "M_H_CPU0_SB_CA<5>")
	)
	(segment
		(start 395.913864 -263.88441)
		(end 410.543502 -263.88441)
		(width 0.14478)
		(layer "In13.Cu")
		(net "M_H_CPU0_SB_CA<5>")
	)
	(segment
		(start 417.192968 -264.678414)
		(end 417.192968 -264.765282)
		(width 0.14478)
		(layer "In13.Cu")
		(net "M_H_CPU0_SB_CA<5>")
	)
	(segment
		(start 416.786568 -264.533634)
		(end 417.048188 -264.533634)
		(width 0.14478)
		(layer "In13.Cu")
		(net "M_H_CPU0_SB_CA<5>")
	)
	(segment
		(start 417.048188 -264.533634)
		(end 417.192968 -264.678414)
		(width 0.14478)
		(layer "In13.Cu")
		(net "M_H_CPU0_SB_CA<5>")
	)
	(segment
		(start 416.090608 -264.678414)
		(end 416.090608 -264.765282)
		(width 0.14478)
		(layer "In13.Cu")
		(net "M_H_CPU0_SB_CA<5>")
	)
	(segment
		(start 414.090104 -265.7602)
		(end 414.940242 -264.910062)
		(width 0.14478)
		(layer "In13.Cu")
		(net "M_H_CPU0_SB_CA<5>")
	)
	(segment
		(start 416.641788 -264.765282)
		(end 416.641788 -264.678414)
		(width 0.14478)
		(layer "In13.Cu")
		(net "M_H_CPU0_SB_CA<5>")
	)
	(segment
		(start 418.122608 -264.910062)
		(end 418.972746 -265.7602)
		(width 0.14478)
		(layer "In13.Cu")
		(net "M_H_CPU0_SB_CA<5>")
	)
	(segment
		(start 391.317734 -264.043414)
		(end 391.326116 -264.038588)
		(width 0.0889)
		(layer "In13.Cu")
		(net "M_H_CPU0_SB_CA<5>")
	)
	(arc
		(start 385.677664 -264.043414)
		(mid 385.859915 -263.993064)
		(end 386.043424 -264.038588)
		(width 0.0889)
		(layer "In13.Cu")
		(net "M_H_CPU0_SB_CA<5>")
	)
	(arc
		(start 386.99186 -264.043414)
		(mid 387.274816 -264.119591)
		(end 387.557772 -264.043414)
		(width 0.0889)
		(layer "In13.Cu")
		(net "M_H_CPU0_SB_CA<5>")
	)
	(arc
		(start 390.37768 -264.043414)
		(mid 390.559931 -263.993064)
		(end 390.74344 -264.038588)
		(width 0.0889)
		(layer "In13.Cu")
		(net "M_H_CPU0_SB_CA<5>")
	)
	(arc
		(start 393.192508 -264.04697)
		(mid 393.28494 -264.006688)
		(end 393.384786 -263.992614)
		(width 0.0889)
		(layer "In13.Cu")
		(net "M_H_CPU0_SB_CA<5>")
	)
	(arc
		(start 387.931914 -264.043414)
		(mid 388.21487 -264.119591)
		(end 388.497826 -264.043414)
		(width 0.0889)
		(layer "In13.Cu")
		(net "M_H_CPU0_SB_CA<5>")
	)
	(arc
		(start 391.326116 -264.038588)
		(mid 391.509624 -263.993094)
		(end 391.691876 -264.043414)
		(width 0.0889)
		(layer "In13.Cu")
		(net "M_H_CPU0_SB_CA<5>")
	)
	(arc
		(start 384.171952 -264.043414)
		(mid 384.454908 -264.119591)
		(end 384.737864 -264.043414)
		(width 0.0889)
		(layer "In13.Cu")
		(net "M_H_CPU0_SB_CA<5>")
	)
	(arc
		(start 392.258042 -264.043414)
		(mid 392.440547 -263.992937)
		(end 392.62431 -264.038588)
		(width 0.0889)
		(layer "In13.Cu")
		(net "M_H_CPU0_SB_CA<5>")
	)
	(arc
		(start 387.566154 -264.038588)
		(mid 387.749662 -263.993094)
		(end 387.931914 -264.043414)
		(width 0.0889)
		(layer "In13.Cu")
		(net "M_H_CPU0_SB_CA<5>")
	)
	(arc
		(start 392.632692 -264.043414)
		(mid 392.91212 -264.11958)
		(end 393.192508 -264.04697)
		(width 0.0889)
		(layer "In13.Cu")
		(net "M_H_CPU0_SB_CA<5>")
	)
	(arc
		(start 389.811768 -264.043414)
		(mid 390.094724 -264.119591)
		(end 390.37768 -264.043414)
		(width 0.0889)
		(layer "In13.Cu")
		(net "M_H_CPU0_SB_CA<5>")
	)
	(arc
		(start 383.231898 -264.043414)
		(mid 383.514854 -264.119591)
		(end 383.79781 -264.043414)
		(width 0.0889)
		(layer "In13.Cu")
		(net "M_H_CPU0_SB_CA<5>")
	)
	(arc
		(start 384.737864 -264.043414)
		(mid 384.924808 -263.993159)
		(end 385.111752 -264.043414)
		(width 0.0889)
		(layer "In13.Cu")
		(net "M_H_CPU0_SB_CA<5>")
	)
	(arc
		(start 389.43788 -264.043414)
		(mid 389.624824 -263.993159)
		(end 389.811768 -264.043414)
		(width 0.0889)
		(layer "In13.Cu")
		(net "M_H_CPU0_SB_CA<5>")
	)
	(arc
		(start 383.806192 -264.038588)
		(mid 383.9897 -263.993094)
		(end 384.171952 -264.043414)
		(width 0.0889)
		(layer "In13.Cu")
		(net "M_H_CPU0_SB_CA<5>")
	)
	(arc
		(start 385.111752 -264.043414)
		(mid 385.394708 -264.119591)
		(end 385.677664 -264.043414)
		(width 0.0889)
		(layer "In13.Cu")
		(net "M_H_CPU0_SB_CA<5>")
	)
	(arc
		(start 391.70229 -264.04951)
		(mid 391.980976 -264.11973)
		(end 392.258042 -264.043414)
		(width 0.0889)
		(layer "In13.Cu")
		(net "M_H_CPU0_SB_CA<5>")
	)
	(arc
		(start 386.617718 -264.043414)
		(mid 386.799969 -263.993064)
		(end 386.983478 -264.038588)
		(width 0.0889)
		(layer "In13.Cu")
		(net "M_H_CPU0_SB_CA<5>")
	)
	(arc
		(start 388.506208 -264.038588)
		(mid 388.689716 -263.993094)
		(end 388.871968 -264.043414)
		(width 0.0889)
		(layer "In13.Cu")
		(net "M_H_CPU0_SB_CA<5>")
	)
	(arc
		(start 382.913128 -264.017252)
		(mid 383.07546 -263.994434)
		(end 383.231898 -264.043414)
		(width 0.0889)
		(layer "In13.Cu")
		(net "M_H_CPU0_SB_CA<5>")
	)
	(arc
		(start 388.871968 -264.043414)
		(mid 389.154924 -264.119591)
		(end 389.43788 -264.043414)
		(width 0.0889)
		(layer "In13.Cu")
		(net "M_H_CPU0_SB_CA<5>")
	)
	(arc
		(start 390.751822 -264.043414)
		(mid 391.034778 -264.119591)
		(end 391.317734 -264.043414)
		(width 0.0889)
		(layer "In13.Cu")
		(net "M_H_CPU0_SB_CA<5>")
	)
	(arc
		(start 386.051806 -264.043414)
		(mid 386.334762 -264.119591)
		(end 386.617718 -264.043414)
		(width 0.0889)
		(layer "In13.Cu")
		(net "M_H_CPU0_SB_CA<5>")
	)
	(segment
		(start 382.107948 -263.29005)
		(end 382.5748 -263.555988)
		(width 0.10668)
		(layer "F.Cu")
		(net "M_H_CPU0_SB_CA<4>")
	)
	(segment
		(start 392.718036 -263.872472)
		(end 392.72845 -263.878568)
		(width 0.0889)
		(layer "In13.Cu")
		(net "M_H_CPU0_SB_CA<4>")
	)
	(segment
		(start 395.942312 -263.42975)
		(end 410.724858 -263.42975)
		(width 0.14478)
		(layer "In13.Cu")
		(net "M_H_CPU0_SB_CA<4>")
	)
	(segment
		(start 382.5748 -263.555988)
		(end 382.728724 -263.821418)
		(width 0.0889)
		(layer "In13.Cu")
		(net "M_H_CPU0_SB_CA<4>")
	)
	(segment
		(start 385.207764 -263.878568)
		(end 385.216146 -263.883394)
		(width 0.0889)
		(layer "In13.Cu")
		(net "M_H_CPU0_SB_CA<4>")
	)
	(segment
		(start 389.333486 -263.883394)
		(end 389.341868 -263.878568)
		(width 0.0889)
		(layer "In13.Cu")
		(net "M_H_CPU0_SB_CA<4>")
	)
	(segment
		(start 418.907468 -264.910062)
		(end 421.727122 -264.910062)
		(width 0.14478)
		(layer "In13.Cu")
		(net "M_H_CPU0_SB_CA<4>")
	)
	(segment
		(start 383.693416 -263.883394)
		(end 383.701798 -263.878568)
		(width 0.0889)
		(layer "In13.Cu")
		(net "M_H_CPU0_SB_CA<4>")
	)
	(segment
		(start 410.724858 -263.42975)
		(end 412.20517 -264.910062)
		(width 0.14478)
		(layer "In13.Cu")
		(net "M_H_CPU0_SB_CA<4>")
	)
	(segment
		(start 421.727122 -264.910062)
		(end 423.86377 -264.48512)
		(width 0.14478)
		(layer "In13.Cu")
		(net "M_H_CPU0_SB_CA<4>")
	)
	(segment
		(start 395.400022 -263.42975)
		(end 395.942312 -263.42975)
		(width 0.0889)
		(layer "In13.Cu")
		(net "M_H_CPU0_SB_CA<4>")
	)
	(segment
		(start 388.393432 -263.883394)
		(end 388.401814 -263.878568)
		(width 0.0889)
		(layer "In13.Cu")
		(net "M_H_CPU0_SB_CA<4>")
	)
	(segment
		(start 393.384278 -263.802114)
		(end 395.027658 -263.802114)
		(width 0.0889)
		(layer "In13.Cu")
		(net "M_H_CPU0_SB_CA<4>")
	)
	(segment
		(start 384.63347 -263.883394)
		(end 384.641852 -263.878568)
		(width 0.0889)
		(layer "In13.Cu")
		(net "M_H_CPU0_SB_CA<4>")
	)
	(segment
		(start 423.86377 -264.48512)
		(end 424.012106 -264.48512)
		(width 0.14478)
		(layer "In13.Cu")
		(net "M_H_CPU0_SB_CA<4>")
	)
	(segment
		(start 386.147818 -263.878568)
		(end 386.1562 -263.883394)
		(width 0.0889)
		(layer "In13.Cu")
		(net "M_H_CPU0_SB_CA<4>")
	)
	(segment
		(start 412.20517 -264.910062)
		(end 414.183068 -264.910062)
		(width 0.14478)
		(layer "In13.Cu")
		(net "M_H_CPU0_SB_CA<4>")
	)
	(segment
		(start 382.728724 -263.821418)
		(end 382.824736 -263.846818)
		(width 0.0889)
		(layer "In13.Cu")
		(net "M_H_CPU0_SB_CA<4>")
	)
	(segment
		(start 414.183068 -264.910062)
		(end 415.032952 -264.060178)
		(width 0.14478)
		(layer "In13.Cu")
		(net "M_H_CPU0_SB_CA<4>")
	)
	(segment
		(start 418.057584 -264.060178)
		(end 418.907468 -264.910062)
		(width 0.14478)
		(layer "In13.Cu")
		(net "M_H_CPU0_SB_CA<4>")
	)
	(segment
		(start 415.032952 -264.060178)
		(end 418.057584 -264.060178)
		(width 0.14478)
		(layer "In13.Cu")
		(net "M_H_CPU0_SB_CA<4>")
	)
	(segment
		(start 389.90778 -263.878568)
		(end 389.916162 -263.883394)
		(width 0.0889)
		(layer "In13.Cu")
		(net "M_H_CPU0_SB_CA<4>")
	)
	(segment
		(start 395.027658 -263.802114)
		(end 395.400022 -263.42975)
		(width 0.0889)
		(layer "In13.Cu")
		(net "M_H_CPU0_SB_CA<4>")
	)
	(segment
		(start 391.787634 -263.878568)
		(end 391.796016 -263.883394)
		(width 0.0889)
		(layer "In13.Cu")
		(net "M_H_CPU0_SB_CA<4>")
	)
	(arc
		(start 384.26771 -263.878568)
		(mid 384.449961 -263.928918)
		(end 384.63347 -263.883394)
		(width 0.0889)
		(layer "In13.Cu")
		(net "M_H_CPU0_SB_CA<4>")
	)
	(arc
		(start 388.401814 -263.878568)
		(mid 388.68477 -263.802391)
		(end 388.967726 -263.878568)
		(width 0.0889)
		(layer "In13.Cu")
		(net "M_H_CPU0_SB_CA<4>")
	)
	(arc
		(start 386.1562 -263.883394)
		(mid 386.339708 -263.928888)
		(end 386.52196 -263.878568)
		(width 0.0889)
		(layer "In13.Cu")
		(net "M_H_CPU0_SB_CA<4>")
	)
	(arc
		(start 387.087872 -263.878568)
		(mid 387.274816 -263.928823)
		(end 387.46176 -263.878568)
		(width 0.0889)
		(layer "In13.Cu")
		(net "M_H_CPU0_SB_CA<4>")
	)
	(arc
		(start 388.967726 -263.878568)
		(mid 389.149977 -263.928918)
		(end 389.333486 -263.883394)
		(width 0.0889)
		(layer "In13.Cu")
		(net "M_H_CPU0_SB_CA<4>")
	)
	(arc
		(start 389.341868 -263.878568)
		(mid 389.624824 -263.802391)
		(end 389.90778 -263.878568)
		(width 0.0889)
		(layer "In13.Cu")
		(net "M_H_CPU0_SB_CA<4>")
	)
	(arc
		(start 383.701798 -263.878568)
		(mid 383.984754 -263.802391)
		(end 384.26771 -263.878568)
		(width 0.0889)
		(layer "In13.Cu")
		(net "M_H_CPU0_SB_CA<4>")
	)
	(arc
		(start 391.221722 -263.878568)
		(mid 391.504678 -263.802391)
		(end 391.787634 -263.878568)
		(width 0.0889)
		(layer "In13.Cu")
		(net "M_H_CPU0_SB_CA<4>")
	)
	(arc
		(start 388.027672 -263.878568)
		(mid 388.209923 -263.928918)
		(end 388.393432 -263.883394)
		(width 0.0889)
		(layer "In13.Cu")
		(net "M_H_CPU0_SB_CA<4>")
	)
	(arc
		(start 389.916162 -263.883394)
		(mid 390.09967 -263.928888)
		(end 390.281922 -263.878568)
		(width 0.0889)
		(layer "In13.Cu")
		(net "M_H_CPU0_SB_CA<4>")
	)
	(arc
		(start 391.796016 -263.883394)
		(mid 391.979778 -263.92901)
		(end 392.162284 -263.878568)
		(width 0.0889)
		(layer "In13.Cu")
		(net "M_H_CPU0_SB_CA<4>")
	)
	(arc
		(start 392.162284 -263.878568)
		(mid 392.439351 -263.802297)
		(end 392.718036 -263.872472)
		(width 0.0889)
		(layer "In13.Cu")
		(net "M_H_CPU0_SB_CA<4>")
	)
	(arc
		(start 383.327656 -263.878568)
		(mid 383.509907 -263.928918)
		(end 383.693416 -263.883394)
		(width 0.0889)
		(layer "In13.Cu")
		(net "M_H_CPU0_SB_CA<4>")
	)
	(arc
		(start 393.086082 -263.887712)
		(mid 393.229176 -263.823995)
		(end 393.384278 -263.802114)
		(width 0.0889)
		(layer "In13.Cu")
		(net "M_H_CPU0_SB_CA<4>")
	)
	(arc
		(start 384.641852 -263.878568)
		(mid 384.924808 -263.802391)
		(end 385.207764 -263.878568)
		(width 0.0889)
		(layer "In13.Cu")
		(net "M_H_CPU0_SB_CA<4>")
	)
	(arc
		(start 385.216146 -263.883394)
		(mid 385.399654 -263.928888)
		(end 385.581906 -263.878568)
		(width 0.0889)
		(layer "In13.Cu")
		(net "M_H_CPU0_SB_CA<4>")
	)
	(arc
		(start 392.72845 -263.878568)
		(mid 392.9061 -263.928828)
		(end 393.086082 -263.887712)
		(width 0.0889)
		(layer "In13.Cu")
		(net "M_H_CPU0_SB_CA<4>")
	)
	(arc
		(start 385.581906 -263.878568)
		(mid 385.864862 -263.802391)
		(end 386.147818 -263.878568)
		(width 0.0889)
		(layer "In13.Cu")
		(net "M_H_CPU0_SB_CA<4>")
	)
	(arc
		(start 382.824736 -263.846818)
		(mid 383.079944 -263.803341)
		(end 383.327656 -263.878568)
		(width 0.0889)
		(layer "In13.Cu")
		(net "M_H_CPU0_SB_CA<4>")
	)
	(arc
		(start 387.46176 -263.878568)
		(mid 387.744716 -263.802391)
		(end 388.027672 -263.878568)
		(width 0.0889)
		(layer "In13.Cu")
		(net "M_H_CPU0_SB_CA<4>")
	)
	(arc
		(start 386.52196 -263.878568)
		(mid 386.804916 -263.802391)
		(end 387.087872 -263.878568)
		(width 0.0889)
		(layer "In13.Cu")
		(net "M_H_CPU0_SB_CA<4>")
	)
	(arc
		(start 390.281922 -263.878568)
		(mid 390.564878 -263.802391)
		(end 390.847834 -263.878568)
		(width 0.0889)
		(layer "In13.Cu")
		(net "M_H_CPU0_SB_CA<4>")
	)
	(arc
		(start 390.847834 -263.878568)
		(mid 391.034778 -263.928823)
		(end 391.221722 -263.878568)
		(width 0.0889)
		(layer "In13.Cu")
		(net "M_H_CPU0_SB_CA<4>")
	)
	(segment
		(start 383.988056 -263.29005)
		(end 384.454908 -263.555988)
		(width 0.10668)
		(layer "F.Cu")
		(net "M_H_CPU0_SB_CA<3>")
	)
	(segment
		(start 405.687022 -262.97509)
		(end 405.525478 -262.813546)
		(width 0.14478)
		(layer "In13.Cu")
		(net "M_H_CPU0_SB_CA<3>")
	)
	(segment
		(start 395.288262 -262.97509)
		(end 395.237462 -262.92429)
		(width 0.0889)
		(layer "In13.Cu")
		(net "M_H_CPU0_SB_CA<3>")
	)
	(segment
		(start 395.237462 -262.92429)
		(end 394.46708 -262.92429)
		(width 0.0889)
		(layer "In13.Cu")
		(net "M_H_CPU0_SB_CA<3>")
	)
	(segment
		(start 407.17978 -262.603996)
		(end 407.17978 -262.813546)
		(width 0.14478)
		(layer "In13.Cu")
		(net "M_H_CPU0_SB_CA<3>")
	)
	(segment
		(start 392.744198 -263.222486)
		(end 392.725402 -263.233408)
		(width 0.0889)
		(layer "In13.Cu")
		(net "M_H_CPU0_SB_CA<3>")
	)
	(segment
		(start 418.972746 -264.060178)
		(end 418.122608 -263.21004)
		(width 0.14478)
		(layer "In13.Cu")
		(net "M_H_CPU0_SB_CA<3>")
	)
	(segment
		(start 405.363934 -262.442452)
		(end 405.135588 -262.442452)
		(width 0.14478)
		(layer "In13.Cu")
		(net "M_H_CPU0_SB_CA<3>")
	)
	(segment
		(start 406.78989 -262.97509)
		(end 406.628346 -262.813546)
		(width 0.14478)
		(layer "In13.Cu")
		(net "M_H_CPU0_SB_CA<3>")
	)
	(segment
		(start 419.912038 -263.665208)
		(end 419.517068 -264.060178)
		(width 0.14478)
		(layer "In13.Cu")
		(net "M_H_CPU0_SB_CA<3>")
	)
	(segment
		(start 407.341324 -262.442452)
		(end 407.17978 -262.603996)
		(width 0.14478)
		(layer "In13.Cu")
		(net "M_H_CPU0_SB_CA<3>")
	)
	(segment
		(start 414.940242 -263.21004)
		(end 414.090104 -264.060178)
		(width 0.14478)
		(layer "In13.Cu")
		(net "M_H_CPU0_SB_CA<3>")
	)
	(segment
		(start 410.91358 -262.97509)
		(end 407.892758 -262.97509)
		(width 0.14478)
		(layer "In13.Cu")
		(net "M_H_CPU0_SB_CA<3>")
	)
	(segment
		(start 388.401814 -263.233408)
		(end 388.393432 -263.228582)
		(width 0.0889)
		(layer "In13.Cu")
		(net "M_H_CPU0_SB_CA<3>")
	)
	(segment
		(start 389.341868 -263.233408)
		(end 389.333486 -263.228582)
		(width 0.0889)
		(layer "In13.Cu")
		(net "M_H_CPU0_SB_CA<3>")
	)
	(segment
		(start 405.525478 -262.603996)
		(end 405.363934 -262.442452)
		(width 0.14478)
		(layer "In13.Cu")
		(net "M_H_CPU0_SB_CA<3>")
	)
	(segment
		(start 407.56967 -262.442452)
		(end 407.341324 -262.442452)
		(width 0.14478)
		(layer "In13.Cu")
		(net "M_H_CPU0_SB_CA<3>")
	)
	(segment
		(start 405.915368 -262.97509)
		(end 405.687022 -262.97509)
		(width 0.14478)
		(layer "In13.Cu")
		(net "M_H_CPU0_SB_CA<3>")
	)
	(segment
		(start 392.161014 -263.233662)
		(end 392.140948 -263.222232)
		(width 0.0889)
		(layer "In13.Cu")
		(net "M_H_CPU0_SB_CA<3>")
	)
	(segment
		(start 404.974044 -262.603996)
		(end 404.974044 -262.813546)
		(width 0.14478)
		(layer "In13.Cu")
		(net "M_H_CPU0_SB_CA<3>")
	)
	(segment
		(start 418.122608 -263.21004)
		(end 414.940242 -263.21004)
		(width 0.14478)
		(layer "In13.Cu")
		(net "M_H_CPU0_SB_CA<3>")
	)
	(segment
		(start 404.8125 -262.97509)
		(end 395.949932 -262.97509)
		(width 0.14478)
		(layer "In13.Cu")
		(net "M_H_CPU0_SB_CA<3>")
	)
	(segment
		(start 386.1562 -263.228582)
		(end 386.147818 -263.233408)
		(width 0.0889)
		(layer "In13.Cu")
		(net "M_H_CPU0_SB_CA<3>")
	)
	(segment
		(start 419.912038 -263.634982)
		(end 419.912038 -263.665208)
		(width 0.14478)
		(layer "In13.Cu")
		(net "M_H_CPU0_SB_CA<3>")
	)
	(segment
		(start 406.628346 -262.603996)
		(end 406.466802 -262.442452)
		(width 0.14478)
		(layer "In13.Cu")
		(net "M_H_CPU0_SB_CA<3>")
	)
	(segment
		(start 407.731214 -262.813546)
		(end 407.731214 -262.603996)
		(width 0.14478)
		(layer "In13.Cu")
		(net "M_H_CPU0_SB_CA<3>")
	)
	(segment
		(start 406.238456 -262.442452)
		(end 406.076912 -262.603996)
		(width 0.14478)
		(layer "In13.Cu")
		(net "M_H_CPU0_SB_CA<3>")
	)
	(segment
		(start 406.628346 -262.813546)
		(end 406.628346 -262.603996)
		(width 0.14478)
		(layer "In13.Cu")
		(net "M_H_CPU0_SB_CA<3>")
	)
	(segment
		(start 419.517068 -264.060178)
		(end 418.972746 -264.060178)
		(width 0.14478)
		(layer "In13.Cu")
		(net "M_H_CPU0_SB_CA<3>")
	)
	(segment
		(start 394.081254 -263.310116)
		(end 393.384786 -263.310116)
		(width 0.0889)
		(layer "In13.Cu")
		(net "M_H_CPU0_SB_CA<3>")
	)
	(segment
		(start 407.731214 -262.603996)
		(end 407.56967 -262.442452)
		(width 0.14478)
		(layer "In13.Cu")
		(net "M_H_CPU0_SB_CA<3>")
	)
	(segment
		(start 407.17978 -262.813546)
		(end 407.018236 -262.97509)
		(width 0.14478)
		(layer "In13.Cu")
		(net "M_H_CPU0_SB_CA<3>")
	)
	(segment
		(start 389.916162 -263.228582)
		(end 389.90778 -263.233408)
		(width 0.0889)
		(layer "In13.Cu")
		(net "M_H_CPU0_SB_CA<3>")
	)
	(segment
		(start 405.135588 -262.442452)
		(end 404.974044 -262.603996)
		(width 0.14478)
		(layer "In13.Cu")
		(net "M_H_CPU0_SB_CA<3>")
	)
	(segment
		(start 385.216146 -263.228582)
		(end 385.207764 -263.233408)
		(width 0.0889)
		(layer "In13.Cu")
		(net "M_H_CPU0_SB_CA<3>")
	)
	(segment
		(start 406.076912 -262.813546)
		(end 405.915368 -262.97509)
		(width 0.14478)
		(layer "In13.Cu")
		(net "M_H_CPU0_SB_CA<3>")
	)
	(segment
		(start 392.182604 -263.246108)
		(end 392.161014 -263.233662)
		(width 0.0889)
		(layer "In13.Cu")
		(net "M_H_CPU0_SB_CA<3>")
	)
	(segment
		(start 404.974044 -262.813546)
		(end 404.8125 -262.97509)
		(width 0.14478)
		(layer "In13.Cu")
		(net "M_H_CPU0_SB_CA<3>")
	)
	(segment
		(start 394.46708 -262.92429)
		(end 394.081254 -263.310116)
		(width 0.0889)
		(layer "In13.Cu")
		(net "M_H_CPU0_SB_CA<3>")
	)
	(segment
		(start 384.30073 -263.290558)
		(end 384.454908 -263.555988)
		(width 0.0889)
		(layer "In13.Cu")
		(net "M_H_CPU0_SB_CA<3>")
	)
	(segment
		(start 406.076912 -262.603996)
		(end 406.076912 -262.813546)
		(width 0.14478)
		(layer "In13.Cu")
		(net "M_H_CPU0_SB_CA<3>")
	)
	(segment
		(start 411.998668 -264.060178)
		(end 410.91358 -262.97509)
		(width 0.14478)
		(layer "In13.Cu")
		(net "M_H_CPU0_SB_CA<3>")
	)
	(segment
		(start 405.525478 -262.813546)
		(end 405.525478 -262.603996)
		(width 0.14478)
		(layer "In13.Cu")
		(net "M_H_CPU0_SB_CA<3>")
	)
	(segment
		(start 407.892758 -262.97509)
		(end 407.731214 -262.813546)
		(width 0.14478)
		(layer "In13.Cu")
		(net "M_H_CPU0_SB_CA<3>")
	)
	(segment
		(start 406.466802 -262.442452)
		(end 406.238456 -262.442452)
		(width 0.14478)
		(layer "In13.Cu")
		(net "M_H_CPU0_SB_CA<3>")
	)
	(segment
		(start 414.090104 -264.060178)
		(end 411.998668 -264.060178)
		(width 0.14478)
		(layer "In13.Cu")
		(net "M_H_CPU0_SB_CA<3>")
	)
	(segment
		(start 384.323082 -263.207246)
		(end 384.30073 -263.290558)
		(width 0.0889)
		(layer "In13.Cu")
		(net "M_H_CPU0_SB_CA<3>")
	)
	(segment
		(start 384.641852 -263.233408)
		(end 384.63347 -263.228582)
		(width 0.0889)
		(layer "In13.Cu")
		(net "M_H_CPU0_SB_CA<3>")
	)
	(segment
		(start 407.018236 -262.97509)
		(end 406.78989 -262.97509)
		(width 0.14478)
		(layer "In13.Cu")
		(net "M_H_CPU0_SB_CA<3>")
	)
	(segment
		(start 395.949932 -262.97509)
		(end 395.288262 -262.97509)
		(width 0.0889)
		(layer "In13.Cu")
		(net "M_H_CPU0_SB_CA<3>")
	)
	(arc
		(start 393.384786 -263.310116)
		(mid 393.237577 -263.290639)
		(end 393.10056 -263.233408)
		(width 0.0889)
		(layer "In13.Cu")
		(net "M_H_CPU0_SB_CA<3>")
	)
	(arc
		(start 390.281922 -263.233408)
		(mid 390.099671 -263.183058)
		(end 389.916162 -263.228582)
		(width 0.0889)
		(layer "In13.Cu")
		(net "M_H_CPU0_SB_CA<3>")
	)
	(arc
		(start 386.52196 -263.233408)
		(mid 386.339709 -263.183058)
		(end 386.1562 -263.228582)
		(width 0.0889)
		(layer "In13.Cu")
		(net "M_H_CPU0_SB_CA<3>")
	)
	(arc
		(start 384.63347 -263.228582)
		(mid 384.4806 -263.183941)
		(end 384.323082 -263.207246)
		(width 0.0889)
		(layer "In13.Cu")
		(net "M_H_CPU0_SB_CA<3>")
	)
	(arc
		(start 388.967726 -263.233408)
		(mid 388.68477 -263.309585)
		(end 388.401814 -263.233408)
		(width 0.0889)
		(layer "In13.Cu")
		(net "M_H_CPU0_SB_CA<3>")
	)
	(arc
		(start 389.90778 -263.233408)
		(mid 389.624824 -263.309585)
		(end 389.341868 -263.233408)
		(width 0.0889)
		(layer "In13.Cu")
		(net "M_H_CPU0_SB_CA<3>")
	)
	(arc
		(start 391.787634 -263.233408)
		(mid 391.504678 -263.309585)
		(end 391.221722 -263.233408)
		(width 0.0889)
		(layer "In13.Cu")
		(net "M_H_CPU0_SB_CA<3>")
	)
	(arc
		(start 387.087872 -263.233408)
		(mid 386.804916 -263.309585)
		(end 386.52196 -263.233408)
		(width 0.0889)
		(layer "In13.Cu")
		(net "M_H_CPU0_SB_CA<3>")
	)
	(arc
		(start 388.027672 -263.233408)
		(mid 387.744716 -263.309585)
		(end 387.46176 -263.233408)
		(width 0.0889)
		(layer "In13.Cu")
		(net "M_H_CPU0_SB_CA<3>")
	)
	(arc
		(start 386.147818 -263.233408)
		(mid 385.864862 -263.309585)
		(end 385.581906 -263.233408)
		(width 0.0889)
		(layer "In13.Cu")
		(net "M_H_CPU0_SB_CA<3>")
	)
	(arc
		(start 392.725402 -263.233408)
		(mid 392.455633 -263.309431)
		(end 392.182604 -263.246108)
		(width 0.0889)
		(layer "In13.Cu")
		(net "M_H_CPU0_SB_CA<3>")
	)
	(arc
		(start 385.207764 -263.233408)
		(mid 384.924808 -263.309585)
		(end 384.641852 -263.233408)
		(width 0.0889)
		(layer "In13.Cu")
		(net "M_H_CPU0_SB_CA<3>")
	)
	(arc
		(start 393.10056 -263.233408)
		(mid 392.923769 -263.182689)
		(end 392.744198 -263.222486)
		(width 0.0889)
		(layer "In13.Cu")
		(net "M_H_CPU0_SB_CA<3>")
	)
	(arc
		(start 387.46176 -263.233408)
		(mid 387.274816 -263.183153)
		(end 387.087872 -263.233408)
		(width 0.0889)
		(layer "In13.Cu")
		(net "M_H_CPU0_SB_CA<3>")
	)
	(arc
		(start 391.221722 -263.233408)
		(mid 391.034778 -263.183153)
		(end 390.847834 -263.233408)
		(width 0.0889)
		(layer "In13.Cu")
		(net "M_H_CPU0_SB_CA<3>")
	)
	(arc
		(start 389.333486 -263.228582)
		(mid 389.149978 -263.183088)
		(end 388.967726 -263.233408)
		(width 0.0889)
		(layer "In13.Cu")
		(net "M_H_CPU0_SB_CA<3>")
	)
	(arc
		(start 385.581906 -263.233408)
		(mid 385.399655 -263.183058)
		(end 385.216146 -263.228582)
		(width 0.0889)
		(layer "In13.Cu")
		(net "M_H_CPU0_SB_CA<3>")
	)
	(arc
		(start 392.140948 -263.222232)
		(mid 391.96287 -263.183248)
		(end 391.787634 -263.233408)
		(width 0.0889)
		(layer "In13.Cu")
		(net "M_H_CPU0_SB_CA<3>")
	)
	(arc
		(start 390.847834 -263.233408)
		(mid 390.564878 -263.309585)
		(end 390.281922 -263.233408)
		(width 0.0889)
		(layer "In13.Cu")
		(net "M_H_CPU0_SB_CA<3>")
	)
	(arc
		(start 388.393432 -263.228582)
		(mid 388.209924 -263.183088)
		(end 388.027672 -263.233408)
		(width 0.0889)
		(layer "In13.Cu")
		(net "M_H_CPU0_SB_CA<3>")
	)
	(segment
		(start 383.517902 -262.480044)
		(end 383.984754 -262.745982)
		(width 0.10668)
		(layer "F.Cu")
		(net "M_H_CPU0_SB_CA<2>")
	)
	(segment
		(start 408.007058 -261.992872)
		(end 408.539696 -262.52551)
		(width 0.14478)
		(layer "In13.Cu")
		(net "M_H_CPU0_SB_CA<2>")
	)
	(segment
		(start 392.234674 -263.055862)
		(end 392.256264 -263.068308)
		(width 0.0889)
		(layer "In13.Cu")
		(net "M_H_CPU0_SB_CA<2>")
	)
	(segment
		(start 414.183068 -263.21004)
		(end 415.032952 -262.360156)
		(width 0.14478)
		(layer "In13.Cu")
		(net "M_H_CPU0_SB_CA<2>")
	)
	(segment
		(start 383.984754 -262.745982)
		(end 384.138932 -263.011412)
		(width 0.0889)
		(layer "In13.Cu")
		(net "M_H_CPU0_SB_CA<2>")
	)
	(segment
		(start 421.875966 -263.21004)
		(end 424.012106 -262.785098)
		(width 0.14478)
		(layer "In13.Cu")
		(net "M_H_CPU0_SB_CA<2>")
	)
	(segment
		(start 395.310106 -262.52043)
		(end 395.956536 -262.52043)
		(width 0.0889)
		(layer "In13.Cu")
		(net "M_H_CPU0_SB_CA<2>")
	)
	(segment
		(start 415.032952 -262.360156)
		(end 418.057584 -262.360156)
		(width 0.14478)
		(layer "In13.Cu")
		(net "M_H_CPU0_SB_CA<2>")
	)
	(segment
		(start 386.984494 -263.07288)
		(end 386.99186 -263.068562)
		(width 0.0889)
		(layer "In13.Cu")
		(net "M_H_CPU0_SB_CA<2>")
	)
	(segment
		(start 412.088838 -263.21004)
		(end 414.183068 -263.21004)
		(width 0.14478)
		(layer "In13.Cu")
		(net "M_H_CPU0_SB_CA<2>")
	)
	(segment
		(start 390.74344 -263.073388)
		(end 390.751822 -263.068562)
		(width 0.0889)
		(layer "In13.Cu")
		(net "M_H_CPU0_SB_CA<2>")
	)
	(segment
		(start 392.256264 -263.068308)
		(end 392.274552 -263.078722)
		(width 0.0889)
		(layer "In13.Cu")
		(net "M_H_CPU0_SB_CA<2>")
	)
	(segment
		(start 418.057584 -262.360156)
		(end 418.907468 -263.21004)
		(width 0.14478)
		(layer "In13.Cu")
		(net "M_H_CPU0_SB_CA<2>")
	)
	(segment
		(start 387.557772 -263.068562)
		(end 387.566154 -263.073388)
		(width 0.0889)
		(layer "In13.Cu")
		(net "M_H_CPU0_SB_CA<2>")
	)
	(segment
		(start 384.138932 -263.011412)
		(end 384.235198 -263.036812)
		(width 0.0889)
		(layer "In13.Cu")
		(net "M_H_CPU0_SB_CA<2>")
	)
	(segment
		(start 418.907468 -263.21004)
		(end 421.875966 -263.21004)
		(width 0.14478)
		(layer "In13.Cu")
		(net "M_H_CPU0_SB_CA<2>")
	)
	(segment
		(start 391.317734 -263.068562)
		(end 391.326116 -263.073388)
		(width 0.0889)
		(layer "In13.Cu")
		(net "M_H_CPU0_SB_CA<2>")
	)
	(segment
		(start 395.956536 -262.52043)
		(end 404.194518 -262.52043)
		(width 0.14478)
		(layer "In13.Cu")
		(net "M_H_CPU0_SB_CA<2>")
	)
	(segment
		(start 393.982194 -263.119616)
		(end 394.38072 -262.72109)
		(width 0.0889)
		(layer "In13.Cu")
		(net "M_H_CPU0_SB_CA<2>")
	)
	(segment
		(start 386.043424 -263.073388)
		(end 386.051806 -263.068562)
		(width 0.0889)
		(layer "In13.Cu")
		(net "M_H_CPU0_SB_CA<2>")
	)
	(segment
		(start 393.384786 -263.119362)
		(end 393.38504 -263.119616)
		(width 0.0889)
		(layer "In13.Cu")
		(net "M_H_CPU0_SB_CA<2>")
	)
	(segment
		(start 408.539696 -262.52551)
		(end 411.404308 -262.52551)
		(width 0.14478)
		(layer "In13.Cu")
		(net "M_H_CPU0_SB_CA<2>")
	)
	(segment
		(start 388.497826 -263.068562)
		(end 388.506208 -263.073388)
		(width 0.0889)
		(layer "In13.Cu")
		(net "M_H_CPU0_SB_CA<2>")
	)
	(segment
		(start 411.404308 -262.52551)
		(end 412.088838 -263.21004)
		(width 0.14478)
		(layer "In13.Cu")
		(net "M_H_CPU0_SB_CA<2>")
	)
	(segment
		(start 386.983478 -263.073388)
		(end 386.984494 -263.07288)
		(width 0.0889)
		(layer "In13.Cu")
		(net "M_H_CPU0_SB_CA<2>")
	)
	(segment
		(start 392.62939 -263.068562)
		(end 392.652758 -263.054846)
		(width 0.0889)
		(layer "In13.Cu")
		(net "M_H_CPU0_SB_CA<2>")
	)
	(segment
		(start 395.109446 -262.72109)
		(end 395.310106 -262.52043)
		(width 0.0889)
		(layer "In13.Cu")
		(net "M_H_CPU0_SB_CA<2>")
	)
	(segment
		(start 404.194518 -262.52043)
		(end 404.722076 -261.992872)
		(width 0.14478)
		(layer "In13.Cu")
		(net "M_H_CPU0_SB_CA<2>")
	)
	(segment
		(start 404.722076 -261.992872)
		(end 408.007058 -261.992872)
		(width 0.14478)
		(layer "In13.Cu")
		(net "M_H_CPU0_SB_CA<2>")
	)
	(segment
		(start 394.38072 -262.72109)
		(end 395.109446 -262.72109)
		(width 0.0889)
		(layer "In13.Cu")
		(net "M_H_CPU0_SB_CA<2>")
	)
	(segment
		(start 393.38504 -263.119616)
		(end 393.982194 -263.119616)
		(width 0.0889)
		(layer "In13.Cu")
		(net "M_H_CPU0_SB_CA<2>")
	)
	(arc
		(start 385.677664 -263.068562)
		(mid 385.859915 -263.118912)
		(end 386.043424 -263.073388)
		(width 0.0889)
		(layer "In13.Cu")
		(net "M_H_CPU0_SB_CA<2>")
	)
	(arc
		(start 386.99186 -263.068562)
		(mid 387.274816 -262.992385)
		(end 387.557772 -263.068562)
		(width 0.0889)
		(layer "In13.Cu")
		(net "M_H_CPU0_SB_CA<2>")
	)
	(arc
		(start 388.871968 -263.068562)
		(mid 389.154924 -262.992385)
		(end 389.43788 -263.068562)
		(width 0.0889)
		(layer "In13.Cu")
		(net "M_H_CPU0_SB_CA<2>")
	)
	(arc
		(start 392.274552 -263.078722)
		(mid 392.453273 -263.118645)
		(end 392.62939 -263.068562)
		(width 0.0889)
		(layer "In13.Cu")
		(net "M_H_CPU0_SB_CA<2>")
	)
	(arc
		(start 389.811768 -263.068562)
		(mid 390.094724 -262.992385)
		(end 390.37768 -263.068562)
		(width 0.0889)
		(layer "In13.Cu")
		(net "M_H_CPU0_SB_CA<2>")
	)
	(arc
		(start 390.751822 -263.068562)
		(mid 391.034778 -262.992385)
		(end 391.317734 -263.068562)
		(width 0.0889)
		(layer "In13.Cu")
		(net "M_H_CPU0_SB_CA<2>")
	)
	(arc
		(start 386.617718 -263.068562)
		(mid 386.799969 -263.118912)
		(end 386.983478 -263.073388)
		(width 0.0889)
		(layer "In13.Cu")
		(net "M_H_CPU0_SB_CA<2>")
	)
	(arc
		(start 386.051806 -263.068562)
		(mid 386.334762 -262.992385)
		(end 386.617718 -263.068562)
		(width 0.0889)
		(layer "In13.Cu")
		(net "M_H_CPU0_SB_CA<2>")
	)
	(arc
		(start 385.111752 -263.068562)
		(mid 385.394708 -262.992385)
		(end 385.677664 -263.068562)
		(width 0.0889)
		(layer "In13.Cu")
		(net "M_H_CPU0_SB_CA<2>")
	)
	(arc
		(start 387.566154 -263.073388)
		(mid 387.749662 -263.118882)
		(end 387.931914 -263.068562)
		(width 0.0889)
		(layer "In13.Cu")
		(net "M_H_CPU0_SB_CA<2>")
	)
	(arc
		(start 389.43788 -263.068562)
		(mid 389.624824 -263.118817)
		(end 389.811768 -263.068562)
		(width 0.0889)
		(layer "In13.Cu")
		(net "M_H_CPU0_SB_CA<2>")
	)
	(arc
		(start 384.235198 -263.036812)
		(mid 384.490263 -262.993461)
		(end 384.737864 -263.068562)
		(width 0.0889)
		(layer "In13.Cu")
		(net "M_H_CPU0_SB_CA<2>")
	)
	(arc
		(start 392.652758 -263.054846)
		(mid 392.926412 -262.991903)
		(end 393.196572 -263.068562)
		(width 0.0889)
		(layer "In13.Cu")
		(net "M_H_CPU0_SB_CA<2>")
	)
	(arc
		(start 388.506208 -263.073388)
		(mid 388.689716 -263.118882)
		(end 388.871968 -263.068562)
		(width 0.0889)
		(layer "In13.Cu")
		(net "M_H_CPU0_SB_CA<2>")
	)
	(arc
		(start 390.37768 -263.068562)
		(mid 390.559931 -263.118912)
		(end 390.74344 -263.073388)
		(width 0.0889)
		(layer "In13.Cu")
		(net "M_H_CPU0_SB_CA<2>")
	)
	(arc
		(start 391.691876 -263.068562)
		(mid 391.961645 -262.992539)
		(end 392.234674 -263.055862)
		(width 0.0889)
		(layer "In13.Cu")
		(net "M_H_CPU0_SB_CA<2>")
	)
	(arc
		(start 384.737864 -263.068562)
		(mid 384.924808 -263.118817)
		(end 385.111752 -263.068562)
		(width 0.0889)
		(layer "In13.Cu")
		(net "M_H_CPU0_SB_CA<2>")
	)
	(arc
		(start 387.931914 -263.068562)
		(mid 388.21487 -262.992385)
		(end 388.497826 -263.068562)
		(width 0.0889)
		(layer "In13.Cu")
		(net "M_H_CPU0_SB_CA<2>")
	)
	(arc
		(start 393.196572 -263.068562)
		(mid 393.287307 -263.106446)
		(end 393.384786 -263.119362)
		(width 0.0889)
		(layer "In13.Cu")
		(net "M_H_CPU0_SB_CA<2>")
	)
	(arc
		(start 391.326116 -263.073388)
		(mid 391.509624 -263.118882)
		(end 391.691876 -263.068562)
		(width 0.0889)
		(layer "In13.Cu")
		(net "M_H_CPU0_SB_CA<2>")
	)
	(segment
		(start 382.577848 -262.480044)
		(end 383.0447 -262.745982)
		(width 0.10668)
		(layer "F.Cu")
		(net "M_H_CPU0_SB_CA<1>")
	)
	(segment
		(start 386.043424 -262.418576)
		(end 386.051806 -262.423402)
		(width 0.0889)
		(layer "In13.Cu")
		(net "M_H_CPU0_SB_CA<1>")
	)
	(segment
		(start 395.95933 -262.06577)
		(end 403.726142 -262.06577)
		(width 0.14478)
		(layer "In13.Cu")
		(net "M_H_CPU0_SB_CA<1>")
	)
	(segment
		(start 387.557772 -262.423402)
		(end 387.566154 -262.418576)
		(width 0.0889)
		(layer "In13.Cu")
		(net "M_H_CPU0_SB_CA<1>")
	)
	(segment
		(start 419.491668 -262.360156)
		(end 419.912038 -261.939786)
		(width 0.14478)
		(layer "In13.Cu")
		(net "M_H_CPU0_SB_CA<1>")
	)
	(segment
		(start 395.118336 -262.372602)
		(end 395.425168 -262.06577)
		(width 0.0889)
		(layer "In13.Cu")
		(net "M_H_CPU0_SB_CA<1>")
	)
	(segment
		(start 386.983478 -262.418576)
		(end 386.984494 -262.419084)
		(width 0.0889)
		(layer "In13.Cu")
		(net "M_H_CPU0_SB_CA<1>")
	)
	(segment
		(start 418.972746 -262.360156)
		(end 419.491668 -262.360156)
		(width 0.14478)
		(layer "In13.Cu")
		(net "M_H_CPU0_SB_CA<1>")
	)
	(segment
		(start 391.317734 -262.423402)
		(end 391.326116 -262.418576)
		(width 0.0889)
		(layer "In13.Cu")
		(net "M_H_CPU0_SB_CA<1>")
	)
	(segment
		(start 388.497826 -262.423402)
		(end 388.506208 -262.418576)
		(width 0.0889)
		(layer "In13.Cu")
		(net "M_H_CPU0_SB_CA<1>")
	)
	(segment
		(start 408.890724 -261.716012)
		(end 409.253944 -261.716012)
		(width 0.14478)
		(layer "In13.Cu")
		(net "M_H_CPU0_SB_CA<1>")
	)
	(segment
		(start 383.0447 -262.745982)
		(end 382.890776 -262.480552)
		(width 0.0889)
		(layer "In13.Cu")
		(net "M_H_CPU0_SB_CA<1>")
	)
	(segment
		(start 409.543504 -261.109714)
		(end 410.826458 -261.109714)
		(width 0.14478)
		(layer "In13.Cu")
		(net "M_H_CPU0_SB_CA<1>")
	)
	(segment
		(start 409.398724 -261.254494)
		(end 409.543504 -261.109714)
		(width 0.14478)
		(layer "In13.Cu")
		(net "M_H_CPU0_SB_CA<1>")
	)
	(segment
		(start 383.79781 -262.423402)
		(end 383.806192 -262.418576)
		(width 0.0889)
		(layer "In13.Cu")
		(net "M_H_CPU0_SB_CA<1>")
	)
	(segment
		(start 408.745944 -261.571232)
		(end 408.890724 -261.716012)
		(width 0.14478)
		(layer "In13.Cu")
		(net "M_H_CPU0_SB_CA<1>")
	)
	(segment
		(start 409.253944 -261.716012)
		(end 409.398724 -261.571232)
		(width 0.14478)
		(layer "In13.Cu")
		(net "M_H_CPU0_SB_CA<1>")
	)
	(segment
		(start 418.122608 -261.510018)
		(end 418.972746 -262.360156)
		(width 0.14478)
		(layer "In13.Cu")
		(net "M_H_CPU0_SB_CA<1>")
	)
	(segment
		(start 390.74344 -262.418576)
		(end 390.751822 -262.423402)
		(width 0.0889)
		(layer "In13.Cu")
		(net "M_H_CPU0_SB_CA<1>")
	)
	(segment
		(start 382.890776 -262.480552)
		(end 382.913128 -262.39724)
		(width 0.0889)
		(layer "In13.Cu")
		(net "M_H_CPU0_SB_CA<1>")
	)
	(segment
		(start 404.682198 -261.109714)
		(end 408.601164 -261.109714)
		(width 0.14478)
		(layer "In13.Cu")
		(net "M_H_CPU0_SB_CA<1>")
	)
	(segment
		(start 419.912038 -261.939786)
		(end 419.912038 -261.93496)
		(width 0.14478)
		(layer "In13.Cu")
		(net "M_H_CPU0_SB_CA<1>")
	)
	(segment
		(start 393.384786 -262.372602)
		(end 395.118336 -262.372602)
		(width 0.0889)
		(layer "In13.Cu")
		(net "M_H_CPU0_SB_CA<1>")
	)
	(segment
		(start 403.726142 -262.06577)
		(end 404.682198 -261.109714)
		(width 0.14478)
		(layer "In13.Cu")
		(net "M_H_CPU0_SB_CA<1>")
	)
	(segment
		(start 386.984494 -262.419084)
		(end 386.99186 -262.423402)
		(width 0.0889)
		(layer "In13.Cu")
		(net "M_H_CPU0_SB_CA<1>")
	)
	(segment
		(start 410.826458 -261.109714)
		(end 412.0769 -262.360156)
		(width 0.14478)
		(layer "In13.Cu")
		(net "M_H_CPU0_SB_CA<1>")
	)
	(segment
		(start 408.745944 -261.254494)
		(end 408.745944 -261.571232)
		(width 0.14478)
		(layer "In13.Cu")
		(net "M_H_CPU0_SB_CA<1>")
	)
	(segment
		(start 391.691876 -262.423402)
		(end 391.70229 -262.429498)
		(width 0.0889)
		(layer "In13.Cu")
		(net "M_H_CPU0_SB_CA<1>")
	)
	(segment
		(start 412.0769 -262.360156)
		(end 414.090104 -262.360156)
		(width 0.14478)
		(layer "In13.Cu")
		(net "M_H_CPU0_SB_CA<1>")
	)
	(segment
		(start 408.601164 -261.109714)
		(end 408.745944 -261.254494)
		(width 0.14478)
		(layer "In13.Cu")
		(net "M_H_CPU0_SB_CA<1>")
	)
	(segment
		(start 414.940242 -261.510018)
		(end 418.122608 -261.510018)
		(width 0.14478)
		(layer "In13.Cu")
		(net "M_H_CPU0_SB_CA<1>")
	)
	(segment
		(start 395.425168 -262.06577)
		(end 395.95933 -262.06577)
		(width 0.0889)
		(layer "In13.Cu")
		(net "M_H_CPU0_SB_CA<1>")
	)
	(segment
		(start 409.398724 -261.571232)
		(end 409.398724 -261.254494)
		(width 0.14478)
		(layer "In13.Cu")
		(net "M_H_CPU0_SB_CA<1>")
	)
	(segment
		(start 392.62431 -262.418576)
		(end 392.632692 -262.423402)
		(width 0.0889)
		(layer "In13.Cu")
		(net "M_H_CPU0_SB_CA<1>")
	)
	(segment
		(start 414.090104 -262.360156)
		(end 414.940242 -261.510018)
		(width 0.14478)
		(layer "In13.Cu")
		(net "M_H_CPU0_SB_CA<1>")
	)
	(arc
		(start 385.111752 -262.423402)
		(mid 385.394708 -262.499579)
		(end 385.677664 -262.423402)
		(width 0.0889)
		(layer "In13.Cu")
		(net "M_H_CPU0_SB_CA<1>")
	)
	(arc
		(start 390.751822 -262.423402)
		(mid 391.034778 -262.499579)
		(end 391.317734 -262.423402)
		(width 0.0889)
		(layer "In13.Cu")
		(net "M_H_CPU0_SB_CA<1>")
	)
	(arc
		(start 393.192508 -262.426958)
		(mid 393.28494 -262.386676)
		(end 393.384786 -262.372602)
		(width 0.0889)
		(layer "In13.Cu")
		(net "M_H_CPU0_SB_CA<1>")
	)
	(arc
		(start 386.99186 -262.423402)
		(mid 387.274816 -262.499579)
		(end 387.557772 -262.423402)
		(width 0.0889)
		(layer "In13.Cu")
		(net "M_H_CPU0_SB_CA<1>")
	)
	(arc
		(start 392.258042 -262.423402)
		(mid 392.440547 -262.372925)
		(end 392.62431 -262.418576)
		(width 0.0889)
		(layer "In13.Cu")
		(net "M_H_CPU0_SB_CA<1>")
	)
	(arc
		(start 385.677664 -262.423402)
		(mid 385.859915 -262.373052)
		(end 386.043424 -262.418576)
		(width 0.0889)
		(layer "In13.Cu")
		(net "M_H_CPU0_SB_CA<1>")
	)
	(arc
		(start 391.326116 -262.418576)
		(mid 391.509624 -262.373082)
		(end 391.691876 -262.423402)
		(width 0.0889)
		(layer "In13.Cu")
		(net "M_H_CPU0_SB_CA<1>")
	)
	(arc
		(start 387.931914 -262.423402)
		(mid 388.21487 -262.499579)
		(end 388.497826 -262.423402)
		(width 0.0889)
		(layer "In13.Cu")
		(net "M_H_CPU0_SB_CA<1>")
	)
	(arc
		(start 384.171952 -262.423402)
		(mid 384.454908 -262.499579)
		(end 384.737864 -262.423402)
		(width 0.0889)
		(layer "In13.Cu")
		(net "M_H_CPU0_SB_CA<1>")
	)
	(arc
		(start 388.871968 -262.423402)
		(mid 389.154924 -262.499579)
		(end 389.43788 -262.423402)
		(width 0.0889)
		(layer "In13.Cu")
		(net "M_H_CPU0_SB_CA<1>")
	)
	(arc
		(start 382.913128 -262.39724)
		(mid 383.07546 -262.374422)
		(end 383.231898 -262.423402)
		(width 0.0889)
		(layer "In13.Cu")
		(net "M_H_CPU0_SB_CA<1>")
	)
	(arc
		(start 389.43788 -262.423402)
		(mid 389.624824 -262.373147)
		(end 389.811768 -262.423402)
		(width 0.0889)
		(layer "In13.Cu")
		(net "M_H_CPU0_SB_CA<1>")
	)
	(arc
		(start 389.811768 -262.423402)
		(mid 390.094724 -262.499579)
		(end 390.37768 -262.423402)
		(width 0.0889)
		(layer "In13.Cu")
		(net "M_H_CPU0_SB_CA<1>")
	)
	(arc
		(start 383.806192 -262.418576)
		(mid 383.9897 -262.373082)
		(end 384.171952 -262.423402)
		(width 0.0889)
		(layer "In13.Cu")
		(net "M_H_CPU0_SB_CA<1>")
	)
	(arc
		(start 383.231898 -262.423402)
		(mid 383.514854 -262.499579)
		(end 383.79781 -262.423402)
		(width 0.0889)
		(layer "In13.Cu")
		(net "M_H_CPU0_SB_CA<1>")
	)
	(arc
		(start 387.566154 -262.418576)
		(mid 387.749662 -262.373082)
		(end 387.931914 -262.423402)
		(width 0.0889)
		(layer "In13.Cu")
		(net "M_H_CPU0_SB_CA<1>")
	)
	(arc
		(start 384.737864 -262.423402)
		(mid 384.924808 -262.373147)
		(end 385.111752 -262.423402)
		(width 0.0889)
		(layer "In13.Cu")
		(net "M_H_CPU0_SB_CA<1>")
	)
	(arc
		(start 391.70229 -262.429498)
		(mid 391.980976 -262.499718)
		(end 392.258042 -262.423402)
		(width 0.0889)
		(layer "In13.Cu")
		(net "M_H_CPU0_SB_CA<1>")
	)
	(arc
		(start 386.617718 -262.423402)
		(mid 386.799969 -262.373052)
		(end 386.983478 -262.418576)
		(width 0.0889)
		(layer "In13.Cu")
		(net "M_H_CPU0_SB_CA<1>")
	)
	(arc
		(start 388.506208 -262.418576)
		(mid 388.689716 -262.373082)
		(end 388.871968 -262.423402)
		(width 0.0889)
		(layer "In13.Cu")
		(net "M_H_CPU0_SB_CA<1>")
	)
	(arc
		(start 386.051806 -262.423402)
		(mid 386.334762 -262.499579)
		(end 386.617718 -262.423402)
		(width 0.0889)
		(layer "In13.Cu")
		(net "M_H_CPU0_SB_CA<1>")
	)
	(arc
		(start 390.37768 -262.423402)
		(mid 390.559931 -262.373052)
		(end 390.74344 -262.418576)
		(width 0.0889)
		(layer "In13.Cu")
		(net "M_H_CPU0_SB_CA<1>")
	)
	(arc
		(start 392.632692 -262.423402)
		(mid 392.91212 -262.499568)
		(end 393.192508 -262.426958)
		(width 0.0889)
		(layer "In13.Cu")
		(net "M_H_CPU0_SB_CA<1>")
	)
	(segment
		(start 382.107948 -261.670038)
		(end 382.5748 -261.935976)
		(width 0.10668)
		(layer "F.Cu")
		(net "M_H_CPU0_SB_CA<0>")
	)
	(segment
		(start 386.147818 -262.258556)
		(end 386.1562 -262.263382)
		(width 0.0889)
		(layer "In13.Cu")
		(net "M_H_CPU0_SB_CA<0>")
	)
	(segment
		(start 403.544786 -261.61111)
		(end 404.495762 -260.660134)
		(width 0.14478)
		(layer "In13.Cu")
		(net "M_H_CPU0_SB_CA<0>")
	)
	(segment
		(start 384.63347 -262.263382)
		(end 384.641852 -262.258556)
		(width 0.0889)
		(layer "In13.Cu")
		(net "M_H_CPU0_SB_CA<0>")
	)
	(segment
		(start 383.693416 -262.263382)
		(end 383.701798 -262.258556)
		(width 0.0889)
		(layer "In13.Cu")
		(net "M_H_CPU0_SB_CA<0>")
	)
	(segment
		(start 393.5222 -262.142732)
		(end 395.042136 -262.142732)
		(width 0.0889)
		(layer "In13.Cu")
		(net "M_H_CPU0_SB_CA<0>")
	)
	(segment
		(start 388.393432 -262.263382)
		(end 388.401814 -262.258556)
		(width 0.0889)
		(layer "In13.Cu")
		(net "M_H_CPU0_SB_CA<0>")
	)
	(segment
		(start 395.042136 -262.142732)
		(end 395.573758 -261.61111)
		(width 0.0889)
		(layer "In13.Cu")
		(net "M_H_CPU0_SB_CA<0>")
	)
	(segment
		(start 382.5748 -261.935976)
		(end 382.728724 -262.201406)
		(width 0.0889)
		(layer "In13.Cu")
		(net "M_H_CPU0_SB_CA<0>")
	)
	(segment
		(start 416.674554 -260.660134)
		(end 420.98976 -261.085076)
		(width 0.14478)
		(layer "In13.Cu")
		(net "M_H_CPU0_SB_CA<0>")
	)
	(segment
		(start 391.787634 -262.258556)
		(end 391.796016 -262.263382)
		(width 0.0889)
		(layer "In13.Cu")
		(net "M_H_CPU0_SB_CA<0>")
	)
	(segment
		(start 404.495762 -260.660134)
		(end 416.674554 -260.660134)
		(width 0.14478)
		(layer "In13.Cu")
		(net "M_H_CPU0_SB_CA<0>")
	)
	(segment
		(start 385.207764 -262.258556)
		(end 385.216146 -262.263382)
		(width 0.0889)
		(layer "In13.Cu")
		(net "M_H_CPU0_SB_CA<0>")
	)
	(segment
		(start 395.573758 -261.61111)
		(end 395.96822 -261.61111)
		(width 0.0889)
		(layer "In13.Cu")
		(net "M_H_CPU0_SB_CA<0>")
	)
	(segment
		(start 395.96822 -261.61111)
		(end 403.544786 -261.61111)
		(width 0.14478)
		(layer "In13.Cu")
		(net "M_H_CPU0_SB_CA<0>")
	)
	(segment
		(start 420.98976 -261.085076)
		(end 424.012106 -261.085076)
		(width 0.14478)
		(layer "In13.Cu")
		(net "M_H_CPU0_SB_CA<0>")
	)
	(segment
		(start 382.728724 -262.201406)
		(end 382.824736 -262.226806)
		(width 0.0889)
		(layer "In13.Cu")
		(net "M_H_CPU0_SB_CA<0>")
	)
	(segment
		(start 389.90778 -262.258556)
		(end 389.916162 -262.263382)
		(width 0.0889)
		(layer "In13.Cu")
		(net "M_H_CPU0_SB_CA<0>")
	)
	(segment
		(start 392.718036 -262.25246)
		(end 392.72845 -262.258556)
		(width 0.0889)
		(layer "In13.Cu")
		(net "M_H_CPU0_SB_CA<0>")
	)
	(segment
		(start 389.333486 -262.263382)
		(end 389.341868 -262.258556)
		(width 0.0889)
		(layer "In13.Cu")
		(net "M_H_CPU0_SB_CA<0>")
	)
	(arc
		(start 389.916162 -262.263382)
		(mid 390.09967 -262.308876)
		(end 390.281922 -262.258556)
		(width 0.0889)
		(layer "In13.Cu")
		(net "M_H_CPU0_SB_CA<0>")
	)
	(arc
		(start 393.086082 -262.2677)
		(mid 393.295365 -262.17459)
		(end 393.5222 -262.142732)
		(width 0.0889)
		(layer "In13.Cu")
		(net "M_H_CPU0_SB_CA<0>")
	)
	(arc
		(start 391.221722 -262.258556)
		(mid 391.504678 -262.182379)
		(end 391.787634 -262.258556)
		(width 0.0889)
		(layer "In13.Cu")
		(net "M_H_CPU0_SB_CA<0>")
	)
	(arc
		(start 383.701798 -262.258556)
		(mid 383.984754 -262.182379)
		(end 384.26771 -262.258556)
		(width 0.0889)
		(layer "In13.Cu")
		(net "M_H_CPU0_SB_CA<0>")
	)
	(arc
		(start 384.26771 -262.258556)
		(mid 384.449961 -262.308906)
		(end 384.63347 -262.263382)
		(width 0.0889)
		(layer "In13.Cu")
		(net "M_H_CPU0_SB_CA<0>")
	)
	(arc
		(start 385.216146 -262.263382)
		(mid 385.399654 -262.308876)
		(end 385.581906 -262.258556)
		(width 0.0889)
		(layer "In13.Cu")
		(net "M_H_CPU0_SB_CA<0>")
	)
	(arc
		(start 388.027672 -262.258556)
		(mid 388.209923 -262.308906)
		(end 388.393432 -262.263382)
		(width 0.0889)
		(layer "In13.Cu")
		(net "M_H_CPU0_SB_CA<0>")
	)
	(arc
		(start 387.46176 -262.258556)
		(mid 387.744716 -262.182379)
		(end 388.027672 -262.258556)
		(width 0.0889)
		(layer "In13.Cu")
		(net "M_H_CPU0_SB_CA<0>")
	)
	(arc
		(start 390.281922 -262.258556)
		(mid 390.564878 -262.182379)
		(end 390.847834 -262.258556)
		(width 0.0889)
		(layer "In13.Cu")
		(net "M_H_CPU0_SB_CA<0>")
	)
	(arc
		(start 385.581906 -262.258556)
		(mid 385.864862 -262.182379)
		(end 386.147818 -262.258556)
		(width 0.0889)
		(layer "In13.Cu")
		(net "M_H_CPU0_SB_CA<0>")
	)
	(arc
		(start 386.1562 -262.263382)
		(mid 386.339708 -262.308876)
		(end 386.52196 -262.258556)
		(width 0.0889)
		(layer "In13.Cu")
		(net "M_H_CPU0_SB_CA<0>")
	)
	(arc
		(start 391.796016 -262.263382)
		(mid 391.979778 -262.308998)
		(end 392.162284 -262.258556)
		(width 0.0889)
		(layer "In13.Cu")
		(net "M_H_CPU0_SB_CA<0>")
	)
	(arc
		(start 388.967726 -262.258556)
		(mid 389.149977 -262.308906)
		(end 389.333486 -262.263382)
		(width 0.0889)
		(layer "In13.Cu")
		(net "M_H_CPU0_SB_CA<0>")
	)
	(arc
		(start 392.72845 -262.258556)
		(mid 392.9061 -262.308816)
		(end 393.086082 -262.2677)
		(width 0.0889)
		(layer "In13.Cu")
		(net "M_H_CPU0_SB_CA<0>")
	)
	(arc
		(start 382.824736 -262.226806)
		(mid 383.079944 -262.183329)
		(end 383.327656 -262.258556)
		(width 0.0889)
		(layer "In13.Cu")
		(net "M_H_CPU0_SB_CA<0>")
	)
	(arc
		(start 386.52196 -262.258556)
		(mid 386.804916 -262.182379)
		(end 387.087872 -262.258556)
		(width 0.0889)
		(layer "In13.Cu")
		(net "M_H_CPU0_SB_CA<0>")
	)
	(arc
		(start 389.341868 -262.258556)
		(mid 389.624824 -262.182379)
		(end 389.90778 -262.258556)
		(width 0.0889)
		(layer "In13.Cu")
		(net "M_H_CPU0_SB_CA<0>")
	)
	(arc
		(start 388.401814 -262.258556)
		(mid 388.68477 -262.182379)
		(end 388.967726 -262.258556)
		(width 0.0889)
		(layer "In13.Cu")
		(net "M_H_CPU0_SB_CA<0>")
	)
	(arc
		(start 383.327656 -262.258556)
		(mid 383.509907 -262.308906)
		(end 383.693416 -262.263382)
		(width 0.0889)
		(layer "In13.Cu")
		(net "M_H_CPU0_SB_CA<0>")
	)
	(arc
		(start 384.641852 -262.258556)
		(mid 384.924808 -262.182379)
		(end 385.207764 -262.258556)
		(width 0.0889)
		(layer "In13.Cu")
		(net "M_H_CPU0_SB_CA<0>")
	)
	(arc
		(start 390.847834 -262.258556)
		(mid 391.034778 -262.308811)
		(end 391.221722 -262.258556)
		(width 0.0889)
		(layer "In13.Cu")
		(net "M_H_CPU0_SB_CA<0>")
	)
	(arc
		(start 387.087872 -262.258556)
		(mid 387.274816 -262.308811)
		(end 387.46176 -262.258556)
		(width 0.0889)
		(layer "In13.Cu")
		(net "M_H_CPU0_SB_CA<0>")
	)
	(arc
		(start 392.162284 -262.258556)
		(mid 392.439351 -262.182285)
		(end 392.718036 -262.25246)
		(width 0.0889)
		(layer "In13.Cu")
		(net "M_H_CPU0_SB_CA<0>")
	)
	(segment
		(start 382.107948 -266.530074)
		(end 382.5748 -266.796012)
		(width 0.10668)
		(layer "F.Cu")
		(net "M_H_CPU0_SA_RSP<0>")
	)
	(segment
		(start 412.22549 -270.010382)
		(end 408.358848 -266.14374)
		(width 0.11684)
		(layer "In13.Cu")
		(net "M_H_CPU0_SA_RSP<0>")
	)
	(segment
		(start 395.878558 -266.14374)
		(end 394.075666 -266.14374)
		(width 0.0889)
		(layer "In13.Cu")
		(net "M_H_CPU0_SA_RSP<0>")
	)
	(segment
		(start 392.795252 -267.157708)
		(end 392.718036 -267.112496)
		(width 0.0889)
		(layer "In13.Cu")
		(net "M_H_CPU0_SA_RSP<0>")
	)
	(segment
		(start 421.904922 -269.585186)
		(end 420.878254 -270.010382)
		(width 0.11684)
		(layer "In13.Cu")
		(net "M_H_CPU0_SA_RSP<0>")
	)
	(segment
		(start 382.425956 -267.052298)
		(end 382.5748 -266.796012)
		(width 0.0889)
		(layer "In13.Cu")
		(net "M_H_CPU0_SA_RSP<0>")
	)
	(segment
		(start 394.075666 -266.14374)
		(end 393.061698 -267.157708)
		(width 0.0889)
		(layer "In13.Cu")
		(net "M_H_CPU0_SA_RSP<0>")
	)
	(segment
		(start 413.366204 -270.010382)
		(end 412.22549 -270.010382)
		(width 0.11684)
		(layer "In13.Cu")
		(net "M_H_CPU0_SA_RSP<0>")
	)
	(segment
		(start 382.449324 -267.140182)
		(end 382.425956 -267.052298)
		(width 0.0889)
		(layer "In13.Cu")
		(net "M_H_CPU0_SA_RSP<0>")
	)
	(segment
		(start 408.358848 -266.14374)
		(end 395.878558 -266.14374)
		(width 0.11684)
		(layer "In13.Cu")
		(net "M_H_CPU0_SA_RSP<0>")
	)
	(segment
		(start 424.012106 -269.585186)
		(end 421.904922 -269.585186)
		(width 0.11684)
		(layer "In13.Cu")
		(net "M_H_CPU0_SA_RSP<0>")
	)
	(segment
		(start 420.878254 -270.010382)
		(end 419.818058 -270.010382)
		(width 0.11684)
		(layer "In13.Cu")
		(net "M_H_CPU0_SA_RSP<0>")
	)
	(segment
		(start 393.061698 -267.157708)
		(end 392.795252 -267.157708)
		(width 0.0889)
		(layer "In13.Cu")
		(net "M_H_CPU0_SA_RSP<0>")
	)
	(segment
		(start 417.765484 -269.160244)
		(end 415.418778 -269.160244)
		(width 0.11684)
		(layer "In13.Cu")
		(net "M_H_CPU0_SA_RSP<0>")
	)
	(segment
		(start 382.769364 -267.106908)
		(end 382.758696 -267.113004)
		(width 0.0889)
		(layer "In13.Cu")
		(net "M_H_CPU0_SA_RSP<0>")
	)
	(segment
		(start 415.418778 -269.160244)
		(end 413.366204 -270.010382)
		(width 0.11684)
		(layer "In13.Cu")
		(net "M_H_CPU0_SA_RSP<0>")
	)
	(segment
		(start 388.401814 -267.118592)
		(end 388.393432 -267.123418)
		(width 0.0889)
		(layer "In13.Cu")
		(net "M_H_CPU0_SA_RSP<0>")
	)
	(segment
		(start 389.916162 -267.123418)
		(end 389.90778 -267.118592)
		(width 0.0889)
		(layer "In13.Cu")
		(net "M_H_CPU0_SA_RSP<0>")
	)
	(segment
		(start 389.341868 -267.118592)
		(end 389.333486 -267.123418)
		(width 0.0889)
		(layer "In13.Cu")
		(net "M_H_CPU0_SA_RSP<0>")
	)
	(segment
		(start 383.34061 -267.118338)
		(end 383.330958 -267.113004)
		(width 0.0889)
		(layer "In13.Cu")
		(net "M_H_CPU0_SA_RSP<0>")
	)
	(segment
		(start 391.796016 -267.123418)
		(end 391.787634 -267.118592)
		(width 0.0889)
		(layer "In13.Cu")
		(net "M_H_CPU0_SA_RSP<0>")
	)
	(segment
		(start 386.1562 -267.123418)
		(end 386.147818 -267.118592)
		(width 0.0889)
		(layer "In13.Cu")
		(net "M_H_CPU0_SA_RSP<0>")
	)
	(segment
		(start 419.818058 -270.010382)
		(end 417.765484 -269.160244)
		(width 0.11684)
		(layer "In13.Cu")
		(net "M_H_CPU0_SA_RSP<0>")
	)
	(segment
		(start 385.216146 -267.123418)
		(end 385.207764 -267.118592)
		(width 0.0889)
		(layer "In13.Cu")
		(net "M_H_CPU0_SA_RSP<0>")
	)
	(segment
		(start 384.641852 -267.118592)
		(end 384.63347 -267.123418)
		(width 0.0889)
		(layer "In13.Cu")
		(net "M_H_CPU0_SA_RSP<0>")
	)
	(arc
		(start 387.087872 -267.118592)
		(mid 386.804916 -267.042415)
		(end 386.52196 -267.118592)
		(width 0.0889)
		(layer "In13.Cu")
		(net "M_H_CPU0_SA_RSP<0>")
	)
	(arc
		(start 387.46176 -267.118592)
		(mid 387.274816 -267.168847)
		(end 387.087872 -267.118592)
		(width 0.0889)
		(layer "In13.Cu")
		(net "M_H_CPU0_SA_RSP<0>")
	)
	(arc
		(start 388.967726 -267.118592)
		(mid 388.68477 -267.042415)
		(end 388.401814 -267.118592)
		(width 0.0889)
		(layer "In13.Cu")
		(net "M_H_CPU0_SA_RSP<0>")
	)
	(arc
		(start 384.26771 -267.118592)
		(mid 383.984754 -267.042415)
		(end 383.701798 -267.118592)
		(width 0.0889)
		(layer "In13.Cu")
		(net "M_H_CPU0_SA_RSP<0>")
	)
	(arc
		(start 391.787634 -267.118592)
		(mid 391.504678 -267.042415)
		(end 391.221722 -267.118592)
		(width 0.0889)
		(layer "In13.Cu")
		(net "M_H_CPU0_SA_RSP<0>")
	)
	(arc
		(start 388.393432 -267.123418)
		(mid 388.209924 -267.168912)
		(end 388.027672 -267.118592)
		(width 0.0889)
		(layer "In13.Cu")
		(net "M_H_CPU0_SA_RSP<0>")
	)
	(arc
		(start 384.63347 -267.123418)
		(mid 384.449962 -267.168912)
		(end 384.26771 -267.118592)
		(width 0.0889)
		(layer "In13.Cu")
		(net "M_H_CPU0_SA_RSP<0>")
	)
	(arc
		(start 383.330958 -267.113004)
		(mid 383.050954 -267.035959)
		(end 382.769364 -267.106908)
		(width 0.0889)
		(layer "In13.Cu")
		(net "M_H_CPU0_SA_RSP<0>")
	)
	(arc
		(start 386.52196 -267.118592)
		(mid 386.339709 -267.168942)
		(end 386.1562 -267.123418)
		(width 0.0889)
		(layer "In13.Cu")
		(net "M_H_CPU0_SA_RSP<0>")
	)
	(arc
		(start 392.718036 -267.112496)
		(mid 392.43935 -267.042276)
		(end 392.162284 -267.118592)
		(width 0.0889)
		(layer "In13.Cu")
		(net "M_H_CPU0_SA_RSP<0>")
	)
	(arc
		(start 385.581906 -267.118592)
		(mid 385.399655 -267.168942)
		(end 385.216146 -267.123418)
		(width 0.0889)
		(layer "In13.Cu")
		(net "M_H_CPU0_SA_RSP<0>")
	)
	(arc
		(start 390.281922 -267.118592)
		(mid 390.099671 -267.168942)
		(end 389.916162 -267.123418)
		(width 0.0889)
		(layer "In13.Cu")
		(net "M_H_CPU0_SA_RSP<0>")
	)
	(arc
		(start 391.221722 -267.118592)
		(mid 391.034778 -267.168847)
		(end 390.847834 -267.118592)
		(width 0.0889)
		(layer "In13.Cu")
		(net "M_H_CPU0_SA_RSP<0>")
	)
	(arc
		(start 389.333486 -267.123418)
		(mid 389.149978 -267.168912)
		(end 388.967726 -267.118592)
		(width 0.0889)
		(layer "In13.Cu")
		(net "M_H_CPU0_SA_RSP<0>")
	)
	(arc
		(start 386.147818 -267.118592)
		(mid 385.864862 -267.042415)
		(end 385.581906 -267.118592)
		(width 0.0889)
		(layer "In13.Cu")
		(net "M_H_CPU0_SA_RSP<0>")
	)
	(arc
		(start 388.027672 -267.118592)
		(mid 387.744716 -267.042415)
		(end 387.46176 -267.118592)
		(width 0.0889)
		(layer "In13.Cu")
		(net "M_H_CPU0_SA_RSP<0>")
	)
	(arc
		(start 392.162284 -267.118592)
		(mid 391.979779 -267.169069)
		(end 391.796016 -267.123418)
		(width 0.0889)
		(layer "In13.Cu")
		(net "M_H_CPU0_SA_RSP<0>")
	)
	(arc
		(start 383.701798 -267.118592)
		(mid 383.521175 -267.167042)
		(end 383.34061 -267.118338)
		(width 0.0889)
		(layer "In13.Cu")
		(net "M_H_CPU0_SA_RSP<0>")
	)
	(arc
		(start 390.847834 -267.118592)
		(mid 390.564878 -267.042415)
		(end 390.281922 -267.118592)
		(width 0.0889)
		(layer "In13.Cu")
		(net "M_H_CPU0_SA_RSP<0>")
	)
	(arc
		(start 385.207764 -267.118592)
		(mid 384.924808 -267.042449)
		(end 384.641852 -267.118592)
		(width 0.0889)
		(layer "In13.Cu")
		(net "M_H_CPU0_SA_RSP<0>")
	)
	(arc
		(start 382.758696 -267.113004)
		(mid 382.607037 -267.160958)
		(end 382.449324 -267.140182)
		(width 0.0889)
		(layer "In13.Cu")
		(net "M_H_CPU0_SA_RSP<0>")
	)
	(arc
		(start 389.90778 -267.118592)
		(mid 389.624824 -267.042415)
		(end 389.341868 -267.118592)
		(width 0.0889)
		(layer "In13.Cu")
		(net "M_H_CPU0_SA_RSP<0>")
	)
	(segment
		(start 381.807974 -256.090166)
		(end 382.274826 -255.824228)
		(width 0.10668)
		(layer "F.Cu")
		(net "M_H_CPU0_SA_PAR")
	)
	(segment
		(start 391.496042 -255.496822)
		(end 391.48766 -255.501648)
		(width 0.0889)
		(layer "In13.Cu")
		(net "M_H_CPU0_SA_PAR")
	)
	(segment
		(start 385.856226 -255.496822)
		(end 385.847844 -255.501648)
		(width 0.0889)
		(layer "In13.Cu")
		(net "M_H_CPU0_SA_PAR")
	)
	(segment
		(start 400.009614 -255.165352)
		(end 398.549876 -256.62509)
		(width 0.14478)
		(layer "In13.Cu")
		(net "M_H_CPU0_SA_PAR")
	)
	(segment
		(start 384.341878 -255.501648)
		(end 384.333496 -255.496822)
		(width 0.0889)
		(layer "In13.Cu")
		(net "M_H_CPU0_SA_PAR")
	)
	(segment
		(start 383.401824 -255.501648)
		(end 383.393442 -255.496822)
		(width 0.0889)
		(layer "In13.Cu")
		(net "M_H_CPU0_SA_PAR")
	)
	(segment
		(start 382.42875 -255.558798)
		(end 382.274826 -255.824228)
		(width 0.0889)
		(layer "In13.Cu")
		(net "M_H_CPU0_SA_PAR")
	)
	(segment
		(start 424.012106 -254.284988)
		(end 420.934388 -253.010162)
		(width 0.14478)
		(layer "In13.Cu")
		(net "M_H_CPU0_SA_PAR")
	)
	(segment
		(start 394.551916 -256.62509)
		(end 393.511278 -255.584452)
		(width 0.0889)
		(layer "In13.Cu")
		(net "M_H_CPU0_SA_PAR")
	)
	(segment
		(start 417.231068 -254.650494)
		(end 416.215068 -254.650494)
		(width 0.14478)
		(layer "In13.Cu")
		(net "M_H_CPU0_SA_PAR")
	)
	(segment
		(start 416.215068 -254.650494)
		(end 415.121852 -255.74371)
		(width 0.14478)
		(layer "In13.Cu")
		(net "M_H_CPU0_SA_PAR")
	)
	(segment
		(start 418.8714 -253.010162)
		(end 417.231068 -254.650494)
		(width 0.14478)
		(layer "In13.Cu")
		(net "M_H_CPU0_SA_PAR")
	)
	(segment
		(start 420.934388 -253.010162)
		(end 418.8714 -253.010162)
		(width 0.14478)
		(layer "In13.Cu")
		(net "M_H_CPU0_SA_PAR")
	)
	(segment
		(start 392.818112 -255.511046)
		(end 392.802364 -255.501902)
		(width 0.0889)
		(layer "In13.Cu")
		(net "M_H_CPU0_SA_PAR")
	)
	(segment
		(start 392.802364 -255.501902)
		(end 392.788648 -255.494028)
		(width 0.0889)
		(layer "In13.Cu")
		(net "M_H_CPU0_SA_PAR")
	)
	(segment
		(start 384.916172 -255.496822)
		(end 384.90779 -255.501648)
		(width 0.0889)
		(layer "In13.Cu")
		(net "M_H_CPU0_SA_PAR")
	)
	(segment
		(start 415.121852 -255.74371)
		(end 404.158196 -255.74371)
		(width 0.14478)
		(layer "In13.Cu")
		(net "M_H_CPU0_SA_PAR")
	)
	(segment
		(start 389.041894 -255.501648)
		(end 389.033512 -255.496822)
		(width 0.0889)
		(layer "In13.Cu")
		(net "M_H_CPU0_SA_PAR")
	)
	(segment
		(start 388.10184 -255.501648)
		(end 388.093458 -255.496822)
		(width 0.0889)
		(layer "In13.Cu")
		(net "M_H_CPU0_SA_PAR")
	)
	(segment
		(start 392.42873 -255.501648)
		(end 392.413998 -255.510284)
		(width 0.0889)
		(layer "In13.Cu")
		(net "M_H_CPU0_SA_PAR")
	)
	(segment
		(start 398.549876 -256.62509)
		(end 395.664436 -256.62509)
		(width 0.14478)
		(layer "In13.Cu")
		(net "M_H_CPU0_SA_PAR")
	)
	(segment
		(start 389.616188 -255.496822)
		(end 389.607806 -255.501648)
		(width 0.0889)
		(layer "In13.Cu")
		(net "M_H_CPU0_SA_PAR")
	)
	(segment
		(start 395.664436 -256.62509)
		(end 394.551916 -256.62509)
		(width 0.0889)
		(layer "In13.Cu")
		(net "M_H_CPU0_SA_PAR")
	)
	(segment
		(start 393.511278 -255.584452)
		(end 393.090654 -255.584452)
		(width 0.0889)
		(layer "In13.Cu")
		(net "M_H_CPU0_SA_PAR")
	)
	(segment
		(start 403.579838 -255.165352)
		(end 400.009614 -255.165352)
		(width 0.14478)
		(layer "In13.Cu")
		(net "M_H_CPU0_SA_PAR")
	)
	(segment
		(start 404.158196 -255.74371)
		(end 403.579838 -255.165352)
		(width 0.14478)
		(layer "In13.Cu")
		(net "M_H_CPU0_SA_PAR")
	)
	(segment
		(start 382.524762 -255.533398)
		(end 382.42875 -255.558798)
		(width 0.0889)
		(layer "In13.Cu")
		(net "M_H_CPU0_SA_PAR")
	)
	(arc
		(start 388.093458 -255.496822)
		(mid 387.90995 -255.451328)
		(end 387.727698 -255.501648)
		(width 0.0889)
		(layer "In13.Cu")
		(net "M_H_CPU0_SA_PAR")
	)
	(arc
		(start 392.413998 -255.510284)
		(mid 392.137015 -255.578088)
		(end 391.86231 -255.501648)
		(width 0.0889)
		(layer "In13.Cu")
		(net "M_H_CPU0_SA_PAR")
	)
	(arc
		(start 384.90779 -255.501648)
		(mid 384.624834 -255.577825)
		(end 384.341878 -255.501648)
		(width 0.0889)
		(layer "In13.Cu")
		(net "M_H_CPU0_SA_PAR")
	)
	(arc
		(start 389.981948 -255.501648)
		(mid 389.799697 -255.451298)
		(end 389.616188 -255.496822)
		(width 0.0889)
		(layer "In13.Cu")
		(net "M_H_CPU0_SA_PAR")
	)
	(arc
		(start 387.727698 -255.501648)
		(mid 387.444742 -255.577825)
		(end 387.161786 -255.501648)
		(width 0.0889)
		(layer "In13.Cu")
		(net "M_H_CPU0_SA_PAR")
	)
	(arc
		(start 383.393442 -255.496822)
		(mid 383.209934 -255.451328)
		(end 383.027682 -255.501648)
		(width 0.0889)
		(layer "In13.Cu")
		(net "M_H_CPU0_SA_PAR")
	)
	(arc
		(start 390.54786 -255.501648)
		(mid 390.264904 -255.577825)
		(end 389.981948 -255.501648)
		(width 0.0889)
		(layer "In13.Cu")
		(net "M_H_CPU0_SA_PAR")
	)
	(arc
		(start 390.921748 -255.501648)
		(mid 390.734804 -255.451393)
		(end 390.54786 -255.501648)
		(width 0.0889)
		(layer "In13.Cu")
		(net "M_H_CPU0_SA_PAR")
	)
	(arc
		(start 393.090654 -255.584452)
		(mid 392.949524 -255.565784)
		(end 392.818112 -255.511046)
		(width 0.0889)
		(layer "In13.Cu")
		(net "M_H_CPU0_SA_PAR")
	)
	(arc
		(start 391.48766 -255.501648)
		(mid 391.204704 -255.577825)
		(end 390.921748 -255.501648)
		(width 0.0889)
		(layer "In13.Cu")
		(net "M_H_CPU0_SA_PAR")
	)
	(arc
		(start 389.607806 -255.501648)
		(mid 389.32485 -255.577825)
		(end 389.041894 -255.501648)
		(width 0.0889)
		(layer "In13.Cu")
		(net "M_H_CPU0_SA_PAR")
	)
	(arc
		(start 387.161786 -255.501648)
		(mid 386.974842 -255.451393)
		(end 386.787898 -255.501648)
		(width 0.0889)
		(layer "In13.Cu")
		(net "M_H_CPU0_SA_PAR")
	)
	(arc
		(start 391.86231 -255.501648)
		(mid 391.679805 -255.451171)
		(end 391.496042 -255.496822)
		(width 0.0889)
		(layer "In13.Cu")
		(net "M_H_CPU0_SA_PAR")
	)
	(arc
		(start 388.667752 -255.501648)
		(mid 388.384796 -255.577825)
		(end 388.10184 -255.501648)
		(width 0.0889)
		(layer "In13.Cu")
		(net "M_H_CPU0_SA_PAR")
	)
	(arc
		(start 383.967736 -255.501648)
		(mid 383.68478 -255.577825)
		(end 383.401824 -255.501648)
		(width 0.0889)
		(layer "In13.Cu")
		(net "M_H_CPU0_SA_PAR")
	)
	(arc
		(start 386.221986 -255.501648)
		(mid 386.039735 -255.451298)
		(end 385.856226 -255.496822)
		(width 0.0889)
		(layer "In13.Cu")
		(net "M_H_CPU0_SA_PAR")
	)
	(arc
		(start 383.027682 -255.501648)
		(mid 382.779969 -255.576868)
		(end 382.524762 -255.533398)
		(width 0.0889)
		(layer "In13.Cu")
		(net "M_H_CPU0_SA_PAR")
	)
	(arc
		(start 386.787898 -255.501648)
		(mid 386.504942 -255.577825)
		(end 386.221986 -255.501648)
		(width 0.0889)
		(layer "In13.Cu")
		(net "M_H_CPU0_SA_PAR")
	)
	(arc
		(start 389.033512 -255.496822)
		(mid 388.850004 -255.451328)
		(end 388.667752 -255.501648)
		(width 0.0889)
		(layer "In13.Cu")
		(net "M_H_CPU0_SA_PAR")
	)
	(arc
		(start 392.788648 -255.494028)
		(mid 392.607718 -255.45155)
		(end 392.42873 -255.501648)
		(width 0.0889)
		(layer "In13.Cu")
		(net "M_H_CPU0_SA_PAR")
	)
	(arc
		(start 385.847844 -255.501648)
		(mid 385.564888 -255.577825)
		(end 385.281932 -255.501648)
		(width 0.0889)
		(layer "In13.Cu")
		(net "M_H_CPU0_SA_PAR")
	)
	(arc
		(start 384.333496 -255.496822)
		(mid 384.149988 -255.451328)
		(end 383.967736 -255.501648)
		(width 0.0889)
		(layer "In13.Cu")
		(net "M_H_CPU0_SA_PAR")
	)
	(arc
		(start 385.281932 -255.501648)
		(mid 385.099681 -255.451298)
		(end 384.916172 -255.496822)
		(width 0.0889)
		(layer "In13.Cu")
		(net "M_H_CPU0_SA_PAR")
	)
	(segment
		(start 381.807974 -247.990106)
		(end 382.274826 -247.724168)
		(width 0.12954)
		(layer "F.Cu")
		(net "M_H_CPU0_SA_DQS_DP<9>")
	)
	(segment
		(start 408.358086 -244.389656)
		(end 408.264106 -244.295676)
		(width 0.16002)
		(layer "In13.Cu")
		(net "M_H_CPU0_SA_DQS_DP<9>")
	)
	(segment
		(start 409.258008 -243.966238)
		(end 408.83459 -244.389656)
		(width 0.16002)
		(layer "In13.Cu")
		(net "M_H_CPU0_SA_DQS_DP<9>")
	)
	(segment
		(start 406.985216 -245.762526)
		(end 406.891236 -245.668546)
		(width 0.16002)
		(layer "In13.Cu")
		(net "M_H_CPU0_SA_DQS_DP<9>")
	)
	(segment
		(start 393.973812 -247.60936)
		(end 393.822174 -247.457976)
		(width 0.09525)
		(layer "In13.Cu")
		(net "M_H_CPU0_SA_DQS_DP<9>")
	)
	(segment
		(start 406.66543 -245.668546)
		(end 406.418542 -245.915434)
		(width 0.16002)
		(layer "In13.Cu")
		(net "M_H_CPU0_SA_DQS_DP<9>")
	)
	(segment
		(start 408.264106 -244.295676)
		(end 408.0383 -244.295676)
		(width 0.16002)
		(layer "In13.Cu")
		(net "M_H_CPU0_SA_DQS_DP<9>")
	)
	(segment
		(start 414.868614 -239.397032)
		(end 414.105598 -240.160048)
		(width 0.16002)
		(layer "In13.Cu")
		(net "M_H_CPU0_SA_DQS_DP<9>")
	)
	(segment
		(start 391.494518 -247.394222)
		(end 391.486136 -247.399048)
		(width 0.09525)
		(layer "In13.Cu")
		(net "M_H_CPU0_SA_DQS_DP<9>")
	)
	(segment
		(start 409.636976 -242.922806)
		(end 409.41117 -242.922806)
		(width 0.16002)
		(layer "In13.Cu")
		(net "M_H_CPU0_SA_DQS_DP<9>")
	)
	(segment
		(start 395.776704 -247.045734)
		(end 395.44244 -247.045734)
		(width 0.09525)
		(layer "In13.Cu")
		(net "M_H_CPU0_SA_DQS_DP<9>")
	)
	(segment
		(start 406.512268 -246.711978)
		(end 406.119584 -247.104662)
		(width 0.16002)
		(layer "In13.Cu")
		(net "M_H_CPU0_SA_DQS_DP<9>")
	)
	(segment
		(start 395.44244 -247.045734)
		(end 394.878814 -247.60936)
		(width 0.09525)
		(layer "In13.Cu")
		(net "M_H_CPU0_SA_DQS_DP<9>")
	)
	(segment
		(start 411.009846 -241.549936)
		(end 410.78404 -241.549936)
		(width 0.16002)
		(layer "In13.Cu")
		(net "M_H_CPU0_SA_DQS_DP<9>")
	)
	(segment
		(start 418.477954 -240.197894)
		(end 416.272472 -240.197894)
		(width 0.16002)
		(layer "In13.Cu")
		(net "M_H_CPU0_SA_DQS_DP<9>")
	)
	(segment
		(start 410.537152 -242.023138)
		(end 410.630878 -242.117118)
		(width 0.16002)
		(layer "In13.Cu")
		(net "M_H_CPU0_SA_DQS_DP<9>")
	)
	(segment
		(start 392.824716 -247.41124)
		(end 392.803888 -247.399048)
		(width 0.09525)
		(layer "In13.Cu")
		(net "M_H_CPU0_SA_DQS_DP<9>")
	)
	(segment
		(start 385.854702 -247.394222)
		(end 385.84632 -247.399048)
		(width 0.09525)
		(layer "In13.Cu")
		(net "M_H_CPU0_SA_DQS_DP<9>")
	)
	(segment
		(start 409.730956 -243.016786)
		(end 409.636976 -242.922806)
		(width 0.16002)
		(layer "In13.Cu")
		(net "M_H_CPU0_SA_DQS_DP<9>")
	)
	(segment
		(start 382.529588 -247.432068)
		(end 382.42875 -247.458738)
		(width 0.09525)
		(layer "In13.Cu")
		(net "M_H_CPU0_SA_DQS_DP<9>")
	)
	(segment
		(start 415.47161 -239.397032)
		(end 414.868614 -239.397032)
		(width 0.16002)
		(layer "In13.Cu")
		(net "M_H_CPU0_SA_DQS_DP<9>")
	)
	(segment
		(start 392.427206 -247.399048)
		(end 392.412474 -247.407684)
		(width 0.09525)
		(layer "In13.Cu")
		(net "M_H_CPU0_SA_DQS_DP<9>")
	)
	(segment
		(start 382.42875 -247.458738)
		(end 382.274826 -247.724168)
		(width 0.09525)
		(layer "In13.Cu")
		(net "M_H_CPU0_SA_DQS_DP<9>")
	)
	(segment
		(start 409.258008 -243.489988)
		(end 409.258008 -243.966238)
		(width 0.16002)
		(layer "In13.Cu")
		(net "M_H_CPU0_SA_DQS_DP<9>")
	)
	(segment
		(start 395.859254 -247.104662)
		(end 395.835632 -247.104662)
		(width 0.09525)
		(layer "In13.Cu")
		(net "M_H_CPU0_SA_DQS_DP<9>")
	)
	(segment
		(start 383.403348 -247.399048)
		(end 383.394966 -247.394222)
		(width 0.09525)
		(layer "In13.Cu")
		(net "M_H_CPU0_SA_DQS_DP<9>")
	)
	(segment
		(start 406.418542 -245.915434)
		(end 406.418542 -246.141748)
		(width 0.16002)
		(layer "In13.Cu")
		(net "M_H_CPU0_SA_DQS_DP<9>")
	)
	(segment
		(start 395.835632 -247.104662)
		(end 395.776704 -247.045734)
		(width 0.09525)
		(layer "In13.Cu")
		(net "M_H_CPU0_SA_DQS_DP<9>")
	)
	(segment
		(start 408.83459 -244.389656)
		(end 408.358086 -244.389656)
		(width 0.16002)
		(layer "In13.Cu")
		(net "M_H_CPU0_SA_DQS_DP<9>")
	)
	(segment
		(start 409.41117 -242.922806)
		(end 409.164282 -243.169694)
		(width 0.16002)
		(layer "In13.Cu")
		(net "M_H_CPU0_SA_DQS_DP<9>")
	)
	(segment
		(start 406.891236 -245.668546)
		(end 406.66543 -245.668546)
		(width 0.16002)
		(layer "In13.Cu")
		(net "M_H_CPU0_SA_DQS_DP<9>")
	)
	(segment
		(start 407.791412 -244.768878)
		(end 407.885138 -244.862858)
		(width 0.16002)
		(layer "In13.Cu")
		(net "M_H_CPU0_SA_DQS_DP<9>")
	)
	(segment
		(start 406.418542 -246.141748)
		(end 406.512268 -246.235728)
		(width 0.16002)
		(layer "In13.Cu")
		(net "M_H_CPU0_SA_DQS_DP<9>")
	)
	(segment
		(start 389.614664 -247.394222)
		(end 389.606282 -247.399048)
		(width 0.09525)
		(layer "In13.Cu")
		(net "M_H_CPU0_SA_DQS_DP<9>")
	)
	(segment
		(start 411.58033 -241.643916)
		(end 411.103826 -241.643916)
		(width 0.16002)
		(layer "In13.Cu")
		(net "M_H_CPU0_SA_DQS_DP<9>")
	)
	(segment
		(start 384.343402 -247.399048)
		(end 384.33502 -247.394222)
		(width 0.09525)
		(layer "In13.Cu")
		(net "M_H_CPU0_SA_DQS_DP<9>")
	)
	(segment
		(start 410.20746 -243.016786)
		(end 409.730956 -243.016786)
		(width 0.16002)
		(layer "In13.Cu")
		(net "M_H_CPU0_SA_DQS_DP<9>")
	)
	(segment
		(start 406.512268 -246.235728)
		(end 406.512268 -246.711978)
		(width 0.16002)
		(layer "In13.Cu")
		(net "M_H_CPU0_SA_DQS_DP<9>")
	)
	(segment
		(start 389.043418 -247.399048)
		(end 389.035036 -247.394222)
		(width 0.09525)
		(layer "In13.Cu")
		(net "M_H_CPU0_SA_DQS_DP<9>")
	)
	(segment
		(start 408.0383 -244.295676)
		(end 407.791412 -244.542564)
		(width 0.16002)
		(layer "In13.Cu")
		(net "M_H_CPU0_SA_DQS_DP<9>")
	)
	(segment
		(start 410.630878 -242.117118)
		(end 410.630878 -242.593368)
		(width 0.16002)
		(layer "In13.Cu")
		(net "M_H_CPU0_SA_DQS_DP<9>")
	)
	(segment
		(start 419.66261 -239.585754)
		(end 419.090094 -239.585754)
		(width 0.16002)
		(layer "In13.Cu")
		(net "M_H_CPU0_SA_DQS_DP<9>")
	)
	(segment
		(start 419.090094 -239.585754)
		(end 418.477954 -240.197894)
		(width 0.16002)
		(layer "In13.Cu")
		(net "M_H_CPU0_SA_DQS_DP<9>")
	)
	(segment
		(start 413.064198 -240.160048)
		(end 411.58033 -241.643916)
		(width 0.16002)
		(layer "In13.Cu")
		(net "M_H_CPU0_SA_DQS_DP<9>")
	)
	(segment
		(start 388.103364 -247.399048)
		(end 388.094982 -247.394222)
		(width 0.09525)
		(layer "In13.Cu")
		(net "M_H_CPU0_SA_DQS_DP<9>")
	)
	(segment
		(start 410.537152 -241.796824)
		(end 410.537152 -242.023138)
		(width 0.16002)
		(layer "In13.Cu")
		(net "M_H_CPU0_SA_DQS_DP<9>")
	)
	(segment
		(start 414.105598 -240.160048)
		(end 413.064198 -240.160048)
		(width 0.16002)
		(layer "In13.Cu")
		(net "M_H_CPU0_SA_DQS_DP<9>")
	)
	(segment
		(start 409.164282 -243.169694)
		(end 409.164282 -243.396008)
		(width 0.16002)
		(layer "In13.Cu")
		(net "M_H_CPU0_SA_DQS_DP<9>")
	)
	(segment
		(start 410.630878 -242.593368)
		(end 410.20746 -243.016786)
		(width 0.16002)
		(layer "In13.Cu")
		(net "M_H_CPU0_SA_DQS_DP<9>")
	)
	(segment
		(start 407.885138 -245.339108)
		(end 407.46172 -245.762526)
		(width 0.16002)
		(layer "In13.Cu")
		(net "M_H_CPU0_SA_DQS_DP<9>")
	)
	(segment
		(start 411.103826 -241.643916)
		(end 411.009846 -241.549936)
		(width 0.16002)
		(layer "In13.Cu")
		(net "M_H_CPU0_SA_DQS_DP<9>")
	)
	(segment
		(start 409.164282 -243.396008)
		(end 409.258008 -243.489988)
		(width 0.16002)
		(layer "In13.Cu")
		(net "M_H_CPU0_SA_DQS_DP<9>")
	)
	(segment
		(start 407.885138 -244.862858)
		(end 407.885138 -245.339108)
		(width 0.16002)
		(layer "In13.Cu")
		(net "M_H_CPU0_SA_DQS_DP<9>")
	)
	(segment
		(start 407.791412 -244.542564)
		(end 407.791412 -244.768878)
		(width 0.16002)
		(layer "In13.Cu")
		(net "M_H_CPU0_SA_DQS_DP<9>")
	)
	(segment
		(start 410.78404 -241.549936)
		(end 410.537152 -241.796824)
		(width 0.16002)
		(layer "In13.Cu")
		(net "M_H_CPU0_SA_DQS_DP<9>")
	)
	(segment
		(start 392.803888 -247.399048)
		(end 392.795506 -247.394222)
		(width 0.09525)
		(layer "In13.Cu")
		(net "M_H_CPU0_SA_DQS_DP<9>")
	)
	(segment
		(start 419.912038 -239.835182)
		(end 419.66261 -239.585754)
		(width 0.16002)
		(layer "In13.Cu")
		(net "M_H_CPU0_SA_DQS_DP<9>")
	)
	(segment
		(start 407.46172 -245.762526)
		(end 406.985216 -245.762526)
		(width 0.16002)
		(layer "In13.Cu")
		(net "M_H_CPU0_SA_DQS_DP<9>")
	)
	(segment
		(start 416.272472 -240.197894)
		(end 415.47161 -239.397032)
		(width 0.16002)
		(layer "In13.Cu")
		(net "M_H_CPU0_SA_DQS_DP<9>")
	)
	(segment
		(start 394.878814 -247.60936)
		(end 393.973812 -247.60936)
		(width 0.09525)
		(layer "In13.Cu")
		(net "M_H_CPU0_SA_DQS_DP<9>")
	)
	(segment
		(start 406.119584 -247.104662)
		(end 395.859254 -247.104662)
		(width 0.16002)
		(layer "In13.Cu")
		(net "M_H_CPU0_SA_DQS_DP<9>")
	)
	(segment
		(start 384.914648 -247.394222)
		(end 384.906266 -247.399048)
		(width 0.09525)
		(layer "In13.Cu")
		(net "M_H_CPU0_SA_DQS_DP<9>")
	)
	(arc
		(start 385.84632 -247.399048)
		(mid 385.564888 -247.474803)
		(end 385.283456 -247.399048)
		(width 0.09525)
		(layer "In13.Cu")
		(net "M_H_CPU0_SA_DQS_DP<9>")
	)
	(arc
		(start 389.035036 -247.394222)
		(mid 388.850004 -247.348308)
		(end 388.666228 -247.399048)
		(width 0.09525)
		(layer "In13.Cu")
		(net "M_H_CPU0_SA_DQS_DP<9>")
	)
	(arc
		(start 386.786374 -247.399048)
		(mid 386.504942 -247.474803)
		(end 386.22351 -247.399048)
		(width 0.09525)
		(layer "In13.Cu")
		(net "M_H_CPU0_SA_DQS_DP<9>")
	)
	(arc
		(start 391.863834 -247.399048)
		(mid 391.679805 -247.348149)
		(end 391.494518 -247.394222)
		(width 0.09525)
		(layer "In13.Cu")
		(net "M_H_CPU0_SA_DQS_DP<9>")
	)
	(arc
		(start 388.094982 -247.394222)
		(mid 387.90995 -247.348308)
		(end 387.726174 -247.399048)
		(width 0.09525)
		(layer "In13.Cu")
		(net "M_H_CPU0_SA_DQS_DP<9>")
	)
	(arc
		(start 389.983472 -247.399048)
		(mid 389.799697 -247.348276)
		(end 389.614664 -247.394222)
		(width 0.09525)
		(layer "In13.Cu")
		(net "M_H_CPU0_SA_DQS_DP<9>")
	)
	(arc
		(start 392.795506 -247.394222)
		(mid 392.610728 -247.348429)
		(end 392.427206 -247.399048)
		(width 0.09525)
		(layer "In13.Cu")
		(net "M_H_CPU0_SA_DQS_DP<9>")
	)
	(arc
		(start 384.33502 -247.394222)
		(mid 384.149988 -247.348308)
		(end 383.966212 -247.399048)
		(width 0.09525)
		(layer "In13.Cu")
		(net "M_H_CPU0_SA_DQS_DP<9>")
	)
	(arc
		(start 393.366752 -247.399048)
		(mid 393.097319 -247.474919)
		(end 392.824716 -247.41124)
		(width 0.09525)
		(layer "In13.Cu")
		(net "M_H_CPU0_SA_DQS_DP<9>")
	)
	(arc
		(start 387.16331 -247.399048)
		(mid 386.974842 -247.348371)
		(end 386.786374 -247.399048)
		(width 0.09525)
		(layer "In13.Cu")
		(net "M_H_CPU0_SA_DQS_DP<9>")
	)
	(arc
		(start 383.394966 -247.394222)
		(mid 383.209934 -247.348308)
		(end 383.026158 -247.399048)
		(width 0.09525)
		(layer "In13.Cu")
		(net "M_H_CPU0_SA_DQS_DP<9>")
	)
	(arc
		(start 387.726174 -247.399048)
		(mid 387.444742 -247.474803)
		(end 387.16331 -247.399048)
		(width 0.09525)
		(layer "In13.Cu")
		(net "M_H_CPU0_SA_DQS_DP<9>")
	)
	(arc
		(start 384.906266 -247.399048)
		(mid 384.624834 -247.474803)
		(end 384.343402 -247.399048)
		(width 0.09525)
		(layer "In13.Cu")
		(net "M_H_CPU0_SA_DQS_DP<9>")
	)
	(arc
		(start 386.22351 -247.399048)
		(mid 386.039735 -247.348276)
		(end 385.854702 -247.394222)
		(width 0.09525)
		(layer "In13.Cu")
		(net "M_H_CPU0_SA_DQS_DP<9>")
	)
	(arc
		(start 393.805918 -247.442736)
		(mid 393.772361 -247.416511)
		(end 393.736068 -247.394222)
		(width 0.09525)
		(layer "In13.Cu")
		(net "M_H_CPU0_SA_DQS_DP<9>")
	)
	(arc
		(start 393.736068 -247.394222)
		(mid 393.550782 -247.348186)
		(end 393.366752 -247.399048)
		(width 0.09525)
		(layer "In13.Cu")
		(net "M_H_CPU0_SA_DQS_DP<9>")
	)
	(arc
		(start 383.026158 -247.399048)
		(mid 382.792614 -247.472754)
		(end 382.549908 -247.439942)
		(width 0.09525)
		(layer "In13.Cu")
		(net "M_H_CPU0_SA_DQS_DP<9>")
	)
	(arc
		(start 388.666228 -247.399048)
		(mid 388.384796 -247.474803)
		(end 388.103364 -247.399048)
		(width 0.09525)
		(layer "In13.Cu")
		(net "M_H_CPU0_SA_DQS_DP<9>")
	)
	(arc
		(start 393.822174 -247.457976)
		(mid 393.814157 -247.450237)
		(end 393.805918 -247.442736)
		(width 0.09525)
		(layer "In13.Cu")
		(net "M_H_CPU0_SA_DQS_DP<9>")
	)
	(arc
		(start 385.283456 -247.399048)
		(mid 385.099681 -247.348276)
		(end 384.914648 -247.394222)
		(width 0.09525)
		(layer "In13.Cu")
		(net "M_H_CPU0_SA_DQS_DP<9>")
	)
	(arc
		(start 382.549908 -247.439942)
		(mid 382.539709 -247.436105)
		(end 382.529588 -247.432068)
		(width 0.09525)
		(layer "In13.Cu")
		(net "M_H_CPU0_SA_DQS_DP<9>")
	)
	(arc
		(start 390.546336 -247.399048)
		(mid 390.264904 -247.474803)
		(end 389.983472 -247.399048)
		(width 0.09525)
		(layer "In13.Cu")
		(net "M_H_CPU0_SA_DQS_DP<9>")
	)
	(arc
		(start 390.923272 -247.399048)
		(mid 390.734804 -247.348371)
		(end 390.546336 -247.399048)
		(width 0.09525)
		(layer "In13.Cu")
		(net "M_H_CPU0_SA_DQS_DP<9>")
	)
	(arc
		(start 391.486136 -247.399048)
		(mid 391.204704 -247.474803)
		(end 390.923272 -247.399048)
		(width 0.09525)
		(layer "In13.Cu")
		(net "M_H_CPU0_SA_DQS_DP<9>")
	)
	(arc
		(start 383.966212 -247.399048)
		(mid 383.68478 -247.474803)
		(end 383.403348 -247.399048)
		(width 0.09525)
		(layer "In13.Cu")
		(net "M_H_CPU0_SA_DQS_DP<9>")
	)
	(arc
		(start 392.412474 -247.407684)
		(mid 392.137015 -247.475069)
		(end 391.863834 -247.399048)
		(width 0.09525)
		(layer "In13.Cu")
		(net "M_H_CPU0_SA_DQS_DP<9>")
	)
	(arc
		(start 389.606282 -247.399048)
		(mid 389.32485 -247.474803)
		(end 389.043418 -247.399048)
		(width 0.09525)
		(layer "In13.Cu")
		(net "M_H_CPU0_SA_DQS_DP<9>")
	)
	(segment
		(start 381.807974 -243.13007)
		(end 382.274826 -242.864132)
		(width 0.12954)
		(layer "F.Cu")
		(net "M_H_CPU0_SA_DQS_DP<8>")
	)
	(segment
		(start 395.537436 -241.443764)
		(end 394.826998 -242.154202)
		(width 0.09525)
		(layer "In13.Cu")
		(net "M_H_CPU0_SA_DQS_DP<8>")
	)
	(segment
		(start 384.343402 -242.539012)
		(end 384.33502 -242.534186)
		(width 0.09525)
		(layer "In13.Cu")
		(net "M_H_CPU0_SA_DQS_DP<8>")
	)
	(segment
		(start 409.22321 -232.115614)
		(end 408.99715 -232.115614)
		(width 0.16002)
		(layer "In13.Cu")
		(net "M_H_CPU0_SA_DQS_DP<8>")
	)
	(segment
		(start 389.614664 -242.534186)
		(end 389.606282 -242.539012)
		(width 0.09525)
		(layer "In13.Cu")
		(net "M_H_CPU0_SA_DQS_DP<8>")
	)
	(segment
		(start 407.707084 -234.767628)
		(end 406.951434 -235.523278)
		(width 0.16002)
		(layer "In13.Cu")
		(net "M_H_CPU0_SA_DQS_DP<8>")
	)
	(segment
		(start 407.377392 -233.735372)
		(end 407.377392 -233.961432)
		(width 0.16002)
		(layer "In13.Cu")
		(net "M_H_CPU0_SA_DQS_DP<8>")
	)
	(segment
		(start 414.875218 -230.040434)
		(end 414.105598 -230.810054)
		(width 0.16002)
		(layer "In13.Cu")
		(net "M_H_CPU0_SA_DQS_DP<8>")
	)
	(segment
		(start 410.452824 -232.021888)
		(end 410.029406 -232.445306)
		(width 0.16002)
		(layer "In13.Cu")
		(net "M_H_CPU0_SA_DQS_DP<8>")
	)
	(segment
		(start 410.59608 -230.742744)
		(end 410.37002 -230.742744)
		(width 0.16002)
		(layer "In13.Cu")
		(net "M_H_CPU0_SA_DQS_DP<8>")
	)
	(segment
		(start 410.123132 -231.215692)
		(end 410.452824 -231.545384)
		(width 0.16002)
		(layer "In13.Cu")
		(net "M_H_CPU0_SA_DQS_DP<8>")
	)
	(segment
		(start 414.105598 -230.810054)
		(end 411.664658 -230.810054)
		(width 0.16002)
		(layer "In13.Cu")
		(net "M_H_CPU0_SA_DQS_DP<8>")
	)
	(segment
		(start 382.42875 -242.598702)
		(end 382.274826 -242.864132)
		(width 0.09525)
		(layer "In13.Cu")
		(net "M_H_CPU0_SA_DQS_DP<8>")
	)
	(segment
		(start 388.103364 -242.539012)
		(end 388.094982 -242.534186)
		(width 0.09525)
		(layer "In13.Cu")
		(net "M_H_CPU0_SA_DQS_DP<8>")
	)
	(segment
		(start 391.494518 -242.534186)
		(end 391.486136 -242.539012)
		(width 0.09525)
		(layer "In13.Cu")
		(net "M_H_CPU0_SA_DQS_DP<8>")
	)
	(segment
		(start 395.764004 -241.502692)
		(end 395.705076 -241.443764)
		(width 0.09525)
		(layer "In13.Cu")
		(net "M_H_CPU0_SA_DQS_DP<8>")
	)
	(segment
		(start 408.180032 -233.818176)
		(end 407.85034 -233.488484)
		(width 0.16002)
		(layer "In13.Cu")
		(net "M_H_CPU0_SA_DQS_DP<8>")
	)
	(segment
		(start 395.787626 -241.502692)
		(end 395.764004 -241.502692)
		(width 0.09525)
		(layer "In13.Cu")
		(net "M_H_CPU0_SA_DQS_DP<8>")
	)
	(segment
		(start 410.925772 -231.072436)
		(end 410.59608 -230.742744)
		(width 0.16002)
		(layer "In13.Cu")
		(net "M_H_CPU0_SA_DQS_DP<8>")
	)
	(segment
		(start 410.029406 -232.445306)
		(end 409.552902 -232.445306)
		(width 0.16002)
		(layer "In13.Cu")
		(net "M_H_CPU0_SA_DQS_DP<8>")
	)
	(segment
		(start 394.826998 -242.154202)
		(end 394.325348 -242.154202)
		(width 0.09525)
		(layer "In13.Cu")
		(net "M_H_CPU0_SA_DQS_DP<8>")
	)
	(segment
		(start 393.864338 -242.615212)
		(end 392.146028 -242.615212)
		(width 0.09525)
		(layer "In13.Cu")
		(net "M_H_CPU0_SA_DQS_DP<8>")
	)
	(segment
		(start 407.85034 -233.488484)
		(end 407.62428 -233.488484)
		(width 0.16002)
		(layer "In13.Cu")
		(net "M_H_CPU0_SA_DQS_DP<8>")
	)
	(segment
		(start 406.04821 -235.523278)
		(end 400.068796 -241.502692)
		(width 0.16002)
		(layer "In13.Cu")
		(net "M_H_CPU0_SA_DQS_DP<8>")
	)
	(segment
		(start 406.951434 -235.523278)
		(end 406.04821 -235.523278)
		(width 0.16002)
		(layer "In13.Cu")
		(net "M_H_CPU0_SA_DQS_DP<8>")
	)
	(segment
		(start 409.079954 -233.394758)
		(end 408.656536 -233.818176)
		(width 0.16002)
		(layer "In13.Cu")
		(net "M_H_CPU0_SA_DQS_DP<8>")
	)
	(segment
		(start 417.806378 -230.040434)
		(end 414.875218 -230.040434)
		(width 0.16002)
		(layer "In13.Cu")
		(net "M_H_CPU0_SA_DQS_DP<8>")
	)
	(segment
		(start 394.325348 -242.154202)
		(end 393.864338 -242.615212)
		(width 0.09525)
		(layer "In13.Cu")
		(net "M_H_CPU0_SA_DQS_DP<8>")
	)
	(segment
		(start 410.123132 -230.989632)
		(end 410.123132 -231.215692)
		(width 0.16002)
		(layer "In13.Cu")
		(net "M_H_CPU0_SA_DQS_DP<8>")
	)
	(segment
		(start 408.750262 -232.588562)
		(end 409.079954 -232.918254)
		(width 0.16002)
		(layer "In13.Cu")
		(net "M_H_CPU0_SA_DQS_DP<8>")
	)
	(segment
		(start 419.912038 -230.485188)
		(end 419.614604 -230.187754)
		(width 0.16002)
		(layer "In13.Cu")
		(net "M_H_CPU0_SA_DQS_DP<8>")
	)
	(segment
		(start 407.707084 -234.291124)
		(end 407.707084 -234.767628)
		(width 0.16002)
		(layer "In13.Cu")
		(net "M_H_CPU0_SA_DQS_DP<8>")
	)
	(segment
		(start 385.854702 -242.534186)
		(end 385.84632 -242.539012)
		(width 0.09525)
		(layer "In13.Cu")
		(net "M_H_CPU0_SA_DQS_DP<8>")
	)
	(segment
		(start 409.079954 -232.918254)
		(end 409.079954 -233.394758)
		(width 0.16002)
		(layer "In13.Cu")
		(net "M_H_CPU0_SA_DQS_DP<8>")
	)
	(segment
		(start 410.452824 -231.545384)
		(end 410.452824 -232.021888)
		(width 0.16002)
		(layer "In13.Cu")
		(net "M_H_CPU0_SA_DQS_DP<8>")
	)
	(segment
		(start 384.914648 -242.534186)
		(end 384.906266 -242.539012)
		(width 0.09525)
		(layer "In13.Cu")
		(net "M_H_CPU0_SA_DQS_DP<8>")
	)
	(segment
		(start 407.62428 -233.488484)
		(end 407.377392 -233.735372)
		(width 0.16002)
		(layer "In13.Cu")
		(net "M_H_CPU0_SA_DQS_DP<8>")
	)
	(segment
		(start 419.614604 -230.187754)
		(end 417.953698 -230.187754)
		(width 0.16002)
		(layer "In13.Cu")
		(net "M_H_CPU0_SA_DQS_DP<8>")
	)
	(segment
		(start 408.99715 -232.115614)
		(end 408.750262 -232.362502)
		(width 0.16002)
		(layer "In13.Cu")
		(net "M_H_CPU0_SA_DQS_DP<8>")
	)
	(segment
		(start 408.656536 -233.818176)
		(end 408.180032 -233.818176)
		(width 0.16002)
		(layer "In13.Cu")
		(net "M_H_CPU0_SA_DQS_DP<8>")
	)
	(segment
		(start 389.043418 -242.539012)
		(end 389.035036 -242.534186)
		(width 0.09525)
		(layer "In13.Cu")
		(net "M_H_CPU0_SA_DQS_DP<8>")
	)
	(segment
		(start 411.664658 -230.810054)
		(end 411.402276 -231.072436)
		(width 0.16002)
		(layer "In13.Cu")
		(net "M_H_CPU0_SA_DQS_DP<8>")
	)
	(segment
		(start 407.377392 -233.961432)
		(end 407.707084 -234.291124)
		(width 0.16002)
		(layer "In13.Cu")
		(net "M_H_CPU0_SA_DQS_DP<8>")
	)
	(segment
		(start 382.529588 -242.572032)
		(end 382.42875 -242.598702)
		(width 0.09525)
		(layer "In13.Cu")
		(net "M_H_CPU0_SA_DQS_DP<8>")
	)
	(segment
		(start 383.403348 -242.539012)
		(end 383.394966 -242.534186)
		(width 0.09525)
		(layer "In13.Cu")
		(net "M_H_CPU0_SA_DQS_DP<8>")
	)
	(segment
		(start 411.402276 -231.072436)
		(end 410.925772 -231.072436)
		(width 0.16002)
		(layer "In13.Cu")
		(net "M_H_CPU0_SA_DQS_DP<8>")
	)
	(segment
		(start 410.37002 -230.742744)
		(end 410.123132 -230.989632)
		(width 0.16002)
		(layer "In13.Cu")
		(net "M_H_CPU0_SA_DQS_DP<8>")
	)
	(segment
		(start 400.068796 -241.502692)
		(end 395.787626 -241.502692)
		(width 0.16002)
		(layer "In13.Cu")
		(net "M_H_CPU0_SA_DQS_DP<8>")
	)
	(segment
		(start 395.705076 -241.443764)
		(end 395.537436 -241.443764)
		(width 0.09525)
		(layer "In13.Cu")
		(net "M_H_CPU0_SA_DQS_DP<8>")
	)
	(segment
		(start 409.552902 -232.445306)
		(end 409.22321 -232.115614)
		(width 0.16002)
		(layer "In13.Cu")
		(net "M_H_CPU0_SA_DQS_DP<8>")
	)
	(segment
		(start 417.953698 -230.187754)
		(end 417.806378 -230.040434)
		(width 0.16002)
		(layer "In13.Cu")
		(net "M_H_CPU0_SA_DQS_DP<8>")
	)
	(segment
		(start 408.750262 -232.362502)
		(end 408.750262 -232.588562)
		(width 0.16002)
		(layer "In13.Cu")
		(net "M_H_CPU0_SA_DQS_DP<8>")
	)
	(arc
		(start 382.549908 -242.579906)
		(mid 382.539709 -242.576069)
		(end 382.529588 -242.572032)
		(width 0.09525)
		(layer "In13.Cu")
		(net "M_H_CPU0_SA_DQS_DP<8>")
	)
	(arc
		(start 389.035036 -242.534186)
		(mid 388.850004 -242.488272)
		(end 388.666228 -242.539012)
		(width 0.09525)
		(layer "In13.Cu")
		(net "M_H_CPU0_SA_DQS_DP<8>")
	)
	(arc
		(start 386.786374 -242.539012)
		(mid 386.504942 -242.614767)
		(end 386.22351 -242.539012)
		(width 0.09525)
		(layer "In13.Cu")
		(net "M_H_CPU0_SA_DQS_DP<8>")
	)
	(arc
		(start 383.394966 -242.534186)
		(mid 383.209934 -242.488272)
		(end 383.026158 -242.539012)
		(width 0.09525)
		(layer "In13.Cu")
		(net "M_H_CPU0_SA_DQS_DP<8>")
	)
	(arc
		(start 387.726174 -242.539012)
		(mid 387.444742 -242.614767)
		(end 387.16331 -242.539012)
		(width 0.09525)
		(layer "In13.Cu")
		(net "M_H_CPU0_SA_DQS_DP<8>")
	)
	(arc
		(start 386.22351 -242.539012)
		(mid 386.039735 -242.48824)
		(end 385.854702 -242.534186)
		(width 0.09525)
		(layer "In13.Cu")
		(net "M_H_CPU0_SA_DQS_DP<8>")
	)
	(arc
		(start 387.16331 -242.539012)
		(mid 386.974842 -242.488335)
		(end 386.786374 -242.539012)
		(width 0.09525)
		(layer "In13.Cu")
		(net "M_H_CPU0_SA_DQS_DP<8>")
	)
	(arc
		(start 391.863834 -242.539012)
		(mid 391.679805 -242.488113)
		(end 391.494518 -242.534186)
		(width 0.09525)
		(layer "In13.Cu")
		(net "M_H_CPU0_SA_DQS_DP<8>")
	)
	(arc
		(start 384.906266 -242.539012)
		(mid 384.624834 -242.614767)
		(end 384.343402 -242.539012)
		(width 0.09525)
		(layer "In13.Cu")
		(net "M_H_CPU0_SA_DQS_DP<8>")
	)
	(arc
		(start 383.026158 -242.539012)
		(mid 382.792614 -242.612718)
		(end 382.549908 -242.579906)
		(width 0.09525)
		(layer "In13.Cu")
		(net "M_H_CPU0_SA_DQS_DP<8>")
	)
	(arc
		(start 389.606282 -242.539012)
		(mid 389.32485 -242.614767)
		(end 389.043418 -242.539012)
		(width 0.09525)
		(layer "In13.Cu")
		(net "M_H_CPU0_SA_DQS_DP<8>")
	)
	(arc
		(start 385.283456 -242.539012)
		(mid 385.099681 -242.48824)
		(end 384.914648 -242.534186)
		(width 0.09525)
		(layer "In13.Cu")
		(net "M_H_CPU0_SA_DQS_DP<8>")
	)
	(arc
		(start 383.966212 -242.539012)
		(mid 383.68478 -242.614767)
		(end 383.403348 -242.539012)
		(width 0.09525)
		(layer "In13.Cu")
		(net "M_H_CPU0_SA_DQS_DP<8>")
	)
	(arc
		(start 391.486136 -242.539012)
		(mid 391.204704 -242.614767)
		(end 390.923272 -242.539012)
		(width 0.09525)
		(layer "In13.Cu")
		(net "M_H_CPU0_SA_DQS_DP<8>")
	)
	(arc
		(start 388.666228 -242.539012)
		(mid 388.384796 -242.614767)
		(end 388.103364 -242.539012)
		(width 0.09525)
		(layer "In13.Cu")
		(net "M_H_CPU0_SA_DQS_DP<8>")
	)
	(arc
		(start 392.146028 -242.615212)
		(mid 391.999869 -242.595841)
		(end 391.863834 -242.539012)
		(width 0.09525)
		(layer "In13.Cu")
		(net "M_H_CPU0_SA_DQS_DP<8>")
	)
	(arc
		(start 385.84632 -242.539012)
		(mid 385.564888 -242.614767)
		(end 385.283456 -242.539012)
		(width 0.09525)
		(layer "In13.Cu")
		(net "M_H_CPU0_SA_DQS_DP<8>")
	)
	(arc
		(start 384.33502 -242.534186)
		(mid 384.149988 -242.488272)
		(end 383.966212 -242.539012)
		(width 0.09525)
		(layer "In13.Cu")
		(net "M_H_CPU0_SA_DQS_DP<8>")
	)
	(arc
		(start 389.983472 -242.539012)
		(mid 389.799697 -242.48824)
		(end 389.614664 -242.534186)
		(width 0.09525)
		(layer "In13.Cu")
		(net "M_H_CPU0_SA_DQS_DP<8>")
	)
	(arc
		(start 390.546336 -242.539012)
		(mid 390.264904 -242.614767)
		(end 389.983472 -242.539012)
		(width 0.09525)
		(layer "In13.Cu")
		(net "M_H_CPU0_SA_DQS_DP<8>")
	)
	(arc
		(start 390.923272 -242.539012)
		(mid 390.734804 -242.488335)
		(end 390.546336 -242.539012)
		(width 0.09525)
		(layer "In13.Cu")
		(net "M_H_CPU0_SA_DQS_DP<8>")
	)
	(arc
		(start 388.094982 -242.534186)
		(mid 387.90995 -242.488272)
		(end 387.726174 -242.539012)
		(width 0.09525)
		(layer "In13.Cu")
		(net "M_H_CPU0_SA_DQS_DP<8>")
	)
	(segment
		(start 381.807974 -238.270034)
		(end 382.274826 -238.004096)
		(width 0.12954)
		(layer "F.Cu")
		(net "M_H_CPU0_SA_DQS_DP<7>")
	)
	(segment
		(start 383.403348 -237.678976)
		(end 383.394966 -237.67415)
		(width 0.09525)
		(layer "In13.Cu")
		(net "M_H_CPU0_SA_DQS_DP<7>")
	)
	(segment
		(start 394.885418 -236.277912)
		(end 394.525754 -236.277912)
		(width 0.09525)
		(layer "In13.Cu")
		(net "M_H_CPU0_SA_DQS_DP<7>")
	)
	(segment
		(start 411.259528 -221.85122)
		(end 408.868372 -221.85122)
		(width 0.16002)
		(layer "In13.Cu")
		(net "M_H_CPU0_SA_DQS_DP<7>")
	)
	(segment
		(start 411.79242 -220.811852)
		(end 411.596586 -221.007686)
		(width 0.16002)
		(layer "In13.Cu")
		(net "M_H_CPU0_SA_DQS_DP<7>")
	)
	(segment
		(start 414.105598 -221.46006)
		(end 413.61233 -221.46006)
		(width 0.16002)
		(layer "In13.Cu")
		(net "M_H_CPU0_SA_DQS_DP<7>")
	)
	(segment
		(start 382.42875 -237.738666)
		(end 382.274826 -238.004096)
		(width 0.09525)
		(layer "In13.Cu")
		(net "M_H_CPU0_SA_DQS_DP<7>")
	)
	(segment
		(start 407.959052 -223.828356)
		(end 407.482548 -223.828356)
		(width 0.16002)
		(layer "In13.Cu")
		(net "M_H_CPU0_SA_DQS_DP<7>")
	)
	(segment
		(start 395.458188 -235.705142)
		(end 394.885418 -236.277912)
		(width 0.09525)
		(layer "In13.Cu")
		(net "M_H_CPU0_SA_DQS_DP<7>")
	)
	(segment
		(start 419.396926 -220.891354)
		(end 418.740844 -221.547436)
		(width 0.16002)
		(layer "In13.Cu")
		(net "M_H_CPU0_SA_DQS_DP<7>")
	)
	(segment
		(start 413.22117 -221.85122)
		(end 412.601918 -221.85122)
		(width 0.16002)
		(layer "In13.Cu")
		(net "M_H_CPU0_SA_DQS_DP<7>")
	)
	(segment
		(start 404.295102 -228.77907)
		(end 397.310102 -235.76407)
		(width 0.16002)
		(layer "In13.Cu")
		(net "M_H_CPU0_SA_DQS_DP<7>")
	)
	(segment
		(start 418.740844 -221.547436)
		(end 418.264086 -221.547436)
		(width 0.16002)
		(layer "In13.Cu")
		(net "M_H_CPU0_SA_DQS_DP<7>")
	)
	(segment
		(start 393.36472 -237.679738)
		(end 393.360656 -237.682024)
		(width 0.09525)
		(layer "In13.Cu")
		(net "M_H_CPU0_SA_DQS_DP<7>")
	)
	(segment
		(start 389.614664 -237.67415)
		(end 389.606282 -237.678976)
		(width 0.09525)
		(layer "In13.Cu")
		(net "M_H_CPU0_SA_DQS_DP<7>")
	)
	(segment
		(start 412.26486 -221.007686)
		(end 412.069026 -220.811852)
		(width 0.16002)
		(layer "In13.Cu")
		(net "M_H_CPU0_SA_DQS_DP<7>")
	)
	(segment
		(start 407.299922 -223.64573)
		(end 407.073862 -223.64573)
		(width 0.16002)
		(layer "In13.Cu")
		(net "M_H_CPU0_SA_DQS_DP<7>")
	)
	(segment
		(start 404.295102 -226.42449)
		(end 404.295102 -228.77907)
		(width 0.16002)
		(layer "In13.Cu")
		(net "M_H_CPU0_SA_DQS_DP<7>")
	)
	(segment
		(start 394.525754 -236.277912)
		(end 394.287756 -236.51591)
		(width 0.09525)
		(layer "In13.Cu")
		(net "M_H_CPU0_SA_DQS_DP<7>")
	)
	(segment
		(start 412.26486 -221.514162)
		(end 412.26486 -221.007686)
		(width 0.16002)
		(layer "In13.Cu")
		(net "M_H_CPU0_SA_DQS_DP<7>")
	)
	(segment
		(start 418.264086 -221.547436)
		(end 417.717986 -221.001336)
		(width 0.16002)
		(layer "In13.Cu")
		(net "M_H_CPU0_SA_DQS_DP<7>")
	)
	(segment
		(start 393.36599 -237.678976)
		(end 393.36472 -237.679738)
		(width 0.09525)
		(layer "In13.Cu")
		(net "M_H_CPU0_SA_DQS_DP<7>")
	)
	(segment
		(start 416.197542 -220.20022)
		(end 415.365438 -220.20022)
		(width 0.16002)
		(layer "In13.Cu")
		(net "M_H_CPU0_SA_DQS_DP<7>")
	)
	(segment
		(start 395.835632 -235.76407)
		(end 395.776704 -235.705142)
		(width 0.09525)
		(layer "In13.Cu")
		(net "M_H_CPU0_SA_DQS_DP<7>")
	)
	(segment
		(start 384.914648 -237.67415)
		(end 384.906266 -237.678976)
		(width 0.09525)
		(layer "In13.Cu")
		(net "M_H_CPU0_SA_DQS_DP<7>")
	)
	(segment
		(start 395.776704 -235.705142)
		(end 395.458188 -235.705142)
		(width 0.09525)
		(layer "In13.Cu")
		(net "M_H_CPU0_SA_DQS_DP<7>")
	)
	(segment
		(start 416.998658 -221.001336)
		(end 416.197542 -220.20022)
		(width 0.16002)
		(layer "In13.Cu")
		(net "M_H_CPU0_SA_DQS_DP<7>")
	)
	(segment
		(start 408.38247 -222.928434)
		(end 408.38247 -223.404938)
		(width 0.16002)
		(layer "In13.Cu")
		(net "M_H_CPU0_SA_DQS_DP<7>")
	)
	(segment
		(start 411.596586 -221.514162)
		(end 411.259528 -221.85122)
		(width 0.16002)
		(layer "In13.Cu")
		(net "M_H_CPU0_SA_DQS_DP<7>")
	)
	(segment
		(start 408.199844 -222.745808)
		(end 408.38247 -222.928434)
		(width 0.16002)
		(layer "In13.Cu")
		(net "M_H_CPU0_SA_DQS_DP<7>")
	)
	(segment
		(start 384.343402 -237.678976)
		(end 384.33502 -237.67415)
		(width 0.09525)
		(layer "In13.Cu")
		(net "M_H_CPU0_SA_DQS_DP<7>")
	)
	(segment
		(start 385.854702 -237.67415)
		(end 385.84632 -237.678976)
		(width 0.09525)
		(layer "In13.Cu")
		(net "M_H_CPU0_SA_DQS_DP<7>")
	)
	(segment
		(start 407.482548 -223.828356)
		(end 407.299922 -223.64573)
		(width 0.16002)
		(layer "In13.Cu")
		(net "M_H_CPU0_SA_DQS_DP<7>")
	)
	(segment
		(start 419.912038 -221.13494)
		(end 419.668452 -220.891354)
		(width 0.16002)
		(layer "In13.Cu")
		(net "M_H_CPU0_SA_DQS_DP<7>")
	)
	(segment
		(start 389.043418 -237.678976)
		(end 389.035036 -237.67415)
		(width 0.09525)
		(layer "In13.Cu")
		(net "M_H_CPU0_SA_DQS_DP<7>")
	)
	(segment
		(start 382.529588 -237.711996)
		(end 382.42875 -237.738666)
		(width 0.09525)
		(layer "In13.Cu")
		(net "M_H_CPU0_SA_DQS_DP<7>")
	)
	(segment
		(start 408.38247 -223.404938)
		(end 407.959052 -223.828356)
		(width 0.16002)
		(layer "In13.Cu")
		(net "M_H_CPU0_SA_DQS_DP<7>")
	)
	(segment
		(start 413.61233 -221.46006)
		(end 413.22117 -221.85122)
		(width 0.16002)
		(layer "In13.Cu")
		(net "M_H_CPU0_SA_DQS_DP<7>")
	)
	(segment
		(start 394.287756 -236.783626)
		(end 393.481052 -237.59033)
		(width 0.09525)
		(layer "In13.Cu")
		(net "M_H_CPU0_SA_DQS_DP<7>")
	)
	(segment
		(start 395.859254 -235.76407)
		(end 395.835632 -235.76407)
		(width 0.09525)
		(layer "In13.Cu")
		(net "M_H_CPU0_SA_DQS_DP<7>")
	)
	(segment
		(start 407.073862 -223.64573)
		(end 404.295102 -226.42449)
		(width 0.16002)
		(layer "In13.Cu")
		(net "M_H_CPU0_SA_DQS_DP<7>")
	)
	(segment
		(start 412.601918 -221.85122)
		(end 412.26486 -221.514162)
		(width 0.16002)
		(layer "In13.Cu")
		(net "M_H_CPU0_SA_DQS_DP<7>")
	)
	(segment
		(start 408.199844 -222.519748)
		(end 408.199844 -222.745808)
		(width 0.16002)
		(layer "In13.Cu")
		(net "M_H_CPU0_SA_DQS_DP<7>")
	)
	(segment
		(start 408.868372 -221.85122)
		(end 408.199844 -222.519748)
		(width 0.16002)
		(layer "In13.Cu")
		(net "M_H_CPU0_SA_DQS_DP<7>")
	)
	(segment
		(start 397.310102 -235.76407)
		(end 395.859254 -235.76407)
		(width 0.16002)
		(layer "In13.Cu")
		(net "M_H_CPU0_SA_DQS_DP<7>")
	)
	(segment
		(start 392.434318 -237.67415)
		(end 392.425936 -237.678976)
		(width 0.09525)
		(layer "In13.Cu")
		(net "M_H_CPU0_SA_DQS_DP<7>")
	)
	(segment
		(start 419.668452 -220.891354)
		(end 419.396926 -220.891354)
		(width 0.16002)
		(layer "In13.Cu")
		(net "M_H_CPU0_SA_DQS_DP<7>")
	)
	(segment
		(start 388.103364 -237.678976)
		(end 388.094982 -237.67415)
		(width 0.09525)
		(layer "In13.Cu")
		(net "M_H_CPU0_SA_DQS_DP<7>")
	)
	(segment
		(start 412.069026 -220.811852)
		(end 411.79242 -220.811852)
		(width 0.16002)
		(layer "In13.Cu")
		(net "M_H_CPU0_SA_DQS_DP<7>")
	)
	(segment
		(start 391.863326 -237.678976)
		(end 391.854944 -237.67415)
		(width 0.09525)
		(layer "In13.Cu")
		(net "M_H_CPU0_SA_DQS_DP<7>")
	)
	(segment
		(start 415.365438 -220.20022)
		(end 414.105598 -221.46006)
		(width 0.16002)
		(layer "In13.Cu")
		(net "M_H_CPU0_SA_DQS_DP<7>")
	)
	(segment
		(start 417.717986 -221.001336)
		(end 416.998658 -221.001336)
		(width 0.16002)
		(layer "In13.Cu")
		(net "M_H_CPU0_SA_DQS_DP<7>")
	)
	(segment
		(start 393.360656 -237.682024)
		(end 393.351258 -237.687612)
		(width 0.09525)
		(layer "In13.Cu")
		(net "M_H_CPU0_SA_DQS_DP<7>")
	)
	(segment
		(start 394.287756 -236.51591)
		(end 394.287756 -236.783626)
		(width 0.09525)
		(layer "In13.Cu")
		(net "M_H_CPU0_SA_DQS_DP<7>")
	)
	(segment
		(start 391.87374 -237.685072)
		(end 391.863326 -237.678976)
		(width 0.09525)
		(layer "In13.Cu")
		(net "M_H_CPU0_SA_DQS_DP<7>")
	)
	(segment
		(start 411.596586 -221.007686)
		(end 411.596586 -221.514162)
		(width 0.16002)
		(layer "In13.Cu")
		(net "M_H_CPU0_SA_DQS_DP<7>")
	)
	(arc
		(start 383.966212 -237.678976)
		(mid 383.68478 -237.754731)
		(end 383.403348 -237.678976)
		(width 0.09525)
		(layer "In13.Cu")
		(net "M_H_CPU0_SA_DQS_DP<7>")
	)
	(arc
		(start 391.854944 -237.67415)
		(mid 391.669912 -237.628236)
		(end 391.486136 -237.678976)
		(width 0.09525)
		(layer "In13.Cu")
		(net "M_H_CPU0_SA_DQS_DP<7>")
	)
	(arc
		(start 390.923272 -237.678976)
		(mid 390.734804 -237.628299)
		(end 390.546336 -237.678976)
		(width 0.09525)
		(layer "In13.Cu")
		(net "M_H_CPU0_SA_DQS_DP<7>")
	)
	(arc
		(start 387.726174 -237.678976)
		(mid 387.444742 -237.754731)
		(end 387.16331 -237.678976)
		(width 0.09525)
		(layer "In13.Cu")
		(net "M_H_CPU0_SA_DQS_DP<7>")
	)
	(arc
		(start 392.803126 -237.678976)
		(mid 392.619351 -237.628204)
		(end 392.434318 -237.67415)
		(width 0.09525)
		(layer "In13.Cu")
		(net "M_H_CPU0_SA_DQS_DP<7>")
	)
	(arc
		(start 390.546336 -237.678976)
		(mid 390.264904 -237.754731)
		(end 389.983472 -237.678976)
		(width 0.09525)
		(layer "In13.Cu")
		(net "M_H_CPU0_SA_DQS_DP<7>")
	)
	(arc
		(start 392.425936 -237.678976)
		(mid 392.150647 -237.754697)
		(end 391.87374 -237.685072)
		(width 0.09525)
		(layer "In13.Cu")
		(net "M_H_CPU0_SA_DQS_DP<7>")
	)
	(arc
		(start 388.094982 -237.67415)
		(mid 387.90995 -237.628236)
		(end 387.726174 -237.678976)
		(width 0.09525)
		(layer "In13.Cu")
		(net "M_H_CPU0_SA_DQS_DP<7>")
	)
	(arc
		(start 382.549908 -237.71987)
		(mid 382.539709 -237.716033)
		(end 382.529588 -237.711996)
		(width 0.09525)
		(layer "In13.Cu")
		(net "M_H_CPU0_SA_DQS_DP<7>")
	)
	(arc
		(start 393.481052 -237.59033)
		(mid 393.426404 -237.638395)
		(end 393.36599 -237.678976)
		(width 0.09525)
		(layer "In13.Cu")
		(net "M_H_CPU0_SA_DQS_DP<7>")
	)
	(arc
		(start 385.283456 -237.678976)
		(mid 385.099681 -237.628204)
		(end 384.914648 -237.67415)
		(width 0.09525)
		(layer "In13.Cu")
		(net "M_H_CPU0_SA_DQS_DP<7>")
	)
	(arc
		(start 388.666228 -237.678976)
		(mid 388.384796 -237.754731)
		(end 388.103364 -237.678976)
		(width 0.09525)
		(layer "In13.Cu")
		(net "M_H_CPU0_SA_DQS_DP<7>")
	)
	(arc
		(start 384.33502 -237.67415)
		(mid 384.149988 -237.628236)
		(end 383.966212 -237.678976)
		(width 0.09525)
		(layer "In13.Cu")
		(net "M_H_CPU0_SA_DQS_DP<7>")
	)
	(arc
		(start 386.786374 -237.678976)
		(mid 386.504942 -237.754731)
		(end 386.22351 -237.678976)
		(width 0.09525)
		(layer "In13.Cu")
		(net "M_H_CPU0_SA_DQS_DP<7>")
	)
	(arc
		(start 389.983472 -237.678976)
		(mid 389.799697 -237.628204)
		(end 389.614664 -237.67415)
		(width 0.09525)
		(layer "In13.Cu")
		(net "M_H_CPU0_SA_DQS_DP<7>")
	)
	(arc
		(start 393.351258 -237.687612)
		(mid 393.076053 -237.754876)
		(end 392.803126 -237.678976)
		(width 0.09525)
		(layer "In13.Cu")
		(net "M_H_CPU0_SA_DQS_DP<7>")
	)
	(arc
		(start 389.035036 -237.67415)
		(mid 388.850004 -237.628236)
		(end 388.666228 -237.678976)
		(width 0.09525)
		(layer "In13.Cu")
		(net "M_H_CPU0_SA_DQS_DP<7>")
	)
	(arc
		(start 383.394966 -237.67415)
		(mid 383.209934 -237.628236)
		(end 383.026158 -237.678976)
		(width 0.09525)
		(layer "In13.Cu")
		(net "M_H_CPU0_SA_DQS_DP<7>")
	)
	(arc
		(start 391.486136 -237.678976)
		(mid 391.204704 -237.754731)
		(end 390.923272 -237.678976)
		(width 0.09525)
		(layer "In13.Cu")
		(net "M_H_CPU0_SA_DQS_DP<7>")
	)
	(arc
		(start 386.22351 -237.678976)
		(mid 386.039735 -237.628204)
		(end 385.854702 -237.67415)
		(width 0.09525)
		(layer "In13.Cu")
		(net "M_H_CPU0_SA_DQS_DP<7>")
	)
	(arc
		(start 387.16331 -237.678976)
		(mid 386.974842 -237.628299)
		(end 386.786374 -237.678976)
		(width 0.09525)
		(layer "In13.Cu")
		(net "M_H_CPU0_SA_DQS_DP<7>")
	)
	(arc
		(start 389.606282 -237.678976)
		(mid 389.32485 -237.754731)
		(end 389.043418 -237.678976)
		(width 0.09525)
		(layer "In13.Cu")
		(net "M_H_CPU0_SA_DQS_DP<7>")
	)
	(arc
		(start 385.84632 -237.678976)
		(mid 385.564888 -237.754731)
		(end 385.283456 -237.678976)
		(width 0.09525)
		(layer "In13.Cu")
		(net "M_H_CPU0_SA_DQS_DP<7>")
	)
	(arc
		(start 384.906266 -237.678976)
		(mid 384.624834 -237.754731)
		(end 384.343402 -237.678976)
		(width 0.09525)
		(layer "In13.Cu")
		(net "M_H_CPU0_SA_DQS_DP<7>")
	)
	(arc
		(start 383.026158 -237.678976)
		(mid 382.792614 -237.752682)
		(end 382.549908 -237.71987)
		(width 0.09525)
		(layer "In13.Cu")
		(net "M_H_CPU0_SA_DQS_DP<7>")
	)
	(segment
		(start 381.807974 -233.409998)
		(end 382.274826 -233.14406)
		(width 0.12954)
		(layer "F.Cu")
		(net "M_H_CPU0_SA_DQS_DP<6>")
	)
	(segment
		(start 395.741652 -228.852984)
		(end 395.104874 -229.489762)
		(width 0.09525)
		(layer "In13.Cu")
		(net "M_H_CPU0_SA_DQS_DP<6>")
	)
	(segment
		(start 419.645846 -211.518754)
		(end 417.984686 -211.518754)
		(width 0.16002)
		(layer "In13.Cu")
		(net "M_H_CPU0_SA_DQS_DP<6>")
	)
	(segment
		(start 410.339286 -212.724492)
		(end 410.002228 -212.387434)
		(width 0.16002)
		(layer "In13.Cu")
		(net "M_H_CPU0_SA_DQS_DP<6>")
	)
	(segment
		(start 411.942788 -212.387434)
		(end 411.942788 -211.601304)
		(width 0.16002)
		(layer "In13.Cu")
		(net "M_H_CPU0_SA_DQS_DP<6>")
	)
	(segment
		(start 384.343402 -232.81894)
		(end 384.33502 -232.814114)
		(width 0.09525)
		(layer "In13.Cu")
		(net "M_H_CPU0_SA_DQS_DP<6>")
	)
	(segment
		(start 411.274768 -211.601304)
		(end 411.274768 -212.387434)
		(width 0.16002)
		(layer "In13.Cu")
		(net "M_H_CPU0_SA_DQS_DP<6>")
	)
	(segment
		(start 408.500834 -212.724492)
		(end 398.757902 -222.467424)
		(width 0.16002)
		(layer "In13.Cu")
		(net "M_H_CPU0_SA_DQS_DP<6>")
	)
	(segment
		(start 394.226542 -230.664766)
		(end 392.123676 -232.767632)
		(width 0.09525)
		(layer "In13.Cu")
		(net "M_H_CPU0_SA_DQS_DP<6>")
	)
	(segment
		(start 395.825472 -228.852984)
		(end 395.741652 -228.852984)
		(width 0.09525)
		(layer "In13.Cu")
		(net "M_H_CPU0_SA_DQS_DP<6>")
	)
	(segment
		(start 414.875218 -211.340446)
		(end 414.105598 -212.110066)
		(width 0.16002)
		(layer "In13.Cu")
		(net "M_H_CPU0_SA_DQS_DP<6>")
	)
	(segment
		(start 409.842208 -211.441284)
		(end 409.494228 -211.441284)
		(width 0.16002)
		(layer "In13.Cu")
		(net "M_H_CPU0_SA_DQS_DP<6>")
	)
	(segment
		(start 411.274768 -212.387434)
		(end 410.93771 -212.724492)
		(width 0.16002)
		(layer "In13.Cu")
		(net "M_H_CPU0_SA_DQS_DP<6>")
	)
	(segment
		(start 412.279846 -212.724492)
		(end 411.942788 -212.387434)
		(width 0.16002)
		(layer "In13.Cu")
		(net "M_H_CPU0_SA_DQS_DP<6>")
	)
	(segment
		(start 395.104874 -229.489762)
		(end 394.768832 -229.489762)
		(width 0.09525)
		(layer "In13.Cu")
		(net "M_H_CPU0_SA_DQS_DP<6>")
	)
	(segment
		(start 413.678878 -212.110066)
		(end 413.064452 -212.724492)
		(width 0.16002)
		(layer "In13.Cu")
		(net "M_H_CPU0_SA_DQS_DP<6>")
	)
	(segment
		(start 410.93771 -212.724492)
		(end 410.339286 -212.724492)
		(width 0.16002)
		(layer "In13.Cu")
		(net "M_H_CPU0_SA_DQS_DP<6>")
	)
	(segment
		(start 398.757902 -225.920554)
		(end 395.842236 -228.83622)
		(width 0.16002)
		(layer "In13.Cu")
		(net "M_H_CPU0_SA_DQS_DP<6>")
	)
	(segment
		(start 409.494228 -211.441284)
		(end 409.334208 -211.601304)
		(width 0.16002)
		(layer "In13.Cu")
		(net "M_H_CPU0_SA_DQS_DP<6>")
	)
	(segment
		(start 411.942788 -211.601304)
		(end 411.782768 -211.441284)
		(width 0.16002)
		(layer "In13.Cu")
		(net "M_H_CPU0_SA_DQS_DP<6>")
	)
	(segment
		(start 389.043418 -232.81894)
		(end 389.035036 -232.814114)
		(width 0.09525)
		(layer "In13.Cu")
		(net "M_H_CPU0_SA_DQS_DP<6>")
	)
	(segment
		(start 413.064452 -212.724492)
		(end 412.279846 -212.724492)
		(width 0.16002)
		(layer "In13.Cu")
		(net "M_H_CPU0_SA_DQS_DP<6>")
	)
	(segment
		(start 408.99715 -212.724492)
		(end 408.500834 -212.724492)
		(width 0.16002)
		(layer "In13.Cu")
		(net "M_H_CPU0_SA_DQS_DP<6>")
	)
	(segment
		(start 394.768832 -229.489762)
		(end 394.226542 -230.032052)
		(width 0.09525)
		(layer "In13.Cu")
		(net "M_H_CPU0_SA_DQS_DP<6>")
	)
	(segment
		(start 414.105598 -212.110066)
		(end 413.678878 -212.110066)
		(width 0.16002)
		(layer "In13.Cu")
		(net "M_H_CPU0_SA_DQS_DP<6>")
	)
	(segment
		(start 410.002228 -212.387434)
		(end 410.002228 -211.601304)
		(width 0.16002)
		(layer "In13.Cu")
		(net "M_H_CPU0_SA_DQS_DP<6>")
	)
	(segment
		(start 416.336988 -211.457286)
		(end 416.220148 -211.340446)
		(width 0.16002)
		(layer "In13.Cu")
		(net "M_H_CPU0_SA_DQS_DP<6>")
	)
	(segment
		(start 416.220148 -211.340446)
		(end 414.875218 -211.340446)
		(width 0.16002)
		(layer "In13.Cu")
		(net "M_H_CPU0_SA_DQS_DP<6>")
	)
	(segment
		(start 395.842236 -228.83622)
		(end 395.825472 -228.852984)
		(width 0.09525)
		(layer "In13.Cu")
		(net "M_H_CPU0_SA_DQS_DP<6>")
	)
	(segment
		(start 383.403348 -232.81894)
		(end 383.394966 -232.814114)
		(width 0.09525)
		(layer "In13.Cu")
		(net "M_H_CPU0_SA_DQS_DP<6>")
	)
	(segment
		(start 416.933888 -211.340446)
		(end 416.817048 -211.457286)
		(width 0.16002)
		(layer "In13.Cu")
		(net "M_H_CPU0_SA_DQS_DP<6>")
	)
	(segment
		(start 409.334208 -211.601304)
		(end 409.334208 -212.387434)
		(width 0.16002)
		(layer "In13.Cu")
		(net "M_H_CPU0_SA_DQS_DP<6>")
	)
	(segment
		(start 382.42875 -232.87863)
		(end 382.274826 -233.14406)
		(width 0.09525)
		(layer "In13.Cu")
		(net "M_H_CPU0_SA_DQS_DP<6>")
	)
	(segment
		(start 409.334208 -212.387434)
		(end 408.99715 -212.724492)
		(width 0.16002)
		(layer "In13.Cu")
		(net "M_H_CPU0_SA_DQS_DP<6>")
	)
	(segment
		(start 392.123676 -232.767632)
		(end 391.674858 -232.767632)
		(width 0.09525)
		(layer "In13.Cu")
		(net "M_H_CPU0_SA_DQS_DP<6>")
	)
	(segment
		(start 398.757902 -222.467424)
		(end 398.757902 -225.920554)
		(width 0.16002)
		(layer "In13.Cu")
		(net "M_H_CPU0_SA_DQS_DP<6>")
	)
	(segment
		(start 389.614664 -232.814114)
		(end 389.606282 -232.81894)
		(width 0.09525)
		(layer "In13.Cu")
		(net "M_H_CPU0_SA_DQS_DP<6>")
	)
	(segment
		(start 419.912038 -211.784946)
		(end 419.645846 -211.518754)
		(width 0.16002)
		(layer "In13.Cu")
		(net "M_H_CPU0_SA_DQS_DP<6>")
	)
	(segment
		(start 384.914648 -232.814114)
		(end 384.906266 -232.81894)
		(width 0.09525)
		(layer "In13.Cu")
		(net "M_H_CPU0_SA_DQS_DP<6>")
	)
	(segment
		(start 411.782768 -211.441284)
		(end 411.434788 -211.441284)
		(width 0.16002)
		(layer "In13.Cu")
		(net "M_H_CPU0_SA_DQS_DP<6>")
	)
	(segment
		(start 417.984686 -211.518754)
		(end 417.806378 -211.340446)
		(width 0.16002)
		(layer "In13.Cu")
		(net "M_H_CPU0_SA_DQS_DP<6>")
	)
	(segment
		(start 382.529588 -232.85196)
		(end 382.42875 -232.87863)
		(width 0.09525)
		(layer "In13.Cu")
		(net "M_H_CPU0_SA_DQS_DP<6>")
	)
	(segment
		(start 388.103364 -232.81894)
		(end 388.094982 -232.814114)
		(width 0.09525)
		(layer "In13.Cu")
		(net "M_H_CPU0_SA_DQS_DP<6>")
	)
	(segment
		(start 385.854702 -232.814114)
		(end 385.84632 -232.81894)
		(width 0.09525)
		(layer "In13.Cu")
		(net "M_H_CPU0_SA_DQS_DP<6>")
	)
	(segment
		(start 411.434788 -211.441284)
		(end 411.274768 -211.601304)
		(width 0.16002)
		(layer "In13.Cu")
		(net "M_H_CPU0_SA_DQS_DP<6>")
	)
	(segment
		(start 416.817048 -211.457286)
		(end 416.336988 -211.457286)
		(width 0.16002)
		(layer "In13.Cu")
		(net "M_H_CPU0_SA_DQS_DP<6>")
	)
	(segment
		(start 410.002228 -211.601304)
		(end 409.842208 -211.441284)
		(width 0.16002)
		(layer "In13.Cu")
		(net "M_H_CPU0_SA_DQS_DP<6>")
	)
	(segment
		(start 394.226542 -230.032052)
		(end 394.226542 -230.664766)
		(width 0.09525)
		(layer "In13.Cu")
		(net "M_H_CPU0_SA_DQS_DP<6>")
	)
	(segment
		(start 417.806378 -211.340446)
		(end 416.933888 -211.340446)
		(width 0.16002)
		(layer "In13.Cu")
		(net "M_H_CPU0_SA_DQS_DP<6>")
	)
	(arc
		(start 389.983472 -232.81894)
		(mid 389.799697 -232.768168)
		(end 389.614664 -232.814114)
		(width 0.09525)
		(layer "In13.Cu")
		(net "M_H_CPU0_SA_DQS_DP<6>")
	)
	(arc
		(start 386.22351 -232.81894)
		(mid 386.039735 -232.768168)
		(end 385.854702 -232.814114)
		(width 0.09525)
		(layer "In13.Cu")
		(net "M_H_CPU0_SA_DQS_DP<6>")
	)
	(arc
		(start 383.966212 -232.81894)
		(mid 383.68478 -232.894695)
		(end 383.403348 -232.81894)
		(width 0.09525)
		(layer "In13.Cu")
		(net "M_H_CPU0_SA_DQS_DP<6>")
	)
	(arc
		(start 383.394966 -232.814114)
		(mid 383.209934 -232.7682)
		(end 383.026158 -232.81894)
		(width 0.09525)
		(layer "In13.Cu")
		(net "M_H_CPU0_SA_DQS_DP<6>")
	)
	(arc
		(start 385.283456 -232.81894)
		(mid 385.099681 -232.768168)
		(end 384.914648 -232.814114)
		(width 0.09525)
		(layer "In13.Cu")
		(net "M_H_CPU0_SA_DQS_DP<6>")
	)
	(arc
		(start 388.666228 -232.81894)
		(mid 388.384796 -232.894695)
		(end 388.103364 -232.81894)
		(width 0.09525)
		(layer "In13.Cu")
		(net "M_H_CPU0_SA_DQS_DP<6>")
	)
	(arc
		(start 389.606282 -232.81894)
		(mid 389.32485 -232.894695)
		(end 389.043418 -232.81894)
		(width 0.09525)
		(layer "In13.Cu")
		(net "M_H_CPU0_SA_DQS_DP<6>")
	)
	(arc
		(start 388.094982 -232.814114)
		(mid 387.90995 -232.7682)
		(end 387.726174 -232.81894)
		(width 0.09525)
		(layer "In13.Cu")
		(net "M_H_CPU0_SA_DQS_DP<6>")
	)
	(arc
		(start 386.786374 -232.81894)
		(mid 386.504942 -232.894695)
		(end 386.22351 -232.81894)
		(width 0.09525)
		(layer "In13.Cu")
		(net "M_H_CPU0_SA_DQS_DP<6>")
	)
	(arc
		(start 391.674858 -232.767632)
		(mid 391.577112 -232.780827)
		(end 391.486136 -232.81894)
		(width 0.09525)
		(layer "In13.Cu")
		(net "M_H_CPU0_SA_DQS_DP<6>")
	)
	(arc
		(start 390.546336 -232.81894)
		(mid 390.264904 -232.894695)
		(end 389.983472 -232.81894)
		(width 0.09525)
		(layer "In13.Cu")
		(net "M_H_CPU0_SA_DQS_DP<6>")
	)
	(arc
		(start 383.026158 -232.81894)
		(mid 382.792614 -232.892646)
		(end 382.549908 -232.859834)
		(width 0.09525)
		(layer "In13.Cu")
		(net "M_H_CPU0_SA_DQS_DP<6>")
	)
	(arc
		(start 385.84632 -232.81894)
		(mid 385.564888 -232.894695)
		(end 385.283456 -232.81894)
		(width 0.09525)
		(layer "In13.Cu")
		(net "M_H_CPU0_SA_DQS_DP<6>")
	)
	(arc
		(start 387.726174 -232.81894)
		(mid 387.444742 -232.894695)
		(end 387.16331 -232.81894)
		(width 0.09525)
		(layer "In13.Cu")
		(net "M_H_CPU0_SA_DQS_DP<6>")
	)
	(arc
		(start 382.549908 -232.859834)
		(mid 382.539709 -232.855997)
		(end 382.529588 -232.85196)
		(width 0.09525)
		(layer "In13.Cu")
		(net "M_H_CPU0_SA_DQS_DP<6>")
	)
	(arc
		(start 384.906266 -232.81894)
		(mid 384.624834 -232.894695)
		(end 384.343402 -232.81894)
		(width 0.09525)
		(layer "In13.Cu")
		(net "M_H_CPU0_SA_DQS_DP<6>")
	)
	(arc
		(start 389.035036 -232.814114)
		(mid 388.850004 -232.7682)
		(end 388.666228 -232.81894)
		(width 0.09525)
		(layer "In13.Cu")
		(net "M_H_CPU0_SA_DQS_DP<6>")
	)
	(arc
		(start 387.16331 -232.81894)
		(mid 386.974842 -232.768263)
		(end 386.786374 -232.81894)
		(width 0.09525)
		(layer "In13.Cu")
		(net "M_H_CPU0_SA_DQS_DP<6>")
	)
	(arc
		(start 390.923272 -232.81894)
		(mid 390.734804 -232.768263)
		(end 390.546336 -232.81894)
		(width 0.09525)
		(layer "In13.Cu")
		(net "M_H_CPU0_SA_DQS_DP<6>")
	)
	(arc
		(start 391.486136 -232.81894)
		(mid 391.204704 -232.894695)
		(end 390.923272 -232.81894)
		(width 0.09525)
		(layer "In13.Cu")
		(net "M_H_CPU0_SA_DQS_DP<6>")
	)
	(arc
		(start 384.33502 -232.814114)
		(mid 384.149988 -232.7682)
		(end 383.966212 -232.81894)
		(width 0.09525)
		(layer "In13.Cu")
		(net "M_H_CPU0_SA_DQS_DP<6>")
	)
	(segment
		(start 381.807974 -228.550216)
		(end 382.274826 -228.284278)
		(width 0.12954)
		(layer "F.Cu")
		(net "M_H_CPU0_SA_DQS_DP<5>")
	)
	(segment
		(start 404.037038 -207.732122)
		(end 403.61362 -208.15554)
		(width 0.16002)
		(layer "In13.Cu")
		(net "M_H_CPU0_SA_DQS_DP<5>")
	)
	(segment
		(start 405.409908 -206.359252)
		(end 404.98649 -206.78267)
		(width 0.16002)
		(layer "In13.Cu")
		(net "M_H_CPU0_SA_DQS_DP<5>")
	)
	(segment
		(start 390.076182 -227.149152)
		(end 390.044686 -227.16744)
		(width 0.09525)
		(layer "In13.Cu")
		(net "M_H_CPU0_SA_DQS_DP<5>")
	)
	(segment
		(start 402.553678 -208.517998)
		(end 402.664168 -208.628488)
		(width 0.16002)
		(layer "In13.Cu")
		(net "M_H_CPU0_SA_DQS_DP<5>")
	)
	(segment
		(start 403.026626 -208.04505)
		(end 402.800566 -208.04505)
		(width 0.16002)
		(layer "In13.Cu")
		(net "M_H_CPU0_SA_DQS_DP<5>")
	)
	(segment
		(start 404.98649 -206.78267)
		(end 404.509986 -206.78267)
		(width 0.16002)
		(layer "In13.Cu")
		(net "M_H_CPU0_SA_DQS_DP<5>")
	)
	(segment
		(start 391.95629 -223.909128)
		(end 391.923778 -223.927924)
		(width 0.09525)
		(layer "In13.Cu")
		(net "M_H_CPU0_SA_DQS_DP<5>")
	)
	(segment
		(start 414.105598 -202.760072)
		(end 409.009088 -202.760072)
		(width 0.16002)
		(layer "In13.Cu")
		(net "M_H_CPU0_SA_DQS_DP<5>")
	)
	(segment
		(start 407.73223 -204.03693)
		(end 407.255726 -204.03693)
		(width 0.16002)
		(layer "In13.Cu")
		(net "M_H_CPU0_SA_DQS_DP<5>")
	)
	(segment
		(start 416.729418 -202.107292)
		(end 416.612578 -201.990452)
		(width 0.16002)
		(layer "In13.Cu")
		(net "M_H_CPU0_SA_DQS_DP<5>")
	)
	(segment
		(start 403.926548 -207.145128)
		(end 404.037038 -207.255618)
		(width 0.16002)
		(layer "In13.Cu")
		(net "M_H_CPU0_SA_DQS_DP<5>")
	)
	(segment
		(start 385.854702 -227.954332)
		(end 385.84632 -227.959158)
		(width 0.09525)
		(layer "In13.Cu")
		(net "M_H_CPU0_SA_DQS_DP<5>")
	)
	(segment
		(start 402.24075 -209.52841)
		(end 401.764246 -209.52841)
		(width 0.16002)
		(layer "In13.Cu")
		(net "M_H_CPU0_SA_DQS_DP<5>")
	)
	(segment
		(start 405.299418 -205.546198)
		(end 405.299418 -205.772258)
		(width 0.16002)
		(layer "In13.Cu")
		(net "M_H_CPU0_SA_DQS_DP<5>")
	)
	(segment
		(start 407.145236 -203.92644)
		(end 406.919176 -203.92644)
		(width 0.16002)
		(layer "In13.Cu")
		(net "M_H_CPU0_SA_DQS_DP<5>")
	)
	(segment
		(start 401.291298 -210.477862)
		(end 400.86788 -210.90128)
		(width 0.16002)
		(layer "In13.Cu")
		(net "M_H_CPU0_SA_DQS_DP<5>")
	)
	(segment
		(start 415.535618 -202.107292)
		(end 415.418778 -201.990452)
		(width 0.16002)
		(layer "In13.Cu")
		(net "M_H_CPU0_SA_DQS_DP<5>")
	)
	(segment
		(start 382.529588 -227.992178)
		(end 382.42875 -228.018848)
		(width 0.09525)
		(layer "In13.Cu")
		(net "M_H_CPU0_SA_DQS_DP<5>")
	)
	(segment
		(start 392.895836 -222.289116)
		(end 392.86434 -222.307404)
		(width 0.09525)
		(layer "In13.Cu")
		(net "M_H_CPU0_SA_DQS_DP<5>")
	)
	(segment
		(start 393.207748 -221.667578)
		(end 393.207748 -221.977204)
		(width 0.09525)
		(layer "In13.Cu")
		(net "M_H_CPU0_SA_DQS_DP<5>")
	)
	(segment
		(start 401.764246 -209.52841)
		(end 401.653756 -209.41792)
		(width 0.16002)
		(layer "In13.Cu")
		(net "M_H_CPU0_SA_DQS_DP<5>")
	)
	(segment
		(start 401.653756 -209.41792)
		(end 401.427696 -209.41792)
		(width 0.16002)
		(layer "In13.Cu")
		(net "M_H_CPU0_SA_DQS_DP<5>")
	)
	(segment
		(start 406.35936 -205.4098)
		(end 405.882856 -205.4098)
		(width 0.16002)
		(layer "In13.Cu")
		(net "M_H_CPU0_SA_DQS_DP<5>")
	)
	(segment
		(start 384.914648 -227.954332)
		(end 384.906266 -227.959158)
		(width 0.09525)
		(layer "In13.Cu")
		(net "M_H_CPU0_SA_DQS_DP<5>")
	)
	(segment
		(start 399.918428 -211.850732)
		(end 393.218416 -218.550744)
		(width 0.16002)
		(layer "In13.Cu")
		(net "M_H_CPU0_SA_DQS_DP<5>")
	)
	(segment
		(start 388.103364 -227.959158)
		(end 388.094982 -227.954332)
		(width 0.09525)
		(layer "In13.Cu")
		(net "M_H_CPU0_SA_DQS_DP<5>")
	)
	(segment
		(start 399.918428 -211.374228)
		(end 399.918428 -211.850732)
		(width 0.16002)
		(layer "In13.Cu")
		(net "M_H_CPU0_SA_DQS_DP<5>")
	)
	(segment
		(start 403.926548 -206.919068)
		(end 403.926548 -207.145128)
		(width 0.16002)
		(layer "In13.Cu")
		(net "M_H_CPU0_SA_DQS_DP<5>")
	)
	(segment
		(start 417.209478 -202.107292)
		(end 416.729418 -202.107292)
		(width 0.16002)
		(layer "In13.Cu")
		(net "M_H_CPU0_SA_DQS_DP<5>")
	)
	(segment
		(start 389.644382 -227.93706)
		(end 389.606282 -227.959158)
		(width 0.09525)
		(layer "In13.Cu")
		(net "M_H_CPU0_SA_DQS_DP<5>")
	)
	(segment
		(start 404.509986 -206.78267)
		(end 404.399496 -206.67218)
		(width 0.16002)
		(layer "In13.Cu")
		(net "M_H_CPU0_SA_DQS_DP<5>")
	)
	(segment
		(start 399.807938 -211.037678)
		(end 399.807938 -211.263738)
		(width 0.16002)
		(layer "In13.Cu")
		(net "M_H_CPU0_SA_DQS_DP<5>")
	)
	(segment
		(start 393.220702 -221.382844)
		(end 393.161774 -221.441772)
		(width 0.09525)
		(layer "In13.Cu")
		(net "M_H_CPU0_SA_DQS_DP<5>")
	)
	(segment
		(start 390.114282 -227.127054)
		(end 390.076182 -227.149152)
		(width 0.09525)
		(layer "In13.Cu")
		(net "M_H_CPU0_SA_DQS_DP<5>")
	)
	(segment
		(start 391.054336 -225.507042)
		(end 391.016236 -225.52914)
		(width 0.09525)
		(layer "In13.Cu")
		(net "M_H_CPU0_SA_DQS_DP<5>")
	)
	(segment
		(start 393.207748 -221.977204)
		(end 392.895836 -222.289116)
		(width 0.09525)
		(layer "In13.Cu")
		(net "M_H_CPU0_SA_DQS_DP<5>")
	)
	(segment
		(start 390.581388 -226.318572)
		(end 390.546336 -226.339146)
		(width 0.09525)
		(layer "In13.Cu")
		(net "M_H_CPU0_SA_DQS_DP<5>")
	)
	(segment
		(start 400.280886 -210.79079)
		(end 400.054826 -210.79079)
		(width 0.16002)
		(layer "In13.Cu")
		(net "M_H_CPU0_SA_DQS_DP<5>")
	)
	(segment
		(start 419.64864 -202.171554)
		(end 417.98748 -202.171554)
		(width 0.16002)
		(layer "In13.Cu")
		(net "M_H_CPU0_SA_DQS_DP<5>")
	)
	(segment
		(start 391.486136 -224.719134)
		(end 391.45464 -224.737422)
		(width 0.09525)
		(layer "In13.Cu")
		(net "M_H_CPU0_SA_DQS_DP<5>")
	)
	(segment
		(start 401.180808 -209.890868)
		(end 401.291298 -210.001358)
		(width 0.16002)
		(layer "In13.Cu")
		(net "M_H_CPU0_SA_DQS_DP<5>")
	)
	(segment
		(start 406.672288 -204.399388)
		(end 406.782778 -204.509878)
		(width 0.16002)
		(layer "In13.Cu")
		(net "M_H_CPU0_SA_DQS_DP<5>")
	)
	(segment
		(start 404.399496 -206.67218)
		(end 404.173436 -206.67218)
		(width 0.16002)
		(layer "In13.Cu")
		(net "M_H_CPU0_SA_DQS_DP<5>")
	)
	(segment
		(start 400.86788 -210.90128)
		(end 400.391376 -210.90128)
		(width 0.16002)
		(layer "In13.Cu")
		(net "M_H_CPU0_SA_DQS_DP<5>")
	)
	(segment
		(start 393.161774 -221.441772)
		(end 393.161774 -221.621604)
		(width 0.09525)
		(layer "In13.Cu")
		(net "M_H_CPU0_SA_DQS_DP<5>")
	)
	(segment
		(start 406.919176 -203.92644)
		(end 406.672288 -204.173328)
		(width 0.16002)
		(layer "In13.Cu")
		(net "M_H_CPU0_SA_DQS_DP<5>")
	)
	(segment
		(start 406.782778 -204.509878)
		(end 406.782778 -204.986382)
		(width 0.16002)
		(layer "In13.Cu")
		(net "M_H_CPU0_SA_DQS_DP<5>")
	)
	(segment
		(start 405.299418 -205.772258)
		(end 405.409908 -205.882748)
		(width 0.16002)
		(layer "In13.Cu")
		(net "M_H_CPU0_SA_DQS_DP<5>")
	)
	(segment
		(start 404.037038 -207.255618)
		(end 404.037038 -207.732122)
		(width 0.16002)
		(layer "In13.Cu")
		(net "M_H_CPU0_SA_DQS_DP<5>")
	)
	(segment
		(start 416.132518 -201.990452)
		(end 416.015678 -202.107292)
		(width 0.16002)
		(layer "In13.Cu")
		(net "M_H_CPU0_SA_DQS_DP<5>")
	)
	(segment
		(start 409.009088 -202.760072)
		(end 407.73223 -204.03693)
		(width 0.16002)
		(layer "In13.Cu")
		(net "M_H_CPU0_SA_DQS_DP<5>")
	)
	(segment
		(start 382.42875 -228.018848)
		(end 382.274826 -228.284278)
		(width 0.09525)
		(layer "In13.Cu")
		(net "M_H_CPU0_SA_DQS_DP<5>")
	)
	(segment
		(start 416.612578 -201.990452)
		(end 416.132518 -201.990452)
		(width 0.16002)
		(layer "In13.Cu")
		(net "M_H_CPU0_SA_DQS_DP<5>")
	)
	(segment
		(start 416.015678 -202.107292)
		(end 415.535618 -202.107292)
		(width 0.16002)
		(layer "In13.Cu")
		(net "M_H_CPU0_SA_DQS_DP<5>")
	)
	(segment
		(start 393.218416 -221.356936)
		(end 393.220702 -221.359222)
		(width 0.09525)
		(layer "In13.Cu")
		(net "M_H_CPU0_SA_DQS_DP<5>")
	)
	(segment
		(start 390.546336 -226.339146)
		(end 390.513824 -226.357942)
		(width 0.09525)
		(layer "In13.Cu")
		(net "M_H_CPU0_SA_DQS_DP<5>")
	)
	(segment
		(start 391.016236 -225.52914)
		(end 390.983724 -225.547936)
		(width 0.09525)
		(layer "In13.Cu")
		(net "M_H_CPU0_SA_DQS_DP<5>")
	)
	(segment
		(start 401.180808 -209.664808)
		(end 401.180808 -209.890868)
		(width 0.16002)
		(layer "In13.Cu")
		(net "M_H_CPU0_SA_DQS_DP<5>")
	)
	(segment
		(start 402.664168 -208.628488)
		(end 402.664168 -209.104992)
		(width 0.16002)
		(layer "In13.Cu")
		(net "M_H_CPU0_SA_DQS_DP<5>")
	)
	(segment
		(start 419.912038 -202.434952)
		(end 419.64864 -202.171554)
		(width 0.16002)
		(layer "In13.Cu")
		(net "M_H_CPU0_SA_DQS_DP<5>")
	)
	(segment
		(start 402.664168 -209.104992)
		(end 402.24075 -209.52841)
		(width 0.16002)
		(layer "In13.Cu")
		(net "M_H_CPU0_SA_DQS_DP<5>")
	)
	(segment
		(start 393.161774 -221.621604)
		(end 393.207748 -221.667578)
		(width 0.09525)
		(layer "In13.Cu")
		(net "M_H_CPU0_SA_DQS_DP<5>")
	)
	(segment
		(start 384.343402 -227.959158)
		(end 384.33502 -227.954332)
		(width 0.09525)
		(layer "In13.Cu")
		(net "M_H_CPU0_SA_DQS_DP<5>")
	)
	(segment
		(start 415.418778 -201.990452)
		(end 414.875218 -201.990452)
		(width 0.16002)
		(layer "In13.Cu")
		(net "M_H_CPU0_SA_DQS_DP<5>")
	)
	(segment
		(start 414.875218 -201.990452)
		(end 414.105598 -202.760072)
		(width 0.16002)
		(layer "In13.Cu")
		(net "M_H_CPU0_SA_DQS_DP<5>")
	)
	(segment
		(start 389.043418 -227.959158)
		(end 389.035036 -227.954332)
		(width 0.09525)
		(layer "In13.Cu")
		(net "M_H_CPU0_SA_DQS_DP<5>")
	)
	(segment
		(start 405.546306 -205.29931)
		(end 405.299418 -205.546198)
		(width 0.16002)
		(layer "In13.Cu")
		(net "M_H_CPU0_SA_DQS_DP<5>")
	)
	(segment
		(start 417.98748 -202.171554)
		(end 417.806378 -201.990452)
		(width 0.16002)
		(layer "In13.Cu")
		(net "M_H_CPU0_SA_DQS_DP<5>")
	)
	(segment
		(start 403.61362 -208.15554)
		(end 403.137116 -208.15554)
		(width 0.16002)
		(layer "In13.Cu")
		(net "M_H_CPU0_SA_DQS_DP<5>")
	)
	(segment
		(start 405.882856 -205.4098)
		(end 405.772366 -205.29931)
		(width 0.16002)
		(layer "In13.Cu")
		(net "M_H_CPU0_SA_DQS_DP<5>")
	)
	(segment
		(start 403.137116 -208.15554)
		(end 403.026626 -208.04505)
		(width 0.16002)
		(layer "In13.Cu")
		(net "M_H_CPU0_SA_DQS_DP<5>")
	)
	(segment
		(start 417.806378 -201.990452)
		(end 417.326318 -201.990452)
		(width 0.16002)
		(layer "In13.Cu")
		(net "M_H_CPU0_SA_DQS_DP<5>")
	)
	(segment
		(start 402.800566 -208.04505)
		(end 402.553678 -208.291938)
		(width 0.16002)
		(layer "In13.Cu")
		(net "M_H_CPU0_SA_DQS_DP<5>")
	)
	(segment
		(start 393.220702 -221.359222)
		(end 393.220702 -221.382844)
		(width 0.09525)
		(layer "In13.Cu")
		(net "M_H_CPU0_SA_DQS_DP<5>")
	)
	(segment
		(start 392.458194 -223.08058)
		(end 392.42619 -223.099122)
		(width 0.09525)
		(layer "In13.Cu")
		(net "M_H_CPU0_SA_DQS_DP<5>")
	)
	(segment
		(start 404.173436 -206.67218)
		(end 403.926548 -206.919068)
		(width 0.16002)
		(layer "In13.Cu")
		(net "M_H_CPU0_SA_DQS_DP<5>")
	)
	(segment
		(start 417.326318 -201.990452)
		(end 417.209478 -202.107292)
		(width 0.16002)
		(layer "In13.Cu")
		(net "M_H_CPU0_SA_DQS_DP<5>")
	)
	(segment
		(start 401.291298 -210.001358)
		(end 401.291298 -210.477862)
		(width 0.16002)
		(layer "In13.Cu")
		(net "M_H_CPU0_SA_DQS_DP<5>")
	)
	(segment
		(start 400.054826 -210.79079)
		(end 399.807938 -211.037678)
		(width 0.16002)
		(layer "In13.Cu")
		(net "M_H_CPU0_SA_DQS_DP<5>")
	)
	(segment
		(start 405.772366 -205.29931)
		(end 405.546306 -205.29931)
		(width 0.16002)
		(layer "In13.Cu")
		(net "M_H_CPU0_SA_DQS_DP<5>")
	)
	(segment
		(start 391.524236 -224.697036)
		(end 391.486136 -224.719134)
		(width 0.09525)
		(layer "In13.Cu")
		(net "M_H_CPU0_SA_DQS_DP<5>")
	)
	(segment
		(start 383.403348 -227.959158)
		(end 383.394966 -227.954332)
		(width 0.09525)
		(layer "In13.Cu")
		(net "M_H_CPU0_SA_DQS_DP<5>")
	)
	(segment
		(start 401.427696 -209.41792)
		(end 401.180808 -209.664808)
		(width 0.16002)
		(layer "In13.Cu")
		(net "M_H_CPU0_SA_DQS_DP<5>")
	)
	(segment
		(start 393.218416 -218.550744)
		(end 393.218416 -221.356936)
		(width 0.16002)
		(layer "In13.Cu")
		(net "M_H_CPU0_SA_DQS_DP<5>")
	)
	(segment
		(start 406.672288 -204.173328)
		(end 406.672288 -204.399388)
		(width 0.16002)
		(layer "In13.Cu")
		(net "M_H_CPU0_SA_DQS_DP<5>")
	)
	(segment
		(start 392.42619 -223.099122)
		(end 392.394694 -223.11741)
		(width 0.09525)
		(layer "In13.Cu")
		(net "M_H_CPU0_SA_DQS_DP<5>")
	)
	(segment
		(start 391.99439 -223.88703)
		(end 391.95629 -223.909128)
		(width 0.09525)
		(layer "In13.Cu")
		(net "M_H_CPU0_SA_DQS_DP<5>")
	)
	(segment
		(start 400.391376 -210.90128)
		(end 400.280886 -210.79079)
		(width 0.16002)
		(layer "In13.Cu")
		(net "M_H_CPU0_SA_DQS_DP<5>")
	)
	(segment
		(start 399.807938 -211.263738)
		(end 399.918428 -211.374228)
		(width 0.16002)
		(layer "In13.Cu")
		(net "M_H_CPU0_SA_DQS_DP<5>")
	)
	(segment
		(start 407.255726 -204.03693)
		(end 407.145236 -203.92644)
		(width 0.16002)
		(layer "In13.Cu")
		(net "M_H_CPU0_SA_DQS_DP<5>")
	)
	(segment
		(start 405.409908 -205.882748)
		(end 405.409908 -206.359252)
		(width 0.16002)
		(layer "In13.Cu")
		(net "M_H_CPU0_SA_DQS_DP<5>")
	)
	(segment
		(start 402.553678 -208.291938)
		(end 402.553678 -208.517998)
		(width 0.16002)
		(layer "In13.Cu")
		(net "M_H_CPU0_SA_DQS_DP<5>")
	)
	(segment
		(start 406.782778 -204.986382)
		(end 406.35936 -205.4098)
		(width 0.16002)
		(layer "In13.Cu")
		(net "M_H_CPU0_SA_DQS_DP<5>")
	)
	(arc
		(start 391.29716 -225.044254)
		(mid 391.232763 -225.30556)
		(end 391.054336 -225.507042)
		(width 0.09525)
		(layer "In13.Cu")
		(net "M_H_CPU0_SA_DQS_DP<5>")
	)
	(arc
		(start 383.966212 -227.959158)
		(mid 383.68478 -228.034913)
		(end 383.403348 -227.959158)
		(width 0.09525)
		(layer "In13.Cu")
		(net "M_H_CPU0_SA_DQS_DP<5>")
	)
	(arc
		(start 387.726174 -227.959158)
		(mid 387.444742 -228.034913)
		(end 387.16331 -227.959158)
		(width 0.09525)
		(layer "In13.Cu")
		(net "M_H_CPU0_SA_DQS_DP<5>")
	)
	(arc
		(start 382.549908 -228.000052)
		(mid 382.539709 -227.996215)
		(end 382.529588 -227.992178)
		(width 0.09525)
		(layer "In13.Cu")
		(net "M_H_CPU0_SA_DQS_DP<5>")
	)
	(arc
		(start 389.887206 -227.474272)
		(mid 389.822809 -227.735578)
		(end 389.644382 -227.93706)
		(width 0.09525)
		(layer "In13.Cu")
		(net "M_H_CPU0_SA_DQS_DP<5>")
	)
	(arc
		(start 389.606282 -227.959158)
		(mid 389.32485 -228.034913)
		(end 389.043418 -227.959158)
		(width 0.09525)
		(layer "In13.Cu")
		(net "M_H_CPU0_SA_DQS_DP<5>")
	)
	(arc
		(start 383.394966 -227.954332)
		(mid 383.209934 -227.908418)
		(end 383.026158 -227.959158)
		(width 0.09525)
		(layer "In13.Cu")
		(net "M_H_CPU0_SA_DQS_DP<5>")
	)
	(arc
		(start 384.906266 -227.959158)
		(mid 384.624834 -228.034913)
		(end 384.343402 -227.959158)
		(width 0.09525)
		(layer "In13.Cu")
		(net "M_H_CPU0_SA_DQS_DP<5>")
	)
	(arc
		(start 386.22351 -227.959158)
		(mid 386.039735 -227.908386)
		(end 385.854702 -227.954332)
		(width 0.09525)
		(layer "In13.Cu")
		(net "M_H_CPU0_SA_DQS_DP<5>")
	)
	(arc
		(start 385.283456 -227.959158)
		(mid 385.099681 -227.908386)
		(end 384.914648 -227.954332)
		(width 0.09525)
		(layer "In13.Cu")
		(net "M_H_CPU0_SA_DQS_DP<5>")
	)
	(arc
		(start 385.84632 -227.959158)
		(mid 385.564888 -228.034913)
		(end 385.283456 -227.959158)
		(width 0.09525)
		(layer "In13.Cu")
		(net "M_H_CPU0_SA_DQS_DP<5>")
	)
	(arc
		(start 386.786374 -227.959158)
		(mid 386.504942 -228.034913)
		(end 386.22351 -227.959158)
		(width 0.09525)
		(layer "In13.Cu")
		(net "M_H_CPU0_SA_DQS_DP<5>")
	)
	(arc
		(start 390.827006 -225.85426)
		(mid 390.761759 -226.116863)
		(end 390.581388 -226.318572)
		(width 0.09525)
		(layer "In13.Cu")
		(net "M_H_CPU0_SA_DQS_DP<5>")
	)
	(arc
		(start 390.983724 -225.547936)
		(mid 390.86845 -225.682214)
		(end 390.827006 -225.85426)
		(width 0.09525)
		(layer "In13.Cu")
		(net "M_H_CPU0_SA_DQS_DP<5>")
	)
	(arc
		(start 387.16331 -227.959158)
		(mid 386.974842 -227.908481)
		(end 386.786374 -227.959158)
		(width 0.09525)
		(layer "In13.Cu")
		(net "M_H_CPU0_SA_DQS_DP<5>")
	)
	(arc
		(start 391.45464 -224.737422)
		(mid 391.338842 -224.871816)
		(end 391.29716 -225.044254)
		(width 0.09525)
		(layer "In13.Cu")
		(net "M_H_CPU0_SA_DQS_DP<5>")
	)
	(arc
		(start 392.394694 -223.11741)
		(mid 392.278896 -223.251804)
		(end 392.237214 -223.424242)
		(width 0.09525)
		(layer "In13.Cu")
		(net "M_H_CPU0_SA_DQS_DP<5>")
	)
	(arc
		(start 392.237214 -223.424242)
		(mid 392.172817 -223.685548)
		(end 391.99439 -223.88703)
		(width 0.09525)
		(layer "In13.Cu")
		(net "M_H_CPU0_SA_DQS_DP<5>")
	)
	(arc
		(start 391.923778 -223.927924)
		(mid 391.808504 -224.062202)
		(end 391.76706 -224.234248)
		(width 0.09525)
		(layer "In13.Cu")
		(net "M_H_CPU0_SA_DQS_DP<5>")
	)
	(arc
		(start 392.706606 -222.614236)
		(mid 392.640623 -222.878416)
		(end 392.458194 -223.08058)
		(width 0.09525)
		(layer "In13.Cu")
		(net "M_H_CPU0_SA_DQS_DP<5>")
	)
	(arc
		(start 390.044686 -227.16744)
		(mid 389.928888 -227.301834)
		(end 389.887206 -227.474272)
		(width 0.09525)
		(layer "In13.Cu")
		(net "M_H_CPU0_SA_DQS_DP<5>")
	)
	(arc
		(start 390.513824 -226.357942)
		(mid 390.39855 -226.49222)
		(end 390.357106 -226.664266)
		(width 0.09525)
		(layer "In13.Cu")
		(net "M_H_CPU0_SA_DQS_DP<5>")
	)
	(arc
		(start 391.76706 -224.234248)
		(mid 391.702663 -224.495554)
		(end 391.524236 -224.697036)
		(width 0.09525)
		(layer "In13.Cu")
		(net "M_H_CPU0_SA_DQS_DP<5>")
	)
	(arc
		(start 383.026158 -227.959158)
		(mid 382.792614 -228.032864)
		(end 382.549908 -228.000052)
		(width 0.09525)
		(layer "In13.Cu")
		(net "M_H_CPU0_SA_DQS_DP<5>")
	)
	(arc
		(start 384.33502 -227.954332)
		(mid 384.149988 -227.908418)
		(end 383.966212 -227.959158)
		(width 0.09525)
		(layer "In13.Cu")
		(net "M_H_CPU0_SA_DQS_DP<5>")
	)
	(arc
		(start 388.666228 -227.959158)
		(mid 388.384796 -228.034913)
		(end 388.103364 -227.959158)
		(width 0.09525)
		(layer "In13.Cu")
		(net "M_H_CPU0_SA_DQS_DP<5>")
	)
	(arc
		(start 392.86434 -222.307404)
		(mid 392.748316 -222.441725)
		(end 392.706606 -222.614236)
		(width 0.09525)
		(layer "In13.Cu")
		(net "M_H_CPU0_SA_DQS_DP<5>")
	)
	(arc
		(start 389.035036 -227.954332)
		(mid 388.850004 -227.908418)
		(end 388.666228 -227.959158)
		(width 0.09525)
		(layer "In13.Cu")
		(net "M_H_CPU0_SA_DQS_DP<5>")
	)
	(arc
		(start 390.357106 -226.664266)
		(mid 390.292709 -226.925572)
		(end 390.114282 -227.127054)
		(width 0.09525)
		(layer "In13.Cu")
		(net "M_H_CPU0_SA_DQS_DP<5>")
	)
	(arc
		(start 388.094982 -227.954332)
		(mid 387.90995 -227.908418)
		(end 387.726174 -227.959158)
		(width 0.09525)
		(layer "In13.Cu")
		(net "M_H_CPU0_SA_DQS_DP<5>")
	)
	(segment
		(start 383.688082 -246.370094)
		(end 384.154934 -246.104156)
		(width 0.12954)
		(layer "F.Cu")
		(net "M_H_CPU0_SA_DQS_DP<4>")
	)
	(segment
		(start 395.798294 -245.933722)
		(end 395.774672 -245.933722)
		(width 0.09525)
		(layer "In13.Cu")
		(net "M_H_CPU0_SA_DQS_DP<4>")
	)
	(segment
		(start 391.494518 -246.434102)
		(end 391.486136 -246.429276)
		(width 0.09525)
		(layer "In13.Cu")
		(net "M_H_CPU0_SA_DQS_DP<4>")
	)
	(segment
		(start 420.864538 -238.615728)
		(end 420.508684 -238.259874)
		(width 0.16002)
		(layer "In13.Cu")
		(net "M_H_CPU0_SA_DQS_DP<4>")
	)
	(segment
		(start 384.00101 -246.369586)
		(end 384.154934 -246.104156)
		(width 0.09525)
		(layer "In13.Cu")
		(net "M_H_CPU0_SA_DQS_DP<4>")
	)
	(segment
		(start 385.854702 -246.434102)
		(end 385.84632 -246.429276)
		(width 0.09525)
		(layer "In13.Cu")
		(net "M_H_CPU0_SA_DQS_DP<4>")
	)
	(segment
		(start 394.83538 -246.752872)
		(end 394.317982 -246.752872)
		(width 0.09525)
		(layer "In13.Cu")
		(net "M_H_CPU0_SA_DQS_DP<4>")
	)
	(segment
		(start 394.046202 -246.481092)
		(end 393.556236 -246.481092)
		(width 0.09525)
		(layer "In13.Cu")
		(net "M_H_CPU0_SA_DQS_DP<4>")
	)
	(segment
		(start 384.024378 -246.456454)
		(end 384.00101 -246.369586)
		(width 0.09525)
		(layer "In13.Cu")
		(net "M_H_CPU0_SA_DQS_DP<4>")
	)
	(segment
		(start 394.317982 -246.752872)
		(end 394.046202 -246.481092)
		(width 0.09525)
		(layer "In13.Cu")
		(net "M_H_CPU0_SA_DQS_DP<4>")
	)
	(segment
		(start 418.601144 -238.259874)
		(end 418.070538 -237.729268)
		(width 0.16002)
		(layer "In13.Cu")
		(net "M_H_CPU0_SA_DQS_DP<4>")
	)
	(segment
		(start 418.070538 -237.729268)
		(end 414.821878 -237.729268)
		(width 0.16002)
		(layer "In13.Cu")
		(net "M_H_CPU0_SA_DQS_DP<4>")
	)
	(segment
		(start 413.948118 -238.603028)
		(end 412.965138 -238.603028)
		(width 0.16002)
		(layer "In13.Cu")
		(net "M_H_CPU0_SA_DQS_DP<4>")
	)
	(segment
		(start 384.343402 -246.429276)
		(end 384.33502 -246.434102)
		(width 0.09525)
		(layer "In13.Cu")
		(net "M_H_CPU0_SA_DQS_DP<4>")
	)
	(segment
		(start 421.44569 -238.615728)
		(end 420.864538 -238.615728)
		(width 0.16002)
		(layer "In13.Cu")
		(net "M_H_CPU0_SA_DQS_DP<4>")
	)
	(segment
		(start 412.965138 -238.603028)
		(end 411.457902 -240.110264)
		(width 0.16002)
		(layer "In13.Cu")
		(net "M_H_CPU0_SA_DQS_DP<4>")
	)
	(segment
		(start 424.012106 -238.13516)
		(end 423.701972 -238.445294)
		(width 0.16002)
		(layer "In13.Cu")
		(net "M_H_CPU0_SA_DQS_DP<4>")
	)
	(segment
		(start 388.103364 -246.429276)
		(end 388.094982 -246.434102)
		(width 0.09525)
		(layer "In13.Cu")
		(net "M_H_CPU0_SA_DQS_DP<4>")
	)
	(segment
		(start 410.567378 -240.110264)
		(end 404.74392 -245.933722)
		(width 0.16002)
		(layer "In13.Cu")
		(net "M_H_CPU0_SA_DQS_DP<4>")
	)
	(segment
		(start 414.821878 -237.729268)
		(end 413.948118 -238.603028)
		(width 0.16002)
		(layer "In13.Cu")
		(net "M_H_CPU0_SA_DQS_DP<4>")
	)
	(segment
		(start 421.616124 -238.445294)
		(end 421.44569 -238.615728)
		(width 0.16002)
		(layer "In13.Cu")
		(net "M_H_CPU0_SA_DQS_DP<4>")
	)
	(segment
		(start 395.71549 -245.992904)
		(end 395.538198 -245.992904)
		(width 0.09525)
		(layer "In13.Cu")
		(net "M_H_CPU0_SA_DQS_DP<4>")
	)
	(segment
		(start 392.426952 -246.429276)
		(end 392.416538 -246.42318)
		(width 0.09525)
		(layer "In13.Cu")
		(net "M_H_CPU0_SA_DQS_DP<4>")
	)
	(segment
		(start 392.824716 -246.417084)
		(end 392.79195 -246.436134)
		(width 0.09525)
		(layer "In13.Cu")
		(net "M_H_CPU0_SA_DQS_DP<4>")
	)
	(segment
		(start 404.74392 -245.933722)
		(end 395.798294 -245.933722)
		(width 0.16002)
		(layer "In13.Cu")
		(net "M_H_CPU0_SA_DQS_DP<4>")
	)
	(segment
		(start 384.914648 -246.434102)
		(end 384.906266 -246.429276)
		(width 0.09525)
		(layer "In13.Cu")
		(net "M_H_CPU0_SA_DQS_DP<4>")
	)
	(segment
		(start 395.538198 -245.992904)
		(end 394.83538 -246.752872)
		(width 0.09525)
		(layer "In13.Cu")
		(net "M_H_CPU0_SA_DQS_DP<4>")
	)
	(segment
		(start 389.043418 -246.429276)
		(end 389.035036 -246.434102)
		(width 0.09525)
		(layer "In13.Cu")
		(net "M_H_CPU0_SA_DQS_DP<4>")
	)
	(segment
		(start 420.508684 -238.259874)
		(end 418.601144 -238.259874)
		(width 0.16002)
		(layer "In13.Cu")
		(net "M_H_CPU0_SA_DQS_DP<4>")
	)
	(segment
		(start 423.701972 -238.445294)
		(end 421.616124 -238.445294)
		(width 0.16002)
		(layer "In13.Cu")
		(net "M_H_CPU0_SA_DQS_DP<4>")
	)
	(segment
		(start 395.774672 -245.933722)
		(end 395.71549 -245.992904)
		(width 0.09525)
		(layer "In13.Cu")
		(net "M_H_CPU0_SA_DQS_DP<4>")
	)
	(segment
		(start 411.457902 -240.110264)
		(end 410.567378 -240.110264)
		(width 0.16002)
		(layer "In13.Cu")
		(net "M_H_CPU0_SA_DQS_DP<4>")
	)
	(segment
		(start 389.614664 -246.434102)
		(end 389.606282 -246.429276)
		(width 0.09525)
		(layer "In13.Cu")
		(net "M_H_CPU0_SA_DQS_DP<4>")
	)
	(arc
		(start 392.416538 -246.42318)
		(mid 392.139376 -246.35338)
		(end 391.863834 -246.429276)
		(width 0.09525)
		(layer "In13.Cu")
		(net "M_H_CPU0_SA_DQS_DP<4>")
	)
	(arc
		(start 391.863834 -246.429276)
		(mid 391.679805 -246.480175)
		(end 391.494518 -246.434102)
		(width 0.09525)
		(layer "In13.Cu")
		(net "M_H_CPU0_SA_DQS_DP<4>")
	)
	(arc
		(start 390.546336 -246.429276)
		(mid 390.264904 -246.353521)
		(end 389.983472 -246.429276)
		(width 0.09525)
		(layer "In13.Cu")
		(net "M_H_CPU0_SA_DQS_DP<4>")
	)
	(arc
		(start 388.094982 -246.434102)
		(mid 387.90995 -246.480016)
		(end 387.726174 -246.429276)
		(width 0.09525)
		(layer "In13.Cu")
		(net "M_H_CPU0_SA_DQS_DP<4>")
	)
	(arc
		(start 384.33502 -246.434102)
		(mid 384.182125 -246.47893)
		(end 384.024378 -246.456454)
		(width 0.09525)
		(layer "In13.Cu")
		(net "M_H_CPU0_SA_DQS_DP<4>")
	)
	(arc
		(start 386.22351 -246.429276)
		(mid 386.039735 -246.480048)
		(end 385.854702 -246.434102)
		(width 0.09525)
		(layer "In13.Cu")
		(net "M_H_CPU0_SA_DQS_DP<4>")
	)
	(arc
		(start 393.366752 -246.429276)
		(mid 393.097319 -246.353405)
		(end 392.824716 -246.417084)
		(width 0.09525)
		(layer "In13.Cu")
		(net "M_H_CPU0_SA_DQS_DP<4>")
	)
	(arc
		(start 385.84632 -246.429276)
		(mid 385.564888 -246.353521)
		(end 385.283456 -246.429276)
		(width 0.09525)
		(layer "In13.Cu")
		(net "M_H_CPU0_SA_DQS_DP<4>")
	)
	(arc
		(start 389.035036 -246.434102)
		(mid 388.850004 -246.480016)
		(end 388.666228 -246.429276)
		(width 0.09525)
		(layer "In13.Cu")
		(net "M_H_CPU0_SA_DQS_DP<4>")
	)
	(arc
		(start 388.666228 -246.429276)
		(mid 388.384796 -246.353521)
		(end 388.103364 -246.429276)
		(width 0.09525)
		(layer "In13.Cu")
		(net "M_H_CPU0_SA_DQS_DP<4>")
	)
	(arc
		(start 393.556236 -246.481092)
		(mid 393.45807 -246.467724)
		(end 393.366752 -246.429276)
		(width 0.09525)
		(layer "In13.Cu")
		(net "M_H_CPU0_SA_DQS_DP<4>")
	)
	(arc
		(start 384.906266 -246.429276)
		(mid 384.624834 -246.353521)
		(end 384.343402 -246.429276)
		(width 0.09525)
		(layer "In13.Cu")
		(net "M_H_CPU0_SA_DQS_DP<4>")
	)
	(arc
		(start 385.283456 -246.429276)
		(mid 385.099681 -246.480048)
		(end 384.914648 -246.434102)
		(width 0.09525)
		(layer "In13.Cu")
		(net "M_H_CPU0_SA_DQS_DP<4>")
	)
	(arc
		(start 391.486136 -246.429276)
		(mid 391.204704 -246.353521)
		(end 390.923272 -246.429276)
		(width 0.09525)
		(layer "In13.Cu")
		(net "M_H_CPU0_SA_DQS_DP<4>")
	)
	(arc
		(start 386.786374 -246.429276)
		(mid 386.504942 -246.353521)
		(end 386.22351 -246.429276)
		(width 0.09525)
		(layer "In13.Cu")
		(net "M_H_CPU0_SA_DQS_DP<4>")
	)
	(arc
		(start 390.923272 -246.429276)
		(mid 390.734804 -246.479953)
		(end 390.546336 -246.429276)
		(width 0.09525)
		(layer "In13.Cu")
		(net "M_H_CPU0_SA_DQS_DP<4>")
	)
	(arc
		(start 387.726174 -246.429276)
		(mid 387.444742 -246.353521)
		(end 387.16331 -246.429276)
		(width 0.09525)
		(layer "In13.Cu")
		(net "M_H_CPU0_SA_DQS_DP<4>")
	)
	(arc
		(start 389.606282 -246.429276)
		(mid 389.32485 -246.353521)
		(end 389.043418 -246.429276)
		(width 0.09525)
		(layer "In13.Cu")
		(net "M_H_CPU0_SA_DQS_DP<4>")
	)
	(arc
		(start 387.16331 -246.429276)
		(mid 386.974842 -246.479953)
		(end 386.786374 -246.429276)
		(width 0.09525)
		(layer "In13.Cu")
		(net "M_H_CPU0_SA_DQS_DP<4>")
	)
	(arc
		(start 392.79195 -246.436134)
		(mid 392.608569 -246.479965)
		(end 392.426952 -246.429276)
		(width 0.09525)
		(layer "In13.Cu")
		(net "M_H_CPU0_SA_DQS_DP<4>")
	)
	(arc
		(start 389.983472 -246.429276)
		(mid 389.799697 -246.480048)
		(end 389.614664 -246.434102)
		(width 0.09525)
		(layer "In13.Cu")
		(net "M_H_CPU0_SA_DQS_DP<4>")
	)
	(segment
		(start 383.688082 -241.510058)
		(end 384.154934 -241.24412)
		(width 0.12954)
		(layer "F.Cu")
		(net "M_H_CPU0_SA_DQS_DP<3>")
	)
	(segment
		(start 399.618708 -240.2967)
		(end 405.987758 -233.92765)
		(width 0.16002)
		(layer "In13.Cu")
		(net "M_H_CPU0_SA_DQS_DP<3>")
	)
	(segment
		(start 418.070538 -228.379274)
		(end 418.601144 -228.90988)
		(width 0.16002)
		(layer "In13.Cu")
		(net "M_H_CPU0_SA_DQS_DP<3>")
	)
	(segment
		(start 394.305028 -240.92281)
		(end 394.736574 -240.92281)
		(width 0.09525)
		(layer "In13.Cu")
		(net "M_H_CPU0_SA_DQS_DP<3>")
	)
	(segment
		(start 418.601144 -228.90988)
		(end 420.508684 -228.90988)
		(width 0.16002)
		(layer "In13.Cu")
		(net "M_H_CPU0_SA_DQS_DP<3>")
	)
	(segment
		(start 388.094982 -241.574066)
		(end 388.103364 -241.56924)
		(width 0.09525)
		(layer "In13.Cu")
		(net "M_H_CPU0_SA_DQS_DP<3>")
	)
	(segment
		(start 392.416538 -241.563144)
		(end 392.426952 -241.56924)
		(width 0.09525)
		(layer "In13.Cu")
		(net "M_H_CPU0_SA_DQS_DP<3>")
	)
	(segment
		(start 391.486136 -241.56924)
		(end 391.494518 -241.574066)
		(width 0.09525)
		(layer "In13.Cu")
		(net "M_H_CPU0_SA_DQS_DP<3>")
	)
	(segment
		(start 410.177742 -229.253034)
		(end 413.948118 -229.253034)
		(width 0.16002)
		(layer "In13.Cu")
		(net "M_H_CPU0_SA_DQS_DP<3>")
	)
	(segment
		(start 420.508684 -228.90988)
		(end 420.864538 -229.265734)
		(width 0.16002)
		(layer "In13.Cu")
		(net "M_H_CPU0_SA_DQS_DP<3>")
	)
	(segment
		(start 393.084812 -241.493548)
		(end 393.73429 -241.493548)
		(width 0.09525)
		(layer "In13.Cu")
		(net "M_H_CPU0_SA_DQS_DP<3>")
	)
	(segment
		(start 389.606282 -241.56924)
		(end 389.614664 -241.574066)
		(width 0.09525)
		(layer "In13.Cu")
		(net "M_H_CPU0_SA_DQS_DP<3>")
	)
	(segment
		(start 421.66413 -229.047294)
		(end 422.515538 -229.047294)
		(width 0.16002)
		(layer "In13.Cu")
		(net "M_H_CPU0_SA_DQS_DP<3>")
	)
	(segment
		(start 384.00101 -241.50955)
		(end 384.024378 -241.596418)
		(width 0.09525)
		(layer "In13.Cu")
		(net "M_H_CPU0_SA_DQS_DP<3>")
	)
	(segment
		(start 413.948118 -229.253034)
		(end 414.821878 -228.379274)
		(width 0.16002)
		(layer "In13.Cu")
		(net "M_H_CPU0_SA_DQS_DP<3>")
	)
	(segment
		(start 423.132758 -228.907594)
		(end 423.272458 -229.047294)
		(width 0.16002)
		(layer "In13.Cu")
		(net "M_H_CPU0_SA_DQS_DP<3>")
	)
	(segment
		(start 394.736574 -240.92281)
		(end 395.303502 -240.355882)
		(width 0.09525)
		(layer "In13.Cu")
		(net "M_H_CPU0_SA_DQS_DP<3>")
	)
	(segment
		(start 393.73429 -241.493548)
		(end 394.305028 -240.92281)
		(width 0.09525)
		(layer "In13.Cu")
		(net "M_H_CPU0_SA_DQS_DP<3>")
	)
	(segment
		(start 389.035036 -241.574066)
		(end 389.043418 -241.56924)
		(width 0.09525)
		(layer "In13.Cu")
		(net "M_H_CPU0_SA_DQS_DP<3>")
	)
	(segment
		(start 423.272458 -229.047294)
		(end 423.749978 -229.047294)
		(width 0.16002)
		(layer "In13.Cu")
		(net "M_H_CPU0_SA_DQS_DP<3>")
	)
	(segment
		(start 384.906266 -241.56924)
		(end 384.914648 -241.574066)
		(width 0.09525)
		(layer "In13.Cu")
		(net "M_H_CPU0_SA_DQS_DP<3>")
	)
	(segment
		(start 414.821878 -228.379274)
		(end 418.070538 -228.379274)
		(width 0.16002)
		(layer "In13.Cu")
		(net "M_H_CPU0_SA_DQS_DP<3>")
	)
	(segment
		(start 395.769338 -240.355882)
		(end 395.82852 -240.2967)
		(width 0.09525)
		(layer "In13.Cu")
		(net "M_H_CPU0_SA_DQS_DP<3>")
	)
	(segment
		(start 405.987758 -233.443018)
		(end 410.177742 -229.253034)
		(width 0.16002)
		(layer "In13.Cu")
		(net "M_H_CPU0_SA_DQS_DP<3>")
	)
	(segment
		(start 405.987758 -233.92765)
		(end 405.987758 -233.443018)
		(width 0.16002)
		(layer "In13.Cu")
		(net "M_H_CPU0_SA_DQS_DP<3>")
	)
	(segment
		(start 421.44569 -229.265734)
		(end 421.66413 -229.047294)
		(width 0.16002)
		(layer "In13.Cu")
		(net "M_H_CPU0_SA_DQS_DP<3>")
	)
	(segment
		(start 384.154934 -241.24412)
		(end 384.00101 -241.50955)
		(width 0.09525)
		(layer "In13.Cu")
		(net "M_H_CPU0_SA_DQS_DP<3>")
	)
	(segment
		(start 420.864538 -229.265734)
		(end 421.44569 -229.265734)
		(width 0.16002)
		(layer "In13.Cu")
		(net "M_H_CPU0_SA_DQS_DP<3>")
	)
	(segment
		(start 385.84632 -241.56924)
		(end 385.854702 -241.574066)
		(width 0.09525)
		(layer "In13.Cu")
		(net "M_H_CPU0_SA_DQS_DP<3>")
	)
	(segment
		(start 422.655238 -228.907594)
		(end 423.132758 -228.907594)
		(width 0.16002)
		(layer "In13.Cu")
		(net "M_H_CPU0_SA_DQS_DP<3>")
	)
	(segment
		(start 384.33502 -241.574066)
		(end 384.343402 -241.56924)
		(width 0.09525)
		(layer "In13.Cu")
		(net "M_H_CPU0_SA_DQS_DP<3>")
	)
	(segment
		(start 395.303502 -240.355882)
		(end 395.769338 -240.355882)
		(width 0.09525)
		(layer "In13.Cu")
		(net "M_H_CPU0_SA_DQS_DP<3>")
	)
	(segment
		(start 422.515538 -229.047294)
		(end 422.655238 -228.907594)
		(width 0.16002)
		(layer "In13.Cu")
		(net "M_H_CPU0_SA_DQS_DP<3>")
	)
	(segment
		(start 395.82852 -240.2967)
		(end 395.852142 -240.2967)
		(width 0.09525)
		(layer "In13.Cu")
		(net "M_H_CPU0_SA_DQS_DP<3>")
	)
	(segment
		(start 395.852142 -240.2967)
		(end 399.618708 -240.2967)
		(width 0.16002)
		(layer "In13.Cu")
		(net "M_H_CPU0_SA_DQS_DP<3>")
	)
	(segment
		(start 423.749978 -229.047294)
		(end 424.012106 -228.785166)
		(width 0.16002)
		(layer "In13.Cu")
		(net "M_H_CPU0_SA_DQS_DP<3>")
	)
	(arc
		(start 388.103364 -241.56924)
		(mid 388.384796 -241.493485)
		(end 388.666228 -241.56924)
		(width 0.09525)
		(layer "In13.Cu")
		(net "M_H_CPU0_SA_DQS_DP<3>")
	)
	(arc
		(start 391.863834 -241.56924)
		(mid 392.139377 -241.493391)
		(end 392.416538 -241.563144)
		(width 0.09525)
		(layer "In13.Cu")
		(net "M_H_CPU0_SA_DQS_DP<3>")
	)
	(arc
		(start 389.983472 -241.56924)
		(mid 390.264904 -241.493485)
		(end 390.546336 -241.56924)
		(width 0.09525)
		(layer "In13.Cu")
		(net "M_H_CPU0_SA_DQS_DP<3>")
	)
	(arc
		(start 392.79195 -241.576098)
		(mid 392.932676 -241.514587)
		(end 393.084812 -241.493548)
		(width 0.09525)
		(layer "In13.Cu")
		(net "M_H_CPU0_SA_DQS_DP<3>")
	)
	(arc
		(start 387.16331 -241.56924)
		(mid 387.444742 -241.493485)
		(end 387.726174 -241.56924)
		(width 0.09525)
		(layer "In13.Cu")
		(net "M_H_CPU0_SA_DQS_DP<3>")
	)
	(arc
		(start 384.343402 -241.56924)
		(mid 384.624834 -241.493485)
		(end 384.906266 -241.56924)
		(width 0.09525)
		(layer "In13.Cu")
		(net "M_H_CPU0_SA_DQS_DP<3>")
	)
	(arc
		(start 389.614664 -241.574066)
		(mid 389.799696 -241.61998)
		(end 389.983472 -241.56924)
		(width 0.09525)
		(layer "In13.Cu")
		(net "M_H_CPU0_SA_DQS_DP<3>")
	)
	(arc
		(start 391.494518 -241.574066)
		(mid 391.679804 -241.620102)
		(end 391.863834 -241.56924)
		(width 0.09525)
		(layer "In13.Cu")
		(net "M_H_CPU0_SA_DQS_DP<3>")
	)
	(arc
		(start 384.914648 -241.574066)
		(mid 385.09968 -241.61998)
		(end 385.283456 -241.56924)
		(width 0.09525)
		(layer "In13.Cu")
		(net "M_H_CPU0_SA_DQS_DP<3>")
	)
	(arc
		(start 385.283456 -241.56924)
		(mid 385.564888 -241.493485)
		(end 385.84632 -241.56924)
		(width 0.09525)
		(layer "In13.Cu")
		(net "M_H_CPU0_SA_DQS_DP<3>")
	)
	(arc
		(start 390.546336 -241.56924)
		(mid 390.734804 -241.619917)
		(end 390.923272 -241.56924)
		(width 0.09525)
		(layer "In13.Cu")
		(net "M_H_CPU0_SA_DQS_DP<3>")
	)
	(arc
		(start 384.024378 -241.596418)
		(mid 384.182128 -241.618937)
		(end 384.33502 -241.574066)
		(width 0.09525)
		(layer "In13.Cu")
		(net "M_H_CPU0_SA_DQS_DP<3>")
	)
	(arc
		(start 389.043418 -241.56924)
		(mid 389.32485 -241.493485)
		(end 389.606282 -241.56924)
		(width 0.09525)
		(layer "In13.Cu")
		(net "M_H_CPU0_SA_DQS_DP<3>")
	)
	(arc
		(start 386.22351 -241.56924)
		(mid 386.504942 -241.493485)
		(end 386.786374 -241.56924)
		(width 0.09525)
		(layer "In13.Cu")
		(net "M_H_CPU0_SA_DQS_DP<3>")
	)
	(arc
		(start 392.426952 -241.56924)
		(mid 392.608568 -241.619977)
		(end 392.79195 -241.576098)
		(width 0.09525)
		(layer "In13.Cu")
		(net "M_H_CPU0_SA_DQS_DP<3>")
	)
	(arc
		(start 386.786374 -241.56924)
		(mid 386.974842 -241.619917)
		(end 387.16331 -241.56924)
		(width 0.09525)
		(layer "In13.Cu")
		(net "M_H_CPU0_SA_DQS_DP<3>")
	)
	(arc
		(start 385.854702 -241.574066)
		(mid 386.039734 -241.61998)
		(end 386.22351 -241.56924)
		(width 0.09525)
		(layer "In13.Cu")
		(net "M_H_CPU0_SA_DQS_DP<3>")
	)
	(arc
		(start 388.666228 -241.56924)
		(mid 388.850003 -241.620012)
		(end 389.035036 -241.574066)
		(width 0.09525)
		(layer "In13.Cu")
		(net "M_H_CPU0_SA_DQS_DP<3>")
	)
	(arc
		(start 390.923272 -241.56924)
		(mid 391.204704 -241.493485)
		(end 391.486136 -241.56924)
		(width 0.09525)
		(layer "In13.Cu")
		(net "M_H_CPU0_SA_DQS_DP<3>")
	)
	(arc
		(start 387.726174 -241.56924)
		(mid 387.909949 -241.620012)
		(end 388.094982 -241.574066)
		(width 0.09525)
		(layer "In13.Cu")
		(net "M_H_CPU0_SA_DQS_DP<3>")
	)
	(segment
		(start 383.688082 -236.650022)
		(end 384.154934 -236.384084)
		(width 0.12954)
		(layer "F.Cu")
		(net "M_H_CPU0_SA_DQS_DP<2>")
	)
	(segment
		(start 411.36824 -219.579952)
		(end 412.910274 -219.579952)
		(width 0.16002)
		(layer "In13.Cu")
		(net "M_H_CPU0_SA_DQS_DP<2>")
	)
	(segment
		(start 394.801598 -235.481622)
		(end 395.509496 -234.626404)
		(width 0.09525)
		(layer "In13.Cu")
		(net "M_H_CPU0_SA_DQS_DP<2>")
	)
	(segment
		(start 385.84632 -236.709204)
		(end 385.854702 -236.71403)
		(width 0.09525)
		(layer "In13.Cu")
		(net "M_H_CPU0_SA_DQS_DP<2>")
	)
	(segment
		(start 390.909048 -236.717586)
		(end 390.923272 -236.709204)
		(width 0.09525)
		(layer "In13.Cu")
		(net "M_H_CPU0_SA_DQS_DP<2>")
	)
	(segment
		(start 413.233362 -219.90304)
		(end 413.948118 -219.90304)
		(width 0.16002)
		(layer "In13.Cu")
		(net "M_H_CPU0_SA_DQS_DP<2>")
	)
	(segment
		(start 395.825726 -234.567222)
		(end 395.849348 -234.567222)
		(width 0.09525)
		(layer "In13.Cu")
		(net "M_H_CPU0_SA_DQS_DP<2>")
	)
	(segment
		(start 409.033472 -220.68028)
		(end 409.173172 -220.54058)
		(width 0.16002)
		(layer "In13.Cu")
		(net "M_H_CPU0_SA_DQS_DP<2>")
	)
	(segment
		(start 393.292584 -236.629702)
		(end 394.440664 -235.481622)
		(width 0.09525)
		(layer "In13.Cu")
		(net "M_H_CPU0_SA_DQS_DP<2>")
	)
	(segment
		(start 409.790392 -220.68028)
		(end 410.267912 -220.68028)
		(width 0.16002)
		(layer "In13.Cu")
		(net "M_H_CPU0_SA_DQS_DP<2>")
	)
	(segment
		(start 384.154934 -236.384084)
		(end 384.00101 -236.649514)
		(width 0.09525)
		(layer "In13.Cu")
		(net "M_H_CPU0_SA_DQS_DP<2>")
	)
	(segment
		(start 403.124162 -225.882708)
		(end 408.32659 -220.68028)
		(width 0.16002)
		(layer "In13.Cu")
		(net "M_H_CPU0_SA_DQS_DP<2>")
	)
	(segment
		(start 412.910274 -219.579952)
		(end 413.233362 -219.90304)
		(width 0.16002)
		(layer "In13.Cu")
		(net "M_H_CPU0_SA_DQS_DP<2>")
	)
	(segment
		(start 418.601144 -219.559886)
		(end 420.508684 -219.559886)
		(width 0.16002)
		(layer "In13.Cu")
		(net "M_H_CPU0_SA_DQS_DP<2>")
	)
	(segment
		(start 389.606282 -236.709204)
		(end 389.614664 -236.71403)
		(width 0.09525)
		(layer "In13.Cu")
		(net "M_H_CPU0_SA_DQS_DP<2>")
	)
	(segment
		(start 422.076118 -219.285312)
		(end 422.7576 -219.285312)
		(width 0.16002)
		(layer "In13.Cu")
		(net "M_H_CPU0_SA_DQS_DP<2>")
	)
	(segment
		(start 390.895332 -236.723936)
		(end 390.909048 -236.717586)
		(width 0.09525)
		(layer "In13.Cu")
		(net "M_H_CPU0_SA_DQS_DP<2>")
	)
	(segment
		(start 414.821878 -219.02928)
		(end 418.070538 -219.02928)
		(width 0.16002)
		(layer "In13.Cu")
		(net "M_H_CPU0_SA_DQS_DP<2>")
	)
	(segment
		(start 395.766544 -234.626404)
		(end 395.825726 -234.567222)
		(width 0.09525)
		(layer "In13.Cu")
		(net "M_H_CPU0_SA_DQS_DP<2>")
	)
	(segment
		(start 413.948118 -219.90304)
		(end 414.821878 -219.02928)
		(width 0.16002)
		(layer "In13.Cu")
		(net "M_H_CPU0_SA_DQS_DP<2>")
	)
	(segment
		(start 384.00101 -236.649514)
		(end 384.024378 -236.736382)
		(width 0.09525)
		(layer "In13.Cu")
		(net "M_H_CPU0_SA_DQS_DP<2>")
	)
	(segment
		(start 395.509496 -234.626404)
		(end 395.766544 -234.626404)
		(width 0.09525)
		(layer "In13.Cu")
		(net "M_H_CPU0_SA_DQS_DP<2>")
	)
	(segment
		(start 384.906266 -236.709204)
		(end 384.914648 -236.71403)
		(width 0.09525)
		(layer "In13.Cu")
		(net "M_H_CPU0_SA_DQS_DP<2>")
	)
	(segment
		(start 395.849348 -234.567222)
		(end 396.849854 -234.567222)
		(width 0.16002)
		(layer "In13.Cu")
		(net "M_H_CPU0_SA_DQS_DP<2>")
	)
	(segment
		(start 423.747184 -219.700094)
		(end 424.012106 -219.435172)
		(width 0.16002)
		(layer "In13.Cu")
		(net "M_H_CPU0_SA_DQS_DP<2>")
	)
	(segment
		(start 384.33502 -236.71403)
		(end 384.343402 -236.709204)
		(width 0.09525)
		(layer "In13.Cu")
		(net "M_H_CPU0_SA_DQS_DP<2>")
	)
	(segment
		(start 420.508684 -219.559886)
		(end 420.864538 -219.91574)
		(width 0.16002)
		(layer "In13.Cu")
		(net "M_H_CPU0_SA_DQS_DP<2>")
	)
	(segment
		(start 388.094982 -236.71403)
		(end 388.103364 -236.709204)
		(width 0.09525)
		(layer "In13.Cu")
		(net "M_H_CPU0_SA_DQS_DP<2>")
	)
	(segment
		(start 392.376152 -236.679994)
		(end 392.376152 -236.679486)
		(width 0.09525)
		(layer "In13.Cu")
		(net "M_H_CPU0_SA_DQS_DP<2>")
	)
	(segment
		(start 422.7576 -219.285312)
		(end 423.172382 -219.700094)
		(width 0.16002)
		(layer "In13.Cu")
		(net "M_H_CPU0_SA_DQS_DP<2>")
	)
	(segment
		(start 420.864538 -219.91574)
		(end 421.44569 -219.91574)
		(width 0.16002)
		(layer "In13.Cu")
		(net "M_H_CPU0_SA_DQS_DP<2>")
	)
	(segment
		(start 394.440664 -235.481622)
		(end 394.801598 -235.481622)
		(width 0.09525)
		(layer "In13.Cu")
		(net "M_H_CPU0_SA_DQS_DP<2>")
	)
	(segment
		(start 409.650692 -220.54058)
		(end 409.790392 -220.68028)
		(width 0.16002)
		(layer "In13.Cu")
		(net "M_H_CPU0_SA_DQS_DP<2>")
	)
	(segment
		(start 410.267912 -220.68028)
		(end 411.36824 -219.579952)
		(width 0.16002)
		(layer "In13.Cu")
		(net "M_H_CPU0_SA_DQS_DP<2>")
	)
	(segment
		(start 421.44569 -219.91574)
		(end 422.076118 -219.285312)
		(width 0.16002)
		(layer "In13.Cu")
		(net "M_H_CPU0_SA_DQS_DP<2>")
	)
	(segment
		(start 408.32659 -220.68028)
		(end 409.033472 -220.68028)
		(width 0.16002)
		(layer "In13.Cu")
		(net "M_H_CPU0_SA_DQS_DP<2>")
	)
	(segment
		(start 409.173172 -220.54058)
		(end 409.650692 -220.54058)
		(width 0.16002)
		(layer "In13.Cu")
		(net "M_H_CPU0_SA_DQS_DP<2>")
	)
	(segment
		(start 393.042902 -236.629702)
		(end 393.292584 -236.629702)
		(width 0.09525)
		(layer "In13.Cu")
		(net "M_H_CPU0_SA_DQS_DP<2>")
	)
	(segment
		(start 389.035036 -236.71403)
		(end 389.043418 -236.709204)
		(width 0.09525)
		(layer "In13.Cu")
		(net "M_H_CPU0_SA_DQS_DP<2>")
	)
	(segment
		(start 396.849854 -234.567222)
		(end 403.124162 -228.292914)
		(width 0.16002)
		(layer "In13.Cu")
		(net "M_H_CPU0_SA_DQS_DP<2>")
	)
	(segment
		(start 423.172382 -219.700094)
		(end 423.747184 -219.700094)
		(width 0.16002)
		(layer "In13.Cu")
		(net "M_H_CPU0_SA_DQS_DP<2>")
	)
	(segment
		(start 403.124162 -228.292914)
		(end 403.124162 -225.882708)
		(width 0.16002)
		(layer "In13.Cu")
		(net "M_H_CPU0_SA_DQS_DP<2>")
	)
	(segment
		(start 418.070538 -219.02928)
		(end 418.601144 -219.559886)
		(width 0.16002)
		(layer "In13.Cu")
		(net "M_H_CPU0_SA_DQS_DP<2>")
	)
	(arc
		(start 391.889234 -236.701076)
		(mid 392.130916 -236.649613)
		(end 392.376152 -236.679994)
		(width 0.09525)
		(layer "In13.Cu")
		(net "M_H_CPU0_SA_DQS_DP<2>")
	)
	(arc
		(start 389.983472 -236.709204)
		(mid 390.264904 -236.633449)
		(end 390.546336 -236.709204)
		(width 0.09525)
		(layer "In13.Cu")
		(net "M_H_CPU0_SA_DQS_DP<2>")
	)
	(arc
		(start 391.443972 -236.686852)
		(mid 391.46262 -236.6952)
		(end 391.481564 -236.702854)
		(width 0.09525)
		(layer "In13.Cu")
		(net "M_H_CPU0_SA_DQS_DP<2>")
	)
	(arc
		(start 392.92149 -236.653324)
		(mid 392.981041 -236.635569)
		(end 393.042902 -236.629702)
		(width 0.09525)
		(layer "In13.Cu")
		(net "M_H_CPU0_SA_DQS_DP<2>")
	)
	(arc
		(start 384.024378 -236.736382)
		(mid 384.182128 -236.758901)
		(end 384.33502 -236.71403)
		(width 0.09525)
		(layer "In13.Cu")
		(net "M_H_CPU0_SA_DQS_DP<2>")
	)
	(arc
		(start 386.22351 -236.709204)
		(mid 386.504942 -236.633449)
		(end 386.786374 -236.709204)
		(width 0.09525)
		(layer "In13.Cu")
		(net "M_H_CPU0_SA_DQS_DP<2>")
	)
	(arc
		(start 390.923272 -236.709204)
		(mid 391.180871 -236.633839)
		(end 391.443972 -236.686852)
		(width 0.09525)
		(layer "In13.Cu")
		(net "M_H_CPU0_SA_DQS_DP<2>")
	)
	(arc
		(start 384.914648 -236.71403)
		(mid 385.09968 -236.759944)
		(end 385.283456 -236.709204)
		(width 0.09525)
		(layer "In13.Cu")
		(net "M_H_CPU0_SA_DQS_DP<2>")
	)
	(arc
		(start 389.043418 -236.709204)
		(mid 389.32485 -236.633449)
		(end 389.606282 -236.709204)
		(width 0.09525)
		(layer "In13.Cu")
		(net "M_H_CPU0_SA_DQS_DP<2>")
	)
	(arc
		(start 385.854702 -236.71403)
		(mid 386.039734 -236.759944)
		(end 386.22351 -236.709204)
		(width 0.09525)
		(layer "In13.Cu")
		(net "M_H_CPU0_SA_DQS_DP<2>")
	)
	(arc
		(start 387.16331 -236.709204)
		(mid 387.444742 -236.633449)
		(end 387.726174 -236.709204)
		(width 0.09525)
		(layer "In13.Cu")
		(net "M_H_CPU0_SA_DQS_DP<2>")
	)
	(arc
		(start 391.481564 -236.702854)
		(mid 391.685575 -236.740388)
		(end 391.889234 -236.701076)
		(width 0.09525)
		(layer "In13.Cu")
		(net "M_H_CPU0_SA_DQS_DP<2>")
	)
	(arc
		(start 388.103364 -236.709204)
		(mid 388.384796 -236.633449)
		(end 388.666228 -236.709204)
		(width 0.09525)
		(layer "In13.Cu")
		(net "M_H_CPU0_SA_DQS_DP<2>")
	)
	(arc
		(start 392.376152 -236.679486)
		(mid 392.65107 -236.713137)
		(end 392.92149 -236.653324)
		(width 0.09525)
		(layer "In13.Cu")
		(net "M_H_CPU0_SA_DQS_DP<2>")
	)
	(arc
		(start 387.726174 -236.709204)
		(mid 387.909949 -236.759976)
		(end 388.094982 -236.71403)
		(width 0.09525)
		(layer "In13.Cu")
		(net "M_H_CPU0_SA_DQS_DP<2>")
	)
	(arc
		(start 385.283456 -236.709204)
		(mid 385.564888 -236.633449)
		(end 385.84632 -236.709204)
		(width 0.09525)
		(layer "In13.Cu")
		(net "M_H_CPU0_SA_DQS_DP<2>")
	)
	(arc
		(start 389.614664 -236.71403)
		(mid 389.799696 -236.759944)
		(end 389.983472 -236.709204)
		(width 0.09525)
		(layer "In13.Cu")
		(net "M_H_CPU0_SA_DQS_DP<2>")
	)
	(arc
		(start 390.546336 -236.709204)
		(mid 390.719012 -236.759549)
		(end 390.895332 -236.723936)
		(width 0.09525)
		(layer "In13.Cu")
		(net "M_H_CPU0_SA_DQS_DP<2>")
	)
	(arc
		(start 388.666228 -236.709204)
		(mid 388.850003 -236.759976)
		(end 389.035036 -236.71403)
		(width 0.09525)
		(layer "In13.Cu")
		(net "M_H_CPU0_SA_DQS_DP<2>")
	)
	(arc
		(start 386.786374 -236.709204)
		(mid 386.974842 -236.759881)
		(end 387.16331 -236.709204)
		(width 0.09525)
		(layer "In13.Cu")
		(net "M_H_CPU0_SA_DQS_DP<2>")
	)
	(arc
		(start 384.343402 -236.709204)
		(mid 384.624834 -236.633449)
		(end 384.906266 -236.709204)
		(width 0.09525)
		(layer "In13.Cu")
		(net "M_H_CPU0_SA_DQS_DP<2>")
	)
	(segment
		(start 383.688082 -231.789986)
		(end 384.154934 -231.524048)
		(width 0.12954)
		(layer "F.Cu")
		(net "M_H_CPU0_SA_DQS_DP<1>")
	)
	(segment
		(start 392.400536 -231.330246)
		(end 391.940796 -231.789986)
		(width 0.09525)
		(layer "In13.Cu")
		(net "M_H_CPU0_SA_DQS_DP<1>")
	)
	(segment
		(start 384.00101 -231.789478)
		(end 384.154934 -231.524048)
		(width 0.09525)
		(layer "In13.Cu")
		(net "M_H_CPU0_SA_DQS_DP<1>")
	)
	(segment
		(start 392.400536 -230.607362)
		(end 392.400536 -231.330246)
		(width 0.09525)
		(layer "In13.Cu")
		(net "M_H_CPU0_SA_DQS_DP<1>")
	)
	(segment
		(start 393.24788 -230.11765)
		(end 392.890248 -230.11765)
		(width 0.09525)
		(layer "In13.Cu")
		(net "M_H_CPU0_SA_DQS_DP<1>")
	)
	(segment
		(start 389.043418 -231.849168)
		(end 389.035036 -231.853994)
		(width 0.09525)
		(layer "In13.Cu")
		(net "M_H_CPU0_SA_DQS_DP<1>")
	)
	(segment
		(start 385.854702 -231.853994)
		(end 385.84632 -231.849168)
		(width 0.09525)
		(layer "In13.Cu")
		(net "M_H_CPU0_SA_DQS_DP<1>")
	)
	(segment
		(start 395.010386 -227.985828)
		(end 395.010386 -228.355144)
		(width 0.09525)
		(layer "In13.Cu")
		(net "M_H_CPU0_SA_DQS_DP<1>")
	)
	(segment
		(start 420.508684 -210.209892)
		(end 418.601144 -210.209892)
		(width 0.16002)
		(layer "In13.Cu")
		(net "M_H_CPU0_SA_DQS_DP<1>")
	)
	(segment
		(start 421.44569 -210.565746)
		(end 420.864538 -210.565746)
		(width 0.16002)
		(layer "In13.Cu")
		(net "M_H_CPU0_SA_DQS_DP<1>")
	)
	(segment
		(start 392.890248 -230.11765)
		(end 392.400536 -230.607362)
		(width 0.09525)
		(layer "In13.Cu")
		(net "M_H_CPU0_SA_DQS_DP<1>")
	)
	(segment
		(start 413.03956 -210.247992)
		(end 409.031186 -210.247992)
		(width 0.16002)
		(layer "In13.Cu")
		(net "M_H_CPU0_SA_DQS_DP<1>")
	)
	(segment
		(start 414.821878 -209.679286)
		(end 413.948118 -210.553046)
		(width 0.16002)
		(layer "In13.Cu")
		(net "M_H_CPU0_SA_DQS_DP<1>")
	)
	(segment
		(start 397.586962 -225.325432)
		(end 395.383512 -227.528882)
		(width 0.16002)
		(layer "In13.Cu")
		(net "M_H_CPU0_SA_DQS_DP<1>")
	)
	(segment
		(start 409.031186 -210.247992)
		(end 397.586962 -221.692216)
		(width 0.16002)
		(layer "In13.Cu")
		(net "M_H_CPU0_SA_DQS_DP<1>")
	)
	(segment
		(start 384.343402 -231.849168)
		(end 384.33502 -231.853994)
		(width 0.09525)
		(layer "In13.Cu")
		(net "M_H_CPU0_SA_DQS_DP<1>")
	)
	(segment
		(start 389.614664 -231.853994)
		(end 389.606282 -231.849168)
		(width 0.09525)
		(layer "In13.Cu")
		(net "M_H_CPU0_SA_DQS_DP<1>")
	)
	(segment
		(start 418.601144 -210.209892)
		(end 418.070538 -209.679286)
		(width 0.16002)
		(layer "In13.Cu")
		(net "M_H_CPU0_SA_DQS_DP<1>")
	)
	(segment
		(start 395.010386 -228.355144)
		(end 393.24788 -230.11765)
		(width 0.09525)
		(layer "In13.Cu")
		(net "M_H_CPU0_SA_DQS_DP<1>")
	)
	(segment
		(start 384.914648 -231.853994)
		(end 384.906266 -231.849168)
		(width 0.09525)
		(layer "In13.Cu")
		(net "M_H_CPU0_SA_DQS_DP<1>")
	)
	(segment
		(start 413.344614 -210.553046)
		(end 413.03956 -210.247992)
		(width 0.16002)
		(layer "In13.Cu")
		(net "M_H_CPU0_SA_DQS_DP<1>")
	)
	(segment
		(start 391.863326 -231.849168)
		(end 391.854944 -231.853994)
		(width 0.09525)
		(layer "In13.Cu")
		(net "M_H_CPU0_SA_DQS_DP<1>")
	)
	(segment
		(start 395.366748 -227.629466)
		(end 395.010386 -227.985828)
		(width 0.09525)
		(layer "In13.Cu")
		(net "M_H_CPU0_SA_DQS_DP<1>")
	)
	(segment
		(start 418.070538 -209.679286)
		(end 414.821878 -209.679286)
		(width 0.16002)
		(layer "In13.Cu")
		(net "M_H_CPU0_SA_DQS_DP<1>")
	)
	(segment
		(start 421.656002 -210.355434)
		(end 421.44569 -210.565746)
		(width 0.16002)
		(layer "In13.Cu")
		(net "M_H_CPU0_SA_DQS_DP<1>")
	)
	(segment
		(start 413.948118 -210.553046)
		(end 413.344614 -210.553046)
		(width 0.16002)
		(layer "In13.Cu")
		(net "M_H_CPU0_SA_DQS_DP<1>")
	)
	(segment
		(start 384.024378 -231.876346)
		(end 384.00101 -231.789478)
		(width 0.09525)
		(layer "In13.Cu")
		(net "M_H_CPU0_SA_DQS_DP<1>")
	)
	(segment
		(start 397.586962 -221.692216)
		(end 397.586962 -225.325432)
		(width 0.16002)
		(layer "In13.Cu")
		(net "M_H_CPU0_SA_DQS_DP<1>")
	)
	(segment
		(start 423.74185 -210.355434)
		(end 421.656002 -210.355434)
		(width 0.16002)
		(layer "In13.Cu")
		(net "M_H_CPU0_SA_DQS_DP<1>")
	)
	(segment
		(start 395.366748 -227.545646)
		(end 395.366748 -227.629466)
		(width 0.09525)
		(layer "In13.Cu")
		(net "M_H_CPU0_SA_DQS_DP<1>")
	)
	(segment
		(start 395.383512 -227.528882)
		(end 395.366748 -227.545646)
		(width 0.09525)
		(layer "In13.Cu")
		(net "M_H_CPU0_SA_DQS_DP<1>")
	)
	(segment
		(start 388.103364 -231.849168)
		(end 388.094982 -231.853994)
		(width 0.09525)
		(layer "In13.Cu")
		(net "M_H_CPU0_SA_DQS_DP<1>")
	)
	(segment
		(start 424.012106 -210.085178)
		(end 423.74185 -210.355434)
		(width 0.16002)
		(layer "In13.Cu")
		(net "M_H_CPU0_SA_DQS_DP<1>")
	)
	(segment
		(start 420.864538 -210.565746)
		(end 420.508684 -210.209892)
		(width 0.16002)
		(layer "In13.Cu")
		(net "M_H_CPU0_SA_DQS_DP<1>")
	)
	(arc
		(start 385.283456 -231.849168)
		(mid 385.099681 -231.89994)
		(end 384.914648 -231.853994)
		(width 0.09525)
		(layer "In13.Cu")
		(net "M_H_CPU0_SA_DQS_DP<1>")
	)
	(arc
		(start 389.606282 -231.849168)
		(mid 389.32485 -231.773413)
		(end 389.043418 -231.849168)
		(width 0.09525)
		(layer "In13.Cu")
		(net "M_H_CPU0_SA_DQS_DP<1>")
	)
	(arc
		(start 389.035036 -231.853994)
		(mid 388.850004 -231.899908)
		(end 388.666228 -231.849168)
		(width 0.09525)
		(layer "In13.Cu")
		(net "M_H_CPU0_SA_DQS_DP<1>")
	)
	(arc
		(start 390.923272 -231.849168)
		(mid 390.734804 -231.899845)
		(end 390.546336 -231.849168)
		(width 0.09525)
		(layer "In13.Cu")
		(net "M_H_CPU0_SA_DQS_DP<1>")
	)
	(arc
		(start 391.854944 -231.853994)
		(mid 391.669912 -231.899908)
		(end 391.486136 -231.849168)
		(width 0.09525)
		(layer "In13.Cu")
		(net "M_H_CPU0_SA_DQS_DP<1>")
	)
	(arc
		(start 384.33502 -231.853994)
		(mid 384.182125 -231.898822)
		(end 384.024378 -231.876346)
		(width 0.09525)
		(layer "In13.Cu")
		(net "M_H_CPU0_SA_DQS_DP<1>")
	)
	(arc
		(start 384.906266 -231.849168)
		(mid 384.624834 -231.773413)
		(end 384.343402 -231.849168)
		(width 0.09525)
		(layer "In13.Cu")
		(net "M_H_CPU0_SA_DQS_DP<1>")
	)
	(arc
		(start 390.546336 -231.849168)
		(mid 390.264904 -231.773413)
		(end 389.983472 -231.849168)
		(width 0.09525)
		(layer "In13.Cu")
		(net "M_H_CPU0_SA_DQS_DP<1>")
	)
	(arc
		(start 386.22351 -231.849168)
		(mid 386.039735 -231.89994)
		(end 385.854702 -231.853994)
		(width 0.09525)
		(layer "In13.Cu")
		(net "M_H_CPU0_SA_DQS_DP<1>")
	)
	(arc
		(start 387.726174 -231.849168)
		(mid 387.444742 -231.773413)
		(end 387.16331 -231.849168)
		(width 0.09525)
		(layer "In13.Cu")
		(net "M_H_CPU0_SA_DQS_DP<1>")
	)
	(arc
		(start 385.84632 -231.849168)
		(mid 385.564888 -231.773413)
		(end 385.283456 -231.849168)
		(width 0.09525)
		(layer "In13.Cu")
		(net "M_H_CPU0_SA_DQS_DP<1>")
	)
	(arc
		(start 391.940796 -231.789986)
		(mid 391.903978 -231.822085)
		(end 391.863326 -231.849168)
		(width 0.09525)
		(layer "In13.Cu")
		(net "M_H_CPU0_SA_DQS_DP<1>")
	)
	(arc
		(start 387.16331 -231.849168)
		(mid 386.974842 -231.899845)
		(end 386.786374 -231.849168)
		(width 0.09525)
		(layer "In13.Cu")
		(net "M_H_CPU0_SA_DQS_DP<1>")
	)
	(arc
		(start 388.666228 -231.849168)
		(mid 388.384796 -231.773413)
		(end 388.103364 -231.849168)
		(width 0.09525)
		(layer "In13.Cu")
		(net "M_H_CPU0_SA_DQS_DP<1>")
	)
	(arc
		(start 388.094982 -231.853994)
		(mid 387.90995 -231.899908)
		(end 387.726174 -231.849168)
		(width 0.09525)
		(layer "In13.Cu")
		(net "M_H_CPU0_SA_DQS_DP<1>")
	)
	(arc
		(start 389.983472 -231.849168)
		(mid 389.799697 -231.89994)
		(end 389.614664 -231.853994)
		(width 0.09525)
		(layer "In13.Cu")
		(net "M_H_CPU0_SA_DQS_DP<1>")
	)
	(arc
		(start 391.486136 -231.849168)
		(mid 391.204704 -231.773413)
		(end 390.923272 -231.849168)
		(width 0.09525)
		(layer "In13.Cu")
		(net "M_H_CPU0_SA_DQS_DP<1>")
	)
	(arc
		(start 386.786374 -231.849168)
		(mid 386.504942 -231.773413)
		(end 386.22351 -231.849168)
		(width 0.09525)
		(layer "In13.Cu")
		(net "M_H_CPU0_SA_DQS_DP<1>")
	)
	(segment
		(start 383.688082 -226.930204)
		(end 384.154934 -226.664266)
		(width 0.12954)
		(layer "F.Cu")
		(net "M_H_CPU0_SA_DQS_DP<0>")
	)
	(segment
		(start 414.821878 -200.329292)
		(end 413.948118 -201.203052)
		(width 0.16002)
		(layer "In13.Cu")
		(net "M_H_CPU0_SA_DQS_DP<0>")
	)
	(segment
		(start 390.485884 -224.540572)
		(end 390.415272 -224.581466)
		(width 0.09525)
		(layer "In13.Cu")
		(net "M_H_CPU0_SA_DQS_DP<0>")
	)
	(segment
		(start 407.60015 -201.589132)
		(end 398.636998 -210.552284)
		(width 0.16002)
		(layer "In13.Cu")
		(net "M_H_CPU0_SA_DQS_DP<0>")
	)
	(segment
		(start 398.636998 -211.249768)
		(end 391.993882 -217.892884)
		(width 0.16002)
		(layer "In13.Cu")
		(net "M_H_CPU0_SA_DQS_DP<0>")
	)
	(segment
		(start 389.07593 -226.97059)
		(end 389.035036 -226.994212)
		(width 0.09525)
		(layer "In13.Cu")
		(net "M_H_CPU0_SA_DQS_DP<0>")
	)
	(segment
		(start 388.103364 -226.989386)
		(end 388.094982 -226.994212)
		(width 0.09525)
		(layer "In13.Cu")
		(net "M_H_CPU0_SA_DQS_DP<0>")
	)
	(segment
		(start 384.00101 -226.929696)
		(end 384.154934 -226.664266)
		(width 0.09525)
		(layer "In13.Cu")
		(net "M_H_CPU0_SA_DQS_DP<0>")
	)
	(segment
		(start 408.929332 -201.429112)
		(end 408.769312 -201.589132)
		(width 0.16002)
		(layer "In13.Cu")
		(net "M_H_CPU0_SA_DQS_DP<0>")
	)
	(segment
		(start 418.601144 -200.859898)
		(end 418.070538 -200.329292)
		(width 0.16002)
		(layer "In13.Cu")
		(net "M_H_CPU0_SA_DQS_DP<0>")
	)
	(segment
		(start 420.864538 -201.215752)
		(end 420.508684 -200.859898)
		(width 0.16002)
		(layer "In13.Cu")
		(net "M_H_CPU0_SA_DQS_DP<0>")
	)
	(segment
		(start 391.424922 -222.921068)
		(end 391.355326 -222.961454)
		(width 0.09525)
		(layer "In13.Cu")
		(net "M_H_CPU0_SA_DQS_DP<0>")
	)
	(segment
		(start 385.854702 -226.994212)
		(end 385.84632 -226.989386)
		(width 0.09525)
		(layer "In13.Cu")
		(net "M_H_CPU0_SA_DQS_DP<0>")
	)
	(segment
		(start 424.012106 -200.735184)
		(end 423.739056 -201.008234)
		(width 0.16002)
		(layer "In13.Cu")
		(net "M_H_CPU0_SA_DQS_DP<0>")
	)
	(segment
		(start 389.54583 -226.160584)
		(end 389.478266 -226.199954)
		(width 0.09525)
		(layer "In13.Cu")
		(net "M_H_CPU0_SA_DQS_DP<0>")
	)
	(segment
		(start 384.343402 -226.989386)
		(end 384.33502 -226.994212)
		(width 0.09525)
		(layer "In13.Cu")
		(net "M_H_CPU0_SA_DQS_DP<0>")
	)
	(segment
		(start 421.44569 -201.215752)
		(end 420.864538 -201.215752)
		(width 0.16002)
		(layer "In13.Cu")
		(net "M_H_CPU0_SA_DQS_DP<0>")
	)
	(segment
		(start 409.864814 -200.921112)
		(end 409.26639 -200.921112)
		(width 0.16002)
		(layer "In13.Cu")
		(net "M_H_CPU0_SA_DQS_DP<0>")
	)
	(segment
		(start 413.042608 -201.203052)
		(end 412.656528 -201.589132)
		(width 0.16002)
		(layer "In13.Cu")
		(net "M_H_CPU0_SA_DQS_DP<0>")
	)
	(segment
		(start 409.26639 -200.921112)
		(end 408.929332 -201.25817)
		(width 0.16002)
		(layer "In13.Cu")
		(net "M_H_CPU0_SA_DQS_DP<0>")
	)
	(segment
		(start 391.993882 -221.17431)
		(end 391.993882 -221.197932)
		(width 0.09525)
		(layer "In13.Cu")
		(net "M_H_CPU0_SA_DQS_DP<0>")
	)
	(segment
		(start 391.993882 -221.197932)
		(end 392.052302 -221.256352)
		(width 0.09525)
		(layer "In13.Cu")
		(net "M_H_CPU0_SA_DQS_DP<0>")
	)
	(segment
		(start 410.201872 -201.429112)
		(end 410.201872 -201.25817)
		(width 0.16002)
		(layer "In13.Cu")
		(net "M_H_CPU0_SA_DQS_DP<0>")
	)
	(segment
		(start 384.914648 -226.994212)
		(end 384.906266 -226.989386)
		(width 0.09525)
		(layer "In13.Cu")
		(net "M_H_CPU0_SA_DQS_DP<0>")
	)
	(segment
		(start 408.929332 -201.25817)
		(end 408.929332 -201.429112)
		(width 0.16002)
		(layer "In13.Cu")
		(net "M_H_CPU0_SA_DQS_DP<0>")
	)
	(segment
		(start 398.636998 -210.552284)
		(end 398.636998 -211.249768)
		(width 0.16002)
		(layer "In13.Cu")
		(net "M_H_CPU0_SA_DQS_DP<0>")
	)
	(segment
		(start 390.014968 -225.351086)
		(end 389.945372 -225.391472)
		(width 0.09525)
		(layer "In13.Cu")
		(net "M_H_CPU0_SA_DQS_DP<0>")
	)
	(segment
		(start 392.052302 -221.256352)
		(end 392.052302 -221.80423)
		(width 0.09525)
		(layer "In13.Cu")
		(net "M_H_CPU0_SA_DQS_DP<0>")
	)
	(segment
		(start 413.948118 -201.203052)
		(end 413.042608 -201.203052)
		(width 0.16002)
		(layer "In13.Cu")
		(net "M_H_CPU0_SA_DQS_DP<0>")
	)
	(segment
		(start 423.739056 -201.008234)
		(end 421.653208 -201.008234)
		(width 0.16002)
		(layer "In13.Cu")
		(net "M_H_CPU0_SA_DQS_DP<0>")
	)
	(segment
		(start 421.653208 -201.008234)
		(end 421.44569 -201.215752)
		(width 0.16002)
		(layer "In13.Cu")
		(net "M_H_CPU0_SA_DQS_DP<0>")
	)
	(segment
		(start 408.769312 -201.589132)
		(end 407.60015 -201.589132)
		(width 0.16002)
		(layer "In13.Cu")
		(net "M_H_CPU0_SA_DQS_DP<0>")
	)
	(segment
		(start 410.201872 -201.25817)
		(end 409.864814 -200.921112)
		(width 0.16002)
		(layer "In13.Cu")
		(net "M_H_CPU0_SA_DQS_DP<0>")
	)
	(segment
		(start 420.508684 -200.859898)
		(end 418.601144 -200.859898)
		(width 0.16002)
		(layer "In13.Cu")
		(net "M_H_CPU0_SA_DQS_DP<0>")
	)
	(segment
		(start 384.024378 -227.016564)
		(end 384.00101 -226.929696)
		(width 0.09525)
		(layer "In13.Cu")
		(net "M_H_CPU0_SA_DQS_DP<0>")
	)
	(segment
		(start 412.656528 -201.589132)
		(end 410.361892 -201.589132)
		(width 0.16002)
		(layer "In13.Cu")
		(net "M_H_CPU0_SA_DQS_DP<0>")
	)
	(segment
		(start 390.955784 -223.730566)
		(end 390.88822 -223.769936)
		(width 0.09525)
		(layer "In13.Cu")
		(net "M_H_CPU0_SA_DQS_DP<0>")
	)
	(segment
		(start 391.993882 -217.892884)
		(end 391.993882 -221.17431)
		(width 0.16002)
		(layer "In13.Cu")
		(net "M_H_CPU0_SA_DQS_DP<0>")
	)
	(segment
		(start 410.361892 -201.589132)
		(end 410.201872 -201.429112)
		(width 0.16002)
		(layer "In13.Cu")
		(net "M_H_CPU0_SA_DQS_DP<0>")
	)
	(segment
		(start 391.896854 -222.109792)
		(end 391.826496 -222.150686)
		(width 0.09525)
		(layer "In13.Cu")
		(net "M_H_CPU0_SA_DQS_DP<0>")
	)
	(segment
		(start 418.070538 -200.329292)
		(end 414.821878 -200.329292)
		(width 0.16002)
		(layer "In13.Cu")
		(net "M_H_CPU0_SA_DQS_DP<0>")
	)
	(arc
		(start 386.786374 -226.989386)
		(mid 386.504942 -226.913631)
		(end 386.22351 -226.989386)
		(width 0.09525)
		(layer "In13.Cu")
		(net "M_H_CPU0_SA_DQS_DP<0>")
	)
	(arc
		(start 389.702548 -225.85426)
		(mid 389.661091 -226.0263)
		(end 389.54583 -226.160584)
		(width 0.09525)
		(layer "In13.Cu")
		(net "M_H_CPU0_SA_DQS_DP<0>")
	)
	(arc
		(start 384.33502 -226.994212)
		(mid 384.182125 -227.03904)
		(end 384.024378 -227.016564)
		(width 0.09525)
		(layer "In13.Cu")
		(net "M_H_CPU0_SA_DQS_DP<0>")
	)
	(arc
		(start 385.84632 -226.989386)
		(mid 385.564888 -226.913631)
		(end 385.283456 -226.989386)
		(width 0.09525)
		(layer "In13.Cu")
		(net "M_H_CPU0_SA_DQS_DP<0>")
	)
	(arc
		(start 389.478266 -226.199954)
		(mid 389.297875 -226.401653)
		(end 389.232648 -226.664266)
		(width 0.09525)
		(layer "In13.Cu")
		(net "M_H_CPU0_SA_DQS_DP<0>")
	)
	(arc
		(start 387.726174 -226.989386)
		(mid 387.444742 -226.913631)
		(end 387.16331 -226.989386)
		(width 0.09525)
		(layer "In13.Cu")
		(net "M_H_CPU0_SA_DQS_DP<0>")
	)
	(arc
		(start 391.826496 -222.150686)
		(mid 391.647124 -222.352281)
		(end 391.582402 -222.614236)
		(width 0.09525)
		(layer "In13.Cu")
		(net "M_H_CPU0_SA_DQS_DP<0>")
	)
	(arc
		(start 391.355326 -222.961454)
		(mid 391.176876 -223.162924)
		(end 391.112502 -223.424242)
		(width 0.09525)
		(layer "In13.Cu")
		(net "M_H_CPU0_SA_DQS_DP<0>")
	)
	(arc
		(start 388.666228 -226.989386)
		(mid 388.384796 -226.913631)
		(end 388.103364 -226.989386)
		(width 0.09525)
		(layer "In13.Cu")
		(net "M_H_CPU0_SA_DQS_DP<0>")
	)
	(arc
		(start 389.232648 -226.664266)
		(mid 389.191191 -226.836306)
		(end 389.07593 -226.97059)
		(width 0.09525)
		(layer "In13.Cu")
		(net "M_H_CPU0_SA_DQS_DP<0>")
	)
	(arc
		(start 385.283456 -226.989386)
		(mid 385.099681 -227.040158)
		(end 384.914648 -226.994212)
		(width 0.09525)
		(layer "In13.Cu")
		(net "M_H_CPU0_SA_DQS_DP<0>")
	)
	(arc
		(start 391.112502 -223.424242)
		(mid 391.071045 -223.596282)
		(end 390.955784 -223.730566)
		(width 0.09525)
		(layer "In13.Cu")
		(net "M_H_CPU0_SA_DQS_DP<0>")
	)
	(arc
		(start 392.052302 -221.80423)
		(mid 392.0112 -221.975636)
		(end 391.896854 -222.109792)
		(width 0.09525)
		(layer "In13.Cu")
		(net "M_H_CPU0_SA_DQS_DP<0>")
	)
	(arc
		(start 389.035036 -226.994212)
		(mid 388.850004 -227.040126)
		(end 388.666228 -226.989386)
		(width 0.09525)
		(layer "In13.Cu")
		(net "M_H_CPU0_SA_DQS_DP<0>")
	)
	(arc
		(start 391.582402 -222.614236)
		(mid 391.540737 -222.786683)
		(end 391.424922 -222.921068)
		(width 0.09525)
		(layer "In13.Cu")
		(net "M_H_CPU0_SA_DQS_DP<0>")
	)
	(arc
		(start 390.172448 -225.044254)
		(mid 390.130783 -225.216701)
		(end 390.014968 -225.351086)
		(width 0.09525)
		(layer "In13.Cu")
		(net "M_H_CPU0_SA_DQS_DP<0>")
	)
	(arc
		(start 386.22351 -226.989386)
		(mid 386.039735 -227.040158)
		(end 385.854702 -226.994212)
		(width 0.09525)
		(layer "In13.Cu")
		(net "M_H_CPU0_SA_DQS_DP<0>")
	)
	(arc
		(start 389.945372 -225.391472)
		(mid 389.766922 -225.592942)
		(end 389.702548 -225.85426)
		(width 0.09525)
		(layer "In13.Cu")
		(net "M_H_CPU0_SA_DQS_DP<0>")
	)
	(arc
		(start 387.16331 -226.989386)
		(mid 386.974842 -227.040063)
		(end 386.786374 -226.989386)
		(width 0.09525)
		(layer "In13.Cu")
		(net "M_H_CPU0_SA_DQS_DP<0>")
	)
	(arc
		(start 384.906266 -226.989386)
		(mid 384.624834 -226.913631)
		(end 384.343402 -226.989386)
		(width 0.09525)
		(layer "In13.Cu")
		(net "M_H_CPU0_SA_DQS_DP<0>")
	)
	(arc
		(start 390.642602 -224.234248)
		(mid 390.601145 -224.406288)
		(end 390.485884 -224.540572)
		(width 0.09525)
		(layer "In13.Cu")
		(net "M_H_CPU0_SA_DQS_DP<0>")
	)
	(arc
		(start 390.88822 -223.769936)
		(mid 390.707829 -223.971635)
		(end 390.642602 -224.234248)
		(width 0.09525)
		(layer "In13.Cu")
		(net "M_H_CPU0_SA_DQS_DP<0>")
	)
	(arc
		(start 388.094982 -226.994212)
		(mid 387.90995 -227.040126)
		(end 387.726174 -226.989386)
		(width 0.09525)
		(layer "In13.Cu")
		(net "M_H_CPU0_SA_DQS_DP<0>")
	)
	(arc
		(start 390.415272 -224.581466)
		(mid 390.236822 -224.782936)
		(end 390.172448 -225.044254)
		(width 0.09525)
		(layer "In13.Cu")
		(net "M_H_CPU0_SA_DQS_DP<0>")
	)
	(segment
		(start 382.277874 -247.1801)
		(end 382.744726 -246.914162)
		(width 0.12954)
		(layer "F.Cu")
		(net "M_H_CPU0_SA_DQS_DN<9>")
	)
	(segment
		(start 415.596832 -239.094772)
		(end 414.743392 -239.094772)
		(width 0.16002)
		(layer "In13.Cu")
		(net "M_H_CPU0_SA_DQS_DN<9>")
	)
	(segment
		(start 386.69341 -247.239282)
		(end 386.685028 -247.244108)
		(width 0.09525)
		(layer "In13.Cu")
		(net "M_H_CPU0_SA_DQS_DN<9>")
	)
	(segment
		(start 418.352732 -239.895634)
		(end 416.397694 -239.895634)
		(width 0.16002)
		(layer "In13.Cu")
		(net "M_H_CPU0_SA_DQS_DN<9>")
	)
	(segment
		(start 394.80236 -247.42521)
		(end 394.050266 -247.42521)
		(width 0.09525)
		(layer "In13.Cu")
		(net "M_H_CPU0_SA_DQS_DN<9>")
	)
	(segment
		(start 410.658818 -241.247676)
		(end 410.234892 -241.671602)
		(width 0.16002)
		(layer "In13.Cu")
		(net "M_H_CPU0_SA_DQS_DN<9>")
	)
	(segment
		(start 405.994362 -246.802402)
		(end 395.859254 -246.802402)
		(width 0.16002)
		(layer "In13.Cu")
		(net "M_H_CPU0_SA_DQS_DN<9>")
	)
	(segment
		(start 388.20471 -247.244108)
		(end 388.196328 -247.239282)
		(width 0.09525)
		(layer "In13.Cu")
		(net "M_H_CPU0_SA_DQS_DN<9>")
	)
	(segment
		(start 407.913078 -243.993416)
		(end 407.489152 -244.417342)
		(width 0.16002)
		(layer "In13.Cu")
		(net "M_H_CPU0_SA_DQS_DN<9>")
	)
	(segment
		(start 411.455108 -241.341656)
		(end 411.229048 -241.341656)
		(width 0.16002)
		(layer "In13.Cu")
		(net "M_H_CPU0_SA_DQS_DN<9>")
	)
	(segment
		(start 407.110438 -245.460266)
		(end 407.016458 -245.366286)
		(width 0.16002)
		(layer "In13.Cu")
		(net "M_H_CPU0_SA_DQS_DN<9>")
	)
	(segment
		(start 395.77645 -246.861584)
		(end 395.365986 -246.861584)
		(width 0.09525)
		(layer "In13.Cu")
		(net "M_H_CPU0_SA_DQS_DN<9>")
	)
	(segment
		(start 412.938976 -239.857788)
		(end 411.455108 -241.341656)
		(width 0.16002)
		(layer "In13.Cu")
		(net "M_H_CPU0_SA_DQS_DN<9>")
	)
	(segment
		(start 408.862022 -243.044472)
		(end 408.862022 -243.520976)
		(width 0.16002)
		(layer "In13.Cu")
		(net "M_H_CPU0_SA_DQS_DN<9>")
	)
	(segment
		(start 410.234892 -242.148106)
		(end 410.328618 -242.242086)
		(width 0.16002)
		(layer "In13.Cu")
		(net "M_H_CPU0_SA_DQS_DN<9>")
	)
	(segment
		(start 408.389328 -243.993416)
		(end 407.913078 -243.993416)
		(width 0.16002)
		(layer "In13.Cu")
		(net "M_H_CPU0_SA_DQS_DN<9>")
	)
	(segment
		(start 382.590802 -247.179592)
		(end 382.744726 -246.914162)
		(width 0.09525)
		(layer "In13.Cu")
		(net "M_H_CPU0_SA_DQS_DN<9>")
	)
	(segment
		(start 409.285948 -242.620546)
		(end 408.862022 -243.044472)
		(width 0.16002)
		(layer "In13.Cu")
		(net "M_H_CPU0_SA_DQS_DN<9>")
	)
	(segment
		(start 408.862022 -243.520976)
		(end 408.955748 -243.614956)
		(width 0.16002)
		(layer "In13.Cu")
		(net "M_H_CPU0_SA_DQS_DN<9>")
	)
	(segment
		(start 390.453372 -247.239282)
		(end 390.44499 -247.244108)
		(width 0.09525)
		(layer "In13.Cu")
		(net "M_H_CPU0_SA_DQS_DN<9>")
	)
	(segment
		(start 410.328618 -242.242086)
		(end 410.328618 -242.468146)
		(width 0.16002)
		(layer "In13.Cu")
		(net "M_H_CPU0_SA_DQS_DN<9>")
	)
	(segment
		(start 392.911076 -247.247664)
		(end 392.896598 -247.239282)
		(width 0.09525)
		(layer "In13.Cu")
		(net "M_H_CPU0_SA_DQS_DN<9>")
	)
	(segment
		(start 419.613588 -239.283494)
		(end 418.964872 -239.283494)
		(width 0.16002)
		(layer "In13.Cu")
		(net "M_H_CPU0_SA_DQS_DN<9>")
	)
	(segment
		(start 409.762198 -242.620546)
		(end 409.285948 -242.620546)
		(width 0.16002)
		(layer "In13.Cu")
		(net "M_H_CPU0_SA_DQS_DN<9>")
	)
	(segment
		(start 391.024618 -247.244108)
		(end 391.016236 -247.239282)
		(width 0.09525)
		(layer "In13.Cu")
		(net "M_H_CPU0_SA_DQS_DN<9>")
	)
	(segment
		(start 408.483308 -244.087396)
		(end 408.389328 -243.993416)
		(width 0.16002)
		(layer "In13.Cu")
		(net "M_H_CPU0_SA_DQS_DN<9>")
	)
	(segment
		(start 411.229048 -241.341656)
		(end 411.135068 -241.247676)
		(width 0.16002)
		(layer "In13.Cu")
		(net "M_H_CPU0_SA_DQS_DN<9>")
	)
	(segment
		(start 408.955748 -243.841016)
		(end 408.709368 -244.087396)
		(width 0.16002)
		(layer "In13.Cu")
		(net "M_H_CPU0_SA_DQS_DN<9>")
	)
	(segment
		(start 407.582878 -244.987826)
		(end 407.582878 -245.213886)
		(width 0.16002)
		(layer "In13.Cu")
		(net "M_H_CPU0_SA_DQS_DN<9>")
	)
	(segment
		(start 392.334242 -247.239282)
		(end 392.322304 -247.24614)
		(width 0.09525)
		(layer "In13.Cu")
		(net "M_H_CPU0_SA_DQS_DN<9>")
	)
	(segment
		(start 406.540208 -245.366286)
		(end 406.116282 -245.790212)
		(width 0.16002)
		(layer "In13.Cu")
		(net "M_H_CPU0_SA_DQS_DN<9>")
	)
	(segment
		(start 392.896598 -247.239282)
		(end 392.881866 -247.230646)
		(width 0.09525)
		(layer "In13.Cu")
		(net "M_H_CPU0_SA_DQS_DN<9>")
	)
	(segment
		(start 408.955748 -243.614956)
		(end 408.955748 -243.841016)
		(width 0.16002)
		(layer "In13.Cu")
		(net "M_H_CPU0_SA_DQS_DN<9>")
	)
	(segment
		(start 418.964872 -239.283494)
		(end 418.352732 -239.895634)
		(width 0.16002)
		(layer "In13.Cu")
		(net "M_H_CPU0_SA_DQS_DN<9>")
	)
	(segment
		(start 382.61417 -247.26646)
		(end 382.590802 -247.179592)
		(width 0.09525)
		(layer "In13.Cu")
		(net "M_H_CPU0_SA_DQS_DN<9>")
	)
	(segment
		(start 413.980376 -239.857788)
		(end 412.938976 -239.857788)
		(width 0.16002)
		(layer "In13.Cu")
		(net "M_H_CPU0_SA_DQS_DN<9>")
	)
	(segment
		(start 385.753356 -247.239282)
		(end 385.744974 -247.244108)
		(width 0.09525)
		(layer "In13.Cu")
		(net "M_H_CPU0_SA_DQS_DN<9>")
	)
	(segment
		(start 410.328618 -242.468146)
		(end 410.082238 -242.714526)
		(width 0.16002)
		(layer "In13.Cu")
		(net "M_H_CPU0_SA_DQS_DN<9>")
	)
	(segment
		(start 414.743392 -239.094772)
		(end 413.980376 -239.857788)
		(width 0.16002)
		(layer "In13.Cu")
		(net "M_H_CPU0_SA_DQS_DN<9>")
	)
	(segment
		(start 391.408158 -247.230646)
		(end 391.393426 -247.239282)
		(width 0.09525)
		(layer "In13.Cu")
		(net "M_H_CPU0_SA_DQS_DN<9>")
	)
	(segment
		(start 395.365986 -246.861584)
		(end 394.80236 -247.42521)
		(width 0.09525)
		(layer "In13.Cu")
		(net "M_H_CPU0_SA_DQS_DN<9>")
	)
	(segment
		(start 395.835632 -246.802402)
		(end 395.77645 -246.861584)
		(width 0.09525)
		(layer "In13.Cu")
		(net "M_H_CPU0_SA_DQS_DN<9>")
	)
	(segment
		(start 407.016458 -245.366286)
		(end 406.540208 -245.366286)
		(width 0.16002)
		(layer "In13.Cu")
		(net "M_H_CPU0_SA_DQS_DN<9>")
	)
	(segment
		(start 419.912038 -238.985044)
		(end 419.613588 -239.283494)
		(width 0.16002)
		(layer "In13.Cu")
		(net "M_H_CPU0_SA_DQS_DN<9>")
	)
	(segment
		(start 407.489152 -244.417342)
		(end 407.489152 -244.893846)
		(width 0.16002)
		(layer "In13.Cu")
		(net "M_H_CPU0_SA_DQS_DN<9>")
	)
	(segment
		(start 406.210008 -246.360696)
		(end 406.210008 -246.586756)
		(width 0.16002)
		(layer "In13.Cu")
		(net "M_H_CPU0_SA_DQS_DN<9>")
	)
	(segment
		(start 411.135068 -241.247676)
		(end 410.658818 -241.247676)
		(width 0.16002)
		(layer "In13.Cu")
		(net "M_H_CPU0_SA_DQS_DN<9>")
	)
	(segment
		(start 410.234892 -241.671602)
		(end 410.234892 -242.148106)
		(width 0.16002)
		(layer "In13.Cu")
		(net "M_H_CPU0_SA_DQS_DN<9>")
	)
	(segment
		(start 394.050266 -247.42521)
		(end 393.952476 -247.32742)
		(width 0.09525)
		(layer "In13.Cu")
		(net "M_H_CPU0_SA_DQS_DN<9>")
	)
	(segment
		(start 383.504694 -247.244108)
		(end 383.496312 -247.239282)
		(width 0.09525)
		(layer "In13.Cu")
		(net "M_H_CPU0_SA_DQS_DN<9>")
	)
	(segment
		(start 406.116282 -246.266716)
		(end 406.210008 -246.360696)
		(width 0.16002)
		(layer "In13.Cu")
		(net "M_H_CPU0_SA_DQS_DN<9>")
	)
	(segment
		(start 407.489152 -244.893846)
		(end 407.582878 -244.987826)
		(width 0.16002)
		(layer "In13.Cu")
		(net "M_H_CPU0_SA_DQS_DN<9>")
	)
	(segment
		(start 409.856178 -242.714526)
		(end 409.762198 -242.620546)
		(width 0.16002)
		(layer "In13.Cu")
		(net "M_H_CPU0_SA_DQS_DN<9>")
	)
	(segment
		(start 406.210008 -246.586756)
		(end 405.994362 -246.802402)
		(width 0.16002)
		(layer "In13.Cu")
		(net "M_H_CPU0_SA_DQS_DN<9>")
	)
	(segment
		(start 410.082238 -242.714526)
		(end 409.856178 -242.714526)
		(width 0.16002)
		(layer "In13.Cu")
		(net "M_H_CPU0_SA_DQS_DN<9>")
	)
	(segment
		(start 407.336498 -245.460266)
		(end 407.110438 -245.460266)
		(width 0.16002)
		(layer "In13.Cu")
		(net "M_H_CPU0_SA_DQS_DN<9>")
	)
	(segment
		(start 416.397694 -239.895634)
		(end 415.596832 -239.094772)
		(width 0.16002)
		(layer "In13.Cu")
		(net "M_H_CPU0_SA_DQS_DN<9>")
	)
	(segment
		(start 408.709368 -244.087396)
		(end 408.483308 -244.087396)
		(width 0.16002)
		(layer "In13.Cu")
		(net "M_H_CPU0_SA_DQS_DN<9>")
	)
	(segment
		(start 387.264656 -247.244108)
		(end 387.256274 -247.239282)
		(width 0.09525)
		(layer "In13.Cu")
		(net "M_H_CPU0_SA_DQS_DN<9>")
	)
	(segment
		(start 407.582878 -245.213886)
		(end 407.336498 -245.460266)
		(width 0.16002)
		(layer "In13.Cu")
		(net "M_H_CPU0_SA_DQS_DN<9>")
	)
	(segment
		(start 395.859254 -246.802402)
		(end 395.835632 -246.802402)
		(width 0.09525)
		(layer "In13.Cu")
		(net "M_H_CPU0_SA_DQS_DN<9>")
	)
	(segment
		(start 406.116282 -245.790212)
		(end 406.116282 -246.266716)
		(width 0.16002)
		(layer "In13.Cu")
		(net "M_H_CPU0_SA_DQS_DN<9>")
	)
	(arc
		(start 393.824714 -247.231916)
		(mid 393.548277 -247.163267)
		(end 393.273788 -247.239282)
		(width 0.09525)
		(layer "In13.Cu")
		(net "M_H_CPU0_SA_DQS_DN<9>")
	)
	(arc
		(start 391.956798 -247.239282)
		(mid 391.683616 -247.16334)
		(end 391.408158 -247.230646)
		(width 0.09525)
		(layer "In13.Cu")
		(net "M_H_CPU0_SA_DQS_DN<9>")
	)
	(arc
		(start 390.076182 -247.239282)
		(mid 389.79475 -247.163527)
		(end 389.513318 -247.239282)
		(width 0.09525)
		(layer "In13.Cu")
		(net "M_H_CPU0_SA_DQS_DN<9>")
	)
	(arc
		(start 387.256274 -247.239282)
		(mid 386.974842 -247.163527)
		(end 386.69341 -247.239282)
		(width 0.09525)
		(layer "In13.Cu")
		(net "M_H_CPU0_SA_DQS_DN<9>")
	)
	(arc
		(start 386.685028 -247.244108)
		(mid 386.499996 -247.290022)
		(end 386.31622 -247.239282)
		(width 0.09525)
		(layer "In13.Cu")
		(net "M_H_CPU0_SA_DQS_DN<9>")
	)
	(arc
		(start 392.322304 -247.24614)
		(mid 392.138669 -247.29009)
		(end 391.956798 -247.239282)
		(width 0.09525)
		(layer "In13.Cu")
		(net "M_H_CPU0_SA_DQS_DN<9>")
	)
	(arc
		(start 385.376166 -247.239282)
		(mid 385.094734 -247.163527)
		(end 384.813302 -247.239282)
		(width 0.09525)
		(layer "In13.Cu")
		(net "M_H_CPU0_SA_DQS_DN<9>")
	)
	(arc
		(start 384.436366 -247.239282)
		(mid 384.154934 -247.163527)
		(end 383.873502 -247.239282)
		(width 0.09525)
		(layer "In13.Cu")
		(net "M_H_CPU0_SA_DQS_DN<9>")
	)
	(arc
		(start 386.31622 -247.239282)
		(mid 386.034788 -247.163527)
		(end 385.753356 -247.239282)
		(width 0.09525)
		(layer "In13.Cu")
		(net "M_H_CPU0_SA_DQS_DN<9>")
	)
	(arc
		(start 385.744974 -247.244108)
		(mid 385.559942 -247.290022)
		(end 385.376166 -247.239282)
		(width 0.09525)
		(layer "In13.Cu")
		(net "M_H_CPU0_SA_DQS_DN<9>")
	)
	(arc
		(start 389.513318 -247.239282)
		(mid 389.32485 -247.289959)
		(end 389.136382 -247.239282)
		(width 0.09525)
		(layer "In13.Cu")
		(net "M_H_CPU0_SA_DQS_DN<9>")
	)
	(arc
		(start 383.496312 -247.239282)
		(mid 383.21488 -247.163527)
		(end 382.933448 -247.239282)
		(width 0.09525)
		(layer "In13.Cu")
		(net "M_H_CPU0_SA_DQS_DN<9>")
	)
	(arc
		(start 390.44499 -247.244108)
		(mid 390.259958 -247.290022)
		(end 390.076182 -247.239282)
		(width 0.09525)
		(layer "In13.Cu")
		(net "M_H_CPU0_SA_DQS_DN<9>")
	)
	(arc
		(start 391.016236 -247.239282)
		(mid 390.734804 -247.163527)
		(end 390.453372 -247.239282)
		(width 0.09525)
		(layer "In13.Cu")
		(net "M_H_CPU0_SA_DQS_DN<9>")
	)
	(arc
		(start 382.933448 -247.239282)
		(mid 382.77685 -247.288571)
		(end 382.61417 -247.26646)
		(width 0.09525)
		(layer "In13.Cu")
		(net "M_H_CPU0_SA_DQS_DN<9>")
	)
	(arc
		(start 388.573518 -247.239282)
		(mid 388.389743 -247.290054)
		(end 388.20471 -247.244108)
		(width 0.09525)
		(layer "In13.Cu")
		(net "M_H_CPU0_SA_DQS_DN<9>")
	)
	(arc
		(start 383.873502 -247.239282)
		(mid 383.689727 -247.290054)
		(end 383.504694 -247.244108)
		(width 0.09525)
		(layer "In13.Cu")
		(net "M_H_CPU0_SA_DQS_DN<9>")
	)
	(arc
		(start 392.881866 -247.230646)
		(mid 392.606915 -247.163503)
		(end 392.334242 -247.239282)
		(width 0.09525)
		(layer "In13.Cu")
		(net "M_H_CPU0_SA_DQS_DN<9>")
	)
	(arc
		(start 388.196328 -247.239282)
		(mid 387.914896 -247.163527)
		(end 387.633464 -247.239282)
		(width 0.09525)
		(layer "In13.Cu")
		(net "M_H_CPU0_SA_DQS_DN<9>")
	)
	(arc
		(start 387.633464 -247.239282)
		(mid 387.449689 -247.290054)
		(end 387.264656 -247.244108)
		(width 0.09525)
		(layer "In13.Cu")
		(net "M_H_CPU0_SA_DQS_DN<9>")
	)
	(arc
		(start 389.136382 -247.239282)
		(mid 388.85495 -247.163527)
		(end 388.573518 -247.239282)
		(width 0.09525)
		(layer "In13.Cu")
		(net "M_H_CPU0_SA_DQS_DN<9>")
	)
	(arc
		(start 384.813302 -247.239282)
		(mid 384.624834 -247.289959)
		(end 384.436366 -247.239282)
		(width 0.09525)
		(layer "In13.Cu")
		(net "M_H_CPU0_SA_DQS_DN<9>")
	)
	(arc
		(start 393.273788 -247.239282)
		(mid 393.093509 -247.290113)
		(end 392.911076 -247.247664)
		(width 0.09525)
		(layer "In13.Cu")
		(net "M_H_CPU0_SA_DQS_DN<9>")
	)
	(arc
		(start 393.952476 -247.32742)
		(mid 393.892001 -247.275113)
		(end 393.824714 -247.231916)
		(width 0.09525)
		(layer "In13.Cu")
		(net "M_H_CPU0_SA_DQS_DN<9>")
	)
	(arc
		(start 391.393426 -247.239282)
		(mid 391.209651 -247.290054)
		(end 391.024618 -247.244108)
		(width 0.09525)
		(layer "In13.Cu")
		(net "M_H_CPU0_SA_DQS_DN<9>")
	)
	(segment
		(start 382.277874 -242.320064)
		(end 382.744726 -242.054126)
		(width 0.12954)
		(layer "F.Cu")
		(net "M_H_CPU0_SA_DQS_DN<8>")
	)
	(segment
		(start 408.448002 -232.23728)
		(end 408.448002 -232.713784)
		(width 0.16002)
		(layer "In13.Cu")
		(net "M_H_CPU0_SA_DQS_DN<8>")
	)
	(segment
		(start 382.590802 -242.319556)
		(end 382.744726 -242.054126)
		(width 0.09525)
		(layer "In13.Cu")
		(net "M_H_CPU0_SA_DQS_DN<8>")
	)
	(segment
		(start 411.539436 -230.507794)
		(end 411.277054 -230.770176)
		(width 0.16002)
		(layer "In13.Cu")
		(net "M_H_CPU0_SA_DQS_DN<8>")
	)
	(segment
		(start 409.904184 -232.143046)
		(end 409.678124 -232.143046)
		(width 0.16002)
		(layer "In13.Cu")
		(net "M_H_CPU0_SA_DQS_DN<8>")
	)
	(segment
		(start 413.980376 -230.507794)
		(end 411.539436 -230.507794)
		(width 0.16002)
		(layer "In13.Cu")
		(net "M_H_CPU0_SA_DQS_DN<8>")
	)
	(segment
		(start 407.075132 -233.61015)
		(end 407.075132 -234.086654)
		(width 0.16002)
		(layer "In13.Cu")
		(net "M_H_CPU0_SA_DQS_DN<8>")
	)
	(segment
		(start 416.023806 -229.598474)
		(end 415.884106 -229.738174)
		(width 0.16002)
		(layer "In13.Cu")
		(net "M_H_CPU0_SA_DQS_DN<8>")
	)
	(segment
		(start 407.499058 -233.186224)
		(end 407.075132 -233.61015)
		(width 0.16002)
		(layer "In13.Cu")
		(net "M_H_CPU0_SA_DQS_DN<8>")
	)
	(segment
		(start 419.912038 -229.63505)
		(end 419.661594 -229.885494)
		(width 0.16002)
		(layer "In13.Cu")
		(net "M_H_CPU0_SA_DQS_DN<8>")
	)
	(segment
		(start 406.826212 -235.221018)
		(end 405.922988 -235.221018)
		(width 0.16002)
		(layer "In13.Cu")
		(net "M_H_CPU0_SA_DQS_DN<8>")
	)
	(segment
		(start 408.531314 -233.515916)
		(end 408.305254 -233.515916)
		(width 0.16002)
		(layer "In13.Cu")
		(net "M_H_CPU0_SA_DQS_DN<8>")
	)
	(segment
		(start 418.07892 -229.885494)
		(end 417.9316 -229.738174)
		(width 0.16002)
		(layer "In13.Cu")
		(net "M_H_CPU0_SA_DQS_DN<8>")
	)
	(segment
		(start 409.820872 -231.340914)
		(end 410.150564 -231.670606)
		(width 0.16002)
		(layer "In13.Cu")
		(net "M_H_CPU0_SA_DQS_DN<8>")
	)
	(segment
		(start 391.024618 -242.384072)
		(end 391.016236 -242.379246)
		(width 0.09525)
		(layer "In13.Cu")
		(net "M_H_CPU0_SA_DQS_DN<8>")
	)
	(segment
		(start 416.501326 -229.598474)
		(end 416.023806 -229.598474)
		(width 0.16002)
		(layer "In13.Cu")
		(net "M_H_CPU0_SA_DQS_DN<8>")
	)
	(segment
		(start 409.678124 -232.143046)
		(end 409.348432 -231.813354)
		(width 0.16002)
		(layer "In13.Cu")
		(net "M_H_CPU0_SA_DQS_DN<8>")
	)
	(segment
		(start 385.753356 -242.379246)
		(end 385.744974 -242.384072)
		(width 0.09525)
		(layer "In13.Cu")
		(net "M_H_CPU0_SA_DQS_DN<8>")
	)
	(segment
		(start 382.61417 -242.406424)
		(end 382.590802 -242.319556)
		(width 0.09525)
		(layer "In13.Cu")
		(net "M_H_CPU0_SA_DQS_DN<8>")
	)
	(segment
		(start 393.787884 -242.431062)
		(end 392.146028 -242.431062)
		(width 0.09525)
		(layer "In13.Cu")
		(net "M_H_CPU0_SA_DQS_DN<8>")
	)
	(segment
		(start 410.721302 -230.440484)
		(end 410.244798 -230.440484)
		(width 0.16002)
		(layer "In13.Cu")
		(net "M_H_CPU0_SA_DQS_DN<8>")
	)
	(segment
		(start 390.453372 -242.379246)
		(end 390.44499 -242.384072)
		(width 0.09525)
		(layer "In13.Cu")
		(net "M_H_CPU0_SA_DQS_DN<8>")
	)
	(segment
		(start 395.704822 -241.259614)
		(end 395.460982 -241.259614)
		(width 0.09525)
		(layer "In13.Cu")
		(net "M_H_CPU0_SA_DQS_DN<8>")
	)
	(segment
		(start 407.404824 -234.416346)
		(end 407.404824 -234.642406)
		(width 0.16002)
		(layer "In13.Cu")
		(net "M_H_CPU0_SA_DQS_DN<8>")
	)
	(segment
		(start 417.9316 -229.738174)
		(end 416.641026 -229.738174)
		(width 0.16002)
		(layer "In13.Cu")
		(net "M_H_CPU0_SA_DQS_DN<8>")
	)
	(segment
		(start 408.777694 -233.269536)
		(end 408.531314 -233.515916)
		(width 0.16002)
		(layer "In13.Cu")
		(net "M_H_CPU0_SA_DQS_DN<8>")
	)
	(segment
		(start 415.884106 -229.738174)
		(end 414.749996 -229.738174)
		(width 0.16002)
		(layer "In13.Cu")
		(net "M_H_CPU0_SA_DQS_DN<8>")
	)
	(segment
		(start 409.820872 -230.86441)
		(end 409.820872 -231.340914)
		(width 0.16002)
		(layer "In13.Cu")
		(net "M_H_CPU0_SA_DQS_DN<8>")
	)
	(segment
		(start 411.277054 -230.770176)
		(end 411.050994 -230.770176)
		(width 0.16002)
		(layer "In13.Cu")
		(net "M_H_CPU0_SA_DQS_DN<8>")
	)
	(segment
		(start 394.750544 -241.970052)
		(end 394.248894 -241.970052)
		(width 0.09525)
		(layer "In13.Cu")
		(net "M_H_CPU0_SA_DQS_DN<8>")
	)
	(segment
		(start 411.050994 -230.770176)
		(end 410.721302 -230.440484)
		(width 0.16002)
		(layer "In13.Cu")
		(net "M_H_CPU0_SA_DQS_DN<8>")
	)
	(segment
		(start 405.922988 -235.221018)
		(end 399.943574 -241.200432)
		(width 0.16002)
		(layer "In13.Cu")
		(net "M_H_CPU0_SA_DQS_DN<8>")
	)
	(segment
		(start 410.150564 -231.670606)
		(end 410.150564 -231.896666)
		(width 0.16002)
		(layer "In13.Cu")
		(net "M_H_CPU0_SA_DQS_DN<8>")
	)
	(segment
		(start 408.777694 -233.043476)
		(end 408.777694 -233.269536)
		(width 0.16002)
		(layer "In13.Cu")
		(net "M_H_CPU0_SA_DQS_DN<8>")
	)
	(segment
		(start 407.975562 -233.186224)
		(end 407.499058 -233.186224)
		(width 0.16002)
		(layer "In13.Cu")
		(net "M_H_CPU0_SA_DQS_DN<8>")
	)
	(segment
		(start 408.305254 -233.515916)
		(end 407.975562 -233.186224)
		(width 0.16002)
		(layer "In13.Cu")
		(net "M_H_CPU0_SA_DQS_DN<8>")
	)
	(segment
		(start 386.69341 -242.379246)
		(end 386.685028 -242.384072)
		(width 0.09525)
		(layer "In13.Cu")
		(net "M_H_CPU0_SA_DQS_DN<8>")
	)
	(segment
		(start 391.408158 -242.37061)
		(end 391.393426 -242.379246)
		(width 0.09525)
		(layer "In13.Cu")
		(net "M_H_CPU0_SA_DQS_DN<8>")
	)
	(segment
		(start 410.244798 -230.440484)
		(end 409.820872 -230.86441)
		(width 0.16002)
		(layer "In13.Cu")
		(net "M_H_CPU0_SA_DQS_DN<8>")
	)
	(segment
		(start 395.764004 -241.200432)
		(end 395.704822 -241.259614)
		(width 0.09525)
		(layer "In13.Cu")
		(net "M_H_CPU0_SA_DQS_DN<8>")
	)
	(segment
		(start 407.075132 -234.086654)
		(end 407.404824 -234.416346)
		(width 0.16002)
		(layer "In13.Cu")
		(net "M_H_CPU0_SA_DQS_DN<8>")
	)
	(segment
		(start 416.641026 -229.738174)
		(end 416.501326 -229.598474)
		(width 0.16002)
		(layer "In13.Cu")
		(net "M_H_CPU0_SA_DQS_DN<8>")
	)
	(segment
		(start 407.404824 -234.642406)
		(end 406.826212 -235.221018)
		(width 0.16002)
		(layer "In13.Cu")
		(net "M_H_CPU0_SA_DQS_DN<8>")
	)
	(segment
		(start 409.348432 -231.813354)
		(end 408.871928 -231.813354)
		(width 0.16002)
		(layer "In13.Cu")
		(net "M_H_CPU0_SA_DQS_DN<8>")
	)
	(segment
		(start 395.787626 -241.200432)
		(end 395.764004 -241.200432)
		(width 0.09525)
		(layer "In13.Cu")
		(net "M_H_CPU0_SA_DQS_DN<8>")
	)
	(segment
		(start 394.248894 -241.970052)
		(end 393.787884 -242.431062)
		(width 0.09525)
		(layer "In13.Cu")
		(net "M_H_CPU0_SA_DQS_DN<8>")
	)
	(segment
		(start 387.264656 -242.384072)
		(end 387.256274 -242.379246)
		(width 0.09525)
		(layer "In13.Cu")
		(net "M_H_CPU0_SA_DQS_DN<8>")
	)
	(segment
		(start 388.20471 -242.384072)
		(end 388.196328 -242.379246)
		(width 0.09525)
		(layer "In13.Cu")
		(net "M_H_CPU0_SA_DQS_DN<8>")
	)
	(segment
		(start 399.943574 -241.200432)
		(end 395.787626 -241.200432)
		(width 0.16002)
		(layer "In13.Cu")
		(net "M_H_CPU0_SA_DQS_DN<8>")
	)
	(segment
		(start 410.150564 -231.896666)
		(end 409.904184 -232.143046)
		(width 0.16002)
		(layer "In13.Cu")
		(net "M_H_CPU0_SA_DQS_DN<8>")
	)
	(segment
		(start 408.448002 -232.713784)
		(end 408.777694 -233.043476)
		(width 0.16002)
		(layer "In13.Cu")
		(net "M_H_CPU0_SA_DQS_DN<8>")
	)
	(segment
		(start 419.661594 -229.885494)
		(end 418.07892 -229.885494)
		(width 0.16002)
		(layer "In13.Cu")
		(net "M_H_CPU0_SA_DQS_DN<8>")
	)
	(segment
		(start 383.504694 -242.384072)
		(end 383.496312 -242.379246)
		(width 0.09525)
		(layer "In13.Cu")
		(net "M_H_CPU0_SA_DQS_DN<8>")
	)
	(segment
		(start 395.460982 -241.259614)
		(end 394.750544 -241.970052)
		(width 0.09525)
		(layer "In13.Cu")
		(net "M_H_CPU0_SA_DQS_DN<8>")
	)
	(segment
		(start 414.749996 -229.738174)
		(end 413.980376 -230.507794)
		(width 0.16002)
		(layer "In13.Cu")
		(net "M_H_CPU0_SA_DQS_DN<8>")
	)
	(segment
		(start 408.871928 -231.813354)
		(end 408.448002 -232.23728)
		(width 0.16002)
		(layer "In13.Cu")
		(net "M_H_CPU0_SA_DQS_DN<8>")
	)
	(arc
		(start 391.016236 -242.379246)
		(mid 390.734804 -242.303491)
		(end 390.453372 -242.379246)
		(width 0.09525)
		(layer "In13.Cu")
		(net "M_H_CPU0_SA_DQS_DN<8>")
	)
	(arc
		(start 390.44499 -242.384072)
		(mid 390.259958 -242.429986)
		(end 390.076182 -242.379246)
		(width 0.09525)
		(layer "In13.Cu")
		(net "M_H_CPU0_SA_DQS_DN<8>")
	)
	(arc
		(start 386.31622 -242.379246)
		(mid 386.034788 -242.303491)
		(end 385.753356 -242.379246)
		(width 0.09525)
		(layer "In13.Cu")
		(net "M_H_CPU0_SA_DQS_DN<8>")
	)
	(arc
		(start 385.376166 -242.379246)
		(mid 385.094734 -242.303491)
		(end 384.813302 -242.379246)
		(width 0.09525)
		(layer "In13.Cu")
		(net "M_H_CPU0_SA_DQS_DN<8>")
	)
	(arc
		(start 388.573518 -242.379246)
		(mid 388.389743 -242.430018)
		(end 388.20471 -242.384072)
		(width 0.09525)
		(layer "In13.Cu")
		(net "M_H_CPU0_SA_DQS_DN<8>")
	)
	(arc
		(start 385.744974 -242.384072)
		(mid 385.559942 -242.429986)
		(end 385.376166 -242.379246)
		(width 0.09525)
		(layer "In13.Cu")
		(net "M_H_CPU0_SA_DQS_DN<8>")
	)
	(arc
		(start 390.076182 -242.379246)
		(mid 389.79475 -242.303491)
		(end 389.513318 -242.379246)
		(width 0.09525)
		(layer "In13.Cu")
		(net "M_H_CPU0_SA_DQS_DN<8>")
	)
	(arc
		(start 382.933448 -242.379246)
		(mid 382.77685 -242.428535)
		(end 382.61417 -242.406424)
		(width 0.09525)
		(layer "In13.Cu")
		(net "M_H_CPU0_SA_DQS_DN<8>")
	)
	(arc
		(start 387.633464 -242.379246)
		(mid 387.449689 -242.430018)
		(end 387.264656 -242.384072)
		(width 0.09525)
		(layer "In13.Cu")
		(net "M_H_CPU0_SA_DQS_DN<8>")
	)
	(arc
		(start 388.196328 -242.379246)
		(mid 387.914896 -242.303491)
		(end 387.633464 -242.379246)
		(width 0.09525)
		(layer "In13.Cu")
		(net "M_H_CPU0_SA_DQS_DN<8>")
	)
	(arc
		(start 383.496312 -242.379246)
		(mid 383.21488 -242.303491)
		(end 382.933448 -242.379246)
		(width 0.09525)
		(layer "In13.Cu")
		(net "M_H_CPU0_SA_DQS_DN<8>")
	)
	(arc
		(start 387.256274 -242.379246)
		(mid 386.974842 -242.303491)
		(end 386.69341 -242.379246)
		(width 0.09525)
		(layer "In13.Cu")
		(net "M_H_CPU0_SA_DQS_DN<8>")
	)
	(arc
		(start 392.146028 -242.431062)
		(mid 392.047994 -242.417661)
		(end 391.956798 -242.379246)
		(width 0.09525)
		(layer "In13.Cu")
		(net "M_H_CPU0_SA_DQS_DN<8>")
	)
	(arc
		(start 384.813302 -242.379246)
		(mid 384.624834 -242.429923)
		(end 384.436366 -242.379246)
		(width 0.09525)
		(layer "In13.Cu")
		(net "M_H_CPU0_SA_DQS_DN<8>")
	)
	(arc
		(start 386.685028 -242.384072)
		(mid 386.499996 -242.429986)
		(end 386.31622 -242.379246)
		(width 0.09525)
		(layer "In13.Cu")
		(net "M_H_CPU0_SA_DQS_DN<8>")
	)
	(arc
		(start 391.393426 -242.379246)
		(mid 391.209651 -242.430018)
		(end 391.024618 -242.384072)
		(width 0.09525)
		(layer "In13.Cu")
		(net "M_H_CPU0_SA_DQS_DN<8>")
	)
	(arc
		(start 389.136382 -242.379246)
		(mid 388.85495 -242.303491)
		(end 388.573518 -242.379246)
		(width 0.09525)
		(layer "In13.Cu")
		(net "M_H_CPU0_SA_DQS_DN<8>")
	)
	(arc
		(start 383.873502 -242.379246)
		(mid 383.689727 -242.430018)
		(end 383.504694 -242.384072)
		(width 0.09525)
		(layer "In13.Cu")
		(net "M_H_CPU0_SA_DQS_DN<8>")
	)
	(arc
		(start 389.513318 -242.379246)
		(mid 389.32485 -242.429923)
		(end 389.136382 -242.379246)
		(width 0.09525)
		(layer "In13.Cu")
		(net "M_H_CPU0_SA_DQS_DN<8>")
	)
	(arc
		(start 384.436366 -242.379246)
		(mid 384.154934 -242.303491)
		(end 383.873502 -242.379246)
		(width 0.09525)
		(layer "In13.Cu")
		(net "M_H_CPU0_SA_DQS_DN<8>")
	)
	(arc
		(start 391.956798 -242.379246)
		(mid 391.683616 -242.303304)
		(end 391.408158 -242.37061)
		(width 0.09525)
		(layer "In13.Cu")
		(net "M_H_CPU0_SA_DQS_DN<8>")
	)
	(segment
		(start 382.277874 -237.460028)
		(end 382.744726 -237.19409)
		(width 0.12954)
		(layer "F.Cu")
		(net "M_H_CPU0_SA_DQS_DN<7>")
	)
	(segment
		(start 388.20471 -237.524036)
		(end 388.196328 -237.51921)
		(width 0.09525)
		(layer "In13.Cu")
		(net "M_H_CPU0_SA_DQS_DN<7>")
	)
	(segment
		(start 387.264656 -237.524036)
		(end 387.256274 -237.51921)
		(width 0.09525)
		(layer "In13.Cu")
		(net "M_H_CPU0_SA_DQS_DN<7>")
	)
	(segment
		(start 419.608 -220.589094)
		(end 419.271704 -220.589094)
		(width 0.16002)
		(layer "In13.Cu")
		(net "M_H_CPU0_SA_DQS_DN<7>")
	)
	(segment
		(start 411.134306 -221.54896)
		(end 408.74315 -221.54896)
		(width 0.16002)
		(layer "In13.Cu")
		(net "M_H_CPU0_SA_DQS_DN<7>")
	)
	(segment
		(start 416.322764 -219.89796)
		(end 415.240216 -219.89796)
		(width 0.16002)
		(layer "In13.Cu")
		(net "M_H_CPU0_SA_DQS_DN<7>")
	)
	(segment
		(start 411.294326 -221.38894)
		(end 411.134306 -221.54896)
		(width 0.16002)
		(layer "In13.Cu")
		(net "M_H_CPU0_SA_DQS_DN<7>")
	)
	(segment
		(start 391.956036 -237.51921)
		(end 391.945622 -237.513114)
		(width 0.09525)
		(layer "In13.Cu")
		(net "M_H_CPU0_SA_DQS_DN<7>")
	)
	(segment
		(start 415.240216 -219.89796)
		(end 413.980376 -221.1578)
		(width 0.16002)
		(layer "In13.Cu")
		(net "M_H_CPU0_SA_DQS_DN<7>")
	)
	(segment
		(start 391.024618 -237.524036)
		(end 391.016236 -237.51921)
		(width 0.09525)
		(layer "In13.Cu")
		(net "M_H_CPU0_SA_DQS_DN<7>")
	)
	(segment
		(start 406.94864 -223.34347)
		(end 403.992842 -226.299268)
		(width 0.16002)
		(layer "In13.Cu")
		(net "M_H_CPU0_SA_DQS_DN<7>")
	)
	(segment
		(start 403.992842 -226.299268)
		(end 403.992842 -228.653848)
		(width 0.16002)
		(layer "In13.Cu")
		(net "M_H_CPU0_SA_DQS_DN<7>")
	)
	(segment
		(start 397.18488 -235.46181)
		(end 395.859254 -235.46181)
		(width 0.16002)
		(layer "In13.Cu")
		(net "M_H_CPU0_SA_DQS_DN<7>")
	)
	(segment
		(start 382.590802 -237.45952)
		(end 382.744726 -237.19409)
		(width 0.09525)
		(layer "In13.Cu")
		(net "M_H_CPU0_SA_DQS_DN<7>")
	)
	(segment
		(start 417.12388 -220.699076)
		(end 416.322764 -219.89796)
		(width 0.16002)
		(layer "In13.Cu")
		(net "M_H_CPU0_SA_DQS_DN<7>")
	)
	(segment
		(start 393.273026 -237.51921)
		(end 393.267184 -237.522512)
		(width 0.09525)
		(layer "In13.Cu")
		(net "M_H_CPU0_SA_DQS_DN<7>")
	)
	(segment
		(start 395.859254 -235.46181)
		(end 395.835632 -235.46181)
		(width 0.09525)
		(layer "In13.Cu")
		(net "M_H_CPU0_SA_DQS_DN<7>")
	)
	(segment
		(start 383.504694 -237.524036)
		(end 383.496312 -237.51921)
		(width 0.09525)
		(layer "In13.Cu")
		(net "M_H_CPU0_SA_DQS_DN<7>")
	)
	(segment
		(start 395.381734 -235.520992)
		(end 394.808964 -236.093762)
		(width 0.09525)
		(layer "In13.Cu")
		(net "M_H_CPU0_SA_DQS_DN<7>")
	)
	(segment
		(start 412.72714 -221.54896)
		(end 412.56712 -221.38894)
		(width 0.16002)
		(layer "In13.Cu")
		(net "M_H_CPU0_SA_DQS_DN<7>")
	)
	(segment
		(start 390.446006 -237.523528)
		(end 390.44499 -237.524036)
		(width 0.09525)
		(layer "In13.Cu")
		(net "M_H_CPU0_SA_DQS_DN<7>")
	)
	(segment
		(start 419.912038 -220.285056)
		(end 419.608 -220.589094)
		(width 0.16002)
		(layer "In13.Cu")
		(net "M_H_CPU0_SA_DQS_DN<7>")
	)
	(segment
		(start 382.61417 -237.546388)
		(end 382.590802 -237.45952)
		(width 0.09525)
		(layer "In13.Cu")
		(net "M_H_CPU0_SA_DQS_DN<7>")
	)
	(segment
		(start 394.808964 -236.093762)
		(end 394.4493 -236.093762)
		(width 0.09525)
		(layer "In13.Cu")
		(net "M_H_CPU0_SA_DQS_DN<7>")
	)
	(segment
		(start 407.60777 -223.526096)
		(end 407.425144 -223.34347)
		(width 0.16002)
		(layer "In13.Cu")
		(net "M_H_CPU0_SA_DQS_DN<7>")
	)
	(segment
		(start 411.294326 -220.882464)
		(end 411.294326 -221.38894)
		(width 0.16002)
		(layer "In13.Cu")
		(net "M_H_CPU0_SA_DQS_DN<7>")
	)
	(segment
		(start 395.77645 -235.520992)
		(end 395.381734 -235.520992)
		(width 0.09525)
		(layer "In13.Cu")
		(net "M_H_CPU0_SA_DQS_DN<7>")
	)
	(segment
		(start 418.615622 -221.245176)
		(end 418.389308 -221.245176)
		(width 0.16002)
		(layer "In13.Cu")
		(net "M_H_CPU0_SA_DQS_DN<7>")
	)
	(segment
		(start 403.992842 -228.653848)
		(end 397.18488 -235.46181)
		(width 0.16002)
		(layer "In13.Cu")
		(net "M_H_CPU0_SA_DQS_DN<7>")
	)
	(segment
		(start 394.103606 -236.439456)
		(end 394.103606 -236.707172)
		(width 0.09525)
		(layer "In13.Cu")
		(net "M_H_CPU0_SA_DQS_DN<7>")
	)
	(segment
		(start 412.194248 -220.509592)
		(end 411.667198 -220.509592)
		(width 0.16002)
		(layer "In13.Cu")
		(net "M_H_CPU0_SA_DQS_DN<7>")
	)
	(segment
		(start 419.271704 -220.589094)
		(end 418.615622 -221.245176)
		(width 0.16002)
		(layer "In13.Cu")
		(net "M_H_CPU0_SA_DQS_DN<7>")
	)
	(segment
		(start 411.667198 -220.509592)
		(end 411.294326 -220.882464)
		(width 0.16002)
		(layer "In13.Cu")
		(net "M_H_CPU0_SA_DQS_DN<7>")
	)
	(segment
		(start 393.27328 -237.519464)
		(end 393.273026 -237.51921)
		(width 0.09525)
		(layer "In13.Cu")
		(net "M_H_CPU0_SA_DQS_DN<7>")
	)
	(segment
		(start 408.08021 -223.053656)
		(end 408.08021 -223.279716)
		(width 0.16002)
		(layer "In13.Cu")
		(net "M_H_CPU0_SA_DQS_DN<7>")
	)
	(segment
		(start 407.425144 -223.34347)
		(end 406.94864 -223.34347)
		(width 0.16002)
		(layer "In13.Cu")
		(net "M_H_CPU0_SA_DQS_DN<7>")
	)
	(segment
		(start 386.69341 -237.51921)
		(end 386.685028 -237.524036)
		(width 0.09525)
		(layer "In13.Cu")
		(net "M_H_CPU0_SA_DQS_DN<7>")
	)
	(segment
		(start 393.267184 -237.522512)
		(end 393.261088 -237.526068)
		(width 0.09525)
		(layer "In13.Cu")
		(net "M_H_CPU0_SA_DQS_DN<7>")
	)
	(segment
		(start 407.897584 -222.87103)
		(end 408.08021 -223.053656)
		(width 0.16002)
		(layer "In13.Cu")
		(net "M_H_CPU0_SA_DQS_DN<7>")
	)
	(segment
		(start 407.83383 -223.526096)
		(end 407.60777 -223.526096)
		(width 0.16002)
		(layer "In13.Cu")
		(net "M_H_CPU0_SA_DQS_DN<7>")
	)
	(segment
		(start 408.74315 -221.54896)
		(end 407.897584 -222.394526)
		(width 0.16002)
		(layer "In13.Cu")
		(net "M_H_CPU0_SA_DQS_DN<7>")
	)
	(segment
		(start 392.343386 -237.513114)
		(end 392.332972 -237.51921)
		(width 0.09525)
		(layer "In13.Cu")
		(net "M_H_CPU0_SA_DQS_DN<7>")
	)
	(segment
		(start 385.753356 -237.51921)
		(end 385.744974 -237.524036)
		(width 0.09525)
		(layer "In13.Cu")
		(net "M_H_CPU0_SA_DQS_DN<7>")
	)
	(segment
		(start 413.487108 -221.1578)
		(end 413.095948 -221.54896)
		(width 0.16002)
		(layer "In13.Cu")
		(net "M_H_CPU0_SA_DQS_DN<7>")
	)
	(segment
		(start 394.4493 -236.093762)
		(end 394.103606 -236.439456)
		(width 0.09525)
		(layer "In13.Cu")
		(net "M_H_CPU0_SA_DQS_DN<7>")
	)
	(segment
		(start 413.980376 -221.1578)
		(end 413.487108 -221.1578)
		(width 0.16002)
		(layer "In13.Cu")
		(net "M_H_CPU0_SA_DQS_DN<7>")
	)
	(segment
		(start 408.08021 -223.279716)
		(end 407.83383 -223.526096)
		(width 0.16002)
		(layer "In13.Cu")
		(net "M_H_CPU0_SA_DQS_DN<7>")
	)
	(segment
		(start 394.103606 -236.707172)
		(end 393.350496 -237.460028)
		(width 0.09525)
		(layer "In13.Cu")
		(net "M_H_CPU0_SA_DQS_DN<7>")
	)
	(segment
		(start 390.453372 -237.51921)
		(end 390.446006 -237.523528)
		(width 0.09525)
		(layer "In13.Cu")
		(net "M_H_CPU0_SA_DQS_DN<7>")
	)
	(segment
		(start 395.835632 -235.46181)
		(end 395.77645 -235.520992)
		(width 0.09525)
		(layer "In13.Cu")
		(net "M_H_CPU0_SA_DQS_DN<7>")
	)
	(segment
		(start 417.843208 -220.699076)
		(end 417.12388 -220.699076)
		(width 0.16002)
		(layer "In13.Cu")
		(net "M_H_CPU0_SA_DQS_DN<7>")
	)
	(segment
		(start 412.56712 -221.38894)
		(end 412.56712 -220.882464)
		(width 0.16002)
		(layer "In13.Cu")
		(net "M_H_CPU0_SA_DQS_DN<7>")
	)
	(segment
		(start 413.095948 -221.54896)
		(end 412.72714 -221.54896)
		(width 0.16002)
		(layer "In13.Cu")
		(net "M_H_CPU0_SA_DQS_DN<7>")
	)
	(segment
		(start 418.389308 -221.245176)
		(end 417.843208 -220.699076)
		(width 0.16002)
		(layer "In13.Cu")
		(net "M_H_CPU0_SA_DQS_DN<7>")
	)
	(segment
		(start 412.56712 -220.882464)
		(end 412.194248 -220.509592)
		(width 0.16002)
		(layer "In13.Cu")
		(net "M_H_CPU0_SA_DQS_DN<7>")
	)
	(segment
		(start 407.897584 -222.394526)
		(end 407.897584 -222.87103)
		(width 0.16002)
		(layer "In13.Cu")
		(net "M_H_CPU0_SA_DQS_DN<7>")
	)
	(arc
		(start 388.573518 -237.51921)
		(mid 388.389743 -237.569982)
		(end 388.20471 -237.524036)
		(width 0.09525)
		(layer "In13.Cu")
		(net "M_H_CPU0_SA_DQS_DN<7>")
	)
	(arc
		(start 387.256274 -237.51921)
		(mid 386.974842 -237.443455)
		(end 386.69341 -237.51921)
		(width 0.09525)
		(layer "In13.Cu")
		(net "M_H_CPU0_SA_DQS_DN<7>")
	)
	(arc
		(start 390.076182 -237.51921)
		(mid 389.79475 -237.443455)
		(end 389.513318 -237.51921)
		(width 0.09525)
		(layer "In13.Cu")
		(net "M_H_CPU0_SA_DQS_DN<7>")
	)
	(arc
		(start 392.89609 -237.51921)
		(mid 392.620547 -237.443361)
		(end 392.343386 -237.513114)
		(width 0.09525)
		(layer "In13.Cu")
		(net "M_H_CPU0_SA_DQS_DN<7>")
	)
	(arc
		(start 387.633464 -237.51921)
		(mid 387.449689 -237.569982)
		(end 387.264656 -237.524036)
		(width 0.09525)
		(layer "In13.Cu")
		(net "M_H_CPU0_SA_DQS_DN<7>")
	)
	(arc
		(start 389.513318 -237.51921)
		(mid 389.32485 -237.569887)
		(end 389.136382 -237.51921)
		(width 0.09525)
		(layer "In13.Cu")
		(net "M_H_CPU0_SA_DQS_DN<7>")
	)
	(arc
		(start 388.196328 -237.51921)
		(mid 387.914896 -237.443455)
		(end 387.633464 -237.51921)
		(width 0.09525)
		(layer "In13.Cu")
		(net "M_H_CPU0_SA_DQS_DN<7>")
	)
	(arc
		(start 386.685028 -237.524036)
		(mid 386.499996 -237.56995)
		(end 386.31622 -237.51921)
		(width 0.09525)
		(layer "In13.Cu")
		(net "M_H_CPU0_SA_DQS_DN<7>")
	)
	(arc
		(start 389.136382 -237.51921)
		(mid 388.85495 -237.443455)
		(end 388.573518 -237.51921)
		(width 0.09525)
		(layer "In13.Cu")
		(net "M_H_CPU0_SA_DQS_DN<7>")
	)
	(arc
		(start 393.261088 -237.526068)
		(mid 393.077707 -237.569899)
		(end 392.89609 -237.51921)
		(width 0.09525)
		(layer "In13.Cu")
		(net "M_H_CPU0_SA_DQS_DN<7>")
	)
	(arc
		(start 391.945622 -237.513114)
		(mid 391.668714 -237.443437)
		(end 391.393426 -237.51921)
		(width 0.09525)
		(layer "In13.Cu")
		(net "M_H_CPU0_SA_DQS_DN<7>")
	)
	(arc
		(start 391.016236 -237.51921)
		(mid 390.734804 -237.443455)
		(end 390.453372 -237.51921)
		(width 0.09525)
		(layer "In13.Cu")
		(net "M_H_CPU0_SA_DQS_DN<7>")
	)
	(arc
		(start 391.393426 -237.51921)
		(mid 391.209651 -237.569982)
		(end 391.024618 -237.524036)
		(width 0.09525)
		(layer "In13.Cu")
		(net "M_H_CPU0_SA_DQS_DN<7>")
	)
	(arc
		(start 386.31622 -237.51921)
		(mid 386.034788 -237.443455)
		(end 385.753356 -237.51921)
		(width 0.09525)
		(layer "In13.Cu")
		(net "M_H_CPU0_SA_DQS_DN<7>")
	)
	(arc
		(start 382.933448 -237.51921)
		(mid 382.77685 -237.568499)
		(end 382.61417 -237.546388)
		(width 0.09525)
		(layer "In13.Cu")
		(net "M_H_CPU0_SA_DQS_DN<7>")
	)
	(arc
		(start 385.744974 -237.524036)
		(mid 385.559942 -237.56995)
		(end 385.376166 -237.51921)
		(width 0.09525)
		(layer "In13.Cu")
		(net "M_H_CPU0_SA_DQS_DN<7>")
	)
	(arc
		(start 392.332972 -237.51921)
		(mid 392.144504 -237.569887)
		(end 391.956036 -237.51921)
		(width 0.09525)
		(layer "In13.Cu")
		(net "M_H_CPU0_SA_DQS_DN<7>")
	)
	(arc
		(start 384.813302 -237.51921)
		(mid 384.624834 -237.569887)
		(end 384.436366 -237.51921)
		(width 0.09525)
		(layer "In13.Cu")
		(net "M_H_CPU0_SA_DQS_DN<7>")
	)
	(arc
		(start 383.496312 -237.51921)
		(mid 383.21488 -237.443455)
		(end 382.933448 -237.51921)
		(width 0.09525)
		(layer "In13.Cu")
		(net "M_H_CPU0_SA_DQS_DN<7>")
	)
	(arc
		(start 383.873502 -237.51921)
		(mid 383.689727 -237.569982)
		(end 383.504694 -237.524036)
		(width 0.09525)
		(layer "In13.Cu")
		(net "M_H_CPU0_SA_DQS_DN<7>")
	)
	(arc
		(start 390.44499 -237.524036)
		(mid 390.259958 -237.56995)
		(end 390.076182 -237.51921)
		(width 0.09525)
		(layer "In13.Cu")
		(net "M_H_CPU0_SA_DQS_DN<7>")
	)
	(arc
		(start 385.376166 -237.51921)
		(mid 385.094734 -237.443455)
		(end 384.813302 -237.51921)
		(width 0.09525)
		(layer "In13.Cu")
		(net "M_H_CPU0_SA_DQS_DN<7>")
	)
	(arc
		(start 393.350496 -237.460028)
		(mid 393.313833 -237.492275)
		(end 393.27328 -237.519464)
		(width 0.09525)
		(layer "In13.Cu")
		(net "M_H_CPU0_SA_DQS_DN<7>")
	)
	(arc
		(start 384.436366 -237.51921)
		(mid 384.154934 -237.443455)
		(end 383.873502 -237.51921)
		(width 0.09525)
		(layer "In13.Cu")
		(net "M_H_CPU0_SA_DQS_DN<7>")
	)
	(segment
		(start 382.277874 -232.599992)
		(end 382.744726 -232.334054)
		(width 0.12954)
		(layer "F.Cu")
		(net "M_H_CPU0_SA_DQS_DN<6>")
	)
	(segment
		(start 418.109908 -211.216494)
		(end 417.9316 -211.038186)
		(width 0.16002)
		(layer "In13.Cu")
		(net "M_H_CPU0_SA_DQS_DN<6>")
	)
	(segment
		(start 409.369006 -211.139024)
		(end 409.031948 -211.476082)
		(width 0.16002)
		(layer "In13.Cu")
		(net "M_H_CPU0_SA_DQS_DN<6>")
	)
	(segment
		(start 394.042392 -229.955598)
		(end 394.042392 -230.588312)
		(width 0.09525)
		(layer "In13.Cu")
		(net "M_H_CPU0_SA_DQS_DN<6>")
	)
	(segment
		(start 395.02842 -229.305612)
		(end 394.692378 -229.305612)
		(width 0.09525)
		(layer "In13.Cu")
		(net "M_H_CPU0_SA_DQS_DN<6>")
	)
	(segment
		(start 410.304488 -212.262212)
		(end 410.304488 -211.476082)
		(width 0.16002)
		(layer "In13.Cu")
		(net "M_H_CPU0_SA_DQS_DN<6>")
	)
	(segment
		(start 409.031948 -211.476082)
		(end 409.031948 -212.262212)
		(width 0.16002)
		(layer "In13.Cu")
		(net "M_H_CPU0_SA_DQS_DN<6>")
	)
	(segment
		(start 390.453372 -232.659174)
		(end 390.44499 -232.664)
		(width 0.09525)
		(layer "In13.Cu")
		(net "M_H_CPU0_SA_DQS_DN<6>")
	)
	(segment
		(start 412.245048 -211.476082)
		(end 411.90799 -211.139024)
		(width 0.16002)
		(layer "In13.Cu")
		(net "M_H_CPU0_SA_DQS_DN<6>")
	)
	(segment
		(start 386.69341 -232.659174)
		(end 386.685028 -232.664)
		(width 0.09525)
		(layer "In13.Cu")
		(net "M_H_CPU0_SA_DQS_DN<6>")
	)
	(segment
		(start 408.871928 -212.422232)
		(end 408.375612 -212.422232)
		(width 0.16002)
		(layer "In13.Cu")
		(net "M_H_CPU0_SA_DQS_DN<6>")
	)
	(segment
		(start 410.972508 -212.262212)
		(end 410.812488 -212.422232)
		(width 0.16002)
		(layer "In13.Cu")
		(net "M_H_CPU0_SA_DQS_DN<6>")
	)
	(segment
		(start 382.590802 -232.599484)
		(end 382.744726 -232.334054)
		(width 0.09525)
		(layer "In13.Cu")
		(net "M_H_CPU0_SA_DQS_DN<6>")
	)
	(segment
		(start 412.93923 -212.422232)
		(end 412.405068 -212.422232)
		(width 0.16002)
		(layer "In13.Cu")
		(net "M_H_CPU0_SA_DQS_DN<6>")
	)
	(segment
		(start 385.753356 -232.659174)
		(end 385.744974 -232.664)
		(width 0.09525)
		(layer "In13.Cu")
		(net "M_H_CPU0_SA_DQS_DN<6>")
	)
	(segment
		(start 417.9316 -211.038186)
		(end 414.749996 -211.038186)
		(width 0.16002)
		(layer "In13.Cu")
		(net "M_H_CPU0_SA_DQS_DN<6>")
	)
	(segment
		(start 387.264656 -232.664)
		(end 387.256274 -232.659174)
		(width 0.09525)
		(layer "In13.Cu")
		(net "M_H_CPU0_SA_DQS_DN<6>")
	)
	(segment
		(start 419.912038 -210.935062)
		(end 419.630606 -211.216494)
		(width 0.16002)
		(layer "In13.Cu")
		(net "M_H_CPU0_SA_DQS_DN<6>")
	)
	(segment
		(start 410.304488 -211.476082)
		(end 409.96743 -211.139024)
		(width 0.16002)
		(layer "In13.Cu")
		(net "M_H_CPU0_SA_DQS_DN<6>")
	)
	(segment
		(start 410.812488 -212.422232)
		(end 410.464508 -212.422232)
		(width 0.16002)
		(layer "In13.Cu")
		(net "M_H_CPU0_SA_DQS_DN<6>")
	)
	(segment
		(start 394.042392 -230.588312)
		(end 392.047222 -232.583482)
		(width 0.09525)
		(layer "In13.Cu")
		(net "M_H_CPU0_SA_DQS_DN<6>")
	)
	(segment
		(start 419.630606 -211.216494)
		(end 418.109908 -211.216494)
		(width 0.16002)
		(layer "In13.Cu")
		(net "M_H_CPU0_SA_DQS_DN<6>")
	)
	(segment
		(start 395.611604 -228.722174)
		(end 395.02842 -229.305612)
		(width 0.09525)
		(layer "In13.Cu")
		(net "M_H_CPU0_SA_DQS_DN<6>")
	)
	(segment
		(start 412.405068 -212.422232)
		(end 412.245048 -212.262212)
		(width 0.16002)
		(layer "In13.Cu")
		(net "M_H_CPU0_SA_DQS_DN<6>")
	)
	(segment
		(start 409.031948 -212.262212)
		(end 408.871928 -212.422232)
		(width 0.16002)
		(layer "In13.Cu")
		(net "M_H_CPU0_SA_DQS_DN<6>")
	)
	(segment
		(start 398.455642 -222.342202)
		(end 398.455642 -225.795332)
		(width 0.16002)
		(layer "In13.Cu")
		(net "M_H_CPU0_SA_DQS_DN<6>")
	)
	(segment
		(start 412.245048 -212.262212)
		(end 412.245048 -211.476082)
		(width 0.16002)
		(layer "In13.Cu")
		(net "M_H_CPU0_SA_DQS_DN<6>")
	)
	(segment
		(start 395.628368 -228.622606)
		(end 395.611604 -228.63937)
		(width 0.09525)
		(layer "In13.Cu")
		(net "M_H_CPU0_SA_DQS_DN<6>")
	)
	(segment
		(start 398.455642 -225.795332)
		(end 395.628368 -228.622606)
		(width 0.16002)
		(layer "In13.Cu")
		(net "M_H_CPU0_SA_DQS_DN<6>")
	)
	(segment
		(start 410.972508 -211.476082)
		(end 410.972508 -212.262212)
		(width 0.16002)
		(layer "In13.Cu")
		(net "M_H_CPU0_SA_DQS_DN<6>")
	)
	(segment
		(start 408.375612 -212.422232)
		(end 398.455642 -222.342202)
		(width 0.16002)
		(layer "In13.Cu")
		(net "M_H_CPU0_SA_DQS_DN<6>")
	)
	(segment
		(start 413.980376 -211.807806)
		(end 413.553656 -211.807806)
		(width 0.16002)
		(layer "In13.Cu")
		(net "M_H_CPU0_SA_DQS_DN<6>")
	)
	(segment
		(start 383.504694 -232.664)
		(end 383.496312 -232.659174)
		(width 0.09525)
		(layer "In13.Cu")
		(net "M_H_CPU0_SA_DQS_DN<6>")
	)
	(segment
		(start 414.749996 -211.038186)
		(end 413.980376 -211.807806)
		(width 0.16002)
		(layer "In13.Cu")
		(net "M_H_CPU0_SA_DQS_DN<6>")
	)
	(segment
		(start 409.96743 -211.139024)
		(end 409.369006 -211.139024)
		(width 0.16002)
		(layer "In13.Cu")
		(net "M_H_CPU0_SA_DQS_DN<6>")
	)
	(segment
		(start 410.464508 -212.422232)
		(end 410.304488 -212.262212)
		(width 0.16002)
		(layer "In13.Cu")
		(net "M_H_CPU0_SA_DQS_DN<6>")
	)
	(segment
		(start 392.047222 -232.583482)
		(end 391.674858 -232.583482)
		(width 0.09525)
		(layer "In13.Cu")
		(net "M_H_CPU0_SA_DQS_DN<6>")
	)
	(segment
		(start 382.61417 -232.686352)
		(end 382.590802 -232.599484)
		(width 0.09525)
		(layer "In13.Cu")
		(net "M_H_CPU0_SA_DQS_DN<6>")
	)
	(segment
		(start 411.309566 -211.139024)
		(end 410.972508 -211.476082)
		(width 0.16002)
		(layer "In13.Cu")
		(net "M_H_CPU0_SA_DQS_DN<6>")
	)
	(segment
		(start 388.20471 -232.664)
		(end 388.196328 -232.659174)
		(width 0.09525)
		(layer "In13.Cu")
		(net "M_H_CPU0_SA_DQS_DN<6>")
	)
	(segment
		(start 394.692378 -229.305612)
		(end 394.042392 -229.955598)
		(width 0.09525)
		(layer "In13.Cu")
		(net "M_H_CPU0_SA_DQS_DN<6>")
	)
	(segment
		(start 413.553656 -211.807806)
		(end 412.93923 -212.422232)
		(width 0.16002)
		(layer "In13.Cu")
		(net "M_H_CPU0_SA_DQS_DN<6>")
	)
	(segment
		(start 391.024618 -232.664)
		(end 391.016236 -232.659174)
		(width 0.09525)
		(layer "In13.Cu")
		(net "M_H_CPU0_SA_DQS_DN<6>")
	)
	(segment
		(start 411.90799 -211.139024)
		(end 411.309566 -211.139024)
		(width 0.16002)
		(layer "In13.Cu")
		(net "M_H_CPU0_SA_DQS_DN<6>")
	)
	(segment
		(start 395.611604 -228.63937)
		(end 395.611604 -228.722174)
		(width 0.09525)
		(layer "In13.Cu")
		(net "M_H_CPU0_SA_DQS_DN<6>")
	)
	(arc
		(start 387.256274 -232.659174)
		(mid 386.974842 -232.583419)
		(end 386.69341 -232.659174)
		(width 0.09525)
		(layer "In13.Cu")
		(net "M_H_CPU0_SA_DQS_DN<6>")
	)
	(arc
		(start 385.376166 -232.659174)
		(mid 385.094734 -232.583419)
		(end 384.813302 -232.659174)
		(width 0.09525)
		(layer "In13.Cu")
		(net "M_H_CPU0_SA_DQS_DN<6>")
	)
	(arc
		(start 389.513318 -232.659174)
		(mid 389.32485 -232.709851)
		(end 389.136382 -232.659174)
		(width 0.09525)
		(layer "In13.Cu")
		(net "M_H_CPU0_SA_DQS_DN<6>")
	)
	(arc
		(start 383.496312 -232.659174)
		(mid 383.21488 -232.583419)
		(end 382.933448 -232.659174)
		(width 0.09525)
		(layer "In13.Cu")
		(net "M_H_CPU0_SA_DQS_DN<6>")
	)
	(arc
		(start 388.573518 -232.659174)
		(mid 388.389743 -232.709946)
		(end 388.20471 -232.664)
		(width 0.09525)
		(layer "In13.Cu")
		(net "M_H_CPU0_SA_DQS_DN<6>")
	)
	(arc
		(start 391.393426 -232.659174)
		(mid 391.209651 -232.709946)
		(end 391.024618 -232.664)
		(width 0.09525)
		(layer "In13.Cu")
		(net "M_H_CPU0_SA_DQS_DN<6>")
	)
	(arc
		(start 390.076182 -232.659174)
		(mid 389.79475 -232.583419)
		(end 389.513318 -232.659174)
		(width 0.09525)
		(layer "In13.Cu")
		(net "M_H_CPU0_SA_DQS_DN<6>")
	)
	(arc
		(start 386.685028 -232.664)
		(mid 386.499996 -232.709914)
		(end 386.31622 -232.659174)
		(width 0.09525)
		(layer "In13.Cu")
		(net "M_H_CPU0_SA_DQS_DN<6>")
	)
	(arc
		(start 391.016236 -232.659174)
		(mid 390.734804 -232.583419)
		(end 390.453372 -232.659174)
		(width 0.09525)
		(layer "In13.Cu")
		(net "M_H_CPU0_SA_DQS_DN<6>")
	)
	(arc
		(start 384.436366 -232.659174)
		(mid 384.154934 -232.583419)
		(end 383.873502 -232.659174)
		(width 0.09525)
		(layer "In13.Cu")
		(net "M_H_CPU0_SA_DQS_DN<6>")
	)
	(arc
		(start 391.674858 -232.583482)
		(mid 391.52915 -232.60275)
		(end 391.393426 -232.659174)
		(width 0.09525)
		(layer "In13.Cu")
		(net "M_H_CPU0_SA_DQS_DN<6>")
	)
	(arc
		(start 384.813302 -232.659174)
		(mid 384.624834 -232.709851)
		(end 384.436366 -232.659174)
		(width 0.09525)
		(layer "In13.Cu")
		(net "M_H_CPU0_SA_DQS_DN<6>")
	)
	(arc
		(start 386.31622 -232.659174)
		(mid 386.034788 -232.583419)
		(end 385.753356 -232.659174)
		(width 0.09525)
		(layer "In13.Cu")
		(net "M_H_CPU0_SA_DQS_DN<6>")
	)
	(arc
		(start 385.744974 -232.664)
		(mid 385.559942 -232.709914)
		(end 385.376166 -232.659174)
		(width 0.09525)
		(layer "In13.Cu")
		(net "M_H_CPU0_SA_DQS_DN<6>")
	)
	(arc
		(start 390.44499 -232.664)
		(mid 390.259958 -232.709914)
		(end 390.076182 -232.659174)
		(width 0.09525)
		(layer "In13.Cu")
		(net "M_H_CPU0_SA_DQS_DN<6>")
	)
	(arc
		(start 382.933448 -232.659174)
		(mid 382.77685 -232.708463)
		(end 382.61417 -232.686352)
		(width 0.09525)
		(layer "In13.Cu")
		(net "M_H_CPU0_SA_DQS_DN<6>")
	)
	(arc
		(start 389.136382 -232.659174)
		(mid 388.85495 -232.583419)
		(end 388.573518 -232.659174)
		(width 0.09525)
		(layer "In13.Cu")
		(net "M_H_CPU0_SA_DQS_DN<6>")
	)
	(arc
		(start 388.196328 -232.659174)
		(mid 387.914896 -232.583419)
		(end 387.633464 -232.659174)
		(width 0.09525)
		(layer "In13.Cu")
		(net "M_H_CPU0_SA_DQS_DN<6>")
	)
	(arc
		(start 387.633464 -232.659174)
		(mid 387.449689 -232.709946)
		(end 387.264656 -232.664)
		(width 0.09525)
		(layer "In13.Cu")
		(net "M_H_CPU0_SA_DQS_DN<6>")
	)
	(arc
		(start 383.873502 -232.659174)
		(mid 383.689727 -232.709946)
		(end 383.504694 -232.664)
		(width 0.09525)
		(layer "In13.Cu")
		(net "M_H_CPU0_SA_DQS_DN<6>")
	)
	(segment
		(start 382.277874 -227.74021)
		(end 382.744726 -227.474272)
		(width 0.12954)
		(layer "F.Cu")
		(net "M_H_CPU0_SA_DQS_DN<5>")
	)
	(segment
		(start 400.989038 -210.35264)
		(end 400.742658 -210.59902)
		(width 0.16002)
		(layer "In13.Cu")
		(net "M_H_CPU0_SA_DQS_DN<5>")
	)
	(segment
		(start 403.624288 -206.793846)
		(end 403.624288 -207.27035)
		(width 0.16002)
		(layer "In13.Cu")
		(net "M_H_CPU0_SA_DQS_DN<5>")
	)
	(segment
		(start 400.878548 -209.539586)
		(end 400.878548 -210.01609)
		(width 0.16002)
		(layer "In13.Cu")
		(net "M_H_CPU0_SA_DQS_DN<5>")
	)
	(segment
		(start 400.878548 -210.01609)
		(end 400.989038 -210.12658)
		(width 0.16002)
		(layer "In13.Cu")
		(net "M_H_CPU0_SA_DQS_DN<5>")
	)
	(segment
		(start 401.889468 -209.22615)
		(end 401.778978 -209.11566)
		(width 0.16002)
		(layer "In13.Cu")
		(net "M_H_CPU0_SA_DQS_DN<5>")
	)
	(segment
		(start 389.983472 -226.989386)
		(end 389.945372 -227.011484)
		(width 0.09525)
		(layer "In13.Cu")
		(net "M_H_CPU0_SA_DQS_DN<5>")
	)
	(segment
		(start 392.977624 -221.698058)
		(end 393.023598 -221.744032)
		(width 0.09525)
		(layer "In13.Cu")
		(net "M_H_CPU0_SA_DQS_DN<5>")
	)
	(segment
		(start 392.918442 -221.382844)
		(end 392.977624 -221.442026)
		(width 0.09525)
		(layer "In13.Cu")
		(net "M_H_CPU0_SA_DQS_DN<5>")
	)
	(segment
		(start 407.380948 -203.73467)
		(end 407.270458 -203.62418)
		(width 0.16002)
		(layer "In13.Cu")
		(net "M_H_CPU0_SA_DQS_DN<5>")
	)
	(segment
		(start 393.023598 -221.744032)
		(end 393.023598 -221.90075)
		(width 0.09525)
		(layer "In13.Cu")
		(net "M_H_CPU0_SA_DQS_DN<5>")
	)
	(segment
		(start 405.897588 -204.99705)
		(end 405.421084 -204.99705)
		(width 0.16002)
		(layer "In13.Cu")
		(net "M_H_CPU0_SA_DQS_DN<5>")
	)
	(segment
		(start 386.69341 -227.799392)
		(end 386.685028 -227.804218)
		(width 0.09525)
		(layer "In13.Cu")
		(net "M_H_CPU0_SA_DQS_DN<5>")
	)
	(segment
		(start 403.734778 -207.6069)
		(end 403.488398 -207.85328)
		(width 0.16002)
		(layer "In13.Cu")
		(net "M_H_CPU0_SA_DQS_DN<5>")
	)
	(segment
		(start 413.980376 -202.457812)
		(end 408.883866 -202.457812)
		(width 0.16002)
		(layer "In13.Cu")
		(net "M_H_CPU0_SA_DQS_DN<5>")
	)
	(segment
		(start 405.107648 -206.23403)
		(end 404.861268 -206.48041)
		(width 0.16002)
		(layer "In13.Cu")
		(net "M_H_CPU0_SA_DQS_DN<5>")
	)
	(segment
		(start 405.107648 -206.00797)
		(end 405.107648 -206.23403)
		(width 0.16002)
		(layer "In13.Cu")
		(net "M_H_CPU0_SA_DQS_DN<5>")
	)
	(segment
		(start 404.048214 -206.36992)
		(end 403.624288 -206.793846)
		(width 0.16002)
		(layer "In13.Cu")
		(net "M_H_CPU0_SA_DQS_DN<5>")
	)
	(segment
		(start 417.9316 -201.688192)
		(end 414.749996 -201.688192)
		(width 0.16002)
		(layer "In13.Cu")
		(net "M_H_CPU0_SA_DQS_DN<5>")
	)
	(segment
		(start 401.778978 -209.11566)
		(end 401.302474 -209.11566)
		(width 0.16002)
		(layer "In13.Cu")
		(net "M_H_CPU0_SA_DQS_DN<5>")
	)
	(segment
		(start 392.916156 -218.425522)
		(end 392.916156 -221.356936)
		(width 0.16002)
		(layer "In13.Cu")
		(net "M_H_CPU0_SA_DQS_DN<5>")
	)
	(segment
		(start 392.33348 -222.939356)
		(end 392.29538 -222.961454)
		(width 0.09525)
		(layer "In13.Cu")
		(net "M_H_CPU0_SA_DQS_DN<5>")
	)
	(segment
		(start 390.014968 -226.971098)
		(end 389.983472 -226.989386)
		(width 0.09525)
		(layer "In13.Cu")
		(net "M_H_CPU0_SA_DQS_DN<5>")
	)
	(segment
		(start 392.977624 -221.442026)
		(end 392.977624 -221.698058)
		(width 0.09525)
		(layer "In13.Cu")
		(net "M_H_CPU0_SA_DQS_DN<5>")
	)
	(segment
		(start 390.485884 -226.160584)
		(end 390.453372 -226.17938)
		(width 0.09525)
		(layer "In13.Cu")
		(net "M_H_CPU0_SA_DQS_DN<5>")
	)
	(segment
		(start 383.504694 -227.804218)
		(end 383.496312 -227.799392)
		(width 0.09525)
		(layer "In13.Cu")
		(net "M_H_CPU0_SA_DQS_DN<5>")
	)
	(segment
		(start 392.522456 -222.614236)
		(end 392.522202 -222.614236)
		(width 0.09525)
		(layer "In13.Cu")
		(net "M_H_CPU0_SA_DQS_DN<5>")
	)
	(segment
		(start 389.54583 -227.780596)
		(end 389.513318 -227.799392)
		(width 0.09525)
		(layer "In13.Cu")
		(net "M_H_CPU0_SA_DQS_DN<5>")
	)
	(segment
		(start 391.895838 -223.730566)
		(end 391.863326 -223.749362)
		(width 0.09525)
		(layer "In13.Cu")
		(net "M_H_CPU0_SA_DQS_DN<5>")
	)
	(segment
		(start 404.524718 -206.36992)
		(end 404.048214 -206.36992)
		(width 0.16002)
		(layer "In13.Cu")
		(net "M_H_CPU0_SA_DQS_DN<5>")
	)
	(segment
		(start 402.251418 -208.166716)
		(end 402.251418 -208.64322)
		(width 0.16002)
		(layer "In13.Cu")
		(net "M_H_CPU0_SA_DQS_DN<5>")
	)
	(segment
		(start 406.793954 -203.62418)
		(end 406.370028 -204.048106)
		(width 0.16002)
		(layer "In13.Cu")
		(net "M_H_CPU0_SA_DQS_DN<5>")
	)
	(segment
		(start 406.008078 -205.10754)
		(end 405.897588 -204.99705)
		(width 0.16002)
		(layer "In13.Cu")
		(net "M_H_CPU0_SA_DQS_DN<5>")
	)
	(segment
		(start 403.734778 -207.38084)
		(end 403.734778 -207.6069)
		(width 0.16002)
		(layer "In13.Cu")
		(net "M_H_CPU0_SA_DQS_DN<5>")
	)
	(segment
		(start 400.742658 -210.59902)
		(end 400.516598 -210.59902)
		(width 0.16002)
		(layer "In13.Cu")
		(net "M_H_CPU0_SA_DQS_DN<5>")
	)
	(segment
		(start 419.627812 -201.869294)
		(end 418.112702 -201.869294)
		(width 0.16002)
		(layer "In13.Cu")
		(net "M_H_CPU0_SA_DQS_DN<5>")
	)
	(segment
		(start 391.863326 -223.749362)
		(end 391.825226 -223.77146)
		(width 0.09525)
		(layer "In13.Cu")
		(net "M_H_CPU0_SA_DQS_DN<5>")
	)
	(segment
		(start 400.989038 -210.12658)
		(end 400.989038 -210.35264)
		(width 0.16002)
		(layer "In13.Cu")
		(net "M_H_CPU0_SA_DQS_DN<5>")
	)
	(segment
		(start 403.151848 -207.74279)
		(end 402.675344 -207.74279)
		(width 0.16002)
		(layer "In13.Cu")
		(net "M_H_CPU0_SA_DQS_DN<5>")
	)
	(segment
		(start 402.251418 -208.64322)
		(end 402.361908 -208.75371)
		(width 0.16002)
		(layer "In13.Cu")
		(net "M_H_CPU0_SA_DQS_DN<5>")
	)
	(segment
		(start 406.234138 -205.10754)
		(end 406.008078 -205.10754)
		(width 0.16002)
		(layer "In13.Cu")
		(net "M_H_CPU0_SA_DQS_DN<5>")
	)
	(segment
		(start 392.36269 -222.922592)
		(end 392.33348 -222.939356)
		(width 0.09525)
		(layer "In13.Cu")
		(net "M_H_CPU0_SA_DQS_DN<5>")
	)
	(segment
		(start 403.488398 -207.85328)
		(end 403.262338 -207.85328)
		(width 0.16002)
		(layer "In13.Cu")
		(net "M_H_CPU0_SA_DQS_DN<5>")
	)
	(segment
		(start 392.918442 -221.359222)
		(end 392.918442 -221.382844)
		(width 0.09525)
		(layer "In13.Cu")
		(net "M_H_CPU0_SA_DQS_DN<5>")
	)
	(segment
		(start 407.270458 -203.62418)
		(end 406.793954 -203.62418)
		(width 0.16002)
		(layer "In13.Cu")
		(net "M_H_CPU0_SA_DQS_DN<5>")
	)
	(segment
		(start 406.480518 -204.86116)
		(end 406.234138 -205.10754)
		(width 0.16002)
		(layer "In13.Cu")
		(net "M_H_CPU0_SA_DQS_DN<5>")
	)
	(segment
		(start 405.421084 -204.99705)
		(end 404.997158 -205.420976)
		(width 0.16002)
		(layer "In13.Cu")
		(net "M_H_CPU0_SA_DQS_DN<5>")
	)
	(segment
		(start 387.264656 -227.804218)
		(end 387.256274 -227.799392)
		(width 0.09525)
		(layer "In13.Cu")
		(net "M_H_CPU0_SA_DQS_DN<5>")
	)
	(segment
		(start 399.616168 -211.72551)
		(end 392.916156 -218.425522)
		(width 0.16002)
		(layer "In13.Cu")
		(net "M_H_CPU0_SA_DQS_DN<5>")
	)
	(segment
		(start 406.480518 -204.6351)
		(end 406.480518 -204.86116)
		(width 0.16002)
		(layer "In13.Cu")
		(net "M_H_CPU0_SA_DQS_DN<5>")
	)
	(segment
		(start 391.393426 -224.559368)
		(end 391.355326 -224.581466)
		(width 0.09525)
		(layer "In13.Cu")
		(net "M_H_CPU0_SA_DQS_DN<5>")
	)
	(segment
		(start 392.788902 -222.135446)
		(end 392.765026 -222.151956)
		(width 0.09525)
		(layer "In13.Cu")
		(net "M_H_CPU0_SA_DQS_DN<5>")
	)
	(segment
		(start 400.516598 -210.59902)
		(end 400.406108 -210.48853)
		(width 0.16002)
		(layer "In13.Cu")
		(net "M_H_CPU0_SA_DQS_DN<5>")
	)
	(segment
		(start 399.616168 -211.49945)
		(end 399.616168 -211.72551)
		(width 0.16002)
		(layer "In13.Cu")
		(net "M_H_CPU0_SA_DQS_DN<5>")
	)
	(segment
		(start 388.20471 -227.804218)
		(end 388.196328 -227.799392)
		(width 0.09525)
		(layer "In13.Cu")
		(net "M_H_CPU0_SA_DQS_DN<5>")
	)
	(segment
		(start 403.262338 -207.85328)
		(end 403.151848 -207.74279)
		(width 0.16002)
		(layer "In13.Cu")
		(net "M_H_CPU0_SA_DQS_DN<5>")
	)
	(segment
		(start 402.361908 -208.75371)
		(end 402.361908 -208.97977)
		(width 0.16002)
		(layer "In13.Cu")
		(net "M_H_CPU0_SA_DQS_DN<5>")
	)
	(segment
		(start 393.023598 -221.90075)
		(end 392.788902 -222.135446)
		(width 0.09525)
		(layer "In13.Cu")
		(net "M_H_CPU0_SA_DQS_DN<5>")
	)
	(segment
		(start 404.861268 -206.48041)
		(end 404.635208 -206.48041)
		(width 0.16002)
		(layer "In13.Cu")
		(net "M_H_CPU0_SA_DQS_DN<5>")
	)
	(segment
		(start 414.749996 -201.688192)
		(end 413.980376 -202.457812)
		(width 0.16002)
		(layer "In13.Cu")
		(net "M_H_CPU0_SA_DQS_DN<5>")
	)
	(segment
		(start 404.635208 -206.48041)
		(end 404.524718 -206.36992)
		(width 0.16002)
		(layer "In13.Cu")
		(net "M_H_CPU0_SA_DQS_DN<5>")
	)
	(segment
		(start 399.505678 -210.912456)
		(end 399.505678 -211.38896)
		(width 0.16002)
		(layer "In13.Cu")
		(net "M_H_CPU0_SA_DQS_DN<5>")
	)
	(segment
		(start 391.424922 -224.54108)
		(end 391.393426 -224.559368)
		(width 0.09525)
		(layer "In13.Cu")
		(net "M_H_CPU0_SA_DQS_DN<5>")
	)
	(segment
		(start 418.112702 -201.869294)
		(end 417.9316 -201.688192)
		(width 0.16002)
		(layer "In13.Cu")
		(net "M_H_CPU0_SA_DQS_DN<5>")
	)
	(segment
		(start 404.997158 -205.89748)
		(end 405.107648 -206.00797)
		(width 0.16002)
		(layer "In13.Cu")
		(net "M_H_CPU0_SA_DQS_DN<5>")
	)
	(segment
		(start 390.955784 -225.350578)
		(end 390.923272 -225.369374)
		(width 0.09525)
		(layer "In13.Cu")
		(net "M_H_CPU0_SA_DQS_DN<5>")
	)
	(segment
		(start 400.406108 -210.48853)
		(end 399.929604 -210.48853)
		(width 0.16002)
		(layer "In13.Cu")
		(net "M_H_CPU0_SA_DQS_DN<5>")
	)
	(segment
		(start 408.883866 -202.457812)
		(end 407.607008 -203.73467)
		(width 0.16002)
		(layer "In13.Cu")
		(net "M_H_CPU0_SA_DQS_DN<5>")
	)
	(segment
		(start 401.302474 -209.11566)
		(end 400.878548 -209.539586)
		(width 0.16002)
		(layer "In13.Cu")
		(net "M_H_CPU0_SA_DQS_DN<5>")
	)
	(segment
		(start 406.370028 -204.048106)
		(end 406.370028 -204.52461)
		(width 0.16002)
		(layer "In13.Cu")
		(net "M_H_CPU0_SA_DQS_DN<5>")
	)
	(segment
		(start 390.923272 -225.369374)
		(end 390.88822 -225.389948)
		(width 0.09525)
		(layer "In13.Cu")
		(net "M_H_CPU0_SA_DQS_DN<5>")
	)
	(segment
		(start 402.675344 -207.74279)
		(end 402.251418 -208.166716)
		(width 0.16002)
		(layer "In13.Cu")
		(net "M_H_CPU0_SA_DQS_DN<5>")
	)
	(segment
		(start 407.607008 -203.73467)
		(end 407.380948 -203.73467)
		(width 0.16002)
		(layer "In13.Cu")
		(net "M_H_CPU0_SA_DQS_DN<5>")
	)
	(segment
		(start 390.453372 -226.17938)
		(end 390.415272 -226.201478)
		(width 0.09525)
		(layer "In13.Cu")
		(net "M_H_CPU0_SA_DQS_DN<5>")
	)
	(segment
		(start 403.624288 -207.27035)
		(end 403.734778 -207.38084)
		(width 0.16002)
		(layer "In13.Cu")
		(net "M_H_CPU0_SA_DQS_DN<5>")
	)
	(segment
		(start 406.370028 -204.52461)
		(end 406.480518 -204.6351)
		(width 0.16002)
		(layer "In13.Cu")
		(net "M_H_CPU0_SA_DQS_DN<5>")
	)
	(segment
		(start 392.916156 -221.356936)
		(end 392.918442 -221.359222)
		(width 0.16002)
		(layer "In13.Cu")
		(net "M_H_CPU0_SA_DQS_DN<5>")
	)
	(segment
		(start 402.115528 -209.22615)
		(end 401.889468 -209.22615)
		(width 0.16002)
		(layer "In13.Cu")
		(net "M_H_CPU0_SA_DQS_DN<5>")
	)
	(segment
		(start 402.361908 -208.97977)
		(end 402.115528 -209.22615)
		(width 0.16002)
		(layer "In13.Cu")
		(net "M_H_CPU0_SA_DQS_DN<5>")
	)
	(segment
		(start 382.590802 -227.739702)
		(end 382.744726 -227.474272)
		(width 0.09525)
		(layer "In13.Cu")
		(net "M_H_CPU0_SA_DQS_DN<5>")
	)
	(segment
		(start 419.912038 -201.585068)
		(end 419.627812 -201.869294)
		(width 0.16002)
		(layer "In13.Cu")
		(net "M_H_CPU0_SA_DQS_DN<5>")
	)
	(segment
		(start 399.929604 -210.48853)
		(end 399.505678 -210.912456)
		(width 0.16002)
		(layer "In13.Cu")
		(net "M_H_CPU0_SA_DQS_DN<5>")
	)
	(segment
		(start 399.505678 -211.38896)
		(end 399.616168 -211.49945)
		(width 0.16002)
		(layer "In13.Cu")
		(net "M_H_CPU0_SA_DQS_DN<5>")
	)
	(segment
		(start 385.753356 -227.799392)
		(end 385.744974 -227.804218)
		(width 0.09525)
		(layer "In13.Cu")
		(net "M_H_CPU0_SA_DQS_DN<5>")
	)
	(segment
		(start 382.61417 -227.82657)
		(end 382.590802 -227.739702)
		(width 0.09525)
		(layer "In13.Cu")
		(net "M_H_CPU0_SA_DQS_DN<5>")
	)
	(segment
		(start 404.997158 -205.420976)
		(end 404.997158 -205.89748)
		(width 0.16002)
		(layer "In13.Cu")
		(net "M_H_CPU0_SA_DQS_DN<5>")
	)
	(arc
		(start 392.29538 -222.961454)
		(mid 392.11693 -223.162924)
		(end 392.052556 -223.424242)
		(width 0.09525)
		(layer "In13.Cu")
		(net "M_H_CPU0_SA_DQS_DN<5>")
	)
	(arc
		(start 383.496312 -227.799392)
		(mid 383.21488 -227.723637)
		(end 382.933448 -227.799392)
		(width 0.09525)
		(layer "In13.Cu")
		(net "M_H_CPU0_SA_DQS_DN<5>")
	)
	(arc
		(start 386.31622 -227.799392)
		(mid 386.034788 -227.723637)
		(end 385.753356 -227.799392)
		(width 0.09525)
		(layer "In13.Cu")
		(net "M_H_CPU0_SA_DQS_DN<5>")
	)
	(arc
		(start 392.765026 -222.151956)
		(mid 392.586801 -222.353214)
		(end 392.522456 -222.614236)
		(width 0.09525)
		(layer "In13.Cu")
		(net "M_H_CPU0_SA_DQS_DN<5>")
	)
	(arc
		(start 391.112502 -225.044254)
		(mid 391.071045 -225.216294)
		(end 390.955784 -225.350578)
		(width 0.09525)
		(layer "In13.Cu")
		(net "M_H_CPU0_SA_DQS_DN<5>")
	)
	(arc
		(start 387.256274 -227.799392)
		(mid 386.974842 -227.723637)
		(end 386.69341 -227.799392)
		(width 0.09525)
		(layer "In13.Cu")
		(net "M_H_CPU0_SA_DQS_DN<5>")
	)
	(arc
		(start 391.582402 -224.234248)
		(mid 391.540737 -224.406695)
		(end 391.424922 -224.54108)
		(width 0.09525)
		(layer "In13.Cu")
		(net "M_H_CPU0_SA_DQS_DN<5>")
	)
	(arc
		(start 390.642602 -225.85426)
		(mid 390.601145 -226.0263)
		(end 390.485884 -226.160584)
		(width 0.09525)
		(layer "In13.Cu")
		(net "M_H_CPU0_SA_DQS_DN<5>")
	)
	(arc
		(start 390.88822 -225.389948)
		(mid 390.707829 -225.591647)
		(end 390.642602 -225.85426)
		(width 0.09525)
		(layer "In13.Cu")
		(net "M_H_CPU0_SA_DQS_DN<5>")
	)
	(arc
		(start 384.436366 -227.799392)
		(mid 384.154934 -227.723637)
		(end 383.873502 -227.799392)
		(width 0.09525)
		(layer "In13.Cu")
		(net "M_H_CPU0_SA_DQS_DN<5>")
	)
	(arc
		(start 382.933448 -227.799392)
		(mid 382.77685 -227.848681)
		(end 382.61417 -227.82657)
		(width 0.09525)
		(layer "In13.Cu")
		(net "M_H_CPU0_SA_DQS_DN<5>")
	)
	(arc
		(start 391.825226 -223.77146)
		(mid 391.646776 -223.97293)
		(end 391.582402 -224.234248)
		(width 0.09525)
		(layer "In13.Cu")
		(net "M_H_CPU0_SA_DQS_DN<5>")
	)
	(arc
		(start 389.945372 -227.011484)
		(mid 389.766922 -227.212954)
		(end 389.702548 -227.474272)
		(width 0.09525)
		(layer "In13.Cu")
		(net "M_H_CPU0_SA_DQS_DN<5>")
	)
	(arc
		(start 385.376166 -227.799392)
		(mid 385.094734 -227.723637)
		(end 384.813302 -227.799392)
		(width 0.09525)
		(layer "In13.Cu")
		(net "M_H_CPU0_SA_DQS_DN<5>")
	)
	(arc
		(start 388.196328 -227.799392)
		(mid 387.914896 -227.723637)
		(end 387.633464 -227.799392)
		(width 0.09525)
		(layer "In13.Cu")
		(net "M_H_CPU0_SA_DQS_DN<5>")
	)
	(arc
		(start 389.136382 -227.799392)
		(mid 388.85495 -227.723637)
		(end 388.573518 -227.799392)
		(width 0.09525)
		(layer "In13.Cu")
		(net "M_H_CPU0_SA_DQS_DN<5>")
	)
	(arc
		(start 390.172448 -226.664266)
		(mid 390.130783 -226.836713)
		(end 390.014968 -226.971098)
		(width 0.09525)
		(layer "In13.Cu")
		(net "M_H_CPU0_SA_DQS_DN<5>")
	)
	(arc
		(start 388.573518 -227.799392)
		(mid 388.389743 -227.850164)
		(end 388.20471 -227.804218)
		(width 0.09525)
		(layer "In13.Cu")
		(net "M_H_CPU0_SA_DQS_DN<5>")
	)
	(arc
		(start 387.633464 -227.799392)
		(mid 387.449689 -227.850164)
		(end 387.264656 -227.804218)
		(width 0.09525)
		(layer "In13.Cu")
		(net "M_H_CPU0_SA_DQS_DN<5>")
	)
	(arc
		(start 392.052556 -223.424242)
		(mid 392.011099 -223.596282)
		(end 391.895838 -223.730566)
		(width 0.09525)
		(layer "In13.Cu")
		(net "M_H_CPU0_SA_DQS_DN<5>")
	)
	(arc
		(start 390.415272 -226.201478)
		(mid 390.236822 -226.402948)
		(end 390.172448 -226.664266)
		(width 0.09525)
		(layer "In13.Cu")
		(net "M_H_CPU0_SA_DQS_DN<5>")
	)
	(arc
		(start 389.702548 -227.474272)
		(mid 389.661091 -227.646312)
		(end 389.54583 -227.780596)
		(width 0.09525)
		(layer "In13.Cu")
		(net "M_H_CPU0_SA_DQS_DN<5>")
	)
	(arc
		(start 383.873502 -227.799392)
		(mid 383.689727 -227.850164)
		(end 383.504694 -227.804218)
		(width 0.09525)
		(layer "In13.Cu")
		(net "M_H_CPU0_SA_DQS_DN<5>")
	)
	(arc
		(start 386.685028 -227.804218)
		(mid 386.499996 -227.850132)
		(end 386.31622 -227.799392)
		(width 0.09525)
		(layer "In13.Cu")
		(net "M_H_CPU0_SA_DQS_DN<5>")
	)
	(arc
		(start 384.813302 -227.799392)
		(mid 384.624834 -227.850069)
		(end 384.436366 -227.799392)
		(width 0.09525)
		(layer "In13.Cu")
		(net "M_H_CPU0_SA_DQS_DN<5>")
	)
	(arc
		(start 385.744974 -227.804218)
		(mid 385.559942 -227.850132)
		(end 385.376166 -227.799392)
		(width 0.09525)
		(layer "In13.Cu")
		(net "M_H_CPU0_SA_DQS_DN<5>")
	)
	(arc
		(start 392.522202 -222.614236)
		(mid 392.479955 -222.787811)
		(end 392.36269 -222.922592)
		(width 0.09525)
		(layer "In13.Cu")
		(net "M_H_CPU0_SA_DQS_DN<5>")
	)
	(arc
		(start 391.355326 -224.581466)
		(mid 391.176876 -224.782936)
		(end 391.112502 -225.044254)
		(width 0.09525)
		(layer "In13.Cu")
		(net "M_H_CPU0_SA_DQS_DN<5>")
	)
	(arc
		(start 389.513318 -227.799392)
		(mid 389.32485 -227.850069)
		(end 389.136382 -227.799392)
		(width 0.09525)
		(layer "In13.Cu")
		(net "M_H_CPU0_SA_DQS_DN<5>")
	)
	(segment
		(start 383.217928 -247.1801)
		(end 383.68478 -246.914162)
		(width 0.12954)
		(layer "F.Cu")
		(net "M_H_CPU0_SA_DQS_DN<4>")
	)
	(segment
		(start 395.774672 -246.235982)
		(end 395.715744 -246.177054)
		(width 0.09525)
		(layer "In13.Cu")
		(net "M_H_CPU0_SA_DQS_DN<4>")
	)
	(segment
		(start 387.264656 -246.584216)
		(end 387.256274 -246.589042)
		(width 0.09525)
		(layer "In13.Cu")
		(net "M_H_CPU0_SA_DQS_DN<4>")
	)
	(segment
		(start 414.07334 -238.905288)
		(end 413.09036 -238.905288)
		(width 0.16002)
		(layer "In13.Cu")
		(net "M_H_CPU0_SA_DQS_DN<4>")
	)
	(segment
		(start 421.741346 -238.747554)
		(end 421.570912 -238.917988)
		(width 0.16002)
		(layer "In13.Cu")
		(net "M_H_CPU0_SA_DQS_DN<4>")
	)
	(segment
		(start 420.739316 -238.917988)
		(end 420.383462 -238.562134)
		(width 0.16002)
		(layer "In13.Cu")
		(net "M_H_CPU0_SA_DQS_DN<4>")
	)
	(segment
		(start 386.69341 -246.589042)
		(end 386.685028 -246.584216)
		(width 0.09525)
		(layer "In13.Cu")
		(net "M_H_CPU0_SA_DQS_DN<4>")
	)
	(segment
		(start 411.583124 -240.412524)
		(end 410.6926 -240.412524)
		(width 0.16002)
		(layer "In13.Cu")
		(net "M_H_CPU0_SA_DQS_DN<4>")
	)
	(segment
		(start 383.838704 -246.648732)
		(end 383.68478 -246.914162)
		(width 0.09525)
		(layer "In13.Cu")
		(net "M_H_CPU0_SA_DQS_DN<4>")
	)
	(segment
		(start 393.969748 -246.665242)
		(end 393.555982 -246.665242)
		(width 0.09525)
		(layer "In13.Cu")
		(net "M_H_CPU0_SA_DQS_DN<4>")
	)
	(segment
		(start 410.6926 -240.412524)
		(end 404.869142 -246.235982)
		(width 0.16002)
		(layer "In13.Cu")
		(net "M_H_CPU0_SA_DQS_DN<4>")
	)
	(segment
		(start 417.945316 -238.031528)
		(end 414.9471 -238.031528)
		(width 0.16002)
		(layer "In13.Cu")
		(net "M_H_CPU0_SA_DQS_DN<4>")
	)
	(segment
		(start 388.20471 -246.584216)
		(end 388.196328 -246.589042)
		(width 0.09525)
		(layer "In13.Cu")
		(net "M_H_CPU0_SA_DQS_DN<4>")
	)
	(segment
		(start 414.9471 -238.031528)
		(end 414.07334 -238.905288)
		(width 0.16002)
		(layer "In13.Cu")
		(net "M_H_CPU0_SA_DQS_DN<4>")
	)
	(segment
		(start 424.012106 -238.985044)
		(end 423.774616 -238.747554)
		(width 0.16002)
		(layer "In13.Cu")
		(net "M_H_CPU0_SA_DQS_DN<4>")
	)
	(segment
		(start 421.570912 -238.917988)
		(end 420.739316 -238.917988)
		(width 0.16002)
		(layer "In13.Cu")
		(net "M_H_CPU0_SA_DQS_DN<4>")
	)
	(segment
		(start 394.916152 -246.937022)
		(end 394.241528 -246.937022)
		(width 0.09525)
		(layer "In13.Cu")
		(net "M_H_CPU0_SA_DQS_DN<4>")
	)
	(segment
		(start 413.09036 -238.905288)
		(end 411.583124 -240.412524)
		(width 0.16002)
		(layer "In13.Cu")
		(net "M_H_CPU0_SA_DQS_DN<4>")
	)
	(segment
		(start 423.774616 -238.747554)
		(end 421.741346 -238.747554)
		(width 0.16002)
		(layer "In13.Cu")
		(net "M_H_CPU0_SA_DQS_DN<4>")
	)
	(segment
		(start 390.453372 -246.589042)
		(end 390.44499 -246.584216)
		(width 0.09525)
		(layer "In13.Cu")
		(net "M_H_CPU0_SA_DQS_DN<4>")
	)
	(segment
		(start 385.753356 -246.589042)
		(end 385.744974 -246.584216)
		(width 0.09525)
		(layer "In13.Cu")
		(net "M_H_CPU0_SA_DQS_DN<4>")
	)
	(segment
		(start 420.383462 -238.562134)
		(end 418.475922 -238.562134)
		(width 0.16002)
		(layer "In13.Cu")
		(net "M_H_CPU0_SA_DQS_DN<4>")
	)
	(segment
		(start 395.715744 -246.177054)
		(end 395.61897 -246.177054)
		(width 0.09525)
		(layer "In13.Cu")
		(net "M_H_CPU0_SA_DQS_DN<4>")
	)
	(segment
		(start 395.61897 -246.177054)
		(end 394.916152 -246.937022)
		(width 0.09525)
		(layer "In13.Cu")
		(net "M_H_CPU0_SA_DQS_DN<4>")
	)
	(segment
		(start 392.911076 -246.58066)
		(end 392.881866 -246.597678)
		(width 0.09525)
		(layer "In13.Cu")
		(net "M_H_CPU0_SA_DQS_DN<4>")
	)
	(segment
		(start 391.40384 -246.595138)
		(end 391.393426 -246.589042)
		(width 0.09525)
		(layer "In13.Cu")
		(net "M_H_CPU0_SA_DQS_DN<4>")
	)
	(segment
		(start 383.939542 -246.622062)
		(end 383.838704 -246.648732)
		(width 0.09525)
		(layer "In13.Cu")
		(net "M_H_CPU0_SA_DQS_DN<4>")
	)
	(segment
		(start 404.869142 -246.235982)
		(end 395.798294 -246.235982)
		(width 0.16002)
		(layer "In13.Cu")
		(net "M_H_CPU0_SA_DQS_DN<4>")
	)
	(segment
		(start 418.475922 -238.562134)
		(end 417.945316 -238.031528)
		(width 0.16002)
		(layer "In13.Cu")
		(net "M_H_CPU0_SA_DQS_DN<4>")
	)
	(segment
		(start 392.334242 -246.589042)
		(end 392.32586 -246.584216)
		(width 0.09525)
		(layer "In13.Cu")
		(net "M_H_CPU0_SA_DQS_DN<4>")
	)
	(segment
		(start 395.798294 -246.235982)
		(end 395.774672 -246.235982)
		(width 0.09525)
		(layer "In13.Cu")
		(net "M_H_CPU0_SA_DQS_DN<4>")
	)
	(segment
		(start 391.024618 -246.584216)
		(end 391.016236 -246.589042)
		(width 0.09525)
		(layer "In13.Cu")
		(net "M_H_CPU0_SA_DQS_DN<4>")
	)
	(segment
		(start 394.241528 -246.937022)
		(end 393.969748 -246.665242)
		(width 0.09525)
		(layer "In13.Cu")
		(net "M_H_CPU0_SA_DQS_DN<4>")
	)
	(arc
		(start 383.960116 -246.63019)
		(mid 383.949788 -246.62623)
		(end 383.939542 -246.622062)
		(width 0.09525)
		(layer "In13.Cu")
		(net "M_H_CPU0_SA_DQS_DN<4>")
	)
	(arc
		(start 390.076182 -246.589042)
		(mid 389.79475 -246.664797)
		(end 389.513318 -246.589042)
		(width 0.09525)
		(layer "In13.Cu")
		(net "M_H_CPU0_SA_DQS_DN<4>")
	)
	(arc
		(start 393.273788 -246.589042)
		(mid 393.093509 -246.538211)
		(end 392.911076 -246.58066)
		(width 0.09525)
		(layer "In13.Cu")
		(net "M_H_CPU0_SA_DQS_DN<4>")
	)
	(arc
		(start 384.436366 -246.589042)
		(mid 384.202852 -246.662885)
		(end 383.960116 -246.63019)
		(width 0.09525)
		(layer "In13.Cu")
		(net "M_H_CPU0_SA_DQS_DN<4>")
	)
	(arc
		(start 392.32586 -246.584216)
		(mid 392.140574 -246.53818)
		(end 391.956544 -246.589042)
		(width 0.09525)
		(layer "In13.Cu")
		(net "M_H_CPU0_SA_DQS_DN<4>")
	)
	(arc
		(start 392.881866 -246.597678)
		(mid 392.606915 -246.664821)
		(end 392.334242 -246.589042)
		(width 0.09525)
		(layer "In13.Cu")
		(net "M_H_CPU0_SA_DQS_DN<4>")
	)
	(arc
		(start 387.256274 -246.589042)
		(mid 386.974842 -246.664797)
		(end 386.69341 -246.589042)
		(width 0.09525)
		(layer "In13.Cu")
		(net "M_H_CPU0_SA_DQS_DN<4>")
	)
	(arc
		(start 386.31622 -246.589042)
		(mid 386.034788 -246.664797)
		(end 385.753356 -246.589042)
		(width 0.09525)
		(layer "In13.Cu")
		(net "M_H_CPU0_SA_DQS_DN<4>")
	)
	(arc
		(start 389.136382 -246.589042)
		(mid 388.85495 -246.664797)
		(end 388.573518 -246.589042)
		(width 0.09525)
		(layer "In13.Cu")
		(net "M_H_CPU0_SA_DQS_DN<4>")
	)
	(arc
		(start 391.393426 -246.589042)
		(mid 391.209651 -246.53827)
		(end 391.024618 -246.584216)
		(width 0.09525)
		(layer "In13.Cu")
		(net "M_H_CPU0_SA_DQS_DN<4>")
	)
	(arc
		(start 391.016236 -246.589042)
		(mid 390.734804 -246.664797)
		(end 390.453372 -246.589042)
		(width 0.09525)
		(layer "In13.Cu")
		(net "M_H_CPU0_SA_DQS_DN<4>")
	)
	(arc
		(start 388.573518 -246.589042)
		(mid 388.389743 -246.53827)
		(end 388.20471 -246.584216)
		(width 0.09525)
		(layer "In13.Cu")
		(net "M_H_CPU0_SA_DQS_DN<4>")
	)
	(arc
		(start 385.376166 -246.589042)
		(mid 385.094734 -246.664797)
		(end 384.813302 -246.589042)
		(width 0.09525)
		(layer "In13.Cu")
		(net "M_H_CPU0_SA_DQS_DN<4>")
	)
	(arc
		(start 389.513318 -246.589042)
		(mid 389.32485 -246.538365)
		(end 389.136382 -246.589042)
		(width 0.09525)
		(layer "In13.Cu")
		(net "M_H_CPU0_SA_DQS_DN<4>")
	)
	(arc
		(start 384.813302 -246.589042)
		(mid 384.624834 -246.538365)
		(end 384.436366 -246.589042)
		(width 0.09525)
		(layer "In13.Cu")
		(net "M_H_CPU0_SA_DQS_DN<4>")
	)
	(arc
		(start 391.956544 -246.589042)
		(mid 391.681001 -246.664891)
		(end 391.40384 -246.595138)
		(width 0.09525)
		(layer "In13.Cu")
		(net "M_H_CPU0_SA_DQS_DN<4>")
	)
	(arc
		(start 385.744974 -246.584216)
		(mid 385.559942 -246.538302)
		(end 385.376166 -246.589042)
		(width 0.09525)
		(layer "In13.Cu")
		(net "M_H_CPU0_SA_DQS_DN<4>")
	)
	(arc
		(start 388.196328 -246.589042)
		(mid 387.914896 -246.664797)
		(end 387.633464 -246.589042)
		(width 0.09525)
		(layer "In13.Cu")
		(net "M_H_CPU0_SA_DQS_DN<4>")
	)
	(arc
		(start 390.44499 -246.584216)
		(mid 390.259958 -246.538302)
		(end 390.076182 -246.589042)
		(width 0.09525)
		(layer "In13.Cu")
		(net "M_H_CPU0_SA_DQS_DN<4>")
	)
	(arc
		(start 393.555982 -246.665242)
		(mid 393.409823 -246.645871)
		(end 393.273788 -246.589042)
		(width 0.09525)
		(layer "In13.Cu")
		(net "M_H_CPU0_SA_DQS_DN<4>")
	)
	(arc
		(start 387.633464 -246.589042)
		(mid 387.449689 -246.53827)
		(end 387.264656 -246.584216)
		(width 0.09525)
		(layer "In13.Cu")
		(net "M_H_CPU0_SA_DQS_DN<4>")
	)
	(arc
		(start 386.685028 -246.584216)
		(mid 386.499996 -246.538302)
		(end 386.31622 -246.589042)
		(width 0.09525)
		(layer "In13.Cu")
		(net "M_H_CPU0_SA_DQS_DN<4>")
	)
	(segment
		(start 383.217928 -242.320064)
		(end 383.68478 -242.054126)
		(width 0.12954)
		(layer "F.Cu")
		(net "M_H_CPU0_SA_DQS_DN<3>")
	)
	(segment
		(start 390.44499 -241.72418)
		(end 390.453372 -241.729006)
		(width 0.09525)
		(layer "In13.Cu")
		(net "M_H_CPU0_SA_DQS_DN<3>")
	)
	(segment
		(start 387.256274 -241.729006)
		(end 387.264656 -241.72418)
		(width 0.09525)
		(layer "In13.Cu")
		(net "M_H_CPU0_SA_DQS_DN<3>")
	)
	(segment
		(start 395.852142 -240.59896)
		(end 399.74393 -240.59896)
		(width 0.16002)
		(layer "In13.Cu")
		(net "M_H_CPU0_SA_DQS_DN<3>")
	)
	(segment
		(start 395.82852 -240.59896)
		(end 395.852142 -240.59896)
		(width 0.09525)
		(layer "In13.Cu")
		(net "M_H_CPU0_SA_DQS_DN<3>")
	)
	(segment
		(start 394.813028 -241.10696)
		(end 395.379956 -240.540032)
		(width 0.09525)
		(layer "In13.Cu")
		(net "M_H_CPU0_SA_DQS_DN<3>")
	)
	(segment
		(start 383.838704 -241.788696)
		(end 383.939542 -241.762026)
		(width 0.09525)
		(layer "In13.Cu")
		(net "M_H_CPU0_SA_DQS_DN<3>")
	)
	(segment
		(start 395.769592 -240.540032)
		(end 395.82852 -240.59896)
		(width 0.09525)
		(layer "In13.Cu")
		(net "M_H_CPU0_SA_DQS_DN<3>")
	)
	(segment
		(start 420.383462 -229.21214)
		(end 420.739316 -229.567994)
		(width 0.16002)
		(layer "In13.Cu")
		(net "M_H_CPU0_SA_DQS_DN<3>")
	)
	(segment
		(start 393.810744 -241.677698)
		(end 394.381482 -241.10696)
		(width 0.09525)
		(layer "In13.Cu")
		(net "M_H_CPU0_SA_DQS_DN<3>")
	)
	(segment
		(start 414.9471 -228.681534)
		(end 417.945316 -228.681534)
		(width 0.16002)
		(layer "In13.Cu")
		(net "M_H_CPU0_SA_DQS_DN<3>")
	)
	(segment
		(start 399.74393 -240.59896)
		(end 406.290018 -234.052872)
		(width 0.16002)
		(layer "In13.Cu")
		(net "M_H_CPU0_SA_DQS_DN<3>")
	)
	(segment
		(start 385.744974 -241.72418)
		(end 385.753356 -241.729006)
		(width 0.09525)
		(layer "In13.Cu")
		(net "M_H_CPU0_SA_DQS_DN<3>")
	)
	(segment
		(start 386.685028 -241.72418)
		(end 386.69341 -241.729006)
		(width 0.09525)
		(layer "In13.Cu")
		(net "M_H_CPU0_SA_DQS_DN<3>")
	)
	(segment
		(start 391.393426 -241.729006)
		(end 391.40384 -241.735102)
		(width 0.09525)
		(layer "In13.Cu")
		(net "M_H_CPU0_SA_DQS_DN<3>")
	)
	(segment
		(start 420.739316 -229.567994)
		(end 421.570912 -229.567994)
		(width 0.16002)
		(layer "In13.Cu")
		(net "M_H_CPU0_SA_DQS_DN<3>")
	)
	(segment
		(start 392.32586 -241.72418)
		(end 392.334242 -241.729006)
		(width 0.09525)
		(layer "In13.Cu")
		(net "M_H_CPU0_SA_DQS_DN<3>")
	)
	(segment
		(start 423.72661 -229.349554)
		(end 424.012106 -229.63505)
		(width 0.16002)
		(layer "In13.Cu")
		(net "M_H_CPU0_SA_DQS_DN<3>")
	)
	(segment
		(start 418.475922 -229.21214)
		(end 420.383462 -229.21214)
		(width 0.16002)
		(layer "In13.Cu")
		(net "M_H_CPU0_SA_DQS_DN<3>")
	)
	(segment
		(start 388.196328 -241.729006)
		(end 388.20471 -241.72418)
		(width 0.09525)
		(layer "In13.Cu")
		(net "M_H_CPU0_SA_DQS_DN<3>")
	)
	(segment
		(start 395.379956 -240.540032)
		(end 395.769592 -240.540032)
		(width 0.09525)
		(layer "In13.Cu")
		(net "M_H_CPU0_SA_DQS_DN<3>")
	)
	(segment
		(start 410.302964 -229.555294)
		(end 414.07334 -229.555294)
		(width 0.16002)
		(layer "In13.Cu")
		(net "M_H_CPU0_SA_DQS_DN<3>")
	)
	(segment
		(start 383.68478 -242.054126)
		(end 383.838704 -241.788696)
		(width 0.09525)
		(layer "In13.Cu")
		(net "M_H_CPU0_SA_DQS_DN<3>")
	)
	(segment
		(start 406.290018 -234.052872)
		(end 406.290018 -233.56824)
		(width 0.16002)
		(layer "In13.Cu")
		(net "M_H_CPU0_SA_DQS_DN<3>")
	)
	(segment
		(start 406.290018 -233.56824)
		(end 410.302964 -229.555294)
		(width 0.16002)
		(layer "In13.Cu")
		(net "M_H_CPU0_SA_DQS_DN<3>")
	)
	(segment
		(start 421.570912 -229.567994)
		(end 421.789352 -229.349554)
		(width 0.16002)
		(layer "In13.Cu")
		(net "M_H_CPU0_SA_DQS_DN<3>")
	)
	(segment
		(start 421.789352 -229.349554)
		(end 423.72661 -229.349554)
		(width 0.16002)
		(layer "In13.Cu")
		(net "M_H_CPU0_SA_DQS_DN<3>")
	)
	(segment
		(start 394.381482 -241.10696)
		(end 394.813028 -241.10696)
		(width 0.09525)
		(layer "In13.Cu")
		(net "M_H_CPU0_SA_DQS_DN<3>")
	)
	(segment
		(start 391.016236 -241.729006)
		(end 391.024618 -241.72418)
		(width 0.09525)
		(layer "In13.Cu")
		(net "M_H_CPU0_SA_DQS_DN<3>")
	)
	(segment
		(start 417.945316 -228.681534)
		(end 418.475922 -229.21214)
		(width 0.16002)
		(layer "In13.Cu")
		(net "M_H_CPU0_SA_DQS_DN<3>")
	)
	(segment
		(start 414.07334 -229.555294)
		(end 414.9471 -228.681534)
		(width 0.16002)
		(layer "In13.Cu")
		(net "M_H_CPU0_SA_DQS_DN<3>")
	)
	(segment
		(start 393.084812 -241.677698)
		(end 393.810744 -241.677698)
		(width 0.09525)
		(layer "In13.Cu")
		(net "M_H_CPU0_SA_DQS_DN<3>")
	)
	(arc
		(start 392.334242 -241.729006)
		(mid 392.606916 -241.804693)
		(end 392.881866 -241.737642)
		(width 0.09525)
		(layer "In13.Cu")
		(net "M_H_CPU0_SA_DQS_DN<3>")
	)
	(arc
		(start 392.881866 -241.737642)
		(mid 392.979038 -241.693111)
		(end 393.084812 -241.677698)
		(width 0.09525)
		(layer "In13.Cu")
		(net "M_H_CPU0_SA_DQS_DN<3>")
	)
	(arc
		(start 385.376166 -241.729006)
		(mid 385.559941 -241.678234)
		(end 385.744974 -241.72418)
		(width 0.09525)
		(layer "In13.Cu")
		(net "M_H_CPU0_SA_DQS_DN<3>")
	)
	(arc
		(start 386.31622 -241.729006)
		(mid 386.499995 -241.678234)
		(end 386.685028 -241.72418)
		(width 0.09525)
		(layer "In13.Cu")
		(net "M_H_CPU0_SA_DQS_DN<3>")
	)
	(arc
		(start 384.813302 -241.729006)
		(mid 385.094734 -241.804761)
		(end 385.376166 -241.729006)
		(width 0.09525)
		(layer "In13.Cu")
		(net "M_H_CPU0_SA_DQS_DN<3>")
	)
	(arc
		(start 389.513318 -241.729006)
		(mid 389.79475 -241.804761)
		(end 390.076182 -241.729006)
		(width 0.09525)
		(layer "In13.Cu")
		(net "M_H_CPU0_SA_DQS_DN<3>")
	)
	(arc
		(start 387.633464 -241.729006)
		(mid 387.914896 -241.804761)
		(end 388.196328 -241.729006)
		(width 0.09525)
		(layer "In13.Cu")
		(net "M_H_CPU0_SA_DQS_DN<3>")
	)
	(arc
		(start 389.136382 -241.729006)
		(mid 389.32485 -241.678329)
		(end 389.513318 -241.729006)
		(width 0.09525)
		(layer "In13.Cu")
		(net "M_H_CPU0_SA_DQS_DN<3>")
	)
	(arc
		(start 386.69341 -241.729006)
		(mid 386.974842 -241.804761)
		(end 387.256274 -241.729006)
		(width 0.09525)
		(layer "In13.Cu")
		(net "M_H_CPU0_SA_DQS_DN<3>")
	)
	(arc
		(start 388.573518 -241.729006)
		(mid 388.85495 -241.804761)
		(end 389.136382 -241.729006)
		(width 0.09525)
		(layer "In13.Cu")
		(net "M_H_CPU0_SA_DQS_DN<3>")
	)
	(arc
		(start 388.20471 -241.72418)
		(mid 388.389742 -241.678266)
		(end 388.573518 -241.729006)
		(width 0.09525)
		(layer "In13.Cu")
		(net "M_H_CPU0_SA_DQS_DN<3>")
	)
	(arc
		(start 384.436366 -241.729006)
		(mid 384.624834 -241.678329)
		(end 384.813302 -241.729006)
		(width 0.09525)
		(layer "In13.Cu")
		(net "M_H_CPU0_SA_DQS_DN<3>")
	)
	(arc
		(start 391.024618 -241.72418)
		(mid 391.20965 -241.678266)
		(end 391.393426 -241.729006)
		(width 0.09525)
		(layer "In13.Cu")
		(net "M_H_CPU0_SA_DQS_DN<3>")
	)
	(arc
		(start 385.753356 -241.729006)
		(mid 386.034788 -241.804761)
		(end 386.31622 -241.729006)
		(width 0.09525)
		(layer "In13.Cu")
		(net "M_H_CPU0_SA_DQS_DN<3>")
	)
	(arc
		(start 383.939542 -241.762026)
		(mid 383.94979 -241.766189)
		(end 383.960116 -241.770154)
		(width 0.09525)
		(layer "In13.Cu")
		(net "M_H_CPU0_SA_DQS_DN<3>")
	)
	(arc
		(start 383.960116 -241.770154)
		(mid 384.202858 -241.802924)
		(end 384.436366 -241.729006)
		(width 0.09525)
		(layer "In13.Cu")
		(net "M_H_CPU0_SA_DQS_DN<3>")
	)
	(arc
		(start 387.264656 -241.72418)
		(mid 387.449688 -241.678266)
		(end 387.633464 -241.729006)
		(width 0.09525)
		(layer "In13.Cu")
		(net "M_H_CPU0_SA_DQS_DN<3>")
	)
	(arc
		(start 390.076182 -241.729006)
		(mid 390.259957 -241.678234)
		(end 390.44499 -241.72418)
		(width 0.09525)
		(layer "In13.Cu")
		(net "M_H_CPU0_SA_DQS_DN<3>")
	)
	(arc
		(start 391.956544 -241.729006)
		(mid 392.140573 -241.678107)
		(end 392.32586 -241.72418)
		(width 0.09525)
		(layer "In13.Cu")
		(net "M_H_CPU0_SA_DQS_DN<3>")
	)
	(arc
		(start 391.40384 -241.735102)
		(mid 391.681002 -241.804902)
		(end 391.956544 -241.729006)
		(width 0.09525)
		(layer "In13.Cu")
		(net "M_H_CPU0_SA_DQS_DN<3>")
	)
	(arc
		(start 390.453372 -241.729006)
		(mid 390.734804 -241.804761)
		(end 391.016236 -241.729006)
		(width 0.09525)
		(layer "In13.Cu")
		(net "M_H_CPU0_SA_DQS_DN<3>")
	)
	(segment
		(start 383.217928 -237.460028)
		(end 383.68478 -237.19409)
		(width 0.12954)
		(layer "F.Cu")
		(net "M_H_CPU0_SA_DQS_DN<2>")
	)
	(segment
		(start 395.766798 -234.810554)
		(end 395.825726 -234.869482)
		(width 0.09525)
		(layer "In13.Cu")
		(net "M_H_CPU0_SA_DQS_DN<2>")
	)
	(segment
		(start 396.975076 -234.869482)
		(end 403.426422 -228.418136)
		(width 0.16002)
		(layer "In13.Cu")
		(net "M_H_CPU0_SA_DQS_DN<2>")
	)
	(segment
		(start 394.888466 -235.665772)
		(end 395.596364 -234.810554)
		(width 0.09525)
		(layer "In13.Cu")
		(net "M_H_CPU0_SA_DQS_DN<2>")
	)
	(segment
		(start 408.451812 -220.98254)
		(end 410.393134 -220.98254)
		(width 0.16002)
		(layer "In13.Cu")
		(net "M_H_CPU0_SA_DQS_DN<2>")
	)
	(segment
		(start 420.739316 -220.218)
		(end 421.570912 -220.218)
		(width 0.16002)
		(layer "In13.Cu")
		(net "M_H_CPU0_SA_DQS_DN<2>")
	)
	(segment
		(start 413.10814 -220.2053)
		(end 414.07334 -220.2053)
		(width 0.16002)
		(layer "In13.Cu")
		(net "M_H_CPU0_SA_DQS_DN<2>")
	)
	(segment
		(start 418.475922 -219.862146)
		(end 420.383462 -219.862146)
		(width 0.16002)
		(layer "In13.Cu")
		(net "M_H_CPU0_SA_DQS_DN<2>")
	)
	(segment
		(start 386.685028 -236.864144)
		(end 386.69341 -236.86897)
		(width 0.09525)
		(layer "In13.Cu")
		(net "M_H_CPU0_SA_DQS_DN<2>")
	)
	(segment
		(start 393.369038 -236.813852)
		(end 394.517118 -235.665772)
		(width 0.09525)
		(layer "In13.Cu")
		(net "M_H_CPU0_SA_DQS_DN<2>")
	)
	(segment
		(start 395.849348 -234.869482)
		(end 396.975076 -234.869482)
		(width 0.16002)
		(layer "In13.Cu")
		(net "M_H_CPU0_SA_DQS_DN<2>")
	)
	(segment
		(start 387.256274 -236.86897)
		(end 387.264656 -236.864144)
		(width 0.09525)
		(layer "In13.Cu")
		(net "M_H_CPU0_SA_DQS_DN<2>")
	)
	(segment
		(start 383.68478 -237.19409)
		(end 383.838704 -236.92866)
		(width 0.09525)
		(layer "In13.Cu")
		(net "M_H_CPU0_SA_DQS_DN<2>")
	)
	(segment
		(start 403.426422 -228.418136)
		(end 403.426422 -226.00793)
		(width 0.16002)
		(layer "In13.Cu")
		(net "M_H_CPU0_SA_DQS_DN<2>")
	)
	(segment
		(start 420.383462 -219.862146)
		(end 420.739316 -220.218)
		(width 0.16002)
		(layer "In13.Cu")
		(net "M_H_CPU0_SA_DQS_DN<2>")
	)
	(segment
		(start 395.825726 -234.869482)
		(end 395.849348 -234.869482)
		(width 0.09525)
		(layer "In13.Cu")
		(net "M_H_CPU0_SA_DQS_DN<2>")
	)
	(segment
		(start 385.744974 -236.864144)
		(end 385.753356 -236.86897)
		(width 0.09525)
		(layer "In13.Cu")
		(net "M_H_CPU0_SA_DQS_DN<2>")
	)
	(segment
		(start 417.945316 -219.33154)
		(end 418.475922 -219.862146)
		(width 0.16002)
		(layer "In13.Cu")
		(net "M_H_CPU0_SA_DQS_DN<2>")
	)
	(segment
		(start 393.042394 -236.813852)
		(end 393.369038 -236.813852)
		(width 0.09525)
		(layer "In13.Cu")
		(net "M_H_CPU0_SA_DQS_DN<2>")
	)
	(segment
		(start 414.07334 -220.2053)
		(end 414.9471 -219.33154)
		(width 0.16002)
		(layer "In13.Cu")
		(net "M_H_CPU0_SA_DQS_DN<2>")
	)
	(segment
		(start 422.20134 -219.587572)
		(end 422.632378 -219.587572)
		(width 0.16002)
		(layer "In13.Cu")
		(net "M_H_CPU0_SA_DQS_DN<2>")
	)
	(segment
		(start 423.04716 -220.002354)
		(end 423.729404 -220.002354)
		(width 0.16002)
		(layer "In13.Cu")
		(net "M_H_CPU0_SA_DQS_DN<2>")
	)
	(segment
		(start 394.517118 -235.665772)
		(end 394.888466 -235.665772)
		(width 0.09525)
		(layer "In13.Cu")
		(net "M_H_CPU0_SA_DQS_DN<2>")
	)
	(segment
		(start 410.393134 -220.98254)
		(end 411.493462 -219.882212)
		(width 0.16002)
		(layer "In13.Cu")
		(net "M_H_CPU0_SA_DQS_DN<2>")
	)
	(segment
		(start 383.838704 -236.92866)
		(end 383.939542 -236.90199)
		(width 0.09525)
		(layer "In13.Cu")
		(net "M_H_CPU0_SA_DQS_DN<2>")
	)
	(segment
		(start 390.44499 -236.864144)
		(end 390.453372 -236.86897)
		(width 0.09525)
		(layer "In13.Cu")
		(net "M_H_CPU0_SA_DQS_DN<2>")
	)
	(segment
		(start 388.196328 -236.86897)
		(end 388.20471 -236.864144)
		(width 0.09525)
		(layer "In13.Cu")
		(net "M_H_CPU0_SA_DQS_DN<2>")
	)
	(segment
		(start 421.570912 -220.218)
		(end 422.20134 -219.587572)
		(width 0.16002)
		(layer "In13.Cu")
		(net "M_H_CPU0_SA_DQS_DN<2>")
	)
	(segment
		(start 412.785052 -219.882212)
		(end 413.10814 -220.2053)
		(width 0.16002)
		(layer "In13.Cu")
		(net "M_H_CPU0_SA_DQS_DN<2>")
	)
	(segment
		(start 422.632378 -219.587572)
		(end 423.04716 -220.002354)
		(width 0.16002)
		(layer "In13.Cu")
		(net "M_H_CPU0_SA_DQS_DN<2>")
	)
	(segment
		(start 403.426422 -226.00793)
		(end 408.451812 -220.98254)
		(width 0.16002)
		(layer "In13.Cu")
		(net "M_H_CPU0_SA_DQS_DN<2>")
	)
	(segment
		(start 395.596364 -234.810554)
		(end 395.766798 -234.810554)
		(width 0.09525)
		(layer "In13.Cu")
		(net "M_H_CPU0_SA_DQS_DN<2>")
	)
	(segment
		(start 411.493462 -219.882212)
		(end 412.785052 -219.882212)
		(width 0.16002)
		(layer "In13.Cu")
		(net "M_H_CPU0_SA_DQS_DN<2>")
	)
	(segment
		(start 423.729404 -220.002354)
		(end 424.012106 -220.285056)
		(width 0.16002)
		(layer "In13.Cu")
		(net "M_H_CPU0_SA_DQS_DN<2>")
	)
	(segment
		(start 414.9471 -219.33154)
		(end 417.945316 -219.33154)
		(width 0.16002)
		(layer "In13.Cu")
		(net "M_H_CPU0_SA_DQS_DN<2>")
	)
	(arc
		(start 389.136382 -236.86897)
		(mid 389.32485 -236.818293)
		(end 389.513318 -236.86897)
		(width 0.09525)
		(layer "In13.Cu")
		(net "M_H_CPU0_SA_DQS_DN<2>")
	)
	(arc
		(start 384.813302 -236.86897)
		(mid 385.094734 -236.944725)
		(end 385.376166 -236.86897)
		(width 0.09525)
		(layer "In13.Cu")
		(net "M_H_CPU0_SA_DQS_DN<2>")
	)
	(arc
		(start 388.573518 -236.86897)
		(mid 388.85495 -236.944725)
		(end 389.136382 -236.86897)
		(width 0.09525)
		(layer "In13.Cu")
		(net "M_H_CPU0_SA_DQS_DN<2>")
	)
	(arc
		(start 385.376166 -236.86897)
		(mid 385.559941 -236.818198)
		(end 385.744974 -236.864144)
		(width 0.09525)
		(layer "In13.Cu")
		(net "M_H_CPU0_SA_DQS_DN<2>")
	)
	(arc
		(start 391.41527 -236.874812)
		(mid 391.686241 -236.924588)
		(end 391.956798 -236.872526)
		(width 0.09525)
		(layer "In13.Cu")
		(net "M_H_CPU0_SA_DQS_DN<2>")
	)
	(arc
		(start 390.076182 -236.86897)
		(mid 390.259957 -236.818198)
		(end 390.44499 -236.864144)
		(width 0.09525)
		(layer "In13.Cu")
		(net "M_H_CPU0_SA_DQS_DN<2>")
	)
	(arc
		(start 390.453372 -236.86897)
		(mid 390.711116 -236.944224)
		(end 390.974326 -236.891068)
		(width 0.09525)
		(layer "In13.Cu")
		(net "M_H_CPU0_SA_DQS_DN<2>")
	)
	(arc
		(start 385.753356 -236.86897)
		(mid 386.034788 -236.944725)
		(end 386.31622 -236.86897)
		(width 0.09525)
		(layer "In13.Cu")
		(net "M_H_CPU0_SA_DQS_DN<2>")
	)
	(arc
		(start 388.20471 -236.864144)
		(mid 388.389742 -236.81823)
		(end 388.573518 -236.86897)
		(width 0.09525)
		(layer "In13.Cu")
		(net "M_H_CPU0_SA_DQS_DN<2>")
	)
	(arc
		(start 390.974326 -236.891068)
		(mid 391.193136 -236.837718)
		(end 391.41527 -236.874812)
		(width 0.09525)
		(layer "In13.Cu")
		(net "M_H_CPU0_SA_DQS_DN<2>")
	)
	(arc
		(start 387.633464 -236.86897)
		(mid 387.914896 -236.944725)
		(end 388.196328 -236.86897)
		(width 0.09525)
		(layer "In13.Cu")
		(net "M_H_CPU0_SA_DQS_DN<2>")
	)
	(arc
		(start 392.323574 -236.856524)
		(mid 392.659985 -236.897356)
		(end 392.990832 -236.824012)
		(width 0.09525)
		(layer "In13.Cu")
		(net "M_H_CPU0_SA_DQS_DN<2>")
	)
	(arc
		(start 386.31622 -236.86897)
		(mid 386.499995 -236.818198)
		(end 386.685028 -236.864144)
		(width 0.09525)
		(layer "In13.Cu")
		(net "M_H_CPU0_SA_DQS_DN<2>")
	)
	(arc
		(start 392.990832 -236.824012)
		(mid 393.016113 -236.816386)
		(end 393.042394 -236.813852)
		(width 0.09525)
		(layer "In13.Cu")
		(net "M_H_CPU0_SA_DQS_DN<2>")
	)
	(arc
		(start 384.436366 -236.86897)
		(mid 384.624834 -236.818293)
		(end 384.813302 -236.86897)
		(width 0.09525)
		(layer "In13.Cu")
		(net "M_H_CPU0_SA_DQS_DN<2>")
	)
	(arc
		(start 383.960116 -236.910118)
		(mid 384.202858 -236.942888)
		(end 384.436366 -236.86897)
		(width 0.09525)
		(layer "In13.Cu")
		(net "M_H_CPU0_SA_DQS_DN<2>")
	)
	(arc
		(start 383.939542 -236.90199)
		(mid 383.94979 -236.906153)
		(end 383.960116 -236.910118)
		(width 0.09525)
		(layer "In13.Cu")
		(net "M_H_CPU0_SA_DQS_DN<2>")
	)
	(arc
		(start 386.69341 -236.86897)
		(mid 386.974842 -236.944725)
		(end 387.256274 -236.86897)
		(width 0.09525)
		(layer "In13.Cu")
		(net "M_H_CPU0_SA_DQS_DN<2>")
	)
	(arc
		(start 391.956798 -236.872526)
		(mid 392.13884 -236.833642)
		(end 392.323574 -236.856524)
		(width 0.09525)
		(layer "In13.Cu")
		(net "M_H_CPU0_SA_DQS_DN<2>")
	)
	(arc
		(start 389.513318 -236.86897)
		(mid 389.79475 -236.944725)
		(end 390.076182 -236.86897)
		(width 0.09525)
		(layer "In13.Cu")
		(net "M_H_CPU0_SA_DQS_DN<2>")
	)
	(arc
		(start 387.264656 -236.864144)
		(mid 387.449688 -236.81823)
		(end 387.633464 -236.86897)
		(width 0.09525)
		(layer "In13.Cu")
		(net "M_H_CPU0_SA_DQS_DN<2>")
	)
	(segment
		(start 383.217928 -232.599992)
		(end 383.68478 -232.334054)
		(width 0.12954)
		(layer "F.Cu")
		(net "M_H_CPU0_SA_DQS_DN<1>")
	)
	(segment
		(start 390.446006 -232.004616)
		(end 390.44499 -232.004108)
		(width 0.09525)
		(layer "In13.Cu")
		(net "M_H_CPU0_SA_DQS_DN<1>")
	)
	(segment
		(start 390.453372 -232.008934)
		(end 390.446006 -232.004616)
		(width 0.09525)
		(layer "In13.Cu")
		(net "M_H_CPU0_SA_DQS_DN<1>")
	)
	(segment
		(start 397.889222 -221.817438)
		(end 397.889222 -225.450654)
		(width 0.16002)
		(layer "In13.Cu")
		(net "M_H_CPU0_SA_DQS_DN<1>")
	)
	(segment
		(start 392.966702 -230.3018)
		(end 392.584686 -230.683816)
		(width 0.09525)
		(layer "In13.Cu")
		(net "M_H_CPU0_SA_DQS_DN<1>")
	)
	(segment
		(start 385.753356 -232.008934)
		(end 385.744974 -232.004108)
		(width 0.09525)
		(layer "In13.Cu")
		(net "M_H_CPU0_SA_DQS_DN<1>")
	)
	(segment
		(start 397.889222 -225.450654)
		(end 395.597126 -227.74275)
		(width 0.16002)
		(layer "In13.Cu")
		(net "M_H_CPU0_SA_DQS_DN<1>")
	)
	(segment
		(start 423.734738 -210.657694)
		(end 421.781224 -210.657694)
		(width 0.16002)
		(layer "In13.Cu")
		(net "M_H_CPU0_SA_DQS_DN<1>")
	)
	(segment
		(start 386.69341 -232.008934)
		(end 386.685028 -232.004108)
		(width 0.09525)
		(layer "In13.Cu")
		(net "M_H_CPU0_SA_DQS_DN<1>")
	)
	(segment
		(start 417.945316 -209.981546)
		(end 414.9471 -209.981546)
		(width 0.16002)
		(layer "In13.Cu")
		(net "M_H_CPU0_SA_DQS_DN<1>")
	)
	(segment
		(start 412.914338 -210.550252)
		(end 409.156408 -210.550252)
		(width 0.16002)
		(layer "In13.Cu")
		(net "M_H_CPU0_SA_DQS_DN<1>")
	)
	(segment
		(start 391.956036 -232.008934)
		(end 391.945622 -232.01503)
		(width 0.09525)
		(layer "In13.Cu")
		(net "M_H_CPU0_SA_DQS_DN<1>")
	)
	(segment
		(start 409.156408 -210.550252)
		(end 397.889222 -221.817438)
		(width 0.16002)
		(layer "In13.Cu")
		(net "M_H_CPU0_SA_DQS_DN<1>")
	)
	(segment
		(start 421.781224 -210.657694)
		(end 421.570912 -210.868006)
		(width 0.16002)
		(layer "In13.Cu")
		(net "M_H_CPU0_SA_DQS_DN<1>")
	)
	(segment
		(start 395.194536 -228.431598)
		(end 393.324334 -230.3018)
		(width 0.09525)
		(layer "In13.Cu")
		(net "M_H_CPU0_SA_DQS_DN<1>")
	)
	(segment
		(start 413.219392 -210.855306)
		(end 412.914338 -210.550252)
		(width 0.16002)
		(layer "In13.Cu")
		(net "M_H_CPU0_SA_DQS_DN<1>")
	)
	(segment
		(start 395.194536 -228.062282)
		(end 395.194536 -228.431598)
		(width 0.09525)
		(layer "In13.Cu")
		(net "M_H_CPU0_SA_DQS_DN<1>")
	)
	(segment
		(start 395.597126 -227.74275)
		(end 395.580362 -227.759514)
		(width 0.09525)
		(layer "In13.Cu")
		(net "M_H_CPU0_SA_DQS_DN<1>")
	)
	(segment
		(start 393.324334 -230.3018)
		(end 392.966702 -230.3018)
		(width 0.09525)
		(layer "In13.Cu")
		(net "M_H_CPU0_SA_DQS_DN<1>")
	)
	(segment
		(start 392.584686 -231.4067)
		(end 392.071098 -231.920542)
		(width 0.09525)
		(layer "In13.Cu")
		(net "M_H_CPU0_SA_DQS_DN<1>")
	)
	(segment
		(start 421.570912 -210.868006)
		(end 420.739316 -210.868006)
		(width 0.16002)
		(layer "In13.Cu")
		(net "M_H_CPU0_SA_DQS_DN<1>")
	)
	(segment
		(start 395.580362 -227.759514)
		(end 395.497304 -227.759514)
		(width 0.09525)
		(layer "In13.Cu")
		(net "M_H_CPU0_SA_DQS_DN<1>")
	)
	(segment
		(start 392.584686 -230.683816)
		(end 392.584686 -231.4067)
		(width 0.09525)
		(layer "In13.Cu")
		(net "M_H_CPU0_SA_DQS_DN<1>")
	)
	(segment
		(start 395.497304 -227.759514)
		(end 395.194536 -228.062282)
		(width 0.09525)
		(layer "In13.Cu")
		(net "M_H_CPU0_SA_DQS_DN<1>")
	)
	(segment
		(start 420.739316 -210.868006)
		(end 420.383462 -210.512152)
		(width 0.16002)
		(layer "In13.Cu")
		(net "M_H_CPU0_SA_DQS_DN<1>")
	)
	(segment
		(start 388.20471 -232.004108)
		(end 388.196328 -232.008934)
		(width 0.09525)
		(layer "In13.Cu")
		(net "M_H_CPU0_SA_DQS_DN<1>")
	)
	(segment
		(start 391.024618 -232.004108)
		(end 391.016236 -232.008934)
		(width 0.09525)
		(layer "In13.Cu")
		(net "M_H_CPU0_SA_DQS_DN<1>")
	)
	(segment
		(start 383.939542 -232.041954)
		(end 383.838704 -232.068624)
		(width 0.09525)
		(layer "In13.Cu")
		(net "M_H_CPU0_SA_DQS_DN<1>")
	)
	(segment
		(start 383.838704 -232.068624)
		(end 383.68478 -232.334054)
		(width 0.09525)
		(layer "In13.Cu")
		(net "M_H_CPU0_SA_DQS_DN<1>")
	)
	(segment
		(start 418.475922 -210.512152)
		(end 417.945316 -209.981546)
		(width 0.16002)
		(layer "In13.Cu")
		(net "M_H_CPU0_SA_DQS_DN<1>")
	)
	(segment
		(start 414.07334 -210.855306)
		(end 413.219392 -210.855306)
		(width 0.16002)
		(layer "In13.Cu")
		(net "M_H_CPU0_SA_DQS_DN<1>")
	)
	(segment
		(start 387.264656 -232.004108)
		(end 387.256274 -232.008934)
		(width 0.09525)
		(layer "In13.Cu")
		(net "M_H_CPU0_SA_DQS_DN<1>")
	)
	(segment
		(start 424.012106 -210.935062)
		(end 423.734738 -210.657694)
		(width 0.16002)
		(layer "In13.Cu")
		(net "M_H_CPU0_SA_DQS_DN<1>")
	)
	(segment
		(start 420.383462 -210.512152)
		(end 418.475922 -210.512152)
		(width 0.16002)
		(layer "In13.Cu")
		(net "M_H_CPU0_SA_DQS_DN<1>")
	)
	(segment
		(start 414.9471 -209.981546)
		(end 414.07334 -210.855306)
		(width 0.16002)
		(layer "In13.Cu")
		(net "M_H_CPU0_SA_DQS_DN<1>")
	)
	(arc
		(start 390.44499 -232.004108)
		(mid 390.259958 -231.958194)
		(end 390.076182 -232.008934)
		(width 0.09525)
		(layer "In13.Cu")
		(net "M_H_CPU0_SA_DQS_DN<1>")
	)
	(arc
		(start 384.436366 -232.008934)
		(mid 384.202852 -232.082777)
		(end 383.960116 -232.050082)
		(width 0.09525)
		(layer "In13.Cu")
		(net "M_H_CPU0_SA_DQS_DN<1>")
	)
	(arc
		(start 389.136382 -232.008934)
		(mid 388.85495 -232.084689)
		(end 388.573518 -232.008934)
		(width 0.09525)
		(layer "In13.Cu")
		(net "M_H_CPU0_SA_DQS_DN<1>")
	)
	(arc
		(start 383.960116 -232.050082)
		(mid 383.949788 -232.046122)
		(end 383.939542 -232.041954)
		(width 0.09525)
		(layer "In13.Cu")
		(net "M_H_CPU0_SA_DQS_DN<1>")
	)
	(arc
		(start 388.196328 -232.008934)
		(mid 387.914896 -232.084689)
		(end 387.633464 -232.008934)
		(width 0.09525)
		(layer "In13.Cu")
		(net "M_H_CPU0_SA_DQS_DN<1>")
	)
	(arc
		(start 387.256274 -232.008934)
		(mid 386.974842 -232.084689)
		(end 386.69341 -232.008934)
		(width 0.09525)
		(layer "In13.Cu")
		(net "M_H_CPU0_SA_DQS_DN<1>")
	)
	(arc
		(start 391.393426 -232.008934)
		(mid 391.209651 -231.958162)
		(end 391.024618 -232.004108)
		(width 0.09525)
		(layer "In13.Cu")
		(net "M_H_CPU0_SA_DQS_DN<1>")
	)
	(arc
		(start 386.685028 -232.004108)
		(mid 386.499996 -231.958194)
		(end 386.31622 -232.008934)
		(width 0.09525)
		(layer "In13.Cu")
		(net "M_H_CPU0_SA_DQS_DN<1>")
	)
	(arc
		(start 385.744974 -232.004108)
		(mid 385.559942 -231.958194)
		(end 385.376166 -232.008934)
		(width 0.09525)
		(layer "In13.Cu")
		(net "M_H_CPU0_SA_DQS_DN<1>")
	)
	(arc
		(start 385.376166 -232.008934)
		(mid 385.094734 -232.084689)
		(end 384.813302 -232.008934)
		(width 0.09525)
		(layer "In13.Cu")
		(net "M_H_CPU0_SA_DQS_DN<1>")
	)
	(arc
		(start 391.945622 -232.01503)
		(mid 391.668714 -232.084707)
		(end 391.393426 -232.008934)
		(width 0.09525)
		(layer "In13.Cu")
		(net "M_H_CPU0_SA_DQS_DN<1>")
	)
	(arc
		(start 386.31622 -232.008934)
		(mid 386.034788 -232.084689)
		(end 385.753356 -232.008934)
		(width 0.09525)
		(layer "In13.Cu")
		(net "M_H_CPU0_SA_DQS_DN<1>")
	)
	(arc
		(start 392.064748 -231.926892)
		(mid 392.012899 -231.971236)
		(end 391.956036 -232.008934)
		(width 0.09525)
		(layer "In13.Cu")
		(net "M_H_CPU0_SA_DQS_DN<1>")
	)
	(arc
		(start 389.513318 -232.008934)
		(mid 389.32485 -231.958257)
		(end 389.136382 -232.008934)
		(width 0.09525)
		(layer "In13.Cu")
		(net "M_H_CPU0_SA_DQS_DN<1>")
	)
	(arc
		(start 388.573518 -232.008934)
		(mid 388.389743 -231.958162)
		(end 388.20471 -232.004108)
		(width 0.09525)
		(layer "In13.Cu")
		(net "M_H_CPU0_SA_DQS_DN<1>")
	)
	(arc
		(start 390.076182 -232.008934)
		(mid 389.79475 -232.084689)
		(end 389.513318 -232.008934)
		(width 0.09525)
		(layer "In13.Cu")
		(net "M_H_CPU0_SA_DQS_DN<1>")
	)
	(arc
		(start 392.071098 -231.920542)
		(mid 392.067936 -231.92373)
		(end 392.064748 -231.926892)
		(width 0.09525)
		(layer "In13.Cu")
		(net "M_H_CPU0_SA_DQS_DN<1>")
	)
	(arc
		(start 387.633464 -232.008934)
		(mid 387.449689 -231.958162)
		(end 387.264656 -232.004108)
		(width 0.09525)
		(layer "In13.Cu")
		(net "M_H_CPU0_SA_DQS_DN<1>")
	)
	(arc
		(start 391.016236 -232.008934)
		(mid 390.734804 -232.084689)
		(end 390.453372 -232.008934)
		(width 0.09525)
		(layer "In13.Cu")
		(net "M_H_CPU0_SA_DQS_DN<1>")
	)
	(arc
		(start 384.813302 -232.008934)
		(mid 384.624834 -231.958257)
		(end 384.436366 -232.008934)
		(width 0.09525)
		(layer "In13.Cu")
		(net "M_H_CPU0_SA_DQS_DN<1>")
	)
	(segment
		(start 383.217928 -227.74021)
		(end 383.68478 -227.474272)
		(width 0.12954)
		(layer "F.Cu")
		(net "M_H_CPU0_SA_DQS_DN<0>")
	)
	(segment
		(start 386.69341 -227.149152)
		(end 386.685028 -227.144326)
		(width 0.09525)
		(layer "In13.Cu")
		(net "M_H_CPU0_SA_DQS_DN<0>")
	)
	(segment
		(start 383.939542 -227.182172)
		(end 383.838704 -227.208842)
		(width 0.09525)
		(layer "In13.Cu")
		(net "M_H_CPU0_SA_DQS_DN<0>")
	)
	(segment
		(start 424.012106 -201.585068)
		(end 423.737532 -201.310494)
		(width 0.16002)
		(layer "In13.Cu")
		(net "M_H_CPU0_SA_DQS_DN<0>")
	)
	(segment
		(start 407.725372 -201.891392)
		(end 398.939258 -210.677506)
		(width 0.16002)
		(layer "In13.Cu")
		(net "M_H_CPU0_SA_DQS_DN<0>")
	)
	(segment
		(start 392.296142 -221.17431)
		(end 392.296142 -221.197932)
		(width 0.09525)
		(layer "In13.Cu")
		(net "M_H_CPU0_SA_DQS_DN<0>")
	)
	(segment
		(start 391.524236 -223.077024)
		(end 391.45464 -223.11741)
		(width 0.09525)
		(layer "In13.Cu")
		(net "M_H_CPU0_SA_DQS_DN<0>")
	)
	(segment
		(start 385.753356 -227.149152)
		(end 385.744974 -227.144326)
		(width 0.09525)
		(layer "In13.Cu")
		(net "M_H_CPU0_SA_DQS_DN<0>")
	)
	(segment
		(start 420.739316 -201.518012)
		(end 420.383462 -201.162158)
		(width 0.16002)
		(layer "In13.Cu")
		(net "M_H_CPU0_SA_DQS_DN<0>")
	)
	(segment
		(start 392.236452 -221.257622)
		(end 392.236452 -221.803722)
		(width 0.09525)
		(layer "In13.Cu")
		(net "M_H_CPU0_SA_DQS_DN<0>")
	)
	(segment
		(start 390.114282 -225.507042)
		(end 390.044686 -225.547428)
		(width 0.09525)
		(layer "In13.Cu")
		(net "M_H_CPU0_SA_DQS_DN<0>")
	)
	(segment
		(start 412.78175 -201.891392)
		(end 410.23667 -201.891392)
		(width 0.16002)
		(layer "In13.Cu")
		(net "M_H_CPU0_SA_DQS_DN<0>")
	)
	(segment
		(start 389.171434 -227.128578)
		(end 389.136382 -227.149152)
		(width 0.09525)
		(layer "In13.Cu")
		(net "M_H_CPU0_SA_DQS_DN<0>")
	)
	(segment
		(start 414.07334 -201.505312)
		(end 413.16783 -201.505312)
		(width 0.16002)
		(layer "In13.Cu")
		(net "M_H_CPU0_SA_DQS_DN<0>")
	)
	(segment
		(start 421.77843 -201.310494)
		(end 421.570912 -201.518012)
		(width 0.16002)
		(layer "In13.Cu")
		(net "M_H_CPU0_SA_DQS_DN<0>")
	)
	(segment
		(start 388.20471 -227.144326)
		(end 388.196328 -227.149152)
		(width 0.09525)
		(layer "In13.Cu")
		(net "M_H_CPU0_SA_DQS_DN<0>")
	)
	(segment
		(start 418.475922 -201.162158)
		(end 417.945316 -200.631552)
		(width 0.16002)
		(layer "In13.Cu")
		(net "M_H_CPU0_SA_DQS_DN<0>")
	)
	(segment
		(start 410.23667 -201.891392)
		(end 409.899612 -201.554334)
		(width 0.16002)
		(layer "In13.Cu")
		(net "M_H_CPU0_SA_DQS_DN<0>")
	)
	(segment
		(start 387.264656 -227.144326)
		(end 387.256274 -227.149152)
		(width 0.09525)
		(layer "In13.Cu")
		(net "M_H_CPU0_SA_DQS_DN<0>")
	)
	(segment
		(start 422.537128 -201.450194)
		(end 422.397428 -201.310494)
		(width 0.16002)
		(layer "In13.Cu")
		(net "M_H_CPU0_SA_DQS_DN<0>")
	)
	(segment
		(start 414.9471 -200.631552)
		(end 414.07334 -201.505312)
		(width 0.16002)
		(layer "In13.Cu")
		(net "M_H_CPU0_SA_DQS_DN<0>")
	)
	(segment
		(start 423.154348 -201.310494)
		(end 423.014648 -201.450194)
		(width 0.16002)
		(layer "In13.Cu")
		(net "M_H_CPU0_SA_DQS_DN<0>")
	)
	(segment
		(start 409.739592 -201.223372)
		(end 409.391612 -201.223372)
		(width 0.16002)
		(layer "In13.Cu")
		(net "M_H_CPU0_SA_DQS_DN<0>")
	)
	(segment
		(start 383.838704 -227.208842)
		(end 383.68478 -227.474272)
		(width 0.09525)
		(layer "In13.Cu")
		(net "M_H_CPU0_SA_DQS_DN<0>")
	)
	(segment
		(start 409.899612 -201.554334)
		(end 409.899612 -201.383392)
		(width 0.16002)
		(layer "In13.Cu")
		(net "M_H_CPU0_SA_DQS_DN<0>")
	)
	(segment
		(start 398.939258 -210.677506)
		(end 398.939258 -211.37499)
		(width 0.16002)
		(layer "In13.Cu")
		(net "M_H_CPU0_SA_DQS_DN<0>")
	)
	(segment
		(start 423.737532 -201.310494)
		(end 423.154348 -201.310494)
		(width 0.16002)
		(layer "In13.Cu")
		(net "M_H_CPU0_SA_DQS_DN<0>")
	)
	(segment
		(start 409.231592 -201.383392)
		(end 409.231592 -201.554334)
		(width 0.16002)
		(layer "In13.Cu")
		(net "M_H_CPU0_SA_DQS_DN<0>")
	)
	(segment
		(start 421.570912 -201.518012)
		(end 420.739316 -201.518012)
		(width 0.16002)
		(layer "In13.Cu")
		(net "M_H_CPU0_SA_DQS_DN<0>")
	)
	(segment
		(start 389.644382 -226.317048)
		(end 389.57377 -226.357942)
		(width 0.09525)
		(layer "In13.Cu")
		(net "M_H_CPU0_SA_DQS_DN<0>")
	)
	(segment
		(start 392.296142 -221.197932)
		(end 392.236452 -221.257622)
		(width 0.09525)
		(layer "In13.Cu")
		(net "M_H_CPU0_SA_DQS_DN<0>")
	)
	(segment
		(start 391.054336 -223.88703)
		(end 390.983724 -223.927924)
		(width 0.09525)
		(layer "In13.Cu")
		(net "M_H_CPU0_SA_DQS_DN<0>")
	)
	(segment
		(start 423.014648 -201.450194)
		(end 422.537128 -201.450194)
		(width 0.16002)
		(layer "In13.Cu")
		(net "M_H_CPU0_SA_DQS_DN<0>")
	)
	(segment
		(start 413.16783 -201.505312)
		(end 412.78175 -201.891392)
		(width 0.16002)
		(layer "In13.Cu")
		(net "M_H_CPU0_SA_DQS_DN<0>")
	)
	(segment
		(start 408.894534 -201.891392)
		(end 407.725372 -201.891392)
		(width 0.16002)
		(layer "In13.Cu")
		(net "M_H_CPU0_SA_DQS_DN<0>")
	)
	(segment
		(start 417.945316 -200.631552)
		(end 414.9471 -200.631552)
		(width 0.16002)
		(layer "In13.Cu")
		(net "M_H_CPU0_SA_DQS_DN<0>")
	)
	(segment
		(start 409.899612 -201.383392)
		(end 409.739592 -201.223372)
		(width 0.16002)
		(layer "In13.Cu")
		(net "M_H_CPU0_SA_DQS_DN<0>")
	)
	(segment
		(start 409.231592 -201.554334)
		(end 408.894534 -201.891392)
		(width 0.16002)
		(layer "In13.Cu")
		(net "M_H_CPU0_SA_DQS_DN<0>")
	)
	(segment
		(start 390.581388 -224.69856)
		(end 390.513824 -224.73793)
		(width 0.09525)
		(layer "In13.Cu")
		(net "M_H_CPU0_SA_DQS_DN<0>")
	)
	(segment
		(start 420.383462 -201.162158)
		(end 418.475922 -201.162158)
		(width 0.16002)
		(layer "In13.Cu")
		(net "M_H_CPU0_SA_DQS_DN<0>")
	)
	(segment
		(start 398.939258 -211.37499)
		(end 392.296142 -218.018106)
		(width 0.16002)
		(layer "In13.Cu")
		(net "M_H_CPU0_SA_DQS_DN<0>")
	)
	(segment
		(start 391.995406 -222.266256)
		(end 391.92454 -222.307404)
		(width 0.09525)
		(layer "In13.Cu")
		(net "M_H_CPU0_SA_DQS_DN<0>")
	)
	(segment
		(start 392.236452 -221.803722)
		(end 392.23696 -221.80423)
		(width 0.09525)
		(layer "In13.Cu")
		(net "M_H_CPU0_SA_DQS_DN<0>")
	)
	(segment
		(start 422.397428 -201.310494)
		(end 421.77843 -201.310494)
		(width 0.16002)
		(layer "In13.Cu")
		(net "M_H_CPU0_SA_DQS_DN<0>")
	)
	(segment
		(start 409.391612 -201.223372)
		(end 409.231592 -201.383392)
		(width 0.16002)
		(layer "In13.Cu")
		(net "M_H_CPU0_SA_DQS_DN<0>")
	)
	(segment
		(start 392.296142 -218.018106)
		(end 392.296142 -221.17431)
		(width 0.16002)
		(layer "In13.Cu")
		(net "M_H_CPU0_SA_DQS_DN<0>")
	)
	(arc
		(start 391.92454 -222.307404)
		(mid 391.808742 -222.441798)
		(end 391.76706 -222.614236)
		(width 0.09525)
		(layer "In13.Cu")
		(net "M_H_CPU0_SA_DQS_DN<0>")
	)
	(arc
		(start 391.45464 -223.11741)
		(mid 391.338842 -223.251804)
		(end 391.29716 -223.424242)
		(width 0.09525)
		(layer "In13.Cu")
		(net "M_H_CPU0_SA_DQS_DN<0>")
	)
	(arc
		(start 390.513824 -224.73793)
		(mid 390.39855 -224.872208)
		(end 390.357106 -225.044254)
		(width 0.09525)
		(layer "In13.Cu")
		(net "M_H_CPU0_SA_DQS_DN<0>")
	)
	(arc
		(start 391.76706 -222.614236)
		(mid 391.702663 -222.875542)
		(end 391.524236 -223.077024)
		(width 0.09525)
		(layer "In13.Cu")
		(net "M_H_CPU0_SA_DQS_DN<0>")
	)
	(arc
		(start 387.256274 -227.149152)
		(mid 386.974842 -227.224907)
		(end 386.69341 -227.149152)
		(width 0.09525)
		(layer "In13.Cu")
		(net "M_H_CPU0_SA_DQS_DN<0>")
	)
	(arc
		(start 389.136382 -227.149152)
		(mid 388.85495 -227.224907)
		(end 388.573518 -227.149152)
		(width 0.09525)
		(layer "In13.Cu")
		(net "M_H_CPU0_SA_DQS_DN<0>")
	)
	(arc
		(start 385.744974 -227.144326)
		(mid 385.559942 -227.098412)
		(end 385.376166 -227.149152)
		(width 0.09525)
		(layer "In13.Cu")
		(net "M_H_CPU0_SA_DQS_DN<0>")
	)
	(arc
		(start 391.29716 -223.424242)
		(mid 391.232763 -223.685548)
		(end 391.054336 -223.88703)
		(width 0.09525)
		(layer "In13.Cu")
		(net "M_H_CPU0_SA_DQS_DN<0>")
	)
	(arc
		(start 390.357106 -225.044254)
		(mid 390.292709 -225.30556)
		(end 390.114282 -225.507042)
		(width 0.09525)
		(layer "In13.Cu")
		(net "M_H_CPU0_SA_DQS_DN<0>")
	)
	(arc
		(start 388.573518 -227.149152)
		(mid 388.389743 -227.09838)
		(end 388.20471 -227.144326)
		(width 0.09525)
		(layer "In13.Cu")
		(net "M_H_CPU0_SA_DQS_DN<0>")
	)
	(arc
		(start 392.23696 -221.80423)
		(mid 392.172925 -222.064907)
		(end 391.995406 -222.266256)
		(width 0.09525)
		(layer "In13.Cu")
		(net "M_H_CPU0_SA_DQS_DN<0>")
	)
	(arc
		(start 390.044686 -225.547428)
		(mid 389.928888 -225.681822)
		(end 389.887206 -225.85426)
		(width 0.09525)
		(layer "In13.Cu")
		(net "M_H_CPU0_SA_DQS_DN<0>")
	)
	(arc
		(start 387.633464 -227.149152)
		(mid 387.449689 -227.09838)
		(end 387.264656 -227.144326)
		(width 0.09525)
		(layer "In13.Cu")
		(net "M_H_CPU0_SA_DQS_DN<0>")
	)
	(arc
		(start 390.827006 -224.234248)
		(mid 390.761759 -224.496851)
		(end 390.581388 -224.69856)
		(width 0.09525)
		(layer "In13.Cu")
		(net "M_H_CPU0_SA_DQS_DN<0>")
	)
	(arc
		(start 386.685028 -227.144326)
		(mid 386.499996 -227.098412)
		(end 386.31622 -227.149152)
		(width 0.09525)
		(layer "In13.Cu")
		(net "M_H_CPU0_SA_DQS_DN<0>")
	)
	(arc
		(start 385.376166 -227.149152)
		(mid 385.094734 -227.224907)
		(end 384.813302 -227.149152)
		(width 0.09525)
		(layer "In13.Cu")
		(net "M_H_CPU0_SA_DQS_DN<0>")
	)
	(arc
		(start 388.196328 -227.149152)
		(mid 387.914896 -227.224907)
		(end 387.633464 -227.149152)
		(width 0.09525)
		(layer "In13.Cu")
		(net "M_H_CPU0_SA_DQS_DN<0>")
	)
	(arc
		(start 384.813302 -227.149152)
		(mid 384.624834 -227.098475)
		(end 384.436366 -227.149152)
		(width 0.09525)
		(layer "In13.Cu")
		(net "M_H_CPU0_SA_DQS_DN<0>")
	)
	(arc
		(start 389.417052 -226.664266)
		(mid 389.351805 -226.926869)
		(end 389.171434 -227.128578)
		(width 0.09525)
		(layer "In13.Cu")
		(net "M_H_CPU0_SA_DQS_DN<0>")
	)
	(arc
		(start 383.960116 -227.1903)
		(mid 383.949788 -227.18634)
		(end 383.939542 -227.182172)
		(width 0.09525)
		(layer "In13.Cu")
		(net "M_H_CPU0_SA_DQS_DN<0>")
	)
	(arc
		(start 384.436366 -227.149152)
		(mid 384.202852 -227.222995)
		(end 383.960116 -227.1903)
		(width 0.09525)
		(layer "In13.Cu")
		(net "M_H_CPU0_SA_DQS_DN<0>")
	)
	(arc
		(start 390.983724 -223.927924)
		(mid 390.86845 -224.062202)
		(end 390.827006 -224.234248)
		(width 0.09525)
		(layer "In13.Cu")
		(net "M_H_CPU0_SA_DQS_DN<0>")
	)
	(arc
		(start 389.57377 -226.357942)
		(mid 389.458496 -226.49222)
		(end 389.417052 -226.664266)
		(width 0.09525)
		(layer "In13.Cu")
		(net "M_H_CPU0_SA_DQS_DN<0>")
	)
	(arc
		(start 386.31622 -227.149152)
		(mid 386.034788 -227.224907)
		(end 385.753356 -227.149152)
		(width 0.09525)
		(layer "In13.Cu")
		(net "M_H_CPU0_SA_DQS_DN<0>")
	)
	(arc
		(start 389.887206 -225.85426)
		(mid 389.822809 -226.115566)
		(end 389.644382 -226.317048)
		(width 0.09525)
		(layer "In13.Cu")
		(net "M_H_CPU0_SA_DQS_DN<0>")
	)
	(segment
		(start 382.277874 -230.97998)
		(end 382.744726 -230.714296)
		(width 0.10668)
		(layer "F.Cu")
		(net "M_H_CPU0_SA_DQ<9>")
	)
	(segment
		(start 391.391902 -231.036622)
		(end 391.426446 -231.016556)
		(width 0.0889)
		(layer "In13.Cu")
		(net "M_H_CPU0_SA_DQ<9>")
	)
	(segment
		(start 414.560766 -208.360518)
		(end 418.47135 -208.360518)
		(width 0.14478)
		(layer "In13.Cu")
		(net "M_H_CPU0_SA_DQ<9>")
	)
	(segment
		(start 385.74345 -231.041448)
		(end 385.751832 -231.036622)
		(width 0.0889)
		(layer "In13.Cu")
		(net "M_H_CPU0_SA_DQ<9>")
	)
	(segment
		(start 387.257798 -231.036622)
		(end 387.26618 -231.041448)
		(width 0.0889)
		(layer "In13.Cu")
		(net "M_H_CPU0_SA_DQ<9>")
	)
	(segment
		(start 413.475424 -208.810098)
		(end 414.560766 -208.360518)
		(width 0.14478)
		(layer "In13.Cu")
		(net "M_H_CPU0_SA_DQ<9>")
	)
	(segment
		(start 382.744726 -230.714296)
		(end 382.590802 -230.979726)
		(width 0.0889)
		(layer "In13.Cu")
		(net "M_H_CPU0_SA_DQ<9>")
	)
	(segment
		(start 394.981938 -226.48291)
		(end 395.243558 -226.22129)
		(width 0.0889)
		(layer "In13.Cu")
		(net "M_H_CPU0_SA_DQ<9>")
	)
	(segment
		(start 409.042616 -208.810098)
		(end 413.475424 -208.810098)
		(width 0.14478)
		(layer "In13.Cu")
		(net "M_H_CPU0_SA_DQ<9>")
	)
	(segment
		(start 391.01776 -231.036622)
		(end 391.026142 -231.041448)
		(width 0.0889)
		(layer "In13.Cu")
		(net "M_H_CPU0_SA_DQ<9>")
	)
	(segment
		(start 391.82548 -230.247952)
		(end 391.862056 -230.226616)
		(width 0.0889)
		(layer "In13.Cu")
		(net "M_H_CPU0_SA_DQ<9>")
	)
	(segment
		(start 392.043158 -229.604316)
		(end 392.997944 -228.64953)
		(width 0.0889)
		(layer "In13.Cu")
		(net "M_H_CPU0_SA_DQ<9>")
	)
	(segment
		(start 388.197852 -231.036622)
		(end 388.206234 -231.041448)
		(width 0.0889)
		(layer "In13.Cu")
		(net "M_H_CPU0_SA_DQ<9>")
	)
	(segment
		(start 419.556692 -208.810098)
		(end 421.875712 -208.810098)
		(width 0.14478)
		(layer "In13.Cu")
		(net "M_H_CPU0_SA_DQ<9>")
	)
	(segment
		(start 393.062714 -228.64953)
		(end 394.981938 -226.730306)
		(width 0.0889)
		(layer "In13.Cu")
		(net "M_H_CPU0_SA_DQ<9>")
	)
	(segment
		(start 403.685756 -214.166958)
		(end 409.042616 -208.810098)
		(width 0.14478)
		(layer "In13.Cu")
		(net "M_H_CPU0_SA_DQ<9>")
	)
	(segment
		(start 382.590802 -230.979726)
		(end 382.613154 -231.062784)
		(width 0.0889)
		(layer "In13.Cu")
		(net "M_H_CPU0_SA_DQ<9>")
	)
	(segment
		(start 386.683504 -231.041448)
		(end 386.691886 -231.036622)
		(width 0.0889)
		(layer "In13.Cu")
		(net "M_H_CPU0_SA_DQ<9>")
	)
	(segment
		(start 392.997944 -228.64953)
		(end 393.062714 -228.64953)
		(width 0.0889)
		(layer "In13.Cu")
		(net "M_H_CPU0_SA_DQ<9>")
	)
	(segment
		(start 396.578582 -220.612716)
		(end 403.02434 -214.166958)
		(width 0.14478)
		(layer "In13.Cu")
		(net "M_H_CPU0_SA_DQ<9>")
	)
	(segment
		(start 394.981938 -226.730306)
		(end 394.981938 -226.48291)
		(width 0.0889)
		(layer "In13.Cu")
		(net "M_H_CPU0_SA_DQ<9>")
	)
	(segment
		(start 383.497836 -231.036622)
		(end 383.506218 -231.041448)
		(width 0.0889)
		(layer "In13.Cu")
		(net "M_H_CPU0_SA_DQ<9>")
	)
	(segment
		(start 418.47135 -208.360518)
		(end 419.556692 -208.810098)
		(width 0.14478)
		(layer "In13.Cu")
		(net "M_H_CPU0_SA_DQ<9>")
	)
	(segment
		(start 396.578582 -224.886266)
		(end 396.578582 -220.612716)
		(width 0.14478)
		(layer "In13.Cu")
		(net "M_H_CPU0_SA_DQ<9>")
	)
	(segment
		(start 390.443466 -231.041448)
		(end 390.451848 -231.036622)
		(width 0.0889)
		(layer "In13.Cu")
		(net "M_H_CPU0_SA_DQ<9>")
	)
	(segment
		(start 395.243558 -226.22129)
		(end 396.578582 -224.886266)
		(width 0.14478)
		(layer "In13.Cu")
		(net "M_H_CPU0_SA_DQ<9>")
	)
	(segment
		(start 421.875712 -208.810098)
		(end 424.012106 -208.385156)
		(width 0.14478)
		(layer "In13.Cu")
		(net "M_H_CPU0_SA_DQ<9>")
	)
	(segment
		(start 403.02434 -214.166958)
		(end 403.685756 -214.166958)
		(width 0.14478)
		(layer "In13.Cu")
		(net "M_H_CPU0_SA_DQ<9>")
	)
	(segment
		(start 392.043158 -229.911402)
		(end 392.043158 -229.604316)
		(width 0.0889)
		(layer "In13.Cu")
		(net "M_H_CPU0_SA_DQ<9>")
	)
	(arc
		(start 391.862056 -230.226616)
		(mid 391.994615 -230.093154)
		(end 392.043158 -229.911402)
		(width 0.0889)
		(layer "In13.Cu")
		(net "M_H_CPU0_SA_DQ<9>")
	)
	(arc
		(start 389.511794 -231.036622)
		(mid 389.79475 -230.960445)
		(end 390.077706 -231.036622)
		(width 0.0889)
		(layer "In13.Cu")
		(net "M_H_CPU0_SA_DQ<9>")
	)
	(arc
		(start 384.811778 -231.036622)
		(mid 385.094734 -230.960445)
		(end 385.37769 -231.036622)
		(width 0.0889)
		(layer "In13.Cu")
		(net "M_H_CPU0_SA_DQ<9>")
	)
	(arc
		(start 388.206234 -231.041448)
		(mid 388.389742 -231.086973)
		(end 388.571994 -231.036622)
		(width 0.0889)
		(layer "In13.Cu")
		(net "M_H_CPU0_SA_DQ<9>")
	)
	(arc
		(start 386.691886 -231.036622)
		(mid 386.974842 -230.960445)
		(end 387.257798 -231.036622)
		(width 0.0889)
		(layer "In13.Cu")
		(net "M_H_CPU0_SA_DQ<9>")
	)
	(arc
		(start 389.137906 -231.036622)
		(mid 389.32485 -231.086911)
		(end 389.511794 -231.036622)
		(width 0.0889)
		(layer "In13.Cu")
		(net "M_H_CPU0_SA_DQ<9>")
	)
	(arc
		(start 388.571994 -231.036622)
		(mid 388.85495 -230.960445)
		(end 389.137906 -231.036622)
		(width 0.0889)
		(layer "In13.Cu")
		(net "M_H_CPU0_SA_DQ<9>")
	)
	(arc
		(start 384.43789 -231.036622)
		(mid 384.624834 -231.086911)
		(end 384.811778 -231.036622)
		(width 0.0889)
		(layer "In13.Cu")
		(net "M_H_CPU0_SA_DQ<9>")
	)
	(arc
		(start 391.579608 -230.714296)
		(mid 391.644844 -230.450705)
		(end 391.82548 -230.247952)
		(width 0.0889)
		(layer "In13.Cu")
		(net "M_H_CPU0_SA_DQ<9>")
	)
	(arc
		(start 386.317744 -231.036622)
		(mid 386.499995 -231.087006)
		(end 386.683504 -231.041448)
		(width 0.0889)
		(layer "In13.Cu")
		(net "M_H_CPU0_SA_DQ<9>")
	)
	(arc
		(start 387.63194 -231.036622)
		(mid 387.914896 -230.960445)
		(end 388.197852 -231.036622)
		(width 0.0889)
		(layer "In13.Cu")
		(net "M_H_CPU0_SA_DQ<9>")
	)
	(arc
		(start 390.077706 -231.036622)
		(mid 390.259957 -231.087006)
		(end 390.443466 -231.041448)
		(width 0.0889)
		(layer "In13.Cu")
		(net "M_H_CPU0_SA_DQ<9>")
	)
	(arc
		(start 385.751832 -231.036622)
		(mid 386.034788 -230.960445)
		(end 386.317744 -231.036622)
		(width 0.0889)
		(layer "In13.Cu")
		(net "M_H_CPU0_SA_DQ<9>")
	)
	(arc
		(start 391.026142 -231.041448)
		(mid 391.20965 -231.086973)
		(end 391.391902 -231.036622)
		(width 0.0889)
		(layer "In13.Cu")
		(net "M_H_CPU0_SA_DQ<9>")
	)
	(arc
		(start 383.506218 -231.041448)
		(mid 383.689726 -231.086973)
		(end 383.871978 -231.036622)
		(width 0.0889)
		(layer "In13.Cu")
		(net "M_H_CPU0_SA_DQ<9>")
	)
	(arc
		(start 387.26618 -231.041448)
		(mid 387.449688 -231.086973)
		(end 387.63194 -231.036622)
		(width 0.0889)
		(layer "In13.Cu")
		(net "M_H_CPU0_SA_DQ<9>")
	)
	(arc
		(start 391.426446 -231.016556)
		(mid 391.539111 -230.883715)
		(end 391.579608 -230.714296)
		(width 0.0889)
		(layer "In13.Cu")
		(net "M_H_CPU0_SA_DQ<9>")
	)
	(arc
		(start 382.931924 -231.036622)
		(mid 383.21488 -230.960445)
		(end 383.497836 -231.036622)
		(width 0.0889)
		(layer "In13.Cu")
		(net "M_H_CPU0_SA_DQ<9>")
	)
	(arc
		(start 385.37769 -231.036622)
		(mid 385.559941 -231.087006)
		(end 385.74345 -231.041448)
		(width 0.0889)
		(layer "In13.Cu")
		(net "M_H_CPU0_SA_DQ<9>")
	)
	(arc
		(start 382.613154 -231.062784)
		(mid 382.775486 -231.085618)
		(end 382.931924 -231.036622)
		(width 0.0889)
		(layer "In13.Cu")
		(net "M_H_CPU0_SA_DQ<9>")
	)
	(arc
		(start 390.451848 -231.036622)
		(mid 390.734804 -230.960445)
		(end 391.01776 -231.036622)
		(width 0.0889)
		(layer "In13.Cu")
		(net "M_H_CPU0_SA_DQ<9>")
	)
	(arc
		(start 383.871978 -231.036622)
		(mid 384.154934 -230.960445)
		(end 384.43789 -231.036622)
		(width 0.0889)
		(layer "In13.Cu")
		(net "M_H_CPU0_SA_DQ<9>")
	)
	(segment
		(start 383.688082 -230.169974)
		(end 384.154934 -229.904036)
		(width 0.10668)
		(layer "F.Cu")
		(net "M_H_CPU0_SA_DQ<8>")
	)
	(segment
		(start 394.911834 -225.144076)
		(end 394.911834 -224.714816)
		(width 0.0889)
		(layer "In13.Cu")
		(net "M_H_CPU0_SA_DQ<8>")
	)
	(segment
		(start 394.911834 -224.714816)
		(end 395.679422 -223.947228)
		(width 0.0889)
		(layer "In13.Cu")
		(net "M_H_CPU0_SA_DQ<8>")
	)
	(segment
		(start 392.267948 -227.787962)
		(end 394.911834 -225.144076)
		(width 0.0889)
		(layer "In13.Cu")
		(net "M_H_CPU0_SA_DQ<8>")
	)
	(segment
		(start 395.679422 -223.947228)
		(end 395.679422 -220.178884)
		(width 0.14478)
		(layer "In13.Cu")
		(net "M_H_CPU0_SA_DQ<8>")
	)
	(segment
		(start 384.154934 -229.904036)
		(end 384.000756 -230.169466)
		(width 0.0889)
		(layer "In13.Cu")
		(net "M_H_CPU0_SA_DQ<8>")
	)
	(segment
		(start 408.714702 -207.143604)
		(end 414.08096 -207.143604)
		(width 0.14478)
		(layer "In13.Cu")
		(net "M_H_CPU0_SA_DQ<8>")
	)
	(segment
		(start 392.267948 -228.739192)
		(end 392.267948 -227.787962)
		(width 0.0889)
		(layer "In13.Cu")
		(net "M_H_CPU0_SA_DQ<8>")
	)
	(segment
		(start 418.566854 -207.110076)
		(end 421.875712 -207.110076)
		(width 0.14478)
		(layer "In13.Cu")
		(net "M_H_CPU0_SA_DQ<8>")
	)
	(segment
		(start 417.71697 -206.260192)
		(end 418.566854 -207.110076)
		(width 0.14478)
		(layer "In13.Cu")
		(net "M_H_CPU0_SA_DQ<8>")
	)
	(segment
		(start 389.607806 -230.226616)
		(end 389.616188 -230.231442)
		(width 0.0889)
		(layer "In13.Cu")
		(net "M_H_CPU0_SA_DQ<8>")
	)
	(segment
		(start 391.674858 -229.338632)
		(end 391.674858 -229.332282)
		(width 0.0889)
		(layer "In13.Cu")
		(net "M_H_CPU0_SA_DQ<8>")
	)
	(segment
		(start 391.674858 -229.332282)
		(end 392.267948 -228.739192)
		(width 0.0889)
		(layer "In13.Cu")
		(net "M_H_CPU0_SA_DQ<8>")
	)
	(segment
		(start 384.000756 -230.169466)
		(end 384.023108 -230.252778)
		(width 0.0889)
		(layer "In13.Cu")
		(net "M_H_CPU0_SA_DQ<8>")
	)
	(segment
		(start 421.875712 -207.110076)
		(end 424.012106 -206.685134)
		(width 0.14478)
		(layer "In13.Cu")
		(net "M_H_CPU0_SA_DQ<8>")
	)
	(segment
		(start 414.964372 -206.260192)
		(end 417.71697 -206.260192)
		(width 0.14478)
		(layer "In13.Cu")
		(net "M_H_CPU0_SA_DQ<8>")
	)
	(segment
		(start 385.847844 -230.226616)
		(end 385.856226 -230.231442)
		(width 0.0889)
		(layer "In13.Cu")
		(net "M_H_CPU0_SA_DQ<8>")
	)
	(segment
		(start 390.921748 -230.226616)
		(end 390.953498 -230.208328)
		(width 0.0889)
		(layer "In13.Cu")
		(net "M_H_CPU0_SA_DQ<8>")
	)
	(segment
		(start 414.08096 -207.143604)
		(end 414.964372 -206.260192)
		(width 0.14478)
		(layer "In13.Cu")
		(net "M_H_CPU0_SA_DQ<8>")
	)
	(segment
		(start 384.90779 -230.226616)
		(end 384.916172 -230.231442)
		(width 0.0889)
		(layer "In13.Cu")
		(net "M_H_CPU0_SA_DQ<8>")
	)
	(segment
		(start 384.333496 -230.231442)
		(end 384.341878 -230.226616)
		(width 0.0889)
		(layer "In13.Cu")
		(net "M_H_CPU0_SA_DQ<8>")
	)
	(segment
		(start 388.093458 -230.231442)
		(end 388.10184 -230.226616)
		(width 0.0889)
		(layer "In13.Cu")
		(net "M_H_CPU0_SA_DQ<8>")
	)
	(segment
		(start 395.679422 -220.178884)
		(end 408.714702 -207.143604)
		(width 0.14478)
		(layer "In13.Cu")
		(net "M_H_CPU0_SA_DQ<8>")
	)
	(segment
		(start 389.033512 -230.231442)
		(end 389.041894 -230.226616)
		(width 0.0889)
		(layer "In13.Cu")
		(net "M_H_CPU0_SA_DQ<8>")
	)
	(arc
		(start 384.023108 -230.252778)
		(mid 384.180618 -230.275976)
		(end 384.333496 -230.231442)
		(width 0.0889)
		(layer "In13.Cu")
		(net "M_H_CPU0_SA_DQ<8>")
	)
	(arc
		(start 384.341878 -230.226616)
		(mid 384.624834 -230.150473)
		(end 384.90779 -230.226616)
		(width 0.0889)
		(layer "In13.Cu")
		(net "M_H_CPU0_SA_DQ<8>")
	)
	(arc
		(start 389.616188 -230.231442)
		(mid 389.799696 -230.276936)
		(end 389.981948 -230.226616)
		(width 0.0889)
		(layer "In13.Cu")
		(net "M_H_CPU0_SA_DQ<8>")
	)
	(arc
		(start 386.221986 -230.226616)
		(mid 386.504942 -230.150473)
		(end 386.787898 -230.226616)
		(width 0.0889)
		(layer "In13.Cu")
		(net "M_H_CPU0_SA_DQ<8>")
	)
	(arc
		(start 390.953498 -230.208328)
		(mid 391.068174 -230.074994)
		(end 391.109454 -229.904036)
		(width 0.0889)
		(layer "In13.Cu")
		(net "M_H_CPU0_SA_DQ<8>")
	)
	(arc
		(start 387.727698 -230.226616)
		(mid 387.909949 -230.276966)
		(end 388.093458 -230.231442)
		(width 0.0889)
		(layer "In13.Cu")
		(net "M_H_CPU0_SA_DQ<8>")
	)
	(arc
		(start 391.109454 -229.904036)
		(mid 391.173969 -229.641817)
		(end 391.352786 -229.43947)
		(width 0.0889)
		(layer "In13.Cu")
		(net "M_H_CPU0_SA_DQ<8>")
	)
	(arc
		(start 388.10184 -230.226616)
		(mid 388.384796 -230.150473)
		(end 388.667752 -230.226616)
		(width 0.0889)
		(layer "In13.Cu")
		(net "M_H_CPU0_SA_DQ<8>")
	)
	(arc
		(start 389.041894 -230.226616)
		(mid 389.32485 -230.150473)
		(end 389.607806 -230.226616)
		(width 0.0889)
		(layer "In13.Cu")
		(net "M_H_CPU0_SA_DQ<8>")
	)
	(arc
		(start 390.54786 -230.226616)
		(mid 390.734804 -230.276871)
		(end 390.921748 -230.226616)
		(width 0.0889)
		(layer "In13.Cu")
		(net "M_H_CPU0_SA_DQ<8>")
	)
	(arc
		(start 385.281932 -230.226616)
		(mid 385.564888 -230.150473)
		(end 385.847844 -230.226616)
		(width 0.0889)
		(layer "In13.Cu")
		(net "M_H_CPU0_SA_DQ<8>")
	)
	(arc
		(start 385.856226 -230.231442)
		(mid 386.039734 -230.276936)
		(end 386.221986 -230.226616)
		(width 0.0889)
		(layer "In13.Cu")
		(net "M_H_CPU0_SA_DQ<8>")
	)
	(arc
		(start 389.981948 -230.226616)
		(mid 390.264904 -230.150473)
		(end 390.54786 -230.226616)
		(width 0.0889)
		(layer "In13.Cu")
		(net "M_H_CPU0_SA_DQ<8>")
	)
	(arc
		(start 387.161786 -230.226616)
		(mid 387.444742 -230.150473)
		(end 387.727698 -230.226616)
		(width 0.0889)
		(layer "In13.Cu")
		(net "M_H_CPU0_SA_DQ<8>")
	)
	(arc
		(start 391.352786 -229.43947)
		(mid 391.506121 -229.364446)
		(end 391.674858 -229.338632)
		(width 0.0889)
		(layer "In13.Cu")
		(net "M_H_CPU0_SA_DQ<8>")
	)
	(arc
		(start 384.916172 -230.231442)
		(mid 385.09968 -230.276936)
		(end 385.281932 -230.226616)
		(width 0.0889)
		(layer "In13.Cu")
		(net "M_H_CPU0_SA_DQ<8>")
	)
	(arc
		(start 388.667752 -230.226616)
		(mid 388.850003 -230.276966)
		(end 389.033512 -230.231442)
		(width 0.0889)
		(layer "In13.Cu")
		(net "M_H_CPU0_SA_DQ<8>")
	)
	(arc
		(start 386.787898 -230.226616)
		(mid 386.974842 -230.276871)
		(end 387.161786 -230.226616)
		(width 0.0889)
		(layer "In13.Cu")
		(net "M_H_CPU0_SA_DQ<8>")
	)
	(segment
		(start 381.807974 -230.169974)
		(end 382.274826 -229.904036)
		(width 0.10668)
		(layer "F.Cu")
		(net "M_H_CPU0_SA_DQ<7>")
	)
	(segment
		(start 401.235926 -213.63813)
		(end 401.135342 -213.537546)
		(width 0.14478)
		(layer "In13.Cu")
		(net "M_H_CPU0_SA_DQ<7>")
	)
	(segment
		(start 402.305012 -212.367876)
		(end 402.405596 -212.46846)
		(width 0.14478)
		(layer "In13.Cu")
		(net "M_H_CPU0_SA_DQ<7>")
	)
	(segment
		(start 389.607806 -229.58171)
		(end 389.616188 -229.576884)
		(width 0.0889)
		(layer "In13.Cu")
		(net "M_H_CPU0_SA_DQ<7>")
	)
	(segment
		(start 395.777466 -219.301314)
		(end 395.777466 -219.09659)
		(width 0.14478)
		(layer "In13.Cu")
		(net "M_H_CPU0_SA_DQ<7>")
	)
	(segment
		(start 397.626332 -217.046556)
		(end 397.726916 -217.14714)
		(width 0.14478)
		(layer "In13.Cu")
		(net "M_H_CPU0_SA_DQ<7>")
	)
	(segment
		(start 409.460192 -206.576168)
		(end 409.721812 -206.576168)
		(width 0.14478)
		(layer "In13.Cu")
		(net "M_H_CPU0_SA_DQ<7>")
	)
	(segment
		(start 391.75182 -227.911406)
		(end 393.587732 -226.075494)
		(width 0.0889)
		(layer "In13.Cu")
		(net "M_H_CPU0_SA_DQ<7>")
	)
	(segment
		(start 401.320508 -213.147656)
		(end 401.525232 -213.147656)
		(width 0.14478)
		(layer "In13.Cu")
		(net "M_H_CPU0_SA_DQ<7>")
	)
	(segment
		(start 400.456146 -214.41791)
		(end 400.355562 -214.317326)
		(width 0.14478)
		(layer "In13.Cu")
		(net "M_H_CPU0_SA_DQ<7>")
	)
	(segment
		(start 398.506696 -216.36736)
		(end 398.71142 -216.36736)
		(width 0.14478)
		(layer "In13.Cu")
		(net "M_H_CPU0_SA_DQ<7>")
	)
	(segment
		(start 410.824172 -206.576168)
		(end 410.968952 -206.431388)
		(width 0.14478)
		(layer "In13.Cu")
		(net "M_H_CPU0_SA_DQ<7>")
	)
	(segment
		(start 408.818588 -206.260192)
		(end 409.170632 -206.260192)
		(width 0.14478)
		(layer "In13.Cu")
		(net "M_H_CPU0_SA_DQ<7>")
	)
	(segment
		(start 409.315412 -206.431388)
		(end 409.460192 -206.576168)
		(width 0.14478)
		(layer "In13.Cu")
		(net "M_H_CPU0_SA_DQ<7>")
	)
	(segment
		(start 402.405596 -212.46846)
		(end 402.61032 -212.46846)
		(width 0.14478)
		(layer "In13.Cu")
		(net "M_H_CPU0_SA_DQ<7>")
	)
	(segment
		(start 418.551106 -206.260192)
		(end 419.486842 -206.260192)
		(width 0.14478)
		(layer "In13.Cu")
		(net "M_H_CPU0_SA_DQ<7>")
	)
	(segment
		(start 400.27098 -214.8078)
		(end 400.456146 -214.622634)
		(width 0.14478)
		(layer "In13.Cu")
		(net "M_H_CPU0_SA_DQ<7>")
	)
	(segment
		(start 402.694902 -211.773262)
		(end 402.880068 -211.588096)
		(width 0.14478)
		(layer "In13.Cu")
		(net "M_H_CPU0_SA_DQ<7>")
	)
	(segment
		(start 396.947136 -217.92692)
		(end 397.15186 -217.92692)
		(width 0.14478)
		(layer "In13.Cu")
		(net "M_H_CPU0_SA_DQ<7>")
	)
	(segment
		(start 410.011372 -206.260192)
		(end 410.272992 -206.260192)
		(width 0.14478)
		(layer "In13.Cu")
		(net "M_H_CPU0_SA_DQ<7>")
	)
	(segment
		(start 401.235926 -213.842854)
		(end 401.235926 -213.63813)
		(width 0.14478)
		(layer "In13.Cu")
		(net "M_H_CPU0_SA_DQ<7>")
	)
	(segment
		(start 385.847844 -229.58171)
		(end 385.856226 -229.576884)
		(width 0.0889)
		(layer "In13.Cu")
		(net "M_H_CPU0_SA_DQ<7>")
	)
	(segment
		(start 399.185892 -215.486996)
		(end 399.286476 -215.58758)
		(width 0.14478)
		(layer "In13.Cu")
		(net "M_H_CPU0_SA_DQ<7>")
	)
	(segment
		(start 398.796002 -215.672162)
		(end 398.981168 -215.486996)
		(width 0.14478)
		(layer "In13.Cu")
		(net "M_H_CPU0_SA_DQ<7>")
	)
	(segment
		(start 400.355562 -214.112602)
		(end 400.540728 -213.927436)
		(width 0.14478)
		(layer "In13.Cu")
		(net "M_H_CPU0_SA_DQ<7>")
	)
	(segment
		(start 395.128242 -223.653604)
		(end 395.128242 -222.54464)
		(width 0.0889)
		(layer "In13.Cu")
		(net "M_H_CPU0_SA_DQ<7>")
	)
	(segment
		(start 382.42875 -229.638606)
		(end 382.524508 -229.613206)
		(width 0.0889)
		(layer "In13.Cu")
		(net "M_H_CPU0_SA_DQ<7>")
	)
	(segment
		(start 399.575782 -214.892382)
		(end 399.760948 -214.707216)
		(width 0.14478)
		(layer "In13.Cu")
		(net "M_H_CPU0_SA_DQ<7>")
	)
	(segment
		(start 414.855914 -205.410054)
		(end 417.700968 -205.410054)
		(width 0.14478)
		(layer "In13.Cu")
		(net "M_H_CPU0_SA_DQ<7>")
	)
	(segment
		(start 391.01776 -228.771704)
		(end 391.056876 -228.748844)
		(width 0.0889)
		(layer "In13.Cu")
		(net "M_H_CPU0_SA_DQ<7>")
	)
	(segment
		(start 401.915122 -212.757766)
		(end 401.915122 -212.553042)
		(width 0.14478)
		(layer "In13.Cu")
		(net "M_H_CPU0_SA_DQ<7>")
	)
	(segment
		(start 398.201388 -216.266776)
		(end 398.406112 -216.266776)
		(width 0.14478)
		(layer "In13.Cu")
		(net "M_H_CPU0_SA_DQ<7>")
	)
	(segment
		(start 410.417772 -206.404972)
		(end 410.417772 -206.431388)
		(width 0.14478)
		(layer "In13.Cu")
		(net "M_H_CPU0_SA_DQ<7>")
	)
	(segment
		(start 414.005776 -206.260192)
		(end 414.855914 -205.410054)
		(width 0.14478)
		(layer "In13.Cu")
		(net "M_H_CPU0_SA_DQ<7>")
	)
	(segment
		(start 397.421608 -217.046556)
		(end 397.626332 -217.046556)
		(width 0.14478)
		(layer "In13.Cu")
		(net "M_H_CPU0_SA_DQ<7>")
	)
	(segment
		(start 400.540728 -213.927436)
		(end 400.745452 -213.927436)
		(width 0.14478)
		(layer "In13.Cu")
		(net "M_H_CPU0_SA_DQ<7>")
	)
	(segment
		(start 397.236442 -217.436446)
		(end 397.236442 -217.231722)
		(width 0.14478)
		(layer "In13.Cu")
		(net "M_H_CPU0_SA_DQ<7>")
	)
	(segment
		(start 398.406112 -216.266776)
		(end 398.506696 -216.36736)
		(width 0.14478)
		(layer "In13.Cu")
		(net "M_H_CPU0_SA_DQ<7>")
	)
	(segment
		(start 396.846552 -217.826336)
		(end 396.947136 -217.92692)
		(width 0.14478)
		(layer "In13.Cu")
		(net "M_H_CPU0_SA_DQ<7>")
	)
	(segment
		(start 395.862048 -218.606116)
		(end 396.066772 -218.606116)
		(width 0.14478)
		(layer "In13.Cu")
		(net "M_H_CPU0_SA_DQ<7>")
	)
	(segment
		(start 402.015706 -213.063074)
		(end 402.015706 -212.85835)
		(width 0.14478)
		(layer "In13.Cu")
		(net "M_H_CPU0_SA_DQ<7>")
	)
	(segment
		(start 395.128242 -219.950538)
		(end 395.777466 -219.301314)
		(width 0.14478)
		(layer "In13.Cu")
		(net "M_H_CPU0_SA_DQ<7>")
	)
	(segment
		(start 399.286476 -215.58758)
		(end 399.4912 -215.58758)
		(width 0.14478)
		(layer "In13.Cu")
		(net "M_H_CPU0_SA_DQ<7>")
	)
	(segment
		(start 396.456662 -218.011502)
		(end 396.641828 -217.826336)
		(width 0.14478)
		(layer "In13.Cu")
		(net "M_H_CPU0_SA_DQ<7>")
	)
	(segment
		(start 398.116806 -216.961974)
		(end 398.116806 -216.75725)
		(width 0.14478)
		(layer "In13.Cu")
		(net "M_H_CPU0_SA_DQ<7>")
	)
	(segment
		(start 399.575782 -215.097106)
		(end 399.575782 -214.892382)
		(width 0.14478)
		(layer "In13.Cu")
		(net "M_H_CPU0_SA_DQ<7>")
	)
	(segment
		(start 398.981168 -215.486996)
		(end 399.185892 -215.486996)
		(width 0.14478)
		(layer "In13.Cu")
		(net "M_H_CPU0_SA_DQ<7>")
	)
	(segment
		(start 384.90779 -229.58171)
		(end 384.916172 -229.576884)
		(width 0.0889)
		(layer "In13.Cu")
		(net "M_H_CPU0_SA_DQ<7>")
	)
	(segment
		(start 402.880068 -211.588096)
		(end 403.084792 -211.588096)
		(width 0.14478)
		(layer "In13.Cu")
		(net "M_H_CPU0_SA_DQ<7>")
	)
	(segment
		(start 397.337026 -217.741754)
		(end 397.337026 -217.53703)
		(width 0.14478)
		(layer "In13.Cu")
		(net "M_H_CPU0_SA_DQ<7>")
	)
	(segment
		(start 399.676366 -215.402414)
		(end 399.676366 -215.19769)
		(width 0.14478)
		(layer "In13.Cu")
		(net "M_H_CPU0_SA_DQ<7>")
	)
	(segment
		(start 401.625816 -213.24824)
		(end 401.83054 -213.24824)
		(width 0.14478)
		(layer "In13.Cu")
		(net "M_H_CPU0_SA_DQ<7>")
	)
	(segment
		(start 396.557246 -218.521534)
		(end 396.557246 -218.31681)
		(width 0.14478)
		(layer "In13.Cu")
		(net "M_H_CPU0_SA_DQ<7>")
	)
	(segment
		(start 396.066772 -218.606116)
		(end 396.167356 -218.7067)
		(width 0.14478)
		(layer "In13.Cu")
		(net "M_H_CPU0_SA_DQ<7>")
	)
	(segment
		(start 398.016222 -216.656666)
		(end 398.016222 -216.451942)
		(width 0.14478)
		(layer "In13.Cu")
		(net "M_H_CPU0_SA_DQ<7>")
	)
	(segment
		(start 409.170632 -206.260192)
		(end 409.315412 -206.404972)
		(width 0.14478)
		(layer "In13.Cu")
		(net "M_H_CPU0_SA_DQ<7>")
	)
	(segment
		(start 410.968952 -206.431388)
		(end 410.968952 -206.404972)
		(width 0.14478)
		(layer "In13.Cu")
		(net "M_H_CPU0_SA_DQ<7>")
	)
	(segment
		(start 410.968952 -206.404972)
		(end 411.113732 -206.260192)
		(width 0.14478)
		(layer "In13.Cu")
		(net "M_H_CPU0_SA_DQ<7>")
	)
	(segment
		(start 398.896586 -216.182194)
		(end 398.896586 -215.97747)
		(width 0.14478)
		(layer "In13.Cu")
		(net "M_H_CPU0_SA_DQ<7>")
	)
	(segment
		(start 398.896586 -215.97747)
		(end 398.796002 -215.876886)
		(width 0.14478)
		(layer "In13.Cu")
		(net "M_H_CPU0_SA_DQ<7>")
	)
	(segment
		(start 410.562552 -206.576168)
		(end 410.824172 -206.576168)
		(width 0.14478)
		(layer "In13.Cu")
		(net "M_H_CPU0_SA_DQ<7>")
	)
	(segment
		(start 400.745452 -213.927436)
		(end 400.846036 -214.02802)
		(width 0.14478)
		(layer "In13.Cu")
		(net "M_H_CPU0_SA_DQ<7>")
	)
	(segment
		(start 402.694902 -211.977986)
		(end 402.694902 -211.773262)
		(width 0.14478)
		(layer "In13.Cu")
		(net "M_H_CPU0_SA_DQ<7>")
	)
	(segment
		(start 397.236442 -217.231722)
		(end 397.421608 -217.046556)
		(width 0.14478)
		(layer "In13.Cu")
		(net "M_H_CPU0_SA_DQ<7>")
	)
	(segment
		(start 401.05076 -214.02802)
		(end 401.235926 -213.842854)
		(width 0.14478)
		(layer "In13.Cu")
		(net "M_H_CPU0_SA_DQ<7>")
	)
	(segment
		(start 403.185376 -211.68868)
		(end 403.3901 -211.68868)
		(width 0.14478)
		(layer "In13.Cu")
		(net "M_H_CPU0_SA_DQ<7>")
	)
	(segment
		(start 384.333496 -229.576884)
		(end 384.341878 -229.58171)
		(width 0.0889)
		(layer "In13.Cu")
		(net "M_H_CPU0_SA_DQ<7>")
	)
	(segment
		(start 399.676366 -215.19769)
		(end 399.575782 -215.097106)
		(width 0.14478)
		(layer "In13.Cu")
		(net "M_H_CPU0_SA_DQ<7>")
	)
	(segment
		(start 383.393442 -229.576884)
		(end 383.401824 -229.58171)
		(width 0.0889)
		(layer "In13.Cu")
		(net "M_H_CPU0_SA_DQ<7>")
	)
	(segment
		(start 402.61032 -212.46846)
		(end 402.795486 -212.283294)
		(width 0.14478)
		(layer "In13.Cu")
		(net "M_H_CPU0_SA_DQ<7>")
	)
	(segment
		(start 393.587732 -226.075494)
		(end 393.587732 -225.194114)
		(width 0.0889)
		(layer "In13.Cu")
		(net "M_H_CPU0_SA_DQ<7>")
	)
	(segment
		(start 382.274826 -229.904036)
		(end 382.42875 -229.638606)
		(width 0.0889)
		(layer "In13.Cu")
		(net "M_H_CPU0_SA_DQ<7>")
	)
	(segment
		(start 398.796002 -215.876886)
		(end 398.796002 -215.672162)
		(width 0.14478)
		(layer "In13.Cu")
		(net "M_H_CPU0_SA_DQ<7>")
	)
	(segment
		(start 402.795486 -212.283294)
		(end 402.795486 -212.07857)
		(width 0.14478)
		(layer "In13.Cu")
		(net "M_H_CPU0_SA_DQ<7>")
	)
	(segment
		(start 409.866592 -206.404972)
		(end 410.011372 -206.260192)
		(width 0.14478)
		(layer "In13.Cu")
		(net "M_H_CPU0_SA_DQ<7>")
	)
	(segment
		(start 402.795486 -212.07857)
		(end 402.694902 -211.977986)
		(width 0.14478)
		(layer "In13.Cu")
		(net "M_H_CPU0_SA_DQ<7>")
	)
	(segment
		(start 396.557246 -218.31681)
		(end 396.456662 -218.216226)
		(width 0.14478)
		(layer "In13.Cu")
		(net "M_H_CPU0_SA_DQ<7>")
	)
	(segment
		(start 391.45718 -227.979478)
		(end 391.48766 -227.961698)
		(width 0.0889)
		(layer "In13.Cu")
		(net "M_H_CPU0_SA_DQ<7>")
	)
	(segment
		(start 395.676882 -218.996006)
		(end 395.676882 -218.791282)
		(width 0.14478)
		(layer "In13.Cu")
		(net "M_H_CPU0_SA_DQ<7>")
	)
	(segment
		(start 400.355562 -214.317326)
		(end 400.355562 -214.112602)
		(width 0.14478)
		(layer "In13.Cu")
		(net "M_H_CPU0_SA_DQ<7>")
	)
	(segment
		(start 400.066256 -214.8078)
		(end 400.27098 -214.8078)
		(width 0.14478)
		(layer "In13.Cu")
		(net "M_H_CPU0_SA_DQ<7>")
	)
	(segment
		(start 403.3901 -211.68868)
		(end 408.818588 -206.260192)
		(width 0.14478)
		(layer "In13.Cu")
		(net "M_H_CPU0_SA_DQ<7>")
	)
	(segment
		(start 401.915122 -212.553042)
		(end 402.100288 -212.367876)
		(width 0.14478)
		(layer "In13.Cu")
		(net "M_H_CPU0_SA_DQ<7>")
	)
	(segment
		(start 391.674858 -227.911406)
		(end 391.75182 -227.911406)
		(width 0.0889)
		(layer "In13.Cu")
		(net "M_H_CPU0_SA_DQ<7>")
	)
	(segment
		(start 396.167356 -218.7067)
		(end 396.37208 -218.7067)
		(width 0.14478)
		(layer "In13.Cu")
		(net "M_H_CPU0_SA_DQ<7>")
	)
	(segment
		(start 402.100288 -212.367876)
		(end 402.305012 -212.367876)
		(width 0.14478)
		(layer "In13.Cu")
		(net "M_H_CPU0_SA_DQ<7>")
	)
	(segment
		(start 398.116806 -216.75725)
		(end 398.016222 -216.656666)
		(width 0.14478)
		(layer "In13.Cu")
		(net "M_H_CPU0_SA_DQ<7>")
	)
	(segment
		(start 401.135342 -213.537546)
		(end 401.135342 -213.332822)
		(width 0.14478)
		(layer "In13.Cu")
		(net "M_H_CPU0_SA_DQ<7>")
	)
	(segment
		(start 390.98601 -228.789992)
		(end 391.01776 -228.771704)
		(width 0.0889)
		(layer "In13.Cu")
		(net "M_H_CPU0_SA_DQ<7>")
	)
	(segment
		(start 410.272992 -206.260192)
		(end 410.417772 -206.404972)
		(width 0.14478)
		(layer "In13.Cu")
		(net "M_H_CPU0_SA_DQ<7>")
	)
	(segment
		(start 396.37208 -218.7067)
		(end 396.557246 -218.521534)
		(width 0.14478)
		(layer "In13.Cu")
		(net "M_H_CPU0_SA_DQ<7>")
	)
	(segment
		(start 419.486842 -206.260192)
		(end 419.912038 -205.834996)
		(width 0.14478)
		(layer "In13.Cu")
		(net "M_H_CPU0_SA_DQ<7>")
	)
	(segment
		(start 400.846036 -214.02802)
		(end 401.05076 -214.02802)
		(width 0.14478)
		(layer "In13.Cu")
		(net "M_H_CPU0_SA_DQ<7>")
	)
	(segment
		(start 389.033512 -229.576884)
		(end 389.041894 -229.58171)
		(width 0.0889)
		(layer "In13.Cu")
		(net "M_H_CPU0_SA_DQ<7>")
	)
	(segment
		(start 399.760948 -214.707216)
		(end 399.965672 -214.707216)
		(width 0.14478)
		(layer "In13.Cu")
		(net "M_H_CPU0_SA_DQ<7>")
	)
	(segment
		(start 396.641828 -217.826336)
		(end 396.846552 -217.826336)
		(width 0.14478)
		(layer "In13.Cu")
		(net "M_H_CPU0_SA_DQ<7>")
	)
	(segment
		(start 411.113732 -206.260192)
		(end 414.005776 -206.260192)
		(width 0.14478)
		(layer "In13.Cu")
		(net "M_H_CPU0_SA_DQ<7>")
	)
	(segment
		(start 417.700968 -205.410054)
		(end 418.551106 -206.260192)
		(width 0.14478)
		(layer "In13.Cu")
		(net "M_H_CPU0_SA_DQ<7>")
	)
	(segment
		(start 401.135342 -213.332822)
		(end 401.320508 -213.147656)
		(width 0.14478)
		(layer "In13.Cu")
		(net "M_H_CPU0_SA_DQ<7>")
	)
	(segment
		(start 409.315412 -206.404972)
		(end 409.315412 -206.431388)
		(width 0.14478)
		(layer "In13.Cu")
		(net "M_H_CPU0_SA_DQ<7>")
	)
	(segment
		(start 401.525232 -213.147656)
		(end 401.625816 -213.24824)
		(width 0.14478)
		(layer "In13.Cu")
		(net "M_H_CPU0_SA_DQ<7>")
	)
	(segment
		(start 409.866592 -206.431388)
		(end 409.866592 -206.404972)
		(width 0.14478)
		(layer "In13.Cu")
		(net "M_H_CPU0_SA_DQ<7>")
	)
	(segment
		(start 399.4912 -215.58758)
		(end 399.676366 -215.402414)
		(width 0.14478)
		(layer "In13.Cu")
		(net "M_H_CPU0_SA_DQ<7>")
	)
	(segment
		(start 409.721812 -206.576168)
		(end 409.866592 -206.431388)
		(width 0.14478)
		(layer "In13.Cu")
		(net "M_H_CPU0_SA_DQ<7>")
	)
	(segment
		(start 400.456146 -214.622634)
		(end 400.456146 -214.41791)
		(width 0.14478)
		(layer "In13.Cu")
		(net "M_H_CPU0_SA_DQ<7>")
	)
	(segment
		(start 397.337026 -217.53703)
		(end 397.236442 -217.436446)
		(width 0.14478)
		(layer "In13.Cu")
		(net "M_H_CPU0_SA_DQ<7>")
	)
	(segment
		(start 388.093458 -229.576884)
		(end 388.10184 -229.58171)
		(width 0.0889)
		(layer "In13.Cu")
		(net "M_H_CPU0_SA_DQ<7>")
	)
	(segment
		(start 397.93164 -217.14714)
		(end 398.116806 -216.961974)
		(width 0.14478)
		(layer "In13.Cu")
		(net "M_H_CPU0_SA_DQ<7>")
	)
	(segment
		(start 399.965672 -214.707216)
		(end 400.066256 -214.8078)
		(width 0.14478)
		(layer "In13.Cu")
		(net "M_H_CPU0_SA_DQ<7>")
	)
	(segment
		(start 395.777466 -219.09659)
		(end 395.676882 -218.996006)
		(width 0.14478)
		(layer "In13.Cu")
		(net "M_H_CPU0_SA_DQ<7>")
	)
	(segment
		(start 398.71142 -216.36736)
		(end 398.896586 -216.182194)
		(width 0.14478)
		(layer "In13.Cu")
		(net "M_H_CPU0_SA_DQ<7>")
	)
	(segment
		(start 398.016222 -216.451942)
		(end 398.201388 -216.266776)
		(width 0.14478)
		(layer "In13.Cu")
		(net "M_H_CPU0_SA_DQ<7>")
	)
	(segment
		(start 402.015706 -212.85835)
		(end 401.915122 -212.757766)
		(width 0.14478)
		(layer "In13.Cu")
		(net "M_H_CPU0_SA_DQ<7>")
	)
	(segment
		(start 393.587732 -225.194114)
		(end 395.128242 -223.653604)
		(width 0.0889)
		(layer "In13.Cu")
		(net "M_H_CPU0_SA_DQ<7>")
	)
	(segment
		(start 390.54786 -229.58171)
		(end 390.584182 -229.560628)
		(width 0.0889)
		(layer "In13.Cu")
		(net "M_H_CPU0_SA_DQ<7>")
	)
	(segment
		(start 396.456662 -218.216226)
		(end 396.456662 -218.011502)
		(width 0.14478)
		(layer "In13.Cu")
		(net "M_H_CPU0_SA_DQ<7>")
	)
	(segment
		(start 395.676882 -218.791282)
		(end 395.862048 -218.606116)
		(width 0.14478)
		(layer "In13.Cu")
		(net "M_H_CPU0_SA_DQ<7>")
	)
	(segment
		(start 403.084792 -211.588096)
		(end 403.185376 -211.68868)
		(width 0.14478)
		(layer "In13.Cu")
		(net "M_H_CPU0_SA_DQ<7>")
	)
	(segment
		(start 397.15186 -217.92692)
		(end 397.337026 -217.741754)
		(width 0.14478)
		(layer "In13.Cu")
		(net "M_H_CPU0_SA_DQ<7>")
	)
	(segment
		(start 410.417772 -206.431388)
		(end 410.562552 -206.576168)
		(width 0.14478)
		(layer "In13.Cu")
		(net "M_H_CPU0_SA_DQ<7>")
	)
	(segment
		(start 401.83054 -213.24824)
		(end 402.015706 -213.063074)
		(width 0.14478)
		(layer "In13.Cu")
		(net "M_H_CPU0_SA_DQ<7>")
	)
	(segment
		(start 397.726916 -217.14714)
		(end 397.93164 -217.14714)
		(width 0.14478)
		(layer "In13.Cu")
		(net "M_H_CPU0_SA_DQ<7>")
	)
	(segment
		(start 395.128242 -222.54464)
		(end 395.128242 -219.950538)
		(width 0.14478)
		(layer "In13.Cu")
		(net "M_H_CPU0_SA_DQ<7>")
	)
	(arc
		(start 384.916172 -229.576884)
		(mid 385.09968 -229.531359)
		(end 385.281932 -229.58171)
		(width 0.0889)
		(layer "In13.Cu")
		(net "M_H_CPU0_SA_DQ<7>")
	)
	(arc
		(start 391.48766 -227.961698)
		(mid 391.577936 -227.924193)
		(end 391.674858 -227.911406)
		(width 0.0889)
		(layer "In13.Cu")
		(net "M_H_CPU0_SA_DQ<7>")
	)
	(arc
		(start 386.787898 -229.58171)
		(mid 386.974842 -229.531421)
		(end 387.161786 -229.58171)
		(width 0.0889)
		(layer "In13.Cu")
		(net "M_H_CPU0_SA_DQ<7>")
	)
	(arc
		(start 387.727698 -229.58171)
		(mid 387.909949 -229.531326)
		(end 388.093458 -229.576884)
		(width 0.0889)
		(layer "In13.Cu")
		(net "M_H_CPU0_SA_DQ<7>")
	)
	(arc
		(start 389.041894 -229.58171)
		(mid 389.32485 -229.657887)
		(end 389.607806 -229.58171)
		(width 0.0889)
		(layer "In13.Cu")
		(net "M_H_CPU0_SA_DQ<7>")
	)
	(arc
		(start 390.584182 -229.560628)
		(mid 390.764834 -229.357883)
		(end 390.830054 -229.094284)
		(width 0.0889)
		(layer "In13.Cu")
		(net "M_H_CPU0_SA_DQ<7>")
	)
	(arc
		(start 389.981948 -229.58171)
		(mid 390.264904 -229.657887)
		(end 390.54786 -229.58171)
		(width 0.0889)
		(layer "In13.Cu")
		(net "M_H_CPU0_SA_DQ<7>")
	)
	(arc
		(start 383.401824 -229.58171)
		(mid 383.68478 -229.657887)
		(end 383.967736 -229.58171)
		(width 0.0889)
		(layer "In13.Cu")
		(net "M_H_CPU0_SA_DQ<7>")
	)
	(arc
		(start 391.056876 -228.748844)
		(mid 391.235689 -228.546494)
		(end 391.300208 -228.284278)
		(width 0.0889)
		(layer "In13.Cu")
		(net "M_H_CPU0_SA_DQ<7>")
	)
	(arc
		(start 385.856226 -229.576884)
		(mid 386.039734 -229.531359)
		(end 386.221986 -229.58171)
		(width 0.0889)
		(layer "In13.Cu")
		(net "M_H_CPU0_SA_DQ<7>")
	)
	(arc
		(start 383.027682 -229.58171)
		(mid 383.209933 -229.531326)
		(end 383.393442 -229.576884)
		(width 0.0889)
		(layer "In13.Cu")
		(net "M_H_CPU0_SA_DQ<7>")
	)
	(arc
		(start 388.10184 -229.58171)
		(mid 388.384796 -229.657887)
		(end 388.667752 -229.58171)
		(width 0.0889)
		(layer "In13.Cu")
		(net "M_H_CPU0_SA_DQ<7>")
	)
	(arc
		(start 385.281932 -229.58171)
		(mid 385.564888 -229.657887)
		(end 385.847844 -229.58171)
		(width 0.0889)
		(layer "In13.Cu")
		(net "M_H_CPU0_SA_DQ<7>")
	)
	(arc
		(start 386.221986 -229.58171)
		(mid 386.504942 -229.657887)
		(end 386.787898 -229.58171)
		(width 0.0889)
		(layer "In13.Cu")
		(net "M_H_CPU0_SA_DQ<7>")
	)
	(arc
		(start 390.830054 -229.094284)
		(mid 390.871309 -228.923313)
		(end 390.98601 -228.789992)
		(width 0.0889)
		(layer "In13.Cu")
		(net "M_H_CPU0_SA_DQ<7>")
	)
	(arc
		(start 387.161786 -229.58171)
		(mid 387.444742 -229.657887)
		(end 387.727698 -229.58171)
		(width 0.0889)
		(layer "In13.Cu")
		(net "M_H_CPU0_SA_DQ<7>")
	)
	(arc
		(start 383.967736 -229.58171)
		(mid 384.149987 -229.531326)
		(end 384.333496 -229.576884)
		(width 0.0889)
		(layer "In13.Cu")
		(net "M_H_CPU0_SA_DQ<7>")
	)
	(arc
		(start 384.341878 -229.58171)
		(mid 384.624834 -229.657887)
		(end 384.90779 -229.58171)
		(width 0.0889)
		(layer "In13.Cu")
		(net "M_H_CPU0_SA_DQ<7>")
	)
	(arc
		(start 388.667752 -229.58171)
		(mid 388.850003 -229.531326)
		(end 389.033512 -229.576884)
		(width 0.0889)
		(layer "In13.Cu")
		(net "M_H_CPU0_SA_DQ<7>")
	)
	(arc
		(start 389.616188 -229.576884)
		(mid 389.799696 -229.531359)
		(end 389.981948 -229.58171)
		(width 0.0889)
		(layer "In13.Cu")
		(net "M_H_CPU0_SA_DQ<7>")
	)
	(arc
		(start 382.524508 -229.613206)
		(mid 382.77983 -229.656906)
		(end 383.027682 -229.58171)
		(width 0.0889)
		(layer "In13.Cu")
		(net "M_H_CPU0_SA_DQ<7>")
	)
	(arc
		(start 391.300208 -228.284278)
		(mid 391.341757 -228.112856)
		(end 391.45718 -227.979478)
		(width 0.0889)
		(layer "In13.Cu")
		(net "M_H_CPU0_SA_DQ<7>")
	)
	(segment
		(start 383.217928 -229.360222)
		(end 383.68478 -229.094284)
		(width 0.10668)
		(layer "F.Cu")
		(net "M_H_CPU0_SA_DQ<6>")
	)
	(segment
		(start 393.332716 -223.12249)
		(end 393.368276 -223.101916)
		(width 0.0889)
		(layer "In13.Cu")
		(net "M_H_CPU0_SA_DQ<6>")
	)
	(segment
		(start 394.229082 -222.35541)
		(end 394.229082 -222.085154)
		(width 0.0889)
		(layer "In13.Cu")
		(net "M_H_CPU0_SA_DQ<6>")
	)
	(segment
		(start 388.197852 -228.771704)
		(end 388.206234 -228.766878)
		(width 0.0889)
		(layer "In13.Cu")
		(net "M_H_CPU0_SA_DQ<6>")
	)
	(segment
		(start 403.239986 -210.556348)
		(end 403.425152 -210.371182)
		(width 0.14478)
		(layer "In13.Cu")
		(net "M_H_CPU0_SA_DQ<6>")
	)
	(segment
		(start 402.735034 -210.460844)
		(end 402.939758 -210.460844)
		(width 0.14478)
		(layer "In13.Cu")
		(net "M_H_CPU0_SA_DQ<6>")
	)
	(segment
		(start 391.957814 -225.53168)
		(end 391.99693 -225.50882)
		(width 0.0889)
		(layer "In13.Cu")
		(net "M_H_CPU0_SA_DQ<6>")
	)
	(segment
		(start 408.99334 -204.56017)
		(end 409.13812 -204.70495)
		(width 0.14478)
		(layer "In13.Cu")
		(net "M_H_CPU0_SA_DQ<6>")
	)
	(segment
		(start 405.579326 -208.217008)
		(end 405.764492 -208.031842)
		(width 0.14478)
		(layer "In13.Cu")
		(net "M_H_CPU0_SA_DQ<6>")
	)
	(segment
		(start 405.764492 -208.031842)
		(end 405.764492 -207.827118)
		(width 0.14478)
		(layer "In13.Cu")
		(net "M_H_CPU0_SA_DQ<6>")
	)
	(segment
		(start 402.939758 -210.460844)
		(end 403.035262 -210.556348)
		(width 0.14478)
		(layer "In13.Cu")
		(net "M_H_CPU0_SA_DQ<6>")
	)
	(segment
		(start 392.897868 -223.911668)
		(end 392.93419 -223.890586)
		(width 0.0889)
		(layer "In13.Cu")
		(net "M_H_CPU0_SA_DQ<6>")
	)
	(segment
		(start 405.764492 -207.827118)
		(end 405.668988 -207.731614)
		(width 0.14478)
		(layer "In13.Cu")
		(net "M_H_CPU0_SA_DQ<6>")
	)
	(segment
		(start 409.6893 -205.171548)
		(end 409.6893 -204.70495)
		(width 0.14478)
		(layer "In13.Cu")
		(net "M_H_CPU0_SA_DQ<6>")
	)
	(segment
		(start 403.329648 -210.070954)
		(end 403.329648 -209.86623)
		(width 0.14478)
		(layer "In13.Cu")
		(net "M_H_CPU0_SA_DQ<6>")
	)
	(segment
		(start 391.45718 -226.359466)
		(end 391.48766 -226.341686)
		(width 0.0889)
		(layer "In13.Cu")
		(net "M_H_CPU0_SA_DQ<6>")
	)
	(segment
		(start 391.926064 -225.549968)
		(end 391.957814 -225.53168)
		(width 0.0889)
		(layer "In13.Cu")
		(net "M_H_CPU0_SA_DQ<6>")
	)
	(segment
		(start 407.324052 -206.267558)
		(end 407.228548 -206.172054)
		(width 0.14478)
		(layer "In13.Cu")
		(net "M_H_CPU0_SA_DQ<6>")
	)
	(segment
		(start 394.229082 -222.085154)
		(end 394.229082 -218.966796)
		(width 0.14478)
		(layer "In13.Cu")
		(net "M_H_CPU0_SA_DQ<6>")
	)
	(segment
		(start 406.058878 -207.341724)
		(end 406.154382 -207.437228)
		(width 0.14478)
		(layer "In13.Cu")
		(net "M_H_CPU0_SA_DQ<6>")
	)
	(segment
		(start 418.379148 -204.56017)
		(end 419.486842 -204.56017)
		(width 0.14478)
		(layer "In13.Cu")
		(net "M_H_CPU0_SA_DQ<6>")
	)
	(segment
		(start 410.24048 -204.70495)
		(end 410.24048 -205.171548)
		(width 0.14478)
		(layer "In13.Cu")
		(net "M_H_CPU0_SA_DQ<6>")
	)
	(segment
		(start 406.448768 -206.74711)
		(end 406.633934 -206.561944)
		(width 0.14478)
		(layer "In13.Cu")
		(net "M_H_CPU0_SA_DQ<6>")
	)
	(segment
		(start 390.98601 -227.16998)
		(end 391.01776 -227.151692)
		(width 0.0889)
		(layer "In13.Cu")
		(net "M_H_CPU0_SA_DQ<6>")
	)
	(segment
		(start 385.74345 -228.766878)
		(end 385.751832 -228.771704)
		(width 0.0889)
		(layer "In13.Cu")
		(net "M_H_CPU0_SA_DQ<6>")
	)
	(segment
		(start 409.83408 -204.56017)
		(end 410.0957 -204.56017)
		(width 0.14478)
		(layer "In13.Cu")
		(net "M_H_CPU0_SA_DQ<6>")
	)
	(segment
		(start 407.918666 -205.877668)
		(end 408.103832 -205.692502)
		(width 0.14478)
		(layer "In13.Cu")
		(net "M_H_CPU0_SA_DQ<6>")
	)
	(segment
		(start 410.64688 -205.316328)
		(end 410.79166 -205.171548)
		(width 0.14478)
		(layer "In13.Cu")
		(net "M_H_CPU0_SA_DQ<6>")
	)
	(segment
		(start 386.683504 -228.766878)
		(end 386.691886 -228.771704)
		(width 0.0889)
		(layer "In13.Cu")
		(net "M_H_CPU0_SA_DQ<6>")
	)
	(segment
		(start 404.204932 -209.386678)
		(end 404.109428 -209.291174)
		(width 0.14478)
		(layer "In13.Cu")
		(net "M_H_CPU0_SA_DQ<6>")
	)
	(segment
		(start 405.374602 -208.217008)
		(end 405.579326 -208.217008)
		(width 0.14478)
		(layer "In13.Cu")
		(net "M_H_CPU0_SA_DQ<6>")
	)
	(segment
		(start 407.324052 -206.472282)
		(end 407.324052 -206.267558)
		(width 0.14478)
		(layer "In13.Cu")
		(net "M_H_CPU0_SA_DQ<6>")
	)
	(segment
		(start 407.413714 -205.782164)
		(end 407.618438 -205.782164)
		(width 0.14478)
		(layer "In13.Cu")
		(net "M_H_CPU0_SA_DQ<6>")
	)
	(segment
		(start 390.077706 -228.771704)
		(end 390.116822 -228.748844)
		(width 0.0889)
		(layer "In13.Cu")
		(net "M_H_CPU0_SA_DQ<6>")
	)
	(segment
		(start 392.427714 -224.721674)
		(end 392.46683 -224.698814)
		(width 0.0889)
		(layer "In13.Cu")
		(net "M_H_CPU0_SA_DQ<6>")
	)
	(segment
		(start 406.838658 -206.561944)
		(end 406.934162 -206.657448)
		(width 0.14478)
		(layer "In13.Cu")
		(net "M_H_CPU0_SA_DQ<6>")
	)
	(segment
		(start 417.52901 -203.710032)
		(end 418.379148 -204.56017)
		(width 0.14478)
		(layer "In13.Cu")
		(net "M_H_CPU0_SA_DQ<6>")
	)
	(segment
		(start 394.229082 -218.966796)
		(end 402.735034 -210.460844)
		(width 0.14478)
		(layer "In13.Cu")
		(net "M_H_CPU0_SA_DQ<6>")
	)
	(segment
		(start 405.854154 -207.341724)
		(end 406.058878 -207.341724)
		(width 0.14478)
		(layer "In13.Cu")
		(net "M_H_CPU0_SA_DQ<6>")
	)
	(segment
		(start 409.6893 -204.70495)
		(end 409.83408 -204.56017)
		(width 0.14478)
		(layer "In13.Cu")
		(net "M_H_CPU0_SA_DQ<6>")
	)
	(segment
		(start 404.109428 -209.08645)
		(end 404.294594 -208.901284)
		(width 0.14478)
		(layer "In13.Cu")
		(net "M_H_CPU0_SA_DQ<6>")
	)
	(segment
		(start 414.168082 -204.56017)
		(end 415.01822 -203.710032)
		(width 0.14478)
		(layer "In13.Cu")
		(net "M_H_CPU0_SA_DQ<6>")
	)
	(segment
		(start 403.425152 -210.371182)
		(end 403.425152 -210.166458)
		(width 0.14478)
		(layer "In13.Cu")
		(net "M_H_CPU0_SA_DQ<6>")
	)
	(segment
		(start 406.359106 -207.437228)
		(end 406.544272 -207.252062)
		(width 0.14478)
		(layer "In13.Cu")
		(net "M_H_CPU0_SA_DQ<6>")
	)
	(segment
		(start 409.13812 -204.70495)
		(end 409.13812 -205.171548)
		(width 0.14478)
		(layer "In13.Cu")
		(net "M_H_CPU0_SA_DQ<6>")
	)
	(segment
		(start 406.544272 -207.047338)
		(end 406.448768 -206.951834)
		(width 0.14478)
		(layer "In13.Cu")
		(net "M_H_CPU0_SA_DQ<6>")
	)
	(segment
		(start 406.934162 -206.657448)
		(end 407.138886 -206.657448)
		(width 0.14478)
		(layer "In13.Cu")
		(net "M_H_CPU0_SA_DQ<6>")
	)
	(segment
		(start 403.815042 -209.776568)
		(end 404.019766 -209.776568)
		(width 0.14478)
		(layer "In13.Cu")
		(net "M_H_CPU0_SA_DQ<6>")
	)
	(segment
		(start 404.019766 -209.776568)
		(end 404.204932 -209.591402)
		(width 0.14478)
		(layer "In13.Cu")
		(net "M_H_CPU0_SA_DQ<6>")
	)
	(segment
		(start 403.425152 -210.166458)
		(end 403.329648 -210.070954)
		(width 0.14478)
		(layer "In13.Cu")
		(net "M_H_CPU0_SA_DQ<6>")
	)
	(segment
		(start 409.2829 -205.316328)
		(end 409.54452 -205.316328)
		(width 0.14478)
		(layer "In13.Cu")
		(net "M_H_CPU0_SA_DQ<6>")
	)
	(segment
		(start 404.204932 -209.591402)
		(end 404.204932 -209.386678)
		(width 0.14478)
		(layer "In13.Cu")
		(net "M_H_CPU0_SA_DQ<6>")
	)
	(segment
		(start 392.397234 -224.739454)
		(end 392.427714 -224.721674)
		(width 0.0889)
		(layer "In13.Cu")
		(net "M_H_CPU0_SA_DQ<6>")
	)
	(segment
		(start 393.624562 -222.95993)
		(end 394.229082 -222.35541)
		(width 0.0889)
		(layer "In13.Cu")
		(net "M_H_CPU0_SA_DQ<6>")
	)
	(segment
		(start 406.448768 -206.951834)
		(end 406.448768 -206.74711)
		(width 0.14478)
		(layer "In13.Cu")
		(net "M_H_CPU0_SA_DQ<6>")
	)
	(segment
		(start 405.074374 -208.121504)
		(end 405.279098 -208.121504)
		(width 0.14478)
		(layer "In13.Cu")
		(net "M_H_CPU0_SA_DQ<6>")
	)
	(segment
		(start 410.0957 -204.56017)
		(end 410.24048 -204.70495)
		(width 0.14478)
		(layer "In13.Cu")
		(net "M_H_CPU0_SA_DQ<6>")
	)
	(segment
		(start 405.668988 -207.731614)
		(end 405.668988 -207.52689)
		(width 0.14478)
		(layer "In13.Cu")
		(net "M_H_CPU0_SA_DQ<6>")
	)
	(segment
		(start 387.257798 -228.771704)
		(end 387.26618 -228.766878)
		(width 0.0889)
		(layer "In13.Cu")
		(net "M_H_CPU0_SA_DQ<6>")
	)
	(segment
		(start 404.109428 -209.291174)
		(end 404.109428 -209.08645)
		(width 0.14478)
		(layer "In13.Cu")
		(net "M_H_CPU0_SA_DQ<6>")
	)
	(segment
		(start 408.635708 -204.56017)
		(end 408.99334 -204.56017)
		(width 0.14478)
		(layer "In13.Cu")
		(net "M_H_CPU0_SA_DQ<6>")
	)
	(segment
		(start 406.633934 -206.561944)
		(end 406.838658 -206.561944)
		(width 0.14478)
		(layer "In13.Cu")
		(net "M_H_CPU0_SA_DQ<6>")
	)
	(segment
		(start 403.514814 -209.681064)
		(end 403.719538 -209.681064)
		(width 0.14478)
		(layer "In13.Cu")
		(net "M_H_CPU0_SA_DQ<6>")
	)
	(segment
		(start 403.719538 -209.681064)
		(end 403.815042 -209.776568)
		(width 0.14478)
		(layer "In13.Cu")
		(net "M_H_CPU0_SA_DQ<6>")
	)
	(segment
		(start 405.668988 -207.52689)
		(end 405.854154 -207.341724)
		(width 0.14478)
		(layer "In13.Cu")
		(net "M_H_CPU0_SA_DQ<6>")
	)
	(segment
		(start 390.54786 -227.961698)
		(end 390.584182 -227.940616)
		(width 0.0889)
		(layer "In13.Cu")
		(net "M_H_CPU0_SA_DQ<6>")
	)
	(segment
		(start 406.154382 -207.437228)
		(end 406.359106 -207.437228)
		(width 0.14478)
		(layer "In13.Cu")
		(net "M_H_CPU0_SA_DQ<6>")
	)
	(segment
		(start 419.486842 -204.56017)
		(end 419.912038 -204.134974)
		(width 0.14478)
		(layer "In13.Cu")
		(net "M_H_CPU0_SA_DQ<6>")
	)
	(segment
		(start 405.279098 -208.121504)
		(end 405.374602 -208.217008)
		(width 0.14478)
		(layer "In13.Cu")
		(net "M_H_CPU0_SA_DQ<6>")
	)
	(segment
		(start 407.713942 -205.877668)
		(end 407.918666 -205.877668)
		(width 0.14478)
		(layer "In13.Cu")
		(net "M_H_CPU0_SA_DQ<6>")
	)
	(segment
		(start 410.79166 -205.171548)
		(end 410.79166 -204.70495)
		(width 0.14478)
		(layer "In13.Cu")
		(net "M_H_CPU0_SA_DQ<6>")
	)
	(segment
		(start 409.54452 -205.316328)
		(end 409.6893 -205.171548)
		(width 0.14478)
		(layer "In13.Cu")
		(net "M_H_CPU0_SA_DQ<6>")
	)
	(segment
		(start 393.368276 -223.101916)
		(end 393.624562 -222.95993)
		(width 0.0889)
		(layer "In13.Cu")
		(net "M_H_CPU0_SA_DQ<6>")
	)
	(segment
		(start 409.13812 -205.171548)
		(end 409.2829 -205.316328)
		(width 0.14478)
		(layer "In13.Cu")
		(net "M_H_CPU0_SA_DQ<6>")
	)
	(segment
		(start 408.103832 -205.692502)
		(end 408.103832 -205.487778)
		(width 0.14478)
		(layer "In13.Cu")
		(net "M_H_CPU0_SA_DQ<6>")
	)
	(segment
		(start 406.544272 -207.252062)
		(end 406.544272 -207.047338)
		(width 0.14478)
		(layer "In13.Cu")
		(net "M_H_CPU0_SA_DQ<6>")
	)
	(segment
		(start 403.329648 -209.86623)
		(end 403.514814 -209.681064)
		(width 0.14478)
		(layer "In13.Cu")
		(net "M_H_CPU0_SA_DQ<6>")
	)
	(segment
		(start 404.799546 -208.996788)
		(end 404.984712 -208.811622)
		(width 0.14478)
		(layer "In13.Cu")
		(net "M_H_CPU0_SA_DQ<6>")
	)
	(segment
		(start 408.008328 -205.392274)
		(end 408.008328 -205.18755)
		(width 0.14478)
		(layer "In13.Cu")
		(net "M_H_CPU0_SA_DQ<6>")
	)
	(segment
		(start 410.24048 -205.171548)
		(end 410.38526 -205.316328)
		(width 0.14478)
		(layer "In13.Cu")
		(net "M_H_CPU0_SA_DQ<6>")
	)
	(segment
		(start 407.618438 -205.782164)
		(end 407.713942 -205.877668)
		(width 0.14478)
		(layer "In13.Cu")
		(net "M_H_CPU0_SA_DQ<6>")
	)
	(segment
		(start 404.984712 -208.811622)
		(end 404.984712 -208.606898)
		(width 0.14478)
		(layer "In13.Cu")
		(net "M_H_CPU0_SA_DQ<6>")
	)
	(segment
		(start 383.838958 -228.828854)
		(end 383.935224 -228.803454)
		(width 0.0889)
		(layer "In13.Cu")
		(net "M_H_CPU0_SA_DQ<6>")
	)
	(segment
		(start 415.01822 -203.710032)
		(end 417.52901 -203.710032)
		(width 0.14478)
		(layer "In13.Cu")
		(net "M_H_CPU0_SA_DQ<6>")
	)
	(segment
		(start 410.93644 -204.56017)
		(end 414.168082 -204.56017)
		(width 0.14478)
		(layer "In13.Cu")
		(net "M_H_CPU0_SA_DQ<6>")
	)
	(segment
		(start 391.48766 -226.341686)
		(end 391.526776 -226.318826)
		(width 0.0889)
		(layer "In13.Cu")
		(net "M_H_CPU0_SA_DQ<6>")
	)
	(segment
		(start 404.499318 -208.901284)
		(end 404.594822 -208.996788)
		(width 0.14478)
		(layer "In13.Cu")
		(net "M_H_CPU0_SA_DQ<6>")
	)
	(segment
		(start 410.79166 -204.70495)
		(end 410.93644 -204.56017)
		(width 0.14478)
		(layer "In13.Cu")
		(net "M_H_CPU0_SA_DQ<6>")
	)
	(segment
		(start 408.008328 -205.18755)
		(end 408.635708 -204.56017)
		(width 0.14478)
		(layer "In13.Cu")
		(net "M_H_CPU0_SA_DQ<6>")
	)
	(segment
		(start 408.103832 -205.487778)
		(end 408.008328 -205.392274)
		(width 0.14478)
		(layer "In13.Cu")
		(net "M_H_CPU0_SA_DQ<6>")
	)
	(segment
		(start 383.68478 -229.094284)
		(end 383.838958 -228.828854)
		(width 0.0889)
		(layer "In13.Cu")
		(net "M_H_CPU0_SA_DQ<6>")
	)
	(segment
		(start 404.984712 -208.606898)
		(end 404.889208 -208.511394)
		(width 0.14478)
		(layer "In13.Cu")
		(net "M_H_CPU0_SA_DQ<6>")
	)
	(segment
		(start 407.138886 -206.657448)
		(end 407.324052 -206.472282)
		(width 0.14478)
		(layer "In13.Cu")
		(net "M_H_CPU0_SA_DQ<6>")
	)
	(segment
		(start 404.594822 -208.996788)
		(end 404.799546 -208.996788)
		(width 0.14478)
		(layer "In13.Cu")
		(net "M_H_CPU0_SA_DQ<6>")
	)
	(segment
		(start 404.294594 -208.901284)
		(end 404.499318 -208.901284)
		(width 0.14478)
		(layer "In13.Cu")
		(net "M_H_CPU0_SA_DQ<6>")
	)
	(segment
		(start 392.866118 -223.929956)
		(end 392.897868 -223.911668)
		(width 0.0889)
		(layer "In13.Cu")
		(net "M_H_CPU0_SA_DQ<6>")
	)
	(segment
		(start 404.889208 -208.30667)
		(end 405.074374 -208.121504)
		(width 0.14478)
		(layer "In13.Cu")
		(net "M_H_CPU0_SA_DQ<6>")
	)
	(segment
		(start 410.38526 -205.316328)
		(end 410.64688 -205.316328)
		(width 0.14478)
		(layer "In13.Cu")
		(net "M_H_CPU0_SA_DQ<6>")
	)
	(segment
		(start 404.889208 -208.511394)
		(end 404.889208 -208.30667)
		(width 0.14478)
		(layer "In13.Cu")
		(net "M_H_CPU0_SA_DQ<6>")
	)
	(segment
		(start 407.228548 -206.172054)
		(end 407.228548 -205.96733)
		(width 0.14478)
		(layer "In13.Cu")
		(net "M_H_CPU0_SA_DQ<6>")
	)
	(segment
		(start 390.51611 -227.979986)
		(end 390.54786 -227.961698)
		(width 0.0889)
		(layer "In13.Cu")
		(net "M_H_CPU0_SA_DQ<6>")
	)
	(segment
		(start 407.228548 -205.96733)
		(end 407.413714 -205.782164)
		(width 0.14478)
		(layer "In13.Cu")
		(net "M_H_CPU0_SA_DQ<6>")
	)
	(segment
		(start 391.01776 -227.151692)
		(end 391.056876 -227.128832)
		(width 0.0889)
		(layer "In13.Cu")
		(net "M_H_CPU0_SA_DQ<6>")
	)
	(segment
		(start 403.035262 -210.556348)
		(end 403.239986 -210.556348)
		(width 0.14478)
		(layer "In13.Cu")
		(net "M_H_CPU0_SA_DQ<6>")
	)
	(arc
		(start 393.180062 -223.424242)
		(mid 393.220391 -223.25515)
		(end 393.332716 -223.12249)
		(width 0.0889)
		(layer "In13.Cu")
		(net "M_H_CPU0_SA_DQ<6>")
	)
	(arc
		(start 390.360154 -228.284278)
		(mid 390.401409 -228.113307)
		(end 390.51611 -227.979986)
		(width 0.0889)
		(layer "In13.Cu")
		(net "M_H_CPU0_SA_DQ<6>")
	)
	(arc
		(start 388.206234 -228.766878)
		(mid 388.389742 -228.721384)
		(end 388.571994 -228.771704)
		(width 0.0889)
		(layer "In13.Cu")
		(net "M_H_CPU0_SA_DQ<6>")
	)
	(arc
		(start 392.93419 -223.890586)
		(mid 393.114842 -223.687841)
		(end 393.180062 -223.424242)
		(width 0.0889)
		(layer "In13.Cu")
		(net "M_H_CPU0_SA_DQ<6>")
	)
	(arc
		(start 385.751832 -228.771704)
		(mid 386.034788 -228.847881)
		(end 386.317744 -228.771704)
		(width 0.0889)
		(layer "In13.Cu")
		(net "M_H_CPU0_SA_DQ<6>")
	)
	(arc
		(start 390.830054 -227.474272)
		(mid 390.871309 -227.303301)
		(end 390.98601 -227.16998)
		(width 0.0889)
		(layer "In13.Cu")
		(net "M_H_CPU0_SA_DQ<6>")
	)
	(arc
		(start 392.240262 -225.044254)
		(mid 392.281811 -224.872832)
		(end 392.397234 -224.739454)
		(width 0.0889)
		(layer "In13.Cu")
		(net "M_H_CPU0_SA_DQ<6>")
	)
	(arc
		(start 390.584182 -227.940616)
		(mid 390.764834 -227.737871)
		(end 390.830054 -227.474272)
		(width 0.0889)
		(layer "In13.Cu")
		(net "M_H_CPU0_SA_DQ<6>")
	)
	(arc
		(start 386.691886 -228.771704)
		(mid 386.974842 -228.847881)
		(end 387.257798 -228.771704)
		(width 0.0889)
		(layer "In13.Cu")
		(net "M_H_CPU0_SA_DQ<6>")
	)
	(arc
		(start 391.770108 -225.85426)
		(mid 391.811363 -225.683289)
		(end 391.926064 -225.549968)
		(width 0.0889)
		(layer "In13.Cu")
		(net "M_H_CPU0_SA_DQ<6>")
	)
	(arc
		(start 384.811778 -228.771704)
		(mid 385.094734 -228.847881)
		(end 385.37769 -228.771704)
		(width 0.0889)
		(layer "In13.Cu")
		(net "M_H_CPU0_SA_DQ<6>")
	)
	(arc
		(start 384.43789 -228.771704)
		(mid 384.624834 -228.721449)
		(end 384.811778 -228.771704)
		(width 0.0889)
		(layer "In13.Cu")
		(net "M_H_CPU0_SA_DQ<6>")
	)
	(arc
		(start 387.26618 -228.766878)
		(mid 387.449688 -228.721384)
		(end 387.63194 -228.771704)
		(width 0.0889)
		(layer "In13.Cu")
		(net "M_H_CPU0_SA_DQ<6>")
	)
	(arc
		(start 389.511794 -228.771704)
		(mid 389.79475 -228.847881)
		(end 390.077706 -228.771704)
		(width 0.0889)
		(layer "In13.Cu")
		(net "M_H_CPU0_SA_DQ<6>")
	)
	(arc
		(start 391.056876 -227.128832)
		(mid 391.235689 -226.926482)
		(end 391.300208 -226.664266)
		(width 0.0889)
		(layer "In13.Cu")
		(net "M_H_CPU0_SA_DQ<6>")
	)
	(arc
		(start 389.137906 -228.771704)
		(mid 389.32485 -228.721449)
		(end 389.511794 -228.771704)
		(width 0.0889)
		(layer "In13.Cu")
		(net "M_H_CPU0_SA_DQ<6>")
	)
	(arc
		(start 391.99693 -225.50882)
		(mid 392.175743 -225.30647)
		(end 392.240262 -225.044254)
		(width 0.0889)
		(layer "In13.Cu")
		(net "M_H_CPU0_SA_DQ<6>")
	)
	(arc
		(start 390.116822 -228.748844)
		(mid 390.295635 -228.546494)
		(end 390.360154 -228.284278)
		(width 0.0889)
		(layer "In13.Cu")
		(net "M_H_CPU0_SA_DQ<6>")
	)
	(arc
		(start 383.935224 -228.803454)
		(mid 384.190289 -228.846805)
		(end 384.43789 -228.771704)
		(width 0.0889)
		(layer "In13.Cu")
		(net "M_H_CPU0_SA_DQ<6>")
	)
	(arc
		(start 386.317744 -228.771704)
		(mid 386.499995 -228.721354)
		(end 386.683504 -228.766878)
		(width 0.0889)
		(layer "In13.Cu")
		(net "M_H_CPU0_SA_DQ<6>")
	)
	(arc
		(start 392.710162 -224.234248)
		(mid 392.751417 -224.063277)
		(end 392.866118 -223.929956)
		(width 0.0889)
		(layer "In13.Cu")
		(net "M_H_CPU0_SA_DQ<6>")
	)
	(arc
		(start 388.571994 -228.771704)
		(mid 388.85495 -228.847881)
		(end 389.137906 -228.771704)
		(width 0.0889)
		(layer "In13.Cu")
		(net "M_H_CPU0_SA_DQ<6>")
	)
	(arc
		(start 392.46683 -224.698814)
		(mid 392.645643 -224.496464)
		(end 392.710162 -224.234248)
		(width 0.0889)
		(layer "In13.Cu")
		(net "M_H_CPU0_SA_DQ<6>")
	)
	(arc
		(start 391.300208 -226.664266)
		(mid 391.341757 -226.492844)
		(end 391.45718 -226.359466)
		(width 0.0889)
		(layer "In13.Cu")
		(net "M_H_CPU0_SA_DQ<6>")
	)
	(arc
		(start 391.526776 -226.318826)
		(mid 391.705589 -226.116476)
		(end 391.770108 -225.85426)
		(width 0.0889)
		(layer "In13.Cu")
		(net "M_H_CPU0_SA_DQ<6>")
	)
	(arc
		(start 385.37769 -228.771704)
		(mid 385.559941 -228.721354)
		(end 385.74345 -228.766878)
		(width 0.0889)
		(layer "In13.Cu")
		(net "M_H_CPU0_SA_DQ<6>")
	)
	(arc
		(start 387.63194 -228.771704)
		(mid 387.914896 -228.847881)
		(end 388.197852 -228.771704)
		(width 0.0889)
		(layer "In13.Cu")
		(net "M_H_CPU0_SA_DQ<6>")
	)
	(segment
		(start 382.277874 -229.360222)
		(end 382.744726 -229.094284)
		(width 0.10668)
		(layer "F.Cu")
		(net "M_H_CPU0_SA_DQ<5>")
	)
	(segment
		(start 415.012124 -204.56017)
		(end 413.761682 -205.810612)
		(width 0.14478)
		(layer "In13.Cu")
		(net "M_H_CPU0_SA_DQ<5>")
	)
	(segment
		(start 417.619688 -204.56017)
		(end 415.012124 -204.56017)
		(width 0.14478)
		(layer "In13.Cu")
		(net "M_H_CPU0_SA_DQ<5>")
	)
	(segment
		(start 420.839392 -204.985112)
		(end 420.41445 -205.410054)
		(width 0.14478)
		(layer "In13.Cu")
		(net "M_H_CPU0_SA_DQ<5>")
	)
	(segment
		(start 390.921748 -228.606858)
		(end 390.885426 -228.62794)
		(width 0.0889)
		(layer "In13.Cu")
		(net "M_H_CPU0_SA_DQ<5>")
	)
	(segment
		(start 394.678662 -222.06712)
		(end 394.678662 -222.678244)
		(width 0.0889)
		(layer "In13.Cu")
		(net "M_H_CPU0_SA_DQ<5>")
	)
	(segment
		(start 383.506218 -229.421436)
		(end 383.497836 -229.41661)
		(width 0.0889)
		(layer "In13.Cu")
		(net "M_H_CPU0_SA_DQ<5>")
	)
	(segment
		(start 387.26618 -229.421436)
		(end 387.257798 -229.41661)
		(width 0.0889)
		(layer "In13.Cu")
		(net "M_H_CPU0_SA_DQ<5>")
	)
	(segment
		(start 393.535916 -224.12071)
		(end 393.535916 -224.64395)
		(width 0.0889)
		(layer "In13.Cu")
		(net "M_H_CPU0_SA_DQ<5>")
	)
	(segment
		(start 385.751832 -229.41661)
		(end 385.74345 -229.421436)
		(width 0.0889)
		(layer "In13.Cu")
		(net "M_H_CPU0_SA_DQ<5>")
	)
	(segment
		(start 382.590802 -229.359714)
		(end 382.744726 -229.094284)
		(width 0.0889)
		(layer "In13.Cu")
		(net "M_H_CPU0_SA_DQ<5>")
	)
	(segment
		(start 393.535916 -224.64395)
		(end 392.654536 -225.52533)
		(width 0.0889)
		(layer "In13.Cu")
		(net "M_H_CPU0_SA_DQ<5>")
	)
	(segment
		(start 394.069316 -223.28759)
		(end 394.069316 -223.58731)
		(width 0.0889)
		(layer "In13.Cu")
		(net "M_H_CPU0_SA_DQ<5>")
	)
	(segment
		(start 422.527984 -204.985112)
		(end 420.839392 -204.985112)
		(width 0.14478)
		(layer "In13.Cu")
		(net "M_H_CPU0_SA_DQ<5>")
	)
	(segment
		(start 413.761682 -205.810612)
		(end 408.631898 -205.810612)
		(width 0.14478)
		(layer "In13.Cu")
		(net "M_H_CPU0_SA_DQ<5>")
	)
	(segment
		(start 391.463784 -227.733352)
		(end 391.391902 -227.796852)
		(width 0.0889)
		(layer "In13.Cu")
		(net "M_H_CPU0_SA_DQ<5>")
	)
	(segment
		(start 391.391902 -227.796852)
		(end 391.352786 -227.819712)
		(width 0.0889)
		(layer "In13.Cu")
		(net "M_H_CPU0_SA_DQ<5>")
	)
	(segment
		(start 388.206234 -229.421436)
		(end 388.197852 -229.41661)
		(width 0.0889)
		(layer "In13.Cu")
		(net "M_H_CPU0_SA_DQ<5>")
	)
	(segment
		(start 390.953498 -228.58857)
		(end 390.921748 -228.606858)
		(width 0.0889)
		(layer "In13.Cu")
		(net "M_H_CPU0_SA_DQ<5>")
	)
	(segment
		(start 392.654536 -225.52533)
		(end 392.654536 -226.5426)
		(width 0.0889)
		(layer "In13.Cu")
		(net "M_H_CPU0_SA_DQ<5>")
	)
	(segment
		(start 420.41445 -205.410054)
		(end 418.469572 -205.410054)
		(width 0.14478)
		(layer "In13.Cu")
		(net "M_H_CPU0_SA_DQ<5>")
	)
	(segment
		(start 424.012106 -204.985112)
		(end 423.354246 -204.985112)
		(width 0.14478)
		(layer "In13.Cu")
		(net "M_H_CPU0_SA_DQ<5>")
	)
	(segment
		(start 418.469572 -205.410054)
		(end 417.619688 -204.56017)
		(width 0.14478)
		(layer "In13.Cu")
		(net "M_H_CPU0_SA_DQ<5>")
	)
	(segment
		(start 386.691886 -229.41661)
		(end 386.683504 -229.421436)
		(width 0.0889)
		(layer "In13.Cu")
		(net "M_H_CPU0_SA_DQ<5>")
	)
	(segment
		(start 390.451848 -229.41661)
		(end 390.443466 -229.421436)
		(width 0.0889)
		(layer "In13.Cu")
		(net "M_H_CPU0_SA_DQ<5>")
	)
	(segment
		(start 423.354246 -204.985112)
		(end 423.079164 -205.260194)
		(width 0.14478)
		(layer "In13.Cu")
		(net "M_H_CPU0_SA_DQ<5>")
	)
	(segment
		(start 382.613154 -229.442772)
		(end 382.590802 -229.359714)
		(width 0.0889)
		(layer "In13.Cu")
		(net "M_H_CPU0_SA_DQ<5>")
	)
	(segment
		(start 408.631898 -205.810612)
		(end 403.303994 -211.138516)
		(width 0.14478)
		(layer "In13.Cu")
		(net "M_H_CPU0_SA_DQ<5>")
	)
	(segment
		(start 390.485376 -229.397052)
		(end 390.451848 -229.41661)
		(width 0.0889)
		(layer "In13.Cu")
		(net "M_H_CPU0_SA_DQ<5>")
	)
	(segment
		(start 394.069316 -223.58731)
		(end 393.535916 -224.12071)
		(width 0.0889)
		(layer "In13.Cu")
		(net "M_H_CPU0_SA_DQ<5>")
	)
	(segment
		(start 394.678662 -219.153232)
		(end 394.678662 -222.06712)
		(width 0.14478)
		(layer "In13.Cu")
		(net "M_H_CPU0_SA_DQ<5>")
	)
	(segment
		(start 394.678662 -222.678244)
		(end 394.069316 -223.28759)
		(width 0.0889)
		(layer "In13.Cu")
		(net "M_H_CPU0_SA_DQ<5>")
	)
	(segment
		(start 392.654536 -226.5426)
		(end 391.463784 -227.733352)
		(width 0.0889)
		(layer "In13.Cu")
		(net "M_H_CPU0_SA_DQ<5>")
	)
	(segment
		(start 403.303994 -211.138516)
		(end 402.693378 -211.138516)
		(width 0.14478)
		(layer "In13.Cu")
		(net "M_H_CPU0_SA_DQ<5>")
	)
	(segment
		(start 402.693378 -211.138516)
		(end 394.678662 -219.153232)
		(width 0.14478)
		(layer "In13.Cu")
		(net "M_H_CPU0_SA_DQ<5>")
	)
	(segment
		(start 423.079164 -205.260194)
		(end 422.803066 -205.260194)
		(width 0.14478)
		(layer "In13.Cu")
		(net "M_H_CPU0_SA_DQ<5>")
	)
	(segment
		(start 422.803066 -205.260194)
		(end 422.527984 -204.985112)
		(width 0.14478)
		(layer "In13.Cu")
		(net "M_H_CPU0_SA_DQ<5>")
	)
	(arc
		(start 383.871978 -229.41661)
		(mid 383.689727 -229.466994)
		(end 383.506218 -229.421436)
		(width 0.0889)
		(layer "In13.Cu")
		(net "M_H_CPU0_SA_DQ<5>")
	)
	(arc
		(start 387.63194 -229.41661)
		(mid 387.449689 -229.466994)
		(end 387.26618 -229.421436)
		(width 0.0889)
		(layer "In13.Cu")
		(net "M_H_CPU0_SA_DQ<5>")
	)
	(arc
		(start 390.639554 -229.094284)
		(mid 390.598792 -229.264168)
		(end 390.485376 -229.397052)
		(width 0.0889)
		(layer "In13.Cu")
		(net "M_H_CPU0_SA_DQ<5>")
	)
	(arc
		(start 389.137906 -229.41661)
		(mid 388.85495 -229.340433)
		(end 388.571994 -229.41661)
		(width 0.0889)
		(layer "In13.Cu")
		(net "M_H_CPU0_SA_DQ<5>")
	)
	(arc
		(start 388.571994 -229.41661)
		(mid 388.389743 -229.466994)
		(end 388.206234 -229.421436)
		(width 0.0889)
		(layer "In13.Cu")
		(net "M_H_CPU0_SA_DQ<5>")
	)
	(arc
		(start 384.43789 -229.41661)
		(mid 384.154934 -229.340433)
		(end 383.871978 -229.41661)
		(width 0.0889)
		(layer "In13.Cu")
		(net "M_H_CPU0_SA_DQ<5>")
	)
	(arc
		(start 382.931924 -229.41661)
		(mid 382.775486 -229.465615)
		(end 382.613154 -229.442772)
		(width 0.0889)
		(layer "In13.Cu")
		(net "M_H_CPU0_SA_DQ<5>")
	)
	(arc
		(start 387.257798 -229.41661)
		(mid 386.974842 -229.340433)
		(end 386.691886 -229.41661)
		(width 0.0889)
		(layer "In13.Cu")
		(net "M_H_CPU0_SA_DQ<5>")
	)
	(arc
		(start 385.37769 -229.41661)
		(mid 385.094734 -229.340433)
		(end 384.811778 -229.41661)
		(width 0.0889)
		(layer "In13.Cu")
		(net "M_H_CPU0_SA_DQ<5>")
	)
	(arc
		(start 389.511794 -229.41661)
		(mid 389.32485 -229.466899)
		(end 389.137906 -229.41661)
		(width 0.0889)
		(layer "In13.Cu")
		(net "M_H_CPU0_SA_DQ<5>")
	)
	(arc
		(start 384.811778 -229.41661)
		(mid 384.624834 -229.466899)
		(end 384.43789 -229.41661)
		(width 0.0889)
		(layer "In13.Cu")
		(net "M_H_CPU0_SA_DQ<5>")
	)
	(arc
		(start 386.683504 -229.421436)
		(mid 386.499996 -229.466961)
		(end 386.317744 -229.41661)
		(width 0.0889)
		(layer "In13.Cu")
		(net "M_H_CPU0_SA_DQ<5>")
	)
	(arc
		(start 390.443466 -229.421436)
		(mid 390.259958 -229.466961)
		(end 390.077706 -229.41661)
		(width 0.0889)
		(layer "In13.Cu")
		(net "M_H_CPU0_SA_DQ<5>")
	)
	(arc
		(start 390.885426 -228.62794)
		(mid 390.704774 -228.830685)
		(end 390.639554 -229.094284)
		(width 0.0889)
		(layer "In13.Cu")
		(net "M_H_CPU0_SA_DQ<5>")
	)
	(arc
		(start 383.497836 -229.41661)
		(mid 383.21488 -229.340433)
		(end 382.931924 -229.41661)
		(width 0.0889)
		(layer "In13.Cu")
		(net "M_H_CPU0_SA_DQ<5>")
	)
	(arc
		(start 391.352786 -227.819712)
		(mid 391.173973 -228.022062)
		(end 391.109454 -228.284278)
		(width 0.0889)
		(layer "In13.Cu")
		(net "M_H_CPU0_SA_DQ<5>")
	)
	(arc
		(start 391.109454 -228.284278)
		(mid 391.068199 -228.455249)
		(end 390.953498 -228.58857)
		(width 0.0889)
		(layer "In13.Cu")
		(net "M_H_CPU0_SA_DQ<5>")
	)
	(arc
		(start 385.74345 -229.421436)
		(mid 385.559942 -229.466961)
		(end 385.37769 -229.41661)
		(width 0.0889)
		(layer "In13.Cu")
		(net "M_H_CPU0_SA_DQ<5>")
	)
	(arc
		(start 386.317744 -229.41661)
		(mid 386.034788 -229.340433)
		(end 385.751832 -229.41661)
		(width 0.0889)
		(layer "In13.Cu")
		(net "M_H_CPU0_SA_DQ<5>")
	)
	(arc
		(start 390.077706 -229.41661)
		(mid 389.79475 -229.340433)
		(end 389.511794 -229.41661)
		(width 0.0889)
		(layer "In13.Cu")
		(net "M_H_CPU0_SA_DQ<5>")
	)
	(arc
		(start 388.197852 -229.41661)
		(mid 387.914896 -229.340433)
		(end 387.63194 -229.41661)
		(width 0.0889)
		(layer "In13.Cu")
		(net "M_H_CPU0_SA_DQ<5>")
	)
	(segment
		(start 383.688082 -228.550216)
		(end 384.154934 -228.284278)
		(width 0.10668)
		(layer "F.Cu")
		(net "M_H_CPU0_SA_DQ<4>")
	)
	(segment
		(start 422.018206 -203.28509)
		(end 421.583612 -203.719684)
		(width 0.14478)
		(layer "In13.Cu")
		(net "M_H_CPU0_SA_DQ<4>")
	)
	(segment
		(start 422.961816 -204.121766)
		(end 422.817036 -203.976986)
		(width 0.14478)
		(layer "In13.Cu")
		(net "M_H_CPU0_SA_DQ<4>")
	)
	(segment
		(start 417.486084 -202.860148)
		(end 415.120328 -202.860148)
		(width 0.14478)
		(layer "In13.Cu")
		(net "M_H_CPU0_SA_DQ<4>")
	)
	(segment
		(start 384.916172 -228.611684)
		(end 384.90779 -228.606858)
		(width 0.0889)
		(layer "In13.Cu")
		(net "M_H_CPU0_SA_DQ<4>")
	)
	(segment
		(start 390.012428 -228.589078)
		(end 389.981948 -228.606858)
		(width 0.0889)
		(layer "In13.Cu")
		(net "M_H_CPU0_SA_DQ<4>")
	)
	(segment
		(start 392.331956 -224.556828)
		(end 392.29284 -224.579688)
		(width 0.0889)
		(layer "In13.Cu")
		(net "M_H_CPU0_SA_DQ<4>")
	)
	(segment
		(start 422.672256 -203.28509)
		(end 422.018206 -203.28509)
		(width 0.14478)
		(layer "In13.Cu")
		(net "M_H_CPU0_SA_DQ<4>")
	)
	(segment
		(start 391.861802 -225.366834)
		(end 391.822686 -225.389694)
		(width 0.0889)
		(layer "In13.Cu")
		(net "M_H_CPU0_SA_DQ<4>")
	)
	(segment
		(start 424.012106 -203.28509)
		(end 423.512996 -203.28509)
		(width 0.14478)
		(layer "In13.Cu")
		(net "M_H_CPU0_SA_DQ<4>")
	)
	(segment
		(start 392.801856 -223.746822)
		(end 392.76274 -223.769682)
		(width 0.0889)
		(layer "In13.Cu")
		(net "M_H_CPU0_SA_DQ<4>")
	)
	(segment
		(start 384.023108 -228.63302)
		(end 384.000756 -228.549708)
		(width 0.0889)
		(layer "In13.Cu")
		(net "M_H_CPU0_SA_DQ<4>")
	)
	(segment
		(start 423.368216 -203.976986)
		(end 423.223436 -204.121766)
		(width 0.14478)
		(layer "In13.Cu")
		(net "M_H_CPU0_SA_DQ<4>")
	)
	(segment
		(start 384.000756 -228.549708)
		(end 384.154934 -228.284278)
		(width 0.0889)
		(layer "In13.Cu")
		(net "M_H_CPU0_SA_DQ<4>")
	)
	(segment
		(start 390.451848 -227.796852)
		(end 390.412732 -227.819712)
		(width 0.0889)
		(layer "In13.Cu")
		(net "M_H_CPU0_SA_DQ<4>")
	)
	(segment
		(start 389.041894 -228.606858)
		(end 389.033512 -228.611684)
		(width 0.0889)
		(layer "In13.Cu")
		(net "M_H_CPU0_SA_DQ<4>")
	)
	(segment
		(start 422.817036 -203.42987)
		(end 422.672256 -203.28509)
		(width 0.14478)
		(layer "In13.Cu")
		(net "M_H_CPU0_SA_DQ<4>")
	)
	(segment
		(start 408.449272 -204.11059)
		(end 393.779502 -218.78036)
		(width 0.14478)
		(layer "In13.Cu")
		(net "M_H_CPU0_SA_DQ<4>")
	)
	(segment
		(start 390.921748 -226.986846)
		(end 390.885426 -227.007928)
		(width 0.0889)
		(layer "In13.Cu")
		(net "M_H_CPU0_SA_DQ<4>")
	)
	(segment
		(start 385.856226 -228.611684)
		(end 385.847844 -228.606858)
		(width 0.0889)
		(layer "In13.Cu")
		(net "M_H_CPU0_SA_DQ<4>")
	)
	(segment
		(start 391.893552 -225.348546)
		(end 391.861802 -225.366834)
		(width 0.0889)
		(layer "In13.Cu")
		(net "M_H_CPU0_SA_DQ<4>")
	)
	(segment
		(start 423.368216 -203.42987)
		(end 423.368216 -203.976986)
		(width 0.14478)
		(layer "In13.Cu")
		(net "M_H_CPU0_SA_DQ<4>")
	)
	(segment
		(start 391.391902 -226.17684)
		(end 391.352786 -226.1997)
		(width 0.0889)
		(layer "In13.Cu")
		(net "M_H_CPU0_SA_DQ<4>")
	)
	(segment
		(start 423.512996 -203.28509)
		(end 423.368216 -203.42987)
		(width 0.14478)
		(layer "In13.Cu")
		(net "M_H_CPU0_SA_DQ<4>")
	)
	(segment
		(start 391.422382 -226.15906)
		(end 391.391902 -226.17684)
		(width 0.0889)
		(layer "In13.Cu")
		(net "M_H_CPU0_SA_DQ<4>")
	)
	(segment
		(start 393.779502 -221.865952)
		(end 393.779502 -222.437706)
		(width 0.0889)
		(layer "In13.Cu")
		(net "M_H_CPU0_SA_DQ<4>")
	)
	(segment
		(start 418.34562 -203.719684)
		(end 417.486084 -202.860148)
		(width 0.14478)
		(layer "In13.Cu")
		(net "M_H_CPU0_SA_DQ<4>")
	)
	(segment
		(start 422.817036 -203.976986)
		(end 422.817036 -203.42987)
		(width 0.14478)
		(layer "In13.Cu")
		(net "M_H_CPU0_SA_DQ<4>")
	)
	(segment
		(start 413.869886 -204.11059)
		(end 408.449272 -204.11059)
		(width 0.14478)
		(layer "In13.Cu")
		(net "M_H_CPU0_SA_DQ<4>")
	)
	(segment
		(start 393.343892 -222.873316)
		(end 393.272518 -222.936562)
		(width 0.0889)
		(layer "In13.Cu")
		(net "M_H_CPU0_SA_DQ<4>")
	)
	(segment
		(start 393.779502 -218.78036)
		(end 393.779502 -221.865952)
		(width 0.14478)
		(layer "In13.Cu")
		(net "M_H_CPU0_SA_DQ<4>")
	)
	(segment
		(start 415.120328 -202.860148)
		(end 413.869886 -204.11059)
		(width 0.14478)
		(layer "In13.Cu")
		(net "M_H_CPU0_SA_DQ<4>")
	)
	(segment
		(start 393.272518 -222.936562)
		(end 393.234418 -222.95866)
		(width 0.0889)
		(layer "In13.Cu")
		(net "M_H_CPU0_SA_DQ<4>")
	)
	(segment
		(start 392.362436 -224.539048)
		(end 392.331956 -224.556828)
		(width 0.0889)
		(layer "In13.Cu")
		(net "M_H_CPU0_SA_DQ<4>")
	)
	(segment
		(start 389.616188 -228.611684)
		(end 389.607806 -228.606858)
		(width 0.0889)
		(layer "In13.Cu")
		(net "M_H_CPU0_SA_DQ<4>")
	)
	(segment
		(start 423.223436 -204.121766)
		(end 422.961816 -204.121766)
		(width 0.14478)
		(layer "In13.Cu")
		(net "M_H_CPU0_SA_DQ<4>")
	)
	(segment
		(start 421.583612 -203.719684)
		(end 418.34562 -203.719684)
		(width 0.14478)
		(layer "In13.Cu")
		(net "M_H_CPU0_SA_DQ<4>")
	)
	(segment
		(start 392.833606 -223.728534)
		(end 392.801856 -223.746822)
		(width 0.0889)
		(layer "In13.Cu")
		(net "M_H_CPU0_SA_DQ<4>")
	)
	(segment
		(start 393.779502 -222.437706)
		(end 393.343892 -222.873316)
		(width 0.0889)
		(layer "In13.Cu")
		(net "M_H_CPU0_SA_DQ<4>")
	)
	(segment
		(start 384.341878 -228.606858)
		(end 384.333496 -228.611684)
		(width 0.0889)
		(layer "In13.Cu")
		(net "M_H_CPU0_SA_DQ<4>")
	)
	(segment
		(start 388.10184 -228.606858)
		(end 388.093458 -228.611684)
		(width 0.0889)
		(layer "In13.Cu")
		(net "M_H_CPU0_SA_DQ<4>")
	)
	(segment
		(start 390.483598 -227.778564)
		(end 390.451848 -227.796852)
		(width 0.0889)
		(layer "In13.Cu")
		(net "M_H_CPU0_SA_DQ<4>")
	)
	(segment
		(start 390.953498 -226.968558)
		(end 390.921748 -226.986846)
		(width 0.0889)
		(layer "In13.Cu")
		(net "M_H_CPU0_SA_DQ<4>")
	)
	(arc
		(start 388.667752 -228.606858)
		(mid 388.384796 -228.530681)
		(end 388.10184 -228.606858)
		(width 0.0889)
		(layer "In13.Cu")
		(net "M_H_CPU0_SA_DQ<4>")
	)
	(arc
		(start 391.822686 -225.389694)
		(mid 391.643873 -225.592044)
		(end 391.579354 -225.85426)
		(width 0.0889)
		(layer "In13.Cu")
		(net "M_H_CPU0_SA_DQ<4>")
	)
	(arc
		(start 390.412732 -227.819712)
		(mid 390.233919 -228.022062)
		(end 390.1694 -228.284278)
		(width 0.0889)
		(layer "In13.Cu")
		(net "M_H_CPU0_SA_DQ<4>")
	)
	(arc
		(start 392.76274 -223.769682)
		(mid 392.583927 -223.972032)
		(end 392.519408 -224.234248)
		(width 0.0889)
		(layer "In13.Cu")
		(net "M_H_CPU0_SA_DQ<4>")
	)
	(arc
		(start 393.234418 -222.95866)
		(mid 393.054533 -223.161229)
		(end 392.989562 -223.424242)
		(width 0.0889)
		(layer "In13.Cu")
		(net "M_H_CPU0_SA_DQ<4>")
	)
	(arc
		(start 389.607806 -228.606858)
		(mid 389.32485 -228.530681)
		(end 389.041894 -228.606858)
		(width 0.0889)
		(layer "In13.Cu")
		(net "M_H_CPU0_SA_DQ<4>")
	)
	(arc
		(start 392.989562 -223.424242)
		(mid 392.948307 -223.595213)
		(end 392.833606 -223.728534)
		(width 0.0889)
		(layer "In13.Cu")
		(net "M_H_CPU0_SA_DQ<4>")
	)
	(arc
		(start 389.981948 -228.606858)
		(mid 389.799697 -228.657208)
		(end 389.616188 -228.611684)
		(width 0.0889)
		(layer "In13.Cu")
		(net "M_H_CPU0_SA_DQ<4>")
	)
	(arc
		(start 392.519408 -224.234248)
		(mid 392.477859 -224.40567)
		(end 392.362436 -224.539048)
		(width 0.0889)
		(layer "In13.Cu")
		(net "M_H_CPU0_SA_DQ<4>")
	)
	(arc
		(start 390.885426 -227.007928)
		(mid 390.704774 -227.210673)
		(end 390.639554 -227.474272)
		(width 0.0889)
		(layer "In13.Cu")
		(net "M_H_CPU0_SA_DQ<4>")
	)
	(arc
		(start 390.1694 -228.284278)
		(mid 390.127851 -228.4557)
		(end 390.012428 -228.589078)
		(width 0.0889)
		(layer "In13.Cu")
		(net "M_H_CPU0_SA_DQ<4>")
	)
	(arc
		(start 385.281932 -228.606858)
		(mid 385.099681 -228.657208)
		(end 384.916172 -228.611684)
		(width 0.0889)
		(layer "In13.Cu")
		(net "M_H_CPU0_SA_DQ<4>")
	)
	(arc
		(start 387.727698 -228.606858)
		(mid 387.444742 -228.530681)
		(end 387.161786 -228.606858)
		(width 0.0889)
		(layer "In13.Cu")
		(net "M_H_CPU0_SA_DQ<4>")
	)
	(arc
		(start 392.29284 -224.579688)
		(mid 392.114027 -224.782038)
		(end 392.049508 -225.044254)
		(width 0.0889)
		(layer "In13.Cu")
		(net "M_H_CPU0_SA_DQ<4>")
	)
	(arc
		(start 384.333496 -228.611684)
		(mid 384.180626 -228.656325)
		(end 384.023108 -228.63302)
		(width 0.0889)
		(layer "In13.Cu")
		(net "M_H_CPU0_SA_DQ<4>")
	)
	(arc
		(start 387.161786 -228.606858)
		(mid 386.974842 -228.657113)
		(end 386.787898 -228.606858)
		(width 0.0889)
		(layer "In13.Cu")
		(net "M_H_CPU0_SA_DQ<4>")
	)
	(arc
		(start 384.90779 -228.606858)
		(mid 384.624834 -228.530681)
		(end 384.341878 -228.606858)
		(width 0.0889)
		(layer "In13.Cu")
		(net "M_H_CPU0_SA_DQ<4>")
	)
	(arc
		(start 389.033512 -228.611684)
		(mid 388.850004 -228.657178)
		(end 388.667752 -228.606858)
		(width 0.0889)
		(layer "In13.Cu")
		(net "M_H_CPU0_SA_DQ<4>")
	)
	(arc
		(start 390.639554 -227.474272)
		(mid 390.598299 -227.645243)
		(end 390.483598 -227.778564)
		(width 0.0889)
		(layer "In13.Cu")
		(net "M_H_CPU0_SA_DQ<4>")
	)
	(arc
		(start 386.787898 -228.606858)
		(mid 386.504942 -228.530681)
		(end 386.221986 -228.606858)
		(width 0.0889)
		(layer "In13.Cu")
		(net "M_H_CPU0_SA_DQ<4>")
	)
	(arc
		(start 385.847844 -228.606858)
		(mid 385.564888 -228.530681)
		(end 385.281932 -228.606858)
		(width 0.0889)
		(layer "In13.Cu")
		(net "M_H_CPU0_SA_DQ<4>")
	)
	(arc
		(start 388.093458 -228.611684)
		(mid 387.90995 -228.657178)
		(end 387.727698 -228.606858)
		(width 0.0889)
		(layer "In13.Cu")
		(net "M_H_CPU0_SA_DQ<4>")
	)
	(arc
		(start 391.352786 -226.1997)
		(mid 391.173973 -226.40205)
		(end 391.109454 -226.664266)
		(width 0.0889)
		(layer "In13.Cu")
		(net "M_H_CPU0_SA_DQ<4>")
	)
	(arc
		(start 391.109454 -226.664266)
		(mid 391.068199 -226.835237)
		(end 390.953498 -226.968558)
		(width 0.0889)
		(layer "In13.Cu")
		(net "M_H_CPU0_SA_DQ<4>")
	)
	(arc
		(start 386.221986 -228.606858)
		(mid 386.039735 -228.657208)
		(end 385.856226 -228.611684)
		(width 0.0889)
		(layer "In13.Cu")
		(net "M_H_CPU0_SA_DQ<4>")
	)
	(arc
		(start 392.049508 -225.044254)
		(mid 392.008253 -225.215225)
		(end 391.893552 -225.348546)
		(width 0.0889)
		(layer "In13.Cu")
		(net "M_H_CPU0_SA_DQ<4>")
	)
	(arc
		(start 391.579354 -225.85426)
		(mid 391.537805 -226.025682)
		(end 391.422382 -226.15906)
		(width 0.0889)
		(layer "In13.Cu")
		(net "M_H_CPU0_SA_DQ<4>")
	)
	(segment
		(start 381.807974 -226.930204)
		(end 382.274826 -226.664266)
		(width 0.10668)
		(layer "F.Cu")
		(net "M_H_CPU0_SA_DQ<3>")
	)
	(segment
		(start 389.576056 -224.739962)
		(end 389.607806 -224.721674)
		(width 0.0889)
		(layer "In13.Cu")
		(net "M_H_CPU0_SA_DQ<3>")
	)
	(segment
		(start 398.078198 -211.01812)
		(end 398.078198 -210.320382)
		(width 0.14478)
		(layer "In13.Cu")
		(net "M_H_CPU0_SA_DQ<3>")
	)
	(segment
		(start 405.095964 -202.840336)
		(end 405.300688 -202.840336)
		(width 0.14478)
		(layer "In13.Cu")
		(net "M_H_CPU0_SA_DQ<3>")
	)
	(segment
		(start 400.853148 -207.545432)
		(end 401.038314 -207.360266)
		(width 0.14478)
		(layer "In13.Cu")
		(net "M_H_CPU0_SA_DQ<3>")
	)
	(segment
		(start 398.698974 -209.494882)
		(end 398.672558 -209.468466)
		(width 0.14478)
		(layer "In13.Cu")
		(net "M_H_CPU0_SA_DQ<3>")
	)
	(segment
		(start 403.377654 -205.020926)
		(end 403.377654 -204.816202)
		(width 0.14478)
		(layer "In13.Cu")
		(net "M_H_CPU0_SA_DQ<3>")
	)
	(segment
		(start 390.548114 -223.101916)
		(end 390.581642 -223.082358)
		(width 0.0889)
		(layer "In13.Cu")
		(net "M_H_CPU0_SA_DQ<3>")
	)
	(segment
		(start 404.752048 -203.646532)
		(end 404.937214 -203.461366)
		(width 0.14478)
		(layer "In13.Cu")
		(net "M_H_CPU0_SA_DQ<3>")
	)
	(segment
		(start 384.333496 -226.33686)
		(end 384.341878 -226.341686)
		(width 0.0889)
		(layer "In13.Cu")
		(net "M_H_CPU0_SA_DQ<3>")
	)
	(segment
		(start 405.300688 -202.840336)
		(end 405.327104 -202.866752)
		(width 0.14478)
		(layer "In13.Cu")
		(net "M_H_CPU0_SA_DQ<3>")
	)
	(segment
		(start 405.716994 -202.476862)
		(end 405.690578 -202.450446)
		(width 0.14478)
		(layer "In13.Cu")
		(net "M_H_CPU0_SA_DQ<3>")
	)
	(segment
		(start 390.515602 -223.120712)
		(end 390.548114 -223.101916)
		(width 0.0889)
		(layer "In13.Cu")
		(net "M_H_CPU0_SA_DQ<3>")
	)
	(segment
		(start 408.078686 -200.319894)
		(end 413.996378 -200.319894)
		(width 0.14478)
		(layer "In13.Cu")
		(net "M_H_CPU0_SA_DQ<3>")
	)
	(segment
		(start 404.131018 -204.010006)
		(end 404.131018 -203.805282)
		(width 0.14478)
		(layer "In13.Cu")
		(net "M_H_CPU0_SA_DQ<3>")
	)
	(segment
		(start 382.274826 -226.664266)
		(end 382.42875 -226.398836)
		(width 0.0889)
		(layer "In13.Cu")
		(net "M_H_CPU0_SA_DQ<3>")
	)
	(segment
		(start 404.547324 -203.646532)
		(end 404.752048 -203.646532)
		(width 0.14478)
		(layer "In13.Cu")
		(net "M_H_CPU0_SA_DQ<3>")
	)
	(segment
		(start 400.232118 -207.704182)
		(end 400.417284 -207.519016)
		(width 0.14478)
		(layer "In13.Cu")
		(net "M_H_CPU0_SA_DQ<3>")
	)
	(segment
		(start 398.857724 -209.078576)
		(end 399.062448 -209.078576)
		(width 0.14478)
		(layer "In13.Cu")
		(net "M_H_CPU0_SA_DQ<3>")
	)
	(segment
		(start 399.637504 -208.298796)
		(end 399.842228 -208.298796)
		(width 0.14478)
		(layer "In13.Cu")
		(net "M_H_CPU0_SA_DQ<3>")
	)
	(segment
		(start 402.412708 -205.985872)
		(end 402.597874 -205.800706)
		(width 0.14478)
		(layer "In13.Cu")
		(net "M_H_CPU0_SA_DQ<3>")
	)
	(segment
		(start 399.452338 -208.688686)
		(end 399.452338 -208.483962)
		(width 0.14478)
		(layer "In13.Cu")
		(net "M_H_CPU0_SA_DQ<3>")
	)
	(segment
		(start 400.648424 -207.545432)
		(end 400.853148 -207.545432)
		(width 0.14478)
		(layer "In13.Cu")
		(net "M_H_CPU0_SA_DQ<3>")
	)
	(segment
		(start 418.13988 -199.460104)
		(end 418.980112 -200.300336)
		(width 0.14478)
		(layer "In13.Cu")
		(net "M_H_CPU0_SA_DQ<3>")
	)
	(segment
		(start 391.420096 -217.676222)
		(end 398.078198 -211.01812)
		(width 0.14478)
		(layer "In13.Cu")
		(net "M_H_CPU0_SA_DQ<3>")
	)
	(segment
		(start 405.875744 -202.060556)
		(end 406.080468 -202.060556)
		(width 0.14478)
		(layer "In13.Cu")
		(net "M_H_CPU0_SA_DQ<3>")
	)
	(segment
		(start 413.996378 -200.319894)
		(end 414.856168 -199.460104)
		(width 0.14478)
		(layer "In13.Cu")
		(net "M_H_CPU0_SA_DQ<3>")
	)
	(segment
		(start 403.536404 -204.399896)
		(end 403.741128 -204.399896)
		(width 0.14478)
		(layer "In13.Cu")
		(net "M_H_CPU0_SA_DQ<3>")
	)
	(segment
		(start 406.106884 -202.086972)
		(end 406.311608 -202.086972)
		(width 0.14478)
		(layer "In13.Cu")
		(net "M_H_CPU0_SA_DQ<3>")
	)
	(segment
		(start 404.316184 -203.620116)
		(end 404.520908 -203.620116)
		(width 0.14478)
		(layer "In13.Cu")
		(net "M_H_CPU0_SA_DQ<3>")
	)
	(segment
		(start 401.632928 -206.765652)
		(end 401.818094 -206.580486)
		(width 0.14478)
		(layer "In13.Cu")
		(net "M_H_CPU0_SA_DQ<3>")
	)
	(segment
		(start 398.698974 -209.699606)
		(end 398.698974 -209.494882)
		(width 0.14478)
		(layer "In13.Cu")
		(net "M_H_CPU0_SA_DQ<3>")
	)
	(segment
		(start 402.961348 -205.179676)
		(end 402.987764 -205.206092)
		(width 0.14478)
		(layer "In13.Cu")
		(net "M_H_CPU0_SA_DQ<3>")
	)
	(segment
		(start 402.597874 -205.595982)
		(end 402.571458 -205.569566)
		(width 0.14478)
		(layer "In13.Cu")
		(net "M_H_CPU0_SA_DQ<3>")
	)
	(segment
		(start 404.910798 -203.230226)
		(end 404.910798 -203.025502)
		(width 0.14478)
		(layer "In13.Cu")
		(net "M_H_CPU0_SA_DQ<3>")
	)
	(segment
		(start 402.207984 -205.985872)
		(end 402.412708 -205.985872)
		(width 0.14478)
		(layer "In13.Cu")
		(net "M_H_CPU0_SA_DQ<3>")
	)
	(segment
		(start 405.531828 -202.866752)
		(end 405.716994 -202.681586)
		(width 0.14478)
		(layer "In13.Cu")
		(net "M_H_CPU0_SA_DQ<3>")
	)
	(segment
		(start 404.937214 -203.461366)
		(end 404.937214 -203.256642)
		(width 0.14478)
		(layer "In13.Cu")
		(net "M_H_CPU0_SA_DQ<3>")
	)
	(segment
		(start 390.078214 -223.911668)
		(end 390.113012 -223.891348)
		(width 0.0889)
		(layer "In13.Cu")
		(net "M_H_CPU0_SA_DQ<3>")
	)
	(segment
		(start 398.672558 -209.263742)
		(end 398.857724 -209.078576)
		(width 0.14478)
		(layer "In13.Cu")
		(net "M_H_CPU0_SA_DQ<3>")
	)
	(segment
		(start 404.131018 -203.805282)
		(end 404.316184 -203.620116)
		(width 0.14478)
		(layer "In13.Cu")
		(net "M_H_CPU0_SA_DQ<3>")
	)
	(segment
		(start 399.478754 -208.919826)
		(end 399.478754 -208.715102)
		(width 0.14478)
		(layer "In13.Cu")
		(net "M_H_CPU0_SA_DQ<3>")
	)
	(segment
		(start 404.520908 -203.620116)
		(end 404.547324 -203.646532)
		(width 0.14478)
		(layer "In13.Cu")
		(net "M_H_CPU0_SA_DQ<3>")
	)
	(segment
		(start 403.351238 -204.585062)
		(end 403.536404 -204.399896)
		(width 0.14478)
		(layer "In13.Cu")
		(net "M_H_CPU0_SA_DQ<3>")
	)
	(segment
		(start 404.157434 -204.036422)
		(end 404.131018 -204.010006)
		(width 0.14478)
		(layer "In13.Cu")
		(net "M_H_CPU0_SA_DQ<3>")
	)
	(segment
		(start 403.767544 -204.426312)
		(end 403.972268 -204.426312)
		(width 0.14478)
		(layer "In13.Cu")
		(net "M_H_CPU0_SA_DQ<3>")
	)
	(segment
		(start 419.720268 -200.300336)
		(end 419.912038 -200.108566)
		(width 0.14478)
		(layer "In13.Cu")
		(net "M_H_CPU0_SA_DQ<3>")
	)
	(segment
		(start 404.157434 -204.241146)
		(end 404.157434 -204.036422)
		(width 0.14478)
		(layer "In13.Cu")
		(net "M_H_CPU0_SA_DQ<3>")
	)
	(segment
		(start 399.452338 -208.483962)
		(end 399.637504 -208.298796)
		(width 0.14478)
		(layer "In13.Cu")
		(net "M_H_CPU0_SA_DQ<3>")
	)
	(segment
		(start 390.045448 -223.930718)
		(end 390.078214 -223.911668)
		(width 0.0889)
		(layer "In13.Cu")
		(net "M_H_CPU0_SA_DQ<3>")
	)
	(segment
		(start 391.301224 -221.80423)
		(end 391.301224 -221.537022)
		(width 0.0889)
		(layer "In13.Cu")
		(net "M_H_CPU0_SA_DQ<3>")
	)
	(segment
		(start 399.062448 -209.078576)
		(end 399.088864 -209.104992)
		(width 0.14478)
		(layer "In13.Cu")
		(net "M_H_CPU0_SA_DQ<3>")
	)
	(segment
		(start 399.478754 -208.715102)
		(end 399.452338 -208.688686)
		(width 0.14478)
		(layer "In13.Cu")
		(net "M_H_CPU0_SA_DQ<3>")
	)
	(segment
		(start 400.232118 -207.908906)
		(end 400.232118 -207.704182)
		(width 0.14478)
		(layer "In13.Cu")
		(net "M_H_CPU0_SA_DQ<3>")
	)
	(segment
		(start 385.847844 -226.341686)
		(end 385.856226 -226.33686)
		(width 0.0889)
		(layer "In13.Cu")
		(net "M_H_CPU0_SA_DQ<3>")
	)
	(segment
		(start 391.420096 -221.23527)
		(end 391.420096 -217.676222)
		(width 0.14478)
		(layer "In13.Cu")
		(net "M_H_CPU0_SA_DQ<3>")
	)
	(segment
		(start 400.258534 -208.140046)
		(end 400.258534 -207.935322)
		(width 0.14478)
		(layer "In13.Cu")
		(net "M_H_CPU0_SA_DQ<3>")
	)
	(segment
		(start 401.011898 -206.924402)
		(end 401.197064 -206.739236)
		(width 0.14478)
		(layer "In13.Cu")
		(net "M_H_CPU0_SA_DQ<3>")
	)
	(segment
		(start 419.912038 -200.108566)
		(end 419.912038 -199.885046)
		(width 0.14478)
		(layer "In13.Cu")
		(net "M_H_CPU0_SA_DQ<3>")
	)
	(segment
		(start 418.980112 -200.300336)
		(end 419.720268 -200.300336)
		(width 0.14478)
		(layer "In13.Cu")
		(net "M_H_CPU0_SA_DQ<3>")
	)
	(segment
		(start 398.672558 -209.468466)
		(end 398.672558 -209.263742)
		(width 0.14478)
		(layer "In13.Cu")
		(net "M_H_CPU0_SA_DQ<3>")
	)
	(segment
		(start 405.327104 -202.866752)
		(end 405.531828 -202.866752)
		(width 0.14478)
		(layer "In13.Cu")
		(net "M_H_CPU0_SA_DQ<3>")
	)
	(segment
		(start 404.937214 -203.256642)
		(end 404.910798 -203.230226)
		(width 0.14478)
		(layer "In13.Cu")
		(net "M_H_CPU0_SA_DQ<3>")
	)
	(segment
		(start 399.088864 -209.104992)
		(end 399.293588 -209.104992)
		(width 0.14478)
		(layer "In13.Cu")
		(net "M_H_CPU0_SA_DQ<3>")
	)
	(segment
		(start 400.258534 -207.935322)
		(end 400.232118 -207.908906)
		(width 0.14478)
		(layer "In13.Cu")
		(net "M_H_CPU0_SA_DQ<3>")
	)
	(segment
		(start 402.756624 -205.179676)
		(end 402.961348 -205.179676)
		(width 0.14478)
		(layer "In13.Cu")
		(net "M_H_CPU0_SA_DQ<3>")
	)
	(segment
		(start 405.690578 -202.245722)
		(end 405.875744 -202.060556)
		(width 0.14478)
		(layer "In13.Cu")
		(net "M_H_CPU0_SA_DQ<3>")
	)
	(segment
		(start 399.868644 -208.325212)
		(end 400.073368 -208.325212)
		(width 0.14478)
		(layer "In13.Cu")
		(net "M_H_CPU0_SA_DQ<3>")
	)
	(segment
		(start 384.90779 -226.341686)
		(end 384.916172 -226.33686)
		(width 0.0889)
		(layer "In13.Cu")
		(net "M_H_CPU0_SA_DQ<3>")
	)
	(segment
		(start 401.791678 -206.144622)
		(end 401.976844 -205.959456)
		(width 0.14478)
		(layer "In13.Cu")
		(net "M_H_CPU0_SA_DQ<3>")
	)
	(segment
		(start 398.078198 -210.320382)
		(end 398.698974 -209.699606)
		(width 0.14478)
		(layer "In13.Cu")
		(net "M_H_CPU0_SA_DQ<3>")
	)
	(segment
		(start 403.192488 -205.206092)
		(end 403.377654 -205.020926)
		(width 0.14478)
		(layer "In13.Cu")
		(net "M_H_CPU0_SA_DQ<3>")
	)
	(segment
		(start 406.080468 -202.060556)
		(end 406.106884 -202.086972)
		(width 0.14478)
		(layer "In13.Cu")
		(net "M_H_CPU0_SA_DQ<3>")
	)
	(segment
		(start 401.428204 -206.765652)
		(end 401.632928 -206.765652)
		(width 0.14478)
		(layer "In13.Cu")
		(net "M_H_CPU0_SA_DQ<3>")
	)
	(segment
		(start 388.093458 -226.33686)
		(end 388.10184 -226.341686)
		(width 0.0889)
		(layer "In13.Cu")
		(net "M_H_CPU0_SA_DQ<3>")
	)
	(segment
		(start 400.622008 -207.519016)
		(end 400.648424 -207.545432)
		(width 0.14478)
		(layer "In13.Cu")
		(net "M_H_CPU0_SA_DQ<3>")
	)
	(segment
		(start 401.818094 -206.375762)
		(end 401.791678 -206.349346)
		(width 0.14478)
		(layer "In13.Cu")
		(net "M_H_CPU0_SA_DQ<3>")
	)
	(segment
		(start 389.106156 -225.549968)
		(end 389.137906 -225.53168)
		(width 0.0889)
		(layer "In13.Cu")
		(net "M_H_CPU0_SA_DQ<3>")
	)
	(segment
		(start 399.293588 -209.104992)
		(end 399.478754 -208.919826)
		(width 0.14478)
		(layer "In13.Cu")
		(net "M_H_CPU0_SA_DQ<3>")
	)
	(segment
		(start 404.910798 -203.025502)
		(end 405.095964 -202.840336)
		(width 0.14478)
		(layer "In13.Cu")
		(net "M_H_CPU0_SA_DQ<3>")
	)
	(segment
		(start 401.791678 -206.349346)
		(end 401.791678 -206.144622)
		(width 0.14478)
		(layer "In13.Cu")
		(net "M_H_CPU0_SA_DQ<3>")
	)
	(segment
		(start 400.073368 -208.325212)
		(end 400.258534 -208.140046)
		(width 0.14478)
		(layer "In13.Cu")
		(net "M_H_CPU0_SA_DQ<3>")
	)
	(segment
		(start 389.607806 -224.721674)
		(end 389.646922 -224.698814)
		(width 0.0889)
		(layer "In13.Cu")
		(net "M_H_CPU0_SA_DQ<3>")
	)
	(segment
		(start 388.667752 -226.341686)
		(end 388.706868 -226.318826)
		(width 0.0889)
		(layer "In13.Cu")
		(net "M_H_CPU0_SA_DQ<3>")
	)
	(segment
		(start 390.987788 -222.309436)
		(end 391.018014 -222.29191)
		(width 0.0889)
		(layer "In13.Cu")
		(net "M_H_CPU0_SA_DQ<3>")
	)
	(segment
		(start 401.197064 -206.739236)
		(end 401.401788 -206.739236)
		(width 0.14478)
		(layer "In13.Cu")
		(net "M_H_CPU0_SA_DQ<3>")
	)
	(segment
		(start 391.301224 -221.537022)
		(end 391.420096 -221.41815)
		(width 0.0889)
		(layer "In13.Cu")
		(net "M_H_CPU0_SA_DQ<3>")
	)
	(segment
		(start 402.181568 -205.959456)
		(end 402.207984 -205.985872)
		(width 0.14478)
		(layer "In13.Cu")
		(net "M_H_CPU0_SA_DQ<3>")
	)
	(segment
		(start 383.393442 -226.33686)
		(end 383.401824 -226.341686)
		(width 0.0889)
		(layer "In13.Cu")
		(net "M_H_CPU0_SA_DQ<3>")
	)
	(segment
		(start 405.690578 -202.450446)
		(end 405.690578 -202.245722)
		(width 0.14478)
		(layer "In13.Cu")
		(net "M_H_CPU0_SA_DQ<3>")
	)
	(segment
		(start 402.571458 -205.364842)
		(end 402.756624 -205.179676)
		(width 0.14478)
		(layer "In13.Cu")
		(net "M_H_CPU0_SA_DQ<3>")
	)
	(segment
		(start 399.842228 -208.298796)
		(end 399.868644 -208.325212)
		(width 0.14478)
		(layer "In13.Cu")
		(net "M_H_CPU0_SA_DQ<3>")
	)
	(segment
		(start 403.972268 -204.426312)
		(end 404.157434 -204.241146)
		(width 0.14478)
		(layer "In13.Cu")
		(net "M_H_CPU0_SA_DQ<3>")
	)
	(segment
		(start 406.311608 -202.086972)
		(end 408.078686 -200.319894)
		(width 0.14478)
		(layer "In13.Cu")
		(net "M_H_CPU0_SA_DQ<3>")
	)
	(segment
		(start 391.420096 -221.41815)
		(end 391.420096 -221.23527)
		(width 0.0889)
		(layer "In13.Cu")
		(net "M_H_CPU0_SA_DQ<3>")
	)
	(segment
		(start 389.137906 -225.53168)
		(end 389.174228 -225.510598)
		(width 0.0889)
		(layer "In13.Cu")
		(net "M_H_CPU0_SA_DQ<3>")
	)
	(segment
		(start 382.42875 -226.398836)
		(end 382.524762 -226.373436)
		(width 0.0889)
		(layer "In13.Cu")
		(net "M_H_CPU0_SA_DQ<3>")
	)
	(segment
		(start 401.401788 -206.739236)
		(end 401.428204 -206.765652)
		(width 0.14478)
		(layer "In13.Cu")
		(net "M_H_CPU0_SA_DQ<3>")
	)
	(segment
		(start 405.716994 -202.681586)
		(end 405.716994 -202.476862)
		(width 0.14478)
		(layer "In13.Cu")
		(net "M_H_CPU0_SA_DQ<3>")
	)
	(segment
		(start 403.377654 -204.816202)
		(end 403.351238 -204.789786)
		(width 0.14478)
		(layer "In13.Cu")
		(net "M_H_CPU0_SA_DQ<3>")
	)
	(segment
		(start 403.741128 -204.399896)
		(end 403.767544 -204.426312)
		(width 0.14478)
		(layer "In13.Cu")
		(net "M_H_CPU0_SA_DQ<3>")
	)
	(segment
		(start 401.038314 -207.360266)
		(end 401.038314 -207.155542)
		(width 0.14478)
		(layer "In13.Cu")
		(net "M_H_CPU0_SA_DQ<3>")
	)
	(segment
		(start 414.856168 -199.460104)
		(end 418.13988 -199.460104)
		(width 0.14478)
		(layer "In13.Cu")
		(net "M_H_CPU0_SA_DQ<3>")
	)
	(segment
		(start 401.818094 -206.580486)
		(end 401.818094 -206.375762)
		(width 0.14478)
		(layer "In13.Cu")
		(net "M_H_CPU0_SA_DQ<3>")
	)
	(segment
		(start 402.597874 -205.800706)
		(end 402.597874 -205.595982)
		(width 0.14478)
		(layer "In13.Cu")
		(net "M_H_CPU0_SA_DQ<3>")
	)
	(segment
		(start 401.011898 -207.129126)
		(end 401.011898 -206.924402)
		(width 0.14478)
		(layer "In13.Cu")
		(net "M_H_CPU0_SA_DQ<3>")
	)
	(segment
		(start 401.976844 -205.959456)
		(end 402.181568 -205.959456)
		(width 0.14478)
		(layer "In13.Cu")
		(net "M_H_CPU0_SA_DQ<3>")
	)
	(segment
		(start 402.987764 -205.206092)
		(end 403.192488 -205.206092)
		(width 0.14478)
		(layer "In13.Cu")
		(net "M_H_CPU0_SA_DQ<3>")
	)
	(segment
		(start 400.417284 -207.519016)
		(end 400.622008 -207.519016)
		(width 0.14478)
		(layer "In13.Cu")
		(net "M_H_CPU0_SA_DQ<3>")
	)
	(segment
		(start 391.018014 -222.29191)
		(end 391.058908 -222.268288)
		(width 0.0889)
		(layer "In13.Cu")
		(net "M_H_CPU0_SA_DQ<3>")
	)
	(segment
		(start 401.038314 -207.155542)
		(end 401.011898 -207.129126)
		(width 0.14478)
		(layer "In13.Cu")
		(net "M_H_CPU0_SA_DQ<3>")
	)
	(segment
		(start 403.351238 -204.789786)
		(end 403.351238 -204.585062)
		(width 0.14478)
		(layer "In13.Cu")
		(net "M_H_CPU0_SA_DQ<3>")
	)
	(segment
		(start 402.571458 -205.569566)
		(end 402.571458 -205.364842)
		(width 0.14478)
		(layer "In13.Cu")
		(net "M_H_CPU0_SA_DQ<3>")
	)
	(arc
		(start 389.174228 -225.510598)
		(mid 389.35488 -225.307853)
		(end 389.4201 -225.044254)
		(width 0.0889)
		(layer "In13.Cu")
		(net "M_H_CPU0_SA_DQ<3>")
	)
	(arc
		(start 383.401824 -226.341686)
		(mid 383.68478 -226.417863)
		(end 383.967736 -226.341686)
		(width 0.0889)
		(layer "In13.Cu")
		(net "M_H_CPU0_SA_DQ<3>")
	)
	(arc
		(start 386.787898 -226.341686)
		(mid 386.974842 -226.291431)
		(end 387.161786 -226.341686)
		(width 0.0889)
		(layer "In13.Cu")
		(net "M_H_CPU0_SA_DQ<3>")
	)
	(arc
		(start 391.058908 -222.268288)
		(mid 391.237032 -222.065998)
		(end 391.301224 -221.80423)
		(width 0.0889)
		(layer "In13.Cu")
		(net "M_H_CPU0_SA_DQ<3>")
	)
	(arc
		(start 385.281932 -226.341686)
		(mid 385.564888 -226.417863)
		(end 385.847844 -226.341686)
		(width 0.0889)
		(layer "In13.Cu")
		(net "M_H_CPU0_SA_DQ<3>")
	)
	(arc
		(start 385.856226 -226.33686)
		(mid 386.039734 -226.291366)
		(end 386.221986 -226.341686)
		(width 0.0889)
		(layer "In13.Cu")
		(net "M_H_CPU0_SA_DQ<3>")
	)
	(arc
		(start 388.9502 -225.85426)
		(mid 388.991455 -225.683289)
		(end 389.106156 -225.549968)
		(width 0.0889)
		(layer "In13.Cu")
		(net "M_H_CPU0_SA_DQ<3>")
	)
	(arc
		(start 384.916172 -226.33686)
		(mid 385.09968 -226.291366)
		(end 385.281932 -226.341686)
		(width 0.0889)
		(layer "In13.Cu")
		(net "M_H_CPU0_SA_DQ<3>")
	)
	(arc
		(start 383.027682 -226.341686)
		(mid 383.209933 -226.291336)
		(end 383.393442 -226.33686)
		(width 0.0889)
		(layer "In13.Cu")
		(net "M_H_CPU0_SA_DQ<3>")
	)
	(arc
		(start 387.161786 -226.341686)
		(mid 387.444742 -226.417863)
		(end 387.727698 -226.341686)
		(width 0.0889)
		(layer "In13.Cu")
		(net "M_H_CPU0_SA_DQ<3>")
	)
	(arc
		(start 389.646922 -224.698814)
		(mid 389.825735 -224.496464)
		(end 389.890254 -224.234248)
		(width 0.0889)
		(layer "In13.Cu")
		(net "M_H_CPU0_SA_DQ<3>")
	)
	(arc
		(start 384.341878 -226.341686)
		(mid 384.624834 -226.417863)
		(end 384.90779 -226.341686)
		(width 0.0889)
		(layer "In13.Cu")
		(net "M_H_CPU0_SA_DQ<3>")
	)
	(arc
		(start 390.830562 -222.614236)
		(mid 390.872178 -222.442747)
		(end 390.987788 -222.309436)
		(width 0.0889)
		(layer "In13.Cu")
		(net "M_H_CPU0_SA_DQ<3>")
	)
	(arc
		(start 390.113012 -223.891348)
		(mid 390.294748 -223.688533)
		(end 390.360408 -223.424242)
		(width 0.0889)
		(layer "In13.Cu")
		(net "M_H_CPU0_SA_DQ<3>")
	)
	(arc
		(start 389.4201 -225.044254)
		(mid 389.461355 -224.873283)
		(end 389.576056 -224.739962)
		(width 0.0889)
		(layer "In13.Cu")
		(net "M_H_CPU0_SA_DQ<3>")
	)
	(arc
		(start 387.727698 -226.341686)
		(mid 387.909949 -226.291336)
		(end 388.093458 -226.33686)
		(width 0.0889)
		(layer "In13.Cu")
		(net "M_H_CPU0_SA_DQ<3>")
	)
	(arc
		(start 382.524762 -226.373436)
		(mid 382.77997 -226.416913)
		(end 383.027682 -226.341686)
		(width 0.0889)
		(layer "In13.Cu")
		(net "M_H_CPU0_SA_DQ<3>")
	)
	(arc
		(start 386.221986 -226.341686)
		(mid 386.504942 -226.417863)
		(end 386.787898 -226.341686)
		(width 0.0889)
		(layer "In13.Cu")
		(net "M_H_CPU0_SA_DQ<3>")
	)
	(arc
		(start 390.360408 -223.424242)
		(mid 390.401458 -223.253792)
		(end 390.515602 -223.120712)
		(width 0.0889)
		(layer "In13.Cu")
		(net "M_H_CPU0_SA_DQ<3>")
	)
	(arc
		(start 390.581642 -223.082358)
		(mid 390.764462 -222.87933)
		(end 390.830562 -222.614236)
		(width 0.0889)
		(layer "In13.Cu")
		(net "M_H_CPU0_SA_DQ<3>")
	)
	(arc
		(start 383.967736 -226.341686)
		(mid 384.149987 -226.291336)
		(end 384.333496 -226.33686)
		(width 0.0889)
		(layer "In13.Cu")
		(net "M_H_CPU0_SA_DQ<3>")
	)
	(arc
		(start 389.890254 -224.234248)
		(mid 389.931304 -224.063798)
		(end 390.045448 -223.930718)
		(width 0.0889)
		(layer "In13.Cu")
		(net "M_H_CPU0_SA_DQ<3>")
	)
	(arc
		(start 388.706868 -226.318826)
		(mid 388.885681 -226.116476)
		(end 388.9502 -225.85426)
		(width 0.0889)
		(layer "In13.Cu")
		(net "M_H_CPU0_SA_DQ<3>")
	)
	(arc
		(start 388.10184 -226.341686)
		(mid 388.384796 -226.417863)
		(end 388.667752 -226.341686)
		(width 0.0889)
		(layer "In13.Cu")
		(net "M_H_CPU0_SA_DQ<3>")
	)
	(segment
		(start 381.807974 -244.750082)
		(end 382.274826 -244.484144)
		(width 0.10668)
		(layer "F.Cu")
		(net "M_H_CPU0_SA_DQ<31>")
	)
	(segment
		(start 419.912038 -233.884978)
		(end 419.486588 -234.310428)
		(width 0.14478)
		(layer "In13.Cu")
		(net "M_H_CPU0_SA_DQ<31>")
	)
	(segment
		(start 406.691846 -239.017556)
		(end 406.782524 -239.108234)
		(width 0.14478)
		(layer "In13.Cu")
		(net "M_H_CPU0_SA_DQ<31>")
	)
	(segment
		(start 407.562304 -238.328454)
		(end 407.562304 -238.533178)
		(width 0.14478)
		(layer "In13.Cu")
		(net "M_H_CPU0_SA_DQ<31>")
	)
	(segment
		(start 407.471626 -238.033052)
		(end 407.471626 -238.237776)
		(width 0.14478)
		(layer "In13.Cu")
		(net "M_H_CPU0_SA_DQ<31>")
	)
	(segment
		(start 406.002744 -239.888014)
		(end 406.002744 -240.092738)
		(width 0.14478)
		(layer "In13.Cu")
		(net "M_H_CPU0_SA_DQ<31>")
	)
	(segment
		(start 404.352506 -241.152172)
		(end 404.352506 -241.356896)
		(width 0.14478)
		(layer "In13.Cu")
		(net "M_H_CPU0_SA_DQ<31>")
	)
	(segment
		(start 395.860778 -243.43868)
		(end 395.571726 -243.43868)
		(width 0.0889)
		(layer "In13.Cu")
		(net "M_H_CPU0_SA_DQ<31>")
	)
	(segment
		(start 408.251406 -237.457996)
		(end 408.342084 -237.548674)
		(width 0.14478)
		(layer "In13.Cu")
		(net "M_H_CPU0_SA_DQ<31>")
	)
	(segment
		(start 404.443184 -241.652298)
		(end 402.656802 -243.43868)
		(width 0.14478)
		(layer "In13.Cu")
		(net "M_H_CPU0_SA_DQ<31>")
	)
	(segment
		(start 405.132286 -240.372392)
		(end 405.132286 -240.577116)
		(width 0.14478)
		(layer "In13.Cu")
		(net "M_H_CPU0_SA_DQ<31>")
	)
	(segment
		(start 406.782524 -239.312958)
		(end 406.597358 -239.498124)
		(width 0.14478)
		(layer "In13.Cu")
		(net "M_H_CPU0_SA_DQ<31>")
	)
	(segment
		(start 410.590746 -235.118656)
		(end 410.681424 -235.209334)
		(width 0.14478)
		(layer "In13.Cu")
		(net "M_H_CPU0_SA_DQ<31>")
	)
	(segment
		(start 404.352506 -241.356896)
		(end 404.443184 -241.447574)
		(width 0.14478)
		(layer "In13.Cu")
		(net "M_H_CPU0_SA_DQ<31>")
	)
	(segment
		(start 411.276038 -234.819444)
		(end 411.071314 -234.819444)
		(width 0.14478)
		(layer "In13.Cu")
		(net "M_H_CPU0_SA_DQ<31>")
	)
	(segment
		(start 409.810966 -235.898436)
		(end 409.901644 -235.989114)
		(width 0.14478)
		(layer "In13.Cu")
		(net "M_H_CPU0_SA_DQ<31>")
	)
	(segment
		(start 405.037798 -241.057684)
		(end 404.833074 -241.057684)
		(width 0.14478)
		(layer "In13.Cu")
		(net "M_H_CPU0_SA_DQ<31>")
	)
	(segment
		(start 384.916172 -244.156738)
		(end 384.90779 -244.161564)
		(width 0.0889)
		(layer "In13.Cu")
		(net "M_H_CPU0_SA_DQ<31>")
	)
	(segment
		(start 410.980636 -234.728766)
		(end 410.775912 -234.728766)
		(width 0.14478)
		(layer "In13.Cu")
		(net "M_H_CPU0_SA_DQ<31>")
	)
	(segment
		(start 410.291534 -235.599224)
		(end 410.200856 -235.508546)
		(width 0.14478)
		(layer "In13.Cu")
		(net "M_H_CPU0_SA_DQ<31>")
	)
	(segment
		(start 406.782524 -239.108234)
		(end 406.782524 -239.312958)
		(width 0.14478)
		(layer "In13.Cu")
		(net "M_H_CPU0_SA_DQ<31>")
	)
	(segment
		(start 410.681424 -235.209334)
		(end 410.681424 -235.414058)
		(width 0.14478)
		(layer "In13.Cu")
		(net "M_H_CPU0_SA_DQ<31>")
	)
	(segment
		(start 410.496258 -235.599224)
		(end 410.291534 -235.599224)
		(width 0.14478)
		(layer "In13.Cu")
		(net "M_H_CPU0_SA_DQ<31>")
	)
	(segment
		(start 382.42875 -244.218714)
		(end 382.274826 -244.484144)
		(width 0.0889)
		(layer "In13.Cu")
		(net "M_H_CPU0_SA_DQ<31>")
	)
	(segment
		(start 407.952194 -237.938564)
		(end 407.861516 -237.847886)
		(width 0.14478)
		(layer "In13.Cu")
		(net "M_H_CPU0_SA_DQ<31>")
	)
	(segment
		(start 411.071314 -234.819444)
		(end 410.980636 -234.728766)
		(width 0.14478)
		(layer "In13.Cu")
		(net "M_H_CPU0_SA_DQ<31>")
	)
	(segment
		(start 409.121864 -236.973618)
		(end 408.936698 -237.158784)
		(width 0.14478)
		(layer "In13.Cu")
		(net "M_H_CPU0_SA_DQ<31>")
	)
	(segment
		(start 389.041894 -244.161564)
		(end 389.033512 -244.156738)
		(width 0.0889)
		(layer "In13.Cu")
		(net "M_H_CPU0_SA_DQ<31>")
	)
	(segment
		(start 383.401824 -244.161564)
		(end 383.393442 -244.156738)
		(width 0.0889)
		(layer "In13.Cu")
		(net "M_H_CPU0_SA_DQ<31>")
	)
	(segment
		(start 408.731974 -237.158784)
		(end 408.641296 -237.068106)
		(width 0.14478)
		(layer "In13.Cu")
		(net "M_H_CPU0_SA_DQ<31>")
	)
	(segment
		(start 407.656792 -237.847886)
		(end 407.471626 -238.033052)
		(width 0.14478)
		(layer "In13.Cu")
		(net "M_H_CPU0_SA_DQ<31>")
	)
	(segment
		(start 417.700968 -233.46029)
		(end 415.359342 -233.46029)
		(width 0.14478)
		(layer "In13.Cu")
		(net "M_H_CPU0_SA_DQ<31>")
	)
	(segment
		(start 415.359342 -233.46029)
		(end 414.509204 -234.310428)
		(width 0.14478)
		(layer "In13.Cu")
		(net "M_H_CPU0_SA_DQ<31>")
	)
	(segment
		(start 406.002744 -240.092738)
		(end 405.817578 -240.277904)
		(width 0.14478)
		(layer "In13.Cu")
		(net "M_H_CPU0_SA_DQ<31>")
	)
	(segment
		(start 405.132286 -240.577116)
		(end 405.222964 -240.667794)
		(width 0.14478)
		(layer "In13.Cu")
		(net "M_H_CPU0_SA_DQ<31>")
	)
	(segment
		(start 405.222964 -240.667794)
		(end 405.222964 -240.872518)
		(width 0.14478)
		(layer "In13.Cu")
		(net "M_H_CPU0_SA_DQ<31>")
	)
	(segment
		(start 407.172414 -238.718344)
		(end 407.081736 -238.627666)
		(width 0.14478)
		(layer "In13.Cu")
		(net "M_H_CPU0_SA_DQ<31>")
	)
	(segment
		(start 406.301956 -239.407446)
		(end 406.097232 -239.407446)
		(width 0.14478)
		(layer "In13.Cu")
		(net "M_H_CPU0_SA_DQ<31>")
	)
	(segment
		(start 404.443184 -241.447574)
		(end 404.443184 -241.652298)
		(width 0.14478)
		(layer "In13.Cu")
		(net "M_H_CPU0_SA_DQ<31>")
	)
	(segment
		(start 394.114528 -244.238018)
		(end 393.084812 -244.238018)
		(width 0.0889)
		(layer "In13.Cu")
		(net "M_H_CPU0_SA_DQ<31>")
	)
	(segment
		(start 409.810966 -235.693712)
		(end 409.810966 -235.898436)
		(width 0.14478)
		(layer "In13.Cu")
		(net "M_H_CPU0_SA_DQ<31>")
	)
	(segment
		(start 409.511754 -236.379004)
		(end 409.421076 -236.288326)
		(width 0.14478)
		(layer "In13.Cu")
		(net "M_H_CPU0_SA_DQ<31>")
	)
	(segment
		(start 385.856226 -244.156738)
		(end 385.847844 -244.161564)
		(width 0.0889)
		(layer "In13.Cu")
		(net "M_H_CPU0_SA_DQ<31>")
	)
	(segment
		(start 409.421076 -236.288326)
		(end 409.216352 -236.288326)
		(width 0.14478)
		(layer "In13.Cu")
		(net "M_H_CPU0_SA_DQ<31>")
	)
	(segment
		(start 405.612854 -240.277904)
		(end 405.522176 -240.187226)
		(width 0.14478)
		(layer "In13.Cu")
		(net "M_H_CPU0_SA_DQ<31>")
	)
	(segment
		(start 410.681424 -235.414058)
		(end 410.496258 -235.599224)
		(width 0.14478)
		(layer "In13.Cu")
		(net "M_H_CPU0_SA_DQ<31>")
	)
	(segment
		(start 405.317452 -240.187226)
		(end 405.132286 -240.372392)
		(width 0.14478)
		(layer "In13.Cu")
		(net "M_H_CPU0_SA_DQ<31>")
	)
	(segment
		(start 405.912066 -239.592612)
		(end 405.912066 -239.797336)
		(width 0.14478)
		(layer "In13.Cu")
		(net "M_H_CPU0_SA_DQ<31>")
	)
	(segment
		(start 404.833074 -241.057684)
		(end 404.742396 -240.967006)
		(width 0.14478)
		(layer "In13.Cu")
		(net "M_H_CPU0_SA_DQ<31>")
	)
	(segment
		(start 409.031186 -236.678216)
		(end 409.121864 -236.768894)
		(width 0.14478)
		(layer "In13.Cu")
		(net "M_H_CPU0_SA_DQ<31>")
	)
	(segment
		(start 407.562304 -238.533178)
		(end 407.377138 -238.718344)
		(width 0.14478)
		(layer "In13.Cu")
		(net "M_H_CPU0_SA_DQ<31>")
	)
	(segment
		(start 408.641296 -237.068106)
		(end 408.436572 -237.068106)
		(width 0.14478)
		(layer "In13.Cu")
		(net "M_H_CPU0_SA_DQ<31>")
	)
	(segment
		(start 410.590746 -234.913932)
		(end 410.590746 -235.118656)
		(width 0.14478)
		(layer "In13.Cu")
		(net "M_H_CPU0_SA_DQ<31>")
	)
	(segment
		(start 409.716478 -236.379004)
		(end 409.511754 -236.379004)
		(width 0.14478)
		(layer "In13.Cu")
		(net "M_H_CPU0_SA_DQ<31>")
	)
	(segment
		(start 408.342084 -237.753398)
		(end 408.156918 -237.938564)
		(width 0.14478)
		(layer "In13.Cu")
		(net "M_H_CPU0_SA_DQ<31>")
	)
	(segment
		(start 410.775912 -234.728766)
		(end 410.590746 -234.913932)
		(width 0.14478)
		(layer "In13.Cu")
		(net "M_H_CPU0_SA_DQ<31>")
	)
	(segment
		(start 406.691846 -238.812832)
		(end 406.691846 -239.017556)
		(width 0.14478)
		(layer "In13.Cu")
		(net "M_H_CPU0_SA_DQ<31>")
	)
	(segment
		(start 409.216352 -236.288326)
		(end 409.031186 -236.473492)
		(width 0.14478)
		(layer "In13.Cu")
		(net "M_H_CPU0_SA_DQ<31>")
	)
	(segment
		(start 408.251406 -237.253272)
		(end 408.251406 -237.457996)
		(width 0.14478)
		(layer "In13.Cu")
		(net "M_H_CPU0_SA_DQ<31>")
	)
	(segment
		(start 388.10184 -244.161564)
		(end 388.093458 -244.156738)
		(width 0.0889)
		(layer "In13.Cu")
		(net "M_H_CPU0_SA_DQ<31>")
	)
	(segment
		(start 406.097232 -239.407446)
		(end 405.912066 -239.592612)
		(width 0.14478)
		(layer "In13.Cu")
		(net "M_H_CPU0_SA_DQ<31>")
	)
	(segment
		(start 409.901644 -236.193838)
		(end 409.716478 -236.379004)
		(width 0.14478)
		(layer "In13.Cu")
		(net "M_H_CPU0_SA_DQ<31>")
	)
	(segment
		(start 404.742396 -240.967006)
		(end 404.537672 -240.967006)
		(width 0.14478)
		(layer "In13.Cu")
		(net "M_H_CPU0_SA_DQ<31>")
	)
	(segment
		(start 407.377138 -238.718344)
		(end 407.172414 -238.718344)
		(width 0.14478)
		(layer "In13.Cu")
		(net "M_H_CPU0_SA_DQ<31>")
	)
	(segment
		(start 411.785054 -234.310428)
		(end 411.276038 -234.819444)
		(width 0.14478)
		(layer "In13.Cu")
		(net "M_H_CPU0_SA_DQ<31>")
	)
	(segment
		(start 394.910056 -244.10035)
		(end 394.252196 -244.10035)
		(width 0.0889)
		(layer "In13.Cu")
		(net "M_H_CPU0_SA_DQ<31>")
	)
	(segment
		(start 406.597358 -239.498124)
		(end 406.392634 -239.498124)
		(width 0.14478)
		(layer "In13.Cu")
		(net "M_H_CPU0_SA_DQ<31>")
	)
	(segment
		(start 408.936698 -237.158784)
		(end 408.731974 -237.158784)
		(width 0.14478)
		(layer "In13.Cu")
		(net "M_H_CPU0_SA_DQ<31>")
	)
	(segment
		(start 407.081736 -238.627666)
		(end 406.877012 -238.627666)
		(width 0.14478)
		(layer "In13.Cu")
		(net "M_H_CPU0_SA_DQ<31>")
	)
	(segment
		(start 414.509204 -234.310428)
		(end 411.785054 -234.310428)
		(width 0.14478)
		(layer "In13.Cu")
		(net "M_H_CPU0_SA_DQ<31>")
	)
	(segment
		(start 409.901644 -235.989114)
		(end 409.901644 -236.193838)
		(width 0.14478)
		(layer "In13.Cu")
		(net "M_H_CPU0_SA_DQ<31>")
	)
	(segment
		(start 405.222964 -240.872518)
		(end 405.037798 -241.057684)
		(width 0.14478)
		(layer "In13.Cu")
		(net "M_H_CPU0_SA_DQ<31>")
	)
	(segment
		(start 409.996132 -235.508546)
		(end 409.810966 -235.693712)
		(width 0.14478)
		(layer "In13.Cu")
		(net "M_H_CPU0_SA_DQ<31>")
	)
	(segment
		(start 407.861516 -237.847886)
		(end 407.656792 -237.847886)
		(width 0.14478)
		(layer "In13.Cu")
		(net "M_H_CPU0_SA_DQ<31>")
	)
	(segment
		(start 408.342084 -237.548674)
		(end 408.342084 -237.753398)
		(width 0.14478)
		(layer "In13.Cu")
		(net "M_H_CPU0_SA_DQ<31>")
	)
	(segment
		(start 406.392634 -239.498124)
		(end 406.301956 -239.407446)
		(width 0.14478)
		(layer "In13.Cu")
		(net "M_H_CPU0_SA_DQ<31>")
	)
	(segment
		(start 405.912066 -239.797336)
		(end 406.002744 -239.888014)
		(width 0.14478)
		(layer "In13.Cu")
		(net "M_H_CPU0_SA_DQ<31>")
	)
	(segment
		(start 395.571726 -243.43868)
		(end 394.910056 -244.10035)
		(width 0.0889)
		(layer "In13.Cu")
		(net "M_H_CPU0_SA_DQ<31>")
	)
	(segment
		(start 409.031186 -236.473492)
		(end 409.031186 -236.678216)
		(width 0.14478)
		(layer "In13.Cu")
		(net "M_H_CPU0_SA_DQ<31>")
	)
	(segment
		(start 410.200856 -235.508546)
		(end 409.996132 -235.508546)
		(width 0.14478)
		(layer "In13.Cu")
		(net "M_H_CPU0_SA_DQ<31>")
	)
	(segment
		(start 394.252196 -244.10035)
		(end 394.114528 -244.238018)
		(width 0.0889)
		(layer "In13.Cu")
		(net "M_H_CPU0_SA_DQ<31>")
	)
	(segment
		(start 405.817578 -240.277904)
		(end 405.612854 -240.277904)
		(width 0.14478)
		(layer "In13.Cu")
		(net "M_H_CPU0_SA_DQ<31>")
	)
	(segment
		(start 402.656802 -243.43868)
		(end 395.860778 -243.43868)
		(width 0.14478)
		(layer "In13.Cu")
		(net "M_H_CPU0_SA_DQ<31>")
	)
	(segment
		(start 408.156918 -237.938564)
		(end 407.952194 -237.938564)
		(width 0.14478)
		(layer "In13.Cu")
		(net "M_H_CPU0_SA_DQ<31>")
	)
	(segment
		(start 418.551106 -234.310428)
		(end 417.700968 -233.46029)
		(width 0.14478)
		(layer "In13.Cu")
		(net "M_H_CPU0_SA_DQ<31>")
	)
	(segment
		(start 409.121864 -236.768894)
		(end 409.121864 -236.973618)
		(width 0.14478)
		(layer "In13.Cu")
		(net "M_H_CPU0_SA_DQ<31>")
	)
	(segment
		(start 406.877012 -238.627666)
		(end 406.691846 -238.812832)
		(width 0.14478)
		(layer "In13.Cu")
		(net "M_H_CPU0_SA_DQ<31>")
	)
	(segment
		(start 392.42873 -244.161564)
		(end 392.413998 -244.1702)
		(width 0.0889)
		(layer "In13.Cu")
		(net "M_H_CPU0_SA_DQ<31>")
	)
	(segment
		(start 384.341878 -244.161564)
		(end 384.333496 -244.156738)
		(width 0.0889)
		(layer "In13.Cu")
		(net "M_H_CPU0_SA_DQ<31>")
	)
	(segment
		(start 391.496042 -244.156738)
		(end 391.48766 -244.161564)
		(width 0.0889)
		(layer "In13.Cu")
		(net "M_H_CPU0_SA_DQ<31>")
	)
	(segment
		(start 407.471626 -238.237776)
		(end 407.562304 -238.328454)
		(width 0.14478)
		(layer "In13.Cu")
		(net "M_H_CPU0_SA_DQ<31>")
	)
	(segment
		(start 382.524762 -244.193314)
		(end 382.42875 -244.218714)
		(width 0.0889)
		(layer "In13.Cu")
		(net "M_H_CPU0_SA_DQ<31>")
	)
	(segment
		(start 405.522176 -240.187226)
		(end 405.317452 -240.187226)
		(width 0.14478)
		(layer "In13.Cu")
		(net "M_H_CPU0_SA_DQ<31>")
	)
	(segment
		(start 419.486588 -234.310428)
		(end 418.551106 -234.310428)
		(width 0.14478)
		(layer "In13.Cu")
		(net "M_H_CPU0_SA_DQ<31>")
	)
	(segment
		(start 389.616188 -244.156738)
		(end 389.607806 -244.161564)
		(width 0.0889)
		(layer "In13.Cu")
		(net "M_H_CPU0_SA_DQ<31>")
	)
	(segment
		(start 404.537672 -240.967006)
		(end 404.352506 -241.152172)
		(width 0.14478)
		(layer "In13.Cu")
		(net "M_H_CPU0_SA_DQ<31>")
	)
	(segment
		(start 408.436572 -237.068106)
		(end 408.251406 -237.253272)
		(width 0.14478)
		(layer "In13.Cu")
		(net "M_H_CPU0_SA_DQ<31>")
	)
	(arc
		(start 389.981948 -244.161564)
		(mid 389.799697 -244.111214)
		(end 389.616188 -244.156738)
		(width 0.0889)
		(layer "In13.Cu")
		(net "M_H_CPU0_SA_DQ<31>")
	)
	(arc
		(start 388.667752 -244.161564)
		(mid 388.384796 -244.237741)
		(end 388.10184 -244.161564)
		(width 0.0889)
		(layer "In13.Cu")
		(net "M_H_CPU0_SA_DQ<31>")
	)
	(arc
		(start 389.607806 -244.161564)
		(mid 389.32485 -244.237741)
		(end 389.041894 -244.161564)
		(width 0.0889)
		(layer "In13.Cu")
		(net "M_H_CPU0_SA_DQ<31>")
	)
	(arc
		(start 389.033512 -244.156738)
		(mid 388.850004 -244.111244)
		(end 388.667752 -244.161564)
		(width 0.0889)
		(layer "In13.Cu")
		(net "M_H_CPU0_SA_DQ<31>")
	)
	(arc
		(start 383.027682 -244.161564)
		(mid 382.779969 -244.236784)
		(end 382.524762 -244.193314)
		(width 0.0889)
		(layer "In13.Cu")
		(net "M_H_CPU0_SA_DQ<31>")
	)
	(arc
		(start 391.48766 -244.161564)
		(mid 391.204704 -244.237741)
		(end 390.921748 -244.161564)
		(width 0.0889)
		(layer "In13.Cu")
		(net "M_H_CPU0_SA_DQ<31>")
	)
	(arc
		(start 386.221986 -244.161564)
		(mid 386.039735 -244.111214)
		(end 385.856226 -244.156738)
		(width 0.0889)
		(layer "In13.Cu")
		(net "M_H_CPU0_SA_DQ<31>")
	)
	(arc
		(start 393.084812 -244.238018)
		(mid 392.93088 -244.216591)
		(end 392.788648 -244.153944)
		(width 0.0889)
		(layer "In13.Cu")
		(net "M_H_CPU0_SA_DQ<31>")
	)
	(arc
		(start 384.90779 -244.161564)
		(mid 384.624834 -244.237741)
		(end 384.341878 -244.161564)
		(width 0.0889)
		(layer "In13.Cu")
		(net "M_H_CPU0_SA_DQ<31>")
	)
	(arc
		(start 387.727698 -244.161564)
		(mid 387.444742 -244.237741)
		(end 387.161786 -244.161564)
		(width 0.0889)
		(layer "In13.Cu")
		(net "M_H_CPU0_SA_DQ<31>")
	)
	(arc
		(start 383.967736 -244.161564)
		(mid 383.68478 -244.237741)
		(end 383.401824 -244.161564)
		(width 0.0889)
		(layer "In13.Cu")
		(net "M_H_CPU0_SA_DQ<31>")
	)
	(arc
		(start 384.333496 -244.156738)
		(mid 384.149988 -244.111244)
		(end 383.967736 -244.161564)
		(width 0.0889)
		(layer "In13.Cu")
		(net "M_H_CPU0_SA_DQ<31>")
	)
	(arc
		(start 385.281932 -244.161564)
		(mid 385.099681 -244.111214)
		(end 384.916172 -244.156738)
		(width 0.0889)
		(layer "In13.Cu")
		(net "M_H_CPU0_SA_DQ<31>")
	)
	(arc
		(start 392.413998 -244.1702)
		(mid 392.137015 -244.238004)
		(end 391.86231 -244.161564)
		(width 0.0889)
		(layer "In13.Cu")
		(net "M_H_CPU0_SA_DQ<31>")
	)
	(arc
		(start 390.54786 -244.161564)
		(mid 390.264904 -244.237741)
		(end 389.981948 -244.161564)
		(width 0.0889)
		(layer "In13.Cu")
		(net "M_H_CPU0_SA_DQ<31>")
	)
	(arc
		(start 388.093458 -244.156738)
		(mid 387.90995 -244.111244)
		(end 387.727698 -244.161564)
		(width 0.0889)
		(layer "In13.Cu")
		(net "M_H_CPU0_SA_DQ<31>")
	)
	(arc
		(start 391.86231 -244.161564)
		(mid 391.679805 -244.111087)
		(end 391.496042 -244.156738)
		(width 0.0889)
		(layer "In13.Cu")
		(net "M_H_CPU0_SA_DQ<31>")
	)
	(arc
		(start 385.847844 -244.161564)
		(mid 385.564888 -244.237741)
		(end 385.281932 -244.161564)
		(width 0.0889)
		(layer "In13.Cu")
		(net "M_H_CPU0_SA_DQ<31>")
	)
	(arc
		(start 390.921748 -244.161564)
		(mid 390.734804 -244.111309)
		(end 390.54786 -244.161564)
		(width 0.0889)
		(layer "In13.Cu")
		(net "M_H_CPU0_SA_DQ<31>")
	)
	(arc
		(start 387.161786 -244.161564)
		(mid 386.974842 -244.111309)
		(end 386.787898 -244.161564)
		(width 0.0889)
		(layer "In13.Cu")
		(net "M_H_CPU0_SA_DQ<31>")
	)
	(arc
		(start 386.787898 -244.161564)
		(mid 386.504942 -244.237741)
		(end 386.221986 -244.161564)
		(width 0.0889)
		(layer "In13.Cu")
		(net "M_H_CPU0_SA_DQ<31>")
	)
	(arc
		(start 383.393442 -244.156738)
		(mid 383.209934 -244.111244)
		(end 383.027682 -244.161564)
		(width 0.0889)
		(layer "In13.Cu")
		(net "M_H_CPU0_SA_DQ<31>")
	)
	(arc
		(start 392.788648 -244.153944)
		(mid 392.607718 -244.111466)
		(end 392.42873 -244.161564)
		(width 0.0889)
		(layer "In13.Cu")
		(net "M_H_CPU0_SA_DQ<31>")
	)
	(segment
		(start 383.217928 -243.940076)
		(end 383.68478 -243.674138)
		(width 0.10668)
		(layer "F.Cu")
		(net "M_H_CPU0_SA_DQ<30>")
	)
	(segment
		(start 402.476716 -241.551206)
		(end 402.68144 -241.551206)
		(width 0.14478)
		(layer "In13.Cu")
		(net "M_H_CPU0_SA_DQ<30>")
	)
	(segment
		(start 404.397718 -238.998252)
		(end 404.602442 -238.998252)
		(width 0.14478)
		(layer "In13.Cu")
		(net "M_H_CPU0_SA_DQ<30>")
	)
	(segment
		(start 405.205946 -239.0267)
		(end 405.205946 -238.821976)
		(width 0.14478)
		(layer "In13.Cu")
		(net "M_H_CPU0_SA_DQ<30>")
	)
	(segment
		(start 417.52901 -231.760268)
		(end 418.379148 -232.610406)
		(width 0.14478)
		(layer "In13.Cu")
		(net "M_H_CPU0_SA_DQ<30>")
	)
	(segment
		(start 386.683504 -243.346732)
		(end 386.691886 -243.351558)
		(width 0.0889)
		(layer "In13.Cu")
		(net "M_H_CPU0_SA_DQ<30>")
	)
	(segment
		(start 395.166596 -242.892834)
		(end 395.53515 -242.52428)
		(width 0.0889)
		(layer "In13.Cu")
		(net "M_H_CPU0_SA_DQ<30>")
	)
	(segment
		(start 402.866606 -241.36604)
		(end 402.866606 -241.161316)
		(width 0.14478)
		(layer "In13.Cu")
		(net "M_H_CPU0_SA_DQ<30>")
	)
	(segment
		(start 404.816056 -239.211866)
		(end 405.02078 -239.211866)
		(width 0.14478)
		(layer "In13.Cu")
		(net "M_H_CPU0_SA_DQ<30>")
	)
	(segment
		(start 402.838158 -240.557812)
		(end 403.042882 -240.557812)
		(width 0.14478)
		(layer "In13.Cu")
		(net "M_H_CPU0_SA_DQ<30>")
	)
	(segment
		(start 403.822662 -239.778032)
		(end 404.036276 -239.991646)
		(width 0.14478)
		(layer "In13.Cu")
		(net "M_H_CPU0_SA_DQ<30>")
	)
	(segment
		(start 404.241 -239.991646)
		(end 404.426166 -239.80648)
		(width 0.14478)
		(layer "In13.Cu")
		(net "M_H_CPU0_SA_DQ<30>")
	)
	(segment
		(start 402.086826 -241.941096)
		(end 401.873212 -241.727482)
		(width 0.14478)
		(layer "In13.Cu")
		(net "M_H_CPU0_SA_DQ<30>")
	)
	(segment
		(start 404.212552 -239.183418)
		(end 404.397718 -238.998252)
		(width 0.14478)
		(layer "In13.Cu")
		(net "M_H_CPU0_SA_DQ<30>")
	)
	(segment
		(start 395.896338 -242.52428)
		(end 401.708366 -242.52428)
		(width 0.14478)
		(layer "In13.Cu")
		(net "M_H_CPU0_SA_DQ<30>")
	)
	(segment
		(start 401.873212 -241.727482)
		(end 401.873212 -241.522758)
		(width 0.14478)
		(layer "In13.Cu")
		(net "M_H_CPU0_SA_DQ<30>")
	)
	(segment
		(start 403.46122 -240.771426)
		(end 403.646386 -240.58626)
		(width 0.14478)
		(layer "In13.Cu")
		(net "M_H_CPU0_SA_DQ<30>")
	)
	(segment
		(start 388.197852 -243.351558)
		(end 388.206234 -243.346732)
		(width 0.0889)
		(layer "In13.Cu")
		(net "M_H_CPU0_SA_DQ<30>")
	)
	(segment
		(start 403.042882 -240.557812)
		(end 403.256496 -240.771426)
		(width 0.14478)
		(layer "In13.Cu")
		(net "M_H_CPU0_SA_DQ<30>")
	)
	(segment
		(start 404.036276 -239.991646)
		(end 404.241 -239.991646)
		(width 0.14478)
		(layer "In13.Cu")
		(net "M_H_CPU0_SA_DQ<30>")
	)
	(segment
		(start 402.086826 -242.14582)
		(end 402.086826 -241.941096)
		(width 0.14478)
		(layer "In13.Cu")
		(net "M_H_CPU0_SA_DQ<30>")
	)
	(segment
		(start 404.212552 -239.388142)
		(end 404.212552 -239.183418)
		(width 0.14478)
		(layer "In13.Cu")
		(net "M_H_CPU0_SA_DQ<30>")
	)
	(segment
		(start 405.772112 -237.623858)
		(end 405.957278 -237.438692)
		(width 0.14478)
		(layer "In13.Cu")
		(net "M_H_CPU0_SA_DQ<30>")
	)
	(segment
		(start 418.379148 -232.610406)
		(end 419.486588 -232.610406)
		(width 0.14478)
		(layer "In13.Cu")
		(net "M_H_CPU0_SA_DQ<30>")
	)
	(segment
		(start 401.708366 -242.52428)
		(end 402.086826 -242.14582)
		(width 0.14478)
		(layer "In13.Cu")
		(net "M_H_CPU0_SA_DQ<30>")
	)
	(segment
		(start 404.992332 -238.608362)
		(end 404.992332 -238.403638)
		(width 0.14478)
		(layer "In13.Cu")
		(net "M_H_CPU0_SA_DQ<30>")
	)
	(segment
		(start 395.53515 -242.52428)
		(end 395.896338 -242.52428)
		(width 0.0889)
		(layer "In13.Cu")
		(net "M_H_CPU0_SA_DQ<30>")
	)
	(segment
		(start 402.68144 -241.551206)
		(end 402.866606 -241.36604)
		(width 0.14478)
		(layer "In13.Cu")
		(net "M_H_CPU0_SA_DQ<30>")
	)
	(segment
		(start 402.058378 -241.337592)
		(end 402.263102 -241.337592)
		(width 0.14478)
		(layer "In13.Cu")
		(net "M_H_CPU0_SA_DQ<30>")
	)
	(segment
		(start 393.084812 -243.300758)
		(end 394.152628 -243.300758)
		(width 0.0889)
		(layer "In13.Cu")
		(net "M_H_CPU0_SA_DQ<30>")
	)
	(segment
		(start 405.177498 -238.218472)
		(end 405.382222 -238.218472)
		(width 0.14478)
		(layer "In13.Cu")
		(net "M_H_CPU0_SA_DQ<30>")
	)
	(segment
		(start 406.58034 -237.652306)
		(end 411.62224 -232.610406)
		(width 0.14478)
		(layer "In13.Cu")
		(net "M_H_CPU0_SA_DQ<30>")
	)
	(segment
		(start 387.257798 -243.351558)
		(end 387.26618 -243.346732)
		(width 0.0889)
		(layer "In13.Cu")
		(net "M_H_CPU0_SA_DQ<30>")
	)
	(segment
		(start 402.652992 -240.742978)
		(end 402.838158 -240.557812)
		(width 0.14478)
		(layer "In13.Cu")
		(net "M_H_CPU0_SA_DQ<30>")
	)
	(segment
		(start 404.426166 -239.80648)
		(end 404.426166 -239.601756)
		(width 0.14478)
		(layer "In13.Cu")
		(net "M_H_CPU0_SA_DQ<30>")
	)
	(segment
		(start 403.256496 -240.771426)
		(end 403.46122 -240.771426)
		(width 0.14478)
		(layer "In13.Cu")
		(net "M_H_CPU0_SA_DQ<30>")
	)
	(segment
		(start 415.7726 -231.760268)
		(end 417.52901 -231.760268)
		(width 0.14478)
		(layer "In13.Cu")
		(net "M_H_CPU0_SA_DQ<30>")
	)
	(segment
		(start 385.74345 -243.346732)
		(end 385.751832 -243.351558)
		(width 0.0889)
		(layer "In13.Cu")
		(net "M_H_CPU0_SA_DQ<30>")
	)
	(segment
		(start 403.646386 -240.58626)
		(end 403.646386 -240.381536)
		(width 0.14478)
		(layer "In13.Cu")
		(net "M_H_CPU0_SA_DQ<30>")
	)
	(segment
		(start 403.432772 -239.963198)
		(end 403.617938 -239.778032)
		(width 0.14478)
		(layer "In13.Cu")
		(net "M_H_CPU0_SA_DQ<30>")
	)
	(segment
		(start 394.34516 -243.49329)
		(end 394.826236 -243.49329)
		(width 0.0889)
		(layer "In13.Cu")
		(net "M_H_CPU0_SA_DQ<30>")
	)
	(segment
		(start 383.838958 -243.408708)
		(end 383.935224 -243.383308)
		(width 0.0889)
		(layer "In13.Cu")
		(net "M_H_CPU0_SA_DQ<30>")
	)
	(segment
		(start 405.595836 -238.432086)
		(end 405.80056 -238.432086)
		(width 0.14478)
		(layer "In13.Cu")
		(net "M_H_CPU0_SA_DQ<30>")
	)
	(segment
		(start 405.80056 -238.432086)
		(end 405.985726 -238.24692)
		(width 0.14478)
		(layer "In13.Cu")
		(net "M_H_CPU0_SA_DQ<30>")
	)
	(segment
		(start 402.652992 -240.947702)
		(end 402.652992 -240.742978)
		(width 0.14478)
		(layer "In13.Cu")
		(net "M_H_CPU0_SA_DQ<30>")
	)
	(segment
		(start 405.772112 -237.828582)
		(end 405.772112 -237.623858)
		(width 0.14478)
		(layer "In13.Cu")
		(net "M_H_CPU0_SA_DQ<30>")
	)
	(segment
		(start 394.826236 -243.49329)
		(end 395.166596 -243.15293)
		(width 0.0889)
		(layer "In13.Cu")
		(net "M_H_CPU0_SA_DQ<30>")
	)
	(segment
		(start 404.602442 -238.998252)
		(end 404.816056 -239.211866)
		(width 0.14478)
		(layer "In13.Cu")
		(net "M_H_CPU0_SA_DQ<30>")
	)
	(segment
		(start 394.152628 -243.300758)
		(end 394.34516 -243.49329)
		(width 0.0889)
		(layer "In13.Cu")
		(net "M_H_CPU0_SA_DQ<30>")
	)
	(segment
		(start 390.443466 -243.346732)
		(end 390.451848 -243.351558)
		(width 0.0889)
		(layer "In13.Cu")
		(net "M_H_CPU0_SA_DQ<30>")
	)
	(segment
		(start 414.922462 -232.610406)
		(end 415.7726 -231.760268)
		(width 0.14478)
		(layer "In13.Cu")
		(net "M_H_CPU0_SA_DQ<30>")
	)
	(segment
		(start 419.486588 -232.610406)
		(end 419.912038 -232.184956)
		(width 0.14478)
		(layer "In13.Cu")
		(net "M_H_CPU0_SA_DQ<30>")
	)
	(segment
		(start 403.646386 -240.381536)
		(end 403.432772 -240.167922)
		(width 0.14478)
		(layer "In13.Cu")
		(net "M_H_CPU0_SA_DQ<30>")
	)
	(segment
		(start 404.992332 -238.403638)
		(end 405.177498 -238.218472)
		(width 0.14478)
		(layer "In13.Cu")
		(net "M_H_CPU0_SA_DQ<30>")
	)
	(segment
		(start 405.02078 -239.211866)
		(end 405.205946 -239.0267)
		(width 0.14478)
		(layer "In13.Cu")
		(net "M_H_CPU0_SA_DQ<30>")
	)
	(segment
		(start 391.01776 -243.351558)
		(end 391.026142 -243.346732)
		(width 0.0889)
		(layer "In13.Cu")
		(net "M_H_CPU0_SA_DQ<30>")
	)
	(segment
		(start 402.263102 -241.337592)
		(end 402.476716 -241.551206)
		(width 0.14478)
		(layer "In13.Cu")
		(net "M_H_CPU0_SA_DQ<30>")
	)
	(segment
		(start 402.866606 -241.161316)
		(end 402.652992 -240.947702)
		(width 0.14478)
		(layer "In13.Cu")
		(net "M_H_CPU0_SA_DQ<30>")
	)
	(segment
		(start 395.166596 -243.15293)
		(end 395.166596 -242.892834)
		(width 0.0889)
		(layer "In13.Cu")
		(net "M_H_CPU0_SA_DQ<30>")
	)
	(segment
		(start 403.432772 -240.167922)
		(end 403.432772 -239.963198)
		(width 0.14478)
		(layer "In13.Cu")
		(net "M_H_CPU0_SA_DQ<30>")
	)
	(segment
		(start 404.426166 -239.601756)
		(end 404.212552 -239.388142)
		(width 0.14478)
		(layer "In13.Cu")
		(net "M_H_CPU0_SA_DQ<30>")
	)
	(segment
		(start 405.957278 -237.438692)
		(end 406.162002 -237.438692)
		(width 0.14478)
		(layer "In13.Cu")
		(net "M_H_CPU0_SA_DQ<30>")
	)
	(segment
		(start 405.382222 -238.218472)
		(end 405.595836 -238.432086)
		(width 0.14478)
		(layer "In13.Cu")
		(net "M_H_CPU0_SA_DQ<30>")
	)
	(segment
		(start 392.324336 -243.346732)
		(end 392.332718 -243.351558)
		(width 0.0889)
		(layer "In13.Cu")
		(net "M_H_CPU0_SA_DQ<30>")
	)
	(segment
		(start 411.62224 -232.610406)
		(end 414.922462 -232.610406)
		(width 0.14478)
		(layer "In13.Cu")
		(net "M_H_CPU0_SA_DQ<30>")
	)
	(segment
		(start 383.68478 -243.674138)
		(end 383.838958 -243.408708)
		(width 0.0889)
		(layer "In13.Cu")
		(net "M_H_CPU0_SA_DQ<30>")
	)
	(segment
		(start 391.391902 -243.351558)
		(end 391.402316 -243.357654)
		(width 0.0889)
		(layer "In13.Cu")
		(net "M_H_CPU0_SA_DQ<30>")
	)
	(segment
		(start 403.617938 -239.778032)
		(end 403.822662 -239.778032)
		(width 0.14478)
		(layer "In13.Cu")
		(net "M_H_CPU0_SA_DQ<30>")
	)
	(segment
		(start 405.205946 -238.821976)
		(end 404.992332 -238.608362)
		(width 0.14478)
		(layer "In13.Cu")
		(net "M_H_CPU0_SA_DQ<30>")
	)
	(segment
		(start 406.162002 -237.438692)
		(end 406.375616 -237.652306)
		(width 0.14478)
		(layer "In13.Cu")
		(net "M_H_CPU0_SA_DQ<30>")
	)
	(segment
		(start 405.985726 -238.042196)
		(end 405.772112 -237.828582)
		(width 0.14478)
		(layer "In13.Cu")
		(net "M_H_CPU0_SA_DQ<30>")
	)
	(segment
		(start 405.985726 -238.24692)
		(end 405.985726 -238.042196)
		(width 0.14478)
		(layer "In13.Cu")
		(net "M_H_CPU0_SA_DQ<30>")
	)
	(segment
		(start 401.873212 -241.522758)
		(end 402.058378 -241.337592)
		(width 0.14478)
		(layer "In13.Cu")
		(net "M_H_CPU0_SA_DQ<30>")
	)
	(segment
		(start 406.375616 -237.652306)
		(end 406.58034 -237.652306)
		(width 0.14478)
		(layer "In13.Cu")
		(net "M_H_CPU0_SA_DQ<30>")
	)
	(arc
		(start 383.935224 -243.383308)
		(mid 384.190289 -243.426659)
		(end 384.43789 -243.351558)
		(width 0.0889)
		(layer "In13.Cu")
		(net "M_H_CPU0_SA_DQ<30>")
	)
	(arc
		(start 392.892534 -243.355114)
		(mid 392.984966 -243.314832)
		(end 393.084812 -243.300758)
		(width 0.0889)
		(layer "In13.Cu")
		(net "M_H_CPU0_SA_DQ<30>")
	)
	(arc
		(start 390.451848 -243.351558)
		(mid 390.734804 -243.427735)
		(end 391.01776 -243.351558)
		(width 0.0889)
		(layer "In13.Cu")
		(net "M_H_CPU0_SA_DQ<30>")
	)
	(arc
		(start 389.511794 -243.351558)
		(mid 389.79475 -243.427735)
		(end 390.077706 -243.351558)
		(width 0.0889)
		(layer "In13.Cu")
		(net "M_H_CPU0_SA_DQ<30>")
	)
	(arc
		(start 391.958068 -243.351558)
		(mid 392.140573 -243.301081)
		(end 392.324336 -243.346732)
		(width 0.0889)
		(layer "In13.Cu")
		(net "M_H_CPU0_SA_DQ<30>")
	)
	(arc
		(start 389.137906 -243.351558)
		(mid 389.32485 -243.301303)
		(end 389.511794 -243.351558)
		(width 0.0889)
		(layer "In13.Cu")
		(net "M_H_CPU0_SA_DQ<30>")
	)
	(arc
		(start 384.811778 -243.351558)
		(mid 385.094734 -243.427735)
		(end 385.37769 -243.351558)
		(width 0.0889)
		(layer "In13.Cu")
		(net "M_H_CPU0_SA_DQ<30>")
	)
	(arc
		(start 388.571994 -243.351558)
		(mid 388.85495 -243.427735)
		(end 389.137906 -243.351558)
		(width 0.0889)
		(layer "In13.Cu")
		(net "M_H_CPU0_SA_DQ<30>")
	)
	(arc
		(start 392.332718 -243.351558)
		(mid 392.612146 -243.427724)
		(end 392.892534 -243.355114)
		(width 0.0889)
		(layer "In13.Cu")
		(net "M_H_CPU0_SA_DQ<30>")
	)
	(arc
		(start 391.402316 -243.357654)
		(mid 391.681002 -243.427874)
		(end 391.958068 -243.351558)
		(width 0.0889)
		(layer "In13.Cu")
		(net "M_H_CPU0_SA_DQ<30>")
	)
	(arc
		(start 386.691886 -243.351558)
		(mid 386.974842 -243.427735)
		(end 387.257798 -243.351558)
		(width 0.0889)
		(layer "In13.Cu")
		(net "M_H_CPU0_SA_DQ<30>")
	)
	(arc
		(start 385.37769 -243.351558)
		(mid 385.559941 -243.301208)
		(end 385.74345 -243.346732)
		(width 0.0889)
		(layer "In13.Cu")
		(net "M_H_CPU0_SA_DQ<30>")
	)
	(arc
		(start 387.63194 -243.351558)
		(mid 387.914896 -243.427735)
		(end 388.197852 -243.351558)
		(width 0.0889)
		(layer "In13.Cu")
		(net "M_H_CPU0_SA_DQ<30>")
	)
	(arc
		(start 384.43789 -243.351558)
		(mid 384.624834 -243.301303)
		(end 384.811778 -243.351558)
		(width 0.0889)
		(layer "In13.Cu")
		(net "M_H_CPU0_SA_DQ<30>")
	)
	(arc
		(start 388.206234 -243.346732)
		(mid 388.389742 -243.301238)
		(end 388.571994 -243.351558)
		(width 0.0889)
		(layer "In13.Cu")
		(net "M_H_CPU0_SA_DQ<30>")
	)
	(arc
		(start 391.026142 -243.346732)
		(mid 391.20965 -243.301238)
		(end 391.391902 -243.351558)
		(width 0.0889)
		(layer "In13.Cu")
		(net "M_H_CPU0_SA_DQ<30>")
	)
	(arc
		(start 387.26618 -243.346732)
		(mid 387.449688 -243.301238)
		(end 387.63194 -243.351558)
		(width 0.0889)
		(layer "In13.Cu")
		(net "M_H_CPU0_SA_DQ<30>")
	)
	(arc
		(start 390.077706 -243.351558)
		(mid 390.259957 -243.301208)
		(end 390.443466 -243.346732)
		(width 0.0889)
		(layer "In13.Cu")
		(net "M_H_CPU0_SA_DQ<30>")
	)
	(arc
		(start 385.751832 -243.351558)
		(mid 386.034788 -243.427735)
		(end 386.317744 -243.351558)
		(width 0.0889)
		(layer "In13.Cu")
		(net "M_H_CPU0_SA_DQ<30>")
	)
	(arc
		(start 386.317744 -243.351558)
		(mid 386.499995 -243.301208)
		(end 386.683504 -243.346732)
		(width 0.0889)
		(layer "In13.Cu")
		(net "M_H_CPU0_SA_DQ<30>")
	)
	(segment
		(start 383.217928 -226.120198)
		(end 383.68478 -225.85426)
		(width 0.10668)
		(layer "F.Cu")
		(net "M_H_CPU0_SA_DQ<2>")
	)
	(segment
		(start 383.838958 -225.58883)
		(end 383.68478 -225.85426)
		(width 0.0889)
		(layer "In13.Cu")
		(net "M_H_CPU0_SA_DQ<2>")
	)
	(segment
		(start 390.401556 -221.30385)
		(end 390.401556 -221.527624)
		(width 0.0889)
		(layer "In13.Cu")
		(net "M_H_CPU0_SA_DQ<2>")
	)
	(segment
		(start 388.668006 -224.721674)
		(end 388.636256 -224.739962)
		(width 0.0889)
		(layer "In13.Cu")
		(net "M_H_CPU0_SA_DQ<2>")
	)
	(segment
		(start 409.910534 -199.273922)
		(end 409.910534 -198.755)
		(width 0.14478)
		(layer "In13.Cu")
		(net "M_H_CPU0_SA_DQ<2>")
	)
	(segment
		(start 389.890508 -222.038672)
		(end 389.890508 -222.614236)
		(width 0.0889)
		(layer "In13.Cu")
		(net "M_H_CPU0_SA_DQ<2>")
	)
	(segment
		(start 411.157674 -199.418702)
		(end 411.012894 -199.273922)
		(width 0.14478)
		(layer "In13.Cu")
		(net "M_H_CPU0_SA_DQ<2>")
	)
	(segment
		(start 388.236968 -225.50882)
		(end 388.197852 -225.53168)
		(width 0.0889)
		(layer "In13.Cu")
		(net "M_H_CPU0_SA_DQ<2>")
	)
	(segment
		(start 410.316934 -199.418702)
		(end 410.055314 -199.418702)
		(width 0.14478)
		(layer "In13.Cu")
		(net "M_H_CPU0_SA_DQ<2>")
	)
	(segment
		(start 408.808174 -198.755)
		(end 408.663394 -198.61022)
		(width 0.14478)
		(layer "In13.Cu")
		(net "M_H_CPU0_SA_DQ<2>")
	)
	(segment
		(start 390.401556 -217.42273)
		(end 390.401556 -221.30385)
		(width 0.14478)
		(layer "In13.Cu")
		(net "M_H_CPU0_SA_DQ<2>")
	)
	(segment
		(start 408.952954 -199.418702)
		(end 408.808174 -199.273922)
		(width 0.14478)
		(layer "In13.Cu")
		(net "M_H_CPU0_SA_DQ<2>")
	)
	(segment
		(start 409.359354 -199.273922)
		(end 409.214574 -199.418702)
		(width 0.14478)
		(layer "In13.Cu")
		(net "M_H_CPU0_SA_DQ<2>")
	)
	(segment
		(start 407.923238 -198.61022)
		(end 397.179038 -209.35442)
		(width 0.14478)
		(layer "In13.Cu")
		(net "M_H_CPU0_SA_DQ<2>")
	)
	(segment
		(start 409.910534 -198.755)
		(end 409.765754 -198.61022)
		(width 0.14478)
		(layer "In13.Cu")
		(net "M_H_CPU0_SA_DQ<2>")
	)
	(segment
		(start 389.60806 -223.101662)
		(end 389.57758 -223.119442)
		(width 0.0889)
		(layer "In13.Cu")
		(net "M_H_CPU0_SA_DQ<2>")
	)
	(segment
		(start 389.178292 -223.888046)
		(end 389.137906 -223.911668)
		(width 0.0889)
		(layer "In13.Cu")
		(net "M_H_CPU0_SA_DQ<2>")
	)
	(segment
		(start 409.214574 -199.418702)
		(end 408.952954 -199.418702)
		(width 0.14478)
		(layer "In13.Cu")
		(net "M_H_CPU0_SA_DQ<2>")
	)
	(segment
		(start 410.055314 -199.418702)
		(end 409.910534 -199.273922)
		(width 0.14478)
		(layer "In13.Cu")
		(net "M_H_CPU0_SA_DQ<2>")
	)
	(segment
		(start 387.26618 -225.526854)
		(end 387.257798 -225.53168)
		(width 0.0889)
		(layer "In13.Cu")
		(net "M_H_CPU0_SA_DQ<2>")
	)
	(segment
		(start 410.461714 -198.755)
		(end 410.461714 -199.273922)
		(width 0.14478)
		(layer "In13.Cu")
		(net "M_H_CPU0_SA_DQ<2>")
	)
	(segment
		(start 409.504134 -198.61022)
		(end 409.359354 -198.755)
		(width 0.14478)
		(layer "In13.Cu")
		(net "M_H_CPU0_SA_DQ<2>")
	)
	(segment
		(start 418.25545 -197.760082)
		(end 415.01822 -197.760082)
		(width 0.14478)
		(layer "In13.Cu")
		(net "M_H_CPU0_SA_DQ<2>")
	)
	(segment
		(start 410.461714 -199.273922)
		(end 410.316934 -199.418702)
		(width 0.14478)
		(layer "In13.Cu")
		(net "M_H_CPU0_SA_DQ<2>")
	)
	(segment
		(start 410.606494 -198.61022)
		(end 410.461714 -198.755)
		(width 0.14478)
		(layer "In13.Cu")
		(net "M_H_CPU0_SA_DQ<2>")
	)
	(segment
		(start 409.359354 -198.755)
		(end 409.359354 -199.273922)
		(width 0.14478)
		(layer "In13.Cu")
		(net "M_H_CPU0_SA_DQ<2>")
	)
	(segment
		(start 419.912038 -198.185024)
		(end 419.486842 -198.61022)
		(width 0.14478)
		(layer "In13.Cu")
		(net "M_H_CPU0_SA_DQ<2>")
	)
	(segment
		(start 389.137906 -223.911668)
		(end 389.106156 -223.929956)
		(width 0.0889)
		(layer "In13.Cu")
		(net "M_H_CPU0_SA_DQ<2>")
	)
	(segment
		(start 385.751832 -225.53168)
		(end 385.74345 -225.526854)
		(width 0.0889)
		(layer "In13.Cu")
		(net "M_H_CPU0_SA_DQ<2>")
	)
	(segment
		(start 411.419294 -199.418702)
		(end 411.157674 -199.418702)
		(width 0.14478)
		(layer "In13.Cu")
		(net "M_H_CPU0_SA_DQ<2>")
	)
	(segment
		(start 411.708854 -198.61022)
		(end 411.564074 -198.755)
		(width 0.14478)
		(layer "In13.Cu")
		(net "M_H_CPU0_SA_DQ<2>")
	)
	(segment
		(start 411.564074 -198.755)
		(end 411.564074 -199.273922)
		(width 0.14478)
		(layer "In13.Cu")
		(net "M_H_CPU0_SA_DQ<2>")
	)
	(segment
		(start 419.486842 -198.61022)
		(end 419.105588 -198.61022)
		(width 0.14478)
		(layer "In13.Cu")
		(net "M_H_CPU0_SA_DQ<2>")
	)
	(segment
		(start 419.105588 -198.61022)
		(end 418.25545 -197.760082)
		(width 0.14478)
		(layer "In13.Cu")
		(net "M_H_CPU0_SA_DQ<2>")
	)
	(segment
		(start 411.564074 -199.273922)
		(end 411.419294 -199.418702)
		(width 0.14478)
		(layer "In13.Cu")
		(net "M_H_CPU0_SA_DQ<2>")
	)
	(segment
		(start 388.704328 -224.700592)
		(end 388.668006 -224.721674)
		(width 0.0889)
		(layer "In13.Cu")
		(net "M_H_CPU0_SA_DQ<2>")
	)
	(segment
		(start 411.012894 -199.273922)
		(end 411.012894 -198.755)
		(width 0.14478)
		(layer "In13.Cu")
		(net "M_H_CPU0_SA_DQ<2>")
	)
	(segment
		(start 386.691886 -225.53168)
		(end 386.683504 -225.526854)
		(width 0.0889)
		(layer "In13.Cu")
		(net "M_H_CPU0_SA_DQ<2>")
	)
	(segment
		(start 409.765754 -198.61022)
		(end 409.504134 -198.61022)
		(width 0.14478)
		(layer "In13.Cu")
		(net "M_H_CPU0_SA_DQ<2>")
	)
	(segment
		(start 390.401556 -221.527624)
		(end 389.890508 -222.038672)
		(width 0.0889)
		(layer "In13.Cu")
		(net "M_H_CPU0_SA_DQ<2>")
	)
	(segment
		(start 397.179038 -210.645248)
		(end 390.401556 -217.42273)
		(width 0.14478)
		(layer "In13.Cu")
		(net "M_H_CPU0_SA_DQ<2>")
	)
	(segment
		(start 411.012894 -198.755)
		(end 410.868114 -198.61022)
		(width 0.14478)
		(layer "In13.Cu")
		(net "M_H_CPU0_SA_DQ<2>")
	)
	(segment
		(start 410.868114 -198.61022)
		(end 410.606494 -198.61022)
		(width 0.14478)
		(layer "In13.Cu")
		(net "M_H_CPU0_SA_DQ<2>")
	)
	(segment
		(start 408.663394 -198.61022)
		(end 407.923238 -198.61022)
		(width 0.14478)
		(layer "In13.Cu")
		(net "M_H_CPU0_SA_DQ<2>")
	)
	(segment
		(start 408.808174 -199.273922)
		(end 408.808174 -198.755)
		(width 0.14478)
		(layer "In13.Cu")
		(net "M_H_CPU0_SA_DQ<2>")
	)
	(segment
		(start 383.935224 -225.56343)
		(end 383.838958 -225.58883)
		(width 0.0889)
		(layer "In13.Cu")
		(net "M_H_CPU0_SA_DQ<2>")
	)
	(segment
		(start 414.168082 -198.61022)
		(end 411.708854 -198.61022)
		(width 0.14478)
		(layer "In13.Cu")
		(net "M_H_CPU0_SA_DQ<2>")
	)
	(segment
		(start 415.01822 -197.760082)
		(end 414.168082 -198.61022)
		(width 0.14478)
		(layer "In13.Cu")
		(net "M_H_CPU0_SA_DQ<2>")
	)
	(segment
		(start 397.179038 -209.35442)
		(end 397.179038 -210.645248)
		(width 0.14478)
		(layer "In13.Cu")
		(net "M_H_CPU0_SA_DQ<2>")
	)
	(segment
		(start 389.648446 -223.07804)
		(end 389.60806 -223.101662)
		(width 0.0889)
		(layer "In13.Cu")
		(net "M_H_CPU0_SA_DQ<2>")
	)
	(arc
		(start 385.74345 -225.526854)
		(mid 385.559942 -225.48136)
		(end 385.37769 -225.53168)
		(width 0.0889)
		(layer "In13.Cu")
		(net "M_H_CPU0_SA_DQ<2>")
	)
	(arc
		(start 389.890508 -222.614236)
		(mid 389.826355 -222.875825)
		(end 389.648446 -223.07804)
		(width 0.0889)
		(layer "In13.Cu")
		(net "M_H_CPU0_SA_DQ<2>")
	)
	(arc
		(start 384.43789 -225.53168)
		(mid 384.190294 -225.606858)
		(end 383.935224 -225.56343)
		(width 0.0889)
		(layer "In13.Cu")
		(net "M_H_CPU0_SA_DQ<2>")
	)
	(arc
		(start 387.257798 -225.53168)
		(mid 386.974842 -225.607857)
		(end 386.691886 -225.53168)
		(width 0.0889)
		(layer "In13.Cu")
		(net "M_H_CPU0_SA_DQ<2>")
	)
	(arc
		(start 388.197852 -225.53168)
		(mid 387.914896 -225.607857)
		(end 387.63194 -225.53168)
		(width 0.0889)
		(layer "In13.Cu")
		(net "M_H_CPU0_SA_DQ<2>")
	)
	(arc
		(start 386.317744 -225.53168)
		(mid 386.034788 -225.607857)
		(end 385.751832 -225.53168)
		(width 0.0889)
		(layer "In13.Cu")
		(net "M_H_CPU0_SA_DQ<2>")
	)
	(arc
		(start 386.683504 -225.526854)
		(mid 386.499996 -225.48136)
		(end 386.317744 -225.53168)
		(width 0.0889)
		(layer "In13.Cu")
		(net "M_H_CPU0_SA_DQ<2>")
	)
	(arc
		(start 389.420608 -223.424242)
		(mid 389.356315 -223.685847)
		(end 389.178292 -223.888046)
		(width 0.0889)
		(layer "In13.Cu")
		(net "M_H_CPU0_SA_DQ<2>")
	)
	(arc
		(start 384.811778 -225.53168)
		(mid 384.624834 -225.481425)
		(end 384.43789 -225.53168)
		(width 0.0889)
		(layer "In13.Cu")
		(net "M_H_CPU0_SA_DQ<2>")
	)
	(arc
		(start 389.106156 -223.929956)
		(mid 388.99148 -224.06329)
		(end 388.9502 -224.234248)
		(width 0.0889)
		(layer "In13.Cu")
		(net "M_H_CPU0_SA_DQ<2>")
	)
	(arc
		(start 388.4803 -225.044254)
		(mid 388.415785 -225.306473)
		(end 388.236968 -225.50882)
		(width 0.0889)
		(layer "In13.Cu")
		(net "M_H_CPU0_SA_DQ<2>")
	)
	(arc
		(start 388.636256 -224.739962)
		(mid 388.52158 -224.873296)
		(end 388.4803 -225.044254)
		(width 0.0889)
		(layer "In13.Cu")
		(net "M_H_CPU0_SA_DQ<2>")
	)
	(arc
		(start 388.9502 -224.234248)
		(mid 388.884964 -224.497839)
		(end 388.704328 -224.700592)
		(width 0.0889)
		(layer "In13.Cu")
		(net "M_H_CPU0_SA_DQ<2>")
	)
	(arc
		(start 387.63194 -225.53168)
		(mid 387.449689 -225.48133)
		(end 387.26618 -225.526854)
		(width 0.0889)
		(layer "In13.Cu")
		(net "M_H_CPU0_SA_DQ<2>")
	)
	(arc
		(start 389.57758 -223.119442)
		(mid 389.462153 -223.252818)
		(end 389.420608 -223.424242)
		(width 0.0889)
		(layer "In13.Cu")
		(net "M_H_CPU0_SA_DQ<2>")
	)
	(arc
		(start 385.37769 -225.53168)
		(mid 385.094734 -225.607857)
		(end 384.811778 -225.53168)
		(width 0.0889)
		(layer "In13.Cu")
		(net "M_H_CPU0_SA_DQ<2>")
	)
	(segment
		(start 382.277874 -243.940076)
		(end 382.744726 -243.674138)
		(width 0.10668)
		(layer "F.Cu")
		(net "M_H_CPU0_SA_DQ<29>")
	)
	(segment
		(start 411.408372 -233.46029)
		(end 414.71596 -233.46029)
		(width 0.14478)
		(layer "In13.Cu")
		(net "M_H_CPU0_SA_DQ<29>")
	)
	(segment
		(start 395.683486 -242.97894)
		(end 395.87805 -242.97894)
		(width 0.0889)
		(layer "In13.Cu")
		(net "M_H_CPU0_SA_DQ<29>")
	)
	(segment
		(start 393.084812 -244.047518)
		(end 393.869672 -244.047518)
		(width 0.0889)
		(layer "In13.Cu")
		(net "M_H_CPU0_SA_DQ<29>")
	)
	(segment
		(start 417.619688 -232.610406)
		(end 418.469572 -233.46029)
		(width 0.14478)
		(layer "In13.Cu")
		(net "M_H_CPU0_SA_DQ<29>")
	)
	(segment
		(start 393.869672 -244.047518)
		(end 394.12418 -243.79301)
		(width 0.0889)
		(layer "In13.Cu")
		(net "M_H_CPU0_SA_DQ<29>")
	)
	(segment
		(start 415.565844 -232.610406)
		(end 417.619688 -232.610406)
		(width 0.14478)
		(layer "In13.Cu")
		(net "M_H_CPU0_SA_DQ<29>")
	)
	(segment
		(start 386.683504 -244.001544)
		(end 386.691886 -243.996718)
		(width 0.0889)
		(layer "In13.Cu")
		(net "M_H_CPU0_SA_DQ<29>")
	)
	(segment
		(start 392.321034 -244.003576)
		(end 392.332718 -243.996718)
		(width 0.0889)
		(layer "In13.Cu")
		(net "M_H_CPU0_SA_DQ<29>")
	)
	(segment
		(start 391.391902 -243.996718)
		(end 391.406634 -243.988082)
		(width 0.0889)
		(layer "In13.Cu")
		(net "M_H_CPU0_SA_DQ<29>")
	)
	(segment
		(start 390.443466 -244.001544)
		(end 390.451848 -243.996718)
		(width 0.0889)
		(layer "In13.Cu")
		(net "M_H_CPU0_SA_DQ<29>")
	)
	(segment
		(start 391.01776 -243.996718)
		(end 391.026142 -244.001544)
		(width 0.0889)
		(layer "In13.Cu")
		(net "M_H_CPU0_SA_DQ<29>")
	)
	(segment
		(start 414.71596 -233.46029)
		(end 415.565844 -232.610406)
		(width 0.14478)
		(layer "In13.Cu")
		(net "M_H_CPU0_SA_DQ<29>")
	)
	(segment
		(start 383.497836 -243.996718)
		(end 383.506218 -244.001544)
		(width 0.0889)
		(layer "In13.Cu")
		(net "M_H_CPU0_SA_DQ<29>")
	)
	(segment
		(start 401.889722 -242.97894)
		(end 411.408372 -233.46029)
		(width 0.14478)
		(layer "In13.Cu")
		(net "M_H_CPU0_SA_DQ<29>")
	)
	(segment
		(start 421.731186 -233.46029)
		(end 422.156382 -233.035094)
		(width 0.14478)
		(layer "In13.Cu")
		(net "M_H_CPU0_SA_DQ<29>")
	)
	(segment
		(start 422.156382 -233.035094)
		(end 424.012106 -233.035094)
		(width 0.14478)
		(layer "In13.Cu")
		(net "M_H_CPU0_SA_DQ<29>")
	)
	(segment
		(start 388.197852 -243.996718)
		(end 388.206234 -244.001544)
		(width 0.0889)
		(layer "In13.Cu")
		(net "M_H_CPU0_SA_DQ<29>")
	)
	(segment
		(start 395.87805 -242.97894)
		(end 401.889722 -242.97894)
		(width 0.14478)
		(layer "In13.Cu")
		(net "M_H_CPU0_SA_DQ<29>")
	)
	(segment
		(start 394.12418 -243.79301)
		(end 394.869416 -243.79301)
		(width 0.0889)
		(layer "In13.Cu")
		(net "M_H_CPU0_SA_DQ<29>")
	)
	(segment
		(start 418.469572 -233.46029)
		(end 421.731186 -233.46029)
		(width 0.14478)
		(layer "In13.Cu")
		(net "M_H_CPU0_SA_DQ<29>")
	)
	(segment
		(start 382.590802 -243.939568)
		(end 382.613154 -244.02288)
		(width 0.0889)
		(layer "In13.Cu")
		(net "M_H_CPU0_SA_DQ<29>")
	)
	(segment
		(start 382.744726 -243.674138)
		(end 382.590802 -243.939568)
		(width 0.0889)
		(layer "In13.Cu")
		(net "M_H_CPU0_SA_DQ<29>")
	)
	(segment
		(start 387.257798 -243.996718)
		(end 387.26618 -244.001544)
		(width 0.0889)
		(layer "In13.Cu")
		(net "M_H_CPU0_SA_DQ<29>")
	)
	(segment
		(start 394.869416 -243.79301)
		(end 395.683486 -242.97894)
		(width 0.0889)
		(layer "In13.Cu")
		(net "M_H_CPU0_SA_DQ<29>")
	)
	(segment
		(start 385.74345 -244.001544)
		(end 385.751832 -243.996718)
		(width 0.0889)
		(layer "In13.Cu")
		(net "M_H_CPU0_SA_DQ<29>")
	)
	(arc
		(start 383.506218 -244.001544)
		(mid 383.689726 -244.047038)
		(end 383.871978 -243.996718)
		(width 0.0889)
		(layer "In13.Cu")
		(net "M_H_CPU0_SA_DQ<29>")
	)
	(arc
		(start 383.871978 -243.996718)
		(mid 384.154934 -243.920541)
		(end 384.43789 -243.996718)
		(width 0.0889)
		(layer "In13.Cu")
		(net "M_H_CPU0_SA_DQ<29>")
	)
	(arc
		(start 384.43789 -243.996718)
		(mid 384.624834 -244.046973)
		(end 384.811778 -243.996718)
		(width 0.0889)
		(layer "In13.Cu")
		(net "M_H_CPU0_SA_DQ<29>")
	)
	(arc
		(start 386.317744 -243.996718)
		(mid 386.499995 -244.047068)
		(end 386.683504 -244.001544)
		(width 0.0889)
		(layer "In13.Cu")
		(net "M_H_CPU0_SA_DQ<29>")
	)
	(arc
		(start 384.811778 -243.996718)
		(mid 385.094734 -243.920541)
		(end 385.37769 -243.996718)
		(width 0.0889)
		(layer "In13.Cu")
		(net "M_H_CPU0_SA_DQ<29>")
	)
	(arc
		(start 388.571994 -243.996718)
		(mid 388.85495 -243.920541)
		(end 389.137906 -243.996718)
		(width 0.0889)
		(layer "In13.Cu")
		(net "M_H_CPU0_SA_DQ<29>")
	)
	(arc
		(start 386.691886 -243.996718)
		(mid 386.974842 -243.920541)
		(end 387.257798 -243.996718)
		(width 0.0889)
		(layer "In13.Cu")
		(net "M_H_CPU0_SA_DQ<29>")
	)
	(arc
		(start 385.751832 -243.996718)
		(mid 386.034788 -243.920541)
		(end 386.317744 -243.996718)
		(width 0.0889)
		(layer "In13.Cu")
		(net "M_H_CPU0_SA_DQ<29>")
	)
	(arc
		(start 391.406634 -243.988082)
		(mid 391.683617 -243.920278)
		(end 391.958322 -243.996718)
		(width 0.0889)
		(layer "In13.Cu")
		(net "M_H_CPU0_SA_DQ<29>")
	)
	(arc
		(start 392.892534 -243.993162)
		(mid 392.984966 -244.033444)
		(end 393.084812 -244.047518)
		(width 0.0889)
		(layer "In13.Cu")
		(net "M_H_CPU0_SA_DQ<29>")
	)
	(arc
		(start 388.206234 -244.001544)
		(mid 388.389742 -244.047038)
		(end 388.571994 -243.996718)
		(width 0.0889)
		(layer "In13.Cu")
		(net "M_H_CPU0_SA_DQ<29>")
	)
	(arc
		(start 389.511794 -243.996718)
		(mid 389.79475 -243.920541)
		(end 390.077706 -243.996718)
		(width 0.0889)
		(layer "In13.Cu")
		(net "M_H_CPU0_SA_DQ<29>")
	)
	(arc
		(start 392.332718 -243.996718)
		(mid 392.612146 -243.920552)
		(end 392.892534 -243.993162)
		(width 0.0889)
		(layer "In13.Cu")
		(net "M_H_CPU0_SA_DQ<29>")
	)
	(arc
		(start 382.931924 -243.996718)
		(mid 383.21488 -243.920541)
		(end 383.497836 -243.996718)
		(width 0.0889)
		(layer "In13.Cu")
		(net "M_H_CPU0_SA_DQ<29>")
	)
	(arc
		(start 385.37769 -243.996718)
		(mid 385.559941 -244.047068)
		(end 385.74345 -244.001544)
		(width 0.0889)
		(layer "In13.Cu")
		(net "M_H_CPU0_SA_DQ<29>")
	)
	(arc
		(start 387.26618 -244.001544)
		(mid 387.449688 -244.047038)
		(end 387.63194 -243.996718)
		(width 0.0889)
		(layer "In13.Cu")
		(net "M_H_CPU0_SA_DQ<29>")
	)
	(arc
		(start 390.077706 -243.996718)
		(mid 390.259957 -244.047068)
		(end 390.443466 -244.001544)
		(width 0.0889)
		(layer "In13.Cu")
		(net "M_H_CPU0_SA_DQ<29>")
	)
	(arc
		(start 391.026142 -244.001544)
		(mid 391.20965 -244.047038)
		(end 391.391902 -243.996718)
		(width 0.0889)
		(layer "In13.Cu")
		(net "M_H_CPU0_SA_DQ<29>")
	)
	(arc
		(start 390.451848 -243.996718)
		(mid 390.734804 -243.920541)
		(end 391.01776 -243.996718)
		(width 0.0889)
		(layer "In13.Cu")
		(net "M_H_CPU0_SA_DQ<29>")
	)
	(arc
		(start 389.137906 -243.996718)
		(mid 389.32485 -244.046973)
		(end 389.511794 -243.996718)
		(width 0.0889)
		(layer "In13.Cu")
		(net "M_H_CPU0_SA_DQ<29>")
	)
	(arc
		(start 387.63194 -243.996718)
		(mid 387.914896 -243.920541)
		(end 388.197852 -243.996718)
		(width 0.0889)
		(layer "In13.Cu")
		(net "M_H_CPU0_SA_DQ<29>")
	)
	(arc
		(start 391.958322 -243.996718)
		(mid 392.13878 -244.047162)
		(end 392.321034 -244.003576)
		(width 0.0889)
		(layer "In13.Cu")
		(net "M_H_CPU0_SA_DQ<29>")
	)
	(arc
		(start 382.613154 -244.02288)
		(mid 382.775486 -244.045698)
		(end 382.931924 -243.996718)
		(width 0.0889)
		(layer "In13.Cu")
		(net "M_H_CPU0_SA_DQ<29>")
	)
	(segment
		(start 383.688082 -243.13007)
		(end 384.154934 -242.864132)
		(width 0.10668)
		(layer "F.Cu")
		(net "M_H_CPU0_SA_DQ<28>")
	)
	(segment
		(start 417.486084 -230.91013)
		(end 415.120328 -230.91013)
		(width 0.14478)
		(layer "In13.Cu")
		(net "M_H_CPU0_SA_DQ<28>")
	)
	(segment
		(start 394.675106 -242.63477)
		(end 394.199618 -243.110258)
		(width 0.0889)
		(layer "In13.Cu")
		(net "M_H_CPU0_SA_DQ<28>")
	)
	(segment
		(start 384.023108 -243.212874)
		(end 384.000756 -243.129562)
		(width 0.0889)
		(layer "In13.Cu")
		(net "M_H_CPU0_SA_DQ<28>")
	)
	(segment
		(start 422.214802 -232.272332)
		(end 422.070022 -232.127552)
		(width 0.14478)
		(layer "In13.Cu")
		(net "M_H_CPU0_SA_DQ<28>")
	)
	(segment
		(start 384.916172 -243.191538)
		(end 384.90779 -243.186712)
		(width 0.0889)
		(layer "In13.Cu")
		(net "M_H_CPU0_SA_DQ<28>")
	)
	(segment
		(start 385.856226 -243.191538)
		(end 385.847844 -243.186712)
		(width 0.0889)
		(layer "In13.Cu")
		(net "M_H_CPU0_SA_DQ<28>")
	)
	(segment
		(start 422.476422 -232.272332)
		(end 422.214802 -232.272332)
		(width 0.14478)
		(layer "In13.Cu")
		(net "M_H_CPU0_SA_DQ<28>")
	)
	(segment
		(start 422.070022 -232.127552)
		(end 422.070022 -231.914446)
		(width 0.14478)
		(layer "In13.Cu")
		(net "M_H_CPU0_SA_DQ<28>")
	)
	(segment
		(start 392.428476 -243.186712)
		(end 392.418062 -243.180616)
		(width 0.0889)
		(layer "In13.Cu")
		(net "M_H_CPU0_SA_DQ<28>")
	)
	(segment
		(start 423.317162 -231.769666)
		(end 423.172382 -231.624886)
		(width 0.14478)
		(layer "In13.Cu")
		(net "M_H_CPU0_SA_DQ<28>")
	)
	(segment
		(start 384.341878 -243.186712)
		(end 384.333496 -243.191538)
		(width 0.0889)
		(layer "In13.Cu")
		(net "M_H_CPU0_SA_DQ<28>")
	)
	(segment
		(start 422.070022 -231.914446)
		(end 421.925242 -231.769666)
		(width 0.14478)
		(layer "In13.Cu")
		(net "M_H_CPU0_SA_DQ<28>")
	)
	(segment
		(start 423.577512 -231.769666)
		(end 423.317162 -231.769666)
		(width 0.14478)
		(layer "In13.Cu")
		(net "M_H_CPU0_SA_DQ<28>")
	)
	(segment
		(start 411.836616 -231.760014)
		(end 407.227532 -236.369098)
		(width 0.14478)
		(layer "In13.Cu")
		(net "M_H_CPU0_SA_DQ<28>")
	)
	(segment
		(start 423.172382 -231.41178)
		(end 423.027602 -231.267)
		(width 0.14478)
		(layer "In13.Cu")
		(net "M_H_CPU0_SA_DQ<28>")
	)
	(segment
		(start 389.041894 -243.186712)
		(end 389.033512 -243.191538)
		(width 0.0889)
		(layer "In13.Cu")
		(net "M_H_CPU0_SA_DQ<28>")
	)
	(segment
		(start 388.10184 -243.186712)
		(end 388.093458 -243.191538)
		(width 0.0889)
		(layer "In13.Cu")
		(net "M_H_CPU0_SA_DQ<28>")
	)
	(segment
		(start 424.012106 -231.335072)
		(end 423.577512 -231.769666)
		(width 0.14478)
		(layer "In13.Cu")
		(net "M_H_CPU0_SA_DQ<28>")
	)
	(segment
		(start 395.531086 -242.06962)
		(end 395.426946 -242.17376)
		(width 0.14478)
		(layer "In13.Cu")
		(net "M_H_CPU0_SA_DQ<28>")
	)
	(segment
		(start 384.000756 -243.129562)
		(end 384.154934 -242.864132)
		(width 0.0889)
		(layer "In13.Cu")
		(net "M_H_CPU0_SA_DQ<28>")
	)
	(segment
		(start 422.765982 -231.267)
		(end 422.621202 -231.41178)
		(width 0.14478)
		(layer "In13.Cu")
		(net "M_H_CPU0_SA_DQ<28>")
	)
	(segment
		(start 407.227532 -236.369098)
		(end 405.993092 -236.369098)
		(width 0.14478)
		(layer "In13.Cu")
		(net "M_H_CPU0_SA_DQ<28>")
	)
	(segment
		(start 394.965936 -242.63477)
		(end 394.675106 -242.63477)
		(width 0.0889)
		(layer "In13.Cu")
		(net "M_H_CPU0_SA_DQ<28>")
	)
	(segment
		(start 389.616188 -243.191538)
		(end 389.607806 -243.186712)
		(width 0.0889)
		(layer "In13.Cu")
		(net "M_H_CPU0_SA_DQ<28>")
	)
	(segment
		(start 422.621202 -231.41178)
		(end 422.621202 -232.127552)
		(width 0.14478)
		(layer "In13.Cu")
		(net "M_H_CPU0_SA_DQ<28>")
	)
	(segment
		(start 405.993092 -236.369098)
		(end 400.29257 -242.06962)
		(width 0.14478)
		(layer "In13.Cu")
		(net "M_H_CPU0_SA_DQ<28>")
	)
	(segment
		(start 422.621202 -232.127552)
		(end 422.476422 -232.272332)
		(width 0.14478)
		(layer "In13.Cu")
		(net "M_H_CPU0_SA_DQ<28>")
	)
	(segment
		(start 423.172382 -231.624886)
		(end 423.172382 -231.41178)
		(width 0.14478)
		(layer "In13.Cu")
		(net "M_H_CPU0_SA_DQ<28>")
	)
	(segment
		(start 418.34562 -231.769666)
		(end 417.486084 -230.91013)
		(width 0.14478)
		(layer "In13.Cu")
		(net "M_H_CPU0_SA_DQ<28>")
	)
	(segment
		(start 400.29257 -242.06962)
		(end 395.531086 -242.06962)
		(width 0.14478)
		(layer "In13.Cu")
		(net "M_H_CPU0_SA_DQ<28>")
	)
	(segment
		(start 415.120328 -230.91013)
		(end 414.270444 -231.760014)
		(width 0.14478)
		(layer "In13.Cu")
		(net "M_H_CPU0_SA_DQ<28>")
	)
	(segment
		(start 423.027602 -231.267)
		(end 422.765982 -231.267)
		(width 0.14478)
		(layer "In13.Cu")
		(net "M_H_CPU0_SA_DQ<28>")
	)
	(segment
		(start 414.270444 -231.760014)
		(end 411.836616 -231.760014)
		(width 0.14478)
		(layer "In13.Cu")
		(net "M_H_CPU0_SA_DQ<28>")
	)
	(segment
		(start 421.925242 -231.769666)
		(end 418.34562 -231.769666)
		(width 0.14478)
		(layer "In13.Cu")
		(net "M_H_CPU0_SA_DQ<28>")
	)
	(segment
		(start 394.199618 -243.110258)
		(end 393.084812 -243.110258)
		(width 0.0889)
		(layer "In13.Cu")
		(net "M_H_CPU0_SA_DQ<28>")
	)
	(segment
		(start 391.496042 -243.191538)
		(end 391.48766 -243.186712)
		(width 0.0889)
		(layer "In13.Cu")
		(net "M_H_CPU0_SA_DQ<28>")
	)
	(segment
		(start 395.426946 -242.17376)
		(end 394.965936 -242.63477)
		(width 0.0889)
		(layer "In13.Cu")
		(net "M_H_CPU0_SA_DQ<28>")
	)
	(arc
		(start 389.033512 -243.191538)
		(mid 388.850004 -243.237032)
		(end 388.667752 -243.186712)
		(width 0.0889)
		(layer "In13.Cu")
		(net "M_H_CPU0_SA_DQ<28>")
	)
	(arc
		(start 390.54786 -243.186712)
		(mid 390.264904 -243.110535)
		(end 389.981948 -243.186712)
		(width 0.0889)
		(layer "In13.Cu")
		(net "M_H_CPU0_SA_DQ<28>")
	)
	(arc
		(start 384.333496 -243.191538)
		(mid 384.180626 -243.236179)
		(end 384.023108 -243.212874)
		(width 0.0889)
		(layer "In13.Cu")
		(net "M_H_CPU0_SA_DQ<28>")
	)
	(arc
		(start 388.093458 -243.191538)
		(mid 387.90995 -243.237032)
		(end 387.727698 -243.186712)
		(width 0.0889)
		(layer "In13.Cu")
		(net "M_H_CPU0_SA_DQ<28>")
	)
	(arc
		(start 386.787898 -243.186712)
		(mid 386.504942 -243.110535)
		(end 386.221986 -243.186712)
		(width 0.0889)
		(layer "In13.Cu")
		(net "M_H_CPU0_SA_DQ<28>")
	)
	(arc
		(start 388.667752 -243.186712)
		(mid 388.384796 -243.110535)
		(end 388.10184 -243.186712)
		(width 0.0889)
		(layer "In13.Cu")
		(net "M_H_CPU0_SA_DQ<28>")
	)
	(arc
		(start 389.981948 -243.186712)
		(mid 389.799697 -243.237062)
		(end 389.616188 -243.191538)
		(width 0.0889)
		(layer "In13.Cu")
		(net "M_H_CPU0_SA_DQ<28>")
	)
	(arc
		(start 385.281932 -243.186712)
		(mid 385.099681 -243.237062)
		(end 384.916172 -243.191538)
		(width 0.0889)
		(layer "In13.Cu")
		(net "M_H_CPU0_SA_DQ<28>")
	)
	(arc
		(start 385.847844 -243.186712)
		(mid 385.564888 -243.110535)
		(end 385.281932 -243.186712)
		(width 0.0889)
		(layer "In13.Cu")
		(net "M_H_CPU0_SA_DQ<28>")
	)
	(arc
		(start 389.607806 -243.186712)
		(mid 389.32485 -243.110535)
		(end 389.041894 -243.186712)
		(width 0.0889)
		(layer "In13.Cu")
		(net "M_H_CPU0_SA_DQ<28>")
	)
	(arc
		(start 386.221986 -243.186712)
		(mid 386.039735 -243.237062)
		(end 385.856226 -243.191538)
		(width 0.0889)
		(layer "In13.Cu")
		(net "M_H_CPU0_SA_DQ<28>")
	)
	(arc
		(start 391.48766 -243.186712)
		(mid 391.204704 -243.110535)
		(end 390.921748 -243.186712)
		(width 0.0889)
		(layer "In13.Cu")
		(net "M_H_CPU0_SA_DQ<28>")
	)
	(arc
		(start 393.084812 -243.110258)
		(mid 392.929451 -243.132083)
		(end 392.786108 -243.195856)
		(width 0.0889)
		(layer "In13.Cu")
		(net "M_H_CPU0_SA_DQ<28>")
	)
	(arc
		(start 387.161786 -243.186712)
		(mid 386.974842 -243.236967)
		(end 386.787898 -243.186712)
		(width 0.0889)
		(layer "In13.Cu")
		(net "M_H_CPU0_SA_DQ<28>")
	)
	(arc
		(start 390.921748 -243.186712)
		(mid 390.734804 -243.236967)
		(end 390.54786 -243.186712)
		(width 0.0889)
		(layer "In13.Cu")
		(net "M_H_CPU0_SA_DQ<28>")
	)
	(arc
		(start 392.418062 -243.180616)
		(mid 392.139376 -243.110396)
		(end 391.86231 -243.186712)
		(width 0.0889)
		(layer "In13.Cu")
		(net "M_H_CPU0_SA_DQ<28>")
	)
	(arc
		(start 391.86231 -243.186712)
		(mid 391.679805 -243.237189)
		(end 391.496042 -243.191538)
		(width 0.0889)
		(layer "In13.Cu")
		(net "M_H_CPU0_SA_DQ<28>")
	)
	(arc
		(start 384.90779 -243.186712)
		(mid 384.624834 -243.110535)
		(end 384.341878 -243.186712)
		(width 0.0889)
		(layer "In13.Cu")
		(net "M_H_CPU0_SA_DQ<28>")
	)
	(arc
		(start 387.727698 -243.186712)
		(mid 387.444742 -243.110535)
		(end 387.161786 -243.186712)
		(width 0.0889)
		(layer "In13.Cu")
		(net "M_H_CPU0_SA_DQ<28>")
	)
	(arc
		(start 392.786108 -243.195856)
		(mid 392.606126 -243.236956)
		(end 392.428476 -243.186712)
		(width 0.0889)
		(layer "In13.Cu")
		(net "M_H_CPU0_SA_DQ<28>")
	)
	(segment
		(start 381.807974 -241.510058)
		(end 382.274826 -241.24412)
		(width 0.10668)
		(layer "F.Cu")
		(net "M_H_CPU0_SA_DQ<27>")
	)
	(segment
		(start 392.788648 -240.91392)
		(end 392.810238 -240.93551)
		(width 0.0889)
		(layer "In13.Cu")
		(net "M_H_CPU0_SA_DQ<27>")
	)
	(segment
		(start 412.347156 -228.360224)
		(end 412.622746 -228.635814)
		(width 0.14478)
		(layer "In13.Cu")
		(net "M_H_CPU0_SA_DQ<27>")
	)
	(segment
		(start 392.810238 -240.93551)
		(end 392.925554 -240.983262)
		(width 0.0889)
		(layer "In13.Cu")
		(net "M_H_CPU0_SA_DQ<27>")
	)
	(segment
		(start 403.3774 -235.65739)
		(end 403.562058 -235.472732)
		(width 0.14478)
		(layer "In13.Cu")
		(net "M_H_CPU0_SA_DQ<27>")
	)
	(segment
		(start 402.001482 -236.622336)
		(end 402.18614 -236.437678)
		(width 0.14478)
		(layer "In13.Cu")
		(net "M_H_CPU0_SA_DQ<27>")
	)
	(segment
		(start 404.937976 -234.096814)
		(end 405.122634 -233.912156)
		(width 0.14478)
		(layer "In13.Cu")
		(net "M_H_CPU0_SA_DQ<27>")
	)
	(segment
		(start 419.542468 -228.350318)
		(end 419.912038 -227.980748)
		(width 0.14478)
		(layer "In13.Cu")
		(net "M_H_CPU0_SA_DQ<27>")
	)
	(segment
		(start 417.25342 -227.795836)
		(end 417.53917 -227.510086)
		(width 0.14478)
		(layer "In13.Cu")
		(net "M_H_CPU0_SA_DQ<27>")
	)
	(segment
		(start 402.78177 -236.25302)
		(end 402.78177 -235.842048)
		(width 0.14478)
		(layer "In13.Cu")
		(net "M_H_CPU0_SA_DQ<27>")
	)
	(segment
		(start 385.847844 -240.92154)
		(end 385.856226 -240.916714)
		(width 0.0889)
		(layer "In13.Cu")
		(net "M_H_CPU0_SA_DQ<27>")
	)
	(segment
		(start 394.168376 -240.67135)
		(end 394.5636 -240.67135)
		(width 0.0889)
		(layer "In13.Cu")
		(net "M_H_CPU0_SA_DQ<27>")
	)
	(segment
		(start 412.622746 -228.635814)
		(end 412.898336 -228.635814)
		(width 0.14478)
		(layer "In13.Cu")
		(net "M_H_CPU0_SA_DQ<27>")
	)
	(segment
		(start 410.263594 -228.360224)
		(end 411.244796 -228.360224)
		(width 0.14478)
		(layer "In13.Cu")
		(net "M_H_CPU0_SA_DQ<27>")
	)
	(segment
		(start 392.413998 -240.930176)
		(end 392.42873 -240.92154)
		(width 0.0889)
		(layer "In13.Cu")
		(net "M_H_CPU0_SA_DQ<27>")
	)
	(segment
		(start 404.342346 -234.692444)
		(end 404.342346 -234.281472)
		(width 0.14478)
		(layer "In13.Cu")
		(net "M_H_CPU0_SA_DQ<27>")
	)
	(segment
		(start 411.244796 -228.360224)
		(end 411.520386 -228.635814)
		(width 0.14478)
		(layer "In13.Cu")
		(net "M_H_CPU0_SA_DQ<27>")
	)
	(segment
		(start 401.221194 -237.813596)
		(end 401.221194 -237.402624)
		(width 0.14478)
		(layer "In13.Cu")
		(net "M_H_CPU0_SA_DQ<27>")
	)
	(segment
		(start 402.001482 -237.033308)
		(end 402.001482 -236.622336)
		(width 0.14478)
		(layer "In13.Cu")
		(net "M_H_CPU0_SA_DQ<27>")
	)
	(segment
		(start 413.173926 -228.360224)
		(end 414.005776 -228.360224)
		(width 0.14478)
		(layer "In13.Cu")
		(net "M_H_CPU0_SA_DQ<27>")
	)
	(segment
		(start 395.87805 -239.71123)
		(end 398.912588 -239.71123)
		(width 0.14478)
		(layer "In13.Cu")
		(net "M_H_CPU0_SA_DQ<27>")
	)
	(segment
		(start 405.122634 -233.501184)
		(end 410.263594 -228.360224)
		(width 0.14478)
		(layer "In13.Cu")
		(net "M_H_CPU0_SA_DQ<27>")
	)
	(segment
		(start 414.005776 -228.360224)
		(end 414.855914 -227.510086)
		(width 0.14478)
		(layer "In13.Cu")
		(net "M_H_CPU0_SA_DQ<27>")
	)
	(segment
		(start 394.5636 -240.67135)
		(end 395.52372 -239.71123)
		(width 0.0889)
		(layer "In13.Cu")
		(net "M_H_CPU0_SA_DQ<27>")
	)
	(segment
		(start 401.036536 -237.998254)
		(end 401.221194 -237.813596)
		(width 0.14478)
		(layer "In13.Cu")
		(net "M_H_CPU0_SA_DQ<27>")
	)
	(segment
		(start 388.093458 -240.916714)
		(end 388.10184 -240.92154)
		(width 0.0889)
		(layer "In13.Cu")
		(net "M_H_CPU0_SA_DQ<27>")
	)
	(segment
		(start 404.157688 -234.877102)
		(end 404.342346 -234.692444)
		(width 0.14478)
		(layer "In13.Cu")
		(net "M_H_CPU0_SA_DQ<27>")
	)
	(segment
		(start 399.660618 -238.9632)
		(end 399.845276 -238.778542)
		(width 0.14478)
		(layer "In13.Cu")
		(net "M_H_CPU0_SA_DQ<27>")
	)
	(segment
		(start 393.068556 -241.01171)
		(end 393.828016 -241.01171)
		(width 0.0889)
		(layer "In13.Cu")
		(net "M_H_CPU0_SA_DQ<27>")
	)
	(segment
		(start 414.855914 -227.510086)
		(end 415.59988 -227.510086)
		(width 0.14478)
		(layer "In13.Cu")
		(net "M_H_CPU0_SA_DQ<27>")
	)
	(segment
		(start 391.48766 -240.92154)
		(end 391.496042 -240.916714)
		(width 0.0889)
		(layer "In13.Cu")
		(net "M_H_CPU0_SA_DQ<27>")
	)
	(segment
		(start 402.597112 -236.437678)
		(end 402.78177 -236.25302)
		(width 0.14478)
		(layer "In13.Cu")
		(net "M_H_CPU0_SA_DQ<27>")
	)
	(segment
		(start 415.59988 -227.510086)
		(end 415.88563 -227.795836)
		(width 0.14478)
		(layer "In13.Cu")
		(net "M_H_CPU0_SA_DQ<27>")
	)
	(segment
		(start 417.53917 -227.510086)
		(end 418.13988 -227.510086)
		(width 0.14478)
		(layer "In13.Cu")
		(net "M_H_CPU0_SA_DQ<27>")
	)
	(segment
		(start 392.925554 -240.983262)
		(end 393.068556 -241.01171)
		(width 0.0889)
		(layer "In13.Cu")
		(net "M_H_CPU0_SA_DQ<27>")
	)
	(segment
		(start 401.405852 -237.217966)
		(end 401.816824 -237.217966)
		(width 0.14478)
		(layer "In13.Cu")
		(net "M_H_CPU0_SA_DQ<27>")
	)
	(segment
		(start 400.440906 -238.593884)
		(end 400.440906 -238.182912)
		(width 0.14478)
		(layer "In13.Cu")
		(net "M_H_CPU0_SA_DQ<27>")
	)
	(segment
		(start 399.064988 -239.55883)
		(end 399.47596 -239.55883)
		(width 0.14478)
		(layer "In13.Cu")
		(net "M_H_CPU0_SA_DQ<27>")
	)
	(segment
		(start 416.98799 -227.795836)
		(end 417.25342 -227.795836)
		(width 0.14478)
		(layer "In13.Cu")
		(net "M_H_CPU0_SA_DQ<27>")
	)
	(segment
		(start 416.43681 -227.510086)
		(end 416.70224 -227.510086)
		(width 0.14478)
		(layer "In13.Cu")
		(net "M_H_CPU0_SA_DQ<27>")
	)
	(segment
		(start 389.033512 -240.916714)
		(end 389.041894 -240.92154)
		(width 0.0889)
		(layer "In13.Cu")
		(net "M_H_CPU0_SA_DQ<27>")
	)
	(segment
		(start 419.912038 -227.980748)
		(end 419.912038 -227.935028)
		(width 0.14478)
		(layer "In13.Cu")
		(net "M_H_CPU0_SA_DQ<27>")
	)
	(segment
		(start 402.18614 -236.437678)
		(end 402.597112 -236.437678)
		(width 0.14478)
		(layer "In13.Cu")
		(net "M_H_CPU0_SA_DQ<27>")
	)
	(segment
		(start 403.746716 -234.877102)
		(end 404.157688 -234.877102)
		(width 0.14478)
		(layer "In13.Cu")
		(net "M_H_CPU0_SA_DQ<27>")
	)
	(segment
		(start 399.47596 -239.55883)
		(end 399.660618 -239.374172)
		(width 0.14478)
		(layer "In13.Cu")
		(net "M_H_CPU0_SA_DQ<27>")
	)
	(segment
		(start 399.845276 -238.778542)
		(end 400.256248 -238.778542)
		(width 0.14478)
		(layer "In13.Cu")
		(net "M_H_CPU0_SA_DQ<27>")
	)
	(segment
		(start 404.527004 -234.096814)
		(end 404.937976 -234.096814)
		(width 0.14478)
		(layer "In13.Cu")
		(net "M_H_CPU0_SA_DQ<27>")
	)
	(segment
		(start 398.912588 -239.71123)
		(end 399.064988 -239.55883)
		(width 0.14478)
		(layer "In13.Cu")
		(net "M_H_CPU0_SA_DQ<27>")
	)
	(segment
		(start 393.828016 -241.01171)
		(end 394.168376 -240.67135)
		(width 0.0889)
		(layer "In13.Cu")
		(net "M_H_CPU0_SA_DQ<27>")
	)
	(segment
		(start 402.78177 -235.842048)
		(end 402.966428 -235.65739)
		(width 0.14478)
		(layer "In13.Cu")
		(net "M_H_CPU0_SA_DQ<27>")
	)
	(segment
		(start 399.660618 -239.374172)
		(end 399.660618 -238.9632)
		(width 0.14478)
		(layer "In13.Cu")
		(net "M_H_CPU0_SA_DQ<27>")
	)
	(segment
		(start 389.607806 -240.92154)
		(end 389.616188 -240.916714)
		(width 0.0889)
		(layer "In13.Cu")
		(net "M_H_CPU0_SA_DQ<27>")
	)
	(segment
		(start 400.440906 -238.182912)
		(end 400.625564 -237.998254)
		(width 0.14478)
		(layer "In13.Cu")
		(net "M_H_CPU0_SA_DQ<27>")
	)
	(segment
		(start 416.70224 -227.510086)
		(end 416.98799 -227.795836)
		(width 0.14478)
		(layer "In13.Cu")
		(net "M_H_CPU0_SA_DQ<27>")
	)
	(segment
		(start 412.071566 -228.360224)
		(end 412.347156 -228.360224)
		(width 0.14478)
		(layer "In13.Cu")
		(net "M_H_CPU0_SA_DQ<27>")
	)
	(segment
		(start 411.520386 -228.635814)
		(end 411.795976 -228.635814)
		(width 0.14478)
		(layer "In13.Cu")
		(net "M_H_CPU0_SA_DQ<27>")
	)
	(segment
		(start 395.52372 -239.71123)
		(end 395.87805 -239.71123)
		(width 0.0889)
		(layer "In13.Cu")
		(net "M_H_CPU0_SA_DQ<27>")
	)
	(segment
		(start 416.15106 -227.795836)
		(end 416.43681 -227.510086)
		(width 0.14478)
		(layer "In13.Cu")
		(net "M_H_CPU0_SA_DQ<27>")
	)
	(segment
		(start 402.966428 -235.65739)
		(end 403.3774 -235.65739)
		(width 0.14478)
		(layer "In13.Cu")
		(net "M_H_CPU0_SA_DQ<27>")
	)
	(segment
		(start 382.274826 -241.24412)
		(end 382.42875 -240.97869)
		(width 0.0889)
		(layer "In13.Cu")
		(net "M_H_CPU0_SA_DQ<27>")
	)
	(segment
		(start 418.980112 -228.350318)
		(end 419.542468 -228.350318)
		(width 0.14478)
		(layer "In13.Cu")
		(net "M_H_CPU0_SA_DQ<27>")
	)
	(segment
		(start 403.562058 -235.06176)
		(end 403.746716 -234.877102)
		(width 0.14478)
		(layer "In13.Cu")
		(net "M_H_CPU0_SA_DQ<27>")
	)
	(segment
		(start 382.42875 -240.97869)
		(end 382.524762 -240.95329)
		(width 0.0889)
		(layer "In13.Cu")
		(net "M_H_CPU0_SA_DQ<27>")
	)
	(segment
		(start 411.795976 -228.635814)
		(end 412.071566 -228.360224)
		(width 0.14478)
		(layer "In13.Cu")
		(net "M_H_CPU0_SA_DQ<27>")
	)
	(segment
		(start 384.333496 -240.916714)
		(end 384.341878 -240.92154)
		(width 0.0889)
		(layer "In13.Cu")
		(net "M_H_CPU0_SA_DQ<27>")
	)
	(segment
		(start 418.13988 -227.510086)
		(end 418.980112 -228.350318)
		(width 0.14478)
		(layer "In13.Cu")
		(net "M_H_CPU0_SA_DQ<27>")
	)
	(segment
		(start 401.221194 -237.402624)
		(end 401.405852 -237.217966)
		(width 0.14478)
		(layer "In13.Cu")
		(net "M_H_CPU0_SA_DQ<27>")
	)
	(segment
		(start 415.88563 -227.795836)
		(end 416.15106 -227.795836)
		(width 0.14478)
		(layer "In13.Cu")
		(net "M_H_CPU0_SA_DQ<27>")
	)
	(segment
		(start 400.625564 -237.998254)
		(end 401.036536 -237.998254)
		(width 0.14478)
		(layer "In13.Cu")
		(net "M_H_CPU0_SA_DQ<27>")
	)
	(segment
		(start 412.898336 -228.635814)
		(end 413.173926 -228.360224)
		(width 0.14478)
		(layer "In13.Cu")
		(net "M_H_CPU0_SA_DQ<27>")
	)
	(segment
		(start 384.90779 -240.92154)
		(end 384.916172 -240.916714)
		(width 0.0889)
		(layer "In13.Cu")
		(net "M_H_CPU0_SA_DQ<27>")
	)
	(segment
		(start 400.256248 -238.778542)
		(end 400.440906 -238.593884)
		(width 0.14478)
		(layer "In13.Cu")
		(net "M_H_CPU0_SA_DQ<27>")
	)
	(segment
		(start 403.562058 -235.472732)
		(end 403.562058 -235.06176)
		(width 0.14478)
		(layer "In13.Cu")
		(net "M_H_CPU0_SA_DQ<27>")
	)
	(segment
		(start 401.816824 -237.217966)
		(end 402.001482 -237.033308)
		(width 0.14478)
		(layer "In13.Cu")
		(net "M_H_CPU0_SA_DQ<27>")
	)
	(segment
		(start 404.342346 -234.281472)
		(end 404.527004 -234.096814)
		(width 0.14478)
		(layer "In13.Cu")
		(net "M_H_CPU0_SA_DQ<27>")
	)
	(segment
		(start 383.393442 -240.916714)
		(end 383.401824 -240.92154)
		(width 0.0889)
		(layer "In13.Cu")
		(net "M_H_CPU0_SA_DQ<27>")
	)
	(segment
		(start 405.122634 -233.912156)
		(end 405.122634 -233.501184)
		(width 0.14478)
		(layer "In13.Cu")
		(net "M_H_CPU0_SA_DQ<27>")
	)
	(arc
		(start 383.401824 -240.92154)
		(mid 383.68478 -240.997717)
		(end 383.967736 -240.92154)
		(width 0.0889)
		(layer "In13.Cu")
		(net "M_H_CPU0_SA_DQ<27>")
	)
	(arc
		(start 386.221986 -240.92154)
		(mid 386.504942 -240.997717)
		(end 386.787898 -240.92154)
		(width 0.0889)
		(layer "In13.Cu")
		(net "M_H_CPU0_SA_DQ<27>")
	)
	(arc
		(start 390.54786 -240.92154)
		(mid 390.734804 -240.871285)
		(end 390.921748 -240.92154)
		(width 0.0889)
		(layer "In13.Cu")
		(net "M_H_CPU0_SA_DQ<27>")
	)
	(arc
		(start 383.027682 -240.92154)
		(mid 383.209933 -240.87119)
		(end 383.393442 -240.916714)
		(width 0.0889)
		(layer "In13.Cu")
		(net "M_H_CPU0_SA_DQ<27>")
	)
	(arc
		(start 384.341878 -240.92154)
		(mid 384.624834 -240.997717)
		(end 384.90779 -240.92154)
		(width 0.0889)
		(layer "In13.Cu")
		(net "M_H_CPU0_SA_DQ<27>")
	)
	(arc
		(start 382.524762 -240.95329)
		(mid 382.77997 -240.996767)
		(end 383.027682 -240.92154)
		(width 0.0889)
		(layer "In13.Cu")
		(net "M_H_CPU0_SA_DQ<27>")
	)
	(arc
		(start 385.281932 -240.92154)
		(mid 385.564888 -240.997717)
		(end 385.847844 -240.92154)
		(width 0.0889)
		(layer "In13.Cu")
		(net "M_H_CPU0_SA_DQ<27>")
	)
	(arc
		(start 389.981948 -240.92154)
		(mid 390.264904 -240.997717)
		(end 390.54786 -240.92154)
		(width 0.0889)
		(layer "In13.Cu")
		(net "M_H_CPU0_SA_DQ<27>")
	)
	(arc
		(start 390.921748 -240.92154)
		(mid 391.204704 -240.997717)
		(end 391.48766 -240.92154)
		(width 0.0889)
		(layer "In13.Cu")
		(net "M_H_CPU0_SA_DQ<27>")
	)
	(arc
		(start 388.667752 -240.92154)
		(mid 388.850003 -240.87119)
		(end 389.033512 -240.916714)
		(width 0.0889)
		(layer "In13.Cu")
		(net "M_H_CPU0_SA_DQ<27>")
	)
	(arc
		(start 385.856226 -240.916714)
		(mid 386.039734 -240.87122)
		(end 386.221986 -240.92154)
		(width 0.0889)
		(layer "In13.Cu")
		(net "M_H_CPU0_SA_DQ<27>")
	)
	(arc
		(start 389.041894 -240.92154)
		(mid 389.32485 -240.997717)
		(end 389.607806 -240.92154)
		(width 0.0889)
		(layer "In13.Cu")
		(net "M_H_CPU0_SA_DQ<27>")
	)
	(arc
		(start 389.616188 -240.916714)
		(mid 389.799696 -240.87122)
		(end 389.981948 -240.92154)
		(width 0.0889)
		(layer "In13.Cu")
		(net "M_H_CPU0_SA_DQ<27>")
	)
	(arc
		(start 391.86231 -240.92154)
		(mid 392.137016 -240.997904)
		(end 392.413998 -240.930176)
		(width 0.0889)
		(layer "In13.Cu")
		(net "M_H_CPU0_SA_DQ<27>")
	)
	(arc
		(start 383.967736 -240.92154)
		(mid 384.149987 -240.87119)
		(end 384.333496 -240.916714)
		(width 0.0889)
		(layer "In13.Cu")
		(net "M_H_CPU0_SA_DQ<27>")
	)
	(arc
		(start 392.42873 -240.92154)
		(mid 392.607717 -240.87137)
		(end 392.788648 -240.91392)
		(width 0.0889)
		(layer "In13.Cu")
		(net "M_H_CPU0_SA_DQ<27>")
	)
	(arc
		(start 387.161786 -240.92154)
		(mid 387.444742 -240.997717)
		(end 387.727698 -240.92154)
		(width 0.0889)
		(layer "In13.Cu")
		(net "M_H_CPU0_SA_DQ<27>")
	)
	(arc
		(start 388.10184 -240.92154)
		(mid 388.384796 -240.997717)
		(end 388.667752 -240.92154)
		(width 0.0889)
		(layer "In13.Cu")
		(net "M_H_CPU0_SA_DQ<27>")
	)
	(arc
		(start 384.916172 -240.916714)
		(mid 385.09968 -240.87122)
		(end 385.281932 -240.92154)
		(width 0.0889)
		(layer "In13.Cu")
		(net "M_H_CPU0_SA_DQ<27>")
	)
	(arc
		(start 386.787898 -240.92154)
		(mid 386.974842 -240.871285)
		(end 387.161786 -240.92154)
		(width 0.0889)
		(layer "In13.Cu")
		(net "M_H_CPU0_SA_DQ<27>")
	)
	(arc
		(start 387.727698 -240.92154)
		(mid 387.909949 -240.87119)
		(end 388.093458 -240.916714)
		(width 0.0889)
		(layer "In13.Cu")
		(net "M_H_CPU0_SA_DQ<27>")
	)
	(arc
		(start 391.496042 -240.916714)
		(mid 391.679804 -240.871098)
		(end 391.86231 -240.92154)
		(width 0.0889)
		(layer "In13.Cu")
		(net "M_H_CPU0_SA_DQ<27>")
	)
	(segment
		(start 383.217928 -240.700052)
		(end 383.68478 -240.434114)
		(width 0.10668)
		(layer "F.Cu")
		(net "M_H_CPU0_SA_DQ<26>")
	)
	(segment
		(start 390.451848 -240.111534)
		(end 390.443466 -240.106708)
		(width 0.0889)
		(layer "In13.Cu")
		(net "M_H_CPU0_SA_DQ<26>")
	)
	(segment
		(start 409.899612 -227.437696)
		(end 409.714446 -227.622862)
		(width 0.14478)
		(layer "In13.Cu")
		(net "M_H_CPU0_SA_DQ<26>")
	)
	(segment
		(start 394.498576 -239.25149)
		(end 393.577572 -240.172494)
		(width 0.0889)
		(layer "In13.Cu")
		(net "M_H_CPU0_SA_DQ<26>")
	)
	(segment
		(start 407.560272 -229.777036)
		(end 398.535398 -238.80191)
		(width 0.14478)
		(layer "In13.Cu")
		(net "M_H_CPU0_SA_DQ<26>")
	)
	(segment
		(start 419.491668 -226.660202)
		(end 418.732462 -226.660202)
		(width 0.14478)
		(layer "In13.Cu")
		(net "M_H_CPU0_SA_DQ<26>")
	)
	(segment
		(start 409.856686 -226.61499)
		(end 409.67152 -226.800156)
		(width 0.14478)
		(layer "In13.Cu")
		(net "M_H_CPU0_SA_DQ<26>")
	)
	(segment
		(start 412.764224 -226.660202)
		(end 412.52394 -226.660202)
		(width 0.14478)
		(layer "In13.Cu")
		(net "M_H_CPU0_SA_DQ<26>")
	)
	(segment
		(start 408.934666 -228.402642)
		(end 408.729942 -228.402642)
		(width 0.14478)
		(layer "In13.Cu")
		(net "M_H_CPU0_SA_DQ<26>")
	)
	(segment
		(start 411.972506 -226.349052)
		(end 411.661356 -226.660202)
		(width 0.14478)
		(layer "In13.Cu")
		(net "M_H_CPU0_SA_DQ<26>")
	)
	(segment
		(start 413.315658 -226.349052)
		(end 413.075374 -226.349052)
		(width 0.14478)
		(layer "In13.Cu")
		(net "M_H_CPU0_SA_DQ<26>")
	)
	(segment
		(start 398.535398 -238.80191)
		(end 395.885162 -238.80191)
		(width 0.14478)
		(layer "In13.Cu")
		(net "M_H_CPU0_SA_DQ<26>")
	)
	(segment
		(start 419.912038 -226.235006)
		(end 419.912038 -226.239832)
		(width 0.14478)
		(layer "In13.Cu")
		(net "M_H_CPU0_SA_DQ<26>")
	)
	(segment
		(start 407.33218 -229.34422)
		(end 407.560272 -229.572312)
		(width 0.14478)
		(layer "In13.Cu")
		(net "M_H_CPU0_SA_DQ<26>")
	)
	(segment
		(start 391.026142 -240.106708)
		(end 391.01776 -240.111534)
		(width 0.0889)
		(layer "In13.Cu")
		(net "M_H_CPU0_SA_DQ<26>")
	)
	(segment
		(start 408.89174 -227.78466)
		(end 409.119832 -228.012752)
		(width 0.14478)
		(layer "In13.Cu")
		(net "M_H_CPU0_SA_DQ<26>")
	)
	(segment
		(start 392.898122 -240.111534)
		(end 392.887708 -240.11763)
		(width 0.0889)
		(layer "In13.Cu")
		(net "M_H_CPU0_SA_DQ<26>")
	)
	(segment
		(start 411.661356 -226.660202)
		(end 410.677106 -226.660202)
		(width 0.14478)
		(layer "In13.Cu")
		(net "M_H_CPU0_SA_DQ<26>")
	)
	(segment
		(start 408.729942 -228.402642)
		(end 408.50185 -228.17455)
		(width 0.14478)
		(layer "In13.Cu")
		(net "M_H_CPU0_SA_DQ<26>")
	)
	(segment
		(start 386.691886 -240.111534)
		(end 386.683504 -240.106708)
		(width 0.0889)
		(layer "In13.Cu")
		(net "M_H_CPU0_SA_DQ<26>")
	)
	(segment
		(start 395.885162 -238.80191)
		(end 395.555216 -238.80191)
		(width 0.0889)
		(layer "In13.Cu")
		(net "M_H_CPU0_SA_DQ<26>")
	)
	(segment
		(start 407.560272 -229.572312)
		(end 407.560272 -229.777036)
		(width 0.14478)
		(layer "In13.Cu")
		(net "M_H_CPU0_SA_DQ<26>")
	)
	(segment
		(start 395.555216 -238.80191)
		(end 395.105636 -239.25149)
		(width 0.0889)
		(layer "In13.Cu")
		(net "M_H_CPU0_SA_DQ<26>")
	)
	(segment
		(start 408.11196 -228.359716)
		(end 408.11196 -228.56444)
		(width 0.14478)
		(layer "In13.Cu")
		(net "M_H_CPU0_SA_DQ<26>")
	)
	(segment
		(start 393.577572 -240.172494)
		(end 393.333224 -240.172494)
		(width 0.0889)
		(layer "In13.Cu")
		(net "M_H_CPU0_SA_DQ<26>")
	)
	(segment
		(start 408.50185 -228.17455)
		(end 408.297126 -228.17455)
		(width 0.14478)
		(layer "In13.Cu")
		(net "M_H_CPU0_SA_DQ<26>")
	)
	(segment
		(start 418.732462 -226.660202)
		(end 417.882324 -225.810064)
		(width 0.14478)
		(layer "In13.Cu")
		(net "M_H_CPU0_SA_DQ<26>")
	)
	(segment
		(start 408.297126 -228.17455)
		(end 408.11196 -228.359716)
		(width 0.14478)
		(layer "In13.Cu")
		(net "M_H_CPU0_SA_DQ<26>")
	)
	(segment
		(start 408.340052 -228.792532)
		(end 408.340052 -228.997256)
		(width 0.14478)
		(layer "In13.Cu")
		(net "M_H_CPU0_SA_DQ<26>")
	)
	(segment
		(start 391.402316 -240.11763)
		(end 391.391902 -240.111534)
		(width 0.0889)
		(layer "In13.Cu")
		(net "M_H_CPU0_SA_DQ<26>")
	)
	(segment
		(start 393.333224 -240.172494)
		(end 393.272264 -240.111534)
		(width 0.0889)
		(layer "In13.Cu")
		(net "M_H_CPU0_SA_DQ<26>")
	)
	(segment
		(start 410.677106 -226.660202)
		(end 410.494226 -226.843082)
		(width 0.14478)
		(layer "In13.Cu")
		(net "M_H_CPU0_SA_DQ<26>")
	)
	(segment
		(start 392.9126 -240.103152)
		(end 392.898122 -240.111534)
		(width 0.0889)
		(layer "In13.Cu")
		(net "M_H_CPU0_SA_DQ<26>")
	)
	(segment
		(start 383.935224 -240.143284)
		(end 383.838958 -240.168684)
		(width 0.0889)
		(layer "In13.Cu")
		(net "M_H_CPU0_SA_DQ<26>")
	)
	(segment
		(start 409.119832 -228.012752)
		(end 409.119832 -228.217476)
		(width 0.14478)
		(layer "In13.Cu")
		(net "M_H_CPU0_SA_DQ<26>")
	)
	(segment
		(start 409.076906 -227.39477)
		(end 408.89174 -227.579936)
		(width 0.14478)
		(layer "In13.Cu")
		(net "M_H_CPU0_SA_DQ<26>")
	)
	(segment
		(start 413.075374 -226.349052)
		(end 412.764224 -226.660202)
		(width 0.14478)
		(layer "In13.Cu")
		(net "M_H_CPU0_SA_DQ<26>")
	)
	(segment
		(start 407.517346 -228.95433)
		(end 407.33218 -229.139496)
		(width 0.14478)
		(layer "In13.Cu")
		(net "M_H_CPU0_SA_DQ<26>")
	)
	(segment
		(start 408.89174 -227.579936)
		(end 408.89174 -227.78466)
		(width 0.14478)
		(layer "In13.Cu")
		(net "M_H_CPU0_SA_DQ<26>")
	)
	(segment
		(start 410.06141 -226.61499)
		(end 409.856686 -226.61499)
		(width 0.14478)
		(layer "In13.Cu")
		(net "M_H_CPU0_SA_DQ<26>")
	)
	(segment
		(start 410.289502 -226.843082)
		(end 410.06141 -226.61499)
		(width 0.14478)
		(layer "In13.Cu")
		(net "M_H_CPU0_SA_DQ<26>")
	)
	(segment
		(start 387.26618 -240.106708)
		(end 387.257798 -240.111534)
		(width 0.0889)
		(layer "In13.Cu")
		(net "M_H_CPU0_SA_DQ<26>")
	)
	(segment
		(start 409.899612 -227.232972)
		(end 409.899612 -227.437696)
		(width 0.14478)
		(layer "In13.Cu")
		(net "M_H_CPU0_SA_DQ<26>")
	)
	(segment
		(start 407.950162 -229.182422)
		(end 407.72207 -228.95433)
		(width 0.14478)
		(layer "In13.Cu")
		(net "M_H_CPU0_SA_DQ<26>")
	)
	(segment
		(start 385.751832 -240.111534)
		(end 385.74345 -240.106708)
		(width 0.0889)
		(layer "In13.Cu")
		(net "M_H_CPU0_SA_DQ<26>")
	)
	(segment
		(start 409.119832 -228.217476)
		(end 408.934666 -228.402642)
		(width 0.14478)
		(layer "In13.Cu")
		(net "M_H_CPU0_SA_DQ<26>")
	)
	(segment
		(start 415.089594 -225.810064)
		(end 414.239456 -226.660202)
		(width 0.14478)
		(layer "In13.Cu")
		(net "M_H_CPU0_SA_DQ<26>")
	)
	(segment
		(start 407.33218 -229.139496)
		(end 407.33218 -229.34422)
		(width 0.14478)
		(layer "In13.Cu")
		(net "M_H_CPU0_SA_DQ<26>")
	)
	(segment
		(start 408.154886 -229.182422)
		(end 407.950162 -229.182422)
		(width 0.14478)
		(layer "In13.Cu")
		(net "M_H_CPU0_SA_DQ<26>")
	)
	(segment
		(start 407.72207 -228.95433)
		(end 407.517346 -228.95433)
		(width 0.14478)
		(layer "In13.Cu")
		(net "M_H_CPU0_SA_DQ<26>")
	)
	(segment
		(start 408.11196 -228.56444)
		(end 408.340052 -228.792532)
		(width 0.14478)
		(layer "In13.Cu")
		(net "M_H_CPU0_SA_DQ<26>")
	)
	(segment
		(start 395.105636 -239.25149)
		(end 394.498576 -239.25149)
		(width 0.0889)
		(layer "In13.Cu")
		(net "M_H_CPU0_SA_DQ<26>")
	)
	(segment
		(start 409.67152 -226.800156)
		(end 409.67152 -227.00488)
		(width 0.14478)
		(layer "In13.Cu")
		(net "M_H_CPU0_SA_DQ<26>")
	)
	(segment
		(start 409.67152 -227.00488)
		(end 409.899612 -227.232972)
		(width 0.14478)
		(layer "In13.Cu")
		(net "M_H_CPU0_SA_DQ<26>")
	)
	(segment
		(start 409.509722 -227.622862)
		(end 409.28163 -227.39477)
		(width 0.14478)
		(layer "In13.Cu")
		(net "M_H_CPU0_SA_DQ<26>")
	)
	(segment
		(start 408.340052 -228.997256)
		(end 408.154886 -229.182422)
		(width 0.14478)
		(layer "In13.Cu")
		(net "M_H_CPU0_SA_DQ<26>")
	)
	(segment
		(start 409.714446 -227.622862)
		(end 409.509722 -227.622862)
		(width 0.14478)
		(layer "In13.Cu")
		(net "M_H_CPU0_SA_DQ<26>")
	)
	(segment
		(start 412.52394 -226.660202)
		(end 412.21279 -226.349052)
		(width 0.14478)
		(layer "In13.Cu")
		(net "M_H_CPU0_SA_DQ<26>")
	)
	(segment
		(start 414.239456 -226.660202)
		(end 413.626808 -226.660202)
		(width 0.14478)
		(layer "In13.Cu")
		(net "M_H_CPU0_SA_DQ<26>")
	)
	(segment
		(start 388.206234 -240.106708)
		(end 388.197852 -240.111534)
		(width 0.0889)
		(layer "In13.Cu")
		(net "M_H_CPU0_SA_DQ<26>")
	)
	(segment
		(start 409.28163 -227.39477)
		(end 409.076906 -227.39477)
		(width 0.14478)
		(layer "In13.Cu")
		(net "M_H_CPU0_SA_DQ<26>")
	)
	(segment
		(start 383.838958 -240.168684)
		(end 383.68478 -240.434114)
		(width 0.0889)
		(layer "In13.Cu")
		(net "M_H_CPU0_SA_DQ<26>")
	)
	(segment
		(start 419.912038 -226.239832)
		(end 419.491668 -226.660202)
		(width 0.14478)
		(layer "In13.Cu")
		(net "M_H_CPU0_SA_DQ<26>")
	)
	(segment
		(start 413.626808 -226.660202)
		(end 413.315658 -226.349052)
		(width 0.14478)
		(layer "In13.Cu")
		(net "M_H_CPU0_SA_DQ<26>")
	)
	(segment
		(start 410.494226 -226.843082)
		(end 410.289502 -226.843082)
		(width 0.14478)
		(layer "In13.Cu")
		(net "M_H_CPU0_SA_DQ<26>")
	)
	(segment
		(start 417.882324 -225.810064)
		(end 415.089594 -225.810064)
		(width 0.14478)
		(layer "In13.Cu")
		(net "M_H_CPU0_SA_DQ<26>")
	)
	(segment
		(start 412.21279 -226.349052)
		(end 411.972506 -226.349052)
		(width 0.14478)
		(layer "In13.Cu")
		(net "M_H_CPU0_SA_DQ<26>")
	)
	(arc
		(start 388.571994 -240.111534)
		(mid 388.389743 -240.061184)
		(end 388.206234 -240.106708)
		(width 0.0889)
		(layer "In13.Cu")
		(net "M_H_CPU0_SA_DQ<26>")
	)
	(arc
		(start 386.317744 -240.111534)
		(mid 386.034788 -240.187711)
		(end 385.751832 -240.111534)
		(width 0.0889)
		(layer "In13.Cu")
		(net "M_H_CPU0_SA_DQ<26>")
	)
	(arc
		(start 392.332464 -240.111534)
		(mid 392.145266 -240.061152)
		(end 391.958068 -240.111534)
		(width 0.0889)
		(layer "In13.Cu")
		(net "M_H_CPU0_SA_DQ<26>")
	)
	(arc
		(start 387.257798 -240.111534)
		(mid 386.974842 -240.187711)
		(end 386.691886 -240.111534)
		(width 0.0889)
		(layer "In13.Cu")
		(net "M_H_CPU0_SA_DQ<26>")
	)
	(arc
		(start 392.887708 -240.11763)
		(mid 392.609276 -240.187728)
		(end 392.332464 -240.111534)
		(width 0.0889)
		(layer "In13.Cu")
		(net "M_H_CPU0_SA_DQ<26>")
	)
	(arc
		(start 390.077706 -240.111534)
		(mid 389.79475 -240.187711)
		(end 389.511794 -240.111534)
		(width 0.0889)
		(layer "In13.Cu")
		(net "M_H_CPU0_SA_DQ<26>")
	)
	(arc
		(start 390.443466 -240.106708)
		(mid 390.259958 -240.061214)
		(end 390.077706 -240.111534)
		(width 0.0889)
		(layer "In13.Cu")
		(net "M_H_CPU0_SA_DQ<26>")
	)
	(arc
		(start 385.37769 -240.111534)
		(mid 385.094734 -240.187711)
		(end 384.811778 -240.111534)
		(width 0.0889)
		(layer "In13.Cu")
		(net "M_H_CPU0_SA_DQ<26>")
	)
	(arc
		(start 389.137906 -240.111534)
		(mid 388.85495 -240.187711)
		(end 388.571994 -240.111534)
		(width 0.0889)
		(layer "In13.Cu")
		(net "M_H_CPU0_SA_DQ<26>")
	)
	(arc
		(start 386.683504 -240.106708)
		(mid 386.499996 -240.061214)
		(end 386.317744 -240.111534)
		(width 0.0889)
		(layer "In13.Cu")
		(net "M_H_CPU0_SA_DQ<26>")
	)
	(arc
		(start 393.272264 -240.111534)
		(mid 393.093509 -240.061125)
		(end 392.9126 -240.103152)
		(width 0.0889)
		(layer "In13.Cu")
		(net "M_H_CPU0_SA_DQ<26>")
	)
	(arc
		(start 388.197852 -240.111534)
		(mid 387.914896 -240.187711)
		(end 387.63194 -240.111534)
		(width 0.0889)
		(layer "In13.Cu")
		(net "M_H_CPU0_SA_DQ<26>")
	)
	(arc
		(start 385.74345 -240.106708)
		(mid 385.559942 -240.061214)
		(end 385.37769 -240.111534)
		(width 0.0889)
		(layer "In13.Cu")
		(net "M_H_CPU0_SA_DQ<26>")
	)
	(arc
		(start 391.391902 -240.111534)
		(mid 391.209651 -240.061184)
		(end 391.026142 -240.106708)
		(width 0.0889)
		(layer "In13.Cu")
		(net "M_H_CPU0_SA_DQ<26>")
	)
	(arc
		(start 387.63194 -240.111534)
		(mid 387.449689 -240.061184)
		(end 387.26618 -240.106708)
		(width 0.0889)
		(layer "In13.Cu")
		(net "M_H_CPU0_SA_DQ<26>")
	)
	(arc
		(start 389.511794 -240.111534)
		(mid 389.32485 -240.061279)
		(end 389.137906 -240.111534)
		(width 0.0889)
		(layer "In13.Cu")
		(net "M_H_CPU0_SA_DQ<26>")
	)
	(arc
		(start 391.01776 -240.111534)
		(mid 390.734804 -240.187711)
		(end 390.451848 -240.111534)
		(width 0.0889)
		(layer "In13.Cu")
		(net "M_H_CPU0_SA_DQ<26>")
	)
	(arc
		(start 384.43789 -240.111534)
		(mid 384.190294 -240.186712)
		(end 383.935224 -240.143284)
		(width 0.0889)
		(layer "In13.Cu")
		(net "M_H_CPU0_SA_DQ<26>")
	)
	(arc
		(start 384.811778 -240.111534)
		(mid 384.624834 -240.061279)
		(end 384.43789 -240.111534)
		(width 0.0889)
		(layer "In13.Cu")
		(net "M_H_CPU0_SA_DQ<26>")
	)
	(arc
		(start 391.958068 -240.111534)
		(mid 391.681001 -240.187805)
		(end 391.402316 -240.11763)
		(width 0.0889)
		(layer "In13.Cu")
		(net "M_H_CPU0_SA_DQ<26>")
	)
	(segment
		(start 382.277874 -240.700052)
		(end 382.744726 -240.434114)
		(width 0.10668)
		(layer "F.Cu")
		(net "M_H_CPU0_SA_DQ<25>")
	)
	(segment
		(start 414.72993 -227.060506)
		(end 418.229542 -227.060506)
		(width 0.14478)
		(layer "In13.Cu")
		(net "M_H_CPU0_SA_DQ<25>")
	)
	(segment
		(start 421.875204 -227.510086)
		(end 424.012106 -227.085144)
		(width 0.14478)
		(layer "In13.Cu")
		(net "M_H_CPU0_SA_DQ<25>")
	)
	(segment
		(start 395.608556 -239.25657)
		(end 395.843506 -239.25657)
		(width 0.0889)
		(layer "In13.Cu")
		(net "M_H_CPU0_SA_DQ<25>")
	)
	(segment
		(start 391.391902 -240.756694)
		(end 391.406634 -240.748058)
		(width 0.0889)
		(layer "In13.Cu")
		(net "M_H_CPU0_SA_DQ<25>")
	)
	(segment
		(start 382.744726 -240.434114)
		(end 382.590802 -240.699544)
		(width 0.0889)
		(layer "In13.Cu")
		(net "M_H_CPU0_SA_DQ<25>")
	)
	(segment
		(start 393.272264 -240.756694)
		(end 393.608052 -240.756694)
		(width 0.0889)
		(layer "In13.Cu")
		(net "M_H_CPU0_SA_DQ<25>")
	)
	(segment
		(start 386.683504 -240.76152)
		(end 386.691886 -240.756694)
		(width 0.0889)
		(layer "In13.Cu")
		(net "M_H_CPU0_SA_DQ<25>")
	)
	(segment
		(start 393.608052 -240.756694)
		(end 394.325856 -240.03889)
		(width 0.0889)
		(layer "In13.Cu")
		(net "M_H_CPU0_SA_DQ<25>")
	)
	(segment
		(start 410.070046 -227.910644)
		(end 412.67761 -227.910644)
		(width 0.14478)
		(layer "In13.Cu")
		(net "M_H_CPU0_SA_DQ<25>")
	)
	(segment
		(start 390.443466 -240.76152)
		(end 390.451848 -240.756694)
		(width 0.0889)
		(layer "In13.Cu")
		(net "M_H_CPU0_SA_DQ<25>")
	)
	(segment
		(start 391.01776 -240.756694)
		(end 391.026142 -240.76152)
		(width 0.0889)
		(layer "In13.Cu")
		(net "M_H_CPU0_SA_DQ<25>")
	)
	(segment
		(start 418.229542 -227.060506)
		(end 419.314884 -227.510086)
		(width 0.14478)
		(layer "In13.Cu")
		(net "M_H_CPU0_SA_DQ<25>")
	)
	(segment
		(start 395.344396 -239.52073)
		(end 395.608556 -239.25657)
		(width 0.0889)
		(layer "In13.Cu")
		(net "M_H_CPU0_SA_DQ<25>")
	)
	(segment
		(start 412.67761 -227.910644)
		(end 414.72993 -227.060506)
		(width 0.14478)
		(layer "In13.Cu")
		(net "M_H_CPU0_SA_DQ<25>")
	)
	(segment
		(start 419.314884 -227.510086)
		(end 421.875204 -227.510086)
		(width 0.14478)
		(layer "In13.Cu")
		(net "M_H_CPU0_SA_DQ<25>")
	)
	(segment
		(start 392.898122 -240.75644)
		(end 392.91641 -240.766854)
		(width 0.0889)
		(layer "In13.Cu")
		(net "M_H_CPU0_SA_DQ<25>")
	)
	(segment
		(start 394.536676 -239.52073)
		(end 395.344396 -239.52073)
		(width 0.0889)
		(layer "In13.Cu")
		(net "M_H_CPU0_SA_DQ<25>")
	)
	(segment
		(start 392.892534 -240.753138)
		(end 392.898122 -240.75644)
		(width 0.0889)
		(layer "In13.Cu")
		(net "M_H_CPU0_SA_DQ<25>")
	)
	(segment
		(start 394.325856 -240.03889)
		(end 394.325856 -239.73155)
		(width 0.0889)
		(layer "In13.Cu")
		(net "M_H_CPU0_SA_DQ<25>")
	)
	(segment
		(start 395.843506 -239.25657)
		(end 398.72412 -239.25657)
		(width 0.14478)
		(layer "In13.Cu")
		(net "M_H_CPU0_SA_DQ<25>")
	)
	(segment
		(start 385.74345 -240.76152)
		(end 385.751832 -240.756694)
		(width 0.0889)
		(layer "In13.Cu")
		(net "M_H_CPU0_SA_DQ<25>")
	)
	(segment
		(start 392.321034 -240.763552)
		(end 392.332718 -240.756694)
		(width 0.0889)
		(layer "In13.Cu")
		(net "M_H_CPU0_SA_DQ<25>")
	)
	(segment
		(start 383.497836 -240.756694)
		(end 383.506218 -240.76152)
		(width 0.0889)
		(layer "In13.Cu")
		(net "M_H_CPU0_SA_DQ<25>")
	)
	(segment
		(start 387.257798 -240.756694)
		(end 387.26618 -240.76152)
		(width 0.0889)
		(layer "In13.Cu")
		(net "M_H_CPU0_SA_DQ<25>")
	)
	(segment
		(start 398.72412 -239.25657)
		(end 410.070046 -227.910644)
		(width 0.14478)
		(layer "In13.Cu")
		(net "M_H_CPU0_SA_DQ<25>")
	)
	(segment
		(start 394.325856 -239.73155)
		(end 394.536676 -239.52073)
		(width 0.0889)
		(layer "In13.Cu")
		(net "M_H_CPU0_SA_DQ<25>")
	)
	(segment
		(start 382.590802 -240.699544)
		(end 382.613154 -240.782856)
		(width 0.0889)
		(layer "In13.Cu")
		(net "M_H_CPU0_SA_DQ<25>")
	)
	(segment
		(start 388.197852 -240.756694)
		(end 388.206234 -240.76152)
		(width 0.0889)
		(layer "In13.Cu")
		(net "M_H_CPU0_SA_DQ<25>")
	)
	(arc
		(start 383.506218 -240.76152)
		(mid 383.689726 -240.807014)
		(end 383.871978 -240.756694)
		(width 0.0889)
		(layer "In13.Cu")
		(net "M_H_CPU0_SA_DQ<25>")
	)
	(arc
		(start 390.451848 -240.756694)
		(mid 390.734804 -240.680517)
		(end 391.01776 -240.756694)
		(width 0.0889)
		(layer "In13.Cu")
		(net "M_H_CPU0_SA_DQ<25>")
	)
	(arc
		(start 384.811778 -240.756694)
		(mid 385.094734 -240.680517)
		(end 385.37769 -240.756694)
		(width 0.0889)
		(layer "In13.Cu")
		(net "M_H_CPU0_SA_DQ<25>")
	)
	(arc
		(start 384.43789 -240.756694)
		(mid 384.624834 -240.806949)
		(end 384.811778 -240.756694)
		(width 0.0889)
		(layer "In13.Cu")
		(net "M_H_CPU0_SA_DQ<25>")
	)
	(arc
		(start 389.137906 -240.756694)
		(mid 389.32485 -240.806949)
		(end 389.511794 -240.756694)
		(width 0.0889)
		(layer "In13.Cu")
		(net "M_H_CPU0_SA_DQ<25>")
	)
	(arc
		(start 388.571994 -240.756694)
		(mid 388.85495 -240.680517)
		(end 389.137906 -240.756694)
		(width 0.0889)
		(layer "In13.Cu")
		(net "M_H_CPU0_SA_DQ<25>")
	)
	(arc
		(start 382.613154 -240.782856)
		(mid 382.775486 -240.805674)
		(end 382.931924 -240.756694)
		(width 0.0889)
		(layer "In13.Cu")
		(net "M_H_CPU0_SA_DQ<25>")
	)
	(arc
		(start 392.332718 -240.756694)
		(mid 392.612146 -240.680528)
		(end 392.892534 -240.753138)
		(width 0.0889)
		(layer "In13.Cu")
		(net "M_H_CPU0_SA_DQ<25>")
	)
	(arc
		(start 390.077706 -240.756694)
		(mid 390.259957 -240.807044)
		(end 390.443466 -240.76152)
		(width 0.0889)
		(layer "In13.Cu")
		(net "M_H_CPU0_SA_DQ<25>")
	)
	(arc
		(start 386.317744 -240.756694)
		(mid 386.499995 -240.807044)
		(end 386.683504 -240.76152)
		(width 0.0889)
		(layer "In13.Cu")
		(net "M_H_CPU0_SA_DQ<25>")
	)
	(arc
		(start 382.931924 -240.756694)
		(mid 383.21488 -240.680517)
		(end 383.497836 -240.756694)
		(width 0.0889)
		(layer "In13.Cu")
		(net "M_H_CPU0_SA_DQ<25>")
	)
	(arc
		(start 385.751832 -240.756694)
		(mid 386.034788 -240.680517)
		(end 386.317744 -240.756694)
		(width 0.0889)
		(layer "In13.Cu")
		(net "M_H_CPU0_SA_DQ<25>")
	)
	(arc
		(start 383.871978 -240.756694)
		(mid 384.154934 -240.680517)
		(end 384.43789 -240.756694)
		(width 0.0889)
		(layer "In13.Cu")
		(net "M_H_CPU0_SA_DQ<25>")
	)
	(arc
		(start 387.26618 -240.76152)
		(mid 387.449688 -240.807014)
		(end 387.63194 -240.756694)
		(width 0.0889)
		(layer "In13.Cu")
		(net "M_H_CPU0_SA_DQ<25>")
	)
	(arc
		(start 387.63194 -240.756694)
		(mid 387.914896 -240.680517)
		(end 388.197852 -240.756694)
		(width 0.0889)
		(layer "In13.Cu")
		(net "M_H_CPU0_SA_DQ<25>")
	)
	(arc
		(start 388.206234 -240.76152)
		(mid 388.389742 -240.807014)
		(end 388.571994 -240.756694)
		(width 0.0889)
		(layer "In13.Cu")
		(net "M_H_CPU0_SA_DQ<25>")
	)
	(arc
		(start 385.37769 -240.756694)
		(mid 385.559941 -240.807044)
		(end 385.74345 -240.76152)
		(width 0.0889)
		(layer "In13.Cu")
		(net "M_H_CPU0_SA_DQ<25>")
	)
	(arc
		(start 391.958322 -240.756694)
		(mid 392.13878 -240.807138)
		(end 392.321034 -240.763552)
		(width 0.0889)
		(layer "In13.Cu")
		(net "M_H_CPU0_SA_DQ<25>")
	)
	(arc
		(start 391.406634 -240.748058)
		(mid 391.683617 -240.680254)
		(end 391.958322 -240.756694)
		(width 0.0889)
		(layer "In13.Cu")
		(net "M_H_CPU0_SA_DQ<25>")
	)
	(arc
		(start 391.026142 -240.76152)
		(mid 391.20965 -240.807014)
		(end 391.391902 -240.756694)
		(width 0.0889)
		(layer "In13.Cu")
		(net "M_H_CPU0_SA_DQ<25>")
	)
	(arc
		(start 386.691886 -240.756694)
		(mid 386.974842 -240.680517)
		(end 387.257798 -240.756694)
		(width 0.0889)
		(layer "In13.Cu")
		(net "M_H_CPU0_SA_DQ<25>")
	)
	(arc
		(start 389.511794 -240.756694)
		(mid 389.79475 -240.680517)
		(end 390.077706 -240.756694)
		(width 0.0889)
		(layer "In13.Cu")
		(net "M_H_CPU0_SA_DQ<25>")
	)
	(arc
		(start 392.91641 -240.766854)
		(mid 393.095639 -240.807007)
		(end 393.272264 -240.756694)
		(width 0.0889)
		(layer "In13.Cu")
		(net "M_H_CPU0_SA_DQ<25>")
	)
	(segment
		(start 383.688082 -239.890046)
		(end 384.154934 -239.624108)
		(width 0.10668)
		(layer "F.Cu")
		(net "M_H_CPU0_SA_DQ<24>")
	)
	(segment
		(start 410.003244 -225.810064)
		(end 414.114488 -225.810064)
		(width 0.14478)
		(layer "In13.Cu")
		(net "M_H_CPU0_SA_DQ<24>")
	)
	(segment
		(start 392.417808 -239.940592)
		(end 392.428222 -239.946688)
		(width 0.0889)
		(layer "In13.Cu")
		(net "M_H_CPU0_SA_DQ<24>")
	)
	(segment
		(start 406.753822 -229.059486)
		(end 410.003244 -225.810064)
		(width 0.14478)
		(layer "In13.Cu")
		(net "M_H_CPU0_SA_DQ<24>")
	)
	(segment
		(start 422.049956 -225.385122)
		(end 424.012106 -225.385122)
		(width 0.14478)
		(layer "In13.Cu")
		(net "M_H_CPU0_SA_DQ<24>")
	)
	(segment
		(start 384.154934 -239.624108)
		(end 384.000756 -239.889538)
		(width 0.0889)
		(layer "In13.Cu")
		(net "M_H_CPU0_SA_DQ<24>")
	)
	(segment
		(start 406.753822 -229.941374)
		(end 406.753822 -229.059486)
		(width 0.14478)
		(layer "In13.Cu")
		(net "M_H_CPU0_SA_DQ<24>")
	)
	(segment
		(start 414.964372 -224.96018)
		(end 417.71697 -224.96018)
		(width 0.14478)
		(layer "In13.Cu")
		(net "M_H_CPU0_SA_DQ<24>")
	)
	(segment
		(start 384.90779 -239.946688)
		(end 384.916172 -239.951514)
		(width 0.0889)
		(layer "In13.Cu")
		(net "M_H_CPU0_SA_DQ<24>")
	)
	(segment
		(start 421.625014 -225.810064)
		(end 422.049956 -225.385122)
		(width 0.14478)
		(layer "In13.Cu")
		(net "M_H_CPU0_SA_DQ<24>")
	)
	(segment
		(start 384.333496 -239.951514)
		(end 384.341878 -239.946688)
		(width 0.0889)
		(layer "In13.Cu")
		(net "M_H_CPU0_SA_DQ<24>")
	)
	(segment
		(start 385.847844 -239.946688)
		(end 385.856226 -239.951514)
		(width 0.0889)
		(layer "In13.Cu")
		(net "M_H_CPU0_SA_DQ<24>")
	)
	(segment
		(start 393.457938 -239.946688)
		(end 394.394436 -239.01019)
		(width 0.0889)
		(layer "In13.Cu")
		(net "M_H_CPU0_SA_DQ<24>")
	)
	(segment
		(start 398.347946 -238.34725)
		(end 406.753822 -229.941374)
		(width 0.14478)
		(layer "In13.Cu")
		(net "M_H_CPU0_SA_DQ<24>")
	)
	(segment
		(start 418.566854 -225.810064)
		(end 421.625014 -225.810064)
		(width 0.14478)
		(layer "In13.Cu")
		(net "M_H_CPU0_SA_DQ<24>")
	)
	(segment
		(start 393.368022 -239.946688)
		(end 393.457938 -239.946688)
		(width 0.0889)
		(layer "In13.Cu")
		(net "M_H_CPU0_SA_DQ<24>")
	)
	(segment
		(start 392.790426 -239.953546)
		(end 392.80211 -239.946688)
		(width 0.0889)
		(layer "In13.Cu")
		(net "M_H_CPU0_SA_DQ<24>")
	)
	(segment
		(start 384.000756 -239.889538)
		(end 384.023108 -239.97285)
		(width 0.0889)
		(layer "In13.Cu")
		(net "M_H_CPU0_SA_DQ<24>")
	)
	(segment
		(start 395.537436 -238.34725)
		(end 395.898878 -238.34725)
		(width 0.0889)
		(layer "In13.Cu")
		(net "M_H_CPU0_SA_DQ<24>")
	)
	(segment
		(start 389.607806 -239.946688)
		(end 389.616188 -239.951514)
		(width 0.0889)
		(layer "In13.Cu")
		(net "M_H_CPU0_SA_DQ<24>")
	)
	(segment
		(start 417.71697 -224.96018)
		(end 418.566854 -225.810064)
		(width 0.14478)
		(layer "In13.Cu")
		(net "M_H_CPU0_SA_DQ<24>")
	)
	(segment
		(start 414.114488 -225.810064)
		(end 414.964372 -224.96018)
		(width 0.14478)
		(layer "In13.Cu")
		(net "M_H_CPU0_SA_DQ<24>")
	)
	(segment
		(start 389.033512 -239.951514)
		(end 389.041894 -239.946688)
		(width 0.0889)
		(layer "In13.Cu")
		(net "M_H_CPU0_SA_DQ<24>")
	)
	(segment
		(start 388.093458 -239.951514)
		(end 388.10184 -239.946688)
		(width 0.0889)
		(layer "In13.Cu")
		(net "M_H_CPU0_SA_DQ<24>")
	)
	(segment
		(start 395.898878 -238.34725)
		(end 398.347946 -238.34725)
		(width 0.14478)
		(layer "In13.Cu")
		(net "M_H_CPU0_SA_DQ<24>")
	)
	(segment
		(start 394.394436 -239.01019)
		(end 394.874496 -239.01019)
		(width 0.0889)
		(layer "In13.Cu")
		(net "M_H_CPU0_SA_DQ<24>")
	)
	(segment
		(start 394.874496 -239.01019)
		(end 395.537436 -238.34725)
		(width 0.0889)
		(layer "In13.Cu")
		(net "M_H_CPU0_SA_DQ<24>")
	)
	(segment
		(start 392.80211 -239.946688)
		(end 392.816842 -239.938052)
		(width 0.0889)
		(layer "In13.Cu")
		(net "M_H_CPU0_SA_DQ<24>")
	)
	(arc
		(start 386.221986 -239.946688)
		(mid 386.504942 -239.870511)
		(end 386.787898 -239.946688)
		(width 0.0889)
		(layer "In13.Cu")
		(net "M_H_CPU0_SA_DQ<24>")
	)
	(arc
		(start 390.921748 -239.946688)
		(mid 391.204704 -239.870511)
		(end 391.48766 -239.946688)
		(width 0.0889)
		(layer "In13.Cu")
		(net "M_H_CPU0_SA_DQ<24>")
	)
	(arc
		(start 384.023108 -239.97285)
		(mid 384.180618 -239.996048)
		(end 384.333496 -239.951514)
		(width 0.0889)
		(layer "In13.Cu")
		(net "M_H_CPU0_SA_DQ<24>")
	)
	(arc
		(start 386.787898 -239.946688)
		(mid 386.974842 -239.996943)
		(end 387.161786 -239.946688)
		(width 0.0889)
		(layer "In13.Cu")
		(net "M_H_CPU0_SA_DQ<24>")
	)
	(arc
		(start 384.916172 -239.951514)
		(mid 385.09968 -239.997008)
		(end 385.281932 -239.946688)
		(width 0.0889)
		(layer "In13.Cu")
		(net "M_H_CPU0_SA_DQ<24>")
	)
	(arc
		(start 392.816842 -239.938052)
		(mid 393.093571 -239.870369)
		(end 393.368022 -239.946688)
		(width 0.0889)
		(layer "In13.Cu")
		(net "M_H_CPU0_SA_DQ<24>")
	)
	(arc
		(start 385.856226 -239.951514)
		(mid 386.039734 -239.997008)
		(end 386.221986 -239.946688)
		(width 0.0889)
		(layer "In13.Cu")
		(net "M_H_CPU0_SA_DQ<24>")
	)
	(arc
		(start 388.667752 -239.946688)
		(mid 388.850003 -239.997038)
		(end 389.033512 -239.951514)
		(width 0.0889)
		(layer "In13.Cu")
		(net "M_H_CPU0_SA_DQ<24>")
	)
	(arc
		(start 392.428222 -239.946688)
		(mid 392.608427 -239.997005)
		(end 392.790426 -239.953546)
		(width 0.0889)
		(layer "In13.Cu")
		(net "M_H_CPU0_SA_DQ<24>")
	)
	(arc
		(start 385.281932 -239.946688)
		(mid 385.564888 -239.870511)
		(end 385.847844 -239.946688)
		(width 0.0889)
		(layer "In13.Cu")
		(net "M_H_CPU0_SA_DQ<24>")
	)
	(arc
		(start 391.862056 -239.946688)
		(mid 392.139123 -239.870417)
		(end 392.417808 -239.940592)
		(width 0.0889)
		(layer "In13.Cu")
		(net "M_H_CPU0_SA_DQ<24>")
	)
	(arc
		(start 389.616188 -239.951514)
		(mid 389.799696 -239.997008)
		(end 389.981948 -239.946688)
		(width 0.0889)
		(layer "In13.Cu")
		(net "M_H_CPU0_SA_DQ<24>")
	)
	(arc
		(start 390.54786 -239.946688)
		(mid 390.734804 -239.996943)
		(end 390.921748 -239.946688)
		(width 0.0889)
		(layer "In13.Cu")
		(net "M_H_CPU0_SA_DQ<24>")
	)
	(arc
		(start 388.10184 -239.946688)
		(mid 388.384796 -239.870511)
		(end 388.667752 -239.946688)
		(width 0.0889)
		(layer "In13.Cu")
		(net "M_H_CPU0_SA_DQ<24>")
	)
	(arc
		(start 389.981948 -239.946688)
		(mid 390.264904 -239.870511)
		(end 390.54786 -239.946688)
		(width 0.0889)
		(layer "In13.Cu")
		(net "M_H_CPU0_SA_DQ<24>")
	)
	(arc
		(start 387.161786 -239.946688)
		(mid 387.444742 -239.870511)
		(end 387.727698 -239.946688)
		(width 0.0889)
		(layer "In13.Cu")
		(net "M_H_CPU0_SA_DQ<24>")
	)
	(arc
		(start 391.48766 -239.946688)
		(mid 391.674858 -239.99707)
		(end 391.862056 -239.946688)
		(width 0.0889)
		(layer "In13.Cu")
		(net "M_H_CPU0_SA_DQ<24>")
	)
	(arc
		(start 389.041894 -239.946688)
		(mid 389.32485 -239.870511)
		(end 389.607806 -239.946688)
		(width 0.0889)
		(layer "In13.Cu")
		(net "M_H_CPU0_SA_DQ<24>")
	)
	(arc
		(start 387.727698 -239.946688)
		(mid 387.909949 -239.997038)
		(end 388.093458 -239.951514)
		(width 0.0889)
		(layer "In13.Cu")
		(net "M_H_CPU0_SA_DQ<24>")
	)
	(arc
		(start 384.341878 -239.946688)
		(mid 384.624834 -239.870511)
		(end 384.90779 -239.946688)
		(width 0.0889)
		(layer "In13.Cu")
		(net "M_H_CPU0_SA_DQ<24>")
	)
	(segment
		(start 381.807974 -239.890046)
		(end 382.274826 -239.624108)
		(width 0.10668)
		(layer "F.Cu")
		(net "M_H_CPU0_SA_DQ<23>")
	)
	(segment
		(start 408.542236 -226.491546)
		(end 408.35707 -226.676712)
		(width 0.14478)
		(layer "In13.Cu")
		(net "M_H_CPU0_SA_DQ<23>")
	)
	(segment
		(start 406.592786 -228.236272)
		(end 406.592532 -228.236018)
		(width 0.14478)
		(layer "In13.Cu")
		(net "M_H_CPU0_SA_DQ<23>")
	)
	(segment
		(start 412.223966 -224.8154)
		(end 412.223966 -224.725738)
		(width 0.14478)
		(layer "In13.Cu")
		(net "M_H_CPU0_SA_DQ<23>")
	)
	(segment
		(start 414.9979 -224.110042)
		(end 414.855914 -224.110042)
		(width 0.14478)
		(layer "In13.Cu")
		(net "M_H_CPU0_SA_DQ<23>")
	)
	(segment
		(start 407.57729 -227.456492)
		(end 407.372566 -227.456492)
		(width 0.14478)
		(layer "In13.Cu")
		(net "M_H_CPU0_SA_DQ<23>")
	)
	(segment
		(start 392.427714 -239.301528)
		(end 392.417808 -239.307624)
		(width 0.0889)
		(layer "In13.Cu")
		(net "M_H_CPU0_SA_DQ<23>")
	)
	(segment
		(start 407.662888 -226.391978)
		(end 407.477722 -226.577144)
		(width 0.14478)
		(layer "In13.Cu")
		(net "M_H_CPU0_SA_DQ<23>")
	)
	(segment
		(start 411.817566 -224.580958)
		(end 411.672786 -224.725738)
		(width 0.14478)
		(layer "In13.Cu")
		(net "M_H_CPU0_SA_DQ<23>")
	)
	(segment
		(start 413.326326 -224.8154)
		(end 413.326326 -224.725738)
		(width 0.14478)
		(layer "In13.Cu")
		(net "M_H_CPU0_SA_DQ<23>")
	)
	(segment
		(start 412.223966 -224.725738)
		(end 412.079186 -224.580958)
		(width 0.14478)
		(layer "In13.Cu")
		(net "M_H_CPU0_SA_DQ<23>")
	)
	(segment
		(start 410.425646 -224.96018)
		(end 410.073602 -224.96018)
		(width 0.14478)
		(layer "In13.Cu")
		(net "M_H_CPU0_SA_DQ<23>")
	)
	(segment
		(start 383.401824 -239.301528)
		(end 383.393442 -239.296702)
		(width 0.0889)
		(layer "In13.Cu")
		(net "M_H_CPU0_SA_DQ<23>")
	)
	(segment
		(start 416.980878 -223.750632)
		(end 416.719258 -223.750632)
		(width 0.14478)
		(layer "In13.Cu")
		(net "M_H_CPU0_SA_DQ<23>")
	)
	(segment
		(start 406.883108 -227.171758)
		(end 406.697942 -227.356924)
		(width 0.14478)
		(layer "In13.Cu")
		(net "M_H_CPU0_SA_DQ<23>")
	)
	(segment
		(start 412.630366 -224.96018)
		(end 412.368746 -224.96018)
		(width 0.14478)
		(layer "In13.Cu")
		(net "M_H_CPU0_SA_DQ<23>")
	)
	(segment
		(start 406.592532 -228.236018)
		(end 406.387808 -228.236018)
		(width 0.14478)
		(layer "In13.Cu")
		(net "M_H_CPU0_SA_DQ<23>")
	)
	(segment
		(start 392.801856 -239.301528)
		(end 392.793474 -239.296702)
		(width 0.0889)
		(layer "In13.Cu")
		(net "M_H_CPU0_SA_DQ<23>")
	)
	(segment
		(start 417.125658 -223.895412)
		(end 416.980878 -223.750632)
		(width 0.14478)
		(layer "In13.Cu")
		(net "M_H_CPU0_SA_DQ<23>")
	)
	(segment
		(start 388.10184 -239.301528)
		(end 388.093458 -239.296702)
		(width 0.0889)
		(layer "In13.Cu")
		(net "M_H_CPU0_SA_DQ<23>")
	)
	(segment
		(start 406.697942 -227.356924)
		(end 406.697942 -227.561648)
		(width 0.14478)
		(layer "In13.Cu")
		(net "M_H_CPU0_SA_DQ<23>")
	)
	(segment
		(start 412.368746 -224.96018)
		(end 412.223966 -224.8154)
		(width 0.14478)
		(layer "In13.Cu")
		(net "M_H_CPU0_SA_DQ<23>")
	)
	(segment
		(start 413.326326 -224.725738)
		(end 413.181546 -224.580958)
		(width 0.14478)
		(layer "In13.Cu")
		(net "M_H_CPU0_SA_DQ<23>")
	)
	(segment
		(start 411.121606 -224.8154)
		(end 411.121606 -224.725738)
		(width 0.14478)
		(layer "In13.Cu")
		(net "M_H_CPU0_SA_DQ<23>")
	)
	(segment
		(start 415.833306 -224.110042)
		(end 415.54908 -224.394268)
		(width 0.14478)
		(layer "In13.Cu")
		(net "M_H_CPU0_SA_DQ<23>")
	)
	(segment
		(start 410.715206 -224.580958)
		(end 410.570426 -224.725738)
		(width 0.14478)
		(layer "In13.Cu")
		(net "M_H_CPU0_SA_DQ<23>")
	)
	(segment
		(start 395.668754 -237.78718)
		(end 394.781024 -238.67491)
		(width 0.0889)
		(layer "In13.Cu")
		(net "M_H_CPU0_SA_DQ<23>")
	)
	(segment
		(start 406.202642 -228.421184)
		(end 406.202642 -229.692708)
		(width 0.14478)
		(layer "In13.Cu")
		(net "M_H_CPU0_SA_DQ<23>")
	)
	(segment
		(start 412.775146 -224.725738)
		(end 412.775146 -224.8154)
		(width 0.14478)
		(layer "In13.Cu")
		(net "M_H_CPU0_SA_DQ<23>")
	)
	(segment
		(start 408.410156 -226.154742)
		(end 408.542236 -226.286822)
		(width 0.14478)
		(layer "In13.Cu")
		(net "M_H_CPU0_SA_DQ<23>")
	)
	(segment
		(start 384.916172 -239.296702)
		(end 384.90779 -239.301528)
		(width 0.0889)
		(layer "In13.Cu")
		(net "M_H_CPU0_SA_DQ<23>")
	)
	(segment
		(start 406.982676 -228.051106)
		(end 406.79751 -228.236272)
		(width 0.14478)
		(layer "In13.Cu")
		(net "M_H_CPU0_SA_DQ<23>")
	)
	(segment
		(start 382.524762 -239.333278)
		(end 382.42875 -239.358678)
		(width 0.0889)
		(layer "In13.Cu")
		(net "M_H_CPU0_SA_DQ<23>")
	)
	(segment
		(start 408.595322 -225.764852)
		(end 408.410156 -225.950018)
		(width 0.14478)
		(layer "In13.Cu")
		(net "M_H_CPU0_SA_DQ<23>")
	)
	(segment
		(start 408.152346 -226.676712)
		(end 407.867612 -226.391978)
		(width 0.14478)
		(layer "In13.Cu")
		(net "M_H_CPU0_SA_DQ<23>")
	)
	(segment
		(start 389.616188 -239.296702)
		(end 389.607806 -239.301528)
		(width 0.0889)
		(layer "In13.Cu")
		(net "M_H_CPU0_SA_DQ<23>")
	)
	(segment
		(start 394.336016 -238.67491)
		(end 393.633198 -239.377728)
		(width 0.0889)
		(layer "In13.Cu")
		(net "M_H_CPU0_SA_DQ<23>")
	)
	(segment
		(start 419.486842 -224.96018)
		(end 418.551106 -224.96018)
		(width 0.14478)
		(layer "In13.Cu")
		(net "M_H_CPU0_SA_DQ<23>")
	)
	(segment
		(start 418.551106 -224.96018)
		(end 417.700968 -224.110042)
		(width 0.14478)
		(layer "In13.Cu")
		(net "M_H_CPU0_SA_DQ<23>")
	)
	(segment
		(start 419.912038 -224.534984)
		(end 419.486842 -224.96018)
		(width 0.14478)
		(layer "In13.Cu")
		(net "M_H_CPU0_SA_DQ<23>")
	)
	(segment
		(start 407.762456 -227.271326)
		(end 407.57729 -227.456492)
		(width 0.14478)
		(layer "In13.Cu")
		(net "M_H_CPU0_SA_DQ<23>")
	)
	(segment
		(start 408.35707 -226.676712)
		(end 408.152346 -226.676712)
		(width 0.14478)
		(layer "In13.Cu")
		(net "M_H_CPU0_SA_DQ<23>")
	)
	(segment
		(start 406.697942 -227.561648)
		(end 406.982676 -227.846382)
		(width 0.14478)
		(layer "In13.Cu")
		(net "M_H_CPU0_SA_DQ<23>")
	)
	(segment
		(start 415.54908 -224.394268)
		(end 415.282126 -224.394268)
		(width 0.14478)
		(layer "In13.Cu")
		(net "M_H_CPU0_SA_DQ<23>")
	)
	(segment
		(start 411.672786 -224.725738)
		(end 411.672786 -224.8154)
		(width 0.14478)
		(layer "In13.Cu")
		(net "M_H_CPU0_SA_DQ<23>")
	)
	(segment
		(start 412.919926 -224.580958)
		(end 412.775146 -224.725738)
		(width 0.14478)
		(layer "In13.Cu")
		(net "M_H_CPU0_SA_DQ<23>")
	)
	(segment
		(start 417.700968 -224.110042)
		(end 417.270438 -224.110042)
		(width 0.14478)
		(layer "In13.Cu")
		(net "M_H_CPU0_SA_DQ<23>")
	)
	(segment
		(start 398.10817 -237.78718)
		(end 395.796262 -237.78718)
		(width 0.14478)
		(layer "In13.Cu")
		(net "M_H_CPU0_SA_DQ<23>")
	)
	(segment
		(start 415.282126 -224.394268)
		(end 414.9979 -224.110042)
		(width 0.14478)
		(layer "In13.Cu")
		(net "M_H_CPU0_SA_DQ<23>")
	)
	(segment
		(start 416.574478 -223.965262)
		(end 416.429698 -224.110042)
		(width 0.14478)
		(layer "In13.Cu")
		(net "M_H_CPU0_SA_DQ<23>")
	)
	(segment
		(start 410.073602 -224.96018)
		(end 409.13685 -225.896932)
		(width 0.14478)
		(layer "In13.Cu")
		(net "M_H_CPU0_SA_DQ<23>")
	)
	(segment
		(start 406.387808 -228.236018)
		(end 406.202642 -228.421184)
		(width 0.14478)
		(layer "In13.Cu")
		(net "M_H_CPU0_SA_DQ<23>")
	)
	(segment
		(start 413.471106 -224.96018)
		(end 413.326326 -224.8154)
		(width 0.14478)
		(layer "In13.Cu")
		(net "M_H_CPU0_SA_DQ<23>")
	)
	(segment
		(start 408.410156 -225.950018)
		(end 408.410156 -226.154742)
		(width 0.14478)
		(layer "In13.Cu")
		(net "M_H_CPU0_SA_DQ<23>")
	)
	(segment
		(start 407.477722 -226.781868)
		(end 407.762456 -227.066602)
		(width 0.14478)
		(layer "In13.Cu")
		(net "M_H_CPU0_SA_DQ<23>")
	)
	(segment
		(start 414.855914 -224.110042)
		(end 414.005776 -224.96018)
		(width 0.14478)
		(layer "In13.Cu")
		(net "M_H_CPU0_SA_DQ<23>")
	)
	(segment
		(start 411.528006 -224.96018)
		(end 411.266386 -224.96018)
		(width 0.14478)
		(layer "In13.Cu")
		(net "M_H_CPU0_SA_DQ<23>")
	)
	(segment
		(start 384.341878 -239.301528)
		(end 384.333496 -239.296702)
		(width 0.0889)
		(layer "In13.Cu")
		(net "M_H_CPU0_SA_DQ<23>")
	)
	(segment
		(start 417.270438 -224.110042)
		(end 417.125658 -223.965262)
		(width 0.14478)
		(layer "In13.Cu")
		(net "M_H_CPU0_SA_DQ<23>")
	)
	(segment
		(start 407.087832 -227.171758)
		(end 406.883108 -227.171758)
		(width 0.14478)
		(layer "In13.Cu")
		(net "M_H_CPU0_SA_DQ<23>")
	)
	(segment
		(start 382.42875 -239.358678)
		(end 382.274826 -239.624108)
		(width 0.0889)
		(layer "In13.Cu")
		(net "M_H_CPU0_SA_DQ<23>")
	)
	(segment
		(start 407.867612 -226.391978)
		(end 407.662888 -226.391978)
		(width 0.14478)
		(layer "In13.Cu")
		(net "M_H_CPU0_SA_DQ<23>")
	)
	(segment
		(start 393.633198 -239.377728)
		(end 393.084558 -239.377728)
		(width 0.0889)
		(layer "In13.Cu")
		(net "M_H_CPU0_SA_DQ<23>")
	)
	(segment
		(start 411.121606 -224.725738)
		(end 410.976826 -224.580958)
		(width 0.14478)
		(layer "In13.Cu")
		(net "M_H_CPU0_SA_DQ<23>")
	)
	(segment
		(start 407.762456 -227.066602)
		(end 407.762456 -227.271326)
		(width 0.14478)
		(layer "In13.Cu")
		(net "M_H_CPU0_SA_DQ<23>")
	)
	(segment
		(start 409.13685 -225.896932)
		(end 408.932126 -225.896932)
		(width 0.14478)
		(layer "In13.Cu")
		(net "M_H_CPU0_SA_DQ<23>")
	)
	(segment
		(start 407.372566 -227.456492)
		(end 407.087832 -227.171758)
		(width 0.14478)
		(layer "In13.Cu")
		(net "M_H_CPU0_SA_DQ<23>")
	)
	(segment
		(start 406.982676 -227.846382)
		(end 406.982676 -228.051106)
		(width 0.14478)
		(layer "In13.Cu")
		(net "M_H_CPU0_SA_DQ<23>")
	)
	(segment
		(start 411.266386 -224.96018)
		(end 411.121606 -224.8154)
		(width 0.14478)
		(layer "In13.Cu")
		(net "M_H_CPU0_SA_DQ<23>")
	)
	(segment
		(start 394.781024 -238.67491)
		(end 394.336016 -238.67491)
		(width 0.0889)
		(layer "In13.Cu")
		(net "M_H_CPU0_SA_DQ<23>")
	)
	(segment
		(start 416.574478 -223.895412)
		(end 416.574478 -223.965262)
		(width 0.14478)
		(layer "In13.Cu")
		(net "M_H_CPU0_SA_DQ<23>")
	)
	(segment
		(start 416.429698 -224.110042)
		(end 415.833306 -224.110042)
		(width 0.14478)
		(layer "In13.Cu")
		(net "M_H_CPU0_SA_DQ<23>")
	)
	(segment
		(start 407.477722 -226.577144)
		(end 407.477722 -226.781868)
		(width 0.14478)
		(layer "In13.Cu")
		(net "M_H_CPU0_SA_DQ<23>")
	)
	(segment
		(start 414.005776 -224.96018)
		(end 413.471106 -224.96018)
		(width 0.14478)
		(layer "In13.Cu")
		(net "M_H_CPU0_SA_DQ<23>")
	)
	(segment
		(start 385.856226 -239.296702)
		(end 385.847844 -239.301528)
		(width 0.0889)
		(layer "In13.Cu")
		(net "M_H_CPU0_SA_DQ<23>")
	)
	(segment
		(start 408.542236 -226.286822)
		(end 408.542236 -226.491546)
		(width 0.14478)
		(layer "In13.Cu")
		(net "M_H_CPU0_SA_DQ<23>")
	)
	(segment
		(start 412.079186 -224.580958)
		(end 411.817566 -224.580958)
		(width 0.14478)
		(layer "In13.Cu")
		(net "M_H_CPU0_SA_DQ<23>")
	)
	(segment
		(start 389.041894 -239.301528)
		(end 389.033512 -239.296702)
		(width 0.0889)
		(layer "In13.Cu")
		(net "M_H_CPU0_SA_DQ<23>")
	)
	(segment
		(start 408.932126 -225.896932)
		(end 408.800046 -225.764852)
		(width 0.14478)
		(layer "In13.Cu")
		(net "M_H_CPU0_SA_DQ<23>")
	)
	(segment
		(start 413.181546 -224.580958)
		(end 412.919926 -224.580958)
		(width 0.14478)
		(layer "In13.Cu")
		(net "M_H_CPU0_SA_DQ<23>")
	)
	(segment
		(start 412.775146 -224.8154)
		(end 412.630366 -224.96018)
		(width 0.14478)
		(layer "In13.Cu")
		(net "M_H_CPU0_SA_DQ<23>")
	)
	(segment
		(start 408.800046 -225.764852)
		(end 408.595322 -225.764852)
		(width 0.14478)
		(layer "In13.Cu")
		(net "M_H_CPU0_SA_DQ<23>")
	)
	(segment
		(start 416.719258 -223.750632)
		(end 416.574478 -223.895412)
		(width 0.14478)
		(layer "In13.Cu")
		(net "M_H_CPU0_SA_DQ<23>")
	)
	(segment
		(start 417.125658 -223.965262)
		(end 417.125658 -223.895412)
		(width 0.14478)
		(layer "In13.Cu")
		(net "M_H_CPU0_SA_DQ<23>")
	)
	(segment
		(start 410.976826 -224.580958)
		(end 410.715206 -224.580958)
		(width 0.14478)
		(layer "In13.Cu")
		(net "M_H_CPU0_SA_DQ<23>")
	)
	(segment
		(start 406.79751 -228.236272)
		(end 406.592786 -228.236272)
		(width 0.14478)
		(layer "In13.Cu")
		(net "M_H_CPU0_SA_DQ<23>")
	)
	(segment
		(start 410.570426 -224.8154)
		(end 410.425646 -224.96018)
		(width 0.14478)
		(layer "In13.Cu")
		(net "M_H_CPU0_SA_DQ<23>")
	)
	(segment
		(start 395.796262 -237.78718)
		(end 395.668754 -237.78718)
		(width 0.0889)
		(layer "In13.Cu")
		(net "M_H_CPU0_SA_DQ<23>")
	)
	(segment
		(start 411.672786 -224.8154)
		(end 411.528006 -224.96018)
		(width 0.14478)
		(layer "In13.Cu")
		(net "M_H_CPU0_SA_DQ<23>")
	)
	(segment
		(start 406.202642 -229.692708)
		(end 398.10817 -237.78718)
		(width 0.14478)
		(layer "In13.Cu")
		(net "M_H_CPU0_SA_DQ<23>")
	)
	(segment
		(start 410.570426 -224.725738)
		(end 410.570426 -224.8154)
		(width 0.14478)
		(layer "In13.Cu")
		(net "M_H_CPU0_SA_DQ<23>")
	)
	(arc
		(start 383.967736 -239.301528)
		(mid 383.68478 -239.377705)
		(end 383.401824 -239.301528)
		(width 0.0889)
		(layer "In13.Cu")
		(net "M_H_CPU0_SA_DQ<23>")
	)
	(arc
		(start 389.033512 -239.296702)
		(mid 388.850004 -239.251208)
		(end 388.667752 -239.301528)
		(width 0.0889)
		(layer "In13.Cu")
		(net "M_H_CPU0_SA_DQ<23>")
	)
	(arc
		(start 391.862056 -239.301528)
		(mid 391.674858 -239.251146)
		(end 391.48766 -239.301528)
		(width 0.0889)
		(layer "In13.Cu")
		(net "M_H_CPU0_SA_DQ<23>")
	)
	(arc
		(start 390.921748 -239.301528)
		(mid 390.734804 -239.251273)
		(end 390.54786 -239.301528)
		(width 0.0889)
		(layer "In13.Cu")
		(net "M_H_CPU0_SA_DQ<23>")
	)
	(arc
		(start 383.393442 -239.296702)
		(mid 383.209934 -239.251208)
		(end 383.027682 -239.301528)
		(width 0.0889)
		(layer "In13.Cu")
		(net "M_H_CPU0_SA_DQ<23>")
	)
	(arc
		(start 389.981948 -239.301528)
		(mid 389.799697 -239.251178)
		(end 389.616188 -239.296702)
		(width 0.0889)
		(layer "In13.Cu")
		(net "M_H_CPU0_SA_DQ<23>")
	)
	(arc
		(start 392.793474 -239.296702)
		(mid 392.609966 -239.251208)
		(end 392.427714 -239.301528)
		(width 0.0889)
		(layer "In13.Cu")
		(net "M_H_CPU0_SA_DQ<23>")
	)
	(arc
		(start 385.281932 -239.301528)
		(mid 385.099681 -239.251178)
		(end 384.916172 -239.296702)
		(width 0.0889)
		(layer "In13.Cu")
		(net "M_H_CPU0_SA_DQ<23>")
	)
	(arc
		(start 388.093458 -239.296702)
		(mid 387.90995 -239.251208)
		(end 387.727698 -239.301528)
		(width 0.0889)
		(layer "In13.Cu")
		(net "M_H_CPU0_SA_DQ<23>")
	)
	(arc
		(start 389.607806 -239.301528)
		(mid 389.32485 -239.377705)
		(end 389.041894 -239.301528)
		(width 0.0889)
		(layer "In13.Cu")
		(net "M_H_CPU0_SA_DQ<23>")
	)
	(arc
		(start 388.667752 -239.301528)
		(mid 388.384796 -239.377705)
		(end 388.10184 -239.301528)
		(width 0.0889)
		(layer "In13.Cu")
		(net "M_H_CPU0_SA_DQ<23>")
	)
	(arc
		(start 387.161786 -239.301528)
		(mid 386.974842 -239.251273)
		(end 386.787898 -239.301528)
		(width 0.0889)
		(layer "In13.Cu")
		(net "M_H_CPU0_SA_DQ<23>")
	)
	(arc
		(start 390.54786 -239.301528)
		(mid 390.264904 -239.377705)
		(end 389.981948 -239.301528)
		(width 0.0889)
		(layer "In13.Cu")
		(net "M_H_CPU0_SA_DQ<23>")
	)
	(arc
		(start 386.221986 -239.301528)
		(mid 386.039735 -239.251178)
		(end 385.856226 -239.296702)
		(width 0.0889)
		(layer "In13.Cu")
		(net "M_H_CPU0_SA_DQ<23>")
	)
	(arc
		(start 383.027682 -239.301528)
		(mid 382.779969 -239.376748)
		(end 382.524762 -239.333278)
		(width 0.0889)
		(layer "In13.Cu")
		(net "M_H_CPU0_SA_DQ<23>")
	)
	(arc
		(start 392.417808 -239.307624)
		(mid 392.139122 -239.377844)
		(end 391.862056 -239.301528)
		(width 0.0889)
		(layer "In13.Cu")
		(net "M_H_CPU0_SA_DQ<23>")
	)
	(arc
		(start 391.48766 -239.301528)
		(mid 391.204704 -239.377705)
		(end 390.921748 -239.301528)
		(width 0.0889)
		(layer "In13.Cu")
		(net "M_H_CPU0_SA_DQ<23>")
	)
	(arc
		(start 387.727698 -239.301528)
		(mid 387.444742 -239.377705)
		(end 387.161786 -239.301528)
		(width 0.0889)
		(layer "In13.Cu")
		(net "M_H_CPU0_SA_DQ<23>")
	)
	(arc
		(start 384.90779 -239.301528)
		(mid 384.624834 -239.377705)
		(end 384.341878 -239.301528)
		(width 0.0889)
		(layer "In13.Cu")
		(net "M_H_CPU0_SA_DQ<23>")
	)
	(arc
		(start 385.847844 -239.301528)
		(mid 385.564888 -239.377705)
		(end 385.281932 -239.301528)
		(width 0.0889)
		(layer "In13.Cu")
		(net "M_H_CPU0_SA_DQ<23>")
	)
	(arc
		(start 386.787898 -239.301528)
		(mid 386.504942 -239.377705)
		(end 386.221986 -239.301528)
		(width 0.0889)
		(layer "In13.Cu")
		(net "M_H_CPU0_SA_DQ<23>")
	)
	(arc
		(start 393.037568 -239.37595)
		(mid 392.915586 -239.351811)
		(end 392.801856 -239.301528)
		(width 0.0889)
		(layer "In13.Cu")
		(net "M_H_CPU0_SA_DQ<23>")
	)
	(arc
		(start 384.333496 -239.296702)
		(mid 384.149988 -239.251208)
		(end 383.967736 -239.301528)
		(width 0.0889)
		(layer "In13.Cu")
		(net "M_H_CPU0_SA_DQ<23>")
	)
	(arc
		(start 393.084558 -239.377728)
		(mid 393.061044 -239.377333)
		(end 393.037568 -239.37595)
		(width 0.0889)
		(layer "In13.Cu")
		(net "M_H_CPU0_SA_DQ<23>")
	)
	(segment
		(start 383.217928 -239.08004)
		(end 383.68478 -238.814102)
		(width 0.10668)
		(layer "F.Cu")
		(net "M_H_CPU0_SA_DQ<22>")
	)
	(segment
		(start 417.52901 -222.41002)
		(end 417.988242 -222.869252)
		(width 0.14478)
		(layer "In13.Cu")
		(net "M_H_CPU0_SA_DQ<22>")
	)
	(segment
		(start 407.613866 -225.167952)
		(end 407.916126 -224.865692)
		(width 0.14478)
		(layer "In13.Cu")
		(net "M_H_CPU0_SA_DQ<22>")
	)
	(segment
		(start 408.896058 -224.865692)
		(end 410.149294 -223.612456)
		(width 0.14478)
		(layer "In13.Cu")
		(net "M_H_CPU0_SA_DQ<22>")
	)
	(segment
		(start 413.071564 -222.8596)
		(end 413.216344 -223.00438)
		(width 0.14478)
		(layer "In13.Cu")
		(net "M_H_CPU0_SA_DQ<22>")
	)
	(segment
		(start 415.89706 -222.010224)
		(end 416.04184 -222.155004)
		(width 0.14478)
		(layer "In13.Cu")
		(net "M_H_CPU0_SA_DQ<22>")
	)
	(segment
		(start 416.04184 -222.155004)
		(end 416.04184 -222.26524)
		(width 0.14478)
		(layer "In13.Cu")
		(net "M_H_CPU0_SA_DQ<22>")
	)
	(segment
		(start 405.367744 -227.025454)
		(end 405.367744 -226.82073)
		(width 0.14478)
		(layer "In13.Cu")
		(net "M_H_CPU0_SA_DQ<22>")
	)
	(segment
		(start 406.147524 -226.245674)
		(end 406.147524 -226.04095)
		(width 0.14478)
		(layer "In13.Cu")
		(net "M_H_CPU0_SA_DQ<22>")
	)
	(segment
		(start 388.197852 -238.491522)
		(end 388.206234 -238.486696)
		(width 0.0889)
		(layer "In13.Cu")
		(net "M_H_CPU0_SA_DQ<22>")
	)
	(segment
		(start 417.1442 -222.26524)
		(end 417.28898 -222.41002)
		(width 0.14478)
		(layer "In13.Cu")
		(net "M_H_CPU0_SA_DQ<22>")
	)
	(segment
		(start 418.683186 -223.014032)
		(end 418.683186 -223.49841)
		(width 0.14478)
		(layer "In13.Cu")
		(net "M_H_CPU0_SA_DQ<22>")
	)
	(segment
		(start 417.988242 -222.869252)
		(end 418.538406 -222.869252)
		(width 0.14478)
		(layer "In13.Cu")
		(net "M_H_CPU0_SA_DQ<22>")
	)
	(segment
		(start 416.59302 -222.155004)
		(end 416.7378 -222.010224)
		(width 0.14478)
		(layer "In13.Cu")
		(net "M_H_CPU0_SA_DQ<22>")
	)
	(segment
		(start 406.147524 -226.04095)
		(end 406.33269 -225.855784)
		(width 0.14478)
		(layer "In13.Cu")
		(net "M_H_CPU0_SA_DQ<22>")
	)
	(segment
		(start 419.234366 -223.49841)
		(end 419.234366 -223.014032)
		(width 0.14478)
		(layer "In13.Cu")
		(net "M_H_CPU0_SA_DQ<22>")
	)
	(segment
		(start 405.849582 -226.727512)
		(end 406.054306 -226.727512)
		(width 0.14478)
		(layer "In13.Cu")
		(net "M_H_CPU0_SA_DQ<22>")
	)
	(segment
		(start 412.665164 -223.115378)
		(end 412.665164 -223.00438)
		(width 0.14478)
		(layer "In13.Cu")
		(net "M_H_CPU0_SA_DQ<22>")
	)
	(segment
		(start 406.239472 -226.542346)
		(end 406.239472 -226.337622)
		(width 0.14478)
		(layer "In13.Cu")
		(net "M_H_CPU0_SA_DQ<22>")
	)
	(segment
		(start 410.6037 -223.00438)
		(end 410.74848 -222.8596)
		(width 0.14478)
		(layer "In13.Cu")
		(net "M_H_CPU0_SA_DQ<22>")
	)
	(segment
		(start 419.089586 -223.64319)
		(end 419.234366 -223.49841)
		(width 0.14478)
		(layer "In13.Cu")
		(net "M_H_CPU0_SA_DQ<22>")
	)
	(segment
		(start 410.6037 -223.467676)
		(end 410.6037 -223.00438)
		(width 0.14478)
		(layer "In13.Cu")
		(net "M_H_CPU0_SA_DQ<22>")
	)
	(segment
		(start 393.084812 -238.440722)
		(end 393.709398 -238.440722)
		(width 0.0889)
		(layer "In13.Cu")
		(net "M_H_CPU0_SA_DQ<22>")
	)
	(segment
		(start 410.45892 -223.612456)
		(end 410.6037 -223.467676)
		(width 0.14478)
		(layer "In13.Cu")
		(net "M_H_CPU0_SA_DQ<22>")
	)
	(segment
		(start 407.019252 -225.557842)
		(end 406.927304 -225.465894)
		(width 0.14478)
		(layer "In13.Cu")
		(net "M_H_CPU0_SA_DQ<22>")
	)
	(segment
		(start 418.827966 -223.64319)
		(end 419.089586 -223.64319)
		(width 0.14478)
		(layer "In13.Cu")
		(net "M_H_CPU0_SA_DQ<22>")
	)
	(segment
		(start 395.775434 -236.87786)
		(end 397.67129 -236.87786)
		(width 0.14478)
		(layer "In13.Cu")
		(net "M_H_CPU0_SA_DQ<22>")
	)
	(segment
		(start 416.99942 -222.010224)
		(end 417.1442 -222.155004)
		(width 0.14478)
		(layer "In13.Cu")
		(net "M_H_CPU0_SA_DQ<22>")
	)
	(segment
		(start 405.367744 -226.82073)
		(end 405.55291 -226.635564)
		(width 0.14478)
		(layer "In13.Cu")
		(net "M_H_CPU0_SA_DQ<22>")
	)
	(segment
		(start 415.49066 -222.26524)
		(end 415.49066 -222.155004)
		(width 0.14478)
		(layer "In13.Cu")
		(net "M_H_CPU0_SA_DQ<22>")
	)
	(segment
		(start 407.317194 -225.076004)
		(end 407.409142 -225.167952)
		(width 0.14478)
		(layer "In13.Cu")
		(net "M_H_CPU0_SA_DQ<22>")
	)
	(segment
		(start 416.44824 -222.41002)
		(end 416.59302 -222.26524)
		(width 0.14478)
		(layer "In13.Cu")
		(net "M_H_CPU0_SA_DQ<22>")
	)
	(segment
		(start 387.257798 -238.491522)
		(end 387.26618 -238.486696)
		(width 0.0889)
		(layer "In13.Cu")
		(net "M_H_CPU0_SA_DQ<22>")
	)
	(segment
		(start 405.459692 -227.117402)
		(end 405.367744 -227.025454)
		(width 0.14478)
		(layer "In13.Cu")
		(net "M_H_CPU0_SA_DQ<22>")
	)
	(segment
		(start 415.63544 -222.010224)
		(end 415.89706 -222.010224)
		(width 0.14478)
		(layer "In13.Cu")
		(net "M_H_CPU0_SA_DQ<22>")
	)
	(segment
		(start 385.74345 -238.486696)
		(end 385.751832 -238.491522)
		(width 0.0889)
		(layer "In13.Cu")
		(net "M_H_CPU0_SA_DQ<22>")
	)
	(segment
		(start 406.054306 -226.727512)
		(end 406.239472 -226.542346)
		(width 0.14478)
		(layer "In13.Cu")
		(net "M_H_CPU0_SA_DQ<22>")
	)
	(segment
		(start 405.303482 -227.478336)
		(end 405.459692 -227.322126)
		(width 0.14478)
		(layer "In13.Cu")
		(net "M_H_CPU0_SA_DQ<22>")
	)
	(segment
		(start 406.33269 -225.855784)
		(end 406.537414 -225.855784)
		(width 0.14478)
		(layer "In13.Cu")
		(net "M_H_CPU0_SA_DQ<22>")
	)
	(segment
		(start 415.49066 -222.155004)
		(end 415.63544 -222.010224)
		(width 0.14478)
		(layer "In13.Cu")
		(net "M_H_CPU0_SA_DQ<22>")
	)
	(segment
		(start 391.01776 -238.491522)
		(end 391.026142 -238.486696)
		(width 0.0889)
		(layer "In13.Cu")
		(net "M_H_CPU0_SA_DQ<22>")
	)
	(segment
		(start 405.459692 -227.322126)
		(end 405.459692 -227.117402)
		(width 0.14478)
		(layer "In13.Cu")
		(net "M_H_CPU0_SA_DQ<22>")
	)
	(segment
		(start 395.27226 -236.87786)
		(end 395.775434 -236.87786)
		(width 0.0889)
		(layer "In13.Cu")
		(net "M_H_CPU0_SA_DQ<22>")
	)
	(segment
		(start 411.56128 -223.660462)
		(end 411.70606 -223.515682)
		(width 0.14478)
		(layer "In13.Cu")
		(net "M_H_CPU0_SA_DQ<22>")
	)
	(segment
		(start 411.15488 -223.00438)
		(end 411.15488 -223.515682)
		(width 0.14478)
		(layer "In13.Cu")
		(net "M_H_CPU0_SA_DQ<22>")
	)
	(segment
		(start 390.443466 -238.486696)
		(end 390.451848 -238.491522)
		(width 0.0889)
		(layer "In13.Cu")
		(net "M_H_CPU0_SA_DQ<22>")
	)
	(segment
		(start 406.629362 -225.947732)
		(end 406.834086 -225.947732)
		(width 0.14478)
		(layer "In13.Cu")
		(net "M_H_CPU0_SA_DQ<22>")
	)
	(segment
		(start 383.838958 -238.548672)
		(end 383.935224 -238.523272)
		(width 0.0889)
		(layer "In13.Cu")
		(net "M_H_CPU0_SA_DQ<22>")
	)
	(segment
		(start 416.18662 -222.41002)
		(end 416.44824 -222.41002)
		(width 0.14478)
		(layer "In13.Cu")
		(net "M_H_CPU0_SA_DQ<22>")
	)
	(segment
		(start 412.809944 -222.8596)
		(end 413.071564 -222.8596)
		(width 0.14478)
		(layer "In13.Cu")
		(net "M_H_CPU0_SA_DQ<22>")
	)
	(segment
		(start 413.867092 -223.561148)
		(end 415.01822 -222.41002)
		(width 0.14478)
		(layer "In13.Cu")
		(net "M_H_CPU0_SA_DQ<22>")
	)
	(segment
		(start 416.04184 -222.26524)
		(end 416.18662 -222.41002)
		(width 0.14478)
		(layer "In13.Cu")
		(net "M_H_CPU0_SA_DQ<22>")
	)
	(segment
		(start 393.709398 -238.440722)
		(end 395.27226 -236.87786)
		(width 0.0889)
		(layer "In13.Cu")
		(net "M_H_CPU0_SA_DQ<22>")
	)
	(segment
		(start 386.683504 -238.486696)
		(end 386.691886 -238.491522)
		(width 0.0889)
		(layer "In13.Cu")
		(net "M_H_CPU0_SA_DQ<22>")
	)
	(segment
		(start 419.234366 -223.014032)
		(end 419.379146 -222.869252)
		(width 0.14478)
		(layer "In13.Cu")
		(net "M_H_CPU0_SA_DQ<22>")
	)
	(segment
		(start 406.927304 -225.465894)
		(end 406.927304 -225.26117)
		(width 0.14478)
		(layer "In13.Cu")
		(net "M_H_CPU0_SA_DQ<22>")
	)
	(segment
		(start 407.019252 -225.762566)
		(end 407.019252 -225.557842)
		(width 0.14478)
		(layer "In13.Cu")
		(net "M_H_CPU0_SA_DQ<22>")
	)
	(segment
		(start 415.34588 -222.41002)
		(end 415.49066 -222.26524)
		(width 0.14478)
		(layer "In13.Cu")
		(net "M_H_CPU0_SA_DQ<22>")
	)
	(segment
		(start 412.520384 -223.260158)
		(end 412.665164 -223.115378)
		(width 0.14478)
		(layer "In13.Cu")
		(net "M_H_CPU0_SA_DQ<22>")
	)
	(segment
		(start 411.85084 -223.260158)
		(end 412.520384 -223.260158)
		(width 0.14478)
		(layer "In13.Cu")
		(net "M_H_CPU0_SA_DQ<22>")
	)
	(segment
		(start 411.70606 -223.404938)
		(end 411.85084 -223.260158)
		(width 0.14478)
		(layer "In13.Cu")
		(net "M_H_CPU0_SA_DQ<22>")
	)
	(segment
		(start 410.74848 -222.8596)
		(end 411.0101 -222.8596)
		(width 0.14478)
		(layer "In13.Cu")
		(net "M_H_CPU0_SA_DQ<22>")
	)
	(segment
		(start 411.70606 -223.515682)
		(end 411.70606 -223.404938)
		(width 0.14478)
		(layer "In13.Cu")
		(net "M_H_CPU0_SA_DQ<22>")
	)
	(segment
		(start 417.28898 -222.41002)
		(end 417.52901 -222.41002)
		(width 0.14478)
		(layer "In13.Cu")
		(net "M_H_CPU0_SA_DQ<22>")
	)
	(segment
		(start 412.665164 -223.00438)
		(end 412.809944 -222.8596)
		(width 0.14478)
		(layer "In13.Cu")
		(net "M_H_CPU0_SA_DQ<22>")
	)
	(segment
		(start 418.683186 -223.49841)
		(end 418.827966 -223.64319)
		(width 0.14478)
		(layer "In13.Cu")
		(net "M_H_CPU0_SA_DQ<22>")
	)
	(segment
		(start 407.11247 -225.076004)
		(end 407.317194 -225.076004)
		(width 0.14478)
		(layer "In13.Cu")
		(net "M_H_CPU0_SA_DQ<22>")
	)
	(segment
		(start 411.29966 -223.660462)
		(end 411.56128 -223.660462)
		(width 0.14478)
		(layer "In13.Cu")
		(net "M_H_CPU0_SA_DQ<22>")
	)
	(segment
		(start 407.409142 -225.167952)
		(end 407.613866 -225.167952)
		(width 0.14478)
		(layer "In13.Cu")
		(net "M_H_CPU0_SA_DQ<22>")
	)
	(segment
		(start 392.324336 -238.486696)
		(end 392.332718 -238.491522)
		(width 0.0889)
		(layer "In13.Cu")
		(net "M_H_CPU0_SA_DQ<22>")
	)
	(segment
		(start 416.7378 -222.010224)
		(end 416.99942 -222.010224)
		(width 0.14478)
		(layer "In13.Cu")
		(net "M_H_CPU0_SA_DQ<22>")
	)
	(segment
		(start 405.55291 -226.635564)
		(end 405.757634 -226.635564)
		(width 0.14478)
		(layer "In13.Cu")
		(net "M_H_CPU0_SA_DQ<22>")
	)
	(segment
		(start 419.379146 -222.869252)
		(end 419.877748 -222.869252)
		(width 0.14478)
		(layer "In13.Cu")
		(net "M_H_CPU0_SA_DQ<22>")
	)
	(segment
		(start 406.239472 -226.337622)
		(end 406.147524 -226.245674)
		(width 0.14478)
		(layer "In13.Cu")
		(net "M_H_CPU0_SA_DQ<22>")
	)
	(segment
		(start 417.1442 -222.155004)
		(end 417.1442 -222.26524)
		(width 0.14478)
		(layer "In13.Cu")
		(net "M_H_CPU0_SA_DQ<22>")
	)
	(segment
		(start 413.216344 -223.00438)
		(end 413.216344 -223.416368)
		(width 0.14478)
		(layer "In13.Cu")
		(net "M_H_CPU0_SA_DQ<22>")
	)
	(segment
		(start 405.303482 -229.245668)
		(end 405.303482 -227.478336)
		(width 0.14478)
		(layer "In13.Cu")
		(net "M_H_CPU0_SA_DQ<22>")
	)
	(segment
		(start 397.67129 -236.87786)
		(end 405.303482 -229.245668)
		(width 0.14478)
		(layer "In13.Cu")
		(net "M_H_CPU0_SA_DQ<22>")
	)
	(segment
		(start 410.149294 -223.612456)
		(end 410.45892 -223.612456)
		(width 0.14478)
		(layer "In13.Cu")
		(net "M_H_CPU0_SA_DQ<22>")
	)
	(segment
		(start 391.391902 -238.491522)
		(end 391.402316 -238.497618)
		(width 0.0889)
		(layer "In13.Cu")
		(net "M_H_CPU0_SA_DQ<22>")
	)
	(segment
		(start 406.927304 -225.26117)
		(end 407.11247 -225.076004)
		(width 0.14478)
		(layer "In13.Cu")
		(net "M_H_CPU0_SA_DQ<22>")
	)
	(segment
		(start 419.877748 -222.869252)
		(end 419.912038 -222.834962)
		(width 0.14478)
		(layer "In13.Cu")
		(net "M_H_CPU0_SA_DQ<22>")
	)
	(segment
		(start 413.216344 -223.416368)
		(end 413.361124 -223.561148)
		(width 0.14478)
		(layer "In13.Cu")
		(net "M_H_CPU0_SA_DQ<22>")
	)
	(segment
		(start 416.59302 -222.26524)
		(end 416.59302 -222.155004)
		(width 0.14478)
		(layer "In13.Cu")
		(net "M_H_CPU0_SA_DQ<22>")
	)
	(segment
		(start 413.361124 -223.561148)
		(end 413.867092 -223.561148)
		(width 0.14478)
		(layer "In13.Cu")
		(net "M_H_CPU0_SA_DQ<22>")
	)
	(segment
		(start 418.538406 -222.869252)
		(end 418.683186 -223.014032)
		(width 0.14478)
		(layer "In13.Cu")
		(net "M_H_CPU0_SA_DQ<22>")
	)
	(segment
		(start 406.834086 -225.947732)
		(end 407.019252 -225.762566)
		(width 0.14478)
		(layer "In13.Cu")
		(net "M_H_CPU0_SA_DQ<22>")
	)
	(segment
		(start 411.0101 -222.8596)
		(end 411.15488 -223.00438)
		(width 0.14478)
		(layer "In13.Cu")
		(net "M_H_CPU0_SA_DQ<22>")
	)
	(segment
		(start 406.537414 -225.855784)
		(end 406.629362 -225.947732)
		(width 0.14478)
		(layer "In13.Cu")
		(net "M_H_CPU0_SA_DQ<22>")
	)
	(segment
		(start 415.01822 -222.41002)
		(end 415.34588 -222.41002)
		(width 0.14478)
		(layer "In13.Cu")
		(net "M_H_CPU0_SA_DQ<22>")
	)
	(segment
		(start 383.68478 -238.814102)
		(end 383.838958 -238.548672)
		(width 0.0889)
		(layer "In13.Cu")
		(net "M_H_CPU0_SA_DQ<22>")
	)
	(segment
		(start 405.757634 -226.635564)
		(end 405.849582 -226.727512)
		(width 0.14478)
		(layer "In13.Cu")
		(net "M_H_CPU0_SA_DQ<22>")
	)
	(segment
		(start 407.916126 -224.865692)
		(end 408.896058 -224.865692)
		(width 0.14478)
		(layer "In13.Cu")
		(net "M_H_CPU0_SA_DQ<22>")
	)
	(segment
		(start 411.15488 -223.515682)
		(end 411.29966 -223.660462)
		(width 0.14478)
		(layer "In13.Cu")
		(net "M_H_CPU0_SA_DQ<22>")
	)
	(arc
		(start 386.317744 -238.491522)
		(mid 386.499995 -238.441172)
		(end 386.683504 -238.486696)
		(width 0.0889)
		(layer "In13.Cu")
		(net "M_H_CPU0_SA_DQ<22>")
	)
	(arc
		(start 384.43789 -238.491522)
		(mid 384.624834 -238.441267)
		(end 384.811778 -238.491522)
		(width 0.0889)
		(layer "In13.Cu")
		(net "M_H_CPU0_SA_DQ<22>")
	)
	(arc
		(start 387.26618 -238.486696)
		(mid 387.449688 -238.441202)
		(end 387.63194 -238.491522)
		(width 0.0889)
		(layer "In13.Cu")
		(net "M_H_CPU0_SA_DQ<22>")
	)
	(arc
		(start 391.026142 -238.486696)
		(mid 391.20965 -238.441202)
		(end 391.391902 -238.491522)
		(width 0.0889)
		(layer "In13.Cu")
		(net "M_H_CPU0_SA_DQ<22>")
	)
	(arc
		(start 392.892534 -238.495078)
		(mid 392.984966 -238.454796)
		(end 393.084812 -238.440722)
		(width 0.0889)
		(layer "In13.Cu")
		(net "M_H_CPU0_SA_DQ<22>")
	)
	(arc
		(start 385.751832 -238.491522)
		(mid 386.034788 -238.567699)
		(end 386.317744 -238.491522)
		(width 0.0889)
		(layer "In13.Cu")
		(net "M_H_CPU0_SA_DQ<22>")
	)
	(arc
		(start 391.402316 -238.497618)
		(mid 391.681002 -238.567838)
		(end 391.958068 -238.491522)
		(width 0.0889)
		(layer "In13.Cu")
		(net "M_H_CPU0_SA_DQ<22>")
	)
	(arc
		(start 388.206234 -238.486696)
		(mid 388.389742 -238.441202)
		(end 388.571994 -238.491522)
		(width 0.0889)
		(layer "In13.Cu")
		(net "M_H_CPU0_SA_DQ<22>")
	)
	(arc
		(start 389.137906 -238.491522)
		(mid 389.32485 -238.441267)
		(end 389.511794 -238.491522)
		(width 0.0889)
		(layer "In13.Cu")
		(net "M_H_CPU0_SA_DQ<22>")
	)
	(arc
		(start 387.63194 -238.491522)
		(mid 387.914896 -238.567699)
		(end 388.197852 -238.491522)
		(width 0.0889)
		(layer "In13.Cu")
		(net "M_H_CPU0_SA_DQ<22>")
	)
	(arc
		(start 389.511794 -238.491522)
		(mid 389.79475 -238.567699)
		(end 390.077706 -238.491522)
		(width 0.0889)
		(layer "In13.Cu")
		(net "M_H_CPU0_SA_DQ<22>")
	)
	(arc
		(start 392.332718 -238.491522)
		(mid 392.612146 -238.567688)
		(end 392.892534 -238.495078)
		(width 0.0889)
		(layer "In13.Cu")
		(net "M_H_CPU0_SA_DQ<22>")
	)
	(arc
		(start 384.811778 -238.491522)
		(mid 385.094734 -238.567699)
		(end 385.37769 -238.491522)
		(width 0.0889)
		(layer "In13.Cu")
		(net "M_H_CPU0_SA_DQ<22>")
	)
	(arc
		(start 383.935224 -238.523272)
		(mid 384.190289 -238.566623)
		(end 384.43789 -238.491522)
		(width 0.0889)
		(layer "In13.Cu")
		(net "M_H_CPU0_SA_DQ<22>")
	)
	(arc
		(start 390.451848 -238.491522)
		(mid 390.734804 -238.567699)
		(end 391.01776 -238.491522)
		(width 0.0889)
		(layer "In13.Cu")
		(net "M_H_CPU0_SA_DQ<22>")
	)
	(arc
		(start 390.077706 -238.491522)
		(mid 390.259957 -238.441172)
		(end 390.443466 -238.486696)
		(width 0.0889)
		(layer "In13.Cu")
		(net "M_H_CPU0_SA_DQ<22>")
	)
	(arc
		(start 391.958068 -238.491522)
		(mid 392.140573 -238.441045)
		(end 392.324336 -238.486696)
		(width 0.0889)
		(layer "In13.Cu")
		(net "M_H_CPU0_SA_DQ<22>")
	)
	(arc
		(start 388.571994 -238.491522)
		(mid 388.85495 -238.567699)
		(end 389.137906 -238.491522)
		(width 0.0889)
		(layer "In13.Cu")
		(net "M_H_CPU0_SA_DQ<22>")
	)
	(arc
		(start 386.691886 -238.491522)
		(mid 386.974842 -238.567699)
		(end 387.257798 -238.491522)
		(width 0.0889)
		(layer "In13.Cu")
		(net "M_H_CPU0_SA_DQ<22>")
	)
	(arc
		(start 385.37769 -238.491522)
		(mid 385.559941 -238.441172)
		(end 385.74345 -238.486696)
		(width 0.0889)
		(layer "In13.Cu")
		(net "M_H_CPU0_SA_DQ<22>")
	)
	(segment
		(start 382.277874 -239.08004)
		(end 382.744726 -238.814102)
		(width 0.10668)
		(layer "F.Cu")
		(net "M_H_CPU0_SA_DQ<21>")
	)
	(segment
		(start 388.197852 -239.136682)
		(end 388.206234 -239.141508)
		(width 0.0889)
		(layer "In13.Cu")
		(net "M_H_CPU0_SA_DQ<21>")
	)
	(segment
		(start 397.85417 -237.33252)
		(end 405.753062 -229.433628)
		(width 0.14478)
		(layer "In13.Cu")
		(net "M_H_CPU0_SA_DQ<21>")
	)
	(segment
		(start 405.753062 -229.433628)
		(end 405.753062 -227.664772)
		(width 0.14478)
		(layer "In13.Cu")
		(net "M_H_CPU0_SA_DQ<21>")
	)
	(segment
		(start 393.084812 -239.187228)
		(end 393.262866 -239.187228)
		(width 0.0889)
		(layer "In13.Cu")
		(net "M_H_CPU0_SA_DQ<21>")
	)
	(segment
		(start 418.469572 -224.110042)
		(end 421.731186 -224.110042)
		(width 0.14478)
		(layer "In13.Cu")
		(net "M_H_CPU0_SA_DQ<21>")
	)
	(segment
		(start 405.753062 -227.664772)
		(end 408.102562 -225.315272)
		(width 0.14478)
		(layer "In13.Cu")
		(net "M_H_CPU0_SA_DQ<21>")
	)
	(segment
		(start 383.497836 -239.136682)
		(end 383.506218 -239.141508)
		(width 0.0889)
		(layer "In13.Cu")
		(net "M_H_CPU0_SA_DQ<21>")
	)
	(segment
		(start 393.262866 -239.187228)
		(end 395.117574 -237.33252)
		(width 0.0889)
		(layer "In13.Cu")
		(net "M_H_CPU0_SA_DQ<21>")
	)
	(segment
		(start 382.590802 -239.079532)
		(end 382.613154 -239.162844)
		(width 0.0889)
		(layer "In13.Cu")
		(net "M_H_CPU0_SA_DQ<21>")
	)
	(segment
		(start 392.323828 -239.141508)
		(end 392.331956 -239.136682)
		(width 0.0889)
		(layer "In13.Cu")
		(net "M_H_CPU0_SA_DQ<21>")
	)
	(segment
		(start 414.16224 -224.110042)
		(end 415.012124 -223.260158)
		(width 0.14478)
		(layer "In13.Cu")
		(net "M_H_CPU0_SA_DQ<21>")
	)
	(segment
		(start 395.806676 -237.33252)
		(end 397.85417 -237.33252)
		(width 0.14478)
		(layer "In13.Cu")
		(net "M_H_CPU0_SA_DQ<21>")
	)
	(segment
		(start 390.443466 -239.141508)
		(end 390.451848 -239.136682)
		(width 0.0889)
		(layer "In13.Cu")
		(net "M_H_CPU0_SA_DQ<21>")
	)
	(segment
		(start 387.257798 -239.136682)
		(end 387.26618 -239.141508)
		(width 0.0889)
		(layer "In13.Cu")
		(net "M_H_CPU0_SA_DQ<21>")
	)
	(segment
		(start 382.744726 -238.814102)
		(end 382.590802 -239.079532)
		(width 0.0889)
		(layer "In13.Cu")
		(net "M_H_CPU0_SA_DQ<21>")
	)
	(segment
		(start 415.012124 -223.260158)
		(end 417.619688 -223.260158)
		(width 0.14478)
		(layer "In13.Cu")
		(net "M_H_CPU0_SA_DQ<21>")
	)
	(segment
		(start 408.102562 -225.315272)
		(end 409.082494 -225.315272)
		(width 0.14478)
		(layer "In13.Cu")
		(net "M_H_CPU0_SA_DQ<21>")
	)
	(segment
		(start 395.117574 -237.33252)
		(end 395.806676 -237.33252)
		(width 0.0889)
		(layer "In13.Cu")
		(net "M_H_CPU0_SA_DQ<21>")
	)
	(segment
		(start 391.391902 -239.136682)
		(end 391.402316 -239.130586)
		(width 0.0889)
		(layer "In13.Cu")
		(net "M_H_CPU0_SA_DQ<21>")
	)
	(segment
		(start 417.619688 -223.260158)
		(end 418.469572 -224.110042)
		(width 0.14478)
		(layer "In13.Cu")
		(net "M_H_CPU0_SA_DQ<21>")
	)
	(segment
		(start 422.156128 -223.6851)
		(end 424.012106 -223.6851)
		(width 0.14478)
		(layer "In13.Cu")
		(net "M_H_CPU0_SA_DQ<21>")
	)
	(segment
		(start 421.731186 -224.110042)
		(end 422.156128 -223.6851)
		(width 0.14478)
		(layer "In13.Cu")
		(net "M_H_CPU0_SA_DQ<21>")
	)
	(segment
		(start 410.287724 -224.110042)
		(end 414.16224 -224.110042)
		(width 0.14478)
		(layer "In13.Cu")
		(net "M_H_CPU0_SA_DQ<21>")
	)
	(segment
		(start 385.74345 -239.141508)
		(end 385.751832 -239.136682)
		(width 0.0889)
		(layer "In13.Cu")
		(net "M_H_CPU0_SA_DQ<21>")
	)
	(segment
		(start 386.683504 -239.141508)
		(end 386.691886 -239.136682)
		(width 0.0889)
		(layer "In13.Cu")
		(net "M_H_CPU0_SA_DQ<21>")
	)
	(segment
		(start 391.01776 -239.136682)
		(end 391.026142 -239.141508)
		(width 0.0889)
		(layer "In13.Cu")
		(net "M_H_CPU0_SA_DQ<21>")
	)
	(segment
		(start 409.082494 -225.315272)
		(end 410.287724 -224.110042)
		(width 0.14478)
		(layer "In13.Cu")
		(net "M_H_CPU0_SA_DQ<21>")
	)
	(arc
		(start 383.871978 -239.136682)
		(mid 384.154934 -239.060505)
		(end 384.43789 -239.136682)
		(width 0.0889)
		(layer "In13.Cu")
		(net "M_H_CPU0_SA_DQ<21>")
	)
	(arc
		(start 386.317744 -239.136682)
		(mid 386.499995 -239.187032)
		(end 386.683504 -239.141508)
		(width 0.0889)
		(layer "In13.Cu")
		(net "M_H_CPU0_SA_DQ<21>")
	)
	(arc
		(start 384.43789 -239.136682)
		(mid 384.624834 -239.186937)
		(end 384.811778 -239.136682)
		(width 0.0889)
		(layer "In13.Cu")
		(net "M_H_CPU0_SA_DQ<21>")
	)
	(arc
		(start 390.077706 -239.136682)
		(mid 390.259957 -239.187032)
		(end 390.443466 -239.141508)
		(width 0.0889)
		(layer "In13.Cu")
		(net "M_H_CPU0_SA_DQ<21>")
	)
	(arc
		(start 388.571994 -239.136682)
		(mid 388.85495 -239.060505)
		(end 389.137906 -239.136682)
		(width 0.0889)
		(layer "In13.Cu")
		(net "M_H_CPU0_SA_DQ<21>")
	)
	(arc
		(start 387.26618 -239.141508)
		(mid 387.449688 -239.187002)
		(end 387.63194 -239.136682)
		(width 0.0889)
		(layer "In13.Cu")
		(net "M_H_CPU0_SA_DQ<21>")
	)
	(arc
		(start 388.206234 -239.141508)
		(mid 388.389742 -239.187002)
		(end 388.571994 -239.136682)
		(width 0.0889)
		(layer "In13.Cu")
		(net "M_H_CPU0_SA_DQ<21>")
	)
	(arc
		(start 389.137906 -239.136682)
		(mid 389.32485 -239.186937)
		(end 389.511794 -239.136682)
		(width 0.0889)
		(layer "In13.Cu")
		(net "M_H_CPU0_SA_DQ<21>")
	)
	(arc
		(start 391.026142 -239.141508)
		(mid 391.20965 -239.187002)
		(end 391.391902 -239.136682)
		(width 0.0889)
		(layer "In13.Cu")
		(net "M_H_CPU0_SA_DQ<21>")
	)
	(arc
		(start 382.931924 -239.136682)
		(mid 383.21488 -239.060505)
		(end 383.497836 -239.136682)
		(width 0.0889)
		(layer "In13.Cu")
		(net "M_H_CPU0_SA_DQ<21>")
	)
	(arc
		(start 391.958068 -239.136682)
		(mid 392.140319 -239.187032)
		(end 392.323828 -239.141508)
		(width 0.0889)
		(layer "In13.Cu")
		(net "M_H_CPU0_SA_DQ<21>")
	)
	(arc
		(start 384.811778 -239.136682)
		(mid 385.094734 -239.060505)
		(end 385.37769 -239.136682)
		(width 0.0889)
		(layer "In13.Cu")
		(net "M_H_CPU0_SA_DQ<21>")
	)
	(arc
		(start 382.613154 -239.162844)
		(mid 382.775486 -239.185662)
		(end 382.931924 -239.136682)
		(width 0.0889)
		(layer "In13.Cu")
		(net "M_H_CPU0_SA_DQ<21>")
	)
	(arc
		(start 390.451848 -239.136682)
		(mid 390.734804 -239.060505)
		(end 391.01776 -239.136682)
		(width 0.0889)
		(layer "In13.Cu")
		(net "M_H_CPU0_SA_DQ<21>")
	)
	(arc
		(start 385.37769 -239.136682)
		(mid 385.559941 -239.187032)
		(end 385.74345 -239.141508)
		(width 0.0889)
		(layer "In13.Cu")
		(net "M_H_CPU0_SA_DQ<21>")
	)
	(arc
		(start 392.331956 -239.136682)
		(mid 392.614912 -239.060505)
		(end 392.897868 -239.136682)
		(width 0.0889)
		(layer "In13.Cu")
		(net "M_H_CPU0_SA_DQ<21>")
	)
	(arc
		(start 387.63194 -239.136682)
		(mid 387.914896 -239.060505)
		(end 388.197852 -239.136682)
		(width 0.0889)
		(layer "In13.Cu")
		(net "M_H_CPU0_SA_DQ<21>")
	)
	(arc
		(start 391.402316 -239.130586)
		(mid 391.681002 -239.060366)
		(end 391.958068 -239.136682)
		(width 0.0889)
		(layer "In13.Cu")
		(net "M_H_CPU0_SA_DQ<21>")
	)
	(arc
		(start 383.506218 -239.141508)
		(mid 383.689726 -239.187002)
		(end 383.871978 -239.136682)
		(width 0.0889)
		(layer "In13.Cu")
		(net "M_H_CPU0_SA_DQ<21>")
	)
	(arc
		(start 389.511794 -239.136682)
		(mid 389.79475 -239.060505)
		(end 390.077706 -239.136682)
		(width 0.0889)
		(layer "In13.Cu")
		(net "M_H_CPU0_SA_DQ<21>")
	)
	(arc
		(start 386.691886 -239.136682)
		(mid 386.974842 -239.060505)
		(end 387.257798 -239.136682)
		(width 0.0889)
		(layer "In13.Cu")
		(net "M_H_CPU0_SA_DQ<21>")
	)
	(arc
		(start 385.751832 -239.136682)
		(mid 386.034788 -239.060505)
		(end 386.317744 -239.136682)
		(width 0.0889)
		(layer "In13.Cu")
		(net "M_H_CPU0_SA_DQ<21>")
	)
	(arc
		(start 392.897868 -239.136682)
		(mid 392.988001 -239.174302)
		(end 393.084812 -239.187228)
		(width 0.0889)
		(layer "In13.Cu")
		(net "M_H_CPU0_SA_DQ<21>")
	)
	(segment
		(start 383.688082 -238.270034)
		(end 384.154934 -238.004096)
		(width 0.10668)
		(layer "F.Cu")
		(net "M_H_CPU0_SA_DQ<20>")
	)
	(segment
		(start 418.34562 -222.419672)
		(end 417.486084 -221.560136)
		(width 0.14478)
		(layer "In13.Cu")
		(net "M_H_CPU0_SA_DQ<20>")
	)
	(segment
		(start 389.041894 -238.326676)
		(end 389.033512 -238.331502)
		(width 0.0889)
		(layer "In13.Cu")
		(net "M_H_CPU0_SA_DQ<20>")
	)
	(segment
		(start 423.494454 -221.985078)
		(end 423.349674 -222.129858)
		(width 0.14478)
		(layer "In13.Cu")
		(net "M_H_CPU0_SA_DQ<20>")
	)
	(segment
		(start 395.796262 -236.4232)
		(end 395.439392 -236.4232)
		(width 0.0889)
		(layer "In13.Cu")
		(net "M_H_CPU0_SA_DQ<20>")
	)
	(segment
		(start 417.486084 -221.560136)
		(end 415.120328 -221.560136)
		(width 0.14478)
		(layer "In13.Cu")
		(net "M_H_CPU0_SA_DQ<20>")
	)
	(segment
		(start 393.61237 -238.250222)
		(end 393.084812 -238.250222)
		(width 0.0889)
		(layer "In13.Cu")
		(net "M_H_CPU0_SA_DQ<20>")
	)
	(segment
		(start 395.439392 -236.4232)
		(end 393.61237 -238.250222)
		(width 0.0889)
		(layer "In13.Cu")
		(net "M_H_CPU0_SA_DQ<20>")
	)
	(segment
		(start 415.120328 -221.560136)
		(end 414.270444 -222.41002)
		(width 0.14478)
		(layer "In13.Cu")
		(net "M_H_CPU0_SA_DQ<20>")
	)
	(segment
		(start 422.018206 -221.985078)
		(end 421.583612 -222.419672)
		(width 0.14478)
		(layer "In13.Cu")
		(net "M_H_CPU0_SA_DQ<20>")
	)
	(segment
		(start 384.023108 -238.352838)
		(end 384.000756 -238.269526)
		(width 0.0889)
		(layer "In13.Cu")
		(net "M_H_CPU0_SA_DQ<20>")
	)
	(segment
		(start 410.299662 -222.41002)
		(end 408.29357 -224.416112)
		(width 0.14478)
		(layer "In13.Cu")
		(net "M_H_CPU0_SA_DQ<20>")
	)
	(segment
		(start 404.853902 -229.024688)
		(end 397.45539 -236.4232)
		(width 0.14478)
		(layer "In13.Cu")
		(net "M_H_CPU0_SA_DQ<20>")
	)
	(segment
		(start 384.916172 -238.331502)
		(end 384.90779 -238.326676)
		(width 0.0889)
		(layer "In13.Cu")
		(net "M_H_CPU0_SA_DQ<20>")
	)
	(segment
		(start 423.349674 -222.129858)
		(end 423.349674 -222.523304)
		(width 0.14478)
		(layer "In13.Cu")
		(net "M_H_CPU0_SA_DQ<20>")
	)
	(segment
		(start 423.204894 -222.668084)
		(end 422.943274 -222.668084)
		(width 0.14478)
		(layer "In13.Cu")
		(net "M_H_CPU0_SA_DQ<20>")
	)
	(segment
		(start 388.10184 -238.326676)
		(end 388.093458 -238.331502)
		(width 0.0889)
		(layer "In13.Cu")
		(net "M_H_CPU0_SA_DQ<20>")
	)
	(segment
		(start 414.270444 -222.41002)
		(end 410.299662 -222.41002)
		(width 0.14478)
		(layer "In13.Cu")
		(net "M_H_CPU0_SA_DQ<20>")
	)
	(segment
		(start 408.29357 -224.416112)
		(end 407.094182 -224.416112)
		(width 0.14478)
		(layer "In13.Cu")
		(net "M_H_CPU0_SA_DQ<20>")
	)
	(segment
		(start 422.653714 -221.985078)
		(end 422.018206 -221.985078)
		(width 0.14478)
		(layer "In13.Cu")
		(net "M_H_CPU0_SA_DQ<20>")
	)
	(segment
		(start 421.583612 -222.419672)
		(end 418.34562 -222.419672)
		(width 0.14478)
		(layer "In13.Cu")
		(net "M_H_CPU0_SA_DQ<20>")
	)
	(segment
		(start 389.616188 -238.331502)
		(end 389.607806 -238.326676)
		(width 0.0889)
		(layer "In13.Cu")
		(net "M_H_CPU0_SA_DQ<20>")
	)
	(segment
		(start 392.428476 -238.326676)
		(end 392.418062 -238.32058)
		(width 0.0889)
		(layer "In13.Cu")
		(net "M_H_CPU0_SA_DQ<20>")
	)
	(segment
		(start 407.094182 -224.416112)
		(end 404.853902 -226.656392)
		(width 0.14478)
		(layer "In13.Cu")
		(net "M_H_CPU0_SA_DQ<20>")
	)
	(segment
		(start 404.853902 -226.656392)
		(end 404.853902 -229.024688)
		(width 0.14478)
		(layer "In13.Cu")
		(net "M_H_CPU0_SA_DQ<20>")
	)
	(segment
		(start 422.943274 -222.668084)
		(end 422.798494 -222.523304)
		(width 0.14478)
		(layer "In13.Cu")
		(net "M_H_CPU0_SA_DQ<20>")
	)
	(segment
		(start 422.798494 -222.523304)
		(end 422.798494 -222.129858)
		(width 0.14478)
		(layer "In13.Cu")
		(net "M_H_CPU0_SA_DQ<20>")
	)
	(segment
		(start 391.496042 -238.331502)
		(end 391.48766 -238.326676)
		(width 0.0889)
		(layer "In13.Cu")
		(net "M_H_CPU0_SA_DQ<20>")
	)
	(segment
		(start 397.45539 -236.4232)
		(end 395.796262 -236.4232)
		(width 0.14478)
		(layer "In13.Cu")
		(net "M_H_CPU0_SA_DQ<20>")
	)
	(segment
		(start 384.000756 -238.269526)
		(end 384.154934 -238.004096)
		(width 0.0889)
		(layer "In13.Cu")
		(net "M_H_CPU0_SA_DQ<20>")
	)
	(segment
		(start 384.341878 -238.326676)
		(end 384.333496 -238.331502)
		(width 0.0889)
		(layer "In13.Cu")
		(net "M_H_CPU0_SA_DQ<20>")
	)
	(segment
		(start 424.012106 -221.985078)
		(end 423.494454 -221.985078)
		(width 0.14478)
		(layer "In13.Cu")
		(net "M_H_CPU0_SA_DQ<20>")
	)
	(segment
		(start 423.349674 -222.523304)
		(end 423.204894 -222.668084)
		(width 0.14478)
		(layer "In13.Cu")
		(net "M_H_CPU0_SA_DQ<20>")
	)
	(segment
		(start 422.798494 -222.129858)
		(end 422.653714 -221.985078)
		(width 0.14478)
		(layer "In13.Cu")
		(net "M_H_CPU0_SA_DQ<20>")
	)
	(segment
		(start 385.856226 -238.331502)
		(end 385.847844 -238.326676)
		(width 0.0889)
		(layer "In13.Cu")
		(net "M_H_CPU0_SA_DQ<20>")
	)
	(arc
		(start 386.221986 -238.326676)
		(mid 386.039735 -238.377026)
		(end 385.856226 -238.331502)
		(width 0.0889)
		(layer "In13.Cu")
		(net "M_H_CPU0_SA_DQ<20>")
	)
	(arc
		(start 385.281932 -238.326676)
		(mid 385.099681 -238.377026)
		(end 384.916172 -238.331502)
		(width 0.0889)
		(layer "In13.Cu")
		(net "M_H_CPU0_SA_DQ<20>")
	)
	(arc
		(start 387.727698 -238.326676)
		(mid 387.444742 -238.250499)
		(end 387.161786 -238.326676)
		(width 0.0889)
		(layer "In13.Cu")
		(net "M_H_CPU0_SA_DQ<20>")
	)
	(arc
		(start 393.084812 -238.250222)
		(mid 392.929451 -238.272047)
		(end 392.786108 -238.33582)
		(width 0.0889)
		(layer "In13.Cu")
		(net "M_H_CPU0_SA_DQ<20>")
	)
	(arc
		(start 387.161786 -238.326676)
		(mid 386.974842 -238.376931)
		(end 386.787898 -238.326676)
		(width 0.0889)
		(layer "In13.Cu")
		(net "M_H_CPU0_SA_DQ<20>")
	)
	(arc
		(start 389.981948 -238.326676)
		(mid 389.799697 -238.377026)
		(end 389.616188 -238.331502)
		(width 0.0889)
		(layer "In13.Cu")
		(net "M_H_CPU0_SA_DQ<20>")
	)
	(arc
		(start 384.333496 -238.331502)
		(mid 384.180626 -238.376143)
		(end 384.023108 -238.352838)
		(width 0.0889)
		(layer "In13.Cu")
		(net "M_H_CPU0_SA_DQ<20>")
	)
	(arc
		(start 388.093458 -238.331502)
		(mid 387.90995 -238.376996)
		(end 387.727698 -238.326676)
		(width 0.0889)
		(layer "In13.Cu")
		(net "M_H_CPU0_SA_DQ<20>")
	)
	(arc
		(start 391.86231 -238.326676)
		(mid 391.679805 -238.377153)
		(end 391.496042 -238.331502)
		(width 0.0889)
		(layer "In13.Cu")
		(net "M_H_CPU0_SA_DQ<20>")
	)
	(arc
		(start 390.921748 -238.326676)
		(mid 390.734804 -238.376931)
		(end 390.54786 -238.326676)
		(width 0.0889)
		(layer "In13.Cu")
		(net "M_H_CPU0_SA_DQ<20>")
	)
	(arc
		(start 386.787898 -238.326676)
		(mid 386.504942 -238.250499)
		(end 386.221986 -238.326676)
		(width 0.0889)
		(layer "In13.Cu")
		(net "M_H_CPU0_SA_DQ<20>")
	)
	(arc
		(start 392.786108 -238.33582)
		(mid 392.606126 -238.37692)
		(end 392.428476 -238.326676)
		(width 0.0889)
		(layer "In13.Cu")
		(net "M_H_CPU0_SA_DQ<20>")
	)
	(arc
		(start 385.847844 -238.326676)
		(mid 385.564888 -238.250499)
		(end 385.281932 -238.326676)
		(width 0.0889)
		(layer "In13.Cu")
		(net "M_H_CPU0_SA_DQ<20>")
	)
	(arc
		(start 389.033512 -238.331502)
		(mid 388.850004 -238.376996)
		(end 388.667752 -238.326676)
		(width 0.0889)
		(layer "In13.Cu")
		(net "M_H_CPU0_SA_DQ<20>")
	)
	(arc
		(start 390.54786 -238.326676)
		(mid 390.264904 -238.250499)
		(end 389.981948 -238.326676)
		(width 0.0889)
		(layer "In13.Cu")
		(net "M_H_CPU0_SA_DQ<20>")
	)
	(arc
		(start 389.607806 -238.326676)
		(mid 389.32485 -238.250499)
		(end 389.041894 -238.326676)
		(width 0.0889)
		(layer "In13.Cu")
		(net "M_H_CPU0_SA_DQ<20>")
	)
	(arc
		(start 388.667752 -238.326676)
		(mid 388.384796 -238.250499)
		(end 388.10184 -238.326676)
		(width 0.0889)
		(layer "In13.Cu")
		(net "M_H_CPU0_SA_DQ<20>")
	)
	(arc
		(start 384.90779 -238.326676)
		(mid 384.624834 -238.250499)
		(end 384.341878 -238.326676)
		(width 0.0889)
		(layer "In13.Cu")
		(net "M_H_CPU0_SA_DQ<20>")
	)
	(arc
		(start 392.418062 -238.32058)
		(mid 392.139376 -238.25036)
		(end 391.86231 -238.326676)
		(width 0.0889)
		(layer "In13.Cu")
		(net "M_H_CPU0_SA_DQ<20>")
	)
	(arc
		(start 391.48766 -238.326676)
		(mid 391.204704 -238.250499)
		(end 390.921748 -238.326676)
		(width 0.0889)
		(layer "In13.Cu")
		(net "M_H_CPU0_SA_DQ<20>")
	)
	(segment
		(start 382.277874 -226.120198)
		(end 382.744726 -225.85426)
		(width 0.10668)
		(layer "F.Cu")
		(net "M_H_CPU0_SA_DQ<1>")
	)
	(segment
		(start 389.475472 -224.57791)
		(end 389.511794 -224.556828)
		(width 0.0889)
		(layer "In13.Cu")
		(net "M_H_CPU0_SA_DQ<1>")
	)
	(segment
		(start 382.590802 -226.11969)
		(end 382.613154 -226.203002)
		(width 0.0889)
		(layer "In13.Cu")
		(net "M_H_CPU0_SA_DQ<1>")
	)
	(segment
		(start 390.887204 -222.146876)
		(end 390.92251 -222.126556)
		(width 0.0889)
		(layer "In13.Cu")
		(net "M_H_CPU0_SA_DQ<1>")
	)
	(segment
		(start 383.497836 -226.17684)
		(end 383.506218 -226.181666)
		(width 0.0889)
		(layer "In13.Cu")
		(net "M_H_CPU0_SA_DQ<1>")
	)
	(segment
		(start 391.11047 -221.545404)
		(end 390.962896 -221.39783)
		(width 0.0889)
		(layer "In13.Cu")
		(net "M_H_CPU0_SA_DQ<1>")
	)
	(segment
		(start 389.511794 -224.556828)
		(end 389.543544 -224.53854)
		(width 0.0889)
		(layer "In13.Cu")
		(net "M_H_CPU0_SA_DQ<1>")
	)
	(segment
		(start 389.941816 -223.770444)
		(end 389.982202 -223.746822)
		(width 0.0889)
		(layer "In13.Cu")
		(net "M_H_CPU0_SA_DQ<1>")
	)
	(segment
		(start 390.92251 -222.126556)
		(end 390.957054 -222.10649)
		(width 0.0889)
		(layer "In13.Cu")
		(net "M_H_CPU0_SA_DQ<1>")
	)
	(segment
		(start 387.257798 -226.17684)
		(end 387.26618 -226.181666)
		(width 0.0889)
		(layer "In13.Cu")
		(net "M_H_CPU0_SA_DQ<1>")
	)
	(segment
		(start 385.74345 -226.181666)
		(end 385.751832 -226.17684)
		(width 0.0889)
		(layer "In13.Cu")
		(net "M_H_CPU0_SA_DQ<1>")
	)
	(segment
		(start 424.011598 -199.035924)
		(end 424.012106 -199.035162)
		(width 0.14478)
		(layer "In13.Cu")
		(net "M_H_CPU0_SA_DQ<1>")
	)
	(segment
		(start 407.373328 -199.870314)
		(end 412.55315 -199.870314)
		(width 0.14478)
		(layer "In13.Cu")
		(net "M_H_CPU0_SA_DQ<1>")
	)
	(segment
		(start 389.002778 -225.389694)
		(end 389.041894 -225.366834)
		(width 0.0889)
		(layer "In13.Cu")
		(net "M_H_CPU0_SA_DQ<1>")
	)
	(segment
		(start 390.418828 -222.95612)
		(end 390.452356 -222.936562)
		(width 0.0889)
		(layer "In13.Cu")
		(net "M_H_CPU0_SA_DQ<1>")
	)
	(segment
		(start 397.628618 -209.615024)
		(end 407.373328 -199.870314)
		(width 0.14478)
		(layer "In13.Cu")
		(net "M_H_CPU0_SA_DQ<1>")
	)
	(segment
		(start 390.962896 -217.497406)
		(end 397.628618 -210.831684)
		(width 0.14478)
		(layer "In13.Cu")
		(net "M_H_CPU0_SA_DQ<1>")
	)
	(segment
		(start 418.62121 -199.010524)
		(end 419.706552 -199.460104)
		(width 0.14478)
		(layer "In13.Cu")
		(net "M_H_CPU0_SA_DQ<1>")
	)
	(segment
		(start 389.041894 -225.366834)
		(end 389.073644 -225.348546)
		(width 0.0889)
		(layer "In13.Cu")
		(net "M_H_CPU0_SA_DQ<1>")
	)
	(segment
		(start 390.452356 -222.936562)
		(end 390.482582 -222.919036)
		(width 0.0889)
		(layer "In13.Cu")
		(net "M_H_CPU0_SA_DQ<1>")
	)
	(segment
		(start 390.962896 -221.39783)
		(end 390.962896 -221.28861)
		(width 0.0889)
		(layer "In13.Cu")
		(net "M_H_CPU0_SA_DQ<1>")
	)
	(segment
		(start 388.571994 -226.17684)
		(end 388.602474 -226.15906)
		(width 0.0889)
		(layer "In13.Cu")
		(net "M_H_CPU0_SA_DQ<1>")
	)
	(segment
		(start 391.11047 -221.80423)
		(end 391.11047 -221.545404)
		(width 0.0889)
		(layer "In13.Cu")
		(net "M_H_CPU0_SA_DQ<1>")
	)
	(segment
		(start 382.744726 -225.85426)
		(end 382.590802 -226.11969)
		(width 0.0889)
		(layer "In13.Cu")
		(net "M_H_CPU0_SA_DQ<1>")
	)
	(segment
		(start 397.628618 -210.831684)
		(end 397.628618 -209.615024)
		(width 0.14478)
		(layer "In13.Cu")
		(net "M_H_CPU0_SA_DQ<1>")
	)
	(segment
		(start 388.197852 -226.17684)
		(end 388.206234 -226.181666)
		(width 0.0889)
		(layer "In13.Cu")
		(net "M_H_CPU0_SA_DQ<1>")
	)
	(segment
		(start 414.628838 -199.010524)
		(end 418.62121 -199.010524)
		(width 0.14478)
		(layer "In13.Cu")
		(net "M_H_CPU0_SA_DQ<1>")
	)
	(segment
		(start 419.706552 -199.460104)
		(end 421.878506 -199.460104)
		(width 0.14478)
		(layer "In13.Cu")
		(net "M_H_CPU0_SA_DQ<1>")
	)
	(segment
		(start 412.55315 -199.870314)
		(end 414.628838 -199.010524)
		(width 0.14478)
		(layer "In13.Cu")
		(net "M_H_CPU0_SA_DQ<1>")
	)
	(segment
		(start 390.962896 -221.28861)
		(end 390.962896 -217.497406)
		(width 0.14478)
		(layer "In13.Cu")
		(net "M_H_CPU0_SA_DQ<1>")
	)
	(segment
		(start 421.878506 -199.460104)
		(end 424.011598 -199.035924)
		(width 0.14478)
		(layer "In13.Cu")
		(net "M_H_CPU0_SA_DQ<1>")
	)
	(segment
		(start 386.683504 -226.181666)
		(end 386.691886 -226.17684)
		(width 0.0889)
		(layer "In13.Cu")
		(net "M_H_CPU0_SA_DQ<1>")
	)
	(segment
		(start 389.982202 -223.746822)
		(end 390.012936 -223.729042)
		(width 0.0889)
		(layer "In13.Cu")
		(net "M_H_CPU0_SA_DQ<1>")
	)
	(arc
		(start 382.613154 -226.203002)
		(mid 382.775486 -226.22582)
		(end 382.931924 -226.17684)
		(width 0.0889)
		(layer "In13.Cu")
		(net "M_H_CPU0_SA_DQ<1>")
	)
	(arc
		(start 382.931924 -226.17684)
		(mid 383.21488 -226.100663)
		(end 383.497836 -226.17684)
		(width 0.0889)
		(layer "In13.Cu")
		(net "M_H_CPU0_SA_DQ<1>")
	)
	(arc
		(start 387.26618 -226.181666)
		(mid 387.449688 -226.22716)
		(end 387.63194 -226.17684)
		(width 0.0889)
		(layer "In13.Cu")
		(net "M_H_CPU0_SA_DQ<1>")
	)
	(arc
		(start 390.957054 -222.10649)
		(mid 391.06994 -221.973719)
		(end 391.11047 -221.80423)
		(width 0.0889)
		(layer "In13.Cu")
		(net "M_H_CPU0_SA_DQ<1>")
	)
	(arc
		(start 384.811778 -226.17684)
		(mid 385.094734 -226.100663)
		(end 385.37769 -226.17684)
		(width 0.0889)
		(layer "In13.Cu")
		(net "M_H_CPU0_SA_DQ<1>")
	)
	(arc
		(start 389.2296 -225.044254)
		(mid 389.294836 -224.780663)
		(end 389.475472 -224.57791)
		(width 0.0889)
		(layer "In13.Cu")
		(net "M_H_CPU0_SA_DQ<1>")
	)
	(arc
		(start 386.317744 -226.17684)
		(mid 386.499995 -226.22719)
		(end 386.683504 -226.181666)
		(width 0.0889)
		(layer "In13.Cu")
		(net "M_H_CPU0_SA_DQ<1>")
	)
	(arc
		(start 389.6995 -224.234248)
		(mid 389.763793 -223.972643)
		(end 389.941816 -223.770444)
		(width 0.0889)
		(layer "In13.Cu")
		(net "M_H_CPU0_SA_DQ<1>")
	)
	(arc
		(start 385.37769 -226.17684)
		(mid 385.559941 -226.22719)
		(end 385.74345 -226.181666)
		(width 0.0889)
		(layer "In13.Cu")
		(net "M_H_CPU0_SA_DQ<1>")
	)
	(arc
		(start 388.759446 -225.85426)
		(mid 388.823961 -225.592041)
		(end 389.002778 -225.389694)
		(width 0.0889)
		(layer "In13.Cu")
		(net "M_H_CPU0_SA_DQ<1>")
	)
	(arc
		(start 388.602474 -226.15906)
		(mid 388.717901 -226.025684)
		(end 388.759446 -225.85426)
		(width 0.0889)
		(layer "In13.Cu")
		(net "M_H_CPU0_SA_DQ<1>")
	)
	(arc
		(start 389.543544 -224.53854)
		(mid 389.65822 -224.405206)
		(end 389.6995 -224.234248)
		(width 0.0889)
		(layer "In13.Cu")
		(net "M_H_CPU0_SA_DQ<1>")
	)
	(arc
		(start 387.63194 -226.17684)
		(mid 387.914896 -226.100663)
		(end 388.197852 -226.17684)
		(width 0.0889)
		(layer "In13.Cu")
		(net "M_H_CPU0_SA_DQ<1>")
	)
	(arc
		(start 386.691886 -226.17684)
		(mid 386.974842 -226.100663)
		(end 387.257798 -226.17684)
		(width 0.0889)
		(layer "In13.Cu")
		(net "M_H_CPU0_SA_DQ<1>")
	)
	(arc
		(start 390.012936 -223.729042)
		(mid 390.128363 -223.595666)
		(end 390.169908 -223.424242)
		(width 0.0889)
		(layer "In13.Cu")
		(net "M_H_CPU0_SA_DQ<1>")
	)
	(arc
		(start 383.871978 -226.17684)
		(mid 384.154934 -226.100663)
		(end 384.43789 -226.17684)
		(width 0.0889)
		(layer "In13.Cu")
		(net "M_H_CPU0_SA_DQ<1>")
	)
	(arc
		(start 389.073644 -225.348546)
		(mid 389.18832 -225.215212)
		(end 389.2296 -225.044254)
		(width 0.0889)
		(layer "In13.Cu")
		(net "M_H_CPU0_SA_DQ<1>")
	)
	(arc
		(start 385.751832 -226.17684)
		(mid 386.034788 -226.100663)
		(end 386.317744 -226.17684)
		(width 0.0889)
		(layer "In13.Cu")
		(net "M_H_CPU0_SA_DQ<1>")
	)
	(arc
		(start 390.169908 -223.424242)
		(mid 390.236007 -223.159148)
		(end 390.418828 -222.95612)
		(width 0.0889)
		(layer "In13.Cu")
		(net "M_H_CPU0_SA_DQ<1>")
	)
	(arc
		(start 388.206234 -226.181666)
		(mid 388.389742 -226.22716)
		(end 388.571994 -226.17684)
		(width 0.0889)
		(layer "In13.Cu")
		(net "M_H_CPU0_SA_DQ<1>")
	)
	(arc
		(start 384.43789 -226.17684)
		(mid 384.624834 -226.227095)
		(end 384.811778 -226.17684)
		(width 0.0889)
		(layer "In13.Cu")
		(net "M_H_CPU0_SA_DQ<1>")
	)
	(arc
		(start 390.482582 -222.919036)
		(mid 390.598161 -222.785709)
		(end 390.639808 -222.614236)
		(width 0.0889)
		(layer "In13.Cu")
		(net "M_H_CPU0_SA_DQ<1>")
	)
	(arc
		(start 390.639808 -222.614236)
		(mid 390.705471 -222.349835)
		(end 390.887204 -222.146876)
		(width 0.0889)
		(layer "In13.Cu")
		(net "M_H_CPU0_SA_DQ<1>")
	)
	(arc
		(start 383.506218 -226.181666)
		(mid 383.689726 -226.22716)
		(end 383.871978 -226.17684)
		(width 0.0889)
		(layer "In13.Cu")
		(net "M_H_CPU0_SA_DQ<1>")
	)
	(segment
		(start 381.807974 -236.650022)
		(end 382.274826 -236.384084)
		(width 0.10668)
		(layer "F.Cu")
		(net "M_H_CPU0_SA_DQ<19>")
	)
	(segment
		(start 412.416752 -218.744292)
		(end 412.15564 -219.005404)
		(width 0.14478)
		(layer "In13.Cu")
		(net "M_H_CPU0_SA_DQ<19>")
	)
	(segment
		(start 410.532326 -219.625418)
		(end 410.254958 -219.902786)
		(width 0.14478)
		(layer "In13.Cu")
		(net "M_H_CPU0_SA_DQ<19>")
	)
	(segment
		(start 402.565362 -225.65106)
		(end 402.565362 -228.045772)
		(width 0.14478)
		(layer "In13.Cu")
		(net "M_H_CPU0_SA_DQ<19>")
	)
	(segment
		(start 409.16606 -219.758006)
		(end 409.02128 -219.902786)
		(width 0.14478)
		(layer "In13.Cu")
		(net "M_H_CPU0_SA_DQ<19>")
	)
	(segment
		(start 409.57246 -219.350844)
		(end 409.31084 -219.350844)
		(width 0.14478)
		(layer "In13.Cu")
		(net "M_H_CPU0_SA_DQ<19>")
	)
	(segment
		(start 410.301694 -219.190062)
		(end 410.532326 -219.420694)
		(width 0.14478)
		(layer "In13.Cu")
		(net "M_H_CPU0_SA_DQ<19>")
	)
	(segment
		(start 394.297916 -235.210858)
		(end 393.370816 -236.137958)
		(width 0.0889)
		(layer "In13.Cu")
		(net "M_H_CPU0_SA_DQ<19>")
	)
	(segment
		(start 395.456918 -233.96194)
		(end 394.840968 -234.57789)
		(width 0.0889)
		(layer "In13.Cu")
		(net "M_H_CPU0_SA_DQ<19>")
	)
	(segment
		(start 417.820348 -218.45524)
		(end 417.558728 -218.45524)
		(width 0.14478)
		(layer "In13.Cu")
		(net "M_H_CPU0_SA_DQ<19>")
	)
	(segment
		(start 409.71724 -219.758006)
		(end 409.71724 -219.495624)
		(width 0.14478)
		(layer "In13.Cu")
		(net "M_H_CPU0_SA_DQ<19>")
	)
	(segment
		(start 409.16606 -219.495624)
		(end 409.16606 -219.758006)
		(width 0.14478)
		(layer "In13.Cu")
		(net "M_H_CPU0_SA_DQ<19>")
	)
	(segment
		(start 409.71724 -219.495624)
		(end 409.57246 -219.350844)
		(width 0.14478)
		(layer "In13.Cu")
		(net "M_H_CPU0_SA_DQ<19>")
	)
	(segment
		(start 384.916172 -236.056678)
		(end 384.90779 -236.061504)
		(width 0.0889)
		(layer "In13.Cu")
		(net "M_H_CPU0_SA_DQ<19>")
	)
	(segment
		(start 413.519112 -218.744292)
		(end 413.258 -219.005404)
		(width 0.14478)
		(layer "In13.Cu")
		(net "M_H_CPU0_SA_DQ<19>")
	)
	(segment
		(start 396.649194 -233.96194)
		(end 395.768322 -233.96194)
		(width 0.14478)
		(layer "In13.Cu")
		(net "M_H_CPU0_SA_DQ<19>")
	)
	(segment
		(start 393.370816 -236.137958)
		(end 392.146028 -236.137958)
		(width 0.0889)
		(layer "In13.Cu")
		(net "M_H_CPU0_SA_DQ<19>")
	)
	(segment
		(start 418.109908 -218.160092)
		(end 417.965128 -218.304872)
		(width 0.14478)
		(layer "In13.Cu")
		(net "M_H_CPU0_SA_DQ<19>")
	)
	(segment
		(start 417.413948 -218.31046)
		(end 417.413948 -218.304872)
		(width 0.14478)
		(layer "In13.Cu")
		(net "M_H_CPU0_SA_DQ<19>")
	)
	(segment
		(start 416.311588 -218.304872)
		(end 416.166808 -218.160092)
		(width 0.14478)
		(layer "In13.Cu")
		(net "M_H_CPU0_SA_DQ<19>")
	)
	(segment
		(start 417.965128 -218.304872)
		(end 417.965128 -218.31046)
		(width 0.14478)
		(layer "In13.Cu")
		(net "M_H_CPU0_SA_DQ<19>")
	)
	(segment
		(start 410.30144 -218.985846)
		(end 410.301694 -219.190062)
		(width 0.14478)
		(layer "In13.Cu")
		(net "M_H_CPU0_SA_DQ<19>")
	)
	(segment
		(start 409.31084 -219.350844)
		(end 409.16606 -219.495624)
		(width 0.14478)
		(layer "In13.Cu")
		(net "M_H_CPU0_SA_DQ<19>")
	)
	(segment
		(start 382.524762 -236.093254)
		(end 382.42875 -236.118654)
		(width 0.0889)
		(layer "In13.Cu")
		(net "M_H_CPU0_SA_DQ<19>")
	)
	(segment
		(start 389.041894 -236.061504)
		(end 389.033512 -236.056678)
		(width 0.0889)
		(layer "In13.Cu")
		(net "M_H_CPU0_SA_DQ<19>")
	)
	(segment
		(start 410.48686 -218.800426)
		(end 410.30144 -218.985846)
		(width 0.14478)
		(layer "In13.Cu")
		(net "M_H_CPU0_SA_DQ<19>")
	)
	(segment
		(start 417.269168 -218.160092)
		(end 417.007548 -218.160092)
		(width 0.14478)
		(layer "In13.Cu")
		(net "M_H_CPU0_SA_DQ<19>")
	)
	(segment
		(start 419.912038 -218.585034)
		(end 419.496748 -219.000324)
		(width 0.14478)
		(layer "In13.Cu")
		(net "M_H_CPU0_SA_DQ<19>")
	)
	(segment
		(start 416.862768 -218.31046)
		(end 416.717988 -218.45524)
		(width 0.14478)
		(layer "In13.Cu")
		(net "M_H_CPU0_SA_DQ<19>")
	)
	(segment
		(start 391.496042 -236.056678)
		(end 391.48766 -236.061504)
		(width 0.0889)
		(layer "In13.Cu")
		(net "M_H_CPU0_SA_DQ<19>")
	)
	(segment
		(start 417.413948 -218.304872)
		(end 417.269168 -218.160092)
		(width 0.14478)
		(layer "In13.Cu")
		(net "M_H_CPU0_SA_DQ<19>")
	)
	(segment
		(start 416.456368 -218.45524)
		(end 416.311588 -218.31046)
		(width 0.14478)
		(layer "In13.Cu")
		(net "M_H_CPU0_SA_DQ<19>")
	)
	(segment
		(start 416.717988 -218.45524)
		(end 416.456368 -218.45524)
		(width 0.14478)
		(layer "In13.Cu")
		(net "M_H_CPU0_SA_DQ<19>")
	)
	(segment
		(start 394.585444 -234.57789)
		(end 394.297916 -234.865418)
		(width 0.0889)
		(layer "In13.Cu")
		(net "M_H_CPU0_SA_DQ<19>")
	)
	(segment
		(start 411.12694 -219.030804)
		(end 410.922216 -219.031058)
		(width 0.14478)
		(layer "In13.Cu")
		(net "M_H_CPU0_SA_DQ<19>")
	)
	(segment
		(start 410.254958 -219.902786)
		(end 409.86202 -219.902786)
		(width 0.14478)
		(layer "In13.Cu")
		(net "M_H_CPU0_SA_DQ<19>")
	)
	(segment
		(start 410.691584 -218.800426)
		(end 410.48686 -218.800426)
		(width 0.14478)
		(layer "In13.Cu")
		(net "M_H_CPU0_SA_DQ<19>")
	)
	(segment
		(start 414.271714 -218.744292)
		(end 413.519112 -218.744292)
		(width 0.14478)
		(layer "In13.Cu")
		(net "M_H_CPU0_SA_DQ<19>")
	)
	(segment
		(start 416.166808 -218.160092)
		(end 414.855914 -218.160092)
		(width 0.14478)
		(layer "In13.Cu")
		(net "M_H_CPU0_SA_DQ<19>")
	)
	(segment
		(start 416.311588 -218.31046)
		(end 416.311588 -218.304872)
		(width 0.14478)
		(layer "In13.Cu")
		(net "M_H_CPU0_SA_DQ<19>")
	)
	(segment
		(start 417.558728 -218.45524)
		(end 417.413948 -218.31046)
		(width 0.14478)
		(layer "In13.Cu")
		(net "M_H_CPU0_SA_DQ<19>")
	)
	(segment
		(start 412.70682 -218.744292)
		(end 412.416752 -218.744292)
		(width 0.14478)
		(layer "In13.Cu")
		(net "M_H_CPU0_SA_DQ<19>")
	)
	(segment
		(start 395.768322 -233.96194)
		(end 395.456918 -233.96194)
		(width 0.0889)
		(layer "In13.Cu")
		(net "M_H_CPU0_SA_DQ<19>")
	)
	(segment
		(start 389.616188 -236.056678)
		(end 389.607806 -236.061504)
		(width 0.0889)
		(layer "In13.Cu")
		(net "M_H_CPU0_SA_DQ<19>")
	)
	(segment
		(start 410.922216 -219.031058)
		(end 410.691584 -218.800426)
		(width 0.14478)
		(layer "In13.Cu")
		(net "M_H_CPU0_SA_DQ<19>")
	)
	(segment
		(start 412.15564 -219.005404)
		(end 411.865572 -219.005404)
		(width 0.14478)
		(layer "In13.Cu")
		(net "M_H_CPU0_SA_DQ<19>")
	)
	(segment
		(start 408.313636 -219.902786)
		(end 402.565362 -225.65106)
		(width 0.14478)
		(layer "In13.Cu")
		(net "M_H_CPU0_SA_DQ<19>")
	)
	(segment
		(start 388.10184 -236.061504)
		(end 388.093458 -236.056678)
		(width 0.0889)
		(layer "In13.Cu")
		(net "M_H_CPU0_SA_DQ<19>")
	)
	(segment
		(start 394.297916 -234.865418)
		(end 394.297916 -235.210858)
		(width 0.0889)
		(layer "In13.Cu")
		(net "M_H_CPU0_SA_DQ<19>")
	)
	(segment
		(start 384.341878 -236.061504)
		(end 384.333496 -236.056678)
		(width 0.0889)
		(layer "In13.Cu")
		(net "M_H_CPU0_SA_DQ<19>")
	)
	(segment
		(start 411.60446 -218.744292)
		(end 411.413452 -218.744292)
		(width 0.14478)
		(layer "In13.Cu")
		(net "M_H_CPU0_SA_DQ<19>")
	)
	(segment
		(start 402.565362 -228.045772)
		(end 396.649194 -233.96194)
		(width 0.14478)
		(layer "In13.Cu")
		(net "M_H_CPU0_SA_DQ<19>")
	)
	(segment
		(start 382.42875 -236.118654)
		(end 382.274826 -236.384084)
		(width 0.0889)
		(layer "In13.Cu")
		(net "M_H_CPU0_SA_DQ<19>")
	)
	(segment
		(start 409.02128 -219.902786)
		(end 408.313636 -219.902786)
		(width 0.14478)
		(layer "In13.Cu")
		(net "M_H_CPU0_SA_DQ<19>")
	)
	(segment
		(start 419.496748 -219.000324)
		(end 419.173152 -219.000324)
		(width 0.14478)
		(layer "In13.Cu")
		(net "M_H_CPU0_SA_DQ<19>")
	)
	(segment
		(start 411.413452 -218.744292)
		(end 411.12694 -219.030804)
		(width 0.14478)
		(layer "In13.Cu")
		(net "M_H_CPU0_SA_DQ<19>")
	)
	(segment
		(start 383.401824 -236.061504)
		(end 383.393442 -236.056678)
		(width 0.0889)
		(layer "In13.Cu")
		(net "M_H_CPU0_SA_DQ<19>")
	)
	(segment
		(start 409.86202 -219.902786)
		(end 409.71724 -219.758006)
		(width 0.14478)
		(layer "In13.Cu")
		(net "M_H_CPU0_SA_DQ<19>")
	)
	(segment
		(start 417.007548 -218.160092)
		(end 416.862768 -218.304872)
		(width 0.14478)
		(layer "In13.Cu")
		(net "M_H_CPU0_SA_DQ<19>")
	)
	(segment
		(start 416.862768 -218.304872)
		(end 416.862768 -218.31046)
		(width 0.14478)
		(layer "In13.Cu")
		(net "M_H_CPU0_SA_DQ<19>")
	)
	(segment
		(start 385.856226 -236.056678)
		(end 385.847844 -236.061504)
		(width 0.0889)
		(layer "In13.Cu")
		(net "M_H_CPU0_SA_DQ<19>")
	)
	(segment
		(start 412.967932 -219.005404)
		(end 412.70682 -218.744292)
		(width 0.14478)
		(layer "In13.Cu")
		(net "M_H_CPU0_SA_DQ<19>")
	)
	(segment
		(start 419.173152 -219.000324)
		(end 418.33292 -218.160092)
		(width 0.14478)
		(layer "In13.Cu")
		(net "M_H_CPU0_SA_DQ<19>")
	)
	(segment
		(start 414.855914 -218.160092)
		(end 414.271714 -218.744292)
		(width 0.14478)
		(layer "In13.Cu")
		(net "M_H_CPU0_SA_DQ<19>")
	)
	(segment
		(start 418.33292 -218.160092)
		(end 418.109908 -218.160092)
		(width 0.14478)
		(layer "In13.Cu")
		(net "M_H_CPU0_SA_DQ<19>")
	)
	(segment
		(start 411.865572 -219.005404)
		(end 411.60446 -218.744292)
		(width 0.14478)
		(layer "In13.Cu")
		(net "M_H_CPU0_SA_DQ<19>")
	)
	(segment
		(start 394.840968 -234.57789)
		(end 394.585444 -234.57789)
		(width 0.0889)
		(layer "In13.Cu")
		(net "M_H_CPU0_SA_DQ<19>")
	)
	(segment
		(start 410.532326 -219.420694)
		(end 410.532326 -219.625418)
		(width 0.14478)
		(layer "In13.Cu")
		(net "M_H_CPU0_SA_DQ<19>")
	)
	(segment
		(start 413.258 -219.005404)
		(end 412.967932 -219.005404)
		(width 0.14478)
		(layer "In13.Cu")
		(net "M_H_CPU0_SA_DQ<19>")
	)
	(segment
		(start 417.965128 -218.31046)
		(end 417.820348 -218.45524)
		(width 0.14478)
		(layer "In13.Cu")
		(net "M_H_CPU0_SA_DQ<19>")
	)
	(arc
		(start 391.48766 -236.061504)
		(mid 391.204704 -236.137681)
		(end 390.921748 -236.061504)
		(width 0.0889)
		(layer "In13.Cu")
		(net "M_H_CPU0_SA_DQ<19>")
	)
	(arc
		(start 383.027682 -236.061504)
		(mid 382.779969 -236.136724)
		(end 382.524762 -236.093254)
		(width 0.0889)
		(layer "In13.Cu")
		(net "M_H_CPU0_SA_DQ<19>")
	)
	(arc
		(start 391.86231 -236.061504)
		(mid 391.679805 -236.011027)
		(end 391.496042 -236.056678)
		(width 0.0889)
		(layer "In13.Cu")
		(net "M_H_CPU0_SA_DQ<19>")
	)
	(arc
		(start 388.093458 -236.056678)
		(mid 387.90995 -236.011184)
		(end 387.727698 -236.061504)
		(width 0.0889)
		(layer "In13.Cu")
		(net "M_H_CPU0_SA_DQ<19>")
	)
	(arc
		(start 387.727698 -236.061504)
		(mid 387.444742 -236.137681)
		(end 387.161786 -236.061504)
		(width 0.0889)
		(layer "In13.Cu")
		(net "M_H_CPU0_SA_DQ<19>")
	)
	(arc
		(start 383.393442 -236.056678)
		(mid 383.209934 -236.011184)
		(end 383.027682 -236.061504)
		(width 0.0889)
		(layer "In13.Cu")
		(net "M_H_CPU0_SA_DQ<19>")
	)
	(arc
		(start 390.921748 -236.061504)
		(mid 390.734804 -236.011249)
		(end 390.54786 -236.061504)
		(width 0.0889)
		(layer "In13.Cu")
		(net "M_H_CPU0_SA_DQ<19>")
	)
	(arc
		(start 389.607806 -236.061504)
		(mid 389.32485 -236.137681)
		(end 389.041894 -236.061504)
		(width 0.0889)
		(layer "In13.Cu")
		(net "M_H_CPU0_SA_DQ<19>")
	)
	(arc
		(start 388.667752 -236.061504)
		(mid 388.384796 -236.137681)
		(end 388.10184 -236.061504)
		(width 0.0889)
		(layer "In13.Cu")
		(net "M_H_CPU0_SA_DQ<19>")
	)
	(arc
		(start 389.033512 -236.056678)
		(mid 388.850004 -236.011184)
		(end 388.667752 -236.061504)
		(width 0.0889)
		(layer "In13.Cu")
		(net "M_H_CPU0_SA_DQ<19>")
	)
	(arc
		(start 390.54786 -236.061504)
		(mid 390.264904 -236.137681)
		(end 389.981948 -236.061504)
		(width 0.0889)
		(layer "In13.Cu")
		(net "M_H_CPU0_SA_DQ<19>")
	)
	(arc
		(start 386.787898 -236.061504)
		(mid 386.504942 -236.137681)
		(end 386.221986 -236.061504)
		(width 0.0889)
		(layer "In13.Cu")
		(net "M_H_CPU0_SA_DQ<19>")
	)
	(arc
		(start 387.161786 -236.061504)
		(mid 386.974842 -236.011249)
		(end 386.787898 -236.061504)
		(width 0.0889)
		(layer "In13.Cu")
		(net "M_H_CPU0_SA_DQ<19>")
	)
	(arc
		(start 385.281932 -236.061504)
		(mid 385.099681 -236.011154)
		(end 384.916172 -236.056678)
		(width 0.0889)
		(layer "In13.Cu")
		(net "M_H_CPU0_SA_DQ<19>")
	)
	(arc
		(start 384.90779 -236.061504)
		(mid 384.624834 -236.137681)
		(end 384.341878 -236.061504)
		(width 0.0889)
		(layer "In13.Cu")
		(net "M_H_CPU0_SA_DQ<19>")
	)
	(arc
		(start 385.847844 -236.061504)
		(mid 385.564888 -236.137681)
		(end 385.281932 -236.061504)
		(width 0.0889)
		(layer "In13.Cu")
		(net "M_H_CPU0_SA_DQ<19>")
	)
	(arc
		(start 392.146028 -236.137958)
		(mid 391.999097 -236.118547)
		(end 391.86231 -236.061504)
		(width 0.0889)
		(layer "In13.Cu")
		(net "M_H_CPU0_SA_DQ<19>")
	)
	(arc
		(start 384.333496 -236.056678)
		(mid 384.149988 -236.011184)
		(end 383.967736 -236.061504)
		(width 0.0889)
		(layer "In13.Cu")
		(net "M_H_CPU0_SA_DQ<19>")
	)
	(arc
		(start 383.967736 -236.061504)
		(mid 383.68478 -236.137681)
		(end 383.401824 -236.061504)
		(width 0.0889)
		(layer "In13.Cu")
		(net "M_H_CPU0_SA_DQ<19>")
	)
	(arc
		(start 386.221986 -236.061504)
		(mid 386.039735 -236.011154)
		(end 385.856226 -236.056678)
		(width 0.0889)
		(layer "In13.Cu")
		(net "M_H_CPU0_SA_DQ<19>")
	)
	(arc
		(start 389.981948 -236.061504)
		(mid 389.799697 -236.011154)
		(end 389.616188 -236.056678)
		(width 0.0889)
		(layer "In13.Cu")
		(net "M_H_CPU0_SA_DQ<19>")
	)
	(segment
		(start 383.217928 -235.840016)
		(end 383.68478 -235.574078)
		(width 0.10668)
		(layer "F.Cu")
		(net "M_H_CPU0_SA_DQ<18>")
	)
	(segment
		(start 402.050504 -224.315782)
		(end 402.23567 -224.130616)
		(width 0.14478)
		(layer "In13.Cu")
		(net "M_H_CPU0_SA_DQ<18>")
	)
	(segment
		(start 406.91435 -219.451936)
		(end 407.119074 -219.451936)
		(width 0.14478)
		(layer "In13.Cu")
		(net "M_H_CPU0_SA_DQ<18>")
	)
	(segment
		(start 404.779734 -221.791276)
		(end 404.864062 -221.875604)
		(width 0.14478)
		(layer "In13.Cu")
		(net "M_H_CPU0_SA_DQ<18>")
	)
	(segment
		(start 402.524722 -224.214944)
		(end 402.729446 -224.214944)
		(width 0.14478)
		(layer "In13.Cu")
		(net "M_H_CPU0_SA_DQ<18>")
	)
	(segment
		(start 404.57501 -221.791276)
		(end 404.779734 -221.791276)
		(width 0.14478)
		(layer "In13.Cu")
		(net "M_H_CPU0_SA_DQ<18>")
	)
	(segment
		(start 402.134832 -224.809558)
		(end 402.134832 -224.604834)
		(width 0.14478)
		(layer "In13.Cu")
		(net "M_H_CPU0_SA_DQ<18>")
	)
	(segment
		(start 408.288744 -218.077542)
		(end 408.47391 -217.892376)
		(width 0.14478)
		(layer "In13.Cu")
		(net "M_H_CPU0_SA_DQ<18>")
	)
	(segment
		(start 404.389844 -221.976442)
		(end 404.57501 -221.791276)
		(width 0.14478)
		(layer "In13.Cu")
		(net "M_H_CPU0_SA_DQ<18>")
	)
	(segment
		(start 418.732462 -217.310208)
		(end 419.486842 -217.310208)
		(width 0.14478)
		(layer "In13.Cu")
		(net "M_H_CPU0_SA_DQ<18>")
	)
	(segment
		(start 401.666202 -227.658676)
		(end 401.666202 -225.278188)
		(width 0.14478)
		(layer "In13.Cu")
		(net "M_H_CPU0_SA_DQ<18>")
	)
	(segment
		(start 404.289006 -222.655384)
		(end 404.474172 -222.470218)
		(width 0.14478)
		(layer "In13.Cu")
		(net "M_H_CPU0_SA_DQ<18>")
	)
	(segment
		(start 403.694392 -223.249998)
		(end 403.694392 -223.045274)
		(width 0.14478)
		(layer "In13.Cu")
		(net "M_H_CPU0_SA_DQ<18>")
	)
	(segment
		(start 407.508964 -218.857322)
		(end 407.69413 -218.672156)
		(width 0.14478)
		(layer "In13.Cu")
		(net "M_H_CPU0_SA_DQ<18>")
	)
	(segment
		(start 391.01776 -235.251498)
		(end 391.026142 -235.246672)
		(width 0.0889)
		(layer "In13.Cu")
		(net "M_H_CPU0_SA_DQ<18>")
	)
	(segment
		(start 406.729184 -219.637102)
		(end 406.91435 -219.451936)
		(width 0.14478)
		(layer "In13.Cu")
		(net "M_H_CPU0_SA_DQ<18>")
	)
	(segment
		(start 407.203402 -219.536264)
		(end 407.408126 -219.536264)
		(width 0.14478)
		(layer "In13.Cu")
		(net "M_H_CPU0_SA_DQ<18>")
	)
	(segment
		(start 394.543788 -234.05719)
		(end 395.550898 -233.05008)
		(width 0.0889)
		(layer "In13.Cu")
		(net "M_H_CPU0_SA_DQ<18>")
	)
	(segment
		(start 402.914612 -223.825054)
		(end 402.830284 -223.740726)
		(width 0.14478)
		(layer "In13.Cu")
		(net "M_H_CPU0_SA_DQ<18>")
	)
	(segment
		(start 406.339294 -220.231716)
		(end 406.423622 -220.316044)
		(width 0.14478)
		(layer "In13.Cu")
		(net "M_H_CPU0_SA_DQ<18>")
	)
	(segment
		(start 402.134832 -224.604834)
		(end 402.050504 -224.520506)
		(width 0.14478)
		(layer "In13.Cu")
		(net "M_H_CPU0_SA_DQ<18>")
	)
	(segment
		(start 404.474172 -222.265494)
		(end 404.389844 -222.181166)
		(width 0.14478)
		(layer "In13.Cu")
		(net "M_H_CPU0_SA_DQ<18>")
	)
	(segment
		(start 394.099796 -234.05719)
		(end 394.543788 -234.05719)
		(width 0.0889)
		(layer "In13.Cu")
		(net "M_H_CPU0_SA_DQ<18>")
	)
	(segment
		(start 407.898854 -218.672156)
		(end 407.983182 -218.756484)
		(width 0.14478)
		(layer "In13.Cu")
		(net "M_H_CPU0_SA_DQ<18>")
	)
	(segment
		(start 402.23567 -224.130616)
		(end 402.440394 -224.130616)
		(width 0.14478)
		(layer "In13.Cu")
		(net "M_H_CPU0_SA_DQ<18>")
	)
	(segment
		(start 405.949404 -220.621606)
		(end 405.949404 -220.416882)
		(width 0.14478)
		(layer "In13.Cu")
		(net "M_H_CPU0_SA_DQ<18>")
	)
	(segment
		(start 407.983182 -218.756484)
		(end 408.187906 -218.756484)
		(width 0.14478)
		(layer "In13.Cu")
		(net "M_H_CPU0_SA_DQ<18>")
	)
	(segment
		(start 401.666202 -225.278188)
		(end 402.134832 -224.809558)
		(width 0.14478)
		(layer "In13.Cu")
		(net "M_H_CPU0_SA_DQ<18>")
	)
	(segment
		(start 406.729184 -219.841826)
		(end 406.729184 -219.637102)
		(width 0.14478)
		(layer "In13.Cu")
		(net "M_H_CPU0_SA_DQ<18>")
	)
	(segment
		(start 408.373072 -218.571318)
		(end 408.373072 -218.366594)
		(width 0.14478)
		(layer "In13.Cu")
		(net "M_H_CPU0_SA_DQ<18>")
	)
	(segment
		(start 402.914612 -224.029778)
		(end 402.914612 -223.825054)
		(width 0.14478)
		(layer "In13.Cu")
		(net "M_H_CPU0_SA_DQ<18>")
	)
	(segment
		(start 406.423622 -220.316044)
		(end 406.628346 -220.316044)
		(width 0.14478)
		(layer "In13.Cu")
		(net "M_H_CPU0_SA_DQ<18>")
	)
	(segment
		(start 417.882324 -216.46007)
		(end 418.732462 -217.310208)
		(width 0.14478)
		(layer "In13.Cu")
		(net "M_H_CPU0_SA_DQ<18>")
	)
	(segment
		(start 402.050504 -224.520506)
		(end 402.050504 -224.315782)
		(width 0.14478)
		(layer "In13.Cu")
		(net "M_H_CPU0_SA_DQ<18>")
	)
	(segment
		(start 406.813512 -220.130878)
		(end 406.813512 -219.926154)
		(width 0.14478)
		(layer "In13.Cu")
		(net "M_H_CPU0_SA_DQ<18>")
	)
	(segment
		(start 403.610064 -222.756222)
		(end 403.79523 -222.571056)
		(width 0.14478)
		(layer "In13.Cu")
		(net "M_H_CPU0_SA_DQ<18>")
	)
	(segment
		(start 403.220174 -223.350836)
		(end 403.304502 -223.435164)
		(width 0.14478)
		(layer "In13.Cu")
		(net "M_H_CPU0_SA_DQ<18>")
	)
	(segment
		(start 407.593292 -219.146374)
		(end 407.508964 -219.062046)
		(width 0.14478)
		(layer "In13.Cu")
		(net "M_H_CPU0_SA_DQ<18>")
	)
	(segment
		(start 405.068786 -221.875604)
		(end 405.253952 -221.690438)
		(width 0.14478)
		(layer "In13.Cu")
		(net "M_H_CPU0_SA_DQ<18>")
	)
	(segment
		(start 405.643842 -221.095824)
		(end 405.848566 -221.095824)
		(width 0.14478)
		(layer "In13.Cu")
		(net "M_H_CPU0_SA_DQ<18>")
	)
	(segment
		(start 408.967686 -217.976704)
		(end 409.634182 -217.310208)
		(width 0.14478)
		(layer "In13.Cu")
		(net "M_H_CPU0_SA_DQ<18>")
	)
	(segment
		(start 395.550898 -233.05008)
		(end 395.782292 -233.05008)
		(width 0.0889)
		(layer "In13.Cu")
		(net "M_H_CPU0_SA_DQ<18>")
	)
	(segment
		(start 407.593292 -219.351098)
		(end 407.593292 -219.146374)
		(width 0.14478)
		(layer "In13.Cu")
		(net "M_H_CPU0_SA_DQ<18>")
	)
	(segment
		(start 409.634182 -217.310208)
		(end 414.085024 -217.310208)
		(width 0.14478)
		(layer "In13.Cu")
		(net "M_H_CPU0_SA_DQ<18>")
	)
	(segment
		(start 406.628346 -220.316044)
		(end 406.813512 -220.130878)
		(width 0.14478)
		(layer "In13.Cu")
		(net "M_H_CPU0_SA_DQ<18>")
	)
	(segment
		(start 391.89533 -235.287566)
		(end 392.882882 -234.89031)
		(width 0.0889)
		(layer "In13.Cu")
		(net "M_H_CPU0_SA_DQ<18>")
	)
	(segment
		(start 385.74345 -235.246672)
		(end 385.751832 -235.251498)
		(width 0.0889)
		(layer "In13.Cu")
		(net "M_H_CPU0_SA_DQ<18>")
	)
	(segment
		(start 405.949404 -220.416882)
		(end 406.13457 -220.231716)
		(width 0.14478)
		(layer "In13.Cu")
		(net "M_H_CPU0_SA_DQ<18>")
	)
	(segment
		(start 408.47391 -217.892376)
		(end 408.678634 -217.892376)
		(width 0.14478)
		(layer "In13.Cu")
		(net "M_H_CPU0_SA_DQ<18>")
	)
	(segment
		(start 391.391902 -235.251498)
		(end 391.402316 -235.257594)
		(width 0.0889)
		(layer "In13.Cu")
		(net "M_H_CPU0_SA_DQ<18>")
	)
	(segment
		(start 403.610064 -222.960946)
		(end 403.610064 -222.756222)
		(width 0.14478)
		(layer "In13.Cu")
		(net "M_H_CPU0_SA_DQ<18>")
	)
	(segment
		(start 405.253952 -221.485714)
		(end 405.169624 -221.401386)
		(width 0.14478)
		(layer "In13.Cu")
		(net "M_H_CPU0_SA_DQ<18>")
	)
	(segment
		(start 402.729446 -224.214944)
		(end 402.914612 -224.029778)
		(width 0.14478)
		(layer "In13.Cu")
		(net "M_H_CPU0_SA_DQ<18>")
	)
	(segment
		(start 402.830284 -223.536002)
		(end 403.01545 -223.350836)
		(width 0.14478)
		(layer "In13.Cu")
		(net "M_H_CPU0_SA_DQ<18>")
	)
	(segment
		(start 383.838958 -235.308648)
		(end 383.935224 -235.283248)
		(width 0.0889)
		(layer "In13.Cu")
		(net "M_H_CPU0_SA_DQ<18>")
	)
	(segment
		(start 402.440394 -224.130616)
		(end 402.524722 -224.214944)
		(width 0.14478)
		(layer "In13.Cu")
		(net "M_H_CPU0_SA_DQ<18>")
	)
	(segment
		(start 393.266676 -234.89031)
		(end 394.099796 -234.05719)
		(width 0.0889)
		(layer "In13.Cu")
		(net "M_H_CPU0_SA_DQ<18>")
	)
	(segment
		(start 383.68478 -235.574078)
		(end 383.838958 -235.308648)
		(width 0.0889)
		(layer "In13.Cu")
		(net "M_H_CPU0_SA_DQ<18>")
	)
	(segment
		(start 407.69413 -218.672156)
		(end 407.898854 -218.672156)
		(width 0.14478)
		(layer "In13.Cu")
		(net "M_H_CPU0_SA_DQ<18>")
	)
	(segment
		(start 388.197852 -235.251498)
		(end 388.206234 -235.246672)
		(width 0.0889)
		(layer "In13.Cu")
		(net "M_H_CPU0_SA_DQ<18>")
	)
	(segment
		(start 390.443466 -235.246672)
		(end 390.451848 -235.251498)
		(width 0.0889)
		(layer "In13.Cu")
		(net "M_H_CPU0_SA_DQ<18>")
	)
	(segment
		(start 405.848566 -221.095824)
		(end 406.033732 -220.910658)
		(width 0.14478)
		(layer "In13.Cu")
		(net "M_H_CPU0_SA_DQ<18>")
	)
	(segment
		(start 403.509226 -223.435164)
		(end 403.694392 -223.249998)
		(width 0.14478)
		(layer "In13.Cu")
		(net "M_H_CPU0_SA_DQ<18>")
	)
	(segment
		(start 405.169624 -221.401386)
		(end 405.169624 -221.196662)
		(width 0.14478)
		(layer "In13.Cu")
		(net "M_H_CPU0_SA_DQ<18>")
	)
	(segment
		(start 408.762962 -217.976704)
		(end 408.967686 -217.976704)
		(width 0.14478)
		(layer "In13.Cu")
		(net "M_H_CPU0_SA_DQ<18>")
	)
	(segment
		(start 387.257798 -235.251498)
		(end 387.26618 -235.246672)
		(width 0.0889)
		(layer "In13.Cu")
		(net "M_H_CPU0_SA_DQ<18>")
	)
	(segment
		(start 406.033732 -220.910658)
		(end 406.033732 -220.705934)
		(width 0.14478)
		(layer "In13.Cu")
		(net "M_H_CPU0_SA_DQ<18>")
	)
	(segment
		(start 407.408126 -219.536264)
		(end 407.593292 -219.351098)
		(width 0.14478)
		(layer "In13.Cu")
		(net "M_H_CPU0_SA_DQ<18>")
	)
	(segment
		(start 392.882882 -234.89031)
		(end 393.266676 -234.89031)
		(width 0.0889)
		(layer "In13.Cu")
		(net "M_H_CPU0_SA_DQ<18>")
	)
	(segment
		(start 404.084282 -222.655384)
		(end 404.289006 -222.655384)
		(width 0.14478)
		(layer "In13.Cu")
		(net "M_H_CPU0_SA_DQ<18>")
	)
	(segment
		(start 403.694392 -223.045274)
		(end 403.610064 -222.960946)
		(width 0.14478)
		(layer "In13.Cu")
		(net "M_H_CPU0_SA_DQ<18>")
	)
	(segment
		(start 408.187906 -218.756484)
		(end 408.373072 -218.571318)
		(width 0.14478)
		(layer "In13.Cu")
		(net "M_H_CPU0_SA_DQ<18>")
	)
	(segment
		(start 405.35479 -221.011496)
		(end 405.559514 -221.011496)
		(width 0.14478)
		(layer "In13.Cu")
		(net "M_H_CPU0_SA_DQ<18>")
	)
	(segment
		(start 405.559514 -221.011496)
		(end 405.643842 -221.095824)
		(width 0.14478)
		(layer "In13.Cu")
		(net "M_H_CPU0_SA_DQ<18>")
	)
	(segment
		(start 404.389844 -222.181166)
		(end 404.389844 -221.976442)
		(width 0.14478)
		(layer "In13.Cu")
		(net "M_H_CPU0_SA_DQ<18>")
	)
	(segment
		(start 403.999954 -222.571056)
		(end 404.084282 -222.655384)
		(width 0.14478)
		(layer "In13.Cu")
		(net "M_H_CPU0_SA_DQ<18>")
	)
	(segment
		(start 407.508964 -219.062046)
		(end 407.508964 -218.857322)
		(width 0.14478)
		(layer "In13.Cu")
		(net "M_H_CPU0_SA_DQ<18>")
	)
	(segment
		(start 402.830284 -223.740726)
		(end 402.830284 -223.536002)
		(width 0.14478)
		(layer "In13.Cu")
		(net "M_H_CPU0_SA_DQ<18>")
	)
	(segment
		(start 408.678634 -217.892376)
		(end 408.762962 -217.976704)
		(width 0.14478)
		(layer "In13.Cu")
		(net "M_H_CPU0_SA_DQ<18>")
	)
	(segment
		(start 405.253952 -221.690438)
		(end 405.253952 -221.485714)
		(width 0.14478)
		(layer "In13.Cu")
		(net "M_H_CPU0_SA_DQ<18>")
	)
	(segment
		(start 404.864062 -221.875604)
		(end 405.068786 -221.875604)
		(width 0.14478)
		(layer "In13.Cu")
		(net "M_H_CPU0_SA_DQ<18>")
	)
	(segment
		(start 414.085024 -217.310208)
		(end 414.935162 -216.46007)
		(width 0.14478)
		(layer "In13.Cu")
		(net "M_H_CPU0_SA_DQ<18>")
	)
	(segment
		(start 419.486842 -217.310208)
		(end 419.912038 -216.885012)
		(width 0.14478)
		(layer "In13.Cu")
		(net "M_H_CPU0_SA_DQ<18>")
	)
	(segment
		(start 404.474172 -222.470218)
		(end 404.474172 -222.265494)
		(width 0.14478)
		(layer "In13.Cu")
		(net "M_H_CPU0_SA_DQ<18>")
	)
	(segment
		(start 405.169624 -221.196662)
		(end 405.35479 -221.011496)
		(width 0.14478)
		(layer "In13.Cu")
		(net "M_H_CPU0_SA_DQ<18>")
	)
	(segment
		(start 395.782292 -233.05008)
		(end 396.274798 -233.05008)
		(width 0.14478)
		(layer "In13.Cu")
		(net "M_H_CPU0_SA_DQ<18>")
	)
	(segment
		(start 414.935162 -216.46007)
		(end 417.882324 -216.46007)
		(width 0.14478)
		(layer "In13.Cu")
		(net "M_H_CPU0_SA_DQ<18>")
	)
	(segment
		(start 408.373072 -218.366594)
		(end 408.288744 -218.282266)
		(width 0.14478)
		(layer "In13.Cu")
		(net "M_H_CPU0_SA_DQ<18>")
	)
	(segment
		(start 396.274798 -233.05008)
		(end 401.666202 -227.658676)
		(width 0.14478)
		(layer "In13.Cu")
		(net "M_H_CPU0_SA_DQ<18>")
	)
	(segment
		(start 406.033732 -220.705934)
		(end 405.949404 -220.621606)
		(width 0.14478)
		(layer "In13.Cu")
		(net "M_H_CPU0_SA_DQ<18>")
	)
	(segment
		(start 386.683504 -235.246672)
		(end 386.691886 -235.251498)
		(width 0.0889)
		(layer "In13.Cu")
		(net "M_H_CPU0_SA_DQ<18>")
	)
	(segment
		(start 403.304502 -223.435164)
		(end 403.509226 -223.435164)
		(width 0.14478)
		(layer "In13.Cu")
		(net "M_H_CPU0_SA_DQ<18>")
	)
	(segment
		(start 408.288744 -218.282266)
		(end 408.288744 -218.077542)
		(width 0.14478)
		(layer "In13.Cu")
		(net "M_H_CPU0_SA_DQ<18>")
	)
	(segment
		(start 403.01545 -223.350836)
		(end 403.220174 -223.350836)
		(width 0.14478)
		(layer "In13.Cu")
		(net "M_H_CPU0_SA_DQ<18>")
	)
	(segment
		(start 407.119074 -219.451936)
		(end 407.203402 -219.536264)
		(width 0.14478)
		(layer "In13.Cu")
		(net "M_H_CPU0_SA_DQ<18>")
	)
	(segment
		(start 406.813512 -219.926154)
		(end 406.729184 -219.841826)
		(width 0.14478)
		(layer "In13.Cu")
		(net "M_H_CPU0_SA_DQ<18>")
	)
	(segment
		(start 406.13457 -220.231716)
		(end 406.339294 -220.231716)
		(width 0.14478)
		(layer "In13.Cu")
		(net "M_H_CPU0_SA_DQ<18>")
	)
	(segment
		(start 403.79523 -222.571056)
		(end 403.999954 -222.571056)
		(width 0.14478)
		(layer "In13.Cu")
		(net "M_H_CPU0_SA_DQ<18>")
	)
	(arc
		(start 386.691886 -235.251498)
		(mid 386.974842 -235.327675)
		(end 387.257798 -235.251498)
		(width 0.0889)
		(layer "In13.Cu")
		(net "M_H_CPU0_SA_DQ<18>")
	)
	(arc
		(start 386.317744 -235.251498)
		(mid 386.499995 -235.201148)
		(end 386.683504 -235.246672)
		(width 0.0889)
		(layer "In13.Cu")
		(net "M_H_CPU0_SA_DQ<18>")
	)
	(arc
		(start 388.206234 -235.246672)
		(mid 388.389742 -235.201178)
		(end 388.571994 -235.251498)
		(width 0.0889)
		(layer "In13.Cu")
		(net "M_H_CPU0_SA_DQ<18>")
	)
	(arc
		(start 391.026142 -235.246672)
		(mid 391.20965 -235.201178)
		(end 391.391902 -235.251498)
		(width 0.0889)
		(layer "In13.Cu")
		(net "M_H_CPU0_SA_DQ<18>")
	)
	(arc
		(start 390.077706 -235.251498)
		(mid 390.259957 -235.201148)
		(end 390.443466 -235.246672)
		(width 0.0889)
		(layer "In13.Cu")
		(net "M_H_CPU0_SA_DQ<18>")
	)
	(arc
		(start 389.511794 -235.251498)
		(mid 389.79475 -235.327675)
		(end 390.077706 -235.251498)
		(width 0.0889)
		(layer "In13.Cu")
		(net "M_H_CPU0_SA_DQ<18>")
	)
	(arc
		(start 390.451848 -235.251498)
		(mid 390.734804 -235.327675)
		(end 391.01776 -235.251498)
		(width 0.0889)
		(layer "In13.Cu")
		(net "M_H_CPU0_SA_DQ<18>")
	)
	(arc
		(start 391.402316 -235.257594)
		(mid 391.645449 -235.328218)
		(end 391.89533 -235.287566)
		(width 0.0889)
		(layer "In13.Cu")
		(net "M_H_CPU0_SA_DQ<18>")
	)
	(arc
		(start 387.26618 -235.246672)
		(mid 387.449688 -235.201178)
		(end 387.63194 -235.251498)
		(width 0.0889)
		(layer "In13.Cu")
		(net "M_H_CPU0_SA_DQ<18>")
	)
	(arc
		(start 388.571994 -235.251498)
		(mid 388.85495 -235.327675)
		(end 389.137906 -235.251498)
		(width 0.0889)
		(layer "In13.Cu")
		(net "M_H_CPU0_SA_DQ<18>")
	)
	(arc
		(start 385.37769 -235.251498)
		(mid 385.559941 -235.201148)
		(end 385.74345 -235.246672)
		(width 0.0889)
		(layer "In13.Cu")
		(net "M_H_CPU0_SA_DQ<18>")
	)
	(arc
		(start 385.751832 -235.251498)
		(mid 386.034788 -235.327675)
		(end 386.317744 -235.251498)
		(width 0.0889)
		(layer "In13.Cu")
		(net "M_H_CPU0_SA_DQ<18>")
	)
	(arc
		(start 384.811778 -235.251498)
		(mid 385.094734 -235.327675)
		(end 385.37769 -235.251498)
		(width 0.0889)
		(layer "In13.Cu")
		(net "M_H_CPU0_SA_DQ<18>")
	)
	(arc
		(start 389.137906 -235.251498)
		(mid 389.32485 -235.201243)
		(end 389.511794 -235.251498)
		(width 0.0889)
		(layer "In13.Cu")
		(net "M_H_CPU0_SA_DQ<18>")
	)
	(arc
		(start 383.935224 -235.283248)
		(mid 384.190289 -235.326599)
		(end 384.43789 -235.251498)
		(width 0.0889)
		(layer "In13.Cu")
		(net "M_H_CPU0_SA_DQ<18>")
	)
	(arc
		(start 387.63194 -235.251498)
		(mid 387.914896 -235.327675)
		(end 388.197852 -235.251498)
		(width 0.0889)
		(layer "In13.Cu")
		(net "M_H_CPU0_SA_DQ<18>")
	)
	(arc
		(start 384.43789 -235.251498)
		(mid 384.624834 -235.201243)
		(end 384.811778 -235.251498)
		(width 0.0889)
		(layer "In13.Cu")
		(net "M_H_CPU0_SA_DQ<18>")
	)
	(segment
		(start 382.277874 -235.840016)
		(end 382.744726 -235.574078)
		(width 0.10668)
		(layer "F.Cu")
		(net "M_H_CPU0_SA_DQ<17>")
	)
	(segment
		(start 413.129984 -218.294712)
		(end 414.53562 -217.710512)
		(width 0.14478)
		(layer "In13.Cu")
		(net "M_H_CPU0_SA_DQ<17>")
	)
	(segment
		(start 391.958322 -235.896658)
		(end 391.958068 -235.896658)
		(width 0.0889)
		(layer "In13.Cu")
		(net "M_H_CPU0_SA_DQ<17>")
	)
	(segment
		(start 414.53562 -217.710512)
		(end 418.422582 -217.710512)
		(width 0.14478)
		(layer "In13.Cu")
		(net "M_H_CPU0_SA_DQ<17>")
	)
	(segment
		(start 395.782292 -233.50474)
		(end 396.463266 -233.50474)
		(width 0.14478)
		(layer "In13.Cu")
		(net "M_H_CPU0_SA_DQ<17>")
	)
	(segment
		(start 391.391902 -235.896658)
		(end 391.406634 -235.888022)
		(width 0.0889)
		(layer "In13.Cu")
		(net "M_H_CPU0_SA_DQ<17>")
	)
	(segment
		(start 386.683504 -235.901484)
		(end 386.691886 -235.896658)
		(width 0.0889)
		(layer "In13.Cu")
		(net "M_H_CPU0_SA_DQ<17>")
	)
	(segment
		(start 392.145774 -235.947458)
		(end 393.273788 -235.947458)
		(width 0.0889)
		(layer "In13.Cu")
		(net "M_H_CPU0_SA_DQ<17>")
	)
	(segment
		(start 394.094716 -234.64139)
		(end 394.394436 -234.34167)
		(width 0.0889)
		(layer "In13.Cu")
		(net "M_H_CPU0_SA_DQ<17>")
	)
	(segment
		(start 394.094716 -235.12653)
		(end 394.094716 -234.64139)
		(width 0.0889)
		(layer "In13.Cu")
		(net "M_H_CPU0_SA_DQ<17>")
	)
	(segment
		(start 409.285694 -218.294712)
		(end 413.129984 -218.294712)
		(width 0.14478)
		(layer "In13.Cu")
		(net "M_H_CPU0_SA_DQ<17>")
	)
	(segment
		(start 421.875712 -218.160092)
		(end 424.012106 -217.73515)
		(width 0.14478)
		(layer "In13.Cu")
		(net "M_H_CPU0_SA_DQ<17>")
	)
	(segment
		(start 394.394436 -234.34167)
		(end 394.6398 -234.34167)
		(width 0.0889)
		(layer "In13.Cu")
		(net "M_H_CPU0_SA_DQ<17>")
	)
	(segment
		(start 391.01776 -235.896658)
		(end 391.026142 -235.901484)
		(width 0.0889)
		(layer "In13.Cu")
		(net "M_H_CPU0_SA_DQ<17>")
	)
	(segment
		(start 390.443466 -235.901484)
		(end 390.451848 -235.896658)
		(width 0.0889)
		(layer "In13.Cu")
		(net "M_H_CPU0_SA_DQ<17>")
	)
	(segment
		(start 402.115782 -225.464624)
		(end 409.285694 -218.294712)
		(width 0.14478)
		(layer "In13.Cu")
		(net "M_H_CPU0_SA_DQ<17>")
	)
	(segment
		(start 383.497836 -235.896658)
		(end 383.506218 -235.901484)
		(width 0.0889)
		(layer "In13.Cu")
		(net "M_H_CPU0_SA_DQ<17>")
	)
	(segment
		(start 419.507924 -218.160092)
		(end 421.875712 -218.160092)
		(width 0.14478)
		(layer "In13.Cu")
		(net "M_H_CPU0_SA_DQ<17>")
	)
	(segment
		(start 394.6398 -234.34167)
		(end 395.47673 -233.50474)
		(width 0.0889)
		(layer "In13.Cu")
		(net "M_H_CPU0_SA_DQ<17>")
	)
	(segment
		(start 418.422582 -217.710512)
		(end 419.507924 -218.160092)
		(width 0.14478)
		(layer "In13.Cu")
		(net "M_H_CPU0_SA_DQ<17>")
	)
	(segment
		(start 387.257798 -235.896658)
		(end 387.26618 -235.901484)
		(width 0.0889)
		(layer "In13.Cu")
		(net "M_H_CPU0_SA_DQ<17>")
	)
	(segment
		(start 393.273788 -235.947458)
		(end 394.094716 -235.12653)
		(width 0.0889)
		(layer "In13.Cu")
		(net "M_H_CPU0_SA_DQ<17>")
	)
	(segment
		(start 395.47673 -233.50474)
		(end 395.782292 -233.50474)
		(width 0.0889)
		(layer "In13.Cu")
		(net "M_H_CPU0_SA_DQ<17>")
	)
	(segment
		(start 382.744726 -235.574078)
		(end 382.590802 -235.839508)
		(width 0.0889)
		(layer "In13.Cu")
		(net "M_H_CPU0_SA_DQ<17>")
	)
	(segment
		(start 388.197852 -235.896658)
		(end 388.206234 -235.901484)
		(width 0.0889)
		(layer "In13.Cu")
		(net "M_H_CPU0_SA_DQ<17>")
	)
	(segment
		(start 402.115782 -227.852224)
		(end 402.115782 -225.464624)
		(width 0.14478)
		(layer "In13.Cu")
		(net "M_H_CPU0_SA_DQ<17>")
	)
	(segment
		(start 382.590802 -235.839508)
		(end 382.613154 -235.92282)
		(width 0.0889)
		(layer "In13.Cu")
		(net "M_H_CPU0_SA_DQ<17>")
	)
	(segment
		(start 385.74345 -235.901484)
		(end 385.751832 -235.896658)
		(width 0.0889)
		(layer "In13.Cu")
		(net "M_H_CPU0_SA_DQ<17>")
	)
	(segment
		(start 396.463266 -233.50474)
		(end 402.115782 -227.852224)
		(width 0.14478)
		(layer "In13.Cu")
		(net "M_H_CPU0_SA_DQ<17>")
	)
	(arc
		(start 387.26618 -235.901484)
		(mid 387.449688 -235.946978)
		(end 387.63194 -235.896658)
		(width 0.0889)
		(layer "In13.Cu")
		(net "M_H_CPU0_SA_DQ<17>")
	)
	(arc
		(start 385.37769 -235.896658)
		(mid 385.559941 -235.947008)
		(end 385.74345 -235.901484)
		(width 0.0889)
		(layer "In13.Cu")
		(net "M_H_CPU0_SA_DQ<17>")
	)
	(arc
		(start 391.026142 -235.901484)
		(mid 391.20965 -235.946978)
		(end 391.391902 -235.896658)
		(width 0.0889)
		(layer "In13.Cu")
		(net "M_H_CPU0_SA_DQ<17>")
	)
	(arc
		(start 386.691886 -235.896658)
		(mid 386.974842 -235.820481)
		(end 387.257798 -235.896658)
		(width 0.0889)
		(layer "In13.Cu")
		(net "M_H_CPU0_SA_DQ<17>")
	)
	(arc
		(start 388.571994 -235.896658)
		(mid 388.85495 -235.820481)
		(end 389.137906 -235.896658)
		(width 0.0889)
		(layer "In13.Cu")
		(net "M_H_CPU0_SA_DQ<17>")
	)
	(arc
		(start 390.077706 -235.896658)
		(mid 390.259957 -235.947008)
		(end 390.443466 -235.901484)
		(width 0.0889)
		(layer "In13.Cu")
		(net "M_H_CPU0_SA_DQ<17>")
	)
	(arc
		(start 384.811778 -235.896658)
		(mid 385.094734 -235.820481)
		(end 385.37769 -235.896658)
		(width 0.0889)
		(layer "In13.Cu")
		(net "M_H_CPU0_SA_DQ<17>")
	)
	(arc
		(start 384.43789 -235.896658)
		(mid 384.624834 -235.946913)
		(end 384.811778 -235.896658)
		(width 0.0889)
		(layer "In13.Cu")
		(net "M_H_CPU0_SA_DQ<17>")
	)
	(arc
		(start 386.317744 -235.896658)
		(mid 386.499995 -235.947008)
		(end 386.683504 -235.901484)
		(width 0.0889)
		(layer "In13.Cu")
		(net "M_H_CPU0_SA_DQ<17>")
	)
	(arc
		(start 389.137906 -235.896658)
		(mid 389.32485 -235.946913)
		(end 389.511794 -235.896658)
		(width 0.0889)
		(layer "In13.Cu")
		(net "M_H_CPU0_SA_DQ<17>")
	)
	(arc
		(start 391.958068 -235.896658)
		(mid 392.048558 -235.934476)
		(end 392.145774 -235.947458)
		(width 0.0889)
		(layer "In13.Cu")
		(net "M_H_CPU0_SA_DQ<17>")
	)
	(arc
		(start 383.871978 -235.896658)
		(mid 384.154934 -235.820481)
		(end 384.43789 -235.896658)
		(width 0.0889)
		(layer "In13.Cu")
		(net "M_H_CPU0_SA_DQ<17>")
	)
	(arc
		(start 382.931924 -235.896658)
		(mid 383.21488 -235.820481)
		(end 383.497836 -235.896658)
		(width 0.0889)
		(layer "In13.Cu")
		(net "M_H_CPU0_SA_DQ<17>")
	)
	(arc
		(start 383.506218 -235.901484)
		(mid 383.689726 -235.946978)
		(end 383.871978 -235.896658)
		(width 0.0889)
		(layer "In13.Cu")
		(net "M_H_CPU0_SA_DQ<17>")
	)
	(arc
		(start 385.751832 -235.896658)
		(mid 386.034788 -235.820481)
		(end 386.317744 -235.896658)
		(width 0.0889)
		(layer "In13.Cu")
		(net "M_H_CPU0_SA_DQ<17>")
	)
	(arc
		(start 388.206234 -235.901484)
		(mid 388.389742 -235.946978)
		(end 388.571994 -235.896658)
		(width 0.0889)
		(layer "In13.Cu")
		(net "M_H_CPU0_SA_DQ<17>")
	)
	(arc
		(start 387.63194 -235.896658)
		(mid 387.914896 -235.820481)
		(end 388.197852 -235.896658)
		(width 0.0889)
		(layer "In13.Cu")
		(net "M_H_CPU0_SA_DQ<17>")
	)
	(arc
		(start 391.406634 -235.888022)
		(mid 391.683617 -235.820218)
		(end 391.958322 -235.896658)
		(width 0.0889)
		(layer "In13.Cu")
		(net "M_H_CPU0_SA_DQ<17>")
	)
	(arc
		(start 389.511794 -235.896658)
		(mid 389.79475 -235.820481)
		(end 390.077706 -235.896658)
		(width 0.0889)
		(layer "In13.Cu")
		(net "M_H_CPU0_SA_DQ<17>")
	)
	(arc
		(start 382.613154 -235.92282)
		(mid 382.775486 -235.945638)
		(end 382.931924 -235.896658)
		(width 0.0889)
		(layer "In13.Cu")
		(net "M_H_CPU0_SA_DQ<17>")
	)
	(arc
		(start 390.451848 -235.896658)
		(mid 390.734804 -235.820481)
		(end 391.01776 -235.896658)
		(width 0.0889)
		(layer "In13.Cu")
		(net "M_H_CPU0_SA_DQ<17>")
	)
	(segment
		(start 383.688082 -235.03001)
		(end 384.154934 -234.764072)
		(width 0.10668)
		(layer "F.Cu")
		(net "M_H_CPU0_SA_DQ<16>")
	)
	(segment
		(start 384.000756 -235.029502)
		(end 384.023108 -235.112814)
		(width 0.0889)
		(layer "In13.Cu")
		(net "M_H_CPU0_SA_DQ<16>")
	)
	(segment
		(start 394.313156 -233.276902)
		(end 395.016228 -232.57383)
		(width 0.0889)
		(layer "In13.Cu")
		(net "M_H_CPU0_SA_DQ<16>")
	)
	(segment
		(start 421.625014 -216.46007)
		(end 422.049956 -216.035128)
		(width 0.14478)
		(layer "In13.Cu")
		(net "M_H_CPU0_SA_DQ<16>")
	)
	(segment
		(start 395.016228 -232.57383)
		(end 395.886178 -232.57383)
		(width 0.0889)
		(layer "In13.Cu")
		(net "M_H_CPU0_SA_DQ<16>")
	)
	(segment
		(start 384.333496 -235.091478)
		(end 384.341878 -235.086652)
		(width 0.0889)
		(layer "In13.Cu")
		(net "M_H_CPU0_SA_DQ<16>")
	)
	(segment
		(start 389.033512 -235.091478)
		(end 389.041894 -235.086652)
		(width 0.0889)
		(layer "In13.Cu")
		(net "M_H_CPU0_SA_DQ<16>")
	)
	(segment
		(start 392.770614 -234.61599)
		(end 393.119356 -234.61599)
		(width 0.0889)
		(layer "In13.Cu")
		(net "M_H_CPU0_SA_DQ<16>")
	)
	(segment
		(start 417.71697 -215.610186)
		(end 418.566854 -216.46007)
		(width 0.14478)
		(layer "In13.Cu")
		(net "M_H_CPU0_SA_DQ<16>")
	)
	(segment
		(start 389.607806 -235.086652)
		(end 389.616188 -235.091478)
		(width 0.0889)
		(layer "In13.Cu")
		(net "M_H_CPU0_SA_DQ<16>")
	)
	(segment
		(start 394.313156 -233.42219)
		(end 394.313156 -233.276902)
		(width 0.0889)
		(layer "In13.Cu")
		(net "M_H_CPU0_SA_DQ<16>")
	)
	(segment
		(start 388.093458 -235.091478)
		(end 388.10184 -235.086652)
		(width 0.0889)
		(layer "In13.Cu")
		(net "M_H_CPU0_SA_DQ<16>")
	)
	(segment
		(start 409.2702 -216.46007)
		(end 414.114488 -216.46007)
		(width 0.14478)
		(layer "In13.Cu")
		(net "M_H_CPU0_SA_DQ<16>")
	)
	(segment
		(start 385.847844 -235.086652)
		(end 385.856226 -235.091478)
		(width 0.0889)
		(layer "In13.Cu")
		(net "M_H_CPU0_SA_DQ<16>")
	)
	(segment
		(start 401.216622 -224.513648)
		(end 409.2702 -216.46007)
		(width 0.14478)
		(layer "In13.Cu")
		(net "M_H_CPU0_SA_DQ<16>")
	)
	(segment
		(start 391.48766 -235.086652)
		(end 391.496042 -235.091478)
		(width 0.0889)
		(layer "In13.Cu")
		(net "M_H_CPU0_SA_DQ<16>")
	)
	(segment
		(start 418.566854 -216.46007)
		(end 421.625014 -216.46007)
		(width 0.14478)
		(layer "In13.Cu")
		(net "M_H_CPU0_SA_DQ<16>")
	)
	(segment
		(start 396.01394 -232.57383)
		(end 401.216622 -227.371148)
		(width 0.14478)
		(layer "In13.Cu")
		(net "M_H_CPU0_SA_DQ<16>")
	)
	(segment
		(start 395.886178 -232.57383)
		(end 396.01394 -232.57383)
		(width 0.14478)
		(layer "In13.Cu")
		(net "M_H_CPU0_SA_DQ<16>")
	)
	(segment
		(start 384.154934 -234.764072)
		(end 384.000756 -235.029502)
		(width 0.0889)
		(layer "In13.Cu")
		(net "M_H_CPU0_SA_DQ<16>")
	)
	(segment
		(start 414.964372 -215.610186)
		(end 417.71697 -215.610186)
		(width 0.14478)
		(layer "In13.Cu")
		(net "M_H_CPU0_SA_DQ<16>")
	)
	(segment
		(start 391.86231 -235.086652)
		(end 392.770614 -234.61599)
		(width 0.0889)
		(layer "In13.Cu")
		(net "M_H_CPU0_SA_DQ<16>")
	)
	(segment
		(start 414.114488 -216.46007)
		(end 414.964372 -215.610186)
		(width 0.14478)
		(layer "In13.Cu")
		(net "M_H_CPU0_SA_DQ<16>")
	)
	(segment
		(start 384.90779 -235.086652)
		(end 384.916172 -235.091478)
		(width 0.0889)
		(layer "In13.Cu")
		(net "M_H_CPU0_SA_DQ<16>")
	)
	(segment
		(start 401.216622 -227.371148)
		(end 401.216622 -224.513648)
		(width 0.14478)
		(layer "In13.Cu")
		(net "M_H_CPU0_SA_DQ<16>")
	)
	(segment
		(start 422.049956 -216.035128)
		(end 424.012106 -216.035128)
		(width 0.14478)
		(layer "In13.Cu")
		(net "M_H_CPU0_SA_DQ<16>")
	)
	(segment
		(start 393.119356 -234.61599)
		(end 394.313156 -233.42219)
		(width 0.0889)
		(layer "In13.Cu")
		(net "M_H_CPU0_SA_DQ<16>")
	)
	(arc
		(start 390.54786 -235.086652)
		(mid 390.734804 -235.136907)
		(end 390.921748 -235.086652)
		(width 0.0889)
		(layer "In13.Cu")
		(net "M_H_CPU0_SA_DQ<16>")
	)
	(arc
		(start 390.921748 -235.086652)
		(mid 391.204704 -235.010475)
		(end 391.48766 -235.086652)
		(width 0.0889)
		(layer "In13.Cu")
		(net "M_H_CPU0_SA_DQ<16>")
	)
	(arc
		(start 386.787898 -235.086652)
		(mid 386.974842 -235.136907)
		(end 387.161786 -235.086652)
		(width 0.0889)
		(layer "In13.Cu")
		(net "M_H_CPU0_SA_DQ<16>")
	)
	(arc
		(start 384.023108 -235.112814)
		(mid 384.180618 -235.136012)
		(end 384.333496 -235.091478)
		(width 0.0889)
		(layer "In13.Cu")
		(net "M_H_CPU0_SA_DQ<16>")
	)
	(arc
		(start 385.856226 -235.091478)
		(mid 386.039734 -235.136972)
		(end 386.221986 -235.086652)
		(width 0.0889)
		(layer "In13.Cu")
		(net "M_H_CPU0_SA_DQ<16>")
	)
	(arc
		(start 389.041894 -235.086652)
		(mid 389.32485 -235.010475)
		(end 389.607806 -235.086652)
		(width 0.0889)
		(layer "In13.Cu")
		(net "M_H_CPU0_SA_DQ<16>")
	)
	(arc
		(start 386.221986 -235.086652)
		(mid 386.504942 -235.010475)
		(end 386.787898 -235.086652)
		(width 0.0889)
		(layer "In13.Cu")
		(net "M_H_CPU0_SA_DQ<16>")
	)
	(arc
		(start 384.341878 -235.086652)
		(mid 384.624834 -235.010475)
		(end 384.90779 -235.086652)
		(width 0.0889)
		(layer "In13.Cu")
		(net "M_H_CPU0_SA_DQ<16>")
	)
	(arc
		(start 385.281932 -235.086652)
		(mid 385.564888 -235.010475)
		(end 385.847844 -235.086652)
		(width 0.0889)
		(layer "In13.Cu")
		(net "M_H_CPU0_SA_DQ<16>")
	)
	(arc
		(start 388.10184 -235.086652)
		(mid 388.384796 -235.010475)
		(end 388.667752 -235.086652)
		(width 0.0889)
		(layer "In13.Cu")
		(net "M_H_CPU0_SA_DQ<16>")
	)
	(arc
		(start 391.496042 -235.091478)
		(mid 391.679804 -235.137094)
		(end 391.86231 -235.086652)
		(width 0.0889)
		(layer "In13.Cu")
		(net "M_H_CPU0_SA_DQ<16>")
	)
	(arc
		(start 387.727698 -235.086652)
		(mid 387.909949 -235.137002)
		(end 388.093458 -235.091478)
		(width 0.0889)
		(layer "In13.Cu")
		(net "M_H_CPU0_SA_DQ<16>")
	)
	(arc
		(start 388.667752 -235.086652)
		(mid 388.850003 -235.137002)
		(end 389.033512 -235.091478)
		(width 0.0889)
		(layer "In13.Cu")
		(net "M_H_CPU0_SA_DQ<16>")
	)
	(arc
		(start 384.916172 -235.091478)
		(mid 385.09968 -235.136972)
		(end 385.281932 -235.086652)
		(width 0.0889)
		(layer "In13.Cu")
		(net "M_H_CPU0_SA_DQ<16>")
	)
	(arc
		(start 389.981948 -235.086652)
		(mid 390.264904 -235.010475)
		(end 390.54786 -235.086652)
		(width 0.0889)
		(layer "In13.Cu")
		(net "M_H_CPU0_SA_DQ<16>")
	)
	(arc
		(start 389.616188 -235.091478)
		(mid 389.799696 -235.136972)
		(end 389.981948 -235.086652)
		(width 0.0889)
		(layer "In13.Cu")
		(net "M_H_CPU0_SA_DQ<16>")
	)
	(arc
		(start 387.161786 -235.086652)
		(mid 387.444742 -235.010475)
		(end 387.727698 -235.086652)
		(width 0.0889)
		(layer "In13.Cu")
		(net "M_H_CPU0_SA_DQ<16>")
	)
	(segment
		(start 381.807974 -235.03001)
		(end 382.274826 -234.764072)
		(width 0.10668)
		(layer "F.Cu")
		(net "M_H_CPU0_SA_DQ<15>")
	)
	(segment
		(start 404.105618 -220.430598)
		(end 404.105618 -220.225874)
		(width 0.14478)
		(layer "In13.Cu")
		(net "M_H_CPU0_SA_DQ<15>")
	)
	(segment
		(start 404.60041 -220.14561)
		(end 404.805134 -220.14561)
		(width 0.14478)
		(layer "In13.Cu")
		(net "M_H_CPU0_SA_DQ<15>")
	)
	(segment
		(start 382.274826 -234.764072)
		(end 382.42875 -234.498642)
		(width 0.0889)
		(layer "In13.Cu")
		(net "M_H_CPU0_SA_DQ<15>")
	)
	(segment
		(start 406.15997 -218.58605)
		(end 406.364694 -218.58605)
		(width 0.14478)
		(layer "In13.Cu")
		(net "M_H_CPU0_SA_DQ<15>")
	)
	(segment
		(start 405.77008 -219.180664)
		(end 405.77008 -218.97594)
		(width 0.14478)
		(layer "In13.Cu")
		(net "M_H_CPU0_SA_DQ<15>")
	)
	(segment
		(start 404.025354 -220.92539)
		(end 404.21052 -220.740224)
		(width 0.14478)
		(layer "In13.Cu")
		(net "M_H_CPU0_SA_DQ<15>")
	)
	(segment
		(start 389.607806 -234.441492)
		(end 389.616188 -234.436666)
		(width 0.0889)
		(layer "In13.Cu")
		(net "M_H_CPU0_SA_DQ<15>")
	)
	(segment
		(start 388.093458 -234.436666)
		(end 388.10184 -234.441492)
		(width 0.0889)
		(layer "In13.Cu")
		(net "M_H_CPU0_SA_DQ<15>")
	)
	(segment
		(start 400.986498 -223.344994)
		(end 401.171664 -223.159828)
		(width 0.14478)
		(layer "In13.Cu")
		(net "M_H_CPU0_SA_DQ<15>")
	)
	(segment
		(start 419.912038 -215.189816)
		(end 419.912038 -215.18499)
		(width 0.14478)
		(layer "In13.Cu")
		(net "M_H_CPU0_SA_DQ<15>")
	)
	(segment
		(start 382.42875 -234.498642)
		(end 382.524762 -234.473242)
		(width 0.0889)
		(layer "In13.Cu")
		(net "M_H_CPU0_SA_DQ<15>")
	)
	(segment
		(start 406.54986 -218.19616)
		(end 406.444958 -218.091258)
		(width 0.14478)
		(layer "In13.Cu")
		(net "M_H_CPU0_SA_DQ<15>")
	)
	(segment
		(start 401.87118 -222.87484)
		(end 401.766278 -222.769938)
		(width 0.14478)
		(layer "In13.Cu")
		(net "M_H_CPU0_SA_DQ<15>")
	)
	(segment
		(start 403.43074 -221.31528)
		(end 403.325838 -221.210378)
		(width 0.14478)
		(layer "In13.Cu")
		(net "M_H_CPU0_SA_DQ<15>")
	)
	(segment
		(start 417.700968 -214.760048)
		(end 418.551106 -215.610186)
		(width 0.14478)
		(layer "In13.Cu")
		(net "M_H_CPU0_SA_DQ<15>")
	)
	(segment
		(start 418.551106 -215.610186)
		(end 419.491668 -215.610186)
		(width 0.14478)
		(layer "In13.Cu")
		(net "M_H_CPU0_SA_DQ<15>")
	)
	(segment
		(start 400.665442 -224.285302)
		(end 401.0914 -223.859344)
		(width 0.14478)
		(layer "In13.Cu")
		(net "M_H_CPU0_SA_DQ<15>")
	)
	(segment
		(start 389.033512 -234.436666)
		(end 389.041894 -234.441492)
		(width 0.0889)
		(layer "In13.Cu")
		(net "M_H_CPU0_SA_DQ<15>")
	)
	(segment
		(start 414.855914 -214.760048)
		(end 417.700968 -214.760048)
		(width 0.14478)
		(layer "In13.Cu")
		(net "M_H_CPU0_SA_DQ<15>")
	)
	(segment
		(start 393.702794 -233.59491)
		(end 395.277594 -232.02011)
		(width 0.0889)
		(layer "In13.Cu")
		(net "M_H_CPU0_SA_DQ<15>")
	)
	(segment
		(start 392.931396 -233.59491)
		(end 393.702794 -233.59491)
		(width 0.0889)
		(layer "In13.Cu")
		(net "M_H_CPU0_SA_DQ<15>")
	)
	(segment
		(start 408.10942 -216.6366)
		(end 408.004518 -216.531698)
		(width 0.14478)
		(layer "In13.Cu")
		(net "M_H_CPU0_SA_DQ<15>")
	)
	(segment
		(start 404.21052 -220.5355)
		(end 404.105618 -220.430598)
		(width 0.14478)
		(layer "In13.Cu")
		(net "M_H_CPU0_SA_DQ<15>")
	)
	(segment
		(start 404.805134 -220.14561)
		(end 404.9903 -219.960444)
		(width 0.14478)
		(layer "In13.Cu")
		(net "M_H_CPU0_SA_DQ<15>")
	)
	(segment
		(start 403.82063 -220.92539)
		(end 404.025354 -220.92539)
		(width 0.14478)
		(layer "In13.Cu")
		(net "M_H_CPU0_SA_DQ<15>")
	)
	(segment
		(start 408.004518 -216.326974)
		(end 408.189684 -216.141808)
		(width 0.14478)
		(layer "In13.Cu")
		(net "M_H_CPU0_SA_DQ<15>")
	)
	(segment
		(start 401.0914 -223.65462)
		(end 400.986498 -223.549718)
		(width 0.14478)
		(layer "In13.Cu")
		(net "M_H_CPU0_SA_DQ<15>")
	)
	(segment
		(start 402.731224 -221.600268)
		(end 402.935948 -221.600268)
		(width 0.14478)
		(layer "In13.Cu")
		(net "M_H_CPU0_SA_DQ<15>")
	)
	(segment
		(start 406.630124 -217.701368)
		(end 406.834848 -217.701368)
		(width 0.14478)
		(layer "In13.Cu")
		(net "M_H_CPU0_SA_DQ<15>")
	)
	(segment
		(start 403.325838 -221.210378)
		(end 403.325838 -221.005654)
		(width 0.14478)
		(layer "In13.Cu")
		(net "M_H_CPU0_SA_DQ<15>")
	)
	(segment
		(start 407.224738 -217.106754)
		(end 407.409904 -216.921588)
		(width 0.14478)
		(layer "In13.Cu")
		(net "M_H_CPU0_SA_DQ<15>")
	)
	(segment
		(start 405.850344 -218.481148)
		(end 406.055068 -218.481148)
		(width 0.14478)
		(layer "In13.Cu")
		(net "M_H_CPU0_SA_DQ<15>")
	)
	(segment
		(start 406.444958 -218.091258)
		(end 406.444958 -217.886534)
		(width 0.14478)
		(layer "In13.Cu")
		(net "M_H_CPU0_SA_DQ<15>")
	)
	(segment
		(start 402.546058 -221.990158)
		(end 402.546058 -221.785434)
		(width 0.14478)
		(layer "In13.Cu")
		(net "M_H_CPU0_SA_DQ<15>")
	)
	(segment
		(start 406.444958 -217.886534)
		(end 406.630124 -217.701368)
		(width 0.14478)
		(layer "In13.Cu")
		(net "M_H_CPU0_SA_DQ<15>")
	)
	(segment
		(start 401.48129 -223.26473)
		(end 401.686014 -223.26473)
		(width 0.14478)
		(layer "In13.Cu")
		(net "M_H_CPU0_SA_DQ<15>")
	)
	(segment
		(start 404.290784 -220.040708)
		(end 404.495508 -220.040708)
		(width 0.14478)
		(layer "In13.Cu")
		(net "M_H_CPU0_SA_DQ<15>")
	)
	(segment
		(start 407.32964 -217.41638)
		(end 407.224738 -217.311478)
		(width 0.14478)
		(layer "In13.Cu")
		(net "M_H_CPU0_SA_DQ<15>")
	)
	(segment
		(start 403.43074 -221.520004)
		(end 403.43074 -221.31528)
		(width 0.14478)
		(layer "In13.Cu")
		(net "M_H_CPU0_SA_DQ<15>")
	)
	(segment
		(start 402.26107 -222.48495)
		(end 402.465794 -222.48495)
		(width 0.14478)
		(layer "In13.Cu")
		(net "M_H_CPU0_SA_DQ<15>")
	)
	(segment
		(start 405.665178 -218.871038)
		(end 405.665178 -218.666314)
		(width 0.14478)
		(layer "In13.Cu")
		(net "M_H_CPU0_SA_DQ<15>")
	)
	(segment
		(start 404.885398 -219.650818)
		(end 404.885398 -219.446094)
		(width 0.14478)
		(layer "In13.Cu")
		(net "M_H_CPU0_SA_DQ<15>")
	)
	(segment
		(start 404.9903 -219.75572)
		(end 404.885398 -219.650818)
		(width 0.14478)
		(layer "In13.Cu")
		(net "M_H_CPU0_SA_DQ<15>")
	)
	(segment
		(start 408.49931 -216.24671)
		(end 408.704034 -216.24671)
		(width 0.14478)
		(layer "In13.Cu")
		(net "M_H_CPU0_SA_DQ<15>")
	)
	(segment
		(start 408.189684 -216.141808)
		(end 408.394408 -216.141808)
		(width 0.14478)
		(layer "In13.Cu")
		(net "M_H_CPU0_SA_DQ<15>")
	)
	(segment
		(start 414.005776 -215.610186)
		(end 414.855914 -214.760048)
		(width 0.14478)
		(layer "In13.Cu")
		(net "M_H_CPU0_SA_DQ<15>")
	)
	(segment
		(start 409.340558 -215.610186)
		(end 414.005776 -215.610186)
		(width 0.14478)
		(layer "In13.Cu")
		(net "M_H_CPU0_SA_DQ<15>")
	)
	(segment
		(start 408.10942 -216.841324)
		(end 408.10942 -216.6366)
		(width 0.14478)
		(layer "In13.Cu")
		(net "M_H_CPU0_SA_DQ<15>")
	)
	(segment
		(start 407.224738 -217.311478)
		(end 407.224738 -217.106754)
		(width 0.14478)
		(layer "In13.Cu")
		(net "M_H_CPU0_SA_DQ<15>")
	)
	(segment
		(start 403.511004 -220.820488)
		(end 403.715728 -220.820488)
		(width 0.14478)
		(layer "In13.Cu")
		(net "M_H_CPU0_SA_DQ<15>")
	)
	(segment
		(start 400.986498 -223.549718)
		(end 400.986498 -223.344994)
		(width 0.14478)
		(layer "In13.Cu")
		(net "M_H_CPU0_SA_DQ<15>")
	)
	(segment
		(start 419.491668 -215.610186)
		(end 419.912038 -215.189816)
		(width 0.14478)
		(layer "In13.Cu")
		(net "M_H_CPU0_SA_DQ<15>")
	)
	(segment
		(start 408.704034 -216.24671)
		(end 409.340558 -215.610186)
		(width 0.14478)
		(layer "In13.Cu")
		(net "M_H_CPU0_SA_DQ<15>")
	)
	(segment
		(start 405.77008 -218.97594)
		(end 405.665178 -218.871038)
		(width 0.14478)
		(layer "In13.Cu")
		(net "M_H_CPU0_SA_DQ<15>")
	)
	(segment
		(start 392.135106 -234.3912)
		(end 392.931396 -233.59491)
		(width 0.0889)
		(layer "In13.Cu")
		(net "M_H_CPU0_SA_DQ<15>")
	)
	(segment
		(start 407.144474 -217.80627)
		(end 407.32964 -217.621104)
		(width 0.14478)
		(layer "In13.Cu")
		(net "M_H_CPU0_SA_DQ<15>")
	)
	(segment
		(start 384.333496 -234.436666)
		(end 384.341878 -234.441492)
		(width 0.0889)
		(layer "In13.Cu")
		(net "M_H_CPU0_SA_DQ<15>")
	)
	(segment
		(start 401.686014 -223.26473)
		(end 401.87118 -223.079564)
		(width 0.14478)
		(layer "In13.Cu")
		(net "M_H_CPU0_SA_DQ<15>")
	)
	(segment
		(start 403.04085 -221.70517)
		(end 403.245574 -221.70517)
		(width 0.14478)
		(layer "In13.Cu")
		(net "M_H_CPU0_SA_DQ<15>")
	)
	(segment
		(start 404.21052 -220.740224)
		(end 404.21052 -220.5355)
		(width 0.14478)
		(layer "In13.Cu")
		(net "M_H_CPU0_SA_DQ<15>")
	)
	(segment
		(start 402.546058 -221.785434)
		(end 402.731224 -221.600268)
		(width 0.14478)
		(layer "In13.Cu")
		(net "M_H_CPU0_SA_DQ<15>")
	)
	(segment
		(start 401.951444 -222.380048)
		(end 402.156168 -222.380048)
		(width 0.14478)
		(layer "In13.Cu")
		(net "M_H_CPU0_SA_DQ<15>")
	)
	(segment
		(start 405.665178 -218.666314)
		(end 405.850344 -218.481148)
		(width 0.14478)
		(layer "In13.Cu")
		(net "M_H_CPU0_SA_DQ<15>")
	)
	(segment
		(start 407.32964 -217.621104)
		(end 407.32964 -217.41638)
		(width 0.14478)
		(layer "In13.Cu")
		(net "M_H_CPU0_SA_DQ<15>")
	)
	(segment
		(start 407.409904 -216.921588)
		(end 407.614628 -216.921588)
		(width 0.14478)
		(layer "In13.Cu")
		(net "M_H_CPU0_SA_DQ<15>")
	)
	(segment
		(start 402.65096 -222.09506)
		(end 402.546058 -221.990158)
		(width 0.14478)
		(layer "In13.Cu")
		(net "M_H_CPU0_SA_DQ<15>")
	)
	(segment
		(start 401.376388 -223.159828)
		(end 401.48129 -223.26473)
		(width 0.14478)
		(layer "In13.Cu")
		(net "M_H_CPU0_SA_DQ<15>")
	)
	(segment
		(start 391.674858 -234.3912)
		(end 392.135106 -234.3912)
		(width 0.0889)
		(layer "In13.Cu")
		(net "M_H_CPU0_SA_DQ<15>")
	)
	(segment
		(start 406.364694 -218.58605)
		(end 406.54986 -218.400884)
		(width 0.14478)
		(layer "In13.Cu")
		(net "M_H_CPU0_SA_DQ<15>")
	)
	(segment
		(start 385.847844 -234.441492)
		(end 385.856226 -234.436666)
		(width 0.0889)
		(layer "In13.Cu")
		(net "M_H_CPU0_SA_DQ<15>")
	)
	(segment
		(start 406.834848 -217.701368)
		(end 406.93975 -217.80627)
		(width 0.14478)
		(layer "In13.Cu")
		(net "M_H_CPU0_SA_DQ<15>")
	)
	(segment
		(start 407.614628 -216.921588)
		(end 407.71953 -217.02649)
		(width 0.14478)
		(layer "In13.Cu")
		(net "M_H_CPU0_SA_DQ<15>")
	)
	(segment
		(start 408.394408 -216.141808)
		(end 408.49931 -216.24671)
		(width 0.14478)
		(layer "In13.Cu")
		(net "M_H_CPU0_SA_DQ<15>")
	)
	(segment
		(start 401.87118 -223.079564)
		(end 401.87118 -222.87484)
		(width 0.14478)
		(layer "In13.Cu")
		(net "M_H_CPU0_SA_DQ<15>")
	)
	(segment
		(start 405.070564 -219.260928)
		(end 405.275288 -219.260928)
		(width 0.14478)
		(layer "In13.Cu")
		(net "M_H_CPU0_SA_DQ<15>")
	)
	(segment
		(start 404.9903 -219.960444)
		(end 404.9903 -219.75572)
		(width 0.14478)
		(layer "In13.Cu")
		(net "M_H_CPU0_SA_DQ<15>")
	)
	(segment
		(start 405.275288 -219.260928)
		(end 405.38019 -219.36583)
		(width 0.14478)
		(layer "In13.Cu")
		(net "M_H_CPU0_SA_DQ<15>")
	)
	(segment
		(start 400.665442 -227.056442)
		(end 400.665442 -224.285302)
		(width 0.14478)
		(layer "In13.Cu")
		(net "M_H_CPU0_SA_DQ<15>")
	)
	(segment
		(start 402.156168 -222.380048)
		(end 402.26107 -222.48495)
		(width 0.14478)
		(layer "In13.Cu")
		(net "M_H_CPU0_SA_DQ<15>")
	)
	(segment
		(start 408.004518 -216.531698)
		(end 408.004518 -216.326974)
		(width 0.14478)
		(layer "In13.Cu")
		(net "M_H_CPU0_SA_DQ<15>")
	)
	(segment
		(start 403.325838 -221.005654)
		(end 403.511004 -220.820488)
		(width 0.14478)
		(layer "In13.Cu")
		(net "M_H_CPU0_SA_DQ<15>")
	)
	(segment
		(start 406.055068 -218.481148)
		(end 406.15997 -218.58605)
		(width 0.14478)
		(layer "In13.Cu")
		(net "M_H_CPU0_SA_DQ<15>")
	)
	(segment
		(start 402.935948 -221.600268)
		(end 403.04085 -221.70517)
		(width 0.14478)
		(layer "In13.Cu")
		(net "M_H_CPU0_SA_DQ<15>")
	)
	(segment
		(start 405.584914 -219.36583)
		(end 405.77008 -219.180664)
		(width 0.14478)
		(layer "In13.Cu")
		(net "M_H_CPU0_SA_DQ<15>")
	)
	(segment
		(start 401.766278 -222.565214)
		(end 401.951444 -222.380048)
		(width 0.14478)
		(layer "In13.Cu")
		(net "M_H_CPU0_SA_DQ<15>")
	)
	(segment
		(start 395.277594 -232.02011)
		(end 395.701774 -232.02011)
		(width 0.0889)
		(layer "In13.Cu")
		(net "M_H_CPU0_SA_DQ<15>")
	)
	(segment
		(start 404.105618 -220.225874)
		(end 404.290784 -220.040708)
		(width 0.14478)
		(layer "In13.Cu")
		(net "M_H_CPU0_SA_DQ<15>")
	)
	(segment
		(start 384.90779 -234.441492)
		(end 384.916172 -234.436666)
		(width 0.0889)
		(layer "In13.Cu")
		(net "M_H_CPU0_SA_DQ<15>")
	)
	(segment
		(start 402.65096 -222.299784)
		(end 402.65096 -222.09506)
		(width 0.14478)
		(layer "In13.Cu")
		(net "M_H_CPU0_SA_DQ<15>")
	)
	(segment
		(start 401.766278 -222.769938)
		(end 401.766278 -222.565214)
		(width 0.14478)
		(layer "In13.Cu")
		(net "M_H_CPU0_SA_DQ<15>")
	)
	(segment
		(start 404.495508 -220.040708)
		(end 404.60041 -220.14561)
		(width 0.14478)
		(layer "In13.Cu")
		(net "M_H_CPU0_SA_DQ<15>")
	)
	(segment
		(start 406.93975 -217.80627)
		(end 407.144474 -217.80627)
		(width 0.14478)
		(layer "In13.Cu")
		(net "M_H_CPU0_SA_DQ<15>")
	)
	(segment
		(start 402.465794 -222.48495)
		(end 402.65096 -222.299784)
		(width 0.14478)
		(layer "In13.Cu")
		(net "M_H_CPU0_SA_DQ<15>")
	)
	(segment
		(start 383.393442 -234.436666)
		(end 383.401824 -234.441492)
		(width 0.0889)
		(layer "In13.Cu")
		(net "M_H_CPU0_SA_DQ<15>")
	)
	(segment
		(start 395.701774 -232.02011)
		(end 400.665442 -227.056442)
		(width 0.14478)
		(layer "In13.Cu")
		(net "M_H_CPU0_SA_DQ<15>")
	)
	(segment
		(start 404.885398 -219.446094)
		(end 405.070564 -219.260928)
		(width 0.14478)
		(layer "In13.Cu")
		(net "M_H_CPU0_SA_DQ<15>")
	)
	(segment
		(start 407.924254 -217.02649)
		(end 408.10942 -216.841324)
		(width 0.14478)
		(layer "In13.Cu")
		(net "M_H_CPU0_SA_DQ<15>")
	)
	(segment
		(start 407.71953 -217.02649)
		(end 407.924254 -217.02649)
		(width 0.14478)
		(layer "In13.Cu")
		(net "M_H_CPU0_SA_DQ<15>")
	)
	(segment
		(start 401.0914 -223.859344)
		(end 401.0914 -223.65462)
		(width 0.14478)
		(layer "In13.Cu")
		(net "M_H_CPU0_SA_DQ<15>")
	)
	(segment
		(start 406.54986 -218.400884)
		(end 406.54986 -218.19616)
		(width 0.14478)
		(layer "In13.Cu")
		(net "M_H_CPU0_SA_DQ<15>")
	)
	(segment
		(start 401.171664 -223.159828)
		(end 401.376388 -223.159828)
		(width 0.14478)
		(layer "In13.Cu")
		(net "M_H_CPU0_SA_DQ<15>")
	)
	(segment
		(start 403.715728 -220.820488)
		(end 403.82063 -220.92539)
		(width 0.14478)
		(layer "In13.Cu")
		(net "M_H_CPU0_SA_DQ<15>")
	)
	(segment
		(start 403.245574 -221.70517)
		(end 403.43074 -221.520004)
		(width 0.14478)
		(layer "In13.Cu")
		(net "M_H_CPU0_SA_DQ<15>")
	)
	(segment
		(start 405.38019 -219.36583)
		(end 405.584914 -219.36583)
		(width 0.14478)
		(layer "In13.Cu")
		(net "M_H_CPU0_SA_DQ<15>")
	)
	(arc
		(start 386.787898 -234.441492)
		(mid 386.974842 -234.391237)
		(end 387.161786 -234.441492)
		(width 0.0889)
		(layer "In13.Cu")
		(net "M_H_CPU0_SA_DQ<15>")
	)
	(arc
		(start 389.981948 -234.441492)
		(mid 390.264904 -234.517669)
		(end 390.54786 -234.441492)
		(width 0.0889)
		(layer "In13.Cu")
		(net "M_H_CPU0_SA_DQ<15>")
	)
	(arc
		(start 383.967736 -234.441492)
		(mid 384.149987 -234.391142)
		(end 384.333496 -234.436666)
		(width 0.0889)
		(layer "In13.Cu")
		(net "M_H_CPU0_SA_DQ<15>")
	)
	(arc
		(start 389.616188 -234.436666)
		(mid 389.799696 -234.391172)
		(end 389.981948 -234.441492)
		(width 0.0889)
		(layer "In13.Cu")
		(net "M_H_CPU0_SA_DQ<15>")
	)
	(arc
		(start 385.856226 -234.436666)
		(mid 386.039734 -234.391172)
		(end 386.221986 -234.441492)
		(width 0.0889)
		(layer "In13.Cu")
		(net "M_H_CPU0_SA_DQ<15>")
	)
	(arc
		(start 391.48766 -234.441492)
		(mid 391.577936 -234.403987)
		(end 391.674858 -234.3912)
		(width 0.0889)
		(layer "In13.Cu")
		(net "M_H_CPU0_SA_DQ<15>")
	)
	(arc
		(start 385.281932 -234.441492)
		(mid 385.564888 -234.517669)
		(end 385.847844 -234.441492)
		(width 0.0889)
		(layer "In13.Cu")
		(net "M_H_CPU0_SA_DQ<15>")
	)
	(arc
		(start 384.341878 -234.441492)
		(mid 384.624834 -234.517669)
		(end 384.90779 -234.441492)
		(width 0.0889)
		(layer "In13.Cu")
		(net "M_H_CPU0_SA_DQ<15>")
	)
	(arc
		(start 387.161786 -234.441492)
		(mid 387.444742 -234.517669)
		(end 387.727698 -234.441492)
		(width 0.0889)
		(layer "In13.Cu")
		(net "M_H_CPU0_SA_DQ<15>")
	)
	(arc
		(start 386.221986 -234.441492)
		(mid 386.504942 -234.517669)
		(end 386.787898 -234.441492)
		(width 0.0889)
		(layer "In13.Cu")
		(net "M_H_CPU0_SA_DQ<15>")
	)
	(arc
		(start 383.027682 -234.441492)
		(mid 383.209933 -234.391142)
		(end 383.393442 -234.436666)
		(width 0.0889)
		(layer "In13.Cu")
		(net "M_H_CPU0_SA_DQ<15>")
	)
	(arc
		(start 390.54786 -234.441492)
		(mid 390.734804 -234.391237)
		(end 390.921748 -234.441492)
		(width 0.0889)
		(layer "In13.Cu")
		(net "M_H_CPU0_SA_DQ<15>")
	)
	(arc
		(start 388.10184 -234.441492)
		(mid 388.384796 -234.517669)
		(end 388.667752 -234.441492)
		(width 0.0889)
		(layer "In13.Cu")
		(net "M_H_CPU0_SA_DQ<15>")
	)
	(arc
		(start 384.916172 -234.436666)
		(mid 385.09968 -234.391172)
		(end 385.281932 -234.441492)
		(width 0.0889)
		(layer "In13.Cu")
		(net "M_H_CPU0_SA_DQ<15>")
	)
	(arc
		(start 383.401824 -234.441492)
		(mid 383.68478 -234.517669)
		(end 383.967736 -234.441492)
		(width 0.0889)
		(layer "In13.Cu")
		(net "M_H_CPU0_SA_DQ<15>")
	)
	(arc
		(start 390.921748 -234.441492)
		(mid 391.204704 -234.517669)
		(end 391.48766 -234.441492)
		(width 0.0889)
		(layer "In13.Cu")
		(net "M_H_CPU0_SA_DQ<15>")
	)
	(arc
		(start 382.524762 -234.473242)
		(mid 382.77997 -234.516719)
		(end 383.027682 -234.441492)
		(width 0.0889)
		(layer "In13.Cu")
		(net "M_H_CPU0_SA_DQ<15>")
	)
	(arc
		(start 387.727698 -234.441492)
		(mid 387.909949 -234.391142)
		(end 388.093458 -234.436666)
		(width 0.0889)
		(layer "In13.Cu")
		(net "M_H_CPU0_SA_DQ<15>")
	)
	(arc
		(start 389.041894 -234.441492)
		(mid 389.32485 -234.517669)
		(end 389.607806 -234.441492)
		(width 0.0889)
		(layer "In13.Cu")
		(net "M_H_CPU0_SA_DQ<15>")
	)
	(arc
		(start 388.667752 -234.441492)
		(mid 388.850003 -234.391142)
		(end 389.033512 -234.436666)
		(width 0.0889)
		(layer "In13.Cu")
		(net "M_H_CPU0_SA_DQ<15>")
	)
	(segment
		(start 383.217928 -234.220004)
		(end 383.68478 -233.954066)
		(width 0.10668)
		(layer "F.Cu")
		(net "M_H_CPU0_SA_DQ<14>")
	)
	(segment
		(start 409.964382 -214.694516)
		(end 409.702762 -214.694516)
		(width 0.14478)
		(layer "In13.Cu")
		(net "M_H_CPU0_SA_DQ<14>")
	)
	(segment
		(start 410.109162 -214.549736)
		(end 409.964382 -214.694516)
		(width 0.14478)
		(layer "In13.Cu")
		(net "M_H_CPU0_SA_DQ<14>")
	)
	(segment
		(start 405.464772 -217.594434)
		(end 405.057356 -217.594434)
		(width 0.14478)
		(layer "In13.Cu")
		(net "M_H_CPU0_SA_DQ<14>")
	)
	(segment
		(start 413.850328 -214.054944)
		(end 413.850328 -214.367618)
		(width 0.14478)
		(layer "In13.Cu")
		(net "M_H_CPU0_SA_DQ<14>")
	)
	(segment
		(start 411.066742 -214.694516)
		(end 410.805122 -214.694516)
		(width 0.14478)
		(layer "In13.Cu")
		(net "M_H_CPU0_SA_DQ<14>")
	)
	(segment
		(start 407.990294 -215.068912)
		(end 407.804112 -215.255094)
		(width 0.14478)
		(layer "In13.Cu")
		(net "M_H_CPU0_SA_DQ<14>")
	)
	(segment
		(start 401.565872 -221.493334)
		(end 401.158456 -221.493334)
		(width 0.14478)
		(layer "In13.Cu")
		(net "M_H_CPU0_SA_DQ<14>")
	)
	(segment
		(start 383.838958 -233.688636)
		(end 383.68478 -233.954066)
		(width 0.0889)
		(layer "In13.Cu")
		(net "M_H_CPU0_SA_DQ<14>")
	)
	(segment
		(start 391.026142 -233.62666)
		(end 391.01776 -233.631486)
		(width 0.0889)
		(layer "In13.Cu")
		(net "M_H_CPU0_SA_DQ<14>")
	)
	(segment
		(start 419.912038 -213.616794)
		(end 419.618668 -213.910164)
		(width 0.14478)
		(layer "In13.Cu")
		(net "M_H_CPU0_SA_DQ<14>")
	)
	(segment
		(start 407.210514 -215.848692)
		(end 407.024332 -216.034874)
		(width 0.14478)
		(layer "In13.Cu")
		(net "M_H_CPU0_SA_DQ<14>")
	)
	(segment
		(start 399.766282 -223.292924)
		(end 399.766282 -226.525328)
		(width 0.14478)
		(layer "In13.Cu")
		(net "M_H_CPU0_SA_DQ<14>")
	)
	(segment
		(start 400.378676 -222.273114)
		(end 400.192494 -222.459296)
		(width 0.14478)
		(layer "In13.Cu")
		(net "M_H_CPU0_SA_DQ<14>")
	)
	(segment
		(start 405.650954 -217.000836)
		(end 405.650954 -217.408252)
		(width 0.14478)
		(layer "In13.Cu")
		(net "M_H_CPU0_SA_DQ<14>")
	)
	(segment
		(start 405.057356 -217.594434)
		(end 404.871174 -217.780616)
		(width 0.14478)
		(layer "In13.Cu")
		(net "M_H_CPU0_SA_DQ<14>")
	)
	(segment
		(start 405.650954 -217.408252)
		(end 405.464772 -217.594434)
		(width 0.14478)
		(layer "In13.Cu")
		(net "M_H_CPU0_SA_DQ<14>")
	)
	(segment
		(start 401.752054 -221.307152)
		(end 401.565872 -221.493334)
		(width 0.14478)
		(layer "In13.Cu")
		(net "M_H_CPU0_SA_DQ<14>")
	)
	(segment
		(start 401.938236 -220.713554)
		(end 401.752054 -220.899736)
		(width 0.14478)
		(layer "In13.Cu")
		(net "M_H_CPU0_SA_DQ<14>")
	)
	(segment
		(start 409.149042 -213.910164)
		(end 408.583892 -214.475314)
		(width 0.14478)
		(layer "In13.Cu")
		(net "M_H_CPU0_SA_DQ<14>")
	)
	(segment
		(start 392.5951 -233.01833)
		(end 392.014964 -233.598466)
		(width 0.0889)
		(layer "In13.Cu")
		(net "M_H_CPU0_SA_DQ<14>")
	)
	(segment
		(start 406.244552 -216.814654)
		(end 405.837136 -216.814654)
		(width 0.14478)
		(layer "In13.Cu")
		(net "M_H_CPU0_SA_DQ<14>")
	)
	(segment
		(start 410.515562 -213.910164)
		(end 410.253942 -213.910164)
		(width 0.14478)
		(layer "In13.Cu")
		(net "M_H_CPU0_SA_DQ<14>")
	)
	(segment
		(start 410.660342 -214.054944)
		(end 410.515562 -213.910164)
		(width 0.14478)
		(layer "In13.Cu")
		(net "M_H_CPU0_SA_DQ<14>")
	)
	(segment
		(start 395.05128 -231.24033)
		(end 394.689584 -231.24033)
		(width 0.0889)
		(layer "In13.Cu")
		(net "M_H_CPU0_SA_DQ<14>")
	)
	(segment
		(start 408.176476 -214.475314)
		(end 407.990294 -214.661496)
		(width 0.14478)
		(layer "In13.Cu")
		(net "M_H_CPU0_SA_DQ<14>")
	)
	(segment
		(start 404.091394 -218.967812)
		(end 403.905212 -219.153994)
		(width 0.14478)
		(layer "In13.Cu")
		(net "M_H_CPU0_SA_DQ<14>")
	)
	(segment
		(start 386.691886 -233.631486)
		(end 386.683504 -233.62666)
		(width 0.0889)
		(layer "In13.Cu")
		(net "M_H_CPU0_SA_DQ<14>")
	)
	(segment
		(start 403.125432 -219.933774)
		(end 402.718016 -219.933774)
		(width 0.14478)
		(layer "In13.Cu")
		(net "M_H_CPU0_SA_DQ<14>")
	)
	(segment
		(start 419.618668 -213.910164)
		(end 418.379148 -213.910164)
		(width 0.14478)
		(layer "In13.Cu")
		(net "M_H_CPU0_SA_DQ<14>")
	)
	(segment
		(start 409.702762 -214.694516)
		(end 409.557982 -214.549736)
		(width 0.14478)
		(layer "In13.Cu")
		(net "M_H_CPU0_SA_DQ<14>")
	)
	(segment
		(start 407.024332 -216.034874)
		(end 406.616916 -216.034874)
		(width 0.14478)
		(layer "In13.Cu")
		(net "M_H_CPU0_SA_DQ<14>")
	)
	(segment
		(start 401.752054 -220.899736)
		(end 401.752054 -221.307152)
		(width 0.14478)
		(layer "In13.Cu")
		(net "M_H_CPU0_SA_DQ<14>")
	)
	(segment
		(start 400.192494 -222.866712)
		(end 399.766282 -223.292924)
		(width 0.14478)
		(layer "In13.Cu")
		(net "M_H_CPU0_SA_DQ<14>")
	)
	(segment
		(start 388.206234 -233.62666)
		(end 388.197852 -233.631486)
		(width 0.0889)
		(layer "In13.Cu")
		(net "M_H_CPU0_SA_DQ<14>")
	)
	(segment
		(start 391.402316 -233.637582)
		(end 391.391902 -233.631486)
		(width 0.0889)
		(layer "In13.Cu")
		(net "M_H_CPU0_SA_DQ<14>")
	)
	(segment
		(start 417.52901 -213.060026)
		(end 415.01822 -213.060026)
		(width 0.14478)
		(layer "In13.Cu")
		(net "M_H_CPU0_SA_DQ<14>")
	)
	(segment
		(start 413.850328 -214.367618)
		(end 413.705548 -214.512398)
		(width 0.14478)
		(layer "In13.Cu")
		(net "M_H_CPU0_SA_DQ<14>")
	)
	(segment
		(start 390.451848 -233.631486)
		(end 390.443466 -233.62666)
		(width 0.0889)
		(layer "In13.Cu")
		(net "M_H_CPU0_SA_DQ<14>")
	)
	(segment
		(start 413.705548 -214.512398)
		(end 413.443928 -214.512398)
		(width 0.14478)
		(layer "In13.Cu")
		(net "M_H_CPU0_SA_DQ<14>")
	)
	(segment
		(start 407.990294 -214.661496)
		(end 407.990294 -215.068912)
		(width 0.14478)
		(layer "In13.Cu")
		(net "M_H_CPU0_SA_DQ<14>")
	)
	(segment
		(start 408.583892 -214.475314)
		(end 408.176476 -214.475314)
		(width 0.14478)
		(layer "In13.Cu")
		(net "M_H_CPU0_SA_DQ<14>")
	)
	(segment
		(start 406.616916 -216.034874)
		(end 406.430734 -216.221056)
		(width 0.14478)
		(layer "In13.Cu")
		(net "M_H_CPU0_SA_DQ<14>")
	)
	(segment
		(start 409.557982 -214.549736)
		(end 409.557982 -214.054944)
		(width 0.14478)
		(layer "In13.Cu")
		(net "M_H_CPU0_SA_DQ<14>")
	)
	(segment
		(start 413.995108 -213.910164)
		(end 413.850328 -214.054944)
		(width 0.14478)
		(layer "In13.Cu")
		(net "M_H_CPU0_SA_DQ<14>")
	)
	(segment
		(start 403.497796 -219.153994)
		(end 403.311614 -219.340176)
		(width 0.14478)
		(layer "In13.Cu")
		(net "M_H_CPU0_SA_DQ<14>")
	)
	(segment
		(start 403.905212 -219.153994)
		(end 403.497796 -219.153994)
		(width 0.14478)
		(layer "In13.Cu")
		(net "M_H_CPU0_SA_DQ<14>")
	)
	(segment
		(start 402.531834 -220.527372)
		(end 402.345652 -220.713554)
		(width 0.14478)
		(layer "In13.Cu")
		(net "M_H_CPU0_SA_DQ<14>")
	)
	(segment
		(start 400.972274 -221.679516)
		(end 400.972274 -222.086932)
		(width 0.14478)
		(layer "In13.Cu")
		(net "M_H_CPU0_SA_DQ<14>")
	)
	(segment
		(start 402.718016 -219.933774)
		(end 402.531834 -220.119956)
		(width 0.14478)
		(layer "In13.Cu")
		(net "M_H_CPU0_SA_DQ<14>")
	)
	(segment
		(start 411.211522 -214.549736)
		(end 411.066742 -214.694516)
		(width 0.14478)
		(layer "In13.Cu")
		(net "M_H_CPU0_SA_DQ<14>")
	)
	(segment
		(start 399.766282 -226.525328)
		(end 395.633448 -230.658162)
		(width 0.14478)
		(layer "In13.Cu")
		(net "M_H_CPU0_SA_DQ<14>")
	)
	(segment
		(start 385.751832 -233.631486)
		(end 385.74345 -233.62666)
		(width 0.0889)
		(layer "In13.Cu")
		(net "M_H_CPU0_SA_DQ<14>")
	)
	(segment
		(start 395.633448 -230.658162)
		(end 395.05128 -231.24033)
		(width 0.0889)
		(layer "In13.Cu")
		(net "M_H_CPU0_SA_DQ<14>")
	)
	(segment
		(start 407.804112 -215.255094)
		(end 407.396696 -215.255094)
		(width 0.14478)
		(layer "In13.Cu")
		(net "M_H_CPU0_SA_DQ<14>")
	)
	(segment
		(start 413.299148 -214.054944)
		(end 413.154368 -213.910164)
		(width 0.14478)
		(layer "In13.Cu")
		(net "M_H_CPU0_SA_DQ<14>")
	)
	(segment
		(start 383.935224 -233.663236)
		(end 383.838958 -233.688636)
		(width 0.0889)
		(layer "In13.Cu")
		(net "M_H_CPU0_SA_DQ<14>")
	)
	(segment
		(start 404.277576 -218.374214)
		(end 404.091394 -218.560396)
		(width 0.14478)
		(layer "In13.Cu")
		(net "M_H_CPU0_SA_DQ<14>")
	)
	(segment
		(start 410.805122 -214.694516)
		(end 410.660342 -214.549736)
		(width 0.14478)
		(layer "In13.Cu")
		(net "M_H_CPU0_SA_DQ<14>")
	)
	(segment
		(start 418.379148 -213.910164)
		(end 417.52901 -213.060026)
		(width 0.14478)
		(layer "In13.Cu")
		(net "M_H_CPU0_SA_DQ<14>")
	)
	(segment
		(start 413.154368 -213.910164)
		(end 411.356302 -213.910164)
		(width 0.14478)
		(layer "In13.Cu")
		(net "M_H_CPU0_SA_DQ<14>")
	)
	(segment
		(start 400.786092 -222.273114)
		(end 400.378676 -222.273114)
		(width 0.14478)
		(layer "In13.Cu")
		(net "M_H_CPU0_SA_DQ<14>")
	)
	(segment
		(start 409.413202 -213.910164)
		(end 409.149042 -213.910164)
		(width 0.14478)
		(layer "In13.Cu")
		(net "M_H_CPU0_SA_DQ<14>")
	)
	(segment
		(start 410.109162 -214.054944)
		(end 410.109162 -214.549736)
		(width 0.14478)
		(layer "In13.Cu")
		(net "M_H_CPU0_SA_DQ<14>")
	)
	(segment
		(start 392.014964 -233.598466)
		(end 391.958068 -233.631486)
		(width 0.0889)
		(layer "In13.Cu")
		(net "M_H_CPU0_SA_DQ<14>")
	)
	(segment
		(start 400.972274 -222.086932)
		(end 400.786092 -222.273114)
		(width 0.14478)
		(layer "In13.Cu")
		(net "M_H_CPU0_SA_DQ<14>")
	)
	(segment
		(start 403.311614 -219.747592)
		(end 403.125432 -219.933774)
		(width 0.14478)
		(layer "In13.Cu")
		(net "M_H_CPU0_SA_DQ<14>")
	)
	(segment
		(start 404.091394 -218.560396)
		(end 404.091394 -218.967812)
		(width 0.14478)
		(layer "In13.Cu")
		(net "M_H_CPU0_SA_DQ<14>")
	)
	(segment
		(start 407.210514 -215.441276)
		(end 407.210514 -215.848692)
		(width 0.14478)
		(layer "In13.Cu")
		(net "M_H_CPU0_SA_DQ<14>")
	)
	(segment
		(start 410.253942 -213.910164)
		(end 410.109162 -214.054944)
		(width 0.14478)
		(layer "In13.Cu")
		(net "M_H_CPU0_SA_DQ<14>")
	)
	(segment
		(start 410.660342 -214.549736)
		(end 410.660342 -214.054944)
		(width 0.14478)
		(layer "In13.Cu")
		(net "M_H_CPU0_SA_DQ<14>")
	)
	(segment
		(start 407.396696 -215.255094)
		(end 407.210514 -215.441276)
		(width 0.14478)
		(layer "In13.Cu")
		(net "M_H_CPU0_SA_DQ<14>")
	)
	(segment
		(start 413.443928 -214.512398)
		(end 413.299148 -214.367618)
		(width 0.14478)
		(layer "In13.Cu")
		(net "M_H_CPU0_SA_DQ<14>")
	)
	(segment
		(start 393.434824 -233.01833)
		(end 392.5951 -233.01833)
		(width 0.0889)
		(layer "In13.Cu")
		(net "M_H_CPU0_SA_DQ<14>")
	)
	(segment
		(start 413.299148 -214.367618)
		(end 413.299148 -214.054944)
		(width 0.14478)
		(layer "In13.Cu")
		(net "M_H_CPU0_SA_DQ<14>")
	)
	(segment
		(start 405.837136 -216.814654)
		(end 405.650954 -217.000836)
		(width 0.14478)
		(layer "In13.Cu")
		(net "M_H_CPU0_SA_DQ<14>")
	)
	(segment
		(start 414.168082 -213.910164)
		(end 413.995108 -213.910164)
		(width 0.14478)
		(layer "In13.Cu")
		(net "M_H_CPU0_SA_DQ<14>")
	)
	(segment
		(start 411.356302 -213.910164)
		(end 411.211522 -214.054944)
		(width 0.14478)
		(layer "In13.Cu")
		(net "M_H_CPU0_SA_DQ<14>")
	)
	(segment
		(start 403.311614 -219.340176)
		(end 403.311614 -219.747592)
		(width 0.14478)
		(layer "In13.Cu")
		(net "M_H_CPU0_SA_DQ<14>")
	)
	(segment
		(start 409.557982 -214.054944)
		(end 409.413202 -213.910164)
		(width 0.14478)
		(layer "In13.Cu")
		(net "M_H_CPU0_SA_DQ<14>")
	)
	(segment
		(start 411.211522 -214.054944)
		(end 411.211522 -214.549736)
		(width 0.14478)
		(layer "In13.Cu")
		(net "M_H_CPU0_SA_DQ<14>")
	)
	(segment
		(start 406.430734 -216.628472)
		(end 406.244552 -216.814654)
		(width 0.14478)
		(layer "In13.Cu")
		(net "M_H_CPU0_SA_DQ<14>")
	)
	(segment
		(start 415.01822 -213.060026)
		(end 414.168082 -213.910164)
		(width 0.14478)
		(layer "In13.Cu")
		(net "M_H_CPU0_SA_DQ<14>")
	)
	(segment
		(start 401.158456 -221.493334)
		(end 400.972274 -221.679516)
		(width 0.14478)
		(layer "In13.Cu")
		(net "M_H_CPU0_SA_DQ<14>")
	)
	(segment
		(start 394.264896 -231.665018)
		(end 394.264896 -232.188258)
		(width 0.0889)
		(layer "In13.Cu")
		(net "M_H_CPU0_SA_DQ<14>")
	)
	(segment
		(start 402.531834 -220.119956)
		(end 402.531834 -220.527372)
		(width 0.14478)
		(layer "In13.Cu")
		(net "M_H_CPU0_SA_DQ<14>")
	)
	(segment
		(start 394.264896 -232.188258)
		(end 393.434824 -233.01833)
		(width 0.0889)
		(layer "In13.Cu")
		(net "M_H_CPU0_SA_DQ<14>")
	)
	(segment
		(start 419.912038 -213.484968)
		(end 419.912038 -213.616794)
		(width 0.14478)
		(layer "In13.Cu")
		(net "M_H_CPU0_SA_DQ<14>")
	)
	(segment
		(start 387.26618 -233.62666)
		(end 387.257798 -233.631486)
		(width 0.0889)
		(layer "In13.Cu")
		(net "M_H_CPU0_SA_DQ<14>")
	)
	(segment
		(start 404.684992 -218.374214)
		(end 404.277576 -218.374214)
		(width 0.14478)
		(layer "In13.Cu")
		(net "M_H_CPU0_SA_DQ<14>")
	)
	(segment
		(start 406.430734 -216.221056)
		(end 406.430734 -216.628472)
		(width 0.14478)
		(layer "In13.Cu")
		(net "M_H_CPU0_SA_DQ<14>")
	)
	(segment
		(start 404.871174 -217.780616)
		(end 404.871174 -218.188032)
		(width 0.14478)
		(layer "In13.Cu")
		(net "M_H_CPU0_SA_DQ<14>")
	)
	(segment
		(start 404.871174 -218.188032)
		(end 404.684992 -218.374214)
		(width 0.14478)
		(layer "In13.Cu")
		(net "M_H_CPU0_SA_DQ<14>")
	)
	(segment
		(start 400.192494 -222.459296)
		(end 400.192494 -222.866712)
		(width 0.14478)
		(layer "In13.Cu")
		(net "M_H_CPU0_SA_DQ<14>")
	)
	(segment
		(start 394.689584 -231.24033)
		(end 394.264896 -231.665018)
		(width 0.0889)
		(layer "In13.Cu")
		(net "M_H_CPU0_SA_DQ<14>")
	)
	(segment
		(start 402.345652 -220.713554)
		(end 401.938236 -220.713554)
		(width 0.14478)
		(layer "In13.Cu")
		(net "M_H_CPU0_SA_DQ<14>")
	)
	(arc
		(start 385.74345 -233.62666)
		(mid 385.559942 -233.581166)
		(end 385.37769 -233.631486)
		(width 0.0889)
		(layer "In13.Cu")
		(net "M_H_CPU0_SA_DQ<14>")
	)
	(arc
		(start 391.391902 -233.631486)
		(mid 391.209651 -233.581136)
		(end 391.026142 -233.62666)
		(width 0.0889)
		(layer "In13.Cu")
		(net "M_H_CPU0_SA_DQ<14>")
	)
	(arc
		(start 391.958068 -233.631486)
		(mid 391.681001 -233.707757)
		(end 391.402316 -233.637582)
		(width 0.0889)
		(layer "In13.Cu")
		(net "M_H_CPU0_SA_DQ<14>")
	)
	(arc
		(start 384.43789 -233.631486)
		(mid 384.190294 -233.706664)
		(end 383.935224 -233.663236)
		(width 0.0889)
		(layer "In13.Cu")
		(net "M_H_CPU0_SA_DQ<14>")
	)
	(arc
		(start 384.811778 -233.631486)
		(mid 384.624834 -233.581231)
		(end 384.43789 -233.631486)
		(width 0.0889)
		(layer "In13.Cu")
		(net "M_H_CPU0_SA_DQ<14>")
	)
	(arc
		(start 389.511794 -233.631486)
		(mid 389.32485 -233.581231)
		(end 389.137906 -233.631486)
		(width 0.0889)
		(layer "In13.Cu")
		(net "M_H_CPU0_SA_DQ<14>")
	)
	(arc
		(start 385.37769 -233.631486)
		(mid 385.094734 -233.707663)
		(end 384.811778 -233.631486)
		(width 0.0889)
		(layer "In13.Cu")
		(net "M_H_CPU0_SA_DQ<14>")
	)
	(arc
		(start 387.257798 -233.631486)
		(mid 386.974842 -233.707663)
		(end 386.691886 -233.631486)
		(width 0.0889)
		(layer "In13.Cu")
		(net "M_H_CPU0_SA_DQ<14>")
	)
	(arc
		(start 388.571994 -233.631486)
		(mid 388.389743 -233.581136)
		(end 388.206234 -233.62666)
		(width 0.0889)
		(layer "In13.Cu")
		(net "M_H_CPU0_SA_DQ<14>")
	)
	(arc
		(start 386.683504 -233.62666)
		(mid 386.499996 -233.581166)
		(end 386.317744 -233.631486)
		(width 0.0889)
		(layer "In13.Cu")
		(net "M_H_CPU0_SA_DQ<14>")
	)
	(arc
		(start 389.137906 -233.631486)
		(mid 388.85495 -233.707663)
		(end 388.571994 -233.631486)
		(width 0.0889)
		(layer "In13.Cu")
		(net "M_H_CPU0_SA_DQ<14>")
	)
	(arc
		(start 390.077706 -233.631486)
		(mid 389.79475 -233.707663)
		(end 389.511794 -233.631486)
		(width 0.0889)
		(layer "In13.Cu")
		(net "M_H_CPU0_SA_DQ<14>")
	)
	(arc
		(start 388.197852 -233.631486)
		(mid 387.914896 -233.707663)
		(end 387.63194 -233.631486)
		(width 0.0889)
		(layer "In13.Cu")
		(net "M_H_CPU0_SA_DQ<14>")
	)
	(arc
		(start 390.443466 -233.62666)
		(mid 390.259958 -233.581166)
		(end 390.077706 -233.631486)
		(width 0.0889)
		(layer "In13.Cu")
		(net "M_H_CPU0_SA_DQ<14>")
	)
	(arc
		(start 386.317744 -233.631486)
		(mid 386.034788 -233.707663)
		(end 385.751832 -233.631486)
		(width 0.0889)
		(layer "In13.Cu")
		(net "M_H_CPU0_SA_DQ<14>")
	)
	(arc
		(start 387.63194 -233.631486)
		(mid 387.449689 -233.581136)
		(end 387.26618 -233.62666)
		(width 0.0889)
		(layer "In13.Cu")
		(net "M_H_CPU0_SA_DQ<14>")
	)
	(arc
		(start 391.01776 -233.631486)
		(mid 390.734804 -233.707663)
		(end 390.451848 -233.631486)
		(width 0.0889)
		(layer "In13.Cu")
		(net "M_H_CPU0_SA_DQ<14>")
	)
	(segment
		(start 382.277874 -234.220004)
		(end 382.744726 -233.954066)
		(width 0.10668)
		(layer "F.Cu")
		(net "M_H_CPU0_SA_DQ<13>")
	)
	(segment
		(start 385.751832 -234.276646)
		(end 385.74345 -234.281472)
		(width 0.0889)
		(layer "In13.Cu")
		(net "M_H_CPU0_SA_DQ<13>")
	)
	(segment
		(start 395.334998 -231.675432)
		(end 395.329156 -231.675432)
		(width 0.0889)
		(layer "In13.Cu")
		(net "M_H_CPU0_SA_DQ<13>")
	)
	(segment
		(start 421.336724 -214.904828)
		(end 421.191944 -214.760048)
		(width 0.14478)
		(layer "In13.Cu")
		(net "M_H_CPU0_SA_DQ<13>")
	)
	(segment
		(start 422.439084 -215.00211)
		(end 422.439084 -214.904828)
		(width 0.14478)
		(layer "In13.Cu")
		(net "M_H_CPU0_SA_DQ<13>")
	)
	(segment
		(start 422.032684 -214.760048)
		(end 421.887904 -214.904828)
		(width 0.14478)
		(layer "In13.Cu")
		(net "M_H_CPU0_SA_DQ<13>")
	)
	(segment
		(start 386.691886 -234.276646)
		(end 386.683504 -234.281472)
		(width 0.0889)
		(layer "In13.Cu")
		(net "M_H_CPU0_SA_DQ<13>")
	)
	(segment
		(start 421.887904 -214.904828)
		(end 421.887904 -215.00211)
		(width 0.14478)
		(layer "In13.Cu")
		(net "M_H_CPU0_SA_DQ<13>")
	)
	(segment
		(start 421.191944 -214.760048)
		(end 418.469572 -214.760048)
		(width 0.14478)
		(layer "In13.Cu")
		(net "M_H_CPU0_SA_DQ<13>")
	)
	(segment
		(start 382.613154 -234.302808)
		(end 382.590802 -234.219496)
		(width 0.0889)
		(layer "In13.Cu")
		(net "M_H_CPU0_SA_DQ<13>")
	)
	(segment
		(start 393.686538 -233.31805)
		(end 392.866372 -233.31805)
		(width 0.0889)
		(layer "In13.Cu")
		(net "M_H_CPU0_SA_DQ<13>")
	)
	(segment
		(start 395.329156 -231.675432)
		(end 393.686538 -233.31805)
		(width 0.0889)
		(layer "In13.Cu")
		(net "M_H_CPU0_SA_DQ<13>")
	)
	(segment
		(start 387.26618 -234.281472)
		(end 387.257798 -234.276646)
		(width 0.0889)
		(layer "In13.Cu")
		(net "M_H_CPU0_SA_DQ<13>")
	)
	(segment
		(start 400.215862 -226.794568)
		(end 395.896338 -231.114092)
		(width 0.14478)
		(layer "In13.Cu")
		(net "M_H_CPU0_SA_DQ<13>")
	)
	(segment
		(start 422.990264 -215.00211)
		(end 422.845484 -215.14689)
		(width 0.14478)
		(layer "In13.Cu")
		(net "M_H_CPU0_SA_DQ<13>")
	)
	(segment
		(start 421.336724 -215.00211)
		(end 421.336724 -214.904828)
		(width 0.14478)
		(layer "In13.Cu")
		(net "M_H_CPU0_SA_DQ<13>")
	)
	(segment
		(start 422.294304 -214.760048)
		(end 422.032684 -214.760048)
		(width 0.14478)
		(layer "In13.Cu")
		(net "M_H_CPU0_SA_DQ<13>")
	)
	(segment
		(start 415.012124 -213.910164)
		(end 413.761682 -215.160606)
		(width 0.14478)
		(layer "In13.Cu")
		(net "M_H_CPU0_SA_DQ<13>")
	)
	(segment
		(start 421.887904 -215.00211)
		(end 421.743124 -215.14689)
		(width 0.14478)
		(layer "In13.Cu")
		(net "M_H_CPU0_SA_DQ<13>")
	)
	(segment
		(start 421.481504 -215.14689)
		(end 421.336724 -215.00211)
		(width 0.14478)
		(layer "In13.Cu")
		(net "M_H_CPU0_SA_DQ<13>")
	)
	(segment
		(start 408.534616 -215.160606)
		(end 400.215862 -223.47936)
		(width 0.14478)
		(layer "In13.Cu")
		(net "M_H_CPU0_SA_DQ<13>")
	)
	(segment
		(start 382.590802 -234.219496)
		(end 382.744726 -233.954066)
		(width 0.0889)
		(layer "In13.Cu")
		(net "M_H_CPU0_SA_DQ<13>")
	)
	(segment
		(start 417.619688 -213.910164)
		(end 415.012124 -213.910164)
		(width 0.14478)
		(layer "In13.Cu")
		(net "M_H_CPU0_SA_DQ<13>")
	)
	(segment
		(start 395.896338 -231.114092)
		(end 395.334998 -231.675432)
		(width 0.0889)
		(layer "In13.Cu")
		(net "M_H_CPU0_SA_DQ<13>")
	)
	(segment
		(start 423.135044 -214.760048)
		(end 422.990264 -214.904828)
		(width 0.14478)
		(layer "In13.Cu")
		(net "M_H_CPU0_SA_DQ<13>")
	)
	(segment
		(start 391.98423 -234.200192)
		(end 391.674858 -234.200192)
		(width 0.0889)
		(layer "In13.Cu")
		(net "M_H_CPU0_SA_DQ<13>")
	)
	(segment
		(start 423.587164 -214.760048)
		(end 423.135044 -214.760048)
		(width 0.14478)
		(layer "In13.Cu")
		(net "M_H_CPU0_SA_DQ<13>")
	)
	(segment
		(start 418.469572 -214.760048)
		(end 417.619688 -213.910164)
		(width 0.14478)
		(layer "In13.Cu")
		(net "M_H_CPU0_SA_DQ<13>")
	)
	(segment
		(start 390.451848 -234.276646)
		(end 390.443466 -234.281472)
		(width 0.0889)
		(layer "In13.Cu")
		(net "M_H_CPU0_SA_DQ<13>")
	)
	(segment
		(start 391.026142 -234.281472)
		(end 391.01776 -234.276646)
		(width 0.0889)
		(layer "In13.Cu")
		(net "M_H_CPU0_SA_DQ<13>")
	)
	(segment
		(start 400.215862 -223.47936)
		(end 400.215862 -226.794568)
		(width 0.14478)
		(layer "In13.Cu")
		(net "M_H_CPU0_SA_DQ<13>")
	)
	(segment
		(start 422.990264 -214.904828)
		(end 422.990264 -215.00211)
		(width 0.14478)
		(layer "In13.Cu")
		(net "M_H_CPU0_SA_DQ<13>")
	)
	(segment
		(start 392.866372 -233.31805)
		(end 391.98423 -234.200192)
		(width 0.0889)
		(layer "In13.Cu")
		(net "M_H_CPU0_SA_DQ<13>")
	)
	(segment
		(start 424.012106 -214.335106)
		(end 423.587164 -214.760048)
		(width 0.14478)
		(layer "In13.Cu")
		(net "M_H_CPU0_SA_DQ<13>")
	)
	(segment
		(start 383.506218 -234.281472)
		(end 383.497836 -234.276646)
		(width 0.0889)
		(layer "In13.Cu")
		(net "M_H_CPU0_SA_DQ<13>")
	)
	(segment
		(start 388.206234 -234.281472)
		(end 388.197852 -234.276646)
		(width 0.0889)
		(layer "In13.Cu")
		(net "M_H_CPU0_SA_DQ<13>")
	)
	(segment
		(start 391.406634 -234.26801)
		(end 391.391902 -234.276646)
		(width 0.0889)
		(layer "In13.Cu")
		(net "M_H_CPU0_SA_DQ<13>")
	)
	(segment
		(start 422.583864 -215.14689)
		(end 422.439084 -215.00211)
		(width 0.14478)
		(layer "In13.Cu")
		(net "M_H_CPU0_SA_DQ<13>")
	)
	(segment
		(start 421.743124 -215.14689)
		(end 421.481504 -215.14689)
		(width 0.14478)
		(layer "In13.Cu")
		(net "M_H_CPU0_SA_DQ<13>")
	)
	(segment
		(start 413.761682 -215.160606)
		(end 408.534616 -215.160606)
		(width 0.14478)
		(layer "In13.Cu")
		(net "M_H_CPU0_SA_DQ<13>")
	)
	(segment
		(start 422.845484 -215.14689)
		(end 422.583864 -215.14689)
		(width 0.14478)
		(layer "In13.Cu")
		(net "M_H_CPU0_SA_DQ<13>")
	)
	(segment
		(start 422.439084 -214.904828)
		(end 422.294304 -214.760048)
		(width 0.14478)
		(layer "In13.Cu")
		(net "M_H_CPU0_SA_DQ<13>")
	)
	(arc
		(start 384.811778 -234.276646)
		(mid 384.624834 -234.326901)
		(end 384.43789 -234.276646)
		(width 0.0889)
		(layer "In13.Cu")
		(net "M_H_CPU0_SA_DQ<13>")
	)
	(arc
		(start 385.74345 -234.281472)
		(mid 385.559942 -234.326966)
		(end 385.37769 -234.276646)
		(width 0.0889)
		(layer "In13.Cu")
		(net "M_H_CPU0_SA_DQ<13>")
	)
	(arc
		(start 391.391902 -234.276646)
		(mid 391.209651 -234.326996)
		(end 391.026142 -234.281472)
		(width 0.0889)
		(layer "In13.Cu")
		(net "M_H_CPU0_SA_DQ<13>")
	)
	(arc
		(start 390.077706 -234.276646)
		(mid 389.79475 -234.200469)
		(end 389.511794 -234.276646)
		(width 0.0889)
		(layer "In13.Cu")
		(net "M_H_CPU0_SA_DQ<13>")
	)
	(arc
		(start 390.443466 -234.281472)
		(mid 390.259958 -234.326966)
		(end 390.077706 -234.276646)
		(width 0.0889)
		(layer "In13.Cu")
		(net "M_H_CPU0_SA_DQ<13>")
	)
	(arc
		(start 391.674858 -234.200192)
		(mid 391.536532 -234.217422)
		(end 391.406634 -234.26801)
		(width 0.0889)
		(layer "In13.Cu")
		(net "M_H_CPU0_SA_DQ<13>")
	)
	(arc
		(start 383.497836 -234.276646)
		(mid 383.21488 -234.200469)
		(end 382.931924 -234.276646)
		(width 0.0889)
		(layer "In13.Cu")
		(net "M_H_CPU0_SA_DQ<13>")
	)
	(arc
		(start 385.37769 -234.276646)
		(mid 385.094734 -234.200469)
		(end 384.811778 -234.276646)
		(width 0.0889)
		(layer "In13.Cu")
		(net "M_H_CPU0_SA_DQ<13>")
	)
	(arc
		(start 389.511794 -234.276646)
		(mid 389.32485 -234.326901)
		(end 389.137906 -234.276646)
		(width 0.0889)
		(layer "In13.Cu")
		(net "M_H_CPU0_SA_DQ<13>")
	)
	(arc
		(start 388.571994 -234.276646)
		(mid 388.389743 -234.326996)
		(end 388.206234 -234.281472)
		(width 0.0889)
		(layer "In13.Cu")
		(net "M_H_CPU0_SA_DQ<13>")
	)
	(arc
		(start 386.317744 -234.276646)
		(mid 386.034788 -234.200469)
		(end 385.751832 -234.276646)
		(width 0.0889)
		(layer "In13.Cu")
		(net "M_H_CPU0_SA_DQ<13>")
	)
	(arc
		(start 383.871978 -234.276646)
		(mid 383.689727 -234.326996)
		(end 383.506218 -234.281472)
		(width 0.0889)
		(layer "In13.Cu")
		(net "M_H_CPU0_SA_DQ<13>")
	)
	(arc
		(start 384.43789 -234.276646)
		(mid 384.154934 -234.200469)
		(end 383.871978 -234.276646)
		(width 0.0889)
		(layer "In13.Cu")
		(net "M_H_CPU0_SA_DQ<13>")
	)
	(arc
		(start 387.257798 -234.276646)
		(mid 386.974842 -234.200469)
		(end 386.691886 -234.276646)
		(width 0.0889)
		(layer "In13.Cu")
		(net "M_H_CPU0_SA_DQ<13>")
	)
	(arc
		(start 387.63194 -234.276646)
		(mid 387.449689 -234.326996)
		(end 387.26618 -234.281472)
		(width 0.0889)
		(layer "In13.Cu")
		(net "M_H_CPU0_SA_DQ<13>")
	)
	(arc
		(start 389.137906 -234.276646)
		(mid 388.85495 -234.200469)
		(end 388.571994 -234.276646)
		(width 0.0889)
		(layer "In13.Cu")
		(net "M_H_CPU0_SA_DQ<13>")
	)
	(arc
		(start 388.197852 -234.276646)
		(mid 387.914896 -234.200469)
		(end 387.63194 -234.276646)
		(width 0.0889)
		(layer "In13.Cu")
		(net "M_H_CPU0_SA_DQ<13>")
	)
	(arc
		(start 391.01776 -234.276646)
		(mid 390.734804 -234.200469)
		(end 390.451848 -234.276646)
		(width 0.0889)
		(layer "In13.Cu")
		(net "M_H_CPU0_SA_DQ<13>")
	)
	(arc
		(start 386.683504 -234.281472)
		(mid 386.499996 -234.326966)
		(end 386.317744 -234.276646)
		(width 0.0889)
		(layer "In13.Cu")
		(net "M_H_CPU0_SA_DQ<13>")
	)
	(arc
		(start 382.931924 -234.276646)
		(mid 382.775486 -234.325617)
		(end 382.613154 -234.302808)
		(width 0.0889)
		(layer "In13.Cu")
		(net "M_H_CPU0_SA_DQ<13>")
	)
	(segment
		(start 383.688082 -233.409998)
		(end 384.154934 -233.14406)
		(width 0.10668)
		(layer "F.Cu")
		(net "M_H_CPU0_SA_DQ<12>")
	)
	(segment
		(start 384.341878 -233.46664)
		(end 384.333496 -233.471466)
		(width 0.0889)
		(layer "In13.Cu")
		(net "M_H_CPU0_SA_DQ<12>")
	)
	(segment
		(start 384.916172 -233.471466)
		(end 384.90779 -233.46664)
		(width 0.0889)
		(layer "In13.Cu")
		(net "M_H_CPU0_SA_DQ<12>")
	)
	(segment
		(start 421.07485 -213.303866)
		(end 420.93007 -213.448646)
		(width 0.14478)
		(layer "In13.Cu")
		(net "M_H_CPU0_SA_DQ<12>")
	)
	(segment
		(start 420.52367 -213.303866)
		(end 420.52367 -213.214458)
		(width 0.14478)
		(layer "In13.Cu")
		(net "M_H_CPU0_SA_DQ<12>")
	)
	(segment
		(start 423.577512 -213.069678)
		(end 423.42435 -213.069678)
		(width 0.14478)
		(layer "In13.Cu")
		(net "M_H_CPU0_SA_DQ<12>")
	)
	(segment
		(start 393.990576 -231.56291)
		(end 393.990576 -232.05313)
		(width 0.0889)
		(layer "In13.Cu")
		(net "M_H_CPU0_SA_DQ<12>")
	)
	(segment
		(start 421.62603 -213.214458)
		(end 421.48125 -213.069678)
		(width 0.14478)
		(layer "In13.Cu")
		(net "M_H_CPU0_SA_DQ<12>")
	)
	(segment
		(start 420.66845 -213.448646)
		(end 420.52367 -213.303866)
		(width 0.14478)
		(layer "In13.Cu")
		(net "M_H_CPU0_SA_DQ<12>")
	)
	(segment
		(start 399.316702 -226.236784)
		(end 395.185646 -230.36784)
		(width 0.14478)
		(layer "In13.Cu")
		(net "M_H_CPU0_SA_DQ<12>")
	)
	(segment
		(start 423.42435 -213.069678)
		(end 423.27957 -213.214458)
		(width 0.14478)
		(layer "In13.Cu")
		(net "M_H_CPU0_SA_DQ<12>")
	)
	(segment
		(start 395.185646 -230.36784)
		(end 393.990576 -231.56291)
		(width 0.0889)
		(layer "In13.Cu")
		(net "M_H_CPU0_SA_DQ<12>")
	)
	(segment
		(start 392.59256 -232.73639)
		(end 391.86231 -233.46664)
		(width 0.0889)
		(layer "In13.Cu")
		(net "M_H_CPU0_SA_DQ<12>")
	)
	(segment
		(start 421.48125 -213.069678)
		(end 421.21963 -213.069678)
		(width 0.14478)
		(layer "In13.Cu")
		(net "M_H_CPU0_SA_DQ<12>")
	)
	(segment
		(start 420.37889 -213.069678)
		(end 418.34562 -213.069678)
		(width 0.14478)
		(layer "In13.Cu")
		(net "M_H_CPU0_SA_DQ<12>")
	)
	(segment
		(start 393.307316 -232.73639)
		(end 392.59256 -232.73639)
		(width 0.0889)
		(layer "In13.Cu")
		(net "M_H_CPU0_SA_DQ<12>")
	)
	(segment
		(start 422.32199 -213.069678)
		(end 422.17721 -213.214458)
		(width 0.14478)
		(layer "In13.Cu")
		(net "M_H_CPU0_SA_DQ<12>")
	)
	(segment
		(start 417.486084 -212.210142)
		(end 415.120328 -212.210142)
		(width 0.14478)
		(layer "In13.Cu")
		(net "M_H_CPU0_SA_DQ<12>")
	)
	(segment
		(start 421.21963 -213.069678)
		(end 421.07485 -213.214458)
		(width 0.14478)
		(layer "In13.Cu")
		(net "M_H_CPU0_SA_DQ<12>")
	)
	(segment
		(start 399.316702 -222.699072)
		(end 399.316702 -226.236784)
		(width 0.14478)
		(layer "In13.Cu")
		(net "M_H_CPU0_SA_DQ<12>")
	)
	(segment
		(start 389.041894 -233.46664)
		(end 389.033512 -233.471466)
		(width 0.0889)
		(layer "In13.Cu")
		(net "M_H_CPU0_SA_DQ<12>")
	)
	(segment
		(start 423.13479 -213.448646)
		(end 422.87317 -213.448646)
		(width 0.14478)
		(layer "In13.Cu")
		(net "M_H_CPU0_SA_DQ<12>")
	)
	(segment
		(start 391.496042 -233.471466)
		(end 391.48766 -233.46664)
		(width 0.0889)
		(layer "In13.Cu")
		(net "M_H_CPU0_SA_DQ<12>")
	)
	(segment
		(start 421.62603 -213.303866)
		(end 421.62603 -213.214458)
		(width 0.14478)
		(layer "In13.Cu")
		(net "M_H_CPU0_SA_DQ<12>")
	)
	(segment
		(start 421.77081 -213.448646)
		(end 421.62603 -213.303866)
		(width 0.14478)
		(layer "In13.Cu")
		(net "M_H_CPU0_SA_DQ<12>")
	)
	(segment
		(start 422.72839 -213.214458)
		(end 422.58361 -213.069678)
		(width 0.14478)
		(layer "In13.Cu")
		(net "M_H_CPU0_SA_DQ<12>")
	)
	(segment
		(start 413.869886 -213.460584)
		(end 408.55519 -213.460584)
		(width 0.14478)
		(layer "In13.Cu")
		(net "M_H_CPU0_SA_DQ<12>")
	)
	(segment
		(start 408.55519 -213.460584)
		(end 399.316702 -222.699072)
		(width 0.14478)
		(layer "In13.Cu")
		(net "M_H_CPU0_SA_DQ<12>")
	)
	(segment
		(start 423.27957 -213.214458)
		(end 423.27957 -213.303866)
		(width 0.14478)
		(layer "In13.Cu")
		(net "M_H_CPU0_SA_DQ<12>")
	)
	(segment
		(start 422.17721 -213.303866)
		(end 422.03243 -213.448646)
		(width 0.14478)
		(layer "In13.Cu")
		(net "M_H_CPU0_SA_DQ<12>")
	)
	(segment
		(start 423.27957 -213.303866)
		(end 423.13479 -213.448646)
		(width 0.14478)
		(layer "In13.Cu")
		(net "M_H_CPU0_SA_DQ<12>")
	)
	(segment
		(start 421.07485 -213.214458)
		(end 421.07485 -213.303866)
		(width 0.14478)
		(layer "In13.Cu")
		(net "M_H_CPU0_SA_DQ<12>")
	)
	(segment
		(start 422.72839 -213.303866)
		(end 422.72839 -213.214458)
		(width 0.14478)
		(layer "In13.Cu")
		(net "M_H_CPU0_SA_DQ<12>")
	)
	(segment
		(start 424.012106 -212.635084)
		(end 423.577512 -213.069678)
		(width 0.14478)
		(layer "In13.Cu")
		(net "M_H_CPU0_SA_DQ<12>")
	)
	(segment
		(start 393.990576 -232.05313)
		(end 393.307316 -232.73639)
		(width 0.0889)
		(layer "In13.Cu")
		(net "M_H_CPU0_SA_DQ<12>")
	)
	(segment
		(start 420.52367 -213.214458)
		(end 420.37889 -213.069678)
		(width 0.14478)
		(layer "In13.Cu")
		(net "M_H_CPU0_SA_DQ<12>")
	)
	(segment
		(start 422.87317 -213.448646)
		(end 422.72839 -213.303866)
		(width 0.14478)
		(layer "In13.Cu")
		(net "M_H_CPU0_SA_DQ<12>")
	)
	(segment
		(start 418.34562 -213.069678)
		(end 417.486084 -212.210142)
		(width 0.14478)
		(layer "In13.Cu")
		(net "M_H_CPU0_SA_DQ<12>")
	)
	(segment
		(start 420.93007 -213.448646)
		(end 420.66845 -213.448646)
		(width 0.14478)
		(layer "In13.Cu")
		(net "M_H_CPU0_SA_DQ<12>")
	)
	(segment
		(start 422.58361 -213.069678)
		(end 422.32199 -213.069678)
		(width 0.14478)
		(layer "In13.Cu")
		(net "M_H_CPU0_SA_DQ<12>")
	)
	(segment
		(start 389.616188 -233.471466)
		(end 389.607806 -233.46664)
		(width 0.0889)
		(layer "In13.Cu")
		(net "M_H_CPU0_SA_DQ<12>")
	)
	(segment
		(start 422.03243 -213.448646)
		(end 421.77081 -213.448646)
		(width 0.14478)
		(layer "In13.Cu")
		(net "M_H_CPU0_SA_DQ<12>")
	)
	(segment
		(start 388.10184 -233.46664)
		(end 388.093458 -233.471466)
		(width 0.0889)
		(layer "In13.Cu")
		(net "M_H_CPU0_SA_DQ<12>")
	)
	(segment
		(start 415.120328 -212.210142)
		(end 413.869886 -213.460584)
		(width 0.14478)
		(layer "In13.Cu")
		(net "M_H_CPU0_SA_DQ<12>")
	)
	(segment
		(start 422.17721 -213.214458)
		(end 422.17721 -213.303866)
		(width 0.14478)
		(layer "In13.Cu")
		(net "M_H_CPU0_SA_DQ<12>")
	)
	(segment
		(start 385.856226 -233.471466)
		(end 385.847844 -233.46664)
		(width 0.0889)
		(layer "In13.Cu")
		(net "M_H_CPU0_SA_DQ<12>")
	)
	(segment
		(start 384.023108 -233.492802)
		(end 384.000756 -233.40949)
		(width 0.0889)
		(layer "In13.Cu")
		(net "M_H_CPU0_SA_DQ<12>")
	)
	(segment
		(start 384.000756 -233.40949)
		(end 384.154934 -233.14406)
		(width 0.0889)
		(layer "In13.Cu")
		(net "M_H_CPU0_SA_DQ<12>")
	)
	(arc
		(start 385.847844 -233.46664)
		(mid 385.564888 -233.390463)
		(end 385.281932 -233.46664)
		(width 0.0889)
		(layer "In13.Cu")
		(net "M_H_CPU0_SA_DQ<12>")
	)
	(arc
		(start 387.727698 -233.46664)
		(mid 387.444742 -233.390463)
		(end 387.161786 -233.46664)
		(width 0.0889)
		(layer "In13.Cu")
		(net "M_H_CPU0_SA_DQ<12>")
	)
	(arc
		(start 386.221986 -233.46664)
		(mid 386.039735 -233.51699)
		(end 385.856226 -233.471466)
		(width 0.0889)
		(layer "In13.Cu")
		(net "M_H_CPU0_SA_DQ<12>")
	)
	(arc
		(start 384.90779 -233.46664)
		(mid 384.624834 -233.390463)
		(end 384.341878 -233.46664)
		(width 0.0889)
		(layer "In13.Cu")
		(net "M_H_CPU0_SA_DQ<12>")
	)
	(arc
		(start 391.86231 -233.46664)
		(mid 391.679805 -233.517117)
		(end 391.496042 -233.471466)
		(width 0.0889)
		(layer "In13.Cu")
		(net "M_H_CPU0_SA_DQ<12>")
	)
	(arc
		(start 388.667752 -233.46664)
		(mid 388.384796 -233.390463)
		(end 388.10184 -233.46664)
		(width 0.0889)
		(layer "In13.Cu")
		(net "M_H_CPU0_SA_DQ<12>")
	)
	(arc
		(start 386.787898 -233.46664)
		(mid 386.504942 -233.390463)
		(end 386.221986 -233.46664)
		(width 0.0889)
		(layer "In13.Cu")
		(net "M_H_CPU0_SA_DQ<12>")
	)
	(arc
		(start 388.093458 -233.471466)
		(mid 387.90995 -233.51696)
		(end 387.727698 -233.46664)
		(width 0.0889)
		(layer "In13.Cu")
		(net "M_H_CPU0_SA_DQ<12>")
	)
	(arc
		(start 391.48766 -233.46664)
		(mid 391.204704 -233.390463)
		(end 390.921748 -233.46664)
		(width 0.0889)
		(layer "In13.Cu")
		(net "M_H_CPU0_SA_DQ<12>")
	)
	(arc
		(start 390.54786 -233.46664)
		(mid 390.264904 -233.390463)
		(end 389.981948 -233.46664)
		(width 0.0889)
		(layer "In13.Cu")
		(net "M_H_CPU0_SA_DQ<12>")
	)
	(arc
		(start 385.281932 -233.46664)
		(mid 385.099681 -233.51699)
		(end 384.916172 -233.471466)
		(width 0.0889)
		(layer "In13.Cu")
		(net "M_H_CPU0_SA_DQ<12>")
	)
	(arc
		(start 389.607806 -233.46664)
		(mid 389.32485 -233.390463)
		(end 389.041894 -233.46664)
		(width 0.0889)
		(layer "In13.Cu")
		(net "M_H_CPU0_SA_DQ<12>")
	)
	(arc
		(start 389.033512 -233.471466)
		(mid 388.850004 -233.51696)
		(end 388.667752 -233.46664)
		(width 0.0889)
		(layer "In13.Cu")
		(net "M_H_CPU0_SA_DQ<12>")
	)
	(arc
		(start 389.981948 -233.46664)
		(mid 389.799697 -233.51699)
		(end 389.616188 -233.471466)
		(width 0.0889)
		(layer "In13.Cu")
		(net "M_H_CPU0_SA_DQ<12>")
	)
	(arc
		(start 384.333496 -233.471466)
		(mid 384.180626 -233.516107)
		(end 384.023108 -233.492802)
		(width 0.0889)
		(layer "In13.Cu")
		(net "M_H_CPU0_SA_DQ<12>")
	)
	(arc
		(start 387.161786 -233.46664)
		(mid 386.974842 -233.516895)
		(end 386.787898 -233.46664)
		(width 0.0889)
		(layer "In13.Cu")
		(net "M_H_CPU0_SA_DQ<12>")
	)
	(arc
		(start 390.921748 -233.46664)
		(mid 390.734804 -233.516895)
		(end 390.54786 -233.46664)
		(width 0.0889)
		(layer "In13.Cu")
		(net "M_H_CPU0_SA_DQ<12>")
	)
	(segment
		(start 381.807974 -231.789986)
		(end 382.274826 -231.524048)
		(width 0.10668)
		(layer "F.Cu")
		(net "M_H_CPU0_SA_DQ<11>")
	)
	(segment
		(start 399.245328 -218.898978)
		(end 399.315178 -218.968828)
		(width 0.14478)
		(layer "In13.Cu")
		(net "M_H_CPU0_SA_DQ<11>")
	)
	(segment
		(start 399.519902 -218.968828)
		(end 399.705068 -218.783662)
		(width 0.14478)
		(layer "In13.Cu")
		(net "M_H_CPU0_SA_DQ<11>")
	)
	(segment
		(start 414.855914 -208.810098)
		(end 418.13988 -208.810098)
		(width 0.14478)
		(layer "In13.Cu")
		(net "M_H_CPU0_SA_DQ<11>")
	)
	(segment
		(start 398.465548 -219.678758)
		(end 398.535398 -219.748608)
		(width 0.14478)
		(layer "In13.Cu")
		(net "M_H_CPU0_SA_DQ<11>")
	)
	(segment
		(start 403.144228 -215.000078)
		(end 403.214078 -215.069928)
		(width 0.14478)
		(layer "In13.Cu")
		(net "M_H_CPU0_SA_DQ<11>")
	)
	(segment
		(start 397.295878 -220.643704)
		(end 397.481044 -220.458538)
		(width 0.14478)
		(layer "In13.Cu")
		(net "M_H_CPU0_SA_DQ<11>")
	)
	(segment
		(start 397.365728 -220.918278)
		(end 397.295878 -220.848428)
		(width 0.14478)
		(layer "In13.Cu")
		(net "M_H_CPU0_SA_DQ<11>")
	)
	(segment
		(start 389.033512 -231.196896)
		(end 389.041894 -231.201722)
		(width 0.0889)
		(layer "In13.Cu")
		(net "M_H_CPU0_SA_DQ<11>")
	)
	(segment
		(start 399.705068 -218.578938)
		(end 399.635218 -218.509088)
		(width 0.14478)
		(layer "In13.Cu")
		(net "M_H_CPU0_SA_DQ<11>")
	)
	(segment
		(start 402.754338 -215.185244)
		(end 402.939504 -215.000078)
		(width 0.14478)
		(layer "In13.Cu")
		(net "M_H_CPU0_SA_DQ<11>")
	)
	(segment
		(start 400.484848 -218.003882)
		(end 400.484848 -217.799158)
		(width 0.14478)
		(layer "In13.Cu")
		(net "M_H_CPU0_SA_DQ<11>")
	)
	(segment
		(start 401.584668 -216.559638)
		(end 401.654518 -216.629488)
		(width 0.14478)
		(layer "In13.Cu")
		(net "M_H_CPU0_SA_DQ<11>")
	)
	(segment
		(start 399.820384 -218.119198)
		(end 400.025108 -218.119198)
		(width 0.14478)
		(layer "In13.Cu")
		(net "M_H_CPU0_SA_DQ<11>")
	)
	(segment
		(start 385.847844 -231.201722)
		(end 385.856226 -231.196896)
		(width 0.0889)
		(layer "In13.Cu")
		(net "M_H_CPU0_SA_DQ<11>")
	)
	(segment
		(start 402.824188 -215.459818)
		(end 402.754338 -215.389968)
		(width 0.14478)
		(layer "In13.Cu")
		(net "M_H_CPU0_SA_DQ<11>")
	)
	(segment
		(start 398.145508 -220.343222)
		(end 398.145508 -220.138498)
		(width 0.14478)
		(layer "In13.Cu")
		(net "M_H_CPU0_SA_DQ<11>")
	)
	(segment
		(start 388.093458 -231.196896)
		(end 388.10184 -231.201722)
		(width 0.0889)
		(layer "In13.Cu")
		(net "M_H_CPU0_SA_DQ<11>")
	)
	(segment
		(start 382.42875 -231.258618)
		(end 382.524508 -231.233218)
		(width 0.0889)
		(layer "In13.Cu")
		(net "M_H_CPU0_SA_DQ<11>")
	)
	(segment
		(start 399.635218 -218.304364)
		(end 399.820384 -218.119198)
		(width 0.14478)
		(layer "In13.Cu")
		(net "M_H_CPU0_SA_DQ<11>")
	)
	(segment
		(start 403.214078 -215.069928)
		(end 403.418802 -215.069928)
		(width 0.14478)
		(layer "In13.Cu")
		(net "M_H_CPU0_SA_DQ<11>")
	)
	(segment
		(start 401.194778 -216.949528)
		(end 401.194778 -216.744804)
		(width 0.14478)
		(layer "In13.Cu")
		(net "M_H_CPU0_SA_DQ<11>")
	)
	(segment
		(start 400.414998 -217.729308)
		(end 400.414998 -217.524584)
		(width 0.14478)
		(layer "In13.Cu")
		(net "M_H_CPU0_SA_DQ<11>")
	)
	(segment
		(start 391.925048 -230.410766)
		(end 392.332718 -230.181912)
		(width 0.0889)
		(layer "In13.Cu")
		(net "M_H_CPU0_SA_DQ<11>")
	)
	(segment
		(start 397.295878 -220.848428)
		(end 397.295878 -220.643704)
		(width 0.14478)
		(layer "In13.Cu")
		(net "M_H_CPU0_SA_DQ<11>")
	)
	(segment
		(start 391.48766 -231.201722)
		(end 391.526776 -231.178862)
		(width 0.0889)
		(layer "In13.Cu")
		(net "M_H_CPU0_SA_DQ<11>")
	)
	(segment
		(start 393.574778 -229.136448)
		(end 393.574778 -228.526086)
		(width 0.0889)
		(layer "In13.Cu")
		(net "M_H_CPU0_SA_DQ<11>")
	)
	(segment
		(start 398.740122 -219.748608)
		(end 398.925288 -219.563442)
		(width 0.14478)
		(layer "In13.Cu")
		(net "M_H_CPU0_SA_DQ<11>")
	)
	(segment
		(start 401.194778 -216.744804)
		(end 401.379944 -216.559638)
		(width 0.14478)
		(layer "In13.Cu")
		(net "M_H_CPU0_SA_DQ<11>")
	)
	(segment
		(start 414.406334 -209.259678)
		(end 414.855914 -208.810098)
		(width 0.14478)
		(layer "In13.Cu")
		(net "M_H_CPU0_SA_DQ<11>")
	)
	(segment
		(start 402.364448 -215.779858)
		(end 402.434298 -215.849708)
		(width 0.14478)
		(layer "In13.Cu")
		(net "M_H_CPU0_SA_DQ<11>")
	)
	(segment
		(start 400.094958 -218.189048)
		(end 400.299682 -218.189048)
		(width 0.14478)
		(layer "In13.Cu")
		(net "M_H_CPU0_SA_DQ<11>")
	)
	(segment
		(start 392.7094 -229.80523)
		(end 392.905996 -229.80523)
		(width 0.0889)
		(layer "In13.Cu")
		(net "M_H_CPU0_SA_DQ<11>")
	)
	(segment
		(start 383.393442 -231.196896)
		(end 383.401824 -231.201722)
		(width 0.0889)
		(layer "In13.Cu")
		(net "M_H_CPU0_SA_DQ<11>")
	)
	(segment
		(start 393.574778 -228.526086)
		(end 395.52626 -226.574604)
		(width 0.0889)
		(layer "In13.Cu")
		(net "M_H_CPU0_SA_DQ<11>")
	)
	(segment
		(start 400.600164 -217.339418)
		(end 400.804888 -217.339418)
		(width 0.14478)
		(layer "In13.Cu")
		(net "M_H_CPU0_SA_DQ<11>")
	)
	(segment
		(start 398.075658 -219.863924)
		(end 398.260824 -219.678758)
		(width 0.14478)
		(layer "In13.Cu")
		(net "M_H_CPU0_SA_DQ<11>")
	)
	(segment
		(start 400.025108 -218.119198)
		(end 400.094958 -218.189048)
		(width 0.14478)
		(layer "In13.Cu")
		(net "M_H_CPU0_SA_DQ<11>")
	)
	(segment
		(start 399.040604 -218.898978)
		(end 399.245328 -218.898978)
		(width 0.14478)
		(layer "In13.Cu")
		(net "M_H_CPU0_SA_DQ<11>")
	)
	(segment
		(start 397.028162 -225.072702)
		(end 397.028162 -221.460568)
		(width 0.14478)
		(layer "In13.Cu")
		(net "M_H_CPU0_SA_DQ<11>")
	)
	(segment
		(start 398.075658 -220.068648)
		(end 398.075658 -219.863924)
		(width 0.14478)
		(layer "In13.Cu")
		(net "M_H_CPU0_SA_DQ<11>")
	)
	(segment
		(start 399.705068 -218.783662)
		(end 399.705068 -218.578938)
		(width 0.14478)
		(layer "In13.Cu")
		(net "M_H_CPU0_SA_DQ<11>")
	)
	(segment
		(start 397.481044 -220.458538)
		(end 397.685768 -220.458538)
		(width 0.14478)
		(layer "In13.Cu")
		(net "M_H_CPU0_SA_DQ<11>")
	)
	(segment
		(start 402.824188 -215.664542)
		(end 402.824188 -215.459818)
		(width 0.14478)
		(layer "In13.Cu")
		(net "M_H_CPU0_SA_DQ<11>")
	)
	(segment
		(start 398.260824 -219.678758)
		(end 398.465548 -219.678758)
		(width 0.14478)
		(layer "In13.Cu")
		(net "M_H_CPU0_SA_DQ<11>")
	)
	(segment
		(start 402.044408 -216.239598)
		(end 401.974558 -216.169748)
		(width 0.14478)
		(layer "In13.Cu")
		(net "M_H_CPU0_SA_DQ<11>")
	)
	(segment
		(start 399.635218 -218.509088)
		(end 399.635218 -218.304364)
		(width 0.14478)
		(layer "In13.Cu")
		(net "M_H_CPU0_SA_DQ<11>")
	)
	(segment
		(start 398.535398 -219.748608)
		(end 398.740122 -219.748608)
		(width 0.14478)
		(layer "In13.Cu")
		(net "M_H_CPU0_SA_DQ<11>")
	)
	(segment
		(start 400.484848 -217.799158)
		(end 400.414998 -217.729308)
		(width 0.14478)
		(layer "In13.Cu")
		(net "M_H_CPU0_SA_DQ<11>")
	)
	(segment
		(start 397.960342 -220.528388)
		(end 398.145508 -220.343222)
		(width 0.14478)
		(layer "In13.Cu")
		(net "M_H_CPU0_SA_DQ<11>")
	)
	(segment
		(start 400.804888 -217.339418)
		(end 400.874738 -217.409268)
		(width 0.14478)
		(layer "In13.Cu")
		(net "M_H_CPU0_SA_DQ<11>")
	)
	(segment
		(start 402.939504 -215.000078)
		(end 403.144228 -215.000078)
		(width 0.14478)
		(layer "In13.Cu")
		(net "M_H_CPU0_SA_DQ<11>")
	)
	(segment
		(start 392.905996 -229.80523)
		(end 393.574778 -229.136448)
		(width 0.0889)
		(layer "In13.Cu")
		(net "M_H_CPU0_SA_DQ<11>")
	)
	(segment
		(start 401.974558 -216.169748)
		(end 401.974558 -215.965024)
		(width 0.14478)
		(layer "In13.Cu")
		(net "M_H_CPU0_SA_DQ<11>")
	)
	(segment
		(start 409.229052 -209.259678)
		(end 414.406334 -209.259678)
		(width 0.14478)
		(layer "In13.Cu")
		(net "M_H_CPU0_SA_DQ<11>")
	)
	(segment
		(start 397.685768 -220.458538)
		(end 397.755618 -220.528388)
		(width 0.14478)
		(layer "In13.Cu")
		(net "M_H_CPU0_SA_DQ<11>")
	)
	(segment
		(start 392.332718 -230.181912)
		(end 392.7094 -229.80523)
		(width 0.0889)
		(layer "In13.Cu")
		(net "M_H_CPU0_SA_DQ<11>")
	)
	(segment
		(start 399.315178 -218.968828)
		(end 399.519902 -218.968828)
		(width 0.14478)
		(layer "In13.Cu")
		(net "M_H_CPU0_SA_DQ<11>")
	)
	(segment
		(start 419.496748 -209.65033)
		(end 419.912038 -209.23504)
		(width 0.14478)
		(layer "In13.Cu")
		(net "M_H_CPU0_SA_DQ<11>")
	)
	(segment
		(start 401.859242 -216.629488)
		(end 402.044408 -216.444322)
		(width 0.14478)
		(layer "In13.Cu")
		(net "M_H_CPU0_SA_DQ<11>")
	)
	(segment
		(start 384.90779 -231.201722)
		(end 384.916172 -231.196896)
		(width 0.0889)
		(layer "In13.Cu")
		(net "M_H_CPU0_SA_DQ<11>")
	)
	(segment
		(start 400.414998 -217.524584)
		(end 400.600164 -217.339418)
		(width 0.14478)
		(layer "In13.Cu")
		(net "M_H_CPU0_SA_DQ<11>")
	)
	(segment
		(start 401.264628 -217.019378)
		(end 401.194778 -216.949528)
		(width 0.14478)
		(layer "In13.Cu")
		(net "M_H_CPU0_SA_DQ<11>")
	)
	(segment
		(start 402.159724 -215.779858)
		(end 402.364448 -215.779858)
		(width 0.14478)
		(layer "In13.Cu")
		(net "M_H_CPU0_SA_DQ<11>")
	)
	(segment
		(start 401.079462 -217.409268)
		(end 401.264628 -217.224102)
		(width 0.14478)
		(layer "In13.Cu")
		(net "M_H_CPU0_SA_DQ<11>")
	)
	(segment
		(start 418.980112 -209.65033)
		(end 419.496748 -209.65033)
		(width 0.14478)
		(layer "In13.Cu")
		(net "M_H_CPU0_SA_DQ<11>")
	)
	(segment
		(start 398.145508 -220.138498)
		(end 398.075658 -220.068648)
		(width 0.14478)
		(layer "In13.Cu")
		(net "M_H_CPU0_SA_DQ<11>")
	)
	(segment
		(start 400.299682 -218.189048)
		(end 400.484848 -218.003882)
		(width 0.14478)
		(layer "In13.Cu")
		(net "M_H_CPU0_SA_DQ<11>")
	)
	(segment
		(start 402.434298 -215.849708)
		(end 402.639022 -215.849708)
		(width 0.14478)
		(layer "In13.Cu")
		(net "M_H_CPU0_SA_DQ<11>")
	)
	(segment
		(start 389.607806 -231.201722)
		(end 389.616188 -231.196896)
		(width 0.0889)
		(layer "In13.Cu")
		(net "M_H_CPU0_SA_DQ<11>")
	)
	(segment
		(start 397.365728 -221.123002)
		(end 397.365728 -220.918278)
		(width 0.14478)
		(layer "In13.Cu")
		(net "M_H_CPU0_SA_DQ<11>")
	)
	(segment
		(start 402.639022 -215.849708)
		(end 402.824188 -215.664542)
		(width 0.14478)
		(layer "In13.Cu")
		(net "M_H_CPU0_SA_DQ<11>")
	)
	(segment
		(start 382.274826 -231.524048)
		(end 382.42875 -231.258618)
		(width 0.0889)
		(layer "In13.Cu")
		(net "M_H_CPU0_SA_DQ<11>")
	)
	(segment
		(start 402.044408 -216.444322)
		(end 402.044408 -216.239598)
		(width 0.14478)
		(layer "In13.Cu")
		(net "M_H_CPU0_SA_DQ<11>")
	)
	(segment
		(start 384.333496 -231.196896)
		(end 384.341878 -231.201722)
		(width 0.0889)
		(layer "In13.Cu")
		(net "M_H_CPU0_SA_DQ<11>")
	)
	(segment
		(start 418.13988 -208.810098)
		(end 418.980112 -209.65033)
		(width 0.14478)
		(layer "In13.Cu")
		(net "M_H_CPU0_SA_DQ<11>")
	)
	(segment
		(start 400.874738 -217.409268)
		(end 401.079462 -217.409268)
		(width 0.14478)
		(layer "In13.Cu")
		(net "M_H_CPU0_SA_DQ<11>")
	)
	(segment
		(start 398.925288 -219.563442)
		(end 398.925288 -219.358718)
		(width 0.14478)
		(layer "In13.Cu")
		(net "M_H_CPU0_SA_DQ<11>")
	)
	(segment
		(start 403.418802 -215.069928)
		(end 409.229052 -209.259678)
		(width 0.14478)
		(layer "In13.Cu")
		(net "M_H_CPU0_SA_DQ<11>")
	)
	(segment
		(start 402.754338 -215.389968)
		(end 402.754338 -215.185244)
		(width 0.14478)
		(layer "In13.Cu")
		(net "M_H_CPU0_SA_DQ<11>")
	)
	(segment
		(start 395.52626 -226.574604)
		(end 397.028162 -225.072702)
		(width 0.14478)
		(layer "In13.Cu")
		(net "M_H_CPU0_SA_DQ<11>")
	)
	(segment
		(start 397.755618 -220.528388)
		(end 397.960342 -220.528388)
		(width 0.14478)
		(layer "In13.Cu")
		(net "M_H_CPU0_SA_DQ<11>")
	)
	(segment
		(start 401.974558 -215.965024)
		(end 402.159724 -215.779858)
		(width 0.14478)
		(layer "In13.Cu")
		(net "M_H_CPU0_SA_DQ<11>")
	)
	(segment
		(start 401.379944 -216.559638)
		(end 401.584668 -216.559638)
		(width 0.14478)
		(layer "In13.Cu")
		(net "M_H_CPU0_SA_DQ<11>")
	)
	(segment
		(start 398.855438 -219.084144)
		(end 399.040604 -218.898978)
		(width 0.14478)
		(layer "In13.Cu")
		(net "M_H_CPU0_SA_DQ<11>")
	)
	(segment
		(start 398.855438 -219.288868)
		(end 398.855438 -219.084144)
		(width 0.14478)
		(layer "In13.Cu")
		(net "M_H_CPU0_SA_DQ<11>")
	)
	(segment
		(start 401.654518 -216.629488)
		(end 401.859242 -216.629488)
		(width 0.14478)
		(layer "In13.Cu")
		(net "M_H_CPU0_SA_DQ<11>")
	)
	(segment
		(start 397.028162 -221.460568)
		(end 397.365728 -221.123002)
		(width 0.14478)
		(layer "In13.Cu")
		(net "M_H_CPU0_SA_DQ<11>")
	)
	(segment
		(start 398.925288 -219.358718)
		(end 398.855438 -219.288868)
		(width 0.14478)
		(layer "In13.Cu")
		(net "M_H_CPU0_SA_DQ<11>")
	)
	(segment
		(start 401.264628 -217.224102)
		(end 401.264628 -217.019378)
		(width 0.14478)
		(layer "In13.Cu")
		(net "M_H_CPU0_SA_DQ<11>")
	)
	(arc
		(start 386.221986 -231.201722)
		(mid 386.504942 -231.277899)
		(end 386.787898 -231.201722)
		(width 0.0889)
		(layer "In13.Cu")
		(net "M_H_CPU0_SA_DQ<11>")
	)
	(arc
		(start 384.916172 -231.196896)
		(mid 385.09968 -231.151371)
		(end 385.281932 -231.201722)
		(width 0.0889)
		(layer "In13.Cu")
		(net "M_H_CPU0_SA_DQ<11>")
	)
	(arc
		(start 383.401824 -231.201722)
		(mid 383.68478 -231.277899)
		(end 383.967736 -231.201722)
		(width 0.0889)
		(layer "In13.Cu")
		(net "M_H_CPU0_SA_DQ<11>")
	)
	(arc
		(start 389.041894 -231.201722)
		(mid 389.32485 -231.277899)
		(end 389.607806 -231.201722)
		(width 0.0889)
		(layer "In13.Cu")
		(net "M_H_CPU0_SA_DQ<11>")
	)
	(arc
		(start 385.856226 -231.196896)
		(mid 386.039734 -231.151371)
		(end 386.221986 -231.201722)
		(width 0.0889)
		(layer "In13.Cu")
		(net "M_H_CPU0_SA_DQ<11>")
	)
	(arc
		(start 386.787898 -231.201722)
		(mid 386.974842 -231.151433)
		(end 387.161786 -231.201722)
		(width 0.0889)
		(layer "In13.Cu")
		(net "M_H_CPU0_SA_DQ<11>")
	)
	(arc
		(start 387.727698 -231.201722)
		(mid 387.909949 -231.151338)
		(end 388.093458 -231.196896)
		(width 0.0889)
		(layer "In13.Cu")
		(net "M_H_CPU0_SA_DQ<11>")
	)
	(arc
		(start 389.981948 -231.201722)
		(mid 390.264904 -231.277899)
		(end 390.54786 -231.201722)
		(width 0.0889)
		(layer "In13.Cu")
		(net "M_H_CPU0_SA_DQ<11>")
	)
	(arc
		(start 383.027682 -231.201722)
		(mid 383.209933 -231.151338)
		(end 383.393442 -231.196896)
		(width 0.0889)
		(layer "In13.Cu")
		(net "M_H_CPU0_SA_DQ<11>")
	)
	(arc
		(start 391.770108 -230.714296)
		(mid 391.811074 -230.54389)
		(end 391.925048 -230.410766)
		(width 0.0889)
		(layer "In13.Cu")
		(net "M_H_CPU0_SA_DQ<11>")
	)
	(arc
		(start 384.341878 -231.201722)
		(mid 384.624834 -231.277899)
		(end 384.90779 -231.201722)
		(width 0.0889)
		(layer "In13.Cu")
		(net "M_H_CPU0_SA_DQ<11>")
	)
	(arc
		(start 390.54786 -231.201722)
		(mid 390.734804 -231.151433)
		(end 390.921748 -231.201722)
		(width 0.0889)
		(layer "In13.Cu")
		(net "M_H_CPU0_SA_DQ<11>")
	)
	(arc
		(start 390.921748 -231.201722)
		(mid 391.204704 -231.277899)
		(end 391.48766 -231.201722)
		(width 0.0889)
		(layer "In13.Cu")
		(net "M_H_CPU0_SA_DQ<11>")
	)
	(arc
		(start 388.10184 -231.201722)
		(mid 388.384796 -231.277899)
		(end 388.667752 -231.201722)
		(width 0.0889)
		(layer "In13.Cu")
		(net "M_H_CPU0_SA_DQ<11>")
	)
	(arc
		(start 391.526776 -231.178862)
		(mid 391.705589 -230.976512)
		(end 391.770108 -230.714296)
		(width 0.0889)
		(layer "In13.Cu")
		(net "M_H_CPU0_SA_DQ<11>")
	)
	(arc
		(start 385.281932 -231.201722)
		(mid 385.564888 -231.277899)
		(end 385.847844 -231.201722)
		(width 0.0889)
		(layer "In13.Cu")
		(net "M_H_CPU0_SA_DQ<11>")
	)
	(arc
		(start 387.161786 -231.201722)
		(mid 387.444742 -231.277899)
		(end 387.727698 -231.201722)
		(width 0.0889)
		(layer "In13.Cu")
		(net "M_H_CPU0_SA_DQ<11>")
	)
	(arc
		(start 383.967736 -231.201722)
		(mid 384.149987 -231.151338)
		(end 384.333496 -231.196896)
		(width 0.0889)
		(layer "In13.Cu")
		(net "M_H_CPU0_SA_DQ<11>")
	)
	(arc
		(start 388.667752 -231.201722)
		(mid 388.850003 -231.151338)
		(end 389.033512 -231.196896)
		(width 0.0889)
		(layer "In13.Cu")
		(net "M_H_CPU0_SA_DQ<11>")
	)
	(arc
		(start 389.616188 -231.196896)
		(mid 389.799696 -231.151371)
		(end 389.981948 -231.201722)
		(width 0.0889)
		(layer "In13.Cu")
		(net "M_H_CPU0_SA_DQ<11>")
	)
	(arc
		(start 382.524508 -231.233218)
		(mid 382.77983 -231.276918)
		(end 383.027682 -231.201722)
		(width 0.0889)
		(layer "In13.Cu")
		(net "M_H_CPU0_SA_DQ<11>")
	)
	(segment
		(start 383.217928 -230.97998)
		(end 383.68478 -230.714296)
		(width 0.10668)
		(layer "F.Cu")
		(net "M_H_CPU0_SA_DQ<10>")
	)
	(segment
		(start 407.461212 -209.489294)
		(end 407.665936 -209.489294)
		(width 0.14478)
		(layer "In13.Cu")
		(net "M_H_CPU0_SA_DQ<10>")
	)
	(segment
		(start 403.562312 -213.388194)
		(end 403.767036 -213.388194)
		(width 0.14478)
		(layer "In13.Cu")
		(net "M_H_CPU0_SA_DQ<10>")
	)
	(segment
		(start 407.755852 -209.004154)
		(end 407.755852 -208.79943)
		(width 0.14478)
		(layer "In13.Cu")
		(net "M_H_CPU0_SA_DQ<10>")
	)
	(segment
		(start 411.973014 -207.756506)
		(end 412.117794 -207.611726)
		(width 0.14478)
		(layer "In13.Cu")
		(net "M_H_CPU0_SA_DQ<10>")
	)
	(segment
		(start 405.416512 -211.343494)
		(end 405.416512 -211.13877)
		(width 0.14478)
		(layer "In13.Cu")
		(net "M_H_CPU0_SA_DQ<10>")
	)
	(segment
		(start 391.455148 -229.600506)
		(end 391.48766 -229.58171)
		(width 0.0889)
		(layer "In13.Cu")
		(net "M_H_CPU0_SA_DQ<10>")
	)
	(segment
		(start 411.078934 -208.104994)
		(end 411.223714 -207.960214)
		(width 0.14478)
		(layer "In13.Cu")
		(net "M_H_CPU0_SA_DQ<10>")
	)
	(segment
		(start 405.121872 -211.828634)
		(end 405.326596 -211.828634)
		(width 0.14478)
		(layer "In13.Cu")
		(net "M_H_CPU0_SA_DQ<10>")
	)
	(segment
		(start 409.976574 -208.104994)
		(end 410.121354 -207.960214)
		(width 0.14478)
		(layer "In13.Cu")
		(net "M_H_CPU0_SA_DQ<10>")
	)
	(segment
		(start 411.973014 -207.815434)
		(end 411.973014 -207.756506)
		(width 0.14478)
		(layer "In13.Cu")
		(net "M_H_CPU0_SA_DQ<10>")
	)
	(segment
		(start 403.262338 -213.292944)
		(end 403.467062 -213.292944)
		(width 0.14478)
		(layer "In13.Cu")
		(net "M_H_CPU0_SA_DQ<10>")
	)
	(segment
		(start 418.732462 -207.960214)
		(end 419.486842 -207.960214)
		(width 0.14478)
		(layer "In13.Cu")
		(net "M_H_CPU0_SA_DQ<10>")
	)
	(segment
		(start 409.976574 -208.120234)
		(end 409.976574 -208.104994)
		(width 0.14478)
		(layer "In13.Cu")
		(net "M_H_CPU0_SA_DQ<10>")
	)
	(segment
		(start 404.636732 -211.91855)
		(end 404.821898 -211.733384)
		(width 0.14478)
		(layer "In13.Cu")
		(net "M_H_CPU0_SA_DQ<10>")
	)
	(segment
		(start 410.527754 -208.120234)
		(end 410.672534 -208.265014)
		(width 0.14478)
		(layer "In13.Cu")
		(net "M_H_CPU0_SA_DQ<10>")
	)
	(segment
		(start 404.731982 -212.423248)
		(end 404.731982 -212.218524)
		(width 0.14478)
		(layer "In13.Cu")
		(net "M_H_CPU0_SA_DQ<10>")
	)
	(segment
		(start 390.443466 -230.38689)
		(end 390.451848 -230.391716)
		(width 0.0889)
		(layer "In13.Cu")
		(net "M_H_CPU0_SA_DQ<10>")
	)
	(segment
		(start 407.755852 -208.79943)
		(end 408.595068 -207.960214)
		(width 0.14478)
		(layer "In13.Cu")
		(net "M_H_CPU0_SA_DQ<10>")
	)
	(segment
		(start 388.197852 -230.391716)
		(end 388.206234 -230.38689)
		(width 0.0889)
		(layer "In13.Cu")
		(net "M_H_CPU0_SA_DQ<10>")
	)
	(segment
		(start 413.481774 -207.611726)
		(end 413.626554 -207.756506)
		(width 0.14478)
		(layer "In13.Cu")
		(net "M_H_CPU0_SA_DQ<10>")
	)
	(segment
		(start 404.246842 -212.513164)
		(end 404.342092 -212.608414)
		(width 0.14478)
		(layer "In13.Cu")
		(net "M_H_CPU0_SA_DQ<10>")
	)
	(segment
		(start 393.844018 -226.636326)
		(end 395.693138 -224.787206)
		(width 0.0889)
		(layer "In13.Cu")
		(net "M_H_CPU0_SA_DQ<10>")
	)
	(segment
		(start 412.930594 -207.960214)
		(end 413.075374 -207.815434)
		(width 0.14478)
		(layer "In13.Cu")
		(net "M_H_CPU0_SA_DQ<10>")
	)
	(segment
		(start 405.326596 -211.828634)
		(end 405.511762 -211.643468)
		(width 0.14478)
		(layer "In13.Cu")
		(net "M_H_CPU0_SA_DQ<10>")
	)
	(segment
		(start 406.681432 -210.269074)
		(end 406.886156 -210.269074)
		(width 0.14478)
		(layer "In13.Cu")
		(net "M_H_CPU0_SA_DQ<10>")
	)
	(segment
		(start 405.511762 -211.438744)
		(end 405.416512 -211.343494)
		(width 0.14478)
		(layer "In13.Cu")
		(net "M_H_CPU0_SA_DQ<10>")
	)
	(segment
		(start 406.886156 -210.269074)
		(end 407.071322 -210.083908)
		(width 0.14478)
		(layer "In13.Cu")
		(net "M_H_CPU0_SA_DQ<10>")
	)
	(segment
		(start 405.601678 -210.953604)
		(end 405.806402 -210.953604)
		(width 0.14478)
		(layer "In13.Cu")
		(net "M_H_CPU0_SA_DQ<10>")
	)
	(segment
		(start 403.952202 -212.998304)
		(end 403.856952 -212.903054)
		(width 0.14478)
		(layer "In13.Cu")
		(net "M_H_CPU0_SA_DQ<10>")
	)
	(segment
		(start 387.257798 -230.391716)
		(end 387.26618 -230.38689)
		(width 0.0889)
		(layer "In13.Cu")
		(net "M_H_CPU0_SA_DQ<10>")
	)
	(segment
		(start 408.595068 -207.960214)
		(end 409.280614 -207.960214)
		(width 0.14478)
		(layer "In13.Cu")
		(net "M_H_CPU0_SA_DQ<10>")
	)
	(segment
		(start 405.416512 -211.13877)
		(end 405.601678 -210.953604)
		(width 0.14478)
		(layer "In13.Cu")
		(net "M_H_CPU0_SA_DQ<10>")
	)
	(segment
		(start 407.071322 -210.083908)
		(end 407.071322 -209.879184)
		(width 0.14478)
		(layer "In13.Cu")
		(net "M_H_CPU0_SA_DQ<10>")
	)
	(segment
		(start 403.952202 -213.203028)
		(end 403.952202 -212.998304)
		(width 0.14478)
		(layer "In13.Cu")
		(net "M_H_CPU0_SA_DQ<10>")
	)
	(segment
		(start 405.901652 -211.048854)
		(end 406.106376 -211.048854)
		(width 0.14478)
		(layer "In13.Cu")
		(net "M_H_CPU0_SA_DQ<10>")
	)
	(segment
		(start 410.382974 -207.960214)
		(end 410.527754 -208.104994)
		(width 0.14478)
		(layer "In13.Cu")
		(net "M_H_CPU0_SA_DQ<10>")
	)
	(segment
		(start 392.522456 -228.57841)
		(end 393.844018 -227.256848)
		(width 0.0889)
		(layer "In13.Cu")
		(net "M_H_CPU0_SA_DQ<10>")
	)
	(segment
		(start 407.851102 -209.304128)
		(end 407.851102 -209.099404)
		(width 0.14478)
		(layer "In13.Cu")
		(net "M_H_CPU0_SA_DQ<10>")
	)
	(segment
		(start 404.636732 -212.123274)
		(end 404.636732 -211.91855)
		(width 0.14478)
		(layer "In13.Cu")
		(net "M_H_CPU0_SA_DQ<10>")
	)
	(segment
		(start 409.425394 -208.104994)
		(end 409.425394 -208.120234)
		(width 0.14478)
		(layer "In13.Cu")
		(net "M_H_CPU0_SA_DQ<10>")
	)
	(segment
		(start 412.379414 -207.611726)
		(end 412.524194 -207.756506)
		(width 0.14478)
		(layer "In13.Cu")
		(net "M_H_CPU0_SA_DQ<10>")
	)
	(segment
		(start 412.524194 -207.756506)
		(end 412.524194 -207.815434)
		(width 0.14478)
		(layer "In13.Cu")
		(net "M_H_CPU0_SA_DQ<10>")
	)
	(segment
		(start 403.856952 -212.69833)
		(end 404.042118 -212.513164)
		(width 0.14478)
		(layer "In13.Cu")
		(net "M_H_CPU0_SA_DQ<10>")
	)
	(segment
		(start 411.223714 -207.960214)
		(end 411.828234 -207.960214)
		(width 0.14478)
		(layer "In13.Cu")
		(net "M_H_CPU0_SA_DQ<10>")
	)
	(segment
		(start 407.851102 -209.099404)
		(end 407.755852 -209.004154)
		(width 0.14478)
		(layer "In13.Cu")
		(net "M_H_CPU0_SA_DQ<10>")
	)
	(segment
		(start 395.693138 -224.787206)
		(end 396.129002 -224.351342)
		(width 0.14478)
		(layer "In13.Cu")
		(net "M_H_CPU0_SA_DQ<10>")
	)
	(segment
		(start 405.511762 -211.643468)
		(end 405.511762 -211.438744)
		(width 0.14478)
		(layer "In13.Cu")
		(net "M_H_CPU0_SA_DQ<10>")
	)
	(segment
		(start 406.196292 -210.35899)
		(end 406.381458 -210.173824)
		(width 0.14478)
		(layer "In13.Cu")
		(net "M_H_CPU0_SA_DQ<10>")
	)
	(segment
		(start 405.806402 -210.953604)
		(end 405.901652 -211.048854)
		(width 0.14478)
		(layer "In13.Cu")
		(net "M_H_CPU0_SA_DQ<10>")
	)
	(segment
		(start 406.291542 -210.863688)
		(end 406.291542 -210.658964)
		(width 0.14478)
		(layer "In13.Cu")
		(net "M_H_CPU0_SA_DQ<10>")
	)
	(segment
		(start 385.74345 -230.38689)
		(end 385.751832 -230.391716)
		(width 0.0889)
		(layer "In13.Cu")
		(net "M_H_CPU0_SA_DQ<10>")
	)
	(segment
		(start 412.668974 -207.960214)
		(end 412.930594 -207.960214)
		(width 0.14478)
		(layer "In13.Cu")
		(net "M_H_CPU0_SA_DQ<10>")
	)
	(segment
		(start 406.976072 -209.57921)
		(end 407.161238 -209.394044)
		(width 0.14478)
		(layer "In13.Cu")
		(net "M_H_CPU0_SA_DQ<10>")
	)
	(segment
		(start 404.546816 -212.608414)
		(end 404.731982 -212.423248)
		(width 0.14478)
		(layer "In13.Cu")
		(net "M_H_CPU0_SA_DQ<10>")
	)
	(segment
		(start 383.68478 -230.714296)
		(end 383.838958 -230.448866)
		(width 0.0889)
		(layer "In13.Cu")
		(net "M_H_CPU0_SA_DQ<10>")
	)
	(segment
		(start 409.425394 -208.120234)
		(end 409.570174 -208.265014)
		(width 0.14478)
		(layer "In13.Cu")
		(net "M_H_CPU0_SA_DQ<10>")
	)
	(segment
		(start 413.075374 -207.756506)
		(end 413.220154 -207.611726)
		(width 0.14478)
		(layer "In13.Cu")
		(net "M_H_CPU0_SA_DQ<10>")
	)
	(segment
		(start 406.976072 -209.783934)
		(end 406.976072 -209.57921)
		(width 0.14478)
		(layer "In13.Cu")
		(net "M_H_CPU0_SA_DQ<10>")
	)
	(segment
		(start 383.838958 -230.448866)
		(end 383.935224 -230.423466)
		(width 0.0889)
		(layer "In13.Cu")
		(net "M_H_CPU0_SA_DQ<10>")
	)
	(segment
		(start 411.078934 -208.120234)
		(end 411.078934 -208.104994)
		(width 0.14478)
		(layer "In13.Cu")
		(net "M_H_CPU0_SA_DQ<10>")
	)
	(segment
		(start 396.129002 -224.351342)
		(end 396.129002 -220.42628)
		(width 0.14478)
		(layer "In13.Cu")
		(net "M_H_CPU0_SA_DQ<10>")
	)
	(segment
		(start 406.106376 -211.048854)
		(end 406.291542 -210.863688)
		(width 0.14478)
		(layer "In13.Cu")
		(net "M_H_CPU0_SA_DQ<10>")
	)
	(segment
		(start 392.522456 -228.773736)
		(end 392.522456 -228.57841)
		(width 0.0889)
		(layer "In13.Cu")
		(net "M_H_CPU0_SA_DQ<10>")
	)
	(segment
		(start 405.026622 -211.733384)
		(end 405.121872 -211.828634)
		(width 0.14478)
		(layer "In13.Cu")
		(net "M_H_CPU0_SA_DQ<10>")
	)
	(segment
		(start 411.828234 -207.960214)
		(end 411.973014 -207.815434)
		(width 0.14478)
		(layer "In13.Cu")
		(net "M_H_CPU0_SA_DQ<10>")
	)
	(segment
		(start 406.291542 -210.658964)
		(end 406.196292 -210.563714)
		(width 0.14478)
		(layer "In13.Cu")
		(net "M_H_CPU0_SA_DQ<10>")
	)
	(segment
		(start 410.121354 -207.960214)
		(end 410.382974 -207.960214)
		(width 0.14478)
		(layer "In13.Cu")
		(net "M_H_CPU0_SA_DQ<10>")
	)
	(segment
		(start 404.042118 -212.513164)
		(end 404.246842 -212.513164)
		(width 0.14478)
		(layer "In13.Cu")
		(net "M_H_CPU0_SA_DQ<10>")
	)
	(segment
		(start 415.089594 -207.110076)
		(end 417.882324 -207.110076)
		(width 0.14478)
		(layer "In13.Cu")
		(net "M_H_CPU0_SA_DQ<10>")
	)
	(segment
		(start 391.01776 -230.391716)
		(end 391.054336 -230.37038)
		(width 0.0889)
		(layer "In13.Cu")
		(net "M_H_CPU0_SA_DQ<10>")
	)
	(segment
		(start 404.731982 -212.218524)
		(end 404.636732 -212.123274)
		(width 0.14478)
		(layer "In13.Cu")
		(net "M_H_CPU0_SA_DQ<10>")
	)
	(segment
		(start 413.220154 -207.611726)
		(end 413.481774 -207.611726)
		(width 0.14478)
		(layer "In13.Cu")
		(net "M_H_CPU0_SA_DQ<10>")
	)
	(segment
		(start 407.161238 -209.394044)
		(end 407.365962 -209.394044)
		(width 0.14478)
		(layer "In13.Cu")
		(net "M_H_CPU0_SA_DQ<10>")
	)
	(segment
		(start 403.856952 -212.903054)
		(end 403.856952 -212.69833)
		(width 0.14478)
		(layer "In13.Cu")
		(net "M_H_CPU0_SA_DQ<10>")
	)
	(segment
		(start 410.934154 -208.265014)
		(end 411.078934 -208.120234)
		(width 0.14478)
		(layer "In13.Cu")
		(net "M_H_CPU0_SA_DQ<10>")
	)
	(segment
		(start 412.524194 -207.815434)
		(end 412.668974 -207.960214)
		(width 0.14478)
		(layer "In13.Cu")
		(net "M_H_CPU0_SA_DQ<10>")
	)
	(segment
		(start 412.117794 -207.611726)
		(end 412.379414 -207.611726)
		(width 0.14478)
		(layer "In13.Cu")
		(net "M_H_CPU0_SA_DQ<10>")
	)
	(segment
		(start 413.771334 -207.960214)
		(end 414.239456 -207.960214)
		(width 0.14478)
		(layer "In13.Cu")
		(net "M_H_CPU0_SA_DQ<10>")
	)
	(segment
		(start 406.381458 -210.173824)
		(end 406.586182 -210.173824)
		(width 0.14478)
		(layer "In13.Cu")
		(net "M_H_CPU0_SA_DQ<10>")
	)
	(segment
		(start 396.129002 -220.42628)
		(end 403.262338 -213.292944)
		(width 0.14478)
		(layer "In13.Cu")
		(net "M_H_CPU0_SA_DQ<10>")
	)
	(segment
		(start 404.342092 -212.608414)
		(end 404.546816 -212.608414)
		(width 0.14478)
		(layer "In13.Cu")
		(net "M_H_CPU0_SA_DQ<10>")
	)
	(segment
		(start 409.280614 -207.960214)
		(end 409.425394 -208.104994)
		(width 0.14478)
		(layer "In13.Cu")
		(net "M_H_CPU0_SA_DQ<10>")
	)
	(segment
		(start 413.626554 -207.756506)
		(end 413.626554 -207.815434)
		(width 0.14478)
		(layer "In13.Cu")
		(net "M_H_CPU0_SA_DQ<10>")
	)
	(segment
		(start 413.626554 -207.815434)
		(end 413.771334 -207.960214)
		(width 0.14478)
		(layer "In13.Cu")
		(net "M_H_CPU0_SA_DQ<10>")
	)
	(segment
		(start 391.674858 -229.531418)
		(end 391.764774 -229.531418)
		(width 0.0889)
		(layer "In13.Cu")
		(net "M_H_CPU0_SA_DQ<10>")
	)
	(segment
		(start 407.665936 -209.489294)
		(end 407.851102 -209.304128)
		(width 0.14478)
		(layer "In13.Cu")
		(net "M_H_CPU0_SA_DQ<10>")
	)
	(segment
		(start 407.365962 -209.394044)
		(end 407.461212 -209.489294)
		(width 0.14478)
		(layer "In13.Cu")
		(net "M_H_CPU0_SA_DQ<10>")
	)
	(segment
		(start 403.767036 -213.388194)
		(end 403.952202 -213.203028)
		(width 0.14478)
		(layer "In13.Cu")
		(net "M_H_CPU0_SA_DQ<10>")
	)
	(segment
		(start 414.239456 -207.960214)
		(end 415.089594 -207.110076)
		(width 0.14478)
		(layer "In13.Cu")
		(net "M_H_CPU0_SA_DQ<10>")
	)
	(segment
		(start 404.821898 -211.733384)
		(end 405.026622 -211.733384)
		(width 0.14478)
		(layer "In13.Cu")
		(net "M_H_CPU0_SA_DQ<10>")
	)
	(segment
		(start 406.586182 -210.173824)
		(end 406.681432 -210.269074)
		(width 0.14478)
		(layer "In13.Cu")
		(net "M_H_CPU0_SA_DQ<10>")
	)
	(segment
		(start 413.075374 -207.815434)
		(end 413.075374 -207.756506)
		(width 0.14478)
		(layer "In13.Cu")
		(net "M_H_CPU0_SA_DQ<10>")
	)
	(segment
		(start 410.527754 -208.104994)
		(end 410.527754 -208.120234)
		(width 0.14478)
		(layer "In13.Cu")
		(net "M_H_CPU0_SA_DQ<10>")
	)
	(segment
		(start 393.844018 -227.256848)
		(end 393.844018 -226.636326)
		(width 0.0889)
		(layer "In13.Cu")
		(net "M_H_CPU0_SA_DQ<10>")
	)
	(segment
		(start 419.486842 -207.960214)
		(end 419.912038 -207.535018)
		(width 0.14478)
		(layer "In13.Cu")
		(net "M_H_CPU0_SA_DQ<10>")
	)
	(segment
		(start 406.196292 -210.563714)
		(end 406.196292 -210.35899)
		(width 0.14478)
		(layer "In13.Cu")
		(net "M_H_CPU0_SA_DQ<10>")
	)
	(segment
		(start 409.831794 -208.265014)
		(end 409.976574 -208.120234)
		(width 0.14478)
		(layer "In13.Cu")
		(net "M_H_CPU0_SA_DQ<10>")
	)
	(segment
		(start 391.764774 -229.531418)
		(end 392.522456 -228.773736)
		(width 0.0889)
		(layer "In13.Cu")
		(net "M_H_CPU0_SA_DQ<10>")
	)
	(segment
		(start 407.071322 -209.879184)
		(end 406.976072 -209.783934)
		(width 0.14478)
		(layer "In13.Cu")
		(net "M_H_CPU0_SA_DQ<10>")
	)
	(segment
		(start 417.882324 -207.110076)
		(end 418.732462 -207.960214)
		(width 0.14478)
		(layer "In13.Cu")
		(net "M_H_CPU0_SA_DQ<10>")
	)
	(segment
		(start 403.467062 -213.292944)
		(end 403.562312 -213.388194)
		(width 0.14478)
		(layer "In13.Cu")
		(net "M_H_CPU0_SA_DQ<10>")
	)
	(segment
		(start 409.570174 -208.265014)
		(end 409.831794 -208.265014)
		(width 0.14478)
		(layer "In13.Cu")
		(net "M_H_CPU0_SA_DQ<10>")
	)
	(segment
		(start 410.672534 -208.265014)
		(end 410.934154 -208.265014)
		(width 0.14478)
		(layer "In13.Cu")
		(net "M_H_CPU0_SA_DQ<10>")
	)
	(segment
		(start 386.683504 -230.38689)
		(end 386.691886 -230.391716)
		(width 0.0889)
		(layer "In13.Cu")
		(net "M_H_CPU0_SA_DQ<10>")
	)
	(arc
		(start 383.935224 -230.423466)
		(mid 384.190289 -230.466797)
		(end 384.43789 -230.391716)
		(width 0.0889)
		(layer "In13.Cu")
		(net "M_H_CPU0_SA_DQ<10>")
	)
	(arc
		(start 385.37769 -230.391716)
		(mid 385.559941 -230.341366)
		(end 385.74345 -230.38689)
		(width 0.0889)
		(layer "In13.Cu")
		(net "M_H_CPU0_SA_DQ<10>")
	)
	(arc
		(start 387.26618 -230.38689)
		(mid 387.449688 -230.341396)
		(end 387.63194 -230.391716)
		(width 0.0889)
		(layer "In13.Cu")
		(net "M_H_CPU0_SA_DQ<10>")
	)
	(arc
		(start 390.451848 -230.391716)
		(mid 390.734804 -230.467859)
		(end 391.01776 -230.391716)
		(width 0.0889)
		(layer "In13.Cu")
		(net "M_H_CPU0_SA_DQ<10>")
	)
	(arc
		(start 391.300208 -229.904036)
		(mid 391.341174 -229.73363)
		(end 391.455148 -229.600506)
		(width 0.0889)
		(layer "In13.Cu")
		(net "M_H_CPU0_SA_DQ<10>")
	)
	(arc
		(start 389.511794 -230.391716)
		(mid 389.79475 -230.467859)
		(end 390.077706 -230.391716)
		(width 0.0889)
		(layer "In13.Cu")
		(net "M_H_CPU0_SA_DQ<10>")
	)
	(arc
		(start 388.206234 -230.38689)
		(mid 388.389742 -230.341396)
		(end 388.571994 -230.391716)
		(width 0.0889)
		(layer "In13.Cu")
		(net "M_H_CPU0_SA_DQ<10>")
	)
	(arc
		(start 387.63194 -230.391716)
		(mid 387.914896 -230.467859)
		(end 388.197852 -230.391716)
		(width 0.0889)
		(layer "In13.Cu")
		(net "M_H_CPU0_SA_DQ<10>")
	)
	(arc
		(start 391.48766 -229.58171)
		(mid 391.577932 -229.54418)
		(end 391.674858 -229.531418)
		(width 0.0889)
		(layer "In13.Cu")
		(net "M_H_CPU0_SA_DQ<10>")
	)
	(arc
		(start 384.43789 -230.391716)
		(mid 384.624834 -230.341461)
		(end 384.811778 -230.391716)
		(width 0.0889)
		(layer "In13.Cu")
		(net "M_H_CPU0_SA_DQ<10>")
	)
	(arc
		(start 386.691886 -230.391716)
		(mid 386.974842 -230.467859)
		(end 387.257798 -230.391716)
		(width 0.0889)
		(layer "In13.Cu")
		(net "M_H_CPU0_SA_DQ<10>")
	)
	(arc
		(start 390.077706 -230.391716)
		(mid 390.259957 -230.341366)
		(end 390.443466 -230.38689)
		(width 0.0889)
		(layer "In13.Cu")
		(net "M_H_CPU0_SA_DQ<10>")
	)
	(arc
		(start 388.571994 -230.391716)
		(mid 388.85495 -230.467859)
		(end 389.137906 -230.391716)
		(width 0.0889)
		(layer "In13.Cu")
		(net "M_H_CPU0_SA_DQ<10>")
	)
	(arc
		(start 384.811778 -230.391716)
		(mid 385.094734 -230.467859)
		(end 385.37769 -230.391716)
		(width 0.0889)
		(layer "In13.Cu")
		(net "M_H_CPU0_SA_DQ<10>")
	)
	(arc
		(start 389.137906 -230.391716)
		(mid 389.32485 -230.341461)
		(end 389.511794 -230.391716)
		(width 0.0889)
		(layer "In13.Cu")
		(net "M_H_CPU0_SA_DQ<10>")
	)
	(arc
		(start 385.751832 -230.391716)
		(mid 386.034788 -230.467859)
		(end 386.317744 -230.391716)
		(width 0.0889)
		(layer "In13.Cu")
		(net "M_H_CPU0_SA_DQ<10>")
	)
	(arc
		(start 391.054336 -230.37038)
		(mid 391.234988 -230.167635)
		(end 391.300208 -229.904036)
		(width 0.0889)
		(layer "In13.Cu")
		(net "M_H_CPU0_SA_DQ<10>")
	)
	(arc
		(start 386.317744 -230.391716)
		(mid 386.499995 -230.341366)
		(end 386.683504 -230.38689)
		(width 0.0889)
		(layer "In13.Cu")
		(net "M_H_CPU0_SA_DQ<10>")
	)
	(segment
		(start 383.688082 -225.310192)
		(end 384.154934 -225.044254)
		(width 0.10668)
		(layer "F.Cu")
		(net "M_H_CPU0_SA_DQ<0>")
	)
	(segment
		(start 384.154934 -225.044254)
		(end 384.000756 -225.309684)
		(width 0.0889)
		(layer "In13.Cu")
		(net "M_H_CPU0_SA_DQ<0>")
	)
	(segment
		(start 389.69315 -221.380812)
		(end 389.69315 -217.49512)
		(width 0.14478)
		(layer "In13.Cu")
		(net "M_H_CPU0_SA_DQ<0>")
	)
	(segment
		(start 396.729458 -210.458812)
		(end 396.729458 -209.167984)
		(width 0.14478)
		(layer "In13.Cu")
		(net "M_H_CPU0_SA_DQ<0>")
	)
	(segment
		(start 389.69315 -217.49512)
		(end 396.729458 -210.458812)
		(width 0.14478)
		(layer "In13.Cu")
		(net "M_H_CPU0_SA_DQ<0>")
	)
	(segment
		(start 389.512048 -222.936816)
		(end 389.544814 -222.917766)
		(width 0.0889)
		(layer "In13.Cu")
		(net "M_H_CPU0_SA_DQ<0>")
	)
	(segment
		(start 389.004302 -223.768666)
		(end 389.042148 -223.746822)
		(width 0.0889)
		(layer "In13.Cu")
		(net "M_H_CPU0_SA_DQ<0>")
	)
	(segment
		(start 384.90779 -225.366834)
		(end 384.916172 -225.37166)
		(width 0.0889)
		(layer "In13.Cu")
		(net "M_H_CPU0_SA_DQ<0>")
	)
	(segment
		(start 384.000756 -225.309684)
		(end 384.023108 -225.392996)
		(width 0.0889)
		(layer "In13.Cu")
		(net "M_H_CPU0_SA_DQ<0>")
	)
	(segment
		(start 389.69315 -222.607632)
		(end 389.69315 -221.380812)
		(width 0.0889)
		(layer "In13.Cu")
		(net "M_H_CPU0_SA_DQ<0>")
	)
	(segment
		(start 419.746938 -197.760082)
		(end 420.701724 -197.760082)
		(width 0.14478)
		(layer "In13.Cu")
		(net "M_H_CPU0_SA_DQ<0>")
	)
	(segment
		(start 420.701724 -197.760082)
		(end 421.72763 -197.33514)
		(width 0.14478)
		(layer "In13.Cu")
		(net "M_H_CPU0_SA_DQ<0>")
	)
	(segment
		(start 388.532878 -224.579688)
		(end 388.571994 -224.556828)
		(width 0.0889)
		(layer "In13.Cu")
		(net "M_H_CPU0_SA_DQ<0>")
	)
	(segment
		(start 384.333496 -225.37166)
		(end 384.341878 -225.366834)
		(width 0.0889)
		(layer "In13.Cu")
		(net "M_H_CPU0_SA_DQ<0>")
	)
	(segment
		(start 385.847844 -225.366834)
		(end 385.856226 -225.37166)
		(width 0.0889)
		(layer "In13.Cu")
		(net "M_H_CPU0_SA_DQ<0>")
	)
	(segment
		(start 389.699754 -222.614236)
		(end 389.69315 -222.607632)
		(width 0.0889)
		(layer "In13.Cu")
		(net "M_H_CPU0_SA_DQ<0>")
	)
	(segment
		(start 388.093458 -225.37166)
		(end 388.10184 -225.366834)
		(width 0.0889)
		(layer "In13.Cu")
		(net "M_H_CPU0_SA_DQ<0>")
	)
	(segment
		(start 408.13736 -197.760082)
		(end 413.302196 -197.760082)
		(width 0.14478)
		(layer "In13.Cu")
		(net "M_H_CPU0_SA_DQ<0>")
	)
	(segment
		(start 415.354008 -196.910198)
		(end 417.695126 -196.910198)
		(width 0.14478)
		(layer "In13.Cu")
		(net "M_H_CPU0_SA_DQ<0>")
	)
	(segment
		(start 396.729458 -209.167984)
		(end 408.13736 -197.760082)
		(width 0.14478)
		(layer "In13.Cu")
		(net "M_H_CPU0_SA_DQ<0>")
	)
	(segment
		(start 388.10184 -225.366834)
		(end 388.13359 -225.348546)
		(width 0.0889)
		(layer "In13.Cu")
		(net "M_H_CPU0_SA_DQ<0>")
	)
	(segment
		(start 389.474456 -222.95866)
		(end 389.512048 -222.936816)
		(width 0.0889)
		(layer "In13.Cu")
		(net "M_H_CPU0_SA_DQ<0>")
	)
	(segment
		(start 388.571994 -224.556828)
		(end 388.603744 -224.53854)
		(width 0.0889)
		(layer "In13.Cu")
		(net "M_H_CPU0_SA_DQ<0>")
	)
	(segment
		(start 417.695126 -196.910198)
		(end 419.746938 -197.760082)
		(width 0.14478)
		(layer "In13.Cu")
		(net "M_H_CPU0_SA_DQ<0>")
	)
	(segment
		(start 413.302196 -197.760082)
		(end 415.354008 -196.910198)
		(width 0.14478)
		(layer "In13.Cu")
		(net "M_H_CPU0_SA_DQ<0>")
	)
	(segment
		(start 389.042148 -223.746822)
		(end 389.073898 -223.728534)
		(width 0.0889)
		(layer "In13.Cu")
		(net "M_H_CPU0_SA_DQ<0>")
	)
	(segment
		(start 421.72763 -197.33514)
		(end 424.012106 -197.33514)
		(width 0.14478)
		(layer "In13.Cu")
		(net "M_H_CPU0_SA_DQ<0>")
	)
	(arc
		(start 388.7597 -224.234248)
		(mid 388.824572 -223.971285)
		(end 389.004302 -223.768666)
		(width 0.0889)
		(layer "In13.Cu")
		(net "M_H_CPU0_SA_DQ<0>")
	)
	(arc
		(start 387.161786 -225.366834)
		(mid 387.444742 -225.290657)
		(end 387.727698 -225.366834)
		(width 0.0889)
		(layer "In13.Cu")
		(net "M_H_CPU0_SA_DQ<0>")
	)
	(arc
		(start 386.787898 -225.366834)
		(mid 386.974842 -225.417089)
		(end 387.161786 -225.366834)
		(width 0.0889)
		(layer "In13.Cu")
		(net "M_H_CPU0_SA_DQ<0>")
	)
	(arc
		(start 386.221986 -225.366834)
		(mid 386.504942 -225.290657)
		(end 386.787898 -225.366834)
		(width 0.0889)
		(layer "In13.Cu")
		(net "M_H_CPU0_SA_DQ<0>")
	)
	(arc
		(start 389.544814 -222.917766)
		(mid 389.658743 -222.784619)
		(end 389.699754 -222.614236)
		(width 0.0889)
		(layer "In13.Cu")
		(net "M_H_CPU0_SA_DQ<0>")
	)
	(arc
		(start 384.023108 -225.392996)
		(mid 384.180618 -225.416194)
		(end 384.333496 -225.37166)
		(width 0.0889)
		(layer "In13.Cu")
		(net "M_H_CPU0_SA_DQ<0>")
	)
	(arc
		(start 389.073898 -223.728534)
		(mid 389.188574 -223.5952)
		(end 389.229854 -223.424242)
		(width 0.0889)
		(layer "In13.Cu")
		(net "M_H_CPU0_SA_DQ<0>")
	)
	(arc
		(start 384.916172 -225.37166)
		(mid 385.09968 -225.417154)
		(end 385.281932 -225.366834)
		(width 0.0889)
		(layer "In13.Cu")
		(net "M_H_CPU0_SA_DQ<0>")
	)
	(arc
		(start 385.281932 -225.366834)
		(mid 385.564888 -225.290657)
		(end 385.847844 -225.366834)
		(width 0.0889)
		(layer "In13.Cu")
		(net "M_H_CPU0_SA_DQ<0>")
	)
	(arc
		(start 388.289546 -225.044254)
		(mid 388.354061 -224.782035)
		(end 388.532878 -224.579688)
		(width 0.0889)
		(layer "In13.Cu")
		(net "M_H_CPU0_SA_DQ<0>")
	)
	(arc
		(start 389.229854 -223.424242)
		(mid 389.294726 -223.161279)
		(end 389.474456 -222.95866)
		(width 0.0889)
		(layer "In13.Cu")
		(net "M_H_CPU0_SA_DQ<0>")
	)
	(arc
		(start 388.13359 -225.348546)
		(mid 388.248266 -225.215212)
		(end 388.289546 -225.044254)
		(width 0.0889)
		(layer "In13.Cu")
		(net "M_H_CPU0_SA_DQ<0>")
	)
	(arc
		(start 388.603744 -224.53854)
		(mid 388.71842 -224.405206)
		(end 388.7597 -224.234248)
		(width 0.0889)
		(layer "In13.Cu")
		(net "M_H_CPU0_SA_DQ<0>")
	)
	(arc
		(start 387.727698 -225.366834)
		(mid 387.909949 -225.417184)
		(end 388.093458 -225.37166)
		(width 0.0889)
		(layer "In13.Cu")
		(net "M_H_CPU0_SA_DQ<0>")
	)
	(arc
		(start 384.341878 -225.366834)
		(mid 384.624834 -225.290657)
		(end 384.90779 -225.366834)
		(width 0.0889)
		(layer "In13.Cu")
		(net "M_H_CPU0_SA_DQ<0>")
	)
	(arc
		(start 385.856226 -225.37166)
		(mid 386.039734 -225.417154)
		(end 386.221986 -225.366834)
		(width 0.0889)
		(layer "In13.Cu")
		(net "M_H_CPU0_SA_DQ<0>")
	)
	(segment
		(start 382.277874 -252.040136)
		(end 382.744726 -251.774198)
		(width 0.10668)
		(layer "F.Cu")
		(net "M_H_CPU0_SA_CS_N<1>")
	)
	(segment
		(start 397.926814 -251.914152)
		(end 395.530578 -251.914152)
		(width 0.14478)
		(layer "In13.Cu")
		(net "M_H_CPU0_SA_CS_N<1>")
	)
	(segment
		(start 386.326126 -252.101604)
		(end 386.317744 -252.096778)
		(width 0.0889)
		(layer "In13.Cu")
		(net "M_H_CPU0_SA_CS_N<1>")
	)
	(segment
		(start 415.735008 -247.817894)
		(end 414.792668 -248.760234)
		(width 0.14478)
		(layer "In13.Cu")
		(net "M_H_CPU0_SA_CS_N<1>")
	)
	(segment
		(start 385.377944 -252.096778)
		(end 385.37769 -252.096778)
		(width 0.0889)
		(layer "In13.Cu")
		(net "M_H_CPU0_SA_CS_N<1>")
	)
	(segment
		(start 395.530578 -251.914152)
		(end 395.159738 -251.914152)
		(width 0.0889)
		(layer "In13.Cu")
		(net "M_H_CPU0_SA_CS_N<1>")
	)
	(segment
		(start 392.332718 -252.096778)
		(end 392.321034 -252.103636)
		(width 0.0889)
		(layer "In13.Cu")
		(net "M_H_CPU0_SA_CS_N<1>")
	)
	(segment
		(start 414.792668 -248.760234)
		(end 411.774386 -248.760234)
		(width 0.14478)
		(layer "In13.Cu")
		(net "M_H_CPU0_SA_CS_N<1>")
	)
	(segment
		(start 383.871724 -252.096778)
		(end 383.863342 -252.101604)
		(width 0.0889)
		(layer "In13.Cu")
		(net "M_H_CPU0_SA_CS_N<1>")
	)
	(segment
		(start 411.774386 -248.760234)
		(end 408.965908 -251.568712)
		(width 0.14478)
		(layer "In13.Cu")
		(net "M_H_CPU0_SA_CS_N<1>")
	)
	(segment
		(start 398.272254 -251.568712)
		(end 397.926814 -251.914152)
		(width 0.14478)
		(layer "In13.Cu")
		(net "M_H_CPU0_SA_CS_N<1>")
	)
	(segment
		(start 395.07668 -251.99721)
		(end 393.495784 -251.99721)
		(width 0.0889)
		(layer "In13.Cu")
		(net "M_H_CPU0_SA_CS_N<1>")
	)
	(segment
		(start 384.811778 -252.096778)
		(end 384.803396 -252.101604)
		(width 0.0889)
		(layer "In13.Cu")
		(net "M_H_CPU0_SA_CS_N<1>")
	)
	(segment
		(start 391.026142 -252.101604)
		(end 391.01776 -252.096778)
		(width 0.0889)
		(layer "In13.Cu")
		(net "M_H_CPU0_SA_CS_N<1>")
	)
	(segment
		(start 395.159738 -251.914152)
		(end 395.07668 -251.99721)
		(width 0.0889)
		(layer "In13.Cu")
		(net "M_H_CPU0_SA_CS_N<1>")
	)
	(segment
		(start 390.451848 -252.096778)
		(end 390.443466 -252.101604)
		(width 0.0889)
		(layer "In13.Cu")
		(net "M_H_CPU0_SA_CS_N<1>")
	)
	(segment
		(start 419.912038 -246.635016)
		(end 419.64356 -246.903494)
		(width 0.14478)
		(layer "In13.Cu")
		(net "M_H_CPU0_SA_CS_N<1>")
	)
	(segment
		(start 408.965908 -251.568712)
		(end 398.272254 -251.568712)
		(width 0.14478)
		(layer "In13.Cu")
		(net "M_H_CPU0_SA_CS_N<1>")
	)
	(segment
		(start 393.495784 -251.99721)
		(end 393.272264 -252.096778)
		(width 0.0889)
		(layer "In13.Cu")
		(net "M_H_CPU0_SA_CS_N<1>")
	)
	(segment
		(start 392.91641 -252.106938)
		(end 392.898122 -252.096524)
		(width 0.0889)
		(layer "In13.Cu")
		(net "M_H_CPU0_SA_CS_N<1>")
	)
	(segment
		(start 418.348668 -246.903494)
		(end 417.434268 -247.817894)
		(width 0.14478)
		(layer "In13.Cu")
		(net "M_H_CPU0_SA_CS_N<1>")
	)
	(segment
		(start 382.994662 -252.065028)
		(end 382.89865 -252.039628)
		(width 0.0889)
		(layer "In13.Cu")
		(net "M_H_CPU0_SA_CS_N<1>")
	)
	(segment
		(start 387.26618 -252.101604)
		(end 387.257798 -252.096778)
		(width 0.0889)
		(layer "In13.Cu")
		(net "M_H_CPU0_SA_CS_N<1>")
	)
	(segment
		(start 382.89865 -252.039628)
		(end 382.744726 -251.774198)
		(width 0.0889)
		(layer "In13.Cu")
		(net "M_H_CPU0_SA_CS_N<1>")
	)
	(segment
		(start 417.434268 -247.817894)
		(end 415.735008 -247.817894)
		(width 0.14478)
		(layer "In13.Cu")
		(net "M_H_CPU0_SA_CS_N<1>")
	)
	(segment
		(start 391.406634 -252.088142)
		(end 391.391902 -252.096778)
		(width 0.0889)
		(layer "In13.Cu")
		(net "M_H_CPU0_SA_CS_N<1>")
	)
	(segment
		(start 392.898122 -252.096524)
		(end 392.892534 -252.093222)
		(width 0.0889)
		(layer "In13.Cu")
		(net "M_H_CPU0_SA_CS_N<1>")
	)
	(segment
		(start 419.64356 -246.903494)
		(end 418.348668 -246.903494)
		(width 0.14478)
		(layer "In13.Cu")
		(net "M_H_CPU0_SA_CS_N<1>")
	)
	(segment
		(start 388.206234 -252.101604)
		(end 388.197852 -252.096778)
		(width 0.0889)
		(layer "In13.Cu")
		(net "M_H_CPU0_SA_CS_N<1>")
	)
	(arc
		(start 385.751832 -252.096778)
		(mid 385.564888 -252.147102)
		(end 385.377944 -252.096778)
		(width 0.0889)
		(layer "In13.Cu")
		(net "M_H_CPU0_SA_CS_N<1>")
	)
	(arc
		(start 384.803396 -252.101604)
		(mid 384.619888 -252.147098)
		(end 384.437636 -252.096778)
		(width 0.0889)
		(layer "In13.Cu")
		(net "M_H_CPU0_SA_CS_N<1>")
	)
	(arc
		(start 387.257798 -252.096778)
		(mid 386.974842 -252.020635)
		(end 386.691886 -252.096778)
		(width 0.0889)
		(layer "In13.Cu")
		(net "M_H_CPU0_SA_CS_N<1>")
	)
	(arc
		(start 388.571994 -252.096778)
		(mid 388.389743 -252.147128)
		(end 388.206234 -252.101604)
		(width 0.0889)
		(layer "In13.Cu")
		(net "M_H_CPU0_SA_CS_N<1>")
	)
	(arc
		(start 390.443466 -252.101604)
		(mid 390.259958 -252.147098)
		(end 390.077706 -252.096778)
		(width 0.0889)
		(layer "In13.Cu")
		(net "M_H_CPU0_SA_CS_N<1>")
	)
	(arc
		(start 392.892534 -252.093222)
		(mid 392.612145 -252.020553)
		(end 392.332718 -252.096778)
		(width 0.0889)
		(layer "In13.Cu")
		(net "M_H_CPU0_SA_CS_N<1>")
	)
	(arc
		(start 383.497582 -252.096778)
		(mid 383.249869 -252.021558)
		(end 382.994662 -252.065028)
		(width 0.0889)
		(layer "In13.Cu")
		(net "M_H_CPU0_SA_CS_N<1>")
	)
	(arc
		(start 390.077706 -252.096778)
		(mid 389.79475 -252.020601)
		(end 389.511794 -252.096778)
		(width 0.0889)
		(layer "In13.Cu")
		(net "M_H_CPU0_SA_CS_N<1>")
	)
	(arc
		(start 393.272264 -252.096778)
		(mid 393.095636 -252.147011)
		(end 392.91641 -252.106938)
		(width 0.0889)
		(layer "In13.Cu")
		(net "M_H_CPU0_SA_CS_N<1>")
	)
	(arc
		(start 387.63194 -252.096778)
		(mid 387.449689 -252.147128)
		(end 387.26618 -252.101604)
		(width 0.0889)
		(layer "In13.Cu")
		(net "M_H_CPU0_SA_CS_N<1>")
	)
	(arc
		(start 386.691886 -252.096778)
		(mid 386.509635 -252.147128)
		(end 386.326126 -252.101604)
		(width 0.0889)
		(layer "In13.Cu")
		(net "M_H_CPU0_SA_CS_N<1>")
	)
	(arc
		(start 388.197852 -252.096778)
		(mid 387.914896 -252.020601)
		(end 387.63194 -252.096778)
		(width 0.0889)
		(layer "In13.Cu")
		(net "M_H_CPU0_SA_CS_N<1>")
	)
	(arc
		(start 389.137906 -252.096778)
		(mid 388.85495 -252.020601)
		(end 388.571994 -252.096778)
		(width 0.0889)
		(layer "In13.Cu")
		(net "M_H_CPU0_SA_CS_N<1>")
	)
	(arc
		(start 385.37769 -252.096778)
		(mid 385.094734 -252.020601)
		(end 384.811778 -252.096778)
		(width 0.0889)
		(layer "In13.Cu")
		(net "M_H_CPU0_SA_CS_N<1>")
	)
	(arc
		(start 389.511794 -252.096778)
		(mid 389.32485 -252.147033)
		(end 389.137906 -252.096778)
		(width 0.0889)
		(layer "In13.Cu")
		(net "M_H_CPU0_SA_CS_N<1>")
	)
	(arc
		(start 391.01776 -252.096778)
		(mid 390.734804 -252.020601)
		(end 390.451848 -252.096778)
		(width 0.0889)
		(layer "In13.Cu")
		(net "M_H_CPU0_SA_CS_N<1>")
	)
	(arc
		(start 384.437636 -252.096778)
		(mid 384.15468 -252.020601)
		(end 383.871724 -252.096778)
		(width 0.0889)
		(layer "In13.Cu")
		(net "M_H_CPU0_SA_CS_N<1>")
	)
	(arc
		(start 383.863342 -252.101604)
		(mid 383.679834 -252.147098)
		(end 383.497582 -252.096778)
		(width 0.0889)
		(layer "In13.Cu")
		(net "M_H_CPU0_SA_CS_N<1>")
	)
	(arc
		(start 392.321034 -252.103636)
		(mid 392.138779 -252.147289)
		(end 391.958322 -252.096778)
		(width 0.0889)
		(layer "In13.Cu")
		(net "M_H_CPU0_SA_CS_N<1>")
	)
	(arc
		(start 391.958322 -252.096778)
		(mid 391.683616 -252.020414)
		(end 391.406634 -252.088142)
		(width 0.0889)
		(layer "In13.Cu")
		(net "M_H_CPU0_SA_CS_N<1>")
	)
	(arc
		(start 391.391902 -252.096778)
		(mid 391.209651 -252.147128)
		(end 391.026142 -252.101604)
		(width 0.0889)
		(layer "In13.Cu")
		(net "M_H_CPU0_SA_CS_N<1>")
	)
	(arc
		(start 386.317744 -252.096778)
		(mid 386.034788 -252.020601)
		(end 385.751832 -252.096778)
		(width 0.0889)
		(layer "In13.Cu")
		(net "M_H_CPU0_SA_CS_N<1>")
	)
	(segment
		(start 383.688082 -251.23013)
		(end 384.154934 -250.964192)
		(width 0.10668)
		(layer "F.Cu")
		(net "M_H_CPU0_SA_CS_N<0>")
	)
	(segment
		(start 384.308858 -251.229622)
		(end 384.154934 -250.964192)
		(width 0.0889)
		(layer "In13.Cu")
		(net "M_H_CPU0_SA_CS_N<0>")
	)
	(segment
		(start 414.589468 -247.767094)
		(end 414.58007 -247.767094)
		(width 0.14478)
		(layer "In13.Cu")
		(net "M_H_CPU0_SA_CS_N<0>")
	)
	(segment
		(start 415.148268 -247.208294)
		(end 414.589468 -247.767094)
		(width 0.14478)
		(layer "In13.Cu")
		(net "M_H_CPU0_SA_CS_N<0>")
	)
	(segment
		(start 420.903146 -246.210074)
		(end 418.280088 -246.210074)
		(width 0.14478)
		(layer "In13.Cu")
		(net "M_H_CPU0_SA_CS_N<0>")
	)
	(segment
		(start 392.428476 -251.286772)
		(end 392.418062 -251.280676)
		(width 0.0889)
		(layer "In13.Cu")
		(net "M_H_CPU0_SA_CS_N<0>")
	)
	(segment
		(start 414.58007 -247.767094)
		(end 414.437068 -247.910096)
		(width 0.14478)
		(layer "In13.Cu")
		(net "M_H_CPU0_SA_CS_N<0>")
	)
	(segment
		(start 391.496042 -251.291598)
		(end 391.48766 -251.286772)
		(width 0.0889)
		(layer "In13.Cu")
		(net "M_H_CPU0_SA_CS_N<0>")
	)
	(segment
		(start 424.012106 -245.785132)
		(end 421.328088 -245.785132)
		(width 0.14478)
		(layer "In13.Cu")
		(net "M_H_CPU0_SA_CS_N<0>")
	)
	(segment
		(start 385.281932 -251.286772)
		(end 385.27355 -251.291598)
		(width 0.0889)
		(layer "In13.Cu")
		(net "M_H_CPU0_SA_CS_N<0>")
	)
	(segment
		(start 393.897358 -251.281184)
		(end 393.368276 -251.286772)
		(width 0.0889)
		(layer "In13.Cu")
		(net "M_H_CPU0_SA_CS_N<0>")
	)
	(segment
		(start 386.221986 -251.286772)
		(end 386.213604 -251.291598)
		(width 0.0889)
		(layer "In13.Cu")
		(net "M_H_CPU0_SA_CS_N<0>")
	)
	(segment
		(start 421.328088 -245.785132)
		(end 420.903146 -246.210074)
		(width 0.14478)
		(layer "In13.Cu")
		(net "M_H_CPU0_SA_CS_N<0>")
	)
	(segment
		(start 384.40487 -251.255022)
		(end 384.308858 -251.229622)
		(width 0.0889)
		(layer "In13.Cu")
		(net "M_H_CPU0_SA_CS_N<0>")
	)
	(segment
		(start 392.802364 -251.286518)
		(end 392.786108 -251.295916)
		(width 0.0889)
		(layer "In13.Cu")
		(net "M_H_CPU0_SA_CS_N<0>")
	)
	(segment
		(start 411.988254 -247.910096)
		(end 408.779218 -251.119132)
		(width 0.14478)
		(layer "In13.Cu")
		(net "M_H_CPU0_SA_CS_N<0>")
	)
	(segment
		(start 395.009116 -251.59335)
		(end 394.209524 -251.59335)
		(width 0.0889)
		(layer "In13.Cu")
		(net "M_H_CPU0_SA_CS_N<0>")
	)
	(segment
		(start 414.437068 -247.910096)
		(end 411.988254 -247.910096)
		(width 0.14478)
		(layer "In13.Cu")
		(net "M_H_CPU0_SA_CS_N<0>")
	)
	(segment
		(start 394.209524 -251.59335)
		(end 393.897358 -251.281184)
		(width 0.0889)
		(layer "In13.Cu")
		(net "M_H_CPU0_SA_CS_N<0>")
	)
	(segment
		(start 389.616188 -251.291598)
		(end 389.607806 -251.286772)
		(width 0.0889)
		(layer "In13.Cu")
		(net "M_H_CPU0_SA_CS_N<0>")
	)
	(segment
		(start 398.074134 -251.119132)
		(end 397.739616 -251.45365)
		(width 0.14478)
		(layer "In13.Cu")
		(net "M_H_CPU0_SA_CS_N<0>")
	)
	(segment
		(start 388.10184 -251.286772)
		(end 388.093458 -251.291598)
		(width 0.0889)
		(layer "In13.Cu")
		(net "M_H_CPU0_SA_CS_N<0>")
	)
	(segment
		(start 389.041894 -251.286772)
		(end 389.033512 -251.291598)
		(width 0.0889)
		(layer "In13.Cu")
		(net "M_H_CPU0_SA_CS_N<0>")
	)
	(segment
		(start 417.281868 -247.208294)
		(end 415.148268 -247.208294)
		(width 0.14478)
		(layer "In13.Cu")
		(net "M_H_CPU0_SA_CS_N<0>")
	)
	(segment
		(start 395.440916 -251.45365)
		(end 395.148816 -251.45365)
		(width 0.0889)
		(layer "In13.Cu")
		(net "M_H_CPU0_SA_CS_N<0>")
	)
	(segment
		(start 408.779218 -251.119132)
		(end 398.074134 -251.119132)
		(width 0.14478)
		(layer "In13.Cu")
		(net "M_H_CPU0_SA_CS_N<0>")
	)
	(segment
		(start 418.280088 -246.210074)
		(end 417.281868 -247.208294)
		(width 0.14478)
		(layer "In13.Cu")
		(net "M_H_CPU0_SA_CS_N<0>")
	)
	(segment
		(start 397.739616 -251.45365)
		(end 395.440916 -251.45365)
		(width 0.14478)
		(layer "In13.Cu")
		(net "M_H_CPU0_SA_CS_N<0>")
	)
	(segment
		(start 395.148816 -251.45365)
		(end 395.009116 -251.59335)
		(width 0.0889)
		(layer "In13.Cu")
		(net "M_H_CPU0_SA_CS_N<0>")
	)
	(segment
		(start 392.818112 -251.277374)
		(end 392.802364 -251.286518)
		(width 0.0889)
		(layer "In13.Cu")
		(net "M_H_CPU0_SA_CS_N<0>")
	)
	(arc
		(start 388.667752 -251.286772)
		(mid 388.384796 -251.210595)
		(end 388.10184 -251.286772)
		(width 0.0889)
		(layer "In13.Cu")
		(net "M_H_CPU0_SA_CS_N<0>")
	)
	(arc
		(start 386.787898 -251.286772)
		(mid 386.504942 -251.210595)
		(end 386.221986 -251.286772)
		(width 0.0889)
		(layer "In13.Cu")
		(net "M_H_CPU0_SA_CS_N<0>")
	)
	(arc
		(start 389.033512 -251.291598)
		(mid 388.850004 -251.337092)
		(end 388.667752 -251.286772)
		(width 0.0889)
		(layer "In13.Cu")
		(net "M_H_CPU0_SA_CS_N<0>")
	)
	(arc
		(start 387.727698 -251.286772)
		(mid 387.444742 -251.210595)
		(end 387.161786 -251.286772)
		(width 0.0889)
		(layer "In13.Cu")
		(net "M_H_CPU0_SA_CS_N<0>")
	)
	(arc
		(start 388.093458 -251.291598)
		(mid 387.90995 -251.337092)
		(end 387.727698 -251.286772)
		(width 0.0889)
		(layer "In13.Cu")
		(net "M_H_CPU0_SA_CS_N<0>")
	)
	(arc
		(start 385.847844 -251.286772)
		(mid 385.564888 -251.210595)
		(end 385.281932 -251.286772)
		(width 0.0889)
		(layer "In13.Cu")
		(net "M_H_CPU0_SA_CS_N<0>")
	)
	(arc
		(start 386.213604 -251.291598)
		(mid 386.030096 -251.337092)
		(end 385.847844 -251.286772)
		(width 0.0889)
		(layer "In13.Cu")
		(net "M_H_CPU0_SA_CS_N<0>")
	)
	(arc
		(start 384.90779 -251.286772)
		(mid 384.660077 -251.211552)
		(end 384.40487 -251.255022)
		(width 0.0889)
		(layer "In13.Cu")
		(net "M_H_CPU0_SA_CS_N<0>")
	)
	(arc
		(start 387.161786 -251.286772)
		(mid 386.974842 -251.337061)
		(end 386.787898 -251.286772)
		(width 0.0889)
		(layer "In13.Cu")
		(net "M_H_CPU0_SA_CS_N<0>")
	)
	(arc
		(start 385.27355 -251.291598)
		(mid 385.090042 -251.337092)
		(end 384.90779 -251.286772)
		(width 0.0889)
		(layer "In13.Cu")
		(net "M_H_CPU0_SA_CS_N<0>")
	)
	(arc
		(start 389.981948 -251.286772)
		(mid 389.799697 -251.337122)
		(end 389.616188 -251.291598)
		(width 0.0889)
		(layer "In13.Cu")
		(net "M_H_CPU0_SA_CS_N<0>")
	)
	(arc
		(start 390.921748 -251.286772)
		(mid 390.734804 -251.337027)
		(end 390.54786 -251.286772)
		(width 0.0889)
		(layer "In13.Cu")
		(net "M_H_CPU0_SA_CS_N<0>")
	)
	(arc
		(start 393.368276 -251.286772)
		(mid 393.094421 -251.210422)
		(end 392.818112 -251.277374)
		(width 0.0889)
		(layer "In13.Cu")
		(net "M_H_CPU0_SA_CS_N<0>")
	)
	(arc
		(start 391.86231 -251.286772)
		(mid 391.679805 -251.337249)
		(end 391.496042 -251.291598)
		(width 0.0889)
		(layer "In13.Cu")
		(net "M_H_CPU0_SA_CS_N<0>")
	)
	(arc
		(start 392.786108 -251.295916)
		(mid 392.606126 -251.337016)
		(end 392.428476 -251.286772)
		(width 0.0889)
		(layer "In13.Cu")
		(net "M_H_CPU0_SA_CS_N<0>")
	)
	(arc
		(start 389.607806 -251.286772)
		(mid 389.32485 -251.210595)
		(end 389.041894 -251.286772)
		(width 0.0889)
		(layer "In13.Cu")
		(net "M_H_CPU0_SA_CS_N<0>")
	)
	(arc
		(start 392.418062 -251.280676)
		(mid 392.139376 -251.210456)
		(end 391.86231 -251.286772)
		(width 0.0889)
		(layer "In13.Cu")
		(net "M_H_CPU0_SA_CS_N<0>")
	)
	(arc
		(start 391.48766 -251.286772)
		(mid 391.204704 -251.210595)
		(end 390.921748 -251.286772)
		(width 0.0889)
		(layer "In13.Cu")
		(net "M_H_CPU0_SA_CS_N<0>")
	)
	(arc
		(start 390.54786 -251.286772)
		(mid 390.264904 -251.210595)
		(end 389.981948 -251.286772)
		(width 0.0889)
		(layer "In13.Cu")
		(net "M_H_CPU0_SA_CS_N<0>")
	)
	(segment
		(start 381.807974 -249.610118)
		(end 382.274826 -249.34418)
		(width 0.10668)
		(layer "F.Cu")
		(net "M_H_CPU0_SA_CB<7>")
	)
	(segment
		(start 411.230064 -245.95709)
		(end 411.415484 -245.77167)
		(width 0.14478)
		(layer "In13.Cu")
		(net "M_H_CPU0_SA_CB<7>")
	)
	(segment
		(start 419.062916 -243.263674)
		(end 419.883336 -243.263674)
		(width 0.14478)
		(layer "In13.Cu")
		(net "M_H_CPU0_SA_CB<7>")
	)
	(segment
		(start 409.77312 -246.83974)
		(end 409.958286 -246.654574)
		(width 0.14478)
		(layer "In13.Cu")
		(net "M_H_CPU0_SA_CB<7>")
	)
	(segment
		(start 410.738066 -245.874794)
		(end 410.94279 -245.87454)
		(width 0.14478)
		(layer "In13.Cu")
		(net "M_H_CPU0_SA_CB<7>")
	)
	(segment
		(start 408.110944 -249.07621)
		(end 408.296364 -248.89079)
		(width 0.14478)
		(layer "In13.Cu")
		(net "M_H_CPU0_SA_CB<7>")
	)
	(segment
		(start 418.773356 -243.769642)
		(end 418.918136 -243.624862)
		(width 0.14478)
		(layer "In13.Cu")
		(net "M_H_CPU0_SA_CB<7>")
	)
	(segment
		(start 410.635704 -246.55145)
		(end 410.63545 -246.347234)
		(width 0.14478)
		(layer "In13.Cu")
		(net "M_H_CPU0_SA_CB<7>")
	)
	(segment
		(start 409.07589 -247.906794)
		(end 408.99334 -247.824244)
		(width 0.14478)
		(layer "In13.Cu")
		(net "M_H_CPU0_SA_CB<7>")
	)
	(segment
		(start 411.41523 -245.567454)
		(end 411.33268 -245.484904)
		(width 0.14478)
		(layer "In13.Cu")
		(net "M_H_CPU0_SA_CB<7>")
	)
	(segment
		(start 408.686 -248.29643)
		(end 408.890724 -248.29643)
		(width 0.14478)
		(layer "In13.Cu")
		(net "M_H_CPU0_SA_CB<7>")
	)
	(segment
		(start 411.653228 -244.959632)
		(end 412.71698 -244.959632)
		(width 0.14478)
		(layer "In13.Cu")
		(net "M_H_CPU0_SA_CB<7>")
	)
	(segment
		(start 408.99334 -247.824244)
		(end 408.99334 -247.61952)
		(width 0.14478)
		(layer "In13.Cu")
		(net "M_H_CPU0_SA_CB<7>")
	)
	(segment
		(start 413.645096 -244.254528)
		(end 413.789876 -244.109748)
		(width 0.14478)
		(layer "In13.Cu")
		(net "M_H_CPU0_SA_CB<7>")
	)
	(segment
		(start 408.398726 -248.214134)
		(end 408.60345 -248.21388)
		(width 0.14478)
		(layer "In13.Cu")
		(net "M_H_CPU0_SA_CB<7>")
	)
	(segment
		(start 414.196276 -244.254528)
		(end 414.196276 -244.672104)
		(width 0.14478)
		(layer "In13.Cu")
		(net "M_H_CPU0_SA_CB<7>")
	)
	(segment
		(start 384.333496 -249.016774)
		(end 384.341878 -249.0216)
		(width 0.0889)
		(layer "In13.Cu")
		(net "M_H_CPU0_SA_CB<7>")
	)
	(segment
		(start 414.892236 -244.510052)
		(end 416.630612 -244.510052)
		(width 0.14478)
		(layer "In13.Cu")
		(net "M_H_CPU0_SA_CB<7>")
	)
	(segment
		(start 412.71698 -244.959632)
		(end 413.16656 -244.510052)
		(width 0.14478)
		(layer "In13.Cu")
		(net "M_H_CPU0_SA_CB<7>")
	)
	(segment
		(start 397.157194 -249.216672)
		(end 407.396188 -249.216672)
		(width 0.14478)
		(layer "In13.Cu")
		(net "M_H_CPU0_SA_CB<7>")
	)
	(segment
		(start 389.607806 -249.0216)
		(end 389.616188 -249.016774)
		(width 0.0889)
		(layer "In13.Cu")
		(net "M_H_CPU0_SA_CB<7>")
	)
	(segment
		(start 409.85567 -247.127014)
		(end 409.77312 -247.044464)
		(width 0.14478)
		(layer "In13.Cu")
		(net "M_H_CPU0_SA_CB<7>")
	)
	(segment
		(start 409.670504 -247.51665)
		(end 409.855924 -247.33123)
		(width 0.14478)
		(layer "In13.Cu")
		(net "M_H_CPU0_SA_CB<7>")
	)
	(segment
		(start 411.415484 -245.77167)
		(end 411.41523 -245.567454)
		(width 0.14478)
		(layer "In13.Cu")
		(net "M_H_CPU0_SA_CB<7>")
	)
	(segment
		(start 418.366956 -243.624862)
		(end 418.511736 -243.769642)
		(width 0.14478)
		(layer "In13.Cu")
		(net "M_H_CPU0_SA_CB<7>")
	)
	(segment
		(start 392.788648 -249.01398)
		(end 392.802364 -249.021854)
		(width 0.0889)
		(layer "In13.Cu")
		(net "M_H_CPU0_SA_CB<7>")
	)
	(segment
		(start 411.33268 -245.484904)
		(end 411.33268 -245.28018)
		(width 0.14478)
		(layer "In13.Cu")
		(net "M_H_CPU0_SA_CB<7>")
	)
	(segment
		(start 414.341056 -244.816884)
		(end 414.602676 -244.816884)
		(width 0.14478)
		(layer "In13.Cu")
		(net "M_H_CPU0_SA_CB<7>")
	)
	(segment
		(start 394.846556 -249.24385)
		(end 395.062456 -249.45975)
		(width 0.0889)
		(layer "In13.Cu")
		(net "M_H_CPU0_SA_CB<7>")
	)
	(segment
		(start 389.033512 -249.016774)
		(end 389.041894 -249.0216)
		(width 0.0889)
		(layer "In13.Cu")
		(net "M_H_CPU0_SA_CB<7>")
	)
	(segment
		(start 392.802364 -249.021854)
		(end 392.818112 -249.030998)
		(width 0.0889)
		(layer "In13.Cu")
		(net "M_H_CPU0_SA_CB<7>")
	)
	(segment
		(start 408.60345 -248.21388)
		(end 408.686 -248.29643)
		(width 0.14478)
		(layer "In13.Cu")
		(net "M_H_CPU0_SA_CB<7>")
	)
	(segment
		(start 395.062456 -249.45975)
		(end 395.692122 -249.45975)
		(width 0.0889)
		(layer "In13.Cu")
		(net "M_H_CPU0_SA_CB<7>")
	)
	(segment
		(start 414.747456 -244.654832)
		(end 414.892236 -244.510052)
		(width 0.14478)
		(layer "In13.Cu")
		(net "M_H_CPU0_SA_CB<7>")
	)
	(segment
		(start 414.602676 -244.816884)
		(end 414.747456 -244.672104)
		(width 0.14478)
		(layer "In13.Cu")
		(net "M_H_CPU0_SA_CB<7>")
	)
	(segment
		(start 413.645096 -244.365272)
		(end 413.645096 -244.254528)
		(width 0.14478)
		(layer "In13.Cu")
		(net "M_H_CPU0_SA_CB<7>")
	)
	(segment
		(start 410.5529 -246.264684)
		(end 410.5529 -246.05996)
		(width 0.14478)
		(layer "In13.Cu")
		(net "M_H_CPU0_SA_CB<7>")
	)
	(segment
		(start 385.847844 -249.0216)
		(end 385.856226 -249.016774)
		(width 0.0889)
		(layer "In13.Cu")
		(net "M_H_CPU0_SA_CB<7>")
	)
	(segment
		(start 384.90779 -249.0216)
		(end 384.916172 -249.016774)
		(width 0.0889)
		(layer "In13.Cu")
		(net "M_H_CPU0_SA_CB<7>")
	)
	(segment
		(start 393.734544 -249.016774)
		(end 393.734544 -249.022108)
		(width 0.0889)
		(layer "In13.Cu")
		(net "M_H_CPU0_SA_CB<7>")
	)
	(segment
		(start 393.734544 -249.022108)
		(end 393.956286 -249.24385)
		(width 0.0889)
		(layer "In13.Cu")
		(net "M_H_CPU0_SA_CB<7>")
	)
	(segment
		(start 395.692122 -249.45975)
		(end 396.914116 -249.45975)
		(width 0.14478)
		(layer "In13.Cu")
		(net "M_H_CPU0_SA_CB<7>")
	)
	(segment
		(start 417.87699 -243.263674)
		(end 418.222176 -243.263674)
		(width 0.14478)
		(layer "In13.Cu")
		(net "M_H_CPU0_SA_CB<7>")
	)
	(segment
		(start 411.33268 -245.28018)
		(end 411.653228 -244.959632)
		(width 0.14478)
		(layer "In13.Cu")
		(net "M_H_CPU0_SA_CB<7>")
	)
	(segment
		(start 408.890724 -248.29643)
		(end 409.076144 -248.11101)
		(width 0.14478)
		(layer "In13.Cu")
		(net "M_H_CPU0_SA_CB<7>")
	)
	(segment
		(start 407.82367 -248.99366)
		(end 407.90622 -249.07621)
		(width 0.14478)
		(layer "In13.Cu")
		(net "M_H_CPU0_SA_CB<7>")
	)
	(segment
		(start 382.274826 -249.34418)
		(end 382.42875 -249.07875)
		(width 0.0889)
		(layer "In13.Cu")
		(net "M_H_CPU0_SA_CB<7>")
	)
	(segment
		(start 410.24556 -246.73687)
		(end 410.450284 -246.73687)
		(width 0.14478)
		(layer "In13.Cu")
		(net "M_H_CPU0_SA_CB<7>")
	)
	(segment
		(start 408.29611 -248.686574)
		(end 408.21356 -248.604024)
		(width 0.14478)
		(layer "In13.Cu")
		(net "M_H_CPU0_SA_CB<7>")
	)
	(segment
		(start 410.16301 -246.65432)
		(end 410.24556 -246.73687)
		(width 0.14478)
		(layer "In13.Cu")
		(net "M_H_CPU0_SA_CB<7>")
	)
	(segment
		(start 407.396188 -249.216672)
		(end 407.618946 -248.993914)
		(width 0.14478)
		(layer "In13.Cu")
		(net "M_H_CPU0_SA_CB<7>")
	)
	(segment
		(start 392.413998 -249.030236)
		(end 392.42873 -249.0216)
		(width 0.0889)
		(layer "In13.Cu")
		(net "M_H_CPU0_SA_CB<7>")
	)
	(segment
		(start 416.630612 -244.510052)
		(end 417.87699 -243.263674)
		(width 0.14478)
		(layer "In13.Cu")
		(net "M_H_CPU0_SA_CB<7>")
	)
	(segment
		(start 414.196276 -244.672104)
		(end 414.341056 -244.816884)
		(width 0.14478)
		(layer "In13.Cu")
		(net "M_H_CPU0_SA_CB<7>")
	)
	(segment
		(start 413.500316 -244.510052)
		(end 413.645096 -244.365272)
		(width 0.14478)
		(layer "In13.Cu")
		(net "M_H_CPU0_SA_CB<7>")
	)
	(segment
		(start 413.16656 -244.510052)
		(end 413.500316 -244.510052)
		(width 0.14478)
		(layer "In13.Cu")
		(net "M_H_CPU0_SA_CB<7>")
	)
	(segment
		(start 383.393442 -249.016774)
		(end 383.401824 -249.0216)
		(width 0.0889)
		(layer "In13.Cu")
		(net "M_H_CPU0_SA_CB<7>")
	)
	(segment
		(start 408.21356 -248.604024)
		(end 408.21356 -248.3993)
		(width 0.14478)
		(layer "In13.Cu")
		(net "M_H_CPU0_SA_CB<7>")
	)
	(segment
		(start 396.914116 -249.45975)
		(end 397.157194 -249.216672)
		(width 0.14478)
		(layer "In13.Cu")
		(net "M_H_CPU0_SA_CB<7>")
	)
	(segment
		(start 419.883336 -243.263674)
		(end 419.912038 -243.234972)
		(width 0.14478)
		(layer "In13.Cu")
		(net "M_H_CPU0_SA_CB<7>")
	)
	(segment
		(start 418.222176 -243.263674)
		(end 418.366956 -243.408454)
		(width 0.14478)
		(layer "In13.Cu")
		(net "M_H_CPU0_SA_CB<7>")
	)
	(segment
		(start 408.296364 -248.89079)
		(end 408.29611 -248.686574)
		(width 0.14478)
		(layer "In13.Cu")
		(net "M_H_CPU0_SA_CB<7>")
	)
	(segment
		(start 411.02534 -245.95709)
		(end 411.230064 -245.95709)
		(width 0.14478)
		(layer "In13.Cu")
		(net "M_H_CPU0_SA_CB<7>")
	)
	(segment
		(start 414.747456 -244.672104)
		(end 414.747456 -244.654832)
		(width 0.14478)
		(layer "In13.Cu")
		(net "M_H_CPU0_SA_CB<7>")
	)
	(segment
		(start 409.855924 -247.33123)
		(end 409.85567 -247.127014)
		(width 0.14478)
		(layer "In13.Cu")
		(net "M_H_CPU0_SA_CB<7>")
	)
	(segment
		(start 410.450284 -246.73687)
		(end 410.635704 -246.55145)
		(width 0.14478)
		(layer "In13.Cu")
		(net "M_H_CPU0_SA_CB<7>")
	)
	(segment
		(start 409.178506 -247.434354)
		(end 409.38323 -247.4341)
		(width 0.14478)
		(layer "In13.Cu")
		(net "M_H_CPU0_SA_CB<7>")
	)
	(segment
		(start 409.46578 -247.51665)
		(end 409.670504 -247.51665)
		(width 0.14478)
		(layer "In13.Cu")
		(net "M_H_CPU0_SA_CB<7>")
	)
	(segment
		(start 409.958286 -246.654574)
		(end 410.16301 -246.65432)
		(width 0.14478)
		(layer "In13.Cu")
		(net "M_H_CPU0_SA_CB<7>")
	)
	(segment
		(start 410.94279 -245.87454)
		(end 411.02534 -245.95709)
		(width 0.14478)
		(layer "In13.Cu")
		(net "M_H_CPU0_SA_CB<7>")
	)
	(segment
		(start 408.99334 -247.61952)
		(end 409.178506 -247.434354)
		(width 0.14478)
		(layer "In13.Cu")
		(net "M_H_CPU0_SA_CB<7>")
	)
	(segment
		(start 382.42875 -249.07875)
		(end 382.524762 -249.05335)
		(width 0.0889)
		(layer "In13.Cu")
		(net "M_H_CPU0_SA_CB<7>")
	)
	(segment
		(start 410.63545 -246.347234)
		(end 410.5529 -246.264684)
		(width 0.14478)
		(layer "In13.Cu")
		(net "M_H_CPU0_SA_CB<7>")
	)
	(segment
		(start 409.38323 -247.4341)
		(end 409.46578 -247.51665)
		(width 0.14478)
		(layer "In13.Cu")
		(net "M_H_CPU0_SA_CB<7>")
	)
	(segment
		(start 408.21356 -248.3993)
		(end 408.398726 -248.214134)
		(width 0.14478)
		(layer "In13.Cu")
		(net "M_H_CPU0_SA_CB<7>")
	)
	(segment
		(start 410.5529 -246.05996)
		(end 410.738066 -245.874794)
		(width 0.14478)
		(layer "In13.Cu")
		(net "M_H_CPU0_SA_CB<7>")
	)
	(segment
		(start 393.956286 -249.24385)
		(end 394.846556 -249.24385)
		(width 0.0889)
		(layer "In13.Cu")
		(net "M_H_CPU0_SA_CB<7>")
	)
	(segment
		(start 413.789876 -244.109748)
		(end 414.051496 -244.109748)
		(width 0.14478)
		(layer "In13.Cu")
		(net "M_H_CPU0_SA_CB<7>")
	)
	(segment
		(start 391.48766 -249.0216)
		(end 391.496042 -249.016774)
		(width 0.0889)
		(layer "In13.Cu")
		(net "M_H_CPU0_SA_CB<7>")
	)
	(segment
		(start 418.366956 -243.408454)
		(end 418.366956 -243.624862)
		(width 0.14478)
		(layer "In13.Cu")
		(net "M_H_CPU0_SA_CB<7>")
	)
	(segment
		(start 409.076144 -248.11101)
		(end 409.07589 -247.906794)
		(width 0.14478)
		(layer "In13.Cu")
		(net "M_H_CPU0_SA_CB<7>")
	)
	(segment
		(start 407.618946 -248.993914)
		(end 407.82367 -248.99366)
		(width 0.14478)
		(layer "In13.Cu")
		(net "M_H_CPU0_SA_CB<7>")
	)
	(segment
		(start 388.093458 -249.016774)
		(end 388.10184 -249.0216)
		(width 0.0889)
		(layer "In13.Cu")
		(net "M_H_CPU0_SA_CB<7>")
	)
	(segment
		(start 418.511736 -243.769642)
		(end 418.773356 -243.769642)
		(width 0.14478)
		(layer "In13.Cu")
		(net "M_H_CPU0_SA_CB<7>")
	)
	(segment
		(start 418.918136 -243.408454)
		(end 419.062916 -243.263674)
		(width 0.14478)
		(layer "In13.Cu")
		(net "M_H_CPU0_SA_CB<7>")
	)
	(segment
		(start 418.918136 -243.624862)
		(end 418.918136 -243.408454)
		(width 0.14478)
		(layer "In13.Cu")
		(net "M_H_CPU0_SA_CB<7>")
	)
	(segment
		(start 409.77312 -247.044464)
		(end 409.77312 -246.83974)
		(width 0.14478)
		(layer "In13.Cu")
		(net "M_H_CPU0_SA_CB<7>")
	)
	(segment
		(start 407.90622 -249.07621)
		(end 408.110944 -249.07621)
		(width 0.14478)
		(layer "In13.Cu")
		(net "M_H_CPU0_SA_CB<7>")
	)
	(segment
		(start 414.051496 -244.109748)
		(end 414.196276 -244.254528)
		(width 0.14478)
		(layer "In13.Cu")
		(net "M_H_CPU0_SA_CB<7>")
	)
	(arc
		(start 383.967736 -249.0216)
		(mid 384.149987 -248.97125)
		(end 384.333496 -249.016774)
		(width 0.0889)
		(layer "In13.Cu")
		(net "M_H_CPU0_SA_CB<7>")
	)
	(arc
		(start 385.281932 -249.0216)
		(mid 385.564888 -249.097777)
		(end 385.847844 -249.0216)
		(width 0.0889)
		(layer "In13.Cu")
		(net "M_H_CPU0_SA_CB<7>")
	)
	(arc
		(start 389.981948 -249.0216)
		(mid 390.264904 -249.097777)
		(end 390.54786 -249.0216)
		(width 0.0889)
		(layer "In13.Cu")
		(net "M_H_CPU0_SA_CB<7>")
	)
	(arc
		(start 386.787898 -249.0216)
		(mid 386.974842 -248.971345)
		(end 387.161786 -249.0216)
		(width 0.0889)
		(layer "In13.Cu")
		(net "M_H_CPU0_SA_CB<7>")
	)
	(arc
		(start 388.667752 -249.0216)
		(mid 388.850003 -248.97125)
		(end 389.033512 -249.016774)
		(width 0.0889)
		(layer "In13.Cu")
		(net "M_H_CPU0_SA_CB<7>")
	)
	(arc
		(start 392.818112 -249.030998)
		(mid 393.094421 -249.097974)
		(end 393.368276 -249.0216)
		(width 0.0889)
		(layer "In13.Cu")
		(net "M_H_CPU0_SA_CB<7>")
	)
	(arc
		(start 393.368276 -249.0216)
		(mid 393.550781 -248.971123)
		(end 393.734544 -249.016774)
		(width 0.0889)
		(layer "In13.Cu")
		(net "M_H_CPU0_SA_CB<7>")
	)
	(arc
		(start 390.921748 -249.0216)
		(mid 391.204704 -249.097777)
		(end 391.48766 -249.0216)
		(width 0.0889)
		(layer "In13.Cu")
		(net "M_H_CPU0_SA_CB<7>")
	)
	(arc
		(start 387.727698 -249.0216)
		(mid 387.909949 -248.97125)
		(end 388.093458 -249.016774)
		(width 0.0889)
		(layer "In13.Cu")
		(net "M_H_CPU0_SA_CB<7>")
	)
	(arc
		(start 389.616188 -249.016774)
		(mid 389.799696 -248.97128)
		(end 389.981948 -249.0216)
		(width 0.0889)
		(layer "In13.Cu")
		(net "M_H_CPU0_SA_CB<7>")
	)
	(arc
		(start 387.161786 -249.0216)
		(mid 387.444742 -249.097777)
		(end 387.727698 -249.0216)
		(width 0.0889)
		(layer "In13.Cu")
		(net "M_H_CPU0_SA_CB<7>")
	)
	(arc
		(start 391.86231 -249.0216)
		(mid 392.137016 -249.097964)
		(end 392.413998 -249.030236)
		(width 0.0889)
		(layer "In13.Cu")
		(net "M_H_CPU0_SA_CB<7>")
	)
	(arc
		(start 389.041894 -249.0216)
		(mid 389.32485 -249.097777)
		(end 389.607806 -249.0216)
		(width 0.0889)
		(layer "In13.Cu")
		(net "M_H_CPU0_SA_CB<7>")
	)
	(arc
		(start 384.341878 -249.0216)
		(mid 384.624834 -249.097777)
		(end 384.90779 -249.0216)
		(width 0.0889)
		(layer "In13.Cu")
		(net "M_H_CPU0_SA_CB<7>")
	)
	(arc
		(start 382.524762 -249.05335)
		(mid 382.77997 -249.096827)
		(end 383.027682 -249.0216)
		(width 0.0889)
		(layer "In13.Cu")
		(net "M_H_CPU0_SA_CB<7>")
	)
	(arc
		(start 386.221986 -249.0216)
		(mid 386.504942 -249.097777)
		(end 386.787898 -249.0216)
		(width 0.0889)
		(layer "In13.Cu")
		(net "M_H_CPU0_SA_CB<7>")
	)
	(arc
		(start 384.916172 -249.016774)
		(mid 385.09968 -248.97128)
		(end 385.281932 -249.0216)
		(width 0.0889)
		(layer "In13.Cu")
		(net "M_H_CPU0_SA_CB<7>")
	)
	(arc
		(start 385.856226 -249.016774)
		(mid 386.039734 -248.97128)
		(end 386.221986 -249.0216)
		(width 0.0889)
		(layer "In13.Cu")
		(net "M_H_CPU0_SA_CB<7>")
	)
	(arc
		(start 388.10184 -249.0216)
		(mid 388.384796 -249.097777)
		(end 388.667752 -249.0216)
		(width 0.0889)
		(layer "In13.Cu")
		(net "M_H_CPU0_SA_CB<7>")
	)
	(arc
		(start 390.54786 -249.0216)
		(mid 390.734804 -248.971345)
		(end 390.921748 -249.0216)
		(width 0.0889)
		(layer "In13.Cu")
		(net "M_H_CPU0_SA_CB<7>")
	)
	(arc
		(start 392.42873 -249.0216)
		(mid 392.607717 -248.97143)
		(end 392.788648 -249.01398)
		(width 0.0889)
		(layer "In13.Cu")
		(net "M_H_CPU0_SA_CB<7>")
	)
	(arc
		(start 383.027682 -249.0216)
		(mid 383.209933 -248.97125)
		(end 383.393442 -249.016774)
		(width 0.0889)
		(layer "In13.Cu")
		(net "M_H_CPU0_SA_CB<7>")
	)
	(arc
		(start 383.401824 -249.0216)
		(mid 383.68478 -249.097777)
		(end 383.967736 -249.0216)
		(width 0.0889)
		(layer "In13.Cu")
		(net "M_H_CPU0_SA_CB<7>")
	)
	(arc
		(start 391.496042 -249.016774)
		(mid 391.679804 -248.971158)
		(end 391.86231 -249.0216)
		(width 0.0889)
		(layer "In13.Cu")
		(net "M_H_CPU0_SA_CB<7>")
	)
	(segment
		(start 383.217928 -248.800112)
		(end 383.68478 -248.534174)
		(width 0.10668)
		(layer "F.Cu")
		(net "M_H_CPU0_SA_CB<6>")
	)
	(segment
		(start 418.225478 -242.16614)
		(end 418.080698 -242.31092)
		(width 0.14478)
		(layer "In13.Cu")
		(net "M_H_CPU0_SA_CB<6>")
	)
	(segment
		(start 415.407856 -242.284504)
		(end 415.263076 -242.139724)
		(width 0.14478)
		(layer "In13.Cu")
		(net "M_H_CPU0_SA_CB<6>")
	)
	(segment
		(start 419.327838 -242.16614)
		(end 419.183058 -242.31092)
		(width 0.14478)
		(layer "In13.Cu")
		(net "M_H_CPU0_SA_CB<6>")
	)
	(segment
		(start 388.206234 -248.206768)
		(end 388.197852 -248.211594)
		(width 0.0889)
		(layer "In13.Cu")
		(net "M_H_CPU0_SA_CB<6>")
	)
	(segment
		(start 415.959036 -242.828572)
		(end 415.814256 -242.973352)
		(width 0.14478)
		(layer "In13.Cu")
		(net "M_H_CPU0_SA_CB<6>")
	)
	(segment
		(start 417.055554 -241.53495)
		(end 416.45078 -242.139724)
		(width 0.14478)
		(layer "In13.Cu")
		(net "M_H_CPU0_SA_CB<6>")
	)
	(segment
		(start 418.631878 -241.53495)
		(end 418.370258 -241.53495)
		(width 0.14478)
		(layer "In13.Cu")
		(net "M_H_CPU0_SA_CB<6>")
	)
	(segment
		(start 396.9004 -248.165366)
		(end 396.522956 -248.54281)
		(width 0.14478)
		(layer "In13.Cu")
		(net "M_H_CPU0_SA_CB<6>")
	)
	(segment
		(start 414.450276 -242.973352)
		(end 414.305496 -242.828572)
		(width 0.14478)
		(layer "In13.Cu")
		(net "M_H_CPU0_SA_CB<6>")
	)
	(segment
		(start 414.856676 -242.284504)
		(end 414.856676 -242.828572)
		(width 0.14478)
		(layer "In13.Cu")
		(net "M_H_CPU0_SA_CB<6>")
	)
	(segment
		(start 417.529518 -241.53495)
		(end 417.055554 -241.53495)
		(width 0.14478)
		(layer "In13.Cu")
		(net "M_H_CPU0_SA_CB<6>")
	)
	(segment
		(start 415.263076 -242.139724)
		(end 415.001456 -242.139724)
		(width 0.14478)
		(layer "In13.Cu")
		(net "M_H_CPU0_SA_CB<6>")
	)
	(segment
		(start 395.179296 -248.54281)
		(end 395.095476 -248.62663)
		(width 0.0889)
		(layer "In13.Cu")
		(net "M_H_CPU0_SA_CB<6>")
	)
	(segment
		(start 386.691886 -248.211594)
		(end 386.683504 -248.206768)
		(width 0.0889)
		(layer "In13.Cu")
		(net "M_H_CPU0_SA_CB<6>")
	)
	(segment
		(start 395.733778 -248.54281)
		(end 395.179296 -248.54281)
		(width 0.0889)
		(layer "In13.Cu")
		(net "M_H_CPU0_SA_CB<6>")
	)
	(segment
		(start 418.776658 -242.16614)
		(end 418.776658 -241.67973)
		(width 0.14478)
		(layer "In13.Cu")
		(net "M_H_CPU0_SA_CB<6>")
	)
	(segment
		(start 416.45078 -242.139724)
		(end 416.103816 -242.139724)
		(width 0.14478)
		(layer "In13.Cu")
		(net "M_H_CPU0_SA_CB<6>")
	)
	(segment
		(start 392.332718 -248.211594)
		(end 392.324336 -248.206768)
		(width 0.0889)
		(layer "In13.Cu")
		(net "M_H_CPU0_SA_CB<6>")
	)
	(segment
		(start 392.91641 -248.201434)
		(end 392.898122 -248.211848)
		(width 0.0889)
		(layer "In13.Cu")
		(net "M_H_CPU0_SA_CB<6>")
	)
	(segment
		(start 414.856676 -242.828572)
		(end 414.711896 -242.973352)
		(width 0.14478)
		(layer "In13.Cu")
		(net "M_H_CPU0_SA_CB<6>")
	)
	(segment
		(start 415.814256 -242.973352)
		(end 415.552636 -242.973352)
		(width 0.14478)
		(layer "In13.Cu")
		(net "M_H_CPU0_SA_CB<6>")
	)
	(segment
		(start 417.819078 -242.31092)
		(end 417.674298 -242.16614)
		(width 0.14478)
		(layer "In13.Cu")
		(net "M_H_CPU0_SA_CB<6>")
	)
	(segment
		(start 407.175208 -248.165366)
		(end 396.9004 -248.165366)
		(width 0.14478)
		(layer "In13.Cu")
		(net "M_H_CPU0_SA_CB<6>")
	)
	(segment
		(start 413.20085 -242.139724)
		(end 407.175208 -248.165366)
		(width 0.14478)
		(layer "In13.Cu")
		(net "M_H_CPU0_SA_CB<6>")
	)
	(segment
		(start 418.370258 -241.53495)
		(end 418.225478 -241.67973)
		(width 0.14478)
		(layer "In13.Cu")
		(net "M_H_CPU0_SA_CB<6>")
	)
	(segment
		(start 383.838958 -248.268744)
		(end 383.68478 -248.534174)
		(width 0.0889)
		(layer "In13.Cu")
		(net "M_H_CPU0_SA_CB<6>")
	)
	(segment
		(start 418.080698 -242.31092)
		(end 417.819078 -242.31092)
		(width 0.14478)
		(layer "In13.Cu")
		(net "M_H_CPU0_SA_CB<6>")
	)
	(segment
		(start 414.305496 -242.284504)
		(end 414.160716 -242.139724)
		(width 0.14478)
		(layer "In13.Cu")
		(net "M_H_CPU0_SA_CB<6>")
	)
	(segment
		(start 392.898122 -248.211848)
		(end 392.892534 -248.21515)
		(width 0.0889)
		(layer "In13.Cu")
		(net "M_H_CPU0_SA_CB<6>")
	)
	(segment
		(start 414.305496 -242.828572)
		(end 414.305496 -242.284504)
		(width 0.14478)
		(layer "In13.Cu")
		(net "M_H_CPU0_SA_CB<6>")
	)
	(segment
		(start 418.776658 -241.67973)
		(end 418.631878 -241.53495)
		(width 0.14478)
		(layer "In13.Cu")
		(net "M_H_CPU0_SA_CB<6>")
	)
	(segment
		(start 419.912038 -241.53495)
		(end 419.472618 -241.53495)
		(width 0.14478)
		(layer "In13.Cu")
		(net "M_H_CPU0_SA_CB<6>")
	)
	(segment
		(start 393.665964 -248.48439)
		(end 393.461748 -248.280174)
		(width 0.0889)
		(layer "In13.Cu")
		(net "M_H_CPU0_SA_CB<6>")
	)
	(segment
		(start 419.327838 -241.67973)
		(end 419.327838 -242.16614)
		(width 0.14478)
		(layer "In13.Cu")
		(net "M_H_CPU0_SA_CB<6>")
	)
	(segment
		(start 419.472618 -241.53495)
		(end 419.327838 -241.67973)
		(width 0.14478)
		(layer "In13.Cu")
		(net "M_H_CPU0_SA_CB<6>")
	)
	(segment
		(start 391.402316 -248.21769)
		(end 391.391902 -248.211594)
		(width 0.0889)
		(layer "In13.Cu")
		(net "M_H_CPU0_SA_CB<6>")
	)
	(segment
		(start 415.407856 -242.828572)
		(end 415.407856 -242.284504)
		(width 0.14478)
		(layer "In13.Cu")
		(net "M_H_CPU0_SA_CB<6>")
	)
	(segment
		(start 396.522956 -248.54281)
		(end 395.733778 -248.54281)
		(width 0.14478)
		(layer "In13.Cu")
		(net "M_H_CPU0_SA_CB<6>")
	)
	(segment
		(start 418.225478 -241.67973)
		(end 418.225478 -242.16614)
		(width 0.14478)
		(layer "In13.Cu")
		(net "M_H_CPU0_SA_CB<6>")
	)
	(segment
		(start 415.001456 -242.139724)
		(end 414.856676 -242.284504)
		(width 0.14478)
		(layer "In13.Cu")
		(net "M_H_CPU0_SA_CB<6>")
	)
	(segment
		(start 417.674298 -242.16614)
		(end 417.674298 -241.67973)
		(width 0.14478)
		(layer "In13.Cu")
		(net "M_H_CPU0_SA_CB<6>")
	)
	(segment
		(start 414.711896 -242.973352)
		(end 414.450276 -242.973352)
		(width 0.14478)
		(layer "In13.Cu")
		(net "M_H_CPU0_SA_CB<6>")
	)
	(segment
		(start 418.921438 -242.31092)
		(end 418.776658 -242.16614)
		(width 0.14478)
		(layer "In13.Cu")
		(net "M_H_CPU0_SA_CB<6>")
	)
	(segment
		(start 414.160716 -242.139724)
		(end 413.20085 -242.139724)
		(width 0.14478)
		(layer "In13.Cu")
		(net "M_H_CPU0_SA_CB<6>")
	)
	(segment
		(start 416.103816 -242.139724)
		(end 415.959036 -242.284504)
		(width 0.14478)
		(layer "In13.Cu")
		(net "M_H_CPU0_SA_CB<6>")
	)
	(segment
		(start 419.183058 -242.31092)
		(end 418.921438 -242.31092)
		(width 0.14478)
		(layer "In13.Cu")
		(net "M_H_CPU0_SA_CB<6>")
	)
	(segment
		(start 415.959036 -242.284504)
		(end 415.959036 -242.828572)
		(width 0.14478)
		(layer "In13.Cu")
		(net "M_H_CPU0_SA_CB<6>")
	)
	(segment
		(start 387.26618 -248.206768)
		(end 387.257798 -248.211594)
		(width 0.0889)
		(layer "In13.Cu")
		(net "M_H_CPU0_SA_CB<6>")
	)
	(segment
		(start 385.751832 -248.211594)
		(end 385.74345 -248.206768)
		(width 0.0889)
		(layer "In13.Cu")
		(net "M_H_CPU0_SA_CB<6>")
	)
	(segment
		(start 393.896596 -248.48439)
		(end 393.665964 -248.48439)
		(width 0.0889)
		(layer "In13.Cu")
		(net "M_H_CPU0_SA_CB<6>")
	)
	(segment
		(start 394.038836 -248.62663)
		(end 393.896596 -248.48439)
		(width 0.0889)
		(layer "In13.Cu")
		(net "M_H_CPU0_SA_CB<6>")
	)
	(segment
		(start 391.026142 -248.206768)
		(end 391.01776 -248.211594)
		(width 0.0889)
		(layer "In13.Cu")
		(net "M_H_CPU0_SA_CB<6>")
	)
	(segment
		(start 383.935224 -248.243344)
		(end 383.838958 -248.268744)
		(width 0.0889)
		(layer "In13.Cu")
		(net "M_H_CPU0_SA_CB<6>")
	)
	(segment
		(start 395.095476 -248.62663)
		(end 394.038836 -248.62663)
		(width 0.0889)
		(layer "In13.Cu")
		(net "M_H_CPU0_SA_CB<6>")
	)
	(segment
		(start 417.674298 -241.67973)
		(end 417.529518 -241.53495)
		(width 0.14478)
		(layer "In13.Cu")
		(net "M_H_CPU0_SA_CB<6>")
	)
	(segment
		(start 390.451848 -248.211594)
		(end 390.443466 -248.206768)
		(width 0.0889)
		(layer "In13.Cu")
		(net "M_H_CPU0_SA_CB<6>")
	)
	(segment
		(start 415.552636 -242.973352)
		(end 415.407856 -242.828572)
		(width 0.14478)
		(layer "In13.Cu")
		(net "M_H_CPU0_SA_CB<6>")
	)
	(arc
		(start 386.683504 -248.206768)
		(mid 386.499996 -248.161274)
		(end 386.317744 -248.211594)
		(width 0.0889)
		(layer "In13.Cu")
		(net "M_H_CPU0_SA_CB<6>")
	)
	(arc
		(start 384.43789 -248.211594)
		(mid 384.190294 -248.286772)
		(end 383.935224 -248.243344)
		(width 0.0889)
		(layer "In13.Cu")
		(net "M_H_CPU0_SA_CB<6>")
	)
	(arc
		(start 387.63194 -248.211594)
		(mid 387.449689 -248.161244)
		(end 387.26618 -248.206768)
		(width 0.0889)
		(layer "In13.Cu")
		(net "M_H_CPU0_SA_CB<6>")
	)
	(arc
		(start 386.317744 -248.211594)
		(mid 386.034788 -248.287771)
		(end 385.751832 -248.211594)
		(width 0.0889)
		(layer "In13.Cu")
		(net "M_H_CPU0_SA_CB<6>")
	)
	(arc
		(start 388.571994 -248.211594)
		(mid 388.389743 -248.161244)
		(end 388.206234 -248.206768)
		(width 0.0889)
		(layer "In13.Cu")
		(net "M_H_CPU0_SA_CB<6>")
	)
	(arc
		(start 390.077706 -248.211594)
		(mid 389.79475 -248.287771)
		(end 389.511794 -248.211594)
		(width 0.0889)
		(layer "In13.Cu")
		(net "M_H_CPU0_SA_CB<6>")
	)
	(arc
		(start 392.324336 -248.206768)
		(mid 392.140574 -248.161152)
		(end 391.958068 -248.211594)
		(width 0.0889)
		(layer "In13.Cu")
		(net "M_H_CPU0_SA_CB<6>")
	)
	(arc
		(start 391.391902 -248.211594)
		(mid 391.209651 -248.161244)
		(end 391.026142 -248.206768)
		(width 0.0889)
		(layer "In13.Cu")
		(net "M_H_CPU0_SA_CB<6>")
	)
	(arc
		(start 388.197852 -248.211594)
		(mid 387.914896 -248.287771)
		(end 387.63194 -248.211594)
		(width 0.0889)
		(layer "In13.Cu")
		(net "M_H_CPU0_SA_CB<6>")
	)
	(arc
		(start 393.461748 -248.280174)
		(mid 393.36391 -248.254433)
		(end 393.272264 -248.211594)
		(width 0.0889)
		(layer "In13.Cu")
		(net "M_H_CPU0_SA_CB<6>")
	)
	(arc
		(start 385.37769 -248.211594)
		(mid 385.094734 -248.287771)
		(end 384.811778 -248.211594)
		(width 0.0889)
		(layer "In13.Cu")
		(net "M_H_CPU0_SA_CB<6>")
	)
	(arc
		(start 387.257798 -248.211594)
		(mid 386.974842 -248.287771)
		(end 386.691886 -248.211594)
		(width 0.0889)
		(layer "In13.Cu")
		(net "M_H_CPU0_SA_CB<6>")
	)
	(arc
		(start 391.958068 -248.211594)
		(mid 391.681001 -248.287865)
		(end 391.402316 -248.21769)
		(width 0.0889)
		(layer "In13.Cu")
		(net "M_H_CPU0_SA_CB<6>")
	)
	(arc
		(start 389.511794 -248.211594)
		(mid 389.32485 -248.161339)
		(end 389.137906 -248.211594)
		(width 0.0889)
		(layer "In13.Cu")
		(net "M_H_CPU0_SA_CB<6>")
	)
	(arc
		(start 393.272264 -248.211594)
		(mid 393.095636 -248.161361)
		(end 392.91641 -248.201434)
		(width 0.0889)
		(layer "In13.Cu")
		(net "M_H_CPU0_SA_CB<6>")
	)
	(arc
		(start 390.443466 -248.206768)
		(mid 390.259958 -248.161274)
		(end 390.077706 -248.211594)
		(width 0.0889)
		(layer "In13.Cu")
		(net "M_H_CPU0_SA_CB<6>")
	)
	(arc
		(start 384.811778 -248.211594)
		(mid 384.624834 -248.161339)
		(end 384.43789 -248.211594)
		(width 0.0889)
		(layer "In13.Cu")
		(net "M_H_CPU0_SA_CB<6>")
	)
	(arc
		(start 392.892534 -248.21515)
		(mid 392.612145 -248.287819)
		(end 392.332718 -248.211594)
		(width 0.0889)
		(layer "In13.Cu")
		(net "M_H_CPU0_SA_CB<6>")
	)
	(arc
		(start 385.74345 -248.206768)
		(mid 385.559942 -248.161274)
		(end 385.37769 -248.211594)
		(width 0.0889)
		(layer "In13.Cu")
		(net "M_H_CPU0_SA_CB<6>")
	)
	(arc
		(start 389.137906 -248.211594)
		(mid 388.85495 -248.287771)
		(end 388.571994 -248.211594)
		(width 0.0889)
		(layer "In13.Cu")
		(net "M_H_CPU0_SA_CB<6>")
	)
	(arc
		(start 391.01776 -248.211594)
		(mid 390.734804 -248.287771)
		(end 390.451848 -248.211594)
		(width 0.0889)
		(layer "In13.Cu")
		(net "M_H_CPU0_SA_CB<6>")
	)
	(segment
		(start 382.277874 -248.800112)
		(end 382.744726 -248.534174)
		(width 0.10668)
		(layer "F.Cu")
		(net "M_H_CPU0_SA_CB<5>")
	)
	(segment
		(start 392.898122 -248.8565)
		(end 392.91641 -248.866914)
		(width 0.0889)
		(layer "In13.Cu")
		(net "M_H_CPU0_SA_CB<5>")
	)
	(segment
		(start 391.391902 -248.856754)
		(end 391.406634 -248.848118)
		(width 0.0889)
		(layer "In13.Cu")
		(net "M_H_CPU0_SA_CB<5>")
	)
	(segment
		(start 385.74345 -248.86158)
		(end 385.751832 -248.856754)
		(width 0.0889)
		(layer "In13.Cu")
		(net "M_H_CPU0_SA_CB<5>")
	)
	(segment
		(start 411.466538 -244.510052)
		(end 412.530544 -244.510052)
		(width 0.14478)
		(layer "In13.Cu")
		(net "M_H_CPU0_SA_CB<5>")
	)
	(segment
		(start 386.683504 -248.86158)
		(end 386.691886 -248.856754)
		(width 0.0889)
		(layer "In13.Cu")
		(net "M_H_CPU0_SA_CB<5>")
	)
	(segment
		(start 393.823952 -248.848118)
		(end 393.996926 -248.94159)
		(width 0.0889)
		(layer "In13.Cu")
		(net "M_H_CPU0_SA_CB<5>")
	)
	(segment
		(start 382.744726 -248.534174)
		(end 382.590802 -248.799604)
		(width 0.0889)
		(layer "In13.Cu")
		(net "M_H_CPU0_SA_CB<5>")
	)
	(segment
		(start 388.197852 -248.856754)
		(end 388.206234 -248.86158)
		(width 0.0889)
		(layer "In13.Cu")
		(net "M_H_CPU0_SA_CB<5>")
	)
	(segment
		(start 392.321034 -248.863612)
		(end 392.332718 -248.856754)
		(width 0.0889)
		(layer "In13.Cu")
		(net "M_H_CPU0_SA_CB<5>")
	)
	(segment
		(start 421.476424 -242.814094)
		(end 421.90543 -242.385088)
		(width 0.14478)
		(layer "In13.Cu")
		(net "M_H_CPU0_SA_CB<5>")
	)
	(segment
		(start 390.443466 -248.86158)
		(end 390.451848 -248.856754)
		(width 0.0889)
		(layer "In13.Cu")
		(net "M_H_CPU0_SA_CB<5>")
	)
	(segment
		(start 395.334236 -248.94159)
		(end 395.395196 -249.00255)
		(width 0.0889)
		(layer "In13.Cu")
		(net "M_H_CPU0_SA_CB<5>")
	)
	(segment
		(start 413.380428 -243.660168)
		(end 416.765994 -243.660168)
		(width 0.14478)
		(layer "In13.Cu")
		(net "M_H_CPU0_SA_CB<5>")
	)
	(segment
		(start 392.892534 -248.853198)
		(end 392.898122 -248.8565)
		(width 0.0889)
		(layer "In13.Cu")
		(net "M_H_CPU0_SA_CB<5>")
	)
	(segment
		(start 393.996926 -248.94159)
		(end 395.334236 -248.94159)
		(width 0.0889)
		(layer "In13.Cu")
		(net "M_H_CPU0_SA_CB<5>")
	)
	(segment
		(start 395.768322 -249.00255)
		(end 396.721076 -249.00255)
		(width 0.14478)
		(layer "In13.Cu")
		(net "M_H_CPU0_SA_CB<5>")
	)
	(segment
		(start 383.497836 -248.856754)
		(end 383.506218 -248.86158)
		(width 0.0889)
		(layer "In13.Cu")
		(net "M_H_CPU0_SA_CB<5>")
	)
	(segment
		(start 417.612068 -242.814094)
		(end 421.476424 -242.814094)
		(width 0.14478)
		(layer "In13.Cu")
		(net "M_H_CPU0_SA_CB<5>")
	)
	(segment
		(start 387.257798 -248.856754)
		(end 387.26618 -248.86158)
		(width 0.0889)
		(layer "In13.Cu")
		(net "M_H_CPU0_SA_CB<5>")
	)
	(segment
		(start 421.90543 -242.385088)
		(end 424.012106 -242.385088)
		(width 0.14478)
		(layer "In13.Cu")
		(net "M_H_CPU0_SA_CB<5>")
	)
	(segment
		(start 395.395196 -249.00255)
		(end 395.768322 -249.00255)
		(width 0.0889)
		(layer "In13.Cu")
		(net "M_H_CPU0_SA_CB<5>")
	)
	(segment
		(start 382.590802 -248.799604)
		(end 382.613154 -248.882916)
		(width 0.0889)
		(layer "In13.Cu")
		(net "M_H_CPU0_SA_CB<5>")
	)
	(segment
		(start 396.956534 -248.767092)
		(end 407.209498 -248.767092)
		(width 0.14478)
		(layer "In13.Cu")
		(net "M_H_CPU0_SA_CB<5>")
	)
	(segment
		(start 416.765994 -243.660168)
		(end 417.612068 -242.814094)
		(width 0.14478)
		(layer "In13.Cu")
		(net "M_H_CPU0_SA_CB<5>")
	)
	(segment
		(start 391.01776 -248.856754)
		(end 391.026142 -248.86158)
		(width 0.0889)
		(layer "In13.Cu")
		(net "M_H_CPU0_SA_CB<5>")
	)
	(segment
		(start 396.721076 -249.00255)
		(end 396.956534 -248.767092)
		(width 0.14478)
		(layer "In13.Cu")
		(net "M_H_CPU0_SA_CB<5>")
	)
	(segment
		(start 412.530544 -244.510052)
		(end 413.380428 -243.660168)
		(width 0.14478)
		(layer "In13.Cu")
		(net "M_H_CPU0_SA_CB<5>")
	)
	(segment
		(start 407.209498 -248.767092)
		(end 411.466538 -244.510052)
		(width 0.14478)
		(layer "In13.Cu")
		(net "M_H_CPU0_SA_CB<5>")
	)
	(arc
		(start 388.206234 -248.86158)
		(mid 388.389742 -248.907074)
		(end 388.571994 -248.856754)
		(width 0.0889)
		(layer "In13.Cu")
		(net "M_H_CPU0_SA_CB<5>")
	)
	(arc
		(start 387.26618 -248.86158)
		(mid 387.449688 -248.907074)
		(end 387.63194 -248.856754)
		(width 0.0889)
		(layer "In13.Cu")
		(net "M_H_CPU0_SA_CB<5>")
	)
	(arc
		(start 393.272264 -248.856754)
		(mid 393.54697 -248.78039)
		(end 393.823952 -248.848118)
		(width 0.0889)
		(layer "In13.Cu")
		(net "M_H_CPU0_SA_CB<5>")
	)
	(arc
		(start 390.077706 -248.856754)
		(mid 390.259957 -248.907104)
		(end 390.443466 -248.86158)
		(width 0.0889)
		(layer "In13.Cu")
		(net "M_H_CPU0_SA_CB<5>")
	)
	(arc
		(start 389.511794 -248.856754)
		(mid 389.79475 -248.780577)
		(end 390.077706 -248.856754)
		(width 0.0889)
		(layer "In13.Cu")
		(net "M_H_CPU0_SA_CB<5>")
	)
	(arc
		(start 385.37769 -248.856754)
		(mid 385.559941 -248.907104)
		(end 385.74345 -248.86158)
		(width 0.0889)
		(layer "In13.Cu")
		(net "M_H_CPU0_SA_CB<5>")
	)
	(arc
		(start 387.63194 -248.856754)
		(mid 387.914896 -248.780577)
		(end 388.197852 -248.856754)
		(width 0.0889)
		(layer "In13.Cu")
		(net "M_H_CPU0_SA_CB<5>")
	)
	(arc
		(start 385.751832 -248.856754)
		(mid 386.034788 -248.780577)
		(end 386.317744 -248.856754)
		(width 0.0889)
		(layer "In13.Cu")
		(net "M_H_CPU0_SA_CB<5>")
	)
	(arc
		(start 383.871978 -248.856754)
		(mid 384.154934 -248.780577)
		(end 384.43789 -248.856754)
		(width 0.0889)
		(layer "In13.Cu")
		(net "M_H_CPU0_SA_CB<5>")
	)
	(arc
		(start 384.43789 -248.856754)
		(mid 384.624834 -248.907009)
		(end 384.811778 -248.856754)
		(width 0.0889)
		(layer "In13.Cu")
		(net "M_H_CPU0_SA_CB<5>")
	)
	(arc
		(start 386.317744 -248.856754)
		(mid 386.499995 -248.907104)
		(end 386.683504 -248.86158)
		(width 0.0889)
		(layer "In13.Cu")
		(net "M_H_CPU0_SA_CB<5>")
	)
	(arc
		(start 390.451848 -248.856754)
		(mid 390.734804 -248.780577)
		(end 391.01776 -248.856754)
		(width 0.0889)
		(layer "In13.Cu")
		(net "M_H_CPU0_SA_CB<5>")
	)
	(arc
		(start 386.691886 -248.856754)
		(mid 386.974842 -248.780577)
		(end 387.257798 -248.856754)
		(width 0.0889)
		(layer "In13.Cu")
		(net "M_H_CPU0_SA_CB<5>")
	)
	(arc
		(start 391.406634 -248.848118)
		(mid 391.683617 -248.780314)
		(end 391.958322 -248.856754)
		(width 0.0889)
		(layer "In13.Cu")
		(net "M_H_CPU0_SA_CB<5>")
	)
	(arc
		(start 384.811778 -248.856754)
		(mid 385.094734 -248.780577)
		(end 385.37769 -248.856754)
		(width 0.0889)
		(layer "In13.Cu")
		(net "M_H_CPU0_SA_CB<5>")
	)
	(arc
		(start 391.958322 -248.856754)
		(mid 392.13878 -248.907198)
		(end 392.321034 -248.863612)
		(width 0.0889)
		(layer "In13.Cu")
		(net "M_H_CPU0_SA_CB<5>")
	)
	(arc
		(start 382.613154 -248.882916)
		(mid 382.775486 -248.905734)
		(end 382.931924 -248.856754)
		(width 0.0889)
		(layer "In13.Cu")
		(net "M_H_CPU0_SA_CB<5>")
	)
	(arc
		(start 383.506218 -248.86158)
		(mid 383.689726 -248.907074)
		(end 383.871978 -248.856754)
		(width 0.0889)
		(layer "In13.Cu")
		(net "M_H_CPU0_SA_CB<5>")
	)
	(arc
		(start 392.91641 -248.866914)
		(mid 393.095639 -248.907067)
		(end 393.272264 -248.856754)
		(width 0.0889)
		(layer "In13.Cu")
		(net "M_H_CPU0_SA_CB<5>")
	)
	(arc
		(start 392.332718 -248.856754)
		(mid 392.612146 -248.780588)
		(end 392.892534 -248.853198)
		(width 0.0889)
		(layer "In13.Cu")
		(net "M_H_CPU0_SA_CB<5>")
	)
	(arc
		(start 388.571994 -248.856754)
		(mid 388.85495 -248.780577)
		(end 389.137906 -248.856754)
		(width 0.0889)
		(layer "In13.Cu")
		(net "M_H_CPU0_SA_CB<5>")
	)
	(arc
		(start 389.137906 -248.856754)
		(mid 389.32485 -248.907009)
		(end 389.511794 -248.856754)
		(width 0.0889)
		(layer "In13.Cu")
		(net "M_H_CPU0_SA_CB<5>")
	)
	(arc
		(start 391.026142 -248.86158)
		(mid 391.20965 -248.907074)
		(end 391.391902 -248.856754)
		(width 0.0889)
		(layer "In13.Cu")
		(net "M_H_CPU0_SA_CB<5>")
	)
	(arc
		(start 382.931924 -248.856754)
		(mid 383.21488 -248.780577)
		(end 383.497836 -248.856754)
		(width 0.0889)
		(layer "In13.Cu")
		(net "M_H_CPU0_SA_CB<5>")
	)
	(segment
		(start 383.688082 -247.990106)
		(end 384.154934 -247.724168)
		(width 0.10668)
		(layer "F.Cu")
		(net "M_H_CPU0_SA_CB<4>")
	)
	(segment
		(start 413.784796 -241.545364)
		(end 413.784796 -241.464592)
		(width 0.14478)
		(layer "In13.Cu")
		(net "M_H_CPU0_SA_CB<4>")
	)
	(segment
		(start 415.090356 -241.18316)
		(end 415.516822 -240.756694)
		(width 0.14478)
		(layer "In13.Cu")
		(net "M_H_CPU0_SA_CB<4>")
	)
	(segment
		(start 384.154934 -247.724168)
		(end 384.000756 -247.989598)
		(width 0.0889)
		(layer "In13.Cu")
		(net "M_H_CPU0_SA_CB<4>")
	)
	(segment
		(start 415.090356 -241.545364)
		(end 415.090356 -241.18316)
		(width 0.14478)
		(layer "In13.Cu")
		(net "M_H_CPU0_SA_CB<4>")
	)
	(segment
		(start 389.607806 -248.046748)
		(end 389.616188 -248.051574)
		(width 0.0889)
		(layer "In13.Cu")
		(net "M_H_CPU0_SA_CB<4>")
	)
	(segment
		(start 394.250926 -248.35358)
		(end 394.906246 -248.35358)
		(width 0.0889)
		(layer "In13.Cu")
		(net "M_H_CPU0_SA_CB<4>")
	)
	(segment
		(start 414.945576 -241.690144)
		(end 415.090356 -241.545364)
		(width 0.14478)
		(layer "In13.Cu")
		(net "M_H_CPU0_SA_CB<4>")
	)
	(segment
		(start 406.298908 -247.715786)
		(end 412.694882 -241.319812)
		(width 0.14478)
		(layer "In13.Cu")
		(net "M_H_CPU0_SA_CB<4>")
	)
	(segment
		(start 393.368276 -248.046748)
		(end 393.368022 -248.046748)
		(width 0.0889)
		(layer "In13.Cu")
		(net "M_H_CPU0_SA_CB<4>")
	)
	(segment
		(start 395.733778 -248.08307)
		(end 396.327376 -248.08307)
		(width 0.14478)
		(layer "In13.Cu")
		(net "M_H_CPU0_SA_CB<4>")
	)
	(segment
		(start 415.516822 -240.756694)
		(end 420.304468 -240.756694)
		(width 0.14478)
		(layer "In13.Cu")
		(net "M_H_CPU0_SA_CB<4>")
	)
	(segment
		(start 413.929576 -241.319812)
		(end 414.292796 -241.319812)
		(width 0.14478)
		(layer "In13.Cu")
		(net "M_H_CPU0_SA_CB<4>")
	)
	(segment
		(start 384.90779 -248.046748)
		(end 384.916172 -248.051574)
		(width 0.0889)
		(layer "In13.Cu")
		(net "M_H_CPU0_SA_CB<4>")
	)
	(segment
		(start 394.127736 -248.23039)
		(end 394.250926 -248.35358)
		(width 0.0889)
		(layer "In13.Cu")
		(net "M_H_CPU0_SA_CB<4>")
	)
	(segment
		(start 393.552172 -248.097548)
		(end 393.685014 -248.23039)
		(width 0.0889)
		(layer "In13.Cu")
		(net "M_H_CPU0_SA_CB<4>")
	)
	(segment
		(start 413.132016 -241.545364)
		(end 413.276796 -241.690144)
		(width 0.14478)
		(layer "In13.Cu")
		(net "M_H_CPU0_SA_CB<4>")
	)
	(segment
		(start 413.132016 -241.464592)
		(end 413.132016 -241.545364)
		(width 0.14478)
		(layer "In13.Cu")
		(net "M_H_CPU0_SA_CB<4>")
	)
	(segment
		(start 414.437576 -241.545364)
		(end 414.582356 -241.690144)
		(width 0.14478)
		(layer "In13.Cu")
		(net "M_H_CPU0_SA_CB<4>")
	)
	(segment
		(start 384.000756 -247.989598)
		(end 384.023108 -248.07291)
		(width 0.0889)
		(layer "In13.Cu")
		(net "M_H_CPU0_SA_CB<4>")
	)
	(segment
		(start 413.276796 -241.690144)
		(end 413.640016 -241.690144)
		(width 0.14478)
		(layer "In13.Cu")
		(net "M_H_CPU0_SA_CB<4>")
	)
	(segment
		(start 422.331896 -240.685066)
		(end 424.012106 -240.685066)
		(width 0.14478)
		(layer "In13.Cu")
		(net "M_H_CPU0_SA_CB<4>")
	)
	(segment
		(start 412.694882 -241.319812)
		(end 412.987236 -241.319812)
		(width 0.14478)
		(layer "In13.Cu")
		(net "M_H_CPU0_SA_CB<4>")
	)
	(segment
		(start 392.802364 -248.046494)
		(end 392.818112 -248.03735)
		(width 0.0889)
		(layer "In13.Cu")
		(net "M_H_CPU0_SA_CB<4>")
	)
	(segment
		(start 412.987236 -241.319812)
		(end 413.132016 -241.464592)
		(width 0.14478)
		(layer "In13.Cu")
		(net "M_H_CPU0_SA_CB<4>")
	)
	(segment
		(start 393.685014 -248.23039)
		(end 394.127736 -248.23039)
		(width 0.0889)
		(layer "In13.Cu")
		(net "M_H_CPU0_SA_CB<4>")
	)
	(segment
		(start 395.176756 -248.08307)
		(end 395.733778 -248.08307)
		(width 0.0889)
		(layer "In13.Cu")
		(net "M_H_CPU0_SA_CB<4>")
	)
	(segment
		(start 392.786108 -248.055892)
		(end 392.802364 -248.046494)
		(width 0.0889)
		(layer "In13.Cu")
		(net "M_H_CPU0_SA_CB<4>")
	)
	(segment
		(start 414.437576 -241.464592)
		(end 414.437576 -241.545364)
		(width 0.14478)
		(layer "In13.Cu")
		(net "M_H_CPU0_SA_CB<4>")
	)
	(segment
		(start 388.093458 -248.051574)
		(end 388.10184 -248.046748)
		(width 0.0889)
		(layer "In13.Cu")
		(net "M_H_CPU0_SA_CB<4>")
	)
	(segment
		(start 389.033512 -248.051574)
		(end 389.041894 -248.046748)
		(width 0.0889)
		(layer "In13.Cu")
		(net "M_H_CPU0_SA_CB<4>")
	)
	(segment
		(start 413.640016 -241.690144)
		(end 413.784796 -241.545364)
		(width 0.14478)
		(layer "In13.Cu")
		(net "M_H_CPU0_SA_CB<4>")
	)
	(segment
		(start 392.418062 -248.040652)
		(end 392.428476 -248.046748)
		(width 0.0889)
		(layer "In13.Cu")
		(net "M_H_CPU0_SA_CB<4>")
	)
	(segment
		(start 420.825168 -241.277394)
		(end 421.739568 -241.277394)
		(width 0.14478)
		(layer "In13.Cu")
		(net "M_H_CPU0_SA_CB<4>")
	)
	(segment
		(start 394.906246 -248.35358)
		(end 395.176756 -248.08307)
		(width 0.0889)
		(layer "In13.Cu")
		(net "M_H_CPU0_SA_CB<4>")
	)
	(segment
		(start 413.784796 -241.464592)
		(end 413.929576 -241.319812)
		(width 0.14478)
		(layer "In13.Cu")
		(net "M_H_CPU0_SA_CB<4>")
	)
	(segment
		(start 421.739568 -241.277394)
		(end 422.331896 -240.685066)
		(width 0.14478)
		(layer "In13.Cu")
		(net "M_H_CPU0_SA_CB<4>")
	)
	(segment
		(start 414.582356 -241.690144)
		(end 414.945576 -241.690144)
		(width 0.14478)
		(layer "In13.Cu")
		(net "M_H_CPU0_SA_CB<4>")
	)
	(segment
		(start 396.327376 -248.08307)
		(end 396.69466 -247.715786)
		(width 0.14478)
		(layer "In13.Cu")
		(net "M_H_CPU0_SA_CB<4>")
	)
	(segment
		(start 385.847844 -248.046748)
		(end 385.856226 -248.051574)
		(width 0.0889)
		(layer "In13.Cu")
		(net "M_H_CPU0_SA_CB<4>")
	)
	(segment
		(start 420.304468 -240.756694)
		(end 420.825168 -241.277394)
		(width 0.14478)
		(layer "In13.Cu")
		(net "M_H_CPU0_SA_CB<4>")
	)
	(segment
		(start 391.48766 -248.046748)
		(end 391.496042 -248.051574)
		(width 0.0889)
		(layer "In13.Cu")
		(net "M_H_CPU0_SA_CB<4>")
	)
	(segment
		(start 414.292796 -241.319812)
		(end 414.437576 -241.464592)
		(width 0.14478)
		(layer "In13.Cu")
		(net "M_H_CPU0_SA_CB<4>")
	)
	(segment
		(start 396.69466 -247.715786)
		(end 406.298908 -247.715786)
		(width 0.14478)
		(layer "In13.Cu")
		(net "M_H_CPU0_SA_CB<4>")
	)
	(segment
		(start 384.333496 -248.051574)
		(end 384.341878 -248.046748)
		(width 0.0889)
		(layer "In13.Cu")
		(net "M_H_CPU0_SA_CB<4>")
	)
	(arc
		(start 386.221986 -248.046748)
		(mid 386.504942 -247.970571)
		(end 386.787898 -248.046748)
		(width 0.0889)
		(layer "In13.Cu")
		(net "M_H_CPU0_SA_CB<4>")
	)
	(arc
		(start 391.86231 -248.046748)
		(mid 392.139377 -247.970477)
		(end 392.418062 -248.040652)
		(width 0.0889)
		(layer "In13.Cu")
		(net "M_H_CPU0_SA_CB<4>")
	)
	(arc
		(start 389.616188 -248.051574)
		(mid 389.799696 -248.097068)
		(end 389.981948 -248.046748)
		(width 0.0889)
		(layer "In13.Cu")
		(net "M_H_CPU0_SA_CB<4>")
	)
	(arc
		(start 388.10184 -248.046748)
		(mid 388.384796 -247.970571)
		(end 388.667752 -248.046748)
		(width 0.0889)
		(layer "In13.Cu")
		(net "M_H_CPU0_SA_CB<4>")
	)
	(arc
		(start 386.787898 -248.046748)
		(mid 386.974842 -248.097003)
		(end 387.161786 -248.046748)
		(width 0.0889)
		(layer "In13.Cu")
		(net "M_H_CPU0_SA_CB<4>")
	)
	(arc
		(start 385.281932 -248.046748)
		(mid 385.564888 -247.970571)
		(end 385.847844 -248.046748)
		(width 0.0889)
		(layer "In13.Cu")
		(net "M_H_CPU0_SA_CB<4>")
	)
	(arc
		(start 389.041894 -248.046748)
		(mid 389.32485 -247.970571)
		(end 389.607806 -248.046748)
		(width 0.0889)
		(layer "In13.Cu")
		(net "M_H_CPU0_SA_CB<4>")
	)
	(arc
		(start 384.341878 -248.046748)
		(mid 384.624834 -247.970571)
		(end 384.90779 -248.046748)
		(width 0.0889)
		(layer "In13.Cu")
		(net "M_H_CPU0_SA_CB<4>")
	)
	(arc
		(start 389.981948 -248.046748)
		(mid 390.264904 -247.970571)
		(end 390.54786 -248.046748)
		(width 0.0889)
		(layer "In13.Cu")
		(net "M_H_CPU0_SA_CB<4>")
	)
	(arc
		(start 388.667752 -248.046748)
		(mid 388.850003 -248.097098)
		(end 389.033512 -248.051574)
		(width 0.0889)
		(layer "In13.Cu")
		(net "M_H_CPU0_SA_CB<4>")
	)
	(arc
		(start 392.818112 -248.03735)
		(mid 393.094421 -247.970374)
		(end 393.368276 -248.046748)
		(width 0.0889)
		(layer "In13.Cu")
		(net "M_H_CPU0_SA_CB<4>")
	)
	(arc
		(start 384.916172 -248.051574)
		(mid 385.09968 -248.097068)
		(end 385.281932 -248.046748)
		(width 0.0889)
		(layer "In13.Cu")
		(net "M_H_CPU0_SA_CB<4>")
	)
	(arc
		(start 384.023108 -248.07291)
		(mid 384.180618 -248.096108)
		(end 384.333496 -248.051574)
		(width 0.0889)
		(layer "In13.Cu")
		(net "M_H_CPU0_SA_CB<4>")
	)
	(arc
		(start 390.921748 -248.046748)
		(mid 391.204704 -247.970571)
		(end 391.48766 -248.046748)
		(width 0.0889)
		(layer "In13.Cu")
		(net "M_H_CPU0_SA_CB<4>")
	)
	(arc
		(start 392.428476 -248.046748)
		(mid 392.606126 -248.097008)
		(end 392.786108 -248.055892)
		(width 0.0889)
		(layer "In13.Cu")
		(net "M_H_CPU0_SA_CB<4>")
	)
	(arc
		(start 385.856226 -248.051574)
		(mid 386.039734 -248.097068)
		(end 386.221986 -248.046748)
		(width 0.0889)
		(layer "In13.Cu")
		(net "M_H_CPU0_SA_CB<4>")
	)
	(arc
		(start 387.161786 -248.046748)
		(mid 387.444742 -247.970571)
		(end 387.727698 -248.046748)
		(width 0.0889)
		(layer "In13.Cu")
		(net "M_H_CPU0_SA_CB<4>")
	)
	(arc
		(start 391.496042 -248.051574)
		(mid 391.679804 -248.09719)
		(end 391.86231 -248.046748)
		(width 0.0889)
		(layer "In13.Cu")
		(net "M_H_CPU0_SA_CB<4>")
	)
	(arc
		(start 390.54786 -248.046748)
		(mid 390.734804 -248.097003)
		(end 390.921748 -248.046748)
		(width 0.0889)
		(layer "In13.Cu")
		(net "M_H_CPU0_SA_CB<4>")
	)
	(arc
		(start 393.368022 -248.046748)
		(mid 393.456797 -248.084097)
		(end 393.552172 -248.097548)
		(width 0.0889)
		(layer "In13.Cu")
		(net "M_H_CPU0_SA_CB<4>")
	)
	(arc
		(start 387.727698 -248.046748)
		(mid 387.909949 -248.097098)
		(end 388.093458 -248.051574)
		(width 0.0889)
		(layer "In13.Cu")
		(net "M_H_CPU0_SA_CB<4>")
	)
	(segment
		(start 381.807974 -246.370094)
		(end 382.274826 -246.104156)
		(width 0.10668)
		(layer "F.Cu")
		(net "M_H_CPU0_SA_CB<3>")
	)
	(segment
		(start 388.093458 -245.77675)
		(end 388.10184 -245.781576)
		(width 0.0889)
		(layer "In13.Cu")
		(net "M_H_CPU0_SA_CB<3>")
	)
	(segment
		(start 395.87805 -245.371366)
		(end 404.052532 -245.371366)
		(width 0.14478)
		(layer "In13.Cu")
		(net "M_H_CPU0_SA_CB<3>")
	)
	(segment
		(start 411.697424 -238.547402)
		(end 411.697424 -238.342678)
		(width 0.14478)
		(layer "In13.Cu")
		(net "M_H_CPU0_SA_CB<3>")
	)
	(segment
		(start 419.912038 -237.330742)
		(end 419.912038 -237.285022)
		(width 0.14478)
		(layer "In13.Cu")
		(net "M_H_CPU0_SA_CB<3>")
	)
	(segment
		(start 406.521412 -243.294154)
		(end 406.715468 -243.100098)
		(width 0.14478)
		(layer "In13.Cu")
		(net "M_H_CPU0_SA_CB<3>")
	)
	(segment
		(start 405.155908 -244.659658)
		(end 405.155908 -244.26799)
		(width 0.14478)
		(layer "In13.Cu")
		(net "M_H_CPU0_SA_CB<3>")
	)
	(segment
		(start 410.028644 -239.395254)
		(end 410.420312 -239.395254)
		(width 0.14478)
		(layer "In13.Cu")
		(net "M_H_CPU0_SA_CB<3>")
	)
	(segment
		(start 416.798252 -236.86008)
		(end 417.074858 -237.136686)
		(width 0.14478)
		(layer "In13.Cu")
		(net "M_H_CPU0_SA_CB<3>")
	)
	(segment
		(start 382.274826 -246.104156)
		(end 382.42875 -245.838726)
		(width 0.0889)
		(layer "In13.Cu")
		(net "M_H_CPU0_SA_CB<3>")
	)
	(segment
		(start 409.054808 -240.760758)
		(end 409.054808 -240.36909)
		(width 0.14478)
		(layer "In13.Cu")
		(net "M_H_CPU0_SA_CB<3>")
	)
	(segment
		(start 411.101794 -238.526828)
		(end 411.307534 -238.732568)
		(width 0.14478)
		(layer "In13.Cu")
		(net "M_H_CPU0_SA_CB<3>")
	)
	(segment
		(start 383.393442 -245.77675)
		(end 383.401824 -245.781576)
		(width 0.0889)
		(layer "In13.Cu")
		(net "M_H_CPU0_SA_CB<3>")
	)
	(segment
		(start 417.451032 -237.136686)
		(end 417.727638 -236.86008)
		(width 0.14478)
		(layer "In13.Cu")
		(net "M_H_CPU0_SA_CB<3>")
	)
	(segment
		(start 394.88364 -245.98757)
		(end 395.499844 -245.371366)
		(width 0.0889)
		(layer "In13.Cu")
		(net "M_H_CPU0_SA_CB<3>")
	)
	(segment
		(start 382.42875 -245.838726)
		(end 382.524762 -245.813326)
		(width 0.0889)
		(layer "In13.Cu")
		(net "M_H_CPU0_SA_CB<3>")
	)
	(segment
		(start 407.689304 -241.734594)
		(end 408.080972 -241.734594)
		(width 0.14478)
		(layer "In13.Cu")
		(net "M_H_CPU0_SA_CB<3>")
	)
	(segment
		(start 405.349964 -244.073934)
		(end 405.741632 -244.073934)
		(width 0.14478)
		(layer "In13.Cu")
		(net "M_H_CPU0_SA_CB<3>")
	)
	(segment
		(start 411.491684 -238.136938)
		(end 411.491684 -237.932214)
		(width 0.14478)
		(layer "In13.Cu")
		(net "M_H_CPU0_SA_CB<3>")
	)
	(segment
		(start 418.980112 -237.700312)
		(end 419.542468 -237.700312)
		(width 0.14478)
		(layer "In13.Cu")
		(net "M_H_CPU0_SA_CB<3>")
	)
	(segment
		(start 406.909524 -242.514374)
		(end 407.301192 -242.514374)
		(width 0.14478)
		(layer "In13.Cu")
		(net "M_H_CPU0_SA_CB<3>")
	)
	(segment
		(start 406.715468 -242.70843)
		(end 406.909524 -242.514374)
		(width 0.14478)
		(layer "In13.Cu")
		(net "M_H_CPU0_SA_CB<3>")
	)
	(segment
		(start 411.512258 -238.732568)
		(end 411.697424 -238.547402)
		(width 0.14478)
		(layer "In13.Cu")
		(net "M_H_CPU0_SA_CB<3>")
	)
	(segment
		(start 410.420312 -239.395254)
		(end 410.614368 -239.201198)
		(width 0.14478)
		(layer "In13.Cu")
		(net "M_H_CPU0_SA_CB<3>")
	)
	(segment
		(start 385.847844 -245.781576)
		(end 385.856226 -245.77675)
		(width 0.0889)
		(layer "In13.Cu")
		(net "M_H_CPU0_SA_CB<3>")
	)
	(segment
		(start 416.145472 -237.136686)
		(end 416.422078 -236.86008)
		(width 0.14478)
		(layer "In13.Cu")
		(net "M_H_CPU0_SA_CB<3>")
	)
	(segment
		(start 393.734544 -245.77675)
		(end 393.945364 -245.98757)
		(width 0.0889)
		(layer "In13.Cu")
		(net "M_H_CPU0_SA_CB<3>")
	)
	(segment
		(start 415.769298 -237.136686)
		(end 416.145472 -237.136686)
		(width 0.14478)
		(layer "In13.Cu")
		(net "M_H_CPU0_SA_CB<3>")
	)
	(segment
		(start 395.499844 -245.371366)
		(end 395.87805 -245.371366)
		(width 0.0889)
		(layer "In13.Cu")
		(net "M_H_CPU0_SA_CB<3>")
	)
	(segment
		(start 393.945364 -245.98757)
		(end 394.88364 -245.98757)
		(width 0.0889)
		(layer "In13.Cu")
		(net "M_H_CPU0_SA_CB<3>")
	)
	(segment
		(start 407.301192 -242.514374)
		(end 407.495248 -242.320318)
		(width 0.14478)
		(layer "In13.Cu")
		(net "M_H_CPU0_SA_CB<3>")
	)
	(segment
		(start 404.052532 -245.371366)
		(end 404.570184 -244.853714)
		(width 0.14478)
		(layer "In13.Cu")
		(net "M_H_CPU0_SA_CB<3>")
	)
	(segment
		(start 417.727638 -236.86008)
		(end 418.13988 -236.86008)
		(width 0.14478)
		(layer "In13.Cu")
		(net "M_H_CPU0_SA_CB<3>")
	)
	(segment
		(start 409.834588 -239.58931)
		(end 410.028644 -239.395254)
		(width 0.14478)
		(layer "In13.Cu")
		(net "M_H_CPU0_SA_CB<3>")
	)
	(segment
		(start 410.89707 -238.526828)
		(end 411.101794 -238.526828)
		(width 0.14478)
		(layer "In13.Cu")
		(net "M_H_CPU0_SA_CB<3>")
	)
	(segment
		(start 406.715468 -243.100098)
		(end 406.715468 -242.70843)
		(width 0.14478)
		(layer "In13.Cu")
		(net "M_H_CPU0_SA_CB<3>")
	)
	(segment
		(start 409.248864 -240.175034)
		(end 409.640532 -240.175034)
		(width 0.14478)
		(layer "In13.Cu")
		(net "M_H_CPU0_SA_CB<3>")
	)
	(segment
		(start 411.697424 -238.342678)
		(end 411.491684 -238.136938)
		(width 0.14478)
		(layer "In13.Cu")
		(net "M_H_CPU0_SA_CB<3>")
	)
	(segment
		(start 392.413998 -245.790212)
		(end 392.42873 -245.781576)
		(width 0.0889)
		(layer "In13.Cu")
		(net "M_H_CPU0_SA_CB<3>")
	)
	(segment
		(start 391.48766 -245.781576)
		(end 391.496042 -245.77675)
		(width 0.0889)
		(layer "In13.Cu")
		(net "M_H_CPU0_SA_CB<3>")
	)
	(segment
		(start 409.640532 -240.175034)
		(end 409.834588 -239.980978)
		(width 0.14478)
		(layer "In13.Cu")
		(net "M_H_CPU0_SA_CB<3>")
	)
	(segment
		(start 410.614368 -239.201198)
		(end 410.614368 -238.80953)
		(width 0.14478)
		(layer "In13.Cu")
		(net "M_H_CPU0_SA_CB<3>")
	)
	(segment
		(start 411.491684 -237.932214)
		(end 411.71368 -237.710218)
		(width 0.14478)
		(layer "In13.Cu")
		(net "M_H_CPU0_SA_CB<3>")
	)
	(segment
		(start 416.422078 -236.86008)
		(end 416.798252 -236.86008)
		(width 0.14478)
		(layer "In13.Cu")
		(net "M_H_CPU0_SA_CB<3>")
	)
	(segment
		(start 406.129744 -243.294154)
		(end 406.521412 -243.294154)
		(width 0.14478)
		(layer "In13.Cu")
		(net "M_H_CPU0_SA_CB<3>")
	)
	(segment
		(start 419.542468 -237.700312)
		(end 419.912038 -237.330742)
		(width 0.14478)
		(layer "In13.Cu")
		(net "M_H_CPU0_SA_CB<3>")
	)
	(segment
		(start 384.333496 -245.77675)
		(end 384.341878 -245.781576)
		(width 0.0889)
		(layer "In13.Cu")
		(net "M_H_CPU0_SA_CB<3>")
	)
	(segment
		(start 407.495248 -242.320318)
		(end 407.495248 -241.92865)
		(width 0.14478)
		(layer "In13.Cu")
		(net "M_H_CPU0_SA_CB<3>")
	)
	(segment
		(start 414.005776 -237.710218)
		(end 414.855914 -236.86008)
		(width 0.14478)
		(layer "In13.Cu")
		(net "M_H_CPU0_SA_CB<3>")
	)
	(segment
		(start 410.614368 -238.80953)
		(end 410.89707 -238.526828)
		(width 0.14478)
		(layer "In13.Cu")
		(net "M_H_CPU0_SA_CB<3>")
	)
	(segment
		(start 409.834588 -239.980978)
		(end 409.834588 -239.58931)
		(width 0.14478)
		(layer "In13.Cu")
		(net "M_H_CPU0_SA_CB<3>")
	)
	(segment
		(start 409.054808 -240.36909)
		(end 409.248864 -240.175034)
		(width 0.14478)
		(layer "In13.Cu")
		(net "M_H_CPU0_SA_CB<3>")
	)
	(segment
		(start 411.71368 -237.710218)
		(end 414.005776 -237.710218)
		(width 0.14478)
		(layer "In13.Cu")
		(net "M_H_CPU0_SA_CB<3>")
	)
	(segment
		(start 408.275028 -241.540538)
		(end 408.275028 -241.14887)
		(width 0.14478)
		(layer "In13.Cu")
		(net "M_H_CPU0_SA_CB<3>")
	)
	(segment
		(start 408.275028 -241.14887)
		(end 408.469084 -240.954814)
		(width 0.14478)
		(layer "In13.Cu")
		(net "M_H_CPU0_SA_CB<3>")
	)
	(segment
		(start 405.155908 -244.26799)
		(end 405.349964 -244.073934)
		(width 0.14478)
		(layer "In13.Cu")
		(net "M_H_CPU0_SA_CB<3>")
	)
	(segment
		(start 404.961852 -244.853714)
		(end 405.155908 -244.659658)
		(width 0.14478)
		(layer "In13.Cu")
		(net "M_H_CPU0_SA_CB<3>")
	)
	(segment
		(start 408.860752 -240.954814)
		(end 409.054808 -240.760758)
		(width 0.14478)
		(layer "In13.Cu")
		(net "M_H_CPU0_SA_CB<3>")
	)
	(segment
		(start 404.570184 -244.853714)
		(end 404.961852 -244.853714)
		(width 0.14478)
		(layer "In13.Cu")
		(net "M_H_CPU0_SA_CB<3>")
	)
	(segment
		(start 389.607806 -245.781576)
		(end 389.616188 -245.77675)
		(width 0.0889)
		(layer "In13.Cu")
		(net "M_H_CPU0_SA_CB<3>")
	)
	(segment
		(start 384.90779 -245.781576)
		(end 384.916172 -245.77675)
		(width 0.0889)
		(layer "In13.Cu")
		(net "M_H_CPU0_SA_CB<3>")
	)
	(segment
		(start 418.13988 -236.86008)
		(end 418.980112 -237.700312)
		(width 0.14478)
		(layer "In13.Cu")
		(net "M_H_CPU0_SA_CB<3>")
	)
	(segment
		(start 407.495248 -241.92865)
		(end 407.689304 -241.734594)
		(width 0.14478)
		(layer "In13.Cu")
		(net "M_H_CPU0_SA_CB<3>")
	)
	(segment
		(start 408.469084 -240.954814)
		(end 408.860752 -240.954814)
		(width 0.14478)
		(layer "In13.Cu")
		(net "M_H_CPU0_SA_CB<3>")
	)
	(segment
		(start 405.935688 -243.48821)
		(end 406.129744 -243.294154)
		(width 0.14478)
		(layer "In13.Cu")
		(net "M_H_CPU0_SA_CB<3>")
	)
	(segment
		(start 414.855914 -236.86008)
		(end 415.492692 -236.86008)
		(width 0.14478)
		(layer "In13.Cu")
		(net "M_H_CPU0_SA_CB<3>")
	)
	(segment
		(start 415.492692 -236.86008)
		(end 415.769298 -237.136686)
		(width 0.14478)
		(layer "In13.Cu")
		(net "M_H_CPU0_SA_CB<3>")
	)
	(segment
		(start 411.307534 -238.732568)
		(end 411.512258 -238.732568)
		(width 0.14478)
		(layer "In13.Cu")
		(net "M_H_CPU0_SA_CB<3>")
	)
	(segment
		(start 389.033512 -245.77675)
		(end 389.041894 -245.781576)
		(width 0.0889)
		(layer "In13.Cu")
		(net "M_H_CPU0_SA_CB<3>")
	)
	(segment
		(start 405.741632 -244.073934)
		(end 405.935688 -243.879878)
		(width 0.14478)
		(layer "In13.Cu")
		(net "M_H_CPU0_SA_CB<3>")
	)
	(segment
		(start 405.935688 -243.879878)
		(end 405.935688 -243.48821)
		(width 0.14478)
		(layer "In13.Cu")
		(net "M_H_CPU0_SA_CB<3>")
	)
	(segment
		(start 392.788648 -245.773956)
		(end 392.802364 -245.78183)
		(width 0.0889)
		(layer "In13.Cu")
		(net "M_H_CPU0_SA_CB<3>")
	)
	(segment
		(start 408.080972 -241.734594)
		(end 408.275028 -241.540538)
		(width 0.14478)
		(layer "In13.Cu")
		(net "M_H_CPU0_SA_CB<3>")
	)
	(segment
		(start 392.802364 -245.78183)
		(end 392.818112 -245.790974)
		(width 0.0889)
		(layer "In13.Cu")
		(net "M_H_CPU0_SA_CB<3>")
	)
	(segment
		(start 417.074858 -237.136686)
		(end 417.451032 -237.136686)
		(width 0.14478)
		(layer "In13.Cu")
		(net "M_H_CPU0_SA_CB<3>")
	)
	(arc
		(start 393.368276 -245.781576)
		(mid 393.550781 -245.731099)
		(end 393.734544 -245.77675)
		(width 0.0889)
		(layer "In13.Cu")
		(net "M_H_CPU0_SA_CB<3>")
	)
	(arc
		(start 386.221986 -245.781576)
		(mid 386.504942 -245.857753)
		(end 386.787898 -245.781576)
		(width 0.0889)
		(layer "In13.Cu")
		(net "M_H_CPU0_SA_CB<3>")
	)
	(arc
		(start 392.818112 -245.790974)
		(mid 393.094421 -245.85795)
		(end 393.368276 -245.781576)
		(width 0.0889)
		(layer "In13.Cu")
		(net "M_H_CPU0_SA_CB<3>")
	)
	(arc
		(start 391.86231 -245.781576)
		(mid 392.137016 -245.85794)
		(end 392.413998 -245.790212)
		(width 0.0889)
		(layer "In13.Cu")
		(net "M_H_CPU0_SA_CB<3>")
	)
	(arc
		(start 386.787898 -245.781576)
		(mid 386.974842 -245.731321)
		(end 387.161786 -245.781576)
		(width 0.0889)
		(layer "In13.Cu")
		(net "M_H_CPU0_SA_CB<3>")
	)
	(arc
		(start 385.856226 -245.77675)
		(mid 386.039734 -245.731256)
		(end 386.221986 -245.781576)
		(width 0.0889)
		(layer "In13.Cu")
		(net "M_H_CPU0_SA_CB<3>")
	)
	(arc
		(start 382.524762 -245.813326)
		(mid 382.77997 -245.856803)
		(end 383.027682 -245.781576)
		(width 0.0889)
		(layer "In13.Cu")
		(net "M_H_CPU0_SA_CB<3>")
	)
	(arc
		(start 387.727698 -245.781576)
		(mid 387.909949 -245.731226)
		(end 388.093458 -245.77675)
		(width 0.0889)
		(layer "In13.Cu")
		(net "M_H_CPU0_SA_CB<3>")
	)
	(arc
		(start 391.496042 -245.77675)
		(mid 391.679804 -245.731134)
		(end 391.86231 -245.781576)
		(width 0.0889)
		(layer "In13.Cu")
		(net "M_H_CPU0_SA_CB<3>")
	)
	(arc
		(start 389.041894 -245.781576)
		(mid 389.32485 -245.857753)
		(end 389.607806 -245.781576)
		(width 0.0889)
		(layer "In13.Cu")
		(net "M_H_CPU0_SA_CB<3>")
	)
	(arc
		(start 390.921748 -245.781576)
		(mid 391.204704 -245.857753)
		(end 391.48766 -245.781576)
		(width 0.0889)
		(layer "In13.Cu")
		(net "M_H_CPU0_SA_CB<3>")
	)
	(arc
		(start 387.161786 -245.781576)
		(mid 387.444742 -245.857753)
		(end 387.727698 -245.781576)
		(width 0.0889)
		(layer "In13.Cu")
		(net "M_H_CPU0_SA_CB<3>")
	)
	(arc
		(start 392.42873 -245.781576)
		(mid 392.607717 -245.731406)
		(end 392.788648 -245.773956)
		(width 0.0889)
		(layer "In13.Cu")
		(net "M_H_CPU0_SA_CB<3>")
	)
	(arc
		(start 389.616188 -245.77675)
		(mid 389.799696 -245.731256)
		(end 389.981948 -245.781576)
		(width 0.0889)
		(layer "In13.Cu")
		(net "M_H_CPU0_SA_CB<3>")
	)
	(arc
		(start 389.981948 -245.781576)
		(mid 390.264904 -245.857753)
		(end 390.54786 -245.781576)
		(width 0.0889)
		(layer "In13.Cu")
		(net "M_H_CPU0_SA_CB<3>")
	)
	(arc
		(start 383.967736 -245.781576)
		(mid 384.149987 -245.731226)
		(end 384.333496 -245.77675)
		(width 0.0889)
		(layer "In13.Cu")
		(net "M_H_CPU0_SA_CB<3>")
	)
	(arc
		(start 384.341878 -245.781576)
		(mid 384.624834 -245.857753)
		(end 384.90779 -245.781576)
		(width 0.0889)
		(layer "In13.Cu")
		(net "M_H_CPU0_SA_CB<3>")
	)
	(arc
		(start 383.401824 -245.781576)
		(mid 383.68478 -245.857753)
		(end 383.967736 -245.781576)
		(width 0.0889)
		(layer "In13.Cu")
		(net "M_H_CPU0_SA_CB<3>")
	)
	(arc
		(start 383.027682 -245.781576)
		(mid 383.209933 -245.731226)
		(end 383.393442 -245.77675)
		(width 0.0889)
		(layer "In13.Cu")
		(net "M_H_CPU0_SA_CB<3>")
	)
	(arc
		(start 388.667752 -245.781576)
		(mid 388.850003 -245.731226)
		(end 389.033512 -245.77675)
		(width 0.0889)
		(layer "In13.Cu")
		(net "M_H_CPU0_SA_CB<3>")
	)
	(arc
		(start 384.916172 -245.77675)
		(mid 385.09968 -245.731256)
		(end 385.281932 -245.781576)
		(width 0.0889)
		(layer "In13.Cu")
		(net "M_H_CPU0_SA_CB<3>")
	)
	(arc
		(start 388.10184 -245.781576)
		(mid 388.384796 -245.857753)
		(end 388.667752 -245.781576)
		(width 0.0889)
		(layer "In13.Cu")
		(net "M_H_CPU0_SA_CB<3>")
	)
	(arc
		(start 385.281932 -245.781576)
		(mid 385.564888 -245.857753)
		(end 385.847844 -245.781576)
		(width 0.0889)
		(layer "In13.Cu")
		(net "M_H_CPU0_SA_CB<3>")
	)
	(arc
		(start 390.54786 -245.781576)
		(mid 390.734804 -245.731321)
		(end 390.921748 -245.781576)
		(width 0.0889)
		(layer "In13.Cu")
		(net "M_H_CPU0_SA_CB<3>")
	)
	(segment
		(start 383.217928 -245.560088)
		(end 383.68478 -245.29415)
		(width 0.10668)
		(layer "F.Cu")
		(net "M_H_CPU0_SA_CB<2>")
	)
	(segment
		(start 415.089594 -235.160312)
		(end 414.230058 -236.019848)
		(width 0.14478)
		(layer "In13.Cu")
		(net "M_H_CPU0_SA_CB<2>")
	)
	(segment
		(start 405.0538 -242.661948)
		(end 404.849584 -242.661694)
		(width 0.14478)
		(layer "In13.Cu")
		(net "M_H_CPU0_SA_CB<2>")
	)
	(segment
		(start 406.223724 -241.492278)
		(end 406.339294 -241.607848)
		(width 0.14478)
		(layer "In13.Cu")
		(net "M_H_CPU0_SA_CB<2>")
	)
	(segment
		(start 407.713434 -240.438178)
		(end 407.50871 -240.438178)
		(width 0.14478)
		(layer "In13.Cu")
		(net "M_H_CPU0_SA_CB<2>")
	)
	(segment
		(start 407.898854 -240.048288)
		(end 407.8986 -240.253012)
		(width 0.14478)
		(layer "In13.Cu")
		(net "M_H_CPU0_SA_CB<2>")
	)
	(segment
		(start 404.069804 -243.441474)
		(end 403.884384 -243.626894)
		(width 0.14478)
		(layer "In13.Cu")
		(net "M_H_CPU0_SA_CB<2>")
	)
	(segment
		(start 404.594314 -243.557298)
		(end 404.38959 -243.557298)
		(width 0.14478)
		(layer "In13.Cu")
		(net "M_H_CPU0_SA_CB<2>")
	)
	(segment
		(start 393.954 -244.92077)
		(end 393.084812 -244.92077)
		(width 0.0889)
		(layer "In13.Cu")
		(net "M_H_CPU0_SA_CB<2>")
	)
	(segment
		(start 408.17292 -239.542828)
		(end 407.968704 -239.542574)
		(width 0.14478)
		(layer "In13.Cu")
		(net "M_H_CPU0_SA_CB<2>")
	)
	(segment
		(start 394.884148 -245.21033)
		(end 394.24356 -245.21033)
		(width 0.0889)
		(layer "In13.Cu")
		(net "M_H_CPU0_SA_CB<2>")
	)
	(segment
		(start 404.38959 -243.557298)
		(end 404.27402 -243.441728)
		(width 0.14478)
		(layer "In13.Cu")
		(net "M_H_CPU0_SA_CB<2>")
	)
	(segment
		(start 404.27402 -243.441728)
		(end 404.069804 -243.441474)
		(width 0.14478)
		(layer "In13.Cu")
		(net "M_H_CPU0_SA_CB<2>")
	)
	(segment
		(start 407.003504 -240.507774)
		(end 407.003504 -240.712498)
		(width 0.14478)
		(layer "In13.Cu")
		(net "M_H_CPU0_SA_CB<2>")
	)
	(segment
		(start 394.24356 -245.21033)
		(end 393.954 -244.92077)
		(width 0.0889)
		(layer "In13.Cu")
		(net "M_H_CPU0_SA_CB<2>")
	)
	(segment
		(start 385.751832 -244.97157)
		(end 385.74345 -244.966744)
		(width 0.0889)
		(layer "In13.Cu")
		(net "M_H_CPU0_SA_CB<2>")
	)
	(segment
		(start 417.882324 -235.160312)
		(end 415.089594 -235.160312)
		(width 0.14478)
		(layer "In13.Cu")
		(net "M_H_CPU0_SA_CB<2>")
	)
	(segment
		(start 407.003504 -240.712498)
		(end 407.119074 -240.828068)
		(width 0.14478)
		(layer "In13.Cu")
		(net "M_H_CPU0_SA_CB<2>")
	)
	(segment
		(start 406.61336 -241.102388)
		(end 406.409144 -241.102134)
		(width 0.14478)
		(layer "In13.Cu")
		(net "M_H_CPU0_SA_CB<2>")
	)
	(segment
		(start 404.779734 -243.167408)
		(end 404.77948 -243.372132)
		(width 0.14478)
		(layer "In13.Cu")
		(net "M_H_CPU0_SA_CB<2>")
	)
	(segment
		(start 386.691886 -244.97157)
		(end 386.683504 -244.966744)
		(width 0.0889)
		(layer "In13.Cu")
		(net "M_H_CPU0_SA_CB<2>")
	)
	(segment
		(start 403.689566 -244.462046)
		(end 395.85392 -244.462046)
		(width 0.14478)
		(layer "In13.Cu")
		(net "M_H_CPU0_SA_CB<2>")
	)
	(segment
		(start 405.443944 -242.067334)
		(end 405.443944 -242.272058)
		(width 0.14478)
		(layer "In13.Cu")
		(net "M_H_CPU0_SA_CB<2>")
	)
	(segment
		(start 412.131764 -236.019848)
		(end 408.493214 -239.658398)
		(width 0.14478)
		(layer "In13.Cu")
		(net "M_H_CPU0_SA_CB<2>")
	)
	(segment
		(start 405.629364 -241.881914)
		(end 405.443944 -242.067334)
		(width 0.14478)
		(layer "In13.Cu")
		(net "M_H_CPU0_SA_CB<2>")
	)
	(segment
		(start 403.884384 -243.626894)
		(end 403.884384 -243.831618)
		(width 0.14478)
		(layer "In13.Cu")
		(net "M_H_CPU0_SA_CB<2>")
	)
	(segment
		(start 391.026142 -244.966744)
		(end 391.01776 -244.97157)
		(width 0.0889)
		(layer "In13.Cu")
		(net "M_H_CPU0_SA_CB<2>")
	)
	(segment
		(start 405.83358 -241.882168)
		(end 405.629364 -241.881914)
		(width 0.14478)
		(layer "In13.Cu")
		(net "M_H_CPU0_SA_CB<2>")
	)
	(segment
		(start 405.55926 -242.592352)
		(end 405.374094 -242.777518)
		(width 0.14478)
		(layer "In13.Cu")
		(net "M_H_CPU0_SA_CB<2>")
	)
	(segment
		(start 414.230058 -236.019848)
		(end 412.131764 -236.019848)
		(width 0.14478)
		(layer "In13.Cu")
		(net "M_H_CPU0_SA_CB<2>")
	)
	(segment
		(start 407.783284 -239.727994)
		(end 407.783284 -239.932718)
		(width 0.14478)
		(layer "In13.Cu")
		(net "M_H_CPU0_SA_CB<2>")
	)
	(segment
		(start 408.493214 -239.658398)
		(end 408.28849 -239.658398)
		(width 0.14478)
		(layer "In13.Cu")
		(net "M_H_CPU0_SA_CB<2>")
	)
	(segment
		(start 395.632432 -244.462046)
		(end 394.884148 -245.21033)
		(width 0.0889)
		(layer "In13.Cu")
		(net "M_H_CPU0_SA_CB<2>")
	)
	(segment
		(start 407.119074 -240.828068)
		(end 407.11882 -241.032792)
		(width 0.14478)
		(layer "In13.Cu")
		(net "M_H_CPU0_SA_CB<2>")
	)
	(segment
		(start 407.39314 -240.322608)
		(end 407.188924 -240.322354)
		(width 0.14478)
		(layer "In13.Cu")
		(net "M_H_CPU0_SA_CB<2>")
	)
	(segment
		(start 419.542468 -236.01045)
		(end 418.732462 -236.01045)
		(width 0.14478)
		(layer "In13.Cu")
		(net "M_H_CPU0_SA_CB<2>")
	)
	(segment
		(start 383.838958 -245.02872)
		(end 383.68478 -245.29415)
		(width 0.0889)
		(layer "In13.Cu")
		(net "M_H_CPU0_SA_CB<2>")
	)
	(segment
		(start 406.409144 -241.102134)
		(end 406.223724 -241.287554)
		(width 0.14478)
		(layer "In13.Cu")
		(net "M_H_CPU0_SA_CB<2>")
	)
	(segment
		(start 390.451848 -244.97157)
		(end 390.443466 -244.966744)
		(width 0.0889)
		(layer "In13.Cu")
		(net "M_H_CPU0_SA_CB<2>")
	)
	(segment
		(start 407.50871 -240.438178)
		(end 407.39314 -240.322608)
		(width 0.14478)
		(layer "In13.Cu")
		(net "M_H_CPU0_SA_CB<2>")
	)
	(segment
		(start 404.664164 -243.051838)
		(end 404.779734 -243.167408)
		(width 0.14478)
		(layer "In13.Cu")
		(net "M_H_CPU0_SA_CB<2>")
	)
	(segment
		(start 387.26618 -244.966744)
		(end 387.257798 -244.97157)
		(width 0.0889)
		(layer "In13.Cu")
		(net "M_H_CPU0_SA_CB<2>")
	)
	(segment
		(start 405.94915 -241.997738)
		(end 405.83358 -241.882168)
		(width 0.14478)
		(layer "In13.Cu")
		(net "M_H_CPU0_SA_CB<2>")
	)
	(segment
		(start 403.9997 -244.151912)
		(end 403.689566 -244.462046)
		(width 0.14478)
		(layer "In13.Cu")
		(net "M_H_CPU0_SA_CB<2>")
	)
	(segment
		(start 406.72893 -241.217958)
		(end 406.61336 -241.102388)
		(width 0.14478)
		(layer "In13.Cu")
		(net "M_H_CPU0_SA_CB<2>")
	)
	(segment
		(start 408.28849 -239.658398)
		(end 408.17292 -239.542828)
		(width 0.14478)
		(layer "In13.Cu")
		(net "M_H_CPU0_SA_CB<2>")
	)
	(segment
		(start 406.223724 -241.287554)
		(end 406.223724 -241.492278)
		(width 0.14478)
		(layer "In13.Cu")
		(net "M_H_CPU0_SA_CB<2>")
	)
	(segment
		(start 383.935224 -245.00332)
		(end 383.838958 -245.02872)
		(width 0.0889)
		(layer "In13.Cu")
		(net "M_H_CPU0_SA_CB<2>")
	)
	(segment
		(start 392.332718 -244.97157)
		(end 392.324336 -244.966744)
		(width 0.0889)
		(layer "In13.Cu")
		(net "M_H_CPU0_SA_CB<2>")
	)
	(segment
		(start 403.999954 -243.947188)
		(end 403.9997 -244.151912)
		(width 0.14478)
		(layer "In13.Cu")
		(net "M_H_CPU0_SA_CB<2>")
	)
	(segment
		(start 406.339294 -241.607848)
		(end 406.33904 -241.812572)
		(width 0.14478)
		(layer "In13.Cu")
		(net "M_H_CPU0_SA_CB<2>")
	)
	(segment
		(start 406.933654 -241.217958)
		(end 406.72893 -241.217958)
		(width 0.14478)
		(layer "In13.Cu")
		(net "M_H_CPU0_SA_CB<2>")
	)
	(segment
		(start 419.912038 -235.585)
		(end 419.912038 -235.64088)
		(width 0.14478)
		(layer "In13.Cu")
		(net "M_H_CPU0_SA_CB<2>")
	)
	(segment
		(start 406.153874 -241.997738)
		(end 405.94915 -241.997738)
		(width 0.14478)
		(layer "In13.Cu")
		(net "M_H_CPU0_SA_CB<2>")
	)
	(segment
		(start 419.912038 -235.64088)
		(end 419.542468 -236.01045)
		(width 0.14478)
		(layer "In13.Cu")
		(net "M_H_CPU0_SA_CB<2>")
	)
	(segment
		(start 407.8986 -240.253012)
		(end 407.713434 -240.438178)
		(width 0.14478)
		(layer "In13.Cu")
		(net "M_H_CPU0_SA_CB<2>")
	)
	(segment
		(start 418.732462 -236.01045)
		(end 417.882324 -235.160312)
		(width 0.14478)
		(layer "In13.Cu")
		(net "M_H_CPU0_SA_CB<2>")
	)
	(segment
		(start 404.849584 -242.661694)
		(end 404.664164 -242.847114)
		(width 0.14478)
		(layer "In13.Cu")
		(net "M_H_CPU0_SA_CB<2>")
	)
	(segment
		(start 395.85392 -244.462046)
		(end 395.632432 -244.462046)
		(width 0.0889)
		(layer "In13.Cu")
		(net "M_H_CPU0_SA_CB<2>")
	)
	(segment
		(start 406.33904 -241.812572)
		(end 406.153874 -241.997738)
		(width 0.14478)
		(layer "In13.Cu")
		(net "M_H_CPU0_SA_CB<2>")
	)
	(segment
		(start 404.664164 -242.847114)
		(end 404.664164 -243.051838)
		(width 0.14478)
		(layer "In13.Cu")
		(net "M_H_CPU0_SA_CB<2>")
	)
	(segment
		(start 388.206234 -244.966744)
		(end 388.197852 -244.97157)
		(width 0.0889)
		(layer "In13.Cu")
		(net "M_H_CPU0_SA_CB<2>")
	)
	(segment
		(start 407.188924 -240.322354)
		(end 407.003504 -240.507774)
		(width 0.14478)
		(layer "In13.Cu")
		(net "M_H_CPU0_SA_CB<2>")
	)
	(segment
		(start 404.77948 -243.372132)
		(end 404.594314 -243.557298)
		(width 0.14478)
		(layer "In13.Cu")
		(net "M_H_CPU0_SA_CB<2>")
	)
	(segment
		(start 403.884384 -243.831618)
		(end 403.999954 -243.947188)
		(width 0.14478)
		(layer "In13.Cu")
		(net "M_H_CPU0_SA_CB<2>")
	)
	(segment
		(start 405.374094 -242.777518)
		(end 405.16937 -242.777518)
		(width 0.14478)
		(layer "In13.Cu")
		(net "M_H_CPU0_SA_CB<2>")
	)
	(segment
		(start 391.402316 -244.977666)
		(end 391.391902 -244.97157)
		(width 0.0889)
		(layer "In13.Cu")
		(net "M_H_CPU0_SA_CB<2>")
	)
	(segment
		(start 407.968704 -239.542574)
		(end 407.783284 -239.727994)
		(width 0.14478)
		(layer "In13.Cu")
		(net "M_H_CPU0_SA_CB<2>")
	)
	(segment
		(start 407.783284 -239.932718)
		(end 407.898854 -240.048288)
		(width 0.14478)
		(layer "In13.Cu")
		(net "M_H_CPU0_SA_CB<2>")
	)
	(segment
		(start 405.443944 -242.272058)
		(end 405.559514 -242.387628)
		(width 0.14478)
		(layer "In13.Cu")
		(net "M_H_CPU0_SA_CB<2>")
	)
	(segment
		(start 405.16937 -242.777518)
		(end 405.0538 -242.661948)
		(width 0.14478)
		(layer "In13.Cu")
		(net "M_H_CPU0_SA_CB<2>")
	)
	(segment
		(start 407.11882 -241.032792)
		(end 406.933654 -241.217958)
		(width 0.14478)
		(layer "In13.Cu")
		(net "M_H_CPU0_SA_CB<2>")
	)
	(segment
		(start 405.559514 -242.387628)
		(end 405.55926 -242.592352)
		(width 0.14478)
		(layer "In13.Cu")
		(net "M_H_CPU0_SA_CB<2>")
	)
	(arc
		(start 390.443466 -244.966744)
		(mid 390.259958 -244.92125)
		(end 390.077706 -244.97157)
		(width 0.0889)
		(layer "In13.Cu")
		(net "M_H_CPU0_SA_CB<2>")
	)
	(arc
		(start 389.511794 -244.97157)
		(mid 389.32485 -244.921315)
		(end 389.137906 -244.97157)
		(width 0.0889)
		(layer "In13.Cu")
		(net "M_H_CPU0_SA_CB<2>")
	)
	(arc
		(start 392.892534 -244.975126)
		(mid 392.612145 -245.047795)
		(end 392.332718 -244.97157)
		(width 0.0889)
		(layer "In13.Cu")
		(net "M_H_CPU0_SA_CB<2>")
	)
	(arc
		(start 386.683504 -244.966744)
		(mid 386.499996 -244.92125)
		(end 386.317744 -244.97157)
		(width 0.0889)
		(layer "In13.Cu")
		(net "M_H_CPU0_SA_CB<2>")
	)
	(arc
		(start 393.084812 -244.92077)
		(mid 392.984958 -244.934813)
		(end 392.892534 -244.975126)
		(width 0.0889)
		(layer "In13.Cu")
		(net "M_H_CPU0_SA_CB<2>")
	)
	(arc
		(start 392.324336 -244.966744)
		(mid 392.140574 -244.921128)
		(end 391.958068 -244.97157)
		(width 0.0889)
		(layer "In13.Cu")
		(net "M_H_CPU0_SA_CB<2>")
	)
	(arc
		(start 387.257798 -244.97157)
		(mid 386.974842 -245.047747)
		(end 386.691886 -244.97157)
		(width 0.0889)
		(layer "In13.Cu")
		(net "M_H_CPU0_SA_CB<2>")
	)
	(arc
		(start 386.317744 -244.97157)
		(mid 386.034788 -245.047747)
		(end 385.751832 -244.97157)
		(width 0.0889)
		(layer "In13.Cu")
		(net "M_H_CPU0_SA_CB<2>")
	)
	(arc
		(start 387.63194 -244.97157)
		(mid 387.449689 -244.92122)
		(end 387.26618 -244.966744)
		(width 0.0889)
		(layer "In13.Cu")
		(net "M_H_CPU0_SA_CB<2>")
	)
	(arc
		(start 391.958068 -244.97157)
		(mid 391.681001 -245.047841)
		(end 391.402316 -244.977666)
		(width 0.0889)
		(layer "In13.Cu")
		(net "M_H_CPU0_SA_CB<2>")
	)
	(arc
		(start 385.74345 -244.966744)
		(mid 385.559942 -244.92125)
		(end 385.37769 -244.97157)
		(width 0.0889)
		(layer "In13.Cu")
		(net "M_H_CPU0_SA_CB<2>")
	)
	(arc
		(start 384.43789 -244.97157)
		(mid 384.190294 -245.046748)
		(end 383.935224 -245.00332)
		(width 0.0889)
		(layer "In13.Cu")
		(net "M_H_CPU0_SA_CB<2>")
	)
	(arc
		(start 389.137906 -244.97157)
		(mid 388.85495 -245.047747)
		(end 388.571994 -244.97157)
		(width 0.0889)
		(layer "In13.Cu")
		(net "M_H_CPU0_SA_CB<2>")
	)
	(arc
		(start 391.391902 -244.97157)
		(mid 391.209651 -244.92122)
		(end 391.026142 -244.966744)
		(width 0.0889)
		(layer "In13.Cu")
		(net "M_H_CPU0_SA_CB<2>")
	)
	(arc
		(start 388.571994 -244.97157)
		(mid 388.389743 -244.92122)
		(end 388.206234 -244.966744)
		(width 0.0889)
		(layer "In13.Cu")
		(net "M_H_CPU0_SA_CB<2>")
	)
	(arc
		(start 390.077706 -244.97157)
		(mid 389.79475 -245.047747)
		(end 389.511794 -244.97157)
		(width 0.0889)
		(layer "In13.Cu")
		(net "M_H_CPU0_SA_CB<2>")
	)
	(arc
		(start 384.811778 -244.97157)
		(mid 384.624834 -244.921315)
		(end 384.43789 -244.97157)
		(width 0.0889)
		(layer "In13.Cu")
		(net "M_H_CPU0_SA_CB<2>")
	)
	(arc
		(start 385.37769 -244.97157)
		(mid 385.094734 -245.047747)
		(end 384.811778 -244.97157)
		(width 0.0889)
		(layer "In13.Cu")
		(net "M_H_CPU0_SA_CB<2>")
	)
	(arc
		(start 388.197852 -244.97157)
		(mid 387.914896 -245.047747)
		(end 387.63194 -244.97157)
		(width 0.0889)
		(layer "In13.Cu")
		(net "M_H_CPU0_SA_CB<2>")
	)
	(arc
		(start 391.01776 -244.97157)
		(mid 390.734804 -245.047747)
		(end 390.451848 -244.97157)
		(width 0.0889)
		(layer "In13.Cu")
		(net "M_H_CPU0_SA_CB<2>")
	)
	(segment
		(start 382.277874 -245.560088)
		(end 382.744726 -245.29415)
		(width 0.10668)
		(layer "F.Cu")
		(net "M_H_CPU0_SA_CB<1>")
	)
	(segment
		(start 418.360352 -236.4105)
		(end 419.446456 -236.860334)
		(width 0.14478)
		(layer "In13.Cu")
		(net "M_H_CPU0_SA_CB<1>")
	)
	(segment
		(start 383.497836 -245.61673)
		(end 383.506218 -245.621556)
		(width 0.0889)
		(layer "In13.Cu")
		(net "M_H_CPU0_SA_CB<1>")
	)
	(segment
		(start 392.321034 -245.623588)
		(end 392.332718 -245.61673)
		(width 0.0889)
		(layer "In13.Cu")
		(net "M_H_CPU0_SA_CB<1>")
	)
	(segment
		(start 392.892534 -245.613174)
		(end 392.898122 -245.616476)
		(width 0.0889)
		(layer "In13.Cu")
		(net "M_H_CPU0_SA_CB<1>")
	)
	(segment
		(start 387.257798 -245.61673)
		(end 387.26618 -245.621556)
		(width 0.0889)
		(layer "In13.Cu")
		(net "M_H_CPU0_SA_CB<1>")
	)
	(segment
		(start 414.498282 -236.4105)
		(end 418.360352 -236.4105)
		(width 0.14478)
		(layer "In13.Cu")
		(net "M_H_CPU0_SA_CB<1>")
	)
	(segment
		(start 390.443466 -245.621556)
		(end 390.451848 -245.61673)
		(width 0.0889)
		(layer "In13.Cu")
		(net "M_H_CPU0_SA_CB<1>")
	)
	(segment
		(start 395.5923 -244.916706)
		(end 395.850364 -244.916706)
		(width 0.0889)
		(layer "In13.Cu")
		(net "M_H_CPU0_SA_CB<1>")
	)
	(segment
		(start 382.744726 -245.29415)
		(end 382.590802 -245.55958)
		(width 0.0889)
		(layer "In13.Cu")
		(net "M_H_CPU0_SA_CB<1>")
	)
	(segment
		(start 393.823952 -245.608094)
		(end 394.900912 -245.608094)
		(width 0.0889)
		(layer "In13.Cu")
		(net "M_H_CPU0_SA_CB<1>")
	)
	(segment
		(start 385.74345 -245.621556)
		(end 385.751832 -245.61673)
		(width 0.0889)
		(layer "In13.Cu")
		(net "M_H_CPU0_SA_CB<1>")
	)
	(segment
		(start 403.871176 -244.916706)
		(end 411.527244 -237.260638)
		(width 0.14478)
		(layer "In13.Cu")
		(net "M_H_CPU0_SA_CB<1>")
	)
	(segment
		(start 423.048684 -236.435138)
		(end 424.012106 -236.435138)
		(width 0.14478)
		(layer "In13.Cu")
		(net "M_H_CPU0_SA_CB<1>")
	)
	(segment
		(start 386.683504 -245.621556)
		(end 386.691886 -245.61673)
		(width 0.0889)
		(layer "In13.Cu")
		(net "M_H_CPU0_SA_CB<1>")
	)
	(segment
		(start 395.850364 -244.916706)
		(end 403.871176 -244.916706)
		(width 0.14478)
		(layer "In13.Cu")
		(net "M_H_CPU0_SA_CB<1>")
	)
	(segment
		(start 411.527244 -237.260638)
		(end 412.448502 -237.260638)
		(width 0.14478)
		(layer "In13.Cu")
		(net "M_H_CPU0_SA_CB<1>")
	)
	(segment
		(start 392.898122 -245.616476)
		(end 392.91641 -245.62689)
		(width 0.0889)
		(layer "In13.Cu")
		(net "M_H_CPU0_SA_CB<1>")
	)
	(segment
		(start 420.91102 -236.860334)
		(end 423.048684 -236.435138)
		(width 0.14478)
		(layer "In13.Cu")
		(net "M_H_CPU0_SA_CB<1>")
	)
	(segment
		(start 394.900912 -245.608094)
		(end 395.5923 -244.916706)
		(width 0.0889)
		(layer "In13.Cu")
		(net "M_H_CPU0_SA_CB<1>")
	)
	(segment
		(start 419.446456 -236.860334)
		(end 420.91102 -236.860334)
		(width 0.14478)
		(layer "In13.Cu")
		(net "M_H_CPU0_SA_CB<1>")
	)
	(segment
		(start 388.197852 -245.61673)
		(end 388.206234 -245.621556)
		(width 0.0889)
		(layer "In13.Cu")
		(net "M_H_CPU0_SA_CB<1>")
	)
	(segment
		(start 412.448502 -237.260638)
		(end 414.498282 -236.4105)
		(width 0.14478)
		(layer "In13.Cu")
		(net "M_H_CPU0_SA_CB<1>")
	)
	(segment
		(start 391.01776 -245.61673)
		(end 391.026142 -245.621556)
		(width 0.0889)
		(layer "In13.Cu")
		(net "M_H_CPU0_SA_CB<1>")
	)
	(segment
		(start 391.391902 -245.61673)
		(end 391.406634 -245.608094)
		(width 0.0889)
		(layer "In13.Cu")
		(net "M_H_CPU0_SA_CB<1>")
	)
	(segment
		(start 382.590802 -245.55958)
		(end 382.613154 -245.642892)
		(width 0.0889)
		(layer "In13.Cu")
		(net "M_H_CPU0_SA_CB<1>")
	)
	(arc
		(start 389.511794 -245.61673)
		(mid 389.79475 -245.540553)
		(end 390.077706 -245.61673)
		(width 0.0889)
		(layer "In13.Cu")
		(net "M_H_CPU0_SA_CB<1>")
	)
	(arc
		(start 383.871978 -245.61673)
		(mid 384.154934 -245.540553)
		(end 384.43789 -245.61673)
		(width 0.0889)
		(layer "In13.Cu")
		(net "M_H_CPU0_SA_CB<1>")
	)
	(arc
		(start 382.931924 -245.61673)
		(mid 383.21488 -245.540553)
		(end 383.497836 -245.61673)
		(width 0.0889)
		(layer "In13.Cu")
		(net "M_H_CPU0_SA_CB<1>")
	)
	(arc
		(start 392.332718 -245.61673)
		(mid 392.612146 -245.540564)
		(end 392.892534 -245.613174)
		(width 0.0889)
		(layer "In13.Cu")
		(net "M_H_CPU0_SA_CB<1>")
	)
	(arc
		(start 392.91641 -245.62689)
		(mid 393.095639 -245.667043)
		(end 393.272264 -245.61673)
		(width 0.0889)
		(layer "In13.Cu")
		(net "M_H_CPU0_SA_CB<1>")
	)
	(arc
		(start 385.37769 -245.61673)
		(mid 385.559941 -245.66708)
		(end 385.74345 -245.621556)
		(width 0.0889)
		(layer "In13.Cu")
		(net "M_H_CPU0_SA_CB<1>")
	)
	(arc
		(start 387.26618 -245.621556)
		(mid 387.449688 -245.66705)
		(end 387.63194 -245.61673)
		(width 0.0889)
		(layer "In13.Cu")
		(net "M_H_CPU0_SA_CB<1>")
	)
	(arc
		(start 384.43789 -245.61673)
		(mid 384.624834 -245.666985)
		(end 384.811778 -245.61673)
		(width 0.0889)
		(layer "In13.Cu")
		(net "M_H_CPU0_SA_CB<1>")
	)
	(arc
		(start 390.077706 -245.61673)
		(mid 390.259957 -245.66708)
		(end 390.443466 -245.621556)
		(width 0.0889)
		(layer "In13.Cu")
		(net "M_H_CPU0_SA_CB<1>")
	)
	(arc
		(start 382.613154 -245.642892)
		(mid 382.775486 -245.66571)
		(end 382.931924 -245.61673)
		(width 0.0889)
		(layer "In13.Cu")
		(net "M_H_CPU0_SA_CB<1>")
	)
	(arc
		(start 386.317744 -245.61673)
		(mid 386.499995 -245.66708)
		(end 386.683504 -245.621556)
		(width 0.0889)
		(layer "In13.Cu")
		(net "M_H_CPU0_SA_CB<1>")
	)
	(arc
		(start 389.137906 -245.61673)
		(mid 389.32485 -245.666985)
		(end 389.511794 -245.61673)
		(width 0.0889)
		(layer "In13.Cu")
		(net "M_H_CPU0_SA_CB<1>")
	)
	(arc
		(start 383.506218 -245.621556)
		(mid 383.689726 -245.66705)
		(end 383.871978 -245.61673)
		(width 0.0889)
		(layer "In13.Cu")
		(net "M_H_CPU0_SA_CB<1>")
	)
	(arc
		(start 393.272264 -245.61673)
		(mid 393.54697 -245.540366)
		(end 393.823952 -245.608094)
		(width 0.0889)
		(layer "In13.Cu")
		(net "M_H_CPU0_SA_CB<1>")
	)
	(arc
		(start 391.406634 -245.608094)
		(mid 391.683617 -245.54029)
		(end 391.958322 -245.61673)
		(width 0.0889)
		(layer "In13.Cu")
		(net "M_H_CPU0_SA_CB<1>")
	)
	(arc
		(start 385.751832 -245.61673)
		(mid 386.034788 -245.540553)
		(end 386.317744 -245.61673)
		(width 0.0889)
		(layer "In13.Cu")
		(net "M_H_CPU0_SA_CB<1>")
	)
	(arc
		(start 391.026142 -245.621556)
		(mid 391.20965 -245.66705)
		(end 391.391902 -245.61673)
		(width 0.0889)
		(layer "In13.Cu")
		(net "M_H_CPU0_SA_CB<1>")
	)
	(arc
		(start 388.206234 -245.621556)
		(mid 388.389742 -245.66705)
		(end 388.571994 -245.61673)
		(width 0.0889)
		(layer "In13.Cu")
		(net "M_H_CPU0_SA_CB<1>")
	)
	(arc
		(start 386.691886 -245.61673)
		(mid 386.974842 -245.540553)
		(end 387.257798 -245.61673)
		(width 0.0889)
		(layer "In13.Cu")
		(net "M_H_CPU0_SA_CB<1>")
	)
	(arc
		(start 387.63194 -245.61673)
		(mid 387.914896 -245.540553)
		(end 388.197852 -245.61673)
		(width 0.0889)
		(layer "In13.Cu")
		(net "M_H_CPU0_SA_CB<1>")
	)
	(arc
		(start 390.451848 -245.61673)
		(mid 390.734804 -245.540553)
		(end 391.01776 -245.61673)
		(width 0.0889)
		(layer "In13.Cu")
		(net "M_H_CPU0_SA_CB<1>")
	)
	(arc
		(start 391.958322 -245.61673)
		(mid 392.13878 -245.667174)
		(end 392.321034 -245.623588)
		(width 0.0889)
		(layer "In13.Cu")
		(net "M_H_CPU0_SA_CB<1>")
	)
	(arc
		(start 388.571994 -245.61673)
		(mid 388.85495 -245.540553)
		(end 389.137906 -245.61673)
		(width 0.0889)
		(layer "In13.Cu")
		(net "M_H_CPU0_SA_CB<1>")
	)
	(arc
		(start 384.811778 -245.61673)
		(mid 385.094734 -245.540553)
		(end 385.37769 -245.61673)
		(width 0.0889)
		(layer "In13.Cu")
		(net "M_H_CPU0_SA_CB<1>")
	)
	(segment
		(start 383.688082 -244.750082)
		(end 384.154934 -244.484144)
		(width 0.10668)
		(layer "F.Cu")
		(net "M_H_CPU0_SA_CB<0>")
	)
	(segment
		(start 402.880322 -243.99494)
		(end 395.642846 -243.99494)
		(width 0.14478)
		(layer "In13.Cu")
		(net "M_H_CPU0_SA_CB<0>")
	)
	(segment
		(start 395.03858 -244.38991)
		(end 394.419836 -244.38991)
		(width 0.0889)
		(layer "In13.Cu")
		(net "M_H_CPU0_SA_CB<0>")
	)
	(segment
		(start 391.496042 -244.81155)
		(end 391.48766 -244.806724)
		(width 0.0889)
		(layer "In13.Cu")
		(net "M_H_CPU0_SA_CB<0>")
	)
	(segment
		(start 384.341878 -244.806724)
		(end 384.333496 -244.81155)
		(width 0.0889)
		(layer "In13.Cu")
		(net "M_H_CPU0_SA_CB<0>")
	)
	(segment
		(start 389.616188 -244.81155)
		(end 389.607806 -244.806724)
		(width 0.0889)
		(layer "In13.Cu")
		(net "M_H_CPU0_SA_CB<0>")
	)
	(segment
		(start 421.625014 -235.160312)
		(end 418.566854 -235.160312)
		(width 0.14478)
		(layer "In13.Cu")
		(net "M_H_CPU0_SA_CB<0>")
	)
	(segment
		(start 395.43355 -243.99494)
		(end 395.03858 -244.38991)
		(width 0.0889)
		(layer "In13.Cu")
		(net "M_H_CPU0_SA_CB<0>")
	)
	(segment
		(start 395.642846 -243.99494)
		(end 395.43355 -243.99494)
		(width 0.0889)
		(layer "In13.Cu")
		(net "M_H_CPU0_SA_CB<0>")
	)
	(segment
		(start 385.856226 -244.81155)
		(end 385.847844 -244.806724)
		(width 0.0889)
		(layer "In13.Cu")
		(net "M_H_CPU0_SA_CB<0>")
	)
	(segment
		(start 384.000756 -244.749574)
		(end 384.154934 -244.484144)
		(width 0.0889)
		(layer "In13.Cu")
		(net "M_H_CPU0_SA_CB<0>")
	)
	(segment
		(start 424.012106 -234.735116)
		(end 421.625014 -235.160312)
		(width 0.14478)
		(layer "In13.Cu")
		(net "M_H_CPU0_SA_CB<0>")
	)
	(segment
		(start 418.566854 -235.160312)
		(end 417.71697 -234.310428)
		(width 0.14478)
		(layer "In13.Cu")
		(net "M_H_CPU0_SA_CB<0>")
	)
	(segment
		(start 411.304994 -235.570268)
		(end 402.880322 -243.99494)
		(width 0.14478)
		(layer "In13.Cu")
		(net "M_H_CPU0_SA_CB<0>")
	)
	(segment
		(start 414.036256 -235.570268)
		(end 411.304994 -235.570268)
		(width 0.14478)
		(layer "In13.Cu")
		(net "M_H_CPU0_SA_CB<0>")
	)
	(segment
		(start 394.419836 -244.38991)
		(end 394.079476 -244.73027)
		(width 0.0889)
		(layer "In13.Cu")
		(net "M_H_CPU0_SA_CB<0>")
	)
	(segment
		(start 388.10184 -244.806724)
		(end 388.093458 -244.81155)
		(width 0.0889)
		(layer "In13.Cu")
		(net "M_H_CPU0_SA_CB<0>")
	)
	(segment
		(start 415.296096 -234.310428)
		(end 414.036256 -235.570268)
		(width 0.14478)
		(layer "In13.Cu")
		(net "M_H_CPU0_SA_CB<0>")
	)
	(segment
		(start 394.079476 -244.73027)
		(end 393.084812 -244.73027)
		(width 0.0889)
		(layer "In13.Cu")
		(net "M_H_CPU0_SA_CB<0>")
	)
	(segment
		(start 392.428476 -244.806724)
		(end 392.418062 -244.800628)
		(width 0.0889)
		(layer "In13.Cu")
		(net "M_H_CPU0_SA_CB<0>")
	)
	(segment
		(start 384.916172 -244.81155)
		(end 384.90779 -244.806724)
		(width 0.0889)
		(layer "In13.Cu")
		(net "M_H_CPU0_SA_CB<0>")
	)
	(segment
		(start 384.023108 -244.832886)
		(end 384.000756 -244.749574)
		(width 0.0889)
		(layer "In13.Cu")
		(net "M_H_CPU0_SA_CB<0>")
	)
	(segment
		(start 389.041894 -244.806724)
		(end 389.033512 -244.81155)
		(width 0.0889)
		(layer "In13.Cu")
		(net "M_H_CPU0_SA_CB<0>")
	)
	(segment
		(start 417.71697 -234.310428)
		(end 415.296096 -234.310428)
		(width 0.14478)
		(layer "In13.Cu")
		(net "M_H_CPU0_SA_CB<0>")
	)
	(arc
		(start 393.084812 -244.73027)
		(mid 392.929451 -244.752095)
		(end 392.786108 -244.815868)
		(width 0.0889)
		(layer "In13.Cu")
		(net "M_H_CPU0_SA_CB<0>")
	)
	(arc
		(start 389.981948 -244.806724)
		(mid 389.799697 -244.857074)
		(end 389.616188 -244.81155)
		(width 0.0889)
		(layer "In13.Cu")
		(net "M_H_CPU0_SA_CB<0>")
	)
	(arc
		(start 384.90779 -244.806724)
		(mid 384.624834 -244.730547)
		(end 384.341878 -244.806724)
		(width 0.0889)
		(layer "In13.Cu")
		(net "M_H_CPU0_SA_CB<0>")
	)
	(arc
		(start 390.921748 -244.806724)
		(mid 390.734804 -244.856979)
		(end 390.54786 -244.806724)
		(width 0.0889)
		(layer "In13.Cu")
		(net "M_H_CPU0_SA_CB<0>")
	)
	(arc
		(start 390.54786 -244.806724)
		(mid 390.264904 -244.730547)
		(end 389.981948 -244.806724)
		(width 0.0889)
		(layer "In13.Cu")
		(net "M_H_CPU0_SA_CB<0>")
	)
	(arc
		(start 391.48766 -244.806724)
		(mid 391.204704 -244.730547)
		(end 390.921748 -244.806724)
		(width 0.0889)
		(layer "In13.Cu")
		(net "M_H_CPU0_SA_CB<0>")
	)
	(arc
		(start 384.333496 -244.81155)
		(mid 384.180626 -244.856191)
		(end 384.023108 -244.832886)
		(width 0.0889)
		(layer "In13.Cu")
		(net "M_H_CPU0_SA_CB<0>")
	)
	(arc
		(start 389.033512 -244.81155)
		(mid 388.850004 -244.857044)
		(end 388.667752 -244.806724)
		(width 0.0889)
		(layer "In13.Cu")
		(net "M_H_CPU0_SA_CB<0>")
	)
	(arc
		(start 386.787898 -244.806724)
		(mid 386.504942 -244.730547)
		(end 386.221986 -244.806724)
		(width 0.0889)
		(layer "In13.Cu")
		(net "M_H_CPU0_SA_CB<0>")
	)
	(arc
		(start 386.221986 -244.806724)
		(mid 386.039735 -244.857074)
		(end 385.856226 -244.81155)
		(width 0.0889)
		(layer "In13.Cu")
		(net "M_H_CPU0_SA_CB<0>")
	)
	(arc
		(start 389.607806 -244.806724)
		(mid 389.32485 -244.730547)
		(end 389.041894 -244.806724)
		(width 0.0889)
		(layer "In13.Cu")
		(net "M_H_CPU0_SA_CB<0>")
	)
	(arc
		(start 385.847844 -244.806724)
		(mid 385.564888 -244.730547)
		(end 385.281932 -244.806724)
		(width 0.0889)
		(layer "In13.Cu")
		(net "M_H_CPU0_SA_CB<0>")
	)
	(arc
		(start 392.418062 -244.800628)
		(mid 392.139376 -244.730408)
		(end 391.86231 -244.806724)
		(width 0.0889)
		(layer "In13.Cu")
		(net "M_H_CPU0_SA_CB<0>")
	)
	(arc
		(start 387.161786 -244.806724)
		(mid 386.974842 -244.856979)
		(end 386.787898 -244.806724)
		(width 0.0889)
		(layer "In13.Cu")
		(net "M_H_CPU0_SA_CB<0>")
	)
	(arc
		(start 392.786108 -244.815868)
		(mid 392.606126 -244.856968)
		(end 392.428476 -244.806724)
		(width 0.0889)
		(layer "In13.Cu")
		(net "M_H_CPU0_SA_CB<0>")
	)
	(arc
		(start 387.727698 -244.806724)
		(mid 387.444742 -244.730547)
		(end 387.161786 -244.806724)
		(width 0.0889)
		(layer "In13.Cu")
		(net "M_H_CPU0_SA_CB<0>")
	)
	(arc
		(start 388.093458 -244.81155)
		(mid 387.90995 -244.857044)
		(end 387.727698 -244.806724)
		(width 0.0889)
		(layer "In13.Cu")
		(net "M_H_CPU0_SA_CB<0>")
	)
	(arc
		(start 391.86231 -244.806724)
		(mid 391.679805 -244.857201)
		(end 391.496042 -244.81155)
		(width 0.0889)
		(layer "In13.Cu")
		(net "M_H_CPU0_SA_CB<0>")
	)
	(arc
		(start 385.281932 -244.806724)
		(mid 385.099681 -244.857074)
		(end 384.916172 -244.81155)
		(width 0.0889)
		(layer "In13.Cu")
		(net "M_H_CPU0_SA_CB<0>")
	)
	(arc
		(start 388.667752 -244.806724)
		(mid 388.384796 -244.730547)
		(end 388.10184 -244.806724)
		(width 0.0889)
		(layer "In13.Cu")
		(net "M_H_CPU0_SA_CB<0>")
	)
	(segment
		(start 382.277874 -255.28016)
		(end 382.744726 -255.014222)
		(width 0.10668)
		(layer "F.Cu")
		(net "M_H_CPU0_SA_CA<6>")
	)
	(segment
		(start 382.744726 -255.014222)
		(end 382.590802 -255.279652)
		(width 0.0889)
		(layer "In13.Cu")
		(net "M_H_CPU0_SA_CA<6>")
	)
	(segment
		(start 393.272264 -255.336802)
		(end 393.277852 -255.331214)
		(width 0.0889)
		(layer "In13.Cu")
		(net "M_H_CPU0_SA_CA<6>")
	)
	(segment
		(start 386.683504 -255.341628)
		(end 386.691886 -255.336802)
		(width 0.0889)
		(layer "In13.Cu")
		(net "M_H_CPU0_SA_CA<6>")
	)
	(segment
		(start 399.788634 -254.715772)
		(end 403.766528 -254.715772)
		(width 0.14478)
		(layer "In13.Cu")
		(net "M_H_CPU0_SA_CA<6>")
	)
	(segment
		(start 392.892534 -255.333246)
		(end 392.898122 -255.336548)
		(width 0.0889)
		(layer "In13.Cu")
		(net "M_H_CPU0_SA_CA<6>")
	)
	(segment
		(start 387.257798 -255.336802)
		(end 387.26618 -255.341628)
		(width 0.0889)
		(layer "In13.Cu")
		(net "M_H_CPU0_SA_CA<6>")
	)
	(segment
		(start 403.766528 -254.715772)
		(end 404.311866 -255.26111)
		(width 0.14478)
		(layer "In13.Cu")
		(net "M_H_CPU0_SA_CA<6>")
	)
	(segment
		(start 415.326068 -254.710184)
		(end 415.969958 -254.066294)
		(width 0.14478)
		(layer "In13.Cu")
		(net "M_H_CPU0_SA_CA<6>")
	)
	(segment
		(start 419.675056 -252.217174)
		(end 419.68166 -252.217174)
		(width 0.0889)
		(layer "In13.Cu")
		(net "M_H_CPU0_SA_CA<6>")
	)
	(segment
		(start 395.494256 -255.69799)
		(end 398.806416 -255.69799)
		(width 0.14478)
		(layer "In13.Cu")
		(net "M_H_CPU0_SA_CA<6>")
	)
	(segment
		(start 382.590802 -255.279652)
		(end 382.613154 -255.362964)
		(width 0.0889)
		(layer "In13.Cu")
		(net "M_H_CPU0_SA_CA<6>")
	)
	(segment
		(start 416.951668 -254.066294)
		(end 418.628068 -252.389894)
		(width 0.14478)
		(layer "In13.Cu")
		(net "M_H_CPU0_SA_CA<6>")
	)
	(segment
		(start 390.443466 -255.341628)
		(end 390.451848 -255.336802)
		(width 0.0889)
		(layer "In13.Cu")
		(net "M_H_CPU0_SA_CA<6>")
	)
	(segment
		(start 419.73881 -252.160024)
		(end 420.097458 -252.160024)
		(width 0.0889)
		(layer "In13.Cu")
		(net "M_H_CPU0_SA_CA<6>")
	)
	(segment
		(start 422.92397 -252.160024)
		(end 423.348912 -252.584966)
		(width 0.14478)
		(layer "In13.Cu")
		(net "M_H_CPU0_SA_CA<6>")
	)
	(segment
		(start 388.197852 -255.336802)
		(end 388.206234 -255.341628)
		(width 0.0889)
		(layer "In13.Cu")
		(net "M_H_CPU0_SA_CA<6>")
	)
	(segment
		(start 392.321034 -255.34366)
		(end 392.332718 -255.336802)
		(width 0.0889)
		(layer "In13.Cu")
		(net "M_H_CPU0_SA_CA<6>")
	)
	(segment
		(start 391.01776 -255.336802)
		(end 391.026142 -255.341628)
		(width 0.0889)
		(layer "In13.Cu")
		(net "M_H_CPU0_SA_CA<6>")
	)
	(segment
		(start 404.311866 -255.26111)
		(end 411.434026 -255.26111)
		(width 0.14478)
		(layer "In13.Cu")
		(net "M_H_CPU0_SA_CA<6>")
	)
	(segment
		(start 420.097458 -252.160024)
		(end 422.92397 -252.160024)
		(width 0.14478)
		(layer "In13.Cu")
		(net "M_H_CPU0_SA_CA<6>")
	)
	(segment
		(start 392.898122 -255.336548)
		(end 392.91641 -255.346962)
		(width 0.0889)
		(layer "In13.Cu")
		(net "M_H_CPU0_SA_CA<6>")
	)
	(segment
		(start 391.391902 -255.336802)
		(end 391.406634 -255.328166)
		(width 0.0889)
		(layer "In13.Cu")
		(net "M_H_CPU0_SA_CA<6>")
	)
	(segment
		(start 385.74345 -255.341628)
		(end 385.751832 -255.336802)
		(width 0.0889)
		(layer "In13.Cu")
		(net "M_H_CPU0_SA_CA<6>")
	)
	(segment
		(start 423.348912 -252.584966)
		(end 424.012106 -252.584966)
		(width 0.14478)
		(layer "In13.Cu")
		(net "M_H_CPU0_SA_CA<6>")
	)
	(segment
		(start 394.155676 -255.69799)
		(end 395.494256 -255.69799)
		(width 0.0889)
		(layer "In13.Cu")
		(net "M_H_CPU0_SA_CA<6>")
	)
	(segment
		(start 383.497836 -255.336802)
		(end 383.506218 -255.341628)
		(width 0.0889)
		(layer "In13.Cu")
		(net "M_H_CPU0_SA_CA<6>")
	)
	(segment
		(start 418.628068 -252.389894)
		(end 419.502336 -252.389894)
		(width 0.14478)
		(layer "In13.Cu")
		(net "M_H_CPU0_SA_CA<6>")
	)
	(segment
		(start 393.277852 -255.331214)
		(end 393.7889 -255.331214)
		(width 0.0889)
		(layer "In13.Cu")
		(net "M_H_CPU0_SA_CA<6>")
	)
	(segment
		(start 419.68166 -252.217174)
		(end 419.73881 -252.160024)
		(width 0.0889)
		(layer "In13.Cu")
		(net "M_H_CPU0_SA_CA<6>")
	)
	(segment
		(start 415.969958 -254.066294)
		(end 416.951668 -254.066294)
		(width 0.14478)
		(layer "In13.Cu")
		(net "M_H_CPU0_SA_CA<6>")
	)
	(segment
		(start 398.806416 -255.69799)
		(end 399.788634 -254.715772)
		(width 0.14478)
		(layer "In13.Cu")
		(net "M_H_CPU0_SA_CA<6>")
	)
	(segment
		(start 393.7889 -255.331214)
		(end 394.155676 -255.69799)
		(width 0.0889)
		(layer "In13.Cu")
		(net "M_H_CPU0_SA_CA<6>")
	)
	(segment
		(start 419.502336 -252.389894)
		(end 419.675056 -252.217174)
		(width 0.14478)
		(layer "In13.Cu")
		(net "M_H_CPU0_SA_CA<6>")
	)
	(segment
		(start 411.434026 -255.26111)
		(end 411.984952 -254.710184)
		(width 0.14478)
		(layer "In13.Cu")
		(net "M_H_CPU0_SA_CA<6>")
	)
	(segment
		(start 411.984952 -254.710184)
		(end 415.326068 -254.710184)
		(width 0.14478)
		(layer "In13.Cu")
		(net "M_H_CPU0_SA_CA<6>")
	)
	(arc
		(start 391.026142 -255.341628)
		(mid 391.20965 -255.387122)
		(end 391.391902 -255.336802)
		(width 0.0889)
		(layer "In13.Cu")
		(net "M_H_CPU0_SA_CA<6>")
	)
	(arc
		(start 384.811778 -255.336802)
		(mid 385.094734 -255.260625)
		(end 385.37769 -255.336802)
		(width 0.0889)
		(layer "In13.Cu")
		(net "M_H_CPU0_SA_CA<6>")
	)
	(arc
		(start 384.43789 -255.336802)
		(mid 384.624834 -255.387057)
		(end 384.811778 -255.336802)
		(width 0.0889)
		(layer "In13.Cu")
		(net "M_H_CPU0_SA_CA<6>")
	)
	(arc
		(start 383.871978 -255.336802)
		(mid 384.154934 -255.260625)
		(end 384.43789 -255.336802)
		(width 0.0889)
		(layer "In13.Cu")
		(net "M_H_CPU0_SA_CA<6>")
	)
	(arc
		(start 386.317744 -255.336802)
		(mid 386.499995 -255.387152)
		(end 386.683504 -255.341628)
		(width 0.0889)
		(layer "In13.Cu")
		(net "M_H_CPU0_SA_CA<6>")
	)
	(arc
		(start 383.506218 -255.341628)
		(mid 383.689726 -255.387122)
		(end 383.871978 -255.336802)
		(width 0.0889)
		(layer "In13.Cu")
		(net "M_H_CPU0_SA_CA<6>")
	)
	(arc
		(start 391.958322 -255.336802)
		(mid 392.13878 -255.387246)
		(end 392.321034 -255.34366)
		(width 0.0889)
		(layer "In13.Cu")
		(net "M_H_CPU0_SA_CA<6>")
	)
	(arc
		(start 390.077706 -255.336802)
		(mid 390.259957 -255.387152)
		(end 390.443466 -255.341628)
		(width 0.0889)
		(layer "In13.Cu")
		(net "M_H_CPU0_SA_CA<6>")
	)
	(arc
		(start 386.691886 -255.336802)
		(mid 386.974842 -255.260625)
		(end 387.257798 -255.336802)
		(width 0.0889)
		(layer "In13.Cu")
		(net "M_H_CPU0_SA_CA<6>")
	)
	(arc
		(start 389.137906 -255.336802)
		(mid 389.32485 -255.387057)
		(end 389.511794 -255.336802)
		(width 0.0889)
		(layer "In13.Cu")
		(net "M_H_CPU0_SA_CA<6>")
	)
	(arc
		(start 388.206234 -255.341628)
		(mid 388.389742 -255.387122)
		(end 388.571994 -255.336802)
		(width 0.0889)
		(layer "In13.Cu")
		(net "M_H_CPU0_SA_CA<6>")
	)
	(arc
		(start 387.26618 -255.341628)
		(mid 387.449688 -255.387122)
		(end 387.63194 -255.336802)
		(width 0.0889)
		(layer "In13.Cu")
		(net "M_H_CPU0_SA_CA<6>")
	)
	(arc
		(start 389.511794 -255.336802)
		(mid 389.79475 -255.260625)
		(end 390.077706 -255.336802)
		(width 0.0889)
		(layer "In13.Cu")
		(net "M_H_CPU0_SA_CA<6>")
	)
	(arc
		(start 382.931924 -255.336802)
		(mid 383.21488 -255.260625)
		(end 383.497836 -255.336802)
		(width 0.0889)
		(layer "In13.Cu")
		(net "M_H_CPU0_SA_CA<6>")
	)
	(arc
		(start 392.332718 -255.336802)
		(mid 392.612146 -255.260636)
		(end 392.892534 -255.333246)
		(width 0.0889)
		(layer "In13.Cu")
		(net "M_H_CPU0_SA_CA<6>")
	)
	(arc
		(start 385.37769 -255.336802)
		(mid 385.559941 -255.387152)
		(end 385.74345 -255.341628)
		(width 0.0889)
		(layer "In13.Cu")
		(net "M_H_CPU0_SA_CA<6>")
	)
	(arc
		(start 392.91641 -255.346962)
		(mid 393.095639 -255.387115)
		(end 393.272264 -255.336802)
		(width 0.0889)
		(layer "In13.Cu")
		(net "M_H_CPU0_SA_CA<6>")
	)
	(arc
		(start 385.751832 -255.336802)
		(mid 386.034788 -255.260625)
		(end 386.317744 -255.336802)
		(width 0.0889)
		(layer "In13.Cu")
		(net "M_H_CPU0_SA_CA<6>")
	)
	(arc
		(start 388.571994 -255.336802)
		(mid 388.85495 -255.260625)
		(end 389.137906 -255.336802)
		(width 0.0889)
		(layer "In13.Cu")
		(net "M_H_CPU0_SA_CA<6>")
	)
	(arc
		(start 391.406634 -255.328166)
		(mid 391.683617 -255.260362)
		(end 391.958322 -255.336802)
		(width 0.0889)
		(layer "In13.Cu")
		(net "M_H_CPU0_SA_CA<6>")
	)
	(arc
		(start 387.63194 -255.336802)
		(mid 387.914896 -255.260625)
		(end 388.197852 -255.336802)
		(width 0.0889)
		(layer "In13.Cu")
		(net "M_H_CPU0_SA_CA<6>")
	)
	(arc
		(start 382.613154 -255.362964)
		(mid 382.775486 -255.385782)
		(end 382.931924 -255.336802)
		(width 0.0889)
		(layer "In13.Cu")
		(net "M_H_CPU0_SA_CA<6>")
	)
	(arc
		(start 390.451848 -255.336802)
		(mid 390.734804 -255.260625)
		(end 391.01776 -255.336802)
		(width 0.0889)
		(layer "In13.Cu")
		(net "M_H_CPU0_SA_CA<6>")
	)
	(segment
		(start 383.217928 -255.28016)
		(end 383.68478 -255.014222)
		(width 0.10668)
		(layer "F.Cu")
		(net "M_H_CPU0_SA_CA<5>")
	)
	(segment
		(start 407.156666 -254.266192)
		(end 406.995122 -254.427736)
		(width 0.14478)
		(layer "In13.Cu")
		(net "M_H_CPU0_SA_CA<5>")
	)
	(segment
		(start 394.429996 -255.24079)
		(end 393.95019 -254.760984)
		(width 0.0889)
		(layer "In13.Cu")
		(net "M_H_CPU0_SA_CA<5>")
	)
	(segment
		(start 385.751832 -254.691642)
		(end 385.74345 -254.686816)
		(width 0.0889)
		(layer "In13.Cu")
		(net "M_H_CPU0_SA_CA<5>")
	)
	(segment
		(start 405.892254 -254.602488)
		(end 405.73071 -254.764032)
		(width 0.14478)
		(layer "In13.Cu")
		(net "M_H_CPU0_SA_CA<5>")
	)
	(segment
		(start 406.995122 -254.602488)
		(end 406.833578 -254.764032)
		(width 0.14478)
		(layer "In13.Cu")
		(net "M_H_CPU0_SA_CA<5>")
	)
	(segment
		(start 392.332718 -254.691642)
		(end 392.324336 -254.686816)
		(width 0.0889)
		(layer "In13.Cu")
		(net "M_H_CPU0_SA_CA<5>")
	)
	(segment
		(start 406.443688 -254.427736)
		(end 406.282144 -254.266192)
		(width 0.14478)
		(layer "In13.Cu")
		(net "M_H_CPU0_SA_CA<5>")
	)
	(segment
		(start 383.935224 -254.723392)
		(end 383.838958 -254.748792)
		(width 0.0889)
		(layer "In13.Cu")
		(net "M_H_CPU0_SA_CA<5>")
	)
	(segment
		(start 418.394134 -251.735082)
		(end 417.14166 -252.987556)
		(width 0.14478)
		(layer "In13.Cu")
		(net "M_H_CPU0_SA_CA<5>")
	)
	(segment
		(start 406.995122 -254.427736)
		(end 406.995122 -254.602488)
		(width 0.14478)
		(layer "In13.Cu")
		(net "M_H_CPU0_SA_CA<5>")
	)
	(segment
		(start 383.838958 -254.748792)
		(end 383.68478 -255.014222)
		(width 0.0889)
		(layer "In13.Cu")
		(net "M_H_CPU0_SA_CA<5>")
	)
	(segment
		(start 407.936446 -254.764032)
		(end 407.7081 -254.764032)
		(width 0.14478)
		(layer "In13.Cu")
		(net "M_H_CPU0_SA_CA<5>")
	)
	(segment
		(start 392.898122 -254.691896)
		(end 392.892534 -254.695198)
		(width 0.0889)
		(layer "In13.Cu")
		(net "M_H_CPU0_SA_CA<5>")
	)
	(segment
		(start 405.73071 -254.764032)
		(end 405.502364 -254.764032)
		(width 0.14478)
		(layer "In13.Cu")
		(net "M_H_CPU0_SA_CA<5>")
	)
	(segment
		(start 390.451848 -254.691642)
		(end 390.443466 -254.686816)
		(width 0.0889)
		(layer "In13.Cu")
		(net "M_H_CPU0_SA_CA<5>")
	)
	(segment
		(start 405.34082 -254.602488)
		(end 405.34082 -254.427736)
		(width 0.14478)
		(layer "In13.Cu")
		(net "M_H_CPU0_SA_CA<5>")
	)
	(segment
		(start 407.385012 -254.266192)
		(end 407.156666 -254.266192)
		(width 0.14478)
		(layer "In13.Cu")
		(net "M_H_CPU0_SA_CA<5>")
	)
	(segment
		(start 410.491178 -253.860046)
		(end 410.085032 -254.266192)
		(width 0.14478)
		(layer "In13.Cu")
		(net "M_H_CPU0_SA_CA<5>")
	)
	(segment
		(start 408.09799 -254.427736)
		(end 408.09799 -254.602488)
		(width 0.14478)
		(layer "In13.Cu")
		(net "M_H_CPU0_SA_CA<5>")
	)
	(segment
		(start 407.546556 -254.602488)
		(end 407.546556 -254.427736)
		(width 0.14478)
		(layer "In13.Cu")
		(net "M_H_CPU0_SA_CA<5>")
	)
	(segment
		(start 392.91641 -254.681482)
		(end 392.898122 -254.691896)
		(width 0.0889)
		(layer "In13.Cu")
		(net "M_H_CPU0_SA_CA<5>")
	)
	(segment
		(start 406.282144 -254.266192)
		(end 406.053798 -254.266192)
		(width 0.14478)
		(layer "In13.Cu")
		(net "M_H_CPU0_SA_CA<5>")
	)
	(segment
		(start 410.085032 -254.266192)
		(end 408.259534 -254.266192)
		(width 0.14478)
		(layer "In13.Cu")
		(net "M_H_CPU0_SA_CA<5>")
	)
	(segment
		(start 417.14166 -252.987556)
		(end 415.995358 -252.987556)
		(width 0.14478)
		(layer "In13.Cu")
		(net "M_H_CPU0_SA_CA<5>")
	)
	(segment
		(start 407.546556 -254.427736)
		(end 407.385012 -254.266192)
		(width 0.14478)
		(layer "In13.Cu")
		(net "M_H_CPU0_SA_CA<5>")
	)
	(segment
		(start 406.443688 -254.602488)
		(end 406.443688 -254.427736)
		(width 0.14478)
		(layer "In13.Cu")
		(net "M_H_CPU0_SA_CA<5>")
	)
	(segment
		(start 405.34082 -254.427736)
		(end 405.179276 -254.266192)
		(width 0.14478)
		(layer "In13.Cu")
		(net "M_H_CPU0_SA_CA<5>")
	)
	(segment
		(start 393.356338 -254.74041)
		(end 393.272264 -254.691642)
		(width 0.0889)
		(layer "In13.Cu")
		(net "M_H_CPU0_SA_CA<5>")
	)
	(segment
		(start 408.09799 -254.602488)
		(end 407.936446 -254.764032)
		(width 0.14478)
		(layer "In13.Cu")
		(net "M_H_CPU0_SA_CA<5>")
	)
	(segment
		(start 407.7081 -254.764032)
		(end 407.546556 -254.602488)
		(width 0.14478)
		(layer "In13.Cu")
		(net "M_H_CPU0_SA_CA<5>")
	)
	(segment
		(start 406.053798 -254.266192)
		(end 405.892254 -254.427736)
		(width 0.14478)
		(layer "In13.Cu")
		(net "M_H_CPU0_SA_CA<5>")
	)
	(segment
		(start 391.402316 -254.697738)
		(end 391.391902 -254.691642)
		(width 0.0889)
		(layer "In13.Cu")
		(net "M_H_CPU0_SA_CA<5>")
	)
	(segment
		(start 388.206234 -254.686816)
		(end 388.197852 -254.691642)
		(width 0.0889)
		(layer "In13.Cu")
		(net "M_H_CPU0_SA_CA<5>")
	)
	(segment
		(start 415.122868 -253.860046)
		(end 410.491178 -253.860046)
		(width 0.14478)
		(layer "In13.Cu")
		(net "M_H_CPU0_SA_CA<5>")
	)
	(segment
		(start 399.565368 -254.266192)
		(end 398.59077 -255.24079)
		(width 0.14478)
		(layer "In13.Cu")
		(net "M_H_CPU0_SA_CA<5>")
	)
	(segment
		(start 406.833578 -254.764032)
		(end 406.605232 -254.764032)
		(width 0.14478)
		(layer "In13.Cu")
		(net "M_H_CPU0_SA_CA<5>")
	)
	(segment
		(start 395.522196 -255.24079)
		(end 394.429996 -255.24079)
		(width 0.0889)
		(layer "In13.Cu")
		(net "M_H_CPU0_SA_CA<5>")
	)
	(segment
		(start 405.892254 -254.427736)
		(end 405.892254 -254.602488)
		(width 0.14478)
		(layer "In13.Cu")
		(net "M_H_CPU0_SA_CA<5>")
	)
	(segment
		(start 419.912038 -251.735082)
		(end 418.394134 -251.735082)
		(width 0.14478)
		(layer "In13.Cu")
		(net "M_H_CPU0_SA_CA<5>")
	)
	(segment
		(start 406.605232 -254.764032)
		(end 406.443688 -254.602488)
		(width 0.14478)
		(layer "In13.Cu")
		(net "M_H_CPU0_SA_CA<5>")
	)
	(segment
		(start 405.502364 -254.764032)
		(end 405.34082 -254.602488)
		(width 0.14478)
		(layer "In13.Cu")
		(net "M_H_CPU0_SA_CA<5>")
	)
	(segment
		(start 386.691886 -254.691642)
		(end 386.683504 -254.686816)
		(width 0.0889)
		(layer "In13.Cu")
		(net "M_H_CPU0_SA_CA<5>")
	)
	(segment
		(start 387.26618 -254.686816)
		(end 387.257798 -254.691642)
		(width 0.0889)
		(layer "In13.Cu")
		(net "M_H_CPU0_SA_CA<5>")
	)
	(segment
		(start 393.95019 -254.760984)
		(end 393.432792 -254.760984)
		(width 0.0889)
		(layer "In13.Cu")
		(net "M_H_CPU0_SA_CA<5>")
	)
	(segment
		(start 405.179276 -254.266192)
		(end 399.565368 -254.266192)
		(width 0.14478)
		(layer "In13.Cu")
		(net "M_H_CPU0_SA_CA<5>")
	)
	(segment
		(start 391.026142 -254.686816)
		(end 391.01776 -254.691642)
		(width 0.0889)
		(layer "In13.Cu")
		(net "M_H_CPU0_SA_CA<5>")
	)
	(segment
		(start 398.59077 -255.24079)
		(end 395.522196 -255.24079)
		(width 0.14478)
		(layer "In13.Cu")
		(net "M_H_CPU0_SA_CA<5>")
	)
	(segment
		(start 408.259534 -254.266192)
		(end 408.09799 -254.427736)
		(width 0.14478)
		(layer "In13.Cu")
		(net "M_H_CPU0_SA_CA<5>")
	)
	(segment
		(start 415.995358 -252.987556)
		(end 415.122868 -253.860046)
		(width 0.14478)
		(layer "In13.Cu")
		(net "M_H_CPU0_SA_CA<5>")
	)
	(arc
		(start 386.317744 -254.691642)
		(mid 386.034788 -254.767819)
		(end 385.751832 -254.691642)
		(width 0.0889)
		(layer "In13.Cu")
		(net "M_H_CPU0_SA_CA<5>")
	)
	(arc
		(start 384.43789 -254.691642)
		(mid 384.190294 -254.76682)
		(end 383.935224 -254.723392)
		(width 0.0889)
		(layer "In13.Cu")
		(net "M_H_CPU0_SA_CA<5>")
	)
	(arc
		(start 390.077706 -254.691642)
		(mid 389.79475 -254.767819)
		(end 389.511794 -254.691642)
		(width 0.0889)
		(layer "In13.Cu")
		(net "M_H_CPU0_SA_CA<5>")
	)
	(arc
		(start 392.892534 -254.695198)
		(mid 392.612145 -254.767867)
		(end 392.332718 -254.691642)
		(width 0.0889)
		(layer "In13.Cu")
		(net "M_H_CPU0_SA_CA<5>")
	)
	(arc
		(start 386.683504 -254.686816)
		(mid 386.499996 -254.641322)
		(end 386.317744 -254.691642)
		(width 0.0889)
		(layer "In13.Cu")
		(net "M_H_CPU0_SA_CA<5>")
	)
	(arc
		(start 389.511794 -254.691642)
		(mid 389.32485 -254.641387)
		(end 389.137906 -254.691642)
		(width 0.0889)
		(layer "In13.Cu")
		(net "M_H_CPU0_SA_CA<5>")
	)
	(arc
		(start 388.571994 -254.691642)
		(mid 388.389743 -254.641292)
		(end 388.206234 -254.686816)
		(width 0.0889)
		(layer "In13.Cu")
		(net "M_H_CPU0_SA_CA<5>")
	)
	(arc
		(start 391.391902 -254.691642)
		(mid 391.209651 -254.641292)
		(end 391.026142 -254.686816)
		(width 0.0889)
		(layer "In13.Cu")
		(net "M_H_CPU0_SA_CA<5>")
	)
	(arc
		(start 391.958068 -254.691642)
		(mid 391.681001 -254.767913)
		(end 391.402316 -254.697738)
		(width 0.0889)
		(layer "In13.Cu")
		(net "M_H_CPU0_SA_CA<5>")
	)
	(arc
		(start 392.324336 -254.686816)
		(mid 392.140574 -254.6412)
		(end 391.958068 -254.691642)
		(width 0.0889)
		(layer "In13.Cu")
		(net "M_H_CPU0_SA_CA<5>")
	)
	(arc
		(start 387.63194 -254.691642)
		(mid 387.449689 -254.641292)
		(end 387.26618 -254.686816)
		(width 0.0889)
		(layer "In13.Cu")
		(net "M_H_CPU0_SA_CA<5>")
	)
	(arc
		(start 389.137906 -254.691642)
		(mid 388.85495 -254.767819)
		(end 388.571994 -254.691642)
		(width 0.0889)
		(layer "In13.Cu")
		(net "M_H_CPU0_SA_CA<5>")
	)
	(arc
		(start 393.272264 -254.691642)
		(mid 393.095636 -254.641409)
		(end 392.91641 -254.681482)
		(width 0.0889)
		(layer "In13.Cu")
		(net "M_H_CPU0_SA_CA<5>")
	)
	(arc
		(start 390.443466 -254.686816)
		(mid 390.259958 -254.641322)
		(end 390.077706 -254.691642)
		(width 0.0889)
		(layer "In13.Cu")
		(net "M_H_CPU0_SA_CA<5>")
	)
	(arc
		(start 385.37769 -254.691642)
		(mid 385.094734 -254.767819)
		(end 384.811778 -254.691642)
		(width 0.0889)
		(layer "In13.Cu")
		(net "M_H_CPU0_SA_CA<5>")
	)
	(arc
		(start 388.197852 -254.691642)
		(mid 387.914896 -254.767819)
		(end 387.63194 -254.691642)
		(width 0.0889)
		(layer "In13.Cu")
		(net "M_H_CPU0_SA_CA<5>")
	)
	(arc
		(start 387.257798 -254.691642)
		(mid 386.974842 -254.767819)
		(end 386.691886 -254.691642)
		(width 0.0889)
		(layer "In13.Cu")
		(net "M_H_CPU0_SA_CA<5>")
	)
	(arc
		(start 391.01776 -254.691642)
		(mid 390.734804 -254.767819)
		(end 390.451848 -254.691642)
		(width 0.0889)
		(layer "In13.Cu")
		(net "M_H_CPU0_SA_CA<5>")
	)
	(arc
		(start 385.74345 -254.686816)
		(mid 385.559942 -254.641322)
		(end 385.37769 -254.691642)
		(width 0.0889)
		(layer "In13.Cu")
		(net "M_H_CPU0_SA_CA<5>")
	)
	(arc
		(start 384.811778 -254.691642)
		(mid 384.624834 -254.641387)
		(end 384.43789 -254.691642)
		(width 0.0889)
		(layer "In13.Cu")
		(net "M_H_CPU0_SA_CA<5>")
	)
	(arc
		(start 393.432792 -254.760984)
		(mid 393.393204 -254.755752)
		(end 393.356338 -254.74041)
		(width 0.0889)
		(layer "In13.Cu")
		(net "M_H_CPU0_SA_CA<5>")
	)
	(segment
		(start 383.688082 -254.470154)
		(end 384.154934 -254.204216)
		(width 0.10668)
		(layer "F.Cu")
		(net "M_H_CPU0_SA_CA<4>")
	)
	(segment
		(start 419.41496 -250.992894)
		(end 419.675056 -251.25299)
		(width 0.14478)
		(layer "In13.Cu")
		(net "M_H_CPU0_SA_CA<4>")
	)
	(segment
		(start 419.73881 -251.31014)
		(end 420.097458 -251.31014)
		(width 0.0889)
		(layer "In13.Cu")
		(net "M_H_CPU0_SA_CA<4>")
	)
	(segment
		(start 385.847844 -254.526796)
		(end 385.856226 -254.531622)
		(width 0.0889)
		(layer "In13.Cu")
		(net "M_H_CPU0_SA_CA<4>")
	)
	(segment
		(start 420.097458 -251.31014)
		(end 420.454328 -251.31014)
		(width 0.14478)
		(layer "In13.Cu")
		(net "M_H_CPU0_SA_CA<4>")
	)
	(segment
		(start 392.786108 -254.53594)
		(end 392.802364 -254.526542)
		(width 0.0889)
		(layer "In13.Cu")
		(net "M_H_CPU0_SA_CA<4>")
	)
	(segment
		(start 418.297614 -250.992894)
		(end 419.41496 -250.992894)
		(width 0.14478)
		(layer "In13.Cu")
		(net "M_H_CPU0_SA_CA<4>")
	)
	(segment
		(start 391.48766 -254.526796)
		(end 391.496042 -254.531622)
		(width 0.0889)
		(layer "In13.Cu")
		(net "M_H_CPU0_SA_CA<4>")
	)
	(segment
		(start 398.374616 -254.77597)
		(end 399.333974 -253.816612)
		(width 0.14478)
		(layer "In13.Cu")
		(net "M_H_CPU0_SA_CA<4>")
	)
	(segment
		(start 420.454328 -251.31014)
		(end 420.879524 -250.884944)
		(width 0.14478)
		(layer "In13.Cu")
		(net "M_H_CPU0_SA_CA<4>")
	)
	(segment
		(start 410.704792 -253.010162)
		(end 415.199068 -253.010162)
		(width 0.14478)
		(layer "In13.Cu")
		(net "M_H_CPU0_SA_CA<4>")
	)
	(segment
		(start 392.418062 -254.5207)
		(end 392.428476 -254.526796)
		(width 0.0889)
		(layer "In13.Cu")
		(net "M_H_CPU0_SA_CA<4>")
	)
	(segment
		(start 393.529312 -254.57023)
		(end 394.219176 -254.57023)
		(width 0.0889)
		(layer "In13.Cu")
		(net "M_H_CPU0_SA_CA<4>")
	)
	(segment
		(start 409.898342 -253.816612)
		(end 410.704792 -253.010162)
		(width 0.14478)
		(layer "In13.Cu")
		(net "M_H_CPU0_SA_CA<4>")
	)
	(segment
		(start 395.088618 -254.77597)
		(end 395.80312 -254.77597)
		(width 0.0889)
		(layer "In13.Cu")
		(net "M_H_CPU0_SA_CA<4>")
	)
	(segment
		(start 417.027614 -252.262894)
		(end 418.297614 -250.992894)
		(width 0.14478)
		(layer "In13.Cu")
		(net "M_H_CPU0_SA_CA<4>")
	)
	(segment
		(start 384.333496 -254.531622)
		(end 384.341878 -254.526796)
		(width 0.0889)
		(layer "In13.Cu")
		(net "M_H_CPU0_SA_CA<4>")
	)
	(segment
		(start 415.199068 -253.010162)
		(end 415.946336 -252.262894)
		(width 0.14478)
		(layer "In13.Cu")
		(net "M_H_CPU0_SA_CA<4>")
	)
	(segment
		(start 388.093458 -254.531622)
		(end 388.10184 -254.526796)
		(width 0.0889)
		(layer "In13.Cu")
		(net "M_H_CPU0_SA_CA<4>")
	)
	(segment
		(start 384.154934 -254.204216)
		(end 384.000756 -254.469646)
		(width 0.0889)
		(layer "In13.Cu")
		(net "M_H_CPU0_SA_CA<4>")
	)
	(segment
		(start 394.987018 -254.87757)
		(end 395.088618 -254.77597)
		(width 0.0889)
		(layer "In13.Cu")
		(net "M_H_CPU0_SA_CA<4>")
	)
	(segment
		(start 419.675056 -251.25299)
		(end 419.68166 -251.25299)
		(width 0.0889)
		(layer "In13.Cu")
		(net "M_H_CPU0_SA_CA<4>")
	)
	(segment
		(start 394.526516 -254.87757)
		(end 394.987018 -254.87757)
		(width 0.0889)
		(layer "In13.Cu")
		(net "M_H_CPU0_SA_CA<4>")
	)
	(segment
		(start 384.000756 -254.469646)
		(end 384.023108 -254.552958)
		(width 0.0889)
		(layer "In13.Cu")
		(net "M_H_CPU0_SA_CA<4>")
	)
	(segment
		(start 420.879524 -250.884944)
		(end 424.012106 -250.884944)
		(width 0.14478)
		(layer "In13.Cu")
		(net "M_H_CPU0_SA_CA<4>")
	)
	(segment
		(start 389.607806 -254.526796)
		(end 389.616188 -254.531622)
		(width 0.0889)
		(layer "In13.Cu")
		(net "M_H_CPU0_SA_CA<4>")
	)
	(segment
		(start 394.219176 -254.57023)
		(end 394.526516 -254.87757)
		(width 0.0889)
		(layer "In13.Cu")
		(net "M_H_CPU0_SA_CA<4>")
	)
	(segment
		(start 392.802364 -254.526542)
		(end 392.818112 -254.517398)
		(width 0.0889)
		(layer "In13.Cu")
		(net "M_H_CPU0_SA_CA<4>")
	)
	(segment
		(start 384.90779 -254.526796)
		(end 384.916172 -254.531622)
		(width 0.0889)
		(layer "In13.Cu")
		(net "M_H_CPU0_SA_CA<4>")
	)
	(segment
		(start 395.80312 -254.77597)
		(end 398.374616 -254.77597)
		(width 0.14478)
		(layer "In13.Cu")
		(net "M_H_CPU0_SA_CA<4>")
	)
	(segment
		(start 399.333974 -253.816612)
		(end 409.898342 -253.816612)
		(width 0.14478)
		(layer "In13.Cu")
		(net "M_H_CPU0_SA_CA<4>")
	)
	(segment
		(start 415.946336 -252.262894)
		(end 417.027614 -252.262894)
		(width 0.14478)
		(layer "In13.Cu")
		(net "M_H_CPU0_SA_CA<4>")
	)
	(segment
		(start 419.68166 -251.25299)
		(end 419.73881 -251.31014)
		(width 0.0889)
		(layer "In13.Cu")
		(net "M_H_CPU0_SA_CA<4>")
	)
	(segment
		(start 389.033512 -254.531622)
		(end 389.041894 -254.526796)
		(width 0.0889)
		(layer "In13.Cu")
		(net "M_H_CPU0_SA_CA<4>")
	)
	(arc
		(start 384.341878 -254.526796)
		(mid 384.624834 -254.450619)
		(end 384.90779 -254.526796)
		(width 0.0889)
		(layer "In13.Cu")
		(net "M_H_CPU0_SA_CA<4>")
	)
	(arc
		(start 385.281932 -254.526796)
		(mid 385.564888 -254.450619)
		(end 385.847844 -254.526796)
		(width 0.0889)
		(layer "In13.Cu")
		(net "M_H_CPU0_SA_CA<4>")
	)
	(arc
		(start 389.616188 -254.531622)
		(mid 389.799696 -254.577116)
		(end 389.981948 -254.526796)
		(width 0.0889)
		(layer "In13.Cu")
		(net "M_H_CPU0_SA_CA<4>")
	)
	(arc
		(start 386.221986 -254.526796)
		(mid 386.504942 -254.450619)
		(end 386.787898 -254.526796)
		(width 0.0889)
		(layer "In13.Cu")
		(net "M_H_CPU0_SA_CA<4>")
	)
	(arc
		(start 391.496042 -254.531622)
		(mid 391.679804 -254.577238)
		(end 391.86231 -254.526796)
		(width 0.0889)
		(layer "In13.Cu")
		(net "M_H_CPU0_SA_CA<4>")
	)
	(arc
		(start 388.10184 -254.526796)
		(mid 388.384796 -254.450619)
		(end 388.667752 -254.526796)
		(width 0.0889)
		(layer "In13.Cu")
		(net "M_H_CPU0_SA_CA<4>")
	)
	(arc
		(start 388.667752 -254.526796)
		(mid 388.850003 -254.577146)
		(end 389.033512 -254.531622)
		(width 0.0889)
		(layer "In13.Cu")
		(net "M_H_CPU0_SA_CA<4>")
	)
	(arc
		(start 384.023108 -254.552958)
		(mid 384.180618 -254.576156)
		(end 384.333496 -254.531622)
		(width 0.0889)
		(layer "In13.Cu")
		(net "M_H_CPU0_SA_CA<4>")
	)
	(arc
		(start 390.54786 -254.526796)
		(mid 390.734804 -254.577051)
		(end 390.921748 -254.526796)
		(width 0.0889)
		(layer "In13.Cu")
		(net "M_H_CPU0_SA_CA<4>")
	)
	(arc
		(start 389.981948 -254.526796)
		(mid 390.264904 -254.450619)
		(end 390.54786 -254.526796)
		(width 0.0889)
		(layer "In13.Cu")
		(net "M_H_CPU0_SA_CA<4>")
	)
	(arc
		(start 387.161786 -254.526796)
		(mid 387.444742 -254.450619)
		(end 387.727698 -254.526796)
		(width 0.0889)
		(layer "In13.Cu")
		(net "M_H_CPU0_SA_CA<4>")
	)
	(arc
		(start 390.921748 -254.526796)
		(mid 391.204704 -254.450619)
		(end 391.48766 -254.526796)
		(width 0.0889)
		(layer "In13.Cu")
		(net "M_H_CPU0_SA_CA<4>")
	)
	(arc
		(start 392.428476 -254.526796)
		(mid 392.606126 -254.577056)
		(end 392.786108 -254.53594)
		(width 0.0889)
		(layer "In13.Cu")
		(net "M_H_CPU0_SA_CA<4>")
	)
	(arc
		(start 392.818112 -254.517398)
		(mid 393.094421 -254.450422)
		(end 393.368276 -254.526796)
		(width 0.0889)
		(layer "In13.Cu")
		(net "M_H_CPU0_SA_CA<4>")
	)
	(arc
		(start 393.368276 -254.526796)
		(mid 393.445922 -254.559151)
		(end 393.529312 -254.57023)
		(width 0.0889)
		(layer "In13.Cu")
		(net "M_H_CPU0_SA_CA<4>")
	)
	(arc
		(start 391.86231 -254.526796)
		(mid 392.139377 -254.450525)
		(end 392.418062 -254.5207)
		(width 0.0889)
		(layer "In13.Cu")
		(net "M_H_CPU0_SA_CA<4>")
	)
	(arc
		(start 387.727698 -254.526796)
		(mid 387.909949 -254.577146)
		(end 388.093458 -254.531622)
		(width 0.0889)
		(layer "In13.Cu")
		(net "M_H_CPU0_SA_CA<4>")
	)
	(arc
		(start 389.041894 -254.526796)
		(mid 389.32485 -254.450619)
		(end 389.607806 -254.526796)
		(width 0.0889)
		(layer "In13.Cu")
		(net "M_H_CPU0_SA_CA<4>")
	)
	(arc
		(start 385.856226 -254.531622)
		(mid 386.039734 -254.577116)
		(end 386.221986 -254.526796)
		(width 0.0889)
		(layer "In13.Cu")
		(net "M_H_CPU0_SA_CA<4>")
	)
	(arc
		(start 386.787898 -254.526796)
		(mid 386.974842 -254.577051)
		(end 387.161786 -254.526796)
		(width 0.0889)
		(layer "In13.Cu")
		(net "M_H_CPU0_SA_CA<4>")
	)
	(arc
		(start 384.916172 -254.531622)
		(mid 385.09968 -254.577116)
		(end 385.281932 -254.526796)
		(width 0.0889)
		(layer "In13.Cu")
		(net "M_H_CPU0_SA_CA<4>")
	)
	(segment
		(start 381.807974 -254.470154)
		(end 382.274826 -254.204216)
		(width 0.10668)
		(layer "F.Cu")
		(net "M_H_CPU0_SA_CA<3>")
	)
	(segment
		(start 389.616188 -253.87681)
		(end 389.607806 -253.881636)
		(width 0.0889)
		(layer "In13.Cu")
		(net "M_H_CPU0_SA_CA<3>")
	)
	(segment
		(start 392.42873 -253.881636)
		(end 392.413998 -253.890272)
		(width 0.0889)
		(layer "In13.Cu")
		(net "M_H_CPU0_SA_CA<3>")
	)
	(segment
		(start 383.401824 -253.881636)
		(end 383.393442 -253.87681)
		(width 0.0889)
		(layer "In13.Cu")
		(net "M_H_CPU0_SA_CA<3>")
	)
	(segment
		(start 413.667702 -252.460252)
		(end 413.367474 -252.160024)
		(width 0.14478)
		(layer "In13.Cu")
		(net "M_H_CPU0_SA_CA<3>")
	)
	(segment
		(start 382.524762 -253.913386)
		(end 382.42875 -253.938786)
		(width 0.0889)
		(layer "In13.Cu")
		(net "M_H_CPU0_SA_CA<3>")
	)
	(segment
		(start 398.168876 -254.31623)
		(end 395.69898 -254.31623)
		(width 0.14478)
		(layer "In13.Cu")
		(net "M_H_CPU0_SA_CA<3>")
	)
	(segment
		(start 418.145468 -250.256294)
		(end 417.140898 -251.260864)
		(width 0.14478)
		(layer "In13.Cu")
		(net "M_H_CPU0_SA_CA<3>")
	)
	(segment
		(start 384.341878 -253.881636)
		(end 384.333496 -253.87681)
		(width 0.0889)
		(layer "In13.Cu")
		(net "M_H_CPU0_SA_CA<3>")
	)
	(segment
		(start 392.802364 -253.88189)
		(end 392.788648 -253.874016)
		(width 0.0889)
		(layer "In13.Cu")
		(net "M_H_CPU0_SA_CA<3>")
	)
	(segment
		(start 391.496042 -253.87681)
		(end 391.48766 -253.881636)
		(width 0.0889)
		(layer "In13.Cu")
		(net "M_H_CPU0_SA_CA<3>")
	)
	(segment
		(start 382.42875 -253.938786)
		(end 382.274826 -254.204216)
		(width 0.0889)
		(layer "In13.Cu")
		(net "M_H_CPU0_SA_CA<3>")
	)
	(segment
		(start 413.367474 -252.160024)
		(end 410.918914 -252.160024)
		(width 0.14478)
		(layer "In13.Cu")
		(net "M_H_CPU0_SA_CA<3>")
	)
	(segment
		(start 395.69898 -254.31623)
		(end 395.209776 -254.31623)
		(width 0.0889)
		(layer "In13.Cu")
		(net "M_H_CPU0_SA_CA<3>")
	)
	(segment
		(start 393.958064 -254.10033)
		(end 393.734544 -253.87681)
		(width 0.0889)
		(layer "In13.Cu")
		(net "M_H_CPU0_SA_CA<3>")
	)
	(segment
		(start 414.470342 -252.160024)
		(end 414.219136 -252.160024)
		(width 0.14478)
		(layer "In13.Cu")
		(net "M_H_CPU0_SA_CA<3>")
	)
	(segment
		(start 417.140898 -251.260864)
		(end 416.221164 -251.260864)
		(width 0.14478)
		(layer "In13.Cu")
		(net "M_H_CPU0_SA_CA<3>")
	)
	(segment
		(start 416.221164 -251.260864)
		(end 415.021776 -252.460252)
		(width 0.14478)
		(layer "In13.Cu")
		(net "M_H_CPU0_SA_CA<3>")
	)
	(segment
		(start 414.219136 -252.160024)
		(end 413.918908 -252.460252)
		(width 0.14478)
		(layer "In13.Cu")
		(net "M_H_CPU0_SA_CA<3>")
	)
	(segment
		(start 392.818112 -253.891034)
		(end 392.802364 -253.88189)
		(width 0.0889)
		(layer "In13.Cu")
		(net "M_H_CPU0_SA_CA<3>")
	)
	(segment
		(start 419.690804 -250.256294)
		(end 418.145468 -250.256294)
		(width 0.14478)
		(layer "In13.Cu")
		(net "M_H_CPU0_SA_CA<3>")
	)
	(segment
		(start 388.10184 -253.881636)
		(end 388.093458 -253.87681)
		(width 0.0889)
		(layer "In13.Cu")
		(net "M_H_CPU0_SA_CA<3>")
	)
	(segment
		(start 385.856226 -253.87681)
		(end 385.847844 -253.881636)
		(width 0.0889)
		(layer "In13.Cu")
		(net "M_H_CPU0_SA_CA<3>")
	)
	(segment
		(start 413.918908 -252.460252)
		(end 413.667702 -252.460252)
		(width 0.14478)
		(layer "In13.Cu")
		(net "M_H_CPU0_SA_CA<3>")
	)
	(segment
		(start 384.916172 -253.87681)
		(end 384.90779 -253.881636)
		(width 0.0889)
		(layer "In13.Cu")
		(net "M_H_CPU0_SA_CA<3>")
	)
	(segment
		(start 415.021776 -252.460252)
		(end 414.77057 -252.460252)
		(width 0.14478)
		(layer "In13.Cu")
		(net "M_H_CPU0_SA_CA<3>")
	)
	(segment
		(start 389.041894 -253.881636)
		(end 389.033512 -253.87681)
		(width 0.0889)
		(layer "In13.Cu")
		(net "M_H_CPU0_SA_CA<3>")
	)
	(segment
		(start 410.918914 -252.160024)
		(end 409.711906 -253.367032)
		(width 0.14478)
		(layer "In13.Cu")
		(net "M_H_CPU0_SA_CA<3>")
	)
	(segment
		(start 394.993876 -254.10033)
		(end 393.958064 -254.10033)
		(width 0.0889)
		(layer "In13.Cu")
		(net "M_H_CPU0_SA_CA<3>")
	)
	(segment
		(start 419.912038 -250.03506)
		(end 419.690804 -250.256294)
		(width 0.14478)
		(layer "In13.Cu")
		(net "M_H_CPU0_SA_CA<3>")
	)
	(segment
		(start 409.711906 -253.367032)
		(end 399.118074 -253.367032)
		(width 0.14478)
		(layer "In13.Cu")
		(net "M_H_CPU0_SA_CA<3>")
	)
	(segment
		(start 395.209776 -254.31623)
		(end 394.993876 -254.10033)
		(width 0.0889)
		(layer "In13.Cu")
		(net "M_H_CPU0_SA_CA<3>")
	)
	(segment
		(start 414.77057 -252.460252)
		(end 414.470342 -252.160024)
		(width 0.14478)
		(layer "In13.Cu")
		(net "M_H_CPU0_SA_CA<3>")
	)
	(segment
		(start 399.118074 -253.367032)
		(end 398.168876 -254.31623)
		(width 0.14478)
		(layer "In13.Cu")
		(net "M_H_CPU0_SA_CA<3>")
	)
	(arc
		(start 386.787898 -253.881636)
		(mid 386.504942 -253.957813)
		(end 386.221986 -253.881636)
		(width 0.0889)
		(layer "In13.Cu")
		(net "M_H_CPU0_SA_CA<3>")
	)
	(arc
		(start 390.54786 -253.881636)
		(mid 390.264904 -253.957813)
		(end 389.981948 -253.881636)
		(width 0.0889)
		(layer "In13.Cu")
		(net "M_H_CPU0_SA_CA<3>")
	)
	(arc
		(start 383.393442 -253.87681)
		(mid 383.209934 -253.831316)
		(end 383.027682 -253.881636)
		(width 0.0889)
		(layer "In13.Cu")
		(net "M_H_CPU0_SA_CA<3>")
	)
	(arc
		(start 388.667752 -253.881636)
		(mid 388.384796 -253.957813)
		(end 388.10184 -253.881636)
		(width 0.0889)
		(layer "In13.Cu")
		(net "M_H_CPU0_SA_CA<3>")
	)
	(arc
		(start 385.847844 -253.881636)
		(mid 385.564888 -253.957813)
		(end 385.281932 -253.881636)
		(width 0.0889)
		(layer "In13.Cu")
		(net "M_H_CPU0_SA_CA<3>")
	)
	(arc
		(start 389.607806 -253.881636)
		(mid 389.32485 -253.957813)
		(end 389.041894 -253.881636)
		(width 0.0889)
		(layer "In13.Cu")
		(net "M_H_CPU0_SA_CA<3>")
	)
	(arc
		(start 384.90779 -253.881636)
		(mid 384.624834 -253.957813)
		(end 384.341878 -253.881636)
		(width 0.0889)
		(layer "In13.Cu")
		(net "M_H_CPU0_SA_CA<3>")
	)
	(arc
		(start 391.48766 -253.881636)
		(mid 391.204704 -253.957813)
		(end 390.921748 -253.881636)
		(width 0.0889)
		(layer "In13.Cu")
		(net "M_H_CPU0_SA_CA<3>")
	)
	(arc
		(start 387.161786 -253.881636)
		(mid 386.974842 -253.831381)
		(end 386.787898 -253.881636)
		(width 0.0889)
		(layer "In13.Cu")
		(net "M_H_CPU0_SA_CA<3>")
	)
	(arc
		(start 392.413998 -253.890272)
		(mid 392.137015 -253.958076)
		(end 391.86231 -253.881636)
		(width 0.0889)
		(layer "In13.Cu")
		(net "M_H_CPU0_SA_CA<3>")
	)
	(arc
		(start 383.967736 -253.881636)
		(mid 383.68478 -253.957813)
		(end 383.401824 -253.881636)
		(width 0.0889)
		(layer "In13.Cu")
		(net "M_H_CPU0_SA_CA<3>")
	)
	(arc
		(start 391.86231 -253.881636)
		(mid 391.679805 -253.831159)
		(end 391.496042 -253.87681)
		(width 0.0889)
		(layer "In13.Cu")
		(net "M_H_CPU0_SA_CA<3>")
	)
	(arc
		(start 385.281932 -253.881636)
		(mid 385.099681 -253.831286)
		(end 384.916172 -253.87681)
		(width 0.0889)
		(layer "In13.Cu")
		(net "M_H_CPU0_SA_CA<3>")
	)
	(arc
		(start 386.221986 -253.881636)
		(mid 386.039735 -253.831286)
		(end 385.856226 -253.87681)
		(width 0.0889)
		(layer "In13.Cu")
		(net "M_H_CPU0_SA_CA<3>")
	)
	(arc
		(start 388.093458 -253.87681)
		(mid 387.90995 -253.831316)
		(end 387.727698 -253.881636)
		(width 0.0889)
		(layer "In13.Cu")
		(net "M_H_CPU0_SA_CA<3>")
	)
	(arc
		(start 383.027682 -253.881636)
		(mid 382.779969 -253.956856)
		(end 382.524762 -253.913386)
		(width 0.0889)
		(layer "In13.Cu")
		(net "M_H_CPU0_SA_CA<3>")
	)
	(arc
		(start 387.727698 -253.881636)
		(mid 387.444742 -253.957813)
		(end 387.161786 -253.881636)
		(width 0.0889)
		(layer "In13.Cu")
		(net "M_H_CPU0_SA_CA<3>")
	)
	(arc
		(start 389.033512 -253.87681)
		(mid 388.850004 -253.831316)
		(end 388.667752 -253.881636)
		(width 0.0889)
		(layer "In13.Cu")
		(net "M_H_CPU0_SA_CA<3>")
	)
	(arc
		(start 393.734544 -253.87681)
		(mid 393.550782 -253.831194)
		(end 393.368276 -253.881636)
		(width 0.0889)
		(layer "In13.Cu")
		(net "M_H_CPU0_SA_CA<3>")
	)
	(arc
		(start 384.333496 -253.87681)
		(mid 384.149988 -253.831316)
		(end 383.967736 -253.881636)
		(width 0.0889)
		(layer "In13.Cu")
		(net "M_H_CPU0_SA_CA<3>")
	)
	(arc
		(start 392.788648 -253.874016)
		(mid 392.607718 -253.831538)
		(end 392.42873 -253.881636)
		(width 0.0889)
		(layer "In13.Cu")
		(net "M_H_CPU0_SA_CA<3>")
	)
	(arc
		(start 393.368276 -253.881636)
		(mid 393.094421 -253.957986)
		(end 392.818112 -253.891034)
		(width 0.0889)
		(layer "In13.Cu")
		(net "M_H_CPU0_SA_CA<3>")
	)
	(arc
		(start 389.981948 -253.881636)
		(mid 389.799697 -253.831286)
		(end 389.616188 -253.87681)
		(width 0.0889)
		(layer "In13.Cu")
		(net "M_H_CPU0_SA_CA<3>")
	)
	(arc
		(start 390.921748 -253.881636)
		(mid 390.734804 -253.831381)
		(end 390.54786 -253.881636)
		(width 0.0889)
		(layer "In13.Cu")
		(net "M_H_CPU0_SA_CA<3>")
	)
	(segment
		(start 382.277874 -253.660148)
		(end 382.744726 -253.39421)
		(width 0.10668)
		(layer "F.Cu")
		(net "M_H_CPU0_SA_CA<2>")
	)
	(segment
		(start 424.012106 -249.185176)
		(end 421.78986 -249.185176)
		(width 0.14478)
		(layer "In13.Cu")
		(net "M_H_CPU0_SA_CA<2>")
	)
	(segment
		(start 415.80816 -250.726448)
		(end 415.224468 -251.31014)
		(width 0.14478)
		(layer "In13.Cu")
		(net "M_H_CPU0_SA_CA<2>")
	)
	(segment
		(start 398.894554 -252.917452)
		(end 397.952976 -253.85903)
		(width 0.14478)
		(layer "In13.Cu")
		(net "M_H_CPU0_SA_CA<2>")
	)
	(segment
		(start 393.965684 -253.791212)
		(end 393.823952 -253.708154)
		(width 0.0889)
		(layer "In13.Cu")
		(net "M_H_CPU0_SA_CA<2>")
	)
	(segment
		(start 387.26618 -253.721616)
		(end 387.257798 -253.71679)
		(width 0.0889)
		(layer "In13.Cu")
		(net "M_H_CPU0_SA_CA<2>")
	)
	(segment
		(start 393.971526 -253.78537)
		(end 393.965684 -253.791212)
		(width 0.0889)
		(layer "In13.Cu")
		(net "M_H_CPU0_SA_CA<2>")
	)
	(segment
		(start 392.332718 -253.71679)
		(end 392.321034 -253.723648)
		(width 0.0889)
		(layer "In13.Cu")
		(net "M_H_CPU0_SA_CA<2>")
	)
	(segment
		(start 409.52547 -252.917452)
		(end 398.894554 -252.917452)
		(width 0.14478)
		(layer "In13.Cu")
		(net "M_H_CPU0_SA_CA<2>")
	)
	(segment
		(start 395.664182 -253.85903)
		(end 395.227556 -253.85903)
		(width 0.0889)
		(layer "In13.Cu")
		(net "M_H_CPU0_SA_CA<2>")
	)
	(segment
		(start 391.026142 -253.721616)
		(end 391.01776 -253.71679)
		(width 0.0889)
		(layer "In13.Cu")
		(net "M_H_CPU0_SA_CA<2>")
	)
	(segment
		(start 385.751832 -253.71679)
		(end 385.74345 -253.721616)
		(width 0.0889)
		(layer "In13.Cu")
		(net "M_H_CPU0_SA_CA<2>")
	)
	(segment
		(start 421.364918 -249.610118)
		(end 418.055298 -249.610118)
		(width 0.14478)
		(layer "In13.Cu")
		(net "M_H_CPU0_SA_CA<2>")
	)
	(segment
		(start 388.206234 -253.721616)
		(end 388.197852 -253.71679)
		(width 0.0889)
		(layer "In13.Cu")
		(net "M_H_CPU0_SA_CA<2>")
	)
	(segment
		(start 392.898122 -253.716536)
		(end 392.892534 -253.713234)
		(width 0.0889)
		(layer "In13.Cu")
		(net "M_H_CPU0_SA_CA<2>")
	)
	(segment
		(start 395.153896 -253.78537)
		(end 393.971526 -253.78537)
		(width 0.0889)
		(layer "In13.Cu")
		(net "M_H_CPU0_SA_CA<2>")
	)
	(segment
		(start 382.613154 -253.742952)
		(end 382.590802 -253.65964)
		(width 0.0889)
		(layer "In13.Cu")
		(net "M_H_CPU0_SA_CA<2>")
	)
	(segment
		(start 421.78986 -249.185176)
		(end 421.364918 -249.610118)
		(width 0.14478)
		(layer "In13.Cu")
		(net "M_H_CPU0_SA_CA<2>")
	)
	(segment
		(start 391.406634 -253.708154)
		(end 391.391902 -253.71679)
		(width 0.0889)
		(layer "In13.Cu")
		(net "M_H_CPU0_SA_CA<2>")
	)
	(segment
		(start 386.691886 -253.71679)
		(end 386.683504 -253.721616)
		(width 0.0889)
		(layer "In13.Cu")
		(net "M_H_CPU0_SA_CA<2>")
	)
	(segment
		(start 392.91641 -253.72695)
		(end 392.898122 -253.716536)
		(width 0.0889)
		(layer "In13.Cu")
		(net "M_H_CPU0_SA_CA<2>")
	)
	(segment
		(start 415.224468 -251.31014)
		(end 411.132782 -251.31014)
		(width 0.14478)
		(layer "In13.Cu")
		(net "M_H_CPU0_SA_CA<2>")
	)
	(segment
		(start 418.055298 -249.610118)
		(end 416.938968 -250.726448)
		(width 0.14478)
		(layer "In13.Cu")
		(net "M_H_CPU0_SA_CA<2>")
	)
	(segment
		(start 411.132782 -251.31014)
		(end 409.52547 -252.917452)
		(width 0.14478)
		(layer "In13.Cu")
		(net "M_H_CPU0_SA_CA<2>")
	)
	(segment
		(start 383.506218 -253.721616)
		(end 383.497836 -253.71679)
		(width 0.0889)
		(layer "In13.Cu")
		(net "M_H_CPU0_SA_CA<2>")
	)
	(segment
		(start 395.227556 -253.85903)
		(end 395.153896 -253.78537)
		(width 0.0889)
		(layer "In13.Cu")
		(net "M_H_CPU0_SA_CA<2>")
	)
	(segment
		(start 390.451848 -253.71679)
		(end 390.443466 -253.721616)
		(width 0.0889)
		(layer "In13.Cu")
		(net "M_H_CPU0_SA_CA<2>")
	)
	(segment
		(start 382.590802 -253.65964)
		(end 382.744726 -253.39421)
		(width 0.0889)
		(layer "In13.Cu")
		(net "M_H_CPU0_SA_CA<2>")
	)
	(segment
		(start 416.938968 -250.726448)
		(end 415.80816 -250.726448)
		(width 0.14478)
		(layer "In13.Cu")
		(net "M_H_CPU0_SA_CA<2>")
	)
	(segment
		(start 397.952976 -253.85903)
		(end 395.664182 -253.85903)
		(width 0.14478)
		(layer "In13.Cu")
		(net "M_H_CPU0_SA_CA<2>")
	)
	(arc
		(start 391.391902 -253.71679)
		(mid 391.209651 -253.76714)
		(end 391.026142 -253.721616)
		(width 0.0889)
		(layer "In13.Cu")
		(net "M_H_CPU0_SA_CA<2>")
	)
	(arc
		(start 388.571994 -253.71679)
		(mid 388.389743 -253.76714)
		(end 388.206234 -253.721616)
		(width 0.0889)
		(layer "In13.Cu")
		(net "M_H_CPU0_SA_CA<2>")
	)
	(arc
		(start 387.63194 -253.71679)
		(mid 387.449689 -253.76714)
		(end 387.26618 -253.721616)
		(width 0.0889)
		(layer "In13.Cu")
		(net "M_H_CPU0_SA_CA<2>")
	)
	(arc
		(start 386.683504 -253.721616)
		(mid 386.499996 -253.76711)
		(end 386.317744 -253.71679)
		(width 0.0889)
		(layer "In13.Cu")
		(net "M_H_CPU0_SA_CA<2>")
	)
	(arc
		(start 389.137906 -253.71679)
		(mid 388.85495 -253.640613)
		(end 388.571994 -253.71679)
		(width 0.0889)
		(layer "In13.Cu")
		(net "M_H_CPU0_SA_CA<2>")
	)
	(arc
		(start 390.443466 -253.721616)
		(mid 390.259958 -253.76711)
		(end 390.077706 -253.71679)
		(width 0.0889)
		(layer "In13.Cu")
		(net "M_H_CPU0_SA_CA<2>")
	)
	(arc
		(start 387.257798 -253.71679)
		(mid 386.974842 -253.640613)
		(end 386.691886 -253.71679)
		(width 0.0889)
		(layer "In13.Cu")
		(net "M_H_CPU0_SA_CA<2>")
	)
	(arc
		(start 385.74345 -253.721616)
		(mid 385.559942 -253.76711)
		(end 385.37769 -253.71679)
		(width 0.0889)
		(layer "In13.Cu")
		(net "M_H_CPU0_SA_CA<2>")
	)
	(arc
		(start 388.197852 -253.71679)
		(mid 387.914896 -253.640613)
		(end 387.63194 -253.71679)
		(width 0.0889)
		(layer "In13.Cu")
		(net "M_H_CPU0_SA_CA<2>")
	)
	(arc
		(start 390.077706 -253.71679)
		(mid 389.79475 -253.640613)
		(end 389.511794 -253.71679)
		(width 0.0889)
		(layer "In13.Cu")
		(net "M_H_CPU0_SA_CA<2>")
	)
	(arc
		(start 391.958322 -253.71679)
		(mid 391.683616 -253.640426)
		(end 391.406634 -253.708154)
		(width 0.0889)
		(layer "In13.Cu")
		(net "M_H_CPU0_SA_CA<2>")
	)
	(arc
		(start 386.317744 -253.71679)
		(mid 386.034788 -253.640613)
		(end 385.751832 -253.71679)
		(width 0.0889)
		(layer "In13.Cu")
		(net "M_H_CPU0_SA_CA<2>")
	)
	(arc
		(start 384.43789 -253.71679)
		(mid 384.154934 -253.640613)
		(end 383.871978 -253.71679)
		(width 0.0889)
		(layer "In13.Cu")
		(net "M_H_CPU0_SA_CA<2>")
	)
	(arc
		(start 384.811778 -253.71679)
		(mid 384.624834 -253.767045)
		(end 384.43789 -253.71679)
		(width 0.0889)
		(layer "In13.Cu")
		(net "M_H_CPU0_SA_CA<2>")
	)
	(arc
		(start 389.511794 -253.71679)
		(mid 389.32485 -253.767045)
		(end 389.137906 -253.71679)
		(width 0.0889)
		(layer "In13.Cu")
		(net "M_H_CPU0_SA_CA<2>")
	)
	(arc
		(start 383.497836 -253.71679)
		(mid 383.21488 -253.640613)
		(end 382.931924 -253.71679)
		(width 0.0889)
		(layer "In13.Cu")
		(net "M_H_CPU0_SA_CA<2>")
	)
	(arc
		(start 393.823952 -253.708154)
		(mid 393.546969 -253.64035)
		(end 393.272264 -253.71679)
		(width 0.0889)
		(layer "In13.Cu")
		(net "M_H_CPU0_SA_CA<2>")
	)
	(arc
		(start 392.321034 -253.723648)
		(mid 392.138779 -253.767301)
		(end 391.958322 -253.71679)
		(width 0.0889)
		(layer "In13.Cu")
		(net "M_H_CPU0_SA_CA<2>")
	)
	(arc
		(start 385.37769 -253.71679)
		(mid 385.094734 -253.640613)
		(end 384.811778 -253.71679)
		(width 0.0889)
		(layer "In13.Cu")
		(net "M_H_CPU0_SA_CA<2>")
	)
	(arc
		(start 392.892534 -253.713234)
		(mid 392.612145 -253.640565)
		(end 392.332718 -253.71679)
		(width 0.0889)
		(layer "In13.Cu")
		(net "M_H_CPU0_SA_CA<2>")
	)
	(arc
		(start 393.272264 -253.71679)
		(mid 393.095636 -253.767023)
		(end 392.91641 -253.72695)
		(width 0.0889)
		(layer "In13.Cu")
		(net "M_H_CPU0_SA_CA<2>")
	)
	(arc
		(start 391.01776 -253.71679)
		(mid 390.734804 -253.640613)
		(end 390.451848 -253.71679)
		(width 0.0889)
		(layer "In13.Cu")
		(net "M_H_CPU0_SA_CA<2>")
	)
	(arc
		(start 383.871978 -253.71679)
		(mid 383.689727 -253.76714)
		(end 383.506218 -253.721616)
		(width 0.0889)
		(layer "In13.Cu")
		(net "M_H_CPU0_SA_CA<2>")
	)
	(arc
		(start 382.931924 -253.71679)
		(mid 382.775486 -253.765761)
		(end 382.613154 -253.742952)
		(width 0.0889)
		(layer "In13.Cu")
		(net "M_H_CPU0_SA_CA<2>")
	)
	(segment
		(start 383.217928 -253.660148)
		(end 383.68478 -253.39421)
		(width 0.10668)
		(layer "F.Cu")
		(net "M_H_CPU0_SA_CA<1>")
	)
	(segment
		(start 413.150812 -250.700032)
		(end 413.295592 -250.844812)
		(width 0.14478)
		(layer "In13.Cu")
		(net "M_H_CPU0_SA_CA<1>")
	)
	(segment
		(start 414.949132 -250.460002)
		(end 415.362136 -250.460002)
		(width 0.14478)
		(layer "In13.Cu")
		(net "M_H_CPU0_SA_CA<1>")
	)
	(segment
		(start 411.346904 -250.460002)
		(end 413.006032 -250.460002)
		(width 0.14478)
		(layer "In13.Cu")
		(net "M_H_CPU0_SA_CA<1>")
	)
	(segment
		(start 419.641782 -248.605294)
		(end 419.912038 -248.335038)
		(width 0.14478)
		(layer "In13.Cu")
		(net "M_H_CPU0_SA_CA<1>")
	)
	(segment
		(start 394.320522 -253.39675)
		(end 395.070838 -253.39675)
		(width 0.0889)
		(layer "In13.Cu")
		(net "M_H_CPU0_SA_CA<1>")
	)
	(segment
		(start 395.357096 -253.110492)
		(end 398.041114 -253.110492)
		(width 0.14478)
		(layer "In13.Cu")
		(net "M_H_CPU0_SA_CA<1>")
	)
	(segment
		(start 395.070838 -253.39675)
		(end 395.357096 -253.110492)
		(width 0.14478)
		(layer "In13.Cu")
		(net "M_H_CPU0_SA_CA<1>")
	)
	(segment
		(start 392.898122 -253.071884)
		(end 392.91641 -253.06147)
		(width 0.0889)
		(layer "In13.Cu")
		(net "M_H_CPU0_SA_CA<1>")
	)
	(segment
		(start 409.339034 -252.467872)
		(end 411.346904 -250.460002)
		(width 0.14478)
		(layer "In13.Cu")
		(net "M_H_CPU0_SA_CA<1>")
	)
	(segment
		(start 392.892534 -253.075186)
		(end 392.898122 -253.071884)
		(width 0.0889)
		(layer "In13.Cu")
		(net "M_H_CPU0_SA_CA<1>")
	)
	(segment
		(start 385.74345 -253.066804)
		(end 385.751832 -253.07163)
		(width 0.0889)
		(layer "In13.Cu")
		(net "M_H_CPU0_SA_CA<1>")
	)
	(segment
		(start 414.397952 -250.844812)
		(end 414.659572 -250.844812)
		(width 0.14478)
		(layer "In13.Cu")
		(net "M_H_CPU0_SA_CA<1>")
	)
	(segment
		(start 413.557212 -250.844812)
		(end 413.701992 -250.700032)
		(width 0.14478)
		(layer "In13.Cu")
		(net "M_H_CPU0_SA_CA<1>")
	)
	(segment
		(start 387.257798 -253.07163)
		(end 387.26618 -253.066804)
		(width 0.0889)
		(layer "In13.Cu")
		(net "M_H_CPU0_SA_CA<1>")
	)
	(segment
		(start 413.701992 -250.604782)
		(end 413.846772 -250.460002)
		(width 0.14478)
		(layer "In13.Cu")
		(net "M_H_CPU0_SA_CA<1>")
	)
	(segment
		(start 413.846772 -250.460002)
		(end 414.108392 -250.460002)
		(width 0.14478)
		(layer "In13.Cu")
		(net "M_H_CPU0_SA_CA<1>")
	)
	(segment
		(start 398.683734 -252.467872)
		(end 409.339034 -252.467872)
		(width 0.14478)
		(layer "In13.Cu")
		(net "M_H_CPU0_SA_CA<1>")
	)
	(segment
		(start 392.324336 -253.066804)
		(end 392.332718 -253.07163)
		(width 0.0889)
		(layer "In13.Cu")
		(net "M_H_CPU0_SA_CA<1>")
	)
	(segment
		(start 393.555982 -253.148084)
		(end 394.071856 -253.148084)
		(width 0.0889)
		(layer "In13.Cu")
		(net "M_H_CPU0_SA_CA<1>")
	)
	(segment
		(start 414.659572 -250.844812)
		(end 414.804352 -250.700032)
		(width 0.14478)
		(layer "In13.Cu")
		(net "M_H_CPU0_SA_CA<1>")
	)
	(segment
		(start 413.295592 -250.844812)
		(end 413.557212 -250.844812)
		(width 0.14478)
		(layer "In13.Cu")
		(net "M_H_CPU0_SA_CA<1>")
	)
	(segment
		(start 391.391902 -253.07163)
		(end 391.402316 -253.077726)
		(width 0.0889)
		(layer "In13.Cu")
		(net "M_H_CPU0_SA_CA<1>")
	)
	(segment
		(start 415.362136 -250.460002)
		(end 416.238944 -249.583194)
		(width 0.14478)
		(layer "In13.Cu")
		(net "M_H_CPU0_SA_CA<1>")
	)
	(segment
		(start 416.238944 -249.583194)
		(end 417.269168 -249.583194)
		(width 0.14478)
		(layer "In13.Cu")
		(net "M_H_CPU0_SA_CA<1>")
	)
	(segment
		(start 414.108392 -250.460002)
		(end 414.253172 -250.604782)
		(width 0.14478)
		(layer "In13.Cu")
		(net "M_H_CPU0_SA_CA<1>")
	)
	(segment
		(start 413.150812 -250.604782)
		(end 413.150812 -250.700032)
		(width 0.14478)
		(layer "In13.Cu")
		(net "M_H_CPU0_SA_CA<1>")
	)
	(segment
		(start 383.68478 -253.39421)
		(end 383.838958 -253.12878)
		(width 0.0889)
		(layer "In13.Cu")
		(net "M_H_CPU0_SA_CA<1>")
	)
	(segment
		(start 414.253172 -250.604782)
		(end 414.253172 -250.700032)
		(width 0.14478)
		(layer "In13.Cu")
		(net "M_H_CPU0_SA_CA<1>")
	)
	(segment
		(start 417.269168 -249.583194)
		(end 418.247068 -248.605294)
		(width 0.14478)
		(layer "In13.Cu")
		(net "M_H_CPU0_SA_CA<1>")
	)
	(segment
		(start 391.01776 -253.07163)
		(end 391.026142 -253.066804)
		(width 0.0889)
		(layer "In13.Cu")
		(net "M_H_CPU0_SA_CA<1>")
	)
	(segment
		(start 390.443466 -253.066804)
		(end 390.451848 -253.07163)
		(width 0.0889)
		(layer "In13.Cu")
		(net "M_H_CPU0_SA_CA<1>")
	)
	(segment
		(start 414.804352 -250.700032)
		(end 414.804352 -250.604782)
		(width 0.14478)
		(layer "In13.Cu")
		(net "M_H_CPU0_SA_CA<1>")
	)
	(segment
		(start 388.197852 -253.07163)
		(end 388.206234 -253.066804)
		(width 0.0889)
		(layer "In13.Cu")
		(net "M_H_CPU0_SA_CA<1>")
	)
	(segment
		(start 413.701992 -250.700032)
		(end 413.701992 -250.604782)
		(width 0.14478)
		(layer "In13.Cu")
		(net "M_H_CPU0_SA_CA<1>")
	)
	(segment
		(start 414.253172 -250.700032)
		(end 414.397952 -250.844812)
		(width 0.14478)
		(layer "In13.Cu")
		(net "M_H_CPU0_SA_CA<1>")
	)
	(segment
		(start 383.838958 -253.12878)
		(end 383.935224 -253.10338)
		(width 0.0889)
		(layer "In13.Cu")
		(net "M_H_CPU0_SA_CA<1>")
	)
	(segment
		(start 398.041114 -253.110492)
		(end 398.683734 -252.467872)
		(width 0.14478)
		(layer "In13.Cu")
		(net "M_H_CPU0_SA_CA<1>")
	)
	(segment
		(start 418.247068 -248.605294)
		(end 419.641782 -248.605294)
		(width 0.14478)
		(layer "In13.Cu")
		(net "M_H_CPU0_SA_CA<1>")
	)
	(segment
		(start 394.071856 -253.148084)
		(end 394.320522 -253.39675)
		(width 0.0889)
		(layer "In13.Cu")
		(net "M_H_CPU0_SA_CA<1>")
	)
	(segment
		(start 413.006032 -250.460002)
		(end 413.150812 -250.604782)
		(width 0.14478)
		(layer "In13.Cu")
		(net "M_H_CPU0_SA_CA<1>")
	)
	(segment
		(start 414.804352 -250.604782)
		(end 414.949132 -250.460002)
		(width 0.14478)
		(layer "In13.Cu")
		(net "M_H_CPU0_SA_CA<1>")
	)
	(segment
		(start 386.683504 -253.066804)
		(end 386.691886 -253.07163)
		(width 0.0889)
		(layer "In13.Cu")
		(net "M_H_CPU0_SA_CA<1>")
	)
	(arc
		(start 387.63194 -253.07163)
		(mid 387.914896 -253.147807)
		(end 388.197852 -253.07163)
		(width 0.0889)
		(layer "In13.Cu")
		(net "M_H_CPU0_SA_CA<1>")
	)
	(arc
		(start 390.451848 -253.07163)
		(mid 390.734804 -253.147807)
		(end 391.01776 -253.07163)
		(width 0.0889)
		(layer "In13.Cu")
		(net "M_H_CPU0_SA_CA<1>")
	)
	(arc
		(start 383.935224 -253.10338)
		(mid 384.190289 -253.146731)
		(end 384.43789 -253.07163)
		(width 0.0889)
		(layer "In13.Cu")
		(net "M_H_CPU0_SA_CA<1>")
	)
	(arc
		(start 385.751832 -253.07163)
		(mid 386.034788 -253.147807)
		(end 386.317744 -253.07163)
		(width 0.0889)
		(layer "In13.Cu")
		(net "M_H_CPU0_SA_CA<1>")
	)
	(arc
		(start 385.37769 -253.07163)
		(mid 385.559941 -253.02128)
		(end 385.74345 -253.066804)
		(width 0.0889)
		(layer "In13.Cu")
		(net "M_H_CPU0_SA_CA<1>")
	)
	(arc
		(start 388.571994 -253.07163)
		(mid 388.85495 -253.147807)
		(end 389.137906 -253.07163)
		(width 0.0889)
		(layer "In13.Cu")
		(net "M_H_CPU0_SA_CA<1>")
	)
	(arc
		(start 384.811778 -253.07163)
		(mid 385.094734 -253.147807)
		(end 385.37769 -253.07163)
		(width 0.0889)
		(layer "In13.Cu")
		(net "M_H_CPU0_SA_CA<1>")
	)
	(arc
		(start 384.43789 -253.07163)
		(mid 384.624834 -253.021375)
		(end 384.811778 -253.07163)
		(width 0.0889)
		(layer "In13.Cu")
		(net "M_H_CPU0_SA_CA<1>")
	)
	(arc
		(start 387.26618 -253.066804)
		(mid 387.449688 -253.02131)
		(end 387.63194 -253.07163)
		(width 0.0889)
		(layer "In13.Cu")
		(net "M_H_CPU0_SA_CA<1>")
	)
	(arc
		(start 392.91641 -253.06147)
		(mid 393.095639 -253.021317)
		(end 393.272264 -253.07163)
		(width 0.0889)
		(layer "In13.Cu")
		(net "M_H_CPU0_SA_CA<1>")
	)
	(arc
		(start 391.402316 -253.077726)
		(mid 391.681002 -253.147946)
		(end 391.958068 -253.07163)
		(width 0.0889)
		(layer "In13.Cu")
		(net "M_H_CPU0_SA_CA<1>")
	)
	(arc
		(start 389.137906 -253.07163)
		(mid 389.32485 -253.021375)
		(end 389.511794 -253.07163)
		(width 0.0889)
		(layer "In13.Cu")
		(net "M_H_CPU0_SA_CA<1>")
	)
	(arc
		(start 386.317744 -253.07163)
		(mid 386.499995 -253.02128)
		(end 386.683504 -253.066804)
		(width 0.0889)
		(layer "In13.Cu")
		(net "M_H_CPU0_SA_CA<1>")
	)
	(arc
		(start 388.206234 -253.066804)
		(mid 388.389742 -253.02131)
		(end 388.571994 -253.07163)
		(width 0.0889)
		(layer "In13.Cu")
		(net "M_H_CPU0_SA_CA<1>")
	)
	(arc
		(start 386.691886 -253.07163)
		(mid 386.974842 -253.147807)
		(end 387.257798 -253.07163)
		(width 0.0889)
		(layer "In13.Cu")
		(net "M_H_CPU0_SA_CA<1>")
	)
	(arc
		(start 389.511794 -253.07163)
		(mid 389.79475 -253.147807)
		(end 390.077706 -253.07163)
		(width 0.0889)
		(layer "In13.Cu")
		(net "M_H_CPU0_SA_CA<1>")
	)
	(arc
		(start 392.332718 -253.07163)
		(mid 392.612146 -253.147796)
		(end 392.892534 -253.075186)
		(width 0.0889)
		(layer "In13.Cu")
		(net "M_H_CPU0_SA_CA<1>")
	)
	(arc
		(start 391.026142 -253.066804)
		(mid 391.20965 -253.02131)
		(end 391.391902 -253.07163)
		(width 0.0889)
		(layer "In13.Cu")
		(net "M_H_CPU0_SA_CA<1>")
	)
	(arc
		(start 391.958068 -253.07163)
		(mid 392.140573 -253.021153)
		(end 392.324336 -253.066804)
		(width 0.0889)
		(layer "In13.Cu")
		(net "M_H_CPU0_SA_CA<1>")
	)
	(arc
		(start 390.077706 -253.07163)
		(mid 390.259957 -253.02128)
		(end 390.443466 -253.066804)
		(width 0.0889)
		(layer "In13.Cu")
		(net "M_H_CPU0_SA_CA<1>")
	)
	(arc
		(start 393.272264 -253.07163)
		(mid 393.409057 -253.128652)
		(end 393.555982 -253.148084)
		(width 0.0889)
		(layer "In13.Cu")
		(net "M_H_CPU0_SA_CA<1>")
	)
	(segment
		(start 383.688082 -252.850142)
		(end 384.154934 -252.584204)
		(width 0.10668)
		(layer "F.Cu")
		(net "M_H_CPU0_SA_CA<0>")
	)
	(segment
		(start 422.354502 -247.485154)
		(end 421.92956 -247.910096)
		(width 0.14478)
		(layer "In13.Cu")
		(net "M_H_CPU0_SA_CA<0>")
	)
	(segment
		(start 415.159444 -249.610118)
		(end 411.560772 -249.610118)
		(width 0.14478)
		(layer "In13.Cu")
		(net "M_H_CPU0_SA_CA<0>")
	)
	(segment
		(start 388.10184 -252.906784)
		(end 388.093458 -252.91161)
		(width 0.0889)
		(layer "In13.Cu")
		(net "M_H_CPU0_SA_CA<0>")
	)
	(segment
		(start 392.428476 -252.906784)
		(end 392.418062 -252.900688)
		(width 0.0889)
		(layer "In13.Cu")
		(net "M_H_CPU0_SA_CA<0>")
	)
	(segment
		(start 384.023108 -252.932946)
		(end 384.000756 -252.849634)
		(width 0.0889)
		(layer "In13.Cu")
		(net "M_H_CPU0_SA_CA<0>")
	)
	(segment
		(start 393.982448 -252.957584)
		(end 393.555728 -252.957584)
		(width 0.0889)
		(layer "In13.Cu")
		(net "M_H_CPU0_SA_CA<0>")
	)
	(segment
		(start 424.012106 -247.485154)
		(end 422.354502 -247.485154)
		(width 0.14478)
		(layer "In13.Cu")
		(net "M_H_CPU0_SA_CA<0>")
	)
	(segment
		(start 409.152598 -252.018292)
		(end 398.483074 -252.018292)
		(width 0.14478)
		(layer "In13.Cu")
		(net "M_H_CPU0_SA_CA<0>")
	)
	(segment
		(start 389.041894 -252.906784)
		(end 389.033512 -252.91161)
		(width 0.0889)
		(layer "In13.Cu")
		(net "M_H_CPU0_SA_CA<0>")
	)
	(segment
		(start 421.92956 -247.910096)
		(end 418.205412 -247.910096)
		(width 0.14478)
		(layer "In13.Cu")
		(net "M_H_CPU0_SA_CA<0>")
	)
	(segment
		(start 385.856226 -252.91161)
		(end 385.847844 -252.906784)
		(width 0.0889)
		(layer "In13.Cu")
		(net "M_H_CPU0_SA_CA<0>")
	)
	(segment
		(start 418.205412 -247.910096)
		(end 417.180014 -248.935494)
		(width 0.14478)
		(layer "In13.Cu")
		(net "M_H_CPU0_SA_CA<0>")
	)
	(segment
		(start 384.341878 -252.906784)
		(end 384.333496 -252.91161)
		(width 0.0889)
		(layer "In13.Cu")
		(net "M_H_CPU0_SA_CA<0>")
	)
	(segment
		(start 398.020286 -252.48108)
		(end 395.347698 -252.48108)
		(width 0.14478)
		(layer "In13.Cu")
		(net "M_H_CPU0_SA_CA<0>")
	)
	(segment
		(start 398.483074 -252.018292)
		(end 398.020286 -252.48108)
		(width 0.14478)
		(layer "In13.Cu")
		(net "M_H_CPU0_SA_CA<0>")
	)
	(segment
		(start 384.000756 -252.849634)
		(end 384.154934 -252.584204)
		(width 0.0889)
		(layer "In13.Cu")
		(net "M_H_CPU0_SA_CA<0>")
	)
	(segment
		(start 393.368022 -252.906784)
		(end 393.368276 -252.906784)
		(width 0.0889)
		(layer "In13.Cu")
		(net "M_H_CPU0_SA_CA<0>")
	)
	(segment
		(start 389.616188 -252.91161)
		(end 389.607806 -252.906784)
		(width 0.0889)
		(layer "In13.Cu")
		(net "M_H_CPU0_SA_CA<0>")
	)
	(segment
		(start 415.834068 -248.935494)
		(end 415.159444 -249.610118)
		(width 0.14478)
		(layer "In13.Cu")
		(net "M_H_CPU0_SA_CA<0>")
	)
	(segment
		(start 395.347698 -252.48108)
		(end 394.458952 -252.48108)
		(width 0.0889)
		(layer "In13.Cu")
		(net "M_H_CPU0_SA_CA<0>")
	)
	(segment
		(start 392.818112 -252.897386)
		(end 392.802364 -252.90653)
		(width 0.0889)
		(layer "In13.Cu")
		(net "M_H_CPU0_SA_CA<0>")
	)
	(segment
		(start 392.802364 -252.90653)
		(end 392.786108 -252.915928)
		(width 0.0889)
		(layer "In13.Cu")
		(net "M_H_CPU0_SA_CA<0>")
	)
	(segment
		(start 384.916172 -252.91161)
		(end 384.90779 -252.906784)
		(width 0.0889)
		(layer "In13.Cu")
		(net "M_H_CPU0_SA_CA<0>")
	)
	(segment
		(start 391.496042 -252.91161)
		(end 391.48766 -252.906784)
		(width 0.0889)
		(layer "In13.Cu")
		(net "M_H_CPU0_SA_CA<0>")
	)
	(segment
		(start 411.560772 -249.610118)
		(end 409.152598 -252.018292)
		(width 0.14478)
		(layer "In13.Cu")
		(net "M_H_CPU0_SA_CA<0>")
	)
	(segment
		(start 394.458952 -252.48108)
		(end 393.982448 -252.957584)
		(width 0.0889)
		(layer "In13.Cu")
		(net "M_H_CPU0_SA_CA<0>")
	)
	(segment
		(start 417.180014 -248.935494)
		(end 415.834068 -248.935494)
		(width 0.14478)
		(layer "In13.Cu")
		(net "M_H_CPU0_SA_CA<0>")
	)
	(arc
		(start 390.54786 -252.906784)
		(mid 390.264904 -252.830607)
		(end 389.981948 -252.906784)
		(width 0.0889)
		(layer "In13.Cu")
		(net "M_H_CPU0_SA_CA<0>")
	)
	(arc
		(start 393.368276 -252.906784)
		(mid 393.094421 -252.830434)
		(end 392.818112 -252.897386)
		(width 0.0889)
		(layer "In13.Cu")
		(net "M_H_CPU0_SA_CA<0>")
	)
	(arc
		(start 385.847844 -252.906784)
		(mid 385.564888 -252.830607)
		(end 385.281932 -252.906784)
		(width 0.0889)
		(layer "In13.Cu")
		(net "M_H_CPU0_SA_CA<0>")
	)
	(arc
		(start 393.555728 -252.957584)
		(mid 393.458503 -252.944635)
		(end 393.368022 -252.906784)
		(width 0.0889)
		(layer "In13.Cu")
		(net "M_H_CPU0_SA_CA<0>")
	)
	(arc
		(start 389.033512 -252.91161)
		(mid 388.850004 -252.957104)
		(end 388.667752 -252.906784)
		(width 0.0889)
		(layer "In13.Cu")
		(net "M_H_CPU0_SA_CA<0>")
	)
	(arc
		(start 390.921748 -252.906784)
		(mid 390.734804 -252.957039)
		(end 390.54786 -252.906784)
		(width 0.0889)
		(layer "In13.Cu")
		(net "M_H_CPU0_SA_CA<0>")
	)
	(arc
		(start 388.093458 -252.91161)
		(mid 387.90995 -252.957104)
		(end 387.727698 -252.906784)
		(width 0.0889)
		(layer "In13.Cu")
		(net "M_H_CPU0_SA_CA<0>")
	)
	(arc
		(start 384.333496 -252.91161)
		(mid 384.180626 -252.956251)
		(end 384.023108 -252.932946)
		(width 0.0889)
		(layer "In13.Cu")
		(net "M_H_CPU0_SA_CA<0>")
	)
	(arc
		(start 387.161786 -252.906784)
		(mid 386.974842 -252.957039)
		(end 386.787898 -252.906784)
		(width 0.0889)
		(layer "In13.Cu")
		(net "M_H_CPU0_SA_CA<0>")
	)
	(arc
		(start 386.787898 -252.906784)
		(mid 386.504942 -252.830607)
		(end 386.221986 -252.906784)
		(width 0.0889)
		(layer "In13.Cu")
		(net "M_H_CPU0_SA_CA<0>")
	)
	(arc
		(start 392.786108 -252.915928)
		(mid 392.606126 -252.957028)
		(end 392.428476 -252.906784)
		(width 0.0889)
		(layer "In13.Cu")
		(net "M_H_CPU0_SA_CA<0>")
	)
	(arc
		(start 387.727698 -252.906784)
		(mid 387.444742 -252.830607)
		(end 387.161786 -252.906784)
		(width 0.0889)
		(layer "In13.Cu")
		(net "M_H_CPU0_SA_CA<0>")
	)
	(arc
		(start 391.86231 -252.906784)
		(mid 391.679805 -252.957261)
		(end 391.496042 -252.91161)
		(width 0.0889)
		(layer "In13.Cu")
		(net "M_H_CPU0_SA_CA<0>")
	)
	(arc
		(start 386.221986 -252.906784)
		(mid 386.039735 -252.957134)
		(end 385.856226 -252.91161)
		(width 0.0889)
		(layer "In13.Cu")
		(net "M_H_CPU0_SA_CA<0>")
	)
	(arc
		(start 391.48766 -252.906784)
		(mid 391.204704 -252.830607)
		(end 390.921748 -252.906784)
		(width 0.0889)
		(layer "In13.Cu")
		(net "M_H_CPU0_SA_CA<0>")
	)
	(arc
		(start 385.281932 -252.906784)
		(mid 385.099681 -252.957134)
		(end 384.916172 -252.91161)
		(width 0.0889)
		(layer "In13.Cu")
		(net "M_H_CPU0_SA_CA<0>")
	)
	(arc
		(start 389.981948 -252.906784)
		(mid 389.799697 -252.957134)
		(end 389.616188 -252.91161)
		(width 0.0889)
		(layer "In13.Cu")
		(net "M_H_CPU0_SA_CA<0>")
	)
	(arc
		(start 384.90779 -252.906784)
		(mid 384.624834 -252.830607)
		(end 384.341878 -252.906784)
		(width 0.0889)
		(layer "In13.Cu")
		(net "M_H_CPU0_SA_CA<0>")
	)
	(arc
		(start 388.667752 -252.906784)
		(mid 388.384796 -252.830607)
		(end 388.10184 -252.906784)
		(width 0.0889)
		(layer "In13.Cu")
		(net "M_H_CPU0_SA_CA<0>")
	)
	(arc
		(start 392.418062 -252.900688)
		(mid 392.139376 -252.830468)
		(end 391.86231 -252.906784)
		(width 0.0889)
		(layer "In13.Cu")
		(net "M_H_CPU0_SA_CA<0>")
	)
	(arc
		(start 389.607806 -252.906784)
		(mid 389.32485 -252.830607)
		(end 389.041894 -252.906784)
		(width 0.0889)
		(layer "In13.Cu")
		(net "M_H_CPU0_SA_CA<0>")
	)
	(segment
		(start 381.807974 -251.23013)
		(end 382.274826 -250.964192)
		(width 0.10668)
		(layer "F.Cu")
		(net "M_H_CPU0_RESET_N")
	)
	(segment
		(start 419.912038 -244.934994)
		(end 419.619938 -245.227094)
		(width 0.11684)
		(layer "In13.Cu")
		(net "M_H_CPU0_RESET_N")
	)
	(segment
		(start 384.916172 -250.636786)
		(end 384.90779 -250.641612)
		(width 0.0889)
		(layer "In13.Cu")
		(net "M_H_CPU0_RESET_N")
	)
	(segment
		(start 382.42875 -250.698762)
		(end 382.274826 -250.964192)
		(width 0.0889)
		(layer "In13.Cu")
		(net "M_H_CPU0_RESET_N")
	)
	(segment
		(start 392.802364 -250.641866)
		(end 392.788648 -250.633992)
		(width 0.0889)
		(layer "In13.Cu")
		(net "M_H_CPU0_RESET_N")
	)
	(segment
		(start 395.576552 -250.67641)
		(end 395.34084 -250.67641)
		(width 0.0889)
		(layer "In13.Cu")
		(net "M_H_CPU0_RESET_N")
	)
	(segment
		(start 408.472132 -250.378722)
		(end 397.767048 -250.378722)
		(width 0.11684)
		(layer "In13.Cu")
		(net "M_H_CPU0_RESET_N")
	)
	(segment
		(start 415.095944 -246.210074)
		(end 414.245806 -247.060212)
		(width 0.11684)
		(layer "In13.Cu")
		(net "M_H_CPU0_RESET_N")
	)
	(segment
		(start 391.496042 -250.636786)
		(end 391.48766 -250.641612)
		(width 0.0889)
		(layer "In13.Cu")
		(net "M_H_CPU0_RESET_N")
	)
	(segment
		(start 382.524762 -250.673362)
		(end 382.42875 -250.698762)
		(width 0.0889)
		(layer "In13.Cu")
		(net "M_H_CPU0_RESET_N")
	)
	(segment
		(start 397.46936 -250.67641)
		(end 395.576552 -250.67641)
		(width 0.11684)
		(layer "In13.Cu")
		(net "M_H_CPU0_RESET_N")
	)
	(segment
		(start 418.193982 -245.227094)
		(end 417.211002 -246.210074)
		(width 0.11684)
		(layer "In13.Cu")
		(net "M_H_CPU0_RESET_N")
	)
	(segment
		(start 384.341878 -250.641612)
		(end 384.333496 -250.636786)
		(width 0.0889)
		(layer "In13.Cu")
		(net "M_H_CPU0_RESET_N")
	)
	(segment
		(start 383.401824 -250.641612)
		(end 383.393442 -250.636786)
		(width 0.0889)
		(layer "In13.Cu")
		(net "M_H_CPU0_RESET_N")
	)
	(segment
		(start 419.619938 -245.227094)
		(end 418.193982 -245.227094)
		(width 0.11684)
		(layer "In13.Cu")
		(net "M_H_CPU0_RESET_N")
	)
	(segment
		(start 414.245806 -247.060212)
		(end 411.790642 -247.060212)
		(width 0.11684)
		(layer "In13.Cu")
		(net "M_H_CPU0_RESET_N")
	)
	(segment
		(start 392.42873 -250.641612)
		(end 392.413998 -250.650248)
		(width 0.0889)
		(layer "In13.Cu")
		(net "M_H_CPU0_RESET_N")
	)
	(segment
		(start 385.856226 -250.636786)
		(end 385.847844 -250.641612)
		(width 0.0889)
		(layer "In13.Cu")
		(net "M_H_CPU0_RESET_N")
	)
	(segment
		(start 395.34084 -250.67641)
		(end 395.293088 -250.724162)
		(width 0.0889)
		(layer "In13.Cu")
		(net "M_H_CPU0_RESET_N")
	)
	(segment
		(start 417.211002 -246.210074)
		(end 415.095944 -246.210074)
		(width 0.11684)
		(layer "In13.Cu")
		(net "M_H_CPU0_RESET_N")
	)
	(segment
		(start 388.10184 -250.641612)
		(end 388.093458 -250.636786)
		(width 0.0889)
		(layer "In13.Cu")
		(net "M_H_CPU0_RESET_N")
	)
	(segment
		(start 389.616188 -250.636786)
		(end 389.607806 -250.641612)
		(width 0.0889)
		(layer "In13.Cu")
		(net "M_H_CPU0_RESET_N")
	)
	(segment
		(start 389.041894 -250.641612)
		(end 389.033512 -250.636786)
		(width 0.0889)
		(layer "In13.Cu")
		(net "M_H_CPU0_RESET_N")
	)
	(segment
		(start 392.818112 -250.65101)
		(end 392.802364 -250.641866)
		(width 0.0889)
		(layer "In13.Cu")
		(net "M_H_CPU0_RESET_N")
	)
	(segment
		(start 411.790642 -247.060212)
		(end 408.472132 -250.378722)
		(width 0.11684)
		(layer "In13.Cu")
		(net "M_H_CPU0_RESET_N")
	)
	(segment
		(start 397.767048 -250.378722)
		(end 397.46936 -250.67641)
		(width 0.11684)
		(layer "In13.Cu")
		(net "M_H_CPU0_RESET_N")
	)
	(segment
		(start 395.293088 -250.724162)
		(end 393.107418 -250.724162)
		(width 0.0889)
		(layer "In13.Cu")
		(net "M_H_CPU0_RESET_N")
	)
	(arc
		(start 383.393442 -250.636786)
		(mid 383.209934 -250.591292)
		(end 383.027682 -250.641612)
		(width 0.0889)
		(layer "In13.Cu")
		(net "M_H_CPU0_RESET_N")
	)
	(arc
		(start 392.788648 -250.633992)
		(mid 392.607718 -250.591514)
		(end 392.42873 -250.641612)
		(width 0.0889)
		(layer "In13.Cu")
		(net "M_H_CPU0_RESET_N")
	)
	(arc
		(start 391.86231 -250.641612)
		(mid 391.679805 -250.591135)
		(end 391.496042 -250.636786)
		(width 0.0889)
		(layer "In13.Cu")
		(net "M_H_CPU0_RESET_N")
	)
	(arc
		(start 390.54786 -250.641612)
		(mid 390.264904 -250.717789)
		(end 389.981948 -250.641612)
		(width 0.0889)
		(layer "In13.Cu")
		(net "M_H_CPU0_RESET_N")
	)
	(arc
		(start 384.333496 -250.636786)
		(mid 384.149988 -250.591292)
		(end 383.967736 -250.641612)
		(width 0.0889)
		(layer "In13.Cu")
		(net "M_H_CPU0_RESET_N")
	)
	(arc
		(start 387.727698 -250.641612)
		(mid 387.444742 -250.717789)
		(end 387.161786 -250.641612)
		(width 0.0889)
		(layer "In13.Cu")
		(net "M_H_CPU0_RESET_N")
	)
	(arc
		(start 386.221986 -250.641612)
		(mid 386.039735 -250.591262)
		(end 385.856226 -250.636786)
		(width 0.0889)
		(layer "In13.Cu")
		(net "M_H_CPU0_RESET_N")
	)
	(arc
		(start 387.161786 -250.641612)
		(mid 386.974842 -250.591357)
		(end 386.787898 -250.641612)
		(width 0.0889)
		(layer "In13.Cu")
		(net "M_H_CPU0_RESET_N")
	)
	(arc
		(start 390.921748 -250.641612)
		(mid 390.734804 -250.591357)
		(end 390.54786 -250.641612)
		(width 0.0889)
		(layer "In13.Cu")
		(net "M_H_CPU0_RESET_N")
	)
	(arc
		(start 393.107418 -250.724162)
		(mid 392.957634 -250.70787)
		(end 392.818112 -250.65101)
		(width 0.0889)
		(layer "In13.Cu")
		(net "M_H_CPU0_RESET_N")
	)
	(arc
		(start 391.48766 -250.641612)
		(mid 391.204704 -250.717789)
		(end 390.921748 -250.641612)
		(width 0.0889)
		(layer "In13.Cu")
		(net "M_H_CPU0_RESET_N")
	)
	(arc
		(start 385.847844 -250.641612)
		(mid 385.564888 -250.717789)
		(end 385.281932 -250.641612)
		(width 0.0889)
		(layer "In13.Cu")
		(net "M_H_CPU0_RESET_N")
	)
	(arc
		(start 389.607806 -250.641612)
		(mid 389.32485 -250.717789)
		(end 389.041894 -250.641612)
		(width 0.0889)
		(layer "In13.Cu")
		(net "M_H_CPU0_RESET_N")
	)
	(arc
		(start 388.093458 -250.636786)
		(mid 387.90995 -250.591292)
		(end 387.727698 -250.641612)
		(width 0.0889)
		(layer "In13.Cu")
		(net "M_H_CPU0_RESET_N")
	)
	(arc
		(start 384.90779 -250.641612)
		(mid 384.624834 -250.717789)
		(end 384.341878 -250.641612)
		(width 0.0889)
		(layer "In13.Cu")
		(net "M_H_CPU0_RESET_N")
	)
	(arc
		(start 385.281932 -250.641612)
		(mid 385.099681 -250.591262)
		(end 384.916172 -250.636786)
		(width 0.0889)
		(layer "In13.Cu")
		(net "M_H_CPU0_RESET_N")
	)
	(arc
		(start 386.787898 -250.641612)
		(mid 386.504942 -250.717789)
		(end 386.221986 -250.641612)
		(width 0.0889)
		(layer "In13.Cu")
		(net "M_H_CPU0_RESET_N")
	)
	(arc
		(start 388.667752 -250.641612)
		(mid 388.384796 -250.717789)
		(end 388.10184 -250.641612)
		(width 0.0889)
		(layer "In13.Cu")
		(net "M_H_CPU0_RESET_N")
	)
	(arc
		(start 392.413998 -250.650248)
		(mid 392.137015 -250.718052)
		(end 391.86231 -250.641612)
		(width 0.0889)
		(layer "In13.Cu")
		(net "M_H_CPU0_RESET_N")
	)
	(arc
		(start 389.981948 -250.641612)
		(mid 389.799697 -250.591262)
		(end 389.616188 -250.636786)
		(width 0.0889)
		(layer "In13.Cu")
		(net "M_H_CPU0_RESET_N")
	)
	(arc
		(start 383.027682 -250.641612)
		(mid 382.779969 -250.716832)
		(end 382.524762 -250.673362)
		(width 0.0889)
		(layer "In13.Cu")
		(net "M_H_CPU0_RESET_N")
	)
	(arc
		(start 389.033512 -250.636786)
		(mid 388.850004 -250.591292)
		(end 388.667752 -250.641612)
		(width 0.0889)
		(layer "In13.Cu")
		(net "M_H_CPU0_RESET_N")
	)
	(arc
		(start 383.967736 -250.641612)
		(mid 383.68478 -250.717789)
		(end 383.401824 -250.641612)
		(width 0.0889)
		(layer "In13.Cu")
		(net "M_H_CPU0_RESET_N")
	)
	(segment
		(start 383.688082 -256.090166)
		(end 384.154934 -255.824228)
		(width 0.14732)
		(layer "F.Cu")
		(net "M_H_CPU0_CLK_DP<0>")
	)
	(segment
		(start 413.028384 -257.51282)
		(end 413.477964 -257.51282)
		(width 0.16002)
		(layer "In13.Cu")
		(net "M_H_CPU0_CLK_DP<0>")
	)
	(segment
		(start 415.781744 -257.3528)
		(end 415.781744 -256.79781)
		(width 0.16002)
		(layer "In13.Cu")
		(net "M_H_CPU0_CLK_DP<0>")
	)
	(segment
		(start 389.035036 -256.154174)
		(end 389.043418 -256.149348)
		(width 0.09525)
		(layer "In13.Cu")
		(net "M_H_CPU0_CLK_DP<0>")
	)
	(segment
		(start 403.884638 -256.460752)
		(end 412.531306 -256.460752)
		(width 0.16002)
		(layer "In13.Cu")
		(net "M_H_CPU0_CLK_DP<0>")
	)
	(segment
		(start 391.854944 -256.154174)
		(end 391.863326 -256.149348)
		(width 0.09525)
		(layer "In13.Cu")
		(net "M_H_CPU0_CLK_DP<0>")
	)
	(segment
		(start 419.661848 -253.685294)
		(end 419.912038 -253.435104)
		(width 0.16002)
		(layer "In13.Cu")
		(net "M_H_CPU0_CLK_DP<0>")
	)
	(segment
		(start 416.46221 -256.460752)
		(end 416.799776 -256.123186)
		(width 0.16002)
		(layer "In13.Cu")
		(net "M_H_CPU0_CLK_DP<0>")
	)
	(segment
		(start 393.481306 -256.23774)
		(end 394.61567 -257.372104)
		(width 0.09525)
		(layer "In13.Cu")
		(net "M_H_CPU0_CLK_DP<0>")
	)
	(segment
		(start 384.00101 -256.089658)
		(end 384.024378 -256.176526)
		(width 0.09525)
		(layer "In13.Cu")
		(net "M_H_CPU0_CLK_DP<0>")
	)
	(segment
		(start 391.863326 -256.149348)
		(end 391.878058 -256.140712)
		(width 0.09525)
		(layer "In13.Cu")
		(net "M_H_CPU0_CLK_DP<0>")
	)
	(segment
		(start 417.335208 -255.587754)
		(end 419.237668 -253.685294)
		(width 0.16002)
		(layer "In13.Cu")
		(net "M_H_CPU0_CLK_DP<0>")
	)
	(segment
		(start 392.803888 -256.149348)
		(end 392.824716 -256.137156)
		(width 0.09525)
		(layer "In13.Cu")
		(net "M_H_CPU0_CLK_DP<0>")
	)
	(segment
		(start 419.237668 -253.685294)
		(end 419.661848 -253.685294)
		(width 0.16002)
		(layer "In13.Cu")
		(net "M_H_CPU0_CLK_DP<0>")
	)
	(segment
		(start 413.477964 -257.51282)
		(end 413.637984 -257.3528)
		(width 0.16002)
		(layer "In13.Cu")
		(net "M_H_CPU0_CLK_DP<0>")
	)
	(segment
		(start 398.833848 -257.312922)
		(end 400.321018 -255.825752)
		(width 0.16002)
		(layer "In13.Cu")
		(net "M_H_CPU0_CLK_DP<0>")
	)
	(segment
		(start 403.249638 -255.825752)
		(end 403.884638 -256.460752)
		(width 0.16002)
		(layer "In13.Cu")
		(net "M_H_CPU0_CLK_DP<0>")
	)
	(segment
		(start 413.975042 -256.460752)
		(end 414.675066 -256.460752)
		(width 0.16002)
		(layer "In13.Cu")
		(net "M_H_CPU0_CLK_DP<0>")
	)
	(segment
		(start 415.012124 -257.3528)
		(end 415.172144 -257.51282)
		(width 0.16002)
		(layer "In13.Cu")
		(net "M_H_CPU0_CLK_DP<0>")
	)
	(segment
		(start 416.118802 -256.460752)
		(end 416.46221 -256.460752)
		(width 0.16002)
		(layer "In13.Cu")
		(net "M_H_CPU0_CLK_DP<0>")
	)
	(segment
		(start 417.137596 -255.587754)
		(end 417.335208 -255.587754)
		(width 0.16002)
		(layer "In13.Cu")
		(net "M_H_CPU0_CLK_DP<0>")
	)
	(segment
		(start 415.621724 -257.51282)
		(end 415.781744 -257.3528)
		(width 0.16002)
		(layer "In13.Cu")
		(net "M_H_CPU0_CLK_DP<0>")
	)
	(segment
		(start 395.738858 -257.312922)
		(end 398.833848 -257.312922)
		(width 0.16002)
		(layer "In13.Cu")
		(net "M_H_CPU0_CLK_DP<0>")
	)
	(segment
		(start 412.531306 -256.460752)
		(end 412.868364 -256.79781)
		(width 0.16002)
		(layer "In13.Cu")
		(net "M_H_CPU0_CLK_DP<0>")
	)
	(segment
		(start 385.84632 -256.149348)
		(end 385.854702 -256.154174)
		(width 0.09525)
		(layer "In13.Cu")
		(net "M_H_CPU0_CLK_DP<0>")
	)
	(segment
		(start 384.906266 -256.149348)
		(end 384.914648 -256.154174)
		(width 0.09525)
		(layer "In13.Cu")
		(net "M_H_CPU0_CLK_DP<0>")
	)
	(segment
		(start 415.012124 -256.79781)
		(end 415.012124 -257.3528)
		(width 0.16002)
		(layer "In13.Cu")
		(net "M_H_CPU0_CLK_DP<0>")
	)
	(segment
		(start 394.61567 -257.372104)
		(end 395.656054 -257.372104)
		(width 0.09525)
		(layer "In13.Cu")
		(net "M_H_CPU0_CLK_DP<0>")
	)
	(segment
		(start 416.799776 -256.123186)
		(end 416.799776 -255.925574)
		(width 0.16002)
		(layer "In13.Cu")
		(net "M_H_CPU0_CLK_DP<0>")
	)
	(segment
		(start 412.868364 -257.3528)
		(end 413.028384 -257.51282)
		(width 0.16002)
		(layer "In13.Cu")
		(net "M_H_CPU0_CLK_DP<0>")
	)
	(segment
		(start 412.868364 -256.79781)
		(end 412.868364 -257.3528)
		(width 0.16002)
		(layer "In13.Cu")
		(net "M_H_CPU0_CLK_DP<0>")
	)
	(segment
		(start 389.606282 -256.149348)
		(end 389.614664 -256.154174)
		(width 0.09525)
		(layer "In13.Cu")
		(net "M_H_CPU0_CLK_DP<0>")
	)
	(segment
		(start 413.637984 -257.3528)
		(end 413.637984 -256.79781)
		(width 0.16002)
		(layer "In13.Cu")
		(net "M_H_CPU0_CLK_DP<0>")
	)
	(segment
		(start 415.172144 -257.51282)
		(end 415.621724 -257.51282)
		(width 0.16002)
		(layer "In13.Cu")
		(net "M_H_CPU0_CLK_DP<0>")
	)
	(segment
		(start 395.656054 -257.372104)
		(end 395.715236 -257.312922)
		(width 0.09525)
		(layer "In13.Cu")
		(net "M_H_CPU0_CLK_DP<0>")
	)
	(segment
		(start 414.675066 -256.460752)
		(end 415.012124 -256.79781)
		(width 0.16002)
		(layer "In13.Cu")
		(net "M_H_CPU0_CLK_DP<0>")
	)
	(segment
		(start 392.78941 -256.15773)
		(end 392.803888 -256.149348)
		(width 0.09525)
		(layer "In13.Cu")
		(net "M_H_CPU0_CLK_DP<0>")
	)
	(segment
		(start 416.799776 -255.925574)
		(end 417.137596 -255.587754)
		(width 0.16002)
		(layer "In13.Cu")
		(net "M_H_CPU0_CLK_DP<0>")
	)
	(segment
		(start 395.715236 -257.312922)
		(end 395.738858 -257.312922)
		(width 0.09525)
		(layer "In13.Cu")
		(net "M_H_CPU0_CLK_DP<0>")
	)
	(segment
		(start 415.781744 -256.79781)
		(end 416.118802 -256.460752)
		(width 0.16002)
		(layer "In13.Cu")
		(net "M_H_CPU0_CLK_DP<0>")
	)
	(segment
		(start 400.321018 -255.825752)
		(end 403.249638 -255.825752)
		(width 0.16002)
		(layer "In13.Cu")
		(net "M_H_CPU0_CLK_DP<0>")
	)
	(segment
		(start 413.637984 -256.79781)
		(end 413.975042 -256.460752)
		(width 0.16002)
		(layer "In13.Cu")
		(net "M_H_CPU0_CLK_DP<0>")
	)
	(segment
		(start 388.094982 -256.154174)
		(end 388.103364 -256.149348)
		(width 0.09525)
		(layer "In13.Cu")
		(net "M_H_CPU0_CLK_DP<0>")
	)
	(segment
		(start 384.33502 -256.154174)
		(end 384.343402 -256.149348)
		(width 0.09525)
		(layer "In13.Cu")
		(net "M_H_CPU0_CLK_DP<0>")
	)
	(segment
		(start 384.154934 -255.824228)
		(end 384.00101 -256.089658)
		(width 0.09525)
		(layer "In13.Cu")
		(net "M_H_CPU0_CLK_DP<0>")
	)
	(arc
		(start 384.343402 -256.149348)
		(mid 384.624834 -256.073593)
		(end 384.906266 -256.149348)
		(width 0.09525)
		(layer "In13.Cu")
		(net "M_H_CPU0_CLK_DP<0>")
	)
	(arc
		(start 388.103364 -256.149348)
		(mid 388.384796 -256.073593)
		(end 388.666228 -256.149348)
		(width 0.09525)
		(layer "In13.Cu")
		(net "M_H_CPU0_CLK_DP<0>")
	)
	(arc
		(start 391.878058 -256.140712)
		(mid 392.153517 -256.073327)
		(end 392.426698 -256.149348)
		(width 0.09525)
		(layer "In13.Cu")
		(net "M_H_CPU0_CLK_DP<0>")
	)
	(arc
		(start 391.486136 -256.149348)
		(mid 391.669911 -256.20012)
		(end 391.854944 -256.154174)
		(width 0.09525)
		(layer "In13.Cu")
		(net "M_H_CPU0_CLK_DP<0>")
	)
	(arc
		(start 385.283456 -256.149348)
		(mid 385.564888 -256.073593)
		(end 385.84632 -256.149348)
		(width 0.09525)
		(layer "In13.Cu")
		(net "M_H_CPU0_CLK_DP<0>")
	)
	(arc
		(start 388.666228 -256.149348)
		(mid 388.850003 -256.20012)
		(end 389.035036 -256.154174)
		(width 0.09525)
		(layer "In13.Cu")
		(net "M_H_CPU0_CLK_DP<0>")
	)
	(arc
		(start 393.366752 -256.149348)
		(mid 393.426887 -256.189839)
		(end 393.481306 -256.23774)
		(width 0.09525)
		(layer "In13.Cu")
		(net "M_H_CPU0_CLK_DP<0>")
	)
	(arc
		(start 390.923272 -256.149348)
		(mid 391.204704 -256.073593)
		(end 391.486136 -256.149348)
		(width 0.09525)
		(layer "In13.Cu")
		(net "M_H_CPU0_CLK_DP<0>")
	)
	(arc
		(start 392.824716 -256.137156)
		(mid 393.097321 -256.07336)
		(end 393.366752 -256.149348)
		(width 0.09525)
		(layer "In13.Cu")
		(net "M_H_CPU0_CLK_DP<0>")
	)
	(arc
		(start 386.22351 -256.149348)
		(mid 386.504942 -256.073593)
		(end 386.786374 -256.149348)
		(width 0.09525)
		(layer "In13.Cu")
		(net "M_H_CPU0_CLK_DP<0>")
	)
	(arc
		(start 392.426698 -256.149348)
		(mid 392.606977 -256.200179)
		(end 392.78941 -256.15773)
		(width 0.09525)
		(layer "In13.Cu")
		(net "M_H_CPU0_CLK_DP<0>")
	)
	(arc
		(start 387.16331 -256.149348)
		(mid 387.444742 -256.073593)
		(end 387.726174 -256.149348)
		(width 0.09525)
		(layer "In13.Cu")
		(net "M_H_CPU0_CLK_DP<0>")
	)
	(arc
		(start 390.546336 -256.149348)
		(mid 390.734804 -256.200025)
		(end 390.923272 -256.149348)
		(width 0.09525)
		(layer "In13.Cu")
		(net "M_H_CPU0_CLK_DP<0>")
	)
	(arc
		(start 389.614664 -256.154174)
		(mid 389.799696 -256.200088)
		(end 389.983472 -256.149348)
		(width 0.09525)
		(layer "In13.Cu")
		(net "M_H_CPU0_CLK_DP<0>")
	)
	(arc
		(start 384.024378 -256.176526)
		(mid 384.182128 -256.199045)
		(end 384.33502 -256.154174)
		(width 0.09525)
		(layer "In13.Cu")
		(net "M_H_CPU0_CLK_DP<0>")
	)
	(arc
		(start 385.854702 -256.154174)
		(mid 386.039734 -256.200088)
		(end 386.22351 -256.149348)
		(width 0.09525)
		(layer "In13.Cu")
		(net "M_H_CPU0_CLK_DP<0>")
	)
	(arc
		(start 387.726174 -256.149348)
		(mid 387.909949 -256.20012)
		(end 388.094982 -256.154174)
		(width 0.09525)
		(layer "In13.Cu")
		(net "M_H_CPU0_CLK_DP<0>")
	)
	(arc
		(start 389.983472 -256.149348)
		(mid 390.264904 -256.073593)
		(end 390.546336 -256.149348)
		(width 0.09525)
		(layer "In13.Cu")
		(net "M_H_CPU0_CLK_DP<0>")
	)
	(arc
		(start 389.043418 -256.149348)
		(mid 389.32485 -256.073593)
		(end 389.606282 -256.149348)
		(width 0.09525)
		(layer "In13.Cu")
		(net "M_H_CPU0_CLK_DP<0>")
	)
	(arc
		(start 386.786374 -256.149348)
		(mid 386.974842 -256.200025)
		(end 387.16331 -256.149348)
		(width 0.09525)
		(layer "In13.Cu")
		(net "M_H_CPU0_CLK_DP<0>")
	)
	(arc
		(start 384.914648 -256.154174)
		(mid 385.09968 -256.200088)
		(end 385.283456 -256.149348)
		(width 0.09525)
		(layer "In13.Cu")
		(net "M_H_CPU0_CLK_DP<0>")
	)
	(segment
		(start 383.217928 -256.900172)
		(end 383.68478 -256.634234)
		(width 0.14732)
		(layer "F.Cu")
		(net "M_H_CPU0_CLK_DN<0>")
	)
	(segment
		(start 413.940244 -257.478022)
		(end 413.940244 -256.923032)
		(width 0.16002)
		(layer "In13.Cu")
		(net "M_H_CPU0_CLK_DN<0>")
	)
	(segment
		(start 412.903162 -257.81508)
		(end 413.603186 -257.81508)
		(width 0.16002)
		(layer "In13.Cu")
		(net "M_H_CPU0_CLK_DN<0>")
	)
	(segment
		(start 414.100264 -256.763012)
		(end 414.549844 -256.763012)
		(width 0.16002)
		(layer "In13.Cu")
		(net "M_H_CPU0_CLK_DN<0>")
	)
	(segment
		(start 415.046922 -257.81508)
		(end 415.746946 -257.81508)
		(width 0.16002)
		(layer "In13.Cu")
		(net "M_H_CPU0_CLK_DN<0>")
	)
	(segment
		(start 416.084004 -257.478022)
		(end 416.084004 -256.923032)
		(width 0.16002)
		(layer "In13.Cu")
		(net "M_H_CPU0_CLK_DN<0>")
	)
	(segment
		(start 386.685028 -256.304288)
		(end 386.69341 -256.309114)
		(width 0.09525)
		(layer "In13.Cu")
		(net "M_H_CPU0_CLK_DN<0>")
	)
	(segment
		(start 414.709864 -256.923032)
		(end 414.709864 -257.478022)
		(width 0.16002)
		(layer "In13.Cu")
		(net "M_H_CPU0_CLK_DN<0>")
	)
	(segment
		(start 383.838704 -256.368804)
		(end 383.939542 -256.342134)
		(width 0.09525)
		(layer "In13.Cu")
		(net "M_H_CPU0_CLK_DN<0>")
	)
	(segment
		(start 412.566104 -256.923032)
		(end 412.566104 -257.478022)
		(width 0.16002)
		(layer "In13.Cu")
		(net "M_H_CPU0_CLK_DN<0>")
	)
	(segment
		(start 395.738858 -257.615182)
		(end 398.95907 -257.615182)
		(width 0.16002)
		(layer "In13.Cu")
		(net "M_H_CPU0_CLK_DN<0>")
	)
	(segment
		(start 414.549844 -256.763012)
		(end 414.709864 -256.923032)
		(width 0.16002)
		(layer "In13.Cu")
		(net "M_H_CPU0_CLK_DN<0>")
	)
	(segment
		(start 416.244024 -256.763012)
		(end 416.587432 -256.763012)
		(width 0.16002)
		(layer "In13.Cu")
		(net "M_H_CPU0_CLK_DN<0>")
	)
	(segment
		(start 414.709864 -257.478022)
		(end 415.046922 -257.81508)
		(width 0.16002)
		(layer "In13.Cu")
		(net "M_H_CPU0_CLK_DN<0>")
	)
	(segment
		(start 419.36289 -253.987554)
		(end 419.614604 -253.987554)
		(width 0.16002)
		(layer "In13.Cu")
		(net "M_H_CPU0_CLK_DN<0>")
	)
	(segment
		(start 413.603186 -257.81508)
		(end 413.940244 -257.478022)
		(width 0.16002)
		(layer "In13.Cu")
		(net "M_H_CPU0_CLK_DN<0>")
	)
	(segment
		(start 416.084004 -256.923032)
		(end 416.244024 -256.763012)
		(width 0.16002)
		(layer "In13.Cu")
		(net "M_H_CPU0_CLK_DN<0>")
	)
	(segment
		(start 400.44624 -256.128012)
		(end 403.124416 -256.128012)
		(width 0.16002)
		(layer "In13.Cu")
		(net "M_H_CPU0_CLK_DN<0>")
	)
	(segment
		(start 391.95629 -256.309114)
		(end 391.968228 -256.302256)
		(width 0.09525)
		(layer "In13.Cu")
		(net "M_H_CPU0_CLK_DN<0>")
	)
	(segment
		(start 391.016236 -256.309114)
		(end 391.024618 -256.304288)
		(width 0.09525)
		(layer "In13.Cu")
		(net "M_H_CPU0_CLK_DN<0>")
	)
	(segment
		(start 416.587432 -256.763012)
		(end 419.36289 -253.987554)
		(width 0.16002)
		(layer "In13.Cu")
		(net "M_H_CPU0_CLK_DN<0>")
	)
	(segment
		(start 415.746946 -257.81508)
		(end 416.084004 -257.478022)
		(width 0.16002)
		(layer "In13.Cu")
		(net "M_H_CPU0_CLK_DN<0>")
	)
	(segment
		(start 385.744974 -256.304288)
		(end 385.753356 -256.309114)
		(width 0.09525)
		(layer "In13.Cu")
		(net "M_H_CPU0_CLK_DN<0>")
	)
	(segment
		(start 403.124416 -256.128012)
		(end 403.759416 -256.763012)
		(width 0.16002)
		(layer "In13.Cu")
		(net "M_H_CPU0_CLK_DN<0>")
	)
	(segment
		(start 413.940244 -256.923032)
		(end 414.100264 -256.763012)
		(width 0.16002)
		(layer "In13.Cu")
		(net "M_H_CPU0_CLK_DN<0>")
	)
	(segment
		(start 387.256274 -256.309114)
		(end 387.264656 -256.304288)
		(width 0.09525)
		(layer "In13.Cu")
		(net "M_H_CPU0_CLK_DN<0>")
	)
	(segment
		(start 419.614604 -253.987554)
		(end 419.912038 -254.284988)
		(width 0.16002)
		(layer "In13.Cu")
		(net "M_H_CPU0_CLK_DN<0>")
	)
	(segment
		(start 383.68478 -256.634234)
		(end 383.838704 -256.368804)
		(width 0.09525)
		(layer "In13.Cu")
		(net "M_H_CPU0_CLK_DN<0>")
	)
	(segment
		(start 412.406084 -256.763012)
		(end 412.566104 -256.923032)
		(width 0.16002)
		(layer "In13.Cu")
		(net "M_H_CPU0_CLK_DN<0>")
	)
	(segment
		(start 398.95907 -257.615182)
		(end 400.44624 -256.128012)
		(width 0.16002)
		(layer "In13.Cu")
		(net "M_H_CPU0_CLK_DN<0>")
	)
	(segment
		(start 403.759416 -256.763012)
		(end 412.406084 -256.763012)
		(width 0.16002)
		(layer "In13.Cu")
		(net "M_H_CPU0_CLK_DN<0>")
	)
	(segment
		(start 393.351004 -256.368042)
		(end 394.539216 -257.556254)
		(width 0.09525)
		(layer "In13.Cu")
		(net "M_H_CPU0_CLK_DN<0>")
	)
	(segment
		(start 390.44499 -256.304288)
		(end 390.453372 -256.309114)
		(width 0.09525)
		(layer "In13.Cu")
		(net "M_H_CPU0_CLK_DN<0>")
	)
	(segment
		(start 394.539216 -257.556254)
		(end 395.656308 -257.556254)
		(width 0.09525)
		(layer "In13.Cu")
		(net "M_H_CPU0_CLK_DN<0>")
	)
	(segment
		(start 412.566104 -257.478022)
		(end 412.903162 -257.81508)
		(width 0.16002)
		(layer "In13.Cu")
		(net "M_H_CPU0_CLK_DN<0>")
	)
	(segment
		(start 395.656308 -257.556254)
		(end 395.715236 -257.615182)
		(width 0.09525)
		(layer "In13.Cu")
		(net "M_H_CPU0_CLK_DN<0>")
	)
	(segment
		(start 395.715236 -257.615182)
		(end 395.738858 -257.615182)
		(width 0.09525)
		(layer "In13.Cu")
		(net "M_H_CPU0_CLK_DN<0>")
	)
	(segment
		(start 388.196328 -256.309114)
		(end 388.20471 -256.304288)
		(width 0.09525)
		(layer "In13.Cu")
		(net "M_H_CPU0_CLK_DN<0>")
	)
	(segment
		(start 392.87577 -256.321306)
		(end 392.911076 -256.300732)
		(width 0.09525)
		(layer "In13.Cu")
		(net "M_H_CPU0_CLK_DN<0>")
	)
	(arc
		(start 388.20471 -256.304288)
		(mid 388.389742 -256.258374)
		(end 388.573518 -256.309114)
		(width 0.09525)
		(layer "In13.Cu")
		(net "M_H_CPU0_CLK_DN<0>")
	)
	(arc
		(start 392.333734 -256.309114)
		(mid 392.603167 -256.384985)
		(end 392.87577 -256.321306)
		(width 0.09525)
		(layer "In13.Cu")
		(net "M_H_CPU0_CLK_DN<0>")
	)
	(arc
		(start 391.393426 -256.309114)
		(mid 391.674858 -256.384869)
		(end 391.95629 -256.309114)
		(width 0.09525)
		(layer "In13.Cu")
		(net "M_H_CPU0_CLK_DN<0>")
	)
	(arc
		(start 387.264656 -256.304288)
		(mid 387.449688 -256.258374)
		(end 387.633464 -256.309114)
		(width 0.09525)
		(layer "In13.Cu")
		(net "M_H_CPU0_CLK_DN<0>")
	)
	(arc
		(start 385.376166 -256.309114)
		(mid 385.559941 -256.258342)
		(end 385.744974 -256.304288)
		(width 0.09525)
		(layer "In13.Cu")
		(net "M_H_CPU0_CLK_DN<0>")
	)
	(arc
		(start 390.453372 -256.309114)
		(mid 390.734804 -256.384869)
		(end 391.016236 -256.309114)
		(width 0.09525)
		(layer "In13.Cu")
		(net "M_H_CPU0_CLK_DN<0>")
	)
	(arc
		(start 384.436366 -256.309114)
		(mid 384.624834 -256.258437)
		(end 384.813302 -256.309114)
		(width 0.09525)
		(layer "In13.Cu")
		(net "M_H_CPU0_CLK_DN<0>")
	)
	(arc
		(start 386.31622 -256.309114)
		(mid 386.499995 -256.258342)
		(end 386.685028 -256.304288)
		(width 0.09525)
		(layer "In13.Cu")
		(net "M_H_CPU0_CLK_DN<0>")
	)
	(arc
		(start 388.573518 -256.309114)
		(mid 388.85495 -256.384869)
		(end 389.136382 -256.309114)
		(width 0.09525)
		(layer "In13.Cu")
		(net "M_H_CPU0_CLK_DN<0>")
	)
	(arc
		(start 386.69341 -256.309114)
		(mid 386.974842 -256.384869)
		(end 387.256274 -256.309114)
		(width 0.09525)
		(layer "In13.Cu")
		(net "M_H_CPU0_CLK_DN<0>")
	)
	(arc
		(start 383.939542 -256.342134)
		(mid 383.94979 -256.346297)
		(end 383.960116 -256.350262)
		(width 0.09525)
		(layer "In13.Cu")
		(net "M_H_CPU0_CLK_DN<0>")
	)
	(arc
		(start 391.024618 -256.304288)
		(mid 391.20965 -256.258374)
		(end 391.393426 -256.309114)
		(width 0.09525)
		(layer "In13.Cu")
		(net "M_H_CPU0_CLK_DN<0>")
	)
	(arc
		(start 391.968228 -256.302256)
		(mid 392.151863 -256.258306)
		(end 392.333734 -256.309114)
		(width 0.09525)
		(layer "In13.Cu")
		(net "M_H_CPU0_CLK_DN<0>")
	)
	(arc
		(start 392.911076 -256.300732)
		(mid 393.093508 -256.258292)
		(end 393.273788 -256.309114)
		(width 0.09525)
		(layer "In13.Cu")
		(net "M_H_CPU0_CLK_DN<0>")
	)
	(arc
		(start 393.273788 -256.309114)
		(mid 393.314312 -256.336069)
		(end 393.351004 -256.368042)
		(width 0.09525)
		(layer "In13.Cu")
		(net "M_H_CPU0_CLK_DN<0>")
	)
	(arc
		(start 387.633464 -256.309114)
		(mid 387.914896 -256.384869)
		(end 388.196328 -256.309114)
		(width 0.09525)
		(layer "In13.Cu")
		(net "M_H_CPU0_CLK_DN<0>")
	)
	(arc
		(start 389.513318 -256.309114)
		(mid 389.79475 -256.384869)
		(end 390.076182 -256.309114)
		(width 0.09525)
		(layer "In13.Cu")
		(net "M_H_CPU0_CLK_DN<0>")
	)
	(arc
		(start 383.960116 -256.350262)
		(mid 384.202858 -256.383032)
		(end 384.436366 -256.309114)
		(width 0.09525)
		(layer "In13.Cu")
		(net "M_H_CPU0_CLK_DN<0>")
	)
	(arc
		(start 385.753356 -256.309114)
		(mid 386.034788 -256.384869)
		(end 386.31622 -256.309114)
		(width 0.09525)
		(layer "In13.Cu")
		(net "M_H_CPU0_CLK_DN<0>")
	)
	(arc
		(start 390.076182 -256.309114)
		(mid 390.259957 -256.258342)
		(end 390.44499 -256.304288)
		(width 0.09525)
		(layer "In13.Cu")
		(net "M_H_CPU0_CLK_DN<0>")
	)
	(arc
		(start 384.813302 -256.309114)
		(mid 385.094734 -256.384869)
		(end 385.376166 -256.309114)
		(width 0.09525)
		(layer "In13.Cu")
		(net "M_H_CPU0_CLK_DN<0>")
	)
	(arc
		(start 389.136382 -256.309114)
		(mid 389.32485 -256.258437)
		(end 389.513318 -256.309114)
		(width 0.09525)
		(layer "In13.Cu")
		(net "M_H_CPU0_CLK_DN<0>")
	)
	(segment
		(start 382.277874 -250.420124)
		(end 382.744726 -250.154186)
		(width 0.10668)
		(layer "F.Cu")
		(net "M_H_CPU0_ALERT_R_N")
	)
	(segment
		(start 413.925004 -246.210074)
		(end 414.577784 -245.557294)
		(width 0.11684)
		(layer "In13.Cu")
		(net "M_H_CPU0_ALERT_R_N")
	)
	(segment
		(start 395.418818 -250.209812)
		(end 397.263874 -250.209812)
		(width 0.11684)
		(layer "In13.Cu")
		(net "M_H_CPU0_ALERT_R_N")
	)
	(segment
		(start 392.892534 -250.47321)
		(end 392.898122 -250.476512)
		(width 0.0889)
		(layer "In13.Cu")
		(net "M_H_CPU0_ALERT_R_N")
	)
	(segment
		(start 397.516604 -249.957082)
		(end 408.29738 -249.957082)
		(width 0.11684)
		(layer "In13.Cu")
		(net "M_H_CPU0_ALERT_R_N")
	)
	(segment
		(start 391.01776 -250.476766)
		(end 391.026142 -250.481592)
		(width 0.0889)
		(layer "In13.Cu")
		(net "M_H_CPU0_ALERT_R_N")
	)
	(segment
		(start 390.443466 -250.481592)
		(end 390.451848 -250.476766)
		(width 0.0889)
		(layer "In13.Cu")
		(net "M_H_CPU0_ALERT_R_N")
	)
	(segment
		(start 421.661844 -244.08511)
		(end 422.615106 -244.08511)
		(width 0.11684)
		(layer "In13.Cu")
		(net "M_H_CPU0_ALERT_R_N")
	)
	(segment
		(start 395.097508 -250.37669)
		(end 395.264386 -250.209812)
		(width 0.0889)
		(layer "In13.Cu")
		(net "M_H_CPU0_ALERT_R_N")
	)
	(segment
		(start 386.683504 -250.481592)
		(end 386.691886 -250.476766)
		(width 0.0889)
		(layer "In13.Cu")
		(net "M_H_CPU0_ALERT_R_N")
	)
	(segment
		(start 397.263874 -250.209812)
		(end 397.516604 -249.957082)
		(width 0.11684)
		(layer "In13.Cu")
		(net "M_H_CPU0_ALERT_R_N")
	)
	(segment
		(start 408.29738 -249.957082)
		(end 412.044388 -246.210074)
		(width 0.11684)
		(layer "In13.Cu")
		(net "M_H_CPU0_ALERT_R_N")
	)
	(segment
		(start 391.391902 -250.476766)
		(end 391.406634 -250.46813)
		(width 0.0889)
		(layer "In13.Cu")
		(net "M_H_CPU0_ALERT_R_N")
	)
	(segment
		(start 393.618974 -250.37669)
		(end 395.097508 -250.37669)
		(width 0.0889)
		(layer "In13.Cu")
		(net "M_H_CPU0_ALERT_R_N")
	)
	(segment
		(start 395.264386 -250.209812)
		(end 395.418818 -250.209812)
		(width 0.0889)
		(layer "In13.Cu")
		(net "M_H_CPU0_ALERT_R_N")
	)
	(segment
		(start 385.74345 -250.481592)
		(end 385.751832 -250.476766)
		(width 0.0889)
		(layer "In13.Cu")
		(net "M_H_CPU0_ALERT_R_N")
	)
	(segment
		(start 412.044388 -246.210074)
		(end 413.925004 -246.210074)
		(width 0.11684)
		(layer "In13.Cu")
		(net "M_H_CPU0_ALERT_R_N")
	)
	(segment
		(start 388.197852 -250.476766)
		(end 388.206234 -250.481592)
		(width 0.0889)
		(layer "In13.Cu")
		(net "M_H_CPU0_ALERT_R_N")
	)
	(segment
		(start 387.257798 -250.476766)
		(end 387.26618 -250.481592)
		(width 0.0889)
		(layer "In13.Cu")
		(net "M_H_CPU0_ALERT_R_N")
	)
	(segment
		(start 421.236902 -244.510052)
		(end 421.661844 -244.08511)
		(width 0.11684)
		(layer "In13.Cu")
		(net "M_H_CPU0_ALERT_R_N")
	)
	(segment
		(start 392.321034 -250.483624)
		(end 392.332718 -250.476766)
		(width 0.0889)
		(layer "In13.Cu")
		(net "M_H_CPU0_ALERT_R_N")
	)
	(segment
		(start 416.847528 -245.557294)
		(end 417.89477 -244.510052)
		(width 0.11684)
		(layer "In13.Cu")
		(net "M_H_CPU0_ALERT_R_N")
	)
	(segment
		(start 382.744726 -250.154186)
		(end 382.590802 -250.419616)
		(width 0.0889)
		(layer "In13.Cu")
		(net "M_H_CPU0_ALERT_R_N")
	)
	(segment
		(start 382.590802 -250.419616)
		(end 382.613154 -250.502928)
		(width 0.0889)
		(layer "In13.Cu")
		(net "M_H_CPU0_ALERT_R_N")
	)
	(segment
		(start 392.898122 -250.476512)
		(end 392.91641 -250.486926)
		(width 0.0889)
		(layer "In13.Cu")
		(net "M_H_CPU0_ALERT_R_N")
	)
	(segment
		(start 417.89477 -244.510052)
		(end 421.236902 -244.510052)
		(width 0.11684)
		(layer "In13.Cu")
		(net "M_H_CPU0_ALERT_R_N")
	)
	(segment
		(start 383.497836 -250.476766)
		(end 383.506218 -250.481592)
		(width 0.0889)
		(layer "In13.Cu")
		(net "M_H_CPU0_ALERT_R_N")
	)
	(segment
		(start 414.577784 -245.557294)
		(end 416.847528 -245.557294)
		(width 0.11684)
		(layer "In13.Cu")
		(net "M_H_CPU0_ALERT_R_N")
	)
	(arc
		(start 382.931924 -250.476766)
		(mid 383.21488 -250.400589)
		(end 383.497836 -250.476766)
		(width 0.0889)
		(layer "In13.Cu")
		(net "M_H_CPU0_ALERT_R_N")
	)
	(arc
		(start 383.871978 -250.476766)
		(mid 384.154934 -250.400589)
		(end 384.43789 -250.476766)
		(width 0.0889)
		(layer "In13.Cu")
		(net "M_H_CPU0_ALERT_R_N")
	)
	(arc
		(start 384.43789 -250.476766)
		(mid 384.624834 -250.527021)
		(end 384.811778 -250.476766)
		(width 0.0889)
		(layer "In13.Cu")
		(net "M_H_CPU0_ALERT_R_N")
	)
	(arc
		(start 393.272264 -250.476766)
		(mid 393.439464 -250.405407)
		(end 393.618974 -250.37669)
		(width 0.0889)
		(layer "In13.Cu")
		(net "M_H_CPU0_ALERT_R_N")
	)
	(arc
		(start 389.137906 -250.476766)
		(mid 389.32485 -250.527021)
		(end 389.511794 -250.476766)
		(width 0.0889)
		(layer "In13.Cu")
		(net "M_H_CPU0_ALERT_R_N")
	)
	(arc
		(start 392.91641 -250.486926)
		(mid 393.095639 -250.527079)
		(end 393.272264 -250.476766)
		(width 0.0889)
		(layer "In13.Cu")
		(net "M_H_CPU0_ALERT_R_N")
	)
	(arc
		(start 386.691886 -250.476766)
		(mid 386.974842 -250.400589)
		(end 387.257798 -250.476766)
		(width 0.0889)
		(layer "In13.Cu")
		(net "M_H_CPU0_ALERT_R_N")
	)
	(arc
		(start 391.406634 -250.46813)
		(mid 391.683617 -250.400326)
		(end 391.958322 -250.476766)
		(width 0.0889)
		(layer "In13.Cu")
		(net "M_H_CPU0_ALERT_R_N")
	)
	(arc
		(start 384.811778 -250.476766)
		(mid 385.094734 -250.400589)
		(end 385.37769 -250.476766)
		(width 0.0889)
		(layer "In13.Cu")
		(net "M_H_CPU0_ALERT_R_N")
	)
	(arc
		(start 391.958322 -250.476766)
		(mid 392.13878 -250.52721)
		(end 392.321034 -250.483624)
		(width 0.0889)
		(layer "In13.Cu")
		(net "M_H_CPU0_ALERT_R_N")
	)
	(arc
		(start 390.451848 -250.476766)
		(mid 390.734804 -250.400589)
		(end 391.01776 -250.476766)
		(width 0.0889)
		(layer "In13.Cu")
		(net "M_H_CPU0_ALERT_R_N")
	)
	(arc
		(start 386.317744 -250.476766)
		(mid 386.499995 -250.527116)
		(end 386.683504 -250.481592)
		(width 0.0889)
		(layer "In13.Cu")
		(net "M_H_CPU0_ALERT_R_N")
	)
	(arc
		(start 383.506218 -250.481592)
		(mid 383.689726 -250.527086)
		(end 383.871978 -250.476766)
		(width 0.0889)
		(layer "In13.Cu")
		(net "M_H_CPU0_ALERT_R_N")
	)
	(arc
		(start 387.26618 -250.481592)
		(mid 387.449688 -250.527086)
		(end 387.63194 -250.476766)
		(width 0.0889)
		(layer "In13.Cu")
		(net "M_H_CPU0_ALERT_R_N")
	)
	(arc
		(start 387.63194 -250.476766)
		(mid 387.914896 -250.400589)
		(end 388.197852 -250.476766)
		(width 0.0889)
		(layer "In13.Cu")
		(net "M_H_CPU0_ALERT_R_N")
	)
	(arc
		(start 391.026142 -250.481592)
		(mid 391.20965 -250.527086)
		(end 391.391902 -250.476766)
		(width 0.0889)
		(layer "In13.Cu")
		(net "M_H_CPU0_ALERT_R_N")
	)
	(arc
		(start 388.206234 -250.481592)
		(mid 388.389742 -250.527086)
		(end 388.571994 -250.476766)
		(width 0.0889)
		(layer "In13.Cu")
		(net "M_H_CPU0_ALERT_R_N")
	)
	(arc
		(start 385.37769 -250.476766)
		(mid 385.559941 -250.527116)
		(end 385.74345 -250.481592)
		(width 0.0889)
		(layer "In13.Cu")
		(net "M_H_CPU0_ALERT_R_N")
	)
	(arc
		(start 390.077706 -250.476766)
		(mid 390.259957 -250.527116)
		(end 390.443466 -250.481592)
		(width 0.0889)
		(layer "In13.Cu")
		(net "M_H_CPU0_ALERT_R_N")
	)
	(arc
		(start 385.751832 -250.476766)
		(mid 386.034788 -250.400589)
		(end 386.317744 -250.476766)
		(width 0.0889)
		(layer "In13.Cu")
		(net "M_H_CPU0_ALERT_R_N")
	)
	(arc
		(start 392.332718 -250.476766)
		(mid 392.612146 -250.4006)
		(end 392.892534 -250.47321)
		(width 0.0889)
		(layer "In13.Cu")
		(net "M_H_CPU0_ALERT_R_N")
	)
	(arc
		(start 389.511794 -250.476766)
		(mid 389.79475 -250.400589)
		(end 390.077706 -250.476766)
		(width 0.0889)
		(layer "In13.Cu")
		(net "M_H_CPU0_ALERT_R_N")
	)
	(arc
		(start 388.571994 -250.476766)
		(mid 388.85495 -250.400589)
		(end 389.137906 -250.476766)
		(width 0.0889)
		(layer "In13.Cu")
		(net "M_H_CPU0_ALERT_R_N")
	)
	(arc
		(start 382.613154 -250.502928)
		(mid 382.775486 -250.525746)
		(end 382.931924 -250.476766)
		(width 0.0889)
		(layer "In13.Cu")
		(net "M_H_CPU0_ALERT_R_N")
	)
	(via
		(at 424.012106 -244.08511)
		(size 0.4826)
		(drill 0.254)
		(layers "F.Cu" "B.Cu")
		(net "M_H_CPU0_ALERT_N")
	)
	(segment
		(start 423.415206 -244.08511)
		(end 424.012106 -244.08511)
		(width 0.10668)
		(layer "B.Cu")
		(net "M_H_CPU0_ALERT_N")
	)
	(segment
		(start 146.096482 -267.66774)
		(end 146.104864 -267.662914)
		(width 0.0762)
		(layer "F.Cu")
		(net "M_G_CPU1_SB_RSP<0>")
	)
	(segment
		(start 166.206424 -270.860266)
		(end 166.631366 -270.435324)
		(width 0.101346)
		(layer "F.Cu")
		(net "M_G_CPU1_SB_RSP<0>")
	)
	(segment
		(start 147.51685 -267.42517)
		(end 147.757896 -267.42517)
		(width 0.0762)
		(layer "F.Cu")
		(net "M_G_CPU1_SB_RSP<0>")
	)
	(segment
		(start 166.631366 -270.435324)
		(end 168.527984 -270.435324)
		(width 0.101346)
		(layer "F.Cu")
		(net "M_G_CPU1_SB_RSP<0>")
	)
	(segment
		(start 149.238462 -267.42517)
		(end 149.763734 -267.950442)
		(width 0.10668)
		(layer "F.Cu")
		(net "M_G_CPU1_SB_RSP<0>")
	)
	(segment
		(start 163.609782 -270.860266)
		(end 166.206424 -270.860266)
		(width 0.101346)
		(layer "F.Cu")
		(net "M_G_CPU1_SB_RSP<0>")
	)
	(segment
		(start 145.91792 -267.340334)
		(end 145.815558 -267.51661)
		(width 0.0762)
		(layer "F.Cu")
		(net "M_G_CPU1_SB_RSP<0>")
	)
	(segment
		(start 147.355306 -267.586714)
		(end 147.51685 -267.42517)
		(width 0.0762)
		(layer "F.Cu")
		(net "M_G_CPU1_SB_RSP<0>")
	)
	(segment
		(start 160.699958 -267.950442)
		(end 163.447476 -270.69796)
		(width 0.10668)
		(layer "F.Cu")
		(net "M_G_CPU1_SB_RSP<0>")
	)
	(segment
		(start 149.763734 -267.950442)
		(end 160.699958 -267.950442)
		(width 0.10668)
		(layer "F.Cu")
		(net "M_G_CPU1_SB_RSP<0>")
	)
	(segment
		(start 146.387566 -267.586714)
		(end 147.355306 -267.586714)
		(width 0.0762)
		(layer "F.Cu")
		(net "M_G_CPU1_SB_RSP<0>")
	)
	(segment
		(start 163.447476 -270.69796)
		(end 163.609782 -270.860266)
		(width 0.101346)
		(layer "F.Cu")
		(net "M_G_CPU1_SB_RSP<0>")
	)
	(segment
		(start 147.757896 -267.42517)
		(end 149.238462 -267.42517)
		(width 0.10668)
		(layer "F.Cu")
		(net "M_G_CPU1_SB_RSP<0>")
	)
	(arc
		(start 146.340576 -267.588492)
		(mid 146.364053 -267.587116)
		(end 146.387566 -267.586714)
		(width 0.0762)
		(layer "F.Cu")
		(net "M_G_CPU1_SB_RSP<0>")
	)
	(arc
		(start 146.104864 -267.662914)
		(mid 146.218588 -267.612613)
		(end 146.340576 -267.588492)
		(width 0.0762)
		(layer "F.Cu")
		(net "M_G_CPU1_SB_RSP<0>")
	)
	(arc
		(start 145.815558 -267.51661)
		(mid 145.845187 -267.659097)
		(end 145.982436 -267.707618)
		(width 0.0762)
		(layer "F.Cu")
		(net "M_G_CPU1_SB_RSP<0>")
	)
	(arc
		(start 145.982436 -267.707618)
		(mid 146.041082 -267.692325)
		(end 146.096482 -267.66774)
		(width 0.0762)
		(layer "F.Cu")
		(net "M_G_CPU1_SB_RSP<0>")
	)
	(segment
		(start 156.798772 -266.248642)
		(end 157.277562 -266.248642)
		(width 0.10668)
		(layer "F.Cu")
		(net "M_G_CPU1_SB_PAR")
	)
	(segment
		(start 156.399738 -265.909806)
		(end 156.565092 -265.909806)
		(width 0.10668)
		(layer "F.Cu")
		(net "M_G_CPU1_SB_PAR")
	)
	(segment
		(start 161.225738 -264.962386)
		(end 161.342578 -265.079226)
		(width 0.10668)
		(layer "F.Cu")
		(net "M_G_CPU1_SB_PAR")
	)
	(segment
		(start 144.686528 -265.237722)
		(end 144.69491 -265.232896)
		(width 0.0762)
		(layer "F.Cu")
		(net "M_G_CPU1_SB_PAR")
	)
	(segment
		(start 145.260822 -265.232896)
		(end 145.261076 -265.232896)
		(width 0.0762)
		(layer "F.Cu")
		(net "M_G_CPU1_SB_PAR")
	)
	(segment
		(start 160.262316 -264.962386)
		(end 160.42767 -264.962386)
		(width 0.10668)
		(layer "F.Cu")
		(net "M_G_CPU1_SB_PAR")
	)
	(segment
		(start 153.888694 -266.026646)
		(end 154.005534 -265.909806)
		(width 0.10668)
		(layer "F.Cu")
		(net "M_G_CPU1_SB_PAR")
	)
	(segment
		(start 159.065214 -265.450574)
		(end 159.230568 -265.450574)
		(width 0.10668)
		(layer "F.Cu")
		(net "M_G_CPU1_SB_PAR")
	)
	(segment
		(start 160.145476 -265.333734)
		(end 160.145476 -265.079226)
		(width 0.10668)
		(layer "F.Cu")
		(net "M_G_CPU1_SB_PAR")
	)
	(segment
		(start 160.66135 -265.450574)
		(end 160.826704 -265.450574)
		(width 0.10668)
		(layer "F.Cu")
		(net "M_G_CPU1_SB_PAR")
	)
	(segment
		(start 155.48483 -266.026646)
		(end 155.60167 -265.909806)
		(width 0.10668)
		(layer "F.Cu")
		(net "M_G_CPU1_SB_PAR")
	)
	(segment
		(start 156.282898 -266.026646)
		(end 156.399738 -265.909806)
		(width 0.10668)
		(layer "F.Cu")
		(net "M_G_CPU1_SB_PAR")
	)
	(segment
		(start 159.464248 -264.962386)
		(end 159.629602 -264.962386)
		(width 0.10668)
		(layer "F.Cu")
		(net "M_G_CPU1_SB_PAR")
	)
	(segment
		(start 150.951692 -266.248642)
		(end 153.771854 -266.248642)
		(width 0.10668)
		(layer "F.Cu")
		(net "M_G_CPU1_SB_PAR")
	)
	(segment
		(start 156.000704 -266.248642)
		(end 156.166058 -266.248642)
		(width 0.10668)
		(layer "F.Cu")
		(net "M_G_CPU1_SB_PAR")
	)
	(segment
		(start 156.166058 -266.248642)
		(end 156.282898 -266.131802)
		(width 0.10668)
		(layer "F.Cu")
		(net "M_G_CPU1_SB_PAR")
	)
	(segment
		(start 155.36799 -266.248642)
		(end 155.48483 -266.131802)
		(width 0.10668)
		(layer "F.Cu")
		(net "M_G_CPU1_SB_PAR")
	)
	(segment
		(start 158.831534 -264.962386)
		(end 158.948374 -265.079226)
		(width 0.10668)
		(layer "F.Cu")
		(net "M_G_CPU1_SB_PAR")
	)
	(segment
		(start 144.507966 -264.910316)
		(end 144.399508 -265.097006)
		(width 0.0762)
		(layer "F.Cu")
		(net "M_G_CPU1_SB_PAR")
	)
	(segment
		(start 161.342578 -265.333734)
		(end 161.459418 -265.450574)
		(width 0.10668)
		(layer "F.Cu")
		(net "M_G_CPU1_SB_PAR")
	)
	(segment
		(start 160.54451 -265.333734)
		(end 160.66135 -265.450574)
		(width 0.10668)
		(layer "F.Cu")
		(net "M_G_CPU1_SB_PAR")
	)
	(segment
		(start 156.282898 -266.131802)
		(end 156.282898 -266.026646)
		(width 0.10668)
		(layer "F.Cu")
		(net "M_G_CPU1_SB_PAR")
	)
	(segment
		(start 160.42767 -264.962386)
		(end 160.54451 -265.079226)
		(width 0.10668)
		(layer "F.Cu")
		(net "M_G_CPU1_SB_PAR")
	)
	(segment
		(start 154.686762 -266.026646)
		(end 154.803602 -265.909806)
		(width 0.10668)
		(layer "F.Cu")
		(net "M_G_CPU1_SB_PAR")
	)
	(segment
		(start 158.948374 -265.079226)
		(end 158.948374 -265.333734)
		(width 0.10668)
		(layer "F.Cu")
		(net "M_G_CPU1_SB_PAR")
	)
	(segment
		(start 158.948374 -265.333734)
		(end 159.065214 -265.450574)
		(width 0.10668)
		(layer "F.Cu")
		(net "M_G_CPU1_SB_PAR")
	)
	(segment
		(start 159.746442 -265.079226)
		(end 159.746442 -265.333734)
		(width 0.10668)
		(layer "F.Cu")
		(net "M_G_CPU1_SB_PAR")
	)
	(segment
		(start 154.803602 -265.909806)
		(end 154.968956 -265.909806)
		(width 0.10668)
		(layer "F.Cu")
		(net "M_G_CPU1_SB_PAR")
	)
	(segment
		(start 155.883864 -266.026646)
		(end 155.883864 -266.131802)
		(width 0.10668)
		(layer "F.Cu")
		(net "M_G_CPU1_SB_PAR")
	)
	(segment
		(start 153.771854 -266.248642)
		(end 153.888694 -266.131802)
		(width 0.10668)
		(layer "F.Cu")
		(net "M_G_CPU1_SB_PAR")
	)
	(segment
		(start 155.085796 -266.026646)
		(end 155.085796 -266.131802)
		(width 0.10668)
		(layer "F.Cu")
		(net "M_G_CPU1_SB_PAR")
	)
	(segment
		(start 159.347408 -265.333734)
		(end 159.347408 -265.079226)
		(width 0.10668)
		(layer "F.Cu")
		(net "M_G_CPU1_SB_PAR")
	)
	(segment
		(start 154.287728 -266.131802)
		(end 154.404568 -266.248642)
		(width 0.10668)
		(layer "F.Cu")
		(net "M_G_CPU1_SB_PAR")
	)
	(segment
		(start 161.696908 -265.450574)
		(end 163.281614 -267.03528)
		(width 0.10668)
		(layer "F.Cu")
		(net "M_G_CPU1_SB_PAR")
	)
	(segment
		(start 156.681932 -266.131802)
		(end 156.798772 -266.248642)
		(width 0.10668)
		(layer "F.Cu")
		(net "M_G_CPU1_SB_PAR")
	)
	(segment
		(start 155.60167 -265.909806)
		(end 155.767024 -265.909806)
		(width 0.10668)
		(layer "F.Cu")
		(net "M_G_CPU1_SB_PAR")
	)
	(segment
		(start 154.170888 -265.909806)
		(end 154.287728 -266.026646)
		(width 0.10668)
		(layer "F.Cu")
		(net "M_G_CPU1_SB_PAR")
	)
	(segment
		(start 159.746442 -265.333734)
		(end 159.863282 -265.450574)
		(width 0.10668)
		(layer "F.Cu")
		(net "M_G_CPU1_SB_PAR")
	)
	(segment
		(start 147.397978 -265.124946)
		(end 147.917916 -265.124946)
		(width 0.0762)
		(layer "F.Cu")
		(net "M_G_CPU1_SB_PAR")
	)
	(segment
		(start 158.4325 -265.450574)
		(end 158.54934 -265.333734)
		(width 0.10668)
		(layer "F.Cu")
		(net "M_G_CPU1_SB_PAR")
	)
	(segment
		(start 160.943544 -265.079226)
		(end 161.060384 -264.962386)
		(width 0.10668)
		(layer "F.Cu")
		(net "M_G_CPU1_SB_PAR")
	)
	(segment
		(start 158.66618 -264.962386)
		(end 158.831534 -264.962386)
		(width 0.10668)
		(layer "F.Cu")
		(net "M_G_CPU1_SB_PAR")
	)
	(segment
		(start 155.883864 -266.131802)
		(end 156.000704 -266.248642)
		(width 0.10668)
		(layer "F.Cu")
		(net "M_G_CPU1_SB_PAR")
	)
	(segment
		(start 154.404568 -266.248642)
		(end 154.569922 -266.248642)
		(width 0.10668)
		(layer "F.Cu")
		(net "M_G_CPU1_SB_PAR")
	)
	(segment
		(start 160.145476 -265.079226)
		(end 160.262316 -264.962386)
		(width 0.10668)
		(layer "F.Cu")
		(net "M_G_CPU1_SB_PAR")
	)
	(segment
		(start 155.085796 -266.131802)
		(end 155.202636 -266.248642)
		(width 0.10668)
		(layer "F.Cu")
		(net "M_G_CPU1_SB_PAR")
	)
	(segment
		(start 154.005534 -265.909806)
		(end 154.170888 -265.909806)
		(width 0.10668)
		(layer "F.Cu")
		(net "M_G_CPU1_SB_PAR")
	)
	(segment
		(start 153.888694 -266.131802)
		(end 153.888694 -266.026646)
		(width 0.10668)
		(layer "F.Cu")
		(net "M_G_CPU1_SB_PAR")
	)
	(segment
		(start 160.028636 -265.450574)
		(end 160.145476 -265.333734)
		(width 0.10668)
		(layer "F.Cu")
		(net "M_G_CPU1_SB_PAR")
	)
	(segment
		(start 147.917916 -265.124946)
		(end 149.827996 -265.124946)
		(width 0.10668)
		(layer "F.Cu")
		(net "M_G_CPU1_SB_PAR")
	)
	(segment
		(start 155.48483 -266.131802)
		(end 155.48483 -266.026646)
		(width 0.10668)
		(layer "F.Cu")
		(net "M_G_CPU1_SB_PAR")
	)
	(segment
		(start 156.565092 -265.909806)
		(end 156.681932 -266.026646)
		(width 0.10668)
		(layer "F.Cu")
		(net "M_G_CPU1_SB_PAR")
	)
	(segment
		(start 161.459418 -265.450574)
		(end 161.696908 -265.450574)
		(width 0.10668)
		(layer "F.Cu")
		(net "M_G_CPU1_SB_PAR")
	)
	(segment
		(start 158.07563 -265.450574)
		(end 158.4325 -265.450574)
		(width 0.10668)
		(layer "F.Cu")
		(net "M_G_CPU1_SB_PAR")
	)
	(segment
		(start 163.281614 -267.03528)
		(end 164.427916 -267.03528)
		(width 0.10668)
		(layer "F.Cu")
		(net "M_G_CPU1_SB_PAR")
	)
	(segment
		(start 159.230568 -265.450574)
		(end 159.347408 -265.333734)
		(width 0.10668)
		(layer "F.Cu")
		(net "M_G_CPU1_SB_PAR")
	)
	(segment
		(start 159.629602 -264.962386)
		(end 159.746442 -265.079226)
		(width 0.10668)
		(layer "F.Cu")
		(net "M_G_CPU1_SB_PAR")
	)
	(segment
		(start 158.54934 -265.079226)
		(end 158.66618 -264.962386)
		(width 0.10668)
		(layer "F.Cu")
		(net "M_G_CPU1_SB_PAR")
	)
	(segment
		(start 147.230846 -265.292078)
		(end 147.397978 -265.124946)
		(width 0.0762)
		(layer "F.Cu")
		(net "M_G_CPU1_SB_PAR")
	)
	(segment
		(start 154.968956 -265.909806)
		(end 155.085796 -266.026646)
		(width 0.10668)
		(layer "F.Cu")
		(net "M_G_CPU1_SB_PAR")
	)
	(segment
		(start 159.347408 -265.079226)
		(end 159.464248 -264.962386)
		(width 0.10668)
		(layer "F.Cu")
		(net "M_G_CPU1_SB_PAR")
	)
	(segment
		(start 155.767024 -265.909806)
		(end 155.883864 -266.026646)
		(width 0.10668)
		(layer "F.Cu")
		(net "M_G_CPU1_SB_PAR")
	)
	(segment
		(start 161.060384 -264.962386)
		(end 161.225738 -264.962386)
		(width 0.10668)
		(layer "F.Cu")
		(net "M_G_CPU1_SB_PAR")
	)
	(segment
		(start 160.943544 -265.333734)
		(end 160.943544 -265.079226)
		(width 0.10668)
		(layer "F.Cu")
		(net "M_G_CPU1_SB_PAR")
	)
	(segment
		(start 154.287728 -266.026646)
		(end 154.287728 -266.131802)
		(width 0.10668)
		(layer "F.Cu")
		(net "M_G_CPU1_SB_PAR")
	)
	(segment
		(start 158.54934 -265.333734)
		(end 158.54934 -265.079226)
		(width 0.10668)
		(layer "F.Cu")
		(net "M_G_CPU1_SB_PAR")
	)
	(segment
		(start 149.827996 -265.124946)
		(end 150.951692 -266.248642)
		(width 0.10668)
		(layer "F.Cu")
		(net "M_G_CPU1_SB_PAR")
	)
	(segment
		(start 146.358356 -265.291062)
		(end 147.230846 -265.292078)
		(width 0.0762)
		(layer "F.Cu")
		(net "M_G_CPU1_SB_PAR")
	)
	(segment
		(start 159.863282 -265.450574)
		(end 160.028636 -265.450574)
		(width 0.10668)
		(layer "F.Cu")
		(net "M_G_CPU1_SB_PAR")
	)
	(segment
		(start 154.686762 -266.131802)
		(end 154.686762 -266.026646)
		(width 0.10668)
		(layer "F.Cu")
		(net "M_G_CPU1_SB_PAR")
	)
	(segment
		(start 154.569922 -266.248642)
		(end 154.686762 -266.131802)
		(width 0.10668)
		(layer "F.Cu")
		(net "M_G_CPU1_SB_PAR")
	)
	(segment
		(start 160.54451 -265.079226)
		(end 160.54451 -265.333734)
		(width 0.10668)
		(layer "F.Cu")
		(net "M_G_CPU1_SB_PAR")
	)
	(segment
		(start 156.681932 -266.026646)
		(end 156.681932 -266.131802)
		(width 0.10668)
		(layer "F.Cu")
		(net "M_G_CPU1_SB_PAR")
	)
	(segment
		(start 157.277562 -266.248642)
		(end 158.07563 -265.450574)
		(width 0.10668)
		(layer "F.Cu")
		(net "M_G_CPU1_SB_PAR")
	)
	(segment
		(start 161.342578 -265.079226)
		(end 161.342578 -265.333734)
		(width 0.10668)
		(layer "F.Cu")
		(net "M_G_CPU1_SB_PAR")
	)
	(segment
		(start 155.202636 -266.248642)
		(end 155.36799 -266.248642)
		(width 0.10668)
		(layer "F.Cu")
		(net "M_G_CPU1_SB_PAR")
	)
	(segment
		(start 160.826704 -265.450574)
		(end 160.943544 -265.333734)
		(width 0.10668)
		(layer "F.Cu")
		(net "M_G_CPU1_SB_PAR")
	)
	(arc
		(start 145.261076 -265.232896)
		(mid 145.44802 -265.28322)
		(end 145.634964 -265.232896)
		(width 0.0762)
		(layer "F.Cu")
		(net "M_G_CPU1_SB_PAR")
	)
	(arc
		(start 144.551146 -265.280648)
		(mid 144.6209 -265.265691)
		(end 144.686528 -265.237722)
		(width 0.0762)
		(layer "F.Cu")
		(net "M_G_CPU1_SB_PAR")
	)
	(arc
		(start 144.69491 -265.232896)
		(mid 144.977866 -265.156719)
		(end 145.260822 -265.232896)
		(width 0.0762)
		(layer "F.Cu")
		(net "M_G_CPU1_SB_PAR")
	)
	(arc
		(start 146.200876 -265.232896)
		(mid 146.24157 -265.255115)
		(end 146.283426 -265.27506)
		(width 0.0762)
		(layer "F.Cu")
		(net "M_G_CPU1_SB_PAR")
	)
	(arc
		(start 144.399508 -265.097006)
		(mid 144.425425 -265.230048)
		(end 144.551146 -265.280648)
		(width 0.0762)
		(layer "F.Cu")
		(net "M_G_CPU1_SB_PAR")
	)
	(arc
		(start 146.283426 -265.27506)
		(mid 146.320054 -265.28699)
		(end 146.358356 -265.291062)
		(width 0.0762)
		(layer "F.Cu")
		(net "M_G_CPU1_SB_PAR")
	)
	(arc
		(start 145.634964 -265.232896)
		(mid 145.91792 -265.156719)
		(end 146.200876 -265.232896)
		(width 0.0762)
		(layer "F.Cu")
		(net "M_G_CPU1_SB_PAR")
	)
	(segment
		(start 146.096482 -270.907764)
		(end 146.104864 -270.902938)
		(width 0.0762)
		(layer "F.Cu")
		(net "M_G_CPU1_SB_DQS_DP<9>")
	)
	(segment
		(start 146.387566 -270.826738)
		(end 146.879818 -270.826738)
		(width 0.0762)
		(layer "F.Cu")
		(net "M_G_CPU1_SB_DQS_DP<9>")
	)
	(segment
		(start 146.879818 -270.826738)
		(end 146.991578 -270.714978)
		(width 0.0762)
		(layer "F.Cu")
		(net "M_G_CPU1_SB_DQS_DP<9>")
	)
	(segment
		(start 147.483322 -270.714978)
		(end 147.549362 -270.648938)
		(width 0.0762)
		(layer "F.Cu")
		(net "M_G_CPU1_SB_DQS_DP<9>")
	)
	(segment
		(start 163.566602 -275.110448)
		(end 165.99535 -275.110448)
		(width 0.101346)
		(layer "F.Cu")
		(net "M_G_CPU1_SB_DQS_DP<9>")
	)
	(segment
		(start 145.91792 -270.580358)
		(end 145.815558 -270.756634)
		(width 0.0762)
		(layer "F.Cu")
		(net "M_G_CPU1_SB_DQS_DP<9>")
	)
	(segment
		(start 162.947858 -275.374862)
		(end 163.302188 -275.374862)
		(width 0.12954)
		(layer "F.Cu")
		(net "M_G_CPU1_SB_DQS_DP<9>")
	)
	(segment
		(start 146.991578 -270.714978)
		(end 147.483322 -270.714978)
		(width 0.0762)
		(layer "F.Cu")
		(net "M_G_CPU1_SB_DQS_DP<9>")
	)
	(segment
		(start 161.103056 -273.53006)
		(end 162.947858 -275.374862)
		(width 0.12954)
		(layer "F.Cu")
		(net "M_G_CPU1_SB_DQS_DP<9>")
	)
	(segment
		(start 168.014396 -275.53539)
		(end 168.527984 -275.53539)
		(width 0.101346)
		(layer "F.Cu")
		(net "M_G_CPU1_SB_DQS_DP<9>")
	)
	(segment
		(start 147.568412 -270.648938)
		(end 159.672782 -270.648938)
		(width 0.12954)
		(layer "F.Cu")
		(net "M_G_CPU1_SB_DQS_DP<9>")
	)
	(segment
		(start 166.698422 -275.427186)
		(end 167.123618 -275.852382)
		(width 0.101346)
		(layer "F.Cu")
		(net "M_G_CPU1_SB_DQS_DP<9>")
	)
	(segment
		(start 167.123618 -275.852382)
		(end 167.697404 -275.852382)
		(width 0.101346)
		(layer "F.Cu")
		(net "M_G_CPU1_SB_DQS_DP<9>")
	)
	(segment
		(start 147.549362 -270.648938)
		(end 147.568412 -270.648938)
		(width 0.0762)
		(layer "F.Cu")
		(net "M_G_CPU1_SB_DQS_DP<9>")
	)
	(segment
		(start 159.672782 -270.648938)
		(end 161.103056 -272.079212)
		(width 0.12954)
		(layer "F.Cu")
		(net "M_G_CPU1_SB_DQS_DP<9>")
	)
	(segment
		(start 161.103056 -272.079212)
		(end 161.103056 -273.53006)
		(width 0.12954)
		(layer "F.Cu")
		(net "M_G_CPU1_SB_DQS_DP<9>")
	)
	(segment
		(start 165.99535 -275.110448)
		(end 166.312088 -275.427186)
		(width 0.101346)
		(layer "F.Cu")
		(net "M_G_CPU1_SB_DQS_DP<9>")
	)
	(segment
		(start 167.697404 -275.852382)
		(end 168.014396 -275.53539)
		(width 0.101346)
		(layer "F.Cu")
		(net "M_G_CPU1_SB_DQS_DP<9>")
	)
	(segment
		(start 163.302188 -275.374862)
		(end 163.566602 -275.110448)
		(width 0.12954)
		(layer "F.Cu")
		(net "M_G_CPU1_SB_DQS_DP<9>")
	)
	(segment
		(start 166.312088 -275.427186)
		(end 166.698422 -275.427186)
		(width 0.101346)
		(layer "F.Cu")
		(net "M_G_CPU1_SB_DQS_DP<9>")
	)
	(arc
		(start 145.815558 -270.756634)
		(mid 145.845187 -270.899121)
		(end 145.982436 -270.947642)
		(width 0.0762)
		(layer "F.Cu")
		(net "M_G_CPU1_SB_DQS_DP<9>")
	)
	(arc
		(start 146.340576 -270.828516)
		(mid 146.364053 -270.82714)
		(end 146.387566 -270.826738)
		(width 0.0762)
		(layer "F.Cu")
		(net "M_G_CPU1_SB_DQS_DP<9>")
	)
	(arc
		(start 145.982436 -270.947642)
		(mid 146.041082 -270.932349)
		(end 146.096482 -270.907764)
		(width 0.0762)
		(layer "F.Cu")
		(net "M_G_CPU1_SB_DQS_DP<9>")
	)
	(arc
		(start 146.104864 -270.902938)
		(mid 146.218588 -270.852637)
		(end 146.340576 -270.828516)
		(width 0.0762)
		(layer "F.Cu")
		(net "M_G_CPU1_SB_DQS_DP<9>")
	)
	(segment
		(start 160.466024 -310.888126)
		(end 160.204404 -311.15)
		(width 0.12954)
		(layer "F.Cu")
		(net "M_G_CPU1_SB_DQS_DP<8>")
	)
	(segment
		(start 158.26105 -309.67299)
		(end 158.72714 -309.67299)
		(width 0.12954)
		(layer "F.Cu")
		(net "M_G_CPU1_SB_DQS_DP<8>")
	)
	(segment
		(start 157.59049 -308.53634)
		(end 157.852364 -308.27472)
		(width 0.12954)
		(layer "F.Cu")
		(net "M_G_CPU1_SB_DQS_DP<8>")
	)
	(segment
		(start 160.204404 -311.15)
		(end 160.204404 -311.616344)
		(width 0.12954)
		(layer "F.Cu")
		(net "M_G_CPU1_SB_DQS_DP<8>")
	)
	(segment
		(start 158.192978 -308.41696)
		(end 158.192724 -308.614826)
		(width 0.12954)
		(layer "F.Cu")
		(net "M_G_CPU1_SB_DQS_DP<8>")
	)
	(segment
		(start 157.852364 -308.27472)
		(end 158.050738 -308.27472)
		(width 0.12954)
		(layer "F.Cu")
		(net "M_G_CPU1_SB_DQS_DP<8>")
	)
	(segment
		(start 156.794454 -308.206394)
		(end 157.1244 -308.53634)
		(width 0.12954)
		(layer "F.Cu")
		(net "M_G_CPU1_SB_DQS_DP<8>")
	)
	(segment
		(start 160.324038 -310.54802)
		(end 160.466278 -310.69026)
		(width 0.12954)
		(layer "F.Cu")
		(net "M_G_CPU1_SB_DQS_DP<8>")
	)
	(segment
		(start 147.72513 -291.45992)
		(end 147.74418 -291.45992)
		(width 0.0762)
		(layer "F.Cu")
		(net "M_G_CPU1_SB_DQS_DP<8>")
	)
	(segment
		(start 163.606988 -314.371736)
		(end 163.87064 -314.635388)
		(width 0.12954)
		(layer "F.Cu")
		(net "M_G_CPU1_SB_DQS_DP<8>")
	)
	(segment
		(start 163.87064 -314.635388)
		(end 164.427916 -314.635388)
		(width 0.12954)
		(layer "F.Cu")
		(net "M_G_CPU1_SB_DQS_DP<8>")
	)
	(segment
		(start 147.65909 -291.39388)
		(end 147.72513 -291.45992)
		(width 0.0762)
		(layer "F.Cu")
		(net "M_G_CPU1_SB_DQS_DP<8>")
	)
	(segment
		(start 159.86379 -310.80964)
		(end 160.125664 -310.54802)
		(width 0.12954)
		(layer "F.Cu")
		(net "M_G_CPU1_SB_DQS_DP<8>")
	)
	(segment
		(start 147.926552 -291.45992)
		(end 148.78939 -292.322758)
		(width 0.12954)
		(layer "F.Cu")
		(net "M_G_CPU1_SB_DQS_DP<8>")
	)
	(segment
		(start 157.931104 -309.343044)
		(end 158.26105 -309.67299)
		(width 0.12954)
		(layer "F.Cu")
		(net "M_G_CPU1_SB_DQS_DP<8>")
	)
	(segment
		(start 148.78939 -292.322758)
		(end 148.78939 -299.013372)
		(width 0.12954)
		(layer "F.Cu")
		(net "M_G_CPU1_SB_DQS_DP<8>")
	)
	(segment
		(start 159.067754 -310.01335)
		(end 159.067754 -310.479694)
		(width 0.12954)
		(layer "F.Cu")
		(net "M_G_CPU1_SB_DQS_DP<8>")
	)
	(segment
		(start 157.931104 -308.8767)
		(end 157.931104 -309.343044)
		(width 0.12954)
		(layer "F.Cu")
		(net "M_G_CPU1_SB_DQS_DP<8>")
	)
	(segment
		(start 158.050738 -308.27472)
		(end 158.192978 -308.41696)
		(width 0.12954)
		(layer "F.Cu")
		(net "M_G_CPU1_SB_DQS_DP<8>")
	)
	(segment
		(start 159.067754 -310.479694)
		(end 159.3977 -310.80964)
		(width 0.12954)
		(layer "F.Cu")
		(net "M_G_CPU1_SB_DQS_DP<8>")
	)
	(segment
		(start 147.74418 -291.45992)
		(end 147.926552 -291.45992)
		(width 0.12954)
		(layer "F.Cu")
		(net "M_G_CPU1_SB_DQS_DP<8>")
	)
	(segment
		(start 158.989014 -309.41137)
		(end 159.187388 -309.41137)
		(width 0.12954)
		(layer "F.Cu")
		(net "M_G_CPU1_SB_DQS_DP<8>")
	)
	(segment
		(start 158.192724 -308.614826)
		(end 157.931104 -308.8767)
		(width 0.12954)
		(layer "F.Cu")
		(net "M_G_CPU1_SB_DQS_DP<8>")
	)
	(segment
		(start 159.187388 -309.41137)
		(end 159.329628 -309.55361)
		(width 0.12954)
		(layer "F.Cu")
		(net "M_G_CPU1_SB_DQS_DP<8>")
	)
	(segment
		(start 146.096482 -291.312854)
		(end 146.104864 -291.31768)
		(width 0.0762)
		(layer "F.Cu")
		(net "M_G_CPU1_SB_DQS_DP<8>")
	)
	(segment
		(start 159.329374 -309.751476)
		(end 159.067754 -310.01335)
		(width 0.12954)
		(layer "F.Cu")
		(net "M_G_CPU1_SB_DQS_DP<8>")
	)
	(segment
		(start 160.125664 -310.54802)
		(end 160.324038 -310.54802)
		(width 0.12954)
		(layer "F.Cu")
		(net "M_G_CPU1_SB_DQS_DP<8>")
	)
	(segment
		(start 157.1244 -308.53634)
		(end 157.59049 -308.53634)
		(width 0.12954)
		(layer "F.Cu")
		(net "M_G_CPU1_SB_DQS_DP<8>")
	)
	(segment
		(start 146.38782 -291.39388)
		(end 147.65909 -291.39388)
		(width 0.0762)
		(layer "F.Cu")
		(net "M_G_CPU1_SB_DQS_DP<8>")
	)
	(segment
		(start 156.794454 -307.74005)
		(end 156.794454 -308.206394)
		(width 0.12954)
		(layer "F.Cu")
		(net "M_G_CPU1_SB_DQS_DP<8>")
	)
	(segment
		(start 157.06344 -307.471064)
		(end 156.794454 -307.74005)
		(width 0.12954)
		(layer "F.Cu")
		(net "M_G_CPU1_SB_DQS_DP<8>")
	)
	(segment
		(start 157.06344 -307.287422)
		(end 157.06344 -307.471064)
		(width 0.12954)
		(layer "F.Cu")
		(net "M_G_CPU1_SB_DQS_DP<8>")
	)
	(segment
		(start 160.466278 -310.69026)
		(end 160.466024 -310.888126)
		(width 0.12954)
		(layer "F.Cu")
		(net "M_G_CPU1_SB_DQS_DP<8>")
	)
	(segment
		(start 159.3977 -310.80964)
		(end 159.86379 -310.80964)
		(width 0.12954)
		(layer "F.Cu")
		(net "M_G_CPU1_SB_DQS_DP<8>")
	)
	(segment
		(start 160.204404 -311.616344)
		(end 162.959796 -314.371736)
		(width 0.12954)
		(layer "F.Cu")
		(net "M_G_CPU1_SB_DQS_DP<8>")
	)
	(segment
		(start 158.72714 -309.67299)
		(end 158.989014 -309.41137)
		(width 0.12954)
		(layer "F.Cu")
		(net "M_G_CPU1_SB_DQS_DP<8>")
	)
	(segment
		(start 159.329628 -309.55361)
		(end 159.329374 -309.751476)
		(width 0.12954)
		(layer "F.Cu")
		(net "M_G_CPU1_SB_DQS_DP<8>")
	)
	(segment
		(start 148.78939 -299.013372)
		(end 157.06344 -307.287422)
		(width 0.12954)
		(layer "F.Cu")
		(net "M_G_CPU1_SB_DQS_DP<8>")
	)
	(segment
		(start 162.959796 -314.371736)
		(end 163.606988 -314.371736)
		(width 0.12954)
		(layer "F.Cu")
		(net "M_G_CPU1_SB_DQS_DP<8>")
	)
	(arc
		(start 145.730722 -291.31768)
		(mid 145.912973 -291.26733)
		(end 146.096482 -291.312854)
		(width 0.0762)
		(layer "F.Cu")
		(net "M_G_CPU1_SB_DQS_DP<8>")
	)
	(arc
		(start 145.16481 -291.31768)
		(mid 145.447766 -291.393857)
		(end 145.730722 -291.31768)
		(width 0.0762)
		(layer "F.Cu")
		(net "M_G_CPU1_SB_DQS_DP<8>")
	)
	(arc
		(start 144.790922 -291.31768)
		(mid 144.977866 -291.267425)
		(end 145.16481 -291.31768)
		(width 0.0762)
		(layer "F.Cu")
		(net "M_G_CPU1_SB_DQS_DP<8>")
	)
	(arc
		(start 144.575784 -291.39007)
		(mid 144.68703 -291.364807)
		(end 144.790922 -291.31768)
		(width 0.0762)
		(layer "F.Cu")
		(net "M_G_CPU1_SB_DQS_DP<8>")
	)
	(arc
		(start 144.037812 -291.64026)
		(mid 144.27181 -291.468217)
		(end 144.552162 -291.392356)
		(width 0.0762)
		(layer "F.Cu")
		(net "M_G_CPU1_SB_DQS_DP<8>")
	)
	(arc
		(start 144.552162 -291.392356)
		(mid 144.563985 -291.391339)
		(end 144.575784 -291.39007)
		(width 0.0762)
		(layer "F.Cu")
		(net "M_G_CPU1_SB_DQS_DP<8>")
	)
	(arc
		(start 146.104864 -291.31768)
		(mid 146.2413 -291.374505)
		(end 146.38782 -291.39388)
		(width 0.0762)
		(layer "F.Cu")
		(net "M_G_CPU1_SB_DQS_DP<8>")
	)
	(segment
		(start 147.834096 -286.363664)
		(end 147.900136 -286.429704)
		(width 0.0762)
		(layer "F.Cu")
		(net "M_G_CPU1_SB_DQS_DP<7>")
	)
	(segment
		(start 158.324296 -300.070012)
		(end 158.466536 -300.211998)
		(width 0.12954)
		(layer "F.Cu")
		(net "M_G_CPU1_SB_DQS_DP<7>")
	)
	(segment
		(start 154.914346 -296.660062)
		(end 155.056586 -296.802048)
		(width 0.12954)
		(layer "F.Cu")
		(net "M_G_CPU1_SB_DQS_DP<7>")
	)
	(segment
		(start 158.313374 -301.02937)
		(end 158.643066 -301.359062)
		(width 0.12954)
		(layer "F.Cu")
		(net "M_G_CPU1_SB_DQS_DP<7>")
	)
	(segment
		(start 157.176724 -299.89272)
		(end 157.506416 -300.222412)
		(width 0.12954)
		(layer "F.Cu")
		(net "M_G_CPU1_SB_DQS_DP<7>")
	)
	(segment
		(start 159.602932 -301.546514)
		(end 159.450024 -301.699676)
		(width 0.12954)
		(layer "F.Cu")
		(net "M_G_CPU1_SB_DQS_DP<7>")
	)
	(segment
		(start 153.188924 -290.392866)
		(end 153.188924 -295.90492)
		(width 0.12954)
		(layer "F.Cu")
		(net "M_G_CPU1_SB_DQS_DP<7>")
	)
	(segment
		(start 158.313374 -300.563026)
		(end 158.313374 -301.02937)
		(width 0.12954)
		(layer "F.Cu")
		(net "M_G_CPU1_SB_DQS_DP<7>")
	)
	(segment
		(start 155.056332 -296.999914)
		(end 154.903424 -297.153076)
		(width 0.12954)
		(layer "F.Cu")
		(net "M_G_CPU1_SB_DQS_DP<7>")
	)
	(segment
		(start 154.903424 -297.153076)
		(end 154.903424 -297.61942)
		(width 0.12954)
		(layer "F.Cu")
		(net "M_G_CPU1_SB_DQS_DP<7>")
	)
	(segment
		(start 156.369766 -299.085762)
		(end 156.836618 -299.085762)
		(width 0.12954)
		(layer "F.Cu")
		(net "M_G_CPU1_SB_DQS_DP<7>")
	)
	(segment
		(start 155.056586 -296.802048)
		(end 155.056332 -296.999914)
		(width 0.12954)
		(layer "F.Cu")
		(net "M_G_CPU1_SB_DQS_DP<7>")
	)
	(segment
		(start 156.192982 -298.136564)
		(end 156.040074 -298.289726)
		(width 0.12954)
		(layer "F.Cu")
		(net "M_G_CPU1_SB_DQS_DP<7>")
	)
	(segment
		(start 157.329632 -299.273214)
		(end 157.176724 -299.426376)
		(width 0.12954)
		(layer "F.Cu")
		(net "M_G_CPU1_SB_DQS_DP<7>")
	)
	(segment
		(start 146.38782 -286.534098)
		(end 147.350988 -286.534098)
		(width 0.0762)
		(layer "F.Cu")
		(net "M_G_CPU1_SB_DQS_DP<7>")
	)
	(segment
		(start 158.466536 -300.211998)
		(end 158.466282 -300.409864)
		(width 0.12954)
		(layer "F.Cu")
		(net "M_G_CPU1_SB_DQS_DP<7>")
	)
	(segment
		(start 155.852622 -297.796458)
		(end 156.050996 -297.796712)
		(width 0.12954)
		(layer "F.Cu")
		(net "M_G_CPU1_SB_DQS_DP<7>")
	)
	(segment
		(start 159.603186 -301.348648)
		(end 159.602932 -301.546514)
		(width 0.12954)
		(layer "F.Cu")
		(net "M_G_CPU1_SB_DQS_DP<7>")
	)
	(segment
		(start 159.460946 -301.206662)
		(end 159.603186 -301.348648)
		(width 0.12954)
		(layer "F.Cu")
		(net "M_G_CPU1_SB_DQS_DP<7>")
	)
	(segment
		(start 156.040074 -298.75607)
		(end 156.369766 -299.085762)
		(width 0.12954)
		(layer "F.Cu")
		(net "M_G_CPU1_SB_DQS_DP<7>")
	)
	(segment
		(start 155.233116 -297.949112)
		(end 155.699968 -297.949112)
		(width 0.12954)
		(layer "F.Cu")
		(net "M_G_CPU1_SB_DQS_DP<7>")
	)
	(segment
		(start 154.563318 -296.812462)
		(end 154.715972 -296.659808)
		(width 0.12954)
		(layer "F.Cu")
		(net "M_G_CPU1_SB_DQS_DP<7>")
	)
	(segment
		(start 157.506416 -300.222412)
		(end 157.973268 -300.222412)
		(width 0.12954)
		(layer "F.Cu")
		(net "M_G_CPU1_SB_DQS_DP<7>")
	)
	(segment
		(start 156.836618 -299.085762)
		(end 156.989272 -298.933108)
		(width 0.12954)
		(layer "F.Cu")
		(net "M_G_CPU1_SB_DQS_DP<7>")
	)
	(segment
		(start 147.350988 -286.534098)
		(end 147.521422 -286.363664)
		(width 0.0762)
		(layer "F.Cu")
		(net "M_G_CPU1_SB_DQS_DP<7>")
	)
	(segment
		(start 154.715972 -296.659808)
		(end 154.914346 -296.660062)
		(width 0.12954)
		(layer "F.Cu")
		(net "M_G_CPU1_SB_DQS_DP<7>")
	)
	(segment
		(start 155.699968 -297.949112)
		(end 155.852622 -297.796458)
		(width 0.12954)
		(layer "F.Cu")
		(net "M_G_CPU1_SB_DQS_DP<7>")
	)
	(segment
		(start 157.329886 -299.075348)
		(end 157.329632 -299.273214)
		(width 0.12954)
		(layer "F.Cu")
		(net "M_G_CPU1_SB_DQS_DP<7>")
	)
	(segment
		(start 163.606988 -305.021742)
		(end 163.87064 -305.285394)
		(width 0.12954)
		(layer "F.Cu")
		(net "M_G_CPU1_SB_DQS_DP<7>")
	)
	(segment
		(start 156.050996 -297.796712)
		(end 156.193236 -297.938698)
		(width 0.12954)
		(layer "F.Cu")
		(net "M_G_CPU1_SB_DQS_DP<7>")
	)
	(segment
		(start 158.643066 -301.359062)
		(end 159.109918 -301.359062)
		(width 0.12954)
		(layer "F.Cu")
		(net "M_G_CPU1_SB_DQS_DP<7>")
	)
	(segment
		(start 157.187646 -298.933362)
		(end 157.329886 -299.075348)
		(width 0.12954)
		(layer "F.Cu")
		(net "M_G_CPU1_SB_DQS_DP<7>")
	)
	(segment
		(start 157.973268 -300.222412)
		(end 158.125922 -300.069758)
		(width 0.12954)
		(layer "F.Cu")
		(net "M_G_CPU1_SB_DQS_DP<7>")
	)
	(segment
		(start 154.096466 -296.812462)
		(end 154.563318 -296.812462)
		(width 0.12954)
		(layer "F.Cu")
		(net "M_G_CPU1_SB_DQS_DP<7>")
	)
	(segment
		(start 156.040074 -298.289726)
		(end 156.040074 -298.75607)
		(width 0.12954)
		(layer "F.Cu")
		(net "M_G_CPU1_SB_DQS_DP<7>")
	)
	(segment
		(start 149.225762 -286.429704)
		(end 153.188924 -290.392866)
		(width 0.12954)
		(layer "F.Cu")
		(net "M_G_CPU1_SB_DQS_DP<7>")
	)
	(segment
		(start 163.87064 -305.285394)
		(end 164.427916 -305.285394)
		(width 0.12954)
		(layer "F.Cu")
		(net "M_G_CPU1_SB_DQS_DP<7>")
	)
	(segment
		(start 159.450024 -301.699676)
		(end 159.450024 -302.16602)
		(width 0.12954)
		(layer "F.Cu")
		(net "M_G_CPU1_SB_DQS_DP<7>")
	)
	(segment
		(start 158.466282 -300.409864)
		(end 158.313374 -300.563026)
		(width 0.12954)
		(layer "F.Cu")
		(net "M_G_CPU1_SB_DQS_DP<7>")
	)
	(segment
		(start 158.125922 -300.069758)
		(end 158.324296 -300.070012)
		(width 0.12954)
		(layer "F.Cu")
		(net "M_G_CPU1_SB_DQS_DP<7>")
	)
	(segment
		(start 147.919186 -286.429704)
		(end 149.225762 -286.429704)
		(width 0.12954)
		(layer "F.Cu")
		(net "M_G_CPU1_SB_DQS_DP<7>")
	)
	(segment
		(start 157.176724 -299.426376)
		(end 157.176724 -299.89272)
		(width 0.12954)
		(layer "F.Cu")
		(net "M_G_CPU1_SB_DQS_DP<7>")
	)
	(segment
		(start 159.450024 -302.16602)
		(end 162.305746 -305.021742)
		(width 0.12954)
		(layer "F.Cu")
		(net "M_G_CPU1_SB_DQS_DP<7>")
	)
	(segment
		(start 156.989272 -298.933108)
		(end 157.187646 -298.933362)
		(width 0.12954)
		(layer "F.Cu")
		(net "M_G_CPU1_SB_DQS_DP<7>")
	)
	(segment
		(start 156.193236 -297.938698)
		(end 156.192982 -298.136564)
		(width 0.12954)
		(layer "F.Cu")
		(net "M_G_CPU1_SB_DQS_DP<7>")
	)
	(segment
		(start 147.521422 -286.363664)
		(end 147.834096 -286.363664)
		(width 0.0762)
		(layer "F.Cu")
		(net "M_G_CPU1_SB_DQS_DP<7>")
	)
	(segment
		(start 146.096482 -286.453072)
		(end 146.104864 -286.457898)
		(width 0.0762)
		(layer "F.Cu")
		(net "M_G_CPU1_SB_DQS_DP<7>")
	)
	(segment
		(start 159.262572 -301.206408)
		(end 159.460946 -301.206662)
		(width 0.12954)
		(layer "F.Cu")
		(net "M_G_CPU1_SB_DQS_DP<7>")
	)
	(segment
		(start 147.900136 -286.429704)
		(end 147.919186 -286.429704)
		(width 0.0762)
		(layer "F.Cu")
		(net "M_G_CPU1_SB_DQS_DP<7>")
	)
	(segment
		(start 154.903424 -297.61942)
		(end 155.233116 -297.949112)
		(width 0.12954)
		(layer "F.Cu")
		(net "M_G_CPU1_SB_DQS_DP<7>")
	)
	(segment
		(start 159.109918 -301.359062)
		(end 159.262572 -301.206408)
		(width 0.12954)
		(layer "F.Cu")
		(net "M_G_CPU1_SB_DQS_DP<7>")
	)
	(segment
		(start 162.305746 -305.021742)
		(end 163.606988 -305.021742)
		(width 0.12954)
		(layer "F.Cu")
		(net "M_G_CPU1_SB_DQS_DP<7>")
	)
	(segment
		(start 153.188924 -295.90492)
		(end 154.096466 -296.812462)
		(width 0.12954)
		(layer "F.Cu")
		(net "M_G_CPU1_SB_DQS_DP<7>")
	)
	(arc
		(start 144.790922 -286.457898)
		(mid 144.977866 -286.407643)
		(end 145.16481 -286.457898)
		(width 0.0762)
		(layer "F.Cu")
		(net "M_G_CPU1_SB_DQS_DP<7>")
	)
	(arc
		(start 144.552162 -286.532574)
		(mid 144.563985 -286.531557)
		(end 144.575784 -286.530288)
		(width 0.0762)
		(layer "F.Cu")
		(net "M_G_CPU1_SB_DQS_DP<7>")
	)
	(arc
		(start 145.16481 -286.457898)
		(mid 145.447766 -286.534075)
		(end 145.730722 -286.457898)
		(width 0.0762)
		(layer "F.Cu")
		(net "M_G_CPU1_SB_DQS_DP<7>")
	)
	(arc
		(start 144.037812 -286.780478)
		(mid 144.27181 -286.608435)
		(end 144.552162 -286.532574)
		(width 0.0762)
		(layer "F.Cu")
		(net "M_G_CPU1_SB_DQS_DP<7>")
	)
	(arc
		(start 146.104864 -286.457898)
		(mid 146.2413 -286.514723)
		(end 146.38782 -286.534098)
		(width 0.0762)
		(layer "F.Cu")
		(net "M_G_CPU1_SB_DQS_DP<7>")
	)
	(arc
		(start 145.730722 -286.457898)
		(mid 145.912973 -286.407548)
		(end 146.096482 -286.453072)
		(width 0.0762)
		(layer "F.Cu")
		(net "M_G_CPU1_SB_DQS_DP<7>")
	)
	(arc
		(start 144.575784 -286.530288)
		(mid 144.68703 -286.505025)
		(end 144.790922 -286.457898)
		(width 0.0762)
		(layer "F.Cu")
		(net "M_G_CPU1_SB_DQS_DP<7>")
	)
	(segment
		(start 159.04972 -289.901884)
		(end 159.04972 -291.7444)
		(width 0.12954)
		(layer "F.Cu")
		(net "M_G_CPU1_SB_DQS_DP<6>")
	)
	(segment
		(start 147.626578 -281.347418)
		(end 147.834096 -281.347418)
		(width 0.0762)
		(layer "F.Cu")
		(net "M_G_CPU1_SB_DQS_DP<6>")
	)
	(segment
		(start 158.957518 -293.131494)
		(end 159.28848 -293.462456)
		(width 0.12954)
		(layer "F.Cu")
		(net "M_G_CPU1_SB_DQS_DP<6>")
	)
	(segment
		(start 161.298128 -294.191944)
		(end 161.497264 -294.191944)
		(width 0.12954)
		(layer "F.Cu")
		(net "M_G_CPU1_SB_DQS_DP<6>")
	)
	(segment
		(start 159.36468 -292.258496)
		(end 158.957518 -292.665658)
		(width 0.12954)
		(layer "F.Cu")
		(net "M_G_CPU1_SB_DQS_DP<6>")
	)
	(segment
		(start 146.38782 -281.674062)
		(end 147.299934 -281.674062)
		(width 0.0762)
		(layer "F.Cu")
		(net "M_G_CPU1_SB_DQS_DP<6>")
	)
	(segment
		(start 161.63798 -294.33266)
		(end 161.63798 -294.531796)
		(width 0.12954)
		(layer "F.Cu")
		(net "M_G_CPU1_SB_DQS_DP<6>")
	)
	(segment
		(start 161.63798 -294.531796)
		(end 161.230818 -294.938958)
		(width 0.12954)
		(layer "F.Cu")
		(net "M_G_CPU1_SB_DQS_DP<6>")
	)
	(segment
		(start 147.919186 -281.413458)
		(end 150.561294 -281.413458)
		(width 0.12954)
		(layer "F.Cu")
		(net "M_G_CPU1_SB_DQS_DP<6>")
	)
	(segment
		(start 161.230818 -295.404794)
		(end 161.56178 -295.735756)
		(width 0.12954)
		(layer "F.Cu")
		(net "M_G_CPU1_SB_DQS_DP<6>")
	)
	(segment
		(start 159.28848 -293.462456)
		(end 159.754316 -293.462456)
		(width 0.12954)
		(layer "F.Cu")
		(net "M_G_CPU1_SB_DQS_DP<6>")
	)
	(segment
		(start 163.606988 -295.671748)
		(end 163.87064 -295.9354)
		(width 0.12954)
		(layer "F.Cu")
		(net "M_G_CPU1_SB_DQS_DP<6>")
	)
	(segment
		(start 159.36468 -292.05936)
		(end 159.36468 -292.258496)
		(width 0.12954)
		(layer "F.Cu")
		(net "M_G_CPU1_SB_DQS_DP<6>")
	)
	(segment
		(start 160.360614 -293.055294)
		(end 160.50133 -293.19601)
		(width 0.12954)
		(layer "F.Cu")
		(net "M_G_CPU1_SB_DQS_DP<6>")
	)
	(segment
		(start 159.04972 -291.7444)
		(end 159.36468 -292.05936)
		(width 0.12954)
		(layer "F.Cu")
		(net "M_G_CPU1_SB_DQS_DP<6>")
	)
	(segment
		(start 160.42513 -294.599106)
		(end 160.890966 -294.599106)
		(width 0.12954)
		(layer "F.Cu")
		(net "M_G_CPU1_SB_DQS_DP<6>")
	)
	(segment
		(start 158.957518 -292.665658)
		(end 158.957518 -293.131494)
		(width 0.12954)
		(layer "F.Cu")
		(net "M_G_CPU1_SB_DQS_DP<6>")
	)
	(segment
		(start 161.497264 -294.191944)
		(end 161.63798 -294.33266)
		(width 0.12954)
		(layer "F.Cu")
		(net "M_G_CPU1_SB_DQS_DP<6>")
	)
	(segment
		(start 160.161478 -293.055294)
		(end 160.360614 -293.055294)
		(width 0.12954)
		(layer "F.Cu")
		(net "M_G_CPU1_SB_DQS_DP<6>")
	)
	(segment
		(start 146.096482 -281.593036)
		(end 146.104864 -281.597862)
		(width 0.0762)
		(layer "F.Cu")
		(net "M_G_CPU1_SB_DQS_DP<6>")
	)
	(segment
		(start 147.834096 -281.347418)
		(end 147.900136 -281.413458)
		(width 0.0762)
		(layer "F.Cu")
		(net "M_G_CPU1_SB_DQS_DP<6>")
	)
	(segment
		(start 160.890966 -294.599106)
		(end 161.298128 -294.191944)
		(width 0.12954)
		(layer "F.Cu")
		(net "M_G_CPU1_SB_DQS_DP<6>")
	)
	(segment
		(start 160.50133 -293.395146)
		(end 160.094168 -293.802308)
		(width 0.12954)
		(layer "F.Cu")
		(net "M_G_CPU1_SB_DQS_DP<6>")
	)
	(segment
		(start 159.754316 -293.462456)
		(end 160.161478 -293.055294)
		(width 0.12954)
		(layer "F.Cu")
		(net "M_G_CPU1_SB_DQS_DP<6>")
	)
	(segment
		(start 160.094168 -294.268144)
		(end 160.42513 -294.599106)
		(width 0.12954)
		(layer "F.Cu")
		(net "M_G_CPU1_SB_DQS_DP<6>")
	)
	(segment
		(start 161.56178 -295.735756)
		(end 162.027616 -295.735756)
		(width 0.12954)
		(layer "F.Cu")
		(net "M_G_CPU1_SB_DQS_DP<6>")
	)
	(segment
		(start 162.633914 -295.328594)
		(end 162.977068 -295.671748)
		(width 0.12954)
		(layer "F.Cu")
		(net "M_G_CPU1_SB_DQS_DP<6>")
	)
	(segment
		(start 147.900136 -281.413458)
		(end 147.919186 -281.413458)
		(width 0.0762)
		(layer "F.Cu")
		(net "M_G_CPU1_SB_DQS_DP<6>")
	)
	(segment
		(start 162.977068 -295.671748)
		(end 163.606988 -295.671748)
		(width 0.12954)
		(layer "F.Cu")
		(net "M_G_CPU1_SB_DQS_DP<6>")
	)
	(segment
		(start 163.87064 -295.9354)
		(end 164.427916 -295.9354)
		(width 0.12954)
		(layer "F.Cu")
		(net "M_G_CPU1_SB_DQS_DP<6>")
	)
	(segment
		(start 162.027616 -295.735756)
		(end 162.434778 -295.328594)
		(width 0.12954)
		(layer "F.Cu")
		(net "M_G_CPU1_SB_DQS_DP<6>")
	)
	(segment
		(start 160.094168 -293.802308)
		(end 160.094168 -294.268144)
		(width 0.12954)
		(layer "F.Cu")
		(net "M_G_CPU1_SB_DQS_DP<6>")
	)
	(segment
		(start 162.434778 -295.328594)
		(end 162.633914 -295.328594)
		(width 0.12954)
		(layer "F.Cu")
		(net "M_G_CPU1_SB_DQS_DP<6>")
	)
	(segment
		(start 150.561294 -281.413458)
		(end 159.04972 -289.901884)
		(width 0.12954)
		(layer "F.Cu")
		(net "M_G_CPU1_SB_DQS_DP<6>")
	)
	(segment
		(start 161.230818 -294.938958)
		(end 161.230818 -295.404794)
		(width 0.12954)
		(layer "F.Cu")
		(net "M_G_CPU1_SB_DQS_DP<6>")
	)
	(segment
		(start 160.50133 -293.19601)
		(end 160.50133 -293.395146)
		(width 0.12954)
		(layer "F.Cu")
		(net "M_G_CPU1_SB_DQS_DP<6>")
	)
	(segment
		(start 147.299934 -281.674062)
		(end 147.626578 -281.347418)
		(width 0.0762)
		(layer "F.Cu")
		(net "M_G_CPU1_SB_DQS_DP<6>")
	)
	(arc
		(start 145.730722 -281.597862)
		(mid 145.912973 -281.547512)
		(end 146.096482 -281.593036)
		(width 0.0762)
		(layer "F.Cu")
		(net "M_G_CPU1_SB_DQS_DP<6>")
	)
	(arc
		(start 144.037812 -281.920442)
		(mid 144.27181 -281.748399)
		(end 144.552162 -281.672538)
		(width 0.0762)
		(layer "F.Cu")
		(net "M_G_CPU1_SB_DQS_DP<6>")
	)
	(arc
		(start 144.790922 -281.597862)
		(mid 144.977866 -281.547607)
		(end 145.16481 -281.597862)
		(width 0.0762)
		(layer "F.Cu")
		(net "M_G_CPU1_SB_DQS_DP<6>")
	)
	(arc
		(start 146.104864 -281.597862)
		(mid 146.2413 -281.654687)
		(end 146.38782 -281.674062)
		(width 0.0762)
		(layer "F.Cu")
		(net "M_G_CPU1_SB_DQS_DP<6>")
	)
	(arc
		(start 145.16481 -281.597862)
		(mid 145.447766 -281.674039)
		(end 145.730722 -281.597862)
		(width 0.0762)
		(layer "F.Cu")
		(net "M_G_CPU1_SB_DQS_DP<6>")
	)
	(arc
		(start 144.575784 -281.670252)
		(mid 144.68703 -281.644989)
		(end 144.790922 -281.597862)
		(width 0.0762)
		(layer "F.Cu")
		(net "M_G_CPU1_SB_DQS_DP<6>")
	)
	(arc
		(start 144.552162 -281.672538)
		(mid 144.563985 -281.671521)
		(end 144.575784 -281.670252)
		(width 0.0762)
		(layer "F.Cu")
		(net "M_G_CPU1_SB_DQS_DP<6>")
	)
	(segment
		(start 154.429714 -276.736556)
		(end 156.775404 -279.082246)
		(width 0.12954)
		(layer "F.Cu")
		(net "M_G_CPU1_SB_DQS_DP<5>")
	)
	(segment
		(start 156.775404 -279.082246)
		(end 156.775404 -279.265634)
		(width 0.12954)
		(layer "F.Cu")
		(net "M_G_CPU1_SB_DQS_DP<5>")
	)
	(segment
		(start 158.787338 -281.800554)
		(end 158.787338 -282.266898)
		(width 0.12954)
		(layer "F.Cu")
		(net "M_G_CPU1_SB_DQS_DP<5>")
	)
	(segment
		(start 163.87064 -286.585406)
		(end 164.427916 -286.585406)
		(width 0.12954)
		(layer "F.Cu")
		(net "M_G_CPU1_SB_DQS_DP<5>")
	)
	(segment
		(start 147.292822 -276.814026)
		(end 147.436332 -276.670516)
		(width 0.0762)
		(layer "F.Cu")
		(net "M_G_CPU1_SB_DQS_DP<5>")
	)
	(segment
		(start 157.564328 -280.069544)
		(end 157.762702 -280.069544)
		(width 0.12954)
		(layer "F.Cu")
		(net "M_G_CPU1_SB_DQS_DP<5>")
	)
	(segment
		(start 159.837628 -282.342844)
		(end 160.036002 -282.342844)
		(width 0.12954)
		(layer "F.Cu")
		(net "M_G_CPU1_SB_DQS_DP<5>")
	)
	(segment
		(start 160.036002 -282.342844)
		(end 160.178242 -282.485084)
		(width 0.12954)
		(layer "F.Cu")
		(net "M_G_CPU1_SB_DQS_DP<5>")
	)
	(segment
		(start 147.436332 -276.670516)
		(end 147.834096 -276.670516)
		(width 0.0762)
		(layer "F.Cu")
		(net "M_G_CPU1_SB_DQS_DP<5>")
	)
	(segment
		(start 147.900136 -276.736556)
		(end 147.919186 -276.736556)
		(width 0.0762)
		(layer "F.Cu")
		(net "M_G_CPU1_SB_DQS_DP<5>")
	)
	(segment
		(start 146.096482 -276.733)
		(end 146.104864 -276.737826)
		(width 0.0762)
		(layer "F.Cu")
		(net "M_G_CPU1_SB_DQS_DP<5>")
	)
	(segment
		(start 159.923988 -283.403548)
		(end 162.842194 -286.321754)
		(width 0.12954)
		(layer "F.Cu")
		(net "M_G_CPU1_SB_DQS_DP<5>")
	)
	(segment
		(start 159.041338 -281.5463)
		(end 158.787338 -281.800554)
		(width 0.12954)
		(layer "F.Cu")
		(net "M_G_CPU1_SB_DQS_DP<5>")
	)
	(segment
		(start 157.650688 -280.663904)
		(end 157.650688 -281.130248)
		(width 0.12954)
		(layer "F.Cu")
		(net "M_G_CPU1_SB_DQS_DP<5>")
	)
	(segment
		(start 158.787338 -282.266898)
		(end 159.117284 -282.596844)
		(width 0.12954)
		(layer "F.Cu")
		(net "M_G_CPU1_SB_DQS_DP<5>")
	)
	(segment
		(start 159.041592 -281.348434)
		(end 159.041338 -281.5463)
		(width 0.12954)
		(layer "F.Cu")
		(net "M_G_CPU1_SB_DQS_DP<5>")
	)
	(segment
		(start 146.38782 -276.814026)
		(end 147.292822 -276.814026)
		(width 0.0762)
		(layer "F.Cu")
		(net "M_G_CPU1_SB_DQS_DP<5>")
	)
	(segment
		(start 157.904688 -280.40965)
		(end 157.650688 -280.663904)
		(width 0.12954)
		(layer "F.Cu")
		(net "M_G_CPU1_SB_DQS_DP<5>")
	)
	(segment
		(start 162.842194 -286.321754)
		(end 163.606988 -286.321754)
		(width 0.12954)
		(layer "F.Cu")
		(net "M_G_CPU1_SB_DQS_DP<5>")
	)
	(segment
		(start 158.700978 -281.206194)
		(end 158.899352 -281.206194)
		(width 0.12954)
		(layer "F.Cu")
		(net "M_G_CPU1_SB_DQS_DP<5>")
	)
	(segment
		(start 158.899352 -281.206194)
		(end 159.041592 -281.348434)
		(width 0.12954)
		(layer "F.Cu")
		(net "M_G_CPU1_SB_DQS_DP<5>")
	)
	(segment
		(start 159.117284 -282.596844)
		(end 159.583374 -282.596844)
		(width 0.12954)
		(layer "F.Cu")
		(net "M_G_CPU1_SB_DQS_DP<5>")
	)
	(segment
		(start 147.919186 -276.736556)
		(end 154.429714 -276.736556)
		(width 0.12954)
		(layer "F.Cu")
		(net "M_G_CPU1_SB_DQS_DP<5>")
	)
	(segment
		(start 160.178242 -282.485084)
		(end 160.177988 -282.68295)
		(width 0.12954)
		(layer "F.Cu")
		(net "M_G_CPU1_SB_DQS_DP<5>")
	)
	(segment
		(start 160.177988 -282.68295)
		(end 159.923988 -282.937204)
		(width 0.12954)
		(layer "F.Cu")
		(net "M_G_CPU1_SB_DQS_DP<5>")
	)
	(segment
		(start 157.980634 -281.460194)
		(end 158.446724 -281.460194)
		(width 0.12954)
		(layer "F.Cu")
		(net "M_G_CPU1_SB_DQS_DP<5>")
	)
	(segment
		(start 156.514038 -279.527)
		(end 156.514038 -279.993598)
		(width 0.12954)
		(layer "F.Cu")
		(net "M_G_CPU1_SB_DQS_DP<5>")
	)
	(segment
		(start 156.514038 -279.993598)
		(end 156.843984 -280.323544)
		(width 0.12954)
		(layer "F.Cu")
		(net "M_G_CPU1_SB_DQS_DP<5>")
	)
	(segment
		(start 158.446724 -281.460194)
		(end 158.700978 -281.206194)
		(width 0.12954)
		(layer "F.Cu")
		(net "M_G_CPU1_SB_DQS_DP<5>")
	)
	(segment
		(start 157.762702 -280.069544)
		(end 157.904942 -280.211784)
		(width 0.12954)
		(layer "F.Cu")
		(net "M_G_CPU1_SB_DQS_DP<5>")
	)
	(segment
		(start 163.606988 -286.321754)
		(end 163.87064 -286.585406)
		(width 0.12954)
		(layer "F.Cu")
		(net "M_G_CPU1_SB_DQS_DP<5>")
	)
	(segment
		(start 147.834096 -276.670516)
		(end 147.900136 -276.736556)
		(width 0.0762)
		(layer "F.Cu")
		(net "M_G_CPU1_SB_DQS_DP<5>")
	)
	(segment
		(start 156.775404 -279.265634)
		(end 156.514038 -279.527)
		(width 0.12954)
		(layer "F.Cu")
		(net "M_G_CPU1_SB_DQS_DP<5>")
	)
	(segment
		(start 157.310074 -280.323544)
		(end 157.564328 -280.069544)
		(width 0.12954)
		(layer "F.Cu")
		(net "M_G_CPU1_SB_DQS_DP<5>")
	)
	(segment
		(start 156.843984 -280.323544)
		(end 157.310074 -280.323544)
		(width 0.12954)
		(layer "F.Cu")
		(net "M_G_CPU1_SB_DQS_DP<5>")
	)
	(segment
		(start 157.650688 -281.130248)
		(end 157.980634 -281.460194)
		(width 0.12954)
		(layer "F.Cu")
		(net "M_G_CPU1_SB_DQS_DP<5>")
	)
	(segment
		(start 157.904942 -280.211784)
		(end 157.904688 -280.40965)
		(width 0.12954)
		(layer "F.Cu")
		(net "M_G_CPU1_SB_DQS_DP<5>")
	)
	(segment
		(start 159.923988 -282.937204)
		(end 159.923988 -283.403548)
		(width 0.12954)
		(layer "F.Cu")
		(net "M_G_CPU1_SB_DQS_DP<5>")
	)
	(segment
		(start 159.583374 -282.596844)
		(end 159.837628 -282.342844)
		(width 0.12954)
		(layer "F.Cu")
		(net "M_G_CPU1_SB_DQS_DP<5>")
	)
	(arc
		(start 144.552162 -276.812502)
		(mid 144.563985 -276.811485)
		(end 144.575784 -276.810216)
		(width 0.0762)
		(layer "F.Cu")
		(net "M_G_CPU1_SB_DQS_DP<5>")
	)
	(arc
		(start 145.16481 -276.737826)
		(mid 145.447766 -276.814003)
		(end 145.730722 -276.737826)
		(width 0.0762)
		(layer "F.Cu")
		(net "M_G_CPU1_SB_DQS_DP<5>")
	)
	(arc
		(start 146.104864 -276.737826)
		(mid 146.2413 -276.794651)
		(end 146.38782 -276.814026)
		(width 0.0762)
		(layer "F.Cu")
		(net "M_G_CPU1_SB_DQS_DP<5>")
	)
	(arc
		(start 145.730722 -276.737826)
		(mid 145.912973 -276.687476)
		(end 146.096482 -276.733)
		(width 0.0762)
		(layer "F.Cu")
		(net "M_G_CPU1_SB_DQS_DP<5>")
	)
	(arc
		(start 144.037812 -277.060406)
		(mid 144.27181 -276.888363)
		(end 144.552162 -276.812502)
		(width 0.0762)
		(layer "F.Cu")
		(net "M_G_CPU1_SB_DQS_DP<5>")
	)
	(arc
		(start 144.575784 -276.810216)
		(mid 144.68703 -276.784953)
		(end 144.790922 -276.737826)
		(width 0.0762)
		(layer "F.Cu")
		(net "M_G_CPU1_SB_DQS_DP<5>")
	)
	(arc
		(start 144.790922 -276.737826)
		(mid 144.977866 -276.687571)
		(end 145.16481 -276.737826)
		(width 0.0762)
		(layer "F.Cu")
		(net "M_G_CPU1_SB_DQS_DP<5>")
	)
	(segment
		(start 158.702756 -273.27225)
		(end 159.169608 -273.27225)
		(width 0.12954)
		(layer "F.Cu")
		(net "M_G_CPU1_SB_DQS_DP<4>")
	)
	(segment
		(start 161.887154 -275.867368)
		(end 161.887154 -276.456648)
		(width 0.12954)
		(layer "F.Cu")
		(net "M_G_CPU1_SB_DQS_DP<4>")
	)
	(segment
		(start 158.206186 -271.962372)
		(end 158.45282 -271.715738)
		(width 0.12954)
		(layer "F.Cu")
		(net "M_G_CPU1_SB_DQS_DP<4>")
	)
	(segment
		(start 160.750504 -274.730718)
		(end 160.750504 -275.319998)
		(width 0.12954)
		(layer "F.Cu")
		(net "M_G_CPU1_SB_DQS_DP<4>")
	)
	(segment
		(start 158.373318 -272.942812)
		(end 158.702756 -273.27225)
		(width 0.12954)
		(layer "F.Cu")
		(net "M_G_CPU1_SB_DQS_DP<4>")
	)
	(segment
		(start 159.695896 -272.745962)
		(end 159.894016 -272.745962)
		(width 0.12954)
		(layer "F.Cu")
		(net "M_G_CPU1_SB_DQS_DP<4>")
	)
	(segment
		(start 160.036256 -272.888202)
		(end 160.036256 -273.086322)
		(width 0.12954)
		(layer "F.Cu")
		(net "M_G_CPU1_SB_DQS_DP<4>")
	)
	(segment
		(start 147.292822 -271.95399)
		(end 147.597114 -271.649698)
		(width 0.0762)
		(layer "F.Cu")
		(net "M_G_CPU1_SB_DQS_DP<4>")
	)
	(segment
		(start 161.887154 -276.456648)
		(end 162.402266 -276.97176)
		(width 0.12954)
		(layer "F.Cu")
		(net "M_G_CPU1_SB_DQS_DP<4>")
	)
	(segment
		(start 159.981138 -274.550632)
		(end 160.570418 -274.550632)
		(width 0.12954)
		(layer "F.Cu")
		(net "M_G_CPU1_SB_DQS_DP<4>")
	)
	(segment
		(start 159.894016 -272.745962)
		(end 160.036256 -272.888202)
		(width 0.12954)
		(layer "F.Cu")
		(net "M_G_CPU1_SB_DQS_DP<4>")
	)
	(segment
		(start 160.750504 -275.319998)
		(end 161.117788 -275.687282)
		(width 0.12954)
		(layer "F.Cu")
		(net "M_G_CPU1_SB_DQS_DP<4>")
	)
	(segment
		(start 159.169608 -273.27225)
		(end 159.695896 -272.745962)
		(width 0.12954)
		(layer "F.Cu")
		(net "M_G_CPU1_SB_DQS_DP<4>")
	)
	(segment
		(start 160.036256 -273.086322)
		(end 159.50184 -273.620738)
		(width 0.12954)
		(layer "F.Cu")
		(net "M_G_CPU1_SB_DQS_DP<4>")
	)
	(segment
		(start 159.50184 -274.071334)
		(end 159.981138 -274.550632)
		(width 0.12954)
		(layer "F.Cu")
		(net "M_G_CPU1_SB_DQS_DP<4>")
	)
	(segment
		(start 158.79318 -272.056098)
		(end 158.373318 -272.47596)
		(width 0.12954)
		(layer "F.Cu")
		(net "M_G_CPU1_SB_DQS_DP<4>")
	)
	(segment
		(start 159.50184 -273.620738)
		(end 159.50184 -274.071334)
		(width 0.12954)
		(layer "F.Cu")
		(net "M_G_CPU1_SB_DQS_DP<4>")
	)
	(segment
		(start 163.606988 -276.97176)
		(end 163.87064 -277.235412)
		(width 0.12954)
		(layer "F.Cu")
		(net "M_G_CPU1_SB_DQS_DP<4>")
	)
	(segment
		(start 147.597114 -271.649698)
		(end 147.834096 -271.649698)
		(width 0.0762)
		(layer "F.Cu")
		(net "M_G_CPU1_SB_DQS_DP<4>")
	)
	(segment
		(start 158.65094 -271.715738)
		(end 158.79318 -271.857978)
		(width 0.12954)
		(layer "F.Cu")
		(net "M_G_CPU1_SB_DQS_DP<4>")
	)
	(segment
		(start 160.570418 -274.550632)
		(end 160.750504 -274.730718)
		(width 0.12954)
		(layer "F.Cu")
		(net "M_G_CPU1_SB_DQS_DP<4>")
	)
	(segment
		(start 163.87064 -277.235412)
		(end 164.427916 -277.235412)
		(width 0.12954)
		(layer "F.Cu")
		(net "M_G_CPU1_SB_DQS_DP<4>")
	)
	(segment
		(start 147.834096 -271.649698)
		(end 147.900136 -271.715738)
		(width 0.0762)
		(layer "F.Cu")
		(net "M_G_CPU1_SB_DQS_DP<4>")
	)
	(segment
		(start 161.117788 -275.687282)
		(end 161.707068 -275.687282)
		(width 0.12954)
		(layer "F.Cu")
		(net "M_G_CPU1_SB_DQS_DP<4>")
	)
	(segment
		(start 158.45282 -271.715738)
		(end 158.65094 -271.715738)
		(width 0.12954)
		(layer "F.Cu")
		(net "M_G_CPU1_SB_DQS_DP<4>")
	)
	(segment
		(start 146.38782 -271.95399)
		(end 147.292822 -271.95399)
		(width 0.0762)
		(layer "F.Cu")
		(net "M_G_CPU1_SB_DQS_DP<4>")
	)
	(segment
		(start 146.096482 -271.872964)
		(end 146.104864 -271.87779)
		(width 0.0762)
		(layer "F.Cu")
		(net "M_G_CPU1_SB_DQS_DP<4>")
	)
	(segment
		(start 147.900136 -271.715738)
		(end 147.919186 -271.715738)
		(width 0.0762)
		(layer "F.Cu")
		(net "M_G_CPU1_SB_DQS_DP<4>")
	)
	(segment
		(start 158.79318 -271.857978)
		(end 158.79318 -272.056098)
		(width 0.12954)
		(layer "F.Cu")
		(net "M_G_CPU1_SB_DQS_DP<4>")
	)
	(segment
		(start 157.739334 -271.962372)
		(end 158.206186 -271.962372)
		(width 0.12954)
		(layer "F.Cu")
		(net "M_G_CPU1_SB_DQS_DP<4>")
	)
	(segment
		(start 157.4927 -271.715738)
		(end 157.739334 -271.962372)
		(width 0.12954)
		(layer "F.Cu")
		(net "M_G_CPU1_SB_DQS_DP<4>")
	)
	(segment
		(start 147.919186 -271.715738)
		(end 157.4927 -271.715738)
		(width 0.12954)
		(layer "F.Cu")
		(net "M_G_CPU1_SB_DQS_DP<4>")
	)
	(segment
		(start 162.402266 -276.97176)
		(end 163.606988 -276.97176)
		(width 0.12954)
		(layer "F.Cu")
		(net "M_G_CPU1_SB_DQS_DP<4>")
	)
	(segment
		(start 158.373318 -272.47596)
		(end 158.373318 -272.942812)
		(width 0.12954)
		(layer "F.Cu")
		(net "M_G_CPU1_SB_DQS_DP<4>")
	)
	(segment
		(start 161.707068 -275.687282)
		(end 161.887154 -275.867368)
		(width 0.12954)
		(layer "F.Cu")
		(net "M_G_CPU1_SB_DQS_DP<4>")
	)
	(arc
		(start 144.790922 -271.87779)
		(mid 144.977866 -271.827535)
		(end 145.16481 -271.87779)
		(width 0.0762)
		(layer "F.Cu")
		(net "M_G_CPU1_SB_DQS_DP<4>")
	)
	(arc
		(start 146.104864 -271.87779)
		(mid 146.2413 -271.934615)
		(end 146.38782 -271.95399)
		(width 0.0762)
		(layer "F.Cu")
		(net "M_G_CPU1_SB_DQS_DP<4>")
	)
	(arc
		(start 144.575784 -271.95018)
		(mid 144.68703 -271.924917)
		(end 144.790922 -271.87779)
		(width 0.0762)
		(layer "F.Cu")
		(net "M_G_CPU1_SB_DQS_DP<4>")
	)
	(arc
		(start 144.037812 -272.20037)
		(mid 144.27181 -272.028327)
		(end 144.552162 -271.952466)
		(width 0.0762)
		(layer "F.Cu")
		(net "M_G_CPU1_SB_DQS_DP<4>")
	)
	(arc
		(start 144.552162 -271.952466)
		(mid 144.563985 -271.951449)
		(end 144.575784 -271.95018)
		(width 0.0762)
		(layer "F.Cu")
		(net "M_G_CPU1_SB_DQS_DP<4>")
	)
	(arc
		(start 145.730722 -271.87779)
		(mid 145.912973 -271.82744)
		(end 146.096482 -271.872964)
		(width 0.0762)
		(layer "F.Cu")
		(net "M_G_CPU1_SB_DQS_DP<4>")
	)
	(arc
		(start 145.16481 -271.87779)
		(mid 145.447766 -271.953967)
		(end 145.730722 -271.87779)
		(width 0.0762)
		(layer "F.Cu")
		(net "M_G_CPU1_SB_DQS_DP<4>")
	)
	(segment
		(start 162.87242 -312.774838)
		(end 163.302188 -312.774838)
		(width 0.12954)
		(layer "F.Cu")
		(net "M_G_CPU1_SB_DQS_DP<3>")
	)
	(segment
		(start 149.86381 -298.559474)
		(end 161.830004 -310.525668)
		(width 0.12954)
		(layer "F.Cu")
		(net "M_G_CPU1_SB_DQS_DP<3>")
	)
	(segment
		(start 147.710144 -290.451286)
		(end 147.776184 -290.385246)
		(width 0.0762)
		(layer "F.Cu")
		(net "M_G_CPU1_SB_DQS_DP<3>")
	)
	(segment
		(start 167.697404 -313.252358)
		(end 168.014396 -312.935366)
		(width 0.101346)
		(layer "F.Cu")
		(net "M_G_CPU1_SB_DQS_DP<3>")
	)
	(segment
		(start 163.566602 -312.510424)
		(end 165.99535 -312.510424)
		(width 0.101346)
		(layer "F.Cu")
		(net "M_G_CPU1_SB_DQS_DP<3>")
	)
	(segment
		(start 161.558732 -311.46115)
		(end 161.699956 -311.602374)
		(width 0.12954)
		(layer "F.Cu")
		(net "M_G_CPU1_SB_DQS_DP<3>")
	)
	(segment
		(start 162.695382 -312.399172)
		(end 162.695382 -312.5978)
		(width 0.12954)
		(layer "F.Cu")
		(net "M_G_CPU1_SB_DQS_DP<3>")
	)
	(segment
		(start 162.966654 -311.662318)
		(end 162.966654 -312.1279)
		(width 0.12954)
		(layer "F.Cu")
		(net "M_G_CPU1_SB_DQS_DP<3>")
	)
	(segment
		(start 162.695382 -312.5978)
		(end 162.87242 -312.774838)
		(width 0.12954)
		(layer "F.Cu")
		(net "M_G_CPU1_SB_DQS_DP<3>")
	)
	(segment
		(start 167.132254 -313.252358)
		(end 167.697404 -313.252358)
		(width 0.101346)
		(layer "F.Cu")
		(net "M_G_CPU1_SB_DQS_DP<3>")
	)
	(segment
		(start 161.558732 -311.262522)
		(end 161.558732 -311.46115)
		(width 0.12954)
		(layer "F.Cu")
		(net "M_G_CPU1_SB_DQS_DP<3>")
	)
	(segment
		(start 146.387566 -290.266628)
		(end 147.34032 -290.266628)
		(width 0.0762)
		(layer "F.Cu")
		(net "M_G_CPU1_SB_DQS_DP<3>")
	)
	(segment
		(start 162.635692 -311.331356)
		(end 162.966654 -311.662318)
		(width 0.12954)
		(layer "F.Cu")
		(net "M_G_CPU1_SB_DQS_DP<3>")
	)
	(segment
		(start 149.86381 -291.886386)
		(end 149.86381 -298.559474)
		(width 0.12954)
		(layer "F.Cu")
		(net "M_G_CPU1_SB_DQS_DP<3>")
	)
	(segment
		(start 145.91792 -290.020248)
		(end 145.815558 -290.196524)
		(width 0.0762)
		(layer "F.Cu")
		(net "M_G_CPU1_SB_DQS_DP<3>")
	)
	(segment
		(start 161.830004 -310.525668)
		(end 161.830004 -310.99125)
		(width 0.12954)
		(layer "F.Cu")
		(net "M_G_CPU1_SB_DQS_DP<3>")
	)
	(segment
		(start 147.795234 -290.385246)
		(end 148.36267 -290.385246)
		(width 0.12954)
		(layer "F.Cu")
		(net "M_G_CPU1_SB_DQS_DP<3>")
	)
	(segment
		(start 147.776184 -290.385246)
		(end 147.795234 -290.385246)
		(width 0.0762)
		(layer "F.Cu")
		(net "M_G_CPU1_SB_DQS_DP<3>")
	)
	(segment
		(start 165.99535 -312.510424)
		(end 166.312088 -312.827162)
		(width 0.101346)
		(layer "F.Cu")
		(net "M_G_CPU1_SB_DQS_DP<3>")
	)
	(segment
		(start 161.898584 -311.602374)
		(end 162.169856 -311.331356)
		(width 0.12954)
		(layer "F.Cu")
		(net "M_G_CPU1_SB_DQS_DP<3>")
	)
	(segment
		(start 146.096482 -290.347654)
		(end 146.104864 -290.342828)
		(width 0.0762)
		(layer "F.Cu")
		(net "M_G_CPU1_SB_DQS_DP<3>")
	)
	(segment
		(start 161.699956 -311.602374)
		(end 161.898584 -311.602374)
		(width 0.12954)
		(layer "F.Cu")
		(net "M_G_CPU1_SB_DQS_DP<3>")
	)
	(segment
		(start 162.966654 -312.1279)
		(end 162.695382 -312.399172)
		(width 0.12954)
		(layer "F.Cu")
		(net "M_G_CPU1_SB_DQS_DP<3>")
	)
	(segment
		(start 166.707058 -312.827162)
		(end 167.132254 -313.252358)
		(width 0.101346)
		(layer "F.Cu")
		(net "M_G_CPU1_SB_DQS_DP<3>")
	)
	(segment
		(start 166.312088 -312.827162)
		(end 166.707058 -312.827162)
		(width 0.101346)
		(layer "F.Cu")
		(net "M_G_CPU1_SB_DQS_DP<3>")
	)
	(segment
		(start 147.34032 -290.266628)
		(end 147.524978 -290.451286)
		(width 0.0762)
		(layer "F.Cu")
		(net "M_G_CPU1_SB_DQS_DP<3>")
	)
	(segment
		(start 163.302188 -312.774838)
		(end 163.566602 -312.510424)
		(width 0.12954)
		(layer "F.Cu")
		(net "M_G_CPU1_SB_DQS_DP<3>")
	)
	(segment
		(start 161.830004 -310.99125)
		(end 161.558732 -311.262522)
		(width 0.12954)
		(layer "F.Cu")
		(net "M_G_CPU1_SB_DQS_DP<3>")
	)
	(segment
		(start 147.524978 -290.451286)
		(end 147.710144 -290.451286)
		(width 0.0762)
		(layer "F.Cu")
		(net "M_G_CPU1_SB_DQS_DP<3>")
	)
	(segment
		(start 162.169856 -311.331356)
		(end 162.635692 -311.331356)
		(width 0.12954)
		(layer "F.Cu")
		(net "M_G_CPU1_SB_DQS_DP<3>")
	)
	(segment
		(start 148.36267 -290.385246)
		(end 149.86381 -291.886386)
		(width 0.12954)
		(layer "F.Cu")
		(net "M_G_CPU1_SB_DQS_DP<3>")
	)
	(segment
		(start 168.014396 -312.935366)
		(end 168.527984 -312.935366)
		(width 0.101346)
		(layer "F.Cu")
		(net "M_G_CPU1_SB_DQS_DP<3>")
	)
	(arc
		(start 145.815558 -290.196524)
		(mid 145.845187 -290.339011)
		(end 145.982436 -290.387532)
		(width 0.0762)
		(layer "F.Cu")
		(net "M_G_CPU1_SB_DQS_DP<3>")
	)
	(arc
		(start 145.982436 -290.387532)
		(mid 146.041082 -290.372239)
		(end 146.096482 -290.347654)
		(width 0.0762)
		(layer "F.Cu")
		(net "M_G_CPU1_SB_DQS_DP<3>")
	)
	(arc
		(start 146.340576 -290.268406)
		(mid 146.364053 -290.26703)
		(end 146.387566 -290.266628)
		(width 0.0762)
		(layer "F.Cu")
		(net "M_G_CPU1_SB_DQS_DP<3>")
	)
	(arc
		(start 146.104864 -290.342828)
		(mid 146.218588 -290.292527)
		(end 146.340576 -290.268406)
		(width 0.0762)
		(layer "F.Cu")
		(net "M_G_CPU1_SB_DQS_DP<3>")
	)
	(segment
		(start 161.23285 -302.240442)
		(end 161.42716 -302.046132)
		(width 0.12954)
		(layer "F.Cu")
		(net "M_G_CPU1_SB_DQS_DP<2>")
	)
	(segment
		(start 149.67331 -285.356046)
		(end 154.255724 -289.93846)
		(width 0.12954)
		(layer "F.Cu")
		(net "M_G_CPU1_SB_DQS_DP<2>")
	)
	(segment
		(start 161.087308 -301.25162)
		(end 161.087308 -301.70628)
		(width 0.12954)
		(layer "F.Cu")
		(net "M_G_CPU1_SB_DQS_DP<2>")
	)
	(segment
		(start 154.255724 -294.420036)
		(end 161.087308 -301.25162)
		(width 0.12954)
		(layer "F.Cu")
		(net "M_G_CPU1_SB_DQS_DP<2>")
	)
	(segment
		(start 163.302188 -303.424844)
		(end 163.566602 -303.16043)
		(width 0.12954)
		(layer "F.Cu")
		(net "M_G_CPU1_SB_DQS_DP<2>")
	)
	(segment
		(start 166.312088 -303.477168)
		(end 166.68115 -303.477168)
		(width 0.101346)
		(layer "F.Cu")
		(net "M_G_CPU1_SB_DQS_DP<2>")
	)
	(segment
		(start 147.50161 -285.422086)
		(end 147.834096 -285.422086)
		(width 0.0762)
		(layer "F.Cu")
		(net "M_G_CPU1_SB_DQS_DP<2>")
	)
	(segment
		(start 146.096482 -285.487872)
		(end 146.104864 -285.483046)
		(width 0.0762)
		(layer "F.Cu")
		(net "M_G_CPU1_SB_DQS_DP<2>")
	)
	(segment
		(start 145.91792 -285.160466)
		(end 145.815558 -285.336742)
		(width 0.0762)
		(layer "F.Cu")
		(net "M_G_CPU1_SB_DQS_DP<2>")
	)
	(segment
		(start 154.255724 -289.93846)
		(end 154.255724 -294.420036)
		(width 0.12954)
		(layer "F.Cu")
		(net "M_G_CPU1_SB_DQS_DP<2>")
	)
	(segment
		(start 161.087308 -301.70628)
		(end 160.892998 -301.90059)
		(width 0.12954)
		(layer "F.Cu")
		(net "M_G_CPU1_SB_DQS_DP<2>")
	)
	(segment
		(start 147.919186 -285.356046)
		(end 149.67331 -285.356046)
		(width 0.12954)
		(layer "F.Cu")
		(net "M_G_CPU1_SB_DQS_DP<2>")
	)
	(segment
		(start 165.99535 -303.16043)
		(end 166.312088 -303.477168)
		(width 0.101346)
		(layer "F.Cu")
		(net "M_G_CPU1_SB_DQS_DP<2>")
	)
	(segment
		(start 162.029648 -303.03724)
		(end 162.029648 -303.236376)
		(width 0.12954)
		(layer "F.Cu")
		(net "M_G_CPU1_SB_DQS_DP<2>")
	)
	(segment
		(start 163.566602 -303.16043)
		(end 165.99535 -303.16043)
		(width 0.101346)
		(layer "F.Cu")
		(net "M_G_CPU1_SB_DQS_DP<2>")
	)
	(segment
		(start 162.223958 -302.377094)
		(end 162.223958 -302.84293)
		(width 0.12954)
		(layer "F.Cu")
		(net "M_G_CPU1_SB_DQS_DP<2>")
	)
	(segment
		(start 147.900136 -285.356046)
		(end 147.919186 -285.356046)
		(width 0.0762)
		(layer "F.Cu")
		(net "M_G_CPU1_SB_DQS_DP<2>")
	)
	(segment
		(start 162.223958 -302.84293)
		(end 162.029648 -303.03724)
		(width 0.12954)
		(layer "F.Cu")
		(net "M_G_CPU1_SB_DQS_DP<2>")
	)
	(segment
		(start 168.014396 -303.585372)
		(end 168.527984 -303.585372)
		(width 0.101346)
		(layer "F.Cu")
		(net "M_G_CPU1_SB_DQS_DP<2>")
	)
	(segment
		(start 167.106346 -303.902364)
		(end 167.697404 -303.902364)
		(width 0.101346)
		(layer "F.Cu")
		(net "M_G_CPU1_SB_DQS_DP<2>")
	)
	(segment
		(start 166.68115 -303.477168)
		(end 167.106346 -303.902364)
		(width 0.101346)
		(layer "F.Cu")
		(net "M_G_CPU1_SB_DQS_DP<2>")
	)
	(segment
		(start 161.892996 -302.046132)
		(end 162.223958 -302.377094)
		(width 0.12954)
		(layer "F.Cu")
		(net "M_G_CPU1_SB_DQS_DP<2>")
	)
	(segment
		(start 147.48637 -285.406846)
		(end 147.50161 -285.422086)
		(width 0.0762)
		(layer "F.Cu")
		(net "M_G_CPU1_SB_DQS_DP<2>")
	)
	(segment
		(start 160.892998 -302.099726)
		(end 161.033714 -302.240442)
		(width 0.12954)
		(layer "F.Cu")
		(net "M_G_CPU1_SB_DQS_DP<2>")
	)
	(segment
		(start 162.029648 -303.236376)
		(end 162.218116 -303.424844)
		(width 0.12954)
		(layer "F.Cu")
		(net "M_G_CPU1_SB_DQS_DP<2>")
	)
	(segment
		(start 161.42716 -302.046132)
		(end 161.892996 -302.046132)
		(width 0.12954)
		(layer "F.Cu")
		(net "M_G_CPU1_SB_DQS_DP<2>")
	)
	(segment
		(start 167.697404 -303.902364)
		(end 168.014396 -303.585372)
		(width 0.101346)
		(layer "F.Cu")
		(net "M_G_CPU1_SB_DQS_DP<2>")
	)
	(segment
		(start 146.387566 -285.406846)
		(end 147.48637 -285.406846)
		(width 0.0762)
		(layer "F.Cu")
		(net "M_G_CPU1_SB_DQS_DP<2>")
	)
	(segment
		(start 161.033714 -302.240442)
		(end 161.23285 -302.240442)
		(width 0.12954)
		(layer "F.Cu")
		(net "M_G_CPU1_SB_DQS_DP<2>")
	)
	(segment
		(start 162.218116 -303.424844)
		(end 163.302188 -303.424844)
		(width 0.12954)
		(layer "F.Cu")
		(net "M_G_CPU1_SB_DQS_DP<2>")
	)
	(segment
		(start 160.892998 -301.90059)
		(end 160.892998 -302.099726)
		(width 0.12954)
		(layer "F.Cu")
		(net "M_G_CPU1_SB_DQS_DP<2>")
	)
	(segment
		(start 147.834096 -285.422086)
		(end 147.900136 -285.356046)
		(width 0.0762)
		(layer "F.Cu")
		(net "M_G_CPU1_SB_DQS_DP<2>")
	)
	(arc
		(start 146.340576 -285.408624)
		(mid 146.364053 -285.407248)
		(end 146.387566 -285.406846)
		(width 0.0762)
		(layer "F.Cu")
		(net "M_G_CPU1_SB_DQS_DP<2>")
	)
	(arc
		(start 146.104864 -285.483046)
		(mid 146.218588 -285.432745)
		(end 146.340576 -285.408624)
		(width 0.0762)
		(layer "F.Cu")
		(net "M_G_CPU1_SB_DQS_DP<2>")
	)
	(arc
		(start 145.815558 -285.336742)
		(mid 145.845187 -285.479229)
		(end 145.982436 -285.52775)
		(width 0.0762)
		(layer "F.Cu")
		(net "M_G_CPU1_SB_DQS_DP<2>")
	)
	(arc
		(start 145.982436 -285.52775)
		(mid 146.041082 -285.512457)
		(end 146.096482 -285.487872)
		(width 0.0762)
		(layer "F.Cu")
		(net "M_G_CPU1_SB_DQS_DP<2>")
	)
	(segment
		(start 160.11652 -291.301932)
		(end 160.257236 -291.442648)
		(width 0.12954)
		(layer "F.Cu")
		(net "M_G_CPU1_SB_DQS_DP<1>")
	)
	(segment
		(start 167.124126 -294.55237)
		(end 167.697404 -294.55237)
		(width 0.101346)
		(layer "F.Cu")
		(net "M_G_CPU1_SB_DQS_DP<1>")
	)
	(segment
		(start 165.99535 -293.810436)
		(end 166.312088 -294.127174)
		(width 0.101346)
		(layer "F.Cu")
		(net "M_G_CPU1_SB_DQS_DP<1>")
	)
	(segment
		(start 147.508976 -280.289508)
		(end 147.834096 -280.289508)
		(width 0.0762)
		(layer "F.Cu")
		(net "M_G_CPU1_SB_DQS_DP<1>")
	)
	(segment
		(start 167.697404 -294.55237)
		(end 168.014396 -294.235378)
		(width 0.101346)
		(layer "F.Cu")
		(net "M_G_CPU1_SB_DQS_DP<1>")
	)
	(segment
		(start 161.819082 -291.673534)
		(end 161.25317 -292.239446)
		(width 0.12954)
		(layer "F.Cu")
		(net "M_G_CPU1_SB_DQS_DP<1>")
	)
	(segment
		(start 160.682432 -290.025328)
		(end 160.682432 -290.536884)
		(width 0.12954)
		(layer "F.Cu")
		(net "M_G_CPU1_SB_DQS_DP<1>")
	)
	(segment
		(start 147.834096 -280.289508)
		(end 147.900136 -280.223468)
		(width 0.0762)
		(layer "F.Cu")
		(net "M_G_CPU1_SB_DQS_DP<1>")
	)
	(segment
		(start 162.889438 -294.07485)
		(end 163.302188 -294.07485)
		(width 0.12954)
		(layer "F.Cu")
		(net "M_G_CPU1_SB_DQS_DP<1>")
	)
	(segment
		(start 168.014396 -294.235378)
		(end 168.527984 -294.235378)
		(width 0.101346)
		(layer "F.Cu")
		(net "M_G_CPU1_SB_DQS_DP<1>")
	)
	(segment
		(start 147.251674 -280.54681)
		(end 147.508976 -280.289508)
		(width 0.0762)
		(layer "F.Cu")
		(net "M_G_CPU1_SB_DQS_DP<1>")
	)
	(segment
		(start 146.096482 -280.627836)
		(end 146.104864 -280.62301)
		(width 0.0762)
		(layer "F.Cu")
		(net "M_G_CPU1_SB_DQS_DP<1>")
	)
	(segment
		(start 163.302188 -294.07485)
		(end 163.566602 -293.810436)
		(width 0.12954)
		(layer "F.Cu")
		(net "M_G_CPU1_SB_DQS_DP<1>")
	)
	(segment
		(start 161.25317 -292.239446)
		(end 161.25317 -292.438582)
		(width 0.12954)
		(layer "F.Cu")
		(net "M_G_CPU1_SB_DQS_DP<1>")
	)
	(segment
		(start 160.11652 -291.102796)
		(end 160.11652 -291.301932)
		(width 0.12954)
		(layer "F.Cu")
		(net "M_G_CPU1_SB_DQS_DP<1>")
	)
	(segment
		(start 166.312088 -294.127174)
		(end 166.69893 -294.127174)
		(width 0.101346)
		(layer "F.Cu")
		(net "M_G_CPU1_SB_DQS_DP<1>")
	)
	(segment
		(start 161.25317 -292.438582)
		(end 162.889438 -294.07485)
		(width 0.12954)
		(layer "F.Cu")
		(net "M_G_CPU1_SB_DQS_DP<1>")
	)
	(segment
		(start 150.880572 -280.223468)
		(end 160.682432 -290.025328)
		(width 0.12954)
		(layer "F.Cu")
		(net "M_G_CPU1_SB_DQS_DP<1>")
	)
	(segment
		(start 147.919186 -280.223468)
		(end 150.880572 -280.223468)
		(width 0.12954)
		(layer "F.Cu")
		(net "M_G_CPU1_SB_DQS_DP<1>")
	)
	(segment
		(start 145.91792 -280.30043)
		(end 145.815558 -280.476706)
		(width 0.0762)
		(layer "F.Cu")
		(net "M_G_CPU1_SB_DQS_DP<1>")
	)
	(segment
		(start 160.682432 -290.536884)
		(end 160.11652 -291.102796)
		(width 0.12954)
		(layer "F.Cu")
		(net "M_G_CPU1_SB_DQS_DP<1>")
	)
	(segment
		(start 161.819082 -291.207698)
		(end 161.819082 -291.673534)
		(width 0.12954)
		(layer "F.Cu")
		(net "M_G_CPU1_SB_DQS_DP<1>")
	)
	(segment
		(start 160.456372 -291.442648)
		(end 161.022284 -290.876736)
		(width 0.12954)
		(layer "F.Cu")
		(net "M_G_CPU1_SB_DQS_DP<1>")
	)
	(segment
		(start 147.900136 -280.223468)
		(end 147.919186 -280.223468)
		(width 0.0762)
		(layer "F.Cu")
		(net "M_G_CPU1_SB_DQS_DP<1>")
	)
	(segment
		(start 166.69893 -294.127174)
		(end 167.124126 -294.55237)
		(width 0.101346)
		(layer "F.Cu")
		(net "M_G_CPU1_SB_DQS_DP<1>")
	)
	(segment
		(start 160.257236 -291.442648)
		(end 160.456372 -291.442648)
		(width 0.12954)
		(layer "F.Cu")
		(net "M_G_CPU1_SB_DQS_DP<1>")
	)
	(segment
		(start 163.566602 -293.810436)
		(end 165.99535 -293.810436)
		(width 0.101346)
		(layer "F.Cu")
		(net "M_G_CPU1_SB_DQS_DP<1>")
	)
	(segment
		(start 161.48812 -290.876736)
		(end 161.819082 -291.207698)
		(width 0.12954)
		(layer "F.Cu")
		(net "M_G_CPU1_SB_DQS_DP<1>")
	)
	(segment
		(start 161.022284 -290.876736)
		(end 161.48812 -290.876736)
		(width 0.12954)
		(layer "F.Cu")
		(net "M_G_CPU1_SB_DQS_DP<1>")
	)
	(segment
		(start 146.387566 -280.54681)
		(end 147.251674 -280.54681)
		(width 0.0762)
		(layer "F.Cu")
		(net "M_G_CPU1_SB_DQS_DP<1>")
	)
	(arc
		(start 146.104864 -280.62301)
		(mid 146.218588 -280.572709)
		(end 146.340576 -280.548588)
		(width 0.0762)
		(layer "F.Cu")
		(net "M_G_CPU1_SB_DQS_DP<1>")
	)
	(arc
		(start 145.982436 -280.667714)
		(mid 146.041082 -280.652421)
		(end 146.096482 -280.627836)
		(width 0.0762)
		(layer "F.Cu")
		(net "M_G_CPU1_SB_DQS_DP<1>")
	)
	(arc
		(start 145.815558 -280.476706)
		(mid 145.845187 -280.619193)
		(end 145.982436 -280.667714)
		(width 0.0762)
		(layer "F.Cu")
		(net "M_G_CPU1_SB_DQS_DP<1>")
	)
	(arc
		(start 146.340576 -280.548588)
		(mid 146.364053 -280.547212)
		(end 146.387566 -280.54681)
		(width 0.0762)
		(layer "F.Cu")
		(net "M_G_CPU1_SB_DQS_DP<1>")
	)
	(segment
		(start 161.525712 -283.449522)
		(end 161.723578 -283.449268)
		(width 0.12954)
		(layer "F.Cu")
		(net "M_G_CPU1_SB_DQS_DP<0>")
	)
	(segment
		(start 146.387566 -275.686774)
		(end 147.381722 -275.686774)
		(width 0.0762)
		(layer "F.Cu")
		(net "M_G_CPU1_SB_DQS_DP<0>")
	)
	(segment
		(start 147.421854 -275.726906)
		(end 147.834096 -275.726906)
		(width 0.0762)
		(layer "F.Cu")
		(net "M_G_CPU1_SB_DQS_DP<0>")
	)
	(segment
		(start 167.697404 -285.202376)
		(end 168.014396 -284.885384)
		(width 0.101346)
		(layer "F.Cu")
		(net "M_G_CPU1_SB_DQS_DP<0>")
	)
	(segment
		(start 145.91792 -275.440394)
		(end 145.815558 -275.61667)
		(width 0.0762)
		(layer "F.Cu")
		(net "M_G_CPU1_SB_DQS_DP<0>")
	)
	(segment
		(start 163.566602 -284.460442)
		(end 165.99535 -284.460442)
		(width 0.101346)
		(layer "F.Cu")
		(net "M_G_CPU1_SB_DQS_DP<0>")
	)
	(segment
		(start 168.014396 -284.885384)
		(end 168.527984 -284.885384)
		(width 0.101346)
		(layer "F.Cu")
		(net "M_G_CPU1_SB_DQS_DP<0>")
	)
	(segment
		(start 161.383472 -283.108908)
		(end 161.383472 -283.307282)
		(width 0.12954)
		(layer "F.Cu")
		(net "M_G_CPU1_SB_DQS_DP<0>")
	)
	(segment
		(start 165.99535 -284.460442)
		(end 166.312088 -284.77718)
		(width 0.101346)
		(layer "F.Cu")
		(net "M_G_CPU1_SB_DQS_DP<0>")
	)
	(segment
		(start 147.919186 -275.660866)
		(end 154.893518 -275.660866)
		(width 0.12954)
		(layer "F.Cu")
		(net "M_G_CPU1_SB_DQS_DP<0>")
	)
	(segment
		(start 162.93719 -284.595316)
		(end 163.06673 -284.724856)
		(width 0.12954)
		(layer "F.Cu")
		(net "M_G_CPU1_SB_DQS_DP<0>")
	)
	(segment
		(start 161.383472 -283.307282)
		(end 161.525712 -283.449522)
		(width 0.12954)
		(layer "F.Cu")
		(net "M_G_CPU1_SB_DQS_DP<0>")
	)
	(segment
		(start 166.312088 -284.77718)
		(end 166.66591 -284.77718)
		(width 0.101346)
		(layer "F.Cu")
		(net "M_G_CPU1_SB_DQS_DP<0>")
	)
	(segment
		(start 163.302188 -284.724856)
		(end 163.566602 -284.460442)
		(width 0.12954)
		(layer "F.Cu")
		(net "M_G_CPU1_SB_DQS_DP<0>")
	)
	(segment
		(start 147.381722 -275.686774)
		(end 147.421854 -275.726906)
		(width 0.0762)
		(layer "F.Cu")
		(net "M_G_CPU1_SB_DQS_DP<0>")
	)
	(segment
		(start 166.66591 -284.77718)
		(end 167.091106 -285.202376)
		(width 0.101346)
		(layer "F.Cu")
		(net "M_G_CPU1_SB_DQS_DP<0>")
	)
	(segment
		(start 162.93719 -283.704538)
		(end 162.93719 -284.595316)
		(width 0.12954)
		(layer "F.Cu")
		(net "M_G_CPU1_SB_DQS_DP<0>")
	)
	(segment
		(start 161.969704 -283.203396)
		(end 162.436048 -283.203396)
		(width 0.12954)
		(layer "F.Cu")
		(net "M_G_CPU1_SB_DQS_DP<0>")
	)
	(segment
		(start 161.629344 -282.862782)
		(end 161.383472 -283.108908)
		(width 0.12954)
		(layer "F.Cu")
		(net "M_G_CPU1_SB_DQS_DP<0>")
	)
	(segment
		(start 146.096482 -275.7678)
		(end 146.104864 -275.762974)
		(width 0.0762)
		(layer "F.Cu")
		(net "M_G_CPU1_SB_DQS_DP<0>")
	)
	(segment
		(start 161.629344 -282.396692)
		(end 161.629344 -282.862782)
		(width 0.12954)
		(layer "F.Cu")
		(net "M_G_CPU1_SB_DQS_DP<0>")
	)
	(segment
		(start 162.436048 -283.203396)
		(end 162.93719 -283.704538)
		(width 0.12954)
		(layer "F.Cu")
		(net "M_G_CPU1_SB_DQS_DP<0>")
	)
	(segment
		(start 167.091106 -285.202376)
		(end 167.697404 -285.202376)
		(width 0.101346)
		(layer "F.Cu")
		(net "M_G_CPU1_SB_DQS_DP<0>")
	)
	(segment
		(start 147.834096 -275.726906)
		(end 147.900136 -275.660866)
		(width 0.0762)
		(layer "F.Cu")
		(net "M_G_CPU1_SB_DQS_DP<0>")
	)
	(segment
		(start 161.723578 -283.449268)
		(end 161.969704 -283.203396)
		(width 0.12954)
		(layer "F.Cu")
		(net "M_G_CPU1_SB_DQS_DP<0>")
	)
	(segment
		(start 154.893518 -275.660866)
		(end 161.629344 -282.396692)
		(width 0.12954)
		(layer "F.Cu")
		(net "M_G_CPU1_SB_DQS_DP<0>")
	)
	(segment
		(start 147.900136 -275.660866)
		(end 147.919186 -275.660866)
		(width 0.0762)
		(layer "F.Cu")
		(net "M_G_CPU1_SB_DQS_DP<0>")
	)
	(segment
		(start 163.06673 -284.724856)
		(end 163.302188 -284.724856)
		(width 0.12954)
		(layer "F.Cu")
		(net "M_G_CPU1_SB_DQS_DP<0>")
	)
	(arc
		(start 145.982436 -275.807678)
		(mid 146.041082 -275.792385)
		(end 146.096482 -275.7678)
		(width 0.0762)
		(layer "F.Cu")
		(net "M_G_CPU1_SB_DQS_DP<0>")
	)
	(arc
		(start 145.815558 -275.61667)
		(mid 145.845187 -275.759157)
		(end 145.982436 -275.807678)
		(width 0.0762)
		(layer "F.Cu")
		(net "M_G_CPU1_SB_DQS_DP<0>")
	)
	(arc
		(start 146.104864 -275.762974)
		(mid 146.218588 -275.712673)
		(end 146.340576 -275.688552)
		(width 0.0762)
		(layer "F.Cu")
		(net "M_G_CPU1_SB_DQS_DP<0>")
	)
	(arc
		(start 146.340576 -275.688552)
		(mid 146.364053 -275.687176)
		(end 146.387566 -275.686774)
		(width 0.0762)
		(layer "F.Cu")
		(net "M_G_CPU1_SB_DQS_DP<0>")
	)
	(segment
		(start 159.538924 -270.971518)
		(end 160.780476 -272.21307)
		(width 0.12954)
		(layer "F.Cu")
		(net "M_G_CPU1_SB_DQS_DN<9>")
	)
	(segment
		(start 163.303712 -275.697442)
		(end 163.566602 -275.960332)
		(width 0.12954)
		(layer "F.Cu")
		(net "M_G_CPU1_SB_DQS_DN<9>")
	)
	(segment
		(start 146.38782 -271.017238)
		(end 146.958812 -271.017238)
		(width 0.0762)
		(layer "F.Cu")
		(net "M_G_CPU1_SB_DQS_DN<9>")
	)
	(segment
		(start 168.014396 -276.385274)
		(end 168.527984 -276.385274)
		(width 0.101346)
		(layer "F.Cu")
		(net "M_G_CPU1_SB_DQS_DN<9>")
	)
	(segment
		(start 166.312342 -275.642832)
		(end 166.609014 -275.642832)
		(width 0.101346)
		(layer "F.Cu")
		(net "M_G_CPU1_SB_DQS_DN<9>")
	)
	(segment
		(start 147.070572 -270.905478)
		(end 147.483322 -270.905478)
		(width 0.0762)
		(layer "F.Cu")
		(net "M_G_CPU1_SB_DQS_DN<9>")
	)
	(segment
		(start 163.566602 -275.960332)
		(end 165.994842 -275.960332)
		(width 0.101346)
		(layer "F.Cu")
		(net "M_G_CPU1_SB_DQS_DN<9>")
	)
	(segment
		(start 167.69715 -276.068028)
		(end 168.014396 -276.385274)
		(width 0.101346)
		(layer "F.Cu")
		(net "M_G_CPU1_SB_DQS_DN<9>")
	)
	(segment
		(start 160.780476 -272.21307)
		(end 160.780476 -273.663918)
		(width 0.12954)
		(layer "F.Cu")
		(net "M_G_CPU1_SB_DQS_DN<9>")
	)
	(segment
		(start 167.03421 -276.068028)
		(end 167.69715 -276.068028)
		(width 0.101346)
		(layer "F.Cu")
		(net "M_G_CPU1_SB_DQS_DN<9>")
	)
	(segment
		(start 147.483322 -270.905478)
		(end 147.549362 -270.971518)
		(width 0.0762)
		(layer "F.Cu")
		(net "M_G_CPU1_SB_DQS_DN<9>")
	)
	(segment
		(start 147.549362 -270.971518)
		(end 147.568412 -270.971518)
		(width 0.0762)
		(layer "F.Cu")
		(net "M_G_CPU1_SB_DQS_DN<9>")
	)
	(segment
		(start 146.958812 -271.017238)
		(end 147.070572 -270.905478)
		(width 0.0762)
		(layer "F.Cu")
		(net "M_G_CPU1_SB_DQS_DN<9>")
	)
	(segment
		(start 162.814 -275.697442)
		(end 163.303712 -275.697442)
		(width 0.12954)
		(layer "F.Cu")
		(net "M_G_CPU1_SB_DQS_DN<9>")
	)
	(segment
		(start 160.780476 -273.663918)
		(end 162.814 -275.697442)
		(width 0.12954)
		(layer "F.Cu")
		(net "M_G_CPU1_SB_DQS_DN<9>")
	)
	(segment
		(start 166.609014 -275.642832)
		(end 167.03421 -276.068028)
		(width 0.101346)
		(layer "F.Cu")
		(net "M_G_CPU1_SB_DQS_DN<9>")
	)
	(segment
		(start 147.568412 -270.971518)
		(end 159.538924 -270.971518)
		(width 0.12954)
		(layer "F.Cu")
		(net "M_G_CPU1_SB_DQS_DN<9>")
	)
	(segment
		(start 165.994842 -275.960332)
		(end 166.312342 -275.642832)
		(width 0.101346)
		(layer "F.Cu")
		(net "M_G_CPU1_SB_DQS_DN<9>")
	)
	(arc
		(start 145.447766 -271.390364)
		(mid 145.691197 -271.220877)
		(end 145.976848 -271.140936)
		(width 0.0762)
		(layer "F.Cu")
		(net "M_G_CPU1_SB_DQS_DN<9>")
	)
	(arc
		(start 146.356832 -271.018508)
		(mid 146.372313 -271.017552)
		(end 146.38782 -271.017238)
		(width 0.0762)
		(layer "F.Cu")
		(net "M_G_CPU1_SB_DQS_DN<9>")
	)
	(arc
		(start 146.015456 -271.135602)
		(mid 146.111165 -271.10989)
		(end 146.200876 -271.067784)
		(width 0.0762)
		(layer "F.Cu")
		(net "M_G_CPU1_SB_DQS_DN<9>")
	)
	(arc
		(start 146.200876 -271.067784)
		(mid 146.276116 -271.034471)
		(end 146.356832 -271.018508)
		(width 0.0762)
		(layer "F.Cu")
		(net "M_G_CPU1_SB_DQS_DN<9>")
	)
	(arc
		(start 145.976848 -271.140936)
		(mid 145.996197 -271.138598)
		(end 146.015456 -271.135602)
		(width 0.0762)
		(layer "F.Cu")
		(net "M_G_CPU1_SB_DQS_DN<9>")
	)
	(segment
		(start 160.789112 -310.556656)
		(end 160.788858 -311.021984)
		(width 0.12954)
		(layer "F.Cu")
		(net "M_G_CPU1_SB_DQS_DN<8>")
	)
	(segment
		(start 147.65909 -291.20338)
		(end 147.72513 -291.13734)
		(width 0.0762)
		(layer "F.Cu")
		(net "M_G_CPU1_SB_DQS_DN<8>")
	)
	(segment
		(start 158.253684 -309.010558)
		(end 158.253684 -309.209186)
		(width 0.12954)
		(layer "F.Cu")
		(net "M_G_CPU1_SB_DQS_DN<8>")
	)
	(segment
		(start 147.72513 -291.13734)
		(end 147.74418 -291.13734)
		(width 0.0762)
		(layer "F.Cu")
		(net "M_G_CPU1_SB_DQS_DN<8>")
	)
	(segment
		(start 149.11197 -292.1889)
		(end 149.11197 -298.879514)
		(width 0.12954)
		(layer "F.Cu")
		(net "M_G_CPU1_SB_DQS_DN<8>")
	)
	(segment
		(start 159.652462 -309.420006)
		(end 159.652208 -309.885334)
		(width 0.12954)
		(layer "F.Cu")
		(net "M_G_CPU1_SB_DQS_DN<8>")
	)
	(segment
		(start 145.260822 -291.152834)
		(end 145.269204 -291.15766)
		(width 0.0762)
		(layer "F.Cu")
		(net "M_G_CPU1_SB_DQS_DN<8>")
	)
	(segment
		(start 160.526984 -311.283858)
		(end 160.526984 -311.482486)
		(width 0.12954)
		(layer "F.Cu")
		(net "M_G_CPU1_SB_DQS_DN<8>")
	)
	(segment
		(start 158.85541 -309.08879)
		(end 159.321246 -309.08879)
		(width 0.12954)
		(layer "F.Cu")
		(net "M_G_CPU1_SB_DQS_DN<8>")
	)
	(segment
		(start 157.456886 -308.21376)
		(end 157.71876 -307.95214)
		(width 0.12954)
		(layer "F.Cu")
		(net "M_G_CPU1_SB_DQS_DN<8>")
	)
	(segment
		(start 157.258258 -308.21376)
		(end 157.456886 -308.21376)
		(width 0.12954)
		(layer "F.Cu")
		(net "M_G_CPU1_SB_DQS_DN<8>")
	)
	(segment
		(start 158.593536 -309.35041)
		(end 158.85541 -309.08879)
		(width 0.12954)
		(layer "F.Cu")
		(net "M_G_CPU1_SB_DQS_DN<8>")
	)
	(segment
		(start 144.686528 -291.15766)
		(end 144.69491 -291.152834)
		(width 0.0762)
		(layer "F.Cu")
		(net "M_G_CPU1_SB_DQS_DN<8>")
	)
	(segment
		(start 158.184596 -307.95214)
		(end 158.515812 -308.283356)
		(width 0.12954)
		(layer "F.Cu")
		(net "M_G_CPU1_SB_DQS_DN<8>")
	)
	(segment
		(start 160.526984 -311.482486)
		(end 163.093654 -314.049156)
		(width 0.12954)
		(layer "F.Cu")
		(net "M_G_CPU1_SB_DQS_DN<8>")
	)
	(segment
		(start 158.515558 -308.748684)
		(end 158.253684 -309.010558)
		(width 0.12954)
		(layer "F.Cu")
		(net "M_G_CPU1_SB_DQS_DN<8>")
	)
	(segment
		(start 158.253684 -309.209186)
		(end 158.394908 -309.35041)
		(width 0.12954)
		(layer "F.Cu")
		(net "M_G_CPU1_SB_DQS_DN<8>")
	)
	(segment
		(start 147.74418 -291.13734)
		(end 148.06041 -291.13734)
		(width 0.12954)
		(layer "F.Cu")
		(net "M_G_CPU1_SB_DQS_DN<8>")
	)
	(segment
		(start 163.869878 -313.78525)
		(end 164.427916 -313.78525)
		(width 0.12954)
		(layer "F.Cu")
		(net "M_G_CPU1_SB_DQS_DN<8>")
	)
	(segment
		(start 160.788858 -311.021984)
		(end 160.526984 -311.283858)
		(width 0.12954)
		(layer "F.Cu")
		(net "M_G_CPU1_SB_DQS_DN<8>")
	)
	(segment
		(start 159.390334 -310.147208)
		(end 159.390334 -310.345836)
		(width 0.12954)
		(layer "F.Cu")
		(net "M_G_CPU1_SB_DQS_DN<8>")
	)
	(segment
		(start 157.117034 -308.072536)
		(end 157.258258 -308.21376)
		(width 0.12954)
		(layer "F.Cu")
		(net "M_G_CPU1_SB_DQS_DN<8>")
	)
	(segment
		(start 157.117034 -307.873908)
		(end 157.117034 -308.072536)
		(width 0.12954)
		(layer "F.Cu")
		(net "M_G_CPU1_SB_DQS_DN<8>")
	)
	(segment
		(start 160.457896 -310.22544)
		(end 160.789112 -310.556656)
		(width 0.12954)
		(layer "F.Cu")
		(net "M_G_CPU1_SB_DQS_DN<8>")
	)
	(segment
		(start 146.388328 -291.20338)
		(end 147.65909 -291.20338)
		(width 0.0762)
		(layer "F.Cu")
		(net "M_G_CPU1_SB_DQS_DN<8>")
	)
	(segment
		(start 159.390334 -310.345836)
		(end 159.531558 -310.48706)
		(width 0.12954)
		(layer "F.Cu")
		(net "M_G_CPU1_SB_DQS_DN<8>")
	)
	(segment
		(start 159.531558 -310.48706)
		(end 159.730186 -310.48706)
		(width 0.12954)
		(layer "F.Cu")
		(net "M_G_CPU1_SB_DQS_DN<8>")
	)
	(segment
		(start 159.99206 -310.22544)
		(end 160.457896 -310.22544)
		(width 0.12954)
		(layer "F.Cu")
		(net "M_G_CPU1_SB_DQS_DN<8>")
	)
	(segment
		(start 157.38602 -307.604922)
		(end 157.117034 -307.873908)
		(width 0.12954)
		(layer "F.Cu")
		(net "M_G_CPU1_SB_DQS_DN<8>")
	)
	(segment
		(start 144.507966 -290.830254)
		(end 144.406112 -291.005514)
		(width 0.0762)
		(layer "F.Cu")
		(net "M_G_CPU1_SB_DQS_DN<8>")
	)
	(segment
		(start 149.11197 -298.879514)
		(end 157.38602 -307.153564)
		(width 0.12954)
		(layer "F.Cu")
		(net "M_G_CPU1_SB_DQS_DN<8>")
	)
	(segment
		(start 159.321246 -309.08879)
		(end 159.652462 -309.420006)
		(width 0.12954)
		(layer "F.Cu")
		(net "M_G_CPU1_SB_DQS_DN<8>")
	)
	(segment
		(start 148.06041 -291.13734)
		(end 149.11197 -292.1889)
		(width 0.12954)
		(layer "F.Cu")
		(net "M_G_CPU1_SB_DQS_DN<8>")
	)
	(segment
		(start 158.394908 -309.35041)
		(end 158.593536 -309.35041)
		(width 0.12954)
		(layer "F.Cu")
		(net "M_G_CPU1_SB_DQS_DN<8>")
	)
	(segment
		(start 157.71876 -307.95214)
		(end 158.184596 -307.95214)
		(width 0.12954)
		(layer "F.Cu")
		(net "M_G_CPU1_SB_DQS_DN<8>")
	)
	(segment
		(start 159.652208 -309.885334)
		(end 159.390334 -310.147208)
		(width 0.12954)
		(layer "F.Cu")
		(net "M_G_CPU1_SB_DQS_DN<8>")
	)
	(segment
		(start 146.38782 -291.202872)
		(end 146.388328 -291.20338)
		(width 0.0762)
		(layer "F.Cu")
		(net "M_G_CPU1_SB_DQS_DN<8>")
	)
	(segment
		(start 163.093654 -314.049156)
		(end 163.605972 -314.049156)
		(width 0.12954)
		(layer "F.Cu")
		(net "M_G_CPU1_SB_DQS_DN<8>")
	)
	(segment
		(start 157.38602 -307.153564)
		(end 157.38602 -307.604922)
		(width 0.12954)
		(layer "F.Cu")
		(net "M_G_CPU1_SB_DQS_DN<8>")
	)
	(segment
		(start 159.730186 -310.48706)
		(end 159.99206 -310.22544)
		(width 0.12954)
		(layer "F.Cu")
		(net "M_G_CPU1_SB_DQS_DN<8>")
	)
	(segment
		(start 158.515812 -308.283356)
		(end 158.515558 -308.748684)
		(width 0.12954)
		(layer "F.Cu")
		(net "M_G_CPU1_SB_DQS_DN<8>")
	)
	(segment
		(start 163.605972 -314.049156)
		(end 163.869878 -313.78525)
		(width 0.12954)
		(layer "F.Cu")
		(net "M_G_CPU1_SB_DQS_DN<8>")
	)
	(arc
		(start 144.406112 -291.005514)
		(mid 144.423306 -291.1451)
		(end 144.55267 -291.200332)
		(width 0.0762)
		(layer "F.Cu")
		(net "M_G_CPU1_SB_DQS_DN<8>")
	)
	(arc
		(start 145.634964 -291.152834)
		(mid 145.91792 -291.076657)
		(end 146.200876 -291.152834)
		(width 0.0762)
		(layer "F.Cu")
		(net "M_G_CPU1_SB_DQS_DN<8>")
	)
	(arc
		(start 144.69491 -291.152834)
		(mid 144.977866 -291.076657)
		(end 145.260822 -291.152834)
		(width 0.0762)
		(layer "F.Cu")
		(net "M_G_CPU1_SB_DQS_DN<8>")
	)
	(arc
		(start 146.200876 -291.152834)
		(mid 146.291045 -291.190183)
		(end 146.38782 -291.202872)
		(width 0.0762)
		(layer "F.Cu")
		(net "M_G_CPU1_SB_DQS_DN<8>")
	)
	(arc
		(start 144.55267 -291.200332)
		(mid 144.621617 -291.185335)
		(end 144.686528 -291.15766)
		(width 0.0762)
		(layer "F.Cu")
		(net "M_G_CPU1_SB_DQS_DN<8>")
	)
	(arc
		(start 145.269204 -291.15766)
		(mid 145.452712 -291.203154)
		(end 145.634964 -291.152834)
		(width 0.0762)
		(layer "F.Cu")
		(net "M_G_CPU1_SB_DQS_DN<8>")
	)
	(segment
		(start 158.458154 -299.747178)
		(end 158.78937 -300.078394)
		(width 0.12954)
		(layer "F.Cu")
		(net "M_G_CPU1_SB_DQS_DN<7>")
	)
	(segment
		(start 154.582368 -296.336974)
		(end 155.048204 -296.337228)
		(width 0.12954)
		(layer "F.Cu")
		(net "M_G_CPU1_SB_DQS_DN<7>")
	)
	(segment
		(start 159.92602 -301.215044)
		(end 159.925766 -301.680372)
		(width 0.12954)
		(layer "F.Cu")
		(net "M_G_CPU1_SB_DQS_DN<7>")
	)
	(segment
		(start 156.515816 -298.270422)
		(end 156.362654 -298.423584)
		(width 0.12954)
		(layer "F.Cu")
		(net "M_G_CPU1_SB_DQS_DN<7>")
	)
	(segment
		(start 155.56611 -297.626532)
		(end 155.719018 -297.473624)
		(width 0.12954)
		(layer "F.Cu")
		(net "M_G_CPU1_SB_DQS_DN<7>")
	)
	(segment
		(start 159.594804 -300.883828)
		(end 159.92602 -301.215044)
		(width 0.12954)
		(layer "F.Cu")
		(net "M_G_CPU1_SB_DQS_DN<7>")
	)
	(segment
		(start 154.230324 -296.489882)
		(end 154.42946 -296.489882)
		(width 0.12954)
		(layer "F.Cu")
		(net "M_G_CPU1_SB_DQS_DN<7>")
	)
	(segment
		(start 162.439604 -304.699162)
		(end 163.605972 -304.699162)
		(width 0.12954)
		(layer "F.Cu")
		(net "M_G_CPU1_SB_DQS_DN<7>")
	)
	(segment
		(start 157.83941 -299.899832)
		(end 157.992318 -299.746924)
		(width 0.12954)
		(layer "F.Cu")
		(net "M_G_CPU1_SB_DQS_DN<7>")
	)
	(segment
		(start 156.184854 -297.473878)
		(end 156.51607 -297.805094)
		(width 0.12954)
		(layer "F.Cu")
		(net "M_G_CPU1_SB_DQS_DN<7>")
	)
	(segment
		(start 163.869878 -304.435256)
		(end 164.427916 -304.435256)
		(width 0.12954)
		(layer "F.Cu")
		(net "M_G_CPU1_SB_DQS_DN<7>")
	)
	(segment
		(start 149.35962 -286.107124)
		(end 153.511504 -290.259008)
		(width 0.12954)
		(layer "F.Cu")
		(net "M_G_CPU1_SB_DQS_DN<7>")
	)
	(segment
		(start 145.260822 -286.293052)
		(end 145.269204 -286.297878)
		(width 0.0762)
		(layer "F.Cu")
		(net "M_G_CPU1_SB_DQS_DN<7>")
	)
	(segment
		(start 156.362654 -298.622212)
		(end 156.503624 -298.763182)
		(width 0.12954)
		(layer "F.Cu")
		(net "M_G_CPU1_SB_DQS_DN<7>")
	)
	(segment
		(start 153.511504 -290.259008)
		(end 153.511504 -295.771062)
		(width 0.12954)
		(layer "F.Cu")
		(net "M_G_CPU1_SB_DQS_DN<7>")
	)
	(segment
		(start 157.992318 -299.746924)
		(end 158.458154 -299.747178)
		(width 0.12954)
		(layer "F.Cu")
		(net "M_G_CPU1_SB_DQS_DN<7>")
	)
	(segment
		(start 156.70276 -298.763182)
		(end 156.855668 -298.610274)
		(width 0.12954)
		(layer "F.Cu")
		(net "M_G_CPU1_SB_DQS_DN<7>")
	)
	(segment
		(start 158.97606 -301.036482)
		(end 159.128968 -300.883574)
		(width 0.12954)
		(layer "F.Cu")
		(net "M_G_CPU1_SB_DQS_DN<7>")
	)
	(segment
		(start 156.51607 -297.805094)
		(end 156.515816 -298.270422)
		(width 0.12954)
		(layer "F.Cu")
		(net "M_G_CPU1_SB_DQS_DN<7>")
	)
	(segment
		(start 158.78937 -300.078394)
		(end 158.789116 -300.543722)
		(width 0.12954)
		(layer "F.Cu")
		(net "M_G_CPU1_SB_DQS_DN<7>")
	)
	(segment
		(start 158.776924 -301.036482)
		(end 158.97606 -301.036482)
		(width 0.12954)
		(layer "F.Cu")
		(net "M_G_CPU1_SB_DQS_DN<7>")
	)
	(segment
		(start 157.499304 -299.758862)
		(end 157.640274 -299.899832)
		(width 0.12954)
		(layer "F.Cu")
		(net "M_G_CPU1_SB_DQS_DN<7>")
	)
	(segment
		(start 146.388328 -286.343598)
		(end 147.271994 -286.343598)
		(width 0.0762)
		(layer "F.Cu")
		(net "M_G_CPU1_SB_DQS_DN<7>")
	)
	(segment
		(start 147.900136 -286.107124)
		(end 147.919186 -286.107124)
		(width 0.0762)
		(layer "F.Cu")
		(net "M_G_CPU1_SB_DQS_DN<7>")
	)
	(segment
		(start 158.789116 -300.543722)
		(end 158.635954 -300.696884)
		(width 0.12954)
		(layer "F.Cu")
		(net "M_G_CPU1_SB_DQS_DN<7>")
	)
	(segment
		(start 157.321504 -298.610528)
		(end 157.65272 -298.941744)
		(width 0.12954)
		(layer "F.Cu")
		(net "M_G_CPU1_SB_DQS_DN<7>")
	)
	(segment
		(start 158.635954 -300.696884)
		(end 158.635954 -300.895512)
		(width 0.12954)
		(layer "F.Cu")
		(net "M_G_CPU1_SB_DQS_DN<7>")
	)
	(segment
		(start 144.507966 -285.970472)
		(end 144.406112 -286.145732)
		(width 0.0762)
		(layer "F.Cu")
		(net "M_G_CPU1_SB_DQS_DN<7>")
	)
	(segment
		(start 155.226004 -297.286934)
		(end 155.226004 -297.485562)
		(width 0.12954)
		(layer "F.Cu")
		(net "M_G_CPU1_SB_DQS_DN<7>")
	)
	(segment
		(start 157.640274 -299.899832)
		(end 157.83941 -299.899832)
		(width 0.12954)
		(layer "F.Cu")
		(net "M_G_CPU1_SB_DQS_DN<7>")
	)
	(segment
		(start 154.42946 -296.489882)
		(end 154.582368 -296.336974)
		(width 0.12954)
		(layer "F.Cu")
		(net "M_G_CPU1_SB_DQS_DN<7>")
	)
	(segment
		(start 163.605972 -304.699162)
		(end 163.869878 -304.435256)
		(width 0.12954)
		(layer "F.Cu")
		(net "M_G_CPU1_SB_DQS_DN<7>")
	)
	(segment
		(start 155.719018 -297.473624)
		(end 156.184854 -297.473878)
		(width 0.12954)
		(layer "F.Cu")
		(net "M_G_CPU1_SB_DQS_DN<7>")
	)
	(segment
		(start 155.366974 -297.626532)
		(end 155.56611 -297.626532)
		(width 0.12954)
		(layer "F.Cu")
		(net "M_G_CPU1_SB_DQS_DN<7>")
	)
	(segment
		(start 156.855668 -298.610274)
		(end 157.321504 -298.610528)
		(width 0.12954)
		(layer "F.Cu")
		(net "M_G_CPU1_SB_DQS_DN<7>")
	)
	(segment
		(start 155.048204 -296.337228)
		(end 155.37942 -296.668444)
		(width 0.12954)
		(layer "F.Cu")
		(net "M_G_CPU1_SB_DQS_DN<7>")
	)
	(segment
		(start 147.442428 -286.173164)
		(end 147.834096 -286.173164)
		(width 0.0762)
		(layer "F.Cu")
		(net "M_G_CPU1_SB_DQS_DN<7>")
	)
	(segment
		(start 156.362654 -298.423584)
		(end 156.362654 -298.622212)
		(width 0.12954)
		(layer "F.Cu")
		(net "M_G_CPU1_SB_DQS_DN<7>")
	)
	(segment
		(start 157.65272 -298.941744)
		(end 157.652466 -299.407072)
		(width 0.12954)
		(layer "F.Cu")
		(net "M_G_CPU1_SB_DQS_DN<7>")
	)
	(segment
		(start 159.772604 -301.833534)
		(end 159.772604 -302.032162)
		(width 0.12954)
		(layer "F.Cu")
		(net "M_G_CPU1_SB_DQS_DN<7>")
	)
	(segment
		(start 158.635954 -300.895512)
		(end 158.776924 -301.036482)
		(width 0.12954)
		(layer "F.Cu")
		(net "M_G_CPU1_SB_DQS_DN<7>")
	)
	(segment
		(start 153.511504 -295.771062)
		(end 154.230324 -296.489882)
		(width 0.12954)
		(layer "F.Cu")
		(net "M_G_CPU1_SB_DQS_DN<7>")
	)
	(segment
		(start 147.919186 -286.107124)
		(end 149.35962 -286.107124)
		(width 0.12954)
		(layer "F.Cu")
		(net "M_G_CPU1_SB_DQS_DN<7>")
	)
	(segment
		(start 155.226004 -297.485562)
		(end 155.366974 -297.626532)
		(width 0.12954)
		(layer "F.Cu")
		(net "M_G_CPU1_SB_DQS_DN<7>")
	)
	(segment
		(start 159.128968 -300.883574)
		(end 159.594804 -300.883828)
		(width 0.12954)
		(layer "F.Cu")
		(net "M_G_CPU1_SB_DQS_DN<7>")
	)
	(segment
		(start 146.38782 -286.34309)
		(end 146.388328 -286.343598)
		(width 0.0762)
		(layer "F.Cu")
		(net "M_G_CPU1_SB_DQS_DN<7>")
	)
	(segment
		(start 147.834096 -286.173164)
		(end 147.900136 -286.107124)
		(width 0.0762)
		(layer "F.Cu")
		(net "M_G_CPU1_SB_DQS_DN<7>")
	)
	(segment
		(start 155.37942 -296.668444)
		(end 155.379166 -297.133772)
		(width 0.12954)
		(layer "F.Cu")
		(net "M_G_CPU1_SB_DQS_DN<7>")
	)
	(segment
		(start 156.503624 -298.763182)
		(end 156.70276 -298.763182)
		(width 0.12954)
		(layer "F.Cu")
		(net "M_G_CPU1_SB_DQS_DN<7>")
	)
	(segment
		(start 159.772604 -302.032162)
		(end 162.439604 -304.699162)
		(width 0.12954)
		(layer "F.Cu")
		(net "M_G_CPU1_SB_DQS_DN<7>")
	)
	(segment
		(start 157.499304 -299.560234)
		(end 157.499304 -299.758862)
		(width 0.12954)
		(layer "F.Cu")
		(net "M_G_CPU1_SB_DQS_DN<7>")
	)
	(segment
		(start 155.379166 -297.133772)
		(end 155.226004 -297.286934)
		(width 0.12954)
		(layer "F.Cu")
		(net "M_G_CPU1_SB_DQS_DN<7>")
	)
	(segment
		(start 147.271994 -286.343598)
		(end 147.442428 -286.173164)
		(width 0.0762)
		(layer "F.Cu")
		(net "M_G_CPU1_SB_DQS_DN<7>")
	)
	(segment
		(start 144.686528 -286.297878)
		(end 144.69491 -286.293052)
		(width 0.0762)
		(layer "F.Cu")
		(net "M_G_CPU1_SB_DQS_DN<7>")
	)
	(segment
		(start 157.652466 -299.407072)
		(end 157.499304 -299.560234)
		(width 0.12954)
		(layer "F.Cu")
		(net "M_G_CPU1_SB_DQS_DN<7>")
	)
	(segment
		(start 159.925766 -301.680372)
		(end 159.772604 -301.833534)
		(width 0.12954)
		(layer "F.Cu")
		(net "M_G_CPU1_SB_DQS_DN<7>")
	)
	(arc
		(start 144.406112 -286.145732)
		(mid 144.423306 -286.285318)
		(end 144.55267 -286.34055)
		(width 0.0762)
		(layer "F.Cu")
		(net "M_G_CPU1_SB_DQS_DN<7>")
	)
	(arc
		(start 146.200876 -286.293052)
		(mid 146.291045 -286.330401)
		(end 146.38782 -286.34309)
		(width 0.0762)
		(layer "F.Cu")
		(net "M_G_CPU1_SB_DQS_DN<7>")
	)
	(arc
		(start 144.55267 -286.34055)
		(mid 144.621617 -286.325553)
		(end 144.686528 -286.297878)
		(width 0.0762)
		(layer "F.Cu")
		(net "M_G_CPU1_SB_DQS_DN<7>")
	)
	(arc
		(start 144.69491 -286.293052)
		(mid 144.977866 -286.216875)
		(end 145.260822 -286.293052)
		(width 0.0762)
		(layer "F.Cu")
		(net "M_G_CPU1_SB_DQS_DN<7>")
	)
	(arc
		(start 145.269204 -286.297878)
		(mid 145.452712 -286.343372)
		(end 145.634964 -286.293052)
		(width 0.0762)
		(layer "F.Cu")
		(net "M_G_CPU1_SB_DQS_DN<7>")
	)
	(arc
		(start 145.634964 -286.293052)
		(mid 145.91792 -286.216875)
		(end 146.200876 -286.293052)
		(width 0.0762)
		(layer "F.Cu")
		(net "M_G_CPU1_SB_DQS_DN<7>")
	)
	(segment
		(start 159.280098 -292.799516)
		(end 159.280098 -292.997636)
		(width 0.12954)
		(layer "F.Cu")
		(net "M_G_CPU1_SB_DQS_DN<6>")
	)
	(segment
		(start 144.686528 -281.437842)
		(end 144.69491 -281.433016)
		(width 0.0762)
		(layer "F.Cu")
		(net "M_G_CPU1_SB_DQS_DN<6>")
	)
	(segment
		(start 147.22094 -281.483562)
		(end 147.547584 -281.156918)
		(width 0.0762)
		(layer "F.Cu")
		(net "M_G_CPU1_SB_DQS_DN<6>")
	)
	(segment
		(start 150.695152 -281.090878)
		(end 159.3723 -289.768026)
		(width 0.12954)
		(layer "F.Cu")
		(net "M_G_CPU1_SB_DQS_DN<6>")
	)
	(segment
		(start 146.38782 -281.483054)
		(end 146.388328 -281.483562)
		(width 0.0762)
		(layer "F.Cu")
		(net "M_G_CPU1_SB_DQS_DN<6>")
	)
	(segment
		(start 147.834096 -281.156918)
		(end 147.900136 -281.090878)
		(width 0.0762)
		(layer "F.Cu")
		(net "M_G_CPU1_SB_DQS_DN<6>")
	)
	(segment
		(start 159.68726 -292.392354)
		(end 159.280098 -292.799516)
		(width 0.12954)
		(layer "F.Cu")
		(net "M_G_CPU1_SB_DQS_DN<6>")
	)
	(segment
		(start 161.553398 -295.270936)
		(end 161.695638 -295.413176)
		(width 0.12954)
		(layer "F.Cu")
		(net "M_G_CPU1_SB_DQS_DN<6>")
	)
	(segment
		(start 160.02762 -292.732714)
		(end 160.494472 -292.732714)
		(width 0.12954)
		(layer "F.Cu")
		(net "M_G_CPU1_SB_DQS_DN<6>")
	)
	(segment
		(start 163.605972 -295.349168)
		(end 163.869878 -295.085262)
		(width 0.12954)
		(layer "F.Cu")
		(net "M_G_CPU1_SB_DQS_DN<6>")
	)
	(segment
		(start 159.3723 -291.610542)
		(end 159.68726 -291.925502)
		(width 0.12954)
		(layer "F.Cu")
		(net "M_G_CPU1_SB_DQS_DN<6>")
	)
	(segment
		(start 161.893758 -295.413176)
		(end 162.30092 -295.006014)
		(width 0.12954)
		(layer "F.Cu")
		(net "M_G_CPU1_SB_DQS_DN<6>")
	)
	(segment
		(start 161.96056 -294.198802)
		(end 161.96056 -294.665654)
		(width 0.12954)
		(layer "F.Cu")
		(net "M_G_CPU1_SB_DQS_DN<6>")
	)
	(segment
		(start 160.82391 -293.529004)
		(end 160.416748 -293.936166)
		(width 0.12954)
		(layer "F.Cu")
		(net "M_G_CPU1_SB_DQS_DN<6>")
	)
	(segment
		(start 159.68726 -291.925502)
		(end 159.68726 -292.392354)
		(width 0.12954)
		(layer "F.Cu")
		(net "M_G_CPU1_SB_DQS_DN<6>")
	)
	(segment
		(start 160.757108 -294.276526)
		(end 161.16427 -293.869364)
		(width 0.12954)
		(layer "F.Cu")
		(net "M_G_CPU1_SB_DQS_DN<6>")
	)
	(segment
		(start 160.558988 -294.276526)
		(end 160.757108 -294.276526)
		(width 0.12954)
		(layer "F.Cu")
		(net "M_G_CPU1_SB_DQS_DN<6>")
	)
	(segment
		(start 159.3723 -289.768026)
		(end 159.3723 -291.610542)
		(width 0.12954)
		(layer "F.Cu")
		(net "M_G_CPU1_SB_DQS_DN<6>")
	)
	(segment
		(start 146.388328 -281.483562)
		(end 147.22094 -281.483562)
		(width 0.0762)
		(layer "F.Cu")
		(net "M_G_CPU1_SB_DQS_DN<6>")
	)
	(segment
		(start 162.767772 -295.006014)
		(end 163.110926 -295.349168)
		(width 0.12954)
		(layer "F.Cu")
		(net "M_G_CPU1_SB_DQS_DN<6>")
	)
	(segment
		(start 159.620458 -293.139876)
		(end 160.02762 -292.732714)
		(width 0.12954)
		(layer "F.Cu")
		(net "M_G_CPU1_SB_DQS_DN<6>")
	)
	(segment
		(start 159.422338 -293.139876)
		(end 159.620458 -293.139876)
		(width 0.12954)
		(layer "F.Cu")
		(net "M_G_CPU1_SB_DQS_DN<6>")
	)
	(segment
		(start 162.30092 -295.006014)
		(end 162.767772 -295.006014)
		(width 0.12954)
		(layer "F.Cu")
		(net "M_G_CPU1_SB_DQS_DN<6>")
	)
	(segment
		(start 147.919186 -281.090878)
		(end 150.695152 -281.090878)
		(width 0.12954)
		(layer "F.Cu")
		(net "M_G_CPU1_SB_DQS_DN<6>")
	)
	(segment
		(start 161.553398 -295.072816)
		(end 161.553398 -295.270936)
		(width 0.12954)
		(layer "F.Cu")
		(net "M_G_CPU1_SB_DQS_DN<6>")
	)
	(segment
		(start 163.110926 -295.349168)
		(end 163.605972 -295.349168)
		(width 0.12954)
		(layer "F.Cu")
		(net "M_G_CPU1_SB_DQS_DN<6>")
	)
	(segment
		(start 160.416748 -293.936166)
		(end 160.416748 -294.134286)
		(width 0.12954)
		(layer "F.Cu")
		(net "M_G_CPU1_SB_DQS_DN<6>")
	)
	(segment
		(start 159.280098 -292.997636)
		(end 159.422338 -293.139876)
		(width 0.12954)
		(layer "F.Cu")
		(net "M_G_CPU1_SB_DQS_DN<6>")
	)
	(segment
		(start 147.900136 -281.090878)
		(end 147.919186 -281.090878)
		(width 0.0762)
		(layer "F.Cu")
		(net "M_G_CPU1_SB_DQS_DN<6>")
	)
	(segment
		(start 147.547584 -281.156918)
		(end 147.834096 -281.156918)
		(width 0.0762)
		(layer "F.Cu")
		(net "M_G_CPU1_SB_DQS_DN<6>")
	)
	(segment
		(start 160.416748 -294.134286)
		(end 160.558988 -294.276526)
		(width 0.12954)
		(layer "F.Cu")
		(net "M_G_CPU1_SB_DQS_DN<6>")
	)
	(segment
		(start 163.869878 -295.085262)
		(end 164.427916 -295.085262)
		(width 0.12954)
		(layer "F.Cu")
		(net "M_G_CPU1_SB_DQS_DN<6>")
	)
	(segment
		(start 161.695638 -295.413176)
		(end 161.893758 -295.413176)
		(width 0.12954)
		(layer "F.Cu")
		(net "M_G_CPU1_SB_DQS_DN<6>")
	)
	(segment
		(start 145.260822 -281.433016)
		(end 145.269204 -281.437842)
		(width 0.0762)
		(layer "F.Cu")
		(net "M_G_CPU1_SB_DQS_DN<6>")
	)
	(segment
		(start 160.82391 -293.062152)
		(end 160.82391 -293.529004)
		(width 0.12954)
		(layer "F.Cu")
		(net "M_G_CPU1_SB_DQS_DN<6>")
	)
	(segment
		(start 161.631122 -293.869364)
		(end 161.96056 -294.198802)
		(width 0.12954)
		(layer "F.Cu")
		(net "M_G_CPU1_SB_DQS_DN<6>")
	)
	(segment
		(start 160.494472 -292.732714)
		(end 160.82391 -293.062152)
		(width 0.12954)
		(layer "F.Cu")
		(net "M_G_CPU1_SB_DQS_DN<6>")
	)
	(segment
		(start 144.507966 -281.110436)
		(end 144.406112 -281.285696)
		(width 0.0762)
		(layer "F.Cu")
		(net "M_G_CPU1_SB_DQS_DN<6>")
	)
	(segment
		(start 161.16427 -293.869364)
		(end 161.631122 -293.869364)
		(width 0.12954)
		(layer "F.Cu")
		(net "M_G_CPU1_SB_DQS_DN<6>")
	)
	(segment
		(start 161.96056 -294.665654)
		(end 161.553398 -295.072816)
		(width 0.12954)
		(layer "F.Cu")
		(net "M_G_CPU1_SB_DQS_DN<6>")
	)
	(arc
		(start 144.69491 -281.433016)
		(mid 144.977866 -281.356839)
		(end 145.260822 -281.433016)
		(width 0.0762)
		(layer "F.Cu")
		(net "M_G_CPU1_SB_DQS_DN<6>")
	)
	(arc
		(start 145.634964 -281.433016)
		(mid 145.91792 -281.356839)
		(end 146.200876 -281.433016)
		(width 0.0762)
		(layer "F.Cu")
		(net "M_G_CPU1_SB_DQS_DN<6>")
	)
	(arc
		(start 146.200876 -281.433016)
		(mid 146.291045 -281.470365)
		(end 146.38782 -281.483054)
		(width 0.0762)
		(layer "F.Cu")
		(net "M_G_CPU1_SB_DQS_DN<6>")
	)
	(arc
		(start 144.406112 -281.285696)
		(mid 144.423306 -281.425282)
		(end 144.55267 -281.480514)
		(width 0.0762)
		(layer "F.Cu")
		(net "M_G_CPU1_SB_DQS_DN<6>")
	)
	(arc
		(start 145.269204 -281.437842)
		(mid 145.452712 -281.483336)
		(end 145.634964 -281.433016)
		(width 0.0762)
		(layer "F.Cu")
		(net "M_G_CPU1_SB_DQS_DN<6>")
	)
	(arc
		(start 144.55267 -281.480514)
		(mid 144.621617 -281.465517)
		(end 144.686528 -281.437842)
		(width 0.0762)
		(layer "F.Cu")
		(net "M_G_CPU1_SB_DQS_DN<6>")
	)
	(segment
		(start 159.03321 -280.883614)
		(end 159.364426 -281.21483)
		(width 0.12954)
		(layer "F.Cu")
		(net "M_G_CPU1_SB_DQS_DN<5>")
	)
	(segment
		(start 156.836618 -279.660858)
		(end 156.836618 -279.85974)
		(width 0.12954)
		(layer "F.Cu")
		(net "M_G_CPU1_SB_DQS_DN<5>")
	)
	(segment
		(start 158.31312 -281.137614)
		(end 158.567374 -280.883614)
		(width 0.12954)
		(layer "F.Cu")
		(net "M_G_CPU1_SB_DQS_DN<5>")
	)
	(segment
		(start 157.973268 -280.797762)
		(end 157.973268 -280.99639)
		(width 0.12954)
		(layer "F.Cu")
		(net "M_G_CPU1_SB_DQS_DN<5>")
	)
	(segment
		(start 145.260822 -276.57298)
		(end 145.269204 -276.577806)
		(width 0.0762)
		(layer "F.Cu")
		(net "M_G_CPU1_SB_DQS_DN<5>")
	)
	(segment
		(start 146.38782 -276.623018)
		(end 146.388328 -276.623526)
		(width 0.0762)
		(layer "F.Cu")
		(net "M_G_CPU1_SB_DQS_DN<5>")
	)
	(segment
		(start 160.246568 -283.071062)
		(end 160.246568 -283.26969)
		(width 0.12954)
		(layer "F.Cu")
		(net "M_G_CPU1_SB_DQS_DN<5>")
	)
	(segment
		(start 144.686528 -276.577806)
		(end 144.69491 -276.57298)
		(width 0.0762)
		(layer "F.Cu")
		(net "M_G_CPU1_SB_DQS_DN<5>")
	)
	(segment
		(start 158.227776 -280.07818)
		(end 158.227522 -280.543508)
		(width 0.12954)
		(layer "F.Cu")
		(net "M_G_CPU1_SB_DQS_DN<5>")
	)
	(segment
		(start 160.246568 -283.26969)
		(end 162.976052 -285.999174)
		(width 0.12954)
		(layer "F.Cu")
		(net "M_G_CPU1_SB_DQS_DN<5>")
	)
	(segment
		(start 158.227522 -280.543508)
		(end 157.973268 -280.797762)
		(width 0.12954)
		(layer "F.Cu")
		(net "M_G_CPU1_SB_DQS_DN<5>")
	)
	(segment
		(start 157.89656 -279.746964)
		(end 158.227776 -280.07818)
		(width 0.12954)
		(layer "F.Cu")
		(net "M_G_CPU1_SB_DQS_DN<5>")
	)
	(segment
		(start 146.388328 -276.623526)
		(end 147.213828 -276.623526)
		(width 0.0762)
		(layer "F.Cu")
		(net "M_G_CPU1_SB_DQS_DN<5>")
	)
	(segment
		(start 159.44977 -282.274264)
		(end 159.704024 -282.020264)
		(width 0.12954)
		(layer "F.Cu")
		(net "M_G_CPU1_SB_DQS_DN<5>")
	)
	(segment
		(start 159.109918 -282.13304)
		(end 159.251142 -282.274264)
		(width 0.12954)
		(layer "F.Cu")
		(net "M_G_CPU1_SB_DQS_DN<5>")
	)
	(segment
		(start 159.251142 -282.274264)
		(end 159.44977 -282.274264)
		(width 0.12954)
		(layer "F.Cu")
		(net "M_G_CPU1_SB_DQS_DN<5>")
	)
	(segment
		(start 163.869878 -285.735268)
		(end 164.427916 -285.735268)
		(width 0.12954)
		(layer "F.Cu")
		(net "M_G_CPU1_SB_DQS_DN<5>")
	)
	(segment
		(start 160.16986 -282.020264)
		(end 160.501076 -282.35148)
		(width 0.12954)
		(layer "F.Cu")
		(net "M_G_CPU1_SB_DQS_DN<5>")
	)
	(segment
		(start 144.507966 -276.2504)
		(end 144.406112 -276.42566)
		(width 0.0762)
		(layer "F.Cu")
		(net "M_G_CPU1_SB_DQS_DN<5>")
	)
	(segment
		(start 147.900136 -276.413976)
		(end 147.919186 -276.413976)
		(width 0.0762)
		(layer "F.Cu")
		(net "M_G_CPU1_SB_DQS_DN<5>")
	)
	(segment
		(start 158.114492 -281.137614)
		(end 158.31312 -281.137614)
		(width 0.12954)
		(layer "F.Cu")
		(net "M_G_CPU1_SB_DQS_DN<5>")
	)
	(segment
		(start 156.836618 -279.85974)
		(end 156.977842 -280.000964)
		(width 0.12954)
		(layer "F.Cu")
		(net "M_G_CPU1_SB_DQS_DN<5>")
	)
	(segment
		(start 158.567374 -280.883614)
		(end 159.03321 -280.883614)
		(width 0.12954)
		(layer "F.Cu")
		(net "M_G_CPU1_SB_DQS_DN<5>")
	)
	(segment
		(start 157.973268 -280.99639)
		(end 158.114492 -281.137614)
		(width 0.12954)
		(layer "F.Cu")
		(net "M_G_CPU1_SB_DQS_DN<5>")
	)
	(segment
		(start 154.563572 -276.413976)
		(end 157.097984 -278.948388)
		(width 0.12954)
		(layer "F.Cu")
		(net "M_G_CPU1_SB_DQS_DN<5>")
	)
	(segment
		(start 157.430724 -279.746964)
		(end 157.89656 -279.746964)
		(width 0.12954)
		(layer "F.Cu")
		(net "M_G_CPU1_SB_DQS_DN<5>")
	)
	(segment
		(start 159.704024 -282.020264)
		(end 160.16986 -282.020264)
		(width 0.12954)
		(layer "F.Cu")
		(net "M_G_CPU1_SB_DQS_DN<5>")
	)
	(segment
		(start 160.500822 -282.816808)
		(end 160.246568 -283.071062)
		(width 0.12954)
		(layer "F.Cu")
		(net "M_G_CPU1_SB_DQS_DN<5>")
	)
	(segment
		(start 157.17647 -280.000964)
		(end 157.430724 -279.746964)
		(width 0.12954)
		(layer "F.Cu")
		(net "M_G_CPU1_SB_DQS_DN<5>")
	)
	(segment
		(start 160.501076 -282.35148)
		(end 160.500822 -282.816808)
		(width 0.12954)
		(layer "F.Cu")
		(net "M_G_CPU1_SB_DQS_DN<5>")
	)
	(segment
		(start 147.834096 -276.480016)
		(end 147.900136 -276.413976)
		(width 0.0762)
		(layer "F.Cu")
		(net "M_G_CPU1_SB_DQS_DN<5>")
	)
	(segment
		(start 147.213828 -276.623526)
		(end 147.357338 -276.480016)
		(width 0.0762)
		(layer "F.Cu")
		(net "M_G_CPU1_SB_DQS_DN<5>")
	)
	(segment
		(start 157.097984 -279.399492)
		(end 156.836618 -279.660858)
		(width 0.12954)
		(layer "F.Cu")
		(net "M_G_CPU1_SB_DQS_DN<5>")
	)
	(segment
		(start 162.976052 -285.999174)
		(end 163.605972 -285.999174)
		(width 0.12954)
		(layer "F.Cu")
		(net "M_G_CPU1_SB_DQS_DN<5>")
	)
	(segment
		(start 159.364426 -281.21483)
		(end 159.364172 -281.680158)
		(width 0.12954)
		(layer "F.Cu")
		(net "M_G_CPU1_SB_DQS_DN<5>")
	)
	(segment
		(start 156.977842 -280.000964)
		(end 157.17647 -280.000964)
		(width 0.12954)
		(layer "F.Cu")
		(net "M_G_CPU1_SB_DQS_DN<5>")
	)
	(segment
		(start 147.357338 -276.480016)
		(end 147.834096 -276.480016)
		(width 0.0762)
		(layer "F.Cu")
		(net "M_G_CPU1_SB_DQS_DN<5>")
	)
	(segment
		(start 159.109918 -281.934412)
		(end 159.109918 -282.13304)
		(width 0.12954)
		(layer "F.Cu")
		(net "M_G_CPU1_SB_DQS_DN<5>")
	)
	(segment
		(start 163.605972 -285.999174)
		(end 163.869878 -285.735268)
		(width 0.12954)
		(layer "F.Cu")
		(net "M_G_CPU1_SB_DQS_DN<5>")
	)
	(segment
		(start 159.364172 -281.680158)
		(end 159.109918 -281.934412)
		(width 0.12954)
		(layer "F.Cu")
		(net "M_G_CPU1_SB_DQS_DN<5>")
	)
	(segment
		(start 157.097984 -278.948388)
		(end 157.097984 -279.399492)
		(width 0.12954)
		(layer "F.Cu")
		(net "M_G_CPU1_SB_DQS_DN<5>")
	)
	(segment
		(start 147.919186 -276.413976)
		(end 154.563572 -276.413976)
		(width 0.12954)
		(layer "F.Cu")
		(net "M_G_CPU1_SB_DQS_DN<5>")
	)
	(arc
		(start 146.200876 -276.57298)
		(mid 146.291045 -276.610329)
		(end 146.38782 -276.623018)
		(width 0.0762)
		(layer "F.Cu")
		(net "M_G_CPU1_SB_DQS_DN<5>")
	)
	(arc
		(start 145.634964 -276.57298)
		(mid 145.91792 -276.496803)
		(end 146.200876 -276.57298)
		(width 0.0762)
		(layer "F.Cu")
		(net "M_G_CPU1_SB_DQS_DN<5>")
	)
	(arc
		(start 144.69491 -276.57298)
		(mid 144.977866 -276.496803)
		(end 145.260822 -276.57298)
		(width 0.0762)
		(layer "F.Cu")
		(net "M_G_CPU1_SB_DQS_DN<5>")
	)
	(arc
		(start 145.269204 -276.577806)
		(mid 145.452712 -276.6233)
		(end 145.634964 -276.57298)
		(width 0.0762)
		(layer "F.Cu")
		(net "M_G_CPU1_SB_DQS_DN<5>")
	)
	(arc
		(start 144.55267 -276.620478)
		(mid 144.621617 -276.605481)
		(end 144.686528 -276.577806)
		(width 0.0762)
		(layer "F.Cu")
		(net "M_G_CPU1_SB_DQS_DN<5>")
	)
	(arc
		(start 144.406112 -276.42566)
		(mid 144.423306 -276.565246)
		(end 144.55267 -276.620478)
		(width 0.0762)
		(layer "F.Cu")
		(net "M_G_CPU1_SB_DQS_DN<5>")
	)
	(segment
		(start 159.82442 -273.754596)
		(end 159.82442 -273.937476)
		(width 0.12954)
		(layer "F.Cu")
		(net "M_G_CPU1_SB_DQS_DN<4>")
	)
	(segment
		(start 158.695898 -272.609818)
		(end 158.695898 -272.808954)
		(width 0.12954)
		(layer "F.Cu")
		(net "M_G_CPU1_SB_DQS_DN<4>")
	)
	(segment
		(start 147.919186 -271.393158)
		(end 157.626558 -271.393158)
		(width 0.12954)
		(layer "F.Cu")
		(net "M_G_CPU1_SB_DQS_DN<4>")
	)
	(segment
		(start 160.358836 -273.22018)
		(end 159.82442 -273.754596)
		(width 0.12954)
		(layer "F.Cu")
		(net "M_G_CPU1_SB_DQS_DN<4>")
	)
	(segment
		(start 159.11576 -271.72412)
		(end 159.11576 -272.189956)
		(width 0.12954)
		(layer "F.Cu")
		(net "M_G_CPU1_SB_DQS_DN<4>")
	)
	(segment
		(start 147.900136 -271.393158)
		(end 147.919186 -271.393158)
		(width 0.0762)
		(layer "F.Cu")
		(net "M_G_CPU1_SB_DQS_DN<4>")
	)
	(segment
		(start 158.784798 -271.393158)
		(end 159.11576 -271.72412)
		(width 0.12954)
		(layer "F.Cu")
		(net "M_G_CPU1_SB_DQS_DN<4>")
	)
	(segment
		(start 146.388328 -271.76349)
		(end 147.213828 -271.76349)
		(width 0.0762)
		(layer "F.Cu")
		(net "M_G_CPU1_SB_DQS_DN<4>")
	)
	(segment
		(start 158.318962 -271.393158)
		(end 158.784798 -271.393158)
		(width 0.12954)
		(layer "F.Cu")
		(net "M_G_CPU1_SB_DQS_DN<4>")
	)
	(segment
		(start 163.605972 -276.64918)
		(end 163.869878 -276.385274)
		(width 0.12954)
		(layer "F.Cu")
		(net "M_G_CPU1_SB_DQS_DN<4>")
	)
	(segment
		(start 160.704276 -274.228052)
		(end 161.073084 -274.59686)
		(width 0.12954)
		(layer "F.Cu")
		(net "M_G_CPU1_SB_DQS_DN<4>")
	)
	(segment
		(start 158.836614 -272.94967)
		(end 159.03575 -272.94967)
		(width 0.12954)
		(layer "F.Cu")
		(net "M_G_CPU1_SB_DQS_DN<4>")
	)
	(segment
		(start 159.82442 -273.937476)
		(end 160.114996 -274.228052)
		(width 0.12954)
		(layer "F.Cu")
		(net "M_G_CPU1_SB_DQS_DN<4>")
	)
	(segment
		(start 144.507966 -271.390364)
		(end 144.406112 -271.565624)
		(width 0.0762)
		(layer "F.Cu")
		(net "M_G_CPU1_SB_DQS_DN<4>")
	)
	(segment
		(start 160.358836 -272.754344)
		(end 160.358836 -273.22018)
		(width 0.12954)
		(layer "F.Cu")
		(net "M_G_CPU1_SB_DQS_DN<4>")
	)
	(segment
		(start 157.873192 -271.639792)
		(end 158.072328 -271.639792)
		(width 0.12954)
		(layer "F.Cu")
		(net "M_G_CPU1_SB_DQS_DN<4>")
	)
	(segment
		(start 159.03575 -272.94967)
		(end 159.562038 -272.423382)
		(width 0.12954)
		(layer "F.Cu")
		(net "M_G_CPU1_SB_DQS_DN<4>")
	)
	(segment
		(start 162.209734 -276.32279)
		(end 162.536124 -276.64918)
		(width 0.12954)
		(layer "F.Cu")
		(net "M_G_CPU1_SB_DQS_DN<4>")
	)
	(segment
		(start 146.38782 -271.762982)
		(end 146.388328 -271.76349)
		(width 0.0762)
		(layer "F.Cu")
		(net "M_G_CPU1_SB_DQS_DN<4>")
	)
	(segment
		(start 161.840926 -275.364702)
		(end 162.209734 -275.73351)
		(width 0.12954)
		(layer "F.Cu")
		(net "M_G_CPU1_SB_DQS_DN<4>")
	)
	(segment
		(start 161.073084 -275.18614)
		(end 161.251646 -275.364702)
		(width 0.12954)
		(layer "F.Cu")
		(net "M_G_CPU1_SB_DQS_DN<4>")
	)
	(segment
		(start 161.073084 -274.59686)
		(end 161.073084 -275.18614)
		(width 0.12954)
		(layer "F.Cu")
		(net "M_G_CPU1_SB_DQS_DN<4>")
	)
	(segment
		(start 161.251646 -275.364702)
		(end 161.840926 -275.364702)
		(width 0.12954)
		(layer "F.Cu")
		(net "M_G_CPU1_SB_DQS_DN<4>")
	)
	(segment
		(start 160.114996 -274.228052)
		(end 160.704276 -274.228052)
		(width 0.12954)
		(layer "F.Cu")
		(net "M_G_CPU1_SB_DQS_DN<4>")
	)
	(segment
		(start 160.027874 -272.423382)
		(end 160.358836 -272.754344)
		(width 0.12954)
		(layer "F.Cu")
		(net "M_G_CPU1_SB_DQS_DN<4>")
	)
	(segment
		(start 159.562038 -272.423382)
		(end 160.027874 -272.423382)
		(width 0.12954)
		(layer "F.Cu")
		(net "M_G_CPU1_SB_DQS_DN<4>")
	)
	(segment
		(start 147.834096 -271.459198)
		(end 147.900136 -271.393158)
		(width 0.0762)
		(layer "F.Cu")
		(net "M_G_CPU1_SB_DQS_DN<4>")
	)
	(segment
		(start 162.209734 -275.73351)
		(end 162.209734 -276.32279)
		(width 0.12954)
		(layer "F.Cu")
		(net "M_G_CPU1_SB_DQS_DN<4>")
	)
	(segment
		(start 162.536124 -276.64918)
		(end 163.605972 -276.64918)
		(width 0.12954)
		(layer "F.Cu")
		(net "M_G_CPU1_SB_DQS_DN<4>")
	)
	(segment
		(start 159.11576 -272.189956)
		(end 158.695898 -272.609818)
		(width 0.12954)
		(layer "F.Cu")
		(net "M_G_CPU1_SB_DQS_DN<4>")
	)
	(segment
		(start 163.869878 -276.385274)
		(end 164.427916 -276.385274)
		(width 0.12954)
		(layer "F.Cu")
		(net "M_G_CPU1_SB_DQS_DN<4>")
	)
	(segment
		(start 144.686528 -271.71777)
		(end 144.69491 -271.712944)
		(width 0.0762)
		(layer "F.Cu")
		(net "M_G_CPU1_SB_DQS_DN<4>")
	)
	(segment
		(start 158.072328 -271.639792)
		(end 158.318962 -271.393158)
		(width 0.12954)
		(layer "F.Cu")
		(net "M_G_CPU1_SB_DQS_DN<4>")
	)
	(segment
		(start 157.626558 -271.393158)
		(end 157.873192 -271.639792)
		(width 0.12954)
		(layer "F.Cu")
		(net "M_G_CPU1_SB_DQS_DN<4>")
	)
	(segment
		(start 147.213828 -271.76349)
		(end 147.51812 -271.459198)
		(width 0.0762)
		(layer "F.Cu")
		(net "M_G_CPU1_SB_DQS_DN<4>")
	)
	(segment
		(start 158.695898 -272.808954)
		(end 158.836614 -272.94967)
		(width 0.12954)
		(layer "F.Cu")
		(net "M_G_CPU1_SB_DQS_DN<4>")
	)
	(segment
		(start 147.51812 -271.459198)
		(end 147.834096 -271.459198)
		(width 0.0762)
		(layer "F.Cu")
		(net "M_G_CPU1_SB_DQS_DN<4>")
	)
	(segment
		(start 145.260822 -271.712944)
		(end 145.269204 -271.71777)
		(width 0.0762)
		(layer "F.Cu")
		(net "M_G_CPU1_SB_DQS_DN<4>")
	)
	(arc
		(start 144.406112 -271.565624)
		(mid 144.423306 -271.70521)
		(end 144.55267 -271.760442)
		(width 0.0762)
		(layer "F.Cu")
		(net "M_G_CPU1_SB_DQS_DN<4>")
	)
	(arc
		(start 144.69491 -271.712944)
		(mid 144.977866 -271.636767)
		(end 145.260822 -271.712944)
		(width 0.0762)
		(layer "F.Cu")
		(net "M_G_CPU1_SB_DQS_DN<4>")
	)
	(arc
		(start 146.200876 -271.712944)
		(mid 146.291045 -271.750293)
		(end 146.38782 -271.762982)
		(width 0.0762)
		(layer "F.Cu")
		(net "M_G_CPU1_SB_DQS_DN<4>")
	)
	(arc
		(start 145.269204 -271.71777)
		(mid 145.452712 -271.763264)
		(end 145.634964 -271.712944)
		(width 0.0762)
		(layer "F.Cu")
		(net "M_G_CPU1_SB_DQS_DN<4>")
	)
	(arc
		(start 144.55267 -271.760442)
		(mid 144.621617 -271.745445)
		(end 144.686528 -271.71777)
		(width 0.0762)
		(layer "F.Cu")
		(net "M_G_CPU1_SB_DQS_DN<4>")
	)
	(arc
		(start 145.634964 -271.712944)
		(mid 145.91792 -271.636767)
		(end 146.200876 -271.712944)
		(width 0.0762)
		(layer "F.Cu")
		(net "M_G_CPU1_SB_DQS_DN<4>")
	)
	(segment
		(start 147.261326 -290.457128)
		(end 147.445984 -290.641786)
		(width 0.0762)
		(layer "F.Cu")
		(net "M_G_CPU1_SB_DQS_DN<3>")
	)
	(segment
		(start 147.776184 -290.707826)
		(end 147.795234 -290.707826)
		(width 0.0762)
		(layer "F.Cu")
		(net "M_G_CPU1_SB_DQS_DN<3>")
	)
	(segment
		(start 162.644074 -311.994042)
		(end 162.372802 -312.265314)
		(width 0.12954)
		(layer "F.Cu")
		(net "M_G_CPU1_SB_DQS_DN<3>")
	)
	(segment
		(start 162.501834 -311.653936)
		(end 162.644074 -311.796176)
		(width 0.12954)
		(layer "F.Cu")
		(net "M_G_CPU1_SB_DQS_DN<3>")
	)
	(segment
		(start 148.228812 -290.707826)
		(end 149.54123 -292.020244)
		(width 0.12954)
		(layer "F.Cu")
		(net "M_G_CPU1_SB_DQS_DN<3>")
	)
	(segment
		(start 162.644074 -311.796176)
		(end 162.644074 -311.994042)
		(width 0.12954)
		(layer "F.Cu")
		(net "M_G_CPU1_SB_DQS_DN<3>")
	)
	(segment
		(start 161.236152 -311.128664)
		(end 161.236152 -311.595008)
		(width 0.12954)
		(layer "F.Cu")
		(net "M_G_CPU1_SB_DQS_DN<3>")
	)
	(segment
		(start 162.032188 -311.924954)
		(end 162.30346 -311.653936)
		(width 0.12954)
		(layer "F.Cu")
		(net "M_G_CPU1_SB_DQS_DN<3>")
	)
	(segment
		(start 166.312342 -313.042808)
		(end 166.61765 -313.042808)
		(width 0.101346)
		(layer "F.Cu")
		(net "M_G_CPU1_SB_DQS_DN<3>")
	)
	(segment
		(start 147.445984 -290.641786)
		(end 147.710144 -290.641786)
		(width 0.0762)
		(layer "F.Cu")
		(net "M_G_CPU1_SB_DQS_DN<3>")
	)
	(segment
		(start 149.54123 -298.693332)
		(end 161.507424 -310.659526)
		(width 0.12954)
		(layer "F.Cu")
		(net "M_G_CPU1_SB_DQS_DN<3>")
	)
	(segment
		(start 161.507424 -310.857392)
		(end 161.236152 -311.128664)
		(width 0.12954)
		(layer "F.Cu")
		(net "M_G_CPU1_SB_DQS_DN<3>")
	)
	(segment
		(start 165.994842 -313.360308)
		(end 166.312342 -313.042808)
		(width 0.101346)
		(layer "F.Cu")
		(net "M_G_CPU1_SB_DQS_DN<3>")
	)
	(segment
		(start 162.30346 -311.653936)
		(end 162.501834 -311.653936)
		(width 0.12954)
		(layer "F.Cu")
		(net "M_G_CPU1_SB_DQS_DN<3>")
	)
	(segment
		(start 162.372802 -312.731658)
		(end 162.738562 -313.097418)
		(width 0.12954)
		(layer "F.Cu")
		(net "M_G_CPU1_SB_DQS_DN<3>")
	)
	(segment
		(start 167.042846 -313.468004)
		(end 167.69715 -313.468004)
		(width 0.101346)
		(layer "F.Cu")
		(net "M_G_CPU1_SB_DQS_DN<3>")
	)
	(segment
		(start 167.69715 -313.468004)
		(end 168.014396 -313.78525)
		(width 0.101346)
		(layer "F.Cu")
		(net "M_G_CPU1_SB_DQS_DN<3>")
	)
	(segment
		(start 149.54123 -292.020244)
		(end 149.54123 -298.693332)
		(width 0.12954)
		(layer "F.Cu")
		(net "M_G_CPU1_SB_DQS_DN<3>")
	)
	(segment
		(start 146.38782 -290.457128)
		(end 147.261326 -290.457128)
		(width 0.0762)
		(layer "F.Cu")
		(net "M_G_CPU1_SB_DQS_DN<3>")
	)
	(segment
		(start 161.507424 -310.659526)
		(end 161.507424 -310.857392)
		(width 0.12954)
		(layer "F.Cu")
		(net "M_G_CPU1_SB_DQS_DN<3>")
	)
	(segment
		(start 168.014396 -313.78525)
		(end 168.527984 -313.78525)
		(width 0.101346)
		(layer "F.Cu")
		(net "M_G_CPU1_SB_DQS_DN<3>")
	)
	(segment
		(start 161.236152 -311.595008)
		(end 161.566098 -311.924954)
		(width 0.12954)
		(layer "F.Cu")
		(net "M_G_CPU1_SB_DQS_DN<3>")
	)
	(segment
		(start 147.710144 -290.641786)
		(end 147.776184 -290.707826)
		(width 0.0762)
		(layer "F.Cu")
		(net "M_G_CPU1_SB_DQS_DN<3>")
	)
	(segment
		(start 163.303712 -313.097418)
		(end 163.566602 -313.360308)
		(width 0.12954)
		(layer "F.Cu")
		(net "M_G_CPU1_SB_DQS_DN<3>")
	)
	(segment
		(start 163.566602 -313.360308)
		(end 165.994842 -313.360308)
		(width 0.101346)
		(layer "F.Cu")
		(net "M_G_CPU1_SB_DQS_DN<3>")
	)
	(segment
		(start 166.61765 -313.042808)
		(end 167.042846 -313.468004)
		(width 0.101346)
		(layer "F.Cu")
		(net "M_G_CPU1_SB_DQS_DN<3>")
	)
	(segment
		(start 161.566098 -311.924954)
		(end 162.032188 -311.924954)
		(width 0.12954)
		(layer "F.Cu")
		(net "M_G_CPU1_SB_DQS_DN<3>")
	)
	(segment
		(start 147.795234 -290.707826)
		(end 148.228812 -290.707826)
		(width 0.12954)
		(layer "F.Cu")
		(net "M_G_CPU1_SB_DQS_DN<3>")
	)
	(segment
		(start 162.738562 -313.097418)
		(end 163.303712 -313.097418)
		(width 0.12954)
		(layer "F.Cu")
		(net "M_G_CPU1_SB_DQS_DN<3>")
	)
	(segment
		(start 162.372802 -312.265314)
		(end 162.372802 -312.731658)
		(width 0.12954)
		(layer "F.Cu")
		(net "M_G_CPU1_SB_DQS_DN<3>")
	)
	(arc
		(start 145.976848 -290.580826)
		(mid 145.996197 -290.578488)
		(end 146.015456 -290.575492)
		(width 0.0762)
		(layer "F.Cu")
		(net "M_G_CPU1_SB_DQS_DN<3>")
	)
	(arc
		(start 146.200876 -290.507674)
		(mid 146.276116 -290.474361)
		(end 146.356832 -290.458398)
		(width 0.0762)
		(layer "F.Cu")
		(net "M_G_CPU1_SB_DQS_DN<3>")
	)
	(arc
		(start 146.356832 -290.458398)
		(mid 146.372313 -290.457442)
		(end 146.38782 -290.457128)
		(width 0.0762)
		(layer "F.Cu")
		(net "M_G_CPU1_SB_DQS_DN<3>")
	)
	(arc
		(start 145.447766 -290.830254)
		(mid 145.691197 -290.660767)
		(end 145.976848 -290.580826)
		(width 0.0762)
		(layer "F.Cu")
		(net "M_G_CPU1_SB_DQS_DN<3>")
	)
	(arc
		(start 146.015456 -290.575492)
		(mid 146.111165 -290.54978)
		(end 146.200876 -290.507674)
		(width 0.0762)
		(layer "F.Cu")
		(net "M_G_CPU1_SB_DQS_DN<3>")
	)
	(segment
		(start 160.764728 -301.572422)
		(end 160.570418 -301.766732)
		(width 0.12954)
		(layer "F.Cu")
		(net "M_G_CPU1_SB_DQS_DN<2>")
	)
	(segment
		(start 161.366708 -302.563022)
		(end 161.561018 -302.368712)
		(width 0.12954)
		(layer "F.Cu")
		(net "M_G_CPU1_SB_DQS_DN<2>")
	)
	(segment
		(start 149.539452 -285.678626)
		(end 153.933144 -290.072318)
		(width 0.12954)
		(layer "F.Cu")
		(net "M_G_CPU1_SB_DQS_DN<2>")
	)
	(segment
		(start 161.707068 -302.903382)
		(end 161.707068 -303.370234)
		(width 0.12954)
		(layer "F.Cu")
		(net "M_G_CPU1_SB_DQS_DN<2>")
	)
	(segment
		(start 163.303712 -303.747424)
		(end 163.566602 -304.010314)
		(width 0.12954)
		(layer "F.Cu")
		(net "M_G_CPU1_SB_DQS_DN<2>")
	)
	(segment
		(start 153.933144 -294.553894)
		(end 160.764728 -301.385478)
		(width 0.12954)
		(layer "F.Cu")
		(net "M_G_CPU1_SB_DQS_DN<2>")
	)
	(segment
		(start 153.933144 -290.072318)
		(end 153.933144 -294.553894)
		(width 0.12954)
		(layer "F.Cu")
		(net "M_G_CPU1_SB_DQS_DN<2>")
	)
	(segment
		(start 147.407376 -285.597346)
		(end 147.422616 -285.612586)
		(width 0.0762)
		(layer "F.Cu")
		(net "M_G_CPU1_SB_DQS_DN<2>")
	)
	(segment
		(start 161.759138 -302.368712)
		(end 161.901378 -302.510952)
		(width 0.12954)
		(layer "F.Cu")
		(net "M_G_CPU1_SB_DQS_DN<2>")
	)
	(segment
		(start 160.570418 -301.766732)
		(end 160.570418 -302.233584)
		(width 0.12954)
		(layer "F.Cu")
		(net "M_G_CPU1_SB_DQS_DN<2>")
	)
	(segment
		(start 161.901378 -302.510952)
		(end 161.901378 -302.709072)
		(width 0.12954)
		(layer "F.Cu")
		(net "M_G_CPU1_SB_DQS_DN<2>")
	)
	(segment
		(start 161.901378 -302.709072)
		(end 161.707068 -302.903382)
		(width 0.12954)
		(layer "F.Cu")
		(net "M_G_CPU1_SB_DQS_DN<2>")
	)
	(segment
		(start 166.312342 -303.692814)
		(end 166.591742 -303.692814)
		(width 0.101346)
		(layer "F.Cu")
		(net "M_G_CPU1_SB_DQS_DN<2>")
	)
	(segment
		(start 161.707068 -303.370234)
		(end 162.084258 -303.747424)
		(width 0.12954)
		(layer "F.Cu")
		(net "M_G_CPU1_SB_DQS_DN<2>")
	)
	(segment
		(start 162.084258 -303.747424)
		(end 163.303712 -303.747424)
		(width 0.12954)
		(layer "F.Cu")
		(net "M_G_CPU1_SB_DQS_DN<2>")
	)
	(segment
		(start 161.561018 -302.368712)
		(end 161.759138 -302.368712)
		(width 0.12954)
		(layer "F.Cu")
		(net "M_G_CPU1_SB_DQS_DN<2>")
	)
	(segment
		(start 147.834096 -285.612586)
		(end 147.900136 -285.678626)
		(width 0.0762)
		(layer "F.Cu")
		(net "M_G_CPU1_SB_DQS_DN<2>")
	)
	(segment
		(start 165.994842 -304.010314)
		(end 166.312342 -303.692814)
		(width 0.101346)
		(layer "F.Cu")
		(net "M_G_CPU1_SB_DQS_DN<2>")
	)
	(segment
		(start 160.764728 -301.385478)
		(end 160.764728 -301.572422)
		(width 0.12954)
		(layer "F.Cu")
		(net "M_G_CPU1_SB_DQS_DN<2>")
	)
	(segment
		(start 160.899856 -302.563022)
		(end 161.366708 -302.563022)
		(width 0.12954)
		(layer "F.Cu")
		(net "M_G_CPU1_SB_DQS_DN<2>")
	)
	(segment
		(start 147.422616 -285.612586)
		(end 147.834096 -285.612586)
		(width 0.0762)
		(layer "F.Cu")
		(net "M_G_CPU1_SB_DQS_DN<2>")
	)
	(segment
		(start 146.38782 -285.597346)
		(end 147.407376 -285.597346)
		(width 0.0762)
		(layer "F.Cu")
		(net "M_G_CPU1_SB_DQS_DN<2>")
	)
	(segment
		(start 163.566602 -304.010314)
		(end 165.994842 -304.010314)
		(width 0.101346)
		(layer "F.Cu")
		(net "M_G_CPU1_SB_DQS_DN<2>")
	)
	(segment
		(start 147.900136 -285.678626)
		(end 147.919186 -285.678626)
		(width 0.0762)
		(layer "F.Cu")
		(net "M_G_CPU1_SB_DQS_DN<2>")
	)
	(segment
		(start 166.591742 -303.692814)
		(end 167.016938 -304.11801)
		(width 0.101346)
		(layer "F.Cu")
		(net "M_G_CPU1_SB_DQS_DN<2>")
	)
	(segment
		(start 167.69715 -304.11801)
		(end 168.014396 -304.435256)
		(width 0.101346)
		(layer "F.Cu")
		(net "M_G_CPU1_SB_DQS_DN<2>")
	)
	(segment
		(start 147.919186 -285.678626)
		(end 149.539452 -285.678626)
		(width 0.12954)
		(layer "F.Cu")
		(net "M_G_CPU1_SB_DQS_DN<2>")
	)
	(segment
		(start 160.570418 -302.233584)
		(end 160.899856 -302.563022)
		(width 0.12954)
		(layer "F.Cu")
		(net "M_G_CPU1_SB_DQS_DN<2>")
	)
	(segment
		(start 167.016938 -304.11801)
		(end 167.69715 -304.11801)
		(width 0.101346)
		(layer "F.Cu")
		(net "M_G_CPU1_SB_DQS_DN<2>")
	)
	(segment
		(start 168.014396 -304.435256)
		(end 168.527984 -304.435256)
		(width 0.101346)
		(layer "F.Cu")
		(net "M_G_CPU1_SB_DQS_DN<2>")
	)
	(arc
		(start 145.447766 -285.970472)
		(mid 145.691197 -285.800985)
		(end 145.976848 -285.721044)
		(width 0.0762)
		(layer "F.Cu")
		(net "M_G_CPU1_SB_DQS_DN<2>")
	)
	(arc
		(start 145.976848 -285.721044)
		(mid 145.996197 -285.718706)
		(end 146.015456 -285.71571)
		(width 0.0762)
		(layer "F.Cu")
		(net "M_G_CPU1_SB_DQS_DN<2>")
	)
	(arc
		(start 146.015456 -285.71571)
		(mid 146.111165 -285.689998)
		(end 146.200876 -285.647892)
		(width 0.0762)
		(layer "F.Cu")
		(net "M_G_CPU1_SB_DQS_DN<2>")
	)
	(arc
		(start 146.200876 -285.647892)
		(mid 146.276116 -285.614579)
		(end 146.356832 -285.598616)
		(width 0.0762)
		(layer "F.Cu")
		(net "M_G_CPU1_SB_DQS_DN<2>")
	)
	(arc
		(start 146.356832 -285.598616)
		(mid 146.372313 -285.59766)
		(end 146.38782 -285.597346)
		(width 0.0762)
		(layer "F.Cu")
		(net "M_G_CPU1_SB_DQS_DN<2>")
	)
	(segment
		(start 165.994842 -294.66032)
		(end 166.312342 -294.34282)
		(width 0.101346)
		(layer "F.Cu")
		(net "M_G_CPU1_SB_DQS_DN<1>")
	)
	(segment
		(start 147.900136 -280.546048)
		(end 147.919186 -280.546048)
		(width 0.0762)
		(layer "F.Cu")
		(net "M_G_CPU1_SB_DQS_DN<1>")
	)
	(segment
		(start 161.354262 -291.199316)
		(end 161.496502 -291.341556)
		(width 0.12954)
		(layer "F.Cu")
		(net "M_G_CPU1_SB_DQS_DN<1>")
	)
	(segment
		(start 147.834096 -280.480008)
		(end 147.900136 -280.546048)
		(width 0.0762)
		(layer "F.Cu")
		(net "M_G_CPU1_SB_DQS_DN<1>")
	)
	(segment
		(start 166.609522 -294.34282)
		(end 167.034718 -294.768016)
		(width 0.101346)
		(layer "F.Cu")
		(net "M_G_CPU1_SB_DQS_DN<1>")
	)
	(segment
		(start 147.919186 -280.546048)
		(end 150.746714 -280.546048)
		(width 0.12954)
		(layer "F.Cu")
		(net "M_G_CPU1_SB_DQS_DN<1>")
	)
	(segment
		(start 147.58797 -280.480008)
		(end 147.834096 -280.480008)
		(width 0.0762)
		(layer "F.Cu")
		(net "M_G_CPU1_SB_DQS_DN<1>")
	)
	(segment
		(start 167.034718 -294.768016)
		(end 167.69715 -294.768016)
		(width 0.101346)
		(layer "F.Cu")
		(net "M_G_CPU1_SB_DQS_DN<1>")
	)
	(segment
		(start 160.359852 -290.159186)
		(end 160.359852 -290.403026)
		(width 0.12954)
		(layer "F.Cu")
		(net "M_G_CPU1_SB_DQS_DN<1>")
	)
	(segment
		(start 161.496502 -291.341556)
		(end 161.496502 -291.539676)
		(width 0.12954)
		(layer "F.Cu")
		(net "M_G_CPU1_SB_DQS_DN<1>")
	)
	(segment
		(start 162.75558 -294.39743)
		(end 163.303712 -294.39743)
		(width 0.12954)
		(layer "F.Cu")
		(net "M_G_CPU1_SB_DQS_DN<1>")
	)
	(segment
		(start 166.312342 -294.34282)
		(end 166.609522 -294.34282)
		(width 0.101346)
		(layer "F.Cu")
		(net "M_G_CPU1_SB_DQS_DN<1>")
	)
	(segment
		(start 160.359852 -290.403026)
		(end 159.79394 -290.968938)
		(width 0.12954)
		(layer "F.Cu")
		(net "M_G_CPU1_SB_DQS_DN<1>")
	)
	(segment
		(start 160.123378 -291.765228)
		(end 160.59023 -291.765228)
		(width 0.12954)
		(layer "F.Cu")
		(net "M_G_CPU1_SB_DQS_DN<1>")
	)
	(segment
		(start 167.69715 -294.768016)
		(end 168.014396 -295.085262)
		(width 0.101346)
		(layer "F.Cu")
		(net "M_G_CPU1_SB_DQS_DN<1>")
	)
	(segment
		(start 161.156142 -291.199316)
		(end 161.354262 -291.199316)
		(width 0.12954)
		(layer "F.Cu")
		(net "M_G_CPU1_SB_DQS_DN<1>")
	)
	(segment
		(start 161.496502 -291.539676)
		(end 160.93059 -292.105588)
		(width 0.12954)
		(layer "F.Cu")
		(net "M_G_CPU1_SB_DQS_DN<1>")
	)
	(segment
		(start 160.93059 -292.57244)
		(end 162.75558 -294.39743)
		(width 0.12954)
		(layer "F.Cu")
		(net "M_G_CPU1_SB_DQS_DN<1>")
	)
	(segment
		(start 146.38782 -280.73731)
		(end 147.330668 -280.73731)
		(width 0.0762)
		(layer "F.Cu")
		(net "M_G_CPU1_SB_DQS_DN<1>")
	)
	(segment
		(start 168.014396 -295.085262)
		(end 168.527984 -295.085262)
		(width 0.101346)
		(layer "F.Cu")
		(net "M_G_CPU1_SB_DQS_DN<1>")
	)
	(segment
		(start 163.566602 -294.66032)
		(end 165.994842 -294.66032)
		(width 0.101346)
		(layer "F.Cu")
		(net "M_G_CPU1_SB_DQS_DN<1>")
	)
	(segment
		(start 147.330668 -280.73731)
		(end 147.58797 -280.480008)
		(width 0.0762)
		(layer "F.Cu")
		(net "M_G_CPU1_SB_DQS_DN<1>")
	)
	(segment
		(start 163.303712 -294.39743)
		(end 163.566602 -294.66032)
		(width 0.12954)
		(layer "F.Cu")
		(net "M_G_CPU1_SB_DQS_DN<1>")
	)
	(segment
		(start 150.746714 -280.546048)
		(end 160.359852 -290.159186)
		(width 0.12954)
		(layer "F.Cu")
		(net "M_G_CPU1_SB_DQS_DN<1>")
	)
	(segment
		(start 160.59023 -291.765228)
		(end 161.156142 -291.199316)
		(width 0.12954)
		(layer "F.Cu")
		(net "M_G_CPU1_SB_DQS_DN<1>")
	)
	(segment
		(start 160.93059 -292.105588)
		(end 160.93059 -292.57244)
		(width 0.12954)
		(layer "F.Cu")
		(net "M_G_CPU1_SB_DQS_DN<1>")
	)
	(segment
		(start 159.79394 -291.43579)
		(end 160.123378 -291.765228)
		(width 0.12954)
		(layer "F.Cu")
		(net "M_G_CPU1_SB_DQS_DN<1>")
	)
	(segment
		(start 159.79394 -290.968938)
		(end 159.79394 -291.43579)
		(width 0.12954)
		(layer "F.Cu")
		(net "M_G_CPU1_SB_DQS_DN<1>")
	)
	(arc
		(start 146.015456 -280.855674)
		(mid 146.111165 -280.829962)
		(end 146.200876 -280.787856)
		(width 0.0762)
		(layer "F.Cu")
		(net "M_G_CPU1_SB_DQS_DN<1>")
	)
	(arc
		(start 145.976848 -280.861008)
		(mid 145.996197 -280.85867)
		(end 146.015456 -280.855674)
		(width 0.0762)
		(layer "F.Cu")
		(net "M_G_CPU1_SB_DQS_DN<1>")
	)
	(arc
		(start 146.200876 -280.787856)
		(mid 146.276116 -280.754543)
		(end 146.356832 -280.73858)
		(width 0.0762)
		(layer "F.Cu")
		(net "M_G_CPU1_SB_DQS_DN<1>")
	)
	(arc
		(start 146.356832 -280.73858)
		(mid 146.372313 -280.737624)
		(end 146.38782 -280.73731)
		(width 0.0762)
		(layer "F.Cu")
		(net "M_G_CPU1_SB_DQS_DN<1>")
	)
	(arc
		(start 145.447766 -281.110436)
		(mid 145.691197 -280.940949)
		(end 145.976848 -280.861008)
		(width 0.0762)
		(layer "F.Cu")
		(net "M_G_CPU1_SB_DQS_DN<1>")
	)
	(segment
		(start 163.303712 -285.047436)
		(end 163.566602 -285.310326)
		(width 0.12954)
		(layer "F.Cu")
		(net "M_G_CPU1_SB_DQS_DN<0>")
	)
	(segment
		(start 146.38782 -275.877274)
		(end 147.302728 -275.877274)
		(width 0.0762)
		(layer "F.Cu")
		(net "M_G_CPU1_SB_DQS_DN<0>")
	)
	(segment
		(start 162.30219 -283.525976)
		(end 162.61461 -283.838396)
		(width 0.12954)
		(layer "F.Cu")
		(net "M_G_CPU1_SB_DQS_DN<0>")
	)
	(segment
		(start 162.61461 -284.729174)
		(end 162.932872 -285.047436)
		(width 0.12954)
		(layer "F.Cu")
		(net "M_G_CPU1_SB_DQS_DN<0>")
	)
	(segment
		(start 161.857436 -283.772102)
		(end 162.103562 -283.525976)
		(width 0.12954)
		(layer "F.Cu")
		(net "M_G_CPU1_SB_DQS_DN<0>")
	)
	(segment
		(start 147.900136 -275.983446)
		(end 147.919186 -275.983446)
		(width 0.0762)
		(layer "F.Cu")
		(net "M_G_CPU1_SB_DQS_DN<0>")
	)
	(segment
		(start 147.302728 -275.877274)
		(end 147.34286 -275.917406)
		(width 0.0762)
		(layer "F.Cu")
		(net "M_G_CPU1_SB_DQS_DN<0>")
	)
	(segment
		(start 147.834096 -275.917406)
		(end 147.900136 -275.983446)
		(width 0.0762)
		(layer "F.Cu")
		(net "M_G_CPU1_SB_DQS_DN<0>")
	)
	(segment
		(start 166.576502 -284.992826)
		(end 167.001698 -285.418022)
		(width 0.101346)
		(layer "F.Cu")
		(net "M_G_CPU1_SB_DQS_DN<0>")
	)
	(segment
		(start 165.994842 -285.310326)
		(end 166.312342 -284.992826)
		(width 0.101346)
		(layer "F.Cu")
		(net "M_G_CPU1_SB_DQS_DN<0>")
	)
	(segment
		(start 167.69715 -285.418022)
		(end 168.014396 -285.735268)
		(width 0.101346)
		(layer "F.Cu")
		(net "M_G_CPU1_SB_DQS_DN<0>")
	)
	(segment
		(start 163.566602 -285.310326)
		(end 165.994842 -285.310326)
		(width 0.101346)
		(layer "F.Cu")
		(net "M_G_CPU1_SB_DQS_DN<0>")
	)
	(segment
		(start 166.312342 -284.992826)
		(end 166.576502 -284.992826)
		(width 0.101346)
		(layer "F.Cu")
		(net "M_G_CPU1_SB_DQS_DN<0>")
	)
	(segment
		(start 162.103562 -283.525976)
		(end 162.30219 -283.525976)
		(width 0.12954)
		(layer "F.Cu")
		(net "M_G_CPU1_SB_DQS_DN<0>")
	)
	(segment
		(start 161.306764 -282.53055)
		(end 161.306764 -282.729178)
		(width 0.12954)
		(layer "F.Cu")
		(net "M_G_CPU1_SB_DQS_DN<0>")
	)
	(segment
		(start 161.306764 -282.729178)
		(end 161.060892 -282.975304)
		(width 0.12954)
		(layer "F.Cu")
		(net "M_G_CPU1_SB_DQS_DN<0>")
	)
	(segment
		(start 161.060892 -283.44114)
		(end 161.392108 -283.772356)
		(width 0.12954)
		(layer "F.Cu")
		(net "M_G_CPU1_SB_DQS_DN<0>")
	)
	(segment
		(start 168.014396 -285.735268)
		(end 168.527984 -285.735268)
		(width 0.101346)
		(layer "F.Cu")
		(net "M_G_CPU1_SB_DQS_DN<0>")
	)
	(segment
		(start 167.001698 -285.418022)
		(end 167.69715 -285.418022)
		(width 0.101346)
		(layer "F.Cu")
		(net "M_G_CPU1_SB_DQS_DN<0>")
	)
	(segment
		(start 162.61461 -283.838396)
		(end 162.61461 -284.729174)
		(width 0.12954)
		(layer "F.Cu")
		(net "M_G_CPU1_SB_DQS_DN<0>")
	)
	(segment
		(start 162.932872 -285.047436)
		(end 163.303712 -285.047436)
		(width 0.12954)
		(layer "F.Cu")
		(net "M_G_CPU1_SB_DQS_DN<0>")
	)
	(segment
		(start 147.34286 -275.917406)
		(end 147.834096 -275.917406)
		(width 0.0762)
		(layer "F.Cu")
		(net "M_G_CPU1_SB_DQS_DN<0>")
	)
	(segment
		(start 161.060892 -282.975304)
		(end 161.060892 -283.44114)
		(width 0.12954)
		(layer "F.Cu")
		(net "M_G_CPU1_SB_DQS_DN<0>")
	)
	(segment
		(start 147.919186 -275.983446)
		(end 154.75966 -275.983446)
		(width 0.12954)
		(layer "F.Cu")
		(net "M_G_CPU1_SB_DQS_DN<0>")
	)
	(segment
		(start 154.75966 -275.983446)
		(end 161.306764 -282.53055)
		(width 0.12954)
		(layer "F.Cu")
		(net "M_G_CPU1_SB_DQS_DN<0>")
	)
	(segment
		(start 161.392108 -283.772356)
		(end 161.857436 -283.772102)
		(width 0.12954)
		(layer "F.Cu")
		(net "M_G_CPU1_SB_DQS_DN<0>")
	)
	(arc
		(start 146.200876 -275.92782)
		(mid 146.276116 -275.894507)
		(end 146.356832 -275.878544)
		(width 0.0762)
		(layer "F.Cu")
		(net "M_G_CPU1_SB_DQS_DN<0>")
	)
	(arc
		(start 146.356832 -275.878544)
		(mid 146.372313 -275.877588)
		(end 146.38782 -275.877274)
		(width 0.0762)
		(layer "F.Cu")
		(net "M_G_CPU1_SB_DQS_DN<0>")
	)
	(arc
		(start 146.015456 -275.995638)
		(mid 146.111165 -275.969926)
		(end 146.200876 -275.92782)
		(width 0.0762)
		(layer "F.Cu")
		(net "M_G_CPU1_SB_DQS_DN<0>")
	)
	(arc
		(start 145.976848 -276.000972)
		(mid 145.996197 -275.998634)
		(end 146.015456 -275.995638)
		(width 0.0762)
		(layer "F.Cu")
		(net "M_G_CPU1_SB_DQS_DN<0>")
	)
	(arc
		(start 145.447766 -276.2504)
		(mid 145.691197 -276.080913)
		(end 145.976848 -276.000972)
		(width 0.0762)
		(layer "F.Cu")
		(net "M_G_CPU1_SB_DQS_DN<0>")
	)
	(segment
		(start 146.358356 -279.87117)
		(end 147.166838 -279.872186)
		(width 0.0762)
		(layer "F.Cu")
		(net "M_G_CPU1_SB_DQ<9>")
	)
	(segment
		(start 166.34587 -291.975286)
		(end 166.461186 -292.090602)
		(width 0.101346)
		(layer "F.Cu")
		(net "M_G_CPU1_SB_DQ<9>")
	)
	(segment
		(start 145.260822 -279.813004)
		(end 145.261076 -279.813004)
		(width 0.0762)
		(layer "F.Cu")
		(net "M_G_CPU1_SB_DQ<9>")
	)
	(segment
		(start 166.970202 -291.975286)
		(end 167.13327 -291.975286)
		(width 0.101346)
		(layer "F.Cu")
		(net "M_G_CPU1_SB_DQ<9>")
	)
	(segment
		(start 147.91436 -279.446482)
		(end 151.18715 -279.446482)
		(width 0.10668)
		(layer "F.Cu")
		(net "M_G_CPU1_SB_DQ<9>")
	)
	(segment
		(start 166.182802 -291.975286)
		(end 166.34587 -291.975286)
		(width 0.101346)
		(layer "F.Cu")
		(net "M_G_CPU1_SB_DQ<9>")
	)
	(segment
		(start 144.507966 -279.490424)
		(end 144.399508 -279.677114)
		(width 0.0762)
		(layer "F.Cu")
		(net "M_G_CPU1_SB_DQ<9>")
	)
	(segment
		(start 166.067486 -292.42004)
		(end 166.067486 -292.090602)
		(width 0.101346)
		(layer "F.Cu")
		(net "M_G_CPU1_SB_DQ<9>")
	)
	(segment
		(start 157.959552 -285.703772)
		(end 162.62096 -290.36518)
		(width 0.10668)
		(layer "F.Cu")
		(net "M_G_CPU1_SB_DQ<9>")
	)
	(segment
		(start 157.44444 -285.703772)
		(end 157.959552 -285.703772)
		(width 0.10668)
		(layer "F.Cu")
		(net "M_G_CPU1_SB_DQ<9>")
	)
	(segment
		(start 163.495736 -292.110414)
		(end 165.24605 -292.110414)
		(width 0.101346)
		(layer "F.Cu")
		(net "M_G_CPU1_SB_DQ<9>")
	)
	(segment
		(start 167.363902 -292.535356)
		(end 168.527984 -292.535356)
		(width 0.101346)
		(layer "F.Cu")
		(net "M_G_CPU1_SB_DQ<9>")
	)
	(segment
		(start 163.377626 -291.992304)
		(end 163.495736 -292.110414)
		(width 0.101346)
		(layer "F.Cu")
		(net "M_G_CPU1_SB_DQ<9>")
	)
	(segment
		(start 144.686528 -279.81783)
		(end 144.69491 -279.813004)
		(width 0.0762)
		(layer "F.Cu")
		(net "M_G_CPU1_SB_DQ<9>")
	)
	(segment
		(start 162.62096 -291.235638)
		(end 163.377626 -291.992304)
		(width 0.10668)
		(layer "F.Cu")
		(net "M_G_CPU1_SB_DQ<9>")
	)
	(segment
		(start 165.24605 -292.110414)
		(end 165.670992 -292.535356)
		(width 0.101346)
		(layer "F.Cu")
		(net "M_G_CPU1_SB_DQ<9>")
	)
	(segment
		(start 166.461186 -292.090602)
		(end 166.461186 -292.42004)
		(width 0.101346)
		(layer "F.Cu")
		(net "M_G_CPU1_SB_DQ<9>")
	)
	(segment
		(start 166.73957 -292.535356)
		(end 166.854886 -292.42004)
		(width 0.101346)
		(layer "F.Cu")
		(net "M_G_CPU1_SB_DQ<9>")
	)
	(segment
		(start 165.95217 -292.535356)
		(end 166.067486 -292.42004)
		(width 0.101346)
		(layer "F.Cu")
		(net "M_G_CPU1_SB_DQ<9>")
	)
	(segment
		(start 166.461186 -292.42004)
		(end 166.576502 -292.535356)
		(width 0.101346)
		(layer "F.Cu")
		(net "M_G_CPU1_SB_DQ<9>")
	)
	(segment
		(start 151.18715 -279.446482)
		(end 157.44444 -285.703772)
		(width 0.10668)
		(layer "F.Cu")
		(net "M_G_CPU1_SB_DQ<9>")
	)
	(segment
		(start 166.854886 -292.090602)
		(end 166.970202 -291.975286)
		(width 0.101346)
		(layer "F.Cu")
		(net "M_G_CPU1_SB_DQ<9>")
	)
	(segment
		(start 166.067486 -292.090602)
		(end 166.182802 -291.975286)
		(width 0.101346)
		(layer "F.Cu")
		(net "M_G_CPU1_SB_DQ<9>")
	)
	(segment
		(start 165.670992 -292.535356)
		(end 165.95217 -292.535356)
		(width 0.101346)
		(layer "F.Cu")
		(net "M_G_CPU1_SB_DQ<9>")
	)
	(segment
		(start 167.248586 -292.090602)
		(end 167.248586 -292.42004)
		(width 0.101346)
		(layer "F.Cu")
		(net "M_G_CPU1_SB_DQ<9>")
	)
	(segment
		(start 162.62096 -290.36518)
		(end 162.62096 -291.235638)
		(width 0.10668)
		(layer "F.Cu")
		(net "M_G_CPU1_SB_DQ<9>")
	)
	(segment
		(start 166.576502 -292.535356)
		(end 166.73957 -292.535356)
		(width 0.101346)
		(layer "F.Cu")
		(net "M_G_CPU1_SB_DQ<9>")
	)
	(segment
		(start 147.592542 -279.446482)
		(end 147.91436 -279.446482)
		(width 0.0762)
		(layer "F.Cu")
		(net "M_G_CPU1_SB_DQ<9>")
	)
	(segment
		(start 167.13327 -291.975286)
		(end 167.248586 -292.090602)
		(width 0.101346)
		(layer "F.Cu")
		(net "M_G_CPU1_SB_DQ<9>")
	)
	(segment
		(start 147.166838 -279.872186)
		(end 147.592542 -279.446482)
		(width 0.0762)
		(layer "F.Cu")
		(net "M_G_CPU1_SB_DQ<9>")
	)
	(segment
		(start 166.854886 -292.42004)
		(end 166.854886 -292.090602)
		(width 0.101346)
		(layer "F.Cu")
		(net "M_G_CPU1_SB_DQ<9>")
	)
	(segment
		(start 167.248586 -292.42004)
		(end 167.363902 -292.535356)
		(width 0.101346)
		(layer "F.Cu")
		(net "M_G_CPU1_SB_DQ<9>")
	)
	(arc
		(start 146.283426 -279.855168)
		(mid 146.320054 -279.867098)
		(end 146.358356 -279.87117)
		(width 0.0762)
		(layer "F.Cu")
		(net "M_G_CPU1_SB_DQ<9>")
	)
	(arc
		(start 144.399508 -279.677114)
		(mid 144.425425 -279.810156)
		(end 144.551146 -279.860756)
		(width 0.0762)
		(layer "F.Cu")
		(net "M_G_CPU1_SB_DQ<9>")
	)
	(arc
		(start 144.551146 -279.860756)
		(mid 144.6209 -279.845799)
		(end 144.686528 -279.81783)
		(width 0.0762)
		(layer "F.Cu")
		(net "M_G_CPU1_SB_DQ<9>")
	)
	(arc
		(start 144.69491 -279.813004)
		(mid 144.977866 -279.736827)
		(end 145.260822 -279.813004)
		(width 0.0762)
		(layer "F.Cu")
		(net "M_G_CPU1_SB_DQ<9>")
	)
	(arc
		(start 145.634964 -279.813004)
		(mid 145.91792 -279.736827)
		(end 146.200876 -279.813004)
		(width 0.0762)
		(layer "F.Cu")
		(net "M_G_CPU1_SB_DQ<9>")
	)
	(arc
		(start 145.261076 -279.813004)
		(mid 145.44802 -279.863328)
		(end 145.634964 -279.813004)
		(width 0.0762)
		(layer "F.Cu")
		(net "M_G_CPU1_SB_DQ<9>")
	)
	(arc
		(start 146.200876 -279.813004)
		(mid 146.24157 -279.835223)
		(end 146.283426 -279.855168)
		(width 0.0762)
		(layer "F.Cu")
		(net "M_G_CPU1_SB_DQ<9>")
	)
	(segment
		(start 156.880052 -283.661104)
		(end 156.997146 -283.778198)
		(width 0.10668)
		(layer "F.Cu")
		(net "M_G_CPU1_SB_DQ<8>")
	)
	(segment
		(start 158.103316 -284.365192)
		(end 158.103316 -284.530292)
		(width 0.10668)
		(layer "F.Cu")
		(net "M_G_CPU1_SB_DQ<8>")
	)
	(segment
		(start 146.387566 -278.926798)
		(end 147.125944 -278.926798)
		(width 0.0762)
		(layer "F.Cu")
		(net "M_G_CPU1_SB_DQ<8>")
	)
	(segment
		(start 158.573216 -285.189168)
		(end 158.573216 -285.354268)
		(width 0.10668)
		(layer "F.Cu")
		(net "M_G_CPU1_SB_DQ<8>")
	)
	(segment
		(start 158.55061 -284.812486)
		(end 158.667704 -284.92958)
		(width 0.10668)
		(layer "F.Cu")
		(net "M_G_CPU1_SB_DQ<8>")
	)
	(segment
		(start 155.751276 -282.367228)
		(end 155.751276 -282.532328)
		(width 0.10668)
		(layer "F.Cu")
		(net "M_G_CPU1_SB_DQ<8>")
	)
	(segment
		(start 159.701992 -286.317944)
		(end 159.701992 -286.483044)
		(width 0.10668)
		(layer "F.Cu")
		(net "M_G_CPU1_SB_DQ<8>")
	)
	(segment
		(start 159.232092 -285.659068)
		(end 159.137604 -285.753556)
		(width 0.10668)
		(layer "F.Cu")
		(net "M_G_CPU1_SB_DQ<8>")
	)
	(segment
		(start 157.538928 -283.800804)
		(end 157.538928 -283.965904)
		(width 0.10668)
		(layer "F.Cu")
		(net "M_G_CPU1_SB_DQ<8>")
	)
	(segment
		(start 158.125922 -284.906974)
		(end 158.291022 -284.906974)
		(width 0.10668)
		(layer "F.Cu")
		(net "M_G_CPU1_SB_DQ<8>")
	)
	(segment
		(start 157.162246 -283.778198)
		(end 157.256734 -283.68371)
		(width 0.10668)
		(layer "F.Cu")
		(net "M_G_CPU1_SB_DQ<8>")
	)
	(segment
		(start 158.008828 -284.78988)
		(end 158.125922 -284.906974)
		(width 0.10668)
		(layer "F.Cu")
		(net "M_G_CPU1_SB_DQ<8>")
	)
	(segment
		(start 147.897088 -278.762206)
		(end 152.50033 -278.762206)
		(width 0.10668)
		(layer "F.Cu")
		(net "M_G_CPU1_SB_DQ<8>")
	)
	(segment
		(start 156.127958 -282.554934)
		(end 156.293058 -282.554934)
		(width 0.10668)
		(layer "F.Cu")
		(net "M_G_CPU1_SB_DQ<8>")
	)
	(segment
		(start 157.821122 -284.248098)
		(end 157.986222 -284.248098)
		(width 0.10668)
		(layer "F.Cu")
		(net "M_G_CPU1_SB_DQ<8>")
	)
	(segment
		(start 157.44444 -284.060392)
		(end 157.44444 -284.225492)
		(width 0.10668)
		(layer "F.Cu")
		(net "M_G_CPU1_SB_DQ<8>")
	)
	(segment
		(start 156.97454 -283.236416)
		(end 156.97454 -283.401516)
		(width 0.10668)
		(layer "F.Cu")
		(net "M_G_CPU1_SB_DQ<8>")
	)
	(segment
		(start 156.997146 -283.778198)
		(end 157.162246 -283.778198)
		(width 0.10668)
		(layer "F.Cu")
		(net "M_G_CPU1_SB_DQ<8>")
	)
	(segment
		(start 167.08374 -291.260276)
		(end 167.508682 -290.835334)
		(width 0.101346)
		(layer "F.Cu")
		(net "M_G_CPU1_SB_DQ<8>")
	)
	(segment
		(start 156.597858 -283.21381)
		(end 156.692346 -283.119322)
		(width 0.10668)
		(layer "F.Cu")
		(net "M_G_CPU1_SB_DQ<8>")
	)
	(segment
		(start 158.667704 -284.92958)
		(end 158.667704 -285.09468)
		(width 0.10668)
		(layer "F.Cu")
		(net "M_G_CPU1_SB_DQ<8>")
	)
	(segment
		(start 156.432758 -283.21381)
		(end 156.597858 -283.21381)
		(width 0.10668)
		(layer "F.Cu")
		(net "M_G_CPU1_SB_DQ<8>")
	)
	(segment
		(start 156.97454 -283.401516)
		(end 156.880052 -283.496004)
		(width 0.10668)
		(layer "F.Cu")
		(net "M_G_CPU1_SB_DQ<8>")
	)
	(segment
		(start 157.538928 -283.965904)
		(end 157.44444 -284.060392)
		(width 0.10668)
		(layer "F.Cu")
		(net "M_G_CPU1_SB_DQ<8>")
	)
	(segment
		(start 159.232092 -285.493968)
		(end 159.232092 -285.659068)
		(width 0.10668)
		(layer "F.Cu")
		(net "M_G_CPU1_SB_DQ<8>")
	)
	(segment
		(start 155.86837 -282.649422)
		(end 156.03347 -282.649422)
		(width 0.10668)
		(layer "F.Cu")
		(net "M_G_CPU1_SB_DQ<8>")
	)
	(segment
		(start 158.573216 -285.354268)
		(end 158.69031 -285.471362)
		(width 0.10668)
		(layer "F.Cu")
		(net "M_G_CPU1_SB_DQ<8>")
	)
	(segment
		(start 157.726634 -284.342586)
		(end 157.821122 -284.248098)
		(width 0.10668)
		(layer "F.Cu")
		(net "M_G_CPU1_SB_DQ<8>")
	)
	(segment
		(start 145.91792 -278.680418)
		(end 145.815558 -278.856694)
		(width 0.0762)
		(layer "F.Cu")
		(net "M_G_CPU1_SB_DQ<8>")
	)
	(segment
		(start 147.290536 -278.762206)
		(end 147.897088 -278.762206)
		(width 0.0762)
		(layer "F.Cu")
		(net "M_G_CPU1_SB_DQ<8>")
	)
	(segment
		(start 163.30168 -290.082732)
		(end 163.30168 -290.952174)
		(width 0.10668)
		(layer "F.Cu")
		(net "M_G_CPU1_SB_DQ<8>")
	)
	(segment
		(start 156.293058 -282.554934)
		(end 156.410152 -282.672028)
		(width 0.10668)
		(layer "F.Cu")
		(net "M_G_CPU1_SB_DQ<8>")
	)
	(segment
		(start 156.315664 -282.931616)
		(end 156.315664 -283.096716)
		(width 0.10668)
		(layer "F.Cu")
		(net "M_G_CPU1_SB_DQ<8>")
	)
	(segment
		(start 157.256734 -283.68371)
		(end 157.421834 -283.68371)
		(width 0.10668)
		(layer "F.Cu")
		(net "M_G_CPU1_SB_DQ<8>")
	)
	(segment
		(start 159.79648 -286.223456)
		(end 159.701992 -286.317944)
		(width 0.10668)
		(layer "F.Cu")
		(net "M_G_CPU1_SB_DQ<8>")
	)
	(segment
		(start 156.880052 -283.496004)
		(end 156.880052 -283.661104)
		(width 0.10668)
		(layer "F.Cu")
		(net "M_G_CPU1_SB_DQ<8>")
	)
	(segment
		(start 155.845764 -282.27274)
		(end 155.751276 -282.367228)
		(width 0.10668)
		(layer "F.Cu")
		(net "M_G_CPU1_SB_DQ<8>")
	)
	(segment
		(start 157.44444 -284.225492)
		(end 157.561534 -284.342586)
		(width 0.10668)
		(layer "F.Cu")
		(net "M_G_CPU1_SB_DQ<8>")
	)
	(segment
		(start 158.69031 -285.471362)
		(end 158.85541 -285.471362)
		(width 0.10668)
		(layer "F.Cu")
		(net "M_G_CPU1_SB_DQ<8>")
	)
	(segment
		(start 159.79648 -286.058356)
		(end 159.79648 -286.223456)
		(width 0.10668)
		(layer "F.Cu")
		(net "M_G_CPU1_SB_DQ<8>")
	)
	(segment
		(start 158.667704 -285.09468)
		(end 158.573216 -285.189168)
		(width 0.10668)
		(layer "F.Cu")
		(net "M_G_CPU1_SB_DQ<8>")
	)
	(segment
		(start 156.410152 -282.837128)
		(end 156.315664 -282.931616)
		(width 0.10668)
		(layer "F.Cu")
		(net "M_G_CPU1_SB_DQ<8>")
	)
	(segment
		(start 158.85541 -285.471362)
		(end 158.949898 -285.376874)
		(width 0.10668)
		(layer "F.Cu")
		(net "M_G_CPU1_SB_DQ<8>")
	)
	(segment
		(start 159.679386 -285.941262)
		(end 159.79648 -286.058356)
		(width 0.10668)
		(layer "F.Cu")
		(net "M_G_CPU1_SB_DQ<8>")
	)
	(segment
		(start 157.986222 -284.248098)
		(end 158.103316 -284.365192)
		(width 0.10668)
		(layer "F.Cu")
		(net "M_G_CPU1_SB_DQ<8>")
	)
	(segment
		(start 163.609782 -291.260276)
		(end 167.08374 -291.260276)
		(width 0.101346)
		(layer "F.Cu")
		(net "M_G_CPU1_SB_DQ<8>")
	)
	(segment
		(start 159.137604 -285.918656)
		(end 159.254698 -286.03575)
		(width 0.10668)
		(layer "F.Cu")
		(net "M_G_CPU1_SB_DQ<8>")
	)
	(segment
		(start 159.419798 -286.03575)
		(end 159.514286 -285.941262)
		(width 0.10668)
		(layer "F.Cu")
		(net "M_G_CPU1_SB_DQ<8>")
	)
	(segment
		(start 158.949898 -285.376874)
		(end 159.114998 -285.376874)
		(width 0.10668)
		(layer "F.Cu")
		(net "M_G_CPU1_SB_DQ<8>")
	)
	(segment
		(start 146.096482 -279.007824)
		(end 146.104864 -279.002998)
		(width 0.0762)
		(layer "F.Cu")
		(net "M_G_CPU1_SB_DQ<8>")
	)
	(segment
		(start 156.03347 -282.649422)
		(end 156.127958 -282.554934)
		(width 0.10668)
		(layer "F.Cu")
		(net "M_G_CPU1_SB_DQ<8>")
	)
	(segment
		(start 159.514286 -285.941262)
		(end 159.679386 -285.941262)
		(width 0.10668)
		(layer "F.Cu")
		(net "M_G_CPU1_SB_DQ<8>")
	)
	(segment
		(start 159.114998 -285.376874)
		(end 159.232092 -285.493968)
		(width 0.10668)
		(layer "F.Cu")
		(net "M_G_CPU1_SB_DQ<8>")
	)
	(segment
		(start 158.291022 -284.906974)
		(end 158.38551 -284.812486)
		(width 0.10668)
		(layer "F.Cu")
		(net "M_G_CPU1_SB_DQ<8>")
	)
	(segment
		(start 155.845764 -282.10764)
		(end 155.845764 -282.27274)
		(width 0.10668)
		(layer "F.Cu")
		(net "M_G_CPU1_SB_DQ<8>")
	)
	(segment
		(start 158.38551 -284.812486)
		(end 158.55061 -284.812486)
		(width 0.10668)
		(layer "F.Cu")
		(net "M_G_CPU1_SB_DQ<8>")
	)
	(segment
		(start 156.410152 -282.672028)
		(end 156.410152 -282.837128)
		(width 0.10668)
		(layer "F.Cu")
		(net "M_G_CPU1_SB_DQ<8>")
	)
	(segment
		(start 157.561534 -284.342586)
		(end 157.726634 -284.342586)
		(width 0.10668)
		(layer "F.Cu")
		(net "M_G_CPU1_SB_DQ<8>")
	)
	(segment
		(start 158.103316 -284.530292)
		(end 158.008828 -284.62478)
		(width 0.10668)
		(layer "F.Cu")
		(net "M_G_CPU1_SB_DQ<8>")
	)
	(segment
		(start 147.125944 -278.926798)
		(end 147.290536 -278.762206)
		(width 0.0762)
		(layer "F.Cu")
		(net "M_G_CPU1_SB_DQ<8>")
	)
	(segment
		(start 152.50033 -278.762206)
		(end 155.845764 -282.10764)
		(width 0.10668)
		(layer "F.Cu")
		(net "M_G_CPU1_SB_DQ<8>")
	)
	(segment
		(start 156.315664 -283.096716)
		(end 156.432758 -283.21381)
		(width 0.10668)
		(layer "F.Cu")
		(net "M_G_CPU1_SB_DQ<8>")
	)
	(segment
		(start 158.008828 -284.62478)
		(end 158.008828 -284.78988)
		(width 0.10668)
		(layer "F.Cu")
		(net "M_G_CPU1_SB_DQ<8>")
	)
	(segment
		(start 156.857446 -283.119322)
		(end 156.97454 -283.236416)
		(width 0.10668)
		(layer "F.Cu")
		(net "M_G_CPU1_SB_DQ<8>")
	)
	(segment
		(start 163.30168 -290.952174)
		(end 163.447476 -291.09797)
		(width 0.10668)
		(layer "F.Cu")
		(net "M_G_CPU1_SB_DQ<8>")
	)
	(segment
		(start 159.254698 -286.03575)
		(end 159.419798 -286.03575)
		(width 0.10668)
		(layer "F.Cu")
		(net "M_G_CPU1_SB_DQ<8>")
	)
	(segment
		(start 159.137604 -285.753556)
		(end 159.137604 -285.918656)
		(width 0.10668)
		(layer "F.Cu")
		(net "M_G_CPU1_SB_DQ<8>")
	)
	(segment
		(start 157.421834 -283.68371)
		(end 157.538928 -283.800804)
		(width 0.10668)
		(layer "F.Cu")
		(net "M_G_CPU1_SB_DQ<8>")
	)
	(segment
		(start 156.692346 -283.119322)
		(end 156.857446 -283.119322)
		(width 0.10668)
		(layer "F.Cu")
		(net "M_G_CPU1_SB_DQ<8>")
	)
	(segment
		(start 159.701992 -286.483044)
		(end 163.30168 -290.082732)
		(width 0.10668)
		(layer "F.Cu")
		(net "M_G_CPU1_SB_DQ<8>")
	)
	(segment
		(start 167.508682 -290.835334)
		(end 168.527984 -290.835334)
		(width 0.101346)
		(layer "F.Cu")
		(net "M_G_CPU1_SB_DQ<8>")
	)
	(segment
		(start 163.447476 -291.09797)
		(end 163.609782 -291.260276)
		(width 0.101346)
		(layer "F.Cu")
		(net "M_G_CPU1_SB_DQ<8>")
	)
	(segment
		(start 155.751276 -282.532328)
		(end 155.86837 -282.649422)
		(width 0.10668)
		(layer "F.Cu")
		(net "M_G_CPU1_SB_DQ<8>")
	)
	(arc
		(start 146.340576 -278.928576)
		(mid 146.364053 -278.9272)
		(end 146.387566 -278.926798)
		(width 0.0762)
		(layer "F.Cu")
		(net "M_G_CPU1_SB_DQ<8>")
	)
	(arc
		(start 145.982436 -279.047702)
		(mid 146.041082 -279.032409)
		(end 146.096482 -279.007824)
		(width 0.0762)
		(layer "F.Cu")
		(net "M_G_CPU1_SB_DQ<8>")
	)
	(arc
		(start 145.815558 -278.856694)
		(mid 145.845187 -278.999181)
		(end 145.982436 -279.047702)
		(width 0.0762)
		(layer "F.Cu")
		(net "M_G_CPU1_SB_DQ<8>")
	)
	(arc
		(start 146.104864 -279.002998)
		(mid 146.218588 -278.952697)
		(end 146.340576 -278.928576)
		(width 0.0762)
		(layer "F.Cu")
		(net "M_G_CPU1_SB_DQ<8>")
	)
	(segment
		(start 162.014916 -287.984184)
		(end 162.014916 -288.149284)
		(width 0.10668)
		(layer "F.Cu")
		(net "M_G_CPU1_SB_DQ<7>")
	)
	(segment
		(start 161.450528 -287.584896)
		(end 161.567622 -287.70199)
		(width 0.10668)
		(layer "F.Cu")
		(net "M_G_CPU1_SB_DQ<7>")
	)
	(segment
		(start 162.29711 -288.266378)
		(end 162.40379 -288.159952)
		(width 0.10668)
		(layer "F.Cu")
		(net "M_G_CPU1_SB_DQ<7>")
	)
	(segment
		(start 146.096482 -278.353012)
		(end 146.104864 -278.357838)
		(width 0.0762)
		(layer "F.Cu")
		(net "M_G_CPU1_SB_DQ<7>")
	)
	(segment
		(start 147.560284 -278.461724)
		(end 147.748752 -278.273256)
		(width 0.0762)
		(layer "F.Cu")
		(net "M_G_CPU1_SB_DQ<7>")
	)
	(segment
		(start 162.40379 -288.159952)
		(end 162.56889 -288.159952)
		(width 0.10668)
		(layer "F.Cu")
		(net "M_G_CPU1_SB_DQ<7>")
	)
	(segment
		(start 160.99282 -286.583882)
		(end 160.99282 -286.748728)
		(width 0.10668)
		(layer "F.Cu")
		(net "M_G_CPU1_SB_DQ<7>")
	)
	(segment
		(start 161.275014 -287.031176)
		(end 161.440114 -287.031176)
		(width 0.10668)
		(layer "F.Cu")
		(net "M_G_CPU1_SB_DQ<7>")
	)
	(segment
		(start 161.732722 -287.70199)
		(end 161.839402 -287.595564)
		(width 0.10668)
		(layer "F.Cu")
		(net "M_G_CPU1_SB_DQ<7>")
	)
	(segment
		(start 162.579304 -288.713672)
		(end 162.696398 -288.830766)
		(width 0.10668)
		(layer "F.Cu")
		(net "M_G_CPU1_SB_DQ<7>")
	)
	(segment
		(start 162.56889 -288.159952)
		(end 162.685984 -288.277046)
		(width 0.10668)
		(layer "F.Cu")
		(net "M_G_CPU1_SB_DQ<7>")
	)
	(segment
		(start 146.39163 -278.461724)
		(end 147.560284 -278.461724)
		(width 0.0762)
		(layer "F.Cu")
		(net "M_G_CPU1_SB_DQ<7>")
	)
	(segment
		(start 162.014916 -288.149284)
		(end 162.13201 -288.266378)
		(width 0.10668)
		(layer "F.Cu")
		(net "M_G_CPU1_SB_DQ<7>")
	)
	(segment
		(start 162.13201 -288.266378)
		(end 162.29711 -288.266378)
		(width 0.10668)
		(layer "F.Cu")
		(net "M_G_CPU1_SB_DQ<7>")
	)
	(segment
		(start 160.99282 -286.748728)
		(end 160.88614 -286.855408)
		(width 0.10668)
		(layer "F.Cu")
		(net "M_G_CPU1_SB_DQ<7>")
	)
	(segment
		(start 163.262564 -288.853626)
		(end 163.262564 -289.388296)
		(width 0.10668)
		(layer "F.Cu")
		(net "M_G_CPU1_SB_DQ<7>")
	)
	(segment
		(start 160.88614 -286.855408)
		(end 160.88614 -287.020508)
		(width 0.10668)
		(layer "F.Cu")
		(net "M_G_CPU1_SB_DQ<7>")
	)
	(segment
		(start 162.579304 -288.548572)
		(end 162.579304 -288.713672)
		(width 0.10668)
		(layer "F.Cu")
		(net "M_G_CPU1_SB_DQ<7>")
	)
	(segment
		(start 160.321752 -286.45612)
		(end 160.438846 -286.573214)
		(width 0.10668)
		(layer "F.Cu")
		(net "M_G_CPU1_SB_DQ<7>")
	)
	(segment
		(start 161.168334 -287.137602)
		(end 161.275014 -287.031176)
		(width 0.10668)
		(layer "F.Cu")
		(net "M_G_CPU1_SB_DQ<7>")
	)
	(segment
		(start 161.557208 -287.14827)
		(end 161.557208 -287.313116)
		(width 0.10668)
		(layer "F.Cu")
		(net "M_G_CPU1_SB_DQ<7>")
	)
	(segment
		(start 162.121596 -287.877504)
		(end 162.014916 -287.984184)
		(width 0.10668)
		(layer "F.Cu")
		(net "M_G_CPU1_SB_DQ<7>")
	)
	(segment
		(start 159.759142 -285.341314)
		(end 159.759142 -285.350204)
		(width 0.10668)
		(layer "F.Cu")
		(net "M_G_CPU1_SB_DQ<7>")
	)
	(segment
		(start 161.003234 -287.137602)
		(end 161.168334 -287.137602)
		(width 0.10668)
		(layer "F.Cu")
		(net "M_G_CPU1_SB_DQ<7>")
	)
	(segment
		(start 161.440114 -287.031176)
		(end 161.557208 -287.14827)
		(width 0.10668)
		(layer "F.Cu")
		(net "M_G_CPU1_SB_DQ<7>")
	)
	(segment
		(start 163.859718 -289.98545)
		(end 164.427916 -289.98545)
		(width 0.10668)
		(layer "F.Cu")
		(net "M_G_CPU1_SB_DQ<7>")
	)
	(segment
		(start 152.691084 -278.273256)
		(end 159.759142 -285.341314)
		(width 0.10668)
		(layer "F.Cu")
		(net "M_G_CPU1_SB_DQ<7>")
	)
	(segment
		(start 160.875726 -286.466788)
		(end 160.99282 -286.583882)
		(width 0.10668)
		(layer "F.Cu")
		(net "M_G_CPU1_SB_DQ<7>")
	)
	(segment
		(start 160.428432 -286.019494)
		(end 160.428432 -286.18434)
		(width 0.10668)
		(layer "F.Cu")
		(net "M_G_CPU1_SB_DQ<7>")
	)
	(segment
		(start 161.450528 -287.419796)
		(end 161.450528 -287.584896)
		(width 0.10668)
		(layer "F.Cu")
		(net "M_G_CPU1_SB_DQ<7>")
	)
	(segment
		(start 162.685984 -288.277046)
		(end 162.685984 -288.441892)
		(width 0.10668)
		(layer "F.Cu")
		(net "M_G_CPU1_SB_DQ<7>")
	)
	(segment
		(start 161.557208 -287.313116)
		(end 161.450528 -287.419796)
		(width 0.10668)
		(layer "F.Cu")
		(net "M_G_CPU1_SB_DQ<7>")
	)
	(segment
		(start 163.133278 -288.72434)
		(end 163.262564 -288.853626)
		(width 0.10668)
		(layer "F.Cu")
		(net "M_G_CPU1_SB_DQ<7>")
	)
	(segment
		(start 147.748752 -278.273256)
		(end 147.997418 -278.273256)
		(width 0.0762)
		(layer "F.Cu")
		(net "M_G_CPU1_SB_DQ<7>")
	)
	(segment
		(start 160.88614 -287.020508)
		(end 161.003234 -287.137602)
		(width 0.10668)
		(layer "F.Cu")
		(net "M_G_CPU1_SB_DQ<7>")
	)
	(segment
		(start 163.262564 -289.388296)
		(end 163.859718 -289.98545)
		(width 0.10668)
		(layer "F.Cu")
		(net "M_G_CPU1_SB_DQ<7>")
	)
	(segment
		(start 160.710626 -286.466788)
		(end 160.875726 -286.466788)
		(width 0.10668)
		(layer "F.Cu")
		(net "M_G_CPU1_SB_DQ<7>")
	)
	(segment
		(start 159.759142 -285.350204)
		(end 160.428432 -286.019494)
		(width 0.10668)
		(layer "F.Cu")
		(net "M_G_CPU1_SB_DQ<7>")
	)
	(segment
		(start 162.861498 -288.830766)
		(end 162.968178 -288.72434)
		(width 0.10668)
		(layer "F.Cu")
		(net "M_G_CPU1_SB_DQ<7>")
	)
	(segment
		(start 162.121596 -287.712658)
		(end 162.121596 -287.877504)
		(width 0.10668)
		(layer "F.Cu")
		(net "M_G_CPU1_SB_DQ<7>")
	)
	(segment
		(start 162.696398 -288.830766)
		(end 162.861498 -288.830766)
		(width 0.10668)
		(layer "F.Cu")
		(net "M_G_CPU1_SB_DQ<7>")
	)
	(segment
		(start 162.685984 -288.441892)
		(end 162.579304 -288.548572)
		(width 0.10668)
		(layer "F.Cu")
		(net "M_G_CPU1_SB_DQ<7>")
	)
	(segment
		(start 160.438846 -286.573214)
		(end 160.603946 -286.573214)
		(width 0.10668)
		(layer "F.Cu")
		(net "M_G_CPU1_SB_DQ<7>")
	)
	(segment
		(start 160.603946 -286.573214)
		(end 160.710626 -286.466788)
		(width 0.10668)
		(layer "F.Cu")
		(net "M_G_CPU1_SB_DQ<7>")
	)
	(segment
		(start 161.567622 -287.70199)
		(end 161.732722 -287.70199)
		(width 0.10668)
		(layer "F.Cu")
		(net "M_G_CPU1_SB_DQ<7>")
	)
	(segment
		(start 161.839402 -287.595564)
		(end 162.004502 -287.595564)
		(width 0.10668)
		(layer "F.Cu")
		(net "M_G_CPU1_SB_DQ<7>")
	)
	(segment
		(start 162.004502 -287.595564)
		(end 162.121596 -287.712658)
		(width 0.10668)
		(layer "F.Cu")
		(net "M_G_CPU1_SB_DQ<7>")
	)
	(segment
		(start 160.428432 -286.18434)
		(end 160.321752 -286.29102)
		(width 0.10668)
		(layer "F.Cu")
		(net "M_G_CPU1_SB_DQ<7>")
	)
	(segment
		(start 160.321752 -286.29102)
		(end 160.321752 -286.45612)
		(width 0.10668)
		(layer "F.Cu")
		(net "M_G_CPU1_SB_DQ<7>")
	)
	(segment
		(start 147.997418 -278.273256)
		(end 152.691084 -278.273256)
		(width 0.10668)
		(layer "F.Cu")
		(net "M_G_CPU1_SB_DQ<7>")
	)
	(segment
		(start 162.968178 -288.72434)
		(end 163.133278 -288.72434)
		(width 0.10668)
		(layer "F.Cu")
		(net "M_G_CPU1_SB_DQ<7>")
	)
	(arc
		(start 144.037812 -278.680418)
		(mid 144.233161 -278.496599)
		(end 144.493996 -278.434038)
		(width 0.0762)
		(layer "F.Cu")
		(net "M_G_CPU1_SB_DQ<7>")
	)
	(arc
		(start 145.730722 -278.357838)
		(mid 145.912973 -278.307488)
		(end 146.096482 -278.353012)
		(width 0.0762)
		(layer "F.Cu")
		(net "M_G_CPU1_SB_DQ<7>")
	)
	(arc
		(start 144.790922 -278.357838)
		(mid 144.977866 -278.307583)
		(end 145.16481 -278.357838)
		(width 0.0762)
		(layer "F.Cu")
		(net "M_G_CPU1_SB_DQ<7>")
	)
	(arc
		(start 146.315938 -278.450548)
		(mid 146.353364 -278.458987)
		(end 146.39163 -278.461724)
		(width 0.0762)
		(layer "F.Cu")
		(net "M_G_CPU1_SB_DQ<7>")
	)
	(arc
		(start 146.104864 -278.357838)
		(mid 146.207758 -278.41021)
		(end 146.315938 -278.450548)
		(width 0.0762)
		(layer "F.Cu")
		(net "M_G_CPU1_SB_DQ<7>")
	)
	(arc
		(start 144.493996 -278.434038)
		(mid 144.647745 -278.416529)
		(end 144.790922 -278.357838)
		(width 0.0762)
		(layer "F.Cu")
		(net "M_G_CPU1_SB_DQ<7>")
	)
	(arc
		(start 145.16481 -278.357838)
		(mid 145.447766 -278.434015)
		(end 145.730722 -278.357838)
		(width 0.0762)
		(layer "F.Cu")
		(net "M_G_CPU1_SB_DQ<7>")
	)
	(segment
		(start 153.796238 -278.172926)
		(end 153.796238 -278.338026)
		(width 0.10668)
		(layer "F.Cu")
		(net "M_G_CPU1_SB_DQ<6>")
	)
	(segment
		(start 155.28544 -278.941276)
		(end 154.925014 -279.301702)
		(width 0.10668)
		(layer "F.Cu")
		(net "M_G_CPU1_SB_DQ<6>")
	)
	(segment
		(start 155.489402 -279.86609)
		(end 155.489402 -280.03119)
		(width 0.10668)
		(layer "F.Cu")
		(net "M_G_CPU1_SB_DQ<6>")
	)
	(segment
		(start 154.47772 -279.019508)
		(end 154.64282 -279.019508)
		(width 0.10668)
		(layer "F.Cu")
		(net "M_G_CPU1_SB_DQ<6>")
	)
	(segment
		(start 154.156664 -277.8125)
		(end 153.796238 -278.172926)
		(width 0.10668)
		(layer "F.Cu")
		(net "M_G_CPU1_SB_DQ<6>")
	)
	(segment
		(start 154.078432 -278.45512)
		(end 154.438858 -278.094694)
		(width 0.10668)
		(layer "F.Cu")
		(net "M_G_CPU1_SB_DQ<6>")
	)
	(segment
		(start 155.489402 -280.03119)
		(end 158.013654 -282.555442)
		(width 0.10668)
		(layer "F.Cu")
		(net "M_G_CPU1_SB_DQ<6>")
	)
	(segment
		(start 147.67179 -277.497286)
		(end 147.68703 -277.512526)
		(width 0.0762)
		(layer "F.Cu")
		(net "M_G_CPU1_SB_DQ<6>")
	)
	(segment
		(start 154.360626 -278.902414)
		(end 154.47772 -279.019508)
		(width 0.10668)
		(layer "F.Cu")
		(net "M_G_CPU1_SB_DQ<6>")
	)
	(segment
		(start 153.514044 -277.890732)
		(end 153.87447 -277.530306)
		(width 0.10668)
		(layer "F.Cu")
		(net "M_G_CPU1_SB_DQ<6>")
	)
	(segment
		(start 155.763468 -279.592024)
		(end 155.489402 -279.86609)
		(width 0.10668)
		(layer "F.Cu")
		(net "M_G_CPU1_SB_DQ<6>")
	)
	(segment
		(start 154.925014 -279.466802)
		(end 155.042108 -279.583896)
		(width 0.10668)
		(layer "F.Cu")
		(net "M_G_CPU1_SB_DQ<6>")
	)
	(segment
		(start 154.64282 -279.019508)
		(end 155.003246 -278.659082)
		(width 0.10668)
		(layer "F.Cu")
		(net "M_G_CPU1_SB_DQ<6>")
	)
	(segment
		(start 154.03957 -277.530306)
		(end 154.156664 -277.6474)
		(width 0.10668)
		(layer "F.Cu")
		(net "M_G_CPU1_SB_DQ<6>")
	)
	(segment
		(start 146.38782 -277.497286)
		(end 147.67179 -277.497286)
		(width 0.0762)
		(layer "F.Cu")
		(net "M_G_CPU1_SB_DQ<6>")
	)
	(segment
		(start 155.207208 -279.583896)
		(end 155.481274 -279.30983)
		(width 0.10668)
		(layer "F.Cu")
		(net "M_G_CPU1_SB_DQ<6>")
	)
	(segment
		(start 153.87447 -277.530306)
		(end 154.03957 -277.530306)
		(width 0.10668)
		(layer "F.Cu")
		(net "M_G_CPU1_SB_DQ<6>")
	)
	(segment
		(start 155.042108 -279.583896)
		(end 155.207208 -279.583896)
		(width 0.10668)
		(layer "F.Cu")
		(net "M_G_CPU1_SB_DQ<6>")
	)
	(segment
		(start 154.360626 -278.737314)
		(end 154.360626 -278.902414)
		(width 0.10668)
		(layer "F.Cu")
		(net "M_G_CPU1_SB_DQ<6>")
	)
	(segment
		(start 154.721052 -278.376888)
		(end 154.360626 -278.737314)
		(width 0.10668)
		(layer "F.Cu")
		(net "M_G_CPU1_SB_DQ<6>")
	)
	(segment
		(start 154.925014 -279.301702)
		(end 154.925014 -279.466802)
		(width 0.10668)
		(layer "F.Cu")
		(net "M_G_CPU1_SB_DQ<6>")
	)
	(segment
		(start 163.741608 -288.285428)
		(end 164.427916 -288.285428)
		(width 0.10668)
		(layer "F.Cu")
		(net "M_G_CPU1_SB_DQ<6>")
	)
	(segment
		(start 155.763468 -279.426924)
		(end 155.763468 -279.592024)
		(width 0.10668)
		(layer "F.Cu")
		(net "M_G_CPU1_SB_DQ<6>")
	)
	(segment
		(start 155.481274 -279.30983)
		(end 155.646374 -279.30983)
		(width 0.10668)
		(layer "F.Cu")
		(net "M_G_CPU1_SB_DQ<6>")
	)
	(segment
		(start 155.28544 -278.776176)
		(end 155.28544 -278.941276)
		(width 0.10668)
		(layer "F.Cu")
		(net "M_G_CPU1_SB_DQ<6>")
	)
	(segment
		(start 154.156664 -277.6474)
		(end 154.156664 -277.8125)
		(width 0.10668)
		(layer "F.Cu")
		(net "M_G_CPU1_SB_DQ<6>")
	)
	(segment
		(start 154.721052 -278.211788)
		(end 154.721052 -278.376888)
		(width 0.10668)
		(layer "F.Cu")
		(net "M_G_CPU1_SB_DQ<6>")
	)
	(segment
		(start 153.348944 -277.890732)
		(end 153.514044 -277.890732)
		(width 0.10668)
		(layer "F.Cu")
		(net "M_G_CPU1_SB_DQ<6>")
	)
	(segment
		(start 152.970738 -277.512526)
		(end 153.348944 -277.890732)
		(width 0.10668)
		(layer "F.Cu")
		(net "M_G_CPU1_SB_DQ<6>")
	)
	(segment
		(start 154.603958 -278.094694)
		(end 154.721052 -278.211788)
		(width 0.10668)
		(layer "F.Cu")
		(net "M_G_CPU1_SB_DQ<6>")
	)
	(segment
		(start 147.68703 -277.512526)
		(end 152.970738 -277.512526)
		(width 0.10668)
		(layer "F.Cu")
		(net "M_G_CPU1_SB_DQ<6>")
	)
	(segment
		(start 155.646374 -279.30983)
		(end 155.763468 -279.426924)
		(width 0.10668)
		(layer "F.Cu")
		(net "M_G_CPU1_SB_DQ<6>")
	)
	(segment
		(start 153.913332 -278.45512)
		(end 154.078432 -278.45512)
		(width 0.10668)
		(layer "F.Cu")
		(net "M_G_CPU1_SB_DQ<6>")
	)
	(segment
		(start 155.003246 -278.659082)
		(end 155.168346 -278.659082)
		(width 0.10668)
		(layer "F.Cu")
		(net "M_G_CPU1_SB_DQ<6>")
	)
	(segment
		(start 158.013654 -282.557474)
		(end 163.741608 -288.285428)
		(width 0.10668)
		(layer "F.Cu")
		(net "M_G_CPU1_SB_DQ<6>")
	)
	(segment
		(start 158.013654 -282.555442)
		(end 158.013654 -282.557474)
		(width 0.10668)
		(layer "F.Cu")
		(net "M_G_CPU1_SB_DQ<6>")
	)
	(segment
		(start 155.168346 -278.659082)
		(end 155.28544 -278.776176)
		(width 0.10668)
		(layer "F.Cu")
		(net "M_G_CPU1_SB_DQ<6>")
	)
	(segment
		(start 154.438858 -278.094694)
		(end 154.603958 -278.094694)
		(width 0.10668)
		(layer "F.Cu")
		(net "M_G_CPU1_SB_DQ<6>")
	)
	(segment
		(start 153.796238 -278.338026)
		(end 153.913332 -278.45512)
		(width 0.10668)
		(layer "F.Cu")
		(net "M_G_CPU1_SB_DQ<6>")
	)
	(arc
		(start 145.447766 -277.870412)
		(mid 145.691197 -277.700925)
		(end 145.976848 -277.620984)
		(width 0.0762)
		(layer "F.Cu")
		(net "M_G_CPU1_SB_DQ<6>")
	)
	(arc
		(start 146.356832 -277.498556)
		(mid 146.372313 -277.4976)
		(end 146.38782 -277.497286)
		(width 0.0762)
		(layer "F.Cu")
		(net "M_G_CPU1_SB_DQ<6>")
	)
	(arc
		(start 146.200876 -277.547832)
		(mid 146.276116 -277.514519)
		(end 146.356832 -277.498556)
		(width 0.0762)
		(layer "F.Cu")
		(net "M_G_CPU1_SB_DQ<6>")
	)
	(arc
		(start 146.015456 -277.61565)
		(mid 146.111165 -277.589938)
		(end 146.200876 -277.547832)
		(width 0.0762)
		(layer "F.Cu")
		(net "M_G_CPU1_SB_DQ<6>")
	)
	(arc
		(start 145.976848 -277.620984)
		(mid 145.996197 -277.618646)
		(end 146.015456 -277.61565)
		(width 0.0762)
		(layer "F.Cu")
		(net "M_G_CPU1_SB_DQ<6>")
	)
	(segment
		(start 147.87118 -277.913846)
		(end 152.813258 -277.913846)
		(width 0.10668)
		(layer "F.Cu")
		(net "M_G_CPU1_SB_DQ<5>")
	)
	(segment
		(start 144.686528 -278.197818)
		(end 144.69491 -278.192992)
		(width 0.0762)
		(layer "F.Cu")
		(net "M_G_CPU1_SB_DQ<5>")
	)
	(segment
		(start 146.358356 -278.251158)
		(end 147.056094 -278.252174)
		(width 0.0762)
		(layer "F.Cu")
		(net "M_G_CPU1_SB_DQ<5>")
	)
	(segment
		(start 165.296596 -288.73069)
		(end 167.330628 -289.135312)
		(width 0.101346)
		(layer "F.Cu")
		(net "M_G_CPU1_SB_DQ<5>")
	)
	(segment
		(start 152.813258 -277.913846)
		(end 163.442142 -288.54273)
		(width 0.10668)
		(layer "F.Cu")
		(net "M_G_CPU1_SB_DQ<5>")
	)
	(segment
		(start 165.194234 -288.71037)
		(end 165.296596 -288.73069)
		(width 0.101346)
		(layer "F.Cu")
		(net "M_G_CPU1_SB_DQ<5>")
	)
	(segment
		(start 163.442142 -288.54273)
		(end 163.609782 -288.71037)
		(width 0.101346)
		(layer "F.Cu")
		(net "M_G_CPU1_SB_DQ<5>")
	)
	(segment
		(start 144.507966 -277.870412)
		(end 144.399508 -278.057102)
		(width 0.0762)
		(layer "F.Cu")
		(net "M_G_CPU1_SB_DQ<5>")
	)
	(segment
		(start 145.260822 -278.192992)
		(end 145.261076 -278.192992)
		(width 0.0762)
		(layer "F.Cu")
		(net "M_G_CPU1_SB_DQ<5>")
	)
	(segment
		(start 167.330628 -289.135312)
		(end 168.527984 -289.135312)
		(width 0.101346)
		(layer "F.Cu")
		(net "M_G_CPU1_SB_DQ<5>")
	)
	(segment
		(start 147.056094 -278.252174)
		(end 147.87118 -277.913846)
		(width 0.0762)
		(layer "F.Cu")
		(net "M_G_CPU1_SB_DQ<5>")
	)
	(segment
		(start 163.609782 -288.71037)
		(end 165.194234 -288.71037)
		(width 0.101346)
		(layer "F.Cu")
		(net "M_G_CPU1_SB_DQ<5>")
	)
	(arc
		(start 144.551146 -278.240744)
		(mid 144.6209 -278.225787)
		(end 144.686528 -278.197818)
		(width 0.0762)
		(layer "F.Cu")
		(net "M_G_CPU1_SB_DQ<5>")
	)
	(arc
		(start 144.69491 -278.192992)
		(mid 144.977866 -278.116815)
		(end 145.260822 -278.192992)
		(width 0.0762)
		(layer "F.Cu")
		(net "M_G_CPU1_SB_DQ<5>")
	)
	(arc
		(start 144.399508 -278.057102)
		(mid 144.425425 -278.190144)
		(end 144.551146 -278.240744)
		(width 0.0762)
		(layer "F.Cu")
		(net "M_G_CPU1_SB_DQ<5>")
	)
	(arc
		(start 145.261076 -278.192992)
		(mid 145.44802 -278.243316)
		(end 145.634964 -278.192992)
		(width 0.0762)
		(layer "F.Cu")
		(net "M_G_CPU1_SB_DQ<5>")
	)
	(arc
		(start 145.634964 -278.192992)
		(mid 145.91792 -278.116815)
		(end 146.200876 -278.192992)
		(width 0.0762)
		(layer "F.Cu")
		(net "M_G_CPU1_SB_DQ<5>")
	)
	(arc
		(start 146.283426 -278.235156)
		(mid 146.320054 -278.247086)
		(end 146.358356 -278.251158)
		(width 0.0762)
		(layer "F.Cu")
		(net "M_G_CPU1_SB_DQ<5>")
	)
	(arc
		(start 146.200876 -278.192992)
		(mid 146.24157 -278.215211)
		(end 146.283426 -278.235156)
		(width 0.0762)
		(layer "F.Cu")
		(net "M_G_CPU1_SB_DQ<5>")
	)
	(segment
		(start 146.096482 -277.387812)
		(end 146.104864 -277.382986)
		(width 0.0762)
		(layer "F.Cu")
		(net "M_G_CPU1_SB_DQ<4>")
	)
	(segment
		(start 156.103828 -280.163778)
		(end 162.950398 -287.010348)
		(width 0.10668)
		(layer "F.Cu")
		(net "M_G_CPU1_SB_DQ<4>")
	)
	(segment
		(start 165.989254 -287.010348)
		(end 166.414196 -287.43529)
		(width 0.101346)
		(layer "F.Cu")
		(net "M_G_CPU1_SB_DQ<4>")
	)
	(segment
		(start 154.261312 -277.14829)
		(end 156.103828 -278.990806)
		(width 0.10668)
		(layer "F.Cu")
		(net "M_G_CPU1_SB_DQ<4>")
	)
	(segment
		(start 146.387566 -277.306786)
		(end 147.221194 -277.306786)
		(width 0.0762)
		(layer "F.Cu")
		(net "M_G_CPU1_SB_DQ<4>")
	)
	(segment
		(start 162.950398 -287.010348)
		(end 163.377626 -287.010348)
		(width 0.10668)
		(layer "F.Cu")
		(net "M_G_CPU1_SB_DQ<4>")
	)
	(segment
		(start 166.414196 -287.43529)
		(end 168.527984 -287.43529)
		(width 0.101346)
		(layer "F.Cu")
		(net "M_G_CPU1_SB_DQ<4>")
	)
	(segment
		(start 147.974304 -277.14829)
		(end 154.261312 -277.14829)
		(width 0.10668)
		(layer "F.Cu")
		(net "M_G_CPU1_SB_DQ<4>")
	)
	(segment
		(start 163.377626 -287.010348)
		(end 165.989254 -287.010348)
		(width 0.101346)
		(layer "F.Cu")
		(net "M_G_CPU1_SB_DQ<4>")
	)
	(segment
		(start 147.221194 -277.306786)
		(end 147.37969 -277.14829)
		(width 0.0762)
		(layer "F.Cu")
		(net "M_G_CPU1_SB_DQ<4>")
	)
	(segment
		(start 145.91792 -277.060406)
		(end 145.815558 -277.236682)
		(width 0.0762)
		(layer "F.Cu")
		(net "M_G_CPU1_SB_DQ<4>")
	)
	(segment
		(start 147.37969 -277.14829)
		(end 147.974304 -277.14829)
		(width 0.0762)
		(layer "F.Cu")
		(net "M_G_CPU1_SB_DQ<4>")
	)
	(segment
		(start 156.103828 -278.990806)
		(end 156.103828 -280.163778)
		(width 0.10668)
		(layer "F.Cu")
		(net "M_G_CPU1_SB_DQ<4>")
	)
	(arc
		(start 146.104864 -277.382986)
		(mid 146.218588 -277.332685)
		(end 146.340576 -277.308564)
		(width 0.0762)
		(layer "F.Cu")
		(net "M_G_CPU1_SB_DQ<4>")
	)
	(arc
		(start 145.982436 -277.42769)
		(mid 146.041082 -277.412397)
		(end 146.096482 -277.387812)
		(width 0.0762)
		(layer "F.Cu")
		(net "M_G_CPU1_SB_DQ<4>")
	)
	(arc
		(start 145.815558 -277.236682)
		(mid 145.845187 -277.379169)
		(end 145.982436 -277.42769)
		(width 0.0762)
		(layer "F.Cu")
		(net "M_G_CPU1_SB_DQ<4>")
	)
	(arc
		(start 146.340576 -277.308564)
		(mid 146.364053 -277.307188)
		(end 146.387566 -277.306786)
		(width 0.0762)
		(layer "F.Cu")
		(net "M_G_CPU1_SB_DQ<4>")
	)
	(segment
		(start 160.048448 -280.070306)
		(end 160.048448 -280.235406)
		(width 0.10668)
		(layer "F.Cu")
		(net "M_G_CPU1_SB_DQ<3>")
	)
	(segment
		(start 160.325308 -279.628092)
		(end 160.325308 -279.793192)
		(width 0.10668)
		(layer "F.Cu")
		(net "M_G_CPU1_SB_DQ<3>")
	)
	(segment
		(start 160.208214 -279.510998)
		(end 160.325308 -279.628092)
		(width 0.10668)
		(layer "F.Cu")
		(net "M_G_CPU1_SB_DQ<3>")
	)
	(segment
		(start 160.612836 -280.799794)
		(end 160.72993 -280.916888)
		(width 0.10668)
		(layer "F.Cu")
		(net "M_G_CPU1_SB_DQ<3>")
	)
	(segment
		(start 160.165542 -280.3525)
		(end 160.330642 -280.3525)
		(width 0.10668)
		(layer "F.Cu")
		(net "M_G_CPU1_SB_DQ<3>")
	)
	(segment
		(start 160.772602 -280.075386)
		(end 160.889696 -280.19248)
		(width 0.10668)
		(layer "F.Cu")
		(net "M_G_CPU1_SB_DQ<3>")
	)
	(segment
		(start 147.940014 -275.247354)
		(end 155.060396 -275.247354)
		(width 0.10668)
		(layer "F.Cu")
		(net "M_G_CPU1_SB_DQ<3>")
	)
	(segment
		(start 161.33699 -280.639774)
		(end 161.454084 -280.756868)
		(width 0.10668)
		(layer "F.Cu")
		(net "M_G_CPU1_SB_DQ<3>")
	)
	(segment
		(start 162.018472 -281.321256)
		(end 162.018472 -281.486356)
		(width 0.10668)
		(layer "F.Cu")
		(net "M_G_CPU1_SB_DQ<3>")
	)
	(segment
		(start 146.562572 -275.247354)
		(end 147.940014 -275.247354)
		(width 0.0762)
		(layer "F.Cu")
		(net "M_G_CPU1_SB_DQ<3>")
	)
	(segment
		(start 160.325308 -279.793192)
		(end 160.048448 -280.070306)
		(width 0.10668)
		(layer "F.Cu")
		(net "M_G_CPU1_SB_DQ<3>")
	)
	(segment
		(start 159.201866 -279.223724)
		(end 159.478726 -278.94661)
		(width 0.10668)
		(layer "F.Cu")
		(net "M_G_CPU1_SB_DQ<3>")
	)
	(segment
		(start 161.177224 -281.199082)
		(end 161.177224 -281.364182)
		(width 0.10668)
		(layer "F.Cu")
		(net "M_G_CPU1_SB_DQ<3>")
	)
	(segment
		(start 160.889696 -280.19248)
		(end 160.889696 -280.35758)
		(width 0.10668)
		(layer "F.Cu")
		(net "M_G_CPU1_SB_DQ<3>")
	)
	(segment
		(start 161.901378 -281.204162)
		(end 162.018472 -281.321256)
		(width 0.10668)
		(layer "F.Cu")
		(net "M_G_CPU1_SB_DQ<3>")
	)
	(segment
		(start 159.601154 -279.788112)
		(end 159.766254 -279.788112)
		(width 0.10668)
		(layer "F.Cu")
		(net "M_G_CPU1_SB_DQ<3>")
	)
	(segment
		(start 160.048448 -280.235406)
		(end 160.165542 -280.3525)
		(width 0.10668)
		(layer "F.Cu")
		(net "M_G_CPU1_SB_DQ<3>")
	)
	(segment
		(start 159.766254 -279.788112)
		(end 160.043114 -279.510998)
		(width 0.10668)
		(layer "F.Cu")
		(net "M_G_CPU1_SB_DQ<3>")
	)
	(segment
		(start 161.294318 -281.481276)
		(end 161.459418 -281.481276)
		(width 0.10668)
		(layer "F.Cu")
		(net "M_G_CPU1_SB_DQ<3>")
	)
	(segment
		(start 160.607502 -280.075386)
		(end 160.772602 -280.075386)
		(width 0.10668)
		(layer "F.Cu")
		(net "M_G_CPU1_SB_DQ<3>")
	)
	(segment
		(start 161.177224 -281.364182)
		(end 161.294318 -281.481276)
		(width 0.10668)
		(layer "F.Cu")
		(net "M_G_CPU1_SB_DQ<3>")
	)
	(segment
		(start 159.643826 -278.94661)
		(end 159.76092 -279.063704)
		(width 0.10668)
		(layer "F.Cu")
		(net "M_G_CPU1_SB_DQ<3>")
	)
	(segment
		(start 155.060396 -275.247354)
		(end 159.036766 -279.223724)
		(width 0.10668)
		(layer "F.Cu")
		(net "M_G_CPU1_SB_DQ<3>")
	)
	(segment
		(start 160.612836 -280.634694)
		(end 160.612836 -280.799794)
		(width 0.10668)
		(layer "F.Cu")
		(net "M_G_CPU1_SB_DQ<3>")
	)
	(segment
		(start 161.736278 -281.204162)
		(end 161.901378 -281.204162)
		(width 0.10668)
		(layer "F.Cu")
		(net "M_G_CPU1_SB_DQ<3>")
	)
	(segment
		(start 159.48406 -279.505918)
		(end 159.48406 -279.671018)
		(width 0.10668)
		(layer "F.Cu")
		(net "M_G_CPU1_SB_DQ<3>")
	)
	(segment
		(start 160.043114 -279.510998)
		(end 160.208214 -279.510998)
		(width 0.10668)
		(layer "F.Cu")
		(net "M_G_CPU1_SB_DQ<3>")
	)
	(segment
		(start 160.330642 -280.3525)
		(end 160.607502 -280.075386)
		(width 0.10668)
		(layer "F.Cu")
		(net "M_G_CPU1_SB_DQ<3>")
	)
	(segment
		(start 163.848288 -284.035246)
		(end 164.427916 -284.035246)
		(width 0.10668)
		(layer "F.Cu")
		(net "M_G_CPU1_SB_DQ<3>")
	)
	(segment
		(start 159.76092 -279.228804)
		(end 159.48406 -279.505918)
		(width 0.10668)
		(layer "F.Cu")
		(net "M_G_CPU1_SB_DQ<3>")
	)
	(segment
		(start 162.018472 -281.486356)
		(end 161.741612 -281.76347)
		(width 0.10668)
		(layer "F.Cu")
		(net "M_G_CPU1_SB_DQ<3>")
	)
	(segment
		(start 159.478726 -278.94661)
		(end 159.643826 -278.94661)
		(width 0.10668)
		(layer "F.Cu")
		(net "M_G_CPU1_SB_DQ<3>")
	)
	(segment
		(start 160.889696 -280.35758)
		(end 160.612836 -280.634694)
		(width 0.10668)
		(layer "F.Cu")
		(net "M_G_CPU1_SB_DQ<3>")
	)
	(segment
		(start 146.096482 -275.112988)
		(end 146.104864 -275.117814)
		(width 0.0762)
		(layer "F.Cu")
		(net "M_G_CPU1_SB_DQ<3>")
	)
	(segment
		(start 159.76092 -279.063704)
		(end 159.76092 -279.228804)
		(width 0.10668)
		(layer "F.Cu")
		(net "M_G_CPU1_SB_DQ<3>")
	)
	(segment
		(start 161.459418 -281.481276)
		(end 161.736278 -281.204162)
		(width 0.10668)
		(layer "F.Cu")
		(net "M_G_CPU1_SB_DQ<3>")
	)
	(segment
		(start 161.741612 -281.76347)
		(end 161.741612 -281.92857)
		(width 0.10668)
		(layer "F.Cu")
		(net "M_G_CPU1_SB_DQ<3>")
	)
	(segment
		(start 160.89503 -280.916888)
		(end 161.17189 -280.639774)
		(width 0.10668)
		(layer "F.Cu")
		(net "M_G_CPU1_SB_DQ<3>")
	)
	(segment
		(start 161.17189 -280.639774)
		(end 161.33699 -280.639774)
		(width 0.10668)
		(layer "F.Cu")
		(net "M_G_CPU1_SB_DQ<3>")
	)
	(segment
		(start 161.741612 -281.92857)
		(end 163.848288 -284.035246)
		(width 0.10668)
		(layer "F.Cu")
		(net "M_G_CPU1_SB_DQ<3>")
	)
	(segment
		(start 159.48406 -279.671018)
		(end 159.601154 -279.788112)
		(width 0.10668)
		(layer "F.Cu")
		(net "M_G_CPU1_SB_DQ<3>")
	)
	(segment
		(start 161.454084 -280.756868)
		(end 161.454084 -280.921968)
		(width 0.10668)
		(layer "F.Cu")
		(net "M_G_CPU1_SB_DQ<3>")
	)
	(segment
		(start 161.454084 -280.921968)
		(end 161.177224 -281.199082)
		(width 0.10668)
		(layer "F.Cu")
		(net "M_G_CPU1_SB_DQ<3>")
	)
	(segment
		(start 159.036766 -279.223724)
		(end 159.201866 -279.223724)
		(width 0.10668)
		(layer "F.Cu")
		(net "M_G_CPU1_SB_DQ<3>")
	)
	(segment
		(start 160.72993 -280.916888)
		(end 160.89503 -280.916888)
		(width 0.10668)
		(layer "F.Cu")
		(net "M_G_CPU1_SB_DQ<3>")
	)
	(arc
		(start 145.730722 -275.117814)
		(mid 145.912973 -275.067464)
		(end 146.096482 -275.112988)
		(width 0.0762)
		(layer "F.Cu")
		(net "M_G_CPU1_SB_DQ<3>")
	)
	(arc
		(start 145.16481 -275.117814)
		(mid 145.447766 -275.193991)
		(end 145.730722 -275.117814)
		(width 0.0762)
		(layer "F.Cu")
		(net "M_G_CPU1_SB_DQ<3>")
	)
	(arc
		(start 144.493996 -275.194014)
		(mid 144.647745 -275.176505)
		(end 144.790922 -275.117814)
		(width 0.0762)
		(layer "F.Cu")
		(net "M_G_CPU1_SB_DQ<3>")
	)
	(arc
		(start 146.104864 -275.117814)
		(mid 146.207758 -275.170186)
		(end 146.315938 -275.210524)
		(width 0.0762)
		(layer "F.Cu")
		(net "M_G_CPU1_SB_DQ<3>")
	)
	(arc
		(start 144.037812 -275.440394)
		(mid 144.233161 -275.256575)
		(end 144.493996 -275.194014)
		(width 0.0762)
		(layer "F.Cu")
		(net "M_G_CPU1_SB_DQ<3>")
	)
	(arc
		(start 146.315938 -275.210524)
		(mid 146.437887 -275.238101)
		(end 146.562572 -275.247354)
		(width 0.0762)
		(layer "F.Cu")
		(net "M_G_CPU1_SB_DQ<3>")
	)
	(arc
		(start 144.790922 -275.117814)
		(mid 144.977866 -275.067559)
		(end 145.16481 -275.117814)
		(width 0.0762)
		(layer "F.Cu")
		(net "M_G_CPU1_SB_DQ<3>")
	)
	(segment
		(start 162.68319 -317.412624)
		(end 162.82416 -317.271908)
		(width 0.10668)
		(layer "F.Cu")
		(net "M_G_CPU1_SB_DQ<31>")
	)
	(segment
		(start 162.11677 -316.121034)
		(end 162.11677 -316.286134)
		(width 0.10668)
		(layer "F.Cu")
		(net "M_G_CPU1_SB_DQ<31>")
	)
	(segment
		(start 161.953702 -316.848236)
		(end 162.118802 -316.848236)
		(width 0.10668)
		(layer "F.Cu")
		(net "M_G_CPU1_SB_DQ<31>")
	)
	(segment
		(start 160.8709 -314.875164)
		(end 160.987994 -314.992258)
		(width 0.10668)
		(layer "F.Cu")
		(net "M_G_CPU1_SB_DQ<31>")
	)
	(segment
		(start 160.143444 -315.037978)
		(end 160.260538 -315.155072)
		(width 0.10668)
		(layer "F.Cu")
		(net "M_G_CPU1_SB_DQ<31>")
	)
	(segment
		(start 159.86125 -314.590684)
		(end 160.141412 -314.310776)
		(width 0.10668)
		(layer "F.Cu")
		(net "M_G_CPU1_SB_DQ<31>")
	)
	(segment
		(start 160.987994 -315.157358)
		(end 160.707832 -315.437266)
		(width 0.10668)
		(layer "F.Cu")
		(net "M_G_CPU1_SB_DQ<31>")
	)
	(segment
		(start 160.425638 -315.155072)
		(end 160.7058 -314.875164)
		(width 0.10668)
		(layer "F.Cu")
		(net "M_G_CPU1_SB_DQ<31>")
	)
	(segment
		(start 161.836608 -316.731142)
		(end 161.953702 -316.848236)
		(width 0.10668)
		(layer "F.Cu")
		(net "M_G_CPU1_SB_DQ<31>")
	)
	(segment
		(start 162.298126 -316.669166)
		(end 162.398964 -316.568328)
		(width 0.10668)
		(layer "F.Cu")
		(net "M_G_CPU1_SB_DQ<31>")
	)
	(segment
		(start 160.306512 -314.310776)
		(end 160.423606 -314.42787)
		(width 0.10668)
		(layer "F.Cu")
		(net "M_G_CPU1_SB_DQ<31>")
	)
	(segment
		(start 147.35429 -294.007286)
		(end 147.35429 -301.358554)
		(width 0.10668)
		(layer "F.Cu")
		(net "M_G_CPU1_SB_DQ<31>")
	)
	(segment
		(start 161.270188 -315.439552)
		(end 161.435288 -315.439552)
		(width 0.10668)
		(layer "F.Cu")
		(net "M_G_CPU1_SB_DQ<31>")
	)
	(segment
		(start 164.031168 -318.035432)
		(end 164.427916 -318.035432)
		(width 0.10668)
		(layer "F.Cu")
		(net "M_G_CPU1_SB_DQ<31>")
	)
	(segment
		(start 161.435288 -315.439552)
		(end 161.552382 -315.556646)
		(width 0.10668)
		(layer "F.Cu")
		(net "M_G_CPU1_SB_DQ<31>")
	)
	(segment
		(start 162.955478 -317.14059)
		(end 163.136326 -317.14059)
		(width 0.10668)
		(layer "F.Cu")
		(net "M_G_CPU1_SB_DQ<31>")
	)
	(segment
		(start 162.681158 -316.685422)
		(end 162.681158 -316.850522)
		(width 0.10668)
		(layer "F.Cu")
		(net "M_G_CPU1_SB_DQ<31>")
	)
	(segment
		(start 162.51809 -317.412624)
		(end 162.68319 -317.412624)
		(width 0.10668)
		(layer "F.Cu")
		(net "M_G_CPU1_SB_DQ<31>")
	)
	(segment
		(start 161.552382 -315.556646)
		(end 161.552382 -315.721746)
		(width 0.10668)
		(layer "F.Cu")
		(net "M_G_CPU1_SB_DQ<31>")
	)
	(segment
		(start 145.91792 -293.260272)
		(end 146.179794 -293.522146)
		(width 0.10668)
		(layer "F.Cu")
		(net "M_G_CPU1_SB_DQ<31>")
	)
	(segment
		(start 160.141412 -314.310776)
		(end 160.306512 -314.310776)
		(width 0.10668)
		(layer "F.Cu")
		(net "M_G_CPU1_SB_DQ<31>")
	)
	(segment
		(start 162.564064 -316.568328)
		(end 162.681158 -316.685422)
		(width 0.10668)
		(layer "F.Cu")
		(net "M_G_CPU1_SB_DQ<31>")
	)
	(segment
		(start 160.987994 -314.992258)
		(end 160.987994 -315.157358)
		(width 0.10668)
		(layer "F.Cu")
		(net "M_G_CPU1_SB_DQ<31>")
	)
	(segment
		(start 160.423606 -314.42787)
		(end 160.423606 -314.59297)
		(width 0.10668)
		(layer "F.Cu")
		(net "M_G_CPU1_SB_DQ<31>")
	)
	(segment
		(start 162.400996 -317.29553)
		(end 162.51809 -317.412624)
		(width 0.10668)
		(layer "F.Cu")
		(net "M_G_CPU1_SB_DQ<31>")
	)
	(segment
		(start 147.35429 -301.358554)
		(end 159.859218 -313.863482)
		(width 0.10668)
		(layer "F.Cu")
		(net "M_G_CPU1_SB_DQ<31>")
	)
	(segment
		(start 160.707832 -315.602366)
		(end 160.824926 -315.71946)
		(width 0.10668)
		(layer "F.Cu")
		(net "M_G_CPU1_SB_DQ<31>")
	)
	(segment
		(start 160.707832 -315.437266)
		(end 160.707832 -315.602366)
		(width 0.10668)
		(layer "F.Cu")
		(net "M_G_CPU1_SB_DQ<31>")
	)
	(segment
		(start 162.118802 -316.848236)
		(end 162.298126 -316.669166)
		(width 0.10668)
		(layer "F.Cu")
		(net "M_G_CPU1_SB_DQ<31>")
	)
	(segment
		(start 161.552382 -315.721746)
		(end 161.27222 -316.001654)
		(width 0.10668)
		(layer "F.Cu")
		(net "M_G_CPU1_SB_DQ<31>")
	)
	(segment
		(start 162.11677 -316.286134)
		(end 161.836608 -316.566042)
		(width 0.10668)
		(layer "F.Cu")
		(net "M_G_CPU1_SB_DQ<31>")
	)
	(segment
		(start 160.7058 -314.875164)
		(end 160.8709 -314.875164)
		(width 0.10668)
		(layer "F.Cu")
		(net "M_G_CPU1_SB_DQ<31>")
	)
	(segment
		(start 161.836608 -316.566042)
		(end 161.836608 -316.731142)
		(width 0.10668)
		(layer "F.Cu")
		(net "M_G_CPU1_SB_DQ<31>")
	)
	(segment
		(start 160.824926 -315.71946)
		(end 160.990026 -315.71946)
		(width 0.10668)
		(layer "F.Cu")
		(net "M_G_CPU1_SB_DQ<31>")
	)
	(segment
		(start 159.859218 -314.028582)
		(end 159.579056 -314.30849)
		(width 0.10668)
		(layer "F.Cu")
		(net "M_G_CPU1_SB_DQ<31>")
	)
	(segment
		(start 161.999676 -316.00394)
		(end 162.11677 -316.121034)
		(width 0.10668)
		(layer "F.Cu")
		(net "M_G_CPU1_SB_DQ<31>")
	)
	(segment
		(start 162.398964 -316.568328)
		(end 162.564064 -316.568328)
		(width 0.10668)
		(layer "F.Cu")
		(net "M_G_CPU1_SB_DQ<31>")
	)
	(segment
		(start 163.136326 -317.14059)
		(end 164.031168 -318.035432)
		(width 0.10668)
		(layer "F.Cu")
		(net "M_G_CPU1_SB_DQ<31>")
	)
	(segment
		(start 160.260538 -315.155072)
		(end 160.425638 -315.155072)
		(width 0.10668)
		(layer "F.Cu")
		(net "M_G_CPU1_SB_DQ<31>")
	)
	(segment
		(start 146.179794 -293.522146)
		(end 146.86915 -293.522146)
		(width 0.10668)
		(layer "F.Cu")
		(net "M_G_CPU1_SB_DQ<31>")
	)
	(segment
		(start 161.554414 -316.283848)
		(end 161.834576 -316.00394)
		(width 0.10668)
		(layer "F.Cu")
		(net "M_G_CPU1_SB_DQ<31>")
	)
	(segment
		(start 162.82416 -317.271908)
		(end 162.955478 -317.14059)
		(width 0.10668)
		(layer "F.Cu")
		(net "M_G_CPU1_SB_DQ<31>")
	)
	(segment
		(start 160.423606 -314.59297)
		(end 160.143444 -314.872878)
		(width 0.10668)
		(layer "F.Cu")
		(net "M_G_CPU1_SB_DQ<31>")
	)
	(segment
		(start 162.681158 -316.850522)
		(end 162.400996 -317.13043)
		(width 0.10668)
		(layer "F.Cu")
		(net "M_G_CPU1_SB_DQ<31>")
	)
	(segment
		(start 159.579056 -314.47359)
		(end 159.69615 -314.590684)
		(width 0.10668)
		(layer "F.Cu")
		(net "M_G_CPU1_SB_DQ<31>")
	)
	(segment
		(start 162.400996 -317.13043)
		(end 162.400996 -317.29553)
		(width 0.10668)
		(layer "F.Cu")
		(net "M_G_CPU1_SB_DQ<31>")
	)
	(segment
		(start 160.143444 -314.872878)
		(end 160.143444 -315.037978)
		(width 0.10668)
		(layer "F.Cu")
		(net "M_G_CPU1_SB_DQ<31>")
	)
	(segment
		(start 159.69615 -314.590684)
		(end 159.86125 -314.590684)
		(width 0.10668)
		(layer "F.Cu")
		(net "M_G_CPU1_SB_DQ<31>")
	)
	(segment
		(start 161.389314 -316.283848)
		(end 161.554414 -316.283848)
		(width 0.10668)
		(layer "F.Cu")
		(net "M_G_CPU1_SB_DQ<31>")
	)
	(segment
		(start 146.86915 -293.522146)
		(end 147.35429 -294.007286)
		(width 0.10668)
		(layer "F.Cu")
		(net "M_G_CPU1_SB_DQ<31>")
	)
	(segment
		(start 161.834576 -316.00394)
		(end 161.999676 -316.00394)
		(width 0.10668)
		(layer "F.Cu")
		(net "M_G_CPU1_SB_DQ<31>")
	)
	(segment
		(start 161.27222 -316.166754)
		(end 161.389314 -316.283848)
		(width 0.10668)
		(layer "F.Cu")
		(net "M_G_CPU1_SB_DQ<31>")
	)
	(segment
		(start 159.579056 -314.30849)
		(end 159.579056 -314.47359)
		(width 0.10668)
		(layer "F.Cu")
		(net "M_G_CPU1_SB_DQ<31>")
	)
	(segment
		(start 160.990026 -315.71946)
		(end 161.270188 -315.439552)
		(width 0.10668)
		(layer "F.Cu")
		(net "M_G_CPU1_SB_DQ<31>")
	)
	(segment
		(start 161.27222 -316.001654)
		(end 161.27222 -316.166754)
		(width 0.10668)
		(layer "F.Cu")
		(net "M_G_CPU1_SB_DQ<31>")
	)
	(segment
		(start 159.859218 -313.863482)
		(end 159.859218 -314.028582)
		(width 0.10668)
		(layer "F.Cu")
		(net "M_G_CPU1_SB_DQ<31>")
	)
	(segment
		(start 155.077414 -306.36337)
		(end 155.077414 -306.52847)
		(width 0.10668)
		(layer "F.Cu")
		(net "M_G_CPU1_SB_DQ<30>")
	)
	(segment
		(start 154.26817 -306.773326)
		(end 154.79522 -306.246276)
		(width 0.10668)
		(layer "F.Cu")
		(net "M_G_CPU1_SB_DQ<30>")
	)
	(segment
		(start 151.67483 -303.034446)
		(end 151.67483 -304.345086)
		(width 0.10668)
		(layer "F.Cu")
		(net "M_G_CPU1_SB_DQ<30>")
	)
	(segment
		(start 146.38782 -292.07714)
		(end 147.195286 -292.07714)
		(width 0.0762)
		(layer "F.Cu")
		(net "M_G_CPU1_SB_DQ<30>")
	)
	(segment
		(start 155.67914 -308.349396)
		(end 163.600638 -316.271148)
		(width 0.10668)
		(layer "F.Cu")
		(net "M_G_CPU1_SB_DQ<30>")
	)
	(segment
		(start 147.55876 -292.440614)
		(end 148.036534 -292.918388)
		(width 0.10668)
		(layer "F.Cu")
		(net "M_G_CPU1_SB_DQ<30>")
	)
	(segment
		(start 155.396946 -307.902102)
		(end 155.714446 -307.584602)
		(width 0.10668)
		(layer "F.Cu")
		(net "M_G_CPU1_SB_DQ<30>")
	)
	(segment
		(start 154.667458 -307.337714)
		(end 154.832558 -307.337714)
		(width 0.10668)
		(layer "F.Cu")
		(net "M_G_CPU1_SB_DQ<30>")
	)
	(segment
		(start 151.67483 -304.345086)
		(end 154.10307 -306.773326)
		(width 0.10668)
		(layer "F.Cu")
		(net "M_G_CPU1_SB_DQ<30>")
	)
	(segment
		(start 155.714446 -307.584602)
		(end 155.879546 -307.584602)
		(width 0.10668)
		(layer "F.Cu")
		(net "M_G_CPU1_SB_DQ<30>")
	)
	(segment
		(start 155.879546 -307.584602)
		(end 155.99664 -307.701696)
		(width 0.10668)
		(layer "F.Cu")
		(net "M_G_CPU1_SB_DQ<30>")
	)
	(segment
		(start 155.231846 -307.902102)
		(end 155.396946 -307.902102)
		(width 0.10668)
		(layer "F.Cu")
		(net "M_G_CPU1_SB_DQ<30>")
	)
	(segment
		(start 148.036534 -299.39615)
		(end 151.67483 -303.034446)
		(width 0.10668)
		(layer "F.Cu")
		(net "M_G_CPU1_SB_DQ<30>")
	)
	(segment
		(start 155.99664 -307.701696)
		(end 155.99664 -307.866796)
		(width 0.10668)
		(layer "F.Cu")
		(net "M_G_CPU1_SB_DQ<30>")
	)
	(segment
		(start 155.114752 -307.619908)
		(end 155.114752 -307.785008)
		(width 0.10668)
		(layer "F.Cu")
		(net "M_G_CPU1_SB_DQ<30>")
	)
	(segment
		(start 163.665154 -316.33541)
		(end 164.427916 -316.33541)
		(width 0.10668)
		(layer "F.Cu")
		(net "M_G_CPU1_SB_DQ<30>")
	)
	(segment
		(start 154.550364 -307.22062)
		(end 154.667458 -307.337714)
		(width 0.10668)
		(layer "F.Cu")
		(net "M_G_CPU1_SB_DQ<30>")
	)
	(segment
		(start 154.96032 -306.246276)
		(end 155.077414 -306.36337)
		(width 0.10668)
		(layer "F.Cu")
		(net "M_G_CPU1_SB_DQ<30>")
	)
	(segment
		(start 154.550364 -307.05552)
		(end 154.550364 -307.22062)
		(width 0.10668)
		(layer "F.Cu")
		(net "M_G_CPU1_SB_DQ<30>")
	)
	(segment
		(start 148.036534 -292.918388)
		(end 148.036534 -299.39615)
		(width 0.10668)
		(layer "F.Cu")
		(net "M_G_CPU1_SB_DQ<30>")
	)
	(segment
		(start 155.524708 -306.810664)
		(end 155.641802 -306.927758)
		(width 0.10668)
		(layer "F.Cu")
		(net "M_G_CPU1_SB_DQ<30>")
	)
	(segment
		(start 163.600638 -316.271148)
		(end 163.665154 -316.33541)
		(width 0.10668)
		(layer "F.Cu")
		(net "M_G_CPU1_SB_DQ<30>")
	)
	(segment
		(start 155.67914 -308.184296)
		(end 155.67914 -308.349396)
		(width 0.10668)
		(layer "F.Cu")
		(net "M_G_CPU1_SB_DQ<30>")
	)
	(segment
		(start 155.99664 -307.866796)
		(end 155.67914 -308.184296)
		(width 0.10668)
		(layer "F.Cu")
		(net "M_G_CPU1_SB_DQ<30>")
	)
	(segment
		(start 155.077414 -306.52847)
		(end 154.550364 -307.05552)
		(width 0.10668)
		(layer "F.Cu")
		(net "M_G_CPU1_SB_DQ<30>")
	)
	(segment
		(start 154.832558 -307.337714)
		(end 155.359608 -306.810664)
		(width 0.10668)
		(layer "F.Cu")
		(net "M_G_CPU1_SB_DQ<30>")
	)
	(segment
		(start 155.114752 -307.785008)
		(end 155.231846 -307.902102)
		(width 0.10668)
		(layer "F.Cu")
		(net "M_G_CPU1_SB_DQ<30>")
	)
	(segment
		(start 154.10307 -306.773326)
		(end 154.26817 -306.773326)
		(width 0.10668)
		(layer "F.Cu")
		(net "M_G_CPU1_SB_DQ<30>")
	)
	(segment
		(start 155.641802 -307.092858)
		(end 155.114752 -307.619908)
		(width 0.10668)
		(layer "F.Cu")
		(net "M_G_CPU1_SB_DQ<30>")
	)
	(segment
		(start 147.195286 -292.07714)
		(end 147.55876 -292.440614)
		(width 0.0762)
		(layer "F.Cu")
		(net "M_G_CPU1_SB_DQ<30>")
	)
	(segment
		(start 155.359608 -306.810664)
		(end 155.524708 -306.810664)
		(width 0.10668)
		(layer "F.Cu")
		(net "M_G_CPU1_SB_DQ<30>")
	)
	(segment
		(start 154.79522 -306.246276)
		(end 154.96032 -306.246276)
		(width 0.10668)
		(layer "F.Cu")
		(net "M_G_CPU1_SB_DQ<30>")
	)
	(segment
		(start 155.641802 -306.927758)
		(end 155.641802 -307.092858)
		(width 0.10668)
		(layer "F.Cu")
		(net "M_G_CPU1_SB_DQ<30>")
	)
	(arc
		(start 145.976848 -292.200838)
		(mid 145.996197 -292.1985)
		(end 146.015456 -292.195504)
		(width 0.0762)
		(layer "F.Cu")
		(net "M_G_CPU1_SB_DQ<30>")
	)
	(arc
		(start 146.015456 -292.195504)
		(mid 146.111165 -292.169792)
		(end 146.200876 -292.127686)
		(width 0.0762)
		(layer "F.Cu")
		(net "M_G_CPU1_SB_DQ<30>")
	)
	(arc
		(start 145.447766 -292.450266)
		(mid 145.691197 -292.280779)
		(end 145.976848 -292.200838)
		(width 0.0762)
		(layer "F.Cu")
		(net "M_G_CPU1_SB_DQ<30>")
	)
	(arc
		(start 146.356832 -292.07841)
		(mid 146.372313 -292.077454)
		(end 146.38782 -292.07714)
		(width 0.0762)
		(layer "F.Cu")
		(net "M_G_CPU1_SB_DQ<30>")
	)
	(arc
		(start 146.200876 -292.127686)
		(mid 146.276116 -292.094373)
		(end 146.356832 -292.07841)
		(width 0.0762)
		(layer "F.Cu")
		(net "M_G_CPU1_SB_DQ<30>")
	)
	(segment
		(start 157.962092 -276.248368)
		(end 157.962092 -276.413468)
		(width 0.10668)
		(layer "F.Cu")
		(net "M_G_CPU1_SB_DQ<2>")
	)
	(segment
		(start 150.803864 -274.398994)
		(end 150.979124 -274.398994)
		(width 0.10668)
		(layer "F.Cu")
		(net "M_G_CPU1_SB_DQ<2>")
	)
	(segment
		(start 148.808694 -274.17522)
		(end 148.983954 -274.17522)
		(width 0.10668)
		(layer "F.Cu")
		(net "M_G_CPU1_SB_DQ<2>")
	)
	(segment
		(start 157.962092 -276.413468)
		(end 157.658562 -276.716998)
		(width 0.10668)
		(layer "F.Cu")
		(net "M_G_CPU1_SB_DQ<2>")
	)
	(segment
		(start 157.397704 -275.68398)
		(end 157.397704 -275.84908)
		(width 0.10668)
		(layer "F.Cu")
		(net "M_G_CPU1_SB_DQ<2>")
	)
	(segment
		(start 158.808674 -277.26005)
		(end 158.973774 -277.26005)
		(width 0.10668)
		(layer "F.Cu")
		(net "M_G_CPU1_SB_DQ<2>")
	)
	(segment
		(start 158.787338 -277.845774)
		(end 158.787338 -278.010874)
		(width 0.10668)
		(layer "F.Cu")
		(net "M_G_CPU1_SB_DQ<2>")
	)
	(segment
		(start 157.679898 -276.131274)
		(end 157.844998 -276.131274)
		(width 0.10668)
		(layer "F.Cu")
		(net "M_G_CPU1_SB_DQ<2>")
	)
	(segment
		(start 151.202898 -274.17522)
		(end 151.378158 -274.17522)
		(width 0.10668)
		(layer "F.Cu")
		(net "M_G_CPU1_SB_DQ<2>")
	)
	(segment
		(start 159.069532 -278.127968)
		(end 159.373062 -277.824438)
		(width 0.10668)
		(layer "F.Cu")
		(net "M_G_CPU1_SB_DQ<2>")
	)
	(segment
		(start 159.090868 -277.377144)
		(end 159.090868 -277.542244)
		(width 0.10668)
		(layer "F.Cu")
		(net "M_G_CPU1_SB_DQ<2>")
	)
	(segment
		(start 158.904432 -278.127968)
		(end 159.069532 -278.127968)
		(width 0.10668)
		(layer "F.Cu")
		(net "M_G_CPU1_SB_DQ<2>")
	)
	(segment
		(start 154.951684 -274.17522)
		(end 156.64688 -275.870416)
		(width 0.10668)
		(layer "F.Cu")
		(net "M_G_CPU1_SB_DQ<2>")
	)
	(segment
		(start 158.409386 -276.695662)
		(end 158.52648 -276.812756)
		(width 0.10668)
		(layer "F.Cu")
		(net "M_G_CPU1_SB_DQ<2>")
	)
	(segment
		(start 158.340044 -277.56358)
		(end 158.505144 -277.56358)
		(width 0.10668)
		(layer "F.Cu")
		(net "M_G_CPU1_SB_DQ<2>")
	)
	(segment
		(start 156.81198 -275.870416)
		(end 157.11551 -275.566886)
		(width 0.10668)
		(layer "F.Cu")
		(net "M_G_CPU1_SB_DQ<2>")
	)
	(segment
		(start 150.979124 -274.398994)
		(end 151.202898 -274.17522)
		(width 0.10668)
		(layer "F.Cu")
		(net "M_G_CPU1_SB_DQ<2>")
	)
	(segment
		(start 147.888452 -274.17522)
		(end 148.185886 -274.17522)
		(width 0.10668)
		(layer "F.Cu")
		(net "M_G_CPU1_SB_DQ<2>")
	)
	(segment
		(start 157.658562 -276.716998)
		(end 157.658562 -276.882098)
		(width 0.10668)
		(layer "F.Cu")
		(net "M_G_CPU1_SB_DQ<2>")
	)
	(segment
		(start 157.376368 -276.434804)
		(end 157.679898 -276.131274)
		(width 0.10668)
		(layer "F.Cu")
		(net "M_G_CPU1_SB_DQ<2>")
	)
	(segment
		(start 163.111688 -282.335224)
		(end 164.427916 -282.335224)
		(width 0.10668)
		(layer "F.Cu")
		(net "M_G_CPU1_SB_DQ<2>")
	)
	(segment
		(start 157.940756 -276.999192)
		(end 158.244286 -276.695662)
		(width 0.10668)
		(layer "F.Cu")
		(net "M_G_CPU1_SB_DQ<2>")
	)
	(segment
		(start 158.22295 -277.281386)
		(end 158.22295 -277.446486)
		(width 0.10668)
		(layer "F.Cu")
		(net "M_G_CPU1_SB_DQ<2>")
	)
	(segment
		(start 162.73907 -281.962606)
		(end 163.111688 -282.335224)
		(width 0.10668)
		(layer "F.Cu")
		(net "M_G_CPU1_SB_DQ<2>")
	)
	(segment
		(start 149.207728 -274.398994)
		(end 149.382988 -274.398994)
		(width 0.10668)
		(layer "F.Cu")
		(net "M_G_CPU1_SB_DQ<2>")
	)
	(segment
		(start 158.973774 -277.26005)
		(end 159.090868 -277.377144)
		(width 0.10668)
		(layer "F.Cu")
		(net "M_G_CPU1_SB_DQ<2>")
	)
	(segment
		(start 147.41779 -274.17522)
		(end 147.888452 -274.17522)
		(width 0.0762)
		(layer "F.Cu")
		(net "M_G_CPU1_SB_DQ<2>")
	)
	(segment
		(start 149.382988 -274.398994)
		(end 149.606762 -274.17522)
		(width 0.10668)
		(layer "F.Cu")
		(net "M_G_CPU1_SB_DQ<2>")
	)
	(segment
		(start 150.58009 -274.17522)
		(end 150.803864 -274.398994)
		(width 0.10668)
		(layer "F.Cu")
		(net "M_G_CPU1_SB_DQ<2>")
	)
	(segment
		(start 148.983954 -274.17522)
		(end 149.207728 -274.398994)
		(width 0.10668)
		(layer "F.Cu")
		(net "M_G_CPU1_SB_DQ<2>")
	)
	(segment
		(start 157.211268 -276.434804)
		(end 157.376368 -276.434804)
		(width 0.10668)
		(layer "F.Cu")
		(net "M_G_CPU1_SB_DQ<2>")
	)
	(segment
		(start 158.505144 -277.56358)
		(end 158.808674 -277.26005)
		(width 0.10668)
		(layer "F.Cu")
		(net "M_G_CPU1_SB_DQ<2>")
	)
	(segment
		(start 151.378158 -274.17522)
		(end 151.601932 -274.398994)
		(width 0.10668)
		(layer "F.Cu")
		(net "M_G_CPU1_SB_DQ<2>")
	)
	(segment
		(start 148.40966 -274.398994)
		(end 148.58492 -274.398994)
		(width 0.10668)
		(layer "F.Cu")
		(net "M_G_CPU1_SB_DQ<2>")
	)
	(segment
		(start 158.22295 -277.446486)
		(end 158.340044 -277.56358)
		(width 0.10668)
		(layer "F.Cu")
		(net "M_G_CPU1_SB_DQ<2>")
	)
	(segment
		(start 157.094174 -276.31771)
		(end 157.211268 -276.434804)
		(width 0.10668)
		(layer "F.Cu")
		(net "M_G_CPU1_SB_DQ<2>")
	)
	(segment
		(start 149.606762 -274.17522)
		(end 149.782022 -274.17522)
		(width 0.10668)
		(layer "F.Cu")
		(net "M_G_CPU1_SB_DQ<2>")
	)
	(segment
		(start 158.52648 -276.812756)
		(end 158.52648 -276.977856)
		(width 0.10668)
		(layer "F.Cu")
		(net "M_G_CPU1_SB_DQ<2>")
	)
	(segment
		(start 152.000966 -274.17522)
		(end 154.951684 -274.17522)
		(width 0.10668)
		(layer "F.Cu")
		(net "M_G_CPU1_SB_DQ<2>")
	)
	(segment
		(start 158.52648 -276.977856)
		(end 158.22295 -277.281386)
		(width 0.10668)
		(layer "F.Cu")
		(net "M_G_CPU1_SB_DQ<2>")
	)
	(segment
		(start 157.658562 -276.882098)
		(end 157.775656 -276.999192)
		(width 0.10668)
		(layer "F.Cu")
		(net "M_G_CPU1_SB_DQ<2>")
	)
	(segment
		(start 157.094174 -276.15261)
		(end 157.094174 -276.31771)
		(width 0.10668)
		(layer "F.Cu")
		(net "M_G_CPU1_SB_DQ<2>")
	)
	(segment
		(start 150.40483 -274.17522)
		(end 150.58009 -274.17522)
		(width 0.10668)
		(layer "F.Cu")
		(net "M_G_CPU1_SB_DQ<2>")
	)
	(segment
		(start 162.73907 -281.025346)
		(end 162.73907 -281.962606)
		(width 0.10668)
		(layer "F.Cu")
		(net "M_G_CPU1_SB_DQ<2>")
	)
	(segment
		(start 151.601932 -274.398994)
		(end 151.777192 -274.398994)
		(width 0.10668)
		(layer "F.Cu")
		(net "M_G_CPU1_SB_DQ<2>")
	)
	(segment
		(start 158.244286 -276.695662)
		(end 158.409386 -276.695662)
		(width 0.10668)
		(layer "F.Cu")
		(net "M_G_CPU1_SB_DQ<2>")
	)
	(segment
		(start 146.38782 -274.257262)
		(end 147.335748 -274.257262)
		(width 0.0762)
		(layer "F.Cu")
		(net "M_G_CPU1_SB_DQ<2>")
	)
	(segment
		(start 148.185886 -274.17522)
		(end 148.40966 -274.398994)
		(width 0.10668)
		(layer "F.Cu")
		(net "M_G_CPU1_SB_DQ<2>")
	)
	(segment
		(start 157.397704 -275.84908)
		(end 157.094174 -276.15261)
		(width 0.10668)
		(layer "F.Cu")
		(net "M_G_CPU1_SB_DQ<2>")
	)
	(segment
		(start 147.335748 -274.257262)
		(end 147.41779 -274.17522)
		(width 0.0762)
		(layer "F.Cu")
		(net "M_G_CPU1_SB_DQ<2>")
	)
	(segment
		(start 149.782022 -274.17522)
		(end 150.005796 -274.398994)
		(width 0.10668)
		(layer "F.Cu")
		(net "M_G_CPU1_SB_DQ<2>")
	)
	(segment
		(start 150.181056 -274.398994)
		(end 150.40483 -274.17522)
		(width 0.10668)
		(layer "F.Cu")
		(net "M_G_CPU1_SB_DQ<2>")
	)
	(segment
		(start 150.005796 -274.398994)
		(end 150.181056 -274.398994)
		(width 0.10668)
		(layer "F.Cu")
		(net "M_G_CPU1_SB_DQ<2>")
	)
	(segment
		(start 157.28061 -275.566886)
		(end 157.397704 -275.68398)
		(width 0.10668)
		(layer "F.Cu")
		(net "M_G_CPU1_SB_DQ<2>")
	)
	(segment
		(start 157.11551 -275.566886)
		(end 157.28061 -275.566886)
		(width 0.10668)
		(layer "F.Cu")
		(net "M_G_CPU1_SB_DQ<2>")
	)
	(segment
		(start 158.787338 -278.010874)
		(end 158.904432 -278.127968)
		(width 0.10668)
		(layer "F.Cu")
		(net "M_G_CPU1_SB_DQ<2>")
	)
	(segment
		(start 159.090868 -277.542244)
		(end 158.787338 -277.845774)
		(width 0.10668)
		(layer "F.Cu")
		(net "M_G_CPU1_SB_DQ<2>")
	)
	(segment
		(start 148.58492 -274.398994)
		(end 148.808694 -274.17522)
		(width 0.10668)
		(layer "F.Cu")
		(net "M_G_CPU1_SB_DQ<2>")
	)
	(segment
		(start 157.775656 -276.999192)
		(end 157.940756 -276.999192)
		(width 0.10668)
		(layer "F.Cu")
		(net "M_G_CPU1_SB_DQ<2>")
	)
	(segment
		(start 157.844998 -276.131274)
		(end 157.962092 -276.248368)
		(width 0.10668)
		(layer "F.Cu")
		(net "M_G_CPU1_SB_DQ<2>")
	)
	(segment
		(start 151.777192 -274.398994)
		(end 152.000966 -274.17522)
		(width 0.10668)
		(layer "F.Cu")
		(net "M_G_CPU1_SB_DQ<2>")
	)
	(segment
		(start 156.64688 -275.870416)
		(end 156.81198 -275.870416)
		(width 0.10668)
		(layer "F.Cu")
		(net "M_G_CPU1_SB_DQ<2>")
	)
	(segment
		(start 159.538162 -277.824438)
		(end 162.73907 -281.025346)
		(width 0.10668)
		(layer "F.Cu")
		(net "M_G_CPU1_SB_DQ<2>")
	)
	(segment
		(start 159.373062 -277.824438)
		(end 159.538162 -277.824438)
		(width 0.10668)
		(layer "F.Cu")
		(net "M_G_CPU1_SB_DQ<2>")
	)
	(arc
		(start 146.015456 -274.375626)
		(mid 146.111165 -274.349914)
		(end 146.200876 -274.307808)
		(width 0.0762)
		(layer "F.Cu")
		(net "M_G_CPU1_SB_DQ<2>")
	)
	(arc
		(start 145.447766 -274.630388)
		(mid 145.691197 -274.460901)
		(end 145.976848 -274.38096)
		(width 0.0762)
		(layer "F.Cu")
		(net "M_G_CPU1_SB_DQ<2>")
	)
	(arc
		(start 146.200876 -274.307808)
		(mid 146.276116 -274.274495)
		(end 146.356832 -274.258532)
		(width 0.0762)
		(layer "F.Cu")
		(net "M_G_CPU1_SB_DQ<2>")
	)
	(arc
		(start 146.356832 -274.258532)
		(mid 146.372313 -274.257576)
		(end 146.38782 -274.257262)
		(width 0.0762)
		(layer "F.Cu")
		(net "M_G_CPU1_SB_DQ<2>")
	)
	(arc
		(start 145.976848 -274.38096)
		(mid 145.996197 -274.378622)
		(end 146.015456 -274.375626)
		(width 0.0762)
		(layer "F.Cu")
		(net "M_G_CPU1_SB_DQ<2>")
	)
	(segment
		(start 147.69592 -293.239952)
		(end 147.69592 -293.52621)
		(width 0.0762)
		(layer "F.Cu")
		(net "M_G_CPU1_SB_DQ<29>")
	)
	(segment
		(start 147.28825 -292.832282)
		(end 147.69592 -293.239952)
		(width 0.0762)
		(layer "F.Cu")
		(net "M_G_CPU1_SB_DQ<29>")
	)
	(segment
		(start 147.69592 -293.52621)
		(end 147.69592 -301.041054)
		(width 0.10668)
		(layer "F.Cu")
		(net "M_G_CPU1_SB_DQ<29>")
	)
	(segment
		(start 147.69592 -301.041054)
		(end 163.377626 -316.72276)
		(width 0.10668)
		(layer "F.Cu")
		(net "M_G_CPU1_SB_DQ<29>")
	)
	(segment
		(start 163.415218 -316.760352)
		(end 165.462966 -316.760352)
		(width 0.101346)
		(layer "F.Cu")
		(net "M_G_CPU1_SB_DQ<29>")
	)
	(segment
		(start 145.260822 -292.772846)
		(end 145.261076 -292.772846)
		(width 0.0762)
		(layer "F.Cu")
		(net "M_G_CPU1_SB_DQ<29>")
	)
	(segment
		(start 147.248626 -292.832282)
		(end 147.28825 -292.832282)
		(width 0.0762)
		(layer "F.Cu")
		(net "M_G_CPU1_SB_DQ<29>")
	)
	(segment
		(start 167.59936 -317.185294)
		(end 168.527984 -317.185294)
		(width 0.101346)
		(layer "F.Cu")
		(net "M_G_CPU1_SB_DQ<29>")
	)
	(segment
		(start 144.686528 -292.777672)
		(end 144.69491 -292.772846)
		(width 0.0762)
		(layer "F.Cu")
		(net "M_G_CPU1_SB_DQ<29>")
	)
	(segment
		(start 165.462966 -316.760352)
		(end 167.59936 -317.185294)
		(width 0.101346)
		(layer "F.Cu")
		(net "M_G_CPU1_SB_DQ<29>")
	)
	(segment
		(start 163.377626 -316.72276)
		(end 163.415218 -316.760352)
		(width 0.101346)
		(layer "F.Cu")
		(net "M_G_CPU1_SB_DQ<29>")
	)
	(segment
		(start 146.358356 -292.831012)
		(end 147.248626 -292.832282)
		(width 0.0762)
		(layer "F.Cu")
		(net "M_G_CPU1_SB_DQ<29>")
	)
	(segment
		(start 144.507966 -292.450266)
		(end 144.399508 -292.636956)
		(width 0.0762)
		(layer "F.Cu")
		(net "M_G_CPU1_SB_DQ<29>")
	)
	(arc
		(start 146.283426 -292.81501)
		(mid 146.320054 -292.82694)
		(end 146.358356 -292.831012)
		(width 0.0762)
		(layer "F.Cu")
		(net "M_G_CPU1_SB_DQ<29>")
	)
	(arc
		(start 145.261076 -292.772846)
		(mid 145.44802 -292.82317)
		(end 145.634964 -292.772846)
		(width 0.0762)
		(layer "F.Cu")
		(net "M_G_CPU1_SB_DQ<29>")
	)
	(arc
		(start 145.634964 -292.772846)
		(mid 145.91792 -292.696669)
		(end 146.200876 -292.772846)
		(width 0.0762)
		(layer "F.Cu")
		(net "M_G_CPU1_SB_DQ<29>")
	)
	(arc
		(start 146.200876 -292.772846)
		(mid 146.24157 -292.795065)
		(end 146.283426 -292.81501)
		(width 0.0762)
		(layer "F.Cu")
		(net "M_G_CPU1_SB_DQ<29>")
	)
	(arc
		(start 144.399508 -292.636956)
		(mid 144.425425 -292.769998)
		(end 144.551146 -292.820598)
		(width 0.0762)
		(layer "F.Cu")
		(net "M_G_CPU1_SB_DQ<29>")
	)
	(arc
		(start 144.69491 -292.772846)
		(mid 144.977866 -292.696669)
		(end 145.260822 -292.772846)
		(width 0.0762)
		(layer "F.Cu")
		(net "M_G_CPU1_SB_DQ<29>")
	)
	(arc
		(start 144.551146 -292.820598)
		(mid 144.6209 -292.805641)
		(end 144.686528 -292.777672)
		(width 0.0762)
		(layer "F.Cu")
		(net "M_G_CPU1_SB_DQ<29>")
	)
	(segment
		(start 147.451064 -291.82187)
		(end 147.885912 -292.256718)
		(width 0.0762)
		(layer "F.Cu")
		(net "M_G_CPU1_SB_DQ<28>")
	)
	(segment
		(start 154.40152 -305.205638)
		(end 154.40152 -305.370738)
		(width 0.10668)
		(layer "F.Cu")
		(net "M_G_CPU1_SB_DQ<28>")
	)
	(segment
		(start 145.91792 -291.64026)
		(end 145.815558 -291.816536)
		(width 0.0762)
		(layer "F.Cu")
		(net "M_G_CPU1_SB_DQ<28>")
	)
	(segment
		(start 156.384244 -308.376574)
		(end 163.068 -315.06033)
		(width 0.10668)
		(layer "F.Cu")
		(net "M_G_CPU1_SB_DQ<28>")
	)
	(segment
		(start 146.67738 -291.82187)
		(end 147.451064 -291.82187)
		(width 0.0762)
		(layer "F.Cu")
		(net "M_G_CPU1_SB_DQ<28>")
	)
	(segment
		(start 163.068 -315.06033)
		(end 163.377626 -315.06033)
		(width 0.10668)
		(layer "F.Cu")
		(net "M_G_CPU1_SB_DQ<28>")
	)
	(segment
		(start 146.61261 -291.88664)
		(end 146.67738 -291.82187)
		(width 0.0762)
		(layer "F.Cu")
		(net "M_G_CPU1_SB_DQ<28>")
	)
	(segment
		(start 165.989254 -315.06033)
		(end 166.414196 -315.485272)
		(width 0.101346)
		(layer "F.Cu")
		(net "M_G_CPU1_SB_DQ<28>")
	)
	(segment
		(start 154.40152 -305.370738)
		(end 153.906728 -305.865276)
		(width 0.10668)
		(layer "F.Cu")
		(net "M_G_CPU1_SB_DQ<28>")
	)
	(segment
		(start 154.023822 -306.14747)
		(end 154.188922 -306.14747)
		(width 0.10668)
		(layer "F.Cu")
		(net "M_G_CPU1_SB_DQ<28>")
	)
	(segment
		(start 148.376894 -299.181012)
		(end 154.40152 -305.205638)
		(width 0.10668)
		(layer "F.Cu")
		(net "M_G_CPU1_SB_DQ<28>")
	)
	(segment
		(start 146.387566 -291.88664)
		(end 146.61261 -291.88664)
		(width 0.0762)
		(layer "F.Cu")
		(net "M_G_CPU1_SB_DQ<28>")
	)
	(segment
		(start 166.414196 -315.485272)
		(end 168.527984 -315.485272)
		(width 0.101346)
		(layer "F.Cu")
		(net "M_G_CPU1_SB_DQ<28>")
	)
	(segment
		(start 153.906728 -306.030376)
		(end 154.023822 -306.14747)
		(width 0.10668)
		(layer "F.Cu")
		(net "M_G_CPU1_SB_DQ<28>")
	)
	(segment
		(start 148.376894 -292.7477)
		(end 148.376894 -299.181012)
		(width 0.10668)
		(layer "F.Cu")
		(net "M_G_CPU1_SB_DQ<28>")
	)
	(segment
		(start 153.906728 -305.865276)
		(end 153.906728 -306.030376)
		(width 0.10668)
		(layer "F.Cu")
		(net "M_G_CPU1_SB_DQ<28>")
	)
	(segment
		(start 146.096482 -291.967666)
		(end 146.104864 -291.96284)
		(width 0.0762)
		(layer "F.Cu")
		(net "M_G_CPU1_SB_DQ<28>")
	)
	(segment
		(start 156.384244 -307.188362)
		(end 156.384244 -308.376574)
		(width 0.10668)
		(layer "F.Cu")
		(net "M_G_CPU1_SB_DQ<28>")
	)
	(segment
		(start 163.377626 -315.06033)
		(end 165.989254 -315.06033)
		(width 0.101346)
		(layer "F.Cu")
		(net "M_G_CPU1_SB_DQ<28>")
	)
	(segment
		(start 147.885912 -292.256718)
		(end 148.376894 -292.7477)
		(width 0.10668)
		(layer "F.Cu")
		(net "M_G_CPU1_SB_DQ<28>")
	)
	(segment
		(start 154.683714 -305.652932)
		(end 154.848814 -305.652932)
		(width 0.10668)
		(layer "F.Cu")
		(net "M_G_CPU1_SB_DQ<28>")
	)
	(segment
		(start 154.848814 -305.652932)
		(end 156.384244 -307.188362)
		(width 0.10668)
		(layer "F.Cu")
		(net "M_G_CPU1_SB_DQ<28>")
	)
	(segment
		(start 154.188922 -306.14747)
		(end 154.683714 -305.652932)
		(width 0.10668)
		(layer "F.Cu")
		(net "M_G_CPU1_SB_DQ<28>")
	)
	(arc
		(start 145.982436 -292.007544)
		(mid 146.041082 -291.992251)
		(end 146.096482 -291.967666)
		(width 0.0762)
		(layer "F.Cu")
		(net "M_G_CPU1_SB_DQ<28>")
	)
	(arc
		(start 145.815558 -291.816536)
		(mid 145.845187 -291.959023)
		(end 145.982436 -292.007544)
		(width 0.0762)
		(layer "F.Cu")
		(net "M_G_CPU1_SB_DQ<28>")
	)
	(arc
		(start 146.340576 -291.888418)
		(mid 146.364053 -291.887042)
		(end 146.387566 -291.88664)
		(width 0.0762)
		(layer "F.Cu")
		(net "M_G_CPU1_SB_DQ<28>")
	)
	(arc
		(start 146.104864 -291.96284)
		(mid 146.218588 -291.912539)
		(end 146.340576 -291.888418)
		(width 0.0762)
		(layer "F.Cu")
		(net "M_G_CPU1_SB_DQ<28>")
	)
	(segment
		(start 161.410396 -308.50078)
		(end 161.293302 -308.617874)
		(width 0.10668)
		(layer "F.Cu")
		(net "M_G_CPU1_SB_DQ<27>")
	)
	(segment
		(start 148.406866 -289.827208)
		(end 150.279354 -291.699696)
		(width 0.10668)
		(layer "F.Cu")
		(net "M_G_CPU1_SB_DQ<27>")
	)
	(segment
		(start 146.562572 -289.827208)
		(end 147.686522 -289.827208)
		(width 0.0762)
		(layer "F.Cu")
		(net "M_G_CPU1_SB_DQ<27>")
	)
	(segment
		(start 147.686522 -289.827208)
		(end 148.406866 -289.827208)
		(width 0.10668)
		(layer "F.Cu")
		(net "M_G_CPU1_SB_DQ<27>")
	)
	(segment
		(start 159.836104 -306.761388)
		(end 161.410396 -308.33568)
		(width 0.10668)
		(layer "F.Cu")
		(net "M_G_CPU1_SB_DQ<27>")
	)
	(segment
		(start 159.671004 -307.325776)
		(end 159.55391 -307.44287)
		(width 0.10668)
		(layer "F.Cu")
		(net "M_G_CPU1_SB_DQ<27>")
	)
	(segment
		(start 159.836104 -307.325776)
		(end 159.671004 -307.325776)
		(width 0.10668)
		(layer "F.Cu")
		(net "M_G_CPU1_SB_DQ<27>")
	)
	(segment
		(start 159.271716 -307.160676)
		(end 159.671004 -306.761388)
		(width 0.10668)
		(layer "F.Cu")
		(net "M_G_CPU1_SB_DQ<27>")
	)
	(segment
		(start 146.096482 -289.692842)
		(end 146.104864 -289.697668)
		(width 0.0762)
		(layer "F.Cu")
		(net "M_G_CPU1_SB_DQ<27>")
	)
	(segment
		(start 150.279354 -298.333414)
		(end 159.106616 -307.160676)
		(width 0.10668)
		(layer "F.Cu")
		(net "M_G_CPU1_SB_DQ<27>")
	)
	(segment
		(start 161.293302 -308.617874)
		(end 161.128202 -308.617874)
		(width 0.10668)
		(layer "F.Cu")
		(net "M_G_CPU1_SB_DQ<27>")
	)
	(segment
		(start 164.031168 -312.085228)
		(end 164.427916 -312.085228)
		(width 0.10668)
		(layer "F.Cu")
		(net "M_G_CPU1_SB_DQ<27>")
	)
	(segment
		(start 150.279354 -291.699696)
		(end 150.279354 -298.333414)
		(width 0.10668)
		(layer "F.Cu")
		(net "M_G_CPU1_SB_DQ<27>")
	)
	(segment
		(start 159.55391 -307.44287)
		(end 159.55391 -307.60797)
		(width 0.10668)
		(layer "F.Cu")
		(net "M_G_CPU1_SB_DQ<27>")
	)
	(segment
		(start 159.671004 -306.761388)
		(end 159.836104 -306.761388)
		(width 0.10668)
		(layer "F.Cu")
		(net "M_G_CPU1_SB_DQ<27>")
	)
	(segment
		(start 159.106616 -307.160676)
		(end 159.271716 -307.160676)
		(width 0.10668)
		(layer "F.Cu")
		(net "M_G_CPU1_SB_DQ<27>")
	)
	(segment
		(start 161.410396 -308.33568)
		(end 161.410396 -308.50078)
		(width 0.10668)
		(layer "F.Cu")
		(net "M_G_CPU1_SB_DQ<27>")
	)
	(segment
		(start 161.128202 -308.617874)
		(end 159.836104 -307.325776)
		(width 0.10668)
		(layer "F.Cu")
		(net "M_G_CPU1_SB_DQ<27>")
	)
	(segment
		(start 159.55391 -307.60797)
		(end 164.031168 -312.085228)
		(width 0.10668)
		(layer "F.Cu")
		(net "M_G_CPU1_SB_DQ<27>")
	)
	(arc
		(start 146.315938 -289.790378)
		(mid 146.437887 -289.817955)
		(end 146.562572 -289.827208)
		(width 0.0762)
		(layer "F.Cu")
		(net "M_G_CPU1_SB_DQ<27>")
	)
	(arc
		(start 146.104864 -289.697668)
		(mid 146.207758 -289.75004)
		(end 146.315938 -289.790378)
		(width 0.0762)
		(layer "F.Cu")
		(net "M_G_CPU1_SB_DQ<27>")
	)
	(arc
		(start 144.037812 -290.020248)
		(mid 144.233161 -289.836429)
		(end 144.493996 -289.773868)
		(width 0.0762)
		(layer "F.Cu")
		(net "M_G_CPU1_SB_DQ<27>")
	)
	(arc
		(start 144.790922 -289.697668)
		(mid 144.977866 -289.647413)
		(end 145.16481 -289.697668)
		(width 0.0762)
		(layer "F.Cu")
		(net "M_G_CPU1_SB_DQ<27>")
	)
	(arc
		(start 145.16481 -289.697668)
		(mid 145.447766 -289.773845)
		(end 145.730722 -289.697668)
		(width 0.0762)
		(layer "F.Cu")
		(net "M_G_CPU1_SB_DQ<27>")
	)
	(arc
		(start 145.730722 -289.697668)
		(mid 145.912973 -289.647318)
		(end 146.096482 -289.692842)
		(width 0.0762)
		(layer "F.Cu")
		(net "M_G_CPU1_SB_DQ<27>")
	)
	(arc
		(start 144.493996 -289.773868)
		(mid 144.647745 -289.756359)
		(end 144.790922 -289.697668)
		(width 0.0762)
		(layer "F.Cu")
		(net "M_G_CPU1_SB_DQ<27>")
	)
	(segment
		(start 158.176214 -304.067718)
		(end 162.091116 -307.98262)
		(width 0.10668)
		(layer "F.Cu")
		(net "M_G_CPU1_SB_DQ<26>")
	)
	(segment
		(start 158.011114 -304.067718)
		(end 158.176214 -304.067718)
		(width 0.10668)
		(layer "F.Cu")
		(net "M_G_CPU1_SB_DQ<26>")
	)
	(segment
		(start 162.091116 -308.922928)
		(end 162.226752 -309.058564)
		(width 0.10668)
		(layer "F.Cu")
		(net "M_G_CPU1_SB_DQ<26>")
	)
	(segment
		(start 148.751798 -289.146488)
		(end 150.960074 -291.354764)
		(width 0.10668)
		(layer "F.Cu")
		(net "M_G_CPU1_SB_DQ<26>")
	)
	(segment
		(start 162.226752 -309.058564)
		(end 162.391852 -309.058564)
		(width 0.10668)
		(layer "F.Cu")
		(net "M_G_CPU1_SB_DQ<26>")
	)
	(segment
		(start 159.342582 -305.963574)
		(end 159.342582 -305.798474)
		(width 0.10668)
		(layer "F.Cu")
		(net "M_G_CPU1_SB_DQ<26>")
	)
	(segment
		(start 162.67811 -308.772306)
		(end 162.84321 -308.772306)
		(width 0.10668)
		(layer "F.Cu")
		(net "M_G_CPU1_SB_DQ<26>")
	)
	(segment
		(start 147.525232 -289.146488)
		(end 147.738592 -289.146488)
		(width 0.0762)
		(layer "F.Cu")
		(net "M_G_CPU1_SB_DQ<26>")
	)
	(segment
		(start 162.960304 -308.8894)
		(end 162.960304 -309.0545)
		(width 0.10668)
		(layer "F.Cu")
		(net "M_G_CPU1_SB_DQ<26>")
	)
	(segment
		(start 162.091116 -307.98262)
		(end 162.091116 -308.922928)
		(width 0.10668)
		(layer "F.Cu")
		(net "M_G_CPU1_SB_DQ<26>")
	)
	(segment
		(start 147.21586 -288.837116)
		(end 147.525232 -289.146488)
		(width 0.0762)
		(layer "F.Cu")
		(net "M_G_CPU1_SB_DQ<26>")
	)
	(segment
		(start 157.89402 -304.349912)
		(end 157.89402 -304.184812)
		(width 0.10668)
		(layer "F.Cu")
		(net "M_G_CPU1_SB_DQ<26>")
	)
	(segment
		(start 162.674046 -309.340758)
		(end 162.674046 -309.505858)
		(width 0.10668)
		(layer "F.Cu")
		(net "M_G_CPU1_SB_DQ<26>")
	)
	(segment
		(start 150.960074 -291.354764)
		(end 150.960074 -297.980354)
		(width 0.10668)
		(layer "F.Cu")
		(net "M_G_CPU1_SB_DQ<26>")
	)
	(segment
		(start 162.674046 -309.505858)
		(end 163.553394 -310.385206)
		(width 0.10668)
		(layer "F.Cu")
		(net "M_G_CPU1_SB_DQ<26>")
	)
	(segment
		(start 159.060388 -306.080668)
		(end 159.225488 -306.080668)
		(width 0.10668)
		(layer "F.Cu")
		(net "M_G_CPU1_SB_DQ<26>")
	)
	(segment
		(start 159.342582 -305.798474)
		(end 157.89402 -304.349912)
		(width 0.10668)
		(layer "F.Cu")
		(net "M_G_CPU1_SB_DQ<26>")
	)
	(segment
		(start 159.225488 -306.080668)
		(end 159.342582 -305.963574)
		(width 0.10668)
		(layer "F.Cu")
		(net "M_G_CPU1_SB_DQ<26>")
	)
	(segment
		(start 147.738592 -289.146488)
		(end 148.751798 -289.146488)
		(width 0.10668)
		(layer "F.Cu")
		(net "M_G_CPU1_SB_DQ<26>")
	)
	(segment
		(start 162.84321 -308.772306)
		(end 162.960304 -308.8894)
		(width 0.10668)
		(layer "F.Cu")
		(net "M_G_CPU1_SB_DQ<26>")
	)
	(segment
		(start 162.391852 -309.058564)
		(end 162.67811 -308.772306)
		(width 0.10668)
		(layer "F.Cu")
		(net "M_G_CPU1_SB_DQ<26>")
	)
	(segment
		(start 146.38782 -288.837116)
		(end 147.21586 -288.837116)
		(width 0.0762)
		(layer "F.Cu")
		(net "M_G_CPU1_SB_DQ<26>")
	)
	(segment
		(start 157.89402 -304.184812)
		(end 158.011114 -304.067718)
		(width 0.10668)
		(layer "F.Cu")
		(net "M_G_CPU1_SB_DQ<26>")
	)
	(segment
		(start 163.553394 -310.385206)
		(end 164.427916 -310.385206)
		(width 0.10668)
		(layer "F.Cu")
		(net "M_G_CPU1_SB_DQ<26>")
	)
	(segment
		(start 150.960074 -297.980354)
		(end 159.060388 -306.080668)
		(width 0.10668)
		(layer "F.Cu")
		(net "M_G_CPU1_SB_DQ<26>")
	)
	(segment
		(start 162.960304 -309.0545)
		(end 162.674046 -309.340758)
		(width 0.10668)
		(layer "F.Cu")
		(net "M_G_CPU1_SB_DQ<26>")
	)
	(arc
		(start 145.976848 -288.960814)
		(mid 145.996197 -288.958476)
		(end 146.015456 -288.95548)
		(width 0.0762)
		(layer "F.Cu")
		(net "M_G_CPU1_SB_DQ<26>")
	)
	(arc
		(start 145.447766 -289.210242)
		(mid 145.691197 -289.040755)
		(end 145.976848 -288.960814)
		(width 0.0762)
		(layer "F.Cu")
		(net "M_G_CPU1_SB_DQ<26>")
	)
	(arc
		(start 146.015456 -288.95548)
		(mid 146.111165 -288.929768)
		(end 146.200876 -288.887662)
		(width 0.0762)
		(layer "F.Cu")
		(net "M_G_CPU1_SB_DQ<26>")
	)
	(arc
		(start 146.200876 -288.887662)
		(mid 146.276116 -288.854349)
		(end 146.356832 -288.838386)
		(width 0.0762)
		(layer "F.Cu")
		(net "M_G_CPU1_SB_DQ<26>")
	)
	(arc
		(start 146.356832 -288.838386)
		(mid 146.372313 -288.83743)
		(end 146.38782 -288.837116)
		(width 0.0762)
		(layer "F.Cu")
		(net "M_G_CPU1_SB_DQ<26>")
	)
	(segment
		(start 145.260822 -289.532822)
		(end 145.261076 -289.532822)
		(width 0.0762)
		(layer "F.Cu")
		(net "M_G_CPU1_SB_DQ<25>")
	)
	(segment
		(start 148.610574 -289.486848)
		(end 150.619714 -291.495988)
		(width 0.10668)
		(layer "F.Cu")
		(net "M_G_CPU1_SB_DQ<25>")
	)
	(segment
		(start 161.750756 -308.123844)
		(end 161.750756 -309.25262)
		(width 0.10668)
		(layer "F.Cu")
		(net "M_G_CPU1_SB_DQ<25>")
	)
	(segment
		(start 165.719506 -310.810402)
		(end 166.144448 -311.235344)
		(width 0.101346)
		(layer "F.Cu")
		(net "M_G_CPU1_SB_DQ<25>")
	)
	(segment
		(start 166.144448 -311.235344)
		(end 168.527984 -311.235344)
		(width 0.101346)
		(layer "F.Cu")
		(net "M_G_CPU1_SB_DQ<25>")
	)
	(segment
		(start 144.686528 -289.537648)
		(end 144.69491 -289.532822)
		(width 0.0762)
		(layer "F.Cu")
		(net "M_G_CPU1_SB_DQ<25>")
	)
	(segment
		(start 150.619714 -298.121578)
		(end 158.919164 -306.421028)
		(width 0.10668)
		(layer "F.Cu")
		(net "M_G_CPU1_SB_DQ<25>")
	)
	(segment
		(start 161.750756 -309.25262)
		(end 163.308538 -310.810402)
		(width 0.10668)
		(layer "F.Cu")
		(net "M_G_CPU1_SB_DQ<25>")
	)
	(segment
		(start 163.308538 -310.810402)
		(end 165.719506 -310.810402)
		(width 0.101346)
		(layer "F.Cu")
		(net "M_G_CPU1_SB_DQ<25>")
	)
	(segment
		(start 158.919164 -306.421028)
		(end 160.04794 -306.421028)
		(width 0.10668)
		(layer "F.Cu")
		(net "M_G_CPU1_SB_DQ<25>")
	)
	(segment
		(start 146.358356 -289.590988)
		(end 147.248626 -289.592258)
		(width 0.0762)
		(layer "F.Cu")
		(net "M_G_CPU1_SB_DQ<25>")
	)
	(segment
		(start 150.619714 -291.495988)
		(end 150.619714 -298.121578)
		(width 0.10668)
		(layer "F.Cu")
		(net "M_G_CPU1_SB_DQ<25>")
	)
	(segment
		(start 147.248626 -289.592258)
		(end 147.361656 -289.592258)
		(width 0.0762)
		(layer "F.Cu")
		(net "M_G_CPU1_SB_DQ<25>")
	)
	(segment
		(start 144.507966 -289.210242)
		(end 144.399508 -289.396932)
		(width 0.0762)
		(layer "F.Cu")
		(net "M_G_CPU1_SB_DQ<25>")
	)
	(segment
		(start 147.467066 -289.486848)
		(end 147.71243 -289.486848)
		(width 0.0762)
		(layer "F.Cu")
		(net "M_G_CPU1_SB_DQ<25>")
	)
	(segment
		(start 147.361656 -289.592258)
		(end 147.467066 -289.486848)
		(width 0.0762)
		(layer "F.Cu")
		(net "M_G_CPU1_SB_DQ<25>")
	)
	(segment
		(start 147.71243 -289.486848)
		(end 148.610574 -289.486848)
		(width 0.10668)
		(layer "F.Cu")
		(net "M_G_CPU1_SB_DQ<25>")
	)
	(segment
		(start 160.04794 -306.421028)
		(end 161.750756 -308.123844)
		(width 0.10668)
		(layer "F.Cu")
		(net "M_G_CPU1_SB_DQ<25>")
	)
	(arc
		(start 146.283426 -289.574986)
		(mid 146.320054 -289.586916)
		(end 146.358356 -289.590988)
		(width 0.0762)
		(layer "F.Cu")
		(net "M_G_CPU1_SB_DQ<25>")
	)
	(arc
		(start 144.399508 -289.396932)
		(mid 144.425425 -289.529974)
		(end 144.551146 -289.580574)
		(width 0.0762)
		(layer "F.Cu")
		(net "M_G_CPU1_SB_DQ<25>")
	)
	(arc
		(start 146.200876 -289.532822)
		(mid 146.24157 -289.555041)
		(end 146.283426 -289.574986)
		(width 0.0762)
		(layer "F.Cu")
		(net "M_G_CPU1_SB_DQ<25>")
	)
	(arc
		(start 145.261076 -289.532822)
		(mid 145.44802 -289.583146)
		(end 145.634964 -289.532822)
		(width 0.0762)
		(layer "F.Cu")
		(net "M_G_CPU1_SB_DQ<25>")
	)
	(arc
		(start 144.69491 -289.532822)
		(mid 144.977866 -289.456645)
		(end 145.260822 -289.532822)
		(width 0.0762)
		(layer "F.Cu")
		(net "M_G_CPU1_SB_DQ<25>")
	)
	(arc
		(start 145.634964 -289.532822)
		(mid 145.91792 -289.456645)
		(end 146.200876 -289.532822)
		(width 0.0762)
		(layer "F.Cu")
		(net "M_G_CPU1_SB_DQ<25>")
	)
	(arc
		(start 144.551146 -289.580574)
		(mid 144.6209 -289.565617)
		(end 144.686528 -289.537648)
		(width 0.0762)
		(layer "F.Cu")
		(net "M_G_CPU1_SB_DQ<25>")
	)
	(segment
		(start 166.055548 -309.535322)
		(end 166.170864 -309.650638)
		(width 0.101346)
		(layer "F.Cu")
		(net "M_G_CPU1_SB_DQ<24>")
	)
	(segment
		(start 163.610036 -309.960264)
		(end 165.386512 -309.960264)
		(width 0.101346)
		(layer "F.Cu")
		(net "M_G_CPU1_SB_DQ<24>")
	)
	(segment
		(start 151.300434 -291.21354)
		(end 151.300434 -297.467274)
		(width 0.10668)
		(layer "F.Cu")
		(net "M_G_CPU1_SB_DQ<24>")
	)
	(segment
		(start 166.170864 -309.650638)
		(end 166.170864 -310.07431)
		(width 0.101346)
		(layer "F.Cu")
		(net "M_G_CPU1_SB_DQ<24>")
	)
	(segment
		(start 165.811454 -309.535322)
		(end 166.055548 -309.535322)
		(width 0.101346)
		(layer "F.Cu")
		(net "M_G_CPU1_SB_DQ<24>")
	)
	(segment
		(start 166.170864 -310.07431)
		(end 166.28618 -310.189626)
		(width 0.101346)
		(layer "F.Cu")
		(net "M_G_CPU1_SB_DQ<24>")
	)
	(segment
		(start 163.32073 -308.73065)
		(end 163.32073 -309.670958)
		(width 0.10668)
		(layer "F.Cu")
		(net "M_G_CPU1_SB_DQ<24>")
	)
	(segment
		(start 147.294854 -288.646616)
		(end 147.454366 -288.806128)
		(width 0.0762)
		(layer "F.Cu")
		(net "M_G_CPU1_SB_DQ<24>")
	)
	(segment
		(start 163.44773 -309.797958)
		(end 163.610036 -309.960264)
		(width 0.101346)
		(layer "F.Cu")
		(net "M_G_CPU1_SB_DQ<24>")
	)
	(segment
		(start 167.07358 -310.189626)
		(end 167.236648 -310.189626)
		(width 0.101346)
		(layer "F.Cu")
		(net "M_G_CPU1_SB_DQ<24>")
	)
	(segment
		(start 146.387566 -288.646616)
		(end 147.294854 -288.646616)
		(width 0.0762)
		(layer "F.Cu")
		(net "M_G_CPU1_SB_DQ<24>")
	)
	(segment
		(start 166.564564 -310.07431)
		(end 166.564564 -309.650638)
		(width 0.101346)
		(layer "F.Cu")
		(net "M_G_CPU1_SB_DQ<24>")
	)
	(segment
		(start 147.702524 -288.806128)
		(end 148.893022 -288.806128)
		(width 0.10668)
		(layer "F.Cu")
		(net "M_G_CPU1_SB_DQ<24>")
	)
	(segment
		(start 167.46728 -309.535322)
		(end 168.527984 -309.535322)
		(width 0.101346)
		(layer "F.Cu")
		(net "M_G_CPU1_SB_DQ<24>")
	)
	(segment
		(start 157.560518 -303.727358)
		(end 158.317438 -303.727358)
		(width 0.10668)
		(layer "F.Cu")
		(net "M_G_CPU1_SB_DQ<24>")
	)
	(segment
		(start 167.351964 -309.650638)
		(end 167.46728 -309.535322)
		(width 0.101346)
		(layer "F.Cu")
		(net "M_G_CPU1_SB_DQ<24>")
	)
	(segment
		(start 146.096482 -288.727642)
		(end 146.104864 -288.722816)
		(width 0.0762)
		(layer "F.Cu")
		(net "M_G_CPU1_SB_DQ<24>")
	)
	(segment
		(start 166.564564 -309.650638)
		(end 166.67988 -309.535322)
		(width 0.101346)
		(layer "F.Cu")
		(net "M_G_CPU1_SB_DQ<24>")
	)
	(segment
		(start 158.317438 -303.727358)
		(end 163.32073 -308.73065)
		(width 0.10668)
		(layer "F.Cu")
		(net "M_G_CPU1_SB_DQ<24>")
	)
	(segment
		(start 166.28618 -310.189626)
		(end 166.449248 -310.189626)
		(width 0.101346)
		(layer "F.Cu")
		(net "M_G_CPU1_SB_DQ<24>")
	)
	(segment
		(start 167.351964 -310.07431)
		(end 167.351964 -309.650638)
		(width 0.101346)
		(layer "F.Cu")
		(net "M_G_CPU1_SB_DQ<24>")
	)
	(segment
		(start 166.958264 -310.07431)
		(end 167.07358 -310.189626)
		(width 0.101346)
		(layer "F.Cu")
		(net "M_G_CPU1_SB_DQ<24>")
	)
	(segment
		(start 163.32073 -309.670958)
		(end 163.44773 -309.797958)
		(width 0.10668)
		(layer "F.Cu")
		(net "M_G_CPU1_SB_DQ<24>")
	)
	(segment
		(start 151.300434 -297.467274)
		(end 157.560518 -303.727358)
		(width 0.10668)
		(layer "F.Cu")
		(net "M_G_CPU1_SB_DQ<24>")
	)
	(segment
		(start 145.91792 -288.400236)
		(end 145.815558 -288.576512)
		(width 0.0762)
		(layer "F.Cu")
		(net "M_G_CPU1_SB_DQ<24>")
	)
	(segment
		(start 148.893022 -288.806128)
		(end 151.300434 -291.21354)
		(width 0.10668)
		(layer "F.Cu")
		(net "M_G_CPU1_SB_DQ<24>")
	)
	(segment
		(start 167.236648 -310.189626)
		(end 167.351964 -310.07431)
		(width 0.101346)
		(layer "F.Cu")
		(net "M_G_CPU1_SB_DQ<24>")
	)
	(segment
		(start 165.386512 -309.960264)
		(end 165.811454 -309.535322)
		(width 0.101346)
		(layer "F.Cu")
		(net "M_G_CPU1_SB_DQ<24>")
	)
	(segment
		(start 147.454366 -288.806128)
		(end 147.702524 -288.806128)
		(width 0.0762)
		(layer "F.Cu")
		(net "M_G_CPU1_SB_DQ<24>")
	)
	(segment
		(start 166.449248 -310.189626)
		(end 166.564564 -310.07431)
		(width 0.101346)
		(layer "F.Cu")
		(net "M_G_CPU1_SB_DQ<24>")
	)
	(segment
		(start 166.958264 -309.650638)
		(end 166.958264 -310.07431)
		(width 0.101346)
		(layer "F.Cu")
		(net "M_G_CPU1_SB_DQ<24>")
	)
	(segment
		(start 166.67988 -309.535322)
		(end 166.842948 -309.535322)
		(width 0.101346)
		(layer "F.Cu")
		(net "M_G_CPU1_SB_DQ<24>")
	)
	(segment
		(start 166.842948 -309.535322)
		(end 166.958264 -309.650638)
		(width 0.101346)
		(layer "F.Cu")
		(net "M_G_CPU1_SB_DQ<24>")
	)
	(arc
		(start 146.104864 -288.722816)
		(mid 146.218588 -288.672515)
		(end 146.340576 -288.648394)
		(width 0.0762)
		(layer "F.Cu")
		(net "M_G_CPU1_SB_DQ<24>")
	)
	(arc
		(start 146.340576 -288.648394)
		(mid 146.364053 -288.647018)
		(end 146.387566 -288.646616)
		(width 0.0762)
		(layer "F.Cu")
		(net "M_G_CPU1_SB_DQ<24>")
	)
	(arc
		(start 145.815558 -288.576512)
		(mid 145.845187 -288.718999)
		(end 145.982436 -288.76752)
		(width 0.0762)
		(layer "F.Cu")
		(net "M_G_CPU1_SB_DQ<24>")
	)
	(arc
		(start 145.982436 -288.76752)
		(mid 146.041082 -288.752227)
		(end 146.096482 -288.727642)
		(width 0.0762)
		(layer "F.Cu")
		(net "M_G_CPU1_SB_DQ<24>")
	)
	(segment
		(start 157.729174 -302.49241)
		(end 157.846268 -302.609504)
		(width 0.10668)
		(layer "F.Cu")
		(net "M_G_CPU1_SB_DQ<23>")
	)
	(segment
		(start 147.94738 -288.348928)
		(end 149.090126 -288.348928)
		(width 0.10668)
		(layer "F.Cu")
		(net "M_G_CPU1_SB_DQ<23>")
	)
	(segment
		(start 151.757634 -297.27779)
		(end 155.49245 -301.012606)
		(width 0.10668)
		(layer "F.Cu")
		(net "M_G_CPU1_SB_DQ<23>")
	)
	(segment
		(start 151.757634 -291.016436)
		(end 151.757634 -297.27779)
		(width 0.10668)
		(layer "F.Cu")
		(net "M_G_CPU1_SB_DQ<23>")
	)
	(segment
		(start 155.65755 -301.012606)
		(end 155.87091 -300.799246)
		(width 0.10668)
		(layer "F.Cu")
		(net "M_G_CPU1_SB_DQ<23>")
	)
	(segment
		(start 163.922202 -308.685438)
		(end 164.427916 -308.685438)
		(width 0.10668)
		(layer "F.Cu")
		(net "M_G_CPU1_SB_DQ<23>")
	)
	(segment
		(start 156.999686 -301.928022)
		(end 157.164786 -301.928022)
		(width 0.10668)
		(layer "F.Cu")
		(net "M_G_CPU1_SB_DQ<23>")
	)
	(segment
		(start 156.504132 -301.859188)
		(end 156.504132 -302.024288)
		(width 0.10668)
		(layer "F.Cu")
		(net "M_G_CPU1_SB_DQ<23>")
	)
	(segment
		(start 157.28188 -302.045116)
		(end 157.28188 -302.210216)
		(width 0.10668)
		(layer "F.Cu")
		(net "M_G_CPU1_SB_DQ<23>")
	)
	(segment
		(start 157.846268 -302.609504)
		(end 157.846268 -302.774604)
		(width 0.10668)
		(layer "F.Cu")
		(net "M_G_CPU1_SB_DQ<23>")
	)
	(segment
		(start 157.915102 -303.270158)
		(end 158.128462 -303.056798)
		(width 0.10668)
		(layer "F.Cu")
		(net "M_G_CPU1_SB_DQ<23>")
	)
	(segment
		(start 157.846268 -302.774604)
		(end 157.632908 -302.987964)
		(width 0.10668)
		(layer "F.Cu")
		(net "M_G_CPU1_SB_DQ<23>")
	)
	(segment
		(start 156.03601 -300.799246)
		(end 156.153104 -300.91634)
		(width 0.10668)
		(layer "F.Cu")
		(net "M_G_CPU1_SB_DQ<23>")
	)
	(segment
		(start 157.564074 -302.49241)
		(end 157.729174 -302.49241)
		(width 0.10668)
		(layer "F.Cu")
		(net "M_G_CPU1_SB_DQ<23>")
	)
	(segment
		(start 149.090126 -288.348928)
		(end 151.757634 -291.016436)
		(width 0.10668)
		(layer "F.Cu")
		(net "M_G_CPU1_SB_DQ<23>")
	)
	(segment
		(start 155.49245 -301.012606)
		(end 155.65755 -301.012606)
		(width 0.10668)
		(layer "F.Cu")
		(net "M_G_CPU1_SB_DQ<23>")
	)
	(segment
		(start 156.600398 -301.363634)
		(end 156.717492 -301.480728)
		(width 0.10668)
		(layer "F.Cu")
		(net "M_G_CPU1_SB_DQ<23>")
	)
	(segment
		(start 157.632908 -302.987964)
		(end 157.632908 -303.153064)
		(width 0.10668)
		(layer "F.Cu")
		(net "M_G_CPU1_SB_DQ<23>")
	)
	(segment
		(start 156.056838 -301.576994)
		(end 156.221938 -301.576994)
		(width 0.10668)
		(layer "F.Cu")
		(net "M_G_CPU1_SB_DQ<23>")
	)
	(segment
		(start 157.185614 -302.70577)
		(end 157.350714 -302.70577)
		(width 0.10668)
		(layer "F.Cu")
		(net "M_G_CPU1_SB_DQ<23>")
	)
	(segment
		(start 147.245832 -288.181796)
		(end 147.412964 -288.348928)
		(width 0.0762)
		(layer "F.Cu")
		(net "M_G_CPU1_SB_DQ<23>")
	)
	(segment
		(start 146.39163 -288.181796)
		(end 147.245832 -288.181796)
		(width 0.0762)
		(layer "F.Cu")
		(net "M_G_CPU1_SB_DQ<23>")
	)
	(segment
		(start 157.06852 -302.423576)
		(end 157.06852 -302.588676)
		(width 0.10668)
		(layer "F.Cu")
		(net "M_G_CPU1_SB_DQ<23>")
	)
	(segment
		(start 157.350714 -302.70577)
		(end 157.564074 -302.49241)
		(width 0.10668)
		(layer "F.Cu")
		(net "M_G_CPU1_SB_DQ<23>")
	)
	(segment
		(start 157.750002 -303.270158)
		(end 157.915102 -303.270158)
		(width 0.10668)
		(layer "F.Cu")
		(net "M_G_CPU1_SB_DQ<23>")
	)
	(segment
		(start 156.221938 -301.576994)
		(end 156.435298 -301.363634)
		(width 0.10668)
		(layer "F.Cu")
		(net "M_G_CPU1_SB_DQ<23>")
	)
	(segment
		(start 156.621226 -302.141382)
		(end 156.786326 -302.141382)
		(width 0.10668)
		(layer "F.Cu")
		(net "M_G_CPU1_SB_DQ<23>")
	)
	(segment
		(start 157.164786 -301.928022)
		(end 157.28188 -302.045116)
		(width 0.10668)
		(layer "F.Cu")
		(net "M_G_CPU1_SB_DQ<23>")
	)
	(segment
		(start 156.717492 -301.480728)
		(end 156.717492 -301.645828)
		(width 0.10668)
		(layer "F.Cu")
		(net "M_G_CPU1_SB_DQ<23>")
	)
	(segment
		(start 156.153104 -300.91634)
		(end 156.153104 -301.08144)
		(width 0.10668)
		(layer "F.Cu")
		(net "M_G_CPU1_SB_DQ<23>")
	)
	(segment
		(start 155.939744 -301.2948)
		(end 155.939744 -301.4599)
		(width 0.10668)
		(layer "F.Cu")
		(net "M_G_CPU1_SB_DQ<23>")
	)
	(segment
		(start 157.28188 -302.210216)
		(end 157.06852 -302.423576)
		(width 0.10668)
		(layer "F.Cu")
		(net "M_G_CPU1_SB_DQ<23>")
	)
	(segment
		(start 158.293562 -303.056798)
		(end 163.922202 -308.685438)
		(width 0.10668)
		(layer "F.Cu")
		(net "M_G_CPU1_SB_DQ<23>")
	)
	(segment
		(start 157.632908 -303.153064)
		(end 157.750002 -303.270158)
		(width 0.10668)
		(layer "F.Cu")
		(net "M_G_CPU1_SB_DQ<23>")
	)
	(segment
		(start 156.717492 -301.645828)
		(end 156.504132 -301.859188)
		(width 0.10668)
		(layer "F.Cu")
		(net "M_G_CPU1_SB_DQ<23>")
	)
	(segment
		(start 156.153104 -301.08144)
		(end 155.939744 -301.2948)
		(width 0.10668)
		(layer "F.Cu")
		(net "M_G_CPU1_SB_DQ<23>")
	)
	(segment
		(start 156.504132 -302.024288)
		(end 156.621226 -302.141382)
		(width 0.10668)
		(layer "F.Cu")
		(net "M_G_CPU1_SB_DQ<23>")
	)
	(segment
		(start 147.412964 -288.348928)
		(end 147.94738 -288.348928)
		(width 0.0762)
		(layer "F.Cu")
		(net "M_G_CPU1_SB_DQ<23>")
	)
	(segment
		(start 158.128462 -303.056798)
		(end 158.293562 -303.056798)
		(width 0.10668)
		(layer "F.Cu")
		(net "M_G_CPU1_SB_DQ<23>")
	)
	(segment
		(start 146.096482 -288.073084)
		(end 146.104864 -288.07791)
		(width 0.0762)
		(layer "F.Cu")
		(net "M_G_CPU1_SB_DQ<23>")
	)
	(segment
		(start 156.435298 -301.363634)
		(end 156.600398 -301.363634)
		(width 0.10668)
		(layer "F.Cu")
		(net "M_G_CPU1_SB_DQ<23>")
	)
	(segment
		(start 156.786326 -302.141382)
		(end 156.999686 -301.928022)
		(width 0.10668)
		(layer "F.Cu")
		(net "M_G_CPU1_SB_DQ<23>")
	)
	(segment
		(start 155.939744 -301.4599)
		(end 156.056838 -301.576994)
		(width 0.10668)
		(layer "F.Cu")
		(net "M_G_CPU1_SB_DQ<23>")
	)
	(segment
		(start 155.87091 -300.799246)
		(end 156.03601 -300.799246)
		(width 0.10668)
		(layer "F.Cu")
		(net "M_G_CPU1_SB_DQ<23>")
	)
	(segment
		(start 157.06852 -302.588676)
		(end 157.185614 -302.70577)
		(width 0.10668)
		(layer "F.Cu")
		(net "M_G_CPU1_SB_DQ<23>")
	)
	(arc
		(start 146.104864 -288.07791)
		(mid 146.207758 -288.130282)
		(end 146.315938 -288.17062)
		(width 0.0762)
		(layer "F.Cu")
		(net "M_G_CPU1_SB_DQ<23>")
	)
	(arc
		(start 144.790922 -288.07791)
		(mid 144.977866 -288.027655)
		(end 145.16481 -288.07791)
		(width 0.0762)
		(layer "F.Cu")
		(net "M_G_CPU1_SB_DQ<23>")
	)
	(arc
		(start 145.16481 -288.07791)
		(mid 145.447766 -288.154087)
		(end 145.730722 -288.07791)
		(width 0.0762)
		(layer "F.Cu")
		(net "M_G_CPU1_SB_DQ<23>")
	)
	(arc
		(start 144.493996 -288.15411)
		(mid 144.647745 -288.136601)
		(end 144.790922 -288.07791)
		(width 0.0762)
		(layer "F.Cu")
		(net "M_G_CPU1_SB_DQ<23>")
	)
	(arc
		(start 144.037812 -288.400236)
		(mid 144.247894 -288.243791)
		(end 144.493996 -288.15411)
		(width 0.0762)
		(layer "F.Cu")
		(net "M_G_CPU1_SB_DQ<23>")
	)
	(arc
		(start 146.315938 -288.17062)
		(mid 146.353364 -288.179059)
		(end 146.39163 -288.181796)
		(width 0.0762)
		(layer "F.Cu")
		(net "M_G_CPU1_SB_DQ<23>")
	)
	(arc
		(start 145.730722 -288.07791)
		(mid 145.912973 -288.02756)
		(end 146.096482 -288.073084)
		(width 0.0762)
		(layer "F.Cu")
		(net "M_G_CPU1_SB_DQ<23>")
	)
	(segment
		(start 152.828244 -297.220132)
		(end 153.05278 -296.99585)
		(width 0.10668)
		(layer "F.Cu")
		(net "M_G_CPU1_SB_DQ<22>")
	)
	(segment
		(start 154.356308 -298.913296)
		(end 154.521408 -298.913296)
		(width 0.10668)
		(layer "F.Cu")
		(net "M_G_CPU1_SB_DQ<22>")
	)
	(segment
		(start 149.372574 -287.668208)
		(end 152.438354 -290.733988)
		(width 0.10668)
		(layer "F.Cu")
		(net "M_G_CPU1_SB_DQ<22>")
	)
	(segment
		(start 153.21788 -296.99585)
		(end 153.334974 -297.112944)
		(width 0.10668)
		(layer "F.Cu")
		(net "M_G_CPU1_SB_DQ<22>")
	)
	(segment
		(start 147.668234 -287.668208)
		(end 147.89531 -287.668208)
		(width 0.0762)
		(layer "F.Cu")
		(net "M_G_CPU1_SB_DQ<22>")
	)
	(segment
		(start 153.110438 -297.502326)
		(end 153.110438 -297.667426)
		(width 0.10668)
		(layer "F.Cu")
		(net "M_G_CPU1_SB_DQ<22>")
	)
	(segment
		(start 153.95702 -298.348908)
		(end 154.181556 -298.124626)
		(width 0.10668)
		(layer "F.Cu")
		(net "M_G_CPU1_SB_DQ<22>")
	)
	(segment
		(start 153.334974 -297.112944)
		(end 153.334974 -297.278044)
		(width 0.10668)
		(layer "F.Cu")
		(net "M_G_CPU1_SB_DQ<22>")
	)
	(segment
		(start 155.085796 -299.477684)
		(end 155.310332 -299.253402)
		(width 0.10668)
		(layer "F.Cu")
		(net "M_G_CPU1_SB_DQ<22>")
	)
	(segment
		(start 154.521408 -298.913296)
		(end 154.745944 -298.689014)
		(width 0.10668)
		(layer "F.Cu")
		(net "M_G_CPU1_SB_DQ<22>")
	)
	(segment
		(start 153.79192 -298.348908)
		(end 153.95702 -298.348908)
		(width 0.10668)
		(layer "F.Cu")
		(net "M_G_CPU1_SB_DQ<22>")
	)
	(segment
		(start 153.617168 -297.560238)
		(end 153.782268 -297.560238)
		(width 0.10668)
		(layer "F.Cu")
		(net "M_G_CPU1_SB_DQ<22>")
	)
	(segment
		(start 147.217384 -287.217358)
		(end 147.668234 -287.668208)
		(width 0.0762)
		(layer "F.Cu")
		(net "M_G_CPU1_SB_DQ<22>")
	)
	(segment
		(start 155.650184 -300.042072)
		(end 155.87472 -299.81779)
		(width 0.10668)
		(layer "F.Cu")
		(net "M_G_CPU1_SB_DQ<22>")
	)
	(segment
		(start 153.674826 -298.066714)
		(end 153.674826 -298.231814)
		(width 0.10668)
		(layer "F.Cu")
		(net "M_G_CPU1_SB_DQ<22>")
	)
	(segment
		(start 155.485084 -300.042072)
		(end 155.650184 -300.042072)
		(width 0.10668)
		(layer "F.Cu")
		(net "M_G_CPU1_SB_DQ<22>")
	)
	(segment
		(start 153.899362 -297.677332)
		(end 153.899362 -297.842432)
		(width 0.10668)
		(layer "F.Cu")
		(net "M_G_CPU1_SB_DQ<22>")
	)
	(segment
		(start 155.36799 -299.924978)
		(end 155.485084 -300.042072)
		(width 0.10668)
		(layer "F.Cu")
		(net "M_G_CPU1_SB_DQ<22>")
	)
	(segment
		(start 155.87472 -299.81779)
		(end 156.03982 -299.81779)
		(width 0.10668)
		(layer "F.Cu")
		(net "M_G_CPU1_SB_DQ<22>")
	)
	(segment
		(start 152.770586 -296.548556)
		(end 152.770586 -296.713656)
		(width 0.10668)
		(layer "F.Cu")
		(net "M_G_CPU1_SB_DQ<22>")
	)
	(segment
		(start 155.475432 -299.253402)
		(end 155.592526 -299.370496)
		(width 0.10668)
		(layer "F.Cu")
		(net "M_G_CPU1_SB_DQ<22>")
	)
	(segment
		(start 154.239214 -298.796202)
		(end 154.356308 -298.913296)
		(width 0.10668)
		(layer "F.Cu")
		(net "M_G_CPU1_SB_DQ<22>")
	)
	(segment
		(start 155.310332 -299.253402)
		(end 155.475432 -299.253402)
		(width 0.10668)
		(layer "F.Cu")
		(net "M_G_CPU1_SB_DQ<22>")
	)
	(segment
		(start 154.745944 -298.689014)
		(end 154.911044 -298.689014)
		(width 0.10668)
		(layer "F.Cu")
		(net "M_G_CPU1_SB_DQ<22>")
	)
	(segment
		(start 152.54605 -297.103038)
		(end 152.663144 -297.220132)
		(width 0.10668)
		(layer "F.Cu")
		(net "M_G_CPU1_SB_DQ<22>")
	)
	(segment
		(start 154.46375 -298.40682)
		(end 154.239214 -298.631102)
		(width 0.10668)
		(layer "F.Cu")
		(net "M_G_CPU1_SB_DQ<22>")
	)
	(segment
		(start 146.38782 -287.217358)
		(end 147.217384 -287.217358)
		(width 0.0762)
		(layer "F.Cu")
		(net "M_G_CPU1_SB_DQ<22>")
	)
	(segment
		(start 153.334974 -297.278044)
		(end 153.110438 -297.502326)
		(width 0.10668)
		(layer "F.Cu")
		(net "M_G_CPU1_SB_DQ<22>")
	)
	(segment
		(start 156.03982 -299.81779)
		(end 163.189158 -306.967128)
		(width 0.10668)
		(layer "F.Cu")
		(net "M_G_CPU1_SB_DQ<22>")
	)
	(segment
		(start 154.911044 -298.689014)
		(end 155.028138 -298.806108)
		(width 0.10668)
		(layer "F.Cu")
		(net "M_G_CPU1_SB_DQ<22>")
	)
	(segment
		(start 152.54605 -296.937938)
		(end 152.54605 -297.103038)
		(width 0.10668)
		(layer "F.Cu")
		(net "M_G_CPU1_SB_DQ<22>")
	)
	(segment
		(start 163.233354 -306.985416)
		(end 164.427916 -306.985416)
		(width 0.10668)
		(layer "F.Cu")
		(net "M_G_CPU1_SB_DQ<22>")
	)
	(segment
		(start 154.803602 -299.19549)
		(end 154.803602 -299.36059)
		(width 0.10668)
		(layer "F.Cu")
		(net "M_G_CPU1_SB_DQ<22>")
	)
	(segment
		(start 153.899362 -297.842432)
		(end 153.674826 -298.066714)
		(width 0.10668)
		(layer "F.Cu")
		(net "M_G_CPU1_SB_DQ<22>")
	)
	(segment
		(start 154.346656 -298.124626)
		(end 154.46375 -298.24172)
		(width 0.10668)
		(layer "F.Cu")
		(net "M_G_CPU1_SB_DQ<22>")
	)
	(segment
		(start 155.36799 -299.759878)
		(end 155.36799 -299.924978)
		(width 0.10668)
		(layer "F.Cu")
		(net "M_G_CPU1_SB_DQ<22>")
	)
	(segment
		(start 155.028138 -298.971208)
		(end 154.803602 -299.19549)
		(width 0.10668)
		(layer "F.Cu")
		(net "M_G_CPU1_SB_DQ<22>")
	)
	(segment
		(start 153.392632 -297.78452)
		(end 153.617168 -297.560238)
		(width 0.10668)
		(layer "F.Cu")
		(net "M_G_CPU1_SB_DQ<22>")
	)
	(segment
		(start 153.227532 -297.78452)
		(end 153.392632 -297.78452)
		(width 0.10668)
		(layer "F.Cu")
		(net "M_G_CPU1_SB_DQ<22>")
	)
	(segment
		(start 153.110438 -297.667426)
		(end 153.227532 -297.78452)
		(width 0.10668)
		(layer "F.Cu")
		(net "M_G_CPU1_SB_DQ<22>")
	)
	(segment
		(start 154.239214 -298.631102)
		(end 154.239214 -298.796202)
		(width 0.10668)
		(layer "F.Cu")
		(net "M_G_CPU1_SB_DQ<22>")
	)
	(segment
		(start 163.189158 -306.967128)
		(end 163.233354 -306.985416)
		(width 0.10668)
		(layer "F.Cu")
		(net "M_G_CPU1_SB_DQ<22>")
	)
	(segment
		(start 147.89531 -287.668208)
		(end 149.372574 -287.668208)
		(width 0.10668)
		(layer "F.Cu")
		(net "M_G_CPU1_SB_DQ<22>")
	)
	(segment
		(start 153.05278 -296.99585)
		(end 153.21788 -296.99585)
		(width 0.10668)
		(layer "F.Cu")
		(net "M_G_CPU1_SB_DQ<22>")
	)
	(segment
		(start 154.181556 -298.124626)
		(end 154.346656 -298.124626)
		(width 0.10668)
		(layer "F.Cu")
		(net "M_G_CPU1_SB_DQ<22>")
	)
	(segment
		(start 155.592526 -299.535596)
		(end 155.36799 -299.759878)
		(width 0.10668)
		(layer "F.Cu")
		(net "M_G_CPU1_SB_DQ<22>")
	)
	(segment
		(start 154.803602 -299.36059)
		(end 154.920696 -299.477684)
		(width 0.10668)
		(layer "F.Cu")
		(net "M_G_CPU1_SB_DQ<22>")
	)
	(segment
		(start 153.674826 -298.231814)
		(end 153.79192 -298.348908)
		(width 0.10668)
		(layer "F.Cu")
		(net "M_G_CPU1_SB_DQ<22>")
	)
	(segment
		(start 152.438354 -296.216324)
		(end 152.770586 -296.548556)
		(width 0.10668)
		(layer "F.Cu")
		(net "M_G_CPU1_SB_DQ<22>")
	)
	(segment
		(start 154.920696 -299.477684)
		(end 155.085796 -299.477684)
		(width 0.10668)
		(layer "F.Cu")
		(net "M_G_CPU1_SB_DQ<22>")
	)
	(segment
		(start 152.663144 -297.220132)
		(end 152.828244 -297.220132)
		(width 0.10668)
		(layer "F.Cu")
		(net "M_G_CPU1_SB_DQ<22>")
	)
	(segment
		(start 152.770586 -296.713656)
		(end 152.54605 -296.937938)
		(width 0.10668)
		(layer "F.Cu")
		(net "M_G_CPU1_SB_DQ<22>")
	)
	(segment
		(start 155.592526 -299.370496)
		(end 155.592526 -299.535596)
		(width 0.10668)
		(layer "F.Cu")
		(net "M_G_CPU1_SB_DQ<22>")
	)
	(segment
		(start 152.438354 -290.733988)
		(end 152.438354 -296.216324)
		(width 0.10668)
		(layer "F.Cu")
		(net "M_G_CPU1_SB_DQ<22>")
	)
	(segment
		(start 155.028138 -298.806108)
		(end 155.028138 -298.971208)
		(width 0.10668)
		(layer "F.Cu")
		(net "M_G_CPU1_SB_DQ<22>")
	)
	(segment
		(start 153.782268 -297.560238)
		(end 153.899362 -297.677332)
		(width 0.10668)
		(layer "F.Cu")
		(net "M_G_CPU1_SB_DQ<22>")
	)
	(segment
		(start 154.46375 -298.24172)
		(end 154.46375 -298.40682)
		(width 0.10668)
		(layer "F.Cu")
		(net "M_G_CPU1_SB_DQ<22>")
	)
	(arc
		(start 145.447766 -287.590484)
		(mid 145.691197 -287.420997)
		(end 145.976848 -287.341056)
		(width 0.0762)
		(layer "F.Cu")
		(net "M_G_CPU1_SB_DQ<22>")
	)
	(arc
		(start 146.015456 -287.335722)
		(mid 146.111165 -287.31001)
		(end 146.200876 -287.267904)
		(width 0.0762)
		(layer "F.Cu")
		(net "M_G_CPU1_SB_DQ<22>")
	)
	(arc
		(start 146.356832 -287.218628)
		(mid 146.372313 -287.217672)
		(end 146.38782 -287.217358)
		(width 0.0762)
		(layer "F.Cu")
		(net "M_G_CPU1_SB_DQ<22>")
	)
	(arc
		(start 145.976848 -287.341056)
		(mid 145.996197 -287.338718)
		(end 146.015456 -287.335722)
		(width 0.0762)
		(layer "F.Cu")
		(net "M_G_CPU1_SB_DQ<22>")
	)
	(arc
		(start 146.200876 -287.267904)
		(mid 146.276116 -287.234591)
		(end 146.356832 -287.218628)
		(width 0.0762)
		(layer "F.Cu")
		(net "M_G_CPU1_SB_DQ<22>")
	)
	(segment
		(start 163.15055 -307.410358)
		(end 163.377626 -307.410358)
		(width 0.10668)
		(layer "F.Cu")
		(net "M_G_CPU1_SB_DQ<21>")
	)
	(segment
		(start 167.650668 -307.8353)
		(end 168.527984 -307.8353)
		(width 0.101346)
		(layer "F.Cu")
		(net "M_G_CPU1_SB_DQ<21>")
	)
	(segment
		(start 152.097994 -290.875212)
		(end 152.097994 -297.136566)
		(width 0.10668)
		(layer "F.Cu")
		(net "M_G_CPU1_SB_DQ<21>")
	)
	(segment
		(start 149.23135 -288.008568)
		(end 152.097994 -290.875212)
		(width 0.10668)
		(layer "F.Cu")
		(net "M_G_CPU1_SB_DQ<21>")
	)
	(segment
		(start 144.507966 -287.590484)
		(end 144.399508 -287.777174)
		(width 0.0762)
		(layer "F.Cu")
		(net "M_G_CPU1_SB_DQ<21>")
	)
	(segment
		(start 145.260822 -287.913064)
		(end 145.261076 -287.913064)
		(width 0.0762)
		(layer "F.Cu")
		(net "M_G_CPU1_SB_DQ<21>")
	)
	(segment
		(start 155.34386 -300.382432)
		(end 156.122624 -300.382432)
		(width 0.10668)
		(layer "F.Cu")
		(net "M_G_CPU1_SB_DQ<21>")
	)
	(segment
		(start 147.248626 -287.9725)
		(end 147.396708 -287.9725)
		(width 0.0762)
		(layer "F.Cu")
		(net "M_G_CPU1_SB_DQ<21>")
	)
	(segment
		(start 163.377626 -307.410358)
		(end 165.514274 -307.410358)
		(width 0.101346)
		(layer "F.Cu")
		(net "M_G_CPU1_SB_DQ<21>")
	)
	(segment
		(start 152.097994 -297.136566)
		(end 155.34386 -300.382432)
		(width 0.10668)
		(layer "F.Cu")
		(net "M_G_CPU1_SB_DQ<21>")
	)
	(segment
		(start 147.432776 -288.008568)
		(end 147.913598 -288.008568)
		(width 0.0762)
		(layer "F.Cu")
		(net "M_G_CPU1_SB_DQ<21>")
	)
	(segment
		(start 144.686528 -287.91789)
		(end 144.69491 -287.913064)
		(width 0.0762)
		(layer "F.Cu")
		(net "M_G_CPU1_SB_DQ<21>")
	)
	(segment
		(start 147.913598 -288.008568)
		(end 149.23135 -288.008568)
		(width 0.10668)
		(layer "F.Cu")
		(net "M_G_CPU1_SB_DQ<21>")
	)
	(segment
		(start 147.396708 -287.9725)
		(end 147.432776 -288.008568)
		(width 0.0762)
		(layer "F.Cu")
		(net "M_G_CPU1_SB_DQ<21>")
	)
	(segment
		(start 165.514274 -307.410358)
		(end 167.650668 -307.8353)
		(width 0.101346)
		(layer "F.Cu")
		(net "M_G_CPU1_SB_DQ<21>")
	)
	(segment
		(start 156.122624 -300.382432)
		(end 163.15055 -307.410358)
		(width 0.10668)
		(layer "F.Cu")
		(net "M_G_CPU1_SB_DQ<21>")
	)
	(segment
		(start 146.358356 -287.97123)
		(end 147.248626 -287.9725)
		(width 0.0762)
		(layer "F.Cu")
		(net "M_G_CPU1_SB_DQ<21>")
	)
	(arc
		(start 144.551146 -287.960816)
		(mid 144.6209 -287.945859)
		(end 144.686528 -287.91789)
		(width 0.0762)
		(layer "F.Cu")
		(net "M_G_CPU1_SB_DQ<21>")
	)
	(arc
		(start 144.69491 -287.913064)
		(mid 144.977866 -287.836887)
		(end 145.260822 -287.913064)
		(width 0.0762)
		(layer "F.Cu")
		(net "M_G_CPU1_SB_DQ<21>")
	)
	(arc
		(start 145.261076 -287.913064)
		(mid 145.44802 -287.963388)
		(end 145.634964 -287.913064)
		(width 0.0762)
		(layer "F.Cu")
		(net "M_G_CPU1_SB_DQ<21>")
	)
	(arc
		(start 145.634964 -287.913064)
		(mid 145.91792 -287.836887)
		(end 146.200876 -287.913064)
		(width 0.0762)
		(layer "F.Cu")
		(net "M_G_CPU1_SB_DQ<21>")
	)
	(arc
		(start 146.200876 -287.913064)
		(mid 146.24157 -287.935283)
		(end 146.283426 -287.955228)
		(width 0.0762)
		(layer "F.Cu")
		(net "M_G_CPU1_SB_DQ<21>")
	)
	(arc
		(start 144.399508 -287.777174)
		(mid 144.425425 -287.910216)
		(end 144.551146 -287.960816)
		(width 0.0762)
		(layer "F.Cu")
		(net "M_G_CPU1_SB_DQ<21>")
	)
	(arc
		(start 146.283426 -287.955228)
		(mid 146.320054 -287.967158)
		(end 146.358356 -287.97123)
		(width 0.0762)
		(layer "F.Cu")
		(net "M_G_CPU1_SB_DQ<21>")
	)
	(segment
		(start 152.778714 -290.592764)
		(end 152.778714 -296.074846)
		(width 0.10668)
		(layer "F.Cu")
		(net "M_G_CPU1_SB_DQ<20>")
	)
	(segment
		(start 146.387566 -287.026858)
		(end 147.296378 -287.026858)
		(width 0.0762)
		(layer "F.Cu")
		(net "M_G_CPU1_SB_DQ<20>")
	)
	(segment
		(start 167.300148 -306.73167)
		(end 167.300148 -306.250594)
		(width 0.101346)
		(layer "F.Cu")
		(net "M_G_CPU1_SB_DQ<20>")
	)
	(segment
		(start 166.906448 -306.250594)
		(end 166.906448 -306.73167)
		(width 0.101346)
		(layer "F.Cu")
		(net "M_G_CPU1_SB_DQ<20>")
	)
	(segment
		(start 163.377626 -305.710336)
		(end 165.989254 -305.710336)
		(width 0.101346)
		(layer "F.Cu")
		(net "M_G_CPU1_SB_DQ<20>")
	)
	(segment
		(start 148.46808 -286.991806)
		(end 148.633434 -286.991806)
		(width 0.10668)
		(layer "F.Cu")
		(net "M_G_CPU1_SB_DQ<20>")
	)
	(segment
		(start 166.791132 -306.135278)
		(end 166.906448 -306.250594)
		(width 0.101346)
		(layer "F.Cu")
		(net "M_G_CPU1_SB_DQ<20>")
	)
	(segment
		(start 162.414204 -305.710336)
		(end 163.377626 -305.710336)
		(width 0.10668)
		(layer "F.Cu")
		(net "M_G_CPU1_SB_DQ<20>")
	)
	(segment
		(start 148.750274 -287.108646)
		(end 148.750274 -287.211008)
		(width 0.10668)
		(layer "F.Cu")
		(net "M_G_CPU1_SB_DQ<20>")
	)
	(segment
		(start 167.021764 -306.846986)
		(end 167.184832 -306.846986)
		(width 0.101346)
		(layer "F.Cu")
		(net "M_G_CPU1_SB_DQ<20>")
	)
	(segment
		(start 148.750274 -287.211008)
		(end 148.867114 -287.327848)
		(width 0.10668)
		(layer "F.Cu")
		(net "M_G_CPU1_SB_DQ<20>")
	)
	(segment
		(start 148.633434 -286.991806)
		(end 148.750274 -287.108646)
		(width 0.10668)
		(layer "F.Cu")
		(net "M_G_CPU1_SB_DQ<20>")
	)
	(segment
		(start 147.296378 -287.026858)
		(end 147.597368 -287.327848)
		(width 0.0762)
		(layer "F.Cu")
		(net "M_G_CPU1_SB_DQ<20>")
	)
	(segment
		(start 166.414196 -306.135278)
		(end 166.791132 -306.135278)
		(width 0.101346)
		(layer "F.Cu")
		(net "M_G_CPU1_SB_DQ<20>")
	)
	(segment
		(start 145.91792 -286.780478)
		(end 145.815558 -286.956754)
		(width 0.0762)
		(layer "F.Cu")
		(net "M_G_CPU1_SB_DQ<20>")
	)
	(segment
		(start 146.096482 -287.107884)
		(end 146.104864 -287.103058)
		(width 0.0762)
		(layer "F.Cu")
		(net "M_G_CPU1_SB_DQ<20>")
	)
	(segment
		(start 152.778714 -296.074846)
		(end 162.414204 -305.710336)
		(width 0.10668)
		(layer "F.Cu")
		(net "M_G_CPU1_SB_DQ<20>")
	)
	(segment
		(start 147.891246 -287.327848)
		(end 148.2344 -287.327848)
		(width 0.10668)
		(layer "F.Cu")
		(net "M_G_CPU1_SB_DQ<20>")
	)
	(segment
		(start 149.513798 -287.327848)
		(end 152.778714 -290.592764)
		(width 0.10668)
		(layer "F.Cu")
		(net "M_G_CPU1_SB_DQ<20>")
	)
	(segment
		(start 167.300148 -306.250594)
		(end 167.415464 -306.135278)
		(width 0.101346)
		(layer "F.Cu")
		(net "M_G_CPU1_SB_DQ<20>")
	)
	(segment
		(start 148.2344 -287.327848)
		(end 148.35124 -287.211008)
		(width 0.10668)
		(layer "F.Cu")
		(net "M_G_CPU1_SB_DQ<20>")
	)
	(segment
		(start 167.415464 -306.135278)
		(end 168.527984 -306.135278)
		(width 0.101346)
		(layer "F.Cu")
		(net "M_G_CPU1_SB_DQ<20>")
	)
	(segment
		(start 148.867114 -287.327848)
		(end 149.513798 -287.327848)
		(width 0.10668)
		(layer "F.Cu")
		(net "M_G_CPU1_SB_DQ<20>")
	)
	(segment
		(start 166.906448 -306.73167)
		(end 167.021764 -306.846986)
		(width 0.101346)
		(layer "F.Cu")
		(net "M_G_CPU1_SB_DQ<20>")
	)
	(segment
		(start 148.35124 -287.211008)
		(end 148.35124 -287.108646)
		(width 0.10668)
		(layer "F.Cu")
		(net "M_G_CPU1_SB_DQ<20>")
	)
	(segment
		(start 147.597368 -287.327848)
		(end 147.891246 -287.327848)
		(width 0.0762)
		(layer "F.Cu")
		(net "M_G_CPU1_SB_DQ<20>")
	)
	(segment
		(start 167.184832 -306.846986)
		(end 167.300148 -306.73167)
		(width 0.101346)
		(layer "F.Cu")
		(net "M_G_CPU1_SB_DQ<20>")
	)
	(segment
		(start 165.989254 -305.710336)
		(end 166.414196 -306.135278)
		(width 0.101346)
		(layer "F.Cu")
		(net "M_G_CPU1_SB_DQ<20>")
	)
	(segment
		(start 148.35124 -287.108646)
		(end 148.46808 -286.991806)
		(width 0.10668)
		(layer "F.Cu")
		(net "M_G_CPU1_SB_DQ<20>")
	)
	(arc
		(start 145.982436 -287.147762)
		(mid 146.041082 -287.132469)
		(end 146.096482 -287.107884)
		(width 0.0762)
		(layer "F.Cu")
		(net "M_G_CPU1_SB_DQ<20>")
	)
	(arc
		(start 145.815558 -286.956754)
		(mid 145.845187 -287.099241)
		(end 145.982436 -287.147762)
		(width 0.0762)
		(layer "F.Cu")
		(net "M_G_CPU1_SB_DQ<20>")
	)
	(arc
		(start 146.104864 -287.103058)
		(mid 146.218588 -287.052757)
		(end 146.340576 -287.028636)
		(width 0.0762)
		(layer "F.Cu")
		(net "M_G_CPU1_SB_DQ<20>")
	)
	(arc
		(start 146.340576 -287.028636)
		(mid 146.364053 -287.02726)
		(end 146.387566 -287.026858)
		(width 0.0762)
		(layer "F.Cu")
		(net "M_G_CPU1_SB_DQ<20>")
	)
	(segment
		(start 152.46604 -274.540472)
		(end 152.58288 -274.657312)
		(width 0.10668)
		(layer "F.Cu")
		(net "M_G_CPU1_SB_DQ<1>")
	)
	(segment
		(start 152.69972 -274.906994)
		(end 155.20162 -274.906994)
		(width 0.10668)
		(layer "F.Cu")
		(net "M_G_CPU1_SB_DQ<1>")
	)
	(segment
		(start 152.183846 -274.657312)
		(end 152.300686 -274.540472)
		(width 0.10668)
		(layer "F.Cu")
		(net "M_G_CPU1_SB_DQ<1>")
	)
	(segment
		(start 145.260822 -274.952968)
		(end 145.261076 -274.952968)
		(width 0.0762)
		(layer "F.Cu")
		(net "M_G_CPU1_SB_DQ<1>")
	)
	(segment
		(start 147.63242 -274.906994)
		(end 147.684236 -274.906994)
		(width 0.0762)
		(layer "F.Cu")
		(net "M_G_CPU1_SB_DQ<1>")
	)
	(segment
		(start 147.684236 -274.906994)
		(end 152.067006 -274.906994)
		(width 0.10668)
		(layer "F.Cu")
		(net "M_G_CPU1_SB_DQ<1>")
	)
	(segment
		(start 158.762954 -278.468328)
		(end 159.700214 -278.468328)
		(width 0.10668)
		(layer "F.Cu")
		(net "M_G_CPU1_SB_DQ<1>")
	)
	(segment
		(start 155.20162 -274.906994)
		(end 158.762954 -278.468328)
		(width 0.10668)
		(layer "F.Cu")
		(net "M_G_CPU1_SB_DQ<1>")
	)
	(segment
		(start 163.377626 -282.76042)
		(end 165.719506 -282.76042)
		(width 0.101346)
		(layer "F.Cu")
		(net "M_G_CPU1_SB_DQ<1>")
	)
	(segment
		(start 144.507966 -274.630388)
		(end 144.399508 -274.817078)
		(width 0.0762)
		(layer "F.Cu")
		(net "M_G_CPU1_SB_DQ<1>")
	)
	(segment
		(start 152.183846 -274.790154)
		(end 152.183846 -274.657312)
		(width 0.10668)
		(layer "F.Cu")
		(net "M_G_CPU1_SB_DQ<1>")
	)
	(segment
		(start 162.383978 -282.089352)
		(end 163.055046 -282.76042)
		(width 0.10668)
		(layer "F.Cu")
		(net "M_G_CPU1_SB_DQ<1>")
	)
	(segment
		(start 165.719506 -282.76042)
		(end 166.144448 -283.185362)
		(width 0.101346)
		(layer "F.Cu")
		(net "M_G_CPU1_SB_DQ<1>")
	)
	(segment
		(start 166.144448 -283.185362)
		(end 168.527984 -283.185362)
		(width 0.101346)
		(layer "F.Cu")
		(net "M_G_CPU1_SB_DQ<1>")
	)
	(segment
		(start 144.686528 -274.957794)
		(end 144.69491 -274.952968)
		(width 0.0762)
		(layer "F.Cu")
		(net "M_G_CPU1_SB_DQ<1>")
	)
	(segment
		(start 162.383978 -281.152092)
		(end 162.383978 -282.089352)
		(width 0.10668)
		(layer "F.Cu")
		(net "M_G_CPU1_SB_DQ<1>")
	)
	(segment
		(start 163.055046 -282.76042)
		(end 163.377626 -282.76042)
		(width 0.10668)
		(layer "F.Cu")
		(net "M_G_CPU1_SB_DQ<1>")
	)
	(segment
		(start 146.358356 -275.011134)
		(end 147.526756 -275.012658)
		(width 0.0762)
		(layer "F.Cu")
		(net "M_G_CPU1_SB_DQ<1>")
	)
	(segment
		(start 152.58288 -274.790154)
		(end 152.69972 -274.906994)
		(width 0.10668)
		(layer "F.Cu")
		(net "M_G_CPU1_SB_DQ<1>")
	)
	(segment
		(start 147.526756 -275.012658)
		(end 147.63242 -274.906994)
		(width 0.0762)
		(layer "F.Cu")
		(net "M_G_CPU1_SB_DQ<1>")
	)
	(segment
		(start 159.700214 -278.468328)
		(end 162.383978 -281.152092)
		(width 0.10668)
		(layer "F.Cu")
		(net "M_G_CPU1_SB_DQ<1>")
	)
	(segment
		(start 152.300686 -274.540472)
		(end 152.46604 -274.540472)
		(width 0.10668)
		(layer "F.Cu")
		(net "M_G_CPU1_SB_DQ<1>")
	)
	(segment
		(start 152.58288 -274.657312)
		(end 152.58288 -274.790154)
		(width 0.10668)
		(layer "F.Cu")
		(net "M_G_CPU1_SB_DQ<1>")
	)
	(segment
		(start 152.067006 -274.906994)
		(end 152.183846 -274.790154)
		(width 0.10668)
		(layer "F.Cu")
		(net "M_G_CPU1_SB_DQ<1>")
	)
	(arc
		(start 145.634964 -274.952968)
		(mid 145.91792 -274.876791)
		(end 146.200876 -274.952968)
		(width 0.0762)
		(layer "F.Cu")
		(net "M_G_CPU1_SB_DQ<1>")
	)
	(arc
		(start 146.283426 -274.995132)
		(mid 146.320054 -275.007062)
		(end 146.358356 -275.011134)
		(width 0.0762)
		(layer "F.Cu")
		(net "M_G_CPU1_SB_DQ<1>")
	)
	(arc
		(start 144.69491 -274.952968)
		(mid 144.977866 -274.876791)
		(end 145.260822 -274.952968)
		(width 0.0762)
		(layer "F.Cu")
		(net "M_G_CPU1_SB_DQ<1>")
	)
	(arc
		(start 144.399508 -274.817078)
		(mid 144.425425 -274.95012)
		(end 144.551146 -275.00072)
		(width 0.0762)
		(layer "F.Cu")
		(net "M_G_CPU1_SB_DQ<1>")
	)
	(arc
		(start 146.200876 -274.952968)
		(mid 146.24157 -274.975187)
		(end 146.283426 -274.995132)
		(width 0.0762)
		(layer "F.Cu")
		(net "M_G_CPU1_SB_DQ<1>")
	)
	(arc
		(start 144.551146 -275.00072)
		(mid 144.6209 -274.985763)
		(end 144.686528 -274.957794)
		(width 0.0762)
		(layer "F.Cu")
		(net "M_G_CPU1_SB_DQ<1>")
	)
	(arc
		(start 145.261076 -274.952968)
		(mid 145.44802 -275.003292)
		(end 145.634964 -274.952968)
		(width 0.0762)
		(layer "F.Cu")
		(net "M_G_CPU1_SB_DQ<1>")
	)
	(segment
		(start 154.782774 -292.896798)
		(end 154.665934 -293.013638)
		(width 0.10668)
		(layer "F.Cu")
		(net "M_G_CPU1_SB_DQ<19>")
	)
	(segment
		(start 155.22321 -290.2204)
		(end 155.22321 -290.385754)
		(width 0.10668)
		(layer "F.Cu")
		(net "M_G_CPU1_SB_DQ<19>")
	)
	(segment
		(start 155.10637 -291.699696)
		(end 155.22321 -291.816536)
		(width 0.10668)
		(layer "F.Cu")
		(net "M_G_CPU1_SB_DQ<19>")
	)
	(segment
		(start 155.113736 -294.531542)
		(end 155.485338 -294.158162)
		(width 0.10668)
		(layer "F.Cu")
		(net "M_G_CPU1_SB_DQ<19>")
	)
	(segment
		(start 155.396946 -294.978074)
		(end 163.187634 -302.735234)
		(width 0.10668)
		(layer "F.Cu")
		(net "M_G_CPU1_SB_DQ<19>")
	)
	(segment
		(start 154.782774 -292.497764)
		(end 155.10637 -292.497764)
		(width 0.10668)
		(layer "F.Cu")
		(net "M_G_CPU1_SB_DQ<19>")
	)
	(segment
		(start 155.22321 -292.614604)
		(end 155.22321 -292.779958)
		(width 0.10668)
		(layer "F.Cu")
		(net "M_G_CPU1_SB_DQ<19>")
	)
	(segment
		(start 154.782774 -292.09873)
		(end 154.665934 -292.21557)
		(width 0.10668)
		(layer "F.Cu")
		(net "M_G_CPU1_SB_DQ<19>")
	)
	(segment
		(start 155.22321 -290.385754)
		(end 155.10637 -290.502594)
		(width 0.10668)
		(layer "F.Cu")
		(net "M_G_CPU1_SB_DQ<19>")
	)
	(segment
		(start 146.39163 -284.941772)
		(end 147.60829 -284.941772)
		(width 0.0762)
		(layer "F.Cu")
		(net "M_G_CPU1_SB_DQ<19>")
	)
	(segment
		(start 155.22321 -293.578026)
		(end 155.10637 -293.694866)
		(width 0.10668)
		(layer "F.Cu")
		(net "M_G_CPU1_SB_DQ<19>")
	)
	(segment
		(start 154.665934 -293.811706)
		(end 154.665934 -294.25011)
		(width 0.10668)
		(layer "F.Cu")
		(net "M_G_CPU1_SB_DQ<19>")
	)
	(segment
		(start 154.782774 -293.694866)
		(end 154.665934 -293.811706)
		(width 0.10668)
		(layer "F.Cu")
		(net "M_G_CPU1_SB_DQ<19>")
	)
	(segment
		(start 155.22321 -293.412672)
		(end 155.22321 -293.578026)
		(width 0.10668)
		(layer "F.Cu")
		(net "M_G_CPU1_SB_DQ<19>")
	)
	(segment
		(start 155.650438 -294.157908)
		(end 155.76804 -294.275002)
		(width 0.10668)
		(layer "F.Cu")
		(net "M_G_CPU1_SB_DQ<19>")
	)
	(segment
		(start 155.768294 -294.439848)
		(end 155.396692 -294.812974)
		(width 0.10668)
		(layer "F.Cu")
		(net "M_G_CPU1_SB_DQ<19>")
	)
	(segment
		(start 154.665934 -290.784788)
		(end 154.782774 -290.901628)
		(width 0.10668)
		(layer "F.Cu")
		(net "M_G_CPU1_SB_DQ<19>")
	)
	(segment
		(start 155.22321 -291.183822)
		(end 155.10637 -291.300662)
		(width 0.10668)
		(layer "F.Cu")
		(net "M_G_CPU1_SB_DQ<19>")
	)
	(segment
		(start 154.665934 -292.21557)
		(end 154.665934 -292.380924)
		(width 0.10668)
		(layer "F.Cu")
		(net "M_G_CPU1_SB_DQ<19>")
	)
	(segment
		(start 155.10637 -291.300662)
		(end 154.782774 -291.300662)
		(width 0.10668)
		(layer "F.Cu")
		(net "M_G_CPU1_SB_DQ<19>")
	)
	(segment
		(start 154.782774 -290.502594)
		(end 154.665934 -290.619434)
		(width 0.10668)
		(layer "F.Cu")
		(net "M_G_CPU1_SB_DQ<19>")
	)
	(segment
		(start 155.76804 -294.275002)
		(end 155.768294 -294.439848)
		(width 0.10668)
		(layer "F.Cu")
		(net "M_G_CPU1_SB_DQ<19>")
	)
	(segment
		(start 155.10637 -292.09873)
		(end 154.782774 -292.09873)
		(width 0.10668)
		(layer "F.Cu")
		(net "M_G_CPU1_SB_DQ<19>")
	)
	(segment
		(start 155.396692 -294.812974)
		(end 155.396946 -294.978074)
		(width 0.10668)
		(layer "F.Cu")
		(net "M_G_CPU1_SB_DQ<19>")
	)
	(segment
		(start 155.10637 -292.497764)
		(end 155.22321 -292.614604)
		(width 0.10668)
		(layer "F.Cu")
		(net "M_G_CPU1_SB_DQ<19>")
	)
	(segment
		(start 155.10637 -293.694866)
		(end 154.782774 -293.694866)
		(width 0.10668)
		(layer "F.Cu")
		(net "M_G_CPU1_SB_DQ<19>")
	)
	(segment
		(start 155.10637 -292.896798)
		(end 154.782774 -292.896798)
		(width 0.10668)
		(layer "F.Cu")
		(net "M_G_CPU1_SB_DQ<19>")
	)
	(segment
		(start 154.94889 -294.531796)
		(end 155.113736 -294.531542)
		(width 0.10668)
		(layer "F.Cu")
		(net "M_G_CPU1_SB_DQ<19>")
	)
	(segment
		(start 154.782774 -293.295832)
		(end 155.10637 -293.295832)
		(width 0.10668)
		(layer "F.Cu")
		(net "M_G_CPU1_SB_DQ<19>")
	)
	(segment
		(start 154.665934 -289.63493)
		(end 154.665934 -289.98672)
		(width 0.10668)
		(layer "F.Cu")
		(net "M_G_CPU1_SB_DQ<19>")
	)
	(segment
		(start 155.22321 -291.98189)
		(end 155.10637 -292.09873)
		(width 0.10668)
		(layer "F.Cu")
		(net "M_G_CPU1_SB_DQ<19>")
	)
	(segment
		(start 155.485338 -294.158162)
		(end 155.650438 -294.157908)
		(width 0.10668)
		(layer "F.Cu")
		(net "M_G_CPU1_SB_DQ<19>")
	)
	(segment
		(start 155.10637 -290.502594)
		(end 154.782774 -290.502594)
		(width 0.10668)
		(layer "F.Cu")
		(net "M_G_CPU1_SB_DQ<19>")
	)
	(segment
		(start 154.782774 -290.10356)
		(end 155.10637 -290.10356)
		(width 0.10668)
		(layer "F.Cu")
		(net "M_G_CPU1_SB_DQ<19>")
	)
	(segment
		(start 154.665934 -290.619434)
		(end 154.665934 -290.784788)
		(width 0.10668)
		(layer "F.Cu")
		(net "M_G_CPU1_SB_DQ<19>")
	)
	(segment
		(start 154.665934 -291.417502)
		(end 154.665934 -291.582856)
		(width 0.10668)
		(layer "F.Cu")
		(net "M_G_CPU1_SB_DQ<19>")
	)
	(segment
		(start 154.665934 -294.25011)
		(end 154.94889 -294.531796)
		(width 0.10668)
		(layer "F.Cu")
		(net "M_G_CPU1_SB_DQ<19>")
	)
	(segment
		(start 155.22321 -291.816536)
		(end 155.22321 -291.98189)
		(width 0.10668)
		(layer "F.Cu")
		(net "M_G_CPU1_SB_DQ<19>")
	)
	(segment
		(start 154.665934 -291.582856)
		(end 154.782774 -291.699696)
		(width 0.10668)
		(layer "F.Cu")
		(net "M_G_CPU1_SB_DQ<19>")
	)
	(segment
		(start 154.782774 -291.300662)
		(end 154.665934 -291.417502)
		(width 0.10668)
		(layer "F.Cu")
		(net "M_G_CPU1_SB_DQ<19>")
	)
	(segment
		(start 155.10637 -290.901628)
		(end 155.22321 -291.018468)
		(width 0.10668)
		(layer "F.Cu")
		(net "M_G_CPU1_SB_DQ<19>")
	)
	(segment
		(start 155.22321 -292.779958)
		(end 155.10637 -292.896798)
		(width 0.10668)
		(layer "F.Cu")
		(net "M_G_CPU1_SB_DQ<19>")
	)
	(segment
		(start 155.10637 -290.10356)
		(end 155.22321 -290.2204)
		(width 0.10668)
		(layer "F.Cu")
		(net "M_G_CPU1_SB_DQ<19>")
	)
	(segment
		(start 154.665934 -293.013638)
		(end 154.665934 -293.178992)
		(width 0.10668)
		(layer "F.Cu")
		(net "M_G_CPU1_SB_DQ<19>")
	)
	(segment
		(start 154.665934 -292.380924)
		(end 154.782774 -292.497764)
		(width 0.10668)
		(layer "F.Cu")
		(net "M_G_CPU1_SB_DQ<19>")
	)
	(segment
		(start 149.972776 -284.941772)
		(end 154.665934 -289.63493)
		(width 0.10668)
		(layer "F.Cu")
		(net "M_G_CPU1_SB_DQ<19>")
	)
	(segment
		(start 147.60829 -284.941772)
		(end 149.972776 -284.941772)
		(width 0.10668)
		(layer "F.Cu")
		(net "M_G_CPU1_SB_DQ<19>")
	)
	(segment
		(start 155.10637 -293.295832)
		(end 155.22321 -293.412672)
		(width 0.10668)
		(layer "F.Cu")
		(net "M_G_CPU1_SB_DQ<19>")
	)
	(segment
		(start 154.665934 -293.178992)
		(end 154.782774 -293.295832)
		(width 0.10668)
		(layer "F.Cu")
		(net "M_G_CPU1_SB_DQ<19>")
	)
	(segment
		(start 163.187634 -302.735234)
		(end 164.427916 -302.735234)
		(width 0.10668)
		(layer "F.Cu")
		(net "M_G_CPU1_SB_DQ<19>")
	)
	(segment
		(start 154.782774 -290.901628)
		(end 155.10637 -290.901628)
		(width 0.10668)
		(layer "F.Cu")
		(net "M_G_CPU1_SB_DQ<19>")
	)
	(segment
		(start 146.096482 -284.83306)
		(end 146.104864 -284.837886)
		(width 0.0762)
		(layer "F.Cu")
		(net "M_G_CPU1_SB_DQ<19>")
	)
	(segment
		(start 154.782774 -291.699696)
		(end 155.10637 -291.699696)
		(width 0.10668)
		(layer "F.Cu")
		(net "M_G_CPU1_SB_DQ<19>")
	)
	(segment
		(start 155.22321 -291.018468)
		(end 155.22321 -291.183822)
		(width 0.10668)
		(layer "F.Cu")
		(net "M_G_CPU1_SB_DQ<19>")
	)
	(segment
		(start 154.665934 -289.98672)
		(end 154.782774 -290.10356)
		(width 0.10668)
		(layer "F.Cu")
		(net "M_G_CPU1_SB_DQ<19>")
	)
	(arc
		(start 146.104864 -284.837886)
		(mid 146.207758 -284.890258)
		(end 146.315938 -284.930596)
		(width 0.0762)
		(layer "F.Cu")
		(net "M_G_CPU1_SB_DQ<19>")
	)
	(arc
		(start 144.037812 -285.160466)
		(mid 144.233161 -284.976647)
		(end 144.493996 -284.914086)
		(width 0.0762)
		(layer "F.Cu")
		(net "M_G_CPU1_SB_DQ<19>")
	)
	(arc
		(start 145.730722 -284.837886)
		(mid 145.912973 -284.787536)
		(end 146.096482 -284.83306)
		(width 0.0762)
		(layer "F.Cu")
		(net "M_G_CPU1_SB_DQ<19>")
	)
	(arc
		(start 145.16481 -284.837886)
		(mid 145.447766 -284.914063)
		(end 145.730722 -284.837886)
		(width 0.0762)
		(layer "F.Cu")
		(net "M_G_CPU1_SB_DQ<19>")
	)
	(arc
		(start 146.315938 -284.930596)
		(mid 146.353364 -284.939035)
		(end 146.39163 -284.941772)
		(width 0.0762)
		(layer "F.Cu")
		(net "M_G_CPU1_SB_DQ<19>")
	)
	(arc
		(start 144.493996 -284.914086)
		(mid 144.647745 -284.896577)
		(end 144.790922 -284.837886)
		(width 0.0762)
		(layer "F.Cu")
		(net "M_G_CPU1_SB_DQ<19>")
	)
	(arc
		(start 144.790922 -284.837886)
		(mid 144.977866 -284.787631)
		(end 145.16481 -284.837886)
		(width 0.0762)
		(layer "F.Cu")
		(net "M_G_CPU1_SB_DQ<19>")
	)
	(segment
		(start 158.064454 -295.553638)
		(end 158.181548 -295.670732)
		(width 0.10668)
		(layer "F.Cu")
		(net "M_G_CPU1_SB_DQ<18>")
	)
	(segment
		(start 159.310324 -296.964608)
		(end 158.9278 -297.347132)
		(width 0.10668)
		(layer "F.Cu")
		(net "M_G_CPU1_SB_DQ<18>")
	)
	(segment
		(start 156.79039 -295.368726)
		(end 156.95549 -295.368726)
		(width 0.10668)
		(layer "F.Cu")
		(net "M_G_CPU1_SB_DQ<18>")
	)
	(segment
		(start 157.500066 -294.98925)
		(end 157.61716 -295.106344)
		(width 0.10668)
		(layer "F.Cu")
		(net "M_G_CPU1_SB_DQ<18>")
	)
	(segment
		(start 157.234636 -295.653968)
		(end 157.234636 -295.819068)
		(width 0.10668)
		(layer "F.Cu")
		(net "M_G_CPU1_SB_DQ<18>")
	)
	(segment
		(start 159.02813 -296.682414)
		(end 159.19323 -296.682414)
		(width 0.10668)
		(layer "F.Cu")
		(net "M_G_CPU1_SB_DQ<18>")
	)
	(segment
		(start 157.334966 -294.98925)
		(end 157.500066 -294.98925)
		(width 0.10668)
		(layer "F.Cu")
		(net "M_G_CPU1_SB_DQ<18>")
	)
	(segment
		(start 160.056576 -298.641008)
		(end 162.45078 -301.035212)
		(width 0.10668)
		(layer "F.Cu")
		(net "M_G_CPU1_SB_DQ<18>")
	)
	(segment
		(start 160.164018 -297.969178)
		(end 160.281112 -298.086272)
		(width 0.10668)
		(layer "F.Cu")
		(net "M_G_CPU1_SB_DQ<18>")
	)
	(segment
		(start 157.799024 -296.383456)
		(end 157.916118 -296.50055)
		(width 0.10668)
		(layer "F.Cu")
		(net "M_G_CPU1_SB_DQ<18>")
	)
	(segment
		(start 156.673296 -295.251632)
		(end 156.79039 -295.368726)
		(width 0.10668)
		(layer "F.Cu")
		(net "M_G_CPU1_SB_DQ<18>")
	)
	(segment
		(start 147.269454 -283.977334)
		(end 147.522438 -284.230318)
		(width 0.0762)
		(layer "F.Cu")
		(net "M_G_CPU1_SB_DQ<18>")
	)
	(segment
		(start 146.38782 -283.977334)
		(end 147.269454 -283.977334)
		(width 0.0762)
		(layer "F.Cu")
		(net "M_G_CPU1_SB_DQ<18>")
	)
	(segment
		(start 159.492188 -297.91152)
		(end 159.492188 -298.07662)
		(width 0.10668)
		(layer "F.Cu")
		(net "M_G_CPU1_SB_DQ<18>")
	)
	(segment
		(start 155.9306 -293.419784)
		(end 157.052772 -294.541956)
		(width 0.10668)
		(layer "F.Cu")
		(net "M_G_CPU1_SB_DQ<18>")
	)
	(segment
		(start 158.480506 -297.064938)
		(end 158.645606 -297.064938)
		(width 0.10668)
		(layer "F.Cu")
		(net "M_G_CPU1_SB_DQ<18>")
	)
	(segment
		(start 158.9278 -297.512232)
		(end 159.044894 -297.629326)
		(width 0.10668)
		(layer "F.Cu")
		(net "M_G_CPU1_SB_DQ<18>")
	)
	(segment
		(start 159.998918 -297.969178)
		(end 160.164018 -297.969178)
		(width 0.10668)
		(layer "F.Cu")
		(net "M_G_CPU1_SB_DQ<18>")
	)
	(segment
		(start 157.61716 -295.271444)
		(end 157.234636 -295.653968)
		(width 0.10668)
		(layer "F.Cu")
		(net "M_G_CPU1_SB_DQ<18>")
	)
	(segment
		(start 157.61716 -295.106344)
		(end 157.61716 -295.271444)
		(width 0.10668)
		(layer "F.Cu")
		(net "M_G_CPU1_SB_DQ<18>")
	)
	(segment
		(start 147.697698 -284.230318)
		(end 150.22449 -284.230318)
		(width 0.10668)
		(layer "F.Cu")
		(net "M_G_CPU1_SB_DQ<18>")
	)
	(segment
		(start 158.745936 -296.23512)
		(end 158.745936 -296.40022)
		(width 0.10668)
		(layer "F.Cu")
		(net "M_G_CPU1_SB_DQ<18>")
	)
	(segment
		(start 159.874712 -297.363896)
		(end 159.874712 -297.528996)
		(width 0.10668)
		(layer "F.Cu")
		(net "M_G_CPU1_SB_DQ<18>")
	)
	(segment
		(start 160.281112 -298.086272)
		(end 160.281112 -298.251372)
		(width 0.10668)
		(layer "F.Cu")
		(net "M_G_CPU1_SB_DQ<18>")
	)
	(segment
		(start 159.19323 -296.682414)
		(end 159.310324 -296.799508)
		(width 0.10668)
		(layer "F.Cu")
		(net "M_G_CPU1_SB_DQ<18>")
	)
	(segment
		(start 157.899354 -295.553638)
		(end 158.064454 -295.553638)
		(width 0.10668)
		(layer "F.Cu")
		(net "M_G_CPU1_SB_DQ<18>")
	)
	(segment
		(start 147.522438 -284.230318)
		(end 147.697698 -284.230318)
		(width 0.0762)
		(layer "F.Cu")
		(net "M_G_CPU1_SB_DQ<18>")
	)
	(segment
		(start 159.609282 -298.193714)
		(end 159.774382 -298.193714)
		(width 0.10668)
		(layer "F.Cu")
		(net "M_G_CPU1_SB_DQ<18>")
	)
	(segment
		(start 160.281112 -298.251372)
		(end 160.056576 -298.475908)
		(width 0.10668)
		(layer "F.Cu")
		(net "M_G_CPU1_SB_DQ<18>")
	)
	(segment
		(start 160.056576 -298.475908)
		(end 160.056576 -298.641008)
		(width 0.10668)
		(layer "F.Cu")
		(net "M_G_CPU1_SB_DQ<18>")
	)
	(segment
		(start 157.35173 -295.936162)
		(end 157.51683 -295.936162)
		(width 0.10668)
		(layer "F.Cu")
		(net "M_G_CPU1_SB_DQ<18>")
	)
	(segment
		(start 159.310324 -296.799508)
		(end 159.310324 -296.964608)
		(width 0.10668)
		(layer "F.Cu")
		(net "M_G_CPU1_SB_DQ<18>")
	)
	(segment
		(start 157.799024 -296.218356)
		(end 157.799024 -296.383456)
		(width 0.10668)
		(layer "F.Cu")
		(net "M_G_CPU1_SB_DQ<18>")
	)
	(segment
		(start 159.874712 -297.528996)
		(end 159.492188 -297.91152)
		(width 0.10668)
		(layer "F.Cu")
		(net "M_G_CPU1_SB_DQ<18>")
	)
	(segment
		(start 157.052772 -294.541956)
		(end 157.052772 -294.707056)
		(width 0.10668)
		(layer "F.Cu")
		(net "M_G_CPU1_SB_DQ<18>")
	)
	(segment
		(start 158.463742 -296.118026)
		(end 158.628842 -296.118026)
		(width 0.10668)
		(layer "F.Cu")
		(net "M_G_CPU1_SB_DQ<18>")
	)
	(segment
		(start 158.745936 -296.40022)
		(end 158.363412 -296.782744)
		(width 0.10668)
		(layer "F.Cu")
		(net "M_G_CPU1_SB_DQ<18>")
	)
	(segment
		(start 159.044894 -297.629326)
		(end 159.209994 -297.629326)
		(width 0.10668)
		(layer "F.Cu")
		(net "M_G_CPU1_SB_DQ<18>")
	)
	(segment
		(start 156.673296 -295.086532)
		(end 156.673296 -295.251632)
		(width 0.10668)
		(layer "F.Cu")
		(net "M_G_CPU1_SB_DQ<18>")
	)
	(segment
		(start 159.592518 -297.246802)
		(end 159.757618 -297.246802)
		(width 0.10668)
		(layer "F.Cu")
		(net "M_G_CPU1_SB_DQ<18>")
	)
	(segment
		(start 158.363412 -296.782744)
		(end 158.363412 -296.947844)
		(width 0.10668)
		(layer "F.Cu")
		(net "M_G_CPU1_SB_DQ<18>")
	)
	(segment
		(start 158.081218 -296.50055)
		(end 158.463742 -296.118026)
		(width 0.10668)
		(layer "F.Cu")
		(net "M_G_CPU1_SB_DQ<18>")
	)
	(segment
		(start 157.052772 -294.707056)
		(end 156.673296 -295.086532)
		(width 0.10668)
		(layer "F.Cu")
		(net "M_G_CPU1_SB_DQ<18>")
	)
	(segment
		(start 158.181548 -295.670732)
		(end 158.181548 -295.835832)
		(width 0.10668)
		(layer "F.Cu")
		(net "M_G_CPU1_SB_DQ<18>")
	)
	(segment
		(start 150.22449 -284.230318)
		(end 155.9306 -289.936428)
		(width 0.10668)
		(layer "F.Cu")
		(net "M_G_CPU1_SB_DQ<18>")
	)
	(segment
		(start 159.209994 -297.629326)
		(end 159.592518 -297.246802)
		(width 0.10668)
		(layer "F.Cu")
		(net "M_G_CPU1_SB_DQ<18>")
	)
	(segment
		(start 159.757618 -297.246802)
		(end 159.874712 -297.363896)
		(width 0.10668)
		(layer "F.Cu")
		(net "M_G_CPU1_SB_DQ<18>")
	)
	(segment
		(start 158.645606 -297.064938)
		(end 159.02813 -296.682414)
		(width 0.10668)
		(layer "F.Cu")
		(net "M_G_CPU1_SB_DQ<18>")
	)
	(segment
		(start 158.9278 -297.347132)
		(end 158.9278 -297.512232)
		(width 0.10668)
		(layer "F.Cu")
		(net "M_G_CPU1_SB_DQ<18>")
	)
	(segment
		(start 157.916118 -296.50055)
		(end 158.081218 -296.50055)
		(width 0.10668)
		(layer "F.Cu")
		(net "M_G_CPU1_SB_DQ<18>")
	)
	(segment
		(start 159.492188 -298.07662)
		(end 159.609282 -298.193714)
		(width 0.10668)
		(layer "F.Cu")
		(net "M_G_CPU1_SB_DQ<18>")
	)
	(segment
		(start 158.628842 -296.118026)
		(end 158.745936 -296.23512)
		(width 0.10668)
		(layer "F.Cu")
		(net "M_G_CPU1_SB_DQ<18>")
	)
	(segment
		(start 159.774382 -298.193714)
		(end 159.998918 -297.969178)
		(width 0.10668)
		(layer "F.Cu")
		(net "M_G_CPU1_SB_DQ<18>")
	)
	(segment
		(start 162.45078 -301.035212)
		(end 164.427916 -301.035212)
		(width 0.10668)
		(layer "F.Cu")
		(net "M_G_CPU1_SB_DQ<18>")
	)
	(segment
		(start 155.9306 -289.936428)
		(end 155.9306 -293.419784)
		(width 0.10668)
		(layer "F.Cu")
		(net "M_G_CPU1_SB_DQ<18>")
	)
	(segment
		(start 157.51683 -295.936162)
		(end 157.899354 -295.553638)
		(width 0.10668)
		(layer "F.Cu")
		(net "M_G_CPU1_SB_DQ<18>")
	)
	(segment
		(start 158.363412 -296.947844)
		(end 158.480506 -297.064938)
		(width 0.10668)
		(layer "F.Cu")
		(net "M_G_CPU1_SB_DQ<18>")
	)
	(segment
		(start 156.95549 -295.368726)
		(end 157.334966 -294.98925)
		(width 0.10668)
		(layer "F.Cu")
		(net "M_G_CPU1_SB_DQ<18>")
	)
	(segment
		(start 158.181548 -295.835832)
		(end 157.799024 -296.218356)
		(width 0.10668)
		(layer "F.Cu")
		(net "M_G_CPU1_SB_DQ<18>")
	)
	(segment
		(start 157.234636 -295.819068)
		(end 157.35173 -295.936162)
		(width 0.10668)
		(layer "F.Cu")
		(net "M_G_CPU1_SB_DQ<18>")
	)
	(arc
		(start 146.356832 -283.978604)
		(mid 146.372313 -283.977648)
		(end 146.38782 -283.977334)
		(width 0.0762)
		(layer "F.Cu")
		(net "M_G_CPU1_SB_DQ<18>")
	)
	(arc
		(start 146.015456 -284.095698)
		(mid 146.111165 -284.069986)
		(end 146.200876 -284.02788)
		(width 0.0762)
		(layer "F.Cu")
		(net "M_G_CPU1_SB_DQ<18>")
	)
	(arc
		(start 146.200876 -284.02788)
		(mid 146.276116 -283.994567)
		(end 146.356832 -283.978604)
		(width 0.0762)
		(layer "F.Cu")
		(net "M_G_CPU1_SB_DQ<18>")
	)
	(arc
		(start 145.976848 -284.101032)
		(mid 145.996197 -284.098694)
		(end 146.015456 -284.095698)
		(width 0.0762)
		(layer "F.Cu")
		(net "M_G_CPU1_SB_DQ<18>")
	)
	(arc
		(start 145.447766 -284.35046)
		(mid 145.691197 -284.180973)
		(end 145.976848 -284.101032)
		(width 0.0762)
		(layer "F.Cu")
		(net "M_G_CPU1_SB_DQ<18>")
	)
	(segment
		(start 156.22778 -294.198548)
		(end 156.22778 -295.293796)
		(width 0.10668)
		(layer "F.Cu")
		(net "M_G_CPU1_SB_DQ<17>")
	)
	(segment
		(start 166.047674 -301.88535)
		(end 166.16299 -302.000666)
		(width 0.101346)
		(layer "F.Cu")
		(net "M_G_CPU1_SB_DQ<17>")
	)
	(segment
		(start 144.507966 -284.35046)
		(end 144.399508 -284.53715)
		(width 0.0762)
		(layer "F.Cu")
		(net "M_G_CPU1_SB_DQ<17>")
	)
	(segment
		(start 145.260822 -284.67304)
		(end 145.261076 -284.67304)
		(width 0.0762)
		(layer "F.Cu")
		(net "M_G_CPU1_SB_DQ<17>")
	)
	(segment
		(start 155.59024 -293.561008)
		(end 156.22778 -294.198548)
		(width 0.10668)
		(layer "F.Cu")
		(net "M_G_CPU1_SB_DQ<17>")
	)
	(segment
		(start 147.477734 -284.58795)
		(end 147.65274 -284.58795)
		(width 0.0762)
		(layer "F.Cu")
		(net "M_G_CPU1_SB_DQ<17>")
	)
	(segment
		(start 166.441374 -302.457866)
		(end 166.55669 -302.34255)
		(width 0.101346)
		(layer "F.Cu")
		(net "M_G_CPU1_SB_DQ<17>")
	)
	(segment
		(start 150.100538 -284.58795)
		(end 155.59024 -290.077652)
		(width 0.10668)
		(layer "F.Cu")
		(net "M_G_CPU1_SB_DQ<17>")
	)
	(segment
		(start 166.16299 -302.34255)
		(end 166.278306 -302.457866)
		(width 0.101346)
		(layer "F.Cu")
		(net "M_G_CPU1_SB_DQ<17>")
	)
	(segment
		(start 166.16299 -302.000666)
		(end 166.16299 -302.34255)
		(width 0.101346)
		(layer "F.Cu")
		(net "M_G_CPU1_SB_DQ<17>")
	)
	(segment
		(start 166.55669 -302.000666)
		(end 166.672006 -301.88535)
		(width 0.101346)
		(layer "F.Cu")
		(net "M_G_CPU1_SB_DQ<17>")
	)
	(segment
		(start 155.59024 -290.077652)
		(end 155.59024 -293.561008)
		(width 0.10668)
		(layer "F.Cu")
		(net "M_G_CPU1_SB_DQ<17>")
	)
	(segment
		(start 162.394392 -301.460408)
		(end 163.377626 -301.460408)
		(width 0.10668)
		(layer "F.Cu")
		(net "M_G_CPU1_SB_DQ<17>")
	)
	(segment
		(start 147.65274 -284.58795)
		(end 150.100538 -284.58795)
		(width 0.10668)
		(layer "F.Cu")
		(net "M_G_CPU1_SB_DQ<17>")
	)
	(segment
		(start 165.670992 -301.88535)
		(end 166.047674 -301.88535)
		(width 0.101346)
		(layer "F.Cu")
		(net "M_G_CPU1_SB_DQ<17>")
	)
	(segment
		(start 165.24605 -301.460408)
		(end 165.670992 -301.88535)
		(width 0.101346)
		(layer "F.Cu")
		(net "M_G_CPU1_SB_DQ<17>")
	)
	(segment
		(start 147.248626 -284.732476)
		(end 147.333208 -284.732476)
		(width 0.0762)
		(layer "F.Cu")
		(net "M_G_CPU1_SB_DQ<17>")
	)
	(segment
		(start 166.672006 -301.88535)
		(end 168.527984 -301.88535)
		(width 0.101346)
		(layer "F.Cu")
		(net "M_G_CPU1_SB_DQ<17>")
	)
	(segment
		(start 146.358356 -284.731206)
		(end 147.248626 -284.732476)
		(width 0.0762)
		(layer "F.Cu")
		(net "M_G_CPU1_SB_DQ<17>")
	)
	(segment
		(start 144.686528 -284.677866)
		(end 144.69491 -284.67304)
		(width 0.0762)
		(layer "F.Cu")
		(net "M_G_CPU1_SB_DQ<17>")
	)
	(segment
		(start 166.55669 -302.34255)
		(end 166.55669 -302.000666)
		(width 0.101346)
		(layer "F.Cu")
		(net "M_G_CPU1_SB_DQ<17>")
	)
	(segment
		(start 147.333208 -284.732476)
		(end 147.477734 -284.58795)
		(width 0.0762)
		(layer "F.Cu")
		(net "M_G_CPU1_SB_DQ<17>")
	)
	(segment
		(start 163.377626 -301.460408)
		(end 165.24605 -301.460408)
		(width 0.101346)
		(layer "F.Cu")
		(net "M_G_CPU1_SB_DQ<17>")
	)
	(segment
		(start 156.22778 -295.293796)
		(end 162.394392 -301.460408)
		(width 0.10668)
		(layer "F.Cu")
		(net "M_G_CPU1_SB_DQ<17>")
	)
	(segment
		(start 166.278306 -302.457866)
		(end 166.441374 -302.457866)
		(width 0.101346)
		(layer "F.Cu")
		(net "M_G_CPU1_SB_DQ<17>")
	)
	(arc
		(start 144.551146 -284.720792)
		(mid 144.6209 -284.705835)
		(end 144.686528 -284.677866)
		(width 0.0762)
		(layer "F.Cu")
		(net "M_G_CPU1_SB_DQ<17>")
	)
	(arc
		(start 146.200876 -284.67304)
		(mid 146.24157 -284.695259)
		(end 146.283426 -284.715204)
		(width 0.0762)
		(layer "F.Cu")
		(net "M_G_CPU1_SB_DQ<17>")
	)
	(arc
		(start 144.399508 -284.53715)
		(mid 144.425425 -284.670192)
		(end 144.551146 -284.720792)
		(width 0.0762)
		(layer "F.Cu")
		(net "M_G_CPU1_SB_DQ<17>")
	)
	(arc
		(start 145.261076 -284.67304)
		(mid 145.44802 -284.723364)
		(end 145.634964 -284.67304)
		(width 0.0762)
		(layer "F.Cu")
		(net "M_G_CPU1_SB_DQ<17>")
	)
	(arc
		(start 145.634964 -284.67304)
		(mid 145.91792 -284.596863)
		(end 146.200876 -284.67304)
		(width 0.0762)
		(layer "F.Cu")
		(net "M_G_CPU1_SB_DQ<17>")
	)
	(arc
		(start 144.69491 -284.67304)
		(mid 144.977866 -284.596863)
		(end 145.260822 -284.67304)
		(width 0.0762)
		(layer "F.Cu")
		(net "M_G_CPU1_SB_DQ<17>")
	)
	(arc
		(start 146.283426 -284.715204)
		(mid 146.320054 -284.727134)
		(end 146.358356 -284.731206)
		(width 0.0762)
		(layer "F.Cu")
		(net "M_G_CPU1_SB_DQ<17>")
	)
	(segment
		(start 167.105584 -300.79823)
		(end 167.2209 -300.913546)
		(width 0.101346)
		(layer "F.Cu")
		(net "M_G_CPU1_SB_DQ<16>")
	)
	(segment
		(start 156.27096 -289.795204)
		(end 156.27096 -293.244524)
		(width 0.10668)
		(layer "F.Cu")
		(net "M_G_CPU1_SB_DQ<16>")
	)
	(segment
		(start 146.096482 -283.86786)
		(end 146.104864 -283.863034)
		(width 0.0762)
		(layer "F.Cu")
		(net "M_G_CPU1_SB_DQ<16>")
	)
	(segment
		(start 165.55466 -300.61027)
		(end 165.979602 -300.185328)
		(width 0.101346)
		(layer "F.Cu")
		(net "M_G_CPU1_SB_DQ<16>")
	)
	(segment
		(start 167.2209 -300.913546)
		(end 167.383968 -300.913546)
		(width 0.101346)
		(layer "F.Cu")
		(net "M_G_CPU1_SB_DQ<16>")
	)
	(segment
		(start 160.621472 -297.595036)
		(end 160.621472 -298.72432)
		(width 0.10668)
		(layer "F.Cu")
		(net "M_G_CPU1_SB_DQ<16>")
	)
	(segment
		(start 145.91792 -283.540454)
		(end 145.815558 -283.71673)
		(width 0.0762)
		(layer "F.Cu")
		(net "M_G_CPU1_SB_DQ<16>")
	)
	(segment
		(start 167.6146 -300.185328)
		(end 168.527984 -300.185328)
		(width 0.101346)
		(layer "F.Cu")
		(net "M_G_CPU1_SB_DQ<16>")
	)
	(segment
		(start 167.105584 -300.300644)
		(end 167.105584 -300.79823)
		(width 0.101346)
		(layer "F.Cu")
		(net "M_G_CPU1_SB_DQ<16>")
	)
	(segment
		(start 147.563586 -283.887418)
		(end 147.820634 -283.887418)
		(width 0.0762)
		(layer "F.Cu")
		(net "M_G_CPU1_SB_DQ<16>")
	)
	(segment
		(start 166.318184 -300.300644)
		(end 166.318184 -300.79823)
		(width 0.101346)
		(layer "F.Cu")
		(net "M_G_CPU1_SB_DQ<16>")
	)
	(segment
		(start 166.4335 -300.913546)
		(end 166.596568 -300.913546)
		(width 0.101346)
		(layer "F.Cu")
		(net "M_G_CPU1_SB_DQ<16>")
	)
	(segment
		(start 166.596568 -300.913546)
		(end 166.711884 -300.79823)
		(width 0.101346)
		(layer "F.Cu")
		(net "M_G_CPU1_SB_DQ<16>")
	)
	(segment
		(start 147.463002 -283.786834)
		(end 147.563586 -283.887418)
		(width 0.0762)
		(layer "F.Cu")
		(net "M_G_CPU1_SB_DQ<16>")
	)
	(segment
		(start 160.621472 -298.72432)
		(end 162.507422 -300.61027)
		(width 0.10668)
		(layer "F.Cu")
		(net "M_G_CPU1_SB_DQ<16>")
	)
	(segment
		(start 167.499284 -300.300644)
		(end 167.6146 -300.185328)
		(width 0.101346)
		(layer "F.Cu")
		(net "M_G_CPU1_SB_DQ<16>")
	)
	(segment
		(start 150.363174 -283.887418)
		(end 156.27096 -289.795204)
		(width 0.10668)
		(layer "F.Cu")
		(net "M_G_CPU1_SB_DQ<16>")
	)
	(segment
		(start 166.711884 -300.79823)
		(end 166.711884 -300.300644)
		(width 0.101346)
		(layer "F.Cu")
		(net "M_G_CPU1_SB_DQ<16>")
	)
	(segment
		(start 167.383968 -300.913546)
		(end 167.499284 -300.79823)
		(width 0.101346)
		(layer "F.Cu")
		(net "M_G_CPU1_SB_DQ<16>")
	)
	(segment
		(start 166.202868 -300.185328)
		(end 166.318184 -300.300644)
		(width 0.101346)
		(layer "F.Cu")
		(net "M_G_CPU1_SB_DQ<16>")
	)
	(segment
		(start 156.27096 -293.244524)
		(end 160.621472 -297.595036)
		(width 0.10668)
		(layer "F.Cu")
		(net "M_G_CPU1_SB_DQ<16>")
	)
	(segment
		(start 166.711884 -300.300644)
		(end 166.8272 -300.185328)
		(width 0.101346)
		(layer "F.Cu")
		(net "M_G_CPU1_SB_DQ<16>")
	)
	(segment
		(start 166.8272 -300.185328)
		(end 166.990268 -300.185328)
		(width 0.101346)
		(layer "F.Cu")
		(net "M_G_CPU1_SB_DQ<16>")
	)
	(segment
		(start 162.507422 -300.61027)
		(end 163.377626 -300.61027)
		(width 0.10668)
		(layer "F.Cu")
		(net "M_G_CPU1_SB_DQ<16>")
	)
	(segment
		(start 165.979602 -300.185328)
		(end 166.202868 -300.185328)
		(width 0.101346)
		(layer "F.Cu")
		(net "M_G_CPU1_SB_DQ<16>")
	)
	(segment
		(start 167.499284 -300.79823)
		(end 167.499284 -300.300644)
		(width 0.101346)
		(layer "F.Cu")
		(net "M_G_CPU1_SB_DQ<16>")
	)
	(segment
		(start 166.318184 -300.79823)
		(end 166.4335 -300.913546)
		(width 0.101346)
		(layer "F.Cu")
		(net "M_G_CPU1_SB_DQ<16>")
	)
	(segment
		(start 163.377626 -300.61027)
		(end 165.55466 -300.61027)
		(width 0.101346)
		(layer "F.Cu")
		(net "M_G_CPU1_SB_DQ<16>")
	)
	(segment
		(start 147.820634 -283.887418)
		(end 150.363174 -283.887418)
		(width 0.10668)
		(layer "F.Cu")
		(net "M_G_CPU1_SB_DQ<16>")
	)
	(segment
		(start 146.387566 -283.786834)
		(end 147.463002 -283.786834)
		(width 0.0762)
		(layer "F.Cu")
		(net "M_G_CPU1_SB_DQ<16>")
	)
	(segment
		(start 166.990268 -300.185328)
		(end 167.105584 -300.300644)
		(width 0.101346)
		(layer "F.Cu")
		(net "M_G_CPU1_SB_DQ<16>")
	)
	(arc
		(start 145.815558 -283.71673)
		(mid 145.845187 -283.859217)
		(end 145.982436 -283.907738)
		(width 0.0762)
		(layer "F.Cu")
		(net "M_G_CPU1_SB_DQ<16>")
	)
	(arc
		(start 145.982436 -283.907738)
		(mid 146.041082 -283.892445)
		(end 146.096482 -283.86786)
		(width 0.0762)
		(layer "F.Cu")
		(net "M_G_CPU1_SB_DQ<16>")
	)
	(arc
		(start 146.104864 -283.863034)
		(mid 146.218588 -283.812733)
		(end 146.340576 -283.788612)
		(width 0.0762)
		(layer "F.Cu")
		(net "M_G_CPU1_SB_DQ<16>")
	)
	(arc
		(start 146.340576 -283.788612)
		(mid 146.364053 -283.787236)
		(end 146.387566 -283.786834)
		(width 0.0762)
		(layer "F.Cu")
		(net "M_G_CPU1_SB_DQ<16>")
	)
	(segment
		(start 162.247834 -299.538644)
		(end 162.64763 -299.139356)
		(width 0.10668)
		(layer "F.Cu")
		(net "M_G_CPU1_SB_DQ<15>")
	)
	(segment
		(start 150.552658 -283.430218)
		(end 156.72816 -289.60572)
		(width 0.10668)
		(layer "F.Cu")
		(net "M_G_CPU1_SB_DQ<15>")
	)
	(segment
		(start 162.64763 -299.139356)
		(end 162.81273 -299.139356)
		(width 0.10668)
		(layer "F.Cu")
		(net "M_G_CPU1_SB_DQ<15>")
	)
	(segment
		(start 156.72816 -293.054786)
		(end 162.365436 -298.692062)
		(width 0.10668)
		(layer "F.Cu")
		(net "M_G_CPU1_SB_DQ<15>")
	)
	(segment
		(start 163.008818 -299.335444)
		(end 164.427916 -299.335444)
		(width 0.10668)
		(layer "F.Cu")
		(net "M_G_CPU1_SB_DQ<15>")
	)
	(segment
		(start 161.19602 -298.252388)
		(end 161.078672 -298.369482)
		(width 0.10668)
		(layer "F.Cu")
		(net "M_G_CPU1_SB_DQ<15>")
	)
	(segment
		(start 161.078672 -298.369482)
		(end 161.078672 -298.534582)
		(width 0.10668)
		(layer "F.Cu")
		(net "M_G_CPU1_SB_DQ<15>")
	)
	(segment
		(start 161.36112 -298.252388)
		(end 161.19602 -298.252388)
		(width 0.10668)
		(layer "F.Cu")
		(net "M_G_CPU1_SB_DQ<15>")
	)
	(segment
		(start 146.39163 -283.32176)
		(end 147.382484 -283.32176)
		(width 0.0762)
		(layer "F.Cu")
		(net "M_G_CPU1_SB_DQ<15>")
	)
	(segment
		(start 162.248088 -298.974256)
		(end 162.082988 -298.974256)
		(width 0.10668)
		(layer "F.Cu")
		(net "M_G_CPU1_SB_DQ<15>")
	)
	(segment
		(start 162.365436 -298.856908)
		(end 162.248088 -298.974256)
		(width 0.10668)
		(layer "F.Cu")
		(net "M_G_CPU1_SB_DQ<15>")
	)
	(segment
		(start 156.72816 -289.60572)
		(end 156.72816 -293.054786)
		(width 0.10668)
		(layer "F.Cu")
		(net "M_G_CPU1_SB_DQ<15>")
	)
	(segment
		(start 147.490942 -283.430218)
		(end 147.988528 -283.430218)
		(width 0.0762)
		(layer "F.Cu")
		(net "M_G_CPU1_SB_DQ<15>")
	)
	(segment
		(start 147.988528 -283.430218)
		(end 150.552658 -283.430218)
		(width 0.10668)
		(layer "F.Cu")
		(net "M_G_CPU1_SB_DQ<15>")
	)
	(segment
		(start 161.078672 -298.534582)
		(end 162.082734 -299.538644)
		(width 0.10668)
		(layer "F.Cu")
		(net "M_G_CPU1_SB_DQ<15>")
	)
	(segment
		(start 162.082734 -299.538644)
		(end 162.247834 -299.538644)
		(width 0.10668)
		(layer "F.Cu")
		(net "M_G_CPU1_SB_DQ<15>")
	)
	(segment
		(start 147.382484 -283.32176)
		(end 147.490942 -283.430218)
		(width 0.0762)
		(layer "F.Cu")
		(net "M_G_CPU1_SB_DQ<15>")
	)
	(segment
		(start 162.082988 -298.974256)
		(end 161.36112 -298.252388)
		(width 0.10668)
		(layer "F.Cu")
		(net "M_G_CPU1_SB_DQ<15>")
	)
	(segment
		(start 146.096482 -283.213048)
		(end 146.104864 -283.217874)
		(width 0.0762)
		(layer "F.Cu")
		(net "M_G_CPU1_SB_DQ<15>")
	)
	(segment
		(start 162.365436 -298.692062)
		(end 162.365436 -298.856908)
		(width 0.10668)
		(layer "F.Cu")
		(net "M_G_CPU1_SB_DQ<15>")
	)
	(segment
		(start 162.81273 -299.139356)
		(end 163.008818 -299.335444)
		(width 0.10668)
		(layer "F.Cu")
		(net "M_G_CPU1_SB_DQ<15>")
	)
	(arc
		(start 146.104864 -283.217874)
		(mid 146.207758 -283.270246)
		(end 146.315938 -283.310584)
		(width 0.0762)
		(layer "F.Cu")
		(net "M_G_CPU1_SB_DQ<15>")
	)
	(arc
		(start 144.493996 -283.294074)
		(mid 144.647745 -283.276565)
		(end 144.790922 -283.217874)
		(width 0.0762)
		(layer "F.Cu")
		(net "M_G_CPU1_SB_DQ<15>")
	)
	(arc
		(start 144.037812 -283.540454)
		(mid 144.233161 -283.356635)
		(end 144.493996 -283.294074)
		(width 0.0762)
		(layer "F.Cu")
		(net "M_G_CPU1_SB_DQ<15>")
	)
	(arc
		(start 146.315938 -283.310584)
		(mid 146.353364 -283.319023)
		(end 146.39163 -283.32176)
		(width 0.0762)
		(layer "F.Cu")
		(net "M_G_CPU1_SB_DQ<15>")
	)
	(arc
		(start 145.730722 -283.217874)
		(mid 145.912973 -283.167524)
		(end 146.096482 -283.213048)
		(width 0.0762)
		(layer "F.Cu")
		(net "M_G_CPU1_SB_DQ<15>")
	)
	(arc
		(start 145.16481 -283.217874)
		(mid 145.447766 -283.294051)
		(end 145.730722 -283.217874)
		(width 0.0762)
		(layer "F.Cu")
		(net "M_G_CPU1_SB_DQ<15>")
	)
	(arc
		(start 144.790922 -283.217874)
		(mid 144.977866 -283.167619)
		(end 145.16481 -283.217874)
		(width 0.0762)
		(layer "F.Cu")
		(net "M_G_CPU1_SB_DQ<15>")
	)
	(segment
		(start 157.40888 -290.367466)
		(end 157.40888 -292.77183)
		(width 0.10668)
		(layer "F.Cu")
		(net "M_G_CPU1_SB_DQ<14>")
	)
	(segment
		(start 157.52572 -290.250626)
		(end 157.40888 -290.367466)
		(width 0.10668)
		(layer "F.Cu")
		(net "M_G_CPU1_SB_DQ<14>")
	)
	(segment
		(start 158.090108 -292.489636)
		(end 157.924754 -292.489636)
		(width 0.10668)
		(layer "F.Cu")
		(net "M_G_CPU1_SB_DQ<14>")
	)
	(segment
		(start 158.206948 -292.372796)
		(end 158.090108 -292.489636)
		(width 0.10668)
		(layer "F.Cu")
		(net "M_G_CPU1_SB_DQ<14>")
	)
	(segment
		(start 150.80234 -282.716478)
		(end 158.206948 -290.121086)
		(width 0.10668)
		(layer "F.Cu")
		(net "M_G_CPU1_SB_DQ<14>")
	)
	(segment
		(start 162.399218 -297.635422)
		(end 164.427916 -297.635422)
		(width 0.10668)
		(layer "F.Cu")
		(net "M_G_CPU1_SB_DQ<14>")
	)
	(segment
		(start 158.206948 -293.443152)
		(end 162.399218 -297.635422)
		(width 0.10668)
		(layer "F.Cu")
		(net "M_G_CPU1_SB_DQ<14>")
	)
	(segment
		(start 157.807914 -290.367466)
		(end 157.691074 -290.250626)
		(width 0.10668)
		(layer "F.Cu")
		(net "M_G_CPU1_SB_DQ<14>")
	)
	(segment
		(start 158.206948 -290.121086)
		(end 158.206948 -292.372796)
		(width 0.10668)
		(layer "F.Cu")
		(net "M_G_CPU1_SB_DQ<14>")
	)
	(segment
		(start 157.924754 -292.489636)
		(end 157.807914 -292.372796)
		(width 0.10668)
		(layer "F.Cu")
		(net "M_G_CPU1_SB_DQ<14>")
	)
	(segment
		(start 157.691074 -290.250626)
		(end 157.52572 -290.250626)
		(width 0.10668)
		(layer "F.Cu")
		(net "M_G_CPU1_SB_DQ<14>")
	)
	(segment
		(start 157.40888 -292.77183)
		(end 157.52572 -292.88867)
		(width 0.10668)
		(layer "F.Cu")
		(net "M_G_CPU1_SB_DQ<14>")
	)
	(segment
		(start 146.38782 -282.357322)
		(end 147.270216 -282.357322)
		(width 0.0762)
		(layer "F.Cu")
		(net "M_G_CPU1_SB_DQ<14>")
	)
	(segment
		(start 147.270216 -282.357322)
		(end 147.629372 -282.716478)
		(width 0.0762)
		(layer "F.Cu")
		(net "M_G_CPU1_SB_DQ<14>")
	)
	(segment
		(start 157.807914 -292.372796)
		(end 157.807914 -290.367466)
		(width 0.10668)
		(layer "F.Cu")
		(net "M_G_CPU1_SB_DQ<14>")
	)
	(segment
		(start 157.52572 -292.88867)
		(end 158.090108 -292.88867)
		(width 0.10668)
		(layer "F.Cu")
		(net "M_G_CPU1_SB_DQ<14>")
	)
	(segment
		(start 158.206948 -293.00551)
		(end 158.206948 -293.443152)
		(width 0.10668)
		(layer "F.Cu")
		(net "M_G_CPU1_SB_DQ<14>")
	)
	(segment
		(start 158.090108 -292.88867)
		(end 158.206948 -293.00551)
		(width 0.10668)
		(layer "F.Cu")
		(net "M_G_CPU1_SB_DQ<14>")
	)
	(segment
		(start 147.629372 -282.716478)
		(end 150.80234 -282.716478)
		(width 0.10668)
		(layer "F.Cu")
		(net "M_G_CPU1_SB_DQ<14>")
	)
	(arc
		(start 146.356832 -282.358592)
		(mid 146.372313 -282.357636)
		(end 146.38782 -282.357322)
		(width 0.0762)
		(layer "F.Cu")
		(net "M_G_CPU1_SB_DQ<14>")
	)
	(arc
		(start 146.015456 -282.475686)
		(mid 146.111165 -282.449974)
		(end 146.200876 -282.407868)
		(width 0.0762)
		(layer "F.Cu")
		(net "M_G_CPU1_SB_DQ<14>")
	)
	(arc
		(start 146.200876 -282.407868)
		(mid 146.276116 -282.374555)
		(end 146.356832 -282.358592)
		(width 0.0762)
		(layer "F.Cu")
		(net "M_G_CPU1_SB_DQ<14>")
	)
	(arc
		(start 145.447766 -282.730448)
		(mid 145.691197 -282.560961)
		(end 145.976848 -282.48102)
		(width 0.0762)
		(layer "F.Cu")
		(net "M_G_CPU1_SB_DQ<14>")
	)
	(arc
		(start 145.976848 -282.48102)
		(mid 145.996197 -282.478682)
		(end 146.015456 -282.475686)
		(width 0.0762)
		(layer "F.Cu")
		(net "M_G_CPU1_SB_DQ<14>")
	)
	(segment
		(start 147.16887 -283.089858)
		(end 147.997164 -283.089858)
		(width 0.0762)
		(layer "F.Cu")
		(net "M_G_CPU1_SB_DQ<13>")
	)
	(segment
		(start 150.694136 -283.089858)
		(end 157.06852 -289.464242)
		(width 0.10668)
		(layer "F.Cu")
		(net "M_G_CPU1_SB_DQ<13>")
	)
	(segment
		(start 146.358356 -283.111194)
		(end 147.146518 -283.11221)
		(width 0.0762)
		(layer "F.Cu")
		(net "M_G_CPU1_SB_DQ<13>")
	)
	(segment
		(start 147.997164 -283.089858)
		(end 150.694136 -283.089858)
		(width 0.10668)
		(layer "F.Cu")
		(net "M_G_CPU1_SB_DQ<13>")
	)
	(segment
		(start 144.507966 -282.730448)
		(end 144.399508 -282.917138)
		(width 0.0762)
		(layer "F.Cu")
		(net "M_G_CPU1_SB_DQ<13>")
	)
	(segment
		(start 144.686528 -283.057854)
		(end 144.69491 -283.053028)
		(width 0.0762)
		(layer "F.Cu")
		(net "M_G_CPU1_SB_DQ<13>")
	)
	(segment
		(start 157.06852 -292.913308)
		(end 162.215576 -298.060364)
		(width 0.10668)
		(layer "F.Cu")
		(net "M_G_CPU1_SB_DQ<13>")
	)
	(segment
		(start 167.632888 -298.485306)
		(end 168.527984 -298.485306)
		(width 0.101346)
		(layer "F.Cu")
		(net "M_G_CPU1_SB_DQ<13>")
	)
	(segment
		(start 162.215576 -298.060364)
		(end 163.377626 -298.060364)
		(width 0.10668)
		(layer "F.Cu")
		(net "M_G_CPU1_SB_DQ<13>")
	)
	(segment
		(start 157.06852 -289.464242)
		(end 157.06852 -292.913308)
		(width 0.10668)
		(layer "F.Cu")
		(net "M_G_CPU1_SB_DQ<13>")
	)
	(segment
		(start 145.260822 -283.053028)
		(end 145.261076 -283.053028)
		(width 0.0762)
		(layer "F.Cu")
		(net "M_G_CPU1_SB_DQ<13>")
	)
	(segment
		(start 163.377626 -298.060364)
		(end 167.207946 -298.060364)
		(width 0.101346)
		(layer "F.Cu")
		(net "M_G_CPU1_SB_DQ<13>")
	)
	(segment
		(start 167.207946 -298.060364)
		(end 167.632888 -298.485306)
		(width 0.101346)
		(layer "F.Cu")
		(net "M_G_CPU1_SB_DQ<13>")
	)
	(segment
		(start 147.146518 -283.11221)
		(end 147.16887 -283.089858)
		(width 0.0762)
		(layer "F.Cu")
		(net "M_G_CPU1_SB_DQ<13>")
	)
	(arc
		(start 144.69491 -283.053028)
		(mid 144.977866 -282.976851)
		(end 145.260822 -283.053028)
		(width 0.0762)
		(layer "F.Cu")
		(net "M_G_CPU1_SB_DQ<13>")
	)
	(arc
		(start 145.261076 -283.053028)
		(mid 145.44802 -283.103352)
		(end 145.634964 -283.053028)
		(width 0.0762)
		(layer "F.Cu")
		(net "M_G_CPU1_SB_DQ<13>")
	)
	(arc
		(start 146.283426 -283.095192)
		(mid 146.320054 -283.107122)
		(end 146.358356 -283.111194)
		(width 0.0762)
		(layer "F.Cu")
		(net "M_G_CPU1_SB_DQ<13>")
	)
	(arc
		(start 145.634964 -283.053028)
		(mid 145.91792 -282.976851)
		(end 146.200876 -283.053028)
		(width 0.0762)
		(layer "F.Cu")
		(net "M_G_CPU1_SB_DQ<13>")
	)
	(arc
		(start 144.399508 -282.917138)
		(mid 144.425425 -283.05018)
		(end 144.551146 -283.10078)
		(width 0.0762)
		(layer "F.Cu")
		(net "M_G_CPU1_SB_DQ<13>")
	)
	(arc
		(start 146.200876 -283.053028)
		(mid 146.24157 -283.075247)
		(end 146.283426 -283.095192)
		(width 0.0762)
		(layer "F.Cu")
		(net "M_G_CPU1_SB_DQ<13>")
	)
	(arc
		(start 144.551146 -283.10078)
		(mid 144.6209 -283.085823)
		(end 144.686528 -283.057854)
		(width 0.0762)
		(layer "F.Cu")
		(net "M_G_CPU1_SB_DQ<13>")
	)
	(segment
		(start 146.387566 -282.166822)
		(end 147.349464 -282.166822)
		(width 0.0762)
		(layer "F.Cu")
		(net "M_G_CPU1_SB_DQ<12>")
	)
	(segment
		(start 147.349464 -282.166822)
		(end 147.55876 -282.376118)
		(width 0.0762)
		(layer "F.Cu")
		(net "M_G_CPU1_SB_DQ<12>")
	)
	(segment
		(start 166.904162 -297.629326)
		(end 167.06723 -297.629326)
		(width 0.101346)
		(layer "F.Cu")
		(net "M_G_CPU1_SB_DQ<12>")
	)
	(segment
		(start 167.182546 -297.51401)
		(end 167.182546 -296.9006)
		(width 0.101346)
		(layer "F.Cu")
		(net "M_G_CPU1_SB_DQ<12>")
	)
	(segment
		(start 147.55876 -282.376118)
		(end 147.871434 -282.376118)
		(width 0.0762)
		(layer "F.Cu")
		(net "M_G_CPU1_SB_DQ<12>")
	)
	(segment
		(start 167.06723 -297.629326)
		(end 167.182546 -297.51401)
		(width 0.101346)
		(layer "F.Cu")
		(net "M_G_CPU1_SB_DQ<12>")
	)
	(segment
		(start 147.871434 -282.376118)
		(end 150.943564 -282.376118)
		(width 0.10668)
		(layer "F.Cu")
		(net "M_G_CPU1_SB_DQ<12>")
	)
	(segment
		(start 150.943564 -282.376118)
		(end 158.547308 -289.979862)
		(width 0.10668)
		(layer "F.Cu")
		(net "M_G_CPU1_SB_DQ<12>")
	)
	(segment
		(start 146.096482 -282.247848)
		(end 146.104864 -282.243022)
		(width 0.0762)
		(layer "F.Cu")
		(net "M_G_CPU1_SB_DQ<12>")
	)
	(segment
		(start 165.989254 -296.360342)
		(end 166.414196 -296.785284)
		(width 0.101346)
		(layer "F.Cu")
		(net "M_G_CPU1_SB_DQ<12>")
	)
	(segment
		(start 167.297862 -296.785284)
		(end 168.527984 -296.785284)
		(width 0.101346)
		(layer "F.Cu")
		(net "M_G_CPU1_SB_DQ<12>")
	)
	(segment
		(start 166.788846 -297.51401)
		(end 166.904162 -297.629326)
		(width 0.101346)
		(layer "F.Cu")
		(net "M_G_CPU1_SB_DQ<12>")
	)
	(segment
		(start 145.91792 -281.920442)
		(end 145.815558 -282.096718)
		(width 0.0762)
		(layer "F.Cu")
		(net "M_G_CPU1_SB_DQ<12>")
	)
	(segment
		(start 161.605976 -296.360342)
		(end 163.377626 -296.360342)
		(width 0.10668)
		(layer "F.Cu")
		(net "M_G_CPU1_SB_DQ<12>")
	)
	(segment
		(start 158.547308 -293.301674)
		(end 161.605976 -296.360342)
		(width 0.10668)
		(layer "F.Cu")
		(net "M_G_CPU1_SB_DQ<12>")
	)
	(segment
		(start 163.377626 -296.360342)
		(end 165.989254 -296.360342)
		(width 0.101346)
		(layer "F.Cu")
		(net "M_G_CPU1_SB_DQ<12>")
	)
	(segment
		(start 166.67353 -296.785284)
		(end 166.788846 -296.9006)
		(width 0.101346)
		(layer "F.Cu")
		(net "M_G_CPU1_SB_DQ<12>")
	)
	(segment
		(start 158.547308 -289.979862)
		(end 158.547308 -293.301674)
		(width 0.10668)
		(layer "F.Cu")
		(net "M_G_CPU1_SB_DQ<12>")
	)
	(segment
		(start 166.788846 -296.9006)
		(end 166.788846 -297.51401)
		(width 0.101346)
		(layer "F.Cu")
		(net "M_G_CPU1_SB_DQ<12>")
	)
	(segment
		(start 166.414196 -296.785284)
		(end 166.67353 -296.785284)
		(width 0.101346)
		(layer "F.Cu")
		(net "M_G_CPU1_SB_DQ<12>")
	)
	(segment
		(start 167.182546 -296.9006)
		(end 167.297862 -296.785284)
		(width 0.101346)
		(layer "F.Cu")
		(net "M_G_CPU1_SB_DQ<12>")
	)
	(arc
		(start 145.815558 -282.096718)
		(mid 145.845187 -282.239205)
		(end 145.982436 -282.287726)
		(width 0.0762)
		(layer "F.Cu")
		(net "M_G_CPU1_SB_DQ<12>")
	)
	(arc
		(start 145.982436 -282.287726)
		(mid 146.041082 -282.272433)
		(end 146.096482 -282.247848)
		(width 0.0762)
		(layer "F.Cu")
		(net "M_G_CPU1_SB_DQ<12>")
	)
	(arc
		(start 146.340576 -282.1686)
		(mid 146.364053 -282.167224)
		(end 146.387566 -282.166822)
		(width 0.0762)
		(layer "F.Cu")
		(net "M_G_CPU1_SB_DQ<12>")
	)
	(arc
		(start 146.104864 -282.243022)
		(mid 146.218588 -282.192721)
		(end 146.340576 -282.1686)
		(width 0.0762)
		(layer "F.Cu")
		(net "M_G_CPU1_SB_DQ<12>")
	)
	(segment
		(start 163.047426 -292.800786)
		(end 162.882326 -292.800786)
		(width 0.10668)
		(layer "F.Cu")
		(net "M_G_CPU1_SB_DQ<11>")
	)
	(segment
		(start 146.096482 -279.973024)
		(end 146.104864 -279.97785)
		(width 0.0762)
		(layer "F.Cu")
		(net "M_G_CPU1_SB_DQ<11>")
	)
	(segment
		(start 160.699704 -289.275774)
		(end 160.780984 -289.194494)
		(width 0.10668)
		(layer "F.Cu")
		(net "M_G_CPU1_SB_DQ<11>")
	)
	(segment
		(start 158.442152 -287.018222)
		(end 158.523432 -286.936942)
		(width 0.10668)
		(layer "F.Cu")
		(net "M_G_CPU1_SB_DQ<11>")
	)
	(segment
		(start 161.546286 -290.122356)
		(end 161.546286 -290.287456)
		(width 0.10668)
		(layer "F.Cu")
		(net "M_G_CPU1_SB_DQ<11>")
	)
	(segment
		(start 162.882326 -292.800786)
		(end 162.477958 -292.396418)
		(width 0.10668)
		(layer "F.Cu")
		(net "M_G_CPU1_SB_DQ<11>")
	)
	(segment
		(start 164.031168 -293.38524)
		(end 164.427916 -293.38524)
		(width 0.10668)
		(layer "F.Cu")
		(net "M_G_CPU1_SB_DQ<11>")
	)
	(segment
		(start 161.82848 -290.40455)
		(end 161.90976 -290.32327)
		(width 0.10668)
		(layer "F.Cu")
		(net "M_G_CPU1_SB_DQ<11>")
	)
	(segment
		(start 159.370014 -287.618424)
		(end 159.370014 -287.783524)
		(width 0.10668)
		(layer "F.Cu")
		(net "M_G_CPU1_SB_DQ<11>")
	)
	(segment
		(start 160.981898 -289.723068)
		(end 161.098992 -289.840162)
		(width 0.10668)
		(layer "F.Cu")
		(net "M_G_CPU1_SB_DQ<11>")
	)
	(segment
		(start 147.54352 -279.786842)
		(end 147.850606 -279.786842)
		(width 0.0762)
		(layer "F.Cu")
		(net "M_G_CPU1_SB_DQ<11>")
	)
	(segment
		(start 163.611814 -292.965886)
		(end 164.031168 -293.38524)
		(width 0.10668)
		(layer "F.Cu")
		(net "M_G_CPU1_SB_DQ<11>")
	)
	(segment
		(start 157.712664 -286.453834)
		(end 157.877764 -286.453834)
		(width 0.10668)
		(layer "F.Cu")
		(net "M_G_CPU1_SB_DQ<11>")
	)
	(segment
		(start 146.39163 -280.081736)
		(end 147.248626 -280.081736)
		(width 0.0762)
		(layer "F.Cu")
		(net "M_G_CPU1_SB_DQ<11>")
	)
	(segment
		(start 161.510472 -289.758882)
		(end 161.627566 -289.875976)
		(width 0.10668)
		(layer "F.Cu")
		(net "M_G_CPU1_SB_DQ<11>")
	)
	(segment
		(start 158.124144 -286.372554)
		(end 158.241238 -286.489648)
		(width 0.10668)
		(layer "F.Cu")
		(net "M_G_CPU1_SB_DQ<11>")
	)
	(segment
		(start 158.724346 -287.465516)
		(end 158.84144 -287.58261)
		(width 0.10668)
		(layer "F.Cu")
		(net "M_G_CPU1_SB_DQ<11>")
	)
	(segment
		(start 159.25292 -287.50133)
		(end 159.370014 -287.618424)
		(width 0.10668)
		(layer "F.Cu")
		(net "M_G_CPU1_SB_DQ<11>")
	)
	(segment
		(start 161.546286 -290.287456)
		(end 161.66338 -290.40455)
		(width 0.10668)
		(layer "F.Cu")
		(net "M_G_CPU1_SB_DQ<11>")
	)
	(segment
		(start 159.934402 -288.182812)
		(end 159.934402 -288.347912)
		(width 0.10668)
		(layer "F.Cu")
		(net "M_G_CPU1_SB_DQ<11>")
	)
	(segment
		(start 158.805626 -287.219136)
		(end 158.724346 -287.300416)
		(width 0.10668)
		(layer "F.Cu")
		(net "M_G_CPU1_SB_DQ<11>")
	)
	(segment
		(start 157.877764 -286.453834)
		(end 157.959044 -286.372554)
		(width 0.10668)
		(layer "F.Cu")
		(net "M_G_CPU1_SB_DQ<11>")
	)
	(segment
		(start 157.959044 -286.372554)
		(end 158.124144 -286.372554)
		(width 0.10668)
		(layer "F.Cu")
		(net "M_G_CPU1_SB_DQ<11>")
	)
	(segment
		(start 159.288734 -288.029904)
		(end 159.405828 -288.146998)
		(width 0.10668)
		(layer "F.Cu")
		(net "M_G_CPU1_SB_DQ<11>")
	)
	(segment
		(start 160.49879 -288.7472)
		(end 160.49879 -288.9123)
		(width 0.10668)
		(layer "F.Cu")
		(net "M_G_CPU1_SB_DQ<11>")
	)
	(segment
		(start 160.216596 -288.630106)
		(end 160.381696 -288.630106)
		(width 0.10668)
		(layer "F.Cu")
		(net "M_G_CPU1_SB_DQ<11>")
	)
	(segment
		(start 161.264092 -289.840162)
		(end 161.345372 -289.758882)
		(width 0.10668)
		(layer "F.Cu")
		(net "M_G_CPU1_SB_DQ<11>")
	)
	(segment
		(start 159.405828 -288.146998)
		(end 159.570928 -288.146998)
		(width 0.10668)
		(layer "F.Cu")
		(net "M_G_CPU1_SB_DQ<11>")
	)
	(segment
		(start 162.191954 -290.605464)
		(end 162.110674 -290.686744)
		(width 0.10668)
		(layer "F.Cu")
		(net "M_G_CPU1_SB_DQ<11>")
	)
	(segment
		(start 160.981898 -289.557968)
		(end 160.981898 -289.723068)
		(width 0.10668)
		(layer "F.Cu")
		(net "M_G_CPU1_SB_DQ<11>")
	)
	(segment
		(start 160.946084 -289.194494)
		(end 161.063178 -289.311588)
		(width 0.10668)
		(layer "F.Cu")
		(net "M_G_CPU1_SB_DQ<11>")
	)
	(segment
		(start 161.66338 -290.40455)
		(end 161.82848 -290.40455)
		(width 0.10668)
		(layer "F.Cu")
		(net "M_G_CPU1_SB_DQ<11>")
	)
	(segment
		(start 158.159958 -286.736028)
		(end 158.159958 -286.901128)
		(width 0.10668)
		(layer "F.Cu")
		(net "M_G_CPU1_SB_DQ<11>")
	)
	(segment
		(start 159.08782 -287.50133)
		(end 159.25292 -287.50133)
		(width 0.10668)
		(layer "F.Cu")
		(net "M_G_CPU1_SB_DQ<11>")
	)
	(segment
		(start 160.41751 -288.99358)
		(end 160.41751 -289.15868)
		(width 0.10668)
		(layer "F.Cu")
		(net "M_G_CPU1_SB_DQ<11>")
	)
	(segment
		(start 161.627566 -290.041076)
		(end 161.546286 -290.122356)
		(width 0.10668)
		(layer "F.Cu")
		(net "M_G_CPU1_SB_DQ<11>")
	)
	(segment
		(start 147.248626 -280.081736)
		(end 147.54352 -279.786842)
		(width 0.0762)
		(layer "F.Cu")
		(net "M_G_CPU1_SB_DQ<11>")
	)
	(segment
		(start 162.195764 -292.513512)
		(end 162.195764 -292.678612)
		(width 0.10668)
		(layer "F.Cu")
		(net "M_G_CPU1_SB_DQ<11>")
	)
	(segment
		(start 158.277052 -287.018222)
		(end 158.442152 -287.018222)
		(width 0.10668)
		(layer "F.Cu")
		(net "M_G_CPU1_SB_DQ<11>")
	)
	(segment
		(start 158.159958 -286.901128)
		(end 158.277052 -287.018222)
		(width 0.10668)
		(layer "F.Cu")
		(net "M_G_CPU1_SB_DQ<11>")
	)
	(segment
		(start 158.724346 -287.300416)
		(end 158.724346 -287.465516)
		(width 0.10668)
		(layer "F.Cu")
		(net "M_G_CPU1_SB_DQ<11>")
	)
	(segment
		(start 159.817308 -288.065718)
		(end 159.934402 -288.182812)
		(width 0.10668)
		(layer "F.Cu")
		(net "M_G_CPU1_SB_DQ<11>")
	)
	(segment
		(start 161.098992 -289.840162)
		(end 161.264092 -289.840162)
		(width 0.10668)
		(layer "F.Cu")
		(net "M_G_CPU1_SB_DQ<11>")
	)
	(segment
		(start 158.805626 -287.054036)
		(end 158.805626 -287.219136)
		(width 0.10668)
		(layer "F.Cu")
		(net "M_G_CPU1_SB_DQ<11>")
	)
	(segment
		(start 162.191954 -290.440364)
		(end 162.191954 -290.605464)
		(width 0.10668)
		(layer "F.Cu")
		(net "M_G_CPU1_SB_DQ<11>")
	)
	(segment
		(start 159.288734 -287.864804)
		(end 159.288734 -288.029904)
		(width 0.10668)
		(layer "F.Cu")
		(net "M_G_CPU1_SB_DQ<11>")
	)
	(segment
		(start 163.16452 -292.518592)
		(end 163.16452 -292.683692)
		(width 0.10668)
		(layer "F.Cu")
		(net "M_G_CPU1_SB_DQ<11>")
	)
	(segment
		(start 159.853122 -288.429192)
		(end 159.853122 -288.594292)
		(width 0.10668)
		(layer "F.Cu")
		(net "M_G_CPU1_SB_DQ<11>")
	)
	(segment
		(start 162.2806 -291.02177)
		(end 162.2806 -291.634672)
		(width 0.10668)
		(layer "F.Cu")
		(net "M_G_CPU1_SB_DQ<11>")
	)
	(segment
		(start 162.882326 -293.365174)
		(end 163.047426 -293.365174)
		(width 0.10668)
		(layer "F.Cu")
		(net "M_G_CPU1_SB_DQ<11>")
	)
	(segment
		(start 163.047426 -293.365174)
		(end 163.446714 -292.965886)
		(width 0.10668)
		(layer "F.Cu")
		(net "M_G_CPU1_SB_DQ<11>")
	)
	(segment
		(start 159.570928 -288.146998)
		(end 159.652208 -288.065718)
		(width 0.10668)
		(layer "F.Cu")
		(net "M_G_CPU1_SB_DQ<11>")
	)
	(segment
		(start 151.045672 -279.786842)
		(end 157.712664 -286.453834)
		(width 0.10668)
		(layer "F.Cu")
		(net "M_G_CPU1_SB_DQ<11>")
	)
	(segment
		(start 161.345372 -289.758882)
		(end 161.510472 -289.758882)
		(width 0.10668)
		(layer "F.Cu")
		(net "M_G_CPU1_SB_DQ<11>")
	)
	(segment
		(start 163.16452 -292.683692)
		(end 163.047426 -292.800786)
		(width 0.10668)
		(layer "F.Cu")
		(net "M_G_CPU1_SB_DQ<11>")
	)
	(segment
		(start 159.00654 -287.58261)
		(end 159.08782 -287.50133)
		(width 0.10668)
		(layer "F.Cu")
		(net "M_G_CPU1_SB_DQ<11>")
	)
	(segment
		(start 160.381696 -288.630106)
		(end 160.49879 -288.7472)
		(width 0.10668)
		(layer "F.Cu")
		(net "M_G_CPU1_SB_DQ<11>")
	)
	(segment
		(start 159.853122 -288.594292)
		(end 159.970216 -288.711386)
		(width 0.10668)
		(layer "F.Cu")
		(net "M_G_CPU1_SB_DQ<11>")
	)
	(segment
		(start 162.110674 -290.851844)
		(end 162.2806 -291.02177)
		(width 0.10668)
		(layer "F.Cu")
		(net "M_G_CPU1_SB_DQ<11>")
	)
	(segment
		(start 162.312858 -292.396418)
		(end 162.195764 -292.513512)
		(width 0.10668)
		(layer "F.Cu")
		(net "M_G_CPU1_SB_DQ<11>")
	)
	(segment
		(start 162.110674 -290.686744)
		(end 162.110674 -290.851844)
		(width 0.10668)
		(layer "F.Cu")
		(net "M_G_CPU1_SB_DQ<11>")
	)
	(segment
		(start 160.135316 -288.711386)
		(end 160.216596 -288.630106)
		(width 0.10668)
		(layer "F.Cu")
		(net "M_G_CPU1_SB_DQ<11>")
	)
	(segment
		(start 161.90976 -290.32327)
		(end 162.07486 -290.32327)
		(width 0.10668)
		(layer "F.Cu")
		(net "M_G_CPU1_SB_DQ<11>")
	)
	(segment
		(start 158.241238 -286.654748)
		(end 158.159958 -286.736028)
		(width 0.10668)
		(layer "F.Cu")
		(net "M_G_CPU1_SB_DQ<11>")
	)
	(segment
		(start 161.627566 -289.875976)
		(end 161.627566 -290.041076)
		(width 0.10668)
		(layer "F.Cu")
		(net "M_G_CPU1_SB_DQ<11>")
	)
	(segment
		(start 160.41751 -289.15868)
		(end 160.534604 -289.275774)
		(width 0.10668)
		(layer "F.Cu")
		(net "M_G_CPU1_SB_DQ<11>")
	)
	(segment
		(start 160.780984 -289.194494)
		(end 160.946084 -289.194494)
		(width 0.10668)
		(layer "F.Cu")
		(net "M_G_CPU1_SB_DQ<11>")
	)
	(segment
		(start 162.07486 -290.32327)
		(end 162.191954 -290.440364)
		(width 0.10668)
		(layer "F.Cu")
		(net "M_G_CPU1_SB_DQ<11>")
	)
	(segment
		(start 162.477958 -292.396418)
		(end 162.312858 -292.396418)
		(width 0.10668)
		(layer "F.Cu")
		(net "M_G_CPU1_SB_DQ<11>")
	)
	(segment
		(start 147.850606 -279.786842)
		(end 151.045672 -279.786842)
		(width 0.10668)
		(layer "F.Cu")
		(net "M_G_CPU1_SB_DQ<11>")
	)
	(segment
		(start 158.241238 -286.489648)
		(end 158.241238 -286.654748)
		(width 0.10668)
		(layer "F.Cu")
		(net "M_G_CPU1_SB_DQ<11>")
	)
	(segment
		(start 160.534604 -289.275774)
		(end 160.699704 -289.275774)
		(width 0.10668)
		(layer "F.Cu")
		(net "M_G_CPU1_SB_DQ<11>")
	)
	(segment
		(start 159.970216 -288.711386)
		(end 160.135316 -288.711386)
		(width 0.10668)
		(layer "F.Cu")
		(net "M_G_CPU1_SB_DQ<11>")
	)
	(segment
		(start 159.934402 -288.347912)
		(end 159.853122 -288.429192)
		(width 0.10668)
		(layer "F.Cu")
		(net "M_G_CPU1_SB_DQ<11>")
	)
	(segment
		(start 161.063178 -289.476688)
		(end 160.981898 -289.557968)
		(width 0.10668)
		(layer "F.Cu")
		(net "M_G_CPU1_SB_DQ<11>")
	)
	(segment
		(start 158.523432 -286.936942)
		(end 158.688532 -286.936942)
		(width 0.10668)
		(layer "F.Cu")
		(net "M_G_CPU1_SB_DQ<11>")
	)
	(segment
		(start 158.688532 -286.936942)
		(end 158.805626 -287.054036)
		(width 0.10668)
		(layer "F.Cu")
		(net "M_G_CPU1_SB_DQ<11>")
	)
	(segment
		(start 162.2806 -291.634672)
		(end 163.16452 -292.518592)
		(width 0.10668)
		(layer "F.Cu")
		(net "M_G_CPU1_SB_DQ<11>")
	)
	(segment
		(start 158.84144 -287.58261)
		(end 159.00654 -287.58261)
		(width 0.10668)
		(layer "F.Cu")
		(net "M_G_CPU1_SB_DQ<11>")
	)
	(segment
		(start 159.370014 -287.783524)
		(end 159.288734 -287.864804)
		(width 0.10668)
		(layer "F.Cu")
		(net "M_G_CPU1_SB_DQ<11>")
	)
	(segment
		(start 162.195764 -292.678612)
		(end 162.882326 -293.365174)
		(width 0.10668)
		(layer "F.Cu")
		(net "M_G_CPU1_SB_DQ<11>")
	)
	(segment
		(start 163.446714 -292.965886)
		(end 163.611814 -292.965886)
		(width 0.10668)
		(layer "F.Cu")
		(net "M_G_CPU1_SB_DQ<11>")
	)
	(segment
		(start 160.49879 -288.9123)
		(end 160.41751 -288.99358)
		(width 0.10668)
		(layer "F.Cu")
		(net "M_G_CPU1_SB_DQ<11>")
	)
	(segment
		(start 161.063178 -289.311588)
		(end 161.063178 -289.476688)
		(width 0.10668)
		(layer "F.Cu")
		(net "M_G_CPU1_SB_DQ<11>")
	)
	(segment
		(start 159.652208 -288.065718)
		(end 159.817308 -288.065718)
		(width 0.10668)
		(layer "F.Cu")
		(net "M_G_CPU1_SB_DQ<11>")
	)
	(arc
		(start 144.037812 -280.30043)
		(mid 144.233161 -280.116611)
		(end 144.493996 -280.05405)
		(width 0.0762)
		(layer "F.Cu")
		(net "M_G_CPU1_SB_DQ<11>")
	)
	(arc
		(start 144.790922 -279.97785)
		(mid 144.977866 -279.927595)
		(end 145.16481 -279.97785)
		(width 0.0762)
		(layer "F.Cu")
		(net "M_G_CPU1_SB_DQ<11>")
	)
	(arc
		(start 144.493996 -280.05405)
		(mid 144.647745 -280.036541)
		(end 144.790922 -279.97785)
		(width 0.0762)
		(layer "F.Cu")
		(net "M_G_CPU1_SB_DQ<11>")
	)
	(arc
		(start 146.315938 -280.07056)
		(mid 146.353364 -280.078999)
		(end 146.39163 -280.081736)
		(width 0.0762)
		(layer "F.Cu")
		(net "M_G_CPU1_SB_DQ<11>")
	)
	(arc
		(start 146.104864 -279.97785)
		(mid 146.207758 -280.030222)
		(end 146.315938 -280.07056)
		(width 0.0762)
		(layer "F.Cu")
		(net "M_G_CPU1_SB_DQ<11>")
	)
	(arc
		(start 145.16481 -279.97785)
		(mid 145.447766 -280.054027)
		(end 145.730722 -279.97785)
		(width 0.0762)
		(layer "F.Cu")
		(net "M_G_CPU1_SB_DQ<11>")
	)
	(arc
		(start 145.730722 -279.97785)
		(mid 145.912973 -279.9275)
		(end 146.096482 -279.973024)
		(width 0.0762)
		(layer "F.Cu")
		(net "M_G_CPU1_SB_DQ<11>")
	)
	(segment
		(start 153.673048 -280.585672)
		(end 153.838148 -280.585672)
		(width 0.10668)
		(layer "F.Cu")
		(net "M_G_CPU1_SB_DQ<10>")
	)
	(segment
		(start 156.487368 -283.882846)
		(end 156.618686 -284.014164)
		(width 0.10668)
		(layer "F.Cu")
		(net "M_G_CPU1_SB_DQ<10>")
	)
	(segment
		(start 157.051756 -284.447234)
		(end 157.183074 -284.578552)
		(width 0.10668)
		(layer "F.Cu")
		(net "M_G_CPU1_SB_DQ<10>")
	)
	(segment
		(start 157.142942 -284.92069)
		(end 157.532324 -285.310072)
		(width 0.10668)
		(layer "F.Cu")
		(net "M_G_CPU1_SB_DQ<10>")
	)
	(segment
		(start 154.51963 -281.267154)
		(end 154.51963 -281.432254)
		(width 0.10668)
		(layer "F.Cu")
		(net "M_G_CPU1_SB_DQ<10>")
	)
	(segment
		(start 156.336492 -283.882846)
		(end 156.487368 -283.882846)
		(width 0.10668)
		(layer "F.Cu")
		(net "M_G_CPU1_SB_DQ<10>")
	)
	(segment
		(start 152.758648 -280.371296)
		(end 153.10866 -280.021284)
		(width 0.10668)
		(layer "F.Cu")
		(net "M_G_CPU1_SB_DQ<10>")
	)
	(segment
		(start 153.722324 -281.500072)
		(end 153.887424 -281.500072)
		(width 0.10668)
		(layer "F.Cu")
		(net "M_G_CPU1_SB_DQ<10>")
	)
	(segment
		(start 163.552886 -291.685218)
		(end 164.427916 -291.685218)
		(width 0.10668)
		(layer "F.Cu")
		(net "M_G_CPU1_SB_DQ<10>")
	)
	(segment
		(start 154.51963 -281.432254)
		(end 154.169618 -281.782266)
		(width 0.10668)
		(layer "F.Cu")
		(net "M_G_CPU1_SB_DQ<10>")
	)
	(segment
		(start 147.247864 -279.117298)
		(end 147.25904 -279.106122)
		(width 0.0762)
		(layer "F.Cu")
		(net "M_G_CPU1_SB_DQ<10>")
	)
	(segment
		(start 152.709372 -279.456896)
		(end 152.826466 -279.57399)
		(width 0.10668)
		(layer "F.Cu")
		(net "M_G_CPU1_SB_DQ<10>")
	)
	(segment
		(start 154.169618 -281.947366)
		(end 154.286712 -282.06446)
		(width 0.10668)
		(layer "F.Cu")
		(net "M_G_CPU1_SB_DQ<10>")
	)
	(segment
		(start 156.860494 -284.48762)
		(end 156.90088 -284.447234)
		(width 0.10668)
		(layer "F.Cu")
		(net "M_G_CPU1_SB_DQ<10>")
	)
	(segment
		(start 152.19426 -279.806908)
		(end 152.544272 -279.456896)
		(width 0.10668)
		(layer "F.Cu")
		(net "M_G_CPU1_SB_DQ<10>")
	)
	(segment
		(start 154.451812 -282.06446)
		(end 154.801824 -281.714448)
		(width 0.10668)
		(layer "F.Cu")
		(net "M_G_CPU1_SB_DQ<10>")
	)
	(segment
		(start 156.578554 -284.205426)
		(end 156.578554 -284.356302)
		(width 0.10668)
		(layer "F.Cu")
		(net "M_G_CPU1_SB_DQ<10>")
	)
	(segment
		(start 156.618686 -284.014164)
		(end 156.61894 -284.16504)
		(width 0.10668)
		(layer "F.Cu")
		(net "M_G_CPU1_SB_DQ<10>")
	)
	(segment
		(start 155.16733 -282.794456)
		(end 155.207716 -282.75407)
		(width 0.10668)
		(layer "F.Cu")
		(net "M_G_CPU1_SB_DQ<10>")
	)
	(segment
		(start 162.96132 -290.223956)
		(end 162.96132 -291.093652)
		(width 0.10668)
		(layer "F.Cu")
		(net "M_G_CPU1_SB_DQ<10>")
	)
	(segment
		(start 152.476454 -280.254202)
		(end 152.593548 -280.371296)
		(width 0.10668)
		(layer "F.Cu")
		(net "M_G_CPU1_SB_DQ<10>")
	)
	(segment
		(start 152.544272 -279.456896)
		(end 152.709372 -279.456896)
		(width 0.10668)
		(layer "F.Cu")
		(net "M_G_CPU1_SB_DQ<10>")
	)
	(segment
		(start 153.955242 -280.702766)
		(end 153.955242 -280.867866)
		(width 0.10668)
		(layer "F.Cu")
		(net "M_G_CPU1_SB_DQ<10>")
	)
	(segment
		(start 152.004522 -279.267158)
		(end 152.004522 -279.432258)
		(width 0.10668)
		(layer "F.Cu")
		(net "M_G_CPU1_SB_DQ<10>")
	)
	(segment
		(start 155.731718 -283.358844)
		(end 155.772104 -283.318458)
		(width 0.10668)
		(layer "F.Cu")
		(net "M_G_CPU1_SB_DQ<10>")
	)
	(segment
		(start 156.014166 -283.791914)
		(end 156.145738 -283.923486)
		(width 0.10668)
		(layer "F.Cu")
		(net "M_G_CPU1_SB_DQ<10>")
	)
	(segment
		(start 153.60523 -281.382978)
		(end 153.722324 -281.500072)
		(width 0.10668)
		(layer "F.Cu")
		(net "M_G_CPU1_SB_DQ<10>")
	)
	(segment
		(start 156.145738 -283.923486)
		(end 156.296106 -283.923232)
		(width 0.10668)
		(layer "F.Cu")
		(net "M_G_CPU1_SB_DQ<10>")
	)
	(segment
		(start 158.047436 -285.310072)
		(end 162.96132 -290.223956)
		(width 0.10668)
		(layer "F.Cu")
		(net "M_G_CPU1_SB_DQ<10>")
	)
	(segment
		(start 155.016962 -282.79471)
		(end 155.16733 -282.794456)
		(width 0.10668)
		(layer "F.Cu")
		(net "M_G_CPU1_SB_DQ<10>")
	)
	(segment
		(start 155.92298 -283.318458)
		(end 156.054298 -283.449776)
		(width 0.10668)
		(layer "F.Cu")
		(net "M_G_CPU1_SB_DQ<10>")
	)
	(segment
		(start 153.955242 -280.867866)
		(end 153.60523 -281.217878)
		(width 0.10668)
		(layer "F.Cu")
		(net "M_G_CPU1_SB_DQ<10>")
	)
	(segment
		(start 156.710126 -284.487874)
		(end 156.860494 -284.48762)
		(width 0.10668)
		(layer "F.Cu")
		(net "M_G_CPU1_SB_DQ<10>")
	)
	(segment
		(start 151.912066 -279.524714)
		(end 151.912066 -279.689814)
		(width 0.10668)
		(layer "F.Cu")
		(net "M_G_CPU1_SB_DQ<10>")
	)
	(segment
		(start 154.286712 -282.06446)
		(end 154.451812 -282.06446)
		(width 0.10668)
		(layer "F.Cu")
		(net "M_G_CPU1_SB_DQ<10>")
	)
	(segment
		(start 152.826466 -279.73909)
		(end 152.476454 -280.089102)
		(width 0.10668)
		(layer "F.Cu")
		(net "M_G_CPU1_SB_DQ<10>")
	)
	(segment
		(start 157.142942 -284.769814)
		(end 157.142942 -284.92069)
		(width 0.10668)
		(layer "F.Cu")
		(net "M_G_CPU1_SB_DQ<10>")
	)
	(segment
		(start 156.61894 -284.16504)
		(end 156.578554 -284.205426)
		(width 0.10668)
		(layer "F.Cu")
		(net "M_G_CPU1_SB_DQ<10>")
	)
	(segment
		(start 157.183328 -284.729428)
		(end 157.142942 -284.769814)
		(width 0.10668)
		(layer "F.Cu")
		(net "M_G_CPU1_SB_DQ<10>")
	)
	(segment
		(start 153.323036 -280.935684)
		(end 153.673048 -280.585672)
		(width 0.10668)
		(layer "F.Cu")
		(net "M_G_CPU1_SB_DQ<10>")
	)
	(segment
		(start 153.390854 -280.303478)
		(end 153.040842 -280.65349)
		(width 0.10668)
		(layer "F.Cu")
		(net "M_G_CPU1_SB_DQ<10>")
	)
	(segment
		(start 152.476454 -280.089102)
		(end 152.476454 -280.254202)
		(width 0.10668)
		(layer "F.Cu")
		(net "M_G_CPU1_SB_DQ<10>")
	)
	(segment
		(start 151.843486 -279.106122)
		(end 152.004522 -279.267158)
		(width 0.10668)
		(layer "F.Cu")
		(net "M_G_CPU1_SB_DQ<10>")
	)
	(segment
		(start 153.838148 -280.585672)
		(end 153.955242 -280.702766)
		(width 0.10668)
		(layer "F.Cu")
		(net "M_G_CPU1_SB_DQ<10>")
	)
	(segment
		(start 156.014166 -283.641038)
		(end 156.014166 -283.791914)
		(width 0.10668)
		(layer "F.Cu")
		(net "M_G_CPU1_SB_DQ<10>")
	)
	(segment
		(start 147.25904 -279.106122)
		(end 147.94865 -279.106122)
		(width 0.0762)
		(layer "F.Cu")
		(net "M_G_CPU1_SB_DQ<10>")
	)
	(segment
		(start 155.772104 -283.318458)
		(end 155.92298 -283.318458)
		(width 0.10668)
		(layer "F.Cu")
		(net "M_G_CPU1_SB_DQ<10>")
	)
	(segment
		(start 153.10866 -280.021284)
		(end 153.27376 -280.021284)
		(width 0.10668)
		(layer "F.Cu")
		(net "M_G_CPU1_SB_DQ<10>")
	)
	(segment
		(start 156.296106 -283.923232)
		(end 156.336492 -283.882846)
		(width 0.10668)
		(layer "F.Cu")
		(net "M_G_CPU1_SB_DQ<10>")
	)
	(segment
		(start 153.60523 -281.217878)
		(end 153.60523 -281.382978)
		(width 0.10668)
		(layer "F.Cu")
		(net "M_G_CPU1_SB_DQ<10>")
	)
	(segment
		(start 147.94865 -279.106122)
		(end 151.843486 -279.106122)
		(width 0.10668)
		(layer "F.Cu")
		(net "M_G_CPU1_SB_DQ<10>")
	)
	(segment
		(start 156.054552 -283.600652)
		(end 156.014166 -283.641038)
		(width 0.10668)
		(layer "F.Cu")
		(net "M_G_CPU1_SB_DQ<10>")
	)
	(segment
		(start 155.207716 -282.75407)
		(end 155.358592 -282.75407)
		(width 0.10668)
		(layer "F.Cu")
		(net "M_G_CPU1_SB_DQ<10>")
	)
	(segment
		(start 154.966924 -281.714448)
		(end 155.084018 -281.831542)
		(width 0.10668)
		(layer "F.Cu")
		(net "M_G_CPU1_SB_DQ<10>")
	)
	(segment
		(start 153.040842 -280.81859)
		(end 153.157936 -280.935684)
		(width 0.10668)
		(layer "F.Cu")
		(net "M_G_CPU1_SB_DQ<10>")
	)
	(segment
		(start 153.040842 -280.65349)
		(end 153.040842 -280.81859)
		(width 0.10668)
		(layer "F.Cu")
		(net "M_G_CPU1_SB_DQ<10>")
	)
	(segment
		(start 156.90088 -284.447234)
		(end 157.051756 -284.447234)
		(width 0.10668)
		(layer "F.Cu")
		(net "M_G_CPU1_SB_DQ<10>")
	)
	(segment
		(start 162.96132 -291.093652)
		(end 163.552886 -291.685218)
		(width 0.10668)
		(layer "F.Cu")
		(net "M_G_CPU1_SB_DQ<10>")
	)
	(segment
		(start 155.358592 -282.75407)
		(end 155.48991 -282.885388)
		(width 0.10668)
		(layer "F.Cu")
		(net "M_G_CPU1_SB_DQ<10>")
	)
	(segment
		(start 154.169618 -281.782266)
		(end 154.169618 -281.947366)
		(width 0.10668)
		(layer "F.Cu")
		(net "M_G_CPU1_SB_DQ<10>")
	)
	(segment
		(start 152.593548 -280.371296)
		(end 152.758648 -280.371296)
		(width 0.10668)
		(layer "F.Cu")
		(net "M_G_CPU1_SB_DQ<10>")
	)
	(segment
		(start 155.449778 -283.07665)
		(end 155.449778 -283.227526)
		(width 0.10668)
		(layer "F.Cu")
		(net "M_G_CPU1_SB_DQ<10>")
	)
	(segment
		(start 155.490164 -283.036264)
		(end 155.449778 -283.07665)
		(width 0.10668)
		(layer "F.Cu")
		(net "M_G_CPU1_SB_DQ<10>")
	)
	(segment
		(start 153.887424 -281.500072)
		(end 154.237436 -281.15006)
		(width 0.10668)
		(layer "F.Cu")
		(net "M_G_CPU1_SB_DQ<10>")
	)
	(segment
		(start 153.390854 -280.138378)
		(end 153.390854 -280.303478)
		(width 0.10668)
		(layer "F.Cu")
		(net "M_G_CPU1_SB_DQ<10>")
	)
	(segment
		(start 154.402536 -281.15006)
		(end 154.51963 -281.267154)
		(width 0.10668)
		(layer "F.Cu")
		(net "M_G_CPU1_SB_DQ<10>")
	)
	(segment
		(start 153.157936 -280.935684)
		(end 153.323036 -280.935684)
		(width 0.10668)
		(layer "F.Cu")
		(net "M_G_CPU1_SB_DQ<10>")
	)
	(segment
		(start 155.58135 -283.359098)
		(end 155.731718 -283.358844)
		(width 0.10668)
		(layer "F.Cu")
		(net "M_G_CPU1_SB_DQ<10>")
	)
	(segment
		(start 154.801824 -281.714448)
		(end 154.966924 -281.714448)
		(width 0.10668)
		(layer "F.Cu")
		(net "M_G_CPU1_SB_DQ<10>")
	)
	(segment
		(start 155.084018 -281.831542)
		(end 155.084018 -281.996642)
		(width 0.10668)
		(layer "F.Cu")
		(net "M_G_CPU1_SB_DQ<10>")
	)
	(segment
		(start 154.734006 -282.346654)
		(end 154.734006 -282.511754)
		(width 0.10668)
		(layer "F.Cu")
		(net "M_G_CPU1_SB_DQ<10>")
	)
	(segment
		(start 157.532324 -285.310072)
		(end 158.047436 -285.310072)
		(width 0.10668)
		(layer "F.Cu")
		(net "M_G_CPU1_SB_DQ<10>")
	)
	(segment
		(start 152.004522 -279.432258)
		(end 151.912066 -279.524714)
		(width 0.10668)
		(layer "F.Cu")
		(net "M_G_CPU1_SB_DQ<10>")
	)
	(segment
		(start 155.084018 -281.996642)
		(end 154.734006 -282.346654)
		(width 0.10668)
		(layer "F.Cu")
		(net "M_G_CPU1_SB_DQ<10>")
	)
	(segment
		(start 152.02916 -279.806908)
		(end 152.19426 -279.806908)
		(width 0.10668)
		(layer "F.Cu")
		(net "M_G_CPU1_SB_DQ<10>")
	)
	(segment
		(start 156.578554 -284.356302)
		(end 156.710126 -284.487874)
		(width 0.10668)
		(layer "F.Cu")
		(net "M_G_CPU1_SB_DQ<10>")
	)
	(segment
		(start 153.27376 -280.021284)
		(end 153.390854 -280.138378)
		(width 0.10668)
		(layer "F.Cu")
		(net "M_G_CPU1_SB_DQ<10>")
	)
	(segment
		(start 146.38782 -279.117298)
		(end 147.247864 -279.117298)
		(width 0.0762)
		(layer "F.Cu")
		(net "M_G_CPU1_SB_DQ<10>")
	)
	(segment
		(start 157.183074 -284.578552)
		(end 157.183328 -284.729428)
		(width 0.10668)
		(layer "F.Cu")
		(net "M_G_CPU1_SB_DQ<10>")
	)
	(segment
		(start 152.826466 -279.57399)
		(end 152.826466 -279.73909)
		(width 0.10668)
		(layer "F.Cu")
		(net "M_G_CPU1_SB_DQ<10>")
	)
	(segment
		(start 155.449778 -283.227526)
		(end 155.58135 -283.359098)
		(width 0.10668)
		(layer "F.Cu")
		(net "M_G_CPU1_SB_DQ<10>")
	)
	(segment
		(start 154.734006 -282.511754)
		(end 155.016962 -282.79471)
		(width 0.10668)
		(layer "F.Cu")
		(net "M_G_CPU1_SB_DQ<10>")
	)
	(segment
		(start 156.054298 -283.449776)
		(end 156.054552 -283.600652)
		(width 0.10668)
		(layer "F.Cu")
		(net "M_G_CPU1_SB_DQ<10>")
	)
	(segment
		(start 154.237436 -281.15006)
		(end 154.402536 -281.15006)
		(width 0.10668)
		(layer "F.Cu")
		(net "M_G_CPU1_SB_DQ<10>")
	)
	(segment
		(start 155.48991 -282.885388)
		(end 155.490164 -283.036264)
		(width 0.10668)
		(layer "F.Cu")
		(net "M_G_CPU1_SB_DQ<10>")
	)
	(segment
		(start 151.912066 -279.689814)
		(end 152.02916 -279.806908)
		(width 0.10668)
		(layer "F.Cu")
		(net "M_G_CPU1_SB_DQ<10>")
	)
	(arc
		(start 146.356832 -279.118568)
		(mid 146.372313 -279.117612)
		(end 146.38782 -279.117298)
		(width 0.0762)
		(layer "F.Cu")
		(net "M_G_CPU1_SB_DQ<10>")
	)
	(arc
		(start 145.447766 -279.490424)
		(mid 145.691197 -279.320937)
		(end 145.976848 -279.240996)
		(width 0.0762)
		(layer "F.Cu")
		(net "M_G_CPU1_SB_DQ<10>")
	)
	(arc
		(start 145.976848 -279.240996)
		(mid 145.996197 -279.238658)
		(end 146.015456 -279.235662)
		(width 0.0762)
		(layer "F.Cu")
		(net "M_G_CPU1_SB_DQ<10>")
	)
	(arc
		(start 146.200876 -279.167844)
		(mid 146.276116 -279.134531)
		(end 146.356832 -279.118568)
		(width 0.0762)
		(layer "F.Cu")
		(net "M_G_CPU1_SB_DQ<10>")
	)
	(arc
		(start 146.015456 -279.235662)
		(mid 146.111165 -279.20995)
		(end 146.200876 -279.167844)
		(width 0.0762)
		(layer "F.Cu")
		(net "M_G_CPU1_SB_DQ<10>")
	)
	(segment
		(start 166.647368 -281.020266)
		(end 166.762684 -281.135582)
		(width 0.101346)
		(layer "F.Cu")
		(net "M_G_CPU1_SB_DQ<0>")
	)
	(segment
		(start 166.4843 -281.020266)
		(end 166.647368 -281.020266)
		(width 0.101346)
		(layer "F.Cu")
		(net "M_G_CPU1_SB_DQ<0>")
	)
	(segment
		(start 166.368984 -281.794966)
		(end 166.368984 -281.135582)
		(width 0.101346)
		(layer "F.Cu")
		(net "M_G_CPU1_SB_DQ<0>")
	)
	(segment
		(start 147.150074 -274.066762)
		(end 147.381976 -273.83486)
		(width 0.0762)
		(layer "F.Cu")
		(net "M_G_CPU1_SB_DQ<0>")
	)
	(segment
		(start 166.762684 -281.794966)
		(end 166.878 -281.910282)
		(width 0.101346)
		(layer "F.Cu")
		(net "M_G_CPU1_SB_DQ<0>")
	)
	(segment
		(start 163.377626 -281.884882)
		(end 163.403026 -281.910282)
		(width 0.101346)
		(layer "F.Cu")
		(net "M_G_CPU1_SB_DQ<0>")
	)
	(segment
		(start 146.096482 -274.147788)
		(end 146.104864 -274.142962)
		(width 0.0762)
		(layer "F.Cu")
		(net "M_G_CPU1_SB_DQ<0>")
	)
	(segment
		(start 146.387566 -274.066762)
		(end 147.150074 -274.066762)
		(width 0.0762)
		(layer "F.Cu")
		(net "M_G_CPU1_SB_DQ<0>")
	)
	(segment
		(start 166.368984 -281.135582)
		(end 166.4843 -281.020266)
		(width 0.101346)
		(layer "F.Cu")
		(net "M_G_CPU1_SB_DQ<0>")
	)
	(segment
		(start 147.922742 -273.83486)
		(end 155.092908 -273.83486)
		(width 0.10668)
		(layer "F.Cu")
		(net "M_G_CPU1_SB_DQ<0>")
	)
	(segment
		(start 157.354524 -275.13788)
		(end 163.07943 -280.862786)
		(width 0.10668)
		(layer "F.Cu")
		(net "M_G_CPU1_SB_DQ<0>")
	)
	(segment
		(start 166.253668 -281.910282)
		(end 166.368984 -281.794966)
		(width 0.101346)
		(layer "F.Cu")
		(net "M_G_CPU1_SB_DQ<0>")
	)
	(segment
		(start 167.70477 -281.48534)
		(end 168.527984 -281.48534)
		(width 0.101346)
		(layer "F.Cu")
		(net "M_G_CPU1_SB_DQ<0>")
	)
	(segment
		(start 147.381976 -273.83486)
		(end 147.922742 -273.83486)
		(width 0.0762)
		(layer "F.Cu")
		(net "M_G_CPU1_SB_DQ<0>")
	)
	(segment
		(start 167.279828 -281.910282)
		(end 167.70477 -281.48534)
		(width 0.101346)
		(layer "F.Cu")
		(net "M_G_CPU1_SB_DQ<0>")
	)
	(segment
		(start 163.07943 -280.862786)
		(end 163.07943 -281.586686)
		(width 0.10668)
		(layer "F.Cu")
		(net "M_G_CPU1_SB_DQ<0>")
	)
	(segment
		(start 166.878 -281.910282)
		(end 167.279828 -281.910282)
		(width 0.101346)
		(layer "F.Cu")
		(net "M_G_CPU1_SB_DQ<0>")
	)
	(segment
		(start 163.07943 -281.586686)
		(end 163.377626 -281.884882)
		(width 0.10668)
		(layer "F.Cu")
		(net "M_G_CPU1_SB_DQ<0>")
	)
	(segment
		(start 163.403026 -281.910282)
		(end 166.253668 -281.910282)
		(width 0.101346)
		(layer "F.Cu")
		(net "M_G_CPU1_SB_DQ<0>")
	)
	(segment
		(start 156.395928 -275.13788)
		(end 157.354524 -275.13788)
		(width 0.10668)
		(layer "F.Cu")
		(net "M_G_CPU1_SB_DQ<0>")
	)
	(segment
		(start 155.092908 -273.83486)
		(end 156.395928 -275.13788)
		(width 0.10668)
		(layer "F.Cu")
		(net "M_G_CPU1_SB_DQ<0>")
	)
	(segment
		(start 166.762684 -281.135582)
		(end 166.762684 -281.794966)
		(width 0.101346)
		(layer "F.Cu")
		(net "M_G_CPU1_SB_DQ<0>")
	)
	(segment
		(start 145.91792 -273.820382)
		(end 145.815558 -273.996658)
		(width 0.0762)
		(layer "F.Cu")
		(net "M_G_CPU1_SB_DQ<0>")
	)
	(arc
		(start 145.982436 -274.187666)
		(mid 146.041082 -274.172373)
		(end 146.096482 -274.147788)
		(width 0.0762)
		(layer "F.Cu")
		(net "M_G_CPU1_SB_DQ<0>")
	)
	(arc
		(start 146.104864 -274.142962)
		(mid 146.218588 -274.092661)
		(end 146.340576 -274.06854)
		(width 0.0762)
		(layer "F.Cu")
		(net "M_G_CPU1_SB_DQ<0>")
	)
	(arc
		(start 146.340576 -274.06854)
		(mid 146.364053 -274.067164)
		(end 146.387566 -274.066762)
		(width 0.0762)
		(layer "F.Cu")
		(net "M_G_CPU1_SB_DQ<0>")
	)
	(arc
		(start 145.815558 -273.996658)
		(mid 145.845187 -274.139145)
		(end 145.982436 -274.187666)
		(width 0.0762)
		(layer "F.Cu")
		(net "M_G_CPU1_SB_DQ<0>")
	)
	(segment
		(start 158.763462 -266.588494)
		(end 158.880302 -266.471654)
		(width 0.10668)
		(layer "F.Cu")
		(net "M_G_CPU1_SB_CS_N<1>")
	)
	(segment
		(start 158.763462 -267.152882)
		(end 158.763462 -266.588494)
		(width 0.10668)
		(layer "F.Cu")
		(net "M_G_CPU1_SB_CS_N<1>")
	)
	(segment
		(start 161.30143 -266.588494)
		(end 161.30143 -266.753848)
		(width 0.10668)
		(layer "F.Cu")
		(net "M_G_CPU1_SB_CS_N<1>")
	)
	(segment
		(start 158.880302 -266.471654)
		(end 161.18459 -266.471654)
		(width 0.10668)
		(layer "F.Cu")
		(net "M_G_CPU1_SB_CS_N<1>")
	)
	(segment
		(start 146.42465 -266.147296)
		(end 147.221702 -266.146026)
		(width 0.0762)
		(layer "F.Cu")
		(net "M_G_CPU1_SB_CS_N<1>")
	)
	(segment
		(start 150.527766 -267.269722)
		(end 158.646622 -267.269722)
		(width 0.10668)
		(layer "F.Cu")
		(net "M_G_CPU1_SB_CS_N<1>")
	)
	(segment
		(start 149.40407 -266.146026)
		(end 150.527766 -267.269722)
		(width 0.10668)
		(layer "F.Cu")
		(net "M_G_CPU1_SB_CS_N<1>")
	)
	(segment
		(start 159.279336 -267.269722)
		(end 162.005264 -267.269722)
		(width 0.10668)
		(layer "F.Cu")
		(net "M_G_CPU1_SB_CS_N<1>")
	)
	(segment
		(start 159.162496 -267.152882)
		(end 159.279336 -267.269722)
		(width 0.10668)
		(layer "F.Cu")
		(net "M_G_CPU1_SB_CS_N<1>")
	)
	(segment
		(start 161.30143 -266.753848)
		(end 161.18459 -266.870688)
		(width 0.10668)
		(layer "F.Cu")
		(net "M_G_CPU1_SB_CS_N<1>")
	)
	(segment
		(start 147.747228 -266.146026)
		(end 149.40407 -266.146026)
		(width 0.10668)
		(layer "F.Cu")
		(net "M_G_CPU1_SB_CS_N<1>")
	)
	(segment
		(start 161.18459 -266.870688)
		(end 159.279336 -266.870688)
		(width 0.10668)
		(layer "F.Cu")
		(net "M_G_CPU1_SB_CS_N<1>")
	)
	(segment
		(start 147.221702 -266.146026)
		(end 147.747228 -266.146026)
		(width 0.0762)
		(layer "F.Cu")
		(net "M_G_CPU1_SB_CS_N<1>")
	)
	(segment
		(start 163.470844 -268.735302)
		(end 164.427916 -268.735302)
		(width 0.10668)
		(layer "F.Cu")
		(net "M_G_CPU1_SB_CS_N<1>")
	)
	(segment
		(start 161.18459 -266.471654)
		(end 161.30143 -266.588494)
		(width 0.10668)
		(layer "F.Cu")
		(net "M_G_CPU1_SB_CS_N<1>")
	)
	(segment
		(start 158.646622 -267.269722)
		(end 158.763462 -267.152882)
		(width 0.10668)
		(layer "F.Cu")
		(net "M_G_CPU1_SB_CS_N<1>")
	)
	(segment
		(start 162.005264 -267.269722)
		(end 163.470844 -268.735302)
		(width 0.10668)
		(layer "F.Cu")
		(net "M_G_CPU1_SB_CS_N<1>")
	)
	(segment
		(start 159.162496 -266.987528)
		(end 159.162496 -267.152882)
		(width 0.10668)
		(layer "F.Cu")
		(net "M_G_CPU1_SB_CS_N<1>")
	)
	(segment
		(start 159.279336 -266.870688)
		(end 159.162496 -266.987528)
		(width 0.10668)
		(layer "F.Cu")
		(net "M_G_CPU1_SB_CS_N<1>")
	)
	(arc
		(start 145.447766 -266.530328)
		(mid 145.638053 -266.344902)
		(end 145.896584 -266.283694)
		(width 0.0762)
		(layer "F.Cu")
		(net "M_G_CPU1_SB_CS_N<1>")
	)
	(arc
		(start 146.200876 -266.207748)
		(mid 146.308774 -266.162765)
		(end 146.42465 -266.147296)
		(width 0.0762)
		(layer "F.Cu")
		(net "M_G_CPU1_SB_CS_N<1>")
	)
	(arc
		(start 145.896584 -266.283694)
		(mid 146.05412 -266.267318)
		(end 146.200876 -266.207748)
		(width 0.0762)
		(layer "F.Cu")
		(net "M_G_CPU1_SB_CS_N<1>")
	)
	(segment
		(start 157.41904 -266.589002)
		(end 158.217108 -265.790934)
		(width 0.10668)
		(layer "F.Cu")
		(net "M_G_CPU1_SB_CS_N<0>")
	)
	(segment
		(start 158.217108 -265.790934)
		(end 161.555684 -265.790934)
		(width 0.10668)
		(layer "F.Cu")
		(net "M_G_CPU1_SB_CS_N<0>")
	)
	(segment
		(start 146.39163 -265.501628)
		(end 147.374356 -265.501628)
		(width 0.0762)
		(layer "F.Cu")
		(net "M_G_CPU1_SB_CS_N<0>")
	)
	(segment
		(start 161.555684 -265.790934)
		(end 163.225226 -267.460476)
		(width 0.10668)
		(layer "F.Cu")
		(net "M_G_CPU1_SB_CS_N<0>")
	)
	(segment
		(start 146.096482 -265.392916)
		(end 146.104864 -265.397742)
		(width 0.0762)
		(layer "F.Cu")
		(net "M_G_CPU1_SB_CS_N<0>")
	)
	(segment
		(start 163.225226 -267.460476)
		(end 163.377626 -267.460476)
		(width 0.10668)
		(layer "F.Cu")
		(net "M_G_CPU1_SB_CS_N<0>")
	)
	(segment
		(start 149.686772 -265.465306)
		(end 150.810468 -266.589002)
		(width 0.10668)
		(layer "F.Cu")
		(net "M_G_CPU1_SB_CS_N<0>")
	)
	(segment
		(start 163.377626 -267.460476)
		(end 166.133018 -267.460476)
		(width 0.101346)
		(layer "F.Cu")
		(net "M_G_CPU1_SB_CS_N<0>")
	)
	(segment
		(start 147.862798 -265.465306)
		(end 149.686772 -265.465306)
		(width 0.10668)
		(layer "F.Cu")
		(net "M_G_CPU1_SB_CS_N<0>")
	)
	(segment
		(start 166.55796 -267.885418)
		(end 168.527984 -267.885418)
		(width 0.101346)
		(layer "F.Cu")
		(net "M_G_CPU1_SB_CS_N<0>")
	)
	(segment
		(start 150.810468 -266.589002)
		(end 157.41904 -266.589002)
		(width 0.10668)
		(layer "F.Cu")
		(net "M_G_CPU1_SB_CS_N<0>")
	)
	(segment
		(start 147.410678 -265.465306)
		(end 147.862798 -265.465306)
		(width 0.0762)
		(layer "F.Cu")
		(net "M_G_CPU1_SB_CS_N<0>")
	)
	(segment
		(start 166.133018 -267.460476)
		(end 166.55796 -267.885418)
		(width 0.101346)
		(layer "F.Cu")
		(net "M_G_CPU1_SB_CS_N<0>")
	)
	(segment
		(start 147.374356 -265.501628)
		(end 147.410678 -265.465306)
		(width 0.0762)
		(layer "F.Cu")
		(net "M_G_CPU1_SB_CS_N<0>")
	)
	(arc
		(start 144.037812 -265.720322)
		(mid 144.233161 -265.536503)
		(end 144.493996 -265.473942)
		(width 0.0762)
		(layer "F.Cu")
		(net "M_G_CPU1_SB_CS_N<0>")
	)
	(arc
		(start 146.315938 -265.490452)
		(mid 146.353364 -265.498891)
		(end 146.39163 -265.501628)
		(width 0.0762)
		(layer "F.Cu")
		(net "M_G_CPU1_SB_CS_N<0>")
	)
	(arc
		(start 144.493996 -265.473942)
		(mid 144.647745 -265.456433)
		(end 144.790922 -265.397742)
		(width 0.0762)
		(layer "F.Cu")
		(net "M_G_CPU1_SB_CS_N<0>")
	)
	(arc
		(start 145.730722 -265.397742)
		(mid 145.912973 -265.347392)
		(end 146.096482 -265.392916)
		(width 0.0762)
		(layer "F.Cu")
		(net "M_G_CPU1_SB_CS_N<0>")
	)
	(arc
		(start 144.790922 -265.397742)
		(mid 144.977866 -265.347487)
		(end 145.16481 -265.397742)
		(width 0.0762)
		(layer "F.Cu")
		(net "M_G_CPU1_SB_CS_N<0>")
	)
	(arc
		(start 145.16481 -265.397742)
		(mid 145.447766 -265.473919)
		(end 145.730722 -265.397742)
		(width 0.0762)
		(layer "F.Cu")
		(net "M_G_CPU1_SB_CS_N<0>")
	)
	(arc
		(start 146.104864 -265.397742)
		(mid 146.207758 -265.450114)
		(end 146.315938 -265.490452)
		(width 0.0762)
		(layer "F.Cu")
		(net "M_G_CPU1_SB_CS_N<0>")
	)
	(segment
		(start 163.208462 -273.769074)
		(end 163.091114 -273.886422)
		(width 0.10668)
		(layer "F.Cu")
		(net "M_G_CPU1_SB_CB<7>")
	)
	(segment
		(start 147.294092 -270.361664)
		(end 147.42033 -270.235426)
		(width 0.0762)
		(layer "F.Cu")
		(net "M_G_CPU1_SB_CB<7>")
	)
	(segment
		(start 146.39163 -270.361664)
		(end 147.294092 -270.361664)
		(width 0.0762)
		(layer "F.Cu")
		(net "M_G_CPU1_SB_CB<7>")
	)
	(segment
		(start 161.630614 -272.756122)
		(end 161.513266 -272.87347)
		(width 0.10668)
		(layer "F.Cu")
		(net "M_G_CPU1_SB_CB<7>")
	)
	(segment
		(start 147.84959 -270.235426)
		(end 159.83966 -270.235426)
		(width 0.10668)
		(layer "F.Cu")
		(net "M_G_CPU1_SB_CB<7>")
	)
	(segment
		(start 146.096482 -270.252952)
		(end 146.104864 -270.257778)
		(width 0.0762)
		(layer "F.Cu")
		(net "M_G_CPU1_SB_CB<7>")
	)
	(segment
		(start 162.926014 -273.886422)
		(end 161.795714 -272.756122)
		(width 0.10668)
		(layer "F.Cu")
		(net "M_G_CPU1_SB_CB<7>")
	)
	(segment
		(start 147.42033 -270.235426)
		(end 147.84959 -270.235426)
		(width 0.0762)
		(layer "F.Cu")
		(net "M_G_CPU1_SB_CB<7>")
	)
	(segment
		(start 161.795714 -272.756122)
		(end 161.630614 -272.756122)
		(width 0.10668)
		(layer "F.Cu")
		(net "M_G_CPU1_SB_CB<7>")
	)
	(segment
		(start 163.208462 -273.604228)
		(end 163.208462 -273.769074)
		(width 0.10668)
		(layer "F.Cu")
		(net "M_G_CPU1_SB_CB<7>")
	)
	(segment
		(start 163.160202 -274.685252)
		(end 164.427916 -274.685252)
		(width 0.10668)
		(layer "F.Cu")
		(net "M_G_CPU1_SB_CB<7>")
	)
	(segment
		(start 161.513266 -273.038316)
		(end 163.160202 -274.685252)
		(width 0.10668)
		(layer "F.Cu")
		(net "M_G_CPU1_SB_CB<7>")
	)
	(segment
		(start 163.091114 -273.886422)
		(end 162.926014 -273.886422)
		(width 0.10668)
		(layer "F.Cu")
		(net "M_G_CPU1_SB_CB<7>")
	)
	(segment
		(start 159.83966 -270.235426)
		(end 163.208462 -273.604228)
		(width 0.10668)
		(layer "F.Cu")
		(net "M_G_CPU1_SB_CB<7>")
	)
	(segment
		(start 161.513266 -272.87347)
		(end 161.513266 -273.038316)
		(width 0.10668)
		(layer "F.Cu")
		(net "M_G_CPU1_SB_CB<7>")
	)
	(arc
		(start 146.315938 -270.350488)
		(mid 146.353364 -270.358927)
		(end 146.39163 -270.361664)
		(width 0.0762)
		(layer "F.Cu")
		(net "M_G_CPU1_SB_CB<7>")
	)
	(arc
		(start 145.16481 -270.257778)
		(mid 145.447766 -270.333955)
		(end 145.730722 -270.257778)
		(width 0.0762)
		(layer "F.Cu")
		(net "M_G_CPU1_SB_CB<7>")
	)
	(arc
		(start 144.037812 -270.580358)
		(mid 144.233161 -270.396539)
		(end 144.493996 -270.333978)
		(width 0.0762)
		(layer "F.Cu")
		(net "M_G_CPU1_SB_CB<7>")
	)
	(arc
		(start 146.104864 -270.257778)
		(mid 146.207758 -270.31015)
		(end 146.315938 -270.350488)
		(width 0.0762)
		(layer "F.Cu")
		(net "M_G_CPU1_SB_CB<7>")
	)
	(arc
		(start 144.790922 -270.257778)
		(mid 144.977866 -270.207523)
		(end 145.16481 -270.257778)
		(width 0.0762)
		(layer "F.Cu")
		(net "M_G_CPU1_SB_CB<7>")
	)
	(arc
		(start 145.730722 -270.257778)
		(mid 145.912973 -270.207428)
		(end 146.096482 -270.252952)
		(width 0.0762)
		(layer "F.Cu")
		(net "M_G_CPU1_SB_CB<7>")
	)
	(arc
		(start 144.493996 -270.333978)
		(mid 144.647745 -270.316469)
		(end 144.790922 -270.257778)
		(width 0.0762)
		(layer "F.Cu")
		(net "M_G_CPU1_SB_CB<7>")
	)
	(segment
		(start 152.904698 -268.886686)
		(end 153.021538 -269.003526)
		(width 0.10668)
		(layer "F.Cu")
		(net "M_G_CPU1_SB_CB<6>")
	)
	(segment
		(start 157.809946 -269.003526)
		(end 157.809946 -269.237206)
		(width 0.10668)
		(layer "F.Cu")
		(net "M_G_CPU1_SB_CB<6>")
	)
	(segment
		(start 158.608014 -269.237206)
		(end 158.724854 -269.354046)
		(width 0.10668)
		(layer "F.Cu")
		(net "M_G_CPU1_SB_CB<6>")
	)
	(segment
		(start 154.1018 -269.354046)
		(end 154.21864 -269.237206)
		(width 0.10668)
		(layer "F.Cu")
		(net "M_G_CPU1_SB_CB<6>")
	)
	(segment
		(start 158.20898 -269.237206)
		(end 158.20898 -269.003526)
		(width 0.10668)
		(layer "F.Cu")
		(net "M_G_CPU1_SB_CB<6>")
	)
	(segment
		(start 152.505664 -269.354046)
		(end 152.622504 -269.237206)
		(width 0.10668)
		(layer "F.Cu")
		(net "M_G_CPU1_SB_CB<6>")
	)
	(segment
		(start 157.926786 -269.354046)
		(end 158.09214 -269.354046)
		(width 0.10668)
		(layer "F.Cu")
		(net "M_G_CPU1_SB_CB<6>")
	)
	(segment
		(start 154.33548 -268.886686)
		(end 154.500834 -268.886686)
		(width 0.10668)
		(layer "F.Cu")
		(net "M_G_CPU1_SB_CB<6>")
	)
	(segment
		(start 154.617674 -269.237206)
		(end 154.734514 -269.354046)
		(width 0.10668)
		(layer "F.Cu")
		(net "M_G_CPU1_SB_CB<6>")
	)
	(segment
		(start 153.420572 -269.003526)
		(end 153.537412 -268.886686)
		(width 0.10668)
		(layer "F.Cu")
		(net "M_G_CPU1_SB_CB<6>")
	)
	(segment
		(start 156.496004 -269.354046)
		(end 156.612844 -269.237206)
		(width 0.10668)
		(layer "F.Cu")
		(net "M_G_CPU1_SB_CB<6>")
	)
	(segment
		(start 158.20898 -269.003526)
		(end 158.32582 -268.886686)
		(width 0.10668)
		(layer "F.Cu")
		(net "M_G_CPU1_SB_CB<6>")
	)
	(segment
		(start 152.622504 -269.003526)
		(end 152.739344 -268.886686)
		(width 0.10668)
		(layer "F.Cu")
		(net "M_G_CPU1_SB_CB<6>")
	)
	(segment
		(start 155.133548 -268.886686)
		(end 155.298902 -268.886686)
		(width 0.10668)
		(layer "F.Cu")
		(net "M_G_CPU1_SB_CB<6>")
	)
	(segment
		(start 151.941276 -268.886686)
		(end 152.10663 -268.886686)
		(width 0.10668)
		(layer "F.Cu")
		(net "M_G_CPU1_SB_CB<6>")
	)
	(segment
		(start 157.410912 -269.003526)
		(end 157.527752 -268.886686)
		(width 0.10668)
		(layer "F.Cu")
		(net "M_G_CPU1_SB_CB<6>")
	)
	(segment
		(start 155.697936 -269.354046)
		(end 155.814776 -269.237206)
		(width 0.10668)
		(layer "F.Cu")
		(net "M_G_CPU1_SB_CB<6>")
	)
	(segment
		(start 155.814776 -269.003526)
		(end 155.931616 -268.886686)
		(width 0.10668)
		(layer "F.Cu")
		(net "M_G_CPU1_SB_CB<6>")
	)
	(segment
		(start 155.532582 -269.354046)
		(end 155.697936 -269.354046)
		(width 0.10668)
		(layer "F.Cu")
		(net "M_G_CPU1_SB_CB<6>")
	)
	(segment
		(start 151.707596 -269.354046)
		(end 151.824436 -269.237206)
		(width 0.10668)
		(layer "F.Cu")
		(net "M_G_CPU1_SB_CB<6>")
	)
	(segment
		(start 153.702766 -268.886686)
		(end 153.819606 -269.003526)
		(width 0.10668)
		(layer "F.Cu")
		(net "M_G_CPU1_SB_CB<6>")
	)
	(segment
		(start 163.441634 -272.873724)
		(end 163.55314 -272.98523)
		(width 0.10668)
		(layer "F.Cu")
		(net "M_G_CPU1_SB_CB<6>")
	)
	(segment
		(start 153.819606 -269.003526)
		(end 153.819606 -269.237206)
		(width 0.10668)
		(layer "F.Cu")
		(net "M_G_CPU1_SB_CB<6>")
	)
	(segment
		(start 159.406082 -269.237206)
		(end 159.522922 -269.354046)
		(width 0.10668)
		(layer "F.Cu")
		(net "M_G_CPU1_SB_CB<6>")
	)
	(segment
		(start 151.824436 -269.003526)
		(end 151.941276 -268.886686)
		(width 0.10668)
		(layer "F.Cu")
		(net "M_G_CPU1_SB_CB<6>")
	)
	(segment
		(start 152.34031 -269.354046)
		(end 152.505664 -269.354046)
		(width 0.10668)
		(layer "F.Cu")
		(net "M_G_CPU1_SB_CB<6>")
	)
	(segment
		(start 152.10663 -268.886686)
		(end 152.22347 -269.003526)
		(width 0.10668)
		(layer "F.Cu")
		(net "M_G_CPU1_SB_CB<6>")
	)
	(segment
		(start 156.612844 -269.003526)
		(end 156.729684 -268.886686)
		(width 0.10668)
		(layer "F.Cu")
		(net "M_G_CPU1_SB_CB<6>")
	)
	(segment
		(start 159.007048 -269.003526)
		(end 159.123888 -268.886686)
		(width 0.10668)
		(layer "F.Cu")
		(net "M_G_CPU1_SB_CB<6>")
	)
	(segment
		(start 147.247864 -269.397226)
		(end 147.291044 -269.354046)
		(width 0.0762)
		(layer "F.Cu")
		(net "M_G_CPU1_SB_CB<6>")
	)
	(segment
		(start 159.522922 -269.354046)
		(end 159.92221 -269.354046)
		(width 0.10668)
		(layer "F.Cu")
		(net "M_G_CPU1_SB_CB<6>")
	)
	(segment
		(start 153.819606 -269.237206)
		(end 153.936446 -269.354046)
		(width 0.10668)
		(layer "F.Cu")
		(net "M_G_CPU1_SB_CB<6>")
	)
	(segment
		(start 158.09214 -269.354046)
		(end 158.20898 -269.237206)
		(width 0.10668)
		(layer "F.Cu")
		(net "M_G_CPU1_SB_CB<6>")
	)
	(segment
		(start 153.303732 -269.354046)
		(end 153.420572 -269.237206)
		(width 0.10668)
		(layer "F.Cu")
		(net "M_G_CPU1_SB_CB<6>")
	)
	(segment
		(start 151.824436 -269.237206)
		(end 151.824436 -269.003526)
		(width 0.10668)
		(layer "F.Cu")
		(net "M_G_CPU1_SB_CB<6>")
	)
	(segment
		(start 158.608014 -269.003526)
		(end 158.608014 -269.237206)
		(width 0.10668)
		(layer "F.Cu")
		(net "M_G_CPU1_SB_CB<6>")
	)
	(segment
		(start 159.289242 -268.886686)
		(end 159.406082 -269.003526)
		(width 0.10668)
		(layer "F.Cu")
		(net "M_G_CPU1_SB_CB<6>")
	)
	(segment
		(start 156.729684 -268.886686)
		(end 156.895038 -268.886686)
		(width 0.10668)
		(layer "F.Cu")
		(net "M_G_CPU1_SB_CB<6>")
	)
	(segment
		(start 154.21864 -269.237206)
		(end 154.21864 -269.003526)
		(width 0.10668)
		(layer "F.Cu")
		(net "M_G_CPU1_SB_CB<6>")
	)
	(segment
		(start 155.931616 -268.886686)
		(end 156.09697 -268.886686)
		(width 0.10668)
		(layer "F.Cu")
		(net "M_G_CPU1_SB_CB<6>")
	)
	(segment
		(start 157.693106 -268.886686)
		(end 157.809946 -269.003526)
		(width 0.10668)
		(layer "F.Cu")
		(net "M_G_CPU1_SB_CB<6>")
	)
	(segment
		(start 152.739344 -268.886686)
		(end 152.904698 -268.886686)
		(width 0.10668)
		(layer "F.Cu")
		(net "M_G_CPU1_SB_CB<6>")
	)
	(segment
		(start 146.38782 -269.397226)
		(end 147.247864 -269.397226)
		(width 0.0762)
		(layer "F.Cu")
		(net "M_G_CPU1_SB_CB<6>")
	)
	(segment
		(start 152.22347 -269.237206)
		(end 152.34031 -269.354046)
		(width 0.10668)
		(layer "F.Cu")
		(net "M_G_CPU1_SB_CB<6>")
	)
	(segment
		(start 147.962874 -269.354046)
		(end 151.707596 -269.354046)
		(width 0.10668)
		(layer "F.Cu")
		(net "M_G_CPU1_SB_CB<6>")
	)
	(segment
		(start 157.011878 -269.003526)
		(end 157.011878 -269.237206)
		(width 0.10668)
		(layer "F.Cu")
		(net "M_G_CPU1_SB_CB<6>")
	)
	(segment
		(start 157.410912 -269.237206)
		(end 157.410912 -269.003526)
		(width 0.10668)
		(layer "F.Cu")
		(net "M_G_CPU1_SB_CB<6>")
	)
	(segment
		(start 157.294072 -269.354046)
		(end 157.410912 -269.237206)
		(width 0.10668)
		(layer "F.Cu")
		(net "M_G_CPU1_SB_CB<6>")
	)
	(segment
		(start 157.527752 -268.886686)
		(end 157.693106 -268.886686)
		(width 0.10668)
		(layer "F.Cu")
		(net "M_G_CPU1_SB_CB<6>")
	)
	(segment
		(start 155.415742 -269.237206)
		(end 155.532582 -269.354046)
		(width 0.10668)
		(layer "F.Cu")
		(net "M_G_CPU1_SB_CB<6>")
	)
	(segment
		(start 156.612844 -269.237206)
		(end 156.612844 -269.003526)
		(width 0.10668)
		(layer "F.Cu")
		(net "M_G_CPU1_SB_CB<6>")
	)
	(segment
		(start 163.55314 -272.98523)
		(end 164.427916 -272.98523)
		(width 0.10668)
		(layer "F.Cu")
		(net "M_G_CPU1_SB_CB<6>")
	)
	(segment
		(start 158.32582 -268.886686)
		(end 158.491174 -268.886686)
		(width 0.10668)
		(layer "F.Cu")
		(net "M_G_CPU1_SB_CB<6>")
	)
	(segment
		(start 153.021538 -269.003526)
		(end 153.021538 -269.237206)
		(width 0.10668)
		(layer "F.Cu")
		(net "M_G_CPU1_SB_CB<6>")
	)
	(segment
		(start 147.291044 -269.354046)
		(end 147.962874 -269.354046)
		(width 0.0762)
		(layer "F.Cu")
		(net "M_G_CPU1_SB_CB<6>")
	)
	(segment
		(start 156.09697 -268.886686)
		(end 156.21381 -269.003526)
		(width 0.10668)
		(layer "F.Cu")
		(net "M_G_CPU1_SB_CB<6>")
	)
	(segment
		(start 157.011878 -269.237206)
		(end 157.128718 -269.354046)
		(width 0.10668)
		(layer "F.Cu")
		(net "M_G_CPU1_SB_CB<6>")
	)
	(segment
		(start 157.809946 -269.237206)
		(end 157.926786 -269.354046)
		(width 0.10668)
		(layer "F.Cu")
		(net "M_G_CPU1_SB_CB<6>")
	)
	(segment
		(start 159.92221 -269.354046)
		(end 163.441634 -272.87347)
		(width 0.10668)
		(layer "F.Cu")
		(net "M_G_CPU1_SB_CB<6>")
	)
	(segment
		(start 153.537412 -268.886686)
		(end 153.702766 -268.886686)
		(width 0.10668)
		(layer "F.Cu")
		(net "M_G_CPU1_SB_CB<6>")
	)
	(segment
		(start 158.724854 -269.354046)
		(end 158.890208 -269.354046)
		(width 0.10668)
		(layer "F.Cu")
		(net "M_G_CPU1_SB_CB<6>")
	)
	(segment
		(start 152.22347 -269.003526)
		(end 152.22347 -269.237206)
		(width 0.10668)
		(layer "F.Cu")
		(net "M_G_CPU1_SB_CB<6>")
	)
	(segment
		(start 159.406082 -269.003526)
		(end 159.406082 -269.237206)
		(width 0.10668)
		(layer "F.Cu")
		(net "M_G_CPU1_SB_CB<6>")
	)
	(segment
		(start 153.138378 -269.354046)
		(end 153.303732 -269.354046)
		(width 0.10668)
		(layer "F.Cu")
		(net "M_G_CPU1_SB_CB<6>")
	)
	(segment
		(start 158.890208 -269.354046)
		(end 159.007048 -269.237206)
		(width 0.10668)
		(layer "F.Cu")
		(net "M_G_CPU1_SB_CB<6>")
	)
	(segment
		(start 156.21381 -269.003526)
		(end 156.21381 -269.237206)
		(width 0.10668)
		(layer "F.Cu")
		(net "M_G_CPU1_SB_CB<6>")
	)
	(segment
		(start 156.21381 -269.237206)
		(end 156.33065 -269.354046)
		(width 0.10668)
		(layer "F.Cu")
		(net "M_G_CPU1_SB_CB<6>")
	)
	(segment
		(start 154.617674 -269.003526)
		(end 154.617674 -269.237206)
		(width 0.10668)
		(layer "F.Cu")
		(net "M_G_CPU1_SB_CB<6>")
	)
	(segment
		(start 155.298902 -268.886686)
		(end 155.415742 -269.003526)
		(width 0.10668)
		(layer "F.Cu")
		(net "M_G_CPU1_SB_CB<6>")
	)
	(segment
		(start 152.622504 -269.237206)
		(end 152.622504 -269.003526)
		(width 0.10668)
		(layer "F.Cu")
		(net "M_G_CPU1_SB_CB<6>")
	)
	(segment
		(start 159.123888 -268.886686)
		(end 159.289242 -268.886686)
		(width 0.10668)
		(layer "F.Cu")
		(net "M_G_CPU1_SB_CB<6>")
	)
	(segment
		(start 158.491174 -268.886686)
		(end 158.608014 -269.003526)
		(width 0.10668)
		(layer "F.Cu")
		(net "M_G_CPU1_SB_CB<6>")
	)
	(segment
		(start 154.500834 -268.886686)
		(end 154.617674 -269.003526)
		(width 0.10668)
		(layer "F.Cu")
		(net "M_G_CPU1_SB_CB<6>")
	)
	(segment
		(start 153.420572 -269.237206)
		(end 153.420572 -269.003526)
		(width 0.10668)
		(layer "F.Cu")
		(net "M_G_CPU1_SB_CB<6>")
	)
	(segment
		(start 159.007048 -269.237206)
		(end 159.007048 -269.003526)
		(width 0.10668)
		(layer "F.Cu")
		(net "M_G_CPU1_SB_CB<6>")
	)
	(segment
		(start 154.899868 -269.354046)
		(end 155.016708 -269.237206)
		(width 0.10668)
		(layer "F.Cu")
		(net "M_G_CPU1_SB_CB<6>")
	)
	(segment
		(start 156.895038 -268.886686)
		(end 157.011878 -269.003526)
		(width 0.10668)
		(layer "F.Cu")
		(net "M_G_CPU1_SB_CB<6>")
	)
	(segment
		(start 154.21864 -269.003526)
		(end 154.33548 -268.886686)
		(width 0.10668)
		(layer "F.Cu")
		(net "M_G_CPU1_SB_CB<6>")
	)
	(segment
		(start 156.33065 -269.354046)
		(end 156.496004 -269.354046)
		(width 0.10668)
		(layer "F.Cu")
		(net "M_G_CPU1_SB_CB<6>")
	)
	(segment
		(start 153.021538 -269.237206)
		(end 153.138378 -269.354046)
		(width 0.10668)
		(layer "F.Cu")
		(net "M_G_CPU1_SB_CB<6>")
	)
	(segment
		(start 163.441634 -272.87347)
		(end 163.441634 -272.873724)
		(width 0.10668)
		(layer "F.Cu")
		(net "M_G_CPU1_SB_CB<6>")
	)
	(segment
		(start 155.016708 -269.003526)
		(end 155.133548 -268.886686)
		(width 0.10668)
		(layer "F.Cu")
		(net "M_G_CPU1_SB_CB<6>")
	)
	(segment
		(start 155.016708 -269.237206)
		(end 155.016708 -269.003526)
		(width 0.10668)
		(layer "F.Cu")
		(net "M_G_CPU1_SB_CB<6>")
	)
	(segment
		(start 153.936446 -269.354046)
		(end 154.1018 -269.354046)
		(width 0.10668)
		(layer "F.Cu")
		(net "M_G_CPU1_SB_CB<6>")
	)
	(segment
		(start 155.814776 -269.237206)
		(end 155.814776 -269.003526)
		(width 0.10668)
		(layer "F.Cu")
		(net "M_G_CPU1_SB_CB<6>")
	)
	(segment
		(start 157.128718 -269.354046)
		(end 157.294072 -269.354046)
		(width 0.10668)
		(layer "F.Cu")
		(net "M_G_CPU1_SB_CB<6>")
	)
	(segment
		(start 154.734514 -269.354046)
		(end 154.899868 -269.354046)
		(width 0.10668)
		(layer "F.Cu")
		(net "M_G_CPU1_SB_CB<6>")
	)
	(segment
		(start 155.415742 -269.003526)
		(end 155.415742 -269.237206)
		(width 0.10668)
		(layer "F.Cu")
		(net "M_G_CPU1_SB_CB<6>")
	)
	(arc
		(start 146.356832 -269.398496)
		(mid 146.372313 -269.39754)
		(end 146.38782 -269.397226)
		(width 0.0762)
		(layer "F.Cu")
		(net "M_G_CPU1_SB_CB<6>")
	)
	(arc
		(start 146.200876 -269.447772)
		(mid 146.276116 -269.414459)
		(end 146.356832 -269.398496)
		(width 0.0762)
		(layer "F.Cu")
		(net "M_G_CPU1_SB_CB<6>")
	)
	(arc
		(start 145.447766 -269.770352)
		(mid 145.691197 -269.600865)
		(end 145.976848 -269.520924)
		(width 0.0762)
		(layer "F.Cu")
		(net "M_G_CPU1_SB_CB<6>")
	)
	(arc
		(start 145.976848 -269.520924)
		(mid 145.996197 -269.518586)
		(end 146.015456 -269.51559)
		(width 0.0762)
		(layer "F.Cu")
		(net "M_G_CPU1_SB_CB<6>")
	)
	(arc
		(start 146.015456 -269.51559)
		(mid 146.111165 -269.489878)
		(end 146.200876 -269.447772)
		(width 0.0762)
		(layer "F.Cu")
		(net "M_G_CPU1_SB_CB<6>")
	)
	(segment
		(start 147.168108 -270.152368)
		(end 147.572222 -269.748254)
		(width 0.0762)
		(layer "F.Cu")
		(net "M_G_CPU1_SB_CB<5>")
	)
	(segment
		(start 166.771574 -273.125946)
		(end 166.934642 -273.125946)
		(width 0.101346)
		(layer "F.Cu")
		(net "M_G_CPU1_SB_CB<5>")
	)
	(segment
		(start 165.719506 -273.410426)
		(end 166.144448 -273.835368)
		(width 0.101346)
		(layer "F.Cu")
		(net "M_G_CPU1_SB_CB<5>")
	)
	(segment
		(start 145.260822 -270.092932)
		(end 145.261076 -270.092932)
		(width 0.0762)
		(layer "F.Cu")
		(net "M_G_CPU1_SB_CB<5>")
	)
	(segment
		(start 166.656258 -273.720052)
		(end 166.656258 -273.241262)
		(width 0.101346)
		(layer "F.Cu")
		(net "M_G_CPU1_SB_CB<5>")
	)
	(segment
		(start 147.671028 -269.748254)
		(end 159.834326 -269.748254)
		(width 0.10668)
		(layer "F.Cu")
		(net "M_G_CPU1_SB_CB<5>")
	)
	(segment
		(start 159.834326 -269.748254)
		(end 163.377626 -273.291554)
		(width 0.10668)
		(layer "F.Cu")
		(net "M_G_CPU1_SB_CB<5>")
	)
	(segment
		(start 166.656258 -273.241262)
		(end 166.771574 -273.125946)
		(width 0.101346)
		(layer "F.Cu")
		(net "M_G_CPU1_SB_CB<5>")
	)
	(segment
		(start 144.686528 -270.097758)
		(end 144.69491 -270.092932)
		(width 0.0762)
		(layer "F.Cu")
		(net "M_G_CPU1_SB_CB<5>")
	)
	(segment
		(start 144.507966 -269.770352)
		(end 144.399508 -269.957042)
		(width 0.0762)
		(layer "F.Cu")
		(net "M_G_CPU1_SB_CB<5>")
	)
	(segment
		(start 166.934642 -273.125946)
		(end 167.049958 -273.241262)
		(width 0.101346)
		(layer "F.Cu")
		(net "M_G_CPU1_SB_CB<5>")
	)
	(segment
		(start 166.540942 -273.835368)
		(end 166.656258 -273.720052)
		(width 0.101346)
		(layer "F.Cu")
		(net "M_G_CPU1_SB_CB<5>")
	)
	(segment
		(start 167.049958 -273.241262)
		(end 167.049958 -273.720052)
		(width 0.101346)
		(layer "F.Cu")
		(net "M_G_CPU1_SB_CB<5>")
	)
	(segment
		(start 167.049958 -273.720052)
		(end 167.165274 -273.835368)
		(width 0.101346)
		(layer "F.Cu")
		(net "M_G_CPU1_SB_CB<5>")
	)
	(segment
		(start 147.572222 -269.748254)
		(end 147.671028 -269.748254)
		(width 0.0762)
		(layer "F.Cu")
		(net "M_G_CPU1_SB_CB<5>")
	)
	(segment
		(start 163.496498 -273.410426)
		(end 165.719506 -273.410426)
		(width 0.101346)
		(layer "F.Cu")
		(net "M_G_CPU1_SB_CB<5>")
	)
	(segment
		(start 163.377626 -273.291554)
		(end 163.496498 -273.410426)
		(width 0.101346)
		(layer "F.Cu")
		(net "M_G_CPU1_SB_CB<5>")
	)
	(segment
		(start 146.358356 -270.151098)
		(end 147.168108 -270.152368)
		(width 0.0762)
		(layer "F.Cu")
		(net "M_G_CPU1_SB_CB<5>")
	)
	(segment
		(start 166.144448 -273.835368)
		(end 166.540942 -273.835368)
		(width 0.101346)
		(layer "F.Cu")
		(net "M_G_CPU1_SB_CB<5>")
	)
	(segment
		(start 167.165274 -273.835368)
		(end 168.527984 -273.835368)
		(width 0.101346)
		(layer "F.Cu")
		(net "M_G_CPU1_SB_CB<5>")
	)
	(arc
		(start 146.283426 -270.135096)
		(mid 146.320054 -270.147026)
		(end 146.358356 -270.151098)
		(width 0.0762)
		(layer "F.Cu")
		(net "M_G_CPU1_SB_CB<5>")
	)
	(arc
		(start 145.634964 -270.092932)
		(mid 145.91792 -270.016755)
		(end 146.200876 -270.092932)
		(width 0.0762)
		(layer "F.Cu")
		(net "M_G_CPU1_SB_CB<5>")
	)
	(arc
		(start 146.200876 -270.092932)
		(mid 146.24157 -270.115151)
		(end 146.283426 -270.135096)
		(width 0.0762)
		(layer "F.Cu")
		(net "M_G_CPU1_SB_CB<5>")
	)
	(arc
		(start 144.551146 -270.140684)
		(mid 144.6209 -270.125727)
		(end 144.686528 -270.097758)
		(width 0.0762)
		(layer "F.Cu")
		(net "M_G_CPU1_SB_CB<5>")
	)
	(arc
		(start 144.399508 -269.957042)
		(mid 144.425425 -270.090084)
		(end 144.551146 -270.140684)
		(width 0.0762)
		(layer "F.Cu")
		(net "M_G_CPU1_SB_CB<5>")
	)
	(arc
		(start 145.261076 -270.092932)
		(mid 145.44802 -270.143256)
		(end 145.634964 -270.092932)
		(width 0.0762)
		(layer "F.Cu")
		(net "M_G_CPU1_SB_CB<5>")
	)
	(arc
		(start 144.69491 -270.092932)
		(mid 144.977866 -270.016755)
		(end 145.260822 -270.092932)
		(width 0.0762)
		(layer "F.Cu")
		(net "M_G_CPU1_SB_CB<5>")
	)
	(segment
		(start 151.374348 -268.843506)
		(end 151.374348 -268.641322)
		(width 0.10668)
		(layer "F.Cu")
		(net "M_G_CPU1_SB_CB<4>")
	)
	(segment
		(start 149.895052 -268.524482)
		(end 150.060406 -268.524482)
		(width 0.10668)
		(layer "F.Cu")
		(net "M_G_CPU1_SB_CB<4>")
	)
	(segment
		(start 149.379178 -268.843506)
		(end 149.496018 -268.960346)
		(width 0.10668)
		(layer "F.Cu")
		(net "M_G_CPU1_SB_CB<4>")
	)
	(segment
		(start 150.294086 -268.960346)
		(end 150.45944 -268.960346)
		(width 0.10668)
		(layer "F.Cu")
		(net "M_G_CPU1_SB_CB<4>")
	)
	(segment
		(start 150.060406 -268.524482)
		(end 150.177246 -268.641322)
		(width 0.10668)
		(layer "F.Cu")
		(net "M_G_CPU1_SB_CB<4>")
	)
	(segment
		(start 149.262338 -268.524482)
		(end 149.379178 -268.641322)
		(width 0.10668)
		(layer "F.Cu")
		(net "M_G_CPU1_SB_CB<4>")
	)
	(segment
		(start 146.096482 -269.287752)
		(end 146.104864 -269.282926)
		(width 0.0762)
		(layer "F.Cu")
		(net "M_G_CPU1_SB_CB<4>")
	)
	(segment
		(start 147.199604 -268.864842)
		(end 147.785074 -268.864842)
		(width 0.0762)
		(layer "F.Cu")
		(net "M_G_CPU1_SB_CB<4>")
	)
	(segment
		(start 163.44773 -272.397982)
		(end 163.610036 -272.560288)
		(width 0.101346)
		(layer "F.Cu")
		(net "M_G_CPU1_SB_CB<4>")
	)
	(segment
		(start 166.585138 -272.135346)
		(end 168.527984 -272.135346)
		(width 0.101346)
		(layer "F.Cu")
		(net "M_G_CPU1_SB_CB<4>")
	)
	(segment
		(start 148.69795 -268.960346)
		(end 148.863304 -268.960346)
		(width 0.10668)
		(layer "F.Cu")
		(net "M_G_CPU1_SB_CB<4>")
	)
	(segment
		(start 149.778212 -268.641322)
		(end 149.895052 -268.524482)
		(width 0.10668)
		(layer "F.Cu")
		(net "M_G_CPU1_SB_CB<4>")
	)
	(segment
		(start 148.125434 -268.524482)
		(end 148.46427 -268.524482)
		(width 0.10668)
		(layer "F.Cu")
		(net "M_G_CPU1_SB_CB<4>")
	)
	(segment
		(start 151.257508 -268.960346)
		(end 151.374348 -268.843506)
		(width 0.10668)
		(layer "F.Cu")
		(net "M_G_CPU1_SB_CB<4>")
	)
	(segment
		(start 148.863304 -268.960346)
		(end 148.980144 -268.843506)
		(width 0.10668)
		(layer "F.Cu")
		(net "M_G_CPU1_SB_CB<4>")
	)
	(segment
		(start 150.177246 -268.843506)
		(end 150.294086 -268.960346)
		(width 0.10668)
		(layer "F.Cu")
		(net "M_G_CPU1_SB_CB<4>")
	)
	(segment
		(start 145.91792 -268.960346)
		(end 145.815558 -269.136622)
		(width 0.0762)
		(layer "F.Cu")
		(net "M_G_CPU1_SB_CB<4>")
	)
	(segment
		(start 163.610036 -272.560288)
		(end 166.160196 -272.560288)
		(width 0.101346)
		(layer "F.Cu")
		(net "M_G_CPU1_SB_CB<4>")
	)
	(segment
		(start 148.58111 -268.641322)
		(end 148.58111 -268.843506)
		(width 0.10668)
		(layer "F.Cu")
		(net "M_G_CPU1_SB_CB<4>")
	)
	(segment
		(start 149.778212 -268.843506)
		(end 149.778212 -268.641322)
		(width 0.10668)
		(layer "F.Cu")
		(net "M_G_CPU1_SB_CB<4>")
	)
	(segment
		(start 148.46427 -268.524482)
		(end 148.58111 -268.641322)
		(width 0.10668)
		(layer "F.Cu")
		(net "M_G_CPU1_SB_CB<4>")
	)
	(segment
		(start 151.374348 -268.641322)
		(end 151.491188 -268.524482)
		(width 0.10668)
		(layer "F.Cu")
		(net "M_G_CPU1_SB_CB<4>")
	)
	(segment
		(start 150.975314 -268.843506)
		(end 151.092154 -268.960346)
		(width 0.10668)
		(layer "F.Cu")
		(net "M_G_CPU1_SB_CB<4>")
	)
	(segment
		(start 148.58111 -268.843506)
		(end 148.69795 -268.960346)
		(width 0.10668)
		(layer "F.Cu")
		(net "M_G_CPU1_SB_CB<4>")
	)
	(segment
		(start 149.379178 -268.641322)
		(end 149.379178 -268.843506)
		(width 0.10668)
		(layer "F.Cu")
		(net "M_G_CPU1_SB_CB<4>")
	)
	(segment
		(start 148.980144 -268.843506)
		(end 148.980144 -268.641322)
		(width 0.10668)
		(layer "F.Cu")
		(net "M_G_CPU1_SB_CB<4>")
	)
	(segment
		(start 150.858474 -268.524482)
		(end 150.975314 -268.641322)
		(width 0.10668)
		(layer "F.Cu")
		(net "M_G_CPU1_SB_CB<4>")
	)
	(segment
		(start 150.45944 -268.960346)
		(end 150.57628 -268.843506)
		(width 0.10668)
		(layer "F.Cu")
		(net "M_G_CPU1_SB_CB<4>")
	)
	(segment
		(start 148.980144 -268.641322)
		(end 149.096984 -268.524482)
		(width 0.10668)
		(layer "F.Cu")
		(net "M_G_CPU1_SB_CB<4>")
	)
	(segment
		(start 151.092154 -268.960346)
		(end 151.257508 -268.960346)
		(width 0.10668)
		(layer "F.Cu")
		(net "M_G_CPU1_SB_CB<4>")
	)
	(segment
		(start 150.177246 -268.641322)
		(end 150.177246 -268.843506)
		(width 0.10668)
		(layer "F.Cu")
		(net "M_G_CPU1_SB_CB<4>")
	)
	(segment
		(start 166.160196 -272.560288)
		(end 166.585138 -272.135346)
		(width 0.101346)
		(layer "F.Cu")
		(net "M_G_CPU1_SB_CB<4>")
	)
	(segment
		(start 150.57628 -268.843506)
		(end 150.57628 -268.641322)
		(width 0.10668)
		(layer "F.Cu")
		(net "M_G_CPU1_SB_CB<4>")
	)
	(segment
		(start 150.57628 -268.641322)
		(end 150.69312 -268.524482)
		(width 0.10668)
		(layer "F.Cu")
		(net "M_G_CPU1_SB_CB<4>")
	)
	(segment
		(start 149.096984 -268.524482)
		(end 149.262338 -268.524482)
		(width 0.10668)
		(layer "F.Cu")
		(net "M_G_CPU1_SB_CB<4>")
	)
	(segment
		(start 159.57423 -268.524482)
		(end 163.44773 -272.397982)
		(width 0.10668)
		(layer "F.Cu")
		(net "M_G_CPU1_SB_CB<4>")
	)
	(segment
		(start 147.785074 -268.864842)
		(end 148.125434 -268.524482)
		(width 0.10668)
		(layer "F.Cu")
		(net "M_G_CPU1_SB_CB<4>")
	)
	(segment
		(start 146.387566 -269.206726)
		(end 146.85772 -269.206726)
		(width 0.0762)
		(layer "F.Cu")
		(net "M_G_CPU1_SB_CB<4>")
	)
	(segment
		(start 149.496018 -268.960346)
		(end 149.661372 -268.960346)
		(width 0.10668)
		(layer "F.Cu")
		(net "M_G_CPU1_SB_CB<4>")
	)
	(segment
		(start 146.85772 -269.206726)
		(end 147.199604 -268.864842)
		(width 0.0762)
		(layer "F.Cu")
		(net "M_G_CPU1_SB_CB<4>")
	)
	(segment
		(start 151.491188 -268.524482)
		(end 159.57423 -268.524482)
		(width 0.10668)
		(layer "F.Cu")
		(net "M_G_CPU1_SB_CB<4>")
	)
	(segment
		(start 150.975314 -268.641322)
		(end 150.975314 -268.843506)
		(width 0.10668)
		(layer "F.Cu")
		(net "M_G_CPU1_SB_CB<4>")
	)
	(segment
		(start 149.661372 -268.960346)
		(end 149.778212 -268.843506)
		(width 0.10668)
		(layer "F.Cu")
		(net "M_G_CPU1_SB_CB<4>")
	)
	(segment
		(start 150.69312 -268.524482)
		(end 150.858474 -268.524482)
		(width 0.10668)
		(layer "F.Cu")
		(net "M_G_CPU1_SB_CB<4>")
	)
	(arc
		(start 146.340576 -269.208504)
		(mid 146.364053 -269.207128)
		(end 146.387566 -269.206726)
		(width 0.0762)
		(layer "F.Cu")
		(net "M_G_CPU1_SB_CB<4>")
	)
	(arc
		(start 145.815558 -269.136622)
		(mid 145.845187 -269.279109)
		(end 145.982436 -269.32763)
		(width 0.0762)
		(layer "F.Cu")
		(net "M_G_CPU1_SB_CB<4>")
	)
	(arc
		(start 145.982436 -269.32763)
		(mid 146.041082 -269.312337)
		(end 146.096482 -269.287752)
		(width 0.0762)
		(layer "F.Cu")
		(net "M_G_CPU1_SB_CB<4>")
	)
	(arc
		(start 146.104864 -269.282926)
		(mid 146.218588 -269.232625)
		(end 146.340576 -269.208504)
		(width 0.0762)
		(layer "F.Cu")
		(net "M_G_CPU1_SB_CB<4>")
	)
	(segment
		(start 151.590756 -273.362166)
		(end 151.775922 -273.362166)
		(width 0.10668)
		(layer "F.Cu")
		(net "M_G_CPU1_SB_CB<3>")
	)
	(segment
		(start 153.585926 -273.148298)
		(end 153.771092 -273.148298)
		(width 0.10668)
		(layer "F.Cu")
		(net "M_G_CPU1_SB_CB<3>")
	)
	(segment
		(start 153.372058 -273.362166)
		(end 153.585926 -273.148298)
		(width 0.10668)
		(layer "F.Cu")
		(net "M_G_CPU1_SB_CB<3>")
	)
	(segment
		(start 154.383994 -273.148298)
		(end 154.56916 -273.148298)
		(width 0.10668)
		(layer "F.Cu")
		(net "M_G_CPU1_SB_CB<3>")
	)
	(segment
		(start 148.58365 -273.362166)
		(end 148.797518 -273.148298)
		(width 0.10668)
		(layer "F.Cu")
		(net "M_G_CPU1_SB_CB<3>")
	)
	(segment
		(start 151.191722 -273.148298)
		(end 151.376888 -273.148298)
		(width 0.10668)
		(layer "F.Cu")
		(net "M_G_CPU1_SB_CB<3>")
	)
	(segment
		(start 163.498784 -280.635202)
		(end 164.427916 -280.635202)
		(width 0.10668)
		(layer "F.Cu")
		(net "M_G_CPU1_SB_CB<3>")
	)
	(segment
		(start 148.184616 -273.148298)
		(end 148.398484 -273.362166)
		(width 0.10668)
		(layer "F.Cu")
		(net "M_G_CPU1_SB_CB<3>")
	)
	(segment
		(start 154.56916 -273.148298)
		(end 154.783028 -273.362166)
		(width 0.10668)
		(layer "F.Cu")
		(net "M_G_CPU1_SB_CB<3>")
	)
	(segment
		(start 156.186124 -274.116292)
		(end 156.500322 -273.80184)
		(width 0.10668)
		(layer "F.Cu")
		(net "M_G_CPU1_SB_CB<3>")
	)
	(segment
		(start 147.261326 -273.601688)
		(end 147.714716 -273.148298)
		(width 0.0762)
		(layer "F.Cu")
		(net "M_G_CPU1_SB_CB<3>")
	)
	(segment
		(start 149.595586 -273.148298)
		(end 149.780752 -273.148298)
		(width 0.10668)
		(layer "F.Cu")
		(net "M_G_CPU1_SB_CB<3>")
	)
	(segment
		(start 155.90393 -273.999198)
		(end 156.021024 -274.116292)
		(width 0.10668)
		(layer "F.Cu")
		(net "M_G_CPU1_SB_CB<3>")
	)
	(segment
		(start 156.782516 -273.918934)
		(end 156.782516 -274.084034)
		(width 0.10668)
		(layer "F.Cu")
		(net "M_G_CPU1_SB_CB<3>")
	)
	(segment
		(start 149.99462 -273.362166)
		(end 150.179786 -273.362166)
		(width 0.10668)
		(layer "F.Cu")
		(net "M_G_CPU1_SB_CB<3>")
	)
	(segment
		(start 149.780752 -273.148298)
		(end 149.99462 -273.362166)
		(width 0.10668)
		(layer "F.Cu")
		(net "M_G_CPU1_SB_CB<3>")
	)
	(segment
		(start 156.585412 -274.68068)
		(end 156.750512 -274.68068)
		(width 0.10668)
		(layer "F.Cu")
		(net "M_G_CPU1_SB_CB<3>")
	)
	(segment
		(start 155.182062 -273.148298)
		(end 156.01188 -273.148298)
		(width 0.10668)
		(layer "F.Cu")
		(net "M_G_CPU1_SB_CB<3>")
	)
	(segment
		(start 147.88896 -273.148298)
		(end 148.184616 -273.148298)
		(width 0.10668)
		(layer "F.Cu")
		(net "M_G_CPU1_SB_CB<3>")
	)
	(segment
		(start 156.665422 -273.80184)
		(end 156.782516 -273.918934)
		(width 0.10668)
		(layer "F.Cu")
		(net "M_G_CPU1_SB_CB<3>")
	)
	(segment
		(start 151.376888 -273.148298)
		(end 151.590756 -273.362166)
		(width 0.10668)
		(layer "F.Cu")
		(net "M_G_CPU1_SB_CB<3>")
	)
	(segment
		(start 150.393654 -273.148298)
		(end 150.57882 -273.148298)
		(width 0.10668)
		(layer "F.Cu")
		(net "M_G_CPU1_SB_CB<3>")
	)
	(segment
		(start 156.468318 -274.398486)
		(end 156.468318 -274.563586)
		(width 0.10668)
		(layer "F.Cu")
		(net "M_G_CPU1_SB_CB<3>")
	)
	(segment
		(start 156.01188 -273.148298)
		(end 156.218128 -273.354546)
		(width 0.10668)
		(layer "F.Cu")
		(net "M_G_CPU1_SB_CB<3>")
	)
	(segment
		(start 154.968194 -273.362166)
		(end 155.182062 -273.148298)
		(width 0.10668)
		(layer "F.Cu")
		(net "M_G_CPU1_SB_CB<3>")
	)
	(segment
		(start 156.218128 -273.519646)
		(end 155.90393 -273.834098)
		(width 0.10668)
		(layer "F.Cu")
		(net "M_G_CPU1_SB_CB<3>")
	)
	(segment
		(start 153.98496 -273.362166)
		(end 154.170126 -273.362166)
		(width 0.10668)
		(layer "F.Cu")
		(net "M_G_CPU1_SB_CB<3>")
	)
	(segment
		(start 154.783028 -273.362166)
		(end 154.968194 -273.362166)
		(width 0.10668)
		(layer "F.Cu")
		(net "M_G_CPU1_SB_CB<3>")
	)
	(segment
		(start 149.196552 -273.362166)
		(end 149.381718 -273.362166)
		(width 0.10668)
		(layer "F.Cu")
		(net "M_G_CPU1_SB_CB<3>")
	)
	(segment
		(start 150.179786 -273.362166)
		(end 150.393654 -273.148298)
		(width 0.10668)
		(layer "F.Cu")
		(net "M_G_CPU1_SB_CB<3>")
	)
	(segment
		(start 156.218128 -273.354546)
		(end 156.218128 -273.519646)
		(width 0.10668)
		(layer "F.Cu")
		(net "M_G_CPU1_SB_CB<3>")
	)
	(segment
		(start 156.782516 -274.084034)
		(end 156.468318 -274.398486)
		(width 0.10668)
		(layer "F.Cu")
		(net "M_G_CPU1_SB_CB<3>")
	)
	(segment
		(start 152.973024 -273.148298)
		(end 153.186892 -273.362166)
		(width 0.10668)
		(layer "F.Cu")
		(net "M_G_CPU1_SB_CB<3>")
	)
	(segment
		(start 147.714716 -273.148298)
		(end 147.88896 -273.148298)
		(width 0.0762)
		(layer "F.Cu")
		(net "M_G_CPU1_SB_CB<3>")
	)
	(segment
		(start 151.98979 -273.148298)
		(end 152.174956 -273.148298)
		(width 0.10668)
		(layer "F.Cu")
		(net "M_G_CPU1_SB_CB<3>")
	)
	(segment
		(start 146.096482 -273.492976)
		(end 146.104864 -273.497802)
		(width 0.0762)
		(layer "F.Cu")
		(net "M_G_CPU1_SB_CB<3>")
	)
	(segment
		(start 153.186892 -273.362166)
		(end 153.372058 -273.362166)
		(width 0.10668)
		(layer "F.Cu")
		(net "M_G_CPU1_SB_CB<3>")
	)
	(segment
		(start 153.771092 -273.148298)
		(end 153.98496 -273.362166)
		(width 0.10668)
		(layer "F.Cu")
		(net "M_G_CPU1_SB_CB<3>")
	)
	(segment
		(start 152.57399 -273.362166)
		(end 152.787858 -273.148298)
		(width 0.10668)
		(layer "F.Cu")
		(net "M_G_CPU1_SB_CB<3>")
	)
	(segment
		(start 156.750512 -274.68068)
		(end 157.06471 -274.366228)
		(width 0.10668)
		(layer "F.Cu")
		(net "M_G_CPU1_SB_CB<3>")
	)
	(segment
		(start 148.982684 -273.148298)
		(end 149.196552 -273.362166)
		(width 0.10668)
		(layer "F.Cu")
		(net "M_G_CPU1_SB_CB<3>")
	)
	(segment
		(start 152.388824 -273.362166)
		(end 152.57399 -273.362166)
		(width 0.10668)
		(layer "F.Cu")
		(net "M_G_CPU1_SB_CB<3>")
	)
	(segment
		(start 155.90393 -273.834098)
		(end 155.90393 -273.999198)
		(width 0.10668)
		(layer "F.Cu")
		(net "M_G_CPU1_SB_CB<3>")
	)
	(segment
		(start 149.381718 -273.362166)
		(end 149.595586 -273.148298)
		(width 0.10668)
		(layer "F.Cu")
		(net "M_G_CPU1_SB_CB<3>")
	)
	(segment
		(start 156.500322 -273.80184)
		(end 156.665422 -273.80184)
		(width 0.10668)
		(layer "F.Cu")
		(net "M_G_CPU1_SB_CB<3>")
	)
	(segment
		(start 148.797518 -273.148298)
		(end 148.982684 -273.148298)
		(width 0.10668)
		(layer "F.Cu")
		(net "M_G_CPU1_SB_CB<3>")
	)
	(segment
		(start 148.398484 -273.362166)
		(end 148.58365 -273.362166)
		(width 0.10668)
		(layer "F.Cu")
		(net "M_G_CPU1_SB_CB<3>")
	)
	(segment
		(start 146.39163 -273.601688)
		(end 147.261326 -273.601688)
		(width 0.0762)
		(layer "F.Cu")
		(net "M_G_CPU1_SB_CB<3>")
	)
	(segment
		(start 151.775922 -273.362166)
		(end 151.98979 -273.148298)
		(width 0.10668)
		(layer "F.Cu")
		(net "M_G_CPU1_SB_CB<3>")
	)
	(segment
		(start 150.57882 -273.148298)
		(end 150.792688 -273.362166)
		(width 0.10668)
		(layer "F.Cu")
		(net "M_G_CPU1_SB_CB<3>")
	)
	(segment
		(start 152.787858 -273.148298)
		(end 152.973024 -273.148298)
		(width 0.10668)
		(layer "F.Cu")
		(net "M_G_CPU1_SB_CB<3>")
	)
	(segment
		(start 152.174956 -273.148298)
		(end 152.388824 -273.362166)
		(width 0.10668)
		(layer "F.Cu")
		(net "M_G_CPU1_SB_CB<3>")
	)
	(segment
		(start 156.468318 -274.563586)
		(end 156.585412 -274.68068)
		(width 0.10668)
		(layer "F.Cu")
		(net "M_G_CPU1_SB_CB<3>")
	)
	(segment
		(start 157.06471 -274.366228)
		(end 157.22981 -274.366228)
		(width 0.10668)
		(layer "F.Cu")
		(net "M_G_CPU1_SB_CB<3>")
	)
	(segment
		(start 150.792688 -273.362166)
		(end 150.977854 -273.362166)
		(width 0.10668)
		(layer "F.Cu")
		(net "M_G_CPU1_SB_CB<3>")
	)
	(segment
		(start 157.22981 -274.366228)
		(end 163.498784 -280.635202)
		(width 0.10668)
		(layer "F.Cu")
		(net "M_G_CPU1_SB_CB<3>")
	)
	(segment
		(start 154.170126 -273.362166)
		(end 154.383994 -273.148298)
		(width 0.10668)
		(layer "F.Cu")
		(net "M_G_CPU1_SB_CB<3>")
	)
	(segment
		(start 150.977854 -273.362166)
		(end 151.191722 -273.148298)
		(width 0.10668)
		(layer "F.Cu")
		(net "M_G_CPU1_SB_CB<3>")
	)
	(segment
		(start 156.021024 -274.116292)
		(end 156.186124 -274.116292)
		(width 0.10668)
		(layer "F.Cu")
		(net "M_G_CPU1_SB_CB<3>")
	)
	(arc
		(start 146.315938 -273.590512)
		(mid 146.353364 -273.598951)
		(end 146.39163 -273.601688)
		(width 0.0762)
		(layer "F.Cu")
		(net "M_G_CPU1_SB_CB<3>")
	)
	(arc
		(start 146.104864 -273.497802)
		(mid 146.207758 -273.550174)
		(end 146.315938 -273.590512)
		(width 0.0762)
		(layer "F.Cu")
		(net "M_G_CPU1_SB_CB<3>")
	)
	(arc
		(start 144.493996 -273.574002)
		(mid 144.647745 -273.556493)
		(end 144.790922 -273.497802)
		(width 0.0762)
		(layer "F.Cu")
		(net "M_G_CPU1_SB_CB<3>")
	)
	(arc
		(start 145.16481 -273.497802)
		(mid 145.447766 -273.573979)
		(end 145.730722 -273.497802)
		(width 0.0762)
		(layer "F.Cu")
		(net "M_G_CPU1_SB_CB<3>")
	)
	(arc
		(start 145.730722 -273.497802)
		(mid 145.912973 -273.447452)
		(end 146.096482 -273.492976)
		(width 0.0762)
		(layer "F.Cu")
		(net "M_G_CPU1_SB_CB<3>")
	)
	(arc
		(start 144.790922 -273.497802)
		(mid 144.977866 -273.447547)
		(end 145.16481 -273.497802)
		(width 0.0762)
		(layer "F.Cu")
		(net "M_G_CPU1_SB_CB<3>")
	)
	(arc
		(start 144.037812 -273.820382)
		(mid 144.233161 -273.636563)
		(end 144.493996 -273.574002)
		(width 0.0762)
		(layer "F.Cu")
		(net "M_G_CPU1_SB_CB<3>")
	)
	(segment
		(start 162.593274 -278.60117)
		(end 162.593274 -278.76627)
		(width 0.10668)
		(layer "F.Cu")
		(net "M_G_CPU1_SB_CB<2>")
	)
	(segment
		(start 161.005774 -276.802342)
		(end 160.90011 -276.908006)
		(width 0.10668)
		(layer "F.Cu")
		(net "M_G_CPU1_SB_CB<2>")
	)
	(segment
		(start 161.017204 -277.1902)
		(end 161.182304 -277.1902)
		(width 0.10668)
		(layer "F.Cu")
		(net "M_G_CPU1_SB_CB<2>")
	)
	(segment
		(start 158.07817 -274.251166)
		(end 158.195264 -274.36826)
		(width 0.10668)
		(layer "F.Cu")
		(net "M_G_CPU1_SB_CB<2>")
	)
	(segment
		(start 157.795976 -273.803872)
		(end 157.90164 -273.698208)
		(width 0.10668)
		(layer "F.Cu")
		(net "M_G_CPU1_SB_CB<2>")
	)
	(segment
		(start 162.028886 -278.201882)
		(end 162.14598 -278.318976)
		(width 0.10668)
		(layer "F.Cu")
		(net "M_G_CPU1_SB_CB<2>")
	)
	(segment
		(start 157.630876 -273.803872)
		(end 157.795976 -273.803872)
		(width 0.10668)
		(layer "F.Cu")
		(net "M_G_CPU1_SB_CB<2>")
	)
	(segment
		(start 162.416744 -278.213312)
		(end 162.581844 -278.213312)
		(width 0.10668)
		(layer "F.Cu")
		(net "M_G_CPU1_SB_CB<2>")
	)
	(segment
		(start 158.642558 -274.650454)
		(end 158.642558 -274.815554)
		(width 0.10668)
		(layer "F.Cu")
		(net "M_G_CPU1_SB_CB<2>")
	)
	(segment
		(start 157.513782 -273.521678)
		(end 157.513782 -273.686778)
		(width 0.10668)
		(layer "F.Cu")
		(net "M_G_CPU1_SB_CB<2>")
	)
	(segment
		(start 158.183834 -273.815302)
		(end 158.183834 -273.980402)
		(width 0.10668)
		(layer "F.Cu")
		(net "M_G_CPU1_SB_CB<2>")
	)
	(segment
		(start 147.464526 -272.467578)
		(end 147.77466 -272.467578)
		(width 0.0762)
		(layer "F.Cu")
		(net "M_G_CPU1_SB_CB<2>")
	)
	(segment
		(start 159.32404 -275.497036)
		(end 159.48914 -275.497036)
		(width 0.10668)
		(layer "F.Cu")
		(net "M_G_CPU1_SB_CB<2>")
	)
	(segment
		(start 160.335722 -276.343618)
		(end 160.335722 -276.508718)
		(width 0.10668)
		(layer "F.Cu")
		(net "M_G_CPU1_SB_CB<2>")
	)
	(segment
		(start 156.949394 -273.12239)
		(end 157.066488 -273.239484)
		(width 0.10668)
		(layer "F.Cu")
		(net "M_G_CPU1_SB_CB<2>")
	)
	(segment
		(start 157.502352 -273.13382)
		(end 157.619446 -273.250914)
		(width 0.10668)
		(layer "F.Cu")
		(net "M_G_CPU1_SB_CB<2>")
	)
	(segment
		(start 157.055058 -272.686526)
		(end 157.055058 -272.851626)
		(width 0.10668)
		(layer "F.Cu")
		(net "M_G_CPU1_SB_CB<2>")
	)
	(segment
		(start 157.055058 -272.851626)
		(end 156.949394 -272.95729)
		(width 0.10668)
		(layer "F.Cu")
		(net "M_G_CPU1_SB_CB<2>")
	)
	(segment
		(start 158.748222 -274.37969)
		(end 158.748222 -274.54479)
		(width 0.10668)
		(layer "F.Cu")
		(net "M_G_CPU1_SB_CB<2>")
	)
	(segment
		(start 159.594804 -275.391372)
		(end 159.759904 -275.391372)
		(width 0.10668)
		(layer "F.Cu")
		(net "M_G_CPU1_SB_CB<2>")
	)
	(segment
		(start 162.017456 -277.648924)
		(end 162.13455 -277.766018)
		(width 0.10668)
		(layer "F.Cu")
		(net "M_G_CPU1_SB_CB<2>")
	)
	(segment
		(start 163.303966 -278.935434)
		(end 164.427916 -278.935434)
		(width 0.10668)
		(layer "F.Cu")
		(net "M_G_CPU1_SB_CB<2>")
	)
	(segment
		(start 161.005774 -276.637242)
		(end 161.005774 -276.802342)
		(width 0.10668)
		(layer "F.Cu")
		(net "M_G_CPU1_SB_CB<2>")
	)
	(segment
		(start 158.466028 -274.262596)
		(end 158.631128 -274.262596)
		(width 0.10668)
		(layer "F.Cu")
		(net "M_G_CPU1_SB_CB<2>")
	)
	(segment
		(start 157.337252 -273.13382)
		(end 157.502352 -273.13382)
		(width 0.10668)
		(layer "F.Cu")
		(net "M_G_CPU1_SB_CB<2>")
	)
	(segment
		(start 162.981132 -278.7777)
		(end 163.146232 -278.7777)
		(width 0.10668)
		(layer "F.Cu")
		(net "M_G_CPU1_SB_CB<2>")
	)
	(segment
		(start 157.90164 -273.698208)
		(end 158.06674 -273.698208)
		(width 0.10668)
		(layer "F.Cu")
		(net "M_G_CPU1_SB_CB<2>")
	)
	(segment
		(start 159.206946 -275.214842)
		(end 159.206946 -275.379942)
		(width 0.10668)
		(layer "F.Cu")
		(net "M_G_CPU1_SB_CB<2>")
	)
	(segment
		(start 157.619446 -273.250914)
		(end 157.619446 -273.416014)
		(width 0.10668)
		(layer "F.Cu")
		(net "M_G_CPU1_SB_CB<2>")
	)
	(segment
		(start 161.570162 -277.36673)
		(end 161.464498 -277.472394)
		(width 0.10668)
		(layer "F.Cu")
		(net "M_G_CPU1_SB_CB<2>")
	)
	(segment
		(start 158.195264 -274.36826)
		(end 158.360364 -274.36826)
		(width 0.10668)
		(layer "F.Cu")
		(net "M_G_CPU1_SB_CB<2>")
	)
	(segment
		(start 158.759652 -274.932648)
		(end 158.924752 -274.932648)
		(width 0.10668)
		(layer "F.Cu")
		(net "M_G_CPU1_SB_CB<2>")
	)
	(segment
		(start 162.593274 -278.76627)
		(end 162.710368 -278.883364)
		(width 0.10668)
		(layer "F.Cu")
		(net "M_G_CPU1_SB_CB<2>")
	)
	(segment
		(start 159.195516 -274.826984)
		(end 159.31261 -274.944078)
		(width 0.10668)
		(layer "F.Cu")
		(net "M_G_CPU1_SB_CB<2>")
	)
	(segment
		(start 161.581592 -277.754588)
		(end 161.746692 -277.754588)
		(width 0.10668)
		(layer "F.Cu")
		(net "M_G_CPU1_SB_CB<2>")
	)
	(segment
		(start 157.513782 -273.686778)
		(end 157.630876 -273.803872)
		(width 0.10668)
		(layer "F.Cu")
		(net "M_G_CPU1_SB_CB<2>")
	)
	(segment
		(start 147.294854 -272.63725)
		(end 147.464526 -272.467578)
		(width 0.0762)
		(layer "F.Cu")
		(net "M_G_CPU1_SB_CB<2>")
	)
	(segment
		(start 160.441386 -276.237954)
		(end 160.335722 -276.343618)
		(width 0.10668)
		(layer "F.Cu")
		(net "M_G_CPU1_SB_CB<2>")
	)
	(segment
		(start 160.159192 -275.95576)
		(end 160.324292 -275.95576)
		(width 0.10668)
		(layer "F.Cu")
		(net "M_G_CPU1_SB_CB<2>")
	)
	(segment
		(start 162.581844 -278.213312)
		(end 162.698938 -278.330406)
		(width 0.10668)
		(layer "F.Cu")
		(net "M_G_CPU1_SB_CB<2>")
	)
	(segment
		(start 161.570162 -277.20163)
		(end 161.570162 -277.36673)
		(width 0.10668)
		(layer "F.Cu")
		(net "M_G_CPU1_SB_CB<2>")
	)
	(segment
		(start 158.631128 -274.262596)
		(end 158.748222 -274.37969)
		(width 0.10668)
		(layer "F.Cu")
		(net "M_G_CPU1_SB_CB<2>")
	)
	(segment
		(start 162.14598 -278.318976)
		(end 162.31108 -278.318976)
		(width 0.10668)
		(layer "F.Cu")
		(net "M_G_CPU1_SB_CB<2>")
	)
	(segment
		(start 146.38782 -272.63725)
		(end 147.294854 -272.63725)
		(width 0.0762)
		(layer "F.Cu")
		(net "M_G_CPU1_SB_CB<2>")
	)
	(segment
		(start 160.88868 -276.520148)
		(end 161.005774 -276.637242)
		(width 0.10668)
		(layer "F.Cu")
		(net "M_G_CPU1_SB_CB<2>")
	)
	(segment
		(start 159.48914 -275.497036)
		(end 159.594804 -275.391372)
		(width 0.10668)
		(layer "F.Cu")
		(net "M_G_CPU1_SB_CB<2>")
	)
	(segment
		(start 159.771334 -275.94433)
		(end 159.888428 -276.061424)
		(width 0.10668)
		(layer "F.Cu")
		(net "M_G_CPU1_SB_CB<2>")
	)
	(segment
		(start 162.875468 -278.883364)
		(end 162.981132 -278.7777)
		(width 0.10668)
		(layer "F.Cu")
		(net "M_G_CPU1_SB_CB<2>")
	)
	(segment
		(start 159.31261 -275.109178)
		(end 159.206946 -275.214842)
		(width 0.10668)
		(layer "F.Cu")
		(net "M_G_CPU1_SB_CB<2>")
	)
	(segment
		(start 159.888428 -276.061424)
		(end 160.053528 -276.061424)
		(width 0.10668)
		(layer "F.Cu")
		(net "M_G_CPU1_SB_CB<2>")
	)
	(segment
		(start 159.759904 -275.391372)
		(end 159.876998 -275.508466)
		(width 0.10668)
		(layer "F.Cu")
		(net "M_G_CPU1_SB_CB<2>")
	)
	(segment
		(start 158.748222 -274.54479)
		(end 158.642558 -274.650454)
		(width 0.10668)
		(layer "F.Cu")
		(net "M_G_CPU1_SB_CB<2>")
	)
	(segment
		(start 162.710368 -278.883364)
		(end 162.875468 -278.883364)
		(width 0.10668)
		(layer "F.Cu")
		(net "M_G_CPU1_SB_CB<2>")
	)
	(segment
		(start 160.324292 -275.95576)
		(end 160.441386 -276.072854)
		(width 0.10668)
		(layer "F.Cu")
		(net "M_G_CPU1_SB_CB<2>")
	)
	(segment
		(start 158.360364 -274.36826)
		(end 158.466028 -274.262596)
		(width 0.10668)
		(layer "F.Cu")
		(net "M_G_CPU1_SB_CB<2>")
	)
	(segment
		(start 162.028886 -278.036782)
		(end 162.028886 -278.201882)
		(width 0.10668)
		(layer "F.Cu")
		(net "M_G_CPU1_SB_CB<2>")
	)
	(segment
		(start 159.771334 -275.77923)
		(end 159.771334 -275.94433)
		(width 0.10668)
		(layer "F.Cu")
		(net "M_G_CPU1_SB_CB<2>")
	)
	(segment
		(start 159.31261 -274.944078)
		(end 159.31261 -275.109178)
		(width 0.10668)
		(layer "F.Cu")
		(net "M_G_CPU1_SB_CB<2>")
	)
	(segment
		(start 160.053528 -276.061424)
		(end 160.159192 -275.95576)
		(width 0.10668)
		(layer "F.Cu")
		(net "M_G_CPU1_SB_CB<2>")
	)
	(segment
		(start 161.464498 -277.472394)
		(end 161.464498 -277.637494)
		(width 0.10668)
		(layer "F.Cu")
		(net "M_G_CPU1_SB_CB<2>")
	)
	(segment
		(start 159.876998 -275.673566)
		(end 159.771334 -275.77923)
		(width 0.10668)
		(layer "F.Cu")
		(net "M_G_CPU1_SB_CB<2>")
	)
	(segment
		(start 161.182304 -277.1902)
		(end 161.287968 -277.084536)
		(width 0.10668)
		(layer "F.Cu")
		(net "M_G_CPU1_SB_CB<2>")
	)
	(segment
		(start 160.72358 -276.520148)
		(end 160.88868 -276.520148)
		(width 0.10668)
		(layer "F.Cu")
		(net "M_G_CPU1_SB_CB<2>")
	)
	(segment
		(start 161.453068 -277.084536)
		(end 161.570162 -277.20163)
		(width 0.10668)
		(layer "F.Cu")
		(net "M_G_CPU1_SB_CB<2>")
	)
	(segment
		(start 160.335722 -276.508718)
		(end 160.452816 -276.625812)
		(width 0.10668)
		(layer "F.Cu")
		(net "M_G_CPU1_SB_CB<2>")
	)
	(segment
		(start 157.066488 -273.239484)
		(end 157.231588 -273.239484)
		(width 0.10668)
		(layer "F.Cu")
		(net "M_G_CPU1_SB_CB<2>")
	)
	(segment
		(start 162.698938 -278.495506)
		(end 162.593274 -278.60117)
		(width 0.10668)
		(layer "F.Cu")
		(net "M_G_CPU1_SB_CB<2>")
	)
	(segment
		(start 160.617916 -276.625812)
		(end 160.72358 -276.520148)
		(width 0.10668)
		(layer "F.Cu")
		(net "M_G_CPU1_SB_CB<2>")
	)
	(segment
		(start 161.464498 -277.637494)
		(end 161.581592 -277.754588)
		(width 0.10668)
		(layer "F.Cu")
		(net "M_G_CPU1_SB_CB<2>")
	)
	(segment
		(start 161.852356 -277.648924)
		(end 162.017456 -277.648924)
		(width 0.10668)
		(layer "F.Cu")
		(net "M_G_CPU1_SB_CB<2>")
	)
	(segment
		(start 158.642558 -274.815554)
		(end 158.759652 -274.932648)
		(width 0.10668)
		(layer "F.Cu")
		(net "M_G_CPU1_SB_CB<2>")
	)
	(segment
		(start 156.949394 -272.95729)
		(end 156.949394 -273.12239)
		(width 0.10668)
		(layer "F.Cu")
		(net "M_G_CPU1_SB_CB<2>")
	)
	(segment
		(start 162.13455 -277.766018)
		(end 162.13455 -277.931118)
		(width 0.10668)
		(layer "F.Cu")
		(net "M_G_CPU1_SB_CB<2>")
	)
	(segment
		(start 161.746692 -277.754588)
		(end 161.852356 -277.648924)
		(width 0.10668)
		(layer "F.Cu")
		(net "M_G_CPU1_SB_CB<2>")
	)
	(segment
		(start 157.231588 -273.239484)
		(end 157.337252 -273.13382)
		(width 0.10668)
		(layer "F.Cu")
		(net "M_G_CPU1_SB_CB<2>")
	)
	(segment
		(start 158.06674 -273.698208)
		(end 158.183834 -273.815302)
		(width 0.10668)
		(layer "F.Cu")
		(net "M_G_CPU1_SB_CB<2>")
	)
	(segment
		(start 162.698938 -278.330406)
		(end 162.698938 -278.495506)
		(width 0.10668)
		(layer "F.Cu")
		(net "M_G_CPU1_SB_CB<2>")
	)
	(segment
		(start 162.13455 -277.931118)
		(end 162.028886 -278.036782)
		(width 0.10668)
		(layer "F.Cu")
		(net "M_G_CPU1_SB_CB<2>")
	)
	(segment
		(start 159.030416 -274.826984)
		(end 159.195516 -274.826984)
		(width 0.10668)
		(layer "F.Cu")
		(net "M_G_CPU1_SB_CB<2>")
	)
	(segment
		(start 147.77466 -272.467578)
		(end 156.83611 -272.467578)
		(width 0.10668)
		(layer "F.Cu")
		(net "M_G_CPU1_SB_CB<2>")
	)
	(segment
		(start 160.90011 -277.073106)
		(end 161.017204 -277.1902)
		(width 0.10668)
		(layer "F.Cu")
		(net "M_G_CPU1_SB_CB<2>")
	)
	(segment
		(start 158.183834 -273.980402)
		(end 158.07817 -274.086066)
		(width 0.10668)
		(layer "F.Cu")
		(net "M_G_CPU1_SB_CB<2>")
	)
	(segment
		(start 163.146232 -278.7777)
		(end 163.303966 -278.935434)
		(width 0.10668)
		(layer "F.Cu")
		(net "M_G_CPU1_SB_CB<2>")
	)
	(segment
		(start 158.924752 -274.932648)
		(end 159.030416 -274.826984)
		(width 0.10668)
		(layer "F.Cu")
		(net "M_G_CPU1_SB_CB<2>")
	)
	(segment
		(start 160.452816 -276.625812)
		(end 160.617916 -276.625812)
		(width 0.10668)
		(layer "F.Cu")
		(net "M_G_CPU1_SB_CB<2>")
	)
	(segment
		(start 160.441386 -276.072854)
		(end 160.441386 -276.237954)
		(width 0.10668)
		(layer "F.Cu")
		(net "M_G_CPU1_SB_CB<2>")
	)
	(segment
		(start 156.83611 -272.467578)
		(end 157.055058 -272.686526)
		(width 0.10668)
		(layer "F.Cu")
		(net "M_G_CPU1_SB_CB<2>")
	)
	(segment
		(start 158.07817 -274.086066)
		(end 158.07817 -274.251166)
		(width 0.10668)
		(layer "F.Cu")
		(net "M_G_CPU1_SB_CB<2>")
	)
	(segment
		(start 159.206946 -275.379942)
		(end 159.32404 -275.497036)
		(width 0.10668)
		(layer "F.Cu")
		(net "M_G_CPU1_SB_CB<2>")
	)
	(segment
		(start 157.619446 -273.416014)
		(end 157.513782 -273.521678)
		(width 0.10668)
		(layer "F.Cu")
		(net "M_G_CPU1_SB_CB<2>")
	)
	(segment
		(start 161.287968 -277.084536)
		(end 161.453068 -277.084536)
		(width 0.10668)
		(layer "F.Cu")
		(net "M_G_CPU1_SB_CB<2>")
	)
	(segment
		(start 159.876998 -275.508466)
		(end 159.876998 -275.673566)
		(width 0.10668)
		(layer "F.Cu")
		(net "M_G_CPU1_SB_CB<2>")
	)
	(segment
		(start 160.90011 -276.908006)
		(end 160.90011 -277.073106)
		(width 0.10668)
		(layer "F.Cu")
		(net "M_G_CPU1_SB_CB<2>")
	)
	(segment
		(start 162.31108 -278.318976)
		(end 162.416744 -278.213312)
		(width 0.10668)
		(layer "F.Cu")
		(net "M_G_CPU1_SB_CB<2>")
	)
	(arc
		(start 146.015456 -272.755614)
		(mid 146.111165 -272.729902)
		(end 146.200876 -272.687796)
		(width 0.0762)
		(layer "F.Cu")
		(net "M_G_CPU1_SB_CB<2>")
	)
	(arc
		(start 146.356832 -272.63852)
		(mid 146.372313 -272.637564)
		(end 146.38782 -272.63725)
		(width 0.0762)
		(layer "F.Cu")
		(net "M_G_CPU1_SB_CB<2>")
	)
	(arc
		(start 145.976848 -272.760948)
		(mid 145.996197 -272.75861)
		(end 146.015456 -272.755614)
		(width 0.0762)
		(layer "F.Cu")
		(net "M_G_CPU1_SB_CB<2>")
	)
	(arc
		(start 146.200876 -272.687796)
		(mid 146.276116 -272.654483)
		(end 146.356832 -272.63852)
		(width 0.0762)
		(layer "F.Cu")
		(net "M_G_CPU1_SB_CB<2>")
	)
	(arc
		(start 145.447766 -273.010376)
		(mid 145.691197 -272.840889)
		(end 145.976848 -272.760948)
		(width 0.0762)
		(layer "F.Cu")
		(net "M_G_CPU1_SB_CB<2>")
	)
	(segment
		(start 162.705542 -279.360376)
		(end 163.377626 -279.360376)
		(width 0.10668)
		(layer "F.Cu")
		(net "M_G_CPU1_SB_CB<1>")
	)
	(segment
		(start 146.358356 -273.391122)
		(end 147.167346 -273.392392)
		(width 0.0762)
		(layer "F.Cu")
		(net "M_G_CPU1_SB_CB<1>")
	)
	(segment
		(start 147.7518 -272.807938)
		(end 147.871688 -272.807938)
		(width 0.0762)
		(layer "F.Cu")
		(net "M_G_CPU1_SB_CB<1>")
	)
	(segment
		(start 165.567106 -279.360376)
		(end 167.7035 -279.785318)
		(width 0.101346)
		(layer "F.Cu")
		(net "M_G_CPU1_SB_CB<1>")
	)
	(segment
		(start 144.686528 -273.337782)
		(end 144.69491 -273.332956)
		(width 0.0762)
		(layer "F.Cu")
		(net "M_G_CPU1_SB_CB<1>")
	)
	(segment
		(start 145.260822 -273.332956)
		(end 145.261076 -273.332956)
		(width 0.0762)
		(layer "F.Cu")
		(net "M_G_CPU1_SB_CB<1>")
	)
	(segment
		(start 156.153104 -272.807938)
		(end 162.705542 -279.360376)
		(width 0.10668)
		(layer "F.Cu")
		(net "M_G_CPU1_SB_CB<1>")
	)
	(segment
		(start 147.167346 -273.392392)
		(end 147.7518 -272.807938)
		(width 0.0762)
		(layer "F.Cu")
		(net "M_G_CPU1_SB_CB<1>")
	)
	(segment
		(start 147.871688 -272.807938)
		(end 156.153104 -272.807938)
		(width 0.10668)
		(layer "F.Cu")
		(net "M_G_CPU1_SB_CB<1>")
	)
	(segment
		(start 163.377626 -279.360376)
		(end 165.567106 -279.360376)
		(width 0.101346)
		(layer "F.Cu")
		(net "M_G_CPU1_SB_CB<1>")
	)
	(segment
		(start 144.507966 -273.010376)
		(end 144.399508 -273.197066)
		(width 0.0762)
		(layer "F.Cu")
		(net "M_G_CPU1_SB_CB<1>")
	)
	(segment
		(start 167.7035 -279.785318)
		(end 168.527984 -279.785318)
		(width 0.101346)
		(layer "F.Cu")
		(net "M_G_CPU1_SB_CB<1>")
	)
	(arc
		(start 144.69491 -273.332956)
		(mid 144.977866 -273.256779)
		(end 145.260822 -273.332956)
		(width 0.0762)
		(layer "F.Cu")
		(net "M_G_CPU1_SB_CB<1>")
	)
	(arc
		(start 145.261076 -273.332956)
		(mid 145.44802 -273.38328)
		(end 145.634964 -273.332956)
		(width 0.0762)
		(layer "F.Cu")
		(net "M_G_CPU1_SB_CB<1>")
	)
	(arc
		(start 145.634964 -273.332956)
		(mid 145.91792 -273.256779)
		(end 146.200876 -273.332956)
		(width 0.0762)
		(layer "F.Cu")
		(net "M_G_CPU1_SB_CB<1>")
	)
	(arc
		(start 146.283426 -273.37512)
		(mid 146.320054 -273.38705)
		(end 146.358356 -273.391122)
		(width 0.0762)
		(layer "F.Cu")
		(net "M_G_CPU1_SB_CB<1>")
	)
	(arc
		(start 144.399508 -273.197066)
		(mid 144.425425 -273.330108)
		(end 144.551146 -273.380708)
		(width 0.0762)
		(layer "F.Cu")
		(net "M_G_CPU1_SB_CB<1>")
	)
	(arc
		(start 144.551146 -273.380708)
		(mid 144.6209 -273.365751)
		(end 144.686528 -273.337782)
		(width 0.0762)
		(layer "F.Cu")
		(net "M_G_CPU1_SB_CB<1>")
	)
	(arc
		(start 146.200876 -273.332956)
		(mid 146.24157 -273.355175)
		(end 146.283426 -273.37512)
		(width 0.0762)
		(layer "F.Cu")
		(net "M_G_CPU1_SB_CB<1>")
	)
	(segment
		(start 147.516088 -272.127218)
		(end 147.831302 -272.127218)
		(width 0.0762)
		(layer "F.Cu")
		(net "M_G_CPU1_SB_CB<0>")
	)
	(segment
		(start 167.248586 -278.200612)
		(end 167.363902 -278.085296)
		(width 0.101346)
		(layer "F.Cu")
		(net "M_G_CPU1_SB_CB<0>")
	)
	(segment
		(start 146.387566 -272.44675)
		(end 147.196556 -272.44675)
		(width 0.0762)
		(layer "F.Cu")
		(net "M_G_CPU1_SB_CB<0>")
	)
	(segment
		(start 166.73957 -278.085296)
		(end 166.854886 -278.200612)
		(width 0.101346)
		(layer "F.Cu")
		(net "M_G_CPU1_SB_CB<0>")
	)
	(segment
		(start 165.989254 -277.660354)
		(end 166.414196 -278.085296)
		(width 0.101346)
		(layer "F.Cu")
		(net "M_G_CPU1_SB_CB<0>")
	)
	(segment
		(start 156.977588 -272.127218)
		(end 162.510724 -277.660354)
		(width 0.10668)
		(layer "F.Cu")
		(net "M_G_CPU1_SB_CB<0>")
	)
	(segment
		(start 166.414196 -278.085296)
		(end 166.73957 -278.085296)
		(width 0.101346)
		(layer "F.Cu")
		(net "M_G_CPU1_SB_CB<0>")
	)
	(segment
		(start 166.854886 -278.87803)
		(end 166.970202 -278.993346)
		(width 0.101346)
		(layer "F.Cu")
		(net "M_G_CPU1_SB_CB<0>")
	)
	(segment
		(start 166.970202 -278.993346)
		(end 167.13327 -278.993346)
		(width 0.101346)
		(layer "F.Cu")
		(net "M_G_CPU1_SB_CB<0>")
	)
	(segment
		(start 147.831302 -272.127218)
		(end 156.977588 -272.127218)
		(width 0.10668)
		(layer "F.Cu")
		(net "M_G_CPU1_SB_CB<0>")
	)
	(segment
		(start 163.377626 -277.660354)
		(end 165.989254 -277.660354)
		(width 0.101346)
		(layer "F.Cu")
		(net "M_G_CPU1_SB_CB<0>")
	)
	(segment
		(start 167.13327 -278.993346)
		(end 167.248586 -278.87803)
		(width 0.101346)
		(layer "F.Cu")
		(net "M_G_CPU1_SB_CB<0>")
	)
	(segment
		(start 167.363902 -278.085296)
		(end 168.527984 -278.085296)
		(width 0.101346)
		(layer "F.Cu")
		(net "M_G_CPU1_SB_CB<0>")
	)
	(segment
		(start 147.196556 -272.44675)
		(end 147.516088 -272.127218)
		(width 0.0762)
		(layer "F.Cu")
		(net "M_G_CPU1_SB_CB<0>")
	)
	(segment
		(start 162.510724 -277.660354)
		(end 163.377626 -277.660354)
		(width 0.10668)
		(layer "F.Cu")
		(net "M_G_CPU1_SB_CB<0>")
	)
	(segment
		(start 145.91792 -272.20037)
		(end 145.815558 -272.376646)
		(width 0.0762)
		(layer "F.Cu")
		(net "M_G_CPU1_SB_CB<0>")
	)
	(segment
		(start 146.096482 -272.527776)
		(end 146.104864 -272.52295)
		(width 0.0762)
		(layer "F.Cu")
		(net "M_G_CPU1_SB_CB<0>")
	)
	(segment
		(start 167.248586 -278.87803)
		(end 167.248586 -278.200612)
		(width 0.101346)
		(layer "F.Cu")
		(net "M_G_CPU1_SB_CB<0>")
	)
	(segment
		(start 166.854886 -278.200612)
		(end 166.854886 -278.87803)
		(width 0.101346)
		(layer "F.Cu")
		(net "M_G_CPU1_SB_CB<0>")
	)
	(arc
		(start 145.982436 -272.567654)
		(mid 146.041082 -272.552361)
		(end 146.096482 -272.527776)
		(width 0.0762)
		(layer "F.Cu")
		(net "M_G_CPU1_SB_CB<0>")
	)
	(arc
		(start 146.340576 -272.448528)
		(mid 146.364053 -272.447152)
		(end 146.387566 -272.44675)
		(width 0.0762)
		(layer "F.Cu")
		(net "M_G_CPU1_SB_CB<0>")
	)
	(arc
		(start 145.815558 -272.376646)
		(mid 145.845187 -272.519133)
		(end 145.982436 -272.567654)
		(width 0.0762)
		(layer "F.Cu")
		(net "M_G_CPU1_SB_CB<0>")
	)
	(arc
		(start 146.104864 -272.52295)
		(mid 146.218588 -272.472649)
		(end 146.340576 -272.448528)
		(width 0.0762)
		(layer "F.Cu")
		(net "M_G_CPU1_SB_CB<0>")
	)
	(segment
		(start 167.147494 -265.760454)
		(end 167.572436 -266.185396)
		(width 0.101346)
		(layer "F.Cu")
		(net "M_G_CPU1_SB_CA<6>")
	)
	(segment
		(start 147.447 -264.185654)
		(end 147.912328 -264.185654)
		(width 0.0762)
		(layer "F.Cu")
		(net "M_G_CPU1_SB_CA<6>")
	)
	(segment
		(start 157.982158 -264.580624)
		(end 161.790126 -264.580624)
		(width 0.10668)
		(layer "F.Cu")
		(net "M_G_CPU1_SB_CA<6>")
	)
	(segment
		(start 145.91792 -264.10031)
		(end 145.815558 -264.276586)
		(width 0.0762)
		(layer "F.Cu")
		(net "M_G_CPU1_SB_CA<6>")
	)
	(segment
		(start 151.234394 -265.567922)
		(end 156.99486 -265.567922)
		(width 0.10668)
		(layer "F.Cu")
		(net "M_G_CPU1_SB_CA<6>")
	)
	(segment
		(start 162.969956 -265.760454)
		(end 163.377626 -265.760454)
		(width 0.10668)
		(layer "F.Cu")
		(net "M_G_CPU1_SB_CA<6>")
	)
	(segment
		(start 149.852126 -264.185654)
		(end 151.234394 -265.567922)
		(width 0.10668)
		(layer "F.Cu")
		(net "M_G_CPU1_SB_CA<6>")
	)
	(segment
		(start 167.572436 -266.185396)
		(end 168.527984 -266.185396)
		(width 0.101346)
		(layer "F.Cu")
		(net "M_G_CPU1_SB_CA<6>")
	)
	(segment
		(start 163.377626 -265.760454)
		(end 167.147494 -265.760454)
		(width 0.101346)
		(layer "F.Cu")
		(net "M_G_CPU1_SB_CA<6>")
	)
	(segment
		(start 147.285964 -264.34669)
		(end 147.447 -264.185654)
		(width 0.0762)
		(layer "F.Cu")
		(net "M_G_CPU1_SB_CA<6>")
	)
	(segment
		(start 161.790126 -264.580624)
		(end 162.969956 -265.760454)
		(width 0.10668)
		(layer "F.Cu")
		(net "M_G_CPU1_SB_CA<6>")
	)
	(segment
		(start 146.096482 -264.427716)
		(end 146.104864 -264.42289)
		(width 0.0762)
		(layer "F.Cu")
		(net "M_G_CPU1_SB_CA<6>")
	)
	(segment
		(start 146.387566 -264.34669)
		(end 147.285964 -264.34669)
		(width 0.0762)
		(layer "F.Cu")
		(net "M_G_CPU1_SB_CA<6>")
	)
	(segment
		(start 147.912328 -264.185654)
		(end 149.852126 -264.185654)
		(width 0.10668)
		(layer "F.Cu")
		(net "M_G_CPU1_SB_CA<6>")
	)
	(segment
		(start 156.99486 -265.567922)
		(end 157.982158 -264.580624)
		(width 0.10668)
		(layer "F.Cu")
		(net "M_G_CPU1_SB_CA<6>")
	)
	(arc
		(start 145.815558 -264.276586)
		(mid 145.845187 -264.419073)
		(end 145.982436 -264.467594)
		(width 0.0762)
		(layer "F.Cu")
		(net "M_G_CPU1_SB_CA<6>")
	)
	(arc
		(start 146.340576 -264.348468)
		(mid 146.364053 -264.347092)
		(end 146.387566 -264.34669)
		(width 0.0762)
		(layer "F.Cu")
		(net "M_G_CPU1_SB_CA<6>")
	)
	(arc
		(start 146.104864 -264.42289)
		(mid 146.218588 -264.372589)
		(end 146.340576 -264.348468)
		(width 0.0762)
		(layer "F.Cu")
		(net "M_G_CPU1_SB_CA<6>")
	)
	(arc
		(start 145.982436 -264.467594)
		(mid 146.041082 -264.452301)
		(end 146.096482 -264.427716)
		(width 0.0762)
		(layer "F.Cu")
		(net "M_G_CPU1_SB_CA<6>")
	)
	(segment
		(start 159.057594 -264.123424)
		(end 159.057594 -263.919208)
		(width 0.10668)
		(layer "F.Cu")
		(net "M_G_CPU1_SB_CA<5>")
	)
	(segment
		(start 160.65373 -263.919208)
		(end 160.77057 -263.802368)
		(width 0.10668)
		(layer "F.Cu")
		(net "M_G_CPU1_SB_CA<5>")
	)
	(segment
		(start 158.54172 -263.802368)
		(end 158.65856 -263.919208)
		(width 0.10668)
		(layer "F.Cu")
		(net "M_G_CPU1_SB_CA<5>")
	)
	(segment
		(start 160.53689 -264.240264)
		(end 160.65373 -264.123424)
		(width 0.10668)
		(layer "F.Cu")
		(net "M_G_CPU1_SB_CA<5>")
	)
	(segment
		(start 159.855662 -264.123424)
		(end 159.855662 -263.919208)
		(width 0.10668)
		(layer "F.Cu")
		(net "M_G_CPU1_SB_CA<5>")
	)
	(segment
		(start 159.456628 -264.123424)
		(end 159.573468 -264.240264)
		(width 0.10668)
		(layer "F.Cu")
		(net "M_G_CPU1_SB_CA<5>")
	)
	(segment
		(start 159.456628 -263.919208)
		(end 159.456628 -264.123424)
		(width 0.10668)
		(layer "F.Cu")
		(net "M_G_CPU1_SB_CA<5>")
	)
	(segment
		(start 147.375372 -263.845294)
		(end 147.872958 -263.845294)
		(width 0.0762)
		(layer "F.Cu")
		(net "M_G_CPU1_SB_CA<5>")
	)
	(segment
		(start 147.872958 -263.845294)
		(end 149.993604 -263.845294)
		(width 0.10668)
		(layer "F.Cu")
		(net "M_G_CPU1_SB_CA<5>")
	)
	(segment
		(start 146.39163 -263.881616)
		(end 147.33905 -263.881616)
		(width 0.0762)
		(layer "F.Cu")
		(net "M_G_CPU1_SB_CA<5>")
	)
	(segment
		(start 156.853636 -265.227562)
		(end 158.27883 -263.802368)
		(width 0.10668)
		(layer "F.Cu")
		(net "M_G_CPU1_SB_CA<5>")
	)
	(segment
		(start 160.77057 -263.802368)
		(end 161.957004 -263.802368)
		(width 0.10668)
		(layer "F.Cu")
		(net "M_G_CPU1_SB_CA<5>")
	)
	(segment
		(start 160.371536 -264.240264)
		(end 160.53689 -264.240264)
		(width 0.10668)
		(layer "F.Cu")
		(net "M_G_CPU1_SB_CA<5>")
	)
	(segment
		(start 160.137856 -263.802368)
		(end 160.254696 -263.919208)
		(width 0.10668)
		(layer "F.Cu")
		(net "M_G_CPU1_SB_CA<5>")
	)
	(segment
		(start 160.254696 -263.919208)
		(end 160.254696 -264.123424)
		(width 0.10668)
		(layer "F.Cu")
		(net "M_G_CPU1_SB_CA<5>")
	)
	(segment
		(start 160.254696 -264.123424)
		(end 160.371536 -264.240264)
		(width 0.10668)
		(layer "F.Cu")
		(net "M_G_CPU1_SB_CA<5>")
	)
	(segment
		(start 158.65856 -263.919208)
		(end 158.65856 -264.123424)
		(width 0.10668)
		(layer "F.Cu")
		(net "M_G_CPU1_SB_CA<5>")
	)
	(segment
		(start 151.375872 -265.227562)
		(end 156.853636 -265.227562)
		(width 0.10668)
		(layer "F.Cu")
		(net "M_G_CPU1_SB_CA<5>")
	)
	(segment
		(start 159.339788 -263.802368)
		(end 159.456628 -263.919208)
		(width 0.10668)
		(layer "F.Cu")
		(net "M_G_CPU1_SB_CA<5>")
	)
	(segment
		(start 158.940754 -264.240264)
		(end 159.057594 -264.123424)
		(width 0.10668)
		(layer "F.Cu")
		(net "M_G_CPU1_SB_CA<5>")
	)
	(segment
		(start 158.27883 -263.802368)
		(end 158.54172 -263.802368)
		(width 0.10668)
		(layer "F.Cu")
		(net "M_G_CPU1_SB_CA<5>")
	)
	(segment
		(start 147.33905 -263.881616)
		(end 147.375372 -263.845294)
		(width 0.0762)
		(layer "F.Cu")
		(net "M_G_CPU1_SB_CA<5>")
	)
	(segment
		(start 158.7754 -264.240264)
		(end 158.940754 -264.240264)
		(width 0.10668)
		(layer "F.Cu")
		(net "M_G_CPU1_SB_CA<5>")
	)
	(segment
		(start 149.993604 -263.845294)
		(end 151.375872 -265.227562)
		(width 0.10668)
		(layer "F.Cu")
		(net "M_G_CPU1_SB_CA<5>")
	)
	(segment
		(start 158.65856 -264.123424)
		(end 158.7754 -264.240264)
		(width 0.10668)
		(layer "F.Cu")
		(net "M_G_CPU1_SB_CA<5>")
	)
	(segment
		(start 159.738822 -264.240264)
		(end 159.855662 -264.123424)
		(width 0.10668)
		(layer "F.Cu")
		(net "M_G_CPU1_SB_CA<5>")
	)
	(segment
		(start 159.855662 -263.919208)
		(end 159.972502 -263.802368)
		(width 0.10668)
		(layer "F.Cu")
		(net "M_G_CPU1_SB_CA<5>")
	)
	(segment
		(start 159.972502 -263.802368)
		(end 160.137856 -263.802368)
		(width 0.10668)
		(layer "F.Cu")
		(net "M_G_CPU1_SB_CA<5>")
	)
	(segment
		(start 159.174434 -263.802368)
		(end 159.339788 -263.802368)
		(width 0.10668)
		(layer "F.Cu")
		(net "M_G_CPU1_SB_CA<5>")
	)
	(segment
		(start 160.65373 -264.123424)
		(end 160.65373 -263.919208)
		(width 0.10668)
		(layer "F.Cu")
		(net "M_G_CPU1_SB_CA<5>")
	)
	(segment
		(start 159.573468 -264.240264)
		(end 159.738822 -264.240264)
		(width 0.10668)
		(layer "F.Cu")
		(net "M_G_CPU1_SB_CA<5>")
	)
	(segment
		(start 159.057594 -263.919208)
		(end 159.174434 -263.802368)
		(width 0.10668)
		(layer "F.Cu")
		(net "M_G_CPU1_SB_CA<5>")
	)
	(segment
		(start 161.957004 -263.802368)
		(end 163.489894 -265.335258)
		(width 0.10668)
		(layer "F.Cu")
		(net "M_G_CPU1_SB_CA<5>")
	)
	(segment
		(start 146.096482 -263.772904)
		(end 146.104864 -263.77773)
		(width 0.0762)
		(layer "F.Cu")
		(net "M_G_CPU1_SB_CA<5>")
	)
	(segment
		(start 163.489894 -265.335258)
		(end 164.427916 -265.335258)
		(width 0.10668)
		(layer "F.Cu")
		(net "M_G_CPU1_SB_CA<5>")
	)
	(arc
		(start 146.315938 -263.87044)
		(mid 146.353364 -263.878879)
		(end 146.39163 -263.881616)
		(width 0.0762)
		(layer "F.Cu")
		(net "M_G_CPU1_SB_CA<5>")
	)
	(arc
		(start 144.493996 -263.85393)
		(mid 144.647745 -263.836421)
		(end 144.790922 -263.77773)
		(width 0.0762)
		(layer "F.Cu")
		(net "M_G_CPU1_SB_CA<5>")
	)
	(arc
		(start 144.790922 -263.77773)
		(mid 144.977866 -263.727475)
		(end 145.16481 -263.77773)
		(width 0.0762)
		(layer "F.Cu")
		(net "M_G_CPU1_SB_CA<5>")
	)
	(arc
		(start 145.16481 -263.77773)
		(mid 145.447766 -263.853907)
		(end 145.730722 -263.77773)
		(width 0.0762)
		(layer "F.Cu")
		(net "M_G_CPU1_SB_CA<5>")
	)
	(arc
		(start 146.104864 -263.77773)
		(mid 146.207758 -263.830102)
		(end 146.315938 -263.87044)
		(width 0.0762)
		(layer "F.Cu")
		(net "M_G_CPU1_SB_CA<5>")
	)
	(arc
		(start 144.037812 -264.10031)
		(mid 144.233161 -263.916491)
		(end 144.493996 -263.85393)
		(width 0.0762)
		(layer "F.Cu")
		(net "M_G_CPU1_SB_CA<5>")
	)
	(arc
		(start 145.730722 -263.77773)
		(mid 145.912973 -263.72738)
		(end 146.096482 -263.772904)
		(width 0.0762)
		(layer "F.Cu")
		(net "M_G_CPU1_SB_CA<5>")
	)
	(segment
		(start 145.260822 -263.612884)
		(end 145.261076 -263.612884)
		(width 0.0762)
		(layer "F.Cu")
		(net "M_G_CPU1_SB_CA<4>")
	)
	(segment
		(start 167.20693 -264.060432)
		(end 167.631872 -264.485374)
		(width 0.101346)
		(layer "F.Cu")
		(net "M_G_CPU1_SB_CA<4>")
	)
	(segment
		(start 163.377626 -264.060432)
		(end 167.20693 -264.060432)
		(width 0.101346)
		(layer "F.Cu")
		(net "M_G_CPU1_SB_CA<4>")
	)
	(segment
		(start 147.369022 -263.504934)
		(end 147.943062 -263.504934)
		(width 0.0762)
		(layer "F.Cu")
		(net "M_G_CPU1_SB_CA<4>")
	)
	(segment
		(start 158.137606 -263.462008)
		(end 162.779202 -263.462008)
		(width 0.10668)
		(layer "F.Cu")
		(net "M_G_CPU1_SB_CA<4>")
	)
	(segment
		(start 147.943062 -263.504934)
		(end 150.134828 -263.504934)
		(width 0.10668)
		(layer "F.Cu")
		(net "M_G_CPU1_SB_CA<4>")
	)
	(segment
		(start 162.779202 -263.462008)
		(end 163.377626 -264.060432)
		(width 0.10668)
		(layer "F.Cu")
		(net "M_G_CPU1_SB_CA<4>")
	)
	(segment
		(start 144.507966 -263.290304)
		(end 144.399508 -263.476994)
		(width 0.0762)
		(layer "F.Cu")
		(net "M_G_CPU1_SB_CA<4>")
	)
	(segment
		(start 156.712412 -264.887202)
		(end 158.137606 -263.462008)
		(width 0.10668)
		(layer "F.Cu")
		(net "M_G_CPU1_SB_CA<4>")
	)
	(segment
		(start 144.686528 -263.61771)
		(end 144.69491 -263.612884)
		(width 0.0762)
		(layer "F.Cu")
		(net "M_G_CPU1_SB_CA<4>")
	)
	(segment
		(start 167.631872 -264.485374)
		(end 168.527984 -264.485374)
		(width 0.101346)
		(layer "F.Cu")
		(net "M_G_CPU1_SB_CA<4>")
	)
	(segment
		(start 147.206208 -263.672066)
		(end 147.369022 -263.504934)
		(width 0.0762)
		(layer "F.Cu")
		(net "M_G_CPU1_SB_CA<4>")
	)
	(segment
		(start 150.134828 -263.504934)
		(end 151.517096 -264.887202)
		(width 0.10668)
		(layer "F.Cu")
		(net "M_G_CPU1_SB_CA<4>")
	)
	(segment
		(start 151.517096 -264.887202)
		(end 156.712412 -264.887202)
		(width 0.10668)
		(layer "F.Cu")
		(net "M_G_CPU1_SB_CA<4>")
	)
	(segment
		(start 146.358356 -263.67105)
		(end 147.206208 -263.672066)
		(width 0.0762)
		(layer "F.Cu")
		(net "M_G_CPU1_SB_CA<4>")
	)
	(arc
		(start 144.69491 -263.612884)
		(mid 144.977866 -263.536707)
		(end 145.260822 -263.612884)
		(width 0.0762)
		(layer "F.Cu")
		(net "M_G_CPU1_SB_CA<4>")
	)
	(arc
		(start 145.261076 -263.612884)
		(mid 145.44802 -263.663208)
		(end 145.634964 -263.612884)
		(width 0.0762)
		(layer "F.Cu")
		(net "M_G_CPU1_SB_CA<4>")
	)
	(arc
		(start 146.283426 -263.655048)
		(mid 146.320054 -263.666978)
		(end 146.358356 -263.67105)
		(width 0.0762)
		(layer "F.Cu")
		(net "M_G_CPU1_SB_CA<4>")
	)
	(arc
		(start 146.200876 -263.612884)
		(mid 146.24157 -263.635103)
		(end 146.283426 -263.655048)
		(width 0.0762)
		(layer "F.Cu")
		(net "M_G_CPU1_SB_CA<4>")
	)
	(arc
		(start 144.551146 -263.660636)
		(mid 144.6209 -263.645679)
		(end 144.686528 -263.61771)
		(width 0.0762)
		(layer "F.Cu")
		(net "M_G_CPU1_SB_CA<4>")
	)
	(arc
		(start 145.634964 -263.612884)
		(mid 145.91792 -263.536707)
		(end 146.200876 -263.612884)
		(width 0.0762)
		(layer "F.Cu")
		(net "M_G_CPU1_SB_CA<4>")
	)
	(arc
		(start 144.399508 -263.476994)
		(mid 144.425425 -263.610036)
		(end 144.551146 -263.660636)
		(width 0.0762)
		(layer "F.Cu")
		(net "M_G_CPU1_SB_CA<4>")
	)
	(segment
		(start 158.416752 -262.70077)
		(end 158.777178 -262.70077)
		(width 0.10668)
		(layer "F.Cu")
		(net "M_G_CPU1_SB_CA<3>")
	)
	(segment
		(start 158.894018 -263.004808)
		(end 159.010858 -263.121648)
		(width 0.10668)
		(layer "F.Cu")
		(net "M_G_CPU1_SB_CA<3>")
	)
	(segment
		(start 160.373314 -262.70077)
		(end 160.490154 -262.81761)
		(width 0.10668)
		(layer "F.Cu")
		(net "M_G_CPU1_SB_CA<3>")
	)
	(segment
		(start 161.288222 -262.81761)
		(end 161.288222 -263.004808)
		(width 0.10668)
		(layer "F.Cu")
		(net "M_G_CPU1_SB_CA<3>")
	)
	(segment
		(start 156.570934 -264.546842)
		(end 157.48254 -263.635236)
		(width 0.10668)
		(layer "F.Cu")
		(net "M_G_CPU1_SB_CA<3>")
	)
	(segment
		(start 146.38782 -262.917178)
		(end 147.374356 -262.917178)
		(width 0.0762)
		(layer "F.Cu")
		(net "M_G_CPU1_SB_CA<3>")
	)
	(segment
		(start 161.171382 -262.70077)
		(end 161.288222 -262.81761)
		(width 0.10668)
		(layer "F.Cu")
		(net "M_G_CPU1_SB_CA<3>")
	)
	(segment
		(start 147.432522 -262.859012)
		(end 147.73656 -262.859012)
		(width 0.0762)
		(layer "F.Cu")
		(net "M_G_CPU1_SB_CA<3>")
	)
	(segment
		(start 161.570416 -263.121648)
		(end 161.687256 -263.004808)
		(width 0.10668)
		(layer "F.Cu")
		(net "M_G_CPU1_SB_CA<3>")
	)
	(segment
		(start 163.465002 -263.635236)
		(end 164.427916 -263.635236)
		(width 0.10668)
		(layer "F.Cu")
		(net "M_G_CPU1_SB_CA<3>")
	)
	(segment
		(start 160.490154 -262.81761)
		(end 160.490154 -263.004808)
		(width 0.10668)
		(layer "F.Cu")
		(net "M_G_CPU1_SB_CA<3>")
	)
	(segment
		(start 160.772348 -263.121648)
		(end 160.889188 -263.004808)
		(width 0.10668)
		(layer "F.Cu")
		(net "M_G_CPU1_SB_CA<3>")
	)
	(segment
		(start 147.73656 -262.859012)
		(end 149.99081 -262.859012)
		(width 0.10668)
		(layer "F.Cu")
		(net "M_G_CPU1_SB_CA<3>")
	)
	(segment
		(start 157.48254 -263.635236)
		(end 157.48254 -263.634982)
		(width 0.10668)
		(layer "F.Cu")
		(net "M_G_CPU1_SB_CA<3>")
	)
	(segment
		(start 159.808926 -263.121648)
		(end 159.97428 -263.121648)
		(width 0.10668)
		(layer "F.Cu")
		(net "M_G_CPU1_SB_CA<3>")
	)
	(segment
		(start 159.97428 -263.121648)
		(end 160.09112 -263.004808)
		(width 0.10668)
		(layer "F.Cu")
		(net "M_G_CPU1_SB_CA<3>")
	)
	(segment
		(start 159.293052 -262.81761)
		(end 159.409892 -262.70077)
		(width 0.10668)
		(layer "F.Cu")
		(net "M_G_CPU1_SB_CA<3>")
	)
	(segment
		(start 160.490154 -263.004808)
		(end 160.606994 -263.121648)
		(width 0.10668)
		(layer "F.Cu")
		(net "M_G_CPU1_SB_CA<3>")
	)
	(segment
		(start 159.575246 -262.70077)
		(end 159.692086 -262.81761)
		(width 0.10668)
		(layer "F.Cu")
		(net "M_G_CPU1_SB_CA<3>")
	)
	(segment
		(start 159.176212 -263.121648)
		(end 159.293052 -263.004808)
		(width 0.10668)
		(layer "F.Cu")
		(net "M_G_CPU1_SB_CA<3>")
	)
	(segment
		(start 161.405062 -263.121648)
		(end 161.570416 -263.121648)
		(width 0.10668)
		(layer "F.Cu")
		(net "M_G_CPU1_SB_CA<3>")
	)
	(segment
		(start 160.606994 -263.121648)
		(end 160.772348 -263.121648)
		(width 0.10668)
		(layer "F.Cu")
		(net "M_G_CPU1_SB_CA<3>")
	)
	(segment
		(start 147.374356 -262.917178)
		(end 147.432522 -262.859012)
		(width 0.0762)
		(layer "F.Cu")
		(net "M_G_CPU1_SB_CA<3>")
	)
	(segment
		(start 159.409892 -262.70077)
		(end 159.575246 -262.70077)
		(width 0.10668)
		(layer "F.Cu")
		(net "M_G_CPU1_SB_CA<3>")
	)
	(segment
		(start 159.010858 -263.121648)
		(end 159.176212 -263.121648)
		(width 0.10668)
		(layer "F.Cu")
		(net "M_G_CPU1_SB_CA<3>")
	)
	(segment
		(start 162.530536 -262.70077)
		(end 163.465002 -263.635236)
		(width 0.10668)
		(layer "F.Cu")
		(net "M_G_CPU1_SB_CA<3>")
	)
	(segment
		(start 160.09112 -262.81761)
		(end 160.20796 -262.70077)
		(width 0.10668)
		(layer "F.Cu")
		(net "M_G_CPU1_SB_CA<3>")
	)
	(segment
		(start 160.889188 -263.004808)
		(end 160.889188 -262.81761)
		(width 0.10668)
		(layer "F.Cu")
		(net "M_G_CPU1_SB_CA<3>")
	)
	(segment
		(start 161.006028 -262.70077)
		(end 161.171382 -262.70077)
		(width 0.10668)
		(layer "F.Cu")
		(net "M_G_CPU1_SB_CA<3>")
	)
	(segment
		(start 161.804096 -262.70077)
		(end 162.530536 -262.70077)
		(width 0.10668)
		(layer "F.Cu")
		(net "M_G_CPU1_SB_CA<3>")
	)
	(segment
		(start 161.687256 -263.004808)
		(end 161.687256 -262.81761)
		(width 0.10668)
		(layer "F.Cu")
		(net "M_G_CPU1_SB_CA<3>")
	)
	(segment
		(start 161.288222 -263.004808)
		(end 161.405062 -263.121648)
		(width 0.10668)
		(layer "F.Cu")
		(net "M_G_CPU1_SB_CA<3>")
	)
	(segment
		(start 149.99081 -262.859012)
		(end 151.67864 -264.546842)
		(width 0.10668)
		(layer "F.Cu")
		(net "M_G_CPU1_SB_CA<3>")
	)
	(segment
		(start 160.20796 -262.70077)
		(end 160.373314 -262.70077)
		(width 0.10668)
		(layer "F.Cu")
		(net "M_G_CPU1_SB_CA<3>")
	)
	(segment
		(start 160.889188 -262.81761)
		(end 161.006028 -262.70077)
		(width 0.10668)
		(layer "F.Cu")
		(net "M_G_CPU1_SB_CA<3>")
	)
	(segment
		(start 160.09112 -263.004808)
		(end 160.09112 -262.81761)
		(width 0.10668)
		(layer "F.Cu")
		(net "M_G_CPU1_SB_CA<3>")
	)
	(segment
		(start 159.692086 -263.004808)
		(end 159.808926 -263.121648)
		(width 0.10668)
		(layer "F.Cu")
		(net "M_G_CPU1_SB_CA<3>")
	)
	(segment
		(start 161.687256 -262.81761)
		(end 161.804096 -262.70077)
		(width 0.10668)
		(layer "F.Cu")
		(net "M_G_CPU1_SB_CA<3>")
	)
	(segment
		(start 159.692086 -262.81761)
		(end 159.692086 -263.004808)
		(width 0.10668)
		(layer "F.Cu")
		(net "M_G_CPU1_SB_CA<3>")
	)
	(segment
		(start 151.67864 -264.546842)
		(end 156.570934 -264.546842)
		(width 0.10668)
		(layer "F.Cu")
		(net "M_G_CPU1_SB_CA<3>")
	)
	(segment
		(start 157.48254 -263.634982)
		(end 158.416752 -262.70077)
		(width 0.10668)
		(layer "F.Cu")
		(net "M_G_CPU1_SB_CA<3>")
	)
	(segment
		(start 158.894018 -262.81761)
		(end 158.894018 -263.004808)
		(width 0.10668)
		(layer "F.Cu")
		(net "M_G_CPU1_SB_CA<3>")
	)
	(segment
		(start 158.777178 -262.70077)
		(end 158.894018 -262.81761)
		(width 0.10668)
		(layer "F.Cu")
		(net "M_G_CPU1_SB_CA<3>")
	)
	(segment
		(start 159.293052 -263.004808)
		(end 159.293052 -262.81761)
		(width 0.10668)
		(layer "F.Cu")
		(net "M_G_CPU1_SB_CA<3>")
	)
	(arc
		(start 145.447766 -263.290304)
		(mid 145.691197 -263.120817)
		(end 145.976848 -263.040876)
		(width 0.0762)
		(layer "F.Cu")
		(net "M_G_CPU1_SB_CA<3>")
	)
	(arc
		(start 145.976848 -263.040876)
		(mid 145.996197 -263.038538)
		(end 146.015456 -263.035542)
		(width 0.0762)
		(layer "F.Cu")
		(net "M_G_CPU1_SB_CA<3>")
	)
	(arc
		(start 146.200876 -262.967724)
		(mid 146.276116 -262.934411)
		(end 146.356832 -262.918448)
		(width 0.0762)
		(layer "F.Cu")
		(net "M_G_CPU1_SB_CA<3>")
	)
	(arc
		(start 146.015456 -263.035542)
		(mid 146.111165 -263.00983)
		(end 146.200876 -262.967724)
		(width 0.0762)
		(layer "F.Cu")
		(net "M_G_CPU1_SB_CA<3>")
	)
	(arc
		(start 146.356832 -262.918448)
		(mid 146.372313 -262.917492)
		(end 146.38782 -262.917178)
		(width 0.0762)
		(layer "F.Cu")
		(net "M_G_CPU1_SB_CA<3>")
	)
	(segment
		(start 158.275528 -262.36041)
		(end 163.377626 -262.36041)
		(width 0.10668)
		(layer "F.Cu")
		(net "M_G_CPU1_SB_CA<2>")
	)
	(segment
		(start 156.429456 -264.206482)
		(end 158.275528 -262.36041)
		(width 0.10668)
		(layer "F.Cu")
		(net "M_G_CPU1_SB_CA<2>")
	)
	(segment
		(start 147.72259 -262.518652)
		(end 150.132288 -262.518652)
		(width 0.10668)
		(layer "F.Cu")
		(net "M_G_CPU1_SB_CA<2>")
	)
	(segment
		(start 163.377626 -262.36041)
		(end 167.194738 -262.36041)
		(width 0.101346)
		(layer "F.Cu")
		(net "M_G_CPU1_SB_CA<2>")
	)
	(segment
		(start 145.91792 -262.480298)
		(end 145.815558 -262.656574)
		(width 0.0762)
		(layer "F.Cu")
		(net "M_G_CPU1_SB_CA<2>")
	)
	(segment
		(start 146.387566 -262.726678)
		(end 147.170394 -262.726678)
		(width 0.0762)
		(layer "F.Cu")
		(net "M_G_CPU1_SB_CA<2>")
	)
	(segment
		(start 147.170394 -262.726678)
		(end 147.37842 -262.518652)
		(width 0.0762)
		(layer "F.Cu")
		(net "M_G_CPU1_SB_CA<2>")
	)
	(segment
		(start 146.096482 -262.807704)
		(end 146.104864 -262.802878)
		(width 0.0762)
		(layer "F.Cu")
		(net "M_G_CPU1_SB_CA<2>")
	)
	(segment
		(start 151.820118 -264.206482)
		(end 156.429456 -264.206482)
		(width 0.10668)
		(layer "F.Cu")
		(net "M_G_CPU1_SB_CA<2>")
	)
	(segment
		(start 150.132288 -262.518652)
		(end 151.820118 -264.206482)
		(width 0.10668)
		(layer "F.Cu")
		(net "M_G_CPU1_SB_CA<2>")
	)
	(segment
		(start 147.37842 -262.518652)
		(end 147.72259 -262.518652)
		(width 0.0762)
		(layer "F.Cu")
		(net "M_G_CPU1_SB_CA<2>")
	)
	(segment
		(start 167.61968 -262.785352)
		(end 168.527984 -262.785352)
		(width 0.101346)
		(layer "F.Cu")
		(net "M_G_CPU1_SB_CA<2>")
	)
	(segment
		(start 167.194738 -262.36041)
		(end 167.61968 -262.785352)
		(width 0.101346)
		(layer "F.Cu")
		(net "M_G_CPU1_SB_CA<2>")
	)
	(arc
		(start 145.982436 -262.847582)
		(mid 146.041082 -262.832289)
		(end 146.096482 -262.807704)
		(width 0.0762)
		(layer "F.Cu")
		(net "M_G_CPU1_SB_CA<2>")
	)
	(arc
		(start 145.815558 -262.656574)
		(mid 145.845187 -262.799061)
		(end 145.982436 -262.847582)
		(width 0.0762)
		(layer "F.Cu")
		(net "M_G_CPU1_SB_CA<2>")
	)
	(arc
		(start 146.104864 -262.802878)
		(mid 146.218588 -262.752577)
		(end 146.340576 -262.728456)
		(width 0.0762)
		(layer "F.Cu")
		(net "M_G_CPU1_SB_CA<2>")
	)
	(arc
		(start 146.340576 -262.728456)
		(mid 146.364053 -262.72708)
		(end 146.387566 -262.726678)
		(width 0.0762)
		(layer "F.Cu")
		(net "M_G_CPU1_SB_CA<2>")
	)
	(segment
		(start 147.809966 -262.178292)
		(end 150.273766 -262.178292)
		(width 0.10668)
		(layer "F.Cu")
		(net "M_G_CPU1_SB_CA<1>")
	)
	(segment
		(start 159.822896 -261.818374)
		(end 159.822896 -261.439406)
		(width 0.10668)
		(layer "F.Cu")
		(net "M_G_CPU1_SB_CA<1>")
	)
	(segment
		(start 147.416012 -262.261604)
		(end 147.499324 -262.178292)
		(width 0.0762)
		(layer "F.Cu")
		(net "M_G_CPU1_SB_CA<1>")
	)
	(segment
		(start 150.273766 -262.178292)
		(end 151.961596 -263.866122)
		(width 0.10668)
		(layer "F.Cu")
		(net "M_G_CPU1_SB_CA<1>")
	)
	(segment
		(start 146.39163 -262.261604)
		(end 147.416012 -262.261604)
		(width 0.0762)
		(layer "F.Cu")
		(net "M_G_CPU1_SB_CA<1>")
	)
	(segment
		(start 160.22193 -261.818374)
		(end 160.33877 -261.935214)
		(width 0.10668)
		(layer "F.Cu")
		(net "M_G_CPU1_SB_CA<1>")
	)
	(segment
		(start 159.141668 -261.322566)
		(end 159.307022 -261.322566)
		(width 0.10668)
		(layer "F.Cu")
		(net "M_G_CPU1_SB_CA<1>")
	)
	(segment
		(start 158.907988 -261.935214)
		(end 159.024828 -261.818374)
		(width 0.10668)
		(layer "F.Cu")
		(net "M_G_CPU1_SB_CA<1>")
	)
	(segment
		(start 159.423862 -261.818374)
		(end 159.540702 -261.935214)
		(width 0.10668)
		(layer "F.Cu")
		(net "M_G_CPU1_SB_CA<1>")
	)
	(segment
		(start 159.307022 -261.322566)
		(end 159.423862 -261.439406)
		(width 0.10668)
		(layer "F.Cu")
		(net "M_G_CPU1_SB_CA<1>")
	)
	(segment
		(start 151.961596 -263.866122)
		(end 156.288232 -263.866122)
		(width 0.10668)
		(layer "F.Cu")
		(net "M_G_CPU1_SB_CA<1>")
	)
	(segment
		(start 159.706056 -261.935214)
		(end 159.822896 -261.818374)
		(width 0.10668)
		(layer "F.Cu")
		(net "M_G_CPU1_SB_CA<1>")
	)
	(segment
		(start 159.024828 -261.818374)
		(end 159.024828 -261.439406)
		(width 0.10668)
		(layer "F.Cu")
		(net "M_G_CPU1_SB_CA<1>")
	)
	(segment
		(start 160.22193 -261.439406)
		(end 160.22193 -261.818374)
		(width 0.10668)
		(layer "F.Cu")
		(net "M_G_CPU1_SB_CA<1>")
	)
	(segment
		(start 147.499324 -262.178292)
		(end 147.809966 -262.178292)
		(width 0.0762)
		(layer "F.Cu")
		(net "M_G_CPU1_SB_CA<1>")
	)
	(segment
		(start 160.10509 -261.322566)
		(end 160.22193 -261.439406)
		(width 0.10668)
		(layer "F.Cu")
		(net "M_G_CPU1_SB_CA<1>")
	)
	(segment
		(start 159.822896 -261.439406)
		(end 159.939736 -261.322566)
		(width 0.10668)
		(layer "F.Cu")
		(net "M_G_CPU1_SB_CA<1>")
	)
	(segment
		(start 160.33877 -261.935214)
		(end 164.427916 -261.935214)
		(width 0.10668)
		(layer "F.Cu")
		(net "M_G_CPU1_SB_CA<1>")
	)
	(segment
		(start 158.21914 -261.935214)
		(end 158.907988 -261.935214)
		(width 0.10668)
		(layer "F.Cu")
		(net "M_G_CPU1_SB_CA<1>")
	)
	(segment
		(start 156.288232 -263.866122)
		(end 158.21914 -261.935214)
		(width 0.10668)
		(layer "F.Cu")
		(net "M_G_CPU1_SB_CA<1>")
	)
	(segment
		(start 159.939736 -261.322566)
		(end 160.10509 -261.322566)
		(width 0.10668)
		(layer "F.Cu")
		(net "M_G_CPU1_SB_CA<1>")
	)
	(segment
		(start 159.024828 -261.439406)
		(end 159.141668 -261.322566)
		(width 0.10668)
		(layer "F.Cu")
		(net "M_G_CPU1_SB_CA<1>")
	)
	(segment
		(start 146.096482 -262.152892)
		(end 146.104864 -262.157718)
		(width 0.0762)
		(layer "F.Cu")
		(net "M_G_CPU1_SB_CA<1>")
	)
	(segment
		(start 159.540702 -261.935214)
		(end 159.706056 -261.935214)
		(width 0.10668)
		(layer "F.Cu")
		(net "M_G_CPU1_SB_CA<1>")
	)
	(segment
		(start 159.423862 -261.439406)
		(end 159.423862 -261.818374)
		(width 0.10668)
		(layer "F.Cu")
		(net "M_G_CPU1_SB_CA<1>")
	)
	(arc
		(start 144.790922 -262.157718)
		(mid 144.977866 -262.107463)
		(end 145.16481 -262.157718)
		(width 0.0762)
		(layer "F.Cu")
		(net "M_G_CPU1_SB_CA<1>")
	)
	(arc
		(start 146.104864 -262.157718)
		(mid 146.207758 -262.21009)
		(end 146.315938 -262.250428)
		(width 0.0762)
		(layer "F.Cu")
		(net "M_G_CPU1_SB_CA<1>")
	)
	(arc
		(start 144.037812 -262.480298)
		(mid 144.233161 -262.296479)
		(end 144.493996 -262.233918)
		(width 0.0762)
		(layer "F.Cu")
		(net "M_G_CPU1_SB_CA<1>")
	)
	(arc
		(start 145.730722 -262.157718)
		(mid 145.912973 -262.107368)
		(end 146.096482 -262.152892)
		(width 0.0762)
		(layer "F.Cu")
		(net "M_G_CPU1_SB_CA<1>")
	)
	(arc
		(start 145.16481 -262.157718)
		(mid 145.447766 -262.233895)
		(end 145.730722 -262.157718)
		(width 0.0762)
		(layer "F.Cu")
		(net "M_G_CPU1_SB_CA<1>")
	)
	(arc
		(start 146.315938 -262.250428)
		(mid 146.353364 -262.258867)
		(end 146.39163 -262.261604)
		(width 0.0762)
		(layer "F.Cu")
		(net "M_G_CPU1_SB_CA<1>")
	)
	(arc
		(start 144.493996 -262.233918)
		(mid 144.647745 -262.216409)
		(end 144.790922 -262.157718)
		(width 0.0762)
		(layer "F.Cu")
		(net "M_G_CPU1_SB_CA<1>")
	)
	(segment
		(start 146.358356 -262.051038)
		(end 147.189698 -262.052308)
		(width 0.0762)
		(layer "F.Cu")
		(net "M_G_CPU1_SB_CA<0>")
	)
	(segment
		(start 144.507966 -261.670292)
		(end 144.399508 -261.856982)
		(width 0.0762)
		(layer "F.Cu")
		(net "M_G_CPU1_SB_CA<0>")
	)
	(segment
		(start 145.260822 -261.992872)
		(end 145.261076 -261.992872)
		(width 0.0762)
		(layer "F.Cu")
		(net "M_G_CPU1_SB_CA<0>")
	)
	(segment
		(start 147.883626 -261.837932)
		(end 150.41499 -261.837932)
		(width 0.10668)
		(layer "F.Cu")
		(net "M_G_CPU1_SB_CA<0>")
	)
	(segment
		(start 168.031668 -261.08533)
		(end 168.527984 -261.08533)
		(width 0.10668)
		(layer "F.Cu")
		(net "M_G_CPU1_SB_CA<0>")
	)
	(segment
		(start 147.189698 -262.052308)
		(end 147.404074 -261.837932)
		(width 0.0762)
		(layer "F.Cu")
		(net "M_G_CPU1_SB_CA<0>")
	)
	(segment
		(start 150.41499 -261.837932)
		(end 152.10282 -263.525762)
		(width 0.10668)
		(layer "F.Cu")
		(net "M_G_CPU1_SB_CA<0>")
	)
	(segment
		(start 152.10282 -263.525762)
		(end 156.147008 -263.525762)
		(width 0.10668)
		(layer "F.Cu")
		(net "M_G_CPU1_SB_CA<0>")
	)
	(segment
		(start 156.147008 -263.525762)
		(end 159.015176 -260.657594)
		(width 0.10668)
		(layer "F.Cu")
		(net "M_G_CPU1_SB_CA<0>")
	)
	(segment
		(start 144.686528 -261.997698)
		(end 144.69491 -261.992872)
		(width 0.0762)
		(layer "F.Cu")
		(net "M_G_CPU1_SB_CA<0>")
	)
	(segment
		(start 147.404074 -261.837932)
		(end 147.883626 -261.837932)
		(width 0.0762)
		(layer "F.Cu")
		(net "M_G_CPU1_SB_CA<0>")
	)
	(segment
		(start 159.015176 -260.657594)
		(end 167.603932 -260.657594)
		(width 0.10668)
		(layer "F.Cu")
		(net "M_G_CPU1_SB_CA<0>")
	)
	(segment
		(start 167.603932 -260.657594)
		(end 168.031668 -261.08533)
		(width 0.10668)
		(layer "F.Cu")
		(net "M_G_CPU1_SB_CA<0>")
	)
	(arc
		(start 145.634964 -261.992872)
		(mid 145.91792 -261.916695)
		(end 146.200876 -261.992872)
		(width 0.0762)
		(layer "F.Cu")
		(net "M_G_CPU1_SB_CA<0>")
	)
	(arc
		(start 144.399508 -261.856982)
		(mid 144.425425 -261.990024)
		(end 144.551146 -262.040624)
		(width 0.0762)
		(layer "F.Cu")
		(net "M_G_CPU1_SB_CA<0>")
	)
	(arc
		(start 145.261076 -261.992872)
		(mid 145.44802 -262.043196)
		(end 145.634964 -261.992872)
		(width 0.0762)
		(layer "F.Cu")
		(net "M_G_CPU1_SB_CA<0>")
	)
	(arc
		(start 144.69491 -261.992872)
		(mid 144.977866 -261.916695)
		(end 145.260822 -261.992872)
		(width 0.0762)
		(layer "F.Cu")
		(net "M_G_CPU1_SB_CA<0>")
	)
	(arc
		(start 146.200876 -261.992872)
		(mid 146.24157 -262.015091)
		(end 146.283426 -262.035036)
		(width 0.0762)
		(layer "F.Cu")
		(net "M_G_CPU1_SB_CA<0>")
	)
	(arc
		(start 146.283426 -262.035036)
		(mid 146.320054 -262.046966)
		(end 146.358356 -262.051038)
		(width 0.0762)
		(layer "F.Cu")
		(net "M_G_CPU1_SB_CA<0>")
	)
	(arc
		(start 144.551146 -262.040624)
		(mid 144.6209 -262.025667)
		(end 144.686528 -261.997698)
		(width 0.0762)
		(layer "F.Cu")
		(net "M_G_CPU1_SB_CA<0>")
	)
	(segment
		(start 144.686528 -266.857734)
		(end 144.69491 -266.852908)
		(width 0.0762)
		(layer "F.Cu")
		(net "M_G_CPU1_SA_RSP<0>")
	)
	(segment
		(start 146.358356 -266.911074)
		(end 147.201382 -266.91209)
		(width 0.0762)
		(layer "F.Cu")
		(net "M_G_CPU1_SA_RSP<0>")
	)
	(segment
		(start 147.368006 -266.74445)
		(end 147.694904 -266.74445)
		(width 0.0762)
		(layer "F.Cu")
		(net "M_G_CPU1_SA_RSP<0>")
	)
	(segment
		(start 161.86404 -267.610082)
		(end 163.377626 -269.123668)
		(width 0.10668)
		(layer "F.Cu")
		(net "M_G_CPU1_SA_RSP<0>")
	)
	(segment
		(start 163.377626 -269.123668)
		(end 163.414456 -269.160498)
		(width 0.101346)
		(layer "F.Cu")
		(net "M_G_CPU1_SA_RSP<0>")
	)
	(segment
		(start 147.201382 -266.91209)
		(end 147.227544 -266.884912)
		(width 0.0762)
		(layer "F.Cu")
		(net "M_G_CPU1_SA_RSP<0>")
	)
	(segment
		(start 163.414456 -269.160498)
		(end 165.864286 -269.160498)
		(width 0.101346)
		(layer "F.Cu")
		(net "M_G_CPU1_SA_RSP<0>")
	)
	(segment
		(start 165.864286 -269.160498)
		(end 166.289228 -269.58544)
		(width 0.101346)
		(layer "F.Cu")
		(net "M_G_CPU1_SA_RSP<0>")
	)
	(segment
		(start 150.386542 -267.610082)
		(end 161.86404 -267.610082)
		(width 0.10668)
		(layer "F.Cu")
		(net "M_G_CPU1_SA_RSP<0>")
	)
	(segment
		(start 149.52091 -266.74445)
		(end 150.386542 -267.610082)
		(width 0.10668)
		(layer "F.Cu")
		(net "M_G_CPU1_SA_RSP<0>")
	)
	(segment
		(start 147.227544 -266.884912)
		(end 147.368006 -266.74445)
		(width 0.0762)
		(layer "F.Cu")
		(net "M_G_CPU1_SA_RSP<0>")
	)
	(segment
		(start 145.260822 -266.852908)
		(end 145.261076 -266.852908)
		(width 0.0762)
		(layer "F.Cu")
		(net "M_G_CPU1_SA_RSP<0>")
	)
	(segment
		(start 144.507966 -266.530328)
		(end 144.399508 -266.717018)
		(width 0.0762)
		(layer "F.Cu")
		(net "M_G_CPU1_SA_RSP<0>")
	)
	(segment
		(start 166.289228 -269.58544)
		(end 168.527984 -269.58544)
		(width 0.101346)
		(layer "F.Cu")
		(net "M_G_CPU1_SA_RSP<0>")
	)
	(segment
		(start 147.694904 -266.74445)
		(end 149.52091 -266.74445)
		(width 0.10668)
		(layer "F.Cu")
		(net "M_G_CPU1_SA_RSP<0>")
	)
	(arc
		(start 146.283426 -266.895072)
		(mid 146.320054 -266.907002)
		(end 146.358356 -266.911074)
		(width 0.0762)
		(layer "F.Cu")
		(net "M_G_CPU1_SA_RSP<0>")
	)
	(arc
		(start 146.200876 -266.852908)
		(mid 146.24157 -266.875127)
		(end 146.283426 -266.895072)
		(width 0.0762)
		(layer "F.Cu")
		(net "M_G_CPU1_SA_RSP<0>")
	)
	(arc
		(start 144.551146 -266.90066)
		(mid 144.6209 -266.885703)
		(end 144.686528 -266.857734)
		(width 0.0762)
		(layer "F.Cu")
		(net "M_G_CPU1_SA_RSP<0>")
	)
	(arc
		(start 145.634964 -266.852908)
		(mid 145.91792 -266.776731)
		(end 146.200876 -266.852908)
		(width 0.0762)
		(layer "F.Cu")
		(net "M_G_CPU1_SA_RSP<0>")
	)
	(arc
		(start 144.399508 -266.717018)
		(mid 144.425425 -266.85006)
		(end 144.551146 -266.90066)
		(width 0.0762)
		(layer "F.Cu")
		(net "M_G_CPU1_SA_RSP<0>")
	)
	(arc
		(start 145.261076 -266.852908)
		(mid 145.44802 -266.903232)
		(end 145.634964 -266.852908)
		(width 0.0762)
		(layer "F.Cu")
		(net "M_G_CPU1_SA_RSP<0>")
	)
	(arc
		(start 144.69491 -266.852908)
		(mid 144.977866 -266.776731)
		(end 145.260822 -266.852908)
		(width 0.0762)
		(layer "F.Cu")
		(net "M_G_CPU1_SA_RSP<0>")
	)
	(segment
		(start 147.60575 -255.878076)
		(end 150.444708 -255.878076)
		(width 0.10668)
		(layer "F.Cu")
		(net "M_G_CPU1_SA_PAR")
	)
	(segment
		(start 146.954748 -255.710944)
		(end 147.12188 -255.878076)
		(width 0.0762)
		(layer "F.Cu")
		(net "M_G_CPU1_SA_PAR")
	)
	(segment
		(start 165.367208 -253.010416)
		(end 166.642034 -254.285242)
		(width 0.101346)
		(layer "F.Cu")
		(net "M_G_CPU1_SA_PAR")
	)
	(segment
		(start 144.38757 -255.763522)
		(end 144.394936 -255.76784)
		(width 0.0762)
		(layer "F.Cu")
		(net "M_G_CPU1_SA_PAR")
	)
	(segment
		(start 144.960848 -255.76784)
		(end 144.96923 -255.763014)
		(width 0.0762)
		(layer "F.Cu")
		(net "M_G_CPU1_SA_PAR")
	)
	(segment
		(start 163.05022 -253.010416)
		(end 163.377626 -253.010416)
		(width 0.10668)
		(layer "F.Cu")
		(net "M_G_CPU1_SA_PAR")
	)
	(segment
		(start 147.12188 -255.878076)
		(end 147.60575 -255.878076)
		(width 0.0762)
		(layer "F.Cu")
		(net "M_G_CPU1_SA_PAR")
	)
	(segment
		(start 144.207992 -256.090166)
		(end 144.102836 -255.909318)
		(width 0.0762)
		(layer "F.Cu")
		(net "M_G_CPU1_SA_PAR")
	)
	(segment
		(start 161.083752 -254.976884)
		(end 163.05022 -253.010416)
		(width 0.10668)
		(layer "F.Cu")
		(net "M_G_CPU1_SA_PAR")
	)
	(segment
		(start 163.377626 -253.010416)
		(end 165.367208 -253.010416)
		(width 0.101346)
		(layer "F.Cu")
		(net "M_G_CPU1_SA_PAR")
	)
	(segment
		(start 152.112218 -254.210566)
		(end 155.881324 -254.210566)
		(width 0.10668)
		(layer "F.Cu")
		(net "M_G_CPU1_SA_PAR")
	)
	(segment
		(start 144.207992 -256.09042)
		(end 144.207992 -256.090166)
		(width 0.0762)
		(layer "F.Cu")
		(net "M_G_CPU1_SA_PAR")
	)
	(segment
		(start 150.444708 -255.878076)
		(end 152.112218 -254.210566)
		(width 0.10668)
		(layer "F.Cu")
		(net "M_G_CPU1_SA_PAR")
	)
	(segment
		(start 166.642034 -254.285242)
		(end 168.527984 -254.285242)
		(width 0.101346)
		(layer "F.Cu")
		(net "M_G_CPU1_SA_PAR")
	)
	(segment
		(start 144.386554 -255.763014)
		(end 144.38757 -255.763522)
		(width 0.0762)
		(layer "F.Cu")
		(net "M_G_CPU1_SA_PAR")
	)
	(segment
		(start 146.111976 -255.710944)
		(end 146.954748 -255.710944)
		(width 0.0762)
		(layer "F.Cu")
		(net "M_G_CPU1_SA_PAR")
	)
	(segment
		(start 157.73146 -254.976884)
		(end 161.083752 -254.976884)
		(width 0.10668)
		(layer "F.Cu")
		(net "M_G_CPU1_SA_PAR")
	)
	(segment
		(start 155.881324 -254.210566)
		(end 157.73146 -254.976884)
		(width 0.10668)
		(layer "F.Cu")
		(net "M_G_CPU1_SA_PAR")
	)
	(arc
		(start 144.96923 -255.763014)
		(mid 145.152738 -255.71752)
		(end 145.33499 -255.76784)
		(width 0.0762)
		(layer "F.Cu")
		(net "M_G_CPU1_SA_PAR")
	)
	(arc
		(start 145.900902 -255.76784)
		(mid 146.00267 -255.725406)
		(end 146.111976 -255.710944)
		(width 0.0762)
		(layer "F.Cu")
		(net "M_G_CPU1_SA_PAR")
	)
	(arc
		(start 144.102836 -255.909318)
		(mid 144.111773 -255.790294)
		(end 144.206468 -255.717548)
		(width 0.0762)
		(layer "F.Cu")
		(net "M_G_CPU1_SA_PAR")
	)
	(arc
		(start 144.394936 -255.76784)
		(mid 144.677892 -255.844017)
		(end 144.960848 -255.76784)
		(width 0.0762)
		(layer "F.Cu")
		(net "M_G_CPU1_SA_PAR")
	)
	(arc
		(start 144.206468 -255.717548)
		(mid 144.299392 -255.728871)
		(end 144.386554 -255.763014)
		(width 0.0762)
		(layer "F.Cu")
		(net "M_G_CPU1_SA_PAR")
	)
	(arc
		(start 145.33499 -255.76784)
		(mid 145.617946 -255.844017)
		(end 145.900902 -255.76784)
		(width 0.0762)
		(layer "F.Cu")
		(net "M_G_CPU1_SA_PAR")
	)
	(segment
		(start 160.749996 -241.868198)
		(end 161.02203 -242.140232)
		(width 0.12954)
		(layer "F.Cu")
		(net "M_G_CPU1_SA_DQS_DP<9>")
	)
	(segment
		(start 147.396708 -247.642634)
		(end 147.415758 -247.642634)
		(width 0.0762)
		(layer "F.Cu")
		(net "M_G_CPU1_SA_DQS_DP<9>")
	)
	(segment
		(start 160.68167 -242.947444)
		(end 160.68167 -242.480592)
		(width 0.12954)
		(layer "F.Cu")
		(net "M_G_CPU1_SA_DQS_DP<9>")
	)
	(segment
		(start 163.00831 -240.620804)
		(end 163.00831 -239.777524)
		(width 0.12954)
		(layer "F.Cu")
		(net "M_G_CPU1_SA_DQS_DP<9>")
	)
	(segment
		(start 156.418788 -247.642634)
		(end 159.54502 -244.516402)
		(width 0.12954)
		(layer "F.Cu")
		(net "M_G_CPU1_SA_DQS_DP<9>")
	)
	(segment
		(start 159.272986 -243.345208)
		(end 159.272986 -243.147088)
		(width 0.12954)
		(layer "F.Cu")
		(net "M_G_CPU1_SA_DQS_DP<9>")
	)
	(segment
		(start 161.81832 -241.343942)
		(end 161.546286 -241.071908)
		(width 0.12954)
		(layer "F.Cu")
		(net "M_G_CPU1_SA_DQS_DP<9>")
	)
	(segment
		(start 159.415226 -243.004848)
		(end 159.613346 -243.004848)
		(width 0.12954)
		(layer "F.Cu")
		(net "M_G_CPU1_SA_DQS_DP<9>")
	)
	(segment
		(start 160.68167 -242.480592)
		(end 160.409636 -242.208558)
		(width 0.12954)
		(layer "F.Cu")
		(net "M_G_CPU1_SA_DQS_DP<9>")
	)
	(segment
		(start 161.546286 -241.071908)
		(end 161.546286 -240.873788)
		(width 0.12954)
		(layer "F.Cu")
		(net "M_G_CPU1_SA_DQS_DP<9>")
	)
	(segment
		(start 160.352232 -243.276882)
		(end 160.68167 -242.947444)
		(width 0.12954)
		(layer "F.Cu")
		(net "M_G_CPU1_SA_DQS_DP<9>")
	)
	(segment
		(start 146.628104 -247.617234)
		(end 146.668744 -247.576594)
		(width 0.0762)
		(layer "F.Cu")
		(net "M_G_CPU1_SA_DQS_DP<9>")
	)
	(segment
		(start 146.087846 -247.617742)
		(end 146.088354 -247.617234)
		(width 0.0762)
		(layer "F.Cu")
		(net "M_G_CPU1_SA_DQS_DP<9>")
	)
	(segment
		(start 144.207992 -247.99036)
		(end 144.106138 -247.8151)
		(width 0.0762)
		(layer "F.Cu")
		(net "M_G_CPU1_SA_DQS_DP<9>")
	)
	(segment
		(start 147.330668 -247.576594)
		(end 147.396708 -247.642634)
		(width 0.0762)
		(layer "F.Cu")
		(net "M_G_CPU1_SA_DQS_DP<9>")
	)
	(segment
		(start 161.688526 -240.731548)
		(end 161.886646 -240.731548)
		(width 0.12954)
		(layer "F.Cu")
		(net "M_G_CPU1_SA_DQS_DP<9>")
	)
	(segment
		(start 159.54502 -243.617242)
		(end 159.272986 -243.345208)
		(width 0.12954)
		(layer "F.Cu")
		(net "M_G_CPU1_SA_DQS_DP<9>")
	)
	(segment
		(start 161.886646 -240.731548)
		(end 162.15868 -241.003582)
		(width 0.12954)
		(layer "F.Cu")
		(net "M_G_CPU1_SA_DQS_DP<9>")
	)
	(segment
		(start 161.02203 -242.140232)
		(end 161.488882 -242.140232)
		(width 0.12954)
		(layer "F.Cu")
		(net "M_G_CPU1_SA_DQS_DP<9>")
	)
	(segment
		(start 162.625532 -241.003582)
		(end 163.00831 -240.620804)
		(width 0.12954)
		(layer "F.Cu")
		(net "M_G_CPU1_SA_DQS_DP<9>")
	)
	(segment
		(start 147.415758 -247.642634)
		(end 156.418788 -247.642634)
		(width 0.12954)
		(layer "F.Cu")
		(net "M_G_CPU1_SA_DQS_DP<9>")
	)
	(segment
		(start 146.088354 -247.617234)
		(end 146.628104 -247.617234)
		(width 0.0762)
		(layer "F.Cu")
		(net "M_G_CPU1_SA_DQS_DP<9>")
	)
	(segment
		(start 160.551876 -241.868198)
		(end 160.749996 -241.868198)
		(width 0.12954)
		(layer "F.Cu")
		(net "M_G_CPU1_SA_DQS_DP<9>")
	)
	(segment
		(start 161.81832 -241.810794)
		(end 161.81832 -241.343942)
		(width 0.12954)
		(layer "F.Cu")
		(net "M_G_CPU1_SA_DQS_DP<9>")
	)
	(segment
		(start 161.488882 -242.140232)
		(end 161.81832 -241.810794)
		(width 0.12954)
		(layer "F.Cu")
		(net "M_G_CPU1_SA_DQS_DP<9>")
	)
	(segment
		(start 163.87064 -239.835436)
		(end 164.427916 -239.835436)
		(width 0.12954)
		(layer "F.Cu")
		(net "M_G_CPU1_SA_DQS_DP<9>")
	)
	(segment
		(start 144.386554 -247.662954)
		(end 144.394936 -247.66778)
		(width 0.0762)
		(layer "F.Cu")
		(net "M_G_CPU1_SA_DQS_DP<9>")
	)
	(segment
		(start 160.409636 -242.010438)
		(end 160.551876 -241.868198)
		(width 0.12954)
		(layer "F.Cu")
		(net "M_G_CPU1_SA_DQS_DP<9>")
	)
	(segment
		(start 162.15868 -241.003582)
		(end 162.625532 -241.003582)
		(width 0.12954)
		(layer "F.Cu")
		(net "M_G_CPU1_SA_DQS_DP<9>")
	)
	(segment
		(start 160.409636 -242.208558)
		(end 160.409636 -242.010438)
		(width 0.12954)
		(layer "F.Cu")
		(net "M_G_CPU1_SA_DQS_DP<9>")
	)
	(segment
		(start 159.88538 -243.276882)
		(end 160.352232 -243.276882)
		(width 0.12954)
		(layer "F.Cu")
		(net "M_G_CPU1_SA_DQS_DP<9>")
	)
	(segment
		(start 163.00831 -239.777524)
		(end 163.21405 -239.571784)
		(width 0.12954)
		(layer "F.Cu")
		(net "M_G_CPU1_SA_DQS_DP<9>")
	)
	(segment
		(start 163.21405 -239.571784)
		(end 163.606988 -239.571784)
		(width 0.12954)
		(layer "F.Cu")
		(net "M_G_CPU1_SA_DQS_DP<9>")
	)
	(segment
		(start 159.272986 -243.147088)
		(end 159.415226 -243.004848)
		(width 0.12954)
		(layer "F.Cu")
		(net "M_G_CPU1_SA_DQS_DP<9>")
	)
	(segment
		(start 146.668744 -247.576594)
		(end 147.330668 -247.576594)
		(width 0.0762)
		(layer "F.Cu")
		(net "M_G_CPU1_SA_DQS_DP<9>")
	)
	(segment
		(start 159.613346 -243.004848)
		(end 159.88538 -243.276882)
		(width 0.12954)
		(layer "F.Cu")
		(net "M_G_CPU1_SA_DQS_DP<9>")
	)
	(segment
		(start 159.54502 -244.516402)
		(end 159.54502 -243.617242)
		(width 0.12954)
		(layer "F.Cu")
		(net "M_G_CPU1_SA_DQS_DP<9>")
	)
	(segment
		(start 161.546286 -240.873788)
		(end 161.688526 -240.731548)
		(width 0.12954)
		(layer "F.Cu")
		(net "M_G_CPU1_SA_DQS_DP<9>")
	)
	(segment
		(start 144.960848 -247.66778)
		(end 144.96923 -247.662954)
		(width 0.0762)
		(layer "F.Cu")
		(net "M_G_CPU1_SA_DQS_DP<9>")
	)
	(segment
		(start 163.606988 -239.571784)
		(end 163.87064 -239.835436)
		(width 0.12954)
		(layer "F.Cu")
		(net "M_G_CPU1_SA_DQS_DP<9>")
	)
	(arc
		(start 145.900902 -247.66778)
		(mid 145.991071 -247.630431)
		(end 146.087846 -247.617742)
		(width 0.0762)
		(layer "F.Cu")
		(net "M_G_CPU1_SA_DQS_DP<9>")
	)
	(arc
		(start 144.106138 -247.8151)
		(mid 144.123332 -247.675514)
		(end 144.252696 -247.620282)
		(width 0.0762)
		(layer "F.Cu")
		(net "M_G_CPU1_SA_DQS_DP<9>")
	)
	(arc
		(start 144.96923 -247.662954)
		(mid 145.152738 -247.61746)
		(end 145.33499 -247.66778)
		(width 0.0762)
		(layer "F.Cu")
		(net "M_G_CPU1_SA_DQS_DP<9>")
	)
	(arc
		(start 144.252696 -247.620282)
		(mid 144.321643 -247.635279)
		(end 144.386554 -247.662954)
		(width 0.0762)
		(layer "F.Cu")
		(net "M_G_CPU1_SA_DQS_DP<9>")
	)
	(arc
		(start 144.394936 -247.66778)
		(mid 144.677892 -247.743957)
		(end 144.960848 -247.66778)
		(width 0.0762)
		(layer "F.Cu")
		(net "M_G_CPU1_SA_DQS_DP<9>")
	)
	(arc
		(start 145.33499 -247.66778)
		(mid 145.617946 -247.743957)
		(end 145.900902 -247.66778)
		(width 0.0762)
		(layer "F.Cu")
		(net "M_G_CPU1_SA_DQS_DP<9>")
	)
	(segment
		(start 144.207992 -243.130324)
		(end 144.106138 -242.955064)
		(width 0.0762)
		(layer "F.Cu")
		(net "M_G_CPU1_SA_DQS_DP<8>")
	)
	(segment
		(start 157.818836 -238.25962)
		(end 161.057336 -235.02112)
		(width 0.12954)
		(layer "F.Cu")
		(net "M_G_CPU1_SA_DQS_DP<8>")
	)
	(segment
		(start 160.210754 -233.708702)
		(end 160.210754 -233.509566)
		(width 0.12954)
		(layer "F.Cu")
		(net "M_G_CPU1_SA_DQS_DP<8>")
	)
	(segment
		(start 160.550606 -233.36885)
		(end 161.239962 -234.058206)
		(width 0.12954)
		(layer "F.Cu")
		(net "M_G_CPU1_SA_DQS_DP<8>")
	)
	(segment
		(start 161.705798 -234.058206)
		(end 162.03676 -233.727244)
		(width 0.12954)
		(layer "F.Cu")
		(net "M_G_CPU1_SA_DQS_DP<8>")
	)
	(segment
		(start 144.386554 -242.802918)
		(end 144.394936 -242.807744)
		(width 0.0762)
		(layer "F.Cu")
		(net "M_G_CPU1_SA_DQS_DP<8>")
	)
	(segment
		(start 146.885914 -242.757198)
		(end 147.24126 -243.112544)
		(width 0.0762)
		(layer "F.Cu")
		(net "M_G_CPU1_SA_DQS_DP<8>")
	)
	(segment
		(start 146.088354 -242.757198)
		(end 146.885914 -242.757198)
		(width 0.0762)
		(layer "F.Cu")
		(net "M_G_CPU1_SA_DQS_DP<8>")
	)
	(segment
		(start 147.675092 -243.178584)
		(end 151.7904 -243.178584)
		(width 0.12954)
		(layer "F.Cu")
		(net "M_G_CPU1_SA_DQS_DP<8>")
	)
	(segment
		(start 147.656042 -243.178584)
		(end 147.675092 -243.178584)
		(width 0.0762)
		(layer "F.Cu")
		(net "M_G_CPU1_SA_DQS_DP<8>")
	)
	(segment
		(start 162.03676 -233.261408)
		(end 161.347404 -232.572052)
		(width 0.12954)
		(layer "F.Cu")
		(net "M_G_CPU1_SA_DQS_DP<8>")
	)
	(segment
		(start 161.347404 -232.572052)
		(end 161.347404 -232.372916)
		(width 0.12954)
		(layer "F.Cu")
		(net "M_G_CPU1_SA_DQS_DP<8>")
	)
	(segment
		(start 163.49853 -230.22179)
		(end 163.606988 -230.22179)
		(width 0.12954)
		(layer "F.Cu")
		(net "M_G_CPU1_SA_DQS_DP<8>")
	)
	(segment
		(start 147.24126 -243.112544)
		(end 147.590002 -243.112544)
		(width 0.0762)
		(layer "F.Cu")
		(net "M_G_CPU1_SA_DQS_DP<8>")
	)
	(segment
		(start 161.057336 -234.555284)
		(end 160.210754 -233.708702)
		(width 0.12954)
		(layer "F.Cu")
		(net "M_G_CPU1_SA_DQS_DP<8>")
	)
	(segment
		(start 146.087846 -242.757706)
		(end 146.088354 -242.757198)
		(width 0.0762)
		(layer "F.Cu")
		(net "M_G_CPU1_SA_DQS_DP<8>")
	)
	(segment
		(start 163.87064 -230.485442)
		(end 164.427916 -230.485442)
		(width 0.12954)
		(layer "F.Cu")
		(net "M_G_CPU1_SA_DQS_DP<8>")
	)
	(segment
		(start 162.03676 -233.727244)
		(end 162.03676 -233.261408)
		(width 0.12954)
		(layer "F.Cu")
		(net "M_G_CPU1_SA_DQS_DP<8>")
	)
	(segment
		(start 163.606988 -230.22179)
		(end 163.87064 -230.485442)
		(width 0.12954)
		(layer "F.Cu")
		(net "M_G_CPU1_SA_DQS_DP<8>")
	)
	(segment
		(start 160.35147 -233.36885)
		(end 160.550606 -233.36885)
		(width 0.12954)
		(layer "F.Cu")
		(net "M_G_CPU1_SA_DQS_DP<8>")
	)
	(segment
		(start 144.960848 -242.807744)
		(end 144.96923 -242.802918)
		(width 0.0762)
		(layer "F.Cu")
		(net "M_G_CPU1_SA_DQS_DP<8>")
	)
	(segment
		(start 151.7904 -243.178584)
		(end 156.709364 -238.25962)
		(width 0.12954)
		(layer "F.Cu")
		(net "M_G_CPU1_SA_DQS_DP<8>")
	)
	(segment
		(start 161.239962 -234.058206)
		(end 161.705798 -234.058206)
		(width 0.12954)
		(layer "F.Cu")
		(net "M_G_CPU1_SA_DQS_DP<8>")
	)
	(segment
		(start 161.057336 -235.02112)
		(end 161.057336 -234.555284)
		(width 0.12954)
		(layer "F.Cu")
		(net "M_G_CPU1_SA_DQS_DP<8>")
	)
	(segment
		(start 160.210754 -233.509566)
		(end 160.35147 -233.36885)
		(width 0.12954)
		(layer "F.Cu")
		(net "M_G_CPU1_SA_DQS_DP<8>")
	)
	(segment
		(start 156.709364 -238.25962)
		(end 157.818836 -238.25962)
		(width 0.12954)
		(layer "F.Cu")
		(net "M_G_CPU1_SA_DQS_DP<8>")
	)
	(segment
		(start 147.590002 -243.112544)
		(end 147.656042 -243.178584)
		(width 0.0762)
		(layer "F.Cu")
		(net "M_G_CPU1_SA_DQS_DP<8>")
	)
	(segment
		(start 161.347404 -232.372916)
		(end 163.49853 -230.22179)
		(width 0.12954)
		(layer "F.Cu")
		(net "M_G_CPU1_SA_DQS_DP<8>")
	)
	(arc
		(start 144.106138 -242.955064)
		(mid 144.123332 -242.815478)
		(end 144.252696 -242.760246)
		(width 0.0762)
		(layer "F.Cu")
		(net "M_G_CPU1_SA_DQS_DP<8>")
	)
	(arc
		(start 144.96923 -242.802918)
		(mid 145.152738 -242.757424)
		(end 145.33499 -242.807744)
		(width 0.0762)
		(layer "F.Cu")
		(net "M_G_CPU1_SA_DQS_DP<8>")
	)
	(arc
		(start 144.394936 -242.807744)
		(mid 144.677892 -242.883921)
		(end 144.960848 -242.807744)
		(width 0.0762)
		(layer "F.Cu")
		(net "M_G_CPU1_SA_DQS_DP<8>")
	)
	(arc
		(start 145.33499 -242.807744)
		(mid 145.617946 -242.883921)
		(end 145.900902 -242.807744)
		(width 0.0762)
		(layer "F.Cu")
		(net "M_G_CPU1_SA_DQS_DP<8>")
	)
	(arc
		(start 145.900902 -242.807744)
		(mid 145.991071 -242.770395)
		(end 146.087846 -242.757706)
		(width 0.0762)
		(layer "F.Cu")
		(net "M_G_CPU1_SA_DQS_DP<8>")
	)
	(arc
		(start 144.252696 -242.760246)
		(mid 144.321643 -242.775243)
		(end 144.386554 -242.802918)
		(width 0.0762)
		(layer "F.Cu")
		(net "M_G_CPU1_SA_DQS_DP<8>")
	)
	(segment
		(start 162.16249 -222.530924)
		(end 162.628326 -222.530924)
		(width 0.12954)
		(layer "F.Cu")
		(net "M_G_CPU1_SA_DQS_DP<7>")
	)
	(segment
		(start 162.959288 -222.199962)
		(end 162.959288 -221.734126)
		(width 0.12954)
		(layer "F.Cu")
		(net "M_G_CPU1_SA_DQS_DP<7>")
	)
	(segment
		(start 162.628326 -222.530924)
		(end 162.959288 -222.199962)
		(width 0.12954)
		(layer "F.Cu")
		(net "M_G_CPU1_SA_DQS_DP<7>")
	)
	(segment
		(start 162.066986 -223.58096)
		(end 162.066986 -223.115124)
		(width 0.12954)
		(layer "F.Cu")
		(net "M_G_CPU1_SA_DQS_DP<7>")
	)
	(segment
		(start 161.722562 -222.290132)
		(end 161.921698 -222.290132)
		(width 0.12954)
		(layer "F.Cu")
		(net "M_G_CPU1_SA_DQS_DP<7>")
	)
	(segment
		(start 160.497012 -223.337882)
		(end 160.696148 -223.337882)
		(width 0.12954)
		(layer "F.Cu")
		(net "M_G_CPU1_SA_DQS_DP<7>")
	)
	(segment
		(start 162.728148 -221.502986)
		(end 162.728148 -221.320106)
		(width 0.12954)
		(layer "F.Cu")
		(net "M_G_CPU1_SA_DQS_DP<7>")
	)
	(segment
		(start 161.581846 -222.430848)
		(end 161.722562 -222.290132)
		(width 0.12954)
		(layer "F.Cu")
		(net "M_G_CPU1_SA_DQS_DP<7>")
	)
	(segment
		(start 161.02584 -224.813114)
		(end 161.02584 -224.347278)
		(width 0.12954)
		(layer "F.Cu")
		(net "M_G_CPU1_SA_DQS_DP<7>")
	)
	(segment
		(start 149.333966 -238.154464)
		(end 159.20466 -228.28377)
		(width 0.12954)
		(layer "F.Cu")
		(net "M_G_CPU1_SA_DQS_DP<7>")
	)
	(segment
		(start 161.921698 -222.290132)
		(end 162.16249 -222.530924)
		(width 0.12954)
		(layer "F.Cu")
		(net "M_G_CPU1_SA_DQS_DP<7>")
	)
	(segment
		(start 146.087846 -237.89767)
		(end 146.088354 -237.897162)
		(width 0.0762)
		(layer "F.Cu")
		(net "M_G_CPU1_SA_DQS_DP<7>")
	)
	(segment
		(start 159.20466 -228.28377)
		(end 159.20466 -224.579434)
		(width 0.12954)
		(layer "F.Cu")
		(net "M_G_CPU1_SA_DQS_DP<7>")
	)
	(segment
		(start 163.870894 -221.135194)
		(end 164.427916 -221.135194)
		(width 0.12954)
		(layer "F.Cu")
		(net "M_G_CPU1_SA_DQS_DP<7>")
	)
	(segment
		(start 144.207992 -238.270288)
		(end 144.106138 -238.095028)
		(width 0.0762)
		(layer "F.Cu")
		(net "M_G_CPU1_SA_DQS_DP<7>")
	)
	(segment
		(start 163.606988 -220.871796)
		(end 163.87064 -221.135448)
		(width 0.12954)
		(layer "F.Cu")
		(net "M_G_CPU1_SA_DQS_DP<7>")
	)
	(segment
		(start 162.959288 -221.734126)
		(end 162.728148 -221.502986)
		(width 0.12954)
		(layer "F.Cu")
		(net "M_G_CPU1_SA_DQS_DP<7>")
	)
	(segment
		(start 161.581846 -222.629984)
		(end 161.581846 -222.430848)
		(width 0.12954)
		(layer "F.Cu")
		(net "M_G_CPU1_SA_DQS_DP<7>")
	)
	(segment
		(start 147.53209 -238.154464)
		(end 147.55114 -238.154464)
		(width 0.0762)
		(layer "F.Cu")
		(net "M_G_CPU1_SA_DQS_DP<7>")
	)
	(segment
		(start 163.87064 -221.135448)
		(end 163.870894 -221.135194)
		(width 0.12954)
		(layer "F.Cu")
		(net "M_G_CPU1_SA_DQS_DP<7>")
	)
	(segment
		(start 144.960848 -237.947708)
		(end 144.96923 -237.942882)
		(width 0.0762)
		(layer "F.Cu")
		(net "M_G_CPU1_SA_DQS_DP<7>")
	)
	(segment
		(start 146.088354 -237.897162)
		(end 146.89455 -237.897162)
		(width 0.0762)
		(layer "F.Cu")
		(net "M_G_CPU1_SA_DQS_DP<7>")
	)
	(segment
		(start 159.20466 -224.579434)
		(end 159.34309 -224.441004)
		(width 0.12954)
		(layer "F.Cu")
		(net "M_G_CPU1_SA_DQS_DP<7>")
	)
	(segment
		(start 161.736024 -223.911922)
		(end 162.066986 -223.58096)
		(width 0.12954)
		(layer "F.Cu")
		(net "M_G_CPU1_SA_DQS_DP<7>")
	)
	(segment
		(start 163.176458 -220.871796)
		(end 163.606988 -220.871796)
		(width 0.12954)
		(layer "F.Cu")
		(net "M_G_CPU1_SA_DQS_DP<7>")
	)
	(segment
		(start 160.229042 -225.144076)
		(end 160.694878 -225.144076)
		(width 0.12954)
		(layer "F.Cu")
		(net "M_G_CPU1_SA_DQS_DP<7>")
	)
	(segment
		(start 162.066986 -223.115124)
		(end 161.581846 -222.629984)
		(width 0.12954)
		(layer "F.Cu")
		(net "M_G_CPU1_SA_DQS_DP<7>")
	)
	(segment
		(start 160.696148 -223.337882)
		(end 161.270188 -223.911922)
		(width 0.12954)
		(layer "F.Cu")
		(net "M_G_CPU1_SA_DQS_DP<7>")
	)
	(segment
		(start 144.386554 -237.942882)
		(end 144.394936 -237.947708)
		(width 0.0762)
		(layer "F.Cu")
		(net "M_G_CPU1_SA_DQS_DP<7>")
	)
	(segment
		(start 159.34309 -224.441004)
		(end 159.52597 -224.441004)
		(width 0.12954)
		(layer "F.Cu")
		(net "M_G_CPU1_SA_DQS_DP<7>")
	)
	(segment
		(start 147.46605 -238.088424)
		(end 147.53209 -238.154464)
		(width 0.0762)
		(layer "F.Cu")
		(net "M_G_CPU1_SA_DQS_DP<7>")
	)
	(segment
		(start 159.52597 -224.441004)
		(end 160.229042 -225.144076)
		(width 0.12954)
		(layer "F.Cu")
		(net "M_G_CPU1_SA_DQS_DP<7>")
	)
	(segment
		(start 161.02584 -224.347278)
		(end 160.356296 -223.677734)
		(width 0.12954)
		(layer "F.Cu")
		(net "M_G_CPU1_SA_DQS_DP<7>")
	)
	(segment
		(start 146.89455 -237.897162)
		(end 147.085812 -238.088424)
		(width 0.0762)
		(layer "F.Cu")
		(net "M_G_CPU1_SA_DQS_DP<7>")
	)
	(segment
		(start 147.55114 -238.154464)
		(end 149.333966 -238.154464)
		(width 0.12954)
		(layer "F.Cu")
		(net "M_G_CPU1_SA_DQS_DP<7>")
	)
	(segment
		(start 162.728148 -221.320106)
		(end 163.176458 -220.871796)
		(width 0.12954)
		(layer "F.Cu")
		(net "M_G_CPU1_SA_DQS_DP<7>")
	)
	(segment
		(start 147.085812 -238.088424)
		(end 147.46605 -238.088424)
		(width 0.0762)
		(layer "F.Cu")
		(net "M_G_CPU1_SA_DQS_DP<7>")
	)
	(segment
		(start 161.270188 -223.911922)
		(end 161.736024 -223.911922)
		(width 0.12954)
		(layer "F.Cu")
		(net "M_G_CPU1_SA_DQS_DP<7>")
	)
	(segment
		(start 160.356296 -223.478598)
		(end 160.497012 -223.337882)
		(width 0.12954)
		(layer "F.Cu")
		(net "M_G_CPU1_SA_DQS_DP<7>")
	)
	(segment
		(start 160.356296 -223.677734)
		(end 160.356296 -223.478598)
		(width 0.12954)
		(layer "F.Cu")
		(net "M_G_CPU1_SA_DQS_DP<7>")
	)
	(segment
		(start 160.694878 -225.144076)
		(end 161.02584 -224.813114)
		(width 0.12954)
		(layer "F.Cu")
		(net "M_G_CPU1_SA_DQS_DP<7>")
	)
	(arc
		(start 144.252696 -237.90021)
		(mid 144.321643 -237.915207)
		(end 144.386554 -237.942882)
		(width 0.0762)
		(layer "F.Cu")
		(net "M_G_CPU1_SA_DQS_DP<7>")
	)
	(arc
		(start 144.96923 -237.942882)
		(mid 145.152738 -237.897388)
		(end 145.33499 -237.947708)
		(width 0.0762)
		(layer "F.Cu")
		(net "M_G_CPU1_SA_DQS_DP<7>")
	)
	(arc
		(start 144.106138 -238.095028)
		(mid 144.123332 -237.955442)
		(end 144.252696 -237.90021)
		(width 0.0762)
		(layer "F.Cu")
		(net "M_G_CPU1_SA_DQS_DP<7>")
	)
	(arc
		(start 144.394936 -237.947708)
		(mid 144.677892 -238.023885)
		(end 144.960848 -237.947708)
		(width 0.0762)
		(layer "F.Cu")
		(net "M_G_CPU1_SA_DQS_DP<7>")
	)
	(arc
		(start 145.33499 -237.947708)
		(mid 145.617946 -238.023885)
		(end 145.900902 -237.947708)
		(width 0.0762)
		(layer "F.Cu")
		(net "M_G_CPU1_SA_DQS_DP<7>")
	)
	(arc
		(start 145.900902 -237.947708)
		(mid 145.991071 -237.910359)
		(end 146.087846 -237.89767)
		(width 0.0762)
		(layer "F.Cu")
		(net "M_G_CPU1_SA_DQS_DP<7>")
	)
	(segment
		(start 159.846518 -214.883492)
		(end 159.846518 -214.41664)
		(width 0.12954)
		(layer "F.Cu")
		(net "M_G_CPU1_SA_DQS_DP<6>")
	)
	(segment
		(start 162.119818 -212.610192)
		(end 162.119818 -212.14334)
		(width 0.12954)
		(layer "F.Cu")
		(net "M_G_CPU1_SA_DQS_DP<6>")
	)
	(segment
		(start 159.704786 -213.594188)
		(end 160.186878 -214.07628)
		(width 0.12954)
		(layer "F.Cu")
		(net "M_G_CPU1_SA_DQS_DP<6>")
	)
	(segment
		(start 147.302728 -233.103166)
		(end 147.321778 -233.103166)
		(width 0.0762)
		(layer "F.Cu")
		(net "M_G_CPU1_SA_DQS_DP<6>")
	)
	(segment
		(start 159.506666 -213.594188)
		(end 159.704786 -213.594188)
		(width 0.12954)
		(layer "F.Cu")
		(net "M_G_CPU1_SA_DQS_DP<6>")
	)
	(segment
		(start 159.364426 -213.736428)
		(end 159.506666 -213.594188)
		(width 0.12954)
		(layer "F.Cu")
		(net "M_G_CPU1_SA_DQS_DP<6>")
	)
	(segment
		(start 160.65373 -214.07628)
		(end 160.983168 -213.746842)
		(width 0.12954)
		(layer "F.Cu")
		(net "M_G_CPU1_SA_DQS_DP<6>")
	)
	(segment
		(start 160.186878 -214.07628)
		(end 160.65373 -214.07628)
		(width 0.12954)
		(layer "F.Cu")
		(net "M_G_CPU1_SA_DQS_DP<6>")
	)
	(segment
		(start 161.978086 -211.320888)
		(end 162.460178 -211.80298)
		(width 0.12954)
		(layer "F.Cu")
		(net "M_G_CPU1_SA_DQS_DP<6>")
	)
	(segment
		(start 147.321778 -233.103166)
		(end 148.138388 -233.103166)
		(width 0.12954)
		(layer "F.Cu")
		(net "M_G_CPU1_SA_DQS_DP<6>")
	)
	(segment
		(start 160.501076 -212.797898)
		(end 160.501076 -212.599778)
		(width 0.12954)
		(layer "F.Cu")
		(net "M_G_CPU1_SA_DQS_DP<6>")
	)
	(segment
		(start 161.637726 -211.661248)
		(end 161.637726 -211.463128)
		(width 0.12954)
		(layer "F.Cu")
		(net "M_G_CPU1_SA_DQS_DP<6>")
	)
	(segment
		(start 147.236688 -233.037126)
		(end 147.302728 -233.103166)
		(width 0.0762)
		(layer "F.Cu")
		(net "M_G_CPU1_SA_DQS_DP<6>")
	)
	(segment
		(start 163.87064 -211.785454)
		(end 163.870894 -211.7852)
		(width 0.12954)
		(layer "F.Cu")
		(net "M_G_CPU1_SA_DQS_DP<6>")
	)
	(segment
		(start 146.088354 -233.037126)
		(end 147.236688 -233.037126)
		(width 0.0762)
		(layer "F.Cu")
		(net "M_G_CPU1_SA_DQS_DP<6>")
	)
	(segment
		(start 163.606988 -211.521802)
		(end 163.87064 -211.785454)
		(width 0.12954)
		(layer "F.Cu")
		(net "M_G_CPU1_SA_DQS_DP<6>")
	)
	(segment
		(start 162.119818 -212.14334)
		(end 161.637726 -211.661248)
		(width 0.12954)
		(layer "F.Cu")
		(net "M_G_CPU1_SA_DQS_DP<6>")
	)
	(segment
		(start 160.643316 -212.457538)
		(end 160.841436 -212.457538)
		(width 0.12954)
		(layer "F.Cu")
		(net "M_G_CPU1_SA_DQS_DP<6>")
	)
	(segment
		(start 162.92703 -211.80298)
		(end 163.208208 -211.521802)
		(width 0.12954)
		(layer "F.Cu")
		(net "M_G_CPU1_SA_DQS_DP<6>")
	)
	(segment
		(start 159.846518 -214.41664)
		(end 159.364426 -213.934548)
		(width 0.12954)
		(layer "F.Cu")
		(net "M_G_CPU1_SA_DQS_DP<6>")
	)
	(segment
		(start 162.460178 -211.80298)
		(end 162.92703 -211.80298)
		(width 0.12954)
		(layer "F.Cu")
		(net "M_G_CPU1_SA_DQS_DP<6>")
	)
	(segment
		(start 144.386554 -233.082846)
		(end 144.394936 -233.087672)
		(width 0.0762)
		(layer "F.Cu")
		(net "M_G_CPU1_SA_DQS_DP<6>")
	)
	(segment
		(start 163.870894 -211.7852)
		(end 164.427916 -211.7852)
		(width 0.12954)
		(layer "F.Cu")
		(net "M_G_CPU1_SA_DQS_DP<6>")
	)
	(segment
		(start 159.364426 -213.934548)
		(end 159.364426 -213.736428)
		(width 0.12954)
		(layer "F.Cu")
		(net "M_G_CPU1_SA_DQS_DP<6>")
	)
	(segment
		(start 148.138388 -233.103166)
		(end 154.76093 -226.480624)
		(width 0.12954)
		(layer "F.Cu")
		(net "M_G_CPU1_SA_DQS_DP<6>")
	)
	(segment
		(start 163.208208 -211.521802)
		(end 163.606988 -211.521802)
		(width 0.12954)
		(layer "F.Cu")
		(net "M_G_CPU1_SA_DQS_DP<6>")
	)
	(segment
		(start 161.79038 -212.93963)
		(end 162.119818 -212.610192)
		(width 0.12954)
		(layer "F.Cu")
		(net "M_G_CPU1_SA_DQS_DP<6>")
	)
	(segment
		(start 161.323528 -212.93963)
		(end 161.79038 -212.93963)
		(width 0.12954)
		(layer "F.Cu")
		(net "M_G_CPU1_SA_DQS_DP<6>")
	)
	(segment
		(start 160.501076 -212.599778)
		(end 160.643316 -212.457538)
		(width 0.12954)
		(layer "F.Cu")
		(net "M_G_CPU1_SA_DQS_DP<6>")
	)
	(segment
		(start 160.841436 -212.457538)
		(end 161.323528 -212.93963)
		(width 0.12954)
		(layer "F.Cu")
		(net "M_G_CPU1_SA_DQS_DP<6>")
	)
	(segment
		(start 154.76093 -226.480624)
		(end 154.76093 -219.96908)
		(width 0.12954)
		(layer "F.Cu")
		(net "M_G_CPU1_SA_DQS_DP<6>")
	)
	(segment
		(start 160.983168 -213.746842)
		(end 160.983168 -213.27999)
		(width 0.12954)
		(layer "F.Cu")
		(net "M_G_CPU1_SA_DQS_DP<6>")
	)
	(segment
		(start 161.779966 -211.320888)
		(end 161.978086 -211.320888)
		(width 0.12954)
		(layer "F.Cu")
		(net "M_G_CPU1_SA_DQS_DP<6>")
	)
	(segment
		(start 144.960848 -233.087672)
		(end 144.96923 -233.082846)
		(width 0.0762)
		(layer "F.Cu")
		(net "M_G_CPU1_SA_DQS_DP<6>")
	)
	(segment
		(start 144.207992 -233.410252)
		(end 144.106138 -233.234992)
		(width 0.0762)
		(layer "F.Cu")
		(net "M_G_CPU1_SA_DQS_DP<6>")
	)
	(segment
		(start 146.087846 -233.037634)
		(end 146.088354 -233.037126)
		(width 0.0762)
		(layer "F.Cu")
		(net "M_G_CPU1_SA_DQS_DP<6>")
	)
	(segment
		(start 160.983168 -213.27999)
		(end 160.501076 -212.797898)
		(width 0.12954)
		(layer "F.Cu")
		(net "M_G_CPU1_SA_DQS_DP<6>")
	)
	(segment
		(start 161.637726 -211.463128)
		(end 161.779966 -211.320888)
		(width 0.12954)
		(layer "F.Cu")
		(net "M_G_CPU1_SA_DQS_DP<6>")
	)
	(segment
		(start 154.76093 -219.96908)
		(end 159.846518 -214.883492)
		(width 0.12954)
		(layer "F.Cu")
		(net "M_G_CPU1_SA_DQS_DP<6>")
	)
	(arc
		(start 145.900902 -233.087672)
		(mid 145.991071 -233.050323)
		(end 146.087846 -233.037634)
		(width 0.0762)
		(layer "F.Cu")
		(net "M_G_CPU1_SA_DQS_DP<6>")
	)
	(arc
		(start 144.106138 -233.234992)
		(mid 144.123332 -233.095406)
		(end 144.252696 -233.040174)
		(width 0.0762)
		(layer "F.Cu")
		(net "M_G_CPU1_SA_DQS_DP<6>")
	)
	(arc
		(start 145.33499 -233.087672)
		(mid 145.617946 -233.163849)
		(end 145.900902 -233.087672)
		(width 0.0762)
		(layer "F.Cu")
		(net "M_G_CPU1_SA_DQS_DP<6>")
	)
	(arc
		(start 144.252696 -233.040174)
		(mid 144.321643 -233.055171)
		(end 144.386554 -233.082846)
		(width 0.0762)
		(layer "F.Cu")
		(net "M_G_CPU1_SA_DQS_DP<6>")
	)
	(arc
		(start 144.394936 -233.087672)
		(mid 144.677892 -233.163849)
		(end 144.960848 -233.087672)
		(width 0.0762)
		(layer "F.Cu")
		(net "M_G_CPU1_SA_DQS_DP<6>")
	)
	(arc
		(start 144.96923 -233.082846)
		(mid 145.152738 -233.037352)
		(end 145.33499 -233.087672)
		(width 0.0762)
		(layer "F.Cu")
		(net "M_G_CPU1_SA_DQS_DP<6>")
	)
	(segment
		(start 160.901888 -205.09865)
		(end 161.367978 -205.09865)
		(width 0.12954)
		(layer "F.Cu")
		(net "M_G_CPU1_SA_DQS_DP<5>")
	)
	(segment
		(start 146.952208 -227.896166)
		(end 147.44573 -227.402644)
		(width 0.0762)
		(layer "F.Cu")
		(net "M_G_CPU1_SA_DQS_DP<5>")
	)
	(segment
		(start 161.55543 -203.478892)
		(end 162.038538 -203.962)
		(width 0.12954)
		(layer "F.Cu")
		(net "M_G_CPU1_SA_DQS_DP<5>")
	)
	(segment
		(start 162.038538 -203.962)
		(end 162.504628 -203.962)
		(width 0.12954)
		(layer "F.Cu")
		(net "M_G_CPU1_SA_DQS_DP<5>")
	)
	(segment
		(start 160.231328 -206.2353)
		(end 160.56229 -205.904338)
		(width 0.12954)
		(layer "F.Cu")
		(net "M_G_CPU1_SA_DQS_DP<5>")
	)
	(segment
		(start 160.40481 -204.601572)
		(end 160.901888 -205.09865)
		(width 0.12954)
		(layer "F.Cu")
		(net "M_G_CPU1_SA_DQS_DP<5>")
	)
	(segment
		(start 159.138366 -206.74711)
		(end 159.138366 -206.509874)
		(width 0.12954)
		(layer "F.Cu")
		(net "M_G_CPU1_SA_DQS_DP<5>")
	)
	(segment
		(start 161.69894 -204.302106)
		(end 161.215578 -203.818744)
		(width 0.12954)
		(layer "F.Cu")
		(net "M_G_CPU1_SA_DQS_DP<5>")
	)
	(segment
		(start 161.215578 -203.818744)
		(end 161.215578 -203.620116)
		(width 0.12954)
		(layer "F.Cu")
		(net "M_G_CPU1_SA_DQS_DP<5>")
	)
	(segment
		(start 161.367978 -205.09865)
		(end 161.69894 -204.767688)
		(width 0.12954)
		(layer "F.Cu")
		(net "M_G_CPU1_SA_DQS_DP<5>")
	)
	(segment
		(start 158.863284 -207.022192)
		(end 159.138366 -206.74711)
		(width 0.12954)
		(layer "F.Cu")
		(net "M_G_CPU1_SA_DQS_DP<5>")
	)
	(segment
		(start 162.504628 -203.962)
		(end 162.83559 -203.631038)
		(width 0.12954)
		(layer "F.Cu")
		(net "M_G_CPU1_SA_DQS_DP<5>")
	)
	(segment
		(start 163.87064 -202.43546)
		(end 163.870894 -202.435206)
		(width 0.12954)
		(layer "F.Cu")
		(net "M_G_CPU1_SA_DQS_DP<5>")
	)
	(segment
		(start 162.410394 -202.55738)
		(end 162.795966 -202.171808)
		(width 0.12954)
		(layer "F.Cu")
		(net "M_G_CPU1_SA_DQS_DP<5>")
	)
	(segment
		(start 163.606988 -202.171808)
		(end 163.87064 -202.43546)
		(width 0.12954)
		(layer "F.Cu")
		(net "M_G_CPU1_SA_DQS_DP<5>")
	)
	(segment
		(start 158.626048 -207.022192)
		(end 158.863284 -207.022192)
		(width 0.12954)
		(layer "F.Cu")
		(net "M_G_CPU1_SA_DQS_DP<5>")
	)
	(segment
		(start 162.83559 -203.631038)
		(end 162.83559 -203.165456)
		(width 0.12954)
		(layer "F.Cu")
		(net "M_G_CPU1_SA_DQS_DP<5>")
	)
	(segment
		(start 162.410394 -202.74026)
		(end 162.410394 -202.55738)
		(width 0.12954)
		(layer "F.Cu")
		(net "M_G_CPU1_SA_DQS_DP<5>")
	)
	(segment
		(start 144.386554 -228.223064)
		(end 144.394936 -228.22789)
		(width 0.0762)
		(layer "F.Cu")
		(net "M_G_CPU1_SA_DQS_DP<5>")
	)
	(segment
		(start 161.215578 -203.620116)
		(end 161.356802 -203.478892)
		(width 0.12954)
		(layer "F.Cu")
		(net "M_G_CPU1_SA_DQS_DP<5>")
	)
	(segment
		(start 163.870894 -202.435206)
		(end 164.427916 -202.435206)
		(width 0.12954)
		(layer "F.Cu")
		(net "M_G_CPU1_SA_DQS_DP<5>")
	)
	(segment
		(start 144.960848 -228.22789)
		(end 144.96923 -228.223064)
		(width 0.0762)
		(layer "F.Cu")
		(net "M_G_CPU1_SA_DQS_DP<5>")
	)
	(segment
		(start 161.69894 -204.767688)
		(end 161.69894 -204.302106)
		(width 0.12954)
		(layer "F.Cu")
		(net "M_G_CPU1_SA_DQS_DP<5>")
	)
	(segment
		(start 161.356802 -203.478892)
		(end 161.55543 -203.478892)
		(width 0.12954)
		(layer "F.Cu")
		(net "M_G_CPU1_SA_DQS_DP<5>")
	)
	(segment
		(start 160.206182 -204.601572)
		(end 160.40481 -204.601572)
		(width 0.12954)
		(layer "F.Cu")
		(net "M_G_CPU1_SA_DQS_DP<5>")
	)
	(segment
		(start 162.795966 -202.171808)
		(end 163.606988 -202.171808)
		(width 0.12954)
		(layer "F.Cu")
		(net "M_G_CPU1_SA_DQS_DP<5>")
	)
	(segment
		(start 160.56229 -205.904338)
		(end 160.56229 -205.438756)
		(width 0.12954)
		(layer "F.Cu")
		(net "M_G_CPU1_SA_DQS_DP<5>")
	)
	(segment
		(start 162.83559 -203.165456)
		(end 162.410394 -202.74026)
		(width 0.12954)
		(layer "F.Cu")
		(net "M_G_CPU1_SA_DQS_DP<5>")
	)
	(segment
		(start 146.259296 -227.896166)
		(end 146.952208 -227.896166)
		(width 0.0762)
		(layer "F.Cu")
		(net "M_G_CPU1_SA_DQS_DP<5>")
	)
	(segment
		(start 159.41294 -206.2353)
		(end 160.231328 -206.2353)
		(width 0.12954)
		(layer "F.Cu")
		(net "M_G_CPU1_SA_DQS_DP<5>")
	)
	(segment
		(start 159.138366 -206.509874)
		(end 159.41294 -206.2353)
		(width 0.12954)
		(layer "F.Cu")
		(net "M_G_CPU1_SA_DQS_DP<5>")
	)
	(segment
		(start 144.207992 -228.55047)
		(end 144.106138 -228.37521)
		(width 0.0762)
		(layer "F.Cu")
		(net "M_G_CPU1_SA_DQS_DP<5>")
	)
	(segment
		(start 160.064958 -204.941424)
		(end 160.064958 -204.742796)
		(width 0.12954)
		(layer "F.Cu")
		(net "M_G_CPU1_SA_DQS_DP<5>")
	)
	(segment
		(start 147.44573 -227.402644)
		(end 147.538948 -227.402644)
		(width 0.0762)
		(layer "F.Cu")
		(net "M_G_CPU1_SA_DQS_DP<5>")
	)
	(segment
		(start 147.538948 -227.402644)
		(end 150.13559 -224.804732)
		(width 0.12954)
		(layer "F.Cu")
		(net "M_G_CPU1_SA_DQS_DP<5>")
	)
	(segment
		(start 160.064958 -204.742796)
		(end 160.206182 -204.601572)
		(width 0.12954)
		(layer "F.Cu")
		(net "M_G_CPU1_SA_DQS_DP<5>")
	)
	(segment
		(start 146.016472 -228.13899)
		(end 146.259296 -227.896166)
		(width 0.0762)
		(layer "F.Cu")
		(net "M_G_CPU1_SA_DQS_DP<5>")
	)
	(segment
		(start 160.56229 -205.438756)
		(end 160.064958 -204.941424)
		(width 0.12954)
		(layer "F.Cu")
		(net "M_G_CPU1_SA_DQS_DP<5>")
	)
	(segment
		(start 150.13559 -215.51265)
		(end 158.626048 -207.022192)
		(width 0.12954)
		(layer "F.Cu")
		(net "M_G_CPU1_SA_DQS_DP<5>")
	)
	(segment
		(start 150.13559 -224.804732)
		(end 150.13559 -215.51265)
		(width 0.12954)
		(layer "F.Cu")
		(net "M_G_CPU1_SA_DQS_DP<5>")
	)
	(arc
		(start 144.106138 -228.37521)
		(mid 144.123332 -228.235624)
		(end 144.252696 -228.180392)
		(width 0.0762)
		(layer "F.Cu")
		(net "M_G_CPU1_SA_DQS_DP<5>")
	)
	(arc
		(start 144.252696 -228.180392)
		(mid 144.321643 -228.195389)
		(end 144.386554 -228.223064)
		(width 0.0762)
		(layer "F.Cu")
		(net "M_G_CPU1_SA_DQS_DP<5>")
	)
	(arc
		(start 144.96923 -228.223064)
		(mid 145.152738 -228.17757)
		(end 145.33499 -228.22789)
		(width 0.0762)
		(layer "F.Cu")
		(net "M_G_CPU1_SA_DQS_DP<5>")
	)
	(arc
		(start 145.900902 -228.22789)
		(mid 145.961575 -228.187194)
		(end 146.016472 -228.13899)
		(width 0.0762)
		(layer "F.Cu")
		(net "M_G_CPU1_SA_DQS_DP<5>")
	)
	(arc
		(start 145.33499 -228.22789)
		(mid 145.617946 -228.304067)
		(end 145.900902 -228.22789)
		(width 0.0762)
		(layer "F.Cu")
		(net "M_G_CPU1_SA_DQS_DP<5>")
	)
	(arc
		(start 144.394936 -228.22789)
		(mid 144.677892 -228.304067)
		(end 144.960848 -228.22789)
		(width 0.0762)
		(layer "F.Cu")
		(net "M_G_CPU1_SA_DQS_DP<5>")
	)
	(segment
		(start 158.206186 -242.68557)
		(end 162.91687 -237.974886)
		(width 0.12954)
		(layer "F.Cu")
		(net "M_G_CPU1_SA_DQS_DP<4>")
	)
	(segment
		(start 158.206186 -244.345714)
		(end 158.206186 -242.68557)
		(width 0.12954)
		(layer "F.Cu")
		(net "M_G_CPU1_SA_DQS_DP<4>")
	)
	(segment
		(start 166.686738 -238.02721)
		(end 167.111934 -238.452406)
		(width 0.101346)
		(layer "F.Cu")
		(net "M_G_CPU1_SA_DQS_DP<4>")
	)
	(segment
		(start 147.40001 -246.549926)
		(end 147.41906 -246.549926)
		(width 0.0762)
		(layer "F.Cu")
		(net "M_G_CPU1_SA_DQS_DP<4>")
	)
	(segment
		(start 163.302188 -237.974886)
		(end 163.566602 -237.710472)
		(width 0.12954)
		(layer "F.Cu")
		(net "M_G_CPU1_SA_DQS_DP<4>")
	)
	(segment
		(start 168.012872 -238.135414)
		(end 168.527984 -238.135414)
		(width 0.101346)
		(layer "F.Cu")
		(net "M_G_CPU1_SA_DQS_DP<4>")
	)
	(segment
		(start 147.33397 -246.615966)
		(end 147.40001 -246.549926)
		(width 0.0762)
		(layer "F.Cu")
		(net "M_G_CPU1_SA_DQS_DP<4>")
	)
	(segment
		(start 165.99535 -237.710472)
		(end 166.312088 -238.02721)
		(width 0.101346)
		(layer "F.Cu")
		(net "M_G_CPU1_SA_DQS_DP<4>")
	)
	(segment
		(start 162.91687 -237.974886)
		(end 163.302188 -237.974886)
		(width 0.12954)
		(layer "F.Cu")
		(net "M_G_CPU1_SA_DQS_DP<4>")
	)
	(segment
		(start 156.001974 -246.549926)
		(end 158.206186 -244.345714)
		(width 0.12954)
		(layer "F.Cu")
		(net "M_G_CPU1_SA_DQS_DP<4>")
	)
	(segment
		(start 147.41906 -246.549926)
		(end 156.001974 -246.549926)
		(width 0.12954)
		(layer "F.Cu")
		(net "M_G_CPU1_SA_DQS_DP<4>")
	)
	(segment
		(start 167.111934 -238.452406)
		(end 167.69588 -238.452406)
		(width 0.101346)
		(layer "F.Cu")
		(net "M_G_CPU1_SA_DQS_DP<4>")
	)
	(segment
		(start 163.566602 -237.710472)
		(end 165.99535 -237.710472)
		(width 0.101346)
		(layer "F.Cu")
		(net "M_G_CPU1_SA_DQS_DP<4>")
	)
	(segment
		(start 147.11553 -246.615966)
		(end 147.33397 -246.615966)
		(width 0.0762)
		(layer "F.Cu")
		(net "M_G_CPU1_SA_DQS_DP<4>")
	)
	(segment
		(start 167.69588 -238.452406)
		(end 168.012872 -238.135414)
		(width 0.101346)
		(layer "F.Cu")
		(net "M_G_CPU1_SA_DQS_DP<4>")
	)
	(segment
		(start 146.087846 -246.743474)
		(end 146.988022 -246.743474)
		(width 0.0762)
		(layer "F.Cu")
		(net "M_G_CPU1_SA_DQS_DP<4>")
	)
	(segment
		(start 146.988022 -246.743474)
		(end 147.11553 -246.615966)
		(width 0.0762)
		(layer "F.Cu")
		(net "M_G_CPU1_SA_DQS_DP<4>")
	)
	(segment
		(start 166.312088 -238.02721)
		(end 166.686738 -238.02721)
		(width 0.101346)
		(layer "F.Cu")
		(net "M_G_CPU1_SA_DQS_DP<4>")
	)
	(arc
		(start 145.147792 -246.370348)
		(mid 145.391223 -246.539835)
		(end 145.676874 -246.619776)
		(width 0.0762)
		(layer "F.Cu")
		(net "M_G_CPU1_SA_DQS_DP<4>")
	)
	(arc
		(start 145.676874 -246.619776)
		(mid 145.696223 -246.622114)
		(end 145.715482 -246.62511)
		(width 0.0762)
		(layer "F.Cu")
		(net "M_G_CPU1_SA_DQS_DP<4>")
	)
	(arc
		(start 146.056858 -246.742204)
		(mid 146.072339 -246.74316)
		(end 146.087846 -246.743474)
		(width 0.0762)
		(layer "F.Cu")
		(net "M_G_CPU1_SA_DQS_DP<4>")
	)
	(arc
		(start 145.715482 -246.62511)
		(mid 145.811191 -246.650822)
		(end 145.900902 -246.692928)
		(width 0.0762)
		(layer "F.Cu")
		(net "M_G_CPU1_SA_DQS_DP<4>")
	)
	(arc
		(start 145.900902 -246.692928)
		(mid 145.976142 -246.726241)
		(end 146.056858 -246.742204)
		(width 0.0762)
		(layer "F.Cu")
		(net "M_G_CPU1_SA_DQS_DP<4>")
	)
	(segment
		(start 147.53971 -242.086638)
		(end 147.60575 -242.020598)
		(width 0.0762)
		(layer "F.Cu")
		(net "M_G_CPU1_SA_DQS_DP<3>")
	)
	(segment
		(start 167.081454 -229.102412)
		(end 167.69588 -229.102412)
		(width 0.101346)
		(layer "F.Cu")
		(net "M_G_CPU1_SA_DQS_DP<3>")
	)
	(segment
		(start 162.65271 -228.95306)
		(end 162.980878 -228.624892)
		(width 0.12954)
		(layer "F.Cu")
		(net "M_G_CPU1_SA_DQS_DP<3>")
	)
	(segment
		(start 163.566602 -228.360478)
		(end 165.99535 -228.360478)
		(width 0.101346)
		(layer "F.Cu")
		(net "M_G_CPU1_SA_DQS_DP<3>")
	)
	(segment
		(start 146.087846 -241.883438)
		(end 147.08251 -241.883438)
		(width 0.0762)
		(layer "F.Cu")
		(net "M_G_CPU1_SA_DQS_DP<3>")
	)
	(segment
		(start 151.439118 -242.020598)
		(end 156.266896 -237.19282)
		(width 0.12954)
		(layer "F.Cu")
		(net "M_G_CPU1_SA_DQS_DP<3>")
	)
	(segment
		(start 162.65271 -229.535482)
		(end 162.65271 -228.95306)
		(width 0.12954)
		(layer "F.Cu")
		(net "M_G_CPU1_SA_DQS_DP<3>")
	)
	(segment
		(start 159.10433 -235.420662)
		(end 159.10433 -233.083862)
		(width 0.12954)
		(layer "F.Cu")
		(net "M_G_CPU1_SA_DQS_DP<3>")
	)
	(segment
		(start 167.69588 -229.102412)
		(end 168.012872 -228.78542)
		(width 0.101346)
		(layer "F.Cu")
		(net "M_G_CPU1_SA_DQS_DP<3>")
	)
	(segment
		(start 165.99535 -228.360478)
		(end 166.312088 -228.677216)
		(width 0.101346)
		(layer "F.Cu")
		(net "M_G_CPU1_SA_DQS_DP<3>")
	)
	(segment
		(start 157.332172 -237.19282)
		(end 159.10433 -235.420662)
		(width 0.12954)
		(layer "F.Cu")
		(net "M_G_CPU1_SA_DQS_DP<3>")
	)
	(segment
		(start 163.302188 -228.624892)
		(end 163.566602 -228.360478)
		(width 0.12954)
		(layer "F.Cu")
		(net "M_G_CPU1_SA_DQS_DP<3>")
	)
	(segment
		(start 156.266896 -237.19282)
		(end 157.332172 -237.19282)
		(width 0.12954)
		(layer "F.Cu")
		(net "M_G_CPU1_SA_DQS_DP<3>")
	)
	(segment
		(start 168.012872 -228.78542)
		(end 168.527984 -228.78542)
		(width 0.101346)
		(layer "F.Cu")
		(net "M_G_CPU1_SA_DQS_DP<3>")
	)
	(segment
		(start 162.980878 -228.624892)
		(end 163.302188 -228.624892)
		(width 0.12954)
		(layer "F.Cu")
		(net "M_G_CPU1_SA_DQS_DP<3>")
	)
	(segment
		(start 147.60575 -242.020598)
		(end 147.6248 -242.020598)
		(width 0.0762)
		(layer "F.Cu")
		(net "M_G_CPU1_SA_DQS_DP<3>")
	)
	(segment
		(start 147.08251 -241.883438)
		(end 147.28571 -242.086638)
		(width 0.0762)
		(layer "F.Cu")
		(net "M_G_CPU1_SA_DQS_DP<3>")
	)
	(segment
		(start 147.28571 -242.086638)
		(end 147.53971 -242.086638)
		(width 0.0762)
		(layer "F.Cu")
		(net "M_G_CPU1_SA_DQS_DP<3>")
	)
	(segment
		(start 166.312088 -228.677216)
		(end 166.656258 -228.677216)
		(width 0.101346)
		(layer "F.Cu")
		(net "M_G_CPU1_SA_DQS_DP<3>")
	)
	(segment
		(start 159.10433 -233.083862)
		(end 162.65271 -229.535482)
		(width 0.12954)
		(layer "F.Cu")
		(net "M_G_CPU1_SA_DQS_DP<3>")
	)
	(segment
		(start 166.656258 -228.677216)
		(end 167.081454 -229.102412)
		(width 0.101346)
		(layer "F.Cu")
		(net "M_G_CPU1_SA_DQS_DP<3>")
	)
	(segment
		(start 147.6248 -242.020598)
		(end 151.439118 -242.020598)
		(width 0.12954)
		(layer "F.Cu")
		(net "M_G_CPU1_SA_DQS_DP<3>")
	)
	(arc
		(start 145.147792 -241.510312)
		(mid 145.391223 -241.679799)
		(end 145.676874 -241.75974)
		(width 0.0762)
		(layer "F.Cu")
		(net "M_G_CPU1_SA_DQS_DP<3>")
	)
	(arc
		(start 145.676874 -241.75974)
		(mid 145.696223 -241.762078)
		(end 145.715482 -241.765074)
		(width 0.0762)
		(layer "F.Cu")
		(net "M_G_CPU1_SA_DQS_DP<3>")
	)
	(arc
		(start 146.056858 -241.882168)
		(mid 146.072339 -241.883124)
		(end 146.087846 -241.883438)
		(width 0.0762)
		(layer "F.Cu")
		(net "M_G_CPU1_SA_DQS_DP<3>")
	)
	(arc
		(start 145.900902 -241.832892)
		(mid 145.976142 -241.866205)
		(end 146.056858 -241.882168)
		(width 0.0762)
		(layer "F.Cu")
		(net "M_G_CPU1_SA_DQS_DP<3>")
	)
	(arc
		(start 145.715482 -241.765074)
		(mid 145.811191 -241.790786)
		(end 145.900902 -241.832892)
		(width 0.0762)
		(layer "F.Cu")
		(net "M_G_CPU1_SA_DQS_DP<3>")
	)
	(segment
		(start 160.771078 -221.473014)
		(end 160.771078 -221.052898)
		(width 0.12954)
		(layer "F.Cu")
		(net "M_G_CPU1_SA_DQS_DP<2>")
	)
	(segment
		(start 159.425894 -222.818198)
		(end 159.634428 -222.609664)
		(width 0.12954)
		(layer "F.Cu")
		(net "M_G_CPU1_SA_DQS_DP<2>")
	)
	(segment
		(start 163.302188 -219.274898)
		(end 163.566602 -219.010484)
		(width 0.12954)
		(layer "F.Cu")
		(net "M_G_CPU1_SA_DQS_DP<2>")
	)
	(segment
		(start 165.99535 -219.010484)
		(end 166.312088 -219.327222)
		(width 0.101346)
		(layer "F.Cu")
		(net "M_G_CPU1_SA_DQS_DP<2>")
	)
	(segment
		(start 160.144968 -221.681548)
		(end 160.562544 -221.681548)
		(width 0.12954)
		(layer "F.Cu")
		(net "M_G_CPU1_SA_DQS_DP<2>")
	)
	(segment
		(start 161.279078 -220.544898)
		(end 161.699194 -220.544898)
		(width 0.12954)
		(layer "F.Cu")
		(net "M_G_CPU1_SA_DQS_DP<2>")
	)
	(segment
		(start 163.566602 -219.010484)
		(end 165.99535 -219.010484)
		(width 0.101346)
		(layer "F.Cu")
		(net "M_G_CPU1_SA_DQS_DP<2>")
	)
	(segment
		(start 158.13786 -224.106232)
		(end 158.497778 -223.746314)
		(width 0.12954)
		(layer "F.Cu")
		(net "M_G_CPU1_SA_DQS_DP<2>")
	)
	(segment
		(start 146.087846 -237.023402)
		(end 147.035266 -237.023402)
		(width 0.0762)
		(layer "F.Cu")
		(net "M_G_CPU1_SA_DQS_DP<2>")
	)
	(segment
		(start 147.413218 -237.138464)
		(end 147.479258 -237.072424)
		(width 0.0762)
		(layer "F.Cu")
		(net "M_G_CPU1_SA_DQS_DP<2>")
	)
	(segment
		(start 161.907728 -219.807028)
		(end 162.439858 -219.274898)
		(width 0.12954)
		(layer "F.Cu")
		(net "M_G_CPU1_SA_DQS_DP<2>")
	)
	(segment
		(start 158.497778 -223.746314)
		(end 158.497778 -223.252538)
		(width 0.12954)
		(layer "F.Cu")
		(net "M_G_CPU1_SA_DQS_DP<2>")
	)
	(segment
		(start 158.497778 -223.252538)
		(end 158.932118 -222.818198)
		(width 0.12954)
		(layer "F.Cu")
		(net "M_G_CPU1_SA_DQS_DP<2>")
	)
	(segment
		(start 166.312088 -219.327222)
		(end 166.68623 -219.327222)
		(width 0.101346)
		(layer "F.Cu")
		(net "M_G_CPU1_SA_DQS_DP<2>")
	)
	(segment
		(start 160.562544 -221.681548)
		(end 160.771078 -221.473014)
		(width 0.12954)
		(layer "F.Cu")
		(net "M_G_CPU1_SA_DQS_DP<2>")
	)
	(segment
		(start 158.13786 -227.836984)
		(end 158.13786 -224.106232)
		(width 0.12954)
		(layer "F.Cu")
		(net "M_G_CPU1_SA_DQS_DP<2>")
	)
	(segment
		(start 148.90242 -237.072424)
		(end 158.13786 -227.836984)
		(width 0.12954)
		(layer "F.Cu")
		(net "M_G_CPU1_SA_DQS_DP<2>")
	)
	(segment
		(start 159.634428 -222.192088)
		(end 160.144968 -221.681548)
		(width 0.12954)
		(layer "F.Cu")
		(net "M_G_CPU1_SA_DQS_DP<2>")
	)
	(segment
		(start 158.932118 -222.818198)
		(end 159.425894 -222.818198)
		(width 0.12954)
		(layer "F.Cu")
		(net "M_G_CPU1_SA_DQS_DP<2>")
	)
	(segment
		(start 159.634428 -222.609664)
		(end 159.634428 -222.192088)
		(width 0.12954)
		(layer "F.Cu")
		(net "M_G_CPU1_SA_DQS_DP<2>")
	)
	(segment
		(start 166.68623 -219.327222)
		(end 167.111426 -219.752418)
		(width 0.101346)
		(layer "F.Cu")
		(net "M_G_CPU1_SA_DQS_DP<2>")
	)
	(segment
		(start 147.150328 -237.138464)
		(end 147.413218 -237.138464)
		(width 0.0762)
		(layer "F.Cu")
		(net "M_G_CPU1_SA_DQS_DP<2>")
	)
	(segment
		(start 147.479258 -237.072424)
		(end 147.498308 -237.072424)
		(width 0.0762)
		(layer "F.Cu")
		(net "M_G_CPU1_SA_DQS_DP<2>")
	)
	(segment
		(start 147.035266 -237.023402)
		(end 147.150328 -237.138464)
		(width 0.0762)
		(layer "F.Cu")
		(net "M_G_CPU1_SA_DQS_DP<2>")
	)
	(segment
		(start 160.771078 -221.052898)
		(end 161.279078 -220.544898)
		(width 0.12954)
		(layer "F.Cu")
		(net "M_G_CPU1_SA_DQS_DP<2>")
	)
	(segment
		(start 168.012872 -219.435426)
		(end 168.527984 -219.435426)
		(width 0.101346)
		(layer "F.Cu")
		(net "M_G_CPU1_SA_DQS_DP<2>")
	)
	(segment
		(start 161.699194 -220.544898)
		(end 161.907728 -220.336364)
		(width 0.12954)
		(layer "F.Cu")
		(net "M_G_CPU1_SA_DQS_DP<2>")
	)
	(segment
		(start 161.907728 -220.336364)
		(end 161.907728 -219.807028)
		(width 0.12954)
		(layer "F.Cu")
		(net "M_G_CPU1_SA_DQS_DP<2>")
	)
	(segment
		(start 147.498308 -237.072424)
		(end 148.90242 -237.072424)
		(width 0.12954)
		(layer "F.Cu")
		(net "M_G_CPU1_SA_DQS_DP<2>")
	)
	(segment
		(start 167.111426 -219.752418)
		(end 167.69588 -219.752418)
		(width 0.101346)
		(layer "F.Cu")
		(net "M_G_CPU1_SA_DQS_DP<2>")
	)
	(segment
		(start 162.439858 -219.274898)
		(end 163.302188 -219.274898)
		(width 0.12954)
		(layer "F.Cu")
		(net "M_G_CPU1_SA_DQS_DP<2>")
	)
	(segment
		(start 167.69588 -219.752418)
		(end 168.012872 -219.435426)
		(width 0.101346)
		(layer "F.Cu")
		(net "M_G_CPU1_SA_DQS_DP<2>")
	)
	(arc
		(start 145.900902 -236.972856)
		(mid 145.976142 -237.006169)
		(end 146.056858 -237.022132)
		(width 0.0762)
		(layer "F.Cu")
		(net "M_G_CPU1_SA_DQS_DP<2>")
	)
	(arc
		(start 146.056858 -237.022132)
		(mid 146.072339 -237.023088)
		(end 146.087846 -237.023402)
		(width 0.0762)
		(layer "F.Cu")
		(net "M_G_CPU1_SA_DQS_DP<2>")
	)
	(arc
		(start 145.676874 -236.899704)
		(mid 145.696223 -236.902042)
		(end 145.715482 -236.905038)
		(width 0.0762)
		(layer "F.Cu")
		(net "M_G_CPU1_SA_DQS_DP<2>")
	)
	(arc
		(start 145.715482 -236.905038)
		(mid 145.811191 -236.93075)
		(end 145.900902 -236.972856)
		(width 0.0762)
		(layer "F.Cu")
		(net "M_G_CPU1_SA_DQS_DP<2>")
	)
	(arc
		(start 145.147792 -236.650276)
		(mid 145.391223 -236.819763)
		(end 145.676874 -236.899704)
		(width 0.0762)
		(layer "F.Cu")
		(net "M_G_CPU1_SA_DQS_DP<2>")
	)
	(segment
		(start 167.121586 -210.402424)
		(end 167.69588 -210.402424)
		(width 0.101346)
		(layer "F.Cu")
		(net "M_G_CPU1_SA_DQS_DP<1>")
	)
	(segment
		(start 156.335222 -216.293954)
		(end 156.926534 -216.293954)
		(width 0.12954)
		(layer "F.Cu")
		(net "M_G_CPU1_SA_DQS_DP<1>")
	)
	(segment
		(start 146.93265 -232.163366)
		(end 147.19935 -231.896666)
		(width 0.0762)
		(layer "F.Cu")
		(net "M_G_CPU1_SA_DQS_DP<1>")
	)
	(segment
		(start 157.471872 -215.157304)
		(end 158.063184 -215.157304)
		(width 0.12954)
		(layer "F.Cu")
		(net "M_G_CPU1_SA_DQS_DP<1>")
	)
	(segment
		(start 147.64385 -231.896666)
		(end 147.70989 -231.830626)
		(width 0.0762)
		(layer "F.Cu")
		(net "M_G_CPU1_SA_DQS_DP<1>")
	)
	(segment
		(start 146.087846 -232.163366)
		(end 146.93265 -232.163366)
		(width 0.0762)
		(layer "F.Cu")
		(net "M_G_CPU1_SA_DQS_DP<1>")
	)
	(segment
		(start 166.312088 -209.977228)
		(end 166.69639 -209.977228)
		(width 0.101346)
		(layer "F.Cu")
		(net "M_G_CPU1_SA_DQS_DP<1>")
	)
	(segment
		(start 167.69588 -210.402424)
		(end 168.012872 -210.085432)
		(width 0.101346)
		(layer "F.Cu")
		(net "M_G_CPU1_SA_DQS_DP<1>")
	)
	(segment
		(start 161.623248 -209.955384)
		(end 163.271708 -209.955384)
		(width 0.12954)
		(layer "F.Cu")
		(net "M_G_CPU1_SA_DQS_DP<1>")
	)
	(segment
		(start 153.69413 -219.526358)
		(end 154.83078 -218.389708)
		(width 0.12954)
		(layer "F.Cu")
		(net "M_G_CPU1_SA_DQS_DP<1>")
	)
	(segment
		(start 147.88769 -231.830626)
		(end 153.69413 -226.024186)
		(width 0.12954)
		(layer "F.Cu")
		(net "M_G_CPU1_SA_DQS_DP<1>")
	)
	(segment
		(start 166.69639 -209.977228)
		(end 167.121586 -210.402424)
		(width 0.101346)
		(layer "F.Cu")
		(net "M_G_CPU1_SA_DQS_DP<1>")
	)
	(segment
		(start 153.69413 -226.024186)
		(end 153.69413 -219.526358)
		(width 0.12954)
		(layer "F.Cu")
		(net "M_G_CPU1_SA_DQS_DP<1>")
	)
	(segment
		(start 165.99535 -209.66049)
		(end 166.312088 -209.977228)
		(width 0.101346)
		(layer "F.Cu")
		(net "M_G_CPU1_SA_DQS_DP<1>")
	)
	(segment
		(start 156.926534 -216.293954)
		(end 157.10408 -216.116408)
		(width 0.12954)
		(layer "F.Cu")
		(net "M_G_CPU1_SA_DQS_DP<1>")
	)
	(segment
		(start 157.10408 -216.116408)
		(end 157.10408 -215.525096)
		(width 0.12954)
		(layer "F.Cu")
		(net "M_G_CPU1_SA_DQS_DP<1>")
	)
	(segment
		(start 157.10408 -215.525096)
		(end 157.471872 -215.157304)
		(width 0.12954)
		(layer "F.Cu")
		(net "M_G_CPU1_SA_DQS_DP<1>")
	)
	(segment
		(start 168.012872 -210.085432)
		(end 168.527984 -210.085432)
		(width 0.101346)
		(layer "F.Cu")
		(net "M_G_CPU1_SA_DQS_DP<1>")
	)
	(segment
		(start 163.271708 -209.955384)
		(end 163.566602 -209.66049)
		(width 0.12954)
		(layer "F.Cu")
		(net "M_G_CPU1_SA_DQS_DP<1>")
	)
	(segment
		(start 158.297626 -213.281006)
		(end 161.623248 -209.955384)
		(width 0.12954)
		(layer "F.Cu")
		(net "M_G_CPU1_SA_DQS_DP<1>")
	)
	(segment
		(start 163.566602 -209.66049)
		(end 165.99535 -209.66049)
		(width 0.101346)
		(layer "F.Cu")
		(net "M_G_CPU1_SA_DQS_DP<1>")
	)
	(segment
		(start 155.198572 -217.430604)
		(end 155.789884 -217.430604)
		(width 0.12954)
		(layer "F.Cu")
		(net "M_G_CPU1_SA_DQS_DP<1>")
	)
	(segment
		(start 147.72894 -231.830626)
		(end 147.88769 -231.830626)
		(width 0.12954)
		(layer "F.Cu")
		(net "M_G_CPU1_SA_DQS_DP<1>")
	)
	(segment
		(start 147.70989 -231.830626)
		(end 147.72894 -231.830626)
		(width 0.0762)
		(layer "F.Cu")
		(net "M_G_CPU1_SA_DQS_DP<1>")
	)
	(segment
		(start 158.063184 -215.157304)
		(end 158.297626 -214.922862)
		(width 0.12954)
		(layer "F.Cu")
		(net "M_G_CPU1_SA_DQS_DP<1>")
	)
	(segment
		(start 154.83078 -217.798396)
		(end 155.198572 -217.430604)
		(width 0.12954)
		(layer "F.Cu")
		(net "M_G_CPU1_SA_DQS_DP<1>")
	)
	(segment
		(start 155.96743 -216.661746)
		(end 156.335222 -216.293954)
		(width 0.12954)
		(layer "F.Cu")
		(net "M_G_CPU1_SA_DQS_DP<1>")
	)
	(segment
		(start 155.789884 -217.430604)
		(end 155.96743 -217.253058)
		(width 0.12954)
		(layer "F.Cu")
		(net "M_G_CPU1_SA_DQS_DP<1>")
	)
	(segment
		(start 158.297626 -214.922862)
		(end 158.297626 -213.281006)
		(width 0.12954)
		(layer "F.Cu")
		(net "M_G_CPU1_SA_DQS_DP<1>")
	)
	(segment
		(start 154.83078 -218.389708)
		(end 154.83078 -217.798396)
		(width 0.12954)
		(layer "F.Cu")
		(net "M_G_CPU1_SA_DQS_DP<1>")
	)
	(segment
		(start 155.96743 -217.253058)
		(end 155.96743 -216.661746)
		(width 0.12954)
		(layer "F.Cu")
		(net "M_G_CPU1_SA_DQS_DP<1>")
	)
	(segment
		(start 147.19935 -231.896666)
		(end 147.64385 -231.896666)
		(width 0.0762)
		(layer "F.Cu")
		(net "M_G_CPU1_SA_DQS_DP<1>")
	)
	(arc
		(start 145.900902 -232.11282)
		(mid 145.976142 -232.146133)
		(end 146.056858 -232.162096)
		(width 0.0762)
		(layer "F.Cu")
		(net "M_G_CPU1_SA_DQS_DP<1>")
	)
	(arc
		(start 146.056858 -232.162096)
		(mid 146.072339 -232.163052)
		(end 146.087846 -232.163366)
		(width 0.0762)
		(layer "F.Cu")
		(net "M_G_CPU1_SA_DQS_DP<1>")
	)
	(arc
		(start 145.147792 -231.79024)
		(mid 145.391223 -231.959727)
		(end 145.676874 -232.039668)
		(width 0.0762)
		(layer "F.Cu")
		(net "M_G_CPU1_SA_DQS_DP<1>")
	)
	(arc
		(start 145.676874 -232.039668)
		(mid 145.696223 -232.042006)
		(end 145.715482 -232.045002)
		(width 0.0762)
		(layer "F.Cu")
		(net "M_G_CPU1_SA_DQS_DP<1>")
	)
	(arc
		(start 145.715482 -232.045002)
		(mid 145.811191 -232.070714)
		(end 145.900902 -232.11282)
		(width 0.0762)
		(layer "F.Cu")
		(net "M_G_CPU1_SA_DQS_DP<1>")
	)
	(segment
		(start 165.99535 -200.310496)
		(end 166.312088 -200.627234)
		(width 0.101346)
		(layer "F.Cu")
		(net "M_G_CPU1_SA_DQS_DP<0>")
	)
	(segment
		(start 147.440904 -225.990658)
		(end 147.44065 -225.897186)
		(width 0.0762)
		(layer "F.Cu")
		(net "M_G_CPU1_SA_DQS_DP<0>")
	)
	(segment
		(start 147.44065 -225.897186)
		(end 147.454112 -225.883724)
		(width 0.0762)
		(layer "F.Cu")
		(net "M_G_CPU1_SA_DQS_DP<0>")
	)
	(segment
		(start 167.096186 -201.05243)
		(end 167.69588 -201.05243)
		(width 0.101346)
		(layer "F.Cu")
		(net "M_G_CPU1_SA_DQS_DP<0>")
	)
	(segment
		(start 166.67099 -200.627234)
		(end 167.096186 -201.05243)
		(width 0.101346)
		(layer "F.Cu")
		(net "M_G_CPU1_SA_DQS_DP<0>")
	)
	(segment
		(start 146.522948 -227.199444)
		(end 146.96059 -226.761802)
		(width 0.0762)
		(layer "F.Cu")
		(net "M_G_CPU1_SA_DQS_DP<0>")
	)
	(segment
		(start 168.012872 -200.735438)
		(end 168.527984 -200.735438)
		(width 0.101346)
		(layer "F.Cu")
		(net "M_G_CPU1_SA_DQS_DP<0>")
	)
	(segment
		(start 157.31617 -205.808326)
		(end 162.549586 -200.57491)
		(width 0.12954)
		(layer "F.Cu")
		(net "M_G_CPU1_SA_DQS_DP<0>")
	)
	(segment
		(start 163.566602 -200.310496)
		(end 165.99535 -200.310496)
		(width 0.101346)
		(layer "F.Cu")
		(net "M_G_CPU1_SA_DQS_DP<0>")
	)
	(segment
		(start 147.454112 -225.883724)
		(end 149.05355 -224.284286)
		(width 0.12954)
		(layer "F.Cu")
		(net "M_G_CPU1_SA_DQS_DP<0>")
	)
	(segment
		(start 146.271742 -227.303584)
		(end 146.522948 -227.199444)
		(width 0.0762)
		(layer "F.Cu")
		(net "M_G_CPU1_SA_DQS_DP<0>")
	)
	(segment
		(start 162.549586 -200.57491)
		(end 163.302188 -200.57491)
		(width 0.12954)
		(layer "F.Cu")
		(net "M_G_CPU1_SA_DQS_DP<0>")
	)
	(segment
		(start 146.087846 -227.303584)
		(end 146.271742 -227.303584)
		(width 0.0762)
		(layer "F.Cu")
		(net "M_G_CPU1_SA_DQS_DP<0>")
	)
	(segment
		(start 157.31617 -206.822802)
		(end 157.31617 -205.808326)
		(width 0.12954)
		(layer "F.Cu")
		(net "M_G_CPU1_SA_DQS_DP<0>")
	)
	(segment
		(start 146.96059 -226.470972)
		(end 147.440904 -225.990658)
		(width 0.0762)
		(layer "F.Cu")
		(net "M_G_CPU1_SA_DQS_DP<0>")
	)
	(segment
		(start 163.302188 -200.57491)
		(end 163.566602 -200.310496)
		(width 0.12954)
		(layer "F.Cu")
		(net "M_G_CPU1_SA_DQS_DP<0>")
	)
	(segment
		(start 166.312088 -200.627234)
		(end 166.67099 -200.627234)
		(width 0.101346)
		(layer "F.Cu")
		(net "M_G_CPU1_SA_DQS_DP<0>")
	)
	(segment
		(start 149.05355 -215.085422)
		(end 157.31617 -206.822802)
		(width 0.12954)
		(layer "F.Cu")
		(net "M_G_CPU1_SA_DQS_DP<0>")
	)
	(segment
		(start 146.96059 -226.761802)
		(end 146.96059 -226.470972)
		(width 0.0762)
		(layer "F.Cu")
		(net "M_G_CPU1_SA_DQS_DP<0>")
	)
	(segment
		(start 149.05355 -224.284286)
		(end 149.05355 -215.085422)
		(width 0.12954)
		(layer "F.Cu")
		(net "M_G_CPU1_SA_DQS_DP<0>")
	)
	(segment
		(start 167.69588 -201.05243)
		(end 168.012872 -200.735438)
		(width 0.101346)
		(layer "F.Cu")
		(net "M_G_CPU1_SA_DQS_DP<0>")
	)
	(arc
		(start 145.715482 -227.18522)
		(mid 145.811191 -227.210932)
		(end 145.900902 -227.253038)
		(width 0.0762)
		(layer "F.Cu")
		(net "M_G_CPU1_SA_DQS_DP<0>")
	)
	(arc
		(start 145.676874 -227.179886)
		(mid 145.696223 -227.182224)
		(end 145.715482 -227.18522)
		(width 0.0762)
		(layer "F.Cu")
		(net "M_G_CPU1_SA_DQS_DP<0>")
	)
	(arc
		(start 146.056858 -227.302314)
		(mid 146.072339 -227.30327)
		(end 146.087846 -227.303584)
		(width 0.0762)
		(layer "F.Cu")
		(net "M_G_CPU1_SA_DQS_DP<0>")
	)
	(arc
		(start 145.147792 -226.930458)
		(mid 145.391223 -227.099945)
		(end 145.676874 -227.179886)
		(width 0.0762)
		(layer "F.Cu")
		(net "M_G_CPU1_SA_DQS_DP<0>")
	)
	(arc
		(start 145.900902 -227.253038)
		(mid 145.976142 -227.286351)
		(end 146.056858 -227.302314)
		(width 0.0762)
		(layer "F.Cu")
		(net "M_G_CPU1_SA_DQS_DP<0>")
	)
	(segment
		(start 161.49574 -241.676936)
		(end 161.49574 -241.4778)
		(width 0.12954)
		(layer "F.Cu")
		(net "M_G_CPU1_SA_DQS_DN<9>")
	)
	(segment
		(start 147.396708 -247.320054)
		(end 147.415758 -247.320054)
		(width 0.0762)
		(layer "F.Cu")
		(net "M_G_CPU1_SA_DQS_DN<9>")
	)
	(segment
		(start 160.087056 -241.87658)
		(end 160.418018 -241.545618)
		(width 0.12954)
		(layer "F.Cu")
		(net "M_G_CPU1_SA_DQS_DN<9>")
	)
	(segment
		(start 162.292538 -240.681002)
		(end 162.491674 -240.681002)
		(width 0.12954)
		(layer "F.Cu")
		(net "M_G_CPU1_SA_DQS_DN<9>")
	)
	(segment
		(start 145.796508 -247.50776)
		(end 145.80489 -247.502934)
		(width 0.0762)
		(layer "F.Cu")
		(net "M_G_CPU1_SA_DQS_DN<9>")
	)
	(segment
		(start 159.22244 -243.7511)
		(end 158.950406 -243.479066)
		(width 0.12954)
		(layer "F.Cu")
		(net "M_G_CPU1_SA_DQS_DN<9>")
	)
	(segment
		(start 162.68573 -239.643666)
		(end 163.080192 -239.249204)
		(width 0.12954)
		(layer "F.Cu")
		(net "M_G_CPU1_SA_DQS_DN<9>")
	)
	(segment
		(start 160.087056 -242.342416)
		(end 160.087056 -241.87658)
		(width 0.12954)
		(layer "F.Cu")
		(net "M_G_CPU1_SA_DQS_DN<9>")
	)
	(segment
		(start 161.554668 -240.408968)
		(end 162.020504 -240.408968)
		(width 0.12954)
		(layer "F.Cu")
		(net "M_G_CPU1_SA_DQS_DN<9>")
	)
	(segment
		(start 163.080192 -239.249204)
		(end 163.605972 -239.249204)
		(width 0.12954)
		(layer "F.Cu")
		(net "M_G_CPU1_SA_DQS_DN<9>")
	)
	(segment
		(start 160.418018 -241.545618)
		(end 160.883854 -241.545618)
		(width 0.12954)
		(layer "F.Cu")
		(net "M_G_CPU1_SA_DQS_DN<9>")
	)
	(segment
		(start 160.019238 -242.954302)
		(end 160.218374 -242.954302)
		(width 0.12954)
		(layer "F.Cu")
		(net "M_G_CPU1_SA_DQS_DN<9>")
	)
	(segment
		(start 163.605972 -239.249204)
		(end 163.869878 -238.985298)
		(width 0.12954)
		(layer "F.Cu")
		(net "M_G_CPU1_SA_DQS_DN<9>")
	)
	(segment
		(start 160.35909 -242.813586)
		(end 160.35909 -242.61445)
		(width 0.12954)
		(layer "F.Cu")
		(net "M_G_CPU1_SA_DQS_DN<9>")
	)
	(segment
		(start 156.28493 -247.320054)
		(end 159.22244 -244.382544)
		(width 0.12954)
		(layer "F.Cu")
		(net "M_G_CPU1_SA_DQS_DN<9>")
	)
	(segment
		(start 159.281368 -242.682268)
		(end 159.747204 -242.682268)
		(width 0.12954)
		(layer "F.Cu")
		(net "M_G_CPU1_SA_DQS_DN<9>")
	)
	(segment
		(start 161.355024 -241.817652)
		(end 161.49574 -241.676936)
		(width 0.12954)
		(layer "F.Cu")
		(net "M_G_CPU1_SA_DQS_DN<9>")
	)
	(segment
		(start 146.54911 -247.426734)
		(end 146.58975 -247.386094)
		(width 0.0762)
		(layer "F.Cu")
		(net "M_G_CPU1_SA_DQS_DN<9>")
	)
	(segment
		(start 158.950406 -243.01323)
		(end 159.281368 -242.682268)
		(width 0.12954)
		(layer "F.Cu")
		(net "M_G_CPU1_SA_DQS_DN<9>")
	)
	(segment
		(start 147.415758 -247.320054)
		(end 156.28493 -247.320054)
		(width 0.12954)
		(layer "F.Cu")
		(net "M_G_CPU1_SA_DQS_DN<9>")
	)
	(segment
		(start 159.747204 -242.682268)
		(end 160.019238 -242.954302)
		(width 0.12954)
		(layer "F.Cu")
		(net "M_G_CPU1_SA_DQS_DN<9>")
	)
	(segment
		(start 162.68573 -240.486946)
		(end 162.68573 -239.643666)
		(width 0.12954)
		(layer "F.Cu")
		(net "M_G_CPU1_SA_DQS_DN<9>")
	)
	(segment
		(start 162.020504 -240.408968)
		(end 162.292538 -240.681002)
		(width 0.12954)
		(layer "F.Cu")
		(net "M_G_CPU1_SA_DQS_DN<9>")
	)
	(segment
		(start 147.330668 -247.386094)
		(end 147.396708 -247.320054)
		(width 0.0762)
		(layer "F.Cu")
		(net "M_G_CPU1_SA_DQS_DN<9>")
	)
	(segment
		(start 158.950406 -243.479066)
		(end 158.950406 -243.01323)
		(width 0.12954)
		(layer "F.Cu")
		(net "M_G_CPU1_SA_DQS_DN<9>")
	)
	(segment
		(start 146.087846 -247.426734)
		(end 146.54911 -247.426734)
		(width 0.0762)
		(layer "F.Cu")
		(net "M_G_CPU1_SA_DQS_DN<9>")
	)
	(segment
		(start 159.22244 -244.382544)
		(end 159.22244 -243.7511)
		(width 0.12954)
		(layer "F.Cu")
		(net "M_G_CPU1_SA_DQS_DN<9>")
	)
	(segment
		(start 161.155888 -241.817652)
		(end 161.355024 -241.817652)
		(width 0.12954)
		(layer "F.Cu")
		(net "M_G_CPU1_SA_DQS_DN<9>")
	)
	(segment
		(start 160.883854 -241.545618)
		(end 161.155888 -241.817652)
		(width 0.12954)
		(layer "F.Cu")
		(net "M_G_CPU1_SA_DQS_DN<9>")
	)
	(segment
		(start 161.223706 -240.73993)
		(end 161.554668 -240.408968)
		(width 0.12954)
		(layer "F.Cu")
		(net "M_G_CPU1_SA_DQS_DN<9>")
	)
	(segment
		(start 160.35909 -242.61445)
		(end 160.087056 -242.342416)
		(width 0.12954)
		(layer "F.Cu")
		(net "M_G_CPU1_SA_DQS_DN<9>")
	)
	(segment
		(start 163.869878 -238.985298)
		(end 164.427916 -238.985298)
		(width 0.12954)
		(layer "F.Cu")
		(net "M_G_CPU1_SA_DQS_DN<9>")
	)
	(segment
		(start 162.491674 -240.681002)
		(end 162.68573 -240.486946)
		(width 0.12954)
		(layer "F.Cu")
		(net "M_G_CPU1_SA_DQS_DN<9>")
	)
	(segment
		(start 160.218374 -242.954302)
		(end 160.35909 -242.813586)
		(width 0.12954)
		(layer "F.Cu")
		(net "M_G_CPU1_SA_DQS_DN<9>")
	)
	(segment
		(start 161.223706 -241.205766)
		(end 161.223706 -240.73993)
		(width 0.12954)
		(layer "F.Cu")
		(net "M_G_CPU1_SA_DQS_DN<9>")
	)
	(segment
		(start 161.49574 -241.4778)
		(end 161.223706 -241.205766)
		(width 0.12954)
		(layer "F.Cu")
		(net "M_G_CPU1_SA_DQS_DN<9>")
	)
	(segment
		(start 146.58975 -247.386094)
		(end 147.330668 -247.386094)
		(width 0.0762)
		(layer "F.Cu")
		(net "M_G_CPU1_SA_DQS_DN<9>")
	)
	(arc
		(start 144.27581 -247.430544)
		(mid 144.387056 -247.455807)
		(end 144.490948 -247.502934)
		(width 0.0762)
		(layer "F.Cu")
		(net "M_G_CPU1_SA_DQS_DN<9>")
	)
	(arc
		(start 145.430748 -247.502934)
		(mid 145.612999 -247.553284)
		(end 145.796508 -247.50776)
		(width 0.0762)
		(layer "F.Cu")
		(net "M_G_CPU1_SA_DQS_DN<9>")
	)
	(arc
		(start 144.864836 -247.502934)
		(mid 145.147792 -247.426757)
		(end 145.430748 -247.502934)
		(width 0.0762)
		(layer "F.Cu")
		(net "M_G_CPU1_SA_DQS_DN<9>")
	)
	(arc
		(start 144.252188 -247.428258)
		(mid 144.264011 -247.429275)
		(end 144.27581 -247.430544)
		(width 0.0762)
		(layer "F.Cu")
		(net "M_G_CPU1_SA_DQS_DN<9>")
	)
	(arc
		(start 144.490948 -247.502934)
		(mid 144.677892 -247.553189)
		(end 144.864836 -247.502934)
		(width 0.0762)
		(layer "F.Cu")
		(net "M_G_CPU1_SA_DQS_DN<9>")
	)
	(arc
		(start 143.737838 -247.180354)
		(mid 143.971836 -247.352397)
		(end 144.252188 -247.428258)
		(width 0.0762)
		(layer "F.Cu")
		(net "M_G_CPU1_SA_DQS_DN<9>")
	)
	(arc
		(start 145.80489 -247.502934)
		(mid 145.941326 -247.446109)
		(end 146.087846 -247.426734)
		(width 0.0762)
		(layer "F.Cu")
		(net "M_G_CPU1_SA_DQS_DN<9>")
	)
	(segment
		(start 161.37382 -233.735626)
		(end 161.57194 -233.735626)
		(width 0.12954)
		(layer "F.Cu")
		(net "M_G_CPU1_SA_DQS_DN<8>")
	)
	(segment
		(start 145.796508 -242.647724)
		(end 145.80489 -242.642898)
		(width 0.0762)
		(layer "F.Cu")
		(net "M_G_CPU1_SA_DQS_DN<8>")
	)
	(segment
		(start 146.087846 -242.566698)
		(end 146.964908 -242.566698)
		(width 0.0762)
		(layer "F.Cu")
		(net "M_G_CPU1_SA_DQS_DN<8>")
	)
	(segment
		(start 159.888174 -233.375708)
		(end 160.217612 -233.04627)
		(width 0.12954)
		(layer "F.Cu")
		(net "M_G_CPU1_SA_DQS_DN<8>")
	)
	(segment
		(start 147.656042 -242.856004)
		(end 147.675092 -242.856004)
		(width 0.0762)
		(layer "F.Cu")
		(net "M_G_CPU1_SA_DQS_DN<8>")
	)
	(segment
		(start 163.869878 -229.635304)
		(end 164.427916 -229.635304)
		(width 0.12954)
		(layer "F.Cu")
		(net "M_G_CPU1_SA_DQS_DN<8>")
	)
	(segment
		(start 161.71418 -233.395266)
		(end 161.024824 -232.70591)
		(width 0.12954)
		(layer "F.Cu")
		(net "M_G_CPU1_SA_DQS_DN<8>")
	)
	(segment
		(start 161.024824 -232.70591)
		(end 161.024824 -232.239058)
		(width 0.12954)
		(layer "F.Cu")
		(net "M_G_CPU1_SA_DQS_DN<8>")
	)
	(segment
		(start 159.888174 -233.84256)
		(end 159.888174 -233.375708)
		(width 0.12954)
		(layer "F.Cu")
		(net "M_G_CPU1_SA_DQS_DN<8>")
	)
	(segment
		(start 160.734756 -234.689142)
		(end 159.888174 -233.84256)
		(width 0.12954)
		(layer "F.Cu")
		(net "M_G_CPU1_SA_DQS_DN<8>")
	)
	(segment
		(start 163.364672 -229.89921)
		(end 163.605972 -229.89921)
		(width 0.12954)
		(layer "F.Cu")
		(net "M_G_CPU1_SA_DQS_DN<8>")
	)
	(segment
		(start 161.71418 -233.593386)
		(end 161.71418 -233.395266)
		(width 0.12954)
		(layer "F.Cu")
		(net "M_G_CPU1_SA_DQS_DN<8>")
	)
	(segment
		(start 157.684978 -237.93704)
		(end 160.734756 -234.887262)
		(width 0.12954)
		(layer "F.Cu")
		(net "M_G_CPU1_SA_DQS_DN<8>")
	)
	(segment
		(start 161.024824 -232.239058)
		(end 163.364672 -229.89921)
		(width 0.12954)
		(layer "F.Cu")
		(net "M_G_CPU1_SA_DQS_DN<8>")
	)
	(segment
		(start 147.590002 -242.922044)
		(end 147.656042 -242.856004)
		(width 0.0762)
		(layer "F.Cu")
		(net "M_G_CPU1_SA_DQS_DN<8>")
	)
	(segment
		(start 147.320254 -242.922044)
		(end 147.590002 -242.922044)
		(width 0.0762)
		(layer "F.Cu")
		(net "M_G_CPU1_SA_DQS_DN<8>")
	)
	(segment
		(start 151.656542 -242.856004)
		(end 156.575506 -237.93704)
		(width 0.12954)
		(layer "F.Cu")
		(net "M_G_CPU1_SA_DQS_DN<8>")
	)
	(segment
		(start 160.217612 -233.04627)
		(end 160.684464 -233.04627)
		(width 0.12954)
		(layer "F.Cu")
		(net "M_G_CPU1_SA_DQS_DN<8>")
	)
	(segment
		(start 146.964908 -242.566698)
		(end 147.320254 -242.922044)
		(width 0.0762)
		(layer "F.Cu")
		(net "M_G_CPU1_SA_DQS_DN<8>")
	)
	(segment
		(start 147.675092 -242.856004)
		(end 151.656542 -242.856004)
		(width 0.12954)
		(layer "F.Cu")
		(net "M_G_CPU1_SA_DQS_DN<8>")
	)
	(segment
		(start 160.734756 -234.887262)
		(end 160.734756 -234.689142)
		(width 0.12954)
		(layer "F.Cu")
		(net "M_G_CPU1_SA_DQS_DN<8>")
	)
	(segment
		(start 160.684464 -233.04627)
		(end 161.37382 -233.735626)
		(width 0.12954)
		(layer "F.Cu")
		(net "M_G_CPU1_SA_DQS_DN<8>")
	)
	(segment
		(start 161.57194 -233.735626)
		(end 161.71418 -233.593386)
		(width 0.12954)
		(layer "F.Cu")
		(net "M_G_CPU1_SA_DQS_DN<8>")
	)
	(segment
		(start 156.575506 -237.93704)
		(end 157.684978 -237.93704)
		(width 0.12954)
		(layer "F.Cu")
		(net "M_G_CPU1_SA_DQS_DN<8>")
	)
	(segment
		(start 163.605972 -229.89921)
		(end 163.869878 -229.635304)
		(width 0.12954)
		(layer "F.Cu")
		(net "M_G_CPU1_SA_DQS_DN<8>")
	)
	(arc
		(start 144.252188 -242.568222)
		(mid 144.264011 -242.569239)
		(end 144.27581 -242.570508)
		(width 0.0762)
		(layer "F.Cu")
		(net "M_G_CPU1_SA_DQS_DN<8>")
	)
	(arc
		(start 144.490948 -242.642898)
		(mid 144.677892 -242.693153)
		(end 144.864836 -242.642898)
		(width 0.0762)
		(layer "F.Cu")
		(net "M_G_CPU1_SA_DQS_DN<8>")
	)
	(arc
		(start 144.27581 -242.570508)
		(mid 144.387056 -242.595771)
		(end 144.490948 -242.642898)
		(width 0.0762)
		(layer "F.Cu")
		(net "M_G_CPU1_SA_DQS_DN<8>")
	)
	(arc
		(start 144.864836 -242.642898)
		(mid 145.147792 -242.566721)
		(end 145.430748 -242.642898)
		(width 0.0762)
		(layer "F.Cu")
		(net "M_G_CPU1_SA_DQS_DN<8>")
	)
	(arc
		(start 145.430748 -242.642898)
		(mid 145.612999 -242.693248)
		(end 145.796508 -242.647724)
		(width 0.0762)
		(layer "F.Cu")
		(net "M_G_CPU1_SA_DQS_DN<8>")
	)
	(arc
		(start 145.80489 -242.642898)
		(mid 145.941326 -242.586073)
		(end 146.087846 -242.566698)
		(width 0.0762)
		(layer "F.Cu")
		(net "M_G_CPU1_SA_DQS_DN<8>")
	)
	(arc
		(start 143.737838 -242.320318)
		(mid 143.971836 -242.492361)
		(end 144.252188 -242.568222)
		(width 0.0762)
		(layer "F.Cu")
		(net "M_G_CPU1_SA_DQS_DN<8>")
	)
	(segment
		(start 149.200108 -237.831884)
		(end 158.88208 -228.149912)
		(width 0.12954)
		(layer "F.Cu")
		(net "M_G_CPU1_SA_DQS_DN<7>")
	)
	(segment
		(start 162.636708 -222.066104)
		(end 162.636708 -221.867984)
		(width 0.12954)
		(layer "F.Cu")
		(net "M_G_CPU1_SA_DQS_DN<7>")
	)
	(segment
		(start 160.033716 -223.811592)
		(end 160.033716 -223.34474)
		(width 0.12954)
		(layer "F.Cu")
		(net "M_G_CPU1_SA_DQS_DN<7>")
	)
	(segment
		(start 162.296348 -222.208344)
		(end 162.494468 -222.208344)
		(width 0.12954)
		(layer "F.Cu")
		(net "M_G_CPU1_SA_DQS_DN<7>")
	)
	(segment
		(start 146.973544 -237.706662)
		(end 147.164806 -237.897924)
		(width 0.0762)
		(layer "F.Cu")
		(net "M_G_CPU1_SA_DQS_DN<7>")
	)
	(segment
		(start 163.869878 -220.28531)
		(end 164.427916 -220.28531)
		(width 0.12954)
		(layer "F.Cu")
		(net "M_G_CPU1_SA_DQS_DN<7>")
	)
	(segment
		(start 163.605972 -220.549216)
		(end 163.869878 -220.28531)
		(width 0.12954)
		(layer "F.Cu")
		(net "M_G_CPU1_SA_DQS_DN<7>")
	)
	(segment
		(start 147.55114 -237.831884)
		(end 149.200108 -237.831884)
		(width 0.12954)
		(layer "F.Cu")
		(net "M_G_CPU1_SA_DQS_DN<7>")
	)
	(segment
		(start 161.602166 -223.589342)
		(end 161.744406 -223.447102)
		(width 0.12954)
		(layer "F.Cu")
		(net "M_G_CPU1_SA_DQS_DN<7>")
	)
	(segment
		(start 161.404046 -223.589342)
		(end 161.602166 -223.589342)
		(width 0.12954)
		(layer "F.Cu")
		(net "M_G_CPU1_SA_DQS_DN<7>")
	)
	(segment
		(start 161.744406 -223.248982)
		(end 161.259266 -222.763842)
		(width 0.12954)
		(layer "F.Cu")
		(net "M_G_CPU1_SA_DQS_DN<7>")
	)
	(segment
		(start 146.087846 -237.706662)
		(end 146.973544 -237.706662)
		(width 0.0762)
		(layer "F.Cu")
		(net "M_G_CPU1_SA_DQS_DN<7>")
	)
	(segment
		(start 161.588704 -221.967552)
		(end 162.055556 -221.967552)
		(width 0.12954)
		(layer "F.Cu")
		(net "M_G_CPU1_SA_DQS_DN<7>")
	)
	(segment
		(start 160.56102 -224.821496)
		(end 160.70326 -224.679256)
		(width 0.12954)
		(layer "F.Cu")
		(net "M_G_CPU1_SA_DQS_DN<7>")
	)
	(segment
		(start 159.659828 -224.118424)
		(end 160.3629 -224.821496)
		(width 0.12954)
		(layer "F.Cu")
		(net "M_G_CPU1_SA_DQS_DN<7>")
	)
	(segment
		(start 162.055556 -221.967552)
		(end 162.296348 -222.208344)
		(width 0.12954)
		(layer "F.Cu")
		(net "M_G_CPU1_SA_DQS_DN<7>")
	)
	(segment
		(start 162.494468 -222.208344)
		(end 162.636708 -222.066104)
		(width 0.12954)
		(layer "F.Cu")
		(net "M_G_CPU1_SA_DQS_DN<7>")
	)
	(segment
		(start 159.209232 -224.118424)
		(end 159.659828 -224.118424)
		(width 0.12954)
		(layer "F.Cu")
		(net "M_G_CPU1_SA_DQS_DN<7>")
	)
	(segment
		(start 145.796508 -237.787688)
		(end 145.80489 -237.782862)
		(width 0.0762)
		(layer "F.Cu")
		(net "M_G_CPU1_SA_DQS_DN<7>")
	)
	(segment
		(start 160.830006 -223.015302)
		(end 161.404046 -223.589342)
		(width 0.12954)
		(layer "F.Cu")
		(net "M_G_CPU1_SA_DQS_DN<7>")
	)
	(segment
		(start 163.0426 -220.549216)
		(end 163.605972 -220.549216)
		(width 0.12954)
		(layer "F.Cu")
		(net "M_G_CPU1_SA_DQS_DN<7>")
	)
	(segment
		(start 162.405568 -221.636844)
		(end 162.405568 -221.186248)
		(width 0.12954)
		(layer "F.Cu")
		(net "M_G_CPU1_SA_DQS_DN<7>")
	)
	(segment
		(start 161.259266 -222.763842)
		(end 161.259266 -222.29699)
		(width 0.12954)
		(layer "F.Cu")
		(net "M_G_CPU1_SA_DQS_DN<7>")
	)
	(segment
		(start 162.636708 -221.867984)
		(end 162.405568 -221.636844)
		(width 0.12954)
		(layer "F.Cu")
		(net "M_G_CPU1_SA_DQS_DN<7>")
	)
	(segment
		(start 147.46605 -237.897924)
		(end 147.53209 -237.831884)
		(width 0.0762)
		(layer "F.Cu")
		(net "M_G_CPU1_SA_DQS_DN<7>")
	)
	(segment
		(start 160.70326 -224.481136)
		(end 160.033716 -223.811592)
		(width 0.12954)
		(layer "F.Cu")
		(net "M_G_CPU1_SA_DQS_DN<7>")
	)
	(segment
		(start 147.164806 -237.897924)
		(end 147.46605 -237.897924)
		(width 0.0762)
		(layer "F.Cu")
		(net "M_G_CPU1_SA_DQS_DN<7>")
	)
	(segment
		(start 160.3629 -224.821496)
		(end 160.56102 -224.821496)
		(width 0.12954)
		(layer "F.Cu")
		(net "M_G_CPU1_SA_DQS_DN<7>")
	)
	(segment
		(start 160.363154 -223.015302)
		(end 160.830006 -223.015302)
		(width 0.12954)
		(layer "F.Cu")
		(net "M_G_CPU1_SA_DQS_DN<7>")
	)
	(segment
		(start 161.744406 -223.447102)
		(end 161.744406 -223.248982)
		(width 0.12954)
		(layer "F.Cu")
		(net "M_G_CPU1_SA_DQS_DN<7>")
	)
	(segment
		(start 158.88208 -228.149912)
		(end 158.88208 -224.445576)
		(width 0.12954)
		(layer "F.Cu")
		(net "M_G_CPU1_SA_DQS_DN<7>")
	)
	(segment
		(start 162.405568 -221.186248)
		(end 163.0426 -220.549216)
		(width 0.12954)
		(layer "F.Cu")
		(net "M_G_CPU1_SA_DQS_DN<7>")
	)
	(segment
		(start 158.88208 -224.445576)
		(end 159.209232 -224.118424)
		(width 0.12954)
		(layer "F.Cu")
		(net "M_G_CPU1_SA_DQS_DN<7>")
	)
	(segment
		(start 160.033716 -223.34474)
		(end 160.363154 -223.015302)
		(width 0.12954)
		(layer "F.Cu")
		(net "M_G_CPU1_SA_DQS_DN<7>")
	)
	(segment
		(start 161.259266 -222.29699)
		(end 161.588704 -221.967552)
		(width 0.12954)
		(layer "F.Cu")
		(net "M_G_CPU1_SA_DQS_DN<7>")
	)
	(segment
		(start 160.70326 -224.679256)
		(end 160.70326 -224.481136)
		(width 0.12954)
		(layer "F.Cu")
		(net "M_G_CPU1_SA_DQS_DN<7>")
	)
	(segment
		(start 147.53209 -237.831884)
		(end 147.55114 -237.831884)
		(width 0.0762)
		(layer "F.Cu")
		(net "M_G_CPU1_SA_DQS_DN<7>")
	)
	(arc
		(start 144.27581 -237.710472)
		(mid 144.387056 -237.735735)
		(end 144.490948 -237.782862)
		(width 0.0762)
		(layer "F.Cu")
		(net "M_G_CPU1_SA_DQS_DN<7>")
	)
	(arc
		(start 145.80489 -237.782862)
		(mid 145.941326 -237.726037)
		(end 146.087846 -237.706662)
		(width 0.0762)
		(layer "F.Cu")
		(net "M_G_CPU1_SA_DQS_DN<7>")
	)
	(arc
		(start 144.252188 -237.708186)
		(mid 144.264011 -237.709203)
		(end 144.27581 -237.710472)
		(width 0.0762)
		(layer "F.Cu")
		(net "M_G_CPU1_SA_DQS_DN<7>")
	)
	(arc
		(start 145.430748 -237.782862)
		(mid 145.612999 -237.833212)
		(end 145.796508 -237.787688)
		(width 0.0762)
		(layer "F.Cu")
		(net "M_G_CPU1_SA_DQS_DN<7>")
	)
	(arc
		(start 144.490948 -237.782862)
		(mid 144.677892 -237.833117)
		(end 144.864836 -237.782862)
		(width 0.0762)
		(layer "F.Cu")
		(net "M_G_CPU1_SA_DQS_DN<7>")
	)
	(arc
		(start 143.737838 -237.460282)
		(mid 143.971836 -237.632325)
		(end 144.252188 -237.708186)
		(width 0.0762)
		(layer "F.Cu")
		(net "M_G_CPU1_SA_DQS_DN<7>")
	)
	(arc
		(start 144.864836 -237.782862)
		(mid 145.147792 -237.706685)
		(end 145.430748 -237.782862)
		(width 0.0762)
		(layer "F.Cu")
		(net "M_G_CPU1_SA_DQS_DN<7>")
	)
	(segment
		(start 159.041846 -214.068406)
		(end 159.041846 -213.60257)
		(width 0.12954)
		(layer "F.Cu")
		(net "M_G_CPU1_SA_DQS_DN<6>")
	)
	(segment
		(start 160.509458 -212.134958)
		(end 160.975294 -212.134958)
		(width 0.12954)
		(layer "F.Cu")
		(net "M_G_CPU1_SA_DQS_DN<6>")
	)
	(segment
		(start 159.523938 -214.550498)
		(end 159.041846 -214.068406)
		(width 0.12954)
		(layer "F.Cu")
		(net "M_G_CPU1_SA_DQS_DN<6>")
	)
	(segment
		(start 159.523938 -214.749634)
		(end 159.523938 -214.550498)
		(width 0.12954)
		(layer "F.Cu")
		(net "M_G_CPU1_SA_DQS_DN<6>")
	)
	(segment
		(start 160.660588 -213.413848)
		(end 160.178496 -212.931756)
		(width 0.12954)
		(layer "F.Cu")
		(net "M_G_CPU1_SA_DQS_DN<6>")
	)
	(segment
		(start 163.869878 -210.935316)
		(end 164.427916 -210.935316)
		(width 0.12954)
		(layer "F.Cu")
		(net "M_G_CPU1_SA_DQS_DN<6>")
	)
	(segment
		(start 161.656522 -212.61705)
		(end 161.797238 -212.476334)
		(width 0.12954)
		(layer "F.Cu")
		(net "M_G_CPU1_SA_DQS_DN<6>")
	)
	(segment
		(start 162.594036 -211.4804)
		(end 162.793172 -211.4804)
		(width 0.12954)
		(layer "F.Cu")
		(net "M_G_CPU1_SA_DQS_DN<6>")
	)
	(segment
		(start 160.660588 -213.612984)
		(end 160.660588 -213.413848)
		(width 0.12954)
		(layer "F.Cu")
		(net "M_G_CPU1_SA_DQS_DN<6>")
	)
	(segment
		(start 145.796508 -232.927652)
		(end 145.80489 -232.922826)
		(width 0.0762)
		(layer "F.Cu")
		(net "M_G_CPU1_SA_DQS_DN<6>")
	)
	(segment
		(start 160.519872 -213.7537)
		(end 160.660588 -213.612984)
		(width 0.12954)
		(layer "F.Cu")
		(net "M_G_CPU1_SA_DQS_DN<6>")
	)
	(segment
		(start 154.43835 -219.835222)
		(end 159.523938 -214.749634)
		(width 0.12954)
		(layer "F.Cu")
		(net "M_G_CPU1_SA_DQS_DN<6>")
	)
	(segment
		(start 159.372808 -213.271608)
		(end 159.838644 -213.271608)
		(width 0.12954)
		(layer "F.Cu")
		(net "M_G_CPU1_SA_DQS_DN<6>")
	)
	(segment
		(start 161.457386 -212.61705)
		(end 161.656522 -212.61705)
		(width 0.12954)
		(layer "F.Cu")
		(net "M_G_CPU1_SA_DQS_DN<6>")
	)
	(segment
		(start 163.07435 -211.199222)
		(end 163.605972 -211.199222)
		(width 0.12954)
		(layer "F.Cu")
		(net "M_G_CPU1_SA_DQS_DN<6>")
	)
	(segment
		(start 160.178496 -212.931756)
		(end 160.178496 -212.46592)
		(width 0.12954)
		(layer "F.Cu")
		(net "M_G_CPU1_SA_DQS_DN<6>")
	)
	(segment
		(start 161.646108 -210.998308)
		(end 162.111944 -210.998308)
		(width 0.12954)
		(layer "F.Cu")
		(net "M_G_CPU1_SA_DQS_DN<6>")
	)
	(segment
		(start 163.605972 -211.199222)
		(end 163.869878 -210.935316)
		(width 0.12954)
		(layer "F.Cu")
		(net "M_G_CPU1_SA_DQS_DN<6>")
	)
	(segment
		(start 148.00453 -232.780586)
		(end 154.43835 -226.346766)
		(width 0.12954)
		(layer "F.Cu")
		(net "M_G_CPU1_SA_DQS_DN<6>")
	)
	(segment
		(start 161.797238 -212.476334)
		(end 161.797238 -212.277198)
		(width 0.12954)
		(layer "F.Cu")
		(net "M_G_CPU1_SA_DQS_DN<6>")
	)
	(segment
		(start 161.315146 -211.32927)
		(end 161.646108 -210.998308)
		(width 0.12954)
		(layer "F.Cu")
		(net "M_G_CPU1_SA_DQS_DN<6>")
	)
	(segment
		(start 160.975294 -212.134958)
		(end 161.457386 -212.61705)
		(width 0.12954)
		(layer "F.Cu")
		(net "M_G_CPU1_SA_DQS_DN<6>")
	)
	(segment
		(start 146.087846 -232.846626)
		(end 147.236688 -232.846626)
		(width 0.0762)
		(layer "F.Cu")
		(net "M_G_CPU1_SA_DQS_DN<6>")
	)
	(segment
		(start 154.43835 -226.346766)
		(end 154.43835 -219.835222)
		(width 0.12954)
		(layer "F.Cu")
		(net "M_G_CPU1_SA_DQS_DN<6>")
	)
	(segment
		(start 147.321778 -232.780586)
		(end 148.00453 -232.780586)
		(width 0.12954)
		(layer "F.Cu")
		(net "M_G_CPU1_SA_DQS_DN<6>")
	)
	(segment
		(start 160.178496 -212.46592)
		(end 160.509458 -212.134958)
		(width 0.12954)
		(layer "F.Cu")
		(net "M_G_CPU1_SA_DQS_DN<6>")
	)
	(segment
		(start 147.302728 -232.780586)
		(end 147.321778 -232.780586)
		(width 0.0762)
		(layer "F.Cu")
		(net "M_G_CPU1_SA_DQS_DN<6>")
	)
	(segment
		(start 161.797238 -212.277198)
		(end 161.315146 -211.795106)
		(width 0.12954)
		(layer "F.Cu")
		(net "M_G_CPU1_SA_DQS_DN<6>")
	)
	(segment
		(start 159.838644 -213.271608)
		(end 160.320736 -213.7537)
		(width 0.12954)
		(layer "F.Cu")
		(net "M_G_CPU1_SA_DQS_DN<6>")
	)
	(segment
		(start 159.041846 -213.60257)
		(end 159.372808 -213.271608)
		(width 0.12954)
		(layer "F.Cu")
		(net "M_G_CPU1_SA_DQS_DN<6>")
	)
	(segment
		(start 160.320736 -213.7537)
		(end 160.519872 -213.7537)
		(width 0.12954)
		(layer "F.Cu")
		(net "M_G_CPU1_SA_DQS_DN<6>")
	)
	(segment
		(start 162.793172 -211.4804)
		(end 163.07435 -211.199222)
		(width 0.12954)
		(layer "F.Cu")
		(net "M_G_CPU1_SA_DQS_DN<6>")
	)
	(segment
		(start 162.111944 -210.998308)
		(end 162.594036 -211.4804)
		(width 0.12954)
		(layer "F.Cu")
		(net "M_G_CPU1_SA_DQS_DN<6>")
	)
	(segment
		(start 161.315146 -211.795106)
		(end 161.315146 -211.32927)
		(width 0.12954)
		(layer "F.Cu")
		(net "M_G_CPU1_SA_DQS_DN<6>")
	)
	(segment
		(start 147.236688 -232.846626)
		(end 147.302728 -232.780586)
		(width 0.0762)
		(layer "F.Cu")
		(net "M_G_CPU1_SA_DQS_DN<6>")
	)
	(arc
		(start 143.737838 -232.600246)
		(mid 143.971836 -232.772289)
		(end 144.252188 -232.84815)
		(width 0.0762)
		(layer "F.Cu")
		(net "M_G_CPU1_SA_DQS_DN<6>")
	)
	(arc
		(start 145.430748 -232.922826)
		(mid 145.612999 -232.973176)
		(end 145.796508 -232.927652)
		(width 0.0762)
		(layer "F.Cu")
		(net "M_G_CPU1_SA_DQS_DN<6>")
	)
	(arc
		(start 144.864836 -232.922826)
		(mid 145.147792 -232.846649)
		(end 145.430748 -232.922826)
		(width 0.0762)
		(layer "F.Cu")
		(net "M_G_CPU1_SA_DQS_DN<6>")
	)
	(arc
		(start 144.490948 -232.922826)
		(mid 144.677892 -232.973081)
		(end 144.864836 -232.922826)
		(width 0.0762)
		(layer "F.Cu")
		(net "M_G_CPU1_SA_DQS_DN<6>")
	)
	(arc
		(start 144.27581 -232.850436)
		(mid 144.387056 -232.875699)
		(end 144.490948 -232.922826)
		(width 0.0762)
		(layer "F.Cu")
		(net "M_G_CPU1_SA_DQS_DN<6>")
	)
	(arc
		(start 144.252188 -232.84815)
		(mid 144.264011 -232.849167)
		(end 144.27581 -232.850436)
		(width 0.0762)
		(layer "F.Cu")
		(net "M_G_CPU1_SA_DQS_DN<6>")
	)
	(arc
		(start 145.80489 -232.922826)
		(mid 145.941326 -232.866001)
		(end 146.087846 -232.846626)
		(width 0.0762)
		(layer "F.Cu")
		(net "M_G_CPU1_SA_DQS_DN<6>")
	)
	(segment
		(start 160.23971 -205.77048)
		(end 160.23971 -205.572614)
		(width 0.12954)
		(layer "F.Cu")
		(net "M_G_CPU1_SA_DQS_DN<5>")
	)
	(segment
		(start 162.662108 -201.849228)
		(end 163.605972 -201.849228)
		(width 0.12954)
		(layer "F.Cu")
		(net "M_G_CPU1_SA_DQS_DN<5>")
	)
	(segment
		(start 162.51301 -203.49718)
		(end 162.51301 -203.299314)
		(width 0.12954)
		(layer "F.Cu")
		(net "M_G_CPU1_SA_DQS_DN<5>")
	)
	(segment
		(start 160.538668 -204.278992)
		(end 161.035746 -204.77607)
		(width 0.12954)
		(layer "F.Cu")
		(net "M_G_CPU1_SA_DQS_DN<5>")
	)
	(segment
		(start 147.310602 -227.174552)
		(end 149.81301 -224.671128)
		(width 0.12954)
		(layer "F.Cu")
		(net "M_G_CPU1_SA_DQS_DN<5>")
	)
	(segment
		(start 160.892998 -203.952602)
		(end 160.892998 -203.486258)
		(width 0.12954)
		(layer "F.Cu")
		(net "M_G_CPU1_SA_DQS_DN<5>")
	)
	(segment
		(start 159.742378 -204.608938)
		(end 160.072324 -204.278992)
		(width 0.12954)
		(layer "F.Cu")
		(net "M_G_CPU1_SA_DQS_DN<5>")
	)
	(segment
		(start 159.742378 -205.075282)
		(end 159.742378 -204.608938)
		(width 0.12954)
		(layer "F.Cu")
		(net "M_G_CPU1_SA_DQS_DN<5>")
	)
	(segment
		(start 161.37636 -204.63383)
		(end 161.37636 -204.435964)
		(width 0.12954)
		(layer "F.Cu")
		(net "M_G_CPU1_SA_DQS_DN<5>")
	)
	(segment
		(start 147.297394 -227.280978)
		(end 147.29714 -227.188014)
		(width 0.0762)
		(layer "F.Cu")
		(net "M_G_CPU1_SA_DQS_DN<5>")
	)
	(segment
		(start 146.180302 -227.705666)
		(end 146.873214 -227.705666)
		(width 0.0762)
		(layer "F.Cu")
		(net "M_G_CPU1_SA_DQS_DN<5>")
	)
	(segment
		(start 160.892998 -203.486258)
		(end 161.222944 -203.156312)
		(width 0.12954)
		(layer "F.Cu")
		(net "M_G_CPU1_SA_DQS_DN<5>")
	)
	(segment
		(start 160.072324 -204.278992)
		(end 160.538668 -204.278992)
		(width 0.12954)
		(layer "F.Cu")
		(net "M_G_CPU1_SA_DQS_DN<5>")
	)
	(segment
		(start 163.869878 -201.585322)
		(end 164.427916 -201.585322)
		(width 0.12954)
		(layer "F.Cu")
		(net "M_G_CPU1_SA_DQS_DN<5>")
	)
	(segment
		(start 147.29714 -227.188014)
		(end 147.310602 -227.174552)
		(width 0.0762)
		(layer "F.Cu")
		(net "M_G_CPU1_SA_DQS_DN<5>")
	)
	(segment
		(start 161.035746 -204.77607)
		(end 161.23412 -204.77607)
		(width 0.12954)
		(layer "F.Cu")
		(net "M_G_CPU1_SA_DQS_DN<5>")
	)
	(segment
		(start 162.37077 -203.63942)
		(end 162.51301 -203.49718)
		(width 0.12954)
		(layer "F.Cu")
		(net "M_G_CPU1_SA_DQS_DN<5>")
	)
	(segment
		(start 161.23412 -204.77607)
		(end 161.37636 -204.63383)
		(width 0.12954)
		(layer "F.Cu")
		(net "M_G_CPU1_SA_DQS_DN<5>")
	)
	(segment
		(start 161.222944 -203.156312)
		(end 161.689288 -203.156312)
		(width 0.12954)
		(layer "F.Cu")
		(net "M_G_CPU1_SA_DQS_DN<5>")
	)
	(segment
		(start 146.873214 -227.705158)
		(end 147.297394 -227.280978)
		(width 0.0762)
		(layer "F.Cu")
		(net "M_G_CPU1_SA_DQS_DN<5>")
	)
	(segment
		(start 162.087814 -202.423522)
		(end 162.662108 -201.849228)
		(width 0.12954)
		(layer "F.Cu")
		(net "M_G_CPU1_SA_DQS_DN<5>")
	)
	(segment
		(start 146.873214 -227.705666)
		(end 146.873214 -227.705158)
		(width 0.0762)
		(layer "F.Cu")
		(net "M_G_CPU1_SA_DQS_DN<5>")
	)
	(segment
		(start 161.37636 -204.435964)
		(end 160.892998 -203.952602)
		(width 0.12954)
		(layer "F.Cu")
		(net "M_G_CPU1_SA_DQS_DN<5>")
	)
	(segment
		(start 159.279082 -205.91272)
		(end 160.09747 -205.91272)
		(width 0.12954)
		(layer "F.Cu")
		(net "M_G_CPU1_SA_DQS_DN<5>")
	)
	(segment
		(start 149.81301 -215.378792)
		(end 159.279082 -205.91272)
		(width 0.12954)
		(layer "F.Cu")
		(net "M_G_CPU1_SA_DQS_DN<5>")
	)
	(segment
		(start 162.172396 -203.63942)
		(end 162.37077 -203.63942)
		(width 0.12954)
		(layer "F.Cu")
		(net "M_G_CPU1_SA_DQS_DN<5>")
	)
	(segment
		(start 161.689288 -203.156312)
		(end 162.172396 -203.63942)
		(width 0.12954)
		(layer "F.Cu")
		(net "M_G_CPU1_SA_DQS_DN<5>")
	)
	(segment
		(start 160.23971 -205.572614)
		(end 159.742378 -205.075282)
		(width 0.12954)
		(layer "F.Cu")
		(net "M_G_CPU1_SA_DQS_DN<5>")
	)
	(segment
		(start 163.605972 -201.849228)
		(end 163.869878 -201.585322)
		(width 0.12954)
		(layer "F.Cu")
		(net "M_G_CPU1_SA_DQS_DN<5>")
	)
	(segment
		(start 145.881598 -228.004116)
		(end 146.180302 -227.705666)
		(width 0.0762)
		(layer "F.Cu")
		(net "M_G_CPU1_SA_DQS_DN<5>")
	)
	(segment
		(start 160.09747 -205.91272)
		(end 160.23971 -205.77048)
		(width 0.12954)
		(layer "F.Cu")
		(net "M_G_CPU1_SA_DQS_DN<5>")
	)
	(segment
		(start 162.51301 -203.299314)
		(end 162.087814 -202.874118)
		(width 0.12954)
		(layer "F.Cu")
		(net "M_G_CPU1_SA_DQS_DN<5>")
	)
	(segment
		(start 162.087814 -202.874118)
		(end 162.087814 -202.423522)
		(width 0.12954)
		(layer "F.Cu")
		(net "M_G_CPU1_SA_DQS_DN<5>")
	)
	(segment
		(start 149.81301 -224.671128)
		(end 149.81301 -215.378792)
		(width 0.12954)
		(layer "F.Cu")
		(net "M_G_CPU1_SA_DQS_DN<5>")
	)
	(arc
		(start 145.805144 -228.063044)
		(mid 145.845289 -228.036068)
		(end 145.881598 -228.004116)
		(width 0.0762)
		(layer "F.Cu")
		(net "M_G_CPU1_SA_DQS_DN<5>")
	)
	(arc
		(start 144.864836 -228.063044)
		(mid 145.147792 -227.986867)
		(end 145.430748 -228.063044)
		(width 0.0762)
		(layer "F.Cu")
		(net "M_G_CPU1_SA_DQS_DN<5>")
	)
	(arc
		(start 145.430748 -228.063044)
		(mid 145.617946 -228.113426)
		(end 145.805144 -228.063044)
		(width 0.0762)
		(layer "F.Cu")
		(net "M_G_CPU1_SA_DQS_DN<5>")
	)
	(arc
		(start 144.27581 -227.990654)
		(mid 144.387056 -228.015917)
		(end 144.490948 -228.063044)
		(width 0.0762)
		(layer "F.Cu")
		(net "M_G_CPU1_SA_DQS_DN<5>")
	)
	(arc
		(start 144.490948 -228.063044)
		(mid 144.677892 -228.113299)
		(end 144.864836 -228.063044)
		(width 0.0762)
		(layer "F.Cu")
		(net "M_G_CPU1_SA_DQS_DN<5>")
	)
	(arc
		(start 143.737838 -227.740464)
		(mid 143.971836 -227.912507)
		(end 144.252188 -227.988368)
		(width 0.0762)
		(layer "F.Cu")
		(net "M_G_CPU1_SA_DQS_DN<5>")
	)
	(arc
		(start 144.252188 -227.988368)
		(mid 144.264011 -227.989385)
		(end 144.27581 -227.990654)
		(width 0.0762)
		(layer "F.Cu")
		(net "M_G_CPU1_SA_DQS_DN<5>")
	)
	(segment
		(start 156.135832 -246.872506)
		(end 158.528766 -244.479572)
		(width 0.12954)
		(layer "F.Cu")
		(net "M_G_CPU1_SA_DQS_DN<4>")
	)
	(segment
		(start 167.695626 -238.668052)
		(end 168.012872 -238.985298)
		(width 0.101346)
		(layer "F.Cu")
		(net "M_G_CPU1_SA_DQS_DN<4>")
	)
	(segment
		(start 163.566602 -238.560356)
		(end 165.994842 -238.560356)
		(width 0.101346)
		(layer "F.Cu")
		(net "M_G_CPU1_SA_DQS_DN<4>")
	)
	(segment
		(start 147.41906 -246.872506)
		(end 156.135832 -246.872506)
		(width 0.12954)
		(layer "F.Cu")
		(net "M_G_CPU1_SA_DQS_DN<4>")
	)
	(segment
		(start 163.303712 -238.297466)
		(end 163.566602 -238.560356)
		(width 0.12954)
		(layer "F.Cu")
		(net "M_G_CPU1_SA_DQS_DN<4>")
	)
	(segment
		(start 147.40001 -246.872506)
		(end 147.41906 -246.872506)
		(width 0.0762)
		(layer "F.Cu")
		(net "M_G_CPU1_SA_DQS_DN<4>")
	)
	(segment
		(start 166.59733 -238.242856)
		(end 167.022526 -238.668052)
		(width 0.101346)
		(layer "F.Cu")
		(net "M_G_CPU1_SA_DQS_DN<4>")
	)
	(segment
		(start 147.067016 -246.933974)
		(end 147.194524 -246.806466)
		(width 0.0762)
		(layer "F.Cu")
		(net "M_G_CPU1_SA_DQS_DN<4>")
	)
	(segment
		(start 147.194524 -246.806466)
		(end 147.33397 -246.806466)
		(width 0.0762)
		(layer "F.Cu")
		(net "M_G_CPU1_SA_DQS_DN<4>")
	)
	(segment
		(start 158.528766 -244.479572)
		(end 158.528766 -242.819428)
		(width 0.12954)
		(layer "F.Cu")
		(net "M_G_CPU1_SA_DQS_DN<4>")
	)
	(segment
		(start 147.33397 -246.806466)
		(end 147.40001 -246.872506)
		(width 0.0762)
		(layer "F.Cu")
		(net "M_G_CPU1_SA_DQS_DN<4>")
	)
	(segment
		(start 145.617946 -247.180354)
		(end 145.515584 -247.004078)
		(width 0.0762)
		(layer "F.Cu")
		(net "M_G_CPU1_SA_DQS_DN<4>")
	)
	(segment
		(start 165.994842 -238.560356)
		(end 166.312342 -238.242856)
		(width 0.101346)
		(layer "F.Cu")
		(net "M_G_CPU1_SA_DQS_DN<4>")
	)
	(segment
		(start 167.022526 -238.668052)
		(end 167.695626 -238.668052)
		(width 0.101346)
		(layer "F.Cu")
		(net "M_G_CPU1_SA_DQS_DN<4>")
	)
	(segment
		(start 145.796508 -246.852948)
		(end 145.80489 -246.857774)
		(width 0.0762)
		(layer "F.Cu")
		(net "M_G_CPU1_SA_DQS_DN<4>")
	)
	(segment
		(start 166.312342 -238.242856)
		(end 166.59733 -238.242856)
		(width 0.101346)
		(layer "F.Cu")
		(net "M_G_CPU1_SA_DQS_DN<4>")
	)
	(segment
		(start 146.087592 -246.933974)
		(end 147.067016 -246.933974)
		(width 0.0762)
		(layer "F.Cu")
		(net "M_G_CPU1_SA_DQS_DN<4>")
	)
	(segment
		(start 163.050728 -238.297466)
		(end 163.303712 -238.297466)
		(width 0.12954)
		(layer "F.Cu")
		(net "M_G_CPU1_SA_DQS_DN<4>")
	)
	(segment
		(start 158.528766 -242.819428)
		(end 163.050728 -238.297466)
		(width 0.12954)
		(layer "F.Cu")
		(net "M_G_CPU1_SA_DQS_DN<4>")
	)
	(segment
		(start 168.012872 -238.985298)
		(end 168.527984 -238.985298)
		(width 0.101346)
		(layer "F.Cu")
		(net "M_G_CPU1_SA_DQS_DN<4>")
	)
	(arc
		(start 146.040602 -246.932196)
		(mid 146.064079 -246.933572)
		(end 146.087592 -246.933974)
		(width 0.0762)
		(layer "F.Cu")
		(net "M_G_CPU1_SA_DQS_DN<4>")
	)
	(arc
		(start 145.80489 -246.857774)
		(mid 145.918614 -246.908075)
		(end 146.040602 -246.932196)
		(width 0.0762)
		(layer "F.Cu")
		(net "M_G_CPU1_SA_DQS_DN<4>")
	)
	(arc
		(start 145.682462 -246.81307)
		(mid 145.741108 -246.828363)
		(end 145.796508 -246.852948)
		(width 0.0762)
		(layer "F.Cu")
		(net "M_G_CPU1_SA_DQS_DN<4>")
	)
	(arc
		(start 145.515584 -247.004078)
		(mid 145.545213 -246.861591)
		(end 145.682462 -246.81307)
		(width 0.0762)
		(layer "F.Cu")
		(net "M_G_CPU1_SA_DQS_DN<4>")
	)
	(segment
		(start 147.6248 -242.343178)
		(end 151.572976 -242.343178)
		(width 0.12954)
		(layer "F.Cu")
		(net "M_G_CPU1_SA_DQS_DN<3>")
	)
	(segment
		(start 147.60575 -242.343178)
		(end 147.6248 -242.343178)
		(width 0.0762)
		(layer "F.Cu")
		(net "M_G_CPU1_SA_DQS_DN<3>")
	)
	(segment
		(start 159.42691 -235.55452)
		(end 159.42691 -233.21772)
		(width 0.12954)
		(layer "F.Cu")
		(net "M_G_CPU1_SA_DQS_DN<3>")
	)
	(segment
		(start 163.114736 -228.947472)
		(end 163.303712 -228.947472)
		(width 0.12954)
		(layer "F.Cu")
		(net "M_G_CPU1_SA_DQS_DN<3>")
	)
	(segment
		(start 163.566602 -229.210362)
		(end 165.994842 -229.210362)
		(width 0.101346)
		(layer "F.Cu")
		(net "M_G_CPU1_SA_DQS_DN<3>")
	)
	(segment
		(start 159.42691 -233.21772)
		(end 162.97529 -229.66934)
		(width 0.12954)
		(layer "F.Cu")
		(net "M_G_CPU1_SA_DQS_DN<3>")
	)
	(segment
		(start 156.400754 -237.5154)
		(end 157.46603 -237.5154)
		(width 0.12954)
		(layer "F.Cu")
		(net "M_G_CPU1_SA_DQS_DN<3>")
	)
	(segment
		(start 167.695626 -229.318058)
		(end 168.012872 -229.635304)
		(width 0.101346)
		(layer "F.Cu")
		(net "M_G_CPU1_SA_DQS_DN<3>")
	)
	(segment
		(start 165.994842 -229.210362)
		(end 166.312342 -228.892862)
		(width 0.101346)
		(layer "F.Cu")
		(net "M_G_CPU1_SA_DQS_DN<3>")
	)
	(segment
		(start 147.53971 -242.277138)
		(end 147.60575 -242.343178)
		(width 0.0762)
		(layer "F.Cu")
		(net "M_G_CPU1_SA_DQS_DN<3>")
	)
	(segment
		(start 147.003516 -242.073938)
		(end 147.206716 -242.277138)
		(width 0.0762)
		(layer "F.Cu")
		(net "M_G_CPU1_SA_DQS_DN<3>")
	)
	(segment
		(start 146.087592 -242.073938)
		(end 147.003516 -242.073938)
		(width 0.0762)
		(layer "F.Cu")
		(net "M_G_CPU1_SA_DQS_DN<3>")
	)
	(segment
		(start 166.56685 -228.892862)
		(end 166.992046 -229.318058)
		(width 0.101346)
		(layer "F.Cu")
		(net "M_G_CPU1_SA_DQS_DN<3>")
	)
	(segment
		(start 163.303712 -228.947472)
		(end 163.566602 -229.210362)
		(width 0.12954)
		(layer "F.Cu")
		(net "M_G_CPU1_SA_DQS_DN<3>")
	)
	(segment
		(start 168.012872 -229.635304)
		(end 168.527984 -229.635304)
		(width 0.101346)
		(layer "F.Cu")
		(net "M_G_CPU1_SA_DQS_DN<3>")
	)
	(segment
		(start 162.97529 -229.086918)
		(end 163.114736 -228.947472)
		(width 0.12954)
		(layer "F.Cu")
		(net "M_G_CPU1_SA_DQS_DN<3>")
	)
	(segment
		(start 151.572976 -242.343178)
		(end 156.400754 -237.5154)
		(width 0.12954)
		(layer "F.Cu")
		(net "M_G_CPU1_SA_DQS_DN<3>")
	)
	(segment
		(start 145.617946 -242.320318)
		(end 145.515584 -242.144042)
		(width 0.0762)
		(layer "F.Cu")
		(net "M_G_CPU1_SA_DQS_DN<3>")
	)
	(segment
		(start 166.312342 -228.892862)
		(end 166.56685 -228.892862)
		(width 0.101346)
		(layer "F.Cu")
		(net "M_G_CPU1_SA_DQS_DN<3>")
	)
	(segment
		(start 147.206716 -242.277138)
		(end 147.53971 -242.277138)
		(width 0.0762)
		(layer "F.Cu")
		(net "M_G_CPU1_SA_DQS_DN<3>")
	)
	(segment
		(start 157.46603 -237.5154)
		(end 159.42691 -235.55452)
		(width 0.12954)
		(layer "F.Cu")
		(net "M_G_CPU1_SA_DQS_DN<3>")
	)
	(segment
		(start 145.796508 -241.992912)
		(end 145.80489 -241.997738)
		(width 0.0762)
		(layer "F.Cu")
		(net "M_G_CPU1_SA_DQS_DN<3>")
	)
	(segment
		(start 166.992046 -229.318058)
		(end 167.695626 -229.318058)
		(width 0.101346)
		(layer "F.Cu")
		(net "M_G_CPU1_SA_DQS_DN<3>")
	)
	(segment
		(start 162.97529 -229.66934)
		(end 162.97529 -229.086918)
		(width 0.12954)
		(layer "F.Cu")
		(net "M_G_CPU1_SA_DQS_DN<3>")
	)
	(arc
		(start 145.515584 -242.144042)
		(mid 145.545213 -242.001555)
		(end 145.682462 -241.953034)
		(width 0.0762)
		(layer "F.Cu")
		(net "M_G_CPU1_SA_DQS_DN<3>")
	)
	(arc
		(start 146.040602 -242.07216)
		(mid 146.064079 -242.073536)
		(end 146.087592 -242.073938)
		(width 0.0762)
		(layer "F.Cu")
		(net "M_G_CPU1_SA_DQS_DN<3>")
	)
	(arc
		(start 145.682462 -241.953034)
		(mid 145.741108 -241.968327)
		(end 145.796508 -241.992912)
		(width 0.0762)
		(layer "F.Cu")
		(net "M_G_CPU1_SA_DQS_DN<3>")
	)
	(arc
		(start 145.80489 -241.997738)
		(mid 145.918614 -242.048039)
		(end 146.040602 -242.07216)
		(width 0.0762)
		(layer "F.Cu")
		(net "M_G_CPU1_SA_DQS_DN<3>")
	)
	(segment
		(start 167.022018 -219.968064)
		(end 167.695626 -219.968064)
		(width 0.101346)
		(layer "F.Cu")
		(net "M_G_CPU1_SA_DQS_DN<2>")
	)
	(segment
		(start 160.696402 -222.004128)
		(end 161.093658 -221.606872)
		(width 0.12954)
		(layer "F.Cu")
		(net "M_G_CPU1_SA_DQS_DN<2>")
	)
	(segment
		(start 158.820358 -223.386396)
		(end 159.065976 -223.140778)
		(width 0.12954)
		(layer "F.Cu")
		(net "M_G_CPU1_SA_DQS_DN<2>")
	)
	(segment
		(start 145.617946 -237.460282)
		(end 145.515584 -237.284006)
		(width 0.0762)
		(layer "F.Cu")
		(net "M_G_CPU1_SA_DQS_DN<2>")
	)
	(segment
		(start 147.413218 -237.328964)
		(end 147.479258 -237.395004)
		(width 0.0762)
		(layer "F.Cu")
		(net "M_G_CPU1_SA_DQS_DN<2>")
	)
	(segment
		(start 147.479258 -237.395004)
		(end 147.498308 -237.395004)
		(width 0.0762)
		(layer "F.Cu")
		(net "M_G_CPU1_SA_DQS_DN<2>")
	)
	(segment
		(start 146.087592 -237.213902)
		(end 146.956272 -237.213902)
		(width 0.0762)
		(layer "F.Cu")
		(net "M_G_CPU1_SA_DQS_DN<2>")
	)
	(segment
		(start 165.994842 -219.860368)
		(end 166.312342 -219.542868)
		(width 0.101346)
		(layer "F.Cu")
		(net "M_G_CPU1_SA_DQS_DN<2>")
	)
	(segment
		(start 161.833052 -220.867478)
		(end 162.230308 -220.470222)
		(width 0.12954)
		(layer "F.Cu")
		(net "M_G_CPU1_SA_DQS_DN<2>")
	)
	(segment
		(start 161.412936 -220.867478)
		(end 161.833052 -220.867478)
		(width 0.12954)
		(layer "F.Cu")
		(net "M_G_CPU1_SA_DQS_DN<2>")
	)
	(segment
		(start 163.566602 -219.860368)
		(end 165.994842 -219.860368)
		(width 0.101346)
		(layer "F.Cu")
		(net "M_G_CPU1_SA_DQS_DN<2>")
	)
	(segment
		(start 159.957008 -222.325946)
		(end 160.278826 -222.004128)
		(width 0.12954)
		(layer "F.Cu")
		(net "M_G_CPU1_SA_DQS_DN<2>")
	)
	(segment
		(start 166.596822 -219.542868)
		(end 167.022018 -219.968064)
		(width 0.101346)
		(layer "F.Cu")
		(net "M_G_CPU1_SA_DQS_DN<2>")
	)
	(segment
		(start 145.796508 -237.132876)
		(end 145.80489 -237.137702)
		(width 0.0762)
		(layer "F.Cu")
		(net "M_G_CPU1_SA_DQS_DN<2>")
	)
	(segment
		(start 147.498308 -237.395004)
		(end 149.036278 -237.395004)
		(width 0.12954)
		(layer "F.Cu")
		(net "M_G_CPU1_SA_DQS_DN<2>")
	)
	(segment
		(start 159.957008 -222.743522)
		(end 159.957008 -222.325946)
		(width 0.12954)
		(layer "F.Cu")
		(net "M_G_CPU1_SA_DQS_DN<2>")
	)
	(segment
		(start 147.071334 -237.328964)
		(end 147.413218 -237.328964)
		(width 0.0762)
		(layer "F.Cu")
		(net "M_G_CPU1_SA_DQS_DN<2>")
	)
	(segment
		(start 162.573716 -219.597478)
		(end 163.303712 -219.597478)
		(width 0.12954)
		(layer "F.Cu")
		(net "M_G_CPU1_SA_DQS_DN<2>")
	)
	(segment
		(start 166.312342 -219.542868)
		(end 166.596822 -219.542868)
		(width 0.101346)
		(layer "F.Cu")
		(net "M_G_CPU1_SA_DQS_DN<2>")
	)
	(segment
		(start 146.956272 -237.213902)
		(end 147.071334 -237.328964)
		(width 0.0762)
		(layer "F.Cu")
		(net "M_G_CPU1_SA_DQS_DN<2>")
	)
	(segment
		(start 158.46044 -227.970842)
		(end 158.46044 -224.24009)
		(width 0.12954)
		(layer "F.Cu")
		(net "M_G_CPU1_SA_DQS_DN<2>")
	)
	(segment
		(start 160.278826 -222.004128)
		(end 160.696402 -222.004128)
		(width 0.12954)
		(layer "F.Cu")
		(net "M_G_CPU1_SA_DQS_DN<2>")
	)
	(segment
		(start 163.303712 -219.597478)
		(end 163.566602 -219.860368)
		(width 0.12954)
		(layer "F.Cu")
		(net "M_G_CPU1_SA_DQS_DN<2>")
	)
	(segment
		(start 162.230308 -220.470222)
		(end 162.230308 -219.940886)
		(width 0.12954)
		(layer "F.Cu")
		(net "M_G_CPU1_SA_DQS_DN<2>")
	)
	(segment
		(start 161.093658 -221.606872)
		(end 161.093658 -221.186756)
		(width 0.12954)
		(layer "F.Cu")
		(net "M_G_CPU1_SA_DQS_DN<2>")
	)
	(segment
		(start 168.012872 -220.28531)
		(end 168.527984 -220.28531)
		(width 0.101346)
		(layer "F.Cu")
		(net "M_G_CPU1_SA_DQS_DN<2>")
	)
	(segment
		(start 149.036278 -237.395004)
		(end 158.46044 -227.970842)
		(width 0.12954)
		(layer "F.Cu")
		(net "M_G_CPU1_SA_DQS_DN<2>")
	)
	(segment
		(start 167.695626 -219.968064)
		(end 168.012872 -220.28531)
		(width 0.101346)
		(layer "F.Cu")
		(net "M_G_CPU1_SA_DQS_DN<2>")
	)
	(segment
		(start 162.230308 -219.940886)
		(end 162.573716 -219.597478)
		(width 0.12954)
		(layer "F.Cu")
		(net "M_G_CPU1_SA_DQS_DN<2>")
	)
	(segment
		(start 158.46044 -224.24009)
		(end 158.820358 -223.880172)
		(width 0.12954)
		(layer "F.Cu")
		(net "M_G_CPU1_SA_DQS_DN<2>")
	)
	(segment
		(start 159.559752 -223.140778)
		(end 159.957008 -222.743522)
		(width 0.12954)
		(layer "F.Cu")
		(net "M_G_CPU1_SA_DQS_DN<2>")
	)
	(segment
		(start 158.820358 -223.880172)
		(end 158.820358 -223.386396)
		(width 0.12954)
		(layer "F.Cu")
		(net "M_G_CPU1_SA_DQS_DN<2>")
	)
	(segment
		(start 159.065976 -223.140778)
		(end 159.559752 -223.140778)
		(width 0.12954)
		(layer "F.Cu")
		(net "M_G_CPU1_SA_DQS_DN<2>")
	)
	(segment
		(start 161.093658 -221.186756)
		(end 161.412936 -220.867478)
		(width 0.12954)
		(layer "F.Cu")
		(net "M_G_CPU1_SA_DQS_DN<2>")
	)
	(arc
		(start 145.682462 -237.092998)
		(mid 145.741108 -237.108291)
		(end 145.796508 -237.132876)
		(width 0.0762)
		(layer "F.Cu")
		(net "M_G_CPU1_SA_DQS_DN<2>")
	)
	(arc
		(start 146.040602 -237.212124)
		(mid 146.064079 -237.2135)
		(end 146.087592 -237.213902)
		(width 0.0762)
		(layer "F.Cu")
		(net "M_G_CPU1_SA_DQS_DN<2>")
	)
	(arc
		(start 145.80489 -237.137702)
		(mid 145.918614 -237.188003)
		(end 146.040602 -237.212124)
		(width 0.0762)
		(layer "F.Cu")
		(net "M_G_CPU1_SA_DQS_DN<2>")
	)
	(arc
		(start 145.515584 -237.284006)
		(mid 145.545213 -237.141519)
		(end 145.682462 -237.092998)
		(width 0.0762)
		(layer "F.Cu")
		(net "M_G_CPU1_SA_DQS_DN<2>")
	)
	(segment
		(start 166.606982 -210.192874)
		(end 167.032178 -210.61807)
		(width 0.101346)
		(layer "F.Cu")
		(net "M_G_CPU1_SA_DQS_DN<1>")
	)
	(segment
		(start 147.72894 -232.153206)
		(end 148.021548 -232.153206)
		(width 0.12954)
		(layer "F.Cu")
		(net "M_G_CPU1_SA_DQS_DN<1>")
	)
	(segment
		(start 155.923742 -217.753184)
		(end 156.29001 -217.386916)
		(width 0.12954)
		(layer "F.Cu")
		(net "M_G_CPU1_SA_DQS_DN<1>")
	)
	(segment
		(start 156.46908 -216.616534)
		(end 157.060392 -216.616534)
		(width 0.12954)
		(layer "F.Cu")
		(net "M_G_CPU1_SA_DQS_DN<1>")
	)
	(segment
		(start 161.757106 -210.277964)
		(end 162.221672 -210.277964)
		(width 0.12954)
		(layer "F.Cu")
		(net "M_G_CPU1_SA_DQS_DN<1>")
	)
	(segment
		(start 162.945572 -210.277964)
		(end 163.334192 -210.277964)
		(width 0.12954)
		(layer "F.Cu")
		(net "M_G_CPU1_SA_DQS_DN<1>")
	)
	(segment
		(start 156.29001 -216.795604)
		(end 156.46908 -216.616534)
		(width 0.12954)
		(layer "F.Cu")
		(net "M_G_CPU1_SA_DQS_DN<1>")
	)
	(segment
		(start 155.15336 -217.932254)
		(end 155.33243 -217.753184)
		(width 0.12954)
		(layer "F.Cu")
		(net "M_G_CPU1_SA_DQS_DN<1>")
	)
	(segment
		(start 147.278344 -232.087166)
		(end 147.64385 -232.087166)
		(width 0.0762)
		(layer "F.Cu")
		(net "M_G_CPU1_SA_DQS_DN<1>")
	)
	(segment
		(start 145.796508 -232.27284)
		(end 145.80489 -232.277666)
		(width 0.0762)
		(layer "F.Cu")
		(net "M_G_CPU1_SA_DQS_DN<1>")
	)
	(segment
		(start 157.60573 -215.479884)
		(end 158.197042 -215.479884)
		(width 0.12954)
		(layer "F.Cu")
		(net "M_G_CPU1_SA_DQS_DN<1>")
	)
	(segment
		(start 154.01671 -226.158044)
		(end 154.01671 -219.660216)
		(width 0.12954)
		(layer "F.Cu")
		(net "M_G_CPU1_SA_DQS_DN<1>")
	)
	(segment
		(start 157.42666 -215.658954)
		(end 157.60573 -215.479884)
		(width 0.12954)
		(layer "F.Cu")
		(net "M_G_CPU1_SA_DQS_DN<1>")
	)
	(segment
		(start 145.617946 -232.600246)
		(end 145.515584 -232.42397)
		(width 0.0762)
		(layer "F.Cu")
		(net "M_G_CPU1_SA_DQS_DN<1>")
	)
	(segment
		(start 154.01671 -219.660216)
		(end 155.15336 -218.523566)
		(width 0.12954)
		(layer "F.Cu")
		(net "M_G_CPU1_SA_DQS_DN<1>")
	)
	(segment
		(start 165.994842 -210.510374)
		(end 166.312342 -210.192874)
		(width 0.101346)
		(layer "F.Cu")
		(net "M_G_CPU1_SA_DQS_DN<1>")
	)
	(segment
		(start 162.777932 -210.445604)
		(end 162.945572 -210.277964)
		(width 0.12954)
		(layer "F.Cu")
		(net "M_G_CPU1_SA_DQS_DN<1>")
	)
	(segment
		(start 155.15336 -218.523566)
		(end 155.15336 -217.932254)
		(width 0.12954)
		(layer "F.Cu")
		(net "M_G_CPU1_SA_DQS_DN<1>")
	)
	(segment
		(start 163.334192 -210.277964)
		(end 163.566602 -210.510374)
		(width 0.12954)
		(layer "F.Cu")
		(net "M_G_CPU1_SA_DQS_DN<1>")
	)
	(segment
		(start 163.566602 -210.510374)
		(end 165.994842 -210.510374)
		(width 0.101346)
		(layer "F.Cu")
		(net "M_G_CPU1_SA_DQS_DN<1>")
	)
	(segment
		(start 157.060392 -216.616534)
		(end 157.42666 -216.250266)
		(width 0.12954)
		(layer "F.Cu")
		(net "M_G_CPU1_SA_DQS_DN<1>")
	)
	(segment
		(start 158.197042 -215.479884)
		(end 158.620206 -215.05672)
		(width 0.12954)
		(layer "F.Cu")
		(net "M_G_CPU1_SA_DQS_DN<1>")
	)
	(segment
		(start 147.64385 -232.087166)
		(end 147.70989 -232.153206)
		(width 0.0762)
		(layer "F.Cu")
		(net "M_G_CPU1_SA_DQS_DN<1>")
	)
	(segment
		(start 158.620206 -215.05672)
		(end 158.620206 -213.414864)
		(width 0.12954)
		(layer "F.Cu")
		(net "M_G_CPU1_SA_DQS_DN<1>")
	)
	(segment
		(start 147.70989 -232.153206)
		(end 147.72894 -232.153206)
		(width 0.0762)
		(layer "F.Cu")
		(net "M_G_CPU1_SA_DQS_DN<1>")
	)
	(segment
		(start 167.032178 -210.61807)
		(end 167.695626 -210.61807)
		(width 0.101346)
		(layer "F.Cu")
		(net "M_G_CPU1_SA_DQS_DN<1>")
	)
	(segment
		(start 162.389312 -210.445604)
		(end 162.777932 -210.445604)
		(width 0.12954)
		(layer "F.Cu")
		(net "M_G_CPU1_SA_DQS_DN<1>")
	)
	(segment
		(start 148.021548 -232.153206)
		(end 154.01671 -226.158044)
		(width 0.12954)
		(layer "F.Cu")
		(net "M_G_CPU1_SA_DQS_DN<1>")
	)
	(segment
		(start 158.620206 -213.414864)
		(end 161.757106 -210.277964)
		(width 0.12954)
		(layer "F.Cu")
		(net "M_G_CPU1_SA_DQS_DN<1>")
	)
	(segment
		(start 156.29001 -217.386916)
		(end 156.29001 -216.795604)
		(width 0.12954)
		(layer "F.Cu")
		(net "M_G_CPU1_SA_DQS_DN<1>")
	)
	(segment
		(start 168.012872 -210.935316)
		(end 168.527984 -210.935316)
		(width 0.101346)
		(layer "F.Cu")
		(net "M_G_CPU1_SA_DQS_DN<1>")
	)
	(segment
		(start 167.695626 -210.61807)
		(end 168.012872 -210.935316)
		(width 0.101346)
		(layer "F.Cu")
		(net "M_G_CPU1_SA_DQS_DN<1>")
	)
	(segment
		(start 162.221672 -210.277964)
		(end 162.389312 -210.445604)
		(width 0.12954)
		(layer "F.Cu")
		(net "M_G_CPU1_SA_DQS_DN<1>")
	)
	(segment
		(start 157.42666 -216.250266)
		(end 157.42666 -215.658954)
		(width 0.12954)
		(layer "F.Cu")
		(net "M_G_CPU1_SA_DQS_DN<1>")
	)
	(segment
		(start 166.312342 -210.192874)
		(end 166.606982 -210.192874)
		(width 0.101346)
		(layer "F.Cu")
		(net "M_G_CPU1_SA_DQS_DN<1>")
	)
	(segment
		(start 155.33243 -217.753184)
		(end 155.923742 -217.753184)
		(width 0.12954)
		(layer "F.Cu")
		(net "M_G_CPU1_SA_DQS_DN<1>")
	)
	(segment
		(start 147.011644 -232.353866)
		(end 147.278344 -232.087166)
		(width 0.0762)
		(layer "F.Cu")
		(net "M_G_CPU1_SA_DQS_DN<1>")
	)
	(segment
		(start 146.087592 -232.353866)
		(end 147.011644 -232.353866)
		(width 0.0762)
		(layer "F.Cu")
		(net "M_G_CPU1_SA_DQS_DN<1>")
	)
	(arc
		(start 146.040602 -232.352088)
		(mid 146.064079 -232.353464)
		(end 146.087592 -232.353866)
		(width 0.0762)
		(layer "F.Cu")
		(net "M_G_CPU1_SA_DQS_DN<1>")
	)
	(arc
		(start 145.80489 -232.277666)
		(mid 145.918614 -232.327967)
		(end 146.040602 -232.352088)
		(width 0.0762)
		(layer "F.Cu")
		(net "M_G_CPU1_SA_DQS_DN<1>")
	)
	(arc
		(start 145.682462 -232.232962)
		(mid 145.741108 -232.248255)
		(end 145.796508 -232.27284)
		(width 0.0762)
		(layer "F.Cu")
		(net "M_G_CPU1_SA_DQS_DN<1>")
	)
	(arc
		(start 145.515584 -232.42397)
		(mid 145.545213 -232.281483)
		(end 145.682462 -232.232962)
		(width 0.0762)
		(layer "F.Cu")
		(net "M_G_CPU1_SA_DQS_DN<1>")
	)
	(segment
		(start 145.796508 -227.413058)
		(end 145.80489 -227.417884)
		(width 0.0762)
		(layer "F.Cu")
		(net "M_G_CPU1_SA_DQS_DN<0>")
	)
	(segment
		(start 145.617946 -227.740464)
		(end 145.515584 -227.564188)
		(width 0.0762)
		(layer "F.Cu")
		(net "M_G_CPU1_SA_DQS_DN<0>")
	)
	(segment
		(start 158.159704 -205.658466)
		(end 158.434786 -205.383384)
		(width 0.12954)
		(layer "F.Cu")
		(net "M_G_CPU1_SA_DQS_DN<0>")
	)
	(segment
		(start 146.630898 -227.360988)
		(end 147.15109 -226.840796)
		(width 0.0762)
		(layer "F.Cu")
		(net "M_G_CPU1_SA_DQS_DN<0>")
	)
	(segment
		(start 163.303712 -200.89749)
		(end 163.566602 -201.16038)
		(width 0.12954)
		(layer "F.Cu")
		(net "M_G_CPU1_SA_DQS_DN<0>")
	)
	(segment
		(start 158.434786 -205.383384)
		(end 158.434786 -205.146148)
		(width 0.12954)
		(layer "F.Cu")
		(net "M_G_CPU1_SA_DQS_DN<0>")
	)
	(segment
		(start 167.695626 -201.268076)
		(end 168.012872 -201.585322)
		(width 0.101346)
		(layer "F.Cu")
		(net "M_G_CPU1_SA_DQS_DN<0>")
	)
	(segment
		(start 147.668996 -226.125532)
		(end 147.682458 -226.11207)
		(width 0.0762)
		(layer "F.Cu")
		(net "M_G_CPU1_SA_DQS_DN<0>")
	)
	(segment
		(start 166.312342 -200.84288)
		(end 166.581582 -200.84288)
		(width 0.101346)
		(layer "F.Cu")
		(net "M_G_CPU1_SA_DQS_DN<0>")
	)
	(segment
		(start 158.70936 -204.871574)
		(end 158.946596 -204.871574)
		(width 0.12954)
		(layer "F.Cu")
		(net "M_G_CPU1_SA_DQS_DN<0>")
	)
	(segment
		(start 147.575524 -226.125532)
		(end 147.668996 -226.125532)
		(width 0.0762)
		(layer "F.Cu")
		(net "M_G_CPU1_SA_DQS_DN<0>")
	)
	(segment
		(start 147.15109 -226.840796)
		(end 147.15109 -226.549966)
		(width 0.0762)
		(layer "F.Cu")
		(net "M_G_CPU1_SA_DQS_DN<0>")
	)
	(segment
		(start 147.15109 -226.549966)
		(end 147.575524 -226.125532)
		(width 0.0762)
		(layer "F.Cu")
		(net "M_G_CPU1_SA_DQS_DN<0>")
	)
	(segment
		(start 157.63875 -205.942184)
		(end 157.922468 -205.658466)
		(width 0.12954)
		(layer "F.Cu")
		(net "M_G_CPU1_SA_DQS_DN<0>")
	)
	(segment
		(start 166.581582 -200.84288)
		(end 167.006778 -201.268076)
		(width 0.101346)
		(layer "F.Cu")
		(net "M_G_CPU1_SA_DQS_DN<0>")
	)
	(segment
		(start 159.221678 -204.596492)
		(end 159.221678 -204.359256)
		(width 0.12954)
		(layer "F.Cu")
		(net "M_G_CPU1_SA_DQS_DN<0>")
	)
	(segment
		(start 159.221678 -204.359256)
		(end 162.683444 -200.89749)
		(width 0.12954)
		(layer "F.Cu")
		(net "M_G_CPU1_SA_DQS_DN<0>")
	)
	(segment
		(start 165.994842 -201.16038)
		(end 166.312342 -200.84288)
		(width 0.101346)
		(layer "F.Cu")
		(net "M_G_CPU1_SA_DQS_DN<0>")
	)
	(segment
		(start 162.683444 -200.89749)
		(end 163.303712 -200.89749)
		(width 0.12954)
		(layer "F.Cu")
		(net "M_G_CPU1_SA_DQS_DN<0>")
	)
	(segment
		(start 146.087592 -227.494084)
		(end 146.309842 -227.494084)
		(width 0.0762)
		(layer "F.Cu")
		(net "M_G_CPU1_SA_DQS_DN<0>")
	)
	(segment
		(start 149.37613 -215.21928)
		(end 157.63875 -206.95666)
		(width 0.12954)
		(layer "F.Cu")
		(net "M_G_CPU1_SA_DQS_DN<0>")
	)
	(segment
		(start 147.682458 -226.11207)
		(end 149.37613 -224.418144)
		(width 0.12954)
		(layer "F.Cu")
		(net "M_G_CPU1_SA_DQS_DN<0>")
	)
	(segment
		(start 167.006778 -201.268076)
		(end 167.695626 -201.268076)
		(width 0.101346)
		(layer "F.Cu")
		(net "M_G_CPU1_SA_DQS_DN<0>")
	)
	(segment
		(start 146.309842 -227.494084)
		(end 146.630898 -227.360988)
		(width 0.0762)
		(layer "F.Cu")
		(net "M_G_CPU1_SA_DQS_DN<0>")
	)
	(segment
		(start 158.434786 -205.146148)
		(end 158.70936 -204.871574)
		(width 0.12954)
		(layer "F.Cu")
		(net "M_G_CPU1_SA_DQS_DN<0>")
	)
	(segment
		(start 158.946596 -204.871574)
		(end 159.221678 -204.596492)
		(width 0.12954)
		(layer "F.Cu")
		(net "M_G_CPU1_SA_DQS_DN<0>")
	)
	(segment
		(start 168.012872 -201.585322)
		(end 168.527984 -201.585322)
		(width 0.101346)
		(layer "F.Cu")
		(net "M_G_CPU1_SA_DQS_DN<0>")
	)
	(segment
		(start 163.566602 -201.16038)
		(end 165.994842 -201.16038)
		(width 0.101346)
		(layer "F.Cu")
		(net "M_G_CPU1_SA_DQS_DN<0>")
	)
	(segment
		(start 157.922468 -205.658466)
		(end 158.159704 -205.658466)
		(width 0.12954)
		(layer "F.Cu")
		(net "M_G_CPU1_SA_DQS_DN<0>")
	)
	(segment
		(start 149.37613 -224.418144)
		(end 149.37613 -215.21928)
		(width 0.12954)
		(layer "F.Cu")
		(net "M_G_CPU1_SA_DQS_DN<0>")
	)
	(segment
		(start 157.63875 -206.95666)
		(end 157.63875 -205.942184)
		(width 0.12954)
		(layer "F.Cu")
		(net "M_G_CPU1_SA_DQS_DN<0>")
	)
	(arc
		(start 145.682462 -227.37318)
		(mid 145.741108 -227.388473)
		(end 145.796508 -227.413058)
		(width 0.0762)
		(layer "F.Cu")
		(net "M_G_CPU1_SA_DQS_DN<0>")
	)
	(arc
		(start 145.80489 -227.417884)
		(mid 145.918614 -227.468185)
		(end 146.040602 -227.492306)
		(width 0.0762)
		(layer "F.Cu")
		(net "M_G_CPU1_SA_DQS_DN<0>")
	)
	(arc
		(start 146.040602 -227.492306)
		(mid 146.064079 -227.493682)
		(end 146.087592 -227.494084)
		(width 0.0762)
		(layer "F.Cu")
		(net "M_G_CPU1_SA_DQS_DN<0>")
	)
	(arc
		(start 145.515584 -227.564188)
		(mid 145.545213 -227.421701)
		(end 145.682462 -227.37318)
		(width 0.0762)
		(layer "F.Cu")
		(net "M_G_CPU1_SA_DQS_DN<0>")
	)
	(segment
		(start 165.686994 -208.810352)
		(end 166.111936 -208.38541)
		(width 0.101346)
		(layer "F.Cu")
		(net "M_G_CPU1_SA_DQ<9>")
	)
	(segment
		(start 152.900126 -225.735642)
		(end 152.900126 -218.66733)
		(width 0.10668)
		(layer "F.Cu")
		(net "M_G_CPU1_SA_DQ<9>")
	)
	(segment
		(start 166.111936 -208.38541)
		(end 168.527984 -208.38541)
		(width 0.101346)
		(layer "F.Cu")
		(net "M_G_CPU1_SA_DQ<9>")
	)
	(segment
		(start 147.168108 -231.034844)
		(end 147.600924 -231.034844)
		(width 0.0762)
		(layer "F.Cu")
		(net "M_G_CPU1_SA_DQ<9>")
	)
	(segment
		(start 145.796508 -231.30764)
		(end 145.80489 -231.302814)
		(width 0.0762)
		(layer "F.Cu")
		(net "M_G_CPU1_SA_DQ<9>")
	)
	(segment
		(start 147.600924 -231.034844)
		(end 152.900126 -225.735642)
		(width 0.10668)
		(layer "F.Cu")
		(net "M_G_CPU1_SA_DQ<9>")
	)
	(segment
		(start 155.46959 -216.097866)
		(end 155.46959 -214.986362)
		(width 0.10668)
		(layer "F.Cu")
		(net "M_G_CPU1_SA_DQ<9>")
	)
	(segment
		(start 163.377626 -208.810352)
		(end 165.686994 -208.810352)
		(width 0.101346)
		(layer "F.Cu")
		(net "M_G_CPU1_SA_DQ<9>")
	)
	(segment
		(start 155.46959 -214.986362)
		(end 161.6456 -208.810352)
		(width 0.10668)
		(layer "F.Cu")
		(net "M_G_CPU1_SA_DQ<9>")
	)
	(segment
		(start 146.50466 -231.114346)
		(end 147.088606 -231.114346)
		(width 0.0762)
		(layer "F.Cu")
		(net "M_G_CPU1_SA_DQ<9>")
	)
	(segment
		(start 147.088606 -231.114346)
		(end 147.168108 -231.034844)
		(width 0.0762)
		(layer "F.Cu")
		(net "M_G_CPU1_SA_DQ<9>")
	)
	(segment
		(start 161.6456 -208.810352)
		(end 163.377626 -208.810352)
		(width 0.10668)
		(layer "F.Cu")
		(net "M_G_CPU1_SA_DQ<9>")
	)
	(segment
		(start 152.900126 -218.66733)
		(end 155.46959 -216.097866)
		(width 0.10668)
		(layer "F.Cu")
		(net "M_G_CPU1_SA_DQ<9>")
	)
	(arc
		(start 145.80489 -231.302814)
		(mid 146.142314 -231.162324)
		(end 146.50466 -231.114346)
		(width 0.0762)
		(layer "F.Cu")
		(net "M_G_CPU1_SA_DQ<9>")
	)
	(arc
		(start 144.490948 -231.302814)
		(mid 144.677892 -231.353103)
		(end 144.864836 -231.302814)
		(width 0.0762)
		(layer "F.Cu")
		(net "M_G_CPU1_SA_DQ<9>")
	)
	(arc
		(start 143.737838 -230.980234)
		(mid 143.941803 -231.161083)
		(end 144.206468 -231.22636)
		(width 0.0762)
		(layer "F.Cu")
		(net "M_G_CPU1_SA_DQ<9>")
	)
	(arc
		(start 144.206468 -231.22636)
		(mid 144.353789 -231.245679)
		(end 144.490948 -231.302814)
		(width 0.0762)
		(layer "F.Cu")
		(net "M_G_CPU1_SA_DQ<9>")
	)
	(arc
		(start 145.430748 -231.302814)
		(mid 145.612999 -231.353198)
		(end 145.796508 -231.30764)
		(width 0.0762)
		(layer "F.Cu")
		(net "M_G_CPU1_SA_DQ<9>")
	)
	(arc
		(start 144.864836 -231.302814)
		(mid 145.147792 -231.226637)
		(end 145.430748 -231.302814)
		(width 0.0762)
		(layer "F.Cu")
		(net "M_G_CPU1_SA_DQ<9>")
	)
	(segment
		(start 167.020494 -207.11033)
		(end 167.445436 -206.685388)
		(width 0.101346)
		(layer "F.Cu")
		(net "M_G_CPU1_SA_DQ<8>")
	)
	(segment
		(start 147.12188 -230.310944)
		(end 147.361656 -230.310944)
		(width 0.0762)
		(layer "F.Cu")
		(net "M_G_CPU1_SA_DQ<8>")
	)
	(segment
		(start 147.361656 -230.310944)
		(end 152.219406 -225.453194)
		(width 0.10668)
		(layer "F.Cu")
		(net "M_G_CPU1_SA_DQ<8>")
	)
	(segment
		(start 152.219406 -217.273378)
		(end 162.382454 -207.11033)
		(width 0.10668)
		(layer "F.Cu")
		(net "M_G_CPU1_SA_DQ<8>")
	)
	(segment
		(start 163.377626 -207.11033)
		(end 167.020494 -207.11033)
		(width 0.101346)
		(layer "F.Cu")
		(net "M_G_CPU1_SA_DQ<8>")
	)
	(segment
		(start 162.382454 -207.11033)
		(end 163.377626 -207.11033)
		(width 0.10668)
		(layer "F.Cu")
		(net "M_G_CPU1_SA_DQ<8>")
	)
	(segment
		(start 146.111722 -230.549704)
		(end 146.88312 -230.549704)
		(width 0.0762)
		(layer "F.Cu")
		(net "M_G_CPU1_SA_DQ<8>")
	)
	(segment
		(start 146.88312 -230.549704)
		(end 147.12188 -230.310944)
		(width 0.0762)
		(layer "F.Cu")
		(net "M_G_CPU1_SA_DQ<8>")
	)
	(segment
		(start 167.445436 -206.685388)
		(end 168.527984 -206.685388)
		(width 0.101346)
		(layer "F.Cu")
		(net "M_G_CPU1_SA_DQ<8>")
	)
	(segment
		(start 152.219406 -225.453194)
		(end 152.219406 -217.273378)
		(width 0.10668)
		(layer "F.Cu")
		(net "M_G_CPU1_SA_DQ<8>")
	)
	(arc
		(start 145.900902 -230.492808)
		(mid 146.002542 -230.535223)
		(end 146.111722 -230.549704)
		(width 0.0762)
		(layer "F.Cu")
		(net "M_G_CPU1_SA_DQ<8>")
	)
	(arc
		(start 145.147792 -230.170228)
		(mid 145.38392 -230.341663)
		(end 145.665444 -230.418386)
		(width 0.0762)
		(layer "F.Cu")
		(net "M_G_CPU1_SA_DQ<8>")
	)
	(arc
		(start 145.665444 -230.418386)
		(mid 145.7873 -230.442542)
		(end 145.900902 -230.492808)
		(width 0.0762)
		(layer "F.Cu")
		(net "M_G_CPU1_SA_DQ<8>")
	)
	(segment
		(start 153.903426 -213.769956)
		(end 154.068526 -213.769956)
		(width 0.10668)
		(layer "F.Cu")
		(net "M_G_CPU1_SA_DQ<7>")
	)
	(segment
		(start 154.068526 -213.769956)
		(end 154.185874 -213.887304)
		(width 0.10668)
		(layer "F.Cu")
		(net "M_G_CPU1_SA_DQ<7>")
	)
	(segment
		(start 144.960848 -229.847902)
		(end 144.96923 -229.843076)
		(width 0.0762)
		(layer "F.Cu")
		(net "M_G_CPU1_SA_DQ<7>")
	)
	(segment
		(start 162.967416 -205.83525)
		(end 164.427916 -205.83525)
		(width 0.10668)
		(layer "F.Cu")
		(net "M_G_CPU1_SA_DQ<7>")
	)
	(segment
		(start 146.087846 -229.797864)
		(end 146.088354 -229.797356)
		(width 0.0762)
		(layer "F.Cu")
		(net "M_G_CPU1_SA_DQ<7>")
	)
	(segment
		(start 151.885142 -215.95334)
		(end 151.885142 -215.78824)
		(width 0.10668)
		(layer "F.Cu")
		(net "M_G_CPU1_SA_DQ<7>")
	)
	(segment
		(start 151.885142 -215.78824)
		(end 153.903426 -213.769956)
		(width 0.10668)
		(layer "F.Cu")
		(net "M_G_CPU1_SA_DQ<7>")
	)
	(segment
		(start 154.185874 -214.05215)
		(end 152.449784 -215.78824)
		(width 0.10668)
		(layer "F.Cu")
		(net "M_G_CPU1_SA_DQ<7>")
	)
	(segment
		(start 152.567132 -216.070434)
		(end 152.732232 -216.070434)
		(width 0.10668)
		(layer "F.Cu")
		(net "M_G_CPU1_SA_DQ<7>")
	)
	(segment
		(start 151.757126 -225.263456)
		(end 151.757126 -217.04554)
		(width 0.10668)
		(layer "F.Cu")
		(net "M_G_CPU1_SA_DQ<7>")
	)
	(segment
		(start 146.088354 -229.797356)
		(end 147.223226 -229.797356)
		(width 0.0762)
		(layer "F.Cu")
		(net "M_G_CPU1_SA_DQ<7>")
	)
	(segment
		(start 152.284938 -216.517728)
		(end 152.284938 -216.352628)
		(width 0.10668)
		(layer "F.Cu")
		(net "M_G_CPU1_SA_DQ<7>")
	)
	(segment
		(start 152.732232 -216.070434)
		(end 162.967416 -205.83525)
		(width 0.10668)
		(layer "F.Cu")
		(net "M_G_CPU1_SA_DQ<7>")
	)
	(segment
		(start 154.185874 -213.887304)
		(end 154.185874 -214.05215)
		(width 0.10668)
		(layer "F.Cu")
		(net "M_G_CPU1_SA_DQ<7>")
	)
	(segment
		(start 147.223226 -229.797356)
		(end 147.92579 -229.094792)
		(width 0.0762)
		(layer "F.Cu")
		(net "M_G_CPU1_SA_DQ<7>")
	)
	(segment
		(start 152.449784 -215.95334)
		(end 152.567132 -216.070434)
		(width 0.10668)
		(layer "F.Cu")
		(net "M_G_CPU1_SA_DQ<7>")
	)
	(segment
		(start 144.386554 -229.843076)
		(end 144.394936 -229.847902)
		(width 0.0762)
		(layer "F.Cu")
		(net "M_G_CPU1_SA_DQ<7>")
	)
	(segment
		(start 152.284938 -216.352628)
		(end 151.885142 -215.95334)
		(width 0.10668)
		(layer "F.Cu")
		(net "M_G_CPU1_SA_DQ<7>")
	)
	(segment
		(start 152.449784 -215.78824)
		(end 152.449784 -215.95334)
		(width 0.10668)
		(layer "F.Cu")
		(net "M_G_CPU1_SA_DQ<7>")
	)
	(segment
		(start 147.92579 -229.094792)
		(end 151.757126 -225.263456)
		(width 0.10668)
		(layer "F.Cu")
		(net "M_G_CPU1_SA_DQ<7>")
	)
	(segment
		(start 144.207992 -230.170228)
		(end 144.106138 -229.995222)
		(width 0.0762)
		(layer "F.Cu")
		(net "M_G_CPU1_SA_DQ<7>")
	)
	(segment
		(start 151.757126 -217.04554)
		(end 152.284938 -216.517728)
		(width 0.10668)
		(layer "F.Cu")
		(net "M_G_CPU1_SA_DQ<7>")
	)
	(arc
		(start 145.900902 -229.847902)
		(mid 145.991071 -229.810553)
		(end 146.087846 -229.797864)
		(width 0.0762)
		(layer "F.Cu")
		(net "M_G_CPU1_SA_DQ<7>")
	)
	(arc
		(start 145.33499 -229.847902)
		(mid 145.617946 -229.924079)
		(end 145.900902 -229.847902)
		(width 0.0762)
		(layer "F.Cu")
		(net "M_G_CPU1_SA_DQ<7>")
	)
	(arc
		(start 144.394936 -229.847902)
		(mid 144.677892 -229.924079)
		(end 144.960848 -229.847902)
		(width 0.0762)
		(layer "F.Cu")
		(net "M_G_CPU1_SA_DQ<7>")
	)
	(arc
		(start 144.106138 -229.995222)
		(mid 144.123332 -229.855636)
		(end 144.252696 -229.800404)
		(width 0.0762)
		(layer "F.Cu")
		(net "M_G_CPU1_SA_DQ<7>")
	)
	(arc
		(start 144.252696 -229.800404)
		(mid 144.321643 -229.815401)
		(end 144.386554 -229.843076)
		(width 0.0762)
		(layer "F.Cu")
		(net "M_G_CPU1_SA_DQ<7>")
	)
	(arc
		(start 144.96923 -229.843076)
		(mid 145.152738 -229.797582)
		(end 145.33499 -229.847902)
		(width 0.0762)
		(layer "F.Cu")
		(net "M_G_CPU1_SA_DQ<7>")
	)
	(segment
		(start 156.37256 -210.902042)
		(end 154.679396 -212.595206)
		(width 0.10668)
		(layer "F.Cu")
		(net "M_G_CPU1_SA_DQ<6>")
	)
	(segment
		(start 147.124166 -229.162864)
		(end 147.34667 -228.94036)
		(width 0.0762)
		(layer "F.Cu")
		(net "M_G_CPU1_SA_DQ<6>")
	)
	(segment
		(start 154.115008 -212.760306)
		(end 154.514296 -213.159594)
		(width 0.10668)
		(layer "F.Cu")
		(net "M_G_CPU1_SA_DQ<6>")
	)
	(segment
		(start 145.796508 -229.03307)
		(end 145.80489 -229.037896)
		(width 0.0762)
		(layer "F.Cu")
		(net "M_G_CPU1_SA_DQ<6>")
	)
	(segment
		(start 156.206952 -210.503262)
		(end 157.336236 -210.503262)
		(width 0.10668)
		(layer "F.Cu")
		(net "M_G_CPU1_SA_DQ<6>")
	)
	(segment
		(start 154.397202 -212.478112)
		(end 154.397202 -212.313012)
		(width 0.10668)
		(layer "F.Cu")
		(net "M_G_CPU1_SA_DQ<6>")
	)
	(segment
		(start 154.514296 -213.159594)
		(end 154.679396 -213.159594)
		(width 0.10668)
		(layer "F.Cu")
		(net "M_G_CPU1_SA_DQ<6>")
	)
	(segment
		(start 154.397202 -212.313012)
		(end 156.206952 -210.503262)
		(width 0.10668)
		(layer "F.Cu")
		(net "M_G_CPU1_SA_DQ<6>")
	)
	(segment
		(start 154.514296 -212.595206)
		(end 154.397202 -212.478112)
		(width 0.10668)
		(layer "F.Cu")
		(net "M_G_CPU1_SA_DQ<6>")
	)
	(segment
		(start 150.954486 -215.755728)
		(end 153.949908 -212.760306)
		(width 0.10668)
		(layer "F.Cu")
		(net "M_G_CPU1_SA_DQ<6>")
	)
	(segment
		(start 157.336236 -210.503262)
		(end 163.70427 -204.135228)
		(width 0.10668)
		(layer "F.Cu")
		(net "M_G_CPU1_SA_DQ<6>")
	)
	(segment
		(start 163.70427 -204.135228)
		(end 164.427916 -204.135228)
		(width 0.10668)
		(layer "F.Cu")
		(net "M_G_CPU1_SA_DQ<6>")
	)
	(segment
		(start 150.954486 -225.088704)
		(end 150.954486 -215.755728)
		(width 0.10668)
		(layer "F.Cu")
		(net "M_G_CPU1_SA_DQ<6>")
	)
	(segment
		(start 146.233388 -229.162864)
		(end 147.124166 -229.162864)
		(width 0.0762)
		(layer "F.Cu")
		(net "M_G_CPU1_SA_DQ<6>")
	)
	(segment
		(start 154.679396 -213.159594)
		(end 156.654754 -211.184236)
		(width 0.10668)
		(layer "F.Cu")
		(net "M_G_CPU1_SA_DQ<6>")
	)
	(segment
		(start 147.34667 -228.94036)
		(end 147.34667 -228.69652)
		(width 0.0762)
		(layer "F.Cu")
		(net "M_G_CPU1_SA_DQ<6>")
	)
	(segment
		(start 147.87499 -228.1682)
		(end 150.954486 -225.088704)
		(width 0.10668)
		(layer "F.Cu")
		(net "M_G_CPU1_SA_DQ<6>")
	)
	(segment
		(start 156.654754 -211.019136)
		(end 156.53766 -210.902042)
		(width 0.10668)
		(layer "F.Cu")
		(net "M_G_CPU1_SA_DQ<6>")
	)
	(segment
		(start 154.679396 -212.595206)
		(end 154.514296 -212.595206)
		(width 0.10668)
		(layer "F.Cu")
		(net "M_G_CPU1_SA_DQ<6>")
	)
	(segment
		(start 156.654754 -211.184236)
		(end 156.654754 -211.019136)
		(width 0.10668)
		(layer "F.Cu")
		(net "M_G_CPU1_SA_DQ<6>")
	)
	(segment
		(start 147.34667 -228.69652)
		(end 147.87499 -228.1682)
		(width 0.0762)
		(layer "F.Cu")
		(net "M_G_CPU1_SA_DQ<6>")
	)
	(segment
		(start 153.949908 -212.760306)
		(end 154.115008 -212.760306)
		(width 0.10668)
		(layer "F.Cu")
		(net "M_G_CPU1_SA_DQ<6>")
	)
	(segment
		(start 145.617946 -229.360476)
		(end 145.522188 -229.19563)
		(width 0.0762)
		(layer "F.Cu")
		(net "M_G_CPU1_SA_DQ<6>")
	)
	(segment
		(start 156.53766 -210.902042)
		(end 156.37256 -210.902042)
		(width 0.10668)
		(layer "F.Cu")
		(net "M_G_CPU1_SA_DQ<6>")
	)
	(arc
		(start 145.80489 -229.037896)
		(mid 146.010212 -229.130992)
		(end 146.233388 -229.162864)
		(width 0.0762)
		(layer "F.Cu")
		(net "M_G_CPU1_SA_DQ<6>")
	)
	(arc
		(start 145.522188 -229.19563)
		(mid 145.533378 -229.049074)
		(end 145.668238 -228.990906)
		(width 0.0762)
		(layer "F.Cu")
		(net "M_G_CPU1_SA_DQ<6>")
	)
	(arc
		(start 145.668238 -228.990906)
		(mid 145.734306 -229.006115)
		(end 145.796508 -229.03307)
		(width 0.0762)
		(layer "F.Cu")
		(net "M_G_CPU1_SA_DQ<6>")
	)
	(segment
		(start 147.070826 -229.606856)
		(end 147.60575 -229.071932)
		(width 0.0762)
		(layer "F.Cu")
		(net "M_G_CPU1_SA_DQ<5>")
	)
	(segment
		(start 166.283386 -204.985366)
		(end 168.527984 -204.985366)
		(width 0.101346)
		(layer "F.Cu")
		(net "M_G_CPU1_SA_DQ<5>")
	)
	(segment
		(start 154.096466 -213.316058)
		(end 154.468068 -213.68766)
		(width 0.10668)
		(layer "F.Cu")
		(net "M_G_CPU1_SA_DQ<5>")
	)
	(segment
		(start 153.87574 -213.316058)
		(end 154.096466 -213.316058)
		(width 0.10668)
		(layer "F.Cu")
		(net "M_G_CPU1_SA_DQ<5>")
	)
	(segment
		(start 154.468068 -213.68766)
		(end 154.633422 -213.68766)
		(width 0.10668)
		(layer "F.Cu")
		(net "M_G_CPU1_SA_DQ<5>")
	)
	(segment
		(start 147.60575 -228.919024)
		(end 147.93595 -228.588824)
		(width 0.0762)
		(layer "F.Cu")
		(net "M_G_CPU1_SA_DQ<5>")
	)
	(segment
		(start 163.377626 -205.410308)
		(end 165.858444 -205.410308)
		(width 0.101346)
		(layer "F.Cu")
		(net "M_G_CPU1_SA_DQ<5>")
	)
	(segment
		(start 147.93595 -228.588824)
		(end 151.355806 -225.168968)
		(width 0.10668)
		(layer "F.Cu")
		(net "M_G_CPU1_SA_DQ<5>")
	)
	(segment
		(start 162.910774 -205.410308)
		(end 163.377626 -205.410308)
		(width 0.10668)
		(layer "F.Cu")
		(net "M_G_CPU1_SA_DQ<5>")
	)
	(segment
		(start 165.858444 -205.410308)
		(end 166.283386 -204.985366)
		(width 0.101346)
		(layer "F.Cu")
		(net "M_G_CPU1_SA_DQ<5>")
	)
	(segment
		(start 151.355806 -215.835992)
		(end 153.87574 -213.316058)
		(width 0.10668)
		(layer "F.Cu")
		(net "M_G_CPU1_SA_DQ<5>")
	)
	(segment
		(start 145.796508 -229.687882)
		(end 145.80489 -229.683056)
		(width 0.0762)
		(layer "F.Cu")
		(net "M_G_CPU1_SA_DQ<5>")
	)
	(segment
		(start 151.355806 -225.168968)
		(end 151.355806 -215.835992)
		(width 0.10668)
		(layer "F.Cu")
		(net "M_G_CPU1_SA_DQ<5>")
	)
	(segment
		(start 147.60575 -229.071932)
		(end 147.60575 -228.919024)
		(width 0.0762)
		(layer "F.Cu")
		(net "M_G_CPU1_SA_DQ<5>")
	)
	(segment
		(start 154.633422 -213.68766)
		(end 162.910774 -205.410308)
		(width 0.10668)
		(layer "F.Cu")
		(net "M_G_CPU1_SA_DQ<5>")
	)
	(segment
		(start 146.087846 -229.606856)
		(end 147.070826 -229.606856)
		(width 0.0762)
		(layer "F.Cu")
		(net "M_G_CPU1_SA_DQ<5>")
	)
	(arc
		(start 145.80489 -229.683056)
		(mid 145.941326 -229.626231)
		(end 146.087846 -229.606856)
		(width 0.0762)
		(layer "F.Cu")
		(net "M_G_CPU1_SA_DQ<5>")
	)
	(arc
		(start 144.252188 -229.60838)
		(mid 144.264011 -229.609397)
		(end 144.27581 -229.610666)
		(width 0.0762)
		(layer "F.Cu")
		(net "M_G_CPU1_SA_DQ<5>")
	)
	(arc
		(start 144.490948 -229.683056)
		(mid 144.677892 -229.733311)
		(end 144.864836 -229.683056)
		(width 0.0762)
		(layer "F.Cu")
		(net "M_G_CPU1_SA_DQ<5>")
	)
	(arc
		(start 144.864836 -229.683056)
		(mid 145.147792 -229.606879)
		(end 145.430748 -229.683056)
		(width 0.0762)
		(layer "F.Cu")
		(net "M_G_CPU1_SA_DQ<5>")
	)
	(arc
		(start 145.430748 -229.683056)
		(mid 145.612999 -229.733406)
		(end 145.796508 -229.687882)
		(width 0.0762)
		(layer "F.Cu")
		(net "M_G_CPU1_SA_DQ<5>")
	)
	(arc
		(start 143.737838 -229.360476)
		(mid 143.971836 -229.532519)
		(end 144.252188 -229.60838)
		(width 0.0762)
		(layer "F.Cu")
		(net "M_G_CPU1_SA_DQ<5>")
	)
	(arc
		(start 144.27581 -229.610666)
		(mid 144.387056 -229.635929)
		(end 144.490948 -229.683056)
		(width 0.0762)
		(layer "F.Cu")
		(net "M_G_CPU1_SA_DQ<5>")
	)
	(segment
		(start 165.993318 -203.710286)
		(end 166.110158 -203.827126)
		(width 0.101346)
		(layer "F.Cu")
		(net "M_G_CPU1_SA_DQ<4>")
	)
	(segment
		(start 150.553166 -225.007932)
		(end 150.553166 -215.675464)
		(width 0.10668)
		(layer "F.Cu")
		(net "M_G_CPU1_SA_DQ<4>")
	)
	(segment
		(start 166.939468 -204.021944)
		(end 167.056308 -204.138784)
		(width 0.101346)
		(layer "F.Cu")
		(net "M_G_CPU1_SA_DQ<4>")
	)
	(segment
		(start 166.615618 -203.285344)
		(end 166.822628 -203.285344)
		(width 0.101346)
		(layer "F.Cu")
		(net "M_G_CPU1_SA_DQ<4>")
	)
	(segment
		(start 167.338248 -203.402184)
		(end 167.455088 -203.285344)
		(width 0.101346)
		(layer "F.Cu")
		(net "M_G_CPU1_SA_DQ<4>")
	)
	(segment
		(start 146.095212 -228.934264)
		(end 146.870674 -228.934264)
		(width 0.0762)
		(layer "F.Cu")
		(net "M_G_CPU1_SA_DQ<4>")
	)
	(segment
		(start 166.392098 -204.158088)
		(end 166.508938 -204.041248)
		(width 0.101346)
		(layer "F.Cu")
		(net "M_G_CPU1_SA_DQ<4>")
	)
	(segment
		(start 156.926788 -210.162902)
		(end 163.377626 -203.712064)
		(width 0.10668)
		(layer "F.Cu")
		(net "M_G_CPU1_SA_DQ<4>")
	)
	(segment
		(start 147.12315 -228.437948)
		(end 147.825968 -227.73513)
		(width 0.0762)
		(layer "F.Cu")
		(net "M_G_CPU1_SA_DQ<4>")
	)
	(segment
		(start 147.825968 -227.73513)
		(end 150.553166 -225.007932)
		(width 0.10668)
		(layer "F.Cu")
		(net "M_G_CPU1_SA_DQ<4>")
	)
	(segment
		(start 167.221408 -204.138784)
		(end 167.338248 -204.021944)
		(width 0.101346)
		(layer "F.Cu")
		(net "M_G_CPU1_SA_DQ<4>")
	)
	(segment
		(start 163.379404 -203.710286)
		(end 165.993318 -203.710286)
		(width 0.101346)
		(layer "F.Cu")
		(net "M_G_CPU1_SA_DQ<4>")
	)
	(segment
		(start 166.110158 -203.827126)
		(end 166.110158 -204.041248)
		(width 0.101346)
		(layer "F.Cu")
		(net "M_G_CPU1_SA_DQ<4>")
	)
	(segment
		(start 167.455088 -203.285344)
		(end 168.527984 -203.285344)
		(width 0.101346)
		(layer "F.Cu")
		(net "M_G_CPU1_SA_DQ<4>")
	)
	(segment
		(start 167.338248 -204.021944)
		(end 167.338248 -203.402184)
		(width 0.101346)
		(layer "F.Cu")
		(net "M_G_CPU1_SA_DQ<4>")
	)
	(segment
		(start 167.056308 -204.138784)
		(end 167.221408 -204.138784)
		(width 0.101346)
		(layer "F.Cu")
		(net "M_G_CPU1_SA_DQ<4>")
	)
	(segment
		(start 166.508938 -204.041248)
		(end 166.508938 -203.392024)
		(width 0.101346)
		(layer "F.Cu")
		(net "M_G_CPU1_SA_DQ<4>")
	)
	(segment
		(start 166.939468 -203.402184)
		(end 166.939468 -204.021944)
		(width 0.101346)
		(layer "F.Cu")
		(net "M_G_CPU1_SA_DQ<4>")
	)
	(segment
		(start 147.12315 -228.681788)
		(end 147.12315 -228.437948)
		(width 0.0762)
		(layer "F.Cu")
		(net "M_G_CPU1_SA_DQ<4>")
	)
	(segment
		(start 166.110158 -204.041248)
		(end 166.226998 -204.158088)
		(width 0.101346)
		(layer "F.Cu")
		(net "M_G_CPU1_SA_DQ<4>")
	)
	(segment
		(start 150.553166 -215.675464)
		(end 156.065728 -210.162902)
		(width 0.10668)
		(layer "F.Cu")
		(net "M_G_CPU1_SA_DQ<4>")
	)
	(segment
		(start 146.870674 -228.934264)
		(end 147.12315 -228.681788)
		(width 0.0762)
		(layer "F.Cu")
		(net "M_G_CPU1_SA_DQ<4>")
	)
	(segment
		(start 166.508938 -203.392024)
		(end 166.615618 -203.285344)
		(width 0.101346)
		(layer "F.Cu")
		(net "M_G_CPU1_SA_DQ<4>")
	)
	(segment
		(start 166.226998 -204.158088)
		(end 166.392098 -204.158088)
		(width 0.101346)
		(layer "F.Cu")
		(net "M_G_CPU1_SA_DQ<4>")
	)
	(segment
		(start 163.377626 -203.712064)
		(end 163.379404 -203.710286)
		(width 0.101346)
		(layer "F.Cu")
		(net "M_G_CPU1_SA_DQ<4>")
	)
	(segment
		(start 166.822628 -203.285344)
		(end 166.939468 -203.402184)
		(width 0.101346)
		(layer "F.Cu")
		(net "M_G_CPU1_SA_DQ<4>")
	)
	(segment
		(start 156.065728 -210.162902)
		(end 156.926788 -210.162902)
		(width 0.10668)
		(layer "F.Cu")
		(net "M_G_CPU1_SA_DQ<4>")
	)
	(arc
		(start 145.147792 -228.55047)
		(mid 145.384154 -228.722063)
		(end 145.665952 -228.798882)
		(width 0.0762)
		(layer "F.Cu")
		(net "M_G_CPU1_SA_DQ<4>")
	)
	(arc
		(start 145.900902 -228.87305)
		(mid 145.95879 -228.90155)
		(end 146.01952 -228.923342)
		(width 0.0762)
		(layer "F.Cu")
		(net "M_G_CPU1_SA_DQ<4>")
	)
	(arc
		(start 145.665952 -228.798882)
		(mid 145.787537 -228.822953)
		(end 145.900902 -228.87305)
		(width 0.0762)
		(layer "F.Cu")
		(net "M_G_CPU1_SA_DQ<4>")
	)
	(arc
		(start 146.01952 -228.923342)
		(mid 146.05697 -228.931555)
		(end 146.095212 -228.934264)
		(width 0.0762)
		(layer "F.Cu")
		(net "M_G_CPU1_SA_DQ<4>")
	)
	(segment
		(start 156.90596 -205.638146)
		(end 162.658806 -199.8853)
		(width 0.10668)
		(layer "F.Cu")
		(net "M_G_CPU1_SA_DQ<3>")
	)
	(segment
		(start 155.481274 -207.912208)
		(end 155.646374 -207.912208)
		(width 0.10668)
		(layer "F.Cu")
		(net "M_G_CPU1_SA_DQ<3>")
	)
	(segment
		(start 155.431236 -207.297528)
		(end 155.431236 -207.132428)
		(width 0.10668)
		(layer "F.Cu")
		(net "M_G_CPU1_SA_DQ<3>")
	)
	(segment
		(start 146.016472 -226.518978)
		(end 146.263106 -226.272344)
		(width 0.0762)
		(layer "F.Cu")
		(net "M_G_CPU1_SA_DQ<3>")
	)
	(segment
		(start 155.431236 -207.132428)
		(end 155.54833 -207.015334)
		(width 0.10668)
		(layer "F.Cu")
		(net "M_G_CPU1_SA_DQ<3>")
	)
	(segment
		(start 156.327856 -207.065626)
		(end 155.995624 -206.73314)
		(width 0.10668)
		(layer "F.Cu")
		(net "M_G_CPU1_SA_DQ<3>")
	)
	(segment
		(start 155.995624 -206.73314)
		(end 155.995624 -206.56804)
		(width 0.10668)
		(layer "F.Cu")
		(net "M_G_CPU1_SA_DQ<3>")
	)
	(segment
		(start 155.71343 -207.015334)
		(end 156.045662 -207.34782)
		(width 0.10668)
		(layer "F.Cu")
		(net "M_G_CPU1_SA_DQ<3>")
	)
	(segment
		(start 155.19908 -208.194402)
		(end 154.866848 -207.861916)
		(width 0.10668)
		(layer "F.Cu")
		(net "M_G_CPU1_SA_DQ<3>")
	)
	(segment
		(start 148.637244 -224.116646)
		(end 148.637244 -214.921338)
		(width 0.10668)
		(layer "F.Cu")
		(net "M_G_CPU1_SA_DQ<3>")
	)
	(segment
		(start 155.995624 -206.56804)
		(end 156.112718 -206.450946)
		(width 0.10668)
		(layer "F.Cu")
		(net "M_G_CPU1_SA_DQ<3>")
	)
	(segment
		(start 154.983942 -207.579722)
		(end 155.149042 -207.579722)
		(width 0.10668)
		(layer "F.Cu")
		(net "M_G_CPU1_SA_DQ<3>")
	)
	(segment
		(start 156.210762 -207.34782)
		(end 156.327856 -207.230726)
		(width 0.10668)
		(layer "F.Cu")
		(net "M_G_CPU1_SA_DQ<3>")
	)
	(segment
		(start 155.54833 -207.015334)
		(end 155.71343 -207.015334)
		(width 0.10668)
		(layer "F.Cu")
		(net "M_G_CPU1_SA_DQ<3>")
	)
	(segment
		(start 156.90596 -206.652622)
		(end 156.90596 -205.638146)
		(width 0.10668)
		(layer "F.Cu")
		(net "M_G_CPU1_SA_DQ<3>")
	)
	(segment
		(start 155.646374 -207.912208)
		(end 155.763468 -207.795114)
		(width 0.10668)
		(layer "F.Cu")
		(net "M_G_CPU1_SA_DQ<3>")
	)
	(segment
		(start 144.960848 -226.607878)
		(end 144.96923 -226.603052)
		(width 0.0762)
		(layer "F.Cu")
		(net "M_G_CPU1_SA_DQ<3>")
	)
	(segment
		(start 146.263106 -226.272344)
		(end 146.481546 -226.272344)
		(width 0.0762)
		(layer "F.Cu")
		(net "M_G_CPU1_SA_DQ<3>")
	)
	(segment
		(start 144.386554 -226.603052)
		(end 144.394936 -226.607878)
		(width 0.0762)
		(layer "F.Cu")
		(net "M_G_CPU1_SA_DQ<3>")
	)
	(segment
		(start 154.866848 -207.861916)
		(end 154.866848 -207.696816)
		(width 0.10668)
		(layer "F.Cu")
		(net "M_G_CPU1_SA_DQ<3>")
	)
	(segment
		(start 156.277818 -206.450946)
		(end 156.61005 -206.783432)
		(width 0.10668)
		(layer "F.Cu")
		(net "M_G_CPU1_SA_DQ<3>")
	)
	(segment
		(start 155.149042 -207.579722)
		(end 155.481274 -207.912208)
		(width 0.10668)
		(layer "F.Cu")
		(net "M_G_CPU1_SA_DQ<3>")
	)
	(segment
		(start 156.61005 -206.783432)
		(end 156.77515 -206.783432)
		(width 0.10668)
		(layer "F.Cu")
		(net "M_G_CPU1_SA_DQ<3>")
	)
	(segment
		(start 146.481546 -226.272344)
		(end 147.60575 -225.14814)
		(width 0.0762)
		(layer "F.Cu")
		(net "M_G_CPU1_SA_DQ<3>")
	)
	(segment
		(start 156.77515 -206.783432)
		(end 156.90596 -206.652622)
		(width 0.10668)
		(layer "F.Cu")
		(net "M_G_CPU1_SA_DQ<3>")
	)
	(segment
		(start 162.658806 -199.8853)
		(end 164.427916 -199.8853)
		(width 0.10668)
		(layer "F.Cu")
		(net "M_G_CPU1_SA_DQ<3>")
	)
	(segment
		(start 155.763468 -207.630014)
		(end 155.431236 -207.297528)
		(width 0.10668)
		(layer "F.Cu")
		(net "M_G_CPU1_SA_DQ<3>")
	)
	(segment
		(start 156.327856 -207.230726)
		(end 156.327856 -207.065626)
		(width 0.10668)
		(layer "F.Cu")
		(net "M_G_CPU1_SA_DQ<3>")
	)
	(segment
		(start 155.763468 -207.795114)
		(end 155.763468 -207.630014)
		(width 0.10668)
		(layer "F.Cu")
		(net "M_G_CPU1_SA_DQ<3>")
	)
	(segment
		(start 144.112742 -226.766374)
		(end 144.112742 -226.67341)
		(width 0.0762)
		(layer "F.Cu")
		(net "M_G_CPU1_SA_DQ<3>")
	)
	(segment
		(start 156.045662 -207.34782)
		(end 156.210762 -207.34782)
		(width 0.10668)
		(layer "F.Cu")
		(net "M_G_CPU1_SA_DQ<3>")
	)
	(segment
		(start 144.207992 -226.930458)
		(end 144.112742 -226.766374)
		(width 0.0762)
		(layer "F.Cu")
		(net "M_G_CPU1_SA_DQ<3>")
	)
	(segment
		(start 154.866848 -207.696816)
		(end 154.983942 -207.579722)
		(width 0.10668)
		(layer "F.Cu")
		(net "M_G_CPU1_SA_DQ<3>")
	)
	(segment
		(start 155.19908 -208.359502)
		(end 155.19908 -208.194402)
		(width 0.10668)
		(layer "F.Cu")
		(net "M_G_CPU1_SA_DQ<3>")
	)
	(segment
		(start 156.112718 -206.450946)
		(end 156.277818 -206.450946)
		(width 0.10668)
		(layer "F.Cu")
		(net "M_G_CPU1_SA_DQ<3>")
	)
	(segment
		(start 147.60575 -225.14814)
		(end 148.637244 -224.116646)
		(width 0.10668)
		(layer "F.Cu")
		(net "M_G_CPU1_SA_DQ<3>")
	)
	(segment
		(start 148.637244 -214.921338)
		(end 155.19908 -208.359502)
		(width 0.10668)
		(layer "F.Cu")
		(net "M_G_CPU1_SA_DQ<3>")
	)
	(arc
		(start 144.394936 -226.607878)
		(mid 144.677892 -226.684055)
		(end 144.960848 -226.607878)
		(width 0.0762)
		(layer "F.Cu")
		(net "M_G_CPU1_SA_DQ<3>")
	)
	(arc
		(start 144.112742 -226.67341)
		(mid 144.146159 -226.592229)
		(end 144.227042 -226.558094)
		(width 0.0762)
		(layer "F.Cu")
		(net "M_G_CPU1_SA_DQ<3>")
	)
	(arc
		(start 145.33499 -226.607878)
		(mid 145.69085 -226.67932)
		(end 146.016472 -226.518978)
		(width 0.0762)
		(layer "F.Cu")
		(net "M_G_CPU1_SA_DQ<3>")
	)
	(arc
		(start 144.227042 -226.558094)
		(mid 144.309333 -226.571585)
		(end 144.386554 -226.603052)
		(width 0.0762)
		(layer "F.Cu")
		(net "M_G_CPU1_SA_DQ<3>")
	)
	(arc
		(start 144.96923 -226.603052)
		(mid 145.152738 -226.557558)
		(end 145.33499 -226.607878)
		(width 0.0762)
		(layer "F.Cu")
		(net "M_G_CPU1_SA_DQ<3>")
	)
	(segment
		(start 154.013408 -243.944902)
		(end 154.178508 -243.944902)
		(width 0.10668)
		(layer "F.Cu")
		(net "M_G_CPU1_SA_DQ<31>")
	)
	(segment
		(start 153.731214 -244.392196)
		(end 153.731214 -244.227096)
		(width 0.10668)
		(layer "F.Cu")
		(net "M_G_CPU1_SA_DQ<31>")
	)
	(segment
		(start 163.46805 -234.65536)
		(end 163.46805 -234.066334)
		(width 0.10668)
		(layer "F.Cu")
		(net "M_G_CPU1_SA_DQ<31>")
	)
	(segment
		(start 155.023058 -242.136168)
		(end 155.140406 -242.253516)
		(width 0.10668)
		(layer "F.Cu")
		(net "M_G_CPU1_SA_DQ<31>")
	)
	(segment
		(start 153.494486 -244.628924)
		(end 153.731214 -244.392196)
		(width 0.10668)
		(layer "F.Cu")
		(net "M_G_CPU1_SA_DQ<31>")
	)
	(segment
		(start 153.331418 -243.662708)
		(end 154.857958 -242.136168)
		(width 0.10668)
		(layer "F.Cu")
		(net "M_G_CPU1_SA_DQ<31>")
	)
	(segment
		(start 147.170648 -244.628924)
		(end 147.715732 -244.628924)
		(width 0.0762)
		(layer "F.Cu")
		(net "M_G_CPU1_SA_DQ<31>")
	)
	(segment
		(start 163.46805 -234.066334)
		(end 163.649152 -233.885232)
		(width 0.10668)
		(layer "F.Cu")
		(net "M_G_CPU1_SA_DQ<31>")
	)
	(segment
		(start 153.89606 -243.662708)
		(end 153.89606 -243.827808)
		(width 0.10668)
		(layer "F.Cu")
		(net "M_G_CPU1_SA_DQ<31>")
	)
	(segment
		(start 155.140406 -242.253516)
		(end 155.140406 -242.418362)
		(width 0.10668)
		(layer "F.Cu")
		(net "M_G_CPU1_SA_DQ<31>")
	)
	(segment
		(start 155.140406 -242.418362)
		(end 153.89606 -243.662708)
		(width 0.10668)
		(layer "F.Cu")
		(net "M_G_CPU1_SA_DQ<31>")
	)
	(segment
		(start 144.38757 -244.423438)
		(end 144.394936 -244.427756)
		(width 0.0762)
		(layer "F.Cu")
		(net "M_G_CPU1_SA_DQ<31>")
	)
	(segment
		(start 153.731214 -244.227096)
		(end 153.331418 -243.827808)
		(width 0.10668)
		(layer "F.Cu")
		(net "M_G_CPU1_SA_DQ<31>")
	)
	(segment
		(start 147.715732 -244.628924)
		(end 153.494486 -244.628924)
		(width 0.10668)
		(layer "F.Cu")
		(net "M_G_CPU1_SA_DQ<31>")
	)
	(segment
		(start 153.331418 -243.827808)
		(end 153.331418 -243.662708)
		(width 0.10668)
		(layer "F.Cu")
		(net "M_G_CPU1_SA_DQ<31>")
	)
	(segment
		(start 146.914108 -244.372384)
		(end 147.170648 -244.628924)
		(width 0.0762)
		(layer "F.Cu")
		(net "M_G_CPU1_SA_DQ<31>")
	)
	(segment
		(start 163.649152 -233.885232)
		(end 164.427916 -233.885232)
		(width 0.10668)
		(layer "F.Cu")
		(net "M_G_CPU1_SA_DQ<31>")
	)
	(segment
		(start 153.89606 -243.827808)
		(end 154.013408 -243.944902)
		(width 0.10668)
		(layer "F.Cu")
		(net "M_G_CPU1_SA_DQ<31>")
	)
	(segment
		(start 144.207992 -244.750336)
		(end 144.207992 -244.750082)
		(width 0.0762)
		(layer "F.Cu")
		(net "M_G_CPU1_SA_DQ<31>")
	)
	(segment
		(start 154.178508 -243.944902)
		(end 163.46805 -234.65536)
		(width 0.10668)
		(layer "F.Cu")
		(net "M_G_CPU1_SA_DQ<31>")
	)
	(segment
		(start 144.386554 -244.42293)
		(end 144.38757 -244.423438)
		(width 0.0762)
		(layer "F.Cu")
		(net "M_G_CPU1_SA_DQ<31>")
	)
	(segment
		(start 144.207992 -244.750082)
		(end 144.102836 -244.569234)
		(width 0.0762)
		(layer "F.Cu")
		(net "M_G_CPU1_SA_DQ<31>")
	)
	(segment
		(start 146.106388 -244.372384)
		(end 146.914108 -244.372384)
		(width 0.0762)
		(layer "F.Cu")
		(net "M_G_CPU1_SA_DQ<31>")
	)
	(segment
		(start 154.857958 -242.136168)
		(end 155.023058 -242.136168)
		(width 0.10668)
		(layer "F.Cu")
		(net "M_G_CPU1_SA_DQ<31>")
	)
	(segment
		(start 144.960848 -244.427756)
		(end 144.96923 -244.42293)
		(width 0.0762)
		(layer "F.Cu")
		(net "M_G_CPU1_SA_DQ<31>")
	)
	(arc
		(start 145.900902 -244.427756)
		(mid 145.999975 -244.386442)
		(end 146.106388 -244.372384)
		(width 0.0762)
		(layer "F.Cu")
		(net "M_G_CPU1_SA_DQ<31>")
	)
	(arc
		(start 144.206468 -244.377464)
		(mid 144.299392 -244.388787)
		(end 144.386554 -244.42293)
		(width 0.0762)
		(layer "F.Cu")
		(net "M_G_CPU1_SA_DQ<31>")
	)
	(arc
		(start 144.102836 -244.569234)
		(mid 144.111773 -244.45021)
		(end 144.206468 -244.377464)
		(width 0.0762)
		(layer "F.Cu")
		(net "M_G_CPU1_SA_DQ<31>")
	)
	(arc
		(start 145.33499 -244.427756)
		(mid 145.617946 -244.503933)
		(end 145.900902 -244.427756)
		(width 0.0762)
		(layer "F.Cu")
		(net "M_G_CPU1_SA_DQ<31>")
	)
	(arc
		(start 144.96923 -244.42293)
		(mid 145.152738 -244.377436)
		(end 145.33499 -244.427756)
		(width 0.0762)
		(layer "F.Cu")
		(net "M_G_CPU1_SA_DQ<31>")
	)
	(arc
		(start 144.394936 -244.427756)
		(mid 144.677892 -244.503933)
		(end 144.960848 -244.427756)
		(width 0.0762)
		(layer "F.Cu")
		(net "M_G_CPU1_SA_DQ<31>")
	)
	(segment
		(start 145.617946 -243.94033)
		(end 145.524982 -243.78031)
		(width 0.0762)
		(layer "F.Cu")
		(net "M_G_CPU1_SA_DQ<30>")
	)
	(segment
		(start 157.302708 -239.127284)
		(end 157.302708 -239.292384)
		(width 0.10668)
		(layer "F.Cu")
		(net "M_G_CPU1_SA_DQ<30>")
	)
	(segment
		(start 157.185614 -239.01019)
		(end 157.302708 -239.127284)
		(width 0.10668)
		(layer "F.Cu")
		(net "M_G_CPU1_SA_DQ<30>")
	)
	(segment
		(start 147.373848 -243.818664)
		(end 147.49399 -243.938806)
		(width 0.0762)
		(layer "F.Cu")
		(net "M_G_CPU1_SA_DQ<30>")
	)
	(segment
		(start 152.091898 -243.938806)
		(end 157.020514 -239.01019)
		(width 0.10668)
		(layer "F.Cu")
		(net "M_G_CPU1_SA_DQ<30>")
	)
	(segment
		(start 146.762978 -243.818664)
		(end 147.373848 -243.818664)
		(width 0.0762)
		(layer "F.Cu")
		(net "M_G_CPU1_SA_DQ<30>")
	)
	(segment
		(start 155.716732 -241.442748)
		(end 162.78733 -234.37215)
		(width 0.10668)
		(layer "F.Cu")
		(net "M_G_CPU1_SA_DQ<30>")
	)
	(segment
		(start 147.82673 -243.938806)
		(end 152.091898 -243.938806)
		(width 0.10668)
		(layer "F.Cu")
		(net "M_G_CPU1_SA_DQ<30>")
	)
	(segment
		(start 145.796508 -243.612924)
		(end 145.80489 -243.61775)
		(width 0.0762)
		(layer "F.Cu")
		(net "M_G_CPU1_SA_DQ<30>")
	)
	(segment
		(start 157.020514 -239.01019)
		(end 157.185614 -239.01019)
		(width 0.10668)
		(layer "F.Cu")
		(net "M_G_CPU1_SA_DQ<30>")
	)
	(segment
		(start 155.434538 -241.160554)
		(end 155.434538 -241.325654)
		(width 0.10668)
		(layer "F.Cu")
		(net "M_G_CPU1_SA_DQ<30>")
	)
	(segment
		(start 157.302708 -239.292384)
		(end 155.434538 -241.160554)
		(width 0.10668)
		(layer "F.Cu")
		(net "M_G_CPU1_SA_DQ<30>")
	)
	(segment
		(start 162.78733 -233.031792)
		(end 163.633912 -232.18521)
		(width 0.10668)
		(layer "F.Cu")
		(net "M_G_CPU1_SA_DQ<30>")
	)
	(segment
		(start 155.434538 -241.325654)
		(end 155.551632 -241.442748)
		(width 0.10668)
		(layer "F.Cu")
		(net "M_G_CPU1_SA_DQ<30>")
	)
	(segment
		(start 147.49399 -243.938806)
		(end 147.82673 -243.938806)
		(width 0.0762)
		(layer "F.Cu")
		(net "M_G_CPU1_SA_DQ<30>")
	)
	(segment
		(start 155.551632 -241.442748)
		(end 155.716732 -241.442748)
		(width 0.10668)
		(layer "F.Cu")
		(net "M_G_CPU1_SA_DQ<30>")
	)
	(segment
		(start 163.633912 -232.18521)
		(end 164.427916 -232.18521)
		(width 0.10668)
		(layer "F.Cu")
		(net "M_G_CPU1_SA_DQ<30>")
	)
	(segment
		(start 162.78733 -234.37215)
		(end 162.78733 -233.031792)
		(width 0.10668)
		(layer "F.Cu")
		(net "M_G_CPU1_SA_DQ<30>")
	)
	(arc
		(start 145.887694 -243.65712)
		(mid 146.317948 -243.77791)
		(end 146.762978 -243.818664)
		(width 0.0762)
		(layer "F.Cu")
		(net "M_G_CPU1_SA_DQ<30>")
	)
	(arc
		(start 145.80489 -243.61775)
		(mid 145.845488 -243.639126)
		(end 145.887694 -243.65712)
		(width 0.0762)
		(layer "F.Cu")
		(net "M_G_CPU1_SA_DQ<30>")
	)
	(arc
		(start 145.524982 -243.78031)
		(mid 145.525142 -243.633749)
		(end 145.656808 -243.56949)
		(width 0.0762)
		(layer "F.Cu")
		(net "M_G_CPU1_SA_DQ<30>")
	)
	(arc
		(start 145.656808 -243.56949)
		(mid 145.728816 -243.584272)
		(end 145.796508 -243.612924)
		(width 0.0762)
		(layer "F.Cu")
		(net "M_G_CPU1_SA_DQ<30>")
	)
	(segment
		(start 152.9842 -209.375248)
		(end 153.1493 -209.375248)
		(width 0.10668)
		(layer "F.Cu")
		(net "M_G_CPU1_SA_DQ<2>")
	)
	(segment
		(start 151.266398 -210.479132)
		(end 151.266398 -210.314032)
		(width 0.10668)
		(layer "F.Cu")
		(net "M_G_CPU1_SA_DQ<2>")
	)
	(segment
		(start 150.726648 -211.6328)
		(end 150.891748 -211.6328)
		(width 0.10668)
		(layer "F.Cu")
		(net "M_G_CPU1_SA_DQ<2>")
	)
	(segment
		(start 152.702006 -209.657442)
		(end 152.395174 -209.350356)
		(width 0.10668)
		(layer "F.Cu")
		(net "M_G_CPU1_SA_DQ<2>")
	)
	(segment
		(start 152.395174 -209.350356)
		(end 152.395174 -209.185256)
		(width 0.10668)
		(layer "F.Cu")
		(net "M_G_CPU1_SA_DQ<2>")
	)
	(segment
		(start 152.959562 -208.785968)
		(end 152.959562 -208.620868)
		(width 0.10668)
		(layer "F.Cu")
		(net "M_G_CPU1_SA_DQ<2>")
	)
	(segment
		(start 150.254716 -211.325714)
		(end 150.419816 -211.325714)
		(width 0.10668)
		(layer "F.Cu")
		(net "M_G_CPU1_SA_DQ<2>")
	)
	(segment
		(start 152.11298 -209.63255)
		(end 152.419812 -209.939636)
		(width 0.10668)
		(layer "F.Cu")
		(net "M_G_CPU1_SA_DQ<2>")
	)
	(segment
		(start 152.419812 -209.939636)
		(end 152.584912 -209.939636)
		(width 0.10668)
		(layer "F.Cu")
		(net "M_G_CPU1_SA_DQ<2>")
	)
	(segment
		(start 152.512268 -209.068162)
		(end 152.677368 -209.068162)
		(width 0.10668)
		(layer "F.Cu")
		(net "M_G_CPU1_SA_DQ<2>")
	)
	(segment
		(start 150.819104 -210.761326)
		(end 150.984204 -210.761326)
		(width 0.10668)
		(layer "F.Cu")
		(net "M_G_CPU1_SA_DQ<2>")
	)
	(segment
		(start 148.725382 -212.855048)
		(end 150.254716 -211.325714)
		(width 0.10668)
		(layer "F.Cu")
		(net "M_G_CPU1_SA_DQ<2>")
	)
	(segment
		(start 150.70201 -210.87842)
		(end 150.819104 -210.761326)
		(width 0.10668)
		(layer "F.Cu")
		(net "M_G_CPU1_SA_DQ<2>")
	)
	(segment
		(start 153.1493 -209.375248)
		(end 153.266394 -209.258154)
		(width 0.10668)
		(layer "F.Cu")
		(net "M_G_CPU1_SA_DQ<2>")
	)
	(segment
		(start 152.137618 -210.38693)
		(end 152.137618 -210.22183)
		(width 0.10668)
		(layer "F.Cu")
		(net "M_G_CPU1_SA_DQ<2>")
	)
	(segment
		(start 152.395174 -209.185256)
		(end 152.512268 -209.068162)
		(width 0.10668)
		(layer "F.Cu")
		(net "M_G_CPU1_SA_DQ<2>")
	)
	(segment
		(start 151.855424 -210.504024)
		(end 152.020524 -210.504024)
		(width 0.10668)
		(layer "F.Cu")
		(net "M_G_CPU1_SA_DQ<2>")
	)
	(segment
		(start 151.57323 -210.951318)
		(end 151.57323 -210.786218)
		(width 0.10668)
		(layer "F.Cu")
		(net "M_G_CPU1_SA_DQ<2>")
	)
	(segment
		(start 151.383492 -210.196938)
		(end 151.548592 -210.196938)
		(width 0.10668)
		(layer "F.Cu")
		(net "M_G_CPU1_SA_DQ<2>")
	)
	(segment
		(start 152.020524 -210.504024)
		(end 152.137618 -210.38693)
		(width 0.10668)
		(layer "F.Cu")
		(net "M_G_CPU1_SA_DQ<2>")
	)
	(segment
		(start 151.456136 -211.068412)
		(end 151.57323 -210.951318)
		(width 0.10668)
		(layer "F.Cu")
		(net "M_G_CPU1_SA_DQ<2>")
	)
	(segment
		(start 151.830786 -209.749644)
		(end 151.94788 -209.63255)
		(width 0.10668)
		(layer "F.Cu")
		(net "M_G_CPU1_SA_DQ<2>")
	)
	(segment
		(start 146.956526 -225.154744)
		(end 146.956526 -224.71126)
		(width 0.0762)
		(layer "F.Cu")
		(net "M_G_CPU1_SA_DQ<2>")
	)
	(segment
		(start 152.137618 -210.22183)
		(end 151.830786 -209.914744)
		(width 0.10668)
		(layer "F.Cu")
		(net "M_G_CPU1_SA_DQ<2>")
	)
	(segment
		(start 150.984204 -210.761326)
		(end 151.291036 -211.068412)
		(width 0.10668)
		(layer "F.Cu")
		(net "M_G_CPU1_SA_DQ<2>")
	)
	(segment
		(start 147.956524 -214.71128)
		(end 148.725382 -212.855048)
		(width 0.10668)
		(layer "F.Cu")
		(net "M_G_CPU1_SA_DQ<2>")
	)
	(segment
		(start 146.050508 -225.68789)
		(end 146.42338 -225.68789)
		(width 0.0762)
		(layer "F.Cu")
		(net "M_G_CPU1_SA_DQ<2>")
	)
	(segment
		(start 152.677368 -209.068162)
		(end 152.9842 -209.375248)
		(width 0.10668)
		(layer "F.Cu")
		(net "M_G_CPU1_SA_DQ<2>")
	)
	(segment
		(start 147.956524 -223.711262)
		(end 147.956524 -214.71128)
		(width 0.10668)
		(layer "F.Cu")
		(net "M_G_CPU1_SA_DQ<2>")
	)
	(segment
		(start 147.038314 -224.629472)
		(end 147.956524 -223.711262)
		(width 0.10668)
		(layer "F.Cu")
		(net "M_G_CPU1_SA_DQ<2>")
	)
	(segment
		(start 152.702006 -209.822542)
		(end 152.702006 -209.657442)
		(width 0.10668)
		(layer "F.Cu")
		(net "M_G_CPU1_SA_DQ<2>")
	)
	(segment
		(start 150.419816 -211.325714)
		(end 150.726648 -211.6328)
		(width 0.10668)
		(layer "F.Cu")
		(net "M_G_CPU1_SA_DQ<2>")
	)
	(segment
		(start 151.291036 -211.068412)
		(end 151.456136 -211.068412)
		(width 0.10668)
		(layer "F.Cu")
		(net "M_G_CPU1_SA_DQ<2>")
	)
	(segment
		(start 146.956526 -224.71126)
		(end 147.038314 -224.629472)
		(width 0.0762)
		(layer "F.Cu")
		(net "M_G_CPU1_SA_DQ<2>")
	)
	(segment
		(start 150.891748 -211.6328)
		(end 151.008842 -211.515706)
		(width 0.10668)
		(layer "F.Cu")
		(net "M_G_CPU1_SA_DQ<2>")
	)
	(segment
		(start 146.42338 -225.68789)
		(end 146.956526 -225.154744)
		(width 0.0762)
		(layer "F.Cu")
		(net "M_G_CPU1_SA_DQ<2>")
	)
	(segment
		(start 150.70201 -211.04352)
		(end 150.70201 -210.87842)
		(width 0.10668)
		(layer "F.Cu")
		(net "M_G_CPU1_SA_DQ<2>")
	)
	(segment
		(start 151.57323 -210.786218)
		(end 151.266398 -210.479132)
		(width 0.10668)
		(layer "F.Cu")
		(net "M_G_CPU1_SA_DQ<2>")
	)
	(segment
		(start 151.548592 -210.196938)
		(end 151.855424 -210.504024)
		(width 0.10668)
		(layer "F.Cu")
		(net "M_G_CPU1_SA_DQ<2>")
	)
	(segment
		(start 152.584912 -209.939636)
		(end 152.702006 -209.822542)
		(width 0.10668)
		(layer "F.Cu")
		(net "M_G_CPU1_SA_DQ<2>")
	)
	(segment
		(start 153.266394 -209.258154)
		(end 153.266394 -209.093054)
		(width 0.10668)
		(layer "F.Cu")
		(net "M_G_CPU1_SA_DQ<2>")
	)
	(segment
		(start 151.008842 -211.515706)
		(end 151.008842 -211.350606)
		(width 0.10668)
		(layer "F.Cu")
		(net "M_G_CPU1_SA_DQ<2>")
	)
	(segment
		(start 163.395152 -198.185278)
		(end 164.427916 -198.185278)
		(width 0.10668)
		(layer "F.Cu")
		(net "M_G_CPU1_SA_DQ<2>")
	)
	(segment
		(start 151.008842 -211.350606)
		(end 150.70201 -211.04352)
		(width 0.10668)
		(layer "F.Cu")
		(net "M_G_CPU1_SA_DQ<2>")
	)
	(segment
		(start 151.94788 -209.63255)
		(end 152.11298 -209.63255)
		(width 0.10668)
		(layer "F.Cu")
		(net "M_G_CPU1_SA_DQ<2>")
	)
	(segment
		(start 151.830786 -209.914744)
		(end 151.830786 -209.749644)
		(width 0.10668)
		(layer "F.Cu")
		(net "M_G_CPU1_SA_DQ<2>")
	)
	(segment
		(start 153.266394 -209.093054)
		(end 152.959562 -208.785968)
		(width 0.10668)
		(layer "F.Cu")
		(net "M_G_CPU1_SA_DQ<2>")
	)
	(segment
		(start 151.266398 -210.314032)
		(end 151.383492 -210.196938)
		(width 0.10668)
		(layer "F.Cu")
		(net "M_G_CPU1_SA_DQ<2>")
	)
	(segment
		(start 152.959562 -208.620868)
		(end 163.395152 -198.185278)
		(width 0.10668)
		(layer "F.Cu")
		(net "M_G_CPU1_SA_DQ<2>")
	)
	(arc
		(start 145.617946 -226.120452)
		(mid 145.74464 -225.814584)
		(end 146.050508 -225.68789)
		(width 0.0762)
		(layer "F.Cu")
		(net "M_G_CPU1_SA_DQ<2>")
	)
	(segment
		(start 147.32635 -244.286786)
		(end 147.75561 -244.286786)
		(width 0.0762)
		(layer "F.Cu")
		(net "M_G_CPU1_SA_DQ<29>")
	)
	(segment
		(start 152.99817 -244.154706)
		(end 152.99817 -243.989606)
		(width 0.10668)
		(layer "F.Cu")
		(net "M_G_CPU1_SA_DQ<29>")
	)
	(segment
		(start 163.12769 -233.92511)
		(end 163.42487 -233.62793)
		(width 0.10668)
		(layer "F.Cu")
		(net "M_G_CPU1_SA_DQ<29>")
	)
	(segment
		(start 165.858444 -233.46029)
		(end 166.283386 -233.035348)
		(width 0.101346)
		(layer "F.Cu")
		(net "M_G_CPU1_SA_DQ<29>")
	)
	(segment
		(start 146.407632 -244.100604)
		(end 147.140168 -244.100604)
		(width 0.0762)
		(layer "F.Cu")
		(net "M_G_CPU1_SA_DQ<29>")
	)
	(segment
		(start 163.59251 -233.46029)
		(end 165.858444 -233.46029)
		(width 0.101346)
		(layer "F.Cu")
		(net "M_G_CPU1_SA_DQ<29>")
	)
	(segment
		(start 154.71648 -241.795808)
		(end 155.845764 -241.795808)
		(width 0.10668)
		(layer "F.Cu")
		(net "M_G_CPU1_SA_DQ<29>")
	)
	(segment
		(start 152.715976 -244.2718)
		(end 152.881076 -244.2718)
		(width 0.10668)
		(layer "F.Cu")
		(net "M_G_CPU1_SA_DQ<29>")
	)
	(segment
		(start 155.845764 -241.795808)
		(end 163.12769 -234.513882)
		(width 0.10668)
		(layer "F.Cu")
		(net "M_G_CPU1_SA_DQ<29>")
	)
	(segment
		(start 152.842976 -243.669312)
		(end 154.71648 -241.795808)
		(width 0.10668)
		(layer "F.Cu")
		(net "M_G_CPU1_SA_DQ<29>")
	)
	(segment
		(start 163.42487 -233.62793)
		(end 163.59251 -233.46029)
		(width 0.101346)
		(layer "F.Cu")
		(net "M_G_CPU1_SA_DQ<29>")
	)
	(segment
		(start 152.225502 -244.286786)
		(end 152.395682 -244.116606)
		(width 0.10668)
		(layer "F.Cu")
		(net "M_G_CPU1_SA_DQ<29>")
	)
	(segment
		(start 145.796508 -244.267736)
		(end 145.80489 -244.26291)
		(width 0.0762)
		(layer "F.Cu")
		(net "M_G_CPU1_SA_DQ<29>")
	)
	(segment
		(start 152.842976 -243.834412)
		(end 152.842976 -243.669312)
		(width 0.10668)
		(layer "F.Cu")
		(net "M_G_CPU1_SA_DQ<29>")
	)
	(segment
		(start 152.560782 -244.116606)
		(end 152.715976 -244.2718)
		(width 0.10668)
		(layer "F.Cu")
		(net "M_G_CPU1_SA_DQ<29>")
	)
	(segment
		(start 147.140168 -244.100604)
		(end 147.32635 -244.286786)
		(width 0.0762)
		(layer "F.Cu")
		(net "M_G_CPU1_SA_DQ<29>")
	)
	(segment
		(start 152.395682 -244.116606)
		(end 152.560782 -244.116606)
		(width 0.10668)
		(layer "F.Cu")
		(net "M_G_CPU1_SA_DQ<29>")
	)
	(segment
		(start 163.12769 -234.513882)
		(end 163.12769 -233.92511)
		(width 0.10668)
		(layer "F.Cu")
		(net "M_G_CPU1_SA_DQ<29>")
	)
	(segment
		(start 152.881076 -244.2718)
		(end 152.99817 -244.154706)
		(width 0.10668)
		(layer "F.Cu")
		(net "M_G_CPU1_SA_DQ<29>")
	)
	(segment
		(start 166.283386 -233.035348)
		(end 168.527984 -233.035348)
		(width 0.101346)
		(layer "F.Cu")
		(net "M_G_CPU1_SA_DQ<29>")
	)
	(segment
		(start 152.99817 -243.989606)
		(end 152.842976 -243.834412)
		(width 0.10668)
		(layer "F.Cu")
		(net "M_G_CPU1_SA_DQ<29>")
	)
	(segment
		(start 144.490948 -244.262656)
		(end 144.490948 -244.26291)
		(width 0.0762)
		(layer "F.Cu")
		(net "M_G_CPU1_SA_DQ<29>")
	)
	(segment
		(start 147.75561 -244.286786)
		(end 152.225502 -244.286786)
		(width 0.10668)
		(layer "F.Cu")
		(net "M_G_CPU1_SA_DQ<29>")
	)
	(arc
		(start 143.737838 -243.94033)
		(mid 143.941854 -244.121024)
		(end 144.206468 -244.186202)
		(width 0.0762)
		(layer "F.Cu")
		(net "M_G_CPU1_SA_DQ<29>")
	)
	(arc
		(start 144.864836 -244.26291)
		(mid 145.147792 -244.186733)
		(end 145.430748 -244.26291)
		(width 0.0762)
		(layer "F.Cu")
		(net "M_G_CPU1_SA_DQ<29>")
	)
	(arc
		(start 144.206468 -244.186202)
		(mid 144.353789 -244.205521)
		(end 144.490948 -244.262656)
		(width 0.0762)
		(layer "F.Cu")
		(net "M_G_CPU1_SA_DQ<29>")
	)
	(arc
		(start 145.80489 -244.26291)
		(mid 146.095523 -244.141873)
		(end 146.407632 -244.100604)
		(width 0.0762)
		(layer "F.Cu")
		(net "M_G_CPU1_SA_DQ<29>")
	)
	(arc
		(start 144.490948 -244.26291)
		(mid 144.677892 -244.313165)
		(end 144.864836 -244.26291)
		(width 0.0762)
		(layer "F.Cu")
		(net "M_G_CPU1_SA_DQ<29>")
	)
	(arc
		(start 145.430748 -244.26291)
		(mid 145.612999 -244.31326)
		(end 145.796508 -244.267736)
		(width 0.0762)
		(layer "F.Cu")
		(net "M_G_CPU1_SA_DQ<29>")
	)
	(segment
		(start 162.44697 -234.230926)
		(end 162.44697 -232.718356)
		(width 0.10668)
		(layer "F.Cu")
		(net "M_G_CPU1_SA_DQ<28>")
	)
	(segment
		(start 162.240722 -232.085134)
		(end 162.372294 -231.947974)
		(width 0.10668)
		(layer "F.Cu")
		(net "M_G_CPU1_SA_DQ<28>")
	)
	(segment
		(start 161.616136 -234.53344)
		(end 161.781236 -234.53344)
		(width 0.10668)
		(layer "F.Cu")
		(net "M_G_CPU1_SA_DQ<28>")
	)
	(segment
		(start 161.499042 -234.815634)
		(end 161.499042 -234.650534)
		(width 0.10668)
		(layer "F.Cu")
		(net "M_G_CPU1_SA_DQ<28>")
	)
	(segment
		(start 158.008066 -238.66983)
		(end 161.598102 -235.079794)
		(width 0.10668)
		(layer "F.Cu")
		(net "M_G_CPU1_SA_DQ<28>")
	)
	(segment
		(start 167.16756 -231.760268)
		(end 167.592502 -231.335326)
		(width 0.101346)
		(layer "F.Cu")
		(net "M_G_CPU1_SA_DQ<28>")
	)
	(segment
		(start 162.244532 -232.274364)
		(end 162.240722 -232.085134)
		(width 0.10668)
		(layer "F.Cu")
		(net "M_G_CPU1_SA_DQ<28>")
	)
	(segment
		(start 151.956516 -243.592604)
		(end 156.87929 -238.66983)
		(width 0.10668)
		(layer "F.Cu")
		(net "M_G_CPU1_SA_DQ<28>")
	)
	(segment
		(start 161.499042 -234.650534)
		(end 161.616136 -234.53344)
		(width 0.10668)
		(layer "F.Cu")
		(net "M_G_CPU1_SA_DQ<28>")
	)
	(segment
		(start 162.561778 -231.944164)
		(end 162.79241 -232.165398)
		(width 0.10668)
		(layer "F.Cu")
		(net "M_G_CPU1_SA_DQ<28>")
	)
	(segment
		(start 146.155156 -243.506244)
		(end 147.488148 -243.506244)
		(width 0.0762)
		(layer "F.Cu")
		(net "M_G_CPU1_SA_DQ<28>")
	)
	(segment
		(start 162.475418 -232.495598)
		(end 162.244532 -232.274364)
		(width 0.10668)
		(layer "F.Cu")
		(net "M_G_CPU1_SA_DQ<28>")
	)
	(segment
		(start 161.781236 -234.53344)
		(end 161.880296 -234.6325)
		(width 0.10668)
		(layer "F.Cu")
		(net "M_G_CPU1_SA_DQ<28>")
	)
	(segment
		(start 162.045396 -234.6325)
		(end 162.44697 -234.230926)
		(width 0.10668)
		(layer "F.Cu")
		(net "M_G_CPU1_SA_DQ<28>")
	)
	(segment
		(start 147.488148 -243.506244)
		(end 147.574508 -243.592604)
		(width 0.0762)
		(layer "F.Cu")
		(net "M_G_CPU1_SA_DQ<28>")
	)
	(segment
		(start 162.79241 -232.165398)
		(end 162.98164 -232.161588)
		(width 0.10668)
		(layer "F.Cu")
		(net "M_G_CPU1_SA_DQ<28>")
	)
	(segment
		(start 162.372294 -231.947974)
		(end 162.561778 -231.944164)
		(width 0.10668)
		(layer "F.Cu")
		(net "M_G_CPU1_SA_DQ<28>")
	)
	(segment
		(start 147.87499 -243.592604)
		(end 151.956516 -243.592604)
		(width 0.10668)
		(layer "F.Cu")
		(net "M_G_CPU1_SA_DQ<28>")
	)
	(segment
		(start 161.598102 -235.079794)
		(end 161.598102 -234.914694)
		(width 0.10668)
		(layer "F.Cu")
		(net "M_G_CPU1_SA_DQ<28>")
	)
	(segment
		(start 163.080192 -232.058718)
		(end 163.079938 -232.057956)
		(width 0.10668)
		(layer "F.Cu")
		(net "M_G_CPU1_SA_DQ<28>")
	)
	(segment
		(start 161.880296 -234.6325)
		(end 162.045396 -234.6325)
		(width 0.10668)
		(layer "F.Cu")
		(net "M_G_CPU1_SA_DQ<28>")
	)
	(segment
		(start 147.574508 -243.592604)
		(end 147.87499 -243.592604)
		(width 0.0762)
		(layer "F.Cu")
		(net "M_G_CPU1_SA_DQ<28>")
	)
	(segment
		(start 156.87929 -238.66983)
		(end 158.008066 -238.66983)
		(width 0.10668)
		(layer "F.Cu")
		(net "M_G_CPU1_SA_DQ<28>")
	)
	(segment
		(start 163.079938 -232.057956)
		(end 163.377626 -231.760268)
		(width 0.10668)
		(layer "F.Cu")
		(net "M_G_CPU1_SA_DQ<28>")
	)
	(segment
		(start 161.598102 -234.914694)
		(end 161.499042 -234.815634)
		(width 0.10668)
		(layer "F.Cu")
		(net "M_G_CPU1_SA_DQ<28>")
	)
	(segment
		(start 163.377626 -231.760268)
		(end 167.16756 -231.760268)
		(width 0.101346)
		(layer "F.Cu")
		(net "M_G_CPU1_SA_DQ<28>")
	)
	(segment
		(start 162.44697 -232.718356)
		(end 162.479228 -232.684828)
		(width 0.10668)
		(layer "F.Cu")
		(net "M_G_CPU1_SA_DQ<28>")
	)
	(segment
		(start 162.98164 -232.161588)
		(end 163.080192 -232.058718)
		(width 0.10668)
		(layer "F.Cu")
		(net "M_G_CPU1_SA_DQ<28>")
	)
	(segment
		(start 162.479228 -232.684828)
		(end 162.475418 -232.495598)
		(width 0.10668)
		(layer "F.Cu")
		(net "M_G_CPU1_SA_DQ<28>")
	)
	(segment
		(start 167.592502 -231.335326)
		(end 168.527984 -231.335326)
		(width 0.101346)
		(layer "F.Cu")
		(net "M_G_CPU1_SA_DQ<28>")
	)
	(arc
		(start 146.056858 -243.50218)
		(mid 146.105965 -243.505221)
		(end 146.155156 -243.506244)
		(width 0.0762)
		(layer "F.Cu")
		(net "M_G_CPU1_SA_DQ<28>")
	)
	(arc
		(start 145.665444 -243.378482)
		(mid 145.7873 -243.402638)
		(end 145.900902 -243.452904)
		(width 0.0762)
		(layer "F.Cu")
		(net "M_G_CPU1_SA_DQ<28>")
	)
	(arc
		(start 145.147792 -243.130324)
		(mid 145.38392 -243.301759)
		(end 145.665444 -243.378482)
		(width 0.0762)
		(layer "F.Cu")
		(net "M_G_CPU1_SA_DQ<28>")
	)
	(arc
		(start 145.900902 -243.452904)
		(mid 145.976142 -243.486217)
		(end 146.056858 -243.50218)
		(width 0.0762)
		(layer "F.Cu")
		(net "M_G_CPU1_SA_DQ<28>")
	)
	(segment
		(start 147.79879 -241.513106)
		(end 151.366474 -241.513106)
		(width 0.10668)
		(layer "F.Cu")
		(net "M_G_CPU1_SA_DQ<27>")
	)
	(segment
		(start 158.654242 -235.075222)
		(end 158.33979 -234.760516)
		(width 0.10668)
		(layer "F.Cu")
		(net "M_G_CPU1_SA_DQ<27>")
	)
	(segment
		(start 158.33979 -234.760516)
		(end 158.33979 -234.571032)
		(width 0.10668)
		(layer "F.Cu")
		(net "M_G_CPU1_SA_DQ<27>")
	)
	(segment
		(start 162.172904 -228.787706)
		(end 162.709098 -228.251512)
		(width 0.10668)
		(layer "F.Cu")
		(net "M_G_CPU1_SA_DQ<27>")
	)
	(segment
		(start 157.225746 -236.693202)
		(end 157.359858 -236.55909)
		(width 0.10668)
		(layer "F.Cu")
		(net "M_G_CPU1_SA_DQ<27>")
	)
	(segment
		(start 157.179518 -235.731304)
		(end 157.369002 -235.731304)
		(width 0.10668)
		(layer "F.Cu")
		(net "M_G_CPU1_SA_DQ<27>")
	)
	(segment
		(start 163.23564 -228.033326)
		(end 163.472622 -227.935282)
		(width 0.10668)
		(layer "F.Cu")
		(net "M_G_CPU1_SA_DQ<27>")
	)
	(segment
		(start 157.692598 -235.407708)
		(end 157.692598 -235.218224)
		(width 0.10668)
		(layer "F.Cu")
		(net "M_G_CPU1_SA_DQ<27>")
	)
	(segment
		(start 157.045406 -236.0549)
		(end 157.045406 -235.865416)
		(width 0.10668)
		(layer "F.Cu")
		(net "M_G_CPU1_SA_DQ<27>")
	)
	(segment
		(start 146.109944 -241.131344)
		(end 146.911568 -241.131344)
		(width 0.0762)
		(layer "F.Cu")
		(net "M_G_CPU1_SA_DQ<27>")
	)
	(segment
		(start 156.72181 -236.378496)
		(end 157.036262 -236.693202)
		(width 0.10668)
		(layer "F.Cu")
		(net "M_G_CPU1_SA_DQ<27>")
	)
	(segment
		(start 157.692598 -235.218224)
		(end 157.82671 -235.084112)
		(width 0.10668)
		(layer "F.Cu")
		(net "M_G_CPU1_SA_DQ<27>")
	)
	(segment
		(start 144.38757 -241.183414)
		(end 144.394936 -241.187732)
		(width 0.0762)
		(layer "F.Cu")
		(net "M_G_CPU1_SA_DQ<27>")
	)
	(segment
		(start 157.369002 -235.731304)
		(end 157.683454 -236.04601)
		(width 0.10668)
		(layer "F.Cu")
		(net "M_G_CPU1_SA_DQ<27>")
	)
	(segment
		(start 157.872938 -236.04601)
		(end 158.00705 -235.911898)
		(width 0.10668)
		(layer "F.Cu")
		(net "M_G_CPU1_SA_DQ<27>")
	)
	(segment
		(start 156.501084 -236.378496)
		(end 156.72181 -236.378496)
		(width 0.10668)
		(layer "F.Cu")
		(net "M_G_CPU1_SA_DQ<27>")
	)
	(segment
		(start 146.911568 -241.131344)
		(end 147.29333 -241.513106)
		(width 0.0762)
		(layer "F.Cu")
		(net "M_G_CPU1_SA_DQ<27>")
	)
	(segment
		(start 158.330646 -235.398818)
		(end 158.52013 -235.398818)
		(width 0.10668)
		(layer "F.Cu")
		(net "M_G_CPU1_SA_DQ<27>")
	)
	(segment
		(start 157.036262 -236.693202)
		(end 157.225746 -236.693202)
		(width 0.10668)
		(layer "F.Cu")
		(net "M_G_CPU1_SA_DQ<27>")
	)
	(segment
		(start 157.359858 -236.369606)
		(end 157.045406 -236.0549)
		(width 0.10668)
		(layer "F.Cu")
		(net "M_G_CPU1_SA_DQ<27>")
	)
	(segment
		(start 163.472622 -227.935282)
		(end 164.427916 -227.935282)
		(width 0.10668)
		(layer "F.Cu")
		(net "M_G_CPU1_SA_DQ<27>")
	)
	(segment
		(start 157.82671 -235.084112)
		(end 158.016194 -235.084112)
		(width 0.10668)
		(layer "F.Cu")
		(net "M_G_CPU1_SA_DQ<27>")
	)
	(segment
		(start 144.207992 -241.510058)
		(end 144.102836 -241.32921)
		(width 0.0762)
		(layer "F.Cu")
		(net "M_G_CPU1_SA_DQ<27>")
	)
	(segment
		(start 158.69412 -232.913936)
		(end 162.172904 -229.435152)
		(width 0.10668)
		(layer "F.Cu")
		(net "M_G_CPU1_SA_DQ<27>")
	)
	(segment
		(start 158.69412 -234.216702)
		(end 158.69412 -232.913936)
		(width 0.10668)
		(layer "F.Cu")
		(net "M_G_CPU1_SA_DQ<27>")
	)
	(segment
		(start 158.016194 -235.084112)
		(end 158.330646 -235.398818)
		(width 0.10668)
		(layer "F.Cu")
		(net "M_G_CPU1_SA_DQ<27>")
	)
	(segment
		(start 144.207992 -241.510312)
		(end 144.207992 -241.510058)
		(width 0.0762)
		(layer "F.Cu")
		(net "M_G_CPU1_SA_DQ<27>")
	)
	(segment
		(start 158.33979 -234.571032)
		(end 158.69412 -234.216702)
		(width 0.10668)
		(layer "F.Cu")
		(net "M_G_CPU1_SA_DQ<27>")
	)
	(segment
		(start 147.29333 -241.513106)
		(end 147.79879 -241.513106)
		(width 0.0762)
		(layer "F.Cu")
		(net "M_G_CPU1_SA_DQ<27>")
	)
	(segment
		(start 157.683454 -236.04601)
		(end 157.872938 -236.04601)
		(width 0.10668)
		(layer "F.Cu")
		(net "M_G_CPU1_SA_DQ<27>")
	)
	(segment
		(start 162.709098 -228.251512)
		(end 163.23564 -228.033326)
		(width 0.10668)
		(layer "F.Cu")
		(net "M_G_CPU1_SA_DQ<27>")
	)
	(segment
		(start 162.172904 -229.435152)
		(end 162.172904 -228.787706)
		(width 0.10668)
		(layer "F.Cu")
		(net "M_G_CPU1_SA_DQ<27>")
	)
	(segment
		(start 157.359858 -236.55909)
		(end 157.359858 -236.369606)
		(width 0.10668)
		(layer "F.Cu")
		(net "M_G_CPU1_SA_DQ<27>")
	)
	(segment
		(start 144.960848 -241.187732)
		(end 144.96923 -241.182906)
		(width 0.0762)
		(layer "F.Cu")
		(net "M_G_CPU1_SA_DQ<27>")
	)
	(segment
		(start 151.366474 -241.513106)
		(end 156.501084 -236.378496)
		(width 0.10668)
		(layer "F.Cu")
		(net "M_G_CPU1_SA_DQ<27>")
	)
	(segment
		(start 158.00705 -235.911898)
		(end 158.00705 -235.722414)
		(width 0.10668)
		(layer "F.Cu")
		(net "M_G_CPU1_SA_DQ<27>")
	)
	(segment
		(start 158.00705 -235.722414)
		(end 157.692598 -235.407708)
		(width 0.10668)
		(layer "F.Cu")
		(net "M_G_CPU1_SA_DQ<27>")
	)
	(segment
		(start 157.045406 -235.865416)
		(end 157.179518 -235.731304)
		(width 0.10668)
		(layer "F.Cu")
		(net "M_G_CPU1_SA_DQ<27>")
	)
	(segment
		(start 158.52013 -235.398818)
		(end 158.654242 -235.264706)
		(width 0.10668)
		(layer "F.Cu")
		(net "M_G_CPU1_SA_DQ<27>")
	)
	(segment
		(start 144.386554 -241.182906)
		(end 144.38757 -241.183414)
		(width 0.0762)
		(layer "F.Cu")
		(net "M_G_CPU1_SA_DQ<27>")
	)
	(segment
		(start 158.654242 -235.264706)
		(end 158.654242 -235.075222)
		(width 0.10668)
		(layer "F.Cu")
		(net "M_G_CPU1_SA_DQ<27>")
	)
	(arc
		(start 144.206468 -241.13744)
		(mid 144.299392 -241.148763)
		(end 144.386554 -241.182906)
		(width 0.0762)
		(layer "F.Cu")
		(net "M_G_CPU1_SA_DQ<27>")
	)
	(arc
		(start 145.900902 -241.187732)
		(mid 146.001694 -241.145726)
		(end 146.109944 -241.131344)
		(width 0.0762)
		(layer "F.Cu")
		(net "M_G_CPU1_SA_DQ<27>")
	)
	(arc
		(start 145.33499 -241.187732)
		(mid 145.617946 -241.263909)
		(end 145.900902 -241.187732)
		(width 0.0762)
		(layer "F.Cu")
		(net "M_G_CPU1_SA_DQ<27>")
	)
	(arc
		(start 144.102836 -241.32921)
		(mid 144.111773 -241.210186)
		(end 144.206468 -241.13744)
		(width 0.0762)
		(layer "F.Cu")
		(net "M_G_CPU1_SA_DQ<27>")
	)
	(arc
		(start 144.394936 -241.187732)
		(mid 144.677892 -241.263909)
		(end 144.960848 -241.187732)
		(width 0.0762)
		(layer "F.Cu")
		(net "M_G_CPU1_SA_DQ<27>")
	)
	(arc
		(start 144.96923 -241.182906)
		(mid 145.152738 -241.137412)
		(end 145.33499 -241.187732)
		(width 0.0762)
		(layer "F.Cu")
		(net "M_G_CPU1_SA_DQ<27>")
	)
	(segment
		(start 145.617946 -240.700306)
		(end 145.524982 -240.540286)
		(width 0.0762)
		(layer "F.Cu")
		(net "M_G_CPU1_SA_DQ<26>")
	)
	(segment
		(start 147.297648 -240.808764)
		(end 147.72005 -240.808764)
		(width 0.0762)
		(layer "F.Cu")
		(net "M_G_CPU1_SA_DQ<26>")
	)
	(segment
		(start 146.733006 -240.633504)
		(end 147.122388 -240.633504)
		(width 0.0762)
		(layer "F.Cu")
		(net "M_G_CPU1_SA_DQ<26>")
	)
	(segment
		(start 158.0134 -233.759756)
		(end 158.0134 -233.594656)
		(width 0.10668)
		(layer "F.Cu")
		(net "M_G_CPU1_SA_DQ<26>")
	)
	(segment
		(start 163.09213 -226.842066)
		(end 163.343082 -226.842066)
		(width 0.10668)
		(layer "F.Cu")
		(net "M_G_CPU1_SA_DQ<26>")
	)
	(segment
		(start 156.330396 -234.878372)
		(end 156.165296 -234.878372)
		(width 0.10668)
		(layer "F.Cu")
		(net "M_G_CPU1_SA_DQ<26>")
	)
	(segment
		(start 161.492184 -228.442012)
		(end 163.09213 -226.842066)
		(width 0.10668)
		(layer "F.Cu")
		(net "M_G_CPU1_SA_DQ<26>")
	)
	(segment
		(start 157.896306 -233.477562)
		(end 157.731206 -233.477562)
		(width 0.10668)
		(layer "F.Cu")
		(net "M_G_CPU1_SA_DQ<26>")
	)
	(segment
		(start 147.72005 -240.808764)
		(end 150.964392 -240.808764)
		(width 0.10668)
		(layer "F.Cu")
		(net "M_G_CPU1_SA_DQ<26>")
	)
	(segment
		(start 147.122388 -240.633504)
		(end 147.297648 -240.808764)
		(width 0.0762)
		(layer "F.Cu")
		(net "M_G_CPU1_SA_DQ<26>")
	)
	(segment
		(start 150.964392 -240.808764)
		(end 158.0134 -233.759756)
		(width 0.10668)
		(layer "F.Cu")
		(net "M_G_CPU1_SA_DQ<26>")
	)
	(segment
		(start 163.343082 -226.842066)
		(end 163.949888 -226.23526)
		(width 0.10668)
		(layer "F.Cu")
		(net "M_G_CPU1_SA_DQ<26>")
	)
	(segment
		(start 156.048202 -234.761278)
		(end 156.048202 -234.596178)
		(width 0.10668)
		(layer "F.Cu")
		(net "M_G_CPU1_SA_DQ<26>")
	)
	(segment
		(start 163.949888 -226.23526)
		(end 164.427916 -226.23526)
		(width 0.10668)
		(layer "F.Cu")
		(net "M_G_CPU1_SA_DQ<26>")
	)
	(segment
		(start 156.048202 -234.596178)
		(end 161.492184 -229.152196)
		(width 0.10668)
		(layer "F.Cu")
		(net "M_G_CPU1_SA_DQ<26>")
	)
	(segment
		(start 156.165296 -234.878372)
		(end 156.048202 -234.761278)
		(width 0.10668)
		(layer "F.Cu")
		(net "M_G_CPU1_SA_DQ<26>")
	)
	(segment
		(start 158.0134 -233.594656)
		(end 157.896306 -233.477562)
		(width 0.10668)
		(layer "F.Cu")
		(net "M_G_CPU1_SA_DQ<26>")
	)
	(segment
		(start 161.492184 -229.152196)
		(end 161.492184 -228.442012)
		(width 0.10668)
		(layer "F.Cu")
		(net "M_G_CPU1_SA_DQ<26>")
	)
	(segment
		(start 157.731206 -233.477562)
		(end 156.330396 -234.878372)
		(width 0.10668)
		(layer "F.Cu")
		(net "M_G_CPU1_SA_DQ<26>")
	)
	(arc
		(start 145.656808 -240.329466)
		(mid 145.728816 -240.344248)
		(end 145.796508 -240.3729)
		(width 0.0762)
		(layer "F.Cu")
		(net "M_G_CPU1_SA_DQ<26>")
	)
	(arc
		(start 145.524982 -240.540286)
		(mid 145.525142 -240.393725)
		(end 145.656808 -240.329466)
		(width 0.0762)
		(layer "F.Cu")
		(net "M_G_CPU1_SA_DQ<26>")
	)
	(arc
		(start 145.796508 -240.3729)
		(mid 146.246966 -240.567131)
		(end 146.733006 -240.633504)
		(width 0.0762)
		(layer "F.Cu")
		(net "M_G_CPU1_SA_DQ<26>")
	)
	(segment
		(start 145.796508 -241.027712)
		(end 145.80489 -241.022886)
		(width 0.0762)
		(layer "F.Cu")
		(net "M_G_CPU1_SA_DQ<25>")
	)
	(segment
		(start 147.079716 -240.941352)
		(end 147.608036 -241.160046)
		(width 0.0762)
		(layer "F.Cu")
		(net "M_G_CPU1_SA_DQ<25>")
	)
	(segment
		(start 163.377626 -227.606098)
		(end 163.608512 -227.51034)
		(width 0.101346)
		(layer "F.Cu")
		(net "M_G_CPU1_SA_DQ<25>")
	)
	(segment
		(start 161.832544 -228.594666)
		(end 162.427666 -227.999544)
		(width 0.10668)
		(layer "F.Cu")
		(net "M_G_CPU1_SA_DQ<25>")
	)
	(segment
		(start 158.35376 -232.772204)
		(end 161.832544 -229.29342)
		(width 0.10668)
		(layer "F.Cu")
		(net "M_G_CPU1_SA_DQ<25>")
	)
	(segment
		(start 162.427666 -227.999544)
		(end 163.23564 -227.664772)
		(width 0.10668)
		(layer "F.Cu")
		(net "M_G_CPU1_SA_DQ<25>")
	)
	(segment
		(start 165.79088 -227.51034)
		(end 166.816786 -227.085398)
		(width 0.101346)
		(layer "F.Cu")
		(net "M_G_CPU1_SA_DQ<25>")
	)
	(segment
		(start 166.816786 -227.085398)
		(end 168.527984 -227.085398)
		(width 0.101346)
		(layer "F.Cu")
		(net "M_G_CPU1_SA_DQ<25>")
	)
	(segment
		(start 147.608036 -241.160046)
		(end 147.81403 -241.160046)
		(width 0.0762)
		(layer "F.Cu")
		(net "M_G_CPU1_SA_DQ<25>")
	)
	(segment
		(start 163.23564 -227.664772)
		(end 163.377626 -227.606098)
		(width 0.10668)
		(layer "F.Cu")
		(net "M_G_CPU1_SA_DQ<25>")
	)
	(segment
		(start 147.81403 -241.160046)
		(end 151.23795 -241.160046)
		(width 0.10668)
		(layer "F.Cu")
		(net "M_G_CPU1_SA_DQ<25>")
	)
	(segment
		(start 163.608512 -227.51034)
		(end 165.79088 -227.51034)
		(width 0.101346)
		(layer "F.Cu")
		(net "M_G_CPU1_SA_DQ<25>")
	)
	(segment
		(start 161.832544 -229.29342)
		(end 161.832544 -228.594666)
		(width 0.10668)
		(layer "F.Cu")
		(net "M_G_CPU1_SA_DQ<25>")
	)
	(segment
		(start 146.119088 -240.938304)
		(end 147.076668 -240.938304)
		(width 0.0762)
		(layer "F.Cu")
		(net "M_G_CPU1_SA_DQ<25>")
	)
	(segment
		(start 147.076668 -240.938304)
		(end 147.079716 -240.941352)
		(width 0.0762)
		(layer "F.Cu")
		(net "M_G_CPU1_SA_DQ<25>")
	)
	(segment
		(start 151.23795 -241.160046)
		(end 158.35376 -234.044236)
		(width 0.10668)
		(layer "F.Cu")
		(net "M_G_CPU1_SA_DQ<25>")
	)
	(segment
		(start 158.35376 -234.044236)
		(end 158.35376 -232.772204)
		(width 0.10668)
		(layer "F.Cu")
		(net "M_G_CPU1_SA_DQ<25>")
	)
	(segment
		(start 144.490948 -241.022632)
		(end 144.490948 -241.022886)
		(width 0.0762)
		(layer "F.Cu")
		(net "M_G_CPU1_SA_DQ<25>")
	)
	(arc
		(start 143.737838 -240.700306)
		(mid 143.941854 -240.881)
		(end 144.206468 -240.946178)
		(width 0.0762)
		(layer "F.Cu")
		(net "M_G_CPU1_SA_DQ<25>")
	)
	(arc
		(start 145.430748 -241.022886)
		(mid 145.612999 -241.073236)
		(end 145.796508 -241.027712)
		(width 0.0762)
		(layer "F.Cu")
		(net "M_G_CPU1_SA_DQ<25>")
	)
	(arc
		(start 144.206468 -240.946178)
		(mid 144.353789 -240.965497)
		(end 144.490948 -241.022632)
		(width 0.0762)
		(layer "F.Cu")
		(net "M_G_CPU1_SA_DQ<25>")
	)
	(arc
		(start 145.80489 -241.022886)
		(mid 145.956387 -240.959767)
		(end 146.119088 -240.938304)
		(width 0.0762)
		(layer "F.Cu")
		(net "M_G_CPU1_SA_DQ<25>")
	)
	(arc
		(start 144.490948 -241.022886)
		(mid 144.677892 -241.073141)
		(end 144.864836 -241.022886)
		(width 0.0762)
		(layer "F.Cu")
		(net "M_G_CPU1_SA_DQ<25>")
	)
	(arc
		(start 144.864836 -241.022886)
		(mid 145.147792 -240.946709)
		(end 145.430748 -241.022886)
		(width 0.0762)
		(layer "F.Cu")
		(net "M_G_CPU1_SA_DQ<25>")
	)
	(segment
		(start 155.707842 -234.454954)
		(end 161.151824 -229.010972)
		(width 0.10668)
		(layer "F.Cu")
		(net "M_G_CPU1_SA_DQ<24>")
	)
	(segment
		(start 146.293586 -240.318544)
		(end 147.157948 -240.318544)
		(width 0.0762)
		(layer "F.Cu")
		(net "M_G_CPU1_SA_DQ<24>")
	)
	(segment
		(start 167.020494 -225.810318)
		(end 167.445436 -225.385376)
		(width 0.101346)
		(layer "F.Cu")
		(net "M_G_CPU1_SA_DQ<24>")
	)
	(segment
		(start 166.115238 -225.392742)
		(end 166.230554 -225.277426)
		(width 0.101346)
		(layer "F.Cu")
		(net "M_G_CPU1_SA_DQ<24>")
	)
	(segment
		(start 166.115238 -225.695002)
		(end 166.115238 -225.392742)
		(width 0.101346)
		(layer "F.Cu")
		(net "M_G_CPU1_SA_DQ<24>")
	)
	(segment
		(start 155.707842 -235.58373)
		(end 155.707842 -234.454954)
		(width 0.10668)
		(layer "F.Cu")
		(net "M_G_CPU1_SA_DQ<24>")
	)
	(segment
		(start 166.393622 -225.277426)
		(end 166.508938 -225.392742)
		(width 0.101346)
		(layer "F.Cu")
		(net "M_G_CPU1_SA_DQ<24>")
	)
	(segment
		(start 161.151824 -229.010972)
		(end 161.151824 -228.268276)
		(width 0.10668)
		(layer "F.Cu")
		(net "M_G_CPU1_SA_DQ<24>")
	)
	(segment
		(start 166.508938 -225.695002)
		(end 166.624254 -225.810318)
		(width 0.101346)
		(layer "F.Cu")
		(net "M_G_CPU1_SA_DQ<24>")
	)
	(segment
		(start 161.151824 -228.268276)
		(end 163.442142 -225.977958)
		(width 0.10668)
		(layer "F.Cu")
		(net "M_G_CPU1_SA_DQ<24>")
	)
	(segment
		(start 147.69719 -240.465864)
		(end 150.825708 -240.465864)
		(width 0.10668)
		(layer "F.Cu")
		(net "M_G_CPU1_SA_DQ<24>")
	)
	(segment
		(start 150.825708 -240.465864)
		(end 155.707842 -235.58373)
		(width 0.10668)
		(layer "F.Cu")
		(net "M_G_CPU1_SA_DQ<24>")
	)
	(segment
		(start 147.305268 -240.465864)
		(end 147.69719 -240.465864)
		(width 0.0762)
		(layer "F.Cu")
		(net "M_G_CPU1_SA_DQ<24>")
	)
	(segment
		(start 166.508938 -225.392742)
		(end 166.508938 -225.695002)
		(width 0.101346)
		(layer "F.Cu")
		(net "M_G_CPU1_SA_DQ<24>")
	)
	(segment
		(start 163.442142 -225.977958)
		(end 163.609782 -225.810318)
		(width 0.101346)
		(layer "F.Cu")
		(net "M_G_CPU1_SA_DQ<24>")
	)
	(segment
		(start 147.157948 -240.318544)
		(end 147.305268 -240.465864)
		(width 0.0762)
		(layer "F.Cu")
		(net "M_G_CPU1_SA_DQ<24>")
	)
	(segment
		(start 166.624254 -225.810318)
		(end 167.020494 -225.810318)
		(width 0.101346)
		(layer "F.Cu")
		(net "M_G_CPU1_SA_DQ<24>")
	)
	(segment
		(start 167.445436 -225.385376)
		(end 168.527984 -225.385376)
		(width 0.101346)
		(layer "F.Cu")
		(net "M_G_CPU1_SA_DQ<24>")
	)
	(segment
		(start 163.609782 -225.810318)
		(end 165.999922 -225.810318)
		(width 0.101346)
		(layer "F.Cu")
		(net "M_G_CPU1_SA_DQ<24>")
	)
	(segment
		(start 166.230554 -225.277426)
		(end 166.393622 -225.277426)
		(width 0.101346)
		(layer "F.Cu")
		(net "M_G_CPU1_SA_DQ<24>")
	)
	(segment
		(start 165.999922 -225.810318)
		(end 166.115238 -225.695002)
		(width 0.101346)
		(layer "F.Cu")
		(net "M_G_CPU1_SA_DQ<24>")
	)
	(arc
		(start 145.900902 -240.21288)
		(mid 146.090266 -240.291634)
		(end 146.293586 -240.318544)
		(width 0.0762)
		(layer "F.Cu")
		(net "M_G_CPU1_SA_DQ<24>")
	)
	(arc
		(start 145.147792 -239.8903)
		(mid 145.38392 -240.061735)
		(end 145.665444 -240.138458)
		(width 0.0762)
		(layer "F.Cu")
		(net "M_G_CPU1_SA_DQ<24>")
	)
	(arc
		(start 145.665444 -240.138458)
		(mid 145.7873 -240.162614)
		(end 145.900902 -240.21288)
		(width 0.0762)
		(layer "F.Cu")
		(net "M_G_CPU1_SA_DQ<24>")
	)
	(segment
		(start 163.651184 -224.535238)
		(end 164.427916 -224.535238)
		(width 0.10668)
		(layer "F.Cu")
		(net "M_G_CPU1_SA_DQ<23>")
	)
	(segment
		(start 144.386554 -239.562894)
		(end 144.38757 -239.563402)
		(width 0.0762)
		(layer "F.Cu")
		(net "M_G_CPU1_SA_DQ<23>")
	)
	(segment
		(start 150.636224 -240.008664)
		(end 155.250642 -235.394246)
		(width 0.10668)
		(layer "F.Cu")
		(net "M_G_CPU1_SA_DQ<23>")
	)
	(segment
		(start 147.63115 -240.008664)
		(end 150.636224 -240.008664)
		(width 0.10668)
		(layer "F.Cu")
		(net "M_G_CPU1_SA_DQ<23>")
	)
	(segment
		(start 146.872198 -239.510824)
		(end 147.370038 -240.008664)
		(width 0.0762)
		(layer "F.Cu")
		(net "M_G_CPU1_SA_DQ<23>")
	)
	(segment
		(start 155.250642 -235.229146)
		(end 155.133548 -235.112052)
		(width 0.10668)
		(layer "F.Cu")
		(net "M_G_CPU1_SA_DQ<23>")
	)
	(segment
		(start 146.111976 -239.510824)
		(end 146.872198 -239.510824)
		(width 0.0762)
		(layer "F.Cu")
		(net "M_G_CPU1_SA_DQ<23>")
	)
	(segment
		(start 144.207992 -239.890046)
		(end 144.102836 -239.709198)
		(width 0.0762)
		(layer "F.Cu")
		(net "M_G_CPU1_SA_DQ<23>")
	)
	(segment
		(start 144.960848 -239.56772)
		(end 144.96923 -239.562894)
		(width 0.0762)
		(layer "F.Cu")
		(net "M_G_CPU1_SA_DQ<23>")
	)
	(segment
		(start 155.133548 -235.112052)
		(end 154.968448 -235.112052)
		(width 0.10668)
		(layer "F.Cu")
		(net "M_G_CPU1_SA_DQ<23>")
	)
	(segment
		(start 144.38757 -239.563402)
		(end 144.394936 -239.56772)
		(width 0.0762)
		(layer "F.Cu")
		(net "M_G_CPU1_SA_DQ<23>")
	)
	(segment
		(start 160.694624 -228.821488)
		(end 160.694624 -228.05263)
		(width 0.10668)
		(layer "F.Cu")
		(net "M_G_CPU1_SA_DQ<23>")
	)
	(segment
		(start 152.757378 -236.758734)
		(end 160.694624 -228.821488)
		(width 0.10668)
		(layer "F.Cu")
		(net "M_G_CPU1_SA_DQ<23>")
	)
	(segment
		(start 155.250642 -235.394246)
		(end 155.250642 -235.229146)
		(width 0.10668)
		(layer "F.Cu")
		(net "M_G_CPU1_SA_DQ<23>")
	)
	(segment
		(start 163.498276 -224.688146)
		(end 163.651184 -224.535238)
		(width 0.10668)
		(layer "F.Cu")
		(net "M_G_CPU1_SA_DQ<23>")
	)
	(segment
		(start 144.207992 -239.8903)
		(end 144.207992 -239.890046)
		(width 0.0762)
		(layer "F.Cu")
		(net "M_G_CPU1_SA_DQ<23>")
	)
	(segment
		(start 154.968448 -235.112052)
		(end 153.039572 -237.040928)
		(width 0.10668)
		(layer "F.Cu")
		(net "M_G_CPU1_SA_DQ<23>")
	)
	(segment
		(start 152.874472 -237.040928)
		(end 152.757378 -236.923834)
		(width 0.10668)
		(layer "F.Cu")
		(net "M_G_CPU1_SA_DQ<23>")
	)
	(segment
		(start 153.039572 -237.040928)
		(end 152.874472 -237.040928)
		(width 0.10668)
		(layer "F.Cu")
		(net "M_G_CPU1_SA_DQ<23>")
	)
	(segment
		(start 152.757378 -236.923834)
		(end 152.757378 -236.758734)
		(width 0.10668)
		(layer "F.Cu")
		(net "M_G_CPU1_SA_DQ<23>")
	)
	(segment
		(start 147.370038 -240.008664)
		(end 147.63115 -240.008664)
		(width 0.0762)
		(layer "F.Cu")
		(net "M_G_CPU1_SA_DQ<23>")
	)
	(segment
		(start 163.498276 -225.248978)
		(end 163.498276 -224.688146)
		(width 0.10668)
		(layer "F.Cu")
		(net "M_G_CPU1_SA_DQ<23>")
	)
	(segment
		(start 160.694624 -228.05263)
		(end 163.498276 -225.248978)
		(width 0.10668)
		(layer "F.Cu")
		(net "M_G_CPU1_SA_DQ<23>")
	)
	(arc
		(start 144.102836 -239.709198)
		(mid 144.111773 -239.590174)
		(end 144.206468 -239.517428)
		(width 0.0762)
		(layer "F.Cu")
		(net "M_G_CPU1_SA_DQ<23>")
	)
	(arc
		(start 145.900902 -239.56772)
		(mid 146.00267 -239.525286)
		(end 146.111976 -239.510824)
		(width 0.0762)
		(layer "F.Cu")
		(net "M_G_CPU1_SA_DQ<23>")
	)
	(arc
		(start 144.394936 -239.56772)
		(mid 144.677892 -239.643897)
		(end 144.960848 -239.56772)
		(width 0.0762)
		(layer "F.Cu")
		(net "M_G_CPU1_SA_DQ<23>")
	)
	(arc
		(start 144.96923 -239.562894)
		(mid 145.152738 -239.5174)
		(end 145.33499 -239.56772)
		(width 0.0762)
		(layer "F.Cu")
		(net "M_G_CPU1_SA_DQ<23>")
	)
	(arc
		(start 144.206468 -239.517428)
		(mid 144.299392 -239.528751)
		(end 144.386554 -239.562894)
		(width 0.0762)
		(layer "F.Cu")
		(net "M_G_CPU1_SA_DQ<23>")
	)
	(arc
		(start 145.33499 -239.56772)
		(mid 145.617946 -239.643897)
		(end 145.900902 -239.56772)
		(width 0.0762)
		(layer "F.Cu")
		(net "M_G_CPU1_SA_DQ<23>")
	)
	(segment
		(start 149.960584 -238.75746)
		(end 149.960584 -238.59236)
		(width 0.10668)
		(layer "F.Cu")
		(net "M_G_CPU1_SA_DQ<22>")
	)
	(segment
		(start 149.081236 -239.327944)
		(end 149.198076 -239.211104)
		(width 0.10668)
		(layer "F.Cu")
		(net "M_G_CPU1_SA_DQ<22>")
	)
	(segment
		(start 151.513286 -237.769146)
		(end 151.348186 -237.769146)
		(width 0.10668)
		(layer "F.Cu")
		(net "M_G_CPU1_SA_DQ<22>")
	)
	(segment
		(start 146.457416 -238.936784)
		(end 146.949668 -238.936784)
		(width 0.0762)
		(layer "F.Cu")
		(net "M_G_CPU1_SA_DQ<22>")
	)
	(segment
		(start 161.36366 -225.561144)
		(end 161.480754 -225.44405)
		(width 0.10668)
		(layer "F.Cu")
		(net "M_G_CPU1_SA_DQ<22>")
	)
	(segment
		(start 162.189922 -225.588576)
		(end 162.189922 -225.423476)
		(width 0.10668)
		(layer "F.Cu")
		(net "M_G_CPU1_SA_DQ<22>")
	)
	(segment
		(start 148.283168 -239.327944)
		(end 148.400008 -239.211104)
		(width 0.10668)
		(layer "F.Cu")
		(net "M_G_CPU1_SA_DQ<22>")
	)
	(segment
		(start 145.617946 -239.080294)
		(end 145.524982 -238.920274)
		(width 0.0762)
		(layer "F.Cu")
		(net "M_G_CPU1_SA_DQ<22>")
	)
	(segment
		(start 161.928048 -224.996756)
		(end 162.045142 -224.879662)
		(width 0.10668)
		(layer "F.Cu")
		(net "M_G_CPU1_SA_DQ<22>")
	)
	(segment
		(start 160.013904 -227.764594)
		(end 161.625534 -226.152964)
		(width 0.10668)
		(layer "F.Cu")
		(net "M_G_CPU1_SA_DQ<22>")
	)
	(segment
		(start 151.63038 -238.05134)
		(end 151.63038 -237.88624)
		(width 0.10668)
		(layer "F.Cu")
		(net "M_G_CPU1_SA_DQ<22>")
	)
	(segment
		(start 147.884134 -238.942626)
		(end 148.000974 -239.059466)
		(width 0.10668)
		(layer "F.Cu")
		(net "M_G_CPU1_SA_DQ<22>")
	)
	(segment
		(start 161.625534 -225.987864)
		(end 161.36366 -225.726244)
		(width 0.10668)
		(layer "F.Cu")
		(net "M_G_CPU1_SA_DQ<22>")
	)
	(segment
		(start 148.799042 -239.211104)
		(end 148.915882 -239.327944)
		(width 0.10668)
		(layer "F.Cu")
		(net "M_G_CPU1_SA_DQ<22>")
	)
	(segment
		(start 161.36366 -225.726244)
		(end 161.36366 -225.561144)
		(width 0.10668)
		(layer "F.Cu")
		(net "M_G_CPU1_SA_DQ<22>")
	)
	(segment
		(start 161.625534 -226.152964)
		(end 161.625534 -225.987864)
		(width 0.10668)
		(layer "F.Cu")
		(net "M_G_CPU1_SA_DQ<22>")
	)
	(segment
		(start 148.000974 -239.059466)
		(end 148.000974 -239.211104)
		(width 0.10668)
		(layer "F.Cu")
		(net "M_G_CPU1_SA_DQ<22>")
	)
	(segment
		(start 162.637216 -225.141282)
		(end 162.817556 -224.960942)
		(width 0.10668)
		(layer "F.Cu")
		(net "M_G_CPU1_SA_DQ<22>")
	)
	(segment
		(start 148.400008 -239.059466)
		(end 148.516848 -238.942626)
		(width 0.10668)
		(layer "F.Cu")
		(net "M_G_CPU1_SA_DQ<22>")
	)
	(segment
		(start 162.210242 -224.879662)
		(end 162.472116 -225.141282)
		(width 0.10668)
		(layer "F.Cu")
		(net "M_G_CPU1_SA_DQ<22>")
	)
	(segment
		(start 161.645854 -225.44405)
		(end 161.907728 -225.70567)
		(width 0.10668)
		(layer "F.Cu")
		(net "M_G_CPU1_SA_DQ<22>")
	)
	(segment
		(start 147.60194 -239.211104)
		(end 147.60194 -239.059466)
		(width 0.10668)
		(layer "F.Cu")
		(net "M_G_CPU1_SA_DQ<22>")
	)
	(segment
		(start 162.817556 -223.949006)
		(end 163.931346 -222.835216)
		(width 0.10668)
		(layer "F.Cu")
		(net "M_G_CPU1_SA_DQ<22>")
	)
	(segment
		(start 150.242778 -238.874554)
		(end 150.077678 -238.874554)
		(width 0.10668)
		(layer "F.Cu")
		(net "M_G_CPU1_SA_DQ<22>")
	)
	(segment
		(start 161.480754 -225.44405)
		(end 161.645854 -225.44405)
		(width 0.10668)
		(layer "F.Cu")
		(net "M_G_CPU1_SA_DQ<22>")
	)
	(segment
		(start 149.198076 -239.059466)
		(end 149.314916 -238.942626)
		(width 0.10668)
		(layer "F.Cu")
		(net "M_G_CPU1_SA_DQ<22>")
	)
	(segment
		(start 160.013904 -228.53904)
		(end 160.013904 -227.764594)
		(width 0.10668)
		(layer "F.Cu")
		(net "M_G_CPU1_SA_DQ<22>")
	)
	(segment
		(start 147.340828 -239.327944)
		(end 147.4851 -239.327944)
		(width 0.10668)
		(layer "F.Cu")
		(net "M_G_CPU1_SA_DQ<22>")
	)
	(segment
		(start 151.348186 -237.769146)
		(end 150.242778 -238.874554)
		(width 0.10668)
		(layer "F.Cu")
		(net "M_G_CPU1_SA_DQ<22>")
	)
	(segment
		(start 147.4851 -239.327944)
		(end 147.60194 -239.211104)
		(width 0.10668)
		(layer "F.Cu")
		(net "M_G_CPU1_SA_DQ<22>")
	)
	(segment
		(start 162.045142 -224.879662)
		(end 162.210242 -224.879662)
		(width 0.10668)
		(layer "F.Cu")
		(net "M_G_CPU1_SA_DQ<22>")
	)
	(segment
		(start 147.60194 -239.059466)
		(end 147.71878 -238.942626)
		(width 0.10668)
		(layer "F.Cu")
		(net "M_G_CPU1_SA_DQ<22>")
	)
	(segment
		(start 162.072828 -225.70567)
		(end 162.189922 -225.588576)
		(width 0.10668)
		(layer "F.Cu")
		(net "M_G_CPU1_SA_DQ<22>")
	)
	(segment
		(start 150.077678 -238.874554)
		(end 149.960584 -238.75746)
		(width 0.10668)
		(layer "F.Cu")
		(net "M_G_CPU1_SA_DQ<22>")
	)
	(segment
		(start 150.353776 -239.327944)
		(end 151.63038 -238.05134)
		(width 0.10668)
		(layer "F.Cu")
		(net "M_G_CPU1_SA_DQ<22>")
	)
	(segment
		(start 162.817556 -224.960942)
		(end 162.817556 -223.949006)
		(width 0.10668)
		(layer "F.Cu")
		(net "M_G_CPU1_SA_DQ<22>")
	)
	(segment
		(start 149.48027 -238.942626)
		(end 149.59711 -239.059466)
		(width 0.10668)
		(layer "F.Cu")
		(net "M_G_CPU1_SA_DQ<22>")
	)
	(segment
		(start 161.907728 -225.70567)
		(end 162.072828 -225.70567)
		(width 0.10668)
		(layer "F.Cu")
		(net "M_G_CPU1_SA_DQ<22>")
	)
	(segment
		(start 149.59711 -239.059466)
		(end 149.59711 -239.211104)
		(width 0.10668)
		(layer "F.Cu")
		(net "M_G_CPU1_SA_DQ<22>")
	)
	(segment
		(start 163.931346 -222.835216)
		(end 164.427916 -222.835216)
		(width 0.10668)
		(layer "F.Cu")
		(net "M_G_CPU1_SA_DQ<22>")
	)
	(segment
		(start 149.71395 -239.327944)
		(end 150.353776 -239.327944)
		(width 0.10668)
		(layer "F.Cu")
		(net "M_G_CPU1_SA_DQ<22>")
	)
	(segment
		(start 162.472116 -225.141282)
		(end 162.637216 -225.141282)
		(width 0.10668)
		(layer "F.Cu")
		(net "M_G_CPU1_SA_DQ<22>")
	)
	(segment
		(start 149.314916 -238.942626)
		(end 149.48027 -238.942626)
		(width 0.10668)
		(layer "F.Cu")
		(net "M_G_CPU1_SA_DQ<22>")
	)
	(segment
		(start 148.000974 -239.211104)
		(end 148.117814 -239.327944)
		(width 0.10668)
		(layer "F.Cu")
		(net "M_G_CPU1_SA_DQ<22>")
	)
	(segment
		(start 151.63038 -237.88624)
		(end 151.513286 -237.769146)
		(width 0.10668)
		(layer "F.Cu")
		(net "M_G_CPU1_SA_DQ<22>")
	)
	(segment
		(start 149.960584 -238.59236)
		(end 160.013904 -228.53904)
		(width 0.10668)
		(layer "F.Cu")
		(net "M_G_CPU1_SA_DQ<22>")
	)
	(segment
		(start 146.949668 -238.936784)
		(end 147.340828 -239.327944)
		(width 0.0762)
		(layer "F.Cu")
		(net "M_G_CPU1_SA_DQ<22>")
	)
	(segment
		(start 148.799042 -239.059466)
		(end 148.799042 -239.211104)
		(width 0.10668)
		(layer "F.Cu")
		(net "M_G_CPU1_SA_DQ<22>")
	)
	(segment
		(start 149.198076 -239.211104)
		(end 149.198076 -239.059466)
		(width 0.10668)
		(layer "F.Cu")
		(net "M_G_CPU1_SA_DQ<22>")
	)
	(segment
		(start 148.516848 -238.942626)
		(end 148.682202 -238.942626)
		(width 0.10668)
		(layer "F.Cu")
		(net "M_G_CPU1_SA_DQ<22>")
	)
	(segment
		(start 148.682202 -238.942626)
		(end 148.799042 -239.059466)
		(width 0.10668)
		(layer "F.Cu")
		(net "M_G_CPU1_SA_DQ<22>")
	)
	(segment
		(start 148.915882 -239.327944)
		(end 149.081236 -239.327944)
		(width 0.10668)
		(layer "F.Cu")
		(net "M_G_CPU1_SA_DQ<22>")
	)
	(segment
		(start 149.59711 -239.211104)
		(end 149.71395 -239.327944)
		(width 0.10668)
		(layer "F.Cu")
		(net "M_G_CPU1_SA_DQ<22>")
	)
	(segment
		(start 148.117814 -239.327944)
		(end 148.283168 -239.327944)
		(width 0.10668)
		(layer "F.Cu")
		(net "M_G_CPU1_SA_DQ<22>")
	)
	(segment
		(start 147.71878 -238.942626)
		(end 147.884134 -238.942626)
		(width 0.10668)
		(layer "F.Cu")
		(net "M_G_CPU1_SA_DQ<22>")
	)
	(segment
		(start 161.928048 -225.161856)
		(end 161.928048 -224.996756)
		(width 0.10668)
		(layer "F.Cu")
		(net "M_G_CPU1_SA_DQ<22>")
	)
	(segment
		(start 148.400008 -239.211104)
		(end 148.400008 -239.059466)
		(width 0.10668)
		(layer "F.Cu")
		(net "M_G_CPU1_SA_DQ<22>")
	)
	(segment
		(start 162.189922 -225.423476)
		(end 161.928048 -225.161856)
		(width 0.10668)
		(layer "F.Cu")
		(net "M_G_CPU1_SA_DQ<22>")
	)
	(arc
		(start 145.524982 -238.920274)
		(mid 145.525142 -238.773713)
		(end 145.656808 -238.709454)
		(width 0.0762)
		(layer "F.Cu")
		(net "M_G_CPU1_SA_DQ<22>")
	)
	(arc
		(start 145.796508 -238.752888)
		(mid 146.114405 -238.889972)
		(end 146.457416 -238.936784)
		(width 0.0762)
		(layer "F.Cu")
		(net "M_G_CPU1_SA_DQ<22>")
	)
	(arc
		(start 145.656808 -238.709454)
		(mid 145.728816 -238.724236)
		(end 145.796508 -238.752888)
		(width 0.0762)
		(layer "F.Cu")
		(net "M_G_CPU1_SA_DQ<22>")
	)
	(segment
		(start 152.38984 -237.209076)
		(end 151.99487 -237.604046)
		(width 0.10668)
		(layer "F.Cu")
		(net "M_G_CPU1_SA_DQ<21>")
	)
	(segment
		(start 147.299426 -239.668304)
		(end 147.55495 -239.668304)
		(width 0.0762)
		(layer "F.Cu")
		(net "M_G_CPU1_SA_DQ<21>")
	)
	(segment
		(start 160.354264 -228.680264)
		(end 160.354264 -227.905818)
		(width 0.10668)
		(layer "F.Cu")
		(net "M_G_CPU1_SA_DQ<21>")
	)
	(segment
		(start 163.54044 -224.110296)
		(end 165.858444 -224.110296)
		(width 0.101346)
		(layer "F.Cu")
		(net "M_G_CPU1_SA_DQ<21>")
	)
	(segment
		(start 151.82977 -237.604046)
		(end 151.712676 -237.486952)
		(width 0.10668)
		(layer "F.Cu")
		(net "M_G_CPU1_SA_DQ<21>")
	)
	(segment
		(start 163.157916 -224.49282)
		(end 163.377626 -224.27311)
		(width 0.10668)
		(layer "F.Cu")
		(net "M_G_CPU1_SA_DQ<21>")
	)
	(segment
		(start 151.99487 -237.604046)
		(end 151.82977 -237.604046)
		(width 0.10668)
		(layer "F.Cu")
		(net "M_G_CPU1_SA_DQ<21>")
	)
	(segment
		(start 152.672034 -237.49127)
		(end 152.672034 -237.32617)
		(width 0.10668)
		(layer "F.Cu")
		(net "M_G_CPU1_SA_DQ<21>")
	)
	(segment
		(start 163.377626 -224.27311)
		(end 163.54044 -224.110296)
		(width 0.101346)
		(layer "F.Cu")
		(net "M_G_CPU1_SA_DQ<21>")
	)
	(segment
		(start 147.55495 -239.668304)
		(end 150.495 -239.668304)
		(width 0.10668)
		(layer "F.Cu")
		(net "M_G_CPU1_SA_DQ<21>")
	)
	(segment
		(start 150.495 -239.668304)
		(end 152.672034 -237.49127)
		(width 0.10668)
		(layer "F.Cu")
		(net "M_G_CPU1_SA_DQ<21>")
	)
	(segment
		(start 165.858444 -224.110296)
		(end 166.283386 -223.685354)
		(width 0.101346)
		(layer "F.Cu")
		(net "M_G_CPU1_SA_DQ<21>")
	)
	(segment
		(start 145.796508 -239.4077)
		(end 145.80489 -239.402874)
		(width 0.0762)
		(layer "F.Cu")
		(net "M_G_CPU1_SA_DQ<21>")
	)
	(segment
		(start 146.860006 -239.228884)
		(end 147.299426 -239.668304)
		(width 0.0762)
		(layer "F.Cu")
		(net "M_G_CPU1_SA_DQ<21>")
	)
	(segment
		(start 160.354264 -227.905818)
		(end 163.157916 -225.102166)
		(width 0.10668)
		(layer "F.Cu")
		(net "M_G_CPU1_SA_DQ<21>")
	)
	(segment
		(start 166.283386 -223.685354)
		(end 168.527984 -223.685354)
		(width 0.101346)
		(layer "F.Cu")
		(net "M_G_CPU1_SA_DQ<21>")
	)
	(segment
		(start 144.490948 -239.40262)
		(end 144.490948 -239.402874)
		(width 0.0762)
		(layer "F.Cu")
		(net "M_G_CPU1_SA_DQ<21>")
	)
	(segment
		(start 152.672034 -237.32617)
		(end 152.55494 -237.209076)
		(width 0.10668)
		(layer "F.Cu")
		(net "M_G_CPU1_SA_DQ<21>")
	)
	(segment
		(start 163.157916 -225.102166)
		(end 163.157916 -224.49282)
		(width 0.10668)
		(layer "F.Cu")
		(net "M_G_CPU1_SA_DQ<21>")
	)
	(segment
		(start 152.55494 -237.209076)
		(end 152.38984 -237.209076)
		(width 0.10668)
		(layer "F.Cu")
		(net "M_G_CPU1_SA_DQ<21>")
	)
	(segment
		(start 151.712676 -237.486952)
		(end 151.712676 -237.321852)
		(width 0.10668)
		(layer "F.Cu")
		(net "M_G_CPU1_SA_DQ<21>")
	)
	(segment
		(start 151.712676 -237.321852)
		(end 160.354264 -228.680264)
		(width 0.10668)
		(layer "F.Cu")
		(net "M_G_CPU1_SA_DQ<21>")
	)
	(segment
		(start 146.451066 -239.228884)
		(end 146.860006 -239.228884)
		(width 0.0762)
		(layer "F.Cu")
		(net "M_G_CPU1_SA_DQ<21>")
	)
	(arc
		(start 145.80489 -239.402874)
		(mid 146.116464 -239.273104)
		(end 146.451066 -239.228884)
		(width 0.0762)
		(layer "F.Cu")
		(net "M_G_CPU1_SA_DQ<21>")
	)
	(arc
		(start 144.490948 -239.402874)
		(mid 144.677892 -239.453129)
		(end 144.864836 -239.402874)
		(width 0.0762)
		(layer "F.Cu")
		(net "M_G_CPU1_SA_DQ<21>")
	)
	(arc
		(start 143.737838 -239.080294)
		(mid 143.941854 -239.260988)
		(end 144.206468 -239.326166)
		(width 0.0762)
		(layer "F.Cu")
		(net "M_G_CPU1_SA_DQ<21>")
	)
	(arc
		(start 144.864836 -239.402874)
		(mid 145.147792 -239.326697)
		(end 145.430748 -239.402874)
		(width 0.0762)
		(layer "F.Cu")
		(net "M_G_CPU1_SA_DQ<21>")
	)
	(arc
		(start 144.206468 -239.326166)
		(mid 144.353789 -239.345485)
		(end 144.490948 -239.40262)
		(width 0.0762)
		(layer "F.Cu")
		(net "M_G_CPU1_SA_DQ<21>")
	)
	(arc
		(start 145.430748 -239.402874)
		(mid 145.612999 -239.453224)
		(end 145.796508 -239.4077)
		(width 0.0762)
		(layer "F.Cu")
		(net "M_G_CPU1_SA_DQ<21>")
	)
	(segment
		(start 161.068258 -226.22129)
		(end 161.068258 -226.05619)
		(width 0.10668)
		(layer "F.Cu")
		(net "M_G_CPU1_SA_DQ<20>")
	)
	(segment
		(start 159.731964 -225.449892)
		(end 159.89681 -225.449892)
		(width 0.10668)
		(layer "F.Cu")
		(net "M_G_CPU1_SA_DQ<20>")
	)
	(segment
		(start 167.592502 -221.985332)
		(end 168.527984 -221.985332)
		(width 0.101346)
		(layer "F.Cu")
		(net "M_G_CPU1_SA_DQ<20>")
	)
	(segment
		(start 160.786064 -226.338384)
		(end 160.951164 -226.338384)
		(width 0.10668)
		(layer "F.Cu")
		(net "M_G_CPU1_SA_DQ<20>")
	)
	(segment
		(start 160.798002 -225.621088)
		(end 162.477196 -223.941894)
		(width 0.10668)
		(layer "F.Cu")
		(net "M_G_CPU1_SA_DQ<20>")
	)
	(segment
		(start 167.16756 -222.410274)
		(end 167.592502 -221.985332)
		(width 0.101346)
		(layer "F.Cu")
		(net "M_G_CPU1_SA_DQ<20>")
	)
	(segment
		(start 159.61487 -225.566986)
		(end 159.731964 -225.449892)
		(width 0.10668)
		(layer "F.Cu")
		(net "M_G_CPU1_SA_DQ<20>")
	)
	(segment
		(start 160.798002 -225.786188)
		(end 160.798002 -225.621088)
		(width 0.10668)
		(layer "F.Cu")
		(net "M_G_CPU1_SA_DQ<20>")
	)
	(segment
		(start 163.377626 -222.410274)
		(end 166.327582 -222.410274)
		(width 0.101346)
		(layer "F.Cu")
		(net "M_G_CPU1_SA_DQ<20>")
	)
	(segment
		(start 160.068514 -226.185476)
		(end 159.61487 -225.73234)
		(width 0.10668)
		(layer "F.Cu")
		(net "M_G_CPU1_SA_DQ<20>")
	)
	(segment
		(start 159.673544 -228.397816)
		(end 159.673544 -226.745546)
		(width 0.10668)
		(layer "F.Cu")
		(net "M_G_CPU1_SA_DQ<20>")
	)
	(segment
		(start 149.497796 -238.573564)
		(end 159.673544 -228.397816)
		(width 0.10668)
		(layer "F.Cu")
		(net "M_G_CPU1_SA_DQ<20>")
	)
	(segment
		(start 166.442898 -222.99041)
		(end 166.558214 -223.105726)
		(width 0.101346)
		(layer "F.Cu")
		(net "M_G_CPU1_SA_DQ<20>")
	)
	(segment
		(start 163.376864 -222.410274)
		(end 163.377626 -222.410274)
		(width 0.10668)
		(layer "F.Cu")
		(net "M_G_CPU1_SA_DQ<20>")
	)
	(segment
		(start 146.121882 -238.652304)
		(end 146.987768 -238.652304)
		(width 0.0762)
		(layer "F.Cu")
		(net "M_G_CPU1_SA_DQ<20>")
	)
	(segment
		(start 166.721282 -223.105726)
		(end 166.836598 -222.99041)
		(width 0.101346)
		(layer "F.Cu")
		(net "M_G_CPU1_SA_DQ<20>")
	)
	(segment
		(start 159.61487 -225.73234)
		(end 159.61487 -225.566986)
		(width 0.10668)
		(layer "F.Cu")
		(net "M_G_CPU1_SA_DQ<20>")
	)
	(segment
		(start 147.066508 -238.573564)
		(end 147.63877 -238.573564)
		(width 0.0762)
		(layer "F.Cu")
		(net "M_G_CPU1_SA_DQ<20>")
	)
	(segment
		(start 162.477196 -223.941894)
		(end 162.477196 -223.309942)
		(width 0.10668)
		(layer "F.Cu")
		(net "M_G_CPU1_SA_DQ<20>")
	)
	(segment
		(start 159.89681 -225.449892)
		(end 160.786064 -226.338384)
		(width 0.10668)
		(layer "F.Cu")
		(net "M_G_CPU1_SA_DQ<20>")
	)
	(segment
		(start 166.836598 -222.52559)
		(end 166.951914 -222.410274)
		(width 0.101346)
		(layer "F.Cu")
		(net "M_G_CPU1_SA_DQ<20>")
	)
	(segment
		(start 162.477196 -223.309942)
		(end 163.376864 -222.410274)
		(width 0.10668)
		(layer "F.Cu")
		(net "M_G_CPU1_SA_DQ<20>")
	)
	(segment
		(start 146.987768 -238.652304)
		(end 147.066508 -238.573564)
		(width 0.0762)
		(layer "F.Cu")
		(net "M_G_CPU1_SA_DQ<20>")
	)
	(segment
		(start 159.673544 -226.745546)
		(end 160.068514 -226.350576)
		(width 0.10668)
		(layer "F.Cu")
		(net "M_G_CPU1_SA_DQ<20>")
	)
	(segment
		(start 166.327582 -222.410274)
		(end 166.442898 -222.52559)
		(width 0.101346)
		(layer "F.Cu")
		(net "M_G_CPU1_SA_DQ<20>")
	)
	(segment
		(start 160.068514 -226.350576)
		(end 160.068514 -226.185476)
		(width 0.10668)
		(layer "F.Cu")
		(net "M_G_CPU1_SA_DQ<20>")
	)
	(segment
		(start 161.068258 -226.05619)
		(end 160.798002 -225.786188)
		(width 0.10668)
		(layer "F.Cu")
		(net "M_G_CPU1_SA_DQ<20>")
	)
	(segment
		(start 147.63877 -238.573564)
		(end 149.497796 -238.573564)
		(width 0.10668)
		(layer "F.Cu")
		(net "M_G_CPU1_SA_DQ<20>")
	)
	(segment
		(start 160.951164 -226.338384)
		(end 161.068258 -226.22129)
		(width 0.10668)
		(layer "F.Cu")
		(net "M_G_CPU1_SA_DQ<20>")
	)
	(segment
		(start 166.442898 -222.52559)
		(end 166.442898 -222.99041)
		(width 0.101346)
		(layer "F.Cu")
		(net "M_G_CPU1_SA_DQ<20>")
	)
	(segment
		(start 166.951914 -222.410274)
		(end 167.16756 -222.410274)
		(width 0.101346)
		(layer "F.Cu")
		(net "M_G_CPU1_SA_DQ<20>")
	)
	(segment
		(start 166.836598 -222.99041)
		(end 166.836598 -222.52559)
		(width 0.101346)
		(layer "F.Cu")
		(net "M_G_CPU1_SA_DQ<20>")
	)
	(segment
		(start 166.558214 -223.105726)
		(end 166.721282 -223.105726)
		(width 0.101346)
		(layer "F.Cu")
		(net "M_G_CPU1_SA_DQ<20>")
	)
	(arc
		(start 145.900902 -238.592868)
		(mid 146.007464 -238.637193)
		(end 146.121882 -238.652304)
		(width 0.0762)
		(layer "F.Cu")
		(net "M_G_CPU1_SA_DQ<20>")
	)
	(arc
		(start 145.147792 -238.270288)
		(mid 145.38392 -238.441723)
		(end 145.665444 -238.518446)
		(width 0.0762)
		(layer "F.Cu")
		(net "M_G_CPU1_SA_DQ<20>")
	)
	(arc
		(start 145.665444 -238.518446)
		(mid 145.7873 -238.542602)
		(end 145.900902 -238.592868)
		(width 0.0762)
		(layer "F.Cu")
		(net "M_G_CPU1_SA_DQ<20>")
	)
	(segment
		(start 146.201638 -226.064064)
		(end 146.387058 -226.064064)
		(width 0.0762)
		(layer "F.Cu")
		(net "M_G_CPU1_SA_DQ<1>")
	)
	(segment
		(start 146.387058 -226.064064)
		(end 147.28825 -225.162872)
		(width 0.0762)
		(layer "F.Cu")
		(net "M_G_CPU1_SA_DQ<1>")
	)
	(segment
		(start 165.296596 -199.460358)
		(end 167.433244 -199.035416)
		(width 0.101346)
		(layer "F.Cu")
		(net "M_G_CPU1_SA_DQ<1>")
	)
	(segment
		(start 163.377626 -199.460358)
		(end 165.296596 -199.460358)
		(width 0.101346)
		(layer "F.Cu")
		(net "M_G_CPU1_SA_DQ<1>")
	)
	(segment
		(start 167.433244 -199.035416)
		(end 168.527984 -199.035416)
		(width 0.101346)
		(layer "F.Cu")
		(net "M_G_CPU1_SA_DQ<1>")
	)
	(segment
		(start 148.296884 -214.77986)
		(end 153.808938 -209.267806)
		(width 0.10668)
		(layer "F.Cu")
		(net "M_G_CPU1_SA_DQ<1>")
	)
	(segment
		(start 162.60191 -199.460358)
		(end 163.377626 -199.460358)
		(width 0.10668)
		(layer "F.Cu")
		(net "M_G_CPU1_SA_DQ<1>")
	)
	(segment
		(start 145.881598 -226.384104)
		(end 146.201638 -226.064064)
		(width 0.0762)
		(layer "F.Cu")
		(net "M_G_CPU1_SA_DQ<1>")
	)
	(segment
		(start 148.296884 -223.874838)
		(end 148.296884 -214.77986)
		(width 0.10668)
		(layer "F.Cu")
		(net "M_G_CPU1_SA_DQ<1>")
	)
	(segment
		(start 147.28825 -224.883472)
		(end 148.296884 -223.874838)
		(width 0.10668)
		(layer "F.Cu")
		(net "M_G_CPU1_SA_DQ<1>")
	)
	(segment
		(start 153.808938 -209.267806)
		(end 154.526488 -207.53578)
		(width 0.10668)
		(layer "F.Cu")
		(net "M_G_CPU1_SA_DQ<1>")
	)
	(segment
		(start 154.526488 -207.53578)
		(end 162.60191 -199.460358)
		(width 0.10668)
		(layer "F.Cu")
		(net "M_G_CPU1_SA_DQ<1>")
	)
	(segment
		(start 147.28825 -225.162872)
		(end 147.28825 -224.883472)
		(width 0.0762)
		(layer "F.Cu")
		(net "M_G_CPU1_SA_DQ<1>")
	)
	(arc
		(start 144.490948 -226.443032)
		(mid 144.677892 -226.493287)
		(end 144.864836 -226.443032)
		(width 0.0762)
		(layer "F.Cu")
		(net "M_G_CPU1_SA_DQ<1>")
	)
	(arc
		(start 145.430748 -226.443032)
		(mid 145.612999 -226.493382)
		(end 145.796508 -226.447858)
		(width 0.0762)
		(layer "F.Cu")
		(net "M_G_CPU1_SA_DQ<1>")
	)
	(arc
		(start 144.864836 -226.443032)
		(mid 145.147792 -226.366855)
		(end 145.430748 -226.443032)
		(width 0.0762)
		(layer "F.Cu")
		(net "M_G_CPU1_SA_DQ<1>")
	)
	(arc
		(start 143.737838 -226.120452)
		(mid 143.947549 -226.30159)
		(end 144.216882 -226.366832)
		(width 0.0762)
		(layer "F.Cu")
		(net "M_G_CPU1_SA_DQ<1>")
	)
	(arc
		(start 144.216882 -226.366832)
		(mid 144.358795 -226.387374)
		(end 144.490948 -226.443032)
		(width 0.0762)
		(layer "F.Cu")
		(net "M_G_CPU1_SA_DQ<1>")
	)
	(arc
		(start 145.796508 -226.447858)
		(mid 145.841328 -226.419019)
		(end 145.881598 -226.384104)
		(width 0.0762)
		(layer "F.Cu")
		(net "M_G_CPU1_SA_DQ<1>")
	)
	(segment
		(start 157.72765 -223.406716)
		(end 157.930596 -223.20377)
		(width 0.10668)
		(layer "F.Cu")
		(net "M_G_CPU1_SA_DQ<19>")
	)
	(segment
		(start 160.065466 -220.658436)
		(end 160.065466 -220.493336)
		(width 0.10668)
		(layer "F.Cu")
		(net "M_G_CPU1_SA_DQ<19>")
	)
	(segment
		(start 157.930596 -223.03867)
		(end 157.807914 -222.915988)
		(width 0.10668)
		(layer "F.Cu")
		(net "M_G_CPU1_SA_DQ<19>")
	)
	(segment
		(start 160.34766 -220.376242)
		(end 160.470342 -220.498924)
		(width 0.10668)
		(layer "F.Cu")
		(net "M_G_CPU1_SA_DQ<19>")
	)
	(segment
		(start 161.75863 -218.800172)
		(end 161.875724 -218.683078)
		(width 0.10668)
		(layer "F.Cu")
		(net "M_G_CPU1_SA_DQ<19>")
	)
	(segment
		(start 147.742148 -236.561884)
		(end 148.822156 -236.561884)
		(width 0.10668)
		(layer "F.Cu")
		(net "M_G_CPU1_SA_DQ<19>")
	)
	(segment
		(start 161.599118 -219.370148)
		(end 161.764218 -219.370148)
		(width 0.10668)
		(layer "F.Cu")
		(net "M_G_CPU1_SA_DQ<19>")
	)
	(segment
		(start 160.470342 -220.498924)
		(end 160.635442 -220.498924)
		(width 0.10668)
		(layer "F.Cu")
		(net "M_G_CPU1_SA_DQ<19>")
	)
	(segment
		(start 161.316924 -219.652342)
		(end 161.194242 -219.52966)
		(width 0.10668)
		(layer "F.Cu")
		(net "M_G_CPU1_SA_DQ<19>")
	)
	(segment
		(start 159.905954 -221.063312)
		(end 160.071054 -221.063312)
		(width 0.10668)
		(layer "F.Cu")
		(net "M_G_CPU1_SA_DQ<19>")
	)
	(segment
		(start 160.188148 -220.781118)
		(end 160.065466 -220.658436)
		(width 0.10668)
		(layer "F.Cu")
		(net "M_G_CPU1_SA_DQ<19>")
	)
	(segment
		(start 160.752536 -220.38183)
		(end 160.752536 -220.21673)
		(width 0.10668)
		(layer "F.Cu")
		(net "M_G_CPU1_SA_DQ<19>")
	)
	(segment
		(start 159.059372 -221.909894)
		(end 158.93669 -221.787212)
		(width 0.10668)
		(layer "F.Cu")
		(net "M_G_CPU1_SA_DQ<19>")
	)
	(segment
		(start 160.071054 -221.063312)
		(end 160.188148 -220.946218)
		(width 0.10668)
		(layer "F.Cu")
		(net "M_G_CPU1_SA_DQ<19>")
	)
	(segment
		(start 161.194242 -219.52966)
		(end 161.194242 -219.36456)
		(width 0.10668)
		(layer "F.Cu")
		(net "M_G_CPU1_SA_DQ<19>")
	)
	(segment
		(start 158.494984 -222.639382)
		(end 158.494984 -222.474282)
		(width 0.10668)
		(layer "F.Cu")
		(net "M_G_CPU1_SA_DQ<19>")
	)
	(segment
		(start 157.930596 -223.20377)
		(end 157.930596 -223.03867)
		(width 0.10668)
		(layer "F.Cu")
		(net "M_G_CPU1_SA_DQ<19>")
	)
	(segment
		(start 159.501078 -221.057724)
		(end 159.618172 -220.94063)
		(width 0.10668)
		(layer "F.Cu")
		(net "M_G_CPU1_SA_DQ<19>")
	)
	(segment
		(start 144.207992 -236.650276)
		(end 144.207992 -236.650022)
		(width 0.0762)
		(layer "F.Cu")
		(net "M_G_CPU1_SA_DQ<19>")
	)
	(segment
		(start 159.783272 -220.94063)
		(end 159.905954 -221.063312)
		(width 0.10668)
		(layer "F.Cu")
		(net "M_G_CPU1_SA_DQ<19>")
	)
	(segment
		(start 144.207992 -236.650022)
		(end 144.102836 -236.469174)
		(width 0.0762)
		(layer "F.Cu")
		(net "M_G_CPU1_SA_DQ<19>")
	)
	(segment
		(start 158.93669 -221.787212)
		(end 158.93669 -221.622112)
		(width 0.10668)
		(layer "F.Cu")
		(net "M_G_CPU1_SA_DQ<19>")
	)
	(segment
		(start 158.93669 -221.622112)
		(end 159.053784 -221.505018)
		(width 0.10668)
		(layer "F.Cu")
		(net "M_G_CPU1_SA_DQ<19>")
	)
	(segment
		(start 160.752536 -220.21673)
		(end 160.629854 -220.094048)
		(width 0.10668)
		(layer "F.Cu")
		(net "M_G_CPU1_SA_DQ<19>")
	)
	(segment
		(start 159.059372 -222.074994)
		(end 159.059372 -221.909894)
		(width 0.10668)
		(layer "F.Cu")
		(net "M_G_CPU1_SA_DQ<19>")
	)
	(segment
		(start 159.62376 -221.510606)
		(end 159.62376 -221.345506)
		(width 0.10668)
		(layer "F.Cu")
		(net "M_G_CPU1_SA_DQ<19>")
	)
	(segment
		(start 158.777178 -222.192088)
		(end 158.942278 -222.192088)
		(width 0.10668)
		(layer "F.Cu")
		(net "M_G_CPU1_SA_DQ<19>")
	)
	(segment
		(start 162.163506 -218.80576)
		(end 162.328606 -218.80576)
		(width 0.10668)
		(layer "F.Cu")
		(net "M_G_CPU1_SA_DQ<19>")
	)
	(segment
		(start 161.311336 -219.247466)
		(end 161.476436 -219.247466)
		(width 0.10668)
		(layer "F.Cu")
		(net "M_G_CPU1_SA_DQ<19>")
	)
	(segment
		(start 158.37789 -222.756476)
		(end 158.494984 -222.639382)
		(width 0.10668)
		(layer "F.Cu")
		(net "M_G_CPU1_SA_DQ<19>")
	)
	(segment
		(start 160.188148 -220.946218)
		(end 160.188148 -220.781118)
		(width 0.10668)
		(layer "F.Cu")
		(net "M_G_CPU1_SA_DQ<19>")
	)
	(segment
		(start 161.03473 -219.934536)
		(end 161.19983 -219.934536)
		(width 0.10668)
		(layer "F.Cu")
		(net "M_G_CPU1_SA_DQ<19>")
	)
	(segment
		(start 162.040824 -218.683078)
		(end 162.163506 -218.80576)
		(width 0.10668)
		(layer "F.Cu")
		(net "M_G_CPU1_SA_DQ<19>")
	)
	(segment
		(start 159.618172 -220.94063)
		(end 159.783272 -220.94063)
		(width 0.10668)
		(layer "F.Cu")
		(net "M_G_CPU1_SA_DQ<19>")
	)
	(segment
		(start 159.506666 -221.6277)
		(end 159.62376 -221.510606)
		(width 0.10668)
		(layer "F.Cu")
		(net "M_G_CPU1_SA_DQ<19>")
	)
	(segment
		(start 160.065466 -220.493336)
		(end 160.18256 -220.376242)
		(width 0.10668)
		(layer "F.Cu")
		(net "M_G_CPU1_SA_DQ<19>")
	)
	(segment
		(start 161.316924 -219.817442)
		(end 161.316924 -219.652342)
		(width 0.10668)
		(layer "F.Cu")
		(net "M_G_CPU1_SA_DQ<19>")
	)
	(segment
		(start 157.807914 -222.915988)
		(end 157.807914 -222.750888)
		(width 0.10668)
		(layer "F.Cu")
		(net "M_G_CPU1_SA_DQ<19>")
	)
	(segment
		(start 148.822156 -236.561884)
		(end 157.72765 -227.65639)
		(width 0.10668)
		(layer "F.Cu")
		(net "M_G_CPU1_SA_DQ<19>")
	)
	(segment
		(start 161.19983 -219.934536)
		(end 161.316924 -219.817442)
		(width 0.10668)
		(layer "F.Cu")
		(net "M_G_CPU1_SA_DQ<19>")
	)
	(segment
		(start 158.489396 -222.069406)
		(end 158.654496 -222.069406)
		(width 0.10668)
		(layer "F.Cu")
		(net "M_G_CPU1_SA_DQ<19>")
	)
	(segment
		(start 160.635442 -220.498924)
		(end 160.752536 -220.38183)
		(width 0.10668)
		(layer "F.Cu")
		(net "M_G_CPU1_SA_DQ<19>")
	)
	(segment
		(start 160.912048 -219.811854)
		(end 161.03473 -219.934536)
		(width 0.10668)
		(layer "F.Cu")
		(net "M_G_CPU1_SA_DQ<19>")
	)
	(segment
		(start 158.372302 -222.3516)
		(end 158.372302 -222.1865)
		(width 0.10668)
		(layer "F.Cu")
		(net "M_G_CPU1_SA_DQ<19>")
	)
	(segment
		(start 160.18256 -220.376242)
		(end 160.34766 -220.376242)
		(width 0.10668)
		(layer "F.Cu")
		(net "M_G_CPU1_SA_DQ<19>")
	)
	(segment
		(start 158.372302 -222.1865)
		(end 158.489396 -222.069406)
		(width 0.10668)
		(layer "F.Cu")
		(net "M_G_CPU1_SA_DQ<19>")
	)
	(segment
		(start 161.764218 -219.370148)
		(end 161.881312 -219.253054)
		(width 0.10668)
		(layer "F.Cu")
		(net "M_G_CPU1_SA_DQ<19>")
	)
	(segment
		(start 157.807914 -222.750888)
		(end 157.925008 -222.633794)
		(width 0.10668)
		(layer "F.Cu")
		(net "M_G_CPU1_SA_DQ<19>")
	)
	(segment
		(start 160.746948 -219.811854)
		(end 160.912048 -219.811854)
		(width 0.10668)
		(layer "F.Cu")
		(net "M_G_CPU1_SA_DQ<19>")
	)
	(segment
		(start 159.341566 -221.6277)
		(end 159.506666 -221.6277)
		(width 0.10668)
		(layer "F.Cu")
		(net "M_G_CPU1_SA_DQ<19>")
	)
	(segment
		(start 158.942278 -222.192088)
		(end 159.059372 -222.074994)
		(width 0.10668)
		(layer "F.Cu")
		(net "M_G_CPU1_SA_DQ<19>")
	)
	(segment
		(start 159.62376 -221.345506)
		(end 159.501078 -221.222824)
		(width 0.10668)
		(layer "F.Cu")
		(net "M_G_CPU1_SA_DQ<19>")
	)
	(segment
		(start 160.629854 -219.928948)
		(end 160.746948 -219.811854)
		(width 0.10668)
		(layer "F.Cu")
		(net "M_G_CPU1_SA_DQ<19>")
	)
	(segment
		(start 158.494984 -222.474282)
		(end 158.372302 -222.3516)
		(width 0.10668)
		(layer "F.Cu")
		(net "M_G_CPU1_SA_DQ<19>")
	)
	(segment
		(start 159.501078 -221.222824)
		(end 159.501078 -221.057724)
		(width 0.10668)
		(layer "F.Cu")
		(net "M_G_CPU1_SA_DQ<19>")
	)
	(segment
		(start 159.053784 -221.505018)
		(end 159.218884 -221.505018)
		(width 0.10668)
		(layer "F.Cu")
		(net "M_G_CPU1_SA_DQ<19>")
	)
	(segment
		(start 146.873468 -236.272324)
		(end 147.163028 -236.561884)
		(width 0.0762)
		(layer "F.Cu")
		(net "M_G_CPU1_SA_DQ<19>")
	)
	(segment
		(start 157.72765 -227.65639)
		(end 157.72765 -223.406716)
		(width 0.10668)
		(layer "F.Cu")
		(net "M_G_CPU1_SA_DQ<19>")
	)
	(segment
		(start 158.090108 -222.633794)
		(end 158.21279 -222.756476)
		(width 0.10668)
		(layer "F.Cu")
		(net "M_G_CPU1_SA_DQ<19>")
	)
	(segment
		(start 147.163028 -236.561884)
		(end 147.742148 -236.561884)
		(width 0.0762)
		(layer "F.Cu")
		(net "M_G_CPU1_SA_DQ<19>")
	)
	(segment
		(start 162.328606 -218.80576)
		(end 162.549078 -218.585288)
		(width 0.10668)
		(layer "F.Cu")
		(net "M_G_CPU1_SA_DQ<19>")
	)
	(segment
		(start 158.21279 -222.756476)
		(end 158.37789 -222.756476)
		(width 0.10668)
		(layer "F.Cu")
		(net "M_G_CPU1_SA_DQ<19>")
	)
	(segment
		(start 161.476436 -219.247466)
		(end 161.599118 -219.370148)
		(width 0.10668)
		(layer "F.Cu")
		(net "M_G_CPU1_SA_DQ<19>")
	)
	(segment
		(start 144.38757 -236.323378)
		(end 144.394936 -236.327696)
		(width 0.0762)
		(layer "F.Cu")
		(net "M_G_CPU1_SA_DQ<19>")
	)
	(segment
		(start 144.960848 -236.327696)
		(end 144.96923 -236.32287)
		(width 0.0762)
		(layer "F.Cu")
		(net "M_G_CPU1_SA_DQ<19>")
	)
	(segment
		(start 161.194242 -219.36456)
		(end 161.311336 -219.247466)
		(width 0.10668)
		(layer "F.Cu")
		(net "M_G_CPU1_SA_DQ<19>")
	)
	(segment
		(start 161.75863 -218.965272)
		(end 161.75863 -218.800172)
		(width 0.10668)
		(layer "F.Cu")
		(net "M_G_CPU1_SA_DQ<19>")
	)
	(segment
		(start 146.106388 -236.272324)
		(end 146.873468 -236.272324)
		(width 0.0762)
		(layer "F.Cu")
		(net "M_G_CPU1_SA_DQ<19>")
	)
	(segment
		(start 157.925008 -222.633794)
		(end 158.090108 -222.633794)
		(width 0.10668)
		(layer "F.Cu")
		(net "M_G_CPU1_SA_DQ<19>")
	)
	(segment
		(start 159.218884 -221.505018)
		(end 159.341566 -221.6277)
		(width 0.10668)
		(layer "F.Cu")
		(net "M_G_CPU1_SA_DQ<19>")
	)
	(segment
		(start 161.881312 -219.087954)
		(end 161.75863 -218.965272)
		(width 0.10668)
		(layer "F.Cu")
		(net "M_G_CPU1_SA_DQ<19>")
	)
	(segment
		(start 162.549078 -218.585288)
		(end 164.427916 -218.585288)
		(width 0.10668)
		(layer "F.Cu")
		(net "M_G_CPU1_SA_DQ<19>")
	)
	(segment
		(start 158.654496 -222.069406)
		(end 158.777178 -222.192088)
		(width 0.10668)
		(layer "F.Cu")
		(net "M_G_CPU1_SA_DQ<19>")
	)
	(segment
		(start 161.881312 -219.253054)
		(end 161.881312 -219.087954)
		(width 0.10668)
		(layer "F.Cu")
		(net "M_G_CPU1_SA_DQ<19>")
	)
	(segment
		(start 161.875724 -218.683078)
		(end 162.040824 -218.683078)
		(width 0.10668)
		(layer "F.Cu")
		(net "M_G_CPU1_SA_DQ<19>")
	)
	(segment
		(start 160.629854 -220.094048)
		(end 160.629854 -219.928948)
		(width 0.10668)
		(layer "F.Cu")
		(net "M_G_CPU1_SA_DQ<19>")
	)
	(segment
		(start 144.386554 -236.32287)
		(end 144.38757 -236.323378)
		(width 0.0762)
		(layer "F.Cu")
		(net "M_G_CPU1_SA_DQ<19>")
	)
	(arc
		(start 144.394936 -236.327696)
		(mid 144.677892 -236.403873)
		(end 144.960848 -236.327696)
		(width 0.0762)
		(layer "F.Cu")
		(net "M_G_CPU1_SA_DQ<19>")
	)
	(arc
		(start 144.102836 -236.469174)
		(mid 144.111773 -236.35015)
		(end 144.206468 -236.277404)
		(width 0.0762)
		(layer "F.Cu")
		(net "M_G_CPU1_SA_DQ<19>")
	)
	(arc
		(start 144.206468 -236.277404)
		(mid 144.299392 -236.288727)
		(end 144.386554 -236.32287)
		(width 0.0762)
		(layer "F.Cu")
		(net "M_G_CPU1_SA_DQ<19>")
	)
	(arc
		(start 145.900902 -236.327696)
		(mid 145.999975 -236.286382)
		(end 146.106388 -236.272324)
		(width 0.0762)
		(layer "F.Cu")
		(net "M_G_CPU1_SA_DQ<19>")
	)
	(arc
		(start 145.33499 -236.327696)
		(mid 145.617946 -236.403873)
		(end 145.900902 -236.327696)
		(width 0.0762)
		(layer "F.Cu")
		(net "M_G_CPU1_SA_DQ<19>")
	)
	(arc
		(start 144.96923 -236.32287)
		(mid 145.152738 -236.277376)
		(end 145.33499 -236.327696)
		(width 0.0762)
		(layer "F.Cu")
		(net "M_G_CPU1_SA_DQ<19>")
	)
	(segment
		(start 161.969196 -217.461338)
		(end 161.709354 -217.20175)
		(width 0.10668)
		(layer "F.Cu")
		(net "M_G_CPU1_SA_DQ<18>")
	)
	(segment
		(start 161.122614 -218.30792)
		(end 161.287714 -218.30792)
		(width 0.10668)
		(layer "F.Cu")
		(net "M_G_CPU1_SA_DQ<18>")
	)
	(segment
		(start 162.25139 -217.179144)
		(end 162.41649 -217.179144)
		(width 0.10668)
		(layer "F.Cu")
		(net "M_G_CPU1_SA_DQ<18>")
	)
	(segment
		(start 161.991548 -216.919556)
		(end 162.25139 -217.179144)
		(width 0.10668)
		(layer "F.Cu")
		(net "M_G_CPU1_SA_DQ<18>")
	)
	(segment
		(start 162.41649 -217.179144)
		(end 162.710368 -216.885266)
		(width 0.10668)
		(layer "F.Cu")
		(net "M_G_CPU1_SA_DQ<18>")
	)
	(segment
		(start 161.709354 -217.20175)
		(end 161.709354 -217.03665)
		(width 0.10668)
		(layer "F.Cu")
		(net "M_G_CPU1_SA_DQ<18>")
	)
	(segment
		(start 160.580578 -218.330526)
		(end 160.580578 -218.165426)
		(width 0.10668)
		(layer "F.Cu")
		(net "M_G_CPU1_SA_DQ<18>")
	)
	(segment
		(start 161.144966 -217.601038)
		(end 161.26206 -217.483944)
		(width 0.10668)
		(layer "F.Cu")
		(net "M_G_CPU1_SA_DQ<18>")
	)
	(segment
		(start 159.711644 -219.88399)
		(end 159.711644 -219.71889)
		(width 0.10668)
		(layer "F.Cu")
		(net "M_G_CPU1_SA_DQ<18>")
	)
	(segment
		(start 157.04693 -222.548704)
		(end 159.711644 -219.88399)
		(width 0.10668)
		(layer "F.Cu")
		(net "M_G_CPU1_SA_DQ<18>")
	)
	(segment
		(start 161.26206 -217.483944)
		(end 161.42716 -217.483944)
		(width 0.10668)
		(layer "F.Cu")
		(net "M_G_CPU1_SA_DQ<18>")
	)
	(segment
		(start 159.451802 -219.459302)
		(end 159.451802 -219.294202)
		(width 0.10668)
		(layer "F.Cu")
		(net "M_G_CPU1_SA_DQ<18>")
	)
	(segment
		(start 161.709354 -217.03665)
		(end 161.826448 -216.919556)
		(width 0.10668)
		(layer "F.Cu")
		(net "M_G_CPU1_SA_DQ<18>")
	)
	(segment
		(start 160.276032 -219.154502)
		(end 160.01619 -218.894914)
		(width 0.10668)
		(layer "F.Cu")
		(net "M_G_CPU1_SA_DQ<18>")
	)
	(segment
		(start 160.01619 -218.729814)
		(end 160.133284 -218.61272)
		(width 0.10668)
		(layer "F.Cu")
		(net "M_G_CPU1_SA_DQ<18>")
	)
	(segment
		(start 160.298384 -218.61272)
		(end 160.558226 -218.872308)
		(width 0.10668)
		(layer "F.Cu")
		(net "M_G_CPU1_SA_DQ<18>")
	)
	(segment
		(start 161.144966 -217.766138)
		(end 161.144966 -217.601038)
		(width 0.10668)
		(layer "F.Cu")
		(net "M_G_CPU1_SA_DQ<18>")
	)
	(segment
		(start 161.287714 -218.30792)
		(end 161.404808 -218.190826)
		(width 0.10668)
		(layer "F.Cu")
		(net "M_G_CPU1_SA_DQ<18>")
	)
	(segment
		(start 161.852102 -217.743532)
		(end 161.969196 -217.626438)
		(width 0.10668)
		(layer "F.Cu")
		(net "M_G_CPU1_SA_DQ<18>")
	)
	(segment
		(start 160.276032 -219.319602)
		(end 160.276032 -219.154502)
		(width 0.10668)
		(layer "F.Cu")
		(net "M_G_CPU1_SA_DQ<18>")
	)
	(segment
		(start 148.539708 -235.881164)
		(end 157.04693 -227.373942)
		(width 0.10668)
		(layer "F.Cu")
		(net "M_G_CPU1_SA_DQ<18>")
	)
	(segment
		(start 159.451802 -219.294202)
		(end 159.568896 -219.177108)
		(width 0.10668)
		(layer "F.Cu")
		(net "M_G_CPU1_SA_DQ<18>")
	)
	(segment
		(start 147.338288 -235.881164)
		(end 147.798028 -235.881164)
		(width 0.0762)
		(layer "F.Cu")
		(net "M_G_CPU1_SA_DQ<18>")
	)
	(segment
		(start 160.01619 -218.894914)
		(end 160.01619 -218.729814)
		(width 0.10668)
		(layer "F.Cu")
		(net "M_G_CPU1_SA_DQ<18>")
	)
	(segment
		(start 160.862772 -218.048332)
		(end 161.122614 -218.30792)
		(width 0.10668)
		(layer "F.Cu")
		(net "M_G_CPU1_SA_DQ<18>")
	)
	(segment
		(start 160.158938 -219.436696)
		(end 160.276032 -219.319602)
		(width 0.10668)
		(layer "F.Cu")
		(net "M_G_CPU1_SA_DQ<18>")
	)
	(segment
		(start 160.580578 -218.165426)
		(end 160.697672 -218.048332)
		(width 0.10668)
		(layer "F.Cu")
		(net "M_G_CPU1_SA_DQ<18>")
	)
	(segment
		(start 145.617946 -235.84027)
		(end 145.524982 -235.68025)
		(width 0.0762)
		(layer "F.Cu")
		(net "M_G_CPU1_SA_DQ<18>")
	)
	(segment
		(start 161.687002 -217.743532)
		(end 161.852102 -217.743532)
		(width 0.10668)
		(layer "F.Cu")
		(net "M_G_CPU1_SA_DQ<18>")
	)
	(segment
		(start 147.112228 -235.655104)
		(end 147.338288 -235.881164)
		(width 0.0762)
		(layer "F.Cu")
		(net "M_G_CPU1_SA_DQ<18>")
	)
	(segment
		(start 160.697672 -218.048332)
		(end 160.862772 -218.048332)
		(width 0.10668)
		(layer "F.Cu")
		(net "M_G_CPU1_SA_DQ<18>")
	)
	(segment
		(start 159.711644 -219.71889)
		(end 159.451802 -219.459302)
		(width 0.10668)
		(layer "F.Cu")
		(net "M_G_CPU1_SA_DQ<18>")
	)
	(segment
		(start 159.568896 -219.177108)
		(end 159.733996 -219.177108)
		(width 0.10668)
		(layer "F.Cu")
		(net "M_G_CPU1_SA_DQ<18>")
	)
	(segment
		(start 160.558226 -218.872308)
		(end 160.723326 -218.872308)
		(width 0.10668)
		(layer "F.Cu")
		(net "M_G_CPU1_SA_DQ<18>")
	)
	(segment
		(start 159.733996 -219.177108)
		(end 159.993838 -219.436696)
		(width 0.10668)
		(layer "F.Cu")
		(net "M_G_CPU1_SA_DQ<18>")
	)
	(segment
		(start 162.710368 -216.885266)
		(end 164.427916 -216.885266)
		(width 0.10668)
		(layer "F.Cu")
		(net "M_G_CPU1_SA_DQ<18>")
	)
	(segment
		(start 161.826448 -216.919556)
		(end 161.991548 -216.919556)
		(width 0.10668)
		(layer "F.Cu")
		(net "M_G_CPU1_SA_DQ<18>")
	)
	(segment
		(start 146.315176 -235.655104)
		(end 147.112228 -235.655104)
		(width 0.0762)
		(layer "F.Cu")
		(net "M_G_CPU1_SA_DQ<18>")
	)
	(segment
		(start 157.04693 -227.373942)
		(end 157.04693 -222.548704)
		(width 0.10668)
		(layer "F.Cu")
		(net "M_G_CPU1_SA_DQ<18>")
	)
	(segment
		(start 160.84042 -218.590114)
		(end 160.580578 -218.330526)
		(width 0.10668)
		(layer "F.Cu")
		(net "M_G_CPU1_SA_DQ<18>")
	)
	(segment
		(start 161.404808 -218.025726)
		(end 161.144966 -217.766138)
		(width 0.10668)
		(layer "F.Cu")
		(net "M_G_CPU1_SA_DQ<18>")
	)
	(segment
		(start 161.969196 -217.626438)
		(end 161.969196 -217.461338)
		(width 0.10668)
		(layer "F.Cu")
		(net "M_G_CPU1_SA_DQ<18>")
	)
	(segment
		(start 161.404808 -218.190826)
		(end 161.404808 -218.025726)
		(width 0.10668)
		(layer "F.Cu")
		(net "M_G_CPU1_SA_DQ<18>")
	)
	(segment
		(start 160.133284 -218.61272)
		(end 160.298384 -218.61272)
		(width 0.10668)
		(layer "F.Cu")
		(net "M_G_CPU1_SA_DQ<18>")
	)
	(segment
		(start 145.796508 -235.512864)
		(end 145.80489 -235.51769)
		(width 0.0762)
		(layer "F.Cu")
		(net "M_G_CPU1_SA_DQ<18>")
	)
	(segment
		(start 160.723326 -218.872308)
		(end 160.84042 -218.755214)
		(width 0.10668)
		(layer "F.Cu")
		(net "M_G_CPU1_SA_DQ<18>")
	)
	(segment
		(start 159.993838 -219.436696)
		(end 160.158938 -219.436696)
		(width 0.10668)
		(layer "F.Cu")
		(net "M_G_CPU1_SA_DQ<18>")
	)
	(segment
		(start 160.84042 -218.755214)
		(end 160.84042 -218.590114)
		(width 0.10668)
		(layer "F.Cu")
		(net "M_G_CPU1_SA_DQ<18>")
	)
	(segment
		(start 161.42716 -217.483944)
		(end 161.687002 -217.743532)
		(width 0.10668)
		(layer "F.Cu")
		(net "M_G_CPU1_SA_DQ<18>")
	)
	(segment
		(start 147.798028 -235.881164)
		(end 148.539708 -235.881164)
		(width 0.10668)
		(layer "F.Cu")
		(net "M_G_CPU1_SA_DQ<18>")
	)
	(arc
		(start 145.524982 -235.68025)
		(mid 145.525142 -235.533689)
		(end 145.656808 -235.46943)
		(width 0.0762)
		(layer "F.Cu")
		(net "M_G_CPU1_SA_DQ<18>")
	)
	(arc
		(start 145.656808 -235.46943)
		(mid 145.728816 -235.484212)
		(end 145.796508 -235.512864)
		(width 0.0762)
		(layer "F.Cu")
		(net "M_G_CPU1_SA_DQ<18>")
	)
	(arc
		(start 145.80489 -235.51769)
		(mid 146.050936 -235.620192)
		(end 146.315176 -235.655104)
		(width 0.0762)
		(layer "F.Cu")
		(net "M_G_CPU1_SA_DQ<18>")
	)
	(segment
		(start 144.490948 -236.162596)
		(end 144.490948 -236.16285)
		(width 0.0762)
		(layer "F.Cu")
		(net "M_G_CPU1_SA_DQ<17>")
	)
	(segment
		(start 165.880542 -218.160346)
		(end 166.906448 -217.735404)
		(width 0.101346)
		(layer "F.Cu")
		(net "M_G_CPU1_SA_DQ<17>")
	)
	(segment
		(start 157.38729 -222.689928)
		(end 161.916872 -218.160346)
		(width 0.10668)
		(layer "F.Cu")
		(net "M_G_CPU1_SA_DQ<17>")
	)
	(segment
		(start 148.680932 -236.221524)
		(end 157.38729 -227.515166)
		(width 0.10668)
		(layer "F.Cu")
		(net "M_G_CPU1_SA_DQ<17>")
	)
	(segment
		(start 161.916872 -218.160346)
		(end 163.377626 -218.160346)
		(width 0.10668)
		(layer "F.Cu")
		(net "M_G_CPU1_SA_DQ<17>")
	)
	(segment
		(start 147.206208 -236.221524)
		(end 147.775168 -236.221524)
		(width 0.0762)
		(layer "F.Cu")
		(net "M_G_CPU1_SA_DQ<17>")
	)
	(segment
		(start 147.775168 -236.221524)
		(end 148.680932 -236.221524)
		(width 0.10668)
		(layer "F.Cu")
		(net "M_G_CPU1_SA_DQ<17>")
	)
	(segment
		(start 146.964908 -235.980224)
		(end 147.206208 -236.221524)
		(width 0.0762)
		(layer "F.Cu")
		(net "M_G_CPU1_SA_DQ<17>")
	)
	(segment
		(start 166.906448 -217.735404)
		(end 168.527984 -217.735404)
		(width 0.101346)
		(layer "F.Cu")
		(net "M_G_CPU1_SA_DQ<17>")
	)
	(segment
		(start 145.796508 -236.167676)
		(end 145.80489 -236.16285)
		(width 0.0762)
		(layer "F.Cu")
		(net "M_G_CPU1_SA_DQ<17>")
	)
	(segment
		(start 157.38729 -227.515166)
		(end 157.38729 -222.689928)
		(width 0.10668)
		(layer "F.Cu")
		(net "M_G_CPU1_SA_DQ<17>")
	)
	(segment
		(start 163.377626 -218.160346)
		(end 165.880542 -218.160346)
		(width 0.101346)
		(layer "F.Cu")
		(net "M_G_CPU1_SA_DQ<17>")
	)
	(segment
		(start 146.48307 -235.980224)
		(end 146.964908 -235.980224)
		(width 0.0762)
		(layer "F.Cu")
		(net "M_G_CPU1_SA_DQ<17>")
	)
	(arc
		(start 143.737838 -235.84027)
		(mid 143.941854 -236.020964)
		(end 144.206468 -236.086142)
		(width 0.0762)
		(layer "F.Cu")
		(net "M_G_CPU1_SA_DQ<17>")
	)
	(arc
		(start 145.80489 -236.16285)
		(mid 146.1319 -236.026679)
		(end 146.48307 -235.980224)
		(width 0.0762)
		(layer "F.Cu")
		(net "M_G_CPU1_SA_DQ<17>")
	)
	(arc
		(start 145.430748 -236.16285)
		(mid 145.612999 -236.2132)
		(end 145.796508 -236.167676)
		(width 0.0762)
		(layer "F.Cu")
		(net "M_G_CPU1_SA_DQ<17>")
	)
	(arc
		(start 144.864836 -236.16285)
		(mid 145.147792 -236.086673)
		(end 145.430748 -236.16285)
		(width 0.0762)
		(layer "F.Cu")
		(net "M_G_CPU1_SA_DQ<17>")
	)
	(arc
		(start 144.206468 -236.086142)
		(mid 144.353789 -236.105461)
		(end 144.490948 -236.162596)
		(width 0.0762)
		(layer "F.Cu")
		(net "M_G_CPU1_SA_DQ<17>")
	)
	(arc
		(start 144.490948 -236.16285)
		(mid 144.677892 -236.213105)
		(end 144.864836 -236.16285)
		(width 0.0762)
		(layer "F.Cu")
		(net "M_G_CPU1_SA_DQ<17>")
	)
	(segment
		(start 159.111442 -220.002608)
		(end 159.111442 -219.152724)
		(width 0.10668)
		(layer "F.Cu")
		(net "M_G_CPU1_SA_DQ<16>")
	)
	(segment
		(start 161.803842 -216.460324)
		(end 163.377626 -216.460324)
		(width 0.10668)
		(layer "F.Cu")
		(net "M_G_CPU1_SA_DQ<16>")
	)
	(segment
		(start 146.107912 -235.408724)
		(end 147.27174 -235.408724)
		(width 0.0762)
		(layer "F.Cu")
		(net "M_G_CPU1_SA_DQ<16>")
	)
	(segment
		(start 167.445436 -216.035382)
		(end 168.527984 -216.035382)
		(width 0.101346)
		(layer "F.Cu")
		(net "M_G_CPU1_SA_DQ<16>")
	)
	(segment
		(start 156.70657 -227.232718)
		(end 156.70657 -222.40748)
		(width 0.10668)
		(layer "F.Cu")
		(net "M_G_CPU1_SA_DQ<16>")
	)
	(segment
		(start 147.787868 -235.540804)
		(end 148.398484 -235.540804)
		(width 0.10668)
		(layer "F.Cu")
		(net "M_G_CPU1_SA_DQ<16>")
	)
	(segment
		(start 147.40382 -235.540804)
		(end 147.787868 -235.540804)
		(width 0.0762)
		(layer "F.Cu")
		(net "M_G_CPU1_SA_DQ<16>")
	)
	(segment
		(start 159.111442 -219.152724)
		(end 161.803842 -216.460324)
		(width 0.10668)
		(layer "F.Cu")
		(net "M_G_CPU1_SA_DQ<16>")
	)
	(segment
		(start 163.377626 -216.460324)
		(end 167.020494 -216.460324)
		(width 0.101346)
		(layer "F.Cu")
		(net "M_G_CPU1_SA_DQ<16>")
	)
	(segment
		(start 167.020494 -216.460324)
		(end 167.445436 -216.035382)
		(width 0.101346)
		(layer "F.Cu")
		(net "M_G_CPU1_SA_DQ<16>")
	)
	(segment
		(start 148.398484 -235.540804)
		(end 156.70657 -227.232718)
		(width 0.10668)
		(layer "F.Cu")
		(net "M_G_CPU1_SA_DQ<16>")
	)
	(segment
		(start 156.70657 -222.40748)
		(end 159.111442 -220.002608)
		(width 0.10668)
		(layer "F.Cu")
		(net "M_G_CPU1_SA_DQ<16>")
	)
	(segment
		(start 147.27174 -235.408724)
		(end 147.40382 -235.540804)
		(width 0.0762)
		(layer "F.Cu")
		(net "M_G_CPU1_SA_DQ<16>")
	)
	(arc
		(start 145.147792 -235.030264)
		(mid 145.38392 -235.201699)
		(end 145.665444 -235.278422)
		(width 0.0762)
		(layer "F.Cu")
		(net "M_G_CPU1_SA_DQ<16>")
	)
	(arc
		(start 145.900902 -235.352844)
		(mid 146.000709 -235.394473)
		(end 146.107912 -235.408724)
		(width 0.0762)
		(layer "F.Cu")
		(net "M_G_CPU1_SA_DQ<16>")
	)
	(arc
		(start 145.665444 -235.278422)
		(mid 145.7873 -235.302578)
		(end 145.900902 -235.352844)
		(width 0.0762)
		(layer "F.Cu")
		(net "M_G_CPU1_SA_DQ<16>")
	)
	(segment
		(start 162.915346 -215.66251)
		(end 162.915346 -215.283542)
		(width 0.10668)
		(layer "F.Cu")
		(net "M_G_CPU1_SA_DQ<15>")
	)
	(segment
		(start 158.12008 -219.383356)
		(end 158.237174 -219.50045)
		(width 0.10668)
		(layer "F.Cu")
		(net "M_G_CPU1_SA_DQ<15>")
	)
	(segment
		(start 162.39109 -215.373966)
		(end 162.49777 -215.480646)
		(width 0.10668)
		(layer "F.Cu")
		(net "M_G_CPU1_SA_DQ<15>")
	)
	(segment
		(start 157.06979 -221.232222)
		(end 157.23489 -221.232222)
		(width 0.10668)
		(layer "F.Cu")
		(net "M_G_CPU1_SA_DQ<15>")
	)
	(segment
		(start 156.787596 -221.514416)
		(end 156.388308 -221.115128)
		(width 0.10668)
		(layer "F.Cu")
		(net "M_G_CPU1_SA_DQ<15>")
	)
	(segment
		(start 156.24937 -227.038154)
		(end 156.24937 -222.217742)
		(width 0.10668)
		(layer "F.Cu")
		(net "M_G_CPU1_SA_DQ<15>")
	)
	(segment
		(start 148.20392 -235.083604)
		(end 156.24937 -227.038154)
		(width 0.10668)
		(layer "F.Cu")
		(net "M_G_CPU1_SA_DQ<15>")
	)
	(segment
		(start 156.787596 -221.679516)
		(end 156.787596 -221.514416)
		(width 0.10668)
		(layer "F.Cu")
		(net "M_G_CPU1_SA_DQ<15>")
	)
	(segment
		(start 162.61461 -215.797892)
		(end 162.779964 -215.797892)
		(width 0.10668)
		(layer "F.Cu")
		(net "M_G_CPU1_SA_DQ<15>")
	)
	(segment
		(start 156.952696 -221.115128)
		(end 157.06979 -221.232222)
		(width 0.10668)
		(layer "F.Cu")
		(net "M_G_CPU1_SA_DQ<15>")
	)
	(segment
		(start 162.49777 -215.480646)
		(end 162.49777 -215.681052)
		(width 0.10668)
		(layer "F.Cu")
		(net "M_G_CPU1_SA_DQ<15>")
	)
	(segment
		(start 162.779964 -215.797892)
		(end 162.915346 -215.66251)
		(width 0.10668)
		(layer "F.Cu")
		(net "M_G_CPU1_SA_DQ<15>")
	)
	(segment
		(start 156.24937 -222.217742)
		(end 156.787596 -221.679516)
		(width 0.10668)
		(layer "F.Cu")
		(net "M_G_CPU1_SA_DQ<15>")
	)
	(segment
		(start 158.237174 -219.66555)
		(end 156.952696 -220.950028)
		(width 0.10668)
		(layer "F.Cu")
		(net "M_G_CPU1_SA_DQ<15>")
	)
	(segment
		(start 158.654242 -218.959938)
		(end 162.240214 -215.373966)
		(width 0.10668)
		(layer "F.Cu")
		(net "M_G_CPU1_SA_DQ<15>")
	)
	(segment
		(start 157.95498 -219.383356)
		(end 158.12008 -219.383356)
		(width 0.10668)
		(layer "F.Cu")
		(net "M_G_CPU1_SA_DQ<15>")
	)
	(segment
		(start 144.207992 -235.030264)
		(end 144.207992 -235.03001)
		(width 0.0762)
		(layer "F.Cu")
		(net "M_G_CPU1_SA_DQ<15>")
	)
	(segment
		(start 156.952696 -220.950028)
		(end 156.952696 -221.115128)
		(width 0.10668)
		(layer "F.Cu")
		(net "M_G_CPU1_SA_DQ<15>")
	)
	(segment
		(start 156.388308 -220.950028)
		(end 157.95498 -219.383356)
		(width 0.10668)
		(layer "F.Cu")
		(net "M_G_CPU1_SA_DQ<15>")
	)
	(segment
		(start 144.38757 -234.703366)
		(end 144.394936 -234.707684)
		(width 0.0762)
		(layer "F.Cu")
		(net "M_G_CPU1_SA_DQ<15>")
	)
	(segment
		(start 162.49777 -215.681052)
		(end 162.61461 -215.797892)
		(width 0.10668)
		(layer "F.Cu")
		(net "M_G_CPU1_SA_DQ<15>")
	)
	(segment
		(start 147.005802 -234.657138)
		(end 147.432268 -235.083604)
		(width 0.0762)
		(layer "F.Cu")
		(net "M_G_CPU1_SA_DQ<15>")
	)
	(segment
		(start 144.207992 -235.03001)
		(end 144.102836 -234.849162)
		(width 0.0762)
		(layer "F.Cu")
		(net "M_G_CPU1_SA_DQ<15>")
	)
	(segment
		(start 144.386554 -234.702858)
		(end 144.38757 -234.703366)
		(width 0.0762)
		(layer "F.Cu")
		(net "M_G_CPU1_SA_DQ<15>")
	)
	(segment
		(start 156.388308 -221.115128)
		(end 156.388308 -220.950028)
		(width 0.10668)
		(layer "F.Cu")
		(net "M_G_CPU1_SA_DQ<15>")
	)
	(segment
		(start 163.013644 -215.185244)
		(end 164.427916 -215.185244)
		(width 0.10668)
		(layer "F.Cu")
		(net "M_G_CPU1_SA_DQ<15>")
	)
	(segment
		(start 157.23489 -221.232222)
		(end 158.654242 -219.81287)
		(width 0.10668)
		(layer "F.Cu")
		(net "M_G_CPU1_SA_DQ<15>")
	)
	(segment
		(start 146.087846 -234.657138)
		(end 147.005802 -234.657138)
		(width 0.0762)
		(layer "F.Cu")
		(net "M_G_CPU1_SA_DQ<15>")
	)
	(segment
		(start 162.240214 -215.373966)
		(end 162.39109 -215.373966)
		(width 0.10668)
		(layer "F.Cu")
		(net "M_G_CPU1_SA_DQ<15>")
	)
	(segment
		(start 162.915346 -215.283542)
		(end 163.013644 -215.185244)
		(width 0.10668)
		(layer "F.Cu")
		(net "M_G_CPU1_SA_DQ<15>")
	)
	(segment
		(start 158.237174 -219.50045)
		(end 158.237174 -219.66555)
		(width 0.10668)
		(layer "F.Cu")
		(net "M_G_CPU1_SA_DQ<15>")
	)
	(segment
		(start 147.432268 -235.083604)
		(end 147.762468 -235.083604)
		(width 0.0762)
		(layer "F.Cu")
		(net "M_G_CPU1_SA_DQ<15>")
	)
	(segment
		(start 147.762468 -235.083604)
		(end 148.20392 -235.083604)
		(width 0.10668)
		(layer "F.Cu")
		(net "M_G_CPU1_SA_DQ<15>")
	)
	(segment
		(start 144.960848 -234.707684)
		(end 144.96923 -234.702858)
		(width 0.0762)
		(layer "F.Cu")
		(net "M_G_CPU1_SA_DQ<15>")
	)
	(segment
		(start 158.654242 -219.81287)
		(end 158.654242 -218.959938)
		(width 0.10668)
		(layer "F.Cu")
		(net "M_G_CPU1_SA_DQ<15>")
	)
	(arc
		(start 144.102836 -234.849162)
		(mid 144.111773 -234.730138)
		(end 144.206468 -234.657392)
		(width 0.0762)
		(layer "F.Cu")
		(net "M_G_CPU1_SA_DQ<15>")
	)
	(arc
		(start 144.206468 -234.657392)
		(mid 144.299392 -234.668715)
		(end 144.386554 -234.702858)
		(width 0.0762)
		(layer "F.Cu")
		(net "M_G_CPU1_SA_DQ<15>")
	)
	(arc
		(start 144.96923 -234.702858)
		(mid 145.152738 -234.657364)
		(end 145.33499 -234.707684)
		(width 0.0762)
		(layer "F.Cu")
		(net "M_G_CPU1_SA_DQ<15>")
	)
	(arc
		(start 145.900902 -234.707684)
		(mid 145.991035 -234.670064)
		(end 146.087846 -234.657138)
		(width 0.0762)
		(layer "F.Cu")
		(net "M_G_CPU1_SA_DQ<15>")
	)
	(arc
		(start 145.33499 -234.707684)
		(mid 145.617946 -234.783861)
		(end 145.900902 -234.707684)
		(width 0.0762)
		(layer "F.Cu")
		(net "M_G_CPU1_SA_DQ<15>")
	)
	(arc
		(start 144.394936 -234.707684)
		(mid 144.677892 -234.783861)
		(end 144.960848 -234.707684)
		(width 0.0762)
		(layer "F.Cu")
		(net "M_G_CPU1_SA_DQ<15>")
	)
	(segment
		(start 160.300416 -216.141554)
		(end 160.0581 -215.899238)
		(width 0.10668)
		(layer "F.Cu")
		(net "M_G_CPU1_SA_DQ<14>")
	)
	(segment
		(start 159.17164 -217.43543)
		(end 159.17164 -217.27033)
		(width 0.10668)
		(layer "F.Cu")
		(net "M_G_CPU1_SA_DQ<14>")
	)
	(segment
		(start 160.58261 -215.85936)
		(end 160.74771 -215.85936)
		(width 0.10668)
		(layer "F.Cu")
		(net "M_G_CPU1_SA_DQ<14>")
	)
	(segment
		(start 158.929324 -217.028014)
		(end 158.929324 -216.862914)
		(width 0.10668)
		(layer "F.Cu")
		(net "M_G_CPU1_SA_DQ<14>")
	)
	(segment
		(start 159.453834 -216.988136)
		(end 159.618934 -216.988136)
		(width 0.10668)
		(layer "F.Cu")
		(net "M_G_CPU1_SA_DQ<14>")
	)
	(segment
		(start 158.64713 -217.310208)
		(end 158.889446 -217.552524)
		(width 0.10668)
		(layer "F.Cu")
		(net "M_G_CPU1_SA_DQ<14>")
	)
	(segment
		(start 155.516326 -220.275912)
		(end 157.353254 -218.438984)
		(width 0.10668)
		(layer "F.Cu")
		(net "M_G_CPU1_SA_DQ<14>")
	)
	(segment
		(start 145.796508 -233.892852)
		(end 145.80489 -233.897678)
		(width 0.0762)
		(layer "F.Cu")
		(net "M_G_CPU1_SA_DQ<14>")
	)
	(segment
		(start 161.186876 -214.770462)
		(end 161.186876 -214.605362)
		(width 0.10668)
		(layer "F.Cu")
		(net "M_G_CPU1_SA_DQ<14>")
	)
	(segment
		(start 162.307016 -213.485222)
		(end 164.427916 -213.485222)
		(width 0.10668)
		(layer "F.Cu")
		(net "M_G_CPU1_SA_DQ<14>")
	)
	(segment
		(start 159.046418 -216.74582)
		(end 159.211518 -216.74582)
		(width 0.10668)
		(layer "F.Cu")
		(net "M_G_CPU1_SA_DQ<14>")
	)
	(segment
		(start 159.211518 -216.74582)
		(end 159.453834 -216.988136)
		(width 0.10668)
		(layer "F.Cu")
		(net "M_G_CPU1_SA_DQ<14>")
	)
	(segment
		(start 159.17164 -217.27033)
		(end 158.929324 -217.028014)
		(width 0.10668)
		(layer "F.Cu")
		(net "M_G_CPU1_SA_DQ<14>")
	)
	(segment
		(start 158.042864 -218.399106)
		(end 157.800548 -218.15679)
		(width 0.10668)
		(layer "F.Cu")
		(net "M_G_CPU1_SA_DQ<14>")
	)
	(segment
		(start 147.360132 -234.204764)
		(end 147.747228 -234.204764)
		(width 0.0762)
		(layer "F.Cu")
		(net "M_G_CPU1_SA_DQ<14>")
	)
	(segment
		(start 157.800548 -218.15679)
		(end 157.800548 -217.99169)
		(width 0.10668)
		(layer "F.Cu")
		(net "M_G_CPU1_SA_DQ<14>")
	)
	(segment
		(start 161.751264 -214.040974)
		(end 162.307016 -213.485222)
		(width 0.10668)
		(layer "F.Cu")
		(net "M_G_CPU1_SA_DQ<14>")
	)
	(segment
		(start 157.76067 -218.6813)
		(end 157.92577 -218.6813)
		(width 0.10668)
		(layer "F.Cu")
		(net "M_G_CPU1_SA_DQ<14>")
	)
	(segment
		(start 161.30397 -214.488268)
		(end 161.46907 -214.488268)
		(width 0.10668)
		(layer "F.Cu")
		(net "M_G_CPU1_SA_DQ<14>")
	)
	(segment
		(start 161.146998 -215.294972)
		(end 161.312098 -215.294972)
		(width 0.10668)
		(layer "F.Cu")
		(net "M_G_CPU1_SA_DQ<14>")
	)
	(segment
		(start 160.0581 -215.899238)
		(end 160.0581 -215.734138)
		(width 0.10668)
		(layer "F.Cu")
		(net "M_G_CPU1_SA_DQ<14>")
	)
	(segment
		(start 160.739582 -215.052656)
		(end 160.904682 -215.052656)
		(width 0.10668)
		(layer "F.Cu")
		(net "M_G_CPU1_SA_DQ<14>")
	)
	(segment
		(start 148.119592 -234.204764)
		(end 155.516326 -226.80803)
		(width 0.10668)
		(layer "F.Cu")
		(net "M_G_CPU1_SA_DQ<14>")
	)
	(segment
		(start 146.624294 -234.118404)
		(end 147.273772 -234.118404)
		(width 0.0762)
		(layer "F.Cu")
		(net "M_G_CPU1_SA_DQ<14>")
	)
	(segment
		(start 155.516326 -226.80803)
		(end 155.516326 -220.275912)
		(width 0.10668)
		(layer "F.Cu")
		(net "M_G_CPU1_SA_DQ<14>")
	)
	(segment
		(start 159.618934 -216.988136)
		(end 159.736028 -216.871042)
		(width 0.10668)
		(layer "F.Cu")
		(net "M_G_CPU1_SA_DQ<14>")
	)
	(segment
		(start 158.929324 -216.862914)
		(end 159.046418 -216.74582)
		(width 0.10668)
		(layer "F.Cu")
		(net "M_G_CPU1_SA_DQ<14>")
	)
	(segment
		(start 158.607252 -217.999818)
		(end 158.607252 -217.834718)
		(width 0.10668)
		(layer "F.Cu")
		(net "M_G_CPU1_SA_DQ<14>")
	)
	(segment
		(start 158.889446 -217.552524)
		(end 159.054546 -217.552524)
		(width 0.10668)
		(layer "F.Cu")
		(net "M_G_CPU1_SA_DQ<14>")
	)
	(segment
		(start 157.92577 -218.6813)
		(end 158.042864 -218.564206)
		(width 0.10668)
		(layer "F.Cu")
		(net "M_G_CPU1_SA_DQ<14>")
	)
	(segment
		(start 157.800548 -217.99169)
		(end 157.917642 -217.874596)
		(width 0.10668)
		(layer "F.Cu")
		(net "M_G_CPU1_SA_DQ<14>")
	)
	(segment
		(start 158.325058 -218.116912)
		(end 158.490158 -218.116912)
		(width 0.10668)
		(layer "F.Cu")
		(net "M_G_CPU1_SA_DQ<14>")
	)
	(segment
		(start 161.46907 -214.488268)
		(end 161.711386 -214.730584)
		(width 0.10668)
		(layer "F.Cu")
		(net "M_G_CPU1_SA_DQ<14>")
	)
	(segment
		(start 158.490158 -218.116912)
		(end 158.607252 -217.999818)
		(width 0.10668)
		(layer "F.Cu")
		(net "M_G_CPU1_SA_DQ<14>")
	)
	(segment
		(start 161.876486 -214.730584)
		(end 161.99358 -214.61349)
		(width 0.10668)
		(layer "F.Cu")
		(net "M_G_CPU1_SA_DQ<14>")
	)
	(segment
		(start 158.042864 -218.564206)
		(end 158.042864 -218.399106)
		(width 0.10668)
		(layer "F.Cu")
		(net "M_G_CPU1_SA_DQ<14>")
	)
	(segment
		(start 161.312098 -215.294972)
		(end 161.429192 -215.177878)
		(width 0.10668)
		(layer "F.Cu")
		(net "M_G_CPU1_SA_DQ<14>")
	)
	(segment
		(start 161.186876 -214.605362)
		(end 161.30397 -214.488268)
		(width 0.10668)
		(layer "F.Cu")
		(net "M_G_CPU1_SA_DQ<14>")
	)
	(segment
		(start 158.364936 -217.592402)
		(end 158.364936 -217.427302)
		(width 0.10668)
		(layer "F.Cu")
		(net "M_G_CPU1_SA_DQ<14>")
	)
	(segment
		(start 161.751264 -214.206074)
		(end 161.751264 -214.040974)
		(width 0.10668)
		(layer "F.Cu")
		(net "M_G_CPU1_SA_DQ<14>")
	)
	(segment
		(start 159.736028 -216.705942)
		(end 159.493712 -216.463626)
		(width 0.10668)
		(layer "F.Cu")
		(net "M_G_CPU1_SA_DQ<14>")
	)
	(segment
		(start 161.429192 -215.177878)
		(end 161.429192 -215.012778)
		(width 0.10668)
		(layer "F.Cu")
		(net "M_G_CPU1_SA_DQ<14>")
	)
	(segment
		(start 160.864804 -215.577166)
		(end 160.622488 -215.33485)
		(width 0.10668)
		(layer "F.Cu")
		(net "M_G_CPU1_SA_DQ<14>")
	)
	(segment
		(start 159.493712 -216.298526)
		(end 159.610806 -216.181432)
		(width 0.10668)
		(layer "F.Cu")
		(net "M_G_CPU1_SA_DQ<14>")
	)
	(segment
		(start 147.273772 -234.118404)
		(end 147.360132 -234.204764)
		(width 0.0762)
		(layer "F.Cu")
		(net "M_G_CPU1_SA_DQ<14>")
	)
	(segment
		(start 160.300416 -216.306654)
		(end 160.300416 -216.141554)
		(width 0.10668)
		(layer "F.Cu")
		(net "M_G_CPU1_SA_DQ<14>")
	)
	(segment
		(start 145.617946 -234.220258)
		(end 145.524982 -234.060238)
		(width 0.0762)
		(layer "F.Cu")
		(net "M_G_CPU1_SA_DQ<14>")
	)
	(segment
		(start 161.711386 -214.730584)
		(end 161.876486 -214.730584)
		(width 0.10668)
		(layer "F.Cu")
		(net "M_G_CPU1_SA_DQ<14>")
	)
	(segment
		(start 147.747228 -234.204764)
		(end 148.119592 -234.204764)
		(width 0.10668)
		(layer "F.Cu")
		(net "M_G_CPU1_SA_DQ<14>")
	)
	(segment
		(start 159.610806 -216.181432)
		(end 159.775906 -216.181432)
		(width 0.10668)
		(layer "F.Cu")
		(net "M_G_CPU1_SA_DQ<14>")
	)
	(segment
		(start 157.518354 -218.438984)
		(end 157.76067 -218.6813)
		(width 0.10668)
		(layer "F.Cu")
		(net "M_G_CPU1_SA_DQ<14>")
	)
	(segment
		(start 160.864804 -215.742266)
		(end 160.864804 -215.577166)
		(width 0.10668)
		(layer "F.Cu")
		(net "M_G_CPU1_SA_DQ<14>")
	)
	(segment
		(start 160.175194 -215.617044)
		(end 160.340294 -215.617044)
		(width 0.10668)
		(layer "F.Cu")
		(net "M_G_CPU1_SA_DQ<14>")
	)
	(segment
		(start 160.74771 -215.85936)
		(end 160.864804 -215.742266)
		(width 0.10668)
		(layer "F.Cu")
		(net "M_G_CPU1_SA_DQ<14>")
	)
	(segment
		(start 159.054546 -217.552524)
		(end 159.17164 -217.43543)
		(width 0.10668)
		(layer "F.Cu")
		(net "M_G_CPU1_SA_DQ<14>")
	)
	(segment
		(start 160.904682 -215.052656)
		(end 161.146998 -215.294972)
		(width 0.10668)
		(layer "F.Cu")
		(net "M_G_CPU1_SA_DQ<14>")
	)
	(segment
		(start 160.0581 -215.734138)
		(end 160.175194 -215.617044)
		(width 0.10668)
		(layer "F.Cu")
		(net "M_G_CPU1_SA_DQ<14>")
	)
	(segment
		(start 159.775906 -216.181432)
		(end 160.018222 -216.423748)
		(width 0.10668)
		(layer "F.Cu")
		(net "M_G_CPU1_SA_DQ<14>")
	)
	(segment
		(start 159.493712 -216.463626)
		(end 159.493712 -216.298526)
		(width 0.10668)
		(layer "F.Cu")
		(net "M_G_CPU1_SA_DQ<14>")
	)
	(segment
		(start 160.622488 -215.16975)
		(end 160.739582 -215.052656)
		(width 0.10668)
		(layer "F.Cu")
		(net "M_G_CPU1_SA_DQ<14>")
	)
	(segment
		(start 161.429192 -215.012778)
		(end 161.186876 -214.770462)
		(width 0.10668)
		(layer "F.Cu")
		(net "M_G_CPU1_SA_DQ<14>")
	)
	(segment
		(start 160.340294 -215.617044)
		(end 160.58261 -215.85936)
		(width 0.10668)
		(layer "F.Cu")
		(net "M_G_CPU1_SA_DQ<14>")
	)
	(segment
		(start 158.48203 -217.310208)
		(end 158.64713 -217.310208)
		(width 0.10668)
		(layer "F.Cu")
		(net "M_G_CPU1_SA_DQ<14>")
	)
	(segment
		(start 160.018222 -216.423748)
		(end 160.183322 -216.423748)
		(width 0.10668)
		(layer "F.Cu")
		(net "M_G_CPU1_SA_DQ<14>")
	)
	(segment
		(start 161.99358 -214.61349)
		(end 161.99358 -214.44839)
		(width 0.10668)
		(layer "F.Cu")
		(net "M_G_CPU1_SA_DQ<14>")
	)
	(segment
		(start 160.183322 -216.423748)
		(end 160.300416 -216.306654)
		(width 0.10668)
		(layer "F.Cu")
		(net "M_G_CPU1_SA_DQ<14>")
	)
	(segment
		(start 158.607252 -217.834718)
		(end 158.364936 -217.592402)
		(width 0.10668)
		(layer "F.Cu")
		(net "M_G_CPU1_SA_DQ<14>")
	)
	(segment
		(start 160.622488 -215.33485)
		(end 160.622488 -215.16975)
		(width 0.10668)
		(layer "F.Cu")
		(net "M_G_CPU1_SA_DQ<14>")
	)
	(segment
		(start 157.917642 -217.874596)
		(end 158.082742 -217.874596)
		(width 0.10668)
		(layer "F.Cu")
		(net "M_G_CPU1_SA_DQ<14>")
	)
	(segment
		(start 158.364936 -217.427302)
		(end 158.48203 -217.310208)
		(width 0.10668)
		(layer "F.Cu")
		(net "M_G_CPU1_SA_DQ<14>")
	)
	(segment
		(start 158.082742 -217.874596)
		(end 158.325058 -218.116912)
		(width 0.10668)
		(layer "F.Cu")
		(net "M_G_CPU1_SA_DQ<14>")
	)
	(segment
		(start 157.353254 -218.438984)
		(end 157.518354 -218.438984)
		(width 0.10668)
		(layer "F.Cu")
		(net "M_G_CPU1_SA_DQ<14>")
	)
	(segment
		(start 161.99358 -214.44839)
		(end 161.751264 -214.206074)
		(width 0.10668)
		(layer "F.Cu")
		(net "M_G_CPU1_SA_DQ<14>")
	)
	(segment
		(start 159.736028 -216.871042)
		(end 159.736028 -216.705942)
		(width 0.10668)
		(layer "F.Cu")
		(net "M_G_CPU1_SA_DQ<14>")
	)
	(arc
		(start 145.524982 -234.060238)
		(mid 145.525142 -233.913677)
		(end 145.656808 -233.849418)
		(width 0.0762)
		(layer "F.Cu")
		(net "M_G_CPU1_SA_DQ<14>")
	)
	(arc
		(start 145.656808 -233.849418)
		(mid 145.728816 -233.8642)
		(end 145.796508 -233.892852)
		(width 0.0762)
		(layer "F.Cu")
		(net "M_G_CPU1_SA_DQ<14>")
	)
	(arc
		(start 145.80489 -233.897678)
		(mid 146.199995 -234.062217)
		(end 146.624294 -234.118404)
		(width 0.0762)
		(layer "F.Cu")
		(net "M_G_CPU1_SA_DQ<14>")
	)
	(segment
		(start 156.66466 -220.192092)
		(end 156.66466 -220.026992)
		(width 0.10668)
		(layer "F.Cu")
		(net "M_G_CPU1_SA_DQ<13>")
	)
	(segment
		(start 155.86583 -226.94011)
		(end 155.86583 -220.990922)
		(width 0.10668)
		(layer "F.Cu")
		(net "M_G_CPU1_SA_DQ<13>")
	)
	(segment
		(start 165.858444 -214.760302)
		(end 166.283386 -214.33536)
		(width 0.101346)
		(layer "F.Cu")
		(net "M_G_CPU1_SA_DQ<13>")
	)
	(segment
		(start 156.256228 -220.182948)
		(end 156.382466 -220.309186)
		(width 0.10668)
		(layer "F.Cu")
		(net "M_G_CPU1_SA_DQ<13>")
	)
	(segment
		(start 157.229048 -219.627704)
		(end 157.229048 -219.462604)
		(width 0.10668)
		(layer "F.Cu")
		(net "M_G_CPU1_SA_DQ<13>")
	)
	(segment
		(start 146.087846 -234.466638)
		(end 147.213828 -234.466638)
		(width 0.0762)
		(layer "F.Cu")
		(net "M_G_CPU1_SA_DQ<13>")
	)
	(segment
		(start 156.66466 -220.026992)
		(end 156.538422 -219.900754)
		(width 0.10668)
		(layer "F.Cu")
		(net "M_G_CPU1_SA_DQ<13>")
	)
	(segment
		(start 162.372294 -214.760302)
		(end 163.377626 -214.760302)
		(width 0.10668)
		(layer "F.Cu")
		(net "M_G_CPU1_SA_DQ<13>")
	)
	(segment
		(start 157.229048 -219.462604)
		(end 157.10281 -219.336366)
		(width 0.10668)
		(layer "F.Cu")
		(net "M_G_CPU1_SA_DQ<13>")
	)
	(segment
		(start 156.538422 -219.735654)
		(end 156.655516 -219.61856)
		(width 0.10668)
		(layer "F.Cu")
		(net "M_G_CPU1_SA_DQ<13>")
	)
	(segment
		(start 157.10281 -219.171266)
		(end 157.23108 -219.042996)
		(width 0.10668)
		(layer "F.Cu")
		(net "M_G_CPU1_SA_DQ<13>")
	)
	(segment
		(start 157.10281 -219.336366)
		(end 157.10281 -219.171266)
		(width 0.10668)
		(layer "F.Cu")
		(net "M_G_CPU1_SA_DQ<13>")
	)
	(segment
		(start 147.75815 -234.665266)
		(end 148.140674 -234.665266)
		(width 0.10668)
		(layer "F.Cu")
		(net "M_G_CPU1_SA_DQ<13>")
	)
	(segment
		(start 144.490948 -234.542584)
		(end 144.490948 -234.542838)
		(width 0.0762)
		(layer "F.Cu")
		(net "M_G_CPU1_SA_DQ<13>")
	)
	(segment
		(start 157.111954 -219.744798)
		(end 157.229048 -219.627704)
		(width 0.10668)
		(layer "F.Cu")
		(net "M_G_CPU1_SA_DQ<13>")
	)
	(segment
		(start 156.820616 -219.61856)
		(end 156.946854 -219.744798)
		(width 0.10668)
		(layer "F.Cu")
		(net "M_G_CPU1_SA_DQ<13>")
	)
	(segment
		(start 166.283386 -214.33536)
		(end 168.527984 -214.33536)
		(width 0.101346)
		(layer "F.Cu")
		(net "M_G_CPU1_SA_DQ<13>")
	)
	(segment
		(start 156.538422 -219.900754)
		(end 156.538422 -219.735654)
		(width 0.10668)
		(layer "F.Cu")
		(net "M_G_CPU1_SA_DQ<13>")
	)
	(segment
		(start 163.377626 -214.760302)
		(end 165.858444 -214.760302)
		(width 0.101346)
		(layer "F.Cu")
		(net "M_G_CPU1_SA_DQ<13>")
	)
	(segment
		(start 147.412456 -234.665266)
		(end 147.75815 -234.665266)
		(width 0.0762)
		(layer "F.Cu")
		(net "M_G_CPU1_SA_DQ<13>")
	)
	(segment
		(start 156.091128 -220.182948)
		(end 156.256228 -220.182948)
		(width 0.10668)
		(layer "F.Cu")
		(net "M_G_CPU1_SA_DQ<13>")
	)
	(segment
		(start 156.547566 -220.309186)
		(end 156.66466 -220.192092)
		(width 0.10668)
		(layer "F.Cu")
		(net "M_G_CPU1_SA_DQ<13>")
	)
	(segment
		(start 158.0896 -219.042996)
		(end 162.372294 -214.760302)
		(width 0.10668)
		(layer "F.Cu")
		(net "M_G_CPU1_SA_DQ<13>")
	)
	(segment
		(start 156.655516 -219.61856)
		(end 156.820616 -219.61856)
		(width 0.10668)
		(layer "F.Cu")
		(net "M_G_CPU1_SA_DQ<13>")
	)
	(segment
		(start 148.140674 -234.665266)
		(end 155.86583 -226.94011)
		(width 0.10668)
		(layer "F.Cu")
		(net "M_G_CPU1_SA_DQ<13>")
	)
	(segment
		(start 156.382466 -220.309186)
		(end 156.547566 -220.309186)
		(width 0.10668)
		(layer "F.Cu")
		(net "M_G_CPU1_SA_DQ<13>")
	)
	(segment
		(start 145.796508 -234.547664)
		(end 145.80489 -234.542838)
		(width 0.0762)
		(layer "F.Cu")
		(net "M_G_CPU1_SA_DQ<13>")
	)
	(segment
		(start 157.23108 -219.042996)
		(end 158.0896 -219.042996)
		(width 0.10668)
		(layer "F.Cu")
		(net "M_G_CPU1_SA_DQ<13>")
	)
	(segment
		(start 156.100272 -220.59138)
		(end 155.974034 -220.465142)
		(width 0.10668)
		(layer "F.Cu")
		(net "M_G_CPU1_SA_DQ<13>")
	)
	(segment
		(start 155.974034 -220.465142)
		(end 155.974034 -220.300042)
		(width 0.10668)
		(layer "F.Cu")
		(net "M_G_CPU1_SA_DQ<13>")
	)
	(segment
		(start 155.974034 -220.300042)
		(end 156.091128 -220.182948)
		(width 0.10668)
		(layer "F.Cu")
		(net "M_G_CPU1_SA_DQ<13>")
	)
	(segment
		(start 155.86583 -220.990922)
		(end 156.100272 -220.75648)
		(width 0.10668)
		(layer "F.Cu")
		(net "M_G_CPU1_SA_DQ<13>")
	)
	(segment
		(start 147.213828 -234.466638)
		(end 147.412456 -234.665266)
		(width 0.0762)
		(layer "F.Cu")
		(net "M_G_CPU1_SA_DQ<13>")
	)
	(segment
		(start 156.100272 -220.75648)
		(end 156.100272 -220.59138)
		(width 0.10668)
		(layer "F.Cu")
		(net "M_G_CPU1_SA_DQ<13>")
	)
	(segment
		(start 156.946854 -219.744798)
		(end 157.111954 -219.744798)
		(width 0.10668)
		(layer "F.Cu")
		(net "M_G_CPU1_SA_DQ<13>")
	)
	(arc
		(start 145.80489 -234.542838)
		(mid 145.941326 -234.486013)
		(end 146.087846 -234.466638)
		(width 0.0762)
		(layer "F.Cu")
		(net "M_G_CPU1_SA_DQ<13>")
	)
	(arc
		(start 143.737838 -234.220258)
		(mid 143.941854 -234.400952)
		(end 144.206468 -234.46613)
		(width 0.0762)
		(layer "F.Cu")
		(net "M_G_CPU1_SA_DQ<13>")
	)
	(arc
		(start 145.430748 -234.542838)
		(mid 145.612999 -234.593188)
		(end 145.796508 -234.547664)
		(width 0.0762)
		(layer "F.Cu")
		(net "M_G_CPU1_SA_DQ<13>")
	)
	(arc
		(start 144.490948 -234.542838)
		(mid 144.677892 -234.593093)
		(end 144.864836 -234.542838)
		(width 0.0762)
		(layer "F.Cu")
		(net "M_G_CPU1_SA_DQ<13>")
	)
	(arc
		(start 144.206468 -234.46613)
		(mid 144.353789 -234.485449)
		(end 144.490948 -234.542584)
		(width 0.0762)
		(layer "F.Cu")
		(net "M_G_CPU1_SA_DQ<13>")
	)
	(arc
		(start 144.864836 -234.542838)
		(mid 145.147792 -234.466661)
		(end 145.430748 -234.542838)
		(width 0.0762)
		(layer "F.Cu")
		(net "M_G_CPU1_SA_DQ<13>")
	)
	(segment
		(start 166.70147 -213.82609)
		(end 166.70147 -213.175596)
		(width 0.101346)
		(layer "F.Cu")
		(net "M_G_CPU1_SA_DQ<12>")
	)
	(segment
		(start 146.86407 -233.790744)
		(end 147.150328 -233.790744)
		(width 0.10668)
		(layer "F.Cu")
		(net "M_G_CPU1_SA_DQ<12>")
	)
	(segment
		(start 147.666202 -233.481626)
		(end 147.666202 -233.673904)
		(width 0.10668)
		(layer "F.Cu")
		(net "M_G_CPU1_SA_DQ<12>")
	)
	(segment
		(start 146.115532 -233.790744)
		(end 146.86407 -233.790744)
		(width 0.0762)
		(layer "F.Cu")
		(net "M_G_CPU1_SA_DQ<12>")
	)
	(segment
		(start 162.250374 -213.06028)
		(end 163.339526 -213.06028)
		(width 0.10668)
		(layer "F.Cu")
		(net "M_G_CPU1_SA_DQ<12>")
	)
	(segment
		(start 147.150328 -233.790744)
		(end 147.267168 -233.673904)
		(width 0.10668)
		(layer "F.Cu")
		(net "M_G_CPU1_SA_DQ<12>")
	)
	(segment
		(start 166.586154 -213.941406)
		(end 166.70147 -213.82609)
		(width 0.101346)
		(layer "F.Cu")
		(net "M_G_CPU1_SA_DQ<12>")
	)
	(segment
		(start 148.052028 -233.790744)
		(end 155.175966 -226.666806)
		(width 0.10668)
		(layer "F.Cu")
		(net "M_G_CPU1_SA_DQ<12>")
	)
	(segment
		(start 166.816786 -213.06028)
		(end 167.16756 -213.06028)
		(width 0.101346)
		(layer "F.Cu")
		(net "M_G_CPU1_SA_DQ<12>")
	)
	(segment
		(start 147.267168 -233.673904)
		(end 147.267168 -233.481626)
		(width 0.10668)
		(layer "F.Cu")
		(net "M_G_CPU1_SA_DQ<12>")
	)
	(segment
		(start 155.175966 -226.666806)
		(end 155.175966 -220.134688)
		(width 0.10668)
		(layer "F.Cu")
		(net "M_G_CPU1_SA_DQ<12>")
	)
	(segment
		(start 147.267168 -233.481626)
		(end 147.384008 -233.364786)
		(width 0.10668)
		(layer "F.Cu")
		(net "M_G_CPU1_SA_DQ<12>")
	)
	(segment
		(start 166.192454 -213.06028)
		(end 166.30777 -213.175596)
		(width 0.101346)
		(layer "F.Cu")
		(net "M_G_CPU1_SA_DQ<12>")
	)
	(segment
		(start 147.549362 -233.364786)
		(end 147.666202 -233.481626)
		(width 0.10668)
		(layer "F.Cu")
		(net "M_G_CPU1_SA_DQ<12>")
	)
	(segment
		(start 167.592502 -212.635338)
		(end 168.527984 -212.635338)
		(width 0.101346)
		(layer "F.Cu")
		(net "M_G_CPU1_SA_DQ<12>")
	)
	(segment
		(start 166.30777 -213.82609)
		(end 166.423086 -213.941406)
		(width 0.101346)
		(layer "F.Cu")
		(net "M_G_CPU1_SA_DQ<12>")
	)
	(segment
		(start 147.384008 -233.364786)
		(end 147.549362 -233.364786)
		(width 0.10668)
		(layer "F.Cu")
		(net "M_G_CPU1_SA_DQ<12>")
	)
	(segment
		(start 166.70147 -213.175596)
		(end 166.816786 -213.06028)
		(width 0.101346)
		(layer "F.Cu")
		(net "M_G_CPU1_SA_DQ<12>")
	)
	(segment
		(start 167.16756 -213.06028)
		(end 167.592502 -212.635338)
		(width 0.101346)
		(layer "F.Cu")
		(net "M_G_CPU1_SA_DQ<12>")
	)
	(segment
		(start 155.175966 -220.134688)
		(end 162.250374 -213.06028)
		(width 0.10668)
		(layer "F.Cu")
		(net "M_G_CPU1_SA_DQ<12>")
	)
	(segment
		(start 166.423086 -213.941406)
		(end 166.586154 -213.941406)
		(width 0.101346)
		(layer "F.Cu")
		(net "M_G_CPU1_SA_DQ<12>")
	)
	(segment
		(start 163.339526 -213.06028)
		(end 166.192454 -213.06028)
		(width 0.101346)
		(layer "F.Cu")
		(net "M_G_CPU1_SA_DQ<12>")
	)
	(segment
		(start 147.783042 -233.790744)
		(end 148.052028 -233.790744)
		(width 0.10668)
		(layer "F.Cu")
		(net "M_G_CPU1_SA_DQ<12>")
	)
	(segment
		(start 166.30777 -213.175596)
		(end 166.30777 -213.82609)
		(width 0.101346)
		(layer "F.Cu")
		(net "M_G_CPU1_SA_DQ<12>")
	)
	(segment
		(start 147.666202 -233.673904)
		(end 147.783042 -233.790744)
		(width 0.10668)
		(layer "F.Cu")
		(net "M_G_CPU1_SA_DQ<12>")
	)
	(arc
		(start 145.665444 -233.65841)
		(mid 145.7873 -233.682566)
		(end 145.900902 -233.732832)
		(width 0.0762)
		(layer "F.Cu")
		(net "M_G_CPU1_SA_DQ<12>")
	)
	(arc
		(start 145.900902 -233.732832)
		(mid 146.00438 -233.776008)
		(end 146.115532 -233.790744)
		(width 0.0762)
		(layer "F.Cu")
		(net "M_G_CPU1_SA_DQ<12>")
	)
	(arc
		(start 145.147792 -233.410252)
		(mid 145.38392 -233.581687)
		(end 145.665444 -233.65841)
		(width 0.0762)
		(layer "F.Cu")
		(net "M_G_CPU1_SA_DQ<12>")
	)
	(segment
		(start 155.80995 -215.305386)
		(end 155.80995 -215.140286)
		(width 0.10668)
		(layer "F.Cu")
		(net "M_G_CPU1_SA_DQ<11>")
	)
	(segment
		(start 157.887416 -213.996524)
		(end 157.503114 -213.612222)
		(width 0.10668)
		(layer "F.Cu")
		(net "M_G_CPU1_SA_DQ<11>")
	)
	(segment
		(start 157.22092 -213.894416)
		(end 157.605222 -214.278718)
		(width 0.10668)
		(layer "F.Cu")
		(net "M_G_CPU1_SA_DQ<11>")
	)
	(segment
		(start 156.194252 -215.854788)
		(end 156.194252 -215.689688)
		(width 0.10668)
		(layer "F.Cu")
		(net "M_G_CPU1_SA_DQ<11>")
	)
	(segment
		(start 155.927044 -215.023192)
		(end 156.092144 -215.023192)
		(width 0.10668)
		(layer "F.Cu")
		(net "M_G_CPU1_SA_DQ<11>")
	)
	(segment
		(start 156.75864 -215.1253)
		(end 156.374338 -214.740998)
		(width 0.10668)
		(layer "F.Cu")
		(net "M_G_CPU1_SA_DQ<11>")
	)
	(segment
		(start 157.05582 -213.894416)
		(end 157.22092 -213.894416)
		(width 0.10668)
		(layer "F.Cu")
		(net "M_G_CPU1_SA_DQ<11>")
	)
	(segment
		(start 157.040834 -214.843106)
		(end 157.205934 -214.843106)
		(width 0.10668)
		(layer "F.Cu")
		(net "M_G_CPU1_SA_DQ<11>")
	)
	(segment
		(start 156.656532 -214.458804)
		(end 157.040834 -214.843106)
		(width 0.10668)
		(layer "F.Cu")
		(net "M_G_CPU1_SA_DQ<11>")
	)
	(segment
		(start 156.938726 -214.17661)
		(end 156.938726 -214.01151)
		(width 0.10668)
		(layer "F.Cu")
		(net "M_G_CPU1_SA_DQ<11>")
	)
	(segment
		(start 157.205934 -214.843106)
		(end 157.323028 -214.726012)
		(width 0.10668)
		(layer "F.Cu")
		(net "M_G_CPU1_SA_DQ<11>")
	)
	(segment
		(start 157.605222 -214.278718)
		(end 157.770322 -214.278718)
		(width 0.10668)
		(layer "F.Cu")
		(net "M_G_CPU1_SA_DQ<11>")
	)
	(segment
		(start 157.887416 -214.161624)
		(end 157.887416 -213.996524)
		(width 0.10668)
		(layer "F.Cu")
		(net "M_G_CPU1_SA_DQ<11>")
	)
	(segment
		(start 157.503114 -213.612222)
		(end 157.503114 -213.434422)
		(width 0.10668)
		(layer "F.Cu")
		(net "M_G_CPU1_SA_DQ<11>")
	)
	(segment
		(start 157.323028 -214.726012)
		(end 157.323028 -214.560912)
		(width 0.10668)
		(layer "F.Cu")
		(net "M_G_CPU1_SA_DQ<11>")
	)
	(segment
		(start 144.960848 -231.467914)
		(end 144.96923 -231.463088)
		(width 0.0762)
		(layer "F.Cu")
		(net "M_G_CPU1_SA_DQ<11>")
	)
	(segment
		(start 147.700238 -231.417114)
		(end 153.240486 -225.876866)
		(width 0.10668)
		(layer "F.Cu")
		(net "M_G_CPU1_SA_DQ<11>")
	)
	(segment
		(start 157.323028 -214.560912)
		(end 156.938726 -214.17661)
		(width 0.10668)
		(layer "F.Cu")
		(net "M_G_CPU1_SA_DQ<11>")
	)
	(segment
		(start 146.087846 -231.417114)
		(end 147.491958 -231.417114)
		(width 0.0762)
		(layer "F.Cu")
		(net "M_G_CPU1_SA_DQ<11>")
	)
	(segment
		(start 156.75864 -215.2904)
		(end 156.75864 -215.1253)
		(width 0.10668)
		(layer "F.Cu")
		(net "M_G_CPU1_SA_DQ<11>")
	)
	(segment
		(start 147.491958 -231.417114)
		(end 147.700238 -231.417114)
		(width 0.10668)
		(layer "F.Cu")
		(net "M_G_CPU1_SA_DQ<11>")
	)
	(segment
		(start 156.194252 -215.689688)
		(end 155.80995 -215.305386)
		(width 0.10668)
		(layer "F.Cu")
		(net "M_G_CPU1_SA_DQ<11>")
	)
	(segment
		(start 144.386554 -231.463088)
		(end 144.38757 -231.463596)
		(width 0.0762)
		(layer "F.Cu")
		(net "M_G_CPU1_SA_DQ<11>")
	)
	(segment
		(start 157.503114 -213.434422)
		(end 161.702242 -209.235294)
		(width 0.10668)
		(layer "F.Cu")
		(net "M_G_CPU1_SA_DQ<11>")
	)
	(segment
		(start 144.207992 -231.79024)
		(end 144.102836 -231.609392)
		(width 0.0762)
		(layer "F.Cu")
		(net "M_G_CPU1_SA_DQ<11>")
	)
	(segment
		(start 157.770322 -214.278718)
		(end 157.887416 -214.161624)
		(width 0.10668)
		(layer "F.Cu")
		(net "M_G_CPU1_SA_DQ<11>")
	)
	(segment
		(start 156.938726 -214.01151)
		(end 157.05582 -213.894416)
		(width 0.10668)
		(layer "F.Cu")
		(net "M_G_CPU1_SA_DQ<11>")
	)
	(segment
		(start 156.476446 -215.407494)
		(end 156.641546 -215.407494)
		(width 0.10668)
		(layer "F.Cu")
		(net "M_G_CPU1_SA_DQ<11>")
	)
	(segment
		(start 156.641546 -215.407494)
		(end 156.75864 -215.2904)
		(width 0.10668)
		(layer "F.Cu")
		(net "M_G_CPU1_SA_DQ<11>")
	)
	(segment
		(start 156.374338 -214.575898)
		(end 156.491432 -214.458804)
		(width 0.10668)
		(layer "F.Cu")
		(net "M_G_CPU1_SA_DQ<11>")
	)
	(segment
		(start 153.240486 -218.808554)
		(end 156.194252 -215.854788)
		(width 0.10668)
		(layer "F.Cu")
		(net "M_G_CPU1_SA_DQ<11>")
	)
	(segment
		(start 153.240486 -225.876866)
		(end 153.240486 -218.808554)
		(width 0.10668)
		(layer "F.Cu")
		(net "M_G_CPU1_SA_DQ<11>")
	)
	(segment
		(start 156.374338 -214.740998)
		(end 156.374338 -214.575898)
		(width 0.10668)
		(layer "F.Cu")
		(net "M_G_CPU1_SA_DQ<11>")
	)
	(segment
		(start 155.80995 -215.140286)
		(end 155.927044 -215.023192)
		(width 0.10668)
		(layer "F.Cu")
		(net "M_G_CPU1_SA_DQ<11>")
	)
	(segment
		(start 156.491432 -214.458804)
		(end 156.656532 -214.458804)
		(width 0.10668)
		(layer "F.Cu")
		(net "M_G_CPU1_SA_DQ<11>")
	)
	(segment
		(start 161.702242 -209.235294)
		(end 164.427916 -209.235294)
		(width 0.10668)
		(layer "F.Cu")
		(net "M_G_CPU1_SA_DQ<11>")
	)
	(segment
		(start 156.092144 -215.023192)
		(end 156.476446 -215.407494)
		(width 0.10668)
		(layer "F.Cu")
		(net "M_G_CPU1_SA_DQ<11>")
	)
	(segment
		(start 144.38757 -231.463596)
		(end 144.394936 -231.467914)
		(width 0.0762)
		(layer "F.Cu")
		(net "M_G_CPU1_SA_DQ<11>")
	)
	(arc
		(start 145.900902 -231.467914)
		(mid 145.991015 -231.430145)
		(end 146.087846 -231.417114)
		(width 0.0762)
		(layer "F.Cu")
		(net "M_G_CPU1_SA_DQ<11>")
	)
	(arc
		(start 144.96923 -231.463088)
		(mid 145.152738 -231.417563)
		(end 145.33499 -231.467914)
		(width 0.0762)
		(layer "F.Cu")
		(net "M_G_CPU1_SA_DQ<11>")
	)
	(arc
		(start 144.394936 -231.467914)
		(mid 144.677892 -231.544091)
		(end 144.960848 -231.467914)
		(width 0.0762)
		(layer "F.Cu")
		(net "M_G_CPU1_SA_DQ<11>")
	)
	(arc
		(start 144.206468 -231.417622)
		(mid 144.299392 -231.428945)
		(end 144.386554 -231.463088)
		(width 0.0762)
		(layer "F.Cu")
		(net "M_G_CPU1_SA_DQ<11>")
	)
	(arc
		(start 145.33499 -231.467914)
		(mid 145.617946 -231.544091)
		(end 145.900902 -231.467914)
		(width 0.0762)
		(layer "F.Cu")
		(net "M_G_CPU1_SA_DQ<11>")
	)
	(arc
		(start 144.102836 -231.609392)
		(mid 144.111773 -231.490368)
		(end 144.206468 -231.417622)
		(width 0.0762)
		(layer "F.Cu")
		(net "M_G_CPU1_SA_DQ<11>")
	)
	(segment
		(start 153.426922 -217.515694)
		(end 153.426922 -217.350594)
		(width 0.10668)
		(layer "F.Cu")
		(net "M_G_CPU1_SA_DQ<10>")
	)
	(segment
		(start 154.837892 -215.939624)
		(end 155.002992 -215.939624)
		(width 0.10668)
		(layer "F.Cu")
		(net "M_G_CPU1_SA_DQ<10>")
	)
	(segment
		(start 154.438604 -216.504012)
		(end 154.555698 -216.386918)
		(width 0.10668)
		(layer "F.Cu")
		(net "M_G_CPU1_SA_DQ<10>")
	)
	(segment
		(start 153.390092 -216.749376)
		(end 153.709116 -217.0684)
		(width 0.10668)
		(layer "F.Cu")
		(net "M_G_CPU1_SA_DQ<10>")
	)
	(segment
		(start 152.559766 -225.594418)
		(end 152.559766 -217.414602)
		(width 0.10668)
		(layer "F.Cu")
		(net "M_G_CPU1_SA_DQ<10>")
	)
	(segment
		(start 153.99131 -216.951306)
		(end 153.99131 -216.786206)
		(width 0.10668)
		(layer "F.Cu")
		(net "M_G_CPU1_SA_DQ<10>")
	)
	(segment
		(start 147.48256 -230.671624)
		(end 152.559766 -225.594418)
		(width 0.10668)
		(layer "F.Cu")
		(net "M_G_CPU1_SA_DQ<10>")
	)
	(segment
		(start 153.95448 -216.184988)
		(end 154.273504 -216.504012)
		(width 0.10668)
		(layer "F.Cu")
		(net "M_G_CPU1_SA_DQ<10>")
	)
	(segment
		(start 154.555698 -216.221818)
		(end 154.236674 -215.902794)
		(width 0.10668)
		(layer "F.Cu")
		(net "M_G_CPU1_SA_DQ<10>")
	)
	(segment
		(start 153.426922 -217.350594)
		(end 153.107898 -217.03157)
		(width 0.10668)
		(layer "F.Cu")
		(net "M_G_CPU1_SA_DQ<10>")
	)
	(segment
		(start 162.439096 -207.535272)
		(end 164.427916 -207.535272)
		(width 0.10668)
		(layer "F.Cu")
		(net "M_G_CPU1_SA_DQ<10>")
	)
	(segment
		(start 153.107898 -216.86647)
		(end 153.224992 -216.749376)
		(width 0.10668)
		(layer "F.Cu")
		(net "M_G_CPU1_SA_DQ<10>")
	)
	(segment
		(start 154.353768 -215.6206)
		(end 154.518868 -215.6206)
		(width 0.10668)
		(layer "F.Cu")
		(net "M_G_CPU1_SA_DQ<10>")
	)
	(segment
		(start 154.273504 -216.504012)
		(end 154.438604 -216.504012)
		(width 0.10668)
		(layer "F.Cu")
		(net "M_G_CPU1_SA_DQ<10>")
	)
	(segment
		(start 154.518868 -215.6206)
		(end 154.837892 -215.939624)
		(width 0.10668)
		(layer "F.Cu")
		(net "M_G_CPU1_SA_DQ<10>")
	)
	(segment
		(start 153.309828 -217.632788)
		(end 153.426922 -217.515694)
		(width 0.10668)
		(layer "F.Cu")
		(net "M_G_CPU1_SA_DQ<10>")
	)
	(segment
		(start 153.672286 -216.467182)
		(end 153.672286 -216.302082)
		(width 0.10668)
		(layer "F.Cu")
		(net "M_G_CPU1_SA_DQ<10>")
	)
	(segment
		(start 145.617946 -230.980234)
		(end 145.524982 -230.820214)
		(width 0.0762)
		(layer "F.Cu")
		(net "M_G_CPU1_SA_DQ<10>")
	)
	(segment
		(start 153.107898 -217.03157)
		(end 153.107898 -216.86647)
		(width 0.10668)
		(layer "F.Cu")
		(net "M_G_CPU1_SA_DQ<10>")
	)
	(segment
		(start 154.555698 -216.386918)
		(end 154.555698 -216.221818)
		(width 0.10668)
		(layer "F.Cu")
		(net "M_G_CPU1_SA_DQ<10>")
	)
	(segment
		(start 155.120086 -215.82253)
		(end 155.120086 -215.65743)
		(width 0.10668)
		(layer "F.Cu")
		(net "M_G_CPU1_SA_DQ<10>")
	)
	(segment
		(start 154.236674 -215.902794)
		(end 154.236674 -215.737694)
		(width 0.10668)
		(layer "F.Cu")
		(net "M_G_CPU1_SA_DQ<10>")
	)
	(segment
		(start 154.236674 -215.737694)
		(end 154.353768 -215.6206)
		(width 0.10668)
		(layer "F.Cu")
		(net "M_G_CPU1_SA_DQ<10>")
	)
	(segment
		(start 146.59229 -230.869744)
		(end 146.999452 -230.869744)
		(width 0.0762)
		(layer "F.Cu")
		(net "M_G_CPU1_SA_DQ<10>")
	)
	(segment
		(start 152.660604 -217.313764)
		(end 152.825704 -217.313764)
		(width 0.10668)
		(layer "F.Cu")
		(net "M_G_CPU1_SA_DQ<10>")
	)
	(segment
		(start 153.874216 -217.0684)
		(end 153.99131 -216.951306)
		(width 0.10668)
		(layer "F.Cu")
		(net "M_G_CPU1_SA_DQ<10>")
	)
	(segment
		(start 153.672286 -216.302082)
		(end 153.78938 -216.184988)
		(width 0.10668)
		(layer "F.Cu")
		(net "M_G_CPU1_SA_DQ<10>")
	)
	(segment
		(start 147.197572 -230.671624)
		(end 147.48256 -230.671624)
		(width 0.0762)
		(layer "F.Cu")
		(net "M_G_CPU1_SA_DQ<10>")
	)
	(segment
		(start 154.801062 -215.173306)
		(end 162.439096 -207.535272)
		(width 0.10668)
		(layer "F.Cu")
		(net "M_G_CPU1_SA_DQ<10>")
	)
	(segment
		(start 153.78938 -216.184988)
		(end 153.95448 -216.184988)
		(width 0.10668)
		(layer "F.Cu")
		(net "M_G_CPU1_SA_DQ<10>")
	)
	(segment
		(start 153.709116 -217.0684)
		(end 153.874216 -217.0684)
		(width 0.10668)
		(layer "F.Cu")
		(net "M_G_CPU1_SA_DQ<10>")
	)
	(segment
		(start 153.99131 -216.786206)
		(end 153.672286 -216.467182)
		(width 0.10668)
		(layer "F.Cu")
		(net "M_G_CPU1_SA_DQ<10>")
	)
	(segment
		(start 153.224992 -216.749376)
		(end 153.390092 -216.749376)
		(width 0.10668)
		(layer "F.Cu")
		(net "M_G_CPU1_SA_DQ<10>")
	)
	(segment
		(start 145.796508 -230.652828)
		(end 145.80489 -230.657654)
		(width 0.0762)
		(layer "F.Cu")
		(net "M_G_CPU1_SA_DQ<10>")
	)
	(segment
		(start 152.825704 -217.313764)
		(end 153.144728 -217.632788)
		(width 0.10668)
		(layer "F.Cu")
		(net "M_G_CPU1_SA_DQ<10>")
	)
	(segment
		(start 155.002992 -215.939624)
		(end 155.120086 -215.82253)
		(width 0.10668)
		(layer "F.Cu")
		(net "M_G_CPU1_SA_DQ<10>")
	)
	(segment
		(start 152.559766 -217.414602)
		(end 152.660604 -217.313764)
		(width 0.10668)
		(layer "F.Cu")
		(net "M_G_CPU1_SA_DQ<10>")
	)
	(segment
		(start 155.120086 -215.65743)
		(end 154.801062 -215.338406)
		(width 0.10668)
		(layer "F.Cu")
		(net "M_G_CPU1_SA_DQ<10>")
	)
	(segment
		(start 153.144728 -217.632788)
		(end 153.309828 -217.632788)
		(width 0.10668)
		(layer "F.Cu")
		(net "M_G_CPU1_SA_DQ<10>")
	)
	(segment
		(start 146.999452 -230.869744)
		(end 147.197572 -230.671624)
		(width 0.0762)
		(layer "F.Cu")
		(net "M_G_CPU1_SA_DQ<10>")
	)
	(segment
		(start 154.801062 -215.338406)
		(end 154.801062 -215.173306)
		(width 0.10668)
		(layer "F.Cu")
		(net "M_G_CPU1_SA_DQ<10>")
	)
	(arc
		(start 145.524982 -230.820214)
		(mid 145.525142 -230.673653)
		(end 145.656808 -230.609394)
		(width 0.0762)
		(layer "F.Cu")
		(net "M_G_CPU1_SA_DQ<10>")
	)
	(arc
		(start 145.656808 -230.609394)
		(mid 145.728816 -230.624176)
		(end 145.796508 -230.652828)
		(width 0.0762)
		(layer "F.Cu")
		(net "M_G_CPU1_SA_DQ<10>")
	)
	(arc
		(start 145.80489 -230.657654)
		(mid 146.184558 -230.815793)
		(end 146.59229 -230.869744)
		(width 0.0762)
		(layer "F.Cu")
		(net "M_G_CPU1_SA_DQ<10>")
	)
	(segment
		(start 146.583146 -224.406206)
		(end 147.616164 -223.373188)
		(width 0.10668)
		(layer "F.Cu")
		(net "M_G_CPU1_SA_DQ<0>")
	)
	(segment
		(start 162.07486 -198.714106)
		(end 162.07486 -198.549006)
		(width 0.10668)
		(layer "F.Cu")
		(net "M_G_CPU1_SA_DQ<0>")
	)
	(segment
		(start 167.020494 -197.760336)
		(end 167.445436 -197.335394)
		(width 0.101346)
		(layer "F.Cu")
		(net "M_G_CPU1_SA_DQ<0>")
	)
	(segment
		(start 147.616164 -214.643462)
		(end 148.655786 -212.13318)
		(width 0.10668)
		(layer "F.Cu")
		(net "M_G_CPU1_SA_DQ<0>")
	)
	(segment
		(start 162.150806 -198.060818)
		(end 162.357054 -198.266812)
		(width 0.10668)
		(layer "F.Cu")
		(net "M_G_CPU1_SA_DQ<0>")
	)
	(segment
		(start 163.377626 -197.760336)
		(end 167.020494 -197.760336)
		(width 0.101346)
		(layer "F.Cu")
		(net "M_G_CPU1_SA_DQ<0>")
	)
	(segment
		(start 162.357054 -198.266812)
		(end 162.522154 -198.266812)
		(width 0.10668)
		(layer "F.Cu")
		(net "M_G_CPU1_SA_DQ<0>")
	)
	(segment
		(start 147.616164 -223.373188)
		(end 147.616164 -214.643462)
		(width 0.10668)
		(layer "F.Cu")
		(net "M_G_CPU1_SA_DQ<0>")
	)
	(segment
		(start 148.655786 -212.13318)
		(end 162.07486 -198.714106)
		(width 0.10668)
		(layer "F.Cu")
		(net "M_G_CPU1_SA_DQ<0>")
	)
	(segment
		(start 146.058128 -224.931224)
		(end 146.583146 -224.406206)
		(width 0.0762)
		(layer "F.Cu")
		(net "M_G_CPU1_SA_DQ<0>")
	)
	(segment
		(start 162.522154 -198.266812)
		(end 163.02863 -197.760336)
		(width 0.10668)
		(layer "F.Cu")
		(net "M_G_CPU1_SA_DQ<0>")
	)
	(segment
		(start 167.445436 -197.335394)
		(end 168.527984 -197.335394)
		(width 0.101346)
		(layer "F.Cu")
		(net "M_G_CPU1_SA_DQ<0>")
	)
	(segment
		(start 163.02863 -197.760336)
		(end 163.377626 -197.760336)
		(width 0.10668)
		(layer "F.Cu")
		(net "M_G_CPU1_SA_DQ<0>")
	)
	(segment
		(start 161.868612 -198.177912)
		(end 161.985706 -198.060818)
		(width 0.10668)
		(layer "F.Cu")
		(net "M_G_CPU1_SA_DQ<0>")
	)
	(segment
		(start 161.985706 -198.060818)
		(end 162.150806 -198.060818)
		(width 0.10668)
		(layer "F.Cu")
		(net "M_G_CPU1_SA_DQ<0>")
	)
	(segment
		(start 162.07486 -198.549006)
		(end 161.868612 -198.343012)
		(width 0.10668)
		(layer "F.Cu")
		(net "M_G_CPU1_SA_DQ<0>")
	)
	(segment
		(start 161.868612 -198.343012)
		(end 161.868612 -198.177912)
		(width 0.10668)
		(layer "F.Cu")
		(net "M_G_CPU1_SA_DQ<0>")
	)
	(arc
		(start 145.147792 -225.310446)
		(mid 145.565042 -225.029806)
		(end 146.058128 -224.931224)
		(width 0.0762)
		(layer "F.Cu")
		(net "M_G_CPU1_SA_DQ<0>")
	)
	(segment
		(start 150.832312 -251.171456)
		(end 158.84398 -251.171456)
		(width 0.10668)
		(layer "F.Cu")
		(net "M_G_CPU1_SA_CS_N<1>")
	)
	(segment
		(start 145.796508 -252.367796)
		(end 145.80489 -252.36297)
		(width 0.0762)
		(layer "F.Cu")
		(net "M_G_CPU1_SA_CS_N<1>")
	)
	(segment
		(start 158.84398 -251.171456)
		(end 163.380166 -246.63527)
		(width 0.10668)
		(layer "F.Cu")
		(net "M_G_CPU1_SA_CS_N<1>")
	)
	(segment
		(start 163.380166 -246.63527)
		(end 164.427916 -246.63527)
		(width 0.10668)
		(layer "F.Cu")
		(net "M_G_CPU1_SA_CS_N<1>")
	)
	(segment
		(start 146.962368 -252.172724)
		(end 147.079208 -252.289564)
		(width 0.10668)
		(layer "F.Cu")
		(net "M_G_CPU1_SA_CS_N<1>")
	)
	(segment
		(start 144.490948 -252.362716)
		(end 144.490948 -252.36297)
		(width 0.0762)
		(layer "F.Cu")
		(net "M_G_CPU1_SA_CS_N<1>")
	)
	(segment
		(start 147.079208 -252.289564)
		(end 149.714204 -252.289564)
		(width 0.10668)
		(layer "F.Cu")
		(net "M_G_CPU1_SA_CS_N<1>")
	)
	(segment
		(start 146.511264 -252.172724)
		(end 146.962368 -252.172724)
		(width 0.0762)
		(layer "F.Cu")
		(net "M_G_CPU1_SA_CS_N<1>")
	)
	(segment
		(start 149.714204 -252.289564)
		(end 150.832312 -251.171456)
		(width 0.10668)
		(layer "F.Cu")
		(net "M_G_CPU1_SA_CS_N<1>")
	)
	(arc
		(start 145.430748 -252.36297)
		(mid 145.612999 -252.41332)
		(end 145.796508 -252.367796)
		(width 0.0762)
		(layer "F.Cu")
		(net "M_G_CPU1_SA_CS_N<1>")
	)
	(arc
		(start 145.80489 -252.36297)
		(mid 146.145494 -252.221134)
		(end 146.511264 -252.172724)
		(width 0.0762)
		(layer "F.Cu")
		(net "M_G_CPU1_SA_CS_N<1>")
	)
	(arc
		(start 143.737838 -252.04039)
		(mid 143.941854 -252.221084)
		(end 144.206468 -252.286262)
		(width 0.0762)
		(layer "F.Cu")
		(net "M_G_CPU1_SA_CS_N<1>")
	)
	(arc
		(start 144.206468 -252.286262)
		(mid 144.353789 -252.305581)
		(end 144.490948 -252.362716)
		(width 0.0762)
		(layer "F.Cu")
		(net "M_G_CPU1_SA_CS_N<1>")
	)
	(arc
		(start 144.864836 -252.36297)
		(mid 145.147792 -252.286793)
		(end 145.430748 -252.36297)
		(width 0.0762)
		(layer "F.Cu")
		(net "M_G_CPU1_SA_CS_N<1>")
	)
	(arc
		(start 144.490948 -252.36297)
		(mid 144.677892 -252.413225)
		(end 144.864836 -252.36297)
		(width 0.0762)
		(layer "F.Cu")
		(net "M_G_CPU1_SA_CS_N<1>")
	)
	(segment
		(start 146.107912 -251.608844)
		(end 147.363688 -251.608844)
		(width 0.0762)
		(layer "F.Cu")
		(net "M_G_CPU1_SA_CS_N<0>")
	)
	(segment
		(start 163.591748 -245.360444)
		(end 165.296596 -245.360444)
		(width 0.101346)
		(layer "F.Cu")
		(net "M_G_CPU1_SA_CS_N<0>")
	)
	(segment
		(start 149.751796 -251.608844)
		(end 150.631144 -250.729496)
		(width 0.10668)
		(layer "F.Cu")
		(net "M_G_CPU1_SA_CS_N<0>")
	)
	(segment
		(start 165.296596 -245.360444)
		(end 165.721538 -245.785386)
		(width 0.101346)
		(layer "F.Cu")
		(net "M_G_CPU1_SA_CS_N<0>")
	)
	(segment
		(start 147.363688 -251.608844)
		(end 149.751796 -251.608844)
		(width 0.10668)
		(layer "F.Cu")
		(net "M_G_CPU1_SA_CS_N<0>")
	)
	(segment
		(start 165.721538 -245.785386)
		(end 168.527984 -245.785386)
		(width 0.101346)
		(layer "F.Cu")
		(net "M_G_CPU1_SA_CS_N<0>")
	)
	(segment
		(start 158.222696 -250.729496)
		(end 163.419028 -245.533164)
		(width 0.10668)
		(layer "F.Cu")
		(net "M_G_CPU1_SA_CS_N<0>")
	)
	(segment
		(start 163.419028 -245.533164)
		(end 163.591748 -245.360444)
		(width 0.101346)
		(layer "F.Cu")
		(net "M_G_CPU1_SA_CS_N<0>")
	)
	(segment
		(start 150.631144 -250.729496)
		(end 158.222696 -250.729496)
		(width 0.10668)
		(layer "F.Cu")
		(net "M_G_CPU1_SA_CS_N<0>")
	)
	(arc
		(start 145.900902 -251.552964)
		(mid 146.000709 -251.594593)
		(end 146.107912 -251.608844)
		(width 0.0762)
		(layer "F.Cu")
		(net "M_G_CPU1_SA_CS_N<0>")
	)
	(arc
		(start 145.665444 -251.478542)
		(mid 145.7873 -251.502698)
		(end 145.900902 -251.552964)
		(width 0.0762)
		(layer "F.Cu")
		(net "M_G_CPU1_SA_CS_N<0>")
	)
	(arc
		(start 145.147792 -251.230384)
		(mid 145.38392 -251.401819)
		(end 145.665444 -251.478542)
		(width 0.0762)
		(layer "F.Cu")
		(net "M_G_CPU1_SA_CS_N<0>")
	)
	(segment
		(start 163.489132 -243.235226)
		(end 164.427916 -243.235226)
		(width 0.10668)
		(layer "F.Cu")
		(net "M_G_CPU1_SA_CB<7>")
	)
	(segment
		(start 147.51431 -249.657362)
		(end 149.56155 -249.657362)
		(width 0.10668)
		(layer "F.Cu")
		(net "M_G_CPU1_SA_CB<7>")
	)
	(segment
		(start 159.355028 -247.325134)
		(end 159.520128 -247.325134)
		(width 0.10668)
		(layer "F.Cu")
		(net "M_G_CPU1_SA_CB<7>")
	)
	(segment
		(start 157.649672 -249.195336)
		(end 157.944058 -248.901204)
		(width 0.10668)
		(layer "F.Cu")
		(net "M_G_CPU1_SA_CB<7>")
	)
	(segment
		(start 149.56155 -249.657362)
		(end 150.023576 -249.195336)
		(width 0.10668)
		(layer "F.Cu")
		(net "M_G_CPU1_SA_CB<7>")
	)
	(segment
		(start 158.226252 -248.45391)
		(end 158.391352 -248.45391)
		(width 0.10668)
		(layer "F.Cu")
		(net "M_G_CPU1_SA_CB<7>")
	)
	(segment
		(start 157.751272 -248.378218)
		(end 157.868366 -248.261124)
		(width 0.10668)
		(layer "F.Cu")
		(net "M_G_CPU1_SA_CB<7>")
	)
	(segment
		(start 159.637222 -247.04294)
		(end 159.444436 -246.850154)
		(width 0.10668)
		(layer "F.Cu")
		(net "M_G_CPU1_SA_CB<7>")
	)
	(segment
		(start 157.751272 -248.543318)
		(end 157.751272 -248.378218)
		(width 0.10668)
		(layer "F.Cu")
		(net "M_G_CPU1_SA_CB<7>")
	)
	(segment
		(start 159.56153 -246.56796)
		(end 159.72663 -246.56796)
		(width 0.10668)
		(layer "F.Cu")
		(net "M_G_CPU1_SA_CB<7>")
	)
	(segment
		(start 158.31566 -247.97893)
		(end 158.31566 -247.81383)
		(width 0.10668)
		(layer "F.Cu")
		(net "M_G_CPU1_SA_CB<7>")
	)
	(segment
		(start 158.508446 -248.171716)
		(end 158.31566 -247.97893)
		(width 0.10668)
		(layer "F.Cu")
		(net "M_G_CPU1_SA_CB<7>")
	)
	(segment
		(start 161.145728 -245.578376)
		(end 162.895788 -243.82857)
		(width 0.10668)
		(layer "F.Cu")
		(net "M_G_CPU1_SA_CB<7>")
	)
	(segment
		(start 146.109944 -249.231404)
		(end 146.909028 -249.231404)
		(width 0.0762)
		(layer "F.Cu")
		(net "M_G_CPU1_SA_CB<7>")
	)
	(segment
		(start 159.637222 -247.20804)
		(end 159.637222 -247.04294)
		(width 0.10668)
		(layer "F.Cu")
		(net "M_G_CPU1_SA_CB<7>")
	)
	(segment
		(start 158.880048 -247.249442)
		(end 158.997142 -247.132348)
		(width 0.10668)
		(layer "F.Cu")
		(net "M_G_CPU1_SA_CB<7>")
	)
	(segment
		(start 160.765998 -245.914164)
		(end 160.573212 -245.721378)
		(width 0.10668)
		(layer "F.Cu")
		(net "M_G_CPU1_SA_CB<7>")
	)
	(segment
		(start 158.95574 -247.889522)
		(end 159.072834 -247.772428)
		(width 0.10668)
		(layer "F.Cu")
		(net "M_G_CPU1_SA_CB<7>")
	)
	(segment
		(start 163.43249 -243.801138)
		(end 163.43249 -243.636038)
		(width 0.10668)
		(layer "F.Cu")
		(net "M_G_CPU1_SA_CB<7>")
	)
	(segment
		(start 144.207992 -249.610372)
		(end 144.207992 -249.610118)
		(width 0.0762)
		(layer "F.Cu")
		(net "M_G_CPU1_SA_CB<7>")
	)
	(segment
		(start 159.072834 -247.607328)
		(end 158.880048 -247.414542)
		(width 0.10668)
		(layer "F.Cu")
		(net "M_G_CPU1_SA_CB<7>")
	)
	(segment
		(start 163.343082 -243.546376)
		(end 163.343082 -243.381276)
		(width 0.10668)
		(layer "F.Cu")
		(net "M_G_CPU1_SA_CB<7>")
	)
	(segment
		(start 158.432754 -247.696736)
		(end 158.597854 -247.696736)
		(width 0.10668)
		(layer "F.Cu")
		(net "M_G_CPU1_SA_CB<7>")
	)
	(segment
		(start 159.72663 -246.56796)
		(end 159.919416 -246.760746)
		(width 0.10668)
		(layer "F.Cu")
		(net "M_G_CPU1_SA_CB<7>")
	)
	(segment
		(start 146.909028 -249.231404)
		(end 147.334986 -249.657362)
		(width 0.0762)
		(layer "F.Cu")
		(net "M_G_CPU1_SA_CB<7>")
	)
	(segment
		(start 160.573212 -245.556278)
		(end 160.690306 -245.439184)
		(width 0.10668)
		(layer "F.Cu")
		(net "M_G_CPU1_SA_CB<7>")
	)
	(segment
		(start 158.79064 -247.889522)
		(end 158.95574 -247.889522)
		(width 0.10668)
		(layer "F.Cu")
		(net "M_G_CPU1_SA_CB<7>")
	)
	(segment
		(start 160.573212 -245.721378)
		(end 160.573212 -245.556278)
		(width 0.10668)
		(layer "F.Cu")
		(net "M_G_CPU1_SA_CB<7>")
	)
	(segment
		(start 159.919416 -246.760746)
		(end 160.084516 -246.760746)
		(width 0.10668)
		(layer "F.Cu")
		(net "M_G_CPU1_SA_CB<7>")
	)
	(segment
		(start 144.207992 -249.610118)
		(end 144.102836 -249.42927)
		(width 0.0762)
		(layer "F.Cu")
		(net "M_G_CPU1_SA_CB<7>")
	)
	(segment
		(start 163.343082 -243.381276)
		(end 163.489132 -243.235226)
		(width 0.10668)
		(layer "F.Cu")
		(net "M_G_CPU1_SA_CB<7>")
	)
	(segment
		(start 158.597854 -247.696736)
		(end 158.79064 -247.889522)
		(width 0.10668)
		(layer "F.Cu")
		(net "M_G_CPU1_SA_CB<7>")
	)
	(segment
		(start 159.072834 -247.772428)
		(end 159.072834 -247.607328)
		(width 0.10668)
		(layer "F.Cu")
		(net "M_G_CPU1_SA_CB<7>")
	)
	(segment
		(start 160.008824 -246.120666)
		(end 160.125918 -246.003572)
		(width 0.10668)
		(layer "F.Cu")
		(net "M_G_CPU1_SA_CB<7>")
	)
	(segment
		(start 160.20161 -246.643652)
		(end 160.20161 -246.478552)
		(width 0.10668)
		(layer "F.Cu")
		(net "M_G_CPU1_SA_CB<7>")
	)
	(segment
		(start 144.38757 -249.283474)
		(end 144.394936 -249.287792)
		(width 0.0762)
		(layer "F.Cu")
		(net "M_G_CPU1_SA_CB<7>")
	)
	(segment
		(start 159.444436 -246.685054)
		(end 159.56153 -246.56796)
		(width 0.10668)
		(layer "F.Cu")
		(net "M_G_CPU1_SA_CB<7>")
	)
	(segment
		(start 158.31566 -247.81383)
		(end 158.432754 -247.696736)
		(width 0.10668)
		(layer "F.Cu")
		(net "M_G_CPU1_SA_CB<7>")
	)
	(segment
		(start 150.023576 -249.195336)
		(end 157.649672 -249.195336)
		(width 0.10668)
		(layer "F.Cu")
		(net "M_G_CPU1_SA_CB<7>")
	)
	(segment
		(start 160.125918 -246.003572)
		(end 160.291018 -246.003572)
		(width 0.10668)
		(layer "F.Cu")
		(net "M_G_CPU1_SA_CB<7>")
	)
	(segment
		(start 159.520128 -247.325134)
		(end 159.637222 -247.20804)
		(width 0.10668)
		(layer "F.Cu")
		(net "M_G_CPU1_SA_CB<7>")
	)
	(segment
		(start 157.868366 -248.261124)
		(end 158.033466 -248.261124)
		(width 0.10668)
		(layer "F.Cu")
		(net "M_G_CPU1_SA_CB<7>")
	)
	(segment
		(start 157.944058 -248.736104)
		(end 157.751272 -248.543318)
		(width 0.10668)
		(layer "F.Cu")
		(net "M_G_CPU1_SA_CB<7>")
	)
	(segment
		(start 163.060634 -243.82857)
		(end 163.150296 -243.918232)
		(width 0.10668)
		(layer "F.Cu")
		(net "M_G_CPU1_SA_CB<7>")
	)
	(segment
		(start 160.994598 -245.578376)
		(end 161.145728 -245.578376)
		(width 0.10668)
		(layer "F.Cu")
		(net "M_G_CPU1_SA_CB<7>")
	)
	(segment
		(start 160.20161 -246.478552)
		(end 160.008824 -246.285766)
		(width 0.10668)
		(layer "F.Cu")
		(net "M_G_CPU1_SA_CB<7>")
	)
	(segment
		(start 160.483804 -246.196358)
		(end 160.648904 -246.196358)
		(width 0.10668)
		(layer "F.Cu")
		(net "M_G_CPU1_SA_CB<7>")
	)
	(segment
		(start 159.162242 -247.132348)
		(end 159.355028 -247.325134)
		(width 0.10668)
		(layer "F.Cu")
		(net "M_G_CPU1_SA_CB<7>")
	)
	(segment
		(start 158.391352 -248.45391)
		(end 158.508446 -248.336816)
		(width 0.10668)
		(layer "F.Cu")
		(net "M_G_CPU1_SA_CB<7>")
	)
	(segment
		(start 158.508446 -248.336816)
		(end 158.508446 -248.171716)
		(width 0.10668)
		(layer "F.Cu")
		(net "M_G_CPU1_SA_CB<7>")
	)
	(segment
		(start 160.648904 -246.196358)
		(end 160.765998 -246.079264)
		(width 0.10668)
		(layer "F.Cu")
		(net "M_G_CPU1_SA_CB<7>")
	)
	(segment
		(start 163.43249 -243.636038)
		(end 163.343082 -243.546376)
		(width 0.10668)
		(layer "F.Cu")
		(net "M_G_CPU1_SA_CB<7>")
	)
	(segment
		(start 160.008824 -246.285766)
		(end 160.008824 -246.120666)
		(width 0.10668)
		(layer "F.Cu")
		(net "M_G_CPU1_SA_CB<7>")
	)
	(segment
		(start 159.444436 -246.850154)
		(end 159.444436 -246.685054)
		(width 0.10668)
		(layer "F.Cu")
		(net "M_G_CPU1_SA_CB<7>")
	)
	(segment
		(start 158.880048 -247.414542)
		(end 158.880048 -247.249442)
		(width 0.10668)
		(layer "F.Cu")
		(net "M_G_CPU1_SA_CB<7>")
	)
	(segment
		(start 160.291018 -246.003572)
		(end 160.483804 -246.196358)
		(width 0.10668)
		(layer "F.Cu")
		(net "M_G_CPU1_SA_CB<7>")
	)
	(segment
		(start 160.765998 -246.079264)
		(end 160.765998 -245.914164)
		(width 0.10668)
		(layer "F.Cu")
		(net "M_G_CPU1_SA_CB<7>")
	)
	(segment
		(start 158.997142 -247.132348)
		(end 159.162242 -247.132348)
		(width 0.10668)
		(layer "F.Cu")
		(net "M_G_CPU1_SA_CB<7>")
	)
	(segment
		(start 160.084516 -246.760746)
		(end 160.20161 -246.643652)
		(width 0.10668)
		(layer "F.Cu")
		(net "M_G_CPU1_SA_CB<7>")
	)
	(segment
		(start 144.386554 -249.282966)
		(end 144.38757 -249.283474)
		(width 0.0762)
		(layer "F.Cu")
		(net "M_G_CPU1_SA_CB<7>")
	)
	(segment
		(start 162.895788 -243.82857)
		(end 163.060634 -243.82857)
		(width 0.10668)
		(layer "F.Cu")
		(net "M_G_CPU1_SA_CB<7>")
	)
	(segment
		(start 163.315396 -243.918232)
		(end 163.43249 -243.801138)
		(width 0.10668)
		(layer "F.Cu")
		(net "M_G_CPU1_SA_CB<7>")
	)
	(segment
		(start 160.855406 -245.439184)
		(end 160.994598 -245.578376)
		(width 0.10668)
		(layer "F.Cu")
		(net "M_G_CPU1_SA_CB<7>")
	)
	(segment
		(start 157.944058 -248.901204)
		(end 157.944058 -248.736104)
		(width 0.10668)
		(layer "F.Cu")
		(net "M_G_CPU1_SA_CB<7>")
	)
	(segment
		(start 163.150296 -243.918232)
		(end 163.315396 -243.918232)
		(width 0.10668)
		(layer "F.Cu")
		(net "M_G_CPU1_SA_CB<7>")
	)
	(segment
		(start 158.033466 -248.261124)
		(end 158.226252 -248.45391)
		(width 0.10668)
		(layer "F.Cu")
		(net "M_G_CPU1_SA_CB<7>")
	)
	(segment
		(start 144.960848 -249.287792)
		(end 144.96923 -249.282966)
		(width 0.0762)
		(layer "F.Cu")
		(net "M_G_CPU1_SA_CB<7>")
	)
	(segment
		(start 160.690306 -245.439184)
		(end 160.855406 -245.439184)
		(width 0.10668)
		(layer "F.Cu")
		(net "M_G_CPU1_SA_CB<7>")
	)
	(segment
		(start 147.334986 -249.657362)
		(end 147.51431 -249.657362)
		(width 0.0762)
		(layer "F.Cu")
		(net "M_G_CPU1_SA_CB<7>")
	)
	(arc
		(start 144.394936 -249.287792)
		(mid 144.677892 -249.363969)
		(end 144.960848 -249.287792)
		(width 0.0762)
		(layer "F.Cu")
		(net "M_G_CPU1_SA_CB<7>")
	)
	(arc
		(start 144.96923 -249.282966)
		(mid 145.152738 -249.237472)
		(end 145.33499 -249.287792)
		(width 0.0762)
		(layer "F.Cu")
		(net "M_G_CPU1_SA_CB<7>")
	)
	(arc
		(start 145.900902 -249.287792)
		(mid 146.001694 -249.245786)
		(end 146.109944 -249.231404)
		(width 0.0762)
		(layer "F.Cu")
		(net "M_G_CPU1_SA_CB<7>")
	)
	(arc
		(start 145.33499 -249.287792)
		(mid 145.617946 -249.363969)
		(end 145.900902 -249.287792)
		(width 0.0762)
		(layer "F.Cu")
		(net "M_G_CPU1_SA_CB<7>")
	)
	(arc
		(start 144.206468 -249.2375)
		(mid 144.299392 -249.248823)
		(end 144.386554 -249.282966)
		(width 0.0762)
		(layer "F.Cu")
		(net "M_G_CPU1_SA_CB<7>")
	)
	(arc
		(start 144.102836 -249.42927)
		(mid 144.111773 -249.310246)
		(end 144.206468 -249.2375)
		(width 0.0762)
		(layer "F.Cu")
		(net "M_G_CPU1_SA_CB<7>")
	)
	(segment
		(start 161.981134 -243.614702)
		(end 162.146234 -243.614702)
		(width 0.10668)
		(layer "F.Cu")
		(net "M_G_CPU1_SA_CB<6>")
	)
	(segment
		(start 161.619438 -243.253006)
		(end 161.981134 -243.614702)
		(width 0.10668)
		(layer "F.Cu")
		(net "M_G_CPU1_SA_CB<6>")
	)
	(segment
		(start 162.263328 -243.497608)
		(end 162.263328 -243.332508)
		(width 0.10668)
		(layer "F.Cu")
		(net "M_G_CPU1_SA_CB<6>")
	)
	(segment
		(start 145.617946 -248.800366)
		(end 145.515584 -248.62409)
		(width 0.0762)
		(layer "F.Cu")
		(net "M_G_CPU1_SA_CB<6>")
	)
	(segment
		(start 163.392104 -242.203732)
		(end 163.030408 -241.842036)
		(width 0.10668)
		(layer "F.Cu")
		(net "M_G_CPU1_SA_CB<6>")
	)
	(segment
		(start 161.337244 -243.5352)
		(end 161.337244 -243.3701)
		(width 0.10668)
		(layer "F.Cu")
		(net "M_G_CPU1_SA_CB<6>")
	)
	(segment
		(start 160.772856 -243.934488)
		(end 160.88995 -243.817394)
		(width 0.10668)
		(layer "F.Cu")
		(net "M_G_CPU1_SA_CB<6>")
	)
	(segment
		(start 147.578826 -248.976642)
		(end 149.279102 -248.976642)
		(width 0.10668)
		(layer "F.Cu")
		(net "M_G_CPU1_SA_CB<6>")
	)
	(segment
		(start 161.454338 -243.253006)
		(end 161.619438 -243.253006)
		(width 0.10668)
		(layer "F.Cu")
		(net "M_G_CPU1_SA_CB<6>")
	)
	(segment
		(start 161.69894 -244.061996)
		(end 161.69894 -243.896896)
		(width 0.10668)
		(layer "F.Cu")
		(net "M_G_CPU1_SA_CB<6>")
	)
	(segment
		(start 161.901632 -242.970812)
		(end 161.901632 -242.805712)
		(width 0.10668)
		(layer "F.Cu")
		(net "M_G_CPU1_SA_CB<6>")
	)
	(segment
		(start 163.10991 -242.485926)
		(end 163.27501 -242.485926)
		(width 0.10668)
		(layer "F.Cu")
		(net "M_G_CPU1_SA_CB<6>")
	)
	(segment
		(start 163.030408 -241.676936)
		(end 163.17214 -241.535204)
		(width 0.10668)
		(layer "F.Cu")
		(net "M_G_CPU1_SA_CB<6>")
	)
	(segment
		(start 160.88995 -243.817394)
		(end 161.05505 -243.817394)
		(width 0.10668)
		(layer "F.Cu")
		(net "M_G_CPU1_SA_CB<6>")
	)
	(segment
		(start 147.15617 -248.553986)
		(end 147.578826 -248.976642)
		(width 0.0762)
		(layer "F.Cu")
		(net "M_G_CPU1_SA_CB<6>")
	)
	(segment
		(start 149.741128 -248.514616)
		(end 156.60878 -248.514616)
		(width 0.10668)
		(layer "F.Cu")
		(net "M_G_CPU1_SA_CB<6>")
	)
	(segment
		(start 160.691576 -244.582696)
		(end 160.852358 -244.743478)
		(width 0.10668)
		(layer "F.Cu")
		(net "M_G_CPU1_SA_CB<6>")
	)
	(segment
		(start 160.5407 -244.582696)
		(end 160.691576 -244.582696)
		(width 0.10668)
		(layer "F.Cu")
		(net "M_G_CPU1_SA_CB<6>")
	)
	(segment
		(start 161.69894 -243.896896)
		(end 161.337244 -243.5352)
		(width 0.10668)
		(layer "F.Cu")
		(net "M_G_CPU1_SA_CB<6>")
	)
	(segment
		(start 161.134552 -244.626384)
		(end 161.134552 -244.461284)
		(width 0.10668)
		(layer "F.Cu")
		(net "M_G_CPU1_SA_CB<6>")
	)
	(segment
		(start 162.545522 -243.050314)
		(end 162.710622 -243.050314)
		(width 0.10668)
		(layer "F.Cu")
		(net "M_G_CPU1_SA_CB<6>")
	)
	(segment
		(start 146.087592 -248.553986)
		(end 147.15617 -248.553986)
		(width 0.0762)
		(layer "F.Cu")
		(net "M_G_CPU1_SA_CB<6>")
	)
	(segment
		(start 145.796508 -248.47296)
		(end 145.80489 -248.477786)
		(width 0.0762)
		(layer "F.Cu")
		(net "M_G_CPU1_SA_CB<6>")
	)
	(segment
		(start 162.46602 -242.406424)
		(end 162.46602 -242.241324)
		(width 0.10668)
		(layer "F.Cu")
		(net "M_G_CPU1_SA_CB<6>")
	)
	(segment
		(start 161.901632 -242.805712)
		(end 162.018726 -242.688618)
		(width 0.10668)
		(layer "F.Cu")
		(net "M_G_CPU1_SA_CB<6>")
	)
	(segment
		(start 161.581846 -244.17909)
		(end 161.69894 -244.061996)
		(width 0.10668)
		(layer "F.Cu")
		(net "M_G_CPU1_SA_CB<6>")
	)
	(segment
		(start 162.748214 -242.12423)
		(end 163.10991 -242.485926)
		(width 0.10668)
		(layer "F.Cu")
		(net "M_G_CPU1_SA_CB<6>")
	)
	(segment
		(start 162.263328 -243.332508)
		(end 161.901632 -242.970812)
		(width 0.10668)
		(layer "F.Cu")
		(net "M_G_CPU1_SA_CB<6>")
	)
	(segment
		(start 156.60878 -248.514616)
		(end 160.5407 -244.582696)
		(width 0.10668)
		(layer "F.Cu")
		(net "M_G_CPU1_SA_CB<6>")
	)
	(segment
		(start 163.392104 -242.368832)
		(end 163.392104 -242.203732)
		(width 0.10668)
		(layer "F.Cu")
		(net "M_G_CPU1_SA_CB<6>")
	)
	(segment
		(start 162.146234 -243.614702)
		(end 162.263328 -243.497608)
		(width 0.10668)
		(layer "F.Cu")
		(net "M_G_CPU1_SA_CB<6>")
	)
	(segment
		(start 162.583114 -242.12423)
		(end 162.748214 -242.12423)
		(width 0.10668)
		(layer "F.Cu")
		(net "M_G_CPU1_SA_CB<6>")
	)
	(segment
		(start 162.018726 -242.688618)
		(end 162.183826 -242.688618)
		(width 0.10668)
		(layer "F.Cu")
		(net "M_G_CPU1_SA_CB<6>")
	)
	(segment
		(start 160.852358 -244.743478)
		(end 161.017458 -244.743478)
		(width 0.10668)
		(layer "F.Cu")
		(net "M_G_CPU1_SA_CB<6>")
	)
	(segment
		(start 163.27501 -242.485926)
		(end 163.392104 -242.368832)
		(width 0.10668)
		(layer "F.Cu")
		(net "M_G_CPU1_SA_CB<6>")
	)
	(segment
		(start 161.337244 -243.3701)
		(end 161.454338 -243.253006)
		(width 0.10668)
		(layer "F.Cu")
		(net "M_G_CPU1_SA_CB<6>")
	)
	(segment
		(start 161.017458 -244.743478)
		(end 161.134552 -244.626384)
		(width 0.10668)
		(layer "F.Cu")
		(net "M_G_CPU1_SA_CB<6>")
	)
	(segment
		(start 160.772856 -244.099588)
		(end 160.772856 -243.934488)
		(width 0.10668)
		(layer "F.Cu")
		(net "M_G_CPU1_SA_CB<6>")
	)
	(segment
		(start 161.134552 -244.461284)
		(end 160.772856 -244.099588)
		(width 0.10668)
		(layer "F.Cu")
		(net "M_G_CPU1_SA_CB<6>")
	)
	(segment
		(start 162.827716 -242.93322)
		(end 162.827716 -242.76812)
		(width 0.10668)
		(layer "F.Cu")
		(net "M_G_CPU1_SA_CB<6>")
	)
	(segment
		(start 163.030408 -241.842036)
		(end 163.030408 -241.676936)
		(width 0.10668)
		(layer "F.Cu")
		(net "M_G_CPU1_SA_CB<6>")
	)
	(segment
		(start 162.46602 -242.241324)
		(end 162.583114 -242.12423)
		(width 0.10668)
		(layer "F.Cu")
		(net "M_G_CPU1_SA_CB<6>")
	)
	(segment
		(start 149.279102 -248.976642)
		(end 149.741128 -248.514616)
		(width 0.10668)
		(layer "F.Cu")
		(net "M_G_CPU1_SA_CB<6>")
	)
	(segment
		(start 162.827716 -242.76812)
		(end 162.46602 -242.406424)
		(width 0.10668)
		(layer "F.Cu")
		(net "M_G_CPU1_SA_CB<6>")
	)
	(segment
		(start 162.183826 -242.688618)
		(end 162.545522 -243.050314)
		(width 0.10668)
		(layer "F.Cu")
		(net "M_G_CPU1_SA_CB<6>")
	)
	(segment
		(start 162.710622 -243.050314)
		(end 162.827716 -242.93322)
		(width 0.10668)
		(layer "F.Cu")
		(net "M_G_CPU1_SA_CB<6>")
	)
	(segment
		(start 163.17214 -241.535204)
		(end 164.427916 -241.535204)
		(width 0.10668)
		(layer "F.Cu")
		(net "M_G_CPU1_SA_CB<6>")
	)
	(segment
		(start 161.416746 -244.17909)
		(end 161.581846 -244.17909)
		(width 0.10668)
		(layer "F.Cu")
		(net "M_G_CPU1_SA_CB<6>")
	)
	(segment
		(start 161.05505 -243.817394)
		(end 161.416746 -244.17909)
		(width 0.10668)
		(layer "F.Cu")
		(net "M_G_CPU1_SA_CB<6>")
	)
	(arc
		(start 145.515584 -248.62409)
		(mid 145.545213 -248.481603)
		(end 145.682462 -248.433082)
		(width 0.0762)
		(layer "F.Cu")
		(net "M_G_CPU1_SA_CB<6>")
	)
	(arc
		(start 146.040602 -248.552208)
		(mid 146.064079 -248.553584)
		(end 146.087592 -248.553986)
		(width 0.0762)
		(layer "F.Cu")
		(net "M_G_CPU1_SA_CB<6>")
	)
	(arc
		(start 145.682462 -248.433082)
		(mid 145.741108 -248.448375)
		(end 145.796508 -248.47296)
		(width 0.0762)
		(layer "F.Cu")
		(net "M_G_CPU1_SA_CB<6>")
	)
	(arc
		(start 145.80489 -248.477786)
		(mid 145.918614 -248.528087)
		(end 146.040602 -248.552208)
		(width 0.0762)
		(layer "F.Cu")
		(net "M_G_CPU1_SA_CB<6>")
	)
	(segment
		(start 157.40634 -248.707656)
		(end 157.40634 -248.542556)
		(width 0.10668)
		(layer "F.Cu")
		(net "M_G_CPU1_SA_CB<5>")
	)
	(segment
		(start 157.124146 -248.82475)
		(end 157.289246 -248.82475)
		(width 0.10668)
		(layer "F.Cu")
		(net "M_G_CPU1_SA_CB<5>")
	)
	(segment
		(start 146.505676 -248.934224)
		(end 147.107148 -248.934224)
		(width 0.0762)
		(layer "F.Cu")
		(net "M_G_CPU1_SA_CB<5>")
	)
	(segment
		(start 149.420326 -249.317002)
		(end 149.882352 -248.854976)
		(width 0.10668)
		(layer "F.Cu")
		(net "M_G_CPU1_SA_CB<5>")
	)
	(segment
		(start 167.495474 -242.385342)
		(end 168.527984 -242.385342)
		(width 0.101346)
		(layer "F.Cu")
		(net "M_G_CPU1_SA_CB<5>")
	)
	(segment
		(start 167.070532 -242.810284)
		(end 167.495474 -242.385342)
		(width 0.101346)
		(layer "F.Cu")
		(net "M_G_CPU1_SA_CB<5>")
	)
	(segment
		(start 149.882352 -248.854976)
		(end 156.750004 -248.854976)
		(width 0.10668)
		(layer "F.Cu")
		(net "M_G_CPU1_SA_CB<5>")
	)
	(segment
		(start 156.750004 -248.854976)
		(end 156.869638 -248.735342)
		(width 0.10668)
		(layer "F.Cu")
		(net "M_G_CPU1_SA_CB<5>")
	)
	(segment
		(start 163.432236 -242.810284)
		(end 167.070532 -242.810284)
		(width 0.101346)
		(layer "F.Cu")
		(net "M_G_CPU1_SA_CB<5>")
	)
	(segment
		(start 147.107148 -248.934224)
		(end 147.489926 -249.317002)
		(width 0.0762)
		(layer "F.Cu")
		(net "M_G_CPU1_SA_CB<5>")
	)
	(segment
		(start 163.32581 -242.91671)
		(end 163.432236 -242.810284)
		(width 0.101346)
		(layer "F.Cu")
		(net "M_G_CPU1_SA_CB<5>")
	)
	(segment
		(start 157.034738 -248.735342)
		(end 157.124146 -248.82475)
		(width 0.10668)
		(layer "F.Cu")
		(net "M_G_CPU1_SA_CB<5>")
	)
	(segment
		(start 157.316932 -248.288048)
		(end 160.521142 -245.083838)
		(width 0.10668)
		(layer "F.Cu")
		(net "M_G_CPU1_SA_CB<5>")
	)
	(segment
		(start 157.40634 -248.542556)
		(end 157.316932 -248.453148)
		(width 0.10668)
		(layer "F.Cu")
		(net "M_G_CPU1_SA_CB<5>")
	)
	(segment
		(start 147.489926 -249.317002)
		(end 149.420326 -249.317002)
		(width 0.10668)
		(layer "F.Cu")
		(net "M_G_CPU1_SA_CB<5>")
	)
	(segment
		(start 160.521142 -245.083838)
		(end 161.158682 -245.083838)
		(width 0.10668)
		(layer "F.Cu")
		(net "M_G_CPU1_SA_CB<5>")
	)
	(segment
		(start 145.796508 -249.127772)
		(end 145.80489 -249.122946)
		(width 0.0762)
		(layer "F.Cu")
		(net "M_G_CPU1_SA_CB<5>")
	)
	(segment
		(start 157.316932 -248.453148)
		(end 157.316932 -248.288048)
		(width 0.10668)
		(layer "F.Cu")
		(net "M_G_CPU1_SA_CB<5>")
	)
	(segment
		(start 157.289246 -248.82475)
		(end 157.40634 -248.707656)
		(width 0.10668)
		(layer "F.Cu")
		(net "M_G_CPU1_SA_CB<5>")
	)
	(segment
		(start 161.158682 -245.083838)
		(end 163.32581 -242.91671)
		(width 0.10668)
		(layer "F.Cu")
		(net "M_G_CPU1_SA_CB<5>")
	)
	(segment
		(start 144.490948 -249.122692)
		(end 144.490948 -249.122946)
		(width 0.0762)
		(layer "F.Cu")
		(net "M_G_CPU1_SA_CB<5>")
	)
	(segment
		(start 156.869638 -248.735342)
		(end 157.034738 -248.735342)
		(width 0.10668)
		(layer "F.Cu")
		(net "M_G_CPU1_SA_CB<5>")
	)
	(arc
		(start 144.864836 -249.122946)
		(mid 145.147792 -249.046769)
		(end 145.430748 -249.122946)
		(width 0.0762)
		(layer "F.Cu")
		(net "M_G_CPU1_SA_CB<5>")
	)
	(arc
		(start 144.206468 -249.046238)
		(mid 144.353789 -249.065557)
		(end 144.490948 -249.122692)
		(width 0.0762)
		(layer "F.Cu")
		(net "M_G_CPU1_SA_CB<5>")
	)
	(arc
		(start 145.430748 -249.122946)
		(mid 145.612999 -249.173296)
		(end 145.796508 -249.127772)
		(width 0.0762)
		(layer "F.Cu")
		(net "M_G_CPU1_SA_CB<5>")
	)
	(arc
		(start 143.737838 -248.800366)
		(mid 143.941854 -248.98106)
		(end 144.206468 -249.046238)
		(width 0.0762)
		(layer "F.Cu")
		(net "M_G_CPU1_SA_CB<5>")
	)
	(arc
		(start 144.490948 -249.122946)
		(mid 144.677892 -249.173201)
		(end 144.864836 -249.122946)
		(width 0.0762)
		(layer "F.Cu")
		(net "M_G_CPU1_SA_CB<5>")
	)
	(arc
		(start 145.80489 -249.122946)
		(mid 146.1428 -248.982229)
		(end 146.505676 -248.934224)
		(width 0.0762)
		(layer "F.Cu")
		(net "M_G_CPU1_SA_CB<5>")
	)
	(segment
		(start 147.611592 -248.056654)
		(end 147.728432 -248.173494)
		(width 0.10668)
		(layer "F.Cu")
		(net "M_G_CPU1_SA_CB<4>")
	)
	(segment
		(start 148.127466 -248.173494)
		(end 148.244306 -248.056654)
		(width 0.10668)
		(layer "F.Cu")
		(net "M_G_CPU1_SA_CB<4>")
	)
	(segment
		(start 167.592502 -240.68532)
		(end 168.527984 -240.68532)
		(width 0.101346)
		(layer "F.Cu")
		(net "M_G_CPU1_SA_CB<4>")
	)
	(segment
		(start 148.244306 -248.056654)
		(end 148.40966 -248.056654)
		(width 0.10668)
		(layer "F.Cu")
		(net "M_G_CPU1_SA_CB<4>")
	)
	(segment
		(start 148.127466 -248.506488)
		(end 148.127466 -248.173494)
		(width 0.10668)
		(layer "F.Cu")
		(net "M_G_CPU1_SA_CB<4>")
	)
	(segment
		(start 147.432522 -248.056654)
		(end 147.611592 -248.056654)
		(width 0.10668)
		(layer "F.Cu")
		(net "M_G_CPU1_SA_CB<4>")
	)
	(segment
		(start 147.845272 -248.623328)
		(end 148.010626 -248.623328)
		(width 0.10668)
		(layer "F.Cu")
		(net "M_G_CPU1_SA_CB<4>")
	)
	(segment
		(start 160.432496 -244.209316)
		(end 160.432496 -243.793264)
		(width 0.10668)
		(layer "F.Cu")
		(net "M_G_CPU1_SA_CB<4>")
	)
	(segment
		(start 167.16756 -241.110262)
		(end 167.592502 -240.68532)
		(width 0.101346)
		(layer "F.Cu")
		(net "M_G_CPU1_SA_CB<4>")
	)
	(segment
		(start 156.585158 -248.056654)
		(end 160.432496 -244.209316)
		(width 0.10668)
		(layer "F.Cu")
		(net "M_G_CPU1_SA_CB<4>")
	)
	(segment
		(start 148.5265 -248.506488)
		(end 148.64334 -248.623328)
		(width 0.10668)
		(layer "F.Cu")
		(net "M_G_CPU1_SA_CB<4>")
	)
	(segment
		(start 148.925534 -248.506488)
		(end 148.925534 -248.173494)
		(width 0.10668)
		(layer "F.Cu")
		(net "M_G_CPU1_SA_CB<4>")
	)
	(segment
		(start 160.432496 -243.793264)
		(end 163.115498 -241.110262)
		(width 0.10668)
		(layer "F.Cu")
		(net "M_G_CPU1_SA_CB<4>")
	)
	(segment
		(start 147.202398 -248.056654)
		(end 147.432522 -248.056654)
		(width 0.0762)
		(layer "F.Cu")
		(net "M_G_CPU1_SA_CB<4>")
	)
	(segment
		(start 146.895566 -248.363486)
		(end 147.202398 -248.056654)
		(width 0.0762)
		(layer "F.Cu")
		(net "M_G_CPU1_SA_CB<4>")
	)
	(segment
		(start 148.40966 -248.056654)
		(end 148.5265 -248.173494)
		(width 0.10668)
		(layer "F.Cu")
		(net "M_G_CPU1_SA_CB<4>")
	)
	(segment
		(start 148.5265 -248.173494)
		(end 148.5265 -248.506488)
		(width 0.10668)
		(layer "F.Cu")
		(net "M_G_CPU1_SA_CB<4>")
	)
	(segment
		(start 148.925534 -248.173494)
		(end 149.042374 -248.056654)
		(width 0.10668)
		(layer "F.Cu")
		(net "M_G_CPU1_SA_CB<4>")
	)
	(segment
		(start 147.728432 -248.173494)
		(end 147.728432 -248.506488)
		(width 0.10668)
		(layer "F.Cu")
		(net "M_G_CPU1_SA_CB<4>")
	)
	(segment
		(start 146.087846 -248.363486)
		(end 146.895566 -248.363486)
		(width 0.0762)
		(layer "F.Cu")
		(net "M_G_CPU1_SA_CB<4>")
	)
	(segment
		(start 148.808694 -248.623328)
		(end 148.925534 -248.506488)
		(width 0.10668)
		(layer "F.Cu")
		(net "M_G_CPU1_SA_CB<4>")
	)
	(segment
		(start 149.042374 -248.056654)
		(end 156.585158 -248.056654)
		(width 0.10668)
		(layer "F.Cu")
		(net "M_G_CPU1_SA_CB<4>")
	)
	(segment
		(start 147.728432 -248.506488)
		(end 147.845272 -248.623328)
		(width 0.10668)
		(layer "F.Cu")
		(net "M_G_CPU1_SA_CB<4>")
	)
	(segment
		(start 163.377626 -241.110262)
		(end 167.16756 -241.110262)
		(width 0.101346)
		(layer "F.Cu")
		(net "M_G_CPU1_SA_CB<4>")
	)
	(segment
		(start 163.115498 -241.110262)
		(end 163.377626 -241.110262)
		(width 0.10668)
		(layer "F.Cu")
		(net "M_G_CPU1_SA_CB<4>")
	)
	(segment
		(start 148.64334 -248.623328)
		(end 148.808694 -248.623328)
		(width 0.10668)
		(layer "F.Cu")
		(net "M_G_CPU1_SA_CB<4>")
	)
	(segment
		(start 148.010626 -248.623328)
		(end 148.127466 -248.506488)
		(width 0.10668)
		(layer "F.Cu")
		(net "M_G_CPU1_SA_CB<4>")
	)
	(arc
		(start 145.147792 -247.99036)
		(mid 145.391223 -248.159847)
		(end 145.676874 -248.239788)
		(width 0.0762)
		(layer "F.Cu")
		(net "M_G_CPU1_SA_CB<4>")
	)
	(arc
		(start 146.056858 -248.362216)
		(mid 146.072339 -248.363172)
		(end 146.087846 -248.363486)
		(width 0.0762)
		(layer "F.Cu")
		(net "M_G_CPU1_SA_CB<4>")
	)
	(arc
		(start 145.676874 -248.239788)
		(mid 145.696223 -248.242126)
		(end 145.715482 -248.245122)
		(width 0.0762)
		(layer "F.Cu")
		(net "M_G_CPU1_SA_CB<4>")
	)
	(arc
		(start 145.715482 -248.245122)
		(mid 145.811191 -248.270834)
		(end 145.900902 -248.31294)
		(width 0.0762)
		(layer "F.Cu")
		(net "M_G_CPU1_SA_CB<4>")
	)
	(arc
		(start 145.900902 -248.31294)
		(mid 145.976142 -248.346253)
		(end 146.056858 -248.362216)
		(width 0.0762)
		(layer "F.Cu")
		(net "M_G_CPU1_SA_CB<4>")
	)
	(segment
		(start 156.261054 -244.581934)
		(end 157.110176 -243.732812)
		(width 0.10668)
		(layer "F.Cu")
		(net "M_G_CPU1_SA_CB<3>")
	)
	(segment
		(start 157.39237 -244.015006)
		(end 156.825442 -244.581934)
		(width 0.10668)
		(layer "F.Cu")
		(net "M_G_CPU1_SA_CB<3>")
	)
	(segment
		(start 147.061428 -245.992904)
		(end 147.20189 -246.133366)
		(width 0.0762)
		(layer "F.Cu")
		(net "M_G_CPU1_SA_CB<3>")
	)
	(segment
		(start 156.825442 -244.747034)
		(end 156.942536 -244.864128)
		(width 0.10668)
		(layer "F.Cu")
		(net "M_G_CPU1_SA_CB<3>")
	)
	(segment
		(start 157.275276 -243.732812)
		(end 157.39237 -243.849906)
		(width 0.10668)
		(layer "F.Cu")
		(net "M_G_CPU1_SA_CB<3>")
	)
	(segment
		(start 144.386554 -246.042942)
		(end 144.38757 -246.04345)
		(width 0.0762)
		(layer "F.Cu")
		(net "M_G_CPU1_SA_CB<3>")
	)
	(segment
		(start 156.825442 -244.581934)
		(end 156.825442 -244.747034)
		(width 0.10668)
		(layer "F.Cu")
		(net "M_G_CPU1_SA_CB<3>")
	)
	(segment
		(start 144.38757 -246.04345)
		(end 144.394936 -246.047768)
		(width 0.0762)
		(layer "F.Cu")
		(net "M_G_CPU1_SA_CB<3>")
	)
	(segment
		(start 155.838398 -246.133366)
		(end 156.660342 -245.311422)
		(width 0.10668)
		(layer "F.Cu")
		(net "M_G_CPU1_SA_CB<3>")
	)
	(segment
		(start 156.261054 -244.747034)
		(end 156.261054 -244.581934)
		(width 0.10668)
		(layer "F.Cu")
		(net "M_G_CPU1_SA_CB<3>")
	)
	(segment
		(start 156.660342 -245.146322)
		(end 156.261054 -244.747034)
		(width 0.10668)
		(layer "F.Cu")
		(net "M_G_CPU1_SA_CB<3>")
	)
	(segment
		(start 147.20189 -246.133366)
		(end 147.60575 -246.133366)
		(width 0.0762)
		(layer "F.Cu")
		(net "M_G_CPU1_SA_CB<3>")
	)
	(segment
		(start 146.104356 -245.992904)
		(end 147.061428 -245.992904)
		(width 0.0762)
		(layer "F.Cu")
		(net "M_G_CPU1_SA_CB<3>")
	)
	(segment
		(start 144.960848 -246.047768)
		(end 144.96923 -246.042942)
		(width 0.0762)
		(layer "F.Cu")
		(net "M_G_CPU1_SA_CB<3>")
	)
	(segment
		(start 157.795976 -244.175788)
		(end 157.795976 -242.419378)
		(width 0.10668)
		(layer "F.Cu")
		(net "M_G_CPU1_SA_CB<3>")
	)
	(segment
		(start 162.521392 -237.693962)
		(end 162.915346 -237.53064)
		(width 0.10668)
		(layer "F.Cu")
		(net "M_G_CPU1_SA_CB<3>")
	)
	(segment
		(start 144.207992 -246.370094)
		(end 144.102836 -246.189246)
		(width 0.0762)
		(layer "F.Cu")
		(net "M_G_CPU1_SA_CB<3>")
	)
	(segment
		(start 157.795976 -242.419378)
		(end 162.521392 -237.693962)
		(width 0.10668)
		(layer "F.Cu")
		(net "M_G_CPU1_SA_CB<3>")
	)
	(segment
		(start 163.507928 -237.285276)
		(end 164.427916 -237.285276)
		(width 0.10668)
		(layer "F.Cu")
		(net "M_G_CPU1_SA_CB<3>")
	)
	(segment
		(start 156.660342 -245.311422)
		(end 156.660342 -245.146322)
		(width 0.10668)
		(layer "F.Cu")
		(net "M_G_CPU1_SA_CB<3>")
	)
	(segment
		(start 144.207992 -246.370348)
		(end 144.207992 -246.370094)
		(width 0.0762)
		(layer "F.Cu")
		(net "M_G_CPU1_SA_CB<3>")
	)
	(segment
		(start 157.39237 -243.849906)
		(end 157.39237 -244.015006)
		(width 0.10668)
		(layer "F.Cu")
		(net "M_G_CPU1_SA_CB<3>")
	)
	(segment
		(start 157.110176 -243.732812)
		(end 157.275276 -243.732812)
		(width 0.10668)
		(layer "F.Cu")
		(net "M_G_CPU1_SA_CB<3>")
	)
	(segment
		(start 156.942536 -244.864128)
		(end 157.107636 -244.864128)
		(width 0.10668)
		(layer "F.Cu")
		(net "M_G_CPU1_SA_CB<3>")
	)
	(segment
		(start 147.60575 -246.133366)
		(end 155.838398 -246.133366)
		(width 0.10668)
		(layer "F.Cu")
		(net "M_G_CPU1_SA_CB<3>")
	)
	(segment
		(start 163.279582 -237.379764)
		(end 163.507928 -237.285276)
		(width 0.10668)
		(layer "F.Cu")
		(net "M_G_CPU1_SA_CB<3>")
	)
	(segment
		(start 162.915346 -237.53064)
		(end 163.279582 -237.379764)
		(width 0.10668)
		(layer "F.Cu")
		(net "M_G_CPU1_SA_CB<3>")
	)
	(segment
		(start 157.107636 -244.864128)
		(end 157.795976 -244.175788)
		(width 0.10668)
		(layer "F.Cu")
		(net "M_G_CPU1_SA_CB<3>")
	)
	(arc
		(start 144.206468 -245.997476)
		(mid 144.299392 -246.008799)
		(end 144.386554 -246.042942)
		(width 0.0762)
		(layer "F.Cu")
		(net "M_G_CPU1_SA_CB<3>")
	)
	(arc
		(start 144.96923 -246.042942)
		(mid 145.152738 -245.997448)
		(end 145.33499 -246.047768)
		(width 0.0762)
		(layer "F.Cu")
		(net "M_G_CPU1_SA_CB<3>")
	)
	(arc
		(start 144.102836 -246.189246)
		(mid 144.111773 -246.070222)
		(end 144.206468 -245.997476)
		(width 0.0762)
		(layer "F.Cu")
		(net "M_G_CPU1_SA_CB<3>")
	)
	(arc
		(start 144.394936 -246.047768)
		(mid 144.677892 -246.123945)
		(end 144.960848 -246.047768)
		(width 0.0762)
		(layer "F.Cu")
		(net "M_G_CPU1_SA_CB<3>")
	)
	(arc
		(start 145.900902 -246.047768)
		(mid 145.998999 -246.006881)
		(end 146.104356 -245.992904)
		(width 0.0762)
		(layer "F.Cu")
		(net "M_G_CPU1_SA_CB<3>")
	)
	(arc
		(start 145.33499 -246.047768)
		(mid 145.617946 -246.123945)
		(end 145.900902 -246.047768)
		(width 0.0762)
		(layer "F.Cu")
		(net "M_G_CPU1_SA_CB<3>")
	)
	(segment
		(start 156.82849 -243.041678)
		(end 156.945584 -242.924584)
		(width 0.10668)
		(layer "F.Cu")
		(net "M_G_CPU1_SA_CB<2>")
	)
	(segment
		(start 156.801312 -242.450366)
		(end 162.899852 -236.351826)
		(width 0.10668)
		(layer "F.Cu")
		(net "M_G_CPU1_SA_CB<2>")
	)
	(segment
		(start 156.945584 -242.759484)
		(end 156.801312 -242.615212)
		(width 0.10668)
		(layer "F.Cu")
		(net "M_G_CPU1_SA_CB<2>")
	)
	(segment
		(start 156.381196 -243.323872)
		(end 156.236924 -243.1796)
		(width 0.10668)
		(layer "F.Cu")
		(net "M_G_CPU1_SA_CB<2>")
	)
	(segment
		(start 163.480242 -236.367828)
		(end 163.480242 -236.202728)
		(width 0.10668)
		(layer "F.Cu")
		(net "M_G_CPU1_SA_CB<2>")
	)
	(segment
		(start 155.580334 -244.945154)
		(end 155.580334 -244.780562)
		(width 0.10668)
		(layer "F.Cu")
		(net "M_G_CPU1_SA_CB<2>")
	)
	(segment
		(start 155.29814 -245.062248)
		(end 155.46324 -245.062248)
		(width 0.10668)
		(layer "F.Cu")
		(net "M_G_CPU1_SA_CB<2>")
	)
	(segment
		(start 155.672536 -243.743988)
		(end 155.672536 -243.579142)
		(width 0.10668)
		(layer "F.Cu")
		(net "M_G_CPU1_SA_CB<2>")
	)
	(segment
		(start 154.836876 -245.330472)
		(end 154.836876 -245.16588)
		(width 0.10668)
		(layer "F.Cu")
		(net "M_G_CPU1_SA_CB<2>")
	)
	(segment
		(start 153.806652 -245.445026)
		(end 154.096466 -245.155212)
		(width 0.10668)
		(layer "F.Cu")
		(net "M_G_CPU1_SA_CB<2>")
	)
	(segment
		(start 155.580334 -244.780562)
		(end 155.108148 -244.308376)
		(width 0.10668)
		(layer "F.Cu")
		(net "M_G_CPU1_SA_CB<2>")
	)
	(segment
		(start 163.198048 -236.484922)
		(end 163.363148 -236.484922)
		(width 0.10668)
		(layer "F.Cu")
		(net "M_G_CPU1_SA_CB<2>")
	)
	(segment
		(start 154.096466 -245.155212)
		(end 154.261566 -245.155212)
		(width 0.10668)
		(layer "F.Cu")
		(net "M_G_CPU1_SA_CB<2>")
	)
	(segment
		(start 155.390342 -244.026436)
		(end 155.534614 -244.170454)
		(width 0.10668)
		(layer "F.Cu")
		(net "M_G_CPU1_SA_CB<2>")
	)
	(segment
		(start 155.672536 -243.579142)
		(end 155.78963 -243.462048)
		(width 0.10668)
		(layer "F.Cu")
		(net "M_G_CPU1_SA_CB<2>")
	)
	(segment
		(start 163.347146 -235.904532)
		(end 163.666424 -235.585254)
		(width 0.10668)
		(layer "F.Cu")
		(net "M_G_CPU1_SA_CB<2>")
	)
	(segment
		(start 154.261566 -245.155212)
		(end 154.554428 -245.447566)
		(width 0.10668)
		(layer "F.Cu")
		(net "M_G_CPU1_SA_CB<2>")
	)
	(segment
		(start 163.480242 -236.202728)
		(end 163.347146 -236.069632)
		(width 0.10668)
		(layer "F.Cu")
		(net "M_G_CPU1_SA_CB<2>")
	)
	(segment
		(start 156.236924 -243.014754)
		(end 156.354018 -242.89766)
		(width 0.10668)
		(layer "F.Cu")
		(net "M_G_CPU1_SA_CB<2>")
	)
	(segment
		(start 155.816808 -243.88826)
		(end 155.672536 -243.743988)
		(width 0.10668)
		(layer "F.Cu")
		(net "M_G_CPU1_SA_CB<2>")
	)
	(segment
		(start 162.899852 -236.351826)
		(end 163.064952 -236.351826)
		(width 0.10668)
		(layer "F.Cu")
		(net "M_G_CPU1_SA_CB<2>")
	)
	(segment
		(start 147.51177 -245.445026)
		(end 153.806652 -245.445026)
		(width 0.10668)
		(layer "F.Cu")
		(net "M_G_CPU1_SA_CB<2>")
	)
	(segment
		(start 163.347146 -236.069632)
		(end 163.347146 -235.904532)
		(width 0.10668)
		(layer "F.Cu")
		(net "M_G_CPU1_SA_CB<2>")
	)
	(segment
		(start 154.825954 -244.590824)
		(end 155.29814 -245.062248)
		(width 0.10668)
		(layer "F.Cu")
		(net "M_G_CPU1_SA_CB<2>")
	)
	(segment
		(start 155.108148 -244.308376)
		(end 155.108148 -244.14353)
		(width 0.10668)
		(layer "F.Cu")
		(net "M_G_CPU1_SA_CB<2>")
	)
	(segment
		(start 163.363148 -236.484922)
		(end 163.480242 -236.367828)
		(width 0.10668)
		(layer "F.Cu")
		(net "M_G_CPU1_SA_CB<2>")
	)
	(segment
		(start 156.099002 -243.606066)
		(end 156.264102 -243.606066)
		(width 0.10668)
		(layer "F.Cu")
		(net "M_G_CPU1_SA_CB<2>")
	)
	(segment
		(start 156.236924 -243.1796)
		(end 156.236924 -243.014754)
		(width 0.10668)
		(layer "F.Cu")
		(net "M_G_CPU1_SA_CB<2>")
	)
	(segment
		(start 155.699714 -244.170454)
		(end 155.816808 -244.05336)
		(width 0.10668)
		(layer "F.Cu")
		(net "M_G_CPU1_SA_CB<2>")
	)
	(segment
		(start 154.836876 -245.16588)
		(end 154.54376 -244.872764)
		(width 0.10668)
		(layer "F.Cu")
		(net "M_G_CPU1_SA_CB<2>")
	)
	(segment
		(start 163.666424 -235.585254)
		(end 164.427916 -235.585254)
		(width 0.10668)
		(layer "F.Cu")
		(net "M_G_CPU1_SA_CB<2>")
	)
	(segment
		(start 155.108148 -244.14353)
		(end 155.225242 -244.026436)
		(width 0.10668)
		(layer "F.Cu")
		(net "M_G_CPU1_SA_CB<2>")
	)
	(segment
		(start 163.064952 -236.351826)
		(end 163.198048 -236.484922)
		(width 0.10668)
		(layer "F.Cu")
		(net "M_G_CPU1_SA_CB<2>")
	)
	(segment
		(start 154.54376 -244.707918)
		(end 154.660854 -244.590824)
		(width 0.10668)
		(layer "F.Cu")
		(net "M_G_CPU1_SA_CB<2>")
	)
	(segment
		(start 145.617946 -245.560342)
		(end 145.524982 -245.400322)
		(width 0.0762)
		(layer "F.Cu")
		(net "M_G_CPU1_SA_CB<2>")
	)
	(segment
		(start 156.945584 -242.924584)
		(end 156.945584 -242.759484)
		(width 0.10668)
		(layer "F.Cu")
		(net "M_G_CPU1_SA_CB<2>")
	)
	(segment
		(start 155.225242 -244.026436)
		(end 155.390342 -244.026436)
		(width 0.10668)
		(layer "F.Cu")
		(net "M_G_CPU1_SA_CB<2>")
	)
	(segment
		(start 156.381196 -243.488972)
		(end 156.381196 -243.323872)
		(width 0.10668)
		(layer "F.Cu")
		(net "M_G_CPU1_SA_CB<2>")
	)
	(segment
		(start 155.46324 -245.062248)
		(end 155.580334 -244.945154)
		(width 0.10668)
		(layer "F.Cu")
		(net "M_G_CPU1_SA_CB<2>")
	)
	(segment
		(start 146.860006 -245.445026)
		(end 147.51177 -245.445026)
		(width 0.0762)
		(layer "F.Cu")
		(net "M_G_CPU1_SA_CB<2>")
	)
	(segment
		(start 156.801312 -242.615212)
		(end 156.801312 -242.450366)
		(width 0.10668)
		(layer "F.Cu")
		(net "M_G_CPU1_SA_CB<2>")
	)
	(segment
		(start 154.719782 -245.447566)
		(end 154.836876 -245.330472)
		(width 0.10668)
		(layer "F.Cu")
		(net "M_G_CPU1_SA_CB<2>")
	)
	(segment
		(start 155.78963 -243.462048)
		(end 155.95473 -243.462048)
		(width 0.10668)
		(layer "F.Cu")
		(net "M_G_CPU1_SA_CB<2>")
	)
	(segment
		(start 155.534614 -244.170454)
		(end 155.699714 -244.170454)
		(width 0.10668)
		(layer "F.Cu")
		(net "M_G_CPU1_SA_CB<2>")
	)
	(segment
		(start 156.264102 -243.606066)
		(end 156.381196 -243.488972)
		(width 0.10668)
		(layer "F.Cu")
		(net "M_G_CPU1_SA_CB<2>")
	)
	(segment
		(start 154.54376 -244.872764)
		(end 154.54376 -244.707918)
		(width 0.10668)
		(layer "F.Cu")
		(net "M_G_CPU1_SA_CB<2>")
	)
	(segment
		(start 156.66339 -243.041678)
		(end 156.82849 -243.041678)
		(width 0.10668)
		(layer "F.Cu")
		(net "M_G_CPU1_SA_CB<2>")
	)
	(segment
		(start 154.660854 -244.590824)
		(end 154.825954 -244.590824)
		(width 0.10668)
		(layer "F.Cu")
		(net "M_G_CPU1_SA_CB<2>")
	)
	(segment
		(start 156.519118 -242.89766)
		(end 156.66339 -243.041678)
		(width 0.10668)
		(layer "F.Cu")
		(net "M_G_CPU1_SA_CB<2>")
	)
	(segment
		(start 155.95473 -243.462048)
		(end 156.099002 -243.606066)
		(width 0.10668)
		(layer "F.Cu")
		(net "M_G_CPU1_SA_CB<2>")
	)
	(segment
		(start 145.796508 -245.232936)
		(end 145.80489 -245.237762)
		(width 0.0762)
		(layer "F.Cu")
		(net "M_G_CPU1_SA_CB<2>")
	)
	(segment
		(start 156.354018 -242.89766)
		(end 156.519118 -242.89766)
		(width 0.10668)
		(layer "F.Cu")
		(net "M_G_CPU1_SA_CB<2>")
	)
	(segment
		(start 155.816808 -244.05336)
		(end 155.816808 -243.88826)
		(width 0.10668)
		(layer "F.Cu")
		(net "M_G_CPU1_SA_CB<2>")
	)
	(segment
		(start 154.554428 -245.447566)
		(end 154.719782 -245.447566)
		(width 0.10668)
		(layer "F.Cu")
		(net "M_G_CPU1_SA_CB<2>")
	)
	(arc
		(start 145.80489 -245.237762)
		(mid 145.852584 -245.262572)
		(end 145.902426 -245.28272)
		(width 0.0762)
		(layer "F.Cu")
		(net "M_G_CPU1_SA_CB<2>")
	)
	(arc
		(start 145.656808 -245.189502)
		(mid 145.728816 -245.204284)
		(end 145.796508 -245.232936)
		(width 0.0762)
		(layer "F.Cu")
		(net "M_G_CPU1_SA_CB<2>")
	)
	(arc
		(start 145.524982 -245.400322)
		(mid 145.525142 -245.253761)
		(end 145.656808 -245.189502)
		(width 0.0762)
		(layer "F.Cu")
		(net "M_G_CPU1_SA_CB<2>")
	)
	(arc
		(start 145.902426 -245.28272)
		(mid 146.37439 -245.404138)
		(end 146.860006 -245.445026)
		(width 0.0762)
		(layer "F.Cu")
		(net "M_G_CPU1_SA_CB<2>")
	)
	(segment
		(start 163.279582 -237.010956)
		(end 163.377626 -236.970316)
		(width 0.10668)
		(layer "F.Cu")
		(net "M_G_CPU1_SA_CB<1>")
	)
	(segment
		(start 155.920694 -244.44071)
		(end 157.455616 -242.905788)
		(width 0.10668)
		(layer "F.Cu")
		(net "M_G_CPU1_SA_CB<1>")
	)
	(segment
		(start 147.32635 -245.787926)
		(end 147.761452 -245.787926)
		(width 0.0762)
		(layer "F.Cu")
		(net "M_G_CPU1_SA_CB<1>")
	)
	(segment
		(start 144.490948 -245.882668)
		(end 144.490948 -245.882922)
		(width 0.0762)
		(layer "F.Cu")
		(net "M_G_CPU1_SA_CB<1>")
	)
	(segment
		(start 157.455616 -242.2779)
		(end 162.328352 -237.405164)
		(width 0.10668)
		(layer "F.Cu")
		(net "M_G_CPU1_SA_CB<1>")
	)
	(segment
		(start 165.452806 -236.860334)
		(end 167.588946 -236.435392)
		(width 0.101346)
		(layer "F.Cu")
		(net "M_G_CPU1_SA_CB<1>")
	)
	(segment
		(start 146.386804 -245.726204)
		(end 147.264628 -245.726204)
		(width 0.0762)
		(layer "F.Cu")
		(net "M_G_CPU1_SA_CB<1>")
	)
	(segment
		(start 147.761452 -245.787926)
		(end 155.219146 -245.787926)
		(width 0.10668)
		(layer "F.Cu")
		(net "M_G_CPU1_SA_CB<1>")
	)
	(segment
		(start 163.377626 -236.970316)
		(end 163.64331 -236.860334)
		(width 0.101346)
		(layer "F.Cu")
		(net "M_G_CPU1_SA_CB<1>")
	)
	(segment
		(start 157.455616 -242.905788)
		(end 157.455616 -242.2779)
		(width 0.10668)
		(layer "F.Cu")
		(net "M_G_CPU1_SA_CB<1>")
	)
	(segment
		(start 162.915346 -237.161832)
		(end 163.279582 -237.010956)
		(width 0.10668)
		(layer "F.Cu")
		(net "M_G_CPU1_SA_CB<1>")
	)
	(segment
		(start 155.219146 -245.787926)
		(end 155.920694 -245.086378)
		(width 0.10668)
		(layer "F.Cu")
		(net "M_G_CPU1_SA_CB<1>")
	)
	(segment
		(start 162.328352 -237.405164)
		(end 162.915346 -237.161832)
		(width 0.10668)
		(layer "F.Cu")
		(net "M_G_CPU1_SA_CB<1>")
	)
	(segment
		(start 155.920694 -245.086378)
		(end 155.920694 -244.44071)
		(width 0.10668)
		(layer "F.Cu")
		(net "M_G_CPU1_SA_CB<1>")
	)
	(segment
		(start 167.588946 -236.435392)
		(end 168.527984 -236.435392)
		(width 0.101346)
		(layer "F.Cu")
		(net "M_G_CPU1_SA_CB<1>")
	)
	(segment
		(start 163.64331 -236.860334)
		(end 165.452806 -236.860334)
		(width 0.101346)
		(layer "F.Cu")
		(net "M_G_CPU1_SA_CB<1>")
	)
	(segment
		(start 145.796508 -245.887748)
		(end 145.80489 -245.882922)
		(width 0.0762)
		(layer "F.Cu")
		(net "M_G_CPU1_SA_CB<1>")
	)
	(segment
		(start 147.264628 -245.726204)
		(end 147.32635 -245.787926)
		(width 0.0762)
		(layer "F.Cu")
		(net "M_G_CPU1_SA_CB<1>")
	)
	(arc
		(start 144.864836 -245.882922)
		(mid 145.147792 -245.806745)
		(end 145.430748 -245.882922)
		(width 0.0762)
		(layer "F.Cu")
		(net "M_G_CPU1_SA_CB<1>")
	)
	(arc
		(start 144.490948 -245.882922)
		(mid 144.677892 -245.933177)
		(end 144.864836 -245.882922)
		(width 0.0762)
		(layer "F.Cu")
		(net "M_G_CPU1_SA_CB<1>")
	)
	(arc
		(start 145.430748 -245.882922)
		(mid 145.612999 -245.933272)
		(end 145.796508 -245.887748)
		(width 0.0762)
		(layer "F.Cu")
		(net "M_G_CPU1_SA_CB<1>")
	)
	(arc
		(start 145.80489 -245.882922)
		(mid 146.085481 -245.766072)
		(end 146.386804 -245.726204)
		(width 0.0762)
		(layer "F.Cu")
		(net "M_G_CPU1_SA_CB<1>")
	)
	(arc
		(start 144.206468 -245.806214)
		(mid 144.353789 -245.825533)
		(end 144.490948 -245.882668)
		(width 0.0762)
		(layer "F.Cu")
		(net "M_G_CPU1_SA_CB<1>")
	)
	(arc
		(start 143.737838 -245.560342)
		(mid 143.941854 -245.741036)
		(end 144.206468 -245.806214)
		(width 0.0762)
		(layer "F.Cu")
		(net "M_G_CPU1_SA_CB<1>")
	)
	(segment
		(start 167.222678 -235.160312)
		(end 167.64762 -234.73537)
		(width 0.101346)
		(layer "F.Cu")
		(net "M_G_CPU1_SA_CB<0>")
	)
	(segment
		(start 166.229284 -234.618022)
		(end 166.3446 -234.502706)
		(width 0.101346)
		(layer "F.Cu")
		(net "M_G_CPU1_SA_CB<0>")
	)
	(segment
		(start 146.167602 -245.126764)
		(end 147.111212 -245.126764)
		(width 0.0762)
		(layer "F.Cu")
		(net "M_G_CPU1_SA_CB<0>")
	)
	(segment
		(start 163.014406 -235.755688)
		(end 163.609782 -235.160312)
		(width 0.101346)
		(layer "F.Cu")
		(net "M_G_CPU1_SA_CB<0>")
	)
	(segment
		(start 153.66873 -245.101364)
		(end 163.014406 -235.755688)
		(width 0.10668)
		(layer "F.Cu")
		(net "M_G_CPU1_SA_CB<0>")
	)
	(segment
		(start 166.507668 -234.502706)
		(end 166.622984 -234.618022)
		(width 0.101346)
		(layer "F.Cu")
		(net "M_G_CPU1_SA_CB<0>")
	)
	(segment
		(start 147.513548 -245.101364)
		(end 153.66873 -245.101364)
		(width 0.10668)
		(layer "F.Cu")
		(net "M_G_CPU1_SA_CB<0>")
	)
	(segment
		(start 166.3446 -234.502706)
		(end 166.507668 -234.502706)
		(width 0.101346)
		(layer "F.Cu")
		(net "M_G_CPU1_SA_CB<0>")
	)
	(segment
		(start 147.111212 -245.126764)
		(end 147.136612 -245.101364)
		(width 0.0762)
		(layer "F.Cu")
		(net "M_G_CPU1_SA_CB<0>")
	)
	(segment
		(start 166.229284 -235.044996)
		(end 166.229284 -234.618022)
		(width 0.101346)
		(layer "F.Cu")
		(net "M_G_CPU1_SA_CB<0>")
	)
	(segment
		(start 166.622984 -234.618022)
		(end 166.622984 -235.044996)
		(width 0.101346)
		(layer "F.Cu")
		(net "M_G_CPU1_SA_CB<0>")
	)
	(segment
		(start 167.64762 -234.73537)
		(end 168.527984 -234.73537)
		(width 0.101346)
		(layer "F.Cu")
		(net "M_G_CPU1_SA_CB<0>")
	)
	(segment
		(start 163.609782 -235.160312)
		(end 166.113968 -235.160312)
		(width 0.101346)
		(layer "F.Cu")
		(net "M_G_CPU1_SA_CB<0>")
	)
	(segment
		(start 166.622984 -235.044996)
		(end 166.7383 -235.160312)
		(width 0.101346)
		(layer "F.Cu")
		(net "M_G_CPU1_SA_CB<0>")
	)
	(segment
		(start 166.113968 -235.160312)
		(end 166.229284 -235.044996)
		(width 0.101346)
		(layer "F.Cu")
		(net "M_G_CPU1_SA_CB<0>")
	)
	(segment
		(start 166.7383 -235.160312)
		(end 167.222678 -235.160312)
		(width 0.101346)
		(layer "F.Cu")
		(net "M_G_CPU1_SA_CB<0>")
	)
	(segment
		(start 147.136612 -245.101364)
		(end 147.513548 -245.101364)
		(width 0.0762)
		(layer "F.Cu")
		(net "M_G_CPU1_SA_CB<0>")
	)
	(arc
		(start 146.056858 -245.122192)
		(mid 146.112183 -245.125623)
		(end 146.167602 -245.126764)
		(width 0.0762)
		(layer "F.Cu")
		(net "M_G_CPU1_SA_CB<0>")
	)
	(arc
		(start 145.147792 -244.750336)
		(mid 145.38392 -244.921771)
		(end 145.665444 -244.998494)
		(width 0.0762)
		(layer "F.Cu")
		(net "M_G_CPU1_SA_CB<0>")
	)
	(arc
		(start 145.900902 -245.072916)
		(mid 145.976142 -245.106229)
		(end 146.056858 -245.122192)
		(width 0.0762)
		(layer "F.Cu")
		(net "M_G_CPU1_SA_CB<0>")
	)
	(arc
		(start 145.665444 -244.998494)
		(mid 145.7873 -245.02265)
		(end 145.900902 -245.072916)
		(width 0.0762)
		(layer "F.Cu")
		(net "M_G_CPU1_SA_CB<0>")
	)
	(segment
		(start 163.321238 -252.160278)
		(end 165.296596 -252.160278)
		(width 0.101346)
		(layer "F.Cu")
		(net "M_G_CPU1_SA_CA<6>")
	)
	(segment
		(start 157.07741 -253.814326)
		(end 157.884368 -254.621284)
		(width 0.10668)
		(layer "F.Cu")
		(net "M_G_CPU1_SA_CA<6>")
	)
	(segment
		(start 150.303484 -255.537716)
		(end 152.026874 -253.814326)
		(width 0.10668)
		(layer "F.Cu")
		(net "M_G_CPU1_SA_CA<6>")
	)
	(segment
		(start 165.296596 -252.160278)
		(end 165.721538 -252.58522)
		(width 0.101346)
		(layer "F.Cu")
		(net "M_G_CPU1_SA_CA<6>")
	)
	(segment
		(start 147.208748 -255.451864)
		(end 147.2946 -255.537716)
		(width 0.0762)
		(layer "F.Cu")
		(net "M_G_CPU1_SA_CA<6>")
	)
	(segment
		(start 146.282156 -255.451864)
		(end 147.208748 -255.451864)
		(width 0.0762)
		(layer "F.Cu")
		(net "M_G_CPU1_SA_CA<6>")
	)
	(segment
		(start 163.153598 -252.327918)
		(end 163.321238 -252.160278)
		(width 0.101346)
		(layer "F.Cu")
		(net "M_G_CPU1_SA_CA<6>")
	)
	(segment
		(start 165.721538 -252.58522)
		(end 168.527984 -252.58522)
		(width 0.101346)
		(layer "F.Cu")
		(net "M_G_CPU1_SA_CA<6>")
	)
	(segment
		(start 160.860232 -254.621284)
		(end 163.153598 -252.327918)
		(width 0.10668)
		(layer "F.Cu")
		(net "M_G_CPU1_SA_CA<6>")
	)
	(segment
		(start 152.026874 -253.814326)
		(end 157.07741 -253.814326)
		(width 0.10668)
		(layer "F.Cu")
		(net "M_G_CPU1_SA_CA<6>")
	)
	(segment
		(start 144.490948 -255.60274)
		(end 144.490948 -255.602994)
		(width 0.0762)
		(layer "F.Cu")
		(net "M_G_CPU1_SA_CA<6>")
	)
	(segment
		(start 145.796508 -255.60782)
		(end 145.80489 -255.602994)
		(width 0.0762)
		(layer "F.Cu")
		(net "M_G_CPU1_SA_CA<6>")
	)
	(segment
		(start 147.65401 -255.537716)
		(end 150.303484 -255.537716)
		(width 0.10668)
		(layer "F.Cu")
		(net "M_G_CPU1_SA_CA<6>")
	)
	(segment
		(start 157.884368 -254.621284)
		(end 160.860232 -254.621284)
		(width 0.10668)
		(layer "F.Cu")
		(net "M_G_CPU1_SA_CA<6>")
	)
	(segment
		(start 147.2946 -255.537716)
		(end 147.65401 -255.537716)
		(width 0.0762)
		(layer "F.Cu")
		(net "M_G_CPU1_SA_CA<6>")
	)
	(arc
		(start 143.737838 -255.280414)
		(mid 143.941854 -255.461108)
		(end 144.206468 -255.526286)
		(width 0.0762)
		(layer "F.Cu")
		(net "M_G_CPU1_SA_CA<6>")
	)
	(arc
		(start 145.80489 -255.602994)
		(mid 145.998883 -255.512387)
		(end 146.205956 -255.45796)
		(width 0.0762)
		(layer "F.Cu")
		(net "M_G_CPU1_SA_CA<6>")
	)
	(arc
		(start 144.864836 -255.602994)
		(mid 145.147792 -255.526817)
		(end 145.430748 -255.602994)
		(width 0.0762)
		(layer "F.Cu")
		(net "M_G_CPU1_SA_CA<6>")
	)
	(arc
		(start 146.205956 -255.45796)
		(mid 146.243929 -255.453328)
		(end 146.282156 -255.451864)
		(width 0.0762)
		(layer "F.Cu")
		(net "M_G_CPU1_SA_CA<6>")
	)
	(arc
		(start 144.490948 -255.602994)
		(mid 144.677892 -255.653249)
		(end 144.864836 -255.602994)
		(width 0.0762)
		(layer "F.Cu")
		(net "M_G_CPU1_SA_CA<6>")
	)
	(arc
		(start 145.430748 -255.602994)
		(mid 145.612999 -255.653344)
		(end 145.796508 -255.60782)
		(width 0.0762)
		(layer "F.Cu")
		(net "M_G_CPU1_SA_CA<6>")
	)
	(arc
		(start 144.206468 -255.526286)
		(mid 144.353789 -255.545605)
		(end 144.490948 -255.60274)
		(width 0.0762)
		(layer "F.Cu")
		(net "M_G_CPU1_SA_CA<6>")
	)
	(segment
		(start 150.16226 -255.197356)
		(end 151.89835 -253.461266)
		(width 0.10668)
		(layer "F.Cu")
		(net "M_G_CPU1_SA_CA<5>")
	)
	(segment
		(start 147.67179 -255.197356)
		(end 150.16226 -255.197356)
		(width 0.10668)
		(layer "F.Cu")
		(net "M_G_CPU1_SA_CA<5>")
	)
	(segment
		(start 159.66186 -254.108966)
		(end 159.7787 -253.992126)
		(width 0.10668)
		(layer "F.Cu")
		(net "M_G_CPU1_SA_CA<5>")
	)
	(segment
		(start 159.379666 -253.992126)
		(end 159.496506 -254.108966)
		(width 0.10668)
		(layer "F.Cu")
		(net "M_G_CPU1_SA_CA<5>")
	)
	(segment
		(start 160.576768 -253.992126)
		(end 160.576768 -253.578106)
		(width 0.10668)
		(layer "F.Cu")
		(net "M_G_CPU1_SA_CA<5>")
	)
	(segment
		(start 160.177734 -253.578106)
		(end 160.177734 -253.992126)
		(width 0.10668)
		(layer "F.Cu")
		(net "M_G_CPU1_SA_CA<5>")
	)
	(segment
		(start 160.294574 -254.108966)
		(end 160.459928 -254.108966)
		(width 0.10668)
		(layer "F.Cu")
		(net "M_G_CPU1_SA_CA<5>")
	)
	(segment
		(start 161.301684 -253.461266)
		(end 163.027614 -251.735336)
		(width 0.10668)
		(layer "F.Cu")
		(net "M_G_CPU1_SA_CA<5>")
	)
	(segment
		(start 159.7787 -253.992126)
		(end 159.7787 -253.578106)
		(width 0.10668)
		(layer "F.Cu")
		(net "M_G_CPU1_SA_CA<5>")
	)
	(segment
		(start 158.698438 -254.108966)
		(end 158.863792 -254.108966)
		(width 0.10668)
		(layer "F.Cu")
		(net "M_G_CPU1_SA_CA<5>")
	)
	(segment
		(start 160.060894 -253.461266)
		(end 160.177734 -253.578106)
		(width 0.10668)
		(layer "F.Cu")
		(net "M_G_CPU1_SA_CA<5>")
	)
	(segment
		(start 163.027614 -251.735336)
		(end 164.427916 -251.735336)
		(width 0.10668)
		(layer "F.Cu")
		(net "M_G_CPU1_SA_CA<5>")
	)
	(segment
		(start 159.097472 -253.461266)
		(end 159.262826 -253.461266)
		(width 0.10668)
		(layer "F.Cu")
		(net "M_G_CPU1_SA_CA<5>")
	)
	(segment
		(start 159.496506 -254.108966)
		(end 159.66186 -254.108966)
		(width 0.10668)
		(layer "F.Cu")
		(net "M_G_CPU1_SA_CA<5>")
	)
	(segment
		(start 147.32508 -255.146556)
		(end 147.37588 -255.197356)
		(width 0.0762)
		(layer "F.Cu")
		(net "M_G_CPU1_SA_CA<5>")
	)
	(segment
		(start 158.182564 -253.992126)
		(end 158.182564 -253.578106)
		(width 0.10668)
		(layer "F.Cu")
		(net "M_G_CPU1_SA_CA<5>")
	)
	(segment
		(start 158.980632 -253.578106)
		(end 159.097472 -253.461266)
		(width 0.10668)
		(layer "F.Cu")
		(net "M_G_CPU1_SA_CA<5>")
	)
	(segment
		(start 160.693608 -253.461266)
		(end 161.301684 -253.461266)
		(width 0.10668)
		(layer "F.Cu")
		(net "M_G_CPU1_SA_CA<5>")
	)
	(segment
		(start 147.37588 -255.197356)
		(end 147.67179 -255.197356)
		(width 0.0762)
		(layer "F.Cu")
		(net "M_G_CPU1_SA_CA<5>")
	)
	(segment
		(start 159.7787 -253.578106)
		(end 159.89554 -253.461266)
		(width 0.10668)
		(layer "F.Cu")
		(net "M_G_CPU1_SA_CA<5>")
	)
	(segment
		(start 159.379666 -253.578106)
		(end 159.379666 -253.992126)
		(width 0.10668)
		(layer "F.Cu")
		(net "M_G_CPU1_SA_CA<5>")
	)
	(segment
		(start 159.262826 -253.461266)
		(end 159.379666 -253.578106)
		(width 0.10668)
		(layer "F.Cu")
		(net "M_G_CPU1_SA_CA<5>")
	)
	(segment
		(start 159.89554 -253.461266)
		(end 160.060894 -253.461266)
		(width 0.10668)
		(layer "F.Cu")
		(net "M_G_CPU1_SA_CA<5>")
	)
	(segment
		(start 160.576768 -253.578106)
		(end 160.693608 -253.461266)
		(width 0.10668)
		(layer "F.Cu")
		(net "M_G_CPU1_SA_CA<5>")
	)
	(segment
		(start 158.863792 -254.108966)
		(end 158.980632 -253.992126)
		(width 0.10668)
		(layer "F.Cu")
		(net "M_G_CPU1_SA_CA<5>")
	)
	(segment
		(start 160.177734 -253.992126)
		(end 160.294574 -254.108966)
		(width 0.10668)
		(layer "F.Cu")
		(net "M_G_CPU1_SA_CA<5>")
	)
	(segment
		(start 145.617946 -255.280414)
		(end 145.524982 -255.120394)
		(width 0.0762)
		(layer "F.Cu")
		(net "M_G_CPU1_SA_CA<5>")
	)
	(segment
		(start 151.89835 -253.461266)
		(end 157.66669 -253.461266)
		(width 0.10668)
		(layer "F.Cu")
		(net "M_G_CPU1_SA_CA<5>")
	)
	(segment
		(start 157.78353 -253.992126)
		(end 157.90037 -254.108966)
		(width 0.10668)
		(layer "F.Cu")
		(net "M_G_CPU1_SA_CA<5>")
	)
	(segment
		(start 146.50466 -255.146556)
		(end 147.32508 -255.146556)
		(width 0.0762)
		(layer "F.Cu")
		(net "M_G_CPU1_SA_CA<5>")
	)
	(segment
		(start 158.581598 -253.578106)
		(end 158.581598 -253.992126)
		(width 0.10668)
		(layer "F.Cu")
		(net "M_G_CPU1_SA_CA<5>")
	)
	(segment
		(start 158.299404 -253.461266)
		(end 158.464758 -253.461266)
		(width 0.10668)
		(layer "F.Cu")
		(net "M_G_CPU1_SA_CA<5>")
	)
	(segment
		(start 158.980632 -253.992126)
		(end 158.980632 -253.578106)
		(width 0.10668)
		(layer "F.Cu")
		(net "M_G_CPU1_SA_CA<5>")
	)
	(segment
		(start 158.065724 -254.108966)
		(end 158.182564 -253.992126)
		(width 0.10668)
		(layer "F.Cu")
		(net "M_G_CPU1_SA_CA<5>")
	)
	(segment
		(start 158.182564 -253.578106)
		(end 158.299404 -253.461266)
		(width 0.10668)
		(layer "F.Cu")
		(net "M_G_CPU1_SA_CA<5>")
	)
	(segment
		(start 158.464758 -253.461266)
		(end 158.581598 -253.578106)
		(width 0.10668)
		(layer "F.Cu")
		(net "M_G_CPU1_SA_CA<5>")
	)
	(segment
		(start 160.459928 -254.108966)
		(end 160.576768 -253.992126)
		(width 0.10668)
		(layer "F.Cu")
		(net "M_G_CPU1_SA_CA<5>")
	)
	(segment
		(start 157.90037 -254.108966)
		(end 158.065724 -254.108966)
		(width 0.10668)
		(layer "F.Cu")
		(net "M_G_CPU1_SA_CA<5>")
	)
	(segment
		(start 157.78353 -253.578106)
		(end 157.78353 -253.992126)
		(width 0.10668)
		(layer "F.Cu")
		(net "M_G_CPU1_SA_CA<5>")
	)
	(segment
		(start 158.581598 -253.992126)
		(end 158.698438 -254.108966)
		(width 0.10668)
		(layer "F.Cu")
		(net "M_G_CPU1_SA_CA<5>")
	)
	(segment
		(start 145.796508 -254.953008)
		(end 145.80489 -254.957834)
		(width 0.0762)
		(layer "F.Cu")
		(net "M_G_CPU1_SA_CA<5>")
	)
	(segment
		(start 157.66669 -253.461266)
		(end 157.78353 -253.578106)
		(width 0.10668)
		(layer "F.Cu")
		(net "M_G_CPU1_SA_CA<5>")
	)
	(arc
		(start 145.524982 -255.120394)
		(mid 145.525142 -254.973833)
		(end 145.656808 -254.909574)
		(width 0.0762)
		(layer "F.Cu")
		(net "M_G_CPU1_SA_CA<5>")
	)
	(arc
		(start 145.656808 -254.909574)
		(mid 145.728816 -254.924356)
		(end 145.796508 -254.953008)
		(width 0.0762)
		(layer "F.Cu")
		(net "M_G_CPU1_SA_CA<5>")
	)
	(arc
		(start 145.80489 -254.957834)
		(mid 146.142273 -255.098552)
		(end 146.50466 -255.146556)
		(width 0.0762)
		(layer "F.Cu")
		(net "M_G_CPU1_SA_CA<5>")
	)
	(segment
		(start 150.021036 -254.856996)
		(end 151.760936 -253.117096)
		(width 0.10668)
		(layer "F.Cu")
		(net "M_G_CPU1_SA_CA<4>")
	)
	(segment
		(start 160.951418 -253.117096)
		(end 162.75812 -251.310394)
		(width 0.10668)
		(layer "F.Cu")
		(net "M_G_CPU1_SA_CA<4>")
	)
	(segment
		(start 146.109944 -254.849376)
		(end 147.2438 -254.849376)
		(width 0.0762)
		(layer "F.Cu")
		(net "M_G_CPU1_SA_CA<4>")
	)
	(segment
		(start 147.25142 -254.856996)
		(end 147.67179 -254.856996)
		(width 0.0762)
		(layer "F.Cu")
		(net "M_G_CPU1_SA_CA<4>")
	)
	(segment
		(start 147.2438 -254.849376)
		(end 147.25142 -254.856996)
		(width 0.0762)
		(layer "F.Cu")
		(net "M_G_CPU1_SA_CA<4>")
	)
	(segment
		(start 147.67179 -254.856996)
		(end 150.021036 -254.856996)
		(width 0.10668)
		(layer "F.Cu")
		(net "M_G_CPU1_SA_CA<4>")
	)
	(segment
		(start 165.880796 -251.310394)
		(end 166.305992 -250.885198)
		(width 0.101346)
		(layer "F.Cu")
		(net "M_G_CPU1_SA_CA<4>")
	)
	(segment
		(start 163.377626 -251.310394)
		(end 165.880796 -251.310394)
		(width 0.101346)
		(layer "F.Cu")
		(net "M_G_CPU1_SA_CA<4>")
	)
	(segment
		(start 151.760936 -253.117096)
		(end 160.951418 -253.117096)
		(width 0.10668)
		(layer "F.Cu")
		(net "M_G_CPU1_SA_CA<4>")
	)
	(segment
		(start 162.75812 -251.310394)
		(end 163.377626 -251.310394)
		(width 0.10668)
		(layer "F.Cu")
		(net "M_G_CPU1_SA_CA<4>")
	)
	(segment
		(start 166.305992 -250.885198)
		(end 168.527984 -250.885198)
		(width 0.101346)
		(layer "F.Cu")
		(net "M_G_CPU1_SA_CA<4>")
	)
	(arc
		(start 145.900902 -254.792988)
		(mid 146.001685 -254.835045)
		(end 146.109944 -254.849376)
		(width 0.0762)
		(layer "F.Cu")
		(net "M_G_CPU1_SA_CA<4>")
	)
	(arc
		(start 145.147792 -254.470408)
		(mid 145.38392 -254.641843)
		(end 145.665444 -254.718566)
		(width 0.0762)
		(layer "F.Cu")
		(net "M_G_CPU1_SA_CA<4>")
	)
	(arc
		(start 145.665444 -254.718566)
		(mid 145.7873 -254.742722)
		(end 145.900902 -254.792988)
		(width 0.0762)
		(layer "F.Cu")
		(net "M_G_CPU1_SA_CA<4>")
	)
	(segment
		(start 162.796982 -250.035314)
		(end 164.427916 -250.035314)
		(width 0.10668)
		(layer "F.Cu")
		(net "M_G_CPU1_SA_CA<3>")
	)
	(segment
		(start 160.960054 -252.037342)
		(end 160.960054 -251.872242)
		(width 0.10668)
		(layer "F.Cu")
		(net "M_G_CPU1_SA_CA<3>")
	)
	(segment
		(start 161.619438 -251.967238)
		(end 161.736532 -251.850144)
		(width 0.10668)
		(layer "F.Cu")
		(net "M_G_CPU1_SA_CA<3>")
	)
	(segment
		(start 162.653218 -250.179078)
		(end 162.796982 -250.035314)
		(width 0.10668)
		(layer "F.Cu")
		(net "M_G_CPU1_SA_CA<3>")
	)
	(segment
		(start 161.736532 -251.685044)
		(end 161.524442 -251.472954)
		(width 0.10668)
		(layer "F.Cu")
		(net "M_G_CPU1_SA_CA<3>")
	)
	(segment
		(start 144.207992 -254.470408)
		(end 144.207992 -254.470154)
		(width 0.0762)
		(layer "F.Cu")
		(net "M_G_CPU1_SA_CA<3>")
	)
	(segment
		(start 162.018726 -251.40285)
		(end 162.183826 -251.40285)
		(width 0.10668)
		(layer "F.Cu")
		(net "M_G_CPU1_SA_CA<3>")
	)
	(segment
		(start 162.371024 -250.626372)
		(end 162.583114 -250.838462)
		(width 0.10668)
		(layer "F.Cu")
		(net "M_G_CPU1_SA_CA<3>")
	)
	(segment
		(start 162.205924 -250.626372)
		(end 162.371024 -250.626372)
		(width 0.10668)
		(layer "F.Cu")
		(net "M_G_CPU1_SA_CA<3>")
	)
	(segment
		(start 161.736532 -251.850144)
		(end 161.736532 -251.685044)
		(width 0.10668)
		(layer "F.Cu")
		(net "M_G_CPU1_SA_CA<3>")
	)
	(segment
		(start 147.66417 -254.207264)
		(end 150.189184 -254.207264)
		(width 0.10668)
		(layer "F.Cu")
		(net "M_G_CPU1_SA_CA<3>")
	)
	(segment
		(start 161.172144 -252.249432)
		(end 160.960054 -252.037342)
		(width 0.10668)
		(layer "F.Cu")
		(net "M_G_CPU1_SA_CA<3>")
	)
	(segment
		(start 150.189184 -254.207264)
		(end 151.619712 -252.776736)
		(width 0.10668)
		(layer "F.Cu")
		(net "M_G_CPU1_SA_CA<3>")
	)
	(segment
		(start 151.619712 -252.776736)
		(end 160.05556 -252.776736)
		(width 0.10668)
		(layer "F.Cu")
		(net "M_G_CPU1_SA_CA<3>")
	)
	(segment
		(start 144.960848 -254.147828)
		(end 144.96923 -254.143002)
		(width 0.0762)
		(layer "F.Cu")
		(net "M_G_CPU1_SA_CA<3>")
	)
	(segment
		(start 162.08883 -250.908566)
		(end 162.08883 -250.743466)
		(width 0.10668)
		(layer "F.Cu")
		(net "M_G_CPU1_SA_CA<3>")
	)
	(segment
		(start 162.30092 -251.120656)
		(end 162.08883 -250.908566)
		(width 0.10668)
		(layer "F.Cu")
		(net "M_G_CPU1_SA_CA<3>")
	)
	(segment
		(start 161.806636 -251.19076)
		(end 162.018726 -251.40285)
		(width 0.10668)
		(layer "F.Cu")
		(net "M_G_CPU1_SA_CA<3>")
	)
	(segment
		(start 161.524442 -251.307854)
		(end 161.641536 -251.19076)
		(width 0.10668)
		(layer "F.Cu")
		(net "M_G_CPU1_SA_CA<3>")
	)
	(segment
		(start 161.077148 -251.755148)
		(end 161.242248 -251.755148)
		(width 0.10668)
		(layer "F.Cu")
		(net "M_G_CPU1_SA_CA<3>")
	)
	(segment
		(start 160.960054 -251.872242)
		(end 161.077148 -251.755148)
		(width 0.10668)
		(layer "F.Cu")
		(net "M_G_CPU1_SA_CA<3>")
	)
	(segment
		(start 161.172144 -252.414532)
		(end 161.172144 -252.249432)
		(width 0.10668)
		(layer "F.Cu")
		(net "M_G_CPU1_SA_CA<3>")
	)
	(segment
		(start 144.386554 -254.143002)
		(end 144.38757 -254.14351)
		(width 0.0762)
		(layer "F.Cu")
		(net "M_G_CPU1_SA_CA<3>")
	)
	(segment
		(start 162.08883 -250.743466)
		(end 162.205924 -250.626372)
		(width 0.10668)
		(layer "F.Cu")
		(net "M_G_CPU1_SA_CA<3>")
	)
	(segment
		(start 160.05556 -252.776736)
		(end 160.51276 -252.319536)
		(width 0.10668)
		(layer "F.Cu")
		(net "M_G_CPU1_SA_CA<3>")
	)
	(segment
		(start 160.51276 -252.319536)
		(end 160.67786 -252.319536)
		(width 0.10668)
		(layer "F.Cu")
		(net "M_G_CPU1_SA_CA<3>")
	)
	(segment
		(start 162.30092 -251.285756)
		(end 162.30092 -251.120656)
		(width 0.10668)
		(layer "F.Cu")
		(net "M_G_CPU1_SA_CA<3>")
	)
	(segment
		(start 162.583114 -250.838462)
		(end 162.748214 -250.838462)
		(width 0.10668)
		(layer "F.Cu")
		(net "M_G_CPU1_SA_CA<3>")
	)
	(segment
		(start 146.104356 -254.092964)
		(end 147.023328 -254.092964)
		(width 0.0762)
		(layer "F.Cu")
		(net "M_G_CPU1_SA_CA<3>")
	)
	(segment
		(start 144.207992 -254.470154)
		(end 144.102836 -254.289306)
		(width 0.0762)
		(layer "F.Cu")
		(net "M_G_CPU1_SA_CA<3>")
	)
	(segment
		(start 161.242248 -251.755148)
		(end 161.454338 -251.967238)
		(width 0.10668)
		(layer "F.Cu")
		(net "M_G_CPU1_SA_CA<3>")
	)
	(segment
		(start 162.748214 -250.838462)
		(end 162.865308 -250.721368)
		(width 0.10668)
		(layer "F.Cu")
		(net "M_G_CPU1_SA_CA<3>")
	)
	(segment
		(start 162.653218 -250.344178)
		(end 162.653218 -250.179078)
		(width 0.10668)
		(layer "F.Cu")
		(net "M_G_CPU1_SA_CA<3>")
	)
	(segment
		(start 147.137628 -254.207264)
		(end 147.66417 -254.207264)
		(width 0.0762)
		(layer "F.Cu")
		(net "M_G_CPU1_SA_CA<3>")
	)
	(segment
		(start 161.454338 -251.967238)
		(end 161.619438 -251.967238)
		(width 0.10668)
		(layer "F.Cu")
		(net "M_G_CPU1_SA_CA<3>")
	)
	(segment
		(start 147.023328 -254.092964)
		(end 147.137628 -254.207264)
		(width 0.0762)
		(layer "F.Cu")
		(net "M_G_CPU1_SA_CA<3>")
	)
	(segment
		(start 144.38757 -254.14351)
		(end 144.394936 -254.147828)
		(width 0.0762)
		(layer "F.Cu")
		(net "M_G_CPU1_SA_CA<3>")
	)
	(segment
		(start 161.05505 -252.531626)
		(end 161.172144 -252.414532)
		(width 0.10668)
		(layer "F.Cu")
		(net "M_G_CPU1_SA_CA<3>")
	)
	(segment
		(start 162.183826 -251.40285)
		(end 162.30092 -251.285756)
		(width 0.10668)
		(layer "F.Cu")
		(net "M_G_CPU1_SA_CA<3>")
	)
	(segment
		(start 161.641536 -251.19076)
		(end 161.806636 -251.19076)
		(width 0.10668)
		(layer "F.Cu")
		(net "M_G_CPU1_SA_CA<3>")
	)
	(segment
		(start 160.67786 -252.319536)
		(end 160.88995 -252.531626)
		(width 0.10668)
		(layer "F.Cu")
		(net "M_G_CPU1_SA_CA<3>")
	)
	(segment
		(start 162.865308 -250.721368)
		(end 162.865308 -250.556268)
		(width 0.10668)
		(layer "F.Cu")
		(net "M_G_CPU1_SA_CA<3>")
	)
	(segment
		(start 161.524442 -251.472954)
		(end 161.524442 -251.307854)
		(width 0.10668)
		(layer "F.Cu")
		(net "M_G_CPU1_SA_CA<3>")
	)
	(segment
		(start 160.88995 -252.531626)
		(end 161.05505 -252.531626)
		(width 0.10668)
		(layer "F.Cu")
		(net "M_G_CPU1_SA_CA<3>")
	)
	(segment
		(start 162.865308 -250.556268)
		(end 162.653218 -250.344178)
		(width 0.10668)
		(layer "F.Cu")
		(net "M_G_CPU1_SA_CA<3>")
	)
	(arc
		(start 145.33499 -254.147828)
		(mid 145.617946 -254.224005)
		(end 145.900902 -254.147828)
		(width 0.0762)
		(layer "F.Cu")
		(net "M_G_CPU1_SA_CA<3>")
	)
	(arc
		(start 144.206468 -254.097536)
		(mid 144.299392 -254.108859)
		(end 144.386554 -254.143002)
		(width 0.0762)
		(layer "F.Cu")
		(net "M_G_CPU1_SA_CA<3>")
	)
	(arc
		(start 144.96923 -254.143002)
		(mid 145.152738 -254.097508)
		(end 145.33499 -254.147828)
		(width 0.0762)
		(layer "F.Cu")
		(net "M_G_CPU1_SA_CA<3>")
	)
	(arc
		(start 144.102836 -254.289306)
		(mid 144.111773 -254.170282)
		(end 144.206468 -254.097536)
		(width 0.0762)
		(layer "F.Cu")
		(net "M_G_CPU1_SA_CA<3>")
	)
	(arc
		(start 145.900902 -254.147828)
		(mid 145.998999 -254.106941)
		(end 146.104356 -254.092964)
		(width 0.0762)
		(layer "F.Cu")
		(net "M_G_CPU1_SA_CA<3>")
	)
	(arc
		(start 144.394936 -254.147828)
		(mid 144.677892 -254.224005)
		(end 144.960848 -254.147828)
		(width 0.0762)
		(layer "F.Cu")
		(net "M_G_CPU1_SA_CA<3>")
	)
	(segment
		(start 159.914336 -252.436376)
		(end 163.422584 -248.928128)
		(width 0.10668)
		(layer "F.Cu")
		(net "M_G_CPU1_SA_CA<2>")
	)
	(segment
		(start 146.386804 -253.826264)
		(end 147.64131 -253.826264)
		(width 0.0762)
		(layer "F.Cu")
		(net "M_G_CPU1_SA_CA<2>")
	)
	(segment
		(start 145.796508 -253.987808)
		(end 145.80489 -253.982982)
		(width 0.0762)
		(layer "F.Cu")
		(net "M_G_CPU1_SA_CA<2>")
	)
	(segment
		(start 166.482268 -248.760488)
		(end 166.90721 -249.18543)
		(width 0.101346)
		(layer "F.Cu")
		(net "M_G_CPU1_SA_CA<2>")
	)
	(segment
		(start 147.68195 -253.866904)
		(end 150.04796 -253.866904)
		(width 0.10668)
		(layer "F.Cu")
		(net "M_G_CPU1_SA_CA<2>")
	)
	(segment
		(start 150.04796 -253.866904)
		(end 151.478488 -252.436376)
		(width 0.10668)
		(layer "F.Cu")
		(net "M_G_CPU1_SA_CA<2>")
	)
	(segment
		(start 147.64131 -253.826264)
		(end 147.68195 -253.866904)
		(width 0.0762)
		(layer "F.Cu")
		(net "M_G_CPU1_SA_CA<2>")
	)
	(segment
		(start 163.422584 -248.928128)
		(end 163.590224 -248.760488)
		(width 0.101346)
		(layer "F.Cu")
		(net "M_G_CPU1_SA_CA<2>")
	)
	(segment
		(start 166.90721 -249.18543)
		(end 168.527984 -249.18543)
		(width 0.101346)
		(layer "F.Cu")
		(net "M_G_CPU1_SA_CA<2>")
	)
	(segment
		(start 144.490948 -253.982728)
		(end 144.490948 -253.982982)
		(width 0.0762)
		(layer "F.Cu")
		(net "M_G_CPU1_SA_CA<2>")
	)
	(segment
		(start 163.590224 -248.760488)
		(end 166.482268 -248.760488)
		(width 0.101346)
		(layer "F.Cu")
		(net "M_G_CPU1_SA_CA<2>")
	)
	(segment
		(start 151.478488 -252.436376)
		(end 159.914336 -252.436376)
		(width 0.10668)
		(layer "F.Cu")
		(net "M_G_CPU1_SA_CA<2>")
	)
	(arc
		(start 144.206468 -253.906274)
		(mid 144.353789 -253.925593)
		(end 144.490948 -253.982728)
		(width 0.0762)
		(layer "F.Cu")
		(net "M_G_CPU1_SA_CA<2>")
	)
	(arc
		(start 145.80489 -253.982982)
		(mid 146.085481 -253.866132)
		(end 146.386804 -253.826264)
		(width 0.0762)
		(layer "F.Cu")
		(net "M_G_CPU1_SA_CA<2>")
	)
	(arc
		(start 144.490948 -253.982982)
		(mid 144.677892 -254.033237)
		(end 144.864836 -253.982982)
		(width 0.0762)
		(layer "F.Cu")
		(net "M_G_CPU1_SA_CA<2>")
	)
	(arc
		(start 144.864836 -253.982982)
		(mid 145.147792 -253.906805)
		(end 145.430748 -253.982982)
		(width 0.0762)
		(layer "F.Cu")
		(net "M_G_CPU1_SA_CA<2>")
	)
	(arc
		(start 143.737838 -253.660402)
		(mid 143.941854 -253.841096)
		(end 144.206468 -253.906274)
		(width 0.0762)
		(layer "F.Cu")
		(net "M_G_CPU1_SA_CA<2>")
	)
	(arc
		(start 145.430748 -253.982982)
		(mid 145.612999 -254.033332)
		(end 145.796508 -253.987808)
		(width 0.0762)
		(layer "F.Cu")
		(net "M_G_CPU1_SA_CA<2>")
	)
	(segment
		(start 149.906736 -253.526544)
		(end 151.337264 -252.096016)
		(width 0.10668)
		(layer "F.Cu")
		(net "M_G_CPU1_SA_CA<1>")
	)
	(segment
		(start 160.178242 -250.891294)
		(end 160.295336 -250.7742)
		(width 0.10668)
		(layer "F.Cu")
		(net "M_G_CPU1_SA_CA<1>")
	)
	(segment
		(start 160.74263 -250.326906)
		(end 160.859724 -250.209812)
		(width 0.10668)
		(layer "F.Cu")
		(net "M_G_CPU1_SA_CA<1>")
	)
	(segment
		(start 159.720534 -251.727462)
		(end 159.613854 -251.620782)
		(width 0.10668)
		(layer "F.Cu")
		(net "M_G_CPU1_SA_CA<1>")
	)
	(segment
		(start 162.26028 -249.187716)
		(end 162.42538 -249.187716)
		(width 0.10668)
		(layer "F.Cu")
		(net "M_G_CPU1_SA_CA<1>")
	)
	(segment
		(start 160.167828 -251.445268)
		(end 160.284922 -251.328174)
		(width 0.10668)
		(layer "F.Cu")
		(net "M_G_CPU1_SA_CA<1>")
	)
	(segment
		(start 161.424112 -249.645424)
		(end 161.589212 -249.645424)
		(width 0.10668)
		(layer "F.Cu")
		(net "M_G_CPU1_SA_CA<1>")
	)
	(segment
		(start 151.337264 -252.096016)
		(end 159.51708 -252.096016)
		(width 0.10668)
		(layer "F.Cu")
		(net "M_G_CPU1_SA_CA<1>")
	)
	(segment
		(start 161.024824 -250.209812)
		(end 161.131504 -250.316492)
		(width 0.10668)
		(layer "F.Cu")
		(net "M_G_CPU1_SA_CA<1>")
	)
	(segment
		(start 160.460436 -250.7742)
		(end 160.567116 -250.88088)
		(width 0.10668)
		(layer "F.Cu")
		(net "M_G_CPU1_SA_CA<1>")
	)
	(segment
		(start 162.824668 -248.623328)
		(end 162.989768 -248.623328)
		(width 0.10668)
		(layer "F.Cu")
		(net "M_G_CPU1_SA_CA<1>")
	)
	(segment
		(start 147.686268 -253.526544)
		(end 149.906736 -253.526544)
		(width 0.10668)
		(layer "F.Cu")
		(net "M_G_CPU1_SA_CA<1>")
	)
	(segment
		(start 159.720534 -251.892562)
		(end 159.720534 -251.727462)
		(width 0.10668)
		(layer "F.Cu")
		(net "M_G_CPU1_SA_CA<1>")
	)
	(segment
		(start 162.717988 -248.516648)
		(end 162.824668 -248.623328)
		(width 0.10668)
		(layer "F.Cu")
		(net "M_G_CPU1_SA_CA<1>")
	)
	(segment
		(start 161.131504 -250.316492)
		(end 161.296604 -250.316492)
		(width 0.10668)
		(layer "F.Cu")
		(net "M_G_CPU1_SA_CA<1>")
	)
	(segment
		(start 162.1536 -249.081036)
		(end 162.26028 -249.187716)
		(width 0.10668)
		(layer "F.Cu")
		(net "M_G_CPU1_SA_CA<1>")
	)
	(segment
		(start 159.51708 -252.096016)
		(end 159.720534 -251.892562)
		(width 0.10668)
		(layer "F.Cu")
		(net "M_G_CPU1_SA_CA<1>")
	)
	(segment
		(start 162.552888 -248.516648)
		(end 162.717988 -248.516648)
		(width 0.10668)
		(layer "F.Cu")
		(net "M_G_CPU1_SA_CA<1>")
	)
	(segment
		(start 160.002728 -251.445268)
		(end 160.167828 -251.445268)
		(width 0.10668)
		(layer "F.Cu")
		(net "M_G_CPU1_SA_CA<1>")
	)
	(segment
		(start 161.413698 -250.034298)
		(end 161.307018 -249.927618)
		(width 0.10668)
		(layer "F.Cu")
		(net "M_G_CPU1_SA_CA<1>")
	)
	(segment
		(start 161.871406 -249.19813)
		(end 161.9885 -249.081036)
		(width 0.10668)
		(layer "F.Cu")
		(net "M_G_CPU1_SA_CA<1>")
	)
	(segment
		(start 162.42538 -249.187716)
		(end 162.542474 -249.070622)
		(width 0.10668)
		(layer "F.Cu")
		(net "M_G_CPU1_SA_CA<1>")
	)
	(segment
		(start 161.860992 -249.752104)
		(end 161.978086 -249.63501)
		(width 0.10668)
		(layer "F.Cu")
		(net "M_G_CPU1_SA_CA<1>")
	)
	(segment
		(start 161.307018 -249.927618)
		(end 161.307018 -249.762518)
		(width 0.10668)
		(layer "F.Cu")
		(net "M_G_CPU1_SA_CA<1>")
	)
	(segment
		(start 161.589212 -249.645424)
		(end 161.695892 -249.752104)
		(width 0.10668)
		(layer "F.Cu")
		(net "M_G_CPU1_SA_CA<1>")
	)
	(segment
		(start 160.84931 -250.763786)
		(end 160.84931 -250.598686)
		(width 0.10668)
		(layer "F.Cu")
		(net "M_G_CPU1_SA_CA<1>")
	)
	(segment
		(start 160.284922 -251.163074)
		(end 160.178242 -251.056394)
		(width 0.10668)
		(layer "F.Cu")
		(net "M_G_CPU1_SA_CA<1>")
	)
	(segment
		(start 163.277804 -248.335292)
		(end 164.427916 -248.335292)
		(width 0.10668)
		(layer "F.Cu")
		(net "M_G_CPU1_SA_CA<1>")
	)
	(segment
		(start 161.296604 -250.316492)
		(end 161.413698 -250.199398)
		(width 0.10668)
		(layer "F.Cu")
		(net "M_G_CPU1_SA_CA<1>")
	)
	(segment
		(start 160.84931 -250.598686)
		(end 160.74263 -250.492006)
		(width 0.10668)
		(layer "F.Cu")
		(net "M_G_CPU1_SA_CA<1>")
	)
	(segment
		(start 162.542474 -248.905522)
		(end 162.435794 -248.798842)
		(width 0.10668)
		(layer "F.Cu")
		(net "M_G_CPU1_SA_CA<1>")
	)
	(segment
		(start 146.50466 -253.526544)
		(end 147.686268 -253.526544)
		(width 0.0762)
		(layer "F.Cu")
		(net "M_G_CPU1_SA_CA<1>")
	)
	(segment
		(start 162.542474 -249.070622)
		(end 162.542474 -248.905522)
		(width 0.10668)
		(layer "F.Cu")
		(net "M_G_CPU1_SA_CA<1>")
	)
	(segment
		(start 159.613854 -251.455682)
		(end 159.730948 -251.338588)
		(width 0.10668)
		(layer "F.Cu")
		(net "M_G_CPU1_SA_CA<1>")
	)
	(segment
		(start 145.617946 -253.660402)
		(end 145.524982 -253.500382)
		(width 0.0762)
		(layer "F.Cu")
		(net "M_G_CPU1_SA_CA<1>")
	)
	(segment
		(start 160.732216 -250.88088)
		(end 160.84931 -250.763786)
		(width 0.10668)
		(layer "F.Cu")
		(net "M_G_CPU1_SA_CA<1>")
	)
	(segment
		(start 160.859724 -250.209812)
		(end 161.024824 -250.209812)
		(width 0.10668)
		(layer "F.Cu")
		(net "M_G_CPU1_SA_CA<1>")
	)
	(segment
		(start 162.989768 -248.623328)
		(end 163.277804 -248.335292)
		(width 0.10668)
		(layer "F.Cu")
		(net "M_G_CPU1_SA_CA<1>")
	)
	(segment
		(start 159.730948 -251.338588)
		(end 159.896048 -251.338588)
		(width 0.10668)
		(layer "F.Cu")
		(net "M_G_CPU1_SA_CA<1>")
	)
	(segment
		(start 160.567116 -250.88088)
		(end 160.732216 -250.88088)
		(width 0.10668)
		(layer "F.Cu")
		(net "M_G_CPU1_SA_CA<1>")
	)
	(segment
		(start 162.435794 -248.633742)
		(end 162.552888 -248.516648)
		(width 0.10668)
		(layer "F.Cu")
		(net "M_G_CPU1_SA_CA<1>")
	)
	(segment
		(start 161.978086 -249.46991)
		(end 161.871406 -249.36323)
		(width 0.10668)
		(layer "F.Cu")
		(net "M_G_CPU1_SA_CA<1>")
	)
	(segment
		(start 161.9885 -249.081036)
		(end 162.1536 -249.081036)
		(width 0.10668)
		(layer "F.Cu")
		(net "M_G_CPU1_SA_CA<1>")
	)
	(segment
		(start 159.613854 -251.620782)
		(end 159.613854 -251.455682)
		(width 0.10668)
		(layer "F.Cu")
		(net "M_G_CPU1_SA_CA<1>")
	)
	(segment
		(start 160.178242 -251.056394)
		(end 160.178242 -250.891294)
		(width 0.10668)
		(layer "F.Cu")
		(net "M_G_CPU1_SA_CA<1>")
	)
	(segment
		(start 161.307018 -249.762518)
		(end 161.424112 -249.645424)
		(width 0.10668)
		(layer "F.Cu")
		(net "M_G_CPU1_SA_CA<1>")
	)
	(segment
		(start 145.796508 -253.332996)
		(end 145.80489 -253.337822)
		(width 0.0762)
		(layer "F.Cu")
		(net "M_G_CPU1_SA_CA<1>")
	)
	(segment
		(start 161.413698 -250.199398)
		(end 161.413698 -250.034298)
		(width 0.10668)
		(layer "F.Cu")
		(net "M_G_CPU1_SA_CA<1>")
	)
	(segment
		(start 159.896048 -251.338588)
		(end 160.002728 -251.445268)
		(width 0.10668)
		(layer "F.Cu")
		(net "M_G_CPU1_SA_CA<1>")
	)
	(segment
		(start 160.74263 -250.492006)
		(end 160.74263 -250.326906)
		(width 0.10668)
		(layer "F.Cu")
		(net "M_G_CPU1_SA_CA<1>")
	)
	(segment
		(start 161.871406 -249.36323)
		(end 161.871406 -249.19813)
		(width 0.10668)
		(layer "F.Cu")
		(net "M_G_CPU1_SA_CA<1>")
	)
	(segment
		(start 160.284922 -251.328174)
		(end 160.284922 -251.163074)
		(width 0.10668)
		(layer "F.Cu")
		(net "M_G_CPU1_SA_CA<1>")
	)
	(segment
		(start 161.695892 -249.752104)
		(end 161.860992 -249.752104)
		(width 0.10668)
		(layer "F.Cu")
		(net "M_G_CPU1_SA_CA<1>")
	)
	(segment
		(start 160.295336 -250.7742)
		(end 160.460436 -250.7742)
		(width 0.10668)
		(layer "F.Cu")
		(net "M_G_CPU1_SA_CA<1>")
	)
	(segment
		(start 161.978086 -249.63501)
		(end 161.978086 -249.46991)
		(width 0.10668)
		(layer "F.Cu")
		(net "M_G_CPU1_SA_CA<1>")
	)
	(segment
		(start 162.435794 -248.798842)
		(end 162.435794 -248.633742)
		(width 0.10668)
		(layer "F.Cu")
		(net "M_G_CPU1_SA_CA<1>")
	)
	(arc
		(start 145.80489 -253.337822)
		(mid 146.142273 -253.47854)
		(end 146.50466 -253.526544)
		(width 0.0762)
		(layer "F.Cu")
		(net "M_G_CPU1_SA_CA<1>")
	)
	(arc
		(start 145.656808 -253.289562)
		(mid 145.728816 -253.304344)
		(end 145.796508 -253.332996)
		(width 0.0762)
		(layer "F.Cu")
		(net "M_G_CPU1_SA_CA<1>")
	)
	(arc
		(start 145.524982 -253.500382)
		(mid 145.525142 -253.353821)
		(end 145.656808 -253.289562)
		(width 0.0762)
		(layer "F.Cu")
		(net "M_G_CPU1_SA_CA<1>")
	)
	(segment
		(start 147.66417 -253.186184)
		(end 149.765512 -253.186184)
		(width 0.10668)
		(layer "F.Cu")
		(net "M_G_CPU1_SA_CA<0>")
	)
	(segment
		(start 146.109944 -253.229364)
		(end 146.997928 -253.229364)
		(width 0.0762)
		(layer "F.Cu")
		(net "M_G_CPU1_SA_CA<0>")
	)
	(segment
		(start 163.377626 -247.91035)
		(end 166.671244 -247.91035)
		(width 0.101346)
		(layer "F.Cu")
		(net "M_G_CPU1_SA_CA<0>")
	)
	(segment
		(start 146.997928 -253.229364)
		(end 147.041108 -253.186184)
		(width 0.0762)
		(layer "F.Cu")
		(net "M_G_CPU1_SA_CA<0>")
	)
	(segment
		(start 166.671244 -247.91035)
		(end 167.096186 -247.485408)
		(width 0.101346)
		(layer "F.Cu")
		(net "M_G_CPU1_SA_CA<0>")
	)
	(segment
		(start 149.765512 -253.186184)
		(end 151.19604 -251.755656)
		(width 0.10668)
		(layer "F.Cu")
		(net "M_G_CPU1_SA_CA<0>")
	)
	(segment
		(start 167.096186 -247.485408)
		(end 168.527984 -247.485408)
		(width 0.101346)
		(layer "F.Cu")
		(net "M_G_CPU1_SA_CA<0>")
	)
	(segment
		(start 158.832042 -251.755656)
		(end 162.677348 -247.91035)
		(width 0.10668)
		(layer "F.Cu")
		(net "M_G_CPU1_SA_CA<0>")
	)
	(segment
		(start 151.19604 -251.755656)
		(end 158.832042 -251.755656)
		(width 0.10668)
		(layer "F.Cu")
		(net "M_G_CPU1_SA_CA<0>")
	)
	(segment
		(start 147.041108 -253.186184)
		(end 147.66417 -253.186184)
		(width 0.0762)
		(layer "F.Cu")
		(net "M_G_CPU1_SA_CA<0>")
	)
	(segment
		(start 162.677348 -247.91035)
		(end 163.377626 -247.91035)
		(width 0.10668)
		(layer "F.Cu")
		(net "M_G_CPU1_SA_CA<0>")
	)
	(arc
		(start 145.900902 -253.172976)
		(mid 146.001685 -253.215033)
		(end 146.109944 -253.229364)
		(width 0.0762)
		(layer "F.Cu")
		(net "M_G_CPU1_SA_CA<0>")
	)
	(arc
		(start 145.665444 -253.098554)
		(mid 145.7873 -253.12271)
		(end 145.900902 -253.172976)
		(width 0.0762)
		(layer "F.Cu")
		(net "M_G_CPU1_SA_CA<0>")
	)
	(arc
		(start 145.147792 -252.850396)
		(mid 145.38392 -253.021831)
		(end 145.665444 -253.098554)
		(width 0.0762)
		(layer "F.Cu")
		(net "M_G_CPU1_SA_CA<0>")
	)
	(segment
		(start 145.968212 -250.770644)
		(end 149.777704 -250.770644)
		(width 0.10668)
		(layer "F.Cu")
		(net "M_G_CPU1_RESET_N")
	)
	(segment
		(start 145.617946 -250.420378)
		(end 145.968212 -250.770644)
		(width 0.10668)
		(layer "F.Cu")
		(net "M_G_CPU1_RESET_N")
	)
	(segment
		(start 157.98419 -250.155456)
		(end 163.204398 -244.935248)
		(width 0.10668)
		(layer "F.Cu")
		(net "M_G_CPU1_RESET_N")
	)
	(segment
		(start 150.392892 -250.155456)
		(end 157.98419 -250.155456)
		(width 0.10668)
		(layer "F.Cu")
		(net "M_G_CPU1_RESET_N")
	)
	(segment
		(start 149.777704 -250.770644)
		(end 150.392892 -250.155456)
		(width 0.10668)
		(layer "F.Cu")
		(net "M_G_CPU1_RESET_N")
	)
	(segment
		(start 163.204398 -244.935248)
		(end 164.427916 -244.935248)
		(width 0.10668)
		(layer "F.Cu")
		(net "M_G_CPU1_RESET_N")
	)
	(segment
		(start 163.67125 -253.69012)
		(end 163.926012 -253.435358)
		(width 0.14732)
		(layer "F.Cu")
		(net "M_G_CPU1_CLK_DP<0>")
	)
	(segment
		(start 146.179794 -256.467356)
		(end 146.46529 -256.467356)
		(width 0.0762)
		(layer "F.Cu")
		(net "M_G_CPU1_CLK_DP<0>")
	)
	(segment
		(start 160.437068 -256.584196)
		(end 160.437068 -255.948942)
		(width 0.14732)
		(layer "F.Cu")
		(net "M_G_CPU1_CLK_DP<0>")
	)
	(segment
		(start 159.4231 -255.565148)
		(end 159.806894 -255.948942)
		(width 0.14732)
		(layer "F.Cu")
		(net "M_G_CPU1_CLK_DP<0>")
	)
	(segment
		(start 157.482032 -255.565148)
		(end 157.865826 -255.948942)
		(width 0.14732)
		(layer "F.Cu")
		(net "M_G_CPU1_CLK_DP<0>")
	)
	(segment
		(start 163.926012 -253.435358)
		(end 164.427916 -253.435358)
		(width 0.14732)
		(layer "F.Cu")
		(net "M_G_CPU1_CLK_DP<0>")
	)
	(segment
		(start 160.437068 -255.948942)
		(end 160.820862 -255.565148)
		(width 0.14732)
		(layer "F.Cu")
		(net "M_G_CPU1_CLK_DP<0>")
	)
	(segment
		(start 158.311342 -256.768854)
		(end 158.496 -256.584196)
		(width 0.14732)
		(layer "F.Cu")
		(net "M_G_CPU1_CLK_DP<0>")
	)
	(segment
		(start 161.205164 -255.565148)
		(end 163.080192 -253.69012)
		(width 0.14732)
		(layer "F.Cu")
		(net "M_G_CPU1_CLK_DP<0>")
	)
	(segment
		(start 158.050484 -256.768854)
		(end 158.311342 -256.768854)
		(width 0.14732)
		(layer "F.Cu")
		(net "M_G_CPU1_CLK_DP<0>")
	)
	(segment
		(start 160.820862 -255.565148)
		(end 161.205164 -255.565148)
		(width 0.14732)
		(layer "F.Cu")
		(net "M_G_CPU1_CLK_DP<0>")
	)
	(segment
		(start 157.865826 -255.948942)
		(end 157.865826 -256.584196)
		(width 0.14732)
		(layer "F.Cu")
		(net "M_G_CPU1_CLK_DP<0>")
	)
	(segment
		(start 152.311862 -254.700786)
		(end 155.743148 -254.700786)
		(width 0.14732)
		(layer "F.Cu")
		(net "M_G_CPU1_CLK_DP<0>")
	)
	(segment
		(start 146.690588 -256.692654)
		(end 146.93773 -256.692654)
		(width 0.0762)
		(layer "F.Cu")
		(net "M_G_CPU1_CLK_DP<0>")
	)
	(segment
		(start 157.865826 -256.584196)
		(end 158.050484 -256.768854)
		(width 0.14732)
		(layer "F.Cu")
		(net "M_G_CPU1_CLK_DP<0>")
	)
	(segment
		(start 146.93773 -256.692654)
		(end 147.01266 -256.617724)
		(width 0.0762)
		(layer "F.Cu")
		(net "M_G_CPU1_CLK_DP<0>")
	)
	(segment
		(start 159.806894 -256.584196)
		(end 159.991552 -256.768854)
		(width 0.14732)
		(layer "F.Cu")
		(net "M_G_CPU1_CLK_DP<0>")
	)
	(segment
		(start 158.879794 -255.565148)
		(end 159.4231 -255.565148)
		(width 0.14732)
		(layer "F.Cu")
		(net "M_G_CPU1_CLK_DP<0>")
	)
	(segment
		(start 150.394924 -256.617724)
		(end 152.311862 -254.700786)
		(width 0.14732)
		(layer "F.Cu")
		(net "M_G_CPU1_CLK_DP<0>")
	)
	(segment
		(start 156.60751 -255.565148)
		(end 157.482032 -255.565148)
		(width 0.14732)
		(layer "F.Cu")
		(net "M_G_CPU1_CLK_DP<0>")
	)
	(segment
		(start 146.46529 -256.467356)
		(end 146.690588 -256.692654)
		(width 0.0762)
		(layer "F.Cu")
		(net "M_G_CPU1_CLK_DP<0>")
	)
	(segment
		(start 159.991552 -256.768854)
		(end 160.25241 -256.768854)
		(width 0.14732)
		(layer "F.Cu")
		(net "M_G_CPU1_CLK_DP<0>")
	)
	(segment
		(start 163.080192 -253.69012)
		(end 163.67125 -253.69012)
		(width 0.14732)
		(layer "F.Cu")
		(net "M_G_CPU1_CLK_DP<0>")
	)
	(segment
		(start 158.496 -256.584196)
		(end 158.496 -255.948942)
		(width 0.14732)
		(layer "F.Cu")
		(net "M_G_CPU1_CLK_DP<0>")
	)
	(segment
		(start 160.25241 -256.768854)
		(end 160.437068 -256.584196)
		(width 0.14732)
		(layer "F.Cu")
		(net "M_G_CPU1_CLK_DP<0>")
	)
	(segment
		(start 155.743148 -254.700786)
		(end 156.60751 -255.565148)
		(width 0.14732)
		(layer "F.Cu")
		(net "M_G_CPU1_CLK_DP<0>")
	)
	(segment
		(start 158.496 -255.948942)
		(end 158.879794 -255.565148)
		(width 0.14732)
		(layer "F.Cu")
		(net "M_G_CPU1_CLK_DP<0>")
	)
	(segment
		(start 147.03171 -256.617724)
		(end 150.394924 -256.617724)
		(width 0.14732)
		(layer "F.Cu")
		(net "M_G_CPU1_CLK_DP<0>")
	)
	(segment
		(start 147.01266 -256.617724)
		(end 147.03171 -256.617724)
		(width 0.0762)
		(layer "F.Cu")
		(net "M_G_CPU1_CLK_DP<0>")
	)
	(segment
		(start 159.806894 -255.948942)
		(end 159.806894 -256.584196)
		(width 0.14732)
		(layer "F.Cu")
		(net "M_G_CPU1_CLK_DP<0>")
	)
	(arc
		(start 145.665444 -256.338578)
		(mid 145.7873 -256.362734)
		(end 145.900902 -256.413)
		(width 0.0762)
		(layer "F.Cu")
		(net "M_G_CPU1_CLK_DP<0>")
	)
	(arc
		(start 146.056858 -256.462276)
		(mid 146.118274 -256.466081)
		(end 146.179794 -256.467356)
		(width 0.0762)
		(layer "F.Cu")
		(net "M_G_CPU1_CLK_DP<0>")
	)
	(arc
		(start 145.900902 -256.413)
		(mid 145.976142 -256.446313)
		(end 146.056858 -256.462276)
		(width 0.0762)
		(layer "F.Cu")
		(net "M_G_CPU1_CLK_DP<0>")
	)
	(arc
		(start 145.147792 -256.09042)
		(mid 145.38392 -256.261855)
		(end 145.665444 -256.338578)
		(width 0.0762)
		(layer "F.Cu")
		(net "M_G_CPU1_CLK_DP<0>")
	)
	(segment
		(start 155.601924 -255.041146)
		(end 156.466286 -255.905508)
		(width 0.14732)
		(layer "F.Cu")
		(net "M_G_CPU1_CLK_DN<0>")
	)
	(segment
		(start 159.850328 -257.109214)
		(end 160.393634 -257.109214)
		(width 0.14732)
		(layer "F.Cu")
		(net "M_G_CPU1_CLK_DN<0>")
	)
	(segment
		(start 163.926012 -254.285242)
		(end 164.427916 -254.285242)
		(width 0.14732)
		(layer "F.Cu")
		(net "M_G_CPU1_CLK_DN<0>")
	)
	(segment
		(start 147.01266 -256.958084)
		(end 147.03171 -256.958084)
		(width 0.0762)
		(layer "F.Cu")
		(net "M_G_CPU1_CLK_DN<0>")
	)
	(segment
		(start 158.83636 -256.090166)
		(end 159.021018 -255.905508)
		(width 0.14732)
		(layer "F.Cu")
		(net "M_G_CPU1_CLK_DN<0>")
	)
	(segment
		(start 160.777428 -256.72542)
		(end 160.777428 -256.090166)
		(width 0.14732)
		(layer "F.Cu")
		(net "M_G_CPU1_CLK_DN<0>")
	)
	(segment
		(start 157.90926 -257.109214)
		(end 158.452566 -257.109214)
		(width 0.14732)
		(layer "F.Cu")
		(net "M_G_CPU1_CLK_DN<0>")
	)
	(segment
		(start 159.281876 -255.905508)
		(end 159.466534 -256.090166)
		(width 0.14732)
		(layer "F.Cu")
		(net "M_G_CPU1_CLK_DN<0>")
	)
	(segment
		(start 145.796508 -256.57302)
		(end 145.80489 -256.577846)
		(width 0.0762)
		(layer "F.Cu")
		(net "M_G_CPU1_CLK_DN<0>")
	)
	(segment
		(start 158.452566 -257.109214)
		(end 158.83636 -256.72542)
		(width 0.14732)
		(layer "F.Cu")
		(net "M_G_CPU1_CLK_DN<0>")
	)
	(segment
		(start 146.611594 -256.883154)
		(end 146.93773 -256.883154)
		(width 0.0762)
		(layer "F.Cu")
		(net "M_G_CPU1_CLK_DN<0>")
	)
	(segment
		(start 146.181826 -256.658872)
		(end 146.205702 -256.658872)
		(width 0.0762)
		(layer "F.Cu")
		(net "M_G_CPU1_CLK_DN<0>")
	)
	(segment
		(start 150.536148 -256.958084)
		(end 152.453086 -255.041146)
		(width 0.14732)
		(layer "F.Cu")
		(net "M_G_CPU1_CLK_DN<0>")
	)
	(segment
		(start 157.340808 -255.905508)
		(end 157.525466 -256.090166)
		(width 0.14732)
		(layer "F.Cu")
		(net "M_G_CPU1_CLK_DN<0>")
	)
	(segment
		(start 146.386296 -256.657856)
		(end 146.611594 -256.883154)
		(width 0.0762)
		(layer "F.Cu")
		(net "M_G_CPU1_CLK_DN<0>")
	)
	(segment
		(start 146.93773 -256.883154)
		(end 147.01266 -256.958084)
		(width 0.0762)
		(layer "F.Cu")
		(net "M_G_CPU1_CLK_DN<0>")
	)
	(segment
		(start 147.03171 -256.958084)
		(end 150.536148 -256.958084)
		(width 0.14732)
		(layer "F.Cu")
		(net "M_G_CPU1_CLK_DN<0>")
	)
	(segment
		(start 145.617946 -256.900426)
		(end 145.524982 -256.740406)
		(width 0.0762)
		(layer "F.Cu")
		(net "M_G_CPU1_CLK_DN<0>")
	)
	(segment
		(start 159.466534 -256.72542)
		(end 159.850328 -257.109214)
		(width 0.14732)
		(layer "F.Cu")
		(net "M_G_CPU1_CLK_DN<0>")
	)
	(segment
		(start 160.393634 -257.109214)
		(end 160.777428 -256.72542)
		(width 0.14732)
		(layer "F.Cu")
		(net "M_G_CPU1_CLK_DN<0>")
	)
	(segment
		(start 163.67125 -254.03048)
		(end 163.926012 -254.285242)
		(width 0.14732)
		(layer "F.Cu")
		(net "M_G_CPU1_CLK_DN<0>")
	)
	(segment
		(start 146.040602 -256.652268)
		(end 146.041364 -256.653284)
		(width 0.0762)
		(layer "F.Cu")
		(net "M_G_CPU1_CLK_DN<0>")
	)
	(segment
		(start 160.962086 -255.905508)
		(end 161.346388 -255.905508)
		(width 0.14732)
		(layer "F.Cu")
		(net "M_G_CPU1_CLK_DN<0>")
	)
	(segment
		(start 146.205702 -256.658872)
		(end 146.206718 -256.657856)
		(width 0.0762)
		(layer "F.Cu")
		(net "M_G_CPU1_CLK_DN<0>")
	)
	(segment
		(start 161.346388 -255.905508)
		(end 163.221416 -254.03048)
		(width 0.14732)
		(layer "F.Cu")
		(net "M_G_CPU1_CLK_DN<0>")
	)
	(segment
		(start 159.021018 -255.905508)
		(end 159.281876 -255.905508)
		(width 0.14732)
		(layer "F.Cu")
		(net "M_G_CPU1_CLK_DN<0>")
	)
	(segment
		(start 157.525466 -256.090166)
		(end 157.525466 -256.72542)
		(width 0.14732)
		(layer "F.Cu")
		(net "M_G_CPU1_CLK_DN<0>")
	)
	(segment
		(start 160.777428 -256.090166)
		(end 160.962086 -255.905508)
		(width 0.14732)
		(layer "F.Cu")
		(net "M_G_CPU1_CLK_DN<0>")
	)
	(segment
		(start 163.221416 -254.03048)
		(end 163.67125 -254.03048)
		(width 0.14732)
		(layer "F.Cu")
		(net "M_G_CPU1_CLK_DN<0>")
	)
	(segment
		(start 146.206718 -256.657856)
		(end 146.386296 -256.657856)
		(width 0.0762)
		(layer "F.Cu")
		(net "M_G_CPU1_CLK_DN<0>")
	)
	(segment
		(start 156.466286 -255.905508)
		(end 157.340808 -255.905508)
		(width 0.14732)
		(layer "F.Cu")
		(net "M_G_CPU1_CLK_DN<0>")
	)
	(segment
		(start 159.466534 -256.090166)
		(end 159.466534 -256.72542)
		(width 0.14732)
		(layer "F.Cu")
		(net "M_G_CPU1_CLK_DN<0>")
	)
	(segment
		(start 157.525466 -256.72542)
		(end 157.90926 -257.109214)
		(width 0.14732)
		(layer "F.Cu")
		(net "M_G_CPU1_CLK_DN<0>")
	)
	(segment
		(start 152.453086 -255.041146)
		(end 155.601924 -255.041146)
		(width 0.14732)
		(layer "F.Cu")
		(net "M_G_CPU1_CLK_DN<0>")
	)
	(segment
		(start 158.83636 -256.72542)
		(end 158.83636 -256.090166)
		(width 0.14732)
		(layer "F.Cu")
		(net "M_G_CPU1_CLK_DN<0>")
	)
	(arc
		(start 145.656808 -256.529586)
		(mid 145.728816 -256.544368)
		(end 145.796508 -256.57302)
		(width 0.0762)
		(layer "F.Cu")
		(net "M_G_CPU1_CLK_DN<0>")
	)
	(arc
		(start 145.80489 -256.577846)
		(mid 145.918614 -256.628147)
		(end 146.040602 -256.652268)
		(width 0.0762)
		(layer "F.Cu")
		(net "M_G_CPU1_CLK_DN<0>")
	)
	(arc
		(start 146.041364 -256.653284)
		(mid 146.111539 -256.657478)
		(end 146.181826 -256.658872)
		(width 0.0762)
		(layer "F.Cu")
		(net "M_G_CPU1_CLK_DN<0>")
	)
	(arc
		(start 145.524982 -256.740406)
		(mid 145.525142 -256.593845)
		(end 145.656808 -256.529586)
		(width 0.0762)
		(layer "F.Cu")
		(net "M_G_CPU1_CLK_DN<0>")
	)
	(segment
		(start 163.377626 -244.510306)
		(end 166.706042 -244.510306)
		(width 0.101346)
		(layer "F.Cu")
		(net "M_G_CPU1_ALERT_R_N")
	)
	(segment
		(start 146.759168 -250.232164)
		(end 148.981668 -250.231402)
		(width 0.10668)
		(layer "F.Cu")
		(net "M_G_CPU1_ALERT_R_N")
	)
	(segment
		(start 145.848832 -249.910346)
		(end 146.097244 -250.054364)
		(width 0.0762)
		(layer "F.Cu")
		(net "M_G_CPU1_ALERT_R_N")
	)
	(segment
		(start 150.251668 -249.815096)
		(end 157.842712 -249.815096)
		(width 0.10668)
		(layer "F.Cu")
		(net "M_G_CPU1_ALERT_R_N")
	)
	(segment
		(start 166.706042 -244.510306)
		(end 167.130984 -244.085364)
		(width 0.101346)
		(layer "F.Cu")
		(net "M_G_CPU1_ALERT_R_N")
	)
	(segment
		(start 163.147502 -244.510306)
		(end 163.377626 -244.510306)
		(width 0.10668)
		(layer "F.Cu")
		(net "M_G_CPU1_ALERT_R_N")
	)
	(segment
		(start 157.842712 -249.815096)
		(end 163.147502 -244.510306)
		(width 0.10668)
		(layer "F.Cu")
		(net "M_G_CPU1_ALERT_R_N")
	)
	(segment
		(start 148.981668 -250.231402)
		(end 149.835362 -250.231402)
		(width 0.10668)
		(layer "F.Cu")
		(net "M_G_CPU1_ALERT_R_N")
	)
	(segment
		(start 149.835362 -250.231402)
		(end 150.251668 -249.815096)
		(width 0.10668)
		(layer "F.Cu")
		(net "M_G_CPU1_ALERT_R_N")
	)
	(via
		(at 167.130984 -244.085364)
		(size 0.4826)
		(drill 0.254)
		(layers "F.Cu" "B.Cu")
		(net "M_G_CPU1_ALERT_R_N")
	)
	(arc
		(start 145.147792 -249.610372)
		(mid 145.38392 -249.781807)
		(end 145.665444 -249.85853)
		(width 0.0762)
		(layer "F.Cu")
		(net "M_G_CPU1_ALERT_R_N")
	)
	(arc
		(start 145.778728 -249.879866)
		(mid 145.814681 -249.893033)
		(end 145.848832 -249.910346)
		(width 0.0762)
		(layer "F.Cu")
		(net "M_G_CPU1_ALERT_R_N")
	)
	(arc
		(start 145.665444 -249.85853)
		(mid 145.72263 -249.866306)
		(end 145.778728 -249.879866)
		(width 0.0762)
		(layer "F.Cu")
		(net "M_G_CPU1_ALERT_R_N")
	)
	(arc
		(start 146.097244 -250.054364)
		(mid 146.416469 -250.186951)
		(end 146.759168 -250.232164)
		(width 0.0762)
		(layer "F.Cu")
		(net "M_G_CPU1_ALERT_R_N")
	)
	(via
		(at 168.527984 -244.085364)
		(size 0.4826)
		(drill 0.254)
		(layers "F.Cu" "B.Cu")
		(net "M_G_CPU1_ALERT_N")
	)
	(segment
		(start 167.931084 -244.085364)
		(end 168.527984 -244.085364)
		(width 0.10668)
		(layer "B.Cu")
		(net "M_G_CPU1_ALERT_N")
	)
	(segment
		(start 397.17853 -267.424916)
		(end 397.703802 -267.950188)
		(width 0.10668)
		(layer "F.Cu")
		(net "M_G_CPU0_SB_RSP<0>")
	)
	(segment
		(start 393.857988 -267.34008)
		(end 393.755626 -267.516356)
		(width 0.0762)
		(layer "F.Cu")
		(net "M_G_CPU0_SB_RSP<0>")
	)
	(segment
		(start 411.54985 -270.860012)
		(end 414.146492 -270.860012)
		(width 0.101346)
		(layer "F.Cu")
		(net "M_G_CPU0_SB_RSP<0>")
	)
	(segment
		(start 414.571434 -270.43507)
		(end 416.468052 -270.43507)
		(width 0.101346)
		(layer "F.Cu")
		(net "M_G_CPU0_SB_RSP<0>")
	)
	(segment
		(start 411.387544 -270.697706)
		(end 411.54985 -270.860012)
		(width 0.101346)
		(layer "F.Cu")
		(net "M_G_CPU0_SB_RSP<0>")
	)
	(segment
		(start 395.295374 -267.58646)
		(end 395.456918 -267.424916)
		(width 0.0762)
		(layer "F.Cu")
		(net "M_G_CPU0_SB_RSP<0>")
	)
	(segment
		(start 414.146492 -270.860012)
		(end 414.571434 -270.43507)
		(width 0.101346)
		(layer "F.Cu")
		(net "M_G_CPU0_SB_RSP<0>")
	)
	(segment
		(start 408.640026 -267.950188)
		(end 411.387544 -270.697706)
		(width 0.10668)
		(layer "F.Cu")
		(net "M_G_CPU0_SB_RSP<0>")
	)
	(segment
		(start 395.456918 -267.424916)
		(end 395.697964 -267.424916)
		(width 0.0762)
		(layer "F.Cu")
		(net "M_G_CPU0_SB_RSP<0>")
	)
	(segment
		(start 395.697964 -267.424916)
		(end 397.17853 -267.424916)
		(width 0.10668)
		(layer "F.Cu")
		(net "M_G_CPU0_SB_RSP<0>")
	)
	(segment
		(start 394.327634 -267.58646)
		(end 395.295374 -267.58646)
		(width 0.0762)
		(layer "F.Cu")
		(net "M_G_CPU0_SB_RSP<0>")
	)
	(segment
		(start 397.703802 -267.950188)
		(end 408.640026 -267.950188)
		(width 0.10668)
		(layer "F.Cu")
		(net "M_G_CPU0_SB_RSP<0>")
	)
	(segment
		(start 394.03655 -267.667486)
		(end 394.044932 -267.66266)
		(width 0.0762)
		(layer "F.Cu")
		(net "M_G_CPU0_SB_RSP<0>")
	)
	(arc
		(start 394.280644 -267.588238)
		(mid 394.304121 -267.586862)
		(end 394.327634 -267.58646)
		(width 0.0762)
		(layer "F.Cu")
		(net "M_G_CPU0_SB_RSP<0>")
	)
	(arc
		(start 393.922504 -267.707364)
		(mid 393.98115 -267.692071)
		(end 394.03655 -267.667486)
		(width 0.0762)
		(layer "F.Cu")
		(net "M_G_CPU0_SB_RSP<0>")
	)
	(arc
		(start 393.755626 -267.516356)
		(mid 393.785255 -267.658843)
		(end 393.922504 -267.707364)
		(width 0.0762)
		(layer "F.Cu")
		(net "M_G_CPU0_SB_RSP<0>")
	)
	(arc
		(start 394.044932 -267.66266)
		(mid 394.158656 -267.612359)
		(end 394.280644 -267.588238)
		(width 0.0762)
		(layer "F.Cu")
		(net "M_G_CPU0_SB_RSP<0>")
	)
	(segment
		(start 407.404316 -264.962132)
		(end 407.56967 -264.962132)
		(width 0.10668)
		(layer "F.Cu")
		(net "M_G_CPU0_SB_PAR")
	)
	(segment
		(start 407.170636 -265.45032)
		(end 407.287476 -265.33348)
		(width 0.10668)
		(layer "F.Cu")
		(net "M_G_CPU0_SB_PAR")
	)
	(segment
		(start 404.222966 -266.131548)
		(end 404.222966 -266.026392)
		(width 0.10668)
		(layer "F.Cu")
		(net "M_G_CPU0_SB_PAR")
	)
	(segment
		(start 409.282646 -265.078972)
		(end 409.282646 -265.33348)
		(width 0.10668)
		(layer "F.Cu")
		(net "M_G_CPU0_SB_PAR")
	)
	(segment
		(start 398.89176 -266.248388)
		(end 401.711922 -266.248388)
		(width 0.10668)
		(layer "F.Cu")
		(net "M_G_CPU0_SB_PAR")
	)
	(segment
		(start 407.287476 -265.33348)
		(end 407.287476 -265.078972)
		(width 0.10668)
		(layer "F.Cu")
		(net "M_G_CPU0_SB_PAR")
	)
	(segment
		(start 394.298424 -265.290808)
		(end 395.170914 -265.291824)
		(width 0.0762)
		(layer "F.Cu")
		(net "M_G_CPU0_SB_PAR")
	)
	(segment
		(start 407.68651 -265.33348)
		(end 407.80335 -265.45032)
		(width 0.10668)
		(layer "F.Cu")
		(net "M_G_CPU0_SB_PAR")
	)
	(segment
		(start 406.489408 -265.078972)
		(end 406.606248 -264.962132)
		(width 0.10668)
		(layer "F.Cu")
		(net "M_G_CPU0_SB_PAR")
	)
	(segment
		(start 401.828762 -266.026392)
		(end 401.945602 -265.909552)
		(width 0.10668)
		(layer "F.Cu")
		(net "M_G_CPU0_SB_PAR")
	)
	(segment
		(start 403.142704 -266.248388)
		(end 403.308058 -266.248388)
		(width 0.10668)
		(layer "F.Cu")
		(net "M_G_CPU0_SB_PAR")
	)
	(segment
		(start 392.448034 -264.910062)
		(end 392.339576 -265.096752)
		(width 0.0762)
		(layer "F.Cu")
		(net "M_G_CPU0_SB_PAR")
	)
	(segment
		(start 408.085544 -265.078972)
		(end 408.202384 -264.962132)
		(width 0.10668)
		(layer "F.Cu")
		(net "M_G_CPU0_SB_PAR")
	)
	(segment
		(start 404.339806 -265.909552)
		(end 404.50516 -265.909552)
		(width 0.10668)
		(layer "F.Cu")
		(net "M_G_CPU0_SB_PAR")
	)
	(segment
		(start 402.62683 -266.131548)
		(end 402.62683 -266.026392)
		(width 0.10668)
		(layer "F.Cu")
		(net "M_G_CPU0_SB_PAR")
	)
	(segment
		(start 408.484578 -265.33348)
		(end 408.601418 -265.45032)
		(width 0.10668)
		(layer "F.Cu")
		(net "M_G_CPU0_SB_PAR")
	)
	(segment
		(start 397.768064 -265.124692)
		(end 398.89176 -266.248388)
		(width 0.10668)
		(layer "F.Cu")
		(net "M_G_CPU0_SB_PAR")
	)
	(segment
		(start 403.823932 -266.131548)
		(end 403.940772 -266.248388)
		(width 0.10668)
		(layer "F.Cu")
		(net "M_G_CPU0_SB_PAR")
	)
	(segment
		(start 408.883612 -265.078972)
		(end 409.000452 -264.962132)
		(width 0.10668)
		(layer "F.Cu")
		(net "M_G_CPU0_SB_PAR")
	)
	(segment
		(start 402.909024 -265.909552)
		(end 403.025864 -266.026392)
		(width 0.10668)
		(layer "F.Cu")
		(net "M_G_CPU0_SB_PAR")
	)
	(segment
		(start 404.622 -266.026392)
		(end 404.622 -266.131548)
		(width 0.10668)
		(layer "F.Cu")
		(net "M_G_CPU0_SB_PAR")
	)
	(segment
		(start 407.56967 -264.962132)
		(end 407.68651 -265.078972)
		(width 0.10668)
		(layer "F.Cu")
		(net "M_G_CPU0_SB_PAR")
	)
	(segment
		(start 406.888442 -265.078972)
		(end 406.888442 -265.33348)
		(width 0.10668)
		(layer "F.Cu")
		(net "M_G_CPU0_SB_PAR")
	)
	(segment
		(start 406.771602 -264.962132)
		(end 406.888442 -265.078972)
		(width 0.10668)
		(layer "F.Cu")
		(net "M_G_CPU0_SB_PAR")
	)
	(segment
		(start 404.73884 -266.248388)
		(end 405.21763 -266.248388)
		(width 0.10668)
		(layer "F.Cu")
		(net "M_G_CPU0_SB_PAR")
	)
	(segment
		(start 393.20089 -265.232642)
		(end 393.201144 -265.232642)
		(width 0.0762)
		(layer "F.Cu")
		(net "M_G_CPU0_SB_PAR")
	)
	(segment
		(start 395.338046 -265.124692)
		(end 395.857984 -265.124692)
		(width 0.0762)
		(layer "F.Cu")
		(net "M_G_CPU0_SB_PAR")
	)
	(segment
		(start 404.622 -266.131548)
		(end 404.73884 -266.248388)
		(width 0.10668)
		(layer "F.Cu")
		(net "M_G_CPU0_SB_PAR")
	)
	(segment
		(start 403.707092 -265.909552)
		(end 403.823932 -266.026392)
		(width 0.10668)
		(layer "F.Cu")
		(net "M_G_CPU0_SB_PAR")
	)
	(segment
		(start 408.085544 -265.33348)
		(end 408.085544 -265.078972)
		(width 0.10668)
		(layer "F.Cu")
		(net "M_G_CPU0_SB_PAR")
	)
	(segment
		(start 403.025864 -266.026392)
		(end 403.025864 -266.131548)
		(width 0.10668)
		(layer "F.Cu")
		(net "M_G_CPU0_SB_PAR")
	)
	(segment
		(start 408.883612 -265.33348)
		(end 408.883612 -265.078972)
		(width 0.10668)
		(layer "F.Cu")
		(net "M_G_CPU0_SB_PAR")
	)
	(segment
		(start 404.222966 -266.026392)
		(end 404.339806 -265.909552)
		(width 0.10668)
		(layer "F.Cu")
		(net "M_G_CPU0_SB_PAR")
	)
	(segment
		(start 401.945602 -265.909552)
		(end 402.110956 -265.909552)
		(width 0.10668)
		(layer "F.Cu")
		(net "M_G_CPU0_SB_PAR")
	)
	(segment
		(start 406.372568 -265.45032)
		(end 406.489408 -265.33348)
		(width 0.10668)
		(layer "F.Cu")
		(net "M_G_CPU0_SB_PAR")
	)
	(segment
		(start 409.165806 -264.962132)
		(end 409.282646 -265.078972)
		(width 0.10668)
		(layer "F.Cu")
		(net "M_G_CPU0_SB_PAR")
	)
	(segment
		(start 406.489408 -265.33348)
		(end 406.489408 -265.078972)
		(width 0.10668)
		(layer "F.Cu")
		(net "M_G_CPU0_SB_PAR")
	)
	(segment
		(start 407.287476 -265.078972)
		(end 407.404316 -264.962132)
		(width 0.10668)
		(layer "F.Cu")
		(net "M_G_CPU0_SB_PAR")
	)
	(segment
		(start 406.888442 -265.33348)
		(end 407.005282 -265.45032)
		(width 0.10668)
		(layer "F.Cu")
		(net "M_G_CPU0_SB_PAR")
	)
	(segment
		(start 401.828762 -266.131548)
		(end 401.828762 -266.026392)
		(width 0.10668)
		(layer "F.Cu")
		(net "M_G_CPU0_SB_PAR")
	)
	(segment
		(start 404.106126 -266.248388)
		(end 404.222966 -266.131548)
		(width 0.10668)
		(layer "F.Cu")
		(net "M_G_CPU0_SB_PAR")
	)
	(segment
		(start 405.21763 -266.248388)
		(end 406.015698 -265.45032)
		(width 0.10668)
		(layer "F.Cu")
		(net "M_G_CPU0_SB_PAR")
	)
	(segment
		(start 404.50516 -265.909552)
		(end 404.622 -266.026392)
		(width 0.10668)
		(layer "F.Cu")
		(net "M_G_CPU0_SB_PAR")
	)
	(segment
		(start 408.202384 -264.962132)
		(end 408.367738 -264.962132)
		(width 0.10668)
		(layer "F.Cu")
		(net "M_G_CPU0_SB_PAR")
	)
	(segment
		(start 402.344636 -266.248388)
		(end 402.50999 -266.248388)
		(width 0.10668)
		(layer "F.Cu")
		(net "M_G_CPU0_SB_PAR")
	)
	(segment
		(start 401.711922 -266.248388)
		(end 401.828762 -266.131548)
		(width 0.10668)
		(layer "F.Cu")
		(net "M_G_CPU0_SB_PAR")
	)
	(segment
		(start 403.308058 -266.248388)
		(end 403.424898 -266.131548)
		(width 0.10668)
		(layer "F.Cu")
		(net "M_G_CPU0_SB_PAR")
	)
	(segment
		(start 408.484578 -265.078972)
		(end 408.484578 -265.33348)
		(width 0.10668)
		(layer "F.Cu")
		(net "M_G_CPU0_SB_PAR")
	)
	(segment
		(start 407.005282 -265.45032)
		(end 407.170636 -265.45032)
		(width 0.10668)
		(layer "F.Cu")
		(net "M_G_CPU0_SB_PAR")
	)
	(segment
		(start 403.823932 -266.026392)
		(end 403.823932 -266.131548)
		(width 0.10668)
		(layer "F.Cu")
		(net "M_G_CPU0_SB_PAR")
	)
	(segment
		(start 403.424898 -266.026392)
		(end 403.541738 -265.909552)
		(width 0.10668)
		(layer "F.Cu")
		(net "M_G_CPU0_SB_PAR")
	)
	(segment
		(start 407.968704 -265.45032)
		(end 408.085544 -265.33348)
		(width 0.10668)
		(layer "F.Cu")
		(net "M_G_CPU0_SB_PAR")
	)
	(segment
		(start 403.541738 -265.909552)
		(end 403.707092 -265.909552)
		(width 0.10668)
		(layer "F.Cu")
		(net "M_G_CPU0_SB_PAR")
	)
	(segment
		(start 403.940772 -266.248388)
		(end 404.106126 -266.248388)
		(width 0.10668)
		(layer "F.Cu")
		(net "M_G_CPU0_SB_PAR")
	)
	(segment
		(start 402.110956 -265.909552)
		(end 402.227796 -266.026392)
		(width 0.10668)
		(layer "F.Cu")
		(net "M_G_CPU0_SB_PAR")
	)
	(segment
		(start 408.766772 -265.45032)
		(end 408.883612 -265.33348)
		(width 0.10668)
		(layer "F.Cu")
		(net "M_G_CPU0_SB_PAR")
	)
	(segment
		(start 403.025864 -266.131548)
		(end 403.142704 -266.248388)
		(width 0.10668)
		(layer "F.Cu")
		(net "M_G_CPU0_SB_PAR")
	)
	(segment
		(start 409.636976 -265.45032)
		(end 411.221682 -267.035026)
		(width 0.10668)
		(layer "F.Cu")
		(net "M_G_CPU0_SB_PAR")
	)
	(segment
		(start 406.606248 -264.962132)
		(end 406.771602 -264.962132)
		(width 0.10668)
		(layer "F.Cu")
		(net "M_G_CPU0_SB_PAR")
	)
	(segment
		(start 395.170914 -265.291824)
		(end 395.338046 -265.124692)
		(width 0.0762)
		(layer "F.Cu")
		(net "M_G_CPU0_SB_PAR")
	)
	(segment
		(start 407.68651 -265.078972)
		(end 407.68651 -265.33348)
		(width 0.10668)
		(layer "F.Cu")
		(net "M_G_CPU0_SB_PAR")
	)
	(segment
		(start 409.399486 -265.45032)
		(end 409.636976 -265.45032)
		(width 0.10668)
		(layer "F.Cu")
		(net "M_G_CPU0_SB_PAR")
	)
	(segment
		(start 409.282646 -265.33348)
		(end 409.399486 -265.45032)
		(width 0.10668)
		(layer "F.Cu")
		(net "M_G_CPU0_SB_PAR")
	)
	(segment
		(start 395.857984 -265.124692)
		(end 397.768064 -265.124692)
		(width 0.10668)
		(layer "F.Cu")
		(net "M_G_CPU0_SB_PAR")
	)
	(segment
		(start 402.227796 -266.026392)
		(end 402.227796 -266.131548)
		(width 0.10668)
		(layer "F.Cu")
		(net "M_G_CPU0_SB_PAR")
	)
	(segment
		(start 411.221682 -267.035026)
		(end 412.367984 -267.035026)
		(width 0.10668)
		(layer "F.Cu")
		(net "M_G_CPU0_SB_PAR")
	)
	(segment
		(start 407.80335 -265.45032)
		(end 407.968704 -265.45032)
		(width 0.10668)
		(layer "F.Cu")
		(net "M_G_CPU0_SB_PAR")
	)
	(segment
		(start 402.62683 -266.026392)
		(end 402.74367 -265.909552)
		(width 0.10668)
		(layer "F.Cu")
		(net "M_G_CPU0_SB_PAR")
	)
	(segment
		(start 406.015698 -265.45032)
		(end 406.372568 -265.45032)
		(width 0.10668)
		(layer "F.Cu")
		(net "M_G_CPU0_SB_PAR")
	)
	(segment
		(start 408.601418 -265.45032)
		(end 408.766772 -265.45032)
		(width 0.10668)
		(layer "F.Cu")
		(net "M_G_CPU0_SB_PAR")
	)
	(segment
		(start 409.000452 -264.962132)
		(end 409.165806 -264.962132)
		(width 0.10668)
		(layer "F.Cu")
		(net "M_G_CPU0_SB_PAR")
	)
	(segment
		(start 408.367738 -264.962132)
		(end 408.484578 -265.078972)
		(width 0.10668)
		(layer "F.Cu")
		(net "M_G_CPU0_SB_PAR")
	)
	(segment
		(start 392.626596 -265.237468)
		(end 392.634978 -265.232642)
		(width 0.0762)
		(layer "F.Cu")
		(net "M_G_CPU0_SB_PAR")
	)
	(segment
		(start 403.424898 -266.131548)
		(end 403.424898 -266.026392)
		(width 0.10668)
		(layer "F.Cu")
		(net "M_G_CPU0_SB_PAR")
	)
	(segment
		(start 402.50999 -266.248388)
		(end 402.62683 -266.131548)
		(width 0.10668)
		(layer "F.Cu")
		(net "M_G_CPU0_SB_PAR")
	)
	(segment
		(start 402.74367 -265.909552)
		(end 402.909024 -265.909552)
		(width 0.10668)
		(layer "F.Cu")
		(net "M_G_CPU0_SB_PAR")
	)
	(segment
		(start 402.227796 -266.131548)
		(end 402.344636 -266.248388)
		(width 0.10668)
		(layer "F.Cu")
		(net "M_G_CPU0_SB_PAR")
	)
	(arc
		(start 393.575032 -265.232642)
		(mid 393.857988 -265.156465)
		(end 394.140944 -265.232642)
		(width 0.0762)
		(layer "F.Cu")
		(net "M_G_CPU0_SB_PAR")
	)
	(arc
		(start 392.491214 -265.280394)
		(mid 392.560968 -265.265437)
		(end 392.626596 -265.237468)
		(width 0.0762)
		(layer "F.Cu")
		(net "M_G_CPU0_SB_PAR")
	)
	(arc
		(start 392.634978 -265.232642)
		(mid 392.917934 -265.156465)
		(end 393.20089 -265.232642)
		(width 0.0762)
		(layer "F.Cu")
		(net "M_G_CPU0_SB_PAR")
	)
	(arc
		(start 394.140944 -265.232642)
		(mid 394.181638 -265.254861)
		(end 394.223494 -265.274806)
		(width 0.0762)
		(layer "F.Cu")
		(net "M_G_CPU0_SB_PAR")
	)
	(arc
		(start 392.339576 -265.096752)
		(mid 392.365493 -265.229794)
		(end 392.491214 -265.280394)
		(width 0.0762)
		(layer "F.Cu")
		(net "M_G_CPU0_SB_PAR")
	)
	(arc
		(start 393.201144 -265.232642)
		(mid 393.388088 -265.282966)
		(end 393.575032 -265.232642)
		(width 0.0762)
		(layer "F.Cu")
		(net "M_G_CPU0_SB_PAR")
	)
	(arc
		(start 394.223494 -265.274806)
		(mid 394.260122 -265.286736)
		(end 394.298424 -265.290808)
		(width 0.0762)
		(layer "F.Cu")
		(net "M_G_CPU0_SB_PAR")
	)
	(segment
		(start 394.931646 -270.714724)
		(end 395.42339 -270.714724)
		(width 0.0762)
		(layer "F.Cu")
		(net "M_G_CPU0_SB_DQS_DP<9>")
	)
	(segment
		(start 395.50848 -270.648684)
		(end 407.61285 -270.648684)
		(width 0.12954)
		(layer "F.Cu")
		(net "M_G_CPU0_SB_DQS_DP<9>")
	)
	(segment
		(start 409.043124 -272.078958)
		(end 409.043124 -273.529806)
		(width 0.12954)
		(layer "F.Cu")
		(net "M_G_CPU0_SB_DQS_DP<9>")
	)
	(segment
		(start 413.935418 -275.110194)
		(end 414.252156 -275.426932)
		(width 0.101346)
		(layer "F.Cu")
		(net "M_G_CPU0_SB_DQS_DP<9>")
	)
	(segment
		(start 394.819886 -270.826484)
		(end 394.931646 -270.714724)
		(width 0.0762)
		(layer "F.Cu")
		(net "M_G_CPU0_SB_DQS_DP<9>")
	)
	(segment
		(start 410.887926 -275.374608)
		(end 411.242256 -275.374608)
		(width 0.12954)
		(layer "F.Cu")
		(net "M_G_CPU0_SB_DQS_DP<9>")
	)
	(segment
		(start 394.03655 -270.90751)
		(end 394.044932 -270.902684)
		(width 0.0762)
		(layer "F.Cu")
		(net "M_G_CPU0_SB_DQS_DP<9>")
	)
	(segment
		(start 409.043124 -273.529806)
		(end 410.887926 -275.374608)
		(width 0.12954)
		(layer "F.Cu")
		(net "M_G_CPU0_SB_DQS_DP<9>")
	)
	(segment
		(start 415.637472 -275.852128)
		(end 415.954464 -275.535136)
		(width 0.101346)
		(layer "F.Cu")
		(net "M_G_CPU0_SB_DQS_DP<9>")
	)
	(segment
		(start 393.857988 -270.580104)
		(end 393.755626 -270.75638)
		(width 0.0762)
		(layer "F.Cu")
		(net "M_G_CPU0_SB_DQS_DP<9>")
	)
	(segment
		(start 395.48943 -270.648684)
		(end 395.50848 -270.648684)
		(width 0.0762)
		(layer "F.Cu")
		(net "M_G_CPU0_SB_DQS_DP<9>")
	)
	(segment
		(start 414.252156 -275.426932)
		(end 414.63849 -275.426932)
		(width 0.101346)
		(layer "F.Cu")
		(net "M_G_CPU0_SB_DQS_DP<9>")
	)
	(segment
		(start 414.63849 -275.426932)
		(end 415.063686 -275.852128)
		(width 0.101346)
		(layer "F.Cu")
		(net "M_G_CPU0_SB_DQS_DP<9>")
	)
	(segment
		(start 407.61285 -270.648684)
		(end 409.043124 -272.078958)
		(width 0.12954)
		(layer "F.Cu")
		(net "M_G_CPU0_SB_DQS_DP<9>")
	)
	(segment
		(start 415.954464 -275.535136)
		(end 416.468052 -275.535136)
		(width 0.101346)
		(layer "F.Cu")
		(net "M_G_CPU0_SB_DQS_DP<9>")
	)
	(segment
		(start 411.242256 -275.374608)
		(end 411.50667 -275.110194)
		(width 0.12954)
		(layer "F.Cu")
		(net "M_G_CPU0_SB_DQS_DP<9>")
	)
	(segment
		(start 395.42339 -270.714724)
		(end 395.48943 -270.648684)
		(width 0.0762)
		(layer "F.Cu")
		(net "M_G_CPU0_SB_DQS_DP<9>")
	)
	(segment
		(start 411.50667 -275.110194)
		(end 413.935418 -275.110194)
		(width 0.101346)
		(layer "F.Cu")
		(net "M_G_CPU0_SB_DQS_DP<9>")
	)
	(segment
		(start 415.063686 -275.852128)
		(end 415.637472 -275.852128)
		(width 0.101346)
		(layer "F.Cu")
		(net "M_G_CPU0_SB_DQS_DP<9>")
	)
	(segment
		(start 394.327634 -270.826484)
		(end 394.819886 -270.826484)
		(width 0.0762)
		(layer "F.Cu")
		(net "M_G_CPU0_SB_DQS_DP<9>")
	)
	(arc
		(start 394.280644 -270.828262)
		(mid 394.304121 -270.826886)
		(end 394.327634 -270.826484)
		(width 0.0762)
		(layer "F.Cu")
		(net "M_G_CPU0_SB_DQS_DP<9>")
	)
	(arc
		(start 393.755626 -270.75638)
		(mid 393.785255 -270.898867)
		(end 393.922504 -270.947388)
		(width 0.0762)
		(layer "F.Cu")
		(net "M_G_CPU0_SB_DQS_DP<9>")
	)
	(arc
		(start 394.044932 -270.902684)
		(mid 394.158656 -270.852383)
		(end 394.280644 -270.828262)
		(width 0.0762)
		(layer "F.Cu")
		(net "M_G_CPU0_SB_DQS_DP<9>")
	)
	(arc
		(start 393.922504 -270.947388)
		(mid 393.98115 -270.932095)
		(end 394.03655 -270.90751)
		(width 0.0762)
		(layer "F.Cu")
		(net "M_G_CPU0_SB_DQS_DP<9>")
	)
	(segment
		(start 395.684248 -291.459666)
		(end 395.86662 -291.459666)
		(width 0.12954)
		(layer "F.Cu")
		(net "M_G_CPU0_SB_DQS_DP<8>")
	)
	(segment
		(start 411.547056 -314.371482)
		(end 411.810708 -314.635134)
		(width 0.12954)
		(layer "F.Cu")
		(net "M_G_CPU0_SB_DQS_DP<8>")
	)
	(segment
		(start 406.667208 -309.672736)
		(end 406.929082 -309.411116)
		(width 0.12954)
		(layer "F.Cu")
		(net "M_G_CPU0_SB_DQS_DP<8>")
	)
	(segment
		(start 406.929082 -309.411116)
		(end 407.127456 -309.411116)
		(width 0.12954)
		(layer "F.Cu")
		(net "M_G_CPU0_SB_DQS_DP<8>")
	)
	(segment
		(start 408.406092 -310.887872)
		(end 408.144472 -311.149746)
		(width 0.12954)
		(layer "F.Cu")
		(net "M_G_CPU0_SB_DQS_DP<8>")
	)
	(segment
		(start 405.990806 -308.274466)
		(end 406.133046 -308.416706)
		(width 0.12954)
		(layer "F.Cu")
		(net "M_G_CPU0_SB_DQS_DP<8>")
	)
	(segment
		(start 396.729458 -299.013118)
		(end 405.003508 -307.287168)
		(width 0.12954)
		(layer "F.Cu")
		(net "M_G_CPU0_SB_DQS_DP<8>")
	)
	(segment
		(start 405.792432 -308.274466)
		(end 405.990806 -308.274466)
		(width 0.12954)
		(layer "F.Cu")
		(net "M_G_CPU0_SB_DQS_DP<8>")
	)
	(segment
		(start 406.133046 -308.416706)
		(end 406.132792 -308.614572)
		(width 0.12954)
		(layer "F.Cu")
		(net "M_G_CPU0_SB_DQS_DP<8>")
	)
	(segment
		(start 404.734522 -307.739796)
		(end 404.734522 -308.20614)
		(width 0.12954)
		(layer "F.Cu")
		(net "M_G_CPU0_SB_DQS_DP<8>")
	)
	(segment
		(start 408.264106 -310.547766)
		(end 408.406346 -310.690006)
		(width 0.12954)
		(layer "F.Cu")
		(net "M_G_CPU0_SB_DQS_DP<8>")
	)
	(segment
		(start 408.144472 -311.61609)
		(end 410.899864 -314.371482)
		(width 0.12954)
		(layer "F.Cu")
		(net "M_G_CPU0_SB_DQS_DP<8>")
	)
	(segment
		(start 406.201118 -309.672736)
		(end 406.667208 -309.672736)
		(width 0.12954)
		(layer "F.Cu")
		(net "M_G_CPU0_SB_DQS_DP<8>")
	)
	(segment
		(start 395.86662 -291.459666)
		(end 396.729458 -292.322504)
		(width 0.12954)
		(layer "F.Cu")
		(net "M_G_CPU0_SB_DQS_DP<8>")
	)
	(segment
		(start 394.327888 -291.393626)
		(end 395.599158 -291.393626)
		(width 0.0762)
		(layer "F.Cu")
		(net "M_G_CPU0_SB_DQS_DP<8>")
	)
	(segment
		(start 407.127456 -309.411116)
		(end 407.269696 -309.553356)
		(width 0.12954)
		(layer "F.Cu")
		(net "M_G_CPU0_SB_DQS_DP<8>")
	)
	(segment
		(start 405.064468 -308.536086)
		(end 405.530558 -308.536086)
		(width 0.12954)
		(layer "F.Cu")
		(net "M_G_CPU0_SB_DQS_DP<8>")
	)
	(segment
		(start 407.007822 -310.47944)
		(end 407.337768 -310.809386)
		(width 0.12954)
		(layer "F.Cu")
		(net "M_G_CPU0_SB_DQS_DP<8>")
	)
	(segment
		(start 395.599158 -291.393626)
		(end 395.665198 -291.459666)
		(width 0.0762)
		(layer "F.Cu")
		(net "M_G_CPU0_SB_DQS_DP<8>")
	)
	(segment
		(start 406.132792 -308.614572)
		(end 405.871172 -308.876446)
		(width 0.12954)
		(layer "F.Cu")
		(net "M_G_CPU0_SB_DQS_DP<8>")
	)
	(segment
		(start 410.899864 -314.371482)
		(end 411.547056 -314.371482)
		(width 0.12954)
		(layer "F.Cu")
		(net "M_G_CPU0_SB_DQS_DP<8>")
	)
	(segment
		(start 407.269696 -309.553356)
		(end 407.269442 -309.751222)
		(width 0.12954)
		(layer "F.Cu")
		(net "M_G_CPU0_SB_DQS_DP<8>")
	)
	(segment
		(start 408.144472 -311.149746)
		(end 408.144472 -311.61609)
		(width 0.12954)
		(layer "F.Cu")
		(net "M_G_CPU0_SB_DQS_DP<8>")
	)
	(segment
		(start 407.007822 -310.013096)
		(end 407.007822 -310.47944)
		(width 0.12954)
		(layer "F.Cu")
		(net "M_G_CPU0_SB_DQS_DP<8>")
	)
	(segment
		(start 411.810708 -314.635134)
		(end 412.367984 -314.635134)
		(width 0.12954)
		(layer "F.Cu")
		(net "M_G_CPU0_SB_DQS_DP<8>")
	)
	(segment
		(start 395.665198 -291.459666)
		(end 395.684248 -291.459666)
		(width 0.0762)
		(layer "F.Cu")
		(net "M_G_CPU0_SB_DQS_DP<8>")
	)
	(segment
		(start 405.871172 -309.34279)
		(end 406.201118 -309.672736)
		(width 0.12954)
		(layer "F.Cu")
		(net "M_G_CPU0_SB_DQS_DP<8>")
	)
	(segment
		(start 396.729458 -292.322504)
		(end 396.729458 -299.013118)
		(width 0.12954)
		(layer "F.Cu")
		(net "M_G_CPU0_SB_DQS_DP<8>")
	)
	(segment
		(start 404.734522 -308.20614)
		(end 405.064468 -308.536086)
		(width 0.12954)
		(layer "F.Cu")
		(net "M_G_CPU0_SB_DQS_DP<8>")
	)
	(segment
		(start 405.003508 -307.47081)
		(end 404.734522 -307.739796)
		(width 0.12954)
		(layer "F.Cu")
		(net "M_G_CPU0_SB_DQS_DP<8>")
	)
	(segment
		(start 394.03655 -291.3126)
		(end 394.044932 -291.317426)
		(width 0.0762)
		(layer "F.Cu")
		(net "M_G_CPU0_SB_DQS_DP<8>")
	)
	(segment
		(start 405.530558 -308.536086)
		(end 405.792432 -308.274466)
		(width 0.12954)
		(layer "F.Cu")
		(net "M_G_CPU0_SB_DQS_DP<8>")
	)
	(segment
		(start 407.269442 -309.751222)
		(end 407.007822 -310.013096)
		(width 0.12954)
		(layer "F.Cu")
		(net "M_G_CPU0_SB_DQS_DP<8>")
	)
	(segment
		(start 405.003508 -307.287168)
		(end 405.003508 -307.47081)
		(width 0.12954)
		(layer "F.Cu")
		(net "M_G_CPU0_SB_DQS_DP<8>")
	)
	(segment
		(start 407.803858 -310.809386)
		(end 408.065732 -310.547766)
		(width 0.12954)
		(layer "F.Cu")
		(net "M_G_CPU0_SB_DQS_DP<8>")
	)
	(segment
		(start 408.065732 -310.547766)
		(end 408.264106 -310.547766)
		(width 0.12954)
		(layer "F.Cu")
		(net "M_G_CPU0_SB_DQS_DP<8>")
	)
	(segment
		(start 407.337768 -310.809386)
		(end 407.803858 -310.809386)
		(width 0.12954)
		(layer "F.Cu")
		(net "M_G_CPU0_SB_DQS_DP<8>")
	)
	(segment
		(start 405.871172 -308.876446)
		(end 405.871172 -309.34279)
		(width 0.12954)
		(layer "F.Cu")
		(net "M_G_CPU0_SB_DQS_DP<8>")
	)
	(segment
		(start 408.406346 -310.690006)
		(end 408.406092 -310.887872)
		(width 0.12954)
		(layer "F.Cu")
		(net "M_G_CPU0_SB_DQS_DP<8>")
	)
	(arc
		(start 394.044932 -291.317426)
		(mid 394.181368 -291.374251)
		(end 394.327888 -291.393626)
		(width 0.0762)
		(layer "F.Cu")
		(net "M_G_CPU0_SB_DQS_DP<8>")
	)
	(arc
		(start 392.73099 -291.317426)
		(mid 392.917934 -291.267171)
		(end 393.104878 -291.317426)
		(width 0.0762)
		(layer "F.Cu")
		(net "M_G_CPU0_SB_DQS_DP<8>")
	)
	(arc
		(start 391.97788 -291.640006)
		(mid 392.211878 -291.467963)
		(end 392.49223 -291.392102)
		(width 0.0762)
		(layer "F.Cu")
		(net "M_G_CPU0_SB_DQS_DP<8>")
	)
	(arc
		(start 392.515852 -291.389816)
		(mid 392.627098 -291.364553)
		(end 392.73099 -291.317426)
		(width 0.0762)
		(layer "F.Cu")
		(net "M_G_CPU0_SB_DQS_DP<8>")
	)
	(arc
		(start 392.49223 -291.392102)
		(mid 392.504053 -291.391085)
		(end 392.515852 -291.389816)
		(width 0.0762)
		(layer "F.Cu")
		(net "M_G_CPU0_SB_DQS_DP<8>")
	)
	(arc
		(start 393.67079 -291.317426)
		(mid 393.853041 -291.267076)
		(end 394.03655 -291.3126)
		(width 0.0762)
		(layer "F.Cu")
		(net "M_G_CPU0_SB_DQS_DP<8>")
	)
	(arc
		(start 393.104878 -291.317426)
		(mid 393.387834 -291.393603)
		(end 393.67079 -291.317426)
		(width 0.0762)
		(layer "F.Cu")
		(net "M_G_CPU0_SB_DQS_DP<8>")
	)
	(segment
		(start 405.127714 -298.933108)
		(end 405.269954 -299.075094)
		(width 0.12954)
		(layer "F.Cu")
		(net "M_G_CPU0_SB_DQS_DP<7>")
	)
	(segment
		(start 402.996654 -296.801794)
		(end 402.9964 -296.99966)
		(width 0.12954)
		(layer "F.Cu")
		(net "M_G_CPU0_SB_DQS_DP<7>")
	)
	(segment
		(start 395.46149 -286.36341)
		(end 395.774164 -286.36341)
		(width 0.0762)
		(layer "F.Cu")
		(net "M_G_CPU0_SB_DQS_DP<7>")
	)
	(segment
		(start 405.913336 -300.222158)
		(end 406.06599 -300.069504)
		(width 0.12954)
		(layer "F.Cu")
		(net "M_G_CPU0_SB_DQS_DP<7>")
	)
	(segment
		(start 395.774164 -286.36341)
		(end 395.840204 -286.42945)
		(width 0.0762)
		(layer "F.Cu")
		(net "M_G_CPU0_SB_DQS_DP<7>")
	)
	(segment
		(start 405.116792 -299.426122)
		(end 405.116792 -299.892466)
		(width 0.12954)
		(layer "F.Cu")
		(net "M_G_CPU0_SB_DQS_DP<7>")
	)
	(segment
		(start 401.128992 -290.392612)
		(end 401.128992 -295.904666)
		(width 0.12954)
		(layer "F.Cu")
		(net "M_G_CPU0_SB_DQS_DP<7>")
	)
	(segment
		(start 406.406604 -300.211744)
		(end 406.40635 -300.40961)
		(width 0.12954)
		(layer "F.Cu")
		(net "M_G_CPU0_SB_DQS_DP<7>")
	)
	(segment
		(start 407.390092 -302.165766)
		(end 410.245814 -305.021488)
		(width 0.12954)
		(layer "F.Cu")
		(net "M_G_CPU0_SB_DQS_DP<7>")
	)
	(segment
		(start 401.128992 -295.904666)
		(end 402.036534 -296.812208)
		(width 0.12954)
		(layer "F.Cu")
		(net "M_G_CPU0_SB_DQS_DP<7>")
	)
	(segment
		(start 403.991064 -297.796458)
		(end 404.133304 -297.938444)
		(width 0.12954)
		(layer "F.Cu")
		(net "M_G_CPU0_SB_DQS_DP<7>")
	)
	(segment
		(start 403.980142 -298.289472)
		(end 403.980142 -298.755816)
		(width 0.12954)
		(layer "F.Cu")
		(net "M_G_CPU0_SB_DQS_DP<7>")
	)
	(segment
		(start 403.173184 -297.948858)
		(end 403.640036 -297.948858)
		(width 0.12954)
		(layer "F.Cu")
		(net "M_G_CPU0_SB_DQS_DP<7>")
	)
	(segment
		(start 404.133304 -297.938444)
		(end 404.13305 -298.13631)
		(width 0.12954)
		(layer "F.Cu")
		(net "M_G_CPU0_SB_DQS_DP<7>")
	)
	(segment
		(start 406.40635 -300.40961)
		(end 406.253442 -300.562772)
		(width 0.12954)
		(layer "F.Cu")
		(net "M_G_CPU0_SB_DQS_DP<7>")
	)
	(segment
		(start 406.253442 -300.562772)
		(end 406.253442 -301.029116)
		(width 0.12954)
		(layer "F.Cu")
		(net "M_G_CPU0_SB_DQS_DP<7>")
	)
	(segment
		(start 405.269954 -299.075094)
		(end 405.2697 -299.27296)
		(width 0.12954)
		(layer "F.Cu")
		(net "M_G_CPU0_SB_DQS_DP<7>")
	)
	(segment
		(start 394.327888 -286.533844)
		(end 395.291056 -286.533844)
		(width 0.0762)
		(layer "F.Cu")
		(net "M_G_CPU0_SB_DQS_DP<7>")
	)
	(segment
		(start 402.9964 -296.99966)
		(end 402.843492 -297.152822)
		(width 0.12954)
		(layer "F.Cu")
		(net "M_G_CPU0_SB_DQS_DP<7>")
	)
	(segment
		(start 404.309834 -299.085508)
		(end 404.776686 -299.085508)
		(width 0.12954)
		(layer "F.Cu")
		(net "M_G_CPU0_SB_DQS_DP<7>")
	)
	(segment
		(start 406.583134 -301.358808)
		(end 407.049986 -301.358808)
		(width 0.12954)
		(layer "F.Cu")
		(net "M_G_CPU0_SB_DQS_DP<7>")
	)
	(segment
		(start 403.980142 -298.755816)
		(end 404.309834 -299.085508)
		(width 0.12954)
		(layer "F.Cu")
		(net "M_G_CPU0_SB_DQS_DP<7>")
	)
	(segment
		(start 407.049986 -301.358808)
		(end 407.20264 -301.206154)
		(width 0.12954)
		(layer "F.Cu")
		(net "M_G_CPU0_SB_DQS_DP<7>")
	)
	(segment
		(start 395.859254 -286.42945)
		(end 397.16583 -286.42945)
		(width 0.12954)
		(layer "F.Cu")
		(net "M_G_CPU0_SB_DQS_DP<7>")
	)
	(segment
		(start 403.79269 -297.796204)
		(end 403.991064 -297.796458)
		(width 0.12954)
		(layer "F.Cu")
		(net "M_G_CPU0_SB_DQS_DP<7>")
	)
	(segment
		(start 402.843492 -297.619166)
		(end 403.173184 -297.948858)
		(width 0.12954)
		(layer "F.Cu")
		(net "M_G_CPU0_SB_DQS_DP<7>")
	)
	(segment
		(start 406.06599 -300.069504)
		(end 406.264364 -300.069758)
		(width 0.12954)
		(layer "F.Cu")
		(net "M_G_CPU0_SB_DQS_DP<7>")
	)
	(segment
		(start 404.13305 -298.13631)
		(end 403.980142 -298.289472)
		(width 0.12954)
		(layer "F.Cu")
		(net "M_G_CPU0_SB_DQS_DP<7>")
	)
	(segment
		(start 402.854414 -296.659808)
		(end 402.996654 -296.801794)
		(width 0.12954)
		(layer "F.Cu")
		(net "M_G_CPU0_SB_DQS_DP<7>")
	)
	(segment
		(start 410.245814 -305.021488)
		(end 411.547056 -305.021488)
		(width 0.12954)
		(layer "F.Cu")
		(net "M_G_CPU0_SB_DQS_DP<7>")
	)
	(segment
		(start 405.446484 -300.222158)
		(end 405.913336 -300.222158)
		(width 0.12954)
		(layer "F.Cu")
		(net "M_G_CPU0_SB_DQS_DP<7>")
	)
	(segment
		(start 411.810708 -305.28514)
		(end 412.367984 -305.28514)
		(width 0.12954)
		(layer "F.Cu")
		(net "M_G_CPU0_SB_DQS_DP<7>")
	)
	(segment
		(start 407.401014 -301.206408)
		(end 407.543254 -301.348394)
		(width 0.12954)
		(layer "F.Cu")
		(net "M_G_CPU0_SB_DQS_DP<7>")
	)
	(segment
		(start 404.92934 -298.932854)
		(end 405.127714 -298.933108)
		(width 0.12954)
		(layer "F.Cu")
		(net "M_G_CPU0_SB_DQS_DP<7>")
	)
	(segment
		(start 403.640036 -297.948858)
		(end 403.79269 -297.796204)
		(width 0.12954)
		(layer "F.Cu")
		(net "M_G_CPU0_SB_DQS_DP<7>")
	)
	(segment
		(start 407.543 -301.54626)
		(end 407.390092 -301.699422)
		(width 0.12954)
		(layer "F.Cu")
		(net "M_G_CPU0_SB_DQS_DP<7>")
	)
	(segment
		(start 407.20264 -301.206154)
		(end 407.401014 -301.206408)
		(width 0.12954)
		(layer "F.Cu")
		(net "M_G_CPU0_SB_DQS_DP<7>")
	)
	(segment
		(start 411.547056 -305.021488)
		(end 411.810708 -305.28514)
		(width 0.12954)
		(layer "F.Cu")
		(net "M_G_CPU0_SB_DQS_DP<7>")
	)
	(segment
		(start 404.776686 -299.085508)
		(end 404.92934 -298.932854)
		(width 0.12954)
		(layer "F.Cu")
		(net "M_G_CPU0_SB_DQS_DP<7>")
	)
	(segment
		(start 397.16583 -286.42945)
		(end 401.128992 -290.392612)
		(width 0.12954)
		(layer "F.Cu")
		(net "M_G_CPU0_SB_DQS_DP<7>")
	)
	(segment
		(start 405.116792 -299.892466)
		(end 405.446484 -300.222158)
		(width 0.12954)
		(layer "F.Cu")
		(net "M_G_CPU0_SB_DQS_DP<7>")
	)
	(segment
		(start 407.390092 -301.699422)
		(end 407.390092 -302.165766)
		(width 0.12954)
		(layer "F.Cu")
		(net "M_G_CPU0_SB_DQS_DP<7>")
	)
	(segment
		(start 395.291056 -286.533844)
		(end 395.46149 -286.36341)
		(width 0.0762)
		(layer "F.Cu")
		(net "M_G_CPU0_SB_DQS_DP<7>")
	)
	(segment
		(start 402.65604 -296.659554)
		(end 402.854414 -296.659808)
		(width 0.12954)
		(layer "F.Cu")
		(net "M_G_CPU0_SB_DQS_DP<7>")
	)
	(segment
		(start 402.036534 -296.812208)
		(end 402.503386 -296.812208)
		(width 0.12954)
		(layer "F.Cu")
		(net "M_G_CPU0_SB_DQS_DP<7>")
	)
	(segment
		(start 405.2697 -299.27296)
		(end 405.116792 -299.426122)
		(width 0.12954)
		(layer "F.Cu")
		(net "M_G_CPU0_SB_DQS_DP<7>")
	)
	(segment
		(start 407.543254 -301.348394)
		(end 407.543 -301.54626)
		(width 0.12954)
		(layer "F.Cu")
		(net "M_G_CPU0_SB_DQS_DP<7>")
	)
	(segment
		(start 402.843492 -297.152822)
		(end 402.843492 -297.619166)
		(width 0.12954)
		(layer "F.Cu")
		(net "M_G_CPU0_SB_DQS_DP<7>")
	)
	(segment
		(start 394.03655 -286.452818)
		(end 394.044932 -286.457644)
		(width 0.0762)
		(layer "F.Cu")
		(net "M_G_CPU0_SB_DQS_DP<7>")
	)
	(segment
		(start 406.253442 -301.029116)
		(end 406.583134 -301.358808)
		(width 0.12954)
		(layer "F.Cu")
		(net "M_G_CPU0_SB_DQS_DP<7>")
	)
	(segment
		(start 406.264364 -300.069758)
		(end 406.406604 -300.211744)
		(width 0.12954)
		(layer "F.Cu")
		(net "M_G_CPU0_SB_DQS_DP<7>")
	)
	(segment
		(start 395.840204 -286.42945)
		(end 395.859254 -286.42945)
		(width 0.0762)
		(layer "F.Cu")
		(net "M_G_CPU0_SB_DQS_DP<7>")
	)
	(segment
		(start 402.503386 -296.812208)
		(end 402.65604 -296.659554)
		(width 0.12954)
		(layer "F.Cu")
		(net "M_G_CPU0_SB_DQS_DP<7>")
	)
	(arc
		(start 391.97788 -286.780224)
		(mid 392.211878 -286.608181)
		(end 392.49223 -286.53232)
		(width 0.0762)
		(layer "F.Cu")
		(net "M_G_CPU0_SB_DQS_DP<7>")
	)
	(arc
		(start 392.515852 -286.530034)
		(mid 392.627098 -286.504771)
		(end 392.73099 -286.457644)
		(width 0.0762)
		(layer "F.Cu")
		(net "M_G_CPU0_SB_DQS_DP<7>")
	)
	(arc
		(start 393.67079 -286.457644)
		(mid 393.853041 -286.407294)
		(end 394.03655 -286.452818)
		(width 0.0762)
		(layer "F.Cu")
		(net "M_G_CPU0_SB_DQS_DP<7>")
	)
	(arc
		(start 392.49223 -286.53232)
		(mid 392.504053 -286.531303)
		(end 392.515852 -286.530034)
		(width 0.0762)
		(layer "F.Cu")
		(net "M_G_CPU0_SB_DQS_DP<7>")
	)
	(arc
		(start 393.104878 -286.457644)
		(mid 393.387834 -286.533821)
		(end 393.67079 -286.457644)
		(width 0.0762)
		(layer "F.Cu")
		(net "M_G_CPU0_SB_DQS_DP<7>")
	)
	(arc
		(start 392.73099 -286.457644)
		(mid 392.917934 -286.407389)
		(end 393.104878 -286.457644)
		(width 0.0762)
		(layer "F.Cu")
		(net "M_G_CPU0_SB_DQS_DP<7>")
	)
	(arc
		(start 394.044932 -286.457644)
		(mid 394.181368 -286.514469)
		(end 394.327888 -286.533844)
		(width 0.0762)
		(layer "F.Cu")
		(net "M_G_CPU0_SB_DQS_DP<7>")
	)
	(segment
		(start 395.240002 -281.673808)
		(end 395.566646 -281.347164)
		(width 0.0762)
		(layer "F.Cu")
		(net "M_G_CPU0_SB_DQS_DP<6>")
	)
	(segment
		(start 410.917136 -295.671494)
		(end 411.547056 -295.671494)
		(width 0.12954)
		(layer "F.Cu")
		(net "M_G_CPU0_SB_DQS_DP<6>")
	)
	(segment
		(start 395.840204 -281.413204)
		(end 395.859254 -281.413204)
		(width 0.0762)
		(layer "F.Cu")
		(net "M_G_CPU0_SB_DQS_DP<6>")
	)
	(segment
		(start 407.694384 -293.462202)
		(end 408.101546 -293.05504)
		(width 0.12954)
		(layer "F.Cu")
		(net "M_G_CPU0_SB_DQS_DP<6>")
	)
	(segment
		(start 409.238196 -294.19169)
		(end 409.437332 -294.19169)
		(width 0.12954)
		(layer "F.Cu")
		(net "M_G_CPU0_SB_DQS_DP<6>")
	)
	(segment
		(start 408.101546 -293.05504)
		(end 408.300682 -293.05504)
		(width 0.12954)
		(layer "F.Cu")
		(net "M_G_CPU0_SB_DQS_DP<6>")
	)
	(segment
		(start 409.437332 -294.19169)
		(end 409.578048 -294.332406)
		(width 0.12954)
		(layer "F.Cu")
		(net "M_G_CPU0_SB_DQS_DP<6>")
	)
	(segment
		(start 408.441398 -293.195756)
		(end 408.441398 -293.394892)
		(width 0.12954)
		(layer "F.Cu")
		(net "M_G_CPU0_SB_DQS_DP<6>")
	)
	(segment
		(start 406.897586 -293.13124)
		(end 407.228548 -293.462202)
		(width 0.12954)
		(layer "F.Cu")
		(net "M_G_CPU0_SB_DQS_DP<6>")
	)
	(segment
		(start 409.578048 -294.332406)
		(end 409.578048 -294.531542)
		(width 0.12954)
		(layer "F.Cu")
		(net "M_G_CPU0_SB_DQS_DP<6>")
	)
	(segment
		(start 394.327888 -281.673808)
		(end 395.240002 -281.673808)
		(width 0.0762)
		(layer "F.Cu")
		(net "M_G_CPU0_SB_DQS_DP<6>")
	)
	(segment
		(start 410.573982 -295.32834)
		(end 410.917136 -295.671494)
		(width 0.12954)
		(layer "F.Cu")
		(net "M_G_CPU0_SB_DQS_DP<6>")
	)
	(segment
		(start 408.034236 -294.26789)
		(end 408.365198 -294.598852)
		(width 0.12954)
		(layer "F.Cu")
		(net "M_G_CPU0_SB_DQS_DP<6>")
	)
	(segment
		(start 409.967684 -295.735502)
		(end 410.374846 -295.32834)
		(width 0.12954)
		(layer "F.Cu")
		(net "M_G_CPU0_SB_DQS_DP<6>")
	)
	(segment
		(start 410.374846 -295.32834)
		(end 410.573982 -295.32834)
		(width 0.12954)
		(layer "F.Cu")
		(net "M_G_CPU0_SB_DQS_DP<6>")
	)
	(segment
		(start 395.774164 -281.347164)
		(end 395.840204 -281.413204)
		(width 0.0762)
		(layer "F.Cu")
		(net "M_G_CPU0_SB_DQS_DP<6>")
	)
	(segment
		(start 411.547056 -295.671494)
		(end 411.810708 -295.935146)
		(width 0.12954)
		(layer "F.Cu")
		(net "M_G_CPU0_SB_DQS_DP<6>")
	)
	(segment
		(start 408.300682 -293.05504)
		(end 408.441398 -293.195756)
		(width 0.12954)
		(layer "F.Cu")
		(net "M_G_CPU0_SB_DQS_DP<6>")
	)
	(segment
		(start 395.566646 -281.347164)
		(end 395.774164 -281.347164)
		(width 0.0762)
		(layer "F.Cu")
		(net "M_G_CPU0_SB_DQS_DP<6>")
	)
	(segment
		(start 407.304748 -292.059106)
		(end 407.304748 -292.258242)
		(width 0.12954)
		(layer "F.Cu")
		(net "M_G_CPU0_SB_DQS_DP<6>")
	)
	(segment
		(start 409.578048 -294.531542)
		(end 409.170886 -294.938704)
		(width 0.12954)
		(layer "F.Cu")
		(net "M_G_CPU0_SB_DQS_DP<6>")
	)
	(segment
		(start 407.304748 -292.258242)
		(end 406.897586 -292.665404)
		(width 0.12954)
		(layer "F.Cu")
		(net "M_G_CPU0_SB_DQS_DP<6>")
	)
	(segment
		(start 409.170886 -294.938704)
		(end 409.170886 -295.40454)
		(width 0.12954)
		(layer "F.Cu")
		(net "M_G_CPU0_SB_DQS_DP<6>")
	)
	(segment
		(start 409.170886 -295.40454)
		(end 409.501848 -295.735502)
		(width 0.12954)
		(layer "F.Cu")
		(net "M_G_CPU0_SB_DQS_DP<6>")
	)
	(segment
		(start 408.034236 -293.802054)
		(end 408.034236 -294.26789)
		(width 0.12954)
		(layer "F.Cu")
		(net "M_G_CPU0_SB_DQS_DP<6>")
	)
	(segment
		(start 406.989788 -291.744146)
		(end 407.304748 -292.059106)
		(width 0.12954)
		(layer "F.Cu")
		(net "M_G_CPU0_SB_DQS_DP<6>")
	)
	(segment
		(start 408.365198 -294.598852)
		(end 408.831034 -294.598852)
		(width 0.12954)
		(layer "F.Cu")
		(net "M_G_CPU0_SB_DQS_DP<6>")
	)
	(segment
		(start 395.859254 -281.413204)
		(end 398.501362 -281.413204)
		(width 0.12954)
		(layer "F.Cu")
		(net "M_G_CPU0_SB_DQS_DP<6>")
	)
	(segment
		(start 411.810708 -295.935146)
		(end 412.367984 -295.935146)
		(width 0.12954)
		(layer "F.Cu")
		(net "M_G_CPU0_SB_DQS_DP<6>")
	)
	(segment
		(start 394.03655 -281.592782)
		(end 394.044932 -281.597608)
		(width 0.0762)
		(layer "F.Cu")
		(net "M_G_CPU0_SB_DQS_DP<6>")
	)
	(segment
		(start 408.441398 -293.394892)
		(end 408.034236 -293.802054)
		(width 0.12954)
		(layer "F.Cu")
		(net "M_G_CPU0_SB_DQS_DP<6>")
	)
	(segment
		(start 406.897586 -292.665404)
		(end 406.897586 -293.13124)
		(width 0.12954)
		(layer "F.Cu")
		(net "M_G_CPU0_SB_DQS_DP<6>")
	)
	(segment
		(start 408.831034 -294.598852)
		(end 409.238196 -294.19169)
		(width 0.12954)
		(layer "F.Cu")
		(net "M_G_CPU0_SB_DQS_DP<6>")
	)
	(segment
		(start 407.228548 -293.462202)
		(end 407.694384 -293.462202)
		(width 0.12954)
		(layer "F.Cu")
		(net "M_G_CPU0_SB_DQS_DP<6>")
	)
	(segment
		(start 409.501848 -295.735502)
		(end 409.967684 -295.735502)
		(width 0.12954)
		(layer "F.Cu")
		(net "M_G_CPU0_SB_DQS_DP<6>")
	)
	(segment
		(start 406.989788 -289.90163)
		(end 406.989788 -291.744146)
		(width 0.12954)
		(layer "F.Cu")
		(net "M_G_CPU0_SB_DQS_DP<6>")
	)
	(segment
		(start 398.501362 -281.413204)
		(end 406.989788 -289.90163)
		(width 0.12954)
		(layer "F.Cu")
		(net "M_G_CPU0_SB_DQS_DP<6>")
	)
	(arc
		(start 392.73099 -281.597608)
		(mid 392.917934 -281.547353)
		(end 393.104878 -281.597608)
		(width 0.0762)
		(layer "F.Cu")
		(net "M_G_CPU0_SB_DQS_DP<6>")
	)
	(arc
		(start 392.515852 -281.669998)
		(mid 392.627098 -281.644735)
		(end 392.73099 -281.597608)
		(width 0.0762)
		(layer "F.Cu")
		(net "M_G_CPU0_SB_DQS_DP<6>")
	)
	(arc
		(start 392.49223 -281.672284)
		(mid 392.504053 -281.671267)
		(end 392.515852 -281.669998)
		(width 0.0762)
		(layer "F.Cu")
		(net "M_G_CPU0_SB_DQS_DP<6>")
	)
	(arc
		(start 393.104878 -281.597608)
		(mid 393.387834 -281.673785)
		(end 393.67079 -281.597608)
		(width 0.0762)
		(layer "F.Cu")
		(net "M_G_CPU0_SB_DQS_DP<6>")
	)
	(arc
		(start 393.67079 -281.597608)
		(mid 393.853041 -281.547258)
		(end 394.03655 -281.592782)
		(width 0.0762)
		(layer "F.Cu")
		(net "M_G_CPU0_SB_DQS_DP<6>")
	)
	(arc
		(start 391.97788 -281.920188)
		(mid 392.211878 -281.748145)
		(end 392.49223 -281.672284)
		(width 0.0762)
		(layer "F.Cu")
		(net "M_G_CPU0_SB_DQS_DP<6>")
	)
	(arc
		(start 394.044932 -281.597608)
		(mid 394.181368 -281.654433)
		(end 394.327888 -281.673808)
		(width 0.0762)
		(layer "F.Cu")
		(net "M_G_CPU0_SB_DQS_DP<6>")
	)
	(segment
		(start 395.23289 -276.813772)
		(end 395.3764 -276.670262)
		(width 0.0762)
		(layer "F.Cu")
		(net "M_G_CPU0_SB_DQS_DP<5>")
	)
	(segment
		(start 395.3764 -276.670262)
		(end 395.774164 -276.670262)
		(width 0.0762)
		(layer "F.Cu")
		(net "M_G_CPU0_SB_DQS_DP<5>")
	)
	(segment
		(start 406.386792 -281.45994)
		(end 406.641046 -281.20594)
		(width 0.12954)
		(layer "F.Cu")
		(net "M_G_CPU0_SB_DQS_DP<5>")
	)
	(segment
		(start 406.981406 -281.546046)
		(end 406.727406 -281.8003)
		(width 0.12954)
		(layer "F.Cu")
		(net "M_G_CPU0_SB_DQS_DP<5>")
	)
	(segment
		(start 407.777696 -282.34259)
		(end 407.97607 -282.34259)
		(width 0.12954)
		(layer "F.Cu")
		(net "M_G_CPU0_SB_DQS_DP<5>")
	)
	(segment
		(start 405.84501 -280.21153)
		(end 405.844756 -280.409396)
		(width 0.12954)
		(layer "F.Cu")
		(net "M_G_CPU0_SB_DQS_DP<5>")
	)
	(segment
		(start 411.547056 -286.3215)
		(end 411.810708 -286.585152)
		(width 0.12954)
		(layer "F.Cu")
		(net "M_G_CPU0_SB_DQS_DP<5>")
	)
	(segment
		(start 406.727406 -281.8003)
		(end 406.727406 -282.266644)
		(width 0.12954)
		(layer "F.Cu")
		(net "M_G_CPU0_SB_DQS_DP<5>")
	)
	(segment
		(start 405.590756 -281.129994)
		(end 405.920702 -281.45994)
		(width 0.12954)
		(layer "F.Cu")
		(net "M_G_CPU0_SB_DQS_DP<5>")
	)
	(segment
		(start 404.454106 -279.993344)
		(end 404.784052 -280.32329)
		(width 0.12954)
		(layer "F.Cu")
		(net "M_G_CPU0_SB_DQS_DP<5>")
	)
	(segment
		(start 405.920702 -281.45994)
		(end 406.386792 -281.45994)
		(width 0.12954)
		(layer "F.Cu")
		(net "M_G_CPU0_SB_DQS_DP<5>")
	)
	(segment
		(start 405.70277 -280.06929)
		(end 405.84501 -280.21153)
		(width 0.12954)
		(layer "F.Cu")
		(net "M_G_CPU0_SB_DQS_DP<5>")
	)
	(segment
		(start 395.859254 -276.736302)
		(end 402.369782 -276.736302)
		(width 0.12954)
		(layer "F.Cu")
		(net "M_G_CPU0_SB_DQS_DP<5>")
	)
	(segment
		(start 405.250142 -280.32329)
		(end 405.504396 -280.06929)
		(width 0.12954)
		(layer "F.Cu")
		(net "M_G_CPU0_SB_DQS_DP<5>")
	)
	(segment
		(start 404.715472 -279.26538)
		(end 404.454106 -279.526746)
		(width 0.12954)
		(layer "F.Cu")
		(net "M_G_CPU0_SB_DQS_DP<5>")
	)
	(segment
		(start 408.11831 -282.48483)
		(end 408.118056 -282.682696)
		(width 0.12954)
		(layer "F.Cu")
		(net "M_G_CPU0_SB_DQS_DP<5>")
	)
	(segment
		(start 395.774164 -276.670262)
		(end 395.840204 -276.736302)
		(width 0.0762)
		(layer "F.Cu")
		(net "M_G_CPU0_SB_DQS_DP<5>")
	)
	(segment
		(start 406.98166 -281.34818)
		(end 406.981406 -281.546046)
		(width 0.12954)
		(layer "F.Cu")
		(net "M_G_CPU0_SB_DQS_DP<5>")
	)
	(segment
		(start 395.840204 -276.736302)
		(end 395.859254 -276.736302)
		(width 0.0762)
		(layer "F.Cu")
		(net "M_G_CPU0_SB_DQS_DP<5>")
	)
	(segment
		(start 411.810708 -286.585152)
		(end 412.367984 -286.585152)
		(width 0.12954)
		(layer "F.Cu")
		(net "M_G_CPU0_SB_DQS_DP<5>")
	)
	(segment
		(start 406.727406 -282.266644)
		(end 407.057352 -282.59659)
		(width 0.12954)
		(layer "F.Cu")
		(net "M_G_CPU0_SB_DQS_DP<5>")
	)
	(segment
		(start 405.504396 -280.06929)
		(end 405.70277 -280.06929)
		(width 0.12954)
		(layer "F.Cu")
		(net "M_G_CPU0_SB_DQS_DP<5>")
	)
	(segment
		(start 408.118056 -282.682696)
		(end 407.864056 -282.93695)
		(width 0.12954)
		(layer "F.Cu")
		(net "M_G_CPU0_SB_DQS_DP<5>")
	)
	(segment
		(start 407.864056 -283.403294)
		(end 410.782262 -286.3215)
		(width 0.12954)
		(layer "F.Cu")
		(net "M_G_CPU0_SB_DQS_DP<5>")
	)
	(segment
		(start 402.369782 -276.736302)
		(end 404.715472 -279.081992)
		(width 0.12954)
		(layer "F.Cu")
		(net "M_G_CPU0_SB_DQS_DP<5>")
	)
	(segment
		(start 407.97607 -282.34259)
		(end 408.11831 -282.48483)
		(width 0.12954)
		(layer "F.Cu")
		(net "M_G_CPU0_SB_DQS_DP<5>")
	)
	(segment
		(start 406.641046 -281.20594)
		(end 406.83942 -281.20594)
		(width 0.12954)
		(layer "F.Cu")
		(net "M_G_CPU0_SB_DQS_DP<5>")
	)
	(segment
		(start 410.782262 -286.3215)
		(end 411.547056 -286.3215)
		(width 0.12954)
		(layer "F.Cu")
		(net "M_G_CPU0_SB_DQS_DP<5>")
	)
	(segment
		(start 404.715472 -279.081992)
		(end 404.715472 -279.26538)
		(width 0.12954)
		(layer "F.Cu")
		(net "M_G_CPU0_SB_DQS_DP<5>")
	)
	(segment
		(start 394.03655 -276.732746)
		(end 394.044932 -276.737572)
		(width 0.0762)
		(layer "F.Cu")
		(net "M_G_CPU0_SB_DQS_DP<5>")
	)
	(segment
		(start 405.844756 -280.409396)
		(end 405.590756 -280.66365)
		(width 0.12954)
		(layer "F.Cu")
		(net "M_G_CPU0_SB_DQS_DP<5>")
	)
	(segment
		(start 404.454106 -279.526746)
		(end 404.454106 -279.993344)
		(width 0.12954)
		(layer "F.Cu")
		(net "M_G_CPU0_SB_DQS_DP<5>")
	)
	(segment
		(start 407.057352 -282.59659)
		(end 407.523442 -282.59659)
		(width 0.12954)
		(layer "F.Cu")
		(net "M_G_CPU0_SB_DQS_DP<5>")
	)
	(segment
		(start 405.590756 -280.66365)
		(end 405.590756 -281.129994)
		(width 0.12954)
		(layer "F.Cu")
		(net "M_G_CPU0_SB_DQS_DP<5>")
	)
	(segment
		(start 404.784052 -280.32329)
		(end 405.250142 -280.32329)
		(width 0.12954)
		(layer "F.Cu")
		(net "M_G_CPU0_SB_DQS_DP<5>")
	)
	(segment
		(start 406.83942 -281.20594)
		(end 406.98166 -281.34818)
		(width 0.12954)
		(layer "F.Cu")
		(net "M_G_CPU0_SB_DQS_DP<5>")
	)
	(segment
		(start 407.523442 -282.59659)
		(end 407.777696 -282.34259)
		(width 0.12954)
		(layer "F.Cu")
		(net "M_G_CPU0_SB_DQS_DP<5>")
	)
	(segment
		(start 394.327888 -276.813772)
		(end 395.23289 -276.813772)
		(width 0.0762)
		(layer "F.Cu")
		(net "M_G_CPU0_SB_DQS_DP<5>")
	)
	(segment
		(start 407.864056 -282.93695)
		(end 407.864056 -283.403294)
		(width 0.12954)
		(layer "F.Cu")
		(net "M_G_CPU0_SB_DQS_DP<5>")
	)
	(arc
		(start 394.044932 -276.737572)
		(mid 394.181368 -276.794397)
		(end 394.327888 -276.813772)
		(width 0.0762)
		(layer "F.Cu")
		(net "M_G_CPU0_SB_DQS_DP<5>")
	)
	(arc
		(start 393.67079 -276.737572)
		(mid 393.853041 -276.687222)
		(end 394.03655 -276.732746)
		(width 0.0762)
		(layer "F.Cu")
		(net "M_G_CPU0_SB_DQS_DP<5>")
	)
	(arc
		(start 392.73099 -276.737572)
		(mid 392.917934 -276.687317)
		(end 393.104878 -276.737572)
		(width 0.0762)
		(layer "F.Cu")
		(net "M_G_CPU0_SB_DQS_DP<5>")
	)
	(arc
		(start 393.104878 -276.737572)
		(mid 393.387834 -276.813749)
		(end 393.67079 -276.737572)
		(width 0.0762)
		(layer "F.Cu")
		(net "M_G_CPU0_SB_DQS_DP<5>")
	)
	(arc
		(start 391.97788 -277.060152)
		(mid 392.211878 -276.888109)
		(end 392.49223 -276.812248)
		(width 0.0762)
		(layer "F.Cu")
		(net "M_G_CPU0_SB_DQS_DP<5>")
	)
	(arc
		(start 392.515852 -276.809962)
		(mid 392.627098 -276.784699)
		(end 392.73099 -276.737572)
		(width 0.0762)
		(layer "F.Cu")
		(net "M_G_CPU0_SB_DQS_DP<5>")
	)
	(arc
		(start 392.49223 -276.812248)
		(mid 392.504053 -276.811231)
		(end 392.515852 -276.809962)
		(width 0.0762)
		(layer "F.Cu")
		(net "M_G_CPU0_SB_DQS_DP<5>")
	)
	(segment
		(start 406.591008 -271.715484)
		(end 406.733248 -271.857724)
		(width 0.12954)
		(layer "F.Cu")
		(net "M_G_CPU0_SB_DQS_DP<4>")
	)
	(segment
		(start 406.146254 -271.962118)
		(end 406.392888 -271.715484)
		(width 0.12954)
		(layer "F.Cu")
		(net "M_G_CPU0_SB_DQS_DP<4>")
	)
	(segment
		(start 409.647136 -275.687028)
		(end 409.827222 -275.867114)
		(width 0.12954)
		(layer "F.Cu")
		(net "M_G_CPU0_SB_DQS_DP<4>")
	)
	(segment
		(start 411.810708 -277.235158)
		(end 412.367984 -277.235158)
		(width 0.12954)
		(layer "F.Cu")
		(net "M_G_CPU0_SB_DQS_DP<4>")
	)
	(segment
		(start 406.313386 -272.942558)
		(end 406.642824 -273.271996)
		(width 0.12954)
		(layer "F.Cu")
		(net "M_G_CPU0_SB_DQS_DP<4>")
	)
	(segment
		(start 407.976324 -272.887948)
		(end 407.976324 -273.086068)
		(width 0.12954)
		(layer "F.Cu")
		(net "M_G_CPU0_SB_DQS_DP<4>")
	)
	(segment
		(start 395.23289 -271.953736)
		(end 395.537182 -271.649444)
		(width 0.0762)
		(layer "F.Cu")
		(net "M_G_CPU0_SB_DQS_DP<4>")
	)
	(segment
		(start 406.733248 -272.055844)
		(end 406.313386 -272.475706)
		(width 0.12954)
		(layer "F.Cu")
		(net "M_G_CPU0_SB_DQS_DP<4>")
	)
	(segment
		(start 410.342334 -276.971506)
		(end 411.547056 -276.971506)
		(width 0.12954)
		(layer "F.Cu")
		(net "M_G_CPU0_SB_DQS_DP<4>")
	)
	(segment
		(start 407.441908 -273.620484)
		(end 407.441908 -274.07108)
		(width 0.12954)
		(layer "F.Cu")
		(net "M_G_CPU0_SB_DQS_DP<4>")
	)
	(segment
		(start 406.733248 -271.857724)
		(end 406.733248 -272.055844)
		(width 0.12954)
		(layer "F.Cu")
		(net "M_G_CPU0_SB_DQS_DP<4>")
	)
	(segment
		(start 406.642824 -273.271996)
		(end 407.109676 -273.271996)
		(width 0.12954)
		(layer "F.Cu")
		(net "M_G_CPU0_SB_DQS_DP<4>")
	)
	(segment
		(start 405.432768 -271.715484)
		(end 405.679402 -271.962118)
		(width 0.12954)
		(layer "F.Cu")
		(net "M_G_CPU0_SB_DQS_DP<4>")
	)
	(segment
		(start 395.859254 -271.715484)
		(end 405.432768 -271.715484)
		(width 0.12954)
		(layer "F.Cu")
		(net "M_G_CPU0_SB_DQS_DP<4>")
	)
	(segment
		(start 411.547056 -276.971506)
		(end 411.810708 -277.235158)
		(width 0.12954)
		(layer "F.Cu")
		(net "M_G_CPU0_SB_DQS_DP<4>")
	)
	(segment
		(start 407.635964 -272.745708)
		(end 407.834084 -272.745708)
		(width 0.12954)
		(layer "F.Cu")
		(net "M_G_CPU0_SB_DQS_DP<4>")
	)
	(segment
		(start 405.679402 -271.962118)
		(end 406.146254 -271.962118)
		(width 0.12954)
		(layer "F.Cu")
		(net "M_G_CPU0_SB_DQS_DP<4>")
	)
	(segment
		(start 394.327888 -271.953736)
		(end 395.23289 -271.953736)
		(width 0.0762)
		(layer "F.Cu")
		(net "M_G_CPU0_SB_DQS_DP<4>")
	)
	(segment
		(start 407.976324 -273.086068)
		(end 407.441908 -273.620484)
		(width 0.12954)
		(layer "F.Cu")
		(net "M_G_CPU0_SB_DQS_DP<4>")
	)
	(segment
		(start 407.109676 -273.271996)
		(end 407.635964 -272.745708)
		(width 0.12954)
		(layer "F.Cu")
		(net "M_G_CPU0_SB_DQS_DP<4>")
	)
	(segment
		(start 409.057856 -275.687028)
		(end 409.647136 -275.687028)
		(width 0.12954)
		(layer "F.Cu")
		(net "M_G_CPU0_SB_DQS_DP<4>")
	)
	(segment
		(start 406.313386 -272.475706)
		(end 406.313386 -272.942558)
		(width 0.12954)
		(layer "F.Cu")
		(net "M_G_CPU0_SB_DQS_DP<4>")
	)
	(segment
		(start 408.690572 -274.730464)
		(end 408.690572 -275.319744)
		(width 0.12954)
		(layer "F.Cu")
		(net "M_G_CPU0_SB_DQS_DP<4>")
	)
	(segment
		(start 407.834084 -272.745708)
		(end 407.976324 -272.887948)
		(width 0.12954)
		(layer "F.Cu")
		(net "M_G_CPU0_SB_DQS_DP<4>")
	)
	(segment
		(start 407.921206 -274.550378)
		(end 408.510486 -274.550378)
		(width 0.12954)
		(layer "F.Cu")
		(net "M_G_CPU0_SB_DQS_DP<4>")
	)
	(segment
		(start 395.537182 -271.649444)
		(end 395.774164 -271.649444)
		(width 0.0762)
		(layer "F.Cu")
		(net "M_G_CPU0_SB_DQS_DP<4>")
	)
	(segment
		(start 394.03655 -271.87271)
		(end 394.044932 -271.877536)
		(width 0.0762)
		(layer "F.Cu")
		(net "M_G_CPU0_SB_DQS_DP<4>")
	)
	(segment
		(start 407.441908 -274.07108)
		(end 407.921206 -274.550378)
		(width 0.12954)
		(layer "F.Cu")
		(net "M_G_CPU0_SB_DQS_DP<4>")
	)
	(segment
		(start 409.827222 -275.867114)
		(end 409.827222 -276.456394)
		(width 0.12954)
		(layer "F.Cu")
		(net "M_G_CPU0_SB_DQS_DP<4>")
	)
	(segment
		(start 408.690572 -275.319744)
		(end 409.057856 -275.687028)
		(width 0.12954)
		(layer "F.Cu")
		(net "M_G_CPU0_SB_DQS_DP<4>")
	)
	(segment
		(start 395.840204 -271.715484)
		(end 395.859254 -271.715484)
		(width 0.0762)
		(layer "F.Cu")
		(net "M_G_CPU0_SB_DQS_DP<4>")
	)
	(segment
		(start 409.827222 -276.456394)
		(end 410.342334 -276.971506)
		(width 0.12954)
		(layer "F.Cu")
		(net "M_G_CPU0_SB_DQS_DP<4>")
	)
	(segment
		(start 395.774164 -271.649444)
		(end 395.840204 -271.715484)
		(width 0.0762)
		(layer "F.Cu")
		(net "M_G_CPU0_SB_DQS_DP<4>")
	)
	(segment
		(start 406.392888 -271.715484)
		(end 406.591008 -271.715484)
		(width 0.12954)
		(layer "F.Cu")
		(net "M_G_CPU0_SB_DQS_DP<4>")
	)
	(segment
		(start 408.510486 -274.550378)
		(end 408.690572 -274.730464)
		(width 0.12954)
		(layer "F.Cu")
		(net "M_G_CPU0_SB_DQS_DP<4>")
	)
	(arc
		(start 392.73099 -271.877536)
		(mid 392.917934 -271.827281)
		(end 393.104878 -271.877536)
		(width 0.0762)
		(layer "F.Cu")
		(net "M_G_CPU0_SB_DQS_DP<4>")
	)
	(arc
		(start 392.515852 -271.949926)
		(mid 392.627098 -271.924663)
		(end 392.73099 -271.877536)
		(width 0.0762)
		(layer "F.Cu")
		(net "M_G_CPU0_SB_DQS_DP<4>")
	)
	(arc
		(start 392.49223 -271.952212)
		(mid 392.504053 -271.951195)
		(end 392.515852 -271.949926)
		(width 0.0762)
		(layer "F.Cu")
		(net "M_G_CPU0_SB_DQS_DP<4>")
	)
	(arc
		(start 393.67079 -271.877536)
		(mid 393.853041 -271.827186)
		(end 394.03655 -271.87271)
		(width 0.0762)
		(layer "F.Cu")
		(net "M_G_CPU0_SB_DQS_DP<4>")
	)
	(arc
		(start 394.044932 -271.877536)
		(mid 394.181368 -271.934361)
		(end 394.327888 -271.953736)
		(width 0.0762)
		(layer "F.Cu")
		(net "M_G_CPU0_SB_DQS_DP<4>")
	)
	(arc
		(start 391.97788 -272.200116)
		(mid 392.211878 -272.028073)
		(end 392.49223 -271.952212)
		(width 0.0762)
		(layer "F.Cu")
		(net "M_G_CPU0_SB_DQS_DP<4>")
	)
	(arc
		(start 393.104878 -271.877536)
		(mid 393.387834 -271.953713)
		(end 393.67079 -271.877536)
		(width 0.0762)
		(layer "F.Cu")
		(net "M_G_CPU0_SB_DQS_DP<4>")
	)
	(segment
		(start 410.109924 -311.331102)
		(end 410.57576 -311.331102)
		(width 0.12954)
		(layer "F.Cu")
		(net "M_G_CPU0_SB_DQS_DP<3>")
	)
	(segment
		(start 410.906722 -311.662064)
		(end 410.906722 -312.127646)
		(width 0.12954)
		(layer "F.Cu")
		(net "M_G_CPU0_SB_DQS_DP<3>")
	)
	(segment
		(start 410.63545 -312.398918)
		(end 410.63545 -312.597546)
		(width 0.12954)
		(layer "F.Cu")
		(net "M_G_CPU0_SB_DQS_DP<3>")
	)
	(segment
		(start 394.327634 -290.266374)
		(end 395.280388 -290.266374)
		(width 0.0762)
		(layer "F.Cu")
		(net "M_G_CPU0_SB_DQS_DP<3>")
	)
	(segment
		(start 413.935418 -312.51017)
		(end 414.252156 -312.826908)
		(width 0.101346)
		(layer "F.Cu")
		(net "M_G_CPU0_SB_DQS_DP<3>")
	)
	(segment
		(start 409.4988 -311.262268)
		(end 409.4988 -311.460896)
		(width 0.12954)
		(layer "F.Cu")
		(net "M_G_CPU0_SB_DQS_DP<3>")
	)
	(segment
		(start 395.280388 -290.266374)
		(end 395.465046 -290.451032)
		(width 0.0762)
		(layer "F.Cu")
		(net "M_G_CPU0_SB_DQS_DP<3>")
	)
	(segment
		(start 394.03655 -290.3474)
		(end 394.044932 -290.342574)
		(width 0.0762)
		(layer "F.Cu")
		(net "M_G_CPU0_SB_DQS_DP<3>")
	)
	(segment
		(start 415.637472 -313.252104)
		(end 415.954464 -312.935112)
		(width 0.101346)
		(layer "F.Cu")
		(net "M_G_CPU0_SB_DQS_DP<3>")
	)
	(segment
		(start 411.50667 -312.51017)
		(end 413.935418 -312.51017)
		(width 0.101346)
		(layer "F.Cu")
		(net "M_G_CPU0_SB_DQS_DP<3>")
	)
	(segment
		(start 410.906722 -312.127646)
		(end 410.63545 -312.398918)
		(width 0.12954)
		(layer "F.Cu")
		(net "M_G_CPU0_SB_DQS_DP<3>")
	)
	(segment
		(start 395.465046 -290.451032)
		(end 395.650212 -290.451032)
		(width 0.0762)
		(layer "F.Cu")
		(net "M_G_CPU0_SB_DQS_DP<3>")
	)
	(segment
		(start 410.57576 -311.331102)
		(end 410.906722 -311.662064)
		(width 0.12954)
		(layer "F.Cu")
		(net "M_G_CPU0_SB_DQS_DP<3>")
	)
	(segment
		(start 415.954464 -312.935112)
		(end 416.468052 -312.935112)
		(width 0.101346)
		(layer "F.Cu")
		(net "M_G_CPU0_SB_DQS_DP<3>")
	)
	(segment
		(start 409.838652 -311.60212)
		(end 410.109924 -311.331102)
		(width 0.12954)
		(layer "F.Cu")
		(net "M_G_CPU0_SB_DQS_DP<3>")
	)
	(segment
		(start 410.812488 -312.774584)
		(end 411.242256 -312.774584)
		(width 0.12954)
		(layer "F.Cu")
		(net "M_G_CPU0_SB_DQS_DP<3>")
	)
	(segment
		(start 411.242256 -312.774584)
		(end 411.50667 -312.51017)
		(width 0.12954)
		(layer "F.Cu")
		(net "M_G_CPU0_SB_DQS_DP<3>")
	)
	(segment
		(start 409.640024 -311.60212)
		(end 409.838652 -311.60212)
		(width 0.12954)
		(layer "F.Cu")
		(net "M_G_CPU0_SB_DQS_DP<3>")
	)
	(segment
		(start 409.770072 -310.990996)
		(end 409.4988 -311.262268)
		(width 0.12954)
		(layer "F.Cu")
		(net "M_G_CPU0_SB_DQS_DP<3>")
	)
	(segment
		(start 395.716252 -290.384992)
		(end 395.735302 -290.384992)
		(width 0.0762)
		(layer "F.Cu")
		(net "M_G_CPU0_SB_DQS_DP<3>")
	)
	(segment
		(start 397.803878 -298.55922)
		(end 409.770072 -310.525414)
		(width 0.12954)
		(layer "F.Cu")
		(net "M_G_CPU0_SB_DQS_DP<3>")
	)
	(segment
		(start 410.63545 -312.597546)
		(end 410.812488 -312.774584)
		(width 0.12954)
		(layer "F.Cu")
		(net "M_G_CPU0_SB_DQS_DP<3>")
	)
	(segment
		(start 395.650212 -290.451032)
		(end 395.716252 -290.384992)
		(width 0.0762)
		(layer "F.Cu")
		(net "M_G_CPU0_SB_DQS_DP<3>")
	)
	(segment
		(start 409.4988 -311.460896)
		(end 409.640024 -311.60212)
		(width 0.12954)
		(layer "F.Cu")
		(net "M_G_CPU0_SB_DQS_DP<3>")
	)
	(segment
		(start 393.857988 -290.019994)
		(end 393.755626 -290.19627)
		(width 0.0762)
		(layer "F.Cu")
		(net "M_G_CPU0_SB_DQS_DP<3>")
	)
	(segment
		(start 397.803878 -291.886132)
		(end 397.803878 -298.55922)
		(width 0.12954)
		(layer "F.Cu")
		(net "M_G_CPU0_SB_DQS_DP<3>")
	)
	(segment
		(start 415.072322 -313.252104)
		(end 415.637472 -313.252104)
		(width 0.101346)
		(layer "F.Cu")
		(net "M_G_CPU0_SB_DQS_DP<3>")
	)
	(segment
		(start 409.770072 -310.525414)
		(end 409.770072 -310.990996)
		(width 0.12954)
		(layer "F.Cu")
		(net "M_G_CPU0_SB_DQS_DP<3>")
	)
	(segment
		(start 414.647126 -312.826908)
		(end 415.072322 -313.252104)
		(width 0.101346)
		(layer "F.Cu")
		(net "M_G_CPU0_SB_DQS_DP<3>")
	)
	(segment
		(start 395.735302 -290.384992)
		(end 396.302738 -290.384992)
		(width 0.12954)
		(layer "F.Cu")
		(net "M_G_CPU0_SB_DQS_DP<3>")
	)
	(segment
		(start 396.302738 -290.384992)
		(end 397.803878 -291.886132)
		(width 0.12954)
		(layer "F.Cu")
		(net "M_G_CPU0_SB_DQS_DP<3>")
	)
	(segment
		(start 414.252156 -312.826908)
		(end 414.647126 -312.826908)
		(width 0.101346)
		(layer "F.Cu")
		(net "M_G_CPU0_SB_DQS_DP<3>")
	)
	(arc
		(start 393.922504 -290.387278)
		(mid 393.98115 -290.371985)
		(end 394.03655 -290.3474)
		(width 0.0762)
		(layer "F.Cu")
		(net "M_G_CPU0_SB_DQS_DP<3>")
	)
	(arc
		(start 394.044932 -290.342574)
		(mid 394.158656 -290.292273)
		(end 394.280644 -290.268152)
		(width 0.0762)
		(layer "F.Cu")
		(net "M_G_CPU0_SB_DQS_DP<3>")
	)
	(arc
		(start 394.280644 -290.268152)
		(mid 394.304121 -290.266776)
		(end 394.327634 -290.266374)
		(width 0.0762)
		(layer "F.Cu")
		(net "M_G_CPU0_SB_DQS_DP<3>")
	)
	(arc
		(start 393.755626 -290.19627)
		(mid 393.785255 -290.338757)
		(end 393.922504 -290.387278)
		(width 0.0762)
		(layer "F.Cu")
		(net "M_G_CPU0_SB_DQS_DP<3>")
	)
	(segment
		(start 395.840204 -285.355792)
		(end 395.859254 -285.355792)
		(width 0.0762)
		(layer "F.Cu")
		(net "M_G_CPU0_SB_DQS_DP<2>")
	)
	(segment
		(start 393.857988 -285.160212)
		(end 393.755626 -285.336488)
		(width 0.0762)
		(layer "F.Cu")
		(net "M_G_CPU0_SB_DQS_DP<2>")
	)
	(segment
		(start 408.833066 -301.900336)
		(end 408.833066 -302.099472)
		(width 0.12954)
		(layer "F.Cu")
		(net "M_G_CPU0_SB_DQS_DP<2>")
	)
	(segment
		(start 394.03655 -285.487618)
		(end 394.044932 -285.482792)
		(width 0.0762)
		(layer "F.Cu")
		(net "M_G_CPU0_SB_DQS_DP<2>")
	)
	(segment
		(start 415.046414 -303.90211)
		(end 415.637472 -303.90211)
		(width 0.101346)
		(layer "F.Cu")
		(net "M_G_CPU0_SB_DQS_DP<2>")
	)
	(segment
		(start 402.195792 -294.419782)
		(end 409.027376 -301.251366)
		(width 0.12954)
		(layer "F.Cu")
		(net "M_G_CPU0_SB_DQS_DP<2>")
	)
	(segment
		(start 395.859254 -285.355792)
		(end 397.613378 -285.355792)
		(width 0.12954)
		(layer "F.Cu")
		(net "M_G_CPU0_SB_DQS_DP<2>")
	)
	(segment
		(start 402.195792 -289.938206)
		(end 402.195792 -294.419782)
		(width 0.12954)
		(layer "F.Cu")
		(net "M_G_CPU0_SB_DQS_DP<2>")
	)
	(segment
		(start 409.367228 -302.045878)
		(end 409.833064 -302.045878)
		(width 0.12954)
		(layer "F.Cu")
		(net "M_G_CPU0_SB_DQS_DP<2>")
	)
	(segment
		(start 415.637472 -303.90211)
		(end 415.954464 -303.585118)
		(width 0.101346)
		(layer "F.Cu")
		(net "M_G_CPU0_SB_DQS_DP<2>")
	)
	(segment
		(start 409.027376 -301.251366)
		(end 409.027376 -301.706026)
		(width 0.12954)
		(layer "F.Cu")
		(net "M_G_CPU0_SB_DQS_DP<2>")
	)
	(segment
		(start 413.935418 -303.160176)
		(end 414.252156 -303.476914)
		(width 0.101346)
		(layer "F.Cu")
		(net "M_G_CPU0_SB_DQS_DP<2>")
	)
	(segment
		(start 410.158184 -303.42459)
		(end 411.242256 -303.42459)
		(width 0.12954)
		(layer "F.Cu")
		(net "M_G_CPU0_SB_DQS_DP<2>")
	)
	(segment
		(start 409.969716 -303.036986)
		(end 409.969716 -303.236122)
		(width 0.12954)
		(layer "F.Cu")
		(net "M_G_CPU0_SB_DQS_DP<2>")
	)
	(segment
		(start 395.441678 -285.421832)
		(end 395.774164 -285.421832)
		(width 0.0762)
		(layer "F.Cu")
		(net "M_G_CPU0_SB_DQS_DP<2>")
	)
	(segment
		(start 409.969716 -303.236122)
		(end 410.158184 -303.42459)
		(width 0.12954)
		(layer "F.Cu")
		(net "M_G_CPU0_SB_DQS_DP<2>")
	)
	(segment
		(start 411.242256 -303.42459)
		(end 411.50667 -303.160176)
		(width 0.12954)
		(layer "F.Cu")
		(net "M_G_CPU0_SB_DQS_DP<2>")
	)
	(segment
		(start 395.426438 -285.406592)
		(end 395.441678 -285.421832)
		(width 0.0762)
		(layer "F.Cu")
		(net "M_G_CPU0_SB_DQS_DP<2>")
	)
	(segment
		(start 409.027376 -301.706026)
		(end 408.833066 -301.900336)
		(width 0.12954)
		(layer "F.Cu")
		(net "M_G_CPU0_SB_DQS_DP<2>")
	)
	(segment
		(start 394.327634 -285.406592)
		(end 395.426438 -285.406592)
		(width 0.0762)
		(layer "F.Cu")
		(net "M_G_CPU0_SB_DQS_DP<2>")
	)
	(segment
		(start 408.833066 -302.099472)
		(end 408.973782 -302.240188)
		(width 0.12954)
		(layer "F.Cu")
		(net "M_G_CPU0_SB_DQS_DP<2>")
	)
	(segment
		(start 411.50667 -303.160176)
		(end 413.935418 -303.160176)
		(width 0.101346)
		(layer "F.Cu")
		(net "M_G_CPU0_SB_DQS_DP<2>")
	)
	(segment
		(start 414.252156 -303.476914)
		(end 414.621218 -303.476914)
		(width 0.101346)
		(layer "F.Cu")
		(net "M_G_CPU0_SB_DQS_DP<2>")
	)
	(segment
		(start 415.954464 -303.585118)
		(end 416.468052 -303.585118)
		(width 0.101346)
		(layer "F.Cu")
		(net "M_G_CPU0_SB_DQS_DP<2>")
	)
	(segment
		(start 414.621218 -303.476914)
		(end 415.046414 -303.90211)
		(width 0.101346)
		(layer "F.Cu")
		(net "M_G_CPU0_SB_DQS_DP<2>")
	)
	(segment
		(start 410.164026 -302.37684)
		(end 410.164026 -302.842676)
		(width 0.12954)
		(layer "F.Cu")
		(net "M_G_CPU0_SB_DQS_DP<2>")
	)
	(segment
		(start 410.164026 -302.842676)
		(end 409.969716 -303.036986)
		(width 0.12954)
		(layer "F.Cu")
		(net "M_G_CPU0_SB_DQS_DP<2>")
	)
	(segment
		(start 408.973782 -302.240188)
		(end 409.172918 -302.240188)
		(width 0.12954)
		(layer "F.Cu")
		(net "M_G_CPU0_SB_DQS_DP<2>")
	)
	(segment
		(start 397.613378 -285.355792)
		(end 402.195792 -289.938206)
		(width 0.12954)
		(layer "F.Cu")
		(net "M_G_CPU0_SB_DQS_DP<2>")
	)
	(segment
		(start 409.833064 -302.045878)
		(end 410.164026 -302.37684)
		(width 0.12954)
		(layer "F.Cu")
		(net "M_G_CPU0_SB_DQS_DP<2>")
	)
	(segment
		(start 395.774164 -285.421832)
		(end 395.840204 -285.355792)
		(width 0.0762)
		(layer "F.Cu")
		(net "M_G_CPU0_SB_DQS_DP<2>")
	)
	(segment
		(start 409.172918 -302.240188)
		(end 409.367228 -302.045878)
		(width 0.12954)
		(layer "F.Cu")
		(net "M_G_CPU0_SB_DQS_DP<2>")
	)
	(arc
		(start 394.044932 -285.482792)
		(mid 394.158656 -285.432491)
		(end 394.280644 -285.40837)
		(width 0.0762)
		(layer "F.Cu")
		(net "M_G_CPU0_SB_DQS_DP<2>")
	)
	(arc
		(start 393.922504 -285.527496)
		(mid 393.98115 -285.512203)
		(end 394.03655 -285.487618)
		(width 0.0762)
		(layer "F.Cu")
		(net "M_G_CPU0_SB_DQS_DP<2>")
	)
	(arc
		(start 394.280644 -285.40837)
		(mid 394.304121 -285.406994)
		(end 394.327634 -285.406592)
		(width 0.0762)
		(layer "F.Cu")
		(net "M_G_CPU0_SB_DQS_DP<2>")
	)
	(arc
		(start 393.755626 -285.336488)
		(mid 393.785255 -285.478975)
		(end 393.922504 -285.527496)
		(width 0.0762)
		(layer "F.Cu")
		(net "M_G_CPU0_SB_DQS_DP<2>")
	)
	(segment
		(start 395.191742 -280.546556)
		(end 395.449044 -280.289254)
		(width 0.0762)
		(layer "F.Cu")
		(net "M_G_CPU0_SB_DQS_DP<1>")
	)
	(segment
		(start 415.637472 -294.552116)
		(end 415.954464 -294.235124)
		(width 0.101346)
		(layer "F.Cu")
		(net "M_G_CPU0_SB_DQS_DP<1>")
	)
	(segment
		(start 398.82064 -280.223214)
		(end 408.6225 -290.025074)
		(width 0.12954)
		(layer "F.Cu")
		(net "M_G_CPU0_SB_DQS_DP<1>")
	)
	(segment
		(start 408.6225 -290.025074)
		(end 408.6225 -290.53663)
		(width 0.12954)
		(layer "F.Cu")
		(net "M_G_CPU0_SB_DQS_DP<1>")
	)
	(segment
		(start 408.39644 -291.442394)
		(end 408.962352 -290.876482)
		(width 0.12954)
		(layer "F.Cu")
		(net "M_G_CPU0_SB_DQS_DP<1>")
	)
	(segment
		(start 409.75915 -291.207444)
		(end 409.75915 -291.67328)
		(width 0.12954)
		(layer "F.Cu")
		(net "M_G_CPU0_SB_DQS_DP<1>")
	)
	(segment
		(start 408.056588 -291.102542)
		(end 408.056588 -291.301678)
		(width 0.12954)
		(layer "F.Cu")
		(net "M_G_CPU0_SB_DQS_DP<1>")
	)
	(segment
		(start 408.197304 -291.442394)
		(end 408.39644 -291.442394)
		(width 0.12954)
		(layer "F.Cu")
		(net "M_G_CPU0_SB_DQS_DP<1>")
	)
	(segment
		(start 411.242256 -294.074596)
		(end 411.50667 -293.810182)
		(width 0.12954)
		(layer "F.Cu")
		(net "M_G_CPU0_SB_DQS_DP<1>")
	)
	(segment
		(start 395.774164 -280.289254)
		(end 395.840204 -280.223214)
		(width 0.0762)
		(layer "F.Cu")
		(net "M_G_CPU0_SB_DQS_DP<1>")
	)
	(segment
		(start 395.840204 -280.223214)
		(end 395.859254 -280.223214)
		(width 0.0762)
		(layer "F.Cu")
		(net "M_G_CPU0_SB_DQS_DP<1>")
	)
	(segment
		(start 415.064194 -294.552116)
		(end 415.637472 -294.552116)
		(width 0.101346)
		(layer "F.Cu")
		(net "M_G_CPU0_SB_DQS_DP<1>")
	)
	(segment
		(start 414.252156 -294.12692)
		(end 414.638998 -294.12692)
		(width 0.101346)
		(layer "F.Cu")
		(net "M_G_CPU0_SB_DQS_DP<1>")
	)
	(segment
		(start 394.03655 -280.627582)
		(end 394.044932 -280.622756)
		(width 0.0762)
		(layer "F.Cu")
		(net "M_G_CPU0_SB_DQS_DP<1>")
	)
	(segment
		(start 408.6225 -290.53663)
		(end 408.056588 -291.102542)
		(width 0.12954)
		(layer "F.Cu")
		(net "M_G_CPU0_SB_DQS_DP<1>")
	)
	(segment
		(start 411.50667 -293.810182)
		(end 413.935418 -293.810182)
		(width 0.101346)
		(layer "F.Cu")
		(net "M_G_CPU0_SB_DQS_DP<1>")
	)
	(segment
		(start 409.75915 -291.67328)
		(end 409.193238 -292.239192)
		(width 0.12954)
		(layer "F.Cu")
		(net "M_G_CPU0_SB_DQS_DP<1>")
	)
	(segment
		(start 395.449044 -280.289254)
		(end 395.774164 -280.289254)
		(width 0.0762)
		(layer "F.Cu")
		(net "M_G_CPU0_SB_DQS_DP<1>")
	)
	(segment
		(start 410.829506 -294.074596)
		(end 411.242256 -294.074596)
		(width 0.12954)
		(layer "F.Cu")
		(net "M_G_CPU0_SB_DQS_DP<1>")
	)
	(segment
		(start 409.428188 -290.876482)
		(end 409.75915 -291.207444)
		(width 0.12954)
		(layer "F.Cu")
		(net "M_G_CPU0_SB_DQS_DP<1>")
	)
	(segment
		(start 395.859254 -280.223214)
		(end 398.82064 -280.223214)
		(width 0.12954)
		(layer "F.Cu")
		(net "M_G_CPU0_SB_DQS_DP<1>")
	)
	(segment
		(start 409.193238 -292.239192)
		(end 409.193238 -292.438328)
		(width 0.12954)
		(layer "F.Cu")
		(net "M_G_CPU0_SB_DQS_DP<1>")
	)
	(segment
		(start 409.193238 -292.438328)
		(end 410.829506 -294.074596)
		(width 0.12954)
		(layer "F.Cu")
		(net "M_G_CPU0_SB_DQS_DP<1>")
	)
	(segment
		(start 408.962352 -290.876482)
		(end 409.428188 -290.876482)
		(width 0.12954)
		(layer "F.Cu")
		(net "M_G_CPU0_SB_DQS_DP<1>")
	)
	(segment
		(start 414.638998 -294.12692)
		(end 415.064194 -294.552116)
		(width 0.101346)
		(layer "F.Cu")
		(net "M_G_CPU0_SB_DQS_DP<1>")
	)
	(segment
		(start 393.857988 -280.300176)
		(end 393.755626 -280.476452)
		(width 0.0762)
		(layer "F.Cu")
		(net "M_G_CPU0_SB_DQS_DP<1>")
	)
	(segment
		(start 413.935418 -293.810182)
		(end 414.252156 -294.12692)
		(width 0.101346)
		(layer "F.Cu")
		(net "M_G_CPU0_SB_DQS_DP<1>")
	)
	(segment
		(start 415.954464 -294.235124)
		(end 416.468052 -294.235124)
		(width 0.101346)
		(layer "F.Cu")
		(net "M_G_CPU0_SB_DQS_DP<1>")
	)
	(segment
		(start 394.327634 -280.546556)
		(end 395.191742 -280.546556)
		(width 0.0762)
		(layer "F.Cu")
		(net "M_G_CPU0_SB_DQS_DP<1>")
	)
	(segment
		(start 408.056588 -291.301678)
		(end 408.197304 -291.442394)
		(width 0.12954)
		(layer "F.Cu")
		(net "M_G_CPU0_SB_DQS_DP<1>")
	)
	(arc
		(start 393.755626 -280.476452)
		(mid 393.785255 -280.618939)
		(end 393.922504 -280.66746)
		(width 0.0762)
		(layer "F.Cu")
		(net "M_G_CPU0_SB_DQS_DP<1>")
	)
	(arc
		(start 393.922504 -280.66746)
		(mid 393.98115 -280.652167)
		(end 394.03655 -280.627582)
		(width 0.0762)
		(layer "F.Cu")
		(net "M_G_CPU0_SB_DQS_DP<1>")
	)
	(arc
		(start 394.280644 -280.548334)
		(mid 394.304121 -280.546958)
		(end 394.327634 -280.546556)
		(width 0.0762)
		(layer "F.Cu")
		(net "M_G_CPU0_SB_DQS_DP<1>")
	)
	(arc
		(start 394.044932 -280.622756)
		(mid 394.158656 -280.572455)
		(end 394.280644 -280.548334)
		(width 0.0762)
		(layer "F.Cu")
		(net "M_G_CPU0_SB_DQS_DP<1>")
	)
	(segment
		(start 409.32354 -283.108654)
		(end 409.32354 -283.307028)
		(width 0.12954)
		(layer "F.Cu")
		(net "M_G_CPU0_SB_DQS_DP<0>")
	)
	(segment
		(start 413.935418 -284.460188)
		(end 414.252156 -284.776926)
		(width 0.101346)
		(layer "F.Cu")
		(net "M_G_CPU0_SB_DQS_DP<0>")
	)
	(segment
		(start 415.031174 -285.202122)
		(end 415.637472 -285.202122)
		(width 0.101346)
		(layer "F.Cu")
		(net "M_G_CPU0_SB_DQS_DP<0>")
	)
	(segment
		(start 414.605978 -284.776926)
		(end 415.031174 -285.202122)
		(width 0.101346)
		(layer "F.Cu")
		(net "M_G_CPU0_SB_DQS_DP<0>")
	)
	(segment
		(start 409.46578 -283.449268)
		(end 409.663646 -283.449014)
		(width 0.12954)
		(layer "F.Cu")
		(net "M_G_CPU0_SB_DQS_DP<0>")
	)
	(segment
		(start 410.877258 -283.704284)
		(end 410.877258 -284.595062)
		(width 0.12954)
		(layer "F.Cu")
		(net "M_G_CPU0_SB_DQS_DP<0>")
	)
	(segment
		(start 415.954464 -284.88513)
		(end 416.468052 -284.88513)
		(width 0.101346)
		(layer "F.Cu")
		(net "M_G_CPU0_SB_DQS_DP<0>")
	)
	(segment
		(start 414.252156 -284.776926)
		(end 414.605978 -284.776926)
		(width 0.101346)
		(layer "F.Cu")
		(net "M_G_CPU0_SB_DQS_DP<0>")
	)
	(segment
		(start 409.909772 -283.203142)
		(end 410.376116 -283.203142)
		(width 0.12954)
		(layer "F.Cu")
		(net "M_G_CPU0_SB_DQS_DP<0>")
	)
	(segment
		(start 395.859254 -275.660612)
		(end 402.833586 -275.660612)
		(width 0.12954)
		(layer "F.Cu")
		(net "M_G_CPU0_SB_DQS_DP<0>")
	)
	(segment
		(start 410.877258 -284.595062)
		(end 411.006798 -284.724602)
		(width 0.12954)
		(layer "F.Cu")
		(net "M_G_CPU0_SB_DQS_DP<0>")
	)
	(segment
		(start 409.32354 -283.307028)
		(end 409.46578 -283.449268)
		(width 0.12954)
		(layer "F.Cu")
		(net "M_G_CPU0_SB_DQS_DP<0>")
	)
	(segment
		(start 409.569412 -282.862528)
		(end 409.32354 -283.108654)
		(width 0.12954)
		(layer "F.Cu")
		(net "M_G_CPU0_SB_DQS_DP<0>")
	)
	(segment
		(start 411.50667 -284.460188)
		(end 413.935418 -284.460188)
		(width 0.101346)
		(layer "F.Cu")
		(net "M_G_CPU0_SB_DQS_DP<0>")
	)
	(segment
		(start 410.376116 -283.203142)
		(end 410.877258 -283.704284)
		(width 0.12954)
		(layer "F.Cu")
		(net "M_G_CPU0_SB_DQS_DP<0>")
	)
	(segment
		(start 402.833586 -275.660612)
		(end 409.569412 -282.396438)
		(width 0.12954)
		(layer "F.Cu")
		(net "M_G_CPU0_SB_DQS_DP<0>")
	)
	(segment
		(start 415.637472 -285.202122)
		(end 415.954464 -284.88513)
		(width 0.101346)
		(layer "F.Cu")
		(net "M_G_CPU0_SB_DQS_DP<0>")
	)
	(segment
		(start 411.006798 -284.724602)
		(end 411.242256 -284.724602)
		(width 0.12954)
		(layer "F.Cu")
		(net "M_G_CPU0_SB_DQS_DP<0>")
	)
	(segment
		(start 393.857988 -275.44014)
		(end 393.755626 -275.616416)
		(width 0.0762)
		(layer "F.Cu")
		(net "M_G_CPU0_SB_DQS_DP<0>")
	)
	(segment
		(start 394.327634 -275.68652)
		(end 395.32179 -275.68652)
		(width 0.0762)
		(layer "F.Cu")
		(net "M_G_CPU0_SB_DQS_DP<0>")
	)
	(segment
		(start 411.242256 -284.724602)
		(end 411.50667 -284.460188)
		(width 0.12954)
		(layer "F.Cu")
		(net "M_G_CPU0_SB_DQS_DP<0>")
	)
	(segment
		(start 409.663646 -283.449014)
		(end 409.909772 -283.203142)
		(width 0.12954)
		(layer "F.Cu")
		(net "M_G_CPU0_SB_DQS_DP<0>")
	)
	(segment
		(start 395.774164 -275.726652)
		(end 395.840204 -275.660612)
		(width 0.0762)
		(layer "F.Cu")
		(net "M_G_CPU0_SB_DQS_DP<0>")
	)
	(segment
		(start 395.361922 -275.726652)
		(end 395.774164 -275.726652)
		(width 0.0762)
		(layer "F.Cu")
		(net "M_G_CPU0_SB_DQS_DP<0>")
	)
	(segment
		(start 395.32179 -275.68652)
		(end 395.361922 -275.726652)
		(width 0.0762)
		(layer "F.Cu")
		(net "M_G_CPU0_SB_DQS_DP<0>")
	)
	(segment
		(start 394.03655 -275.767546)
		(end 394.044932 -275.76272)
		(width 0.0762)
		(layer "F.Cu")
		(net "M_G_CPU0_SB_DQS_DP<0>")
	)
	(segment
		(start 409.569412 -282.396438)
		(end 409.569412 -282.862528)
		(width 0.12954)
		(layer "F.Cu")
		(net "M_G_CPU0_SB_DQS_DP<0>")
	)
	(segment
		(start 395.840204 -275.660612)
		(end 395.859254 -275.660612)
		(width 0.0762)
		(layer "F.Cu")
		(net "M_G_CPU0_SB_DQS_DP<0>")
	)
	(arc
		(start 393.922504 -275.807424)
		(mid 393.98115 -275.792131)
		(end 394.03655 -275.767546)
		(width 0.0762)
		(layer "F.Cu")
		(net "M_G_CPU0_SB_DQS_DP<0>")
	)
	(arc
		(start 394.280644 -275.688298)
		(mid 394.304121 -275.686922)
		(end 394.327634 -275.68652)
		(width 0.0762)
		(layer "F.Cu")
		(net "M_G_CPU0_SB_DQS_DP<0>")
	)
	(arc
		(start 393.755626 -275.616416)
		(mid 393.785255 -275.758903)
		(end 393.922504 -275.807424)
		(width 0.0762)
		(layer "F.Cu")
		(net "M_G_CPU0_SB_DQS_DP<0>")
	)
	(arc
		(start 394.044932 -275.76272)
		(mid 394.158656 -275.712419)
		(end 394.280644 -275.688298)
		(width 0.0762)
		(layer "F.Cu")
		(net "M_G_CPU0_SB_DQS_DP<0>")
	)
	(segment
		(start 395.48943 -270.971264)
		(end 395.50848 -270.971264)
		(width 0.0762)
		(layer "F.Cu")
		(net "M_G_CPU0_SB_DQS_DN<9>")
	)
	(segment
		(start 395.01064 -270.905224)
		(end 395.42339 -270.905224)
		(width 0.0762)
		(layer "F.Cu")
		(net "M_G_CPU0_SB_DQS_DN<9>")
	)
	(segment
		(start 410.754068 -275.697188)
		(end 411.24378 -275.697188)
		(width 0.12954)
		(layer "F.Cu")
		(net "M_G_CPU0_SB_DQS_DN<9>")
	)
	(segment
		(start 408.720544 -273.663664)
		(end 410.754068 -275.697188)
		(width 0.12954)
		(layer "F.Cu")
		(net "M_G_CPU0_SB_DQS_DN<9>")
	)
	(segment
		(start 394.327888 -271.016984)
		(end 394.89888 -271.016984)
		(width 0.0762)
		(layer "F.Cu")
		(net "M_G_CPU0_SB_DQS_DN<9>")
	)
	(segment
		(start 415.637218 -276.067774)
		(end 415.954464 -276.38502)
		(width 0.101346)
		(layer "F.Cu")
		(net "M_G_CPU0_SB_DQS_DN<9>")
	)
	(segment
		(start 414.549082 -275.642578)
		(end 414.974278 -276.067774)
		(width 0.101346)
		(layer "F.Cu")
		(net "M_G_CPU0_SB_DQS_DN<9>")
	)
	(segment
		(start 395.50848 -270.971264)
		(end 407.478992 -270.971264)
		(width 0.12954)
		(layer "F.Cu")
		(net "M_G_CPU0_SB_DQS_DN<9>")
	)
	(segment
		(start 414.974278 -276.067774)
		(end 415.637218 -276.067774)
		(width 0.101346)
		(layer "F.Cu")
		(net "M_G_CPU0_SB_DQS_DN<9>")
	)
	(segment
		(start 395.42339 -270.905224)
		(end 395.48943 -270.971264)
		(width 0.0762)
		(layer "F.Cu")
		(net "M_G_CPU0_SB_DQS_DN<9>")
	)
	(segment
		(start 415.954464 -276.38502)
		(end 416.468052 -276.38502)
		(width 0.101346)
		(layer "F.Cu")
		(net "M_G_CPU0_SB_DQS_DN<9>")
	)
	(segment
		(start 411.24378 -275.697188)
		(end 411.50667 -275.960078)
		(width 0.12954)
		(layer "F.Cu")
		(net "M_G_CPU0_SB_DQS_DN<9>")
	)
	(segment
		(start 394.89888 -271.016984)
		(end 395.01064 -270.905224)
		(width 0.0762)
		(layer "F.Cu")
		(net "M_G_CPU0_SB_DQS_DN<9>")
	)
	(segment
		(start 407.478992 -270.971264)
		(end 408.720544 -272.212816)
		(width 0.12954)
		(layer "F.Cu")
		(net "M_G_CPU0_SB_DQS_DN<9>")
	)
	(segment
		(start 414.25241 -275.642578)
		(end 414.549082 -275.642578)
		(width 0.101346)
		(layer "F.Cu")
		(net "M_G_CPU0_SB_DQS_DN<9>")
	)
	(segment
		(start 408.720544 -272.212816)
		(end 408.720544 -273.663664)
		(width 0.12954)
		(layer "F.Cu")
		(net "M_G_CPU0_SB_DQS_DN<9>")
	)
	(segment
		(start 413.93491 -275.960078)
		(end 414.25241 -275.642578)
		(width 0.101346)
		(layer "F.Cu")
		(net "M_G_CPU0_SB_DQS_DN<9>")
	)
	(segment
		(start 411.50667 -275.960078)
		(end 413.93491 -275.960078)
		(width 0.101346)
		(layer "F.Cu")
		(net "M_G_CPU0_SB_DQS_DN<9>")
	)
	(arc
		(start 393.916916 -271.140682)
		(mid 393.936265 -271.138344)
		(end 393.955524 -271.135348)
		(width 0.0762)
		(layer "F.Cu")
		(net "M_G_CPU0_SB_DQS_DN<9>")
	)
	(arc
		(start 394.140944 -271.06753)
		(mid 394.216184 -271.034217)
		(end 394.2969 -271.018254)
		(width 0.0762)
		(layer "F.Cu")
		(net "M_G_CPU0_SB_DQS_DN<9>")
	)
	(arc
		(start 393.387834 -271.39011)
		(mid 393.631265 -271.220623)
		(end 393.916916 -271.140682)
		(width 0.0762)
		(layer "F.Cu")
		(net "M_G_CPU0_SB_DQS_DN<9>")
	)
	(arc
		(start 393.955524 -271.135348)
		(mid 394.051233 -271.109636)
		(end 394.140944 -271.06753)
		(width 0.0762)
		(layer "F.Cu")
		(net "M_G_CPU0_SB_DQS_DN<9>")
	)
	(arc
		(start 394.2969 -271.018254)
		(mid 394.312381 -271.017298)
		(end 394.327888 -271.016984)
		(width 0.0762)
		(layer "F.Cu")
		(net "M_G_CPU0_SB_DQS_DN<9>")
	)
	(segment
		(start 406.193752 -309.208932)
		(end 406.334976 -309.350156)
		(width 0.12954)
		(layer "F.Cu")
		(net "M_G_CPU0_SB_DQS_DN<8>")
	)
	(segment
		(start 408.728926 -311.02173)
		(end 408.467052 -311.283604)
		(width 0.12954)
		(layer "F.Cu")
		(net "M_G_CPU0_SB_DQS_DN<8>")
	)
	(segment
		(start 392.626596 -291.157406)
		(end 392.634978 -291.15258)
		(width 0.0762)
		(layer "F.Cu")
		(net "M_G_CPU0_SB_DQS_DN<8>")
	)
	(segment
		(start 407.932128 -310.225186)
		(end 408.397964 -310.225186)
		(width 0.12954)
		(layer "F.Cu")
		(net "M_G_CPU0_SB_DQS_DN<8>")
	)
	(segment
		(start 407.471626 -310.486806)
		(end 407.670254 -310.486806)
		(width 0.12954)
		(layer "F.Cu")
		(net "M_G_CPU0_SB_DQS_DN<8>")
	)
	(segment
		(start 406.334976 -309.350156)
		(end 406.533604 -309.350156)
		(width 0.12954)
		(layer "F.Cu")
		(net "M_G_CPU0_SB_DQS_DN<8>")
	)
	(segment
		(start 406.795478 -309.088536)
		(end 407.261314 -309.088536)
		(width 0.12954)
		(layer "F.Cu")
		(net "M_G_CPU0_SB_DQS_DN<8>")
	)
	(segment
		(start 405.057102 -307.873654)
		(end 405.057102 -308.072282)
		(width 0.12954)
		(layer "F.Cu")
		(net "M_G_CPU0_SB_DQS_DN<8>")
	)
	(segment
		(start 406.45588 -308.283102)
		(end 406.455626 -308.74843)
		(width 0.12954)
		(layer "F.Cu")
		(net "M_G_CPU0_SB_DQS_DN<8>")
	)
	(segment
		(start 405.198326 -308.213506)
		(end 405.396954 -308.213506)
		(width 0.12954)
		(layer "F.Cu")
		(net "M_G_CPU0_SB_DQS_DN<8>")
	)
	(segment
		(start 408.467052 -311.482232)
		(end 411.033722 -314.048902)
		(width 0.12954)
		(layer "F.Cu")
		(net "M_G_CPU0_SB_DQS_DN<8>")
	)
	(segment
		(start 396.000478 -291.137086)
		(end 397.052038 -292.188646)
		(width 0.12954)
		(layer "F.Cu")
		(net "M_G_CPU0_SB_DQS_DN<8>")
	)
	(segment
		(start 407.59253 -309.419752)
		(end 407.592276 -309.88508)
		(width 0.12954)
		(layer "F.Cu")
		(net "M_G_CPU0_SB_DQS_DN<8>")
	)
	(segment
		(start 408.72918 -310.556402)
		(end 408.728926 -311.02173)
		(width 0.12954)
		(layer "F.Cu")
		(net "M_G_CPU0_SB_DQS_DN<8>")
	)
	(segment
		(start 405.658828 -307.951886)
		(end 406.124664 -307.951886)
		(width 0.12954)
		(layer "F.Cu")
		(net "M_G_CPU0_SB_DQS_DN<8>")
	)
	(segment
		(start 397.052038 -292.188646)
		(end 397.052038 -298.87926)
		(width 0.12954)
		(layer "F.Cu")
		(net "M_G_CPU0_SB_DQS_DN<8>")
	)
	(segment
		(start 405.057102 -308.072282)
		(end 405.198326 -308.213506)
		(width 0.12954)
		(layer "F.Cu")
		(net "M_G_CPU0_SB_DQS_DN<8>")
	)
	(segment
		(start 407.330402 -310.345582)
		(end 407.471626 -310.486806)
		(width 0.12954)
		(layer "F.Cu")
		(net "M_G_CPU0_SB_DQS_DN<8>")
	)
	(segment
		(start 408.397964 -310.225186)
		(end 408.72918 -310.556402)
		(width 0.12954)
		(layer "F.Cu")
		(net "M_G_CPU0_SB_DQS_DN<8>")
	)
	(segment
		(start 395.684248 -291.137086)
		(end 396.000478 -291.137086)
		(width 0.12954)
		(layer "F.Cu")
		(net "M_G_CPU0_SB_DQS_DN<8>")
	)
	(segment
		(start 395.599158 -291.203126)
		(end 395.665198 -291.137086)
		(width 0.0762)
		(layer "F.Cu")
		(net "M_G_CPU0_SB_DQS_DN<8>")
	)
	(segment
		(start 411.809946 -313.784996)
		(end 412.367984 -313.784996)
		(width 0.12954)
		(layer "F.Cu")
		(net "M_G_CPU0_SB_DQS_DN<8>")
	)
	(segment
		(start 393.20089 -291.15258)
		(end 393.209272 -291.157406)
		(width 0.0762)
		(layer "F.Cu")
		(net "M_G_CPU0_SB_DQS_DN<8>")
	)
	(segment
		(start 411.033722 -314.048902)
		(end 411.54604 -314.048902)
		(width 0.12954)
		(layer "F.Cu")
		(net "M_G_CPU0_SB_DQS_DN<8>")
	)
	(segment
		(start 405.326088 -307.15331)
		(end 405.326088 -307.604668)
		(width 0.12954)
		(layer "F.Cu")
		(net "M_G_CPU0_SB_DQS_DN<8>")
	)
	(segment
		(start 405.396954 -308.213506)
		(end 405.658828 -307.951886)
		(width 0.12954)
		(layer "F.Cu")
		(net "M_G_CPU0_SB_DQS_DN<8>")
	)
	(segment
		(start 408.467052 -311.283604)
		(end 408.467052 -311.482232)
		(width 0.12954)
		(layer "F.Cu")
		(net "M_G_CPU0_SB_DQS_DN<8>")
	)
	(segment
		(start 395.665198 -291.137086)
		(end 395.684248 -291.137086)
		(width 0.0762)
		(layer "F.Cu")
		(net "M_G_CPU0_SB_DQS_DN<8>")
	)
	(segment
		(start 405.326088 -307.604668)
		(end 405.057102 -307.873654)
		(width 0.12954)
		(layer "F.Cu")
		(net "M_G_CPU0_SB_DQS_DN<8>")
	)
	(segment
		(start 392.448034 -290.83)
		(end 392.34618 -291.00526)
		(width 0.0762)
		(layer "F.Cu")
		(net "M_G_CPU0_SB_DQS_DN<8>")
	)
	(segment
		(start 394.327888 -291.202618)
		(end 394.328396 -291.203126)
		(width 0.0762)
		(layer "F.Cu")
		(net "M_G_CPU0_SB_DQS_DN<8>")
	)
	(segment
		(start 407.261314 -309.088536)
		(end 407.59253 -309.419752)
		(width 0.12954)
		(layer "F.Cu")
		(net "M_G_CPU0_SB_DQS_DN<8>")
	)
	(segment
		(start 406.533604 -309.350156)
		(end 406.795478 -309.088536)
		(width 0.12954)
		(layer "F.Cu")
		(net "M_G_CPU0_SB_DQS_DN<8>")
	)
	(segment
		(start 406.124664 -307.951886)
		(end 406.45588 -308.283102)
		(width 0.12954)
		(layer "F.Cu")
		(net "M_G_CPU0_SB_DQS_DN<8>")
	)
	(segment
		(start 411.54604 -314.048902)
		(end 411.809946 -313.784996)
		(width 0.12954)
		(layer "F.Cu")
		(net "M_G_CPU0_SB_DQS_DN<8>")
	)
	(segment
		(start 406.455626 -308.74843)
		(end 406.193752 -309.010304)
		(width 0.12954)
		(layer "F.Cu")
		(net "M_G_CPU0_SB_DQS_DN<8>")
	)
	(segment
		(start 397.052038 -298.87926)
		(end 405.326088 -307.15331)
		(width 0.12954)
		(layer "F.Cu")
		(net "M_G_CPU0_SB_DQS_DN<8>")
	)
	(segment
		(start 407.772108 -310.384952)
		(end 407.932128 -310.225186)
		(width 0.12954)
		(layer "F.Cu")
		(net "M_G_CPU0_SB_DQS_DN<8>")
	)
	(segment
		(start 407.670254 -310.486806)
		(end 407.772108 -310.384952)
		(width 0.12954)
		(layer "F.Cu")
		(net "M_G_CPU0_SB_DQS_DN<8>")
	)
	(segment
		(start 406.193752 -309.010304)
		(end 406.193752 -309.208932)
		(width 0.12954)
		(layer "F.Cu")
		(net "M_G_CPU0_SB_DQS_DN<8>")
	)
	(segment
		(start 394.328396 -291.203126)
		(end 395.599158 -291.203126)
		(width 0.0762)
		(layer "F.Cu")
		(net "M_G_CPU0_SB_DQS_DN<8>")
	)
	(segment
		(start 407.592276 -309.88508)
		(end 407.330402 -310.146954)
		(width 0.12954)
		(layer "F.Cu")
		(net "M_G_CPU0_SB_DQS_DN<8>")
	)
	(segment
		(start 407.330402 -310.146954)
		(end 407.330402 -310.345582)
		(width 0.12954)
		(layer "F.Cu")
		(net "M_G_CPU0_SB_DQS_DN<8>")
	)
	(arc
		(start 393.209272 -291.157406)
		(mid 393.39278 -291.2029)
		(end 393.575032 -291.15258)
		(width 0.0762)
		(layer "F.Cu")
		(net "M_G_CPU0_SB_DQS_DN<8>")
	)
	(arc
		(start 393.575032 -291.15258)
		(mid 393.857988 -291.076403)
		(end 394.140944 -291.15258)
		(width 0.0762)
		(layer "F.Cu")
		(net "M_G_CPU0_SB_DQS_DN<8>")
	)
	(arc
		(start 392.492738 -291.200078)
		(mid 392.561685 -291.185081)
		(end 392.626596 -291.157406)
		(width 0.0762)
		(layer "F.Cu")
		(net "M_G_CPU0_SB_DQS_DN<8>")
	)
	(arc
		(start 392.634978 -291.15258)
		(mid 392.917934 -291.076403)
		(end 393.20089 -291.15258)
		(width 0.0762)
		(layer "F.Cu")
		(net "M_G_CPU0_SB_DQS_DN<8>")
	)
	(arc
		(start 392.34618 -291.00526)
		(mid 392.363374 -291.144846)
		(end 392.492738 -291.200078)
		(width 0.0762)
		(layer "F.Cu")
		(net "M_G_CPU0_SB_DQS_DN<8>")
	)
	(arc
		(start 394.140944 -291.15258)
		(mid 394.231113 -291.189929)
		(end 394.327888 -291.202618)
		(width 0.0762)
		(layer "F.Cu")
		(net "M_G_CPU0_SB_DQS_DN<8>")
	)
	(segment
		(start 402.369528 -296.489628)
		(end 402.522436 -296.33672)
		(width 0.12954)
		(layer "F.Cu")
		(net "M_G_CPU0_SB_DQS_DN<7>")
	)
	(segment
		(start 404.795736 -298.61002)
		(end 405.261572 -298.610274)
		(width 0.12954)
		(layer "F.Cu")
		(net "M_G_CPU0_SB_DQS_DN<7>")
	)
	(segment
		(start 406.729438 -300.07814)
		(end 406.729184 -300.543468)
		(width 0.12954)
		(layer "F.Cu")
		(net "M_G_CPU0_SB_DQS_DN<7>")
	)
	(segment
		(start 395.212062 -286.343344)
		(end 395.382496 -286.17291)
		(width 0.0762)
		(layer "F.Cu")
		(net "M_G_CPU0_SB_DQS_DN<7>")
	)
	(segment
		(start 406.398222 -299.746924)
		(end 406.729438 -300.07814)
		(width 0.12954)
		(layer "F.Cu")
		(net "M_G_CPU0_SB_DQS_DN<7>")
	)
	(segment
		(start 404.455884 -298.270168)
		(end 404.302722 -298.42333)
		(width 0.12954)
		(layer "F.Cu")
		(net "M_G_CPU0_SB_DQS_DN<7>")
	)
	(segment
		(start 402.988272 -296.336974)
		(end 403.319488 -296.66819)
		(width 0.12954)
		(layer "F.Cu")
		(net "M_G_CPU0_SB_DQS_DN<7>")
	)
	(segment
		(start 392.626596 -286.297624)
		(end 392.634978 -286.292798)
		(width 0.0762)
		(layer "F.Cu")
		(net "M_G_CPU0_SB_DQS_DN<7>")
	)
	(segment
		(start 405.439372 -299.758608)
		(end 405.580342 -299.899578)
		(width 0.12954)
		(layer "F.Cu")
		(net "M_G_CPU0_SB_DQS_DN<7>")
	)
	(segment
		(start 407.712672 -301.83328)
		(end 407.712672 -302.031908)
		(width 0.12954)
		(layer "F.Cu")
		(net "M_G_CPU0_SB_DQS_DN<7>")
	)
	(segment
		(start 404.443692 -298.762928)
		(end 404.642828 -298.762928)
		(width 0.12954)
		(layer "F.Cu")
		(net "M_G_CPU0_SB_DQS_DN<7>")
	)
	(segment
		(start 406.576022 -300.69663)
		(end 406.576022 -300.895258)
		(width 0.12954)
		(layer "F.Cu")
		(net "M_G_CPU0_SB_DQS_DN<7>")
	)
	(segment
		(start 411.54604 -304.698908)
		(end 411.809946 -304.435002)
		(width 0.12954)
		(layer "F.Cu")
		(net "M_G_CPU0_SB_DQS_DN<7>")
	)
	(segment
		(start 407.865834 -301.680118)
		(end 407.712672 -301.83328)
		(width 0.12954)
		(layer "F.Cu")
		(net "M_G_CPU0_SB_DQS_DN<7>")
	)
	(segment
		(start 403.166072 -297.485308)
		(end 403.307042 -297.626278)
		(width 0.12954)
		(layer "F.Cu")
		(net "M_G_CPU0_SB_DQS_DN<7>")
	)
	(segment
		(start 395.382496 -286.17291)
		(end 395.774164 -286.17291)
		(width 0.0762)
		(layer "F.Cu")
		(net "M_G_CPU0_SB_DQS_DN<7>")
	)
	(segment
		(start 407.069036 -300.88332)
		(end 407.534872 -300.883574)
		(width 0.12954)
		(layer "F.Cu")
		(net "M_G_CPU0_SB_DQS_DN<7>")
	)
	(segment
		(start 406.916128 -301.036228)
		(end 407.069036 -300.88332)
		(width 0.12954)
		(layer "F.Cu")
		(net "M_G_CPU0_SB_DQS_DN<7>")
	)
	(segment
		(start 405.592534 -299.406818)
		(end 405.439372 -299.55998)
		(width 0.12954)
		(layer "F.Cu")
		(net "M_G_CPU0_SB_DQS_DN<7>")
	)
	(segment
		(start 404.124922 -297.473624)
		(end 404.456138 -297.80484)
		(width 0.12954)
		(layer "F.Cu")
		(net "M_G_CPU0_SB_DQS_DN<7>")
	)
	(segment
		(start 403.506178 -297.626278)
		(end 403.659086 -297.47337)
		(width 0.12954)
		(layer "F.Cu")
		(net "M_G_CPU0_SB_DQS_DN<7>")
	)
	(segment
		(start 397.299688 -286.10687)
		(end 401.451572 -290.258754)
		(width 0.12954)
		(layer "F.Cu")
		(net "M_G_CPU0_SB_DQS_DN<7>")
	)
	(segment
		(start 392.448034 -285.970218)
		(end 392.34618 -286.145478)
		(width 0.0762)
		(layer "F.Cu")
		(net "M_G_CPU0_SB_DQS_DN<7>")
	)
	(segment
		(start 407.712672 -302.031908)
		(end 410.379672 -304.698908)
		(width 0.12954)
		(layer "F.Cu")
		(net "M_G_CPU0_SB_DQS_DN<7>")
	)
	(segment
		(start 406.729184 -300.543468)
		(end 406.576022 -300.69663)
		(width 0.12954)
		(layer "F.Cu")
		(net "M_G_CPU0_SB_DQS_DN<7>")
	)
	(segment
		(start 410.379672 -304.698908)
		(end 411.54604 -304.698908)
		(width 0.12954)
		(layer "F.Cu")
		(net "M_G_CPU0_SB_DQS_DN<7>")
	)
	(segment
		(start 402.170392 -296.489628)
		(end 402.369528 -296.489628)
		(width 0.12954)
		(layer "F.Cu")
		(net "M_G_CPU0_SB_DQS_DN<7>")
	)
	(segment
		(start 404.642828 -298.762928)
		(end 404.795736 -298.61002)
		(width 0.12954)
		(layer "F.Cu")
		(net "M_G_CPU0_SB_DQS_DN<7>")
	)
	(segment
		(start 404.456138 -297.80484)
		(end 404.455884 -298.270168)
		(width 0.12954)
		(layer "F.Cu")
		(net "M_G_CPU0_SB_DQS_DN<7>")
	)
	(segment
		(start 401.451572 -295.770808)
		(end 402.170392 -296.489628)
		(width 0.12954)
		(layer "F.Cu")
		(net "M_G_CPU0_SB_DQS_DN<7>")
	)
	(segment
		(start 401.451572 -290.258754)
		(end 401.451572 -295.770808)
		(width 0.12954)
		(layer "F.Cu")
		(net "M_G_CPU0_SB_DQS_DN<7>")
	)
	(segment
		(start 405.261572 -298.610274)
		(end 405.592788 -298.94149)
		(width 0.12954)
		(layer "F.Cu")
		(net "M_G_CPU0_SB_DQS_DN<7>")
	)
	(segment
		(start 405.932386 -299.74667)
		(end 406.398222 -299.746924)
		(width 0.12954)
		(layer "F.Cu")
		(net "M_G_CPU0_SB_DQS_DN<7>")
	)
	(segment
		(start 394.328396 -286.343344)
		(end 395.212062 -286.343344)
		(width 0.0762)
		(layer "F.Cu")
		(net "M_G_CPU0_SB_DQS_DN<7>")
	)
	(segment
		(start 403.319488 -296.66819)
		(end 403.319234 -297.133518)
		(width 0.12954)
		(layer "F.Cu")
		(net "M_G_CPU0_SB_DQS_DN<7>")
	)
	(segment
		(start 407.534872 -300.883574)
		(end 407.866088 -301.21479)
		(width 0.12954)
		(layer "F.Cu")
		(net "M_G_CPU0_SB_DQS_DN<7>")
	)
	(segment
		(start 395.840204 -286.10687)
		(end 395.859254 -286.10687)
		(width 0.0762)
		(layer "F.Cu")
		(net "M_G_CPU0_SB_DQS_DN<7>")
	)
	(segment
		(start 405.580342 -299.899578)
		(end 405.779478 -299.899578)
		(width 0.12954)
		(layer "F.Cu")
		(net "M_G_CPU0_SB_DQS_DN<7>")
	)
	(segment
		(start 407.866088 -301.21479)
		(end 407.865834 -301.680118)
		(width 0.12954)
		(layer "F.Cu")
		(net "M_G_CPU0_SB_DQS_DN<7>")
	)
	(segment
		(start 406.716992 -301.036228)
		(end 406.916128 -301.036228)
		(width 0.12954)
		(layer "F.Cu")
		(net "M_G_CPU0_SB_DQS_DN<7>")
	)
	(segment
		(start 405.779478 -299.899578)
		(end 405.932386 -299.74667)
		(width 0.12954)
		(layer "F.Cu")
		(net "M_G_CPU0_SB_DQS_DN<7>")
	)
	(segment
		(start 403.166072 -297.28668)
		(end 403.166072 -297.485308)
		(width 0.12954)
		(layer "F.Cu")
		(net "M_G_CPU0_SB_DQS_DN<7>")
	)
	(segment
		(start 394.327888 -286.342836)
		(end 394.328396 -286.343344)
		(width 0.0762)
		(layer "F.Cu")
		(net "M_G_CPU0_SB_DQS_DN<7>")
	)
	(segment
		(start 405.592788 -298.94149)
		(end 405.592534 -299.406818)
		(width 0.12954)
		(layer "F.Cu")
		(net "M_G_CPU0_SB_DQS_DN<7>")
	)
	(segment
		(start 404.302722 -298.621958)
		(end 404.443692 -298.762928)
		(width 0.12954)
		(layer "F.Cu")
		(net "M_G_CPU0_SB_DQS_DN<7>")
	)
	(segment
		(start 404.302722 -298.42333)
		(end 404.302722 -298.621958)
		(width 0.12954)
		(layer "F.Cu")
		(net "M_G_CPU0_SB_DQS_DN<7>")
	)
	(segment
		(start 403.307042 -297.626278)
		(end 403.506178 -297.626278)
		(width 0.12954)
		(layer "F.Cu")
		(net "M_G_CPU0_SB_DQS_DN<7>")
	)
	(segment
		(start 411.809946 -304.435002)
		(end 412.367984 -304.435002)
		(width 0.12954)
		(layer "F.Cu")
		(net "M_G_CPU0_SB_DQS_DN<7>")
	)
	(segment
		(start 403.319234 -297.133518)
		(end 403.166072 -297.28668)
		(width 0.12954)
		(layer "F.Cu")
		(net "M_G_CPU0_SB_DQS_DN<7>")
	)
	(segment
		(start 393.20089 -286.292798)
		(end 393.209272 -286.297624)
		(width 0.0762)
		(layer "F.Cu")
		(net "M_G_CPU0_SB_DQS_DN<7>")
	)
	(segment
		(start 405.439372 -299.55998)
		(end 405.439372 -299.758608)
		(width 0.12954)
		(layer "F.Cu")
		(net "M_G_CPU0_SB_DQS_DN<7>")
	)
	(segment
		(start 402.522436 -296.33672)
		(end 402.988272 -296.336974)
		(width 0.12954)
		(layer "F.Cu")
		(net "M_G_CPU0_SB_DQS_DN<7>")
	)
	(segment
		(start 406.576022 -300.895258)
		(end 406.716992 -301.036228)
		(width 0.12954)
		(layer "F.Cu")
		(net "M_G_CPU0_SB_DQS_DN<7>")
	)
	(segment
		(start 395.859254 -286.10687)
		(end 397.299688 -286.10687)
		(width 0.12954)
		(layer "F.Cu")
		(net "M_G_CPU0_SB_DQS_DN<7>")
	)
	(segment
		(start 395.774164 -286.17291)
		(end 395.840204 -286.10687)
		(width 0.0762)
		(layer "F.Cu")
		(net "M_G_CPU0_SB_DQS_DN<7>")
	)
	(segment
		(start 403.659086 -297.47337)
		(end 404.124922 -297.473624)
		(width 0.12954)
		(layer "F.Cu")
		(net "M_G_CPU0_SB_DQS_DN<7>")
	)
	(arc
		(start 392.34618 -286.145478)
		(mid 392.363374 -286.285064)
		(end 392.492738 -286.340296)
		(width 0.0762)
		(layer "F.Cu")
		(net "M_G_CPU0_SB_DQS_DN<7>")
	)
	(arc
		(start 393.209272 -286.297624)
		(mid 393.39278 -286.343118)
		(end 393.575032 -286.292798)
		(width 0.0762)
		(layer "F.Cu")
		(net "M_G_CPU0_SB_DQS_DN<7>")
	)
	(arc
		(start 394.140944 -286.292798)
		(mid 394.231113 -286.330147)
		(end 394.327888 -286.342836)
		(width 0.0762)
		(layer "F.Cu")
		(net "M_G_CPU0_SB_DQS_DN<7>")
	)
	(arc
		(start 393.575032 -286.292798)
		(mid 393.857988 -286.216621)
		(end 394.140944 -286.292798)
		(width 0.0762)
		(layer "F.Cu")
		(net "M_G_CPU0_SB_DQS_DN<7>")
	)
	(arc
		(start 392.492738 -286.340296)
		(mid 392.561685 -286.325299)
		(end 392.626596 -286.297624)
		(width 0.0762)
		(layer "F.Cu")
		(net "M_G_CPU0_SB_DQS_DN<7>")
	)
	(arc
		(start 392.634978 -286.292798)
		(mid 392.917934 -286.216621)
		(end 393.20089 -286.292798)
		(width 0.0762)
		(layer "F.Cu")
		(net "M_G_CPU0_SB_DQS_DN<7>")
	)
	(segment
		(start 409.104338 -293.86911)
		(end 409.57119 -293.86911)
		(width 0.12954)
		(layer "F.Cu")
		(net "M_G_CPU0_SB_DQS_DN<6>")
	)
	(segment
		(start 408.499056 -294.276272)
		(end 408.697176 -294.276272)
		(width 0.12954)
		(layer "F.Cu")
		(net "M_G_CPU0_SB_DQS_DN<6>")
	)
	(segment
		(start 394.327888 -281.4828)
		(end 394.328396 -281.483308)
		(width 0.0762)
		(layer "F.Cu")
		(net "M_G_CPU0_SB_DQS_DN<6>")
	)
	(segment
		(start 409.493466 -295.072562)
		(end 409.493466 -295.270682)
		(width 0.12954)
		(layer "F.Cu")
		(net "M_G_CPU0_SB_DQS_DN<6>")
	)
	(segment
		(start 407.312368 -289.767772)
		(end 407.312368 -291.610288)
		(width 0.12954)
		(layer "F.Cu")
		(net "M_G_CPU0_SB_DQS_DN<6>")
	)
	(segment
		(start 395.161008 -281.483308)
		(end 395.487652 -281.156664)
		(width 0.0762)
		(layer "F.Cu")
		(net "M_G_CPU0_SB_DQS_DN<6>")
	)
	(segment
		(start 407.560526 -293.139622)
		(end 407.967688 -292.73246)
		(width 0.12954)
		(layer "F.Cu")
		(net "M_G_CPU0_SB_DQS_DN<6>")
	)
	(segment
		(start 408.763978 -293.061898)
		(end 408.763978 -293.52875)
		(width 0.12954)
		(layer "F.Cu")
		(net "M_G_CPU0_SB_DQS_DN<6>")
	)
	(segment
		(start 392.448034 -281.110182)
		(end 392.34618 -281.285442)
		(width 0.0762)
		(layer "F.Cu")
		(net "M_G_CPU0_SB_DQS_DN<6>")
	)
	(segment
		(start 407.627328 -291.925248)
		(end 407.627328 -292.3921)
		(width 0.12954)
		(layer "F.Cu")
		(net "M_G_CPU0_SB_DQS_DN<6>")
	)
	(segment
		(start 411.050994 -295.348914)
		(end 411.54604 -295.348914)
		(width 0.12954)
		(layer "F.Cu")
		(net "M_G_CPU0_SB_DQS_DN<6>")
	)
	(segment
		(start 411.809946 -295.085008)
		(end 412.367984 -295.085008)
		(width 0.12954)
		(layer "F.Cu")
		(net "M_G_CPU0_SB_DQS_DN<6>")
	)
	(segment
		(start 411.54604 -295.348914)
		(end 411.809946 -295.085008)
		(width 0.12954)
		(layer "F.Cu")
		(net "M_G_CPU0_SB_DQS_DN<6>")
	)
	(segment
		(start 395.487652 -281.156664)
		(end 395.774164 -281.156664)
		(width 0.0762)
		(layer "F.Cu")
		(net "M_G_CPU0_SB_DQS_DN<6>")
	)
	(segment
		(start 407.627328 -292.3921)
		(end 407.220166 -292.799262)
		(width 0.12954)
		(layer "F.Cu")
		(net "M_G_CPU0_SB_DQS_DN<6>")
	)
	(segment
		(start 410.70784 -295.00576)
		(end 411.050994 -295.348914)
		(width 0.12954)
		(layer "F.Cu")
		(net "M_G_CPU0_SB_DQS_DN<6>")
	)
	(segment
		(start 393.20089 -281.432762)
		(end 393.209272 -281.437588)
		(width 0.0762)
		(layer "F.Cu")
		(net "M_G_CPU0_SB_DQS_DN<6>")
	)
	(segment
		(start 407.220166 -292.799262)
		(end 407.220166 -292.997382)
		(width 0.12954)
		(layer "F.Cu")
		(net "M_G_CPU0_SB_DQS_DN<6>")
	)
	(segment
		(start 395.840204 -281.090624)
		(end 395.859254 -281.090624)
		(width 0.0762)
		(layer "F.Cu")
		(net "M_G_CPU0_SB_DQS_DN<6>")
	)
	(segment
		(start 408.43454 -292.73246)
		(end 408.763978 -293.061898)
		(width 0.12954)
		(layer "F.Cu")
		(net "M_G_CPU0_SB_DQS_DN<6>")
	)
	(segment
		(start 395.774164 -281.156664)
		(end 395.840204 -281.090624)
		(width 0.0762)
		(layer "F.Cu")
		(net "M_G_CPU0_SB_DQS_DN<6>")
	)
	(segment
		(start 407.312368 -291.610288)
		(end 407.627328 -291.925248)
		(width 0.12954)
		(layer "F.Cu")
		(net "M_G_CPU0_SB_DQS_DN<6>")
	)
	(segment
		(start 409.900628 -294.198548)
		(end 409.900628 -294.6654)
		(width 0.12954)
		(layer "F.Cu")
		(net "M_G_CPU0_SB_DQS_DN<6>")
	)
	(segment
		(start 409.57119 -293.86911)
		(end 409.900628 -294.198548)
		(width 0.12954)
		(layer "F.Cu")
		(net "M_G_CPU0_SB_DQS_DN<6>")
	)
	(segment
		(start 407.362406 -293.139622)
		(end 407.560526 -293.139622)
		(width 0.12954)
		(layer "F.Cu")
		(net "M_G_CPU0_SB_DQS_DN<6>")
	)
	(segment
		(start 409.833826 -295.412922)
		(end 410.240988 -295.00576)
		(width 0.12954)
		(layer "F.Cu")
		(net "M_G_CPU0_SB_DQS_DN<6>")
	)
	(segment
		(start 409.493466 -295.270682)
		(end 409.635706 -295.412922)
		(width 0.12954)
		(layer "F.Cu")
		(net "M_G_CPU0_SB_DQS_DN<6>")
	)
	(segment
		(start 409.635706 -295.412922)
		(end 409.833826 -295.412922)
		(width 0.12954)
		(layer "F.Cu")
		(net "M_G_CPU0_SB_DQS_DN<6>")
	)
	(segment
		(start 407.220166 -292.997382)
		(end 407.362406 -293.139622)
		(width 0.12954)
		(layer "F.Cu")
		(net "M_G_CPU0_SB_DQS_DN<6>")
	)
	(segment
		(start 408.356816 -294.134032)
		(end 408.499056 -294.276272)
		(width 0.12954)
		(layer "F.Cu")
		(net "M_G_CPU0_SB_DQS_DN<6>")
	)
	(segment
		(start 408.697176 -294.276272)
		(end 409.104338 -293.86911)
		(width 0.12954)
		(layer "F.Cu")
		(net "M_G_CPU0_SB_DQS_DN<6>")
	)
	(segment
		(start 392.626596 -281.437588)
		(end 392.634978 -281.432762)
		(width 0.0762)
		(layer "F.Cu")
		(net "M_G_CPU0_SB_DQS_DN<6>")
	)
	(segment
		(start 395.859254 -281.090624)
		(end 398.63522 -281.090624)
		(width 0.12954)
		(layer "F.Cu")
		(net "M_G_CPU0_SB_DQS_DN<6>")
	)
	(segment
		(start 407.967688 -292.73246)
		(end 408.43454 -292.73246)
		(width 0.12954)
		(layer "F.Cu")
		(net "M_G_CPU0_SB_DQS_DN<6>")
	)
	(segment
		(start 408.356816 -293.935912)
		(end 408.356816 -294.134032)
		(width 0.12954)
		(layer "F.Cu")
		(net "M_G_CPU0_SB_DQS_DN<6>")
	)
	(segment
		(start 409.900628 -294.6654)
		(end 409.493466 -295.072562)
		(width 0.12954)
		(layer "F.Cu")
		(net "M_G_CPU0_SB_DQS_DN<6>")
	)
	(segment
		(start 394.328396 -281.483308)
		(end 395.161008 -281.483308)
		(width 0.0762)
		(layer "F.Cu")
		(net "M_G_CPU0_SB_DQS_DN<6>")
	)
	(segment
		(start 408.763978 -293.52875)
		(end 408.356816 -293.935912)
		(width 0.12954)
		(layer "F.Cu")
		(net "M_G_CPU0_SB_DQS_DN<6>")
	)
	(segment
		(start 410.240988 -295.00576)
		(end 410.70784 -295.00576)
		(width 0.12954)
		(layer "F.Cu")
		(net "M_G_CPU0_SB_DQS_DN<6>")
	)
	(segment
		(start 398.63522 -281.090624)
		(end 407.312368 -289.767772)
		(width 0.12954)
		(layer "F.Cu")
		(net "M_G_CPU0_SB_DQS_DN<6>")
	)
	(arc
		(start 392.34618 -281.285442)
		(mid 392.363374 -281.425028)
		(end 392.492738 -281.48026)
		(width 0.0762)
		(layer "F.Cu")
		(net "M_G_CPU0_SB_DQS_DN<6>")
	)
	(arc
		(start 393.575032 -281.432762)
		(mid 393.857988 -281.356585)
		(end 394.140944 -281.432762)
		(width 0.0762)
		(layer "F.Cu")
		(net "M_G_CPU0_SB_DQS_DN<6>")
	)
	(arc
		(start 393.209272 -281.437588)
		(mid 393.39278 -281.483082)
		(end 393.575032 -281.432762)
		(width 0.0762)
		(layer "F.Cu")
		(net "M_G_CPU0_SB_DQS_DN<6>")
	)
	(arc
		(start 392.492738 -281.48026)
		(mid 392.561685 -281.465263)
		(end 392.626596 -281.437588)
		(width 0.0762)
		(layer "F.Cu")
		(net "M_G_CPU0_SB_DQS_DN<6>")
	)
	(arc
		(start 394.140944 -281.432762)
		(mid 394.231113 -281.470111)
		(end 394.327888 -281.4828)
		(width 0.0762)
		(layer "F.Cu")
		(net "M_G_CPU0_SB_DQS_DN<6>")
	)
	(arc
		(start 392.634978 -281.432762)
		(mid 392.917934 -281.356585)
		(end 393.20089 -281.432762)
		(width 0.0762)
		(layer "F.Cu")
		(net "M_G_CPU0_SB_DQS_DN<6>")
	)
	(segment
		(start 395.840204 -276.413722)
		(end 395.859254 -276.413722)
		(width 0.0762)
		(layer "F.Cu")
		(net "M_G_CPU0_SB_DQS_DN<5>")
	)
	(segment
		(start 408.109928 -282.02001)
		(end 408.441144 -282.351226)
		(width 0.12954)
		(layer "F.Cu")
		(net "M_G_CPU0_SB_DQS_DN<5>")
	)
	(segment
		(start 395.297406 -276.479762)
		(end 395.774164 -276.479762)
		(width 0.0762)
		(layer "F.Cu")
		(net "M_G_CPU0_SB_DQS_DN<5>")
	)
	(segment
		(start 394.328396 -276.623272)
		(end 395.153896 -276.623272)
		(width 0.0762)
		(layer "F.Cu")
		(net "M_G_CPU0_SB_DQS_DN<5>")
	)
	(segment
		(start 405.116538 -280.00071)
		(end 405.370792 -279.74671)
		(width 0.12954)
		(layer "F.Cu")
		(net "M_G_CPU0_SB_DQS_DN<5>")
	)
	(segment
		(start 407.644092 -282.02001)
		(end 408.109928 -282.02001)
		(width 0.12954)
		(layer "F.Cu")
		(net "M_G_CPU0_SB_DQS_DN<5>")
	)
	(segment
		(start 406.507442 -280.88336)
		(end 406.973278 -280.88336)
		(width 0.12954)
		(layer "F.Cu")
		(net "M_G_CPU0_SB_DQS_DN<5>")
	)
	(segment
		(start 408.44089 -282.816554)
		(end 408.186636 -283.070808)
		(width 0.12954)
		(layer "F.Cu")
		(net "M_G_CPU0_SB_DQS_DN<5>")
	)
	(segment
		(start 405.370792 -279.74671)
		(end 405.836628 -279.74671)
		(width 0.12954)
		(layer "F.Cu")
		(net "M_G_CPU0_SB_DQS_DN<5>")
	)
	(segment
		(start 411.54604 -285.99892)
		(end 411.809946 -285.735014)
		(width 0.12954)
		(layer "F.Cu")
		(net "M_G_CPU0_SB_DQS_DN<5>")
	)
	(segment
		(start 408.441144 -282.351226)
		(end 408.44089 -282.816554)
		(width 0.12954)
		(layer "F.Cu")
		(net "M_G_CPU0_SB_DQS_DN<5>")
	)
	(segment
		(start 410.91612 -285.99892)
		(end 411.54604 -285.99892)
		(width 0.12954)
		(layer "F.Cu")
		(net "M_G_CPU0_SB_DQS_DN<5>")
	)
	(segment
		(start 395.774164 -276.479762)
		(end 395.840204 -276.413722)
		(width 0.0762)
		(layer "F.Cu")
		(net "M_G_CPU0_SB_DQS_DN<5>")
	)
	(segment
		(start 393.20089 -276.572726)
		(end 393.209272 -276.577552)
		(width 0.0762)
		(layer "F.Cu")
		(net "M_G_CPU0_SB_DQS_DN<5>")
	)
	(segment
		(start 407.30424 -281.679904)
		(end 407.049986 -281.934158)
		(width 0.12954)
		(layer "F.Cu")
		(net "M_G_CPU0_SB_DQS_DN<5>")
	)
	(segment
		(start 404.776686 -279.660604)
		(end 404.776686 -279.859486)
		(width 0.12954)
		(layer "F.Cu")
		(net "M_G_CPU0_SB_DQS_DN<5>")
	)
	(segment
		(start 405.038052 -278.948134)
		(end 405.038052 -279.399238)
		(width 0.12954)
		(layer "F.Cu")
		(net "M_G_CPU0_SB_DQS_DN<5>")
	)
	(segment
		(start 402.50364 -276.413722)
		(end 405.038052 -278.948134)
		(width 0.12954)
		(layer "F.Cu")
		(net "M_G_CPU0_SB_DQS_DN<5>")
	)
	(segment
		(start 406.973278 -280.88336)
		(end 407.304494 -281.214576)
		(width 0.12954)
		(layer "F.Cu")
		(net "M_G_CPU0_SB_DQS_DN<5>")
	)
	(segment
		(start 405.836628 -279.74671)
		(end 406.167844 -280.077926)
		(width 0.12954)
		(layer "F.Cu")
		(net "M_G_CPU0_SB_DQS_DN<5>")
	)
	(segment
		(start 404.776686 -279.859486)
		(end 404.91791 -280.00071)
		(width 0.12954)
		(layer "F.Cu")
		(net "M_G_CPU0_SB_DQS_DN<5>")
	)
	(segment
		(start 407.19121 -282.27401)
		(end 407.389838 -282.27401)
		(width 0.12954)
		(layer "F.Cu")
		(net "M_G_CPU0_SB_DQS_DN<5>")
	)
	(segment
		(start 404.91791 -280.00071)
		(end 405.116538 -280.00071)
		(width 0.12954)
		(layer "F.Cu")
		(net "M_G_CPU0_SB_DQS_DN<5>")
	)
	(segment
		(start 406.16759 -280.543254)
		(end 405.913336 -280.797508)
		(width 0.12954)
		(layer "F.Cu")
		(net "M_G_CPU0_SB_DQS_DN<5>")
	)
	(segment
		(start 395.153896 -276.623272)
		(end 395.297406 -276.479762)
		(width 0.0762)
		(layer "F.Cu")
		(net "M_G_CPU0_SB_DQS_DN<5>")
	)
	(segment
		(start 405.913336 -280.797508)
		(end 405.913336 -280.996136)
		(width 0.12954)
		(layer "F.Cu")
		(net "M_G_CPU0_SB_DQS_DN<5>")
	)
	(segment
		(start 395.859254 -276.413722)
		(end 402.50364 -276.413722)
		(width 0.12954)
		(layer "F.Cu")
		(net "M_G_CPU0_SB_DQS_DN<5>")
	)
	(segment
		(start 408.186636 -283.070808)
		(end 408.186636 -283.269436)
		(width 0.12954)
		(layer "F.Cu")
		(net "M_G_CPU0_SB_DQS_DN<5>")
	)
	(segment
		(start 407.304494 -281.214576)
		(end 407.30424 -281.679904)
		(width 0.12954)
		(layer "F.Cu")
		(net "M_G_CPU0_SB_DQS_DN<5>")
	)
	(segment
		(start 394.327888 -276.622764)
		(end 394.328396 -276.623272)
		(width 0.0762)
		(layer "F.Cu")
		(net "M_G_CPU0_SB_DQS_DN<5>")
	)
	(segment
		(start 408.186636 -283.269436)
		(end 410.91612 -285.99892)
		(width 0.12954)
		(layer "F.Cu")
		(net "M_G_CPU0_SB_DQS_DN<5>")
	)
	(segment
		(start 406.05456 -281.13736)
		(end 406.253188 -281.13736)
		(width 0.12954)
		(layer "F.Cu")
		(net "M_G_CPU0_SB_DQS_DN<5>")
	)
	(segment
		(start 405.913336 -280.996136)
		(end 406.05456 -281.13736)
		(width 0.12954)
		(layer "F.Cu")
		(net "M_G_CPU0_SB_DQS_DN<5>")
	)
	(segment
		(start 407.389838 -282.27401)
		(end 407.644092 -282.02001)
		(width 0.12954)
		(layer "F.Cu")
		(net "M_G_CPU0_SB_DQS_DN<5>")
	)
	(segment
		(start 392.448034 -276.250146)
		(end 392.34618 -276.425406)
		(width 0.0762)
		(layer "F.Cu")
		(net "M_G_CPU0_SB_DQS_DN<5>")
	)
	(segment
		(start 407.049986 -282.132786)
		(end 407.19121 -282.27401)
		(width 0.12954)
		(layer "F.Cu")
		(net "M_G_CPU0_SB_DQS_DN<5>")
	)
	(segment
		(start 405.038052 -279.399238)
		(end 404.776686 -279.660604)
		(width 0.12954)
		(layer "F.Cu")
		(net "M_G_CPU0_SB_DQS_DN<5>")
	)
	(segment
		(start 411.809946 -285.735014)
		(end 412.367984 -285.735014)
		(width 0.12954)
		(layer "F.Cu")
		(net "M_G_CPU0_SB_DQS_DN<5>")
	)
	(segment
		(start 392.626596 -276.577552)
		(end 392.634978 -276.572726)
		(width 0.0762)
		(layer "F.Cu")
		(net "M_G_CPU0_SB_DQS_DN<5>")
	)
	(segment
		(start 406.167844 -280.077926)
		(end 406.16759 -280.543254)
		(width 0.12954)
		(layer "F.Cu")
		(net "M_G_CPU0_SB_DQS_DN<5>")
	)
	(segment
		(start 407.049986 -281.934158)
		(end 407.049986 -282.132786)
		(width 0.12954)
		(layer "F.Cu")
		(net "M_G_CPU0_SB_DQS_DN<5>")
	)
	(segment
		(start 406.253188 -281.13736)
		(end 406.507442 -280.88336)
		(width 0.12954)
		(layer "F.Cu")
		(net "M_G_CPU0_SB_DQS_DN<5>")
	)
	(arc
		(start 394.140944 -276.572726)
		(mid 394.231113 -276.610075)
		(end 394.327888 -276.622764)
		(width 0.0762)
		(layer "F.Cu")
		(net "M_G_CPU0_SB_DQS_DN<5>")
	)
	(arc
		(start 392.34618 -276.425406)
		(mid 392.363374 -276.564992)
		(end 392.492738 -276.620224)
		(width 0.0762)
		(layer "F.Cu")
		(net "M_G_CPU0_SB_DQS_DN<5>")
	)
	(arc
		(start 393.575032 -276.572726)
		(mid 393.857988 -276.496549)
		(end 394.140944 -276.572726)
		(width 0.0762)
		(layer "F.Cu")
		(net "M_G_CPU0_SB_DQS_DN<5>")
	)
	(arc
		(start 392.634978 -276.572726)
		(mid 392.917934 -276.496549)
		(end 393.20089 -276.572726)
		(width 0.0762)
		(layer "F.Cu")
		(net "M_G_CPU0_SB_DQS_DN<5>")
	)
	(arc
		(start 392.492738 -276.620224)
		(mid 392.561685 -276.605227)
		(end 392.626596 -276.577552)
		(width 0.0762)
		(layer "F.Cu")
		(net "M_G_CPU0_SB_DQS_DN<5>")
	)
	(arc
		(start 393.209272 -276.577552)
		(mid 393.39278 -276.623046)
		(end 393.575032 -276.572726)
		(width 0.0762)
		(layer "F.Cu")
		(net "M_G_CPU0_SB_DQS_DN<5>")
	)
	(segment
		(start 410.476192 -276.648926)
		(end 411.54604 -276.648926)
		(width 0.12954)
		(layer "F.Cu")
		(net "M_G_CPU0_SB_DQS_DN<4>")
	)
	(segment
		(start 406.724866 -271.392904)
		(end 407.055828 -271.723866)
		(width 0.12954)
		(layer "F.Cu")
		(net "M_G_CPU0_SB_DQS_DN<4>")
	)
	(segment
		(start 408.298904 -272.75409)
		(end 408.298904 -273.219926)
		(width 0.12954)
		(layer "F.Cu")
		(net "M_G_CPU0_SB_DQS_DN<4>")
	)
	(segment
		(start 395.859254 -271.392904)
		(end 405.566626 -271.392904)
		(width 0.12954)
		(layer "F.Cu")
		(net "M_G_CPU0_SB_DQS_DN<4>")
	)
	(segment
		(start 405.81326 -271.639538)
		(end 406.012396 -271.639538)
		(width 0.12954)
		(layer "F.Cu")
		(net "M_G_CPU0_SB_DQS_DN<4>")
	)
	(segment
		(start 411.809946 -276.38502)
		(end 412.367984 -276.38502)
		(width 0.12954)
		(layer "F.Cu")
		(net "M_G_CPU0_SB_DQS_DN<4>")
	)
	(segment
		(start 408.055064 -274.227798)
		(end 408.644344 -274.227798)
		(width 0.12954)
		(layer "F.Cu")
		(net "M_G_CPU0_SB_DQS_DN<4>")
	)
	(segment
		(start 409.780994 -275.364448)
		(end 410.149802 -275.733256)
		(width 0.12954)
		(layer "F.Cu")
		(net "M_G_CPU0_SB_DQS_DN<4>")
	)
	(segment
		(start 406.975818 -272.949416)
		(end 407.502106 -272.423128)
		(width 0.12954)
		(layer "F.Cu")
		(net "M_G_CPU0_SB_DQS_DN<4>")
	)
	(segment
		(start 406.635966 -272.8087)
		(end 406.776682 -272.949416)
		(width 0.12954)
		(layer "F.Cu")
		(net "M_G_CPU0_SB_DQS_DN<4>")
	)
	(segment
		(start 410.149802 -275.733256)
		(end 410.149802 -276.322536)
		(width 0.12954)
		(layer "F.Cu")
		(net "M_G_CPU0_SB_DQS_DN<4>")
	)
	(segment
		(start 408.298904 -273.219926)
		(end 407.764488 -273.754342)
		(width 0.12954)
		(layer "F.Cu")
		(net "M_G_CPU0_SB_DQS_DN<4>")
	)
	(segment
		(start 407.055828 -271.723866)
		(end 407.055828 -272.189702)
		(width 0.12954)
		(layer "F.Cu")
		(net "M_G_CPU0_SB_DQS_DN<4>")
	)
	(segment
		(start 394.327888 -271.762728)
		(end 394.328396 -271.763236)
		(width 0.0762)
		(layer "F.Cu")
		(net "M_G_CPU0_SB_DQS_DN<4>")
	)
	(segment
		(start 394.328396 -271.763236)
		(end 395.153896 -271.763236)
		(width 0.0762)
		(layer "F.Cu")
		(net "M_G_CPU0_SB_DQS_DN<4>")
	)
	(segment
		(start 395.840204 -271.392904)
		(end 395.859254 -271.392904)
		(width 0.0762)
		(layer "F.Cu")
		(net "M_G_CPU0_SB_DQS_DN<4>")
	)
	(segment
		(start 406.635966 -272.609564)
		(end 406.635966 -272.8087)
		(width 0.12954)
		(layer "F.Cu")
		(net "M_G_CPU0_SB_DQS_DN<4>")
	)
	(segment
		(start 408.644344 -274.227798)
		(end 409.013152 -274.596606)
		(width 0.12954)
		(layer "F.Cu")
		(net "M_G_CPU0_SB_DQS_DN<4>")
	)
	(segment
		(start 405.566626 -271.392904)
		(end 405.81326 -271.639538)
		(width 0.12954)
		(layer "F.Cu")
		(net "M_G_CPU0_SB_DQS_DN<4>")
	)
	(segment
		(start 409.013152 -275.185886)
		(end 409.191714 -275.364448)
		(width 0.12954)
		(layer "F.Cu")
		(net "M_G_CPU0_SB_DQS_DN<4>")
	)
	(segment
		(start 406.25903 -271.392904)
		(end 406.724866 -271.392904)
		(width 0.12954)
		(layer "F.Cu")
		(net "M_G_CPU0_SB_DQS_DN<4>")
	)
	(segment
		(start 409.191714 -275.364448)
		(end 409.780994 -275.364448)
		(width 0.12954)
		(layer "F.Cu")
		(net "M_G_CPU0_SB_DQS_DN<4>")
	)
	(segment
		(start 411.54604 -276.648926)
		(end 411.809946 -276.38502)
		(width 0.12954)
		(layer "F.Cu")
		(net "M_G_CPU0_SB_DQS_DN<4>")
	)
	(segment
		(start 407.967942 -272.423128)
		(end 408.298904 -272.75409)
		(width 0.12954)
		(layer "F.Cu")
		(net "M_G_CPU0_SB_DQS_DN<4>")
	)
	(segment
		(start 392.626596 -271.717516)
		(end 392.634978 -271.71269)
		(width 0.0762)
		(layer "F.Cu")
		(net "M_G_CPU0_SB_DQS_DN<4>")
	)
	(segment
		(start 407.502106 -272.423128)
		(end 407.967942 -272.423128)
		(width 0.12954)
		(layer "F.Cu")
		(net "M_G_CPU0_SB_DQS_DN<4>")
	)
	(segment
		(start 406.012396 -271.639538)
		(end 406.25903 -271.392904)
		(width 0.12954)
		(layer "F.Cu")
		(net "M_G_CPU0_SB_DQS_DN<4>")
	)
	(segment
		(start 392.448034 -271.39011)
		(end 392.34618 -271.56537)
		(width 0.0762)
		(layer "F.Cu")
		(net "M_G_CPU0_SB_DQS_DN<4>")
	)
	(segment
		(start 407.055828 -272.189702)
		(end 406.635966 -272.609564)
		(width 0.12954)
		(layer "F.Cu")
		(net "M_G_CPU0_SB_DQS_DN<4>")
	)
	(segment
		(start 395.774164 -271.458944)
		(end 395.840204 -271.392904)
		(width 0.0762)
		(layer "F.Cu")
		(net "M_G_CPU0_SB_DQS_DN<4>")
	)
	(segment
		(start 407.764488 -273.754342)
		(end 407.764488 -273.937222)
		(width 0.12954)
		(layer "F.Cu")
		(net "M_G_CPU0_SB_DQS_DN<4>")
	)
	(segment
		(start 393.20089 -271.71269)
		(end 393.209272 -271.717516)
		(width 0.0762)
		(layer "F.Cu")
		(net "M_G_CPU0_SB_DQS_DN<4>")
	)
	(segment
		(start 409.013152 -274.596606)
		(end 409.013152 -275.185886)
		(width 0.12954)
		(layer "F.Cu")
		(net "M_G_CPU0_SB_DQS_DN<4>")
	)
	(segment
		(start 410.149802 -276.322536)
		(end 410.476192 -276.648926)
		(width 0.12954)
		(layer "F.Cu")
		(net "M_G_CPU0_SB_DQS_DN<4>")
	)
	(segment
		(start 406.776682 -272.949416)
		(end 406.975818 -272.949416)
		(width 0.12954)
		(layer "F.Cu")
		(net "M_G_CPU0_SB_DQS_DN<4>")
	)
	(segment
		(start 395.458188 -271.458944)
		(end 395.774164 -271.458944)
		(width 0.0762)
		(layer "F.Cu")
		(net "M_G_CPU0_SB_DQS_DN<4>")
	)
	(segment
		(start 407.764488 -273.937222)
		(end 408.055064 -274.227798)
		(width 0.12954)
		(layer "F.Cu")
		(net "M_G_CPU0_SB_DQS_DN<4>")
	)
	(segment
		(start 395.153896 -271.763236)
		(end 395.458188 -271.458944)
		(width 0.0762)
		(layer "F.Cu")
		(net "M_G_CPU0_SB_DQS_DN<4>")
	)
	(arc
		(start 392.34618 -271.56537)
		(mid 392.363374 -271.704956)
		(end 392.492738 -271.760188)
		(width 0.0762)
		(layer "F.Cu")
		(net "M_G_CPU0_SB_DQS_DN<4>")
	)
	(arc
		(start 392.492738 -271.760188)
		(mid 392.561685 -271.745191)
		(end 392.626596 -271.717516)
		(width 0.0762)
		(layer "F.Cu")
		(net "M_G_CPU0_SB_DQS_DN<4>")
	)
	(arc
		(start 394.140944 -271.71269)
		(mid 394.231113 -271.750039)
		(end 394.327888 -271.762728)
		(width 0.0762)
		(layer "F.Cu")
		(net "M_G_CPU0_SB_DQS_DN<4>")
	)
	(arc
		(start 392.634978 -271.71269)
		(mid 392.917934 -271.636513)
		(end 393.20089 -271.71269)
		(width 0.0762)
		(layer "F.Cu")
		(net "M_G_CPU0_SB_DQS_DN<4>")
	)
	(arc
		(start 393.575032 -271.71269)
		(mid 393.857988 -271.636513)
		(end 394.140944 -271.71269)
		(width 0.0762)
		(layer "F.Cu")
		(net "M_G_CPU0_SB_DQS_DN<4>")
	)
	(arc
		(start 393.209272 -271.717516)
		(mid 393.39278 -271.76301)
		(end 393.575032 -271.71269)
		(width 0.0762)
		(layer "F.Cu")
		(net "M_G_CPU0_SB_DQS_DN<4>")
	)
	(segment
		(start 410.584142 -311.993788)
		(end 410.31287 -312.26506)
		(width 0.12954)
		(layer "F.Cu")
		(net "M_G_CPU0_SB_DQS_DN<3>")
	)
	(segment
		(start 414.982914 -313.46775)
		(end 415.637218 -313.46775)
		(width 0.101346)
		(layer "F.Cu")
		(net "M_G_CPU0_SB_DQS_DN<3>")
	)
	(segment
		(start 397.481298 -298.693078)
		(end 409.447492 -310.659272)
		(width 0.12954)
		(layer "F.Cu")
		(net "M_G_CPU0_SB_DQS_DN<3>")
	)
	(segment
		(start 395.201394 -290.456874)
		(end 395.386052 -290.641532)
		(width 0.0762)
		(layer "F.Cu")
		(net "M_G_CPU0_SB_DQS_DN<3>")
	)
	(segment
		(start 409.972256 -311.9247)
		(end 410.243528 -311.653682)
		(width 0.12954)
		(layer "F.Cu")
		(net "M_G_CPU0_SB_DQS_DN<3>")
	)
	(segment
		(start 410.31287 -312.26506)
		(end 410.31287 -312.731404)
		(width 0.12954)
		(layer "F.Cu")
		(net "M_G_CPU0_SB_DQS_DN<3>")
	)
	(segment
		(start 409.506166 -311.9247)
		(end 409.972256 -311.9247)
		(width 0.12954)
		(layer "F.Cu")
		(net "M_G_CPU0_SB_DQS_DN<3>")
	)
	(segment
		(start 411.50667 -313.360054)
		(end 413.93491 -313.360054)
		(width 0.101346)
		(layer "F.Cu")
		(net "M_G_CPU0_SB_DQS_DN<3>")
	)
	(segment
		(start 410.67863 -313.097164)
		(end 411.24378 -313.097164)
		(width 0.12954)
		(layer "F.Cu")
		(net "M_G_CPU0_SB_DQS_DN<3>")
	)
	(segment
		(start 396.16888 -290.707572)
		(end 397.481298 -292.01999)
		(width 0.12954)
		(layer "F.Cu")
		(net "M_G_CPU0_SB_DQS_DN<3>")
	)
	(segment
		(start 415.954464 -313.784996)
		(end 416.468052 -313.784996)
		(width 0.101346)
		(layer "F.Cu")
		(net "M_G_CPU0_SB_DQS_DN<3>")
	)
	(segment
		(start 409.447492 -310.857138)
		(end 409.17622 -311.12841)
		(width 0.12954)
		(layer "F.Cu")
		(net "M_G_CPU0_SB_DQS_DN<3>")
	)
	(segment
		(start 395.650212 -290.641532)
		(end 395.716252 -290.707572)
		(width 0.0762)
		(layer "F.Cu")
		(net "M_G_CPU0_SB_DQS_DN<3>")
	)
	(segment
		(start 394.327888 -290.456874)
		(end 395.201394 -290.456874)
		(width 0.0762)
		(layer "F.Cu")
		(net "M_G_CPU0_SB_DQS_DN<3>")
	)
	(segment
		(start 410.31287 -312.731404)
		(end 410.67863 -313.097164)
		(width 0.12954)
		(layer "F.Cu")
		(net "M_G_CPU0_SB_DQS_DN<3>")
	)
	(segment
		(start 411.24378 -313.097164)
		(end 411.50667 -313.360054)
		(width 0.12954)
		(layer "F.Cu")
		(net "M_G_CPU0_SB_DQS_DN<3>")
	)
	(segment
		(start 414.25241 -313.042554)
		(end 414.557718 -313.042554)
		(width 0.101346)
		(layer "F.Cu")
		(net "M_G_CPU0_SB_DQS_DN<3>")
	)
	(segment
		(start 395.386052 -290.641532)
		(end 395.650212 -290.641532)
		(width 0.0762)
		(layer "F.Cu")
		(net "M_G_CPU0_SB_DQS_DN<3>")
	)
	(segment
		(start 395.716252 -290.707572)
		(end 395.735302 -290.707572)
		(width 0.0762)
		(layer "F.Cu")
		(net "M_G_CPU0_SB_DQS_DN<3>")
	)
	(segment
		(start 409.447492 -310.659272)
		(end 409.447492 -310.857138)
		(width 0.12954)
		(layer "F.Cu")
		(net "M_G_CPU0_SB_DQS_DN<3>")
	)
	(segment
		(start 413.93491 -313.360054)
		(end 414.25241 -313.042554)
		(width 0.101346)
		(layer "F.Cu")
		(net "M_G_CPU0_SB_DQS_DN<3>")
	)
	(segment
		(start 410.441902 -311.653682)
		(end 410.584142 -311.795922)
		(width 0.12954)
		(layer "F.Cu")
		(net "M_G_CPU0_SB_DQS_DN<3>")
	)
	(segment
		(start 414.557718 -313.042554)
		(end 414.982914 -313.46775)
		(width 0.101346)
		(layer "F.Cu")
		(net "M_G_CPU0_SB_DQS_DN<3>")
	)
	(segment
		(start 395.735302 -290.707572)
		(end 396.16888 -290.707572)
		(width 0.12954)
		(layer "F.Cu")
		(net "M_G_CPU0_SB_DQS_DN<3>")
	)
	(segment
		(start 409.17622 -311.594754)
		(end 409.506166 -311.9247)
		(width 0.12954)
		(layer "F.Cu")
		(net "M_G_CPU0_SB_DQS_DN<3>")
	)
	(segment
		(start 409.17622 -311.12841)
		(end 409.17622 -311.594754)
		(width 0.12954)
		(layer "F.Cu")
		(net "M_G_CPU0_SB_DQS_DN<3>")
	)
	(segment
		(start 415.637218 -313.46775)
		(end 415.954464 -313.784996)
		(width 0.101346)
		(layer "F.Cu")
		(net "M_G_CPU0_SB_DQS_DN<3>")
	)
	(segment
		(start 410.584142 -311.795922)
		(end 410.584142 -311.993788)
		(width 0.12954)
		(layer "F.Cu")
		(net "M_G_CPU0_SB_DQS_DN<3>")
	)
	(segment
		(start 410.243528 -311.653682)
		(end 410.441902 -311.653682)
		(width 0.12954)
		(layer "F.Cu")
		(net "M_G_CPU0_SB_DQS_DN<3>")
	)
	(segment
		(start 397.481298 -292.01999)
		(end 397.481298 -298.693078)
		(width 0.12954)
		(layer "F.Cu")
		(net "M_G_CPU0_SB_DQS_DN<3>")
	)
	(arc
		(start 393.387834 -290.83)
		(mid 393.631265 -290.660513)
		(end 393.916916 -290.580572)
		(width 0.0762)
		(layer "F.Cu")
		(net "M_G_CPU0_SB_DQS_DN<3>")
	)
	(arc
		(start 394.2969 -290.458144)
		(mid 394.312381 -290.457188)
		(end 394.327888 -290.456874)
		(width 0.0762)
		(layer "F.Cu")
		(net "M_G_CPU0_SB_DQS_DN<3>")
	)
	(arc
		(start 394.140944 -290.50742)
		(mid 394.216184 -290.474107)
		(end 394.2969 -290.458144)
		(width 0.0762)
		(layer "F.Cu")
		(net "M_G_CPU0_SB_DQS_DN<3>")
	)
	(arc
		(start 393.916916 -290.580572)
		(mid 393.936265 -290.578234)
		(end 393.955524 -290.575238)
		(width 0.0762)
		(layer "F.Cu")
		(net "M_G_CPU0_SB_DQS_DN<3>")
	)
	(arc
		(start 393.955524 -290.575238)
		(mid 394.051233 -290.549526)
		(end 394.140944 -290.50742)
		(width 0.0762)
		(layer "F.Cu")
		(net "M_G_CPU0_SB_DQS_DN<3>")
	)
	(segment
		(start 409.647136 -302.903128)
		(end 409.647136 -303.36998)
		(width 0.12954)
		(layer "F.Cu")
		(net "M_G_CPU0_SB_DQS_DN<2>")
	)
	(segment
		(start 414.53181 -303.69256)
		(end 414.957006 -304.117756)
		(width 0.101346)
		(layer "F.Cu")
		(net "M_G_CPU0_SB_DQS_DN<2>")
	)
	(segment
		(start 395.840204 -285.678372)
		(end 395.859254 -285.678372)
		(width 0.0762)
		(layer "F.Cu")
		(net "M_G_CPU0_SB_DQS_DN<2>")
	)
	(segment
		(start 409.841446 -302.510698)
		(end 409.841446 -302.708818)
		(width 0.12954)
		(layer "F.Cu")
		(net "M_G_CPU0_SB_DQS_DN<2>")
	)
	(segment
		(start 409.699206 -302.368458)
		(end 409.841446 -302.510698)
		(width 0.12954)
		(layer "F.Cu")
		(net "M_G_CPU0_SB_DQS_DN<2>")
	)
	(segment
		(start 395.362684 -285.612332)
		(end 395.774164 -285.612332)
		(width 0.0762)
		(layer "F.Cu")
		(net "M_G_CPU0_SB_DQS_DN<2>")
	)
	(segment
		(start 395.859254 -285.678372)
		(end 397.47952 -285.678372)
		(width 0.12954)
		(layer "F.Cu")
		(net "M_G_CPU0_SB_DQS_DN<2>")
	)
	(segment
		(start 401.873212 -290.072064)
		(end 401.873212 -294.55364)
		(width 0.12954)
		(layer "F.Cu")
		(net "M_G_CPU0_SB_DQS_DN<2>")
	)
	(segment
		(start 409.306776 -302.562768)
		(end 409.501086 -302.368458)
		(width 0.12954)
		(layer "F.Cu")
		(net "M_G_CPU0_SB_DQS_DN<2>")
	)
	(segment
		(start 411.50667 -304.01006)
		(end 413.93491 -304.01006)
		(width 0.101346)
		(layer "F.Cu")
		(net "M_G_CPU0_SB_DQS_DN<2>")
	)
	(segment
		(start 415.637218 -304.117756)
		(end 415.954464 -304.435002)
		(width 0.101346)
		(layer "F.Cu")
		(net "M_G_CPU0_SB_DQS_DN<2>")
	)
	(segment
		(start 409.501086 -302.368458)
		(end 409.699206 -302.368458)
		(width 0.12954)
		(layer "F.Cu")
		(net "M_G_CPU0_SB_DQS_DN<2>")
	)
	(segment
		(start 397.47952 -285.678372)
		(end 401.873212 -290.072064)
		(width 0.12954)
		(layer "F.Cu")
		(net "M_G_CPU0_SB_DQS_DN<2>")
	)
	(segment
		(start 395.347444 -285.597092)
		(end 395.362684 -285.612332)
		(width 0.0762)
		(layer "F.Cu")
		(net "M_G_CPU0_SB_DQS_DN<2>")
	)
	(segment
		(start 414.25241 -303.69256)
		(end 414.53181 -303.69256)
		(width 0.101346)
		(layer "F.Cu")
		(net "M_G_CPU0_SB_DQS_DN<2>")
	)
	(segment
		(start 411.24378 -303.74717)
		(end 411.50667 -304.01006)
		(width 0.12954)
		(layer "F.Cu")
		(net "M_G_CPU0_SB_DQS_DN<2>")
	)
	(segment
		(start 414.957006 -304.117756)
		(end 415.637218 -304.117756)
		(width 0.101346)
		(layer "F.Cu")
		(net "M_G_CPU0_SB_DQS_DN<2>")
	)
	(segment
		(start 408.704796 -301.385224)
		(end 408.704796 -301.572168)
		(width 0.12954)
		(layer "F.Cu")
		(net "M_G_CPU0_SB_DQS_DN<2>")
	)
	(segment
		(start 415.954464 -304.435002)
		(end 416.468052 -304.435002)
		(width 0.101346)
		(layer "F.Cu")
		(net "M_G_CPU0_SB_DQS_DN<2>")
	)
	(segment
		(start 413.93491 -304.01006)
		(end 414.25241 -303.69256)
		(width 0.101346)
		(layer "F.Cu")
		(net "M_G_CPU0_SB_DQS_DN<2>")
	)
	(segment
		(start 395.774164 -285.612332)
		(end 395.840204 -285.678372)
		(width 0.0762)
		(layer "F.Cu")
		(net "M_G_CPU0_SB_DQS_DN<2>")
	)
	(segment
		(start 409.841446 -302.708818)
		(end 409.647136 -302.903128)
		(width 0.12954)
		(layer "F.Cu")
		(net "M_G_CPU0_SB_DQS_DN<2>")
	)
	(segment
		(start 408.510486 -302.23333)
		(end 408.839924 -302.562768)
		(width 0.12954)
		(layer "F.Cu")
		(net "M_G_CPU0_SB_DQS_DN<2>")
	)
	(segment
		(start 408.839924 -302.562768)
		(end 409.306776 -302.562768)
		(width 0.12954)
		(layer "F.Cu")
		(net "M_G_CPU0_SB_DQS_DN<2>")
	)
	(segment
		(start 409.647136 -303.36998)
		(end 410.024326 -303.74717)
		(width 0.12954)
		(layer "F.Cu")
		(net "M_G_CPU0_SB_DQS_DN<2>")
	)
	(segment
		(start 408.704796 -301.572168)
		(end 408.510486 -301.766478)
		(width 0.12954)
		(layer "F.Cu")
		(net "M_G_CPU0_SB_DQS_DN<2>")
	)
	(segment
		(start 408.510486 -301.766478)
		(end 408.510486 -302.23333)
		(width 0.12954)
		(layer "F.Cu")
		(net "M_G_CPU0_SB_DQS_DN<2>")
	)
	(segment
		(start 401.873212 -294.55364)
		(end 408.704796 -301.385224)
		(width 0.12954)
		(layer "F.Cu")
		(net "M_G_CPU0_SB_DQS_DN<2>")
	)
	(segment
		(start 394.327888 -285.597092)
		(end 395.347444 -285.597092)
		(width 0.0762)
		(layer "F.Cu")
		(net "M_G_CPU0_SB_DQS_DN<2>")
	)
	(segment
		(start 410.024326 -303.74717)
		(end 411.24378 -303.74717)
		(width 0.12954)
		(layer "F.Cu")
		(net "M_G_CPU0_SB_DQS_DN<2>")
	)
	(arc
		(start 393.387834 -285.970218)
		(mid 393.631265 -285.800731)
		(end 393.916916 -285.72079)
		(width 0.0762)
		(layer "F.Cu")
		(net "M_G_CPU0_SB_DQS_DN<2>")
	)
	(arc
		(start 394.140944 -285.647638)
		(mid 394.216184 -285.614325)
		(end 394.2969 -285.598362)
		(width 0.0762)
		(layer "F.Cu")
		(net "M_G_CPU0_SB_DQS_DN<2>")
	)
	(arc
		(start 394.2969 -285.598362)
		(mid 394.312381 -285.597406)
		(end 394.327888 -285.597092)
		(width 0.0762)
		(layer "F.Cu")
		(net "M_G_CPU0_SB_DQS_DN<2>")
	)
	(arc
		(start 393.916916 -285.72079)
		(mid 393.936265 -285.718452)
		(end 393.955524 -285.715456)
		(width 0.0762)
		(layer "F.Cu")
		(net "M_G_CPU0_SB_DQS_DN<2>")
	)
	(arc
		(start 393.955524 -285.715456)
		(mid 394.051233 -285.689744)
		(end 394.140944 -285.647638)
		(width 0.0762)
		(layer "F.Cu")
		(net "M_G_CPU0_SB_DQS_DN<2>")
	)
	(segment
		(start 407.734008 -291.435536)
		(end 408.063446 -291.764974)
		(width 0.12954)
		(layer "F.Cu")
		(net "M_G_CPU0_SB_DQS_DN<1>")
	)
	(segment
		(start 415.637218 -294.767762)
		(end 415.954464 -295.085008)
		(width 0.101346)
		(layer "F.Cu")
		(net "M_G_CPU0_SB_DQS_DN<1>")
	)
	(segment
		(start 415.954464 -295.085008)
		(end 416.468052 -295.085008)
		(width 0.101346)
		(layer "F.Cu")
		(net "M_G_CPU0_SB_DQS_DN<1>")
	)
	(segment
		(start 413.93491 -294.660066)
		(end 414.25241 -294.342566)
		(width 0.101346)
		(layer "F.Cu")
		(net "M_G_CPU0_SB_DQS_DN<1>")
	)
	(segment
		(start 407.734008 -290.968684)
		(end 407.734008 -291.435536)
		(width 0.12954)
		(layer "F.Cu")
		(net "M_G_CPU0_SB_DQS_DN<1>")
	)
	(segment
		(start 395.840204 -280.545794)
		(end 395.859254 -280.545794)
		(width 0.0762)
		(layer "F.Cu")
		(net "M_G_CPU0_SB_DQS_DN<1>")
	)
	(segment
		(start 408.063446 -291.764974)
		(end 408.530298 -291.764974)
		(width 0.12954)
		(layer "F.Cu")
		(net "M_G_CPU0_SB_DQS_DN<1>")
	)
	(segment
		(start 408.870658 -292.105334)
		(end 408.870658 -292.572186)
		(width 0.12954)
		(layer "F.Cu")
		(net "M_G_CPU0_SB_DQS_DN<1>")
	)
	(segment
		(start 411.50667 -294.660066)
		(end 413.93491 -294.660066)
		(width 0.101346)
		(layer "F.Cu")
		(net "M_G_CPU0_SB_DQS_DN<1>")
	)
	(segment
		(start 398.686782 -280.545794)
		(end 408.29992 -290.158932)
		(width 0.12954)
		(layer "F.Cu")
		(net "M_G_CPU0_SB_DQS_DN<1>")
	)
	(segment
		(start 414.54959 -294.342566)
		(end 414.974786 -294.767762)
		(width 0.101346)
		(layer "F.Cu")
		(net "M_G_CPU0_SB_DQS_DN<1>")
	)
	(segment
		(start 410.695648 -294.397176)
		(end 411.24378 -294.397176)
		(width 0.12954)
		(layer "F.Cu")
		(net "M_G_CPU0_SB_DQS_DN<1>")
	)
	(segment
		(start 395.774164 -280.479754)
		(end 395.840204 -280.545794)
		(width 0.0762)
		(layer "F.Cu")
		(net "M_G_CPU0_SB_DQS_DN<1>")
	)
	(segment
		(start 408.29992 -290.402772)
		(end 407.734008 -290.968684)
		(width 0.12954)
		(layer "F.Cu")
		(net "M_G_CPU0_SB_DQS_DN<1>")
	)
	(segment
		(start 409.43657 -291.341302)
		(end 409.43657 -291.539422)
		(width 0.12954)
		(layer "F.Cu")
		(net "M_G_CPU0_SB_DQS_DN<1>")
	)
	(segment
		(start 395.859254 -280.545794)
		(end 398.686782 -280.545794)
		(width 0.12954)
		(layer "F.Cu")
		(net "M_G_CPU0_SB_DQS_DN<1>")
	)
	(segment
		(start 414.25241 -294.342566)
		(end 414.54959 -294.342566)
		(width 0.101346)
		(layer "F.Cu")
		(net "M_G_CPU0_SB_DQS_DN<1>")
	)
	(segment
		(start 408.870658 -292.572186)
		(end 410.695648 -294.397176)
		(width 0.12954)
		(layer "F.Cu")
		(net "M_G_CPU0_SB_DQS_DN<1>")
	)
	(segment
		(start 408.29992 -290.158932)
		(end 408.29992 -290.402772)
		(width 0.12954)
		(layer "F.Cu")
		(net "M_G_CPU0_SB_DQS_DN<1>")
	)
	(segment
		(start 411.24378 -294.397176)
		(end 411.50667 -294.660066)
		(width 0.12954)
		(layer "F.Cu")
		(net "M_G_CPU0_SB_DQS_DN<1>")
	)
	(segment
		(start 414.974786 -294.767762)
		(end 415.637218 -294.767762)
		(width 0.101346)
		(layer "F.Cu")
		(net "M_G_CPU0_SB_DQS_DN<1>")
	)
	(segment
		(start 409.29433 -291.199062)
		(end 409.43657 -291.341302)
		(width 0.12954)
		(layer "F.Cu")
		(net "M_G_CPU0_SB_DQS_DN<1>")
	)
	(segment
		(start 409.43657 -291.539422)
		(end 408.870658 -292.105334)
		(width 0.12954)
		(layer "F.Cu")
		(net "M_G_CPU0_SB_DQS_DN<1>")
	)
	(segment
		(start 394.327888 -280.737056)
		(end 395.270736 -280.737056)
		(width 0.0762)
		(layer "F.Cu")
		(net "M_G_CPU0_SB_DQS_DN<1>")
	)
	(segment
		(start 395.270736 -280.737056)
		(end 395.528038 -280.479754)
		(width 0.0762)
		(layer "F.Cu")
		(net "M_G_CPU0_SB_DQS_DN<1>")
	)
	(segment
		(start 408.530298 -291.764974)
		(end 409.09621 -291.199062)
		(width 0.12954)
		(layer "F.Cu")
		(net "M_G_CPU0_SB_DQS_DN<1>")
	)
	(segment
		(start 409.09621 -291.199062)
		(end 409.29433 -291.199062)
		(width 0.12954)
		(layer "F.Cu")
		(net "M_G_CPU0_SB_DQS_DN<1>")
	)
	(segment
		(start 395.528038 -280.479754)
		(end 395.774164 -280.479754)
		(width 0.0762)
		(layer "F.Cu")
		(net "M_G_CPU0_SB_DQS_DN<1>")
	)
	(arc
		(start 393.387834 -281.110182)
		(mid 393.631265 -280.940695)
		(end 393.916916 -280.860754)
		(width 0.0762)
		(layer "F.Cu")
		(net "M_G_CPU0_SB_DQS_DN<1>")
	)
	(arc
		(start 394.2969 -280.738326)
		(mid 394.312381 -280.73737)
		(end 394.327888 -280.737056)
		(width 0.0762)
		(layer "F.Cu")
		(net "M_G_CPU0_SB_DQS_DN<1>")
	)
	(arc
		(start 394.140944 -280.787602)
		(mid 394.216184 -280.754289)
		(end 394.2969 -280.738326)
		(width 0.0762)
		(layer "F.Cu")
		(net "M_G_CPU0_SB_DQS_DN<1>")
	)
	(arc
		(start 393.955524 -280.85542)
		(mid 394.051233 -280.829708)
		(end 394.140944 -280.787602)
		(width 0.0762)
		(layer "F.Cu")
		(net "M_G_CPU0_SB_DQS_DN<1>")
	)
	(arc
		(start 393.916916 -280.860754)
		(mid 393.936265 -280.858416)
		(end 393.955524 -280.85542)
		(width 0.0762)
		(layer "F.Cu")
		(net "M_G_CPU0_SB_DQS_DN<1>")
	)
	(segment
		(start 402.699728 -275.983192)
		(end 409.246832 -282.530296)
		(width 0.12954)
		(layer "F.Cu")
		(net "M_G_CPU0_SB_DQS_DN<0>")
	)
	(segment
		(start 414.25241 -284.992572)
		(end 414.51657 -284.992572)
		(width 0.101346)
		(layer "F.Cu")
		(net "M_G_CPU0_SB_DQS_DN<0>")
	)
	(segment
		(start 409.246832 -282.530296)
		(end 409.246832 -282.728924)
		(width 0.12954)
		(layer "F.Cu")
		(net "M_G_CPU0_SB_DQS_DN<0>")
	)
	(segment
		(start 409.00096 -283.440886)
		(end 409.332176 -283.772102)
		(width 0.12954)
		(layer "F.Cu")
		(net "M_G_CPU0_SB_DQS_DN<0>")
	)
	(segment
		(start 409.00096 -282.97505)
		(end 409.00096 -283.440886)
		(width 0.12954)
		(layer "F.Cu")
		(net "M_G_CPU0_SB_DQS_DN<0>")
	)
	(segment
		(start 410.554678 -283.838142)
		(end 410.554678 -284.72892)
		(width 0.12954)
		(layer "F.Cu")
		(net "M_G_CPU0_SB_DQS_DN<0>")
	)
	(segment
		(start 411.50667 -285.310072)
		(end 413.93491 -285.310072)
		(width 0.101346)
		(layer "F.Cu")
		(net "M_G_CPU0_SB_DQS_DN<0>")
	)
	(segment
		(start 395.859254 -275.983192)
		(end 402.699728 -275.983192)
		(width 0.12954)
		(layer "F.Cu")
		(net "M_G_CPU0_SB_DQS_DN<0>")
	)
	(segment
		(start 415.637218 -285.417768)
		(end 415.954464 -285.735014)
		(width 0.101346)
		(layer "F.Cu")
		(net "M_G_CPU0_SB_DQS_DN<0>")
	)
	(segment
		(start 409.332176 -283.772102)
		(end 409.797504 -283.771848)
		(width 0.12954)
		(layer "F.Cu")
		(net "M_G_CPU0_SB_DQS_DN<0>")
	)
	(segment
		(start 409.246832 -282.728924)
		(end 409.00096 -282.97505)
		(width 0.12954)
		(layer "F.Cu")
		(net "M_G_CPU0_SB_DQS_DN<0>")
	)
	(segment
		(start 411.24378 -285.047182)
		(end 411.50667 -285.310072)
		(width 0.12954)
		(layer "F.Cu")
		(net "M_G_CPU0_SB_DQS_DN<0>")
	)
	(segment
		(start 414.51657 -284.992572)
		(end 414.941766 -285.417768)
		(width 0.101346)
		(layer "F.Cu")
		(net "M_G_CPU0_SB_DQS_DN<0>")
	)
	(segment
		(start 409.797504 -283.771848)
		(end 410.04363 -283.525722)
		(width 0.12954)
		(layer "F.Cu")
		(net "M_G_CPU0_SB_DQS_DN<0>")
	)
	(segment
		(start 410.87294 -285.047182)
		(end 411.24378 -285.047182)
		(width 0.12954)
		(layer "F.Cu")
		(net "M_G_CPU0_SB_DQS_DN<0>")
	)
	(segment
		(start 415.954464 -285.735014)
		(end 416.468052 -285.735014)
		(width 0.101346)
		(layer "F.Cu")
		(net "M_G_CPU0_SB_DQS_DN<0>")
	)
	(segment
		(start 413.93491 -285.310072)
		(end 414.25241 -284.992572)
		(width 0.101346)
		(layer "F.Cu")
		(net "M_G_CPU0_SB_DQS_DN<0>")
	)
	(segment
		(start 410.242258 -283.525722)
		(end 410.554678 -283.838142)
		(width 0.12954)
		(layer "F.Cu")
		(net "M_G_CPU0_SB_DQS_DN<0>")
	)
	(segment
		(start 395.840204 -275.983192)
		(end 395.859254 -275.983192)
		(width 0.0762)
		(layer "F.Cu")
		(net "M_G_CPU0_SB_DQS_DN<0>")
	)
	(segment
		(start 395.242796 -275.87702)
		(end 395.282928 -275.917152)
		(width 0.0762)
		(layer "F.Cu")
		(net "M_G_CPU0_SB_DQS_DN<0>")
	)
	(segment
		(start 410.04363 -283.525722)
		(end 410.242258 -283.525722)
		(width 0.12954)
		(layer "F.Cu")
		(net "M_G_CPU0_SB_DQS_DN<0>")
	)
	(segment
		(start 395.774164 -275.917152)
		(end 395.840204 -275.983192)
		(width 0.0762)
		(layer "F.Cu")
		(net "M_G_CPU0_SB_DQS_DN<0>")
	)
	(segment
		(start 414.941766 -285.417768)
		(end 415.637218 -285.417768)
		(width 0.101346)
		(layer "F.Cu")
		(net "M_G_CPU0_SB_DQS_DN<0>")
	)
	(segment
		(start 410.554678 -284.72892)
		(end 410.87294 -285.047182)
		(width 0.12954)
		(layer "F.Cu")
		(net "M_G_CPU0_SB_DQS_DN<0>")
	)
	(segment
		(start 395.282928 -275.917152)
		(end 395.774164 -275.917152)
		(width 0.0762)
		(layer "F.Cu")
		(net "M_G_CPU0_SB_DQS_DN<0>")
	)
	(segment
		(start 394.327888 -275.87702)
		(end 395.242796 -275.87702)
		(width 0.0762)
		(layer "F.Cu")
		(net "M_G_CPU0_SB_DQS_DN<0>")
	)
	(arc
		(start 393.916916 -276.000718)
		(mid 393.936265 -275.99838)
		(end 393.955524 -275.995384)
		(width 0.0762)
		(layer "F.Cu")
		(net "M_G_CPU0_SB_DQS_DN<0>")
	)
	(arc
		(start 393.955524 -275.995384)
		(mid 394.051233 -275.969672)
		(end 394.140944 -275.927566)
		(width 0.0762)
		(layer "F.Cu")
		(net "M_G_CPU0_SB_DQS_DN<0>")
	)
	(arc
		(start 393.387834 -276.250146)
		(mid 393.631265 -276.080659)
		(end 393.916916 -276.000718)
		(width 0.0762)
		(layer "F.Cu")
		(net "M_G_CPU0_SB_DQS_DN<0>")
	)
	(arc
		(start 394.140944 -275.927566)
		(mid 394.216184 -275.894253)
		(end 394.2969 -275.87829)
		(width 0.0762)
		(layer "F.Cu")
		(net "M_G_CPU0_SB_DQS_DN<0>")
	)
	(arc
		(start 394.2969 -275.87829)
		(mid 394.312381 -275.877334)
		(end 394.327888 -275.87702)
		(width 0.0762)
		(layer "F.Cu")
		(net "M_G_CPU0_SB_DQS_DN<0>")
	)
	(segment
		(start 415.30397 -292.535102)
		(end 416.468052 -292.535102)
		(width 0.101346)
		(layer "F.Cu")
		(net "M_G_CPU0_SB_DQ<9>")
	)
	(segment
		(start 415.188654 -292.419786)
		(end 415.30397 -292.535102)
		(width 0.101346)
		(layer "F.Cu")
		(net "M_G_CPU0_SB_DQ<9>")
	)
	(segment
		(start 411.317694 -291.99205)
		(end 411.435804 -292.11016)
		(width 0.101346)
		(layer "F.Cu")
		(net "M_G_CPU0_SB_DQ<9>")
	)
	(segment
		(start 414.401254 -292.090348)
		(end 414.401254 -292.419786)
		(width 0.101346)
		(layer "F.Cu")
		(net "M_G_CPU0_SB_DQ<9>")
	)
	(segment
		(start 415.073338 -291.975032)
		(end 415.188654 -292.090348)
		(width 0.101346)
		(layer "F.Cu")
		(net "M_G_CPU0_SB_DQ<9>")
	)
	(segment
		(start 411.435804 -292.11016)
		(end 413.186118 -292.11016)
		(width 0.101346)
		(layer "F.Cu")
		(net "M_G_CPU0_SB_DQ<9>")
	)
	(segment
		(start 392.448034 -279.49017)
		(end 392.339576 -279.67686)
		(width 0.0762)
		(layer "F.Cu")
		(net "M_G_CPU0_SB_DQ<9>")
	)
	(segment
		(start 414.007554 -292.419786)
		(end 414.007554 -292.090348)
		(width 0.101346)
		(layer "F.Cu")
		(net "M_G_CPU0_SB_DQ<9>")
	)
	(segment
		(start 414.401254 -292.419786)
		(end 414.51657 -292.535102)
		(width 0.101346)
		(layer "F.Cu")
		(net "M_G_CPU0_SB_DQ<9>")
	)
	(segment
		(start 414.679638 -292.535102)
		(end 414.794954 -292.419786)
		(width 0.101346)
		(layer "F.Cu")
		(net "M_G_CPU0_SB_DQ<9>")
	)
	(segment
		(start 414.12287 -291.975032)
		(end 414.285938 -291.975032)
		(width 0.101346)
		(layer "F.Cu")
		(net "M_G_CPU0_SB_DQ<9>")
	)
	(segment
		(start 413.892238 -292.535102)
		(end 414.007554 -292.419786)
		(width 0.101346)
		(layer "F.Cu")
		(net "M_G_CPU0_SB_DQ<9>")
	)
	(segment
		(start 414.794954 -292.419786)
		(end 414.794954 -292.090348)
		(width 0.101346)
		(layer "F.Cu")
		(net "M_G_CPU0_SB_DQ<9>")
	)
	(segment
		(start 413.61106 -292.535102)
		(end 413.892238 -292.535102)
		(width 0.101346)
		(layer "F.Cu")
		(net "M_G_CPU0_SB_DQ<9>")
	)
	(segment
		(start 414.51657 -292.535102)
		(end 414.679638 -292.535102)
		(width 0.101346)
		(layer "F.Cu")
		(net "M_G_CPU0_SB_DQ<9>")
	)
	(segment
		(start 414.794954 -292.090348)
		(end 414.91027 -291.975032)
		(width 0.101346)
		(layer "F.Cu")
		(net "M_G_CPU0_SB_DQ<9>")
	)
	(segment
		(start 392.626596 -279.817576)
		(end 392.634978 -279.81275)
		(width 0.0762)
		(layer "F.Cu")
		(net "M_G_CPU0_SB_DQ<9>")
	)
	(segment
		(start 415.188654 -292.090348)
		(end 415.188654 -292.419786)
		(width 0.101346)
		(layer "F.Cu")
		(net "M_G_CPU0_SB_DQ<9>")
	)
	(segment
		(start 395.53261 -279.446228)
		(end 395.854428 -279.446228)
		(width 0.0762)
		(layer "F.Cu")
		(net "M_G_CPU0_SB_DQ<9>")
	)
	(segment
		(start 414.007554 -292.090348)
		(end 414.12287 -291.975032)
		(width 0.101346)
		(layer "F.Cu")
		(net "M_G_CPU0_SB_DQ<9>")
	)
	(segment
		(start 393.20089 -279.81275)
		(end 393.201144 -279.81275)
		(width 0.0762)
		(layer "F.Cu")
		(net "M_G_CPU0_SB_DQ<9>")
	)
	(segment
		(start 414.91027 -291.975032)
		(end 415.073338 -291.975032)
		(width 0.101346)
		(layer "F.Cu")
		(net "M_G_CPU0_SB_DQ<9>")
	)
	(segment
		(start 394.298424 -279.870916)
		(end 395.106906 -279.871932)
		(width 0.0762)
		(layer "F.Cu")
		(net "M_G_CPU0_SB_DQ<9>")
	)
	(segment
		(start 413.186118 -292.11016)
		(end 413.61106 -292.535102)
		(width 0.101346)
		(layer "F.Cu")
		(net "M_G_CPU0_SB_DQ<9>")
	)
	(segment
		(start 414.285938 -291.975032)
		(end 414.401254 -292.090348)
		(width 0.101346)
		(layer "F.Cu")
		(net "M_G_CPU0_SB_DQ<9>")
	)
	(segment
		(start 410.561028 -291.235384)
		(end 411.317694 -291.99205)
		(width 0.10668)
		(layer "F.Cu")
		(net "M_G_CPU0_SB_DQ<9>")
	)
	(segment
		(start 399.127218 -279.446228)
		(end 405.615902 -285.934912)
		(width 0.10668)
		(layer "F.Cu")
		(net "M_G_CPU0_SB_DQ<9>")
	)
	(segment
		(start 395.106906 -279.871932)
		(end 395.53261 -279.446228)
		(width 0.0762)
		(layer "F.Cu")
		(net "M_G_CPU0_SB_DQ<9>")
	)
	(segment
		(start 395.854428 -279.446228)
		(end 399.127218 -279.446228)
		(width 0.10668)
		(layer "F.Cu")
		(net "M_G_CPU0_SB_DQ<9>")
	)
	(segment
		(start 405.615902 -285.934912)
		(end 406.131014 -285.934912)
		(width 0.10668)
		(layer "F.Cu")
		(net "M_G_CPU0_SB_DQ<9>")
	)
	(segment
		(start 410.561028 -290.364926)
		(end 410.561028 -291.235384)
		(width 0.10668)
		(layer "F.Cu")
		(net "M_G_CPU0_SB_DQ<9>")
	)
	(segment
		(start 406.131014 -285.934912)
		(end 410.561028 -290.364926)
		(width 0.10668)
		(layer "F.Cu")
		(net "M_G_CPU0_SB_DQ<9>")
	)
	(arc
		(start 393.201144 -279.81275)
		(mid 393.388088 -279.863074)
		(end 393.575032 -279.81275)
		(width 0.0762)
		(layer "F.Cu")
		(net "M_G_CPU0_SB_DQ<9>")
	)
	(arc
		(start 392.491214 -279.860502)
		(mid 392.560968 -279.845545)
		(end 392.626596 -279.817576)
		(width 0.0762)
		(layer "F.Cu")
		(net "M_G_CPU0_SB_DQ<9>")
	)
	(arc
		(start 393.575032 -279.81275)
		(mid 393.857988 -279.736573)
		(end 394.140944 -279.81275)
		(width 0.0762)
		(layer "F.Cu")
		(net "M_G_CPU0_SB_DQ<9>")
	)
	(arc
		(start 394.140944 -279.81275)
		(mid 394.181638 -279.834969)
		(end 394.223494 -279.854914)
		(width 0.0762)
		(layer "F.Cu")
		(net "M_G_CPU0_SB_DQ<9>")
	)
	(arc
		(start 392.339576 -279.67686)
		(mid 392.365493 -279.809902)
		(end 392.491214 -279.860502)
		(width 0.0762)
		(layer "F.Cu")
		(net "M_G_CPU0_SB_DQ<9>")
	)
	(arc
		(start 392.634978 -279.81275)
		(mid 392.917934 -279.736573)
		(end 393.20089 -279.81275)
		(width 0.0762)
		(layer "F.Cu")
		(net "M_G_CPU0_SB_DQ<9>")
	)
	(arc
		(start 394.223494 -279.854914)
		(mid 394.260122 -279.866844)
		(end 394.298424 -279.870916)
		(width 0.0762)
		(layer "F.Cu")
		(net "M_G_CPU0_SB_DQ<9>")
	)
	(segment
		(start 404.372826 -283.213556)
		(end 404.537926 -283.213556)
		(width 0.10668)
		(layer "F.Cu")
		(net "M_G_CPU0_SB_DQ<8>")
	)
	(segment
		(start 407.736548 -286.223202)
		(end 407.64206 -286.31769)
		(width 0.10668)
		(layer "F.Cu")
		(net "M_G_CPU0_SB_DQ<8>")
	)
	(segment
		(start 406.607772 -285.094426)
		(end 406.513284 -285.188914)
		(width 0.10668)
		(layer "F.Cu")
		(net "M_G_CPU0_SB_DQ<8>")
	)
	(segment
		(start 415.023808 -291.260022)
		(end 415.44875 -290.83508)
		(width 0.101346)
		(layer "F.Cu")
		(net "M_G_CPU0_SB_DQ<8>")
	)
	(segment
		(start 411.241748 -290.95192)
		(end 411.387544 -291.097716)
		(width 0.10668)
		(layer "F.Cu")
		(net "M_G_CPU0_SB_DQ<8>")
	)
	(segment
		(start 404.35022 -282.836874)
		(end 404.255732 -282.931362)
		(width 0.10668)
		(layer "F.Cu")
		(net "M_G_CPU0_SB_DQ<8>")
	)
	(segment
		(start 404.233126 -282.55468)
		(end 404.35022 -282.671774)
		(width 0.10668)
		(layer "F.Cu")
		(net "M_G_CPU0_SB_DQ<8>")
	)
	(segment
		(start 407.64206 -286.31769)
		(end 407.64206 -286.48279)
		(width 0.10668)
		(layer "F.Cu")
		(net "M_G_CPU0_SB_DQ<8>")
	)
	(segment
		(start 415.44875 -290.83508)
		(end 416.468052 -290.83508)
		(width 0.101346)
		(layer "F.Cu")
		(net "M_G_CPU0_SB_DQ<8>")
	)
	(segment
		(start 403.785832 -282.107386)
		(end 403.785832 -282.272486)
		(width 0.10668)
		(layer "F.Cu")
		(net "M_G_CPU0_SB_DQ<8>")
	)
	(segment
		(start 405.478996 -283.80055)
		(end 405.478996 -283.96565)
		(width 0.10668)
		(layer "F.Cu")
		(net "M_G_CPU0_SB_DQ<8>")
	)
	(segment
		(start 407.194766 -286.035496)
		(end 407.359866 -286.035496)
		(width 0.10668)
		(layer "F.Cu")
		(net "M_G_CPU0_SB_DQ<8>")
	)
	(segment
		(start 407.359866 -286.035496)
		(end 407.454354 -285.941008)
		(width 0.10668)
		(layer "F.Cu")
		(net "M_G_CPU0_SB_DQ<8>")
	)
	(segment
		(start 405.948896 -284.624526)
		(end 405.948896 -284.789626)
		(width 0.10668)
		(layer "F.Cu")
		(net "M_G_CPU0_SB_DQ<8>")
	)
	(segment
		(start 405.501602 -284.342332)
		(end 405.666702 -284.342332)
		(width 0.10668)
		(layer "F.Cu")
		(net "M_G_CPU0_SB_DQ<8>")
	)
	(segment
		(start 405.948896 -284.789626)
		(end 406.06599 -284.90672)
		(width 0.10668)
		(layer "F.Cu")
		(net "M_G_CPU0_SB_DQ<8>")
	)
	(segment
		(start 407.736548 -286.058102)
		(end 407.736548 -286.223202)
		(width 0.10668)
		(layer "F.Cu")
		(net "M_G_CPU0_SB_DQ<8>")
	)
	(segment
		(start 405.361902 -283.683456)
		(end 405.478996 -283.80055)
		(width 0.10668)
		(layer "F.Cu")
		(net "M_G_CPU0_SB_DQ<8>")
	)
	(segment
		(start 406.490678 -284.812232)
		(end 406.607772 -284.929326)
		(width 0.10668)
		(layer "F.Cu")
		(net "M_G_CPU0_SB_DQ<8>")
	)
	(segment
		(start 406.607772 -284.929326)
		(end 406.607772 -285.094426)
		(width 0.10668)
		(layer "F.Cu")
		(net "M_G_CPU0_SB_DQ<8>")
	)
	(segment
		(start 403.973538 -282.649168)
		(end 404.068026 -282.55468)
		(width 0.10668)
		(layer "F.Cu")
		(net "M_G_CPU0_SB_DQ<8>")
	)
	(segment
		(start 406.889966 -285.37662)
		(end 407.055066 -285.37662)
		(width 0.10668)
		(layer "F.Cu")
		(net "M_G_CPU0_SB_DQ<8>")
	)
	(segment
		(start 405.384508 -284.225238)
		(end 405.501602 -284.342332)
		(width 0.10668)
		(layer "F.Cu")
		(net "M_G_CPU0_SB_DQ<8>")
	)
	(segment
		(start 405.76119 -284.247844)
		(end 405.92629 -284.247844)
		(width 0.10668)
		(layer "F.Cu")
		(net "M_G_CPU0_SB_DQ<8>")
	)
	(segment
		(start 407.077672 -285.918402)
		(end 407.194766 -286.035496)
		(width 0.10668)
		(layer "F.Cu")
		(net "M_G_CPU0_SB_DQ<8>")
	)
	(segment
		(start 406.513284 -285.188914)
		(end 406.513284 -285.354014)
		(width 0.10668)
		(layer "F.Cu")
		(net "M_G_CPU0_SB_DQ<8>")
	)
	(segment
		(start 404.537926 -283.213556)
		(end 404.632414 -283.119068)
		(width 0.10668)
		(layer "F.Cu")
		(net "M_G_CPU0_SB_DQ<8>")
	)
	(segment
		(start 406.043384 -284.530038)
		(end 405.948896 -284.624526)
		(width 0.10668)
		(layer "F.Cu")
		(net "M_G_CPU0_SB_DQ<8>")
	)
	(segment
		(start 404.255732 -283.096462)
		(end 404.372826 -283.213556)
		(width 0.10668)
		(layer "F.Cu")
		(net "M_G_CPU0_SB_DQ<8>")
	)
	(segment
		(start 407.17216 -285.493714)
		(end 407.17216 -285.658814)
		(width 0.10668)
		(layer "F.Cu")
		(net "M_G_CPU0_SB_DQ<8>")
	)
	(segment
		(start 404.632414 -283.119068)
		(end 404.797514 -283.119068)
		(width 0.10668)
		(layer "F.Cu")
		(net "M_G_CPU0_SB_DQ<8>")
	)
	(segment
		(start 404.82012 -283.49575)
		(end 404.82012 -283.66085)
		(width 0.10668)
		(layer "F.Cu")
		(net "M_G_CPU0_SB_DQ<8>")
	)
	(segment
		(start 404.35022 -282.671774)
		(end 404.35022 -282.836874)
		(width 0.10668)
		(layer "F.Cu")
		(net "M_G_CPU0_SB_DQ<8>")
	)
	(segment
		(start 407.619454 -285.941008)
		(end 407.736548 -286.058102)
		(width 0.10668)
		(layer "F.Cu")
		(net "M_G_CPU0_SB_DQ<8>")
	)
	(segment
		(start 405.102314 -283.777944)
		(end 405.196802 -283.683456)
		(width 0.10668)
		(layer "F.Cu")
		(net "M_G_CPU0_SB_DQ<8>")
	)
	(segment
		(start 405.196802 -283.683456)
		(end 405.361902 -283.683456)
		(width 0.10668)
		(layer "F.Cu")
		(net "M_G_CPU0_SB_DQ<8>")
	)
	(segment
		(start 403.785832 -282.272486)
		(end 403.691344 -282.366974)
		(width 0.10668)
		(layer "F.Cu")
		(net "M_G_CPU0_SB_DQ<8>")
	)
	(segment
		(start 400.440398 -278.761952)
		(end 403.785832 -282.107386)
		(width 0.10668)
		(layer "F.Cu")
		(net "M_G_CPU0_SB_DQ<8>")
	)
	(segment
		(start 406.23109 -284.90672)
		(end 406.325578 -284.812232)
		(width 0.10668)
		(layer "F.Cu")
		(net "M_G_CPU0_SB_DQ<8>")
	)
	(segment
		(start 407.64206 -286.48279)
		(end 411.241748 -290.082478)
		(width 0.10668)
		(layer "F.Cu")
		(net "M_G_CPU0_SB_DQ<8>")
	)
	(segment
		(start 407.055066 -285.37662)
		(end 407.17216 -285.493714)
		(width 0.10668)
		(layer "F.Cu")
		(net "M_G_CPU0_SB_DQ<8>")
	)
	(segment
		(start 395.837156 -278.761952)
		(end 400.440398 -278.761952)
		(width 0.10668)
		(layer "F.Cu")
		(net "M_G_CPU0_SB_DQ<8>")
	)
	(segment
		(start 404.82012 -283.66085)
		(end 404.937214 -283.777944)
		(width 0.10668)
		(layer "F.Cu")
		(net "M_G_CPU0_SB_DQ<8>")
	)
	(segment
		(start 404.914608 -283.236162)
		(end 404.914608 -283.401262)
		(width 0.10668)
		(layer "F.Cu")
		(net "M_G_CPU0_SB_DQ<8>")
	)
	(segment
		(start 406.06599 -284.90672)
		(end 406.23109 -284.90672)
		(width 0.10668)
		(layer "F.Cu")
		(net "M_G_CPU0_SB_DQ<8>")
	)
	(segment
		(start 411.241748 -290.082478)
		(end 411.241748 -290.95192)
		(width 0.10668)
		(layer "F.Cu")
		(net "M_G_CPU0_SB_DQ<8>")
	)
	(segment
		(start 405.92629 -284.247844)
		(end 406.043384 -284.364938)
		(width 0.10668)
		(layer "F.Cu")
		(net "M_G_CPU0_SB_DQ<8>")
	)
	(segment
		(start 393.857988 -278.680164)
		(end 393.755626 -278.85644)
		(width 0.0762)
		(layer "F.Cu")
		(net "M_G_CPU0_SB_DQ<8>")
	)
	(segment
		(start 405.666702 -284.342332)
		(end 405.76119 -284.247844)
		(width 0.10668)
		(layer "F.Cu")
		(net "M_G_CPU0_SB_DQ<8>")
	)
	(segment
		(start 406.513284 -285.354014)
		(end 406.630378 -285.471108)
		(width 0.10668)
		(layer "F.Cu")
		(net "M_G_CPU0_SB_DQ<8>")
	)
	(segment
		(start 403.691344 -282.366974)
		(end 403.691344 -282.532074)
		(width 0.10668)
		(layer "F.Cu")
		(net "M_G_CPU0_SB_DQ<8>")
	)
	(segment
		(start 404.255732 -282.931362)
		(end 404.255732 -283.096462)
		(width 0.10668)
		(layer "F.Cu")
		(net "M_G_CPU0_SB_DQ<8>")
	)
	(segment
		(start 403.808438 -282.649168)
		(end 403.973538 -282.649168)
		(width 0.10668)
		(layer "F.Cu")
		(net "M_G_CPU0_SB_DQ<8>")
	)
	(segment
		(start 395.066012 -278.926544)
		(end 395.230604 -278.761952)
		(width 0.0762)
		(layer "F.Cu")
		(net "M_G_CPU0_SB_DQ<8>")
	)
	(segment
		(start 407.454354 -285.941008)
		(end 407.619454 -285.941008)
		(width 0.10668)
		(layer "F.Cu")
		(net "M_G_CPU0_SB_DQ<8>")
	)
	(segment
		(start 394.03655 -279.00757)
		(end 394.044932 -279.002744)
		(width 0.0762)
		(layer "F.Cu")
		(net "M_G_CPU0_SB_DQ<8>")
	)
	(segment
		(start 394.327634 -278.926544)
		(end 395.066012 -278.926544)
		(width 0.0762)
		(layer "F.Cu")
		(net "M_G_CPU0_SB_DQ<8>")
	)
	(segment
		(start 405.478996 -283.96565)
		(end 405.384508 -284.060138)
		(width 0.10668)
		(layer "F.Cu")
		(net "M_G_CPU0_SB_DQ<8>")
	)
	(segment
		(start 405.384508 -284.060138)
		(end 405.384508 -284.225238)
		(width 0.10668)
		(layer "F.Cu")
		(net "M_G_CPU0_SB_DQ<8>")
	)
	(segment
		(start 407.17216 -285.658814)
		(end 407.077672 -285.753302)
		(width 0.10668)
		(layer "F.Cu")
		(net "M_G_CPU0_SB_DQ<8>")
	)
	(segment
		(start 411.387544 -291.097716)
		(end 411.54985 -291.260022)
		(width 0.101346)
		(layer "F.Cu")
		(net "M_G_CPU0_SB_DQ<8>")
	)
	(segment
		(start 404.068026 -282.55468)
		(end 404.233126 -282.55468)
		(width 0.10668)
		(layer "F.Cu")
		(net "M_G_CPU0_SB_DQ<8>")
	)
	(segment
		(start 406.325578 -284.812232)
		(end 406.490678 -284.812232)
		(width 0.10668)
		(layer "F.Cu")
		(net "M_G_CPU0_SB_DQ<8>")
	)
	(segment
		(start 403.691344 -282.532074)
		(end 403.808438 -282.649168)
		(width 0.10668)
		(layer "F.Cu")
		(net "M_G_CPU0_SB_DQ<8>")
	)
	(segment
		(start 404.797514 -283.119068)
		(end 404.914608 -283.236162)
		(width 0.10668)
		(layer "F.Cu")
		(net "M_G_CPU0_SB_DQ<8>")
	)
	(segment
		(start 411.54985 -291.260022)
		(end 415.023808 -291.260022)
		(width 0.101346)
		(layer "F.Cu")
		(net "M_G_CPU0_SB_DQ<8>")
	)
	(segment
		(start 404.937214 -283.777944)
		(end 405.102314 -283.777944)
		(width 0.10668)
		(layer "F.Cu")
		(net "M_G_CPU0_SB_DQ<8>")
	)
	(segment
		(start 395.230604 -278.761952)
		(end 395.837156 -278.761952)
		(width 0.0762)
		(layer "F.Cu")
		(net "M_G_CPU0_SB_DQ<8>")
	)
	(segment
		(start 406.630378 -285.471108)
		(end 406.795478 -285.471108)
		(width 0.10668)
		(layer "F.Cu")
		(net "M_G_CPU0_SB_DQ<8>")
	)
	(segment
		(start 404.914608 -283.401262)
		(end 404.82012 -283.49575)
		(width 0.10668)
		(layer "F.Cu")
		(net "M_G_CPU0_SB_DQ<8>")
	)
	(segment
		(start 406.043384 -284.364938)
		(end 406.043384 -284.530038)
		(width 0.10668)
		(layer "F.Cu")
		(net "M_G_CPU0_SB_DQ<8>")
	)
	(segment
		(start 406.795478 -285.471108)
		(end 406.889966 -285.37662)
		(width 0.10668)
		(layer "F.Cu")
		(net "M_G_CPU0_SB_DQ<8>")
	)
	(segment
		(start 407.077672 -285.753302)
		(end 407.077672 -285.918402)
		(width 0.10668)
		(layer "F.Cu")
		(net "M_G_CPU0_SB_DQ<8>")
	)
	(arc
		(start 394.044932 -279.002744)
		(mid 394.158656 -278.952443)
		(end 394.280644 -278.928322)
		(width 0.0762)
		(layer "F.Cu")
		(net "M_G_CPU0_SB_DQ<8>")
	)
	(arc
		(start 393.922504 -279.047448)
		(mid 393.98115 -279.032155)
		(end 394.03655 -279.00757)
		(width 0.0762)
		(layer "F.Cu")
		(net "M_G_CPU0_SB_DQ<8>")
	)
	(arc
		(start 394.280644 -278.928322)
		(mid 394.304121 -278.926946)
		(end 394.327634 -278.926544)
		(width 0.0762)
		(layer "F.Cu")
		(net "M_G_CPU0_SB_DQ<8>")
	)
	(arc
		(start 393.755626 -278.85644)
		(mid 393.785255 -278.998927)
		(end 393.922504 -279.047448)
		(width 0.0762)
		(layer "F.Cu")
		(net "M_G_CPU0_SB_DQ<8>")
	)
	(segment
		(start 410.626052 -288.276792)
		(end 410.626052 -288.441638)
		(width 0.10668)
		(layer "F.Cu")
		(net "M_G_CPU0_SB_DQ<7>")
	)
	(segment
		(start 395.68882 -278.273002)
		(end 395.937486 -278.273002)
		(width 0.0762)
		(layer "F.Cu")
		(net "M_G_CPU0_SB_DQ<7>")
	)
	(segment
		(start 409.390596 -287.584642)
		(end 409.50769 -287.701736)
		(width 0.10668)
		(layer "F.Cu")
		(net "M_G_CPU0_SB_DQ<7>")
	)
	(segment
		(start 410.343858 -288.159698)
		(end 410.508958 -288.159698)
		(width 0.10668)
		(layer "F.Cu")
		(net "M_G_CPU0_SB_DQ<7>")
	)
	(segment
		(start 408.815794 -286.466534)
		(end 408.932888 -286.583628)
		(width 0.10668)
		(layer "F.Cu")
		(net "M_G_CPU0_SB_DQ<7>")
	)
	(segment
		(start 410.801566 -288.830512)
		(end 410.908246 -288.724086)
		(width 0.10668)
		(layer "F.Cu")
		(net "M_G_CPU0_SB_DQ<7>")
	)
	(segment
		(start 394.03655 -278.352758)
		(end 394.044932 -278.357584)
		(width 0.0762)
		(layer "F.Cu")
		(net "M_G_CPU0_SB_DQ<7>")
	)
	(segment
		(start 408.650694 -286.466534)
		(end 408.815794 -286.466534)
		(width 0.10668)
		(layer "F.Cu")
		(net "M_G_CPU0_SB_DQ<7>")
	)
	(segment
		(start 395.937486 -278.273002)
		(end 400.631152 -278.273002)
		(width 0.10668)
		(layer "F.Cu")
		(net "M_G_CPU0_SB_DQ<7>")
	)
	(segment
		(start 408.826208 -286.855154)
		(end 408.826208 -287.020254)
		(width 0.10668)
		(layer "F.Cu")
		(net "M_G_CPU0_SB_DQ<7>")
	)
	(segment
		(start 411.799786 -289.985196)
		(end 412.367984 -289.985196)
		(width 0.10668)
		(layer "F.Cu")
		(net "M_G_CPU0_SB_DQ<7>")
	)
	(segment
		(start 410.908246 -288.724086)
		(end 411.073346 -288.724086)
		(width 0.10668)
		(layer "F.Cu")
		(net "M_G_CPU0_SB_DQ<7>")
	)
	(segment
		(start 409.497276 -287.148016)
		(end 409.497276 -287.312862)
		(width 0.10668)
		(layer "F.Cu")
		(net "M_G_CPU0_SB_DQ<7>")
	)
	(segment
		(start 408.943302 -287.137348)
		(end 409.108402 -287.137348)
		(width 0.10668)
		(layer "F.Cu")
		(net "M_G_CPU0_SB_DQ<7>")
	)
	(segment
		(start 400.631152 -278.273002)
		(end 407.69921 -285.34106)
		(width 0.10668)
		(layer "F.Cu")
		(net "M_G_CPU0_SB_DQ<7>")
	)
	(segment
		(start 409.497276 -287.312862)
		(end 409.390596 -287.419542)
		(width 0.10668)
		(layer "F.Cu")
		(net "M_G_CPU0_SB_DQ<7>")
	)
	(segment
		(start 409.215082 -287.030922)
		(end 409.380182 -287.030922)
		(width 0.10668)
		(layer "F.Cu")
		(net "M_G_CPU0_SB_DQ<7>")
	)
	(segment
		(start 408.544014 -286.57296)
		(end 408.650694 -286.466534)
		(width 0.10668)
		(layer "F.Cu")
		(net "M_G_CPU0_SB_DQ<7>")
	)
	(segment
		(start 408.26182 -286.290766)
		(end 408.26182 -286.455866)
		(width 0.10668)
		(layer "F.Cu")
		(net "M_G_CPU0_SB_DQ<7>")
	)
	(segment
		(start 409.380182 -287.030922)
		(end 409.497276 -287.148016)
		(width 0.10668)
		(layer "F.Cu")
		(net "M_G_CPU0_SB_DQ<7>")
	)
	(segment
		(start 408.3685 -286.184086)
		(end 408.26182 -286.290766)
		(width 0.10668)
		(layer "F.Cu")
		(net "M_G_CPU0_SB_DQ<7>")
	)
	(segment
		(start 409.77947 -287.59531)
		(end 409.94457 -287.59531)
		(width 0.10668)
		(layer "F.Cu")
		(net "M_G_CPU0_SB_DQ<7>")
	)
	(segment
		(start 408.826208 -287.020254)
		(end 408.943302 -287.137348)
		(width 0.10668)
		(layer "F.Cu")
		(net "M_G_CPU0_SB_DQ<7>")
	)
	(segment
		(start 411.202632 -289.388042)
		(end 411.799786 -289.985196)
		(width 0.10668)
		(layer "F.Cu")
		(net "M_G_CPU0_SB_DQ<7>")
	)
	(segment
		(start 409.50769 -287.701736)
		(end 409.67279 -287.701736)
		(width 0.10668)
		(layer "F.Cu")
		(net "M_G_CPU0_SB_DQ<7>")
	)
	(segment
		(start 410.636466 -288.830512)
		(end 410.801566 -288.830512)
		(width 0.10668)
		(layer "F.Cu")
		(net "M_G_CPU0_SB_DQ<7>")
	)
	(segment
		(start 410.626052 -288.441638)
		(end 410.519372 -288.548318)
		(width 0.10668)
		(layer "F.Cu")
		(net "M_G_CPU0_SB_DQ<7>")
	)
	(segment
		(start 409.108402 -287.137348)
		(end 409.215082 -287.030922)
		(width 0.10668)
		(layer "F.Cu")
		(net "M_G_CPU0_SB_DQ<7>")
	)
	(segment
		(start 408.378914 -286.57296)
		(end 408.544014 -286.57296)
		(width 0.10668)
		(layer "F.Cu")
		(net "M_G_CPU0_SB_DQ<7>")
	)
	(segment
		(start 408.932888 -286.583628)
		(end 408.932888 -286.748474)
		(width 0.10668)
		(layer "F.Cu")
		(net "M_G_CPU0_SB_DQ<7>")
	)
	(segment
		(start 409.94457 -287.59531)
		(end 410.061664 -287.712404)
		(width 0.10668)
		(layer "F.Cu")
		(net "M_G_CPU0_SB_DQ<7>")
	)
	(segment
		(start 409.390596 -287.419542)
		(end 409.390596 -287.584642)
		(width 0.10668)
		(layer "F.Cu")
		(net "M_G_CPU0_SB_DQ<7>")
	)
	(segment
		(start 410.061664 -287.712404)
		(end 410.061664 -287.87725)
		(width 0.10668)
		(layer "F.Cu")
		(net "M_G_CPU0_SB_DQ<7>")
	)
	(segment
		(start 409.954984 -288.14903)
		(end 410.072078 -288.266124)
		(width 0.10668)
		(layer "F.Cu")
		(net "M_G_CPU0_SB_DQ<7>")
	)
	(segment
		(start 410.061664 -287.87725)
		(end 409.954984 -287.98393)
		(width 0.10668)
		(layer "F.Cu")
		(net "M_G_CPU0_SB_DQ<7>")
	)
	(segment
		(start 408.26182 -286.455866)
		(end 408.378914 -286.57296)
		(width 0.10668)
		(layer "F.Cu")
		(net "M_G_CPU0_SB_DQ<7>")
	)
	(segment
		(start 410.519372 -288.713418)
		(end 410.636466 -288.830512)
		(width 0.10668)
		(layer "F.Cu")
		(net "M_G_CPU0_SB_DQ<7>")
	)
	(segment
		(start 410.519372 -288.548318)
		(end 410.519372 -288.713418)
		(width 0.10668)
		(layer "F.Cu")
		(net "M_G_CPU0_SB_DQ<7>")
	)
	(segment
		(start 408.3685 -286.01924)
		(end 408.3685 -286.184086)
		(width 0.10668)
		(layer "F.Cu")
		(net "M_G_CPU0_SB_DQ<7>")
	)
	(segment
		(start 410.237178 -288.266124)
		(end 410.343858 -288.159698)
		(width 0.10668)
		(layer "F.Cu")
		(net "M_G_CPU0_SB_DQ<7>")
	)
	(segment
		(start 407.69921 -285.34995)
		(end 408.3685 -286.01924)
		(width 0.10668)
		(layer "F.Cu")
		(net "M_G_CPU0_SB_DQ<7>")
	)
	(segment
		(start 411.073346 -288.724086)
		(end 411.202632 -288.853372)
		(width 0.10668)
		(layer "F.Cu")
		(net "M_G_CPU0_SB_DQ<7>")
	)
	(segment
		(start 411.202632 -288.853372)
		(end 411.202632 -289.388042)
		(width 0.10668)
		(layer "F.Cu")
		(net "M_G_CPU0_SB_DQ<7>")
	)
	(segment
		(start 409.954984 -287.98393)
		(end 409.954984 -288.14903)
		(width 0.10668)
		(layer "F.Cu")
		(net "M_G_CPU0_SB_DQ<7>")
	)
	(segment
		(start 409.67279 -287.701736)
		(end 409.77947 -287.59531)
		(width 0.10668)
		(layer "F.Cu")
		(net "M_G_CPU0_SB_DQ<7>")
	)
	(segment
		(start 395.500352 -278.46147)
		(end 395.68882 -278.273002)
		(width 0.0762)
		(layer "F.Cu")
		(net "M_G_CPU0_SB_DQ<7>")
	)
	(segment
		(start 394.331698 -278.46147)
		(end 395.500352 -278.46147)
		(width 0.0762)
		(layer "F.Cu")
		(net "M_G_CPU0_SB_DQ<7>")
	)
	(segment
		(start 408.932888 -286.748474)
		(end 408.826208 -286.855154)
		(width 0.10668)
		(layer "F.Cu")
		(net "M_G_CPU0_SB_DQ<7>")
	)
	(segment
		(start 407.69921 -285.34106)
		(end 407.69921 -285.34995)
		(width 0.10668)
		(layer "F.Cu")
		(net "M_G_CPU0_SB_DQ<7>")
	)
	(segment
		(start 410.508958 -288.159698)
		(end 410.626052 -288.276792)
		(width 0.10668)
		(layer "F.Cu")
		(net "M_G_CPU0_SB_DQ<7>")
	)
	(segment
		(start 410.072078 -288.266124)
		(end 410.237178 -288.266124)
		(width 0.10668)
		(layer "F.Cu")
		(net "M_G_CPU0_SB_DQ<7>")
	)
	(arc
		(start 391.97788 -278.680164)
		(mid 392.173229 -278.496345)
		(end 392.434064 -278.433784)
		(width 0.0762)
		(layer "F.Cu")
		(net "M_G_CPU0_SB_DQ<7>")
	)
	(arc
		(start 393.104878 -278.357584)
		(mid 393.387834 -278.433761)
		(end 393.67079 -278.357584)
		(width 0.0762)
		(layer "F.Cu")
		(net "M_G_CPU0_SB_DQ<7>")
	)
	(arc
		(start 392.434064 -278.433784)
		(mid 392.587813 -278.416275)
		(end 392.73099 -278.357584)
		(width 0.0762)
		(layer "F.Cu")
		(net "M_G_CPU0_SB_DQ<7>")
	)
	(arc
		(start 392.73099 -278.357584)
		(mid 392.917934 -278.307329)
		(end 393.104878 -278.357584)
		(width 0.0762)
		(layer "F.Cu")
		(net "M_G_CPU0_SB_DQ<7>")
	)
	(arc
		(start 394.256006 -278.450294)
		(mid 394.293432 -278.458733)
		(end 394.331698 -278.46147)
		(width 0.0762)
		(layer "F.Cu")
		(net "M_G_CPU0_SB_DQ<7>")
	)
	(arc
		(start 394.044932 -278.357584)
		(mid 394.147826 -278.409956)
		(end 394.256006 -278.450294)
		(width 0.0762)
		(layer "F.Cu")
		(net "M_G_CPU0_SB_DQ<7>")
	)
	(arc
		(start 393.67079 -278.357584)
		(mid 393.853041 -278.307234)
		(end 394.03655 -278.352758)
		(width 0.0762)
		(layer "F.Cu")
		(net "M_G_CPU0_SB_DQ<7>")
	)
	(segment
		(start 401.979638 -277.530052)
		(end 402.096732 -277.647146)
		(width 0.10668)
		(layer "F.Cu")
		(net "M_G_CPU0_SB_DQ<6>")
	)
	(segment
		(start 402.300694 -278.73706)
		(end 402.300694 -278.90216)
		(width 0.10668)
		(layer "F.Cu")
		(net "M_G_CPU0_SB_DQ<6>")
	)
	(segment
		(start 401.454112 -277.890478)
		(end 401.814538 -277.530052)
		(width 0.10668)
		(layer "F.Cu")
		(net "M_G_CPU0_SB_DQ<6>")
	)
	(segment
		(start 402.417788 -279.019254)
		(end 402.582888 -279.019254)
		(width 0.10668)
		(layer "F.Cu")
		(net "M_G_CPU0_SB_DQ<6>")
	)
	(segment
		(start 402.66112 -278.211534)
		(end 402.66112 -278.376634)
		(width 0.10668)
		(layer "F.Cu")
		(net "M_G_CPU0_SB_DQ<6>")
	)
	(segment
		(start 401.736306 -278.337772)
		(end 401.8534 -278.454866)
		(width 0.10668)
		(layer "F.Cu")
		(net "M_G_CPU0_SB_DQ<6>")
	)
	(segment
		(start 403.703536 -279.42667)
		(end 403.703536 -279.59177)
		(width 0.10668)
		(layer "F.Cu")
		(net "M_G_CPU0_SB_DQ<6>")
	)
	(segment
		(start 405.953722 -282.555188)
		(end 405.953722 -282.55722)
		(width 0.10668)
		(layer "F.Cu")
		(net "M_G_CPU0_SB_DQ<6>")
	)
	(segment
		(start 395.611858 -277.497032)
		(end 395.627098 -277.512272)
		(width 0.0762)
		(layer "F.Cu")
		(net "M_G_CPU0_SB_DQ<6>")
	)
	(segment
		(start 403.147276 -279.583642)
		(end 403.421342 -279.309576)
		(width 0.10668)
		(layer "F.Cu")
		(net "M_G_CPU0_SB_DQ<6>")
	)
	(segment
		(start 402.582888 -279.019254)
		(end 402.943314 -278.658828)
		(width 0.10668)
		(layer "F.Cu")
		(net "M_G_CPU0_SB_DQ<6>")
	)
	(segment
		(start 403.586442 -279.309576)
		(end 403.703536 -279.42667)
		(width 0.10668)
		(layer "F.Cu")
		(net "M_G_CPU0_SB_DQ<6>")
	)
	(segment
		(start 402.096732 -277.647146)
		(end 402.096732 -277.812246)
		(width 0.10668)
		(layer "F.Cu")
		(net "M_G_CPU0_SB_DQ<6>")
	)
	(segment
		(start 401.8534 -278.454866)
		(end 402.0185 -278.454866)
		(width 0.10668)
		(layer "F.Cu")
		(net "M_G_CPU0_SB_DQ<6>")
	)
	(segment
		(start 402.865082 -279.301448)
		(end 402.865082 -279.466548)
		(width 0.10668)
		(layer "F.Cu")
		(net "M_G_CPU0_SB_DQ<6>")
	)
	(segment
		(start 395.627098 -277.512272)
		(end 400.910806 -277.512272)
		(width 0.10668)
		(layer "F.Cu")
		(net "M_G_CPU0_SB_DQ<6>")
	)
	(segment
		(start 403.225508 -278.941022)
		(end 402.865082 -279.301448)
		(width 0.10668)
		(layer "F.Cu")
		(net "M_G_CPU0_SB_DQ<6>")
	)
	(segment
		(start 402.378926 -278.09444)
		(end 402.544026 -278.09444)
		(width 0.10668)
		(layer "F.Cu")
		(net "M_G_CPU0_SB_DQ<6>")
	)
	(segment
		(start 394.327888 -277.497032)
		(end 395.611858 -277.497032)
		(width 0.0762)
		(layer "F.Cu")
		(net "M_G_CPU0_SB_DQ<6>")
	)
	(segment
		(start 403.42947 -280.030936)
		(end 405.953722 -282.555188)
		(width 0.10668)
		(layer "F.Cu")
		(net "M_G_CPU0_SB_DQ<6>")
	)
	(segment
		(start 403.225508 -278.775922)
		(end 403.225508 -278.941022)
		(width 0.10668)
		(layer "F.Cu")
		(net "M_G_CPU0_SB_DQ<6>")
	)
	(segment
		(start 400.910806 -277.512272)
		(end 401.289012 -277.890478)
		(width 0.10668)
		(layer "F.Cu")
		(net "M_G_CPU0_SB_DQ<6>")
	)
	(segment
		(start 405.953722 -282.55722)
		(end 411.681676 -288.285174)
		(width 0.10668)
		(layer "F.Cu")
		(net "M_G_CPU0_SB_DQ<6>")
	)
	(segment
		(start 403.703536 -279.59177)
		(end 403.42947 -279.865836)
		(width 0.10668)
		(layer "F.Cu")
		(net "M_G_CPU0_SB_DQ<6>")
	)
	(segment
		(start 401.736306 -278.172672)
		(end 401.736306 -278.337772)
		(width 0.10668)
		(layer "F.Cu")
		(net "M_G_CPU0_SB_DQ<6>")
	)
	(segment
		(start 401.289012 -277.890478)
		(end 401.454112 -277.890478)
		(width 0.10668)
		(layer "F.Cu")
		(net "M_G_CPU0_SB_DQ<6>")
	)
	(segment
		(start 403.421342 -279.309576)
		(end 403.586442 -279.309576)
		(width 0.10668)
		(layer "F.Cu")
		(net "M_G_CPU0_SB_DQ<6>")
	)
	(segment
		(start 411.681676 -288.285174)
		(end 412.367984 -288.285174)
		(width 0.10668)
		(layer "F.Cu")
		(net "M_G_CPU0_SB_DQ<6>")
	)
	(segment
		(start 403.108414 -278.658828)
		(end 403.225508 -278.775922)
		(width 0.10668)
		(layer "F.Cu")
		(net "M_G_CPU0_SB_DQ<6>")
	)
	(segment
		(start 402.096732 -277.812246)
		(end 401.736306 -278.172672)
		(width 0.10668)
		(layer "F.Cu")
		(net "M_G_CPU0_SB_DQ<6>")
	)
	(segment
		(start 401.814538 -277.530052)
		(end 401.979638 -277.530052)
		(width 0.10668)
		(layer "F.Cu")
		(net "M_G_CPU0_SB_DQ<6>")
	)
	(segment
		(start 403.42947 -279.865836)
		(end 403.42947 -280.030936)
		(width 0.10668)
		(layer "F.Cu")
		(net "M_G_CPU0_SB_DQ<6>")
	)
	(segment
		(start 402.300694 -278.90216)
		(end 402.417788 -279.019254)
		(width 0.10668)
		(layer "F.Cu")
		(net "M_G_CPU0_SB_DQ<6>")
	)
	(segment
		(start 402.0185 -278.454866)
		(end 402.378926 -278.09444)
		(width 0.10668)
		(layer "F.Cu")
		(net "M_G_CPU0_SB_DQ<6>")
	)
	(segment
		(start 402.544026 -278.09444)
		(end 402.66112 -278.211534)
		(width 0.10668)
		(layer "F.Cu")
		(net "M_G_CPU0_SB_DQ<6>")
	)
	(segment
		(start 402.982176 -279.583642)
		(end 403.147276 -279.583642)
		(width 0.10668)
		(layer "F.Cu")
		(net "M_G_CPU0_SB_DQ<6>")
	)
	(segment
		(start 402.865082 -279.466548)
		(end 402.982176 -279.583642)
		(width 0.10668)
		(layer "F.Cu")
		(net "M_G_CPU0_SB_DQ<6>")
	)
	(segment
		(start 402.66112 -278.376634)
		(end 402.300694 -278.73706)
		(width 0.10668)
		(layer "F.Cu")
		(net "M_G_CPU0_SB_DQ<6>")
	)
	(segment
		(start 402.943314 -278.658828)
		(end 403.108414 -278.658828)
		(width 0.10668)
		(layer "F.Cu")
		(net "M_G_CPU0_SB_DQ<6>")
	)
	(arc
		(start 394.2969 -277.498302)
		(mid 394.312381 -277.497346)
		(end 394.327888 -277.497032)
		(width 0.0762)
		(layer "F.Cu")
		(net "M_G_CPU0_SB_DQ<6>")
	)
	(arc
		(start 393.955524 -277.615396)
		(mid 394.051233 -277.589684)
		(end 394.140944 -277.547578)
		(width 0.0762)
		(layer "F.Cu")
		(net "M_G_CPU0_SB_DQ<6>")
	)
	(arc
		(start 393.387834 -277.870158)
		(mid 393.631265 -277.700671)
		(end 393.916916 -277.62073)
		(width 0.0762)
		(layer "F.Cu")
		(net "M_G_CPU0_SB_DQ<6>")
	)
	(arc
		(start 393.916916 -277.62073)
		(mid 393.936265 -277.618392)
		(end 393.955524 -277.615396)
		(width 0.0762)
		(layer "F.Cu")
		(net "M_G_CPU0_SB_DQ<6>")
	)
	(arc
		(start 394.140944 -277.547578)
		(mid 394.216184 -277.514265)
		(end 394.2969 -277.498302)
		(width 0.0762)
		(layer "F.Cu")
		(net "M_G_CPU0_SB_DQ<6>")
	)
	(segment
		(start 411.38221 -288.542476)
		(end 411.54985 -288.710116)
		(width 0.101346)
		(layer "F.Cu")
		(net "M_G_CPU0_SB_DQ<5>")
	)
	(segment
		(start 413.134302 -288.710116)
		(end 413.236664 -288.730436)
		(width 0.101346)
		(layer "F.Cu")
		(net "M_G_CPU0_SB_DQ<5>")
	)
	(segment
		(start 413.236664 -288.730436)
		(end 415.270696 -289.135058)
		(width 0.101346)
		(layer "F.Cu")
		(net "M_G_CPU0_SB_DQ<5>")
	)
	(segment
		(start 400.753326 -277.913592)
		(end 411.38221 -288.542476)
		(width 0.10668)
		(layer "F.Cu")
		(net "M_G_CPU0_SB_DQ<5>")
	)
	(segment
		(start 415.270696 -289.135058)
		(end 416.468052 -289.135058)
		(width 0.101346)
		(layer "F.Cu")
		(net "M_G_CPU0_SB_DQ<5>")
	)
	(segment
		(start 411.54985 -288.710116)
		(end 413.134302 -288.710116)
		(width 0.101346)
		(layer "F.Cu")
		(net "M_G_CPU0_SB_DQ<5>")
	)
	(segment
		(start 394.298424 -278.250904)
		(end 394.996162 -278.25192)
		(width 0.0762)
		(layer "F.Cu")
		(net "M_G_CPU0_SB_DQ<5>")
	)
	(segment
		(start 392.448034 -277.870158)
		(end 392.339576 -278.056848)
		(width 0.0762)
		(layer "F.Cu")
		(net "M_G_CPU0_SB_DQ<5>")
	)
	(segment
		(start 395.811248 -277.913592)
		(end 400.753326 -277.913592)
		(width 0.10668)
		(layer "F.Cu")
		(net "M_G_CPU0_SB_DQ<5>")
	)
	(segment
		(start 394.996162 -278.25192)
		(end 395.811248 -277.913592)
		(width 0.0762)
		(layer "F.Cu")
		(net "M_G_CPU0_SB_DQ<5>")
	)
	(segment
		(start 393.20089 -278.192738)
		(end 393.201144 -278.192738)
		(width 0.0762)
		(layer "F.Cu")
		(net "M_G_CPU0_SB_DQ<5>")
	)
	(segment
		(start 392.626596 -278.197564)
		(end 392.634978 -278.192738)
		(width 0.0762)
		(layer "F.Cu")
		(net "M_G_CPU0_SB_DQ<5>")
	)
	(arc
		(start 392.491214 -278.24049)
		(mid 392.560968 -278.225533)
		(end 392.626596 -278.197564)
		(width 0.0762)
		(layer "F.Cu")
		(net "M_G_CPU0_SB_DQ<5>")
	)
	(arc
		(start 394.140944 -278.192738)
		(mid 394.181638 -278.214957)
		(end 394.223494 -278.234902)
		(width 0.0762)
		(layer "F.Cu")
		(net "M_G_CPU0_SB_DQ<5>")
	)
	(arc
		(start 392.339576 -278.056848)
		(mid 392.365493 -278.18989)
		(end 392.491214 -278.24049)
		(width 0.0762)
		(layer "F.Cu")
		(net "M_G_CPU0_SB_DQ<5>")
	)
	(arc
		(start 393.575032 -278.192738)
		(mid 393.857988 -278.116561)
		(end 394.140944 -278.192738)
		(width 0.0762)
		(layer "F.Cu")
		(net "M_G_CPU0_SB_DQ<5>")
	)
	(arc
		(start 393.201144 -278.192738)
		(mid 393.388088 -278.243062)
		(end 393.575032 -278.192738)
		(width 0.0762)
		(layer "F.Cu")
		(net "M_G_CPU0_SB_DQ<5>")
	)
	(arc
		(start 394.223494 -278.234902)
		(mid 394.260122 -278.246832)
		(end 394.298424 -278.250904)
		(width 0.0762)
		(layer "F.Cu")
		(net "M_G_CPU0_SB_DQ<5>")
	)
	(arc
		(start 392.634978 -278.192738)
		(mid 392.917934 -278.116561)
		(end 393.20089 -278.192738)
		(width 0.0762)
		(layer "F.Cu")
		(net "M_G_CPU0_SB_DQ<5>")
	)
	(segment
		(start 393.857988 -277.060152)
		(end 393.755626 -277.236428)
		(width 0.0762)
		(layer "F.Cu")
		(net "M_G_CPU0_SB_DQ<4>")
	)
	(segment
		(start 395.319758 -277.148036)
		(end 395.914372 -277.148036)
		(width 0.0762)
		(layer "F.Cu")
		(net "M_G_CPU0_SB_DQ<4>")
	)
	(segment
		(start 413.929322 -287.010094)
		(end 414.354264 -287.435036)
		(width 0.101346)
		(layer "F.Cu")
		(net "M_G_CPU0_SB_DQ<4>")
	)
	(segment
		(start 410.890466 -287.010094)
		(end 411.317694 -287.010094)
		(width 0.10668)
		(layer "F.Cu")
		(net "M_G_CPU0_SB_DQ<4>")
	)
	(segment
		(start 394.03655 -277.387558)
		(end 394.044932 -277.382732)
		(width 0.0762)
		(layer "F.Cu")
		(net "M_G_CPU0_SB_DQ<4>")
	)
	(segment
		(start 395.161262 -277.306532)
		(end 395.319758 -277.148036)
		(width 0.0762)
		(layer "F.Cu")
		(net "M_G_CPU0_SB_DQ<4>")
	)
	(segment
		(start 404.043896 -280.163524)
		(end 410.890466 -287.010094)
		(width 0.10668)
		(layer "F.Cu")
		(net "M_G_CPU0_SB_DQ<4>")
	)
	(segment
		(start 402.20138 -277.148036)
		(end 404.043896 -278.990552)
		(width 0.10668)
		(layer "F.Cu")
		(net "M_G_CPU0_SB_DQ<4>")
	)
	(segment
		(start 404.043896 -278.990552)
		(end 404.043896 -280.163524)
		(width 0.10668)
		(layer "F.Cu")
		(net "M_G_CPU0_SB_DQ<4>")
	)
	(segment
		(start 414.354264 -287.435036)
		(end 416.468052 -287.435036)
		(width 0.101346)
		(layer "F.Cu")
		(net "M_G_CPU0_SB_DQ<4>")
	)
	(segment
		(start 411.317694 -287.010094)
		(end 413.929322 -287.010094)
		(width 0.101346)
		(layer "F.Cu")
		(net "M_G_CPU0_SB_DQ<4>")
	)
	(segment
		(start 394.327634 -277.306532)
		(end 395.161262 -277.306532)
		(width 0.0762)
		(layer "F.Cu")
		(net "M_G_CPU0_SB_DQ<4>")
	)
	(segment
		(start 395.914372 -277.148036)
		(end 402.20138 -277.148036)
		(width 0.10668)
		(layer "F.Cu")
		(net "M_G_CPU0_SB_DQ<4>")
	)
	(arc
		(start 393.755626 -277.236428)
		(mid 393.785255 -277.378915)
		(end 393.922504 -277.427436)
		(width 0.0762)
		(layer "F.Cu")
		(net "M_G_CPU0_SB_DQ<4>")
	)
	(arc
		(start 394.044932 -277.382732)
		(mid 394.158656 -277.332431)
		(end 394.280644 -277.30831)
		(width 0.0762)
		(layer "F.Cu")
		(net "M_G_CPU0_SB_DQ<4>")
	)
	(arc
		(start 393.922504 -277.427436)
		(mid 393.98115 -277.412143)
		(end 394.03655 -277.387558)
		(width 0.0762)
		(layer "F.Cu")
		(net "M_G_CPU0_SB_DQ<4>")
	)
	(arc
		(start 394.280644 -277.30831)
		(mid 394.304121 -277.306934)
		(end 394.327634 -277.306532)
		(width 0.0762)
		(layer "F.Cu")
		(net "M_G_CPU0_SB_DQ<4>")
	)
	(segment
		(start 408.835098 -280.916634)
		(end 409.111958 -280.63952)
		(width 0.10668)
		(layer "F.Cu")
		(net "M_G_CPU0_SB_DQ<3>")
	)
	(segment
		(start 409.394152 -280.756614)
		(end 409.394152 -280.921714)
		(width 0.10668)
		(layer "F.Cu")
		(net "M_G_CPU0_SB_DQ<3>")
	)
	(segment
		(start 409.394152 -280.921714)
		(end 409.117292 -281.198828)
		(width 0.10668)
		(layer "F.Cu")
		(net "M_G_CPU0_SB_DQ<3>")
	)
	(segment
		(start 407.583894 -278.946356)
		(end 407.700988 -279.06345)
		(width 0.10668)
		(layer "F.Cu")
		(net "M_G_CPU0_SB_DQ<3>")
	)
	(segment
		(start 407.424128 -279.670764)
		(end 407.541222 -279.787858)
		(width 0.10668)
		(layer "F.Cu")
		(net "M_G_CPU0_SB_DQ<3>")
	)
	(segment
		(start 407.541222 -279.787858)
		(end 407.706322 -279.787858)
		(width 0.10668)
		(layer "F.Cu")
		(net "M_G_CPU0_SB_DQ<3>")
	)
	(segment
		(start 408.829764 -280.357326)
		(end 408.552904 -280.63444)
		(width 0.10668)
		(layer "F.Cu")
		(net "M_G_CPU0_SB_DQ<3>")
	)
	(segment
		(start 403.000464 -275.2471)
		(end 406.976834 -279.22347)
		(width 0.10668)
		(layer "F.Cu")
		(net "M_G_CPU0_SB_DQ<3>")
	)
	(segment
		(start 408.669998 -280.916634)
		(end 408.835098 -280.916634)
		(width 0.10668)
		(layer "F.Cu")
		(net "M_G_CPU0_SB_DQ<3>")
	)
	(segment
		(start 408.552904 -280.79954)
		(end 408.669998 -280.916634)
		(width 0.10668)
		(layer "F.Cu")
		(net "M_G_CPU0_SB_DQ<3>")
	)
	(segment
		(start 408.265376 -279.792938)
		(end 407.988516 -280.070052)
		(width 0.10668)
		(layer "F.Cu")
		(net "M_G_CPU0_SB_DQ<3>")
	)
	(segment
		(start 407.706322 -279.787858)
		(end 407.983182 -279.510744)
		(width 0.10668)
		(layer "F.Cu")
		(net "M_G_CPU0_SB_DQ<3>")
	)
	(segment
		(start 395.880082 -275.2471)
		(end 403.000464 -275.2471)
		(width 0.10668)
		(layer "F.Cu")
		(net "M_G_CPU0_SB_DQ<3>")
	)
	(segment
		(start 394.03655 -275.112734)
		(end 394.044932 -275.11756)
		(width 0.0762)
		(layer "F.Cu")
		(net "M_G_CPU0_SB_DQ<3>")
	)
	(segment
		(start 407.700988 -279.22855)
		(end 407.424128 -279.505664)
		(width 0.10668)
		(layer "F.Cu")
		(net "M_G_CPU0_SB_DQ<3>")
	)
	(segment
		(start 408.148282 -279.510744)
		(end 408.265376 -279.627838)
		(width 0.10668)
		(layer "F.Cu")
		(net "M_G_CPU0_SB_DQ<3>")
	)
	(segment
		(start 408.829764 -280.192226)
		(end 408.829764 -280.357326)
		(width 0.10668)
		(layer "F.Cu")
		(net "M_G_CPU0_SB_DQ<3>")
	)
	(segment
		(start 409.111958 -280.63952)
		(end 409.277058 -280.63952)
		(width 0.10668)
		(layer "F.Cu")
		(net "M_G_CPU0_SB_DQ<3>")
	)
	(segment
		(start 394.50264 -275.2471)
		(end 395.880082 -275.2471)
		(width 0.0762)
		(layer "F.Cu")
		(net "M_G_CPU0_SB_DQ<3>")
	)
	(segment
		(start 408.10561 -280.352246)
		(end 408.27071 -280.352246)
		(width 0.10668)
		(layer "F.Cu")
		(net "M_G_CPU0_SB_DQ<3>")
	)
	(segment
		(start 409.95854 -281.486102)
		(end 409.68168 -281.763216)
		(width 0.10668)
		(layer "F.Cu")
		(net "M_G_CPU0_SB_DQ<3>")
	)
	(segment
		(start 407.988516 -280.070052)
		(end 407.988516 -280.235152)
		(width 0.10668)
		(layer "F.Cu")
		(net "M_G_CPU0_SB_DQ<3>")
	)
	(segment
		(start 407.141934 -279.22347)
		(end 407.418794 -278.946356)
		(width 0.10668)
		(layer "F.Cu")
		(net "M_G_CPU0_SB_DQ<3>")
	)
	(segment
		(start 407.700988 -279.06345)
		(end 407.700988 -279.22855)
		(width 0.10668)
		(layer "F.Cu")
		(net "M_G_CPU0_SB_DQ<3>")
	)
	(segment
		(start 408.27071 -280.352246)
		(end 408.54757 -280.075132)
		(width 0.10668)
		(layer "F.Cu")
		(net "M_G_CPU0_SB_DQ<3>")
	)
	(segment
		(start 407.983182 -279.510744)
		(end 408.148282 -279.510744)
		(width 0.10668)
		(layer "F.Cu")
		(net "M_G_CPU0_SB_DQ<3>")
	)
	(segment
		(start 411.788356 -284.034992)
		(end 412.367984 -284.034992)
		(width 0.10668)
		(layer "F.Cu")
		(net "M_G_CPU0_SB_DQ<3>")
	)
	(segment
		(start 408.54757 -280.075132)
		(end 408.71267 -280.075132)
		(width 0.10668)
		(layer "F.Cu")
		(net "M_G_CPU0_SB_DQ<3>")
	)
	(segment
		(start 409.68168 -281.928316)
		(end 411.788356 -284.034992)
		(width 0.10668)
		(layer "F.Cu")
		(net "M_G_CPU0_SB_DQ<3>")
	)
	(segment
		(start 409.68168 -281.763216)
		(end 409.68168 -281.928316)
		(width 0.10668)
		(layer "F.Cu")
		(net "M_G_CPU0_SB_DQ<3>")
	)
	(segment
		(start 409.117292 -281.198828)
		(end 409.117292 -281.363928)
		(width 0.10668)
		(layer "F.Cu")
		(net "M_G_CPU0_SB_DQ<3>")
	)
	(segment
		(start 408.552904 -280.63444)
		(end 408.552904 -280.79954)
		(width 0.10668)
		(layer "F.Cu")
		(net "M_G_CPU0_SB_DQ<3>")
	)
	(segment
		(start 407.988516 -280.235152)
		(end 408.10561 -280.352246)
		(width 0.10668)
		(layer "F.Cu")
		(net "M_G_CPU0_SB_DQ<3>")
	)
	(segment
		(start 409.95854 -281.321002)
		(end 409.95854 -281.486102)
		(width 0.10668)
		(layer "F.Cu")
		(net "M_G_CPU0_SB_DQ<3>")
	)
	(segment
		(start 409.277058 -280.63952)
		(end 409.394152 -280.756614)
		(width 0.10668)
		(layer "F.Cu")
		(net "M_G_CPU0_SB_DQ<3>")
	)
	(segment
		(start 406.976834 -279.22347)
		(end 407.141934 -279.22347)
		(width 0.10668)
		(layer "F.Cu")
		(net "M_G_CPU0_SB_DQ<3>")
	)
	(segment
		(start 409.676346 -281.203908)
		(end 409.841446 -281.203908)
		(width 0.10668)
		(layer "F.Cu")
		(net "M_G_CPU0_SB_DQ<3>")
	)
	(segment
		(start 409.117292 -281.363928)
		(end 409.234386 -281.481022)
		(width 0.10668)
		(layer "F.Cu")
		(net "M_G_CPU0_SB_DQ<3>")
	)
	(segment
		(start 407.418794 -278.946356)
		(end 407.583894 -278.946356)
		(width 0.10668)
		(layer "F.Cu")
		(net "M_G_CPU0_SB_DQ<3>")
	)
	(segment
		(start 409.234386 -281.481022)
		(end 409.399486 -281.481022)
		(width 0.10668)
		(layer "F.Cu")
		(net "M_G_CPU0_SB_DQ<3>")
	)
	(segment
		(start 407.424128 -279.505664)
		(end 407.424128 -279.670764)
		(width 0.10668)
		(layer "F.Cu")
		(net "M_G_CPU0_SB_DQ<3>")
	)
	(segment
		(start 408.265376 -279.627838)
		(end 408.265376 -279.792938)
		(width 0.10668)
		(layer "F.Cu")
		(net "M_G_CPU0_SB_DQ<3>")
	)
	(segment
		(start 408.71267 -280.075132)
		(end 408.829764 -280.192226)
		(width 0.10668)
		(layer "F.Cu")
		(net "M_G_CPU0_SB_DQ<3>")
	)
	(segment
		(start 409.399486 -281.481022)
		(end 409.676346 -281.203908)
		(width 0.10668)
		(layer "F.Cu")
		(net "M_G_CPU0_SB_DQ<3>")
	)
	(segment
		(start 409.841446 -281.203908)
		(end 409.95854 -281.321002)
		(width 0.10668)
		(layer "F.Cu")
		(net "M_G_CPU0_SB_DQ<3>")
	)
	(arc
		(start 394.044932 -275.11756)
		(mid 394.147826 -275.169932)
		(end 394.256006 -275.21027)
		(width 0.0762)
		(layer "F.Cu")
		(net "M_G_CPU0_SB_DQ<3>")
	)
	(arc
		(start 392.73099 -275.11756)
		(mid 392.917934 -275.067305)
		(end 393.104878 -275.11756)
		(width 0.0762)
		(layer "F.Cu")
		(net "M_G_CPU0_SB_DQ<3>")
	)
	(arc
		(start 394.256006 -275.21027)
		(mid 394.377955 -275.237847)
		(end 394.50264 -275.2471)
		(width 0.0762)
		(layer "F.Cu")
		(net "M_G_CPU0_SB_DQ<3>")
	)
	(arc
		(start 393.67079 -275.11756)
		(mid 393.853041 -275.06721)
		(end 394.03655 -275.112734)
		(width 0.0762)
		(layer "F.Cu")
		(net "M_G_CPU0_SB_DQ<3>")
	)
	(arc
		(start 392.434064 -275.19376)
		(mid 392.587813 -275.176251)
		(end 392.73099 -275.11756)
		(width 0.0762)
		(layer "F.Cu")
		(net "M_G_CPU0_SB_DQ<3>")
	)
	(arc
		(start 391.97788 -275.44014)
		(mid 392.173229 -275.256321)
		(end 392.434064 -275.19376)
		(width 0.0762)
		(layer "F.Cu")
		(net "M_G_CPU0_SB_DQ<3>")
	)
	(arc
		(start 393.104878 -275.11756)
		(mid 393.387834 -275.193737)
		(end 393.67079 -275.11756)
		(width 0.0762)
		(layer "F.Cu")
		(net "M_G_CPU0_SB_DQ<3>")
	)
	(segment
		(start 408.645868 -314.87491)
		(end 408.810968 -314.87491)
		(width 0.10668)
		(layer "F.Cu")
		(net "M_G_CPU0_SB_DQ<31>")
	)
	(segment
		(start 410.537152 -317.333122)
		(end 410.70276 -317.333122)
		(width 0.10668)
		(layer "F.Cu")
		(net "M_G_CPU0_SB_DQ<31>")
	)
	(segment
		(start 410.621226 -316.685168)
		(end 410.621226 -316.850014)
		(width 0.10668)
		(layer "F.Cu")
		(net "M_G_CPU0_SB_DQ<31>")
	)
	(segment
		(start 410.339032 -316.568074)
		(end 410.504132 -316.568074)
		(width 0.10668)
		(layer "F.Cu")
		(net "M_G_CPU0_SB_DQ<31>")
	)
	(segment
		(start 395.294358 -294.007032)
		(end 395.294358 -301.3583)
		(width 0.10668)
		(layer "F.Cu")
		(net "M_G_CPU0_SB_DQ<31>")
	)
	(segment
		(start 407.801318 -314.59043)
		(end 408.08148 -314.310522)
		(width 0.10668)
		(layer "F.Cu")
		(net "M_G_CPU0_SB_DQ<31>")
	)
	(segment
		(start 410.056838 -316.12078)
		(end 410.056838 -316.28588)
		(width 0.10668)
		(layer "F.Cu")
		(net "M_G_CPU0_SB_DQ<31>")
	)
	(segment
		(start 408.365706 -315.154818)
		(end 408.645868 -314.87491)
		(width 0.10668)
		(layer "F.Cu")
		(net "M_G_CPU0_SB_DQ<31>")
	)
	(segment
		(start 411.076394 -317.140336)
		(end 411.971236 -318.035178)
		(width 0.10668)
		(layer "F.Cu")
		(net "M_G_CPU0_SB_DQ<31>")
	)
	(segment
		(start 410.70276 -317.333122)
		(end 410.895546 -317.140336)
		(width 0.10668)
		(layer "F.Cu")
		(net "M_G_CPU0_SB_DQ<31>")
	)
	(segment
		(start 410.23794 -316.669166)
		(end 410.339032 -316.568074)
		(width 0.10668)
		(layer "F.Cu")
		(net "M_G_CPU0_SB_DQ<31>")
	)
	(segment
		(start 410.420058 -317.216028)
		(end 410.537152 -317.333122)
		(width 0.10668)
		(layer "F.Cu")
		(net "M_G_CPU0_SB_DQ<31>")
	)
	(segment
		(start 411.971236 -318.035178)
		(end 412.367984 -318.035178)
		(width 0.10668)
		(layer "F.Cu")
		(net "M_G_CPU0_SB_DQ<31>")
	)
	(segment
		(start 409.212288 -316.1665)
		(end 409.329382 -316.283594)
		(width 0.10668)
		(layer "F.Cu")
		(net "M_G_CPU0_SB_DQ<31>")
	)
	(segment
		(start 410.621226 -316.850014)
		(end 410.420058 -317.051182)
		(width 0.10668)
		(layer "F.Cu")
		(net "M_G_CPU0_SB_DQ<31>")
	)
	(segment
		(start 408.363674 -314.427616)
		(end 408.363674 -314.592716)
		(width 0.10668)
		(layer "F.Cu")
		(net "M_G_CPU0_SB_DQ<31>")
	)
	(segment
		(start 409.776676 -316.565788)
		(end 409.776676 -316.730888)
		(width 0.10668)
		(layer "F.Cu")
		(net "M_G_CPU0_SB_DQ<31>")
	)
	(segment
		(start 409.939744 -316.003686)
		(end 410.056838 -316.12078)
		(width 0.10668)
		(layer "F.Cu")
		(net "M_G_CPU0_SB_DQ<31>")
	)
	(segment
		(start 408.930094 -315.719206)
		(end 409.210256 -315.439298)
		(width 0.10668)
		(layer "F.Cu")
		(net "M_G_CPU0_SB_DQ<31>")
	)
	(segment
		(start 410.895546 -317.140336)
		(end 411.076394 -317.140336)
		(width 0.10668)
		(layer "F.Cu")
		(net "M_G_CPU0_SB_DQ<31>")
	)
	(segment
		(start 407.519124 -314.308236)
		(end 407.519124 -314.473336)
		(width 0.10668)
		(layer "F.Cu")
		(net "M_G_CPU0_SB_DQ<31>")
	)
	(segment
		(start 395.294358 -301.3583)
		(end 407.799286 -313.863228)
		(width 0.10668)
		(layer "F.Cu")
		(net "M_G_CPU0_SB_DQ<31>")
	)
	(segment
		(start 410.056838 -316.28588)
		(end 409.776676 -316.565788)
		(width 0.10668)
		(layer "F.Cu")
		(net "M_G_CPU0_SB_DQ<31>")
	)
	(segment
		(start 409.329382 -316.283594)
		(end 409.494482 -316.283594)
		(width 0.10668)
		(layer "F.Cu")
		(net "M_G_CPU0_SB_DQ<31>")
	)
	(segment
		(start 408.200606 -315.154818)
		(end 408.365706 -315.154818)
		(width 0.10668)
		(layer "F.Cu")
		(net "M_G_CPU0_SB_DQ<31>")
	)
	(segment
		(start 407.799286 -314.028328)
		(end 407.519124 -314.308236)
		(width 0.10668)
		(layer "F.Cu")
		(net "M_G_CPU0_SB_DQ<31>")
	)
	(segment
		(start 409.494482 -316.283594)
		(end 409.774644 -316.003686)
		(width 0.10668)
		(layer "F.Cu")
		(net "M_G_CPU0_SB_DQ<31>")
	)
	(segment
		(start 408.928062 -315.157104)
		(end 408.6479 -315.437012)
		(width 0.10668)
		(layer "F.Cu")
		(net "M_G_CPU0_SB_DQ<31>")
	)
	(segment
		(start 408.363674 -314.592716)
		(end 408.083512 -314.872624)
		(width 0.10668)
		(layer "F.Cu")
		(net "M_G_CPU0_SB_DQ<31>")
	)
	(segment
		(start 407.799286 -313.863228)
		(end 407.799286 -314.028328)
		(width 0.10668)
		(layer "F.Cu")
		(net "M_G_CPU0_SB_DQ<31>")
	)
	(segment
		(start 408.24658 -314.310522)
		(end 408.363674 -314.427616)
		(width 0.10668)
		(layer "F.Cu")
		(net "M_G_CPU0_SB_DQ<31>")
	)
	(segment
		(start 408.6479 -315.602112)
		(end 408.764994 -315.719206)
		(width 0.10668)
		(layer "F.Cu")
		(net "M_G_CPU0_SB_DQ<31>")
	)
	(segment
		(start 407.519124 -314.473336)
		(end 407.636218 -314.59043)
		(width 0.10668)
		(layer "F.Cu")
		(net "M_G_CPU0_SB_DQ<31>")
	)
	(segment
		(start 410.05887 -316.847982)
		(end 410.23794 -316.669166)
		(width 0.10668)
		(layer "F.Cu")
		(net "M_G_CPU0_SB_DQ<31>")
	)
	(segment
		(start 408.764994 -315.719206)
		(end 408.930094 -315.719206)
		(width 0.10668)
		(layer "F.Cu")
		(net "M_G_CPU0_SB_DQ<31>")
	)
	(segment
		(start 407.636218 -314.59043)
		(end 407.801318 -314.59043)
		(width 0.10668)
		(layer "F.Cu")
		(net "M_G_CPU0_SB_DQ<31>")
	)
	(segment
		(start 409.774644 -316.003686)
		(end 409.939744 -316.003686)
		(width 0.10668)
		(layer "F.Cu")
		(net "M_G_CPU0_SB_DQ<31>")
	)
	(segment
		(start 409.49245 -315.556392)
		(end 409.49245 -315.721492)
		(width 0.10668)
		(layer "F.Cu")
		(net "M_G_CPU0_SB_DQ<31>")
	)
	(segment
		(start 408.083512 -315.037724)
		(end 408.200606 -315.154818)
		(width 0.10668)
		(layer "F.Cu")
		(net "M_G_CPU0_SB_DQ<31>")
	)
	(segment
		(start 409.212288 -316.0014)
		(end 409.212288 -316.1665)
		(width 0.10668)
		(layer "F.Cu")
		(net "M_G_CPU0_SB_DQ<31>")
	)
	(segment
		(start 408.083512 -314.872624)
		(end 408.083512 -315.037724)
		(width 0.10668)
		(layer "F.Cu")
		(net "M_G_CPU0_SB_DQ<31>")
	)
	(segment
		(start 409.89377 -316.847982)
		(end 410.05887 -316.847982)
		(width 0.10668)
		(layer "F.Cu")
		(net "M_G_CPU0_SB_DQ<31>")
	)
	(segment
		(start 409.776676 -316.730888)
		(end 409.89377 -316.847982)
		(width 0.10668)
		(layer "F.Cu")
		(net "M_G_CPU0_SB_DQ<31>")
	)
	(segment
		(start 408.928062 -314.992004)
		(end 408.928062 -315.157104)
		(width 0.10668)
		(layer "F.Cu")
		(net "M_G_CPU0_SB_DQ<31>")
	)
	(segment
		(start 408.810968 -314.87491)
		(end 408.928062 -314.992004)
		(width 0.10668)
		(layer "F.Cu")
		(net "M_G_CPU0_SB_DQ<31>")
	)
	(segment
		(start 408.08148 -314.310522)
		(end 408.24658 -314.310522)
		(width 0.10668)
		(layer "F.Cu")
		(net "M_G_CPU0_SB_DQ<31>")
	)
	(segment
		(start 409.49245 -315.721492)
		(end 409.212288 -316.0014)
		(width 0.10668)
		(layer "F.Cu")
		(net "M_G_CPU0_SB_DQ<31>")
	)
	(segment
		(start 408.6479 -315.437012)
		(end 408.6479 -315.602112)
		(width 0.10668)
		(layer "F.Cu")
		(net "M_G_CPU0_SB_DQ<31>")
	)
	(segment
		(start 409.375356 -315.439298)
		(end 409.49245 -315.556392)
		(width 0.10668)
		(layer "F.Cu")
		(net "M_G_CPU0_SB_DQ<31>")
	)
	(segment
		(start 410.420058 -317.051182)
		(end 410.420058 -317.216028)
		(width 0.10668)
		(layer "F.Cu")
		(net "M_G_CPU0_SB_DQ<31>")
	)
	(segment
		(start 409.210256 -315.439298)
		(end 409.375356 -315.439298)
		(width 0.10668)
		(layer "F.Cu")
		(net "M_G_CPU0_SB_DQ<31>")
	)
	(segment
		(start 393.857988 -293.260018)
		(end 394.119862 -293.521892)
		(width 0.10668)
		(layer "F.Cu")
		(net "M_G_CPU0_SB_DQ<31>")
	)
	(segment
		(start 394.119862 -293.521892)
		(end 394.809218 -293.521892)
		(width 0.10668)
		(layer "F.Cu")
		(net "M_G_CPU0_SB_DQ<31>")
	)
	(segment
		(start 410.504132 -316.568074)
		(end 410.621226 -316.685168)
		(width 0.10668)
		(layer "F.Cu")
		(net "M_G_CPU0_SB_DQ<31>")
	)
	(segment
		(start 394.809218 -293.521892)
		(end 395.294358 -294.007032)
		(width 0.10668)
		(layer "F.Cu")
		(net "M_G_CPU0_SB_DQ<31>")
	)
	(segment
		(start 395.135354 -292.076886)
		(end 395.498828 -292.44036)
		(width 0.0762)
		(layer "F.Cu")
		(net "M_G_CPU0_SB_DQ<30>")
	)
	(segment
		(start 395.976602 -299.395896)
		(end 399.614898 -303.034192)
		(width 0.10668)
		(layer "F.Cu")
		(net "M_G_CPU0_SB_DQ<30>")
	)
	(segment
		(start 394.327888 -292.076886)
		(end 395.135354 -292.076886)
		(width 0.0762)
		(layer "F.Cu")
		(net "M_G_CPU0_SB_DQ<30>")
	)
	(segment
		(start 403.936708 -307.701442)
		(end 403.936708 -307.866542)
		(width 0.10668)
		(layer "F.Cu")
		(net "M_G_CPU0_SB_DQ<30>")
	)
	(segment
		(start 403.017482 -306.528216)
		(end 402.490432 -307.055266)
		(width 0.10668)
		(layer "F.Cu")
		(net "M_G_CPU0_SB_DQ<30>")
	)
	(segment
		(start 402.607526 -307.33746)
		(end 402.772626 -307.33746)
		(width 0.10668)
		(layer "F.Cu")
		(net "M_G_CPU0_SB_DQ<30>")
	)
	(segment
		(start 395.976602 -292.918134)
		(end 395.976602 -299.395896)
		(width 0.10668)
		(layer "F.Cu")
		(net "M_G_CPU0_SB_DQ<30>")
	)
	(segment
		(start 403.58187 -307.092604)
		(end 403.05482 -307.619654)
		(width 0.10668)
		(layer "F.Cu")
		(net "M_G_CPU0_SB_DQ<30>")
	)
	(segment
		(start 403.299676 -306.81041)
		(end 403.464776 -306.81041)
		(width 0.10668)
		(layer "F.Cu")
		(net "M_G_CPU0_SB_DQ<30>")
	)
	(segment
		(start 402.208238 -306.773072)
		(end 402.735288 -306.246022)
		(width 0.10668)
		(layer "F.Cu")
		(net "M_G_CPU0_SB_DQ<30>")
	)
	(segment
		(start 403.819614 -307.584348)
		(end 403.936708 -307.701442)
		(width 0.10668)
		(layer "F.Cu")
		(net "M_G_CPU0_SB_DQ<30>")
	)
	(segment
		(start 403.619208 -308.349142)
		(end 411.605222 -316.335156)
		(width 0.10668)
		(layer "F.Cu")
		(net "M_G_CPU0_SB_DQ<30>")
	)
	(segment
		(start 403.58187 -306.927504)
		(end 403.58187 -307.092604)
		(width 0.10668)
		(layer "F.Cu")
		(net "M_G_CPU0_SB_DQ<30>")
	)
	(segment
		(start 399.614898 -304.344832)
		(end 402.043138 -306.773072)
		(width 0.10668)
		(layer "F.Cu")
		(net "M_G_CPU0_SB_DQ<30>")
	)
	(segment
		(start 403.464776 -306.81041)
		(end 403.58187 -306.927504)
		(width 0.10668)
		(layer "F.Cu")
		(net "M_G_CPU0_SB_DQ<30>")
	)
	(segment
		(start 403.619208 -308.184042)
		(end 403.619208 -308.349142)
		(width 0.10668)
		(layer "F.Cu")
		(net "M_G_CPU0_SB_DQ<30>")
	)
	(segment
		(start 395.498828 -292.44036)
		(end 395.976602 -292.918134)
		(width 0.10668)
		(layer "F.Cu")
		(net "M_G_CPU0_SB_DQ<30>")
	)
	(segment
		(start 411.605222 -316.335156)
		(end 412.367984 -316.335156)
		(width 0.10668)
		(layer "F.Cu")
		(net "M_G_CPU0_SB_DQ<30>")
	)
	(segment
		(start 403.05482 -307.619654)
		(end 403.05482 -307.784754)
		(width 0.10668)
		(layer "F.Cu")
		(net "M_G_CPU0_SB_DQ<30>")
	)
	(segment
		(start 402.490432 -307.055266)
		(end 402.490432 -307.220366)
		(width 0.10668)
		(layer "F.Cu")
		(net "M_G_CPU0_SB_DQ<30>")
	)
	(segment
		(start 403.171914 -307.901848)
		(end 403.337014 -307.901848)
		(width 0.10668)
		(layer "F.Cu")
		(net "M_G_CPU0_SB_DQ<30>")
	)
	(segment
		(start 402.735288 -306.246022)
		(end 402.900388 -306.246022)
		(width 0.10668)
		(layer "F.Cu")
		(net "M_G_CPU0_SB_DQ<30>")
	)
	(segment
		(start 403.05482 -307.784754)
		(end 403.171914 -307.901848)
		(width 0.10668)
		(layer "F.Cu")
		(net "M_G_CPU0_SB_DQ<30>")
	)
	(segment
		(start 402.772626 -307.33746)
		(end 403.299676 -306.81041)
		(width 0.10668)
		(layer "F.Cu")
		(net "M_G_CPU0_SB_DQ<30>")
	)
	(segment
		(start 403.654514 -307.584348)
		(end 403.819614 -307.584348)
		(width 0.10668)
		(layer "F.Cu")
		(net "M_G_CPU0_SB_DQ<30>")
	)
	(segment
		(start 403.017482 -306.363116)
		(end 403.017482 -306.528216)
		(width 0.10668)
		(layer "F.Cu")
		(net "M_G_CPU0_SB_DQ<30>")
	)
	(segment
		(start 402.900388 -306.246022)
		(end 403.017482 -306.363116)
		(width 0.10668)
		(layer "F.Cu")
		(net "M_G_CPU0_SB_DQ<30>")
	)
	(segment
		(start 402.043138 -306.773072)
		(end 402.208238 -306.773072)
		(width 0.10668)
		(layer "F.Cu")
		(net "M_G_CPU0_SB_DQ<30>")
	)
	(segment
		(start 399.614898 -303.034192)
		(end 399.614898 -304.344832)
		(width 0.10668)
		(layer "F.Cu")
		(net "M_G_CPU0_SB_DQ<30>")
	)
	(segment
		(start 403.936708 -307.866542)
		(end 403.619208 -308.184042)
		(width 0.10668)
		(layer "F.Cu")
		(net "M_G_CPU0_SB_DQ<30>")
	)
	(segment
		(start 403.337014 -307.901848)
		(end 403.654514 -307.584348)
		(width 0.10668)
		(layer "F.Cu")
		(net "M_G_CPU0_SB_DQ<30>")
	)
	(segment
		(start 402.490432 -307.220366)
		(end 402.607526 -307.33746)
		(width 0.10668)
		(layer "F.Cu")
		(net "M_G_CPU0_SB_DQ<30>")
	)
	(arc
		(start 393.916916 -292.200584)
		(mid 393.936265 -292.198246)
		(end 393.955524 -292.19525)
		(width 0.0762)
		(layer "F.Cu")
		(net "M_G_CPU0_SB_DQ<30>")
	)
	(arc
		(start 393.955524 -292.19525)
		(mid 394.051233 -292.169538)
		(end 394.140944 -292.127432)
		(width 0.0762)
		(layer "F.Cu")
		(net "M_G_CPU0_SB_DQ<30>")
	)
	(arc
		(start 394.2969 -292.078156)
		(mid 394.312381 -292.0772)
		(end 394.327888 -292.076886)
		(width 0.0762)
		(layer "F.Cu")
		(net "M_G_CPU0_SB_DQ<30>")
	)
	(arc
		(start 394.140944 -292.127432)
		(mid 394.216184 -292.094119)
		(end 394.2969 -292.078156)
		(width 0.0762)
		(layer "F.Cu")
		(net "M_G_CPU0_SB_DQ<30>")
	)
	(arc
		(start 393.387834 -292.450012)
		(mid 393.631265 -292.280525)
		(end 393.916916 -292.200584)
		(width 0.0762)
		(layer "F.Cu")
		(net "M_G_CPU0_SB_DQ<30>")
	)
	(segment
		(start 397.72209 -274.174966)
		(end 397.945864 -274.39874)
		(width 0.10668)
		(layer "F.Cu")
		(net "M_G_CPU0_SB_DQ<2>")
	)
	(segment
		(start 398.520158 -274.174966)
		(end 398.743932 -274.39874)
		(width 0.10668)
		(layer "F.Cu")
		(net "M_G_CPU0_SB_DQ<2>")
	)
	(segment
		(start 407.030936 -277.54199)
		(end 406.727406 -277.84552)
		(width 0.10668)
		(layer "F.Cu")
		(net "M_G_CPU0_SB_DQ<2>")
	)
	(segment
		(start 399.318226 -274.174966)
		(end 399.542 -274.39874)
		(width 0.10668)
		(layer "F.Cu")
		(net "M_G_CPU0_SB_DQ<2>")
	)
	(segment
		(start 397.945864 -274.39874)
		(end 398.121124 -274.39874)
		(width 0.10668)
		(layer "F.Cu")
		(net "M_G_CPU0_SB_DQ<2>")
	)
	(segment
		(start 399.941034 -274.174966)
		(end 402.891752 -274.174966)
		(width 0.10668)
		(layer "F.Cu")
		(net "M_G_CPU0_SB_DQ<2>")
	)
	(segment
		(start 397.147796 -274.39874)
		(end 397.323056 -274.39874)
		(width 0.10668)
		(layer "F.Cu")
		(net "M_G_CPU0_SB_DQ<2>")
	)
	(segment
		(start 396.125954 -274.174966)
		(end 396.349728 -274.39874)
		(width 0.10668)
		(layer "F.Cu")
		(net "M_G_CPU0_SB_DQ<2>")
	)
	(segment
		(start 405.619966 -276.13102)
		(end 405.785066 -276.13102)
		(width 0.10668)
		(layer "F.Cu")
		(net "M_G_CPU0_SB_DQ<2>")
	)
	(segment
		(start 397.54683 -274.174966)
		(end 397.72209 -274.174966)
		(width 0.10668)
		(layer "F.Cu")
		(net "M_G_CPU0_SB_DQ<2>")
	)
	(segment
		(start 406.163018 -277.281132)
		(end 406.163018 -277.446232)
		(width 0.10668)
		(layer "F.Cu")
		(net "M_G_CPU0_SB_DQ<2>")
	)
	(segment
		(start 406.280112 -277.563326)
		(end 406.445212 -277.563326)
		(width 0.10668)
		(layer "F.Cu")
		(net "M_G_CPU0_SB_DQ<2>")
	)
	(segment
		(start 406.727406 -277.84552)
		(end 406.727406 -278.01062)
		(width 0.10668)
		(layer "F.Cu")
		(net "M_G_CPU0_SB_DQ<2>")
	)
	(segment
		(start 394.327888 -274.257008)
		(end 395.275816 -274.257008)
		(width 0.0762)
		(layer "F.Cu")
		(net "M_G_CPU0_SB_DQ<2>")
	)
	(segment
		(start 405.316436 -276.43455)
		(end 405.619966 -276.13102)
		(width 0.10668)
		(layer "F.Cu")
		(net "M_G_CPU0_SB_DQ<2>")
	)
	(segment
		(start 406.445212 -277.563326)
		(end 406.748742 -277.259796)
		(width 0.10668)
		(layer "F.Cu")
		(net "M_G_CPU0_SB_DQ<2>")
	)
	(segment
		(start 399.542 -274.39874)
		(end 399.71726 -274.39874)
		(width 0.10668)
		(layer "F.Cu")
		(net "M_G_CPU0_SB_DQ<2>")
	)
	(segment
		(start 405.055578 -275.566632)
		(end 405.220678 -275.566632)
		(width 0.10668)
		(layer "F.Cu")
		(net "M_G_CPU0_SB_DQ<2>")
	)
	(segment
		(start 405.59863 -276.716744)
		(end 405.59863 -276.881844)
		(width 0.10668)
		(layer "F.Cu")
		(net "M_G_CPU0_SB_DQ<2>")
	)
	(segment
		(start 405.715724 -276.998938)
		(end 405.880824 -276.998938)
		(width 0.10668)
		(layer "F.Cu")
		(net "M_G_CPU0_SB_DQ<2>")
	)
	(segment
		(start 399.71726 -274.39874)
		(end 399.941034 -274.174966)
		(width 0.10668)
		(layer "F.Cu")
		(net "M_G_CPU0_SB_DQ<2>")
	)
	(segment
		(start 406.163018 -277.446232)
		(end 406.280112 -277.563326)
		(width 0.10668)
		(layer "F.Cu")
		(net "M_G_CPU0_SB_DQ<2>")
	)
	(segment
		(start 405.337772 -275.848826)
		(end 405.034242 -276.152356)
		(width 0.10668)
		(layer "F.Cu")
		(net "M_G_CPU0_SB_DQ<2>")
	)
	(segment
		(start 405.90216 -276.248114)
		(end 405.90216 -276.413214)
		(width 0.10668)
		(layer "F.Cu")
		(net "M_G_CPU0_SB_DQ<2>")
	)
	(segment
		(start 405.337772 -275.683726)
		(end 405.337772 -275.848826)
		(width 0.10668)
		(layer "F.Cu")
		(net "M_G_CPU0_SB_DQ<2>")
	)
	(segment
		(start 399.142966 -274.174966)
		(end 399.318226 -274.174966)
		(width 0.10668)
		(layer "F.Cu")
		(net "M_G_CPU0_SB_DQ<2>")
	)
	(segment
		(start 405.59863 -276.881844)
		(end 405.715724 -276.998938)
		(width 0.10668)
		(layer "F.Cu")
		(net "M_G_CPU0_SB_DQ<2>")
	)
	(segment
		(start 406.913842 -277.259796)
		(end 407.030936 -277.37689)
		(width 0.10668)
		(layer "F.Cu")
		(net "M_G_CPU0_SB_DQ<2>")
	)
	(segment
		(start 406.748742 -277.259796)
		(end 406.913842 -277.259796)
		(width 0.10668)
		(layer "F.Cu")
		(net "M_G_CPU0_SB_DQ<2>")
	)
	(segment
		(start 405.034242 -276.317456)
		(end 405.151336 -276.43455)
		(width 0.10668)
		(layer "F.Cu")
		(net "M_G_CPU0_SB_DQ<2>")
	)
	(segment
		(start 407.47823 -277.824184)
		(end 410.679138 -281.025092)
		(width 0.10668)
		(layer "F.Cu")
		(net "M_G_CPU0_SB_DQ<2>")
	)
	(segment
		(start 411.051756 -282.33497)
		(end 412.367984 -282.33497)
		(width 0.10668)
		(layer "F.Cu")
		(net "M_G_CPU0_SB_DQ<2>")
	)
	(segment
		(start 396.524988 -274.39874)
		(end 396.748762 -274.174966)
		(width 0.10668)
		(layer "F.Cu")
		(net "M_G_CPU0_SB_DQ<2>")
	)
	(segment
		(start 404.752048 -275.870162)
		(end 405.055578 -275.566632)
		(width 0.10668)
		(layer "F.Cu")
		(net "M_G_CPU0_SB_DQ<2>")
	)
	(segment
		(start 402.891752 -274.174966)
		(end 404.586948 -275.870162)
		(width 0.10668)
		(layer "F.Cu")
		(net "M_G_CPU0_SB_DQ<2>")
	)
	(segment
		(start 398.743932 -274.39874)
		(end 398.919192 -274.39874)
		(width 0.10668)
		(layer "F.Cu")
		(net "M_G_CPU0_SB_DQ<2>")
	)
	(segment
		(start 396.748762 -274.174966)
		(end 396.924022 -274.174966)
		(width 0.10668)
		(layer "F.Cu")
		(net "M_G_CPU0_SB_DQ<2>")
	)
	(segment
		(start 405.90216 -276.413214)
		(end 405.59863 -276.716744)
		(width 0.10668)
		(layer "F.Cu")
		(net "M_G_CPU0_SB_DQ<2>")
	)
	(segment
		(start 395.82852 -274.174966)
		(end 396.125954 -274.174966)
		(width 0.10668)
		(layer "F.Cu")
		(net "M_G_CPU0_SB_DQ<2>")
	)
	(segment
		(start 398.121124 -274.39874)
		(end 398.344898 -274.174966)
		(width 0.10668)
		(layer "F.Cu")
		(net "M_G_CPU0_SB_DQ<2>")
	)
	(segment
		(start 407.31313 -277.824184)
		(end 407.47823 -277.824184)
		(width 0.10668)
		(layer "F.Cu")
		(net "M_G_CPU0_SB_DQ<2>")
	)
	(segment
		(start 405.220678 -275.566632)
		(end 405.337772 -275.683726)
		(width 0.10668)
		(layer "F.Cu")
		(net "M_G_CPU0_SB_DQ<2>")
	)
	(segment
		(start 405.880824 -276.998938)
		(end 406.184354 -276.695408)
		(width 0.10668)
		(layer "F.Cu")
		(net "M_G_CPU0_SB_DQ<2>")
	)
	(segment
		(start 398.344898 -274.174966)
		(end 398.520158 -274.174966)
		(width 0.10668)
		(layer "F.Cu")
		(net "M_G_CPU0_SB_DQ<2>")
	)
	(segment
		(start 396.924022 -274.174966)
		(end 397.147796 -274.39874)
		(width 0.10668)
		(layer "F.Cu")
		(net "M_G_CPU0_SB_DQ<2>")
	)
	(segment
		(start 395.275816 -274.257008)
		(end 395.357858 -274.174966)
		(width 0.0762)
		(layer "F.Cu")
		(net "M_G_CPU0_SB_DQ<2>")
	)
	(segment
		(start 405.151336 -276.43455)
		(end 405.316436 -276.43455)
		(width 0.10668)
		(layer "F.Cu")
		(net "M_G_CPU0_SB_DQ<2>")
	)
	(segment
		(start 407.030936 -277.37689)
		(end 407.030936 -277.54199)
		(width 0.10668)
		(layer "F.Cu")
		(net "M_G_CPU0_SB_DQ<2>")
	)
	(segment
		(start 406.727406 -278.01062)
		(end 406.8445 -278.127714)
		(width 0.10668)
		(layer "F.Cu")
		(net "M_G_CPU0_SB_DQ<2>")
	)
	(segment
		(start 406.184354 -276.695408)
		(end 406.349454 -276.695408)
		(width 0.10668)
		(layer "F.Cu")
		(net "M_G_CPU0_SB_DQ<2>")
	)
	(segment
		(start 406.466548 -276.977602)
		(end 406.163018 -277.281132)
		(width 0.10668)
		(layer "F.Cu")
		(net "M_G_CPU0_SB_DQ<2>")
	)
	(segment
		(start 398.919192 -274.39874)
		(end 399.142966 -274.174966)
		(width 0.10668)
		(layer "F.Cu")
		(net "M_G_CPU0_SB_DQ<2>")
	)
	(segment
		(start 405.785066 -276.13102)
		(end 405.90216 -276.248114)
		(width 0.10668)
		(layer "F.Cu")
		(net "M_G_CPU0_SB_DQ<2>")
	)
	(segment
		(start 404.586948 -275.870162)
		(end 404.752048 -275.870162)
		(width 0.10668)
		(layer "F.Cu")
		(net "M_G_CPU0_SB_DQ<2>")
	)
	(segment
		(start 407.0096 -278.127714)
		(end 407.31313 -277.824184)
		(width 0.10668)
		(layer "F.Cu")
		(net "M_G_CPU0_SB_DQ<2>")
	)
	(segment
		(start 397.323056 -274.39874)
		(end 397.54683 -274.174966)
		(width 0.10668)
		(layer "F.Cu")
		(net "M_G_CPU0_SB_DQ<2>")
	)
	(segment
		(start 395.357858 -274.174966)
		(end 395.82852 -274.174966)
		(width 0.0762)
		(layer "F.Cu")
		(net "M_G_CPU0_SB_DQ<2>")
	)
	(segment
		(start 405.034242 -276.152356)
		(end 405.034242 -276.317456)
		(width 0.10668)
		(layer "F.Cu")
		(net "M_G_CPU0_SB_DQ<2>")
	)
	(segment
		(start 406.466548 -276.812502)
		(end 406.466548 -276.977602)
		(width 0.10668)
		(layer "F.Cu")
		(net "M_G_CPU0_SB_DQ<2>")
	)
	(segment
		(start 406.8445 -278.127714)
		(end 407.0096 -278.127714)
		(width 0.10668)
		(layer "F.Cu")
		(net "M_G_CPU0_SB_DQ<2>")
	)
	(segment
		(start 406.349454 -276.695408)
		(end 406.466548 -276.812502)
		(width 0.10668)
		(layer "F.Cu")
		(net "M_G_CPU0_SB_DQ<2>")
	)
	(segment
		(start 396.349728 -274.39874)
		(end 396.524988 -274.39874)
		(width 0.10668)
		(layer "F.Cu")
		(net "M_G_CPU0_SB_DQ<2>")
	)
	(segment
		(start 410.679138 -281.962352)
		(end 411.051756 -282.33497)
		(width 0.10668)
		(layer "F.Cu")
		(net "M_G_CPU0_SB_DQ<2>")
	)
	(segment
		(start 410.679138 -281.025092)
		(end 410.679138 -281.962352)
		(width 0.10668)
		(layer "F.Cu")
		(net "M_G_CPU0_SB_DQ<2>")
	)
	(arc
		(start 393.916916 -274.380706)
		(mid 393.936265 -274.378368)
		(end 393.955524 -274.375372)
		(width 0.0762)
		(layer "F.Cu")
		(net "M_G_CPU0_SB_DQ<2>")
	)
	(arc
		(start 393.387834 -274.630134)
		(mid 393.631265 -274.460647)
		(end 393.916916 -274.380706)
		(width 0.0762)
		(layer "F.Cu")
		(net "M_G_CPU0_SB_DQ<2>")
	)
	(arc
		(start 393.955524 -274.375372)
		(mid 394.051233 -274.34966)
		(end 394.140944 -274.307554)
		(width 0.0762)
		(layer "F.Cu")
		(net "M_G_CPU0_SB_DQ<2>")
	)
	(arc
		(start 394.140944 -274.307554)
		(mid 394.216184 -274.274241)
		(end 394.2969 -274.258278)
		(width 0.0762)
		(layer "F.Cu")
		(net "M_G_CPU0_SB_DQ<2>")
	)
	(arc
		(start 394.2969 -274.258278)
		(mid 394.312381 -274.257322)
		(end 394.327888 -274.257008)
		(width 0.0762)
		(layer "F.Cu")
		(net "M_G_CPU0_SB_DQ<2>")
	)
	(segment
		(start 411.317694 -316.722506)
		(end 411.355286 -316.760098)
		(width 0.101346)
		(layer "F.Cu")
		(net "M_G_CPU0_SB_DQ<29>")
	)
	(segment
		(start 392.626596 -292.777418)
		(end 392.634978 -292.772592)
		(width 0.0762)
		(layer "F.Cu")
		(net "M_G_CPU0_SB_DQ<29>")
	)
	(segment
		(start 415.539428 -317.18504)
		(end 416.468052 -317.18504)
		(width 0.101346)
		(layer "F.Cu")
		(net "M_G_CPU0_SB_DQ<29>")
	)
	(segment
		(start 393.20089 -292.772592)
		(end 393.201144 -292.772592)
		(width 0.0762)
		(layer "F.Cu")
		(net "M_G_CPU0_SB_DQ<29>")
	)
	(segment
		(start 395.228318 -292.832028)
		(end 395.635988 -293.239698)
		(width 0.0762)
		(layer "F.Cu")
		(net "M_G_CPU0_SB_DQ<29>")
	)
	(segment
		(start 411.355286 -316.760098)
		(end 413.403034 -316.760098)
		(width 0.101346)
		(layer "F.Cu")
		(net "M_G_CPU0_SB_DQ<29>")
	)
	(segment
		(start 413.403034 -316.760098)
		(end 415.539428 -317.18504)
		(width 0.101346)
		(layer "F.Cu")
		(net "M_G_CPU0_SB_DQ<29>")
	)
	(segment
		(start 395.635988 -293.525956)
		(end 395.635988 -301.0408)
		(width 0.10668)
		(layer "F.Cu")
		(net "M_G_CPU0_SB_DQ<29>")
	)
	(segment
		(start 394.298424 -292.830758)
		(end 395.188694 -292.832028)
		(width 0.0762)
		(layer "F.Cu")
		(net "M_G_CPU0_SB_DQ<29>")
	)
	(segment
		(start 395.635988 -301.0408)
		(end 411.317694 -316.722506)
		(width 0.10668)
		(layer "F.Cu")
		(net "M_G_CPU0_SB_DQ<29>")
	)
	(segment
		(start 395.188694 -292.832028)
		(end 395.228318 -292.832028)
		(width 0.0762)
		(layer "F.Cu")
		(net "M_G_CPU0_SB_DQ<29>")
	)
	(segment
		(start 395.635988 -293.239698)
		(end 395.635988 -293.525956)
		(width 0.0762)
		(layer "F.Cu")
		(net "M_G_CPU0_SB_DQ<29>")
	)
	(segment
		(start 392.448034 -292.450012)
		(end 392.339576 -292.636702)
		(width 0.0762)
		(layer "F.Cu")
		(net "M_G_CPU0_SB_DQ<29>")
	)
	(arc
		(start 392.491214 -292.820344)
		(mid 392.560968 -292.805387)
		(end 392.626596 -292.777418)
		(width 0.0762)
		(layer "F.Cu")
		(net "M_G_CPU0_SB_DQ<29>")
	)
	(arc
		(start 393.575032 -292.772592)
		(mid 393.857988 -292.696415)
		(end 394.140944 -292.772592)
		(width 0.0762)
		(layer "F.Cu")
		(net "M_G_CPU0_SB_DQ<29>")
	)
	(arc
		(start 393.201144 -292.772592)
		(mid 393.388088 -292.822916)
		(end 393.575032 -292.772592)
		(width 0.0762)
		(layer "F.Cu")
		(net "M_G_CPU0_SB_DQ<29>")
	)
	(arc
		(start 392.339576 -292.636702)
		(mid 392.365493 -292.769744)
		(end 392.491214 -292.820344)
		(width 0.0762)
		(layer "F.Cu")
		(net "M_G_CPU0_SB_DQ<29>")
	)
	(arc
		(start 394.223494 -292.814756)
		(mid 394.260122 -292.826686)
		(end 394.298424 -292.830758)
		(width 0.0762)
		(layer "F.Cu")
		(net "M_G_CPU0_SB_DQ<29>")
	)
	(arc
		(start 394.140944 -292.772592)
		(mid 394.181638 -292.794811)
		(end 394.223494 -292.814756)
		(width 0.0762)
		(layer "F.Cu")
		(net "M_G_CPU0_SB_DQ<29>")
	)
	(arc
		(start 392.634978 -292.772592)
		(mid 392.917934 -292.696415)
		(end 393.20089 -292.772592)
		(width 0.0762)
		(layer "F.Cu")
		(net "M_G_CPU0_SB_DQ<29>")
	)
	(segment
		(start 395.391132 -291.821616)
		(end 395.82598 -292.256464)
		(width 0.0762)
		(layer "F.Cu")
		(net "M_G_CPU0_SB_DQ<28>")
	)
	(segment
		(start 393.857988 -291.640006)
		(end 393.755626 -291.816282)
		(width 0.0762)
		(layer "F.Cu")
		(net "M_G_CPU0_SB_DQ<28>")
	)
	(segment
		(start 402.341588 -305.205384)
		(end 402.341588 -305.370484)
		(width 0.10668)
		(layer "F.Cu")
		(net "M_G_CPU0_SB_DQ<28>")
	)
	(segment
		(start 402.788882 -305.652678)
		(end 404.324312 -307.188108)
		(width 0.10668)
		(layer "F.Cu")
		(net "M_G_CPU0_SB_DQ<28>")
	)
	(segment
		(start 411.008068 -315.060076)
		(end 411.317694 -315.060076)
		(width 0.10668)
		(layer "F.Cu")
		(net "M_G_CPU0_SB_DQ<28>")
	)
	(segment
		(start 394.03655 -291.967412)
		(end 394.044932 -291.962586)
		(width 0.0762)
		(layer "F.Cu")
		(net "M_G_CPU0_SB_DQ<28>")
	)
	(segment
		(start 396.316962 -292.747446)
		(end 396.316962 -299.180758)
		(width 0.10668)
		(layer "F.Cu")
		(net "M_G_CPU0_SB_DQ<28>")
	)
	(segment
		(start 395.82598 -292.256464)
		(end 396.316962 -292.747446)
		(width 0.10668)
		(layer "F.Cu")
		(net "M_G_CPU0_SB_DQ<28>")
	)
	(segment
		(start 401.96389 -306.147216)
		(end 402.12899 -306.147216)
		(width 0.10668)
		(layer "F.Cu")
		(net "M_G_CPU0_SB_DQ<28>")
	)
	(segment
		(start 401.846796 -306.030122)
		(end 401.96389 -306.147216)
		(width 0.10668)
		(layer "F.Cu")
		(net "M_G_CPU0_SB_DQ<28>")
	)
	(segment
		(start 402.341588 -305.370484)
		(end 401.846796 -305.865022)
		(width 0.10668)
		(layer "F.Cu")
		(net "M_G_CPU0_SB_DQ<28>")
	)
	(segment
		(start 402.623782 -305.652678)
		(end 402.788882 -305.652678)
		(width 0.10668)
		(layer "F.Cu")
		(net "M_G_CPU0_SB_DQ<28>")
	)
	(segment
		(start 401.846796 -305.865022)
		(end 401.846796 -306.030122)
		(width 0.10668)
		(layer "F.Cu")
		(net "M_G_CPU0_SB_DQ<28>")
	)
	(segment
		(start 394.327634 -291.886386)
		(end 394.552678 -291.886386)
		(width 0.0762)
		(layer "F.Cu")
		(net "M_G_CPU0_SB_DQ<28>")
	)
	(segment
		(start 411.317694 -315.060076)
		(end 413.929322 -315.060076)
		(width 0.101346)
		(layer "F.Cu")
		(net "M_G_CPU0_SB_DQ<28>")
	)
	(segment
		(start 414.354264 -315.485018)
		(end 416.468052 -315.485018)
		(width 0.101346)
		(layer "F.Cu")
		(net "M_G_CPU0_SB_DQ<28>")
	)
	(segment
		(start 394.552678 -291.886386)
		(end 394.617448 -291.821616)
		(width 0.0762)
		(layer "F.Cu")
		(net "M_G_CPU0_SB_DQ<28>")
	)
	(segment
		(start 404.324312 -307.188108)
		(end 404.324312 -308.37632)
		(width 0.10668)
		(layer "F.Cu")
		(net "M_G_CPU0_SB_DQ<28>")
	)
	(segment
		(start 404.324312 -308.37632)
		(end 411.008068 -315.060076)
		(width 0.10668)
		(layer "F.Cu")
		(net "M_G_CPU0_SB_DQ<28>")
	)
	(segment
		(start 394.617448 -291.821616)
		(end 395.391132 -291.821616)
		(width 0.0762)
		(layer "F.Cu")
		(net "M_G_CPU0_SB_DQ<28>")
	)
	(segment
		(start 396.316962 -299.180758)
		(end 402.341588 -305.205384)
		(width 0.10668)
		(layer "F.Cu")
		(net "M_G_CPU0_SB_DQ<28>")
	)
	(segment
		(start 413.929322 -315.060076)
		(end 414.354264 -315.485018)
		(width 0.101346)
		(layer "F.Cu")
		(net "M_G_CPU0_SB_DQ<28>")
	)
	(segment
		(start 402.12899 -306.147216)
		(end 402.623782 -305.652678)
		(width 0.10668)
		(layer "F.Cu")
		(net "M_G_CPU0_SB_DQ<28>")
	)
	(arc
		(start 393.755626 -291.816282)
		(mid 393.785255 -291.958769)
		(end 393.922504 -292.00729)
		(width 0.0762)
		(layer "F.Cu")
		(net "M_G_CPU0_SB_DQ<28>")
	)
	(arc
		(start 394.280644 -291.888164)
		(mid 394.304121 -291.886788)
		(end 394.327634 -291.886386)
		(width 0.0762)
		(layer "F.Cu")
		(net "M_G_CPU0_SB_DQ<28>")
	)
	(arc
		(start 394.044932 -291.962586)
		(mid 394.158656 -291.912285)
		(end 394.280644 -291.888164)
		(width 0.0762)
		(layer "F.Cu")
		(net "M_G_CPU0_SB_DQ<28>")
	)
	(arc
		(start 393.922504 -292.00729)
		(mid 393.98115 -291.991997)
		(end 394.03655 -291.967412)
		(width 0.0762)
		(layer "F.Cu")
		(net "M_G_CPU0_SB_DQ<28>")
	)
	(segment
		(start 409.06827 -308.61762)
		(end 407.776172 -307.325522)
		(width 0.10668)
		(layer "F.Cu")
		(net "M_G_CPU0_SB_DQ<27>")
	)
	(segment
		(start 407.611072 -307.325522)
		(end 407.493978 -307.442616)
		(width 0.10668)
		(layer "F.Cu")
		(net "M_G_CPU0_SB_DQ<27>")
	)
	(segment
		(start 407.493978 -307.607716)
		(end 411.971236 -312.084974)
		(width 0.10668)
		(layer "F.Cu")
		(net "M_G_CPU0_SB_DQ<27>")
	)
	(segment
		(start 409.350464 -308.500526)
		(end 409.23337 -308.61762)
		(width 0.10668)
		(layer "F.Cu")
		(net "M_G_CPU0_SB_DQ<27>")
	)
	(segment
		(start 407.211784 -307.160422)
		(end 407.611072 -306.761134)
		(width 0.10668)
		(layer "F.Cu")
		(net "M_G_CPU0_SB_DQ<27>")
	)
	(segment
		(start 407.776172 -307.325522)
		(end 407.611072 -307.325522)
		(width 0.10668)
		(layer "F.Cu")
		(net "M_G_CPU0_SB_DQ<27>")
	)
	(segment
		(start 407.493978 -307.442616)
		(end 407.493978 -307.607716)
		(width 0.10668)
		(layer "F.Cu")
		(net "M_G_CPU0_SB_DQ<27>")
	)
	(segment
		(start 409.350464 -308.335426)
		(end 409.350464 -308.500526)
		(width 0.10668)
		(layer "F.Cu")
		(net "M_G_CPU0_SB_DQ<27>")
	)
	(segment
		(start 394.50264 -289.826954)
		(end 395.62659 -289.826954)
		(width 0.0762)
		(layer "F.Cu")
		(net "M_G_CPU0_SB_DQ<27>")
	)
	(segment
		(start 407.046684 -307.160422)
		(end 407.211784 -307.160422)
		(width 0.10668)
		(layer "F.Cu")
		(net "M_G_CPU0_SB_DQ<27>")
	)
	(segment
		(start 409.23337 -308.61762)
		(end 409.06827 -308.61762)
		(width 0.10668)
		(layer "F.Cu")
		(net "M_G_CPU0_SB_DQ<27>")
	)
	(segment
		(start 398.219422 -291.699442)
		(end 398.219422 -298.33316)
		(width 0.10668)
		(layer "F.Cu")
		(net "M_G_CPU0_SB_DQ<27>")
	)
	(segment
		(start 411.971236 -312.084974)
		(end 412.367984 -312.084974)
		(width 0.10668)
		(layer "F.Cu")
		(net "M_G_CPU0_SB_DQ<27>")
	)
	(segment
		(start 407.776172 -306.761134)
		(end 409.350464 -308.335426)
		(width 0.10668)
		(layer "F.Cu")
		(net "M_G_CPU0_SB_DQ<27>")
	)
	(segment
		(start 395.62659 -289.826954)
		(end 396.346934 -289.826954)
		(width 0.10668)
		(layer "F.Cu")
		(net "M_G_CPU0_SB_DQ<27>")
	)
	(segment
		(start 396.346934 -289.826954)
		(end 398.219422 -291.699442)
		(width 0.10668)
		(layer "F.Cu")
		(net "M_G_CPU0_SB_DQ<27>")
	)
	(segment
		(start 407.611072 -306.761134)
		(end 407.776172 -306.761134)
		(width 0.10668)
		(layer "F.Cu")
		(net "M_G_CPU0_SB_DQ<27>")
	)
	(segment
		(start 394.03655 -289.692588)
		(end 394.044932 -289.697414)
		(width 0.0762)
		(layer "F.Cu")
		(net "M_G_CPU0_SB_DQ<27>")
	)
	(segment
		(start 398.219422 -298.33316)
		(end 407.046684 -307.160422)
		(width 0.10668)
		(layer "F.Cu")
		(net "M_G_CPU0_SB_DQ<27>")
	)
	(arc
		(start 393.104878 -289.697414)
		(mid 393.387834 -289.773591)
		(end 393.67079 -289.697414)
		(width 0.0762)
		(layer "F.Cu")
		(net "M_G_CPU0_SB_DQ<27>")
	)
	(arc
		(start 393.67079 -289.697414)
		(mid 393.853041 -289.647064)
		(end 394.03655 -289.692588)
		(width 0.0762)
		(layer "F.Cu")
		(net "M_G_CPU0_SB_DQ<27>")
	)
	(arc
		(start 392.73099 -289.697414)
		(mid 392.917934 -289.647159)
		(end 393.104878 -289.697414)
		(width 0.0762)
		(layer "F.Cu")
		(net "M_G_CPU0_SB_DQ<27>")
	)
	(arc
		(start 391.97788 -290.019994)
		(mid 392.173229 -289.836175)
		(end 392.434064 -289.773614)
		(width 0.0762)
		(layer "F.Cu")
		(net "M_G_CPU0_SB_DQ<27>")
	)
	(arc
		(start 392.434064 -289.773614)
		(mid 392.587813 -289.756105)
		(end 392.73099 -289.697414)
		(width 0.0762)
		(layer "F.Cu")
		(net "M_G_CPU0_SB_DQ<27>")
	)
	(arc
		(start 394.044932 -289.697414)
		(mid 394.147826 -289.749786)
		(end 394.256006 -289.790124)
		(width 0.0762)
		(layer "F.Cu")
		(net "M_G_CPU0_SB_DQ<27>")
	)
	(arc
		(start 394.256006 -289.790124)
		(mid 394.377955 -289.817701)
		(end 394.50264 -289.826954)
		(width 0.0762)
		(layer "F.Cu")
		(net "M_G_CPU0_SB_DQ<27>")
	)
	(segment
		(start 410.33192 -309.05831)
		(end 410.618178 -308.772052)
		(width 0.10668)
		(layer "F.Cu")
		(net "M_G_CPU0_SB_DQ<26>")
	)
	(segment
		(start 407.28265 -305.96332)
		(end 407.28265 -305.79822)
		(width 0.10668)
		(layer "F.Cu")
		(net "M_G_CPU0_SB_DQ<26>")
	)
	(segment
		(start 407.000456 -306.080414)
		(end 407.165556 -306.080414)
		(width 0.10668)
		(layer "F.Cu")
		(net "M_G_CPU0_SB_DQ<26>")
	)
	(segment
		(start 407.28265 -305.79822)
		(end 405.834088 -304.349658)
		(width 0.10668)
		(layer "F.Cu")
		(net "M_G_CPU0_SB_DQ<26>")
	)
	(segment
		(start 410.618178 -308.772052)
		(end 410.783278 -308.772052)
		(width 0.10668)
		(layer "F.Cu")
		(net "M_G_CPU0_SB_DQ<26>")
	)
	(segment
		(start 405.834088 -304.349658)
		(end 405.834088 -304.184558)
		(width 0.10668)
		(layer "F.Cu")
		(net "M_G_CPU0_SB_DQ<26>")
	)
	(segment
		(start 407.165556 -306.080414)
		(end 407.28265 -305.96332)
		(width 0.10668)
		(layer "F.Cu")
		(net "M_G_CPU0_SB_DQ<26>")
	)
	(segment
		(start 395.67866 -289.146234)
		(end 396.691866 -289.146234)
		(width 0.10668)
		(layer "F.Cu")
		(net "M_G_CPU0_SB_DQ<26>")
	)
	(segment
		(start 411.493462 -310.384952)
		(end 412.367984 -310.384952)
		(width 0.10668)
		(layer "F.Cu")
		(net "M_G_CPU0_SB_DQ<26>")
	)
	(segment
		(start 395.155928 -288.836862)
		(end 395.4653 -289.146234)
		(width 0.0762)
		(layer "F.Cu")
		(net "M_G_CPU0_SB_DQ<26>")
	)
	(segment
		(start 394.327888 -288.836862)
		(end 395.155928 -288.836862)
		(width 0.0762)
		(layer "F.Cu")
		(net "M_G_CPU0_SB_DQ<26>")
	)
	(segment
		(start 396.691866 -289.146234)
		(end 398.900142 -291.35451)
		(width 0.10668)
		(layer "F.Cu")
		(net "M_G_CPU0_SB_DQ<26>")
	)
	(segment
		(start 405.951182 -304.067464)
		(end 406.116282 -304.067464)
		(width 0.10668)
		(layer "F.Cu")
		(net "M_G_CPU0_SB_DQ<26>")
	)
	(segment
		(start 410.031184 -308.922674)
		(end 410.16682 -309.05831)
		(width 0.10668)
		(layer "F.Cu")
		(net "M_G_CPU0_SB_DQ<26>")
	)
	(segment
		(start 398.900142 -291.35451)
		(end 398.900142 -297.9801)
		(width 0.10668)
		(layer "F.Cu")
		(net "M_G_CPU0_SB_DQ<26>")
	)
	(segment
		(start 410.614114 -309.505604)
		(end 411.493462 -310.384952)
		(width 0.10668)
		(layer "F.Cu")
		(net "M_G_CPU0_SB_DQ<26>")
	)
	(segment
		(start 405.834088 -304.184558)
		(end 405.951182 -304.067464)
		(width 0.10668)
		(layer "F.Cu")
		(net "M_G_CPU0_SB_DQ<26>")
	)
	(segment
		(start 395.4653 -289.146234)
		(end 395.67866 -289.146234)
		(width 0.0762)
		(layer "F.Cu")
		(net "M_G_CPU0_SB_DQ<26>")
	)
	(segment
		(start 410.900372 -309.054246)
		(end 410.614114 -309.340504)
		(width 0.10668)
		(layer "F.Cu")
		(net "M_G_CPU0_SB_DQ<26>")
	)
	(segment
		(start 410.783278 -308.772052)
		(end 410.900372 -308.889146)
		(width 0.10668)
		(layer "F.Cu")
		(net "M_G_CPU0_SB_DQ<26>")
	)
	(segment
		(start 410.031184 -307.982366)
		(end 410.031184 -308.922674)
		(width 0.10668)
		(layer "F.Cu")
		(net "M_G_CPU0_SB_DQ<26>")
	)
	(segment
		(start 410.16682 -309.05831)
		(end 410.33192 -309.05831)
		(width 0.10668)
		(layer "F.Cu")
		(net "M_G_CPU0_SB_DQ<26>")
	)
	(segment
		(start 398.900142 -297.9801)
		(end 407.000456 -306.080414)
		(width 0.10668)
		(layer "F.Cu")
		(net "M_G_CPU0_SB_DQ<26>")
	)
	(segment
		(start 410.900372 -308.889146)
		(end 410.900372 -309.054246)
		(width 0.10668)
		(layer "F.Cu")
		(net "M_G_CPU0_SB_DQ<26>")
	)
	(segment
		(start 406.116282 -304.067464)
		(end 410.031184 -307.982366)
		(width 0.10668)
		(layer "F.Cu")
		(net "M_G_CPU0_SB_DQ<26>")
	)
	(segment
		(start 410.614114 -309.340504)
		(end 410.614114 -309.505604)
		(width 0.10668)
		(layer "F.Cu")
		(net "M_G_CPU0_SB_DQ<26>")
	)
	(arc
		(start 393.916916 -288.96056)
		(mid 393.936265 -288.958222)
		(end 393.955524 -288.955226)
		(width 0.0762)
		(layer "F.Cu")
		(net "M_G_CPU0_SB_DQ<26>")
	)
	(arc
		(start 394.2969 -288.838132)
		(mid 394.312381 -288.837176)
		(end 394.327888 -288.836862)
		(width 0.0762)
		(layer "F.Cu")
		(net "M_G_CPU0_SB_DQ<26>")
	)
	(arc
		(start 393.955524 -288.955226)
		(mid 394.051233 -288.929514)
		(end 394.140944 -288.887408)
		(width 0.0762)
		(layer "F.Cu")
		(net "M_G_CPU0_SB_DQ<26>")
	)
	(arc
		(start 394.140944 -288.887408)
		(mid 394.216184 -288.854095)
		(end 394.2969 -288.838132)
		(width 0.0762)
		(layer "F.Cu")
		(net "M_G_CPU0_SB_DQ<26>")
	)
	(arc
		(start 393.387834 -289.209988)
		(mid 393.631265 -289.040501)
		(end 393.916916 -288.96056)
		(width 0.0762)
		(layer "F.Cu")
		(net "M_G_CPU0_SB_DQ<26>")
	)
	(segment
		(start 396.550642 -289.486594)
		(end 398.559782 -291.495734)
		(width 0.10668)
		(layer "F.Cu")
		(net "M_G_CPU0_SB_DQ<25>")
	)
	(segment
		(start 406.859232 -306.420774)
		(end 407.988008 -306.420774)
		(width 0.10668)
		(layer "F.Cu")
		(net "M_G_CPU0_SB_DQ<25>")
	)
	(segment
		(start 393.20089 -289.532568)
		(end 393.201144 -289.532568)
		(width 0.0762)
		(layer "F.Cu")
		(net "M_G_CPU0_SB_DQ<25>")
	)
	(segment
		(start 414.084516 -311.23509)
		(end 416.468052 -311.23509)
		(width 0.101346)
		(layer "F.Cu")
		(net "M_G_CPU0_SB_DQ<25>")
	)
	(segment
		(start 395.407134 -289.486594)
		(end 395.652498 -289.486594)
		(width 0.0762)
		(layer "F.Cu")
		(net "M_G_CPU0_SB_DQ<25>")
	)
	(segment
		(start 394.298424 -289.590734)
		(end 395.188694 -289.592004)
		(width 0.0762)
		(layer "F.Cu")
		(net "M_G_CPU0_SB_DQ<25>")
	)
	(segment
		(start 409.690824 -309.252366)
		(end 411.248606 -310.810148)
		(width 0.10668)
		(layer "F.Cu")
		(net "M_G_CPU0_SB_DQ<25>")
	)
	(segment
		(start 392.448034 -289.209988)
		(end 392.339576 -289.396678)
		(width 0.0762)
		(layer "F.Cu")
		(net "M_G_CPU0_SB_DQ<25>")
	)
	(segment
		(start 395.188694 -289.592004)
		(end 395.301724 -289.592004)
		(width 0.0762)
		(layer "F.Cu")
		(net "M_G_CPU0_SB_DQ<25>")
	)
	(segment
		(start 395.301724 -289.592004)
		(end 395.407134 -289.486594)
		(width 0.0762)
		(layer "F.Cu")
		(net "M_G_CPU0_SB_DQ<25>")
	)
	(segment
		(start 398.559782 -298.121324)
		(end 406.859232 -306.420774)
		(width 0.10668)
		(layer "F.Cu")
		(net "M_G_CPU0_SB_DQ<25>")
	)
	(segment
		(start 398.559782 -291.495734)
		(end 398.559782 -298.121324)
		(width 0.10668)
		(layer "F.Cu")
		(net "M_G_CPU0_SB_DQ<25>")
	)
	(segment
		(start 395.652498 -289.486594)
		(end 396.550642 -289.486594)
		(width 0.10668)
		(layer "F.Cu")
		(net "M_G_CPU0_SB_DQ<25>")
	)
	(segment
		(start 413.659574 -310.810148)
		(end 414.084516 -311.23509)
		(width 0.101346)
		(layer "F.Cu")
		(net "M_G_CPU0_SB_DQ<25>")
	)
	(segment
		(start 392.626596 -289.537394)
		(end 392.634978 -289.532568)
		(width 0.0762)
		(layer "F.Cu")
		(net "M_G_CPU0_SB_DQ<25>")
	)
	(segment
		(start 411.248606 -310.810148)
		(end 413.659574 -310.810148)
		(width 0.101346)
		(layer "F.Cu")
		(net "M_G_CPU0_SB_DQ<25>")
	)
	(segment
		(start 409.690824 -308.12359)
		(end 409.690824 -309.252366)
		(width 0.10668)
		(layer "F.Cu")
		(net "M_G_CPU0_SB_DQ<25>")
	)
	(segment
		(start 407.988008 -306.420774)
		(end 409.690824 -308.12359)
		(width 0.10668)
		(layer "F.Cu")
		(net "M_G_CPU0_SB_DQ<25>")
	)
	(arc
		(start 392.634978 -289.532568)
		(mid 392.917934 -289.456391)
		(end 393.20089 -289.532568)
		(width 0.0762)
		(layer "F.Cu")
		(net "M_G_CPU0_SB_DQ<25>")
	)
	(arc
		(start 394.140944 -289.532568)
		(mid 394.181638 -289.554787)
		(end 394.223494 -289.574732)
		(width 0.0762)
		(layer "F.Cu")
		(net "M_G_CPU0_SB_DQ<25>")
	)
	(arc
		(start 392.339576 -289.396678)
		(mid 392.365493 -289.52972)
		(end 392.491214 -289.58032)
		(width 0.0762)
		(layer "F.Cu")
		(net "M_G_CPU0_SB_DQ<25>")
	)
	(arc
		(start 392.491214 -289.58032)
		(mid 392.560968 -289.565363)
		(end 392.626596 -289.537394)
		(width 0.0762)
		(layer "F.Cu")
		(net "M_G_CPU0_SB_DQ<25>")
	)
	(arc
		(start 393.575032 -289.532568)
		(mid 393.857988 -289.456391)
		(end 394.140944 -289.532568)
		(width 0.0762)
		(layer "F.Cu")
		(net "M_G_CPU0_SB_DQ<25>")
	)
	(arc
		(start 393.201144 -289.532568)
		(mid 393.388088 -289.582892)
		(end 393.575032 -289.532568)
		(width 0.0762)
		(layer "F.Cu")
		(net "M_G_CPU0_SB_DQ<25>")
	)
	(arc
		(start 394.223494 -289.574732)
		(mid 394.260122 -289.586662)
		(end 394.298424 -289.590734)
		(width 0.0762)
		(layer "F.Cu")
		(net "M_G_CPU0_SB_DQ<25>")
	)
	(segment
		(start 415.407348 -309.535068)
		(end 416.468052 -309.535068)
		(width 0.101346)
		(layer "F.Cu")
		(net "M_G_CPU0_SB_DQ<24>")
	)
	(segment
		(start 414.389316 -310.189372)
		(end 414.504632 -310.074056)
		(width 0.101346)
		(layer "F.Cu")
		(net "M_G_CPU0_SB_DQ<24>")
	)
	(segment
		(start 395.642592 -288.805874)
		(end 396.83309 -288.805874)
		(width 0.10668)
		(layer "F.Cu")
		(net "M_G_CPU0_SB_DQ<24>")
	)
	(segment
		(start 394.327634 -288.646362)
		(end 395.234922 -288.646362)
		(width 0.0762)
		(layer "F.Cu")
		(net "M_G_CPU0_SB_DQ<24>")
	)
	(segment
		(start 399.240502 -297.46702)
		(end 405.500586 -303.727104)
		(width 0.10668)
		(layer "F.Cu")
		(net "M_G_CPU0_SB_DQ<24>")
	)
	(segment
		(start 411.260798 -308.730396)
		(end 411.260798 -309.670704)
		(width 0.10668)
		(layer "F.Cu")
		(net "M_G_CPU0_SB_DQ<24>")
	)
	(segment
		(start 411.387798 -309.797704)
		(end 411.550104 -309.96001)
		(width 0.101346)
		(layer "F.Cu")
		(net "M_G_CPU0_SB_DQ<24>")
	)
	(segment
		(start 396.83309 -288.805874)
		(end 399.240502 -291.213286)
		(width 0.10668)
		(layer "F.Cu")
		(net "M_G_CPU0_SB_DQ<24>")
	)
	(segment
		(start 413.32658 -309.96001)
		(end 413.751522 -309.535068)
		(width 0.101346)
		(layer "F.Cu")
		(net "M_G_CPU0_SB_DQ<24>")
	)
	(segment
		(start 415.292032 -310.074056)
		(end 415.292032 -309.650384)
		(width 0.101346)
		(layer "F.Cu")
		(net "M_G_CPU0_SB_DQ<24>")
	)
	(segment
		(start 411.260798 -309.670704)
		(end 411.387798 -309.797704)
		(width 0.10668)
		(layer "F.Cu")
		(net "M_G_CPU0_SB_DQ<24>")
	)
	(segment
		(start 414.898332 -310.074056)
		(end 415.013648 -310.189372)
		(width 0.101346)
		(layer "F.Cu")
		(net "M_G_CPU0_SB_DQ<24>")
	)
	(segment
		(start 415.176716 -310.189372)
		(end 415.292032 -310.074056)
		(width 0.101346)
		(layer "F.Cu")
		(net "M_G_CPU0_SB_DQ<24>")
	)
	(segment
		(start 414.898332 -309.650384)
		(end 414.898332 -310.074056)
		(width 0.101346)
		(layer "F.Cu")
		(net "M_G_CPU0_SB_DQ<24>")
	)
	(segment
		(start 415.292032 -309.650384)
		(end 415.407348 -309.535068)
		(width 0.101346)
		(layer "F.Cu")
		(net "M_G_CPU0_SB_DQ<24>")
	)
	(segment
		(start 413.995616 -309.535068)
		(end 414.110932 -309.650384)
		(width 0.101346)
		(layer "F.Cu")
		(net "M_G_CPU0_SB_DQ<24>")
	)
	(segment
		(start 405.500586 -303.727104)
		(end 406.257506 -303.727104)
		(width 0.10668)
		(layer "F.Cu")
		(net "M_G_CPU0_SB_DQ<24>")
	)
	(segment
		(start 395.394434 -288.805874)
		(end 395.642592 -288.805874)
		(width 0.0762)
		(layer "F.Cu")
		(net "M_G_CPU0_SB_DQ<24>")
	)
	(segment
		(start 406.257506 -303.727104)
		(end 411.260798 -308.730396)
		(width 0.10668)
		(layer "F.Cu")
		(net "M_G_CPU0_SB_DQ<24>")
	)
	(segment
		(start 414.504632 -309.650384)
		(end 414.619948 -309.535068)
		(width 0.101346)
		(layer "F.Cu")
		(net "M_G_CPU0_SB_DQ<24>")
	)
	(segment
		(start 395.234922 -288.646362)
		(end 395.394434 -288.805874)
		(width 0.0762)
		(layer "F.Cu")
		(net "M_G_CPU0_SB_DQ<24>")
	)
	(segment
		(start 414.110932 -309.650384)
		(end 414.110932 -310.074056)
		(width 0.101346)
		(layer "F.Cu")
		(net "M_G_CPU0_SB_DQ<24>")
	)
	(segment
		(start 414.226248 -310.189372)
		(end 414.389316 -310.189372)
		(width 0.101346)
		(layer "F.Cu")
		(net "M_G_CPU0_SB_DQ<24>")
	)
	(segment
		(start 414.783016 -309.535068)
		(end 414.898332 -309.650384)
		(width 0.101346)
		(layer "F.Cu")
		(net "M_G_CPU0_SB_DQ<24>")
	)
	(segment
		(start 414.619948 -309.535068)
		(end 414.783016 -309.535068)
		(width 0.101346)
		(layer "F.Cu")
		(net "M_G_CPU0_SB_DQ<24>")
	)
	(segment
		(start 414.504632 -310.074056)
		(end 414.504632 -309.650384)
		(width 0.101346)
		(layer "F.Cu")
		(net "M_G_CPU0_SB_DQ<24>")
	)
	(segment
		(start 414.110932 -310.074056)
		(end 414.226248 -310.189372)
		(width 0.101346)
		(layer "F.Cu")
		(net "M_G_CPU0_SB_DQ<24>")
	)
	(segment
		(start 393.857988 -288.399982)
		(end 393.755626 -288.576258)
		(width 0.0762)
		(layer "F.Cu")
		(net "M_G_CPU0_SB_DQ<24>")
	)
	(segment
		(start 399.240502 -291.213286)
		(end 399.240502 -297.46702)
		(width 0.10668)
		(layer "F.Cu")
		(net "M_G_CPU0_SB_DQ<24>")
	)
	(segment
		(start 415.013648 -310.189372)
		(end 415.176716 -310.189372)
		(width 0.101346)
		(layer "F.Cu")
		(net "M_G_CPU0_SB_DQ<24>")
	)
	(segment
		(start 394.03655 -288.727388)
		(end 394.044932 -288.722562)
		(width 0.0762)
		(layer "F.Cu")
		(net "M_G_CPU0_SB_DQ<24>")
	)
	(segment
		(start 413.751522 -309.535068)
		(end 413.995616 -309.535068)
		(width 0.101346)
		(layer "F.Cu")
		(net "M_G_CPU0_SB_DQ<24>")
	)
	(segment
		(start 411.550104 -309.96001)
		(end 413.32658 -309.96001)
		(width 0.101346)
		(layer "F.Cu")
		(net "M_G_CPU0_SB_DQ<24>")
	)
	(arc
		(start 393.755626 -288.576258)
		(mid 393.785255 -288.718745)
		(end 393.922504 -288.767266)
		(width 0.0762)
		(layer "F.Cu")
		(net "M_G_CPU0_SB_DQ<24>")
	)
	(arc
		(start 394.280644 -288.64814)
		(mid 394.304121 -288.646764)
		(end 394.327634 -288.646362)
		(width 0.0762)
		(layer "F.Cu")
		(net "M_G_CPU0_SB_DQ<24>")
	)
	(arc
		(start 394.044932 -288.722562)
		(mid 394.158656 -288.672261)
		(end 394.280644 -288.64814)
		(width 0.0762)
		(layer "F.Cu")
		(net "M_G_CPU0_SB_DQ<24>")
	)
	(arc
		(start 393.922504 -288.767266)
		(mid 393.98115 -288.751973)
		(end 394.03655 -288.727388)
		(width 0.0762)
		(layer "F.Cu")
		(net "M_G_CPU0_SB_DQ<24>")
	)
	(segment
		(start 405.85517 -303.269904)
		(end 406.06853 -303.056544)
		(width 0.10668)
		(layer "F.Cu")
		(net "M_G_CPU0_SB_DQ<23>")
	)
	(segment
		(start 399.697702 -291.016182)
		(end 399.697702 -297.277536)
		(width 0.10668)
		(layer "F.Cu")
		(net "M_G_CPU0_SB_DQ<23>")
	)
	(segment
		(start 404.4442 -301.858934)
		(end 404.4442 -302.024034)
		(width 0.10668)
		(layer "F.Cu")
		(net "M_G_CPU0_SB_DQ<23>")
	)
	(segment
		(start 411.86227 -308.685184)
		(end 412.367984 -308.685184)
		(width 0.10668)
		(layer "F.Cu")
		(net "M_G_CPU0_SB_DQ<23>")
	)
	(segment
		(start 403.976078 -300.798992)
		(end 404.093172 -300.916086)
		(width 0.10668)
		(layer "F.Cu")
		(net "M_G_CPU0_SB_DQ<23>")
	)
	(segment
		(start 405.008588 -302.423322)
		(end 405.008588 -302.588422)
		(width 0.10668)
		(layer "F.Cu")
		(net "M_G_CPU0_SB_DQ<23>")
	)
	(segment
		(start 403.996906 -301.57674)
		(end 404.162006 -301.57674)
		(width 0.10668)
		(layer "F.Cu")
		(net "M_G_CPU0_SB_DQ<23>")
	)
	(segment
		(start 405.669242 -302.492156)
		(end 405.786336 -302.60925)
		(width 0.10668)
		(layer "F.Cu")
		(net "M_G_CPU0_SB_DQ<23>")
	)
	(segment
		(start 404.093172 -300.916086)
		(end 404.093172 -301.081186)
		(width 0.10668)
		(layer "F.Cu")
		(net "M_G_CPU0_SB_DQ<23>")
	)
	(segment
		(start 405.221948 -302.209962)
		(end 405.008588 -302.423322)
		(width 0.10668)
		(layer "F.Cu")
		(net "M_G_CPU0_SB_DQ<23>")
	)
	(segment
		(start 405.786336 -302.77435)
		(end 405.572976 -302.98771)
		(width 0.10668)
		(layer "F.Cu")
		(net "M_G_CPU0_SB_DQ<23>")
	)
	(segment
		(start 404.093172 -301.081186)
		(end 403.879812 -301.294546)
		(width 0.10668)
		(layer "F.Cu")
		(net "M_G_CPU0_SB_DQ<23>")
	)
	(segment
		(start 404.726394 -302.141128)
		(end 404.939754 -301.927768)
		(width 0.10668)
		(layer "F.Cu")
		(net "M_G_CPU0_SB_DQ<23>")
	)
	(segment
		(start 404.375366 -301.36338)
		(end 404.540466 -301.36338)
		(width 0.10668)
		(layer "F.Cu")
		(net "M_G_CPU0_SB_DQ<23>")
	)
	(segment
		(start 405.104854 -301.927768)
		(end 405.221948 -302.044862)
		(width 0.10668)
		(layer "F.Cu")
		(net "M_G_CPU0_SB_DQ<23>")
	)
	(segment
		(start 405.572976 -302.98771)
		(end 405.572976 -303.15281)
		(width 0.10668)
		(layer "F.Cu")
		(net "M_G_CPU0_SB_DQ<23>")
	)
	(segment
		(start 404.4442 -302.024034)
		(end 404.561294 -302.141128)
		(width 0.10668)
		(layer "F.Cu")
		(net "M_G_CPU0_SB_DQ<23>")
	)
	(segment
		(start 394.331698 -288.181542)
		(end 395.1859 -288.181542)
		(width 0.0762)
		(layer "F.Cu")
		(net "M_G_CPU0_SB_DQ<23>")
	)
	(segment
		(start 397.030194 -288.348674)
		(end 399.697702 -291.016182)
		(width 0.10668)
		(layer "F.Cu")
		(net "M_G_CPU0_SB_DQ<23>")
	)
	(segment
		(start 405.504142 -302.492156)
		(end 405.669242 -302.492156)
		(width 0.10668)
		(layer "F.Cu")
		(net "M_G_CPU0_SB_DQ<23>")
	)
	(segment
		(start 405.69007 -303.269904)
		(end 405.85517 -303.269904)
		(width 0.10668)
		(layer "F.Cu")
		(net "M_G_CPU0_SB_DQ<23>")
	)
	(segment
		(start 399.697702 -297.277536)
		(end 403.432518 -301.012352)
		(width 0.10668)
		(layer "F.Cu")
		(net "M_G_CPU0_SB_DQ<23>")
	)
	(segment
		(start 404.65756 -301.480474)
		(end 404.65756 -301.645574)
		(width 0.10668)
		(layer "F.Cu")
		(net "M_G_CPU0_SB_DQ<23>")
	)
	(segment
		(start 405.008588 -302.588422)
		(end 405.125682 -302.705516)
		(width 0.10668)
		(layer "F.Cu")
		(net "M_G_CPU0_SB_DQ<23>")
	)
	(segment
		(start 404.540466 -301.36338)
		(end 404.65756 -301.480474)
		(width 0.10668)
		(layer "F.Cu")
		(net "M_G_CPU0_SB_DQ<23>")
	)
	(segment
		(start 403.810978 -300.798992)
		(end 403.976078 -300.798992)
		(width 0.10668)
		(layer "F.Cu")
		(net "M_G_CPU0_SB_DQ<23>")
	)
	(segment
		(start 395.353032 -288.348674)
		(end 395.887448 -288.348674)
		(width 0.0762)
		(layer "F.Cu")
		(net "M_G_CPU0_SB_DQ<23>")
	)
	(segment
		(start 406.06853 -303.056544)
		(end 406.23363 -303.056544)
		(width 0.10668)
		(layer "F.Cu")
		(net "M_G_CPU0_SB_DQ<23>")
	)
	(segment
		(start 405.290782 -302.705516)
		(end 405.504142 -302.492156)
		(width 0.10668)
		(layer "F.Cu")
		(net "M_G_CPU0_SB_DQ<23>")
	)
	(segment
		(start 395.1859 -288.181542)
		(end 395.353032 -288.348674)
		(width 0.0762)
		(layer "F.Cu")
		(net "M_G_CPU0_SB_DQ<23>")
	)
	(segment
		(start 404.561294 -302.141128)
		(end 404.726394 -302.141128)
		(width 0.10668)
		(layer "F.Cu")
		(net "M_G_CPU0_SB_DQ<23>")
	)
	(segment
		(start 404.939754 -301.927768)
		(end 405.104854 -301.927768)
		(width 0.10668)
		(layer "F.Cu")
		(net "M_G_CPU0_SB_DQ<23>")
	)
	(segment
		(start 395.887448 -288.348674)
		(end 397.030194 -288.348674)
		(width 0.10668)
		(layer "F.Cu")
		(net "M_G_CPU0_SB_DQ<23>")
	)
	(segment
		(start 403.597618 -301.012352)
		(end 403.810978 -300.798992)
		(width 0.10668)
		(layer "F.Cu")
		(net "M_G_CPU0_SB_DQ<23>")
	)
	(segment
		(start 404.65756 -301.645574)
		(end 404.4442 -301.858934)
		(width 0.10668)
		(layer "F.Cu")
		(net "M_G_CPU0_SB_DQ<23>")
	)
	(segment
		(start 405.125682 -302.705516)
		(end 405.290782 -302.705516)
		(width 0.10668)
		(layer "F.Cu")
		(net "M_G_CPU0_SB_DQ<23>")
	)
	(segment
		(start 405.572976 -303.15281)
		(end 405.69007 -303.269904)
		(width 0.10668)
		(layer "F.Cu")
		(net "M_G_CPU0_SB_DQ<23>")
	)
	(segment
		(start 394.03655 -288.07283)
		(end 394.044932 -288.077656)
		(width 0.0762)
		(layer "F.Cu")
		(net "M_G_CPU0_SB_DQ<23>")
	)
	(segment
		(start 403.432518 -301.012352)
		(end 403.597618 -301.012352)
		(width 0.10668)
		(layer "F.Cu")
		(net "M_G_CPU0_SB_DQ<23>")
	)
	(segment
		(start 406.23363 -303.056544)
		(end 411.86227 -308.685184)
		(width 0.10668)
		(layer "F.Cu")
		(net "M_G_CPU0_SB_DQ<23>")
	)
	(segment
		(start 403.879812 -301.459646)
		(end 403.996906 -301.57674)
		(width 0.10668)
		(layer "F.Cu")
		(net "M_G_CPU0_SB_DQ<23>")
	)
	(segment
		(start 404.162006 -301.57674)
		(end 404.375366 -301.36338)
		(width 0.10668)
		(layer "F.Cu")
		(net "M_G_CPU0_SB_DQ<23>")
	)
	(segment
		(start 405.786336 -302.60925)
		(end 405.786336 -302.77435)
		(width 0.10668)
		(layer "F.Cu")
		(net "M_G_CPU0_SB_DQ<23>")
	)
	(segment
		(start 403.879812 -301.294546)
		(end 403.879812 -301.459646)
		(width 0.10668)
		(layer "F.Cu")
		(net "M_G_CPU0_SB_DQ<23>")
	)
	(segment
		(start 405.221948 -302.044862)
		(end 405.221948 -302.209962)
		(width 0.10668)
		(layer "F.Cu")
		(net "M_G_CPU0_SB_DQ<23>")
	)
	(arc
		(start 392.434064 -288.153856)
		(mid 392.587813 -288.136347)
		(end 392.73099 -288.077656)
		(width 0.0762)
		(layer "F.Cu")
		(net "M_G_CPU0_SB_DQ<23>")
	)
	(arc
		(start 394.044932 -288.077656)
		(mid 394.147826 -288.130028)
		(end 394.256006 -288.170366)
		(width 0.0762)
		(layer "F.Cu")
		(net "M_G_CPU0_SB_DQ<23>")
	)
	(arc
		(start 392.73099 -288.077656)
		(mid 392.917934 -288.027401)
		(end 393.104878 -288.077656)
		(width 0.0762)
		(layer "F.Cu")
		(net "M_G_CPU0_SB_DQ<23>")
	)
	(arc
		(start 391.97788 -288.399982)
		(mid 392.187962 -288.243537)
		(end 392.434064 -288.153856)
		(width 0.0762)
		(layer "F.Cu")
		(net "M_G_CPU0_SB_DQ<23>")
	)
	(arc
		(start 394.256006 -288.170366)
		(mid 394.293432 -288.178805)
		(end 394.331698 -288.181542)
		(width 0.0762)
		(layer "F.Cu")
		(net "M_G_CPU0_SB_DQ<23>")
	)
	(arc
		(start 393.104878 -288.077656)
		(mid 393.387834 -288.153833)
		(end 393.67079 -288.077656)
		(width 0.0762)
		(layer "F.Cu")
		(net "M_G_CPU0_SB_DQ<23>")
	)
	(arc
		(start 393.67079 -288.077656)
		(mid 393.853041 -288.027306)
		(end 394.03655 -288.07283)
		(width 0.0762)
		(layer "F.Cu")
		(net "M_G_CPU0_SB_DQ<23>")
	)
	(segment
		(start 402.403818 -298.406566)
		(end 402.179282 -298.630848)
		(width 0.10668)
		(layer "F.Cu")
		(net "M_G_CPU0_SB_DQ<22>")
	)
	(segment
		(start 397.312642 -287.667954)
		(end 400.378422 -290.733734)
		(width 0.10668)
		(layer "F.Cu")
		(net "M_G_CPU0_SB_DQ<22>")
	)
	(segment
		(start 401.275042 -297.11269)
		(end 401.275042 -297.27779)
		(width 0.10668)
		(layer "F.Cu")
		(net "M_G_CPU0_SB_DQ<22>")
	)
	(segment
		(start 411.173422 -306.985162)
		(end 412.367984 -306.985162)
		(width 0.10668)
		(layer "F.Cu")
		(net "M_G_CPU0_SB_DQ<22>")
	)
	(segment
		(start 402.860764 -299.47743)
		(end 403.025864 -299.47743)
		(width 0.10668)
		(layer "F.Cu")
		(net "M_G_CPU0_SB_DQ<22>")
	)
	(segment
		(start 401.050506 -297.667172)
		(end 401.1676 -297.784266)
		(width 0.10668)
		(layer "F.Cu")
		(net "M_G_CPU0_SB_DQ<22>")
	)
	(segment
		(start 403.814788 -299.817536)
		(end 403.979888 -299.817536)
		(width 0.10668)
		(layer "F.Cu")
		(net "M_G_CPU0_SB_DQ<22>")
	)
	(segment
		(start 395.157452 -287.217104)
		(end 395.608302 -287.667954)
		(width 0.0762)
		(layer "F.Cu")
		(net "M_G_CPU0_SB_DQ<22>")
	)
	(segment
		(start 403.025864 -299.47743)
		(end 403.2504 -299.253148)
		(width 0.10668)
		(layer "F.Cu")
		(net "M_G_CPU0_SB_DQ<22>")
	)
	(segment
		(start 401.83943 -297.677078)
		(end 401.83943 -297.842178)
		(width 0.10668)
		(layer "F.Cu")
		(net "M_G_CPU0_SB_DQ<22>")
	)
	(segment
		(start 403.308058 -299.924724)
		(end 403.425152 -300.041818)
		(width 0.10668)
		(layer "F.Cu")
		(net "M_G_CPU0_SB_DQ<22>")
	)
	(segment
		(start 401.614894 -298.23156)
		(end 401.731988 -298.348654)
		(width 0.10668)
		(layer "F.Cu")
		(net "M_G_CPU0_SB_DQ<22>")
	)
	(segment
		(start 401.731988 -298.348654)
		(end 401.897088 -298.348654)
		(width 0.10668)
		(layer "F.Cu")
		(net "M_G_CPU0_SB_DQ<22>")
	)
	(segment
		(start 403.308058 -299.759624)
		(end 403.308058 -299.924724)
		(width 0.10668)
		(layer "F.Cu")
		(net "M_G_CPU0_SB_DQ<22>")
	)
	(segment
		(start 403.2504 -299.253148)
		(end 403.4155 -299.253148)
		(width 0.10668)
		(layer "F.Cu")
		(net "M_G_CPU0_SB_DQ<22>")
	)
	(segment
		(start 402.851112 -298.68876)
		(end 402.968206 -298.805854)
		(width 0.10668)
		(layer "F.Cu")
		(net "M_G_CPU0_SB_DQ<22>")
	)
	(segment
		(start 401.722336 -297.559984)
		(end 401.83943 -297.677078)
		(width 0.10668)
		(layer "F.Cu")
		(net "M_G_CPU0_SB_DQ<22>")
	)
	(segment
		(start 403.425152 -300.041818)
		(end 403.590252 -300.041818)
		(width 0.10668)
		(layer "F.Cu")
		(net "M_G_CPU0_SB_DQ<22>")
	)
	(segment
		(start 401.050506 -297.502072)
		(end 401.050506 -297.667172)
		(width 0.10668)
		(layer "F.Cu")
		(net "M_G_CPU0_SB_DQ<22>")
	)
	(segment
		(start 402.461476 -298.913042)
		(end 402.686012 -298.68876)
		(width 0.10668)
		(layer "F.Cu")
		(net "M_G_CPU0_SB_DQ<22>")
	)
	(segment
		(start 402.74367 -299.195236)
		(end 402.74367 -299.360336)
		(width 0.10668)
		(layer "F.Cu")
		(net "M_G_CPU0_SB_DQ<22>")
	)
	(segment
		(start 395.835378 -287.667954)
		(end 397.312642 -287.667954)
		(width 0.10668)
		(layer "F.Cu")
		(net "M_G_CPU0_SB_DQ<22>")
	)
	(segment
		(start 402.968206 -298.970954)
		(end 402.74367 -299.195236)
		(width 0.10668)
		(layer "F.Cu")
		(net "M_G_CPU0_SB_DQ<22>")
	)
	(segment
		(start 403.979888 -299.817536)
		(end 411.129226 -306.966874)
		(width 0.10668)
		(layer "F.Cu")
		(net "M_G_CPU0_SB_DQ<22>")
	)
	(segment
		(start 400.378422 -290.733734)
		(end 400.378422 -296.21607)
		(width 0.10668)
		(layer "F.Cu")
		(net "M_G_CPU0_SB_DQ<22>")
	)
	(segment
		(start 401.557236 -297.559984)
		(end 401.722336 -297.559984)
		(width 0.10668)
		(layer "F.Cu")
		(net "M_G_CPU0_SB_DQ<22>")
	)
	(segment
		(start 403.590252 -300.041818)
		(end 403.814788 -299.817536)
		(width 0.10668)
		(layer "F.Cu")
		(net "M_G_CPU0_SB_DQ<22>")
	)
	(segment
		(start 400.378422 -296.21607)
		(end 400.710654 -296.548302)
		(width 0.10668)
		(layer "F.Cu")
		(net "M_G_CPU0_SB_DQ<22>")
	)
	(segment
		(start 402.968206 -298.805854)
		(end 402.968206 -298.970954)
		(width 0.10668)
		(layer "F.Cu")
		(net "M_G_CPU0_SB_DQ<22>")
	)
	(segment
		(start 401.897088 -298.348654)
		(end 402.121624 -298.124372)
		(width 0.10668)
		(layer "F.Cu")
		(net "M_G_CPU0_SB_DQ<22>")
	)
	(segment
		(start 402.179282 -298.630848)
		(end 402.179282 -298.795948)
		(width 0.10668)
		(layer "F.Cu")
		(net "M_G_CPU0_SB_DQ<22>")
	)
	(segment
		(start 403.532594 -299.370242)
		(end 403.532594 -299.535342)
		(width 0.10668)
		(layer "F.Cu")
		(net "M_G_CPU0_SB_DQ<22>")
	)
	(segment
		(start 402.179282 -298.795948)
		(end 402.296376 -298.913042)
		(width 0.10668)
		(layer "F.Cu")
		(net "M_G_CPU0_SB_DQ<22>")
	)
	(segment
		(start 395.608302 -287.667954)
		(end 395.835378 -287.667954)
		(width 0.0762)
		(layer "F.Cu")
		(net "M_G_CPU0_SB_DQ<22>")
	)
	(segment
		(start 411.129226 -306.966874)
		(end 411.173422 -306.985162)
		(width 0.10668)
		(layer "F.Cu")
		(net "M_G_CPU0_SB_DQ<22>")
	)
	(segment
		(start 401.1676 -297.784266)
		(end 401.3327 -297.784266)
		(width 0.10668)
		(layer "F.Cu")
		(net "M_G_CPU0_SB_DQ<22>")
	)
	(segment
		(start 403.4155 -299.253148)
		(end 403.532594 -299.370242)
		(width 0.10668)
		(layer "F.Cu")
		(net "M_G_CPU0_SB_DQ<22>")
	)
	(segment
		(start 400.486118 -297.102784)
		(end 400.603212 -297.219878)
		(width 0.10668)
		(layer "F.Cu")
		(net "M_G_CPU0_SB_DQ<22>")
	)
	(segment
		(start 400.710654 -296.548302)
		(end 400.710654 -296.713402)
		(width 0.10668)
		(layer "F.Cu")
		(net "M_G_CPU0_SB_DQ<22>")
	)
	(segment
		(start 400.992848 -296.995596)
		(end 401.157948 -296.995596)
		(width 0.10668)
		(layer "F.Cu")
		(net "M_G_CPU0_SB_DQ<22>")
	)
	(segment
		(start 401.3327 -297.784266)
		(end 401.557236 -297.559984)
		(width 0.10668)
		(layer "F.Cu")
		(net "M_G_CPU0_SB_DQ<22>")
	)
	(segment
		(start 400.486118 -296.937684)
		(end 400.486118 -297.102784)
		(width 0.10668)
		(layer "F.Cu")
		(net "M_G_CPU0_SB_DQ<22>")
	)
	(segment
		(start 401.83943 -297.842178)
		(end 401.614894 -298.06646)
		(width 0.10668)
		(layer "F.Cu")
		(net "M_G_CPU0_SB_DQ<22>")
	)
	(segment
		(start 400.603212 -297.219878)
		(end 400.768312 -297.219878)
		(width 0.10668)
		(layer "F.Cu")
		(net "M_G_CPU0_SB_DQ<22>")
	)
	(segment
		(start 401.157948 -296.995596)
		(end 401.275042 -297.11269)
		(width 0.10668)
		(layer "F.Cu")
		(net "M_G_CPU0_SB_DQ<22>")
	)
	(segment
		(start 402.686012 -298.68876)
		(end 402.851112 -298.68876)
		(width 0.10668)
		(layer "F.Cu")
		(net "M_G_CPU0_SB_DQ<22>")
	)
	(segment
		(start 394.327888 -287.217104)
		(end 395.157452 -287.217104)
		(width 0.0762)
		(layer "F.Cu")
		(net "M_G_CPU0_SB_DQ<22>")
	)
	(segment
		(start 400.768312 -297.219878)
		(end 400.992848 -296.995596)
		(width 0.10668)
		(layer "F.Cu")
		(net "M_G_CPU0_SB_DQ<22>")
	)
	(segment
		(start 403.532594 -299.535342)
		(end 403.308058 -299.759624)
		(width 0.10668)
		(layer "F.Cu")
		(net "M_G_CPU0_SB_DQ<22>")
	)
	(segment
		(start 402.121624 -298.124372)
		(end 402.286724 -298.124372)
		(width 0.10668)
		(layer "F.Cu")
		(net "M_G_CPU0_SB_DQ<22>")
	)
	(segment
		(start 402.403818 -298.241466)
		(end 402.403818 -298.406566)
		(width 0.10668)
		(layer "F.Cu")
		(net "M_G_CPU0_SB_DQ<22>")
	)
	(segment
		(start 402.74367 -299.360336)
		(end 402.860764 -299.47743)
		(width 0.10668)
		(layer "F.Cu")
		(net "M_G_CPU0_SB_DQ<22>")
	)
	(segment
		(start 402.286724 -298.124372)
		(end 402.403818 -298.241466)
		(width 0.10668)
		(layer "F.Cu")
		(net "M_G_CPU0_SB_DQ<22>")
	)
	(segment
		(start 401.614894 -298.06646)
		(end 401.614894 -298.23156)
		(width 0.10668)
		(layer "F.Cu")
		(net "M_G_CPU0_SB_DQ<22>")
	)
	(segment
		(start 400.710654 -296.713402)
		(end 400.486118 -296.937684)
		(width 0.10668)
		(layer "F.Cu")
		(net "M_G_CPU0_SB_DQ<22>")
	)
	(segment
		(start 401.275042 -297.27779)
		(end 401.050506 -297.502072)
		(width 0.10668)
		(layer "F.Cu")
		(net "M_G_CPU0_SB_DQ<22>")
	)
	(segment
		(start 402.296376 -298.913042)
		(end 402.461476 -298.913042)
		(width 0.10668)
		(layer "F.Cu")
		(net "M_G_CPU0_SB_DQ<22>")
	)
	(arc
		(start 393.387834 -287.59023)
		(mid 393.631265 -287.420743)
		(end 393.916916 -287.340802)
		(width 0.0762)
		(layer "F.Cu")
		(net "M_G_CPU0_SB_DQ<22>")
	)
	(arc
		(start 393.916916 -287.340802)
		(mid 393.936265 -287.338464)
		(end 393.955524 -287.335468)
		(width 0.0762)
		(layer "F.Cu")
		(net "M_G_CPU0_SB_DQ<22>")
	)
	(arc
		(start 393.955524 -287.335468)
		(mid 394.051233 -287.309756)
		(end 394.140944 -287.26765)
		(width 0.0762)
		(layer "F.Cu")
		(net "M_G_CPU0_SB_DQ<22>")
	)
	(arc
		(start 394.140944 -287.26765)
		(mid 394.216184 -287.234337)
		(end 394.2969 -287.218374)
		(width 0.0762)
		(layer "F.Cu")
		(net "M_G_CPU0_SB_DQ<22>")
	)
	(arc
		(start 394.2969 -287.218374)
		(mid 394.312381 -287.217418)
		(end 394.327888 -287.217104)
		(width 0.0762)
		(layer "F.Cu")
		(net "M_G_CPU0_SB_DQ<22>")
	)
	(segment
		(start 400.038062 -290.874958)
		(end 400.038062 -297.136312)
		(width 0.10668)
		(layer "F.Cu")
		(net "M_G_CPU0_SB_DQ<21>")
	)
	(segment
		(start 395.853666 -288.008314)
		(end 397.171418 -288.008314)
		(width 0.10668)
		(layer "F.Cu")
		(net "M_G_CPU0_SB_DQ<21>")
	)
	(segment
		(start 397.171418 -288.008314)
		(end 400.038062 -290.874958)
		(width 0.10668)
		(layer "F.Cu")
		(net "M_G_CPU0_SB_DQ<21>")
	)
	(segment
		(start 415.590736 -307.835046)
		(end 416.468052 -307.835046)
		(width 0.101346)
		(layer "F.Cu")
		(net "M_G_CPU0_SB_DQ<21>")
	)
	(segment
		(start 394.298424 -287.970976)
		(end 395.188694 -287.972246)
		(width 0.0762)
		(layer "F.Cu")
		(net "M_G_CPU0_SB_DQ<21>")
	)
	(segment
		(start 395.336776 -287.972246)
		(end 395.372844 -288.008314)
		(width 0.0762)
		(layer "F.Cu")
		(net "M_G_CPU0_SB_DQ<21>")
	)
	(segment
		(start 393.20089 -287.91281)
		(end 393.201144 -287.91281)
		(width 0.0762)
		(layer "F.Cu")
		(net "M_G_CPU0_SB_DQ<21>")
	)
	(segment
		(start 404.062692 -300.382178)
		(end 411.090618 -307.410104)
		(width 0.10668)
		(layer "F.Cu")
		(net "M_G_CPU0_SB_DQ<21>")
	)
	(segment
		(start 392.448034 -287.59023)
		(end 392.339576 -287.77692)
		(width 0.0762)
		(layer "F.Cu")
		(net "M_G_CPU0_SB_DQ<21>")
	)
	(segment
		(start 400.038062 -297.136312)
		(end 403.283928 -300.382178)
		(width 0.10668)
		(layer "F.Cu")
		(net "M_G_CPU0_SB_DQ<21>")
	)
	(segment
		(start 395.188694 -287.972246)
		(end 395.336776 -287.972246)
		(width 0.0762)
		(layer "F.Cu")
		(net "M_G_CPU0_SB_DQ<21>")
	)
	(segment
		(start 392.626596 -287.917636)
		(end 392.634978 -287.91281)
		(width 0.0762)
		(layer "F.Cu")
		(net "M_G_CPU0_SB_DQ<21>")
	)
	(segment
		(start 411.090618 -307.410104)
		(end 411.317694 -307.410104)
		(width 0.10668)
		(layer "F.Cu")
		(net "M_G_CPU0_SB_DQ<21>")
	)
	(segment
		(start 413.454342 -307.410104)
		(end 415.590736 -307.835046)
		(width 0.101346)
		(layer "F.Cu")
		(net "M_G_CPU0_SB_DQ<21>")
	)
	(segment
		(start 403.283928 -300.382178)
		(end 404.062692 -300.382178)
		(width 0.10668)
		(layer "F.Cu")
		(net "M_G_CPU0_SB_DQ<21>")
	)
	(segment
		(start 411.317694 -307.410104)
		(end 413.454342 -307.410104)
		(width 0.101346)
		(layer "F.Cu")
		(net "M_G_CPU0_SB_DQ<21>")
	)
	(segment
		(start 395.372844 -288.008314)
		(end 395.853666 -288.008314)
		(width 0.0762)
		(layer "F.Cu")
		(net "M_G_CPU0_SB_DQ<21>")
	)
	(arc
		(start 393.201144 -287.91281)
		(mid 393.388088 -287.963134)
		(end 393.575032 -287.91281)
		(width 0.0762)
		(layer "F.Cu")
		(net "M_G_CPU0_SB_DQ<21>")
	)
	(arc
		(start 392.491214 -287.960562)
		(mid 392.560968 -287.945605)
		(end 392.626596 -287.917636)
		(width 0.0762)
		(layer "F.Cu")
		(net "M_G_CPU0_SB_DQ<21>")
	)
	(arc
		(start 393.575032 -287.91281)
		(mid 393.857988 -287.836633)
		(end 394.140944 -287.91281)
		(width 0.0762)
		(layer "F.Cu")
		(net "M_G_CPU0_SB_DQ<21>")
	)
	(arc
		(start 394.223494 -287.954974)
		(mid 394.260122 -287.966904)
		(end 394.298424 -287.970976)
		(width 0.0762)
		(layer "F.Cu")
		(net "M_G_CPU0_SB_DQ<21>")
	)
	(arc
		(start 392.339576 -287.77692)
		(mid 392.365493 -287.909962)
		(end 392.491214 -287.960562)
		(width 0.0762)
		(layer "F.Cu")
		(net "M_G_CPU0_SB_DQ<21>")
	)
	(arc
		(start 394.140944 -287.91281)
		(mid 394.181638 -287.935029)
		(end 394.223494 -287.954974)
		(width 0.0762)
		(layer "F.Cu")
		(net "M_G_CPU0_SB_DQ<21>")
	)
	(arc
		(start 392.634978 -287.91281)
		(mid 392.917934 -287.836633)
		(end 393.20089 -287.91281)
		(width 0.0762)
		(layer "F.Cu")
		(net "M_G_CPU0_SB_DQ<21>")
	)
	(segment
		(start 415.355532 -306.135024)
		(end 416.468052 -306.135024)
		(width 0.101346)
		(layer "F.Cu")
		(net "M_G_CPU0_SB_DQ<20>")
	)
	(segment
		(start 414.7312 -306.135024)
		(end 414.846516 -306.25034)
		(width 0.101346)
		(layer "F.Cu")
		(net "M_G_CPU0_SB_DQ<20>")
	)
	(segment
		(start 414.961832 -306.846732)
		(end 415.1249 -306.846732)
		(width 0.101346)
		(layer "F.Cu")
		(net "M_G_CPU0_SB_DQ<20>")
	)
	(segment
		(start 394.327634 -287.026604)
		(end 395.236446 -287.026604)
		(width 0.0762)
		(layer "F.Cu")
		(net "M_G_CPU0_SB_DQ<20>")
	)
	(segment
		(start 396.690342 -287.108392)
		(end 396.690342 -287.210754)
		(width 0.10668)
		(layer "F.Cu")
		(net "M_G_CPU0_SB_DQ<20>")
	)
	(segment
		(start 394.03655 -287.10763)
		(end 394.044932 -287.102804)
		(width 0.0762)
		(layer "F.Cu")
		(net "M_G_CPU0_SB_DQ<20>")
	)
	(segment
		(start 396.291308 -287.210754)
		(end 396.291308 -287.108392)
		(width 0.10668)
		(layer "F.Cu")
		(net "M_G_CPU0_SB_DQ<20>")
	)
	(segment
		(start 395.537436 -287.327594)
		(end 395.831314 -287.327594)
		(width 0.0762)
		(layer "F.Cu")
		(net "M_G_CPU0_SB_DQ<20>")
	)
	(segment
		(start 400.718782 -296.074592)
		(end 410.354272 -305.710082)
		(width 0.10668)
		(layer "F.Cu")
		(net "M_G_CPU0_SB_DQ<20>")
	)
	(segment
		(start 396.408148 -286.991552)
		(end 396.573502 -286.991552)
		(width 0.10668)
		(layer "F.Cu")
		(net "M_G_CPU0_SB_DQ<20>")
	)
	(segment
		(start 414.846516 -306.25034)
		(end 414.846516 -306.731416)
		(width 0.101346)
		(layer "F.Cu")
		(net "M_G_CPU0_SB_DQ<20>")
	)
	(segment
		(start 410.354272 -305.710082)
		(end 411.317694 -305.710082)
		(width 0.10668)
		(layer "F.Cu")
		(net "M_G_CPU0_SB_DQ<20>")
	)
	(segment
		(start 414.846516 -306.731416)
		(end 414.961832 -306.846732)
		(width 0.101346)
		(layer "F.Cu")
		(net "M_G_CPU0_SB_DQ<20>")
	)
	(segment
		(start 415.240216 -306.25034)
		(end 415.355532 -306.135024)
		(width 0.101346)
		(layer "F.Cu")
		(net "M_G_CPU0_SB_DQ<20>")
	)
	(segment
		(start 396.573502 -286.991552)
		(end 396.690342 -287.108392)
		(width 0.10668)
		(layer "F.Cu")
		(net "M_G_CPU0_SB_DQ<20>")
	)
	(segment
		(start 415.240216 -306.731416)
		(end 415.240216 -306.25034)
		(width 0.101346)
		(layer "F.Cu")
		(net "M_G_CPU0_SB_DQ<20>")
	)
	(segment
		(start 411.317694 -305.710082)
		(end 413.929322 -305.710082)
		(width 0.101346)
		(layer "F.Cu")
		(net "M_G_CPU0_SB_DQ<20>")
	)
	(segment
		(start 415.1249 -306.846732)
		(end 415.240216 -306.731416)
		(width 0.101346)
		(layer "F.Cu")
		(net "M_G_CPU0_SB_DQ<20>")
	)
	(segment
		(start 396.690342 -287.210754)
		(end 396.807182 -287.327594)
		(width 0.10668)
		(layer "F.Cu")
		(net "M_G_CPU0_SB_DQ<20>")
	)
	(segment
		(start 413.929322 -305.710082)
		(end 414.354264 -306.135024)
		(width 0.101346)
		(layer "F.Cu")
		(net "M_G_CPU0_SB_DQ<20>")
	)
	(segment
		(start 395.831314 -287.327594)
		(end 396.174468 -287.327594)
		(width 0.10668)
		(layer "F.Cu")
		(net "M_G_CPU0_SB_DQ<20>")
	)
	(segment
		(start 414.354264 -306.135024)
		(end 414.7312 -306.135024)
		(width 0.101346)
		(layer "F.Cu")
		(net "M_G_CPU0_SB_DQ<20>")
	)
	(segment
		(start 395.236446 -287.026604)
		(end 395.537436 -287.327594)
		(width 0.0762)
		(layer "F.Cu")
		(net "M_G_CPU0_SB_DQ<20>")
	)
	(segment
		(start 397.453866 -287.327594)
		(end 400.718782 -290.59251)
		(width 0.10668)
		(layer "F.Cu")
		(net "M_G_CPU0_SB_DQ<20>")
	)
	(segment
		(start 396.174468 -287.327594)
		(end 396.291308 -287.210754)
		(width 0.10668)
		(layer "F.Cu")
		(net "M_G_CPU0_SB_DQ<20>")
	)
	(segment
		(start 396.291308 -287.108392)
		(end 396.408148 -286.991552)
		(width 0.10668)
		(layer "F.Cu")
		(net "M_G_CPU0_SB_DQ<20>")
	)
	(segment
		(start 396.807182 -287.327594)
		(end 397.453866 -287.327594)
		(width 0.10668)
		(layer "F.Cu")
		(net "M_G_CPU0_SB_DQ<20>")
	)
	(segment
		(start 393.857988 -286.780224)
		(end 393.755626 -286.9565)
		(width 0.0762)
		(layer "F.Cu")
		(net "M_G_CPU0_SB_DQ<20>")
	)
	(segment
		(start 400.718782 -290.59251)
		(end 400.718782 -296.074592)
		(width 0.10668)
		(layer "F.Cu")
		(net "M_G_CPU0_SB_DQ<20>")
	)
	(arc
		(start 394.044932 -287.102804)
		(mid 394.158656 -287.052503)
		(end 394.280644 -287.028382)
		(width 0.0762)
		(layer "F.Cu")
		(net "M_G_CPU0_SB_DQ<20>")
	)
	(arc
		(start 393.922504 -287.147508)
		(mid 393.98115 -287.132215)
		(end 394.03655 -287.10763)
		(width 0.0762)
		(layer "F.Cu")
		(net "M_G_CPU0_SB_DQ<20>")
	)
	(arc
		(start 393.755626 -286.9565)
		(mid 393.785255 -287.098987)
		(end 393.922504 -287.147508)
		(width 0.0762)
		(layer "F.Cu")
		(net "M_G_CPU0_SB_DQ<20>")
	)
	(arc
		(start 394.280644 -287.028382)
		(mid 394.304121 -287.027006)
		(end 394.327634 -287.026604)
		(width 0.0762)
		(layer "F.Cu")
		(net "M_G_CPU0_SB_DQ<20>")
	)
	(segment
		(start 407.640282 -278.468074)
		(end 410.324046 -281.151838)
		(width 0.10668)
		(layer "F.Cu")
		(net "M_G_CPU0_SB_DQ<1>")
	)
	(segment
		(start 395.624304 -274.90674)
		(end 400.007074 -274.90674)
		(width 0.10668)
		(layer "F.Cu")
		(net "M_G_CPU0_SB_DQ<1>")
	)
	(segment
		(start 414.084516 -283.185108)
		(end 416.468052 -283.185108)
		(width 0.101346)
		(layer "F.Cu")
		(net "M_G_CPU0_SB_DQ<1>")
	)
	(segment
		(start 400.123914 -274.657058)
		(end 400.240754 -274.540218)
		(width 0.10668)
		(layer "F.Cu")
		(net "M_G_CPU0_SB_DQ<1>")
	)
	(segment
		(start 392.448034 -274.630134)
		(end 392.339576 -274.816824)
		(width 0.0762)
		(layer "F.Cu")
		(net "M_G_CPU0_SB_DQ<1>")
	)
	(segment
		(start 413.659574 -282.760166)
		(end 414.084516 -283.185108)
		(width 0.101346)
		(layer "F.Cu")
		(net "M_G_CPU0_SB_DQ<1>")
	)
	(segment
		(start 410.995114 -282.760166)
		(end 411.317694 -282.760166)
		(width 0.10668)
		(layer "F.Cu")
		(net "M_G_CPU0_SB_DQ<1>")
	)
	(segment
		(start 411.317694 -282.760166)
		(end 413.659574 -282.760166)
		(width 0.101346)
		(layer "F.Cu")
		(net "M_G_CPU0_SB_DQ<1>")
	)
	(segment
		(start 393.20089 -274.952714)
		(end 393.201144 -274.952714)
		(width 0.0762)
		(layer "F.Cu")
		(net "M_G_CPU0_SB_DQ<1>")
	)
	(segment
		(start 410.324046 -281.151838)
		(end 410.324046 -282.089098)
		(width 0.10668)
		(layer "F.Cu")
		(net "M_G_CPU0_SB_DQ<1>")
	)
	(segment
		(start 406.703022 -278.468074)
		(end 407.640282 -278.468074)
		(width 0.10668)
		(layer "F.Cu")
		(net "M_G_CPU0_SB_DQ<1>")
	)
	(segment
		(start 403.141688 -274.90674)
		(end 406.703022 -278.468074)
		(width 0.10668)
		(layer "F.Cu")
		(net "M_G_CPU0_SB_DQ<1>")
	)
	(segment
		(start 395.572488 -274.90674)
		(end 395.624304 -274.90674)
		(width 0.0762)
		(layer "F.Cu")
		(net "M_G_CPU0_SB_DQ<1>")
	)
	(segment
		(start 400.123914 -274.7899)
		(end 400.123914 -274.657058)
		(width 0.10668)
		(layer "F.Cu")
		(net "M_G_CPU0_SB_DQ<1>")
	)
	(segment
		(start 392.626596 -274.95754)
		(end 392.634978 -274.952714)
		(width 0.0762)
		(layer "F.Cu")
		(net "M_G_CPU0_SB_DQ<1>")
	)
	(segment
		(start 394.298424 -275.01088)
		(end 395.466824 -275.012404)
		(width 0.0762)
		(layer "F.Cu")
		(net "M_G_CPU0_SB_DQ<1>")
	)
	(segment
		(start 410.324046 -282.089098)
		(end 410.995114 -282.760166)
		(width 0.10668)
		(layer "F.Cu")
		(net "M_G_CPU0_SB_DQ<1>")
	)
	(segment
		(start 400.007074 -274.90674)
		(end 400.123914 -274.7899)
		(width 0.10668)
		(layer "F.Cu")
		(net "M_G_CPU0_SB_DQ<1>")
	)
	(segment
		(start 400.406108 -274.540218)
		(end 400.522948 -274.657058)
		(width 0.10668)
		(layer "F.Cu")
		(net "M_G_CPU0_SB_DQ<1>")
	)
	(segment
		(start 400.522948 -274.7899)
		(end 400.639788 -274.90674)
		(width 0.10668)
		(layer "F.Cu")
		(net "M_G_CPU0_SB_DQ<1>")
	)
	(segment
		(start 400.240754 -274.540218)
		(end 400.406108 -274.540218)
		(width 0.10668)
		(layer "F.Cu")
		(net "M_G_CPU0_SB_DQ<1>")
	)
	(segment
		(start 395.466824 -275.012404)
		(end 395.572488 -274.90674)
		(width 0.0762)
		(layer "F.Cu")
		(net "M_G_CPU0_SB_DQ<1>")
	)
	(segment
		(start 400.639788 -274.90674)
		(end 403.141688 -274.90674)
		(width 0.10668)
		(layer "F.Cu")
		(net "M_G_CPU0_SB_DQ<1>")
	)
	(segment
		(start 400.522948 -274.657058)
		(end 400.522948 -274.7899)
		(width 0.10668)
		(layer "F.Cu")
		(net "M_G_CPU0_SB_DQ<1>")
	)
	(arc
		(start 392.634978 -274.952714)
		(mid 392.917934 -274.876537)
		(end 393.20089 -274.952714)
		(width 0.0762)
		(layer "F.Cu")
		(net "M_G_CPU0_SB_DQ<1>")
	)
	(arc
		(start 393.201144 -274.952714)
		(mid 393.388088 -275.003038)
		(end 393.575032 -274.952714)
		(width 0.0762)
		(layer "F.Cu")
		(net "M_G_CPU0_SB_DQ<1>")
	)
	(arc
		(start 392.339576 -274.816824)
		(mid 392.365493 -274.949866)
		(end 392.491214 -275.000466)
		(width 0.0762)
		(layer "F.Cu")
		(net "M_G_CPU0_SB_DQ<1>")
	)
	(arc
		(start 394.140944 -274.952714)
		(mid 394.181638 -274.974933)
		(end 394.223494 -274.994878)
		(width 0.0762)
		(layer "F.Cu")
		(net "M_G_CPU0_SB_DQ<1>")
	)
	(arc
		(start 392.491214 -275.000466)
		(mid 392.560968 -274.985509)
		(end 392.626596 -274.95754)
		(width 0.0762)
		(layer "F.Cu")
		(net "M_G_CPU0_SB_DQ<1>")
	)
	(arc
		(start 394.223494 -274.994878)
		(mid 394.260122 -275.006808)
		(end 394.298424 -275.01088)
		(width 0.0762)
		(layer "F.Cu")
		(net "M_G_CPU0_SB_DQ<1>")
	)
	(arc
		(start 393.575032 -274.952714)
		(mid 393.857988 -274.876537)
		(end 394.140944 -274.952714)
		(width 0.0762)
		(layer "F.Cu")
		(net "M_G_CPU0_SB_DQ<1>")
	)
	(segment
		(start 403.046438 -293.694612)
		(end 402.722842 -293.694612)
		(width 0.10668)
		(layer "F.Cu")
		(net "M_G_CPU0_SB_DQ<19>")
	)
	(segment
		(start 397.912844 -284.941518)
		(end 402.606002 -289.634676)
		(width 0.10668)
		(layer "F.Cu")
		(net "M_G_CPU0_SB_DQ<19>")
	)
	(segment
		(start 403.046438 -290.103306)
		(end 403.163278 -290.220146)
		(width 0.10668)
		(layer "F.Cu")
		(net "M_G_CPU0_SB_DQ<19>")
	)
	(segment
		(start 403.163278 -291.183568)
		(end 403.046438 -291.300408)
		(width 0.10668)
		(layer "F.Cu")
		(net "M_G_CPU0_SB_DQ<19>")
	)
	(segment
		(start 403.046438 -290.901374)
		(end 403.163278 -291.018214)
		(width 0.10668)
		(layer "F.Cu")
		(net "M_G_CPU0_SB_DQ<19>")
	)
	(segment
		(start 402.606002 -289.986466)
		(end 402.722842 -290.103306)
		(width 0.10668)
		(layer "F.Cu")
		(net "M_G_CPU0_SB_DQ<19>")
	)
	(segment
		(start 402.606002 -290.784534)
		(end 402.722842 -290.901374)
		(width 0.10668)
		(layer "F.Cu")
		(net "M_G_CPU0_SB_DQ<19>")
	)
	(segment
		(start 394.03655 -284.832806)
		(end 394.044932 -284.837632)
		(width 0.0762)
		(layer "F.Cu")
		(net "M_G_CPU0_SB_DQ<19>")
	)
	(segment
		(start 403.163278 -293.412418)
		(end 403.163278 -293.577772)
		(width 0.10668)
		(layer "F.Cu")
		(net "M_G_CPU0_SB_DQ<19>")
	)
	(segment
		(start 402.722842 -291.699442)
		(end 403.046438 -291.699442)
		(width 0.10668)
		(layer "F.Cu")
		(net "M_G_CPU0_SB_DQ<19>")
	)
	(segment
		(start 402.606002 -290.61918)
		(end 402.606002 -290.784534)
		(width 0.10668)
		(layer "F.Cu")
		(net "M_G_CPU0_SB_DQ<19>")
	)
	(segment
		(start 411.127702 -302.73498)
		(end 412.367984 -302.73498)
		(width 0.10668)
		(layer "F.Cu")
		(net "M_G_CPU0_SB_DQ<19>")
	)
	(segment
		(start 403.046438 -291.699442)
		(end 403.163278 -291.816282)
		(width 0.10668)
		(layer "F.Cu")
		(net "M_G_CPU0_SB_DQ<19>")
	)
	(segment
		(start 403.33676 -294.81272)
		(end 403.337014 -294.97782)
		(width 0.10668)
		(layer "F.Cu")
		(net "M_G_CPU0_SB_DQ<19>")
	)
	(segment
		(start 402.722842 -293.295578)
		(end 403.046438 -293.295578)
		(width 0.10668)
		(layer "F.Cu")
		(net "M_G_CPU0_SB_DQ<19>")
	)
	(segment
		(start 402.722842 -292.896544)
		(end 402.606002 -293.013384)
		(width 0.10668)
		(layer "F.Cu")
		(net "M_G_CPU0_SB_DQ<19>")
	)
	(segment
		(start 403.163278 -291.981636)
		(end 403.046438 -292.098476)
		(width 0.10668)
		(layer "F.Cu")
		(net "M_G_CPU0_SB_DQ<19>")
	)
	(segment
		(start 402.606002 -291.582602)
		(end 402.722842 -291.699442)
		(width 0.10668)
		(layer "F.Cu")
		(net "M_G_CPU0_SB_DQ<19>")
	)
	(segment
		(start 403.590506 -294.157654)
		(end 403.708108 -294.274748)
		(width 0.10668)
		(layer "F.Cu")
		(net "M_G_CPU0_SB_DQ<19>")
	)
	(segment
		(start 403.163278 -290.3855)
		(end 403.046438 -290.50234)
		(width 0.10668)
		(layer "F.Cu")
		(net "M_G_CPU0_SB_DQ<19>")
	)
	(segment
		(start 403.708362 -294.439594)
		(end 403.33676 -294.81272)
		(width 0.10668)
		(layer "F.Cu")
		(net "M_G_CPU0_SB_DQ<19>")
	)
	(segment
		(start 402.606002 -292.215316)
		(end 402.606002 -292.38067)
		(width 0.10668)
		(layer "F.Cu")
		(net "M_G_CPU0_SB_DQ<19>")
	)
	(segment
		(start 402.722842 -290.901374)
		(end 403.046438 -290.901374)
		(width 0.10668)
		(layer "F.Cu")
		(net "M_G_CPU0_SB_DQ<19>")
	)
	(segment
		(start 403.163278 -290.220146)
		(end 403.163278 -290.3855)
		(width 0.10668)
		(layer "F.Cu")
		(net "M_G_CPU0_SB_DQ<19>")
	)
	(segment
		(start 402.722842 -291.300408)
		(end 402.606002 -291.417248)
		(width 0.10668)
		(layer "F.Cu")
		(net "M_G_CPU0_SB_DQ<19>")
	)
	(segment
		(start 403.425406 -294.157908)
		(end 403.590506 -294.157654)
		(width 0.10668)
		(layer "F.Cu")
		(net "M_G_CPU0_SB_DQ<19>")
	)
	(segment
		(start 403.046438 -292.896544)
		(end 402.722842 -292.896544)
		(width 0.10668)
		(layer "F.Cu")
		(net "M_G_CPU0_SB_DQ<19>")
	)
	(segment
		(start 403.046438 -292.098476)
		(end 402.722842 -292.098476)
		(width 0.10668)
		(layer "F.Cu")
		(net "M_G_CPU0_SB_DQ<19>")
	)
	(segment
		(start 402.606002 -289.634676)
		(end 402.606002 -289.986466)
		(width 0.10668)
		(layer "F.Cu")
		(net "M_G_CPU0_SB_DQ<19>")
	)
	(segment
		(start 402.888958 -294.531542)
		(end 403.053804 -294.531288)
		(width 0.10668)
		(layer "F.Cu")
		(net "M_G_CPU0_SB_DQ<19>")
	)
	(segment
		(start 402.606002 -293.178738)
		(end 402.722842 -293.295578)
		(width 0.10668)
		(layer "F.Cu")
		(net "M_G_CPU0_SB_DQ<19>")
	)
	(segment
		(start 394.331698 -284.941518)
		(end 395.548358 -284.941518)
		(width 0.0762)
		(layer "F.Cu")
		(net "M_G_CPU0_SB_DQ<19>")
	)
	(segment
		(start 403.163278 -293.577772)
		(end 403.046438 -293.694612)
		(width 0.10668)
		(layer "F.Cu")
		(net "M_G_CPU0_SB_DQ<19>")
	)
	(segment
		(start 403.046438 -292.49751)
		(end 403.163278 -292.61435)
		(width 0.10668)
		(layer "F.Cu")
		(net "M_G_CPU0_SB_DQ<19>")
	)
	(segment
		(start 403.163278 -292.779704)
		(end 403.046438 -292.896544)
		(width 0.10668)
		(layer "F.Cu")
		(net "M_G_CPU0_SB_DQ<19>")
	)
	(segment
		(start 402.606002 -291.417248)
		(end 402.606002 -291.582602)
		(width 0.10668)
		(layer "F.Cu")
		(net "M_G_CPU0_SB_DQ<19>")
	)
	(segment
		(start 403.053804 -294.531288)
		(end 403.425406 -294.157908)
		(width 0.10668)
		(layer "F.Cu")
		(net "M_G_CPU0_SB_DQ<19>")
	)
	(segment
		(start 402.606002 -292.38067)
		(end 402.722842 -292.49751)
		(width 0.10668)
		(layer "F.Cu")
		(net "M_G_CPU0_SB_DQ<19>")
	)
	(segment
		(start 402.606002 -294.249856)
		(end 402.888958 -294.531542)
		(width 0.10668)
		(layer "F.Cu")
		(net "M_G_CPU0_SB_DQ<19>")
	)
	(segment
		(start 395.548358 -284.941518)
		(end 397.912844 -284.941518)
		(width 0.10668)
		(layer "F.Cu")
		(net "M_G_CPU0_SB_DQ<19>")
	)
	(segment
		(start 403.163278 -291.816282)
		(end 403.163278 -291.981636)
		(width 0.10668)
		(layer "F.Cu")
		(net "M_G_CPU0_SB_DQ<19>")
	)
	(segment
		(start 403.046438 -293.295578)
		(end 403.163278 -293.412418)
		(width 0.10668)
		(layer "F.Cu")
		(net "M_G_CPU0_SB_DQ<19>")
	)
	(segment
		(start 402.722842 -292.098476)
		(end 402.606002 -292.215316)
		(width 0.10668)
		(layer "F.Cu")
		(net "M_G_CPU0_SB_DQ<19>")
	)
	(segment
		(start 403.046438 -290.50234)
		(end 402.722842 -290.50234)
		(width 0.10668)
		(layer "F.Cu")
		(net "M_G_CPU0_SB_DQ<19>")
	)
	(segment
		(start 403.163278 -292.61435)
		(end 403.163278 -292.779704)
		(width 0.10668)
		(layer "F.Cu")
		(net "M_G_CPU0_SB_DQ<19>")
	)
	(segment
		(start 403.337014 -294.97782)
		(end 411.127702 -302.73498)
		(width 0.10668)
		(layer "F.Cu")
		(net "M_G_CPU0_SB_DQ<19>")
	)
	(segment
		(start 402.722842 -293.694612)
		(end 402.606002 -293.811452)
		(width 0.10668)
		(layer "F.Cu")
		(net "M_G_CPU0_SB_DQ<19>")
	)
	(segment
		(start 402.606002 -293.013384)
		(end 402.606002 -293.178738)
		(width 0.10668)
		(layer "F.Cu")
		(net "M_G_CPU0_SB_DQ<19>")
	)
	(segment
		(start 403.708108 -294.274748)
		(end 403.708362 -294.439594)
		(width 0.10668)
		(layer "F.Cu")
		(net "M_G_CPU0_SB_DQ<19>")
	)
	(segment
		(start 403.046438 -291.300408)
		(end 402.722842 -291.300408)
		(width 0.10668)
		(layer "F.Cu")
		(net "M_G_CPU0_SB_DQ<19>")
	)
	(segment
		(start 402.722842 -292.49751)
		(end 403.046438 -292.49751)
		(width 0.10668)
		(layer "F.Cu")
		(net "M_G_CPU0_SB_DQ<19>")
	)
	(segment
		(start 402.722842 -290.103306)
		(end 403.046438 -290.103306)
		(width 0.10668)
		(layer "F.Cu")
		(net "M_G_CPU0_SB_DQ<19>")
	)
	(segment
		(start 402.606002 -293.811452)
		(end 402.606002 -294.249856)
		(width 0.10668)
		(layer "F.Cu")
		(net "M_G_CPU0_SB_DQ<19>")
	)
	(segment
		(start 402.722842 -290.50234)
		(end 402.606002 -290.61918)
		(width 0.10668)
		(layer "F.Cu")
		(net "M_G_CPU0_SB_DQ<19>")
	)
	(segment
		(start 403.163278 -291.018214)
		(end 403.163278 -291.183568)
		(width 0.10668)
		(layer "F.Cu")
		(net "M_G_CPU0_SB_DQ<19>")
	)
	(arc
		(start 394.256006 -284.930342)
		(mid 394.293432 -284.938781)
		(end 394.331698 -284.941518)
		(width 0.0762)
		(layer "F.Cu")
		(net "M_G_CPU0_SB_DQ<19>")
	)
	(arc
		(start 393.104878 -284.837632)
		(mid 393.387834 -284.913809)
		(end 393.67079 -284.837632)
		(width 0.0762)
		(layer "F.Cu")
		(net "M_G_CPU0_SB_DQ<19>")
	)
	(arc
		(start 392.434064 -284.913832)
		(mid 392.587813 -284.896323)
		(end 392.73099 -284.837632)
		(width 0.0762)
		(layer "F.Cu")
		(net "M_G_CPU0_SB_DQ<19>")
	)
	(arc
		(start 392.73099 -284.837632)
		(mid 392.917934 -284.787377)
		(end 393.104878 -284.837632)
		(width 0.0762)
		(layer "F.Cu")
		(net "M_G_CPU0_SB_DQ<19>")
	)
	(arc
		(start 391.97788 -285.160212)
		(mid 392.173229 -284.976393)
		(end 392.434064 -284.913832)
		(width 0.0762)
		(layer "F.Cu")
		(net "M_G_CPU0_SB_DQ<19>")
	)
	(arc
		(start 394.044932 -284.837632)
		(mid 394.147826 -284.890004)
		(end 394.256006 -284.930342)
		(width 0.0762)
		(layer "F.Cu")
		(net "M_G_CPU0_SB_DQ<19>")
	)
	(arc
		(start 393.67079 -284.837632)
		(mid 393.853041 -284.787282)
		(end 394.03655 -284.832806)
		(width 0.0762)
		(layer "F.Cu")
		(net "M_G_CPU0_SB_DQ<19>")
	)
	(segment
		(start 406.40381 -296.117772)
		(end 406.56891 -296.117772)
		(width 0.10668)
		(layer "F.Cu")
		(net "M_G_CPU0_SB_DQ<18>")
	)
	(segment
		(start 405.174704 -295.653714)
		(end 405.174704 -295.818814)
		(width 0.10668)
		(layer "F.Cu")
		(net "M_G_CPU0_SB_DQ<18>")
	)
	(segment
		(start 406.867868 -297.511978)
		(end 406.984962 -297.629072)
		(width 0.10668)
		(layer "F.Cu")
		(net "M_G_CPU0_SB_DQ<18>")
	)
	(segment
		(start 405.275034 -294.988996)
		(end 405.440134 -294.988996)
		(width 0.10668)
		(layer "F.Cu")
		(net "M_G_CPU0_SB_DQ<18>")
	)
	(segment
		(start 406.686004 -296.399966)
		(end 406.30348 -296.78249)
		(width 0.10668)
		(layer "F.Cu")
		(net "M_G_CPU0_SB_DQ<18>")
	)
	(segment
		(start 407.697686 -297.246548)
		(end 407.81478 -297.363642)
		(width 0.10668)
		(layer "F.Cu")
		(net "M_G_CPU0_SB_DQ<18>")
	)
	(segment
		(start 406.420574 -297.064684)
		(end 406.585674 -297.064684)
		(width 0.10668)
		(layer "F.Cu")
		(net "M_G_CPU0_SB_DQ<18>")
	)
	(segment
		(start 406.984962 -297.629072)
		(end 407.150062 -297.629072)
		(width 0.10668)
		(layer "F.Cu")
		(net "M_G_CPU0_SB_DQ<18>")
	)
	(segment
		(start 395.637766 -284.230064)
		(end 398.164558 -284.230064)
		(width 0.10668)
		(layer "F.Cu")
		(net "M_G_CPU0_SB_DQ<18>")
	)
	(segment
		(start 406.867868 -297.346878)
		(end 406.867868 -297.511978)
		(width 0.10668)
		(layer "F.Cu")
		(net "M_G_CPU0_SB_DQ<18>")
	)
	(segment
		(start 407.81478 -297.528742)
		(end 407.432256 -297.911266)
		(width 0.10668)
		(layer "F.Cu")
		(net "M_G_CPU0_SB_DQ<18>")
	)
	(segment
		(start 404.895558 -295.368472)
		(end 405.275034 -294.988996)
		(width 0.10668)
		(layer "F.Cu")
		(net "M_G_CPU0_SB_DQ<18>")
	)
	(segment
		(start 406.021286 -296.500296)
		(end 406.40381 -296.117772)
		(width 0.10668)
		(layer "F.Cu")
		(net "M_G_CPU0_SB_DQ<18>")
	)
	(segment
		(start 407.81478 -297.363642)
		(end 407.81478 -297.528742)
		(width 0.10668)
		(layer "F.Cu")
		(net "M_G_CPU0_SB_DQ<18>")
	)
	(segment
		(start 406.121616 -295.670478)
		(end 406.121616 -295.835578)
		(width 0.10668)
		(layer "F.Cu")
		(net "M_G_CPU0_SB_DQ<18>")
	)
	(segment
		(start 406.121616 -295.835578)
		(end 405.739092 -296.218102)
		(width 0.10668)
		(layer "F.Cu")
		(net "M_G_CPU0_SB_DQ<18>")
	)
	(segment
		(start 405.739092 -296.383202)
		(end 405.856186 -296.500296)
		(width 0.10668)
		(layer "F.Cu")
		(net "M_G_CPU0_SB_DQ<18>")
	)
	(segment
		(start 407.54935 -298.19346)
		(end 407.71445 -298.19346)
		(width 0.10668)
		(layer "F.Cu")
		(net "M_G_CPU0_SB_DQ<18>")
	)
	(segment
		(start 406.968198 -296.68216)
		(end 407.133298 -296.68216)
		(width 0.10668)
		(layer "F.Cu")
		(net "M_G_CPU0_SB_DQ<18>")
	)
	(segment
		(start 407.250392 -296.964354)
		(end 406.867868 -297.346878)
		(width 0.10668)
		(layer "F.Cu")
		(net "M_G_CPU0_SB_DQ<18>")
	)
	(segment
		(start 407.150062 -297.629072)
		(end 407.532586 -297.246548)
		(width 0.10668)
		(layer "F.Cu")
		(net "M_G_CPU0_SB_DQ<18>")
	)
	(segment
		(start 407.532586 -297.246548)
		(end 407.697686 -297.246548)
		(width 0.10668)
		(layer "F.Cu")
		(net "M_G_CPU0_SB_DQ<18>")
	)
	(segment
		(start 405.291798 -295.935908)
		(end 405.456898 -295.935908)
		(width 0.10668)
		(layer "F.Cu")
		(net "M_G_CPU0_SB_DQ<18>")
	)
	(segment
		(start 405.440134 -294.988996)
		(end 405.557228 -295.10609)
		(width 0.10668)
		(layer "F.Cu")
		(net "M_G_CPU0_SB_DQ<18>")
	)
	(segment
		(start 407.71445 -298.19346)
		(end 407.938986 -297.968924)
		(width 0.10668)
		(layer "F.Cu")
		(net "M_G_CPU0_SB_DQ<18>")
	)
	(segment
		(start 405.456898 -295.935908)
		(end 405.839422 -295.553384)
		(width 0.10668)
		(layer "F.Cu")
		(net "M_G_CPU0_SB_DQ<18>")
	)
	(segment
		(start 404.613364 -295.251378)
		(end 404.730458 -295.368472)
		(width 0.10668)
		(layer "F.Cu")
		(net "M_G_CPU0_SB_DQ<18>")
	)
	(segment
		(start 407.432256 -297.911266)
		(end 407.432256 -298.076366)
		(width 0.10668)
		(layer "F.Cu")
		(net "M_G_CPU0_SB_DQ<18>")
	)
	(segment
		(start 404.613364 -295.086278)
		(end 404.613364 -295.251378)
		(width 0.10668)
		(layer "F.Cu")
		(net "M_G_CPU0_SB_DQ<18>")
	)
	(segment
		(start 405.856186 -296.500296)
		(end 406.021286 -296.500296)
		(width 0.10668)
		(layer "F.Cu")
		(net "M_G_CPU0_SB_DQ<18>")
	)
	(segment
		(start 408.104086 -297.968924)
		(end 408.22118 -298.086018)
		(width 0.10668)
		(layer "F.Cu")
		(net "M_G_CPU0_SB_DQ<18>")
	)
	(segment
		(start 405.557228 -295.27119)
		(end 405.174704 -295.653714)
		(width 0.10668)
		(layer "F.Cu")
		(net "M_G_CPU0_SB_DQ<18>")
	)
	(segment
		(start 395.209522 -283.97708)
		(end 395.462506 -284.230064)
		(width 0.0762)
		(layer "F.Cu")
		(net "M_G_CPU0_SB_DQ<18>")
	)
	(segment
		(start 406.004522 -295.553384)
		(end 406.121616 -295.670478)
		(width 0.10668)
		(layer "F.Cu")
		(net "M_G_CPU0_SB_DQ<18>")
	)
	(segment
		(start 404.730458 -295.368472)
		(end 404.895558 -295.368472)
		(width 0.10668)
		(layer "F.Cu")
		(net "M_G_CPU0_SB_DQ<18>")
	)
	(segment
		(start 407.432256 -298.076366)
		(end 407.54935 -298.19346)
		(width 0.10668)
		(layer "F.Cu")
		(net "M_G_CPU0_SB_DQ<18>")
	)
	(segment
		(start 395.462506 -284.230064)
		(end 395.637766 -284.230064)
		(width 0.0762)
		(layer "F.Cu")
		(net "M_G_CPU0_SB_DQ<18>")
	)
	(segment
		(start 405.557228 -295.10609)
		(end 405.557228 -295.27119)
		(width 0.10668)
		(layer "F.Cu")
		(net "M_G_CPU0_SB_DQ<18>")
	)
	(segment
		(start 403.870668 -289.936174)
		(end 403.870668 -293.41953)
		(width 0.10668)
		(layer "F.Cu")
		(net "M_G_CPU0_SB_DQ<18>")
	)
	(segment
		(start 403.870668 -293.41953)
		(end 404.99284 -294.541702)
		(width 0.10668)
		(layer "F.Cu")
		(net "M_G_CPU0_SB_DQ<18>")
	)
	(segment
		(start 407.996644 -298.475654)
		(end 407.996644 -298.640754)
		(width 0.10668)
		(layer "F.Cu")
		(net "M_G_CPU0_SB_DQ<18>")
	)
	(segment
		(start 405.174704 -295.818814)
		(end 405.291798 -295.935908)
		(width 0.10668)
		(layer "F.Cu")
		(net "M_G_CPU0_SB_DQ<18>")
	)
	(segment
		(start 405.839422 -295.553384)
		(end 406.004522 -295.553384)
		(width 0.10668)
		(layer "F.Cu")
		(net "M_G_CPU0_SB_DQ<18>")
	)
	(segment
		(start 406.56891 -296.117772)
		(end 406.686004 -296.234866)
		(width 0.10668)
		(layer "F.Cu")
		(net "M_G_CPU0_SB_DQ<18>")
	)
	(segment
		(start 408.22118 -298.251118)
		(end 407.996644 -298.475654)
		(width 0.10668)
		(layer "F.Cu")
		(net "M_G_CPU0_SB_DQ<18>")
	)
	(segment
		(start 407.996644 -298.640754)
		(end 410.390848 -301.034958)
		(width 0.10668)
		(layer "F.Cu")
		(net "M_G_CPU0_SB_DQ<18>")
	)
	(segment
		(start 406.686004 -296.234866)
		(end 406.686004 -296.399966)
		(width 0.10668)
		(layer "F.Cu")
		(net "M_G_CPU0_SB_DQ<18>")
	)
	(segment
		(start 406.30348 -296.78249)
		(end 406.30348 -296.94759)
		(width 0.10668)
		(layer "F.Cu")
		(net "M_G_CPU0_SB_DQ<18>")
	)
	(segment
		(start 398.164558 -284.230064)
		(end 403.870668 -289.936174)
		(width 0.10668)
		(layer "F.Cu")
		(net "M_G_CPU0_SB_DQ<18>")
	)
	(segment
		(start 404.99284 -294.706802)
		(end 404.613364 -295.086278)
		(width 0.10668)
		(layer "F.Cu")
		(net "M_G_CPU0_SB_DQ<18>")
	)
	(segment
		(start 404.99284 -294.541702)
		(end 404.99284 -294.706802)
		(width 0.10668)
		(layer "F.Cu")
		(net "M_G_CPU0_SB_DQ<18>")
	)
	(segment
		(start 410.390848 -301.034958)
		(end 412.367984 -301.034958)
		(width 0.10668)
		(layer "F.Cu")
		(net "M_G_CPU0_SB_DQ<18>")
	)
	(segment
		(start 406.585674 -297.064684)
		(end 406.968198 -296.68216)
		(width 0.10668)
		(layer "F.Cu")
		(net "M_G_CPU0_SB_DQ<18>")
	)
	(segment
		(start 405.739092 -296.218102)
		(end 405.739092 -296.383202)
		(width 0.10668)
		(layer "F.Cu")
		(net "M_G_CPU0_SB_DQ<18>")
	)
	(segment
		(start 407.133298 -296.68216)
		(end 407.250392 -296.799254)
		(width 0.10668)
		(layer "F.Cu")
		(net "M_G_CPU0_SB_DQ<18>")
	)
	(segment
		(start 394.327888 -283.97708)
		(end 395.209522 -283.97708)
		(width 0.0762)
		(layer "F.Cu")
		(net "M_G_CPU0_SB_DQ<18>")
	)
	(segment
		(start 407.938986 -297.968924)
		(end 408.104086 -297.968924)
		(width 0.10668)
		(layer "F.Cu")
		(net "M_G_CPU0_SB_DQ<18>")
	)
	(segment
		(start 406.30348 -296.94759)
		(end 406.420574 -297.064684)
		(width 0.10668)
		(layer "F.Cu")
		(net "M_G_CPU0_SB_DQ<18>")
	)
	(segment
		(start 408.22118 -298.086018)
		(end 408.22118 -298.251118)
		(width 0.10668)
		(layer "F.Cu")
		(net "M_G_CPU0_SB_DQ<18>")
	)
	(segment
		(start 407.250392 -296.799254)
		(end 407.250392 -296.964354)
		(width 0.10668)
		(layer "F.Cu")
		(net "M_G_CPU0_SB_DQ<18>")
	)
	(arc
		(start 393.955524 -284.095444)
		(mid 394.051233 -284.069732)
		(end 394.140944 -284.027626)
		(width 0.0762)
		(layer "F.Cu")
		(net "M_G_CPU0_SB_DQ<18>")
	)
	(arc
		(start 393.916916 -284.100778)
		(mid 393.936265 -284.09844)
		(end 393.955524 -284.095444)
		(width 0.0762)
		(layer "F.Cu")
		(net "M_G_CPU0_SB_DQ<18>")
	)
	(arc
		(start 393.387834 -284.350206)
		(mid 393.631265 -284.180719)
		(end 393.916916 -284.100778)
		(width 0.0762)
		(layer "F.Cu")
		(net "M_G_CPU0_SB_DQ<18>")
	)
	(arc
		(start 394.2969 -283.97835)
		(mid 394.312381 -283.977394)
		(end 394.327888 -283.97708)
		(width 0.0762)
		(layer "F.Cu")
		(net "M_G_CPU0_SB_DQ<18>")
	)
	(arc
		(start 394.140944 -284.027626)
		(mid 394.216184 -283.994313)
		(end 394.2969 -283.97835)
		(width 0.0762)
		(layer "F.Cu")
		(net "M_G_CPU0_SB_DQ<18>")
	)
	(segment
		(start 413.186118 -301.460154)
		(end 413.61106 -301.885096)
		(width 0.101346)
		(layer "F.Cu")
		(net "M_G_CPU0_SB_DQ<17>")
	)
	(segment
		(start 414.218374 -302.457612)
		(end 414.381442 -302.457612)
		(width 0.101346)
		(layer "F.Cu")
		(net "M_G_CPU0_SB_DQ<17>")
	)
	(segment
		(start 404.167848 -294.198294)
		(end 404.167848 -295.293542)
		(width 0.10668)
		(layer "F.Cu")
		(net "M_G_CPU0_SB_DQ<17>")
	)
	(segment
		(start 395.273276 -284.732222)
		(end 395.417802 -284.587696)
		(width 0.0762)
		(layer "F.Cu")
		(net "M_G_CPU0_SB_DQ<17>")
	)
	(segment
		(start 414.496758 -302.342296)
		(end 414.496758 -302.000412)
		(width 0.101346)
		(layer "F.Cu")
		(net "M_G_CPU0_SB_DQ<17>")
	)
	(segment
		(start 393.20089 -284.672786)
		(end 393.201144 -284.672786)
		(width 0.0762)
		(layer "F.Cu")
		(net "M_G_CPU0_SB_DQ<17>")
	)
	(segment
		(start 414.103058 -302.000412)
		(end 414.103058 -302.342296)
		(width 0.101346)
		(layer "F.Cu")
		(net "M_G_CPU0_SB_DQ<17>")
	)
	(segment
		(start 413.987742 -301.885096)
		(end 414.103058 -302.000412)
		(width 0.101346)
		(layer "F.Cu")
		(net "M_G_CPU0_SB_DQ<17>")
	)
	(segment
		(start 395.188694 -284.732222)
		(end 395.273276 -284.732222)
		(width 0.0762)
		(layer "F.Cu")
		(net "M_G_CPU0_SB_DQ<17>")
	)
	(segment
		(start 414.496758 -302.000412)
		(end 414.612074 -301.885096)
		(width 0.101346)
		(layer "F.Cu")
		(net "M_G_CPU0_SB_DQ<17>")
	)
	(segment
		(start 403.530308 -293.560754)
		(end 404.167848 -294.198294)
		(width 0.10668)
		(layer "F.Cu")
		(net "M_G_CPU0_SB_DQ<17>")
	)
	(segment
		(start 410.33446 -301.460154)
		(end 411.317694 -301.460154)
		(width 0.10668)
		(layer "F.Cu")
		(net "M_G_CPU0_SB_DQ<17>")
	)
	(segment
		(start 413.61106 -301.885096)
		(end 413.987742 -301.885096)
		(width 0.101346)
		(layer "F.Cu")
		(net "M_G_CPU0_SB_DQ<17>")
	)
	(segment
		(start 395.417802 -284.587696)
		(end 395.592808 -284.587696)
		(width 0.0762)
		(layer "F.Cu")
		(net "M_G_CPU0_SB_DQ<17>")
	)
	(segment
		(start 414.381442 -302.457612)
		(end 414.496758 -302.342296)
		(width 0.101346)
		(layer "F.Cu")
		(net "M_G_CPU0_SB_DQ<17>")
	)
	(segment
		(start 392.626596 -284.677612)
		(end 392.634978 -284.672786)
		(width 0.0762)
		(layer "F.Cu")
		(net "M_G_CPU0_SB_DQ<17>")
	)
	(segment
		(start 395.592808 -284.587696)
		(end 398.040606 -284.587696)
		(width 0.10668)
		(layer "F.Cu")
		(net "M_G_CPU0_SB_DQ<17>")
	)
	(segment
		(start 394.298424 -284.730952)
		(end 395.188694 -284.732222)
		(width 0.0762)
		(layer "F.Cu")
		(net "M_G_CPU0_SB_DQ<17>")
	)
	(segment
		(start 403.530308 -290.077398)
		(end 403.530308 -293.560754)
		(width 0.10668)
		(layer "F.Cu")
		(net "M_G_CPU0_SB_DQ<17>")
	)
	(segment
		(start 392.448034 -284.350206)
		(end 392.339576 -284.536896)
		(width 0.0762)
		(layer "F.Cu")
		(net "M_G_CPU0_SB_DQ<17>")
	)
	(segment
		(start 404.167848 -295.293542)
		(end 410.33446 -301.460154)
		(width 0.10668)
		(layer "F.Cu")
		(net "M_G_CPU0_SB_DQ<17>")
	)
	(segment
		(start 398.040606 -284.587696)
		(end 403.530308 -290.077398)
		(width 0.10668)
		(layer "F.Cu")
		(net "M_G_CPU0_SB_DQ<17>")
	)
	(segment
		(start 414.612074 -301.885096)
		(end 416.468052 -301.885096)
		(width 0.101346)
		(layer "F.Cu")
		(net "M_G_CPU0_SB_DQ<17>")
	)
	(segment
		(start 414.103058 -302.342296)
		(end 414.218374 -302.457612)
		(width 0.101346)
		(layer "F.Cu")
		(net "M_G_CPU0_SB_DQ<17>")
	)
	(segment
		(start 411.317694 -301.460154)
		(end 413.186118 -301.460154)
		(width 0.101346)
		(layer "F.Cu")
		(net "M_G_CPU0_SB_DQ<17>")
	)
	(arc
		(start 393.575032 -284.672786)
		(mid 393.857988 -284.596609)
		(end 394.140944 -284.672786)
		(width 0.0762)
		(layer "F.Cu")
		(net "M_G_CPU0_SB_DQ<17>")
	)
	(arc
		(start 392.491214 -284.720538)
		(mid 392.560968 -284.705581)
		(end 392.626596 -284.677612)
		(width 0.0762)
		(layer "F.Cu")
		(net "M_G_CPU0_SB_DQ<17>")
	)
	(arc
		(start 392.634978 -284.672786)
		(mid 392.917934 -284.596609)
		(end 393.20089 -284.672786)
		(width 0.0762)
		(layer "F.Cu")
		(net "M_G_CPU0_SB_DQ<17>")
	)
	(arc
		(start 394.223494 -284.71495)
		(mid 394.260122 -284.72688)
		(end 394.298424 -284.730952)
		(width 0.0762)
		(layer "F.Cu")
		(net "M_G_CPU0_SB_DQ<17>")
	)
	(arc
		(start 393.201144 -284.672786)
		(mid 393.388088 -284.72311)
		(end 393.575032 -284.672786)
		(width 0.0762)
		(layer "F.Cu")
		(net "M_G_CPU0_SB_DQ<17>")
	)
	(arc
		(start 394.140944 -284.672786)
		(mid 394.181638 -284.695005)
		(end 394.223494 -284.71495)
		(width 0.0762)
		(layer "F.Cu")
		(net "M_G_CPU0_SB_DQ<17>")
	)
	(arc
		(start 392.339576 -284.536896)
		(mid 392.365493 -284.669938)
		(end 392.491214 -284.720538)
		(width 0.0762)
		(layer "F.Cu")
		(net "M_G_CPU0_SB_DQ<17>")
	)
	(segment
		(start 410.44749 -300.610016)
		(end 411.317694 -300.610016)
		(width 0.10668)
		(layer "F.Cu")
		(net "M_G_CPU0_SB_DQ<16>")
	)
	(segment
		(start 404.211028 -293.24427)
		(end 408.56154 -297.594782)
		(width 0.10668)
		(layer "F.Cu")
		(net "M_G_CPU0_SB_DQ<16>")
	)
	(segment
		(start 415.324036 -300.913292)
		(end 415.439352 -300.797976)
		(width 0.101346)
		(layer "F.Cu")
		(net "M_G_CPU0_SB_DQ<16>")
	)
	(segment
		(start 415.554668 -300.185074)
		(end 416.468052 -300.185074)
		(width 0.101346)
		(layer "F.Cu")
		(net "M_G_CPU0_SB_DQ<16>")
	)
	(segment
		(start 408.56154 -297.594782)
		(end 408.56154 -298.724066)
		(width 0.10668)
		(layer "F.Cu")
		(net "M_G_CPU0_SB_DQ<16>")
	)
	(segment
		(start 395.503654 -283.887164)
		(end 395.760702 -283.887164)
		(width 0.0762)
		(layer "F.Cu")
		(net "M_G_CPU0_SB_DQ<16>")
	)
	(segment
		(start 415.160968 -300.913292)
		(end 415.324036 -300.913292)
		(width 0.101346)
		(layer "F.Cu")
		(net "M_G_CPU0_SB_DQ<16>")
	)
	(segment
		(start 415.439352 -300.797976)
		(end 415.439352 -300.30039)
		(width 0.101346)
		(layer "F.Cu")
		(net "M_G_CPU0_SB_DQ<16>")
	)
	(segment
		(start 414.258252 -300.30039)
		(end 414.258252 -300.797976)
		(width 0.101346)
		(layer "F.Cu")
		(net "M_G_CPU0_SB_DQ<16>")
	)
	(segment
		(start 414.930336 -300.185074)
		(end 415.045652 -300.30039)
		(width 0.101346)
		(layer "F.Cu")
		(net "M_G_CPU0_SB_DQ<16>")
	)
	(segment
		(start 398.303242 -283.887164)
		(end 404.211028 -289.79495)
		(width 0.10668)
		(layer "F.Cu")
		(net "M_G_CPU0_SB_DQ<16>")
	)
	(segment
		(start 395.40307 -283.78658)
		(end 395.503654 -283.887164)
		(width 0.0762)
		(layer "F.Cu")
		(net "M_G_CPU0_SB_DQ<16>")
	)
	(segment
		(start 394.03655 -283.867606)
		(end 394.044932 -283.86278)
		(width 0.0762)
		(layer "F.Cu")
		(net "M_G_CPU0_SB_DQ<16>")
	)
	(segment
		(start 408.56154 -298.724066)
		(end 410.44749 -300.610016)
		(width 0.10668)
		(layer "F.Cu")
		(net "M_G_CPU0_SB_DQ<16>")
	)
	(segment
		(start 414.767268 -300.185074)
		(end 414.930336 -300.185074)
		(width 0.101346)
		(layer "F.Cu")
		(net "M_G_CPU0_SB_DQ<16>")
	)
	(segment
		(start 404.211028 -289.79495)
		(end 404.211028 -293.24427)
		(width 0.10668)
		(layer "F.Cu")
		(net "M_G_CPU0_SB_DQ<16>")
	)
	(segment
		(start 414.651952 -300.30039)
		(end 414.767268 -300.185074)
		(width 0.101346)
		(layer "F.Cu")
		(net "M_G_CPU0_SB_DQ<16>")
	)
	(segment
		(start 414.142936 -300.185074)
		(end 414.258252 -300.30039)
		(width 0.101346)
		(layer "F.Cu")
		(net "M_G_CPU0_SB_DQ<16>")
	)
	(segment
		(start 413.91967 -300.185074)
		(end 414.142936 -300.185074)
		(width 0.101346)
		(layer "F.Cu")
		(net "M_G_CPU0_SB_DQ<16>")
	)
	(segment
		(start 394.327634 -283.78658)
		(end 395.40307 -283.78658)
		(width 0.0762)
		(layer "F.Cu")
		(net "M_G_CPU0_SB_DQ<16>")
	)
	(segment
		(start 415.439352 -300.30039)
		(end 415.554668 -300.185074)
		(width 0.101346)
		(layer "F.Cu")
		(net "M_G_CPU0_SB_DQ<16>")
	)
	(segment
		(start 414.258252 -300.797976)
		(end 414.373568 -300.913292)
		(width 0.101346)
		(layer "F.Cu")
		(net "M_G_CPU0_SB_DQ<16>")
	)
	(segment
		(start 414.536636 -300.913292)
		(end 414.651952 -300.797976)
		(width 0.101346)
		(layer "F.Cu")
		(net "M_G_CPU0_SB_DQ<16>")
	)
	(segment
		(start 414.373568 -300.913292)
		(end 414.536636 -300.913292)
		(width 0.101346)
		(layer "F.Cu")
		(net "M_G_CPU0_SB_DQ<16>")
	)
	(segment
		(start 411.317694 -300.610016)
		(end 413.494728 -300.610016)
		(width 0.101346)
		(layer "F.Cu")
		(net "M_G_CPU0_SB_DQ<16>")
	)
	(segment
		(start 414.651952 -300.797976)
		(end 414.651952 -300.30039)
		(width 0.101346)
		(layer "F.Cu")
		(net "M_G_CPU0_SB_DQ<16>")
	)
	(segment
		(start 415.045652 -300.30039)
		(end 415.045652 -300.797976)
		(width 0.101346)
		(layer "F.Cu")
		(net "M_G_CPU0_SB_DQ<16>")
	)
	(segment
		(start 415.045652 -300.797976)
		(end 415.160968 -300.913292)
		(width 0.101346)
		(layer "F.Cu")
		(net "M_G_CPU0_SB_DQ<16>")
	)
	(segment
		(start 413.494728 -300.610016)
		(end 413.91967 -300.185074)
		(width 0.101346)
		(layer "F.Cu")
		(net "M_G_CPU0_SB_DQ<16>")
	)
	(segment
		(start 393.857988 -283.5402)
		(end 393.755626 -283.716476)
		(width 0.0762)
		(layer "F.Cu")
		(net "M_G_CPU0_SB_DQ<16>")
	)
	(segment
		(start 395.760702 -283.887164)
		(end 398.303242 -283.887164)
		(width 0.10668)
		(layer "F.Cu")
		(net "M_G_CPU0_SB_DQ<16>")
	)
	(arc
		(start 393.922504 -283.907484)
		(mid 393.98115 -283.892191)
		(end 394.03655 -283.867606)
		(width 0.0762)
		(layer "F.Cu")
		(net "M_G_CPU0_SB_DQ<16>")
	)
	(arc
		(start 393.755626 -283.716476)
		(mid 393.785255 -283.858963)
		(end 393.922504 -283.907484)
		(width 0.0762)
		(layer "F.Cu")
		(net "M_G_CPU0_SB_DQ<16>")
	)
	(arc
		(start 394.044932 -283.86278)
		(mid 394.158656 -283.812479)
		(end 394.280644 -283.788358)
		(width 0.0762)
		(layer "F.Cu")
		(net "M_G_CPU0_SB_DQ<16>")
	)
	(arc
		(start 394.280644 -283.788358)
		(mid 394.304121 -283.786982)
		(end 394.327634 -283.78658)
		(width 0.0762)
		(layer "F.Cu")
		(net "M_G_CPU0_SB_DQ<16>")
	)
	(segment
		(start 409.01874 -298.369228)
		(end 409.01874 -298.534328)
		(width 0.10668)
		(layer "F.Cu")
		(net "M_G_CPU0_SB_DQ<15>")
	)
	(segment
		(start 395.928596 -283.429964)
		(end 398.492726 -283.429964)
		(width 0.10668)
		(layer "F.Cu")
		(net "M_G_CPU0_SB_DQ<15>")
	)
	(segment
		(start 410.948886 -299.33519)
		(end 412.367984 -299.33519)
		(width 0.10668)
		(layer "F.Cu")
		(net "M_G_CPU0_SB_DQ<15>")
	)
	(segment
		(start 404.668228 -293.054532)
		(end 410.305504 -298.691808)
		(width 0.10668)
		(layer "F.Cu")
		(net "M_G_CPU0_SB_DQ<15>")
	)
	(segment
		(start 410.752798 -299.139102)
		(end 410.948886 -299.33519)
		(width 0.10668)
		(layer "F.Cu")
		(net "M_G_CPU0_SB_DQ<15>")
	)
	(segment
		(start 410.188156 -298.974002)
		(end 410.023056 -298.974002)
		(width 0.10668)
		(layer "F.Cu")
		(net "M_G_CPU0_SB_DQ<15>")
	)
	(segment
		(start 395.322552 -283.321506)
		(end 395.43101 -283.429964)
		(width 0.0762)
		(layer "F.Cu")
		(net "M_G_CPU0_SB_DQ<15>")
	)
	(segment
		(start 410.587698 -299.139102)
		(end 410.752798 -299.139102)
		(width 0.10668)
		(layer "F.Cu")
		(net "M_G_CPU0_SB_DQ<15>")
	)
	(segment
		(start 409.136088 -298.252134)
		(end 409.01874 -298.369228)
		(width 0.10668)
		(layer "F.Cu")
		(net "M_G_CPU0_SB_DQ<15>")
	)
	(segment
		(start 395.43101 -283.429964)
		(end 395.928596 -283.429964)
		(width 0.0762)
		(layer "F.Cu")
		(net "M_G_CPU0_SB_DQ<15>")
	)
	(segment
		(start 394.331698 -283.321506)
		(end 395.322552 -283.321506)
		(width 0.0762)
		(layer "F.Cu")
		(net "M_G_CPU0_SB_DQ<15>")
	)
	(segment
		(start 410.022802 -299.53839)
		(end 410.187902 -299.53839)
		(width 0.10668)
		(layer "F.Cu")
		(net "M_G_CPU0_SB_DQ<15>")
	)
	(segment
		(start 409.301188 -298.252134)
		(end 409.136088 -298.252134)
		(width 0.10668)
		(layer "F.Cu")
		(net "M_G_CPU0_SB_DQ<15>")
	)
	(segment
		(start 410.187902 -299.53839)
		(end 410.587698 -299.139102)
		(width 0.10668)
		(layer "F.Cu")
		(net "M_G_CPU0_SB_DQ<15>")
	)
	(segment
		(start 394.03655 -283.212794)
		(end 394.044932 -283.21762)
		(width 0.0762)
		(layer "F.Cu")
		(net "M_G_CPU0_SB_DQ<15>")
	)
	(segment
		(start 409.01874 -298.534328)
		(end 410.022802 -299.53839)
		(width 0.10668)
		(layer "F.Cu")
		(net "M_G_CPU0_SB_DQ<15>")
	)
	(segment
		(start 410.305504 -298.691808)
		(end 410.305504 -298.856654)
		(width 0.10668)
		(layer "F.Cu")
		(net "M_G_CPU0_SB_DQ<15>")
	)
	(segment
		(start 398.492726 -283.429964)
		(end 404.668228 -289.605466)
		(width 0.10668)
		(layer "F.Cu")
		(net "M_G_CPU0_SB_DQ<15>")
	)
	(segment
		(start 410.023056 -298.974002)
		(end 409.301188 -298.252134)
		(width 0.10668)
		(layer "F.Cu")
		(net "M_G_CPU0_SB_DQ<15>")
	)
	(segment
		(start 410.305504 -298.856654)
		(end 410.188156 -298.974002)
		(width 0.10668)
		(layer "F.Cu")
		(net "M_G_CPU0_SB_DQ<15>")
	)
	(segment
		(start 404.668228 -289.605466)
		(end 404.668228 -293.054532)
		(width 0.10668)
		(layer "F.Cu")
		(net "M_G_CPU0_SB_DQ<15>")
	)
	(arc
		(start 394.044932 -283.21762)
		(mid 394.147826 -283.269992)
		(end 394.256006 -283.31033)
		(width 0.0762)
		(layer "F.Cu")
		(net "M_G_CPU0_SB_DQ<15>")
	)
	(arc
		(start 392.73099 -283.21762)
		(mid 392.917934 -283.167365)
		(end 393.104878 -283.21762)
		(width 0.0762)
		(layer "F.Cu")
		(net "M_G_CPU0_SB_DQ<15>")
	)
	(arc
		(start 392.434064 -283.29382)
		(mid 392.587813 -283.276311)
		(end 392.73099 -283.21762)
		(width 0.0762)
		(layer "F.Cu")
		(net "M_G_CPU0_SB_DQ<15>")
	)
	(arc
		(start 391.97788 -283.5402)
		(mid 392.173229 -283.356381)
		(end 392.434064 -283.29382)
		(width 0.0762)
		(layer "F.Cu")
		(net "M_G_CPU0_SB_DQ<15>")
	)
	(arc
		(start 393.104878 -283.21762)
		(mid 393.387834 -283.293797)
		(end 393.67079 -283.21762)
		(width 0.0762)
		(layer "F.Cu")
		(net "M_G_CPU0_SB_DQ<15>")
	)
	(arc
		(start 393.67079 -283.21762)
		(mid 393.853041 -283.16727)
		(end 394.03655 -283.212794)
		(width 0.0762)
		(layer "F.Cu")
		(net "M_G_CPU0_SB_DQ<15>")
	)
	(arc
		(start 394.256006 -283.31033)
		(mid 394.293432 -283.318769)
		(end 394.331698 -283.321506)
		(width 0.0762)
		(layer "F.Cu")
		(net "M_G_CPU0_SB_DQ<15>")
	)
	(segment
		(start 405.747982 -290.367212)
		(end 405.631142 -290.250372)
		(width 0.10668)
		(layer "F.Cu")
		(net "M_G_CPU0_SB_DQ<14>")
	)
	(segment
		(start 395.210284 -282.357068)
		(end 395.56944 -282.716224)
		(width 0.0762)
		(layer "F.Cu")
		(net "M_G_CPU0_SB_DQ<14>")
	)
	(segment
		(start 406.147016 -292.372542)
		(end 406.030176 -292.489382)
		(width 0.10668)
		(layer "F.Cu")
		(net "M_G_CPU0_SB_DQ<14>")
	)
	(segment
		(start 395.56944 -282.716224)
		(end 398.742408 -282.716224)
		(width 0.10668)
		(layer "F.Cu")
		(net "M_G_CPU0_SB_DQ<14>")
	)
	(segment
		(start 406.030176 -292.888416)
		(end 406.147016 -293.005256)
		(width 0.10668)
		(layer "F.Cu")
		(net "M_G_CPU0_SB_DQ<14>")
	)
	(segment
		(start 405.348948 -292.771576)
		(end 405.465788 -292.888416)
		(width 0.10668)
		(layer "F.Cu")
		(net "M_G_CPU0_SB_DQ<14>")
	)
	(segment
		(start 405.747982 -292.372542)
		(end 405.747982 -290.367212)
		(width 0.10668)
		(layer "F.Cu")
		(net "M_G_CPU0_SB_DQ<14>")
	)
	(segment
		(start 406.030176 -292.489382)
		(end 405.864822 -292.489382)
		(width 0.10668)
		(layer "F.Cu")
		(net "M_G_CPU0_SB_DQ<14>")
	)
	(segment
		(start 405.465788 -290.250372)
		(end 405.348948 -290.367212)
		(width 0.10668)
		(layer "F.Cu")
		(net "M_G_CPU0_SB_DQ<14>")
	)
	(segment
		(start 405.465788 -292.888416)
		(end 406.030176 -292.888416)
		(width 0.10668)
		(layer "F.Cu")
		(net "M_G_CPU0_SB_DQ<14>")
	)
	(segment
		(start 406.147016 -293.005256)
		(end 406.147016 -293.442898)
		(width 0.10668)
		(layer "F.Cu")
		(net "M_G_CPU0_SB_DQ<14>")
	)
	(segment
		(start 405.631142 -290.250372)
		(end 405.465788 -290.250372)
		(width 0.10668)
		(layer "F.Cu")
		(net "M_G_CPU0_SB_DQ<14>")
	)
	(segment
		(start 410.339286 -297.635168)
		(end 412.367984 -297.635168)
		(width 0.10668)
		(layer "F.Cu")
		(net "M_G_CPU0_SB_DQ<14>")
	)
	(segment
		(start 406.147016 -293.442898)
		(end 410.339286 -297.635168)
		(width 0.10668)
		(layer "F.Cu")
		(net "M_G_CPU0_SB_DQ<14>")
	)
	(segment
		(start 405.864822 -292.489382)
		(end 405.747982 -292.372542)
		(width 0.10668)
		(layer "F.Cu")
		(net "M_G_CPU0_SB_DQ<14>")
	)
	(segment
		(start 394.327888 -282.357068)
		(end 395.210284 -282.357068)
		(width 0.0762)
		(layer "F.Cu")
		(net "M_G_CPU0_SB_DQ<14>")
	)
	(segment
		(start 406.147016 -290.120832)
		(end 406.147016 -292.372542)
		(width 0.10668)
		(layer "F.Cu")
		(net "M_G_CPU0_SB_DQ<14>")
	)
	(segment
		(start 398.742408 -282.716224)
		(end 406.147016 -290.120832)
		(width 0.10668)
		(layer "F.Cu")
		(net "M_G_CPU0_SB_DQ<14>")
	)
	(segment
		(start 405.348948 -290.367212)
		(end 405.348948 -292.771576)
		(width 0.10668)
		(layer "F.Cu")
		(net "M_G_CPU0_SB_DQ<14>")
	)
	(arc
		(start 393.955524 -282.475432)
		(mid 394.051233 -282.44972)
		(end 394.140944 -282.407614)
		(width 0.0762)
		(layer "F.Cu")
		(net "M_G_CPU0_SB_DQ<14>")
	)
	(arc
		(start 393.387834 -282.730194)
		(mid 393.631265 -282.560707)
		(end 393.916916 -282.480766)
		(width 0.0762)
		(layer "F.Cu")
		(net "M_G_CPU0_SB_DQ<14>")
	)
	(arc
		(start 394.2969 -282.358338)
		(mid 394.312381 -282.357382)
		(end 394.327888 -282.357068)
		(width 0.0762)
		(layer "F.Cu")
		(net "M_G_CPU0_SB_DQ<14>")
	)
	(arc
		(start 393.916916 -282.480766)
		(mid 393.936265 -282.478428)
		(end 393.955524 -282.475432)
		(width 0.0762)
		(layer "F.Cu")
		(net "M_G_CPU0_SB_DQ<14>")
	)
	(arc
		(start 394.140944 -282.407614)
		(mid 394.216184 -282.374301)
		(end 394.2969 -282.358338)
		(width 0.0762)
		(layer "F.Cu")
		(net "M_G_CPU0_SB_DQ<14>")
	)
	(segment
		(start 395.086586 -283.111956)
		(end 395.108938 -283.089604)
		(width 0.0762)
		(layer "F.Cu")
		(net "M_G_CPU0_SB_DQ<13>")
	)
	(segment
		(start 392.448034 -282.730194)
		(end 392.339576 -282.916884)
		(width 0.0762)
		(layer "F.Cu")
		(net "M_G_CPU0_SB_DQ<13>")
	)
	(segment
		(start 398.634204 -283.089604)
		(end 405.008588 -289.463988)
		(width 0.10668)
		(layer "F.Cu")
		(net "M_G_CPU0_SB_DQ<13>")
	)
	(segment
		(start 410.155644 -298.06011)
		(end 411.317694 -298.06011)
		(width 0.10668)
		(layer "F.Cu")
		(net "M_G_CPU0_SB_DQ<13>")
	)
	(segment
		(start 405.008588 -292.913054)
		(end 410.155644 -298.06011)
		(width 0.10668)
		(layer "F.Cu")
		(net "M_G_CPU0_SB_DQ<13>")
	)
	(segment
		(start 405.008588 -289.463988)
		(end 405.008588 -292.913054)
		(width 0.10668)
		(layer "F.Cu")
		(net "M_G_CPU0_SB_DQ<13>")
	)
	(segment
		(start 415.572956 -298.485052)
		(end 416.468052 -298.485052)
		(width 0.101346)
		(layer "F.Cu")
		(net "M_G_CPU0_SB_DQ<13>")
	)
	(segment
		(start 394.298424 -283.11094)
		(end 395.086586 -283.111956)
		(width 0.0762)
		(layer "F.Cu")
		(net "M_G_CPU0_SB_DQ<13>")
	)
	(segment
		(start 415.148014 -298.06011)
		(end 415.572956 -298.485052)
		(width 0.101346)
		(layer "F.Cu")
		(net "M_G_CPU0_SB_DQ<13>")
	)
	(segment
		(start 411.317694 -298.06011)
		(end 415.148014 -298.06011)
		(width 0.101346)
		(layer "F.Cu")
		(net "M_G_CPU0_SB_DQ<13>")
	)
	(segment
		(start 393.20089 -283.052774)
		(end 393.201144 -283.052774)
		(width 0.0762)
		(layer "F.Cu")
		(net "M_G_CPU0_SB_DQ<13>")
	)
	(segment
		(start 395.937232 -283.089604)
		(end 398.634204 -283.089604)
		(width 0.10668)
		(layer "F.Cu")
		(net "M_G_CPU0_SB_DQ<13>")
	)
	(segment
		(start 392.626596 -283.0576)
		(end 392.634978 -283.052774)
		(width 0.0762)
		(layer "F.Cu")
		(net "M_G_CPU0_SB_DQ<13>")
	)
	(segment
		(start 395.108938 -283.089604)
		(end 395.937232 -283.089604)
		(width 0.0762)
		(layer "F.Cu")
		(net "M_G_CPU0_SB_DQ<13>")
	)
	(arc
		(start 394.140944 -283.052774)
		(mid 394.181638 -283.074993)
		(end 394.223494 -283.094938)
		(width 0.0762)
		(layer "F.Cu")
		(net "M_G_CPU0_SB_DQ<13>")
	)
	(arc
		(start 392.491214 -283.100526)
		(mid 392.560968 -283.085569)
		(end 392.626596 -283.0576)
		(width 0.0762)
		(layer "F.Cu")
		(net "M_G_CPU0_SB_DQ<13>")
	)
	(arc
		(start 393.201144 -283.052774)
		(mid 393.388088 -283.103098)
		(end 393.575032 -283.052774)
		(width 0.0762)
		(layer "F.Cu")
		(net "M_G_CPU0_SB_DQ<13>")
	)
	(arc
		(start 392.634978 -283.052774)
		(mid 392.917934 -282.976597)
		(end 393.20089 -283.052774)
		(width 0.0762)
		(layer "F.Cu")
		(net "M_G_CPU0_SB_DQ<13>")
	)
	(arc
		(start 393.575032 -283.052774)
		(mid 393.857988 -282.976597)
		(end 394.140944 -283.052774)
		(width 0.0762)
		(layer "F.Cu")
		(net "M_G_CPU0_SB_DQ<13>")
	)
	(arc
		(start 392.339576 -282.916884)
		(mid 392.365493 -283.049926)
		(end 392.491214 -283.100526)
		(width 0.0762)
		(layer "F.Cu")
		(net "M_G_CPU0_SB_DQ<13>")
	)
	(arc
		(start 394.223494 -283.094938)
		(mid 394.260122 -283.106868)
		(end 394.298424 -283.11094)
		(width 0.0762)
		(layer "F.Cu")
		(net "M_G_CPU0_SB_DQ<13>")
	)
	(segment
		(start 414.354264 -296.78503)
		(end 414.613598 -296.78503)
		(width 0.101346)
		(layer "F.Cu")
		(net "M_G_CPU0_SB_DQ<12>")
	)
	(segment
		(start 415.23793 -296.78503)
		(end 416.468052 -296.78503)
		(width 0.101346)
		(layer "F.Cu")
		(net "M_G_CPU0_SB_DQ<12>")
	)
	(segment
		(start 414.728914 -296.900346)
		(end 414.728914 -297.513756)
		(width 0.101346)
		(layer "F.Cu")
		(net "M_G_CPU0_SB_DQ<12>")
	)
	(segment
		(start 406.487376 -293.30142)
		(end 409.546044 -296.360088)
		(width 0.10668)
		(layer "F.Cu")
		(net "M_G_CPU0_SB_DQ<12>")
	)
	(segment
		(start 395.498828 -282.375864)
		(end 395.811502 -282.375864)
		(width 0.0762)
		(layer "F.Cu")
		(net "M_G_CPU0_SB_DQ<12>")
	)
	(segment
		(start 414.613598 -296.78503)
		(end 414.728914 -296.900346)
		(width 0.101346)
		(layer "F.Cu")
		(net "M_G_CPU0_SB_DQ<12>")
	)
	(segment
		(start 415.122614 -296.900346)
		(end 415.23793 -296.78503)
		(width 0.101346)
		(layer "F.Cu")
		(net "M_G_CPU0_SB_DQ<12>")
	)
	(segment
		(start 395.811502 -282.375864)
		(end 398.883632 -282.375864)
		(width 0.10668)
		(layer "F.Cu")
		(net "M_G_CPU0_SB_DQ<12>")
	)
	(segment
		(start 394.03655 -282.247594)
		(end 394.044932 -282.242768)
		(width 0.0762)
		(layer "F.Cu")
		(net "M_G_CPU0_SB_DQ<12>")
	)
	(segment
		(start 406.487376 -289.979608)
		(end 406.487376 -293.30142)
		(width 0.10668)
		(layer "F.Cu")
		(net "M_G_CPU0_SB_DQ<12>")
	)
	(segment
		(start 413.929322 -296.360088)
		(end 414.354264 -296.78503)
		(width 0.101346)
		(layer "F.Cu")
		(net "M_G_CPU0_SB_DQ<12>")
	)
	(segment
		(start 395.289532 -282.166568)
		(end 395.498828 -282.375864)
		(width 0.0762)
		(layer "F.Cu")
		(net "M_G_CPU0_SB_DQ<12>")
	)
	(segment
		(start 415.122614 -297.513756)
		(end 415.122614 -296.900346)
		(width 0.101346)
		(layer "F.Cu")
		(net "M_G_CPU0_SB_DQ<12>")
	)
	(segment
		(start 411.317694 -296.360088)
		(end 413.929322 -296.360088)
		(width 0.101346)
		(layer "F.Cu")
		(net "M_G_CPU0_SB_DQ<12>")
	)
	(segment
		(start 398.883632 -282.375864)
		(end 406.487376 -289.979608)
		(width 0.10668)
		(layer "F.Cu")
		(net "M_G_CPU0_SB_DQ<12>")
	)
	(segment
		(start 394.327634 -282.166568)
		(end 395.289532 -282.166568)
		(width 0.0762)
		(layer "F.Cu")
		(net "M_G_CPU0_SB_DQ<12>")
	)
	(segment
		(start 415.007298 -297.629072)
		(end 415.122614 -297.513756)
		(width 0.101346)
		(layer "F.Cu")
		(net "M_G_CPU0_SB_DQ<12>")
	)
	(segment
		(start 414.728914 -297.513756)
		(end 414.84423 -297.629072)
		(width 0.101346)
		(layer "F.Cu")
		(net "M_G_CPU0_SB_DQ<12>")
	)
	(segment
		(start 414.84423 -297.629072)
		(end 415.007298 -297.629072)
		(width 0.101346)
		(layer "F.Cu")
		(net "M_G_CPU0_SB_DQ<12>")
	)
	(segment
		(start 409.546044 -296.360088)
		(end 411.317694 -296.360088)
		(width 0.10668)
		(layer "F.Cu")
		(net "M_G_CPU0_SB_DQ<12>")
	)
	(segment
		(start 393.857988 -281.920188)
		(end 393.755626 -282.096464)
		(width 0.0762)
		(layer "F.Cu")
		(net "M_G_CPU0_SB_DQ<12>")
	)
	(arc
		(start 393.755626 -282.096464)
		(mid 393.785255 -282.238951)
		(end 393.922504 -282.287472)
		(width 0.0762)
		(layer "F.Cu")
		(net "M_G_CPU0_SB_DQ<12>")
	)
	(arc
		(start 394.044932 -282.242768)
		(mid 394.158656 -282.192467)
		(end 394.280644 -282.168346)
		(width 0.0762)
		(layer "F.Cu")
		(net "M_G_CPU0_SB_DQ<12>")
	)
	(arc
		(start 393.922504 -282.287472)
		(mid 393.98115 -282.272179)
		(end 394.03655 -282.247594)
		(width 0.0762)
		(layer "F.Cu")
		(net "M_G_CPU0_SB_DQ<12>")
	)
	(arc
		(start 394.280644 -282.168346)
		(mid 394.304121 -282.16697)
		(end 394.327634 -282.166568)
		(width 0.0762)
		(layer "F.Cu")
		(net "M_G_CPU0_SB_DQ<12>")
	)
	(segment
		(start 408.474672 -289.27552)
		(end 408.639772 -289.27552)
		(width 0.10668)
		(layer "F.Cu")
		(net "M_G_CPU0_SB_DQ<11>")
	)
	(segment
		(start 395.790674 -279.786588)
		(end 398.98574 -279.786588)
		(width 0.10668)
		(layer "F.Cu")
		(net "M_G_CPU0_SB_DQ<11>")
	)
	(segment
		(start 409.486354 -290.287202)
		(end 409.603448 -290.404296)
		(width 0.10668)
		(layer "F.Cu")
		(net "M_G_CPU0_SB_DQ<11>")
	)
	(segment
		(start 405.652732 -286.45358)
		(end 405.817832 -286.45358)
		(width 0.10668)
		(layer "F.Cu")
		(net "M_G_CPU0_SB_DQ<11>")
	)
	(segment
		(start 406.21712 -287.017968)
		(end 406.38222 -287.017968)
		(width 0.10668)
		(layer "F.Cu")
		(net "M_G_CPU0_SB_DQ<11>")
	)
	(segment
		(start 407.228802 -287.86455)
		(end 407.228802 -288.02965)
		(width 0.10668)
		(layer "F.Cu")
		(net "M_G_CPU0_SB_DQ<11>")
	)
	(segment
		(start 408.156664 -288.629852)
		(end 408.321764 -288.629852)
		(width 0.10668)
		(layer "F.Cu")
		(net "M_G_CPU0_SB_DQ<11>")
	)
	(segment
		(start 406.946608 -287.582356)
		(end 407.027888 -287.501076)
		(width 0.10668)
		(layer "F.Cu")
		(net "M_G_CPU0_SB_DQ<11>")
	)
	(segment
		(start 410.135832 -292.513258)
		(end 410.135832 -292.678358)
		(width 0.10668)
		(layer "F.Cu")
		(net "M_G_CPU0_SB_DQ<11>")
	)
	(segment
		(start 410.822394 -292.800532)
		(end 410.418026 -292.396164)
		(width 0.10668)
		(layer "F.Cu")
		(net "M_G_CPU0_SB_DQ<11>")
	)
	(segment
		(start 410.132022 -290.60521)
		(end 410.050742 -290.68649)
		(width 0.10668)
		(layer "F.Cu")
		(net "M_G_CPU0_SB_DQ<11>")
	)
	(segment
		(start 409.003246 -289.476434)
		(end 408.921966 -289.557714)
		(width 0.10668)
		(layer "F.Cu")
		(net "M_G_CPU0_SB_DQ<11>")
	)
	(segment
		(start 410.135832 -292.678358)
		(end 410.822394 -293.36492)
		(width 0.10668)
		(layer "F.Cu")
		(net "M_G_CPU0_SB_DQ<11>")
	)
	(segment
		(start 409.003246 -289.311334)
		(end 409.003246 -289.476434)
		(width 0.10668)
		(layer "F.Cu")
		(net "M_G_CPU0_SB_DQ<11>")
	)
	(segment
		(start 408.886152 -289.19424)
		(end 409.003246 -289.311334)
		(width 0.10668)
		(layer "F.Cu")
		(net "M_G_CPU0_SB_DQ<11>")
	)
	(segment
		(start 410.220668 -291.634418)
		(end 411.104588 -292.518338)
		(width 0.10668)
		(layer "F.Cu")
		(net "M_G_CPU0_SB_DQ<11>")
	)
	(segment
		(start 407.592276 -288.065464)
		(end 407.757376 -288.065464)
		(width 0.10668)
		(layer "F.Cu")
		(net "M_G_CPU0_SB_DQ<11>")
	)
	(segment
		(start 411.104588 -292.518338)
		(end 411.104588 -292.683438)
		(width 0.10668)
		(layer "F.Cu")
		(net "M_G_CPU0_SB_DQ<11>")
	)
	(segment
		(start 410.132022 -290.44011)
		(end 410.132022 -290.60521)
		(width 0.10668)
		(layer "F.Cu")
		(net "M_G_CPU0_SB_DQ<11>")
	)
	(segment
		(start 411.551882 -292.965632)
		(end 411.971236 -293.384986)
		(width 0.10668)
		(layer "F.Cu")
		(net "M_G_CPU0_SB_DQ<11>")
	)
	(segment
		(start 409.45054 -289.758628)
		(end 409.567634 -289.875722)
		(width 0.10668)
		(layer "F.Cu")
		(net "M_G_CPU0_SB_DQ<11>")
	)
	(segment
		(start 405.899112 -286.3723)
		(end 406.064212 -286.3723)
		(width 0.10668)
		(layer "F.Cu")
		(net "M_G_CPU0_SB_DQ<11>")
	)
	(segment
		(start 407.345896 -288.146744)
		(end 407.510996 -288.146744)
		(width 0.10668)
		(layer "F.Cu")
		(net "M_G_CPU0_SB_DQ<11>")
	)
	(segment
		(start 406.38222 -287.017968)
		(end 406.4635 -286.936688)
		(width 0.10668)
		(layer "F.Cu")
		(net "M_G_CPU0_SB_DQ<11>")
	)
	(segment
		(start 394.331698 -280.081482)
		(end 395.188694 -280.081482)
		(width 0.0762)
		(layer "F.Cu")
		(net "M_G_CPU0_SB_DQ<11>")
	)
	(segment
		(start 406.745694 -287.053782)
		(end 406.745694 -287.218882)
		(width 0.10668)
		(layer "F.Cu")
		(net "M_G_CPU0_SB_DQ<11>")
	)
	(segment
		(start 407.757376 -288.065464)
		(end 407.87447 -288.182558)
		(width 0.10668)
		(layer "F.Cu")
		(net "M_G_CPU0_SB_DQ<11>")
	)
	(segment
		(start 411.971236 -293.384986)
		(end 412.367984 -293.384986)
		(width 0.10668)
		(layer "F.Cu")
		(net "M_G_CPU0_SB_DQ<11>")
	)
	(segment
		(start 406.664414 -287.300162)
		(end 406.664414 -287.465262)
		(width 0.10668)
		(layer "F.Cu")
		(net "M_G_CPU0_SB_DQ<11>")
	)
	(segment
		(start 395.188694 -280.081482)
		(end 395.483588 -279.786588)
		(width 0.0762)
		(layer "F.Cu")
		(net "M_G_CPU0_SB_DQ<11>")
	)
	(segment
		(start 406.6286 -286.936688)
		(end 406.745694 -287.053782)
		(width 0.10668)
		(layer "F.Cu")
		(net "M_G_CPU0_SB_DQ<11>")
	)
	(segment
		(start 408.075384 -288.711132)
		(end 408.156664 -288.629852)
		(width 0.10668)
		(layer "F.Cu")
		(net "M_G_CPU0_SB_DQ<11>")
	)
	(segment
		(start 407.510996 -288.146744)
		(end 407.592276 -288.065464)
		(width 0.10668)
		(layer "F.Cu")
		(net "M_G_CPU0_SB_DQ<11>")
	)
	(segment
		(start 410.987494 -293.36492)
		(end 411.386782 -292.965632)
		(width 0.10668)
		(layer "F.Cu")
		(net "M_G_CPU0_SB_DQ<11>")
	)
	(segment
		(start 408.639772 -289.27552)
		(end 408.721052 -289.19424)
		(width 0.10668)
		(layer "F.Cu")
		(net "M_G_CPU0_SB_DQ<11>")
	)
	(segment
		(start 408.321764 -288.629852)
		(end 408.438858 -288.746946)
		(width 0.10668)
		(layer "F.Cu")
		(net "M_G_CPU0_SB_DQ<11>")
	)
	(segment
		(start 410.050742 -290.68649)
		(end 410.050742 -290.85159)
		(width 0.10668)
		(layer "F.Cu")
		(net "M_G_CPU0_SB_DQ<11>")
	)
	(segment
		(start 410.822394 -293.36492)
		(end 410.987494 -293.36492)
		(width 0.10668)
		(layer "F.Cu")
		(net "M_G_CPU0_SB_DQ<11>")
	)
	(segment
		(start 411.104588 -292.683438)
		(end 410.987494 -292.800532)
		(width 0.10668)
		(layer "F.Cu")
		(net "M_G_CPU0_SB_DQ<11>")
	)
	(segment
		(start 407.310082 -287.61817)
		(end 407.310082 -287.78327)
		(width 0.10668)
		(layer "F.Cu")
		(net "M_G_CPU0_SB_DQ<11>")
	)
	(segment
		(start 409.03906 -289.839908)
		(end 409.20416 -289.839908)
		(width 0.10668)
		(layer "F.Cu")
		(net "M_G_CPU0_SB_DQ<11>")
	)
	(segment
		(start 409.603448 -290.404296)
		(end 409.768548 -290.404296)
		(width 0.10668)
		(layer "F.Cu")
		(net "M_G_CPU0_SB_DQ<11>")
	)
	(segment
		(start 409.567634 -290.040822)
		(end 409.486354 -290.122102)
		(width 0.10668)
		(layer "F.Cu")
		(net "M_G_CPU0_SB_DQ<11>")
	)
	(segment
		(start 409.20416 -289.839908)
		(end 409.28544 -289.758628)
		(width 0.10668)
		(layer "F.Cu")
		(net "M_G_CPU0_SB_DQ<11>")
	)
	(segment
		(start 394.03655 -279.97277)
		(end 394.044932 -279.977596)
		(width 0.0762)
		(layer "F.Cu")
		(net "M_G_CPU0_SB_DQ<11>")
	)
	(segment
		(start 408.921966 -289.722814)
		(end 409.03906 -289.839908)
		(width 0.10668)
		(layer "F.Cu")
		(net "M_G_CPU0_SB_DQ<11>")
	)
	(segment
		(start 407.79319 -288.428938)
		(end 407.79319 -288.594038)
		(width 0.10668)
		(layer "F.Cu")
		(net "M_G_CPU0_SB_DQ<11>")
	)
	(segment
		(start 410.252926 -292.396164)
		(end 410.135832 -292.513258)
		(width 0.10668)
		(layer "F.Cu")
		(net "M_G_CPU0_SB_DQ<11>")
	)
	(segment
		(start 407.79319 -288.594038)
		(end 407.910284 -288.711132)
		(width 0.10668)
		(layer "F.Cu")
		(net "M_G_CPU0_SB_DQ<11>")
	)
	(segment
		(start 407.228802 -288.02965)
		(end 407.345896 -288.146744)
		(width 0.10668)
		(layer "F.Cu")
		(net "M_G_CPU0_SB_DQ<11>")
	)
	(segment
		(start 407.192988 -287.501076)
		(end 407.310082 -287.61817)
		(width 0.10668)
		(layer "F.Cu")
		(net "M_G_CPU0_SB_DQ<11>")
	)
	(segment
		(start 406.781508 -287.582356)
		(end 406.946608 -287.582356)
		(width 0.10668)
		(layer "F.Cu")
		(net "M_G_CPU0_SB_DQ<11>")
	)
	(segment
		(start 408.921966 -289.557714)
		(end 408.921966 -289.722814)
		(width 0.10668)
		(layer "F.Cu")
		(net "M_G_CPU0_SB_DQ<11>")
	)
	(segment
		(start 409.28544 -289.758628)
		(end 409.45054 -289.758628)
		(width 0.10668)
		(layer "F.Cu")
		(net "M_G_CPU0_SB_DQ<11>")
	)
	(segment
		(start 405.817832 -286.45358)
		(end 405.899112 -286.3723)
		(width 0.10668)
		(layer "F.Cu")
		(net "M_G_CPU0_SB_DQ<11>")
	)
	(segment
		(start 407.87447 -288.347658)
		(end 407.79319 -288.428938)
		(width 0.10668)
		(layer "F.Cu")
		(net "M_G_CPU0_SB_DQ<11>")
	)
	(segment
		(start 407.910284 -288.711132)
		(end 408.075384 -288.711132)
		(width 0.10668)
		(layer "F.Cu")
		(net "M_G_CPU0_SB_DQ<11>")
	)
	(segment
		(start 409.567634 -289.875722)
		(end 409.567634 -290.040822)
		(width 0.10668)
		(layer "F.Cu")
		(net "M_G_CPU0_SB_DQ<11>")
	)
	(segment
		(start 409.486354 -290.122102)
		(end 409.486354 -290.287202)
		(width 0.10668)
		(layer "F.Cu")
		(net "M_G_CPU0_SB_DQ<11>")
	)
	(segment
		(start 406.181306 -286.654494)
		(end 406.100026 -286.735774)
		(width 0.10668)
		(layer "F.Cu")
		(net "M_G_CPU0_SB_DQ<11>")
	)
	(segment
		(start 408.357578 -289.158426)
		(end 408.474672 -289.27552)
		(width 0.10668)
		(layer "F.Cu")
		(net "M_G_CPU0_SB_DQ<11>")
	)
	(segment
		(start 407.87447 -288.182558)
		(end 407.87447 -288.347658)
		(width 0.10668)
		(layer "F.Cu")
		(net "M_G_CPU0_SB_DQ<11>")
	)
	(segment
		(start 406.745694 -287.218882)
		(end 406.664414 -287.300162)
		(width 0.10668)
		(layer "F.Cu")
		(net "M_G_CPU0_SB_DQ<11>")
	)
	(segment
		(start 410.220668 -291.021516)
		(end 410.220668 -291.634418)
		(width 0.10668)
		(layer "F.Cu")
		(net "M_G_CPU0_SB_DQ<11>")
	)
	(segment
		(start 410.014928 -290.323016)
		(end 410.132022 -290.44011)
		(width 0.10668)
		(layer "F.Cu")
		(net "M_G_CPU0_SB_DQ<11>")
	)
	(segment
		(start 409.849828 -290.323016)
		(end 410.014928 -290.323016)
		(width 0.10668)
		(layer "F.Cu")
		(net "M_G_CPU0_SB_DQ<11>")
	)
	(segment
		(start 406.100026 -286.900874)
		(end 406.21712 -287.017968)
		(width 0.10668)
		(layer "F.Cu")
		(net "M_G_CPU0_SB_DQ<11>")
	)
	(segment
		(start 407.310082 -287.78327)
		(end 407.228802 -287.86455)
		(width 0.10668)
		(layer "F.Cu")
		(net "M_G_CPU0_SB_DQ<11>")
	)
	(segment
		(start 409.768548 -290.404296)
		(end 409.849828 -290.323016)
		(width 0.10668)
		(layer "F.Cu")
		(net "M_G_CPU0_SB_DQ<11>")
	)
	(segment
		(start 408.438858 -288.746946)
		(end 408.438858 -288.912046)
		(width 0.10668)
		(layer "F.Cu")
		(net "M_G_CPU0_SB_DQ<11>")
	)
	(segment
		(start 410.050742 -290.85159)
		(end 410.220668 -291.021516)
		(width 0.10668)
		(layer "F.Cu")
		(net "M_G_CPU0_SB_DQ<11>")
	)
	(segment
		(start 406.064212 -286.3723)
		(end 406.181306 -286.489394)
		(width 0.10668)
		(layer "F.Cu")
		(net "M_G_CPU0_SB_DQ<11>")
	)
	(segment
		(start 408.721052 -289.19424)
		(end 408.886152 -289.19424)
		(width 0.10668)
		(layer "F.Cu")
		(net "M_G_CPU0_SB_DQ<11>")
	)
	(segment
		(start 398.98574 -279.786588)
		(end 405.652732 -286.45358)
		(width 0.10668)
		(layer "F.Cu")
		(net "M_G_CPU0_SB_DQ<11>")
	)
	(segment
		(start 407.027888 -287.501076)
		(end 407.192988 -287.501076)
		(width 0.10668)
		(layer "F.Cu")
		(net "M_G_CPU0_SB_DQ<11>")
	)
	(segment
		(start 411.386782 -292.965632)
		(end 411.551882 -292.965632)
		(width 0.10668)
		(layer "F.Cu")
		(net "M_G_CPU0_SB_DQ<11>")
	)
	(segment
		(start 410.987494 -292.800532)
		(end 410.822394 -292.800532)
		(width 0.10668)
		(layer "F.Cu")
		(net "M_G_CPU0_SB_DQ<11>")
	)
	(segment
		(start 395.483588 -279.786588)
		(end 395.790674 -279.786588)
		(width 0.0762)
		(layer "F.Cu")
		(net "M_G_CPU0_SB_DQ<11>")
	)
	(segment
		(start 408.357578 -288.993326)
		(end 408.357578 -289.158426)
		(width 0.10668)
		(layer "F.Cu")
		(net "M_G_CPU0_SB_DQ<11>")
	)
	(segment
		(start 406.664414 -287.465262)
		(end 406.781508 -287.582356)
		(width 0.10668)
		(layer "F.Cu")
		(net "M_G_CPU0_SB_DQ<11>")
	)
	(segment
		(start 406.4635 -286.936688)
		(end 406.6286 -286.936688)
		(width 0.10668)
		(layer "F.Cu")
		(net "M_G_CPU0_SB_DQ<11>")
	)
	(segment
		(start 406.100026 -286.735774)
		(end 406.100026 -286.900874)
		(width 0.10668)
		(layer "F.Cu")
		(net "M_G_CPU0_SB_DQ<11>")
	)
	(segment
		(start 406.181306 -286.489394)
		(end 406.181306 -286.654494)
		(width 0.10668)
		(layer "F.Cu")
		(net "M_G_CPU0_SB_DQ<11>")
	)
	(segment
		(start 408.438858 -288.912046)
		(end 408.357578 -288.993326)
		(width 0.10668)
		(layer "F.Cu")
		(net "M_G_CPU0_SB_DQ<11>")
	)
	(segment
		(start 410.418026 -292.396164)
		(end 410.252926 -292.396164)
		(width 0.10668)
		(layer "F.Cu")
		(net "M_G_CPU0_SB_DQ<11>")
	)
	(arc
		(start 394.044932 -279.977596)
		(mid 394.147826 -280.029968)
		(end 394.256006 -280.070306)
		(width 0.0762)
		(layer "F.Cu")
		(net "M_G_CPU0_SB_DQ<11>")
	)
	(arc
		(start 394.256006 -280.070306)
		(mid 394.293432 -280.078745)
		(end 394.331698 -280.081482)
		(width 0.0762)
		(layer "F.Cu")
		(net "M_G_CPU0_SB_DQ<11>")
	)
	(arc
		(start 391.97788 -280.300176)
		(mid 392.173229 -280.116357)
		(end 392.434064 -280.053796)
		(width 0.0762)
		(layer "F.Cu")
		(net "M_G_CPU0_SB_DQ<11>")
	)
	(arc
		(start 393.67079 -279.977596)
		(mid 393.853041 -279.927246)
		(end 394.03655 -279.97277)
		(width 0.0762)
		(layer "F.Cu")
		(net "M_G_CPU0_SB_DQ<11>")
	)
	(arc
		(start 393.104878 -279.977596)
		(mid 393.387834 -280.053773)
		(end 393.67079 -279.977596)
		(width 0.0762)
		(layer "F.Cu")
		(net "M_G_CPU0_SB_DQ<11>")
	)
	(arc
		(start 392.73099 -279.977596)
		(mid 392.917934 -279.927341)
		(end 393.104878 -279.977596)
		(width 0.0762)
		(layer "F.Cu")
		(net "M_G_CPU0_SB_DQ<11>")
	)
	(arc
		(start 392.434064 -280.053796)
		(mid 392.587813 -280.036287)
		(end 392.73099 -279.977596)
		(width 0.0762)
		(layer "F.Cu")
		(net "M_G_CPU0_SB_DQ<11>")
	)
	(segment
		(start 404.640034 -284.210252)
		(end 404.688548 -284.161738)
		(width 0.10668)
		(layer "F.Cu")
		(net "M_G_CPU0_SB_DQ<10>")
	)
	(segment
		(start 402.342604 -281.149806)
		(end 402.459698 -281.2669)
		(width 0.10668)
		(layer "F.Cu")
		(net "M_G_CPU0_SB_DQ<10>")
	)
	(segment
		(start 400.134328 -279.806654)
		(end 400.48434 -279.456642)
		(width 0.10668)
		(layer "F.Cu")
		(net "M_G_CPU0_SB_DQ<10>")
	)
	(segment
		(start 401.89531 -280.702512)
		(end 401.89531 -280.867612)
		(width 0.10668)
		(layer "F.Cu")
		(net "M_G_CPU0_SB_DQ<10>")
	)
	(segment
		(start 403.024086 -281.831288)
		(end 403.024086 -281.996388)
		(width 0.10668)
		(layer "F.Cu")
		(net "M_G_CPU0_SB_DQ<10>")
	)
	(segment
		(start 404.406354 -283.879544)
		(end 404.35784 -283.928058)
		(width 0.10668)
		(layer "F.Cu")
		(net "M_G_CPU0_SB_DQ<10>")
	)
	(segment
		(start 404.970742 -284.293056)
		(end 404.970742 -284.443932)
		(width 0.10668)
		(layer "F.Cu")
		(net "M_G_CPU0_SB_DQ<10>")
	)
	(segment
		(start 400.533616 -280.371042)
		(end 400.698716 -280.371042)
		(width 0.10668)
		(layer "F.Cu")
		(net "M_G_CPU0_SB_DQ<10>")
	)
	(segment
		(start 405.76881 -285.339028)
		(end 405.817324 -285.290514)
		(width 0.10668)
		(layer "F.Cu")
		(net "M_G_CPU0_SB_DQ<10>")
	)
	(segment
		(start 404.35784 -283.928058)
		(end 404.35784 -284.078934)
		(width 0.10668)
		(layer "F.Cu")
		(net "M_G_CPU0_SB_DQ<10>")
	)
	(segment
		(start 403.92477 -283.645864)
		(end 404.075646 -283.645864)
		(width 0.10668)
		(layer "F.Cu")
		(net "M_G_CPU0_SB_DQ<10>")
	)
	(segment
		(start 402.22678 -282.064206)
		(end 402.39188 -282.064206)
		(width 0.10668)
		(layer "F.Cu")
		(net "M_G_CPU0_SB_DQ<10>")
	)
	(segment
		(start 403.841966 -283.16428)
		(end 403.841966 -283.315156)
		(width 0.10668)
		(layer "F.Cu")
		(net "M_G_CPU0_SB_DQ<10>")
	)
	(segment
		(start 401.545298 -281.382724)
		(end 401.662392 -281.499818)
		(width 0.10668)
		(layer "F.Cu")
		(net "M_G_CPU0_SB_DQ<10>")
	)
	(segment
		(start 401.778216 -280.585418)
		(end 401.89531 -280.702512)
		(width 0.10668)
		(layer "F.Cu")
		(net "M_G_CPU0_SB_DQ<10>")
	)
	(segment
		(start 402.674074 -282.5115)
		(end 402.791168 -282.628594)
		(width 0.10668)
		(layer "F.Cu")
		(net "M_G_CPU0_SB_DQ<10>")
	)
	(segment
		(start 400.416522 -280.088848)
		(end 400.416522 -280.253948)
		(width 0.10668)
		(layer "F.Cu")
		(net "M_G_CPU0_SB_DQ<10>")
	)
	(segment
		(start 395.888718 -279.105868)
		(end 399.783554 -279.105868)
		(width 0.10668)
		(layer "F.Cu")
		(net "M_G_CPU0_SB_DQ<10>")
	)
	(segment
		(start 399.852134 -279.68956)
		(end 399.969228 -279.806654)
		(width 0.10668)
		(layer "F.Cu")
		(net "M_G_CPU0_SB_DQ<10>")
	)
	(segment
		(start 401.263104 -280.93543)
		(end 401.613116 -280.585418)
		(width 0.10668)
		(layer "F.Cu")
		(net "M_G_CPU0_SB_DQ<10>")
	)
	(segment
		(start 402.109686 -281.782012)
		(end 402.109686 -281.947112)
		(width 0.10668)
		(layer "F.Cu")
		(net "M_G_CPU0_SB_DQ<10>")
	)
	(segment
		(start 403.048724 -282.536138)
		(end 403.213824 -282.536138)
		(width 0.10668)
		(layer "F.Cu")
		(net "M_G_CPU0_SB_DQ<10>")
	)
	(segment
		(start 403.213824 -282.536138)
		(end 403.841966 -283.16428)
		(width 0.10668)
		(layer "F.Cu")
		(net "M_G_CPU0_SB_DQ<10>")
	)
	(segment
		(start 400.48434 -279.456642)
		(end 400.64944 -279.456642)
		(width 0.10668)
		(layer "F.Cu")
		(net "M_G_CPU0_SB_DQ<10>")
	)
	(segment
		(start 410.901388 -291.093398)
		(end 411.492954 -291.684964)
		(width 0.10668)
		(layer "F.Cu")
		(net "M_G_CPU0_SB_DQ<10>")
	)
	(segment
		(start 399.94459 -279.266904)
		(end 399.94459 -279.432004)
		(width 0.10668)
		(layer "F.Cu")
		(net "M_G_CPU0_SB_DQ<10>")
	)
	(segment
		(start 403.793452 -283.514546)
		(end 403.92477 -283.645864)
		(width 0.10668)
		(layer "F.Cu")
		(net "M_G_CPU0_SB_DQ<10>")
	)
	(segment
		(start 401.330922 -280.138124)
		(end 401.330922 -280.303224)
		(width 0.10668)
		(layer "F.Cu")
		(net "M_G_CPU0_SB_DQ<10>")
	)
	(segment
		(start 405.817324 -285.290514)
		(end 405.9682 -285.290514)
		(width 0.10668)
		(layer "F.Cu")
		(net "M_G_CPU0_SB_DQ<10>")
	)
	(segment
		(start 405.53513 -284.857444)
		(end 405.53513 -285.00832)
		(width 0.10668)
		(layer "F.Cu")
		(net "M_G_CPU0_SB_DQ<10>")
	)
	(segment
		(start 404.12416 -283.59735)
		(end 404.275036 -283.59735)
		(width 0.10668)
		(layer "F.Cu")
		(net "M_G_CPU0_SB_DQ<10>")
	)
	(segment
		(start 400.698716 -280.371042)
		(end 401.048728 -280.02103)
		(width 0.10668)
		(layer "F.Cu")
		(net "M_G_CPU0_SB_DQ<10>")
	)
	(segment
		(start 404.489158 -284.210252)
		(end 404.640034 -284.210252)
		(width 0.10668)
		(layer "F.Cu")
		(net "M_G_CPU0_SB_DQ<10>")
	)
	(segment
		(start 394.327888 -279.117044)
		(end 395.187932 -279.117044)
		(width 0.0762)
		(layer "F.Cu")
		(net "M_G_CPU0_SB_DQ<10>")
	)
	(segment
		(start 403.841966 -283.315156)
		(end 403.793452 -283.36367)
		(width 0.10668)
		(layer "F.Cu")
		(net "M_G_CPU0_SB_DQ<10>")
	)
	(segment
		(start 402.39188 -282.064206)
		(end 402.741892 -281.714194)
		(width 0.10668)
		(layer "F.Cu")
		(net "M_G_CPU0_SB_DQ<10>")
	)
	(segment
		(start 399.783554 -279.105868)
		(end 399.94459 -279.266904)
		(width 0.10668)
		(layer "F.Cu")
		(net "M_G_CPU0_SB_DQ<10>")
	)
	(segment
		(start 401.048728 -280.02103)
		(end 401.213828 -280.02103)
		(width 0.10668)
		(layer "F.Cu")
		(net "M_G_CPU0_SB_DQ<10>")
	)
	(segment
		(start 404.35784 -284.078934)
		(end 404.489158 -284.210252)
		(width 0.10668)
		(layer "F.Cu")
		(net "M_G_CPU0_SB_DQ<10>")
	)
	(segment
		(start 401.827492 -281.499818)
		(end 402.177504 -281.149806)
		(width 0.10668)
		(layer "F.Cu")
		(net "M_G_CPU0_SB_DQ<10>")
	)
	(segment
		(start 400.98091 -280.818336)
		(end 401.098004 -280.93543)
		(width 0.10668)
		(layer "F.Cu")
		(net "M_G_CPU0_SB_DQ<10>")
	)
	(segment
		(start 402.674074 -282.3464)
		(end 402.674074 -282.5115)
		(width 0.10668)
		(layer "F.Cu")
		(net "M_G_CPU0_SB_DQ<10>")
	)
	(segment
		(start 400.98091 -280.653236)
		(end 400.98091 -280.818336)
		(width 0.10668)
		(layer "F.Cu")
		(net "M_G_CPU0_SB_DQ<10>")
	)
	(segment
		(start 404.688548 -284.161738)
		(end 404.839424 -284.161738)
		(width 0.10668)
		(layer "F.Cu")
		(net "M_G_CPU0_SB_DQ<10>")
	)
	(segment
		(start 402.906992 -281.714194)
		(end 403.024086 -281.831288)
		(width 0.10668)
		(layer "F.Cu")
		(net "M_G_CPU0_SB_DQ<10>")
	)
	(segment
		(start 399.852134 -279.52446)
		(end 399.852134 -279.68956)
		(width 0.10668)
		(layer "F.Cu")
		(net "M_G_CPU0_SB_DQ<10>")
	)
	(segment
		(start 405.9682 -285.290514)
		(end 410.901388 -290.223702)
		(width 0.10668)
		(layer "F.Cu")
		(net "M_G_CPU0_SB_DQ<10>")
	)
	(segment
		(start 402.177504 -281.149806)
		(end 402.342604 -281.149806)
		(width 0.10668)
		(layer "F.Cu")
		(net "M_G_CPU0_SB_DQ<10>")
	)
	(segment
		(start 401.89531 -280.867612)
		(end 401.545298 -281.217624)
		(width 0.10668)
		(layer "F.Cu")
		(net "M_G_CPU0_SB_DQ<10>")
	)
	(segment
		(start 401.545298 -281.217624)
		(end 401.545298 -281.382724)
		(width 0.10668)
		(layer "F.Cu")
		(net "M_G_CPU0_SB_DQ<10>")
	)
	(segment
		(start 404.075646 -283.645864)
		(end 404.12416 -283.59735)
		(width 0.10668)
		(layer "F.Cu")
		(net "M_G_CPU0_SB_DQ<10>")
	)
	(segment
		(start 404.406354 -283.728668)
		(end 404.406354 -283.879544)
		(width 0.10668)
		(layer "F.Cu")
		(net "M_G_CPU0_SB_DQ<10>")
	)
	(segment
		(start 402.956268 -282.628594)
		(end 403.048724 -282.536138)
		(width 0.10668)
		(layer "F.Cu")
		(net "M_G_CPU0_SB_DQ<10>")
	)
	(segment
		(start 400.766534 -279.573736)
		(end 400.766534 -279.738836)
		(width 0.10668)
		(layer "F.Cu")
		(net "M_G_CPU0_SB_DQ<10>")
	)
	(segment
		(start 404.922228 -284.492446)
		(end 404.922228 -284.643322)
		(width 0.10668)
		(layer "F.Cu")
		(net "M_G_CPU0_SB_DQ<10>")
	)
	(segment
		(start 405.486616 -285.056834)
		(end 405.486616 -285.20771)
		(width 0.10668)
		(layer "F.Cu")
		(net "M_G_CPU0_SB_DQ<10>")
	)
	(segment
		(start 405.617934 -285.339028)
		(end 405.76881 -285.339028)
		(width 0.10668)
		(layer "F.Cu")
		(net "M_G_CPU0_SB_DQ<10>")
	)
	(segment
		(start 410.901388 -290.223702)
		(end 410.901388 -291.093398)
		(width 0.10668)
		(layer "F.Cu")
		(net "M_G_CPU0_SB_DQ<10>")
	)
	(segment
		(start 402.741892 -281.714194)
		(end 402.906992 -281.714194)
		(width 0.10668)
		(layer "F.Cu")
		(net "M_G_CPU0_SB_DQ<10>")
	)
	(segment
		(start 404.839424 -284.161738)
		(end 404.970742 -284.293056)
		(width 0.10668)
		(layer "F.Cu")
		(net "M_G_CPU0_SB_DQ<10>")
	)
	(segment
		(start 405.252936 -284.726126)
		(end 405.403812 -284.726126)
		(width 0.10668)
		(layer "F.Cu")
		(net "M_G_CPU0_SB_DQ<10>")
	)
	(segment
		(start 404.970742 -284.443932)
		(end 404.922228 -284.492446)
		(width 0.10668)
		(layer "F.Cu")
		(net "M_G_CPU0_SB_DQ<10>")
	)
	(segment
		(start 405.403812 -284.726126)
		(end 405.53513 -284.857444)
		(width 0.10668)
		(layer "F.Cu")
		(net "M_G_CPU0_SB_DQ<10>")
	)
	(segment
		(start 400.766534 -279.738836)
		(end 400.416522 -280.088848)
		(width 0.10668)
		(layer "F.Cu")
		(net "M_G_CPU0_SB_DQ<10>")
	)
	(segment
		(start 395.187932 -279.117044)
		(end 395.199108 -279.105868)
		(width 0.0762)
		(layer "F.Cu")
		(net "M_G_CPU0_SB_DQ<10>")
	)
	(segment
		(start 404.275036 -283.59735)
		(end 404.406354 -283.728668)
		(width 0.10668)
		(layer "F.Cu")
		(net "M_G_CPU0_SB_DQ<10>")
	)
	(segment
		(start 402.459698 -281.432)
		(end 402.109686 -281.782012)
		(width 0.10668)
		(layer "F.Cu")
		(net "M_G_CPU0_SB_DQ<10>")
	)
	(segment
		(start 405.204422 -284.77464)
		(end 405.252936 -284.726126)
		(width 0.10668)
		(layer "F.Cu")
		(net "M_G_CPU0_SB_DQ<10>")
	)
	(segment
		(start 405.053546 -284.77464)
		(end 405.204422 -284.77464)
		(width 0.10668)
		(layer "F.Cu")
		(net "M_G_CPU0_SB_DQ<10>")
	)
	(segment
		(start 399.94459 -279.432004)
		(end 399.852134 -279.52446)
		(width 0.10668)
		(layer "F.Cu")
		(net "M_G_CPU0_SB_DQ<10>")
	)
	(segment
		(start 401.213828 -280.02103)
		(end 401.330922 -280.138124)
		(width 0.10668)
		(layer "F.Cu")
		(net "M_G_CPU0_SB_DQ<10>")
	)
	(segment
		(start 402.459698 -281.2669)
		(end 402.459698 -281.432)
		(width 0.10668)
		(layer "F.Cu")
		(net "M_G_CPU0_SB_DQ<10>")
	)
	(segment
		(start 403.024086 -281.996388)
		(end 402.674074 -282.3464)
		(width 0.10668)
		(layer "F.Cu")
		(net "M_G_CPU0_SB_DQ<10>")
	)
	(segment
		(start 401.613116 -280.585418)
		(end 401.778216 -280.585418)
		(width 0.10668)
		(layer "F.Cu")
		(net "M_G_CPU0_SB_DQ<10>")
	)
	(segment
		(start 400.64944 -279.456642)
		(end 400.766534 -279.573736)
		(width 0.10668)
		(layer "F.Cu")
		(net "M_G_CPU0_SB_DQ<10>")
	)
	(segment
		(start 401.330922 -280.303224)
		(end 400.98091 -280.653236)
		(width 0.10668)
		(layer "F.Cu")
		(net "M_G_CPU0_SB_DQ<10>")
	)
	(segment
		(start 401.662392 -281.499818)
		(end 401.827492 -281.499818)
		(width 0.10668)
		(layer "F.Cu")
		(net "M_G_CPU0_SB_DQ<10>")
	)
	(segment
		(start 395.199108 -279.105868)
		(end 395.888718 -279.105868)
		(width 0.0762)
		(layer "F.Cu")
		(net "M_G_CPU0_SB_DQ<10>")
	)
	(segment
		(start 405.486616 -285.20771)
		(end 405.617934 -285.339028)
		(width 0.10668)
		(layer "F.Cu")
		(net "M_G_CPU0_SB_DQ<10>")
	)
	(segment
		(start 405.53513 -285.00832)
		(end 405.486616 -285.056834)
		(width 0.10668)
		(layer "F.Cu")
		(net "M_G_CPU0_SB_DQ<10>")
	)
	(segment
		(start 404.922228 -284.643322)
		(end 405.053546 -284.77464)
		(width 0.10668)
		(layer "F.Cu")
		(net "M_G_CPU0_SB_DQ<10>")
	)
	(segment
		(start 403.793452 -283.36367)
		(end 403.793452 -283.514546)
		(width 0.10668)
		(layer "F.Cu")
		(net "M_G_CPU0_SB_DQ<10>")
	)
	(segment
		(start 400.416522 -280.253948)
		(end 400.533616 -280.371042)
		(width 0.10668)
		(layer "F.Cu")
		(net "M_G_CPU0_SB_DQ<10>")
	)
	(segment
		(start 401.098004 -280.93543)
		(end 401.263104 -280.93543)
		(width 0.10668)
		(layer "F.Cu")
		(net "M_G_CPU0_SB_DQ<10>")
	)
	(segment
		(start 399.969228 -279.806654)
		(end 400.134328 -279.806654)
		(width 0.10668)
		(layer "F.Cu")
		(net "M_G_CPU0_SB_DQ<10>")
	)
	(segment
		(start 411.492954 -291.684964)
		(end 412.367984 -291.684964)
		(width 0.10668)
		(layer "F.Cu")
		(net "M_G_CPU0_SB_DQ<10>")
	)
	(segment
		(start 402.109686 -281.947112)
		(end 402.22678 -282.064206)
		(width 0.10668)
		(layer "F.Cu")
		(net "M_G_CPU0_SB_DQ<10>")
	)
	(segment
		(start 402.791168 -282.628594)
		(end 402.956268 -282.628594)
		(width 0.10668)
		(layer "F.Cu")
		(net "M_G_CPU0_SB_DQ<10>")
	)
	(arc
		(start 393.916916 -279.240742)
		(mid 393.936265 -279.238404)
		(end 393.955524 -279.235408)
		(width 0.0762)
		(layer "F.Cu")
		(net "M_G_CPU0_SB_DQ<10>")
	)
	(arc
		(start 393.387834 -279.49017)
		(mid 393.631265 -279.320683)
		(end 393.916916 -279.240742)
		(width 0.0762)
		(layer "F.Cu")
		(net "M_G_CPU0_SB_DQ<10>")
	)
	(arc
		(start 394.140944 -279.16759)
		(mid 394.216184 -279.134277)
		(end 394.2969 -279.118314)
		(width 0.0762)
		(layer "F.Cu")
		(net "M_G_CPU0_SB_DQ<10>")
	)
	(arc
		(start 394.2969 -279.118314)
		(mid 394.312381 -279.117358)
		(end 394.327888 -279.117044)
		(width 0.0762)
		(layer "F.Cu")
		(net "M_G_CPU0_SB_DQ<10>")
	)
	(arc
		(start 393.955524 -279.235408)
		(mid 394.051233 -279.209696)
		(end 394.140944 -279.16759)
		(width 0.0762)
		(layer "F.Cu")
		(net "M_G_CPU0_SB_DQ<10>")
	)
	(segment
		(start 414.818068 -281.910028)
		(end 415.219896 -281.910028)
		(width 0.101346)
		(layer "F.Cu")
		(net "M_G_CPU0_SB_DQ<0>")
	)
	(segment
		(start 404.335996 -275.137626)
		(end 405.294592 -275.137626)
		(width 0.10668)
		(layer "F.Cu")
		(net "M_G_CPU0_SB_DQ<0>")
	)
	(segment
		(start 414.309052 -281.135328)
		(end 414.424368 -281.020012)
		(width 0.101346)
		(layer "F.Cu")
		(net "M_G_CPU0_SB_DQ<0>")
	)
	(segment
		(start 393.857988 -273.820128)
		(end 393.755626 -273.996404)
		(width 0.0762)
		(layer "F.Cu")
		(net "M_G_CPU0_SB_DQ<0>")
	)
	(segment
		(start 395.090142 -274.066508)
		(end 395.322044 -273.834606)
		(width 0.0762)
		(layer "F.Cu")
		(net "M_G_CPU0_SB_DQ<0>")
	)
	(segment
		(start 411.019498 -280.862532)
		(end 411.019498 -281.586432)
		(width 0.10668)
		(layer "F.Cu")
		(net "M_G_CPU0_SB_DQ<0>")
	)
	(segment
		(start 395.322044 -273.834606)
		(end 395.86281 -273.834606)
		(width 0.0762)
		(layer "F.Cu")
		(net "M_G_CPU0_SB_DQ<0>")
	)
	(segment
		(start 394.03655 -274.147534)
		(end 394.044932 -274.142708)
		(width 0.0762)
		(layer "F.Cu")
		(net "M_G_CPU0_SB_DQ<0>")
	)
	(segment
		(start 414.587436 -281.020012)
		(end 414.702752 -281.135328)
		(width 0.101346)
		(layer "F.Cu")
		(net "M_G_CPU0_SB_DQ<0>")
	)
	(segment
		(start 394.327634 -274.066508)
		(end 395.090142 -274.066508)
		(width 0.0762)
		(layer "F.Cu")
		(net "M_G_CPU0_SB_DQ<0>")
	)
	(segment
		(start 414.309052 -281.794712)
		(end 414.309052 -281.135328)
		(width 0.101346)
		(layer "F.Cu")
		(net "M_G_CPU0_SB_DQ<0>")
	)
	(segment
		(start 405.294592 -275.137626)
		(end 411.019498 -280.862532)
		(width 0.10668)
		(layer "F.Cu")
		(net "M_G_CPU0_SB_DQ<0>")
	)
	(segment
		(start 411.019498 -281.586432)
		(end 411.317694 -281.884628)
		(width 0.10668)
		(layer "F.Cu")
		(net "M_G_CPU0_SB_DQ<0>")
	)
	(segment
		(start 411.317694 -281.884628)
		(end 411.343094 -281.910028)
		(width 0.101346)
		(layer "F.Cu")
		(net "M_G_CPU0_SB_DQ<0>")
	)
	(segment
		(start 411.343094 -281.910028)
		(end 414.193736 -281.910028)
		(width 0.101346)
		(layer "F.Cu")
		(net "M_G_CPU0_SB_DQ<0>")
	)
	(segment
		(start 414.702752 -281.135328)
		(end 414.702752 -281.794712)
		(width 0.101346)
		(layer "F.Cu")
		(net "M_G_CPU0_SB_DQ<0>")
	)
	(segment
		(start 414.702752 -281.794712)
		(end 414.818068 -281.910028)
		(width 0.101346)
		(layer "F.Cu")
		(net "M_G_CPU0_SB_DQ<0>")
	)
	(segment
		(start 414.424368 -281.020012)
		(end 414.587436 -281.020012)
		(width 0.101346)
		(layer "F.Cu")
		(net "M_G_CPU0_SB_DQ<0>")
	)
	(segment
		(start 415.219896 -281.910028)
		(end 415.644838 -281.485086)
		(width 0.101346)
		(layer "F.Cu")
		(net "M_G_CPU0_SB_DQ<0>")
	)
	(segment
		(start 395.86281 -273.834606)
		(end 403.032976 -273.834606)
		(width 0.10668)
		(layer "F.Cu")
		(net "M_G_CPU0_SB_DQ<0>")
	)
	(segment
		(start 415.644838 -281.485086)
		(end 416.468052 -281.485086)
		(width 0.101346)
		(layer "F.Cu")
		(net "M_G_CPU0_SB_DQ<0>")
	)
	(segment
		(start 403.032976 -273.834606)
		(end 404.335996 -275.137626)
		(width 0.10668)
		(layer "F.Cu")
		(net "M_G_CPU0_SB_DQ<0>")
	)
	(segment
		(start 414.193736 -281.910028)
		(end 414.309052 -281.794712)
		(width 0.101346)
		(layer "F.Cu")
		(net "M_G_CPU0_SB_DQ<0>")
	)
	(arc
		(start 394.044932 -274.142708)
		(mid 394.158656 -274.092407)
		(end 394.280644 -274.068286)
		(width 0.0762)
		(layer "F.Cu")
		(net "M_G_CPU0_SB_DQ<0>")
	)
	(arc
		(start 393.922504 -274.187412)
		(mid 393.98115 -274.172119)
		(end 394.03655 -274.147534)
		(width 0.0762)
		(layer "F.Cu")
		(net "M_G_CPU0_SB_DQ<0>")
	)
	(arc
		(start 394.280644 -274.068286)
		(mid 394.304121 -274.06691)
		(end 394.327634 -274.066508)
		(width 0.0762)
		(layer "F.Cu")
		(net "M_G_CPU0_SB_DQ<0>")
	)
	(arc
		(start 393.755626 -273.996404)
		(mid 393.785255 -274.138891)
		(end 393.922504 -274.187412)
		(width 0.0762)
		(layer "F.Cu")
		(net "M_G_CPU0_SB_DQ<0>")
	)
	(segment
		(start 409.945332 -267.269468)
		(end 411.410912 -268.735048)
		(width 0.10668)
		(layer "F.Cu")
		(net "M_G_CPU0_SB_CS_N<1>")
	)
	(segment
		(start 406.58669 -267.269468)
		(end 406.70353 -267.152628)
		(width 0.10668)
		(layer "F.Cu")
		(net "M_G_CPU0_SB_CS_N<1>")
	)
	(segment
		(start 398.467834 -267.269468)
		(end 406.58669 -267.269468)
		(width 0.10668)
		(layer "F.Cu")
		(net "M_G_CPU0_SB_CS_N<1>")
	)
	(segment
		(start 395.687296 -266.145772)
		(end 397.344138 -266.145772)
		(width 0.10668)
		(layer "F.Cu")
		(net "M_G_CPU0_SB_CS_N<1>")
	)
	(segment
		(start 406.70353 -266.58824)
		(end 406.82037 -266.4714)
		(width 0.10668)
		(layer "F.Cu")
		(net "M_G_CPU0_SB_CS_N<1>")
	)
	(segment
		(start 406.70353 -267.152628)
		(end 406.70353 -266.58824)
		(width 0.10668)
		(layer "F.Cu")
		(net "M_G_CPU0_SB_CS_N<1>")
	)
	(segment
		(start 397.344138 -266.145772)
		(end 398.467834 -267.269468)
		(width 0.10668)
		(layer "F.Cu")
		(net "M_G_CPU0_SB_CS_N<1>")
	)
	(segment
		(start 409.241498 -266.58824)
		(end 409.241498 -266.753594)
		(width 0.10668)
		(layer "F.Cu")
		(net "M_G_CPU0_SB_CS_N<1>")
	)
	(segment
		(start 407.219404 -266.870434)
		(end 407.102564 -266.987274)
		(width 0.10668)
		(layer "F.Cu")
		(net "M_G_CPU0_SB_CS_N<1>")
	)
	(segment
		(start 407.102564 -267.152628)
		(end 407.219404 -267.269468)
		(width 0.10668)
		(layer "F.Cu")
		(net "M_G_CPU0_SB_CS_N<1>")
	)
	(segment
		(start 409.124658 -266.4714)
		(end 409.241498 -266.58824)
		(width 0.10668)
		(layer "F.Cu")
		(net "M_G_CPU0_SB_CS_N<1>")
	)
	(segment
		(start 409.241498 -266.753594)
		(end 409.124658 -266.870434)
		(width 0.10668)
		(layer "F.Cu")
		(net "M_G_CPU0_SB_CS_N<1>")
	)
	(segment
		(start 406.82037 -266.4714)
		(end 409.124658 -266.4714)
		(width 0.10668)
		(layer "F.Cu")
		(net "M_G_CPU0_SB_CS_N<1>")
	)
	(segment
		(start 395.16177 -266.145772)
		(end 395.687296 -266.145772)
		(width 0.0762)
		(layer "F.Cu")
		(net "M_G_CPU0_SB_CS_N<1>")
	)
	(segment
		(start 394.364718 -266.147042)
		(end 395.16177 -266.145772)
		(width 0.0762)
		(layer "F.Cu")
		(net "M_G_CPU0_SB_CS_N<1>")
	)
	(segment
		(start 409.124658 -266.870434)
		(end 407.219404 -266.870434)
		(width 0.10668)
		(layer "F.Cu")
		(net "M_G_CPU0_SB_CS_N<1>")
	)
	(segment
		(start 411.410912 -268.735048)
		(end 412.367984 -268.735048)
		(width 0.10668)
		(layer "F.Cu")
		(net "M_G_CPU0_SB_CS_N<1>")
	)
	(segment
		(start 407.102564 -266.987274)
		(end 407.102564 -267.152628)
		(width 0.10668)
		(layer "F.Cu")
		(net "M_G_CPU0_SB_CS_N<1>")
	)
	(segment
		(start 407.219404 -267.269468)
		(end 409.945332 -267.269468)
		(width 0.10668)
		(layer "F.Cu")
		(net "M_G_CPU0_SB_CS_N<1>")
	)
	(arc
		(start 393.836652 -266.28344)
		(mid 393.994188 -266.267064)
		(end 394.140944 -266.207494)
		(width 0.0762)
		(layer "F.Cu")
		(net "M_G_CPU0_SB_CS_N<1>")
	)
	(arc
		(start 394.140944 -266.207494)
		(mid 394.248842 -266.162511)
		(end 394.364718 -266.147042)
		(width 0.0762)
		(layer "F.Cu")
		(net "M_G_CPU0_SB_CS_N<1>")
	)
	(arc
		(start 393.387834 -266.530074)
		(mid 393.578121 -266.344648)
		(end 393.836652 -266.28344)
		(width 0.0762)
		(layer "F.Cu")
		(net "M_G_CPU0_SB_CS_N<1>")
	)
	(segment
		(start 397.62684 -265.465052)
		(end 398.750536 -266.588748)
		(width 0.10668)
		(layer "F.Cu")
		(net "M_G_CPU0_SB_CS_N<0>")
	)
	(segment
		(start 395.314424 -265.501374)
		(end 395.350746 -265.465052)
		(width 0.0762)
		(layer "F.Cu")
		(net "M_G_CPU0_SB_CS_N<0>")
	)
	(segment
		(start 414.498028 -267.885164)
		(end 416.468052 -267.885164)
		(width 0.101346)
		(layer "F.Cu")
		(net "M_G_CPU0_SB_CS_N<0>")
	)
	(segment
		(start 395.802866 -265.465052)
		(end 397.62684 -265.465052)
		(width 0.10668)
		(layer "F.Cu")
		(net "M_G_CPU0_SB_CS_N<0>")
	)
	(segment
		(start 394.331698 -265.501374)
		(end 395.314424 -265.501374)
		(width 0.0762)
		(layer "F.Cu")
		(net "M_G_CPU0_SB_CS_N<0>")
	)
	(segment
		(start 409.495752 -265.79068)
		(end 411.165294 -267.460222)
		(width 0.10668)
		(layer "F.Cu")
		(net "M_G_CPU0_SB_CS_N<0>")
	)
	(segment
		(start 406.157176 -265.79068)
		(end 409.495752 -265.79068)
		(width 0.10668)
		(layer "F.Cu")
		(net "M_G_CPU0_SB_CS_N<0>")
	)
	(segment
		(start 411.317694 -267.460222)
		(end 414.073086 -267.460222)
		(width 0.101346)
		(layer "F.Cu")
		(net "M_G_CPU0_SB_CS_N<0>")
	)
	(segment
		(start 414.073086 -267.460222)
		(end 414.498028 -267.885164)
		(width 0.101346)
		(layer "F.Cu")
		(net "M_G_CPU0_SB_CS_N<0>")
	)
	(segment
		(start 394.03655 -265.392662)
		(end 394.044932 -265.397488)
		(width 0.0762)
		(layer "F.Cu")
		(net "M_G_CPU0_SB_CS_N<0>")
	)
	(segment
		(start 405.359108 -266.588748)
		(end 406.157176 -265.79068)
		(width 0.10668)
		(layer "F.Cu")
		(net "M_G_CPU0_SB_CS_N<0>")
	)
	(segment
		(start 411.165294 -267.460222)
		(end 411.317694 -267.460222)
		(width 0.10668)
		(layer "F.Cu")
		(net "M_G_CPU0_SB_CS_N<0>")
	)
	(segment
		(start 398.750536 -266.588748)
		(end 405.359108 -266.588748)
		(width 0.10668)
		(layer "F.Cu")
		(net "M_G_CPU0_SB_CS_N<0>")
	)
	(segment
		(start 395.350746 -265.465052)
		(end 395.802866 -265.465052)
		(width 0.0762)
		(layer "F.Cu")
		(net "M_G_CPU0_SB_CS_N<0>")
	)
	(arc
		(start 393.67079 -265.397488)
		(mid 393.853041 -265.347138)
		(end 394.03655 -265.392662)
		(width 0.0762)
		(layer "F.Cu")
		(net "M_G_CPU0_SB_CS_N<0>")
	)
	(arc
		(start 393.104878 -265.397488)
		(mid 393.387834 -265.473665)
		(end 393.67079 -265.397488)
		(width 0.0762)
		(layer "F.Cu")
		(net "M_G_CPU0_SB_CS_N<0>")
	)
	(arc
		(start 394.044932 -265.397488)
		(mid 394.147826 -265.44986)
		(end 394.256006 -265.490198)
		(width 0.0762)
		(layer "F.Cu")
		(net "M_G_CPU0_SB_CS_N<0>")
	)
	(arc
		(start 391.97788 -265.720068)
		(mid 392.173229 -265.536249)
		(end 392.434064 -265.473688)
		(width 0.0762)
		(layer "F.Cu")
		(net "M_G_CPU0_SB_CS_N<0>")
	)
	(arc
		(start 392.73099 -265.397488)
		(mid 392.917934 -265.347233)
		(end 393.104878 -265.397488)
		(width 0.0762)
		(layer "F.Cu")
		(net "M_G_CPU0_SB_CS_N<0>")
	)
	(arc
		(start 392.434064 -265.473688)
		(mid 392.587813 -265.456179)
		(end 392.73099 -265.397488)
		(width 0.0762)
		(layer "F.Cu")
		(net "M_G_CPU0_SB_CS_N<0>")
	)
	(arc
		(start 394.256006 -265.490198)
		(mid 394.293432 -265.498637)
		(end 394.331698 -265.501374)
		(width 0.0762)
		(layer "F.Cu")
		(net "M_G_CPU0_SB_CS_N<0>")
	)
	(segment
		(start 409.453334 -272.873216)
		(end 409.453334 -273.038062)
		(width 0.10668)
		(layer "F.Cu")
		(net "M_G_CPU0_SB_CB<7>")
	)
	(segment
		(start 411.14853 -273.603974)
		(end 411.14853 -273.76882)
		(width 0.10668)
		(layer "F.Cu")
		(net "M_G_CPU0_SB_CB<7>")
	)
	(segment
		(start 409.735782 -272.755868)
		(end 409.570682 -272.755868)
		(width 0.10668)
		(layer "F.Cu")
		(net "M_G_CPU0_SB_CB<7>")
	)
	(segment
		(start 395.789658 -270.235172)
		(end 407.779728 -270.235172)
		(width 0.10668)
		(layer "F.Cu")
		(net "M_G_CPU0_SB_CB<7>")
	)
	(segment
		(start 409.453334 -273.038062)
		(end 411.10027 -274.684998)
		(width 0.10668)
		(layer "F.Cu")
		(net "M_G_CPU0_SB_CB<7>")
	)
	(segment
		(start 395.23416 -270.36141)
		(end 395.360398 -270.235172)
		(width 0.0762)
		(layer "F.Cu")
		(net "M_G_CPU0_SB_CB<7>")
	)
	(segment
		(start 395.360398 -270.235172)
		(end 395.789658 -270.235172)
		(width 0.0762)
		(layer "F.Cu")
		(net "M_G_CPU0_SB_CB<7>")
	)
	(segment
		(start 411.10027 -274.684998)
		(end 412.367984 -274.684998)
		(width 0.10668)
		(layer "F.Cu")
		(net "M_G_CPU0_SB_CB<7>")
	)
	(segment
		(start 407.779728 -270.235172)
		(end 411.14853 -273.603974)
		(width 0.10668)
		(layer "F.Cu")
		(net "M_G_CPU0_SB_CB<7>")
	)
	(segment
		(start 409.570682 -272.755868)
		(end 409.453334 -272.873216)
		(width 0.10668)
		(layer "F.Cu")
		(net "M_G_CPU0_SB_CB<7>")
	)
	(segment
		(start 394.03655 -270.252698)
		(end 394.044932 -270.257524)
		(width 0.0762)
		(layer "F.Cu")
		(net "M_G_CPU0_SB_CB<7>")
	)
	(segment
		(start 411.14853 -273.76882)
		(end 411.031182 -273.886168)
		(width 0.10668)
		(layer "F.Cu")
		(net "M_G_CPU0_SB_CB<7>")
	)
	(segment
		(start 411.031182 -273.886168)
		(end 410.866082 -273.886168)
		(width 0.10668)
		(layer "F.Cu")
		(net "M_G_CPU0_SB_CB<7>")
	)
	(segment
		(start 394.331698 -270.36141)
		(end 395.23416 -270.36141)
		(width 0.0762)
		(layer "F.Cu")
		(net "M_G_CPU0_SB_CB<7>")
	)
	(segment
		(start 410.866082 -273.886168)
		(end 409.735782 -272.755868)
		(width 0.10668)
		(layer "F.Cu")
		(net "M_G_CPU0_SB_CB<7>")
	)
	(arc
		(start 394.256006 -270.350234)
		(mid 394.293432 -270.358673)
		(end 394.331698 -270.36141)
		(width 0.0762)
		(layer "F.Cu")
		(net "M_G_CPU0_SB_CB<7>")
	)
	(arc
		(start 394.044932 -270.257524)
		(mid 394.147826 -270.309896)
		(end 394.256006 -270.350234)
		(width 0.0762)
		(layer "F.Cu")
		(net "M_G_CPU0_SB_CB<7>")
	)
	(arc
		(start 392.73099 -270.257524)
		(mid 392.917934 -270.207269)
		(end 393.104878 -270.257524)
		(width 0.0762)
		(layer "F.Cu")
		(net "M_G_CPU0_SB_CB<7>")
	)
	(arc
		(start 393.104878 -270.257524)
		(mid 393.387834 -270.333701)
		(end 393.67079 -270.257524)
		(width 0.0762)
		(layer "F.Cu")
		(net "M_G_CPU0_SB_CB<7>")
	)
	(arc
		(start 391.97788 -270.580104)
		(mid 392.173229 -270.396285)
		(end 392.434064 -270.333724)
		(width 0.0762)
		(layer "F.Cu")
		(net "M_G_CPU0_SB_CB<7>")
	)
	(arc
		(start 392.434064 -270.333724)
		(mid 392.587813 -270.316215)
		(end 392.73099 -270.257524)
		(width 0.0762)
		(layer "F.Cu")
		(net "M_G_CPU0_SB_CB<7>")
	)
	(arc
		(start 393.67079 -270.257524)
		(mid 393.853041 -270.207174)
		(end 394.03655 -270.252698)
		(width 0.0762)
		(layer "F.Cu")
		(net "M_G_CPU0_SB_CB<7>")
	)
	(segment
		(start 405.633174 -268.886432)
		(end 405.750014 -269.003272)
		(width 0.10668)
		(layer "F.Cu")
		(net "M_G_CPU0_SB_CB<6>")
	)
	(segment
		(start 405.750014 -269.236952)
		(end 405.866854 -269.353792)
		(width 0.10668)
		(layer "F.Cu")
		(net "M_G_CPU0_SB_CB<6>")
	)
	(segment
		(start 394.327888 -269.396972)
		(end 395.187932 -269.396972)
		(width 0.0762)
		(layer "F.Cu")
		(net "M_G_CPU0_SB_CB<6>")
	)
	(segment
		(start 399.881344 -268.886432)
		(end 400.046698 -268.886432)
		(width 0.10668)
		(layer "F.Cu")
		(net "M_G_CPU0_SB_CB<6>")
	)
	(segment
		(start 400.961606 -269.236952)
		(end 401.078446 -269.353792)
		(width 0.10668)
		(layer "F.Cu")
		(net "M_G_CPU0_SB_CB<6>")
	)
	(segment
		(start 402.839936 -269.353792)
		(end 402.956776 -269.236952)
		(width 0.10668)
		(layer "F.Cu")
		(net "M_G_CPU0_SB_CB<6>")
	)
	(segment
		(start 401.759674 -269.003272)
		(end 401.759674 -269.236952)
		(width 0.10668)
		(layer "F.Cu")
		(net "M_G_CPU0_SB_CB<6>")
	)
	(segment
		(start 400.163538 -269.236952)
		(end 400.280378 -269.353792)
		(width 0.10668)
		(layer "F.Cu")
		(net "M_G_CPU0_SB_CB<6>")
	)
	(segment
		(start 401.36064 -269.236952)
		(end 401.36064 -269.003272)
		(width 0.10668)
		(layer "F.Cu")
		(net "M_G_CPU0_SB_CB<6>")
	)
	(segment
		(start 404.153878 -269.003272)
		(end 404.153878 -269.236952)
		(width 0.10668)
		(layer "F.Cu")
		(net "M_G_CPU0_SB_CB<6>")
	)
	(segment
		(start 411.381702 -272.873216)
		(end 411.381702 -272.87347)
		(width 0.10668)
		(layer "F.Cu")
		(net "M_G_CPU0_SB_CB<6>")
	)
	(segment
		(start 407.46299 -269.353792)
		(end 407.862278 -269.353792)
		(width 0.10668)
		(layer "F.Cu")
		(net "M_G_CPU0_SB_CB<6>")
	)
	(segment
		(start 401.876514 -269.353792)
		(end 402.041868 -269.353792)
		(width 0.10668)
		(layer "F.Cu")
		(net "M_G_CPU0_SB_CB<6>")
	)
	(segment
		(start 401.759674 -269.236952)
		(end 401.876514 -269.353792)
		(width 0.10668)
		(layer "F.Cu")
		(net "M_G_CPU0_SB_CB<6>")
	)
	(segment
		(start 405.35098 -269.236952)
		(end 405.35098 -269.003272)
		(width 0.10668)
		(layer "F.Cu")
		(net "M_G_CPU0_SB_CB<6>")
	)
	(segment
		(start 406.431242 -268.886432)
		(end 406.548082 -269.003272)
		(width 0.10668)
		(layer "F.Cu")
		(net "M_G_CPU0_SB_CB<6>")
	)
	(segment
		(start 403.35581 -269.003272)
		(end 403.35581 -269.236952)
		(width 0.10668)
		(layer "F.Cu")
		(net "M_G_CPU0_SB_CB<6>")
	)
	(segment
		(start 405.068786 -269.353792)
		(end 405.23414 -269.353792)
		(width 0.10668)
		(layer "F.Cu")
		(net "M_G_CPU0_SB_CB<6>")
	)
	(segment
		(start 395.902942 -269.353792)
		(end 399.647664 -269.353792)
		(width 0.10668)
		(layer "F.Cu")
		(net "M_G_CPU0_SB_CB<6>")
	)
	(segment
		(start 407.34615 -269.236952)
		(end 407.46299 -269.353792)
		(width 0.10668)
		(layer "F.Cu")
		(net "M_G_CPU0_SB_CB<6>")
	)
	(segment
		(start 402.557742 -269.236952)
		(end 402.674582 -269.353792)
		(width 0.10668)
		(layer "F.Cu")
		(net "M_G_CPU0_SB_CB<6>")
	)
	(segment
		(start 406.548082 -269.236952)
		(end 406.664922 -269.353792)
		(width 0.10668)
		(layer "F.Cu")
		(net "M_G_CPU0_SB_CB<6>")
	)
	(segment
		(start 406.548082 -269.003272)
		(end 406.548082 -269.236952)
		(width 0.10668)
		(layer "F.Cu")
		(net "M_G_CPU0_SB_CB<6>")
	)
	(segment
		(start 399.647664 -269.353792)
		(end 399.764504 -269.236952)
		(width 0.10668)
		(layer "F.Cu")
		(net "M_G_CPU0_SB_CB<6>")
	)
	(segment
		(start 406.149048 -269.003272)
		(end 406.265888 -268.886432)
		(width 0.10668)
		(layer "F.Cu")
		(net "M_G_CPU0_SB_CB<6>")
	)
	(segment
		(start 400.046698 -268.886432)
		(end 400.163538 -269.003272)
		(width 0.10668)
		(layer "F.Cu")
		(net "M_G_CPU0_SB_CB<6>")
	)
	(segment
		(start 404.153878 -269.236952)
		(end 404.270718 -269.353792)
		(width 0.10668)
		(layer "F.Cu")
		(net "M_G_CPU0_SB_CB<6>")
	)
	(segment
		(start 399.764504 -269.236952)
		(end 399.764504 -269.003272)
		(width 0.10668)
		(layer "F.Cu")
		(net "M_G_CPU0_SB_CB<6>")
	)
	(segment
		(start 404.552912 -269.236952)
		(end 404.552912 -269.003272)
		(width 0.10668)
		(layer "F.Cu")
		(net "M_G_CPU0_SB_CB<6>")
	)
	(segment
		(start 400.562572 -269.003272)
		(end 400.679412 -268.886432)
		(width 0.10668)
		(layer "F.Cu")
		(net "M_G_CPU0_SB_CB<6>")
	)
	(segment
		(start 405.46782 -268.886432)
		(end 405.633174 -268.886432)
		(width 0.10668)
		(layer "F.Cu")
		(net "M_G_CPU0_SB_CB<6>")
	)
	(segment
		(start 400.679412 -268.886432)
		(end 400.844766 -268.886432)
		(width 0.10668)
		(layer "F.Cu")
		(net "M_G_CPU0_SB_CB<6>")
	)
	(segment
		(start 400.562572 -269.236952)
		(end 400.562572 -269.003272)
		(width 0.10668)
		(layer "F.Cu")
		(net "M_G_CPU0_SB_CB<6>")
	)
	(segment
		(start 400.961606 -269.003272)
		(end 400.961606 -269.236952)
		(width 0.10668)
		(layer "F.Cu")
		(net "M_G_CPU0_SB_CB<6>")
	)
	(segment
		(start 402.674582 -269.353792)
		(end 402.839936 -269.353792)
		(width 0.10668)
		(layer "F.Cu")
		(net "M_G_CPU0_SB_CB<6>")
	)
	(segment
		(start 401.642834 -268.886432)
		(end 401.759674 -269.003272)
		(width 0.10668)
		(layer "F.Cu")
		(net "M_G_CPU0_SB_CB<6>")
	)
	(segment
		(start 402.440902 -268.886432)
		(end 402.557742 -269.003272)
		(width 0.10668)
		(layer "F.Cu")
		(net "M_G_CPU0_SB_CB<6>")
	)
	(segment
		(start 405.866854 -269.353792)
		(end 406.032208 -269.353792)
		(width 0.10668)
		(layer "F.Cu")
		(net "M_G_CPU0_SB_CB<6>")
	)
	(segment
		(start 403.073616 -268.886432)
		(end 403.23897 -268.886432)
		(width 0.10668)
		(layer "F.Cu")
		(net "M_G_CPU0_SB_CB<6>")
	)
	(segment
		(start 406.149048 -269.236952)
		(end 406.149048 -269.003272)
		(width 0.10668)
		(layer "F.Cu")
		(net "M_G_CPU0_SB_CB<6>")
	)
	(segment
		(start 401.2438 -269.353792)
		(end 401.36064 -269.236952)
		(width 0.10668)
		(layer "F.Cu")
		(net "M_G_CPU0_SB_CB<6>")
	)
	(segment
		(start 403.47265 -269.353792)
		(end 403.638004 -269.353792)
		(width 0.10668)
		(layer "F.Cu")
		(net "M_G_CPU0_SB_CB<6>")
	)
	(segment
		(start 403.23897 -268.886432)
		(end 403.35581 -269.003272)
		(width 0.10668)
		(layer "F.Cu")
		(net "M_G_CPU0_SB_CB<6>")
	)
	(segment
		(start 401.078446 -269.353792)
		(end 401.2438 -269.353792)
		(width 0.10668)
		(layer "F.Cu")
		(net "M_G_CPU0_SB_CB<6>")
	)
	(segment
		(start 404.951946 -269.236952)
		(end 405.068786 -269.353792)
		(width 0.10668)
		(layer "F.Cu")
		(net "M_G_CPU0_SB_CB<6>")
	)
	(segment
		(start 407.862278 -269.353792)
		(end 411.381702 -272.873216)
		(width 0.10668)
		(layer "F.Cu")
		(net "M_G_CPU0_SB_CB<6>")
	)
	(segment
		(start 403.754844 -269.236952)
		(end 403.754844 -269.003272)
		(width 0.10668)
		(layer "F.Cu")
		(net "M_G_CPU0_SB_CB<6>")
	)
	(segment
		(start 402.041868 -269.353792)
		(end 402.158708 -269.236952)
		(width 0.10668)
		(layer "F.Cu")
		(net "M_G_CPU0_SB_CB<6>")
	)
	(segment
		(start 400.280378 -269.353792)
		(end 400.445732 -269.353792)
		(width 0.10668)
		(layer "F.Cu")
		(net "M_G_CPU0_SB_CB<6>")
	)
	(segment
		(start 404.436072 -269.353792)
		(end 404.552912 -269.236952)
		(width 0.10668)
		(layer "F.Cu")
		(net "M_G_CPU0_SB_CB<6>")
	)
	(segment
		(start 403.754844 -269.003272)
		(end 403.871684 -268.886432)
		(width 0.10668)
		(layer "F.Cu")
		(net "M_G_CPU0_SB_CB<6>")
	)
	(segment
		(start 405.750014 -269.003272)
		(end 405.750014 -269.236952)
		(width 0.10668)
		(layer "F.Cu")
		(net "M_G_CPU0_SB_CB<6>")
	)
	(segment
		(start 406.830276 -269.353792)
		(end 406.947116 -269.236952)
		(width 0.10668)
		(layer "F.Cu")
		(net "M_G_CPU0_SB_CB<6>")
	)
	(segment
		(start 405.35098 -269.003272)
		(end 405.46782 -268.886432)
		(width 0.10668)
		(layer "F.Cu")
		(net "M_G_CPU0_SB_CB<6>")
	)
	(segment
		(start 407.34615 -269.003272)
		(end 407.34615 -269.236952)
		(width 0.10668)
		(layer "F.Cu")
		(net "M_G_CPU0_SB_CB<6>")
	)
	(segment
		(start 404.270718 -269.353792)
		(end 404.436072 -269.353792)
		(width 0.10668)
		(layer "F.Cu")
		(net "M_G_CPU0_SB_CB<6>")
	)
	(segment
		(start 404.037038 -268.886432)
		(end 404.153878 -269.003272)
		(width 0.10668)
		(layer "F.Cu")
		(net "M_G_CPU0_SB_CB<6>")
	)
	(segment
		(start 402.956776 -269.236952)
		(end 402.956776 -269.003272)
		(width 0.10668)
		(layer "F.Cu")
		(net "M_G_CPU0_SB_CB<6>")
	)
	(segment
		(start 406.265888 -268.886432)
		(end 406.431242 -268.886432)
		(width 0.10668)
		(layer "F.Cu")
		(net "M_G_CPU0_SB_CB<6>")
	)
	(segment
		(start 407.063956 -268.886432)
		(end 407.22931 -268.886432)
		(width 0.10668)
		(layer "F.Cu")
		(net "M_G_CPU0_SB_CB<6>")
	)
	(segment
		(start 406.947116 -269.003272)
		(end 407.063956 -268.886432)
		(width 0.10668)
		(layer "F.Cu")
		(net "M_G_CPU0_SB_CB<6>")
	)
	(segment
		(start 402.557742 -269.003272)
		(end 402.557742 -269.236952)
		(width 0.10668)
		(layer "F.Cu")
		(net "M_G_CPU0_SB_CB<6>")
	)
	(segment
		(start 400.844766 -268.886432)
		(end 400.961606 -269.003272)
		(width 0.10668)
		(layer "F.Cu")
		(net "M_G_CPU0_SB_CB<6>")
	)
	(segment
		(start 402.275548 -268.886432)
		(end 402.440902 -268.886432)
		(width 0.10668)
		(layer "F.Cu")
		(net "M_G_CPU0_SB_CB<6>")
	)
	(segment
		(start 404.552912 -269.003272)
		(end 404.669752 -268.886432)
		(width 0.10668)
		(layer "F.Cu")
		(net "M_G_CPU0_SB_CB<6>")
	)
	(segment
		(start 402.956776 -269.003272)
		(end 403.073616 -268.886432)
		(width 0.10668)
		(layer "F.Cu")
		(net "M_G_CPU0_SB_CB<6>")
	)
	(segment
		(start 400.163538 -269.003272)
		(end 400.163538 -269.236952)
		(width 0.10668)
		(layer "F.Cu")
		(net "M_G_CPU0_SB_CB<6>")
	)
	(segment
		(start 404.669752 -268.886432)
		(end 404.835106 -268.886432)
		(width 0.10668)
		(layer "F.Cu")
		(net "M_G_CPU0_SB_CB<6>")
	)
	(segment
		(start 401.47748 -268.886432)
		(end 401.642834 -268.886432)
		(width 0.10668)
		(layer "F.Cu")
		(net "M_G_CPU0_SB_CB<6>")
	)
	(segment
		(start 395.231112 -269.353792)
		(end 395.902942 -269.353792)
		(width 0.0762)
		(layer "F.Cu")
		(net "M_G_CPU0_SB_CB<6>")
	)
	(segment
		(start 404.951946 -269.003272)
		(end 404.951946 -269.236952)
		(width 0.10668)
		(layer "F.Cu")
		(net "M_G_CPU0_SB_CB<6>")
	)
	(segment
		(start 406.032208 -269.353792)
		(end 406.149048 -269.236952)
		(width 0.10668)
		(layer "F.Cu")
		(net "M_G_CPU0_SB_CB<6>")
	)
	(segment
		(start 407.22931 -268.886432)
		(end 407.34615 -269.003272)
		(width 0.10668)
		(layer "F.Cu")
		(net "M_G_CPU0_SB_CB<6>")
	)
	(segment
		(start 404.835106 -268.886432)
		(end 404.951946 -269.003272)
		(width 0.10668)
		(layer "F.Cu")
		(net "M_G_CPU0_SB_CB<6>")
	)
	(segment
		(start 400.445732 -269.353792)
		(end 400.562572 -269.236952)
		(width 0.10668)
		(layer "F.Cu")
		(net "M_G_CPU0_SB_CB<6>")
	)
	(segment
		(start 411.493208 -272.984976)
		(end 412.367984 -272.984976)
		(width 0.10668)
		(layer "F.Cu")
		(net "M_G_CPU0_SB_CB<6>")
	)
	(segment
		(start 403.638004 -269.353792)
		(end 403.754844 -269.236952)
		(width 0.10668)
		(layer "F.Cu")
		(net "M_G_CPU0_SB_CB<6>")
	)
	(segment
		(start 411.381702 -272.87347)
		(end 411.493208 -272.984976)
		(width 0.10668)
		(layer "F.Cu")
		(net "M_G_CPU0_SB_CB<6>")
	)
	(segment
		(start 399.764504 -269.003272)
		(end 399.881344 -268.886432)
		(width 0.10668)
		(layer "F.Cu")
		(net "M_G_CPU0_SB_CB<6>")
	)
	(segment
		(start 406.947116 -269.236952)
		(end 406.947116 -269.003272)
		(width 0.10668)
		(layer "F.Cu")
		(net "M_G_CPU0_SB_CB<6>")
	)
	(segment
		(start 395.187932 -269.396972)
		(end 395.231112 -269.353792)
		(width 0.0762)
		(layer "F.Cu")
		(net "M_G_CPU0_SB_CB<6>")
	)
	(segment
		(start 402.158708 -269.236952)
		(end 402.158708 -269.003272)
		(width 0.10668)
		(layer "F.Cu")
		(net "M_G_CPU0_SB_CB<6>")
	)
	(segment
		(start 403.871684 -268.886432)
		(end 404.037038 -268.886432)
		(width 0.10668)
		(layer "F.Cu")
		(net "M_G_CPU0_SB_CB<6>")
	)
	(segment
		(start 401.36064 -269.003272)
		(end 401.47748 -268.886432)
		(width 0.10668)
		(layer "F.Cu")
		(net "M_G_CPU0_SB_CB<6>")
	)
	(segment
		(start 405.23414 -269.353792)
		(end 405.35098 -269.236952)
		(width 0.10668)
		(layer "F.Cu")
		(net "M_G_CPU0_SB_CB<6>")
	)
	(segment
		(start 403.35581 -269.236952)
		(end 403.47265 -269.353792)
		(width 0.10668)
		(layer "F.Cu")
		(net "M_G_CPU0_SB_CB<6>")
	)
	(segment
		(start 406.664922 -269.353792)
		(end 406.830276 -269.353792)
		(width 0.10668)
		(layer "F.Cu")
		(net "M_G_CPU0_SB_CB<6>")
	)
	(segment
		(start 402.158708 -269.003272)
		(end 402.275548 -268.886432)
		(width 0.10668)
		(layer "F.Cu")
		(net "M_G_CPU0_SB_CB<6>")
	)
	(arc
		(start 394.2969 -269.398242)
		(mid 394.312381 -269.397286)
		(end 394.327888 -269.396972)
		(width 0.0762)
		(layer "F.Cu")
		(net "M_G_CPU0_SB_CB<6>")
	)
	(arc
		(start 394.140944 -269.447518)
		(mid 394.216184 -269.414205)
		(end 394.2969 -269.398242)
		(width 0.0762)
		(layer "F.Cu")
		(net "M_G_CPU0_SB_CB<6>")
	)
	(arc
		(start 393.916916 -269.52067)
		(mid 393.936265 -269.518332)
		(end 393.955524 -269.515336)
		(width 0.0762)
		(layer "F.Cu")
		(net "M_G_CPU0_SB_CB<6>")
	)
	(arc
		(start 393.387834 -269.770098)
		(mid 393.631265 -269.600611)
		(end 393.916916 -269.52067)
		(width 0.0762)
		(layer "F.Cu")
		(net "M_G_CPU0_SB_CB<6>")
	)
	(arc
		(start 393.955524 -269.515336)
		(mid 394.051233 -269.489624)
		(end 394.140944 -269.447518)
		(width 0.0762)
		(layer "F.Cu")
		(net "M_G_CPU0_SB_CB<6>")
	)
	(segment
		(start 414.990026 -273.719798)
		(end 415.105342 -273.835114)
		(width 0.101346)
		(layer "F.Cu")
		(net "M_G_CPU0_SB_CB<5>")
	)
	(segment
		(start 395.108176 -270.152114)
		(end 395.51229 -269.748)
		(width 0.0762)
		(layer "F.Cu")
		(net "M_G_CPU0_SB_CB<5>")
	)
	(segment
		(start 414.87471 -273.125692)
		(end 414.990026 -273.241008)
		(width 0.101346)
		(layer "F.Cu")
		(net "M_G_CPU0_SB_CB<5>")
	)
	(segment
		(start 414.711642 -273.125692)
		(end 414.87471 -273.125692)
		(width 0.101346)
		(layer "F.Cu")
		(net "M_G_CPU0_SB_CB<5>")
	)
	(segment
		(start 413.659574 -273.410172)
		(end 414.084516 -273.835114)
		(width 0.101346)
		(layer "F.Cu")
		(net "M_G_CPU0_SB_CB<5>")
	)
	(segment
		(start 414.990026 -273.241008)
		(end 414.990026 -273.719798)
		(width 0.101346)
		(layer "F.Cu")
		(net "M_G_CPU0_SB_CB<5>")
	)
	(segment
		(start 414.084516 -273.835114)
		(end 414.48101 -273.835114)
		(width 0.101346)
		(layer "F.Cu")
		(net "M_G_CPU0_SB_CB<5>")
	)
	(segment
		(start 392.448034 -269.770098)
		(end 392.339576 -269.956788)
		(width 0.0762)
		(layer "F.Cu")
		(net "M_G_CPU0_SB_CB<5>")
	)
	(segment
		(start 414.48101 -273.835114)
		(end 414.596326 -273.719798)
		(width 0.101346)
		(layer "F.Cu")
		(net "M_G_CPU0_SB_CB<5>")
	)
	(segment
		(start 395.51229 -269.748)
		(end 395.611096 -269.748)
		(width 0.0762)
		(layer "F.Cu")
		(net "M_G_CPU0_SB_CB<5>")
	)
	(segment
		(start 395.611096 -269.748)
		(end 407.774394 -269.748)
		(width 0.10668)
		(layer "F.Cu")
		(net "M_G_CPU0_SB_CB<5>")
	)
	(segment
		(start 393.20089 -270.092678)
		(end 393.201144 -270.092678)
		(width 0.0762)
		(layer "F.Cu")
		(net "M_G_CPU0_SB_CB<5>")
	)
	(segment
		(start 411.317694 -273.2913)
		(end 411.436566 -273.410172)
		(width 0.101346)
		(layer "F.Cu")
		(net "M_G_CPU0_SB_CB<5>")
	)
	(segment
		(start 407.774394 -269.748)
		(end 411.317694 -273.2913)
		(width 0.10668)
		(layer "F.Cu")
		(net "M_G_CPU0_SB_CB<5>")
	)
	(segment
		(start 414.596326 -273.719798)
		(end 414.596326 -273.241008)
		(width 0.101346)
		(layer "F.Cu")
		(net "M_G_CPU0_SB_CB<5>")
	)
	(segment
		(start 411.436566 -273.410172)
		(end 413.659574 -273.410172)
		(width 0.101346)
		(layer "F.Cu")
		(net "M_G_CPU0_SB_CB<5>")
	)
	(segment
		(start 392.626596 -270.097504)
		(end 392.634978 -270.092678)
		(width 0.0762)
		(layer "F.Cu")
		(net "M_G_CPU0_SB_CB<5>")
	)
	(segment
		(start 415.105342 -273.835114)
		(end 416.468052 -273.835114)
		(width 0.101346)
		(layer "F.Cu")
		(net "M_G_CPU0_SB_CB<5>")
	)
	(segment
		(start 394.298424 -270.150844)
		(end 395.108176 -270.152114)
		(width 0.0762)
		(layer "F.Cu")
		(net "M_G_CPU0_SB_CB<5>")
	)
	(segment
		(start 414.596326 -273.241008)
		(end 414.711642 -273.125692)
		(width 0.101346)
		(layer "F.Cu")
		(net "M_G_CPU0_SB_CB<5>")
	)
	(arc
		(start 392.634978 -270.092678)
		(mid 392.917934 -270.016501)
		(end 393.20089 -270.092678)
		(width 0.0762)
		(layer "F.Cu")
		(net "M_G_CPU0_SB_CB<5>")
	)
	(arc
		(start 392.339576 -269.956788)
		(mid 392.365493 -270.08983)
		(end 392.491214 -270.14043)
		(width 0.0762)
		(layer "F.Cu")
		(net "M_G_CPU0_SB_CB<5>")
	)
	(arc
		(start 393.201144 -270.092678)
		(mid 393.388088 -270.143002)
		(end 393.575032 -270.092678)
		(width 0.0762)
		(layer "F.Cu")
		(net "M_G_CPU0_SB_CB<5>")
	)
	(arc
		(start 392.491214 -270.14043)
		(mid 392.560968 -270.125473)
		(end 392.626596 -270.097504)
		(width 0.0762)
		(layer "F.Cu")
		(net "M_G_CPU0_SB_CB<5>")
	)
	(arc
		(start 394.140944 -270.092678)
		(mid 394.181638 -270.114897)
		(end 394.223494 -270.134842)
		(width 0.0762)
		(layer "F.Cu")
		(net "M_G_CPU0_SB_CB<5>")
	)
	(arc
		(start 394.223494 -270.134842)
		(mid 394.260122 -270.146772)
		(end 394.298424 -270.150844)
		(width 0.0762)
		(layer "F.Cu")
		(net "M_G_CPU0_SB_CB<5>")
	)
	(arc
		(start 393.575032 -270.092678)
		(mid 393.857988 -270.016501)
		(end 394.140944 -270.092678)
		(width 0.0762)
		(layer "F.Cu")
		(net "M_G_CPU0_SB_CB<5>")
	)
	(segment
		(start 398.000474 -268.524228)
		(end 398.117314 -268.641068)
		(width 0.10668)
		(layer "F.Cu")
		(net "M_G_CPU0_SB_CB<4>")
	)
	(segment
		(start 399.032222 -268.960092)
		(end 399.197576 -268.960092)
		(width 0.10668)
		(layer "F.Cu")
		(net "M_G_CPU0_SB_CB<4>")
	)
	(segment
		(start 397.436086 -268.960092)
		(end 397.60144 -268.960092)
		(width 0.10668)
		(layer "F.Cu")
		(net "M_G_CPU0_SB_CB<4>")
	)
	(segment
		(start 398.798542 -268.524228)
		(end 398.915382 -268.641068)
		(width 0.10668)
		(layer "F.Cu")
		(net "M_G_CPU0_SB_CB<4>")
	)
	(segment
		(start 414.100264 -272.560034)
		(end 414.525206 -272.135092)
		(width 0.101346)
		(layer "F.Cu")
		(net "M_G_CPU0_SB_CB<4>")
	)
	(segment
		(start 397.83512 -268.524228)
		(end 398.000474 -268.524228)
		(width 0.10668)
		(layer "F.Cu")
		(net "M_G_CPU0_SB_CB<4>")
	)
	(segment
		(start 393.857988 -268.960092)
		(end 393.755626 -269.136368)
		(width 0.0762)
		(layer "F.Cu")
		(net "M_G_CPU0_SB_CB<4>")
	)
	(segment
		(start 396.638018 -268.960092)
		(end 396.803372 -268.960092)
		(width 0.10668)
		(layer "F.Cu")
		(net "M_G_CPU0_SB_CB<4>")
	)
	(segment
		(start 396.803372 -268.960092)
		(end 396.920212 -268.843252)
		(width 0.10668)
		(layer "F.Cu")
		(net "M_G_CPU0_SB_CB<4>")
	)
	(segment
		(start 397.71828 -268.843252)
		(end 397.71828 -268.641068)
		(width 0.10668)
		(layer "F.Cu")
		(net "M_G_CPU0_SB_CB<4>")
	)
	(segment
		(start 396.521178 -268.843252)
		(end 396.638018 -268.960092)
		(width 0.10668)
		(layer "F.Cu")
		(net "M_G_CPU0_SB_CB<4>")
	)
	(segment
		(start 397.319246 -268.641068)
		(end 397.319246 -268.843252)
		(width 0.10668)
		(layer "F.Cu")
		(net "M_G_CPU0_SB_CB<4>")
	)
	(segment
		(start 407.514298 -268.524228)
		(end 411.387798 -272.397728)
		(width 0.10668)
		(layer "F.Cu")
		(net "M_G_CPU0_SB_CB<4>")
	)
	(segment
		(start 397.71828 -268.641068)
		(end 397.83512 -268.524228)
		(width 0.10668)
		(layer "F.Cu")
		(net "M_G_CPU0_SB_CB<4>")
	)
	(segment
		(start 397.60144 -268.960092)
		(end 397.71828 -268.843252)
		(width 0.10668)
		(layer "F.Cu")
		(net "M_G_CPU0_SB_CB<4>")
	)
	(segment
		(start 399.431256 -268.524228)
		(end 407.514298 -268.524228)
		(width 0.10668)
		(layer "F.Cu")
		(net "M_G_CPU0_SB_CB<4>")
	)
	(segment
		(start 399.314416 -268.641068)
		(end 399.431256 -268.524228)
		(width 0.10668)
		(layer "F.Cu")
		(net "M_G_CPU0_SB_CB<4>")
	)
	(segment
		(start 398.915382 -268.843252)
		(end 399.032222 -268.960092)
		(width 0.10668)
		(layer "F.Cu")
		(net "M_G_CPU0_SB_CB<4>")
	)
	(segment
		(start 396.065502 -268.524228)
		(end 396.404338 -268.524228)
		(width 0.10668)
		(layer "F.Cu")
		(net "M_G_CPU0_SB_CB<4>")
	)
	(segment
		(start 398.117314 -268.843252)
		(end 398.234154 -268.960092)
		(width 0.10668)
		(layer "F.Cu")
		(net "M_G_CPU0_SB_CB<4>")
	)
	(segment
		(start 397.319246 -268.843252)
		(end 397.436086 -268.960092)
		(width 0.10668)
		(layer "F.Cu")
		(net "M_G_CPU0_SB_CB<4>")
	)
	(segment
		(start 396.920212 -268.641068)
		(end 397.037052 -268.524228)
		(width 0.10668)
		(layer "F.Cu")
		(net "M_G_CPU0_SB_CB<4>")
	)
	(segment
		(start 414.525206 -272.135092)
		(end 416.468052 -272.135092)
		(width 0.101346)
		(layer "F.Cu")
		(net "M_G_CPU0_SB_CB<4>")
	)
	(segment
		(start 398.633188 -268.524228)
		(end 398.798542 -268.524228)
		(width 0.10668)
		(layer "F.Cu")
		(net "M_G_CPU0_SB_CB<4>")
	)
	(segment
		(start 398.915382 -268.641068)
		(end 398.915382 -268.843252)
		(width 0.10668)
		(layer "F.Cu")
		(net "M_G_CPU0_SB_CB<4>")
	)
	(segment
		(start 399.314416 -268.843252)
		(end 399.314416 -268.641068)
		(width 0.10668)
		(layer "F.Cu")
		(net "M_G_CPU0_SB_CB<4>")
	)
	(segment
		(start 396.521178 -268.641068)
		(end 396.521178 -268.843252)
		(width 0.10668)
		(layer "F.Cu")
		(net "M_G_CPU0_SB_CB<4>")
	)
	(segment
		(start 395.725142 -268.864588)
		(end 396.065502 -268.524228)
		(width 0.10668)
		(layer "F.Cu")
		(net "M_G_CPU0_SB_CB<4>")
	)
	(segment
		(start 396.920212 -268.843252)
		(end 396.920212 -268.641068)
		(width 0.10668)
		(layer "F.Cu")
		(net "M_G_CPU0_SB_CB<4>")
	)
	(segment
		(start 394.797788 -269.206472)
		(end 395.139672 -268.864588)
		(width 0.0762)
		(layer "F.Cu")
		(net "M_G_CPU0_SB_CB<4>")
	)
	(segment
		(start 394.327634 -269.206472)
		(end 394.797788 -269.206472)
		(width 0.0762)
		(layer "F.Cu")
		(net "M_G_CPU0_SB_CB<4>")
	)
	(segment
		(start 398.234154 -268.960092)
		(end 398.399508 -268.960092)
		(width 0.10668)
		(layer "F.Cu")
		(net "M_G_CPU0_SB_CB<4>")
	)
	(segment
		(start 397.202406 -268.524228)
		(end 397.319246 -268.641068)
		(width 0.10668)
		(layer "F.Cu")
		(net "M_G_CPU0_SB_CB<4>")
	)
	(segment
		(start 397.037052 -268.524228)
		(end 397.202406 -268.524228)
		(width 0.10668)
		(layer "F.Cu")
		(net "M_G_CPU0_SB_CB<4>")
	)
	(segment
		(start 398.516348 -268.641068)
		(end 398.633188 -268.524228)
		(width 0.10668)
		(layer "F.Cu")
		(net "M_G_CPU0_SB_CB<4>")
	)
	(segment
		(start 399.197576 -268.960092)
		(end 399.314416 -268.843252)
		(width 0.10668)
		(layer "F.Cu")
		(net "M_G_CPU0_SB_CB<4>")
	)
	(segment
		(start 411.550104 -272.560034)
		(end 414.100264 -272.560034)
		(width 0.101346)
		(layer "F.Cu")
		(net "M_G_CPU0_SB_CB<4>")
	)
	(segment
		(start 411.387798 -272.397728)
		(end 411.550104 -272.560034)
		(width 0.101346)
		(layer "F.Cu")
		(net "M_G_CPU0_SB_CB<4>")
	)
	(segment
		(start 395.139672 -268.864588)
		(end 395.725142 -268.864588)
		(width 0.0762)
		(layer "F.Cu")
		(net "M_G_CPU0_SB_CB<4>")
	)
	(segment
		(start 396.404338 -268.524228)
		(end 396.521178 -268.641068)
		(width 0.10668)
		(layer "F.Cu")
		(net "M_G_CPU0_SB_CB<4>")
	)
	(segment
		(start 398.399508 -268.960092)
		(end 398.516348 -268.843252)
		(width 0.10668)
		(layer "F.Cu")
		(net "M_G_CPU0_SB_CB<4>")
	)
	(segment
		(start 394.03655 -269.287498)
		(end 394.044932 -269.282672)
		(width 0.0762)
		(layer "F.Cu")
		(net "M_G_CPU0_SB_CB<4>")
	)
	(segment
		(start 398.117314 -268.641068)
		(end 398.117314 -268.843252)
		(width 0.10668)
		(layer "F.Cu")
		(net "M_G_CPU0_SB_CB<4>")
	)
	(segment
		(start 398.516348 -268.843252)
		(end 398.516348 -268.641068)
		(width 0.10668)
		(layer "F.Cu")
		(net "M_G_CPU0_SB_CB<4>")
	)
	(arc
		(start 393.755626 -269.136368)
		(mid 393.785255 -269.278855)
		(end 393.922504 -269.327376)
		(width 0.0762)
		(layer "F.Cu")
		(net "M_G_CPU0_SB_CB<4>")
	)
	(arc
		(start 393.922504 -269.327376)
		(mid 393.98115 -269.312083)
		(end 394.03655 -269.287498)
		(width 0.0762)
		(layer "F.Cu")
		(net "M_G_CPU0_SB_CB<4>")
	)
	(arc
		(start 394.044932 -269.282672)
		(mid 394.158656 -269.232371)
		(end 394.280644 -269.20825)
		(width 0.0762)
		(layer "F.Cu")
		(net "M_G_CPU0_SB_CB<4>")
	)
	(arc
		(start 394.280644 -269.20825)
		(mid 394.304121 -269.206874)
		(end 394.327634 -269.206472)
		(width 0.0762)
		(layer "F.Cu")
		(net "M_G_CPU0_SB_CB<4>")
	)
	(segment
		(start 396.124684 -273.148044)
		(end 396.338552 -273.361912)
		(width 0.10668)
		(layer "F.Cu")
		(net "M_G_CPU0_SB_CB<3>")
	)
	(segment
		(start 397.321786 -273.361912)
		(end 397.535654 -273.148044)
		(width 0.10668)
		(layer "F.Cu")
		(net "M_G_CPU0_SB_CB<3>")
	)
	(segment
		(start 396.922752 -273.148044)
		(end 397.13662 -273.361912)
		(width 0.10668)
		(layer "F.Cu")
		(net "M_G_CPU0_SB_CB<3>")
	)
	(segment
		(start 398.518888 -273.148044)
		(end 398.732756 -273.361912)
		(width 0.10668)
		(layer "F.Cu")
		(net "M_G_CPU0_SB_CB<3>")
	)
	(segment
		(start 403.951948 -273.148044)
		(end 404.158196 -273.354292)
		(width 0.10668)
		(layer "F.Cu")
		(net "M_G_CPU0_SB_CB<3>")
	)
	(segment
		(start 404.126192 -274.116038)
		(end 404.44039 -273.801586)
		(width 0.10668)
		(layer "F.Cu")
		(net "M_G_CPU0_SB_CB<3>")
	)
	(segment
		(start 404.722584 -273.91868)
		(end 404.722584 -274.08378)
		(width 0.10668)
		(layer "F.Cu")
		(net "M_G_CPU0_SB_CB<3>")
	)
	(segment
		(start 404.722584 -274.08378)
		(end 404.408386 -274.398232)
		(width 0.10668)
		(layer "F.Cu")
		(net "M_G_CPU0_SB_CB<3>")
	)
	(segment
		(start 396.523718 -273.361912)
		(end 396.737586 -273.148044)
		(width 0.10668)
		(layer "F.Cu")
		(net "M_G_CPU0_SB_CB<3>")
	)
	(segment
		(start 398.732756 -273.361912)
		(end 398.917922 -273.361912)
		(width 0.10668)
		(layer "F.Cu")
		(net "M_G_CPU0_SB_CB<3>")
	)
	(segment
		(start 402.509228 -273.148044)
		(end 402.723096 -273.361912)
		(width 0.10668)
		(layer "F.Cu")
		(net "M_G_CPU0_SB_CB<3>")
	)
	(segment
		(start 399.530824 -273.361912)
		(end 399.71599 -273.361912)
		(width 0.10668)
		(layer "F.Cu")
		(net "M_G_CPU0_SB_CB<3>")
	)
	(segment
		(start 403.12213 -273.148044)
		(end 403.951948 -273.148044)
		(width 0.10668)
		(layer "F.Cu")
		(net "M_G_CPU0_SB_CB<3>")
	)
	(segment
		(start 400.328892 -273.361912)
		(end 400.514058 -273.361912)
		(width 0.10668)
		(layer "F.Cu")
		(net "M_G_CPU0_SB_CB<3>")
	)
	(segment
		(start 399.929858 -273.148044)
		(end 400.115024 -273.148044)
		(width 0.10668)
		(layer "F.Cu")
		(net "M_G_CPU0_SB_CB<3>")
	)
	(segment
		(start 404.60549 -273.801586)
		(end 404.722584 -273.91868)
		(width 0.10668)
		(layer "F.Cu")
		(net "M_G_CPU0_SB_CB<3>")
	)
	(segment
		(start 404.158196 -273.354292)
		(end 404.158196 -273.519392)
		(width 0.10668)
		(layer "F.Cu")
		(net "M_G_CPU0_SB_CB<3>")
	)
	(segment
		(start 401.525994 -273.148044)
		(end 401.71116 -273.148044)
		(width 0.10668)
		(layer "F.Cu")
		(net "M_G_CPU0_SB_CB<3>")
	)
	(segment
		(start 396.338552 -273.361912)
		(end 396.523718 -273.361912)
		(width 0.10668)
		(layer "F.Cu")
		(net "M_G_CPU0_SB_CB<3>")
	)
	(segment
		(start 395.829028 -273.148044)
		(end 396.124684 -273.148044)
		(width 0.10668)
		(layer "F.Cu")
		(net "M_G_CPU0_SB_CB<3>")
	)
	(segment
		(start 402.723096 -273.361912)
		(end 402.908262 -273.361912)
		(width 0.10668)
		(layer "F.Cu")
		(net "M_G_CPU0_SB_CB<3>")
	)
	(segment
		(start 404.52548 -274.680426)
		(end 404.69058 -274.680426)
		(width 0.10668)
		(layer "F.Cu")
		(net "M_G_CPU0_SB_CB<3>")
	)
	(segment
		(start 396.737586 -273.148044)
		(end 396.922752 -273.148044)
		(width 0.10668)
		(layer "F.Cu")
		(net "M_G_CPU0_SB_CB<3>")
	)
	(segment
		(start 400.913092 -273.148044)
		(end 401.12696 -273.361912)
		(width 0.10668)
		(layer "F.Cu")
		(net "M_G_CPU0_SB_CB<3>")
	)
	(segment
		(start 399.316956 -273.148044)
		(end 399.530824 -273.361912)
		(width 0.10668)
		(layer "F.Cu")
		(net "M_G_CPU0_SB_CB<3>")
	)
	(segment
		(start 394.03655 -273.492722)
		(end 394.044932 -273.497548)
		(width 0.0762)
		(layer "F.Cu")
		(net "M_G_CPU0_SB_CB<3>")
	)
	(segment
		(start 398.917922 -273.361912)
		(end 399.13179 -273.148044)
		(width 0.10668)
		(layer "F.Cu")
		(net "M_G_CPU0_SB_CB<3>")
	)
	(segment
		(start 402.110194 -273.361912)
		(end 402.324062 -273.148044)
		(width 0.10668)
		(layer "F.Cu")
		(net "M_G_CPU0_SB_CB<3>")
	)
	(segment
		(start 404.408386 -274.398232)
		(end 404.408386 -274.563332)
		(width 0.10668)
		(layer "F.Cu")
		(net "M_G_CPU0_SB_CB<3>")
	)
	(segment
		(start 403.961092 -274.116038)
		(end 404.126192 -274.116038)
		(width 0.10668)
		(layer "F.Cu")
		(net "M_G_CPU0_SB_CB<3>")
	)
	(segment
		(start 397.13662 -273.361912)
		(end 397.321786 -273.361912)
		(width 0.10668)
		(layer "F.Cu")
		(net "M_G_CPU0_SB_CB<3>")
	)
	(segment
		(start 400.727926 -273.148044)
		(end 400.913092 -273.148044)
		(width 0.10668)
		(layer "F.Cu")
		(net "M_G_CPU0_SB_CB<3>")
	)
	(segment
		(start 405.004778 -274.365974)
		(end 405.169878 -274.365974)
		(width 0.10668)
		(layer "F.Cu")
		(net "M_G_CPU0_SB_CB<3>")
	)
	(segment
		(start 397.72082 -273.148044)
		(end 397.934688 -273.361912)
		(width 0.10668)
		(layer "F.Cu")
		(net "M_G_CPU0_SB_CB<3>")
	)
	(segment
		(start 401.71116 -273.148044)
		(end 401.925028 -273.361912)
		(width 0.10668)
		(layer "F.Cu")
		(net "M_G_CPU0_SB_CB<3>")
	)
	(segment
		(start 401.312126 -273.361912)
		(end 401.525994 -273.148044)
		(width 0.10668)
		(layer "F.Cu")
		(net "M_G_CPU0_SB_CB<3>")
	)
	(segment
		(start 400.514058 -273.361912)
		(end 400.727926 -273.148044)
		(width 0.10668)
		(layer "F.Cu")
		(net "M_G_CPU0_SB_CB<3>")
	)
	(segment
		(start 395.654784 -273.148044)
		(end 395.829028 -273.148044)
		(width 0.0762)
		(layer "F.Cu")
		(net "M_G_CPU0_SB_CB<3>")
	)
	(segment
		(start 401.12696 -273.361912)
		(end 401.312126 -273.361912)
		(width 0.10668)
		(layer "F.Cu")
		(net "M_G_CPU0_SB_CB<3>")
	)
	(segment
		(start 402.908262 -273.361912)
		(end 403.12213 -273.148044)
		(width 0.10668)
		(layer "F.Cu")
		(net "M_G_CPU0_SB_CB<3>")
	)
	(segment
		(start 404.158196 -273.519392)
		(end 403.843998 -273.833844)
		(width 0.10668)
		(layer "F.Cu")
		(net "M_G_CPU0_SB_CB<3>")
	)
	(segment
		(start 395.201394 -273.601434)
		(end 395.654784 -273.148044)
		(width 0.0762)
		(layer "F.Cu")
		(net "M_G_CPU0_SB_CB<3>")
	)
	(segment
		(start 399.13179 -273.148044)
		(end 399.316956 -273.148044)
		(width 0.10668)
		(layer "F.Cu")
		(net "M_G_CPU0_SB_CB<3>")
	)
	(segment
		(start 403.843998 -273.833844)
		(end 403.843998 -273.998944)
		(width 0.10668)
		(layer "F.Cu")
		(net "M_G_CPU0_SB_CB<3>")
	)
	(segment
		(start 402.324062 -273.148044)
		(end 402.509228 -273.148044)
		(width 0.10668)
		(layer "F.Cu")
		(net "M_G_CPU0_SB_CB<3>")
	)
	(segment
		(start 397.934688 -273.361912)
		(end 398.119854 -273.361912)
		(width 0.10668)
		(layer "F.Cu")
		(net "M_G_CPU0_SB_CB<3>")
	)
	(segment
		(start 401.925028 -273.361912)
		(end 402.110194 -273.361912)
		(width 0.10668)
		(layer "F.Cu")
		(net "M_G_CPU0_SB_CB<3>")
	)
	(segment
		(start 404.44039 -273.801586)
		(end 404.60549 -273.801586)
		(width 0.10668)
		(layer "F.Cu")
		(net "M_G_CPU0_SB_CB<3>")
	)
	(segment
		(start 404.69058 -274.680426)
		(end 405.004778 -274.365974)
		(width 0.10668)
		(layer "F.Cu")
		(net "M_G_CPU0_SB_CB<3>")
	)
	(segment
		(start 397.535654 -273.148044)
		(end 397.72082 -273.148044)
		(width 0.10668)
		(layer "F.Cu")
		(net "M_G_CPU0_SB_CB<3>")
	)
	(segment
		(start 404.408386 -274.563332)
		(end 404.52548 -274.680426)
		(width 0.10668)
		(layer "F.Cu")
		(net "M_G_CPU0_SB_CB<3>")
	)
	(segment
		(start 399.71599 -273.361912)
		(end 399.929858 -273.148044)
		(width 0.10668)
		(layer "F.Cu")
		(net "M_G_CPU0_SB_CB<3>")
	)
	(segment
		(start 400.115024 -273.148044)
		(end 400.328892 -273.361912)
		(width 0.10668)
		(layer "F.Cu")
		(net "M_G_CPU0_SB_CB<3>")
	)
	(segment
		(start 398.119854 -273.361912)
		(end 398.333722 -273.148044)
		(width 0.10668)
		(layer "F.Cu")
		(net "M_G_CPU0_SB_CB<3>")
	)
	(segment
		(start 411.438852 -280.634948)
		(end 412.367984 -280.634948)
		(width 0.10668)
		(layer "F.Cu")
		(net "M_G_CPU0_SB_CB<3>")
	)
	(segment
		(start 403.843998 -273.998944)
		(end 403.961092 -274.116038)
		(width 0.10668)
		(layer "F.Cu")
		(net "M_G_CPU0_SB_CB<3>")
	)
	(segment
		(start 398.333722 -273.148044)
		(end 398.518888 -273.148044)
		(width 0.10668)
		(layer "F.Cu")
		(net "M_G_CPU0_SB_CB<3>")
	)
	(segment
		(start 405.169878 -274.365974)
		(end 411.438852 -280.634948)
		(width 0.10668)
		(layer "F.Cu")
		(net "M_G_CPU0_SB_CB<3>")
	)
	(segment
		(start 394.331698 -273.601434)
		(end 395.201394 -273.601434)
		(width 0.0762)
		(layer "F.Cu")
		(net "M_G_CPU0_SB_CB<3>")
	)
	(arc
		(start 391.97788 -273.820128)
		(mid 392.173229 -273.636309)
		(end 392.434064 -273.573748)
		(width 0.0762)
		(layer "F.Cu")
		(net "M_G_CPU0_SB_CB<3>")
	)
	(arc
		(start 393.104878 -273.497548)
		(mid 393.387834 -273.573725)
		(end 393.67079 -273.497548)
		(width 0.0762)
		(layer "F.Cu")
		(net "M_G_CPU0_SB_CB<3>")
	)
	(arc
		(start 392.73099 -273.497548)
		(mid 392.917934 -273.447293)
		(end 393.104878 -273.497548)
		(width 0.0762)
		(layer "F.Cu")
		(net "M_G_CPU0_SB_CB<3>")
	)
	(arc
		(start 392.434064 -273.573748)
		(mid 392.587813 -273.556239)
		(end 392.73099 -273.497548)
		(width 0.0762)
		(layer "F.Cu")
		(net "M_G_CPU0_SB_CB<3>")
	)
	(arc
		(start 394.256006 -273.590258)
		(mid 394.293432 -273.598697)
		(end 394.331698 -273.601434)
		(width 0.0762)
		(layer "F.Cu")
		(net "M_G_CPU0_SB_CB<3>")
	)
	(arc
		(start 393.67079 -273.497548)
		(mid 393.853041 -273.447198)
		(end 394.03655 -273.492722)
		(width 0.0762)
		(layer "F.Cu")
		(net "M_G_CPU0_SB_CB<3>")
	)
	(arc
		(start 394.044932 -273.497548)
		(mid 394.147826 -273.54992)
		(end 394.256006 -273.590258)
		(width 0.0762)
		(layer "F.Cu")
		(net "M_G_CPU0_SB_CB<3>")
	)
	(segment
		(start 406.68829 -274.544536)
		(end 406.582626 -274.6502)
		(width 0.10668)
		(layer "F.Cu")
		(net "M_G_CPU0_SB_CB<2>")
	)
	(segment
		(start 405.559514 -273.25066)
		(end 405.559514 -273.41576)
		(width 0.10668)
		(layer "F.Cu")
		(net "M_G_CPU0_SB_CB<2>")
	)
	(segment
		(start 405.559514 -273.41576)
		(end 405.45385 -273.521424)
		(width 0.10668)
		(layer "F.Cu")
		(net "M_G_CPU0_SB_CB<2>")
	)
	(segment
		(start 407.252678 -275.108924)
		(end 407.147014 -275.214588)
		(width 0.10668)
		(layer "F.Cu")
		(net "M_G_CPU0_SB_CB<2>")
	)
	(segment
		(start 407.711402 -275.778976)
		(end 407.711402 -275.944076)
		(width 0.10668)
		(layer "F.Cu")
		(net "M_G_CPU0_SB_CB<2>")
	)
	(segment
		(start 405.45385 -273.521424)
		(end 405.45385 -273.686524)
		(width 0.10668)
		(layer "F.Cu")
		(net "M_G_CPU0_SB_CB<2>")
	)
	(segment
		(start 406.68829 -274.379436)
		(end 406.68829 -274.544536)
		(width 0.10668)
		(layer "F.Cu")
		(net "M_G_CPU0_SB_CB<2>")
	)
	(segment
		(start 408.27579 -276.508464)
		(end 408.392884 -276.625558)
		(width 0.10668)
		(layer "F.Cu")
		(net "M_G_CPU0_SB_CB<2>")
	)
	(segment
		(start 407.993596 -276.06117)
		(end 408.09926 -275.955506)
		(width 0.10668)
		(layer "F.Cu")
		(net "M_G_CPU0_SB_CB<2>")
	)
	(segment
		(start 406.135332 -274.368006)
		(end 406.300432 -274.368006)
		(width 0.10668)
		(layer "F.Cu")
		(net "M_G_CPU0_SB_CB<2>")
	)
	(segment
		(start 407.828496 -276.06117)
		(end 407.993596 -276.06117)
		(width 0.10668)
		(layer "F.Cu")
		(net "M_G_CPU0_SB_CB<2>")
	)
	(segment
		(start 410.356812 -278.213058)
		(end 410.521912 -278.213058)
		(width 0.10668)
		(layer "F.Cu")
		(net "M_G_CPU0_SB_CB<2>")
	)
	(segment
		(start 405.44242 -273.133566)
		(end 405.559514 -273.25066)
		(width 0.10668)
		(layer "F.Cu")
		(net "M_G_CPU0_SB_CB<2>")
	)
	(segment
		(start 395.714728 -272.467324)
		(end 404.776178 -272.467324)
		(width 0.10668)
		(layer "F.Cu")
		(net "M_G_CPU0_SB_CB<2>")
	)
	(segment
		(start 404.776178 -272.467324)
		(end 404.995126 -272.686272)
		(width 0.10668)
		(layer "F.Cu")
		(net "M_G_CPU0_SB_CB<2>")
	)
	(segment
		(start 409.957524 -277.64867)
		(end 410.074618 -277.765764)
		(width 0.10668)
		(layer "F.Cu")
		(net "M_G_CPU0_SB_CB<2>")
	)
	(segment
		(start 406.018238 -274.250912)
		(end 406.135332 -274.368006)
		(width 0.10668)
		(layer "F.Cu")
		(net "M_G_CPU0_SB_CB<2>")
	)
	(segment
		(start 409.404566 -277.63724)
		(end 409.52166 -277.754334)
		(width 0.10668)
		(layer "F.Cu")
		(net "M_G_CPU0_SB_CB<2>")
	)
	(segment
		(start 409.968954 -278.201628)
		(end 410.086048 -278.318722)
		(width 0.10668)
		(layer "F.Cu")
		(net "M_G_CPU0_SB_CB<2>")
	)
	(segment
		(start 409.968954 -278.036528)
		(end 409.968954 -278.201628)
		(width 0.10668)
		(layer "F.Cu")
		(net "M_G_CPU0_SB_CB<2>")
	)
	(segment
		(start 410.639006 -278.495252)
		(end 410.533342 -278.600916)
		(width 0.10668)
		(layer "F.Cu")
		(net "M_G_CPU0_SB_CB<2>")
	)
	(segment
		(start 405.570944 -273.803618)
		(end 405.736044 -273.803618)
		(width 0.10668)
		(layer "F.Cu")
		(net "M_G_CPU0_SB_CB<2>")
	)
	(segment
		(start 406.300432 -274.368006)
		(end 406.406096 -274.262342)
		(width 0.10668)
		(layer "F.Cu")
		(net "M_G_CPU0_SB_CB<2>")
	)
	(segment
		(start 406.123902 -273.980148)
		(end 406.018238 -274.085812)
		(width 0.10668)
		(layer "F.Cu")
		(net "M_G_CPU0_SB_CB<2>")
	)
	(segment
		(start 409.51023 -277.201376)
		(end 409.51023 -277.366476)
		(width 0.10668)
		(layer "F.Cu")
		(net "M_G_CPU0_SB_CB<2>")
	)
	(segment
		(start 408.957272 -277.189946)
		(end 409.122372 -277.189946)
		(width 0.10668)
		(layer "F.Cu")
		(net "M_G_CPU0_SB_CB<2>")
	)
	(segment
		(start 407.711402 -275.944076)
		(end 407.828496 -276.06117)
		(width 0.10668)
		(layer "F.Cu")
		(net "M_G_CPU0_SB_CB<2>")
	)
	(segment
		(start 405.171656 -273.23923)
		(end 405.27732 -273.133566)
		(width 0.10668)
		(layer "F.Cu")
		(net "M_G_CPU0_SB_CB<2>")
	)
	(segment
		(start 410.815536 -278.88311)
		(end 410.9212 -278.777446)
		(width 0.10668)
		(layer "F.Cu")
		(net "M_G_CPU0_SB_CB<2>")
	)
	(segment
		(start 394.327888 -272.636996)
		(end 395.234922 -272.636996)
		(width 0.0762)
		(layer "F.Cu")
		(net "M_G_CPU0_SB_CB<2>")
	)
	(segment
		(start 410.086048 -278.318722)
		(end 410.251148 -278.318722)
		(width 0.10668)
		(layer "F.Cu")
		(net "M_G_CPU0_SB_CB<2>")
	)
	(segment
		(start 409.792424 -277.64867)
		(end 409.957524 -277.64867)
		(width 0.10668)
		(layer "F.Cu")
		(net "M_G_CPU0_SB_CB<2>")
	)
	(segment
		(start 408.381454 -276.2377)
		(end 408.27579 -276.343364)
		(width 0.10668)
		(layer "F.Cu")
		(net "M_G_CPU0_SB_CB<2>")
	)
	(segment
		(start 408.09926 -275.955506)
		(end 408.26436 -275.955506)
		(width 0.10668)
		(layer "F.Cu")
		(net "M_G_CPU0_SB_CB<2>")
	)
	(segment
		(start 409.68676 -277.754334)
		(end 409.792424 -277.64867)
		(width 0.10668)
		(layer "F.Cu")
		(net "M_G_CPU0_SB_CB<2>")
	)
	(segment
		(start 408.945842 -276.636988)
		(end 408.945842 -276.802088)
		(width 0.10668)
		(layer "F.Cu")
		(net "M_G_CPU0_SB_CB<2>")
	)
	(segment
		(start 406.582626 -274.6502)
		(end 406.582626 -274.8153)
		(width 0.10668)
		(layer "F.Cu")
		(net "M_G_CPU0_SB_CB<2>")
	)
	(segment
		(start 410.074618 -277.765764)
		(end 410.074618 -277.930864)
		(width 0.10668)
		(layer "F.Cu")
		(net "M_G_CPU0_SB_CB<2>")
	)
	(segment
		(start 407.699972 -275.391118)
		(end 407.817066 -275.508212)
		(width 0.10668)
		(layer "F.Cu")
		(net "M_G_CPU0_SB_CB<2>")
	)
	(segment
		(start 406.571196 -274.262342)
		(end 406.68829 -274.379436)
		(width 0.10668)
		(layer "F.Cu")
		(net "M_G_CPU0_SB_CB<2>")
	)
	(segment
		(start 406.006808 -273.697954)
		(end 406.123902 -273.815048)
		(width 0.10668)
		(layer "F.Cu")
		(net "M_G_CPU0_SB_CB<2>")
	)
	(segment
		(start 410.639006 -278.330152)
		(end 410.639006 -278.495252)
		(width 0.10668)
		(layer "F.Cu")
		(net "M_G_CPU0_SB_CB<2>")
	)
	(segment
		(start 409.51023 -277.366476)
		(end 409.404566 -277.47214)
		(width 0.10668)
		(layer "F.Cu")
		(net "M_G_CPU0_SB_CB<2>")
	)
	(segment
		(start 406.123902 -273.815048)
		(end 406.123902 -273.980148)
		(width 0.10668)
		(layer "F.Cu")
		(net "M_G_CPU0_SB_CB<2>")
	)
	(segment
		(start 408.840178 -276.907752)
		(end 408.840178 -277.072852)
		(width 0.10668)
		(layer "F.Cu")
		(net "M_G_CPU0_SB_CB<2>")
	)
	(segment
		(start 407.429208 -275.496782)
		(end 407.534872 -275.391118)
		(width 0.10668)
		(layer "F.Cu")
		(net "M_G_CPU0_SB_CB<2>")
	)
	(segment
		(start 406.406096 -274.262342)
		(end 406.571196 -274.262342)
		(width 0.10668)
		(layer "F.Cu")
		(net "M_G_CPU0_SB_CB<2>")
	)
	(segment
		(start 408.392884 -276.625558)
		(end 408.557984 -276.625558)
		(width 0.10668)
		(layer "F.Cu")
		(net "M_G_CPU0_SB_CB<2>")
	)
	(segment
		(start 405.27732 -273.133566)
		(end 405.44242 -273.133566)
		(width 0.10668)
		(layer "F.Cu")
		(net "M_G_CPU0_SB_CB<2>")
	)
	(segment
		(start 410.521912 -278.213058)
		(end 410.639006 -278.330152)
		(width 0.10668)
		(layer "F.Cu")
		(net "M_G_CPU0_SB_CB<2>")
	)
	(segment
		(start 407.534872 -275.391118)
		(end 407.699972 -275.391118)
		(width 0.10668)
		(layer "F.Cu")
		(net "M_G_CPU0_SB_CB<2>")
	)
	(segment
		(start 408.557984 -276.625558)
		(end 408.663648 -276.519894)
		(width 0.10668)
		(layer "F.Cu")
		(net "M_G_CPU0_SB_CB<2>")
	)
	(segment
		(start 406.69972 -274.932394)
		(end 406.86482 -274.932394)
		(width 0.10668)
		(layer "F.Cu")
		(net "M_G_CPU0_SB_CB<2>")
	)
	(segment
		(start 407.252678 -274.943824)
		(end 407.252678 -275.108924)
		(width 0.10668)
		(layer "F.Cu")
		(net "M_G_CPU0_SB_CB<2>")
	)
	(segment
		(start 409.404566 -277.47214)
		(end 409.404566 -277.63724)
		(width 0.10668)
		(layer "F.Cu")
		(net "M_G_CPU0_SB_CB<2>")
	)
	(segment
		(start 409.122372 -277.189946)
		(end 409.228036 -277.084282)
		(width 0.10668)
		(layer "F.Cu")
		(net "M_G_CPU0_SB_CB<2>")
	)
	(segment
		(start 406.970484 -274.82673)
		(end 407.135584 -274.82673)
		(width 0.10668)
		(layer "F.Cu")
		(net "M_G_CPU0_SB_CB<2>")
	)
	(segment
		(start 395.404594 -272.467324)
		(end 395.714728 -272.467324)
		(width 0.0762)
		(layer "F.Cu")
		(net "M_G_CPU0_SB_CB<2>")
	)
	(segment
		(start 405.006556 -273.23923)
		(end 405.171656 -273.23923)
		(width 0.10668)
		(layer "F.Cu")
		(net "M_G_CPU0_SB_CB<2>")
	)
	(segment
		(start 404.889462 -273.122136)
		(end 405.006556 -273.23923)
		(width 0.10668)
		(layer "F.Cu")
		(net "M_G_CPU0_SB_CB<2>")
	)
	(segment
		(start 410.074618 -277.930864)
		(end 409.968954 -278.036528)
		(width 0.10668)
		(layer "F.Cu")
		(net "M_G_CPU0_SB_CB<2>")
	)
	(segment
		(start 404.995126 -272.851372)
		(end 404.889462 -272.957036)
		(width 0.10668)
		(layer "F.Cu")
		(net "M_G_CPU0_SB_CB<2>")
	)
	(segment
		(start 407.817066 -275.673312)
		(end 407.711402 -275.778976)
		(width 0.10668)
		(layer "F.Cu")
		(net "M_G_CPU0_SB_CB<2>")
	)
	(segment
		(start 408.663648 -276.519894)
		(end 408.828748 -276.519894)
		(width 0.10668)
		(layer "F.Cu")
		(net "M_G_CPU0_SB_CB<2>")
	)
	(segment
		(start 408.840178 -277.072852)
		(end 408.957272 -277.189946)
		(width 0.10668)
		(layer "F.Cu")
		(net "M_G_CPU0_SB_CB<2>")
	)
	(segment
		(start 411.244034 -278.93518)
		(end 412.367984 -278.93518)
		(width 0.10668)
		(layer "F.Cu")
		(net "M_G_CPU0_SB_CB<2>")
	)
	(segment
		(start 409.52166 -277.754334)
		(end 409.68676 -277.754334)
		(width 0.10668)
		(layer "F.Cu")
		(net "M_G_CPU0_SB_CB<2>")
	)
	(segment
		(start 406.86482 -274.932394)
		(end 406.970484 -274.82673)
		(width 0.10668)
		(layer "F.Cu")
		(net "M_G_CPU0_SB_CB<2>")
	)
	(segment
		(start 407.817066 -275.508212)
		(end 407.817066 -275.673312)
		(width 0.10668)
		(layer "F.Cu")
		(net "M_G_CPU0_SB_CB<2>")
	)
	(segment
		(start 395.234922 -272.636996)
		(end 395.404594 -272.467324)
		(width 0.0762)
		(layer "F.Cu")
		(net "M_G_CPU0_SB_CB<2>")
	)
	(segment
		(start 409.228036 -277.084282)
		(end 409.393136 -277.084282)
		(width 0.10668)
		(layer "F.Cu")
		(net "M_G_CPU0_SB_CB<2>")
	)
	(segment
		(start 410.533342 -278.600916)
		(end 410.533342 -278.766016)
		(width 0.10668)
		(layer "F.Cu")
		(net "M_G_CPU0_SB_CB<2>")
	)
	(segment
		(start 407.147014 -275.379688)
		(end 407.264108 -275.496782)
		(width 0.10668)
		(layer "F.Cu")
		(net "M_G_CPU0_SB_CB<2>")
	)
	(segment
		(start 407.264108 -275.496782)
		(end 407.429208 -275.496782)
		(width 0.10668)
		(layer "F.Cu")
		(net "M_G_CPU0_SB_CB<2>")
	)
	(segment
		(start 408.828748 -276.519894)
		(end 408.945842 -276.636988)
		(width 0.10668)
		(layer "F.Cu")
		(net "M_G_CPU0_SB_CB<2>")
	)
	(segment
		(start 406.018238 -274.085812)
		(end 406.018238 -274.250912)
		(width 0.10668)
		(layer "F.Cu")
		(net "M_G_CPU0_SB_CB<2>")
	)
	(segment
		(start 409.393136 -277.084282)
		(end 409.51023 -277.201376)
		(width 0.10668)
		(layer "F.Cu")
		(net "M_G_CPU0_SB_CB<2>")
	)
	(segment
		(start 406.582626 -274.8153)
		(end 406.69972 -274.932394)
		(width 0.10668)
		(layer "F.Cu")
		(net "M_G_CPU0_SB_CB<2>")
	)
	(segment
		(start 405.841708 -273.697954)
		(end 406.006808 -273.697954)
		(width 0.10668)
		(layer "F.Cu")
		(net "M_G_CPU0_SB_CB<2>")
	)
	(segment
		(start 408.945842 -276.802088)
		(end 408.840178 -276.907752)
		(width 0.10668)
		(layer "F.Cu")
		(net "M_G_CPU0_SB_CB<2>")
	)
	(segment
		(start 404.889462 -272.957036)
		(end 404.889462 -273.122136)
		(width 0.10668)
		(layer "F.Cu")
		(net "M_G_CPU0_SB_CB<2>")
	)
	(segment
		(start 407.135584 -274.82673)
		(end 407.252678 -274.943824)
		(width 0.10668)
		(layer "F.Cu")
		(net "M_G_CPU0_SB_CB<2>")
	)
	(segment
		(start 408.27579 -276.343364)
		(end 408.27579 -276.508464)
		(width 0.10668)
		(layer "F.Cu")
		(net "M_G_CPU0_SB_CB<2>")
	)
	(segment
		(start 408.381454 -276.0726)
		(end 408.381454 -276.2377)
		(width 0.10668)
		(layer "F.Cu")
		(net "M_G_CPU0_SB_CB<2>")
	)
	(segment
		(start 410.251148 -278.318722)
		(end 410.356812 -278.213058)
		(width 0.10668)
		(layer "F.Cu")
		(net "M_G_CPU0_SB_CB<2>")
	)
	(segment
		(start 411.0863 -278.777446)
		(end 411.244034 -278.93518)
		(width 0.10668)
		(layer "F.Cu")
		(net "M_G_CPU0_SB_CB<2>")
	)
	(segment
		(start 408.26436 -275.955506)
		(end 408.381454 -276.0726)
		(width 0.10668)
		(layer "F.Cu")
		(net "M_G_CPU0_SB_CB<2>")
	)
	(segment
		(start 404.995126 -272.686272)
		(end 404.995126 -272.851372)
		(width 0.10668)
		(layer "F.Cu")
		(net "M_G_CPU0_SB_CB<2>")
	)
	(segment
		(start 410.533342 -278.766016)
		(end 410.650436 -278.88311)
		(width 0.10668)
		(layer "F.Cu")
		(net "M_G_CPU0_SB_CB<2>")
	)
	(segment
		(start 407.147014 -275.214588)
		(end 407.147014 -275.379688)
		(width 0.10668)
		(layer "F.Cu")
		(net "M_G_CPU0_SB_CB<2>")
	)
	(segment
		(start 405.736044 -273.803618)
		(end 405.841708 -273.697954)
		(width 0.10668)
		(layer "F.Cu")
		(net "M_G_CPU0_SB_CB<2>")
	)
	(segment
		(start 410.650436 -278.88311)
		(end 410.815536 -278.88311)
		(width 0.10668)
		(layer "F.Cu")
		(net "M_G_CPU0_SB_CB<2>")
	)
	(segment
		(start 410.9212 -278.777446)
		(end 411.0863 -278.777446)
		(width 0.10668)
		(layer "F.Cu")
		(net "M_G_CPU0_SB_CB<2>")
	)
	(segment
		(start 405.45385 -273.686524)
		(end 405.570944 -273.803618)
		(width 0.10668)
		(layer "F.Cu")
		(net "M_G_CPU0_SB_CB<2>")
	)
	(arc
		(start 393.916916 -272.760694)
		(mid 393.936265 -272.758356)
		(end 393.955524 -272.75536)
		(width 0.0762)
		(layer "F.Cu")
		(net "M_G_CPU0_SB_CB<2>")
	)
	(arc
		(start 394.140944 -272.687542)
		(mid 394.216184 -272.654229)
		(end 394.2969 -272.638266)
		(width 0.0762)
		(layer "F.Cu")
		(net "M_G_CPU0_SB_CB<2>")
	)
	(arc
		(start 393.387834 -273.010122)
		(mid 393.631265 -272.840635)
		(end 393.916916 -272.760694)
		(width 0.0762)
		(layer "F.Cu")
		(net "M_G_CPU0_SB_CB<2>")
	)
	(arc
		(start 393.955524 -272.75536)
		(mid 394.051233 -272.729648)
		(end 394.140944 -272.687542)
		(width 0.0762)
		(layer "F.Cu")
		(net "M_G_CPU0_SB_CB<2>")
	)
	(arc
		(start 394.2969 -272.638266)
		(mid 394.312381 -272.63731)
		(end 394.327888 -272.636996)
		(width 0.0762)
		(layer "F.Cu")
		(net "M_G_CPU0_SB_CB<2>")
	)
	(segment
		(start 413.507174 -279.360122)
		(end 415.643568 -279.785064)
		(width 0.101346)
		(layer "F.Cu")
		(net "M_G_CPU0_SB_CB<1>")
	)
	(segment
		(start 392.448034 -273.010122)
		(end 392.339576 -273.196812)
		(width 0.0762)
		(layer "F.Cu")
		(net "M_G_CPU0_SB_CB<1>")
	)
	(segment
		(start 395.811756 -272.807684)
		(end 404.093172 -272.807684)
		(width 0.10668)
		(layer "F.Cu")
		(net "M_G_CPU0_SB_CB<1>")
	)
	(segment
		(start 395.107414 -273.392138)
		(end 395.691868 -272.807684)
		(width 0.0762)
		(layer "F.Cu")
		(net "M_G_CPU0_SB_CB<1>")
	)
	(segment
		(start 393.20089 -273.332702)
		(end 393.201144 -273.332702)
		(width 0.0762)
		(layer "F.Cu")
		(net "M_G_CPU0_SB_CB<1>")
	)
	(segment
		(start 395.691868 -272.807684)
		(end 395.811756 -272.807684)
		(width 0.0762)
		(layer "F.Cu")
		(net "M_G_CPU0_SB_CB<1>")
	)
	(segment
		(start 394.298424 -273.390868)
		(end 395.107414 -273.392138)
		(width 0.0762)
		(layer "F.Cu")
		(net "M_G_CPU0_SB_CB<1>")
	)
	(segment
		(start 411.317694 -279.360122)
		(end 413.507174 -279.360122)
		(width 0.101346)
		(layer "F.Cu")
		(net "M_G_CPU0_SB_CB<1>")
	)
	(segment
		(start 404.093172 -272.807684)
		(end 410.64561 -279.360122)
		(width 0.10668)
		(layer "F.Cu")
		(net "M_G_CPU0_SB_CB<1>")
	)
	(segment
		(start 392.626596 -273.337528)
		(end 392.634978 -273.332702)
		(width 0.0762)
		(layer "F.Cu")
		(net "M_G_CPU0_SB_CB<1>")
	)
	(segment
		(start 415.643568 -279.785064)
		(end 416.468052 -279.785064)
		(width 0.101346)
		(layer "F.Cu")
		(net "M_G_CPU0_SB_CB<1>")
	)
	(segment
		(start 410.64561 -279.360122)
		(end 411.317694 -279.360122)
		(width 0.10668)
		(layer "F.Cu")
		(net "M_G_CPU0_SB_CB<1>")
	)
	(arc
		(start 392.634978 -273.332702)
		(mid 392.917934 -273.256525)
		(end 393.20089 -273.332702)
		(width 0.0762)
		(layer "F.Cu")
		(net "M_G_CPU0_SB_CB<1>")
	)
	(arc
		(start 392.491214 -273.380454)
		(mid 392.560968 -273.365497)
		(end 392.626596 -273.337528)
		(width 0.0762)
		(layer "F.Cu")
		(net "M_G_CPU0_SB_CB<1>")
	)
	(arc
		(start 392.339576 -273.196812)
		(mid 392.365493 -273.329854)
		(end 392.491214 -273.380454)
		(width 0.0762)
		(layer "F.Cu")
		(net "M_G_CPU0_SB_CB<1>")
	)
	(arc
		(start 394.140944 -273.332702)
		(mid 394.181638 -273.354921)
		(end 394.223494 -273.374866)
		(width 0.0762)
		(layer "F.Cu")
		(net "M_G_CPU0_SB_CB<1>")
	)
	(arc
		(start 394.223494 -273.374866)
		(mid 394.260122 -273.386796)
		(end 394.298424 -273.390868)
		(width 0.0762)
		(layer "F.Cu")
		(net "M_G_CPU0_SB_CB<1>")
	)
	(arc
		(start 393.575032 -273.332702)
		(mid 393.857988 -273.256525)
		(end 394.140944 -273.332702)
		(width 0.0762)
		(layer "F.Cu")
		(net "M_G_CPU0_SB_CB<1>")
	)
	(arc
		(start 393.201144 -273.332702)
		(mid 393.388088 -273.383026)
		(end 393.575032 -273.332702)
		(width 0.0762)
		(layer "F.Cu")
		(net "M_G_CPU0_SB_CB<1>")
	)
	(segment
		(start 415.073338 -278.993092)
		(end 415.188654 -278.877776)
		(width 0.101346)
		(layer "F.Cu")
		(net "M_G_CPU0_SB_CB<0>")
	)
	(segment
		(start 413.929322 -277.6601)
		(end 414.354264 -278.085042)
		(width 0.101346)
		(layer "F.Cu")
		(net "M_G_CPU0_SB_CB<0>")
	)
	(segment
		(start 395.456156 -272.126964)
		(end 395.77137 -272.126964)
		(width 0.0762)
		(layer "F.Cu")
		(net "M_G_CPU0_SB_CB<0>")
	)
	(segment
		(start 414.794954 -278.877776)
		(end 414.91027 -278.993092)
		(width 0.101346)
		(layer "F.Cu")
		(net "M_G_CPU0_SB_CB<0>")
	)
	(segment
		(start 395.77137 -272.126964)
		(end 404.917656 -272.126964)
		(width 0.10668)
		(layer "F.Cu")
		(net "M_G_CPU0_SB_CB<0>")
	)
	(segment
		(start 394.327634 -272.446496)
		(end 395.136624 -272.446496)
		(width 0.0762)
		(layer "F.Cu")
		(net "M_G_CPU0_SB_CB<0>")
	)
	(segment
		(start 393.857988 -272.200116)
		(end 393.755626 -272.376392)
		(width 0.0762)
		(layer "F.Cu")
		(net "M_G_CPU0_SB_CB<0>")
	)
	(segment
		(start 415.188654 -278.200358)
		(end 415.30397 -278.085042)
		(width 0.101346)
		(layer "F.Cu")
		(net "M_G_CPU0_SB_CB<0>")
	)
	(segment
		(start 410.450792 -277.6601)
		(end 411.317694 -277.6601)
		(width 0.10668)
		(layer "F.Cu")
		(net "M_G_CPU0_SB_CB<0>")
	)
	(segment
		(start 414.354264 -278.085042)
		(end 414.679638 -278.085042)
		(width 0.101346)
		(layer "F.Cu")
		(net "M_G_CPU0_SB_CB<0>")
	)
	(segment
		(start 404.917656 -272.126964)
		(end 410.450792 -277.6601)
		(width 0.10668)
		(layer "F.Cu")
		(net "M_G_CPU0_SB_CB<0>")
	)
	(segment
		(start 414.91027 -278.993092)
		(end 415.073338 -278.993092)
		(width 0.101346)
		(layer "F.Cu")
		(net "M_G_CPU0_SB_CB<0>")
	)
	(segment
		(start 414.679638 -278.085042)
		(end 414.794954 -278.200358)
		(width 0.101346)
		(layer "F.Cu")
		(net "M_G_CPU0_SB_CB<0>")
	)
	(segment
		(start 415.188654 -278.877776)
		(end 415.188654 -278.200358)
		(width 0.101346)
		(layer "F.Cu")
		(net "M_G_CPU0_SB_CB<0>")
	)
	(segment
		(start 395.136624 -272.446496)
		(end 395.456156 -272.126964)
		(width 0.0762)
		(layer "F.Cu")
		(net "M_G_CPU0_SB_CB<0>")
	)
	(segment
		(start 411.317694 -277.6601)
		(end 413.929322 -277.6601)
		(width 0.101346)
		(layer "F.Cu")
		(net "M_G_CPU0_SB_CB<0>")
	)
	(segment
		(start 414.794954 -278.200358)
		(end 414.794954 -278.877776)
		(width 0.101346)
		(layer "F.Cu")
		(net "M_G_CPU0_SB_CB<0>")
	)
	(segment
		(start 415.30397 -278.085042)
		(end 416.468052 -278.085042)
		(width 0.101346)
		(layer "F.Cu")
		(net "M_G_CPU0_SB_CB<0>")
	)
	(segment
		(start 394.03655 -272.527522)
		(end 394.044932 -272.522696)
		(width 0.0762)
		(layer "F.Cu")
		(net "M_G_CPU0_SB_CB<0>")
	)
	(arc
		(start 393.755626 -272.376392)
		(mid 393.785255 -272.518879)
		(end 393.922504 -272.5674)
		(width 0.0762)
		(layer "F.Cu")
		(net "M_G_CPU0_SB_CB<0>")
	)
	(arc
		(start 394.280644 -272.448274)
		(mid 394.304121 -272.446898)
		(end 394.327634 -272.446496)
		(width 0.0762)
		(layer "F.Cu")
		(net "M_G_CPU0_SB_CB<0>")
	)
	(arc
		(start 393.922504 -272.5674)
		(mid 393.98115 -272.552107)
		(end 394.03655 -272.527522)
		(width 0.0762)
		(layer "F.Cu")
		(net "M_G_CPU0_SB_CB<0>")
	)
	(arc
		(start 394.044932 -272.522696)
		(mid 394.158656 -272.472395)
		(end 394.280644 -272.448274)
		(width 0.0762)
		(layer "F.Cu")
		(net "M_G_CPU0_SB_CB<0>")
	)
	(segment
		(start 410.910024 -265.7602)
		(end 411.317694 -265.7602)
		(width 0.10668)
		(layer "F.Cu")
		(net "M_G_CPU0_SB_CA<6>")
	)
	(segment
		(start 415.087562 -265.7602)
		(end 415.512504 -266.185142)
		(width 0.101346)
		(layer "F.Cu")
		(net "M_G_CPU0_SB_CA<6>")
	)
	(segment
		(start 395.852396 -264.1854)
		(end 397.792194 -264.1854)
		(width 0.10668)
		(layer "F.Cu")
		(net "M_G_CPU0_SB_CA<6>")
	)
	(segment
		(start 395.226032 -264.346436)
		(end 395.387068 -264.1854)
		(width 0.0762)
		(layer "F.Cu")
		(net "M_G_CPU0_SB_CA<6>")
	)
	(segment
		(start 395.387068 -264.1854)
		(end 395.852396 -264.1854)
		(width 0.0762)
		(layer "F.Cu")
		(net "M_G_CPU0_SB_CA<6>")
	)
	(segment
		(start 399.174462 -265.567668)
		(end 404.934928 -265.567668)
		(width 0.10668)
		(layer "F.Cu")
		(net "M_G_CPU0_SB_CA<6>")
	)
	(segment
		(start 397.792194 -264.1854)
		(end 399.174462 -265.567668)
		(width 0.10668)
		(layer "F.Cu")
		(net "M_G_CPU0_SB_CA<6>")
	)
	(segment
		(start 393.857988 -264.100056)
		(end 393.755626 -264.276332)
		(width 0.0762)
		(layer "F.Cu")
		(net "M_G_CPU0_SB_CA<6>")
	)
	(segment
		(start 404.934928 -265.567668)
		(end 405.922226 -264.58037)
		(width 0.10668)
		(layer "F.Cu")
		(net "M_G_CPU0_SB_CA<6>")
	)
	(segment
		(start 409.730194 -264.58037)
		(end 410.910024 -265.7602)
		(width 0.10668)
		(layer "F.Cu")
		(net "M_G_CPU0_SB_CA<6>")
	)
	(segment
		(start 411.317694 -265.7602)
		(end 415.087562 -265.7602)
		(width 0.101346)
		(layer "F.Cu")
		(net "M_G_CPU0_SB_CA<6>")
	)
	(segment
		(start 394.03655 -264.427462)
		(end 394.044932 -264.422636)
		(width 0.0762)
		(layer "F.Cu")
		(net "M_G_CPU0_SB_CA<6>")
	)
	(segment
		(start 394.327634 -264.346436)
		(end 395.226032 -264.346436)
		(width 0.0762)
		(layer "F.Cu")
		(net "M_G_CPU0_SB_CA<6>")
	)
	(segment
		(start 405.922226 -264.58037)
		(end 409.730194 -264.58037)
		(width 0.10668)
		(layer "F.Cu")
		(net "M_G_CPU0_SB_CA<6>")
	)
	(segment
		(start 415.512504 -266.185142)
		(end 416.468052 -266.185142)
		(width 0.101346)
		(layer "F.Cu")
		(net "M_G_CPU0_SB_CA<6>")
	)
	(arc
		(start 394.280644 -264.348214)
		(mid 394.304121 -264.346838)
		(end 394.327634 -264.346436)
		(width 0.0762)
		(layer "F.Cu")
		(net "M_G_CPU0_SB_CA<6>")
	)
	(arc
		(start 393.922504 -264.46734)
		(mid 393.98115 -264.452047)
		(end 394.03655 -264.427462)
		(width 0.0762)
		(layer "F.Cu")
		(net "M_G_CPU0_SB_CA<6>")
	)
	(arc
		(start 393.755626 -264.276332)
		(mid 393.785255 -264.418819)
		(end 393.922504 -264.46734)
		(width 0.0762)
		(layer "F.Cu")
		(net "M_G_CPU0_SB_CA<6>")
	)
	(arc
		(start 394.044932 -264.422636)
		(mid 394.158656 -264.372335)
		(end 394.280644 -264.348214)
		(width 0.0762)
		(layer "F.Cu")
		(net "M_G_CPU0_SB_CA<6>")
	)
	(segment
		(start 409.897072 -263.802114)
		(end 411.429962 -265.335004)
		(width 0.10668)
		(layer "F.Cu")
		(net "M_G_CPU0_SB_CA<5>")
	)
	(segment
		(start 407.513536 -264.24001)
		(end 407.67889 -264.24001)
		(width 0.10668)
		(layer "F.Cu")
		(net "M_G_CPU0_SB_CA<5>")
	)
	(segment
		(start 407.396696 -263.918954)
		(end 407.396696 -264.12317)
		(width 0.10668)
		(layer "F.Cu")
		(net "M_G_CPU0_SB_CA<5>")
	)
	(segment
		(start 404.793704 -265.227308)
		(end 406.218898 -263.802114)
		(width 0.10668)
		(layer "F.Cu")
		(net "M_G_CPU0_SB_CA<5>")
	)
	(segment
		(start 411.429962 -265.335004)
		(end 412.367984 -265.335004)
		(width 0.10668)
		(layer "F.Cu")
		(net "M_G_CPU0_SB_CA<5>")
	)
	(segment
		(start 408.593798 -263.918954)
		(end 408.710638 -263.802114)
		(width 0.10668)
		(layer "F.Cu")
		(net "M_G_CPU0_SB_CA<5>")
	)
	(segment
		(start 407.279856 -263.802114)
		(end 407.396696 -263.918954)
		(width 0.10668)
		(layer "F.Cu")
		(net "M_G_CPU0_SB_CA<5>")
	)
	(segment
		(start 406.880822 -264.24001)
		(end 406.997662 -264.12317)
		(width 0.10668)
		(layer "F.Cu")
		(net "M_G_CPU0_SB_CA<5>")
	)
	(segment
		(start 408.593798 -264.12317)
		(end 408.593798 -263.918954)
		(width 0.10668)
		(layer "F.Cu")
		(net "M_G_CPU0_SB_CA<5>")
	)
	(segment
		(start 408.311604 -264.24001)
		(end 408.476958 -264.24001)
		(width 0.10668)
		(layer "F.Cu")
		(net "M_G_CPU0_SB_CA<5>")
	)
	(segment
		(start 408.077924 -263.802114)
		(end 408.194764 -263.918954)
		(width 0.10668)
		(layer "F.Cu")
		(net "M_G_CPU0_SB_CA<5>")
	)
	(segment
		(start 406.997662 -263.918954)
		(end 407.114502 -263.802114)
		(width 0.10668)
		(layer "F.Cu")
		(net "M_G_CPU0_SB_CA<5>")
	)
	(segment
		(start 395.279118 -263.881362)
		(end 395.31544 -263.84504)
		(width 0.0762)
		(layer "F.Cu")
		(net "M_G_CPU0_SB_CA<5>")
	)
	(segment
		(start 407.67889 -264.24001)
		(end 407.79573 -264.12317)
		(width 0.10668)
		(layer "F.Cu")
		(net "M_G_CPU0_SB_CA<5>")
	)
	(segment
		(start 407.396696 -264.12317)
		(end 407.513536 -264.24001)
		(width 0.10668)
		(layer "F.Cu")
		(net "M_G_CPU0_SB_CA<5>")
	)
	(segment
		(start 397.933672 -263.84504)
		(end 399.31594 -265.227308)
		(width 0.10668)
		(layer "F.Cu")
		(net "M_G_CPU0_SB_CA<5>")
	)
	(segment
		(start 395.31544 -263.84504)
		(end 395.813026 -263.84504)
		(width 0.0762)
		(layer "F.Cu")
		(net "M_G_CPU0_SB_CA<5>")
	)
	(segment
		(start 406.598628 -263.918954)
		(end 406.598628 -264.12317)
		(width 0.10668)
		(layer "F.Cu")
		(net "M_G_CPU0_SB_CA<5>")
	)
	(segment
		(start 407.79573 -264.12317)
		(end 407.79573 -263.918954)
		(width 0.10668)
		(layer "F.Cu")
		(net "M_G_CPU0_SB_CA<5>")
	)
	(segment
		(start 408.476958 -264.24001)
		(end 408.593798 -264.12317)
		(width 0.10668)
		(layer "F.Cu")
		(net "M_G_CPU0_SB_CA<5>")
	)
	(segment
		(start 406.481788 -263.802114)
		(end 406.598628 -263.918954)
		(width 0.10668)
		(layer "F.Cu")
		(net "M_G_CPU0_SB_CA<5>")
	)
	(segment
		(start 408.194764 -263.918954)
		(end 408.194764 -264.12317)
		(width 0.10668)
		(layer "F.Cu")
		(net "M_G_CPU0_SB_CA<5>")
	)
	(segment
		(start 407.91257 -263.802114)
		(end 408.077924 -263.802114)
		(width 0.10668)
		(layer "F.Cu")
		(net "M_G_CPU0_SB_CA<5>")
	)
	(segment
		(start 399.31594 -265.227308)
		(end 404.793704 -265.227308)
		(width 0.10668)
		(layer "F.Cu")
		(net "M_G_CPU0_SB_CA<5>")
	)
	(segment
		(start 406.997662 -264.12317)
		(end 406.997662 -263.918954)
		(width 0.10668)
		(layer "F.Cu")
		(net "M_G_CPU0_SB_CA<5>")
	)
	(segment
		(start 406.218898 -263.802114)
		(end 406.481788 -263.802114)
		(width 0.10668)
		(layer "F.Cu")
		(net "M_G_CPU0_SB_CA<5>")
	)
	(segment
		(start 394.03655 -263.77265)
		(end 394.044932 -263.777476)
		(width 0.0762)
		(layer "F.Cu")
		(net "M_G_CPU0_SB_CA<5>")
	)
	(segment
		(start 407.114502 -263.802114)
		(end 407.279856 -263.802114)
		(width 0.10668)
		(layer "F.Cu")
		(net "M_G_CPU0_SB_CA<5>")
	)
	(segment
		(start 408.194764 -264.12317)
		(end 408.311604 -264.24001)
		(width 0.10668)
		(layer "F.Cu")
		(net "M_G_CPU0_SB_CA<5>")
	)
	(segment
		(start 395.813026 -263.84504)
		(end 397.933672 -263.84504)
		(width 0.10668)
		(layer "F.Cu")
		(net "M_G_CPU0_SB_CA<5>")
	)
	(segment
		(start 407.79573 -263.918954)
		(end 407.91257 -263.802114)
		(width 0.10668)
		(layer "F.Cu")
		(net "M_G_CPU0_SB_CA<5>")
	)
	(segment
		(start 408.710638 -263.802114)
		(end 409.897072 -263.802114)
		(width 0.10668)
		(layer "F.Cu")
		(net "M_G_CPU0_SB_CA<5>")
	)
	(segment
		(start 406.715468 -264.24001)
		(end 406.880822 -264.24001)
		(width 0.10668)
		(layer "F.Cu")
		(net "M_G_CPU0_SB_CA<5>")
	)
	(segment
		(start 406.598628 -264.12317)
		(end 406.715468 -264.24001)
		(width 0.10668)
		(layer "F.Cu")
		(net "M_G_CPU0_SB_CA<5>")
	)
	(segment
		(start 394.331698 -263.881362)
		(end 395.279118 -263.881362)
		(width 0.0762)
		(layer "F.Cu")
		(net "M_G_CPU0_SB_CA<5>")
	)
	(arc
		(start 392.434064 -263.853676)
		(mid 392.587813 -263.836167)
		(end 392.73099 -263.777476)
		(width 0.0762)
		(layer "F.Cu")
		(net "M_G_CPU0_SB_CA<5>")
	)
	(arc
		(start 394.044932 -263.777476)
		(mid 394.147826 -263.829848)
		(end 394.256006 -263.870186)
		(width 0.0762)
		(layer "F.Cu")
		(net "M_G_CPU0_SB_CA<5>")
	)
	(arc
		(start 391.97788 -264.100056)
		(mid 392.173229 -263.916237)
		(end 392.434064 -263.853676)
		(width 0.0762)
		(layer "F.Cu")
		(net "M_G_CPU0_SB_CA<5>")
	)
	(arc
		(start 392.73099 -263.777476)
		(mid 392.917934 -263.727221)
		(end 393.104878 -263.777476)
		(width 0.0762)
		(layer "F.Cu")
		(net "M_G_CPU0_SB_CA<5>")
	)
	(arc
		(start 393.67079 -263.777476)
		(mid 393.853041 -263.727126)
		(end 394.03655 -263.77265)
		(width 0.0762)
		(layer "F.Cu")
		(net "M_G_CPU0_SB_CA<5>")
	)
	(arc
		(start 394.256006 -263.870186)
		(mid 394.293432 -263.878625)
		(end 394.331698 -263.881362)
		(width 0.0762)
		(layer "F.Cu")
		(net "M_G_CPU0_SB_CA<5>")
	)
	(arc
		(start 393.104878 -263.777476)
		(mid 393.387834 -263.853653)
		(end 393.67079 -263.777476)
		(width 0.0762)
		(layer "F.Cu")
		(net "M_G_CPU0_SB_CA<5>")
	)
	(segment
		(start 398.074896 -263.50468)
		(end 399.457164 -264.886948)
		(width 0.10668)
		(layer "F.Cu")
		(net "M_G_CPU0_SB_CA<4>")
	)
	(segment
		(start 392.448034 -263.29005)
		(end 392.339576 -263.47674)
		(width 0.0762)
		(layer "F.Cu")
		(net "M_G_CPU0_SB_CA<4>")
	)
	(segment
		(start 395.88313 -263.50468)
		(end 398.074896 -263.50468)
		(width 0.10668)
		(layer "F.Cu")
		(net "M_G_CPU0_SB_CA<4>")
	)
	(segment
		(start 415.57194 -264.48512)
		(end 416.468052 -264.48512)
		(width 0.101346)
		(layer "F.Cu")
		(net "M_G_CPU0_SB_CA<4>")
	)
	(segment
		(start 406.077674 -263.461754)
		(end 410.71927 -263.461754)
		(width 0.10668)
		(layer "F.Cu")
		(net "M_G_CPU0_SB_CA<4>")
	)
	(segment
		(start 415.146998 -264.060178)
		(end 415.57194 -264.48512)
		(width 0.101346)
		(layer "F.Cu")
		(net "M_G_CPU0_SB_CA<4>")
	)
	(segment
		(start 395.146276 -263.671812)
		(end 395.30909 -263.50468)
		(width 0.0762)
		(layer "F.Cu")
		(net "M_G_CPU0_SB_CA<4>")
	)
	(segment
		(start 395.30909 -263.50468)
		(end 395.88313 -263.50468)
		(width 0.0762)
		(layer "F.Cu")
		(net "M_G_CPU0_SB_CA<4>")
	)
	(segment
		(start 393.20089 -263.61263)
		(end 393.201144 -263.61263)
		(width 0.0762)
		(layer "F.Cu")
		(net "M_G_CPU0_SB_CA<4>")
	)
	(segment
		(start 399.457164 -264.886948)
		(end 404.65248 -264.886948)
		(width 0.10668)
		(layer "F.Cu")
		(net "M_G_CPU0_SB_CA<4>")
	)
	(segment
		(start 404.65248 -264.886948)
		(end 406.077674 -263.461754)
		(width 0.10668)
		(layer "F.Cu")
		(net "M_G_CPU0_SB_CA<4>")
	)
	(segment
		(start 410.71927 -263.461754)
		(end 411.317694 -264.060178)
		(width 0.10668)
		(layer "F.Cu")
		(net "M_G_CPU0_SB_CA<4>")
	)
	(segment
		(start 411.317694 -264.060178)
		(end 415.146998 -264.060178)
		(width 0.101346)
		(layer "F.Cu")
		(net "M_G_CPU0_SB_CA<4>")
	)
	(segment
		(start 392.626596 -263.617456)
		(end 392.634978 -263.61263)
		(width 0.0762)
		(layer "F.Cu")
		(net "M_G_CPU0_SB_CA<4>")
	)
	(segment
		(start 394.298424 -263.670796)
		(end 395.146276 -263.671812)
		(width 0.0762)
		(layer "F.Cu")
		(net "M_G_CPU0_SB_CA<4>")
	)
	(arc
		(start 392.339576 -263.47674)
		(mid 392.365493 -263.609782)
		(end 392.491214 -263.660382)
		(width 0.0762)
		(layer "F.Cu")
		(net "M_G_CPU0_SB_CA<4>")
	)
	(arc
		(start 393.575032 -263.61263)
		(mid 393.857988 -263.536453)
		(end 394.140944 -263.61263)
		(width 0.0762)
		(layer "F.Cu")
		(net "M_G_CPU0_SB_CA<4>")
	)
	(arc
		(start 394.223494 -263.654794)
		(mid 394.260122 -263.666724)
		(end 394.298424 -263.670796)
		(width 0.0762)
		(layer "F.Cu")
		(net "M_G_CPU0_SB_CA<4>")
	)
	(arc
		(start 394.140944 -263.61263)
		(mid 394.181638 -263.634849)
		(end 394.223494 -263.654794)
		(width 0.0762)
		(layer "F.Cu")
		(net "M_G_CPU0_SB_CA<4>")
	)
	(arc
		(start 392.634978 -263.61263)
		(mid 392.917934 -263.536453)
		(end 393.20089 -263.61263)
		(width 0.0762)
		(layer "F.Cu")
		(net "M_G_CPU0_SB_CA<4>")
	)
	(arc
		(start 393.201144 -263.61263)
		(mid 393.388088 -263.662954)
		(end 393.575032 -263.61263)
		(width 0.0762)
		(layer "F.Cu")
		(net "M_G_CPU0_SB_CA<4>")
	)
	(arc
		(start 392.491214 -263.660382)
		(mid 392.560968 -263.645425)
		(end 392.626596 -263.617456)
		(width 0.0762)
		(layer "F.Cu")
		(net "M_G_CPU0_SB_CA<4>")
	)
	(segment
		(start 404.511002 -264.546588)
		(end 405.422608 -263.634982)
		(width 0.10668)
		(layer "F.Cu")
		(net "M_G_CPU0_SB_CA<3>")
	)
	(segment
		(start 409.22829 -263.004554)
		(end 409.34513 -263.121394)
		(width 0.10668)
		(layer "F.Cu")
		(net "M_G_CPU0_SB_CA<3>")
	)
	(segment
		(start 408.547062 -263.121394)
		(end 408.712416 -263.121394)
		(width 0.10668)
		(layer "F.Cu")
		(net "M_G_CPU0_SB_CA<3>")
	)
	(segment
		(start 408.031188 -262.817356)
		(end 408.148028 -262.700516)
		(width 0.10668)
		(layer "F.Cu")
		(net "M_G_CPU0_SB_CA<3>")
	)
	(segment
		(start 409.627324 -262.817356)
		(end 409.744164 -262.700516)
		(width 0.10668)
		(layer "F.Cu")
		(net "M_G_CPU0_SB_CA<3>")
	)
	(segment
		(start 395.676628 -262.858758)
		(end 397.930878 -262.858758)
		(width 0.10668)
		(layer "F.Cu")
		(net "M_G_CPU0_SB_CA<3>")
	)
	(segment
		(start 394.327888 -262.916924)
		(end 395.314424 -262.916924)
		(width 0.0762)
		(layer "F.Cu")
		(net "M_G_CPU0_SB_CA<3>")
	)
	(segment
		(start 407.748994 -263.121394)
		(end 407.914348 -263.121394)
		(width 0.10668)
		(layer "F.Cu")
		(net "M_G_CPU0_SB_CA<3>")
	)
	(segment
		(start 408.829256 -262.817356)
		(end 408.946096 -262.700516)
		(width 0.10668)
		(layer "F.Cu")
		(net "M_G_CPU0_SB_CA<3>")
	)
	(segment
		(start 406.834086 -262.817356)
		(end 406.834086 -263.004554)
		(width 0.10668)
		(layer "F.Cu")
		(net "M_G_CPU0_SB_CA<3>")
	)
	(segment
		(start 407.632154 -263.004554)
		(end 407.748994 -263.121394)
		(width 0.10668)
		(layer "F.Cu")
		(net "M_G_CPU0_SB_CA<3>")
	)
	(segment
		(start 411.40507 -263.634982)
		(end 412.367984 -263.634982)
		(width 0.10668)
		(layer "F.Cu")
		(net "M_G_CPU0_SB_CA<3>")
	)
	(segment
		(start 406.834086 -263.004554)
		(end 406.950926 -263.121394)
		(width 0.10668)
		(layer "F.Cu")
		(net "M_G_CPU0_SB_CA<3>")
	)
	(segment
		(start 397.930878 -262.858758)
		(end 399.618708 -264.546588)
		(width 0.10668)
		(layer "F.Cu")
		(net "M_G_CPU0_SB_CA<3>")
	)
	(segment
		(start 407.11628 -263.121394)
		(end 407.23312 -263.004554)
		(width 0.10668)
		(layer "F.Cu")
		(net "M_G_CPU0_SB_CA<3>")
	)
	(segment
		(start 408.712416 -263.121394)
		(end 408.829256 -263.004554)
		(width 0.10668)
		(layer "F.Cu")
		(net "M_G_CPU0_SB_CA<3>")
	)
	(segment
		(start 409.22829 -262.817356)
		(end 409.22829 -263.004554)
		(width 0.10668)
		(layer "F.Cu")
		(net "M_G_CPU0_SB_CA<3>")
	)
	(segment
		(start 408.430222 -263.004554)
		(end 408.547062 -263.121394)
		(width 0.10668)
		(layer "F.Cu")
		(net "M_G_CPU0_SB_CA<3>")
	)
	(segment
		(start 406.35682 -262.700516)
		(end 406.717246 -262.700516)
		(width 0.10668)
		(layer "F.Cu")
		(net "M_G_CPU0_SB_CA<3>")
	)
	(segment
		(start 408.829256 -263.004554)
		(end 408.829256 -262.817356)
		(width 0.10668)
		(layer "F.Cu")
		(net "M_G_CPU0_SB_CA<3>")
	)
	(segment
		(start 407.23312 -263.004554)
		(end 407.23312 -262.817356)
		(width 0.10668)
		(layer "F.Cu")
		(net "M_G_CPU0_SB_CA<3>")
	)
	(segment
		(start 409.11145 -262.700516)
		(end 409.22829 -262.817356)
		(width 0.10668)
		(layer "F.Cu")
		(net "M_G_CPU0_SB_CA<3>")
	)
	(segment
		(start 399.618708 -264.546588)
		(end 404.511002 -264.546588)
		(width 0.10668)
		(layer "F.Cu")
		(net "M_G_CPU0_SB_CA<3>")
	)
	(segment
		(start 408.031188 -263.004554)
		(end 408.031188 -262.817356)
		(width 0.10668)
		(layer "F.Cu")
		(net "M_G_CPU0_SB_CA<3>")
	)
	(segment
		(start 407.515314 -262.700516)
		(end 407.632154 -262.817356)
		(width 0.10668)
		(layer "F.Cu")
		(net "M_G_CPU0_SB_CA<3>")
	)
	(segment
		(start 409.510484 -263.121394)
		(end 409.627324 -263.004554)
		(width 0.10668)
		(layer "F.Cu")
		(net "M_G_CPU0_SB_CA<3>")
	)
	(segment
		(start 408.148028 -262.700516)
		(end 408.313382 -262.700516)
		(width 0.10668)
		(layer "F.Cu")
		(net "M_G_CPU0_SB_CA<3>")
	)
	(segment
		(start 408.430222 -262.817356)
		(end 408.430222 -263.004554)
		(width 0.10668)
		(layer "F.Cu")
		(net "M_G_CPU0_SB_CA<3>")
	)
	(segment
		(start 406.950926 -263.121394)
		(end 407.11628 -263.121394)
		(width 0.10668)
		(layer "F.Cu")
		(net "M_G_CPU0_SB_CA<3>")
	)
	(segment
		(start 407.914348 -263.121394)
		(end 408.031188 -263.004554)
		(width 0.10668)
		(layer "F.Cu")
		(net "M_G_CPU0_SB_CA<3>")
	)
	(segment
		(start 410.470604 -262.700516)
		(end 411.40507 -263.634982)
		(width 0.10668)
		(layer "F.Cu")
		(net "M_G_CPU0_SB_CA<3>")
	)
	(segment
		(start 405.422608 -263.634982)
		(end 405.422608 -263.634728)
		(width 0.10668)
		(layer "F.Cu")
		(net "M_G_CPU0_SB_CA<3>")
	)
	(segment
		(start 409.34513 -263.121394)
		(end 409.510484 -263.121394)
		(width 0.10668)
		(layer "F.Cu")
		(net "M_G_CPU0_SB_CA<3>")
	)
	(segment
		(start 407.34996 -262.700516)
		(end 407.515314 -262.700516)
		(width 0.10668)
		(layer "F.Cu")
		(net "M_G_CPU0_SB_CA<3>")
	)
	(segment
		(start 395.37259 -262.858758)
		(end 395.676628 -262.858758)
		(width 0.0762)
		(layer "F.Cu")
		(net "M_G_CPU0_SB_CA<3>")
	)
	(segment
		(start 408.946096 -262.700516)
		(end 409.11145 -262.700516)
		(width 0.10668)
		(layer "F.Cu")
		(net "M_G_CPU0_SB_CA<3>")
	)
	(segment
		(start 408.313382 -262.700516)
		(end 408.430222 -262.817356)
		(width 0.10668)
		(layer "F.Cu")
		(net "M_G_CPU0_SB_CA<3>")
	)
	(segment
		(start 406.717246 -262.700516)
		(end 406.834086 -262.817356)
		(width 0.10668)
		(layer "F.Cu")
		(net "M_G_CPU0_SB_CA<3>")
	)
	(segment
		(start 407.632154 -262.817356)
		(end 407.632154 -263.004554)
		(width 0.10668)
		(layer "F.Cu")
		(net "M_G_CPU0_SB_CA<3>")
	)
	(segment
		(start 407.23312 -262.817356)
		(end 407.34996 -262.700516)
		(width 0.10668)
		(layer "F.Cu")
		(net "M_G_CPU0_SB_CA<3>")
	)
	(segment
		(start 409.744164 -262.700516)
		(end 410.470604 -262.700516)
		(width 0.10668)
		(layer "F.Cu")
		(net "M_G_CPU0_SB_CA<3>")
	)
	(segment
		(start 405.422608 -263.634728)
		(end 406.35682 -262.700516)
		(width 0.10668)
		(layer "F.Cu")
		(net "M_G_CPU0_SB_CA<3>")
	)
	(segment
		(start 395.314424 -262.916924)
		(end 395.37259 -262.858758)
		(width 0.0762)
		(layer "F.Cu")
		(net "M_G_CPU0_SB_CA<3>")
	)
	(segment
		(start 409.627324 -263.004554)
		(end 409.627324 -262.817356)
		(width 0.10668)
		(layer "F.Cu")
		(net "M_G_CPU0_SB_CA<3>")
	)
	(arc
		(start 393.387834 -263.29005)
		(mid 393.631265 -263.120563)
		(end 393.916916 -263.040622)
		(width 0.0762)
		(layer "F.Cu")
		(net "M_G_CPU0_SB_CA<3>")
	)
	(arc
		(start 394.140944 -262.96747)
		(mid 394.216184 -262.934157)
		(end 394.2969 -262.918194)
		(width 0.0762)
		(layer "F.Cu")
		(net "M_G_CPU0_SB_CA<3>")
	)
	(arc
		(start 393.955524 -263.035288)
		(mid 394.051233 -263.009576)
		(end 394.140944 -262.96747)
		(width 0.0762)
		(layer "F.Cu")
		(net "M_G_CPU0_SB_CA<3>")
	)
	(arc
		(start 394.2969 -262.918194)
		(mid 394.312381 -262.917238)
		(end 394.327888 -262.916924)
		(width 0.0762)
		(layer "F.Cu")
		(net "M_G_CPU0_SB_CA<3>")
	)
	(arc
		(start 393.916916 -263.040622)
		(mid 393.936265 -263.038284)
		(end 393.955524 -263.035288)
		(width 0.0762)
		(layer "F.Cu")
		(net "M_G_CPU0_SB_CA<3>")
	)
	(segment
		(start 399.760186 -264.206228)
		(end 404.369524 -264.206228)
		(width 0.10668)
		(layer "F.Cu")
		(net "M_G_CPU0_SB_CA<2>")
	)
	(segment
		(start 415.559748 -262.785098)
		(end 416.468052 -262.785098)
		(width 0.101346)
		(layer "F.Cu")
		(net "M_G_CPU0_SB_CA<2>")
	)
	(segment
		(start 406.215596 -262.360156)
		(end 411.317694 -262.360156)
		(width 0.10668)
		(layer "F.Cu")
		(net "M_G_CPU0_SB_CA<2>")
	)
	(segment
		(start 395.318488 -262.518398)
		(end 395.662658 -262.518398)
		(width 0.0762)
		(layer "F.Cu")
		(net "M_G_CPU0_SB_CA<2>")
	)
	(segment
		(start 411.317694 -262.360156)
		(end 415.134806 -262.360156)
		(width 0.101346)
		(layer "F.Cu")
		(net "M_G_CPU0_SB_CA<2>")
	)
	(segment
		(start 415.134806 -262.360156)
		(end 415.559748 -262.785098)
		(width 0.101346)
		(layer "F.Cu")
		(net "M_G_CPU0_SB_CA<2>")
	)
	(segment
		(start 394.03655 -262.80745)
		(end 394.044932 -262.802624)
		(width 0.0762)
		(layer "F.Cu")
		(net "M_G_CPU0_SB_CA<2>")
	)
	(segment
		(start 398.072356 -262.518398)
		(end 399.760186 -264.206228)
		(width 0.10668)
		(layer "F.Cu")
		(net "M_G_CPU0_SB_CA<2>")
	)
	(segment
		(start 404.369524 -264.206228)
		(end 406.215596 -262.360156)
		(width 0.10668)
		(layer "F.Cu")
		(net "M_G_CPU0_SB_CA<2>")
	)
	(segment
		(start 394.327634 -262.726424)
		(end 395.110462 -262.726424)
		(width 0.0762)
		(layer "F.Cu")
		(net "M_G_CPU0_SB_CA<2>")
	)
	(segment
		(start 395.662658 -262.518398)
		(end 398.072356 -262.518398)
		(width 0.10668)
		(layer "F.Cu")
		(net "M_G_CPU0_SB_CA<2>")
	)
	(segment
		(start 393.857988 -262.480044)
		(end 393.755626 -262.65632)
		(width 0.0762)
		(layer "F.Cu")
		(net "M_G_CPU0_SB_CA<2>")
	)
	(segment
		(start 395.110462 -262.726424)
		(end 395.318488 -262.518398)
		(width 0.0762)
		(layer "F.Cu")
		(net "M_G_CPU0_SB_CA<2>")
	)
	(arc
		(start 393.755626 -262.65632)
		(mid 393.785255 -262.798807)
		(end 393.922504 -262.847328)
		(width 0.0762)
		(layer "F.Cu")
		(net "M_G_CPU0_SB_CA<2>")
	)
	(arc
		(start 394.280644 -262.728202)
		(mid 394.304121 -262.726826)
		(end 394.327634 -262.726424)
		(width 0.0762)
		(layer "F.Cu")
		(net "M_G_CPU0_SB_CA<2>")
	)
	(arc
		(start 393.922504 -262.847328)
		(mid 393.98115 -262.832035)
		(end 394.03655 -262.80745)
		(width 0.0762)
		(layer "F.Cu")
		(net "M_G_CPU0_SB_CA<2>")
	)
	(arc
		(start 394.044932 -262.802624)
		(mid 394.158656 -262.752323)
		(end 394.280644 -262.728202)
		(width 0.0762)
		(layer "F.Cu")
		(net "M_G_CPU0_SB_CA<2>")
	)
	(segment
		(start 394.331698 -262.26135)
		(end 395.35608 -262.26135)
		(width 0.0762)
		(layer "F.Cu")
		(net "M_G_CPU0_SB_CA<1>")
	)
	(segment
		(start 404.2283 -263.865868)
		(end 406.159208 -261.93496)
		(width 0.10668)
		(layer "F.Cu")
		(net "M_G_CPU0_SB_CA<1>")
	)
	(segment
		(start 407.762964 -261.81812)
		(end 407.762964 -261.439152)
		(width 0.10668)
		(layer "F.Cu")
		(net "M_G_CPU0_SB_CA<1>")
	)
	(segment
		(start 408.278838 -261.93496)
		(end 412.367984 -261.93496)
		(width 0.10668)
		(layer "F.Cu")
		(net "M_G_CPU0_SB_CA<1>")
	)
	(segment
		(start 408.045158 -261.322312)
		(end 408.161998 -261.439152)
		(width 0.10668)
		(layer "F.Cu")
		(net "M_G_CPU0_SB_CA<1>")
	)
	(segment
		(start 395.439392 -262.178038)
		(end 395.750034 -262.178038)
		(width 0.0762)
		(layer "F.Cu")
		(net "M_G_CPU0_SB_CA<1>")
	)
	(segment
		(start 399.901664 -263.865868)
		(end 404.2283 -263.865868)
		(width 0.10668)
		(layer "F.Cu")
		(net "M_G_CPU0_SB_CA<1>")
	)
	(segment
		(start 407.081736 -261.322312)
		(end 407.24709 -261.322312)
		(width 0.10668)
		(layer "F.Cu")
		(net "M_G_CPU0_SB_CA<1>")
	)
	(segment
		(start 406.964896 -261.439152)
		(end 407.081736 -261.322312)
		(width 0.10668)
		(layer "F.Cu")
		(net "M_G_CPU0_SB_CA<1>")
	)
	(segment
		(start 398.213834 -262.178038)
		(end 399.901664 -263.865868)
		(width 0.10668)
		(layer "F.Cu")
		(net "M_G_CPU0_SB_CA<1>")
	)
	(segment
		(start 407.48077 -261.93496)
		(end 407.646124 -261.93496)
		(width 0.10668)
		(layer "F.Cu")
		(net "M_G_CPU0_SB_CA<1>")
	)
	(segment
		(start 407.646124 -261.93496)
		(end 407.762964 -261.81812)
		(width 0.10668)
		(layer "F.Cu")
		(net "M_G_CPU0_SB_CA<1>")
	)
	(segment
		(start 406.159208 -261.93496)
		(end 406.848056 -261.93496)
		(width 0.10668)
		(layer "F.Cu")
		(net "M_G_CPU0_SB_CA<1>")
	)
	(segment
		(start 407.24709 -261.322312)
		(end 407.36393 -261.439152)
		(width 0.10668)
		(layer "F.Cu")
		(net "M_G_CPU0_SB_CA<1>")
	)
	(segment
		(start 395.750034 -262.178038)
		(end 398.213834 -262.178038)
		(width 0.10668)
		(layer "F.Cu")
		(net "M_G_CPU0_SB_CA<1>")
	)
	(segment
		(start 407.36393 -261.81812)
		(end 407.48077 -261.93496)
		(width 0.10668)
		(layer "F.Cu")
		(net "M_G_CPU0_SB_CA<1>")
	)
	(segment
		(start 395.35608 -262.26135)
		(end 395.439392 -262.178038)
		(width 0.0762)
		(layer "F.Cu")
		(net "M_G_CPU0_SB_CA<1>")
	)
	(segment
		(start 407.762964 -261.439152)
		(end 407.879804 -261.322312)
		(width 0.10668)
		(layer "F.Cu")
		(net "M_G_CPU0_SB_CA<1>")
	)
	(segment
		(start 407.879804 -261.322312)
		(end 408.045158 -261.322312)
		(width 0.10668)
		(layer "F.Cu")
		(net "M_G_CPU0_SB_CA<1>")
	)
	(segment
		(start 406.848056 -261.93496)
		(end 406.964896 -261.81812)
		(width 0.10668)
		(layer "F.Cu")
		(net "M_G_CPU0_SB_CA<1>")
	)
	(segment
		(start 408.161998 -261.81812)
		(end 408.278838 -261.93496)
		(width 0.10668)
		(layer "F.Cu")
		(net "M_G_CPU0_SB_CA<1>")
	)
	(segment
		(start 408.161998 -261.439152)
		(end 408.161998 -261.81812)
		(width 0.10668)
		(layer "F.Cu")
		(net "M_G_CPU0_SB_CA<1>")
	)
	(segment
		(start 406.964896 -261.81812)
		(end 406.964896 -261.439152)
		(width 0.10668)
		(layer "F.Cu")
		(net "M_G_CPU0_SB_CA<1>")
	)
	(segment
		(start 407.36393 -261.439152)
		(end 407.36393 -261.81812)
		(width 0.10668)
		(layer "F.Cu")
		(net "M_G_CPU0_SB_CA<1>")
	)
	(segment
		(start 394.03655 -262.152638)
		(end 394.044932 -262.157464)
		(width 0.0762)
		(layer "F.Cu")
		(net "M_G_CPU0_SB_CA<1>")
	)
	(arc
		(start 393.67079 -262.157464)
		(mid 393.853041 -262.107114)
		(end 394.03655 -262.152638)
		(width 0.0762)
		(layer "F.Cu")
		(net "M_G_CPU0_SB_CA<1>")
	)
	(arc
		(start 393.104878 -262.157464)
		(mid 393.387834 -262.233641)
		(end 393.67079 -262.157464)
		(width 0.0762)
		(layer "F.Cu")
		(net "M_G_CPU0_SB_CA<1>")
	)
	(arc
		(start 391.97788 -262.480044)
		(mid 392.173229 -262.296225)
		(end 392.434064 -262.233664)
		(width 0.0762)
		(layer "F.Cu")
		(net "M_G_CPU0_SB_CA<1>")
	)
	(arc
		(start 392.434064 -262.233664)
		(mid 392.587813 -262.216155)
		(end 392.73099 -262.157464)
		(width 0.0762)
		(layer "F.Cu")
		(net "M_G_CPU0_SB_CA<1>")
	)
	(arc
		(start 392.73099 -262.157464)
		(mid 392.917934 -262.107209)
		(end 393.104878 -262.157464)
		(width 0.0762)
		(layer "F.Cu")
		(net "M_G_CPU0_SB_CA<1>")
	)
	(arc
		(start 394.044932 -262.157464)
		(mid 394.147826 -262.209836)
		(end 394.256006 -262.250174)
		(width 0.0762)
		(layer "F.Cu")
		(net "M_G_CPU0_SB_CA<1>")
	)
	(arc
		(start 394.256006 -262.250174)
		(mid 394.293432 -262.258613)
		(end 394.331698 -262.26135)
		(width 0.0762)
		(layer "F.Cu")
		(net "M_G_CPU0_SB_CA<1>")
	)
	(segment
		(start 392.626596 -261.997444)
		(end 392.634978 -261.992618)
		(width 0.0762)
		(layer "F.Cu")
		(net "M_G_CPU0_SB_CA<0>")
	)
	(segment
		(start 395.823694 -261.837678)
		(end 398.355058 -261.837678)
		(width 0.10668)
		(layer "F.Cu")
		(net "M_G_CPU0_SB_CA<0>")
	)
	(segment
		(start 406.955244 -260.65734)
		(end 415.544 -260.65734)
		(width 0.10668)
		(layer "F.Cu")
		(net "M_G_CPU0_SB_CA<0>")
	)
	(segment
		(start 415.971736 -261.085076)
		(end 416.468052 -261.085076)
		(width 0.10668)
		(layer "F.Cu")
		(net "M_G_CPU0_SB_CA<0>")
	)
	(segment
		(start 404.087076 -263.525508)
		(end 406.955244 -260.65734)
		(width 0.10668)
		(layer "F.Cu")
		(net "M_G_CPU0_SB_CA<0>")
	)
	(segment
		(start 400.042888 -263.525508)
		(end 404.087076 -263.525508)
		(width 0.10668)
		(layer "F.Cu")
		(net "M_G_CPU0_SB_CA<0>")
	)
	(segment
		(start 392.448034 -261.670038)
		(end 392.339576 -261.856728)
		(width 0.0762)
		(layer "F.Cu")
		(net "M_G_CPU0_SB_CA<0>")
	)
	(segment
		(start 394.298424 -262.050784)
		(end 395.129766 -262.052054)
		(width 0.0762)
		(layer "F.Cu")
		(net "M_G_CPU0_SB_CA<0>")
	)
	(segment
		(start 393.20089 -261.992618)
		(end 393.201144 -261.992618)
		(width 0.0762)
		(layer "F.Cu")
		(net "M_G_CPU0_SB_CA<0>")
	)
	(segment
		(start 398.355058 -261.837678)
		(end 400.042888 -263.525508)
		(width 0.10668)
		(layer "F.Cu")
		(net "M_G_CPU0_SB_CA<0>")
	)
	(segment
		(start 395.129766 -262.052054)
		(end 395.344142 -261.837678)
		(width 0.0762)
		(layer "F.Cu")
		(net "M_G_CPU0_SB_CA<0>")
	)
	(segment
		(start 415.544 -260.65734)
		(end 415.971736 -261.085076)
		(width 0.10668)
		(layer "F.Cu")
		(net "M_G_CPU0_SB_CA<0>")
	)
	(segment
		(start 395.344142 -261.837678)
		(end 395.823694 -261.837678)
		(width 0.0762)
		(layer "F.Cu")
		(net "M_G_CPU0_SB_CA<0>")
	)
	(arc
		(start 392.339576 -261.856728)
		(mid 392.365493 -261.98977)
		(end 392.491214 -262.04037)
		(width 0.0762)
		(layer "F.Cu")
		(net "M_G_CPU0_SB_CA<0>")
	)
	(arc
		(start 392.634978 -261.992618)
		(mid 392.917934 -261.916441)
		(end 393.20089 -261.992618)
		(width 0.0762)
		(layer "F.Cu")
		(net "M_G_CPU0_SB_CA<0>")
	)
	(arc
		(start 394.223494 -262.034782)
		(mid 394.260122 -262.046712)
		(end 394.298424 -262.050784)
		(width 0.0762)
		(layer "F.Cu")
		(net "M_G_CPU0_SB_CA<0>")
	)
	(arc
		(start 393.201144 -261.992618)
		(mid 393.388088 -262.042942)
		(end 393.575032 -261.992618)
		(width 0.0762)
		(layer "F.Cu")
		(net "M_G_CPU0_SB_CA<0>")
	)
	(arc
		(start 393.575032 -261.992618)
		(mid 393.857988 -261.916441)
		(end 394.140944 -261.992618)
		(width 0.0762)
		(layer "F.Cu")
		(net "M_G_CPU0_SB_CA<0>")
	)
	(arc
		(start 392.491214 -262.04037)
		(mid 392.560968 -262.025413)
		(end 392.626596 -261.997444)
		(width 0.0762)
		(layer "F.Cu")
		(net "M_G_CPU0_SB_CA<0>")
	)
	(arc
		(start 394.140944 -261.992618)
		(mid 394.181638 -262.014837)
		(end 394.223494 -262.034782)
		(width 0.0762)
		(layer "F.Cu")
		(net "M_G_CPU0_SB_CA<0>")
	)
	(segment
		(start 394.298424 -266.91082)
		(end 395.14145 -266.911836)
		(width 0.0762)
		(layer "F.Cu")
		(net "M_G_CPU0_SA_RSP<0>")
	)
	(segment
		(start 395.634972 -266.744196)
		(end 397.460978 -266.744196)
		(width 0.10668)
		(layer "F.Cu")
		(net "M_G_CPU0_SA_RSP<0>")
	)
	(segment
		(start 411.317694 -269.123414)
		(end 411.354524 -269.160244)
		(width 0.101346)
		(layer "F.Cu")
		(net "M_G_CPU0_SA_RSP<0>")
	)
	(segment
		(start 409.804108 -267.609828)
		(end 411.317694 -269.123414)
		(width 0.10668)
		(layer "F.Cu")
		(net "M_G_CPU0_SA_RSP<0>")
	)
	(segment
		(start 414.229296 -269.585186)
		(end 416.468052 -269.585186)
		(width 0.101346)
		(layer "F.Cu")
		(net "M_G_CPU0_SA_RSP<0>")
	)
	(segment
		(start 411.354524 -269.160244)
		(end 413.804354 -269.160244)
		(width 0.101346)
		(layer "F.Cu")
		(net "M_G_CPU0_SA_RSP<0>")
	)
	(segment
		(start 397.460978 -266.744196)
		(end 398.32661 -267.609828)
		(width 0.10668)
		(layer "F.Cu")
		(net "M_G_CPU0_SA_RSP<0>")
	)
	(segment
		(start 413.804354 -269.160244)
		(end 414.229296 -269.585186)
		(width 0.101346)
		(layer "F.Cu")
		(net "M_G_CPU0_SA_RSP<0>")
	)
	(segment
		(start 395.308074 -266.744196)
		(end 395.634972 -266.744196)
		(width 0.0762)
		(layer "F.Cu")
		(net "M_G_CPU0_SA_RSP<0>")
	)
	(segment
		(start 393.20089 -266.852654)
		(end 393.201144 -266.852654)
		(width 0.0762)
		(layer "F.Cu")
		(net "M_G_CPU0_SA_RSP<0>")
	)
	(segment
		(start 392.448034 -266.530074)
		(end 392.339576 -266.716764)
		(width 0.0762)
		(layer "F.Cu")
		(net "M_G_CPU0_SA_RSP<0>")
	)
	(segment
		(start 398.32661 -267.609828)
		(end 409.804108 -267.609828)
		(width 0.10668)
		(layer "F.Cu")
		(net "M_G_CPU0_SA_RSP<0>")
	)
	(segment
		(start 392.626596 -266.85748)
		(end 392.634978 -266.852654)
		(width 0.0762)
		(layer "F.Cu")
		(net "M_G_CPU0_SA_RSP<0>")
	)
	(segment
		(start 395.14145 -266.911836)
		(end 395.167612 -266.884658)
		(width 0.0762)
		(layer "F.Cu")
		(net "M_G_CPU0_SA_RSP<0>")
	)
	(segment
		(start 395.167612 -266.884658)
		(end 395.308074 -266.744196)
		(width 0.0762)
		(layer "F.Cu")
		(net "M_G_CPU0_SA_RSP<0>")
	)
	(arc
		(start 392.634978 -266.852654)
		(mid 392.917934 -266.776477)
		(end 393.20089 -266.852654)
		(width 0.0762)
		(layer "F.Cu")
		(net "M_G_CPU0_SA_RSP<0>")
	)
	(arc
		(start 394.223494 -266.894818)
		(mid 394.260122 -266.906748)
		(end 394.298424 -266.91082)
		(width 0.0762)
		(layer "F.Cu")
		(net "M_G_CPU0_SA_RSP<0>")
	)
	(arc
		(start 394.140944 -266.852654)
		(mid 394.181638 -266.874873)
		(end 394.223494 -266.894818)
		(width 0.0762)
		(layer "F.Cu")
		(net "M_G_CPU0_SA_RSP<0>")
	)
	(arc
		(start 393.575032 -266.852654)
		(mid 393.857988 -266.776477)
		(end 394.140944 -266.852654)
		(width 0.0762)
		(layer "F.Cu")
		(net "M_G_CPU0_SA_RSP<0>")
	)
	(arc
		(start 392.339576 -266.716764)
		(mid 392.365493 -266.849806)
		(end 392.491214 -266.900406)
		(width 0.0762)
		(layer "F.Cu")
		(net "M_G_CPU0_SA_RSP<0>")
	)
	(arc
		(start 392.491214 -266.900406)
		(mid 392.560968 -266.885449)
		(end 392.626596 -266.85748)
		(width 0.0762)
		(layer "F.Cu")
		(net "M_G_CPU0_SA_RSP<0>")
	)
	(arc
		(start 393.201144 -266.852654)
		(mid 393.388088 -266.902978)
		(end 393.575032 -266.852654)
		(width 0.0762)
		(layer "F.Cu")
		(net "M_G_CPU0_SA_RSP<0>")
	)
	(segment
		(start 392.900916 -255.767586)
		(end 392.909298 -255.76276)
		(width 0.0762)
		(layer "F.Cu")
		(net "M_G_CPU0_SA_PAR")
	)
	(segment
		(start 392.326622 -255.76276)
		(end 392.327638 -255.763268)
		(width 0.0762)
		(layer "F.Cu")
		(net "M_G_CPU0_SA_PAR")
	)
	(segment
		(start 403.821392 -254.210312)
		(end 405.671528 -254.97663)
		(width 0.10668)
		(layer "F.Cu")
		(net "M_G_CPU0_SA_PAR")
	)
	(segment
		(start 392.327638 -255.763268)
		(end 392.335004 -255.767586)
		(width 0.0762)
		(layer "F.Cu")
		(net "M_G_CPU0_SA_PAR")
	)
	(segment
		(start 414.582102 -254.284988)
		(end 416.468052 -254.284988)
		(width 0.101346)
		(layer "F.Cu")
		(net "M_G_CPU0_SA_PAR")
	)
	(segment
		(start 411.317694 -253.010162)
		(end 413.307276 -253.010162)
		(width 0.101346)
		(layer "F.Cu")
		(net "M_G_CPU0_SA_PAR")
	)
	(segment
		(start 395.545818 -255.877822)
		(end 398.400016 -255.877822)
		(width 0.10668)
		(layer "F.Cu")
		(net "M_G_CPU0_SA_PAR")
	)
	(segment
		(start 392.14806 -256.090166)
		(end 392.14806 -256.089912)
		(width 0.0762)
		(layer "F.Cu")
		(net "M_G_CPU0_SA_PAR")
	)
	(segment
		(start 410.990288 -253.010162)
		(end 411.317694 -253.010162)
		(width 0.10668)
		(layer "F.Cu")
		(net "M_G_CPU0_SA_PAR")
	)
	(segment
		(start 394.052044 -255.71069)
		(end 394.894816 -255.71069)
		(width 0.0762)
		(layer "F.Cu")
		(net "M_G_CPU0_SA_PAR")
	)
	(segment
		(start 405.671528 -254.97663)
		(end 409.02382 -254.97663)
		(width 0.10668)
		(layer "F.Cu")
		(net "M_G_CPU0_SA_PAR")
	)
	(segment
		(start 400.067526 -254.210312)
		(end 403.821392 -254.210312)
		(width 0.10668)
		(layer "F.Cu")
		(net "M_G_CPU0_SA_PAR")
	)
	(segment
		(start 394.894816 -255.71069)
		(end 395.061948 -255.877822)
		(width 0.0762)
		(layer "F.Cu")
		(net "M_G_CPU0_SA_PAR")
	)
	(segment
		(start 392.14806 -256.089912)
		(end 392.042904 -255.909064)
		(width 0.0762)
		(layer "F.Cu")
		(net "M_G_CPU0_SA_PAR")
	)
	(segment
		(start 409.02382 -254.97663)
		(end 410.990288 -253.010162)
		(width 0.10668)
		(layer "F.Cu")
		(net "M_G_CPU0_SA_PAR")
	)
	(segment
		(start 395.061948 -255.877822)
		(end 395.545818 -255.877822)
		(width 0.0762)
		(layer "F.Cu")
		(net "M_G_CPU0_SA_PAR")
	)
	(segment
		(start 413.307276 -253.010162)
		(end 414.582102 -254.284988)
		(width 0.101346)
		(layer "F.Cu")
		(net "M_G_CPU0_SA_PAR")
	)
	(segment
		(start 398.400016 -255.877822)
		(end 400.067526 -254.210312)
		(width 0.10668)
		(layer "F.Cu")
		(net "M_G_CPU0_SA_PAR")
	)
	(arc
		(start 392.909298 -255.76276)
		(mid 393.092806 -255.717266)
		(end 393.275058 -255.767586)
		(width 0.0762)
		(layer "F.Cu")
		(net "M_G_CPU0_SA_PAR")
	)
	(arc
		(start 392.042904 -255.909064)
		(mid 392.051841 -255.79004)
		(end 392.146536 -255.717294)
		(width 0.0762)
		(layer "F.Cu")
		(net "M_G_CPU0_SA_PAR")
	)
	(arc
		(start 393.275058 -255.767586)
		(mid 393.558014 -255.843763)
		(end 393.84097 -255.767586)
		(width 0.0762)
		(layer "F.Cu")
		(net "M_G_CPU0_SA_PAR")
	)
	(arc
		(start 392.335004 -255.767586)
		(mid 392.61796 -255.843763)
		(end 392.900916 -255.767586)
		(width 0.0762)
		(layer "F.Cu")
		(net "M_G_CPU0_SA_PAR")
	)
	(arc
		(start 392.146536 -255.717294)
		(mid 392.23946 -255.728617)
		(end 392.326622 -255.76276)
		(width 0.0762)
		(layer "F.Cu")
		(net "M_G_CPU0_SA_PAR")
	)
	(arc
		(start 393.84097 -255.767586)
		(mid 393.942738 -255.725152)
		(end 394.052044 -255.71069)
		(width 0.0762)
		(layer "F.Cu")
		(net "M_G_CPU0_SA_PAR")
	)
	(segment
		(start 392.900916 -247.667526)
		(end 392.909298 -247.6627)
		(width 0.0762)
		(layer "F.Cu")
		(net "M_G_CPU0_SA_DQS_DP<9>")
	)
	(segment
		(start 409.758388 -241.81054)
		(end 409.758388 -241.343688)
		(width 0.12954)
		(layer "F.Cu")
		(net "M_G_CPU0_SA_DQS_DP<9>")
	)
	(segment
		(start 411.810708 -239.835182)
		(end 412.367984 -239.835182)
		(width 0.12954)
		(layer "F.Cu")
		(net "M_G_CPU0_SA_DQS_DP<9>")
	)
	(segment
		(start 409.42895 -242.139978)
		(end 409.758388 -241.81054)
		(width 0.12954)
		(layer "F.Cu")
		(net "M_G_CPU0_SA_DQS_DP<9>")
	)
	(segment
		(start 407.355294 -243.004594)
		(end 407.553414 -243.004594)
		(width 0.12954)
		(layer "F.Cu")
		(net "M_G_CPU0_SA_DQS_DP<9>")
	)
	(segment
		(start 409.486354 -240.873534)
		(end 409.628594 -240.731294)
		(width 0.12954)
		(layer "F.Cu")
		(net "M_G_CPU0_SA_DQS_DP<9>")
	)
	(segment
		(start 411.154118 -239.57153)
		(end 411.547056 -239.57153)
		(width 0.12954)
		(layer "F.Cu")
		(net "M_G_CPU0_SA_DQS_DP<9>")
	)
	(segment
		(start 395.270736 -247.57634)
		(end 395.336776 -247.64238)
		(width 0.0762)
		(layer "F.Cu")
		(net "M_G_CPU0_SA_DQS_DP<9>")
	)
	(segment
		(start 395.336776 -247.64238)
		(end 395.355826 -247.64238)
		(width 0.0762)
		(layer "F.Cu")
		(net "M_G_CPU0_SA_DQS_DP<9>")
	)
	(segment
		(start 407.553414 -243.004594)
		(end 407.825448 -243.276628)
		(width 0.12954)
		(layer "F.Cu")
		(net "M_G_CPU0_SA_DQS_DP<9>")
	)
	(segment
		(start 409.826714 -240.731294)
		(end 410.098748 -241.003328)
		(width 0.12954)
		(layer "F.Cu")
		(net "M_G_CPU0_SA_DQS_DP<9>")
	)
	(segment
		(start 407.825448 -243.276628)
		(end 408.2923 -243.276628)
		(width 0.12954)
		(layer "F.Cu")
		(net "M_G_CPU0_SA_DQS_DP<9>")
	)
	(segment
		(start 411.547056 -239.57153)
		(end 411.810708 -239.835182)
		(width 0.12954)
		(layer "F.Cu")
		(net "M_G_CPU0_SA_DQS_DP<9>")
	)
	(segment
		(start 407.485088 -243.616988)
		(end 407.213054 -243.344954)
		(width 0.12954)
		(layer "F.Cu")
		(net "M_G_CPU0_SA_DQS_DP<9>")
	)
	(segment
		(start 410.948378 -240.62055)
		(end 410.948378 -239.77727)
		(width 0.12954)
		(layer "F.Cu")
		(net "M_G_CPU0_SA_DQS_DP<9>")
	)
	(segment
		(start 394.027914 -247.617488)
		(end 394.028422 -247.61698)
		(width 0.0762)
		(layer "F.Cu")
		(net "M_G_CPU0_SA_DQS_DP<9>")
	)
	(segment
		(start 408.2923 -243.276628)
		(end 408.621738 -242.94719)
		(width 0.12954)
		(layer "F.Cu")
		(net "M_G_CPU0_SA_DQS_DP<9>")
	)
	(segment
		(start 408.621738 -242.480338)
		(end 408.349704 -242.208304)
		(width 0.12954)
		(layer "F.Cu")
		(net "M_G_CPU0_SA_DQS_DP<9>")
	)
	(segment
		(start 407.485088 -244.516148)
		(end 407.485088 -243.616988)
		(width 0.12954)
		(layer "F.Cu")
		(net "M_G_CPU0_SA_DQS_DP<9>")
	)
	(segment
		(start 410.098748 -241.003328)
		(end 410.5656 -241.003328)
		(width 0.12954)
		(layer "F.Cu")
		(net "M_G_CPU0_SA_DQS_DP<9>")
	)
	(segment
		(start 408.349704 -242.010184)
		(end 408.491944 -241.867944)
		(width 0.12954)
		(layer "F.Cu")
		(net "M_G_CPU0_SA_DQS_DP<9>")
	)
	(segment
		(start 408.621738 -242.94719)
		(end 408.621738 -242.480338)
		(width 0.12954)
		(layer "F.Cu")
		(net "M_G_CPU0_SA_DQS_DP<9>")
	)
	(segment
		(start 392.326622 -247.6627)
		(end 392.335004 -247.667526)
		(width 0.0762)
		(layer "F.Cu")
		(net "M_G_CPU0_SA_DQS_DP<9>")
	)
	(segment
		(start 408.962098 -242.139978)
		(end 409.42895 -242.139978)
		(width 0.12954)
		(layer "F.Cu")
		(net "M_G_CPU0_SA_DQS_DP<9>")
	)
	(segment
		(start 409.628594 -240.731294)
		(end 409.826714 -240.731294)
		(width 0.12954)
		(layer "F.Cu")
		(net "M_G_CPU0_SA_DQS_DP<9>")
	)
	(segment
		(start 407.213054 -243.146834)
		(end 407.355294 -243.004594)
		(width 0.12954)
		(layer "F.Cu")
		(net "M_G_CPU0_SA_DQS_DP<9>")
	)
	(segment
		(start 409.486354 -241.071654)
		(end 409.486354 -240.873534)
		(width 0.12954)
		(layer "F.Cu")
		(net "M_G_CPU0_SA_DQS_DP<9>")
	)
	(segment
		(start 407.213054 -243.344954)
		(end 407.213054 -243.146834)
		(width 0.12954)
		(layer "F.Cu")
		(net "M_G_CPU0_SA_DQS_DP<9>")
	)
	(segment
		(start 410.948378 -239.77727)
		(end 411.154118 -239.57153)
		(width 0.12954)
		(layer "F.Cu")
		(net "M_G_CPU0_SA_DQS_DP<9>")
	)
	(segment
		(start 394.028422 -247.61698)
		(end 394.568172 -247.61698)
		(width 0.0762)
		(layer "F.Cu")
		(net "M_G_CPU0_SA_DQS_DP<9>")
	)
	(segment
		(start 394.608812 -247.57634)
		(end 395.270736 -247.57634)
		(width 0.0762)
		(layer "F.Cu")
		(net "M_G_CPU0_SA_DQS_DP<9>")
	)
	(segment
		(start 394.568172 -247.61698)
		(end 394.608812 -247.57634)
		(width 0.0762)
		(layer "F.Cu")
		(net "M_G_CPU0_SA_DQS_DP<9>")
	)
	(segment
		(start 408.690064 -241.867944)
		(end 408.962098 -242.139978)
		(width 0.12954)
		(layer "F.Cu")
		(net "M_G_CPU0_SA_DQS_DP<9>")
	)
	(segment
		(start 408.349704 -242.208304)
		(end 408.349704 -242.010184)
		(width 0.12954)
		(layer "F.Cu")
		(net "M_G_CPU0_SA_DQS_DP<9>")
	)
	(segment
		(start 409.758388 -241.343688)
		(end 409.486354 -241.071654)
		(width 0.12954)
		(layer "F.Cu")
		(net "M_G_CPU0_SA_DQS_DP<9>")
	)
	(segment
		(start 408.491944 -241.867944)
		(end 408.690064 -241.867944)
		(width 0.12954)
		(layer "F.Cu")
		(net "M_G_CPU0_SA_DQS_DP<9>")
	)
	(segment
		(start 410.5656 -241.003328)
		(end 410.948378 -240.62055)
		(width 0.12954)
		(layer "F.Cu")
		(net "M_G_CPU0_SA_DQS_DP<9>")
	)
	(segment
		(start 395.355826 -247.64238)
		(end 404.358856 -247.64238)
		(width 0.12954)
		(layer "F.Cu")
		(net "M_G_CPU0_SA_DQS_DP<9>")
	)
	(segment
		(start 392.14806 -247.990106)
		(end 392.046206 -247.814846)
		(width 0.0762)
		(layer "F.Cu")
		(net "M_G_CPU0_SA_DQS_DP<9>")
	)
	(segment
		(start 404.358856 -247.64238)
		(end 407.485088 -244.516148)
		(width 0.12954)
		(layer "F.Cu")
		(net "M_G_CPU0_SA_DQS_DP<9>")
	)
	(arc
		(start 392.192764 -247.620028)
		(mid 392.261711 -247.635025)
		(end 392.326622 -247.6627)
		(width 0.0762)
		(layer "F.Cu")
		(net "M_G_CPU0_SA_DQS_DP<9>")
	)
	(arc
		(start 392.909298 -247.6627)
		(mid 393.092806 -247.617206)
		(end 393.275058 -247.667526)
		(width 0.0762)
		(layer "F.Cu")
		(net "M_G_CPU0_SA_DQS_DP<9>")
	)
	(arc
		(start 393.275058 -247.667526)
		(mid 393.558014 -247.743703)
		(end 393.84097 -247.667526)
		(width 0.0762)
		(layer "F.Cu")
		(net "M_G_CPU0_SA_DQS_DP<9>")
	)
	(arc
		(start 392.335004 -247.667526)
		(mid 392.61796 -247.743703)
		(end 392.900916 -247.667526)
		(width 0.0762)
		(layer "F.Cu")
		(net "M_G_CPU0_SA_DQS_DP<9>")
	)
	(arc
		(start 393.84097 -247.667526)
		(mid 393.931139 -247.630177)
		(end 394.027914 -247.617488)
		(width 0.0762)
		(layer "F.Cu")
		(net "M_G_CPU0_SA_DQS_DP<9>")
	)
	(arc
		(start 392.046206 -247.814846)
		(mid 392.0634 -247.67526)
		(end 392.192764 -247.620028)
		(width 0.0762)
		(layer "F.Cu")
		(net "M_G_CPU0_SA_DQS_DP<9>")
	)
	(segment
		(start 408.291538 -233.368596)
		(end 408.490674 -233.368596)
		(width 0.12954)
		(layer "F.Cu")
		(net "M_G_CPU0_SA_DQS_DP<8>")
	)
	(segment
		(start 408.490674 -233.368596)
		(end 409.18003 -234.057952)
		(width 0.12954)
		(layer "F.Cu")
		(net "M_G_CPU0_SA_DQS_DP<8>")
	)
	(segment
		(start 409.645866 -234.057952)
		(end 409.976828 -233.72699)
		(width 0.12954)
		(layer "F.Cu")
		(net "M_G_CPU0_SA_DQS_DP<8>")
	)
	(segment
		(start 392.326622 -242.802664)
		(end 392.335004 -242.80749)
		(width 0.0762)
		(layer "F.Cu")
		(net "M_G_CPU0_SA_DQS_DP<8>")
	)
	(segment
		(start 409.18003 -234.057952)
		(end 409.645866 -234.057952)
		(width 0.12954)
		(layer "F.Cu")
		(net "M_G_CPU0_SA_DQS_DP<8>")
	)
	(segment
		(start 411.810708 -230.485188)
		(end 412.367984 -230.485188)
		(width 0.12954)
		(layer "F.Cu")
		(net "M_G_CPU0_SA_DQS_DP<8>")
	)
	(segment
		(start 392.900916 -242.80749)
		(end 392.909298 -242.802664)
		(width 0.0762)
		(layer "F.Cu")
		(net "M_G_CPU0_SA_DQS_DP<8>")
	)
	(segment
		(start 394.027914 -242.757452)
		(end 394.028422 -242.756944)
		(width 0.0762)
		(layer "F.Cu")
		(net "M_G_CPU0_SA_DQS_DP<8>")
	)
	(segment
		(start 409.976828 -233.261154)
		(end 409.287472 -232.571798)
		(width 0.12954)
		(layer "F.Cu")
		(net "M_G_CPU0_SA_DQS_DP<8>")
	)
	(segment
		(start 411.438598 -230.221536)
		(end 411.547056 -230.221536)
		(width 0.12954)
		(layer "F.Cu")
		(net "M_G_CPU0_SA_DQS_DP<8>")
	)
	(segment
		(start 408.150822 -233.509312)
		(end 408.291538 -233.368596)
		(width 0.12954)
		(layer "F.Cu")
		(net "M_G_CPU0_SA_DQS_DP<8>")
	)
	(segment
		(start 404.649432 -238.259366)
		(end 405.758904 -238.259366)
		(width 0.12954)
		(layer "F.Cu")
		(net "M_G_CPU0_SA_DQS_DP<8>")
	)
	(segment
		(start 392.14806 -243.13007)
		(end 392.046206 -242.95481)
		(width 0.0762)
		(layer "F.Cu")
		(net "M_G_CPU0_SA_DQS_DP<8>")
	)
	(segment
		(start 394.028422 -242.756944)
		(end 394.825982 -242.756944)
		(width 0.0762)
		(layer "F.Cu")
		(net "M_G_CPU0_SA_DQS_DP<8>")
	)
	(segment
		(start 405.758904 -238.259366)
		(end 408.997404 -235.020866)
		(width 0.12954)
		(layer "F.Cu")
		(net "M_G_CPU0_SA_DQS_DP<8>")
	)
	(segment
		(start 394.825982 -242.756944)
		(end 395.181328 -243.11229)
		(width 0.0762)
		(layer "F.Cu")
		(net "M_G_CPU0_SA_DQS_DP<8>")
	)
	(segment
		(start 409.287472 -232.372662)
		(end 411.438598 -230.221536)
		(width 0.12954)
		(layer "F.Cu")
		(net "M_G_CPU0_SA_DQS_DP<8>")
	)
	(segment
		(start 408.997404 -234.55503)
		(end 408.150822 -233.708448)
		(width 0.12954)
		(layer "F.Cu")
		(net "M_G_CPU0_SA_DQS_DP<8>")
	)
	(segment
		(start 411.547056 -230.221536)
		(end 411.810708 -230.485188)
		(width 0.12954)
		(layer "F.Cu")
		(net "M_G_CPU0_SA_DQS_DP<8>")
	)
	(segment
		(start 408.997404 -235.020866)
		(end 408.997404 -234.55503)
		(width 0.12954)
		(layer "F.Cu")
		(net "M_G_CPU0_SA_DQS_DP<8>")
	)
	(segment
		(start 408.150822 -233.708448)
		(end 408.150822 -233.509312)
		(width 0.12954)
		(layer "F.Cu")
		(net "M_G_CPU0_SA_DQS_DP<8>")
	)
	(segment
		(start 399.730468 -243.17833)
		(end 404.649432 -238.259366)
		(width 0.12954)
		(layer "F.Cu")
		(net "M_G_CPU0_SA_DQS_DP<8>")
	)
	(segment
		(start 395.181328 -243.11229)
		(end 395.53007 -243.11229)
		(width 0.0762)
		(layer "F.Cu")
		(net "M_G_CPU0_SA_DQS_DP<8>")
	)
	(segment
		(start 395.61516 -243.17833)
		(end 399.730468 -243.17833)
		(width 0.12954)
		(layer "F.Cu")
		(net "M_G_CPU0_SA_DQS_DP<8>")
	)
	(segment
		(start 409.976828 -233.72699)
		(end 409.976828 -233.261154)
		(width 0.12954)
		(layer "F.Cu")
		(net "M_G_CPU0_SA_DQS_DP<8>")
	)
	(segment
		(start 395.53007 -243.11229)
		(end 395.59611 -243.17833)
		(width 0.0762)
		(layer "F.Cu")
		(net "M_G_CPU0_SA_DQS_DP<8>")
	)
	(segment
		(start 395.59611 -243.17833)
		(end 395.61516 -243.17833)
		(width 0.0762)
		(layer "F.Cu")
		(net "M_G_CPU0_SA_DQS_DP<8>")
	)
	(segment
		(start 409.287472 -232.571798)
		(end 409.287472 -232.372662)
		(width 0.12954)
		(layer "F.Cu")
		(net "M_G_CPU0_SA_DQS_DP<8>")
	)
	(arc
		(start 392.335004 -242.80749)
		(mid 392.61796 -242.883667)
		(end 392.900916 -242.80749)
		(width 0.0762)
		(layer "F.Cu")
		(net "M_G_CPU0_SA_DQS_DP<8>")
	)
	(arc
		(start 392.046206 -242.95481)
		(mid 392.0634 -242.815224)
		(end 392.192764 -242.759992)
		(width 0.0762)
		(layer "F.Cu")
		(net "M_G_CPU0_SA_DQS_DP<8>")
	)
	(arc
		(start 393.84097 -242.80749)
		(mid 393.931139 -242.770141)
		(end 394.027914 -242.757452)
		(width 0.0762)
		(layer "F.Cu")
		(net "M_G_CPU0_SA_DQS_DP<8>")
	)
	(arc
		(start 393.275058 -242.80749)
		(mid 393.558014 -242.883667)
		(end 393.84097 -242.80749)
		(width 0.0762)
		(layer "F.Cu")
		(net "M_G_CPU0_SA_DQS_DP<8>")
	)
	(arc
		(start 392.909298 -242.802664)
		(mid 393.092806 -242.75717)
		(end 393.275058 -242.80749)
		(width 0.0762)
		(layer "F.Cu")
		(net "M_G_CPU0_SA_DQS_DP<8>")
	)
	(arc
		(start 392.192764 -242.759992)
		(mid 392.261711 -242.774989)
		(end 392.326622 -242.802664)
		(width 0.0762)
		(layer "F.Cu")
		(net "M_G_CPU0_SA_DQS_DP<8>")
	)
	(segment
		(start 397.274034 -238.15421)
		(end 407.144728 -228.283516)
		(width 0.12954)
		(layer "F.Cu")
		(net "M_G_CPU0_SA_DQS_DP<7>")
	)
	(segment
		(start 411.547056 -220.871542)
		(end 411.810708 -221.135194)
		(width 0.12954)
		(layer "F.Cu")
		(net "M_G_CPU0_SA_DQS_DP<7>")
	)
	(segment
		(start 410.568394 -222.53067)
		(end 410.899356 -222.199708)
		(width 0.12954)
		(layer "F.Cu")
		(net "M_G_CPU0_SA_DQS_DP<7>")
	)
	(segment
		(start 410.668216 -221.502732)
		(end 410.668216 -221.319852)
		(width 0.12954)
		(layer "F.Cu")
		(net "M_G_CPU0_SA_DQS_DP<7>")
	)
	(segment
		(start 392.326622 -237.942628)
		(end 392.335004 -237.947454)
		(width 0.0762)
		(layer "F.Cu")
		(net "M_G_CPU0_SA_DQS_DP<7>")
	)
	(segment
		(start 395.406118 -238.08817)
		(end 395.472158 -238.15421)
		(width 0.0762)
		(layer "F.Cu")
		(net "M_G_CPU0_SA_DQS_DP<7>")
	)
	(segment
		(start 409.210256 -223.911668)
		(end 409.676092 -223.911668)
		(width 0.12954)
		(layer "F.Cu")
		(net "M_G_CPU0_SA_DQS_DP<7>")
	)
	(segment
		(start 410.007054 -223.580706)
		(end 410.007054 -223.11487)
		(width 0.12954)
		(layer "F.Cu")
		(net "M_G_CPU0_SA_DQS_DP<7>")
	)
	(segment
		(start 408.296364 -223.478344)
		(end 408.43708 -223.337628)
		(width 0.12954)
		(layer "F.Cu")
		(net "M_G_CPU0_SA_DQS_DP<7>")
	)
	(segment
		(start 407.283158 -224.44075)
		(end 407.466038 -224.44075)
		(width 0.12954)
		(layer "F.Cu")
		(net "M_G_CPU0_SA_DQS_DP<7>")
	)
	(segment
		(start 410.668216 -221.319852)
		(end 411.116526 -220.871542)
		(width 0.12954)
		(layer "F.Cu")
		(net "M_G_CPU0_SA_DQS_DP<7>")
	)
	(segment
		(start 392.900916 -237.947454)
		(end 392.909298 -237.942628)
		(width 0.0762)
		(layer "F.Cu")
		(net "M_G_CPU0_SA_DQS_DP<7>")
	)
	(segment
		(start 407.144728 -224.57918)
		(end 407.283158 -224.44075)
		(width 0.12954)
		(layer "F.Cu")
		(net "M_G_CPU0_SA_DQS_DP<7>")
	)
	(segment
		(start 410.899356 -221.733872)
		(end 410.668216 -221.502732)
		(width 0.12954)
		(layer "F.Cu")
		(net "M_G_CPU0_SA_DQS_DP<7>")
	)
	(segment
		(start 408.634946 -225.143822)
		(end 408.965908 -224.81286)
		(width 0.12954)
		(layer "F.Cu")
		(net "M_G_CPU0_SA_DQS_DP<7>")
	)
	(segment
		(start 394.834618 -237.896908)
		(end 395.02588 -238.08817)
		(width 0.0762)
		(layer "F.Cu")
		(net "M_G_CPU0_SA_DQS_DP<7>")
	)
	(segment
		(start 408.965908 -224.347024)
		(end 408.296364 -223.67748)
		(width 0.12954)
		(layer "F.Cu")
		(net "M_G_CPU0_SA_DQS_DP<7>")
	)
	(segment
		(start 409.66263 -222.289878)
		(end 409.861766 -222.289878)
		(width 0.12954)
		(layer "F.Cu")
		(net "M_G_CPU0_SA_DQS_DP<7>")
	)
	(segment
		(start 408.965908 -224.81286)
		(end 408.965908 -224.347024)
		(width 0.12954)
		(layer "F.Cu")
		(net "M_G_CPU0_SA_DQS_DP<7>")
	)
	(segment
		(start 409.861766 -222.289878)
		(end 410.102558 -222.53067)
		(width 0.12954)
		(layer "F.Cu")
		(net "M_G_CPU0_SA_DQS_DP<7>")
	)
	(segment
		(start 395.02588 -238.08817)
		(end 395.406118 -238.08817)
		(width 0.0762)
		(layer "F.Cu")
		(net "M_G_CPU0_SA_DQS_DP<7>")
	)
	(segment
		(start 408.16911 -225.143822)
		(end 408.634946 -225.143822)
		(width 0.12954)
		(layer "F.Cu")
		(net "M_G_CPU0_SA_DQS_DP<7>")
	)
	(segment
		(start 409.521914 -222.62973)
		(end 409.521914 -222.430594)
		(width 0.12954)
		(layer "F.Cu")
		(net "M_G_CPU0_SA_DQS_DP<7>")
	)
	(segment
		(start 411.810708 -221.135194)
		(end 411.810962 -221.13494)
		(width 0.12954)
		(layer "F.Cu")
		(net "M_G_CPU0_SA_DQS_DP<7>")
	)
	(segment
		(start 395.472158 -238.15421)
		(end 395.491208 -238.15421)
		(width 0.0762)
		(layer "F.Cu")
		(net "M_G_CPU0_SA_DQS_DP<7>")
	)
	(segment
		(start 394.028422 -237.896908)
		(end 394.834618 -237.896908)
		(width 0.0762)
		(layer "F.Cu")
		(net "M_G_CPU0_SA_DQS_DP<7>")
	)
	(segment
		(start 410.007054 -223.11487)
		(end 409.521914 -222.62973)
		(width 0.12954)
		(layer "F.Cu")
		(net "M_G_CPU0_SA_DQS_DP<7>")
	)
	(segment
		(start 410.102558 -222.53067)
		(end 410.568394 -222.53067)
		(width 0.12954)
		(layer "F.Cu")
		(net "M_G_CPU0_SA_DQS_DP<7>")
	)
	(segment
		(start 407.144728 -228.283516)
		(end 407.144728 -224.57918)
		(width 0.12954)
		(layer "F.Cu")
		(net "M_G_CPU0_SA_DQS_DP<7>")
	)
	(segment
		(start 394.027914 -237.897416)
		(end 394.028422 -237.896908)
		(width 0.0762)
		(layer "F.Cu")
		(net "M_G_CPU0_SA_DQS_DP<7>")
	)
	(segment
		(start 408.296364 -223.67748)
		(end 408.296364 -223.478344)
		(width 0.12954)
		(layer "F.Cu")
		(net "M_G_CPU0_SA_DQS_DP<7>")
	)
	(segment
		(start 395.491208 -238.15421)
		(end 397.274034 -238.15421)
		(width 0.12954)
		(layer "F.Cu")
		(net "M_G_CPU0_SA_DQS_DP<7>")
	)
	(segment
		(start 392.14806 -238.270034)
		(end 392.046206 -238.094774)
		(width 0.0762)
		(layer "F.Cu")
		(net "M_G_CPU0_SA_DQS_DP<7>")
	)
	(segment
		(start 411.810962 -221.13494)
		(end 412.367984 -221.13494)
		(width 0.12954)
		(layer "F.Cu")
		(net "M_G_CPU0_SA_DQS_DP<7>")
	)
	(segment
		(start 411.116526 -220.871542)
		(end 411.547056 -220.871542)
		(width 0.12954)
		(layer "F.Cu")
		(net "M_G_CPU0_SA_DQS_DP<7>")
	)
	(segment
		(start 408.43708 -223.337628)
		(end 408.636216 -223.337628)
		(width 0.12954)
		(layer "F.Cu")
		(net "M_G_CPU0_SA_DQS_DP<7>")
	)
	(segment
		(start 410.899356 -222.199708)
		(end 410.899356 -221.733872)
		(width 0.12954)
		(layer "F.Cu")
		(net "M_G_CPU0_SA_DQS_DP<7>")
	)
	(segment
		(start 409.676092 -223.911668)
		(end 410.007054 -223.580706)
		(width 0.12954)
		(layer "F.Cu")
		(net "M_G_CPU0_SA_DQS_DP<7>")
	)
	(segment
		(start 409.521914 -222.430594)
		(end 409.66263 -222.289878)
		(width 0.12954)
		(layer "F.Cu")
		(net "M_G_CPU0_SA_DQS_DP<7>")
	)
	(segment
		(start 408.636216 -223.337628)
		(end 409.210256 -223.911668)
		(width 0.12954)
		(layer "F.Cu")
		(net "M_G_CPU0_SA_DQS_DP<7>")
	)
	(segment
		(start 407.466038 -224.44075)
		(end 408.16911 -225.143822)
		(width 0.12954)
		(layer "F.Cu")
		(net "M_G_CPU0_SA_DQS_DP<7>")
	)
	(arc
		(start 393.84097 -237.947454)
		(mid 393.931139 -237.910105)
		(end 394.027914 -237.897416)
		(width 0.0762)
		(layer "F.Cu")
		(net "M_G_CPU0_SA_DQS_DP<7>")
	)
	(arc
		(start 392.335004 -237.947454)
		(mid 392.61796 -238.023631)
		(end 392.900916 -237.947454)
		(width 0.0762)
		(layer "F.Cu")
		(net "M_G_CPU0_SA_DQS_DP<7>")
	)
	(arc
		(start 392.192764 -237.899956)
		(mid 392.261711 -237.914953)
		(end 392.326622 -237.942628)
		(width 0.0762)
		(layer "F.Cu")
		(net "M_G_CPU0_SA_DQS_DP<7>")
	)
	(arc
		(start 392.909298 -237.942628)
		(mid 393.092806 -237.897134)
		(end 393.275058 -237.947454)
		(width 0.0762)
		(layer "F.Cu")
		(net "M_G_CPU0_SA_DQS_DP<7>")
	)
	(arc
		(start 393.275058 -237.947454)
		(mid 393.558014 -238.023631)
		(end 393.84097 -237.947454)
		(width 0.0762)
		(layer "F.Cu")
		(net "M_G_CPU0_SA_DQS_DP<7>")
	)
	(arc
		(start 392.046206 -238.094774)
		(mid 392.0634 -237.955188)
		(end 392.192764 -237.899956)
		(width 0.0762)
		(layer "F.Cu")
		(net "M_G_CPU0_SA_DQS_DP<7>")
	)
	(segment
		(start 407.644854 -213.593934)
		(end 408.126946 -214.076026)
		(width 0.12954)
		(layer "F.Cu")
		(net "M_G_CPU0_SA_DQS_DP<6>")
	)
	(segment
		(start 407.786586 -214.883238)
		(end 407.786586 -214.416386)
		(width 0.12954)
		(layer "F.Cu")
		(net "M_G_CPU0_SA_DQS_DP<6>")
	)
	(segment
		(start 411.148276 -211.521548)
		(end 411.547056 -211.521548)
		(width 0.12954)
		(layer "F.Cu")
		(net "M_G_CPU0_SA_DQS_DP<6>")
	)
	(segment
		(start 392.326622 -233.082592)
		(end 392.335004 -233.087418)
		(width 0.0762)
		(layer "F.Cu")
		(net "M_G_CPU0_SA_DQS_DP<6>")
	)
	(segment
		(start 410.867098 -211.802726)
		(end 411.148276 -211.521548)
		(width 0.12954)
		(layer "F.Cu")
		(net "M_G_CPU0_SA_DQS_DP<6>")
	)
	(segment
		(start 402.700998 -226.48037)
		(end 402.700998 -219.968826)
		(width 0.12954)
		(layer "F.Cu")
		(net "M_G_CPU0_SA_DQS_DP<6>")
	)
	(segment
		(start 410.059886 -212.609938)
		(end 410.059886 -212.143086)
		(width 0.12954)
		(layer "F.Cu")
		(net "M_G_CPU0_SA_DQS_DP<6>")
	)
	(segment
		(start 409.730448 -212.939376)
		(end 410.059886 -212.609938)
		(width 0.12954)
		(layer "F.Cu")
		(net "M_G_CPU0_SA_DQS_DP<6>")
	)
	(segment
		(start 408.593798 -214.076026)
		(end 408.923236 -213.746588)
		(width 0.12954)
		(layer "F.Cu")
		(net "M_G_CPU0_SA_DQS_DP<6>")
	)
	(segment
		(start 395.261846 -233.102912)
		(end 396.078456 -233.102912)
		(width 0.12954)
		(layer "F.Cu")
		(net "M_G_CPU0_SA_DQS_DP<6>")
	)
	(segment
		(start 392.900916 -233.087418)
		(end 392.909298 -233.082592)
		(width 0.0762)
		(layer "F.Cu")
		(net "M_G_CPU0_SA_DQS_DP<6>")
	)
	(segment
		(start 408.583384 -212.457284)
		(end 408.781504 -212.457284)
		(width 0.12954)
		(layer "F.Cu")
		(net "M_G_CPU0_SA_DQS_DP<6>")
	)
	(segment
		(start 407.304494 -213.736174)
		(end 407.446734 -213.593934)
		(width 0.12954)
		(layer "F.Cu")
		(net "M_G_CPU0_SA_DQS_DP<6>")
	)
	(segment
		(start 408.923236 -213.746588)
		(end 408.923236 -213.279736)
		(width 0.12954)
		(layer "F.Cu")
		(net "M_G_CPU0_SA_DQS_DP<6>")
	)
	(segment
		(start 402.700998 -219.968826)
		(end 407.786586 -214.883238)
		(width 0.12954)
		(layer "F.Cu")
		(net "M_G_CPU0_SA_DQS_DP<6>")
	)
	(segment
		(start 395.242796 -233.102912)
		(end 395.261846 -233.102912)
		(width 0.0762)
		(layer "F.Cu")
		(net "M_G_CPU0_SA_DQS_DP<6>")
	)
	(segment
		(start 407.446734 -213.593934)
		(end 407.644854 -213.593934)
		(width 0.12954)
		(layer "F.Cu")
		(net "M_G_CPU0_SA_DQS_DP<6>")
	)
	(segment
		(start 410.400246 -211.802726)
		(end 410.867098 -211.802726)
		(width 0.12954)
		(layer "F.Cu")
		(net "M_G_CPU0_SA_DQS_DP<6>")
	)
	(segment
		(start 395.176756 -233.036872)
		(end 395.242796 -233.102912)
		(width 0.0762)
		(layer "F.Cu")
		(net "M_G_CPU0_SA_DQS_DP<6>")
	)
	(segment
		(start 409.577794 -211.462874)
		(end 409.720034 -211.320634)
		(width 0.12954)
		(layer "F.Cu")
		(net "M_G_CPU0_SA_DQS_DP<6>")
	)
	(segment
		(start 407.304494 -213.934294)
		(end 407.304494 -213.736174)
		(width 0.12954)
		(layer "F.Cu")
		(net "M_G_CPU0_SA_DQS_DP<6>")
	)
	(segment
		(start 409.577794 -211.660994)
		(end 409.577794 -211.462874)
		(width 0.12954)
		(layer "F.Cu")
		(net "M_G_CPU0_SA_DQS_DP<6>")
	)
	(segment
		(start 408.441144 -212.599524)
		(end 408.583384 -212.457284)
		(width 0.12954)
		(layer "F.Cu")
		(net "M_G_CPU0_SA_DQS_DP<6>")
	)
	(segment
		(start 408.781504 -212.457284)
		(end 409.263596 -212.939376)
		(width 0.12954)
		(layer "F.Cu")
		(net "M_G_CPU0_SA_DQS_DP<6>")
	)
	(segment
		(start 409.918154 -211.320634)
		(end 410.400246 -211.802726)
		(width 0.12954)
		(layer "F.Cu")
		(net "M_G_CPU0_SA_DQS_DP<6>")
	)
	(segment
		(start 408.126946 -214.076026)
		(end 408.593798 -214.076026)
		(width 0.12954)
		(layer "F.Cu")
		(net "M_G_CPU0_SA_DQS_DP<6>")
	)
	(segment
		(start 410.059886 -212.143086)
		(end 409.577794 -211.660994)
		(width 0.12954)
		(layer "F.Cu")
		(net "M_G_CPU0_SA_DQS_DP<6>")
	)
	(segment
		(start 411.547056 -211.521548)
		(end 411.810708 -211.7852)
		(width 0.12954)
		(layer "F.Cu")
		(net "M_G_CPU0_SA_DQS_DP<6>")
	)
	(segment
		(start 409.263596 -212.939376)
		(end 409.730448 -212.939376)
		(width 0.12954)
		(layer "F.Cu")
		(net "M_G_CPU0_SA_DQS_DP<6>")
	)
	(segment
		(start 394.027914 -233.03738)
		(end 394.028422 -233.036872)
		(width 0.0762)
		(layer "F.Cu")
		(net "M_G_CPU0_SA_DQS_DP<6>")
	)
	(segment
		(start 411.810962 -211.784946)
		(end 412.367984 -211.784946)
		(width 0.12954)
		(layer "F.Cu")
		(net "M_G_CPU0_SA_DQS_DP<6>")
	)
	(segment
		(start 411.810708 -211.7852)
		(end 411.810962 -211.784946)
		(width 0.12954)
		(layer "F.Cu")
		(net "M_G_CPU0_SA_DQS_DP<6>")
	)
	(segment
		(start 392.14806 -233.409998)
		(end 392.046206 -233.234738)
		(width 0.0762)
		(layer "F.Cu")
		(net "M_G_CPU0_SA_DQS_DP<6>")
	)
	(segment
		(start 408.441144 -212.797644)
		(end 408.441144 -212.599524)
		(width 0.12954)
		(layer "F.Cu")
		(net "M_G_CPU0_SA_DQS_DP<6>")
	)
	(segment
		(start 408.923236 -213.279736)
		(end 408.441144 -212.797644)
		(width 0.12954)
		(layer "F.Cu")
		(net "M_G_CPU0_SA_DQS_DP<6>")
	)
	(segment
		(start 407.786586 -214.416386)
		(end 407.304494 -213.934294)
		(width 0.12954)
		(layer "F.Cu")
		(net "M_G_CPU0_SA_DQS_DP<6>")
	)
	(segment
		(start 396.078456 -233.102912)
		(end 402.700998 -226.48037)
		(width 0.12954)
		(layer "F.Cu")
		(net "M_G_CPU0_SA_DQS_DP<6>")
	)
	(segment
		(start 409.720034 -211.320634)
		(end 409.918154 -211.320634)
		(width 0.12954)
		(layer "F.Cu")
		(net "M_G_CPU0_SA_DQS_DP<6>")
	)
	(segment
		(start 394.028422 -233.036872)
		(end 395.176756 -233.036872)
		(width 0.0762)
		(layer "F.Cu")
		(net "M_G_CPU0_SA_DQS_DP<6>")
	)
	(arc
		(start 393.275058 -233.087418)
		(mid 393.558014 -233.163595)
		(end 393.84097 -233.087418)
		(width 0.0762)
		(layer "F.Cu")
		(net "M_G_CPU0_SA_DQS_DP<6>")
	)
	(arc
		(start 393.84097 -233.087418)
		(mid 393.931139 -233.050069)
		(end 394.027914 -233.03738)
		(width 0.0762)
		(layer "F.Cu")
		(net "M_G_CPU0_SA_DQS_DP<6>")
	)
	(arc
		(start 392.192764 -233.03992)
		(mid 392.261711 -233.054917)
		(end 392.326622 -233.082592)
		(width 0.0762)
		(layer "F.Cu")
		(net "M_G_CPU0_SA_DQS_DP<6>")
	)
	(arc
		(start 392.046206 -233.234738)
		(mid 392.0634 -233.095152)
		(end 392.192764 -233.03992)
		(width 0.0762)
		(layer "F.Cu")
		(net "M_G_CPU0_SA_DQS_DP<6>")
	)
	(arc
		(start 392.335004 -233.087418)
		(mid 392.61796 -233.163595)
		(end 392.900916 -233.087418)
		(width 0.0762)
		(layer "F.Cu")
		(net "M_G_CPU0_SA_DQS_DP<6>")
	)
	(arc
		(start 392.909298 -233.082592)
		(mid 393.092806 -233.037098)
		(end 393.275058 -233.087418)
		(width 0.0762)
		(layer "F.Cu")
		(net "M_G_CPU0_SA_DQS_DP<6>")
	)
	(segment
		(start 408.171396 -206.235046)
		(end 408.502358 -205.904084)
		(width 0.12954)
		(layer "F.Cu")
		(net "M_G_CPU0_SA_DQS_DP<5>")
	)
	(segment
		(start 410.736034 -202.171554)
		(end 411.547056 -202.171554)
		(width 0.12954)
		(layer "F.Cu")
		(net "M_G_CPU0_SA_DQS_DP<5>")
	)
	(segment
		(start 395.385798 -227.40239)
		(end 395.479016 -227.40239)
		(width 0.0762)
		(layer "F.Cu")
		(net "M_G_CPU0_SA_DQS_DP<5>")
	)
	(segment
		(start 410.350462 -202.557126)
		(end 410.736034 -202.171554)
		(width 0.12954)
		(layer "F.Cu")
		(net "M_G_CPU0_SA_DQS_DP<5>")
	)
	(segment
		(start 408.502358 -205.904084)
		(end 408.502358 -205.438502)
		(width 0.12954)
		(layer "F.Cu")
		(net "M_G_CPU0_SA_DQS_DP<5>")
	)
	(segment
		(start 392.326622 -228.22281)
		(end 392.335004 -228.227636)
		(width 0.0762)
		(layer "F.Cu")
		(net "M_G_CPU0_SA_DQS_DP<5>")
	)
	(segment
		(start 409.639008 -204.767434)
		(end 409.639008 -204.301852)
		(width 0.12954)
		(layer "F.Cu")
		(net "M_G_CPU0_SA_DQS_DP<5>")
	)
	(segment
		(start 392.14806 -228.550216)
		(end 392.046206 -228.374956)
		(width 0.0762)
		(layer "F.Cu")
		(net "M_G_CPU0_SA_DQS_DP<5>")
	)
	(segment
		(start 410.350462 -202.740006)
		(end 410.350462 -202.557126)
		(width 0.12954)
		(layer "F.Cu")
		(net "M_G_CPU0_SA_DQS_DP<5>")
	)
	(segment
		(start 394.892276 -227.895912)
		(end 395.385798 -227.40239)
		(width 0.0762)
		(layer "F.Cu")
		(net "M_G_CPU0_SA_DQS_DP<5>")
	)
	(segment
		(start 409.155646 -203.619862)
		(end 409.29687 -203.478638)
		(width 0.12954)
		(layer "F.Cu")
		(net "M_G_CPU0_SA_DQS_DP<5>")
	)
	(segment
		(start 392.900916 -228.227636)
		(end 392.909298 -228.22281)
		(width 0.0762)
		(layer "F.Cu")
		(net "M_G_CPU0_SA_DQS_DP<5>")
	)
	(segment
		(start 410.444696 -203.961746)
		(end 410.775658 -203.630784)
		(width 0.12954)
		(layer "F.Cu")
		(net "M_G_CPU0_SA_DQS_DP<5>")
	)
	(segment
		(start 408.14625 -204.601318)
		(end 408.344878 -204.601318)
		(width 0.12954)
		(layer "F.Cu")
		(net "M_G_CPU0_SA_DQS_DP<5>")
	)
	(segment
		(start 407.353008 -206.235046)
		(end 408.171396 -206.235046)
		(width 0.12954)
		(layer "F.Cu")
		(net "M_G_CPU0_SA_DQS_DP<5>")
	)
	(segment
		(start 408.344878 -204.601318)
		(end 408.841956 -205.098396)
		(width 0.12954)
		(layer "F.Cu")
		(net "M_G_CPU0_SA_DQS_DP<5>")
	)
	(segment
		(start 408.005026 -204.742542)
		(end 408.14625 -204.601318)
		(width 0.12954)
		(layer "F.Cu")
		(net "M_G_CPU0_SA_DQS_DP<5>")
	)
	(segment
		(start 409.308046 -205.098396)
		(end 409.639008 -204.767434)
		(width 0.12954)
		(layer "F.Cu")
		(net "M_G_CPU0_SA_DQS_DP<5>")
	)
	(segment
		(start 398.075658 -224.804478)
		(end 398.075658 -215.512396)
		(width 0.12954)
		(layer "F.Cu")
		(net "M_G_CPU0_SA_DQS_DP<5>")
	)
	(segment
		(start 393.95654 -228.138736)
		(end 394.199364 -227.895912)
		(width 0.0762)
		(layer "F.Cu")
		(net "M_G_CPU0_SA_DQS_DP<5>")
	)
	(segment
		(start 411.810962 -202.434952)
		(end 412.367984 -202.434952)
		(width 0.12954)
		(layer "F.Cu")
		(net "M_G_CPU0_SA_DQS_DP<5>")
	)
	(segment
		(start 409.29687 -203.478638)
		(end 409.495498 -203.478638)
		(width 0.12954)
		(layer "F.Cu")
		(net "M_G_CPU0_SA_DQS_DP<5>")
	)
	(segment
		(start 411.810708 -202.435206)
		(end 411.810962 -202.434952)
		(width 0.12954)
		(layer "F.Cu")
		(net "M_G_CPU0_SA_DQS_DP<5>")
	)
	(segment
		(start 407.078434 -206.746856)
		(end 407.078434 -206.50962)
		(width 0.12954)
		(layer "F.Cu")
		(net "M_G_CPU0_SA_DQS_DP<5>")
	)
	(segment
		(start 410.775658 -203.165202)
		(end 410.350462 -202.740006)
		(width 0.12954)
		(layer "F.Cu")
		(net "M_G_CPU0_SA_DQS_DP<5>")
	)
	(segment
		(start 408.841956 -205.098396)
		(end 409.308046 -205.098396)
		(width 0.12954)
		(layer "F.Cu")
		(net "M_G_CPU0_SA_DQS_DP<5>")
	)
	(segment
		(start 409.495498 -203.478638)
		(end 409.978606 -203.961746)
		(width 0.12954)
		(layer "F.Cu")
		(net "M_G_CPU0_SA_DQS_DP<5>")
	)
	(segment
		(start 408.502358 -205.438502)
		(end 408.005026 -204.94117)
		(width 0.12954)
		(layer "F.Cu")
		(net "M_G_CPU0_SA_DQS_DP<5>")
	)
	(segment
		(start 410.775658 -203.630784)
		(end 410.775658 -203.165202)
		(width 0.12954)
		(layer "F.Cu")
		(net "M_G_CPU0_SA_DQS_DP<5>")
	)
	(segment
		(start 395.479016 -227.40239)
		(end 398.075658 -224.804478)
		(width 0.12954)
		(layer "F.Cu")
		(net "M_G_CPU0_SA_DQS_DP<5>")
	)
	(segment
		(start 406.566116 -207.021938)
		(end 406.803352 -207.021938)
		(width 0.12954)
		(layer "F.Cu")
		(net "M_G_CPU0_SA_DQS_DP<5>")
	)
	(segment
		(start 406.803352 -207.021938)
		(end 407.078434 -206.746856)
		(width 0.12954)
		(layer "F.Cu")
		(net "M_G_CPU0_SA_DQS_DP<5>")
	)
	(segment
		(start 409.978606 -203.961746)
		(end 410.444696 -203.961746)
		(width 0.12954)
		(layer "F.Cu")
		(net "M_G_CPU0_SA_DQS_DP<5>")
	)
	(segment
		(start 394.199364 -227.895912)
		(end 394.892276 -227.895912)
		(width 0.0762)
		(layer "F.Cu")
		(net "M_G_CPU0_SA_DQS_DP<5>")
	)
	(segment
		(start 398.075658 -215.512396)
		(end 406.566116 -207.021938)
		(width 0.12954)
		(layer "F.Cu")
		(net "M_G_CPU0_SA_DQS_DP<5>")
	)
	(segment
		(start 411.547056 -202.171554)
		(end 411.810708 -202.435206)
		(width 0.12954)
		(layer "F.Cu")
		(net "M_G_CPU0_SA_DQS_DP<5>")
	)
	(segment
		(start 409.155646 -203.81849)
		(end 409.155646 -203.619862)
		(width 0.12954)
		(layer "F.Cu")
		(net "M_G_CPU0_SA_DQS_DP<5>")
	)
	(segment
		(start 407.078434 -206.50962)
		(end 407.353008 -206.235046)
		(width 0.12954)
		(layer "F.Cu")
		(net "M_G_CPU0_SA_DQS_DP<5>")
	)
	(segment
		(start 408.005026 -204.94117)
		(end 408.005026 -204.742542)
		(width 0.12954)
		(layer "F.Cu")
		(net "M_G_CPU0_SA_DQS_DP<5>")
	)
	(segment
		(start 409.639008 -204.301852)
		(end 409.155646 -203.81849)
		(width 0.12954)
		(layer "F.Cu")
		(net "M_G_CPU0_SA_DQS_DP<5>")
	)
	(arc
		(start 393.84097 -228.227636)
		(mid 393.901643 -228.18694)
		(end 393.95654 -228.138736)
		(width 0.0762)
		(layer "F.Cu")
		(net "M_G_CPU0_SA_DQS_DP<5>")
	)
	(arc
		(start 392.192764 -228.180138)
		(mid 392.261711 -228.195135)
		(end 392.326622 -228.22281)
		(width 0.0762)
		(layer "F.Cu")
		(net "M_G_CPU0_SA_DQS_DP<5>")
	)
	(arc
		(start 393.275058 -228.227636)
		(mid 393.558014 -228.303813)
		(end 393.84097 -228.227636)
		(width 0.0762)
		(layer "F.Cu")
		(net "M_G_CPU0_SA_DQS_DP<5>")
	)
	(arc
		(start 392.909298 -228.22281)
		(mid 393.092806 -228.177316)
		(end 393.275058 -228.227636)
		(width 0.0762)
		(layer "F.Cu")
		(net "M_G_CPU0_SA_DQS_DP<5>")
	)
	(arc
		(start 392.046206 -228.374956)
		(mid 392.0634 -228.23537)
		(end 392.192764 -228.180138)
		(width 0.0762)
		(layer "F.Cu")
		(net "M_G_CPU0_SA_DQS_DP<5>")
	)
	(arc
		(start 392.335004 -228.227636)
		(mid 392.61796 -228.303813)
		(end 392.900916 -228.227636)
		(width 0.0762)
		(layer "F.Cu")
		(net "M_G_CPU0_SA_DQS_DP<5>")
	)
	(segment
		(start 395.340078 -246.549672)
		(end 395.359128 -246.549672)
		(width 0.0762)
		(layer "F.Cu")
		(net "M_G_CPU0_SA_DQS_DP<4>")
	)
	(segment
		(start 394.027914 -246.74322)
		(end 394.92809 -246.74322)
		(width 0.0762)
		(layer "F.Cu")
		(net "M_G_CPU0_SA_DQS_DP<4>")
	)
	(segment
		(start 410.856938 -237.974632)
		(end 411.242256 -237.974632)
		(width 0.12954)
		(layer "F.Cu")
		(net "M_G_CPU0_SA_DQS_DP<4>")
	)
	(segment
		(start 411.242256 -237.974632)
		(end 411.50667 -237.710218)
		(width 0.12954)
		(layer "F.Cu")
		(net "M_G_CPU0_SA_DQS_DP<4>")
	)
	(segment
		(start 414.252156 -238.026956)
		(end 414.626806 -238.026956)
		(width 0.101346)
		(layer "F.Cu")
		(net "M_G_CPU0_SA_DQS_DP<4>")
	)
	(segment
		(start 415.635948 -238.452152)
		(end 415.95294 -238.13516)
		(width 0.101346)
		(layer "F.Cu")
		(net "M_G_CPU0_SA_DQS_DP<4>")
	)
	(segment
		(start 415.95294 -238.13516)
		(end 416.468052 -238.13516)
		(width 0.101346)
		(layer "F.Cu")
		(net "M_G_CPU0_SA_DQS_DP<4>")
	)
	(segment
		(start 403.942042 -246.549672)
		(end 406.146254 -244.34546)
		(width 0.12954)
		(layer "F.Cu")
		(net "M_G_CPU0_SA_DQS_DP<4>")
	)
	(segment
		(start 413.935418 -237.710218)
		(end 414.252156 -238.026956)
		(width 0.101346)
		(layer "F.Cu")
		(net "M_G_CPU0_SA_DQS_DP<4>")
	)
	(segment
		(start 394.92809 -246.74322)
		(end 395.055598 -246.615712)
		(width 0.0762)
		(layer "F.Cu")
		(net "M_G_CPU0_SA_DQS_DP<4>")
	)
	(segment
		(start 406.146254 -242.685316)
		(end 410.856938 -237.974632)
		(width 0.12954)
		(layer "F.Cu")
		(net "M_G_CPU0_SA_DQS_DP<4>")
	)
	(segment
		(start 395.359128 -246.549672)
		(end 403.942042 -246.549672)
		(width 0.12954)
		(layer "F.Cu")
		(net "M_G_CPU0_SA_DQS_DP<4>")
	)
	(segment
		(start 414.626806 -238.026956)
		(end 415.052002 -238.452152)
		(width 0.101346)
		(layer "F.Cu")
		(net "M_G_CPU0_SA_DQS_DP<4>")
	)
	(segment
		(start 395.274038 -246.615712)
		(end 395.340078 -246.549672)
		(width 0.0762)
		(layer "F.Cu")
		(net "M_G_CPU0_SA_DQS_DP<4>")
	)
	(segment
		(start 411.50667 -237.710218)
		(end 413.935418 -237.710218)
		(width 0.101346)
		(layer "F.Cu")
		(net "M_G_CPU0_SA_DQS_DP<4>")
	)
	(segment
		(start 395.055598 -246.615712)
		(end 395.274038 -246.615712)
		(width 0.0762)
		(layer "F.Cu")
		(net "M_G_CPU0_SA_DQS_DP<4>")
	)
	(segment
		(start 415.052002 -238.452152)
		(end 415.635948 -238.452152)
		(width 0.101346)
		(layer "F.Cu")
		(net "M_G_CPU0_SA_DQS_DP<4>")
	)
	(segment
		(start 406.146254 -244.34546)
		(end 406.146254 -242.685316)
		(width 0.12954)
		(layer "F.Cu")
		(net "M_G_CPU0_SA_DQS_DP<4>")
	)
	(arc
		(start 393.996926 -246.74195)
		(mid 394.012407 -246.742906)
		(end 394.027914 -246.74322)
		(width 0.0762)
		(layer "F.Cu")
		(net "M_G_CPU0_SA_DQS_DP<4>")
	)
	(arc
		(start 393.616942 -246.619522)
		(mid 393.636291 -246.62186)
		(end 393.65555 -246.624856)
		(width 0.0762)
		(layer "F.Cu")
		(net "M_G_CPU0_SA_DQS_DP<4>")
	)
	(arc
		(start 393.84097 -246.692674)
		(mid 393.91621 -246.725987)
		(end 393.996926 -246.74195)
		(width 0.0762)
		(layer "F.Cu")
		(net "M_G_CPU0_SA_DQS_DP<4>")
	)
	(arc
		(start 393.08786 -246.370094)
		(mid 393.331291 -246.539581)
		(end 393.616942 -246.619522)
		(width 0.0762)
		(layer "F.Cu")
		(net "M_G_CPU0_SA_DQS_DP<4>")
	)
	(arc
		(start 393.65555 -246.624856)
		(mid 393.751259 -246.650568)
		(end 393.84097 -246.692674)
		(width 0.0762)
		(layer "F.Cu")
		(net "M_G_CPU0_SA_DQS_DP<4>")
	)
	(segment
		(start 413.935418 -228.360224)
		(end 414.252156 -228.676962)
		(width 0.101346)
		(layer "F.Cu")
		(net "M_G_CPU0_SA_DQS_DP<3>")
	)
	(segment
		(start 395.564868 -242.020344)
		(end 399.379186 -242.020344)
		(width 0.12954)
		(layer "F.Cu")
		(net "M_G_CPU0_SA_DQS_DP<3>")
	)
	(segment
		(start 411.242256 -228.624638)
		(end 411.50667 -228.360224)
		(width 0.12954)
		(layer "F.Cu")
		(net "M_G_CPU0_SA_DQS_DP<3>")
	)
	(segment
		(start 410.920946 -228.624638)
		(end 411.242256 -228.624638)
		(width 0.12954)
		(layer "F.Cu")
		(net "M_G_CPU0_SA_DQS_DP<3>")
	)
	(segment
		(start 399.379186 -242.020344)
		(end 404.206964 -237.192566)
		(width 0.12954)
		(layer "F.Cu")
		(net "M_G_CPU0_SA_DQS_DP<3>")
	)
	(segment
		(start 414.596326 -228.676962)
		(end 415.021522 -229.102158)
		(width 0.101346)
		(layer "F.Cu")
		(net "M_G_CPU0_SA_DQS_DP<3>")
	)
	(segment
		(start 410.592778 -229.535228)
		(end 410.592778 -228.952806)
		(width 0.12954)
		(layer "F.Cu")
		(net "M_G_CPU0_SA_DQS_DP<3>")
	)
	(segment
		(start 415.95294 -228.785166)
		(end 416.468052 -228.785166)
		(width 0.101346)
		(layer "F.Cu")
		(net "M_G_CPU0_SA_DQS_DP<3>")
	)
	(segment
		(start 404.206964 -237.192566)
		(end 405.27224 -237.192566)
		(width 0.12954)
		(layer "F.Cu")
		(net "M_G_CPU0_SA_DQS_DP<3>")
	)
	(segment
		(start 415.021522 -229.102158)
		(end 415.635948 -229.102158)
		(width 0.101346)
		(layer "F.Cu")
		(net "M_G_CPU0_SA_DQS_DP<3>")
	)
	(segment
		(start 407.044398 -233.083608)
		(end 410.592778 -229.535228)
		(width 0.12954)
		(layer "F.Cu")
		(net "M_G_CPU0_SA_DQS_DP<3>")
	)
	(segment
		(start 411.50667 -228.360224)
		(end 413.935418 -228.360224)
		(width 0.101346)
		(layer "F.Cu")
		(net "M_G_CPU0_SA_DQS_DP<3>")
	)
	(segment
		(start 395.225778 -242.086384)
		(end 395.479778 -242.086384)
		(width 0.0762)
		(layer "F.Cu")
		(net "M_G_CPU0_SA_DQS_DP<3>")
	)
	(segment
		(start 394.027914 -241.883184)
		(end 395.022578 -241.883184)
		(width 0.0762)
		(layer "F.Cu")
		(net "M_G_CPU0_SA_DQS_DP<3>")
	)
	(segment
		(start 414.252156 -228.676962)
		(end 414.596326 -228.676962)
		(width 0.101346)
		(layer "F.Cu")
		(net "M_G_CPU0_SA_DQS_DP<3>")
	)
	(segment
		(start 395.545818 -242.020344)
		(end 395.564868 -242.020344)
		(width 0.0762)
		(layer "F.Cu")
		(net "M_G_CPU0_SA_DQS_DP<3>")
	)
	(segment
		(start 395.479778 -242.086384)
		(end 395.545818 -242.020344)
		(width 0.0762)
		(layer "F.Cu")
		(net "M_G_CPU0_SA_DQS_DP<3>")
	)
	(segment
		(start 405.27224 -237.192566)
		(end 407.044398 -235.420408)
		(width 0.12954)
		(layer "F.Cu")
		(net "M_G_CPU0_SA_DQS_DP<3>")
	)
	(segment
		(start 410.592778 -228.952806)
		(end 410.920946 -228.624638)
		(width 0.12954)
		(layer "F.Cu")
		(net "M_G_CPU0_SA_DQS_DP<3>")
	)
	(segment
		(start 407.044398 -235.420408)
		(end 407.044398 -233.083608)
		(width 0.12954)
		(layer "F.Cu")
		(net "M_G_CPU0_SA_DQS_DP<3>")
	)
	(segment
		(start 395.022578 -241.883184)
		(end 395.225778 -242.086384)
		(width 0.0762)
		(layer "F.Cu")
		(net "M_G_CPU0_SA_DQS_DP<3>")
	)
	(segment
		(start 415.635948 -229.102158)
		(end 415.95294 -228.785166)
		(width 0.101346)
		(layer "F.Cu")
		(net "M_G_CPU0_SA_DQS_DP<3>")
	)
	(arc
		(start 393.84097 -241.832638)
		(mid 393.91621 -241.865951)
		(end 393.996926 -241.881914)
		(width 0.0762)
		(layer "F.Cu")
		(net "M_G_CPU0_SA_DQS_DP<3>")
	)
	(arc
		(start 393.65555 -241.76482)
		(mid 393.751259 -241.790532)
		(end 393.84097 -241.832638)
		(width 0.0762)
		(layer "F.Cu")
		(net "M_G_CPU0_SA_DQS_DP<3>")
	)
	(arc
		(start 393.616942 -241.759486)
		(mid 393.636291 -241.761824)
		(end 393.65555 -241.76482)
		(width 0.0762)
		(layer "F.Cu")
		(net "M_G_CPU0_SA_DQS_DP<3>")
	)
	(arc
		(start 393.08786 -241.510058)
		(mid 393.331291 -241.679545)
		(end 393.616942 -241.759486)
		(width 0.0762)
		(layer "F.Cu")
		(net "M_G_CPU0_SA_DQS_DP<3>")
	)
	(arc
		(start 393.996926 -241.881914)
		(mid 394.012407 -241.88287)
		(end 394.027914 -241.883184)
		(width 0.0762)
		(layer "F.Cu")
		(net "M_G_CPU0_SA_DQS_DP<3>")
	)
	(segment
		(start 407.365962 -222.817944)
		(end 407.574496 -222.60941)
		(width 0.12954)
		(layer "F.Cu")
		(net "M_G_CPU0_SA_DQS_DP<2>")
	)
	(segment
		(start 415.635948 -219.752164)
		(end 415.95294 -219.435172)
		(width 0.101346)
		(layer "F.Cu")
		(net "M_G_CPU0_SA_DQS_DP<2>")
	)
	(segment
		(start 395.419326 -237.07217)
		(end 395.438376 -237.07217)
		(width 0.0762)
		(layer "F.Cu")
		(net "M_G_CPU0_SA_DQS_DP<2>")
	)
	(segment
		(start 406.077928 -227.83673)
		(end 406.077928 -224.105978)
		(width 0.12954)
		(layer "F.Cu")
		(net "M_G_CPU0_SA_DQS_DP<2>")
	)
	(segment
		(start 407.574496 -222.60941)
		(end 407.574496 -222.191834)
		(width 0.12954)
		(layer "F.Cu")
		(net "M_G_CPU0_SA_DQS_DP<2>")
	)
	(segment
		(start 415.95294 -219.435172)
		(end 416.468052 -219.435172)
		(width 0.101346)
		(layer "F.Cu")
		(net "M_G_CPU0_SA_DQS_DP<2>")
	)
	(segment
		(start 406.437846 -223.252284)
		(end 406.872186 -222.817944)
		(width 0.12954)
		(layer "F.Cu")
		(net "M_G_CPU0_SA_DQS_DP<2>")
	)
	(segment
		(start 408.085036 -221.681294)
		(end 408.502612 -221.681294)
		(width 0.12954)
		(layer "F.Cu")
		(net "M_G_CPU0_SA_DQS_DP<2>")
	)
	(segment
		(start 406.437846 -223.74606)
		(end 406.437846 -223.252284)
		(width 0.12954)
		(layer "F.Cu")
		(net "M_G_CPU0_SA_DQS_DP<2>")
	)
	(segment
		(start 409.847796 -219.806774)
		(end 410.379926 -219.274644)
		(width 0.12954)
		(layer "F.Cu")
		(net "M_G_CPU0_SA_DQS_DP<2>")
	)
	(segment
		(start 408.502612 -221.681294)
		(end 408.711146 -221.47276)
		(width 0.12954)
		(layer "F.Cu")
		(net "M_G_CPU0_SA_DQS_DP<2>")
	)
	(segment
		(start 395.353286 -237.13821)
		(end 395.419326 -237.07217)
		(width 0.0762)
		(layer "F.Cu")
		(net "M_G_CPU0_SA_DQS_DP<2>")
	)
	(segment
		(start 410.379926 -219.274644)
		(end 411.242256 -219.274644)
		(width 0.12954)
		(layer "F.Cu")
		(net "M_G_CPU0_SA_DQS_DP<2>")
	)
	(segment
		(start 394.027914 -237.023148)
		(end 394.975334 -237.023148)
		(width 0.0762)
		(layer "F.Cu")
		(net "M_G_CPU0_SA_DQS_DP<2>")
	)
	(segment
		(start 394.975334 -237.023148)
		(end 395.090396 -237.13821)
		(width 0.0762)
		(layer "F.Cu")
		(net "M_G_CPU0_SA_DQS_DP<2>")
	)
	(segment
		(start 407.574496 -222.191834)
		(end 408.085036 -221.681294)
		(width 0.12954)
		(layer "F.Cu")
		(net "M_G_CPU0_SA_DQS_DP<2>")
	)
	(segment
		(start 408.711146 -221.052644)
		(end 409.219146 -220.544644)
		(width 0.12954)
		(layer "F.Cu")
		(net "M_G_CPU0_SA_DQS_DP<2>")
	)
	(segment
		(start 409.639262 -220.544644)
		(end 409.847796 -220.33611)
		(width 0.12954)
		(layer "F.Cu")
		(net "M_G_CPU0_SA_DQS_DP<2>")
	)
	(segment
		(start 409.847796 -220.33611)
		(end 409.847796 -219.806774)
		(width 0.12954)
		(layer "F.Cu")
		(net "M_G_CPU0_SA_DQS_DP<2>")
	)
	(segment
		(start 414.252156 -219.326968)
		(end 414.626298 -219.326968)
		(width 0.101346)
		(layer "F.Cu")
		(net "M_G_CPU0_SA_DQS_DP<2>")
	)
	(segment
		(start 413.935418 -219.01023)
		(end 414.252156 -219.326968)
		(width 0.101346)
		(layer "F.Cu")
		(net "M_G_CPU0_SA_DQS_DP<2>")
	)
	(segment
		(start 396.842488 -237.07217)
		(end 406.077928 -227.83673)
		(width 0.12954)
		(layer "F.Cu")
		(net "M_G_CPU0_SA_DQS_DP<2>")
	)
	(segment
		(start 411.50667 -219.01023)
		(end 413.935418 -219.01023)
		(width 0.101346)
		(layer "F.Cu")
		(net "M_G_CPU0_SA_DQS_DP<2>")
	)
	(segment
		(start 409.219146 -220.544644)
		(end 409.639262 -220.544644)
		(width 0.12954)
		(layer "F.Cu")
		(net "M_G_CPU0_SA_DQS_DP<2>")
	)
	(segment
		(start 411.242256 -219.274644)
		(end 411.50667 -219.01023)
		(width 0.12954)
		(layer "F.Cu")
		(net "M_G_CPU0_SA_DQS_DP<2>")
	)
	(segment
		(start 395.438376 -237.07217)
		(end 396.842488 -237.07217)
		(width 0.12954)
		(layer "F.Cu")
		(net "M_G_CPU0_SA_DQS_DP<2>")
	)
	(segment
		(start 414.626298 -219.326968)
		(end 415.051494 -219.752164)
		(width 0.101346)
		(layer "F.Cu")
		(net "M_G_CPU0_SA_DQS_DP<2>")
	)
	(segment
		(start 408.711146 -221.47276)
		(end 408.711146 -221.052644)
		(width 0.12954)
		(layer "F.Cu")
		(net "M_G_CPU0_SA_DQS_DP<2>")
	)
	(segment
		(start 415.051494 -219.752164)
		(end 415.635948 -219.752164)
		(width 0.101346)
		(layer "F.Cu")
		(net "M_G_CPU0_SA_DQS_DP<2>")
	)
	(segment
		(start 406.872186 -222.817944)
		(end 407.365962 -222.817944)
		(width 0.12954)
		(layer "F.Cu")
		(net "M_G_CPU0_SA_DQS_DP<2>")
	)
	(segment
		(start 395.090396 -237.13821)
		(end 395.353286 -237.13821)
		(width 0.0762)
		(layer "F.Cu")
		(net "M_G_CPU0_SA_DQS_DP<2>")
	)
	(segment
		(start 406.077928 -224.105978)
		(end 406.437846 -223.74606)
		(width 0.12954)
		(layer "F.Cu")
		(net "M_G_CPU0_SA_DQS_DP<2>")
	)
	(arc
		(start 393.08786 -236.650022)
		(mid 393.331291 -236.819509)
		(end 393.616942 -236.89945)
		(width 0.0762)
		(layer "F.Cu")
		(net "M_G_CPU0_SA_DQS_DP<2>")
	)
	(arc
		(start 393.996926 -237.021878)
		(mid 394.012407 -237.022834)
		(end 394.027914 -237.023148)
		(width 0.0762)
		(layer "F.Cu")
		(net "M_G_CPU0_SA_DQS_DP<2>")
	)
	(arc
		(start 393.616942 -236.89945)
		(mid 393.636291 -236.901788)
		(end 393.65555 -236.904784)
		(width 0.0762)
		(layer "F.Cu")
		(net "M_G_CPU0_SA_DQS_DP<2>")
	)
	(arc
		(start 393.65555 -236.904784)
		(mid 393.751259 -236.930496)
		(end 393.84097 -236.972602)
		(width 0.0762)
		(layer "F.Cu")
		(net "M_G_CPU0_SA_DQS_DP<2>")
	)
	(arc
		(start 393.84097 -236.972602)
		(mid 393.91621 -237.005915)
		(end 393.996926 -237.021878)
		(width 0.0762)
		(layer "F.Cu")
		(net "M_G_CPU0_SA_DQS_DP<2>")
	)
	(segment
		(start 401.634198 -219.526104)
		(end 402.770848 -218.389454)
		(width 0.12954)
		(layer "F.Cu")
		(net "M_G_CPU0_SA_DQS_DP<1>")
	)
	(segment
		(start 395.827758 -231.830372)
		(end 401.634198 -226.023932)
		(width 0.12954)
		(layer "F.Cu")
		(net "M_G_CPU0_SA_DQS_DP<1>")
	)
	(segment
		(start 406.003252 -215.15705)
		(end 406.237694 -214.922608)
		(width 0.12954)
		(layer "F.Cu")
		(net "M_G_CPU0_SA_DQS_DP<1>")
	)
	(segment
		(start 405.41194 -215.15705)
		(end 406.003252 -215.15705)
		(width 0.12954)
		(layer "F.Cu")
		(net "M_G_CPU0_SA_DQS_DP<1>")
	)
	(segment
		(start 395.139418 -231.896412)
		(end 395.583918 -231.896412)
		(width 0.0762)
		(layer "F.Cu")
		(net "M_G_CPU0_SA_DQS_DP<1>")
	)
	(segment
		(start 411.211776 -209.95513)
		(end 411.50667 -209.660236)
		(width 0.12954)
		(layer "F.Cu")
		(net "M_G_CPU0_SA_DQS_DP<1>")
	)
	(segment
		(start 415.635948 -210.40217)
		(end 415.95294 -210.085178)
		(width 0.101346)
		(layer "F.Cu")
		(net "M_G_CPU0_SA_DQS_DP<1>")
	)
	(segment
		(start 395.649958 -231.830372)
		(end 395.669008 -231.830372)
		(width 0.0762)
		(layer "F.Cu")
		(net "M_G_CPU0_SA_DQS_DP<1>")
	)
	(segment
		(start 394.027914 -232.163112)
		(end 394.872718 -232.163112)
		(width 0.0762)
		(layer "F.Cu")
		(net "M_G_CPU0_SA_DQS_DP<1>")
	)
	(segment
		(start 405.044148 -216.116154)
		(end 405.044148 -215.524842)
		(width 0.12954)
		(layer "F.Cu")
		(net "M_G_CPU0_SA_DQS_DP<1>")
	)
	(segment
		(start 414.636458 -209.976974)
		(end 415.061654 -210.40217)
		(width 0.101346)
		(layer "F.Cu")
		(net "M_G_CPU0_SA_DQS_DP<1>")
	)
	(segment
		(start 403.729952 -217.43035)
		(end 403.907498 -217.252804)
		(width 0.12954)
		(layer "F.Cu")
		(net "M_G_CPU0_SA_DQS_DP<1>")
	)
	(segment
		(start 395.583918 -231.896412)
		(end 395.649958 -231.830372)
		(width 0.0762)
		(layer "F.Cu")
		(net "M_G_CPU0_SA_DQS_DP<1>")
	)
	(segment
		(start 415.95294 -210.085178)
		(end 416.468052 -210.085178)
		(width 0.101346)
		(layer "F.Cu")
		(net "M_G_CPU0_SA_DQS_DP<1>")
	)
	(segment
		(start 394.872718 -232.163112)
		(end 395.139418 -231.896412)
		(width 0.0762)
		(layer "F.Cu")
		(net "M_G_CPU0_SA_DQS_DP<1>")
	)
	(segment
		(start 405.044148 -215.524842)
		(end 405.41194 -215.15705)
		(width 0.12954)
		(layer "F.Cu")
		(net "M_G_CPU0_SA_DQS_DP<1>")
	)
	(segment
		(start 402.770848 -217.798142)
		(end 403.13864 -217.43035)
		(width 0.12954)
		(layer "F.Cu")
		(net "M_G_CPU0_SA_DQS_DP<1>")
	)
	(segment
		(start 415.061654 -210.40217)
		(end 415.635948 -210.40217)
		(width 0.101346)
		(layer "F.Cu")
		(net "M_G_CPU0_SA_DQS_DP<1>")
	)
	(segment
		(start 406.237694 -214.922608)
		(end 406.237694 -213.280752)
		(width 0.12954)
		(layer "F.Cu")
		(net "M_G_CPU0_SA_DQS_DP<1>")
	)
	(segment
		(start 403.907498 -216.661492)
		(end 404.27529 -216.2937)
		(width 0.12954)
		(layer "F.Cu")
		(net "M_G_CPU0_SA_DQS_DP<1>")
	)
	(segment
		(start 404.866602 -216.2937)
		(end 405.044148 -216.116154)
		(width 0.12954)
		(layer "F.Cu")
		(net "M_G_CPU0_SA_DQS_DP<1>")
	)
	(segment
		(start 413.935418 -209.660236)
		(end 414.252156 -209.976974)
		(width 0.101346)
		(layer "F.Cu")
		(net "M_G_CPU0_SA_DQS_DP<1>")
	)
	(segment
		(start 414.252156 -209.976974)
		(end 414.636458 -209.976974)
		(width 0.101346)
		(layer "F.Cu")
		(net "M_G_CPU0_SA_DQS_DP<1>")
	)
	(segment
		(start 409.563316 -209.95513)
		(end 411.211776 -209.95513)
		(width 0.12954)
		(layer "F.Cu")
		(net "M_G_CPU0_SA_DQS_DP<1>")
	)
	(segment
		(start 411.50667 -209.660236)
		(end 413.935418 -209.660236)
		(width 0.101346)
		(layer "F.Cu")
		(net "M_G_CPU0_SA_DQS_DP<1>")
	)
	(segment
		(start 403.907498 -217.252804)
		(end 403.907498 -216.661492)
		(width 0.12954)
		(layer "F.Cu")
		(net "M_G_CPU0_SA_DQS_DP<1>")
	)
	(segment
		(start 402.770848 -218.389454)
		(end 402.770848 -217.798142)
		(width 0.12954)
		(layer "F.Cu")
		(net "M_G_CPU0_SA_DQS_DP<1>")
	)
	(segment
		(start 403.13864 -217.43035)
		(end 403.729952 -217.43035)
		(width 0.12954)
		(layer "F.Cu")
		(net "M_G_CPU0_SA_DQS_DP<1>")
	)
	(segment
		(start 401.634198 -226.023932)
		(end 401.634198 -219.526104)
		(width 0.12954)
		(layer "F.Cu")
		(net "M_G_CPU0_SA_DQS_DP<1>")
	)
	(segment
		(start 395.669008 -231.830372)
		(end 395.827758 -231.830372)
		(width 0.12954)
		(layer "F.Cu")
		(net "M_G_CPU0_SA_DQS_DP<1>")
	)
	(segment
		(start 406.237694 -213.280752)
		(end 409.563316 -209.95513)
		(width 0.12954)
		(layer "F.Cu")
		(net "M_G_CPU0_SA_DQS_DP<1>")
	)
	(segment
		(start 404.27529 -216.2937)
		(end 404.866602 -216.2937)
		(width 0.12954)
		(layer "F.Cu")
		(net "M_G_CPU0_SA_DQS_DP<1>")
	)
	(arc
		(start 393.65555 -232.044748)
		(mid 393.751259 -232.07046)
		(end 393.84097 -232.112566)
		(width 0.0762)
		(layer "F.Cu")
		(net "M_G_CPU0_SA_DQS_DP<1>")
	)
	(arc
		(start 393.08786 -231.789986)
		(mid 393.331291 -231.959473)
		(end 393.616942 -232.039414)
		(width 0.0762)
		(layer "F.Cu")
		(net "M_G_CPU0_SA_DQS_DP<1>")
	)
	(arc
		(start 393.616942 -232.039414)
		(mid 393.636291 -232.041752)
		(end 393.65555 -232.044748)
		(width 0.0762)
		(layer "F.Cu")
		(net "M_G_CPU0_SA_DQS_DP<1>")
	)
	(arc
		(start 393.84097 -232.112566)
		(mid 393.91621 -232.145879)
		(end 393.996926 -232.161842)
		(width 0.0762)
		(layer "F.Cu")
		(net "M_G_CPU0_SA_DQS_DP<1>")
	)
	(arc
		(start 393.996926 -232.161842)
		(mid 394.012407 -232.162798)
		(end 394.027914 -232.163112)
		(width 0.0762)
		(layer "F.Cu")
		(net "M_G_CPU0_SA_DQS_DP<1>")
	)
	(segment
		(start 396.993618 -215.085168)
		(end 405.256238 -206.822548)
		(width 0.12954)
		(layer "F.Cu")
		(net "M_G_CPU0_SA_DQS_DP<0>")
	)
	(segment
		(start 413.935418 -200.310242)
		(end 414.252156 -200.62698)
		(width 0.101346)
		(layer "F.Cu")
		(net "M_G_CPU0_SA_DQS_DP<0>")
	)
	(segment
		(start 414.611058 -200.62698)
		(end 415.036254 -201.052176)
		(width 0.101346)
		(layer "F.Cu")
		(net "M_G_CPU0_SA_DQS_DP<0>")
	)
	(segment
		(start 405.256238 -205.808072)
		(end 410.489654 -200.574656)
		(width 0.12954)
		(layer "F.Cu")
		(net "M_G_CPU0_SA_DQS_DP<0>")
	)
	(segment
		(start 394.027914 -227.30333)
		(end 394.21181 -227.30333)
		(width 0.0762)
		(layer "F.Cu")
		(net "M_G_CPU0_SA_DQS_DP<0>")
	)
	(segment
		(start 394.900658 -226.470718)
		(end 395.380972 -225.990404)
		(width 0.0762)
		(layer "F.Cu")
		(net "M_G_CPU0_SA_DQS_DP<0>")
	)
	(segment
		(start 394.463016 -227.19919)
		(end 394.900658 -226.761548)
		(width 0.0762)
		(layer "F.Cu")
		(net "M_G_CPU0_SA_DQS_DP<0>")
	)
	(segment
		(start 415.036254 -201.052176)
		(end 415.635948 -201.052176)
		(width 0.101346)
		(layer "F.Cu")
		(net "M_G_CPU0_SA_DQS_DP<0>")
	)
	(segment
		(start 411.50667 -200.310242)
		(end 413.935418 -200.310242)
		(width 0.101346)
		(layer "F.Cu")
		(net "M_G_CPU0_SA_DQS_DP<0>")
	)
	(segment
		(start 394.900658 -226.761548)
		(end 394.900658 -226.470718)
		(width 0.0762)
		(layer "F.Cu")
		(net "M_G_CPU0_SA_DQS_DP<0>")
	)
	(segment
		(start 405.256238 -206.822548)
		(end 405.256238 -205.808072)
		(width 0.12954)
		(layer "F.Cu")
		(net "M_G_CPU0_SA_DQS_DP<0>")
	)
	(segment
		(start 395.39418 -225.88347)
		(end 396.993618 -224.284032)
		(width 0.12954)
		(layer "F.Cu")
		(net "M_G_CPU0_SA_DQS_DP<0>")
	)
	(segment
		(start 411.242256 -200.574656)
		(end 411.50667 -200.310242)
		(width 0.12954)
		(layer "F.Cu")
		(net "M_G_CPU0_SA_DQS_DP<0>")
	)
	(segment
		(start 415.95294 -200.735184)
		(end 416.468052 -200.735184)
		(width 0.101346)
		(layer "F.Cu")
		(net "M_G_CPU0_SA_DQS_DP<0>")
	)
	(segment
		(start 394.21181 -227.30333)
		(end 394.463016 -227.19919)
		(width 0.0762)
		(layer "F.Cu")
		(net "M_G_CPU0_SA_DQS_DP<0>")
	)
	(segment
		(start 395.380972 -225.990404)
		(end 395.380718 -225.896932)
		(width 0.0762)
		(layer "F.Cu")
		(net "M_G_CPU0_SA_DQS_DP<0>")
	)
	(segment
		(start 396.993618 -224.284032)
		(end 396.993618 -215.085168)
		(width 0.12954)
		(layer "F.Cu")
		(net "M_G_CPU0_SA_DQS_DP<0>")
	)
	(segment
		(start 410.489654 -200.574656)
		(end 411.242256 -200.574656)
		(width 0.12954)
		(layer "F.Cu")
		(net "M_G_CPU0_SA_DQS_DP<0>")
	)
	(segment
		(start 395.380718 -225.896932)
		(end 395.39418 -225.88347)
		(width 0.0762)
		(layer "F.Cu")
		(net "M_G_CPU0_SA_DQS_DP<0>")
	)
	(segment
		(start 414.252156 -200.62698)
		(end 414.611058 -200.62698)
		(width 0.101346)
		(layer "F.Cu")
		(net "M_G_CPU0_SA_DQS_DP<0>")
	)
	(segment
		(start 415.635948 -201.052176)
		(end 415.95294 -200.735184)
		(width 0.101346)
		(layer "F.Cu")
		(net "M_G_CPU0_SA_DQS_DP<0>")
	)
	(arc
		(start 393.65555 -227.184966)
		(mid 393.751259 -227.210678)
		(end 393.84097 -227.252784)
		(width 0.0762)
		(layer "F.Cu")
		(net "M_G_CPU0_SA_DQS_DP<0>")
	)
	(arc
		(start 393.84097 -227.252784)
		(mid 393.91621 -227.286097)
		(end 393.996926 -227.30206)
		(width 0.0762)
		(layer "F.Cu")
		(net "M_G_CPU0_SA_DQS_DP<0>")
	)
	(arc
		(start 393.616942 -227.179632)
		(mid 393.636291 -227.18197)
		(end 393.65555 -227.184966)
		(width 0.0762)
		(layer "F.Cu")
		(net "M_G_CPU0_SA_DQS_DP<0>")
	)
	(arc
		(start 393.996926 -227.30206)
		(mid 394.012407 -227.303016)
		(end 394.027914 -227.30333)
		(width 0.0762)
		(layer "F.Cu")
		(net "M_G_CPU0_SA_DQS_DP<0>")
	)
	(arc
		(start 393.08786 -226.930204)
		(mid 393.331291 -227.099691)
		(end 393.616942 -227.179632)
		(width 0.0762)
		(layer "F.Cu")
		(net "M_G_CPU0_SA_DQS_DP<0>")
	)
	(segment
		(start 410.431742 -240.680748)
		(end 410.625798 -240.486692)
		(width 0.12954)
		(layer "F.Cu")
		(net "M_G_CPU0_SA_DQS_DN<9>")
	)
	(segment
		(start 411.809946 -238.985044)
		(end 412.367984 -238.985044)
		(width 0.12954)
		(layer "F.Cu")
		(net "M_G_CPU0_SA_DQS_DN<9>")
	)
	(segment
		(start 409.163774 -241.205512)
		(end 409.163774 -240.739676)
		(width 0.12954)
		(layer "F.Cu")
		(net "M_G_CPU0_SA_DQS_DN<9>")
	)
	(segment
		(start 408.027124 -241.876326)
		(end 408.358086 -241.545364)
		(width 0.12954)
		(layer "F.Cu")
		(net "M_G_CPU0_SA_DQS_DN<9>")
	)
	(segment
		(start 394.027914 -247.42648)
		(end 394.489178 -247.42648)
		(width 0.0762)
		(layer "F.Cu")
		(net "M_G_CPU0_SA_DQS_DN<9>")
	)
	(segment
		(start 407.687272 -242.682014)
		(end 407.959306 -242.954048)
		(width 0.12954)
		(layer "F.Cu")
		(net "M_G_CPU0_SA_DQS_DN<9>")
	)
	(segment
		(start 408.299158 -242.614196)
		(end 408.027124 -242.342162)
		(width 0.12954)
		(layer "F.Cu")
		(net "M_G_CPU0_SA_DQS_DN<9>")
	)
	(segment
		(start 408.358086 -241.545364)
		(end 408.823922 -241.545364)
		(width 0.12954)
		(layer "F.Cu")
		(net "M_G_CPU0_SA_DQS_DN<9>")
	)
	(segment
		(start 410.625798 -240.486692)
		(end 410.625798 -239.643412)
		(width 0.12954)
		(layer "F.Cu")
		(net "M_G_CPU0_SA_DQS_DN<9>")
	)
	(segment
		(start 393.736576 -247.507506)
		(end 393.744958 -247.50268)
		(width 0.0762)
		(layer "F.Cu")
		(net "M_G_CPU0_SA_DQS_DN<9>")
	)
	(segment
		(start 409.095956 -241.817398)
		(end 409.295092 -241.817398)
		(width 0.12954)
		(layer "F.Cu")
		(net "M_G_CPU0_SA_DQS_DN<9>")
	)
	(segment
		(start 411.54604 -239.24895)
		(end 411.809946 -238.985044)
		(width 0.12954)
		(layer "F.Cu")
		(net "M_G_CPU0_SA_DQS_DN<9>")
	)
	(segment
		(start 407.162508 -243.750846)
		(end 406.890474 -243.478812)
		(width 0.12954)
		(layer "F.Cu")
		(net "M_G_CPU0_SA_DQS_DN<9>")
	)
	(segment
		(start 410.232606 -240.680748)
		(end 410.431742 -240.680748)
		(width 0.12954)
		(layer "F.Cu")
		(net "M_G_CPU0_SA_DQS_DN<9>")
	)
	(segment
		(start 409.295092 -241.817398)
		(end 409.435808 -241.676682)
		(width 0.12954)
		(layer "F.Cu")
		(net "M_G_CPU0_SA_DQS_DN<9>")
	)
	(segment
		(start 395.336776 -247.3198)
		(end 395.355826 -247.3198)
		(width 0.0762)
		(layer "F.Cu")
		(net "M_G_CPU0_SA_DQS_DN<9>")
	)
	(segment
		(start 395.270736 -247.38584)
		(end 395.336776 -247.3198)
		(width 0.0762)
		(layer "F.Cu")
		(net "M_G_CPU0_SA_DQS_DN<9>")
	)
	(segment
		(start 394.489178 -247.42648)
		(end 394.529818 -247.38584)
		(width 0.0762)
		(layer "F.Cu")
		(net "M_G_CPU0_SA_DQS_DN<9>")
	)
	(segment
		(start 407.221436 -242.682014)
		(end 407.687272 -242.682014)
		(width 0.12954)
		(layer "F.Cu")
		(net "M_G_CPU0_SA_DQS_DN<9>")
	)
	(segment
		(start 407.959306 -242.954048)
		(end 408.158442 -242.954048)
		(width 0.12954)
		(layer "F.Cu")
		(net "M_G_CPU0_SA_DQS_DN<9>")
	)
	(segment
		(start 409.163774 -240.739676)
		(end 409.494736 -240.408714)
		(width 0.12954)
		(layer "F.Cu")
		(net "M_G_CPU0_SA_DQS_DN<9>")
	)
	(segment
		(start 411.02026 -239.24895)
		(end 411.54604 -239.24895)
		(width 0.12954)
		(layer "F.Cu")
		(net "M_G_CPU0_SA_DQS_DN<9>")
	)
	(segment
		(start 406.890474 -243.012976)
		(end 407.221436 -242.682014)
		(width 0.12954)
		(layer "F.Cu")
		(net "M_G_CPU0_SA_DQS_DN<9>")
	)
	(segment
		(start 394.529818 -247.38584)
		(end 395.270736 -247.38584)
		(width 0.0762)
		(layer "F.Cu")
		(net "M_G_CPU0_SA_DQS_DN<9>")
	)
	(segment
		(start 410.625798 -239.643412)
		(end 411.02026 -239.24895)
		(width 0.12954)
		(layer "F.Cu")
		(net "M_G_CPU0_SA_DQS_DN<9>")
	)
	(segment
		(start 408.158442 -242.954048)
		(end 408.299158 -242.813332)
		(width 0.12954)
		(layer "F.Cu")
		(net "M_G_CPU0_SA_DQS_DN<9>")
	)
	(segment
		(start 409.435808 -241.477546)
		(end 409.163774 -241.205512)
		(width 0.12954)
		(layer "F.Cu")
		(net "M_G_CPU0_SA_DQS_DN<9>")
	)
	(segment
		(start 409.494736 -240.408714)
		(end 409.960572 -240.408714)
		(width 0.12954)
		(layer "F.Cu")
		(net "M_G_CPU0_SA_DQS_DN<9>")
	)
	(segment
		(start 404.224998 -247.3198)
		(end 407.162508 -244.38229)
		(width 0.12954)
		(layer "F.Cu")
		(net "M_G_CPU0_SA_DQS_DN<9>")
	)
	(segment
		(start 408.823922 -241.545364)
		(end 409.095956 -241.817398)
		(width 0.12954)
		(layer "F.Cu")
		(net "M_G_CPU0_SA_DQS_DN<9>")
	)
	(segment
		(start 407.162508 -244.38229)
		(end 407.162508 -243.750846)
		(width 0.12954)
		(layer "F.Cu")
		(net "M_G_CPU0_SA_DQS_DN<9>")
	)
	(segment
		(start 408.027124 -242.342162)
		(end 408.027124 -241.876326)
		(width 0.12954)
		(layer "F.Cu")
		(net "M_G_CPU0_SA_DQS_DN<9>")
	)
	(segment
		(start 408.299158 -242.813332)
		(end 408.299158 -242.614196)
		(width 0.12954)
		(layer "F.Cu")
		(net "M_G_CPU0_SA_DQS_DN<9>")
	)
	(segment
		(start 409.960572 -240.408714)
		(end 410.232606 -240.680748)
		(width 0.12954)
		(layer "F.Cu")
		(net "M_G_CPU0_SA_DQS_DN<9>")
	)
	(segment
		(start 409.435808 -241.676682)
		(end 409.435808 -241.477546)
		(width 0.12954)
		(layer "F.Cu")
		(net "M_G_CPU0_SA_DQS_DN<9>")
	)
	(segment
		(start 406.890474 -243.478812)
		(end 406.890474 -243.012976)
		(width 0.12954)
		(layer "F.Cu")
		(net "M_G_CPU0_SA_DQS_DN<9>")
	)
	(segment
		(start 395.355826 -247.3198)
		(end 404.224998 -247.3198)
		(width 0.12954)
		(layer "F.Cu")
		(net "M_G_CPU0_SA_DQS_DN<9>")
	)
	(arc
		(start 392.192256 -247.428004)
		(mid 392.204079 -247.429021)
		(end 392.215878 -247.43029)
		(width 0.0762)
		(layer "F.Cu")
		(net "M_G_CPU0_SA_DQS_DN<9>")
	)
	(arc
		(start 392.431016 -247.50268)
		(mid 392.61796 -247.552935)
		(end 392.804904 -247.50268)
		(width 0.0762)
		(layer "F.Cu")
		(net "M_G_CPU0_SA_DQS_DN<9>")
	)
	(arc
		(start 392.215878 -247.43029)
		(mid 392.327124 -247.455553)
		(end 392.431016 -247.50268)
		(width 0.0762)
		(layer "F.Cu")
		(net "M_G_CPU0_SA_DQS_DN<9>")
	)
	(arc
		(start 393.370816 -247.50268)
		(mid 393.553067 -247.55303)
		(end 393.736576 -247.507506)
		(width 0.0762)
		(layer "F.Cu")
		(net "M_G_CPU0_SA_DQS_DN<9>")
	)
	(arc
		(start 392.804904 -247.50268)
		(mid 393.08786 -247.426503)
		(end 393.370816 -247.50268)
		(width 0.0762)
		(layer "F.Cu")
		(net "M_G_CPU0_SA_DQS_DN<9>")
	)
	(arc
		(start 393.744958 -247.50268)
		(mid 393.881394 -247.445855)
		(end 394.027914 -247.42648)
		(width 0.0762)
		(layer "F.Cu")
		(net "M_G_CPU0_SA_DQS_DN<9>")
	)
	(arc
		(start 391.677906 -247.1801)
		(mid 391.911904 -247.352143)
		(end 392.192256 -247.428004)
		(width 0.0762)
		(layer "F.Cu")
		(net "M_G_CPU0_SA_DQS_DN<9>")
	)
	(segment
		(start 411.30474 -229.898956)
		(end 411.54604 -229.898956)
		(width 0.12954)
		(layer "F.Cu")
		(net "M_G_CPU0_SA_DQS_DN<8>")
	)
	(segment
		(start 394.904976 -242.566444)
		(end 395.260322 -242.92179)
		(width 0.0762)
		(layer "F.Cu")
		(net "M_G_CPU0_SA_DQS_DN<8>")
	)
	(segment
		(start 405.625046 -237.936786)
		(end 408.674824 -234.887008)
		(width 0.12954)
		(layer "F.Cu")
		(net "M_G_CPU0_SA_DQS_DN<8>")
	)
	(segment
		(start 409.313888 -233.735372)
		(end 409.512008 -233.735372)
		(width 0.12954)
		(layer "F.Cu")
		(net "M_G_CPU0_SA_DQS_DN<8>")
	)
	(segment
		(start 407.828242 -233.375454)
		(end 408.15768 -233.046016)
		(width 0.12954)
		(layer "F.Cu")
		(net "M_G_CPU0_SA_DQS_DN<8>")
	)
	(segment
		(start 409.654248 -233.593132)
		(end 409.654248 -233.395012)
		(width 0.12954)
		(layer "F.Cu")
		(net "M_G_CPU0_SA_DQS_DN<8>")
	)
	(segment
		(start 411.54604 -229.898956)
		(end 411.809946 -229.63505)
		(width 0.12954)
		(layer "F.Cu")
		(net "M_G_CPU0_SA_DQS_DN<8>")
	)
	(segment
		(start 395.53007 -242.92179)
		(end 395.59611 -242.85575)
		(width 0.0762)
		(layer "F.Cu")
		(net "M_G_CPU0_SA_DQS_DN<8>")
	)
	(segment
		(start 395.260322 -242.92179)
		(end 395.53007 -242.92179)
		(width 0.0762)
		(layer "F.Cu")
		(net "M_G_CPU0_SA_DQS_DN<8>")
	)
	(segment
		(start 407.828242 -233.842306)
		(end 407.828242 -233.375454)
		(width 0.12954)
		(layer "F.Cu")
		(net "M_G_CPU0_SA_DQS_DN<8>")
	)
	(segment
		(start 409.654248 -233.395012)
		(end 408.964892 -232.705656)
		(width 0.12954)
		(layer "F.Cu")
		(net "M_G_CPU0_SA_DQS_DN<8>")
	)
	(segment
		(start 395.61516 -242.85575)
		(end 399.59661 -242.85575)
		(width 0.12954)
		(layer "F.Cu")
		(net "M_G_CPU0_SA_DQS_DN<8>")
	)
	(segment
		(start 411.809946 -229.63505)
		(end 412.367984 -229.63505)
		(width 0.12954)
		(layer "F.Cu")
		(net "M_G_CPU0_SA_DQS_DN<8>")
	)
	(segment
		(start 409.512008 -233.735372)
		(end 409.654248 -233.593132)
		(width 0.12954)
		(layer "F.Cu")
		(net "M_G_CPU0_SA_DQS_DN<8>")
	)
	(segment
		(start 404.515574 -237.936786)
		(end 405.625046 -237.936786)
		(width 0.12954)
		(layer "F.Cu")
		(net "M_G_CPU0_SA_DQS_DN<8>")
	)
	(segment
		(start 408.674824 -234.688888)
		(end 407.828242 -233.842306)
		(width 0.12954)
		(layer "F.Cu")
		(net "M_G_CPU0_SA_DQS_DN<8>")
	)
	(segment
		(start 399.59661 -242.85575)
		(end 404.515574 -237.936786)
		(width 0.12954)
		(layer "F.Cu")
		(net "M_G_CPU0_SA_DQS_DN<8>")
	)
	(segment
		(start 408.964892 -232.238804)
		(end 411.30474 -229.898956)
		(width 0.12954)
		(layer "F.Cu")
		(net "M_G_CPU0_SA_DQS_DN<8>")
	)
	(segment
		(start 408.624532 -233.046016)
		(end 409.313888 -233.735372)
		(width 0.12954)
		(layer "F.Cu")
		(net "M_G_CPU0_SA_DQS_DN<8>")
	)
	(segment
		(start 394.027914 -242.566444)
		(end 394.904976 -242.566444)
		(width 0.0762)
		(layer "F.Cu")
		(net "M_G_CPU0_SA_DQS_DN<8>")
	)
	(segment
		(start 408.15768 -233.046016)
		(end 408.624532 -233.046016)
		(width 0.12954)
		(layer "F.Cu")
		(net "M_G_CPU0_SA_DQS_DN<8>")
	)
	(segment
		(start 395.59611 -242.85575)
		(end 395.61516 -242.85575)
		(width 0.0762)
		(layer "F.Cu")
		(net "M_G_CPU0_SA_DQS_DN<8>")
	)
	(segment
		(start 408.674824 -234.887008)
		(end 408.674824 -234.688888)
		(width 0.12954)
		(layer "F.Cu")
		(net "M_G_CPU0_SA_DQS_DN<8>")
	)
	(segment
		(start 393.736576 -242.64747)
		(end 393.744958 -242.642644)
		(width 0.0762)
		(layer "F.Cu")
		(net "M_G_CPU0_SA_DQS_DN<8>")
	)
	(segment
		(start 408.964892 -232.705656)
		(end 408.964892 -232.238804)
		(width 0.12954)
		(layer "F.Cu")
		(net "M_G_CPU0_SA_DQS_DN<8>")
	)
	(arc
		(start 392.431016 -242.642644)
		(mid 392.61796 -242.692899)
		(end 392.804904 -242.642644)
		(width 0.0762)
		(layer "F.Cu")
		(net "M_G_CPU0_SA_DQS_DN<8>")
	)
	(arc
		(start 391.677906 -242.320064)
		(mid 391.911904 -242.492107)
		(end 392.192256 -242.567968)
		(width 0.0762)
		(layer "F.Cu")
		(net "M_G_CPU0_SA_DQS_DN<8>")
	)
	(arc
		(start 393.370816 -242.642644)
		(mid 393.553067 -242.692994)
		(end 393.736576 -242.64747)
		(width 0.0762)
		(layer "F.Cu")
		(net "M_G_CPU0_SA_DQS_DN<8>")
	)
	(arc
		(start 393.744958 -242.642644)
		(mid 393.881394 -242.585819)
		(end 394.027914 -242.566444)
		(width 0.0762)
		(layer "F.Cu")
		(net "M_G_CPU0_SA_DQS_DN<8>")
	)
	(arc
		(start 392.804904 -242.642644)
		(mid 393.08786 -242.566467)
		(end 393.370816 -242.642644)
		(width 0.0762)
		(layer "F.Cu")
		(net "M_G_CPU0_SA_DQS_DN<8>")
	)
	(arc
		(start 392.192256 -242.567968)
		(mid 392.204079 -242.568985)
		(end 392.215878 -242.570254)
		(width 0.0762)
		(layer "F.Cu")
		(net "M_G_CPU0_SA_DQS_DN<8>")
	)
	(arc
		(start 392.215878 -242.570254)
		(mid 392.327124 -242.595517)
		(end 392.431016 -242.642644)
		(width 0.0762)
		(layer "F.Cu")
		(net "M_G_CPU0_SA_DQS_DN<8>")
	)
	(segment
		(start 395.472158 -237.83163)
		(end 395.491208 -237.83163)
		(width 0.0762)
		(layer "F.Cu")
		(net "M_G_CPU0_SA_DQS_DN<7>")
	)
	(segment
		(start 407.1493 -224.11817)
		(end 407.599896 -224.11817)
		(width 0.12954)
		(layer "F.Cu")
		(net "M_G_CPU0_SA_DQS_DN<7>")
	)
	(segment
		(start 409.528772 -221.967298)
		(end 409.995624 -221.967298)
		(width 0.12954)
		(layer "F.Cu")
		(net "M_G_CPU0_SA_DQS_DN<7>")
	)
	(segment
		(start 408.303222 -223.015048)
		(end 408.770074 -223.015048)
		(width 0.12954)
		(layer "F.Cu")
		(net "M_G_CPU0_SA_DQS_DN<7>")
	)
	(segment
		(start 409.344114 -223.589088)
		(end 409.542234 -223.589088)
		(width 0.12954)
		(layer "F.Cu")
		(net "M_G_CPU0_SA_DQS_DN<7>")
	)
	(segment
		(start 410.576776 -222.06585)
		(end 410.576776 -221.86773)
		(width 0.12954)
		(layer "F.Cu")
		(net "M_G_CPU0_SA_DQS_DN<7>")
	)
	(segment
		(start 408.302968 -224.821242)
		(end 408.501088 -224.821242)
		(width 0.12954)
		(layer "F.Cu")
		(net "M_G_CPU0_SA_DQS_DN<7>")
	)
	(segment
		(start 394.027914 -237.706408)
		(end 394.913612 -237.706408)
		(width 0.0762)
		(layer "F.Cu")
		(net "M_G_CPU0_SA_DQS_DN<7>")
	)
	(segment
		(start 406.822148 -224.445322)
		(end 407.1493 -224.11817)
		(width 0.12954)
		(layer "F.Cu")
		(net "M_G_CPU0_SA_DQS_DN<7>")
	)
	(segment
		(start 408.770074 -223.015048)
		(end 409.344114 -223.589088)
		(width 0.12954)
		(layer "F.Cu")
		(net "M_G_CPU0_SA_DQS_DN<7>")
	)
	(segment
		(start 408.643328 -224.480882)
		(end 407.973784 -223.811338)
		(width 0.12954)
		(layer "F.Cu")
		(net "M_G_CPU0_SA_DQS_DN<7>")
	)
	(segment
		(start 407.973784 -223.811338)
		(end 407.973784 -223.344486)
		(width 0.12954)
		(layer "F.Cu")
		(net "M_G_CPU0_SA_DQS_DN<7>")
	)
	(segment
		(start 410.434536 -222.20809)
		(end 410.576776 -222.06585)
		(width 0.12954)
		(layer "F.Cu")
		(net "M_G_CPU0_SA_DQS_DN<7>")
	)
	(segment
		(start 410.345636 -221.185994)
		(end 410.982668 -220.548962)
		(width 0.12954)
		(layer "F.Cu")
		(net "M_G_CPU0_SA_DQS_DN<7>")
	)
	(segment
		(start 394.913612 -237.706408)
		(end 395.104874 -237.89767)
		(width 0.0762)
		(layer "F.Cu")
		(net "M_G_CPU0_SA_DQS_DN<7>")
	)
	(segment
		(start 411.809946 -220.285056)
		(end 412.367984 -220.285056)
		(width 0.12954)
		(layer "F.Cu")
		(net "M_G_CPU0_SA_DQS_DN<7>")
	)
	(segment
		(start 407.973784 -223.344486)
		(end 408.303222 -223.015048)
		(width 0.12954)
		(layer "F.Cu")
		(net "M_G_CPU0_SA_DQS_DN<7>")
	)
	(segment
		(start 409.199334 -222.763588)
		(end 409.199334 -222.296736)
		(width 0.12954)
		(layer "F.Cu")
		(net "M_G_CPU0_SA_DQS_DN<7>")
	)
	(segment
		(start 409.684474 -223.446848)
		(end 409.684474 -223.248728)
		(width 0.12954)
		(layer "F.Cu")
		(net "M_G_CPU0_SA_DQS_DN<7>")
	)
	(segment
		(start 409.542234 -223.589088)
		(end 409.684474 -223.446848)
		(width 0.12954)
		(layer "F.Cu")
		(net "M_G_CPU0_SA_DQS_DN<7>")
	)
	(segment
		(start 409.684474 -223.248728)
		(end 409.199334 -222.763588)
		(width 0.12954)
		(layer "F.Cu")
		(net "M_G_CPU0_SA_DQS_DN<7>")
	)
	(segment
		(start 407.599896 -224.11817)
		(end 408.302968 -224.821242)
		(width 0.12954)
		(layer "F.Cu")
		(net "M_G_CPU0_SA_DQS_DN<7>")
	)
	(segment
		(start 411.54604 -220.548962)
		(end 411.809946 -220.285056)
		(width 0.12954)
		(layer "F.Cu")
		(net "M_G_CPU0_SA_DQS_DN<7>")
	)
	(segment
		(start 408.501088 -224.821242)
		(end 408.643328 -224.679002)
		(width 0.12954)
		(layer "F.Cu")
		(net "M_G_CPU0_SA_DQS_DN<7>")
	)
	(segment
		(start 409.995624 -221.967298)
		(end 410.236416 -222.20809)
		(width 0.12954)
		(layer "F.Cu")
		(net "M_G_CPU0_SA_DQS_DN<7>")
	)
	(segment
		(start 397.140176 -237.83163)
		(end 406.822148 -228.149658)
		(width 0.12954)
		(layer "F.Cu")
		(net "M_G_CPU0_SA_DQS_DN<7>")
	)
	(segment
		(start 395.406118 -237.89767)
		(end 395.472158 -237.83163)
		(width 0.0762)
		(layer "F.Cu")
		(net "M_G_CPU0_SA_DQS_DN<7>")
	)
	(segment
		(start 409.199334 -222.296736)
		(end 409.528772 -221.967298)
		(width 0.12954)
		(layer "F.Cu")
		(net "M_G_CPU0_SA_DQS_DN<7>")
	)
	(segment
		(start 410.345636 -221.63659)
		(end 410.345636 -221.185994)
		(width 0.12954)
		(layer "F.Cu")
		(net "M_G_CPU0_SA_DQS_DN<7>")
	)
	(segment
		(start 410.236416 -222.20809)
		(end 410.434536 -222.20809)
		(width 0.12954)
		(layer "F.Cu")
		(net "M_G_CPU0_SA_DQS_DN<7>")
	)
	(segment
		(start 395.491208 -237.83163)
		(end 397.140176 -237.83163)
		(width 0.12954)
		(layer "F.Cu")
		(net "M_G_CPU0_SA_DQS_DN<7>")
	)
	(segment
		(start 395.104874 -237.89767)
		(end 395.406118 -237.89767)
		(width 0.0762)
		(layer "F.Cu")
		(net "M_G_CPU0_SA_DQS_DN<7>")
	)
	(segment
		(start 410.576776 -221.86773)
		(end 410.345636 -221.63659)
		(width 0.12954)
		(layer "F.Cu")
		(net "M_G_CPU0_SA_DQS_DN<7>")
	)
	(segment
		(start 408.643328 -224.679002)
		(end 408.643328 -224.480882)
		(width 0.12954)
		(layer "F.Cu")
		(net "M_G_CPU0_SA_DQS_DN<7>")
	)
	(segment
		(start 410.982668 -220.548962)
		(end 411.54604 -220.548962)
		(width 0.12954)
		(layer "F.Cu")
		(net "M_G_CPU0_SA_DQS_DN<7>")
	)
	(segment
		(start 406.822148 -228.149658)
		(end 406.822148 -224.445322)
		(width 0.12954)
		(layer "F.Cu")
		(net "M_G_CPU0_SA_DQS_DN<7>")
	)
	(segment
		(start 393.736576 -237.787434)
		(end 393.744958 -237.782608)
		(width 0.0762)
		(layer "F.Cu")
		(net "M_G_CPU0_SA_DQS_DN<7>")
	)
	(arc
		(start 392.215878 -237.710218)
		(mid 392.327124 -237.735481)
		(end 392.431016 -237.782608)
		(width 0.0762)
		(layer "F.Cu")
		(net "M_G_CPU0_SA_DQS_DN<7>")
	)
	(arc
		(start 391.677906 -237.460028)
		(mid 391.911904 -237.632071)
		(end 392.192256 -237.707932)
		(width 0.0762)
		(layer "F.Cu")
		(net "M_G_CPU0_SA_DQS_DN<7>")
	)
	(arc
		(start 392.431016 -237.782608)
		(mid 392.61796 -237.832863)
		(end 392.804904 -237.782608)
		(width 0.0762)
		(layer "F.Cu")
		(net "M_G_CPU0_SA_DQS_DN<7>")
	)
	(arc
		(start 393.370816 -237.782608)
		(mid 393.553067 -237.832958)
		(end 393.736576 -237.787434)
		(width 0.0762)
		(layer "F.Cu")
		(net "M_G_CPU0_SA_DQS_DN<7>")
	)
	(arc
		(start 392.804904 -237.782608)
		(mid 393.08786 -237.706431)
		(end 393.370816 -237.782608)
		(width 0.0762)
		(layer "F.Cu")
		(net "M_G_CPU0_SA_DQS_DN<7>")
	)
	(arc
		(start 392.192256 -237.707932)
		(mid 392.204079 -237.708949)
		(end 392.215878 -237.710218)
		(width 0.0762)
		(layer "F.Cu")
		(net "M_G_CPU0_SA_DQS_DN<7>")
	)
	(arc
		(start 393.744958 -237.782608)
		(mid 393.881394 -237.725783)
		(end 394.027914 -237.706408)
		(width 0.0762)
		(layer "F.Cu")
		(net "M_G_CPU0_SA_DQS_DN<7>")
	)
	(segment
		(start 408.118564 -212.465666)
		(end 408.449526 -212.134704)
		(width 0.12954)
		(layer "F.Cu")
		(net "M_G_CPU0_SA_DQS_DN<6>")
	)
	(segment
		(start 409.737306 -212.276944)
		(end 409.255214 -211.794852)
		(width 0.12954)
		(layer "F.Cu")
		(net "M_G_CPU0_SA_DQS_DN<6>")
	)
	(segment
		(start 411.54604 -211.198968)
		(end 411.809946 -210.935062)
		(width 0.12954)
		(layer "F.Cu")
		(net "M_G_CPU0_SA_DQS_DN<6>")
	)
	(segment
		(start 402.378418 -219.834968)
		(end 407.464006 -214.74938)
		(width 0.12954)
		(layer "F.Cu")
		(net "M_G_CPU0_SA_DQS_DN<6>")
	)
	(segment
		(start 395.242796 -232.780332)
		(end 395.261846 -232.780332)
		(width 0.0762)
		(layer "F.Cu")
		(net "M_G_CPU0_SA_DQS_DN<6>")
	)
	(segment
		(start 409.737306 -212.47608)
		(end 409.737306 -212.276944)
		(width 0.12954)
		(layer "F.Cu")
		(net "M_G_CPU0_SA_DQS_DN<6>")
	)
	(segment
		(start 408.600656 -213.61273)
		(end 408.600656 -213.413594)
		(width 0.12954)
		(layer "F.Cu")
		(net "M_G_CPU0_SA_DQS_DN<6>")
	)
	(segment
		(start 411.809946 -210.935062)
		(end 412.367984 -210.935062)
		(width 0.12954)
		(layer "F.Cu")
		(net "M_G_CPU0_SA_DQS_DN<6>")
	)
	(segment
		(start 408.260804 -213.753446)
		(end 408.45994 -213.753446)
		(width 0.12954)
		(layer "F.Cu")
		(net "M_G_CPU0_SA_DQS_DN<6>")
	)
	(segment
		(start 406.981914 -214.068152)
		(end 406.981914 -213.602316)
		(width 0.12954)
		(layer "F.Cu")
		(net "M_G_CPU0_SA_DQS_DN<6>")
	)
	(segment
		(start 393.736576 -232.927398)
		(end 393.744958 -232.922572)
		(width 0.0762)
		(layer "F.Cu")
		(net "M_G_CPU0_SA_DQS_DN<6>")
	)
	(segment
		(start 402.378418 -226.346512)
		(end 402.378418 -219.834968)
		(width 0.12954)
		(layer "F.Cu")
		(net "M_G_CPU0_SA_DQS_DN<6>")
	)
	(segment
		(start 408.449526 -212.134704)
		(end 408.915362 -212.134704)
		(width 0.12954)
		(layer "F.Cu")
		(net "M_G_CPU0_SA_DQS_DN<6>")
	)
	(segment
		(start 409.397454 -212.616796)
		(end 409.59659 -212.616796)
		(width 0.12954)
		(layer "F.Cu")
		(net "M_G_CPU0_SA_DQS_DN<6>")
	)
	(segment
		(start 409.255214 -211.794852)
		(end 409.255214 -211.329016)
		(width 0.12954)
		(layer "F.Cu")
		(net "M_G_CPU0_SA_DQS_DN<6>")
	)
	(segment
		(start 409.59659 -212.616796)
		(end 409.737306 -212.47608)
		(width 0.12954)
		(layer "F.Cu")
		(net "M_G_CPU0_SA_DQS_DN<6>")
	)
	(segment
		(start 406.981914 -213.602316)
		(end 407.312876 -213.271354)
		(width 0.12954)
		(layer "F.Cu")
		(net "M_G_CPU0_SA_DQS_DN<6>")
	)
	(segment
		(start 410.73324 -211.480146)
		(end 411.014418 -211.198968)
		(width 0.12954)
		(layer "F.Cu")
		(net "M_G_CPU0_SA_DQS_DN<6>")
	)
	(segment
		(start 409.586176 -210.998054)
		(end 410.052012 -210.998054)
		(width 0.12954)
		(layer "F.Cu")
		(net "M_G_CPU0_SA_DQS_DN<6>")
	)
	(segment
		(start 407.464006 -214.74938)
		(end 407.464006 -214.550244)
		(width 0.12954)
		(layer "F.Cu")
		(net "M_G_CPU0_SA_DQS_DN<6>")
	)
	(segment
		(start 410.534104 -211.480146)
		(end 410.73324 -211.480146)
		(width 0.12954)
		(layer "F.Cu")
		(net "M_G_CPU0_SA_DQS_DN<6>")
	)
	(segment
		(start 407.464006 -214.550244)
		(end 406.981914 -214.068152)
		(width 0.12954)
		(layer "F.Cu")
		(net "M_G_CPU0_SA_DQS_DN<6>")
	)
	(segment
		(start 395.176756 -232.846372)
		(end 395.242796 -232.780332)
		(width 0.0762)
		(layer "F.Cu")
		(net "M_G_CPU0_SA_DQS_DN<6>")
	)
	(segment
		(start 394.027914 -232.846372)
		(end 395.176756 -232.846372)
		(width 0.0762)
		(layer "F.Cu")
		(net "M_G_CPU0_SA_DQS_DN<6>")
	)
	(segment
		(start 411.014418 -211.198968)
		(end 411.54604 -211.198968)
		(width 0.12954)
		(layer "F.Cu")
		(net "M_G_CPU0_SA_DQS_DN<6>")
	)
	(segment
		(start 407.778712 -213.271354)
		(end 408.260804 -213.753446)
		(width 0.12954)
		(layer "F.Cu")
		(net "M_G_CPU0_SA_DQS_DN<6>")
	)
	(segment
		(start 408.118564 -212.931502)
		(end 408.118564 -212.465666)
		(width 0.12954)
		(layer "F.Cu")
		(net "M_G_CPU0_SA_DQS_DN<6>")
	)
	(segment
		(start 395.944598 -232.780332)
		(end 402.378418 -226.346512)
		(width 0.12954)
		(layer "F.Cu")
		(net "M_G_CPU0_SA_DQS_DN<6>")
	)
	(segment
		(start 407.312876 -213.271354)
		(end 407.778712 -213.271354)
		(width 0.12954)
		(layer "F.Cu")
		(net "M_G_CPU0_SA_DQS_DN<6>")
	)
	(segment
		(start 408.600656 -213.413594)
		(end 408.118564 -212.931502)
		(width 0.12954)
		(layer "F.Cu")
		(net "M_G_CPU0_SA_DQS_DN<6>")
	)
	(segment
		(start 408.45994 -213.753446)
		(end 408.600656 -213.61273)
		(width 0.12954)
		(layer "F.Cu")
		(net "M_G_CPU0_SA_DQS_DN<6>")
	)
	(segment
		(start 395.261846 -232.780332)
		(end 395.944598 -232.780332)
		(width 0.12954)
		(layer "F.Cu")
		(net "M_G_CPU0_SA_DQS_DN<6>")
	)
	(segment
		(start 409.255214 -211.329016)
		(end 409.586176 -210.998054)
		(width 0.12954)
		(layer "F.Cu")
		(net "M_G_CPU0_SA_DQS_DN<6>")
	)
	(segment
		(start 410.052012 -210.998054)
		(end 410.534104 -211.480146)
		(width 0.12954)
		(layer "F.Cu")
		(net "M_G_CPU0_SA_DQS_DN<6>")
	)
	(segment
		(start 408.915362 -212.134704)
		(end 409.397454 -212.616796)
		(width 0.12954)
		(layer "F.Cu")
		(net "M_G_CPU0_SA_DQS_DN<6>")
	)
	(arc
		(start 393.370816 -232.922572)
		(mid 393.553067 -232.972922)
		(end 393.736576 -232.927398)
		(width 0.0762)
		(layer "F.Cu")
		(net "M_G_CPU0_SA_DQS_DN<6>")
	)
	(arc
		(start 392.192256 -232.847896)
		(mid 392.204079 -232.848913)
		(end 392.215878 -232.850182)
		(width 0.0762)
		(layer "F.Cu")
		(net "M_G_CPU0_SA_DQS_DN<6>")
	)
	(arc
		(start 393.744958 -232.922572)
		(mid 393.881394 -232.865747)
		(end 394.027914 -232.846372)
		(width 0.0762)
		(layer "F.Cu")
		(net "M_G_CPU0_SA_DQS_DN<6>")
	)
	(arc
		(start 392.431016 -232.922572)
		(mid 392.61796 -232.972827)
		(end 392.804904 -232.922572)
		(width 0.0762)
		(layer "F.Cu")
		(net "M_G_CPU0_SA_DQS_DN<6>")
	)
	(arc
		(start 392.804904 -232.922572)
		(mid 393.08786 -232.846395)
		(end 393.370816 -232.922572)
		(width 0.0762)
		(layer "F.Cu")
		(net "M_G_CPU0_SA_DQS_DN<6>")
	)
	(arc
		(start 392.215878 -232.850182)
		(mid 392.327124 -232.875445)
		(end 392.431016 -232.922572)
		(width 0.0762)
		(layer "F.Cu")
		(net "M_G_CPU0_SA_DQS_DN<6>")
	)
	(arc
		(start 391.677906 -232.599992)
		(mid 391.911904 -232.772035)
		(end 392.192256 -232.847896)
		(width 0.0762)
		(layer "F.Cu")
		(net "M_G_CPU0_SA_DQS_DN<6>")
	)
	(segment
		(start 408.975814 -204.775816)
		(end 409.174188 -204.775816)
		(width 0.12954)
		(layer "F.Cu")
		(net "M_G_CPU0_SA_DQS_DN<5>")
	)
	(segment
		(start 395.25067 -227.174298)
		(end 397.753078 -224.670874)
		(width 0.12954)
		(layer "F.Cu")
		(net "M_G_CPU0_SA_DQS_DN<5>")
	)
	(segment
		(start 395.237208 -227.18776)
		(end 395.25067 -227.174298)
		(width 0.0762)
		(layer "F.Cu")
		(net "M_G_CPU0_SA_DQS_DN<5>")
	)
	(segment
		(start 394.813282 -227.704904)
		(end 395.237462 -227.280724)
		(width 0.0762)
		(layer "F.Cu")
		(net "M_G_CPU0_SA_DQS_DN<5>")
	)
	(segment
		(start 395.237462 -227.280724)
		(end 395.237208 -227.18776)
		(width 0.0762)
		(layer "F.Cu")
		(net "M_G_CPU0_SA_DQS_DN<5>")
	)
	(segment
		(start 410.602176 -201.848974)
		(end 411.54604 -201.848974)
		(width 0.12954)
		(layer "F.Cu")
		(net "M_G_CPU0_SA_DQS_DN<5>")
	)
	(segment
		(start 409.629356 -203.156058)
		(end 410.112464 -203.639166)
		(width 0.12954)
		(layer "F.Cu")
		(net "M_G_CPU0_SA_DQS_DN<5>")
	)
	(segment
		(start 407.682446 -204.608684)
		(end 408.012392 -204.278738)
		(width 0.12954)
		(layer "F.Cu")
		(net "M_G_CPU0_SA_DQS_DN<5>")
	)
	(segment
		(start 409.163012 -203.156058)
		(end 409.629356 -203.156058)
		(width 0.12954)
		(layer "F.Cu")
		(net "M_G_CPU0_SA_DQS_DN<5>")
	)
	(segment
		(start 408.179778 -205.57236)
		(end 407.682446 -205.075028)
		(width 0.12954)
		(layer "F.Cu")
		(net "M_G_CPU0_SA_DQS_DN<5>")
	)
	(segment
		(start 394.12037 -227.705412)
		(end 394.813282 -227.705412)
		(width 0.0762)
		(layer "F.Cu")
		(net "M_G_CPU0_SA_DQS_DN<5>")
	)
	(segment
		(start 397.753078 -224.670874)
		(end 397.753078 -215.378538)
		(width 0.12954)
		(layer "F.Cu")
		(net "M_G_CPU0_SA_DQS_DN<5>")
	)
	(segment
		(start 409.174188 -204.775816)
		(end 409.316428 -204.633576)
		(width 0.12954)
		(layer "F.Cu")
		(net "M_G_CPU0_SA_DQS_DN<5>")
	)
	(segment
		(start 410.453078 -203.29906)
		(end 410.027882 -202.873864)
		(width 0.12954)
		(layer "F.Cu")
		(net "M_G_CPU0_SA_DQS_DN<5>")
	)
	(segment
		(start 407.682446 -205.075028)
		(end 407.682446 -204.608684)
		(width 0.12954)
		(layer "F.Cu")
		(net "M_G_CPU0_SA_DQS_DN<5>")
	)
	(segment
		(start 410.453078 -203.496926)
		(end 410.453078 -203.29906)
		(width 0.12954)
		(layer "F.Cu")
		(net "M_G_CPU0_SA_DQS_DN<5>")
	)
	(segment
		(start 397.753078 -215.378538)
		(end 407.21915 -205.912466)
		(width 0.12954)
		(layer "F.Cu")
		(net "M_G_CPU0_SA_DQS_DN<5>")
	)
	(segment
		(start 408.179778 -205.770226)
		(end 408.179778 -205.57236)
		(width 0.12954)
		(layer "F.Cu")
		(net "M_G_CPU0_SA_DQS_DN<5>")
	)
	(segment
		(start 409.316428 -204.633576)
		(end 409.316428 -204.43571)
		(width 0.12954)
		(layer "F.Cu")
		(net "M_G_CPU0_SA_DQS_DN<5>")
	)
	(segment
		(start 408.037538 -205.912466)
		(end 408.179778 -205.770226)
		(width 0.12954)
		(layer "F.Cu")
		(net "M_G_CPU0_SA_DQS_DN<5>")
	)
	(segment
		(start 408.012392 -204.278738)
		(end 408.478736 -204.278738)
		(width 0.12954)
		(layer "F.Cu")
		(net "M_G_CPU0_SA_DQS_DN<5>")
	)
	(segment
		(start 410.112464 -203.639166)
		(end 410.310838 -203.639166)
		(width 0.12954)
		(layer "F.Cu")
		(net "M_G_CPU0_SA_DQS_DN<5>")
	)
	(segment
		(start 393.821666 -228.003862)
		(end 394.12037 -227.705412)
		(width 0.0762)
		(layer "F.Cu")
		(net "M_G_CPU0_SA_DQS_DN<5>")
	)
	(segment
		(start 407.21915 -205.912466)
		(end 408.037538 -205.912466)
		(width 0.12954)
		(layer "F.Cu")
		(net "M_G_CPU0_SA_DQS_DN<5>")
	)
	(segment
		(start 411.54604 -201.848974)
		(end 411.809946 -201.585068)
		(width 0.12954)
		(layer "F.Cu")
		(net "M_G_CPU0_SA_DQS_DN<5>")
	)
	(segment
		(start 410.027882 -202.423268)
		(end 410.602176 -201.848974)
		(width 0.12954)
		(layer "F.Cu")
		(net "M_G_CPU0_SA_DQS_DN<5>")
	)
	(segment
		(start 410.310838 -203.639166)
		(end 410.453078 -203.496926)
		(width 0.12954)
		(layer "F.Cu")
		(net "M_G_CPU0_SA_DQS_DN<5>")
	)
	(segment
		(start 411.809946 -201.585068)
		(end 412.367984 -201.585068)
		(width 0.12954)
		(layer "F.Cu")
		(net "M_G_CPU0_SA_DQS_DN<5>")
	)
	(segment
		(start 408.833066 -203.952348)
		(end 408.833066 -203.486004)
		(width 0.12954)
		(layer "F.Cu")
		(net "M_G_CPU0_SA_DQS_DN<5>")
	)
	(segment
		(start 409.316428 -204.43571)
		(end 408.833066 -203.952348)
		(width 0.12954)
		(layer "F.Cu")
		(net "M_G_CPU0_SA_DQS_DN<5>")
	)
	(segment
		(start 408.833066 -203.486004)
		(end 409.163012 -203.156058)
		(width 0.12954)
		(layer "F.Cu")
		(net "M_G_CPU0_SA_DQS_DN<5>")
	)
	(segment
		(start 394.813282 -227.705412)
		(end 394.813282 -227.704904)
		(width 0.0762)
		(layer "F.Cu")
		(net "M_G_CPU0_SA_DQS_DN<5>")
	)
	(segment
		(start 410.027882 -202.873864)
		(end 410.027882 -202.423268)
		(width 0.12954)
		(layer "F.Cu")
		(net "M_G_CPU0_SA_DQS_DN<5>")
	)
	(segment
		(start 408.478736 -204.278738)
		(end 408.975814 -204.775816)
		(width 0.12954)
		(layer "F.Cu")
		(net "M_G_CPU0_SA_DQS_DN<5>")
	)
	(arc
		(start 393.370816 -228.06279)
		(mid 393.558014 -228.113172)
		(end 393.745212 -228.06279)
		(width 0.0762)
		(layer "F.Cu")
		(net "M_G_CPU0_SA_DQS_DN<5>")
	)
	(arc
		(start 391.677906 -227.74021)
		(mid 391.911904 -227.912253)
		(end 392.192256 -227.988114)
		(width 0.0762)
		(layer "F.Cu")
		(net "M_G_CPU0_SA_DQS_DN<5>")
	)
	(arc
		(start 392.192256 -227.988114)
		(mid 392.204079 -227.989131)
		(end 392.215878 -227.9904)
		(width 0.0762)
		(layer "F.Cu")
		(net "M_G_CPU0_SA_DQS_DN<5>")
	)
	(arc
		(start 392.215878 -227.9904)
		(mid 392.327124 -228.015663)
		(end 392.431016 -228.06279)
		(width 0.0762)
		(layer "F.Cu")
		(net "M_G_CPU0_SA_DQS_DN<5>")
	)
	(arc
		(start 393.745212 -228.06279)
		(mid 393.785357 -228.035814)
		(end 393.821666 -228.003862)
		(width 0.0762)
		(layer "F.Cu")
		(net "M_G_CPU0_SA_DQS_DN<5>")
	)
	(arc
		(start 392.431016 -228.06279)
		(mid 392.61796 -228.113045)
		(end 392.804904 -228.06279)
		(width 0.0762)
		(layer "F.Cu")
		(net "M_G_CPU0_SA_DQS_DN<5>")
	)
	(arc
		(start 392.804904 -228.06279)
		(mid 393.08786 -227.986613)
		(end 393.370816 -228.06279)
		(width 0.0762)
		(layer "F.Cu")
		(net "M_G_CPU0_SA_DQS_DN<5>")
	)
	(segment
		(start 415.635694 -238.667798)
		(end 415.95294 -238.985044)
		(width 0.101346)
		(layer "F.Cu")
		(net "M_G_CPU0_SA_DQS_DN<4>")
	)
	(segment
		(start 414.962594 -238.667798)
		(end 415.635694 -238.667798)
		(width 0.101346)
		(layer "F.Cu")
		(net "M_G_CPU0_SA_DQS_DN<4>")
	)
	(segment
		(start 395.359128 -246.872252)
		(end 404.0759 -246.872252)
		(width 0.12954)
		(layer "F.Cu")
		(net "M_G_CPU0_SA_DQS_DN<4>")
	)
	(segment
		(start 415.95294 -238.985044)
		(end 416.468052 -238.985044)
		(width 0.101346)
		(layer "F.Cu")
		(net "M_G_CPU0_SA_DQS_DN<4>")
	)
	(segment
		(start 393.558014 -247.1801)
		(end 393.455652 -247.003824)
		(width 0.0762)
		(layer "F.Cu")
		(net "M_G_CPU0_SA_DQS_DN<4>")
	)
	(segment
		(start 394.02766 -246.93372)
		(end 395.007084 -246.93372)
		(width 0.0762)
		(layer "F.Cu")
		(net "M_G_CPU0_SA_DQS_DN<4>")
	)
	(segment
		(start 414.25241 -238.242602)
		(end 414.537398 -238.242602)
		(width 0.101346)
		(layer "F.Cu")
		(net "M_G_CPU0_SA_DQS_DN<4>")
	)
	(segment
		(start 395.340078 -246.872252)
		(end 395.359128 -246.872252)
		(width 0.0762)
		(layer "F.Cu")
		(net "M_G_CPU0_SA_DQS_DN<4>")
	)
	(segment
		(start 406.468834 -242.819174)
		(end 410.990796 -238.297212)
		(width 0.12954)
		(layer "F.Cu")
		(net "M_G_CPU0_SA_DQS_DN<4>")
	)
	(segment
		(start 410.990796 -238.297212)
		(end 411.24378 -238.297212)
		(width 0.12954)
		(layer "F.Cu")
		(net "M_G_CPU0_SA_DQS_DN<4>")
	)
	(segment
		(start 395.134592 -246.806212)
		(end 395.274038 -246.806212)
		(width 0.0762)
		(layer "F.Cu")
		(net "M_G_CPU0_SA_DQS_DN<4>")
	)
	(segment
		(start 395.274038 -246.806212)
		(end 395.340078 -246.872252)
		(width 0.0762)
		(layer "F.Cu")
		(net "M_G_CPU0_SA_DQS_DN<4>")
	)
	(segment
		(start 406.468834 -244.479318)
		(end 406.468834 -242.819174)
		(width 0.12954)
		(layer "F.Cu")
		(net "M_G_CPU0_SA_DQS_DN<4>")
	)
	(segment
		(start 393.736576 -246.852694)
		(end 393.744958 -246.85752)
		(width 0.0762)
		(layer "F.Cu")
		(net "M_G_CPU0_SA_DQS_DN<4>")
	)
	(segment
		(start 395.007084 -246.93372)
		(end 395.134592 -246.806212)
		(width 0.0762)
		(layer "F.Cu")
		(net "M_G_CPU0_SA_DQS_DN<4>")
	)
	(segment
		(start 414.537398 -238.242602)
		(end 414.962594 -238.667798)
		(width 0.101346)
		(layer "F.Cu")
		(net "M_G_CPU0_SA_DQS_DN<4>")
	)
	(segment
		(start 411.24378 -238.297212)
		(end 411.50667 -238.560102)
		(width 0.12954)
		(layer "F.Cu")
		(net "M_G_CPU0_SA_DQS_DN<4>")
	)
	(segment
		(start 404.0759 -246.872252)
		(end 406.468834 -244.479318)
		(width 0.12954)
		(layer "F.Cu")
		(net "M_G_CPU0_SA_DQS_DN<4>")
	)
	(segment
		(start 413.93491 -238.560102)
		(end 414.25241 -238.242602)
		(width 0.101346)
		(layer "F.Cu")
		(net "M_G_CPU0_SA_DQS_DN<4>")
	)
	(segment
		(start 411.50667 -238.560102)
		(end 413.93491 -238.560102)
		(width 0.101346)
		(layer "F.Cu")
		(net "M_G_CPU0_SA_DQS_DN<4>")
	)
	(arc
		(start 393.455652 -247.003824)
		(mid 393.485281 -246.861337)
		(end 393.62253 -246.812816)
		(width 0.0762)
		(layer "F.Cu")
		(net "M_G_CPU0_SA_DQS_DN<4>")
	)
	(arc
		(start 393.744958 -246.85752)
		(mid 393.858682 -246.907821)
		(end 393.98067 -246.931942)
		(width 0.0762)
		(layer "F.Cu")
		(net "M_G_CPU0_SA_DQS_DN<4>")
	)
	(arc
		(start 393.98067 -246.931942)
		(mid 394.004147 -246.933318)
		(end 394.02766 -246.93372)
		(width 0.0762)
		(layer "F.Cu")
		(net "M_G_CPU0_SA_DQS_DN<4>")
	)
	(arc
		(start 393.62253 -246.812816)
		(mid 393.681176 -246.828109)
		(end 393.736576 -246.852694)
		(width 0.0762)
		(layer "F.Cu")
		(net "M_G_CPU0_SA_DQS_DN<4>")
	)
	(segment
		(start 410.915358 -229.669086)
		(end 410.915358 -229.086664)
		(width 0.12954)
		(layer "F.Cu")
		(net "M_G_CPU0_SA_DQS_DN<3>")
	)
	(segment
		(start 415.95294 -229.63505)
		(end 416.468052 -229.63505)
		(width 0.101346)
		(layer "F.Cu")
		(net "M_G_CPU0_SA_DQS_DN<3>")
	)
	(segment
		(start 393.736576 -241.992658)
		(end 393.744958 -241.997484)
		(width 0.0762)
		(layer "F.Cu")
		(net "M_G_CPU0_SA_DQS_DN<3>")
	)
	(segment
		(start 404.340822 -237.515146)
		(end 405.406098 -237.515146)
		(width 0.12954)
		(layer "F.Cu")
		(net "M_G_CPU0_SA_DQS_DN<3>")
	)
	(segment
		(start 394.02766 -242.073684)
		(end 394.943584 -242.073684)
		(width 0.0762)
		(layer "F.Cu")
		(net "M_G_CPU0_SA_DQS_DN<3>")
	)
	(segment
		(start 399.513044 -242.342924)
		(end 404.340822 -237.515146)
		(width 0.12954)
		(layer "F.Cu")
		(net "M_G_CPU0_SA_DQS_DN<3>")
	)
	(segment
		(start 411.054804 -228.947218)
		(end 411.24378 -228.947218)
		(width 0.12954)
		(layer "F.Cu")
		(net "M_G_CPU0_SA_DQS_DN<3>")
	)
	(segment
		(start 411.24378 -228.947218)
		(end 411.50667 -229.210108)
		(width 0.12954)
		(layer "F.Cu")
		(net "M_G_CPU0_SA_DQS_DN<3>")
	)
	(segment
		(start 414.932114 -229.317804)
		(end 415.635694 -229.317804)
		(width 0.101346)
		(layer "F.Cu")
		(net "M_G_CPU0_SA_DQS_DN<3>")
	)
	(segment
		(start 405.406098 -237.515146)
		(end 407.366978 -235.554266)
		(width 0.12954)
		(layer "F.Cu")
		(net "M_G_CPU0_SA_DQS_DN<3>")
	)
	(segment
		(start 411.50667 -229.210108)
		(end 413.93491 -229.210108)
		(width 0.101346)
		(layer "F.Cu")
		(net "M_G_CPU0_SA_DQS_DN<3>")
	)
	(segment
		(start 415.635694 -229.317804)
		(end 415.95294 -229.63505)
		(width 0.101346)
		(layer "F.Cu")
		(net "M_G_CPU0_SA_DQS_DN<3>")
	)
	(segment
		(start 407.366978 -233.217466)
		(end 410.915358 -229.669086)
		(width 0.12954)
		(layer "F.Cu")
		(net "M_G_CPU0_SA_DQS_DN<3>")
	)
	(segment
		(start 393.558014 -242.320064)
		(end 393.455652 -242.143788)
		(width 0.0762)
		(layer "F.Cu")
		(net "M_G_CPU0_SA_DQS_DN<3>")
	)
	(segment
		(start 395.146784 -242.276884)
		(end 395.479778 -242.276884)
		(width 0.0762)
		(layer "F.Cu")
		(net "M_G_CPU0_SA_DQS_DN<3>")
	)
	(segment
		(start 394.943584 -242.073684)
		(end 395.146784 -242.276884)
		(width 0.0762)
		(layer "F.Cu")
		(net "M_G_CPU0_SA_DQS_DN<3>")
	)
	(segment
		(start 407.366978 -235.554266)
		(end 407.366978 -233.217466)
		(width 0.12954)
		(layer "F.Cu")
		(net "M_G_CPU0_SA_DQS_DN<3>")
	)
	(segment
		(start 395.564868 -242.342924)
		(end 399.513044 -242.342924)
		(width 0.12954)
		(layer "F.Cu")
		(net "M_G_CPU0_SA_DQS_DN<3>")
	)
	(segment
		(start 410.915358 -229.086664)
		(end 411.054804 -228.947218)
		(width 0.12954)
		(layer "F.Cu")
		(net "M_G_CPU0_SA_DQS_DN<3>")
	)
	(segment
		(start 414.506918 -228.892608)
		(end 414.932114 -229.317804)
		(width 0.101346)
		(layer "F.Cu")
		(net "M_G_CPU0_SA_DQS_DN<3>")
	)
	(segment
		(start 414.25241 -228.892608)
		(end 414.506918 -228.892608)
		(width 0.101346)
		(layer "F.Cu")
		(net "M_G_CPU0_SA_DQS_DN<3>")
	)
	(segment
		(start 413.93491 -229.210108)
		(end 414.25241 -228.892608)
		(width 0.101346)
		(layer "F.Cu")
		(net "M_G_CPU0_SA_DQS_DN<3>")
	)
	(segment
		(start 395.545818 -242.342924)
		(end 395.564868 -242.342924)
		(width 0.0762)
		(layer "F.Cu")
		(net "M_G_CPU0_SA_DQS_DN<3>")
	)
	(segment
		(start 395.479778 -242.276884)
		(end 395.545818 -242.342924)
		(width 0.0762)
		(layer "F.Cu")
		(net "M_G_CPU0_SA_DQS_DN<3>")
	)
	(arc
		(start 393.98067 -242.071906)
		(mid 394.004147 -242.073282)
		(end 394.02766 -242.073684)
		(width 0.0762)
		(layer "F.Cu")
		(net "M_G_CPU0_SA_DQS_DN<3>")
	)
	(arc
		(start 393.744958 -241.997484)
		(mid 393.858682 -242.047785)
		(end 393.98067 -242.071906)
		(width 0.0762)
		(layer "F.Cu")
		(net "M_G_CPU0_SA_DQS_DN<3>")
	)
	(arc
		(start 393.62253 -241.95278)
		(mid 393.681176 -241.968073)
		(end 393.736576 -241.992658)
		(width 0.0762)
		(layer "F.Cu")
		(net "M_G_CPU0_SA_DQS_DN<3>")
	)
	(arc
		(start 393.455652 -242.143788)
		(mid 393.485281 -242.001301)
		(end 393.62253 -241.95278)
		(width 0.0762)
		(layer "F.Cu")
		(net "M_G_CPU0_SA_DQS_DN<3>")
	)
	(segment
		(start 410.513784 -219.597224)
		(end 411.24378 -219.597224)
		(width 0.12954)
		(layer "F.Cu")
		(net "M_G_CPU0_SA_DQS_DN<2>")
	)
	(segment
		(start 411.50667 -219.860114)
		(end 413.93491 -219.860114)
		(width 0.101346)
		(layer "F.Cu")
		(net "M_G_CPU0_SA_DQS_DN<2>")
	)
	(segment
		(start 414.962086 -219.96781)
		(end 415.635694 -219.96781)
		(width 0.101346)
		(layer "F.Cu")
		(net "M_G_CPU0_SA_DQS_DN<2>")
	)
	(segment
		(start 414.53689 -219.542614)
		(end 414.962086 -219.96781)
		(width 0.101346)
		(layer "F.Cu")
		(net "M_G_CPU0_SA_DQS_DN<2>")
	)
	(segment
		(start 407.006044 -223.140524)
		(end 407.49982 -223.140524)
		(width 0.12954)
		(layer "F.Cu")
		(net "M_G_CPU0_SA_DQS_DN<2>")
	)
	(segment
		(start 395.438376 -237.39475)
		(end 396.976346 -237.39475)
		(width 0.12954)
		(layer "F.Cu")
		(net "M_G_CPU0_SA_DQS_DN<2>")
	)
	(segment
		(start 407.897076 -222.743268)
		(end 407.897076 -222.325692)
		(width 0.12954)
		(layer "F.Cu")
		(net "M_G_CPU0_SA_DQS_DN<2>")
	)
	(segment
		(start 413.93491 -219.860114)
		(end 414.25241 -219.542614)
		(width 0.101346)
		(layer "F.Cu")
		(net "M_G_CPU0_SA_DQS_DN<2>")
	)
	(segment
		(start 406.760426 -223.386142)
		(end 407.006044 -223.140524)
		(width 0.12954)
		(layer "F.Cu")
		(net "M_G_CPU0_SA_DQS_DN<2>")
	)
	(segment
		(start 395.011402 -237.32871)
		(end 395.353286 -237.32871)
		(width 0.0762)
		(layer "F.Cu")
		(net "M_G_CPU0_SA_DQS_DN<2>")
	)
	(segment
		(start 409.353004 -220.867224)
		(end 409.77312 -220.867224)
		(width 0.12954)
		(layer "F.Cu")
		(net "M_G_CPU0_SA_DQS_DN<2>")
	)
	(segment
		(start 395.353286 -237.32871)
		(end 395.419326 -237.39475)
		(width 0.0762)
		(layer "F.Cu")
		(net "M_G_CPU0_SA_DQS_DN<2>")
	)
	(segment
		(start 409.033726 -221.186502)
		(end 409.353004 -220.867224)
		(width 0.12954)
		(layer "F.Cu")
		(net "M_G_CPU0_SA_DQS_DN<2>")
	)
	(segment
		(start 406.400508 -227.970588)
		(end 406.400508 -224.239836)
		(width 0.12954)
		(layer "F.Cu")
		(net "M_G_CPU0_SA_DQS_DN<2>")
	)
	(segment
		(start 410.170376 -220.469968)
		(end 410.170376 -219.940632)
		(width 0.12954)
		(layer "F.Cu")
		(net "M_G_CPU0_SA_DQS_DN<2>")
	)
	(segment
		(start 394.02766 -237.213648)
		(end 394.89634 -237.213648)
		(width 0.0762)
		(layer "F.Cu")
		(net "M_G_CPU0_SA_DQS_DN<2>")
	)
	(segment
		(start 408.218894 -222.003874)
		(end 408.63647 -222.003874)
		(width 0.12954)
		(layer "F.Cu")
		(net "M_G_CPU0_SA_DQS_DN<2>")
	)
	(segment
		(start 409.77312 -220.867224)
		(end 410.170376 -220.469968)
		(width 0.12954)
		(layer "F.Cu")
		(net "M_G_CPU0_SA_DQS_DN<2>")
	)
	(segment
		(start 393.736576 -237.132622)
		(end 393.744958 -237.137448)
		(width 0.0762)
		(layer "F.Cu")
		(net "M_G_CPU0_SA_DQS_DN<2>")
	)
	(segment
		(start 396.976346 -237.39475)
		(end 406.400508 -227.970588)
		(width 0.12954)
		(layer "F.Cu")
		(net "M_G_CPU0_SA_DQS_DN<2>")
	)
	(segment
		(start 411.24378 -219.597224)
		(end 411.50667 -219.860114)
		(width 0.12954)
		(layer "F.Cu")
		(net "M_G_CPU0_SA_DQS_DN<2>")
	)
	(segment
		(start 406.400508 -224.239836)
		(end 406.760426 -223.879918)
		(width 0.12954)
		(layer "F.Cu")
		(net "M_G_CPU0_SA_DQS_DN<2>")
	)
	(segment
		(start 407.897076 -222.325692)
		(end 408.218894 -222.003874)
		(width 0.12954)
		(layer "F.Cu")
		(net "M_G_CPU0_SA_DQS_DN<2>")
	)
	(segment
		(start 415.635694 -219.96781)
		(end 415.95294 -220.285056)
		(width 0.101346)
		(layer "F.Cu")
		(net "M_G_CPU0_SA_DQS_DN<2>")
	)
	(segment
		(start 414.25241 -219.542614)
		(end 414.53689 -219.542614)
		(width 0.101346)
		(layer "F.Cu")
		(net "M_G_CPU0_SA_DQS_DN<2>")
	)
	(segment
		(start 395.419326 -237.39475)
		(end 395.438376 -237.39475)
		(width 0.0762)
		(layer "F.Cu")
		(net "M_G_CPU0_SA_DQS_DN<2>")
	)
	(segment
		(start 409.033726 -221.606618)
		(end 409.033726 -221.186502)
		(width 0.12954)
		(layer "F.Cu")
		(net "M_G_CPU0_SA_DQS_DN<2>")
	)
	(segment
		(start 394.89634 -237.213648)
		(end 395.011402 -237.32871)
		(width 0.0762)
		(layer "F.Cu")
		(net "M_G_CPU0_SA_DQS_DN<2>")
	)
	(segment
		(start 407.49982 -223.140524)
		(end 407.897076 -222.743268)
		(width 0.12954)
		(layer "F.Cu")
		(net "M_G_CPU0_SA_DQS_DN<2>")
	)
	(segment
		(start 408.63647 -222.003874)
		(end 409.033726 -221.606618)
		(width 0.12954)
		(layer "F.Cu")
		(net "M_G_CPU0_SA_DQS_DN<2>")
	)
	(segment
		(start 393.558014 -237.460028)
		(end 393.455652 -237.283752)
		(width 0.0762)
		(layer "F.Cu")
		(net "M_G_CPU0_SA_DQS_DN<2>")
	)
	(segment
		(start 415.95294 -220.285056)
		(end 416.468052 -220.285056)
		(width 0.101346)
		(layer "F.Cu")
		(net "M_G_CPU0_SA_DQS_DN<2>")
	)
	(segment
		(start 406.760426 -223.879918)
		(end 406.760426 -223.386142)
		(width 0.12954)
		(layer "F.Cu")
		(net "M_G_CPU0_SA_DQS_DN<2>")
	)
	(segment
		(start 410.170376 -219.940632)
		(end 410.513784 -219.597224)
		(width 0.12954)
		(layer "F.Cu")
		(net "M_G_CPU0_SA_DQS_DN<2>")
	)
	(arc
		(start 393.98067 -237.21187)
		(mid 394.004147 -237.213246)
		(end 394.02766 -237.213648)
		(width 0.0762)
		(layer "F.Cu")
		(net "M_G_CPU0_SA_DQS_DN<2>")
	)
	(arc
		(start 393.62253 -237.092744)
		(mid 393.681176 -237.108037)
		(end 393.736576 -237.132622)
		(width 0.0762)
		(layer "F.Cu")
		(net "M_G_CPU0_SA_DQS_DN<2>")
	)
	(arc
		(start 393.744958 -237.137448)
		(mid 393.858682 -237.187749)
		(end 393.98067 -237.21187)
		(width 0.0762)
		(layer "F.Cu")
		(net "M_G_CPU0_SA_DQS_DN<2>")
	)
	(arc
		(start 393.455652 -237.283752)
		(mid 393.485281 -237.141265)
		(end 393.62253 -237.092744)
		(width 0.0762)
		(layer "F.Cu")
		(net "M_G_CPU0_SA_DQS_DN<2>")
	)
	(segment
		(start 405.545798 -215.47963)
		(end 406.13711 -215.47963)
		(width 0.12954)
		(layer "F.Cu")
		(net "M_G_CPU0_SA_DQS_DN<1>")
	)
	(segment
		(start 405.366728 -216.250012)
		(end 405.366728 -215.6587)
		(width 0.12954)
		(layer "F.Cu")
		(net "M_G_CPU0_SA_DQS_DN<1>")
	)
	(segment
		(start 403.093428 -218.523312)
		(end 403.093428 -217.932)
		(width 0.12954)
		(layer "F.Cu")
		(net "M_G_CPU0_SA_DQS_DN<1>")
	)
	(segment
		(start 411.50667 -210.51012)
		(end 413.93491 -210.51012)
		(width 0.101346)
		(layer "F.Cu")
		(net "M_G_CPU0_SA_DQS_DN<1>")
	)
	(segment
		(start 404.409148 -216.61628)
		(end 405.00046 -216.61628)
		(width 0.12954)
		(layer "F.Cu")
		(net "M_G_CPU0_SA_DQS_DN<1>")
	)
	(segment
		(start 410.88564 -210.27771)
		(end 411.27426 -210.27771)
		(width 0.12954)
		(layer "F.Cu")
		(net "M_G_CPU0_SA_DQS_DN<1>")
	)
	(segment
		(start 393.736576 -232.272586)
		(end 393.744958 -232.277412)
		(width 0.0762)
		(layer "F.Cu")
		(net "M_G_CPU0_SA_DQS_DN<1>")
	)
	(segment
		(start 413.93491 -210.51012)
		(end 414.25241 -210.19262)
		(width 0.101346)
		(layer "F.Cu")
		(net "M_G_CPU0_SA_DQS_DN<1>")
	)
	(segment
		(start 414.25241 -210.19262)
		(end 414.54705 -210.19262)
		(width 0.101346)
		(layer "F.Cu")
		(net "M_G_CPU0_SA_DQS_DN<1>")
	)
	(segment
		(start 414.972246 -210.617816)
		(end 415.635694 -210.617816)
		(width 0.101346)
		(layer "F.Cu")
		(net "M_G_CPU0_SA_DQS_DN<1>")
	)
	(segment
		(start 403.093428 -217.932)
		(end 403.272498 -217.75293)
		(width 0.12954)
		(layer "F.Cu")
		(net "M_G_CPU0_SA_DQS_DN<1>")
	)
	(segment
		(start 404.230078 -216.79535)
		(end 404.409148 -216.61628)
		(width 0.12954)
		(layer "F.Cu")
		(net "M_G_CPU0_SA_DQS_DN<1>")
	)
	(segment
		(start 395.649958 -232.152952)
		(end 395.669008 -232.152952)
		(width 0.0762)
		(layer "F.Cu")
		(net "M_G_CPU0_SA_DQS_DN<1>")
	)
	(segment
		(start 401.956778 -226.15779)
		(end 401.956778 -219.659962)
		(width 0.12954)
		(layer "F.Cu")
		(net "M_G_CPU0_SA_DQS_DN<1>")
	)
	(segment
		(start 411.27426 -210.27771)
		(end 411.50667 -210.51012)
		(width 0.12954)
		(layer "F.Cu")
		(net "M_G_CPU0_SA_DQS_DN<1>")
	)
	(segment
		(start 406.13711 -215.47963)
		(end 406.560274 -215.056466)
		(width 0.12954)
		(layer "F.Cu")
		(net "M_G_CPU0_SA_DQS_DN<1>")
	)
	(segment
		(start 415.635694 -210.617816)
		(end 415.95294 -210.935062)
		(width 0.101346)
		(layer "F.Cu")
		(net "M_G_CPU0_SA_DQS_DN<1>")
	)
	(segment
		(start 414.54705 -210.19262)
		(end 414.972246 -210.617816)
		(width 0.101346)
		(layer "F.Cu")
		(net "M_G_CPU0_SA_DQS_DN<1>")
	)
	(segment
		(start 394.02766 -232.353612)
		(end 394.951712 -232.353612)
		(width 0.0762)
		(layer "F.Cu")
		(net "M_G_CPU0_SA_DQS_DN<1>")
	)
	(segment
		(start 404.230078 -217.386662)
		(end 404.230078 -216.79535)
		(width 0.12954)
		(layer "F.Cu")
		(net "M_G_CPU0_SA_DQS_DN<1>")
	)
	(segment
		(start 405.00046 -216.61628)
		(end 405.366728 -216.250012)
		(width 0.12954)
		(layer "F.Cu")
		(net "M_G_CPU0_SA_DQS_DN<1>")
	)
	(segment
		(start 395.669008 -232.152952)
		(end 395.961616 -232.152952)
		(width 0.12954)
		(layer "F.Cu")
		(net "M_G_CPU0_SA_DQS_DN<1>")
	)
	(segment
		(start 395.218412 -232.086912)
		(end 395.583918 -232.086912)
		(width 0.0762)
		(layer "F.Cu")
		(net "M_G_CPU0_SA_DQS_DN<1>")
	)
	(segment
		(start 415.95294 -210.935062)
		(end 416.468052 -210.935062)
		(width 0.101346)
		(layer "F.Cu")
		(net "M_G_CPU0_SA_DQS_DN<1>")
	)
	(segment
		(start 406.560274 -215.056466)
		(end 406.560274 -213.41461)
		(width 0.12954)
		(layer "F.Cu")
		(net "M_G_CPU0_SA_DQS_DN<1>")
	)
	(segment
		(start 403.86381 -217.75293)
		(end 404.230078 -217.386662)
		(width 0.12954)
		(layer "F.Cu")
		(net "M_G_CPU0_SA_DQS_DN<1>")
	)
	(segment
		(start 401.956778 -219.659962)
		(end 403.093428 -218.523312)
		(width 0.12954)
		(layer "F.Cu")
		(net "M_G_CPU0_SA_DQS_DN<1>")
	)
	(segment
		(start 410.718 -210.44535)
		(end 410.88564 -210.27771)
		(width 0.12954)
		(layer "F.Cu")
		(net "M_G_CPU0_SA_DQS_DN<1>")
	)
	(segment
		(start 394.951712 -232.353612)
		(end 395.218412 -232.086912)
		(width 0.0762)
		(layer "F.Cu")
		(net "M_G_CPU0_SA_DQS_DN<1>")
	)
	(segment
		(start 409.697174 -210.27771)
		(end 410.16174 -210.27771)
		(width 0.12954)
		(layer "F.Cu")
		(net "M_G_CPU0_SA_DQS_DN<1>")
	)
	(segment
		(start 405.366728 -215.6587)
		(end 405.545798 -215.47963)
		(width 0.12954)
		(layer "F.Cu")
		(net "M_G_CPU0_SA_DQS_DN<1>")
	)
	(segment
		(start 395.583918 -232.086912)
		(end 395.649958 -232.152952)
		(width 0.0762)
		(layer "F.Cu")
		(net "M_G_CPU0_SA_DQS_DN<1>")
	)
	(segment
		(start 395.961616 -232.152952)
		(end 401.956778 -226.15779)
		(width 0.12954)
		(layer "F.Cu")
		(net "M_G_CPU0_SA_DQS_DN<1>")
	)
	(segment
		(start 410.16174 -210.27771)
		(end 410.32938 -210.44535)
		(width 0.12954)
		(layer "F.Cu")
		(net "M_G_CPU0_SA_DQS_DN<1>")
	)
	(segment
		(start 406.560274 -213.41461)
		(end 409.697174 -210.27771)
		(width 0.12954)
		(layer "F.Cu")
		(net "M_G_CPU0_SA_DQS_DN<1>")
	)
	(segment
		(start 403.272498 -217.75293)
		(end 403.86381 -217.75293)
		(width 0.12954)
		(layer "F.Cu")
		(net "M_G_CPU0_SA_DQS_DN<1>")
	)
	(segment
		(start 410.32938 -210.44535)
		(end 410.718 -210.44535)
		(width 0.12954)
		(layer "F.Cu")
		(net "M_G_CPU0_SA_DQS_DN<1>")
	)
	(segment
		(start 393.558014 -232.599992)
		(end 393.455652 -232.423716)
		(width 0.0762)
		(layer "F.Cu")
		(net "M_G_CPU0_SA_DQS_DN<1>")
	)
	(arc
		(start 393.455652 -232.423716)
		(mid 393.485281 -232.281229)
		(end 393.62253 -232.232708)
		(width 0.0762)
		(layer "F.Cu")
		(net "M_G_CPU0_SA_DQS_DN<1>")
	)
	(arc
		(start 393.62253 -232.232708)
		(mid 393.681176 -232.248001)
		(end 393.736576 -232.272586)
		(width 0.0762)
		(layer "F.Cu")
		(net "M_G_CPU0_SA_DQS_DN<1>")
	)
	(arc
		(start 393.744958 -232.277412)
		(mid 393.858682 -232.327713)
		(end 393.98067 -232.351834)
		(width 0.0762)
		(layer "F.Cu")
		(net "M_G_CPU0_SA_DQS_DN<1>")
	)
	(arc
		(start 393.98067 -232.351834)
		(mid 394.004147 -232.35321)
		(end 394.02766 -232.353612)
		(width 0.0762)
		(layer "F.Cu")
		(net "M_G_CPU0_SA_DQS_DN<1>")
	)
	(segment
		(start 411.24378 -200.897236)
		(end 411.50667 -201.160126)
		(width 0.12954)
		(layer "F.Cu")
		(net "M_G_CPU0_SA_DQS_DN<0>")
	)
	(segment
		(start 405.578818 -206.956406)
		(end 405.578818 -205.94193)
		(width 0.12954)
		(layer "F.Cu")
		(net "M_G_CPU0_SA_DQS_DN<0>")
	)
	(segment
		(start 406.649428 -204.87132)
		(end 406.886664 -204.87132)
		(width 0.12954)
		(layer "F.Cu")
		(net "M_G_CPU0_SA_DQS_DN<0>")
	)
	(segment
		(start 406.099772 -205.658212)
		(end 406.374854 -205.38313)
		(width 0.12954)
		(layer "F.Cu")
		(net "M_G_CPU0_SA_DQS_DN<0>")
	)
	(segment
		(start 405.862536 -205.658212)
		(end 406.099772 -205.658212)
		(width 0.12954)
		(layer "F.Cu")
		(net "M_G_CPU0_SA_DQS_DN<0>")
	)
	(segment
		(start 415.95294 -201.585068)
		(end 416.468052 -201.585068)
		(width 0.101346)
		(layer "F.Cu")
		(net "M_G_CPU0_SA_DQS_DN<0>")
	)
	(segment
		(start 414.25241 -200.842626)
		(end 414.52165 -200.842626)
		(width 0.101346)
		(layer "F.Cu")
		(net "M_G_CPU0_SA_DQS_DN<0>")
	)
	(segment
		(start 397.316198 -224.41789)
		(end 397.316198 -215.219026)
		(width 0.12954)
		(layer "F.Cu")
		(net "M_G_CPU0_SA_DQS_DN<0>")
	)
	(segment
		(start 395.515592 -226.125278)
		(end 395.609064 -226.125278)
		(width 0.0762)
		(layer "F.Cu")
		(net "M_G_CPU0_SA_DQS_DN<0>")
	)
	(segment
		(start 407.161746 -204.359002)
		(end 410.623512 -200.897236)
		(width 0.12954)
		(layer "F.Cu")
		(net "M_G_CPU0_SA_DQS_DN<0>")
	)
	(segment
		(start 406.374854 -205.38313)
		(end 406.374854 -205.145894)
		(width 0.12954)
		(layer "F.Cu")
		(net "M_G_CPU0_SA_DQS_DN<0>")
	)
	(segment
		(start 407.161746 -204.596238)
		(end 407.161746 -204.359002)
		(width 0.12954)
		(layer "F.Cu")
		(net "M_G_CPU0_SA_DQS_DN<0>")
	)
	(segment
		(start 395.091158 -226.840542)
		(end 395.091158 -226.549712)
		(width 0.0762)
		(layer "F.Cu")
		(net "M_G_CPU0_SA_DQS_DN<0>")
	)
	(segment
		(start 395.091158 -226.549712)
		(end 395.515592 -226.125278)
		(width 0.0762)
		(layer "F.Cu")
		(net "M_G_CPU0_SA_DQS_DN<0>")
	)
	(segment
		(start 411.50667 -201.160126)
		(end 413.93491 -201.160126)
		(width 0.101346)
		(layer "F.Cu")
		(net "M_G_CPU0_SA_DQS_DN<0>")
	)
	(segment
		(start 405.578818 -205.94193)
		(end 405.862536 -205.658212)
		(width 0.12954)
		(layer "F.Cu")
		(net "M_G_CPU0_SA_DQS_DN<0>")
	)
	(segment
		(start 414.52165 -200.842626)
		(end 414.946846 -201.267822)
		(width 0.101346)
		(layer "F.Cu")
		(net "M_G_CPU0_SA_DQS_DN<0>")
	)
	(segment
		(start 395.609064 -226.125278)
		(end 395.622526 -226.111816)
		(width 0.0762)
		(layer "F.Cu")
		(net "M_G_CPU0_SA_DQS_DN<0>")
	)
	(segment
		(start 393.558014 -227.74021)
		(end 393.455652 -227.563934)
		(width 0.0762)
		(layer "F.Cu")
		(net "M_G_CPU0_SA_DQS_DN<0>")
	)
	(segment
		(start 410.623512 -200.897236)
		(end 411.24378 -200.897236)
		(width 0.12954)
		(layer "F.Cu")
		(net "M_G_CPU0_SA_DQS_DN<0>")
	)
	(segment
		(start 415.635694 -201.267822)
		(end 415.95294 -201.585068)
		(width 0.101346)
		(layer "F.Cu")
		(net "M_G_CPU0_SA_DQS_DN<0>")
	)
	(segment
		(start 397.316198 -215.219026)
		(end 405.578818 -206.956406)
		(width 0.12954)
		(layer "F.Cu")
		(net "M_G_CPU0_SA_DQS_DN<0>")
	)
	(segment
		(start 394.24991 -227.49383)
		(end 394.570966 -227.360734)
		(width 0.0762)
		(layer "F.Cu")
		(net "M_G_CPU0_SA_DQS_DN<0>")
	)
	(segment
		(start 406.886664 -204.87132)
		(end 407.161746 -204.596238)
		(width 0.12954)
		(layer "F.Cu")
		(net "M_G_CPU0_SA_DQS_DN<0>")
	)
	(segment
		(start 406.374854 -205.145894)
		(end 406.649428 -204.87132)
		(width 0.12954)
		(layer "F.Cu")
		(net "M_G_CPU0_SA_DQS_DN<0>")
	)
	(segment
		(start 395.622526 -226.111816)
		(end 397.316198 -224.41789)
		(width 0.12954)
		(layer "F.Cu")
		(net "M_G_CPU0_SA_DQS_DN<0>")
	)
	(segment
		(start 414.946846 -201.267822)
		(end 415.635694 -201.267822)
		(width 0.101346)
		(layer "F.Cu")
		(net "M_G_CPU0_SA_DQS_DN<0>")
	)
	(segment
		(start 394.570966 -227.360734)
		(end 395.091158 -226.840542)
		(width 0.0762)
		(layer "F.Cu")
		(net "M_G_CPU0_SA_DQS_DN<0>")
	)
	(segment
		(start 394.02766 -227.49383)
		(end 394.24991 -227.49383)
		(width 0.0762)
		(layer "F.Cu")
		(net "M_G_CPU0_SA_DQS_DN<0>")
	)
	(segment
		(start 393.736576 -227.412804)
		(end 393.744958 -227.41763)
		(width 0.0762)
		(layer "F.Cu")
		(net "M_G_CPU0_SA_DQS_DN<0>")
	)
	(segment
		(start 413.93491 -201.160126)
		(end 414.25241 -200.842626)
		(width 0.101346)
		(layer "F.Cu")
		(net "M_G_CPU0_SA_DQS_DN<0>")
	)
	(arc
		(start 393.62253 -227.372926)
		(mid 393.681176 -227.388219)
		(end 393.736576 -227.412804)
		(width 0.0762)
		(layer "F.Cu")
		(net "M_G_CPU0_SA_DQS_DN<0>")
	)
	(arc
		(start 393.455652 -227.563934)
		(mid 393.485281 -227.421447)
		(end 393.62253 -227.372926)
		(width 0.0762)
		(layer "F.Cu")
		(net "M_G_CPU0_SA_DQS_DN<0>")
	)
	(arc
		(start 393.98067 -227.492052)
		(mid 394.004147 -227.493428)
		(end 394.02766 -227.49383)
		(width 0.0762)
		(layer "F.Cu")
		(net "M_G_CPU0_SA_DQS_DN<0>")
	)
	(arc
		(start 393.744958 -227.41763)
		(mid 393.858682 -227.467931)
		(end 393.98067 -227.492052)
		(width 0.0762)
		(layer "F.Cu")
		(net "M_G_CPU0_SA_DQS_DN<0>")
	)
	(segment
		(start 403.409658 -216.097612)
		(end 403.409658 -214.986108)
		(width 0.10668)
		(layer "F.Cu")
		(net "M_G_CPU0_SA_DQ<9>")
	)
	(segment
		(start 403.409658 -214.986108)
		(end 409.585668 -208.810098)
		(width 0.10668)
		(layer "F.Cu")
		(net "M_G_CPU0_SA_DQ<9>")
	)
	(segment
		(start 395.108176 -231.03459)
		(end 395.540992 -231.03459)
		(width 0.0762)
		(layer "F.Cu")
		(net "M_G_CPU0_SA_DQ<9>")
	)
	(segment
		(start 411.317694 -208.810098)
		(end 413.627062 -208.810098)
		(width 0.101346)
		(layer "F.Cu")
		(net "M_G_CPU0_SA_DQ<9>")
	)
	(segment
		(start 400.840194 -225.735388)
		(end 400.840194 -218.667076)
		(width 0.10668)
		(layer "F.Cu")
		(net "M_G_CPU0_SA_DQ<9>")
	)
	(segment
		(start 400.840194 -218.667076)
		(end 403.409658 -216.097612)
		(width 0.10668)
		(layer "F.Cu")
		(net "M_G_CPU0_SA_DQ<9>")
	)
	(segment
		(start 409.585668 -208.810098)
		(end 411.317694 -208.810098)
		(width 0.10668)
		(layer "F.Cu")
		(net "M_G_CPU0_SA_DQ<9>")
	)
	(segment
		(start 393.736576 -231.307386)
		(end 393.744958 -231.30256)
		(width 0.0762)
		(layer "F.Cu")
		(net "M_G_CPU0_SA_DQ<9>")
	)
	(segment
		(start 413.627062 -208.810098)
		(end 414.052004 -208.385156)
		(width 0.101346)
		(layer "F.Cu")
		(net "M_G_CPU0_SA_DQ<9>")
	)
	(segment
		(start 395.028674 -231.114092)
		(end 395.108176 -231.03459)
		(width 0.0762)
		(layer "F.Cu")
		(net "M_G_CPU0_SA_DQ<9>")
	)
	(segment
		(start 414.052004 -208.385156)
		(end 416.468052 -208.385156)
		(width 0.101346)
		(layer "F.Cu")
		(net "M_G_CPU0_SA_DQ<9>")
	)
	(segment
		(start 394.444728 -231.114092)
		(end 395.028674 -231.114092)
		(width 0.0762)
		(layer "F.Cu")
		(net "M_G_CPU0_SA_DQ<9>")
	)
	(segment
		(start 395.540992 -231.03459)
		(end 400.840194 -225.735388)
		(width 0.10668)
		(layer "F.Cu")
		(net "M_G_CPU0_SA_DQ<9>")
	)
	(arc
		(start 392.431016 -231.30256)
		(mid 392.61796 -231.352849)
		(end 392.804904 -231.30256)
		(width 0.0762)
		(layer "F.Cu")
		(net "M_G_CPU0_SA_DQ<9>")
	)
	(arc
		(start 392.146536 -231.226106)
		(mid 392.293857 -231.245425)
		(end 392.431016 -231.30256)
		(width 0.0762)
		(layer "F.Cu")
		(net "M_G_CPU0_SA_DQ<9>")
	)
	(arc
		(start 392.804904 -231.30256)
		(mid 393.08786 -231.226383)
		(end 393.370816 -231.30256)
		(width 0.0762)
		(layer "F.Cu")
		(net "M_G_CPU0_SA_DQ<9>")
	)
	(arc
		(start 393.370816 -231.30256)
		(mid 393.553067 -231.352944)
		(end 393.736576 -231.307386)
		(width 0.0762)
		(layer "F.Cu")
		(net "M_G_CPU0_SA_DQ<9>")
	)
	(arc
		(start 391.677906 -230.97998)
		(mid 391.881871 -231.160829)
		(end 392.146536 -231.226106)
		(width 0.0762)
		(layer "F.Cu")
		(net "M_G_CPU0_SA_DQ<9>")
	)
	(arc
		(start 393.744958 -231.30256)
		(mid 394.082382 -231.16207)
		(end 394.444728 -231.114092)
		(width 0.0762)
		(layer "F.Cu")
		(net "M_G_CPU0_SA_DQ<9>")
	)
	(segment
		(start 394.05179 -230.54945)
		(end 394.823188 -230.54945)
		(width 0.0762)
		(layer "F.Cu")
		(net "M_G_CPU0_SA_DQ<8>")
	)
	(segment
		(start 414.960562 -207.110076)
		(end 415.385504 -206.685134)
		(width 0.101346)
		(layer "F.Cu")
		(net "M_G_CPU0_SA_DQ<8>")
	)
	(segment
		(start 395.301724 -230.31069)
		(end 400.159474 -225.45294)
		(width 0.10668)
		(layer "F.Cu")
		(net "M_G_CPU0_SA_DQ<8>")
	)
	(segment
		(start 400.159474 -217.273124)
		(end 410.322522 -207.110076)
		(width 0.10668)
		(layer "F.Cu")
		(net "M_G_CPU0_SA_DQ<8>")
	)
	(segment
		(start 411.317694 -207.110076)
		(end 414.960562 -207.110076)
		(width 0.101346)
		(layer "F.Cu")
		(net "M_G_CPU0_SA_DQ<8>")
	)
	(segment
		(start 410.322522 -207.110076)
		(end 411.317694 -207.110076)
		(width 0.10668)
		(layer "F.Cu")
		(net "M_G_CPU0_SA_DQ<8>")
	)
	(segment
		(start 395.061948 -230.31069)
		(end 395.301724 -230.31069)
		(width 0.0762)
		(layer "F.Cu")
		(net "M_G_CPU0_SA_DQ<8>")
	)
	(segment
		(start 400.159474 -225.45294)
		(end 400.159474 -217.273124)
		(width 0.10668)
		(layer "F.Cu")
		(net "M_G_CPU0_SA_DQ<8>")
	)
	(segment
		(start 394.823188 -230.54945)
		(end 395.061948 -230.31069)
		(width 0.0762)
		(layer "F.Cu")
		(net "M_G_CPU0_SA_DQ<8>")
	)
	(segment
		(start 415.385504 -206.685134)
		(end 416.468052 -206.685134)
		(width 0.101346)
		(layer "F.Cu")
		(net "M_G_CPU0_SA_DQ<8>")
	)
	(arc
		(start 393.84097 -230.492554)
		(mid 393.94261 -230.534969)
		(end 394.05179 -230.54945)
		(width 0.0762)
		(layer "F.Cu")
		(net "M_G_CPU0_SA_DQ<8>")
	)
	(arc
		(start 393.08786 -230.169974)
		(mid 393.323988 -230.341409)
		(end 393.605512 -230.418132)
		(width 0.0762)
		(layer "F.Cu")
		(net "M_G_CPU0_SA_DQ<8>")
	)
	(arc
		(start 393.605512 -230.418132)
		(mid 393.727368 -230.442288)
		(end 393.84097 -230.492554)
		(width 0.0762)
		(layer "F.Cu")
		(net "M_G_CPU0_SA_DQ<8>")
	)
	(segment
		(start 400.225006 -216.352374)
		(end 399.82521 -215.953086)
		(width 0.10668)
		(layer "F.Cu")
		(net "M_G_CPU0_SA_DQ<7>")
	)
	(segment
		(start 392.326622 -229.842822)
		(end 392.335004 -229.847648)
		(width 0.0762)
		(layer "F.Cu")
		(net "M_G_CPU0_SA_DQ<7>")
	)
	(segment
		(start 400.389852 -215.787986)
		(end 400.389852 -215.953086)
		(width 0.10668)
		(layer "F.Cu")
		(net "M_G_CPU0_SA_DQ<7>")
	)
	(segment
		(start 394.028422 -229.797102)
		(end 395.163294 -229.797102)
		(width 0.0762)
		(layer "F.Cu")
		(net "M_G_CPU0_SA_DQ<7>")
	)
	(segment
		(start 392.900916 -229.847648)
		(end 392.909298 -229.842822)
		(width 0.0762)
		(layer "F.Cu")
		(net "M_G_CPU0_SA_DQ<7>")
	)
	(segment
		(start 394.027914 -229.79761)
		(end 394.028422 -229.797102)
		(width 0.0762)
		(layer "F.Cu")
		(net "M_G_CPU0_SA_DQ<7>")
	)
	(segment
		(start 400.389852 -215.953086)
		(end 400.5072 -216.07018)
		(width 0.10668)
		(layer "F.Cu")
		(net "M_G_CPU0_SA_DQ<7>")
	)
	(segment
		(start 399.697194 -217.045286)
		(end 400.225006 -216.517474)
		(width 0.10668)
		(layer "F.Cu")
		(net "M_G_CPU0_SA_DQ<7>")
	)
	(segment
		(start 395.865858 -229.094538)
		(end 399.697194 -225.263202)
		(width 0.10668)
		(layer "F.Cu")
		(net "M_G_CPU0_SA_DQ<7>")
	)
	(segment
		(start 400.225006 -216.517474)
		(end 400.225006 -216.352374)
		(width 0.10668)
		(layer "F.Cu")
		(net "M_G_CPU0_SA_DQ<7>")
	)
	(segment
		(start 400.6723 -216.07018)
		(end 410.907484 -205.834996)
		(width 0.10668)
		(layer "F.Cu")
		(net "M_G_CPU0_SA_DQ<7>")
	)
	(segment
		(start 392.14806 -230.169974)
		(end 392.046206 -229.994968)
		(width 0.0762)
		(layer "F.Cu")
		(net "M_G_CPU0_SA_DQ<7>")
	)
	(segment
		(start 402.125942 -213.88705)
		(end 402.125942 -214.051896)
		(width 0.10668)
		(layer "F.Cu")
		(net "M_G_CPU0_SA_DQ<7>")
	)
	(segment
		(start 395.163294 -229.797102)
		(end 395.865858 -229.094538)
		(width 0.0762)
		(layer "F.Cu")
		(net "M_G_CPU0_SA_DQ<7>")
	)
	(segment
		(start 399.697194 -225.263202)
		(end 399.697194 -217.045286)
		(width 0.10668)
		(layer "F.Cu")
		(net "M_G_CPU0_SA_DQ<7>")
	)
	(segment
		(start 400.5072 -216.07018)
		(end 400.6723 -216.07018)
		(width 0.10668)
		(layer "F.Cu")
		(net "M_G_CPU0_SA_DQ<7>")
	)
	(segment
		(start 399.82521 -215.787986)
		(end 401.843494 -213.769702)
		(width 0.10668)
		(layer "F.Cu")
		(net "M_G_CPU0_SA_DQ<7>")
	)
	(segment
		(start 402.008594 -213.769702)
		(end 402.125942 -213.88705)
		(width 0.10668)
		(layer "F.Cu")
		(net "M_G_CPU0_SA_DQ<7>")
	)
	(segment
		(start 399.82521 -215.953086)
		(end 399.82521 -215.787986)
		(width 0.10668)
		(layer "F.Cu")
		(net "M_G_CPU0_SA_DQ<7>")
	)
	(segment
		(start 401.843494 -213.769702)
		(end 402.008594 -213.769702)
		(width 0.10668)
		(layer "F.Cu")
		(net "M_G_CPU0_SA_DQ<7>")
	)
	(segment
		(start 402.125942 -214.051896)
		(end 400.389852 -215.787986)
		(width 0.10668)
		(layer "F.Cu")
		(net "M_G_CPU0_SA_DQ<7>")
	)
	(segment
		(start 410.907484 -205.834996)
		(end 412.367984 -205.834996)
		(width 0.10668)
		(layer "F.Cu")
		(net "M_G_CPU0_SA_DQ<7>")
	)
	(arc
		(start 393.84097 -229.847648)
		(mid 393.931139 -229.810299)
		(end 394.027914 -229.79761)
		(width 0.0762)
		(layer "F.Cu")
		(net "M_G_CPU0_SA_DQ<7>")
	)
	(arc
		(start 392.335004 -229.847648)
		(mid 392.61796 -229.923825)
		(end 392.900916 -229.847648)
		(width 0.0762)
		(layer "F.Cu")
		(net "M_G_CPU0_SA_DQ<7>")
	)
	(arc
		(start 392.909298 -229.842822)
		(mid 393.092806 -229.797328)
		(end 393.275058 -229.847648)
		(width 0.0762)
		(layer "F.Cu")
		(net "M_G_CPU0_SA_DQ<7>")
	)
	(arc
		(start 392.046206 -229.994968)
		(mid 392.0634 -229.855382)
		(end 392.192764 -229.80015)
		(width 0.0762)
		(layer "F.Cu")
		(net "M_G_CPU0_SA_DQ<7>")
	)
	(arc
		(start 393.275058 -229.847648)
		(mid 393.558014 -229.923825)
		(end 393.84097 -229.847648)
		(width 0.0762)
		(layer "F.Cu")
		(net "M_G_CPU0_SA_DQ<7>")
	)
	(arc
		(start 392.192764 -229.80015)
		(mid 392.261711 -229.815147)
		(end 392.326622 -229.842822)
		(width 0.0762)
		(layer "F.Cu")
		(net "M_G_CPU0_SA_DQ<7>")
	)
	(segment
		(start 402.055076 -212.760052)
		(end 402.454364 -213.15934)
		(width 0.10668)
		(layer "F.Cu")
		(net "M_G_CPU0_SA_DQ<6>")
	)
	(segment
		(start 404.14702 -210.503008)
		(end 405.276304 -210.503008)
		(width 0.10668)
		(layer "F.Cu")
		(net "M_G_CPU0_SA_DQ<6>")
	)
	(segment
		(start 393.736576 -229.032816)
		(end 393.744958 -229.037642)
		(width 0.0762)
		(layer "F.Cu")
		(net "M_G_CPU0_SA_DQ<6>")
	)
	(segment
		(start 405.276304 -210.503008)
		(end 411.644338 -204.134974)
		(width 0.10668)
		(layer "F.Cu")
		(net "M_G_CPU0_SA_DQ<6>")
	)
	(segment
		(start 395.286738 -228.940106)
		(end 395.286738 -228.696266)
		(width 0.0762)
		(layer "F.Cu")
		(net "M_G_CPU0_SA_DQ<6>")
	)
	(segment
		(start 393.558014 -229.360222)
		(end 393.462256 -229.195376)
		(width 0.0762)
		(layer "F.Cu")
		(net "M_G_CPU0_SA_DQ<6>")
	)
	(segment
		(start 404.594822 -211.018882)
		(end 404.477728 -210.901788)
		(width 0.10668)
		(layer "F.Cu")
		(net "M_G_CPU0_SA_DQ<6>")
	)
	(segment
		(start 395.815058 -228.167946)
		(end 398.894554 -225.08845)
		(width 0.10668)
		(layer "F.Cu")
		(net "M_G_CPU0_SA_DQ<6>")
	)
	(segment
		(start 411.644338 -204.134974)
		(end 412.367984 -204.134974)
		(width 0.10668)
		(layer "F.Cu")
		(net "M_G_CPU0_SA_DQ<6>")
	)
	(segment
		(start 398.894554 -215.755474)
		(end 401.889976 -212.760052)
		(width 0.10668)
		(layer "F.Cu")
		(net "M_G_CPU0_SA_DQ<6>")
	)
	(segment
		(start 402.619464 -213.15934)
		(end 404.594822 -211.183982)
		(width 0.10668)
		(layer "F.Cu")
		(net "M_G_CPU0_SA_DQ<6>")
	)
	(segment
		(start 401.889976 -212.760052)
		(end 402.055076 -212.760052)
		(width 0.10668)
		(layer "F.Cu")
		(net "M_G_CPU0_SA_DQ<6>")
	)
	(segment
		(start 394.173456 -229.16261)
		(end 395.064234 -229.16261)
		(width 0.0762)
		(layer "F.Cu")
		(net "M_G_CPU0_SA_DQ<6>")
	)
	(segment
		(start 402.454364 -213.15934)
		(end 402.619464 -213.15934)
		(width 0.10668)
		(layer "F.Cu")
		(net "M_G_CPU0_SA_DQ<6>")
	)
	(segment
		(start 398.894554 -225.08845)
		(end 398.894554 -215.755474)
		(width 0.10668)
		(layer "F.Cu")
		(net "M_G_CPU0_SA_DQ<6>")
	)
	(segment
		(start 402.33727 -212.312758)
		(end 404.14702 -210.503008)
		(width 0.10668)
		(layer "F.Cu")
		(net "M_G_CPU0_SA_DQ<6>")
	)
	(segment
		(start 404.477728 -210.901788)
		(end 404.312628 -210.901788)
		(width 0.10668)
		(layer "F.Cu")
		(net "M_G_CPU0_SA_DQ<6>")
	)
	(segment
		(start 395.064234 -229.16261)
		(end 395.286738 -228.940106)
		(width 0.0762)
		(layer "F.Cu")
		(net "M_G_CPU0_SA_DQ<6>")
	)
	(segment
		(start 402.33727 -212.477858)
		(end 402.33727 -212.312758)
		(width 0.10668)
		(layer "F.Cu")
		(net "M_G_CPU0_SA_DQ<6>")
	)
	(segment
		(start 402.619464 -212.594952)
		(end 402.454364 -212.594952)
		(width 0.10668)
		(layer "F.Cu")
		(net "M_G_CPU0_SA_DQ<6>")
	)
	(segment
		(start 402.454364 -212.594952)
		(end 402.33727 -212.477858)
		(width 0.10668)
		(layer "F.Cu")
		(net "M_G_CPU0_SA_DQ<6>")
	)
	(segment
		(start 404.594822 -211.183982)
		(end 404.594822 -211.018882)
		(width 0.10668)
		(layer "F.Cu")
		(net "M_G_CPU0_SA_DQ<6>")
	)
	(segment
		(start 395.286738 -228.696266)
		(end 395.815058 -228.167946)
		(width 0.0762)
		(layer "F.Cu")
		(net "M_G_CPU0_SA_DQ<6>")
	)
	(segment
		(start 404.312628 -210.901788)
		(end 402.619464 -212.594952)
		(width 0.10668)
		(layer "F.Cu")
		(net "M_G_CPU0_SA_DQ<6>")
	)
	(arc
		(start 393.608306 -228.990652)
		(mid 393.674374 -229.005861)
		(end 393.736576 -229.032816)
		(width 0.0762)
		(layer "F.Cu")
		(net "M_G_CPU0_SA_DQ<6>")
	)
	(arc
		(start 393.744958 -229.037642)
		(mid 393.95028 -229.130738)
		(end 394.173456 -229.16261)
		(width 0.0762)
		(layer "F.Cu")
		(net "M_G_CPU0_SA_DQ<6>")
	)
	(arc
		(start 393.462256 -229.195376)
		(mid 393.473446 -229.04882)
		(end 393.608306 -228.990652)
		(width 0.0762)
		(layer "F.Cu")
		(net "M_G_CPU0_SA_DQ<6>")
	)
	(segment
		(start 402.408136 -213.687406)
		(end 402.57349 -213.687406)
		(width 0.10668)
		(layer "F.Cu")
		(net "M_G_CPU0_SA_DQ<5>")
	)
	(segment
		(start 414.223454 -204.985112)
		(end 416.468052 -204.985112)
		(width 0.101346)
		(layer "F.Cu")
		(net "M_G_CPU0_SA_DQ<5>")
	)
	(segment
		(start 395.010894 -229.606602)
		(end 395.545818 -229.071678)
		(width 0.0762)
		(layer "F.Cu")
		(net "M_G_CPU0_SA_DQ<5>")
	)
	(segment
		(start 395.545818 -229.071678)
		(end 395.545818 -228.91877)
		(width 0.0762)
		(layer "F.Cu")
		(net "M_G_CPU0_SA_DQ<5>")
	)
	(segment
		(start 402.57349 -213.687406)
		(end 410.850842 -205.410054)
		(width 0.10668)
		(layer "F.Cu")
		(net "M_G_CPU0_SA_DQ<5>")
	)
	(segment
		(start 402.036534 -213.315804)
		(end 402.408136 -213.687406)
		(width 0.10668)
		(layer "F.Cu")
		(net "M_G_CPU0_SA_DQ<5>")
	)
	(segment
		(start 410.850842 -205.410054)
		(end 411.317694 -205.410054)
		(width 0.10668)
		(layer "F.Cu")
		(net "M_G_CPU0_SA_DQ<5>")
	)
	(segment
		(start 395.545818 -228.91877)
		(end 395.876018 -228.58857)
		(width 0.0762)
		(layer "F.Cu")
		(net "M_G_CPU0_SA_DQ<5>")
	)
	(segment
		(start 395.876018 -228.58857)
		(end 399.295874 -225.168714)
		(width 0.10668)
		(layer "F.Cu")
		(net "M_G_CPU0_SA_DQ<5>")
	)
	(segment
		(start 399.295874 -225.168714)
		(end 399.295874 -215.835738)
		(width 0.10668)
		(layer "F.Cu")
		(net "M_G_CPU0_SA_DQ<5>")
	)
	(segment
		(start 401.815808 -213.315804)
		(end 402.036534 -213.315804)
		(width 0.10668)
		(layer "F.Cu")
		(net "M_G_CPU0_SA_DQ<5>")
	)
	(segment
		(start 393.736576 -229.687628)
		(end 393.744958 -229.682802)
		(width 0.0762)
		(layer "F.Cu")
		(net "M_G_CPU0_SA_DQ<5>")
	)
	(segment
		(start 394.027914 -229.606602)
		(end 395.010894 -229.606602)
		(width 0.0762)
		(layer "F.Cu")
		(net "M_G_CPU0_SA_DQ<5>")
	)
	(segment
		(start 413.798512 -205.410054)
		(end 414.223454 -204.985112)
		(width 0.101346)
		(layer "F.Cu")
		(net "M_G_CPU0_SA_DQ<5>")
	)
	(segment
		(start 411.317694 -205.410054)
		(end 413.798512 -205.410054)
		(width 0.101346)
		(layer "F.Cu")
		(net "M_G_CPU0_SA_DQ<5>")
	)
	(segment
		(start 399.295874 -215.835738)
		(end 401.815808 -213.315804)
		(width 0.10668)
		(layer "F.Cu")
		(net "M_G_CPU0_SA_DQ<5>")
	)
	(arc
		(start 393.370816 -229.682802)
		(mid 393.553067 -229.733152)
		(end 393.736576 -229.687628)
		(width 0.0762)
		(layer "F.Cu")
		(net "M_G_CPU0_SA_DQ<5>")
	)
	(arc
		(start 392.431016 -229.682802)
		(mid 392.61796 -229.733057)
		(end 392.804904 -229.682802)
		(width 0.0762)
		(layer "F.Cu")
		(net "M_G_CPU0_SA_DQ<5>")
	)
	(arc
		(start 393.744958 -229.682802)
		(mid 393.881394 -229.625977)
		(end 394.027914 -229.606602)
		(width 0.0762)
		(layer "F.Cu")
		(net "M_G_CPU0_SA_DQ<5>")
	)
	(arc
		(start 392.192256 -229.608126)
		(mid 392.204079 -229.609143)
		(end 392.215878 -229.610412)
		(width 0.0762)
		(layer "F.Cu")
		(net "M_G_CPU0_SA_DQ<5>")
	)
	(arc
		(start 391.677906 -229.360222)
		(mid 391.911904 -229.532265)
		(end 392.192256 -229.608126)
		(width 0.0762)
		(layer "F.Cu")
		(net "M_G_CPU0_SA_DQ<5>")
	)
	(arc
		(start 392.804904 -229.682802)
		(mid 393.08786 -229.606625)
		(end 393.370816 -229.682802)
		(width 0.0762)
		(layer "F.Cu")
		(net "M_G_CPU0_SA_DQ<5>")
	)
	(arc
		(start 392.215878 -229.610412)
		(mid 392.327124 -229.635675)
		(end 392.431016 -229.682802)
		(width 0.0762)
		(layer "F.Cu")
		(net "M_G_CPU0_SA_DQ<5>")
	)
	(segment
		(start 414.555686 -203.28509)
		(end 414.762696 -203.28509)
		(width 0.101346)
		(layer "F.Cu")
		(net "M_G_CPU0_SA_DQ<4>")
	)
	(segment
		(start 414.332166 -204.157834)
		(end 414.449006 -204.040994)
		(width 0.101346)
		(layer "F.Cu")
		(net "M_G_CPU0_SA_DQ<4>")
	)
	(segment
		(start 415.278316 -203.40193)
		(end 415.395156 -203.28509)
		(width 0.101346)
		(layer "F.Cu")
		(net "M_G_CPU0_SA_DQ<4>")
	)
	(segment
		(start 414.879536 -203.40193)
		(end 414.879536 -204.02169)
		(width 0.101346)
		(layer "F.Cu")
		(net "M_G_CPU0_SA_DQ<4>")
	)
	(segment
		(start 414.050226 -204.040994)
		(end 414.167066 -204.157834)
		(width 0.101346)
		(layer "F.Cu")
		(net "M_G_CPU0_SA_DQ<4>")
	)
	(segment
		(start 411.317694 -203.71181)
		(end 411.319472 -203.710032)
		(width 0.101346)
		(layer "F.Cu")
		(net "M_G_CPU0_SA_DQ<4>")
	)
	(segment
		(start 414.167066 -204.157834)
		(end 414.332166 -204.157834)
		(width 0.101346)
		(layer "F.Cu")
		(net "M_G_CPU0_SA_DQ<4>")
	)
	(segment
		(start 413.933386 -203.710032)
		(end 414.050226 -203.826872)
		(width 0.101346)
		(layer "F.Cu")
		(net "M_G_CPU0_SA_DQ<4>")
	)
	(segment
		(start 411.319472 -203.710032)
		(end 413.933386 -203.710032)
		(width 0.101346)
		(layer "F.Cu")
		(net "M_G_CPU0_SA_DQ<4>")
	)
	(segment
		(start 414.762696 -203.28509)
		(end 414.879536 -203.40193)
		(width 0.101346)
		(layer "F.Cu")
		(net "M_G_CPU0_SA_DQ<4>")
	)
	(segment
		(start 395.063218 -228.437694)
		(end 395.766036 -227.734876)
		(width 0.0762)
		(layer "F.Cu")
		(net "M_G_CPU0_SA_DQ<4>")
	)
	(segment
		(start 404.866856 -210.162648)
		(end 411.317694 -203.71181)
		(width 0.10668)
		(layer "F.Cu")
		(net "M_G_CPU0_SA_DQ<4>")
	)
	(segment
		(start 415.161476 -204.13853)
		(end 415.278316 -204.02169)
		(width 0.101346)
		(layer "F.Cu")
		(net "M_G_CPU0_SA_DQ<4>")
	)
	(segment
		(start 414.449006 -204.040994)
		(end 414.449006 -203.39177)
		(width 0.101346)
		(layer "F.Cu")
		(net "M_G_CPU0_SA_DQ<4>")
	)
	(segment
		(start 414.050226 -203.826872)
		(end 414.050226 -204.040994)
		(width 0.101346)
		(layer "F.Cu")
		(net "M_G_CPU0_SA_DQ<4>")
	)
	(segment
		(start 414.879536 -204.02169)
		(end 414.996376 -204.13853)
		(width 0.101346)
		(layer "F.Cu")
		(net "M_G_CPU0_SA_DQ<4>")
	)
	(segment
		(start 398.493234 -225.007678)
		(end 398.493234 -215.67521)
		(width 0.10668)
		(layer "F.Cu")
		(net "M_G_CPU0_SA_DQ<4>")
	)
	(segment
		(start 415.278316 -204.02169)
		(end 415.278316 -203.40193)
		(width 0.101346)
		(layer "F.Cu")
		(net "M_G_CPU0_SA_DQ<4>")
	)
	(segment
		(start 395.766036 -227.734876)
		(end 398.493234 -225.007678)
		(width 0.10668)
		(layer "F.Cu")
		(net "M_G_CPU0_SA_DQ<4>")
	)
	(segment
		(start 394.810742 -228.93401)
		(end 395.063218 -228.681534)
		(width 0.0762)
		(layer "F.Cu")
		(net "M_G_CPU0_SA_DQ<4>")
	)
	(segment
		(start 404.005796 -210.162648)
		(end 404.866856 -210.162648)
		(width 0.10668)
		(layer "F.Cu")
		(net "M_G_CPU0_SA_DQ<4>")
	)
	(segment
		(start 394.03528 -228.93401)
		(end 394.810742 -228.93401)
		(width 0.0762)
		(layer "F.Cu")
		(net "M_G_CPU0_SA_DQ<4>")
	)
	(segment
		(start 398.493234 -215.67521)
		(end 404.005796 -210.162648)
		(width 0.10668)
		(layer "F.Cu")
		(net "M_G_CPU0_SA_DQ<4>")
	)
	(segment
		(start 415.395156 -203.28509)
		(end 416.468052 -203.28509)
		(width 0.101346)
		(layer "F.Cu")
		(net "M_G_CPU0_SA_DQ<4>")
	)
	(segment
		(start 414.996376 -204.13853)
		(end 415.161476 -204.13853)
		(width 0.101346)
		(layer "F.Cu")
		(net "M_G_CPU0_SA_DQ<4>")
	)
	(segment
		(start 395.063218 -228.681534)
		(end 395.063218 -228.437694)
		(width 0.0762)
		(layer "F.Cu")
		(net "M_G_CPU0_SA_DQ<4>")
	)
	(segment
		(start 414.449006 -203.39177)
		(end 414.555686 -203.28509)
		(width 0.101346)
		(layer "F.Cu")
		(net "M_G_CPU0_SA_DQ<4>")
	)
	(arc
		(start 393.959588 -228.923088)
		(mid 393.997038 -228.931301)
		(end 394.03528 -228.93401)
		(width 0.0762)
		(layer "F.Cu")
		(net "M_G_CPU0_SA_DQ<4>")
	)
	(arc
		(start 393.08786 -228.550216)
		(mid 393.324222 -228.721809)
		(end 393.60602 -228.798628)
		(width 0.0762)
		(layer "F.Cu")
		(net "M_G_CPU0_SA_DQ<4>")
	)
	(arc
		(start 393.60602 -228.798628)
		(mid 393.727605 -228.822699)
		(end 393.84097 -228.872796)
		(width 0.0762)
		(layer "F.Cu")
		(net "M_G_CPU0_SA_DQ<4>")
	)
	(arc
		(start 393.84097 -228.872796)
		(mid 393.898858 -228.901296)
		(end 393.959588 -228.923088)
		(width 0.0762)
		(layer "F.Cu")
		(net "M_G_CPU0_SA_DQ<4>")
	)
	(segment
		(start 403.371304 -207.132174)
		(end 403.488398 -207.01508)
		(width 0.10668)
		(layer "F.Cu")
		(net "M_G_CPU0_SA_DQ<3>")
	)
	(segment
		(start 402.806916 -207.696562)
		(end 402.92401 -207.579468)
		(width 0.10668)
		(layer "F.Cu")
		(net "M_G_CPU0_SA_DQ<3>")
	)
	(segment
		(start 392.05281 -226.76612)
		(end 392.05281 -226.673156)
		(width 0.0762)
		(layer "F.Cu")
		(net "M_G_CPU0_SA_DQ<3>")
	)
	(segment
		(start 403.586442 -207.911954)
		(end 403.703536 -207.79486)
		(width 0.10668)
		(layer "F.Cu")
		(net "M_G_CPU0_SA_DQ<3>")
	)
	(segment
		(start 404.715218 -206.783178)
		(end 404.846028 -206.652368)
		(width 0.10668)
		(layer "F.Cu")
		(net "M_G_CPU0_SA_DQ<3>")
	)
	(segment
		(start 403.08911 -207.579468)
		(end 403.421342 -207.911954)
		(width 0.10668)
		(layer "F.Cu")
		(net "M_G_CPU0_SA_DQ<3>")
	)
	(segment
		(start 395.545818 -225.147886)
		(end 396.577312 -224.116392)
		(width 0.10668)
		(layer "F.Cu")
		(net "M_G_CPU0_SA_DQ<3>")
	)
	(segment
		(start 396.577312 -214.921084)
		(end 403.139148 -208.359248)
		(width 0.10668)
		(layer "F.Cu")
		(net "M_G_CPU0_SA_DQ<3>")
	)
	(segment
		(start 403.139148 -208.194148)
		(end 402.806916 -207.861662)
		(width 0.10668)
		(layer "F.Cu")
		(net "M_G_CPU0_SA_DQ<3>")
	)
	(segment
		(start 403.703536 -207.62976)
		(end 403.371304 -207.297274)
		(width 0.10668)
		(layer "F.Cu")
		(net "M_G_CPU0_SA_DQ<3>")
	)
	(segment
		(start 404.217886 -206.450692)
		(end 404.550118 -206.783178)
		(width 0.10668)
		(layer "F.Cu")
		(net "M_G_CPU0_SA_DQ<3>")
	)
	(segment
		(start 403.703536 -207.79486)
		(end 403.703536 -207.62976)
		(width 0.10668)
		(layer "F.Cu")
		(net "M_G_CPU0_SA_DQ<3>")
	)
	(segment
		(start 392.326622 -226.602798)
		(end 392.335004 -226.607624)
		(width 0.0762)
		(layer "F.Cu")
		(net "M_G_CPU0_SA_DQ<3>")
	)
	(segment
		(start 403.653498 -207.01508)
		(end 403.98573 -207.347566)
		(width 0.10668)
		(layer "F.Cu")
		(net "M_G_CPU0_SA_DQ<3>")
	)
	(segment
		(start 394.203174 -226.27209)
		(end 394.421614 -226.27209)
		(width 0.0762)
		(layer "F.Cu")
		(net "M_G_CPU0_SA_DQ<3>")
	)
	(segment
		(start 404.550118 -206.783178)
		(end 404.715218 -206.783178)
		(width 0.10668)
		(layer "F.Cu")
		(net "M_G_CPU0_SA_DQ<3>")
	)
	(segment
		(start 394.421614 -226.27209)
		(end 395.545818 -225.147886)
		(width 0.0762)
		(layer "F.Cu")
		(net "M_G_CPU0_SA_DQ<3>")
	)
	(segment
		(start 403.935692 -206.567786)
		(end 404.052786 -206.450692)
		(width 0.10668)
		(layer "F.Cu")
		(net "M_G_CPU0_SA_DQ<3>")
	)
	(segment
		(start 403.935692 -206.732886)
		(end 403.935692 -206.567786)
		(width 0.10668)
		(layer "F.Cu")
		(net "M_G_CPU0_SA_DQ<3>")
	)
	(segment
		(start 404.846028 -205.637892)
		(end 410.598874 -199.885046)
		(width 0.10668)
		(layer "F.Cu")
		(net "M_G_CPU0_SA_DQ<3>")
	)
	(segment
		(start 403.371304 -207.297274)
		(end 403.371304 -207.132174)
		(width 0.10668)
		(layer "F.Cu")
		(net "M_G_CPU0_SA_DQ<3>")
	)
	(segment
		(start 403.421342 -207.911954)
		(end 403.586442 -207.911954)
		(width 0.10668)
		(layer "F.Cu")
		(net "M_G_CPU0_SA_DQ<3>")
	)
	(segment
		(start 402.92401 -207.579468)
		(end 403.08911 -207.579468)
		(width 0.10668)
		(layer "F.Cu")
		(net "M_G_CPU0_SA_DQ<3>")
	)
	(segment
		(start 404.846028 -206.652368)
		(end 404.846028 -205.637892)
		(width 0.10668)
		(layer "F.Cu")
		(net "M_G_CPU0_SA_DQ<3>")
	)
	(segment
		(start 404.267924 -207.065372)
		(end 403.935692 -206.732886)
		(width 0.10668)
		(layer "F.Cu")
		(net "M_G_CPU0_SA_DQ<3>")
	)
	(segment
		(start 403.488398 -207.01508)
		(end 403.653498 -207.01508)
		(width 0.10668)
		(layer "F.Cu")
		(net "M_G_CPU0_SA_DQ<3>")
	)
	(segment
		(start 410.598874 -199.885046)
		(end 412.367984 -199.885046)
		(width 0.10668)
		(layer "F.Cu")
		(net "M_G_CPU0_SA_DQ<3>")
	)
	(segment
		(start 392.14806 -226.930204)
		(end 392.05281 -226.76612)
		(width 0.0762)
		(layer "F.Cu")
		(net "M_G_CPU0_SA_DQ<3>")
	)
	(segment
		(start 392.900916 -226.607624)
		(end 392.909298 -226.602798)
		(width 0.0762)
		(layer "F.Cu")
		(net "M_G_CPU0_SA_DQ<3>")
	)
	(segment
		(start 404.15083 -207.347566)
		(end 404.267924 -207.230472)
		(width 0.10668)
		(layer "F.Cu")
		(net "M_G_CPU0_SA_DQ<3>")
	)
	(segment
		(start 396.577312 -224.116392)
		(end 396.577312 -214.921084)
		(width 0.10668)
		(layer "F.Cu")
		(net "M_G_CPU0_SA_DQ<3>")
	)
	(segment
		(start 402.806916 -207.861662)
		(end 402.806916 -207.696562)
		(width 0.10668)
		(layer "F.Cu")
		(net "M_G_CPU0_SA_DQ<3>")
	)
	(segment
		(start 403.98573 -207.347566)
		(end 404.15083 -207.347566)
		(width 0.10668)
		(layer "F.Cu")
		(net "M_G_CPU0_SA_DQ<3>")
	)
	(segment
		(start 393.95654 -226.518724)
		(end 394.203174 -226.27209)
		(width 0.0762)
		(layer "F.Cu")
		(net "M_G_CPU0_SA_DQ<3>")
	)
	(segment
		(start 404.052786 -206.450692)
		(end 404.217886 -206.450692)
		(width 0.10668)
		(layer "F.Cu")
		(net "M_G_CPU0_SA_DQ<3>")
	)
	(segment
		(start 404.267924 -207.230472)
		(end 404.267924 -207.065372)
		(width 0.10668)
		(layer "F.Cu")
		(net "M_G_CPU0_SA_DQ<3>")
	)
	(segment
		(start 403.139148 -208.359248)
		(end 403.139148 -208.194148)
		(width 0.10668)
		(layer "F.Cu")
		(net "M_G_CPU0_SA_DQ<3>")
	)
	(arc
		(start 392.909298 -226.602798)
		(mid 393.092806 -226.557304)
		(end 393.275058 -226.607624)
		(width 0.0762)
		(layer "F.Cu")
		(net "M_G_CPU0_SA_DQ<3>")
	)
	(arc
		(start 393.275058 -226.607624)
		(mid 393.630918 -226.679066)
		(end 393.95654 -226.518724)
		(width 0.0762)
		(layer "F.Cu")
		(net "M_G_CPU0_SA_DQ<3>")
	)
	(arc
		(start 392.16711 -226.55784)
		(mid 392.249401 -226.571331)
		(end 392.326622 -226.602798)
		(width 0.0762)
		(layer "F.Cu")
		(net "M_G_CPU0_SA_DQ<3>")
	)
	(arc
		(start 392.335004 -226.607624)
		(mid 392.61796 -226.683801)
		(end 392.900916 -226.607624)
		(width 0.0762)
		(layer "F.Cu")
		(net "M_G_CPU0_SA_DQ<3>")
	)
	(arc
		(start 392.05281 -226.673156)
		(mid 392.086227 -226.591975)
		(end 392.16711 -226.55784)
		(width 0.0762)
		(layer "F.Cu")
		(net "M_G_CPU0_SA_DQ<3>")
	)
	(segment
		(start 402.118576 -243.944648)
		(end 411.408118 -234.655106)
		(width 0.10668)
		(layer "F.Cu")
		(net "M_G_CPU0_SA_DQ<31>")
	)
	(segment
		(start 403.080474 -242.253262)
		(end 403.080474 -242.418108)
		(width 0.10668)
		(layer "F.Cu")
		(net "M_G_CPU0_SA_DQ<31>")
	)
	(segment
		(start 402.963126 -242.135914)
		(end 403.080474 -242.253262)
		(width 0.10668)
		(layer "F.Cu")
		(net "M_G_CPU0_SA_DQ<31>")
	)
	(segment
		(start 401.953476 -243.944648)
		(end 402.118576 -243.944648)
		(width 0.10668)
		(layer "F.Cu")
		(net "M_G_CPU0_SA_DQ<31>")
	)
	(segment
		(start 392.14806 -244.749828)
		(end 392.042904 -244.56898)
		(width 0.0762)
		(layer "F.Cu")
		(net "M_G_CPU0_SA_DQ<31>")
	)
	(segment
		(start 392.14806 -244.750082)
		(end 392.14806 -244.749828)
		(width 0.0762)
		(layer "F.Cu")
		(net "M_G_CPU0_SA_DQ<31>")
	)
	(segment
		(start 401.836128 -243.662454)
		(end 401.836128 -243.827554)
		(width 0.10668)
		(layer "F.Cu")
		(net "M_G_CPU0_SA_DQ<31>")
	)
	(segment
		(start 395.6558 -244.62867)
		(end 401.434554 -244.62867)
		(width 0.10668)
		(layer "F.Cu")
		(net "M_G_CPU0_SA_DQ<31>")
	)
	(segment
		(start 403.080474 -242.418108)
		(end 401.836128 -243.662454)
		(width 0.10668)
		(layer "F.Cu")
		(net "M_G_CPU0_SA_DQ<31>")
	)
	(segment
		(start 401.434554 -244.62867)
		(end 401.671282 -244.391942)
		(width 0.10668)
		(layer "F.Cu")
		(net "M_G_CPU0_SA_DQ<31>")
	)
	(segment
		(start 401.271486 -243.662454)
		(end 402.798026 -242.135914)
		(width 0.10668)
		(layer "F.Cu")
		(net "M_G_CPU0_SA_DQ<31>")
	)
	(segment
		(start 392.326622 -244.422676)
		(end 392.327638 -244.423184)
		(width 0.0762)
		(layer "F.Cu")
		(net "M_G_CPU0_SA_DQ<31>")
	)
	(segment
		(start 392.900916 -244.427502)
		(end 392.909298 -244.422676)
		(width 0.0762)
		(layer "F.Cu")
		(net "M_G_CPU0_SA_DQ<31>")
	)
	(segment
		(start 395.110716 -244.62867)
		(end 395.6558 -244.62867)
		(width 0.0762)
		(layer "F.Cu")
		(net "M_G_CPU0_SA_DQ<31>")
	)
	(segment
		(start 411.58922 -233.884978)
		(end 412.367984 -233.884978)
		(width 0.10668)
		(layer "F.Cu")
		(net "M_G_CPU0_SA_DQ<31>")
	)
	(segment
		(start 411.408118 -234.655106)
		(end 411.408118 -234.06608)
		(width 0.10668)
		(layer "F.Cu")
		(net "M_G_CPU0_SA_DQ<31>")
	)
	(segment
		(start 401.671282 -244.226842)
		(end 401.271486 -243.827554)
		(width 0.10668)
		(layer "F.Cu")
		(net "M_G_CPU0_SA_DQ<31>")
	)
	(segment
		(start 394.854176 -244.37213)
		(end 395.110716 -244.62867)
		(width 0.0762)
		(layer "F.Cu")
		(net "M_G_CPU0_SA_DQ<31>")
	)
	(segment
		(start 411.408118 -234.06608)
		(end 411.58922 -233.884978)
		(width 0.10668)
		(layer "F.Cu")
		(net "M_G_CPU0_SA_DQ<31>")
	)
	(segment
		(start 401.836128 -243.827554)
		(end 401.953476 -243.944648)
		(width 0.10668)
		(layer "F.Cu")
		(net "M_G_CPU0_SA_DQ<31>")
	)
	(segment
		(start 392.327638 -244.423184)
		(end 392.335004 -244.427502)
		(width 0.0762)
		(layer "F.Cu")
		(net "M_G_CPU0_SA_DQ<31>")
	)
	(segment
		(start 401.671282 -244.391942)
		(end 401.671282 -244.226842)
		(width 0.10668)
		(layer "F.Cu")
		(net "M_G_CPU0_SA_DQ<31>")
	)
	(segment
		(start 401.271486 -243.827554)
		(end 401.271486 -243.662454)
		(width 0.10668)
		(layer "F.Cu")
		(net "M_G_CPU0_SA_DQ<31>")
	)
	(segment
		(start 402.798026 -242.135914)
		(end 402.963126 -242.135914)
		(width 0.10668)
		(layer "F.Cu")
		(net "M_G_CPU0_SA_DQ<31>")
	)
	(segment
		(start 394.046456 -244.37213)
		(end 394.854176 -244.37213)
		(width 0.0762)
		(layer "F.Cu")
		(net "M_G_CPU0_SA_DQ<31>")
	)
	(arc
		(start 392.909298 -244.422676)
		(mid 393.092806 -244.377182)
		(end 393.275058 -244.427502)
		(width 0.0762)
		(layer "F.Cu")
		(net "M_G_CPU0_SA_DQ<31>")
	)
	(arc
		(start 393.84097 -244.427502)
		(mid 393.940043 -244.386188)
		(end 394.046456 -244.37213)
		(width 0.0762)
		(layer "F.Cu")
		(net "M_G_CPU0_SA_DQ<31>")
	)
	(arc
		(start 392.335004 -244.427502)
		(mid 392.61796 -244.503679)
		(end 392.900916 -244.427502)
		(width 0.0762)
		(layer "F.Cu")
		(net "M_G_CPU0_SA_DQ<31>")
	)
	(arc
		(start 393.275058 -244.427502)
		(mid 393.558014 -244.503679)
		(end 393.84097 -244.427502)
		(width 0.0762)
		(layer "F.Cu")
		(net "M_G_CPU0_SA_DQ<31>")
	)
	(arc
		(start 392.146536 -244.37721)
		(mid 392.23946 -244.388533)
		(end 392.326622 -244.422676)
		(width 0.0762)
		(layer "F.Cu")
		(net "M_G_CPU0_SA_DQ<31>")
	)
	(arc
		(start 392.042904 -244.56898)
		(mid 392.051841 -244.449956)
		(end 392.146536 -244.37721)
		(width 0.0762)
		(layer "F.Cu")
		(net "M_G_CPU0_SA_DQ<31>")
	)
	(segment
		(start 403.4917 -241.442494)
		(end 403.6568 -241.442494)
		(width 0.10668)
		(layer "F.Cu")
		(net "M_G_CPU0_SA_DQ<30>")
	)
	(segment
		(start 393.558014 -243.940076)
		(end 393.46505 -243.780056)
		(width 0.0762)
		(layer "F.Cu")
		(net "M_G_CPU0_SA_DQ<30>")
	)
	(segment
		(start 394.703046 -243.81841)
		(end 395.313916 -243.81841)
		(width 0.0762)
		(layer "F.Cu")
		(net "M_G_CPU0_SA_DQ<30>")
	)
	(segment
		(start 403.374606 -241.3254)
		(end 403.4917 -241.442494)
		(width 0.10668)
		(layer "F.Cu")
		(net "M_G_CPU0_SA_DQ<30>")
	)
	(segment
		(start 395.313916 -243.81841)
		(end 395.434058 -243.938552)
		(width 0.0762)
		(layer "F.Cu")
		(net "M_G_CPU0_SA_DQ<30>")
	)
	(segment
		(start 403.6568 -241.442494)
		(end 410.727398 -234.371896)
		(width 0.10668)
		(layer "F.Cu")
		(net "M_G_CPU0_SA_DQ<30>")
	)
	(segment
		(start 404.960582 -239.009936)
		(end 405.125682 -239.009936)
		(width 0.10668)
		(layer "F.Cu")
		(net "M_G_CPU0_SA_DQ<30>")
	)
	(segment
		(start 405.242776 -239.29213)
		(end 403.374606 -241.1603)
		(width 0.10668)
		(layer "F.Cu")
		(net "M_G_CPU0_SA_DQ<30>")
	)
	(segment
		(start 410.727398 -234.371896)
		(end 410.727398 -233.031538)
		(width 0.10668)
		(layer "F.Cu")
		(net "M_G_CPU0_SA_DQ<30>")
	)
	(segment
		(start 405.125682 -239.009936)
		(end 405.242776 -239.12703)
		(width 0.10668)
		(layer "F.Cu")
		(net "M_G_CPU0_SA_DQ<30>")
	)
	(segment
		(start 393.736576 -243.61267)
		(end 393.744958 -243.617496)
		(width 0.0762)
		(layer "F.Cu")
		(net "M_G_CPU0_SA_DQ<30>")
	)
	(segment
		(start 395.434058 -243.938552)
		(end 395.766798 -243.938552)
		(width 0.0762)
		(layer "F.Cu")
		(net "M_G_CPU0_SA_DQ<30>")
	)
	(segment
		(start 395.766798 -243.938552)
		(end 400.031966 -243.938552)
		(width 0.10668)
		(layer "F.Cu")
		(net "M_G_CPU0_SA_DQ<30>")
	)
	(segment
		(start 403.374606 -241.1603)
		(end 403.374606 -241.3254)
		(width 0.10668)
		(layer "F.Cu")
		(net "M_G_CPU0_SA_DQ<30>")
	)
	(segment
		(start 411.57398 -232.184956)
		(end 412.367984 -232.184956)
		(width 0.10668)
		(layer "F.Cu")
		(net "M_G_CPU0_SA_DQ<30>")
	)
	(segment
		(start 400.031966 -243.938552)
		(end 404.960582 -239.009936)
		(width 0.10668)
		(layer "F.Cu")
		(net "M_G_CPU0_SA_DQ<30>")
	)
	(segment
		(start 405.242776 -239.12703)
		(end 405.242776 -239.29213)
		(width 0.10668)
		(layer "F.Cu")
		(net "M_G_CPU0_SA_DQ<30>")
	)
	(segment
		(start 410.727398 -233.031538)
		(end 411.57398 -232.184956)
		(width 0.10668)
		(layer "F.Cu")
		(net "M_G_CPU0_SA_DQ<30>")
	)
	(arc
		(start 393.46505 -243.780056)
		(mid 393.46521 -243.633495)
		(end 393.596876 -243.569236)
		(width 0.0762)
		(layer "F.Cu")
		(net "M_G_CPU0_SA_DQ<30>")
	)
	(arc
		(start 393.744958 -243.617496)
		(mid 393.785556 -243.638872)
		(end 393.827762 -243.656866)
		(width 0.0762)
		(layer "F.Cu")
		(net "M_G_CPU0_SA_DQ<30>")
	)
	(arc
		(start 393.827762 -243.656866)
		(mid 394.258016 -243.777656)
		(end 394.703046 -243.81841)
		(width 0.0762)
		(layer "F.Cu")
		(net "M_G_CPU0_SA_DQ<30>")
	)
	(arc
		(start 393.596876 -243.569236)
		(mid 393.668884 -243.584018)
		(end 393.736576 -243.61267)
		(width 0.0762)
		(layer "F.Cu")
		(net "M_G_CPU0_SA_DQ<30>")
	)
	(segment
		(start 399.770854 -209.91449)
		(end 399.770854 -209.74939)
		(width 0.10668)
		(layer "F.Cu")
		(net "M_G_CPU0_SA_DQ<2>")
	)
	(segment
		(start 401.089368 -209.374994)
		(end 401.206462 -209.2579)
		(width 0.10668)
		(layer "F.Cu")
		(net "M_G_CPU0_SA_DQ<2>")
	)
	(segment
		(start 399.48866 -210.196684)
		(end 399.795492 -210.50377)
		(width 0.10668)
		(layer "F.Cu")
		(net "M_G_CPU0_SA_DQ<2>")
	)
	(segment
		(start 395.896592 -223.711008)
		(end 395.896592 -214.711026)
		(width 0.10668)
		(layer "F.Cu")
		(net "M_G_CPU0_SA_DQ<2>")
	)
	(segment
		(start 394.978382 -224.629218)
		(end 395.896592 -223.711008)
		(width 0.10668)
		(layer "F.Cu")
		(net "M_G_CPU0_SA_DQ<2>")
	)
	(segment
		(start 399.513298 -210.785964)
		(end 399.206466 -210.478878)
		(width 0.10668)
		(layer "F.Cu")
		(net "M_G_CPU0_SA_DQ<2>")
	)
	(segment
		(start 394.896594 -224.711006)
		(end 394.978382 -224.629218)
		(width 0.0762)
		(layer "F.Cu")
		(net "M_G_CPU0_SA_DQ<2>")
	)
	(segment
		(start 393.990576 -225.687636)
		(end 394.363448 -225.687636)
		(width 0.0762)
		(layer "F.Cu")
		(net "M_G_CPU0_SA_DQ<2>")
	)
	(segment
		(start 400.89963 -208.620614)
		(end 411.33522 -198.185024)
		(width 0.10668)
		(layer "F.Cu")
		(net "M_G_CPU0_SA_DQ<2>")
	)
	(segment
		(start 398.666716 -211.632546)
		(end 398.831816 -211.632546)
		(width 0.10668)
		(layer "F.Cu")
		(net "M_G_CPU0_SA_DQ<2>")
	)
	(segment
		(start 398.924272 -210.761072)
		(end 399.231104 -211.068158)
		(width 0.10668)
		(layer "F.Cu")
		(net "M_G_CPU0_SA_DQ<2>")
	)
	(segment
		(start 400.077686 -210.221576)
		(end 399.770854 -209.91449)
		(width 0.10668)
		(layer "F.Cu")
		(net "M_G_CPU0_SA_DQ<2>")
	)
	(segment
		(start 399.396204 -211.068158)
		(end 399.513298 -210.951064)
		(width 0.10668)
		(layer "F.Cu")
		(net "M_G_CPU0_SA_DQ<2>")
	)
	(segment
		(start 411.33522 -198.185024)
		(end 412.367984 -198.185024)
		(width 0.10668)
		(layer "F.Cu")
		(net "M_G_CPU0_SA_DQ<2>")
	)
	(segment
		(start 400.642074 -209.822288)
		(end 400.642074 -209.657188)
		(width 0.10668)
		(layer "F.Cu")
		(net "M_G_CPU0_SA_DQ<2>")
	)
	(segment
		(start 398.642078 -211.043266)
		(end 398.642078 -210.878166)
		(width 0.10668)
		(layer "F.Cu")
		(net "M_G_CPU0_SA_DQ<2>")
	)
	(segment
		(start 400.642074 -209.657188)
		(end 400.335242 -209.350102)
		(width 0.10668)
		(layer "F.Cu")
		(net "M_G_CPU0_SA_DQ<2>")
	)
	(segment
		(start 398.94891 -211.515452)
		(end 398.94891 -211.350352)
		(width 0.10668)
		(layer "F.Cu")
		(net "M_G_CPU0_SA_DQ<2>")
	)
	(segment
		(start 398.831816 -211.632546)
		(end 398.94891 -211.515452)
		(width 0.10668)
		(layer "F.Cu")
		(net "M_G_CPU0_SA_DQ<2>")
	)
	(segment
		(start 401.206462 -209.2579)
		(end 401.206462 -209.0928)
		(width 0.10668)
		(layer "F.Cu")
		(net "M_G_CPU0_SA_DQ<2>")
	)
	(segment
		(start 400.077686 -210.386676)
		(end 400.077686 -210.221576)
		(width 0.10668)
		(layer "F.Cu")
		(net "M_G_CPU0_SA_DQ<2>")
	)
	(segment
		(start 398.194784 -211.32546)
		(end 398.359884 -211.32546)
		(width 0.10668)
		(layer "F.Cu")
		(net "M_G_CPU0_SA_DQ<2>")
	)
	(segment
		(start 400.35988 -209.939382)
		(end 400.52498 -209.939382)
		(width 0.10668)
		(layer "F.Cu")
		(net "M_G_CPU0_SA_DQ<2>")
	)
	(segment
		(start 400.053048 -209.632296)
		(end 400.35988 -209.939382)
		(width 0.10668)
		(layer "F.Cu")
		(net "M_G_CPU0_SA_DQ<2>")
	)
	(segment
		(start 401.206462 -209.0928)
		(end 400.89963 -208.785714)
		(width 0.10668)
		(layer "F.Cu")
		(net "M_G_CPU0_SA_DQ<2>")
	)
	(segment
		(start 399.32356 -210.196684)
		(end 399.48866 -210.196684)
		(width 0.10668)
		(layer "F.Cu")
		(net "M_G_CPU0_SA_DQ<2>")
	)
	(segment
		(start 398.642078 -210.878166)
		(end 398.759172 -210.761072)
		(width 0.10668)
		(layer "F.Cu")
		(net "M_G_CPU0_SA_DQ<2>")
	)
	(segment
		(start 398.359884 -211.32546)
		(end 398.666716 -211.632546)
		(width 0.10668)
		(layer "F.Cu")
		(net "M_G_CPU0_SA_DQ<2>")
	)
	(segment
		(start 399.206466 -210.313778)
		(end 399.32356 -210.196684)
		(width 0.10668)
		(layer "F.Cu")
		(net "M_G_CPU0_SA_DQ<2>")
	)
	(segment
		(start 400.89963 -208.785714)
		(end 400.89963 -208.620614)
		(width 0.10668)
		(layer "F.Cu")
		(net "M_G_CPU0_SA_DQ<2>")
	)
	(segment
		(start 395.896592 -214.711026)
		(end 396.66545 -212.854794)
		(width 0.10668)
		(layer "F.Cu")
		(net "M_G_CPU0_SA_DQ<2>")
	)
	(segment
		(start 400.335242 -209.350102)
		(end 400.335242 -209.185002)
		(width 0.10668)
		(layer "F.Cu")
		(net "M_G_CPU0_SA_DQ<2>")
	)
	(segment
		(start 400.452336 -209.067908)
		(end 400.617436 -209.067908)
		(width 0.10668)
		(layer "F.Cu")
		(net "M_G_CPU0_SA_DQ<2>")
	)
	(segment
		(start 399.887948 -209.632296)
		(end 400.053048 -209.632296)
		(width 0.10668)
		(layer "F.Cu")
		(net "M_G_CPU0_SA_DQ<2>")
	)
	(segment
		(start 399.206466 -210.478878)
		(end 399.206466 -210.313778)
		(width 0.10668)
		(layer "F.Cu")
		(net "M_G_CPU0_SA_DQ<2>")
	)
	(segment
		(start 394.896594 -225.15449)
		(end 394.896594 -224.711006)
		(width 0.0762)
		(layer "F.Cu")
		(net "M_G_CPU0_SA_DQ<2>")
	)
	(segment
		(start 400.52498 -209.939382)
		(end 400.642074 -209.822288)
		(width 0.10668)
		(layer "F.Cu")
		(net "M_G_CPU0_SA_DQ<2>")
	)
	(segment
		(start 398.759172 -210.761072)
		(end 398.924272 -210.761072)
		(width 0.10668)
		(layer "F.Cu")
		(net "M_G_CPU0_SA_DQ<2>")
	)
	(segment
		(start 400.617436 -209.067908)
		(end 400.924268 -209.374994)
		(width 0.10668)
		(layer "F.Cu")
		(net "M_G_CPU0_SA_DQ<2>")
	)
	(segment
		(start 399.770854 -209.74939)
		(end 399.887948 -209.632296)
		(width 0.10668)
		(layer "F.Cu")
		(net "M_G_CPU0_SA_DQ<2>")
	)
	(segment
		(start 399.795492 -210.50377)
		(end 399.960592 -210.50377)
		(width 0.10668)
		(layer "F.Cu")
		(net "M_G_CPU0_SA_DQ<2>")
	)
	(segment
		(start 394.363448 -225.687636)
		(end 394.896594 -225.15449)
		(width 0.0762)
		(layer "F.Cu")
		(net "M_G_CPU0_SA_DQ<2>")
	)
	(segment
		(start 400.924268 -209.374994)
		(end 401.089368 -209.374994)
		(width 0.10668)
		(layer "F.Cu")
		(net "M_G_CPU0_SA_DQ<2>")
	)
	(segment
		(start 396.66545 -212.854794)
		(end 398.194784 -211.32546)
		(width 0.10668)
		(layer "F.Cu")
		(net "M_G_CPU0_SA_DQ<2>")
	)
	(segment
		(start 399.231104 -211.068158)
		(end 399.396204 -211.068158)
		(width 0.10668)
		(layer "F.Cu")
		(net "M_G_CPU0_SA_DQ<2>")
	)
	(segment
		(start 399.960592 -210.50377)
		(end 400.077686 -210.386676)
		(width 0.10668)
		(layer "F.Cu")
		(net "M_G_CPU0_SA_DQ<2>")
	)
	(segment
		(start 399.513298 -210.951064)
		(end 399.513298 -210.785964)
		(width 0.10668)
		(layer "F.Cu")
		(net "M_G_CPU0_SA_DQ<2>")
	)
	(segment
		(start 400.335242 -209.185002)
		(end 400.452336 -209.067908)
		(width 0.10668)
		(layer "F.Cu")
		(net "M_G_CPU0_SA_DQ<2>")
	)
	(segment
		(start 398.94891 -211.350352)
		(end 398.642078 -211.043266)
		(width 0.10668)
		(layer "F.Cu")
		(net "M_G_CPU0_SA_DQ<2>")
	)
	(arc
		(start 393.558014 -226.120198)
		(mid 393.684708 -225.81433)
		(end 393.990576 -225.687636)
		(width 0.0762)
		(layer "F.Cu")
		(net "M_G_CPU0_SA_DQ<2>")
	)
	(segment
		(start 392.431016 -244.262402)
		(end 392.431016 -244.262656)
		(width 0.0762)
		(layer "F.Cu")
		(net "M_G_CPU0_SA_DQ<29>")
	)
	(segment
		(start 403.785832 -241.795554)
		(end 411.067758 -234.513628)
		(width 0.10668)
		(layer "F.Cu")
		(net "M_G_CPU0_SA_DQ<29>")
	)
	(segment
		(start 395.266418 -244.286532)
		(end 395.695678 -244.286532)
		(width 0.0762)
		(layer "F.Cu")
		(net "M_G_CPU0_SA_DQ<29>")
	)
	(segment
		(start 400.938238 -243.989352)
		(end 400.783044 -243.834158)
		(width 0.10668)
		(layer "F.Cu")
		(net "M_G_CPU0_SA_DQ<29>")
	)
	(segment
		(start 411.364938 -233.627676)
		(end 411.532578 -233.460036)
		(width 0.101346)
		(layer "F.Cu")
		(net "M_G_CPU0_SA_DQ<29>")
	)
	(segment
		(start 400.938238 -244.154452)
		(end 400.938238 -243.989352)
		(width 0.10668)
		(layer "F.Cu")
		(net "M_G_CPU0_SA_DQ<29>")
	)
	(segment
		(start 395.080236 -244.10035)
		(end 395.266418 -244.286532)
		(width 0.0762)
		(layer "F.Cu")
		(net "M_G_CPU0_SA_DQ<29>")
	)
	(segment
		(start 402.656548 -241.795554)
		(end 403.785832 -241.795554)
		(width 0.10668)
		(layer "F.Cu")
		(net "M_G_CPU0_SA_DQ<29>")
	)
	(segment
		(start 400.33575 -244.116352)
		(end 400.50085 -244.116352)
		(width 0.10668)
		(layer "F.Cu")
		(net "M_G_CPU0_SA_DQ<29>")
	)
	(segment
		(start 400.656044 -244.271546)
		(end 400.821144 -244.271546)
		(width 0.10668)
		(layer "F.Cu")
		(net "M_G_CPU0_SA_DQ<29>")
	)
	(segment
		(start 393.736576 -244.267482)
		(end 393.744958 -244.262656)
		(width 0.0762)
		(layer "F.Cu")
		(net "M_G_CPU0_SA_DQ<29>")
	)
	(segment
		(start 414.223454 -233.035094)
		(end 416.468052 -233.035094)
		(width 0.101346)
		(layer "F.Cu")
		(net "M_G_CPU0_SA_DQ<29>")
	)
	(segment
		(start 400.16557 -244.286532)
		(end 400.33575 -244.116352)
		(width 0.10668)
		(layer "F.Cu")
		(net "M_G_CPU0_SA_DQ<29>")
	)
	(segment
		(start 400.783044 -243.834158)
		(end 400.783044 -243.669058)
		(width 0.10668)
		(layer "F.Cu")
		(net "M_G_CPU0_SA_DQ<29>")
	)
	(segment
		(start 411.532578 -233.460036)
		(end 413.798512 -233.460036)
		(width 0.101346)
		(layer "F.Cu")
		(net "M_G_CPU0_SA_DQ<29>")
	)
	(segment
		(start 400.821144 -244.271546)
		(end 400.938238 -244.154452)
		(width 0.10668)
		(layer "F.Cu")
		(net "M_G_CPU0_SA_DQ<29>")
	)
	(segment
		(start 400.783044 -243.669058)
		(end 402.656548 -241.795554)
		(width 0.10668)
		(layer "F.Cu")
		(net "M_G_CPU0_SA_DQ<29>")
	)
	(segment
		(start 400.50085 -244.116352)
		(end 400.656044 -244.271546)
		(width 0.10668)
		(layer "F.Cu")
		(net "M_G_CPU0_SA_DQ<29>")
	)
	(segment
		(start 411.067758 -234.513628)
		(end 411.067758 -233.924856)
		(width 0.10668)
		(layer "F.Cu")
		(net "M_G_CPU0_SA_DQ<29>")
	)
	(segment
		(start 413.798512 -233.460036)
		(end 414.223454 -233.035094)
		(width 0.101346)
		(layer "F.Cu")
		(net "M_G_CPU0_SA_DQ<29>")
	)
	(segment
		(start 395.695678 -244.286532)
		(end 400.16557 -244.286532)
		(width 0.10668)
		(layer "F.Cu")
		(net "M_G_CPU0_SA_DQ<29>")
	)
	(segment
		(start 394.3477 -244.10035)
		(end 395.080236 -244.10035)
		(width 0.0762)
		(layer "F.Cu")
		(net "M_G_CPU0_SA_DQ<29>")
	)
	(segment
		(start 411.067758 -233.924856)
		(end 411.364938 -233.627676)
		(width 0.10668)
		(layer "F.Cu")
		(net "M_G_CPU0_SA_DQ<29>")
	)
	(arc
		(start 392.804904 -244.262656)
		(mid 393.08786 -244.186479)
		(end 393.370816 -244.262656)
		(width 0.0762)
		(layer "F.Cu")
		(net "M_G_CPU0_SA_DQ<29>")
	)
	(arc
		(start 392.146536 -244.185948)
		(mid 392.293857 -244.205267)
		(end 392.431016 -244.262402)
		(width 0.0762)
		(layer "F.Cu")
		(net "M_G_CPU0_SA_DQ<29>")
	)
	(arc
		(start 391.677906 -243.940076)
		(mid 391.881922 -244.12077)
		(end 392.146536 -244.185948)
		(width 0.0762)
		(layer "F.Cu")
		(net "M_G_CPU0_SA_DQ<29>")
	)
	(arc
		(start 392.431016 -244.262656)
		(mid 392.61796 -244.312911)
		(end 392.804904 -244.262656)
		(width 0.0762)
		(layer "F.Cu")
		(net "M_G_CPU0_SA_DQ<29>")
	)
	(arc
		(start 393.744958 -244.262656)
		(mid 394.035591 -244.141619)
		(end 394.3477 -244.10035)
		(width 0.0762)
		(layer "F.Cu")
		(net "M_G_CPU0_SA_DQ<29>")
	)
	(arc
		(start 393.370816 -244.262656)
		(mid 393.553067 -244.313006)
		(end 393.736576 -244.267482)
		(width 0.0762)
		(layer "F.Cu")
		(net "M_G_CPU0_SA_DQ<29>")
	)
	(segment
		(start 410.419296 -232.684574)
		(end 410.415486 -232.495344)
		(width 0.10668)
		(layer "F.Cu")
		(net "M_G_CPU0_SA_DQ<28>")
	)
	(segment
		(start 410.387038 -232.718102)
		(end 410.419296 -232.684574)
		(width 0.10668)
		(layer "F.Cu")
		(net "M_G_CPU0_SA_DQ<28>")
	)
	(segment
		(start 409.53817 -234.91444)
		(end 409.43911 -234.81538)
		(width 0.10668)
		(layer "F.Cu")
		(net "M_G_CPU0_SA_DQ<28>")
	)
	(segment
		(start 395.428216 -243.50599)
		(end 395.514576 -243.59235)
		(width 0.0762)
		(layer "F.Cu")
		(net "M_G_CPU0_SA_DQ<28>")
	)
	(segment
		(start 410.501846 -231.94391)
		(end 410.732478 -232.165144)
		(width 0.10668)
		(layer "F.Cu")
		(net "M_G_CPU0_SA_DQ<28>")
	)
	(segment
		(start 405.948134 -238.669576)
		(end 409.53817 -235.07954)
		(width 0.10668)
		(layer "F.Cu")
		(net "M_G_CPU0_SA_DQ<28>")
	)
	(segment
		(start 399.896584 -243.59235)
		(end 404.819358 -238.669576)
		(width 0.10668)
		(layer "F.Cu")
		(net "M_G_CPU0_SA_DQ<28>")
	)
	(segment
		(start 409.556204 -234.533186)
		(end 409.721304 -234.533186)
		(width 0.10668)
		(layer "F.Cu")
		(net "M_G_CPU0_SA_DQ<28>")
	)
	(segment
		(start 409.985464 -234.632246)
		(end 410.387038 -234.230672)
		(width 0.10668)
		(layer "F.Cu")
		(net "M_G_CPU0_SA_DQ<28>")
	)
	(segment
		(start 404.819358 -238.669576)
		(end 405.948134 -238.669576)
		(width 0.10668)
		(layer "F.Cu")
		(net "M_G_CPU0_SA_DQ<28>")
	)
	(segment
		(start 410.732478 -232.165144)
		(end 410.921708 -232.161334)
		(width 0.10668)
		(layer "F.Cu")
		(net "M_G_CPU0_SA_DQ<28>")
	)
	(segment
		(start 409.43911 -234.65028)
		(end 409.556204 -234.533186)
		(width 0.10668)
		(layer "F.Cu")
		(net "M_G_CPU0_SA_DQ<28>")
	)
	(segment
		(start 409.43911 -234.81538)
		(end 409.43911 -234.65028)
		(width 0.10668)
		(layer "F.Cu")
		(net "M_G_CPU0_SA_DQ<28>")
	)
	(segment
		(start 409.53817 -235.07954)
		(end 409.53817 -234.91444)
		(width 0.10668)
		(layer "F.Cu")
		(net "M_G_CPU0_SA_DQ<28>")
	)
	(segment
		(start 395.815058 -243.59235)
		(end 399.896584 -243.59235)
		(width 0.10668)
		(layer "F.Cu")
		(net "M_G_CPU0_SA_DQ<28>")
	)
	(segment
		(start 394.095224 -243.50599)
		(end 395.428216 -243.50599)
		(width 0.0762)
		(layer "F.Cu")
		(net "M_G_CPU0_SA_DQ<28>")
	)
	(segment
		(start 395.514576 -243.59235)
		(end 395.815058 -243.59235)
		(width 0.0762)
		(layer "F.Cu")
		(net "M_G_CPU0_SA_DQ<28>")
	)
	(segment
		(start 415.107628 -231.760014)
		(end 415.53257 -231.335072)
		(width 0.101346)
		(layer "F.Cu")
		(net "M_G_CPU0_SA_DQ<28>")
	)
	(segment
		(start 410.312362 -231.94772)
		(end 410.501846 -231.94391)
		(width 0.10668)
		(layer "F.Cu")
		(net "M_G_CPU0_SA_DQ<28>")
	)
	(segment
		(start 410.1846 -232.27411)
		(end 410.18079 -232.08488)
		(width 0.10668)
		(layer "F.Cu")
		(net "M_G_CPU0_SA_DQ<28>")
	)
	(segment
		(start 415.53257 -231.335072)
		(end 416.468052 -231.335072)
		(width 0.101346)
		(layer "F.Cu")
		(net "M_G_CPU0_SA_DQ<28>")
	)
	(segment
		(start 410.18079 -232.08488)
		(end 410.312362 -231.94772)
		(width 0.10668)
		(layer "F.Cu")
		(net "M_G_CPU0_SA_DQ<28>")
	)
	(segment
		(start 409.721304 -234.533186)
		(end 409.820364 -234.632246)
		(width 0.10668)
		(layer "F.Cu")
		(net "M_G_CPU0_SA_DQ<28>")
	)
	(segment
		(start 409.820364 -234.632246)
		(end 409.985464 -234.632246)
		(width 0.10668)
		(layer "F.Cu")
		(net "M_G_CPU0_SA_DQ<28>")
	)
	(segment
		(start 411.020006 -232.057702)
		(end 411.317694 -231.760014)
		(width 0.10668)
		(layer "F.Cu")
		(net "M_G_CPU0_SA_DQ<28>")
	)
	(segment
		(start 410.921708 -232.161334)
		(end 411.02026 -232.058464)
		(width 0.10668)
		(layer "F.Cu")
		(net "M_G_CPU0_SA_DQ<28>")
	)
	(segment
		(start 411.317694 -231.760014)
		(end 415.107628 -231.760014)
		(width 0.101346)
		(layer "F.Cu")
		(net "M_G_CPU0_SA_DQ<28>")
	)
	(segment
		(start 410.387038 -234.230672)
		(end 410.387038 -232.718102)
		(width 0.10668)
		(layer "F.Cu")
		(net "M_G_CPU0_SA_DQ<28>")
	)
	(segment
		(start 410.415486 -232.495344)
		(end 410.1846 -232.27411)
		(width 0.10668)
		(layer "F.Cu")
		(net "M_G_CPU0_SA_DQ<28>")
	)
	(segment
		(start 411.02026 -232.058464)
		(end 411.020006 -232.057702)
		(width 0.10668)
		(layer "F.Cu")
		(net "M_G_CPU0_SA_DQ<28>")
	)
	(arc
		(start 393.84097 -243.45265)
		(mid 393.91621 -243.485963)
		(end 393.996926 -243.501926)
		(width 0.0762)
		(layer "F.Cu")
		(net "M_G_CPU0_SA_DQ<28>")
	)
	(arc
		(start 393.08786 -243.13007)
		(mid 393.323988 -243.301505)
		(end 393.605512 -243.378228)
		(width 0.0762)
		(layer "F.Cu")
		(net "M_G_CPU0_SA_DQ<28>")
	)
	(arc
		(start 393.996926 -243.501926)
		(mid 394.046033 -243.504967)
		(end 394.095224 -243.50599)
		(width 0.0762)
		(layer "F.Cu")
		(net "M_G_CPU0_SA_DQ<28>")
	)
	(arc
		(start 393.605512 -243.378228)
		(mid 393.727368 -243.402384)
		(end 393.84097 -243.45265)
		(width 0.0762)
		(layer "F.Cu")
		(net "M_G_CPU0_SA_DQ<28>")
	)
	(segment
		(start 411.175708 -228.033072)
		(end 411.41269 -227.935028)
		(width 0.10668)
		(layer "F.Cu")
		(net "M_G_CPU0_SA_DQ<27>")
	)
	(segment
		(start 405.299926 -236.369352)
		(end 404.985474 -236.054646)
		(width 0.10668)
		(layer "F.Cu")
		(net "M_G_CPU0_SA_DQ<27>")
	)
	(segment
		(start 405.766778 -235.083858)
		(end 405.956262 -235.083858)
		(width 0.10668)
		(layer "F.Cu")
		(net "M_G_CPU0_SA_DQ<27>")
	)
	(segment
		(start 395.738858 -241.512852)
		(end 399.306542 -241.512852)
		(width 0.10668)
		(layer "F.Cu")
		(net "M_G_CPU0_SA_DQ<27>")
	)
	(segment
		(start 392.326622 -241.182652)
		(end 392.327638 -241.18316)
		(width 0.0762)
		(layer "F.Cu")
		(net "M_G_CPU0_SA_DQ<27>")
	)
	(segment
		(start 410.112972 -228.787452)
		(end 410.649166 -228.251258)
		(width 0.10668)
		(layer "F.Cu")
		(net "M_G_CPU0_SA_DQ<27>")
	)
	(segment
		(start 394.050012 -241.13109)
		(end 394.851636 -241.13109)
		(width 0.0762)
		(layer "F.Cu")
		(net "M_G_CPU0_SA_DQ<27>")
	)
	(segment
		(start 394.851636 -241.13109)
		(end 395.233398 -241.512852)
		(width 0.0762)
		(layer "F.Cu")
		(net "M_G_CPU0_SA_DQ<27>")
	)
	(segment
		(start 404.985474 -236.054646)
		(end 404.985474 -235.865162)
		(width 0.10668)
		(layer "F.Cu")
		(net "M_G_CPU0_SA_DQ<27>")
	)
	(segment
		(start 405.632666 -235.21797)
		(end 405.766778 -235.083858)
		(width 0.10668)
		(layer "F.Cu")
		(net "M_G_CPU0_SA_DQ<27>")
	)
	(segment
		(start 405.632666 -235.407454)
		(end 405.632666 -235.21797)
		(width 0.10668)
		(layer "F.Cu")
		(net "M_G_CPU0_SA_DQ<27>")
	)
	(segment
		(start 395.233398 -241.512852)
		(end 395.738858 -241.512852)
		(width 0.0762)
		(layer "F.Cu")
		(net "M_G_CPU0_SA_DQ<27>")
	)
	(segment
		(start 411.41269 -227.935028)
		(end 412.367984 -227.935028)
		(width 0.10668)
		(layer "F.Cu")
		(net "M_G_CPU0_SA_DQ<27>")
	)
	(segment
		(start 405.947118 -235.911644)
		(end 405.947118 -235.72216)
		(width 0.10668)
		(layer "F.Cu")
		(net "M_G_CPU0_SA_DQ<27>")
	)
	(segment
		(start 392.900916 -241.187478)
		(end 392.909298 -241.182652)
		(width 0.0762)
		(layer "F.Cu")
		(net "M_G_CPU0_SA_DQ<27>")
	)
	(segment
		(start 405.119586 -235.73105)
		(end 405.30907 -235.73105)
		(width 0.10668)
		(layer "F.Cu")
		(net "M_G_CPU0_SA_DQ<27>")
	)
	(segment
		(start 404.97633 -236.692948)
		(end 405.165814 -236.692948)
		(width 0.10668)
		(layer "F.Cu")
		(net "M_G_CPU0_SA_DQ<27>")
	)
	(segment
		(start 392.14806 -241.510058)
		(end 392.14806 -241.509804)
		(width 0.0762)
		(layer "F.Cu")
		(net "M_G_CPU0_SA_DQ<27>")
	)
	(segment
		(start 406.279858 -234.570778)
		(end 406.634188 -234.216448)
		(width 0.10668)
		(layer "F.Cu")
		(net "M_G_CPU0_SA_DQ<27>")
	)
	(segment
		(start 405.299926 -236.558836)
		(end 405.299926 -236.369352)
		(width 0.10668)
		(layer "F.Cu")
		(net "M_G_CPU0_SA_DQ<27>")
	)
	(segment
		(start 406.634188 -234.216448)
		(end 406.634188 -232.913682)
		(width 0.10668)
		(layer "F.Cu")
		(net "M_G_CPU0_SA_DQ<27>")
	)
	(segment
		(start 406.59431 -235.264452)
		(end 406.59431 -235.074968)
		(width 0.10668)
		(layer "F.Cu")
		(net "M_G_CPU0_SA_DQ<27>")
	)
	(segment
		(start 404.985474 -235.865162)
		(end 405.119586 -235.73105)
		(width 0.10668)
		(layer "F.Cu")
		(net "M_G_CPU0_SA_DQ<27>")
	)
	(segment
		(start 392.14806 -241.509804)
		(end 392.042904 -241.328956)
		(width 0.0762)
		(layer "F.Cu")
		(net "M_G_CPU0_SA_DQ<27>")
	)
	(segment
		(start 405.813006 -236.045756)
		(end 405.947118 -235.911644)
		(width 0.10668)
		(layer "F.Cu")
		(net "M_G_CPU0_SA_DQ<27>")
	)
	(segment
		(start 406.59431 -235.074968)
		(end 406.279858 -234.760262)
		(width 0.10668)
		(layer "F.Cu")
		(net "M_G_CPU0_SA_DQ<27>")
	)
	(segment
		(start 405.947118 -235.72216)
		(end 405.632666 -235.407454)
		(width 0.10668)
		(layer "F.Cu")
		(net "M_G_CPU0_SA_DQ<27>")
	)
	(segment
		(start 404.441152 -236.378242)
		(end 404.661878 -236.378242)
		(width 0.10668)
		(layer "F.Cu")
		(net "M_G_CPU0_SA_DQ<27>")
	)
	(segment
		(start 410.649166 -228.251258)
		(end 411.175708 -228.033072)
		(width 0.10668)
		(layer "F.Cu")
		(net "M_G_CPU0_SA_DQ<27>")
	)
	(segment
		(start 392.327638 -241.18316)
		(end 392.335004 -241.187478)
		(width 0.0762)
		(layer "F.Cu")
		(net "M_G_CPU0_SA_DQ<27>")
	)
	(segment
		(start 399.306542 -241.512852)
		(end 404.441152 -236.378242)
		(width 0.10668)
		(layer "F.Cu")
		(net "M_G_CPU0_SA_DQ<27>")
	)
	(segment
		(start 404.661878 -236.378242)
		(end 404.97633 -236.692948)
		(width 0.10668)
		(layer "F.Cu")
		(net "M_G_CPU0_SA_DQ<27>")
	)
	(segment
		(start 410.112972 -229.434898)
		(end 410.112972 -228.787452)
		(width 0.10668)
		(layer "F.Cu")
		(net "M_G_CPU0_SA_DQ<27>")
	)
	(segment
		(start 405.623522 -236.045756)
		(end 405.813006 -236.045756)
		(width 0.10668)
		(layer "F.Cu")
		(net "M_G_CPU0_SA_DQ<27>")
	)
	(segment
		(start 405.30907 -235.73105)
		(end 405.623522 -236.045756)
		(width 0.10668)
		(layer "F.Cu")
		(net "M_G_CPU0_SA_DQ<27>")
	)
	(segment
		(start 406.279858 -234.760262)
		(end 406.279858 -234.570778)
		(width 0.10668)
		(layer "F.Cu")
		(net "M_G_CPU0_SA_DQ<27>")
	)
	(segment
		(start 406.634188 -232.913682)
		(end 410.112972 -229.434898)
		(width 0.10668)
		(layer "F.Cu")
		(net "M_G_CPU0_SA_DQ<27>")
	)
	(segment
		(start 405.956262 -235.083858)
		(end 406.270714 -235.398564)
		(width 0.10668)
		(layer "F.Cu")
		(net "M_G_CPU0_SA_DQ<27>")
	)
	(segment
		(start 406.460198 -235.398564)
		(end 406.59431 -235.264452)
		(width 0.10668)
		(layer "F.Cu")
		(net "M_G_CPU0_SA_DQ<27>")
	)
	(segment
		(start 405.165814 -236.692948)
		(end 405.299926 -236.558836)
		(width 0.10668)
		(layer "F.Cu")
		(net "M_G_CPU0_SA_DQ<27>")
	)
	(segment
		(start 406.270714 -235.398564)
		(end 406.460198 -235.398564)
		(width 0.10668)
		(layer "F.Cu")
		(net "M_G_CPU0_SA_DQ<27>")
	)
	(arc
		(start 393.84097 -241.187478)
		(mid 393.941762 -241.145472)
		(end 394.050012 -241.13109)
		(width 0.0762)
		(layer "F.Cu")
		(net "M_G_CPU0_SA_DQ<27>")
	)
	(arc
		(start 392.909298 -241.182652)
		(mid 393.092806 -241.137158)
		(end 393.275058 -241.187478)
		(width 0.0762)
		(layer "F.Cu")
		(net "M_G_CPU0_SA_DQ<27>")
	)
	(arc
		(start 392.042904 -241.328956)
		(mid 392.051841 -241.209932)
		(end 392.146536 -241.137186)
		(width 0.0762)
		(layer "F.Cu")
		(net "M_G_CPU0_SA_DQ<27>")
	)
	(arc
		(start 392.146536 -241.137186)
		(mid 392.23946 -241.148509)
		(end 392.326622 -241.182652)
		(width 0.0762)
		(layer "F.Cu")
		(net "M_G_CPU0_SA_DQ<27>")
	)
	(arc
		(start 393.275058 -241.187478)
		(mid 393.558014 -241.263655)
		(end 393.84097 -241.187478)
		(width 0.0762)
		(layer "F.Cu")
		(net "M_G_CPU0_SA_DQ<27>")
	)
	(arc
		(start 392.335004 -241.187478)
		(mid 392.61796 -241.263655)
		(end 392.900916 -241.187478)
		(width 0.0762)
		(layer "F.Cu")
		(net "M_G_CPU0_SA_DQ<27>")
	)
	(segment
		(start 405.953468 -233.759502)
		(end 405.953468 -233.594402)
		(width 0.10668)
		(layer "F.Cu")
		(net "M_G_CPU0_SA_DQ<26>")
	)
	(segment
		(start 404.105364 -234.878118)
		(end 403.98827 -234.761024)
		(width 0.10668)
		(layer "F.Cu")
		(net "M_G_CPU0_SA_DQ<26>")
	)
	(segment
		(start 404.270464 -234.878118)
		(end 404.105364 -234.878118)
		(width 0.10668)
		(layer "F.Cu")
		(net "M_G_CPU0_SA_DQ<26>")
	)
	(segment
		(start 394.673074 -240.63325)
		(end 395.062456 -240.63325)
		(width 0.0762)
		(layer "F.Cu")
		(net "M_G_CPU0_SA_DQ<26>")
	)
	(segment
		(start 405.671274 -233.477308)
		(end 404.270464 -234.878118)
		(width 0.10668)
		(layer "F.Cu")
		(net "M_G_CPU0_SA_DQ<26>")
	)
	(segment
		(start 411.032198 -226.841812)
		(end 411.28315 -226.841812)
		(width 0.10668)
		(layer "F.Cu")
		(net "M_G_CPU0_SA_DQ<26>")
	)
	(segment
		(start 403.98827 -234.761024)
		(end 403.98827 -234.595924)
		(width 0.10668)
		(layer "F.Cu")
		(net "M_G_CPU0_SA_DQ<26>")
	)
	(segment
		(start 405.953468 -233.594402)
		(end 405.836374 -233.477308)
		(width 0.10668)
		(layer "F.Cu")
		(net "M_G_CPU0_SA_DQ<26>")
	)
	(segment
		(start 405.836374 -233.477308)
		(end 405.671274 -233.477308)
		(width 0.10668)
		(layer "F.Cu")
		(net "M_G_CPU0_SA_DQ<26>")
	)
	(segment
		(start 395.062456 -240.63325)
		(end 395.237716 -240.80851)
		(width 0.0762)
		(layer "F.Cu")
		(net "M_G_CPU0_SA_DQ<26>")
	)
	(segment
		(start 409.432252 -228.441758)
		(end 411.032198 -226.841812)
		(width 0.10668)
		(layer "F.Cu")
		(net "M_G_CPU0_SA_DQ<26>")
	)
	(segment
		(start 395.660118 -240.80851)
		(end 398.90446 -240.80851)
		(width 0.10668)
		(layer "F.Cu")
		(net "M_G_CPU0_SA_DQ<26>")
	)
	(segment
		(start 409.432252 -229.151942)
		(end 409.432252 -228.441758)
		(width 0.10668)
		(layer "F.Cu")
		(net "M_G_CPU0_SA_DQ<26>")
	)
	(segment
		(start 393.558014 -240.700052)
		(end 393.46505 -240.540032)
		(width 0.0762)
		(layer "F.Cu")
		(net "M_G_CPU0_SA_DQ<26>")
	)
	(segment
		(start 395.237716 -240.80851)
		(end 395.660118 -240.80851)
		(width 0.0762)
		(layer "F.Cu")
		(net "M_G_CPU0_SA_DQ<26>")
	)
	(segment
		(start 403.98827 -234.595924)
		(end 409.432252 -229.151942)
		(width 0.10668)
		(layer "F.Cu")
		(net "M_G_CPU0_SA_DQ<26>")
	)
	(segment
		(start 398.90446 -240.80851)
		(end 405.953468 -233.759502)
		(width 0.10668)
		(layer "F.Cu")
		(net "M_G_CPU0_SA_DQ<26>")
	)
	(segment
		(start 411.28315 -226.841812)
		(end 411.889956 -226.235006)
		(width 0.10668)
		(layer "F.Cu")
		(net "M_G_CPU0_SA_DQ<26>")
	)
	(segment
		(start 411.889956 -226.235006)
		(end 412.367984 -226.235006)
		(width 0.10668)
		(layer "F.Cu")
		(net "M_G_CPU0_SA_DQ<26>")
	)
	(arc
		(start 393.596876 -240.329212)
		(mid 393.668884 -240.343994)
		(end 393.736576 -240.372646)
		(width 0.0762)
		(layer "F.Cu")
		(net "M_G_CPU0_SA_DQ<26>")
	)
	(arc
		(start 393.46505 -240.540032)
		(mid 393.46521 -240.393471)
		(end 393.596876 -240.329212)
		(width 0.0762)
		(layer "F.Cu")
		(net "M_G_CPU0_SA_DQ<26>")
	)
	(arc
		(start 393.736576 -240.372646)
		(mid 394.187034 -240.566877)
		(end 394.673074 -240.63325)
		(width 0.0762)
		(layer "F.Cu")
		(net "M_G_CPU0_SA_DQ<26>")
	)
	(segment
		(start 399.178018 -241.159792)
		(end 406.293828 -234.043982)
		(width 0.10668)
		(layer "F.Cu")
		(net "M_G_CPU0_SA_DQ<25>")
	)
	(segment
		(start 411.175708 -227.664518)
		(end 411.317694 -227.605844)
		(width 0.10668)
		(layer "F.Cu")
		(net "M_G_CPU0_SA_DQ<25>")
	)
	(segment
		(start 393.736576 -241.027458)
		(end 393.744958 -241.022632)
		(width 0.0762)
		(layer "F.Cu")
		(net "M_G_CPU0_SA_DQ<25>")
	)
	(segment
		(start 395.754098 -241.159792)
		(end 399.178018 -241.159792)
		(width 0.10668)
		(layer "F.Cu")
		(net "M_G_CPU0_SA_DQ<25>")
	)
	(segment
		(start 409.772612 -229.293166)
		(end 409.772612 -228.594412)
		(width 0.10668)
		(layer "F.Cu")
		(net "M_G_CPU0_SA_DQ<25>")
	)
	(segment
		(start 392.431016 -241.022378)
		(end 392.431016 -241.022632)
		(width 0.0762)
		(layer "F.Cu")
		(net "M_G_CPU0_SA_DQ<25>")
	)
	(segment
		(start 395.548104 -241.159792)
		(end 395.754098 -241.159792)
		(width 0.0762)
		(layer "F.Cu")
		(net "M_G_CPU0_SA_DQ<25>")
	)
	(segment
		(start 413.730948 -227.510086)
		(end 414.756854 -227.085144)
		(width 0.101346)
		(layer "F.Cu")
		(net "M_G_CPU0_SA_DQ<25>")
	)
	(segment
		(start 409.772612 -228.594412)
		(end 410.367734 -227.99929)
		(width 0.10668)
		(layer "F.Cu")
		(net "M_G_CPU0_SA_DQ<25>")
	)
	(segment
		(start 411.54858 -227.510086)
		(end 413.730948 -227.510086)
		(width 0.101346)
		(layer "F.Cu")
		(net "M_G_CPU0_SA_DQ<25>")
	)
	(segment
		(start 406.293828 -232.77195)
		(end 409.772612 -229.293166)
		(width 0.10668)
		(layer "F.Cu")
		(net "M_G_CPU0_SA_DQ<25>")
	)
	(segment
		(start 395.016736 -240.93805)
		(end 395.019784 -240.941098)
		(width 0.0762)
		(layer "F.Cu")
		(net "M_G_CPU0_SA_DQ<25>")
	)
	(segment
		(start 395.019784 -240.941098)
		(end 395.548104 -241.159792)
		(width 0.0762)
		(layer "F.Cu")
		(net "M_G_CPU0_SA_DQ<25>")
	)
	(segment
		(start 414.756854 -227.085144)
		(end 416.468052 -227.085144)
		(width 0.101346)
		(layer "F.Cu")
		(net "M_G_CPU0_SA_DQ<25>")
	)
	(segment
		(start 394.059156 -240.93805)
		(end 395.016736 -240.93805)
		(width 0.0762)
		(layer "F.Cu")
		(net "M_G_CPU0_SA_DQ<25>")
	)
	(segment
		(start 410.367734 -227.99929)
		(end 411.175708 -227.664518)
		(width 0.10668)
		(layer "F.Cu")
		(net "M_G_CPU0_SA_DQ<25>")
	)
	(segment
		(start 411.317694 -227.605844)
		(end 411.54858 -227.510086)
		(width 0.101346)
		(layer "F.Cu")
		(net "M_G_CPU0_SA_DQ<25>")
	)
	(segment
		(start 406.293828 -234.043982)
		(end 406.293828 -232.77195)
		(width 0.10668)
		(layer "F.Cu")
		(net "M_G_CPU0_SA_DQ<25>")
	)
	(arc
		(start 392.804904 -241.022632)
		(mid 393.08786 -240.946455)
		(end 393.370816 -241.022632)
		(width 0.0762)
		(layer "F.Cu")
		(net "M_G_CPU0_SA_DQ<25>")
	)
	(arc
		(start 393.370816 -241.022632)
		(mid 393.553067 -241.072982)
		(end 393.736576 -241.027458)
		(width 0.0762)
		(layer "F.Cu")
		(net "M_G_CPU0_SA_DQ<25>")
	)
	(arc
		(start 393.744958 -241.022632)
		(mid 393.896455 -240.959513)
		(end 394.059156 -240.93805)
		(width 0.0762)
		(layer "F.Cu")
		(net "M_G_CPU0_SA_DQ<25>")
	)
	(arc
		(start 392.431016 -241.022632)
		(mid 392.61796 -241.072887)
		(end 392.804904 -241.022632)
		(width 0.0762)
		(layer "F.Cu")
		(net "M_G_CPU0_SA_DQ<25>")
	)
	(arc
		(start 392.146536 -240.945924)
		(mid 392.293857 -240.965243)
		(end 392.431016 -241.022378)
		(width 0.0762)
		(layer "F.Cu")
		(net "M_G_CPU0_SA_DQ<25>")
	)
	(arc
		(start 391.677906 -240.700052)
		(mid 391.881922 -240.880746)
		(end 392.146536 -240.945924)
		(width 0.0762)
		(layer "F.Cu")
		(net "M_G_CPU0_SA_DQ<25>")
	)
	(segment
		(start 415.385504 -225.385122)
		(end 416.468052 -225.385122)
		(width 0.101346)
		(layer "F.Cu")
		(net "M_G_CPU0_SA_DQ<24>")
	)
	(segment
		(start 414.33369 -225.277172)
		(end 414.449006 -225.392488)
		(width 0.101346)
		(layer "F.Cu")
		(net "M_G_CPU0_SA_DQ<24>")
	)
	(segment
		(start 411.54985 -225.810064)
		(end 413.93999 -225.810064)
		(width 0.101346)
		(layer "F.Cu")
		(net "M_G_CPU0_SA_DQ<24>")
	)
	(segment
		(start 414.170622 -225.277172)
		(end 414.33369 -225.277172)
		(width 0.101346)
		(layer "F.Cu")
		(net "M_G_CPU0_SA_DQ<24>")
	)
	(segment
		(start 414.449006 -225.694748)
		(end 414.564322 -225.810064)
		(width 0.101346)
		(layer "F.Cu")
		(net "M_G_CPU0_SA_DQ<24>")
	)
	(segment
		(start 395.245336 -240.46561)
		(end 395.637258 -240.46561)
		(width 0.0762)
		(layer "F.Cu")
		(net "M_G_CPU0_SA_DQ<24>")
	)
	(segment
		(start 414.960562 -225.810064)
		(end 415.385504 -225.385122)
		(width 0.101346)
		(layer "F.Cu")
		(net "M_G_CPU0_SA_DQ<24>")
	)
	(segment
		(start 394.233654 -240.31829)
		(end 395.098016 -240.31829)
		(width 0.0762)
		(layer "F.Cu")
		(net "M_G_CPU0_SA_DQ<24>")
	)
	(segment
		(start 395.637258 -240.46561)
		(end 398.765776 -240.46561)
		(width 0.10668)
		(layer "F.Cu")
		(net "M_G_CPU0_SA_DQ<24>")
	)
	(segment
		(start 414.055306 -225.392488)
		(end 414.170622 -225.277172)
		(width 0.101346)
		(layer "F.Cu")
		(net "M_G_CPU0_SA_DQ<24>")
	)
	(segment
		(start 413.93999 -225.810064)
		(end 414.055306 -225.694748)
		(width 0.101346)
		(layer "F.Cu")
		(net "M_G_CPU0_SA_DQ<24>")
	)
	(segment
		(start 414.449006 -225.392488)
		(end 414.449006 -225.694748)
		(width 0.101346)
		(layer "F.Cu")
		(net "M_G_CPU0_SA_DQ<24>")
	)
	(segment
		(start 403.64791 -234.4547)
		(end 409.091892 -229.010718)
		(width 0.10668)
		(layer "F.Cu")
		(net "M_G_CPU0_SA_DQ<24>")
	)
	(segment
		(start 414.564322 -225.810064)
		(end 414.960562 -225.810064)
		(width 0.101346)
		(layer "F.Cu")
		(net "M_G_CPU0_SA_DQ<24>")
	)
	(segment
		(start 411.38221 -225.977704)
		(end 411.54985 -225.810064)
		(width 0.101346)
		(layer "F.Cu")
		(net "M_G_CPU0_SA_DQ<24>")
	)
	(segment
		(start 398.765776 -240.46561)
		(end 403.64791 -235.583476)
		(width 0.10668)
		(layer "F.Cu")
		(net "M_G_CPU0_SA_DQ<24>")
	)
	(segment
		(start 409.091892 -229.010718)
		(end 409.091892 -228.268022)
		(width 0.10668)
		(layer "F.Cu")
		(net "M_G_CPU0_SA_DQ<24>")
	)
	(segment
		(start 409.091892 -228.268022)
		(end 411.38221 -225.977704)
		(width 0.10668)
		(layer "F.Cu")
		(net "M_G_CPU0_SA_DQ<24>")
	)
	(segment
		(start 395.098016 -240.31829)
		(end 395.245336 -240.46561)
		(width 0.0762)
		(layer "F.Cu")
		(net "M_G_CPU0_SA_DQ<24>")
	)
	(segment
		(start 403.64791 -235.583476)
		(end 403.64791 -234.4547)
		(width 0.10668)
		(layer "F.Cu")
		(net "M_G_CPU0_SA_DQ<24>")
	)
	(segment
		(start 414.055306 -225.694748)
		(end 414.055306 -225.392488)
		(width 0.101346)
		(layer "F.Cu")
		(net "M_G_CPU0_SA_DQ<24>")
	)
	(arc
		(start 393.605512 -240.138204)
		(mid 393.727368 -240.16236)
		(end 393.84097 -240.212626)
		(width 0.0762)
		(layer "F.Cu")
		(net "M_G_CPU0_SA_DQ<24>")
	)
	(arc
		(start 393.84097 -240.212626)
		(mid 394.030334 -240.29138)
		(end 394.233654 -240.31829)
		(width 0.0762)
		(layer "F.Cu")
		(net "M_G_CPU0_SA_DQ<24>")
	)
	(arc
		(start 393.08786 -239.890046)
		(mid 393.323988 -240.061481)
		(end 393.605512 -240.138204)
		(width 0.0762)
		(layer "F.Cu")
		(net "M_G_CPU0_SA_DQ<24>")
	)
	(segment
		(start 400.97964 -237.040674)
		(end 400.81454 -237.040674)
		(width 0.10668)
		(layer "F.Cu")
		(net "M_G_CPU0_SA_DQ<23>")
	)
	(segment
		(start 403.19071 -235.228892)
		(end 403.073616 -235.111798)
		(width 0.10668)
		(layer "F.Cu")
		(net "M_G_CPU0_SA_DQ<23>")
	)
	(segment
		(start 400.697446 -236.92358)
		(end 400.697446 -236.75848)
		(width 0.10668)
		(layer "F.Cu")
		(net "M_G_CPU0_SA_DQ<23>")
	)
	(segment
		(start 394.052044 -239.51057)
		(end 394.812266 -239.51057)
		(width 0.0762)
		(layer "F.Cu")
		(net "M_G_CPU0_SA_DQ<23>")
	)
	(segment
		(start 392.326622 -239.56264)
		(end 392.327638 -239.563148)
		(width 0.0762)
		(layer "F.Cu")
		(net "M_G_CPU0_SA_DQ<23>")
	)
	(segment
		(start 403.073616 -235.111798)
		(end 402.908516 -235.111798)
		(width 0.10668)
		(layer "F.Cu")
		(net "M_G_CPU0_SA_DQ<23>")
	)
	(segment
		(start 403.19071 -235.393992)
		(end 403.19071 -235.228892)
		(width 0.10668)
		(layer "F.Cu")
		(net "M_G_CPU0_SA_DQ<23>")
	)
	(segment
		(start 408.634692 -228.821234)
		(end 408.634692 -228.052376)
		(width 0.10668)
		(layer "F.Cu")
		(net "M_G_CPU0_SA_DQ<23>")
	)
	(segment
		(start 411.438344 -225.248724)
		(end 411.438344 -224.687892)
		(width 0.10668)
		(layer "F.Cu")
		(net "M_G_CPU0_SA_DQ<23>")
	)
	(segment
		(start 392.14806 -239.890046)
		(end 392.14806 -239.889792)
		(width 0.0762)
		(layer "F.Cu")
		(net "M_G_CPU0_SA_DQ<23>")
	)
	(segment
		(start 402.908516 -235.111798)
		(end 400.97964 -237.040674)
		(width 0.10668)
		(layer "F.Cu")
		(net "M_G_CPU0_SA_DQ<23>")
	)
	(segment
		(start 408.634692 -228.052376)
		(end 411.438344 -225.248724)
		(width 0.10668)
		(layer "F.Cu")
		(net "M_G_CPU0_SA_DQ<23>")
	)
	(segment
		(start 395.310106 -240.00841)
		(end 395.571218 -240.00841)
		(width 0.0762)
		(layer "F.Cu")
		(net "M_G_CPU0_SA_DQ<23>")
	)
	(segment
		(start 394.812266 -239.51057)
		(end 395.310106 -240.00841)
		(width 0.0762)
		(layer "F.Cu")
		(net "M_G_CPU0_SA_DQ<23>")
	)
	(segment
		(start 392.900916 -239.567466)
		(end 392.909298 -239.56264)
		(width 0.0762)
		(layer "F.Cu")
		(net "M_G_CPU0_SA_DQ<23>")
	)
	(segment
		(start 398.576292 -240.00841)
		(end 403.19071 -235.393992)
		(width 0.10668)
		(layer "F.Cu")
		(net "M_G_CPU0_SA_DQ<23>")
	)
	(segment
		(start 392.14806 -239.889792)
		(end 392.042904 -239.708944)
		(width 0.0762)
		(layer "F.Cu")
		(net "M_G_CPU0_SA_DQ<23>")
	)
	(segment
		(start 411.438344 -224.687892)
		(end 411.591252 -224.534984)
		(width 0.10668)
		(layer "F.Cu")
		(net "M_G_CPU0_SA_DQ<23>")
	)
	(segment
		(start 395.571218 -240.00841)
		(end 398.576292 -240.00841)
		(width 0.10668)
		(layer "F.Cu")
		(net "M_G_CPU0_SA_DQ<23>")
	)
	(segment
		(start 392.327638 -239.563148)
		(end 392.335004 -239.567466)
		(width 0.0762)
		(layer "F.Cu")
		(net "M_G_CPU0_SA_DQ<23>")
	)
	(segment
		(start 400.81454 -237.040674)
		(end 400.697446 -236.92358)
		(width 0.10668)
		(layer "F.Cu")
		(net "M_G_CPU0_SA_DQ<23>")
	)
	(segment
		(start 411.591252 -224.534984)
		(end 412.367984 -224.534984)
		(width 0.10668)
		(layer "F.Cu")
		(net "M_G_CPU0_SA_DQ<23>")
	)
	(segment
		(start 400.697446 -236.75848)
		(end 408.634692 -228.821234)
		(width 0.10668)
		(layer "F.Cu")
		(net "M_G_CPU0_SA_DQ<23>")
	)
	(arc
		(start 392.146536 -239.517174)
		(mid 392.23946 -239.528497)
		(end 392.326622 -239.56264)
		(width 0.0762)
		(layer "F.Cu")
		(net "M_G_CPU0_SA_DQ<23>")
	)
	(arc
		(start 393.275058 -239.567466)
		(mid 393.558014 -239.643643)
		(end 393.84097 -239.567466)
		(width 0.0762)
		(layer "F.Cu")
		(net "M_G_CPU0_SA_DQ<23>")
	)
	(arc
		(start 393.84097 -239.567466)
		(mid 393.942738 -239.525032)
		(end 394.052044 -239.51057)
		(width 0.0762)
		(layer "F.Cu")
		(net "M_G_CPU0_SA_DQ<23>")
	)
	(arc
		(start 392.335004 -239.567466)
		(mid 392.61796 -239.643643)
		(end 392.900916 -239.567466)
		(width 0.0762)
		(layer "F.Cu")
		(net "M_G_CPU0_SA_DQ<23>")
	)
	(arc
		(start 392.042904 -239.708944)
		(mid 392.051841 -239.58992)
		(end 392.146536 -239.517174)
		(width 0.0762)
		(layer "F.Cu")
		(net "M_G_CPU0_SA_DQ<23>")
	)
	(arc
		(start 392.909298 -239.56264)
		(mid 393.092806 -239.517146)
		(end 393.275058 -239.567466)
		(width 0.0762)
		(layer "F.Cu")
		(net "M_G_CPU0_SA_DQ<23>")
	)
	(segment
		(start 399.570448 -238.051086)
		(end 399.570448 -237.885986)
		(width 0.10668)
		(layer "F.Cu")
		(net "M_G_CPU0_SA_DQ<22>")
	)
	(segment
		(start 395.941042 -239.21085)
		(end 396.057882 -239.32769)
		(width 0.10668)
		(layer "F.Cu")
		(net "M_G_CPU0_SA_DQ<22>")
	)
	(segment
		(start 409.303728 -225.72599)
		(end 409.303728 -225.56089)
		(width 0.10668)
		(layer "F.Cu")
		(net "M_G_CPU0_SA_DQ<22>")
	)
	(segment
		(start 395.280896 -239.32769)
		(end 395.425168 -239.32769)
		(width 0.10668)
		(layer "F.Cu")
		(net "M_G_CPU0_SA_DQ<22>")
	)
	(segment
		(start 399.288254 -237.768892)
		(end 398.182846 -238.8743)
		(width 0.10668)
		(layer "F.Cu")
		(net "M_G_CPU0_SA_DQ<22>")
	)
	(segment
		(start 396.62227 -238.942372)
		(end 396.73911 -239.059212)
		(width 0.10668)
		(layer "F.Cu")
		(net "M_G_CPU0_SA_DQ<22>")
	)
	(segment
		(start 397.537178 -239.21085)
		(end 397.654018 -239.32769)
		(width 0.10668)
		(layer "F.Cu")
		(net "M_G_CPU0_SA_DQ<22>")
	)
	(segment
		(start 394.889736 -238.93653)
		(end 395.280896 -239.32769)
		(width 0.0762)
		(layer "F.Cu")
		(net "M_G_CPU0_SA_DQ<22>")
	)
	(segment
		(start 397.900652 -238.592106)
		(end 407.953972 -228.538786)
		(width 0.10668)
		(layer "F.Cu")
		(net "M_G_CPU0_SA_DQ<22>")
	)
	(segment
		(start 407.953972 -227.76434)
		(end 409.565602 -226.15271)
		(width 0.10668)
		(layer "F.Cu")
		(net "M_G_CPU0_SA_DQ<22>")
	)
	(segment
		(start 397.420338 -238.942372)
		(end 397.537178 -239.059212)
		(width 0.10668)
		(layer "F.Cu")
		(net "M_G_CPU0_SA_DQ<22>")
	)
	(segment
		(start 395.542008 -239.059212)
		(end 395.658848 -238.942372)
		(width 0.10668)
		(layer "F.Cu")
		(net "M_G_CPU0_SA_DQ<22>")
	)
	(segment
		(start 410.15031 -224.879408)
		(end 410.412184 -225.141028)
		(width 0.10668)
		(layer "F.Cu")
		(net "M_G_CPU0_SA_DQ<22>")
	)
	(segment
		(start 397.900652 -238.757206)
		(end 397.900652 -238.592106)
		(width 0.10668)
		(layer "F.Cu")
		(net "M_G_CPU0_SA_DQ<22>")
	)
	(segment
		(start 395.542008 -239.21085)
		(end 395.542008 -239.059212)
		(width 0.10668)
		(layer "F.Cu")
		(net "M_G_CPU0_SA_DQ<22>")
	)
	(segment
		(start 393.558014 -239.08004)
		(end 393.46505 -238.92002)
		(width 0.0762)
		(layer "F.Cu")
		(net "M_G_CPU0_SA_DQ<22>")
	)
	(segment
		(start 399.453354 -237.768892)
		(end 399.288254 -237.768892)
		(width 0.10668)
		(layer "F.Cu")
		(net "M_G_CPU0_SA_DQ<22>")
	)
	(segment
		(start 409.98521 -224.879408)
		(end 410.15031 -224.879408)
		(width 0.10668)
		(layer "F.Cu")
		(net "M_G_CPU0_SA_DQ<22>")
	)
	(segment
		(start 399.570448 -237.885986)
		(end 399.453354 -237.768892)
		(width 0.10668)
		(layer "F.Cu")
		(net "M_G_CPU0_SA_DQ<22>")
	)
	(segment
		(start 396.057882 -239.32769)
		(end 396.223236 -239.32769)
		(width 0.10668)
		(layer "F.Cu")
		(net "M_G_CPU0_SA_DQ<22>")
	)
	(segment
		(start 410.12999 -225.423222)
		(end 409.868116 -225.161602)
		(width 0.10668)
		(layer "F.Cu")
		(net "M_G_CPU0_SA_DQ<22>")
	)
	(segment
		(start 407.953972 -228.538786)
		(end 407.953972 -227.76434)
		(width 0.10668)
		(layer "F.Cu")
		(net "M_G_CPU0_SA_DQ<22>")
	)
	(segment
		(start 395.658848 -238.942372)
		(end 395.824202 -238.942372)
		(width 0.10668)
		(layer "F.Cu")
		(net "M_G_CPU0_SA_DQ<22>")
	)
	(segment
		(start 396.223236 -239.32769)
		(end 396.340076 -239.21085)
		(width 0.10668)
		(layer "F.Cu")
		(net "M_G_CPU0_SA_DQ<22>")
	)
	(segment
		(start 395.941042 -239.059212)
		(end 395.941042 -239.21085)
		(width 0.10668)
		(layer "F.Cu")
		(net "M_G_CPU0_SA_DQ<22>")
	)
	(segment
		(start 409.303728 -225.56089)
		(end 409.420822 -225.443796)
		(width 0.10668)
		(layer "F.Cu")
		(net "M_G_CPU0_SA_DQ<22>")
	)
	(segment
		(start 394.397484 -238.93653)
		(end 394.889736 -238.93653)
		(width 0.0762)
		(layer "F.Cu")
		(net "M_G_CPU0_SA_DQ<22>")
	)
	(segment
		(start 397.138144 -239.21085)
		(end 397.138144 -239.059212)
		(width 0.10668)
		(layer "F.Cu")
		(net "M_G_CPU0_SA_DQ<22>")
	)
	(segment
		(start 398.293844 -239.32769)
		(end 399.570448 -238.051086)
		(width 0.10668)
		(layer "F.Cu")
		(net "M_G_CPU0_SA_DQ<22>")
	)
	(segment
		(start 409.565602 -225.98761)
		(end 409.303728 -225.72599)
		(width 0.10668)
		(layer "F.Cu")
		(net "M_G_CPU0_SA_DQ<22>")
	)
	(segment
		(start 396.340076 -239.21085)
		(end 396.340076 -239.059212)
		(width 0.10668)
		(layer "F.Cu")
		(net "M_G_CPU0_SA_DQ<22>")
	)
	(segment
		(start 409.420822 -225.443796)
		(end 409.585922 -225.443796)
		(width 0.10668)
		(layer "F.Cu")
		(net "M_G_CPU0_SA_DQ<22>")
	)
	(segment
		(start 410.757624 -224.960688)
		(end 410.757624 -223.948752)
		(width 0.10668)
		(layer "F.Cu")
		(net "M_G_CPU0_SA_DQ<22>")
	)
	(segment
		(start 397.138144 -239.059212)
		(end 397.254984 -238.942372)
		(width 0.10668)
		(layer "F.Cu")
		(net "M_G_CPU0_SA_DQ<22>")
	)
	(segment
		(start 395.425168 -239.32769)
		(end 395.542008 -239.21085)
		(width 0.10668)
		(layer "F.Cu")
		(net "M_G_CPU0_SA_DQ<22>")
	)
	(segment
		(start 410.412184 -225.141028)
		(end 410.577284 -225.141028)
		(width 0.10668)
		(layer "F.Cu")
		(net "M_G_CPU0_SA_DQ<22>")
	)
	(segment
		(start 396.456916 -238.942372)
		(end 396.62227 -238.942372)
		(width 0.10668)
		(layer "F.Cu")
		(net "M_G_CPU0_SA_DQ<22>")
	)
	(segment
		(start 410.757624 -223.948752)
		(end 411.871414 -222.834962)
		(width 0.10668)
		(layer "F.Cu")
		(net "M_G_CPU0_SA_DQ<22>")
	)
	(segment
		(start 410.012896 -225.705416)
		(end 410.12999 -225.588322)
		(width 0.10668)
		(layer "F.Cu")
		(net "M_G_CPU0_SA_DQ<22>")
	)
	(segment
		(start 409.868116 -224.996502)
		(end 409.98521 -224.879408)
		(width 0.10668)
		(layer "F.Cu")
		(net "M_G_CPU0_SA_DQ<22>")
	)
	(segment
		(start 409.868116 -225.161602)
		(end 409.868116 -224.996502)
		(width 0.10668)
		(layer "F.Cu")
		(net "M_G_CPU0_SA_DQ<22>")
	)
	(segment
		(start 410.12999 -225.588322)
		(end 410.12999 -225.423222)
		(width 0.10668)
		(layer "F.Cu")
		(net "M_G_CPU0_SA_DQ<22>")
	)
	(segment
		(start 409.847796 -225.705416)
		(end 410.012896 -225.705416)
		(width 0.10668)
		(layer "F.Cu")
		(net "M_G_CPU0_SA_DQ<22>")
	)
	(segment
		(start 410.577284 -225.141028)
		(end 410.757624 -224.960688)
		(width 0.10668)
		(layer "F.Cu")
		(net "M_G_CPU0_SA_DQ<22>")
	)
	(segment
		(start 396.73911 -239.059212)
		(end 396.73911 -239.21085)
		(width 0.10668)
		(layer "F.Cu")
		(net "M_G_CPU0_SA_DQ<22>")
	)
	(segment
		(start 397.537178 -239.059212)
		(end 397.537178 -239.21085)
		(width 0.10668)
		(layer "F.Cu")
		(net "M_G_CPU0_SA_DQ<22>")
	)
	(segment
		(start 411.871414 -222.834962)
		(end 412.367984 -222.834962)
		(width 0.10668)
		(layer "F.Cu")
		(net "M_G_CPU0_SA_DQ<22>")
	)
	(segment
		(start 397.021304 -239.32769)
		(end 397.138144 -239.21085)
		(width 0.10668)
		(layer "F.Cu")
		(net "M_G_CPU0_SA_DQ<22>")
	)
	(segment
		(start 396.340076 -239.059212)
		(end 396.456916 -238.942372)
		(width 0.10668)
		(layer "F.Cu")
		(net "M_G_CPU0_SA_DQ<22>")
	)
	(segment
		(start 409.585922 -225.443796)
		(end 409.847796 -225.705416)
		(width 0.10668)
		(layer "F.Cu")
		(net "M_G_CPU0_SA_DQ<22>")
	)
	(segment
		(start 395.824202 -238.942372)
		(end 395.941042 -239.059212)
		(width 0.10668)
		(layer "F.Cu")
		(net "M_G_CPU0_SA_DQ<22>")
	)
	(segment
		(start 397.254984 -238.942372)
		(end 397.420338 -238.942372)
		(width 0.10668)
		(layer "F.Cu")
		(net "M_G_CPU0_SA_DQ<22>")
	)
	(segment
		(start 396.73911 -239.21085)
		(end 396.85595 -239.32769)
		(width 0.10668)
		(layer "F.Cu")
		(net "M_G_CPU0_SA_DQ<22>")
	)
	(segment
		(start 409.565602 -226.15271)
		(end 409.565602 -225.98761)
		(width 0.10668)
		(layer "F.Cu")
		(net "M_G_CPU0_SA_DQ<22>")
	)
	(segment
		(start 398.017746 -238.8743)
		(end 397.900652 -238.757206)
		(width 0.10668)
		(layer "F.Cu")
		(net "M_G_CPU0_SA_DQ<22>")
	)
	(segment
		(start 396.85595 -239.32769)
		(end 397.021304 -239.32769)
		(width 0.10668)
		(layer "F.Cu")
		(net "M_G_CPU0_SA_DQ<22>")
	)
	(segment
		(start 398.182846 -238.8743)
		(end 398.017746 -238.8743)
		(width 0.10668)
		(layer "F.Cu")
		(net "M_G_CPU0_SA_DQ<22>")
	)
	(segment
		(start 397.654018 -239.32769)
		(end 398.293844 -239.32769)
		(width 0.10668)
		(layer "F.Cu")
		(net "M_G_CPU0_SA_DQ<22>")
	)
	(arc
		(start 393.736576 -238.752634)
		(mid 394.054473 -238.889718)
		(end 394.397484 -238.93653)
		(width 0.0762)
		(layer "F.Cu")
		(net "M_G_CPU0_SA_DQ<22>")
	)
	(arc
		(start 393.46505 -238.92002)
		(mid 393.46521 -238.773459)
		(end 393.596876 -238.7092)
		(width 0.0762)
		(layer "F.Cu")
		(net "M_G_CPU0_SA_DQ<22>")
	)
	(arc
		(start 393.596876 -238.7092)
		(mid 393.668884 -238.723982)
		(end 393.736576 -238.752634)
		(width 0.0762)
		(layer "F.Cu")
		(net "M_G_CPU0_SA_DQ<22>")
	)
	(segment
		(start 408.294332 -227.905564)
		(end 411.097984 -225.101912)
		(width 0.10668)
		(layer "F.Cu")
		(net "M_G_CPU0_SA_DQ<21>")
	)
	(segment
		(start 400.329908 -237.208822)
		(end 399.934938 -237.603792)
		(width 0.10668)
		(layer "F.Cu")
		(net "M_G_CPU0_SA_DQ<21>")
	)
	(segment
		(start 413.798512 -224.110042)
		(end 414.223454 -223.6851)
		(width 0.101346)
		(layer "F.Cu")
		(net "M_G_CPU0_SA_DQ<21>")
	)
	(segment
		(start 398.435068 -239.66805)
		(end 400.612102 -237.491016)
		(width 0.10668)
		(layer "F.Cu")
		(net "M_G_CPU0_SA_DQ<21>")
	)
	(segment
		(start 395.239494 -239.66805)
		(end 395.495018 -239.66805)
		(width 0.0762)
		(layer "F.Cu")
		(net "M_G_CPU0_SA_DQ<21>")
	)
	(segment
		(start 399.934938 -237.603792)
		(end 399.769838 -237.603792)
		(width 0.10668)
		(layer "F.Cu")
		(net "M_G_CPU0_SA_DQ<21>")
	)
	(segment
		(start 399.769838 -237.603792)
		(end 399.652744 -237.486698)
		(width 0.10668)
		(layer "F.Cu")
		(net "M_G_CPU0_SA_DQ<21>")
	)
	(segment
		(start 395.495018 -239.66805)
		(end 398.435068 -239.66805)
		(width 0.10668)
		(layer "F.Cu")
		(net "M_G_CPU0_SA_DQ<21>")
	)
	(segment
		(start 399.652744 -237.321598)
		(end 408.294332 -228.68001)
		(width 0.10668)
		(layer "F.Cu")
		(net "M_G_CPU0_SA_DQ<21>")
	)
	(segment
		(start 400.612102 -237.325916)
		(end 400.495008 -237.208822)
		(width 0.10668)
		(layer "F.Cu")
		(net "M_G_CPU0_SA_DQ<21>")
	)
	(segment
		(start 408.294332 -228.68001)
		(end 408.294332 -227.905564)
		(width 0.10668)
		(layer "F.Cu")
		(net "M_G_CPU0_SA_DQ<21>")
	)
	(segment
		(start 392.431016 -239.402366)
		(end 392.431016 -239.40262)
		(width 0.0762)
		(layer "F.Cu")
		(net "M_G_CPU0_SA_DQ<21>")
	)
	(segment
		(start 411.317694 -224.272856)
		(end 411.480508 -224.110042)
		(width 0.101346)
		(layer "F.Cu")
		(net "M_G_CPU0_SA_DQ<21>")
	)
	(segment
		(start 411.480508 -224.110042)
		(end 413.798512 -224.110042)
		(width 0.101346)
		(layer "F.Cu")
		(net "M_G_CPU0_SA_DQ<21>")
	)
	(segment
		(start 411.097984 -225.101912)
		(end 411.097984 -224.492566)
		(width 0.10668)
		(layer "F.Cu")
		(net "M_G_CPU0_SA_DQ<21>")
	)
	(segment
		(start 400.495008 -237.208822)
		(end 400.329908 -237.208822)
		(width 0.10668)
		(layer "F.Cu")
		(net "M_G_CPU0_SA_DQ<21>")
	)
	(segment
		(start 394.391134 -239.22863)
		(end 394.800074 -239.22863)
		(width 0.0762)
		(layer "F.Cu")
		(net "M_G_CPU0_SA_DQ<21>")
	)
	(segment
		(start 393.736576 -239.407446)
		(end 393.744958 -239.40262)
		(width 0.0762)
		(layer "F.Cu")
		(net "M_G_CPU0_SA_DQ<21>")
	)
	(segment
		(start 399.652744 -237.486698)
		(end 399.652744 -237.321598)
		(width 0.10668)
		(layer "F.Cu")
		(net "M_G_CPU0_SA_DQ<21>")
	)
	(segment
		(start 414.223454 -223.6851)
		(end 416.468052 -223.6851)
		(width 0.101346)
		(layer "F.Cu")
		(net "M_G_CPU0_SA_DQ<21>")
	)
	(segment
		(start 400.612102 -237.491016)
		(end 400.612102 -237.325916)
		(width 0.10668)
		(layer "F.Cu")
		(net "M_G_CPU0_SA_DQ<21>")
	)
	(segment
		(start 411.097984 -224.492566)
		(end 411.317694 -224.272856)
		(width 0.10668)
		(layer "F.Cu")
		(net "M_G_CPU0_SA_DQ<21>")
	)
	(segment
		(start 394.800074 -239.22863)
		(end 395.239494 -239.66805)
		(width 0.0762)
		(layer "F.Cu")
		(net "M_G_CPU0_SA_DQ<21>")
	)
	(arc
		(start 393.370816 -239.40262)
		(mid 393.553067 -239.45297)
		(end 393.736576 -239.407446)
		(width 0.0762)
		(layer "F.Cu")
		(net "M_G_CPU0_SA_DQ<21>")
	)
	(arc
		(start 392.146536 -239.325912)
		(mid 392.293857 -239.345231)
		(end 392.431016 -239.402366)
		(width 0.0762)
		(layer "F.Cu")
		(net "M_G_CPU0_SA_DQ<21>")
	)
	(arc
		(start 392.804904 -239.40262)
		(mid 393.08786 -239.326443)
		(end 393.370816 -239.40262)
		(width 0.0762)
		(layer "F.Cu")
		(net "M_G_CPU0_SA_DQ<21>")
	)
	(arc
		(start 393.744958 -239.40262)
		(mid 394.056532 -239.27285)
		(end 394.391134 -239.22863)
		(width 0.0762)
		(layer "F.Cu")
		(net "M_G_CPU0_SA_DQ<21>")
	)
	(arc
		(start 392.431016 -239.40262)
		(mid 392.61796 -239.452875)
		(end 392.804904 -239.40262)
		(width 0.0762)
		(layer "F.Cu")
		(net "M_G_CPU0_SA_DQ<21>")
	)
	(arc
		(start 391.677906 -239.08004)
		(mid 391.881922 -239.260734)
		(end 392.146536 -239.325912)
		(width 0.0762)
		(layer "F.Cu")
		(net "M_G_CPU0_SA_DQ<21>")
	)
	(segment
		(start 407.554938 -225.732086)
		(end 407.554938 -225.566732)
		(width 0.10668)
		(layer "F.Cu")
		(net "M_G_CPU0_SA_DQ<20>")
	)
	(segment
		(start 411.316932 -222.41002)
		(end 411.317694 -222.41002)
		(width 0.10668)
		(layer "F.Cu")
		(net "M_G_CPU0_SA_DQ<20>")
	)
	(segment
		(start 408.73807 -225.620834)
		(end 410.417264 -223.94164)
		(width 0.10668)
		(layer "F.Cu")
		(net "M_G_CPU0_SA_DQ<20>")
	)
	(segment
		(start 397.437864 -238.57331)
		(end 407.613612 -228.397562)
		(width 0.10668)
		(layer "F.Cu")
		(net "M_G_CPU0_SA_DQ<20>")
	)
	(segment
		(start 410.417264 -223.309688)
		(end 411.316932 -222.41002)
		(width 0.10668)
		(layer "F.Cu")
		(net "M_G_CPU0_SA_DQ<20>")
	)
	(segment
		(start 415.53257 -221.985078)
		(end 416.468052 -221.985078)
		(width 0.101346)
		(layer "F.Cu")
		(net "M_G_CPU0_SA_DQ<20>")
	)
	(segment
		(start 414.498282 -223.105472)
		(end 414.66135 -223.105472)
		(width 0.101346)
		(layer "F.Cu")
		(net "M_G_CPU0_SA_DQ<20>")
	)
	(segment
		(start 410.417264 -223.94164)
		(end 410.417264 -223.309688)
		(width 0.10668)
		(layer "F.Cu")
		(net "M_G_CPU0_SA_DQ<20>")
	)
	(segment
		(start 394.927836 -238.65205)
		(end 395.006576 -238.57331)
		(width 0.0762)
		(layer "F.Cu")
		(net "M_G_CPU0_SA_DQ<20>")
	)
	(segment
		(start 408.73807 -225.785934)
		(end 408.73807 -225.620834)
		(width 0.10668)
		(layer "F.Cu")
		(net "M_G_CPU0_SA_DQ<20>")
	)
	(segment
		(start 395.578838 -238.57331)
		(end 397.437864 -238.57331)
		(width 0.10668)
		(layer "F.Cu")
		(net "M_G_CPU0_SA_DQ<20>")
	)
	(segment
		(start 409.008326 -226.221036)
		(end 409.008326 -226.055936)
		(width 0.10668)
		(layer "F.Cu")
		(net "M_G_CPU0_SA_DQ<20>")
	)
	(segment
		(start 407.836878 -225.449638)
		(end 408.726132 -226.33813)
		(width 0.10668)
		(layer "F.Cu")
		(net "M_G_CPU0_SA_DQ<20>")
	)
	(segment
		(start 414.382966 -222.525336)
		(end 414.382966 -222.990156)
		(width 0.101346)
		(layer "F.Cu")
		(net "M_G_CPU0_SA_DQ<20>")
	)
	(segment
		(start 408.726132 -226.33813)
		(end 408.891232 -226.33813)
		(width 0.10668)
		(layer "F.Cu")
		(net "M_G_CPU0_SA_DQ<20>")
	)
	(segment
		(start 411.317694 -222.41002)
		(end 414.26765 -222.41002)
		(width 0.101346)
		(layer "F.Cu")
		(net "M_G_CPU0_SA_DQ<20>")
	)
	(segment
		(start 395.006576 -238.57331)
		(end 395.578838 -238.57331)
		(width 0.0762)
		(layer "F.Cu")
		(net "M_G_CPU0_SA_DQ<20>")
	)
	(segment
		(start 408.891232 -226.33813)
		(end 409.008326 -226.221036)
		(width 0.10668)
		(layer "F.Cu")
		(net "M_G_CPU0_SA_DQ<20>")
	)
	(segment
		(start 408.008582 -226.185222)
		(end 407.554938 -225.732086)
		(width 0.10668)
		(layer "F.Cu")
		(net "M_G_CPU0_SA_DQ<20>")
	)
	(segment
		(start 414.891982 -222.41002)
		(end 415.107628 -222.41002)
		(width 0.101346)
		(layer "F.Cu")
		(net "M_G_CPU0_SA_DQ<20>")
	)
	(segment
		(start 407.613612 -228.397562)
		(end 407.613612 -226.745292)
		(width 0.10668)
		(layer "F.Cu")
		(net "M_G_CPU0_SA_DQ<20>")
	)
	(segment
		(start 414.26765 -222.41002)
		(end 414.382966 -222.525336)
		(width 0.101346)
		(layer "F.Cu")
		(net "M_G_CPU0_SA_DQ<20>")
	)
	(segment
		(start 408.008582 -226.350322)
		(end 408.008582 -226.185222)
		(width 0.10668)
		(layer "F.Cu")
		(net "M_G_CPU0_SA_DQ<20>")
	)
	(segment
		(start 409.008326 -226.055936)
		(end 408.73807 -225.785934)
		(width 0.10668)
		(layer "F.Cu")
		(net "M_G_CPU0_SA_DQ<20>")
	)
	(segment
		(start 414.776666 -222.525336)
		(end 414.891982 -222.41002)
		(width 0.101346)
		(layer "F.Cu")
		(net "M_G_CPU0_SA_DQ<20>")
	)
	(segment
		(start 407.672032 -225.449638)
		(end 407.836878 -225.449638)
		(width 0.10668)
		(layer "F.Cu")
		(net "M_G_CPU0_SA_DQ<20>")
	)
	(segment
		(start 414.776666 -222.990156)
		(end 414.776666 -222.525336)
		(width 0.101346)
		(layer "F.Cu")
		(net "M_G_CPU0_SA_DQ<20>")
	)
	(segment
		(start 394.06195 -238.65205)
		(end 394.927836 -238.65205)
		(width 0.0762)
		(layer "F.Cu")
		(net "M_G_CPU0_SA_DQ<20>")
	)
	(segment
		(start 415.107628 -222.41002)
		(end 415.53257 -221.985078)
		(width 0.101346)
		(layer "F.Cu")
		(net "M_G_CPU0_SA_DQ<20>")
	)
	(segment
		(start 414.382966 -222.990156)
		(end 414.498282 -223.105472)
		(width 0.101346)
		(layer "F.Cu")
		(net "M_G_CPU0_SA_DQ<20>")
	)
	(segment
		(start 414.66135 -223.105472)
		(end 414.776666 -222.990156)
		(width 0.101346)
		(layer "F.Cu")
		(net "M_G_CPU0_SA_DQ<20>")
	)
	(segment
		(start 407.554938 -225.566732)
		(end 407.672032 -225.449638)
		(width 0.10668)
		(layer "F.Cu")
		(net "M_G_CPU0_SA_DQ<20>")
	)
	(segment
		(start 407.613612 -226.745292)
		(end 408.008582 -226.350322)
		(width 0.10668)
		(layer "F.Cu")
		(net "M_G_CPU0_SA_DQ<20>")
	)
	(arc
		(start 393.605512 -238.518192)
		(mid 393.727368 -238.542348)
		(end 393.84097 -238.592614)
		(width 0.0762)
		(layer "F.Cu")
		(net "M_G_CPU0_SA_DQ<20>")
	)
	(arc
		(start 393.84097 -238.592614)
		(mid 393.947532 -238.636939)
		(end 394.06195 -238.65205)
		(width 0.0762)
		(layer "F.Cu")
		(net "M_G_CPU0_SA_DQ<20>")
	)
	(arc
		(start 393.08786 -238.270034)
		(mid 393.323988 -238.441469)
		(end 393.605512 -238.518192)
		(width 0.0762)
		(layer "F.Cu")
		(net "M_G_CPU0_SA_DQ<20>")
	)
	(segment
		(start 396.236952 -214.779606)
		(end 401.749006 -209.267552)
		(width 0.10668)
		(layer "F.Cu")
		(net "M_G_CPU0_SA_DQ<1>")
	)
	(segment
		(start 402.466556 -207.535526)
		(end 410.541978 -199.460104)
		(width 0.10668)
		(layer "F.Cu")
		(net "M_G_CPU0_SA_DQ<1>")
	)
	(segment
		(start 401.749006 -209.267552)
		(end 402.466556 -207.535526)
		(width 0.10668)
		(layer "F.Cu")
		(net "M_G_CPU0_SA_DQ<1>")
	)
	(segment
		(start 411.317694 -199.460104)
		(end 413.236664 -199.460104)
		(width 0.101346)
		(layer "F.Cu")
		(net "M_G_CPU0_SA_DQ<1>")
	)
	(segment
		(start 396.236952 -223.874584)
		(end 396.236952 -214.779606)
		(width 0.10668)
		(layer "F.Cu")
		(net "M_G_CPU0_SA_DQ<1>")
	)
	(segment
		(start 395.228318 -225.162618)
		(end 395.228318 -224.883218)
		(width 0.0762)
		(layer "F.Cu")
		(net "M_G_CPU0_SA_DQ<1>")
	)
	(segment
		(start 394.327126 -226.06381)
		(end 395.228318 -225.162618)
		(width 0.0762)
		(layer "F.Cu")
		(net "M_G_CPU0_SA_DQ<1>")
	)
	(segment
		(start 410.541978 -199.460104)
		(end 411.317694 -199.460104)
		(width 0.10668)
		(layer "F.Cu")
		(net "M_G_CPU0_SA_DQ<1>")
	)
	(segment
		(start 415.373312 -199.035162)
		(end 416.468052 -199.035162)
		(width 0.101346)
		(layer "F.Cu")
		(net "M_G_CPU0_SA_DQ<1>")
	)
	(segment
		(start 395.228318 -224.883218)
		(end 396.236952 -223.874584)
		(width 0.10668)
		(layer "F.Cu")
		(net "M_G_CPU0_SA_DQ<1>")
	)
	(segment
		(start 413.236664 -199.460104)
		(end 415.373312 -199.035162)
		(width 0.101346)
		(layer "F.Cu")
		(net "M_G_CPU0_SA_DQ<1>")
	)
	(segment
		(start 393.821666 -226.38385)
		(end 394.141706 -226.06381)
		(width 0.0762)
		(layer "F.Cu")
		(net "M_G_CPU0_SA_DQ<1>")
	)
	(segment
		(start 394.141706 -226.06381)
		(end 394.327126 -226.06381)
		(width 0.0762)
		(layer "F.Cu")
		(net "M_G_CPU0_SA_DQ<1>")
	)
	(arc
		(start 392.804904 -226.442778)
		(mid 393.08786 -226.366601)
		(end 393.370816 -226.442778)
		(width 0.0762)
		(layer "F.Cu")
		(net "M_G_CPU0_SA_DQ<1>")
	)
	(arc
		(start 393.370816 -226.442778)
		(mid 393.553067 -226.493128)
		(end 393.736576 -226.447604)
		(width 0.0762)
		(layer "F.Cu")
		(net "M_G_CPU0_SA_DQ<1>")
	)
	(arc
		(start 392.431016 -226.442778)
		(mid 392.61796 -226.493033)
		(end 392.804904 -226.442778)
		(width 0.0762)
		(layer "F.Cu")
		(net "M_G_CPU0_SA_DQ<1>")
	)
	(arc
		(start 393.736576 -226.447604)
		(mid 393.781396 -226.418765)
		(end 393.821666 -226.38385)
		(width 0.0762)
		(layer "F.Cu")
		(net "M_G_CPU0_SA_DQ<1>")
	)
	(arc
		(start 391.677906 -226.120198)
		(mid 391.887617 -226.301336)
		(end 392.15695 -226.366578)
		(width 0.0762)
		(layer "F.Cu")
		(net "M_G_CPU0_SA_DQ<1>")
	)
	(arc
		(start 392.15695 -226.366578)
		(mid 392.298863 -226.38712)
		(end 392.431016 -226.442778)
		(width 0.0762)
		(layer "F.Cu")
		(net "M_G_CPU0_SA_DQ<1>")
	)
	(segment
		(start 407.563828 -221.510352)
		(end 407.563828 -221.345252)
		(width 0.10668)
		(layer "F.Cu")
		(net "M_G_CPU0_SA_DQ<19>")
	)
	(segment
		(start 396.762224 -236.56163)
		(end 405.667718 -227.656136)
		(width 0.10668)
		(layer "F.Cu")
		(net "M_G_CPU0_SA_DQ<19>")
	)
	(segment
		(start 409.980892 -218.682824)
		(end 410.103574 -218.805506)
		(width 0.10668)
		(layer "F.Cu")
		(net "M_G_CPU0_SA_DQ<19>")
	)
	(segment
		(start 406.31237 -222.351346)
		(end 406.31237 -222.186246)
		(width 0.10668)
		(layer "F.Cu")
		(net "M_G_CPU0_SA_DQ<19>")
	)
	(segment
		(start 408.41041 -220.49867)
		(end 408.57551 -220.49867)
		(width 0.10668)
		(layer "F.Cu")
		(net "M_G_CPU0_SA_DQ<19>")
	)
	(segment
		(start 408.287728 -220.375988)
		(end 408.41041 -220.49867)
		(width 0.10668)
		(layer "F.Cu")
		(net "M_G_CPU0_SA_DQ<19>")
	)
	(segment
		(start 410.268674 -218.805506)
		(end 410.489146 -218.585034)
		(width 0.10668)
		(layer "F.Cu")
		(net "M_G_CPU0_SA_DQ<19>")
	)
	(segment
		(start 408.005534 -220.493082)
		(end 408.122628 -220.375988)
		(width 0.10668)
		(layer "F.Cu")
		(net "M_G_CPU0_SA_DQ<19>")
	)
	(segment
		(start 408.005534 -220.658182)
		(end 408.005534 -220.493082)
		(width 0.10668)
		(layer "F.Cu")
		(net "M_G_CPU0_SA_DQ<19>")
	)
	(segment
		(start 408.569922 -220.093794)
		(end 408.569922 -219.928694)
		(width 0.10668)
		(layer "F.Cu")
		(net "M_G_CPU0_SA_DQ<19>")
	)
	(segment
		(start 392.326622 -236.322616)
		(end 392.327638 -236.323124)
		(width 0.0762)
		(layer "F.Cu")
		(net "M_G_CPU0_SA_DQ<19>")
	)
	(segment
		(start 407.158952 -221.504764)
		(end 407.281634 -221.627446)
		(width 0.10668)
		(layer "F.Cu")
		(net "M_G_CPU0_SA_DQ<19>")
	)
	(segment
		(start 408.57551 -220.49867)
		(end 408.692604 -220.381576)
		(width 0.10668)
		(layer "F.Cu")
		(net "M_G_CPU0_SA_DQ<19>")
	)
	(segment
		(start 408.569922 -219.928694)
		(end 408.687016 -219.8116)
		(width 0.10668)
		(layer "F.Cu")
		(net "M_G_CPU0_SA_DQ<19>")
	)
	(segment
		(start 408.692604 -220.381576)
		(end 408.692604 -220.216476)
		(width 0.10668)
		(layer "F.Cu")
		(net "M_G_CPU0_SA_DQ<19>")
	)
	(segment
		(start 395.682216 -236.56163)
		(end 396.762224 -236.56163)
		(width 0.10668)
		(layer "F.Cu")
		(net "M_G_CPU0_SA_DQ<19>")
	)
	(segment
		(start 392.327638 -236.323124)
		(end 392.335004 -236.327442)
		(width 0.0762)
		(layer "F.Cu")
		(net "M_G_CPU0_SA_DQ<19>")
	)
	(segment
		(start 392.14806 -236.649768)
		(end 392.042904 -236.46892)
		(width 0.0762)
		(layer "F.Cu")
		(net "M_G_CPU0_SA_DQ<19>")
	)
	(segment
		(start 406.435052 -222.474028)
		(end 406.31237 -222.351346)
		(width 0.10668)
		(layer "F.Cu")
		(net "M_G_CPU0_SA_DQ<19>")
	)
	(segment
		(start 407.441146 -221.05747)
		(end 407.55824 -220.940376)
		(width 0.10668)
		(layer "F.Cu")
		(net "M_G_CPU0_SA_DQ<19>")
	)
	(segment
		(start 409.13431 -219.364306)
		(end 409.251404 -219.247212)
		(width 0.10668)
		(layer "F.Cu")
		(net "M_G_CPU0_SA_DQ<19>")
	)
	(segment
		(start 395.103096 -236.56163)
		(end 395.682216 -236.56163)
		(width 0.0762)
		(layer "F.Cu")
		(net "M_G_CPU0_SA_DQ<19>")
	)
	(segment
		(start 407.446734 -221.627446)
		(end 407.563828 -221.510352)
		(width 0.10668)
		(layer "F.Cu")
		(net "M_G_CPU0_SA_DQ<19>")
	)
	(segment
		(start 406.993852 -221.504764)
		(end 407.158952 -221.504764)
		(width 0.10668)
		(layer "F.Cu")
		(net "M_G_CPU0_SA_DQ<19>")
	)
	(segment
		(start 408.687016 -219.8116)
		(end 408.852116 -219.8116)
		(width 0.10668)
		(layer "F.Cu")
		(net "M_G_CPU0_SA_DQ<19>")
	)
	(segment
		(start 408.692604 -220.216476)
		(end 408.569922 -220.093794)
		(width 0.10668)
		(layer "F.Cu")
		(net "M_G_CPU0_SA_DQ<19>")
	)
	(segment
		(start 406.876758 -221.621858)
		(end 406.993852 -221.504764)
		(width 0.10668)
		(layer "F.Cu")
		(net "M_G_CPU0_SA_DQ<19>")
	)
	(segment
		(start 392.900916 -236.327442)
		(end 392.909298 -236.322616)
		(width 0.0762)
		(layer "F.Cu")
		(net "M_G_CPU0_SA_DQ<19>")
	)
	(segment
		(start 409.539186 -219.369894)
		(end 409.704286 -219.369894)
		(width 0.10668)
		(layer "F.Cu")
		(net "M_G_CPU0_SA_DQ<19>")
	)
	(segment
		(start 410.103574 -218.805506)
		(end 410.268674 -218.805506)
		(width 0.10668)
		(layer "F.Cu")
		(net "M_G_CPU0_SA_DQ<19>")
	)
	(segment
		(start 406.99944 -221.90964)
		(end 406.876758 -221.786958)
		(width 0.10668)
		(layer "F.Cu")
		(net "M_G_CPU0_SA_DQ<19>")
	)
	(segment
		(start 409.13431 -219.529406)
		(end 409.13431 -219.364306)
		(width 0.10668)
		(layer "F.Cu")
		(net "M_G_CPU0_SA_DQ<19>")
	)
	(segment
		(start 409.704286 -219.369894)
		(end 409.82138 -219.2528)
		(width 0.10668)
		(layer "F.Cu")
		(net "M_G_CPU0_SA_DQ<19>")
	)
	(segment
		(start 408.852116 -219.8116)
		(end 408.974798 -219.934282)
		(width 0.10668)
		(layer "F.Cu")
		(net "M_G_CPU0_SA_DQ<19>")
	)
	(segment
		(start 392.14806 -236.650022)
		(end 392.14806 -236.649768)
		(width 0.0762)
		(layer "F.Cu")
		(net "M_G_CPU0_SA_DQ<19>")
	)
	(segment
		(start 409.416504 -219.247212)
		(end 409.539186 -219.369894)
		(width 0.10668)
		(layer "F.Cu")
		(net "M_G_CPU0_SA_DQ<19>")
	)
	(segment
		(start 406.435052 -222.639128)
		(end 406.435052 -222.474028)
		(width 0.10668)
		(layer "F.Cu")
		(net "M_G_CPU0_SA_DQ<19>")
	)
	(segment
		(start 407.281634 -221.627446)
		(end 407.446734 -221.627446)
		(width 0.10668)
		(layer "F.Cu")
		(net "M_G_CPU0_SA_DQ<19>")
	)
	(segment
		(start 406.882346 -222.191834)
		(end 406.99944 -222.07474)
		(width 0.10668)
		(layer "F.Cu")
		(net "M_G_CPU0_SA_DQ<19>")
	)
	(segment
		(start 408.128216 -220.780864)
		(end 408.005534 -220.658182)
		(width 0.10668)
		(layer "F.Cu")
		(net "M_G_CPU0_SA_DQ<19>")
	)
	(segment
		(start 407.55824 -220.940376)
		(end 407.72334 -220.940376)
		(width 0.10668)
		(layer "F.Cu")
		(net "M_G_CPU0_SA_DQ<19>")
	)
	(segment
		(start 409.698698 -218.965018)
		(end 409.698698 -218.799918)
		(width 0.10668)
		(layer "F.Cu")
		(net "M_G_CPU0_SA_DQ<19>")
	)
	(segment
		(start 407.72334 -220.940376)
		(end 407.846022 -221.063058)
		(width 0.10668)
		(layer "F.Cu")
		(net "M_G_CPU0_SA_DQ<19>")
	)
	(segment
		(start 405.747982 -222.750634)
		(end 405.865076 -222.63354)
		(width 0.10668)
		(layer "F.Cu")
		(net "M_G_CPU0_SA_DQ<19>")
	)
	(segment
		(start 408.974798 -219.934282)
		(end 409.139898 -219.934282)
		(width 0.10668)
		(layer "F.Cu")
		(net "M_G_CPU0_SA_DQ<19>")
	)
	(segment
		(start 406.429464 -222.069152)
		(end 406.594564 -222.069152)
		(width 0.10668)
		(layer "F.Cu")
		(net "M_G_CPU0_SA_DQ<19>")
	)
	(segment
		(start 409.82138 -219.0877)
		(end 409.698698 -218.965018)
		(width 0.10668)
		(layer "F.Cu")
		(net "M_G_CPU0_SA_DQ<19>")
	)
	(segment
		(start 410.489146 -218.585034)
		(end 412.367984 -218.585034)
		(width 0.10668)
		(layer "F.Cu")
		(net "M_G_CPU0_SA_DQ<19>")
	)
	(segment
		(start 405.667718 -227.656136)
		(end 405.667718 -223.406462)
		(width 0.10668)
		(layer "F.Cu")
		(net "M_G_CPU0_SA_DQ<19>")
	)
	(segment
		(start 409.82138 -219.2528)
		(end 409.82138 -219.0877)
		(width 0.10668)
		(layer "F.Cu")
		(net "M_G_CPU0_SA_DQ<19>")
	)
	(segment
		(start 405.667718 -223.406462)
		(end 405.870664 -223.203516)
		(width 0.10668)
		(layer "F.Cu")
		(net "M_G_CPU0_SA_DQ<19>")
	)
	(segment
		(start 409.256992 -219.652088)
		(end 409.13431 -219.529406)
		(width 0.10668)
		(layer "F.Cu")
		(net "M_G_CPU0_SA_DQ<19>")
	)
	(segment
		(start 406.030176 -222.63354)
		(end 406.152858 -222.756222)
		(width 0.10668)
		(layer "F.Cu")
		(net "M_G_CPU0_SA_DQ<19>")
	)
	(segment
		(start 406.152858 -222.756222)
		(end 406.317958 -222.756222)
		(width 0.10668)
		(layer "F.Cu")
		(net "M_G_CPU0_SA_DQ<19>")
	)
	(segment
		(start 409.698698 -218.799918)
		(end 409.815792 -218.682824)
		(width 0.10668)
		(layer "F.Cu")
		(net "M_G_CPU0_SA_DQ<19>")
	)
	(segment
		(start 409.815792 -218.682824)
		(end 409.980892 -218.682824)
		(width 0.10668)
		(layer "F.Cu")
		(net "M_G_CPU0_SA_DQ<19>")
	)
	(segment
		(start 406.876758 -221.786958)
		(end 406.876758 -221.621858)
		(width 0.10668)
		(layer "F.Cu")
		(net "M_G_CPU0_SA_DQ<19>")
	)
	(segment
		(start 394.046456 -236.27207)
		(end 394.813536 -236.27207)
		(width 0.0762)
		(layer "F.Cu")
		(net "M_G_CPU0_SA_DQ<19>")
	)
	(segment
		(start 406.99944 -222.07474)
		(end 406.99944 -221.90964)
		(width 0.10668)
		(layer "F.Cu")
		(net "M_G_CPU0_SA_DQ<19>")
	)
	(segment
		(start 407.563828 -221.345252)
		(end 407.441146 -221.22257)
		(width 0.10668)
		(layer "F.Cu")
		(net "M_G_CPU0_SA_DQ<19>")
	)
	(segment
		(start 408.011122 -221.063058)
		(end 408.128216 -220.945964)
		(width 0.10668)
		(layer "F.Cu")
		(net "M_G_CPU0_SA_DQ<19>")
	)
	(segment
		(start 406.717246 -222.191834)
		(end 406.882346 -222.191834)
		(width 0.10668)
		(layer "F.Cu")
		(net "M_G_CPU0_SA_DQ<19>")
	)
	(segment
		(start 409.256992 -219.817188)
		(end 409.256992 -219.652088)
		(width 0.10668)
		(layer "F.Cu")
		(net "M_G_CPU0_SA_DQ<19>")
	)
	(segment
		(start 409.139898 -219.934282)
		(end 409.256992 -219.817188)
		(width 0.10668)
		(layer "F.Cu")
		(net "M_G_CPU0_SA_DQ<19>")
	)
	(segment
		(start 407.441146 -221.22257)
		(end 407.441146 -221.05747)
		(width 0.10668)
		(layer "F.Cu")
		(net "M_G_CPU0_SA_DQ<19>")
	)
	(segment
		(start 407.846022 -221.063058)
		(end 408.011122 -221.063058)
		(width 0.10668)
		(layer "F.Cu")
		(net "M_G_CPU0_SA_DQ<19>")
	)
	(segment
		(start 394.813536 -236.27207)
		(end 395.103096 -236.56163)
		(width 0.0762)
		(layer "F.Cu")
		(net "M_G_CPU0_SA_DQ<19>")
	)
	(segment
		(start 408.128216 -220.945964)
		(end 408.128216 -220.780864)
		(width 0.10668)
		(layer "F.Cu")
		(net "M_G_CPU0_SA_DQ<19>")
	)
	(segment
		(start 409.251404 -219.247212)
		(end 409.416504 -219.247212)
		(width 0.10668)
		(layer "F.Cu")
		(net "M_G_CPU0_SA_DQ<19>")
	)
	(segment
		(start 405.870664 -223.038416)
		(end 405.747982 -222.915734)
		(width 0.10668)
		(layer "F.Cu")
		(net "M_G_CPU0_SA_DQ<19>")
	)
	(segment
		(start 405.747982 -222.915734)
		(end 405.747982 -222.750634)
		(width 0.10668)
		(layer "F.Cu")
		(net "M_G_CPU0_SA_DQ<19>")
	)
	(segment
		(start 406.594564 -222.069152)
		(end 406.717246 -222.191834)
		(width 0.10668)
		(layer "F.Cu")
		(net "M_G_CPU0_SA_DQ<19>")
	)
	(segment
		(start 405.865076 -222.63354)
		(end 406.030176 -222.63354)
		(width 0.10668)
		(layer "F.Cu")
		(net "M_G_CPU0_SA_DQ<19>")
	)
	(segment
		(start 405.870664 -223.203516)
		(end 405.870664 -223.038416)
		(width 0.10668)
		(layer "F.Cu")
		(net "M_G_CPU0_SA_DQ<19>")
	)
	(segment
		(start 406.317958 -222.756222)
		(end 406.435052 -222.639128)
		(width 0.10668)
		(layer "F.Cu")
		(net "M_G_CPU0_SA_DQ<19>")
	)
	(segment
		(start 408.122628 -220.375988)
		(end 408.287728 -220.375988)
		(width 0.10668)
		(layer "F.Cu")
		(net "M_G_CPU0_SA_DQ<19>")
	)
	(segment
		(start 406.31237 -222.186246)
		(end 406.429464 -222.069152)
		(width 0.10668)
		(layer "F.Cu")
		(net "M_G_CPU0_SA_DQ<19>")
	)
	(arc
		(start 393.84097 -236.327442)
		(mid 393.940043 -236.286128)
		(end 394.046456 -236.27207)
		(width 0.0762)
		(layer "F.Cu")
		(net "M_G_CPU0_SA_DQ<19>")
	)
	(arc
		(start 392.042904 -236.46892)
		(mid 392.051841 -236.349896)
		(end 392.146536 -236.27715)
		(width 0.0762)
		(layer "F.Cu")
		(net "M_G_CPU0_SA_DQ<19>")
	)
	(arc
		(start 392.335004 -236.327442)
		(mid 392.61796 -236.403619)
		(end 392.900916 -236.327442)
		(width 0.0762)
		(layer "F.Cu")
		(net "M_G_CPU0_SA_DQ<19>")
	)
	(arc
		(start 392.909298 -236.322616)
		(mid 393.092806 -236.277122)
		(end 393.275058 -236.327442)
		(width 0.0762)
		(layer "F.Cu")
		(net "M_G_CPU0_SA_DQ<19>")
	)
	(arc
		(start 392.146536 -236.27715)
		(mid 392.23946 -236.288473)
		(end 392.326622 -236.322616)
		(width 0.0762)
		(layer "F.Cu")
		(net "M_G_CPU0_SA_DQ<19>")
	)
	(arc
		(start 393.275058 -236.327442)
		(mid 393.558014 -236.403619)
		(end 393.84097 -236.327442)
		(width 0.0762)
		(layer "F.Cu")
		(net "M_G_CPU0_SA_DQ<19>")
	)
	(segment
		(start 407.39187 -219.293948)
		(end 407.508964 -219.176854)
		(width 0.10668)
		(layer "F.Cu")
		(net "M_G_CPU0_SA_DQ<18>")
	)
	(segment
		(start 409.085034 -217.600784)
		(end 409.202128 -217.48369)
		(width 0.10668)
		(layer "F.Cu")
		(net "M_G_CPU0_SA_DQ<18>")
	)
	(segment
		(start 408.80284 -218.048078)
		(end 409.062682 -218.307666)
		(width 0.10668)
		(layer "F.Cu")
		(net "M_G_CPU0_SA_DQ<18>")
	)
	(segment
		(start 408.073352 -218.612466)
		(end 408.238452 -218.612466)
		(width 0.10668)
		(layer "F.Cu")
		(net "M_G_CPU0_SA_DQ<18>")
	)
	(segment
		(start 393.736576 -235.51261)
		(end 393.744958 -235.517436)
		(width 0.0762)
		(layer "F.Cu")
		(net "M_G_CPU0_SA_DQ<18>")
	)
	(segment
		(start 407.933906 -219.436442)
		(end 408.099006 -219.436442)
		(width 0.10668)
		(layer "F.Cu")
		(net "M_G_CPU0_SA_DQ<18>")
	)
	(segment
		(start 409.227782 -218.307666)
		(end 409.344876 -218.190572)
		(width 0.10668)
		(layer "F.Cu")
		(net "M_G_CPU0_SA_DQ<18>")
	)
	(segment
		(start 409.766516 -216.919302)
		(end 409.931616 -216.919302)
		(width 0.10668)
		(layer "F.Cu")
		(net "M_G_CPU0_SA_DQ<18>")
	)
	(segment
		(start 395.738096 -235.88091)
		(end 396.479776 -235.88091)
		(width 0.10668)
		(layer "F.Cu")
		(net "M_G_CPU0_SA_DQ<18>")
	)
	(segment
		(start 408.498294 -218.872054)
		(end 408.663394 -218.872054)
		(width 0.10668)
		(layer "F.Cu")
		(net "M_G_CPU0_SA_DQ<18>")
	)
	(segment
		(start 408.780488 -218.75496)
		(end 408.780488 -218.58986)
		(width 0.10668)
		(layer "F.Cu")
		(net "M_G_CPU0_SA_DQ<18>")
	)
	(segment
		(start 396.479776 -235.88091)
		(end 404.986998 -227.373688)
		(width 0.10668)
		(layer "F.Cu")
		(net "M_G_CPU0_SA_DQ<18>")
	)
	(segment
		(start 408.2161 -219.154248)
		(end 407.956258 -218.89466)
		(width 0.10668)
		(layer "F.Cu")
		(net "M_G_CPU0_SA_DQ<18>")
	)
	(segment
		(start 407.651712 -219.883736)
		(end 407.651712 -219.718636)
		(width 0.10668)
		(layer "F.Cu")
		(net "M_G_CPU0_SA_DQ<18>")
	)
	(segment
		(start 409.344876 -218.190572)
		(end 409.344876 -218.025472)
		(width 0.10668)
		(layer "F.Cu")
		(net "M_G_CPU0_SA_DQ<18>")
	)
	(segment
		(start 410.650436 -216.885012)
		(end 412.367984 -216.885012)
		(width 0.10668)
		(layer "F.Cu")
		(net "M_G_CPU0_SA_DQ<18>")
	)
	(segment
		(start 407.508964 -219.176854)
		(end 407.674064 -219.176854)
		(width 0.10668)
		(layer "F.Cu")
		(net "M_G_CPU0_SA_DQ<18>")
	)
	(segment
		(start 407.651712 -219.718636)
		(end 407.39187 -219.459048)
		(width 0.10668)
		(layer "F.Cu")
		(net "M_G_CPU0_SA_DQ<18>")
	)
	(segment
		(start 408.520646 -218.330272)
		(end 408.520646 -218.165172)
		(width 0.10668)
		(layer "F.Cu")
		(net "M_G_CPU0_SA_DQ<18>")
	)
	(segment
		(start 407.956258 -218.89466)
		(end 407.956258 -218.72956)
		(width 0.10668)
		(layer "F.Cu")
		(net "M_G_CPU0_SA_DQ<18>")
	)
	(segment
		(start 409.202128 -217.48369)
		(end 409.367228 -217.48369)
		(width 0.10668)
		(layer "F.Cu")
		(net "M_G_CPU0_SA_DQ<18>")
	)
	(segment
		(start 409.344876 -218.025472)
		(end 409.085034 -217.765884)
		(width 0.10668)
		(layer "F.Cu")
		(net "M_G_CPU0_SA_DQ<18>")
	)
	(segment
		(start 408.238452 -218.612466)
		(end 408.498294 -218.872054)
		(width 0.10668)
		(layer "F.Cu")
		(net "M_G_CPU0_SA_DQ<18>")
	)
	(segment
		(start 410.191458 -217.17889)
		(end 410.356558 -217.17889)
		(width 0.10668)
		(layer "F.Cu")
		(net "M_G_CPU0_SA_DQ<18>")
	)
	(segment
		(start 407.39187 -219.459048)
		(end 407.39187 -219.293948)
		(width 0.10668)
		(layer "F.Cu")
		(net "M_G_CPU0_SA_DQ<18>")
	)
	(segment
		(start 393.558014 -235.840016)
		(end 393.46505 -235.679996)
		(width 0.0762)
		(layer "F.Cu")
		(net "M_G_CPU0_SA_DQ<18>")
	)
	(segment
		(start 409.909264 -217.461084)
		(end 409.649422 -217.201496)
		(width 0.10668)
		(layer "F.Cu")
		(net "M_G_CPU0_SA_DQ<18>")
	)
	(segment
		(start 409.085034 -217.765884)
		(end 409.085034 -217.600784)
		(width 0.10668)
		(layer "F.Cu")
		(net "M_G_CPU0_SA_DQ<18>")
	)
	(segment
		(start 407.674064 -219.176854)
		(end 407.933906 -219.436442)
		(width 0.10668)
		(layer "F.Cu")
		(net "M_G_CPU0_SA_DQ<18>")
	)
	(segment
		(start 404.986998 -227.373688)
		(end 404.986998 -222.54845)
		(width 0.10668)
		(layer "F.Cu")
		(net "M_G_CPU0_SA_DQ<18>")
	)
	(segment
		(start 395.278356 -235.88091)
		(end 395.738096 -235.88091)
		(width 0.0762)
		(layer "F.Cu")
		(net "M_G_CPU0_SA_DQ<18>")
	)
	(segment
		(start 409.649422 -217.201496)
		(end 409.649422 -217.036396)
		(width 0.10668)
		(layer "F.Cu")
		(net "M_G_CPU0_SA_DQ<18>")
	)
	(segment
		(start 395.052296 -235.65485)
		(end 395.278356 -235.88091)
		(width 0.0762)
		(layer "F.Cu")
		(net "M_G_CPU0_SA_DQ<18>")
	)
	(segment
		(start 410.356558 -217.17889)
		(end 410.650436 -216.885012)
		(width 0.10668)
		(layer "F.Cu")
		(net "M_G_CPU0_SA_DQ<18>")
	)
	(segment
		(start 408.099006 -219.436442)
		(end 408.2161 -219.319348)
		(width 0.10668)
		(layer "F.Cu")
		(net "M_G_CPU0_SA_DQ<18>")
	)
	(segment
		(start 409.79217 -217.743278)
		(end 409.909264 -217.626184)
		(width 0.10668)
		(layer "F.Cu")
		(net "M_G_CPU0_SA_DQ<18>")
	)
	(segment
		(start 408.2161 -219.319348)
		(end 408.2161 -219.154248)
		(width 0.10668)
		(layer "F.Cu")
		(net "M_G_CPU0_SA_DQ<18>")
	)
	(segment
		(start 408.663394 -218.872054)
		(end 408.780488 -218.75496)
		(width 0.10668)
		(layer "F.Cu")
		(net "M_G_CPU0_SA_DQ<18>")
	)
	(segment
		(start 409.367228 -217.48369)
		(end 409.62707 -217.743278)
		(width 0.10668)
		(layer "F.Cu")
		(net "M_G_CPU0_SA_DQ<18>")
	)
	(segment
		(start 394.255244 -235.65485)
		(end 395.052296 -235.65485)
		(width 0.0762)
		(layer "F.Cu")
		(net "M_G_CPU0_SA_DQ<18>")
	)
	(segment
		(start 408.520646 -218.165172)
		(end 408.63774 -218.048078)
		(width 0.10668)
		(layer "F.Cu")
		(net "M_G_CPU0_SA_DQ<18>")
	)
	(segment
		(start 408.63774 -218.048078)
		(end 408.80284 -218.048078)
		(width 0.10668)
		(layer "F.Cu")
		(net "M_G_CPU0_SA_DQ<18>")
	)
	(segment
		(start 407.956258 -218.72956)
		(end 408.073352 -218.612466)
		(width 0.10668)
		(layer "F.Cu")
		(net "M_G_CPU0_SA_DQ<18>")
	)
	(segment
		(start 408.780488 -218.58986)
		(end 408.520646 -218.330272)
		(width 0.10668)
		(layer "F.Cu")
		(net "M_G_CPU0_SA_DQ<18>")
	)
	(segment
		(start 409.062682 -218.307666)
		(end 409.227782 -218.307666)
		(width 0.10668)
		(layer "F.Cu")
		(net "M_G_CPU0_SA_DQ<18>")
	)
	(segment
		(start 409.649422 -217.036396)
		(end 409.766516 -216.919302)
		(width 0.10668)
		(layer "F.Cu")
		(net "M_G_CPU0_SA_DQ<18>")
	)
	(segment
		(start 409.909264 -217.626184)
		(end 409.909264 -217.461084)
		(width 0.10668)
		(layer "F.Cu")
		(net "M_G_CPU0_SA_DQ<18>")
	)
	(segment
		(start 409.931616 -216.919302)
		(end 410.191458 -217.17889)
		(width 0.10668)
		(layer "F.Cu")
		(net "M_G_CPU0_SA_DQ<18>")
	)
	(segment
		(start 404.986998 -222.54845)
		(end 407.651712 -219.883736)
		(width 0.10668)
		(layer "F.Cu")
		(net "M_G_CPU0_SA_DQ<18>")
	)
	(segment
		(start 409.62707 -217.743278)
		(end 409.79217 -217.743278)
		(width 0.10668)
		(layer "F.Cu")
		(net "M_G_CPU0_SA_DQ<18>")
	)
	(arc
		(start 393.744958 -235.517436)
		(mid 393.991004 -235.619938)
		(end 394.255244 -235.65485)
		(width 0.0762)
		(layer "F.Cu")
		(net "M_G_CPU0_SA_DQ<18>")
	)
	(arc
		(start 393.46505 -235.679996)
		(mid 393.46521 -235.533435)
		(end 393.596876 -235.469176)
		(width 0.0762)
		(layer "F.Cu")
		(net "M_G_CPU0_SA_DQ<18>")
	)
	(arc
		(start 393.596876 -235.469176)
		(mid 393.668884 -235.483958)
		(end 393.736576 -235.51261)
		(width 0.0762)
		(layer "F.Cu")
		(net "M_G_CPU0_SA_DQ<18>")
	)
	(segment
		(start 405.327358 -227.514912)
		(end 405.327358 -222.689674)
		(width 0.10668)
		(layer "F.Cu")
		(net "M_G_CPU0_SA_DQ<17>")
	)
	(segment
		(start 396.621 -236.22127)
		(end 405.327358 -227.514912)
		(width 0.10668)
		(layer "F.Cu")
		(net "M_G_CPU0_SA_DQ<17>")
	)
	(segment
		(start 395.146276 -236.22127)
		(end 395.715236 -236.22127)
		(width 0.0762)
		(layer "F.Cu")
		(net "M_G_CPU0_SA_DQ<17>")
	)
	(segment
		(start 393.736576 -236.167422)
		(end 393.744958 -236.162596)
		(width 0.0762)
		(layer "F.Cu")
		(net "M_G_CPU0_SA_DQ<17>")
	)
	(segment
		(start 413.82061 -218.160092)
		(end 414.846516 -217.73515)
		(width 0.101346)
		(layer "F.Cu")
		(net "M_G_CPU0_SA_DQ<17>")
	)
	(segment
		(start 409.85694 -218.160092)
		(end 411.317694 -218.160092)
		(width 0.10668)
		(layer "F.Cu")
		(net "M_G_CPU0_SA_DQ<17>")
	)
	(segment
		(start 394.904976 -235.97997)
		(end 395.146276 -236.22127)
		(width 0.0762)
		(layer "F.Cu")
		(net "M_G_CPU0_SA_DQ<17>")
	)
	(segment
		(start 392.431016 -236.162342)
		(end 392.431016 -236.162596)
		(width 0.0762)
		(layer "F.Cu")
		(net "M_G_CPU0_SA_DQ<17>")
	)
	(segment
		(start 394.423138 -235.97997)
		(end 394.904976 -235.97997)
		(width 0.0762)
		(layer "F.Cu")
		(net "M_G_CPU0_SA_DQ<17>")
	)
	(segment
		(start 414.846516 -217.73515)
		(end 416.468052 -217.73515)
		(width 0.101346)
		(layer "F.Cu")
		(net "M_G_CPU0_SA_DQ<17>")
	)
	(segment
		(start 405.327358 -222.689674)
		(end 409.85694 -218.160092)
		(width 0.10668)
		(layer "F.Cu")
		(net "M_G_CPU0_SA_DQ<17>")
	)
	(segment
		(start 395.715236 -236.22127)
		(end 396.621 -236.22127)
		(width 0.10668)
		(layer "F.Cu")
		(net "M_G_CPU0_SA_DQ<17>")
	)
	(segment
		(start 411.317694 -218.160092)
		(end 413.82061 -218.160092)
		(width 0.101346)
		(layer "F.Cu")
		(net "M_G_CPU0_SA_DQ<17>")
	)
	(arc
		(start 392.804904 -236.162596)
		(mid 393.08786 -236.086419)
		(end 393.370816 -236.162596)
		(width 0.0762)
		(layer "F.Cu")
		(net "M_G_CPU0_SA_DQ<17>")
	)
	(arc
		(start 392.431016 -236.162596)
		(mid 392.61796 -236.212851)
		(end 392.804904 -236.162596)
		(width 0.0762)
		(layer "F.Cu")
		(net "M_G_CPU0_SA_DQ<17>")
	)
	(arc
		(start 392.146536 -236.085888)
		(mid 392.293857 -236.105207)
		(end 392.431016 -236.162342)
		(width 0.0762)
		(layer "F.Cu")
		(net "M_G_CPU0_SA_DQ<17>")
	)
	(arc
		(start 393.370816 -236.162596)
		(mid 393.553067 -236.212946)
		(end 393.736576 -236.167422)
		(width 0.0762)
		(layer "F.Cu")
		(net "M_G_CPU0_SA_DQ<17>")
	)
	(arc
		(start 391.677906 -235.840016)
		(mid 391.881922 -236.02071)
		(end 392.146536 -236.085888)
		(width 0.0762)
		(layer "F.Cu")
		(net "M_G_CPU0_SA_DQ<17>")
	)
	(arc
		(start 393.744958 -236.162596)
		(mid 394.071968 -236.026425)
		(end 394.423138 -235.97997)
		(width 0.0762)
		(layer "F.Cu")
		(net "M_G_CPU0_SA_DQ<17>")
	)
	(segment
		(start 395.727936 -235.54055)
		(end 396.338552 -235.54055)
		(width 0.10668)
		(layer "F.Cu")
		(net "M_G_CPU0_SA_DQ<16>")
	)
	(segment
		(start 414.960562 -216.46007)
		(end 415.385504 -216.035128)
		(width 0.101346)
		(layer "F.Cu")
		(net "M_G_CPU0_SA_DQ<16>")
	)
	(segment
		(start 404.646638 -222.407226)
		(end 407.05151 -220.002354)
		(width 0.10668)
		(layer "F.Cu")
		(net "M_G_CPU0_SA_DQ<16>")
	)
	(segment
		(start 404.646638 -227.232464)
		(end 404.646638 -222.407226)
		(width 0.10668)
		(layer "F.Cu")
		(net "M_G_CPU0_SA_DQ<16>")
	)
	(segment
		(start 407.05151 -219.15247)
		(end 409.74391 -216.46007)
		(width 0.10668)
		(layer "F.Cu")
		(net "M_G_CPU0_SA_DQ<16>")
	)
	(segment
		(start 415.385504 -216.035128)
		(end 416.468052 -216.035128)
		(width 0.101346)
		(layer "F.Cu")
		(net "M_G_CPU0_SA_DQ<16>")
	)
	(segment
		(start 394.04798 -235.40847)
		(end 395.211808 -235.40847)
		(width 0.0762)
		(layer "F.Cu")
		(net "M_G_CPU0_SA_DQ<16>")
	)
	(segment
		(start 395.343888 -235.54055)
		(end 395.727936 -235.54055)
		(width 0.0762)
		(layer "F.Cu")
		(net "M_G_CPU0_SA_DQ<16>")
	)
	(segment
		(start 409.74391 -216.46007)
		(end 411.317694 -216.46007)
		(width 0.10668)
		(layer "F.Cu")
		(net "M_G_CPU0_SA_DQ<16>")
	)
	(segment
		(start 411.317694 -216.46007)
		(end 414.960562 -216.46007)
		(width 0.101346)
		(layer "F.Cu")
		(net "M_G_CPU0_SA_DQ<16>")
	)
	(segment
		(start 396.338552 -235.54055)
		(end 404.646638 -227.232464)
		(width 0.10668)
		(layer "F.Cu")
		(net "M_G_CPU0_SA_DQ<16>")
	)
	(segment
		(start 395.211808 -235.40847)
		(end 395.343888 -235.54055)
		(width 0.0762)
		(layer "F.Cu")
		(net "M_G_CPU0_SA_DQ<16>")
	)
	(segment
		(start 407.05151 -220.002354)
		(end 407.05151 -219.15247)
		(width 0.10668)
		(layer "F.Cu")
		(net "M_G_CPU0_SA_DQ<16>")
	)
	(arc
		(start 393.84097 -235.35259)
		(mid 393.940777 -235.394219)
		(end 394.04798 -235.40847)
		(width 0.0762)
		(layer "F.Cu")
		(net "M_G_CPU0_SA_DQ<16>")
	)
	(arc
		(start 393.605512 -235.278168)
		(mid 393.727368 -235.302324)
		(end 393.84097 -235.35259)
		(width 0.0762)
		(layer "F.Cu")
		(net "M_G_CPU0_SA_DQ<16>")
	)
	(arc
		(start 393.08786 -235.03001)
		(mid 393.323988 -235.201445)
		(end 393.605512 -235.278168)
		(width 0.0762)
		(layer "F.Cu")
		(net "M_G_CPU0_SA_DQ<16>")
	)
	(segment
		(start 392.14806 -235.03001)
		(end 392.14806 -235.029756)
		(width 0.0762)
		(layer "F.Cu")
		(net "M_G_CPU0_SA_DQ<15>")
	)
	(segment
		(start 394.027914 -234.656884)
		(end 394.94587 -234.656884)
		(width 0.0762)
		(layer "F.Cu")
		(net "M_G_CPU0_SA_DQ<15>")
	)
	(segment
		(start 405.895048 -219.383102)
		(end 406.060148 -219.383102)
		(width 0.10668)
		(layer "F.Cu")
		(net "M_G_CPU0_SA_DQ<15>")
	)
	(segment
		(start 404.892764 -221.114874)
		(end 405.009858 -221.231968)
		(width 0.10668)
		(layer "F.Cu")
		(net "M_G_CPU0_SA_DQ<15>")
	)
	(segment
		(start 406.59431 -218.959684)
		(end 410.180282 -215.373712)
		(width 0.10668)
		(layer "F.Cu")
		(net "M_G_CPU0_SA_DQ<15>")
	)
	(segment
		(start 405.174958 -221.231968)
		(end 406.59431 -219.812616)
		(width 0.10668)
		(layer "F.Cu")
		(net "M_G_CPU0_SA_DQ<15>")
	)
	(segment
		(start 404.892764 -220.949774)
		(end 404.892764 -221.114874)
		(width 0.10668)
		(layer "F.Cu")
		(net "M_G_CPU0_SA_DQ<15>")
	)
	(segment
		(start 406.060148 -219.383102)
		(end 406.177242 -219.500196)
		(width 0.10668)
		(layer "F.Cu")
		(net "M_G_CPU0_SA_DQ<15>")
	)
	(segment
		(start 410.437838 -215.680798)
		(end 410.554678 -215.797638)
		(width 0.10668)
		(layer "F.Cu")
		(net "M_G_CPU0_SA_DQ<15>")
	)
	(segment
		(start 396.143988 -235.08335)
		(end 404.189438 -227.0379)
		(width 0.10668)
		(layer "F.Cu")
		(net "M_G_CPU0_SA_DQ<15>")
	)
	(segment
		(start 392.326622 -234.702604)
		(end 392.327638 -234.703112)
		(width 0.0762)
		(layer "F.Cu")
		(net "M_G_CPU0_SA_DQ<15>")
	)
	(segment
		(start 406.59431 -219.812616)
		(end 406.59431 -218.959684)
		(width 0.10668)
		(layer "F.Cu")
		(net "M_G_CPU0_SA_DQ<15>")
	)
	(segment
		(start 406.177242 -219.500196)
		(end 406.177242 -219.665296)
		(width 0.10668)
		(layer "F.Cu")
		(net "M_G_CPU0_SA_DQ<15>")
	)
	(segment
		(start 394.94587 -234.656884)
		(end 395.372336 -235.08335)
		(width 0.0762)
		(layer "F.Cu")
		(net "M_G_CPU0_SA_DQ<15>")
	)
	(segment
		(start 392.900916 -234.70743)
		(end 392.909298 -234.702604)
		(width 0.0762)
		(layer "F.Cu")
		(net "M_G_CPU0_SA_DQ<15>")
	)
	(segment
		(start 404.328376 -220.949774)
		(end 405.895048 -219.383102)
		(width 0.10668)
		(layer "F.Cu")
		(net "M_G_CPU0_SA_DQ<15>")
	)
	(segment
		(start 410.180282 -215.373712)
		(end 410.331158 -215.373712)
		(width 0.10668)
		(layer "F.Cu")
		(net "M_G_CPU0_SA_DQ<15>")
	)
	(segment
		(start 410.331158 -215.373712)
		(end 410.437838 -215.480392)
		(width 0.10668)
		(layer "F.Cu")
		(net "M_G_CPU0_SA_DQ<15>")
	)
	(segment
		(start 410.437838 -215.480392)
		(end 410.437838 -215.680798)
		(width 0.10668)
		(layer "F.Cu")
		(net "M_G_CPU0_SA_DQ<15>")
	)
	(segment
		(start 395.702536 -235.08335)
		(end 396.143988 -235.08335)
		(width 0.10668)
		(layer "F.Cu")
		(net "M_G_CPU0_SA_DQ<15>")
	)
	(segment
		(start 392.327638 -234.703112)
		(end 392.335004 -234.70743)
		(width 0.0762)
		(layer "F.Cu")
		(net "M_G_CPU0_SA_DQ<15>")
	)
	(segment
		(start 392.14806 -235.029756)
		(end 392.042904 -234.848908)
		(width 0.0762)
		(layer "F.Cu")
		(net "M_G_CPU0_SA_DQ<15>")
	)
	(segment
		(start 404.189438 -222.217488)
		(end 404.727664 -221.679262)
		(width 0.10668)
		(layer "F.Cu")
		(net "M_G_CPU0_SA_DQ<15>")
	)
	(segment
		(start 410.720032 -215.797638)
		(end 410.855414 -215.662256)
		(width 0.10668)
		(layer "F.Cu")
		(net "M_G_CPU0_SA_DQ<15>")
	)
	(segment
		(start 406.177242 -219.665296)
		(end 404.892764 -220.949774)
		(width 0.10668)
		(layer "F.Cu")
		(net "M_G_CPU0_SA_DQ<15>")
	)
	(segment
		(start 404.727664 -221.514162)
		(end 404.328376 -221.114874)
		(width 0.10668)
		(layer "F.Cu")
		(net "M_G_CPU0_SA_DQ<15>")
	)
	(segment
		(start 410.554678 -215.797638)
		(end 410.720032 -215.797638)
		(width 0.10668)
		(layer "F.Cu")
		(net "M_G_CPU0_SA_DQ<15>")
	)
	(segment
		(start 404.727664 -221.679262)
		(end 404.727664 -221.514162)
		(width 0.10668)
		(layer "F.Cu")
		(net "M_G_CPU0_SA_DQ<15>")
	)
	(segment
		(start 410.855414 -215.283288)
		(end 410.953712 -215.18499)
		(width 0.10668)
		(layer "F.Cu")
		(net "M_G_CPU0_SA_DQ<15>")
	)
	(segment
		(start 395.372336 -235.08335)
		(end 395.702536 -235.08335)
		(width 0.0762)
		(layer "F.Cu")
		(net "M_G_CPU0_SA_DQ<15>")
	)
	(segment
		(start 410.855414 -215.662256)
		(end 410.855414 -215.283288)
		(width 0.10668)
		(layer "F.Cu")
		(net "M_G_CPU0_SA_DQ<15>")
	)
	(segment
		(start 404.189438 -227.0379)
		(end 404.189438 -222.217488)
		(width 0.10668)
		(layer "F.Cu")
		(net "M_G_CPU0_SA_DQ<15>")
	)
	(segment
		(start 405.009858 -221.231968)
		(end 405.174958 -221.231968)
		(width 0.10668)
		(layer "F.Cu")
		(net "M_G_CPU0_SA_DQ<15>")
	)
	(segment
		(start 404.328376 -221.114874)
		(end 404.328376 -220.949774)
		(width 0.10668)
		(layer "F.Cu")
		(net "M_G_CPU0_SA_DQ<15>")
	)
	(segment
		(start 410.953712 -215.18499)
		(end 412.367984 -215.18499)
		(width 0.10668)
		(layer "F.Cu")
		(net "M_G_CPU0_SA_DQ<15>")
	)
	(arc
		(start 392.909298 -234.702604)
		(mid 393.092806 -234.65711)
		(end 393.275058 -234.70743)
		(width 0.0762)
		(layer "F.Cu")
		(net "M_G_CPU0_SA_DQ<15>")
	)
	(arc
		(start 393.275058 -234.70743)
		(mid 393.558014 -234.783607)
		(end 393.84097 -234.70743)
		(width 0.0762)
		(layer "F.Cu")
		(net "M_G_CPU0_SA_DQ<15>")
	)
	(arc
		(start 393.84097 -234.70743)
		(mid 393.931103 -234.66981)
		(end 394.027914 -234.656884)
		(width 0.0762)
		(layer "F.Cu")
		(net "M_G_CPU0_SA_DQ<15>")
	)
	(arc
		(start 392.042904 -234.848908)
		(mid 392.051841 -234.729884)
		(end 392.146536 -234.657138)
		(width 0.0762)
		(layer "F.Cu")
		(net "M_G_CPU0_SA_DQ<15>")
	)
	(arc
		(start 392.146536 -234.657138)
		(mid 392.23946 -234.668461)
		(end 392.326622 -234.702604)
		(width 0.0762)
		(layer "F.Cu")
		(net "M_G_CPU0_SA_DQ<15>")
	)
	(arc
		(start 392.335004 -234.70743)
		(mid 392.61796 -234.783607)
		(end 392.900916 -234.70743)
		(width 0.0762)
		(layer "F.Cu")
		(net "M_G_CPU0_SA_DQ<15>")
	)
	(segment
		(start 408.804872 -215.742012)
		(end 408.804872 -215.576912)
		(width 0.10668)
		(layer "F.Cu")
		(net "M_G_CPU0_SA_DQ<14>")
	)
	(segment
		(start 406.986486 -216.745566)
		(end 407.151586 -216.745566)
		(width 0.10668)
		(layer "F.Cu")
		(net "M_G_CPU0_SA_DQ<14>")
	)
	(segment
		(start 406.430226 -218.116658)
		(end 406.54732 -217.999564)
		(width 0.10668)
		(layer "F.Cu")
		(net "M_G_CPU0_SA_DQ<14>")
	)
	(segment
		(start 409.126944 -214.605108)
		(end 409.244038 -214.488014)
		(width 0.10668)
		(layer "F.Cu")
		(net "M_G_CPU0_SA_DQ<14>")
	)
	(segment
		(start 408.804872 -215.576912)
		(end 408.562556 -215.334596)
		(width 0.10668)
		(layer "F.Cu")
		(net "M_G_CPU0_SA_DQ<14>")
	)
	(segment
		(start 407.43378 -216.463372)
		(end 407.43378 -216.298272)
		(width 0.10668)
		(layer "F.Cu")
		(net "M_G_CPU0_SA_DQ<14>")
	)
	(segment
		(start 395.3002 -234.20451)
		(end 395.687296 -234.20451)
		(width 0.0762)
		(layer "F.Cu")
		(net "M_G_CPU0_SA_DQ<14>")
	)
	(segment
		(start 407.393902 -216.987882)
		(end 407.559002 -216.987882)
		(width 0.10668)
		(layer "F.Cu")
		(net "M_G_CPU0_SA_DQ<14>")
	)
	(segment
		(start 408.115262 -215.61679)
		(end 408.280362 -215.61679)
		(width 0.10668)
		(layer "F.Cu")
		(net "M_G_CPU0_SA_DQ<14>")
	)
	(segment
		(start 406.02281 -217.874342)
		(end 406.265126 -218.116658)
		(width 0.10668)
		(layer "F.Cu")
		(net "M_G_CPU0_SA_DQ<14>")
	)
	(segment
		(start 393.736576 -233.892598)
		(end 393.744958 -233.897424)
		(width 0.0762)
		(layer "F.Cu")
		(net "M_G_CPU0_SA_DQ<14>")
	)
	(segment
		(start 409.244038 -214.488014)
		(end 409.409138 -214.488014)
		(width 0.10668)
		(layer "F.Cu")
		(net "M_G_CPU0_SA_DQ<14>")
	)
	(segment
		(start 407.998168 -215.733884)
		(end 408.115262 -215.61679)
		(width 0.10668)
		(layer "F.Cu")
		(net "M_G_CPU0_SA_DQ<14>")
	)
	(segment
		(start 408.67965 -215.052402)
		(end 408.84475 -215.052402)
		(width 0.10668)
		(layer "F.Cu")
		(net "M_G_CPU0_SA_DQ<14>")
	)
	(segment
		(start 406.265126 -218.116658)
		(end 406.430226 -218.116658)
		(width 0.10668)
		(layer "F.Cu")
		(net "M_G_CPU0_SA_DQ<14>")
	)
	(segment
		(start 409.409138 -214.488014)
		(end 409.651454 -214.73033)
		(width 0.10668)
		(layer "F.Cu")
		(net "M_G_CPU0_SA_DQ<14>")
	)
	(segment
		(start 406.869392 -217.02776)
		(end 406.869392 -216.86266)
		(width 0.10668)
		(layer "F.Cu")
		(net "M_G_CPU0_SA_DQ<14>")
	)
	(segment
		(start 409.126944 -214.770208)
		(end 409.126944 -214.605108)
		(width 0.10668)
		(layer "F.Cu")
		(net "M_G_CPU0_SA_DQ<14>")
	)
	(segment
		(start 395.687296 -234.20451)
		(end 396.05966 -234.20451)
		(width 0.10668)
		(layer "F.Cu")
		(net "M_G_CPU0_SA_DQ<14>")
	)
	(segment
		(start 409.691332 -214.04072)
		(end 410.247084 -213.484968)
		(width 0.10668)
		(layer "F.Cu")
		(net "M_G_CPU0_SA_DQ<14>")
	)
	(segment
		(start 405.458422 -218.43873)
		(end 405.700738 -218.681046)
		(width 0.10668)
		(layer "F.Cu")
		(net "M_G_CPU0_SA_DQ<14>")
	)
	(segment
		(start 410.247084 -213.484968)
		(end 412.367984 -213.484968)
		(width 0.10668)
		(layer "F.Cu")
		(net "M_G_CPU0_SA_DQ<14>")
	)
	(segment
		(start 406.54732 -217.834464)
		(end 406.305004 -217.592148)
		(width 0.10668)
		(layer "F.Cu")
		(net "M_G_CPU0_SA_DQ<14>")
	)
	(segment
		(start 408.12339 -216.423494)
		(end 408.240484 -216.3064)
		(width 0.10668)
		(layer "F.Cu")
		(net "M_G_CPU0_SA_DQ<14>")
	)
	(segment
		(start 408.562556 -215.334596)
		(end 408.562556 -215.169496)
		(width 0.10668)
		(layer "F.Cu")
		(net "M_G_CPU0_SA_DQ<14>")
	)
	(segment
		(start 406.305004 -217.427048)
		(end 406.422098 -217.309954)
		(width 0.10668)
		(layer "F.Cu")
		(net "M_G_CPU0_SA_DQ<14>")
	)
	(segment
		(start 409.933648 -214.613236)
		(end 409.933648 -214.448136)
		(width 0.10668)
		(layer "F.Cu")
		(net "M_G_CPU0_SA_DQ<14>")
	)
	(segment
		(start 405.982932 -218.563952)
		(end 405.982932 -218.398852)
		(width 0.10668)
		(layer "F.Cu")
		(net "M_G_CPU0_SA_DQ<14>")
	)
	(segment
		(start 407.111708 -217.435176)
		(end 407.111708 -217.270076)
		(width 0.10668)
		(layer "F.Cu")
		(net "M_G_CPU0_SA_DQ<14>")
	)
	(segment
		(start 409.36926 -215.012524)
		(end 409.126944 -214.770208)
		(width 0.10668)
		(layer "F.Cu")
		(net "M_G_CPU0_SA_DQ<14>")
	)
	(segment
		(start 406.829514 -217.55227)
		(end 406.994614 -217.55227)
		(width 0.10668)
		(layer "F.Cu")
		(net "M_G_CPU0_SA_DQ<14>")
	)
	(segment
		(start 405.85771 -217.874342)
		(end 406.02281 -217.874342)
		(width 0.10668)
		(layer "F.Cu")
		(net "M_G_CPU0_SA_DQ<14>")
	)
	(segment
		(start 405.740616 -218.156536)
		(end 405.740616 -217.991436)
		(width 0.10668)
		(layer "F.Cu")
		(net "M_G_CPU0_SA_DQ<14>")
	)
	(segment
		(start 394.564362 -234.11815)
		(end 395.21384 -234.11815)
		(width 0.0762)
		(layer "F.Cu")
		(net "M_G_CPU0_SA_DQ<14>")
	)
	(segment
		(start 408.240484 -216.3064)
		(end 408.240484 -216.1413)
		(width 0.10668)
		(layer "F.Cu")
		(net "M_G_CPU0_SA_DQ<14>")
	)
	(segment
		(start 403.456394 -220.275658)
		(end 405.293322 -218.43873)
		(width 0.10668)
		(layer "F.Cu")
		(net "M_G_CPU0_SA_DQ<14>")
	)
	(segment
		(start 408.280362 -215.61679)
		(end 408.522678 -215.859106)
		(width 0.10668)
		(layer "F.Cu")
		(net "M_G_CPU0_SA_DQ<14>")
	)
	(segment
		(start 396.05966 -234.20451)
		(end 403.456394 -226.807776)
		(width 0.10668)
		(layer "F.Cu")
		(net "M_G_CPU0_SA_DQ<14>")
	)
	(segment
		(start 405.865838 -218.681046)
		(end 405.982932 -218.563952)
		(width 0.10668)
		(layer "F.Cu")
		(net "M_G_CPU0_SA_DQ<14>")
	)
	(segment
		(start 407.676096 -216.870788)
		(end 407.676096 -216.705688)
		(width 0.10668)
		(layer "F.Cu")
		(net "M_G_CPU0_SA_DQ<14>")
	)
	(segment
		(start 407.715974 -216.181178)
		(end 407.95829 -216.423494)
		(width 0.10668)
		(layer "F.Cu")
		(net "M_G_CPU0_SA_DQ<14>")
	)
	(segment
		(start 408.240484 -216.1413)
		(end 407.998168 -215.898984)
		(width 0.10668)
		(layer "F.Cu")
		(net "M_G_CPU0_SA_DQ<14>")
	)
	(segment
		(start 407.95829 -216.423494)
		(end 408.12339 -216.423494)
		(width 0.10668)
		(layer "F.Cu")
		(net "M_G_CPU0_SA_DQ<14>")
	)
	(segment
		(start 408.687778 -215.859106)
		(end 408.804872 -215.742012)
		(width 0.10668)
		(layer "F.Cu")
		(net "M_G_CPU0_SA_DQ<14>")
	)
	(segment
		(start 406.54732 -217.999564)
		(end 406.54732 -217.834464)
		(width 0.10668)
		(layer "F.Cu")
		(net "M_G_CPU0_SA_DQ<14>")
	)
	(segment
		(start 406.305004 -217.592148)
		(end 406.305004 -217.427048)
		(width 0.10668)
		(layer "F.Cu")
		(net "M_G_CPU0_SA_DQ<14>")
	)
	(segment
		(start 409.691332 -214.20582)
		(end 409.691332 -214.04072)
		(width 0.10668)
		(layer "F.Cu")
		(net "M_G_CPU0_SA_DQ<14>")
	)
	(segment
		(start 408.522678 -215.859106)
		(end 408.687778 -215.859106)
		(width 0.10668)
		(layer "F.Cu")
		(net "M_G_CPU0_SA_DQ<14>")
	)
	(segment
		(start 406.587198 -217.309954)
		(end 406.829514 -217.55227)
		(width 0.10668)
		(layer "F.Cu")
		(net "M_G_CPU0_SA_DQ<14>")
	)
	(segment
		(start 405.740616 -217.991436)
		(end 405.85771 -217.874342)
		(width 0.10668)
		(layer "F.Cu")
		(net "M_G_CPU0_SA_DQ<14>")
	)
	(segment
		(start 407.151586 -216.745566)
		(end 407.393902 -216.987882)
		(width 0.10668)
		(layer "F.Cu")
		(net "M_G_CPU0_SA_DQ<14>")
	)
	(segment
		(start 408.562556 -215.169496)
		(end 408.67965 -215.052402)
		(width 0.10668)
		(layer "F.Cu")
		(net "M_G_CPU0_SA_DQ<14>")
	)
	(segment
		(start 409.816554 -214.73033)
		(end 409.933648 -214.613236)
		(width 0.10668)
		(layer "F.Cu")
		(net "M_G_CPU0_SA_DQ<14>")
	)
	(segment
		(start 409.651454 -214.73033)
		(end 409.816554 -214.73033)
		(width 0.10668)
		(layer "F.Cu")
		(net "M_G_CPU0_SA_DQ<14>")
	)
	(segment
		(start 406.869392 -216.86266)
		(end 406.986486 -216.745566)
		(width 0.10668)
		(layer "F.Cu")
		(net "M_G_CPU0_SA_DQ<14>")
	)
	(segment
		(start 405.293322 -218.43873)
		(end 405.458422 -218.43873)
		(width 0.10668)
		(layer "F.Cu")
		(net "M_G_CPU0_SA_DQ<14>")
	)
	(segment
		(start 407.998168 -215.898984)
		(end 407.998168 -215.733884)
		(width 0.10668)
		(layer "F.Cu")
		(net "M_G_CPU0_SA_DQ<14>")
	)
	(segment
		(start 407.43378 -216.298272)
		(end 407.550874 -216.181178)
		(width 0.10668)
		(layer "F.Cu")
		(net "M_G_CPU0_SA_DQ<14>")
	)
	(segment
		(start 395.21384 -234.11815)
		(end 395.3002 -234.20451)
		(width 0.0762)
		(layer "F.Cu")
		(net "M_G_CPU0_SA_DQ<14>")
	)
	(segment
		(start 409.252166 -215.294718)
		(end 409.36926 -215.177624)
		(width 0.10668)
		(layer "F.Cu")
		(net "M_G_CPU0_SA_DQ<14>")
	)
	(segment
		(start 406.994614 -217.55227)
		(end 407.111708 -217.435176)
		(width 0.10668)
		(layer "F.Cu")
		(net "M_G_CPU0_SA_DQ<14>")
	)
	(segment
		(start 407.559002 -216.987882)
		(end 407.676096 -216.870788)
		(width 0.10668)
		(layer "F.Cu")
		(net "M_G_CPU0_SA_DQ<14>")
	)
	(segment
		(start 403.456394 -226.807776)
		(end 403.456394 -220.275658)
		(width 0.10668)
		(layer "F.Cu")
		(net "M_G_CPU0_SA_DQ<14>")
	)
	(segment
		(start 407.676096 -216.705688)
		(end 407.43378 -216.463372)
		(width 0.10668)
		(layer "F.Cu")
		(net "M_G_CPU0_SA_DQ<14>")
	)
	(segment
		(start 407.111708 -217.270076)
		(end 406.869392 -217.02776)
		(width 0.10668)
		(layer "F.Cu")
		(net "M_G_CPU0_SA_DQ<14>")
	)
	(segment
		(start 393.558014 -234.220004)
		(end 393.46505 -234.059984)
		(width 0.0762)
		(layer "F.Cu")
		(net "M_G_CPU0_SA_DQ<14>")
	)
	(segment
		(start 405.982932 -218.398852)
		(end 405.740616 -218.156536)
		(width 0.10668)
		(layer "F.Cu")
		(net "M_G_CPU0_SA_DQ<14>")
	)
	(segment
		(start 408.84475 -215.052402)
		(end 409.087066 -215.294718)
		(width 0.10668)
		(layer "F.Cu")
		(net "M_G_CPU0_SA_DQ<14>")
	)
	(segment
		(start 405.700738 -218.681046)
		(end 405.865838 -218.681046)
		(width 0.10668)
		(layer "F.Cu")
		(net "M_G_CPU0_SA_DQ<14>")
	)
	(segment
		(start 406.422098 -217.309954)
		(end 406.587198 -217.309954)
		(width 0.10668)
		(layer "F.Cu")
		(net "M_G_CPU0_SA_DQ<14>")
	)
	(segment
		(start 407.550874 -216.181178)
		(end 407.715974 -216.181178)
		(width 0.10668)
		(layer "F.Cu")
		(net "M_G_CPU0_SA_DQ<14>")
	)
	(segment
		(start 409.087066 -215.294718)
		(end 409.252166 -215.294718)
		(width 0.10668)
		(layer "F.Cu")
		(net "M_G_CPU0_SA_DQ<14>")
	)
	(segment
		(start 409.36926 -215.177624)
		(end 409.36926 -215.012524)
		(width 0.10668)
		(layer "F.Cu")
		(net "M_G_CPU0_SA_DQ<14>")
	)
	(segment
		(start 409.933648 -214.448136)
		(end 409.691332 -214.20582)
		(width 0.10668)
		(layer "F.Cu")
		(net "M_G_CPU0_SA_DQ<14>")
	)
	(arc
		(start 393.46505 -234.059984)
		(mid 393.46521 -233.913423)
		(end 393.596876 -233.849164)
		(width 0.0762)
		(layer "F.Cu")
		(net "M_G_CPU0_SA_DQ<14>")
	)
	(arc
		(start 393.744958 -233.897424)
		(mid 394.140063 -234.061963)
		(end 394.564362 -234.11815)
		(width 0.0762)
		(layer "F.Cu")
		(net "M_G_CPU0_SA_DQ<14>")
	)
	(arc
		(start 393.596876 -233.849164)
		(mid 393.668884 -233.863946)
		(end 393.736576 -233.892598)
		(width 0.0762)
		(layer "F.Cu")
		(net "M_G_CPU0_SA_DQ<14>")
	)
	(segment
		(start 414.223454 -214.335106)
		(end 416.468052 -214.335106)
		(width 0.101346)
		(layer "F.Cu")
		(net "M_G_CPU0_SA_DQ<13>")
	)
	(segment
		(start 393.736576 -234.54741)
		(end 393.744958 -234.542584)
		(width 0.0762)
		(layer "F.Cu")
		(net "M_G_CPU0_SA_DQ<13>")
	)
	(segment
		(start 404.322534 -220.308932)
		(end 404.487634 -220.308932)
		(width 0.10668)
		(layer "F.Cu")
		(net "M_G_CPU0_SA_DQ<13>")
	)
	(segment
		(start 404.604728 -220.191838)
		(end 404.604728 -220.026738)
		(width 0.10668)
		(layer "F.Cu")
		(net "M_G_CPU0_SA_DQ<13>")
	)
	(segment
		(start 404.04034 -220.756226)
		(end 404.04034 -220.591126)
		(width 0.10668)
		(layer "F.Cu")
		(net "M_G_CPU0_SA_DQ<13>")
	)
	(segment
		(start 404.487634 -220.308932)
		(end 404.604728 -220.191838)
		(width 0.10668)
		(layer "F.Cu")
		(net "M_G_CPU0_SA_DQ<13>")
	)
	(segment
		(start 404.47849 -219.9005)
		(end 404.47849 -219.7354)
		(width 0.10668)
		(layer "F.Cu")
		(net "M_G_CPU0_SA_DQ<13>")
	)
	(segment
		(start 404.196296 -220.182694)
		(end 404.322534 -220.308932)
		(width 0.10668)
		(layer "F.Cu")
		(net "M_G_CPU0_SA_DQ<13>")
	)
	(segment
		(start 405.052022 -219.744544)
		(end 405.169116 -219.62745)
		(width 0.10668)
		(layer "F.Cu")
		(net "M_G_CPU0_SA_DQ<13>")
	)
	(segment
		(start 403.914102 -220.299788)
		(end 404.031196 -220.182694)
		(width 0.10668)
		(layer "F.Cu")
		(net "M_G_CPU0_SA_DQ<13>")
	)
	(segment
		(start 413.798512 -214.760048)
		(end 414.223454 -214.335106)
		(width 0.101346)
		(layer "F.Cu")
		(net "M_G_CPU0_SA_DQ<13>")
	)
	(segment
		(start 404.595584 -219.618306)
		(end 404.760684 -219.618306)
		(width 0.10668)
		(layer "F.Cu")
		(net "M_G_CPU0_SA_DQ<13>")
	)
	(segment
		(start 392.431016 -234.54233)
		(end 392.431016 -234.542584)
		(width 0.0762)
		(layer "F.Cu")
		(net "M_G_CPU0_SA_DQ<13>")
	)
	(segment
		(start 405.169116 -219.62745)
		(end 405.169116 -219.46235)
		(width 0.10668)
		(layer "F.Cu")
		(net "M_G_CPU0_SA_DQ<13>")
	)
	(segment
		(start 404.04034 -220.591126)
		(end 403.914102 -220.464888)
		(width 0.10668)
		(layer "F.Cu")
		(net "M_G_CPU0_SA_DQ<13>")
	)
	(segment
		(start 395.698218 -234.665012)
		(end 396.080742 -234.665012)
		(width 0.10668)
		(layer "F.Cu")
		(net "M_G_CPU0_SA_DQ<13>")
	)
	(segment
		(start 396.080742 -234.665012)
		(end 403.805898 -226.939856)
		(width 0.10668)
		(layer "F.Cu")
		(net "M_G_CPU0_SA_DQ<13>")
	)
	(segment
		(start 404.604728 -220.026738)
		(end 404.47849 -219.9005)
		(width 0.10668)
		(layer "F.Cu")
		(net "M_G_CPU0_SA_DQ<13>")
	)
	(segment
		(start 405.169116 -219.46235)
		(end 405.042878 -219.336112)
		(width 0.10668)
		(layer "F.Cu")
		(net "M_G_CPU0_SA_DQ<13>")
	)
	(segment
		(start 404.031196 -220.182694)
		(end 404.196296 -220.182694)
		(width 0.10668)
		(layer "F.Cu")
		(net "M_G_CPU0_SA_DQ<13>")
	)
	(segment
		(start 411.317694 -214.760048)
		(end 413.798512 -214.760048)
		(width 0.101346)
		(layer "F.Cu")
		(net "M_G_CPU0_SA_DQ<13>")
	)
	(segment
		(start 406.029668 -219.042742)
		(end 410.312362 -214.760048)
		(width 0.10668)
		(layer "F.Cu")
		(net "M_G_CPU0_SA_DQ<13>")
	)
	(segment
		(start 405.171148 -219.042742)
		(end 406.029668 -219.042742)
		(width 0.10668)
		(layer "F.Cu")
		(net "M_G_CPU0_SA_DQ<13>")
	)
	(segment
		(start 403.805898 -220.990668)
		(end 404.04034 -220.756226)
		(width 0.10668)
		(layer "F.Cu")
		(net "M_G_CPU0_SA_DQ<13>")
	)
	(segment
		(start 403.914102 -220.464888)
		(end 403.914102 -220.299788)
		(width 0.10668)
		(layer "F.Cu")
		(net "M_G_CPU0_SA_DQ<13>")
	)
	(segment
		(start 404.760684 -219.618306)
		(end 404.886922 -219.744544)
		(width 0.10668)
		(layer "F.Cu")
		(net "M_G_CPU0_SA_DQ<13>")
	)
	(segment
		(start 410.312362 -214.760048)
		(end 411.317694 -214.760048)
		(width 0.10668)
		(layer "F.Cu")
		(net "M_G_CPU0_SA_DQ<13>")
	)
	(segment
		(start 403.805898 -226.939856)
		(end 403.805898 -220.990668)
		(width 0.10668)
		(layer "F.Cu")
		(net "M_G_CPU0_SA_DQ<13>")
	)
	(segment
		(start 405.042878 -219.336112)
		(end 405.042878 -219.171012)
		(width 0.10668)
		(layer "F.Cu")
		(net "M_G_CPU0_SA_DQ<13>")
	)
	(segment
		(start 404.886922 -219.744544)
		(end 405.052022 -219.744544)
		(width 0.10668)
		(layer "F.Cu")
		(net "M_G_CPU0_SA_DQ<13>")
	)
	(segment
		(start 405.042878 -219.171012)
		(end 405.171148 -219.042742)
		(width 0.10668)
		(layer "F.Cu")
		(net "M_G_CPU0_SA_DQ<13>")
	)
	(segment
		(start 394.027914 -234.466384)
		(end 395.153896 -234.466384)
		(width 0.0762)
		(layer "F.Cu")
		(net "M_G_CPU0_SA_DQ<13>")
	)
	(segment
		(start 404.47849 -219.7354)
		(end 404.595584 -219.618306)
		(width 0.10668)
		(layer "F.Cu")
		(net "M_G_CPU0_SA_DQ<13>")
	)
	(segment
		(start 395.153896 -234.466384)
		(end 395.352524 -234.665012)
		(width 0.0762)
		(layer "F.Cu")
		(net "M_G_CPU0_SA_DQ<13>")
	)
	(segment
		(start 395.352524 -234.665012)
		(end 395.698218 -234.665012)
		(width 0.0762)
		(layer "F.Cu")
		(net "M_G_CPU0_SA_DQ<13>")
	)
	(arc
		(start 392.146536 -234.465876)
		(mid 392.293857 -234.485195)
		(end 392.431016 -234.54233)
		(width 0.0762)
		(layer "F.Cu")
		(net "M_G_CPU0_SA_DQ<13>")
	)
	(arc
		(start 393.370816 -234.542584)
		(mid 393.553067 -234.592934)
		(end 393.736576 -234.54741)
		(width 0.0762)
		(layer "F.Cu")
		(net "M_G_CPU0_SA_DQ<13>")
	)
	(arc
		(start 392.804904 -234.542584)
		(mid 393.08786 -234.466407)
		(end 393.370816 -234.542584)
		(width 0.0762)
		(layer "F.Cu")
		(net "M_G_CPU0_SA_DQ<13>")
	)
	(arc
		(start 391.677906 -234.220004)
		(mid 391.881922 -234.400698)
		(end 392.146536 -234.465876)
		(width 0.0762)
		(layer "F.Cu")
		(net "M_G_CPU0_SA_DQ<13>")
	)
	(arc
		(start 392.431016 -234.542584)
		(mid 392.61796 -234.592839)
		(end 392.804904 -234.542584)
		(width 0.0762)
		(layer "F.Cu")
		(net "M_G_CPU0_SA_DQ<13>")
	)
	(arc
		(start 393.744958 -234.542584)
		(mid 393.881394 -234.485759)
		(end 394.027914 -234.466384)
		(width 0.0762)
		(layer "F.Cu")
		(net "M_G_CPU0_SA_DQ<13>")
	)
	(segment
		(start 395.992096 -233.79049)
		(end 403.116034 -226.666552)
		(width 0.10668)
		(layer "F.Cu")
		(net "M_G_CPU0_SA_DQ<12>")
	)
	(segment
		(start 394.804138 -233.79049)
		(end 395.090396 -233.79049)
		(width 0.10668)
		(layer "F.Cu")
		(net "M_G_CPU0_SA_DQ<12>")
	)
	(segment
		(start 415.53257 -212.635084)
		(end 416.468052 -212.635084)
		(width 0.101346)
		(layer "F.Cu")
		(net "M_G_CPU0_SA_DQ<12>")
	)
	(segment
		(start 411.279594 -213.060026)
		(end 414.132522 -213.060026)
		(width 0.101346)
		(layer "F.Cu")
		(net "M_G_CPU0_SA_DQ<12>")
	)
	(segment
		(start 395.090396 -233.79049)
		(end 395.207236 -233.67365)
		(width 0.10668)
		(layer "F.Cu")
		(net "M_G_CPU0_SA_DQ<12>")
	)
	(segment
		(start 414.526222 -213.941152)
		(end 414.641538 -213.825836)
		(width 0.101346)
		(layer "F.Cu")
		(net "M_G_CPU0_SA_DQ<12>")
	)
	(segment
		(start 395.48943 -233.364532)
		(end 395.60627 -233.481372)
		(width 0.10668)
		(layer "F.Cu")
		(net "M_G_CPU0_SA_DQ<12>")
	)
	(segment
		(start 410.190442 -213.060026)
		(end 411.279594 -213.060026)
		(width 0.10668)
		(layer "F.Cu")
		(net "M_G_CPU0_SA_DQ<12>")
	)
	(segment
		(start 415.107628 -213.060026)
		(end 415.53257 -212.635084)
		(width 0.101346)
		(layer "F.Cu")
		(net "M_G_CPU0_SA_DQ<12>")
	)
	(segment
		(start 395.60627 -233.481372)
		(end 395.60627 -233.67365)
		(width 0.10668)
		(layer "F.Cu")
		(net "M_G_CPU0_SA_DQ<12>")
	)
	(segment
		(start 403.116034 -220.134434)
		(end 410.190442 -213.060026)
		(width 0.10668)
		(layer "F.Cu")
		(net "M_G_CPU0_SA_DQ<12>")
	)
	(segment
		(start 395.207236 -233.67365)
		(end 395.207236 -233.481372)
		(width 0.10668)
		(layer "F.Cu")
		(net "M_G_CPU0_SA_DQ<12>")
	)
	(segment
		(start 403.116034 -226.666552)
		(end 403.116034 -220.134434)
		(width 0.10668)
		(layer "F.Cu")
		(net "M_G_CPU0_SA_DQ<12>")
	)
	(segment
		(start 414.363154 -213.941152)
		(end 414.526222 -213.941152)
		(width 0.101346)
		(layer "F.Cu")
		(net "M_G_CPU0_SA_DQ<12>")
	)
	(segment
		(start 395.324076 -233.364532)
		(end 395.48943 -233.364532)
		(width 0.10668)
		(layer "F.Cu")
		(net "M_G_CPU0_SA_DQ<12>")
	)
	(segment
		(start 414.641538 -213.825836)
		(end 414.641538 -213.175342)
		(width 0.101346)
		(layer "F.Cu")
		(net "M_G_CPU0_SA_DQ<12>")
	)
	(segment
		(start 414.132522 -213.060026)
		(end 414.247838 -213.175342)
		(width 0.101346)
		(layer "F.Cu")
		(net "M_G_CPU0_SA_DQ<12>")
	)
	(segment
		(start 395.60627 -233.67365)
		(end 395.72311 -233.79049)
		(width 0.10668)
		(layer "F.Cu")
		(net "M_G_CPU0_SA_DQ<12>")
	)
	(segment
		(start 395.207236 -233.481372)
		(end 395.324076 -233.364532)
		(width 0.10668)
		(layer "F.Cu")
		(net "M_G_CPU0_SA_DQ<12>")
	)
	(segment
		(start 414.247838 -213.825836)
		(end 414.363154 -213.941152)
		(width 0.101346)
		(layer "F.Cu")
		(net "M_G_CPU0_SA_DQ<12>")
	)
	(segment
		(start 414.756854 -213.060026)
		(end 415.107628 -213.060026)
		(width 0.101346)
		(layer "F.Cu")
		(net "M_G_CPU0_SA_DQ<12>")
	)
	(segment
		(start 394.0556 -233.79049)
		(end 394.804138 -233.79049)
		(width 0.0762)
		(layer "F.Cu")
		(net "M_G_CPU0_SA_DQ<12>")
	)
	(segment
		(start 395.72311 -233.79049)
		(end 395.992096 -233.79049)
		(width 0.10668)
		(layer "F.Cu")
		(net "M_G_CPU0_SA_DQ<12>")
	)
	(segment
		(start 414.641538 -213.175342)
		(end 414.756854 -213.060026)
		(width 0.101346)
		(layer "F.Cu")
		(net "M_G_CPU0_SA_DQ<12>")
	)
	(segment
		(start 414.247838 -213.175342)
		(end 414.247838 -213.825836)
		(width 0.101346)
		(layer "F.Cu")
		(net "M_G_CPU0_SA_DQ<12>")
	)
	(arc
		(start 393.605512 -233.658156)
		(mid 393.727368 -233.682312)
		(end 393.84097 -233.732578)
		(width 0.0762)
		(layer "F.Cu")
		(net "M_G_CPU0_SA_DQ<12>")
	)
	(arc
		(start 393.84097 -233.732578)
		(mid 393.944448 -233.775754)
		(end 394.0556 -233.79049)
		(width 0.0762)
		(layer "F.Cu")
		(net "M_G_CPU0_SA_DQ<12>")
	)
	(arc
		(start 393.08786 -233.409998)
		(mid 393.323988 -233.581433)
		(end 393.605512 -233.658156)
		(width 0.0762)
		(layer "F.Cu")
		(net "M_G_CPU0_SA_DQ<12>")
	)
	(segment
		(start 395.432026 -231.41686)
		(end 395.640306 -231.41686)
		(width 0.10668)
		(layer "F.Cu")
		(net "M_G_CPU0_SA_DQ<11>")
	)
	(segment
		(start 401.180554 -218.8083)
		(end 404.13432 -215.854534)
		(width 0.10668)
		(layer "F.Cu")
		(net "M_G_CPU0_SA_DQ<11>")
	)
	(segment
		(start 404.314406 -214.575644)
		(end 404.4315 -214.45855)
		(width 0.10668)
		(layer "F.Cu")
		(net "M_G_CPU0_SA_DQ<11>")
	)
	(segment
		(start 404.5966 -214.45855)
		(end 404.980902 -214.842852)
		(width 0.10668)
		(layer "F.Cu")
		(net "M_G_CPU0_SA_DQ<11>")
	)
	(segment
		(start 405.71039 -214.278464)
		(end 405.827484 -214.16137)
		(width 0.10668)
		(layer "F.Cu")
		(net "M_G_CPU0_SA_DQ<11>")
	)
	(segment
		(start 404.878794 -214.176356)
		(end 404.878794 -214.011256)
		(width 0.10668)
		(layer "F.Cu")
		(net "M_G_CPU0_SA_DQ<11>")
	)
	(segment
		(start 394.027914 -231.41686)
		(end 395.432026 -231.41686)
		(width 0.0762)
		(layer "F.Cu")
		(net "M_G_CPU0_SA_DQ<11>")
	)
	(segment
		(start 392.327638 -231.463342)
		(end 392.335004 -231.46766)
		(width 0.0762)
		(layer "F.Cu")
		(net "M_G_CPU0_SA_DQ<11>")
	)
	(segment
		(start 404.13432 -215.854534)
		(end 404.13432 -215.689434)
		(width 0.10668)
		(layer "F.Cu")
		(net "M_G_CPU0_SA_DQ<11>")
	)
	(segment
		(start 409.64231 -209.23504)
		(end 412.367984 -209.23504)
		(width 0.10668)
		(layer "F.Cu")
		(net "M_G_CPU0_SA_DQ<11>")
	)
	(segment
		(start 405.827484 -214.16137)
		(end 405.827484 -213.99627)
		(width 0.10668)
		(layer "F.Cu")
		(net "M_G_CPU0_SA_DQ<11>")
	)
	(segment
		(start 405.160988 -213.894162)
		(end 405.54529 -214.278464)
		(width 0.10668)
		(layer "F.Cu")
		(net "M_G_CPU0_SA_DQ<11>")
	)
	(segment
		(start 405.146002 -214.842852)
		(end 405.263096 -214.725758)
		(width 0.10668)
		(layer "F.Cu")
		(net "M_G_CPU0_SA_DQ<11>")
	)
	(segment
		(start 392.900916 -231.46766)
		(end 392.909298 -231.462834)
		(width 0.0762)
		(layer "F.Cu")
		(net "M_G_CPU0_SA_DQ<11>")
	)
	(segment
		(start 403.750018 -215.140032)
		(end 403.867112 -215.022938)
		(width 0.10668)
		(layer "F.Cu")
		(net "M_G_CPU0_SA_DQ<11>")
	)
	(segment
		(start 405.263096 -214.560658)
		(end 404.878794 -214.176356)
		(width 0.10668)
		(layer "F.Cu")
		(net "M_G_CPU0_SA_DQ<11>")
	)
	(segment
		(start 403.750018 -215.305132)
		(end 403.750018 -215.140032)
		(width 0.10668)
		(layer "F.Cu")
		(net "M_G_CPU0_SA_DQ<11>")
	)
	(segment
		(start 404.995888 -213.894162)
		(end 405.160988 -213.894162)
		(width 0.10668)
		(layer "F.Cu")
		(net "M_G_CPU0_SA_DQ<11>")
	)
	(segment
		(start 395.640306 -231.41686)
		(end 401.180554 -225.876612)
		(width 0.10668)
		(layer "F.Cu")
		(net "M_G_CPU0_SA_DQ<11>")
	)
	(segment
		(start 401.180554 -225.876612)
		(end 401.180554 -218.8083)
		(width 0.10668)
		(layer "F.Cu")
		(net "M_G_CPU0_SA_DQ<11>")
	)
	(segment
		(start 404.878794 -214.011256)
		(end 404.995888 -213.894162)
		(width 0.10668)
		(layer "F.Cu")
		(net "M_G_CPU0_SA_DQ<11>")
	)
	(segment
		(start 404.698708 -215.290146)
		(end 404.698708 -215.125046)
		(width 0.10668)
		(layer "F.Cu")
		(net "M_G_CPU0_SA_DQ<11>")
	)
	(segment
		(start 404.416514 -215.40724)
		(end 404.581614 -215.40724)
		(width 0.10668)
		(layer "F.Cu")
		(net "M_G_CPU0_SA_DQ<11>")
	)
	(segment
		(start 404.032212 -215.022938)
		(end 404.416514 -215.40724)
		(width 0.10668)
		(layer "F.Cu")
		(net "M_G_CPU0_SA_DQ<11>")
	)
	(segment
		(start 404.980902 -214.842852)
		(end 405.146002 -214.842852)
		(width 0.10668)
		(layer "F.Cu")
		(net "M_G_CPU0_SA_DQ<11>")
	)
	(segment
		(start 405.443182 -213.611968)
		(end 405.443182 -213.434168)
		(width 0.10668)
		(layer "F.Cu")
		(net "M_G_CPU0_SA_DQ<11>")
	)
	(segment
		(start 392.14806 -231.789986)
		(end 392.042904 -231.609138)
		(width 0.0762)
		(layer "F.Cu")
		(net "M_G_CPU0_SA_DQ<11>")
	)
	(segment
		(start 404.698708 -215.125046)
		(end 404.314406 -214.740744)
		(width 0.10668)
		(layer "F.Cu")
		(net "M_G_CPU0_SA_DQ<11>")
	)
	(segment
		(start 405.827484 -213.99627)
		(end 405.443182 -213.611968)
		(width 0.10668)
		(layer "F.Cu")
		(net "M_G_CPU0_SA_DQ<11>")
	)
	(segment
		(start 404.13432 -215.689434)
		(end 403.750018 -215.305132)
		(width 0.10668)
		(layer "F.Cu")
		(net "M_G_CPU0_SA_DQ<11>")
	)
	(segment
		(start 404.581614 -215.40724)
		(end 404.698708 -215.290146)
		(width 0.10668)
		(layer "F.Cu")
		(net "M_G_CPU0_SA_DQ<11>")
	)
	(segment
		(start 405.54529 -214.278464)
		(end 405.71039 -214.278464)
		(width 0.10668)
		(layer "F.Cu")
		(net "M_G_CPU0_SA_DQ<11>")
	)
	(segment
		(start 404.4315 -214.45855)
		(end 404.5966 -214.45855)
		(width 0.10668)
		(layer "F.Cu")
		(net "M_G_CPU0_SA_DQ<11>")
	)
	(segment
		(start 405.263096 -214.725758)
		(end 405.263096 -214.560658)
		(width 0.10668)
		(layer "F.Cu")
		(net "M_G_CPU0_SA_DQ<11>")
	)
	(segment
		(start 405.443182 -213.434168)
		(end 409.64231 -209.23504)
		(width 0.10668)
		(layer "F.Cu")
		(net "M_G_CPU0_SA_DQ<11>")
	)
	(segment
		(start 404.314406 -214.740744)
		(end 404.314406 -214.575644)
		(width 0.10668)
		(layer "F.Cu")
		(net "M_G_CPU0_SA_DQ<11>")
	)
	(segment
		(start 392.326622 -231.462834)
		(end 392.327638 -231.463342)
		(width 0.0762)
		(layer "F.Cu")
		(net "M_G_CPU0_SA_DQ<11>")
	)
	(segment
		(start 403.867112 -215.022938)
		(end 404.032212 -215.022938)
		(width 0.10668)
		(layer "F.Cu")
		(net "M_G_CPU0_SA_DQ<11>")
	)
	(arc
		(start 392.042904 -231.609138)
		(mid 392.051841 -231.490114)
		(end 392.146536 -231.417368)
		(width 0.0762)
		(layer "F.Cu")
		(net "M_G_CPU0_SA_DQ<11>")
	)
	(arc
		(start 392.146536 -231.417368)
		(mid 392.23946 -231.428691)
		(end 392.326622 -231.462834)
		(width 0.0762)
		(layer "F.Cu")
		(net "M_G_CPU0_SA_DQ<11>")
	)
	(arc
		(start 393.275058 -231.46766)
		(mid 393.558014 -231.543837)
		(end 393.84097 -231.46766)
		(width 0.0762)
		(layer "F.Cu")
		(net "M_G_CPU0_SA_DQ<11>")
	)
	(arc
		(start 392.335004 -231.46766)
		(mid 392.61796 -231.543837)
		(end 392.900916 -231.46766)
		(width 0.0762)
		(layer "F.Cu")
		(net "M_G_CPU0_SA_DQ<11>")
	)
	(arc
		(start 392.909298 -231.462834)
		(mid 393.092806 -231.417309)
		(end 393.275058 -231.46766)
		(width 0.0762)
		(layer "F.Cu")
		(net "M_G_CPU0_SA_DQ<11>")
	)
	(arc
		(start 393.84097 -231.46766)
		(mid 393.931083 -231.429891)
		(end 394.027914 -231.41686)
		(width 0.0762)
		(layer "F.Cu")
		(net "M_G_CPU0_SA_DQ<11>")
	)
	(segment
		(start 401.047966 -217.031316)
		(end 401.047966 -216.866216)
		(width 0.10668)
		(layer "F.Cu")
		(net "M_G_CPU0_SA_DQ<10>")
	)
	(segment
		(start 402.94306 -215.93937)
		(end 403.060154 -215.822276)
		(width 0.10668)
		(layer "F.Cu")
		(net "M_G_CPU0_SA_DQ<10>")
	)
	(segment
		(start 401.249896 -217.632534)
		(end 401.36699 -217.51544)
		(width 0.10668)
		(layer "F.Cu")
		(net "M_G_CPU0_SA_DQ<10>")
	)
	(segment
		(start 401.931378 -216.785952)
		(end 401.612354 -216.466928)
		(width 0.10668)
		(layer "F.Cu")
		(net "M_G_CPU0_SA_DQ<10>")
	)
	(segment
		(start 393.736576 -230.652574)
		(end 393.744958 -230.6574)
		(width 0.0762)
		(layer "F.Cu")
		(net "M_G_CPU0_SA_DQ<10>")
	)
	(segment
		(start 401.894548 -216.184734)
		(end 402.213572 -216.503758)
		(width 0.10668)
		(layer "F.Cu")
		(net "M_G_CPU0_SA_DQ<10>")
	)
	(segment
		(start 401.649184 -217.068146)
		(end 401.814284 -217.068146)
		(width 0.10668)
		(layer "F.Cu")
		(net "M_G_CPU0_SA_DQ<10>")
	)
	(segment
		(start 402.176742 -215.73744)
		(end 402.293836 -215.620346)
		(width 0.10668)
		(layer "F.Cu")
		(net "M_G_CPU0_SA_DQ<10>")
	)
	(segment
		(start 401.814284 -217.068146)
		(end 401.931378 -216.951052)
		(width 0.10668)
		(layer "F.Cu")
		(net "M_G_CPU0_SA_DQ<10>")
	)
	(segment
		(start 402.458936 -215.620346)
		(end 402.77796 -215.93937)
		(width 0.10668)
		(layer "F.Cu")
		(net "M_G_CPU0_SA_DQ<10>")
	)
	(segment
		(start 401.612354 -216.301828)
		(end 401.729448 -216.184734)
		(width 0.10668)
		(layer "F.Cu")
		(net "M_G_CPU0_SA_DQ<10>")
	)
	(segment
		(start 401.36699 -217.51544)
		(end 401.36699 -217.35034)
		(width 0.10668)
		(layer "F.Cu")
		(net "M_G_CPU0_SA_DQ<10>")
	)
	(segment
		(start 401.33016 -216.749122)
		(end 401.649184 -217.068146)
		(width 0.10668)
		(layer "F.Cu")
		(net "M_G_CPU0_SA_DQ<10>")
	)
	(segment
		(start 403.060154 -215.657176)
		(end 402.74113 -215.338152)
		(width 0.10668)
		(layer "F.Cu")
		(net "M_G_CPU0_SA_DQ<10>")
	)
	(segment
		(start 402.495766 -216.221564)
		(end 402.176742 -215.90254)
		(width 0.10668)
		(layer "F.Cu")
		(net "M_G_CPU0_SA_DQ<10>")
	)
	(segment
		(start 393.558014 -230.97998)
		(end 393.46505 -230.81996)
		(width 0.0762)
		(layer "F.Cu")
		(net "M_G_CPU0_SA_DQ<10>")
	)
	(segment
		(start 395.422628 -230.67137)
		(end 400.499834 -225.594164)
		(width 0.10668)
		(layer "F.Cu")
		(net "M_G_CPU0_SA_DQ<10>")
	)
	(segment
		(start 400.600672 -217.31351)
		(end 400.765772 -217.31351)
		(width 0.10668)
		(layer "F.Cu")
		(net "M_G_CPU0_SA_DQ<10>")
	)
	(segment
		(start 402.495766 -216.386664)
		(end 402.495766 -216.221564)
		(width 0.10668)
		(layer "F.Cu")
		(net "M_G_CPU0_SA_DQ<10>")
	)
	(segment
		(start 401.729448 -216.184734)
		(end 401.894548 -216.184734)
		(width 0.10668)
		(layer "F.Cu")
		(net "M_G_CPU0_SA_DQ<10>")
	)
	(segment
		(start 395.13764 -230.67137)
		(end 395.422628 -230.67137)
		(width 0.0762)
		(layer "F.Cu")
		(net "M_G_CPU0_SA_DQ<10>")
	)
	(segment
		(start 402.293836 -215.620346)
		(end 402.458936 -215.620346)
		(width 0.10668)
		(layer "F.Cu")
		(net "M_G_CPU0_SA_DQ<10>")
	)
	(segment
		(start 402.378672 -216.503758)
		(end 402.495766 -216.386664)
		(width 0.10668)
		(layer "F.Cu")
		(net "M_G_CPU0_SA_DQ<10>")
	)
	(segment
		(start 400.499834 -217.414348)
		(end 400.600672 -217.31351)
		(width 0.10668)
		(layer "F.Cu")
		(net "M_G_CPU0_SA_DQ<10>")
	)
	(segment
		(start 394.93952 -230.86949)
		(end 395.13764 -230.67137)
		(width 0.0762)
		(layer "F.Cu")
		(net "M_G_CPU0_SA_DQ<10>")
	)
	(segment
		(start 402.74113 -215.338152)
		(end 402.74113 -215.173052)
		(width 0.10668)
		(layer "F.Cu")
		(net "M_G_CPU0_SA_DQ<10>")
	)
	(segment
		(start 401.047966 -216.866216)
		(end 401.16506 -216.749122)
		(width 0.10668)
		(layer "F.Cu")
		(net "M_G_CPU0_SA_DQ<10>")
	)
	(segment
		(start 401.16506 -216.749122)
		(end 401.33016 -216.749122)
		(width 0.10668)
		(layer "F.Cu")
		(net "M_G_CPU0_SA_DQ<10>")
	)
	(segment
		(start 402.176742 -215.90254)
		(end 402.176742 -215.73744)
		(width 0.10668)
		(layer "F.Cu")
		(net "M_G_CPU0_SA_DQ<10>")
	)
	(segment
		(start 401.084796 -217.632534)
		(end 401.249896 -217.632534)
		(width 0.10668)
		(layer "F.Cu")
		(net "M_G_CPU0_SA_DQ<10>")
	)
	(segment
		(start 401.36699 -217.35034)
		(end 401.047966 -217.031316)
		(width 0.10668)
		(layer "F.Cu")
		(net "M_G_CPU0_SA_DQ<10>")
	)
	(segment
		(start 402.74113 -215.173052)
		(end 410.379164 -207.535018)
		(width 0.10668)
		(layer "F.Cu")
		(net "M_G_CPU0_SA_DQ<10>")
	)
	(segment
		(start 403.060154 -215.822276)
		(end 403.060154 -215.657176)
		(width 0.10668)
		(layer "F.Cu")
		(net "M_G_CPU0_SA_DQ<10>")
	)
	(segment
		(start 402.213572 -216.503758)
		(end 402.378672 -216.503758)
		(width 0.10668)
		(layer "F.Cu")
		(net "M_G_CPU0_SA_DQ<10>")
	)
	(segment
		(start 400.499834 -225.594164)
		(end 400.499834 -217.414348)
		(width 0.10668)
		(layer "F.Cu")
		(net "M_G_CPU0_SA_DQ<10>")
	)
	(segment
		(start 401.931378 -216.951052)
		(end 401.931378 -216.785952)
		(width 0.10668)
		(layer "F.Cu")
		(net "M_G_CPU0_SA_DQ<10>")
	)
	(segment
		(start 400.765772 -217.31351)
		(end 401.084796 -217.632534)
		(width 0.10668)
		(layer "F.Cu")
		(net "M_G_CPU0_SA_DQ<10>")
	)
	(segment
		(start 402.77796 -215.93937)
		(end 402.94306 -215.93937)
		(width 0.10668)
		(layer "F.Cu")
		(net "M_G_CPU0_SA_DQ<10>")
	)
	(segment
		(start 394.532358 -230.86949)
		(end 394.93952 -230.86949)
		(width 0.0762)
		(layer "F.Cu")
		(net "M_G_CPU0_SA_DQ<10>")
	)
	(segment
		(start 410.379164 -207.535018)
		(end 412.367984 -207.535018)
		(width 0.10668)
		(layer "F.Cu")
		(net "M_G_CPU0_SA_DQ<10>")
	)
	(segment
		(start 401.612354 -216.466928)
		(end 401.612354 -216.301828)
		(width 0.10668)
		(layer "F.Cu")
		(net "M_G_CPU0_SA_DQ<10>")
	)
	(arc
		(start 393.744958 -230.6574)
		(mid 394.124626 -230.815539)
		(end 394.532358 -230.86949)
		(width 0.0762)
		(layer "F.Cu")
		(net "M_G_CPU0_SA_DQ<10>")
	)
	(arc
		(start 393.46505 -230.81996)
		(mid 393.46521 -230.673399)
		(end 393.596876 -230.60914)
		(width 0.0762)
		(layer "F.Cu")
		(net "M_G_CPU0_SA_DQ<10>")
	)
	(arc
		(start 393.596876 -230.60914)
		(mid 393.668884 -230.623922)
		(end 393.736576 -230.652574)
		(width 0.0762)
		(layer "F.Cu")
		(net "M_G_CPU0_SA_DQ<10>")
	)
	(segment
		(start 395.556232 -223.372934)
		(end 395.556232 -214.643208)
		(width 0.10668)
		(layer "F.Cu")
		(net "M_G_CPU0_SA_DQ<0>")
	)
	(segment
		(start 411.317694 -197.760082)
		(end 414.960562 -197.760082)
		(width 0.101346)
		(layer "F.Cu")
		(net "M_G_CPU0_SA_DQ<0>")
	)
	(segment
		(start 410.462222 -198.266558)
		(end 410.968698 -197.760082)
		(width 0.10668)
		(layer "F.Cu")
		(net "M_G_CPU0_SA_DQ<0>")
	)
	(segment
		(start 414.960562 -197.760082)
		(end 415.385504 -197.33514)
		(width 0.101346)
		(layer "F.Cu")
		(net "M_G_CPU0_SA_DQ<0>")
	)
	(segment
		(start 410.014928 -198.713852)
		(end 410.014928 -198.548752)
		(width 0.10668)
		(layer "F.Cu")
		(net "M_G_CPU0_SA_DQ<0>")
	)
	(segment
		(start 395.556232 -214.643208)
		(end 396.595854 -212.132926)
		(width 0.10668)
		(layer "F.Cu")
		(net "M_G_CPU0_SA_DQ<0>")
	)
	(segment
		(start 410.014928 -198.548752)
		(end 409.80868 -198.342758)
		(width 0.10668)
		(layer "F.Cu")
		(net "M_G_CPU0_SA_DQ<0>")
	)
	(segment
		(start 409.925774 -198.060564)
		(end 410.090874 -198.060564)
		(width 0.10668)
		(layer "F.Cu")
		(net "M_G_CPU0_SA_DQ<0>")
	)
	(segment
		(start 394.523214 -224.405952)
		(end 395.556232 -223.372934)
		(width 0.10668)
		(layer "F.Cu")
		(net "M_G_CPU0_SA_DQ<0>")
	)
	(segment
		(start 410.968698 -197.760082)
		(end 411.317694 -197.760082)
		(width 0.10668)
		(layer "F.Cu")
		(net "M_G_CPU0_SA_DQ<0>")
	)
	(segment
		(start 396.595854 -212.132926)
		(end 410.014928 -198.713852)
		(width 0.10668)
		(layer "F.Cu")
		(net "M_G_CPU0_SA_DQ<0>")
	)
	(segment
		(start 410.297122 -198.266558)
		(end 410.462222 -198.266558)
		(width 0.10668)
		(layer "F.Cu")
		(net "M_G_CPU0_SA_DQ<0>")
	)
	(segment
		(start 409.80868 -198.342758)
		(end 409.80868 -198.177658)
		(width 0.10668)
		(layer "F.Cu")
		(net "M_G_CPU0_SA_DQ<0>")
	)
	(segment
		(start 409.80868 -198.177658)
		(end 409.925774 -198.060564)
		(width 0.10668)
		(layer "F.Cu")
		(net "M_G_CPU0_SA_DQ<0>")
	)
	(segment
		(start 410.090874 -198.060564)
		(end 410.297122 -198.266558)
		(width 0.10668)
		(layer "F.Cu")
		(net "M_G_CPU0_SA_DQ<0>")
	)
	(segment
		(start 415.385504 -197.33514)
		(end 416.468052 -197.33514)
		(width 0.101346)
		(layer "F.Cu")
		(net "M_G_CPU0_SA_DQ<0>")
	)
	(segment
		(start 393.998196 -224.93097)
		(end 394.523214 -224.405952)
		(width 0.0762)
		(layer "F.Cu")
		(net "M_G_CPU0_SA_DQ<0>")
	)
	(arc
		(start 393.08786 -225.310192)
		(mid 393.50511 -225.029552)
		(end 393.998196 -224.93097)
		(width 0.0762)
		(layer "F.Cu")
		(net "M_G_CPU0_SA_DQ<0>")
	)
	(segment
		(start 411.320234 -246.635016)
		(end 412.367984 -246.635016)
		(width 0.10668)
		(layer "F.Cu")
		(net "M_G_CPU0_SA_CS_N<1>")
	)
	(segment
		(start 392.431016 -252.362462)
		(end 392.431016 -252.362716)
		(width 0.0762)
		(layer "F.Cu")
		(net "M_G_CPU0_SA_CS_N<1>")
	)
	(segment
		(start 397.654272 -252.28931)
		(end 398.77238 -251.171202)
		(width 0.10668)
		(layer "F.Cu")
		(net "M_G_CPU0_SA_CS_N<1>")
	)
	(segment
		(start 406.784048 -251.171202)
		(end 411.320234 -246.635016)
		(width 0.10668)
		(layer "F.Cu")
		(net "M_G_CPU0_SA_CS_N<1>")
	)
	(segment
		(start 393.736576 -252.367542)
		(end 393.744958 -252.362716)
		(width 0.0762)
		(layer "F.Cu")
		(net "M_G_CPU0_SA_CS_N<1>")
	)
	(segment
		(start 394.451332 -252.17247)
		(end 394.902436 -252.17247)
		(width 0.0762)
		(layer "F.Cu")
		(net "M_G_CPU0_SA_CS_N<1>")
	)
	(segment
		(start 398.77238 -251.171202)
		(end 406.784048 -251.171202)
		(width 0.10668)
		(layer "F.Cu")
		(net "M_G_CPU0_SA_CS_N<1>")
	)
	(segment
		(start 394.902436 -252.17247)
		(end 395.019276 -252.28931)
		(width 0.10668)
		(layer "F.Cu")
		(net "M_G_CPU0_SA_CS_N<1>")
	)
	(segment
		(start 395.019276 -252.28931)
		(end 397.654272 -252.28931)
		(width 0.10668)
		(layer "F.Cu")
		(net "M_G_CPU0_SA_CS_N<1>")
	)
	(arc
		(start 393.744958 -252.362716)
		(mid 394.085562 -252.22088)
		(end 394.451332 -252.17247)
		(width 0.0762)
		(layer "F.Cu")
		(net "M_G_CPU0_SA_CS_N<1>")
	)
	(arc
		(start 391.677906 -252.040136)
		(mid 391.881922 -252.22083)
		(end 392.146536 -252.286008)
		(width 0.0762)
		(layer "F.Cu")
		(net "M_G_CPU0_SA_CS_N<1>")
	)
	(arc
		(start 392.431016 -252.362716)
		(mid 392.61796 -252.412971)
		(end 392.804904 -252.362716)
		(width 0.0762)
		(layer "F.Cu")
		(net "M_G_CPU0_SA_CS_N<1>")
	)
	(arc
		(start 393.370816 -252.362716)
		(mid 393.553067 -252.413066)
		(end 393.736576 -252.367542)
		(width 0.0762)
		(layer "F.Cu")
		(net "M_G_CPU0_SA_CS_N<1>")
	)
	(arc
		(start 392.804904 -252.362716)
		(mid 393.08786 -252.286539)
		(end 393.370816 -252.362716)
		(width 0.0762)
		(layer "F.Cu")
		(net "M_G_CPU0_SA_CS_N<1>")
	)
	(arc
		(start 392.146536 -252.286008)
		(mid 392.293857 -252.305327)
		(end 392.431016 -252.362462)
		(width 0.0762)
		(layer "F.Cu")
		(net "M_G_CPU0_SA_CS_N<1>")
	)
	(segment
		(start 406.162764 -250.729242)
		(end 411.359096 -245.53291)
		(width 0.10668)
		(layer "F.Cu")
		(net "M_G_CPU0_SA_CS_N<0>")
	)
	(segment
		(start 395.303756 -251.60859)
		(end 397.691864 -251.60859)
		(width 0.10668)
		(layer "F.Cu")
		(net "M_G_CPU0_SA_CS_N<0>")
	)
	(segment
		(start 394.04798 -251.60859)
		(end 395.303756 -251.60859)
		(width 0.0762)
		(layer "F.Cu")
		(net "M_G_CPU0_SA_CS_N<0>")
	)
	(segment
		(start 397.691864 -251.60859)
		(end 398.571212 -250.729242)
		(width 0.10668)
		(layer "F.Cu")
		(net "M_G_CPU0_SA_CS_N<0>")
	)
	(segment
		(start 411.359096 -245.53291)
		(end 411.531816 -245.36019)
		(width 0.101346)
		(layer "F.Cu")
		(net "M_G_CPU0_SA_CS_N<0>")
	)
	(segment
		(start 413.661606 -245.785132)
		(end 416.468052 -245.785132)
		(width 0.101346)
		(layer "F.Cu")
		(net "M_G_CPU0_SA_CS_N<0>")
	)
	(segment
		(start 398.571212 -250.729242)
		(end 406.162764 -250.729242)
		(width 0.10668)
		(layer "F.Cu")
		(net "M_G_CPU0_SA_CS_N<0>")
	)
	(segment
		(start 411.531816 -245.36019)
		(end 413.236664 -245.36019)
		(width 0.101346)
		(layer "F.Cu")
		(net "M_G_CPU0_SA_CS_N<0>")
	)
	(segment
		(start 413.236664 -245.36019)
		(end 413.661606 -245.785132)
		(width 0.101346)
		(layer "F.Cu")
		(net "M_G_CPU0_SA_CS_N<0>")
	)
	(arc
		(start 393.08786 -251.23013)
		(mid 393.323988 -251.401565)
		(end 393.605512 -251.478288)
		(width 0.0762)
		(layer "F.Cu")
		(net "M_G_CPU0_SA_CS_N<0>")
	)
	(arc
		(start 393.84097 -251.55271)
		(mid 393.940777 -251.594339)
		(end 394.04798 -251.60859)
		(width 0.0762)
		(layer "F.Cu")
		(net "M_G_CPU0_SA_CS_N<0>")
	)
	(arc
		(start 393.605512 -251.478288)
		(mid 393.727368 -251.502444)
		(end 393.84097 -251.55271)
		(width 0.0762)
		(layer "F.Cu")
		(net "M_G_CPU0_SA_CS_N<0>")
	)
	(segment
		(start 408.588972 -246.196104)
		(end 408.706066 -246.07901)
		(width 0.10668)
		(layer "F.Cu")
		(net "M_G_CPU0_SA_CB<7>")
	)
	(segment
		(start 395.454378 -249.657108)
		(end 397.501618 -249.657108)
		(width 0.10668)
		(layer "F.Cu")
		(net "M_G_CPU0_SA_CB<7>")
	)
	(segment
		(start 411.372558 -243.635784)
		(end 411.28315 -243.546122)
		(width 0.10668)
		(layer "F.Cu")
		(net "M_G_CPU0_SA_CB<7>")
	)
	(segment
		(start 408.141678 -246.643398)
		(end 408.141678 -246.478298)
		(width 0.10668)
		(layer "F.Cu")
		(net "M_G_CPU0_SA_CB<7>")
	)
	(segment
		(start 407.501598 -246.567706)
		(end 407.666698 -246.567706)
		(width 0.10668)
		(layer "F.Cu")
		(net "M_G_CPU0_SA_CB<7>")
	)
	(segment
		(start 407.295096 -247.32488)
		(end 407.460196 -247.32488)
		(width 0.10668)
		(layer "F.Cu")
		(net "M_G_CPU0_SA_CB<7>")
	)
	(segment
		(start 407.666698 -246.567706)
		(end 407.859484 -246.760492)
		(width 0.10668)
		(layer "F.Cu")
		(net "M_G_CPU0_SA_CB<7>")
	)
	(segment
		(start 407.57729 -247.207786)
		(end 407.57729 -247.042686)
		(width 0.10668)
		(layer "F.Cu")
		(net "M_G_CPU0_SA_CB<7>")
	)
	(segment
		(start 407.948892 -246.285512)
		(end 407.948892 -246.120412)
		(width 0.10668)
		(layer "F.Cu")
		(net "M_G_CPU0_SA_CB<7>")
	)
	(segment
		(start 408.706066 -245.91391)
		(end 408.51328 -245.721124)
		(width 0.10668)
		(layer "F.Cu")
		(net "M_G_CPU0_SA_CB<7>")
	)
	(segment
		(start 406.372822 -247.696482)
		(end 406.537922 -247.696482)
		(width 0.10668)
		(layer "F.Cu")
		(net "M_G_CPU0_SA_CB<7>")
	)
	(segment
		(start 405.973534 -248.26087)
		(end 406.16632 -248.453656)
		(width 0.10668)
		(layer "F.Cu")
		(net "M_G_CPU0_SA_CB<7>")
	)
	(segment
		(start 406.448514 -248.171462)
		(end 406.255728 -247.978676)
		(width 0.10668)
		(layer "F.Cu")
		(net "M_G_CPU0_SA_CB<7>")
	)
	(segment
		(start 406.16632 -248.453656)
		(end 406.33142 -248.453656)
		(width 0.10668)
		(layer "F.Cu")
		(net "M_G_CPU0_SA_CB<7>")
	)
	(segment
		(start 408.51328 -245.721124)
		(end 408.51328 -245.556024)
		(width 0.10668)
		(layer "F.Cu")
		(net "M_G_CPU0_SA_CB<7>")
	)
	(segment
		(start 408.231086 -246.003318)
		(end 408.423872 -246.196104)
		(width 0.10668)
		(layer "F.Cu")
		(net "M_G_CPU0_SA_CB<7>")
	)
	(segment
		(start 408.630374 -245.43893)
		(end 408.795474 -245.43893)
		(width 0.10668)
		(layer "F.Cu")
		(net "M_G_CPU0_SA_CB<7>")
	)
	(segment
		(start 394.050012 -249.23115)
		(end 394.849096 -249.23115)
		(width 0.0762)
		(layer "F.Cu")
		(net "M_G_CPU0_SA_CB<7>")
	)
	(segment
		(start 406.730708 -247.889268)
		(end 406.895808 -247.889268)
		(width 0.10668)
		(layer "F.Cu")
		(net "M_G_CPU0_SA_CB<7>")
	)
	(segment
		(start 408.51328 -245.556024)
		(end 408.630374 -245.43893)
		(width 0.10668)
		(layer "F.Cu")
		(net "M_G_CPU0_SA_CB<7>")
	)
	(segment
		(start 406.820116 -247.414288)
		(end 406.820116 -247.249188)
		(width 0.10668)
		(layer "F.Cu")
		(net "M_G_CPU0_SA_CB<7>")
	)
	(segment
		(start 407.012902 -247.772174)
		(end 407.012902 -247.607074)
		(width 0.10668)
		(layer "F.Cu")
		(net "M_G_CPU0_SA_CB<7>")
	)
	(segment
		(start 406.93721 -247.132094)
		(end 407.10231 -247.132094)
		(width 0.10668)
		(layer "F.Cu")
		(net "M_G_CPU0_SA_CB<7>")
	)
	(segment
		(start 411.28315 -243.546122)
		(end 411.28315 -243.381022)
		(width 0.10668)
		(layer "F.Cu")
		(net "M_G_CPU0_SA_CB<7>")
	)
	(segment
		(start 405.69134 -248.543064)
		(end 405.69134 -248.377964)
		(width 0.10668)
		(layer "F.Cu")
		(net "M_G_CPU0_SA_CB<7>")
	)
	(segment
		(start 411.28315 -243.381022)
		(end 411.4292 -243.234972)
		(width 0.10668)
		(layer "F.Cu")
		(net "M_G_CPU0_SA_CB<7>")
	)
	(segment
		(start 405.58974 -249.195082)
		(end 405.884126 -248.90095)
		(width 0.10668)
		(layer "F.Cu")
		(net "M_G_CPU0_SA_CB<7>")
	)
	(segment
		(start 395.275054 -249.657108)
		(end 395.454378 -249.657108)
		(width 0.0762)
		(layer "F.Cu")
		(net "M_G_CPU0_SA_CB<7>")
	)
	(segment
		(start 405.884126 -248.90095)
		(end 405.884126 -248.73585)
		(width 0.10668)
		(layer "F.Cu")
		(net "M_G_CPU0_SA_CB<7>")
	)
	(segment
		(start 409.085796 -245.578122)
		(end 410.835856 -243.828316)
		(width 0.10668)
		(layer "F.Cu")
		(net "M_G_CPU0_SA_CB<7>")
	)
	(segment
		(start 405.884126 -248.73585)
		(end 405.69134 -248.543064)
		(width 0.10668)
		(layer "F.Cu")
		(net "M_G_CPU0_SA_CB<7>")
	)
	(segment
		(start 411.090364 -243.917978)
		(end 411.255464 -243.917978)
		(width 0.10668)
		(layer "F.Cu")
		(net "M_G_CPU0_SA_CB<7>")
	)
	(segment
		(start 407.012902 -247.607074)
		(end 406.820116 -247.414288)
		(width 0.10668)
		(layer "F.Cu")
		(net "M_G_CPU0_SA_CB<7>")
	)
	(segment
		(start 406.33142 -248.453656)
		(end 406.448514 -248.336562)
		(width 0.10668)
		(layer "F.Cu")
		(net "M_G_CPU0_SA_CB<7>")
	)
	(segment
		(start 408.024584 -246.760492)
		(end 408.141678 -246.643398)
		(width 0.10668)
		(layer "F.Cu")
		(net "M_G_CPU0_SA_CB<7>")
	)
	(segment
		(start 407.57729 -247.042686)
		(end 407.384504 -246.8499)
		(width 0.10668)
		(layer "F.Cu")
		(net "M_G_CPU0_SA_CB<7>")
	)
	(segment
		(start 392.326622 -249.282712)
		(end 392.327638 -249.28322)
		(width 0.0762)
		(layer "F.Cu")
		(net "M_G_CPU0_SA_CB<7>")
	)
	(segment
		(start 408.423872 -246.196104)
		(end 408.588972 -246.196104)
		(width 0.10668)
		(layer "F.Cu")
		(net "M_G_CPU0_SA_CB<7>")
	)
	(segment
		(start 394.849096 -249.23115)
		(end 395.275054 -249.657108)
		(width 0.0762)
		(layer "F.Cu")
		(net "M_G_CPU0_SA_CB<7>")
	)
	(segment
		(start 392.327638 -249.28322)
		(end 392.335004 -249.287538)
		(width 0.0762)
		(layer "F.Cu")
		(net "M_G_CPU0_SA_CB<7>")
	)
	(segment
		(start 408.934666 -245.578122)
		(end 409.085796 -245.578122)
		(width 0.10668)
		(layer "F.Cu")
		(net "M_G_CPU0_SA_CB<7>")
	)
	(segment
		(start 407.384504 -246.6848)
		(end 407.501598 -246.567706)
		(width 0.10668)
		(layer "F.Cu")
		(net "M_G_CPU0_SA_CB<7>")
	)
	(segment
		(start 406.255728 -247.813576)
		(end 406.372822 -247.696482)
		(width 0.10668)
		(layer "F.Cu")
		(net "M_G_CPU0_SA_CB<7>")
	)
	(segment
		(start 407.384504 -246.8499)
		(end 407.384504 -246.6848)
		(width 0.10668)
		(layer "F.Cu")
		(net "M_G_CPU0_SA_CB<7>")
	)
	(segment
		(start 392.14806 -249.610118)
		(end 392.14806 -249.609864)
		(width 0.0762)
		(layer "F.Cu")
		(net "M_G_CPU0_SA_CB<7>")
	)
	(segment
		(start 408.795474 -245.43893)
		(end 408.934666 -245.578122)
		(width 0.10668)
		(layer "F.Cu")
		(net "M_G_CPU0_SA_CB<7>")
	)
	(segment
		(start 397.501618 -249.657108)
		(end 397.963644 -249.195082)
		(width 0.10668)
		(layer "F.Cu")
		(net "M_G_CPU0_SA_CB<7>")
	)
	(segment
		(start 406.537922 -247.696482)
		(end 406.730708 -247.889268)
		(width 0.10668)
		(layer "F.Cu")
		(net "M_G_CPU0_SA_CB<7>")
	)
	(segment
		(start 397.963644 -249.195082)
		(end 405.58974 -249.195082)
		(width 0.10668)
		(layer "F.Cu")
		(net "M_G_CPU0_SA_CB<7>")
	)
	(segment
		(start 392.14806 -249.609864)
		(end 392.042904 -249.429016)
		(width 0.0762)
		(layer "F.Cu")
		(net "M_G_CPU0_SA_CB<7>")
	)
	(segment
		(start 408.141678 -246.478298)
		(end 407.948892 -246.285512)
		(width 0.10668)
		(layer "F.Cu")
		(net "M_G_CPU0_SA_CB<7>")
	)
	(segment
		(start 408.065986 -246.003318)
		(end 408.231086 -246.003318)
		(width 0.10668)
		(layer "F.Cu")
		(net "M_G_CPU0_SA_CB<7>")
	)
	(segment
		(start 406.820116 -247.249188)
		(end 406.93721 -247.132094)
		(width 0.10668)
		(layer "F.Cu")
		(net "M_G_CPU0_SA_CB<7>")
	)
	(segment
		(start 407.460196 -247.32488)
		(end 407.57729 -247.207786)
		(width 0.10668)
		(layer "F.Cu")
		(net "M_G_CPU0_SA_CB<7>")
	)
	(segment
		(start 406.255728 -247.978676)
		(end 406.255728 -247.813576)
		(width 0.10668)
		(layer "F.Cu")
		(net "M_G_CPU0_SA_CB<7>")
	)
	(segment
		(start 408.706066 -246.07901)
		(end 408.706066 -245.91391)
		(width 0.10668)
		(layer "F.Cu")
		(net "M_G_CPU0_SA_CB<7>")
	)
	(segment
		(start 407.10231 -247.132094)
		(end 407.295096 -247.32488)
		(width 0.10668)
		(layer "F.Cu")
		(net "M_G_CPU0_SA_CB<7>")
	)
	(segment
		(start 411.4292 -243.234972)
		(end 412.367984 -243.234972)
		(width 0.10668)
		(layer "F.Cu")
		(net "M_G_CPU0_SA_CB<7>")
	)
	(segment
		(start 407.948892 -246.120412)
		(end 408.065986 -246.003318)
		(width 0.10668)
		(layer "F.Cu")
		(net "M_G_CPU0_SA_CB<7>")
	)
	(segment
		(start 405.808434 -248.26087)
		(end 405.973534 -248.26087)
		(width 0.10668)
		(layer "F.Cu")
		(net "M_G_CPU0_SA_CB<7>")
	)
	(segment
		(start 411.000702 -243.828316)
		(end 411.090364 -243.917978)
		(width 0.10668)
		(layer "F.Cu")
		(net "M_G_CPU0_SA_CB<7>")
	)
	(segment
		(start 405.69134 -248.377964)
		(end 405.808434 -248.26087)
		(width 0.10668)
		(layer "F.Cu")
		(net "M_G_CPU0_SA_CB<7>")
	)
	(segment
		(start 407.859484 -246.760492)
		(end 408.024584 -246.760492)
		(width 0.10668)
		(layer "F.Cu")
		(net "M_G_CPU0_SA_CB<7>")
	)
	(segment
		(start 406.895808 -247.889268)
		(end 407.012902 -247.772174)
		(width 0.10668)
		(layer "F.Cu")
		(net "M_G_CPU0_SA_CB<7>")
	)
	(segment
		(start 392.900916 -249.287538)
		(end 392.909298 -249.282712)
		(width 0.0762)
		(layer "F.Cu")
		(net "M_G_CPU0_SA_CB<7>")
	)
	(segment
		(start 406.448514 -248.336562)
		(end 406.448514 -248.171462)
		(width 0.10668)
		(layer "F.Cu")
		(net "M_G_CPU0_SA_CB<7>")
	)
	(segment
		(start 410.835856 -243.828316)
		(end 411.000702 -243.828316)
		(width 0.10668)
		(layer "F.Cu")
		(net "M_G_CPU0_SA_CB<7>")
	)
	(segment
		(start 411.372558 -243.800884)
		(end 411.372558 -243.635784)
		(width 0.10668)
		(layer "F.Cu")
		(net "M_G_CPU0_SA_CB<7>")
	)
	(segment
		(start 411.255464 -243.917978)
		(end 411.372558 -243.800884)
		(width 0.10668)
		(layer "F.Cu")
		(net "M_G_CPU0_SA_CB<7>")
	)
	(arc
		(start 392.146536 -249.237246)
		(mid 392.23946 -249.248569)
		(end 392.326622 -249.282712)
		(width 0.0762)
		(layer "F.Cu")
		(net "M_G_CPU0_SA_CB<7>")
	)
	(arc
		(start 393.275058 -249.287538)
		(mid 393.558014 -249.363715)
		(end 393.84097 -249.287538)
		(width 0.0762)
		(layer "F.Cu")
		(net "M_G_CPU0_SA_CB<7>")
	)
	(arc
		(start 392.042904 -249.429016)
		(mid 392.051841 -249.309992)
		(end 392.146536 -249.237246)
		(width 0.0762)
		(layer "F.Cu")
		(net "M_G_CPU0_SA_CB<7>")
	)
	(arc
		(start 393.84097 -249.287538)
		(mid 393.941762 -249.245532)
		(end 394.050012 -249.23115)
		(width 0.0762)
		(layer "F.Cu")
		(net "M_G_CPU0_SA_CB<7>")
	)
	(arc
		(start 392.335004 -249.287538)
		(mid 392.61796 -249.363715)
		(end 392.900916 -249.287538)
		(width 0.0762)
		(layer "F.Cu")
		(net "M_G_CPU0_SA_CB<7>")
	)
	(arc
		(start 392.909298 -249.282712)
		(mid 393.092806 -249.237218)
		(end 393.275058 -249.287538)
		(width 0.0762)
		(layer "F.Cu")
		(net "M_G_CPU0_SA_CB<7>")
	)
	(segment
		(start 409.277312 -243.369846)
		(end 409.394406 -243.252752)
		(width 0.10668)
		(layer "F.Cu")
		(net "M_G_CPU0_SA_CB<6>")
	)
	(segment
		(start 409.07462 -244.62613)
		(end 409.07462 -244.46103)
		(width 0.10668)
		(layer "F.Cu")
		(net "M_G_CPU0_SA_CB<6>")
	)
	(segment
		(start 411.332172 -242.368578)
		(end 411.332172 -242.203478)
		(width 0.10668)
		(layer "F.Cu")
		(net "M_G_CPU0_SA_CB<6>")
	)
	(segment
		(start 410.767784 -242.767866)
		(end 410.406088 -242.40617)
		(width 0.10668)
		(layer "F.Cu")
		(net "M_G_CPU0_SA_CB<6>")
	)
	(segment
		(start 397.681196 -248.514362)
		(end 404.548848 -248.514362)
		(width 0.10668)
		(layer "F.Cu")
		(net "M_G_CPU0_SA_CB<6>")
	)
	(segment
		(start 409.958794 -242.688364)
		(end 410.123894 -242.688364)
		(width 0.10668)
		(layer "F.Cu")
		(net "M_G_CPU0_SA_CB<6>")
	)
	(segment
		(start 394.02766 -248.553732)
		(end 395.096238 -248.553732)
		(width 0.0762)
		(layer "F.Cu")
		(net "M_G_CPU0_SA_CB<6>")
	)
	(segment
		(start 409.521914 -244.178836)
		(end 409.639008 -244.061742)
		(width 0.10668)
		(layer "F.Cu")
		(net "M_G_CPU0_SA_CB<6>")
	)
	(segment
		(start 410.523182 -242.123976)
		(end 410.688282 -242.123976)
		(width 0.10668)
		(layer "F.Cu")
		(net "M_G_CPU0_SA_CB<6>")
	)
	(segment
		(start 404.548848 -248.514362)
		(end 408.480768 -244.582442)
		(width 0.10668)
		(layer "F.Cu")
		(net "M_G_CPU0_SA_CB<6>")
	)
	(segment
		(start 410.767784 -242.932966)
		(end 410.767784 -242.767866)
		(width 0.10668)
		(layer "F.Cu")
		(net "M_G_CPU0_SA_CB<6>")
	)
	(segment
		(start 410.203396 -243.497354)
		(end 410.203396 -243.332254)
		(width 0.10668)
		(layer "F.Cu")
		(net "M_G_CPU0_SA_CB<6>")
	)
	(segment
		(start 408.957526 -244.743224)
		(end 409.07462 -244.62613)
		(width 0.10668)
		(layer "F.Cu")
		(net "M_G_CPU0_SA_CB<6>")
	)
	(segment
		(start 410.406088 -242.40617)
		(end 410.406088 -242.24107)
		(width 0.10668)
		(layer "F.Cu")
		(net "M_G_CPU0_SA_CB<6>")
	)
	(segment
		(start 409.921202 -243.614448)
		(end 410.086302 -243.614448)
		(width 0.10668)
		(layer "F.Cu")
		(net "M_G_CPU0_SA_CB<6>")
	)
	(segment
		(start 410.970476 -241.841782)
		(end 410.970476 -241.676682)
		(width 0.10668)
		(layer "F.Cu")
		(net "M_G_CPU0_SA_CB<6>")
	)
	(segment
		(start 411.332172 -242.203478)
		(end 410.970476 -241.841782)
		(width 0.10668)
		(layer "F.Cu")
		(net "M_G_CPU0_SA_CB<6>")
	)
	(segment
		(start 410.086302 -243.614448)
		(end 410.203396 -243.497354)
		(width 0.10668)
		(layer "F.Cu")
		(net "M_G_CPU0_SA_CB<6>")
	)
	(segment
		(start 410.123894 -242.688364)
		(end 410.48559 -243.05006)
		(width 0.10668)
		(layer "F.Cu")
		(net "M_G_CPU0_SA_CB<6>")
	)
	(segment
		(start 409.394406 -243.252752)
		(end 409.559506 -243.252752)
		(width 0.10668)
		(layer "F.Cu")
		(net "M_G_CPU0_SA_CB<6>")
	)
	(segment
		(start 395.096238 -248.553732)
		(end 395.518894 -248.976388)
		(width 0.0762)
		(layer "F.Cu")
		(net "M_G_CPU0_SA_CB<6>")
	)
	(segment
		(start 409.8417 -242.970558)
		(end 409.8417 -242.805458)
		(width 0.10668)
		(layer "F.Cu")
		(net "M_G_CPU0_SA_CB<6>")
	)
	(segment
		(start 410.48559 -243.05006)
		(end 410.65069 -243.05006)
		(width 0.10668)
		(layer "F.Cu")
		(net "M_G_CPU0_SA_CB<6>")
	)
	(segment
		(start 408.712924 -243.934234)
		(end 408.830018 -243.81714)
		(width 0.10668)
		(layer "F.Cu")
		(net "M_G_CPU0_SA_CB<6>")
	)
	(segment
		(start 408.631644 -244.582442)
		(end 408.792426 -244.743224)
		(width 0.10668)
		(layer "F.Cu")
		(net "M_G_CPU0_SA_CB<6>")
	)
	(segment
		(start 408.830018 -243.81714)
		(end 408.995118 -243.81714)
		(width 0.10668)
		(layer "F.Cu")
		(net "M_G_CPU0_SA_CB<6>")
	)
	(segment
		(start 408.792426 -244.743224)
		(end 408.957526 -244.743224)
		(width 0.10668)
		(layer "F.Cu")
		(net "M_G_CPU0_SA_CB<6>")
	)
	(segment
		(start 410.203396 -243.332254)
		(end 409.8417 -242.970558)
		(width 0.10668)
		(layer "F.Cu")
		(net "M_G_CPU0_SA_CB<6>")
	)
	(segment
		(start 411.112208 -241.53495)
		(end 412.367984 -241.53495)
		(width 0.10668)
		(layer "F.Cu")
		(net "M_G_CPU0_SA_CB<6>")
	)
	(segment
		(start 411.215078 -242.485672)
		(end 411.332172 -242.368578)
		(width 0.10668)
		(layer "F.Cu")
		(net "M_G_CPU0_SA_CB<6>")
	)
	(segment
		(start 409.07462 -244.46103)
		(end 408.712924 -244.099334)
		(width 0.10668)
		(layer "F.Cu")
		(net "M_G_CPU0_SA_CB<6>")
	)
	(segment
		(start 408.712924 -244.099334)
		(end 408.712924 -243.934234)
		(width 0.10668)
		(layer "F.Cu")
		(net "M_G_CPU0_SA_CB<6>")
	)
	(segment
		(start 393.558014 -248.800112)
		(end 393.455652 -248.623836)
		(width 0.0762)
		(layer "F.Cu")
		(net "M_G_CPU0_SA_CB<6>")
	)
	(segment
		(start 409.559506 -243.252752)
		(end 409.921202 -243.614448)
		(width 0.10668)
		(layer "F.Cu")
		(net "M_G_CPU0_SA_CB<6>")
	)
	(segment
		(start 395.518894 -248.976388)
		(end 397.21917 -248.976388)
		(width 0.10668)
		(layer "F.Cu")
		(net "M_G_CPU0_SA_CB<6>")
	)
	(segment
		(start 410.970476 -241.676682)
		(end 411.112208 -241.53495)
		(width 0.10668)
		(layer "F.Cu")
		(net "M_G_CPU0_SA_CB<6>")
	)
	(segment
		(start 409.639008 -243.896642)
		(end 409.277312 -243.534946)
		(width 0.10668)
		(layer "F.Cu")
		(net "M_G_CPU0_SA_CB<6>")
	)
	(segment
		(start 409.639008 -244.061742)
		(end 409.639008 -243.896642)
		(width 0.10668)
		(layer "F.Cu")
		(net "M_G_CPU0_SA_CB<6>")
	)
	(segment
		(start 408.480768 -244.582442)
		(end 408.631644 -244.582442)
		(width 0.10668)
		(layer "F.Cu")
		(net "M_G_CPU0_SA_CB<6>")
	)
	(segment
		(start 409.8417 -242.805458)
		(end 409.958794 -242.688364)
		(width 0.10668)
		(layer "F.Cu")
		(net "M_G_CPU0_SA_CB<6>")
	)
	(segment
		(start 410.65069 -243.05006)
		(end 410.767784 -242.932966)
		(width 0.10668)
		(layer "F.Cu")
		(net "M_G_CPU0_SA_CB<6>")
	)
	(segment
		(start 397.21917 -248.976388)
		(end 397.681196 -248.514362)
		(width 0.10668)
		(layer "F.Cu")
		(net "M_G_CPU0_SA_CB<6>")
	)
	(segment
		(start 393.736576 -248.472706)
		(end 393.744958 -248.477532)
		(width 0.0762)
		(layer "F.Cu")
		(net "M_G_CPU0_SA_CB<6>")
	)
	(segment
		(start 410.688282 -242.123976)
		(end 411.049978 -242.485672)
		(width 0.10668)
		(layer "F.Cu")
		(net "M_G_CPU0_SA_CB<6>")
	)
	(segment
		(start 409.356814 -244.178836)
		(end 409.521914 -244.178836)
		(width 0.10668)
		(layer "F.Cu")
		(net "M_G_CPU0_SA_CB<6>")
	)
	(segment
		(start 411.049978 -242.485672)
		(end 411.215078 -242.485672)
		(width 0.10668)
		(layer "F.Cu")
		(net "M_G_CPU0_SA_CB<6>")
	)
	(segment
		(start 410.406088 -242.24107)
		(end 410.523182 -242.123976)
		(width 0.10668)
		(layer "F.Cu")
		(net "M_G_CPU0_SA_CB<6>")
	)
	(segment
		(start 409.277312 -243.534946)
		(end 409.277312 -243.369846)
		(width 0.10668)
		(layer "F.Cu")
		(net "M_G_CPU0_SA_CB<6>")
	)
	(segment
		(start 408.995118 -243.81714)
		(end 409.356814 -244.178836)
		(width 0.10668)
		(layer "F.Cu")
		(net "M_G_CPU0_SA_CB<6>")
	)
	(arc
		(start 393.744958 -248.477532)
		(mid 393.858682 -248.527833)
		(end 393.98067 -248.551954)
		(width 0.0762)
		(layer "F.Cu")
		(net "M_G_CPU0_SA_CB<6>")
	)
	(arc
		(start 393.98067 -248.551954)
		(mid 394.004147 -248.55333)
		(end 394.02766 -248.553732)
		(width 0.0762)
		(layer "F.Cu")
		(net "M_G_CPU0_SA_CB<6>")
	)
	(arc
		(start 393.62253 -248.432828)
		(mid 393.681176 -248.448121)
		(end 393.736576 -248.472706)
		(width 0.0762)
		(layer "F.Cu")
		(net "M_G_CPU0_SA_CB<6>")
	)
	(arc
		(start 393.455652 -248.623836)
		(mid 393.485281 -248.481349)
		(end 393.62253 -248.432828)
		(width 0.0762)
		(layer "F.Cu")
		(net "M_G_CPU0_SA_CB<6>")
	)
	(segment
		(start 405.346408 -248.707402)
		(end 405.346408 -248.542302)
		(width 0.10668)
		(layer "F.Cu")
		(net "M_G_CPU0_SA_CB<5>")
	)
	(segment
		(start 397.360394 -249.316748)
		(end 397.82242 -248.854722)
		(width 0.10668)
		(layer "F.Cu")
		(net "M_G_CPU0_SA_CB<5>")
	)
	(segment
		(start 394.445744 -248.93397)
		(end 395.047216 -248.93397)
		(width 0.0762)
		(layer "F.Cu")
		(net "M_G_CPU0_SA_CB<5>")
	)
	(segment
		(start 405.064214 -248.824496)
		(end 405.229314 -248.824496)
		(width 0.10668)
		(layer "F.Cu")
		(net "M_G_CPU0_SA_CB<5>")
	)
	(segment
		(start 404.690072 -248.854722)
		(end 404.809706 -248.735088)
		(width 0.10668)
		(layer "F.Cu")
		(net "M_G_CPU0_SA_CB<5>")
	)
	(segment
		(start 405.229314 -248.824496)
		(end 405.346408 -248.707402)
		(width 0.10668)
		(layer "F.Cu")
		(net "M_G_CPU0_SA_CB<5>")
	)
	(segment
		(start 404.809706 -248.735088)
		(end 404.974806 -248.735088)
		(width 0.10668)
		(layer "F.Cu")
		(net "M_G_CPU0_SA_CB<5>")
	)
	(segment
		(start 415.0106 -242.81003)
		(end 415.435542 -242.385088)
		(width 0.101346)
		(layer "F.Cu")
		(net "M_G_CPU0_SA_CB<5>")
	)
	(segment
		(start 392.431016 -249.122438)
		(end 392.431016 -249.122692)
		(width 0.0762)
		(layer "F.Cu")
		(net "M_G_CPU0_SA_CB<5>")
	)
	(segment
		(start 415.435542 -242.385088)
		(end 416.468052 -242.385088)
		(width 0.101346)
		(layer "F.Cu")
		(net "M_G_CPU0_SA_CB<5>")
	)
	(segment
		(start 411.372304 -242.81003)
		(end 415.0106 -242.81003)
		(width 0.101346)
		(layer "F.Cu")
		(net "M_G_CPU0_SA_CB<5>")
	)
	(segment
		(start 393.736576 -249.127518)
		(end 393.744958 -249.122692)
		(width 0.0762)
		(layer "F.Cu")
		(net "M_G_CPU0_SA_CB<5>")
	)
	(segment
		(start 411.265878 -242.916456)
		(end 411.372304 -242.81003)
		(width 0.101346)
		(layer "F.Cu")
		(net "M_G_CPU0_SA_CB<5>")
	)
	(segment
		(start 404.974806 -248.735088)
		(end 405.064214 -248.824496)
		(width 0.10668)
		(layer "F.Cu")
		(net "M_G_CPU0_SA_CB<5>")
	)
	(segment
		(start 409.09875 -245.083584)
		(end 411.265878 -242.916456)
		(width 0.10668)
		(layer "F.Cu")
		(net "M_G_CPU0_SA_CB<5>")
	)
	(segment
		(start 395.429994 -249.316748)
		(end 397.360394 -249.316748)
		(width 0.10668)
		(layer "F.Cu")
		(net "M_G_CPU0_SA_CB<5>")
	)
	(segment
		(start 405.257 -248.287794)
		(end 408.46121 -245.083584)
		(width 0.10668)
		(layer "F.Cu")
		(net "M_G_CPU0_SA_CB<5>")
	)
	(segment
		(start 405.257 -248.452894)
		(end 405.257 -248.287794)
		(width 0.10668)
		(layer "F.Cu")
		(net "M_G_CPU0_SA_CB<5>")
	)
	(segment
		(start 395.047216 -248.93397)
		(end 395.429994 -249.316748)
		(width 0.0762)
		(layer "F.Cu")
		(net "M_G_CPU0_SA_CB<5>")
	)
	(segment
		(start 408.46121 -245.083584)
		(end 409.09875 -245.083584)
		(width 0.10668)
		(layer "F.Cu")
		(net "M_G_CPU0_SA_CB<5>")
	)
	(segment
		(start 405.346408 -248.542302)
		(end 405.257 -248.452894)
		(width 0.10668)
		(layer "F.Cu")
		(net "M_G_CPU0_SA_CB<5>")
	)
	(segment
		(start 397.82242 -248.854722)
		(end 404.690072 -248.854722)
		(width 0.10668)
		(layer "F.Cu")
		(net "M_G_CPU0_SA_CB<5>")
	)
	(arc
		(start 392.804904 -249.122692)
		(mid 393.08786 -249.046515)
		(end 393.370816 -249.122692)
		(width 0.0762)
		(layer "F.Cu")
		(net "M_G_CPU0_SA_CB<5>")
	)
	(arc
		(start 392.431016 -249.122692)
		(mid 392.61796 -249.172947)
		(end 392.804904 -249.122692)
		(width 0.0762)
		(layer "F.Cu")
		(net "M_G_CPU0_SA_CB<5>")
	)
	(arc
		(start 392.146536 -249.045984)
		(mid 392.293857 -249.065303)
		(end 392.431016 -249.122438)
		(width 0.0762)
		(layer "F.Cu")
		(net "M_G_CPU0_SA_CB<5>")
	)
	(arc
		(start 391.677906 -248.800112)
		(mid 391.881922 -248.980806)
		(end 392.146536 -249.045984)
		(width 0.0762)
		(layer "F.Cu")
		(net "M_G_CPU0_SA_CB<5>")
	)
	(arc
		(start 393.744958 -249.122692)
		(mid 394.082868 -248.981975)
		(end 394.445744 -248.93397)
		(width 0.0762)
		(layer "F.Cu")
		(net "M_G_CPU0_SA_CB<5>")
	)
	(arc
		(start 393.370816 -249.122692)
		(mid 393.553067 -249.173042)
		(end 393.736576 -249.127518)
		(width 0.0762)
		(layer "F.Cu")
		(net "M_G_CPU0_SA_CB<5>")
	)
	(segment
		(start 396.865602 -248.17324)
		(end 396.982442 -248.0564)
		(width 0.10668)
		(layer "F.Cu")
		(net "M_G_CPU0_SA_CB<4>")
	)
	(segment
		(start 396.865602 -248.506234)
		(end 396.865602 -248.17324)
		(width 0.10668)
		(layer "F.Cu")
		(net "M_G_CPU0_SA_CB<4>")
	)
	(segment
		(start 396.067534 -248.506234)
		(end 396.067534 -248.17324)
		(width 0.10668)
		(layer "F.Cu")
		(net "M_G_CPU0_SA_CB<4>")
	)
	(segment
		(start 408.372564 -244.209062)
		(end 408.372564 -243.79301)
		(width 0.10668)
		(layer "F.Cu")
		(net "M_G_CPU0_SA_CB<4>")
	)
	(segment
		(start 396.982442 -248.0564)
		(end 404.525226 -248.0564)
		(width 0.10668)
		(layer "F.Cu")
		(net "M_G_CPU0_SA_CB<4>")
	)
	(segment
		(start 394.027914 -248.363232)
		(end 394.835634 -248.363232)
		(width 0.0762)
		(layer "F.Cu")
		(net "M_G_CPU0_SA_CB<4>")
	)
	(segment
		(start 408.372564 -243.79301)
		(end 411.055566 -241.110008)
		(width 0.10668)
		(layer "F.Cu")
		(net "M_G_CPU0_SA_CB<4>")
	)
	(segment
		(start 411.055566 -241.110008)
		(end 411.317694 -241.110008)
		(width 0.10668)
		(layer "F.Cu")
		(net "M_G_CPU0_SA_CB<4>")
	)
	(segment
		(start 394.835634 -248.363232)
		(end 395.142466 -248.0564)
		(width 0.0762)
		(layer "F.Cu")
		(net "M_G_CPU0_SA_CB<4>")
	)
	(segment
		(start 415.53257 -240.685066)
		(end 416.468052 -240.685066)
		(width 0.101346)
		(layer "F.Cu")
		(net "M_G_CPU0_SA_CB<4>")
	)
	(segment
		(start 411.317694 -241.110008)
		(end 415.107628 -241.110008)
		(width 0.101346)
		(layer "F.Cu")
		(net "M_G_CPU0_SA_CB<4>")
	)
	(segment
		(start 395.55166 -248.0564)
		(end 395.6685 -248.17324)
		(width 0.10668)
		(layer "F.Cu")
		(net "M_G_CPU0_SA_CB<4>")
	)
	(segment
		(start 404.525226 -248.0564)
		(end 408.372564 -244.209062)
		(width 0.10668)
		(layer "F.Cu")
		(net "M_G_CPU0_SA_CB<4>")
	)
	(segment
		(start 395.950694 -248.623074)
		(end 396.067534 -248.506234)
		(width 0.10668)
		(layer "F.Cu")
		(net "M_G_CPU0_SA_CB<4>")
	)
	(segment
		(start 395.142466 -248.0564)
		(end 395.37259 -248.0564)
		(width 0.0762)
		(layer "F.Cu")
		(net "M_G_CPU0_SA_CB<4>")
	)
	(segment
		(start 395.6685 -248.17324)
		(end 395.6685 -248.506234)
		(width 0.10668)
		(layer "F.Cu")
		(net "M_G_CPU0_SA_CB<4>")
	)
	(segment
		(start 396.466568 -248.17324)
		(end 396.466568 -248.506234)
		(width 0.10668)
		(layer "F.Cu")
		(net "M_G_CPU0_SA_CB<4>")
	)
	(segment
		(start 396.067534 -248.17324)
		(end 396.184374 -248.0564)
		(width 0.10668)
		(layer "F.Cu")
		(net "M_G_CPU0_SA_CB<4>")
	)
	(segment
		(start 395.78534 -248.623074)
		(end 395.950694 -248.623074)
		(width 0.10668)
		(layer "F.Cu")
		(net "M_G_CPU0_SA_CB<4>")
	)
	(segment
		(start 396.583408 -248.623074)
		(end 396.748762 -248.623074)
		(width 0.10668)
		(layer "F.Cu")
		(net "M_G_CPU0_SA_CB<4>")
	)
	(segment
		(start 396.466568 -248.506234)
		(end 396.583408 -248.623074)
		(width 0.10668)
		(layer "F.Cu")
		(net "M_G_CPU0_SA_CB<4>")
	)
	(segment
		(start 396.748762 -248.623074)
		(end 396.865602 -248.506234)
		(width 0.10668)
		(layer "F.Cu")
		(net "M_G_CPU0_SA_CB<4>")
	)
	(segment
		(start 395.6685 -248.506234)
		(end 395.78534 -248.623074)
		(width 0.10668)
		(layer "F.Cu")
		(net "M_G_CPU0_SA_CB<4>")
	)
	(segment
		(start 396.184374 -248.0564)
		(end 396.349728 -248.0564)
		(width 0.10668)
		(layer "F.Cu")
		(net "M_G_CPU0_SA_CB<4>")
	)
	(segment
		(start 415.107628 -241.110008)
		(end 415.53257 -240.685066)
		(width 0.101346)
		(layer "F.Cu")
		(net "M_G_CPU0_SA_CB<4>")
	)
	(segment
		(start 396.349728 -248.0564)
		(end 396.466568 -248.17324)
		(width 0.10668)
		(layer "F.Cu")
		(net "M_G_CPU0_SA_CB<4>")
	)
	(segment
		(start 395.37259 -248.0564)
		(end 395.55166 -248.0564)
		(width 0.10668)
		(layer "F.Cu")
		(net "M_G_CPU0_SA_CB<4>")
	)
	(arc
		(start 393.08786 -247.990106)
		(mid 393.331291 -248.159593)
		(end 393.616942 -248.239534)
		(width 0.0762)
		(layer "F.Cu")
		(net "M_G_CPU0_SA_CB<4>")
	)
	(arc
		(start 393.84097 -248.312686)
		(mid 393.91621 -248.345999)
		(end 393.996926 -248.361962)
		(width 0.0762)
		(layer "F.Cu")
		(net "M_G_CPU0_SA_CB<4>")
	)
	(arc
		(start 393.996926 -248.361962)
		(mid 394.012407 -248.362918)
		(end 394.027914 -248.363232)
		(width 0.0762)
		(layer "F.Cu")
		(net "M_G_CPU0_SA_CB<4>")
	)
	(arc
		(start 393.65555 -248.244868)
		(mid 393.751259 -248.27058)
		(end 393.84097 -248.312686)
		(width 0.0762)
		(layer "F.Cu")
		(net "M_G_CPU0_SA_CB<4>")
	)
	(arc
		(start 393.616942 -248.239534)
		(mid 393.636291 -248.241872)
		(end 393.65555 -248.244868)
		(width 0.0762)
		(layer "F.Cu")
		(net "M_G_CPU0_SA_CB<4>")
	)
	(segment
		(start 404.60041 -245.311168)
		(end 404.60041 -245.146068)
		(width 0.10668)
		(layer "F.Cu")
		(net "M_G_CPU0_SA_CB<3>")
	)
	(segment
		(start 404.882604 -244.863874)
		(end 405.047704 -244.863874)
		(width 0.10668)
		(layer "F.Cu")
		(net "M_G_CPU0_SA_CB<3>")
	)
	(segment
		(start 392.326622 -246.042688)
		(end 392.327638 -246.043196)
		(width 0.0762)
		(layer "F.Cu")
		(net "M_G_CPU0_SA_CB<3>")
	)
	(segment
		(start 410.46146 -237.693708)
		(end 410.855414 -237.530386)
		(width 0.10668)
		(layer "F.Cu")
		(net "M_G_CPU0_SA_CB<3>")
	)
	(segment
		(start 405.050244 -243.732558)
		(end 405.215344 -243.732558)
		(width 0.10668)
		(layer "F.Cu")
		(net "M_G_CPU0_SA_CB<3>")
	)
	(segment
		(start 392.900916 -246.047514)
		(end 392.909298 -246.042688)
		(width 0.0762)
		(layer "F.Cu")
		(net "M_G_CPU0_SA_CB<3>")
	)
	(segment
		(start 392.327638 -246.043196)
		(end 392.335004 -246.047514)
		(width 0.0762)
		(layer "F.Cu")
		(net "M_G_CPU0_SA_CB<3>")
	)
	(segment
		(start 403.778466 -246.133112)
		(end 404.60041 -245.311168)
		(width 0.10668)
		(layer "F.Cu")
		(net "M_G_CPU0_SA_CB<3>")
	)
	(segment
		(start 404.60041 -245.146068)
		(end 404.201122 -244.74678)
		(width 0.10668)
		(layer "F.Cu")
		(net "M_G_CPU0_SA_CB<3>")
	)
	(segment
		(start 405.332438 -244.014752)
		(end 404.76551 -244.58168)
		(width 0.10668)
		(layer "F.Cu")
		(net "M_G_CPU0_SA_CB<3>")
	)
	(segment
		(start 395.001496 -245.99265)
		(end 395.141958 -246.133112)
		(width 0.0762)
		(layer "F.Cu")
		(net "M_G_CPU0_SA_CB<3>")
	)
	(segment
		(start 395.141958 -246.133112)
		(end 395.545818 -246.133112)
		(width 0.0762)
		(layer "F.Cu")
		(net "M_G_CPU0_SA_CB<3>")
	)
	(segment
		(start 404.76551 -244.58168)
		(end 404.76551 -244.74678)
		(width 0.10668)
		(layer "F.Cu")
		(net "M_G_CPU0_SA_CB<3>")
	)
	(segment
		(start 404.201122 -244.74678)
		(end 404.201122 -244.58168)
		(width 0.10668)
		(layer "F.Cu")
		(net "M_G_CPU0_SA_CB<3>")
	)
	(segment
		(start 405.736044 -244.175534)
		(end 405.736044 -242.419124)
		(width 0.10668)
		(layer "F.Cu")
		(net "M_G_CPU0_SA_CB<3>")
	)
	(segment
		(start 405.332438 -243.849652)
		(end 405.332438 -244.014752)
		(width 0.10668)
		(layer "F.Cu")
		(net "M_G_CPU0_SA_CB<3>")
	)
	(segment
		(start 411.21965 -237.37951)
		(end 411.447996 -237.285022)
		(width 0.10668)
		(layer "F.Cu")
		(net "M_G_CPU0_SA_CB<3>")
	)
	(segment
		(start 394.044424 -245.99265)
		(end 395.001496 -245.99265)
		(width 0.0762)
		(layer "F.Cu")
		(net "M_G_CPU0_SA_CB<3>")
	)
	(segment
		(start 404.201122 -244.58168)
		(end 405.050244 -243.732558)
		(width 0.10668)
		(layer "F.Cu")
		(net "M_G_CPU0_SA_CB<3>")
	)
	(segment
		(start 392.14806 -246.36984)
		(end 392.042904 -246.188992)
		(width 0.0762)
		(layer "F.Cu")
		(net "M_G_CPU0_SA_CB<3>")
	)
	(segment
		(start 405.215344 -243.732558)
		(end 405.332438 -243.849652)
		(width 0.10668)
		(layer "F.Cu")
		(net "M_G_CPU0_SA_CB<3>")
	)
	(segment
		(start 405.736044 -242.419124)
		(end 410.46146 -237.693708)
		(width 0.10668)
		(layer "F.Cu")
		(net "M_G_CPU0_SA_CB<3>")
	)
	(segment
		(start 405.047704 -244.863874)
		(end 405.736044 -244.175534)
		(width 0.10668)
		(layer "F.Cu")
		(net "M_G_CPU0_SA_CB<3>")
	)
	(segment
		(start 411.447996 -237.285022)
		(end 412.367984 -237.285022)
		(width 0.10668)
		(layer "F.Cu")
		(net "M_G_CPU0_SA_CB<3>")
	)
	(segment
		(start 392.14806 -246.370094)
		(end 392.14806 -246.36984)
		(width 0.0762)
		(layer "F.Cu")
		(net "M_G_CPU0_SA_CB<3>")
	)
	(segment
		(start 404.76551 -244.74678)
		(end 404.882604 -244.863874)
		(width 0.10668)
		(layer "F.Cu")
		(net "M_G_CPU0_SA_CB<3>")
	)
	(segment
		(start 410.855414 -237.530386)
		(end 411.21965 -237.37951)
		(width 0.10668)
		(layer "F.Cu")
		(net "M_G_CPU0_SA_CB<3>")
	)
	(segment
		(start 395.545818 -246.133112)
		(end 403.778466 -246.133112)
		(width 0.10668)
		(layer "F.Cu")
		(net "M_G_CPU0_SA_CB<3>")
	)
	(arc
		(start 392.042904 -246.188992)
		(mid 392.051841 -246.069968)
		(end 392.146536 -245.997222)
		(width 0.0762)
		(layer "F.Cu")
		(net "M_G_CPU0_SA_CB<3>")
	)
	(arc
		(start 392.909298 -246.042688)
		(mid 393.092806 -245.997194)
		(end 393.275058 -246.047514)
		(width 0.0762)
		(layer "F.Cu")
		(net "M_G_CPU0_SA_CB<3>")
	)
	(arc
		(start 392.335004 -246.047514)
		(mid 392.61796 -246.123691)
		(end 392.900916 -246.047514)
		(width 0.0762)
		(layer "F.Cu")
		(net "M_G_CPU0_SA_CB<3>")
	)
	(arc
		(start 393.275058 -246.047514)
		(mid 393.558014 -246.123691)
		(end 393.84097 -246.047514)
		(width 0.0762)
		(layer "F.Cu")
		(net "M_G_CPU0_SA_CB<3>")
	)
	(arc
		(start 393.84097 -246.047514)
		(mid 393.939067 -246.006627)
		(end 394.044424 -245.99265)
		(width 0.0762)
		(layer "F.Cu")
		(net "M_G_CPU0_SA_CB<3>")
	)
	(arc
		(start 392.146536 -245.997222)
		(mid 392.23946 -246.008545)
		(end 392.326622 -246.042688)
		(width 0.0762)
		(layer "F.Cu")
		(net "M_G_CPU0_SA_CB<3>")
	)
	(segment
		(start 404.20417 -243.605812)
		(end 404.321264 -243.488718)
		(width 0.10668)
		(layer "F.Cu")
		(net "M_G_CPU0_SA_CB<2>")
	)
	(segment
		(start 403.238208 -245.061994)
		(end 403.403308 -245.061994)
		(width 0.10668)
		(layer "F.Cu")
		(net "M_G_CPU0_SA_CB<2>")
	)
	(segment
		(start 403.729698 -243.461794)
		(end 403.894798 -243.461794)
		(width 0.10668)
		(layer "F.Cu")
		(net "M_G_CPU0_SA_CB<2>")
	)
	(segment
		(start 402.776944 -245.330218)
		(end 402.776944 -245.165626)
		(width 0.10668)
		(layer "F.Cu")
		(net "M_G_CPU0_SA_CB<2>")
	)
	(segment
		(start 402.766022 -244.59057)
		(end 403.238208 -245.061994)
		(width 0.10668)
		(layer "F.Cu")
		(net "M_G_CPU0_SA_CB<2>")
	)
	(segment
		(start 411.00502 -236.351572)
		(end 411.138116 -236.484668)
		(width 0.10668)
		(layer "F.Cu")
		(net "M_G_CPU0_SA_CB<2>")
	)
	(segment
		(start 404.03907 -243.605812)
		(end 404.20417 -243.605812)
		(width 0.10668)
		(layer "F.Cu")
		(net "M_G_CPU0_SA_CB<2>")
	)
	(segment
		(start 411.42031 -236.367574)
		(end 411.42031 -236.202474)
		(width 0.10668)
		(layer "F.Cu")
		(net "M_G_CPU0_SA_CB<2>")
	)
	(segment
		(start 404.768558 -243.041424)
		(end 404.885652 -242.92433)
		(width 0.10668)
		(layer "F.Cu")
		(net "M_G_CPU0_SA_CB<2>")
	)
	(segment
		(start 403.33041 -244.026182)
		(end 403.474682 -244.1702)
		(width 0.10668)
		(layer "F.Cu")
		(net "M_G_CPU0_SA_CB<2>")
	)
	(segment
		(start 403.474682 -244.1702)
		(end 403.639782 -244.1702)
		(width 0.10668)
		(layer "F.Cu")
		(net "M_G_CPU0_SA_CB<2>")
	)
	(segment
		(start 404.885652 -242.75923)
		(end 404.74138 -242.614958)
		(width 0.10668)
		(layer "F.Cu")
		(net "M_G_CPU0_SA_CB<2>")
	)
	(segment
		(start 403.894798 -243.461794)
		(end 404.03907 -243.605812)
		(width 0.10668)
		(layer "F.Cu")
		(net "M_G_CPU0_SA_CB<2>")
	)
	(segment
		(start 401.74672 -245.444772)
		(end 402.036534 -245.154958)
		(width 0.10668)
		(layer "F.Cu")
		(net "M_G_CPU0_SA_CB<2>")
	)
	(segment
		(start 403.048216 -244.143276)
		(end 403.16531 -244.026182)
		(width 0.10668)
		(layer "F.Cu")
		(net "M_G_CPU0_SA_CB<2>")
	)
	(segment
		(start 411.303216 -236.484668)
		(end 411.42031 -236.367574)
		(width 0.10668)
		(layer "F.Cu")
		(net "M_G_CPU0_SA_CB<2>")
	)
	(segment
		(start 404.321264 -243.323618)
		(end 404.176992 -243.179346)
		(width 0.10668)
		(layer "F.Cu")
		(net "M_G_CPU0_SA_CB<2>")
	)
	(segment
		(start 403.612604 -243.578888)
		(end 403.729698 -243.461794)
		(width 0.10668)
		(layer "F.Cu")
		(net "M_G_CPU0_SA_CB<2>")
	)
	(segment
		(start 402.201634 -245.154958)
		(end 402.494496 -245.447312)
		(width 0.10668)
		(layer "F.Cu")
		(net "M_G_CPU0_SA_CB<2>")
	)
	(segment
		(start 403.756876 -243.888006)
		(end 403.612604 -243.743734)
		(width 0.10668)
		(layer "F.Cu")
		(net "M_G_CPU0_SA_CB<2>")
	)
	(segment
		(start 395.451838 -245.444772)
		(end 401.74672 -245.444772)
		(width 0.10668)
		(layer "F.Cu")
		(net "M_G_CPU0_SA_CB<2>")
	)
	(segment
		(start 403.16531 -244.026182)
		(end 403.33041 -244.026182)
		(width 0.10668)
		(layer "F.Cu")
		(net "M_G_CPU0_SA_CB<2>")
	)
	(segment
		(start 404.74138 -242.450112)
		(end 410.83992 -236.351572)
		(width 0.10668)
		(layer "F.Cu")
		(net "M_G_CPU0_SA_CB<2>")
	)
	(segment
		(start 402.483828 -244.707664)
		(end 402.600922 -244.59057)
		(width 0.10668)
		(layer "F.Cu")
		(net "M_G_CPU0_SA_CB<2>")
	)
	(segment
		(start 393.558014 -245.560088)
		(end 393.46505 -245.400068)
		(width 0.0762)
		(layer "F.Cu")
		(net "M_G_CPU0_SA_CB<2>")
	)
	(segment
		(start 404.885652 -242.92433)
		(end 404.885652 -242.75923)
		(width 0.10668)
		(layer "F.Cu")
		(net "M_G_CPU0_SA_CB<2>")
	)
	(segment
		(start 411.287214 -236.069378)
		(end 411.287214 -235.904278)
		(width 0.10668)
		(layer "F.Cu")
		(net "M_G_CPU0_SA_CB<2>")
	)
	(segment
		(start 404.294086 -242.897406)
		(end 404.459186 -242.897406)
		(width 0.10668)
		(layer "F.Cu")
		(net "M_G_CPU0_SA_CB<2>")
	)
	(segment
		(start 402.600922 -244.59057)
		(end 402.766022 -244.59057)
		(width 0.10668)
		(layer "F.Cu")
		(net "M_G_CPU0_SA_CB<2>")
	)
	(segment
		(start 402.776944 -245.165626)
		(end 402.483828 -244.87251)
		(width 0.10668)
		(layer "F.Cu")
		(net "M_G_CPU0_SA_CB<2>")
	)
	(segment
		(start 403.520402 -244.9449)
		(end 403.520402 -244.780308)
		(width 0.10668)
		(layer "F.Cu")
		(net "M_G_CPU0_SA_CB<2>")
	)
	(segment
		(start 403.403308 -245.061994)
		(end 403.520402 -244.9449)
		(width 0.10668)
		(layer "F.Cu")
		(net "M_G_CPU0_SA_CB<2>")
	)
	(segment
		(start 403.520402 -244.780308)
		(end 403.048216 -244.308122)
		(width 0.10668)
		(layer "F.Cu")
		(net "M_G_CPU0_SA_CB<2>")
	)
	(segment
		(start 411.138116 -236.484668)
		(end 411.303216 -236.484668)
		(width 0.10668)
		(layer "F.Cu")
		(net "M_G_CPU0_SA_CB<2>")
	)
	(segment
		(start 404.459186 -242.897406)
		(end 404.603458 -243.041424)
		(width 0.10668)
		(layer "F.Cu")
		(net "M_G_CPU0_SA_CB<2>")
	)
	(segment
		(start 403.048216 -244.308122)
		(end 403.048216 -244.143276)
		(width 0.10668)
		(layer "F.Cu")
		(net "M_G_CPU0_SA_CB<2>")
	)
	(segment
		(start 402.036534 -245.154958)
		(end 402.201634 -245.154958)
		(width 0.10668)
		(layer "F.Cu")
		(net "M_G_CPU0_SA_CB<2>")
	)
	(segment
		(start 403.756876 -244.053106)
		(end 403.756876 -243.888006)
		(width 0.10668)
		(layer "F.Cu")
		(net "M_G_CPU0_SA_CB<2>")
	)
	(segment
		(start 411.287214 -235.904278)
		(end 411.606492 -235.585)
		(width 0.10668)
		(layer "F.Cu")
		(net "M_G_CPU0_SA_CB<2>")
	)
	(segment
		(start 404.321264 -243.488718)
		(end 404.321264 -243.323618)
		(width 0.10668)
		(layer "F.Cu")
		(net "M_G_CPU0_SA_CB<2>")
	)
	(segment
		(start 402.494496 -245.447312)
		(end 402.65985 -245.447312)
		(width 0.10668)
		(layer "F.Cu")
		(net "M_G_CPU0_SA_CB<2>")
	)
	(segment
		(start 402.65985 -245.447312)
		(end 402.776944 -245.330218)
		(width 0.10668)
		(layer "F.Cu")
		(net "M_G_CPU0_SA_CB<2>")
	)
	(segment
		(start 410.83992 -236.351572)
		(end 411.00502 -236.351572)
		(width 0.10668)
		(layer "F.Cu")
		(net "M_G_CPU0_SA_CB<2>")
	)
	(segment
		(start 394.800074 -245.444772)
		(end 395.451838 -245.444772)
		(width 0.0762)
		(layer "F.Cu")
		(net "M_G_CPU0_SA_CB<2>")
	)
	(segment
		(start 404.176992 -243.0145)
		(end 404.294086 -242.897406)
		(width 0.10668)
		(layer "F.Cu")
		(net "M_G_CPU0_SA_CB<2>")
	)
	(segment
		(start 411.606492 -235.585)
		(end 412.367984 -235.585)
		(width 0.10668)
		(layer "F.Cu")
		(net "M_G_CPU0_SA_CB<2>")
	)
	(segment
		(start 404.603458 -243.041424)
		(end 404.768558 -243.041424)
		(width 0.10668)
		(layer "F.Cu")
		(net "M_G_CPU0_SA_CB<2>")
	)
	(segment
		(start 402.483828 -244.87251)
		(end 402.483828 -244.707664)
		(width 0.10668)
		(layer "F.Cu")
		(net "M_G_CPU0_SA_CB<2>")
	)
	(segment
		(start 404.74138 -242.614958)
		(end 404.74138 -242.450112)
		(width 0.10668)
		(layer "F.Cu")
		(net "M_G_CPU0_SA_CB<2>")
	)
	(segment
		(start 403.612604 -243.743734)
		(end 403.612604 -243.578888)
		(width 0.10668)
		(layer "F.Cu")
		(net "M_G_CPU0_SA_CB<2>")
	)
	(segment
		(start 404.176992 -243.179346)
		(end 404.176992 -243.0145)
		(width 0.10668)
		(layer "F.Cu")
		(net "M_G_CPU0_SA_CB<2>")
	)
	(segment
		(start 403.639782 -244.1702)
		(end 403.756876 -244.053106)
		(width 0.10668)
		(layer "F.Cu")
		(net "M_G_CPU0_SA_CB<2>")
	)
	(segment
		(start 393.736576 -245.232682)
		(end 393.744958 -245.237508)
		(width 0.0762)
		(layer "F.Cu")
		(net "M_G_CPU0_SA_CB<2>")
	)
	(segment
		(start 411.42031 -236.202474)
		(end 411.287214 -236.069378)
		(width 0.10668)
		(layer "F.Cu")
		(net "M_G_CPU0_SA_CB<2>")
	)
	(arc
		(start 393.842494 -245.282466)
		(mid 394.314458 -245.403884)
		(end 394.800074 -245.444772)
		(width 0.0762)
		(layer "F.Cu")
		(net "M_G_CPU0_SA_CB<2>")
	)
	(arc
		(start 393.46505 -245.400068)
		(mid 393.46521 -245.253507)
		(end 393.596876 -245.189248)
		(width 0.0762)
		(layer "F.Cu")
		(net "M_G_CPU0_SA_CB<2>")
	)
	(arc
		(start 393.596876 -245.189248)
		(mid 393.668884 -245.20403)
		(end 393.736576 -245.232682)
		(width 0.0762)
		(layer "F.Cu")
		(net "M_G_CPU0_SA_CB<2>")
	)
	(arc
		(start 393.744958 -245.237508)
		(mid 393.792652 -245.262318)
		(end 393.842494 -245.282466)
		(width 0.0762)
		(layer "F.Cu")
		(net "M_G_CPU0_SA_CB<2>")
	)
	(segment
		(start 405.395684 -242.905534)
		(end 405.395684 -242.277646)
		(width 0.10668)
		(layer "F.Cu")
		(net "M_G_CPU0_SA_CB<1>")
	)
	(segment
		(start 410.855414 -237.161578)
		(end 411.21965 -237.010702)
		(width 0.10668)
		(layer "F.Cu")
		(net "M_G_CPU0_SA_CB<1>")
	)
	(segment
		(start 395.204696 -245.72595)
		(end 395.266418 -245.787672)
		(width 0.0762)
		(layer "F.Cu")
		(net "M_G_CPU0_SA_CB<1>")
	)
	(segment
		(start 411.317694 -236.970062)
		(end 411.583378 -236.86008)
		(width 0.101346)
		(layer "F.Cu")
		(net "M_G_CPU0_SA_CB<1>")
	)
	(segment
		(start 394.326872 -245.72595)
		(end 395.204696 -245.72595)
		(width 0.0762)
		(layer "F.Cu")
		(net "M_G_CPU0_SA_CB<1>")
	)
	(segment
		(start 392.431016 -245.882414)
		(end 392.431016 -245.882668)
		(width 0.0762)
		(layer "F.Cu")
		(net "M_G_CPU0_SA_CB<1>")
	)
	(segment
		(start 405.395684 -242.277646)
		(end 410.26842 -237.40491)
		(width 0.10668)
		(layer "F.Cu")
		(net "M_G_CPU0_SA_CB<1>")
	)
	(segment
		(start 411.21965 -237.010702)
		(end 411.317694 -236.970062)
		(width 0.10668)
		(layer "F.Cu")
		(net "M_G_CPU0_SA_CB<1>")
	)
	(segment
		(start 393.736576 -245.887494)
		(end 393.744958 -245.882668)
		(width 0.0762)
		(layer "F.Cu")
		(net "M_G_CPU0_SA_CB<1>")
	)
	(segment
		(start 403.159214 -245.787672)
		(end 403.860762 -245.086124)
		(width 0.10668)
		(layer "F.Cu")
		(net "M_G_CPU0_SA_CB<1>")
	)
	(segment
		(start 403.860762 -245.086124)
		(end 403.860762 -244.440456)
		(width 0.10668)
		(layer "F.Cu")
		(net "M_G_CPU0_SA_CB<1>")
	)
	(segment
		(start 410.26842 -237.40491)
		(end 410.855414 -237.161578)
		(width 0.10668)
		(layer "F.Cu")
		(net "M_G_CPU0_SA_CB<1>")
	)
	(segment
		(start 395.70152 -245.787672)
		(end 403.159214 -245.787672)
		(width 0.10668)
		(layer "F.Cu")
		(net "M_G_CPU0_SA_CB<1>")
	)
	(segment
		(start 413.392874 -236.86008)
		(end 415.529014 -236.435138)
		(width 0.101346)
		(layer "F.Cu")
		(net "M_G_CPU0_SA_CB<1>")
	)
	(segment
		(start 415.529014 -236.435138)
		(end 416.468052 -236.435138)
		(width 0.101346)
		(layer "F.Cu")
		(net "M_G_CPU0_SA_CB<1>")
	)
	(segment
		(start 395.266418 -245.787672)
		(end 395.70152 -245.787672)
		(width 0.0762)
		(layer "F.Cu")
		(net "M_G_CPU0_SA_CB<1>")
	)
	(segment
		(start 411.583378 -236.86008)
		(end 413.392874 -236.86008)
		(width 0.101346)
		(layer "F.Cu")
		(net "M_G_CPU0_SA_CB<1>")
	)
	(segment
		(start 403.860762 -244.440456)
		(end 405.395684 -242.905534)
		(width 0.10668)
		(layer "F.Cu")
		(net "M_G_CPU0_SA_CB<1>")
	)
	(arc
		(start 392.146536 -245.80596)
		(mid 392.293857 -245.825279)
		(end 392.431016 -245.882414)
		(width 0.0762)
		(layer "F.Cu")
		(net "M_G_CPU0_SA_CB<1>")
	)
	(arc
		(start 393.744958 -245.882668)
		(mid 394.025549 -245.765818)
		(end 394.326872 -245.72595)
		(width 0.0762)
		(layer "F.Cu")
		(net "M_G_CPU0_SA_CB<1>")
	)
	(arc
		(start 392.431016 -245.882668)
		(mid 392.61796 -245.932923)
		(end 392.804904 -245.882668)
		(width 0.0762)
		(layer "F.Cu")
		(net "M_G_CPU0_SA_CB<1>")
	)
	(arc
		(start 392.804904 -245.882668)
		(mid 393.08786 -245.806491)
		(end 393.370816 -245.882668)
		(width 0.0762)
		(layer "F.Cu")
		(net "M_G_CPU0_SA_CB<1>")
	)
	(arc
		(start 391.677906 -245.560088)
		(mid 391.881922 -245.740782)
		(end 392.146536 -245.80596)
		(width 0.0762)
		(layer "F.Cu")
		(net "M_G_CPU0_SA_CB<1>")
	)
	(arc
		(start 393.370816 -245.882668)
		(mid 393.553067 -245.933018)
		(end 393.736576 -245.887494)
		(width 0.0762)
		(layer "F.Cu")
		(net "M_G_CPU0_SA_CB<1>")
	)
	(segment
		(start 410.954474 -235.755434)
		(end 411.54985 -235.160058)
		(width 0.101346)
		(layer "F.Cu")
		(net "M_G_CPU0_SA_CB<0>")
	)
	(segment
		(start 414.169352 -235.044742)
		(end 414.169352 -234.617768)
		(width 0.101346)
		(layer "F.Cu")
		(net "M_G_CPU0_SA_CB<0>")
	)
	(segment
		(start 415.587688 -234.735116)
		(end 416.468052 -234.735116)
		(width 0.101346)
		(layer "F.Cu")
		(net "M_G_CPU0_SA_CB<0>")
	)
	(segment
		(start 414.563052 -234.617768)
		(end 414.563052 -235.044742)
		(width 0.101346)
		(layer "F.Cu")
		(net "M_G_CPU0_SA_CB<0>")
	)
	(segment
		(start 395.05128 -245.12651)
		(end 395.07668 -245.10111)
		(width 0.0762)
		(layer "F.Cu")
		(net "M_G_CPU0_SA_CB<0>")
	)
	(segment
		(start 414.563052 -235.044742)
		(end 414.678368 -235.160058)
		(width 0.101346)
		(layer "F.Cu")
		(net "M_G_CPU0_SA_CB<0>")
	)
	(segment
		(start 414.054036 -235.160058)
		(end 414.169352 -235.044742)
		(width 0.101346)
		(layer "F.Cu")
		(net "M_G_CPU0_SA_CB<0>")
	)
	(segment
		(start 414.447736 -234.502452)
		(end 414.563052 -234.617768)
		(width 0.101346)
		(layer "F.Cu")
		(net "M_G_CPU0_SA_CB<0>")
	)
	(segment
		(start 414.284668 -234.502452)
		(end 414.447736 -234.502452)
		(width 0.101346)
		(layer "F.Cu")
		(net "M_G_CPU0_SA_CB<0>")
	)
	(segment
		(start 395.453616 -245.10111)
		(end 401.608798 -245.10111)
		(width 0.10668)
		(layer "F.Cu")
		(net "M_G_CPU0_SA_CB<0>")
	)
	(segment
		(start 401.608798 -245.10111)
		(end 410.954474 -235.755434)
		(width 0.10668)
		(layer "F.Cu")
		(net "M_G_CPU0_SA_CB<0>")
	)
	(segment
		(start 394.10767 -245.12651)
		(end 395.05128 -245.12651)
		(width 0.0762)
		(layer "F.Cu")
		(net "M_G_CPU0_SA_CB<0>")
	)
	(segment
		(start 415.162746 -235.160058)
		(end 415.587688 -234.735116)
		(width 0.101346)
		(layer "F.Cu")
		(net "M_G_CPU0_SA_CB<0>")
	)
	(segment
		(start 395.07668 -245.10111)
		(end 395.453616 -245.10111)
		(width 0.0762)
		(layer "F.Cu")
		(net "M_G_CPU0_SA_CB<0>")
	)
	(segment
		(start 414.169352 -234.617768)
		(end 414.284668 -234.502452)
		(width 0.101346)
		(layer "F.Cu")
		(net "M_G_CPU0_SA_CB<0>")
	)
	(segment
		(start 411.54985 -235.160058)
		(end 414.054036 -235.160058)
		(width 0.101346)
		(layer "F.Cu")
		(net "M_G_CPU0_SA_CB<0>")
	)
	(segment
		(start 414.678368 -235.160058)
		(end 415.162746 -235.160058)
		(width 0.101346)
		(layer "F.Cu")
		(net "M_G_CPU0_SA_CB<0>")
	)
	(arc
		(start 393.996926 -245.121938)
		(mid 394.052251 -245.125369)
		(end 394.10767 -245.12651)
		(width 0.0762)
		(layer "F.Cu")
		(net "M_G_CPU0_SA_CB<0>")
	)
	(arc
		(start 393.605512 -244.99824)
		(mid 393.727368 -245.022396)
		(end 393.84097 -245.072662)
		(width 0.0762)
		(layer "F.Cu")
		(net "M_G_CPU0_SA_CB<0>")
	)
	(arc
		(start 393.08786 -244.750082)
		(mid 393.323988 -244.921517)
		(end 393.605512 -244.99824)
		(width 0.0762)
		(layer "F.Cu")
		(net "M_G_CPU0_SA_CB<0>")
	)
	(arc
		(start 393.84097 -245.072662)
		(mid 393.91621 -245.105975)
		(end 393.996926 -245.121938)
		(width 0.0762)
		(layer "F.Cu")
		(net "M_G_CPU0_SA_CB<0>")
	)
	(segment
		(start 395.594078 -255.537462)
		(end 398.258792 -255.537462)
		(width 0.10668)
		(layer "F.Cu")
		(net "M_G_CPU0_SA_CA<6>")
	)
	(segment
		(start 399.982182 -253.814072)
		(end 405.017478 -253.814072)
		(width 0.10668)
		(layer "F.Cu")
		(net "M_G_CPU0_SA_CA<6>")
	)
	(segment
		(start 408.8003 -254.62103)
		(end 411.093666 -252.327664)
		(width 0.10668)
		(layer "F.Cu")
		(net "M_G_CPU0_SA_CA<6>")
	)
	(segment
		(start 393.736576 -255.607566)
		(end 393.744958 -255.60274)
		(width 0.0762)
		(layer "F.Cu")
		(net "M_G_CPU0_SA_CA<6>")
	)
	(segment
		(start 411.261306 -252.160024)
		(end 413.236664 -252.160024)
		(width 0.101346)
		(layer "F.Cu")
		(net "M_G_CPU0_SA_CA<6>")
	)
	(segment
		(start 395.148816 -255.45161)
		(end 395.234668 -255.537462)
		(width 0.0762)
		(layer "F.Cu")
		(net "M_G_CPU0_SA_CA<6>")
	)
	(segment
		(start 394.222224 -255.45161)
		(end 395.148816 -255.45161)
		(width 0.0762)
		(layer "F.Cu")
		(net "M_G_CPU0_SA_CA<6>")
	)
	(segment
		(start 395.234668 -255.537462)
		(end 395.594078 -255.537462)
		(width 0.0762)
		(layer "F.Cu")
		(net "M_G_CPU0_SA_CA<6>")
	)
	(segment
		(start 405.017478 -253.814072)
		(end 405.824436 -254.62103)
		(width 0.10668)
		(layer "F.Cu")
		(net "M_G_CPU0_SA_CA<6>")
	)
	(segment
		(start 411.093666 -252.327664)
		(end 411.261306 -252.160024)
		(width 0.101346)
		(layer "F.Cu")
		(net "M_G_CPU0_SA_CA<6>")
	)
	(segment
		(start 413.661606 -252.584966)
		(end 416.468052 -252.584966)
		(width 0.101346)
		(layer "F.Cu")
		(net "M_G_CPU0_SA_CA<6>")
	)
	(segment
		(start 413.236664 -252.160024)
		(end 413.661606 -252.584966)
		(width 0.101346)
		(layer "F.Cu")
		(net "M_G_CPU0_SA_CA<6>")
	)
	(segment
		(start 392.431016 -255.602486)
		(end 392.431016 -255.60274)
		(width 0.0762)
		(layer "F.Cu")
		(net "M_G_CPU0_SA_CA<6>")
	)
	(segment
		(start 405.824436 -254.62103)
		(end 408.8003 -254.62103)
		(width 0.10668)
		(layer "F.Cu")
		(net "M_G_CPU0_SA_CA<6>")
	)
	(segment
		(start 398.258792 -255.537462)
		(end 399.982182 -253.814072)
		(width 0.10668)
		(layer "F.Cu")
		(net "M_G_CPU0_SA_CA<6>")
	)
	(arc
		(start 392.431016 -255.60274)
		(mid 392.61796 -255.652995)
		(end 392.804904 -255.60274)
		(width 0.0762)
		(layer "F.Cu")
		(net "M_G_CPU0_SA_CA<6>")
	)
	(arc
		(start 392.146536 -255.526032)
		(mid 392.293857 -255.545351)
		(end 392.431016 -255.602486)
		(width 0.0762)
		(layer "F.Cu")
		(net "M_G_CPU0_SA_CA<6>")
	)
	(arc
		(start 392.804904 -255.60274)
		(mid 393.08786 -255.526563)
		(end 393.370816 -255.60274)
		(width 0.0762)
		(layer "F.Cu")
		(net "M_G_CPU0_SA_CA<6>")
	)
	(arc
		(start 394.146024 -255.457706)
		(mid 394.183997 -255.453074)
		(end 394.222224 -255.45161)
		(width 0.0762)
		(layer "F.Cu")
		(net "M_G_CPU0_SA_CA<6>")
	)
	(arc
		(start 393.744958 -255.60274)
		(mid 393.938951 -255.512133)
		(end 394.146024 -255.457706)
		(width 0.0762)
		(layer "F.Cu")
		(net "M_G_CPU0_SA_CA<6>")
	)
	(arc
		(start 391.677906 -255.28016)
		(mid 391.881922 -255.460854)
		(end 392.146536 -255.526032)
		(width 0.0762)
		(layer "F.Cu")
		(net "M_G_CPU0_SA_CA<6>")
	)
	(arc
		(start 393.370816 -255.60274)
		(mid 393.553067 -255.65309)
		(end 393.736576 -255.607566)
		(width 0.0762)
		(layer "F.Cu")
		(net "M_G_CPU0_SA_CA<6>")
	)
	(segment
		(start 406.521666 -253.991872)
		(end 406.638506 -254.108712)
		(width 0.10668)
		(layer "F.Cu")
		(net "M_G_CPU0_SA_CA<5>")
	)
	(segment
		(start 408.117802 -253.577852)
		(end 408.117802 -253.991872)
		(width 0.10668)
		(layer "F.Cu")
		(net "M_G_CPU0_SA_CA<5>")
	)
	(segment
		(start 406.404826 -253.461012)
		(end 406.521666 -253.577852)
		(width 0.10668)
		(layer "F.Cu")
		(net "M_G_CPU0_SA_CA<5>")
	)
	(segment
		(start 406.122632 -253.577852)
		(end 406.239472 -253.461012)
		(width 0.10668)
		(layer "F.Cu")
		(net "M_G_CPU0_SA_CA<5>")
	)
	(segment
		(start 394.444728 -255.146302)
		(end 395.265148 -255.146302)
		(width 0.0762)
		(layer "F.Cu")
		(net "M_G_CPU0_SA_CA<5>")
	)
	(segment
		(start 406.122632 -253.991872)
		(end 406.122632 -253.577852)
		(width 0.10668)
		(layer "F.Cu")
		(net "M_G_CPU0_SA_CA<5>")
	)
	(segment
		(start 399.853658 -253.461012)
		(end 405.606758 -253.461012)
		(width 0.10668)
		(layer "F.Cu")
		(net "M_G_CPU0_SA_CA<5>")
	)
	(segment
		(start 405.840438 -254.108712)
		(end 406.005792 -254.108712)
		(width 0.10668)
		(layer "F.Cu")
		(net "M_G_CPU0_SA_CA<5>")
	)
	(segment
		(start 408.516836 -253.577852)
		(end 408.633676 -253.461012)
		(width 0.10668)
		(layer "F.Cu")
		(net "M_G_CPU0_SA_CA<5>")
	)
	(segment
		(start 406.9207 -253.577852)
		(end 407.03754 -253.461012)
		(width 0.10668)
		(layer "F.Cu")
		(net "M_G_CPU0_SA_CA<5>")
	)
	(segment
		(start 407.202894 -253.461012)
		(end 407.319734 -253.577852)
		(width 0.10668)
		(layer "F.Cu")
		(net "M_G_CPU0_SA_CA<5>")
	)
	(segment
		(start 393.558014 -255.28016)
		(end 393.46505 -255.12014)
		(width 0.0762)
		(layer "F.Cu")
		(net "M_G_CPU0_SA_CA<5>")
	)
	(segment
		(start 407.601928 -254.108712)
		(end 407.718768 -253.991872)
		(width 0.10668)
		(layer "F.Cu")
		(net "M_G_CPU0_SA_CA<5>")
	)
	(segment
		(start 407.718768 -253.991872)
		(end 407.718768 -253.577852)
		(width 0.10668)
		(layer "F.Cu")
		(net "M_G_CPU0_SA_CA<5>")
	)
	(segment
		(start 409.241752 -253.461012)
		(end 410.967682 -251.735082)
		(width 0.10668)
		(layer "F.Cu")
		(net "M_G_CPU0_SA_CA<5>")
	)
	(segment
		(start 408.399996 -254.108712)
		(end 408.516836 -253.991872)
		(width 0.10668)
		(layer "F.Cu")
		(net "M_G_CPU0_SA_CA<5>")
	)
	(segment
		(start 395.265148 -255.146302)
		(end 395.315948 -255.197102)
		(width 0.0762)
		(layer "F.Cu")
		(net "M_G_CPU0_SA_CA<5>")
	)
	(segment
		(start 408.117802 -253.991872)
		(end 408.234642 -254.108712)
		(width 0.10668)
		(layer "F.Cu")
		(net "M_G_CPU0_SA_CA<5>")
	)
	(segment
		(start 408.234642 -254.108712)
		(end 408.399996 -254.108712)
		(width 0.10668)
		(layer "F.Cu")
		(net "M_G_CPU0_SA_CA<5>")
	)
	(segment
		(start 407.319734 -253.577852)
		(end 407.319734 -253.991872)
		(width 0.10668)
		(layer "F.Cu")
		(net "M_G_CPU0_SA_CA<5>")
	)
	(segment
		(start 407.436574 -254.108712)
		(end 407.601928 -254.108712)
		(width 0.10668)
		(layer "F.Cu")
		(net "M_G_CPU0_SA_CA<5>")
	)
	(segment
		(start 408.516836 -253.991872)
		(end 408.516836 -253.577852)
		(width 0.10668)
		(layer "F.Cu")
		(net "M_G_CPU0_SA_CA<5>")
	)
	(segment
		(start 407.835608 -253.461012)
		(end 408.000962 -253.461012)
		(width 0.10668)
		(layer "F.Cu")
		(net "M_G_CPU0_SA_CA<5>")
	)
	(segment
		(start 406.005792 -254.108712)
		(end 406.122632 -253.991872)
		(width 0.10668)
		(layer "F.Cu")
		(net "M_G_CPU0_SA_CA<5>")
	)
	(segment
		(start 406.9207 -253.991872)
		(end 406.9207 -253.577852)
		(width 0.10668)
		(layer "F.Cu")
		(net "M_G_CPU0_SA_CA<5>")
	)
	(segment
		(start 406.638506 -254.108712)
		(end 406.80386 -254.108712)
		(width 0.10668)
		(layer "F.Cu")
		(net "M_G_CPU0_SA_CA<5>")
	)
	(segment
		(start 406.521666 -253.577852)
		(end 406.521666 -253.991872)
		(width 0.10668)
		(layer "F.Cu")
		(net "M_G_CPU0_SA_CA<5>")
	)
	(segment
		(start 408.000962 -253.461012)
		(end 408.117802 -253.577852)
		(width 0.10668)
		(layer "F.Cu")
		(net "M_G_CPU0_SA_CA<5>")
	)
	(segment
		(start 405.606758 -253.461012)
		(end 405.723598 -253.577852)
		(width 0.10668)
		(layer "F.Cu")
		(net "M_G_CPU0_SA_CA<5>")
	)
	(segment
		(start 407.319734 -253.991872)
		(end 407.436574 -254.108712)
		(width 0.10668)
		(layer "F.Cu")
		(net "M_G_CPU0_SA_CA<5>")
	)
	(segment
		(start 393.736576 -254.952754)
		(end 393.744958 -254.95758)
		(width 0.0762)
		(layer "F.Cu")
		(net "M_G_CPU0_SA_CA<5>")
	)
	(segment
		(start 395.611858 -255.197102)
		(end 398.117568 -255.197102)
		(width 0.10668)
		(layer "F.Cu")
		(net "M_G_CPU0_SA_CA<5>")
	)
	(segment
		(start 407.03754 -253.461012)
		(end 407.202894 -253.461012)
		(width 0.10668)
		(layer "F.Cu")
		(net "M_G_CPU0_SA_CA<5>")
	)
	(segment
		(start 395.315948 -255.197102)
		(end 395.611858 -255.197102)
		(width 0.0762)
		(layer "F.Cu")
		(net "M_G_CPU0_SA_CA<5>")
	)
	(segment
		(start 405.723598 -253.991872)
		(end 405.840438 -254.108712)
		(width 0.10668)
		(layer "F.Cu")
		(net "M_G_CPU0_SA_CA<5>")
	)
	(segment
		(start 398.117568 -255.197102)
		(end 399.853658 -253.461012)
		(width 0.10668)
		(layer "F.Cu")
		(net "M_G_CPU0_SA_CA<5>")
	)
	(segment
		(start 405.723598 -253.577852)
		(end 405.723598 -253.991872)
		(width 0.10668)
		(layer "F.Cu")
		(net "M_G_CPU0_SA_CA<5>")
	)
	(segment
		(start 410.967682 -251.735082)
		(end 412.367984 -251.735082)
		(width 0.10668)
		(layer "F.Cu")
		(net "M_G_CPU0_SA_CA<5>")
	)
	(segment
		(start 406.239472 -253.461012)
		(end 406.404826 -253.461012)
		(width 0.10668)
		(layer "F.Cu")
		(net "M_G_CPU0_SA_CA<5>")
	)
	(segment
		(start 406.80386 -254.108712)
		(end 406.9207 -253.991872)
		(width 0.10668)
		(layer "F.Cu")
		(net "M_G_CPU0_SA_CA<5>")
	)
	(segment
		(start 408.633676 -253.461012)
		(end 409.241752 -253.461012)
		(width 0.10668)
		(layer "F.Cu")
		(net "M_G_CPU0_SA_CA<5>")
	)
	(segment
		(start 407.718768 -253.577852)
		(end 407.835608 -253.461012)
		(width 0.10668)
		(layer "F.Cu")
		(net "M_G_CPU0_SA_CA<5>")
	)
	(arc
		(start 393.596876 -254.90932)
		(mid 393.668884 -254.924102)
		(end 393.736576 -254.952754)
		(width 0.0762)
		(layer "F.Cu")
		(net "M_G_CPU0_SA_CA<5>")
	)
	(arc
		(start 393.744958 -254.95758)
		(mid 394.082341 -255.098298)
		(end 394.444728 -255.146302)
		(width 0.0762)
		(layer "F.Cu")
		(net "M_G_CPU0_SA_CA<5>")
	)
	(arc
		(start 393.46505 -255.12014)
		(mid 393.46521 -254.973579)
		(end 393.596876 -254.90932)
		(width 0.0762)
		(layer "F.Cu")
		(net "M_G_CPU0_SA_CA<5>")
	)
	(segment
		(start 414.24606 -250.884944)
		(end 416.468052 -250.884944)
		(width 0.101346)
		(layer "F.Cu")
		(net "M_G_CPU0_SA_CA<4>")
	)
	(segment
		(start 395.183868 -254.849122)
		(end 395.191488 -254.856742)
		(width 0.0762)
		(layer "F.Cu")
		(net "M_G_CPU0_SA_CA<4>")
	)
	(segment
		(start 394.050012 -254.849122)
		(end 395.183868 -254.849122)
		(width 0.0762)
		(layer "F.Cu")
		(net "M_G_CPU0_SA_CA<4>")
	)
	(segment
		(start 397.976344 -254.856742)
		(end 399.716244 -253.116842)
		(width 0.10668)
		(layer "F.Cu")
		(net "M_G_CPU0_SA_CA<4>")
	)
	(segment
		(start 411.317694 -251.31014)
		(end 413.820864 -251.31014)
		(width 0.101346)
		(layer "F.Cu")
		(net "M_G_CPU0_SA_CA<4>")
	)
	(segment
		(start 395.191488 -254.856742)
		(end 395.611858 -254.856742)
		(width 0.0762)
		(layer "F.Cu")
		(net "M_G_CPU0_SA_CA<4>")
	)
	(segment
		(start 399.716244 -253.116842)
		(end 408.891486 -253.116842)
		(width 0.10668)
		(layer "F.Cu")
		(net "M_G_CPU0_SA_CA<4>")
	)
	(segment
		(start 408.891486 -253.116842)
		(end 410.698188 -251.31014)
		(width 0.10668)
		(layer "F.Cu")
		(net "M_G_CPU0_SA_CA<4>")
	)
	(segment
		(start 413.820864 -251.31014)
		(end 414.24606 -250.884944)
		(width 0.101346)
		(layer "F.Cu")
		(net "M_G_CPU0_SA_CA<4>")
	)
	(segment
		(start 395.611858 -254.856742)
		(end 397.976344 -254.856742)
		(width 0.10668)
		(layer "F.Cu")
		(net "M_G_CPU0_SA_CA<4>")
	)
	(segment
		(start 410.698188 -251.31014)
		(end 411.317694 -251.31014)
		(width 0.10668)
		(layer "F.Cu")
		(net "M_G_CPU0_SA_CA<4>")
	)
	(arc
		(start 393.84097 -254.792734)
		(mid 393.941753 -254.834791)
		(end 394.050012 -254.849122)
		(width 0.0762)
		(layer "F.Cu")
		(net "M_G_CPU0_SA_CA<4>")
	)
	(arc
		(start 393.605512 -254.718312)
		(mid 393.727368 -254.742468)
		(end 393.84097 -254.792734)
		(width 0.0762)
		(layer "F.Cu")
		(net "M_G_CPU0_SA_CA<4>")
	)
	(arc
		(start 393.08786 -254.470154)
		(mid 393.323988 -254.641589)
		(end 393.605512 -254.718312)
		(width 0.0762)
		(layer "F.Cu")
		(net "M_G_CPU0_SA_CA<4>")
	)
	(segment
		(start 408.900122 -252.037088)
		(end 408.900122 -251.871988)
		(width 0.10668)
		(layer "F.Cu")
		(net "M_G_CPU0_SA_CA<3>")
	)
	(segment
		(start 410.688282 -250.838208)
		(end 410.805376 -250.721114)
		(width 0.10668)
		(layer "F.Cu")
		(net "M_G_CPU0_SA_CA<3>")
	)
	(segment
		(start 408.900122 -251.871988)
		(end 409.017216 -251.754894)
		(width 0.10668)
		(layer "F.Cu")
		(net "M_G_CPU0_SA_CA<3>")
	)
	(segment
		(start 409.017216 -251.754894)
		(end 409.182316 -251.754894)
		(width 0.10668)
		(layer "F.Cu")
		(net "M_G_CPU0_SA_CA<3>")
	)
	(segment
		(start 409.394406 -251.966984)
		(end 409.559506 -251.966984)
		(width 0.10668)
		(layer "F.Cu")
		(net "M_G_CPU0_SA_CA<3>")
	)
	(segment
		(start 410.311092 -250.626118)
		(end 410.523182 -250.838208)
		(width 0.10668)
		(layer "F.Cu")
		(net "M_G_CPU0_SA_CA<3>")
	)
	(segment
		(start 410.593286 -250.343924)
		(end 410.593286 -250.178824)
		(width 0.10668)
		(layer "F.Cu")
		(net "M_G_CPU0_SA_CA<3>")
	)
	(segment
		(start 409.182316 -251.754894)
		(end 409.394406 -251.966984)
		(width 0.10668)
		(layer "F.Cu")
		(net "M_G_CPU0_SA_CA<3>")
	)
	(segment
		(start 410.805376 -250.556014)
		(end 410.593286 -250.343924)
		(width 0.10668)
		(layer "F.Cu")
		(net "M_G_CPU0_SA_CA<3>")
	)
	(segment
		(start 407.995628 -252.776482)
		(end 408.452828 -252.319282)
		(width 0.10668)
		(layer "F.Cu")
		(net "M_G_CPU0_SA_CA<3>")
	)
	(segment
		(start 394.963396 -254.09271)
		(end 395.077696 -254.20701)
		(width 0.0762)
		(layer "F.Cu")
		(net "M_G_CPU0_SA_CA<3>")
	)
	(segment
		(start 392.326622 -254.142748)
		(end 392.327638 -254.143256)
		(width 0.0762)
		(layer "F.Cu")
		(net "M_G_CPU0_SA_CA<3>")
	)
	(segment
		(start 409.559506 -251.966984)
		(end 409.6766 -251.84989)
		(width 0.10668)
		(layer "F.Cu")
		(net "M_G_CPU0_SA_CA<3>")
	)
	(segment
		(start 395.077696 -254.20701)
		(end 395.604238 -254.20701)
		(width 0.0762)
		(layer "F.Cu")
		(net "M_G_CPU0_SA_CA<3>")
	)
	(segment
		(start 409.112212 -252.414278)
		(end 409.112212 -252.249178)
		(width 0.10668)
		(layer "F.Cu")
		(net "M_G_CPU0_SA_CA<3>")
	)
	(segment
		(start 408.995118 -252.531372)
		(end 409.112212 -252.414278)
		(width 0.10668)
		(layer "F.Cu")
		(net "M_G_CPU0_SA_CA<3>")
	)
	(segment
		(start 409.958794 -251.402596)
		(end 410.123894 -251.402596)
		(width 0.10668)
		(layer "F.Cu")
		(net "M_G_CPU0_SA_CA<3>")
	)
	(segment
		(start 392.900916 -254.147574)
		(end 392.909298 -254.142748)
		(width 0.0762)
		(layer "F.Cu")
		(net "M_G_CPU0_SA_CA<3>")
	)
	(segment
		(start 410.028898 -250.908312)
		(end 410.028898 -250.743212)
		(width 0.10668)
		(layer "F.Cu")
		(net "M_G_CPU0_SA_CA<3>")
	)
	(segment
		(start 408.830018 -252.531372)
		(end 408.995118 -252.531372)
		(width 0.10668)
		(layer "F.Cu")
		(net "M_G_CPU0_SA_CA<3>")
	)
	(segment
		(start 409.6766 -251.84989)
		(end 409.6766 -251.68479)
		(width 0.10668)
		(layer "F.Cu")
		(net "M_G_CPU0_SA_CA<3>")
	)
	(segment
		(start 410.123894 -251.402596)
		(end 410.240988 -251.285502)
		(width 0.10668)
		(layer "F.Cu")
		(net "M_G_CPU0_SA_CA<3>")
	)
	(segment
		(start 410.593286 -250.178824)
		(end 410.73705 -250.03506)
		(width 0.10668)
		(layer "F.Cu")
		(net "M_G_CPU0_SA_CA<3>")
	)
	(segment
		(start 392.14806 -254.4699)
		(end 392.042904 -254.289052)
		(width 0.0762)
		(layer "F.Cu")
		(net "M_G_CPU0_SA_CA<3>")
	)
	(segment
		(start 410.805376 -250.721114)
		(end 410.805376 -250.556014)
		(width 0.10668)
		(layer "F.Cu")
		(net "M_G_CPU0_SA_CA<3>")
	)
	(segment
		(start 409.46451 -251.4727)
		(end 409.46451 -251.3076)
		(width 0.10668)
		(layer "F.Cu")
		(net "M_G_CPU0_SA_CA<3>")
	)
	(segment
		(start 408.452828 -252.319282)
		(end 408.617928 -252.319282)
		(width 0.10668)
		(layer "F.Cu")
		(net "M_G_CPU0_SA_CA<3>")
	)
	(segment
		(start 410.523182 -250.838208)
		(end 410.688282 -250.838208)
		(width 0.10668)
		(layer "F.Cu")
		(net "M_G_CPU0_SA_CA<3>")
	)
	(segment
		(start 410.028898 -250.743212)
		(end 410.145992 -250.626118)
		(width 0.10668)
		(layer "F.Cu")
		(net "M_G_CPU0_SA_CA<3>")
	)
	(segment
		(start 392.14806 -254.470154)
		(end 392.14806 -254.4699)
		(width 0.0762)
		(layer "F.Cu")
		(net "M_G_CPU0_SA_CA<3>")
	)
	(segment
		(start 408.617928 -252.319282)
		(end 408.830018 -252.531372)
		(width 0.10668)
		(layer "F.Cu")
		(net "M_G_CPU0_SA_CA<3>")
	)
	(segment
		(start 409.6766 -251.68479)
		(end 409.46451 -251.4727)
		(width 0.10668)
		(layer "F.Cu")
		(net "M_G_CPU0_SA_CA<3>")
	)
	(segment
		(start 409.746704 -251.190506)
		(end 409.958794 -251.402596)
		(width 0.10668)
		(layer "F.Cu")
		(net "M_G_CPU0_SA_CA<3>")
	)
	(segment
		(start 409.46451 -251.3076)
		(end 409.581604 -251.190506)
		(width 0.10668)
		(layer "F.Cu")
		(net "M_G_CPU0_SA_CA<3>")
	)
	(segment
		(start 409.112212 -252.249178)
		(end 408.900122 -252.037088)
		(width 0.10668)
		(layer "F.Cu")
		(net "M_G_CPU0_SA_CA<3>")
	)
	(segment
		(start 410.240988 -251.285502)
		(end 410.240988 -251.120402)
		(width 0.10668)
		(layer "F.Cu")
		(net "M_G_CPU0_SA_CA<3>")
	)
	(segment
		(start 409.581604 -251.190506)
		(end 409.746704 -251.190506)
		(width 0.10668)
		(layer "F.Cu")
		(net "M_G_CPU0_SA_CA<3>")
	)
	(segment
		(start 399.57502 -252.776482)
		(end 407.995628 -252.776482)
		(width 0.10668)
		(layer "F.Cu")
		(net "M_G_CPU0_SA_CA<3>")
	)
	(segment
		(start 410.145992 -250.626118)
		(end 410.311092 -250.626118)
		(width 0.10668)
		(layer "F.Cu")
		(net "M_G_CPU0_SA_CA<3>")
	)
	(segment
		(start 392.327638 -254.143256)
		(end 392.335004 -254.147574)
		(width 0.0762)
		(layer "F.Cu")
		(net "M_G_CPU0_SA_CA<3>")
	)
	(segment
		(start 395.604238 -254.20701)
		(end 398.144492 -254.20701)
		(width 0.10668)
		(layer "F.Cu")
		(net "M_G_CPU0_SA_CA<3>")
	)
	(segment
		(start 394.044424 -254.09271)
		(end 394.963396 -254.09271)
		(width 0.0762)
		(layer "F.Cu")
		(net "M_G_CPU0_SA_CA<3>")
	)
	(segment
		(start 398.144492 -254.20701)
		(end 399.57502 -252.776482)
		(width 0.10668)
		(layer "F.Cu")
		(net "M_G_CPU0_SA_CA<3>")
	)
	(segment
		(start 410.240988 -251.120402)
		(end 410.028898 -250.908312)
		(width 0.10668)
		(layer "F.Cu")
		(net "M_G_CPU0_SA_CA<3>")
	)
	(segment
		(start 410.73705 -250.03506)
		(end 412.367984 -250.03506)
		(width 0.10668)
		(layer "F.Cu")
		(net "M_G_CPU0_SA_CA<3>")
	)
	(arc
		(start 392.042904 -254.289052)
		(mid 392.051841 -254.170028)
		(end 392.146536 -254.097282)
		(width 0.0762)
		(layer "F.Cu")
		(net "M_G_CPU0_SA_CA<3>")
	)
	(arc
		(start 392.909298 -254.142748)
		(mid 393.092806 -254.097254)
		(end 393.275058 -254.147574)
		(width 0.0762)
		(layer "F.Cu")
		(net "M_G_CPU0_SA_CA<3>")
	)
	(arc
		(start 392.335004 -254.147574)
		(mid 392.61796 -254.223751)
		(end 392.900916 -254.147574)
		(width 0.0762)
		(layer "F.Cu")
		(net "M_G_CPU0_SA_CA<3>")
	)
	(arc
		(start 393.84097 -254.147574)
		(mid 393.939067 -254.106687)
		(end 394.044424 -254.09271)
		(width 0.0762)
		(layer "F.Cu")
		(net "M_G_CPU0_SA_CA<3>")
	)
	(arc
		(start 393.275058 -254.147574)
		(mid 393.558014 -254.223751)
		(end 393.84097 -254.147574)
		(width 0.0762)
		(layer "F.Cu")
		(net "M_G_CPU0_SA_CA<3>")
	)
	(arc
		(start 392.146536 -254.097282)
		(mid 392.23946 -254.108605)
		(end 392.326622 -254.142748)
		(width 0.0762)
		(layer "F.Cu")
		(net "M_G_CPU0_SA_CA<3>")
	)
	(segment
		(start 395.622018 -253.86665)
		(end 398.003268 -253.86665)
		(width 0.10668)
		(layer "F.Cu")
		(net "M_G_CPU0_SA_CA<2>")
	)
	(segment
		(start 392.431016 -253.982474)
		(end 392.431016 -253.982728)
		(width 0.0762)
		(layer "F.Cu")
		(net "M_G_CPU0_SA_CA<2>")
	)
	(segment
		(start 395.581378 -253.82601)
		(end 395.622018 -253.86665)
		(width 0.0762)
		(layer "F.Cu")
		(net "M_G_CPU0_SA_CA<2>")
	)
	(segment
		(start 414.847278 -249.185176)
		(end 416.468052 -249.185176)
		(width 0.101346)
		(layer "F.Cu")
		(net "M_G_CPU0_SA_CA<2>")
	)
	(segment
		(start 407.854404 -252.436122)
		(end 411.362652 -248.927874)
		(width 0.10668)
		(layer "F.Cu")
		(net "M_G_CPU0_SA_CA<2>")
	)
	(segment
		(start 393.736576 -253.987554)
		(end 393.744958 -253.982728)
		(width 0.0762)
		(layer "F.Cu")
		(net "M_G_CPU0_SA_CA<2>")
	)
	(segment
		(start 411.362652 -248.927874)
		(end 411.530292 -248.760234)
		(width 0.101346)
		(layer "F.Cu")
		(net "M_G_CPU0_SA_CA<2>")
	)
	(segment
		(start 399.433796 -252.436122)
		(end 407.854404 -252.436122)
		(width 0.10668)
		(layer "F.Cu")
		(net "M_G_CPU0_SA_CA<2>")
	)
	(segment
		(start 414.422336 -248.760234)
		(end 414.847278 -249.185176)
		(width 0.101346)
		(layer "F.Cu")
		(net "M_G_CPU0_SA_CA<2>")
	)
	(segment
		(start 394.326872 -253.82601)
		(end 395.581378 -253.82601)
		(width 0.0762)
		(layer "F.Cu")
		(net "M_G_CPU0_SA_CA<2>")
	)
	(segment
		(start 411.530292 -248.760234)
		(end 414.422336 -248.760234)
		(width 0.101346)
		(layer "F.Cu")
		(net "M_G_CPU0_SA_CA<2>")
	)
	(segment
		(start 398.003268 -253.86665)
		(end 399.433796 -252.436122)
		(width 0.10668)
		(layer "F.Cu")
		(net "M_G_CPU0_SA_CA<2>")
	)
	(arc
		(start 393.744958 -253.982728)
		(mid 394.025549 -253.865878)
		(end 394.326872 -253.82601)
		(width 0.0762)
		(layer "F.Cu")
		(net "M_G_CPU0_SA_CA<2>")
	)
	(arc
		(start 392.431016 -253.982728)
		(mid 392.61796 -254.032983)
		(end 392.804904 -253.982728)
		(width 0.0762)
		(layer "F.Cu")
		(net "M_G_CPU0_SA_CA<2>")
	)
	(arc
		(start 392.804904 -253.982728)
		(mid 393.08786 -253.906551)
		(end 393.370816 -253.982728)
		(width 0.0762)
		(layer "F.Cu")
		(net "M_G_CPU0_SA_CA<2>")
	)
	(arc
		(start 393.370816 -253.982728)
		(mid 393.553067 -254.033078)
		(end 393.736576 -253.987554)
		(width 0.0762)
		(layer "F.Cu")
		(net "M_G_CPU0_SA_CA<2>")
	)
	(arc
		(start 392.146536 -253.90602)
		(mid 392.293857 -253.925339)
		(end 392.431016 -253.982474)
		(width 0.0762)
		(layer "F.Cu")
		(net "M_G_CPU0_SA_CA<2>")
	)
	(arc
		(start 391.677906 -253.660148)
		(mid 391.881922 -253.840842)
		(end 392.146536 -253.90602)
		(width 0.0762)
		(layer "F.Cu")
		(net "M_G_CPU0_SA_CA<2>")
	)
	(segment
		(start 408.11831 -250.89104)
		(end 408.235404 -250.773946)
		(width 0.10668)
		(layer "F.Cu")
		(net "M_G_CPU0_SA_CA<1>")
	)
	(segment
		(start 409.811474 -249.197876)
		(end 409.928568 -249.080782)
		(width 0.10668)
		(layer "F.Cu")
		(net "M_G_CPU0_SA_CA<1>")
	)
	(segment
		(start 411.217872 -248.335038)
		(end 412.367984 -248.335038)
		(width 0.10668)
		(layer "F.Cu")
		(net "M_G_CPU0_SA_CA<1>")
	)
	(segment
		(start 409.236672 -250.316238)
		(end 409.353766 -250.199144)
		(width 0.10668)
		(layer "F.Cu")
		(net "M_G_CPU0_SA_CA<1>")
	)
	(segment
		(start 408.799792 -250.209558)
		(end 408.964892 -250.209558)
		(width 0.10668)
		(layer "F.Cu")
		(net "M_G_CPU0_SA_CA<1>")
	)
	(segment
		(start 410.482542 -249.070368)
		(end 410.482542 -248.905268)
		(width 0.10668)
		(layer "F.Cu")
		(net "M_G_CPU0_SA_CA<1>")
	)
	(segment
		(start 408.964892 -250.209558)
		(end 409.071572 -250.316238)
		(width 0.10668)
		(layer "F.Cu")
		(net "M_G_CPU0_SA_CA<1>")
	)
	(segment
		(start 409.247086 -249.927364)
		(end 409.247086 -249.762264)
		(width 0.10668)
		(layer "F.Cu")
		(net "M_G_CPU0_SA_CA<1>")
	)
	(segment
		(start 410.365448 -249.187462)
		(end 410.482542 -249.070368)
		(width 0.10668)
		(layer "F.Cu")
		(net "M_G_CPU0_SA_CA<1>")
	)
	(segment
		(start 408.235404 -250.773946)
		(end 408.400504 -250.773946)
		(width 0.10668)
		(layer "F.Cu")
		(net "M_G_CPU0_SA_CA<1>")
	)
	(segment
		(start 407.660602 -251.727208)
		(end 407.553922 -251.620528)
		(width 0.10668)
		(layer "F.Cu")
		(net "M_G_CPU0_SA_CA<1>")
	)
	(segment
		(start 407.553922 -251.620528)
		(end 407.553922 -251.455428)
		(width 0.10668)
		(layer "F.Cu")
		(net "M_G_CPU0_SA_CA<1>")
	)
	(segment
		(start 410.375862 -248.633488)
		(end 410.492956 -248.516394)
		(width 0.10668)
		(layer "F.Cu")
		(net "M_G_CPU0_SA_CA<1>")
	)
	(segment
		(start 408.400504 -250.773946)
		(end 408.507184 -250.880626)
		(width 0.10668)
		(layer "F.Cu")
		(net "M_G_CPU0_SA_CA<1>")
	)
	(segment
		(start 409.80106 -249.75185)
		(end 409.918154 -249.634756)
		(width 0.10668)
		(layer "F.Cu")
		(net "M_G_CPU0_SA_CA<1>")
	)
	(segment
		(start 408.672284 -250.880626)
		(end 408.789378 -250.763532)
		(width 0.10668)
		(layer "F.Cu")
		(net "M_G_CPU0_SA_CA<1>")
	)
	(segment
		(start 407.836116 -251.338334)
		(end 407.942796 -251.445014)
		(width 0.10668)
		(layer "F.Cu")
		(net "M_G_CPU0_SA_CA<1>")
	)
	(segment
		(start 409.63596 -249.75185)
		(end 409.80106 -249.75185)
		(width 0.10668)
		(layer "F.Cu")
		(net "M_G_CPU0_SA_CA<1>")
	)
	(segment
		(start 393.558014 -253.660148)
		(end 393.46505 -253.500128)
		(width 0.0762)
		(layer "F.Cu")
		(net "M_G_CPU0_SA_CA<1>")
	)
	(segment
		(start 408.11831 -251.05614)
		(end 408.11831 -250.89104)
		(width 0.10668)
		(layer "F.Cu")
		(net "M_G_CPU0_SA_CA<1>")
	)
	(segment
		(start 407.942796 -251.445014)
		(end 408.107896 -251.445014)
		(width 0.10668)
		(layer "F.Cu")
		(net "M_G_CPU0_SA_CA<1>")
	)
	(segment
		(start 410.375862 -248.798588)
		(end 410.375862 -248.633488)
		(width 0.10668)
		(layer "F.Cu")
		(net "M_G_CPU0_SA_CA<1>")
	)
	(segment
		(start 393.736576 -253.332742)
		(end 393.744958 -253.337568)
		(width 0.0762)
		(layer "F.Cu")
		(net "M_G_CPU0_SA_CA<1>")
	)
	(segment
		(start 409.353766 -250.199144)
		(end 409.353766 -250.034044)
		(width 0.10668)
		(layer "F.Cu")
		(net "M_G_CPU0_SA_CA<1>")
	)
	(segment
		(start 409.071572 -250.316238)
		(end 409.236672 -250.316238)
		(width 0.10668)
		(layer "F.Cu")
		(net "M_G_CPU0_SA_CA<1>")
	)
	(segment
		(start 408.107896 -251.445014)
		(end 408.22499 -251.32792)
		(width 0.10668)
		(layer "F.Cu")
		(net "M_G_CPU0_SA_CA<1>")
	)
	(segment
		(start 399.292572 -252.095762)
		(end 407.457148 -252.095762)
		(width 0.10668)
		(layer "F.Cu")
		(net "M_G_CPU0_SA_CA<1>")
	)
	(segment
		(start 408.22499 -251.16282)
		(end 408.11831 -251.05614)
		(width 0.10668)
		(layer "F.Cu")
		(net "M_G_CPU0_SA_CA<1>")
	)
	(segment
		(start 409.918154 -249.634756)
		(end 409.918154 -249.469656)
		(width 0.10668)
		(layer "F.Cu")
		(net "M_G_CPU0_SA_CA<1>")
	)
	(segment
		(start 409.918154 -249.469656)
		(end 409.811474 -249.362976)
		(width 0.10668)
		(layer "F.Cu")
		(net "M_G_CPU0_SA_CA<1>")
	)
	(segment
		(start 407.660602 -251.892308)
		(end 407.660602 -251.727208)
		(width 0.10668)
		(layer "F.Cu")
		(net "M_G_CPU0_SA_CA<1>")
	)
	(segment
		(start 410.929836 -248.623074)
		(end 411.217872 -248.335038)
		(width 0.10668)
		(layer "F.Cu")
		(net "M_G_CPU0_SA_CA<1>")
	)
	(segment
		(start 407.671016 -251.338334)
		(end 407.836116 -251.338334)
		(width 0.10668)
		(layer "F.Cu")
		(net "M_G_CPU0_SA_CA<1>")
	)
	(segment
		(start 408.789378 -250.598432)
		(end 408.682698 -250.491752)
		(width 0.10668)
		(layer "F.Cu")
		(net "M_G_CPU0_SA_CA<1>")
	)
	(segment
		(start 408.682698 -250.326652)
		(end 408.799792 -250.209558)
		(width 0.10668)
		(layer "F.Cu")
		(net "M_G_CPU0_SA_CA<1>")
	)
	(segment
		(start 410.200348 -249.187462)
		(end 410.365448 -249.187462)
		(width 0.10668)
		(layer "F.Cu")
		(net "M_G_CPU0_SA_CA<1>")
	)
	(segment
		(start 409.811474 -249.362976)
		(end 409.811474 -249.197876)
		(width 0.10668)
		(layer "F.Cu")
		(net "M_G_CPU0_SA_CA<1>")
	)
	(segment
		(start 407.457148 -252.095762)
		(end 407.660602 -251.892308)
		(width 0.10668)
		(layer "F.Cu")
		(net "M_G_CPU0_SA_CA<1>")
	)
	(segment
		(start 408.789378 -250.763532)
		(end 408.789378 -250.598432)
		(width 0.10668)
		(layer "F.Cu")
		(net "M_G_CPU0_SA_CA<1>")
	)
	(segment
		(start 407.553922 -251.455428)
		(end 407.671016 -251.338334)
		(width 0.10668)
		(layer "F.Cu")
		(net "M_G_CPU0_SA_CA<1>")
	)
	(segment
		(start 408.22499 -251.32792)
		(end 408.22499 -251.16282)
		(width 0.10668)
		(layer "F.Cu")
		(net "M_G_CPU0_SA_CA<1>")
	)
	(segment
		(start 410.482542 -248.905268)
		(end 410.375862 -248.798588)
		(width 0.10668)
		(layer "F.Cu")
		(net "M_G_CPU0_SA_CA<1>")
	)
	(segment
		(start 409.36418 -249.64517)
		(end 409.52928 -249.64517)
		(width 0.10668)
		(layer "F.Cu")
		(net "M_G_CPU0_SA_CA<1>")
	)
	(segment
		(start 409.52928 -249.64517)
		(end 409.63596 -249.75185)
		(width 0.10668)
		(layer "F.Cu")
		(net "M_G_CPU0_SA_CA<1>")
	)
	(segment
		(start 397.862044 -253.52629)
		(end 399.292572 -252.095762)
		(width 0.10668)
		(layer "F.Cu")
		(net "M_G_CPU0_SA_CA<1>")
	)
	(segment
		(start 410.764736 -248.623074)
		(end 410.929836 -248.623074)
		(width 0.10668)
		(layer "F.Cu")
		(net "M_G_CPU0_SA_CA<1>")
	)
	(segment
		(start 409.353766 -250.034044)
		(end 409.247086 -249.927364)
		(width 0.10668)
		(layer "F.Cu")
		(net "M_G_CPU0_SA_CA<1>")
	)
	(segment
		(start 408.507184 -250.880626)
		(end 408.672284 -250.880626)
		(width 0.10668)
		(layer "F.Cu")
		(net "M_G_CPU0_SA_CA<1>")
	)
	(segment
		(start 408.682698 -250.491752)
		(end 408.682698 -250.326652)
		(width 0.10668)
		(layer "F.Cu")
		(net "M_G_CPU0_SA_CA<1>")
	)
	(segment
		(start 394.444728 -253.52629)
		(end 395.626336 -253.52629)
		(width 0.0762)
		(layer "F.Cu")
		(net "M_G_CPU0_SA_CA<1>")
	)
	(segment
		(start 410.093668 -249.080782)
		(end 410.200348 -249.187462)
		(width 0.10668)
		(layer "F.Cu")
		(net "M_G_CPU0_SA_CA<1>")
	)
	(segment
		(start 410.658056 -248.516394)
		(end 410.764736 -248.623074)
		(width 0.10668)
		(layer "F.Cu")
		(net "M_G_CPU0_SA_CA<1>")
	)
	(segment
		(start 410.492956 -248.516394)
		(end 410.658056 -248.516394)
		(width 0.10668)
		(layer "F.Cu")
		(net "M_G_CPU0_SA_CA<1>")
	)
	(segment
		(start 395.626336 -253.52629)
		(end 397.862044 -253.52629)
		(width 0.10668)
		(layer "F.Cu")
		(net "M_G_CPU0_SA_CA<1>")
	)
	(segment
		(start 409.928568 -249.080782)
		(end 410.093668 -249.080782)
		(width 0.10668)
		(layer "F.Cu")
		(net "M_G_CPU0_SA_CA<1>")
	)
	(segment
		(start 409.247086 -249.762264)
		(end 409.36418 -249.64517)
		(width 0.10668)
		(layer "F.Cu")
		(net "M_G_CPU0_SA_CA<1>")
	)
	(arc
		(start 393.744958 -253.337568)
		(mid 394.082341 -253.478286)
		(end 394.444728 -253.52629)
		(width 0.0762)
		(layer "F.Cu")
		(net "M_G_CPU0_SA_CA<1>")
	)
	(arc
		(start 393.46505 -253.500128)
		(mid 393.46521 -253.353567)
		(end 393.596876 -253.289308)
		(width 0.0762)
		(layer "F.Cu")
		(net "M_G_CPU0_SA_CA<1>")
	)
	(arc
		(start 393.596876 -253.289308)
		(mid 393.668884 -253.30409)
		(end 393.736576 -253.332742)
		(width 0.0762)
		(layer "F.Cu")
		(net "M_G_CPU0_SA_CA<1>")
	)
	(segment
		(start 406.77211 -251.755402)
		(end 410.617416 -247.910096)
		(width 0.10668)
		(layer "F.Cu")
		(net "M_G_CPU0_SA_CA<0>")
	)
	(segment
		(start 397.72082 -253.18593)
		(end 399.151348 -251.755402)
		(width 0.10668)
		(layer "F.Cu")
		(net "M_G_CPU0_SA_CA<0>")
	)
	(segment
		(start 394.981176 -253.18593)
		(end 395.604238 -253.18593)
		(width 0.0762)
		(layer "F.Cu")
		(net "M_G_CPU0_SA_CA<0>")
	)
	(segment
		(start 394.937996 -253.22911)
		(end 394.981176 -253.18593)
		(width 0.0762)
		(layer "F.Cu")
		(net "M_G_CPU0_SA_CA<0>")
	)
	(segment
		(start 394.050012 -253.22911)
		(end 394.937996 -253.22911)
		(width 0.0762)
		(layer "F.Cu")
		(net "M_G_CPU0_SA_CA<0>")
	)
	(segment
		(start 399.151348 -251.755402)
		(end 406.77211 -251.755402)
		(width 0.10668)
		(layer "F.Cu")
		(net "M_G_CPU0_SA_CA<0>")
	)
	(segment
		(start 414.611312 -247.910096)
		(end 415.036254 -247.485154)
		(width 0.101346)
		(layer "F.Cu")
		(net "M_G_CPU0_SA_CA<0>")
	)
	(segment
		(start 395.604238 -253.18593)
		(end 397.72082 -253.18593)
		(width 0.10668)
		(layer "F.Cu")
		(net "M_G_CPU0_SA_CA<0>")
	)
	(segment
		(start 411.317694 -247.910096)
		(end 414.611312 -247.910096)
		(width 0.101346)
		(layer "F.Cu")
		(net "M_G_CPU0_SA_CA<0>")
	)
	(segment
		(start 410.617416 -247.910096)
		(end 411.317694 -247.910096)
		(width 0.10668)
		(layer "F.Cu")
		(net "M_G_CPU0_SA_CA<0>")
	)
	(segment
		(start 415.036254 -247.485154)
		(end 416.468052 -247.485154)
		(width 0.101346)
		(layer "F.Cu")
		(net "M_G_CPU0_SA_CA<0>")
	)
	(arc
		(start 393.08786 -252.850142)
		(mid 393.323988 -253.021577)
		(end 393.605512 -253.0983)
		(width 0.0762)
		(layer "F.Cu")
		(net "M_G_CPU0_SA_CA<0>")
	)
	(arc
		(start 393.605512 -253.0983)
		(mid 393.727368 -253.122456)
		(end 393.84097 -253.172722)
		(width 0.0762)
		(layer "F.Cu")
		(net "M_G_CPU0_SA_CA<0>")
	)
	(arc
		(start 393.84097 -253.172722)
		(mid 393.941753 -253.214779)
		(end 394.050012 -253.22911)
		(width 0.0762)
		(layer "F.Cu")
		(net "M_G_CPU0_SA_CA<0>")
	)
	(segment
		(start 398.33296 -250.155202)
		(end 405.924258 -250.155202)
		(width 0.10668)
		(layer "F.Cu")
		(net "M_G_CPU0_RESET_N")
	)
	(segment
		(start 405.924258 -250.155202)
		(end 411.144466 -244.934994)
		(width 0.10668)
		(layer "F.Cu")
		(net "M_G_CPU0_RESET_N")
	)
	(segment
		(start 411.144466 -244.934994)
		(end 412.367984 -244.934994)
		(width 0.10668)
		(layer "F.Cu")
		(net "M_G_CPU0_RESET_N")
	)
	(segment
		(start 393.90828 -250.77039)
		(end 397.717772 -250.77039)
		(width 0.10668)
		(layer "F.Cu")
		(net "M_G_CPU0_RESET_N")
	)
	(segment
		(start 397.717772 -250.77039)
		(end 398.33296 -250.155202)
		(width 0.10668)
		(layer "F.Cu")
		(net "M_G_CPU0_RESET_N")
	)
	(segment
		(start 393.558014 -250.420124)
		(end 393.90828 -250.77039)
		(width 0.10668)
		(layer "F.Cu")
		(net "M_G_CPU0_RESET_N")
	)
	(segment
		(start 394.405358 -256.467102)
		(end 394.630656 -256.6924)
		(width 0.0762)
		(layer "F.Cu")
		(net "M_G_CPU0_CLK_DP<0>")
	)
	(segment
		(start 394.119862 -256.467102)
		(end 394.405358 -256.467102)
		(width 0.0762)
		(layer "F.Cu")
		(net "M_G_CPU0_CLK_DP<0>")
	)
	(segment
		(start 408.377136 -255.948688)
		(end 408.76093 -255.564894)
		(width 0.14732)
		(layer "F.Cu")
		(net "M_G_CPU0_CLK_DP<0>")
	)
	(segment
		(start 406.819862 -255.564894)
		(end 407.363168 -255.564894)
		(width 0.14732)
		(layer "F.Cu")
		(net "M_G_CPU0_CLK_DP<0>")
	)
	(segment
		(start 411.611318 -253.689866)
		(end 411.86608 -253.435104)
		(width 0.14732)
		(layer "F.Cu")
		(net "M_G_CPU0_CLK_DP<0>")
	)
	(segment
		(start 406.25141 -256.7686)
		(end 406.436068 -256.583942)
		(width 0.14732)
		(layer "F.Cu")
		(net "M_G_CPU0_CLK_DP<0>")
	)
	(segment
		(start 394.971778 -256.61747)
		(end 398.336008 -256.61747)
		(width 0.14732)
		(layer "F.Cu")
		(net "M_G_CPU0_CLK_DP<0>")
	)
	(segment
		(start 411.86608 -253.435104)
		(end 412.367984 -253.435104)
		(width 0.14732)
		(layer "F.Cu")
		(net "M_G_CPU0_CLK_DP<0>")
	)
	(segment
		(start 406.436068 -255.948688)
		(end 406.819862 -255.564894)
		(width 0.14732)
		(layer "F.Cu")
		(net "M_G_CPU0_CLK_DP<0>")
	)
	(segment
		(start 407.93162 -256.7686)
		(end 408.192478 -256.7686)
		(width 0.14732)
		(layer "F.Cu")
		(net "M_G_CPU0_CLK_DP<0>")
	)
	(segment
		(start 409.145232 -255.564894)
		(end 411.02026 -253.689866)
		(width 0.14732)
		(layer "F.Cu")
		(net "M_G_CPU0_CLK_DP<0>")
	)
	(segment
		(start 406.436068 -256.583942)
		(end 406.436068 -255.948688)
		(width 0.14732)
		(layer "F.Cu")
		(net "M_G_CPU0_CLK_DP<0>")
	)
	(segment
		(start 394.952728 -256.61747)
		(end 394.971778 -256.61747)
		(width 0.0762)
		(layer "F.Cu")
		(net "M_G_CPU0_CLK_DP<0>")
	)
	(segment
		(start 408.76093 -255.564894)
		(end 409.145232 -255.564894)
		(width 0.14732)
		(layer "F.Cu")
		(net "M_G_CPU0_CLK_DP<0>")
	)
	(segment
		(start 404.547578 -255.564894)
		(end 405.4221 -255.564894)
		(width 0.14732)
		(layer "F.Cu")
		(net "M_G_CPU0_CLK_DP<0>")
	)
	(segment
		(start 407.746962 -256.583942)
		(end 407.93162 -256.7686)
		(width 0.14732)
		(layer "F.Cu")
		(net "M_G_CPU0_CLK_DP<0>")
	)
	(segment
		(start 407.746962 -255.948688)
		(end 407.746962 -256.583942)
		(width 0.14732)
		(layer "F.Cu")
		(net "M_G_CPU0_CLK_DP<0>")
	)
	(segment
		(start 394.877798 -256.6924)
		(end 394.952728 -256.61747)
		(width 0.0762)
		(layer "F.Cu")
		(net "M_G_CPU0_CLK_DP<0>")
	)
	(segment
		(start 408.377136 -256.583942)
		(end 408.377136 -255.948688)
		(width 0.14732)
		(layer "F.Cu")
		(net "M_G_CPU0_CLK_DP<0>")
	)
	(segment
		(start 398.336008 -256.61747)
		(end 400.252946 -254.700532)
		(width 0.14732)
		(layer "F.Cu")
		(net "M_G_CPU0_CLK_DP<0>")
	)
	(segment
		(start 405.990552 -256.7686)
		(end 406.25141 -256.7686)
		(width 0.14732)
		(layer "F.Cu")
		(net "M_G_CPU0_CLK_DP<0>")
	)
	(segment
		(start 408.192478 -256.7686)
		(end 408.377136 -256.583942)
		(width 0.14732)
		(layer "F.Cu")
		(net "M_G_CPU0_CLK_DP<0>")
	)
	(segment
		(start 405.805894 -256.583942)
		(end 405.990552 -256.7686)
		(width 0.14732)
		(layer "F.Cu")
		(net "M_G_CPU0_CLK_DP<0>")
	)
	(segment
		(start 407.363168 -255.564894)
		(end 407.746962 -255.948688)
		(width 0.14732)
		(layer "F.Cu")
		(net "M_G_CPU0_CLK_DP<0>")
	)
	(segment
		(start 411.02026 -253.689866)
		(end 411.611318 -253.689866)
		(width 0.14732)
		(layer "F.Cu")
		(net "M_G_CPU0_CLK_DP<0>")
	)
	(segment
		(start 405.4221 -255.564894)
		(end 405.805894 -255.948688)
		(width 0.14732)
		(layer "F.Cu")
		(net "M_G_CPU0_CLK_DP<0>")
	)
	(segment
		(start 405.805894 -255.948688)
		(end 405.805894 -256.583942)
		(width 0.14732)
		(layer "F.Cu")
		(net "M_G_CPU0_CLK_DP<0>")
	)
	(segment
		(start 403.683216 -254.700532)
		(end 404.547578 -255.564894)
		(width 0.14732)
		(layer "F.Cu")
		(net "M_G_CPU0_CLK_DP<0>")
	)
	(segment
		(start 394.630656 -256.6924)
		(end 394.877798 -256.6924)
		(width 0.0762)
		(layer "F.Cu")
		(net "M_G_CPU0_CLK_DP<0>")
	)
	(segment
		(start 400.252946 -254.700532)
		(end 403.683216 -254.700532)
		(width 0.14732)
		(layer "F.Cu")
		(net "M_G_CPU0_CLK_DP<0>")
	)
	(arc
		(start 393.08786 -256.090166)
		(mid 393.323988 -256.261601)
		(end 393.605512 -256.338324)
		(width 0.0762)
		(layer "F.Cu")
		(net "M_G_CPU0_CLK_DP<0>")
	)
	(arc
		(start 393.605512 -256.338324)
		(mid 393.727368 -256.36248)
		(end 393.84097 -256.412746)
		(width 0.0762)
		(layer "F.Cu")
		(net "M_G_CPU0_CLK_DP<0>")
	)
	(arc
		(start 393.996926 -256.462022)
		(mid 394.058342 -256.465827)
		(end 394.119862 -256.467102)
		(width 0.0762)
		(layer "F.Cu")
		(net "M_G_CPU0_CLK_DP<0>")
	)
	(arc
		(start 393.84097 -256.412746)
		(mid 393.91621 -256.446059)
		(end 393.996926 -256.462022)
		(width 0.0762)
		(layer "F.Cu")
		(net "M_G_CPU0_CLK_DP<0>")
	)
	(segment
		(start 407.406602 -256.725166)
		(end 407.790396 -257.10896)
		(width 0.14732)
		(layer "F.Cu")
		(net "M_G_CPU0_CLK_DN<0>")
	)
	(segment
		(start 393.98067 -256.652014)
		(end 393.981432 -256.65303)
		(width 0.0762)
		(layer "F.Cu")
		(net "M_G_CPU0_CLK_DN<0>")
	)
	(segment
		(start 408.717496 -256.089912)
		(end 408.902154 -255.905254)
		(width 0.14732)
		(layer "F.Cu")
		(net "M_G_CPU0_CLK_DN<0>")
	)
	(segment
		(start 398.477232 -256.95783)
		(end 400.39417 -255.040892)
		(width 0.14732)
		(layer "F.Cu")
		(net "M_G_CPU0_CLK_DN<0>")
	)
	(segment
		(start 406.961086 -255.905254)
		(end 407.221944 -255.905254)
		(width 0.14732)
		(layer "F.Cu")
		(net "M_G_CPU0_CLK_DN<0>")
	)
	(segment
		(start 394.14577 -256.658618)
		(end 394.146786 -256.657602)
		(width 0.0762)
		(layer "F.Cu")
		(net "M_G_CPU0_CLK_DN<0>")
	)
	(segment
		(start 403.541992 -255.040892)
		(end 404.406354 -255.905254)
		(width 0.14732)
		(layer "F.Cu")
		(net "M_G_CPU0_CLK_DN<0>")
	)
	(segment
		(start 405.849328 -257.10896)
		(end 406.392634 -257.10896)
		(width 0.14732)
		(layer "F.Cu")
		(net "M_G_CPU0_CLK_DN<0>")
	)
	(segment
		(start 394.971778 -256.95783)
		(end 398.477232 -256.95783)
		(width 0.14732)
		(layer "F.Cu")
		(net "M_G_CPU0_CLK_DN<0>")
	)
	(segment
		(start 411.86608 -254.284988)
		(end 412.367984 -254.284988)
		(width 0.14732)
		(layer "F.Cu")
		(net "M_G_CPU0_CLK_DN<0>")
	)
	(segment
		(start 406.392634 -257.10896)
		(end 406.776428 -256.725166)
		(width 0.14732)
		(layer "F.Cu")
		(net "M_G_CPU0_CLK_DN<0>")
	)
	(segment
		(start 404.406354 -255.905254)
		(end 405.280876 -255.905254)
		(width 0.14732)
		(layer "F.Cu")
		(net "M_G_CPU0_CLK_DN<0>")
	)
	(segment
		(start 393.558014 -256.900172)
		(end 393.46505 -256.740152)
		(width 0.0762)
		(layer "F.Cu")
		(net "M_G_CPU0_CLK_DN<0>")
	)
	(segment
		(start 393.736576 -256.572766)
		(end 393.744958 -256.577592)
		(width 0.0762)
		(layer "F.Cu")
		(net "M_G_CPU0_CLK_DN<0>")
	)
	(segment
		(start 406.776428 -256.725166)
		(end 406.776428 -256.089912)
		(width 0.14732)
		(layer "F.Cu")
		(net "M_G_CPU0_CLK_DN<0>")
	)
	(segment
		(start 405.465534 -256.089912)
		(end 405.465534 -256.725166)
		(width 0.14732)
		(layer "F.Cu")
		(net "M_G_CPU0_CLK_DN<0>")
	)
	(segment
		(start 405.280876 -255.905254)
		(end 405.465534 -256.089912)
		(width 0.14732)
		(layer "F.Cu")
		(net "M_G_CPU0_CLK_DN<0>")
	)
	(segment
		(start 405.465534 -256.725166)
		(end 405.849328 -257.10896)
		(width 0.14732)
		(layer "F.Cu")
		(net "M_G_CPU0_CLK_DN<0>")
	)
	(segment
		(start 408.333702 -257.10896)
		(end 408.717496 -256.725166)
		(width 0.14732)
		(layer "F.Cu")
		(net "M_G_CPU0_CLK_DN<0>")
	)
	(segment
		(start 400.39417 -255.040892)
		(end 403.541992 -255.040892)
		(width 0.14732)
		(layer "F.Cu")
		(net "M_G_CPU0_CLK_DN<0>")
	)
	(segment
		(start 411.161484 -254.030226)
		(end 411.611318 -254.030226)
		(width 0.14732)
		(layer "F.Cu")
		(net "M_G_CPU0_CLK_DN<0>")
	)
	(segment
		(start 394.146786 -256.657602)
		(end 394.326364 -256.657602)
		(width 0.0762)
		(layer "F.Cu")
		(net "M_G_CPU0_CLK_DN<0>")
	)
	(segment
		(start 407.406602 -256.089912)
		(end 407.406602 -256.725166)
		(width 0.14732)
		(layer "F.Cu")
		(net "M_G_CPU0_CLK_DN<0>")
	)
	(segment
		(start 406.776428 -256.089912)
		(end 406.961086 -255.905254)
		(width 0.14732)
		(layer "F.Cu")
		(net "M_G_CPU0_CLK_DN<0>")
	)
	(segment
		(start 394.877798 -256.8829)
		(end 394.952728 -256.95783)
		(width 0.0762)
		(layer "F.Cu")
		(net "M_G_CPU0_CLK_DN<0>")
	)
	(segment
		(start 394.121894 -256.658618)
		(end 394.14577 -256.658618)
		(width 0.0762)
		(layer "F.Cu")
		(net "M_G_CPU0_CLK_DN<0>")
	)
	(segment
		(start 408.717496 -256.725166)
		(end 408.717496 -256.089912)
		(width 0.14732)
		(layer "F.Cu")
		(net "M_G_CPU0_CLK_DN<0>")
	)
	(segment
		(start 411.611318 -254.030226)
		(end 411.86608 -254.284988)
		(width 0.14732)
		(layer "F.Cu")
		(net "M_G_CPU0_CLK_DN<0>")
	)
	(segment
		(start 408.902154 -255.905254)
		(end 409.286456 -255.905254)
		(width 0.14732)
		(layer "F.Cu")
		(net "M_G_CPU0_CLK_DN<0>")
	)
	(segment
		(start 394.326364 -256.657602)
		(end 394.551662 -256.8829)
		(width 0.0762)
		(layer "F.Cu")
		(net "M_G_CPU0_CLK_DN<0>")
	)
	(segment
		(start 409.286456 -255.905254)
		(end 411.161484 -254.030226)
		(width 0.14732)
		(layer "F.Cu")
		(net "M_G_CPU0_CLK_DN<0>")
	)
	(segment
		(start 407.790396 -257.10896)
		(end 408.333702 -257.10896)
		(width 0.14732)
		(layer "F.Cu")
		(net "M_G_CPU0_CLK_DN<0>")
	)
	(segment
		(start 394.551662 -256.8829)
		(end 394.877798 -256.8829)
		(width 0.0762)
		(layer "F.Cu")
		(net "M_G_CPU0_CLK_DN<0>")
	)
	(segment
		(start 394.952728 -256.95783)
		(end 394.971778 -256.95783)
		(width 0.0762)
		(layer "F.Cu")
		(net "M_G_CPU0_CLK_DN<0>")
	)
	(segment
		(start 407.221944 -255.905254)
		(end 407.406602 -256.089912)
		(width 0.14732)
		(layer "F.Cu")
		(net "M_G_CPU0_CLK_DN<0>")
	)
	(arc
		(start 393.596876 -256.529332)
		(mid 393.668884 -256.544114)
		(end 393.736576 -256.572766)
		(width 0.0762)
		(layer "F.Cu")
		(net "M_G_CPU0_CLK_DN<0>")
	)
	(arc
		(start 393.46505 -256.740152)
		(mid 393.46521 -256.593591)
		(end 393.596876 -256.529332)
		(width 0.0762)
		(layer "F.Cu")
		(net "M_G_CPU0_CLK_DN<0>")
	)
	(arc
		(start 393.744958 -256.577592)
		(mid 393.858682 -256.627893)
		(end 393.98067 -256.652014)
		(width 0.0762)
		(layer "F.Cu")
		(net "M_G_CPU0_CLK_DN<0>")
	)
	(arc
		(start 393.981432 -256.65303)
		(mid 394.051607 -256.657224)
		(end 394.121894 -256.658618)
		(width 0.0762)
		(layer "F.Cu")
		(net "M_G_CPU0_CLK_DN<0>")
	)
	(segment
		(start 397.77543 -250.231148)
		(end 398.191736 -249.814842)
		(width 0.10668)
		(layer "F.Cu")
		(net "M_G_CPU0_ALERT_R_N")
	)
	(segment
		(start 411.08757 -244.510052)
		(end 411.317694 -244.510052)
		(width 0.10668)
		(layer "F.Cu")
		(net "M_G_CPU0_ALERT_R_N")
	)
	(segment
		(start 398.191736 -249.814842)
		(end 405.78278 -249.814842)
		(width 0.10668)
		(layer "F.Cu")
		(net "M_G_CPU0_ALERT_R_N")
	)
	(segment
		(start 411.317694 -244.510052)
		(end 414.64611 -244.510052)
		(width 0.101346)
		(layer "F.Cu")
		(net "M_G_CPU0_ALERT_R_N")
	)
	(segment
		(start 394.699236 -250.23191)
		(end 396.921736 -250.231148)
		(width 0.10668)
		(layer "F.Cu")
		(net "M_G_CPU0_ALERT_R_N")
	)
	(segment
		(start 396.921736 -250.231148)
		(end 397.77543 -250.231148)
		(width 0.10668)
		(layer "F.Cu")
		(net "M_G_CPU0_ALERT_R_N")
	)
	(segment
		(start 393.7889 -249.910092)
		(end 394.037312 -250.05411)
		(width 0.0762)
		(layer "F.Cu")
		(net "M_G_CPU0_ALERT_R_N")
	)
	(segment
		(start 405.78278 -249.814842)
		(end 411.08757 -244.510052)
		(width 0.10668)
		(layer "F.Cu")
		(net "M_G_CPU0_ALERT_R_N")
	)
	(segment
		(start 414.64611 -244.510052)
		(end 415.071052 -244.08511)
		(width 0.101346)
		(layer "F.Cu")
		(net "M_G_CPU0_ALERT_R_N")
	)
	(via
		(at 415.071052 -244.08511)
		(size 0.4826)
		(drill 0.254)
		(layers "F.Cu" "B.Cu")
		(net "M_G_CPU0_ALERT_R_N")
	)
	(arc
		(start 394.037312 -250.05411)
		(mid 394.356537 -250.186697)
		(end 394.699236 -250.23191)
		(width 0.0762)
		(layer "F.Cu")
		(net "M_G_CPU0_ALERT_R_N")
	)
	(arc
		(start 393.605512 -249.858276)
		(mid 393.662698 -249.866052)
		(end 393.718796 -249.879612)
		(width 0.0762)
		(layer "F.Cu")
		(net "M_G_CPU0_ALERT_R_N")
	)
	(arc
		(start 393.08786 -249.610118)
		(mid 393.323988 -249.781553)
		(end 393.605512 -249.858276)
		(width 0.0762)
		(layer "F.Cu")
		(net "M_G_CPU0_ALERT_R_N")
	)
	(arc
		(start 393.718796 -249.879612)
		(mid 393.754749 -249.892779)
		(end 393.7889 -249.910092)
		(width 0.0762)
		(layer "F.Cu")
		(net "M_G_CPU0_ALERT_R_N")
	)
	(via
		(at 416.468052 -244.08511)
		(size 0.4826)
		(drill 0.254)
		(layers "F.Cu" "B.Cu")
		(net "M_G_CPU0_ALERT_N")
	)
	(segment
		(start 415.871152 -244.08511)
		(end 416.468052 -244.08511)
		(width 0.10668)
		(layer "B.Cu")
		(net "M_G_CPU0_ALERT_N")
	)
	(segment
		(start 84.817966 -267.340334)
		(end 84.351114 -267.606272)
		(width 0.10668)
		(layer "F.Cu")
		(net "M_F_CPU1_SB_RSP<0>")
	)
	(segment
		(start 80.769714 -267.933678)
		(end 80.778096 -267.928852)
		(width 0.0889)
		(layer "In11.Cu")
		(net "M_F_CPU1_SB_RSP<0>")
	)
	(segment
		(start 22.691344 -270.165068)
		(end 22.691344 -270.400018)
		(width 0.11684)
		(layer "In11.Cu")
		(net "M_F_CPU1_SB_RSP<0>")
	)
	(segment
		(start 26.272744 -270.318738)
		(end 26.272744 -270.165068)
		(width 0.11684)
		(layer "In11.Cu")
		(net "M_F_CPU1_SB_RSP<0>")
	)
	(segment
		(start 82.284062 -267.928852)
		(end 82.292444 -267.933678)
		(width 0.0889)
		(layer "In11.Cu")
		(net "M_F_CPU1_SB_RSP<0>")
	)
	(segment
		(start 23.747984 -270.165068)
		(end 23.747984 -270.400018)
		(width 0.11684)
		(layer "In11.Cu")
		(net "M_F_CPU1_SB_RSP<0>")
	)
	(segment
		(start 63.405766 -266.851384)
		(end 75.968606 -266.851384)
		(width 0.11684)
		(layer "In11.Cu")
		(net "M_F_CPU1_SB_RSP<0>")
	)
	(segment
		(start 21.70811 -270.435324)
		(end 22.133052 -270.010382)
		(width 0.11684)
		(layer "In11.Cu")
		(net "M_F_CPU1_SB_RSP<0>")
	)
	(segment
		(start 25.744424 -270.165068)
		(end 25.744424 -270.318738)
		(width 0.11684)
		(layer "In11.Cu")
		(net "M_F_CPU1_SB_RSP<0>")
	)
	(segment
		(start 26.118058 -270.473424)
		(end 26.272744 -270.318738)
		(width 0.11684)
		(layer "In11.Cu")
		(net "M_F_CPU1_SB_RSP<0>")
	)
	(segment
		(start 76.944982 -267.364718)
		(end 77.424534 -267.364718)
		(width 0.0889)
		(layer "In11.Cu")
		(net "M_F_CPU1_SB_RSP<0>")
	)
	(segment
		(start 24.43099 -270.010382)
		(end 25.589738 -270.010382)
		(width 0.11684)
		(layer "In11.Cu")
		(net "M_F_CPU1_SB_RSP<0>")
	)
	(segment
		(start 28.815538 -270.010382)
		(end 60.246768 -270.010382)
		(width 0.11684)
		(layer "In11.Cu")
		(net "M_F_CPU1_SB_RSP<0>")
	)
	(segment
		(start 22.133052 -270.010382)
		(end 22.536658 -270.010382)
		(width 0.11684)
		(layer "In11.Cu")
		(net "M_F_CPU1_SB_RSP<0>")
	)
	(segment
		(start 28.287218 -269.719044)
		(end 28.5242 -269.719044)
		(width 0.11684)
		(layer "In11.Cu")
		(net "M_F_CPU1_SB_RSP<0>")
	)
	(segment
		(start 77.424534 -267.364718)
		(end 78.54061 -267.937996)
		(width 0.0889)
		(layer "In11.Cu")
		(net "M_F_CPU1_SB_RSP<0>")
	)
	(segment
		(start 27.230578 -269.719044)
		(end 27.46756 -269.719044)
		(width 0.11684)
		(layer "In11.Cu")
		(net "M_F_CPU1_SB_RSP<0>")
	)
	(segment
		(start 27.46756 -269.719044)
		(end 27.758898 -270.010382)
		(width 0.11684)
		(layer "In11.Cu")
		(net "M_F_CPU1_SB_RSP<0>")
	)
	(segment
		(start 23.747984 -270.400018)
		(end 23.90267 -270.554704)
		(width 0.11684)
		(layer "In11.Cu")
		(net "M_F_CPU1_SB_RSP<0>")
	)
	(segment
		(start 26.42743 -270.010382)
		(end 26.93924 -270.010382)
		(width 0.11684)
		(layer "In11.Cu")
		(net "M_F_CPU1_SB_RSP<0>")
	)
	(segment
		(start 84.482686 -267.955014)
		(end 84.505038 -267.871702)
		(width 0.0889)
		(layer "In11.Cu")
		(net "M_F_CPU1_SB_RSP<0>")
	)
	(segment
		(start 76.431648 -266.851384)
		(end 76.944982 -267.364718)
		(width 0.0889)
		(layer "In11.Cu")
		(net "M_F_CPU1_SB_RSP<0>")
	)
	(segment
		(start 23.219664 -270.400018)
		(end 23.219664 -270.165068)
		(width 0.11684)
		(layer "In11.Cu")
		(net "M_F_CPU1_SB_RSP<0>")
	)
	(segment
		(start 26.93924 -270.010382)
		(end 27.230578 -269.719044)
		(width 0.11684)
		(layer "In11.Cu")
		(net "M_F_CPU1_SB_RSP<0>")
	)
	(segment
		(start 24.276304 -270.400018)
		(end 24.276304 -270.165068)
		(width 0.11684)
		(layer "In11.Cu")
		(net "M_F_CPU1_SB_RSP<0>")
	)
	(segment
		(start 75.968606 -266.851384)
		(end 76.431648 -266.851384)
		(width 0.0889)
		(layer "In11.Cu")
		(net "M_F_CPU1_SB_RSP<0>")
	)
	(segment
		(start 25.744424 -270.318738)
		(end 25.89911 -270.473424)
		(width 0.11684)
		(layer "In11.Cu")
		(net "M_F_CPU1_SB_RSP<0>")
	)
	(segment
		(start 23.219664 -270.165068)
		(end 23.37435 -270.010382)
		(width 0.11684)
		(layer "In11.Cu")
		(net "M_F_CPU1_SB_RSP<0>")
	)
	(segment
		(start 81.344008 -267.928852)
		(end 81.35239 -267.933678)
		(width 0.0889)
		(layer "In11.Cu")
		(net "M_F_CPU1_SB_RSP<0>")
	)
	(segment
		(start 24.121618 -270.554704)
		(end 24.276304 -270.400018)
		(width 0.11684)
		(layer "In11.Cu")
		(net "M_F_CPU1_SB_RSP<0>")
	)
	(segment
		(start 23.593298 -270.010382)
		(end 23.747984 -270.165068)
		(width 0.11684)
		(layer "In11.Cu")
		(net "M_F_CPU1_SB_RSP<0>")
	)
	(segment
		(start 23.37435 -270.010382)
		(end 23.593298 -270.010382)
		(width 0.11684)
		(layer "In11.Cu")
		(net "M_F_CPU1_SB_RSP<0>")
	)
	(segment
		(start 60.246768 -270.010382)
		(end 63.405766 -266.851384)
		(width 0.11684)
		(layer "In11.Cu")
		(net "M_F_CPU1_SB_RSP<0>")
	)
	(segment
		(start 27.758898 -270.010382)
		(end 27.99588 -270.010382)
		(width 0.11684)
		(layer "In11.Cu")
		(net "M_F_CPU1_SB_RSP<0>")
	)
	(segment
		(start 22.691344 -270.400018)
		(end 22.84603 -270.554704)
		(width 0.11684)
		(layer "In11.Cu")
		(net "M_F_CPU1_SB_RSP<0>")
	)
	(segment
		(start 25.89911 -270.473424)
		(end 26.118058 -270.473424)
		(width 0.11684)
		(layer "In11.Cu")
		(net "M_F_CPU1_SB_RSP<0>")
	)
	(segment
		(start 24.276304 -270.165068)
		(end 24.43099 -270.010382)
		(width 0.11684)
		(layer "In11.Cu")
		(net "M_F_CPU1_SB_RSP<0>")
	)
	(segment
		(start 27.99588 -270.010382)
		(end 28.287218 -269.719044)
		(width 0.11684)
		(layer "In11.Cu")
		(net "M_F_CPU1_SB_RSP<0>")
	)
	(segment
		(start 26.272744 -270.165068)
		(end 26.42743 -270.010382)
		(width 0.11684)
		(layer "In11.Cu")
		(net "M_F_CPU1_SB_RSP<0>")
	)
	(segment
		(start 22.536658 -270.010382)
		(end 22.691344 -270.165068)
		(width 0.11684)
		(layer "In11.Cu")
		(net "M_F_CPU1_SB_RSP<0>")
	)
	(segment
		(start 22.84603 -270.554704)
		(end 23.064978 -270.554704)
		(width 0.11684)
		(layer "In11.Cu")
		(net "M_F_CPU1_SB_RSP<0>")
	)
	(segment
		(start 84.505038 -267.871702)
		(end 84.351114 -267.606272)
		(width 0.0889)
		(layer "In11.Cu")
		(net "M_F_CPU1_SB_RSP<0>")
	)
	(segment
		(start 28.5242 -269.719044)
		(end 28.815538 -270.010382)
		(width 0.11684)
		(layer "In11.Cu")
		(net "M_F_CPU1_SB_RSP<0>")
	)
	(segment
		(start 23.90267 -270.554704)
		(end 24.121618 -270.554704)
		(width 0.11684)
		(layer "In11.Cu")
		(net "M_F_CPU1_SB_RSP<0>")
	)
	(segment
		(start 25.589738 -270.010382)
		(end 25.744424 -270.165068)
		(width 0.11684)
		(layer "In11.Cu")
		(net "M_F_CPU1_SB_RSP<0>")
	)
	(segment
		(start 23.064978 -270.554704)
		(end 23.219664 -270.400018)
		(width 0.11684)
		(layer "In11.Cu")
		(net "M_F_CPU1_SB_RSP<0>")
	)
	(arc
		(start 80.403954 -267.928852)
		(mid 80.586205 -267.979202)
		(end 80.769714 -267.933678)
		(width 0.0889)
		(layer "In11.Cu")
		(net "M_F_CPU1_SB_RSP<0>")
	)
	(arc
		(start 82.292444 -267.933678)
		(mid 82.475952 -267.979172)
		(end 82.658204 -267.928852)
		(width 0.0889)
		(layer "In11.Cu")
		(net "M_F_CPU1_SB_RSP<0>")
	)
	(arc
		(start 81.71815 -267.928852)
		(mid 82.001106 -267.852675)
		(end 82.284062 -267.928852)
		(width 0.0889)
		(layer "In11.Cu")
		(net "M_F_CPU1_SB_RSP<0>")
	)
	(arc
		(start 78.898242 -267.928852)
		(mid 79.181198 -267.852675)
		(end 79.464154 -267.928852)
		(width 0.0889)
		(layer "In11.Cu")
		(net "M_F_CPU1_SB_RSP<0>")
	)
	(arc
		(start 83.598004 -267.928852)
		(mid 83.88096 -267.852675)
		(end 84.163916 -267.928852)
		(width 0.0889)
		(layer "In11.Cu")
		(net "M_F_CPU1_SB_RSP<0>")
	)
	(arc
		(start 82.658204 -267.928852)
		(mid 82.94116 -267.852675)
		(end 83.224116 -267.928852)
		(width 0.0889)
		(layer "In11.Cu")
		(net "M_F_CPU1_SB_RSP<0>")
	)
	(arc
		(start 79.838042 -267.928852)
		(mid 80.120998 -267.852675)
		(end 80.403954 -267.928852)
		(width 0.0889)
		(layer "In11.Cu")
		(net "M_F_CPU1_SB_RSP<0>")
	)
	(arc
		(start 79.464154 -267.928852)
		(mid 79.651098 -267.979107)
		(end 79.838042 -267.928852)
		(width 0.0889)
		(layer "In11.Cu")
		(net "M_F_CPU1_SB_RSP<0>")
	)
	(arc
		(start 84.163916 -267.928852)
		(mid 84.320354 -267.977823)
		(end 84.482686 -267.955014)
		(width 0.0889)
		(layer "In11.Cu")
		(net "M_F_CPU1_SB_RSP<0>")
	)
	(arc
		(start 81.35239 -267.933678)
		(mid 81.535898 -267.979172)
		(end 81.71815 -267.928852)
		(width 0.0889)
		(layer "In11.Cu")
		(net "M_F_CPU1_SB_RSP<0>")
	)
	(arc
		(start 80.778096 -267.928852)
		(mid 81.061052 -267.852675)
		(end 81.344008 -267.928852)
		(width 0.0889)
		(layer "In11.Cu")
		(net "M_F_CPU1_SB_RSP<0>")
	)
	(arc
		(start 83.224116 -267.928852)
		(mid 83.41106 -267.979107)
		(end 83.598004 -267.928852)
		(width 0.0889)
		(layer "In11.Cu")
		(net "M_F_CPU1_SB_RSP<0>")
	)
	(arc
		(start 78.54061 -267.937996)
		(mid 78.720592 -267.979096)
		(end 78.898242 -267.928852)
		(width 0.0889)
		(layer "In11.Cu")
		(net "M_F_CPU1_SB_RSP<0>")
	)
	(segment
		(start 85.287866 -264.910316)
		(end 84.821014 -265.176254)
		(width 0.10668)
		(layer "F.Cu")
		(net "M_F_CPU1_SB_PAR")
	)
	(segment
		(start 83.119722 -264.848848)
		(end 83.128104 -264.853674)
		(width 0.0889)
		(layer "In11.Cu")
		(net "M_F_CPU1_SB_PAR")
	)
	(segment
		(start 82.179668 -264.848848)
		(end 82.18805 -264.853674)
		(width 0.0889)
		(layer "In11.Cu")
		(net "M_F_CPU1_SB_PAR")
	)
	(segment
		(start 61.829696 -265.074654)
		(end 75.963526 -265.074654)
		(width 0.14478)
		(layer "In11.Cu")
		(net "M_F_CPU1_SB_PAR")
	)
	(segment
		(start 84.66709 -264.910824)
		(end 84.821014 -265.176254)
		(width 0.0889)
		(layer "In11.Cu")
		(net "M_F_CPU1_SB_PAR")
	)
	(segment
		(start 75.963526 -265.074654)
		(end 76.312776 -265.074654)
		(width 0.0889)
		(layer "In11.Cu")
		(net "M_F_CPU1_SB_PAR")
	)
	(segment
		(start 84.571078 -264.885424)
		(end 84.66709 -264.910824)
		(width 0.0889)
		(layer "In11.Cu")
		(net "M_F_CPU1_SB_PAR")
	)
	(segment
		(start 18.032984 -266.610338)
		(end 60.294012 -266.610338)
		(width 0.14478)
		(layer "In11.Cu")
		(net "M_F_CPU1_SB_PAR")
	)
	(segment
		(start 60.294012 -266.610338)
		(end 61.829696 -265.074654)
		(width 0.14478)
		(layer "In11.Cu")
		(net "M_F_CPU1_SB_PAR")
	)
	(segment
		(start 76.880466 -264.506964)
		(end 77.375258 -264.506964)
		(width 0.0889)
		(layer "In11.Cu")
		(net "M_F_CPU1_SB_PAR")
	)
	(segment
		(start 79.357474 -264.846816)
		(end 79.369158 -264.853674)
		(width 0.0889)
		(layer "In11.Cu")
		(net "M_F_CPU1_SB_PAR")
	)
	(segment
		(start 77.375258 -264.506964)
		(end 77.671422 -264.803128)
		(width 0.0889)
		(layer "In11.Cu")
		(net "M_F_CPU1_SB_PAR")
	)
	(segment
		(start 79.92237 -264.860786)
		(end 79.934308 -264.853928)
		(width 0.0889)
		(layer "In11.Cu")
		(net "M_F_CPU1_SB_PAR")
	)
	(segment
		(start 79.934308 -264.853928)
		(end 79.950564 -264.84453)
		(width 0.0889)
		(layer "In11.Cu")
		(net "M_F_CPU1_SB_PAR")
	)
	(segment
		(start 83.694016 -264.853674)
		(end 83.702398 -264.848848)
		(width 0.0889)
		(layer "In11.Cu")
		(net "M_F_CPU1_SB_PAR")
	)
	(segment
		(start 17.608042 -267.03528)
		(end 18.032984 -266.610338)
		(width 0.14478)
		(layer "In11.Cu")
		(net "M_F_CPU1_SB_PAR")
	)
	(segment
		(start 78.42885 -264.853928)
		(end 78.45044 -264.866374)
		(width 0.0889)
		(layer "In11.Cu")
		(net "M_F_CPU1_SB_PAR")
	)
	(segment
		(start 77.671422 -264.803128)
		(end 78.24216 -264.803128)
		(width 0.0889)
		(layer "In11.Cu")
		(net "M_F_CPU1_SB_PAR")
	)
	(segment
		(start 76.312776 -265.074654)
		(end 76.880466 -264.506964)
		(width 0.0889)
		(layer "In11.Cu")
		(net "M_F_CPU1_SB_PAR")
	)
	(arc
		(start 79.369158 -264.853674)
		(mid 79.644836 -264.929804)
		(end 79.92237 -264.860786)
		(width 0.0889)
		(layer "In11.Cu")
		(net "M_F_CPU1_SB_PAR")
	)
	(arc
		(start 81.247996 -264.853674)
		(mid 81.530952 -264.929851)
		(end 81.813908 -264.853674)
		(width 0.0889)
		(layer "In11.Cu")
		(net "M_F_CPU1_SB_PAR")
	)
	(arc
		(start 78.994762 -264.853674)
		(mid 79.17522 -264.80323)
		(end 79.357474 -264.846816)
		(width 0.0889)
		(layer "In11.Cu")
		(net "M_F_CPU1_SB_PAR")
	)
	(arc
		(start 82.18805 -264.853674)
		(mid 82.471006 -264.929851)
		(end 82.753962 -264.853674)
		(width 0.0889)
		(layer "In11.Cu")
		(net "M_F_CPU1_SB_PAR")
	)
	(arc
		(start 78.24216 -264.803128)
		(mid 78.338851 -264.816224)
		(end 78.42885 -264.853928)
		(width 0.0889)
		(layer "In11.Cu")
		(net "M_F_CPU1_SB_PAR")
	)
	(arc
		(start 81.813908 -264.853674)
		(mid 81.996159 -264.803324)
		(end 82.179668 -264.848848)
		(width 0.0889)
		(layer "In11.Cu")
		(net "M_F_CPU1_SB_PAR")
	)
	(arc
		(start 79.950564 -264.84453)
		(mid 80.130546 -264.80343)
		(end 80.308196 -264.853674)
		(width 0.0889)
		(layer "In11.Cu")
		(net "M_F_CPU1_SB_PAR")
	)
	(arc
		(start 82.753962 -264.853674)
		(mid 82.936213 -264.803324)
		(end 83.119722 -264.848848)
		(width 0.0889)
		(layer "In11.Cu")
		(net "M_F_CPU1_SB_PAR")
	)
	(arc
		(start 84.068158 -264.853674)
		(mid 84.315871 -264.928894)
		(end 84.571078 -264.885424)
		(width 0.0889)
		(layer "In11.Cu")
		(net "M_F_CPU1_SB_PAR")
	)
	(arc
		(start 83.702398 -264.848848)
		(mid 83.885906 -264.803354)
		(end 84.068158 -264.853674)
		(width 0.0889)
		(layer "In11.Cu")
		(net "M_F_CPU1_SB_PAR")
	)
	(arc
		(start 80.308196 -264.853674)
		(mid 80.591152 -264.929851)
		(end 80.874108 -264.853674)
		(width 0.0889)
		(layer "In11.Cu")
		(net "M_F_CPU1_SB_PAR")
	)
	(arc
		(start 83.128104 -264.853674)
		(mid 83.41106 -264.929851)
		(end 83.694016 -264.853674)
		(width 0.0889)
		(layer "In11.Cu")
		(net "M_F_CPU1_SB_PAR")
	)
	(arc
		(start 80.874108 -264.853674)
		(mid 81.061052 -264.803419)
		(end 81.247996 -264.853674)
		(width 0.0889)
		(layer "In11.Cu")
		(net "M_F_CPU1_SB_PAR")
	)
	(arc
		(start 78.45044 -264.866374)
		(mid 78.72423 -264.930045)
		(end 78.994762 -264.853674)
		(width 0.0889)
		(layer "In11.Cu")
		(net "M_F_CPU1_SB_PAR")
	)
	(segment
		(start 84.817966 -270.580358)
		(end 84.351114 -270.846296)
		(width 0.12954)
		(layer "F.Cu")
		(net "M_F_CPU1_SB_DQS_DP<9>")
	)
	(segment
		(start 39.642034 -274.644104)
		(end 39.642034 -275.500084)
		(width 0.16002)
		(layer "In11.Cu")
		(net "M_F_CPU1_SB_DQS_DP<9>")
	)
	(segment
		(start 52.877466 -274.81022)
		(end 53.520086 -275.45284)
		(width 0.16002)
		(layer "In11.Cu")
		(net "M_F_CPU1_SB_DQS_DP<9>")
	)
	(segment
		(start 38.20922 -275.660104)
		(end 38.36924 -275.500084)
		(width 0.16002)
		(layer "In11.Cu")
		(net "M_F_CPU1_SB_DQS_DP<9>")
	)
	(segment
		(start 39.802054 -275.660104)
		(end 41.09339 -275.660104)
		(width 0.16002)
		(layer "In11.Cu")
		(net "M_F_CPU1_SB_DQS_DP<9>")
	)
	(segment
		(start 80.771238 -271.176242)
		(end 80.77962 -271.171416)
		(width 0.09525)
		(layer "In11.Cu")
		(net "M_F_CPU1_SB_DQS_DP<9>")
	)
	(segment
		(start 26.34996 -276.004782)
		(end 26.749248 -276.004782)
		(width 0.16002)
		(layer "In11.Cu")
		(net "M_F_CPU1_SB_DQS_DP<9>")
	)
	(segment
		(start 46.183296 -275.660104)
		(end 48.637444 -275.660104)
		(width 0.16002)
		(layer "In11.Cu")
		(net "M_F_CPU1_SB_DQS_DP<9>")
	)
	(segment
		(start 54.428898 -276.004782)
		(end 56.92521 -276.004782)
		(width 0.16002)
		(layer "In11.Cu")
		(net "M_F_CPU1_SB_DQS_DP<9>")
	)
	(segment
		(start 37.96411 -275.660104)
		(end 38.20922 -275.660104)
		(width 0.16002)
		(layer "In11.Cu")
		(net "M_F_CPU1_SB_DQS_DP<9>")
	)
	(segment
		(start 43.476672 -274.81022)
		(end 45.333412 -274.81022)
		(width 0.16002)
		(layer "In11.Cu")
		(net "M_F_CPU1_SB_DQS_DP<9>")
	)
	(segment
		(start 78.542642 -271.22247)
		(end 79.652114 -271.22247)
		(width 0.09525)
		(layer "In11.Cu")
		(net "M_F_CPU1_SB_DQS_DP<9>")
	)
	(segment
		(start 81.342484 -271.171416)
		(end 81.350866 -271.176242)
		(width 0.09525)
		(layer "In11.Cu")
		(net "M_F_CPU1_SB_DQS_DP<9>")
	)
	(segment
		(start 30.740604 -275.500084)
		(end 30.740604 -274.331684)
		(width 0.16002)
		(layer "In11.Cu")
		(net "M_F_CPU1_SB_DQS_DP<9>")
	)
	(segment
		(start 41.438068 -276.004782)
		(end 41.837356 -276.004782)
		(width 0.16002)
		(layer "In11.Cu")
		(net "M_F_CPU1_SB_DQS_DP<9>")
	)
	(segment
		(start 28.019502 -275.179282)
		(end 28.388564 -274.81022)
		(width 0.16002)
		(layer "In11.Cu")
		(net "M_F_CPU1_SB_DQS_DP<9>")
	)
	(segment
		(start 76.038456 -269.592552)
		(end 76.406502 -269.592552)
		(width 0.09525)
		(layer "In11.Cu")
		(net "M_F_CPU1_SB_DQS_DP<9>")
	)
	(segment
		(start 41.09339 -275.660104)
		(end 41.438068 -276.004782)
		(width 0.16002)
		(layer "In11.Cu")
		(net "M_F_CPU1_SB_DQS_DP<9>")
	)
	(segment
		(start 26.005282 -275.660104)
		(end 26.34996 -276.004782)
		(width 0.16002)
		(layer "In11.Cu")
		(net "M_F_CPU1_SB_DQS_DP<9>")
	)
	(segment
		(start 79.840582 -271.171416)
		(end 79.840328 -271.171416)
		(width 0.09525)
		(layer "In11.Cu")
		(net "M_F_CPU1_SB_DQS_DP<9>")
	)
	(segment
		(start 30.402784 -275.660104)
		(end 30.580584 -275.660104)
		(width 0.16002)
		(layer "In11.Cu")
		(net "M_F_CPU1_SB_DQS_DP<9>")
	)
	(segment
		(start 33.894014 -276.004782)
		(end 34.293302 -276.004782)
		(width 0.16002)
		(layer "In11.Cu")
		(net "M_F_CPU1_SB_DQS_DP<9>")
	)
	(segment
		(start 32.013398 -274.331684)
		(end 32.013398 -275.500084)
		(width 0.16002)
		(layer "In11.Cu")
		(net "M_F_CPU1_SB_DQS_DP<9>")
	)
	(segment
		(start 50.651664 -275.179282)
		(end 51.020726 -274.81022)
		(width 0.16002)
		(layer "In11.Cu")
		(net "M_F_CPU1_SB_DQS_DP<9>")
	)
	(segment
		(start 38.36924 -275.500084)
		(end 38.36924 -274.644104)
		(width 0.16002)
		(layer "In11.Cu")
		(net "M_F_CPU1_SB_DQS_DP<9>")
	)
	(segment
		(start 28.388564 -274.81022)
		(end 29.5529 -274.81022)
		(width 0.16002)
		(layer "In11.Cu")
		(net "M_F_CPU1_SB_DQS_DP<9>")
	)
	(segment
		(start 35.563556 -275.179282)
		(end 35.932618 -274.81022)
		(width 0.16002)
		(layer "In11.Cu")
		(net "M_F_CPU1_SB_DQS_DP<9>")
	)
	(segment
		(start 35.118802 -275.179282)
		(end 35.563556 -275.179282)
		(width 0.16002)
		(layer "In11.Cu")
		(net "M_F_CPU1_SB_DQS_DP<9>")
	)
	(segment
		(start 22.73046 -275.692362)
		(end 23.21052 -275.692362)
		(width 0.16002)
		(layer "In11.Cu")
		(net "M_F_CPU1_SB_DQS_DP<9>")
	)
	(segment
		(start 48.982122 -276.004782)
		(end 49.38141 -276.004782)
		(width 0.16002)
		(layer "In11.Cu")
		(net "M_F_CPU1_SB_DQS_DP<9>")
	)
	(segment
		(start 50.20691 -275.179282)
		(end 50.651664 -275.179282)
		(width 0.16002)
		(layer "In11.Cu")
		(net "M_F_CPU1_SB_DQS_DP<9>")
	)
	(segment
		(start 75.979528 -269.533624)
		(end 76.038456 -269.592552)
		(width 0.09525)
		(layer "In11.Cu")
		(net "M_F_CPU1_SB_DQS_DP<9>")
	)
	(segment
		(start 24.006302 -275.809202)
		(end 24.1554 -275.660104)
		(width 0.16002)
		(layer "In11.Cu")
		(net "M_F_CPU1_SB_DQS_DP<9>")
	)
	(segment
		(start 48.637444 -275.660104)
		(end 48.982122 -276.004782)
		(width 0.16002)
		(layer "In11.Cu")
		(net "M_F_CPU1_SB_DQS_DP<9>")
	)
	(segment
		(start 45.333412 -274.81022)
		(end 46.183296 -275.660104)
		(width 0.16002)
		(layer "In11.Cu")
		(net "M_F_CPU1_SB_DQS_DP<9>")
	)
	(segment
		(start 51.020726 -274.81022)
		(end 52.877466 -274.81022)
		(width 0.16002)
		(layer "In11.Cu")
		(net "M_F_CPU1_SB_DQS_DP<9>")
	)
	(segment
		(start 35.932618 -274.81022)
		(end 37.114226 -274.81022)
		(width 0.16002)
		(layer "In11.Cu")
		(net "M_F_CPU1_SB_DQS_DP<9>")
	)
	(segment
		(start 57.75071 -275.179282)
		(end 59.361578 -275.179282)
		(width 0.16002)
		(layer "In11.Cu")
		(net "M_F_CPU1_SB_DQS_DP<9>")
	)
	(segment
		(start 79.840328 -271.171416)
		(end 79.858362 -271.161002)
		(width 0.09525)
		(layer "In11.Cu")
		(net "M_F_CPU1_SB_DQS_DP<9>")
	)
	(segment
		(start 27.574748 -275.179282)
		(end 28.019502 -275.179282)
		(width 0.16002)
		(layer "In11.Cu")
		(net "M_F_CPU1_SB_DQS_DP<9>")
	)
	(segment
		(start 37.114226 -274.81022)
		(end 37.96411 -275.660104)
		(width 0.16002)
		(layer "In11.Cu")
		(net "M_F_CPU1_SB_DQS_DP<9>")
	)
	(segment
		(start 77.465936 -270.145764)
		(end 78.542642 -271.22247)
		(width 0.09525)
		(layer "In11.Cu")
		(net "M_F_CPU1_SB_DQS_DP<9>")
	)
	(segment
		(start 75.955906 -269.533624)
		(end 75.979528 -269.533624)
		(width 0.09525)
		(layer "In11.Cu")
		(net "M_F_CPU1_SB_DQS_DP<9>")
	)
	(segment
		(start 41.837356 -276.004782)
		(end 42.662856 -275.179282)
		(width 0.16002)
		(layer "In11.Cu")
		(net "M_F_CPU1_SB_DQS_DP<9>")
	)
	(segment
		(start 26.749248 -276.004782)
		(end 27.574748 -275.179282)
		(width 0.16002)
		(layer "In11.Cu")
		(net "M_F_CPU1_SB_DQS_DP<9>")
	)
	(segment
		(start 59.361578 -275.179282)
		(end 65.007236 -269.533624)
		(width 0.16002)
		(layer "In11.Cu")
		(net "M_F_CPU1_SB_DQS_DP<9>")
	)
	(segment
		(start 23.32736 -275.809202)
		(end 24.006302 -275.809202)
		(width 0.16002)
		(layer "In11.Cu")
		(net "M_F_CPU1_SB_DQS_DP<9>")
	)
	(segment
		(start 22.61362 -275.809202)
		(end 22.73046 -275.692362)
		(width 0.16002)
		(layer "In11.Cu")
		(net "M_F_CPU1_SB_DQS_DP<9>")
	)
	(segment
		(start 24.1554 -275.660104)
		(end 26.005282 -275.660104)
		(width 0.16002)
		(layer "In11.Cu")
		(net "M_F_CPU1_SB_DQS_DP<9>")
	)
	(segment
		(start 83.591146 -271.176242)
		(end 83.599528 -271.171416)
		(width 0.09525)
		(layer "In11.Cu")
		(net "M_F_CPU1_SB_DQS_DP<9>")
	)
	(segment
		(start 65.007236 -269.533624)
		(end 75.955906 -269.533624)
		(width 0.16002)
		(layer "In11.Cu")
		(net "M_F_CPU1_SB_DQS_DP<9>")
	)
	(segment
		(start 39.642034 -275.500084)
		(end 39.802054 -275.660104)
		(width 0.16002)
		(layer "In11.Cu")
		(net "M_F_CPU1_SB_DQS_DP<9>")
	)
	(segment
		(start 30.740604 -274.331684)
		(end 31.077662 -273.994626)
		(width 0.16002)
		(layer "In11.Cu")
		(net "M_F_CPU1_SB_DQS_DP<9>")
	)
	(segment
		(start 31.077662 -273.994626)
		(end 31.67634 -273.994626)
		(width 0.16002)
		(layer "In11.Cu")
		(net "M_F_CPU1_SB_DQS_DP<9>")
	)
	(segment
		(start 76.406502 -269.592552)
		(end 76.959714 -270.145764)
		(width 0.09525)
		(layer "In11.Cu")
		(net "M_F_CPU1_SB_DQS_DP<9>")
	)
	(segment
		(start 39.304976 -274.307046)
		(end 39.642034 -274.644104)
		(width 0.16002)
		(layer "In11.Cu")
		(net "M_F_CPU1_SB_DQS_DP<9>")
	)
	(segment
		(start 29.5529 -274.81022)
		(end 30.402784 -275.660104)
		(width 0.16002)
		(layer "In11.Cu")
		(net "M_F_CPU1_SB_DQS_DP<9>")
	)
	(segment
		(start 42.662856 -275.179282)
		(end 43.10761 -275.179282)
		(width 0.16002)
		(layer "In11.Cu")
		(net "M_F_CPU1_SB_DQS_DP<9>")
	)
	(segment
		(start 56.92521 -276.004782)
		(end 57.75071 -275.179282)
		(width 0.16002)
		(layer "In11.Cu")
		(net "M_F_CPU1_SB_DQS_DP<9>")
	)
	(segment
		(start 23.21052 -275.692362)
		(end 23.32736 -275.809202)
		(width 0.16002)
		(layer "In11.Cu")
		(net "M_F_CPU1_SB_DQS_DP<9>")
	)
	(segment
		(start 38.706298 -274.307046)
		(end 39.304976 -274.307046)
		(width 0.16002)
		(layer "In11.Cu")
		(net "M_F_CPU1_SB_DQS_DP<9>")
	)
	(segment
		(start 76.959714 -270.145764)
		(end 77.465936 -270.145764)
		(width 0.09525)
		(layer "In11.Cu")
		(net "M_F_CPU1_SB_DQS_DP<9>")
	)
	(segment
		(start 53.876956 -275.45284)
		(end 54.428898 -276.004782)
		(width 0.16002)
		(layer "In11.Cu")
		(net "M_F_CPU1_SB_DQS_DP<9>")
	)
	(segment
		(start 33.549336 -275.660104)
		(end 33.894014 -276.004782)
		(width 0.16002)
		(layer "In11.Cu")
		(net "M_F_CPU1_SB_DQS_DP<9>")
	)
	(segment
		(start 32.013398 -275.500084)
		(end 32.173418 -275.660104)
		(width 0.16002)
		(layer "In11.Cu")
		(net "M_F_CPU1_SB_DQS_DP<9>")
	)
	(segment
		(start 43.10761 -275.179282)
		(end 43.476672 -274.81022)
		(width 0.16002)
		(layer "In11.Cu")
		(net "M_F_CPU1_SB_DQS_DP<9>")
	)
	(segment
		(start 38.36924 -274.644104)
		(end 38.706298 -274.307046)
		(width 0.16002)
		(layer "In11.Cu")
		(net "M_F_CPU1_SB_DQS_DP<9>")
	)
	(segment
		(start 53.520086 -275.45284)
		(end 53.876956 -275.45284)
		(width 0.16002)
		(layer "In11.Cu")
		(net "M_F_CPU1_SB_DQS_DP<9>")
	)
	(segment
		(start 79.840328 -271.17167)
		(end 79.840582 -271.171416)
		(width 0.09525)
		(layer "In11.Cu")
		(net "M_F_CPU1_SB_DQS_DP<9>")
	)
	(segment
		(start 34.293302 -276.004782)
		(end 35.118802 -275.179282)
		(width 0.16002)
		(layer "In11.Cu")
		(net "M_F_CPU1_SB_DQS_DP<9>")
	)
	(segment
		(start 21.70811 -275.53539)
		(end 21.981922 -275.809202)
		(width 0.16002)
		(layer "In11.Cu")
		(net "M_F_CPU1_SB_DQS_DP<9>")
	)
	(segment
		(start 31.67634 -273.994626)
		(end 32.013398 -274.331684)
		(width 0.16002)
		(layer "In11.Cu")
		(net "M_F_CPU1_SB_DQS_DP<9>")
	)
	(segment
		(start 21.981922 -275.809202)
		(end 22.61362 -275.809202)
		(width 0.16002)
		(layer "In11.Cu")
		(net "M_F_CPU1_SB_DQS_DP<9>")
	)
	(segment
		(start 32.173418 -275.660104)
		(end 33.549336 -275.660104)
		(width 0.16002)
		(layer "In11.Cu")
		(net "M_F_CPU1_SB_DQS_DP<9>")
	)
	(segment
		(start 84.505038 -271.111726)
		(end 84.351114 -270.846296)
		(width 0.09525)
		(layer "In11.Cu")
		(net "M_F_CPU1_SB_DQS_DP<9>")
	)
	(segment
		(start 84.48167 -271.198594)
		(end 84.505038 -271.111726)
		(width 0.09525)
		(layer "In11.Cu")
		(net "M_F_CPU1_SB_DQS_DP<9>")
	)
	(segment
		(start 30.580584 -275.660104)
		(end 30.740604 -275.500084)
		(width 0.16002)
		(layer "In11.Cu")
		(net "M_F_CPU1_SB_DQS_DP<9>")
	)
	(segment
		(start 49.38141 -276.004782)
		(end 50.20691 -275.179282)
		(width 0.16002)
		(layer "In11.Cu")
		(net "M_F_CPU1_SB_DQS_DP<9>")
	)
	(arc
		(start 82.659474 -271.171416)
		(mid 82.940906 -271.095661)
		(end 83.222338 -271.171416)
		(width 0.09525)
		(layer "In11.Cu")
		(net "M_F_CPU1_SB_DQS_DP<9>")
	)
	(arc
		(start 81.719674 -271.171416)
		(mid 82.001106 -271.095661)
		(end 82.282538 -271.171416)
		(width 0.09525)
		(layer "In11.Cu")
		(net "M_F_CPU1_SB_DQS_DP<9>")
	)
	(arc
		(start 80.40243 -271.171416)
		(mid 80.586205 -271.222188)
		(end 80.771238 -271.176242)
		(width 0.09525)
		(layer "In11.Cu")
		(net "M_F_CPU1_SB_DQS_DP<9>")
	)
	(arc
		(start 80.77962 -271.171416)
		(mid 81.061052 -271.095661)
		(end 81.342484 -271.171416)
		(width 0.09525)
		(layer "In11.Cu")
		(net "M_F_CPU1_SB_DQS_DP<9>")
	)
	(arc
		(start 79.652114 -271.22247)
		(mid 79.749575 -271.209489)
		(end 79.840328 -271.17167)
		(width 0.09525)
		(layer "In11.Cu")
		(net "M_F_CPU1_SB_DQS_DP<9>")
	)
	(arc
		(start 82.282538 -271.171416)
		(mid 82.471006 -271.222093)
		(end 82.659474 -271.171416)
		(width 0.09525)
		(layer "In11.Cu")
		(net "M_F_CPU1_SB_DQS_DP<9>")
	)
	(arc
		(start 83.222338 -271.171416)
		(mid 83.406113 -271.222188)
		(end 83.591146 -271.176242)
		(width 0.09525)
		(layer "In11.Cu")
		(net "M_F_CPU1_SB_DQS_DP<9>")
	)
	(arc
		(start 79.858362 -271.161002)
		(mid 80.131742 -271.095781)
		(end 80.40243 -271.171416)
		(width 0.09525)
		(layer "In11.Cu")
		(net "M_F_CPU1_SB_DQS_DP<9>")
	)
	(arc
		(start 81.350866 -271.176242)
		(mid 81.535898 -271.222156)
		(end 81.719674 -271.171416)
		(width 0.09525)
		(layer "In11.Cu")
		(net "M_F_CPU1_SB_DQS_DP<9>")
	)
	(arc
		(start 83.599528 -271.171416)
		(mid 83.88096 -271.095661)
		(end 84.162392 -271.171416)
		(width 0.09525)
		(layer "In11.Cu")
		(net "M_F_CPU1_SB_DQS_DP<9>")
	)
	(arc
		(start 84.162392 -271.171416)
		(mid 84.31899 -271.220705)
		(end 84.48167 -271.198594)
		(width 0.09525)
		(layer "In11.Cu")
		(net "M_F_CPU1_SB_DQS_DP<9>")
	)
	(segment
		(start 86.69782 -291.64026)
		(end 86.230968 -291.906198)
		(width 0.12954)
		(layer "F.Cu")
		(net "M_F_CPU1_SB_DQS_DP<8>")
	)
	(segment
		(start 26.83129 -315.040518)
		(end 27.715464 -314.156344)
		(width 0.16002)
		(layer "In11.Cu")
		(net "M_F_CPU1_SB_DQS_DP<8>")
	)
	(segment
		(start 24.071072 -315.360558)
		(end 26.03373 -315.360558)
		(width 0.16002)
		(layer "In11.Cu")
		(net "M_F_CPU1_SB_DQS_DP<8>")
	)
	(segment
		(start 41.121838 -315.360558)
		(end 41.441878 -315.040518)
		(width 0.16002)
		(layer "In11.Cu")
		(net "M_F_CPU1_SB_DQS_DP<8>")
	)
	(segment
		(start 30.731714 -314.51042)
		(end 31.581852 -315.360558)
		(width 0.16002)
		(layer "In11.Cu")
		(net "M_F_CPU1_SB_DQS_DP<8>")
	)
	(segment
		(start 43.459654 -314.51042)
		(end 45.819822 -314.51042)
		(width 0.16002)
		(layer "In11.Cu")
		(net "M_F_CPU1_SB_DQS_DP<8>")
	)
	(segment
		(start 85.976206 -291.614098)
		(end 86.077044 -291.640768)
		(width 0.09525)
		(layer "In11.Cu")
		(net "M_F_CPU1_SB_DQS_DP<8>")
	)
	(segment
		(start 27.715464 -314.156344)
		(end 28.01747 -314.156344)
		(width 0.16002)
		(layer "In11.Cu")
		(net "M_F_CPU1_SB_DQS_DP<8>")
	)
	(segment
		(start 86.077044 -291.640768)
		(end 86.230968 -291.906198)
		(width 0.09525)
		(layer "In11.Cu")
		(net "M_F_CPU1_SB_DQS_DP<8>")
	)
	(segment
		(start 77.8764 -295.927272)
		(end 77.8764 -293.711884)
		(width 0.09525)
		(layer "In11.Cu")
		(net "M_F_CPU1_SB_DQS_DP<8>")
	)
	(segment
		(start 49.463452 -315.040518)
		(end 50.347626 -314.156344)
		(width 0.16002)
		(layer "In11.Cu")
		(net "M_F_CPU1_SB_DQS_DP<8>")
	)
	(segment
		(start 19.7612 -314.361322)
		(end 19.926808 -314.195714)
		(width 0.16002)
		(layer "In11.Cu")
		(net "M_F_CPU1_SB_DQS_DP<8>")
	)
	(segment
		(start 35.561524 -314.156344)
		(end 35.9156 -314.51042)
		(width 0.16002)
		(layer "In11.Cu")
		(net "M_F_CPU1_SB_DQS_DP<8>")
	)
	(segment
		(start 39.125906 -315.360558)
		(end 41.121838 -315.360558)
		(width 0.16002)
		(layer "In11.Cu")
		(net "M_F_CPU1_SB_DQS_DP<8>")
	)
	(segment
		(start 77.8764 -293.711884)
		(end 79.835248 -291.753036)
		(width 0.09525)
		(layer "In11.Cu")
		(net "M_F_CPU1_SB_DQS_DP<8>")
	)
	(segment
		(start 23.252684 -314.54217)
		(end 24.071072 -315.360558)
		(width 0.16002)
		(layer "In11.Cu")
		(net "M_F_CPU1_SB_DQS_DP<8>")
	)
	(segment
		(start 45.819822 -314.51042)
		(end 46.66996 -315.360558)
		(width 0.16002)
		(layer "In11.Cu")
		(net "M_F_CPU1_SB_DQS_DP<8>")
	)
	(segment
		(start 20.516088 -314.195714)
		(end 20.862544 -314.54217)
		(width 0.16002)
		(layer "In11.Cu")
		(net "M_F_CPU1_SB_DQS_DP<8>")
	)
	(segment
		(start 26.03373 -315.360558)
		(end 26.35377 -315.040518)
		(width 0.16002)
		(layer "In11.Cu")
		(net "M_F_CPU1_SB_DQS_DP<8>")
	)
	(segment
		(start 38.275768 -314.51042)
		(end 39.125906 -315.360558)
		(width 0.16002)
		(layer "In11.Cu")
		(net "M_F_CPU1_SB_DQS_DP<8>")
	)
	(segment
		(start 85.102446 -291.581078)
		(end 85.110828 -291.576252)
		(width 0.09525)
		(layer "In11.Cu")
		(net "M_F_CPU1_SB_DQS_DP<8>")
	)
	(segment
		(start 81.342484 -291.581078)
		(end 81.350866 -291.576252)
		(width 0.09525)
		(layer "In11.Cu")
		(net "M_F_CPU1_SB_DQS_DP<8>")
	)
	(segment
		(start 48.665892 -315.360558)
		(end 48.985932 -315.040518)
		(width 0.16002)
		(layer "In11.Cu")
		(net "M_F_CPU1_SB_DQS_DP<8>")
	)
	(segment
		(start 31.581852 -315.360558)
		(end 33.577784 -315.360558)
		(width 0.16002)
		(layer "In11.Cu")
		(net "M_F_CPU1_SB_DQS_DP<8>")
	)
	(segment
		(start 48.985932 -315.040518)
		(end 49.463452 -315.040518)
		(width 0.16002)
		(layer "In11.Cu")
		(net "M_F_CPU1_SB_DQS_DP<8>")
	)
	(segment
		(start 80.067404 -291.65677)
		(end 80.120998 -291.65677)
		(width 0.09525)
		(layer "In11.Cu")
		(net "M_F_CPU1_SB_DQS_DP<8>")
	)
	(segment
		(start 80.771238 -291.576252)
		(end 80.77962 -291.581078)
		(width 0.09525)
		(layer "In11.Cu")
		(net "M_F_CPU1_SB_DQS_DP<8>")
	)
	(segment
		(start 46.66996 -315.360558)
		(end 48.665892 -315.360558)
		(width 0.16002)
		(layer "In11.Cu")
		(net "M_F_CPU1_SB_DQS_DP<8>")
	)
	(segment
		(start 77.50048 -296.38625)
		(end 77.517244 -296.369486)
		(width 0.09525)
		(layer "In11.Cu")
		(net "M_F_CPU1_SB_DQS_DP<8>")
	)
	(segment
		(start 50.347626 -314.156344)
		(end 50.649632 -314.156344)
		(width 0.16002)
		(layer "In11.Cu")
		(net "M_F_CPU1_SB_DQS_DP<8>")
	)
	(segment
		(start 19.926808 -314.195714)
		(end 20.516088 -314.195714)
		(width 0.16002)
		(layer "In11.Cu")
		(net "M_F_CPU1_SB_DQS_DP<8>")
	)
	(segment
		(start 53.893974 -315.040518)
		(end 57.007252 -315.040518)
		(width 0.16002)
		(layer "In11.Cu")
		(net "M_F_CPU1_SB_DQS_DP<8>")
	)
	(segment
		(start 79.835248 -291.753036)
		(end 80.067404 -291.65677)
		(width 0.09525)
		(layer "In11.Cu")
		(net "M_F_CPU1_SB_DQS_DP<8>")
	)
	(segment
		(start 51.003708 -314.51042)
		(end 53.363876 -314.51042)
		(width 0.16002)
		(layer "In11.Cu")
		(net "M_F_CPU1_SB_DQS_DP<8>")
	)
	(segment
		(start 59.730386 -314.156344)
		(end 77.50048 -296.38625)
		(width 0.16002)
		(layer "In11.Cu")
		(net "M_F_CPU1_SB_DQS_DP<8>")
	)
	(segment
		(start 42.803572 -314.156344)
		(end 43.105578 -314.156344)
		(width 0.16002)
		(layer "In11.Cu")
		(net "M_F_CPU1_SB_DQS_DP<8>")
	)
	(segment
		(start 41.919398 -315.040518)
		(end 42.803572 -314.156344)
		(width 0.16002)
		(layer "In11.Cu")
		(net "M_F_CPU1_SB_DQS_DP<8>")
	)
	(segment
		(start 28.371546 -314.51042)
		(end 30.731714 -314.51042)
		(width 0.16002)
		(layer "In11.Cu")
		(net "M_F_CPU1_SB_DQS_DP<8>")
	)
	(segment
		(start 28.01747 -314.156344)
		(end 28.371546 -314.51042)
		(width 0.16002)
		(layer "In11.Cu")
		(net "M_F_CPU1_SB_DQS_DP<8>")
	)
	(segment
		(start 33.897824 -315.040518)
		(end 34.375344 -315.040518)
		(width 0.16002)
		(layer "In11.Cu")
		(net "M_F_CPU1_SB_DQS_DP<8>")
	)
	(segment
		(start 33.577784 -315.360558)
		(end 33.897824 -315.040518)
		(width 0.16002)
		(layer "In11.Cu")
		(net "M_F_CPU1_SB_DQS_DP<8>")
	)
	(segment
		(start 17.608042 -314.635388)
		(end 17.882108 -314.361322)
		(width 0.16002)
		(layer "In11.Cu")
		(net "M_F_CPU1_SB_DQS_DP<8>")
	)
	(segment
		(start 43.105578 -314.156344)
		(end 43.459654 -314.51042)
		(width 0.16002)
		(layer "In11.Cu")
		(net "M_F_CPU1_SB_DQS_DP<8>")
	)
	(segment
		(start 26.35377 -315.040518)
		(end 26.83129 -315.040518)
		(width 0.16002)
		(layer "In11.Cu")
		(net "M_F_CPU1_SB_DQS_DP<8>")
	)
	(segment
		(start 41.441878 -315.040518)
		(end 41.919398 -315.040518)
		(width 0.16002)
		(layer "In11.Cu")
		(net "M_F_CPU1_SB_DQS_DP<8>")
	)
	(segment
		(start 83.591146 -291.576252)
		(end 83.599528 -291.581078)
		(width 0.09525)
		(layer "In11.Cu")
		(net "M_F_CPU1_SB_DQS_DP<8>")
	)
	(segment
		(start 20.862544 -314.54217)
		(end 23.252684 -314.54217)
		(width 0.16002)
		(layer "In11.Cu")
		(net "M_F_CPU1_SB_DQS_DP<8>")
	)
	(segment
		(start 57.007252 -315.040518)
		(end 57.891426 -314.156344)
		(width 0.16002)
		(layer "In11.Cu")
		(net "M_F_CPU1_SB_DQS_DP<8>")
	)
	(segment
		(start 50.649632 -314.156344)
		(end 51.003708 -314.51042)
		(width 0.16002)
		(layer "In11.Cu")
		(net "M_F_CPU1_SB_DQS_DP<8>")
	)
	(segment
		(start 35.259518 -314.156344)
		(end 35.561524 -314.156344)
		(width 0.16002)
		(layer "In11.Cu")
		(net "M_F_CPU1_SB_DQS_DP<8>")
	)
	(segment
		(start 17.882108 -314.361322)
		(end 19.7612 -314.361322)
		(width 0.16002)
		(layer "In11.Cu")
		(net "M_F_CPU1_SB_DQS_DP<8>")
	)
	(segment
		(start 53.363876 -314.51042)
		(end 53.893974 -315.040518)
		(width 0.16002)
		(layer "In11.Cu")
		(net "M_F_CPU1_SB_DQS_DP<8>")
	)
	(segment
		(start 84.5312 -291.576252)
		(end 84.539582 -291.581078)
		(width 0.09525)
		(layer "In11.Cu")
		(net "M_F_CPU1_SB_DQS_DP<8>")
	)
	(segment
		(start 57.891426 -314.156344)
		(end 59.730386 -314.156344)
		(width 0.16002)
		(layer "In11.Cu")
		(net "M_F_CPU1_SB_DQS_DP<8>")
	)
	(segment
		(start 77.517244 -296.286428)
		(end 77.8764 -295.927272)
		(width 0.09525)
		(layer "In11.Cu")
		(net "M_F_CPU1_SB_DQS_DP<8>")
	)
	(segment
		(start 35.9156 -314.51042)
		(end 38.275768 -314.51042)
		(width 0.16002)
		(layer "In11.Cu")
		(net "M_F_CPU1_SB_DQS_DP<8>")
	)
	(segment
		(start 77.517244 -296.369486)
		(end 77.517244 -296.286428)
		(width 0.09525)
		(layer "In11.Cu")
		(net "M_F_CPU1_SB_DQS_DP<8>")
	)
	(segment
		(start 34.375344 -315.040518)
		(end 35.259518 -314.156344)
		(width 0.16002)
		(layer "In11.Cu")
		(net "M_F_CPU1_SB_DQS_DP<8>")
	)
	(arc
		(start 80.40243 -291.581078)
		(mid 80.586205 -291.530306)
		(end 80.771238 -291.576252)
		(width 0.09525)
		(layer "In11.Cu")
		(net "M_F_CPU1_SB_DQS_DP<8>")
	)
	(arc
		(start 81.719674 -291.581078)
		(mid 82.001106 -291.656833)
		(end 82.282538 -291.581078)
		(width 0.09525)
		(layer "In11.Cu")
		(net "M_F_CPU1_SB_DQS_DP<8>")
	)
	(arc
		(start 85.110828 -291.576252)
		(mid 85.29586 -291.530338)
		(end 85.479636 -291.581078)
		(width 0.09525)
		(layer "In11.Cu")
		(net "M_F_CPU1_SB_DQS_DP<8>")
	)
	(arc
		(start 81.350866 -291.576252)
		(mid 81.535898 -291.530338)
		(end 81.719674 -291.581078)
		(width 0.09525)
		(layer "In11.Cu")
		(net "M_F_CPU1_SB_DQS_DP<8>")
	)
	(arc
		(start 82.282538 -291.581078)
		(mid 82.471006 -291.530401)
		(end 82.659474 -291.581078)
		(width 0.09525)
		(layer "In11.Cu")
		(net "M_F_CPU1_SB_DQS_DP<8>")
	)
	(arc
		(start 80.120998 -291.65677)
		(mid 80.266706 -291.637502)
		(end 80.40243 -291.581078)
		(width 0.09525)
		(layer "In11.Cu")
		(net "M_F_CPU1_SB_DQS_DP<8>")
	)
	(arc
		(start 85.955886 -291.621972)
		(mid 85.966085 -291.618135)
		(end 85.976206 -291.614098)
		(width 0.09525)
		(layer "In11.Cu")
		(net "M_F_CPU1_SB_DQS_DP<8>")
	)
	(arc
		(start 84.162392 -291.581078)
		(mid 84.346167 -291.530306)
		(end 84.5312 -291.576252)
		(width 0.09525)
		(layer "In11.Cu")
		(net "M_F_CPU1_SB_DQS_DP<8>")
	)
	(arc
		(start 85.479636 -291.581078)
		(mid 85.71318 -291.654784)
		(end 85.955886 -291.621972)
		(width 0.09525)
		(layer "In11.Cu")
		(net "M_F_CPU1_SB_DQS_DP<8>")
	)
	(arc
		(start 80.77962 -291.581078)
		(mid 81.061052 -291.656833)
		(end 81.342484 -291.581078)
		(width 0.09525)
		(layer "In11.Cu")
		(net "M_F_CPU1_SB_DQS_DP<8>")
	)
	(arc
		(start 83.599528 -291.581078)
		(mid 83.88096 -291.656833)
		(end 84.162392 -291.581078)
		(width 0.09525)
		(layer "In11.Cu")
		(net "M_F_CPU1_SB_DQS_DP<8>")
	)
	(arc
		(start 82.659474 -291.581078)
		(mid 82.940906 -291.656833)
		(end 83.222338 -291.581078)
		(width 0.09525)
		(layer "In11.Cu")
		(net "M_F_CPU1_SB_DQS_DP<8>")
	)
	(arc
		(start 83.222338 -291.581078)
		(mid 83.406113 -291.530306)
		(end 83.591146 -291.576252)
		(width 0.09525)
		(layer "In11.Cu")
		(net "M_F_CPU1_SB_DQS_DP<8>")
	)
	(arc
		(start 84.539582 -291.581078)
		(mid 84.821014 -291.656833)
		(end 85.102446 -291.581078)
		(width 0.09525)
		(layer "In11.Cu")
		(net "M_F_CPU1_SB_DQS_DP<8>")
	)
	(segment
		(start 86.69782 -286.780478)
		(end 86.230968 -287.046162)
		(width 0.12954)
		(layer "F.Cu")
		(net "M_F_CPU1_SB_DQS_DP<7>")
	)
	(segment
		(start 23.252684 -305.192176)
		(end 20.862544 -305.192176)
		(width 0.16002)
		(layer "In11.Cu")
		(net "M_F_CPU1_SB_DQS_DP<7>")
	)
	(segment
		(start 42.803572 -304.80635)
		(end 41.919398 -305.690524)
		(width 0.16002)
		(layer "In11.Cu")
		(net "M_F_CPU1_SB_DQS_DP<7>")
	)
	(segment
		(start 50.347626 -304.80635)
		(end 49.463452 -305.690524)
		(width 0.16002)
		(layer "In11.Cu")
		(net "M_F_CPU1_SB_DQS_DP<7>")
	)
	(segment
		(start 80.40243 -286.721042)
		(end 80.392016 -286.727138)
		(width 0.09525)
		(layer "In11.Cu")
		(net "M_F_CPU1_SB_DQS_DP<7>")
	)
	(segment
		(start 59.276488 -304.80635)
		(end 57.891426 -304.80635)
		(width 0.16002)
		(layer "In11.Cu")
		(net "M_F_CPU1_SB_DQS_DP<7>")
	)
	(segment
		(start 78.444852 -286.77997)
		(end 78.111096 -287.113726)
		(width 0.09525)
		(layer "In11.Cu")
		(net "M_F_CPU1_SB_DQS_DP<7>")
	)
	(segment
		(start 76.18603 -287.81375)
		(end 76.185776 -287.897062)
		(width 0.09525)
		(layer "In11.Cu")
		(net "M_F_CPU1_SB_DQS_DP<7>")
	)
	(segment
		(start 24.071072 -306.010564)
		(end 23.252684 -305.192176)
		(width 0.16002)
		(layer "In11.Cu")
		(net "M_F_CPU1_SB_DQS_DP<7>")
	)
	(segment
		(start 49.463452 -305.690524)
		(end 48.985932 -305.690524)
		(width 0.16002)
		(layer "In11.Cu")
		(net "M_F_CPU1_SB_DQS_DP<7>")
	)
	(segment
		(start 46.66996 -306.010564)
		(end 45.819822 -305.160426)
		(width 0.16002)
		(layer "In11.Cu")
		(net "M_F_CPU1_SB_DQS_DP<7>")
	)
	(segment
		(start 26.03373 -306.010564)
		(end 24.071072 -306.010564)
		(width 0.16002)
		(layer "In11.Cu")
		(net "M_F_CPU1_SB_DQS_DP<7>")
	)
	(segment
		(start 79.462122 -286.721042)
		(end 79.453232 -286.726376)
		(width 0.09525)
		(layer "In11.Cu")
		(net "M_F_CPU1_SB_DQS_DP<7>")
	)
	(segment
		(start 19.926808 -304.84572)
		(end 19.7612 -305.011328)
		(width 0.16002)
		(layer "In11.Cu")
		(net "M_F_CPU1_SB_DQS_DP<7>")
	)
	(segment
		(start 48.985932 -305.690524)
		(end 48.665892 -306.010564)
		(width 0.16002)
		(layer "In11.Cu")
		(net "M_F_CPU1_SB_DQS_DP<7>")
	)
	(segment
		(start 48.665892 -306.010564)
		(end 46.66996 -306.010564)
		(width 0.16002)
		(layer "In11.Cu")
		(net "M_F_CPU1_SB_DQS_DP<7>")
	)
	(segment
		(start 78.111096 -287.113726)
		(end 76.88707 -287.113726)
		(width 0.09525)
		(layer "In11.Cu")
		(net "M_F_CPU1_SB_DQS_DP<7>")
	)
	(segment
		(start 45.819822 -305.160426)
		(end 43.459654 -305.160426)
		(width 0.16002)
		(layer "In11.Cu")
		(net "M_F_CPU1_SB_DQS_DP<7>")
	)
	(segment
		(start 34.375344 -305.690524)
		(end 33.897824 -305.690524)
		(width 0.16002)
		(layer "In11.Cu")
		(net "M_F_CPU1_SB_DQS_DP<7>")
	)
	(segment
		(start 50.649632 -304.80635)
		(end 50.347626 -304.80635)
		(width 0.16002)
		(layer "In11.Cu")
		(net "M_F_CPU1_SB_DQS_DP<7>")
	)
	(segment
		(start 39.125906 -306.010564)
		(end 38.275768 -305.160426)
		(width 0.16002)
		(layer "In11.Cu")
		(net "M_F_CPU1_SB_DQS_DP<7>")
	)
	(segment
		(start 33.897824 -305.690524)
		(end 33.577784 -306.010564)
		(width 0.16002)
		(layer "In11.Cu")
		(net "M_F_CPU1_SB_DQS_DP<7>")
	)
	(segment
		(start 85.110828 -286.716216)
		(end 85.102446 -286.721042)
		(width 0.09525)
		(layer "In11.Cu")
		(net "M_F_CPU1_SB_DQS_DP<7>")
	)
	(segment
		(start 57.007252 -305.690524)
		(end 53.893974 -305.690524)
		(width 0.16002)
		(layer "In11.Cu")
		(net "M_F_CPU1_SB_DQS_DP<7>")
	)
	(segment
		(start 86.077044 -286.780732)
		(end 85.976206 -286.754062)
		(width 0.09525)
		(layer "In11.Cu")
		(net "M_F_CPU1_SB_DQS_DP<7>")
	)
	(segment
		(start 41.441878 -305.690524)
		(end 41.121838 -306.010564)
		(width 0.16002)
		(layer "In11.Cu")
		(net "M_F_CPU1_SB_DQS_DP<7>")
	)
	(segment
		(start 57.891426 -304.80635)
		(end 57.007252 -305.690524)
		(width 0.16002)
		(layer "In11.Cu")
		(net "M_F_CPU1_SB_DQS_DP<7>")
	)
	(segment
		(start 41.121838 -306.010564)
		(end 39.125906 -306.010564)
		(width 0.16002)
		(layer "In11.Cu")
		(net "M_F_CPU1_SB_DQS_DP<7>")
	)
	(segment
		(start 41.919398 -305.690524)
		(end 41.441878 -305.690524)
		(width 0.16002)
		(layer "In11.Cu")
		(net "M_F_CPU1_SB_DQS_DP<7>")
	)
	(segment
		(start 27.715464 -304.80635)
		(end 26.83129 -305.690524)
		(width 0.16002)
		(layer "In11.Cu")
		(net "M_F_CPU1_SB_DQS_DP<7>")
	)
	(segment
		(start 28.01747 -304.80635)
		(end 27.715464 -304.80635)
		(width 0.16002)
		(layer "In11.Cu")
		(net "M_F_CPU1_SB_DQS_DP<7>")
	)
	(segment
		(start 26.35377 -305.690524)
		(end 26.03373 -306.010564)
		(width 0.16002)
		(layer "In11.Cu")
		(net "M_F_CPU1_SB_DQS_DP<7>")
	)
	(segment
		(start 43.459654 -305.160426)
		(end 43.105578 -304.80635)
		(width 0.16002)
		(layer "In11.Cu")
		(net "M_F_CPU1_SB_DQS_DP<7>")
	)
	(segment
		(start 19.7612 -305.011328)
		(end 17.882108 -305.011328)
		(width 0.16002)
		(layer "In11.Cu")
		(net "M_F_CPU1_SB_DQS_DP<7>")
	)
	(segment
		(start 79.470504 -286.716216)
		(end 79.462122 -286.721042)
		(width 0.09525)
		(layer "In11.Cu")
		(net "M_F_CPU1_SB_DQS_DP<7>")
	)
	(segment
		(start 53.363876 -305.160426)
		(end 51.003708 -305.160426)
		(width 0.16002)
		(layer "In11.Cu")
		(net "M_F_CPU1_SB_DQS_DP<7>")
	)
	(segment
		(start 76.185776 -287.897062)
		(end 76.169012 -287.913826)
		(width 0.09525)
		(layer "In11.Cu")
		(net "M_F_CPU1_SB_DQS_DP<7>")
	)
	(segment
		(start 20.516088 -304.84572)
		(end 19.926808 -304.84572)
		(width 0.16002)
		(layer "In11.Cu")
		(net "M_F_CPU1_SB_DQS_DP<7>")
	)
	(segment
		(start 53.893974 -305.690524)
		(end 53.363876 -305.160426)
		(width 0.16002)
		(layer "In11.Cu")
		(net "M_F_CPU1_SB_DQS_DP<7>")
	)
	(segment
		(start 81.350866 -286.716216)
		(end 81.342484 -286.721042)
		(width 0.09525)
		(layer "In11.Cu")
		(net "M_F_CPU1_SB_DQS_DP<7>")
	)
	(segment
		(start 31.581852 -306.010564)
		(end 30.731714 -305.160426)
		(width 0.16002)
		(layer "In11.Cu")
		(net "M_F_CPU1_SB_DQS_DP<7>")
	)
	(segment
		(start 78.899512 -286.721296)
		(end 78.885542 -286.713422)
		(width 0.09525)
		(layer "In11.Cu")
		(net "M_F_CPU1_SB_DQS_DP<7>")
	)
	(segment
		(start 84.539582 -286.721042)
		(end 84.5312 -286.716216)
		(width 0.09525)
		(layer "In11.Cu")
		(net "M_F_CPU1_SB_DQS_DP<7>")
	)
	(segment
		(start 28.371546 -305.160426)
		(end 28.01747 -304.80635)
		(width 0.16002)
		(layer "In11.Cu")
		(net "M_F_CPU1_SB_DQS_DP<7>")
	)
	(segment
		(start 35.259518 -304.80635)
		(end 34.375344 -305.690524)
		(width 0.16002)
		(layer "In11.Cu")
		(net "M_F_CPU1_SB_DQS_DP<7>")
	)
	(segment
		(start 35.9156 -305.160426)
		(end 35.561524 -304.80635)
		(width 0.16002)
		(layer "In11.Cu")
		(net "M_F_CPU1_SB_DQS_DP<7>")
	)
	(segment
		(start 51.003708 -305.160426)
		(end 50.649632 -304.80635)
		(width 0.16002)
		(layer "In11.Cu")
		(net "M_F_CPU1_SB_DQS_DP<7>")
	)
	(segment
		(start 20.862544 -305.192176)
		(end 20.516088 -304.84572)
		(width 0.16002)
		(layer "In11.Cu")
		(net "M_F_CPU1_SB_DQS_DP<7>")
	)
	(segment
		(start 26.83129 -305.690524)
		(end 26.35377 -305.690524)
		(width 0.16002)
		(layer "In11.Cu")
		(net "M_F_CPU1_SB_DQS_DP<7>")
	)
	(segment
		(start 76.88707 -287.113726)
		(end 76.18603 -287.81375)
		(width 0.09525)
		(layer "In11.Cu")
		(net "M_F_CPU1_SB_DQS_DP<7>")
	)
	(segment
		(start 17.882108 -305.011328)
		(end 17.608042 -305.285394)
		(width 0.16002)
		(layer "In11.Cu")
		(net "M_F_CPU1_SB_DQS_DP<7>")
	)
	(segment
		(start 83.599528 -286.721042)
		(end 83.591146 -286.716216)
		(width 0.09525)
		(layer "In11.Cu")
		(net "M_F_CPU1_SB_DQS_DP<7>")
	)
	(segment
		(start 30.731714 -305.160426)
		(end 28.371546 -305.160426)
		(width 0.16002)
		(layer "In11.Cu")
		(net "M_F_CPU1_SB_DQS_DP<7>")
	)
	(segment
		(start 33.577784 -306.010564)
		(end 31.581852 -306.010564)
		(width 0.16002)
		(layer "In11.Cu")
		(net "M_F_CPU1_SB_DQS_DP<7>")
	)
	(segment
		(start 76.169012 -287.913826)
		(end 59.276488 -304.80635)
		(width 0.16002)
		(layer "In11.Cu")
		(net "M_F_CPU1_SB_DQS_DP<7>")
	)
	(segment
		(start 43.105578 -304.80635)
		(end 42.803572 -304.80635)
		(width 0.16002)
		(layer "In11.Cu")
		(net "M_F_CPU1_SB_DQS_DP<7>")
	)
	(segment
		(start 86.230968 -287.046162)
		(end 86.077044 -286.780732)
		(width 0.09525)
		(layer "In11.Cu")
		(net "M_F_CPU1_SB_DQS_DP<7>")
	)
	(segment
		(start 80.77962 -286.721042)
		(end 80.771238 -286.716216)
		(width 0.09525)
		(layer "In11.Cu")
		(net "M_F_CPU1_SB_DQS_DP<7>")
	)
	(segment
		(start 35.561524 -304.80635)
		(end 35.259518 -304.80635)
		(width 0.16002)
		(layer "In11.Cu")
		(net "M_F_CPU1_SB_DQS_DP<7>")
	)
	(segment
		(start 38.275768 -305.160426)
		(end 35.9156 -305.160426)
		(width 0.16002)
		(layer "In11.Cu")
		(net "M_F_CPU1_SB_DQS_DP<7>")
	)
	(arc
		(start 78.522322 -286.721042)
		(mid 78.509077 -286.728906)
		(end 78.49616 -286.737298)
		(width 0.09525)
		(layer "In11.Cu")
		(net "M_F_CPU1_SB_DQS_DP<7>")
	)
	(arc
		(start 85.955886 -286.76219)
		(mid 85.713144 -286.794975)
		(end 85.479636 -286.721042)
		(width 0.09525)
		(layer "In11.Cu")
		(net "M_F_CPU1_SB_DQS_DP<7>")
	)
	(arc
		(start 80.392016 -286.727138)
		(mid 80.114854 -286.79697)
		(end 79.839312 -286.721042)
		(width 0.09525)
		(layer "In11.Cu")
		(net "M_F_CPU1_SB_DQS_DP<7>")
	)
	(arc
		(start 78.49616 -286.737298)
		(mid 78.469556 -286.757492)
		(end 78.444852 -286.77997)
		(width 0.09525)
		(layer "In11.Cu")
		(net "M_F_CPU1_SB_DQS_DP<7>")
	)
	(arc
		(start 81.719674 -286.721042)
		(mid 81.535899 -286.67027)
		(end 81.350866 -286.716216)
		(width 0.09525)
		(layer "In11.Cu")
		(net "M_F_CPU1_SB_DQS_DP<7>")
	)
	(arc
		(start 85.102446 -286.721042)
		(mid 84.821014 -286.796831)
		(end 84.539582 -286.721042)
		(width 0.09525)
		(layer "In11.Cu")
		(net "M_F_CPU1_SB_DQS_DP<7>")
	)
	(arc
		(start 82.659474 -286.721042)
		(mid 82.471006 -286.670365)
		(end 82.282538 -286.721042)
		(width 0.09525)
		(layer "In11.Cu")
		(net "M_F_CPU1_SB_DQS_DP<7>")
	)
	(arc
		(start 85.479636 -286.721042)
		(mid 85.295861 -286.67027)
		(end 85.110828 -286.716216)
		(width 0.09525)
		(layer "In11.Cu")
		(net "M_F_CPU1_SB_DQS_DP<7>")
	)
	(arc
		(start 85.976206 -286.754062)
		(mid 85.966085 -286.758224)
		(end 85.955886 -286.76219)
		(width 0.09525)
		(layer "In11.Cu")
		(net "M_F_CPU1_SB_DQS_DP<7>")
	)
	(arc
		(start 81.342484 -286.721042)
		(mid 81.061052 -286.796831)
		(end 80.77962 -286.721042)
		(width 0.09525)
		(layer "In11.Cu")
		(net "M_F_CPU1_SB_DQS_DP<7>")
	)
	(arc
		(start 84.5312 -286.716216)
		(mid 84.346168 -286.670302)
		(end 84.162392 -286.721042)
		(width 0.09525)
		(layer "In11.Cu")
		(net "M_F_CPU1_SB_DQS_DP<7>")
	)
	(arc
		(start 83.222338 -286.721042)
		(mid 82.940906 -286.796831)
		(end 82.659474 -286.721042)
		(width 0.09525)
		(layer "In11.Cu")
		(net "M_F_CPU1_SB_DQS_DP<7>")
	)
	(arc
		(start 84.162392 -286.721042)
		(mid 83.88096 -286.796831)
		(end 83.599528 -286.721042)
		(width 0.09525)
		(layer "In11.Cu")
		(net "M_F_CPU1_SB_DQS_DP<7>")
	)
	(arc
		(start 79.453232 -286.726376)
		(mid 79.175715 -286.796928)
		(end 78.899512 -286.721296)
		(width 0.09525)
		(layer "In11.Cu")
		(net "M_F_CPU1_SB_DQS_DP<7>")
	)
	(arc
		(start 79.839312 -286.721042)
		(mid 79.655537 -286.67027)
		(end 79.470504 -286.716216)
		(width 0.09525)
		(layer "In11.Cu")
		(net "M_F_CPU1_SB_DQS_DP<7>")
	)
	(arc
		(start 83.591146 -286.716216)
		(mid 83.406114 -286.670302)
		(end 83.222338 -286.721042)
		(width 0.09525)
		(layer "In11.Cu")
		(net "M_F_CPU1_SB_DQS_DP<7>")
	)
	(arc
		(start 80.771238 -286.716216)
		(mid 80.586206 -286.670302)
		(end 80.40243 -286.721042)
		(width 0.09525)
		(layer "In11.Cu")
		(net "M_F_CPU1_SB_DQS_DP<7>")
	)
	(arc
		(start 78.885542 -286.713422)
		(mid 78.702944 -286.670406)
		(end 78.522322 -286.721042)
		(width 0.09525)
		(layer "In11.Cu")
		(net "M_F_CPU1_SB_DQS_DP<7>")
	)
	(arc
		(start 82.282538 -286.721042)
		(mid 82.001106 -286.796831)
		(end 81.719674 -286.721042)
		(width 0.09525)
		(layer "In11.Cu")
		(net "M_F_CPU1_SB_DQS_DP<7>")
	)
	(segment
		(start 86.69782 -281.920442)
		(end 86.230968 -282.18638)
		(width 0.12954)
		(layer "F.Cu")
		(net "M_F_CPU1_SB_DQS_DP<6>")
	)
	(segment
		(start 80.392016 -281.867356)
		(end 80.40243 -281.86126)
		(width 0.09525)
		(layer "In11.Cu")
		(net "M_F_CPU1_SB_DQS_DP<6>")
	)
	(segment
		(start 79.6798 -281.728164)
		(end 79.724504 -281.772868)
		(width 0.09525)
		(layer "In11.Cu")
		(net "M_F_CPU1_SB_DQS_DP<6>")
	)
	(segment
		(start 73.312782 -281.974544)
		(end 75.955906 -281.974544)
		(width 0.16002)
		(layer "In11.Cu")
		(net "M_F_CPU1_SB_DQS_DP<6>")
	)
	(segment
		(start 17.608042 -295.9354)
		(end 17.882108 -295.661334)
		(width 0.16002)
		(layer "In11.Cu")
		(net "M_F_CPU1_SB_DQS_DP<6>")
	)
	(segment
		(start 39.125906 -296.66057)
		(end 41.121838 -296.66057)
		(width 0.16002)
		(layer "In11.Cu")
		(net "M_F_CPU1_SB_DQS_DP<6>")
	)
	(segment
		(start 31.581852 -296.66057)
		(end 33.577784 -296.66057)
		(width 0.16002)
		(layer "In11.Cu")
		(net "M_F_CPU1_SB_DQS_DP<6>")
	)
	(segment
		(start 75.955906 -281.974544)
		(end 75.979528 -281.974544)
		(width 0.09525)
		(layer "In11.Cu")
		(net "M_F_CPU1_SB_DQS_DP<6>")
	)
	(segment
		(start 46.66996 -296.66057)
		(end 48.665892 -296.66057)
		(width 0.16002)
		(layer "In11.Cu")
		(net "M_F_CPU1_SB_DQS_DP<6>")
	)
	(segment
		(start 43.459654 -295.810432)
		(end 45.819822 -295.810432)
		(width 0.16002)
		(layer "In11.Cu")
		(net "M_F_CPU1_SB_DQS_DP<6>")
	)
	(segment
		(start 48.665892 -296.66057)
		(end 48.985932 -296.34053)
		(width 0.16002)
		(layer "In11.Cu")
		(net "M_F_CPU1_SB_DQS_DP<6>")
	)
	(segment
		(start 75.979528 -281.974544)
		(end 76.038456 -281.915616)
		(width 0.09525)
		(layer "In11.Cu")
		(net "M_F_CPU1_SB_DQS_DP<6>")
	)
	(segment
		(start 50.347626 -295.456356)
		(end 50.649632 -295.456356)
		(width 0.16002)
		(layer "In11.Cu")
		(net "M_F_CPU1_SB_DQS_DP<6>")
	)
	(segment
		(start 41.121838 -296.66057)
		(end 41.441878 -296.34053)
		(width 0.16002)
		(layer "In11.Cu")
		(net "M_F_CPU1_SB_DQS_DP<6>")
	)
	(segment
		(start 42.803572 -295.456356)
		(end 43.105578 -295.456356)
		(width 0.16002)
		(layer "In11.Cu")
		(net "M_F_CPU1_SB_DQS_DP<6>")
	)
	(segment
		(start 50.649632 -295.456356)
		(end 51.003708 -295.810432)
		(width 0.16002)
		(layer "In11.Cu")
		(net "M_F_CPU1_SB_DQS_DP<6>")
	)
	(segment
		(start 28.01747 -295.456356)
		(end 28.371546 -295.810432)
		(width 0.16002)
		(layer "In11.Cu")
		(net "M_F_CPU1_SB_DQS_DP<6>")
	)
	(segment
		(start 76.038456 -281.915616)
		(end 77.305662 -281.915616)
		(width 0.09525)
		(layer "In11.Cu")
		(net "M_F_CPU1_SB_DQS_DP<6>")
	)
	(segment
		(start 35.561524 -295.456356)
		(end 35.9156 -295.810432)
		(width 0.16002)
		(layer "In11.Cu")
		(net "M_F_CPU1_SB_DQS_DP<6>")
	)
	(segment
		(start 41.919398 -296.34053)
		(end 42.803572 -295.456356)
		(width 0.16002)
		(layer "In11.Cu")
		(net "M_F_CPU1_SB_DQS_DP<6>")
	)
	(segment
		(start 26.83129 -296.34053)
		(end 27.715464 -295.456356)
		(width 0.16002)
		(layer "In11.Cu")
		(net "M_F_CPU1_SB_DQS_DP<6>")
	)
	(segment
		(start 77.493114 -281.728164)
		(end 79.6798 -281.728164)
		(width 0.09525)
		(layer "In11.Cu")
		(net "M_F_CPU1_SB_DQS_DP<6>")
	)
	(segment
		(start 45.819822 -295.810432)
		(end 46.66996 -296.66057)
		(width 0.16002)
		(layer "In11.Cu")
		(net "M_F_CPU1_SB_DQS_DP<6>")
	)
	(segment
		(start 85.102446 -281.86126)
		(end 85.110828 -281.856434)
		(width 0.09525)
		(layer "In11.Cu")
		(net "M_F_CPU1_SB_DQS_DP<6>")
	)
	(segment
		(start 17.882108 -295.661334)
		(end 19.7612 -295.661334)
		(width 0.16002)
		(layer "In11.Cu")
		(net "M_F_CPU1_SB_DQS_DP<6>")
	)
	(segment
		(start 49.463452 -296.34053)
		(end 50.347626 -295.456356)
		(width 0.16002)
		(layer "In11.Cu")
		(net "M_F_CPU1_SB_DQS_DP<6>")
	)
	(segment
		(start 20.862544 -295.842182)
		(end 23.252684 -295.842182)
		(width 0.16002)
		(layer "In11.Cu")
		(net "M_F_CPU1_SB_DQS_DP<6>")
	)
	(segment
		(start 83.591146 -281.856434)
		(end 83.599528 -281.86126)
		(width 0.09525)
		(layer "In11.Cu")
		(net "M_F_CPU1_SB_DQS_DP<6>")
	)
	(segment
		(start 20.516088 -295.495726)
		(end 20.862544 -295.842182)
		(width 0.16002)
		(layer "In11.Cu")
		(net "M_F_CPU1_SB_DQS_DP<6>")
	)
	(segment
		(start 30.731714 -295.810432)
		(end 31.581852 -296.66057)
		(width 0.16002)
		(layer "In11.Cu")
		(net "M_F_CPU1_SB_DQS_DP<6>")
	)
	(segment
		(start 80.771238 -281.856434)
		(end 80.77962 -281.86126)
		(width 0.09525)
		(layer "In11.Cu")
		(net "M_F_CPU1_SB_DQS_DP<6>")
	)
	(segment
		(start 86.077044 -281.92095)
		(end 86.230968 -282.18638)
		(width 0.09525)
		(layer "In11.Cu")
		(net "M_F_CPU1_SB_DQS_DP<6>")
	)
	(segment
		(start 35.9156 -295.810432)
		(end 38.275768 -295.810432)
		(width 0.16002)
		(layer "In11.Cu")
		(net "M_F_CPU1_SB_DQS_DP<6>")
	)
	(segment
		(start 38.275768 -295.810432)
		(end 39.125906 -296.66057)
		(width 0.16002)
		(layer "In11.Cu")
		(net "M_F_CPU1_SB_DQS_DP<6>")
	)
	(segment
		(start 53.893974 -296.34053)
		(end 57.007252 -296.34053)
		(width 0.16002)
		(layer "In11.Cu")
		(net "M_F_CPU1_SB_DQS_DP<6>")
	)
	(segment
		(start 19.7612 -295.661334)
		(end 19.926808 -295.495726)
		(width 0.16002)
		(layer "In11.Cu")
		(net "M_F_CPU1_SB_DQS_DP<6>")
	)
	(segment
		(start 59.83097 -295.456356)
		(end 73.312782 -281.974544)
		(width 0.16002)
		(layer "In11.Cu")
		(net "M_F_CPU1_SB_DQS_DP<6>")
	)
	(segment
		(start 34.375344 -296.34053)
		(end 35.259518 -295.456356)
		(width 0.16002)
		(layer "In11.Cu")
		(net "M_F_CPU1_SB_DQS_DP<6>")
	)
	(segment
		(start 35.259518 -295.456356)
		(end 35.561524 -295.456356)
		(width 0.16002)
		(layer "In11.Cu")
		(net "M_F_CPU1_SB_DQS_DP<6>")
	)
	(segment
		(start 28.371546 -295.810432)
		(end 30.731714 -295.810432)
		(width 0.16002)
		(layer "In11.Cu")
		(net "M_F_CPU1_SB_DQS_DP<6>")
	)
	(segment
		(start 57.891426 -295.456356)
		(end 59.83097 -295.456356)
		(width 0.16002)
		(layer "In11.Cu")
		(net "M_F_CPU1_SB_DQS_DP<6>")
	)
	(segment
		(start 85.976206 -281.89428)
		(end 86.077044 -281.92095)
		(width 0.09525)
		(layer "In11.Cu")
		(net "M_F_CPU1_SB_DQS_DP<6>")
	)
	(segment
		(start 33.577784 -296.66057)
		(end 33.897824 -296.34053)
		(width 0.16002)
		(layer "In11.Cu")
		(net "M_F_CPU1_SB_DQS_DP<6>")
	)
	(segment
		(start 19.926808 -295.495726)
		(end 20.516088 -295.495726)
		(width 0.16002)
		(layer "In11.Cu")
		(net "M_F_CPU1_SB_DQS_DP<6>")
	)
	(segment
		(start 23.252684 -295.842182)
		(end 24.071072 -296.66057)
		(width 0.16002)
		(layer "In11.Cu")
		(net "M_F_CPU1_SB_DQS_DP<6>")
	)
	(segment
		(start 84.5312 -281.856434)
		(end 84.539582 -281.86126)
		(width 0.09525)
		(layer "In11.Cu")
		(net "M_F_CPU1_SB_DQS_DP<6>")
	)
	(segment
		(start 51.003708 -295.810432)
		(end 53.363876 -295.810432)
		(width 0.16002)
		(layer "In11.Cu")
		(net "M_F_CPU1_SB_DQS_DP<6>")
	)
	(segment
		(start 43.105578 -295.456356)
		(end 43.459654 -295.810432)
		(width 0.16002)
		(layer "In11.Cu")
		(net "M_F_CPU1_SB_DQS_DP<6>")
	)
	(segment
		(start 48.985932 -296.34053)
		(end 49.463452 -296.34053)
		(width 0.16002)
		(layer "In11.Cu")
		(net "M_F_CPU1_SB_DQS_DP<6>")
	)
	(segment
		(start 26.35377 -296.34053)
		(end 26.83129 -296.34053)
		(width 0.16002)
		(layer "In11.Cu")
		(net "M_F_CPU1_SB_DQS_DP<6>")
	)
	(segment
		(start 53.363876 -295.810432)
		(end 53.893974 -296.34053)
		(width 0.16002)
		(layer "In11.Cu")
		(net "M_F_CPU1_SB_DQS_DP<6>")
	)
	(segment
		(start 41.441878 -296.34053)
		(end 41.919398 -296.34053)
		(width 0.16002)
		(layer "In11.Cu")
		(net "M_F_CPU1_SB_DQS_DP<6>")
	)
	(segment
		(start 81.342484 -281.86126)
		(end 81.350866 -281.856434)
		(width 0.09525)
		(layer "In11.Cu")
		(net "M_F_CPU1_SB_DQS_DP<6>")
	)
	(segment
		(start 24.071072 -296.66057)
		(end 26.03373 -296.66057)
		(width 0.16002)
		(layer "In11.Cu")
		(net "M_F_CPU1_SB_DQS_DP<6>")
	)
	(segment
		(start 33.897824 -296.34053)
		(end 34.375344 -296.34053)
		(width 0.16002)
		(layer "In11.Cu")
		(net "M_F_CPU1_SB_DQS_DP<6>")
	)
	(segment
		(start 57.007252 -296.34053)
		(end 57.891426 -295.456356)
		(width 0.16002)
		(layer "In11.Cu")
		(net "M_F_CPU1_SB_DQS_DP<6>")
	)
	(segment
		(start 26.03373 -296.66057)
		(end 26.35377 -296.34053)
		(width 0.16002)
		(layer "In11.Cu")
		(net "M_F_CPU1_SB_DQS_DP<6>")
	)
	(segment
		(start 27.715464 -295.456356)
		(end 28.01747 -295.456356)
		(width 0.16002)
		(layer "In11.Cu")
		(net "M_F_CPU1_SB_DQS_DP<6>")
	)
	(segment
		(start 77.305662 -281.915616)
		(end 77.493114 -281.728164)
		(width 0.09525)
		(layer "In11.Cu")
		(net "M_F_CPU1_SB_DQS_DP<6>")
	)
	(arc
		(start 80.40243 -281.86126)
		(mid 80.586205 -281.810488)
		(end 80.771238 -281.856434)
		(width 0.09525)
		(layer "In11.Cu")
		(net "M_F_CPU1_SB_DQS_DP<6>")
	)
	(arc
		(start 82.659474 -281.86126)
		(mid 82.940906 -281.937015)
		(end 83.222338 -281.86126)
		(width 0.09525)
		(layer "In11.Cu")
		(net "M_F_CPU1_SB_DQS_DP<6>")
	)
	(arc
		(start 82.282538 -281.86126)
		(mid 82.471006 -281.810583)
		(end 82.659474 -281.86126)
		(width 0.09525)
		(layer "In11.Cu")
		(net "M_F_CPU1_SB_DQS_DP<6>")
	)
	(arc
		(start 81.350866 -281.856434)
		(mid 81.535898 -281.81052)
		(end 81.719674 -281.86126)
		(width 0.09525)
		(layer "In11.Cu")
		(net "M_F_CPU1_SB_DQS_DP<6>")
	)
	(arc
		(start 84.539582 -281.86126)
		(mid 84.821014 -281.937015)
		(end 85.102446 -281.86126)
		(width 0.09525)
		(layer "In11.Cu")
		(net "M_F_CPU1_SB_DQS_DP<6>")
	)
	(arc
		(start 85.955886 -281.902154)
		(mid 85.966085 -281.898317)
		(end 85.976206 -281.89428)
		(width 0.09525)
		(layer "In11.Cu")
		(net "M_F_CPU1_SB_DQS_DP<6>")
	)
	(arc
		(start 83.599528 -281.86126)
		(mid 83.88096 -281.937015)
		(end 84.162392 -281.86126)
		(width 0.09525)
		(layer "In11.Cu")
		(net "M_F_CPU1_SB_DQS_DP<6>")
	)
	(arc
		(start 84.162392 -281.86126)
		(mid 84.346167 -281.810488)
		(end 84.5312 -281.856434)
		(width 0.09525)
		(layer "In11.Cu")
		(net "M_F_CPU1_SB_DQS_DP<6>")
	)
	(arc
		(start 85.479636 -281.86126)
		(mid 85.71318 -281.934966)
		(end 85.955886 -281.902154)
		(width 0.09525)
		(layer "In11.Cu")
		(net "M_F_CPU1_SB_DQS_DP<6>")
	)
	(arc
		(start 83.222338 -281.86126)
		(mid 83.406113 -281.810488)
		(end 83.591146 -281.856434)
		(width 0.09525)
		(layer "In11.Cu")
		(net "M_F_CPU1_SB_DQS_DP<6>")
	)
	(arc
		(start 80.77962 -281.86126)
		(mid 81.061052 -281.937015)
		(end 81.342484 -281.86126)
		(width 0.09525)
		(layer "In11.Cu")
		(net "M_F_CPU1_SB_DQS_DP<6>")
	)
	(arc
		(start 81.719674 -281.86126)
		(mid 82.001106 -281.937015)
		(end 82.282538 -281.86126)
		(width 0.09525)
		(layer "In11.Cu")
		(net "M_F_CPU1_SB_DQS_DP<6>")
	)
	(arc
		(start 85.110828 -281.856434)
		(mid 85.29586 -281.81052)
		(end 85.479636 -281.86126)
		(width 0.09525)
		(layer "In11.Cu")
		(net "M_F_CPU1_SB_DQS_DP<6>")
	)
	(arc
		(start 79.724504 -281.772868)
		(mid 80.042467 -281.931575)
		(end 80.392016 -281.867356)
		(width 0.09525)
		(layer "In11.Cu")
		(net "M_F_CPU1_SB_DQS_DP<6>")
	)
	(segment
		(start 86.69782 -277.060406)
		(end 86.230968 -277.326344)
		(width 0.12954)
		(layer "F.Cu")
		(net "M_F_CPU1_SB_DQS_DP<5>")
	)
	(segment
		(start 27.715464 -286.106362)
		(end 28.01747 -286.106362)
		(width 0.16002)
		(layer "In11.Cu")
		(net "M_F_CPU1_SB_DQS_DP<5>")
	)
	(segment
		(start 26.35377 -286.990536)
		(end 26.83129 -286.990536)
		(width 0.16002)
		(layer "In11.Cu")
		(net "M_F_CPU1_SB_DQS_DP<5>")
	)
	(segment
		(start 51.003708 -286.460438)
		(end 53.363876 -286.460438)
		(width 0.16002)
		(layer "In11.Cu")
		(net "M_F_CPU1_SB_DQS_DP<5>")
	)
	(segment
		(start 35.259518 -286.106362)
		(end 35.561524 -286.106362)
		(width 0.16002)
		(layer "In11.Cu")
		(net "M_F_CPU1_SB_DQS_DP<5>")
	)
	(segment
		(start 33.577784 -287.310576)
		(end 33.897824 -286.990536)
		(width 0.16002)
		(layer "In11.Cu")
		(net "M_F_CPU1_SB_DQS_DP<5>")
	)
	(segment
		(start 85.976206 -277.034244)
		(end 86.077044 -277.060914)
		(width 0.09525)
		(layer "In11.Cu")
		(net "M_F_CPU1_SB_DQS_DP<5>")
	)
	(segment
		(start 41.121838 -287.310576)
		(end 41.441878 -286.990536)
		(width 0.16002)
		(layer "In11.Cu")
		(net "M_F_CPU1_SB_DQS_DP<5>")
	)
	(segment
		(start 45.819822 -286.460438)
		(end 46.66996 -287.310576)
		(width 0.16002)
		(layer "In11.Cu")
		(net "M_F_CPU1_SB_DQS_DP<5>")
	)
	(segment
		(start 53.363876 -286.460438)
		(end 53.893974 -286.990536)
		(width 0.16002)
		(layer "In11.Cu")
		(net "M_F_CPU1_SB_DQS_DP<5>")
	)
	(segment
		(start 34.375344 -286.990536)
		(end 35.259518 -286.106362)
		(width 0.16002)
		(layer "In11.Cu")
		(net "M_F_CPU1_SB_DQS_DP<5>")
	)
	(segment
		(start 49.463452 -286.990536)
		(end 50.347626 -286.106362)
		(width 0.16002)
		(layer "In11.Cu")
		(net "M_F_CPU1_SB_DQS_DP<5>")
	)
	(segment
		(start 50.347626 -286.106362)
		(end 50.649632 -286.106362)
		(width 0.16002)
		(layer "In11.Cu")
		(net "M_F_CPU1_SB_DQS_DP<5>")
	)
	(segment
		(start 75.979528 -276.350984)
		(end 76.038456 -276.292056)
		(width 0.09525)
		(layer "In11.Cu")
		(net "M_F_CPU1_SB_DQS_DP<5>")
	)
	(segment
		(start 38.275768 -286.460438)
		(end 39.125906 -287.310576)
		(width 0.16002)
		(layer "In11.Cu")
		(net "M_F_CPU1_SB_DQS_DP<5>")
	)
	(segment
		(start 84.5312 -276.996398)
		(end 84.539582 -277.001224)
		(width 0.09525)
		(layer "In11.Cu")
		(net "M_F_CPU1_SB_DQS_DP<5>")
	)
	(segment
		(start 48.665892 -287.310576)
		(end 48.985932 -286.990536)
		(width 0.16002)
		(layer "In11.Cu")
		(net "M_F_CPU1_SB_DQS_DP<5>")
	)
	(segment
		(start 41.441878 -286.990536)
		(end 41.919398 -286.990536)
		(width 0.16002)
		(layer "In11.Cu")
		(net "M_F_CPU1_SB_DQS_DP<5>")
	)
	(segment
		(start 28.01747 -286.106362)
		(end 28.371546 -286.460438)
		(width 0.16002)
		(layer "In11.Cu")
		(net "M_F_CPU1_SB_DQS_DP<5>")
	)
	(segment
		(start 23.252684 -286.492188)
		(end 24.071072 -287.310576)
		(width 0.16002)
		(layer "In11.Cu")
		(net "M_F_CPU1_SB_DQS_DP<5>")
	)
	(segment
		(start 50.649632 -286.106362)
		(end 51.003708 -286.460438)
		(width 0.16002)
		(layer "In11.Cu")
		(net "M_F_CPU1_SB_DQS_DP<5>")
	)
	(segment
		(start 20.516088 -286.145732)
		(end 20.862544 -286.492188)
		(width 0.16002)
		(layer "In11.Cu")
		(net "M_F_CPU1_SB_DQS_DP<5>")
	)
	(segment
		(start 86.077044 -277.060914)
		(end 86.230968 -277.326344)
		(width 0.09525)
		(layer "In11.Cu")
		(net "M_F_CPU1_SB_DQS_DP<5>")
	)
	(segment
		(start 20.862544 -286.492188)
		(end 23.252684 -286.492188)
		(width 0.16002)
		(layer "In11.Cu")
		(net "M_F_CPU1_SB_DQS_DP<5>")
	)
	(segment
		(start 26.03373 -287.310576)
		(end 26.35377 -286.990536)
		(width 0.16002)
		(layer "In11.Cu")
		(net "M_F_CPU1_SB_DQS_DP<5>")
	)
	(segment
		(start 60.36818 -286.106362)
		(end 70.123558 -276.350984)
		(width 0.16002)
		(layer "In11.Cu")
		(net "M_F_CPU1_SB_DQS_DP<5>")
	)
	(segment
		(start 76.038456 -276.292056)
		(end 76.316586 -276.292056)
		(width 0.09525)
		(layer "In11.Cu")
		(net "M_F_CPU1_SB_DQS_DP<5>")
	)
	(segment
		(start 80.402176 -277.00097)
		(end 80.40243 -277.001224)
		(width 0.09525)
		(layer "In11.Cu")
		(net "M_F_CPU1_SB_DQS_DP<5>")
	)
	(segment
		(start 19.7612 -286.31134)
		(end 19.926808 -286.145732)
		(width 0.16002)
		(layer "In11.Cu")
		(net "M_F_CPU1_SB_DQS_DP<5>")
	)
	(segment
		(start 76.316586 -276.292056)
		(end 76.831444 -276.806914)
		(width 0.09525)
		(layer "In11.Cu")
		(net "M_F_CPU1_SB_DQS_DP<5>")
	)
	(segment
		(start 76.831444 -276.806914)
		(end 79.120492 -276.806914)
		(width 0.09525)
		(layer "In11.Cu")
		(net "M_F_CPU1_SB_DQS_DP<5>")
	)
	(segment
		(start 70.123558 -276.350984)
		(end 75.955906 -276.350984)
		(width 0.16002)
		(layer "In11.Cu")
		(net "M_F_CPU1_SB_DQS_DP<5>")
	)
	(segment
		(start 28.371546 -286.460438)
		(end 30.731714 -286.460438)
		(width 0.16002)
		(layer "In11.Cu")
		(net "M_F_CPU1_SB_DQS_DP<5>")
	)
	(segment
		(start 81.342484 -277.001224)
		(end 81.350866 -276.996398)
		(width 0.09525)
		(layer "In11.Cu")
		(net "M_F_CPU1_SB_DQS_DP<5>")
	)
	(segment
		(start 17.882108 -286.31134)
		(end 19.7612 -286.31134)
		(width 0.16002)
		(layer "In11.Cu")
		(net "M_F_CPU1_SB_DQS_DP<5>")
	)
	(segment
		(start 33.897824 -286.990536)
		(end 34.375344 -286.990536)
		(width 0.16002)
		(layer "In11.Cu")
		(net "M_F_CPU1_SB_DQS_DP<5>")
	)
	(segment
		(start 53.893974 -286.990536)
		(end 57.007252 -286.990536)
		(width 0.16002)
		(layer "In11.Cu")
		(net "M_F_CPU1_SB_DQS_DP<5>")
	)
	(segment
		(start 83.591146 -276.996398)
		(end 83.599528 -277.001224)
		(width 0.09525)
		(layer "In11.Cu")
		(net "M_F_CPU1_SB_DQS_DP<5>")
	)
	(segment
		(start 43.459654 -286.460438)
		(end 45.819822 -286.460438)
		(width 0.16002)
		(layer "In11.Cu")
		(net "M_F_CPU1_SB_DQS_DP<5>")
	)
	(segment
		(start 57.891426 -286.106362)
		(end 60.36818 -286.106362)
		(width 0.16002)
		(layer "In11.Cu")
		(net "M_F_CPU1_SB_DQS_DP<5>")
	)
	(segment
		(start 19.926808 -286.145732)
		(end 20.516088 -286.145732)
		(width 0.16002)
		(layer "In11.Cu")
		(net "M_F_CPU1_SB_DQS_DP<5>")
	)
	(segment
		(start 48.985932 -286.990536)
		(end 49.463452 -286.990536)
		(width 0.16002)
		(layer "In11.Cu")
		(net "M_F_CPU1_SB_DQS_DP<5>")
	)
	(segment
		(start 31.581852 -287.310576)
		(end 33.577784 -287.310576)
		(width 0.16002)
		(layer "In11.Cu")
		(net "M_F_CPU1_SB_DQS_DP<5>")
	)
	(segment
		(start 26.83129 -286.990536)
		(end 27.715464 -286.106362)
		(width 0.16002)
		(layer "In11.Cu")
		(net "M_F_CPU1_SB_DQS_DP<5>")
	)
	(segment
		(start 42.803572 -286.106362)
		(end 43.105578 -286.106362)
		(width 0.16002)
		(layer "In11.Cu")
		(net "M_F_CPU1_SB_DQS_DP<5>")
	)
	(segment
		(start 75.955906 -276.350984)
		(end 75.979528 -276.350984)
		(width 0.09525)
		(layer "In11.Cu")
		(net "M_F_CPU1_SB_DQS_DP<5>")
	)
	(segment
		(start 57.007252 -286.990536)
		(end 57.891426 -286.106362)
		(width 0.16002)
		(layer "In11.Cu")
		(net "M_F_CPU1_SB_DQS_DP<5>")
	)
	(segment
		(start 30.731714 -286.460438)
		(end 31.581852 -287.310576)
		(width 0.16002)
		(layer "In11.Cu")
		(net "M_F_CPU1_SB_DQS_DP<5>")
	)
	(segment
		(start 17.608042 -286.585406)
		(end 17.882108 -286.31134)
		(width 0.16002)
		(layer "In11.Cu")
		(net "M_F_CPU1_SB_DQS_DP<5>")
	)
	(segment
		(start 24.071072 -287.310576)
		(end 26.03373 -287.310576)
		(width 0.16002)
		(layer "In11.Cu")
		(net "M_F_CPU1_SB_DQS_DP<5>")
	)
	(segment
		(start 43.105578 -286.106362)
		(end 43.459654 -286.460438)
		(width 0.16002)
		(layer "In11.Cu")
		(net "M_F_CPU1_SB_DQS_DP<5>")
	)
	(segment
		(start 46.66996 -287.310576)
		(end 48.665892 -287.310576)
		(width 0.16002)
		(layer "In11.Cu")
		(net "M_F_CPU1_SB_DQS_DP<5>")
	)
	(segment
		(start 35.9156 -286.460438)
		(end 38.275768 -286.460438)
		(width 0.16002)
		(layer "In11.Cu")
		(net "M_F_CPU1_SB_DQS_DP<5>")
	)
	(segment
		(start 85.102446 -277.001224)
		(end 85.110828 -276.996398)
		(width 0.09525)
		(layer "In11.Cu")
		(net "M_F_CPU1_SB_DQS_DP<5>")
	)
	(segment
		(start 39.125906 -287.310576)
		(end 41.121838 -287.310576)
		(width 0.16002)
		(layer "In11.Cu")
		(net "M_F_CPU1_SB_DQS_DP<5>")
	)
	(segment
		(start 35.561524 -286.106362)
		(end 35.9156 -286.460438)
		(width 0.16002)
		(layer "In11.Cu")
		(net "M_F_CPU1_SB_DQS_DP<5>")
	)
	(segment
		(start 80.771238 -276.996398)
		(end 80.77962 -277.001224)
		(width 0.09525)
		(layer "In11.Cu")
		(net "M_F_CPU1_SB_DQS_DP<5>")
	)
	(segment
		(start 41.919398 -286.990536)
		(end 42.803572 -286.106362)
		(width 0.16002)
		(layer "In11.Cu")
		(net "M_F_CPU1_SB_DQS_DP<5>")
	)
	(arc
		(start 79.120492 -276.806914)
		(mid 79.492998 -276.856325)
		(end 79.83982 -277.00097)
		(width 0.09525)
		(layer "In11.Cu")
		(net "M_F_CPU1_SB_DQS_DP<5>")
	)
	(arc
		(start 82.282538 -277.001224)
		(mid 82.471006 -276.950547)
		(end 82.659474 -277.001224)
		(width 0.09525)
		(layer "In11.Cu")
		(net "M_F_CPU1_SB_DQS_DP<5>")
	)
	(arc
		(start 81.719674 -277.001224)
		(mid 82.001106 -277.076979)
		(end 82.282538 -277.001224)
		(width 0.09525)
		(layer "In11.Cu")
		(net "M_F_CPU1_SB_DQS_DP<5>")
	)
	(arc
		(start 83.222338 -277.001224)
		(mid 83.406113 -276.950452)
		(end 83.591146 -276.996398)
		(width 0.09525)
		(layer "In11.Cu")
		(net "M_F_CPU1_SB_DQS_DP<5>")
	)
	(arc
		(start 80.77962 -277.001224)
		(mid 81.061052 -277.076979)
		(end 81.342484 -277.001224)
		(width 0.09525)
		(layer "In11.Cu")
		(net "M_F_CPU1_SB_DQS_DP<5>")
	)
	(arc
		(start 80.40243 -277.001224)
		(mid 80.586205 -276.950452)
		(end 80.771238 -276.996398)
		(width 0.09525)
		(layer "In11.Cu")
		(net "M_F_CPU1_SB_DQS_DP<5>")
	)
	(arc
		(start 82.659474 -277.001224)
		(mid 82.940906 -277.076979)
		(end 83.222338 -277.001224)
		(width 0.09525)
		(layer "In11.Cu")
		(net "M_F_CPU1_SB_DQS_DP<5>")
	)
	(arc
		(start 79.83982 -277.00097)
		(mid 80.120998 -277.076632)
		(end 80.402176 -277.00097)
		(width 0.09525)
		(layer "In11.Cu")
		(net "M_F_CPU1_SB_DQS_DP<5>")
	)
	(arc
		(start 81.350866 -276.996398)
		(mid 81.535898 -276.950484)
		(end 81.719674 -277.001224)
		(width 0.09525)
		(layer "In11.Cu")
		(net "M_F_CPU1_SB_DQS_DP<5>")
	)
	(arc
		(start 84.162392 -277.001224)
		(mid 84.346167 -276.950452)
		(end 84.5312 -276.996398)
		(width 0.09525)
		(layer "In11.Cu")
		(net "M_F_CPU1_SB_DQS_DP<5>")
	)
	(arc
		(start 85.110828 -276.996398)
		(mid 85.29586 -276.950484)
		(end 85.479636 -277.001224)
		(width 0.09525)
		(layer "In11.Cu")
		(net "M_F_CPU1_SB_DQS_DP<5>")
	)
	(arc
		(start 85.955886 -277.042118)
		(mid 85.966085 -277.038281)
		(end 85.976206 -277.034244)
		(width 0.09525)
		(layer "In11.Cu")
		(net "M_F_CPU1_SB_DQS_DP<5>")
	)
	(arc
		(start 84.539582 -277.001224)
		(mid 84.821014 -277.076979)
		(end 85.102446 -277.001224)
		(width 0.09525)
		(layer "In11.Cu")
		(net "M_F_CPU1_SB_DQS_DP<5>")
	)
	(arc
		(start 83.599528 -277.001224)
		(mid 83.88096 -277.076979)
		(end 84.162392 -277.001224)
		(width 0.09525)
		(layer "In11.Cu")
		(net "M_F_CPU1_SB_DQS_DP<5>")
	)
	(arc
		(start 85.479636 -277.001224)
		(mid 85.71318 -277.07493)
		(end 85.955886 -277.042118)
		(width 0.09525)
		(layer "In11.Cu")
		(net "M_F_CPU1_SB_DQS_DP<5>")
	)
	(segment
		(start 86.69782 -272.20037)
		(end 86.230968 -272.466308)
		(width 0.12954)
		(layer "F.Cu")
		(net "M_F_CPU1_SB_DQS_DP<4>")
	)
	(segment
		(start 33.577784 -277.960582)
		(end 33.897824 -277.640542)
		(width 0.16002)
		(layer "In11.Cu")
		(net "M_F_CPU1_SB_DQS_DP<4>")
	)
	(segment
		(start 42.803572 -276.756368)
		(end 43.105578 -276.756368)
		(width 0.16002)
		(layer "In11.Cu")
		(net "M_F_CPU1_SB_DQS_DP<4>")
	)
	(segment
		(start 85.976206 -272.174208)
		(end 86.077044 -272.200878)
		(width 0.09525)
		(layer "In11.Cu")
		(net "M_F_CPU1_SB_DQS_DP<4>")
	)
	(segment
		(start 35.561524 -276.756368)
		(end 35.9156 -277.110444)
		(width 0.16002)
		(layer "In11.Cu")
		(net "M_F_CPU1_SB_DQS_DP<4>")
	)
	(segment
		(start 26.83129 -277.640542)
		(end 27.715464 -276.756368)
		(width 0.16002)
		(layer "In11.Cu")
		(net "M_F_CPU1_SB_DQS_DP<4>")
	)
	(segment
		(start 33.897824 -277.640542)
		(end 34.375344 -277.640542)
		(width 0.16002)
		(layer "In11.Cu")
		(net "M_F_CPU1_SB_DQS_DP<4>")
	)
	(segment
		(start 28.371546 -277.110444)
		(end 30.731714 -277.110444)
		(width 0.16002)
		(layer "In11.Cu")
		(net "M_F_CPU1_SB_DQS_DP<4>")
	)
	(segment
		(start 83.591146 -272.136362)
		(end 83.599528 -272.141188)
		(width 0.09525)
		(layer "In11.Cu")
		(net "M_F_CPU1_SB_DQS_DP<4>")
	)
	(segment
		(start 48.985932 -277.640542)
		(end 49.463452 -277.640542)
		(width 0.16002)
		(layer "In11.Cu")
		(net "M_F_CPU1_SB_DQS_DP<4>")
	)
	(segment
		(start 31.581852 -277.960582)
		(end 33.577784 -277.960582)
		(width 0.16002)
		(layer "In11.Cu")
		(net "M_F_CPU1_SB_DQS_DP<4>")
	)
	(segment
		(start 20.862544 -277.142194)
		(end 23.252684 -277.142194)
		(width 0.16002)
		(layer "In11.Cu")
		(net "M_F_CPU1_SB_DQS_DP<4>")
	)
	(segment
		(start 65.46977 -270.727424)
		(end 75.955906 -270.727424)
		(width 0.16002)
		(layer "In11.Cu")
		(net "M_F_CPU1_SB_DQS_DP<4>")
	)
	(segment
		(start 76.475844 -270.863314)
		(end 77.31506 -270.863314)
		(width 0.09525)
		(layer "In11.Cu")
		(net "M_F_CPU1_SB_DQS_DP<4>")
	)
	(segment
		(start 24.071072 -277.960582)
		(end 26.03373 -277.960582)
		(width 0.16002)
		(layer "In11.Cu")
		(net "M_F_CPU1_SB_DQS_DP<4>")
	)
	(segment
		(start 17.608042 -277.235412)
		(end 17.882108 -276.961346)
		(width 0.16002)
		(layer "In11.Cu")
		(net "M_F_CPU1_SB_DQS_DP<4>")
	)
	(segment
		(start 34.375344 -277.640542)
		(end 35.259518 -276.756368)
		(width 0.16002)
		(layer "In11.Cu")
		(net "M_F_CPU1_SB_DQS_DP<4>")
	)
	(segment
		(start 43.459654 -277.110444)
		(end 45.819822 -277.110444)
		(width 0.16002)
		(layer "In11.Cu")
		(net "M_F_CPU1_SB_DQS_DP<4>")
	)
	(segment
		(start 86.077044 -272.200878)
		(end 86.230968 -272.466308)
		(width 0.09525)
		(layer "In11.Cu")
		(net "M_F_CPU1_SB_DQS_DP<4>")
	)
	(segment
		(start 26.03373 -277.960582)
		(end 26.35377 -277.640542)
		(width 0.16002)
		(layer "In11.Cu")
		(net "M_F_CPU1_SB_DQS_DP<4>")
	)
	(segment
		(start 20.516088 -276.795738)
		(end 20.862544 -277.142194)
		(width 0.16002)
		(layer "In11.Cu")
		(net "M_F_CPU1_SB_DQS_DP<4>")
	)
	(segment
		(start 77.31506 -270.863314)
		(end 78.49108 -272.039334)
		(width 0.09525)
		(layer "In11.Cu")
		(net "M_F_CPU1_SB_DQS_DP<4>")
	)
	(segment
		(start 80.771238 -272.136362)
		(end 80.77962 -272.141188)
		(width 0.09525)
		(layer "In11.Cu")
		(net "M_F_CPU1_SB_DQS_DP<4>")
	)
	(segment
		(start 38.275768 -277.110444)
		(end 39.125906 -277.960582)
		(width 0.16002)
		(layer "In11.Cu")
		(net "M_F_CPU1_SB_DQS_DP<4>")
	)
	(segment
		(start 27.715464 -276.756368)
		(end 28.01747 -276.756368)
		(width 0.16002)
		(layer "In11.Cu")
		(net "M_F_CPU1_SB_DQS_DP<4>")
	)
	(segment
		(start 59.440826 -276.756368)
		(end 65.46977 -270.727424)
		(width 0.16002)
		(layer "In11.Cu")
		(net "M_F_CPU1_SB_DQS_DP<4>")
	)
	(segment
		(start 41.919398 -277.640542)
		(end 42.803572 -276.756368)
		(width 0.16002)
		(layer "In11.Cu")
		(net "M_F_CPU1_SB_DQS_DP<4>")
	)
	(segment
		(start 75.979528 -270.727424)
		(end 76.038456 -270.668496)
		(width 0.09525)
		(layer "In11.Cu")
		(net "M_F_CPU1_SB_DQS_DP<4>")
	)
	(segment
		(start 78.49108 -272.039334)
		(end 79.463646 -272.039334)
		(width 0.09525)
		(layer "In11.Cu")
		(net "M_F_CPU1_SB_DQS_DP<4>")
	)
	(segment
		(start 50.347626 -276.756368)
		(end 50.649632 -276.756368)
		(width 0.16002)
		(layer "In11.Cu")
		(net "M_F_CPU1_SB_DQS_DP<4>")
	)
	(segment
		(start 53.363876 -277.110444)
		(end 53.893974 -277.640542)
		(width 0.16002)
		(layer "In11.Cu")
		(net "M_F_CPU1_SB_DQS_DP<4>")
	)
	(segment
		(start 35.9156 -277.110444)
		(end 38.275768 -277.110444)
		(width 0.16002)
		(layer "In11.Cu")
		(net "M_F_CPU1_SB_DQS_DP<4>")
	)
	(segment
		(start 76.281026 -270.668496)
		(end 76.475844 -270.863314)
		(width 0.09525)
		(layer "In11.Cu")
		(net "M_F_CPU1_SB_DQS_DP<4>")
	)
	(segment
		(start 23.252684 -277.142194)
		(end 24.071072 -277.960582)
		(width 0.16002)
		(layer "In11.Cu")
		(net "M_F_CPU1_SB_DQS_DP<4>")
	)
	(segment
		(start 35.259518 -276.756368)
		(end 35.561524 -276.756368)
		(width 0.16002)
		(layer "In11.Cu")
		(net "M_F_CPU1_SB_DQS_DP<4>")
	)
	(segment
		(start 76.038456 -270.668496)
		(end 76.281026 -270.668496)
		(width 0.09525)
		(layer "In11.Cu")
		(net "M_F_CPU1_SB_DQS_DP<4>")
	)
	(segment
		(start 26.35377 -277.640542)
		(end 26.83129 -277.640542)
		(width 0.16002)
		(layer "In11.Cu")
		(net "M_F_CPU1_SB_DQS_DP<4>")
	)
	(segment
		(start 48.665892 -277.960582)
		(end 48.985932 -277.640542)
		(width 0.16002)
		(layer "In11.Cu")
		(net "M_F_CPU1_SB_DQS_DP<4>")
	)
	(segment
		(start 45.819822 -277.110444)
		(end 46.66996 -277.960582)
		(width 0.16002)
		(layer "In11.Cu")
		(net "M_F_CPU1_SB_DQS_DP<4>")
	)
	(segment
		(start 39.125906 -277.960582)
		(end 41.121838 -277.960582)
		(width 0.16002)
		(layer "In11.Cu")
		(net "M_F_CPU1_SB_DQS_DP<4>")
	)
	(segment
		(start 53.893974 -277.640542)
		(end 57.007252 -277.640542)
		(width 0.16002)
		(layer "In11.Cu")
		(net "M_F_CPU1_SB_DQS_DP<4>")
	)
	(segment
		(start 51.003708 -277.110444)
		(end 53.363876 -277.110444)
		(width 0.16002)
		(layer "In11.Cu")
		(net "M_F_CPU1_SB_DQS_DP<4>")
	)
	(segment
		(start 41.441878 -277.640542)
		(end 41.919398 -277.640542)
		(width 0.16002)
		(layer "In11.Cu")
		(net "M_F_CPU1_SB_DQS_DP<4>")
	)
	(segment
		(start 41.121838 -277.960582)
		(end 41.441878 -277.640542)
		(width 0.16002)
		(layer "In11.Cu")
		(net "M_F_CPU1_SB_DQS_DP<4>")
	)
	(segment
		(start 19.7612 -276.961346)
		(end 19.926808 -276.795738)
		(width 0.16002)
		(layer "In11.Cu")
		(net "M_F_CPU1_SB_DQS_DP<4>")
	)
	(segment
		(start 84.5312 -272.136362)
		(end 84.539582 -272.141188)
		(width 0.09525)
		(layer "In11.Cu")
		(net "M_F_CPU1_SB_DQS_DP<4>")
	)
	(segment
		(start 57.891426 -276.756368)
		(end 59.440826 -276.756368)
		(width 0.16002)
		(layer "In11.Cu")
		(net "M_F_CPU1_SB_DQS_DP<4>")
	)
	(segment
		(start 49.463452 -277.640542)
		(end 50.347626 -276.756368)
		(width 0.16002)
		(layer "In11.Cu")
		(net "M_F_CPU1_SB_DQS_DP<4>")
	)
	(segment
		(start 81.342484 -272.141188)
		(end 81.350866 -272.136362)
		(width 0.09525)
		(layer "In11.Cu")
		(net "M_F_CPU1_SB_DQS_DP<4>")
	)
	(segment
		(start 57.007252 -277.640542)
		(end 57.891426 -276.756368)
		(width 0.16002)
		(layer "In11.Cu")
		(net "M_F_CPU1_SB_DQS_DP<4>")
	)
	(segment
		(start 43.105578 -276.756368)
		(end 43.459654 -277.110444)
		(width 0.16002)
		(layer "In11.Cu")
		(net "M_F_CPU1_SB_DQS_DP<4>")
	)
	(segment
		(start 19.926808 -276.795738)
		(end 20.516088 -276.795738)
		(width 0.16002)
		(layer "In11.Cu")
		(net "M_F_CPU1_SB_DQS_DP<4>")
	)
	(segment
		(start 46.66996 -277.960582)
		(end 48.665892 -277.960582)
		(width 0.16002)
		(layer "In11.Cu")
		(net "M_F_CPU1_SB_DQS_DP<4>")
	)
	(segment
		(start 75.955906 -270.727424)
		(end 75.979528 -270.727424)
		(width 0.09525)
		(layer "In11.Cu")
		(net "M_F_CPU1_SB_DQS_DP<4>")
	)
	(segment
		(start 50.649632 -276.756368)
		(end 51.003708 -277.110444)
		(width 0.16002)
		(layer "In11.Cu")
		(net "M_F_CPU1_SB_DQS_DP<4>")
	)
	(segment
		(start 85.102446 -272.141188)
		(end 85.110828 -272.136362)
		(width 0.09525)
		(layer "In11.Cu")
		(net "M_F_CPU1_SB_DQS_DP<4>")
	)
	(segment
		(start 17.882108 -276.961346)
		(end 19.7612 -276.961346)
		(width 0.16002)
		(layer "In11.Cu")
		(net "M_F_CPU1_SB_DQS_DP<4>")
	)
	(segment
		(start 80.402176 -272.140934)
		(end 80.40243 -272.141188)
		(width 0.09525)
		(layer "In11.Cu")
		(net "M_F_CPU1_SB_DQS_DP<4>")
	)
	(segment
		(start 28.01747 -276.756368)
		(end 28.371546 -277.110444)
		(width 0.16002)
		(layer "In11.Cu")
		(net "M_F_CPU1_SB_DQS_DP<4>")
	)
	(segment
		(start 30.731714 -277.110444)
		(end 31.581852 -277.960582)
		(width 0.16002)
		(layer "In11.Cu")
		(net "M_F_CPU1_SB_DQS_DP<4>")
	)
	(arc
		(start 85.110828 -272.136362)
		(mid 85.29586 -272.090448)
		(end 85.479636 -272.141188)
		(width 0.09525)
		(layer "In11.Cu")
		(net "M_F_CPU1_SB_DQS_DP<4>")
	)
	(arc
		(start 83.599528 -272.141188)
		(mid 83.88096 -272.216943)
		(end 84.162392 -272.141188)
		(width 0.09525)
		(layer "In11.Cu")
		(net "M_F_CPU1_SB_DQS_DP<4>")
	)
	(arc
		(start 84.162392 -272.141188)
		(mid 84.346167 -272.090416)
		(end 84.5312 -272.136362)
		(width 0.09525)
		(layer "In11.Cu")
		(net "M_F_CPU1_SB_DQS_DP<4>")
	)
	(arc
		(start 80.77962 -272.141188)
		(mid 81.061052 -272.216943)
		(end 81.342484 -272.141188)
		(width 0.09525)
		(layer "In11.Cu")
		(net "M_F_CPU1_SB_DQS_DP<4>")
	)
	(arc
		(start 81.719674 -272.141188)
		(mid 82.001106 -272.216943)
		(end 82.282538 -272.141188)
		(width 0.09525)
		(layer "In11.Cu")
		(net "M_F_CPU1_SB_DQS_DP<4>")
	)
	(arc
		(start 85.479636 -272.141188)
		(mid 85.71318 -272.214894)
		(end 85.955886 -272.182082)
		(width 0.09525)
		(layer "In11.Cu")
		(net "M_F_CPU1_SB_DQS_DP<4>")
	)
	(arc
		(start 85.955886 -272.182082)
		(mid 85.966085 -272.178245)
		(end 85.976206 -272.174208)
		(width 0.09525)
		(layer "In11.Cu")
		(net "M_F_CPU1_SB_DQS_DP<4>")
	)
	(arc
		(start 82.282538 -272.141188)
		(mid 82.471006 -272.090511)
		(end 82.659474 -272.141188)
		(width 0.09525)
		(layer "In11.Cu")
		(net "M_F_CPU1_SB_DQS_DP<4>")
	)
	(arc
		(start 79.83982 -272.140934)
		(mid 80.120998 -272.216596)
		(end 80.402176 -272.140934)
		(width 0.09525)
		(layer "In11.Cu")
		(net "M_F_CPU1_SB_DQS_DP<4>")
	)
	(arc
		(start 79.463646 -272.039334)
		(mid 79.658462 -272.065217)
		(end 79.83982 -272.140934)
		(width 0.09525)
		(layer "In11.Cu")
		(net "M_F_CPU1_SB_DQS_DP<4>")
	)
	(arc
		(start 80.40243 -272.141188)
		(mid 80.586205 -272.090416)
		(end 80.771238 -272.136362)
		(width 0.09525)
		(layer "In11.Cu")
		(net "M_F_CPU1_SB_DQS_DP<4>")
	)
	(arc
		(start 83.222338 -272.141188)
		(mid 83.406113 -272.090416)
		(end 83.591146 -272.136362)
		(width 0.09525)
		(layer "In11.Cu")
		(net "M_F_CPU1_SB_DQS_DP<4>")
	)
	(arc
		(start 84.539582 -272.141188)
		(mid 84.821014 -272.216943)
		(end 85.102446 -272.141188)
		(width 0.09525)
		(layer "In11.Cu")
		(net "M_F_CPU1_SB_DQS_DP<4>")
	)
	(arc
		(start 82.659474 -272.141188)
		(mid 82.940906 -272.216943)
		(end 83.222338 -272.141188)
		(width 0.09525)
		(layer "In11.Cu")
		(net "M_F_CPU1_SB_DQS_DP<4>")
	)
	(arc
		(start 81.350866 -272.136362)
		(mid 81.535898 -272.090448)
		(end 81.719674 -272.141188)
		(width 0.09525)
		(layer "In11.Cu")
		(net "M_F_CPU1_SB_DQS_DP<4>")
	)
	(segment
		(start 84.817966 -290.020248)
		(end 84.351114 -290.286186)
		(width 0.12954)
		(layer "F.Cu")
		(net "M_F_CPU1_SB_DQS_DP<3>")
	)
	(segment
		(start 71.667116 -299.466762)
		(end 71.667116 -299.943266)
		(width 0.16002)
		(layer "In11.Cu")
		(net "M_F_CPU1_SB_DQS_DP<3>")
	)
	(segment
		(start 52.877466 -312.210196)
		(end 51.020726 -312.210196)
		(width 0.16002)
		(layer "In11.Cu")
		(net "M_F_CPU1_SB_DQS_DP<3>")
	)
	(segment
		(start 73.108312 -298.864782)
		(end 72.861932 -299.111162)
		(width 0.16002)
		(layer "In11.Cu")
		(net "M_F_CPU1_SB_DQS_DP<3>")
	)
	(segment
		(start 68.921376 -302.689006)
		(end 68.989702 -302.757332)
		(width 0.16002)
		(layer "In11.Cu")
		(net "M_F_CPU1_SB_DQS_DP<3>")
	)
	(segment
		(start 22.461982 -313.209178)
		(end 21.981922 -313.209178)
		(width 0.16002)
		(layer "In11.Cu")
		(net "M_F_CPU1_SB_DQS_DP<3>")
	)
	(segment
		(start 73.463912 -297.669966)
		(end 73.039986 -298.093892)
		(width 0.16002)
		(layer "In11.Cu")
		(net "M_F_CPU1_SB_DQS_DP<3>")
	)
	(segment
		(start 53.876956 -312.852816)
		(end 53.520086 -312.852816)
		(width 0.16002)
		(layer "In11.Cu")
		(net "M_F_CPU1_SB_DQS_DP<3>")
	)
	(segment
		(start 30.245304 -312.210196)
		(end 28.388564 -312.210196)
		(width 0.16002)
		(layer "In11.Cu")
		(net "M_F_CPU1_SB_DQS_DP<3>")
	)
	(segment
		(start 56.92521 -313.404758)
		(end 56.24322 -313.404758)
		(width 0.16002)
		(layer "In11.Cu")
		(net "M_F_CPU1_SB_DQS_DP<3>")
	)
	(segment
		(start 71.263002 -300.484032)
		(end 71.194676 -300.415706)
		(width 0.16002)
		(layer "In11.Cu")
		(net "M_F_CPU1_SB_DQS_DP<3>")
	)
	(segment
		(start 67.548506 -303.585372)
		(end 67.548506 -304.061876)
		(width 0.16002)
		(layer "In11.Cu")
		(net "M_F_CPU1_SB_DQS_DP<3>")
	)
	(segment
		(start 42.662856 -312.579258)
		(end 41.837356 -313.404758)
		(width 0.16002)
		(layer "In11.Cu")
		(net "M_F_CPU1_SB_DQS_DP<3>")
	)
	(segment
		(start 70.362572 -301.384462)
		(end 70.362572 -301.610522)
		(width 0.16002)
		(layer "In11.Cu")
		(net "M_F_CPU1_SB_DQS_DP<3>")
	)
	(segment
		(start 71.667116 -299.943266)
		(end 71.735442 -300.011592)
		(width 0.16002)
		(layer "In11.Cu")
		(net "M_F_CPU1_SB_DQS_DP<3>")
	)
	(segment
		(start 74.412856 -296.721022)
		(end 74.412856 -297.197526)
		(width 0.16002)
		(layer "In11.Cu")
		(net "M_F_CPU1_SB_DQS_DP<3>")
	)
	(segment
		(start 63.853822 -307.280056)
		(end 63.429896 -307.703982)
		(width 0.16002)
		(layer "In11.Cu")
		(net "M_F_CPU1_SB_DQS_DP<3>")
	)
	(segment
		(start 33.549336 -313.06008)
		(end 31.095188 -313.06008)
		(width 0.16002)
		(layer "In11.Cu")
		(net "M_F_CPU1_SB_DQS_DP<3>")
	)
	(segment
		(start 78.918562 -290.860988)
		(end 78.001622 -291.777928)
		(width 0.09525)
		(layer "In11.Cu")
		(net "M_F_CPU1_SB_DQS_DP<3>")
	)
	(segment
		(start 73.039986 -298.570396)
		(end 73.108312 -298.638722)
		(width 0.16002)
		(layer "In11.Cu")
		(net "M_F_CPU1_SB_DQS_DP<3>")
	)
	(segment
		(start 66.243962 -305.503072)
		(end 66.243962 -305.729132)
		(width 0.16002)
		(layer "In11.Cu")
		(net "M_F_CPU1_SB_DQS_DP<3>")
	)
	(segment
		(start 67.076066 -304.534316)
		(end 66.599562 -304.534316)
		(width 0.16002)
		(layer "In11.Cu")
		(net "M_F_CPU1_SB_DQS_DP<3>")
	)
	(segment
		(start 24.006302 -313.209178)
		(end 23.175722 -313.209178)
		(width 0.16002)
		(layer "In11.Cu")
		(net "M_F_CPU1_SB_DQS_DP<3>")
	)
	(segment
		(start 43.10761 -312.579258)
		(end 42.662856 -312.579258)
		(width 0.16002)
		(layer "In11.Cu")
		(net "M_F_CPU1_SB_DQS_DP<3>")
	)
	(segment
		(start 64.802766 -306.331112)
		(end 64.802766 -306.807616)
		(width 0.16002)
		(layer "In11.Cu")
		(net "M_F_CPU1_SB_DQS_DP<3>")
	)
	(segment
		(start 73.108312 -298.638722)
		(end 73.108312 -298.864782)
		(width 0.16002)
		(layer "In11.Cu")
		(net "M_F_CPU1_SB_DQS_DP<3>")
	)
	(segment
		(start 37.789358 -312.210196)
		(end 35.932618 -312.210196)
		(width 0.16002)
		(layer "In11.Cu")
		(net "M_F_CPU1_SB_DQS_DP<3>")
	)
	(segment
		(start 64.802766 -306.807616)
		(end 64.871092 -306.875942)
		(width 0.16002)
		(layer "In11.Cu")
		(net "M_F_CPU1_SB_DQS_DP<3>")
	)
	(segment
		(start 74.008742 -297.738292)
		(end 73.940416 -297.669966)
		(width 0.16002)
		(layer "In11.Cu")
		(net "M_F_CPU1_SB_DQS_DP<3>")
	)
	(segment
		(start 31.095188 -313.06008)
		(end 30.245304 -312.210196)
		(width 0.16002)
		(layer "In11.Cu")
		(net "M_F_CPU1_SB_DQS_DP<3>")
	)
	(segment
		(start 73.039986 -298.093892)
		(end 73.039986 -298.570396)
		(width 0.16002)
		(layer "In11.Cu")
		(net "M_F_CPU1_SB_DQS_DP<3>")
	)
	(segment
		(start 23.175722 -313.209178)
		(end 23.058882 -313.092338)
		(width 0.16002)
		(layer "In11.Cu")
		(net "M_F_CPU1_SB_DQS_DP<3>")
	)
	(segment
		(start 57.75071 -312.579258)
		(end 56.92521 -313.404758)
		(width 0.16002)
		(layer "In11.Cu")
		(net "M_F_CPU1_SB_DQS_DP<3>")
	)
	(segment
		(start 34.293302 -313.404758)
		(end 33.894014 -313.404758)
		(width 0.16002)
		(layer "In11.Cu")
		(net "M_F_CPU1_SB_DQS_DP<3>")
	)
	(segment
		(start 63.429896 -307.703982)
		(end 63.429896 -308.180486)
		(width 0.16002)
		(layer "In11.Cu")
		(net "M_F_CPU1_SB_DQS_DP<3>")
	)
	(segment
		(start 56.24322 -313.404758)
		(end 56.12638 -313.287918)
		(width 0.16002)
		(layer "In11.Cu")
		(net "M_F_CPU1_SB_DQS_DP<3>")
	)
	(segment
		(start 77.90053 -292.022022)
		(end 77.90053 -292.50259)
		(width 0.09525)
		(layer "In11.Cu")
		(net "M_F_CPU1_SB_DQS_DP<3>")
	)
	(segment
		(start 77.90053 -292.50259)
		(end 76.490576 -293.912544)
		(width 0.09525)
		(layer "In11.Cu")
		(net "M_F_CPU1_SB_DQS_DP<3>")
	)
	(segment
		(start 76.049124 -296.00779)
		(end 75.965304 -296.00779)
		(width 0.09525)
		(layer "In11.Cu")
		(net "M_F_CPU1_SB_DQS_DP<3>")
	)
	(segment
		(start 41.837356 -313.404758)
		(end 41.438068 -313.404758)
		(width 0.16002)
		(layer "In11.Cu")
		(net "M_F_CPU1_SB_DQS_DP<3>")
	)
	(segment
		(start 80.77962 -290.611306)
		(end 80.771238 -290.616132)
		(width 0.09525)
		(layer "In11.Cu")
		(net "M_F_CPU1_SB_DQS_DP<3>")
	)
	(segment
		(start 65.997582 -305.975512)
		(end 65.771522 -305.975512)
		(width 0.16002)
		(layer "In11.Cu")
		(net "M_F_CPU1_SB_DQS_DP<3>")
	)
	(segment
		(start 75.965304 -296.00779)
		(end 75.94854 -296.024554)
		(width 0.09525)
		(layer "In11.Cu")
		(net "M_F_CPU1_SB_DQS_DP<3>")
	)
	(segment
		(start 26.005282 -313.06008)
		(end 24.1554 -313.06008)
		(width 0.16002)
		(layer "In11.Cu")
		(net "M_F_CPU1_SB_DQS_DP<3>")
	)
	(segment
		(start 35.563556 -312.579258)
		(end 35.118802 -312.579258)
		(width 0.16002)
		(layer "In11.Cu")
		(net "M_F_CPU1_SB_DQS_DP<3>")
	)
	(segment
		(start 26.34996 -313.404758)
		(end 26.005282 -313.06008)
		(width 0.16002)
		(layer "In11.Cu")
		(net "M_F_CPU1_SB_DQS_DP<3>")
	)
	(segment
		(start 35.118802 -312.579258)
		(end 34.293302 -313.404758)
		(width 0.16002)
		(layer "In11.Cu")
		(net "M_F_CPU1_SB_DQS_DP<3>")
	)
	(segment
		(start 70.294246 -300.839632)
		(end 70.294246 -301.316136)
		(width 0.16002)
		(layer "In11.Cu")
		(net "M_F_CPU1_SB_DQS_DP<3>")
	)
	(segment
		(start 65.226692 -305.907186)
		(end 64.802766 -306.331112)
		(width 0.16002)
		(layer "In11.Cu")
		(net "M_F_CPU1_SB_DQS_DP<3>")
	)
	(segment
		(start 48.982122 -313.404758)
		(end 48.637444 -313.06008)
		(width 0.16002)
		(layer "In11.Cu")
		(net "M_F_CPU1_SB_DQS_DP<3>")
	)
	(segment
		(start 84.505038 -290.551616)
		(end 84.48167 -290.638484)
		(width 0.09525)
		(layer "In11.Cu")
		(net "M_F_CPU1_SB_DQS_DP<3>")
	)
	(segment
		(start 71.735442 -300.237652)
		(end 71.489062 -300.484032)
		(width 0.16002)
		(layer "In11.Cu")
		(net "M_F_CPU1_SB_DQS_DP<3>")
	)
	(segment
		(start 74.481182 -297.491912)
		(end 74.234802 -297.738292)
		(width 0.16002)
		(layer "In11.Cu")
		(net "M_F_CPU1_SB_DQS_DP<3>")
	)
	(segment
		(start 71.735442 -300.011592)
		(end 71.735442 -300.237652)
		(width 0.16002)
		(layer "In11.Cu")
		(net "M_F_CPU1_SB_DQS_DP<3>")
	)
	(segment
		(start 64.871092 -307.102002)
		(end 64.624712 -307.348382)
		(width 0.16002)
		(layer "In11.Cu")
		(net "M_F_CPU1_SB_DQS_DP<3>")
	)
	(segment
		(start 64.624712 -307.348382)
		(end 64.398652 -307.348382)
		(width 0.16002)
		(layer "In11.Cu")
		(net "M_F_CPU1_SB_DQS_DP<3>")
	)
	(segment
		(start 28.019502 -312.579258)
		(end 27.574748 -312.579258)
		(width 0.16002)
		(layer "In11.Cu")
		(net "M_F_CPU1_SB_DQS_DP<3>")
	)
	(segment
		(start 41.09339 -313.06008)
		(end 38.639242 -313.06008)
		(width 0.16002)
		(layer "In11.Cu")
		(net "M_F_CPU1_SB_DQS_DP<3>")
	)
	(segment
		(start 74.481182 -297.265852)
		(end 74.481182 -297.491912)
		(width 0.16002)
		(layer "In11.Cu")
		(net "M_F_CPU1_SB_DQS_DP<3>")
	)
	(segment
		(start 41.438068 -313.404758)
		(end 41.09339 -313.06008)
		(width 0.16002)
		(layer "In11.Cu")
		(net "M_F_CPU1_SB_DQS_DP<3>")
	)
	(segment
		(start 63.498222 -308.248812)
		(end 63.498222 -308.647592)
		(width 0.16002)
		(layer "In11.Cu")
		(net "M_F_CPU1_SB_DQS_DP<3>")
	)
	(segment
		(start 74.234802 -297.738292)
		(end 74.008742 -297.738292)
		(width 0.16002)
		(layer "In11.Cu")
		(net "M_F_CPU1_SB_DQS_DP<3>")
	)
	(segment
		(start 76.490576 -293.912544)
		(end 76.490576 -295.566338)
		(width 0.09525)
		(layer "In11.Cu")
		(net "M_F_CPU1_SB_DQS_DP<3>")
	)
	(segment
		(start 67.972432 -303.161446)
		(end 67.548506 -303.585372)
		(width 0.16002)
		(layer "In11.Cu")
		(net "M_F_CPU1_SB_DQS_DP<3>")
	)
	(segment
		(start 59.566556 -312.579258)
		(end 57.75071 -312.579258)
		(width 0.16002)
		(layer "In11.Cu")
		(net "M_F_CPU1_SB_DQS_DP<3>")
	)
	(segment
		(start 76.490576 -295.566338)
		(end 76.049124 -296.00779)
		(width 0.09525)
		(layer "In11.Cu")
		(net "M_F_CPU1_SB_DQS_DP<3>")
	)
	(segment
		(start 46.183296 -313.06008)
		(end 45.333412 -312.210196)
		(width 0.16002)
		(layer "In11.Cu")
		(net "M_F_CPU1_SB_DQS_DP<3>")
	)
	(segment
		(start 73.940416 -297.669966)
		(end 73.463912 -297.669966)
		(width 0.16002)
		(layer "In11.Cu")
		(net "M_F_CPU1_SB_DQS_DP<3>")
	)
	(segment
		(start 84.351114 -290.286186)
		(end 84.505038 -290.551616)
		(width 0.09525)
		(layer "In11.Cu")
		(net "M_F_CPU1_SB_DQS_DP<3>")
	)
	(segment
		(start 28.388564 -312.210196)
		(end 28.019502 -312.579258)
		(width 0.16002)
		(layer "In11.Cu")
		(net "M_F_CPU1_SB_DQS_DP<3>")
	)
	(segment
		(start 65.771522 -305.975512)
		(end 65.703196 -305.907186)
		(width 0.16002)
		(layer "In11.Cu")
		(net "M_F_CPU1_SB_DQS_DP<3>")
	)
	(segment
		(start 22.578822 -313.092338)
		(end 22.461982 -313.209178)
		(width 0.16002)
		(layer "In11.Cu")
		(net "M_F_CPU1_SB_DQS_DP<3>")
	)
	(segment
		(start 74.412856 -297.197526)
		(end 74.481182 -297.265852)
		(width 0.16002)
		(layer "In11.Cu")
		(net "M_F_CPU1_SB_DQS_DP<3>")
	)
	(segment
		(start 67.144392 -304.602642)
		(end 67.076066 -304.534316)
		(width 0.16002)
		(layer "In11.Cu")
		(net "M_F_CPU1_SB_DQS_DP<3>")
	)
	(segment
		(start 63.429896 -308.180486)
		(end 63.498222 -308.248812)
		(width 0.16002)
		(layer "In11.Cu")
		(net "M_F_CPU1_SB_DQS_DP<3>")
	)
	(segment
		(start 65.703196 -305.907186)
		(end 65.226692 -305.907186)
		(width 0.16002)
		(layer "In11.Cu")
		(net "M_F_CPU1_SB_DQS_DP<3>")
	)
	(segment
		(start 66.175636 -305.434746)
		(end 66.243962 -305.503072)
		(width 0.16002)
		(layer "In11.Cu")
		(net "M_F_CPU1_SB_DQS_DP<3>")
	)
	(segment
		(start 50.651664 -312.579258)
		(end 50.20691 -312.579258)
		(width 0.16002)
		(layer "In11.Cu")
		(net "M_F_CPU1_SB_DQS_DP<3>")
	)
	(segment
		(start 68.743322 -303.229772)
		(end 68.517262 -303.229772)
		(width 0.16002)
		(layer "In11.Cu")
		(net "M_F_CPU1_SB_DQS_DP<3>")
	)
	(segment
		(start 70.362572 -301.610522)
		(end 70.116192 -301.856902)
		(width 0.16002)
		(layer "In11.Cu")
		(net "M_F_CPU1_SB_DQS_DP<3>")
	)
	(segment
		(start 55.64632 -313.287918)
		(end 55.52948 -313.404758)
		(width 0.16002)
		(layer "In11.Cu")
		(net "M_F_CPU1_SB_DQS_DP<3>")
	)
	(segment
		(start 70.294246 -301.316136)
		(end 70.362572 -301.384462)
		(width 0.16002)
		(layer "In11.Cu")
		(net "M_F_CPU1_SB_DQS_DP<3>")
	)
	(segment
		(start 51.020726 -312.210196)
		(end 50.651664 -312.579258)
		(width 0.16002)
		(layer "In11.Cu")
		(net "M_F_CPU1_SB_DQS_DP<3>")
	)
	(segment
		(start 63.498222 -308.647592)
		(end 59.566556 -312.579258)
		(width 0.16002)
		(layer "In11.Cu")
		(net "M_F_CPU1_SB_DQS_DP<3>")
	)
	(segment
		(start 56.12638 -313.287918)
		(end 55.64632 -313.287918)
		(width 0.16002)
		(layer "In11.Cu")
		(net "M_F_CPU1_SB_DQS_DP<3>")
	)
	(segment
		(start 68.448936 -303.161446)
		(end 67.972432 -303.161446)
		(width 0.16002)
		(layer "In11.Cu")
		(net "M_F_CPU1_SB_DQS_DP<3>")
	)
	(segment
		(start 70.718172 -300.415706)
		(end 70.294246 -300.839632)
		(width 0.16002)
		(layer "In11.Cu")
		(net "M_F_CPU1_SB_DQS_DP<3>")
	)
	(segment
		(start 27.574748 -312.579258)
		(end 26.749248 -313.404758)
		(width 0.16002)
		(layer "In11.Cu")
		(net "M_F_CPU1_SB_DQS_DP<3>")
	)
	(segment
		(start 69.345302 -301.788576)
		(end 68.921376 -302.212502)
		(width 0.16002)
		(layer "In11.Cu")
		(net "M_F_CPU1_SB_DQS_DP<3>")
	)
	(segment
		(start 70.116192 -301.856902)
		(end 69.890132 -301.856902)
		(width 0.16002)
		(layer "In11.Cu")
		(net "M_F_CPU1_SB_DQS_DP<3>")
	)
	(segment
		(start 75.607672 -296.365422)
		(end 75.381612 -296.365422)
		(width 0.16002)
		(layer "In11.Cu")
		(net "M_F_CPU1_SB_DQS_DP<3>")
	)
	(segment
		(start 67.548506 -304.061876)
		(end 67.616832 -304.130202)
		(width 0.16002)
		(layer "In11.Cu")
		(net "M_F_CPU1_SB_DQS_DP<3>")
	)
	(segment
		(start 64.330326 -307.280056)
		(end 63.853822 -307.280056)
		(width 0.16002)
		(layer "In11.Cu")
		(net "M_F_CPU1_SB_DQS_DP<3>")
	)
	(segment
		(start 67.370452 -304.602642)
		(end 67.144392 -304.602642)
		(width 0.16002)
		(layer "In11.Cu")
		(net "M_F_CPU1_SB_DQS_DP<3>")
	)
	(segment
		(start 68.921376 -302.212502)
		(end 68.921376 -302.689006)
		(width 0.16002)
		(layer "In11.Cu")
		(net "M_F_CPU1_SB_DQS_DP<3>")
	)
	(segment
		(start 35.932618 -312.210196)
		(end 35.563556 -312.579258)
		(width 0.16002)
		(layer "In11.Cu")
		(net "M_F_CPU1_SB_DQS_DP<3>")
	)
	(segment
		(start 72.861932 -299.111162)
		(end 72.635872 -299.111162)
		(width 0.16002)
		(layer "In11.Cu")
		(net "M_F_CPU1_SB_DQS_DP<3>")
	)
	(segment
		(start 33.894014 -313.404758)
		(end 33.549336 -313.06008)
		(width 0.16002)
		(layer "In11.Cu")
		(net "M_F_CPU1_SB_DQS_DP<3>")
	)
	(segment
		(start 67.616832 -304.130202)
		(end 67.616832 -304.356262)
		(width 0.16002)
		(layer "In11.Cu")
		(net "M_F_CPU1_SB_DQS_DP<3>")
	)
	(segment
		(start 81.350866 -290.616132)
		(end 81.342484 -290.611306)
		(width 0.09525)
		(layer "In11.Cu")
		(net "M_F_CPU1_SB_DQS_DP<3>")
	)
	(segment
		(start 38.639242 -313.06008)
		(end 37.789358 -312.210196)
		(width 0.16002)
		(layer "In11.Cu")
		(net "M_F_CPU1_SB_DQS_DP<3>")
	)
	(segment
		(start 48.637444 -313.06008)
		(end 46.183296 -313.06008)
		(width 0.16002)
		(layer "In11.Cu")
		(net "M_F_CPU1_SB_DQS_DP<3>")
	)
	(segment
		(start 55.52948 -313.404758)
		(end 54.428898 -313.404758)
		(width 0.16002)
		(layer "In11.Cu")
		(net "M_F_CPU1_SB_DQS_DP<3>")
	)
	(segment
		(start 71.194676 -300.415706)
		(end 70.718172 -300.415706)
		(width 0.16002)
		(layer "In11.Cu")
		(net "M_F_CPU1_SB_DQS_DP<3>")
	)
	(segment
		(start 43.476672 -312.210196)
		(end 43.10761 -312.579258)
		(width 0.16002)
		(layer "In11.Cu")
		(net "M_F_CPU1_SB_DQS_DP<3>")
	)
	(segment
		(start 64.398652 -307.348382)
		(end 64.330326 -307.280056)
		(width 0.16002)
		(layer "In11.Cu")
		(net "M_F_CPU1_SB_DQS_DP<3>")
	)
	(segment
		(start 72.091042 -299.042836)
		(end 71.667116 -299.466762)
		(width 0.16002)
		(layer "In11.Cu")
		(net "M_F_CPU1_SB_DQS_DP<3>")
	)
	(segment
		(start 49.38141 -313.404758)
		(end 48.982122 -313.404758)
		(width 0.16002)
		(layer "In11.Cu")
		(net "M_F_CPU1_SB_DQS_DP<3>")
	)
	(segment
		(start 83.599528 -290.611306)
		(end 83.591146 -290.616132)
		(width 0.09525)
		(layer "In11.Cu")
		(net "M_F_CPU1_SB_DQS_DP<3>")
	)
	(segment
		(start 45.333412 -312.210196)
		(end 43.476672 -312.210196)
		(width 0.16002)
		(layer "In11.Cu")
		(net "M_F_CPU1_SB_DQS_DP<3>")
	)
	(segment
		(start 54.428898 -313.404758)
		(end 53.876956 -312.852816)
		(width 0.16002)
		(layer "In11.Cu")
		(net "M_F_CPU1_SB_DQS_DP<3>")
	)
	(segment
		(start 69.890132 -301.856902)
		(end 69.821806 -301.788576)
		(width 0.16002)
		(layer "In11.Cu")
		(net "M_F_CPU1_SB_DQS_DP<3>")
	)
	(segment
		(start 67.616832 -304.356262)
		(end 67.370452 -304.602642)
		(width 0.16002)
		(layer "In11.Cu")
		(net "M_F_CPU1_SB_DQS_DP<3>")
	)
	(segment
		(start 75.313286 -296.297096)
		(end 74.836782 -296.297096)
		(width 0.16002)
		(layer "In11.Cu")
		(net "M_F_CPU1_SB_DQS_DP<3>")
	)
	(segment
		(start 68.989702 -302.983392)
		(end 68.743322 -303.229772)
		(width 0.16002)
		(layer "In11.Cu")
		(net "M_F_CPU1_SB_DQS_DP<3>")
	)
	(segment
		(start 64.871092 -306.875942)
		(end 64.871092 -307.102002)
		(width 0.16002)
		(layer "In11.Cu")
		(net "M_F_CPU1_SB_DQS_DP<3>")
	)
	(segment
		(start 66.599562 -304.534316)
		(end 66.175636 -304.958242)
		(width 0.16002)
		(layer "In11.Cu")
		(net "M_F_CPU1_SB_DQS_DP<3>")
	)
	(segment
		(start 68.517262 -303.229772)
		(end 68.448936 -303.161446)
		(width 0.16002)
		(layer "In11.Cu")
		(net "M_F_CPU1_SB_DQS_DP<3>")
	)
	(segment
		(start 21.981922 -313.209178)
		(end 21.70811 -312.935366)
		(width 0.16002)
		(layer "In11.Cu")
		(net "M_F_CPU1_SB_DQS_DP<3>")
	)
	(segment
		(start 66.243962 -305.729132)
		(end 65.997582 -305.975512)
		(width 0.16002)
		(layer "In11.Cu")
		(net "M_F_CPU1_SB_DQS_DP<3>")
	)
	(segment
		(start 68.989702 -302.757332)
		(end 68.989702 -302.983392)
		(width 0.16002)
		(layer "In11.Cu")
		(net "M_F_CPU1_SB_DQS_DP<3>")
	)
	(segment
		(start 69.821806 -301.788576)
		(end 69.345302 -301.788576)
		(width 0.16002)
		(layer "In11.Cu")
		(net "M_F_CPU1_SB_DQS_DP<3>")
	)
	(segment
		(start 23.058882 -313.092338)
		(end 22.578822 -313.092338)
		(width 0.16002)
		(layer "In11.Cu")
		(net "M_F_CPU1_SB_DQS_DP<3>")
	)
	(segment
		(start 26.749248 -313.404758)
		(end 26.34996 -313.404758)
		(width 0.16002)
		(layer "In11.Cu")
		(net "M_F_CPU1_SB_DQS_DP<3>")
	)
	(segment
		(start 53.520086 -312.852816)
		(end 52.877466 -312.210196)
		(width 0.16002)
		(layer "In11.Cu")
		(net "M_F_CPU1_SB_DQS_DP<3>")
	)
	(segment
		(start 75.94854 -296.024554)
		(end 75.607672 -296.365422)
		(width 0.16002)
		(layer "In11.Cu")
		(net "M_F_CPU1_SB_DQS_DP<3>")
	)
	(segment
		(start 72.567546 -299.042836)
		(end 72.091042 -299.042836)
		(width 0.16002)
		(layer "In11.Cu")
		(net "M_F_CPU1_SB_DQS_DP<3>")
	)
	(segment
		(start 75.381612 -296.365422)
		(end 75.313286 -296.297096)
		(width 0.16002)
		(layer "In11.Cu")
		(net "M_F_CPU1_SB_DQS_DP<3>")
	)
	(segment
		(start 72.635872 -299.111162)
		(end 72.567546 -299.042836)
		(width 0.16002)
		(layer "In11.Cu")
		(net "M_F_CPU1_SB_DQS_DP<3>")
	)
	(segment
		(start 74.836782 -296.297096)
		(end 74.412856 -296.721022)
		(width 0.16002)
		(layer "In11.Cu")
		(net "M_F_CPU1_SB_DQS_DP<3>")
	)
	(segment
		(start 66.175636 -304.958242)
		(end 66.175636 -305.434746)
		(width 0.16002)
		(layer "In11.Cu")
		(net "M_F_CPU1_SB_DQS_DP<3>")
	)
	(segment
		(start 50.20691 -312.579258)
		(end 49.38141 -313.404758)
		(width 0.16002)
		(layer "In11.Cu")
		(net "M_F_CPU1_SB_DQS_DP<3>")
	)
	(segment
		(start 71.489062 -300.484032)
		(end 71.263002 -300.484032)
		(width 0.16002)
		(layer "In11.Cu")
		(net "M_F_CPU1_SB_DQS_DP<3>")
	)
	(segment
		(start 24.1554 -313.06008)
		(end 24.006302 -313.209178)
		(width 0.16002)
		(layer "In11.Cu")
		(net "M_F_CPU1_SB_DQS_DP<3>")
	)
	(arc
		(start 80.40243 -290.611306)
		(mid 80.138076 -290.535657)
		(end 79.869538 -290.594796)
		(width 0.09525)
		(layer "In11.Cu")
		(net "M_F_CPU1_SB_DQS_DP<3>")
	)
	(arc
		(start 82.659474 -290.611306)
		(mid 82.471006 -290.661983)
		(end 82.282538 -290.611306)
		(width 0.09525)
		(layer "In11.Cu")
		(net "M_F_CPU1_SB_DQS_DP<3>")
	)
	(arc
		(start 81.342484 -290.611306)
		(mid 81.061052 -290.535551)
		(end 80.77962 -290.611306)
		(width 0.09525)
		(layer "In11.Cu")
		(net "M_F_CPU1_SB_DQS_DP<3>")
	)
	(arc
		(start 84.162392 -290.611306)
		(mid 83.88096 -290.535551)
		(end 83.599528 -290.611306)
		(width 0.09525)
		(layer "In11.Cu")
		(net "M_F_CPU1_SB_DQS_DP<3>")
	)
	(arc
		(start 78.001622 -291.777928)
		(mid 77.926845 -291.889934)
		(end 77.90053 -292.022022)
		(width 0.09525)
		(layer "In11.Cu")
		(net "M_F_CPU1_SB_DQS_DP<3>")
	)
	(arc
		(start 79.869538 -290.594796)
		(mid 79.710837 -290.646644)
		(end 79.54391 -290.649406)
		(width 0.09525)
		(layer "In11.Cu")
		(net "M_F_CPU1_SB_DQS_DP<3>")
	)
	(arc
		(start 83.222338 -290.611306)
		(mid 82.940906 -290.535551)
		(end 82.659474 -290.611306)
		(width 0.09525)
		(layer "In11.Cu")
		(net "M_F_CPU1_SB_DQS_DP<3>")
	)
	(arc
		(start 84.48167 -290.638484)
		(mid 84.318988 -290.660616)
		(end 84.162392 -290.611306)
		(width 0.09525)
		(layer "In11.Cu")
		(net "M_F_CPU1_SB_DQS_DP<3>")
	)
	(arc
		(start 79.54391 -290.649406)
		(mid 79.206514 -290.6821)
		(end 78.918562 -290.860988)
		(width 0.09525)
		(layer "In11.Cu")
		(net "M_F_CPU1_SB_DQS_DP<3>")
	)
	(arc
		(start 81.719674 -290.611306)
		(mid 81.535899 -290.662078)
		(end 81.350866 -290.616132)
		(width 0.09525)
		(layer "In11.Cu")
		(net "M_F_CPU1_SB_DQS_DP<3>")
	)
	(arc
		(start 80.771238 -290.616132)
		(mid 80.586206 -290.662046)
		(end 80.40243 -290.611306)
		(width 0.09525)
		(layer "In11.Cu")
		(net "M_F_CPU1_SB_DQS_DP<3>")
	)
	(arc
		(start 83.591146 -290.616132)
		(mid 83.406114 -290.662046)
		(end 83.222338 -290.611306)
		(width 0.09525)
		(layer "In11.Cu")
		(net "M_F_CPU1_SB_DQS_DP<3>")
	)
	(arc
		(start 82.282538 -290.611306)
		(mid 82.001106 -290.535551)
		(end 81.719674 -290.611306)
		(width 0.09525)
		(layer "In11.Cu")
		(net "M_F_CPU1_SB_DQS_DP<3>")
	)
	(segment
		(start 84.817966 -285.160466)
		(end 84.351114 -285.426404)
		(width 0.12954)
		(layer "F.Cu")
		(net "M_F_CPU1_SB_DQS_DP<2>")
	)
	(segment
		(start 63.755524 -298.44492)
		(end 63.755524 -298.67098)
		(width 0.16002)
		(layer "In11.Cu")
		(net "M_F_CPU1_SB_DQS_DP<2>")
	)
	(segment
		(start 27.574748 -303.229264)
		(end 26.749248 -304.054764)
		(width 0.16002)
		(layer "In11.Cu")
		(net "M_F_CPU1_SB_DQS_DP<2>")
	)
	(segment
		(start 62.331346 -299.289724)
		(end 62.331346 -299.766228)
		(width 0.16002)
		(layer "In11.Cu")
		(net "M_F_CPU1_SB_DQS_DP<2>")
	)
	(segment
		(start 70.568566 -291.529008)
		(end 70.619874 -291.58057)
		(width 0.16002)
		(layer "In11.Cu")
		(net "M_F_CPU1_SB_DQS_DP<2>")
	)
	(segment
		(start 70.619874 -291.80663)
		(end 70.373494 -292.05301)
		(width 0.16002)
		(layer "In11.Cu")
		(net "M_F_CPU1_SB_DQS_DP<2>")
	)
	(segment
		(start 56.92521 -304.054764)
		(end 54.428898 -304.054764)
		(width 0.16002)
		(layer "In11.Cu")
		(net "M_F_CPU1_SB_DQS_DP<2>")
	)
	(segment
		(start 63.283084 -298.91736)
		(end 63.231522 -298.865798)
		(width 0.16002)
		(layer "In11.Cu")
		(net "M_F_CPU1_SB_DQS_DP<2>")
	)
	(segment
		(start 71.520304 -290.68014)
		(end 71.468742 -290.628578)
		(width 0.16002)
		(layer "In11.Cu")
		(net "M_F_CPU1_SB_DQS_DP<2>")
	)
	(segment
		(start 76.70546 -286.521652)
		(end 76.646278 -286.46247)
		(width 0.09525)
		(layer "In11.Cu")
		(net "M_F_CPU1_SB_DQS_DP<2>")
	)
	(segment
		(start 37.789358 -302.860202)
		(end 35.932618 -302.860202)
		(width 0.16002)
		(layer "In11.Cu")
		(net "M_F_CPU1_SB_DQS_DP<2>")
	)
	(segment
		(start 65.977262 -296.120058)
		(end 65.501012 -296.120058)
		(width 0.16002)
		(layer "In11.Cu")
		(net "M_F_CPU1_SB_DQS_DP<2>")
	)
	(segment
		(start 68.774564 -293.42588)
		(end 68.723002 -293.374318)
		(width 0.16002)
		(layer "In11.Cu")
		(net "M_F_CPU1_SB_DQS_DP<2>")
	)
	(segment
		(start 41.438068 -304.054764)
		(end 41.09339 -303.710086)
		(width 0.16002)
		(layer "In11.Cu")
		(net "M_F_CPU1_SB_DQS_DP<2>")
	)
	(segment
		(start 77.923136 -285.80334)
		(end 77.204824 -286.521652)
		(width 0.09525)
		(layer "In11.Cu")
		(net "M_F_CPU1_SB_DQS_DP<2>")
	)
	(segment
		(start 26.749248 -304.054764)
		(end 26.34996 -304.054764)
		(width 0.16002)
		(layer "In11.Cu")
		(net "M_F_CPU1_SB_DQS_DP<2>")
	)
	(segment
		(start 62.382654 -300.04385)
		(end 62.136274 -300.29023)
		(width 0.16002)
		(layer "In11.Cu")
		(net "M_F_CPU1_SB_DQS_DP<2>")
	)
	(segment
		(start 23.21052 -303.742344)
		(end 22.73046 -303.742344)
		(width 0.16002)
		(layer "In11.Cu")
		(net "M_F_CPU1_SB_DQS_DP<2>")
	)
	(segment
		(start 26.005282 -303.710086)
		(end 24.1554 -303.710086)
		(width 0.16002)
		(layer "In11.Cu")
		(net "M_F_CPU1_SB_DQS_DP<2>")
	)
	(segment
		(start 64.882014 -297.54449)
		(end 64.655954 -297.54449)
		(width 0.16002)
		(layer "In11.Cu")
		(net "M_F_CPU1_SB_DQS_DP<2>")
	)
	(segment
		(start 66.028824 -296.17162)
		(end 65.977262 -296.120058)
		(width 0.16002)
		(layer "In11.Cu")
		(net "M_F_CPU1_SB_DQS_DP<2>")
	)
	(segment
		(start 79.858362 -285.74111)
		(end 79.840328 -285.751524)
		(width 0.09525)
		(layer "In11.Cu")
		(net "M_F_CPU1_SB_DQS_DP<2>")
	)
	(segment
		(start 26.34996 -304.054764)
		(end 26.005282 -303.710086)
		(width 0.16002)
		(layer "In11.Cu")
		(net "M_F_CPU1_SB_DQS_DP<2>")
	)
	(segment
		(start 67.350132 -294.747188)
		(end 66.873882 -294.747188)
		(width 0.16002)
		(layer "In11.Cu")
		(net "M_F_CPU1_SB_DQS_DP<2>")
	)
	(segment
		(start 34.293302 -304.054764)
		(end 33.894014 -304.054764)
		(width 0.16002)
		(layer "In11.Cu")
		(net "M_F_CPU1_SB_DQS_DP<2>")
	)
	(segment
		(start 49.38141 -304.054764)
		(end 48.982122 -304.054764)
		(width 0.16002)
		(layer "In11.Cu")
		(net "M_F_CPU1_SB_DQS_DP<2>")
	)
	(segment
		(start 24.1554 -303.710086)
		(end 24.006302 -303.859184)
		(width 0.16002)
		(layer "In11.Cu")
		(net "M_F_CPU1_SB_DQS_DP<2>")
	)
	(segment
		(start 65.077086 -296.543984)
		(end 65.077086 -297.020488)
		(width 0.16002)
		(layer "In11.Cu")
		(net "M_F_CPU1_SB_DQS_DP<2>")
	)
	(segment
		(start 77.204824 -286.521652)
		(end 76.70546 -286.521652)
		(width 0.09525)
		(layer "In11.Cu")
		(net "M_F_CPU1_SB_DQS_DP<2>")
	)
	(segment
		(start 53.520086 -303.502822)
		(end 52.877466 -302.860202)
		(width 0.16002)
		(layer "In11.Cu")
		(net "M_F_CPU1_SB_DQS_DP<2>")
	)
	(segment
		(start 69.195696 -292.425374)
		(end 69.195696 -292.901878)
		(width 0.16002)
		(layer "In11.Cu")
		(net "M_F_CPU1_SB_DQS_DP<2>")
	)
	(segment
		(start 70.992492 -290.628578)
		(end 70.568566 -291.052504)
		(width 0.16002)
		(layer "In11.Cu")
		(net "M_F_CPU1_SB_DQS_DP<2>")
	)
	(segment
		(start 23.32736 -303.859184)
		(end 23.21052 -303.742344)
		(width 0.16002)
		(layer "In11.Cu")
		(net "M_F_CPU1_SB_DQS_DP<2>")
	)
	(segment
		(start 51.020726 -302.860202)
		(end 50.651664 -303.229264)
		(width 0.16002)
		(layer "In11.Cu")
		(net "M_F_CPU1_SB_DQS_DP<2>")
	)
	(segment
		(start 84.351114 -285.426404)
		(end 84.505038 -285.691834)
		(width 0.09525)
		(layer "In11.Cu")
		(net "M_F_CPU1_SB_DQS_DP<2>")
	)
	(segment
		(start 50.20691 -303.229264)
		(end 49.38141 -304.054764)
		(width 0.16002)
		(layer "In11.Cu")
		(net "M_F_CPU1_SB_DQS_DP<2>")
	)
	(segment
		(start 31.095188 -303.710086)
		(end 30.245304 -302.860202)
		(width 0.16002)
		(layer "In11.Cu")
		(net "M_F_CPU1_SB_DQS_DP<2>")
	)
	(segment
		(start 66.501264 -295.92524)
		(end 66.254884 -296.17162)
		(width 0.16002)
		(layer "In11.Cu")
		(net "M_F_CPU1_SB_DQS_DP<2>")
	)
	(segment
		(start 75.96124 -286.46247)
		(end 73.168002 -289.255708)
		(width 0.16002)
		(layer "In11.Cu")
		(net "M_F_CPU1_SB_DQS_DP<2>")
	)
	(segment
		(start 64.655954 -297.54449)
		(end 64.604392 -297.492928)
		(width 0.16002)
		(layer "In11.Cu")
		(net "M_F_CPU1_SB_DQS_DP<2>")
	)
	(segment
		(start 65.128394 -297.07205)
		(end 65.128394 -297.29811)
		(width 0.16002)
		(layer "In11.Cu")
		(net "M_F_CPU1_SB_DQS_DP<2>")
	)
	(segment
		(start 60.958476 -301.139098)
		(end 61.009784 -301.19066)
		(width 0.16002)
		(layer "In11.Cu")
		(net "M_F_CPU1_SB_DQS_DP<2>")
	)
	(segment
		(start 61.858652 -300.238668)
		(end 61.382402 -300.238668)
		(width 0.16002)
		(layer "In11.Cu")
		(net "M_F_CPU1_SB_DQS_DP<2>")
	)
	(segment
		(start 65.501012 -296.120058)
		(end 65.077086 -296.543984)
		(width 0.16002)
		(layer "In11.Cu")
		(net "M_F_CPU1_SB_DQS_DP<2>")
	)
	(segment
		(start 43.10761 -303.229264)
		(end 42.662856 -303.229264)
		(width 0.16002)
		(layer "In11.Cu")
		(net "M_F_CPU1_SB_DQS_DP<2>")
	)
	(segment
		(start 59.636914 -302.78959)
		(end 59.225942 -303.200562)
		(width 0.16002)
		(layer "In11.Cu")
		(net "M_F_CPU1_SB_DQS_DP<2>")
	)
	(segment
		(start 69.247004 -292.95344)
		(end 69.247004 -293.1795)
		(width 0.16002)
		(layer "In11.Cu")
		(net "M_F_CPU1_SB_DQS_DP<2>")
	)
	(segment
		(start 48.982122 -304.054764)
		(end 48.637444 -303.710086)
		(width 0.16002)
		(layer "In11.Cu")
		(net "M_F_CPU1_SB_DQS_DP<2>")
	)
	(segment
		(start 68.246752 -293.374318)
		(end 67.822826 -293.798244)
		(width 0.16002)
		(layer "In11.Cu")
		(net "M_F_CPU1_SB_DQS_DP<2>")
	)
	(segment
		(start 38.639242 -303.710086)
		(end 37.789358 -302.860202)
		(width 0.16002)
		(layer "In11.Cu")
		(net "M_F_CPU1_SB_DQS_DP<2>")
	)
	(segment
		(start 57.75071 -303.229264)
		(end 56.92521 -304.054764)
		(width 0.16002)
		(layer "In11.Cu")
		(net "M_F_CPU1_SB_DQS_DP<2>")
	)
	(segment
		(start 33.549336 -303.710086)
		(end 31.095188 -303.710086)
		(width 0.16002)
		(layer "In11.Cu")
		(net "M_F_CPU1_SB_DQS_DP<2>")
	)
	(segment
		(start 76.622656 -286.46247)
		(end 75.96124 -286.46247)
		(width 0.16002)
		(layer "In11.Cu")
		(net "M_F_CPU1_SB_DQS_DP<2>")
	)
	(segment
		(start 35.932618 -302.860202)
		(end 35.563556 -303.229264)
		(width 0.16002)
		(layer "In11.Cu")
		(net "M_F_CPU1_SB_DQS_DP<2>")
	)
	(segment
		(start 78.71079 -285.80334)
		(end 77.923136 -285.80334)
		(width 0.09525)
		(layer "In11.Cu")
		(net "M_F_CPU1_SB_DQS_DP<2>")
	)
	(segment
		(start 61.009784 -301.41672)
		(end 60.763404 -301.6631)
		(width 0.16002)
		(layer "In11.Cu")
		(net "M_F_CPU1_SB_DQS_DP<2>")
	)
	(segment
		(start 80.77962 -285.751524)
		(end 80.771238 -285.75635)
		(width 0.09525)
		(layer "In11.Cu")
		(net "M_F_CPU1_SB_DQS_DP<2>")
	)
	(segment
		(start 41.837356 -304.054764)
		(end 41.438068 -304.054764)
		(width 0.16002)
		(layer "In11.Cu")
		(net "M_F_CPU1_SB_DQS_DP<2>")
	)
	(segment
		(start 63.755524 -298.67098)
		(end 63.509144 -298.91736)
		(width 0.16002)
		(layer "In11.Cu")
		(net "M_F_CPU1_SB_DQS_DP<2>")
	)
	(segment
		(start 66.254884 -296.17162)
		(end 66.028824 -296.17162)
		(width 0.16002)
		(layer "In11.Cu")
		(net "M_F_CPU1_SB_DQS_DP<2>")
	)
	(segment
		(start 60.287154 -301.6631)
		(end 59.636914 -302.31334)
		(width 0.16002)
		(layer "In11.Cu")
		(net "M_F_CPU1_SB_DQS_DP<2>")
	)
	(segment
		(start 62.331346 -299.766228)
		(end 62.382654 -299.81779)
		(width 0.16002)
		(layer "In11.Cu")
		(net "M_F_CPU1_SB_DQS_DP<2>")
	)
	(segment
		(start 72.365362 -289.255708)
		(end 71.941436 -289.679634)
		(width 0.16002)
		(layer "In11.Cu")
		(net "M_F_CPU1_SB_DQS_DP<2>")
	)
	(segment
		(start 69.000624 -293.42588)
		(end 68.774564 -293.42588)
		(width 0.16002)
		(layer "In11.Cu")
		(net "M_F_CPU1_SB_DQS_DP<2>")
	)
	(segment
		(start 59.225942 -303.200562)
		(end 59.156854 -303.229264)
		(width 0.16002)
		(layer "In11.Cu")
		(net "M_F_CPU1_SB_DQS_DP<2>")
	)
	(segment
		(start 70.619874 -291.58057)
		(end 70.619874 -291.80663)
		(width 0.16002)
		(layer "In11.Cu")
		(net "M_F_CPU1_SB_DQS_DP<2>")
	)
	(segment
		(start 67.874134 -294.55237)
		(end 67.627754 -294.79875)
		(width 0.16002)
		(layer "In11.Cu")
		(net "M_F_CPU1_SB_DQS_DP<2>")
	)
	(segment
		(start 81.350866 -285.75635)
		(end 81.342484 -285.751524)
		(width 0.09525)
		(layer "In11.Cu")
		(net "M_F_CPU1_SB_DQS_DP<2>")
	)
	(segment
		(start 71.992744 -290.2077)
		(end 71.992744 -290.43376)
		(width 0.16002)
		(layer "In11.Cu")
		(net "M_F_CPU1_SB_DQS_DP<2>")
	)
	(segment
		(start 69.195696 -292.901878)
		(end 69.247004 -292.95344)
		(width 0.16002)
		(layer "In11.Cu")
		(net "M_F_CPU1_SB_DQS_DP<2>")
	)
	(segment
		(start 22.61362 -303.859184)
		(end 21.981922 -303.859184)
		(width 0.16002)
		(layer "In11.Cu")
		(net "M_F_CPU1_SB_DQS_DP<2>")
	)
	(segment
		(start 69.247004 -293.1795)
		(end 69.000624 -293.42588)
		(width 0.16002)
		(layer "In11.Cu")
		(net "M_F_CPU1_SB_DQS_DP<2>")
	)
	(segment
		(start 53.876956 -303.502822)
		(end 53.520086 -303.502822)
		(width 0.16002)
		(layer "In11.Cu")
		(net "M_F_CPU1_SB_DQS_DP<2>")
	)
	(segment
		(start 30.245304 -302.860202)
		(end 28.388564 -302.860202)
		(width 0.16002)
		(layer "In11.Cu")
		(net "M_F_CPU1_SB_DQS_DP<2>")
	)
	(segment
		(start 43.476672 -302.860202)
		(end 43.10761 -303.229264)
		(width 0.16002)
		(layer "In11.Cu")
		(net "M_F_CPU1_SB_DQS_DP<2>")
	)
	(segment
		(start 83.599528 -285.751524)
		(end 83.591146 -285.75635)
		(width 0.09525)
		(layer "In11.Cu")
		(net "M_F_CPU1_SB_DQS_DP<2>")
	)
	(segment
		(start 67.822826 -294.274748)
		(end 67.874134 -294.32631)
		(width 0.16002)
		(layer "In11.Cu")
		(net "M_F_CPU1_SB_DQS_DP<2>")
	)
	(segment
		(start 73.168002 -289.255708)
		(end 72.365362 -289.255708)
		(width 0.16002)
		(layer "In11.Cu")
		(net "M_F_CPU1_SB_DQS_DP<2>")
	)
	(segment
		(start 71.992744 -290.43376)
		(end 71.746364 -290.68014)
		(width 0.16002)
		(layer "In11.Cu")
		(net "M_F_CPU1_SB_DQS_DP<2>")
	)
	(segment
		(start 67.822826 -293.798244)
		(end 67.822826 -294.274748)
		(width 0.16002)
		(layer "In11.Cu")
		(net "M_F_CPU1_SB_DQS_DP<2>")
	)
	(segment
		(start 63.704216 -297.916854)
		(end 63.704216 -298.393358)
		(width 0.16002)
		(layer "In11.Cu")
		(net "M_F_CPU1_SB_DQS_DP<2>")
	)
	(segment
		(start 61.910214 -300.29023)
		(end 61.858652 -300.238668)
		(width 0.16002)
		(layer "In11.Cu")
		(net "M_F_CPU1_SB_DQS_DP<2>")
	)
	(segment
		(start 66.449956 -295.171114)
		(end 66.449956 -295.647618)
		(width 0.16002)
		(layer "In11.Cu")
		(net "M_F_CPU1_SB_DQS_DP<2>")
	)
	(segment
		(start 64.128142 -297.492928)
		(end 63.704216 -297.916854)
		(width 0.16002)
		(layer "In11.Cu")
		(net "M_F_CPU1_SB_DQS_DP<2>")
	)
	(segment
		(start 66.501264 -295.69918)
		(end 66.501264 -295.92524)
		(width 0.16002)
		(layer "In11.Cu")
		(net "M_F_CPU1_SB_DQS_DP<2>")
	)
	(segment
		(start 61.382402 -300.238668)
		(end 60.958476 -300.662594)
		(width 0.16002)
		(layer "In11.Cu")
		(net "M_F_CPU1_SB_DQS_DP<2>")
	)
	(segment
		(start 67.874134 -294.32631)
		(end 67.874134 -294.55237)
		(width 0.16002)
		(layer "In11.Cu")
		(net "M_F_CPU1_SB_DQS_DP<2>")
	)
	(segment
		(start 70.095872 -292.001448)
		(end 69.619622 -292.001448)
		(width 0.16002)
		(layer "In11.Cu")
		(net "M_F_CPU1_SB_DQS_DP<2>")
	)
	(segment
		(start 63.704216 -298.393358)
		(end 63.755524 -298.44492)
		(width 0.16002)
		(layer "In11.Cu")
		(net "M_F_CPU1_SB_DQS_DP<2>")
	)
	(segment
		(start 62.382654 -299.81779)
		(end 62.382654 -300.04385)
		(width 0.16002)
		(layer "In11.Cu")
		(net "M_F_CPU1_SB_DQS_DP<2>")
	)
	(segment
		(start 69.619622 -292.001448)
		(end 69.195696 -292.425374)
		(width 0.16002)
		(layer "In11.Cu")
		(net "M_F_CPU1_SB_DQS_DP<2>")
	)
	(segment
		(start 35.563556 -303.229264)
		(end 35.118802 -303.229264)
		(width 0.16002)
		(layer "In11.Cu")
		(net "M_F_CPU1_SB_DQS_DP<2>")
	)
	(segment
		(start 70.373494 -292.05301)
		(end 70.147434 -292.05301)
		(width 0.16002)
		(layer "In11.Cu")
		(net "M_F_CPU1_SB_DQS_DP<2>")
	)
	(segment
		(start 60.958476 -300.662594)
		(end 60.958476 -301.139098)
		(width 0.16002)
		(layer "In11.Cu")
		(net "M_F_CPU1_SB_DQS_DP<2>")
	)
	(segment
		(start 24.006302 -303.859184)
		(end 23.32736 -303.859184)
		(width 0.16002)
		(layer "In11.Cu")
		(net "M_F_CPU1_SB_DQS_DP<2>")
	)
	(segment
		(start 79.840328 -285.751524)
		(end 79.831946 -285.75635)
		(width 0.09525)
		(layer "In11.Cu")
		(net "M_F_CPU1_SB_DQS_DP<2>")
	)
	(segment
		(start 71.746364 -290.68014)
		(end 71.520304 -290.68014)
		(width 0.16002)
		(layer "In11.Cu")
		(net "M_F_CPU1_SB_DQS_DP<2>")
	)
	(segment
		(start 54.428898 -304.054764)
		(end 53.876956 -303.502822)
		(width 0.16002)
		(layer "In11.Cu")
		(net "M_F_CPU1_SB_DQS_DP<2>")
	)
	(segment
		(start 63.231522 -298.865798)
		(end 62.755272 -298.865798)
		(width 0.16002)
		(layer "In11.Cu")
		(net "M_F_CPU1_SB_DQS_DP<2>")
	)
	(segment
		(start 71.941436 -289.679634)
		(end 71.941436 -290.156138)
		(width 0.16002)
		(layer "In11.Cu")
		(net "M_F_CPU1_SB_DQS_DP<2>")
	)
	(segment
		(start 21.981922 -303.859184)
		(end 21.70811 -303.585372)
		(width 0.16002)
		(layer "In11.Cu")
		(net "M_F_CPU1_SB_DQS_DP<2>")
	)
	(segment
		(start 84.505038 -285.691834)
		(end 84.48167 -285.778702)
		(width 0.09525)
		(layer "In11.Cu")
		(net "M_F_CPU1_SB_DQS_DP<2>")
	)
	(segment
		(start 48.637444 -303.710086)
		(end 46.183296 -303.710086)
		(width 0.16002)
		(layer "In11.Cu")
		(net "M_F_CPU1_SB_DQS_DP<2>")
	)
	(segment
		(start 79.463646 -285.751524)
		(end 79.445612 -285.74111)
		(width 0.09525)
		(layer "In11.Cu")
		(net "M_F_CPU1_SB_DQS_DP<2>")
	)
	(segment
		(start 66.449956 -295.647618)
		(end 66.501264 -295.69918)
		(width 0.16002)
		(layer "In11.Cu")
		(net "M_F_CPU1_SB_DQS_DP<2>")
	)
	(segment
		(start 35.118802 -303.229264)
		(end 34.293302 -304.054764)
		(width 0.16002)
		(layer "In11.Cu")
		(net "M_F_CPU1_SB_DQS_DP<2>")
	)
	(segment
		(start 45.333412 -302.860202)
		(end 43.476672 -302.860202)
		(width 0.16002)
		(layer "In11.Cu")
		(net "M_F_CPU1_SB_DQS_DP<2>")
	)
	(segment
		(start 71.468742 -290.628578)
		(end 70.992492 -290.628578)
		(width 0.16002)
		(layer "In11.Cu")
		(net "M_F_CPU1_SB_DQS_DP<2>")
	)
	(segment
		(start 52.877466 -302.860202)
		(end 51.020726 -302.860202)
		(width 0.16002)
		(layer "In11.Cu")
		(net "M_F_CPU1_SB_DQS_DP<2>")
	)
	(segment
		(start 59.636914 -302.31334)
		(end 59.636914 -302.78959)
		(width 0.16002)
		(layer "In11.Cu")
		(net "M_F_CPU1_SB_DQS_DP<2>")
	)
	(segment
		(start 33.894014 -304.054764)
		(end 33.549336 -303.710086)
		(width 0.16002)
		(layer "In11.Cu")
		(net "M_F_CPU1_SB_DQS_DP<2>")
	)
	(segment
		(start 76.646278 -286.46247)
		(end 76.622656 -286.46247)
		(width 0.09525)
		(layer "In11.Cu")
		(net "M_F_CPU1_SB_DQS_DP<2>")
	)
	(segment
		(start 22.73046 -303.742344)
		(end 22.61362 -303.859184)
		(width 0.16002)
		(layer "In11.Cu")
		(net "M_F_CPU1_SB_DQS_DP<2>")
	)
	(segment
		(start 67.627754 -294.79875)
		(end 67.401694 -294.79875)
		(width 0.16002)
		(layer "In11.Cu")
		(net "M_F_CPU1_SB_DQS_DP<2>")
	)
	(segment
		(start 65.077086 -297.020488)
		(end 65.128394 -297.07205)
		(width 0.16002)
		(layer "In11.Cu")
		(net "M_F_CPU1_SB_DQS_DP<2>")
	)
	(segment
		(start 46.183296 -303.710086)
		(end 45.333412 -302.860202)
		(width 0.16002)
		(layer "In11.Cu")
		(net "M_F_CPU1_SB_DQS_DP<2>")
	)
	(segment
		(start 62.136274 -300.29023)
		(end 61.910214 -300.29023)
		(width 0.16002)
		(layer "In11.Cu")
		(net "M_F_CPU1_SB_DQS_DP<2>")
	)
	(segment
		(start 41.09339 -303.710086)
		(end 38.639242 -303.710086)
		(width 0.16002)
		(layer "In11.Cu")
		(net "M_F_CPU1_SB_DQS_DP<2>")
	)
	(segment
		(start 63.509144 -298.91736)
		(end 63.283084 -298.91736)
		(width 0.16002)
		(layer "In11.Cu")
		(net "M_F_CPU1_SB_DQS_DP<2>")
	)
	(segment
		(start 71.941436 -290.156138)
		(end 71.992744 -290.2077)
		(width 0.16002)
		(layer "In11.Cu")
		(net "M_F_CPU1_SB_DQS_DP<2>")
	)
	(segment
		(start 28.388564 -302.860202)
		(end 28.019502 -303.229264)
		(width 0.16002)
		(layer "In11.Cu")
		(net "M_F_CPU1_SB_DQS_DP<2>")
	)
	(segment
		(start 70.568566 -291.052504)
		(end 70.568566 -291.529008)
		(width 0.16002)
		(layer "In11.Cu")
		(net "M_F_CPU1_SB_DQS_DP<2>")
	)
	(segment
		(start 64.604392 -297.492928)
		(end 64.128142 -297.492928)
		(width 0.16002)
		(layer "In11.Cu")
		(net "M_F_CPU1_SB_DQS_DP<2>")
	)
	(segment
		(start 62.755272 -298.865798)
		(end 62.331346 -299.289724)
		(width 0.16002)
		(layer "In11.Cu")
		(net "M_F_CPU1_SB_DQS_DP<2>")
	)
	(segment
		(start 28.019502 -303.229264)
		(end 27.574748 -303.229264)
		(width 0.16002)
		(layer "In11.Cu")
		(net "M_F_CPU1_SB_DQS_DP<2>")
	)
	(segment
		(start 42.662856 -303.229264)
		(end 41.837356 -304.054764)
		(width 0.16002)
		(layer "In11.Cu")
		(net "M_F_CPU1_SB_DQS_DP<2>")
	)
	(segment
		(start 68.723002 -293.374318)
		(end 68.246752 -293.374318)
		(width 0.16002)
		(layer "In11.Cu")
		(net "M_F_CPU1_SB_DQS_DP<2>")
	)
	(segment
		(start 66.873882 -294.747188)
		(end 66.449956 -295.171114)
		(width 0.16002)
		(layer "In11.Cu")
		(net "M_F_CPU1_SB_DQS_DP<2>")
	)
	(segment
		(start 60.763404 -301.6631)
		(end 60.287154 -301.6631)
		(width 0.16002)
		(layer "In11.Cu")
		(net "M_F_CPU1_SB_DQS_DP<2>")
	)
	(segment
		(start 61.009784 -301.19066)
		(end 61.009784 -301.41672)
		(width 0.16002)
		(layer "In11.Cu")
		(net "M_F_CPU1_SB_DQS_DP<2>")
	)
	(segment
		(start 50.651664 -303.229264)
		(end 50.20691 -303.229264)
		(width 0.16002)
		(layer "In11.Cu")
		(net "M_F_CPU1_SB_DQS_DP<2>")
	)
	(segment
		(start 70.147434 -292.05301)
		(end 70.095872 -292.001448)
		(width 0.16002)
		(layer "In11.Cu")
		(net "M_F_CPU1_SB_DQS_DP<2>")
	)
	(segment
		(start 65.128394 -297.29811)
		(end 64.882014 -297.54449)
		(width 0.16002)
		(layer "In11.Cu")
		(net "M_F_CPU1_SB_DQS_DP<2>")
	)
	(segment
		(start 59.156854 -303.229264)
		(end 57.75071 -303.229264)
		(width 0.16002)
		(layer "In11.Cu")
		(net "M_F_CPU1_SB_DQS_DP<2>")
	)
	(segment
		(start 67.401694 -294.79875)
		(end 67.350132 -294.747188)
		(width 0.16002)
		(layer "In11.Cu")
		(net "M_F_CPU1_SB_DQS_DP<2>")
	)
	(arc
		(start 81.342484 -285.751524)
		(mid 81.061052 -285.675769)
		(end 80.77962 -285.751524)
		(width 0.09525)
		(layer "In11.Cu")
		(net "M_F_CPU1_SB_DQS_DP<2>")
	)
	(arc
		(start 83.591146 -285.75635)
		(mid 83.406114 -285.802264)
		(end 83.222338 -285.751524)
		(width 0.09525)
		(layer "In11.Cu")
		(net "M_F_CPU1_SB_DQS_DP<2>")
	)
	(arc
		(start 80.771238 -285.75635)
		(mid 80.586206 -285.802264)
		(end 80.40243 -285.751524)
		(width 0.09525)
		(layer "In11.Cu")
		(net "M_F_CPU1_SB_DQS_DP<2>")
	)
	(arc
		(start 84.48167 -285.778702)
		(mid 84.318988 -285.800834)
		(end 84.162392 -285.751524)
		(width 0.09525)
		(layer "In11.Cu")
		(net "M_F_CPU1_SB_DQS_DP<2>")
	)
	(arc
		(start 79.445612 -285.74111)
		(mid 79.17147 -285.675531)
		(end 78.90002 -285.751524)
		(width 0.09525)
		(layer "In11.Cu")
		(net "M_F_CPU1_SB_DQS_DP<2>")
	)
	(arc
		(start 84.162392 -285.751524)
		(mid 83.88096 -285.675769)
		(end 83.599528 -285.751524)
		(width 0.09525)
		(layer "In11.Cu")
		(net "M_F_CPU1_SB_DQS_DP<2>")
	)
	(arc
		(start 80.40243 -285.751524)
		(mid 80.131742 -285.675872)
		(end 79.858362 -285.74111)
		(width 0.09525)
		(layer "In11.Cu")
		(net "M_F_CPU1_SB_DQS_DP<2>")
	)
	(arc
		(start 78.90002 -285.751524)
		(mid 78.808837 -285.789954)
		(end 78.71079 -285.80334)
		(width 0.09525)
		(layer "In11.Cu")
		(net "M_F_CPU1_SB_DQS_DP<2>")
	)
	(arc
		(start 82.282538 -285.751524)
		(mid 82.001106 -285.675769)
		(end 81.719674 -285.751524)
		(width 0.09525)
		(layer "In11.Cu")
		(net "M_F_CPU1_SB_DQS_DP<2>")
	)
	(arc
		(start 83.222338 -285.751524)
		(mid 82.940906 -285.675769)
		(end 82.659474 -285.751524)
		(width 0.09525)
		(layer "In11.Cu")
		(net "M_F_CPU1_SB_DQS_DP<2>")
	)
	(arc
		(start 79.831946 -285.75635)
		(mid 79.647168 -285.802143)
		(end 79.463646 -285.751524)
		(width 0.09525)
		(layer "In11.Cu")
		(net "M_F_CPU1_SB_DQS_DP<2>")
	)
	(arc
		(start 82.659474 -285.751524)
		(mid 82.471006 -285.802201)
		(end 82.282538 -285.751524)
		(width 0.09525)
		(layer "In11.Cu")
		(net "M_F_CPU1_SB_DQS_DP<2>")
	)
	(arc
		(start 81.719674 -285.751524)
		(mid 81.535899 -285.802296)
		(end 81.350866 -285.75635)
		(width 0.09525)
		(layer "In11.Cu")
		(net "M_F_CPU1_SB_DQS_DP<2>")
	)
	(segment
		(start 84.817966 -280.30043)
		(end 84.351114 -280.566368)
		(width 0.12954)
		(layer "F.Cu")
		(net "M_F_CPU1_SB_DQS_DP<1>")
	)
	(segment
		(start 27.574748 -293.87927)
		(end 28.019502 -293.87927)
		(width 0.16002)
		(layer "In11.Cu")
		(net "M_F_CPU1_SB_DQS_DP<1>")
	)
	(segment
		(start 67.5132 -285.18739)
		(end 67.936872 -284.763718)
		(width 0.16002)
		(layer "In11.Cu")
		(net "M_F_CPU1_SB_DQS_DP<1>")
	)
	(segment
		(start 63.50635 -290.124896)
		(end 63.50635 -289.898836)
		(width 0.16002)
		(layer "In11.Cu")
		(net "M_F_CPU1_SB_DQS_DP<1>")
	)
	(segment
		(start 41.09339 -294.360092)
		(end 41.438068 -294.70477)
		(width 0.16002)
		(layer "In11.Cu")
		(net "M_F_CPU1_SB_DQS_DP<1>")
	)
	(segment
		(start 50.651664 -293.87927)
		(end 51.020726 -293.510208)
		(width 0.16002)
		(layer "In11.Cu")
		(net "M_F_CPU1_SB_DQS_DP<1>")
	)
	(segment
		(start 80.771238 -280.896314)
		(end 80.77962 -280.891488)
		(width 0.09525)
		(layer "In11.Cu")
		(net "M_F_CPU1_SB_DQS_DP<1>")
	)
	(segment
		(start 64.879982 -288.525204)
		(end 64.765936 -288.411158)
		(width 0.16002)
		(layer "In11.Cu")
		(net "M_F_CPU1_SB_DQS_DP<1>")
	)
	(segment
		(start 67.627246 -285.77794)
		(end 67.5132 -285.663894)
		(width 0.16002)
		(layer "In11.Cu")
		(net "M_F_CPU1_SB_DQS_DP<1>")
	)
	(segment
		(start 61.38164 -291.745924)
		(end 61.885322 -291.745924)
		(width 0.16002)
		(layer "In11.Cu")
		(net "M_F_CPU1_SB_DQS_DP<1>")
	)
	(segment
		(start 64.765936 -287.934654)
		(end 65.189608 -287.510982)
		(width 0.16002)
		(layer "In11.Cu")
		(net "M_F_CPU1_SB_DQS_DP<1>")
	)
	(segment
		(start 62.442344 -290.258246)
		(end 62.918848 -290.258246)
		(width 0.16002)
		(layer "In11.Cu")
		(net "M_F_CPU1_SB_DQS_DP<1>")
	)
	(segment
		(start 66.139568 -287.037526)
		(end 66.139568 -286.561022)
		(width 0.16002)
		(layer "In11.Cu")
		(net "M_F_CPU1_SB_DQS_DP<1>")
	)
	(segment
		(start 70.997064 -282.1305)
		(end 71.500746 -282.1305)
		(width 0.16002)
		(layer "In11.Cu")
		(net "M_F_CPU1_SB_DQS_DP<1>")
	)
	(segment
		(start 35.118802 -293.87927)
		(end 35.563556 -293.87927)
		(width 0.16002)
		(layer "In11.Cu")
		(net "M_F_CPU1_SB_DQS_DP<1>")
	)
	(segment
		(start 65.189608 -287.510982)
		(end 65.666112 -287.510982)
		(width 0.16002)
		(layer "In11.Cu")
		(net "M_F_CPU1_SB_DQS_DP<1>")
	)
	(segment
		(start 63.815976 -288.884614)
		(end 64.29248 -288.884614)
		(width 0.16002)
		(layer "In11.Cu")
		(net "M_F_CPU1_SB_DQS_DP<1>")
	)
	(segment
		(start 66.139568 -286.561022)
		(end 66.56324 -286.13735)
		(width 0.16002)
		(layer "In11.Cu")
		(net "M_F_CPU1_SB_DQS_DP<1>")
	)
	(segment
		(start 83.591146 -280.896314)
		(end 83.599528 -280.891488)
		(width 0.09525)
		(layer "In11.Cu")
		(net "M_F_CPU1_SB_DQS_DP<1>")
	)
	(segment
		(start 62.018672 -290.681918)
		(end 62.442344 -290.258246)
		(width 0.16002)
		(layer "In11.Cu")
		(net "M_F_CPU1_SB_DQS_DP<1>")
	)
	(segment
		(start 43.476672 -293.510208)
		(end 45.333412 -293.510208)
		(width 0.16002)
		(layer "In11.Cu")
		(net "M_F_CPU1_SB_DQS_DP<1>")
	)
	(segment
		(start 64.29248 -288.884614)
		(end 64.406526 -288.99866)
		(width 0.16002)
		(layer "In11.Cu")
		(net "M_F_CPU1_SB_DQS_DP<1>")
	)
	(segment
		(start 28.019502 -293.87927)
		(end 28.388564 -293.510208)
		(width 0.16002)
		(layer "In11.Cu")
		(net "M_F_CPU1_SB_DQS_DP<1>")
	)
	(segment
		(start 63.032894 -290.372292)
		(end 63.258954 -290.372292)
		(width 0.16002)
		(layer "In11.Cu")
		(net "M_F_CPU1_SB_DQS_DP<1>")
	)
	(segment
		(start 63.392304 -289.78479)
		(end 63.392304 -289.308286)
		(width 0.16002)
		(layer "In11.Cu")
		(net "M_F_CPU1_SB_DQS_DP<1>")
	)
	(segment
		(start 24.1554 -294.360092)
		(end 26.005282 -294.360092)
		(width 0.16002)
		(layer "In11.Cu")
		(net "M_F_CPU1_SB_DQS_DP<1>")
	)
	(segment
		(start 26.34996 -294.70477)
		(end 26.749248 -294.70477)
		(width 0.16002)
		(layer "In11.Cu")
		(net "M_F_CPU1_SB_DQS_DP<1>")
	)
	(segment
		(start 54.428898 -294.70477)
		(end 56.92521 -294.70477)
		(width 0.16002)
		(layer "In11.Cu")
		(net "M_F_CPU1_SB_DQS_DP<1>")
	)
	(segment
		(start 56.92521 -294.70477)
		(end 57.75071 -293.87927)
		(width 0.16002)
		(layer "In11.Cu")
		(net "M_F_CPU1_SB_DQS_DP<1>")
	)
	(segment
		(start 38.639242 -294.360092)
		(end 41.09339 -294.360092)
		(width 0.16002)
		(layer "In11.Cu")
		(net "M_F_CPU1_SB_DQS_DP<1>")
	)
	(segment
		(start 48.637444 -294.360092)
		(end 48.982122 -294.70477)
		(width 0.16002)
		(layer "In11.Cu")
		(net "M_F_CPU1_SB_DQS_DP<1>")
	)
	(segment
		(start 78.166214 -280.553414)
		(end 78.445106 -280.832306)
		(width 0.09525)
		(layer "In11.Cu")
		(net "M_F_CPU1_SB_DQS_DP<1>")
	)
	(segment
		(start 35.932618 -293.510208)
		(end 37.789358 -293.510208)
		(width 0.16002)
		(layer "In11.Cu")
		(net "M_F_CPU1_SB_DQS_DP<1>")
	)
	(segment
		(start 75.955906 -280.780744)
		(end 75.979528 -280.780744)
		(width 0.09525)
		(layer "In11.Cu")
		(net "M_F_CPU1_SB_DQS_DP<1>")
	)
	(segment
		(start 24.006302 -294.50919)
		(end 24.1554 -294.360092)
		(width 0.16002)
		(layer "In11.Cu")
		(net "M_F_CPU1_SB_DQS_DP<1>")
	)
	(segment
		(start 31.095188 -294.360092)
		(end 33.549336 -294.360092)
		(width 0.16002)
		(layer "In11.Cu")
		(net "M_F_CPU1_SB_DQS_DP<1>")
	)
	(segment
		(start 64.879982 -288.751264)
		(end 64.879982 -288.525204)
		(width 0.16002)
		(layer "In11.Cu")
		(net "M_F_CPU1_SB_DQS_DP<1>")
	)
	(segment
		(start 71.500746 -282.1305)
		(end 71.748142 -281.883104)
		(width 0.16002)
		(layer "In11.Cu")
		(net "M_F_CPU1_SB_DQS_DP<1>")
	)
	(segment
		(start 79.445612 -280.881074)
		(end 79.463646 -280.891488)
		(width 0.09525)
		(layer "In11.Cu")
		(net "M_F_CPU1_SB_DQS_DP<1>")
	)
	(segment
		(start 63.392304 -289.308286)
		(end 63.815976 -288.884614)
		(width 0.16002)
		(layer "In11.Cu")
		(net "M_F_CPU1_SB_DQS_DP<1>")
	)
	(segment
		(start 41.837356 -294.70477)
		(end 42.662856 -293.87927)
		(width 0.16002)
		(layer "In11.Cu")
		(net "M_F_CPU1_SB_DQS_DP<1>")
	)
	(segment
		(start 41.438068 -294.70477)
		(end 41.837356 -294.70477)
		(width 0.16002)
		(layer "In11.Cu")
		(net "M_F_CPU1_SB_DQS_DP<1>")
	)
	(segment
		(start 23.4696 -294.50919)
		(end 24.006302 -294.50919)
		(width 0.16002)
		(layer "In11.Cu")
		(net "M_F_CPU1_SB_DQS_DP<1>")
	)
	(segment
		(start 70.127114 -283.504132)
		(end 70.37451 -283.256736)
		(width 0.16002)
		(layer "In11.Cu")
		(net "M_F_CPU1_SB_DQS_DP<1>")
	)
	(segment
		(start 22.8727 -294.39235)
		(end 23.35276 -294.39235)
		(width 0.16002)
		(layer "In11.Cu")
		(net "M_F_CPU1_SB_DQS_DP<1>")
	)
	(segment
		(start 66.006218 -287.625028)
		(end 66.253614 -287.377632)
		(width 0.16002)
		(layer "In11.Cu")
		(net "M_F_CPU1_SB_DQS_DP<1>")
	)
	(segment
		(start 68.753482 -284.877764)
		(end 69.000878 -284.630368)
		(width 0.16002)
		(layer "In11.Cu")
		(net "M_F_CPU1_SB_DQS_DP<1>")
	)
	(segment
		(start 43.10761 -293.87927)
		(end 43.476672 -293.510208)
		(width 0.16002)
		(layer "In11.Cu")
		(net "M_F_CPU1_SB_DQS_DP<1>")
	)
	(segment
		(start 34.293302 -294.70477)
		(end 35.118802 -293.87927)
		(width 0.16002)
		(layer "In11.Cu")
		(net "M_F_CPU1_SB_DQS_DP<1>")
	)
	(segment
		(start 26.005282 -294.360092)
		(end 26.34996 -294.70477)
		(width 0.16002)
		(layer "In11.Cu")
		(net "M_F_CPU1_SB_DQS_DP<1>")
	)
	(segment
		(start 48.982122 -294.70477)
		(end 49.38141 -294.70477)
		(width 0.16002)
		(layer "In11.Cu")
		(net "M_F_CPU1_SB_DQS_DP<1>")
	)
	(segment
		(start 28.388564 -293.510208)
		(end 30.245304 -293.510208)
		(width 0.16002)
		(layer "In11.Cu")
		(net "M_F_CPU1_SB_DQS_DP<1>")
	)
	(segment
		(start 76.038456 -280.839672)
		(end 76.392532 -280.839672)
		(width 0.09525)
		(layer "In11.Cu")
		(net "M_F_CPU1_SB_DQS_DP<1>")
	)
	(segment
		(start 69.623432 -283.504132)
		(end 70.127114 -283.504132)
		(width 0.16002)
		(layer "In11.Cu")
		(net "M_F_CPU1_SB_DQS_DP<1>")
	)
	(segment
		(start 76.392532 -280.839672)
		(end 76.67879 -280.553414)
		(width 0.09525)
		(layer "In11.Cu")
		(net "M_F_CPU1_SB_DQS_DP<1>")
	)
	(segment
		(start 66.253614 -287.377632)
		(end 66.253614 -287.151572)
		(width 0.16002)
		(layer "In11.Cu")
		(net "M_F_CPU1_SB_DQS_DP<1>")
	)
	(segment
		(start 84.48167 -280.918666)
		(end 84.505038 -280.831798)
		(width 0.09525)
		(layer "In11.Cu")
		(net "M_F_CPU1_SB_DQS_DP<1>")
	)
	(segment
		(start 23.35276 -294.39235)
		(end 23.4696 -294.50919)
		(width 0.16002)
		(layer "In11.Cu")
		(net "M_F_CPU1_SB_DQS_DP<1>")
	)
	(segment
		(start 64.406526 -288.99866)
		(end 64.632586 -288.99866)
		(width 0.16002)
		(layer "In11.Cu")
		(net "M_F_CPU1_SB_DQS_DP<1>")
	)
	(segment
		(start 68.527422 -284.877764)
		(end 68.753482 -284.877764)
		(width 0.16002)
		(layer "In11.Cu")
		(net "M_F_CPU1_SB_DQS_DP<1>")
	)
	(segment
		(start 69.000878 -284.630368)
		(end 69.000878 -284.126686)
		(width 0.16002)
		(layer "In11.Cu")
		(net "M_F_CPU1_SB_DQS_DP<1>")
	)
	(segment
		(start 75.979528 -280.780744)
		(end 76.038456 -280.839672)
		(width 0.09525)
		(layer "In11.Cu")
		(net "M_F_CPU1_SB_DQS_DP<1>")
	)
	(segment
		(start 61.885322 -291.745924)
		(end 62.132718 -291.498528)
		(width 0.16002)
		(layer "In11.Cu")
		(net "M_F_CPU1_SB_DQS_DP<1>")
	)
	(segment
		(start 30.245304 -293.510208)
		(end 31.095188 -294.360092)
		(width 0.16002)
		(layer "In11.Cu")
		(net "M_F_CPU1_SB_DQS_DP<1>")
	)
	(segment
		(start 67.627246 -286.004)
		(end 67.627246 -285.77794)
		(width 0.16002)
		(layer "In11.Cu")
		(net "M_F_CPU1_SB_DQS_DP<1>")
	)
	(segment
		(start 60.759086 -292.87216)
		(end 60.759086 -292.368478)
		(width 0.16002)
		(layer "In11.Cu")
		(net "M_F_CPU1_SB_DQS_DP<1>")
	)
	(segment
		(start 68.413376 -284.763718)
		(end 68.527422 -284.877764)
		(width 0.16002)
		(layer "In11.Cu")
		(net "M_F_CPU1_SB_DQS_DP<1>")
	)
	(segment
		(start 79.831946 -280.896314)
		(end 79.840328 -280.891488)
		(width 0.09525)
		(layer "In11.Cu")
		(net "M_F_CPU1_SB_DQS_DP<1>")
	)
	(segment
		(start 53.520086 -294.152828)
		(end 53.876956 -294.152828)
		(width 0.16002)
		(layer "In11.Cu")
		(net "M_F_CPU1_SB_DQS_DP<1>")
	)
	(segment
		(start 62.918848 -290.258246)
		(end 63.032894 -290.372292)
		(width 0.16002)
		(layer "In11.Cu")
		(net "M_F_CPU1_SB_DQS_DP<1>")
	)
	(segment
		(start 65.666112 -287.510982)
		(end 65.780158 -287.625028)
		(width 0.16002)
		(layer "In11.Cu")
		(net "M_F_CPU1_SB_DQS_DP<1>")
	)
	(segment
		(start 21.981922 -294.50919)
		(end 22.75586 -294.50919)
		(width 0.16002)
		(layer "In11.Cu")
		(net "M_F_CPU1_SB_DQS_DP<1>")
	)
	(segment
		(start 42.662856 -293.87927)
		(end 43.10761 -293.87927)
		(width 0.16002)
		(layer "In11.Cu")
		(net "M_F_CPU1_SB_DQS_DP<1>")
	)
	(segment
		(start 67.37985 -286.251396)
		(end 67.627246 -286.004)
		(width 0.16002)
		(layer "In11.Cu")
		(net "M_F_CPU1_SB_DQS_DP<1>")
	)
	(segment
		(start 26.749248 -294.70477)
		(end 27.574748 -293.87927)
		(width 0.16002)
		(layer "In11.Cu")
		(net "M_F_CPU1_SB_DQS_DP<1>")
	)
	(segment
		(start 45.333412 -293.510208)
		(end 46.183296 -294.360092)
		(width 0.16002)
		(layer "In11.Cu")
		(net "M_F_CPU1_SB_DQS_DP<1>")
	)
	(segment
		(start 51.020726 -293.510208)
		(end 52.877466 -293.510208)
		(width 0.16002)
		(layer "In11.Cu")
		(net "M_F_CPU1_SB_DQS_DP<1>")
	)
	(segment
		(start 79.840328 -280.891488)
		(end 79.858362 -280.881074)
		(width 0.09525)
		(layer "In11.Cu")
		(net "M_F_CPU1_SB_DQS_DP<1>")
	)
	(segment
		(start 62.132718 -291.498528)
		(end 62.132718 -291.272468)
		(width 0.16002)
		(layer "In11.Cu")
		(net "M_F_CPU1_SB_DQS_DP<1>")
	)
	(segment
		(start 66.253614 -287.151572)
		(end 66.139568 -287.037526)
		(width 0.16002)
		(layer "In11.Cu")
		(net "M_F_CPU1_SB_DQS_DP<1>")
	)
	(segment
		(start 70.37451 -282.753054)
		(end 70.997064 -282.1305)
		(width 0.16002)
		(layer "In11.Cu")
		(net "M_F_CPU1_SB_DQS_DP<1>")
	)
	(segment
		(start 81.342484 -280.891488)
		(end 81.350866 -280.896314)
		(width 0.09525)
		(layer "In11.Cu")
		(net "M_F_CPU1_SB_DQS_DP<1>")
	)
	(segment
		(start 78.523084 -280.891488)
		(end 78.539848 -280.90114)
		(width 0.09525)
		(layer "In11.Cu")
		(net "M_F_CPU1_SB_DQS_DP<1>")
	)
	(segment
		(start 59.248294 -293.87927)
		(end 60.008008 -293.119556)
		(width 0.16002)
		(layer "In11.Cu")
		(net "M_F_CPU1_SB_DQS_DP<1>")
	)
	(segment
		(start 37.789358 -293.510208)
		(end 38.639242 -294.360092)
		(width 0.16002)
		(layer "In11.Cu")
		(net "M_F_CPU1_SB_DQS_DP<1>")
	)
	(segment
		(start 67.936872 -284.763718)
		(end 68.413376 -284.763718)
		(width 0.16002)
		(layer "In11.Cu")
		(net "M_F_CPU1_SB_DQS_DP<1>")
	)
	(segment
		(start 46.183296 -294.360092)
		(end 48.637444 -294.360092)
		(width 0.16002)
		(layer "In11.Cu")
		(net "M_F_CPU1_SB_DQS_DP<1>")
	)
	(segment
		(start 84.505038 -280.831798)
		(end 84.351114 -280.566368)
		(width 0.09525)
		(layer "In11.Cu")
		(net "M_F_CPU1_SB_DQS_DP<1>")
	)
	(segment
		(start 66.56324 -286.13735)
		(end 67.039744 -286.13735)
		(width 0.16002)
		(layer "In11.Cu")
		(net "M_F_CPU1_SB_DQS_DP<1>")
	)
	(segment
		(start 76.67879 -280.553414)
		(end 78.166214 -280.553414)
		(width 0.09525)
		(layer "In11.Cu")
		(net "M_F_CPU1_SB_DQS_DP<1>")
	)
	(segment
		(start 67.15379 -286.251396)
		(end 67.37985 -286.251396)
		(width 0.16002)
		(layer "In11.Cu")
		(net "M_F_CPU1_SB_DQS_DP<1>")
	)
	(segment
		(start 71.748142 -281.883104)
		(end 71.748142 -281.379422)
		(width 0.16002)
		(layer "In11.Cu")
		(net "M_F_CPU1_SB_DQS_DP<1>")
	)
	(segment
		(start 33.894014 -294.70477)
		(end 34.293302 -294.70477)
		(width 0.16002)
		(layer "In11.Cu")
		(net "M_F_CPU1_SB_DQS_DP<1>")
	)
	(segment
		(start 22.75586 -294.50919)
		(end 22.8727 -294.39235)
		(width 0.16002)
		(layer "In11.Cu")
		(net "M_F_CPU1_SB_DQS_DP<1>")
	)
	(segment
		(start 21.70811 -294.235378)
		(end 21.981922 -294.50919)
		(width 0.16002)
		(layer "In11.Cu")
		(net "M_F_CPU1_SB_DQS_DP<1>")
	)
	(segment
		(start 57.75071 -293.87927)
		(end 59.248294 -293.87927)
		(width 0.16002)
		(layer "In11.Cu")
		(net "M_F_CPU1_SB_DQS_DP<1>")
	)
	(segment
		(start 62.132718 -291.272468)
		(end 62.018672 -291.158422)
		(width 0.16002)
		(layer "In11.Cu")
		(net "M_F_CPU1_SB_DQS_DP<1>")
	)
	(segment
		(start 72.34682 -280.780744)
		(end 75.955906 -280.780744)
		(width 0.16002)
		(layer "In11.Cu")
		(net "M_F_CPU1_SB_DQS_DP<1>")
	)
	(segment
		(start 60.51169 -293.119556)
		(end 60.759086 -292.87216)
		(width 0.16002)
		(layer "In11.Cu")
		(net "M_F_CPU1_SB_DQS_DP<1>")
	)
	(segment
		(start 35.563556 -293.87927)
		(end 35.932618 -293.510208)
		(width 0.16002)
		(layer "In11.Cu")
		(net "M_F_CPU1_SB_DQS_DP<1>")
	)
	(segment
		(start 64.632586 -288.99866)
		(end 64.879982 -288.751264)
		(width 0.16002)
		(layer "In11.Cu")
		(net "M_F_CPU1_SB_DQS_DP<1>")
	)
	(segment
		(start 60.759086 -292.368478)
		(end 61.38164 -291.745924)
		(width 0.16002)
		(layer "In11.Cu")
		(net "M_F_CPU1_SB_DQS_DP<1>")
	)
	(segment
		(start 62.018672 -291.158422)
		(end 62.018672 -290.681918)
		(width 0.16002)
		(layer "In11.Cu")
		(net "M_F_CPU1_SB_DQS_DP<1>")
	)
	(segment
		(start 49.38141 -294.70477)
		(end 50.20691 -293.87927)
		(width 0.16002)
		(layer "In11.Cu")
		(net "M_F_CPU1_SB_DQS_DP<1>")
	)
	(segment
		(start 63.258954 -290.372292)
		(end 63.50635 -290.124896)
		(width 0.16002)
		(layer "In11.Cu")
		(net "M_F_CPU1_SB_DQS_DP<1>")
	)
	(segment
		(start 64.765936 -288.411158)
		(end 64.765936 -287.934654)
		(width 0.16002)
		(layer "In11.Cu")
		(net "M_F_CPU1_SB_DQS_DP<1>")
	)
	(segment
		(start 52.877466 -293.510208)
		(end 53.520086 -294.152828)
		(width 0.16002)
		(layer "In11.Cu")
		(net "M_F_CPU1_SB_DQS_DP<1>")
	)
	(segment
		(start 71.748142 -281.379422)
		(end 72.34682 -280.780744)
		(width 0.16002)
		(layer "In11.Cu")
		(net "M_F_CPU1_SB_DQS_DP<1>")
	)
	(segment
		(start 67.039744 -286.13735)
		(end 67.15379 -286.251396)
		(width 0.16002)
		(layer "In11.Cu")
		(net "M_F_CPU1_SB_DQS_DP<1>")
	)
	(segment
		(start 67.5132 -285.663894)
		(end 67.5132 -285.18739)
		(width 0.16002)
		(layer "In11.Cu")
		(net "M_F_CPU1_SB_DQS_DP<1>")
	)
	(segment
		(start 70.37451 -283.256736)
		(end 70.37451 -282.753054)
		(width 0.16002)
		(layer "In11.Cu")
		(net "M_F_CPU1_SB_DQS_DP<1>")
	)
	(segment
		(start 69.000878 -284.126686)
		(end 69.623432 -283.504132)
		(width 0.16002)
		(layer "In11.Cu")
		(net "M_F_CPU1_SB_DQS_DP<1>")
	)
	(segment
		(start 53.876956 -294.152828)
		(end 54.428898 -294.70477)
		(width 0.16002)
		(layer "In11.Cu")
		(net "M_F_CPU1_SB_DQS_DP<1>")
	)
	(segment
		(start 60.008008 -293.119556)
		(end 60.51169 -293.119556)
		(width 0.16002)
		(layer "In11.Cu")
		(net "M_F_CPU1_SB_DQS_DP<1>")
	)
	(segment
		(start 33.549336 -294.360092)
		(end 33.894014 -294.70477)
		(width 0.16002)
		(layer "In11.Cu")
		(net "M_F_CPU1_SB_DQS_DP<1>")
	)
	(segment
		(start 63.50635 -289.898836)
		(end 63.392304 -289.78479)
		(width 0.16002)
		(layer "In11.Cu")
		(net "M_F_CPU1_SB_DQS_DP<1>")
	)
	(segment
		(start 65.780158 -287.625028)
		(end 66.006218 -287.625028)
		(width 0.16002)
		(layer "In11.Cu")
		(net "M_F_CPU1_SB_DQS_DP<1>")
	)
	(segment
		(start 50.20691 -293.87927)
		(end 50.651664 -293.87927)
		(width 0.16002)
		(layer "In11.Cu")
		(net "M_F_CPU1_SB_DQS_DP<1>")
	)
	(arc
		(start 79.858362 -280.881074)
		(mid 80.131742 -280.815853)
		(end 80.40243 -280.891488)
		(width 0.09525)
		(layer "In11.Cu")
		(net "M_F_CPU1_SB_DQS_DP<1>")
	)
	(arc
		(start 82.659474 -280.891488)
		(mid 82.940906 -280.815733)
		(end 83.222338 -280.891488)
		(width 0.09525)
		(layer "In11.Cu")
		(net "M_F_CPU1_SB_DQS_DP<1>")
	)
	(arc
		(start 81.350866 -280.896314)
		(mid 81.535898 -280.942228)
		(end 81.719674 -280.891488)
		(width 0.09525)
		(layer "In11.Cu")
		(net "M_F_CPU1_SB_DQS_DP<1>")
	)
	(arc
		(start 78.90002 -280.891488)
		(mid 79.17147 -280.815453)
		(end 79.445612 -280.881074)
		(width 0.09525)
		(layer "In11.Cu")
		(net "M_F_CPU1_SB_DQS_DP<1>")
	)
	(arc
		(start 78.445106 -280.832306)
		(mid 78.482164 -280.86444)
		(end 78.523084 -280.891488)
		(width 0.09525)
		(layer "In11.Cu")
		(net "M_F_CPU1_SB_DQS_DP<1>")
	)
	(arc
		(start 79.463646 -280.891488)
		(mid 79.647167 -280.942132)
		(end 79.831946 -280.896314)
		(width 0.09525)
		(layer "In11.Cu")
		(net "M_F_CPU1_SB_DQS_DP<1>")
	)
	(arc
		(start 80.40243 -280.891488)
		(mid 80.586205 -280.94226)
		(end 80.771238 -280.896314)
		(width 0.09525)
		(layer "In11.Cu")
		(net "M_F_CPU1_SB_DQS_DP<1>")
	)
	(arc
		(start 80.77962 -280.891488)
		(mid 81.061052 -280.815733)
		(end 81.342484 -280.891488)
		(width 0.09525)
		(layer "In11.Cu")
		(net "M_F_CPU1_SB_DQS_DP<1>")
	)
	(arc
		(start 83.222338 -280.891488)
		(mid 83.406113 -280.94226)
		(end 83.591146 -280.896314)
		(width 0.09525)
		(layer "In11.Cu")
		(net "M_F_CPU1_SB_DQS_DP<1>")
	)
	(arc
		(start 84.162392 -280.891488)
		(mid 84.31899 -280.940777)
		(end 84.48167 -280.918666)
		(width 0.09525)
		(layer "In11.Cu")
		(net "M_F_CPU1_SB_DQS_DP<1>")
	)
	(arc
		(start 82.282538 -280.891488)
		(mid 82.471006 -280.942165)
		(end 82.659474 -280.891488)
		(width 0.09525)
		(layer "In11.Cu")
		(net "M_F_CPU1_SB_DQS_DP<1>")
	)
	(arc
		(start 78.539848 -280.90114)
		(mid 78.721159 -280.942238)
		(end 78.90002 -280.891488)
		(width 0.09525)
		(layer "In11.Cu")
		(net "M_F_CPU1_SB_DQS_DP<1>")
	)
	(arc
		(start 81.719674 -280.891488)
		(mid 82.001106 -280.815733)
		(end 82.282538 -280.891488)
		(width 0.09525)
		(layer "In11.Cu")
		(net "M_F_CPU1_SB_DQS_DP<1>")
	)
	(arc
		(start 83.599528 -280.891488)
		(mid 83.88096 -280.815733)
		(end 84.162392 -280.891488)
		(width 0.09525)
		(layer "In11.Cu")
		(net "M_F_CPU1_SB_DQS_DP<1>")
	)
	(segment
		(start 84.817966 -275.440394)
		(end 84.351114 -275.706332)
		(width 0.12954)
		(layer "F.Cu")
		(net "M_F_CPU1_SB_DQS_DP<0>")
	)
	(segment
		(start 52.877466 -284.160214)
		(end 53.520086 -284.802834)
		(width 0.16002)
		(layer "In11.Cu")
		(net "M_F_CPU1_SB_DQS_DP<0>")
	)
	(segment
		(start 78.078584 -276.082506)
		(end 79.652114 -276.082506)
		(width 0.09525)
		(layer "In11.Cu")
		(net "M_F_CPU1_SB_DQS_DP<0>")
	)
	(segment
		(start 64.421766 -279.356058)
		(end 64.89827 -279.356058)
		(width 0.16002)
		(layer "In11.Cu")
		(net "M_F_CPU1_SB_DQS_DP<0>")
	)
	(segment
		(start 61.674502 -282.103322)
		(end 62.151006 -282.103322)
		(width 0.16002)
		(layer "In11.Cu")
		(net "M_F_CPU1_SB_DQS_DP<0>")
	)
	(segment
		(start 30.245304 -284.160214)
		(end 31.095188 -285.010098)
		(width 0.16002)
		(layer "In11.Cu")
		(net "M_F_CPU1_SB_DQS_DP<0>")
	)
	(segment
		(start 61.41974 -283.398468)
		(end 61.41974 -283.172408)
		(width 0.16002)
		(layer "In11.Cu")
		(net "M_F_CPU1_SB_DQS_DP<0>")
	)
	(segment
		(start 64.167004 -280.425144)
		(end 63.998094 -280.256234)
		(width 0.16002)
		(layer "In11.Cu")
		(net "M_F_CPU1_SB_DQS_DP<0>")
	)
	(segment
		(start 80.771238 -276.036278)
		(end 80.77962 -276.031452)
		(width 0.09525)
		(layer "In11.Cu")
		(net "M_F_CPU1_SB_DQS_DP<0>")
	)
	(segment
		(start 62.793372 -281.798776)
		(end 62.624462 -281.629866)
		(width 0.16002)
		(layer "In11.Cu")
		(net "M_F_CPU1_SB_DQS_DP<0>")
	)
	(segment
		(start 28.019502 -284.529276)
		(end 28.388564 -284.160214)
		(width 0.16002)
		(layer "In11.Cu")
		(net "M_F_CPU1_SB_DQS_DP<0>")
	)
	(segment
		(start 63.998094 -280.256234)
		(end 63.998094 -279.77973)
		(width 0.16002)
		(layer "In11.Cu")
		(net "M_F_CPU1_SB_DQS_DP<0>")
	)
	(segment
		(start 21.70811 -284.885384)
		(end 21.981922 -285.159196)
		(width 0.16002)
		(layer "In11.Cu")
		(net "M_F_CPU1_SB_DQS_DP<0>")
	)
	(segment
		(start 66.914268 -277.67788)
		(end 66.745358 -277.50897)
		(width 0.16002)
		(layer "In11.Cu")
		(net "M_F_CPU1_SB_DQS_DP<0>")
	)
	(segment
		(start 79.840328 -276.031452)
		(end 79.858362 -276.021038)
		(width 0.09525)
		(layer "In11.Cu")
		(net "M_F_CPU1_SB_DQS_DP<0>")
	)
	(segment
		(start 26.005282 -285.010098)
		(end 26.34996 -285.354776)
		(width 0.16002)
		(layer "In11.Cu")
		(net "M_F_CPU1_SB_DQS_DP<0>")
	)
	(segment
		(start 35.118802 -284.529276)
		(end 35.563556 -284.529276)
		(width 0.16002)
		(layer "In11.Cu")
		(net "M_F_CPU1_SB_DQS_DP<0>")
	)
	(segment
		(start 83.591146 -276.036278)
		(end 83.599528 -276.031452)
		(width 0.09525)
		(layer "In11.Cu")
		(net "M_F_CPU1_SB_DQS_DP<0>")
	)
	(segment
		(start 81.342484 -276.031452)
		(end 81.350866 -276.036278)
		(width 0.09525)
		(layer "In11.Cu")
		(net "M_F_CPU1_SB_DQS_DP<0>")
	)
	(segment
		(start 65.29324 -279.524968)
		(end 65.540636 -279.277572)
		(width 0.16002)
		(layer "In11.Cu")
		(net "M_F_CPU1_SB_DQS_DP<0>")
	)
	(segment
		(start 59.248548 -284.529276)
		(end 60.30087 -283.476954)
		(width 0.16002)
		(layer "In11.Cu")
		(net "M_F_CPU1_SB_DQS_DP<0>")
	)
	(segment
		(start 68.62064 -275.157184)
		(end 75.963526 -275.157184)
		(width 0.16002)
		(layer "In11.Cu")
		(net "M_F_CPU1_SB_DQS_DP<0>")
	)
	(segment
		(start 62.151006 -282.103322)
		(end 62.319916 -282.272232)
		(width 0.16002)
		(layer "In11.Cu")
		(net "M_F_CPU1_SB_DQS_DP<0>")
	)
	(segment
		(start 77.21219 -275.216112)
		(end 78.078584 -276.082506)
		(width 0.09525)
		(layer "In11.Cu")
		(net "M_F_CPU1_SB_DQS_DP<0>")
	)
	(segment
		(start 37.789358 -284.160214)
		(end 38.639242 -285.010098)
		(width 0.16002)
		(layer "In11.Cu")
		(net "M_F_CPU1_SB_DQS_DP<0>")
	)
	(segment
		(start 38.639242 -285.010098)
		(end 41.09339 -285.010098)
		(width 0.16002)
		(layer "In11.Cu")
		(net "M_F_CPU1_SB_DQS_DP<0>")
	)
	(segment
		(start 68.11899 -275.658834)
		(end 68.62064 -275.157184)
		(width 0.16002)
		(layer "In11.Cu")
		(net "M_F_CPU1_SB_DQS_DP<0>")
	)
	(segment
		(start 60.946284 -283.645864)
		(end 61.172344 -283.645864)
		(width 0.16002)
		(layer "In11.Cu")
		(net "M_F_CPU1_SB_DQS_DP<0>")
	)
	(segment
		(start 67.645534 -276.608794)
		(end 67.814444 -276.777704)
		(width 0.16002)
		(layer "In11.Cu")
		(net "M_F_CPU1_SB_DQS_DP<0>")
	)
	(segment
		(start 65.371726 -278.882602)
		(end 65.371726 -278.406098)
		(width 0.16002)
		(layer "In11.Cu")
		(net "M_F_CPU1_SB_DQS_DP<0>")
	)
	(segment
		(start 63.693548 -280.8986)
		(end 63.919608 -280.8986)
		(width 0.16002)
		(layer "In11.Cu")
		(net "M_F_CPU1_SB_DQS_DP<0>")
	)
	(segment
		(start 41.09339 -285.010098)
		(end 41.438068 -285.354776)
		(width 0.16002)
		(layer "In11.Cu")
		(net "M_F_CPU1_SB_DQS_DP<0>")
	)
	(segment
		(start 66.745358 -277.50897)
		(end 66.745358 -277.032466)
		(width 0.16002)
		(layer "In11.Cu")
		(net "M_F_CPU1_SB_DQS_DP<0>")
	)
	(segment
		(start 53.876956 -284.802834)
		(end 54.428898 -285.354776)
		(width 0.16002)
		(layer "In11.Cu")
		(net "M_F_CPU1_SB_DQS_DP<0>")
	)
	(segment
		(start 84.505038 -275.971762)
		(end 84.351114 -275.706332)
		(width 0.09525)
		(layer "In11.Cu")
		(net "M_F_CPU1_SB_DQS_DP<0>")
	)
	(segment
		(start 65.371726 -278.406098)
		(end 65.795398 -277.982426)
		(width 0.16002)
		(layer "In11.Cu")
		(net "M_F_CPU1_SB_DQS_DP<0>")
	)
	(segment
		(start 24.1554 -285.010098)
		(end 26.005282 -285.010098)
		(width 0.16002)
		(layer "In11.Cu")
		(net "M_F_CPU1_SB_DQS_DP<0>")
	)
	(segment
		(start 67.16903 -276.608794)
		(end 67.645534 -276.608794)
		(width 0.16002)
		(layer "In11.Cu")
		(net "M_F_CPU1_SB_DQS_DP<0>")
	)
	(segment
		(start 66.666872 -278.151336)
		(end 66.914268 -277.90394)
		(width 0.16002)
		(layer "In11.Cu")
		(net "M_F_CPU1_SB_DQS_DP<0>")
	)
	(segment
		(start 61.41974 -283.172408)
		(end 61.25083 -283.003498)
		(width 0.16002)
		(layer "In11.Cu")
		(net "M_F_CPU1_SB_DQS_DP<0>")
	)
	(segment
		(start 66.440812 -278.151336)
		(end 66.666872 -278.151336)
		(width 0.16002)
		(layer "In11.Cu")
		(net "M_F_CPU1_SB_DQS_DP<0>")
	)
	(segment
		(start 62.545976 -282.272232)
		(end 62.793372 -282.024836)
		(width 0.16002)
		(layer "In11.Cu")
		(net "M_F_CPU1_SB_DQS_DP<0>")
	)
	(segment
		(start 22.71268 -285.159196)
		(end 22.82952 -285.042356)
		(width 0.16002)
		(layer "In11.Cu")
		(net "M_F_CPU1_SB_DQS_DP<0>")
	)
	(segment
		(start 79.840582 -276.031452)
		(end 79.840328 -276.031452)
		(width 0.09525)
		(layer "In11.Cu")
		(net "M_F_CPU1_SB_DQS_DP<0>")
	)
	(segment
		(start 49.38141 -285.354776)
		(end 50.20691 -284.529276)
		(width 0.16002)
		(layer "In11.Cu")
		(net "M_F_CPU1_SB_DQS_DP<0>")
	)
	(segment
		(start 51.020726 -284.160214)
		(end 52.877466 -284.160214)
		(width 0.16002)
		(layer "In11.Cu")
		(net "M_F_CPU1_SB_DQS_DP<0>")
	)
	(segment
		(start 31.095188 -285.010098)
		(end 33.549336 -285.010098)
		(width 0.16002)
		(layer "In11.Cu")
		(net "M_F_CPU1_SB_DQS_DP<0>")
	)
	(segment
		(start 62.624462 -281.153362)
		(end 63.048134 -280.72969)
		(width 0.16002)
		(layer "In11.Cu")
		(net "M_F_CPU1_SB_DQS_DP<0>")
	)
	(segment
		(start 61.25083 -282.526994)
		(end 61.674502 -282.103322)
		(width 0.16002)
		(layer "In11.Cu")
		(net "M_F_CPU1_SB_DQS_DP<0>")
	)
	(segment
		(start 48.982122 -285.354776)
		(end 49.38141 -285.354776)
		(width 0.16002)
		(layer "In11.Cu")
		(net "M_F_CPU1_SB_DQS_DP<0>")
	)
	(segment
		(start 57.75071 -284.529276)
		(end 59.248548 -284.529276)
		(width 0.16002)
		(layer "In11.Cu")
		(net "M_F_CPU1_SB_DQS_DP<0>")
	)
	(segment
		(start 63.998094 -279.77973)
		(end 64.421766 -279.356058)
		(width 0.16002)
		(layer "In11.Cu")
		(net "M_F_CPU1_SB_DQS_DP<0>")
	)
	(segment
		(start 62.793372 -282.024836)
		(end 62.793372 -281.798776)
		(width 0.16002)
		(layer "In11.Cu")
		(net "M_F_CPU1_SB_DQS_DP<0>")
	)
	(segment
		(start 67.814444 -276.777704)
		(end 68.040504 -276.777704)
		(width 0.16002)
		(layer "In11.Cu")
		(net "M_F_CPU1_SB_DQS_DP<0>")
	)
	(segment
		(start 63.524638 -280.72969)
		(end 63.693548 -280.8986)
		(width 0.16002)
		(layer "In11.Cu")
		(net "M_F_CPU1_SB_DQS_DP<0>")
	)
	(segment
		(start 65.06718 -279.524968)
		(end 65.29324 -279.524968)
		(width 0.16002)
		(layer "In11.Cu")
		(net "M_F_CPU1_SB_DQS_DP<0>")
	)
	(segment
		(start 64.167004 -280.651204)
		(end 64.167004 -280.425144)
		(width 0.16002)
		(layer "In11.Cu")
		(net "M_F_CPU1_SB_DQS_DP<0>")
	)
	(segment
		(start 46.183296 -285.010098)
		(end 48.637444 -285.010098)
		(width 0.16002)
		(layer "In11.Cu")
		(net "M_F_CPU1_SB_DQS_DP<0>")
	)
	(segment
		(start 34.293302 -285.354776)
		(end 35.118802 -284.529276)
		(width 0.16002)
		(layer "In11.Cu")
		(net "M_F_CPU1_SB_DQS_DP<0>")
	)
	(segment
		(start 23.30958 -285.042356)
		(end 23.42642 -285.159196)
		(width 0.16002)
		(layer "In11.Cu")
		(net "M_F_CPU1_SB_DQS_DP<0>")
	)
	(segment
		(start 33.549336 -285.010098)
		(end 33.894014 -285.354776)
		(width 0.16002)
		(layer "In11.Cu")
		(net "M_F_CPU1_SB_DQS_DP<0>")
	)
	(segment
		(start 66.271902 -277.982426)
		(end 66.440812 -278.151336)
		(width 0.16002)
		(layer "In11.Cu")
		(net "M_F_CPU1_SB_DQS_DP<0>")
	)
	(segment
		(start 26.749248 -285.354776)
		(end 27.574748 -284.529276)
		(width 0.16002)
		(layer "In11.Cu")
		(net "M_F_CPU1_SB_DQS_DP<0>")
	)
	(segment
		(start 21.981922 -285.159196)
		(end 22.71268 -285.159196)
		(width 0.16002)
		(layer "In11.Cu")
		(net "M_F_CPU1_SB_DQS_DP<0>")
	)
	(segment
		(start 68.2879 -276.530308)
		(end 68.2879 -276.304248)
		(width 0.16002)
		(layer "In11.Cu")
		(net "M_F_CPU1_SB_DQS_DP<0>")
	)
	(segment
		(start 43.10761 -284.529276)
		(end 43.476672 -284.160214)
		(width 0.16002)
		(layer "In11.Cu")
		(net "M_F_CPU1_SB_DQS_DP<0>")
	)
	(segment
		(start 26.34996 -285.354776)
		(end 26.749248 -285.354776)
		(width 0.16002)
		(layer "In11.Cu")
		(net "M_F_CPU1_SB_DQS_DP<0>")
	)
	(segment
		(start 43.476672 -284.160214)
		(end 45.333412 -284.160214)
		(width 0.16002)
		(layer "In11.Cu")
		(net "M_F_CPU1_SB_DQS_DP<0>")
	)
	(segment
		(start 62.624462 -281.629866)
		(end 62.624462 -281.153362)
		(width 0.16002)
		(layer "In11.Cu")
		(net "M_F_CPU1_SB_DQS_DP<0>")
	)
	(segment
		(start 28.388564 -284.160214)
		(end 30.245304 -284.160214)
		(width 0.16002)
		(layer "In11.Cu")
		(net "M_F_CPU1_SB_DQS_DP<0>")
	)
	(segment
		(start 54.428898 -285.354776)
		(end 56.92521 -285.354776)
		(width 0.16002)
		(layer "In11.Cu")
		(net "M_F_CPU1_SB_DQS_DP<0>")
	)
	(segment
		(start 50.20691 -284.529276)
		(end 50.651664 -284.529276)
		(width 0.16002)
		(layer "In11.Cu")
		(net "M_F_CPU1_SB_DQS_DP<0>")
	)
	(segment
		(start 35.563556 -284.529276)
		(end 35.932618 -284.160214)
		(width 0.16002)
		(layer "In11.Cu")
		(net "M_F_CPU1_SB_DQS_DP<0>")
	)
	(segment
		(start 27.574748 -284.529276)
		(end 28.019502 -284.529276)
		(width 0.16002)
		(layer "In11.Cu")
		(net "M_F_CPU1_SB_DQS_DP<0>")
	)
	(segment
		(start 84.48167 -276.05863)
		(end 84.505038 -275.971762)
		(width 0.09525)
		(layer "In11.Cu")
		(net "M_F_CPU1_SB_DQS_DP<0>")
	)
	(segment
		(start 23.42642 -285.159196)
		(end 24.006302 -285.159196)
		(width 0.16002)
		(layer "In11.Cu")
		(net "M_F_CPU1_SB_DQS_DP<0>")
	)
	(segment
		(start 75.963526 -275.157184)
		(end 75.987148 -275.157184)
		(width 0.09525)
		(layer "In11.Cu")
		(net "M_F_CPU1_SB_DQS_DP<0>")
	)
	(segment
		(start 60.777374 -283.476954)
		(end 60.946284 -283.645864)
		(width 0.16002)
		(layer "In11.Cu")
		(net "M_F_CPU1_SB_DQS_DP<0>")
	)
	(segment
		(start 53.520086 -284.802834)
		(end 53.876956 -284.802834)
		(width 0.16002)
		(layer "In11.Cu")
		(net "M_F_CPU1_SB_DQS_DP<0>")
	)
	(segment
		(start 65.540636 -279.277572)
		(end 65.540636 -279.051512)
		(width 0.16002)
		(layer "In11.Cu")
		(net "M_F_CPU1_SB_DQS_DP<0>")
	)
	(segment
		(start 56.92521 -285.354776)
		(end 57.75071 -284.529276)
		(width 0.16002)
		(layer "In11.Cu")
		(net "M_F_CPU1_SB_DQS_DP<0>")
	)
	(segment
		(start 61.172344 -283.645864)
		(end 61.41974 -283.398468)
		(width 0.16002)
		(layer "In11.Cu")
		(net "M_F_CPU1_SB_DQS_DP<0>")
	)
	(segment
		(start 50.651664 -284.529276)
		(end 51.020726 -284.160214)
		(width 0.16002)
		(layer "In11.Cu")
		(net "M_F_CPU1_SB_DQS_DP<0>")
	)
	(segment
		(start 24.006302 -285.159196)
		(end 24.1554 -285.010098)
		(width 0.16002)
		(layer "In11.Cu")
		(net "M_F_CPU1_SB_DQS_DP<0>")
	)
	(segment
		(start 60.30087 -283.476954)
		(end 60.777374 -283.476954)
		(width 0.16002)
		(layer "In11.Cu")
		(net "M_F_CPU1_SB_DQS_DP<0>")
	)
	(segment
		(start 66.745358 -277.032466)
		(end 67.16903 -276.608794)
		(width 0.16002)
		(layer "In11.Cu")
		(net "M_F_CPU1_SB_DQS_DP<0>")
	)
	(segment
		(start 22.82952 -285.042356)
		(end 23.30958 -285.042356)
		(width 0.16002)
		(layer "In11.Cu")
		(net "M_F_CPU1_SB_DQS_DP<0>")
	)
	(segment
		(start 33.894014 -285.354776)
		(end 34.293302 -285.354776)
		(width 0.16002)
		(layer "In11.Cu")
		(net "M_F_CPU1_SB_DQS_DP<0>")
	)
	(segment
		(start 48.637444 -285.010098)
		(end 48.982122 -285.354776)
		(width 0.16002)
		(layer "In11.Cu")
		(net "M_F_CPU1_SB_DQS_DP<0>")
	)
	(segment
		(start 63.919608 -280.8986)
		(end 64.167004 -280.651204)
		(width 0.16002)
		(layer "In11.Cu")
		(net "M_F_CPU1_SB_DQS_DP<0>")
	)
	(segment
		(start 41.837356 -285.354776)
		(end 42.662856 -284.529276)
		(width 0.16002)
		(layer "In11.Cu")
		(net "M_F_CPU1_SB_DQS_DP<0>")
	)
	(segment
		(start 63.048134 -280.72969)
		(end 63.524638 -280.72969)
		(width 0.16002)
		(layer "In11.Cu")
		(net "M_F_CPU1_SB_DQS_DP<0>")
	)
	(segment
		(start 64.89827 -279.356058)
		(end 65.06718 -279.524968)
		(width 0.16002)
		(layer "In11.Cu")
		(net "M_F_CPU1_SB_DQS_DP<0>")
	)
	(segment
		(start 45.333412 -284.160214)
		(end 46.183296 -285.010098)
		(width 0.16002)
		(layer "In11.Cu")
		(net "M_F_CPU1_SB_DQS_DP<0>")
	)
	(segment
		(start 42.662856 -284.529276)
		(end 43.10761 -284.529276)
		(width 0.16002)
		(layer "In11.Cu")
		(net "M_F_CPU1_SB_DQS_DP<0>")
	)
	(segment
		(start 65.795398 -277.982426)
		(end 66.271902 -277.982426)
		(width 0.16002)
		(layer "In11.Cu")
		(net "M_F_CPU1_SB_DQS_DP<0>")
	)
	(segment
		(start 66.914268 -277.90394)
		(end 66.914268 -277.67788)
		(width 0.16002)
		(layer "In11.Cu")
		(net "M_F_CPU1_SB_DQS_DP<0>")
	)
	(segment
		(start 79.840328 -276.031706)
		(end 79.840582 -276.031452)
		(width 0.09525)
		(layer "In11.Cu")
		(net "M_F_CPU1_SB_DQS_DP<0>")
	)
	(segment
		(start 76.046076 -275.216112)
		(end 77.21219 -275.216112)
		(width 0.09525)
		(layer "In11.Cu")
		(net "M_F_CPU1_SB_DQS_DP<0>")
	)
	(segment
		(start 41.438068 -285.354776)
		(end 41.837356 -285.354776)
		(width 0.16002)
		(layer "In11.Cu")
		(net "M_F_CPU1_SB_DQS_DP<0>")
	)
	(segment
		(start 68.040504 -276.777704)
		(end 68.2879 -276.530308)
		(width 0.16002)
		(layer "In11.Cu")
		(net "M_F_CPU1_SB_DQS_DP<0>")
	)
	(segment
		(start 62.319916 -282.272232)
		(end 62.545976 -282.272232)
		(width 0.16002)
		(layer "In11.Cu")
		(net "M_F_CPU1_SB_DQS_DP<0>")
	)
	(segment
		(start 35.932618 -284.160214)
		(end 37.789358 -284.160214)
		(width 0.16002)
		(layer "In11.Cu")
		(net "M_F_CPU1_SB_DQS_DP<0>")
	)
	(segment
		(start 75.987148 -275.157184)
		(end 76.046076 -275.216112)
		(width 0.09525)
		(layer "In11.Cu")
		(net "M_F_CPU1_SB_DQS_DP<0>")
	)
	(segment
		(start 61.25083 -283.003498)
		(end 61.25083 -282.526994)
		(width 0.16002)
		(layer "In11.Cu")
		(net "M_F_CPU1_SB_DQS_DP<0>")
	)
	(segment
		(start 68.2879 -276.304248)
		(end 68.11899 -276.135338)
		(width 0.16002)
		(layer "In11.Cu")
		(net "M_F_CPU1_SB_DQS_DP<0>")
	)
	(segment
		(start 68.11899 -276.135338)
		(end 68.11899 -275.658834)
		(width 0.16002)
		(layer "In11.Cu")
		(net "M_F_CPU1_SB_DQS_DP<0>")
	)
	(segment
		(start 65.540636 -279.051512)
		(end 65.371726 -278.882602)
		(width 0.16002)
		(layer "In11.Cu")
		(net "M_F_CPU1_SB_DQS_DP<0>")
	)
	(arc
		(start 82.282538 -276.031452)
		(mid 82.471006 -276.082129)
		(end 82.659474 -276.031452)
		(width 0.09525)
		(layer "In11.Cu")
		(net "M_F_CPU1_SB_DQS_DP<0>")
	)
	(arc
		(start 81.719674 -276.031452)
		(mid 82.001106 -275.955697)
		(end 82.282538 -276.031452)
		(width 0.09525)
		(layer "In11.Cu")
		(net "M_F_CPU1_SB_DQS_DP<0>")
	)
	(arc
		(start 82.659474 -276.031452)
		(mid 82.940906 -275.955697)
		(end 83.222338 -276.031452)
		(width 0.09525)
		(layer "In11.Cu")
		(net "M_F_CPU1_SB_DQS_DP<0>")
	)
	(arc
		(start 79.858362 -276.021038)
		(mid 80.131742 -275.955817)
		(end 80.40243 -276.031452)
		(width 0.09525)
		(layer "In11.Cu")
		(net "M_F_CPU1_SB_DQS_DP<0>")
	)
	(arc
		(start 81.350866 -276.036278)
		(mid 81.535898 -276.082192)
		(end 81.719674 -276.031452)
		(width 0.09525)
		(layer "In11.Cu")
		(net "M_F_CPU1_SB_DQS_DP<0>")
	)
	(arc
		(start 83.222338 -276.031452)
		(mid 83.406113 -276.082224)
		(end 83.591146 -276.036278)
		(width 0.09525)
		(layer "In11.Cu")
		(net "M_F_CPU1_SB_DQS_DP<0>")
	)
	(arc
		(start 83.599528 -276.031452)
		(mid 83.88096 -275.955697)
		(end 84.162392 -276.031452)
		(width 0.09525)
		(layer "In11.Cu")
		(net "M_F_CPU1_SB_DQS_DP<0>")
	)
	(arc
		(start 80.40243 -276.031452)
		(mid 80.586205 -276.082224)
		(end 80.771238 -276.036278)
		(width 0.09525)
		(layer "In11.Cu")
		(net "M_F_CPU1_SB_DQS_DP<0>")
	)
	(arc
		(start 79.652114 -276.082506)
		(mid 79.749575 -276.069525)
		(end 79.840328 -276.031706)
		(width 0.09525)
		(layer "In11.Cu")
		(net "M_F_CPU1_SB_DQS_DP<0>")
	)
	(arc
		(start 80.77962 -276.031452)
		(mid 81.061052 -275.955697)
		(end 81.342484 -276.031452)
		(width 0.09525)
		(layer "In11.Cu")
		(net "M_F_CPU1_SB_DQS_DP<0>")
	)
	(arc
		(start 84.162392 -276.031452)
		(mid 84.31899 -276.080741)
		(end 84.48167 -276.05863)
		(width 0.09525)
		(layer "In11.Cu")
		(net "M_F_CPU1_SB_DQS_DP<0>")
	)
	(segment
		(start 85.287866 -271.390364)
		(end 84.821014 -271.656302)
		(width 0.12954)
		(layer "F.Cu")
		(net "M_F_CPU1_SB_DQS_DN<9>")
	)
	(segment
		(start 51.145948 -275.11248)
		(end 52.752244 -275.11248)
		(width 0.16002)
		(layer "In11.Cu")
		(net "M_F_CPU1_SB_DQS_DN<9>")
	)
	(segment
		(start 77.389482 -270.329914)
		(end 78.466188 -271.40662)
		(width 0.09525)
		(layer "In11.Cu")
		(net "M_F_CPU1_SB_DQS_DN<9>")
	)
	(segment
		(start 45.20819 -275.11248)
		(end 46.058074 -275.962364)
		(width 0.16002)
		(layer "In11.Cu")
		(net "M_F_CPU1_SB_DQS_DN<9>")
	)
	(segment
		(start 76.88326 -270.329914)
		(end 77.389482 -270.329914)
		(width 0.09525)
		(layer "In11.Cu")
		(net "M_F_CPU1_SB_DQS_DN<9>")
	)
	(segment
		(start 38.334442 -275.962364)
		(end 38.6715 -275.625306)
		(width 0.16002)
		(layer "In11.Cu")
		(net "M_F_CPU1_SB_DQS_DN<9>")
	)
	(segment
		(start 34.418524 -276.307042)
		(end 35.244024 -275.481542)
		(width 0.16002)
		(layer "In11.Cu")
		(net "M_F_CPU1_SB_DQS_DN<9>")
	)
	(segment
		(start 39.179754 -274.609306)
		(end 39.339774 -274.769326)
		(width 0.16002)
		(layer "In11.Cu")
		(net "M_F_CPU1_SB_DQS_DN<9>")
	)
	(segment
		(start 32.048196 -275.962364)
		(end 33.424114 -275.962364)
		(width 0.16002)
		(layer "In11.Cu")
		(net "M_F_CPU1_SB_DQS_DN<9>")
	)
	(segment
		(start 48.8569 -276.307042)
		(end 49.506632 -276.307042)
		(width 0.16002)
		(layer "In11.Cu")
		(net "M_F_CPU1_SB_DQS_DN<9>")
	)
	(segment
		(start 84.566252 -271.364202)
		(end 84.66709 -271.390872)
		(width 0.09525)
		(layer "In11.Cu")
		(net "M_F_CPU1_SB_DQS_DN<9>")
	)
	(segment
		(start 43.232832 -275.481542)
		(end 43.601894 -275.11248)
		(width 0.16002)
		(layer "In11.Cu")
		(net "M_F_CPU1_SB_DQS_DN<9>")
	)
	(segment
		(start 42.788078 -275.481542)
		(end 43.232832 -275.481542)
		(width 0.16002)
		(layer "In11.Cu")
		(net "M_F_CPU1_SB_DQS_DN<9>")
	)
	(segment
		(start 29.427678 -275.11248)
		(end 30.277562 -275.962364)
		(width 0.16002)
		(layer "In11.Cu")
		(net "M_F_CPU1_SB_DQS_DN<9>")
	)
	(segment
		(start 83.692492 -271.331182)
		(end 83.700874 -271.326356)
		(width 0.09525)
		(layer "In11.Cu")
		(net "M_F_CPU1_SB_DQS_DN<9>")
	)
	(segment
		(start 27.69997 -275.481542)
		(end 28.144724 -275.481542)
		(width 0.16002)
		(layer "In11.Cu")
		(net "M_F_CPU1_SB_DQS_DN<9>")
	)
	(segment
		(start 48.512222 -275.962364)
		(end 48.8569 -276.307042)
		(width 0.16002)
		(layer "In11.Cu")
		(net "M_F_CPU1_SB_DQS_DN<9>")
	)
	(segment
		(start 82.752438 -271.331182)
		(end 82.76082 -271.326356)
		(width 0.09525)
		(layer "In11.Cu")
		(net "M_F_CPU1_SB_DQS_DN<9>")
	)
	(segment
		(start 43.601894 -275.11248)
		(end 45.20819 -275.11248)
		(width 0.16002)
		(layer "In11.Cu")
		(net "M_F_CPU1_SB_DQS_DN<9>")
	)
	(segment
		(start 31.042864 -275.625306)
		(end 31.042864 -274.456906)
		(width 0.16002)
		(layer "In11.Cu")
		(net "M_F_CPU1_SB_DQS_DN<9>")
	)
	(segment
		(start 54.303676 -276.307042)
		(end 57.050432 -276.307042)
		(width 0.16002)
		(layer "In11.Cu")
		(net "M_F_CPU1_SB_DQS_DN<9>")
	)
	(segment
		(start 41.962578 -276.307042)
		(end 42.788078 -275.481542)
		(width 0.16002)
		(layer "In11.Cu")
		(net "M_F_CPU1_SB_DQS_DN<9>")
	)
	(segment
		(start 82.181192 -271.326356)
		(end 82.189574 -271.331182)
		(width 0.09525)
		(layer "In11.Cu")
		(net "M_F_CPU1_SB_DQS_DN<9>")
	)
	(segment
		(start 36.989004 -275.11248)
		(end 37.838888 -275.962364)
		(width 0.16002)
		(layer "In11.Cu")
		(net "M_F_CPU1_SB_DQS_DN<9>")
	)
	(segment
		(start 49.506632 -276.307042)
		(end 50.332132 -275.481542)
		(width 0.16002)
		(layer "In11.Cu")
		(net "M_F_CPU1_SB_DQS_DN<9>")
	)
	(segment
		(start 75.955906 -269.835884)
		(end 75.979528 -269.835884)
		(width 0.09525)
		(layer "In11.Cu")
		(net "M_F_CPU1_SB_DQS_DN<9>")
	)
	(segment
		(start 84.66709 -271.390872)
		(end 84.821014 -271.656302)
		(width 0.09525)
		(layer "In11.Cu")
		(net "M_F_CPU1_SB_DQS_DN<9>")
	)
	(segment
		(start 31.551118 -274.296886)
		(end 31.711138 -274.456906)
		(width 0.16002)
		(layer "In11.Cu")
		(net "M_F_CPU1_SB_DQS_DN<9>")
	)
	(segment
		(start 28.144724 -275.481542)
		(end 28.513786 -275.11248)
		(width 0.16002)
		(layer "In11.Cu")
		(net "M_F_CPU1_SB_DQS_DN<9>")
	)
	(segment
		(start 31.711138 -274.456906)
		(end 31.711138 -275.625306)
		(width 0.16002)
		(layer "In11.Cu")
		(net "M_F_CPU1_SB_DQS_DN<9>")
	)
	(segment
		(start 31.042864 -274.456906)
		(end 31.202884 -274.296886)
		(width 0.16002)
		(layer "In11.Cu")
		(net "M_F_CPU1_SB_DQS_DN<9>")
	)
	(segment
		(start 65.132458 -269.835884)
		(end 75.955906 -269.835884)
		(width 0.16002)
		(layer "In11.Cu")
		(net "M_F_CPU1_SB_DQS_DN<9>")
	)
	(segment
		(start 57.875932 -275.481542)
		(end 59.4868 -275.481542)
		(width 0.16002)
		(layer "In11.Cu")
		(net "M_F_CPU1_SB_DQS_DN<9>")
	)
	(segment
		(start 35.688778 -275.481542)
		(end 36.05784 -275.11248)
		(width 0.16002)
		(layer "In11.Cu")
		(net "M_F_CPU1_SB_DQS_DN<9>")
	)
	(segment
		(start 24.280622 -275.962364)
		(end 25.88006 -275.962364)
		(width 0.16002)
		(layer "In11.Cu")
		(net "M_F_CPU1_SB_DQS_DN<9>")
	)
	(segment
		(start 26.224738 -276.307042)
		(end 26.87447 -276.307042)
		(width 0.16002)
		(layer "In11.Cu")
		(net "M_F_CPU1_SB_DQS_DN<9>")
	)
	(segment
		(start 75.979528 -269.835884)
		(end 76.03871 -269.776702)
		(width 0.09525)
		(layer "In11.Cu")
		(net "M_F_CPU1_SB_DQS_DN<9>")
	)
	(segment
		(start 39.339774 -274.769326)
		(end 39.339774 -275.625306)
		(width 0.16002)
		(layer "In11.Cu")
		(net "M_F_CPU1_SB_DQS_DN<9>")
	)
	(segment
		(start 59.4868 -275.481542)
		(end 65.132458 -269.835884)
		(width 0.16002)
		(layer "In11.Cu")
		(net "M_F_CPU1_SB_DQS_DN<9>")
	)
	(segment
		(start 57.050432 -276.307042)
		(end 57.875932 -275.481542)
		(width 0.16002)
		(layer "In11.Cu")
		(net "M_F_CPU1_SB_DQS_DN<9>")
	)
	(segment
		(start 37.838888 -275.962364)
		(end 38.334442 -275.962364)
		(width 0.16002)
		(layer "In11.Cu")
		(net "M_F_CPU1_SB_DQS_DN<9>")
	)
	(segment
		(start 50.776886 -275.481542)
		(end 51.145948 -275.11248)
		(width 0.16002)
		(layer "In11.Cu")
		(net "M_F_CPU1_SB_DQS_DN<9>")
	)
	(segment
		(start 40.968168 -275.962364)
		(end 41.312846 -276.307042)
		(width 0.16002)
		(layer "In11.Cu")
		(net "M_F_CPU1_SB_DQS_DN<9>")
	)
	(segment
		(start 21.981922 -276.111462)
		(end 24.131524 -276.111462)
		(width 0.16002)
		(layer "In11.Cu")
		(net "M_F_CPU1_SB_DQS_DN<9>")
	)
	(segment
		(start 30.277562 -275.962364)
		(end 30.705806 -275.962364)
		(width 0.16002)
		(layer "In11.Cu")
		(net "M_F_CPU1_SB_DQS_DN<9>")
	)
	(segment
		(start 30.705806 -275.962364)
		(end 31.042864 -275.625306)
		(width 0.16002)
		(layer "In11.Cu")
		(net "M_F_CPU1_SB_DQS_DN<9>")
	)
	(segment
		(start 25.88006 -275.962364)
		(end 26.224738 -276.307042)
		(width 0.16002)
		(layer "In11.Cu")
		(net "M_F_CPU1_SB_DQS_DN<9>")
	)
	(segment
		(start 38.83152 -274.609306)
		(end 39.179754 -274.609306)
		(width 0.16002)
		(layer "In11.Cu")
		(net "M_F_CPU1_SB_DQS_DN<9>")
	)
	(segment
		(start 21.70811 -276.385274)
		(end 21.981922 -276.111462)
		(width 0.16002)
		(layer "In11.Cu")
		(net "M_F_CPU1_SB_DQS_DN<9>")
	)
	(segment
		(start 76.330048 -269.776702)
		(end 76.88326 -270.329914)
		(width 0.09525)
		(layer "In11.Cu")
		(net "M_F_CPU1_SB_DQS_DN<9>")
	)
	(segment
		(start 50.332132 -275.481542)
		(end 50.776886 -275.481542)
		(width 0.16002)
		(layer "In11.Cu")
		(net "M_F_CPU1_SB_DQS_DN<9>")
	)
	(segment
		(start 78.466188 -271.40662)
		(end 79.65186 -271.40662)
		(width 0.09525)
		(layer "In11.Cu")
		(net "M_F_CPU1_SB_DQS_DN<9>")
	)
	(segment
		(start 31.202884 -274.296886)
		(end 31.551118 -274.296886)
		(width 0.16002)
		(layer "In11.Cu")
		(net "M_F_CPU1_SB_DQS_DN<9>")
	)
	(segment
		(start 31.711138 -275.625306)
		(end 32.048196 -275.962364)
		(width 0.16002)
		(layer "In11.Cu")
		(net "M_F_CPU1_SB_DQS_DN<9>")
	)
	(segment
		(start 39.339774 -275.625306)
		(end 39.676832 -275.962364)
		(width 0.16002)
		(layer "In11.Cu")
		(net "M_F_CPU1_SB_DQS_DN<9>")
	)
	(segment
		(start 41.312846 -276.307042)
		(end 41.962578 -276.307042)
		(width 0.16002)
		(layer "In11.Cu")
		(net "M_F_CPU1_SB_DQS_DN<9>")
	)
	(segment
		(start 38.6715 -275.625306)
		(end 38.6715 -274.769326)
		(width 0.16002)
		(layer "In11.Cu")
		(net "M_F_CPU1_SB_DQS_DN<9>")
	)
	(segment
		(start 39.676832 -275.962364)
		(end 40.968168 -275.962364)
		(width 0.16002)
		(layer "In11.Cu")
		(net "M_F_CPU1_SB_DQS_DN<9>")
	)
	(segment
		(start 46.058074 -275.962364)
		(end 48.512222 -275.962364)
		(width 0.16002)
		(layer "In11.Cu")
		(net "M_F_CPU1_SB_DQS_DN<9>")
	)
	(segment
		(start 33.768792 -276.307042)
		(end 34.418524 -276.307042)
		(width 0.16002)
		(layer "In11.Cu")
		(net "M_F_CPU1_SB_DQS_DN<9>")
	)
	(segment
		(start 35.244024 -275.481542)
		(end 35.688778 -275.481542)
		(width 0.16002)
		(layer "In11.Cu")
		(net "M_F_CPU1_SB_DQS_DN<9>")
	)
	(segment
		(start 28.513786 -275.11248)
		(end 29.427678 -275.11248)
		(width 0.16002)
		(layer "In11.Cu")
		(net "M_F_CPU1_SB_DQS_DN<9>")
	)
	(segment
		(start 52.752244 -275.11248)
		(end 53.394864 -275.7551)
		(width 0.16002)
		(layer "In11.Cu")
		(net "M_F_CPU1_SB_DQS_DN<9>")
	)
	(segment
		(start 24.131524 -276.111462)
		(end 24.280622 -275.962364)
		(width 0.16002)
		(layer "In11.Cu")
		(net "M_F_CPU1_SB_DQS_DN<9>")
	)
	(segment
		(start 36.05784 -275.11248)
		(end 36.989004 -275.11248)
		(width 0.16002)
		(layer "In11.Cu")
		(net "M_F_CPU1_SB_DQS_DN<9>")
	)
	(segment
		(start 53.394864 -275.7551)
		(end 53.751734 -275.7551)
		(width 0.16002)
		(layer "In11.Cu")
		(net "M_F_CPU1_SB_DQS_DN<9>")
	)
	(segment
		(start 26.87447 -276.307042)
		(end 27.69997 -275.481542)
		(width 0.16002)
		(layer "In11.Cu")
		(net "M_F_CPU1_SB_DQS_DN<9>")
	)
	(segment
		(start 33.424114 -275.962364)
		(end 33.768792 -276.307042)
		(width 0.16002)
		(layer "In11.Cu")
		(net "M_F_CPU1_SB_DQS_DN<9>")
	)
	(segment
		(start 76.03871 -269.776702)
		(end 76.330048 -269.776702)
		(width 0.09525)
		(layer "In11.Cu")
		(net "M_F_CPU1_SB_DQS_DN<9>")
	)
	(segment
		(start 53.751734 -275.7551)
		(end 54.303676 -276.307042)
		(width 0.16002)
		(layer "In11.Cu")
		(net "M_F_CPU1_SB_DQS_DN<9>")
	)
	(segment
		(start 79.932784 -271.331182)
		(end 79.944722 -271.324324)
		(width 0.09525)
		(layer "In11.Cu")
		(net "M_F_CPU1_SB_DQS_DN<9>")
	)
	(segment
		(start 38.6715 -274.769326)
		(end 38.83152 -274.609306)
		(width 0.16002)
		(layer "In11.Cu")
		(net "M_F_CPU1_SB_DQS_DN<9>")
	)
	(arc
		(start 81.812384 -271.331182)
		(mid 81.996159 -271.28041)
		(end 82.181192 -271.326356)
		(width 0.09525)
		(layer "In11.Cu")
		(net "M_F_CPU1_SB_DQS_DN<9>")
	)
	(arc
		(start 84.545932 -271.372076)
		(mid 84.556131 -271.368239)
		(end 84.566252 -271.364202)
		(width 0.09525)
		(layer "In11.Cu")
		(net "M_F_CPU1_SB_DQS_DN<9>")
	)
	(arc
		(start 83.700874 -271.326356)
		(mid 83.885906 -271.280442)
		(end 84.069682 -271.331182)
		(width 0.09525)
		(layer "In11.Cu")
		(net "M_F_CPU1_SB_DQS_DN<9>")
	)
	(arc
		(start 80.30972 -271.331182)
		(mid 80.591152 -271.406937)
		(end 80.872584 -271.331182)
		(width 0.09525)
		(layer "In11.Cu")
		(net "M_F_CPU1_SB_DQS_DN<9>")
	)
	(arc
		(start 79.944722 -271.324324)
		(mid 80.128103 -271.280493)
		(end 80.30972 -271.331182)
		(width 0.09525)
		(layer "In11.Cu")
		(net "M_F_CPU1_SB_DQS_DN<9>")
	)
	(arc
		(start 83.129628 -271.331182)
		(mid 83.41106 -271.406937)
		(end 83.692492 -271.331182)
		(width 0.09525)
		(layer "In11.Cu")
		(net "M_F_CPU1_SB_DQS_DN<9>")
	)
	(arc
		(start 81.24952 -271.331182)
		(mid 81.530952 -271.406937)
		(end 81.812384 -271.331182)
		(width 0.09525)
		(layer "In11.Cu")
		(net "M_F_CPU1_SB_DQS_DN<9>")
	)
	(arc
		(start 79.65186 -271.40662)
		(mid 79.79729 -271.387418)
		(end 79.932784 -271.331182)
		(width 0.09525)
		(layer "In11.Cu")
		(net "M_F_CPU1_SB_DQS_DN<9>")
	)
	(arc
		(start 82.189574 -271.331182)
		(mid 82.471006 -271.406937)
		(end 82.752438 -271.331182)
		(width 0.09525)
		(layer "In11.Cu")
		(net "M_F_CPU1_SB_DQS_DN<9>")
	)
	(arc
		(start 82.76082 -271.326356)
		(mid 82.945852 -271.280442)
		(end 83.129628 -271.331182)
		(width 0.09525)
		(layer "In11.Cu")
		(net "M_F_CPU1_SB_DQS_DN<9>")
	)
	(arc
		(start 84.069682 -271.331182)
		(mid 84.303226 -271.404888)
		(end 84.545932 -271.372076)
		(width 0.09525)
		(layer "In11.Cu")
		(net "M_F_CPU1_SB_DQS_DN<9>")
	)
	(arc
		(start 80.872584 -271.331182)
		(mid 81.061052 -271.280505)
		(end 81.24952 -271.331182)
		(width 0.09525)
		(layer "In11.Cu")
		(net "M_F_CPU1_SB_DQS_DN<9>")
	)
	(segment
		(start 86.22792 -290.830254)
		(end 85.761068 -291.096192)
		(width 0.12954)
		(layer "F.Cu")
		(net "M_F_CPU1_SB_DQS_DN<8>")
	)
	(segment
		(start 19.075654 -314.059062)
		(end 19.635978 -314.059062)
		(width 0.16002)
		(layer "In11.Cu")
		(net "M_F_CPU1_SB_DQS_DN<8>")
	)
	(segment
		(start 22.86762 -314.23991)
		(end 23.377906 -314.23991)
		(width 0.16002)
		(layer "In11.Cu")
		(net "M_F_CPU1_SB_DQS_DN<8>")
	)
	(segment
		(start 53.489098 -314.20816)
		(end 54.019196 -314.738258)
		(width 0.16002)
		(layer "In11.Cu")
		(net "M_F_CPU1_SB_DQS_DN<8>")
	)
	(segment
		(start 51.12893 -314.20816)
		(end 53.489098 -314.20816)
		(width 0.16002)
		(layer "In11.Cu")
		(net "M_F_CPU1_SB_DQS_DN<8>")
	)
	(segment
		(start 48.86071 -314.738258)
		(end 49.33823 -314.738258)
		(width 0.16002)
		(layer "In11.Cu")
		(net "M_F_CPU1_SB_DQS_DN<8>")
	)
	(segment
		(start 40.996616 -315.058298)
		(end 41.316656 -314.738258)
		(width 0.16002)
		(layer "In11.Cu")
		(net "M_F_CPU1_SB_DQS_DN<8>")
	)
	(segment
		(start 36.040822 -314.20816)
		(end 38.40099 -314.20816)
		(width 0.16002)
		(layer "In11.Cu")
		(net "M_F_CPU1_SB_DQS_DN<8>")
	)
	(segment
		(start 85.914992 -291.361622)
		(end 85.761068 -291.096192)
		(width 0.09525)
		(layer "In11.Cu")
		(net "M_F_CPU1_SB_DQS_DN<8>")
	)
	(segment
		(start 18.958814 -313.942222)
		(end 19.075654 -314.059062)
		(width 0.16002)
		(layer "In11.Cu")
		(net "M_F_CPU1_SB_DQS_DN<8>")
	)
	(segment
		(start 54.019196 -314.738258)
		(end 56.88203 -314.738258)
		(width 0.16002)
		(layer "In11.Cu")
		(net "M_F_CPU1_SB_DQS_DN<8>")
	)
	(segment
		(start 77.69225 -295.850818)
		(end 77.69225 -293.63543)
		(width 0.09525)
		(layer "In11.Cu")
		(net "M_F_CPU1_SB_DQS_DN<8>")
	)
	(segment
		(start 35.686746 -313.854084)
		(end 36.040822 -314.20816)
		(width 0.16002)
		(layer "In11.Cu")
		(net "M_F_CPU1_SB_DQS_DN<8>")
	)
	(segment
		(start 27.590242 -313.854084)
		(end 28.142692 -313.854084)
		(width 0.16002)
		(layer "In11.Cu")
		(net "M_F_CPU1_SB_DQS_DN<8>")
	)
	(segment
		(start 22.10816 -314.23991)
		(end 22.24786 -314.10021)
		(width 0.16002)
		(layer "In11.Cu")
		(net "M_F_CPU1_SB_DQS_DN<8>")
	)
	(segment
		(start 80.030574 -291.47262)
		(end 80.120998 -291.47262)
		(width 0.09525)
		(layer "In11.Cu")
		(net "M_F_CPU1_SB_DQS_DN<8>")
	)
	(segment
		(start 45.945044 -314.20816)
		(end 46.795182 -315.058298)
		(width 0.16002)
		(layer "In11.Cu")
		(net "M_F_CPU1_SB_DQS_DN<8>")
	)
	(segment
		(start 43.584876 -314.20816)
		(end 45.945044 -314.20816)
		(width 0.16002)
		(layer "In11.Cu")
		(net "M_F_CPU1_SB_DQS_DN<8>")
	)
	(segment
		(start 34.250122 -314.738258)
		(end 35.134296 -313.854084)
		(width 0.16002)
		(layer "In11.Cu")
		(net "M_F_CPU1_SB_DQS_DN<8>")
	)
	(segment
		(start 77.303376 -296.155872)
		(end 77.387196 -296.155872)
		(width 0.09525)
		(layer "In11.Cu")
		(net "M_F_CPU1_SB_DQS_DN<8>")
	)
	(segment
		(start 17.881854 -314.059062)
		(end 18.361914 -314.059062)
		(width 0.16002)
		(layer "In11.Cu")
		(net "M_F_CPU1_SB_DQS_DN<8>")
	)
	(segment
		(start 82.181192 -291.426138)
		(end 82.189574 -291.421312)
		(width 0.09525)
		(layer "In11.Cu")
		(net "M_F_CPU1_SB_DQS_DN<8>")
	)
	(segment
		(start 39.251128 -315.058298)
		(end 40.996616 -315.058298)
		(width 0.16002)
		(layer "In11.Cu")
		(net "M_F_CPU1_SB_DQS_DN<8>")
	)
	(segment
		(start 18.361914 -314.059062)
		(end 18.478754 -313.942222)
		(width 0.16002)
		(layer "In11.Cu")
		(net "M_F_CPU1_SB_DQS_DN<8>")
	)
	(segment
		(start 22.24786 -314.10021)
		(end 22.72792 -314.10021)
		(width 0.16002)
		(layer "In11.Cu")
		(net "M_F_CPU1_SB_DQS_DN<8>")
	)
	(segment
		(start 20.64131 -313.893454)
		(end 20.987766 -314.23991)
		(width 0.16002)
		(layer "In11.Cu")
		(net "M_F_CPU1_SB_DQS_DN<8>")
	)
	(segment
		(start 28.496768 -314.20816)
		(end 30.856936 -314.20816)
		(width 0.16002)
		(layer "In11.Cu")
		(net "M_F_CPU1_SB_DQS_DN<8>")
	)
	(segment
		(start 82.752438 -291.421312)
		(end 82.76082 -291.426138)
		(width 0.09525)
		(layer "In11.Cu")
		(net "M_F_CPU1_SB_DQS_DN<8>")
	)
	(segment
		(start 77.286612 -296.172636)
		(end 77.303376 -296.155872)
		(width 0.09525)
		(layer "In11.Cu")
		(net "M_F_CPU1_SB_DQS_DN<8>")
	)
	(segment
		(start 38.40099 -314.20816)
		(end 39.251128 -315.058298)
		(width 0.16002)
		(layer "In11.Cu")
		(net "M_F_CPU1_SB_DQS_DN<8>")
	)
	(segment
		(start 33.772602 -314.738258)
		(end 34.250122 -314.738258)
		(width 0.16002)
		(layer "In11.Cu")
		(net "M_F_CPU1_SB_DQS_DN<8>")
	)
	(segment
		(start 22.72792 -314.10021)
		(end 22.86762 -314.23991)
		(width 0.16002)
		(layer "In11.Cu")
		(net "M_F_CPU1_SB_DQS_DN<8>")
	)
	(segment
		(start 77.69225 -293.63543)
		(end 79.730854 -291.596826)
		(width 0.09525)
		(layer "In11.Cu")
		(net "M_F_CPU1_SB_DQS_DN<8>")
	)
	(segment
		(start 50.774854 -313.854084)
		(end 51.12893 -314.20816)
		(width 0.16002)
		(layer "In11.Cu")
		(net "M_F_CPU1_SB_DQS_DN<8>")
	)
	(segment
		(start 18.478754 -313.942222)
		(end 18.958814 -313.942222)
		(width 0.16002)
		(layer "In11.Cu")
		(net "M_F_CPU1_SB_DQS_DN<8>")
	)
	(segment
		(start 31.707074 -315.058298)
		(end 33.452562 -315.058298)
		(width 0.16002)
		(layer "In11.Cu")
		(net "M_F_CPU1_SB_DQS_DN<8>")
	)
	(segment
		(start 49.33823 -314.738258)
		(end 50.222404 -313.854084)
		(width 0.16002)
		(layer "In11.Cu")
		(net "M_F_CPU1_SB_DQS_DN<8>")
	)
	(segment
		(start 59.605164 -313.854084)
		(end 77.286612 -296.172636)
		(width 0.16002)
		(layer "In11.Cu")
		(net "M_F_CPU1_SB_DQS_DN<8>")
	)
	(segment
		(start 25.908508 -315.058298)
		(end 26.228548 -314.738258)
		(width 0.16002)
		(layer "In11.Cu")
		(net "M_F_CPU1_SB_DQS_DN<8>")
	)
	(segment
		(start 42.67835 -313.854084)
		(end 43.2308 -313.854084)
		(width 0.16002)
		(layer "In11.Cu")
		(net "M_F_CPU1_SB_DQS_DN<8>")
	)
	(segment
		(start 41.794176 -314.738258)
		(end 42.67835 -313.854084)
		(width 0.16002)
		(layer "In11.Cu")
		(net "M_F_CPU1_SB_DQS_DN<8>")
	)
	(segment
		(start 35.134296 -313.854084)
		(end 35.686746 -313.854084)
		(width 0.16002)
		(layer "In11.Cu")
		(net "M_F_CPU1_SB_DQS_DN<8>")
	)
	(segment
		(start 83.692492 -291.421312)
		(end 83.700874 -291.426138)
		(width 0.09525)
		(layer "In11.Cu")
		(net "M_F_CPU1_SB_DQS_DN<8>")
	)
	(segment
		(start 28.142692 -313.854084)
		(end 28.496768 -314.20816)
		(width 0.16002)
		(layer "In11.Cu")
		(net "M_F_CPU1_SB_DQS_DN<8>")
	)
	(segment
		(start 24.196294 -315.058298)
		(end 25.908508 -315.058298)
		(width 0.16002)
		(layer "In11.Cu")
		(net "M_F_CPU1_SB_DQS_DN<8>")
	)
	(segment
		(start 46.795182 -315.058298)
		(end 48.54067 -315.058298)
		(width 0.16002)
		(layer "In11.Cu")
		(net "M_F_CPU1_SB_DQS_DN<8>")
	)
	(segment
		(start 56.88203 -314.738258)
		(end 57.766204 -313.854084)
		(width 0.16002)
		(layer "In11.Cu")
		(net "M_F_CPU1_SB_DQS_DN<8>")
	)
	(segment
		(start 30.856936 -314.20816)
		(end 31.707074 -315.058298)
		(width 0.16002)
		(layer "In11.Cu")
		(net "M_F_CPU1_SB_DQS_DN<8>")
	)
	(segment
		(start 85.891624 -291.44849)
		(end 85.914992 -291.361622)
		(width 0.09525)
		(layer "In11.Cu")
		(net "M_F_CPU1_SB_DQS_DN<8>")
	)
	(segment
		(start 17.608042 -313.78525)
		(end 17.881854 -314.059062)
		(width 0.16002)
		(layer "In11.Cu")
		(net "M_F_CPU1_SB_DQS_DN<8>")
	)
	(segment
		(start 23.377906 -314.23991)
		(end 24.196294 -315.058298)
		(width 0.16002)
		(layer "In11.Cu")
		(net "M_F_CPU1_SB_DQS_DN<8>")
	)
	(segment
		(start 43.2308 -313.854084)
		(end 43.584876 -314.20816)
		(width 0.16002)
		(layer "In11.Cu")
		(net "M_F_CPU1_SB_DQS_DN<8>")
	)
	(segment
		(start 26.706068 -314.738258)
		(end 27.590242 -313.854084)
		(width 0.16002)
		(layer "In11.Cu")
		(net "M_F_CPU1_SB_DQS_DN<8>")
	)
	(segment
		(start 50.222404 -313.854084)
		(end 50.774854 -313.854084)
		(width 0.16002)
		(layer "In11.Cu")
		(net "M_F_CPU1_SB_DQS_DN<8>")
	)
	(segment
		(start 33.452562 -315.058298)
		(end 33.772602 -314.738258)
		(width 0.16002)
		(layer "In11.Cu")
		(net "M_F_CPU1_SB_DQS_DN<8>")
	)
	(segment
		(start 19.801586 -313.893454)
		(end 20.64131 -313.893454)
		(width 0.16002)
		(layer "In11.Cu")
		(net "M_F_CPU1_SB_DQS_DN<8>")
	)
	(segment
		(start 79.730854 -291.596826)
		(end 80.030574 -291.47262)
		(width 0.09525)
		(layer "In11.Cu")
		(net "M_F_CPU1_SB_DQS_DN<8>")
	)
	(segment
		(start 26.228548 -314.738258)
		(end 26.706068 -314.738258)
		(width 0.16002)
		(layer "In11.Cu")
		(net "M_F_CPU1_SB_DQS_DN<8>")
	)
	(segment
		(start 20.987766 -314.23991)
		(end 22.10816 -314.23991)
		(width 0.16002)
		(layer "In11.Cu")
		(net "M_F_CPU1_SB_DQS_DN<8>")
	)
	(segment
		(start 57.766204 -313.854084)
		(end 59.605164 -313.854084)
		(width 0.16002)
		(layer "In11.Cu")
		(net "M_F_CPU1_SB_DQS_DN<8>")
	)
	(segment
		(start 19.635978 -314.059062)
		(end 19.801586 -313.893454)
		(width 0.16002)
		(layer "In11.Cu")
		(net "M_F_CPU1_SB_DQS_DN<8>")
	)
	(segment
		(start 48.54067 -315.058298)
		(end 48.86071 -314.738258)
		(width 0.16002)
		(layer "In11.Cu")
		(net "M_F_CPU1_SB_DQS_DN<8>")
	)
	(segment
		(start 77.387196 -296.155872)
		(end 77.69225 -295.850818)
		(width 0.09525)
		(layer "In11.Cu")
		(net "M_F_CPU1_SB_DQS_DN<8>")
	)
	(segment
		(start 41.316656 -314.738258)
		(end 41.794176 -314.738258)
		(width 0.16002)
		(layer "In11.Cu")
		(net "M_F_CPU1_SB_DQS_DN<8>")
	)
	(arc
		(start 84.069682 -291.421312)
		(mid 84.351114 -291.345557)
		(end 84.632546 -291.421312)
		(width 0.09525)
		(layer "In11.Cu")
		(net "M_F_CPU1_SB_DQS_DN<8>")
	)
	(arc
		(start 85.572346 -291.421312)
		(mid 85.728944 -291.470601)
		(end 85.891624 -291.44849)
		(width 0.09525)
		(layer "In11.Cu")
		(net "M_F_CPU1_SB_DQS_DN<8>")
	)
	(arc
		(start 83.700874 -291.426138)
		(mid 83.885906 -291.472052)
		(end 84.069682 -291.421312)
		(width 0.09525)
		(layer "In11.Cu")
		(net "M_F_CPU1_SB_DQS_DN<8>")
	)
	(arc
		(start 80.120998 -291.47262)
		(mid 80.218744 -291.459425)
		(end 80.30972 -291.421312)
		(width 0.09525)
		(layer "In11.Cu")
		(net "M_F_CPU1_SB_DQS_DN<8>")
	)
	(arc
		(start 85.009482 -291.421312)
		(mid 85.290914 -291.345557)
		(end 85.572346 -291.421312)
		(width 0.09525)
		(layer "In11.Cu")
		(net "M_F_CPU1_SB_DQS_DN<8>")
	)
	(arc
		(start 80.872584 -291.421312)
		(mid 81.061052 -291.471989)
		(end 81.24952 -291.421312)
		(width 0.09525)
		(layer "In11.Cu")
		(net "M_F_CPU1_SB_DQS_DN<8>")
	)
	(arc
		(start 81.812384 -291.421312)
		(mid 81.996159 -291.472084)
		(end 82.181192 -291.426138)
		(width 0.09525)
		(layer "In11.Cu")
		(net "M_F_CPU1_SB_DQS_DN<8>")
	)
	(arc
		(start 82.189574 -291.421312)
		(mid 82.471006 -291.345557)
		(end 82.752438 -291.421312)
		(width 0.09525)
		(layer "In11.Cu")
		(net "M_F_CPU1_SB_DQS_DN<8>")
	)
	(arc
		(start 80.30972 -291.421312)
		(mid 80.591152 -291.345557)
		(end 80.872584 -291.421312)
		(width 0.09525)
		(layer "In11.Cu")
		(net "M_F_CPU1_SB_DQS_DN<8>")
	)
	(arc
		(start 81.24952 -291.421312)
		(mid 81.530952 -291.345557)
		(end 81.812384 -291.421312)
		(width 0.09525)
		(layer "In11.Cu")
		(net "M_F_CPU1_SB_DQS_DN<8>")
	)
	(arc
		(start 84.632546 -291.421312)
		(mid 84.821014 -291.471989)
		(end 85.009482 -291.421312)
		(width 0.09525)
		(layer "In11.Cu")
		(net "M_F_CPU1_SB_DQS_DN<8>")
	)
	(arc
		(start 83.129628 -291.421312)
		(mid 83.41106 -291.345557)
		(end 83.692492 -291.421312)
		(width 0.09525)
		(layer "In11.Cu")
		(net "M_F_CPU1_SB_DQS_DN<8>")
	)
	(arc
		(start 82.76082 -291.426138)
		(mid 82.945852 -291.472052)
		(end 83.129628 -291.421312)
		(width 0.09525)
		(layer "In11.Cu")
		(net "M_F_CPU1_SB_DQS_DN<8>")
	)
	(segment
		(start 86.22792 -285.970472)
		(end 85.761068 -286.23641)
		(width 0.12954)
		(layer "F.Cu")
		(net "M_F_CPU1_SB_DQS_DN<7>")
	)
	(segment
		(start 78.034642 -286.929576)
		(end 76.810616 -286.929576)
		(width 0.09525)
		(layer "In11.Cu")
		(net "M_F_CPU1_SB_DQS_DN<7>")
	)
	(segment
		(start 78.31455 -286.649668)
		(end 78.034642 -286.929576)
		(width 0.09525)
		(layer "In11.Cu")
		(net "M_F_CPU1_SB_DQS_DN<7>")
	)
	(segment
		(start 76.810616 -286.929576)
		(end 76.055982 -287.68294)
		(width 0.09525)
		(layer "In11.Cu")
		(net "M_F_CPU1_SB_DQS_DN<7>")
	)
	(segment
		(start 18.55216 -304.592228)
		(end 18.43532 -304.709068)
		(width 0.16002)
		(layer "In11.Cu")
		(net "M_F_CPU1_SB_DQS_DN<7>")
	)
	(segment
		(start 79.379572 -286.555434)
		(end 79.369158 -286.56153)
		(width 0.09525)
		(layer "In11.Cu")
		(net "M_F_CPU1_SB_DQS_DN<7>")
	)
	(segment
		(start 20.987766 -304.889916)
		(end 20.64131 -304.54346)
		(width 0.16002)
		(layer "In11.Cu")
		(net "M_F_CPU1_SB_DQS_DN<7>")
	)
	(segment
		(start 43.2308 -304.50409)
		(end 42.67835 -304.50409)
		(width 0.16002)
		(layer "In11.Cu")
		(net "M_F_CPU1_SB_DQS_DN<7>")
	)
	(segment
		(start 83.700874 -286.566356)
		(end 83.692492 -286.56153)
		(width 0.09525)
		(layer "In11.Cu")
		(net "M_F_CPU1_SB_DQS_DN<7>")
	)
	(segment
		(start 48.86071 -305.388264)
		(end 48.54067 -305.708304)
		(width 0.16002)
		(layer "In11.Cu")
		(net "M_F_CPU1_SB_DQS_DN<7>")
	)
	(segment
		(start 22.300946 -304.773076)
		(end 22.184106 -304.889916)
		(width 0.16002)
		(layer "In11.Cu")
		(net "M_F_CPU1_SB_DQS_DN<7>")
	)
	(segment
		(start 33.452562 -305.708304)
		(end 31.707074 -305.708304)
		(width 0.16002)
		(layer "In11.Cu")
		(net "M_F_CPU1_SB_DQS_DN<7>")
	)
	(segment
		(start 17.881854 -304.709068)
		(end 17.608042 -304.435256)
		(width 0.16002)
		(layer "In11.Cu")
		(net "M_F_CPU1_SB_DQS_DN<7>")
	)
	(segment
		(start 85.761068 -286.23641)
		(end 85.914992 -286.50184)
		(width 0.09525)
		(layer "In11.Cu")
		(net "M_F_CPU1_SB_DQS_DN<7>")
	)
	(segment
		(start 78.992222 -286.561276)
		(end 78.986634 -286.557974)
		(width 0.09525)
		(layer "In11.Cu")
		(net "M_F_CPU1_SB_DQS_DN<7>")
	)
	(segment
		(start 75.955906 -287.699196)
		(end 67.553078 -296.102024)
		(width 0.16002)
		(layer "In11.Cu")
		(net "M_F_CPU1_SB_DQS_DN<7>")
	)
	(segment
		(start 57.766204 -304.50409)
		(end 56.88203 -305.388264)
		(width 0.16002)
		(layer "In11.Cu")
		(net "M_F_CPU1_SB_DQS_DN<7>")
	)
	(segment
		(start 24.196294 -305.708304)
		(end 23.377906 -304.889916)
		(width 0.16002)
		(layer "In11.Cu")
		(net "M_F_CPU1_SB_DQS_DN<7>")
	)
	(segment
		(start 26.706068 -305.388264)
		(end 26.228548 -305.388264)
		(width 0.16002)
		(layer "In11.Cu")
		(net "M_F_CPU1_SB_DQS_DN<7>")
	)
	(segment
		(start 76.055982 -287.68294)
		(end 75.97267 -287.682432)
		(width 0.09525)
		(layer "In11.Cu")
		(net "M_F_CPU1_SB_DQS_DN<7>")
	)
	(segment
		(start 53.489098 -304.858166)
		(end 51.12893 -304.858166)
		(width 0.16002)
		(layer "In11.Cu")
		(net "M_F_CPU1_SB_DQS_DN<7>")
	)
	(segment
		(start 39.251128 -305.708304)
		(end 38.40099 -304.858166)
		(width 0.16002)
		(layer "In11.Cu")
		(net "M_F_CPU1_SB_DQS_DN<7>")
	)
	(segment
		(start 31.707074 -305.708304)
		(end 30.856936 -304.858166)
		(width 0.16002)
		(layer "In11.Cu")
		(net "M_F_CPU1_SB_DQS_DN<7>")
	)
	(segment
		(start 19.635978 -304.709068)
		(end 19.14906 -304.709068)
		(width 0.16002)
		(layer "In11.Cu")
		(net "M_F_CPU1_SB_DQS_DN<7>")
	)
	(segment
		(start 51.12893 -304.858166)
		(end 50.774854 -304.50409)
		(width 0.16002)
		(layer "In11.Cu")
		(net "M_F_CPU1_SB_DQS_DN<7>")
	)
	(segment
		(start 18.43532 -304.709068)
		(end 17.881854 -304.709068)
		(width 0.16002)
		(layer "In11.Cu")
		(net "M_F_CPU1_SB_DQS_DN<7>")
	)
	(segment
		(start 79.003144 -286.567626)
		(end 78.992222 -286.561276)
		(width 0.09525)
		(layer "In11.Cu")
		(net "M_F_CPU1_SB_DQS_DN<7>")
	)
	(segment
		(start 40.996616 -305.708304)
		(end 39.251128 -305.708304)
		(width 0.16002)
		(layer "In11.Cu")
		(net "M_F_CPU1_SB_DQS_DN<7>")
	)
	(segment
		(start 36.040822 -304.858166)
		(end 35.686746 -304.50409)
		(width 0.16002)
		(layer "In11.Cu")
		(net "M_F_CPU1_SB_DQS_DN<7>")
	)
	(segment
		(start 19.03222 -304.592228)
		(end 18.55216 -304.592228)
		(width 0.16002)
		(layer "In11.Cu")
		(net "M_F_CPU1_SB_DQS_DN<7>")
	)
	(segment
		(start 49.33823 -305.388264)
		(end 48.86071 -305.388264)
		(width 0.16002)
		(layer "In11.Cu")
		(net "M_F_CPU1_SB_DQS_DN<7>")
	)
	(segment
		(start 22.184106 -304.889916)
		(end 20.987766 -304.889916)
		(width 0.16002)
		(layer "In11.Cu")
		(net "M_F_CPU1_SB_DQS_DN<7>")
	)
	(segment
		(start 23.377906 -304.889916)
		(end 22.897846 -304.889916)
		(width 0.16002)
		(layer "In11.Cu")
		(net "M_F_CPU1_SB_DQS_DN<7>")
	)
	(segment
		(start 35.134296 -304.50409)
		(end 34.250122 -305.388264)
		(width 0.16002)
		(layer "In11.Cu")
		(net "M_F_CPU1_SB_DQS_DN<7>")
	)
	(segment
		(start 41.794176 -305.388264)
		(end 41.316656 -305.388264)
		(width 0.16002)
		(layer "In11.Cu")
		(net "M_F_CPU1_SB_DQS_DN<7>")
	)
	(segment
		(start 30.856936 -304.858166)
		(end 28.496768 -304.858166)
		(width 0.16002)
		(layer "In11.Cu")
		(net "M_F_CPU1_SB_DQS_DN<7>")
	)
	(segment
		(start 28.496768 -304.858166)
		(end 28.142692 -304.50409)
		(width 0.16002)
		(layer "In11.Cu")
		(net "M_F_CPU1_SB_DQS_DN<7>")
	)
	(segment
		(start 85.914992 -286.50184)
		(end 85.891624 -286.588708)
		(width 0.09525)
		(layer "In11.Cu")
		(net "M_F_CPU1_SB_DQS_DN<7>")
	)
	(segment
		(start 22.897846 -304.889916)
		(end 22.781006 -304.773076)
		(width 0.16002)
		(layer "In11.Cu")
		(net "M_F_CPU1_SB_DQS_DN<7>")
	)
	(segment
		(start 82.189574 -286.56153)
		(end 82.181192 -286.566356)
		(width 0.09525)
		(layer "In11.Cu")
		(net "M_F_CPU1_SB_DQS_DN<7>")
	)
	(segment
		(start 42.67835 -304.50409)
		(end 41.794176 -305.388264)
		(width 0.16002)
		(layer "In11.Cu")
		(net "M_F_CPU1_SB_DQS_DN<7>")
	)
	(segment
		(start 82.76082 -286.566356)
		(end 82.752438 -286.56153)
		(width 0.09525)
		(layer "In11.Cu")
		(net "M_F_CPU1_SB_DQS_DN<7>")
	)
	(segment
		(start 35.686746 -304.50409)
		(end 35.134296 -304.50409)
		(width 0.16002)
		(layer "In11.Cu")
		(net "M_F_CPU1_SB_DQS_DN<7>")
	)
	(segment
		(start 27.590242 -304.50409)
		(end 26.706068 -305.388264)
		(width 0.16002)
		(layer "In11.Cu")
		(net "M_F_CPU1_SB_DQS_DN<7>")
	)
	(segment
		(start 48.54067 -305.708304)
		(end 46.795182 -305.708304)
		(width 0.16002)
		(layer "In11.Cu")
		(net "M_F_CPU1_SB_DQS_DN<7>")
	)
	(segment
		(start 46.795182 -305.708304)
		(end 45.945044 -304.858166)
		(width 0.16002)
		(layer "In11.Cu")
		(net "M_F_CPU1_SB_DQS_DN<7>")
	)
	(segment
		(start 41.316656 -305.388264)
		(end 40.996616 -305.708304)
		(width 0.16002)
		(layer "In11.Cu")
		(net "M_F_CPU1_SB_DQS_DN<7>")
	)
	(segment
		(start 45.945044 -304.858166)
		(end 43.584876 -304.858166)
		(width 0.16002)
		(layer "In11.Cu")
		(net "M_F_CPU1_SB_DQS_DN<7>")
	)
	(segment
		(start 26.228548 -305.388264)
		(end 25.908508 -305.708304)
		(width 0.16002)
		(layer "In11.Cu")
		(net "M_F_CPU1_SB_DQS_DN<7>")
	)
	(segment
		(start 19.801586 -304.54346)
		(end 19.635978 -304.709068)
		(width 0.16002)
		(layer "In11.Cu")
		(net "M_F_CPU1_SB_DQS_DN<7>")
	)
	(segment
		(start 25.908508 -305.708304)
		(end 24.196294 -305.708304)
		(width 0.16002)
		(layer "In11.Cu")
		(net "M_F_CPU1_SB_DQS_DN<7>")
	)
	(segment
		(start 59.151266 -304.50409)
		(end 57.766204 -304.50409)
		(width 0.16002)
		(layer "In11.Cu")
		(net "M_F_CPU1_SB_DQS_DN<7>")
	)
	(segment
		(start 50.774854 -304.50409)
		(end 50.222404 -304.50409)
		(width 0.16002)
		(layer "In11.Cu")
		(net "M_F_CPU1_SB_DQS_DN<7>")
	)
	(segment
		(start 22.781006 -304.773076)
		(end 22.300946 -304.773076)
		(width 0.16002)
		(layer "In11.Cu")
		(net "M_F_CPU1_SB_DQS_DN<7>")
	)
	(segment
		(start 75.97267 -287.682432)
		(end 75.955906 -287.699196)
		(width 0.09525)
		(layer "In11.Cu")
		(net "M_F_CPU1_SB_DQS_DN<7>")
	)
	(segment
		(start 78.314804 -286.64916)
		(end 78.31455 -286.649668)
		(width 0.09525)
		(layer "In11.Cu")
		(net "M_F_CPU1_SB_DQS_DN<7>")
	)
	(segment
		(start 28.142692 -304.50409)
		(end 27.590242 -304.50409)
		(width 0.16002)
		(layer "In11.Cu")
		(net "M_F_CPU1_SB_DQS_DN<7>")
	)
	(segment
		(start 20.64131 -304.54346)
		(end 19.801586 -304.54346)
		(width 0.16002)
		(layer "In11.Cu")
		(net "M_F_CPU1_SB_DQS_DN<7>")
	)
	(segment
		(start 34.250122 -305.388264)
		(end 33.772602 -305.388264)
		(width 0.16002)
		(layer "In11.Cu")
		(net "M_F_CPU1_SB_DQS_DN<7>")
	)
	(segment
		(start 56.88203 -305.388264)
		(end 54.019196 -305.388264)
		(width 0.16002)
		(layer "In11.Cu")
		(net "M_F_CPU1_SB_DQS_DN<7>")
	)
	(segment
		(start 43.584876 -304.858166)
		(end 43.2308 -304.50409)
		(width 0.16002)
		(layer "In11.Cu")
		(net "M_F_CPU1_SB_DQS_DN<7>")
	)
	(segment
		(start 19.14906 -304.709068)
		(end 19.03222 -304.592228)
		(width 0.16002)
		(layer "In11.Cu")
		(net "M_F_CPU1_SB_DQS_DN<7>")
	)
	(segment
		(start 67.553078 -296.102024)
		(end 67.553078 -296.102278)
		(width 0.16002)
		(layer "In11.Cu")
		(net "M_F_CPU1_SB_DQS_DN<7>")
	)
	(segment
		(start 54.019196 -305.388264)
		(end 53.489098 -304.858166)
		(width 0.16002)
		(layer "In11.Cu")
		(net "M_F_CPU1_SB_DQS_DN<7>")
	)
	(segment
		(start 50.222404 -304.50409)
		(end 49.33823 -305.388264)
		(width 0.16002)
		(layer "In11.Cu")
		(net "M_F_CPU1_SB_DQS_DN<7>")
	)
	(segment
		(start 33.772602 -305.388264)
		(end 33.452562 -305.708304)
		(width 0.16002)
		(layer "In11.Cu")
		(net "M_F_CPU1_SB_DQS_DN<7>")
	)
	(segment
		(start 67.553078 -296.102278)
		(end 59.151266 -304.50409)
		(width 0.16002)
		(layer "In11.Cu")
		(net "M_F_CPU1_SB_DQS_DN<7>")
	)
	(segment
		(start 38.40099 -304.858166)
		(end 36.040822 -304.858166)
		(width 0.16002)
		(layer "In11.Cu")
		(net "M_F_CPU1_SB_DQS_DN<7>")
	)
	(arc
		(start 82.752438 -286.56153)
		(mid 82.471006 -286.485741)
		(end 82.189574 -286.56153)
		(width 0.09525)
		(layer "In11.Cu")
		(net "M_F_CPU1_SB_DQS_DN<7>")
	)
	(arc
		(start 85.009482 -286.56153)
		(mid 84.821014 -286.612207)
		(end 84.632546 -286.56153)
		(width 0.09525)
		(layer "In11.Cu")
		(net "M_F_CPU1_SB_DQS_DN<7>")
	)
	(arc
		(start 85.891624 -286.588708)
		(mid 85.728942 -286.61084)
		(end 85.572346 -286.56153)
		(width 0.09525)
		(layer "In11.Cu")
		(net "M_F_CPU1_SB_DQS_DN<7>")
	)
	(arc
		(start 84.632546 -286.56153)
		(mid 84.351114 -286.485741)
		(end 84.069682 -286.56153)
		(width 0.09525)
		(layer "In11.Cu")
		(net "M_F_CPU1_SB_DQS_DN<7>")
	)
	(arc
		(start 78.429358 -286.56153)
		(mid 78.410325 -286.573095)
		(end 78.391766 -286.585406)
		(width 0.09525)
		(layer "In11.Cu")
		(net "M_F_CPU1_SB_DQS_DN<7>")
	)
	(arc
		(start 83.129628 -286.56153)
		(mid 82.945853 -286.612302)
		(end 82.76082 -286.566356)
		(width 0.09525)
		(layer "In11.Cu")
		(net "M_F_CPU1_SB_DQS_DN<7>")
	)
	(arc
		(start 83.692492 -286.56153)
		(mid 83.41106 -286.485741)
		(end 83.129628 -286.56153)
		(width 0.09525)
		(layer "In11.Cu")
		(net "M_F_CPU1_SB_DQS_DN<7>")
	)
	(arc
		(start 79.369158 -286.56153)
		(mid 79.186944 -286.612155)
		(end 79.003144 -286.567626)
		(width 0.09525)
		(layer "In11.Cu")
		(net "M_F_CPU1_SB_DQS_DN<7>")
	)
	(arc
		(start 78.986634 -286.557974)
		(mid 78.707515 -286.485569)
		(end 78.429358 -286.56153)
		(width 0.09525)
		(layer "In11.Cu")
		(net "M_F_CPU1_SB_DQS_DN<7>")
	)
	(arc
		(start 82.181192 -286.566356)
		(mid 81.99616 -286.61227)
		(end 81.812384 -286.56153)
		(width 0.09525)
		(layer "In11.Cu")
		(net "M_F_CPU1_SB_DQS_DN<7>")
	)
	(arc
		(start 84.069682 -286.56153)
		(mid 83.885907 -286.612302)
		(end 83.700874 -286.566356)
		(width 0.09525)
		(layer "In11.Cu")
		(net "M_F_CPU1_SB_DQS_DN<7>")
	)
	(arc
		(start 81.24952 -286.56153)
		(mid 81.061052 -286.612207)
		(end 80.872584 -286.56153)
		(width 0.09525)
		(layer "In11.Cu")
		(net "M_F_CPU1_SB_DQS_DN<7>")
	)
	(arc
		(start 78.391766 -286.585406)
		(mid 78.351867 -286.61557)
		(end 78.314804 -286.64916)
		(width 0.09525)
		(layer "In11.Cu")
		(net "M_F_CPU1_SB_DQS_DN<7>")
	)
	(arc
		(start 80.872584 -286.56153)
		(mid 80.591152 -286.485741)
		(end 80.30972 -286.56153)
		(width 0.09525)
		(layer "In11.Cu")
		(net "M_F_CPU1_SB_DQS_DN<7>")
	)
	(arc
		(start 85.572346 -286.56153)
		(mid 85.290914 -286.485741)
		(end 85.009482 -286.56153)
		(width 0.09525)
		(layer "In11.Cu")
		(net "M_F_CPU1_SB_DQS_DN<7>")
	)
	(arc
		(start 80.30972 -286.56153)
		(mid 80.120998 -286.612334)
		(end 79.932276 -286.56153)
		(width 0.09525)
		(layer "In11.Cu")
		(net "M_F_CPU1_SB_DQS_DN<7>")
	)
	(arc
		(start 79.932276 -286.56153)
		(mid 79.656733 -286.485647)
		(end 79.379572 -286.555434)
		(width 0.09525)
		(layer "In11.Cu")
		(net "M_F_CPU1_SB_DQS_DN<7>")
	)
	(arc
		(start 81.812384 -286.56153)
		(mid 81.530952 -286.485741)
		(end 81.24952 -286.56153)
		(width 0.09525)
		(layer "In11.Cu")
		(net "M_F_CPU1_SB_DQS_DN<7>")
	)
	(segment
		(start 86.22792 -281.110436)
		(end 85.761068 -281.376374)
		(width 0.12954)
		(layer "F.Cu")
		(net "M_F_CPU1_SB_DQS_DN<6>")
	)
	(segment
		(start 38.40099 -295.508172)
		(end 39.251128 -296.35831)
		(width 0.16002)
		(layer "In11.Cu")
		(net "M_F_CPU1_SB_DQS_DN<6>")
	)
	(segment
		(start 39.251128 -296.35831)
		(end 40.996616 -296.35831)
		(width 0.16002)
		(layer "In11.Cu")
		(net "M_F_CPU1_SB_DQS_DN<6>")
	)
	(segment
		(start 85.914992 -281.641804)
		(end 85.761068 -281.376374)
		(width 0.09525)
		(layer "In11.Cu")
		(net "M_F_CPU1_SB_DQS_DN<6>")
	)
	(segment
		(start 27.590242 -295.154096)
		(end 28.142692 -295.154096)
		(width 0.16002)
		(layer "In11.Cu")
		(net "M_F_CPU1_SB_DQS_DN<6>")
	)
	(segment
		(start 24.196294 -296.35831)
		(end 25.908508 -296.35831)
		(width 0.16002)
		(layer "In11.Cu")
		(net "M_F_CPU1_SB_DQS_DN<6>")
	)
	(segment
		(start 56.88203 -296.03827)
		(end 57.766204 -295.154096)
		(width 0.16002)
		(layer "In11.Cu")
		(net "M_F_CPU1_SB_DQS_DN<6>")
	)
	(segment
		(start 35.134296 -295.154096)
		(end 35.686746 -295.154096)
		(width 0.16002)
		(layer "In11.Cu")
		(net "M_F_CPU1_SB_DQS_DN<6>")
	)
	(segment
		(start 33.772602 -296.03827)
		(end 34.250122 -296.03827)
		(width 0.16002)
		(layer "In11.Cu")
		(net "M_F_CPU1_SB_DQS_DN<6>")
	)
	(segment
		(start 30.856936 -295.508172)
		(end 31.707074 -296.35831)
		(width 0.16002)
		(layer "In11.Cu")
		(net "M_F_CPU1_SB_DQS_DN<6>")
	)
	(segment
		(start 40.996616 -296.35831)
		(end 41.316656 -296.03827)
		(width 0.16002)
		(layer "In11.Cu")
		(net "M_F_CPU1_SB_DQS_DN<6>")
	)
	(segment
		(start 17.608042 -295.085262)
		(end 17.881854 -295.359074)
		(width 0.16002)
		(layer "In11.Cu")
		(net "M_F_CPU1_SB_DQS_DN<6>")
	)
	(segment
		(start 19.039078 -295.242234)
		(end 19.155918 -295.359074)
		(width 0.16002)
		(layer "In11.Cu")
		(net "M_F_CPU1_SB_DQS_DN<6>")
	)
	(segment
		(start 85.891624 -281.728672)
		(end 85.914992 -281.641804)
		(width 0.09525)
		(layer "In11.Cu")
		(net "M_F_CPU1_SB_DQS_DN<6>")
	)
	(segment
		(start 41.794176 -296.03827)
		(end 42.67835 -295.154096)
		(width 0.16002)
		(layer "In11.Cu")
		(net "M_F_CPU1_SB_DQS_DN<6>")
	)
	(segment
		(start 18.559018 -295.242234)
		(end 19.039078 -295.242234)
		(width 0.16002)
		(layer "In11.Cu")
		(net "M_F_CPU1_SB_DQS_DN<6>")
	)
	(segment
		(start 43.2308 -295.154096)
		(end 43.584876 -295.508172)
		(width 0.16002)
		(layer "In11.Cu")
		(net "M_F_CPU1_SB_DQS_DN<6>")
	)
	(segment
		(start 57.766204 -295.154096)
		(end 59.705748 -295.154096)
		(width 0.16002)
		(layer "In11.Cu")
		(net "M_F_CPU1_SB_DQS_DN<6>")
	)
	(segment
		(start 41.316656 -296.03827)
		(end 41.794176 -296.03827)
		(width 0.16002)
		(layer "In11.Cu")
		(net "M_F_CPU1_SB_DQS_DN<6>")
	)
	(segment
		(start 76.03871 -281.731466)
		(end 77.229208 -281.731466)
		(width 0.09525)
		(layer "In11.Cu")
		(net "M_F_CPU1_SB_DQS_DN<6>")
	)
	(segment
		(start 19.801586 -295.193466)
		(end 20.64131 -295.193466)
		(width 0.16002)
		(layer "In11.Cu")
		(net "M_F_CPU1_SB_DQS_DN<6>")
	)
	(segment
		(start 48.86071 -296.03827)
		(end 49.33823 -296.03827)
		(width 0.16002)
		(layer "In11.Cu")
		(net "M_F_CPU1_SB_DQS_DN<6>")
	)
	(segment
		(start 34.250122 -296.03827)
		(end 35.134296 -295.154096)
		(width 0.16002)
		(layer "In11.Cu")
		(net "M_F_CPU1_SB_DQS_DN<6>")
	)
	(segment
		(start 75.979528 -281.672284)
		(end 76.03871 -281.731466)
		(width 0.09525)
		(layer "In11.Cu")
		(net "M_F_CPU1_SB_DQS_DN<6>")
	)
	(segment
		(start 50.222404 -295.154096)
		(end 50.774854 -295.154096)
		(width 0.16002)
		(layer "In11.Cu")
		(net "M_F_CPU1_SB_DQS_DN<6>")
	)
	(segment
		(start 43.584876 -295.508172)
		(end 45.945044 -295.508172)
		(width 0.16002)
		(layer "In11.Cu")
		(net "M_F_CPU1_SB_DQS_DN<6>")
	)
	(segment
		(start 20.987766 -295.539922)
		(end 23.377906 -295.539922)
		(width 0.16002)
		(layer "In11.Cu")
		(net "M_F_CPU1_SB_DQS_DN<6>")
	)
	(segment
		(start 19.635978 -295.359074)
		(end 19.801586 -295.193466)
		(width 0.16002)
		(layer "In11.Cu")
		(net "M_F_CPU1_SB_DQS_DN<6>")
	)
	(segment
		(start 51.12893 -295.508172)
		(end 53.489098 -295.508172)
		(width 0.16002)
		(layer "In11.Cu")
		(net "M_F_CPU1_SB_DQS_DN<6>")
	)
	(segment
		(start 26.706068 -296.03827)
		(end 27.590242 -295.154096)
		(width 0.16002)
		(layer "In11.Cu")
		(net "M_F_CPU1_SB_DQS_DN<6>")
	)
	(segment
		(start 50.774854 -295.154096)
		(end 51.12893 -295.508172)
		(width 0.16002)
		(layer "In11.Cu")
		(net "M_F_CPU1_SB_DQS_DN<6>")
	)
	(segment
		(start 35.686746 -295.154096)
		(end 36.040822 -295.508172)
		(width 0.16002)
		(layer "In11.Cu")
		(net "M_F_CPU1_SB_DQS_DN<6>")
	)
	(segment
		(start 54.019196 -296.03827)
		(end 56.88203 -296.03827)
		(width 0.16002)
		(layer "In11.Cu")
		(net "M_F_CPU1_SB_DQS_DN<6>")
	)
	(segment
		(start 28.142692 -295.154096)
		(end 28.496768 -295.508172)
		(width 0.16002)
		(layer "In11.Cu")
		(net "M_F_CPU1_SB_DQS_DN<6>")
	)
	(segment
		(start 77.229208 -281.731466)
		(end 77.41666 -281.544014)
		(width 0.09525)
		(layer "In11.Cu")
		(net "M_F_CPU1_SB_DQS_DN<6>")
	)
	(segment
		(start 31.707074 -296.35831)
		(end 33.452562 -296.35831)
		(width 0.16002)
		(layer "In11.Cu")
		(net "M_F_CPU1_SB_DQS_DN<6>")
	)
	(segment
		(start 82.752438 -281.701494)
		(end 82.76082 -281.70632)
		(width 0.09525)
		(layer "In11.Cu")
		(net "M_F_CPU1_SB_DQS_DN<6>")
	)
	(segment
		(start 49.33823 -296.03827)
		(end 50.222404 -295.154096)
		(width 0.16002)
		(layer "In11.Cu")
		(net "M_F_CPU1_SB_DQS_DN<6>")
	)
	(segment
		(start 17.881854 -295.359074)
		(end 18.442178 -295.359074)
		(width 0.16002)
		(layer "In11.Cu")
		(net "M_F_CPU1_SB_DQS_DN<6>")
	)
	(segment
		(start 45.945044 -295.508172)
		(end 46.795182 -296.35831)
		(width 0.16002)
		(layer "In11.Cu")
		(net "M_F_CPU1_SB_DQS_DN<6>")
	)
	(segment
		(start 48.54067 -296.35831)
		(end 48.86071 -296.03827)
		(width 0.16002)
		(layer "In11.Cu")
		(net "M_F_CPU1_SB_DQS_DN<6>")
	)
	(segment
		(start 42.67835 -295.154096)
		(end 43.2308 -295.154096)
		(width 0.16002)
		(layer "In11.Cu")
		(net "M_F_CPU1_SB_DQS_DN<6>")
	)
	(segment
		(start 19.155918 -295.359074)
		(end 19.635978 -295.359074)
		(width 0.16002)
		(layer "In11.Cu")
		(net "M_F_CPU1_SB_DQS_DN<6>")
	)
	(segment
		(start 25.908508 -296.35831)
		(end 26.228548 -296.03827)
		(width 0.16002)
		(layer "In11.Cu")
		(net "M_F_CPU1_SB_DQS_DN<6>")
	)
	(segment
		(start 59.705748 -295.154096)
		(end 73.18756 -281.672284)
		(width 0.16002)
		(layer "In11.Cu")
		(net "M_F_CPU1_SB_DQS_DN<6>")
	)
	(segment
		(start 26.228548 -296.03827)
		(end 26.706068 -296.03827)
		(width 0.16002)
		(layer "In11.Cu")
		(net "M_F_CPU1_SB_DQS_DN<6>")
	)
	(segment
		(start 73.18756 -281.672284)
		(end 75.955906 -281.672284)
		(width 0.16002)
		(layer "In11.Cu")
		(net "M_F_CPU1_SB_DQS_DN<6>")
	)
	(segment
		(start 82.181192 -281.70632)
		(end 82.189574 -281.701494)
		(width 0.09525)
		(layer "In11.Cu")
		(net "M_F_CPU1_SB_DQS_DN<6>")
	)
	(segment
		(start 28.496768 -295.508172)
		(end 30.856936 -295.508172)
		(width 0.16002)
		(layer "In11.Cu")
		(net "M_F_CPU1_SB_DQS_DN<6>")
	)
	(segment
		(start 18.442178 -295.359074)
		(end 18.559018 -295.242234)
		(width 0.16002)
		(layer "In11.Cu")
		(net "M_F_CPU1_SB_DQS_DN<6>")
	)
	(segment
		(start 75.955906 -281.672284)
		(end 75.979528 -281.672284)
		(width 0.09525)
		(layer "In11.Cu")
		(net "M_F_CPU1_SB_DQS_DN<6>")
	)
	(segment
		(start 46.795182 -296.35831)
		(end 48.54067 -296.35831)
		(width 0.16002)
		(layer "In11.Cu")
		(net "M_F_CPU1_SB_DQS_DN<6>")
	)
	(segment
		(start 83.692492 -281.701494)
		(end 83.700874 -281.70632)
		(width 0.09525)
		(layer "In11.Cu")
		(net "M_F_CPU1_SB_DQS_DN<6>")
	)
	(segment
		(start 79.756254 -281.544014)
		(end 79.854806 -281.642566)
		(width 0.09525)
		(layer "In11.Cu")
		(net "M_F_CPU1_SB_DQS_DN<6>")
	)
	(segment
		(start 77.41666 -281.544014)
		(end 79.756254 -281.544014)
		(width 0.09525)
		(layer "In11.Cu")
		(net "M_F_CPU1_SB_DQS_DN<6>")
	)
	(segment
		(start 20.64131 -295.193466)
		(end 20.987766 -295.539922)
		(width 0.16002)
		(layer "In11.Cu")
		(net "M_F_CPU1_SB_DQS_DN<6>")
	)
	(segment
		(start 53.489098 -295.508172)
		(end 54.019196 -296.03827)
		(width 0.16002)
		(layer "In11.Cu")
		(net "M_F_CPU1_SB_DQS_DN<6>")
	)
	(segment
		(start 33.452562 -296.35831)
		(end 33.772602 -296.03827)
		(width 0.16002)
		(layer "In11.Cu")
		(net "M_F_CPU1_SB_DQS_DN<6>")
	)
	(segment
		(start 23.377906 -295.539922)
		(end 24.196294 -296.35831)
		(width 0.16002)
		(layer "In11.Cu")
		(net "M_F_CPU1_SB_DQS_DN<6>")
	)
	(segment
		(start 36.040822 -295.508172)
		(end 38.40099 -295.508172)
		(width 0.16002)
		(layer "In11.Cu")
		(net "M_F_CPU1_SB_DQS_DN<6>")
	)
	(arc
		(start 82.76082 -281.70632)
		(mid 82.945852 -281.752234)
		(end 83.129628 -281.701494)
		(width 0.09525)
		(layer "In11.Cu")
		(net "M_F_CPU1_SB_DQS_DN<6>")
	)
	(arc
		(start 81.24952 -281.701494)
		(mid 81.530952 -281.625739)
		(end 81.812384 -281.701494)
		(width 0.09525)
		(layer "In11.Cu")
		(net "M_F_CPU1_SB_DQS_DN<6>")
	)
	(arc
		(start 84.069682 -281.701494)
		(mid 84.351114 -281.625739)
		(end 84.632546 -281.701494)
		(width 0.09525)
		(layer "In11.Cu")
		(net "M_F_CPU1_SB_DQS_DN<6>")
	)
	(arc
		(start 85.009482 -281.701494)
		(mid 85.290914 -281.625739)
		(end 85.572346 -281.701494)
		(width 0.09525)
		(layer "In11.Cu")
		(net "M_F_CPU1_SB_DQS_DN<6>")
	)
	(arc
		(start 85.572346 -281.701494)
		(mid 85.728944 -281.750783)
		(end 85.891624 -281.728672)
		(width 0.09525)
		(layer "In11.Cu")
		(net "M_F_CPU1_SB_DQS_DN<6>")
	)
	(arc
		(start 79.854806 -281.642566)
		(mid 79.891623 -281.674552)
		(end 79.932276 -281.701494)
		(width 0.09525)
		(layer "In11.Cu")
		(net "M_F_CPU1_SB_DQS_DN<6>")
	)
	(arc
		(start 84.632546 -281.701494)
		(mid 84.821014 -281.752171)
		(end 85.009482 -281.701494)
		(width 0.09525)
		(layer "In11.Cu")
		(net "M_F_CPU1_SB_DQS_DN<6>")
	)
	(arc
		(start 83.129628 -281.701494)
		(mid 83.41106 -281.625739)
		(end 83.692492 -281.701494)
		(width 0.09525)
		(layer "In11.Cu")
		(net "M_F_CPU1_SB_DQS_DN<6>")
	)
	(arc
		(start 80.30972 -281.701494)
		(mid 80.591152 -281.625739)
		(end 80.872584 -281.701494)
		(width 0.09525)
		(layer "In11.Cu")
		(net "M_F_CPU1_SB_DQS_DN<6>")
	)
	(arc
		(start 80.872584 -281.701494)
		(mid 81.061052 -281.752171)
		(end 81.24952 -281.701494)
		(width 0.09525)
		(layer "In11.Cu")
		(net "M_F_CPU1_SB_DQS_DN<6>")
	)
	(arc
		(start 82.189574 -281.701494)
		(mid 82.471006 -281.625739)
		(end 82.752438 -281.701494)
		(width 0.09525)
		(layer "In11.Cu")
		(net "M_F_CPU1_SB_DQS_DN<6>")
	)
	(arc
		(start 81.812384 -281.701494)
		(mid 81.996159 -281.752266)
		(end 82.181192 -281.70632)
		(width 0.09525)
		(layer "In11.Cu")
		(net "M_F_CPU1_SB_DQS_DN<6>")
	)
	(arc
		(start 83.700874 -281.70632)
		(mid 83.885906 -281.752234)
		(end 84.069682 -281.701494)
		(width 0.09525)
		(layer "In11.Cu")
		(net "M_F_CPU1_SB_DQS_DN<6>")
	)
	(arc
		(start 79.932276 -281.701494)
		(mid 80.120998 -281.752298)
		(end 80.30972 -281.701494)
		(width 0.09525)
		(layer "In11.Cu")
		(net "M_F_CPU1_SB_DQS_DN<6>")
	)
	(segment
		(start 86.22792 -276.2504)
		(end 85.761068 -276.516338)
		(width 0.12954)
		(layer "F.Cu")
		(net "M_F_CPU1_SB_DQS_DN<5>")
	)
	(segment
		(start 33.452562 -287.008316)
		(end 33.772602 -286.688276)
		(width 0.16002)
		(layer "In11.Cu")
		(net "M_F_CPU1_SB_DQS_DN<5>")
	)
	(segment
		(start 28.496768 -286.158178)
		(end 30.856936 -286.158178)
		(width 0.16002)
		(layer "In11.Cu")
		(net "M_F_CPU1_SB_DQS_DN<5>")
	)
	(segment
		(start 41.794176 -286.688276)
		(end 42.67835 -285.804102)
		(width 0.16002)
		(layer "In11.Cu")
		(net "M_F_CPU1_SB_DQS_DN<5>")
	)
	(segment
		(start 76.03871 -276.107906)
		(end 76.39304 -276.107906)
		(width 0.09525)
		(layer "In11.Cu")
		(net "M_F_CPU1_SB_DQS_DN<5>")
	)
	(segment
		(start 33.772602 -286.688276)
		(end 34.250122 -286.688276)
		(width 0.16002)
		(layer "In11.Cu")
		(net "M_F_CPU1_SB_DQS_DN<5>")
	)
	(segment
		(start 53.489098 -286.158178)
		(end 54.019196 -286.688276)
		(width 0.16002)
		(layer "In11.Cu")
		(net "M_F_CPU1_SB_DQS_DN<5>")
	)
	(segment
		(start 54.019196 -286.688276)
		(end 56.88203 -286.688276)
		(width 0.16002)
		(layer "In11.Cu")
		(net "M_F_CPU1_SB_DQS_DN<5>")
	)
	(segment
		(start 19.155918 -286.00908)
		(end 19.635978 -286.00908)
		(width 0.16002)
		(layer "In11.Cu")
		(net "M_F_CPU1_SB_DQS_DN<5>")
	)
	(segment
		(start 19.801586 -285.843472)
		(end 20.64131 -285.843472)
		(width 0.16002)
		(layer "In11.Cu")
		(net "M_F_CPU1_SB_DQS_DN<5>")
	)
	(segment
		(start 56.88203 -286.688276)
		(end 57.766204 -285.804102)
		(width 0.16002)
		(layer "In11.Cu")
		(net "M_F_CPU1_SB_DQS_DN<5>")
	)
	(segment
		(start 41.316656 -286.688276)
		(end 41.794176 -286.688276)
		(width 0.16002)
		(layer "In11.Cu")
		(net "M_F_CPU1_SB_DQS_DN<5>")
	)
	(segment
		(start 43.2308 -285.804102)
		(end 43.584876 -286.158178)
		(width 0.16002)
		(layer "In11.Cu")
		(net "M_F_CPU1_SB_DQS_DN<5>")
	)
	(segment
		(start 35.134296 -285.804102)
		(end 35.686746 -285.804102)
		(width 0.16002)
		(layer "In11.Cu")
		(net "M_F_CPU1_SB_DQS_DN<5>")
	)
	(segment
		(start 19.039078 -285.89224)
		(end 19.155918 -286.00908)
		(width 0.16002)
		(layer "In11.Cu")
		(net "M_F_CPU1_SB_DQS_DN<5>")
	)
	(segment
		(start 51.12893 -286.158178)
		(end 53.489098 -286.158178)
		(width 0.16002)
		(layer "In11.Cu")
		(net "M_F_CPU1_SB_DQS_DN<5>")
	)
	(segment
		(start 17.881854 -286.00908)
		(end 18.442178 -286.00908)
		(width 0.16002)
		(layer "In11.Cu")
		(net "M_F_CPU1_SB_DQS_DN<5>")
	)
	(segment
		(start 27.590242 -285.804102)
		(end 28.142692 -285.804102)
		(width 0.16002)
		(layer "In11.Cu")
		(net "M_F_CPU1_SB_DQS_DN<5>")
	)
	(segment
		(start 20.64131 -285.843472)
		(end 20.987766 -286.189928)
		(width 0.16002)
		(layer "In11.Cu")
		(net "M_F_CPU1_SB_DQS_DN<5>")
	)
	(segment
		(start 48.54067 -287.008316)
		(end 48.86071 -286.688276)
		(width 0.16002)
		(layer "In11.Cu")
		(net "M_F_CPU1_SB_DQS_DN<5>")
	)
	(segment
		(start 85.891624 -276.868636)
		(end 85.914992 -276.781768)
		(width 0.09525)
		(layer "In11.Cu")
		(net "M_F_CPU1_SB_DQS_DN<5>")
	)
	(segment
		(start 76.39304 -276.107906)
		(end 76.907898 -276.622764)
		(width 0.09525)
		(layer "In11.Cu")
		(net "M_F_CPU1_SB_DQS_DN<5>")
	)
	(segment
		(start 31.707074 -287.008316)
		(end 33.452562 -287.008316)
		(width 0.16002)
		(layer "In11.Cu")
		(net "M_F_CPU1_SB_DQS_DN<5>")
	)
	(segment
		(start 46.795182 -287.008316)
		(end 48.54067 -287.008316)
		(width 0.16002)
		(layer "In11.Cu")
		(net "M_F_CPU1_SB_DQS_DN<5>")
	)
	(segment
		(start 75.979528 -276.048724)
		(end 76.03871 -276.107906)
		(width 0.09525)
		(layer "In11.Cu")
		(net "M_F_CPU1_SB_DQS_DN<5>")
	)
	(segment
		(start 50.774854 -285.804102)
		(end 51.12893 -286.158178)
		(width 0.16002)
		(layer "In11.Cu")
		(net "M_F_CPU1_SB_DQS_DN<5>")
	)
	(segment
		(start 26.228548 -286.688276)
		(end 26.706068 -286.688276)
		(width 0.16002)
		(layer "In11.Cu")
		(net "M_F_CPU1_SB_DQS_DN<5>")
	)
	(segment
		(start 18.559018 -285.89224)
		(end 19.039078 -285.89224)
		(width 0.16002)
		(layer "In11.Cu")
		(net "M_F_CPU1_SB_DQS_DN<5>")
	)
	(segment
		(start 85.914992 -276.781768)
		(end 85.761068 -276.516338)
		(width 0.09525)
		(layer "In11.Cu")
		(net "M_F_CPU1_SB_DQS_DN<5>")
	)
	(segment
		(start 24.196294 -287.008316)
		(end 25.908508 -287.008316)
		(width 0.16002)
		(layer "In11.Cu")
		(net "M_F_CPU1_SB_DQS_DN<5>")
	)
	(segment
		(start 39.251128 -287.008316)
		(end 40.996616 -287.008316)
		(width 0.16002)
		(layer "In11.Cu")
		(net "M_F_CPU1_SB_DQS_DN<5>")
	)
	(segment
		(start 76.907898 -276.622764)
		(end 79.120746 -276.622764)
		(width 0.09525)
		(layer "In11.Cu")
		(net "M_F_CPU1_SB_DQS_DN<5>")
	)
	(segment
		(start 17.608042 -285.735268)
		(end 17.881854 -286.00908)
		(width 0.16002)
		(layer "In11.Cu")
		(net "M_F_CPU1_SB_DQS_DN<5>")
	)
	(segment
		(start 83.692492 -276.841458)
		(end 83.700874 -276.846284)
		(width 0.09525)
		(layer "In11.Cu")
		(net "M_F_CPU1_SB_DQS_DN<5>")
	)
	(segment
		(start 34.250122 -286.688276)
		(end 35.134296 -285.804102)
		(width 0.16002)
		(layer "In11.Cu")
		(net "M_F_CPU1_SB_DQS_DN<5>")
	)
	(segment
		(start 20.987766 -286.189928)
		(end 23.377906 -286.189928)
		(width 0.16002)
		(layer "In11.Cu")
		(net "M_F_CPU1_SB_DQS_DN<5>")
	)
	(segment
		(start 49.33823 -286.688276)
		(end 50.222404 -285.804102)
		(width 0.16002)
		(layer "In11.Cu")
		(net "M_F_CPU1_SB_DQS_DN<5>")
	)
	(segment
		(start 28.142692 -285.804102)
		(end 28.496768 -286.158178)
		(width 0.16002)
		(layer "In11.Cu")
		(net "M_F_CPU1_SB_DQS_DN<5>")
	)
	(segment
		(start 69.998336 -276.048724)
		(end 75.955906 -276.048724)
		(width 0.16002)
		(layer "In11.Cu")
		(net "M_F_CPU1_SB_DQS_DN<5>")
	)
	(segment
		(start 48.86071 -286.688276)
		(end 49.33823 -286.688276)
		(width 0.16002)
		(layer "In11.Cu")
		(net "M_F_CPU1_SB_DQS_DN<5>")
	)
	(segment
		(start 40.996616 -287.008316)
		(end 41.316656 -286.688276)
		(width 0.16002)
		(layer "In11.Cu")
		(net "M_F_CPU1_SB_DQS_DN<5>")
	)
	(segment
		(start 35.686746 -285.804102)
		(end 36.040822 -286.158178)
		(width 0.16002)
		(layer "In11.Cu")
		(net "M_F_CPU1_SB_DQS_DN<5>")
	)
	(segment
		(start 50.222404 -285.804102)
		(end 50.774854 -285.804102)
		(width 0.16002)
		(layer "In11.Cu")
		(net "M_F_CPU1_SB_DQS_DN<5>")
	)
	(segment
		(start 19.635978 -286.00908)
		(end 19.801586 -285.843472)
		(width 0.16002)
		(layer "In11.Cu")
		(net "M_F_CPU1_SB_DQS_DN<5>")
	)
	(segment
		(start 43.584876 -286.158178)
		(end 45.945044 -286.158178)
		(width 0.16002)
		(layer "In11.Cu")
		(net "M_F_CPU1_SB_DQS_DN<5>")
	)
	(segment
		(start 42.67835 -285.804102)
		(end 43.2308 -285.804102)
		(width 0.16002)
		(layer "In11.Cu")
		(net "M_F_CPU1_SB_DQS_DN<5>")
	)
	(segment
		(start 36.040822 -286.158178)
		(end 38.40099 -286.158178)
		(width 0.16002)
		(layer "In11.Cu")
		(net "M_F_CPU1_SB_DQS_DN<5>")
	)
	(segment
		(start 75.955906 -276.048724)
		(end 75.979528 -276.048724)
		(width 0.09525)
		(layer "In11.Cu")
		(net "M_F_CPU1_SB_DQS_DN<5>")
	)
	(segment
		(start 30.856936 -286.158178)
		(end 31.707074 -287.008316)
		(width 0.16002)
		(layer "In11.Cu")
		(net "M_F_CPU1_SB_DQS_DN<5>")
	)
	(segment
		(start 38.40099 -286.158178)
		(end 39.251128 -287.008316)
		(width 0.16002)
		(layer "In11.Cu")
		(net "M_F_CPU1_SB_DQS_DN<5>")
	)
	(segment
		(start 45.945044 -286.158178)
		(end 46.795182 -287.008316)
		(width 0.16002)
		(layer "In11.Cu")
		(net "M_F_CPU1_SB_DQS_DN<5>")
	)
	(segment
		(start 23.377906 -286.189928)
		(end 24.196294 -287.008316)
		(width 0.16002)
		(layer "In11.Cu")
		(net "M_F_CPU1_SB_DQS_DN<5>")
	)
	(segment
		(start 18.442178 -286.00908)
		(end 18.559018 -285.89224)
		(width 0.16002)
		(layer "In11.Cu")
		(net "M_F_CPU1_SB_DQS_DN<5>")
	)
	(segment
		(start 82.752438 -276.841458)
		(end 82.76082 -276.846284)
		(width 0.09525)
		(layer "In11.Cu")
		(net "M_F_CPU1_SB_DQS_DN<5>")
	)
	(segment
		(start 82.181192 -276.846284)
		(end 82.189574 -276.841458)
		(width 0.09525)
		(layer "In11.Cu")
		(net "M_F_CPU1_SB_DQS_DN<5>")
	)
	(segment
		(start 26.706068 -286.688276)
		(end 27.590242 -285.804102)
		(width 0.16002)
		(layer "In11.Cu")
		(net "M_F_CPU1_SB_DQS_DN<5>")
	)
	(segment
		(start 57.766204 -285.804102)
		(end 60.242958 -285.804102)
		(width 0.16002)
		(layer "In11.Cu")
		(net "M_F_CPU1_SB_DQS_DN<5>")
	)
	(segment
		(start 60.242958 -285.804102)
		(end 69.998336 -276.048724)
		(width 0.16002)
		(layer "In11.Cu")
		(net "M_F_CPU1_SB_DQS_DN<5>")
	)
	(segment
		(start 25.908508 -287.008316)
		(end 26.228548 -286.688276)
		(width 0.16002)
		(layer "In11.Cu")
		(net "M_F_CPU1_SB_DQS_DN<5>")
	)
	(arc
		(start 85.572346 -276.841458)
		(mid 85.728944 -276.890747)
		(end 85.891624 -276.868636)
		(width 0.09525)
		(layer "In11.Cu")
		(net "M_F_CPU1_SB_DQS_DN<5>")
	)
	(arc
		(start 83.129628 -276.841458)
		(mid 83.41106 -276.765703)
		(end 83.692492 -276.841458)
		(width 0.09525)
		(layer "In11.Cu")
		(net "M_F_CPU1_SB_DQS_DN<5>")
	)
	(arc
		(start 79.120746 -276.622764)
		(mid 79.540989 -276.678392)
		(end 79.932276 -276.841458)
		(width 0.09525)
		(layer "In11.Cu")
		(net "M_F_CPU1_SB_DQS_DN<5>")
	)
	(arc
		(start 82.189574 -276.841458)
		(mid 82.471006 -276.765703)
		(end 82.752438 -276.841458)
		(width 0.09525)
		(layer "In11.Cu")
		(net "M_F_CPU1_SB_DQS_DN<5>")
	)
	(arc
		(start 82.76082 -276.846284)
		(mid 82.945852 -276.892198)
		(end 83.129628 -276.841458)
		(width 0.09525)
		(layer "In11.Cu")
		(net "M_F_CPU1_SB_DQS_DN<5>")
	)
	(arc
		(start 84.632546 -276.841458)
		(mid 84.821014 -276.892135)
		(end 85.009482 -276.841458)
		(width 0.09525)
		(layer "In11.Cu")
		(net "M_F_CPU1_SB_DQS_DN<5>")
	)
	(arc
		(start 84.069682 -276.841458)
		(mid 84.351114 -276.765703)
		(end 84.632546 -276.841458)
		(width 0.09525)
		(layer "In11.Cu")
		(net "M_F_CPU1_SB_DQS_DN<5>")
	)
	(arc
		(start 80.872584 -276.841458)
		(mid 81.061052 -276.892135)
		(end 81.24952 -276.841458)
		(width 0.09525)
		(layer "In11.Cu")
		(net "M_F_CPU1_SB_DQS_DN<5>")
	)
	(arc
		(start 79.932276 -276.841458)
		(mid 80.120998 -276.892262)
		(end 80.30972 -276.841458)
		(width 0.09525)
		(layer "In11.Cu")
		(net "M_F_CPU1_SB_DQS_DN<5>")
	)
	(arc
		(start 80.30972 -276.841458)
		(mid 80.591152 -276.765703)
		(end 80.872584 -276.841458)
		(width 0.09525)
		(layer "In11.Cu")
		(net "M_F_CPU1_SB_DQS_DN<5>")
	)
	(arc
		(start 81.24952 -276.841458)
		(mid 81.530952 -276.765703)
		(end 81.812384 -276.841458)
		(width 0.09525)
		(layer "In11.Cu")
		(net "M_F_CPU1_SB_DQS_DN<5>")
	)
	(arc
		(start 85.009482 -276.841458)
		(mid 85.290914 -276.765703)
		(end 85.572346 -276.841458)
		(width 0.09525)
		(layer "In11.Cu")
		(net "M_F_CPU1_SB_DQS_DN<5>")
	)
	(arc
		(start 81.812384 -276.841458)
		(mid 81.996159 -276.89223)
		(end 82.181192 -276.846284)
		(width 0.09525)
		(layer "In11.Cu")
		(net "M_F_CPU1_SB_DQS_DN<5>")
	)
	(arc
		(start 83.700874 -276.846284)
		(mid 83.885906 -276.892198)
		(end 84.069682 -276.841458)
		(width 0.09525)
		(layer "In11.Cu")
		(net "M_F_CPU1_SB_DQS_DN<5>")
	)
	(segment
		(start 86.22792 -271.390364)
		(end 85.761068 -271.656302)
		(width 0.12954)
		(layer "F.Cu")
		(net "M_F_CPU1_SB_DQS_DN<4>")
	)
	(segment
		(start 17.881854 -276.659086)
		(end 18.442178 -276.659086)
		(width 0.16002)
		(layer "In11.Cu")
		(net "M_F_CPU1_SB_DQS_DN<4>")
	)
	(segment
		(start 26.706068 -277.338282)
		(end 27.590242 -276.454108)
		(width 0.16002)
		(layer "In11.Cu")
		(net "M_F_CPU1_SB_DQS_DN<4>")
	)
	(segment
		(start 78.567534 -271.855184)
		(end 79.4639 -271.855184)
		(width 0.09525)
		(layer "In11.Cu")
		(net "M_F_CPU1_SB_DQS_DN<4>")
	)
	(segment
		(start 39.251128 -277.658322)
		(end 40.996616 -277.658322)
		(width 0.16002)
		(layer "In11.Cu")
		(net "M_F_CPU1_SB_DQS_DN<4>")
	)
	(segment
		(start 34.250122 -277.338282)
		(end 35.134296 -276.454108)
		(width 0.16002)
		(layer "In11.Cu")
		(net "M_F_CPU1_SB_DQS_DN<4>")
	)
	(segment
		(start 51.12893 -276.808184)
		(end 53.489098 -276.808184)
		(width 0.16002)
		(layer "In11.Cu")
		(net "M_F_CPU1_SB_DQS_DN<4>")
	)
	(segment
		(start 82.752438 -271.981422)
		(end 82.76082 -271.986248)
		(width 0.09525)
		(layer "In11.Cu")
		(net "M_F_CPU1_SB_DQS_DN<4>")
	)
	(segment
		(start 59.315604 -276.454108)
		(end 65.344548 -270.425164)
		(width 0.16002)
		(layer "In11.Cu")
		(net "M_F_CPU1_SB_DQS_DN<4>")
	)
	(segment
		(start 40.996616 -277.658322)
		(end 41.316656 -277.338282)
		(width 0.16002)
		(layer "In11.Cu")
		(net "M_F_CPU1_SB_DQS_DN<4>")
	)
	(segment
		(start 19.155918 -276.659086)
		(end 19.635978 -276.659086)
		(width 0.16002)
		(layer "In11.Cu")
		(net "M_F_CPU1_SB_DQS_DN<4>")
	)
	(segment
		(start 85.891624 -272.0086)
		(end 85.914992 -271.921732)
		(width 0.09525)
		(layer "In11.Cu")
		(net "M_F_CPU1_SB_DQS_DN<4>")
	)
	(segment
		(start 41.794176 -277.338282)
		(end 42.67835 -276.454108)
		(width 0.16002)
		(layer "In11.Cu")
		(net "M_F_CPU1_SB_DQS_DN<4>")
	)
	(segment
		(start 50.774854 -276.454108)
		(end 51.12893 -276.808184)
		(width 0.16002)
		(layer "In11.Cu")
		(net "M_F_CPU1_SB_DQS_DN<4>")
	)
	(segment
		(start 19.635978 -276.659086)
		(end 19.801586 -276.493478)
		(width 0.16002)
		(layer "In11.Cu")
		(net "M_F_CPU1_SB_DQS_DN<4>")
	)
	(segment
		(start 75.979528 -270.425164)
		(end 76.03871 -270.484346)
		(width 0.09525)
		(layer "In11.Cu")
		(net "M_F_CPU1_SB_DQS_DN<4>")
	)
	(segment
		(start 42.67835 -276.454108)
		(end 43.2308 -276.454108)
		(width 0.16002)
		(layer "In11.Cu")
		(net "M_F_CPU1_SB_DQS_DN<4>")
	)
	(segment
		(start 43.2308 -276.454108)
		(end 43.584876 -276.808184)
		(width 0.16002)
		(layer "In11.Cu")
		(net "M_F_CPU1_SB_DQS_DN<4>")
	)
	(segment
		(start 20.987766 -276.839934)
		(end 23.377906 -276.839934)
		(width 0.16002)
		(layer "In11.Cu")
		(net "M_F_CPU1_SB_DQS_DN<4>")
	)
	(segment
		(start 76.552298 -270.679164)
		(end 77.391514 -270.679164)
		(width 0.09525)
		(layer "In11.Cu")
		(net "M_F_CPU1_SB_DQS_DN<4>")
	)
	(segment
		(start 48.86071 -277.338282)
		(end 49.33823 -277.338282)
		(width 0.16002)
		(layer "In11.Cu")
		(net "M_F_CPU1_SB_DQS_DN<4>")
	)
	(segment
		(start 82.181192 -271.986248)
		(end 82.189574 -271.981422)
		(width 0.09525)
		(layer "In11.Cu")
		(net "M_F_CPU1_SB_DQS_DN<4>")
	)
	(segment
		(start 50.222404 -276.454108)
		(end 50.774854 -276.454108)
		(width 0.16002)
		(layer "In11.Cu")
		(net "M_F_CPU1_SB_DQS_DN<4>")
	)
	(segment
		(start 27.590242 -276.454108)
		(end 28.142692 -276.454108)
		(width 0.16002)
		(layer "In11.Cu")
		(net "M_F_CPU1_SB_DQS_DN<4>")
	)
	(segment
		(start 23.377906 -276.839934)
		(end 24.196294 -277.658322)
		(width 0.16002)
		(layer "In11.Cu")
		(net "M_F_CPU1_SB_DQS_DN<4>")
	)
	(segment
		(start 53.489098 -276.808184)
		(end 54.019196 -277.338282)
		(width 0.16002)
		(layer "In11.Cu")
		(net "M_F_CPU1_SB_DQS_DN<4>")
	)
	(segment
		(start 26.228548 -277.338282)
		(end 26.706068 -277.338282)
		(width 0.16002)
		(layer "In11.Cu")
		(net "M_F_CPU1_SB_DQS_DN<4>")
	)
	(segment
		(start 18.559018 -276.542246)
		(end 19.039078 -276.542246)
		(width 0.16002)
		(layer "In11.Cu")
		(net "M_F_CPU1_SB_DQS_DN<4>")
	)
	(segment
		(start 33.772602 -277.338282)
		(end 34.250122 -277.338282)
		(width 0.16002)
		(layer "In11.Cu")
		(net "M_F_CPU1_SB_DQS_DN<4>")
	)
	(segment
		(start 24.196294 -277.658322)
		(end 25.908508 -277.658322)
		(width 0.16002)
		(layer "In11.Cu")
		(net "M_F_CPU1_SB_DQS_DN<4>")
	)
	(segment
		(start 31.707074 -277.658322)
		(end 33.452562 -277.658322)
		(width 0.16002)
		(layer "In11.Cu")
		(net "M_F_CPU1_SB_DQS_DN<4>")
	)
	(segment
		(start 43.584876 -276.808184)
		(end 45.945044 -276.808184)
		(width 0.16002)
		(layer "In11.Cu")
		(net "M_F_CPU1_SB_DQS_DN<4>")
	)
	(segment
		(start 19.801586 -276.493478)
		(end 20.64131 -276.493478)
		(width 0.16002)
		(layer "In11.Cu")
		(net "M_F_CPU1_SB_DQS_DN<4>")
	)
	(segment
		(start 76.35748 -270.484346)
		(end 76.552298 -270.679164)
		(width 0.09525)
		(layer "In11.Cu")
		(net "M_F_CPU1_SB_DQS_DN<4>")
	)
	(segment
		(start 77.391514 -270.679164)
		(end 78.567534 -271.855184)
		(width 0.09525)
		(layer "In11.Cu")
		(net "M_F_CPU1_SB_DQS_DN<4>")
	)
	(segment
		(start 19.039078 -276.542246)
		(end 19.155918 -276.659086)
		(width 0.16002)
		(layer "In11.Cu")
		(net "M_F_CPU1_SB_DQS_DN<4>")
	)
	(segment
		(start 65.344548 -270.425164)
		(end 75.955906 -270.425164)
		(width 0.16002)
		(layer "In11.Cu")
		(net "M_F_CPU1_SB_DQS_DN<4>")
	)
	(segment
		(start 35.134296 -276.454108)
		(end 35.686746 -276.454108)
		(width 0.16002)
		(layer "In11.Cu")
		(net "M_F_CPU1_SB_DQS_DN<4>")
	)
	(segment
		(start 76.03871 -270.484346)
		(end 76.35748 -270.484346)
		(width 0.09525)
		(layer "In11.Cu")
		(net "M_F_CPU1_SB_DQS_DN<4>")
	)
	(segment
		(start 56.88203 -277.338282)
		(end 57.766204 -276.454108)
		(width 0.16002)
		(layer "In11.Cu")
		(net "M_F_CPU1_SB_DQS_DN<4>")
	)
	(segment
		(start 85.914992 -271.921732)
		(end 85.761068 -271.656302)
		(width 0.09525)
		(layer "In11.Cu")
		(net "M_F_CPU1_SB_DQS_DN<4>")
	)
	(segment
		(start 46.795182 -277.658322)
		(end 48.54067 -277.658322)
		(width 0.16002)
		(layer "In11.Cu")
		(net "M_F_CPU1_SB_DQS_DN<4>")
	)
	(segment
		(start 35.686746 -276.454108)
		(end 36.040822 -276.808184)
		(width 0.16002)
		(layer "In11.Cu")
		(net "M_F_CPU1_SB_DQS_DN<4>")
	)
	(segment
		(start 75.955906 -270.425164)
		(end 75.979528 -270.425164)
		(width 0.09525)
		(layer "In11.Cu")
		(net "M_F_CPU1_SB_DQS_DN<4>")
	)
	(segment
		(start 28.496768 -276.808184)
		(end 30.856936 -276.808184)
		(width 0.16002)
		(layer "In11.Cu")
		(net "M_F_CPU1_SB_DQS_DN<4>")
	)
	(segment
		(start 45.945044 -276.808184)
		(end 46.795182 -277.658322)
		(width 0.16002)
		(layer "In11.Cu")
		(net "M_F_CPU1_SB_DQS_DN<4>")
	)
	(segment
		(start 20.64131 -276.493478)
		(end 20.987766 -276.839934)
		(width 0.16002)
		(layer "In11.Cu")
		(net "M_F_CPU1_SB_DQS_DN<4>")
	)
	(segment
		(start 83.692492 -271.981422)
		(end 83.700874 -271.986248)
		(width 0.09525)
		(layer "In11.Cu")
		(net "M_F_CPU1_SB_DQS_DN<4>")
	)
	(segment
		(start 49.33823 -277.338282)
		(end 50.222404 -276.454108)
		(width 0.16002)
		(layer "In11.Cu")
		(net "M_F_CPU1_SB_DQS_DN<4>")
	)
	(segment
		(start 57.766204 -276.454108)
		(end 59.315604 -276.454108)
		(width 0.16002)
		(layer "In11.Cu")
		(net "M_F_CPU1_SB_DQS_DN<4>")
	)
	(segment
		(start 41.316656 -277.338282)
		(end 41.794176 -277.338282)
		(width 0.16002)
		(layer "In11.Cu")
		(net "M_F_CPU1_SB_DQS_DN<4>")
	)
	(segment
		(start 33.452562 -277.658322)
		(end 33.772602 -277.338282)
		(width 0.16002)
		(layer "In11.Cu")
		(net "M_F_CPU1_SB_DQS_DN<4>")
	)
	(segment
		(start 48.54067 -277.658322)
		(end 48.86071 -277.338282)
		(width 0.16002)
		(layer "In11.Cu")
		(net "M_F_CPU1_SB_DQS_DN<4>")
	)
	(segment
		(start 38.40099 -276.808184)
		(end 39.251128 -277.658322)
		(width 0.16002)
		(layer "In11.Cu")
		(net "M_F_CPU1_SB_DQS_DN<4>")
	)
	(segment
		(start 28.142692 -276.454108)
		(end 28.496768 -276.808184)
		(width 0.16002)
		(layer "In11.Cu")
		(net "M_F_CPU1_SB_DQS_DN<4>")
	)
	(segment
		(start 25.908508 -277.658322)
		(end 26.228548 -277.338282)
		(width 0.16002)
		(layer "In11.Cu")
		(net "M_F_CPU1_SB_DQS_DN<4>")
	)
	(segment
		(start 18.442178 -276.659086)
		(end 18.559018 -276.542246)
		(width 0.16002)
		(layer "In11.Cu")
		(net "M_F_CPU1_SB_DQS_DN<4>")
	)
	(segment
		(start 17.608042 -276.385274)
		(end 17.881854 -276.659086)
		(width 0.16002)
		(layer "In11.Cu")
		(net "M_F_CPU1_SB_DQS_DN<4>")
	)
	(segment
		(start 30.856936 -276.808184)
		(end 31.707074 -277.658322)
		(width 0.16002)
		(layer "In11.Cu")
		(net "M_F_CPU1_SB_DQS_DN<4>")
	)
	(segment
		(start 54.019196 -277.338282)
		(end 56.88203 -277.338282)
		(width 0.16002)
		(layer "In11.Cu")
		(net "M_F_CPU1_SB_DQS_DN<4>")
	)
	(segment
		(start 36.040822 -276.808184)
		(end 38.40099 -276.808184)
		(width 0.16002)
		(layer "In11.Cu")
		(net "M_F_CPU1_SB_DQS_DN<4>")
	)
	(arc
		(start 79.4639 -271.855184)
		(mid 79.706448 -271.887292)
		(end 79.932276 -271.981422)
		(width 0.09525)
		(layer "In11.Cu")
		(net "M_F_CPU1_SB_DQS_DN<4>")
	)
	(arc
		(start 84.069682 -271.981422)
		(mid 84.351114 -271.905667)
		(end 84.632546 -271.981422)
		(width 0.09525)
		(layer "In11.Cu")
		(net "M_F_CPU1_SB_DQS_DN<4>")
	)
	(arc
		(start 81.24952 -271.981422)
		(mid 81.530952 -271.905667)
		(end 81.812384 -271.981422)
		(width 0.09525)
		(layer "In11.Cu")
		(net "M_F_CPU1_SB_DQS_DN<4>")
	)
	(arc
		(start 83.700874 -271.986248)
		(mid 83.885906 -272.032162)
		(end 84.069682 -271.981422)
		(width 0.09525)
		(layer "In11.Cu")
		(net "M_F_CPU1_SB_DQS_DN<4>")
	)
	(arc
		(start 81.812384 -271.981422)
		(mid 81.996159 -272.032194)
		(end 82.181192 -271.986248)
		(width 0.09525)
		(layer "In11.Cu")
		(net "M_F_CPU1_SB_DQS_DN<4>")
	)
	(arc
		(start 80.872584 -271.981422)
		(mid 81.061052 -272.032099)
		(end 81.24952 -271.981422)
		(width 0.09525)
		(layer "In11.Cu")
		(net "M_F_CPU1_SB_DQS_DN<4>")
	)
	(arc
		(start 80.30972 -271.981422)
		(mid 80.591152 -271.905667)
		(end 80.872584 -271.981422)
		(width 0.09525)
		(layer "In11.Cu")
		(net "M_F_CPU1_SB_DQS_DN<4>")
	)
	(arc
		(start 85.572346 -271.981422)
		(mid 85.728944 -272.030711)
		(end 85.891624 -272.0086)
		(width 0.09525)
		(layer "In11.Cu")
		(net "M_F_CPU1_SB_DQS_DN<4>")
	)
	(arc
		(start 84.632546 -271.981422)
		(mid 84.821014 -272.032099)
		(end 85.009482 -271.981422)
		(width 0.09525)
		(layer "In11.Cu")
		(net "M_F_CPU1_SB_DQS_DN<4>")
	)
	(arc
		(start 85.009482 -271.981422)
		(mid 85.290914 -271.905667)
		(end 85.572346 -271.981422)
		(width 0.09525)
		(layer "In11.Cu")
		(net "M_F_CPU1_SB_DQS_DN<4>")
	)
	(arc
		(start 82.76082 -271.986248)
		(mid 82.945852 -272.032162)
		(end 83.129628 -271.981422)
		(width 0.09525)
		(layer "In11.Cu")
		(net "M_F_CPU1_SB_DQS_DN<4>")
	)
	(arc
		(start 83.129628 -271.981422)
		(mid 83.41106 -271.905667)
		(end 83.692492 -271.981422)
		(width 0.09525)
		(layer "In11.Cu")
		(net "M_F_CPU1_SB_DQS_DN<4>")
	)
	(arc
		(start 82.189574 -271.981422)
		(mid 82.471006 -271.905667)
		(end 82.752438 -271.981422)
		(width 0.09525)
		(layer "In11.Cu")
		(net "M_F_CPU1_SB_DQS_DN<4>")
	)
	(arc
		(start 79.932276 -271.981422)
		(mid 80.120998 -272.032226)
		(end 80.30972 -271.981422)
		(width 0.09525)
		(layer "In11.Cu")
		(net "M_F_CPU1_SB_DQS_DN<4>")
	)
	(segment
		(start 85.287866 -290.830254)
		(end 84.821014 -291.096192)
		(width 0.12954)
		(layer "F.Cu")
		(net "M_F_CPU1_SB_DQS_DN<3>")
	)
	(segment
		(start 65.173352 -306.75072)
		(end 65.173352 -307.227224)
		(width 0.16002)
		(layer "In11.Cu")
		(net "M_F_CPU1_SB_DQS_DN<3>")
	)
	(segment
		(start 74.360024 -298.040552)
		(end 73.88352 -298.040552)
		(width 0.16002)
		(layer "In11.Cu")
		(net "M_F_CPU1_SB_DQS_DN<3>")
	)
	(segment
		(start 34.418524 -313.707018)
		(end 33.768792 -313.707018)
		(width 0.16002)
		(layer "In11.Cu")
		(net "M_F_CPU1_SB_DQS_DN<3>")
	)
	(segment
		(start 65.105026 -306.456334)
		(end 65.105026 -306.682394)
		(width 0.16002)
		(layer "In11.Cu")
		(net "M_F_CPU1_SB_DQS_DN<3>")
	)
	(segment
		(start 74.783442 -297.14063)
		(end 74.783442 -297.617134)
		(width 0.16002)
		(layer "In11.Cu")
		(net "M_F_CPU1_SB_DQS_DN<3>")
	)
	(segment
		(start 65.173352 -307.227224)
		(end 64.749934 -307.650642)
		(width 0.16002)
		(layer "In11.Cu")
		(net "M_F_CPU1_SB_DQS_DN<3>")
	)
	(segment
		(start 65.351914 -306.209446)
		(end 65.105026 -306.456334)
		(width 0.16002)
		(layer "In11.Cu")
		(net "M_F_CPU1_SB_DQS_DN<3>")
	)
	(segment
		(start 71.969376 -299.591984)
		(end 71.969376 -299.818044)
		(width 0.16002)
		(layer "In11.Cu")
		(net "M_F_CPU1_SB_DQS_DN<3>")
	)
	(segment
		(start 76.674726 -295.642792)
		(end 76.178918 -296.1386)
		(width 0.09525)
		(layer "In11.Cu")
		(net "M_F_CPU1_SB_DQS_DN<3>")
	)
	(segment
		(start 64.749934 -307.650642)
		(end 64.27343 -307.650642)
		(width 0.16002)
		(layer "In11.Cu")
		(net "M_F_CPU1_SB_DQS_DN<3>")
	)
	(segment
		(start 27.69997 -312.881518)
		(end 26.87447 -313.707018)
		(width 0.16002)
		(layer "In11.Cu")
		(net "M_F_CPU1_SB_DQS_DN<3>")
	)
	(segment
		(start 70.241414 -302.159162)
		(end 69.76491 -302.159162)
		(width 0.16002)
		(layer "In11.Cu")
		(net "M_F_CPU1_SB_DQS_DN<3>")
	)
	(segment
		(start 50.776886 -312.881518)
		(end 50.332132 -312.881518)
		(width 0.16002)
		(layer "In11.Cu")
		(net "M_F_CPU1_SB_DQS_DN<3>")
	)
	(segment
		(start 71.13778 -300.786292)
		(end 71.069454 -300.717966)
		(width 0.16002)
		(layer "In11.Cu")
		(net "M_F_CPU1_SB_DQS_DN<3>")
	)
	(segment
		(start 66.546222 -305.854354)
		(end 66.122804 -306.277772)
		(width 0.16002)
		(layer "In11.Cu")
		(net "M_F_CPU1_SB_DQS_DN<3>")
	)
	(segment
		(start 73.410572 -298.5135)
		(end 73.410572 -298.990004)
		(width 0.16002)
		(layer "In11.Cu")
		(net "M_F_CPU1_SB_DQS_DN<3>")
	)
	(segment
		(start 35.244024 -312.881518)
		(end 34.418524 -313.707018)
		(width 0.16002)
		(layer "In11.Cu")
		(net "M_F_CPU1_SB_DQS_DN<3>")
	)
	(segment
		(start 67.919092 -304.00498)
		(end 67.919092 -304.481484)
		(width 0.16002)
		(layer "In11.Cu")
		(net "M_F_CPU1_SB_DQS_DN<3>")
	)
	(segment
		(start 72.442324 -299.345096)
		(end 72.216264 -299.345096)
		(width 0.16002)
		(layer "In11.Cu")
		(net "M_F_CPU1_SB_DQS_DN<3>")
	)
	(segment
		(start 66.546222 -305.37785)
		(end 66.546222 -305.854354)
		(width 0.16002)
		(layer "In11.Cu")
		(net "M_F_CPU1_SB_DQS_DN<3>")
	)
	(segment
		(start 59.691778 -312.881518)
		(end 57.875932 -312.881518)
		(width 0.16002)
		(layer "In11.Cu")
		(net "M_F_CPU1_SB_DQS_DN<3>")
	)
	(segment
		(start 75.732894 -296.667682)
		(end 75.25639 -296.667682)
		(width 0.16002)
		(layer "In11.Cu")
		(net "M_F_CPU1_SB_DQS_DN<3>")
	)
	(segment
		(start 28.513786 -312.512456)
		(end 28.144724 -312.881518)
		(width 0.16002)
		(layer "In11.Cu")
		(net "M_F_CPU1_SB_DQS_DN<3>")
	)
	(segment
		(start 67.01917 -304.904902)
		(end 66.950844 -304.836576)
		(width 0.16002)
		(layer "In11.Cu")
		(net "M_F_CPU1_SB_DQS_DN<3>")
	)
	(segment
		(start 66.724784 -304.836576)
		(end 66.477896 -305.083464)
		(width 0.16002)
		(layer "In11.Cu")
		(net "M_F_CPU1_SB_DQS_DN<3>")
	)
	(segment
		(start 69.470524 -302.090836)
		(end 69.223636 -302.337724)
		(width 0.16002)
		(layer "In11.Cu")
		(net "M_F_CPU1_SB_DQS_DN<3>")
	)
	(segment
		(start 63.800482 -308.12359)
		(end 63.800482 -308.772814)
		(width 0.16002)
		(layer "In11.Cu")
		(net "M_F_CPU1_SB_DQS_DN<3>")
	)
	(segment
		(start 65.577974 -306.209446)
		(end 65.351914 -306.209446)
		(width 0.16002)
		(layer "In11.Cu")
		(net "M_F_CPU1_SB_DQS_DN<3>")
	)
	(segment
		(start 74.715116 -296.846244)
		(end 74.715116 -297.072304)
		(width 0.16002)
		(layer "In11.Cu")
		(net "M_F_CPU1_SB_DQS_DN<3>")
	)
	(segment
		(start 75.188064 -296.599356)
		(end 74.962004 -296.599356)
		(width 0.16002)
		(layer "In11.Cu")
		(net "M_F_CPU1_SB_DQS_DN<3>")
	)
	(segment
		(start 69.76491 -302.159162)
		(end 69.696584 -302.090836)
		(width 0.16002)
		(layer "In11.Cu")
		(net "M_F_CPU1_SB_DQS_DN<3>")
	)
	(segment
		(start 65.105026 -306.682394)
		(end 65.173352 -306.75072)
		(width 0.16002)
		(layer "In11.Cu")
		(net "M_F_CPU1_SB_DQS_DN<3>")
	)
	(segment
		(start 73.342246 -298.445174)
		(end 73.410572 -298.5135)
		(width 0.16002)
		(layer "In11.Cu")
		(net "M_F_CPU1_SB_DQS_DN<3>")
	)
	(segment
		(start 67.495674 -304.904902)
		(end 67.01917 -304.904902)
		(width 0.16002)
		(layer "In11.Cu")
		(net "M_F_CPU1_SB_DQS_DN<3>")
	)
	(segment
		(start 54.303676 -313.707018)
		(end 53.751734 -313.155076)
		(width 0.16002)
		(layer "In11.Cu")
		(net "M_F_CPU1_SB_DQS_DN<3>")
	)
	(segment
		(start 53.394864 -313.155076)
		(end 52.752244 -312.512456)
		(width 0.16002)
		(layer "In11.Cu")
		(net "M_F_CPU1_SB_DQS_DN<3>")
	)
	(segment
		(start 52.752244 -312.512456)
		(end 51.145948 -312.512456)
		(width 0.16002)
		(layer "In11.Cu")
		(net "M_F_CPU1_SB_DQS_DN<3>")
	)
	(segment
		(start 72.037702 -299.88637)
		(end 72.037702 -300.362874)
		(width 0.16002)
		(layer "In11.Cu")
		(net "M_F_CPU1_SB_DQS_DN<3>")
	)
	(segment
		(start 33.424114 -313.36234)
		(end 30.969966 -313.36234)
		(width 0.16002)
		(layer "In11.Cu")
		(net "M_F_CPU1_SB_DQS_DN<3>")
	)
	(segment
		(start 79.048864 -290.99129)
		(end 78.131924 -291.90823)
		(width 0.09525)
		(layer "In11.Cu")
		(net "M_F_CPU1_SB_DQS_DN<3>")
	)
	(segment
		(start 43.601894 -312.512456)
		(end 43.232832 -312.881518)
		(width 0.16002)
		(layer "In11.Cu")
		(net "M_F_CPU1_SB_DQS_DN<3>")
	)
	(segment
		(start 76.162154 -296.238422)
		(end 75.732894 -296.667682)
		(width 0.16002)
		(layer "In11.Cu")
		(net "M_F_CPU1_SB_DQS_DN<3>")
	)
	(segment
		(start 42.788078 -312.881518)
		(end 41.962578 -313.707018)
		(width 0.16002)
		(layer "In11.Cu")
		(net "M_F_CPU1_SB_DQS_DN<3>")
	)
	(segment
		(start 70.843394 -300.717966)
		(end 70.596506 -300.964854)
		(width 0.16002)
		(layer "In11.Cu")
		(net "M_F_CPU1_SB_DQS_DN<3>")
	)
	(segment
		(start 66.950844 -304.836576)
		(end 66.724784 -304.836576)
		(width 0.16002)
		(layer "In11.Cu")
		(net "M_F_CPU1_SB_DQS_DN<3>")
	)
	(segment
		(start 66.477896 -305.309524)
		(end 66.546222 -305.37785)
		(width 0.16002)
		(layer "In11.Cu")
		(net "M_F_CPU1_SB_DQS_DN<3>")
	)
	(segment
		(start 38.51402 -313.36234)
		(end 37.664136 -312.512456)
		(width 0.16002)
		(layer "In11.Cu")
		(net "M_F_CPU1_SB_DQS_DN<3>")
	)
	(segment
		(start 67.919092 -304.481484)
		(end 67.495674 -304.904902)
		(width 0.16002)
		(layer "In11.Cu")
		(net "M_F_CPU1_SB_DQS_DN<3>")
	)
	(segment
		(start 48.512222 -313.36234)
		(end 46.058074 -313.36234)
		(width 0.16002)
		(layer "In11.Cu")
		(net "M_F_CPU1_SB_DQS_DN<3>")
	)
	(segment
		(start 57.050432 -313.707018)
		(end 54.303676 -313.707018)
		(width 0.16002)
		(layer "In11.Cu")
		(net "M_F_CPU1_SB_DQS_DN<3>")
	)
	(segment
		(start 70.596506 -301.190914)
		(end 70.664832 -301.25924)
		(width 0.16002)
		(layer "In11.Cu")
		(net "M_F_CPU1_SB_DQS_DN<3>")
	)
	(segment
		(start 83.700874 -290.766246)
		(end 83.692492 -290.771072)
		(width 0.09525)
		(layer "In11.Cu")
		(net "M_F_CPU1_SB_DQS_DN<3>")
	)
	(segment
		(start 68.868544 -303.532032)
		(end 68.39204 -303.532032)
		(width 0.16002)
		(layer "In11.Cu")
		(net "M_F_CPU1_SB_DQS_DN<3>")
	)
	(segment
		(start 65.6463 -306.277772)
		(end 65.577974 -306.209446)
		(width 0.16002)
		(layer "In11.Cu")
		(net "M_F_CPU1_SB_DQS_DN<3>")
	)
	(segment
		(start 66.477896 -305.083464)
		(end 66.477896 -305.309524)
		(width 0.16002)
		(layer "In11.Cu")
		(net "M_F_CPU1_SB_DQS_DN<3>")
	)
	(segment
		(start 37.664136 -312.512456)
		(end 36.05784 -312.512456)
		(width 0.16002)
		(layer "In11.Cu")
		(net "M_F_CPU1_SB_DQS_DN<3>")
	)
	(segment
		(start 24.131524 -313.511438)
		(end 21.981922 -313.511438)
		(width 0.16002)
		(layer "In11.Cu")
		(net "M_F_CPU1_SB_DQS_DN<3>")
	)
	(segment
		(start 69.291962 -302.63211)
		(end 69.291962 -303.108614)
		(width 0.16002)
		(layer "In11.Cu")
		(net "M_F_CPU1_SB_DQS_DN<3>")
	)
	(segment
		(start 84.821014 -291.096192)
		(end 84.66709 -290.830762)
		(width 0.09525)
		(layer "In11.Cu")
		(net "M_F_CPU1_SB_DQS_DN<3>")
	)
	(segment
		(start 63.979044 -307.582316)
		(end 63.732156 -307.829204)
		(width 0.16002)
		(layer "In11.Cu")
		(net "M_F_CPU1_SB_DQS_DN<3>")
	)
	(segment
		(start 71.614284 -300.786292)
		(end 71.13778 -300.786292)
		(width 0.16002)
		(layer "In11.Cu")
		(net "M_F_CPU1_SB_DQS_DN<3>")
	)
	(segment
		(start 84.66709 -290.830762)
		(end 84.566252 -290.804092)
		(width 0.09525)
		(layer "In11.Cu")
		(net "M_F_CPU1_SB_DQS_DN<3>")
	)
	(segment
		(start 26.87447 -313.707018)
		(end 26.224738 -313.707018)
		(width 0.16002)
		(layer "In11.Cu")
		(net "M_F_CPU1_SB_DQS_DN<3>")
	)
	(segment
		(start 41.962578 -313.707018)
		(end 41.312846 -313.707018)
		(width 0.16002)
		(layer "In11.Cu")
		(net "M_F_CPU1_SB_DQS_DN<3>")
	)
	(segment
		(start 72.987154 -299.413422)
		(end 72.51065 -299.413422)
		(width 0.16002)
		(layer "In11.Cu")
		(net "M_F_CPU1_SB_DQS_DN<3>")
	)
	(segment
		(start 25.88006 -313.36234)
		(end 24.280622 -313.36234)
		(width 0.16002)
		(layer "In11.Cu")
		(net "M_F_CPU1_SB_DQS_DN<3>")
	)
	(segment
		(start 69.223636 -302.563784)
		(end 69.291962 -302.63211)
		(width 0.16002)
		(layer "In11.Cu")
		(net "M_F_CPU1_SB_DQS_DN<3>")
	)
	(segment
		(start 76.178918 -296.1386)
		(end 76.178918 -296.221658)
		(width 0.09525)
		(layer "In11.Cu")
		(net "M_F_CPU1_SB_DQS_DN<3>")
	)
	(segment
		(start 82.189574 -290.771072)
		(end 82.181192 -290.766246)
		(width 0.09525)
		(layer "In11.Cu")
		(net "M_F_CPU1_SB_DQS_DN<3>")
	)
	(segment
		(start 63.800482 -308.772814)
		(end 59.691778 -312.881518)
		(width 0.16002)
		(layer "In11.Cu")
		(net "M_F_CPU1_SB_DQS_DN<3>")
	)
	(segment
		(start 76.178918 -296.221658)
		(end 76.162154 -296.238422)
		(width 0.09525)
		(layer "In11.Cu")
		(net "M_F_CPU1_SB_DQS_DN<3>")
	)
	(segment
		(start 68.323714 -303.463706)
		(end 68.097654 -303.463706)
		(width 0.16002)
		(layer "In11.Cu")
		(net "M_F_CPU1_SB_DQS_DN<3>")
	)
	(segment
		(start 48.8569 -313.707018)
		(end 48.512222 -313.36234)
		(width 0.16002)
		(layer "In11.Cu")
		(net "M_F_CPU1_SB_DQS_DN<3>")
	)
	(segment
		(start 71.069454 -300.717966)
		(end 70.843394 -300.717966)
		(width 0.16002)
		(layer "In11.Cu")
		(net "M_F_CPU1_SB_DQS_DN<3>")
	)
	(segment
		(start 67.850766 -303.936654)
		(end 67.919092 -304.00498)
		(width 0.16002)
		(layer "In11.Cu")
		(net "M_F_CPU1_SB_DQS_DN<3>")
	)
	(segment
		(start 36.05784 -312.512456)
		(end 35.688778 -312.881518)
		(width 0.16002)
		(layer "In11.Cu")
		(net "M_F_CPU1_SB_DQS_DN<3>")
	)
	(segment
		(start 30.120082 -312.512456)
		(end 28.513786 -312.512456)
		(width 0.16002)
		(layer "In11.Cu")
		(net "M_F_CPU1_SB_DQS_DN<3>")
	)
	(segment
		(start 64.27343 -307.650642)
		(end 64.205104 -307.582316)
		(width 0.16002)
		(layer "In11.Cu")
		(net "M_F_CPU1_SB_DQS_DN<3>")
	)
	(segment
		(start 40.968168 -313.36234)
		(end 38.51402 -313.36234)
		(width 0.16002)
		(layer "In11.Cu")
		(net "M_F_CPU1_SB_DQS_DN<3>")
	)
	(segment
		(start 24.280622 -313.36234)
		(end 24.131524 -313.511438)
		(width 0.16002)
		(layer "In11.Cu")
		(net "M_F_CPU1_SB_DQS_DN<3>")
	)
	(segment
		(start 46.058074 -313.36234)
		(end 45.20819 -312.512456)
		(width 0.16002)
		(layer "In11.Cu")
		(net "M_F_CPU1_SB_DQS_DN<3>")
	)
	(segment
		(start 75.25639 -296.667682)
		(end 75.188064 -296.599356)
		(width 0.16002)
		(layer "In11.Cu")
		(net "M_F_CPU1_SB_DQS_DN<3>")
	)
	(segment
		(start 74.715116 -297.072304)
		(end 74.783442 -297.14063)
		(width 0.16002)
		(layer "In11.Cu")
		(net "M_F_CPU1_SB_DQS_DN<3>")
	)
	(segment
		(start 72.51065 -299.413422)
		(end 72.442324 -299.345096)
		(width 0.16002)
		(layer "In11.Cu")
		(net "M_F_CPU1_SB_DQS_DN<3>")
	)
	(segment
		(start 50.332132 -312.881518)
		(end 49.506632 -313.707018)
		(width 0.16002)
		(layer "In11.Cu")
		(net "M_F_CPU1_SB_DQS_DN<3>")
	)
	(segment
		(start 21.981922 -313.511438)
		(end 21.70811 -313.78525)
		(width 0.16002)
		(layer "In11.Cu")
		(net "M_F_CPU1_SB_DQS_DN<3>")
	)
	(segment
		(start 70.664832 -301.735744)
		(end 70.241414 -302.159162)
		(width 0.16002)
		(layer "In11.Cu")
		(net "M_F_CPU1_SB_DQS_DN<3>")
	)
	(segment
		(start 68.39204 -303.532032)
		(end 68.323714 -303.463706)
		(width 0.16002)
		(layer "In11.Cu")
		(net "M_F_CPU1_SB_DQS_DN<3>")
	)
	(segment
		(start 69.696584 -302.090836)
		(end 69.470524 -302.090836)
		(width 0.16002)
		(layer "In11.Cu")
		(net "M_F_CPU1_SB_DQS_DN<3>")
	)
	(segment
		(start 67.850766 -303.710594)
		(end 67.850766 -303.936654)
		(width 0.16002)
		(layer "In11.Cu")
		(net "M_F_CPU1_SB_DQS_DN<3>")
	)
	(segment
		(start 78.08468 -292.579044)
		(end 76.674726 -293.988998)
		(width 0.09525)
		(layer "In11.Cu")
		(net "M_F_CPU1_SB_DQS_DN<3>")
	)
	(segment
		(start 63.732156 -308.055264)
		(end 63.800482 -308.12359)
		(width 0.16002)
		(layer "In11.Cu")
		(net "M_F_CPU1_SB_DQS_DN<3>")
	)
	(segment
		(start 64.205104 -307.582316)
		(end 63.979044 -307.582316)
		(width 0.16002)
		(layer "In11.Cu")
		(net "M_F_CPU1_SB_DQS_DN<3>")
	)
	(segment
		(start 28.144724 -312.881518)
		(end 27.69997 -312.881518)
		(width 0.16002)
		(layer "In11.Cu")
		(net "M_F_CPU1_SB_DQS_DN<3>")
	)
	(segment
		(start 71.969376 -299.818044)
		(end 72.037702 -299.88637)
		(width 0.16002)
		(layer "In11.Cu")
		(net "M_F_CPU1_SB_DQS_DN<3>")
	)
	(segment
		(start 73.88352 -298.040552)
		(end 73.815194 -297.972226)
		(width 0.16002)
		(layer "In11.Cu")
		(net "M_F_CPU1_SB_DQS_DN<3>")
	)
	(segment
		(start 74.783442 -297.617134)
		(end 74.360024 -298.040552)
		(width 0.16002)
		(layer "In11.Cu")
		(net "M_F_CPU1_SB_DQS_DN<3>")
	)
	(segment
		(start 49.506632 -313.707018)
		(end 48.8569 -313.707018)
		(width 0.16002)
		(layer "In11.Cu")
		(net "M_F_CPU1_SB_DQS_DN<3>")
	)
	(segment
		(start 33.768792 -313.707018)
		(end 33.424114 -313.36234)
		(width 0.16002)
		(layer "In11.Cu")
		(net "M_F_CPU1_SB_DQS_DN<3>")
	)
	(segment
		(start 30.969966 -313.36234)
		(end 30.120082 -312.512456)
		(width 0.16002)
		(layer "In11.Cu")
		(net "M_F_CPU1_SB_DQS_DN<3>")
	)
	(segment
		(start 72.037702 -300.362874)
		(end 71.614284 -300.786292)
		(width 0.16002)
		(layer "In11.Cu")
		(net "M_F_CPU1_SB_DQS_DN<3>")
	)
	(segment
		(start 76.674726 -293.988998)
		(end 76.674726 -295.642792)
		(width 0.09525)
		(layer "In11.Cu")
		(net "M_F_CPU1_SB_DQS_DN<3>")
	)
	(segment
		(start 68.097654 -303.463706)
		(end 67.850766 -303.710594)
		(width 0.16002)
		(layer "In11.Cu")
		(net "M_F_CPU1_SB_DQS_DN<3>")
	)
	(segment
		(start 70.664832 -301.25924)
		(end 70.664832 -301.735744)
		(width 0.16002)
		(layer "In11.Cu")
		(net "M_F_CPU1_SB_DQS_DN<3>")
	)
	(segment
		(start 70.596506 -300.964854)
		(end 70.596506 -301.190914)
		(width 0.16002)
		(layer "In11.Cu")
		(net "M_F_CPU1_SB_DQS_DN<3>")
	)
	(segment
		(start 69.223636 -302.337724)
		(end 69.223636 -302.563784)
		(width 0.16002)
		(layer "In11.Cu")
		(net "M_F_CPU1_SB_DQS_DN<3>")
	)
	(segment
		(start 74.962004 -296.599356)
		(end 74.715116 -296.846244)
		(width 0.16002)
		(layer "In11.Cu")
		(net "M_F_CPU1_SB_DQS_DN<3>")
	)
	(segment
		(start 73.410572 -298.990004)
		(end 72.987154 -299.413422)
		(width 0.16002)
		(layer "In11.Cu")
		(net "M_F_CPU1_SB_DQS_DN<3>")
	)
	(segment
		(start 35.688778 -312.881518)
		(end 35.244024 -312.881518)
		(width 0.16002)
		(layer "In11.Cu")
		(net "M_F_CPU1_SB_DQS_DN<3>")
	)
	(segment
		(start 82.76082 -290.766246)
		(end 82.752438 -290.771072)
		(width 0.09525)
		(layer "In11.Cu")
		(net "M_F_CPU1_SB_DQS_DN<3>")
	)
	(segment
		(start 26.224738 -313.707018)
		(end 25.88006 -313.36234)
		(width 0.16002)
		(layer "In11.Cu")
		(net "M_F_CPU1_SB_DQS_DN<3>")
	)
	(segment
		(start 41.312846 -313.707018)
		(end 40.968168 -313.36234)
		(width 0.16002)
		(layer "In11.Cu")
		(net "M_F_CPU1_SB_DQS_DN<3>")
	)
	(segment
		(start 45.20819 -312.512456)
		(end 43.601894 -312.512456)
		(width 0.16002)
		(layer "In11.Cu")
		(net "M_F_CPU1_SB_DQS_DN<3>")
	)
	(segment
		(start 69.291962 -303.108614)
		(end 68.868544 -303.532032)
		(width 0.16002)
		(layer "In11.Cu")
		(net "M_F_CPU1_SB_DQS_DN<3>")
	)
	(segment
		(start 78.08468 -292.022276)
		(end 78.08468 -292.579044)
		(width 0.09525)
		(layer "In11.Cu")
		(net "M_F_CPU1_SB_DQS_DN<3>")
	)
	(segment
		(start 53.751734 -313.155076)
		(end 53.394864 -313.155076)
		(width 0.16002)
		(layer "In11.Cu")
		(net "M_F_CPU1_SB_DQS_DN<3>")
	)
	(segment
		(start 72.216264 -299.345096)
		(end 71.969376 -299.591984)
		(width 0.16002)
		(layer "In11.Cu")
		(net "M_F_CPU1_SB_DQS_DN<3>")
	)
	(segment
		(start 73.342246 -298.219114)
		(end 73.342246 -298.445174)
		(width 0.16002)
		(layer "In11.Cu")
		(net "M_F_CPU1_SB_DQS_DN<3>")
	)
	(segment
		(start 63.732156 -307.829204)
		(end 63.732156 -308.055264)
		(width 0.16002)
		(layer "In11.Cu")
		(net "M_F_CPU1_SB_DQS_DN<3>")
	)
	(segment
		(start 57.875932 -312.881518)
		(end 57.050432 -313.707018)
		(width 0.16002)
		(layer "In11.Cu")
		(net "M_F_CPU1_SB_DQS_DN<3>")
	)
	(segment
		(start 73.815194 -297.972226)
		(end 73.589134 -297.972226)
		(width 0.16002)
		(layer "In11.Cu")
		(net "M_F_CPU1_SB_DQS_DN<3>")
	)
	(segment
		(start 66.122804 -306.277772)
		(end 65.6463 -306.277772)
		(width 0.16002)
		(layer "In11.Cu")
		(net "M_F_CPU1_SB_DQS_DN<3>")
	)
	(segment
		(start 43.232832 -312.881518)
		(end 42.788078 -312.881518)
		(width 0.16002)
		(layer "In11.Cu")
		(net "M_F_CPU1_SB_DQS_DN<3>")
	)
	(segment
		(start 73.589134 -297.972226)
		(end 73.342246 -298.219114)
		(width 0.16002)
		(layer "In11.Cu")
		(net "M_F_CPU1_SB_DQS_DN<3>")
	)
	(segment
		(start 51.145948 -312.512456)
		(end 50.776886 -312.881518)
		(width 0.16002)
		(layer "In11.Cu")
		(net "M_F_CPU1_SB_DQS_DN<3>")
	)
	(arc
		(start 79.519526 -290.832032)
		(mid 79.265578 -290.856623)
		(end 79.048864 -290.99129)
		(width 0.09525)
		(layer "In11.Cu")
		(net "M_F_CPU1_SB_DQS_DN<3>")
	)
	(arc
		(start 79.952088 -290.759642)
		(mid 79.741257 -290.828404)
		(end 79.519526 -290.832032)
		(width 0.09525)
		(layer "In11.Cu")
		(net "M_F_CPU1_SB_DQS_DN<3>")
	)
	(arc
		(start 82.752438 -290.771072)
		(mid 82.471006 -290.846827)
		(end 82.189574 -290.771072)
		(width 0.09525)
		(layer "In11.Cu")
		(net "M_F_CPU1_SB_DQS_DN<3>")
	)
	(arc
		(start 79.952342 -290.760404)
		(mid 79.952215 -290.760023)
		(end 79.952088 -290.759642)
		(width 0.09525)
		(layer "In11.Cu")
		(net "M_F_CPU1_SB_DQS_DN<3>")
	)
	(arc
		(start 80.30972 -290.771072)
		(mid 80.13239 -290.72056)
		(end 79.952342 -290.760404)
		(width 0.09525)
		(layer "In11.Cu")
		(net "M_F_CPU1_SB_DQS_DN<3>")
	)
	(arc
		(start 84.566252 -290.804092)
		(mid 84.55613 -290.808127)
		(end 84.545932 -290.811966)
		(width 0.09525)
		(layer "In11.Cu")
		(net "M_F_CPU1_SB_DQS_DN<3>")
	)
	(arc
		(start 81.24952 -290.771072)
		(mid 81.061052 -290.720395)
		(end 80.872584 -290.771072)
		(width 0.09525)
		(layer "In11.Cu")
		(net "M_F_CPU1_SB_DQS_DN<3>")
	)
	(arc
		(start 82.181192 -290.766246)
		(mid 81.99616 -290.720332)
		(end 81.812384 -290.771072)
		(width 0.09525)
		(layer "In11.Cu")
		(net "M_F_CPU1_SB_DQS_DN<3>")
	)
	(arc
		(start 80.872584 -290.771072)
		(mid 80.591152 -290.846827)
		(end 80.30972 -290.771072)
		(width 0.09525)
		(layer "In11.Cu")
		(net "M_F_CPU1_SB_DQS_DN<3>")
	)
	(arc
		(start 84.069682 -290.771072)
		(mid 83.885907 -290.7203)
		(end 83.700874 -290.766246)
		(width 0.09525)
		(layer "In11.Cu")
		(net "M_F_CPU1_SB_DQS_DN<3>")
	)
	(arc
		(start 84.545932 -290.811966)
		(mid 84.30322 -290.844849)
		(end 84.069682 -290.771072)
		(width 0.09525)
		(layer "In11.Cu")
		(net "M_F_CPU1_SB_DQS_DN<3>")
	)
	(arc
		(start 81.812384 -290.771072)
		(mid 81.530952 -290.846827)
		(end 81.24952 -290.771072)
		(width 0.09525)
		(layer "In11.Cu")
		(net "M_F_CPU1_SB_DQS_DN<3>")
	)
	(arc
		(start 83.692492 -290.771072)
		(mid 83.41106 -290.846827)
		(end 83.129628 -290.771072)
		(width 0.09525)
		(layer "In11.Cu")
		(net "M_F_CPU1_SB_DQS_DN<3>")
	)
	(arc
		(start 78.131924 -291.90823)
		(mid 78.096962 -291.960555)
		(end 78.08468 -292.022276)
		(width 0.09525)
		(layer "In11.Cu")
		(net "M_F_CPU1_SB_DQS_DN<3>")
	)
	(arc
		(start 83.129628 -290.771072)
		(mid 82.945853 -290.7203)
		(end 82.76082 -290.766246)
		(width 0.09525)
		(layer "In11.Cu")
		(net "M_F_CPU1_SB_DQS_DN<3>")
	)
	(segment
		(start 85.287866 -285.970472)
		(end 84.821014 -286.23641)
		(width 0.12954)
		(layer "F.Cu")
		(net "M_F_CPU1_SB_DQS_DN<2>")
	)
	(segment
		(start 72.490584 -289.557968)
		(end 72.243696 -289.804856)
		(width 0.16002)
		(layer "In11.Cu")
		(net "M_F_CPU1_SB_DQS_DN<2>")
	)
	(segment
		(start 62.633606 -299.64126)
		(end 62.684914 -299.692822)
		(width 0.16002)
		(layer "In11.Cu")
		(net "M_F_CPU1_SB_DQS_DN<2>")
	)
	(segment
		(start 71.395082 -290.9824)
		(end 71.34352 -290.930838)
		(width 0.16002)
		(layer "In11.Cu")
		(net "M_F_CPU1_SB_DQS_DN<2>")
	)
	(segment
		(start 64.006476 -298.042076)
		(end 64.006476 -298.26839)
		(width 0.16002)
		(layer "In11.Cu")
		(net "M_F_CPU1_SB_DQS_DN<2>")
	)
	(segment
		(start 26.87447 -304.357024)
		(end 26.224738 -304.357024)
		(width 0.16002)
		(layer "In11.Cu")
		(net "M_F_CPU1_SB_DQS_DN<2>")
	)
	(segment
		(start 45.20819 -303.162462)
		(end 43.601894 -303.162462)
		(width 0.16002)
		(layer "In11.Cu")
		(net "M_F_CPU1_SB_DQS_DN<2>")
	)
	(segment
		(start 61.312044 -301.065692)
		(end 61.312044 -301.541942)
		(width 0.16002)
		(layer "In11.Cu")
		(net "M_F_CPU1_SB_DQS_DN<2>")
	)
	(segment
		(start 76.622656 -286.76473)
		(end 76.086462 -286.76473)
		(width 0.16002)
		(layer "In11.Cu")
		(net "M_F_CPU1_SB_DQS_DN<2>")
	)
	(segment
		(start 76.086462 -286.76473)
		(end 73.293224 -289.557968)
		(width 0.16002)
		(layer "In11.Cu")
		(net "M_F_CPU1_SB_DQS_DN<2>")
	)
	(segment
		(start 68.125086 -294.14978)
		(end 68.176394 -294.201342)
		(width 0.16002)
		(layer "In11.Cu")
		(net "M_F_CPU1_SB_DQS_DN<2>")
	)
	(segment
		(start 70.922134 -291.931852)
		(end 70.498716 -292.35527)
		(width 0.16002)
		(layer "In11.Cu")
		(net "M_F_CPU1_SB_DQS_DN<2>")
	)
	(segment
		(start 65.379346 -296.89552)
		(end 65.430654 -296.947082)
		(width 0.16002)
		(layer "In11.Cu")
		(net "M_F_CPU1_SB_DQS_DN<2>")
	)
	(segment
		(start 43.601894 -303.162462)
		(end 43.232832 -303.531524)
		(width 0.16002)
		(layer "In11.Cu")
		(net "M_F_CPU1_SB_DQS_DN<2>")
	)
	(segment
		(start 70.022212 -292.35527)
		(end 69.97065 -292.303708)
		(width 0.16002)
		(layer "In11.Cu")
		(net "M_F_CPU1_SB_DQS_DN<2>")
	)
	(segment
		(start 21.981922 -304.161444)
		(end 21.70811 -304.435256)
		(width 0.16002)
		(layer "In11.Cu")
		(net "M_F_CPU1_SB_DQS_DN<2>")
	)
	(segment
		(start 65.85204 -296.422318)
		(end 65.626234 -296.422318)
		(width 0.16002)
		(layer "In11.Cu")
		(net "M_F_CPU1_SB_DQS_DN<2>")
	)
	(segment
		(start 65.903602 -296.47388)
		(end 65.85204 -296.422318)
		(width 0.16002)
		(layer "In11.Cu")
		(net "M_F_CPU1_SB_DQS_DN<2>")
	)
	(segment
		(start 62.684914 -299.692822)
		(end 62.684914 -300.169072)
		(width 0.16002)
		(layer "In11.Cu")
		(net "M_F_CPU1_SB_DQS_DN<2>")
	)
	(segment
		(start 65.007236 -297.84675)
		(end 64.530732 -297.84675)
		(width 0.16002)
		(layer "In11.Cu")
		(net "M_F_CPU1_SB_DQS_DN<2>")
	)
	(segment
		(start 64.057784 -298.319952)
		(end 64.057784 -298.796202)
		(width 0.16002)
		(layer "In11.Cu")
		(net "M_F_CPU1_SB_DQS_DN<2>")
	)
	(segment
		(start 62.684914 -300.169072)
		(end 62.261496 -300.59249)
		(width 0.16002)
		(layer "In11.Cu")
		(net "M_F_CPU1_SB_DQS_DN<2>")
	)
	(segment
		(start 33.768792 -304.357024)
		(end 33.424114 -304.012346)
		(width 0.16002)
		(layer "In11.Cu")
		(net "M_F_CPU1_SB_DQS_DN<2>")
	)
	(segment
		(start 28.513786 -303.162462)
		(end 28.144724 -303.531524)
		(width 0.16002)
		(layer "In11.Cu")
		(net "M_F_CPU1_SB_DQS_DN<2>")
	)
	(segment
		(start 73.293224 -289.557968)
		(end 72.490584 -289.557968)
		(width 0.16002)
		(layer "In11.Cu")
		(net "M_F_CPU1_SB_DQS_DN<2>")
	)
	(segment
		(start 62.261496 -300.59249)
		(end 61.784992 -300.59249)
		(width 0.16002)
		(layer "In11.Cu")
		(net "M_F_CPU1_SB_DQS_DN<2>")
	)
	(segment
		(start 66.752216 -295.52265)
		(end 66.803524 -295.574212)
		(width 0.16002)
		(layer "In11.Cu")
		(net "M_F_CPU1_SB_DQS_DN<2>")
	)
	(segment
		(start 57.875932 -303.531524)
		(end 57.050432 -304.357024)
		(width 0.16002)
		(layer "In11.Cu")
		(net "M_F_CPU1_SB_DQS_DN<2>")
	)
	(segment
		(start 25.88006 -304.012346)
		(end 24.280622 -304.012346)
		(width 0.16002)
		(layer "In11.Cu")
		(net "M_F_CPU1_SB_DQS_DN<2>")
	)
	(segment
		(start 76.705206 -286.705802)
		(end 76.646278 -286.76473)
		(width 0.09525)
		(layer "In11.Cu")
		(net "M_F_CPU1_SB_DQS_DN<2>")
	)
	(segment
		(start 68.59778 -293.676578)
		(end 68.371974 -293.676578)
		(width 0.16002)
		(layer "In11.Cu")
		(net "M_F_CPU1_SB_DQS_DN<2>")
	)
	(segment
		(start 68.176394 -294.677592)
		(end 67.752976 -295.10101)
		(width 0.16002)
		(layer "In11.Cu")
		(net "M_F_CPU1_SB_DQS_DN<2>")
	)
	(segment
		(start 35.688778 -303.531524)
		(end 35.244024 -303.531524)
		(width 0.16002)
		(layer "In11.Cu")
		(net "M_F_CPU1_SB_DQS_DN<2>")
	)
	(segment
		(start 59.939174 -302.914812)
		(end 59.397392 -303.456848)
		(width 0.16002)
		(layer "In11.Cu")
		(net "M_F_CPU1_SB_DQS_DN<2>")
	)
	(segment
		(start 35.244024 -303.531524)
		(end 34.418524 -304.357024)
		(width 0.16002)
		(layer "In11.Cu")
		(net "M_F_CPU1_SB_DQS_DN<2>")
	)
	(segment
		(start 72.295004 -290.082732)
		(end 72.295004 -290.558982)
		(width 0.16002)
		(layer "In11.Cu")
		(net "M_F_CPU1_SB_DQS_DN<2>")
	)
	(segment
		(start 67.276472 -295.10101)
		(end 67.22491 -295.049448)
		(width 0.16002)
		(layer "In11.Cu")
		(net "M_F_CPU1_SB_DQS_DN<2>")
	)
	(segment
		(start 27.69997 -303.531524)
		(end 26.87447 -304.357024)
		(width 0.16002)
		(layer "In11.Cu")
		(net "M_F_CPU1_SB_DQS_DN<2>")
	)
	(segment
		(start 69.497956 -292.550596)
		(end 69.497956 -292.77691)
		(width 0.16002)
		(layer "In11.Cu")
		(net "M_F_CPU1_SB_DQS_DN<2>")
	)
	(segment
		(start 71.34352 -290.930838)
		(end 71.117714 -290.930838)
		(width 0.16002)
		(layer "In11.Cu")
		(net "M_F_CPU1_SB_DQS_DN<2>")
	)
	(segment
		(start 30.969966 -304.012346)
		(end 30.120082 -303.162462)
		(width 0.16002)
		(layer "In11.Cu")
		(net "M_F_CPU1_SB_DQS_DN<2>")
	)
	(segment
		(start 65.379346 -296.669206)
		(end 65.379346 -296.89552)
		(width 0.16002)
		(layer "In11.Cu")
		(net "M_F_CPU1_SB_DQS_DN<2>")
	)
	(segment
		(start 61.507624 -300.540928)
		(end 61.260736 -300.787816)
		(width 0.16002)
		(layer "In11.Cu")
		(net "M_F_CPU1_SB_DQS_DN<2>")
	)
	(segment
		(start 42.788078 -303.531524)
		(end 41.962578 -304.357024)
		(width 0.16002)
		(layer "In11.Cu")
		(net "M_F_CPU1_SB_DQS_DN<2>")
	)
	(segment
		(start 66.999104 -295.049448)
		(end 66.752216 -295.296336)
		(width 0.16002)
		(layer "In11.Cu")
		(net "M_F_CPU1_SB_DQS_DN<2>")
	)
	(segment
		(start 63.157862 -299.21962)
		(end 63.1063 -299.168058)
		(width 0.16002)
		(layer "In11.Cu")
		(net "M_F_CPU1_SB_DQS_DN<2>")
	)
	(segment
		(start 46.058074 -304.012346)
		(end 45.20819 -303.162462)
		(width 0.16002)
		(layer "In11.Cu")
		(net "M_F_CPU1_SB_DQS_DN<2>")
	)
	(segment
		(start 70.870826 -291.177726)
		(end 70.870826 -291.40404)
		(width 0.16002)
		(layer "In11.Cu")
		(net "M_F_CPU1_SB_DQS_DN<2>")
	)
	(segment
		(start 64.057784 -298.796202)
		(end 63.634366 -299.21962)
		(width 0.16002)
		(layer "In11.Cu")
		(net "M_F_CPU1_SB_DQS_DN<2>")
	)
	(segment
		(start 59.939174 -302.438562)
		(end 59.939174 -302.914812)
		(width 0.16002)
		(layer "In11.Cu")
		(net "M_F_CPU1_SB_DQS_DN<2>")
	)
	(segment
		(start 83.700874 -285.906464)
		(end 83.692492 -285.91129)
		(width 0.09525)
		(layer "In11.Cu")
		(net "M_F_CPU1_SB_DQS_DN<2>")
	)
	(segment
		(start 26.224738 -304.357024)
		(end 25.88006 -304.012346)
		(width 0.16002)
		(layer "In11.Cu")
		(net "M_F_CPU1_SB_DQS_DN<2>")
	)
	(segment
		(start 43.232832 -303.531524)
		(end 42.788078 -303.531524)
		(width 0.16002)
		(layer "In11.Cu")
		(net "M_F_CPU1_SB_DQS_DN<2>")
	)
	(segment
		(start 53.751734 -303.805082)
		(end 53.394864 -303.805082)
		(width 0.16002)
		(layer "In11.Cu")
		(net "M_F_CPU1_SB_DQS_DN<2>")
	)
	(segment
		(start 24.131524 -304.161444)
		(end 21.981922 -304.161444)
		(width 0.16002)
		(layer "In11.Cu")
		(net "M_F_CPU1_SB_DQS_DN<2>")
	)
	(segment
		(start 40.968168 -304.012346)
		(end 38.51402 -304.012346)
		(width 0.16002)
		(layer "In11.Cu")
		(net "M_F_CPU1_SB_DQS_DN<2>")
	)
	(segment
		(start 57.050432 -304.357024)
		(end 54.303676 -304.357024)
		(width 0.16002)
		(layer "In11.Cu")
		(net "M_F_CPU1_SB_DQS_DN<2>")
	)
	(segment
		(start 30.120082 -303.162462)
		(end 28.513786 -303.162462)
		(width 0.16002)
		(layer "In11.Cu")
		(net "M_F_CPU1_SB_DQS_DN<2>")
	)
	(segment
		(start 68.176394 -294.201342)
		(end 68.176394 -294.677592)
		(width 0.16002)
		(layer "In11.Cu")
		(net "M_F_CPU1_SB_DQS_DN<2>")
	)
	(segment
		(start 68.649342 -293.72814)
		(end 68.59778 -293.676578)
		(width 0.16002)
		(layer "In11.Cu")
		(net "M_F_CPU1_SB_DQS_DN<2>")
	)
	(segment
		(start 63.1063 -299.168058)
		(end 62.880494 -299.168058)
		(width 0.16002)
		(layer "In11.Cu")
		(net "M_F_CPU1_SB_DQS_DN<2>")
	)
	(segment
		(start 60.888626 -301.96536)
		(end 60.412376 -301.96536)
		(width 0.16002)
		(layer "In11.Cu")
		(net "M_F_CPU1_SB_DQS_DN<2>")
	)
	(segment
		(start 66.803524 -296.050462)
		(end 66.380106 -296.47388)
		(width 0.16002)
		(layer "In11.Cu")
		(net "M_F_CPU1_SB_DQS_DN<2>")
	)
	(segment
		(start 62.880494 -299.168058)
		(end 62.633606 -299.414946)
		(width 0.16002)
		(layer "In11.Cu")
		(net "M_F_CPU1_SB_DQS_DN<2>")
	)
	(segment
		(start 72.243696 -290.03117)
		(end 72.295004 -290.082732)
		(width 0.16002)
		(layer "In11.Cu")
		(net "M_F_CPU1_SB_DQS_DN<2>")
	)
	(segment
		(start 48.8569 -304.357024)
		(end 48.512222 -304.012346)
		(width 0.16002)
		(layer "In11.Cu")
		(net "M_F_CPU1_SB_DQS_DN<2>")
	)
	(segment
		(start 61.784992 -300.59249)
		(end 61.73343 -300.540928)
		(width 0.16002)
		(layer "In11.Cu")
		(net "M_F_CPU1_SB_DQS_DN<2>")
	)
	(segment
		(start 69.549264 -293.304722)
		(end 69.125846 -293.72814)
		(width 0.16002)
		(layer "In11.Cu")
		(net "M_F_CPU1_SB_DQS_DN<2>")
	)
	(segment
		(start 82.76082 -285.906464)
		(end 82.752438 -285.91129)
		(width 0.09525)
		(layer "In11.Cu")
		(net "M_F_CPU1_SB_DQS_DN<2>")
	)
	(segment
		(start 62.633606 -299.414946)
		(end 62.633606 -299.64126)
		(width 0.16002)
		(layer "In11.Cu")
		(net "M_F_CPU1_SB_DQS_DN<2>")
	)
	(segment
		(start 65.626234 -296.422318)
		(end 65.379346 -296.669206)
		(width 0.16002)
		(layer "In11.Cu")
		(net "M_F_CPU1_SB_DQS_DN<2>")
	)
	(segment
		(start 52.752244 -303.162462)
		(end 51.145948 -303.162462)
		(width 0.16002)
		(layer "In11.Cu")
		(net "M_F_CPU1_SB_DQS_DN<2>")
	)
	(segment
		(start 37.664136 -303.162462)
		(end 36.05784 -303.162462)
		(width 0.16002)
		(layer "In11.Cu")
		(net "M_F_CPU1_SB_DQS_DN<2>")
	)
	(segment
		(start 61.260736 -301.01413)
		(end 61.312044 -301.065692)
		(width 0.16002)
		(layer "In11.Cu")
		(net "M_F_CPU1_SB_DQS_DN<2>")
	)
	(segment
		(start 36.05784 -303.162462)
		(end 35.688778 -303.531524)
		(width 0.16002)
		(layer "In11.Cu")
		(net "M_F_CPU1_SB_DQS_DN<2>")
	)
	(segment
		(start 66.803524 -295.574212)
		(end 66.803524 -296.050462)
		(width 0.16002)
		(layer "In11.Cu")
		(net "M_F_CPU1_SB_DQS_DN<2>")
	)
	(segment
		(start 84.66709 -285.97098)
		(end 84.566252 -285.94431)
		(width 0.09525)
		(layer "In11.Cu")
		(net "M_F_CPU1_SB_DQS_DN<2>")
	)
	(segment
		(start 64.006476 -298.26839)
		(end 64.057784 -298.319952)
		(width 0.16002)
		(layer "In11.Cu")
		(net "M_F_CPU1_SB_DQS_DN<2>")
	)
	(segment
		(start 51.145948 -303.162462)
		(end 50.776886 -303.531524)
		(width 0.16002)
		(layer "In11.Cu")
		(net "M_F_CPU1_SB_DQS_DN<2>")
	)
	(segment
		(start 84.821014 -286.23641)
		(end 84.66709 -285.97098)
		(width 0.09525)
		(layer "In11.Cu")
		(net "M_F_CPU1_SB_DQS_DN<2>")
	)
	(segment
		(start 61.73343 -300.540928)
		(end 61.507624 -300.540928)
		(width 0.16002)
		(layer "In11.Cu")
		(net "M_F_CPU1_SB_DQS_DN<2>")
	)
	(segment
		(start 79.932784 -285.91129)
		(end 79.91475 -285.921704)
		(width 0.09525)
		(layer "In11.Cu")
		(net "M_F_CPU1_SB_DQS_DN<2>")
	)
	(segment
		(start 69.549264 -292.828472)
		(end 69.549264 -293.304722)
		(width 0.16002)
		(layer "In11.Cu")
		(net "M_F_CPU1_SB_DQS_DN<2>")
	)
	(segment
		(start 63.634366 -299.21962)
		(end 63.157862 -299.21962)
		(width 0.16002)
		(layer "In11.Cu")
		(net "M_F_CPU1_SB_DQS_DN<2>")
	)
	(segment
		(start 54.303676 -304.357024)
		(end 53.751734 -303.805082)
		(width 0.16002)
		(layer "In11.Cu")
		(net "M_F_CPU1_SB_DQS_DN<2>")
	)
	(segment
		(start 72.295004 -290.558982)
		(end 71.871586 -290.9824)
		(width 0.16002)
		(layer "In11.Cu")
		(net "M_F_CPU1_SB_DQS_DN<2>")
	)
	(segment
		(start 70.922134 -291.455602)
		(end 70.922134 -291.931852)
		(width 0.16002)
		(layer "In11.Cu")
		(net "M_F_CPU1_SB_DQS_DN<2>")
	)
	(segment
		(start 33.424114 -304.012346)
		(end 30.969966 -304.012346)
		(width 0.16002)
		(layer "In11.Cu")
		(net "M_F_CPU1_SB_DQS_DN<2>")
	)
	(segment
		(start 82.189574 -285.91129)
		(end 82.181192 -285.906464)
		(width 0.09525)
		(layer "In11.Cu")
		(net "M_F_CPU1_SB_DQS_DN<2>")
	)
	(segment
		(start 77.281278 -286.705802)
		(end 76.705206 -286.705802)
		(width 0.09525)
		(layer "In11.Cu")
		(net "M_F_CPU1_SB_DQS_DN<2>")
	)
	(segment
		(start 38.51402 -304.012346)
		(end 37.664136 -303.162462)
		(width 0.16002)
		(layer "In11.Cu")
		(net "M_F_CPU1_SB_DQS_DN<2>")
	)
	(segment
		(start 65.430654 -297.423332)
		(end 65.007236 -297.84675)
		(width 0.16002)
		(layer "In11.Cu")
		(net "M_F_CPU1_SB_DQS_DN<2>")
	)
	(segment
		(start 59.397392 -303.456848)
		(end 59.217306 -303.531524)
		(width 0.16002)
		(layer "In11.Cu")
		(net "M_F_CPU1_SB_DQS_DN<2>")
	)
	(segment
		(start 67.752976 -295.10101)
		(end 67.276472 -295.10101)
		(width 0.16002)
		(layer "In11.Cu")
		(net "M_F_CPU1_SB_DQS_DN<2>")
	)
	(segment
		(start 64.253364 -297.795188)
		(end 64.006476 -298.042076)
		(width 0.16002)
		(layer "In11.Cu")
		(net "M_F_CPU1_SB_DQS_DN<2>")
	)
	(segment
		(start 71.117714 -290.930838)
		(end 70.870826 -291.177726)
		(width 0.16002)
		(layer "In11.Cu")
		(net "M_F_CPU1_SB_DQS_DN<2>")
	)
	(segment
		(start 66.752216 -295.296336)
		(end 66.752216 -295.52265)
		(width 0.16002)
		(layer "In11.Cu")
		(net "M_F_CPU1_SB_DQS_DN<2>")
	)
	(segment
		(start 66.380106 -296.47388)
		(end 65.903602 -296.47388)
		(width 0.16002)
		(layer "In11.Cu")
		(net "M_F_CPU1_SB_DQS_DN<2>")
	)
	(segment
		(start 69.97065 -292.303708)
		(end 69.744844 -292.303708)
		(width 0.16002)
		(layer "In11.Cu")
		(net "M_F_CPU1_SB_DQS_DN<2>")
	)
	(segment
		(start 34.418524 -304.357024)
		(end 33.768792 -304.357024)
		(width 0.16002)
		(layer "In11.Cu")
		(net "M_F_CPU1_SB_DQS_DN<2>")
	)
	(segment
		(start 61.312044 -301.541942)
		(end 60.888626 -301.96536)
		(width 0.16002)
		(layer "In11.Cu")
		(net "M_F_CPU1_SB_DQS_DN<2>")
	)
	(segment
		(start 60.412376 -301.96536)
		(end 59.939174 -302.438562)
		(width 0.16002)
		(layer "In11.Cu")
		(net "M_F_CPU1_SB_DQS_DN<2>")
	)
	(segment
		(start 70.870826 -291.40404)
		(end 70.922134 -291.455602)
		(width 0.16002)
		(layer "In11.Cu")
		(net "M_F_CPU1_SB_DQS_DN<2>")
	)
	(segment
		(start 64.530732 -297.84675)
		(end 64.47917 -297.795188)
		(width 0.16002)
		(layer "In11.Cu")
		(net "M_F_CPU1_SB_DQS_DN<2>")
	)
	(segment
		(start 24.280622 -304.012346)
		(end 24.131524 -304.161444)
		(width 0.16002)
		(layer "In11.Cu")
		(net "M_F_CPU1_SB_DQS_DN<2>")
	)
	(segment
		(start 71.871586 -290.9824)
		(end 71.395082 -290.9824)
		(width 0.16002)
		(layer "In11.Cu")
		(net "M_F_CPU1_SB_DQS_DN<2>")
	)
	(segment
		(start 59.217306 -303.531524)
		(end 57.875932 -303.531524)
		(width 0.16002)
		(layer "In11.Cu")
		(net "M_F_CPU1_SB_DQS_DN<2>")
	)
	(segment
		(start 78.711044 -285.98749)
		(end 77.99959 -285.98749)
		(width 0.09525)
		(layer "In11.Cu")
		(net "M_F_CPU1_SB_DQS_DN<2>")
	)
	(segment
		(start 41.962578 -304.357024)
		(end 41.312846 -304.357024)
		(width 0.16002)
		(layer "In11.Cu")
		(net "M_F_CPU1_SB_DQS_DN<2>")
	)
	(segment
		(start 77.99959 -285.98749)
		(end 77.281278 -286.705802)
		(width 0.09525)
		(layer "In11.Cu")
		(net "M_F_CPU1_SB_DQS_DN<2>")
	)
	(segment
		(start 69.744844 -292.303708)
		(end 69.497956 -292.550596)
		(width 0.16002)
		(layer "In11.Cu")
		(net "M_F_CPU1_SB_DQS_DN<2>")
	)
	(segment
		(start 68.371974 -293.676578)
		(end 68.125086 -293.923466)
		(width 0.16002)
		(layer "In11.Cu")
		(net "M_F_CPU1_SB_DQS_DN<2>")
	)
	(segment
		(start 53.394864 -303.805082)
		(end 52.752244 -303.162462)
		(width 0.16002)
		(layer "In11.Cu")
		(net "M_F_CPU1_SB_DQS_DN<2>")
	)
	(segment
		(start 65.430654 -296.947082)
		(end 65.430654 -297.423332)
		(width 0.16002)
		(layer "In11.Cu")
		(net "M_F_CPU1_SB_DQS_DN<2>")
	)
	(segment
		(start 69.125846 -293.72814)
		(end 68.649342 -293.72814)
		(width 0.16002)
		(layer "In11.Cu")
		(net "M_F_CPU1_SB_DQS_DN<2>")
	)
	(segment
		(start 50.776886 -303.531524)
		(end 50.332132 -303.531524)
		(width 0.16002)
		(layer "In11.Cu")
		(net "M_F_CPU1_SB_DQS_DN<2>")
	)
	(segment
		(start 72.243696 -289.804856)
		(end 72.243696 -290.03117)
		(width 0.16002)
		(layer "In11.Cu")
		(net "M_F_CPU1_SB_DQS_DN<2>")
	)
	(segment
		(start 69.497956 -292.77691)
		(end 69.549264 -292.828472)
		(width 0.16002)
		(layer "In11.Cu")
		(net "M_F_CPU1_SB_DQS_DN<2>")
	)
	(segment
		(start 70.498716 -292.35527)
		(end 70.022212 -292.35527)
		(width 0.16002)
		(layer "In11.Cu")
		(net "M_F_CPU1_SB_DQS_DN<2>")
	)
	(segment
		(start 61.260736 -300.787816)
		(end 61.260736 -301.01413)
		(width 0.16002)
		(layer "In11.Cu")
		(net "M_F_CPU1_SB_DQS_DN<2>")
	)
	(segment
		(start 41.312846 -304.357024)
		(end 40.968168 -304.012346)
		(width 0.16002)
		(layer "In11.Cu")
		(net "M_F_CPU1_SB_DQS_DN<2>")
	)
	(segment
		(start 79.944722 -285.904432)
		(end 79.932784 -285.91129)
		(width 0.09525)
		(layer "In11.Cu")
		(net "M_F_CPU1_SB_DQS_DN<2>")
	)
	(segment
		(start 48.512222 -304.012346)
		(end 46.058074 -304.012346)
		(width 0.16002)
		(layer "In11.Cu")
		(net "M_F_CPU1_SB_DQS_DN<2>")
	)
	(segment
		(start 68.125086 -293.923466)
		(end 68.125086 -294.14978)
		(width 0.16002)
		(layer "In11.Cu")
		(net "M_F_CPU1_SB_DQS_DN<2>")
	)
	(segment
		(start 67.22491 -295.049448)
		(end 66.999104 -295.049448)
		(width 0.16002)
		(layer "In11.Cu")
		(net "M_F_CPU1_SB_DQS_DN<2>")
	)
	(segment
		(start 50.332132 -303.531524)
		(end 49.506632 -304.357024)
		(width 0.16002)
		(layer "In11.Cu")
		(net "M_F_CPU1_SB_DQS_DN<2>")
	)
	(segment
		(start 28.144724 -303.531524)
		(end 27.69997 -303.531524)
		(width 0.16002)
		(layer "In11.Cu")
		(net "M_F_CPU1_SB_DQS_DN<2>")
	)
	(segment
		(start 64.47917 -297.795188)
		(end 64.253364 -297.795188)
		(width 0.16002)
		(layer "In11.Cu")
		(net "M_F_CPU1_SB_DQS_DN<2>")
	)
	(segment
		(start 79.370682 -285.91129)
		(end 79.358744 -285.904432)
		(width 0.09525)
		(layer "In11.Cu")
		(net "M_F_CPU1_SB_DQS_DN<2>")
	)
	(segment
		(start 76.646278 -286.76473)
		(end 76.622656 -286.76473)
		(width 0.09525)
		(layer "In11.Cu")
		(net "M_F_CPU1_SB_DQS_DN<2>")
	)
	(segment
		(start 49.506632 -304.357024)
		(end 48.8569 -304.357024)
		(width 0.16002)
		(layer "In11.Cu")
		(net "M_F_CPU1_SB_DQS_DN<2>")
	)
	(arc
		(start 79.91475 -285.921704)
		(mid 79.64137 -285.986925)
		(end 79.370682 -285.91129)
		(width 0.09525)
		(layer "In11.Cu")
		(net "M_F_CPU1_SB_DQS_DN<2>")
	)
	(arc
		(start 81.24952 -285.91129)
		(mid 81.061052 -285.860613)
		(end 80.872584 -285.91129)
		(width 0.09525)
		(layer "In11.Cu")
		(net "M_F_CPU1_SB_DQS_DN<2>")
	)
	(arc
		(start 79.358744 -285.904432)
		(mid 79.175109 -285.860482)
		(end 78.993238 -285.91129)
		(width 0.09525)
		(layer "In11.Cu")
		(net "M_F_CPU1_SB_DQS_DN<2>")
	)
	(arc
		(start 83.129628 -285.91129)
		(mid 82.945853 -285.860518)
		(end 82.76082 -285.906464)
		(width 0.09525)
		(layer "In11.Cu")
		(net "M_F_CPU1_SB_DQS_DN<2>")
	)
	(arc
		(start 84.545932 -285.952184)
		(mid 84.30322 -285.985067)
		(end 84.069682 -285.91129)
		(width 0.09525)
		(layer "In11.Cu")
		(net "M_F_CPU1_SB_DQS_DN<2>")
	)
	(arc
		(start 84.069682 -285.91129)
		(mid 83.885907 -285.860518)
		(end 83.700874 -285.906464)
		(width 0.09525)
		(layer "In11.Cu")
		(net "M_F_CPU1_SB_DQS_DN<2>")
	)
	(arc
		(start 80.30972 -285.91129)
		(mid 80.128104 -285.860553)
		(end 79.944722 -285.904432)
		(width 0.09525)
		(layer "In11.Cu")
		(net "M_F_CPU1_SB_DQS_DN<2>")
	)
	(arc
		(start 83.692492 -285.91129)
		(mid 83.41106 -285.987045)
		(end 83.129628 -285.91129)
		(width 0.09525)
		(layer "In11.Cu")
		(net "M_F_CPU1_SB_DQS_DN<2>")
	)
	(arc
		(start 84.566252 -285.94431)
		(mid 84.55613 -285.948345)
		(end 84.545932 -285.952184)
		(width 0.09525)
		(layer "In11.Cu")
		(net "M_F_CPU1_SB_DQS_DN<2>")
	)
	(arc
		(start 81.812384 -285.91129)
		(mid 81.530952 -285.987045)
		(end 81.24952 -285.91129)
		(width 0.09525)
		(layer "In11.Cu")
		(net "M_F_CPU1_SB_DQS_DN<2>")
	)
	(arc
		(start 80.872584 -285.91129)
		(mid 80.591152 -285.987045)
		(end 80.30972 -285.91129)
		(width 0.09525)
		(layer "In11.Cu")
		(net "M_F_CPU1_SB_DQS_DN<2>")
	)
	(arc
		(start 82.181192 -285.906464)
		(mid 81.99616 -285.86055)
		(end 81.812384 -285.91129)
		(width 0.09525)
		(layer "In11.Cu")
		(net "M_F_CPU1_SB_DQS_DN<2>")
	)
	(arc
		(start 82.752438 -285.91129)
		(mid 82.471006 -285.987045)
		(end 82.189574 -285.91129)
		(width 0.09525)
		(layer "In11.Cu")
		(net "M_F_CPU1_SB_DQS_DN<2>")
	)
	(arc
		(start 78.993238 -285.91129)
		(mid 78.857186 -285.968059)
		(end 78.711044 -285.98749)
		(width 0.09525)
		(layer "In11.Cu")
		(net "M_F_CPU1_SB_DQS_DN<2>")
	)
	(segment
		(start 85.287866 -281.110436)
		(end 84.821014 -281.376374)
		(width 0.12954)
		(layer "F.Cu")
		(net "M_F_CPU1_SB_DQS_DN<1>")
	)
	(segment
		(start 64.167258 -289.186874)
		(end 64.281304 -289.30092)
		(width 0.16002)
		(layer "In11.Cu")
		(net "M_F_CPU1_SB_DQS_DN<1>")
	)
	(segment
		(start 75.955906 -281.083004)
		(end 75.979528 -281.083004)
		(width 0.09525)
		(layer "In11.Cu")
		(net "M_F_CPU1_SB_DQS_DN<1>")
	)
	(segment
		(start 65.54089 -287.813242)
		(end 65.654936 -287.927288)
		(width 0.16002)
		(layer "In11.Cu")
		(net "M_F_CPU1_SB_DQS_DN<1>")
	)
	(segment
		(start 83.692492 -281.051254)
		(end 83.700874 -281.046428)
		(width 0.09525)
		(layer "In11.Cu")
		(net "M_F_CPU1_SB_DQS_DN<1>")
	)
	(segment
		(start 68.4022 -285.180024)
		(end 68.878704 -285.180024)
		(width 0.16002)
		(layer "In11.Cu")
		(net "M_F_CPU1_SB_DQS_DN<1>")
	)
	(segment
		(start 63.384176 -290.674552)
		(end 63.80861 -290.250118)
		(width 0.16002)
		(layer "In11.Cu")
		(net "M_F_CPU1_SB_DQS_DN<1>")
	)
	(segment
		(start 24.131524 -294.81145)
		(end 24.280622 -294.662352)
		(width 0.16002)
		(layer "In11.Cu")
		(net "M_F_CPU1_SB_DQS_DN<1>")
	)
	(segment
		(start 84.66709 -281.110944)
		(end 84.821014 -281.376374)
		(width 0.09525)
		(layer "In11.Cu")
		(net "M_F_CPU1_SB_DQS_DN<1>")
	)
	(segment
		(start 49.506632 -295.00703)
		(end 50.332132 -294.18153)
		(width 0.16002)
		(layer "In11.Cu")
		(net "M_F_CPU1_SB_DQS_DN<1>")
	)
	(segment
		(start 66.688462 -286.43961)
		(end 66.914522 -286.43961)
		(width 0.16002)
		(layer "In11.Cu")
		(net "M_F_CPU1_SB_DQS_DN<1>")
	)
	(segment
		(start 69.303138 -284.251908)
		(end 69.748654 -283.806392)
		(width 0.16002)
		(layer "In11.Cu")
		(net "M_F_CPU1_SB_DQS_DN<1>")
	)
	(segment
		(start 63.80861 -290.250118)
		(end 63.80861 -289.773614)
		(width 0.16002)
		(layer "In11.Cu")
		(net "M_F_CPU1_SB_DQS_DN<1>")
	)
	(segment
		(start 30.969966 -294.662352)
		(end 33.424114 -294.662352)
		(width 0.16002)
		(layer "In11.Cu")
		(net "M_F_CPU1_SB_DQS_DN<1>")
	)
	(segment
		(start 30.120082 -293.812468)
		(end 30.969966 -294.662352)
		(width 0.16002)
		(layer "In11.Cu")
		(net "M_F_CPU1_SB_DQS_DN<1>")
	)
	(segment
		(start 82.752438 -281.051254)
		(end 82.76082 -281.046428)
		(width 0.09525)
		(layer "In11.Cu")
		(net "M_F_CPU1_SB_DQS_DN<1>")
	)
	(segment
		(start 48.512222 -294.662352)
		(end 48.8569 -295.00703)
		(width 0.16002)
		(layer "In11.Cu")
		(net "M_F_CPU1_SB_DQS_DN<1>")
	)
	(segment
		(start 67.929506 -286.129222)
		(end 67.929506 -285.652718)
		(width 0.16002)
		(layer "In11.Cu")
		(net "M_F_CPU1_SB_DQS_DN<1>")
	)
	(segment
		(start 46.058074 -294.662352)
		(end 48.512222 -294.662352)
		(width 0.16002)
		(layer "In11.Cu")
		(net "M_F_CPU1_SB_DQS_DN<1>")
	)
	(segment
		(start 65.654936 -287.927288)
		(end 66.13144 -287.927288)
		(width 0.16002)
		(layer "In11.Cu")
		(net "M_F_CPU1_SB_DQS_DN<1>")
	)
	(segment
		(start 66.13144 -287.927288)
		(end 66.555874 -287.502854)
		(width 0.16002)
		(layer "In11.Cu")
		(net "M_F_CPU1_SB_DQS_DN<1>")
	)
	(segment
		(start 65.068196 -288.285936)
		(end 65.068196 -288.059876)
		(width 0.16002)
		(layer "In11.Cu")
		(net "M_F_CPU1_SB_DQS_DN<1>")
	)
	(segment
		(start 35.244024 -294.18153)
		(end 35.688778 -294.18153)
		(width 0.16002)
		(layer "In11.Cu")
		(net "M_F_CPU1_SB_DQS_DN<1>")
	)
	(segment
		(start 69.303138 -284.75559)
		(end 69.303138 -284.251908)
		(width 0.16002)
		(layer "In11.Cu")
		(net "M_F_CPU1_SB_DQS_DN<1>")
	)
	(segment
		(start 76.755244 -280.737564)
		(end 78.08976 -280.737564)
		(width 0.09525)
		(layer "In11.Cu")
		(net "M_F_CPU1_SB_DQS_DN<1>")
	)
	(segment
		(start 52.752244 -293.812468)
		(end 53.394864 -294.455088)
		(width 0.16002)
		(layer "In11.Cu")
		(net "M_F_CPU1_SB_DQS_DN<1>")
	)
	(segment
		(start 78.08976 -280.737564)
		(end 78.315058 -280.963116)
		(width 0.09525)
		(layer "In11.Cu")
		(net "M_F_CPU1_SB_DQS_DN<1>")
	)
	(segment
		(start 50.776886 -294.18153)
		(end 51.145948 -293.812468)
		(width 0.16002)
		(layer "In11.Cu")
		(net "M_F_CPU1_SB_DQS_DN<1>")
	)
	(segment
		(start 69.748654 -283.806392)
		(end 70.252336 -283.806392)
		(width 0.16002)
		(layer "In11.Cu")
		(net "M_F_CPU1_SB_DQS_DN<1>")
	)
	(segment
		(start 41.312846 -295.00703)
		(end 41.962578 -295.00703)
		(width 0.16002)
		(layer "In11.Cu")
		(net "M_F_CPU1_SB_DQS_DN<1>")
	)
	(segment
		(start 71.122286 -282.43276)
		(end 71.625968 -282.43276)
		(width 0.16002)
		(layer "In11.Cu")
		(net "M_F_CPU1_SB_DQS_DN<1>")
	)
	(segment
		(start 62.907672 -290.674552)
		(end 63.384176 -290.674552)
		(width 0.16002)
		(layer "In11.Cu")
		(net "M_F_CPU1_SB_DQS_DN<1>")
	)
	(segment
		(start 43.601894 -293.812468)
		(end 45.20819 -293.812468)
		(width 0.16002)
		(layer "In11.Cu")
		(net "M_F_CPU1_SB_DQS_DN<1>")
	)
	(segment
		(start 72.472042 -281.083004)
		(end 75.955906 -281.083004)
		(width 0.16002)
		(layer "In11.Cu")
		(net "M_F_CPU1_SB_DQS_DN<1>")
	)
	(segment
		(start 72.050402 -282.008326)
		(end 72.050402 -281.504644)
		(width 0.16002)
		(layer "In11.Cu")
		(net "M_F_CPU1_SB_DQS_DN<1>")
	)
	(segment
		(start 60.636912 -293.421816)
		(end 61.061346 -292.997382)
		(width 0.16002)
		(layer "In11.Cu")
		(net "M_F_CPU1_SB_DQS_DN<1>")
	)
	(segment
		(start 25.88006 -294.662352)
		(end 26.224738 -295.00703)
		(width 0.16002)
		(layer "In11.Cu")
		(net "M_F_CPU1_SB_DQS_DN<1>")
	)
	(segment
		(start 48.8569 -295.00703)
		(end 49.506632 -295.00703)
		(width 0.16002)
		(layer "In11.Cu")
		(net "M_F_CPU1_SB_DQS_DN<1>")
	)
	(segment
		(start 72.050402 -281.504644)
		(end 72.472042 -281.083004)
		(width 0.16002)
		(layer "In11.Cu")
		(net "M_F_CPU1_SB_DQS_DN<1>")
	)
	(segment
		(start 45.20819 -293.812468)
		(end 46.058074 -294.662352)
		(width 0.16002)
		(layer "In11.Cu")
		(net "M_F_CPU1_SB_DQS_DN<1>")
	)
	(segment
		(start 62.434978 -291.147246)
		(end 62.320932 -291.0332)
		(width 0.16002)
		(layer "In11.Cu")
		(net "M_F_CPU1_SB_DQS_DN<1>")
	)
	(segment
		(start 53.751734 -294.455088)
		(end 54.303676 -295.00703)
		(width 0.16002)
		(layer "In11.Cu")
		(net "M_F_CPU1_SB_DQS_DN<1>")
	)
	(segment
		(start 78.430374 -281.051254)
		(end 78.455774 -281.065986)
		(width 0.09525)
		(layer "In11.Cu")
		(net "M_F_CPU1_SB_DQS_DN<1>")
	)
	(segment
		(start 43.232832 -294.18153)
		(end 43.601894 -293.812468)
		(width 0.16002)
		(layer "In11.Cu")
		(net "M_F_CPU1_SB_DQS_DN<1>")
	)
	(segment
		(start 62.567566 -290.560506)
		(end 62.793626 -290.560506)
		(width 0.16002)
		(layer "In11.Cu")
		(net "M_F_CPU1_SB_DQS_DN<1>")
	)
	(segment
		(start 64.757808 -289.30092)
		(end 65.182242 -288.876486)
		(width 0.16002)
		(layer "In11.Cu")
		(net "M_F_CPU1_SB_DQS_DN<1>")
	)
	(segment
		(start 79.358744 -281.044396)
		(end 79.370682 -281.051254)
		(width 0.09525)
		(layer "In11.Cu")
		(net "M_F_CPU1_SB_DQS_DN<1>")
	)
	(segment
		(start 21.70811 -295.085262)
		(end 21.981922 -294.81145)
		(width 0.16002)
		(layer "In11.Cu")
		(net "M_F_CPU1_SB_DQS_DN<1>")
	)
	(segment
		(start 33.768792 -295.00703)
		(end 34.418524 -295.00703)
		(width 0.16002)
		(layer "In11.Cu")
		(net "M_F_CPU1_SB_DQS_DN<1>")
	)
	(segment
		(start 67.028568 -286.553656)
		(end 67.505072 -286.553656)
		(width 0.16002)
		(layer "In11.Cu")
		(net "M_F_CPU1_SB_DQS_DN<1>")
	)
	(segment
		(start 62.320932 -290.80714)
		(end 62.567566 -290.560506)
		(width 0.16002)
		(layer "In11.Cu")
		(net "M_F_CPU1_SB_DQS_DN<1>")
	)
	(segment
		(start 61.061346 -292.4937)
		(end 61.506862 -292.048184)
		(width 0.16002)
		(layer "In11.Cu")
		(net "M_F_CPU1_SB_DQS_DN<1>")
	)
	(segment
		(start 24.280622 -294.662352)
		(end 25.88006 -294.662352)
		(width 0.16002)
		(layer "In11.Cu")
		(net "M_F_CPU1_SB_DQS_DN<1>")
	)
	(segment
		(start 61.506862 -292.048184)
		(end 62.010544 -292.048184)
		(width 0.16002)
		(layer "In11.Cu")
		(net "M_F_CPU1_SB_DQS_DN<1>")
	)
	(segment
		(start 41.962578 -295.00703)
		(end 42.788078 -294.18153)
		(width 0.16002)
		(layer "In11.Cu")
		(net "M_F_CPU1_SB_DQS_DN<1>")
	)
	(segment
		(start 75.979528 -281.083004)
		(end 76.03871 -281.023822)
		(width 0.09525)
		(layer "In11.Cu")
		(net "M_F_CPU1_SB_DQS_DN<1>")
	)
	(segment
		(start 63.694564 -289.659568)
		(end 63.694564 -289.433508)
		(width 0.16002)
		(layer "In11.Cu")
		(net "M_F_CPU1_SB_DQS_DN<1>")
	)
	(segment
		(start 64.281304 -289.30092)
		(end 64.757808 -289.30092)
		(width 0.16002)
		(layer "In11.Cu")
		(net "M_F_CPU1_SB_DQS_DN<1>")
	)
	(segment
		(start 66.914522 -286.43961)
		(end 67.028568 -286.553656)
		(width 0.16002)
		(layer "In11.Cu")
		(net "M_F_CPU1_SB_DQS_DN<1>")
	)
	(segment
		(start 84.566252 -281.084274)
		(end 84.66709 -281.110944)
		(width 0.09525)
		(layer "In11.Cu")
		(net "M_F_CPU1_SB_DQS_DN<1>")
	)
	(segment
		(start 62.793626 -290.560506)
		(end 62.907672 -290.674552)
		(width 0.16002)
		(layer "In11.Cu")
		(net "M_F_CPU1_SB_DQS_DN<1>")
	)
	(segment
		(start 65.182242 -288.399982)
		(end 65.068196 -288.285936)
		(width 0.16002)
		(layer "In11.Cu")
		(net "M_F_CPU1_SB_DQS_DN<1>")
	)
	(segment
		(start 68.062094 -285.065978)
		(end 68.288154 -285.065978)
		(width 0.16002)
		(layer "In11.Cu")
		(net "M_F_CPU1_SB_DQS_DN<1>")
	)
	(segment
		(start 57.050432 -295.00703)
		(end 57.875932 -294.18153)
		(width 0.16002)
		(layer "In11.Cu")
		(net "M_F_CPU1_SB_DQS_DN<1>")
	)
	(segment
		(start 79.932784 -281.051254)
		(end 79.944722 -281.044396)
		(width 0.09525)
		(layer "In11.Cu")
		(net "M_F_CPU1_SB_DQS_DN<1>")
	)
	(segment
		(start 35.688778 -294.18153)
		(end 36.05784 -293.812468)
		(width 0.16002)
		(layer "In11.Cu")
		(net "M_F_CPU1_SB_DQS_DN<1>")
	)
	(segment
		(start 67.505072 -286.553656)
		(end 67.929506 -286.129222)
		(width 0.16002)
		(layer "In11.Cu")
		(net "M_F_CPU1_SB_DQS_DN<1>")
	)
	(segment
		(start 27.69997 -294.18153)
		(end 28.144724 -294.18153)
		(width 0.16002)
		(layer "In11.Cu")
		(net "M_F_CPU1_SB_DQS_DN<1>")
	)
	(segment
		(start 66.441828 -286.912304)
		(end 66.441828 -286.686244)
		(width 0.16002)
		(layer "In11.Cu")
		(net "M_F_CPU1_SB_DQS_DN<1>")
	)
	(segment
		(start 66.555874 -287.502854)
		(end 66.555874 -287.02635)
		(width 0.16002)
		(layer "In11.Cu")
		(net "M_F_CPU1_SB_DQS_DN<1>")
	)
	(segment
		(start 37.664136 -293.812468)
		(end 38.51402 -294.662352)
		(width 0.16002)
		(layer "In11.Cu")
		(net "M_F_CPU1_SB_DQS_DN<1>")
	)
	(segment
		(start 68.878704 -285.180024)
		(end 69.303138 -284.75559)
		(width 0.16002)
		(layer "In11.Cu")
		(net "M_F_CPU1_SB_DQS_DN<1>")
	)
	(segment
		(start 51.145948 -293.812468)
		(end 52.752244 -293.812468)
		(width 0.16002)
		(layer "In11.Cu")
		(net "M_F_CPU1_SB_DQS_DN<1>")
	)
	(segment
		(start 42.788078 -294.18153)
		(end 43.232832 -294.18153)
		(width 0.16002)
		(layer "In11.Cu")
		(net "M_F_CPU1_SB_DQS_DN<1>")
	)
	(segment
		(start 62.320932 -291.0332)
		(end 62.320932 -290.80714)
		(width 0.16002)
		(layer "In11.Cu")
		(net "M_F_CPU1_SB_DQS_DN<1>")
	)
	(segment
		(start 71.625968 -282.43276)
		(end 72.050402 -282.008326)
		(width 0.16002)
		(layer "In11.Cu")
		(net "M_F_CPU1_SB_DQS_DN<1>")
	)
	(segment
		(start 66.441828 -286.686244)
		(end 66.688462 -286.43961)
		(width 0.16002)
		(layer "In11.Cu")
		(net "M_F_CPU1_SB_DQS_DN<1>")
	)
	(segment
		(start 34.418524 -295.00703)
		(end 35.244024 -294.18153)
		(width 0.16002)
		(layer "In11.Cu")
		(net "M_F_CPU1_SB_DQS_DN<1>")
	)
	(segment
		(start 63.694564 -289.433508)
		(end 63.941198 -289.186874)
		(width 0.16002)
		(layer "In11.Cu")
		(net "M_F_CPU1_SB_DQS_DN<1>")
	)
	(segment
		(start 76.468986 -281.023822)
		(end 76.755244 -280.737564)
		(width 0.09525)
		(layer "In11.Cu")
		(net "M_F_CPU1_SB_DQS_DN<1>")
	)
	(segment
		(start 26.87447 -295.00703)
		(end 27.69997 -294.18153)
		(width 0.16002)
		(layer "In11.Cu")
		(net "M_F_CPU1_SB_DQS_DN<1>")
	)
	(segment
		(start 66.555874 -287.02635)
		(end 66.441828 -286.912304)
		(width 0.16002)
		(layer "In11.Cu")
		(net "M_F_CPU1_SB_DQS_DN<1>")
	)
	(segment
		(start 70.67677 -283.381958)
		(end 70.67677 -282.878276)
		(width 0.16002)
		(layer "In11.Cu")
		(net "M_F_CPU1_SB_DQS_DN<1>")
	)
	(segment
		(start 76.03871 -281.023822)
		(end 76.468986 -281.023822)
		(width 0.09525)
		(layer "In11.Cu")
		(net "M_F_CPU1_SB_DQS_DN<1>")
	)
	(segment
		(start 28.513786 -293.812468)
		(end 30.120082 -293.812468)
		(width 0.16002)
		(layer "In11.Cu")
		(net "M_F_CPU1_SB_DQS_DN<1>")
	)
	(segment
		(start 62.434978 -291.62375)
		(end 62.434978 -291.147246)
		(width 0.16002)
		(layer "In11.Cu")
		(net "M_F_CPU1_SB_DQS_DN<1>")
	)
	(segment
		(start 65.182242 -288.876486)
		(end 65.182242 -288.399982)
		(width 0.16002)
		(layer "In11.Cu")
		(net "M_F_CPU1_SB_DQS_DN<1>")
	)
	(segment
		(start 67.929506 -285.652718)
		(end 67.81546 -285.538672)
		(width 0.16002)
		(layer "In11.Cu")
		(net "M_F_CPU1_SB_DQS_DN<1>")
	)
	(segment
		(start 79.91475 -281.061668)
		(end 79.932784 -281.051254)
		(width 0.09525)
		(layer "In11.Cu")
		(net "M_F_CPU1_SB_DQS_DN<1>")
	)
	(segment
		(start 65.31483 -287.813242)
		(end 65.54089 -287.813242)
		(width 0.16002)
		(layer "In11.Cu")
		(net "M_F_CPU1_SB_DQS_DN<1>")
	)
	(segment
		(start 54.303676 -295.00703)
		(end 57.050432 -295.00703)
		(width 0.16002)
		(layer "In11.Cu")
		(net "M_F_CPU1_SB_DQS_DN<1>")
	)
	(segment
		(start 61.061346 -292.997382)
		(end 61.061346 -292.4937)
		(width 0.16002)
		(layer "In11.Cu")
		(net "M_F_CPU1_SB_DQS_DN<1>")
	)
	(segment
		(start 40.968168 -294.662352)
		(end 41.312846 -295.00703)
		(width 0.16002)
		(layer "In11.Cu")
		(net "M_F_CPU1_SB_DQS_DN<1>")
	)
	(segment
		(start 28.144724 -294.18153)
		(end 28.513786 -293.812468)
		(width 0.16002)
		(layer "In11.Cu")
		(net "M_F_CPU1_SB_DQS_DN<1>")
	)
	(segment
		(start 60.13323 -293.421816)
		(end 60.636912 -293.421816)
		(width 0.16002)
		(layer "In11.Cu")
		(net "M_F_CPU1_SB_DQS_DN<1>")
	)
	(segment
		(start 65.068196 -288.059876)
		(end 65.31483 -287.813242)
		(width 0.16002)
		(layer "In11.Cu")
		(net "M_F_CPU1_SB_DQS_DN<1>")
	)
	(segment
		(start 50.332132 -294.18153)
		(end 50.776886 -294.18153)
		(width 0.16002)
		(layer "In11.Cu")
		(net "M_F_CPU1_SB_DQS_DN<1>")
	)
	(segment
		(start 82.181192 -281.046428)
		(end 82.189574 -281.051254)
		(width 0.09525)
		(layer "In11.Cu")
		(net "M_F_CPU1_SB_DQS_DN<1>")
	)
	(segment
		(start 62.010544 -292.048184)
		(end 62.434978 -291.62375)
		(width 0.16002)
		(layer "In11.Cu")
		(net "M_F_CPU1_SB_DQS_DN<1>")
	)
	(segment
		(start 63.80861 -289.773614)
		(end 63.694564 -289.659568)
		(width 0.16002)
		(layer "In11.Cu")
		(net "M_F_CPU1_SB_DQS_DN<1>")
	)
	(segment
		(start 67.81546 -285.312612)
		(end 68.062094 -285.065978)
		(width 0.16002)
		(layer "In11.Cu")
		(net "M_F_CPU1_SB_DQS_DN<1>")
	)
	(segment
		(start 57.875932 -294.18153)
		(end 59.373516 -294.18153)
		(width 0.16002)
		(layer "In11.Cu")
		(net "M_F_CPU1_SB_DQS_DN<1>")
	)
	(segment
		(start 21.981922 -294.81145)
		(end 24.131524 -294.81145)
		(width 0.16002)
		(layer "In11.Cu")
		(net "M_F_CPU1_SB_DQS_DN<1>")
	)
	(segment
		(start 70.252336 -283.806392)
		(end 70.67677 -283.381958)
		(width 0.16002)
		(layer "In11.Cu")
		(net "M_F_CPU1_SB_DQS_DN<1>")
	)
	(segment
		(start 70.67677 -282.878276)
		(end 71.122286 -282.43276)
		(width 0.16002)
		(layer "In11.Cu")
		(net "M_F_CPU1_SB_DQS_DN<1>")
	)
	(segment
		(start 36.05784 -293.812468)
		(end 37.664136 -293.812468)
		(width 0.16002)
		(layer "In11.Cu")
		(net "M_F_CPU1_SB_DQS_DN<1>")
	)
	(segment
		(start 63.941198 -289.186874)
		(end 64.167258 -289.186874)
		(width 0.16002)
		(layer "In11.Cu")
		(net "M_F_CPU1_SB_DQS_DN<1>")
	)
	(segment
		(start 67.81546 -285.538672)
		(end 67.81546 -285.312612)
		(width 0.16002)
		(layer "In11.Cu")
		(net "M_F_CPU1_SB_DQS_DN<1>")
	)
	(segment
		(start 38.51402 -294.662352)
		(end 40.968168 -294.662352)
		(width 0.16002)
		(layer "In11.Cu")
		(net "M_F_CPU1_SB_DQS_DN<1>")
	)
	(segment
		(start 33.424114 -294.662352)
		(end 33.768792 -295.00703)
		(width 0.16002)
		(layer "In11.Cu")
		(net "M_F_CPU1_SB_DQS_DN<1>")
	)
	(segment
		(start 53.394864 -294.455088)
		(end 53.751734 -294.455088)
		(width 0.16002)
		(layer "In11.Cu")
		(net "M_F_CPU1_SB_DQS_DN<1>")
	)
	(segment
		(start 26.224738 -295.00703)
		(end 26.87447 -295.00703)
		(width 0.16002)
		(layer "In11.Cu")
		(net "M_F_CPU1_SB_DQS_DN<1>")
	)
	(segment
		(start 68.288154 -285.065978)
		(end 68.4022 -285.180024)
		(width 0.16002)
		(layer "In11.Cu")
		(net "M_F_CPU1_SB_DQS_DN<1>")
	)
	(segment
		(start 59.373516 -294.18153)
		(end 60.13323 -293.421816)
		(width 0.16002)
		(layer "In11.Cu")
		(net "M_F_CPU1_SB_DQS_DN<1>")
	)
	(arc
		(start 78.315058 -280.963116)
		(mid 78.328316 -280.975783)
		(end 78.341982 -280.988008)
		(width 0.09525)
		(layer "In11.Cu")
		(net "M_F_CPU1_SB_DQS_DN<1>")
	)
	(arc
		(start 84.069682 -281.051254)
		(mid 84.303226 -281.12496)
		(end 84.545932 -281.092148)
		(width 0.09525)
		(layer "In11.Cu")
		(net "M_F_CPU1_SB_DQS_DN<1>")
	)
	(arc
		(start 79.370682 -281.051254)
		(mid 79.64137 -281.126906)
		(end 79.91475 -281.061668)
		(width 0.09525)
		(layer "In11.Cu")
		(net "M_F_CPU1_SB_DQS_DN<1>")
	)
	(arc
		(start 84.545932 -281.092148)
		(mid 84.556131 -281.088311)
		(end 84.566252 -281.084274)
		(width 0.09525)
		(layer "In11.Cu")
		(net "M_F_CPU1_SB_DQS_DN<1>")
	)
	(arc
		(start 80.30972 -281.051254)
		(mid 80.591152 -281.127009)
		(end 80.872584 -281.051254)
		(width 0.09525)
		(layer "In11.Cu")
		(net "M_F_CPU1_SB_DQS_DN<1>")
	)
	(arc
		(start 82.189574 -281.051254)
		(mid 82.471006 -281.127009)
		(end 82.752438 -281.051254)
		(width 0.09525)
		(layer "In11.Cu")
		(net "M_F_CPU1_SB_DQS_DN<1>")
	)
	(arc
		(start 81.812384 -281.051254)
		(mid 81.996159 -281.000482)
		(end 82.181192 -281.046428)
		(width 0.09525)
		(layer "In11.Cu")
		(net "M_F_CPU1_SB_DQS_DN<1>")
	)
	(arc
		(start 81.24952 -281.051254)
		(mid 81.530952 -281.127009)
		(end 81.812384 -281.051254)
		(width 0.09525)
		(layer "In11.Cu")
		(net "M_F_CPU1_SB_DQS_DN<1>")
	)
	(arc
		(start 78.455774 -281.065986)
		(mid 78.72639 -281.127211)
		(end 78.993238 -281.051254)
		(width 0.09525)
		(layer "In11.Cu")
		(net "M_F_CPU1_SB_DQS_DN<1>")
	)
	(arc
		(start 78.341982 -280.988008)
		(mid 78.384636 -281.021787)
		(end 78.430374 -281.051254)
		(width 0.09525)
		(layer "In11.Cu")
		(net "M_F_CPU1_SB_DQS_DN<1>")
	)
	(arc
		(start 83.700874 -281.046428)
		(mid 83.885906 -281.000514)
		(end 84.069682 -281.051254)
		(width 0.09525)
		(layer "In11.Cu")
		(net "M_F_CPU1_SB_DQS_DN<1>")
	)
	(arc
		(start 79.944722 -281.044396)
		(mid 80.128103 -281.000565)
		(end 80.30972 -281.051254)
		(width 0.09525)
		(layer "In11.Cu")
		(net "M_F_CPU1_SB_DQS_DN<1>")
	)
	(arc
		(start 78.993238 -281.051254)
		(mid 79.175108 -281.000389)
		(end 79.358744 -281.044396)
		(width 0.09525)
		(layer "In11.Cu")
		(net "M_F_CPU1_SB_DQS_DN<1>")
	)
	(arc
		(start 83.129628 -281.051254)
		(mid 83.41106 -281.127009)
		(end 83.692492 -281.051254)
		(width 0.09525)
		(layer "In11.Cu")
		(net "M_F_CPU1_SB_DQS_DN<1>")
	)
	(arc
		(start 80.872584 -281.051254)
		(mid 81.061052 -281.000577)
		(end 81.24952 -281.051254)
		(width 0.09525)
		(layer "In11.Cu")
		(net "M_F_CPU1_SB_DQS_DN<1>")
	)
	(arc
		(start 82.76082 -281.046428)
		(mid 82.945852 -281.000514)
		(end 83.129628 -281.051254)
		(width 0.09525)
		(layer "In11.Cu")
		(net "M_F_CPU1_SB_DQS_DN<1>")
	)
	(segment
		(start 85.287866 -276.2504)
		(end 84.821014 -276.516338)
		(width 0.12954)
		(layer "F.Cu")
		(net "M_F_CPU1_SB_DQS_DN<0>")
	)
	(segment
		(start 68.59016 -276.65553)
		(end 68.59016 -276.179026)
		(width 0.16002)
		(layer "In11.Cu")
		(net "M_F_CPU1_SB_DQS_DN<0>")
	)
	(segment
		(start 66.31559 -278.453596)
		(end 66.792094 -278.453596)
		(width 0.16002)
		(layer "In11.Cu")
		(net "M_F_CPU1_SB_DQS_DN<0>")
	)
	(segment
		(start 35.688778 -284.831536)
		(end 36.05784 -284.462474)
		(width 0.16002)
		(layer "In11.Cu")
		(net "M_F_CPU1_SB_DQS_DN<0>")
	)
	(segment
		(start 57.050432 -285.657036)
		(end 57.875932 -284.831536)
		(width 0.16002)
		(layer "In11.Cu")
		(net "M_F_CPU1_SB_DQS_DN<0>")
	)
	(segment
		(start 28.513786 -284.462474)
		(end 30.120082 -284.462474)
		(width 0.16002)
		(layer "In11.Cu")
		(net "M_F_CPU1_SB_DQS_DN<0>")
	)
	(segment
		(start 63.173356 -281.03195)
		(end 63.399416 -281.03195)
		(width 0.16002)
		(layer "In11.Cu")
		(net "M_F_CPU1_SB_DQS_DN<0>")
	)
	(segment
		(start 24.131524 -285.461456)
		(end 24.280622 -285.312358)
		(width 0.16002)
		(layer "In11.Cu")
		(net "M_F_CPU1_SB_DQS_DN<0>")
	)
	(segment
		(start 50.776886 -284.831536)
		(end 51.145948 -284.462474)
		(width 0.16002)
		(layer "In11.Cu")
		(net "M_F_CPU1_SB_DQS_DN<0>")
	)
	(segment
		(start 60.426092 -283.779214)
		(end 60.652152 -283.779214)
		(width 0.16002)
		(layer "In11.Cu")
		(net "M_F_CPU1_SB_DQS_DN<0>")
	)
	(segment
		(start 61.55309 -282.652216)
		(end 61.799724 -282.405582)
		(width 0.16002)
		(layer "In11.Cu")
		(net "M_F_CPU1_SB_DQS_DN<0>")
	)
	(segment
		(start 27.69997 -284.831536)
		(end 28.144724 -284.831536)
		(width 0.16002)
		(layer "In11.Cu")
		(net "M_F_CPU1_SB_DQS_DN<0>")
	)
	(segment
		(start 67.216528 -278.029162)
		(end 67.216528 -277.552658)
		(width 0.16002)
		(layer "In11.Cu")
		(net "M_F_CPU1_SB_DQS_DN<0>")
	)
	(segment
		(start 34.418524 -285.657036)
		(end 35.244024 -284.831536)
		(width 0.16002)
		(layer "In11.Cu")
		(net "M_F_CPU1_SB_DQS_DN<0>")
	)
	(segment
		(start 78.00213 -276.266656)
		(end 79.65186 -276.266656)
		(width 0.09525)
		(layer "In11.Cu")
		(net "M_F_CPU1_SB_DQS_DN<0>")
	)
	(segment
		(start 63.399416 -281.03195)
		(end 63.568326 -281.20086)
		(width 0.16002)
		(layer "In11.Cu")
		(net "M_F_CPU1_SB_DQS_DN<0>")
	)
	(segment
		(start 63.095632 -282.150058)
		(end 63.095632 -281.673554)
		(width 0.16002)
		(layer "In11.Cu")
		(net "M_F_CPU1_SB_DQS_DN<0>")
	)
	(segment
		(start 30.120082 -284.462474)
		(end 30.969966 -285.312358)
		(width 0.16002)
		(layer "In11.Cu")
		(net "M_F_CPU1_SB_DQS_DN<0>")
	)
	(segment
		(start 84.566252 -276.224238)
		(end 84.66709 -276.250908)
		(width 0.09525)
		(layer "In11.Cu")
		(net "M_F_CPU1_SB_DQS_DN<0>")
	)
	(segment
		(start 43.601894 -284.462474)
		(end 45.20819 -284.462474)
		(width 0.16002)
		(layer "In11.Cu")
		(net "M_F_CPU1_SB_DQS_DN<0>")
	)
	(segment
		(start 48.512222 -285.312358)
		(end 48.8569 -285.657036)
		(width 0.16002)
		(layer "In11.Cu")
		(net "M_F_CPU1_SB_DQS_DN<0>")
	)
	(segment
		(start 37.664136 -284.462474)
		(end 38.51402 -285.312358)
		(width 0.16002)
		(layer "In11.Cu")
		(net "M_F_CPU1_SB_DQS_DN<0>")
	)
	(segment
		(start 67.689222 -277.079964)
		(end 68.165726 -277.079964)
		(width 0.16002)
		(layer "In11.Cu")
		(net "M_F_CPU1_SB_DQS_DN<0>")
	)
	(segment
		(start 75.963526 -275.459444)
		(end 75.987148 -275.459444)
		(width 0.09525)
		(layer "In11.Cu")
		(net "M_F_CPU1_SB_DQS_DN<0>")
	)
	(segment
		(start 33.424114 -285.312358)
		(end 33.768792 -285.657036)
		(width 0.16002)
		(layer "In11.Cu")
		(net "M_F_CPU1_SB_DQS_DN<0>")
	)
	(segment
		(start 51.145948 -284.462474)
		(end 52.752244 -284.462474)
		(width 0.16002)
		(layer "In11.Cu")
		(net "M_F_CPU1_SB_DQS_DN<0>")
	)
	(segment
		(start 66.14668 -278.284686)
		(end 66.31559 -278.453596)
		(width 0.16002)
		(layer "In11.Cu")
		(net "M_F_CPU1_SB_DQS_DN<0>")
	)
	(segment
		(start 67.520312 -276.911054)
		(end 67.689222 -277.079964)
		(width 0.16002)
		(layer "In11.Cu")
		(net "M_F_CPU1_SB_DQS_DN<0>")
	)
	(segment
		(start 65.673986 -278.75738)
		(end 65.673986 -278.53132)
		(width 0.16002)
		(layer "In11.Cu")
		(net "M_F_CPU1_SB_DQS_DN<0>")
	)
	(segment
		(start 62.926722 -281.504644)
		(end 62.926722 -281.278584)
		(width 0.16002)
		(layer "In11.Cu")
		(net "M_F_CPU1_SB_DQS_DN<0>")
	)
	(segment
		(start 61.55309 -282.878276)
		(end 61.55309 -282.652216)
		(width 0.16002)
		(layer "In11.Cu")
		(net "M_F_CPU1_SB_DQS_DN<0>")
	)
	(segment
		(start 49.506632 -285.657036)
		(end 50.332132 -284.831536)
		(width 0.16002)
		(layer "In11.Cu")
		(net "M_F_CPU1_SB_DQS_DN<0>")
	)
	(segment
		(start 63.095632 -281.673554)
		(end 62.926722 -281.504644)
		(width 0.16002)
		(layer "In11.Cu")
		(net "M_F_CPU1_SB_DQS_DN<0>")
	)
	(segment
		(start 65.842896 -279.402794)
		(end 65.842896 -278.92629)
		(width 0.16002)
		(layer "In11.Cu")
		(net "M_F_CPU1_SB_DQS_DN<0>")
	)
	(segment
		(start 65.673986 -278.53132)
		(end 65.92062 -278.284686)
		(width 0.16002)
		(layer "In11.Cu")
		(net "M_F_CPU1_SB_DQS_DN<0>")
	)
	(segment
		(start 21.70811 -285.735268)
		(end 21.981922 -285.461456)
		(width 0.16002)
		(layer "In11.Cu")
		(net "M_F_CPU1_SB_DQS_DN<0>")
	)
	(segment
		(start 30.969966 -285.312358)
		(end 33.424114 -285.312358)
		(width 0.16002)
		(layer "In11.Cu")
		(net "M_F_CPU1_SB_DQS_DN<0>")
	)
	(segment
		(start 61.722 -283.047186)
		(end 61.55309 -282.878276)
		(width 0.16002)
		(layer "In11.Cu")
		(net "M_F_CPU1_SB_DQS_DN<0>")
	)
	(segment
		(start 60.821062 -283.948124)
		(end 61.297566 -283.948124)
		(width 0.16002)
		(layer "In11.Cu")
		(net "M_F_CPU1_SB_DQS_DN<0>")
	)
	(segment
		(start 46.058074 -285.312358)
		(end 48.512222 -285.312358)
		(width 0.16002)
		(layer "In11.Cu")
		(net "M_F_CPU1_SB_DQS_DN<0>")
	)
	(segment
		(start 77.135736 -275.400262)
		(end 78.00213 -276.266656)
		(width 0.09525)
		(layer "In11.Cu")
		(net "M_F_CPU1_SB_DQS_DN<0>")
	)
	(segment
		(start 66.792094 -278.453596)
		(end 67.216528 -278.029162)
		(width 0.16002)
		(layer "In11.Cu")
		(net "M_F_CPU1_SB_DQS_DN<0>")
	)
	(segment
		(start 68.165726 -277.079964)
		(end 68.59016 -276.65553)
		(width 0.16002)
		(layer "In11.Cu")
		(net "M_F_CPU1_SB_DQS_DN<0>")
	)
	(segment
		(start 48.8569 -285.657036)
		(end 49.506632 -285.657036)
		(width 0.16002)
		(layer "In11.Cu")
		(net "M_F_CPU1_SB_DQS_DN<0>")
	)
	(segment
		(start 64.546988 -279.658318)
		(end 64.773048 -279.658318)
		(width 0.16002)
		(layer "In11.Cu")
		(net "M_F_CPU1_SB_DQS_DN<0>")
	)
	(segment
		(start 68.42125 -276.010116)
		(end 68.42125 -275.784056)
		(width 0.16002)
		(layer "In11.Cu")
		(net "M_F_CPU1_SB_DQS_DN<0>")
	)
	(segment
		(start 52.752244 -284.462474)
		(end 53.394864 -285.105094)
		(width 0.16002)
		(layer "In11.Cu")
		(net "M_F_CPU1_SB_DQS_DN<0>")
	)
	(segment
		(start 68.745862 -275.459444)
		(end 75.963526 -275.459444)
		(width 0.16002)
		(layer "In11.Cu")
		(net "M_F_CPU1_SB_DQS_DN<0>")
	)
	(segment
		(start 67.216528 -277.552658)
		(end 67.047618 -277.383748)
		(width 0.16002)
		(layer "In11.Cu")
		(net "M_F_CPU1_SB_DQS_DN<0>")
	)
	(segment
		(start 57.875932 -284.831536)
		(end 59.37377 -284.831536)
		(width 0.16002)
		(layer "In11.Cu")
		(net "M_F_CPU1_SB_DQS_DN<0>")
	)
	(segment
		(start 83.692492 -276.191218)
		(end 83.700874 -276.186392)
		(width 0.09525)
		(layer "In11.Cu")
		(net "M_F_CPU1_SB_DQS_DN<0>")
	)
	(segment
		(start 65.92062 -278.284686)
		(end 66.14668 -278.284686)
		(width 0.16002)
		(layer "In11.Cu")
		(net "M_F_CPU1_SB_DQS_DN<0>")
	)
	(segment
		(start 33.768792 -285.657036)
		(end 34.418524 -285.657036)
		(width 0.16002)
		(layer "In11.Cu")
		(net "M_F_CPU1_SB_DQS_DN<0>")
	)
	(segment
		(start 61.722 -283.52369)
		(end 61.722 -283.047186)
		(width 0.16002)
		(layer "In11.Cu")
		(net "M_F_CPU1_SB_DQS_DN<0>")
	)
	(segment
		(start 64.773048 -279.658318)
		(end 64.941958 -279.827228)
		(width 0.16002)
		(layer "In11.Cu")
		(net "M_F_CPU1_SB_DQS_DN<0>")
	)
	(segment
		(start 24.280622 -285.312358)
		(end 25.88006 -285.312358)
		(width 0.16002)
		(layer "In11.Cu")
		(net "M_F_CPU1_SB_DQS_DN<0>")
	)
	(segment
		(start 64.04483 -281.20086)
		(end 64.469264 -280.776426)
		(width 0.16002)
		(layer "In11.Cu")
		(net "M_F_CPU1_SB_DQS_DN<0>")
	)
	(segment
		(start 61.297566 -283.948124)
		(end 61.722 -283.52369)
		(width 0.16002)
		(layer "In11.Cu")
		(net "M_F_CPU1_SB_DQS_DN<0>")
	)
	(segment
		(start 45.20819 -284.462474)
		(end 46.058074 -285.312358)
		(width 0.16002)
		(layer "In11.Cu")
		(net "M_F_CPU1_SB_DQS_DN<0>")
	)
	(segment
		(start 60.652152 -283.779214)
		(end 60.821062 -283.948124)
		(width 0.16002)
		(layer "In11.Cu")
		(net "M_F_CPU1_SB_DQS_DN<0>")
	)
	(segment
		(start 62.671198 -282.574492)
		(end 63.095632 -282.150058)
		(width 0.16002)
		(layer "In11.Cu")
		(net "M_F_CPU1_SB_DQS_DN<0>")
	)
	(segment
		(start 65.842896 -278.92629)
		(end 65.673986 -278.75738)
		(width 0.16002)
		(layer "In11.Cu")
		(net "M_F_CPU1_SB_DQS_DN<0>")
	)
	(segment
		(start 67.047618 -277.383748)
		(end 67.047618 -277.157688)
		(width 0.16002)
		(layer "In11.Cu")
		(net "M_F_CPU1_SB_DQS_DN<0>")
	)
	(segment
		(start 54.303676 -285.657036)
		(end 57.050432 -285.657036)
		(width 0.16002)
		(layer "In11.Cu")
		(net "M_F_CPU1_SB_DQS_DN<0>")
	)
	(segment
		(start 75.987148 -275.459444)
		(end 76.04633 -275.400262)
		(width 0.09525)
		(layer "In11.Cu")
		(net "M_F_CPU1_SB_DQS_DN<0>")
	)
	(segment
		(start 53.394864 -285.105094)
		(end 53.751734 -285.105094)
		(width 0.16002)
		(layer "In11.Cu")
		(net "M_F_CPU1_SB_DQS_DN<0>")
	)
	(segment
		(start 63.568326 -281.20086)
		(end 64.04483 -281.20086)
		(width 0.16002)
		(layer "In11.Cu")
		(net "M_F_CPU1_SB_DQS_DN<0>")
	)
	(segment
		(start 26.224738 -285.657036)
		(end 26.87447 -285.657036)
		(width 0.16002)
		(layer "In11.Cu")
		(net "M_F_CPU1_SB_DQS_DN<0>")
	)
	(segment
		(start 68.42125 -275.784056)
		(end 68.745862 -275.459444)
		(width 0.16002)
		(layer "In11.Cu")
		(net "M_F_CPU1_SB_DQS_DN<0>")
	)
	(segment
		(start 43.232832 -284.831536)
		(end 43.601894 -284.462474)
		(width 0.16002)
		(layer "In11.Cu")
		(net "M_F_CPU1_SB_DQS_DN<0>")
	)
	(segment
		(start 64.300354 -280.131012)
		(end 64.300354 -279.904952)
		(width 0.16002)
		(layer "In11.Cu")
		(net "M_F_CPU1_SB_DQS_DN<0>")
	)
	(segment
		(start 76.04633 -275.400262)
		(end 77.135736 -275.400262)
		(width 0.09525)
		(layer "In11.Cu")
		(net "M_F_CPU1_SB_DQS_DN<0>")
	)
	(segment
		(start 62.926722 -281.278584)
		(end 63.173356 -281.03195)
		(width 0.16002)
		(layer "In11.Cu")
		(net "M_F_CPU1_SB_DQS_DN<0>")
	)
	(segment
		(start 64.469264 -280.776426)
		(end 64.469264 -280.299922)
		(width 0.16002)
		(layer "In11.Cu")
		(net "M_F_CPU1_SB_DQS_DN<0>")
	)
	(segment
		(start 62.194694 -282.574492)
		(end 62.671198 -282.574492)
		(width 0.16002)
		(layer "In11.Cu")
		(net "M_F_CPU1_SB_DQS_DN<0>")
	)
	(segment
		(start 84.66709 -276.250908)
		(end 84.821014 -276.516338)
		(width 0.09525)
		(layer "In11.Cu")
		(net "M_F_CPU1_SB_DQS_DN<0>")
	)
	(segment
		(start 38.51402 -285.312358)
		(end 40.968168 -285.312358)
		(width 0.16002)
		(layer "In11.Cu")
		(net "M_F_CPU1_SB_DQS_DN<0>")
	)
	(segment
		(start 41.312846 -285.657036)
		(end 41.962578 -285.657036)
		(width 0.16002)
		(layer "In11.Cu")
		(net "M_F_CPU1_SB_DQS_DN<0>")
	)
	(segment
		(start 35.244024 -284.831536)
		(end 35.688778 -284.831536)
		(width 0.16002)
		(layer "In11.Cu")
		(net "M_F_CPU1_SB_DQS_DN<0>")
	)
	(segment
		(start 40.968168 -285.312358)
		(end 41.312846 -285.657036)
		(width 0.16002)
		(layer "In11.Cu")
		(net "M_F_CPU1_SB_DQS_DN<0>")
	)
	(segment
		(start 64.300354 -279.904952)
		(end 64.546988 -279.658318)
		(width 0.16002)
		(layer "In11.Cu")
		(net "M_F_CPU1_SB_DQS_DN<0>")
	)
	(segment
		(start 82.752438 -276.191218)
		(end 82.76082 -276.186392)
		(width 0.09525)
		(layer "In11.Cu")
		(net "M_F_CPU1_SB_DQS_DN<0>")
	)
	(segment
		(start 28.144724 -284.831536)
		(end 28.513786 -284.462474)
		(width 0.16002)
		(layer "In11.Cu")
		(net "M_F_CPU1_SB_DQS_DN<0>")
	)
	(segment
		(start 53.751734 -285.105094)
		(end 54.303676 -285.657036)
		(width 0.16002)
		(layer "In11.Cu")
		(net "M_F_CPU1_SB_DQS_DN<0>")
	)
	(segment
		(start 64.941958 -279.827228)
		(end 65.418462 -279.827228)
		(width 0.16002)
		(layer "In11.Cu")
		(net "M_F_CPU1_SB_DQS_DN<0>")
	)
	(segment
		(start 21.981922 -285.461456)
		(end 24.131524 -285.461456)
		(width 0.16002)
		(layer "In11.Cu")
		(net "M_F_CPU1_SB_DQS_DN<0>")
	)
	(segment
		(start 67.294252 -276.911054)
		(end 67.520312 -276.911054)
		(width 0.16002)
		(layer "In11.Cu")
		(net "M_F_CPU1_SB_DQS_DN<0>")
	)
	(segment
		(start 42.788078 -284.831536)
		(end 43.232832 -284.831536)
		(width 0.16002)
		(layer "In11.Cu")
		(net "M_F_CPU1_SB_DQS_DN<0>")
	)
	(segment
		(start 62.025784 -282.405582)
		(end 62.194694 -282.574492)
		(width 0.16002)
		(layer "In11.Cu")
		(net "M_F_CPU1_SB_DQS_DN<0>")
	)
	(segment
		(start 61.799724 -282.405582)
		(end 62.025784 -282.405582)
		(width 0.16002)
		(layer "In11.Cu")
		(net "M_F_CPU1_SB_DQS_DN<0>")
	)
	(segment
		(start 36.05784 -284.462474)
		(end 37.664136 -284.462474)
		(width 0.16002)
		(layer "In11.Cu")
		(net "M_F_CPU1_SB_DQS_DN<0>")
	)
	(segment
		(start 41.962578 -285.657036)
		(end 42.788078 -284.831536)
		(width 0.16002)
		(layer "In11.Cu")
		(net "M_F_CPU1_SB_DQS_DN<0>")
	)
	(segment
		(start 50.332132 -284.831536)
		(end 50.776886 -284.831536)
		(width 0.16002)
		(layer "In11.Cu")
		(net "M_F_CPU1_SB_DQS_DN<0>")
	)
	(segment
		(start 64.469264 -280.299922)
		(end 64.300354 -280.131012)
		(width 0.16002)
		(layer "In11.Cu")
		(net "M_F_CPU1_SB_DQS_DN<0>")
	)
	(segment
		(start 67.047618 -277.157688)
		(end 67.294252 -276.911054)
		(width 0.16002)
		(layer "In11.Cu")
		(net "M_F_CPU1_SB_DQS_DN<0>")
	)
	(segment
		(start 68.59016 -276.179026)
		(end 68.42125 -276.010116)
		(width 0.16002)
		(layer "In11.Cu")
		(net "M_F_CPU1_SB_DQS_DN<0>")
	)
	(segment
		(start 79.932784 -276.191218)
		(end 79.944722 -276.18436)
		(width 0.09525)
		(layer "In11.Cu")
		(net "M_F_CPU1_SB_DQS_DN<0>")
	)
	(segment
		(start 26.87447 -285.657036)
		(end 27.69997 -284.831536)
		(width 0.16002)
		(layer "In11.Cu")
		(net "M_F_CPU1_SB_DQS_DN<0>")
	)
	(segment
		(start 82.181192 -276.186392)
		(end 82.189574 -276.191218)
		(width 0.09525)
		(layer "In11.Cu")
		(net "M_F_CPU1_SB_DQS_DN<0>")
	)
	(segment
		(start 59.37377 -284.831536)
		(end 60.426092 -283.779214)
		(width 0.16002)
		(layer "In11.Cu")
		(net "M_F_CPU1_SB_DQS_DN<0>")
	)
	(segment
		(start 25.88006 -285.312358)
		(end 26.224738 -285.657036)
		(width 0.16002)
		(layer "In11.Cu")
		(net "M_F_CPU1_SB_DQS_DN<0>")
	)
	(segment
		(start 65.418462 -279.827228)
		(end 65.842896 -279.402794)
		(width 0.16002)
		(layer "In11.Cu")
		(net "M_F_CPU1_SB_DQS_DN<0>")
	)
	(arc
		(start 79.944722 -276.18436)
		(mid 80.128103 -276.140529)
		(end 80.30972 -276.191218)
		(width 0.09525)
		(layer "In11.Cu")
		(net "M_F_CPU1_SB_DQS_DN<0>")
	)
	(arc
		(start 80.30972 -276.191218)
		(mid 80.591152 -276.266973)
		(end 80.872584 -276.191218)
		(width 0.09525)
		(layer "In11.Cu")
		(net "M_F_CPU1_SB_DQS_DN<0>")
	)
	(arc
		(start 81.24952 -276.191218)
		(mid 81.530952 -276.266973)
		(end 81.812384 -276.191218)
		(width 0.09525)
		(layer "In11.Cu")
		(net "M_F_CPU1_SB_DQS_DN<0>")
	)
	(arc
		(start 83.129628 -276.191218)
		(mid 83.41106 -276.266973)
		(end 83.692492 -276.191218)
		(width 0.09525)
		(layer "In11.Cu")
		(net "M_F_CPU1_SB_DQS_DN<0>")
	)
	(arc
		(start 79.65186 -276.266656)
		(mid 79.79729 -276.247454)
		(end 79.932784 -276.191218)
		(width 0.09525)
		(layer "In11.Cu")
		(net "M_F_CPU1_SB_DQS_DN<0>")
	)
	(arc
		(start 84.069682 -276.191218)
		(mid 84.303226 -276.264924)
		(end 84.545932 -276.232112)
		(width 0.09525)
		(layer "In11.Cu")
		(net "M_F_CPU1_SB_DQS_DN<0>")
	)
	(arc
		(start 84.545932 -276.232112)
		(mid 84.556131 -276.228275)
		(end 84.566252 -276.224238)
		(width 0.09525)
		(layer "In11.Cu")
		(net "M_F_CPU1_SB_DQS_DN<0>")
	)
	(arc
		(start 81.812384 -276.191218)
		(mid 81.996159 -276.140446)
		(end 82.181192 -276.186392)
		(width 0.09525)
		(layer "In11.Cu")
		(net "M_F_CPU1_SB_DQS_DN<0>")
	)
	(arc
		(start 82.189574 -276.191218)
		(mid 82.471006 -276.266973)
		(end 82.752438 -276.191218)
		(width 0.09525)
		(layer "In11.Cu")
		(net "M_F_CPU1_SB_DQS_DN<0>")
	)
	(arc
		(start 80.872584 -276.191218)
		(mid 81.061052 -276.140541)
		(end 81.24952 -276.191218)
		(width 0.09525)
		(layer "In11.Cu")
		(net "M_F_CPU1_SB_DQS_DN<0>")
	)
	(arc
		(start 83.700874 -276.186392)
		(mid 83.885906 -276.140478)
		(end 84.069682 -276.191218)
		(width 0.09525)
		(layer "In11.Cu")
		(net "M_F_CPU1_SB_DQS_DN<0>")
	)
	(arc
		(start 82.76082 -276.186392)
		(mid 82.945852 -276.140478)
		(end 83.129628 -276.191218)
		(width 0.09525)
		(layer "In11.Cu")
		(net "M_F_CPU1_SB_DQS_DN<0>")
	)
	(segment
		(start 86.22792 -279.490424)
		(end 85.761068 -279.756362)
		(width 0.10668)
		(layer "F.Cu")
		(net "M_F_CPU1_SB_DQ<9>")
	)
	(segment
		(start 39.065454 -292.960298)
		(end 39.38524 -293.280084)
		(width 0.14478)
		(layer "In11.Cu")
		(net "M_F_CPU1_SB_DQ<9>")
	)
	(segment
		(start 33.939988 -292.960298)
		(end 34.477706 -292.960298)
		(width 0.14478)
		(layer "In11.Cu")
		(net "M_F_CPU1_SB_DQ<9>")
	)
	(segment
		(start 69.109844 -282.164028)
		(end 69.439028 -282.164028)
		(width 0.14478)
		(layer "In11.Cu")
		(net "M_F_CPU1_SB_DQ<9>")
	)
	(segment
		(start 38.856666 -292.960298)
		(end 39.065454 -292.960298)
		(width 0.14478)
		(layer "In11.Cu")
		(net "M_F_CPU1_SB_DQ<9>")
	)
	(segment
		(start 23.468838 -293.183564)
		(end 23.631652 -293.346378)
		(width 0.14478)
		(layer "In11.Cu")
		(net "M_F_CPU1_SB_DQ<9>")
	)
	(segment
		(start 53.368448 -292.11016)
		(end 54.218586 -292.960298)
		(width 0.14478)
		(layer "In11.Cu")
		(net "M_F_CPU1_SB_DQ<9>")
	)
	(segment
		(start 43.158918 -292.11016)
		(end 43.477942 -292.429184)
		(width 0.14478)
		(layer "In11.Cu")
		(net "M_F_CPU1_SB_DQ<9>")
	)
	(segment
		(start 22.912578 -293.183564)
		(end 22.912578 -292.73246)
		(width 0.14478)
		(layer "In11.Cu")
		(net "M_F_CPU1_SB_DQ<9>")
	)
	(segment
		(start 85.89264 -280.105104)
		(end 85.914992 -280.021792)
		(width 0.0889)
		(layer "In11.Cu")
		(net "M_F_CPU1_SB_DQ<9>")
	)
	(segment
		(start 35.634168 -292.11016)
		(end 35.955732 -292.431724)
		(width 0.14478)
		(layer "In11.Cu")
		(net "M_F_CPU1_SB_DQ<9>")
	)
	(segment
		(start 48.65624 -293.257224)
		(end 48.953166 -292.960298)
		(width 0.14478)
		(layer "In11.Cu")
		(net "M_F_CPU1_SB_DQ<9>")
	)
	(segment
		(start 21.70811 -292.535356)
		(end 22.519132 -293.346378)
		(width 0.14478)
		(layer "In11.Cu")
		(net "M_F_CPU1_SB_DQ<9>")
	)
	(segment
		(start 23.306024 -292.569646)
		(end 23.468838 -292.73246)
		(width 0.14478)
		(layer "In11.Cu")
		(net "M_F_CPU1_SB_DQ<9>")
	)
	(segment
		(start 70.219316 -281.38374)
		(end 70.444868 -281.158188)
		(width 0.14478)
		(layer "In11.Cu")
		(net "M_F_CPU1_SB_DQ<9>")
	)
	(segment
		(start 69.890132 -281.38374)
		(end 70.219316 -281.38374)
		(width 0.14478)
		(layer "In11.Cu")
		(net "M_F_CPU1_SB_DQ<9>")
	)
	(segment
		(start 48.396906 -293.257224)
		(end 48.65624 -293.257224)
		(width 0.14478)
		(layer "In11.Cu")
		(net "M_F_CPU1_SB_DQ<9>")
	)
	(segment
		(start 47.466758 -292.960298)
		(end 48.09998 -292.960298)
		(width 0.14478)
		(layer "In11.Cu")
		(net "M_F_CPU1_SB_DQ<9>")
	)
	(segment
		(start 68.65874 -282.944316)
		(end 68.884292 -282.718764)
		(width 0.14478)
		(layer "In11.Cu")
		(net "M_F_CPU1_SB_DQ<9>")
	)
	(segment
		(start 71.225156 -280.048716)
		(end 71.520558 -279.753314)
		(width 0.14478)
		(layer "In11.Cu")
		(net "M_F_CPU1_SB_DQ<9>")
	)
	(segment
		(start 44.034202 -292.11016)
		(end 45.424344 -292.11016)
		(width 0.14478)
		(layer "In11.Cu")
		(net "M_F_CPU1_SB_DQ<9>")
	)
	(segment
		(start 23.631652 -293.346378)
		(end 23.862284 -293.346378)
		(width 0.14478)
		(layer "In11.Cu")
		(net "M_F_CPU1_SB_DQ<9>")
	)
	(segment
		(start 68.884292 -282.718764)
		(end 68.884292 -282.38958)
		(width 0.14478)
		(layer "In11.Cu")
		(net "M_F_CPU1_SB_DQ<9>")
	)
	(segment
		(start 49.227994 -292.960298)
		(end 50.078132 -292.11016)
		(width 0.14478)
		(layer "In11.Cu")
		(net "M_F_CPU1_SB_DQ<9>")
	)
	(segment
		(start 70.444868 -281.158188)
		(end 70.444868 -280.829004)
		(width 0.14478)
		(layer "In11.Cu")
		(net "M_F_CPU1_SB_DQ<9>")
	)
	(segment
		(start 76.354686 -279.753314)
		(end 76.492862 -279.89149)
		(width 0.0889)
		(layer "In11.Cu")
		(net "M_F_CPU1_SB_DQ<9>")
	)
	(segment
		(start 54.218586 -292.960298)
		(end 56.746394 -292.960298)
		(width 0.14478)
		(layer "In11.Cu")
		(net "M_F_CPU1_SB_DQ<9>")
	)
	(segment
		(start 59.95035 -291.323522)
		(end 68.329556 -282.944316)
		(width 0.14478)
		(layer "In11.Cu")
		(net "M_F_CPU1_SB_DQ<9>")
	)
	(segment
		(start 76.573126 -279.924764)
		(end 79.362046 -279.924764)
		(width 0.0889)
		(layer "In11.Cu")
		(net "M_F_CPU1_SB_DQ<9>")
	)
	(segment
		(start 42.719244 -292.11016)
		(end 43.158918 -292.11016)
		(width 0.14478)
		(layer "In11.Cu")
		(net "M_F_CPU1_SB_DQ<9>")
	)
	(segment
		(start 33.635442 -293.264844)
		(end 33.939988 -292.960298)
		(width 0.14478)
		(layer "In11.Cu")
		(net "M_F_CPU1_SB_DQ<9>")
	)
	(segment
		(start 70.444868 -280.829004)
		(end 70.67042 -280.603452)
		(width 0.14478)
		(layer "In11.Cu")
		(net "M_F_CPU1_SB_DQ<9>")
	)
	(segment
		(start 39.38524 -293.280084)
		(end 39.621714 -293.280084)
		(width 0.14478)
		(layer "In11.Cu")
		(net "M_F_CPU1_SB_DQ<9>")
	)
	(segment
		(start 82.179668 -280.083768)
		(end 82.18805 -280.078942)
		(width 0.0889)
		(layer "In11.Cu")
		(net "M_F_CPU1_SB_DQ<9>")
	)
	(segment
		(start 24.418544 -292.569646)
		(end 24.809196 -292.960298)
		(width 0.14478)
		(layer "In11.Cu")
		(net "M_F_CPU1_SB_DQ<9>")
	)
	(segment
		(start 24.025098 -293.183564)
		(end 24.025098 -292.73246)
		(width 0.14478)
		(layer "In11.Cu")
		(net "M_F_CPU1_SB_DQ<9>")
	)
	(segment
		(start 31.691326 -293.280084)
		(end 31.9278 -293.280084)
		(width 0.14478)
		(layer "In11.Cu")
		(net "M_F_CPU1_SB_DQ<9>")
	)
	(segment
		(start 36.511992 -292.11016)
		(end 38.006528 -292.11016)
		(width 0.14478)
		(layer "In11.Cu")
		(net "M_F_CPU1_SB_DQ<9>")
	)
	(segment
		(start 45.424344 -292.11016)
		(end 46.274482 -292.960298)
		(width 0.14478)
		(layer "In11.Cu")
		(net "M_F_CPU1_SB_DQ<9>")
	)
	(segment
		(start 39.9415 -292.960298)
		(end 40.66794 -292.960298)
		(width 0.14478)
		(layer "In11.Cu")
		(net "M_F_CPU1_SB_DQ<9>")
	)
	(segment
		(start 57.596532 -292.11016)
		(end 59.59094 -292.11016)
		(width 0.14478)
		(layer "In11.Cu")
		(net "M_F_CPU1_SB_DQ<9>")
	)
	(segment
		(start 82.753962 -280.078942)
		(end 82.762344 -280.083768)
		(width 0.0889)
		(layer "In11.Cu")
		(net "M_F_CPU1_SB_DQ<9>")
	)
	(segment
		(start 48.953166 -292.960298)
		(end 49.227994 -292.960298)
		(width 0.14478)
		(layer "In11.Cu")
		(net "M_F_CPU1_SB_DQ<9>")
	)
	(segment
		(start 59.95035 -291.75075)
		(end 59.95035 -291.323522)
		(width 0.14478)
		(layer "In11.Cu")
		(net "M_F_CPU1_SB_DQ<9>")
	)
	(segment
		(start 23.468838 -292.73246)
		(end 23.468838 -293.183564)
		(width 0.14478)
		(layer "In11.Cu")
		(net "M_F_CPU1_SB_DQ<9>")
	)
	(segment
		(start 71.520558 -279.753314)
		(end 75.968606 -279.753314)
		(width 0.14478)
		(layer "In11.Cu")
		(net "M_F_CPU1_SB_DQ<9>")
	)
	(segment
		(start 41.516046 -292.960298)
		(end 41.869106 -292.960298)
		(width 0.14478)
		(layer "In11.Cu")
		(net "M_F_CPU1_SB_DQ<9>")
	)
	(segment
		(start 68.329556 -282.944316)
		(end 68.65874 -282.944316)
		(width 0.14478)
		(layer "In11.Cu")
		(net "M_F_CPU1_SB_DQ<9>")
	)
	(segment
		(start 35.955732 -292.431724)
		(end 36.190428 -292.431724)
		(width 0.14478)
		(layer "In11.Cu")
		(net "M_F_CPU1_SB_DQ<9>")
	)
	(segment
		(start 69.439028 -282.164028)
		(end 69.66458 -281.938476)
		(width 0.14478)
		(layer "In11.Cu")
		(net "M_F_CPU1_SB_DQ<9>")
	)
	(segment
		(start 24.187912 -292.569646)
		(end 24.418544 -292.569646)
		(width 0.14478)
		(layer "In11.Cu")
		(net "M_F_CPU1_SB_DQ<9>")
	)
	(segment
		(start 75.968606 -279.753314)
		(end 76.354686 -279.753314)
		(width 0.0889)
		(layer "In11.Cu")
		(net "M_F_CPU1_SB_DQ<9>")
	)
	(segment
		(start 46.598332 -292.960298)
		(end 46.910498 -293.272464)
		(width 0.14478)
		(layer "In11.Cu")
		(net "M_F_CPU1_SB_DQ<9>")
	)
	(segment
		(start 23.862284 -293.346378)
		(end 24.025098 -293.183564)
		(width 0.14478)
		(layer "In11.Cu")
		(net "M_F_CPU1_SB_DQ<9>")
	)
	(segment
		(start 22.912578 -292.73246)
		(end 23.075392 -292.569646)
		(width 0.14478)
		(layer "In11.Cu")
		(net "M_F_CPU1_SB_DQ<9>")
	)
	(segment
		(start 70.67042 -280.603452)
		(end 70.999604 -280.603452)
		(width 0.14478)
		(layer "In11.Cu")
		(net "M_F_CPU1_SB_DQ<9>")
	)
	(segment
		(start 41.869106 -292.960298)
		(end 42.719244 -292.11016)
		(width 0.14478)
		(layer "In11.Cu")
		(net "M_F_CPU1_SB_DQ<9>")
	)
	(segment
		(start 39.621714 -293.280084)
		(end 39.9415 -292.960298)
		(width 0.14478)
		(layer "In11.Cu")
		(net "M_F_CPU1_SB_DQ<9>")
	)
	(segment
		(start 33.079182 -292.960298)
		(end 33.383728 -293.264844)
		(width 0.14478)
		(layer "In11.Cu")
		(net "M_F_CPU1_SB_DQ<9>")
	)
	(segment
		(start 69.66458 -281.938476)
		(end 69.66458 -281.609292)
		(width 0.14478)
		(layer "In11.Cu")
		(net "M_F_CPU1_SB_DQ<9>")
	)
	(segment
		(start 33.383728 -293.264844)
		(end 33.635442 -293.264844)
		(width 0.14478)
		(layer "In11.Cu")
		(net "M_F_CPU1_SB_DQ<9>")
	)
	(segment
		(start 31.9278 -293.280084)
		(end 32.247586 -292.960298)
		(width 0.14478)
		(layer "In11.Cu")
		(net "M_F_CPU1_SB_DQ<9>")
	)
	(segment
		(start 46.910498 -293.272464)
		(end 47.154592 -293.272464)
		(width 0.14478)
		(layer "In11.Cu")
		(net "M_F_CPU1_SB_DQ<9>")
	)
	(segment
		(start 46.274482 -292.960298)
		(end 46.598332 -292.960298)
		(width 0.14478)
		(layer "In11.Cu")
		(net "M_F_CPU1_SB_DQ<9>")
	)
	(segment
		(start 30.335728 -292.11016)
		(end 31.185866 -292.960298)
		(width 0.14478)
		(layer "In11.Cu")
		(net "M_F_CPU1_SB_DQ<9>")
	)
	(segment
		(start 26.883106 -292.960298)
		(end 27.733244 -292.11016)
		(width 0.14478)
		(layer "In11.Cu")
		(net "M_F_CPU1_SB_DQ<9>")
	)
	(segment
		(start 71.225156 -280.3779)
		(end 71.225156 -280.048716)
		(width 0.14478)
		(layer "In11.Cu")
		(net "M_F_CPU1_SB_DQ<9>")
	)
	(segment
		(start 31.37154 -292.960298)
		(end 31.691326 -293.280084)
		(width 0.14478)
		(layer "In11.Cu")
		(net "M_F_CPU1_SB_DQ<9>")
	)
	(segment
		(start 41.2242 -293.252144)
		(end 41.516046 -292.960298)
		(width 0.14478)
		(layer "In11.Cu")
		(net "M_F_CPU1_SB_DQ<9>")
	)
	(segment
		(start 83.694016 -280.078942)
		(end 83.702398 -280.083768)
		(width 0.0889)
		(layer "In11.Cu")
		(net "M_F_CPU1_SB_DQ<9>")
	)
	(segment
		(start 36.190428 -292.431724)
		(end 36.511992 -292.11016)
		(width 0.14478)
		(layer "In11.Cu")
		(net "M_F_CPU1_SB_DQ<9>")
	)
	(segment
		(start 31.185866 -292.960298)
		(end 31.37154 -292.960298)
		(width 0.14478)
		(layer "In11.Cu")
		(net "M_F_CPU1_SB_DQ<9>")
	)
	(segment
		(start 22.749764 -293.346378)
		(end 22.912578 -293.183564)
		(width 0.14478)
		(layer "In11.Cu")
		(net "M_F_CPU1_SB_DQ<9>")
	)
	(segment
		(start 43.715178 -292.429184)
		(end 44.034202 -292.11016)
		(width 0.14478)
		(layer "In11.Cu")
		(net "M_F_CPU1_SB_DQ<9>")
	)
	(segment
		(start 35.327844 -292.11016)
		(end 35.634168 -292.11016)
		(width 0.14478)
		(layer "In11.Cu")
		(net "M_F_CPU1_SB_DQ<9>")
	)
	(segment
		(start 27.733244 -292.11016)
		(end 30.335728 -292.11016)
		(width 0.14478)
		(layer "In11.Cu")
		(net "M_F_CPU1_SB_DQ<9>")
	)
	(segment
		(start 38.006528 -292.11016)
		(end 38.856666 -292.960298)
		(width 0.14478)
		(layer "In11.Cu")
		(net "M_F_CPU1_SB_DQ<9>")
	)
	(segment
		(start 34.477706 -292.960298)
		(end 35.327844 -292.11016)
		(width 0.14478)
		(layer "In11.Cu")
		(net "M_F_CPU1_SB_DQ<9>")
	)
	(segment
		(start 68.884292 -282.38958)
		(end 69.109844 -282.164028)
		(width 0.14478)
		(layer "In11.Cu")
		(net "M_F_CPU1_SB_DQ<9>")
	)
	(segment
		(start 70.999604 -280.603452)
		(end 71.225156 -280.3779)
		(width 0.14478)
		(layer "In11.Cu")
		(net "M_F_CPU1_SB_DQ<9>")
	)
	(segment
		(start 24.809196 -292.960298)
		(end 26.883106 -292.960298)
		(width 0.14478)
		(layer "In11.Cu")
		(net "M_F_CPU1_SB_DQ<9>")
	)
	(segment
		(start 23.075392 -292.569646)
		(end 23.306024 -292.569646)
		(width 0.14478)
		(layer "In11.Cu")
		(net "M_F_CPU1_SB_DQ<9>")
	)
	(segment
		(start 40.66794 -292.960298)
		(end 40.959786 -293.252144)
		(width 0.14478)
		(layer "In11.Cu")
		(net "M_F_CPU1_SB_DQ<9>")
	)
	(segment
		(start 43.477942 -292.429184)
		(end 43.715178 -292.429184)
		(width 0.14478)
		(layer "In11.Cu")
		(net "M_F_CPU1_SB_DQ<9>")
	)
	(segment
		(start 85.914992 -280.021792)
		(end 85.761068 -279.756362)
		(width 0.0889)
		(layer "In11.Cu")
		(net "M_F_CPU1_SB_DQ<9>")
	)
	(segment
		(start 32.247586 -292.960298)
		(end 33.079182 -292.960298)
		(width 0.14478)
		(layer "In11.Cu")
		(net "M_F_CPU1_SB_DQ<9>")
	)
	(segment
		(start 22.519132 -293.346378)
		(end 22.749764 -293.346378)
		(width 0.14478)
		(layer "In11.Cu")
		(net "M_F_CPU1_SB_DQ<9>")
	)
	(segment
		(start 56.746394 -292.960298)
		(end 57.596532 -292.11016)
		(width 0.14478)
		(layer "In11.Cu")
		(net "M_F_CPU1_SB_DQ<9>")
	)
	(segment
		(start 48.09998 -292.960298)
		(end 48.396906 -293.257224)
		(width 0.14478)
		(layer "In11.Cu")
		(net "M_F_CPU1_SB_DQ<9>")
	)
	(segment
		(start 59.59094 -292.11016)
		(end 59.95035 -291.75075)
		(width 0.14478)
		(layer "In11.Cu")
		(net "M_F_CPU1_SB_DQ<9>")
	)
	(segment
		(start 50.078132 -292.11016)
		(end 53.368448 -292.11016)
		(width 0.14478)
		(layer "In11.Cu")
		(net "M_F_CPU1_SB_DQ<9>")
	)
	(segment
		(start 24.025098 -292.73246)
		(end 24.187912 -292.569646)
		(width 0.14478)
		(layer "In11.Cu")
		(net "M_F_CPU1_SB_DQ<9>")
	)
	(segment
		(start 69.66458 -281.609292)
		(end 69.890132 -281.38374)
		(width 0.14478)
		(layer "In11.Cu")
		(net "M_F_CPU1_SB_DQ<9>")
	)
	(segment
		(start 40.959786 -293.252144)
		(end 41.2242 -293.252144)
		(width 0.14478)
		(layer "In11.Cu")
		(net "M_F_CPU1_SB_DQ<9>")
	)
	(segment
		(start 47.154592 -293.272464)
		(end 47.466758 -292.960298)
		(width 0.14478)
		(layer "In11.Cu")
		(net "M_F_CPU1_SB_DQ<9>")
	)
	(arc
		(start 80.308196 -280.078942)
		(mid 80.591152 -280.002765)
		(end 80.874108 -280.078942)
		(width 0.0889)
		(layer "In11.Cu")
		(net "M_F_CPU1_SB_DQ<9>")
	)
	(arc
		(start 79.9338 -280.078942)
		(mid 80.120998 -280.129324)
		(end 80.308196 -280.078942)
		(width 0.0889)
		(layer "In11.Cu")
		(net "M_F_CPU1_SB_DQ<9>")
	)
	(arc
		(start 84.068158 -280.078942)
		(mid 84.351114 -280.002765)
		(end 84.63407 -280.078942)
		(width 0.0889)
		(layer "In11.Cu")
		(net "M_F_CPU1_SB_DQ<9>")
	)
	(arc
		(start 76.492862 -279.89149)
		(mid 76.529673 -279.91615)
		(end 76.573126 -279.924764)
		(width 0.0889)
		(layer "In11.Cu")
		(net "M_F_CPU1_SB_DQ<9>")
	)
	(arc
		(start 82.762344 -280.083768)
		(mid 82.945852 -280.129262)
		(end 83.128104 -280.078942)
		(width 0.0889)
		(layer "In11.Cu")
		(net "M_F_CPU1_SB_DQ<9>")
	)
	(arc
		(start 82.18805 -280.078942)
		(mid 82.471006 -280.002765)
		(end 82.753962 -280.078942)
		(width 0.0889)
		(layer "In11.Cu")
		(net "M_F_CPU1_SB_DQ<9>")
	)
	(arc
		(start 81.247996 -280.078942)
		(mid 81.530952 -280.002765)
		(end 81.813908 -280.078942)
		(width 0.0889)
		(layer "In11.Cu")
		(net "M_F_CPU1_SB_DQ<9>")
	)
	(arc
		(start 85.57387 -280.078942)
		(mid 85.730308 -280.127913)
		(end 85.89264 -280.105104)
		(width 0.0889)
		(layer "In11.Cu")
		(net "M_F_CPU1_SB_DQ<9>")
	)
	(arc
		(start 84.63407 -280.078942)
		(mid 84.821014 -280.129197)
		(end 85.007958 -280.078942)
		(width 0.0889)
		(layer "In11.Cu")
		(net "M_F_CPU1_SB_DQ<9>")
	)
	(arc
		(start 80.874108 -280.078942)
		(mid 81.061052 -280.129197)
		(end 81.247996 -280.078942)
		(width 0.0889)
		(layer "In11.Cu")
		(net "M_F_CPU1_SB_DQ<9>")
	)
	(arc
		(start 79.362046 -279.924764)
		(mid 79.658133 -279.963987)
		(end 79.9338 -280.078942)
		(width 0.0889)
		(layer "In11.Cu")
		(net "M_F_CPU1_SB_DQ<9>")
	)
	(arc
		(start 85.007958 -280.078942)
		(mid 85.290914 -280.002765)
		(end 85.57387 -280.078942)
		(width 0.0889)
		(layer "In11.Cu")
		(net "M_F_CPU1_SB_DQ<9>")
	)
	(arc
		(start 81.813908 -280.078942)
		(mid 81.996159 -280.129292)
		(end 82.179668 -280.083768)
		(width 0.0889)
		(layer "In11.Cu")
		(net "M_F_CPU1_SB_DQ<9>")
	)
	(arc
		(start 83.702398 -280.083768)
		(mid 83.885906 -280.129262)
		(end 84.068158 -280.078942)
		(width 0.0889)
		(layer "In11.Cu")
		(net "M_F_CPU1_SB_DQ<9>")
	)
	(arc
		(start 83.128104 -280.078942)
		(mid 83.41106 -280.002765)
		(end 83.694016 -280.078942)
		(width 0.0889)
		(layer "In11.Cu")
		(net "M_F_CPU1_SB_DQ<9>")
	)
	(segment
		(start 84.817966 -278.680418)
		(end 84.351114 -278.946356)
		(width 0.10668)
		(layer "F.Cu")
		(net "M_F_CPU1_SB_DQ<8>")
	)
	(segment
		(start 84.482686 -279.295098)
		(end 84.505038 -279.211786)
		(width 0.0889)
		(layer "In11.Cu")
		(net "M_F_CPU1_SB_DQ<8>")
	)
	(segment
		(start 56.78932 -290.957254)
		(end 56.789574 -290.75253)
		(width 0.14478)
		(layer "In11.Cu")
		(net "M_F_CPU1_SB_DQ<8>")
	)
	(segment
		(start 54.972966 -291.26053)
		(end 55.28564 -291.573204)
		(width 0.14478)
		(layer "In11.Cu")
		(net "M_F_CPU1_SB_DQ<8>")
	)
	(segment
		(start 23.454106 -291.46881)
		(end 23.61692 -291.631624)
		(width 0.14478)
		(layer "In11.Cu")
		(net "M_F_CPU1_SB_DQ<8>")
	)
	(segment
		(start 23.454106 -291.13607)
		(end 23.454106 -291.46881)
		(width 0.14478)
		(layer "In11.Cu")
		(net "M_F_CPU1_SB_DQ<8>")
	)
	(segment
		(start 49.328832 -291.573204)
		(end 50.491644 -290.410392)
		(width 0.14478)
		(layer "In11.Cu")
		(net "M_F_CPU1_SB_DQ<8>")
	)
	(segment
		(start 39.4208 -291.26053)
		(end 41.23182 -291.26053)
		(width 0.14478)
		(layer "In11.Cu")
		(net "M_F_CPU1_SB_DQ<8>")
	)
	(segment
		(start 55.529226 -291.573204)
		(end 55.8419 -291.26053)
		(width 0.14478)
		(layer "In11.Cu")
		(net "M_F_CPU1_SB_DQ<8>")
	)
	(segment
		(start 23.06066 -290.973256)
		(end 23.291292 -290.973256)
		(width 0.14478)
		(layer "In11.Cu")
		(net "M_F_CPU1_SB_DQ<8>")
	)
	(segment
		(start 58.873644 -290.717224)
		(end 59.180476 -290.410392)
		(width 0.14478)
		(layer "In11.Cu")
		(net "M_F_CPU1_SB_DQ<8>")
	)
	(segment
		(start 78.081124 -278.843994)
		(end 78.447138 -279.210008)
		(width 0.0889)
		(layer "In11.Cu")
		(net "M_F_CPU1_SB_DQ<8>")
	)
	(segment
		(start 24.010366 -291.13607)
		(end 24.17318 -290.973256)
		(width 0.14478)
		(layer "In11.Cu")
		(net "M_F_CPU1_SB_DQ<8>")
	)
	(segment
		(start 59.59094 -290.410392)
		(end 71.157338 -278.843994)
		(width 0.14478)
		(layer "In11.Cu")
		(net "M_F_CPU1_SB_DQ<8>")
	)
	(segment
		(start 51.700176 -290.410392)
		(end 53.010308 -290.410392)
		(width 0.14478)
		(layer "In11.Cu")
		(net "M_F_CPU1_SB_DQ<8>")
	)
	(segment
		(start 31.744666 -291.573204)
		(end 32.05734 -291.26053)
		(width 0.14478)
		(layer "In11.Cu")
		(net "M_F_CPU1_SB_DQ<8>")
	)
	(segment
		(start 41.539414 -291.568124)
		(end 41.78808 -291.568124)
		(width 0.14478)
		(layer "In11.Cu")
		(net "M_F_CPU1_SB_DQ<8>")
	)
	(segment
		(start 53.914548 -290.582604)
		(end 54.099968 -290.768024)
		(width 0.14478)
		(layer "In11.Cu")
		(net "M_F_CPU1_SB_DQ<8>")
	)
	(segment
		(start 53.010308 -290.410392)
		(end 53.34381 -290.743894)
		(width 0.14478)
		(layer "In11.Cu")
		(net "M_F_CPU1_SB_DQ<8>")
	)
	(segment
		(start 56.966866 -291.1348)
		(end 56.78932 -290.957254)
		(width 0.14478)
		(layer "In11.Cu")
		(net "M_F_CPU1_SB_DQ<8>")
	)
	(segment
		(start 83.589622 -279.273762)
		(end 83.598004 -279.268936)
		(width 0.0889)
		(layer "In11.Cu")
		(net "M_F_CPU1_SB_DQ<8>")
	)
	(segment
		(start 34.224214 -291.499544)
		(end 34.54146 -291.499544)
		(width 0.14478)
		(layer "In11.Cu")
		(net "M_F_CPU1_SB_DQ<8>")
	)
	(segment
		(start 47.045372 -291.26053)
		(end 48.772572 -291.26053)
		(width 0.14478)
		(layer "In11.Cu")
		(net "M_F_CPU1_SB_DQ<8>")
	)
	(segment
		(start 56.966866 -291.339524)
		(end 56.966866 -291.1348)
		(width 0.14478)
		(layer "In11.Cu")
		(net "M_F_CPU1_SB_DQ<8>")
	)
	(segment
		(start 53.938678 -291.134038)
		(end 53.938678 -291.338762)
		(width 0.14478)
		(layer "In11.Cu")
		(net "M_F_CPU1_SB_DQ<8>")
	)
	(segment
		(start 21.70811 -290.835334)
		(end 22.5044 -291.631624)
		(width 0.14478)
		(layer "In11.Cu")
		(net "M_F_CPU1_SB_DQ<8>")
	)
	(segment
		(start 26.232358 -291.483288)
		(end 26.232358 -291.133276)
		(width 0.14478)
		(layer "In11.Cu")
		(net "M_F_CPU1_SB_DQ<8>")
	)
	(segment
		(start 26.915872 -291.26053)
		(end 27.211274 -291.26053)
		(width 0.14478)
		(layer "In11.Cu")
		(net "M_F_CPU1_SB_DQ<8>")
	)
	(segment
		(start 48.772572 -291.26053)
		(end 49.085246 -291.573204)
		(width 0.14478)
		(layer "In11.Cu")
		(net "M_F_CPU1_SB_DQ<8>")
	)
	(segment
		(start 33.111694 -291.499544)
		(end 33.42894 -291.499544)
		(width 0.14478)
		(layer "In11.Cu")
		(net "M_F_CPU1_SB_DQ<8>")
	)
	(segment
		(start 84.505038 -279.211786)
		(end 84.351114 -278.946356)
		(width 0.0889)
		(layer "In11.Cu")
		(net "M_F_CPU1_SB_DQ<8>")
	)
	(segment
		(start 51.143916 -290.696904)
		(end 51.413664 -290.696904)
		(width 0.14478)
		(layer "In11.Cu")
		(net "M_F_CPU1_SB_DQ<8>")
	)
	(segment
		(start 56.974994 -290.56711)
		(end 57.179718 -290.56711)
		(width 0.14478)
		(layer "In11.Cu")
		(net "M_F_CPU1_SB_DQ<8>")
	)
	(segment
		(start 23.847552 -291.631624)
		(end 24.010366 -291.46881)
		(width 0.14478)
		(layer "In11.Cu")
		(net "M_F_CPU1_SB_DQ<8>")
	)
	(segment
		(start 76.042266 -278.843994)
		(end 78.081124 -278.843994)
		(width 0.0889)
		(layer "In11.Cu")
		(net "M_F_CPU1_SB_DQ<8>")
	)
	(segment
		(start 32.87268 -291.26053)
		(end 33.111694 -291.499544)
		(width 0.14478)
		(layer "In11.Cu")
		(net "M_F_CPU1_SB_DQ<8>")
	)
	(segment
		(start 39.115746 -291.565584)
		(end 39.4208 -291.26053)
		(width 0.14478)
		(layer "In11.Cu")
		(net "M_F_CPU1_SB_DQ<8>")
	)
	(segment
		(start 24.010366 -291.46881)
		(end 24.010366 -291.13607)
		(width 0.14478)
		(layer "In11.Cu")
		(net "M_F_CPU1_SB_DQ<8>")
	)
	(segment
		(start 58.317384 -290.410392)
		(end 58.624216 -290.717224)
		(width 0.14478)
		(layer "In11.Cu")
		(net "M_F_CPU1_SB_DQ<8>")
	)
	(segment
		(start 41.78808 -291.568124)
		(end 42.945812 -290.410392)
		(width 0.14478)
		(layer "In11.Cu")
		(net "M_F_CPU1_SB_DQ<8>")
	)
	(segment
		(start 23.291292 -290.973256)
		(end 23.454106 -291.13607)
		(width 0.14478)
		(layer "In11.Cu")
		(net "M_F_CPU1_SB_DQ<8>")
	)
	(segment
		(start 53.34381 -290.743894)
		(end 53.548534 -290.743894)
		(width 0.14478)
		(layer "In11.Cu")
		(net "M_F_CPU1_SB_DQ<8>")
	)
	(segment
		(start 24.403812 -290.973256)
		(end 24.691086 -291.26053)
		(width 0.14478)
		(layer "In11.Cu")
		(net "M_F_CPU1_SB_DQ<8>")
	)
	(segment
		(start 71.157338 -278.843994)
		(end 76.042266 -278.843994)
		(width 0.14478)
		(layer "In11.Cu")
		(net "M_F_CPU1_SB_DQ<8>")
	)
	(segment
		(start 34.54146 -291.499544)
		(end 35.630612 -290.410392)
		(width 0.14478)
		(layer "In11.Cu")
		(net "M_F_CPU1_SB_DQ<8>")
	)
	(segment
		(start 57.895998 -290.410392)
		(end 58.317384 -290.410392)
		(width 0.14478)
		(layer "In11.Cu")
		(net "M_F_CPU1_SB_DQ<8>")
	)
	(segment
		(start 53.548534 -290.743894)
		(end 53.709824 -290.582604)
		(width 0.14478)
		(layer "In11.Cu")
		(net "M_F_CPU1_SB_DQ<8>")
	)
	(segment
		(start 26.069544 -291.646102)
		(end 26.232358 -291.483288)
		(width 0.14478)
		(layer "In11.Cu")
		(net "M_F_CPU1_SB_DQ<8>")
	)
	(segment
		(start 41.23182 -291.26053)
		(end 41.539414 -291.568124)
		(width 0.14478)
		(layer "In11.Cu")
		(net "M_F_CPU1_SB_DQ<8>")
	)
	(segment
		(start 78.447138 -279.210008)
		(end 78.447392 -279.210008)
		(width 0.0889)
		(layer "In11.Cu")
		(net "M_F_CPU1_SB_DQ<8>")
	)
	(segment
		(start 56.789574 -290.75253)
		(end 56.974994 -290.56711)
		(width 0.14478)
		(layer "In11.Cu")
		(net "M_F_CPU1_SB_DQ<8>")
	)
	(segment
		(start 37.709348 -290.410392)
		(end 38.86454 -291.565584)
		(width 0.14478)
		(layer "In11.Cu")
		(net "M_F_CPU1_SB_DQ<8>")
	)
	(segment
		(start 54.416706 -291.573204)
		(end 54.72938 -291.26053)
		(width 0.14478)
		(layer "In11.Cu")
		(net "M_F_CPU1_SB_DQ<8>")
	)
	(segment
		(start 54.099968 -290.768024)
		(end 54.099968 -290.972748)
		(width 0.14478)
		(layer "In11.Cu")
		(net "M_F_CPU1_SB_DQ<8>")
	)
	(segment
		(start 24.17318 -290.973256)
		(end 24.403812 -290.973256)
		(width 0.14478)
		(layer "In11.Cu")
		(net "M_F_CPU1_SB_DQ<8>")
	)
	(segment
		(start 35.630612 -290.410392)
		(end 37.709348 -290.410392)
		(width 0.14478)
		(layer "In11.Cu")
		(net "M_F_CPU1_SB_DQ<8>")
	)
	(segment
		(start 38.86454 -291.565584)
		(end 39.115746 -291.565584)
		(width 0.14478)
		(layer "In11.Cu")
		(net "M_F_CPU1_SB_DQ<8>")
	)
	(segment
		(start 45.32376 -290.410392)
		(end 46.489112 -291.575744)
		(width 0.14478)
		(layer "In11.Cu")
		(net "M_F_CPU1_SB_DQ<8>")
	)
	(segment
		(start 53.938678 -291.338762)
		(end 54.17312 -291.573204)
		(width 0.14478)
		(layer "In11.Cu")
		(net "M_F_CPU1_SB_DQ<8>")
	)
	(segment
		(start 50.491644 -290.410392)
		(end 50.857404 -290.410392)
		(width 0.14478)
		(layer "In11.Cu")
		(net "M_F_CPU1_SB_DQ<8>")
	)
	(segment
		(start 22.5044 -291.631624)
		(end 22.735032 -291.631624)
		(width 0.14478)
		(layer "In11.Cu")
		(net "M_F_CPU1_SB_DQ<8>")
	)
	(segment
		(start 49.085246 -291.573204)
		(end 49.328832 -291.573204)
		(width 0.14478)
		(layer "In11.Cu")
		(net "M_F_CPU1_SB_DQ<8>")
	)
	(segment
		(start 32.05734 -291.26053)
		(end 32.87268 -291.26053)
		(width 0.14478)
		(layer "In11.Cu")
		(net "M_F_CPU1_SB_DQ<8>")
	)
	(segment
		(start 81.344008 -279.268936)
		(end 81.35239 -279.273762)
		(width 0.0889)
		(layer "In11.Cu")
		(net "M_F_CPU1_SB_DQ<8>")
	)
	(segment
		(start 26.395172 -290.970462)
		(end 26.625804 -290.970462)
		(width 0.14478)
		(layer "In11.Cu")
		(net "M_F_CPU1_SB_DQ<8>")
	)
	(segment
		(start 22.897846 -291.46881)
		(end 22.897846 -291.13607)
		(width 0.14478)
		(layer "In11.Cu")
		(net "M_F_CPU1_SB_DQ<8>")
	)
	(segment
		(start 26.625804 -290.970462)
		(end 26.915872 -291.26053)
		(width 0.14478)
		(layer "In11.Cu")
		(net "M_F_CPU1_SB_DQ<8>")
	)
	(segment
		(start 55.28564 -291.573204)
		(end 55.529226 -291.573204)
		(width 0.14478)
		(layer "In11.Cu")
		(net "M_F_CPU1_SB_DQ<8>")
	)
	(segment
		(start 80.769714 -279.273762)
		(end 80.778096 -279.268936)
		(width 0.0889)
		(layer "In11.Cu")
		(net "M_F_CPU1_SB_DQ<8>")
	)
	(segment
		(start 79.825088 -279.276556)
		(end 79.838804 -279.268682)
		(width 0.0889)
		(layer "In11.Cu")
		(net "M_F_CPU1_SB_DQ<8>")
	)
	(segment
		(start 79.447136 -279.258268)
		(end 79.46517 -279.268936)
		(width 0.0889)
		(layer "In11.Cu")
		(net "M_F_CPU1_SB_DQ<8>")
	)
	(segment
		(start 79.838804 -279.268682)
		(end 79.850742 -279.261824)
		(width 0.0889)
		(layer "In11.Cu")
		(net "M_F_CPU1_SB_DQ<8>")
	)
	(segment
		(start 56.085486 -291.26053)
		(end 56.39816 -291.573204)
		(width 0.14478)
		(layer "In11.Cu")
		(net "M_F_CPU1_SB_DQ<8>")
	)
	(segment
		(start 54.72938 -291.26053)
		(end 54.972966 -291.26053)
		(width 0.14478)
		(layer "In11.Cu")
		(net "M_F_CPU1_SB_DQ<8>")
	)
	(segment
		(start 33.42894 -291.499544)
		(end 33.667954 -291.26053)
		(width 0.14478)
		(layer "In11.Cu")
		(net "M_F_CPU1_SB_DQ<8>")
	)
	(segment
		(start 23.61692 -291.631624)
		(end 23.847552 -291.631624)
		(width 0.14478)
		(layer "In11.Cu")
		(net "M_F_CPU1_SB_DQ<8>")
	)
	(segment
		(start 25.45334 -291.26053)
		(end 25.838912 -291.646102)
		(width 0.14478)
		(layer "In11.Cu")
		(net "M_F_CPU1_SB_DQ<8>")
	)
	(segment
		(start 56.733186 -291.573204)
		(end 56.966866 -291.339524)
		(width 0.14478)
		(layer "In11.Cu")
		(net "M_F_CPU1_SB_DQ<8>")
	)
	(segment
		(start 22.735032 -291.631624)
		(end 22.897846 -291.46881)
		(width 0.14478)
		(layer "In11.Cu")
		(net "M_F_CPU1_SB_DQ<8>")
	)
	(segment
		(start 24.691086 -291.26053)
		(end 25.45334 -291.26053)
		(width 0.14478)
		(layer "In11.Cu")
		(net "M_F_CPU1_SB_DQ<8>")
	)
	(segment
		(start 57.56148 -290.74491)
		(end 57.895998 -290.410392)
		(width 0.14478)
		(layer "In11.Cu")
		(net "M_F_CPU1_SB_DQ<8>")
	)
	(segment
		(start 57.179718 -290.56711)
		(end 57.357264 -290.744656)
		(width 0.14478)
		(layer "In11.Cu")
		(net "M_F_CPU1_SB_DQ<8>")
	)
	(segment
		(start 46.489112 -291.575744)
		(end 46.730158 -291.575744)
		(width 0.14478)
		(layer "In11.Cu")
		(net "M_F_CPU1_SB_DQ<8>")
	)
	(segment
		(start 42.945812 -290.410392)
		(end 45.32376 -290.410392)
		(width 0.14478)
		(layer "In11.Cu")
		(net "M_F_CPU1_SB_DQ<8>")
	)
	(segment
		(start 25.838912 -291.646102)
		(end 26.069544 -291.646102)
		(width 0.14478)
		(layer "In11.Cu")
		(net "M_F_CPU1_SB_DQ<8>")
	)
	(segment
		(start 26.232358 -291.133276)
		(end 26.395172 -290.970462)
		(width 0.14478)
		(layer "In11.Cu")
		(net "M_F_CPU1_SB_DQ<8>")
	)
	(segment
		(start 50.857404 -290.410392)
		(end 51.143916 -290.696904)
		(width 0.14478)
		(layer "In11.Cu")
		(net "M_F_CPU1_SB_DQ<8>")
	)
	(segment
		(start 46.730158 -291.575744)
		(end 47.045372 -291.26053)
		(width 0.14478)
		(layer "In11.Cu")
		(net "M_F_CPU1_SB_DQ<8>")
	)
	(segment
		(start 56.39816 -291.573204)
		(end 56.733186 -291.573204)
		(width 0.14478)
		(layer "In11.Cu")
		(net "M_F_CPU1_SB_DQ<8>")
	)
	(segment
		(start 28.061412 -290.410392)
		(end 30.338268 -290.410392)
		(width 0.14478)
		(layer "In11.Cu")
		(net "M_F_CPU1_SB_DQ<8>")
	)
	(segment
		(start 30.338268 -290.410392)
		(end 31.50108 -291.573204)
		(width 0.14478)
		(layer "In11.Cu")
		(net "M_F_CPU1_SB_DQ<8>")
	)
	(segment
		(start 58.624216 -290.717224)
		(end 58.873644 -290.717224)
		(width 0.14478)
		(layer "In11.Cu")
		(net "M_F_CPU1_SB_DQ<8>")
	)
	(segment
		(start 31.50108 -291.573204)
		(end 31.744666 -291.573204)
		(width 0.14478)
		(layer "In11.Cu")
		(net "M_F_CPU1_SB_DQ<8>")
	)
	(segment
		(start 59.180476 -290.410392)
		(end 59.59094 -290.410392)
		(width 0.14478)
		(layer "In11.Cu")
		(net "M_F_CPU1_SB_DQ<8>")
	)
	(segment
		(start 33.9852 -291.26053)
		(end 34.224214 -291.499544)
		(width 0.14478)
		(layer "In11.Cu")
		(net "M_F_CPU1_SB_DQ<8>")
	)
	(segment
		(start 27.211274 -291.26053)
		(end 28.061412 -290.410392)
		(width 0.14478)
		(layer "In11.Cu")
		(net "M_F_CPU1_SB_DQ<8>")
	)
	(segment
		(start 57.357264 -290.744656)
		(end 57.56148 -290.74491)
		(width 0.14478)
		(layer "In11.Cu")
		(net "M_F_CPU1_SB_DQ<8>")
	)
	(segment
		(start 22.897846 -291.13607)
		(end 23.06066 -290.973256)
		(width 0.14478)
		(layer "In11.Cu")
		(net "M_F_CPU1_SB_DQ<8>")
	)
	(segment
		(start 53.709824 -290.582604)
		(end 53.914548 -290.582604)
		(width 0.14478)
		(layer "In11.Cu")
		(net "M_F_CPU1_SB_DQ<8>")
	)
	(segment
		(start 33.667954 -291.26053)
		(end 33.9852 -291.26053)
		(width 0.14478)
		(layer "In11.Cu")
		(net "M_F_CPU1_SB_DQ<8>")
	)
	(segment
		(start 54.099968 -290.972748)
		(end 53.938678 -291.134038)
		(width 0.14478)
		(layer "In11.Cu")
		(net "M_F_CPU1_SB_DQ<8>")
	)
	(segment
		(start 54.17312 -291.573204)
		(end 54.416706 -291.573204)
		(width 0.14478)
		(layer "In11.Cu")
		(net "M_F_CPU1_SB_DQ<8>")
	)
	(segment
		(start 51.413664 -290.696904)
		(end 51.700176 -290.410392)
		(width 0.14478)
		(layer "In11.Cu")
		(net "M_F_CPU1_SB_DQ<8>")
	)
	(segment
		(start 78.524608 -279.268682)
		(end 78.544674 -279.280112)
		(width 0.0889)
		(layer "In11.Cu")
		(net "M_F_CPU1_SB_DQ<8>")
	)
	(segment
		(start 55.8419 -291.26053)
		(end 56.085486 -291.26053)
		(width 0.14478)
		(layer "In11.Cu")
		(net "M_F_CPU1_SB_DQ<8>")
	)
	(arc
		(start 78.898496 -279.268936)
		(mid 79.17144 -279.192356)
		(end 79.447136 -279.258268)
		(width 0.0889)
		(layer "In11.Cu")
		(net "M_F_CPU1_SB_DQ<8>")
	)
	(arc
		(start 84.163916 -279.268936)
		(mid 84.320354 -279.317907)
		(end 84.482686 -279.295098)
		(width 0.0889)
		(layer "In11.Cu")
		(net "M_F_CPU1_SB_DQ<8>")
	)
	(arc
		(start 78.544674 -279.280112)
		(mid 78.723006 -279.319209)
		(end 78.898496 -279.268936)
		(width 0.0889)
		(layer "In11.Cu")
		(net "M_F_CPU1_SB_DQ<8>")
	)
	(arc
		(start 82.284062 -279.268936)
		(mid 82.471006 -279.319191)
		(end 82.65795 -279.268936)
		(width 0.0889)
		(layer "In11.Cu")
		(net "M_F_CPU1_SB_DQ<8>")
	)
	(arc
		(start 83.598004 -279.268936)
		(mid 83.88096 -279.192759)
		(end 84.163916 -279.268936)
		(width 0.0889)
		(layer "In11.Cu")
		(net "M_F_CPU1_SB_DQ<8>")
	)
	(arc
		(start 79.46517 -279.268936)
		(mid 79.644157 -279.319106)
		(end 79.825088 -279.276556)
		(width 0.0889)
		(layer "In11.Cu")
		(net "M_F_CPU1_SB_DQ<8>")
	)
	(arc
		(start 80.778096 -279.268936)
		(mid 81.061052 -279.192759)
		(end 81.344008 -279.268936)
		(width 0.0889)
		(layer "In11.Cu")
		(net "M_F_CPU1_SB_DQ<8>")
	)
	(arc
		(start 82.65795 -279.268936)
		(mid 82.940906 -279.192759)
		(end 83.223862 -279.268936)
		(width 0.0889)
		(layer "In11.Cu")
		(net "M_F_CPU1_SB_DQ<8>")
	)
	(arc
		(start 83.223862 -279.268936)
		(mid 83.406113 -279.319286)
		(end 83.589622 -279.273762)
		(width 0.0889)
		(layer "In11.Cu")
		(net "M_F_CPU1_SB_DQ<8>")
	)
	(arc
		(start 80.403954 -279.268936)
		(mid 80.586205 -279.319286)
		(end 80.769714 -279.273762)
		(width 0.0889)
		(layer "In11.Cu")
		(net "M_F_CPU1_SB_DQ<8>")
	)
	(arc
		(start 81.35239 -279.273762)
		(mid 81.535898 -279.319256)
		(end 81.71815 -279.268936)
		(width 0.0889)
		(layer "In11.Cu")
		(net "M_F_CPU1_SB_DQ<8>")
	)
	(arc
		(start 78.447392 -279.210008)
		(mid 78.484088 -279.241861)
		(end 78.524608 -279.268682)
		(width 0.0889)
		(layer "In11.Cu")
		(net "M_F_CPU1_SB_DQ<8>")
	)
	(arc
		(start 81.71815 -279.268936)
		(mid 82.001106 -279.192759)
		(end 82.284062 -279.268936)
		(width 0.0889)
		(layer "In11.Cu")
		(net "M_F_CPU1_SB_DQ<8>")
	)
	(arc
		(start 79.850742 -279.261824)
		(mid 80.128276 -279.192843)
		(end 80.403954 -279.268936)
		(width 0.0889)
		(layer "In11.Cu")
		(net "M_F_CPU1_SB_DQ<8>")
	)
	(segment
		(start 86.69782 -278.680418)
		(end 86.230968 -278.946356)
		(width 0.10668)
		(layer "F.Cu")
		(net "M_F_CPU1_SB_DQ<7>")
	)
	(segment
		(start 53.543962 -290.015168)
		(end 57.449974 -290.015168)
		(width 0.14478)
		(layer "In11.Cu")
		(net "M_F_CPU1_SB_DQ<7>")
	)
	(segment
		(start 19.619976 -289.963606)
		(end 19.619976 -290.265612)
		(width 0.14478)
		(layer "In11.Cu")
		(net "M_F_CPU1_SB_DQ<7>")
	)
	(segment
		(start 19.764756 -290.410392)
		(end 20.02663 -290.410392)
		(width 0.14478)
		(layer "In11.Cu")
		(net "M_F_CPU1_SB_DQ<7>")
	)
	(segment
		(start 17.608042 -289.98545)
		(end 18.032984 -290.410392)
		(width 0.14478)
		(layer "In11.Cu")
		(net "M_F_CPU1_SB_DQ<7>")
	)
	(segment
		(start 18.032984 -290.410392)
		(end 18.923762 -290.410392)
		(width 0.14478)
		(layer "In11.Cu")
		(net "M_F_CPU1_SB_DQ<7>")
	)
	(segment
		(start 19.068542 -290.265612)
		(end 19.068542 -289.963606)
		(width 0.14478)
		(layer "In11.Cu")
		(net "M_F_CPU1_SB_DQ<7>")
	)
	(segment
		(start 18.923762 -290.410392)
		(end 19.068542 -290.265612)
		(width 0.14478)
		(layer "In11.Cu")
		(net "M_F_CPU1_SB_DQ<7>")
	)
	(segment
		(start 19.213322 -289.818826)
		(end 19.475196 -289.818826)
		(width 0.14478)
		(layer "In11.Cu")
		(net "M_F_CPU1_SB_DQ<7>")
	)
	(segment
		(start 59.634374 -289.560254)
		(end 70.906894 -278.287734)
		(width 0.14478)
		(layer "In11.Cu")
		(net "M_F_CPU1_SB_DQ<7>")
	)
	(segment
		(start 57.449974 -290.015168)
		(end 57.904888 -289.560254)
		(width 0.14478)
		(layer "In11.Cu")
		(net "M_F_CPU1_SB_DQ<7>")
	)
	(segment
		(start 80.769714 -278.61895)
		(end 80.778096 -278.623776)
		(width 0.0889)
		(layer "In11.Cu")
		(net "M_F_CPU1_SB_DQ<7>")
	)
	(segment
		(start 76.867258 -278.451564)
		(end 79.200502 -278.451564)
		(width 0.0889)
		(layer "In11.Cu")
		(net "M_F_CPU1_SB_DQ<7>")
	)
	(segment
		(start 85.981032 -278.655526)
		(end 86.077044 -278.680926)
		(width 0.0889)
		(layer "In11.Cu")
		(net "M_F_CPU1_SB_DQ<7>")
	)
	(segment
		(start 20.02663 -290.410392)
		(end 20.17141 -290.265612)
		(width 0.14478)
		(layer "In11.Cu")
		(net "M_F_CPU1_SB_DQ<7>")
	)
	(segment
		(start 85.10397 -278.623776)
		(end 85.112352 -278.61895)
		(width 0.0889)
		(layer "In11.Cu")
		(net "M_F_CPU1_SB_DQ<7>")
	)
	(segment
		(start 57.904888 -289.560254)
		(end 59.634374 -289.560254)
		(width 0.14478)
		(layer "In11.Cu")
		(net "M_F_CPU1_SB_DQ<7>")
	)
	(segment
		(start 29.951172 -289.560254)
		(end 32.003746 -290.410392)
		(width 0.14478)
		(layer "In11.Cu")
		(net "M_F_CPU1_SB_DQ<7>")
	)
	(segment
		(start 84.529676 -278.61895)
		(end 84.538058 -278.623776)
		(width 0.0889)
		(layer "In11.Cu")
		(net "M_F_CPU1_SB_DQ<7>")
	)
	(segment
		(start 48.96739 -290.410392)
		(end 51.019964 -289.560254)
		(width 0.14478)
		(layer "In11.Cu")
		(net "M_F_CPU1_SB_DQ<7>")
	)
	(segment
		(start 19.068542 -289.963606)
		(end 19.213322 -289.818826)
		(width 0.14478)
		(layer "In11.Cu")
		(net "M_F_CPU1_SB_DQ<7>")
	)
	(segment
		(start 39.282878 -290.410392)
		(end 41.373806 -290.410392)
		(width 0.14478)
		(layer "In11.Cu")
		(net "M_F_CPU1_SB_DQ<7>")
	)
	(segment
		(start 20.17141 -289.963606)
		(end 20.31619 -289.818826)
		(width 0.14478)
		(layer "In11.Cu")
		(net "M_F_CPU1_SB_DQ<7>")
	)
	(segment
		(start 80.39354 -278.629872)
		(end 80.403954 -278.623776)
		(width 0.0889)
		(layer "In11.Cu")
		(net "M_F_CPU1_SB_DQ<7>")
	)
	(segment
		(start 52.445666 -289.560254)
		(end 53.543962 -290.015168)
		(width 0.14478)
		(layer "In11.Cu")
		(net "M_F_CPU1_SB_DQ<7>")
	)
	(segment
		(start 20.722844 -289.963606)
		(end 20.722844 -290.265612)
		(width 0.14478)
		(layer "In11.Cu")
		(net "M_F_CPU1_SB_DQ<7>")
	)
	(segment
		(start 46.796198 -290.410392)
		(end 48.96739 -290.410392)
		(width 0.14478)
		(layer "In11.Cu")
		(net "M_F_CPU1_SB_DQ<7>")
	)
	(segment
		(start 19.475196 -289.818826)
		(end 19.619976 -289.963606)
		(width 0.14478)
		(layer "In11.Cu")
		(net "M_F_CPU1_SB_DQ<7>")
	)
	(segment
		(start 81.344008 -278.623776)
		(end 81.35239 -278.61895)
		(width 0.0889)
		(layer "In11.Cu")
		(net "M_F_CPU1_SB_DQ<7>")
	)
	(segment
		(start 19.619976 -290.265612)
		(end 19.764756 -290.410392)
		(width 0.14478)
		(layer "In11.Cu")
		(net "M_F_CPU1_SB_DQ<7>")
	)
	(segment
		(start 51.019964 -289.560254)
		(end 52.445666 -289.560254)
		(width 0.14478)
		(layer "In11.Cu")
		(net "M_F_CPU1_SB_DQ<7>")
	)
	(segment
		(start 83.589622 -278.61895)
		(end 83.598004 -278.623776)
		(width 0.0889)
		(layer "In11.Cu")
		(net "M_F_CPU1_SB_DQ<7>")
	)
	(segment
		(start 70.906894 -278.287734)
		(end 76.034392 -278.287734)
		(width 0.14478)
		(layer "In11.Cu")
		(net "M_F_CPU1_SB_DQ<7>")
	)
	(segment
		(start 37.230304 -289.560254)
		(end 39.282878 -290.410392)
		(width 0.14478)
		(layer "In11.Cu")
		(net "M_F_CPU1_SB_DQ<7>")
	)
	(segment
		(start 36.170616 -289.560254)
		(end 37.230304 -289.560254)
		(width 0.14478)
		(layer "In11.Cu")
		(net "M_F_CPU1_SB_DQ<7>")
	)
	(segment
		(start 28.505404 -289.560254)
		(end 29.951172 -289.560254)
		(width 0.14478)
		(layer "In11.Cu")
		(net "M_F_CPU1_SB_DQ<7>")
	)
	(segment
		(start 26.45283 -290.410392)
		(end 28.505404 -289.560254)
		(width 0.14478)
		(layer "In11.Cu")
		(net "M_F_CPU1_SB_DQ<7>")
	)
	(segment
		(start 43.42638 -289.560254)
		(end 44.743624 -289.560254)
		(width 0.14478)
		(layer "In11.Cu")
		(net "M_F_CPU1_SB_DQ<7>")
	)
	(segment
		(start 20.722844 -290.265612)
		(end 20.867624 -290.410392)
		(width 0.14478)
		(layer "In11.Cu")
		(net "M_F_CPU1_SB_DQ<7>")
	)
	(segment
		(start 20.578064 -289.818826)
		(end 20.722844 -289.963606)
		(width 0.14478)
		(layer "In11.Cu")
		(net "M_F_CPU1_SB_DQ<7>")
	)
	(segment
		(start 41.373806 -290.410392)
		(end 43.42638 -289.560254)
		(width 0.14478)
		(layer "In11.Cu")
		(net "M_F_CPU1_SB_DQ<7>")
	)
	(segment
		(start 20.17141 -290.265612)
		(end 20.17141 -289.963606)
		(width 0.14478)
		(layer "In11.Cu")
		(net "M_F_CPU1_SB_DQ<7>")
	)
	(segment
		(start 20.867624 -290.410392)
		(end 26.45283 -290.410392)
		(width 0.14478)
		(layer "In11.Cu")
		(net "M_F_CPU1_SB_DQ<7>")
	)
	(segment
		(start 34.118042 -290.410392)
		(end 36.170616 -289.560254)
		(width 0.14478)
		(layer "In11.Cu")
		(net "M_F_CPU1_SB_DQ<7>")
	)
	(segment
		(start 76.703428 -278.287734)
		(end 76.867258 -278.451564)
		(width 0.0889)
		(layer "In11.Cu")
		(net "M_F_CPU1_SB_DQ<7>")
	)
	(segment
		(start 44.743624 -289.560254)
		(end 46.796198 -290.410392)
		(width 0.14478)
		(layer "In11.Cu")
		(net "M_F_CPU1_SB_DQ<7>")
	)
	(segment
		(start 32.003746 -290.410392)
		(end 34.118042 -290.410392)
		(width 0.14478)
		(layer "In11.Cu")
		(net "M_F_CPU1_SB_DQ<7>")
	)
	(segment
		(start 76.034392 -278.287734)
		(end 76.703428 -278.287734)
		(width 0.0889)
		(layer "In11.Cu")
		(net "M_F_CPU1_SB_DQ<7>")
	)
	(segment
		(start 86.077044 -278.680926)
		(end 86.230968 -278.946356)
		(width 0.0889)
		(layer "In11.Cu")
		(net "M_F_CPU1_SB_DQ<7>")
	)
	(segment
		(start 20.31619 -289.818826)
		(end 20.578064 -289.818826)
		(width 0.14478)
		(layer "In11.Cu")
		(net "M_F_CPU1_SB_DQ<7>")
	)
	(arc
		(start 81.35239 -278.61895)
		(mid 81.535898 -278.573456)
		(end 81.71815 -278.623776)
		(width 0.0889)
		(layer "In11.Cu")
		(net "M_F_CPU1_SB_DQ<7>")
	)
	(arc
		(start 83.598004 -278.623776)
		(mid 83.88096 -278.699953)
		(end 84.163916 -278.623776)
		(width 0.0889)
		(layer "In11.Cu")
		(net "M_F_CPU1_SB_DQ<7>")
	)
	(arc
		(start 84.538058 -278.623776)
		(mid 84.821014 -278.699953)
		(end 85.10397 -278.623776)
		(width 0.0889)
		(layer "In11.Cu")
		(net "M_F_CPU1_SB_DQ<7>")
	)
	(arc
		(start 82.284062 -278.623776)
		(mid 82.471006 -278.573521)
		(end 82.65795 -278.623776)
		(width 0.0889)
		(layer "In11.Cu")
		(net "M_F_CPU1_SB_DQ<7>")
	)
	(arc
		(start 85.478112 -278.623776)
		(mid 85.725825 -278.698996)
		(end 85.981032 -278.655526)
		(width 0.0889)
		(layer "In11.Cu")
		(net "M_F_CPU1_SB_DQ<7>")
	)
	(arc
		(start 83.223862 -278.623776)
		(mid 83.406113 -278.573426)
		(end 83.589622 -278.61895)
		(width 0.0889)
		(layer "In11.Cu")
		(net "M_F_CPU1_SB_DQ<7>")
	)
	(arc
		(start 81.71815 -278.623776)
		(mid 82.001106 -278.699953)
		(end 82.284062 -278.623776)
		(width 0.0889)
		(layer "In11.Cu")
		(net "M_F_CPU1_SB_DQ<7>")
	)
	(arc
		(start 79.837788 -278.623776)
		(mid 80.114855 -278.700047)
		(end 80.39354 -278.629872)
		(width 0.0889)
		(layer "In11.Cu")
		(net "M_F_CPU1_SB_DQ<7>")
	)
	(arc
		(start 80.778096 -278.623776)
		(mid 81.061052 -278.699953)
		(end 81.344008 -278.623776)
		(width 0.0889)
		(layer "In11.Cu")
		(net "M_F_CPU1_SB_DQ<7>")
	)
	(arc
		(start 82.65795 -278.623776)
		(mid 82.940906 -278.699953)
		(end 83.223862 -278.623776)
		(width 0.0889)
		(layer "In11.Cu")
		(net "M_F_CPU1_SB_DQ<7>")
	)
	(arc
		(start 80.403954 -278.623776)
		(mid 80.586205 -278.573426)
		(end 80.769714 -278.61895)
		(width 0.0889)
		(layer "In11.Cu")
		(net "M_F_CPU1_SB_DQ<7>")
	)
	(arc
		(start 85.112352 -278.61895)
		(mid 85.29586 -278.573456)
		(end 85.478112 -278.623776)
		(width 0.0889)
		(layer "In11.Cu")
		(net "M_F_CPU1_SB_DQ<7>")
	)
	(arc
		(start 79.200502 -278.451564)
		(mid 79.530572 -278.495379)
		(end 79.837788 -278.623776)
		(width 0.0889)
		(layer "In11.Cu")
		(net "M_F_CPU1_SB_DQ<7>")
	)
	(arc
		(start 84.163916 -278.623776)
		(mid 84.346167 -278.573426)
		(end 84.529676 -278.61895)
		(width 0.0889)
		(layer "In11.Cu")
		(net "M_F_CPU1_SB_DQ<7>")
	)
	(segment
		(start 85.287866 -277.870412)
		(end 84.821014 -278.13635)
		(width 0.10668)
		(layer "F.Cu")
		(net "M_F_CPU1_SB_DQ<6>")
	)
	(segment
		(start 20.634452 -288.101786)
		(end 20.779232 -288.246566)
		(width 0.14478)
		(layer "In11.Cu")
		(net "M_F_CPU1_SB_DQ<6>")
	)
	(segment
		(start 77.960982 -277.374858)
		(end 78.476348 -277.890224)
		(width 0.0889)
		(layer "In11.Cu")
		(net "M_F_CPU1_SB_DQ<6>")
	)
	(segment
		(start 19.12493 -288.246566)
		(end 19.26971 -288.101786)
		(width 0.14478)
		(layer "In11.Cu")
		(net "M_F_CPU1_SB_DQ<6>")
	)
	(segment
		(start 79.934308 -277.814024)
		(end 79.950564 -277.804626)
		(width 0.0889)
		(layer "In11.Cu")
		(net "M_F_CPU1_SB_DQ<6>")
	)
	(segment
		(start 35.967924 -287.860232)
		(end 37.582348 -287.860232)
		(width 0.14478)
		(layer "In11.Cu")
		(net "M_F_CPU1_SB_DQ<6>")
	)
	(segment
		(start 28.223972 -287.860232)
		(end 30.14472 -287.860232)
		(width 0.14478)
		(layer "In11.Cu")
		(net "M_F_CPU1_SB_DQ<6>")
	)
	(segment
		(start 20.083018 -288.71037)
		(end 20.227798 -288.56559)
		(width 0.14478)
		(layer "In11.Cu")
		(net "M_F_CPU1_SB_DQ<6>")
	)
	(segment
		(start 18.032984 -288.71037)
		(end 18.98015 -288.71037)
		(width 0.14478)
		(layer "In11.Cu")
		(net "M_F_CPU1_SB_DQ<6>")
	)
	(segment
		(start 20.227798 -288.56559)
		(end 20.227798 -288.246566)
		(width 0.14478)
		(layer "In11.Cu")
		(net "M_F_CPU1_SB_DQ<6>")
	)
	(segment
		(start 27.373834 -288.71037)
		(end 28.223972 -287.860232)
		(width 0.14478)
		(layer "In11.Cu")
		(net "M_F_CPU1_SB_DQ<6>")
	)
	(segment
		(start 30.14472 -287.860232)
		(end 30.994858 -288.71037)
		(width 0.14478)
		(layer "In11.Cu")
		(net "M_F_CPU1_SB_DQ<6>")
	)
	(segment
		(start 17.608042 -288.285428)
		(end 18.032984 -288.71037)
		(width 0.14478)
		(layer "In11.Cu")
		(net "M_F_CPU1_SB_DQ<6>")
	)
	(segment
		(start 45.085 -287.860232)
		(end 45.935138 -288.71037)
		(width 0.14478)
		(layer "In11.Cu")
		(net "M_F_CPU1_SB_DQ<6>")
	)
	(segment
		(start 79.357474 -277.806912)
		(end 79.369158 -277.81377)
		(width 0.0889)
		(layer "In11.Cu")
		(net "M_F_CPU1_SB_DQ<6>")
	)
	(segment
		(start 37.582348 -287.860232)
		(end 38.432486 -288.71037)
		(width 0.14478)
		(layer "In11.Cu")
		(net "M_F_CPU1_SB_DQ<6>")
	)
	(segment
		(start 20.372578 -288.101786)
		(end 20.634452 -288.101786)
		(width 0.14478)
		(layer "In11.Cu")
		(net "M_F_CPU1_SB_DQ<6>")
	)
	(segment
		(start 19.26971 -288.101786)
		(end 19.531584 -288.101786)
		(width 0.14478)
		(layer "In11.Cu")
		(net "M_F_CPU1_SB_DQ<6>")
	)
	(segment
		(start 75.958192 -277.374858)
		(end 77.960982 -277.374858)
		(width 0.0889)
		(layer "In11.Cu")
		(net "M_F_CPU1_SB_DQ<6>")
	)
	(segment
		(start 58.023252 -287.860232)
		(end 60.047886 -287.860232)
		(width 0.14478)
		(layer "In11.Cu")
		(net "M_F_CPU1_SB_DQ<6>")
	)
	(segment
		(start 19.12493 -288.56559)
		(end 19.12493 -288.246566)
		(width 0.14478)
		(layer "In11.Cu")
		(net "M_F_CPU1_SB_DQ<6>")
	)
	(segment
		(start 30.994858 -288.71037)
		(end 35.117786 -288.71037)
		(width 0.14478)
		(layer "In11.Cu")
		(net "M_F_CPU1_SB_DQ<6>")
	)
	(segment
		(start 49.939194 -288.71037)
		(end 50.789332 -287.860232)
		(width 0.14478)
		(layer "In11.Cu")
		(net "M_F_CPU1_SB_DQ<6>")
	)
	(segment
		(start 20.924012 -288.71037)
		(end 27.373834 -288.71037)
		(width 0.14478)
		(layer "In11.Cu")
		(net "M_F_CPU1_SB_DQ<6>")
	)
	(segment
		(start 60.047886 -287.860232)
		(end 70.529704 -277.378414)
		(width 0.14478)
		(layer "In11.Cu")
		(net "M_F_CPU1_SB_DQ<6>")
	)
	(segment
		(start 57.173114 -288.71037)
		(end 58.023252 -287.860232)
		(width 0.14478)
		(layer "In11.Cu")
		(net "M_F_CPU1_SB_DQ<6>")
	)
	(segment
		(start 19.821144 -288.71037)
		(end 20.083018 -288.71037)
		(width 0.14478)
		(layer "In11.Cu")
		(net "M_F_CPU1_SB_DQ<6>")
	)
	(segment
		(start 82.179668 -277.808944)
		(end 82.18805 -277.81377)
		(width 0.0889)
		(layer "In11.Cu")
		(net "M_F_CPU1_SB_DQ<6>")
	)
	(segment
		(start 19.676364 -288.246566)
		(end 19.676364 -288.56559)
		(width 0.14478)
		(layer "In11.Cu")
		(net "M_F_CPU1_SB_DQ<6>")
	)
	(segment
		(start 18.98015 -288.71037)
		(end 19.12493 -288.56559)
		(width 0.14478)
		(layer "In11.Cu")
		(net "M_F_CPU1_SB_DQ<6>")
	)
	(segment
		(start 70.529704 -277.378414)
		(end 75.954636 -277.378414)
		(width 0.14478)
		(layer "In11.Cu")
		(net "M_F_CPU1_SB_DQ<6>")
	)
	(segment
		(start 45.935138 -288.71037)
		(end 49.939194 -288.71037)
		(width 0.14478)
		(layer "In11.Cu")
		(net "M_F_CPU1_SB_DQ<6>")
	)
	(segment
		(start 75.954636 -277.378414)
		(end 75.958192 -277.374858)
		(width 0.0889)
		(layer "In11.Cu")
		(net "M_F_CPU1_SB_DQ<6>")
	)
	(segment
		(start 42.309034 -288.71037)
		(end 43.159172 -287.860232)
		(width 0.14478)
		(layer "In11.Cu")
		(net "M_F_CPU1_SB_DQ<6>")
	)
	(segment
		(start 84.66709 -277.87092)
		(end 84.821014 -278.13635)
		(width 0.0889)
		(layer "In11.Cu")
		(net "M_F_CPU1_SB_DQ<6>")
	)
	(segment
		(start 43.159172 -287.860232)
		(end 45.085 -287.860232)
		(width 0.14478)
		(layer "In11.Cu")
		(net "M_F_CPU1_SB_DQ<6>")
	)
	(segment
		(start 82.753962 -277.81377)
		(end 82.762344 -277.808944)
		(width 0.0889)
		(layer "In11.Cu")
		(net "M_F_CPU1_SB_DQ<6>")
	)
	(segment
		(start 52.60594 -287.860232)
		(end 53.456078 -288.71037)
		(width 0.14478)
		(layer "In11.Cu")
		(net "M_F_CPU1_SB_DQ<6>")
	)
	(segment
		(start 19.531584 -288.101786)
		(end 19.676364 -288.246566)
		(width 0.14478)
		(layer "In11.Cu")
		(net "M_F_CPU1_SB_DQ<6>")
	)
	(segment
		(start 20.227798 -288.246566)
		(end 20.372578 -288.101786)
		(width 0.14478)
		(layer "In11.Cu")
		(net "M_F_CPU1_SB_DQ<6>")
	)
	(segment
		(start 83.694016 -277.81377)
		(end 83.702398 -277.808944)
		(width 0.0889)
		(layer "In11.Cu")
		(net "M_F_CPU1_SB_DQ<6>")
	)
	(segment
		(start 35.117786 -288.71037)
		(end 35.967924 -287.860232)
		(width 0.14478)
		(layer "In11.Cu")
		(net "M_F_CPU1_SB_DQ<6>")
	)
	(segment
		(start 53.456078 -288.71037)
		(end 57.173114 -288.71037)
		(width 0.14478)
		(layer "In11.Cu")
		(net "M_F_CPU1_SB_DQ<6>")
	)
	(segment
		(start 19.676364 -288.56559)
		(end 19.821144 -288.71037)
		(width 0.14478)
		(layer "In11.Cu")
		(net "M_F_CPU1_SB_DQ<6>")
	)
	(segment
		(start 84.571078 -277.84552)
		(end 84.66709 -277.87092)
		(width 0.0889)
		(layer "In11.Cu")
		(net "M_F_CPU1_SB_DQ<6>")
	)
	(segment
		(start 78.476348 -277.890224)
		(end 78.711044 -277.890224)
		(width 0.0889)
		(layer "In11.Cu")
		(net "M_F_CPU1_SB_DQ<6>")
	)
	(segment
		(start 50.789332 -287.860232)
		(end 52.60594 -287.860232)
		(width 0.14478)
		(layer "In11.Cu")
		(net "M_F_CPU1_SB_DQ<6>")
	)
	(segment
		(start 20.779232 -288.56559)
		(end 20.924012 -288.71037)
		(width 0.14478)
		(layer "In11.Cu")
		(net "M_F_CPU1_SB_DQ<6>")
	)
	(segment
		(start 20.779232 -288.246566)
		(end 20.779232 -288.56559)
		(width 0.14478)
		(layer "In11.Cu")
		(net "M_F_CPU1_SB_DQ<6>")
	)
	(segment
		(start 38.432486 -288.71037)
		(end 42.309034 -288.71037)
		(width 0.14478)
		(layer "In11.Cu")
		(net "M_F_CPU1_SB_DQ<6>")
	)
	(segment
		(start 79.92237 -277.820882)
		(end 79.934308 -277.814024)
		(width 0.0889)
		(layer "In11.Cu")
		(net "M_F_CPU1_SB_DQ<6>")
	)
	(arc
		(start 83.128104 -277.81377)
		(mid 83.41106 -277.889947)
		(end 83.694016 -277.81377)
		(width 0.0889)
		(layer "In11.Cu")
		(net "M_F_CPU1_SB_DQ<6>")
	)
	(arc
		(start 78.994762 -277.81377)
		(mid 79.17522 -277.763326)
		(end 79.357474 -277.806912)
		(width 0.0889)
		(layer "In11.Cu")
		(net "M_F_CPU1_SB_DQ<6>")
	)
	(arc
		(start 80.308196 -277.81377)
		(mid 80.591152 -277.889947)
		(end 80.874108 -277.81377)
		(width 0.0889)
		(layer "In11.Cu")
		(net "M_F_CPU1_SB_DQ<6>")
	)
	(arc
		(start 81.247996 -277.81377)
		(mid 81.530952 -277.889947)
		(end 81.813908 -277.81377)
		(width 0.0889)
		(layer "In11.Cu")
		(net "M_F_CPU1_SB_DQ<6>")
	)
	(arc
		(start 84.068158 -277.81377)
		(mid 84.315871 -277.88899)
		(end 84.571078 -277.84552)
		(width 0.0889)
		(layer "In11.Cu")
		(net "M_F_CPU1_SB_DQ<6>")
	)
	(arc
		(start 80.874108 -277.81377)
		(mid 81.061052 -277.763515)
		(end 81.247996 -277.81377)
		(width 0.0889)
		(layer "In11.Cu")
		(net "M_F_CPU1_SB_DQ<6>")
	)
	(arc
		(start 83.702398 -277.808944)
		(mid 83.885906 -277.76345)
		(end 84.068158 -277.81377)
		(width 0.0889)
		(layer "In11.Cu")
		(net "M_F_CPU1_SB_DQ<6>")
	)
	(arc
		(start 82.18805 -277.81377)
		(mid 82.471006 -277.889947)
		(end 82.753962 -277.81377)
		(width 0.0889)
		(layer "In11.Cu")
		(net "M_F_CPU1_SB_DQ<6>")
	)
	(arc
		(start 81.813908 -277.81377)
		(mid 81.996159 -277.76342)
		(end 82.179668 -277.808944)
		(width 0.0889)
		(layer "In11.Cu")
		(net "M_F_CPU1_SB_DQ<6>")
	)
	(arc
		(start 79.369158 -277.81377)
		(mid 79.644836 -277.8899)
		(end 79.92237 -277.820882)
		(width 0.0889)
		(layer "In11.Cu")
		(net "M_F_CPU1_SB_DQ<6>")
	)
	(arc
		(start 79.950564 -277.804626)
		(mid 80.130546 -277.763526)
		(end 80.308196 -277.81377)
		(width 0.0889)
		(layer "In11.Cu")
		(net "M_F_CPU1_SB_DQ<6>")
	)
	(arc
		(start 78.711044 -277.890224)
		(mid 78.857975 -277.870813)
		(end 78.994762 -277.81377)
		(width 0.0889)
		(layer "In11.Cu")
		(net "M_F_CPU1_SB_DQ<6>")
	)
	(arc
		(start 82.762344 -277.808944)
		(mid 82.945852 -277.76345)
		(end 83.128104 -277.81377)
		(width 0.0889)
		(layer "In11.Cu")
		(net "M_F_CPU1_SB_DQ<6>")
	)
	(segment
		(start 86.22792 -277.870412)
		(end 85.761068 -278.13635)
		(width 0.10668)
		(layer "F.Cu")
		(net "M_F_CPU1_SB_DQ<5>")
	)
	(segment
		(start 31.939992 -289.176206)
		(end 32.084772 -289.320986)
		(width 0.14478)
		(layer "In11.Cu")
		(net "M_F_CPU1_SB_DQ<5>")
	)
	(segment
		(start 26.785062 -289.313366)
		(end 26.785062 -289.415728)
		(width 0.14478)
		(layer "In11.Cu")
		(net "M_F_CPU1_SB_DQ<5>")
	)
	(segment
		(start 31.533338 -289.415728)
		(end 31.533338 -289.320986)
		(width 0.14478)
		(layer "In11.Cu")
		(net "M_F_CPU1_SB_DQ<5>")
	)
	(segment
		(start 34.505392 -289.415728)
		(end 34.650172 -289.560508)
		(width 0.14478)
		(layer "In11.Cu")
		(net "M_F_CPU1_SB_DQ<5>")
	)
	(segment
		(start 26.785062 -289.415728)
		(end 26.929842 -289.560508)
		(width 0.14478)
		(layer "In11.Cu")
		(net "M_F_CPU1_SB_DQ<5>")
	)
	(segment
		(start 30.314392 -288.71037)
		(end 31.16453 -289.560508)
		(width 0.14478)
		(layer "In11.Cu")
		(net "M_F_CPU1_SB_DQ<5>")
	)
	(segment
		(start 39.703248 -289.560508)
		(end 40.944292 -289.560508)
		(width 0.14478)
		(layer "In11.Cu")
		(net "M_F_CPU1_SB_DQ<5>")
	)
	(segment
		(start 59.84113 -288.71037)
		(end 70.718426 -277.833074)
		(width 0.14478)
		(layer "In11.Cu")
		(net "M_F_CPU1_SB_DQ<5>")
	)
	(segment
		(start 26.640282 -289.168586)
		(end 26.785062 -289.313366)
		(width 0.14478)
		(layer "In11.Cu")
		(net "M_F_CPU1_SB_DQ<5>")
	)
	(segment
		(start 34.505392 -289.320986)
		(end 34.505392 -289.415728)
		(width 0.14478)
		(layer "In11.Cu")
		(net "M_F_CPU1_SB_DQ<5>")
	)
	(segment
		(start 22.909784 -289.780726)
		(end 22.909784 -289.329622)
		(width 0.14478)
		(layer "In11.Cu")
		(net "M_F_CPU1_SB_DQ<5>")
	)
	(segment
		(start 24.80945 -289.560508)
		(end 26.088848 -289.560508)
		(width 0.14478)
		(layer "In11.Cu")
		(net "M_F_CPU1_SB_DQ<5>")
	)
	(segment
		(start 41.785286 -289.560508)
		(end 42.144442 -289.560508)
		(width 0.14478)
		(layer "In11.Cu")
		(net "M_F_CPU1_SB_DQ<5>")
	)
	(segment
		(start 45.94733 -289.560508)
		(end 49.733962 -289.560508)
		(width 0.14478)
		(layer "In11.Cu")
		(net "M_F_CPU1_SB_DQ<5>")
	)
	(segment
		(start 35.80638 -288.71037)
		(end 37.642292 -288.71037)
		(width 0.14478)
		(layer "In11.Cu")
		(net "M_F_CPU1_SB_DQ<5>")
	)
	(segment
		(start 32.084772 -289.320986)
		(end 32.084772 -289.415728)
		(width 0.14478)
		(layer "In11.Cu")
		(net "M_F_CPU1_SB_DQ<5>")
	)
	(segment
		(start 82.179668 -278.463756)
		(end 82.18805 -278.45893)
		(width 0.0889)
		(layer "In11.Cu")
		(net "M_F_CPU1_SB_DQ<5>")
	)
	(segment
		(start 23.85949 -289.94354)
		(end 24.022304 -289.780726)
		(width 0.14478)
		(layer "In11.Cu")
		(net "M_F_CPU1_SB_DQ<5>")
	)
	(segment
		(start 49.733962 -289.560508)
		(end 50.5841 -288.71037)
		(width 0.14478)
		(layer "In11.Cu")
		(net "M_F_CPU1_SB_DQ<5>")
	)
	(segment
		(start 23.30323 -289.166808)
		(end 23.466044 -289.329622)
		(width 0.14478)
		(layer "In11.Cu")
		(net "M_F_CPU1_SB_DQ<5>")
	)
	(segment
		(start 26.088848 -289.560508)
		(end 26.233628 -289.415728)
		(width 0.14478)
		(layer "In11.Cu")
		(net "M_F_CPU1_SB_DQ<5>")
	)
	(segment
		(start 26.378408 -289.168586)
		(end 26.640282 -289.168586)
		(width 0.14478)
		(layer "In11.Cu")
		(net "M_F_CPU1_SB_DQ<5>")
	)
	(segment
		(start 33.809178 -289.560508)
		(end 33.953958 -289.415728)
		(width 0.14478)
		(layer "In11.Cu")
		(net "M_F_CPU1_SB_DQ<5>")
	)
	(segment
		(start 40.944292 -289.560508)
		(end 41.089072 -289.415728)
		(width 0.14478)
		(layer "In11.Cu")
		(net "M_F_CPU1_SB_DQ<5>")
	)
	(segment
		(start 26.233628 -289.313366)
		(end 26.378408 -289.168586)
		(width 0.14478)
		(layer "In11.Cu")
		(net "M_F_CPU1_SB_DQ<5>")
	)
	(segment
		(start 38.862254 -289.560508)
		(end 39.007034 -289.415728)
		(width 0.14478)
		(layer "In11.Cu")
		(net "M_F_CPU1_SB_DQ<5>")
	)
	(segment
		(start 32.229552 -289.560508)
		(end 33.809178 -289.560508)
		(width 0.14478)
		(layer "In11.Cu")
		(net "M_F_CPU1_SB_DQ<5>")
	)
	(segment
		(start 24.185118 -289.166808)
		(end 24.41575 -289.166808)
		(width 0.14478)
		(layer "In11.Cu")
		(net "M_F_CPU1_SB_DQ<5>")
	)
	(segment
		(start 41.495726 -289.168586)
		(end 41.640506 -289.313366)
		(width 0.14478)
		(layer "In11.Cu")
		(net "M_F_CPU1_SB_DQ<5>")
	)
	(segment
		(start 41.089072 -289.415728)
		(end 41.089072 -289.313366)
		(width 0.14478)
		(layer "In11.Cu")
		(net "M_F_CPU1_SB_DQ<5>")
	)
	(segment
		(start 38.49243 -289.560508)
		(end 38.862254 -289.560508)
		(width 0.14478)
		(layer "In11.Cu")
		(net "M_F_CPU1_SB_DQ<5>")
	)
	(segment
		(start 26.929842 -289.560508)
		(end 27.310842 -289.560508)
		(width 0.14478)
		(layer "In11.Cu")
		(net "M_F_CPU1_SB_DQ<5>")
	)
	(segment
		(start 22.909784 -289.329622)
		(end 23.072598 -289.166808)
		(width 0.14478)
		(layer "In11.Cu")
		(net "M_F_CPU1_SB_DQ<5>")
	)
	(segment
		(start 31.533338 -289.320986)
		(end 31.678118 -289.176206)
		(width 0.14478)
		(layer "In11.Cu")
		(net "M_F_CPU1_SB_DQ<5>")
	)
	(segment
		(start 76.951586 -278.248364)
		(end 79.153004 -278.248364)
		(width 0.0889)
		(layer "In11.Cu")
		(net "M_F_CPU1_SB_DQ<5>")
	)
	(segment
		(start 24.022304 -289.780726)
		(end 24.022304 -289.329622)
		(width 0.14478)
		(layer "In11.Cu")
		(net "M_F_CPU1_SB_DQ<5>")
	)
	(segment
		(start 37.642292 -288.71037)
		(end 38.49243 -289.560508)
		(width 0.14478)
		(layer "In11.Cu")
		(net "M_F_CPU1_SB_DQ<5>")
	)
	(segment
		(start 39.558468 -289.305746)
		(end 39.558468 -289.415728)
		(width 0.14478)
		(layer "In11.Cu")
		(net "M_F_CPU1_SB_DQ<5>")
	)
	(segment
		(start 24.022304 -289.329622)
		(end 24.185118 -289.166808)
		(width 0.14478)
		(layer "In11.Cu")
		(net "M_F_CPU1_SB_DQ<5>")
	)
	(segment
		(start 52.793392 -288.71037)
		(end 53.64353 -289.560508)
		(width 0.14478)
		(layer "In11.Cu")
		(net "M_F_CPU1_SB_DQ<5>")
	)
	(segment
		(start 76.034392 -277.833074)
		(end 76.536296 -277.833074)
		(width 0.0889)
		(layer "In11.Cu")
		(net "M_F_CPU1_SB_DQ<5>")
	)
	(segment
		(start 50.5841 -288.71037)
		(end 52.793392 -288.71037)
		(width 0.14478)
		(layer "In11.Cu")
		(net "M_F_CPU1_SB_DQ<5>")
	)
	(segment
		(start 24.41575 -289.166808)
		(end 24.80945 -289.560508)
		(width 0.14478)
		(layer "In11.Cu")
		(net "M_F_CPU1_SB_DQ<5>")
	)
	(segment
		(start 85.914992 -278.40178)
		(end 85.761068 -278.13635)
		(width 0.0889)
		(layer "In11.Cu")
		(net "M_F_CPU1_SB_DQ<5>")
	)
	(segment
		(start 28.16098 -288.71037)
		(end 30.314392 -288.71037)
		(width 0.14478)
		(layer "In11.Cu")
		(net "M_F_CPU1_SB_DQ<5>")
	)
	(segment
		(start 23.466044 -289.329622)
		(end 23.466044 -289.780726)
		(width 0.14478)
		(layer "In11.Cu")
		(net "M_F_CPU1_SB_DQ<5>")
	)
	(segment
		(start 31.16453 -289.560508)
		(end 31.388558 -289.560508)
		(width 0.14478)
		(layer "In11.Cu")
		(net "M_F_CPU1_SB_DQ<5>")
	)
	(segment
		(start 22.74697 -289.94354)
		(end 22.909784 -289.780726)
		(width 0.14478)
		(layer "In11.Cu")
		(net "M_F_CPU1_SB_DQ<5>")
	)
	(segment
		(start 39.007034 -289.415728)
		(end 39.007034 -289.305746)
		(width 0.14478)
		(layer "In11.Cu")
		(net "M_F_CPU1_SB_DQ<5>")
	)
	(segment
		(start 58.01868 -288.71037)
		(end 59.84113 -288.71037)
		(width 0.14478)
		(layer "In11.Cu")
		(net "M_F_CPU1_SB_DQ<5>")
	)
	(segment
		(start 21.70811 -289.135312)
		(end 22.516338 -289.94354)
		(width 0.14478)
		(layer "In11.Cu")
		(net "M_F_CPU1_SB_DQ<5>")
	)
	(segment
		(start 32.084772 -289.415728)
		(end 32.229552 -289.560508)
		(width 0.14478)
		(layer "In11.Cu")
		(net "M_F_CPU1_SB_DQ<5>")
	)
	(segment
		(start 31.678118 -289.176206)
		(end 31.939992 -289.176206)
		(width 0.14478)
		(layer "In11.Cu")
		(net "M_F_CPU1_SB_DQ<5>")
	)
	(segment
		(start 39.007034 -289.305746)
		(end 39.151814 -289.160966)
		(width 0.14478)
		(layer "In11.Cu")
		(net "M_F_CPU1_SB_DQ<5>")
	)
	(segment
		(start 70.718426 -277.833074)
		(end 76.034392 -277.833074)
		(width 0.14478)
		(layer "In11.Cu")
		(net "M_F_CPU1_SB_DQ<5>")
	)
	(segment
		(start 85.89264 -278.485092)
		(end 85.914992 -278.40178)
		(width 0.0889)
		(layer "In11.Cu")
		(net "M_F_CPU1_SB_DQ<5>")
	)
	(segment
		(start 33.953958 -289.415728)
		(end 33.953958 -289.320986)
		(width 0.14478)
		(layer "In11.Cu")
		(net "M_F_CPU1_SB_DQ<5>")
	)
	(segment
		(start 83.694016 -278.45893)
		(end 83.702398 -278.463756)
		(width 0.0889)
		(layer "In11.Cu")
		(net "M_F_CPU1_SB_DQ<5>")
	)
	(segment
		(start 82.753962 -278.45893)
		(end 82.762344 -278.463756)
		(width 0.0889)
		(layer "In11.Cu")
		(net "M_F_CPU1_SB_DQ<5>")
	)
	(segment
		(start 27.310842 -289.560508)
		(end 28.16098 -288.71037)
		(width 0.14478)
		(layer "In11.Cu")
		(net "M_F_CPU1_SB_DQ<5>")
	)
	(segment
		(start 33.953958 -289.320986)
		(end 34.098738 -289.176206)
		(width 0.14478)
		(layer "In11.Cu")
		(net "M_F_CPU1_SB_DQ<5>")
	)
	(segment
		(start 39.151814 -289.160966)
		(end 39.413688 -289.160966)
		(width 0.14478)
		(layer "In11.Cu")
		(net "M_F_CPU1_SB_DQ<5>")
	)
	(segment
		(start 39.413688 -289.160966)
		(end 39.558468 -289.305746)
		(width 0.14478)
		(layer "In11.Cu")
		(net "M_F_CPU1_SB_DQ<5>")
	)
	(segment
		(start 57.168542 -289.560508)
		(end 58.01868 -288.71037)
		(width 0.14478)
		(layer "In11.Cu")
		(net "M_F_CPU1_SB_DQ<5>")
	)
	(segment
		(start 53.64353 -289.560508)
		(end 57.168542 -289.560508)
		(width 0.14478)
		(layer "In11.Cu")
		(net "M_F_CPU1_SB_DQ<5>")
	)
	(segment
		(start 31.388558 -289.560508)
		(end 31.533338 -289.415728)
		(width 0.14478)
		(layer "In11.Cu")
		(net "M_F_CPU1_SB_DQ<5>")
	)
	(segment
		(start 76.536296 -277.833074)
		(end 76.951586 -278.248364)
		(width 0.0889)
		(layer "In11.Cu")
		(net "M_F_CPU1_SB_DQ<5>")
	)
	(segment
		(start 23.628858 -289.94354)
		(end 23.85949 -289.94354)
		(width 0.14478)
		(layer "In11.Cu")
		(net "M_F_CPU1_SB_DQ<5>")
	)
	(segment
		(start 41.233852 -289.168586)
		(end 41.495726 -289.168586)
		(width 0.14478)
		(layer "In11.Cu")
		(net "M_F_CPU1_SB_DQ<5>")
	)
	(segment
		(start 34.650172 -289.560508)
		(end 34.956242 -289.560508)
		(width 0.14478)
		(layer "In11.Cu")
		(net "M_F_CPU1_SB_DQ<5>")
	)
	(segment
		(start 26.233628 -289.415728)
		(end 26.233628 -289.313366)
		(width 0.14478)
		(layer "In11.Cu")
		(net "M_F_CPU1_SB_DQ<5>")
	)
	(segment
		(start 41.089072 -289.313366)
		(end 41.233852 -289.168586)
		(width 0.14478)
		(layer "In11.Cu")
		(net "M_F_CPU1_SB_DQ<5>")
	)
	(segment
		(start 34.956242 -289.560508)
		(end 35.80638 -288.71037)
		(width 0.14478)
		(layer "In11.Cu")
		(net "M_F_CPU1_SB_DQ<5>")
	)
	(segment
		(start 34.360612 -289.176206)
		(end 34.505392 -289.320986)
		(width 0.14478)
		(layer "In11.Cu")
		(net "M_F_CPU1_SB_DQ<5>")
	)
	(segment
		(start 41.640506 -289.313366)
		(end 41.640506 -289.415728)
		(width 0.14478)
		(layer "In11.Cu")
		(net "M_F_CPU1_SB_DQ<5>")
	)
	(segment
		(start 42.144442 -289.560508)
		(end 42.99458 -288.71037)
		(width 0.14478)
		(layer "In11.Cu")
		(net "M_F_CPU1_SB_DQ<5>")
	)
	(segment
		(start 42.99458 -288.71037)
		(end 45.097192 -288.71037)
		(width 0.14478)
		(layer "In11.Cu")
		(net "M_F_CPU1_SB_DQ<5>")
	)
	(segment
		(start 23.072598 -289.166808)
		(end 23.30323 -289.166808)
		(width 0.14478)
		(layer "In11.Cu")
		(net "M_F_CPU1_SB_DQ<5>")
	)
	(segment
		(start 34.098738 -289.176206)
		(end 34.360612 -289.176206)
		(width 0.14478)
		(layer "In11.Cu")
		(net "M_F_CPU1_SB_DQ<5>")
	)
	(segment
		(start 39.558468 -289.415728)
		(end 39.703248 -289.560508)
		(width 0.14478)
		(layer "In11.Cu")
		(net "M_F_CPU1_SB_DQ<5>")
	)
	(segment
		(start 45.097192 -288.71037)
		(end 45.94733 -289.560508)
		(width 0.14478)
		(layer "In11.Cu")
		(net "M_F_CPU1_SB_DQ<5>")
	)
	(segment
		(start 41.640506 -289.415728)
		(end 41.785286 -289.560508)
		(width 0.14478)
		(layer "In11.Cu")
		(net "M_F_CPU1_SB_DQ<5>")
	)
	(segment
		(start 22.516338 -289.94354)
		(end 22.74697 -289.94354)
		(width 0.14478)
		(layer "In11.Cu")
		(net "M_F_CPU1_SB_DQ<5>")
	)
	(segment
		(start 23.466044 -289.780726)
		(end 23.628858 -289.94354)
		(width 0.14478)
		(layer "In11.Cu")
		(net "M_F_CPU1_SB_DQ<5>")
	)
	(arc
		(start 79.153004 -278.248364)
		(mid 79.55735 -278.301928)
		(end 79.9338 -278.45893)
		(width 0.0889)
		(layer "In11.Cu")
		(net "M_F_CPU1_SB_DQ<5>")
	)
	(arc
		(start 80.308196 -278.45893)
		(mid 80.591152 -278.382753)
		(end 80.874108 -278.45893)
		(width 0.0889)
		(layer "In11.Cu")
		(net "M_F_CPU1_SB_DQ<5>")
	)
	(arc
		(start 81.813908 -278.45893)
		(mid 81.996159 -278.50928)
		(end 82.179668 -278.463756)
		(width 0.0889)
		(layer "In11.Cu")
		(net "M_F_CPU1_SB_DQ<5>")
	)
	(arc
		(start 82.762344 -278.463756)
		(mid 82.945852 -278.50925)
		(end 83.128104 -278.45893)
		(width 0.0889)
		(layer "In11.Cu")
		(net "M_F_CPU1_SB_DQ<5>")
	)
	(arc
		(start 83.128104 -278.45893)
		(mid 83.41106 -278.382753)
		(end 83.694016 -278.45893)
		(width 0.0889)
		(layer "In11.Cu")
		(net "M_F_CPU1_SB_DQ<5>")
	)
	(arc
		(start 81.247996 -278.45893)
		(mid 81.530952 -278.382753)
		(end 81.813908 -278.45893)
		(width 0.0889)
		(layer "In11.Cu")
		(net "M_F_CPU1_SB_DQ<5>")
	)
	(arc
		(start 82.18805 -278.45893)
		(mid 82.471006 -278.382753)
		(end 82.753962 -278.45893)
		(width 0.0889)
		(layer "In11.Cu")
		(net "M_F_CPU1_SB_DQ<5>")
	)
	(arc
		(start 85.57387 -278.45893)
		(mid 85.730308 -278.507901)
		(end 85.89264 -278.485092)
		(width 0.0889)
		(layer "In11.Cu")
		(net "M_F_CPU1_SB_DQ<5>")
	)
	(arc
		(start 80.874108 -278.45893)
		(mid 81.061052 -278.509185)
		(end 81.247996 -278.45893)
		(width 0.0889)
		(layer "In11.Cu")
		(net "M_F_CPU1_SB_DQ<5>")
	)
	(arc
		(start 79.9338 -278.45893)
		(mid 80.120998 -278.509312)
		(end 80.308196 -278.45893)
		(width 0.0889)
		(layer "In11.Cu")
		(net "M_F_CPU1_SB_DQ<5>")
	)
	(arc
		(start 85.007958 -278.45893)
		(mid 85.290914 -278.382753)
		(end 85.57387 -278.45893)
		(width 0.0889)
		(layer "In11.Cu")
		(net "M_F_CPU1_SB_DQ<5>")
	)
	(arc
		(start 84.068158 -278.45893)
		(mid 84.351114 -278.382753)
		(end 84.63407 -278.45893)
		(width 0.0889)
		(layer "In11.Cu")
		(net "M_F_CPU1_SB_DQ<5>")
	)
	(arc
		(start 84.63407 -278.45893)
		(mid 84.821014 -278.509185)
		(end 85.007958 -278.45893)
		(width 0.0889)
		(layer "In11.Cu")
		(net "M_F_CPU1_SB_DQ<5>")
	)
	(arc
		(start 83.702398 -278.463756)
		(mid 83.885906 -278.50925)
		(end 84.068158 -278.45893)
		(width 0.0889)
		(layer "In11.Cu")
		(net "M_F_CPU1_SB_DQ<5>")
	)
	(segment
		(start 84.817966 -277.060406)
		(end 84.351114 -277.326344)
		(width 0.10668)
		(layer "F.Cu")
		(net "M_F_CPU1_SB_DQ<4>")
	)
	(segment
		(start 28.476448 -287.404302)
		(end 28.639516 -287.241234)
		(width 0.14478)
		(layer "In11.Cu")
		(net "M_F_CPU1_SB_DQ<4>")
	)
	(segment
		(start 50.579782 -287.010348)
		(end 50.74285 -287.173416)
		(width 0.14478)
		(layer "In11.Cu")
		(net "M_F_CPU1_SB_DQ<4>")
	)
	(segment
		(start 53.12156 -287.02)
		(end 54.354984 -288.253424)
		(width 0.14478)
		(layer "In11.Cu")
		(net "M_F_CPU1_SB_DQ<4>")
	)
	(segment
		(start 26.253694 -288.152586)
		(end 26.522426 -288.152586)
		(width 0.14478)
		(layer "In11.Cu")
		(net "M_F_CPU1_SB_DQ<4>")
	)
	(segment
		(start 83.589622 -277.65375)
		(end 83.598004 -277.648924)
		(width 0.0889)
		(layer "In11.Cu")
		(net "M_F_CPU1_SB_DQ<4>")
	)
	(segment
		(start 23.861776 -288.089594)
		(end 24.024844 -288.252662)
		(width 0.14478)
		(layer "In11.Cu")
		(net "M_F_CPU1_SB_DQ<4>")
	)
	(segment
		(start 34.06013 -288.089594)
		(end 34.06013 -288.0233)
		(width 0.14478)
		(layer "In11.Cu")
		(net "M_F_CPU1_SB_DQ<4>")
	)
	(segment
		(start 54.354984 -288.253424)
		(end 56.050942 -288.253424)
		(width 0.14478)
		(layer "In11.Cu")
		(net "M_F_CPU1_SB_DQ<4>")
	)
	(segment
		(start 48.496474 -288.089594)
		(end 48.659542 -288.252662)
		(width 0.14478)
		(layer "In11.Cu")
		(net "M_F_CPU1_SB_DQ<4>")
	)
	(segment
		(start 41.60139 -288.089594)
		(end 41.60139 -288.0233)
		(width 0.14478)
		(layer "In11.Cu")
		(net "M_F_CPU1_SB_DQ<4>")
	)
	(segment
		(start 48.659542 -288.252662)
		(end 48.88992 -288.252662)
		(width 0.14478)
		(layer "In11.Cu")
		(net "M_F_CPU1_SB_DQ<4>")
	)
	(segment
		(start 43.905424 -287.02)
		(end 45.577506 -287.02)
		(width 0.14478)
		(layer "In11.Cu")
		(net "M_F_CPU1_SB_DQ<4>")
	)
	(segment
		(start 57.791604 -287.405572)
		(end 58.706766 -287.405572)
		(width 0.14478)
		(layer "In11.Cu")
		(net "M_F_CPU1_SB_DQ<4>")
	)
	(segment
		(start 21.70811 -287.43529)
		(end 22.133052 -287.860232)
		(width 0.14478)
		(layer "In11.Cu")
		(net "M_F_CPU1_SB_DQ<4>")
	)
	(segment
		(start 28.639516 -287.173416)
		(end 28.792932 -287.02)
		(width 0.14478)
		(layer "In11.Cu")
		(net "M_F_CPU1_SB_DQ<4>")
	)
	(segment
		(start 41.438322 -288.252662)
		(end 41.60139 -288.089594)
		(width 0.14478)
		(layer "In11.Cu")
		(net "M_F_CPU1_SB_DQ<4>")
	)
	(segment
		(start 41.94302 -287.860232)
		(end 42.792904 -287.010348)
		(width 0.14478)
		(layer "In11.Cu")
		(net "M_F_CPU1_SB_DQ<4>")
	)
	(segment
		(start 46.42739 -287.869884)
		(end 48.343058 -287.869884)
		(width 0.14478)
		(layer "In11.Cu")
		(net "M_F_CPU1_SB_DQ<4>")
	)
	(segment
		(start 27.919934 -287.010348)
		(end 28.083002 -287.173416)
		(width 0.14478)
		(layer "In11.Cu")
		(net "M_F_CPU1_SB_DQ<4>")
	)
	(segment
		(start 26.522426 -288.152586)
		(end 27.664664 -287.010348)
		(width 0.14478)
		(layer "In11.Cu")
		(net "M_F_CPU1_SB_DQ<4>")
	)
	(segment
		(start 22.133052 -287.860232)
		(end 22.282658 -287.860232)
		(width 0.14478)
		(layer "In11.Cu")
		(net "M_F_CPU1_SB_DQ<4>")
	)
	(segment
		(start 79.447136 -277.638256)
		(end 79.46517 -277.648924)
		(width 0.0889)
		(layer "In11.Cu")
		(net "M_F_CPU1_SB_DQ<4>")
	)
	(segment
		(start 23.165308 -287.860232)
		(end 23.698708 -287.860232)
		(width 0.14478)
		(layer "In11.Cu")
		(net "M_F_CPU1_SB_DQ<4>")
	)
	(segment
		(start 33.503616 -288.0233)
		(end 33.503616 -288.089594)
		(width 0.14478)
		(layer "In11.Cu")
		(net "M_F_CPU1_SB_DQ<4>")
	)
	(segment
		(start 30.480508 -287.02)
		(end 31.330392 -287.869884)
		(width 0.14478)
		(layer "In11.Cu")
		(net "M_F_CPU1_SB_DQ<4>")
	)
	(segment
		(start 77.935582 -277.079964)
		(end 78.555342 -277.699724)
		(width 0.0889)
		(layer "In11.Cu")
		(net "M_F_CPU1_SB_DQ<4>")
	)
	(segment
		(start 51.136296 -287.396682)
		(end 51.299364 -287.233614)
		(width 0.14478)
		(layer "In11.Cu")
		(net "M_F_CPU1_SB_DQ<4>")
	)
	(segment
		(start 49.052988 -288.0233)
		(end 49.216056 -287.860232)
		(width 0.14478)
		(layer "In11.Cu")
		(net "M_F_CPU1_SB_DQ<4>")
	)
	(segment
		(start 70.341236 -276.923754)
		(end 75.957176 -276.923754)
		(width 0.14478)
		(layer "In11.Cu")
		(net "M_F_CPU1_SB_DQ<4>")
	)
	(segment
		(start 42.792904 -287.010348)
		(end 43.032426 -287.010348)
		(width 0.14478)
		(layer "In11.Cu")
		(net "M_F_CPU1_SB_DQ<4>")
	)
	(segment
		(start 35.781488 -287.404302)
		(end 36.011866 -287.404302)
		(width 0.14478)
		(layer "In11.Cu")
		(net "M_F_CPU1_SB_DQ<4>")
	)
	(segment
		(start 31.330392 -287.869884)
		(end 33.3502 -287.869884)
		(width 0.14478)
		(layer "In11.Cu")
		(net "M_F_CPU1_SB_DQ<4>")
	)
	(segment
		(start 28.083002 -287.173416)
		(end 28.083002 -287.241234)
		(width 0.14478)
		(layer "In11.Cu")
		(net "M_F_CPU1_SB_DQ<4>")
	)
	(segment
		(start 84.482686 -277.675086)
		(end 84.505038 -277.591774)
		(width 0.0889)
		(layer "In11.Cu")
		(net "M_F_CPU1_SB_DQ<4>")
	)
	(segment
		(start 22.445726 -287.697164)
		(end 22.445726 -287.29305)
		(width 0.14478)
		(layer "In11.Cu")
		(net "M_F_CPU1_SB_DQ<4>")
	)
	(segment
		(start 35.61842 -287.241234)
		(end 35.781488 -287.404302)
		(width 0.14478)
		(layer "In11.Cu")
		(net "M_F_CPU1_SB_DQ<4>")
	)
	(segment
		(start 43.195494 -287.233614)
		(end 43.358562 -287.396682)
		(width 0.14478)
		(layer "In11.Cu")
		(net "M_F_CPU1_SB_DQ<4>")
	)
	(segment
		(start 24.41829 -288.0233)
		(end 24.571706 -287.869884)
		(width 0.14478)
		(layer "In11.Cu")
		(net "M_F_CPU1_SB_DQ<4>")
	)
	(segment
		(start 40.89146 -287.869884)
		(end 41.044876 -288.0233)
		(width 0.14478)
		(layer "In11.Cu")
		(net "M_F_CPU1_SB_DQ<4>")
	)
	(segment
		(start 75.957176 -276.923754)
		(end 76.414376 -276.923754)
		(width 0.0889)
		(layer "In11.Cu")
		(net "M_F_CPU1_SB_DQ<4>")
	)
	(segment
		(start 22.282658 -287.860232)
		(end 22.445726 -287.697164)
		(width 0.14478)
		(layer "In11.Cu")
		(net "M_F_CPU1_SB_DQ<4>")
	)
	(segment
		(start 23.00224 -287.697164)
		(end 23.165308 -287.860232)
		(width 0.14478)
		(layer "In11.Cu")
		(net "M_F_CPU1_SB_DQ<4>")
	)
	(segment
		(start 58.851546 -287.260792)
		(end 58.851546 -286.836866)
		(width 0.14478)
		(layer "In11.Cu")
		(net "M_F_CPU1_SB_DQ<4>")
	)
	(segment
		(start 35.455352 -287.010348)
		(end 35.61842 -287.173416)
		(width 0.14478)
		(layer "In11.Cu")
		(net "M_F_CPU1_SB_DQ<4>")
	)
	(segment
		(start 59.40298 -286.836866)
		(end 59.40298 -287.260792)
		(width 0.14478)
		(layer "In11.Cu")
		(net "M_F_CPU1_SB_DQ<4>")
	)
	(segment
		(start 59.2582 -286.692086)
		(end 59.40298 -286.836866)
		(width 0.14478)
		(layer "In11.Cu")
		(net "M_F_CPU1_SB_DQ<4>")
	)
	(segment
		(start 56.44388 -287.860486)
		(end 57.33669 -287.860486)
		(width 0.14478)
		(layer "In11.Cu")
		(net "M_F_CPU1_SB_DQ<4>")
	)
	(segment
		(start 34.383218 -287.860232)
		(end 35.233102 -287.010348)
		(width 0.14478)
		(layer "In11.Cu")
		(net "M_F_CPU1_SB_DQ<4>")
	)
	(segment
		(start 59.40298 -287.260792)
		(end 59.54776 -287.405572)
		(width 0.14478)
		(layer "In11.Cu")
		(net "M_F_CPU1_SB_DQ<4>")
	)
	(segment
		(start 35.233102 -287.010348)
		(end 35.455352 -287.010348)
		(width 0.14478)
		(layer "In11.Cu")
		(net "M_F_CPU1_SB_DQ<4>")
	)
	(segment
		(start 76.570586 -277.079964)
		(end 77.935582 -277.079964)
		(width 0.0889)
		(layer "In11.Cu")
		(net "M_F_CPU1_SB_DQ<4>")
	)
	(segment
		(start 24.571706 -287.869884)
		(end 25.970992 -287.869884)
		(width 0.14478)
		(layer "In11.Cu")
		(net "M_F_CPU1_SB_DQ<4>")
	)
	(segment
		(start 36.011866 -287.404302)
		(end 36.174934 -287.241234)
		(width 0.14478)
		(layer "In11.Cu")
		(net "M_F_CPU1_SB_DQ<4>")
	)
	(segment
		(start 25.970992 -287.869884)
		(end 26.253694 -288.152586)
		(width 0.14478)
		(layer "In11.Cu")
		(net "M_F_CPU1_SB_DQ<4>")
	)
	(segment
		(start 41.044876 -288.0233)
		(end 41.044876 -288.089594)
		(width 0.14478)
		(layer "In11.Cu")
		(net "M_F_CPU1_SB_DQ<4>")
	)
	(segment
		(start 33.666684 -288.252662)
		(end 33.897062 -288.252662)
		(width 0.14478)
		(layer "In11.Cu")
		(net "M_F_CPU1_SB_DQ<4>")
	)
	(segment
		(start 28.24607 -287.404302)
		(end 28.476448 -287.404302)
		(width 0.14478)
		(layer "In11.Cu")
		(net "M_F_CPU1_SB_DQ<4>")
	)
	(segment
		(start 24.255222 -288.252662)
		(end 24.41829 -288.089594)
		(width 0.14478)
		(layer "In11.Cu")
		(net "M_F_CPU1_SB_DQ<4>")
	)
	(segment
		(start 57.33669 -287.860486)
		(end 57.791604 -287.405572)
		(width 0.14478)
		(layer "In11.Cu")
		(net "M_F_CPU1_SB_DQ<4>")
	)
	(segment
		(start 37.962332 -287.02)
		(end 38.812216 -287.869884)
		(width 0.14478)
		(layer "In11.Cu")
		(net "M_F_CPU1_SB_DQ<4>")
	)
	(segment
		(start 36.174934 -287.173416)
		(end 36.32835 -287.02)
		(width 0.14478)
		(layer "In11.Cu")
		(net "M_F_CPU1_SB_DQ<4>")
	)
	(segment
		(start 34.06013 -288.0233)
		(end 34.223198 -287.860232)
		(width 0.14478)
		(layer "In11.Cu")
		(net "M_F_CPU1_SB_DQ<4>")
	)
	(segment
		(start 24.024844 -288.252662)
		(end 24.255222 -288.252662)
		(width 0.14478)
		(layer "In11.Cu")
		(net "M_F_CPU1_SB_DQ<4>")
	)
	(segment
		(start 28.639516 -287.241234)
		(end 28.639516 -287.173416)
		(width 0.14478)
		(layer "In11.Cu")
		(net "M_F_CPU1_SB_DQ<4>")
	)
	(segment
		(start 43.58894 -287.396682)
		(end 43.752008 -287.233614)
		(width 0.14478)
		(layer "In11.Cu")
		(net "M_F_CPU1_SB_DQ<4>")
	)
	(segment
		(start 43.358562 -287.396682)
		(end 43.58894 -287.396682)
		(width 0.14478)
		(layer "In11.Cu")
		(net "M_F_CPU1_SB_DQ<4>")
	)
	(segment
		(start 48.88992 -288.252662)
		(end 49.052988 -288.089594)
		(width 0.14478)
		(layer "In11.Cu")
		(net "M_F_CPU1_SB_DQ<4>")
	)
	(segment
		(start 49.052988 -288.089594)
		(end 49.052988 -288.0233)
		(width 0.14478)
		(layer "In11.Cu")
		(net "M_F_CPU1_SB_DQ<4>")
	)
	(segment
		(start 23.698708 -287.860232)
		(end 23.861776 -288.0233)
		(width 0.14478)
		(layer "In11.Cu")
		(net "M_F_CPU1_SB_DQ<4>")
	)
	(segment
		(start 43.032426 -287.010348)
		(end 43.195494 -287.173416)
		(width 0.14478)
		(layer "In11.Cu")
		(net "M_F_CPU1_SB_DQ<4>")
	)
	(segment
		(start 51.299364 -287.173416)
		(end 51.45278 -287.02)
		(width 0.14478)
		(layer "In11.Cu")
		(net "M_F_CPU1_SB_DQ<4>")
	)
	(segment
		(start 84.505038 -277.591774)
		(end 84.351114 -277.326344)
		(width 0.0889)
		(layer "In11.Cu")
		(net "M_F_CPU1_SB_DQ<4>")
	)
	(segment
		(start 48.496474 -288.0233)
		(end 48.496474 -288.089594)
		(width 0.14478)
		(layer "In11.Cu")
		(net "M_F_CPU1_SB_DQ<4>")
	)
	(segment
		(start 23.00224 -287.29305)
		(end 23.00224 -287.697164)
		(width 0.14478)
		(layer "In11.Cu")
		(net "M_F_CPU1_SB_DQ<4>")
	)
	(segment
		(start 58.851546 -286.836866)
		(end 58.996326 -286.692086)
		(width 0.14478)
		(layer "In11.Cu")
		(net "M_F_CPU1_SB_DQ<4>")
	)
	(segment
		(start 76.414376 -276.923754)
		(end 76.570586 -277.079964)
		(width 0.0889)
		(layer "In11.Cu")
		(net "M_F_CPU1_SB_DQ<4>")
	)
	(segment
		(start 50.298858 -287.010348)
		(end 50.579782 -287.010348)
		(width 0.14478)
		(layer "In11.Cu")
		(net "M_F_CPU1_SB_DQ<4>")
	)
	(segment
		(start 50.905918 -287.396682)
		(end 51.136296 -287.396682)
		(width 0.14478)
		(layer "In11.Cu")
		(net "M_F_CPU1_SB_DQ<4>")
	)
	(segment
		(start 41.207944 -288.252662)
		(end 41.438322 -288.252662)
		(width 0.14478)
		(layer "In11.Cu")
		(net "M_F_CPU1_SB_DQ<4>")
	)
	(segment
		(start 38.812216 -287.869884)
		(end 40.89146 -287.869884)
		(width 0.14478)
		(layer "In11.Cu")
		(net "M_F_CPU1_SB_DQ<4>")
	)
	(segment
		(start 36.174934 -287.241234)
		(end 36.174934 -287.173416)
		(width 0.14478)
		(layer "In11.Cu")
		(net "M_F_CPU1_SB_DQ<4>")
	)
	(segment
		(start 51.45278 -287.02)
		(end 53.12156 -287.02)
		(width 0.14478)
		(layer "In11.Cu")
		(net "M_F_CPU1_SB_DQ<4>")
	)
	(segment
		(start 49.448974 -287.860232)
		(end 50.298858 -287.010348)
		(width 0.14478)
		(layer "In11.Cu")
		(net "M_F_CPU1_SB_DQ<4>")
	)
	(segment
		(start 35.61842 -287.173416)
		(end 35.61842 -287.241234)
		(width 0.14478)
		(layer "In11.Cu")
		(net "M_F_CPU1_SB_DQ<4>")
	)
	(segment
		(start 22.839172 -287.129982)
		(end 23.00224 -287.29305)
		(width 0.14478)
		(layer "In11.Cu")
		(net "M_F_CPU1_SB_DQ<4>")
	)
	(segment
		(start 48.343058 -287.869884)
		(end 48.496474 -288.0233)
		(width 0.14478)
		(layer "In11.Cu")
		(net "M_F_CPU1_SB_DQ<4>")
	)
	(segment
		(start 36.32835 -287.02)
		(end 37.962332 -287.02)
		(width 0.14478)
		(layer "In11.Cu")
		(net "M_F_CPU1_SB_DQ<4>")
	)
	(segment
		(start 50.74285 -287.173416)
		(end 50.74285 -287.233614)
		(width 0.14478)
		(layer "In11.Cu")
		(net "M_F_CPU1_SB_DQ<4>")
	)
	(segment
		(start 34.223198 -287.860232)
		(end 34.383218 -287.860232)
		(width 0.14478)
		(layer "In11.Cu")
		(net "M_F_CPU1_SB_DQ<4>")
	)
	(segment
		(start 33.503616 -288.089594)
		(end 33.666684 -288.252662)
		(width 0.14478)
		(layer "In11.Cu")
		(net "M_F_CPU1_SB_DQ<4>")
	)
	(segment
		(start 79.838804 -277.64867)
		(end 79.850742 -277.641812)
		(width 0.0889)
		(layer "In11.Cu")
		(net "M_F_CPU1_SB_DQ<4>")
	)
	(segment
		(start 51.299364 -287.233614)
		(end 51.299364 -287.173416)
		(width 0.14478)
		(layer "In11.Cu")
		(net "M_F_CPU1_SB_DQ<4>")
	)
	(segment
		(start 59.859418 -287.405572)
		(end 70.341236 -276.923754)
		(width 0.14478)
		(layer "In11.Cu")
		(net "M_F_CPU1_SB_DQ<4>")
	)
	(segment
		(start 22.445726 -287.29305)
		(end 22.608794 -287.129982)
		(width 0.14478)
		(layer "In11.Cu")
		(net "M_F_CPU1_SB_DQ<4>")
	)
	(segment
		(start 41.044876 -288.089594)
		(end 41.207944 -288.252662)
		(width 0.14478)
		(layer "In11.Cu")
		(net "M_F_CPU1_SB_DQ<4>")
	)
	(segment
		(start 28.792932 -287.02)
		(end 30.480508 -287.02)
		(width 0.14478)
		(layer "In11.Cu")
		(net "M_F_CPU1_SB_DQ<4>")
	)
	(segment
		(start 43.195494 -287.173416)
		(end 43.195494 -287.233614)
		(width 0.14478)
		(layer "In11.Cu")
		(net "M_F_CPU1_SB_DQ<4>")
	)
	(segment
		(start 22.608794 -287.129982)
		(end 22.839172 -287.129982)
		(width 0.14478)
		(layer "In11.Cu")
		(net "M_F_CPU1_SB_DQ<4>")
	)
	(segment
		(start 58.706766 -287.405572)
		(end 58.851546 -287.260792)
		(width 0.14478)
		(layer "In11.Cu")
		(net "M_F_CPU1_SB_DQ<4>")
	)
	(segment
		(start 45.577506 -287.02)
		(end 46.42739 -287.869884)
		(width 0.14478)
		(layer "In11.Cu")
		(net "M_F_CPU1_SB_DQ<4>")
	)
	(segment
		(start 43.752008 -287.233614)
		(end 43.752008 -287.173416)
		(width 0.14478)
		(layer "In11.Cu")
		(net "M_F_CPU1_SB_DQ<4>")
	)
	(segment
		(start 27.664664 -287.010348)
		(end 27.919934 -287.010348)
		(width 0.14478)
		(layer "In11.Cu")
		(net "M_F_CPU1_SB_DQ<4>")
	)
	(segment
		(start 24.41829 -288.089594)
		(end 24.41829 -288.0233)
		(width 0.14478)
		(layer "In11.Cu")
		(net "M_F_CPU1_SB_DQ<4>")
	)
	(segment
		(start 80.769714 -277.65375)
		(end 80.778096 -277.648924)
		(width 0.0889)
		(layer "In11.Cu")
		(net "M_F_CPU1_SB_DQ<4>")
	)
	(segment
		(start 23.861776 -288.0233)
		(end 23.861776 -288.089594)
		(width 0.14478)
		(layer "In11.Cu")
		(net "M_F_CPU1_SB_DQ<4>")
	)
	(segment
		(start 58.996326 -286.692086)
		(end 59.2582 -286.692086)
		(width 0.14478)
		(layer "In11.Cu")
		(net "M_F_CPU1_SB_DQ<4>")
	)
	(segment
		(start 33.897062 -288.252662)
		(end 34.06013 -288.089594)
		(width 0.14478)
		(layer "In11.Cu")
		(net "M_F_CPU1_SB_DQ<4>")
	)
	(segment
		(start 33.3502 -287.869884)
		(end 33.503616 -288.0233)
		(width 0.14478)
		(layer "In11.Cu")
		(net "M_F_CPU1_SB_DQ<4>")
	)
	(segment
		(start 43.752008 -287.173416)
		(end 43.905424 -287.02)
		(width 0.14478)
		(layer "In11.Cu")
		(net "M_F_CPU1_SB_DQ<4>")
	)
	(segment
		(start 59.54776 -287.405572)
		(end 59.859418 -287.405572)
		(width 0.14478)
		(layer "In11.Cu")
		(net "M_F_CPU1_SB_DQ<4>")
	)
	(segment
		(start 41.60139 -288.0233)
		(end 41.764458 -287.860232)
		(width 0.14478)
		(layer "In11.Cu")
		(net "M_F_CPU1_SB_DQ<4>")
	)
	(segment
		(start 50.74285 -287.233614)
		(end 50.905918 -287.396682)
		(width 0.14478)
		(layer "In11.Cu")
		(net "M_F_CPU1_SB_DQ<4>")
	)
	(segment
		(start 56.050942 -288.253424)
		(end 56.44388 -287.860486)
		(width 0.14478)
		(layer "In11.Cu")
		(net "M_F_CPU1_SB_DQ<4>")
	)
	(segment
		(start 81.344008 -277.648924)
		(end 81.35239 -277.65375)
		(width 0.0889)
		(layer "In11.Cu")
		(net "M_F_CPU1_SB_DQ<4>")
	)
	(segment
		(start 79.825088 -277.656544)
		(end 79.838804 -277.64867)
		(width 0.0889)
		(layer "In11.Cu")
		(net "M_F_CPU1_SB_DQ<4>")
	)
	(segment
		(start 41.764458 -287.860232)
		(end 41.94302 -287.860232)
		(width 0.14478)
		(layer "In11.Cu")
		(net "M_F_CPU1_SB_DQ<4>")
	)
	(segment
		(start 28.083002 -287.241234)
		(end 28.24607 -287.404302)
		(width 0.14478)
		(layer "In11.Cu")
		(net "M_F_CPU1_SB_DQ<4>")
	)
	(segment
		(start 49.216056 -287.860232)
		(end 49.448974 -287.860232)
		(width 0.14478)
		(layer "In11.Cu")
		(net "M_F_CPU1_SB_DQ<4>")
	)
	(segment
		(start 78.555342 -277.699724)
		(end 78.711044 -277.699724)
		(width 0.0889)
		(layer "In11.Cu")
		(net "M_F_CPU1_SB_DQ<4>")
	)
	(arc
		(start 82.284062 -277.648924)
		(mid 82.471006 -277.699179)
		(end 82.65795 -277.648924)
		(width 0.0889)
		(layer "In11.Cu")
		(net "M_F_CPU1_SB_DQ<4>")
	)
	(arc
		(start 81.35239 -277.65375)
		(mid 81.535898 -277.699244)
		(end 81.71815 -277.648924)
		(width 0.0889)
		(layer "In11.Cu")
		(net "M_F_CPU1_SB_DQ<4>")
	)
	(arc
		(start 79.46517 -277.648924)
		(mid 79.644157 -277.699094)
		(end 79.825088 -277.656544)
		(width 0.0889)
		(layer "In11.Cu")
		(net "M_F_CPU1_SB_DQ<4>")
	)
	(arc
		(start 82.65795 -277.648924)
		(mid 82.940906 -277.572747)
		(end 83.223862 -277.648924)
		(width 0.0889)
		(layer "In11.Cu")
		(net "M_F_CPU1_SB_DQ<4>")
	)
	(arc
		(start 79.850742 -277.641812)
		(mid 80.128276 -277.572831)
		(end 80.403954 -277.648924)
		(width 0.0889)
		(layer "In11.Cu")
		(net "M_F_CPU1_SB_DQ<4>")
	)
	(arc
		(start 78.898496 -277.648924)
		(mid 79.17144 -277.572344)
		(end 79.447136 -277.638256)
		(width 0.0889)
		(layer "In11.Cu")
		(net "M_F_CPU1_SB_DQ<4>")
	)
	(arc
		(start 80.403954 -277.648924)
		(mid 80.586205 -277.699274)
		(end 80.769714 -277.65375)
		(width 0.0889)
		(layer "In11.Cu")
		(net "M_F_CPU1_SB_DQ<4>")
	)
	(arc
		(start 84.163916 -277.648924)
		(mid 84.320354 -277.697895)
		(end 84.482686 -277.675086)
		(width 0.0889)
		(layer "In11.Cu")
		(net "M_F_CPU1_SB_DQ<4>")
	)
	(arc
		(start 81.71815 -277.648924)
		(mid 82.001106 -277.572747)
		(end 82.284062 -277.648924)
		(width 0.0889)
		(layer "In11.Cu")
		(net "M_F_CPU1_SB_DQ<4>")
	)
	(arc
		(start 78.711044 -277.699724)
		(mid 78.808133 -277.686734)
		(end 78.898496 -277.648924)
		(width 0.0889)
		(layer "In11.Cu")
		(net "M_F_CPU1_SB_DQ<4>")
	)
	(arc
		(start 83.223862 -277.648924)
		(mid 83.406113 -277.699274)
		(end 83.589622 -277.65375)
		(width 0.0889)
		(layer "In11.Cu")
		(net "M_F_CPU1_SB_DQ<4>")
	)
	(arc
		(start 80.778096 -277.648924)
		(mid 81.061052 -277.572747)
		(end 81.344008 -277.648924)
		(width 0.0889)
		(layer "In11.Cu")
		(net "M_F_CPU1_SB_DQ<4>")
	)
	(arc
		(start 83.598004 -277.648924)
		(mid 83.88096 -277.572747)
		(end 84.163916 -277.648924)
		(width 0.0889)
		(layer "In11.Cu")
		(net "M_F_CPU1_SB_DQ<4>")
	)
	(segment
		(start 86.69782 -275.440394)
		(end 86.230968 -275.706332)
		(width 0.10668)
		(layer "F.Cu")
		(net "M_F_CPU1_SB_DQ<3>")
	)
	(segment
		(start 77.299058 -274.235164)
		(end 78.365858 -275.301964)
		(width 0.0889)
		(layer "In11.Cu")
		(net "M_F_CPU1_SB_DQ<3>")
	)
	(segment
		(start 49.399698 -284.450536)
		(end 50.249582 -283.600652)
		(width 0.14478)
		(layer "In11.Cu")
		(net "M_F_CPU1_SB_DQ<3>")
	)
	(segment
		(start 78.365858 -275.301964)
		(end 79.53502 -275.301964)
		(width 0.0889)
		(layer "In11.Cu")
		(net "M_F_CPU1_SB_DQ<3>")
	)
	(segment
		(start 19.226784 -283.964126)
		(end 19.226784 -284.305756)
		(width 0.14478)
		(layer "In11.Cu")
		(net "M_F_CPU1_SB_DQ<3>")
	)
	(segment
		(start 27.616404 -283.600652)
		(end 30.534102 -283.600652)
		(width 0.14478)
		(layer "In11.Cu")
		(net "M_F_CPU1_SB_DQ<3>")
	)
	(segment
		(start 18.53057 -284.450536)
		(end 18.67535 -284.305756)
		(width 0.14478)
		(layer "In11.Cu")
		(net "M_F_CPU1_SB_DQ<3>")
	)
	(segment
		(start 19.082004 -283.819346)
		(end 19.226784 -283.964126)
		(width 0.14478)
		(layer "In11.Cu")
		(net "M_F_CPU1_SB_DQ<3>")
	)
	(segment
		(start 19.371564 -284.450536)
		(end 26.76652 -284.450536)
		(width 0.14478)
		(layer "In11.Cu")
		(net "M_F_CPU1_SB_DQ<3>")
	)
	(segment
		(start 81.344008 -275.383752)
		(end 81.35239 -275.378926)
		(width 0.0889)
		(layer "In11.Cu")
		(net "M_F_CPU1_SB_DQ<3>")
	)
	(segment
		(start 34.368486 -284.450536)
		(end 35.21837 -283.600652)
		(width 0.14478)
		(layer "In11.Cu")
		(net "M_F_CPU1_SB_DQ<3>")
	)
	(segment
		(start 76.472796 -274.584414)
		(end 76.822046 -274.235164)
		(width 0.0889)
		(layer "In11.Cu")
		(net "M_F_CPU1_SB_DQ<3>")
	)
	(segment
		(start 17.608042 -284.035246)
		(end 18.023332 -284.450536)
		(width 0.14478)
		(layer "In11.Cu")
		(net "M_F_CPU1_SB_DQ<3>")
	)
	(segment
		(start 45.609002 -283.600652)
		(end 46.458886 -284.450536)
		(width 0.14478)
		(layer "In11.Cu")
		(net "M_F_CPU1_SB_DQ<3>")
	)
	(segment
		(start 53.609748 -284.064964)
		(end 56.638952 -284.064964)
		(width 0.14478)
		(layer "In11.Cu")
		(net "M_F_CPU1_SB_DQ<3>")
	)
	(segment
		(start 26.76652 -284.450536)
		(end 27.616404 -283.600652)
		(width 0.14478)
		(layer "In11.Cu")
		(net "M_F_CPU1_SB_DQ<3>")
	)
	(segment
		(start 42.751756 -283.600652)
		(end 45.609002 -283.600652)
		(width 0.14478)
		(layer "In11.Cu")
		(net "M_F_CPU1_SB_DQ<3>")
	)
	(segment
		(start 56.638952 -284.064964)
		(end 58.607452 -283.249624)
		(width 0.14478)
		(layer "In11.Cu")
		(net "M_F_CPU1_SB_DQ<3>")
	)
	(segment
		(start 18.82013 -283.819346)
		(end 19.082004 -283.819346)
		(width 0.14478)
		(layer "In11.Cu")
		(net "M_F_CPU1_SB_DQ<3>")
	)
	(segment
		(start 85.10397 -275.383752)
		(end 85.112352 -275.378926)
		(width 0.0889)
		(layer "In11.Cu")
		(net "M_F_CPU1_SB_DQ<3>")
	)
	(segment
		(start 31.383986 -284.450536)
		(end 34.368486 -284.450536)
		(width 0.14478)
		(layer "In11.Cu")
		(net "M_F_CPU1_SB_DQ<3>")
	)
	(segment
		(start 76.822046 -274.235164)
		(end 77.299058 -274.235164)
		(width 0.0889)
		(layer "In11.Cu")
		(net "M_F_CPU1_SB_DQ<3>")
	)
	(segment
		(start 85.981032 -275.415502)
		(end 86.077044 -275.440902)
		(width 0.0889)
		(layer "In11.Cu")
		(net "M_F_CPU1_SB_DQ<3>")
	)
	(segment
		(start 30.534102 -283.600652)
		(end 31.383986 -284.450536)
		(width 0.14478)
		(layer "In11.Cu")
		(net "M_F_CPU1_SB_DQ<3>")
	)
	(segment
		(start 68.402708 -274.584414)
		(end 76.472796 -274.584414)
		(width 0.14478)
		(layer "In11.Cu")
		(net "M_F_CPU1_SB_DQ<3>")
	)
	(segment
		(start 80.39354 -275.389848)
		(end 80.403954 -275.383752)
		(width 0.0889)
		(layer "In11.Cu")
		(net "M_F_CPU1_SB_DQ<3>")
	)
	(segment
		(start 80.769714 -275.378926)
		(end 80.778096 -275.383752)
		(width 0.0889)
		(layer "In11.Cu")
		(net "M_F_CPU1_SB_DQ<3>")
	)
	(segment
		(start 18.023332 -284.450536)
		(end 18.53057 -284.450536)
		(width 0.14478)
		(layer "In11.Cu")
		(net "M_F_CPU1_SB_DQ<3>")
	)
	(segment
		(start 19.226784 -284.305756)
		(end 19.371564 -284.450536)
		(width 0.14478)
		(layer "In11.Cu")
		(net "M_F_CPU1_SB_DQ<3>")
	)
	(segment
		(start 41.901872 -284.450536)
		(end 42.751756 -283.600652)
		(width 0.14478)
		(layer "In11.Cu")
		(net "M_F_CPU1_SB_DQ<3>")
	)
	(segment
		(start 86.077044 -275.440902)
		(end 86.230968 -275.706332)
		(width 0.0889)
		(layer "In11.Cu")
		(net "M_F_CPU1_SB_DQ<3>")
	)
	(segment
		(start 35.21837 -283.600652)
		(end 38.103556 -283.600652)
		(width 0.14478)
		(layer "In11.Cu")
		(net "M_F_CPU1_SB_DQ<3>")
	)
	(segment
		(start 38.103556 -283.600652)
		(end 38.95344 -284.450536)
		(width 0.14478)
		(layer "In11.Cu")
		(net "M_F_CPU1_SB_DQ<3>")
	)
	(segment
		(start 50.249582 -283.600652)
		(end 53.145436 -283.600652)
		(width 0.14478)
		(layer "In11.Cu")
		(net "M_F_CPU1_SB_DQ<3>")
	)
	(segment
		(start 83.589622 -275.378926)
		(end 83.598004 -275.383752)
		(width 0.0889)
		(layer "In11.Cu")
		(net "M_F_CPU1_SB_DQ<3>")
	)
	(segment
		(start 18.67535 -283.964126)
		(end 18.82013 -283.819346)
		(width 0.14478)
		(layer "In11.Cu")
		(net "M_F_CPU1_SB_DQ<3>")
	)
	(segment
		(start 58.607452 -283.249624)
		(end 59.737498 -283.249624)
		(width 0.14478)
		(layer "In11.Cu")
		(net "M_F_CPU1_SB_DQ<3>")
	)
	(segment
		(start 59.737498 -283.249624)
		(end 68.402708 -274.584414)
		(width 0.14478)
		(layer "In11.Cu")
		(net "M_F_CPU1_SB_DQ<3>")
	)
	(segment
		(start 38.95344 -284.450536)
		(end 41.901872 -284.450536)
		(width 0.14478)
		(layer "In11.Cu")
		(net "M_F_CPU1_SB_DQ<3>")
	)
	(segment
		(start 46.458886 -284.450536)
		(end 49.399698 -284.450536)
		(width 0.14478)
		(layer "In11.Cu")
		(net "M_F_CPU1_SB_DQ<3>")
	)
	(segment
		(start 18.67535 -284.305756)
		(end 18.67535 -283.964126)
		(width 0.14478)
		(layer "In11.Cu")
		(net "M_F_CPU1_SB_DQ<3>")
	)
	(segment
		(start 53.145436 -283.600652)
		(end 53.609748 -284.064964)
		(width 0.14478)
		(layer "In11.Cu")
		(net "M_F_CPU1_SB_DQ<3>")
	)
	(segment
		(start 84.529676 -275.378926)
		(end 84.538058 -275.383752)
		(width 0.0889)
		(layer "In11.Cu")
		(net "M_F_CPU1_SB_DQ<3>")
	)
	(arc
		(start 85.478112 -275.383752)
		(mid 85.725825 -275.458972)
		(end 85.981032 -275.415502)
		(width 0.0889)
		(layer "In11.Cu")
		(net "M_F_CPU1_SB_DQ<3>")
	)
	(arc
		(start 80.403954 -275.383752)
		(mid 80.586205 -275.333402)
		(end 80.769714 -275.378926)
		(width 0.0889)
		(layer "In11.Cu")
		(net "M_F_CPU1_SB_DQ<3>")
	)
	(arc
		(start 83.223862 -275.383752)
		(mid 83.406113 -275.333402)
		(end 83.589622 -275.378926)
		(width 0.0889)
		(layer "In11.Cu")
		(net "M_F_CPU1_SB_DQ<3>")
	)
	(arc
		(start 79.837788 -275.383752)
		(mid 80.114855 -275.460023)
		(end 80.39354 -275.389848)
		(width 0.0889)
		(layer "In11.Cu")
		(net "M_F_CPU1_SB_DQ<3>")
	)
	(arc
		(start 81.71815 -275.383752)
		(mid 82.001106 -275.459929)
		(end 82.284062 -275.383752)
		(width 0.0889)
		(layer "In11.Cu")
		(net "M_F_CPU1_SB_DQ<3>")
	)
	(arc
		(start 83.598004 -275.383752)
		(mid 83.88096 -275.459929)
		(end 84.163916 -275.383752)
		(width 0.0889)
		(layer "In11.Cu")
		(net "M_F_CPU1_SB_DQ<3>")
	)
	(arc
		(start 84.538058 -275.383752)
		(mid 84.821014 -275.459929)
		(end 85.10397 -275.383752)
		(width 0.0889)
		(layer "In11.Cu")
		(net "M_F_CPU1_SB_DQ<3>")
	)
	(arc
		(start 84.163916 -275.383752)
		(mid 84.346167 -275.333402)
		(end 84.529676 -275.378926)
		(width 0.0889)
		(layer "In11.Cu")
		(net "M_F_CPU1_SB_DQ<3>")
	)
	(arc
		(start 85.112352 -275.378926)
		(mid 85.29586 -275.333432)
		(end 85.478112 -275.383752)
		(width 0.0889)
		(layer "In11.Cu")
		(net "M_F_CPU1_SB_DQ<3>")
	)
	(arc
		(start 80.778096 -275.383752)
		(mid 81.061052 -275.459929)
		(end 81.344008 -275.383752)
		(width 0.0889)
		(layer "In11.Cu")
		(net "M_F_CPU1_SB_DQ<3>")
	)
	(arc
		(start 79.53502 -275.301964)
		(mid 79.691824 -275.322781)
		(end 79.837788 -275.383752)
		(width 0.0889)
		(layer "In11.Cu")
		(net "M_F_CPU1_SB_DQ<3>")
	)
	(arc
		(start 82.284062 -275.383752)
		(mid 82.471006 -275.333497)
		(end 82.65795 -275.383752)
		(width 0.0889)
		(layer "In11.Cu")
		(net "M_F_CPU1_SB_DQ<3>")
	)
	(arc
		(start 82.65795 -275.383752)
		(mid 82.940906 -275.459929)
		(end 83.223862 -275.383752)
		(width 0.0889)
		(layer "In11.Cu")
		(net "M_F_CPU1_SB_DQ<3>")
	)
	(arc
		(start 81.35239 -275.378926)
		(mid 81.535898 -275.333432)
		(end 81.71815 -275.383752)
		(width 0.0889)
		(layer "In11.Cu")
		(net "M_F_CPU1_SB_DQ<3>")
	)
	(segment
		(start 84.817966 -293.260272)
		(end 84.351114 -293.52621)
		(width 0.10668)
		(layer "F.Cu")
		(net "M_F_CPU1_SB_DQ<31>")
	)
	(segment
		(start 35.811968 -318.763904)
		(end 36.115498 -318.460374)
		(width 0.14478)
		(layer "In11.Cu")
		(net "M_F_CPU1_SB_DQ<31>")
	)
	(segment
		(start 34.446718 -318.763904)
		(end 34.699448 -318.763904)
		(width 0.14478)
		(layer "In11.Cu")
		(net "M_F_CPU1_SB_DQ<31>")
	)
	(segment
		(start 29.163772 -318.776604)
		(end 29.403802 -318.776604)
		(width 0.14478)
		(layer "In11.Cu")
		(net "M_F_CPU1_SB_DQ<31>")
	)
	(segment
		(start 81.813908 -294.013636)
		(end 81.853024 -293.990776)
		(width 0.0889)
		(layer "In11.Cu")
		(net "M_F_CPU1_SB_DQ<31>")
	)
	(segment
		(start 27.735022 -318.460374)
		(end 28.051252 -318.776604)
		(width 0.14478)
		(layer "In11.Cu")
		(net "M_F_CPU1_SB_DQ<31>")
	)
	(segment
		(start 20.010374 -318.460374)
		(end 20.258024 -318.460374)
		(width 0.14478)
		(layer "In11.Cu")
		(net "M_F_CPU1_SB_DQ<31>")
	)
	(segment
		(start 63.982092 -313.392566)
		(end 64.186816 -313.392566)
		(width 0.14478)
		(layer "In11.Cu")
		(net "M_F_CPU1_SB_DQ<31>")
	)
	(segment
		(start 28.847542 -318.460374)
		(end 29.163772 -318.776604)
		(width 0.14478)
		(layer "In11.Cu")
		(net "M_F_CPU1_SB_DQ<31>")
	)
	(segment
		(start 38.593268 -318.460374)
		(end 38.896798 -318.763904)
		(width 0.14478)
		(layer "In11.Cu")
		(net "M_F_CPU1_SB_DQ<31>")
	)
	(segment
		(start 80.224884 -296.57675)
		(end 80.40624 -296.44213)
		(width 0.0889)
		(layer "In11.Cu")
		(net "M_F_CPU1_SB_DQ<31>")
	)
	(segment
		(start 26.622502 -318.460374)
		(end 26.938732 -318.776604)
		(width 0.14478)
		(layer "In11.Cu")
		(net "M_F_CPU1_SB_DQ<31>")
	)
	(segment
		(start 21.679154 -318.768984)
		(end 21.926804 -318.768984)
		(width 0.14478)
		(layer "In11.Cu")
		(net "M_F_CPU1_SB_DQ<31>")
	)
	(segment
		(start 35.255708 -318.460374)
		(end 35.559238 -318.763904)
		(width 0.14478)
		(layer "In11.Cu")
		(net "M_F_CPU1_SB_DQ<31>")
	)
	(segment
		(start 23.595584 -318.460374)
		(end 23.904194 -318.768984)
		(width 0.14478)
		(layer "In11.Cu")
		(net "M_F_CPU1_SB_DQ<31>")
	)
	(segment
		(start 18.589244 -318.768984)
		(end 18.897854 -318.460374)
		(width 0.14478)
		(layer "In11.Cu")
		(net "M_F_CPU1_SB_DQ<31>")
	)
	(segment
		(start 19.145504 -318.460374)
		(end 19.454114 -318.768984)
		(width 0.14478)
		(layer "In11.Cu")
		(net "M_F_CPU1_SB_DQ<31>")
	)
	(segment
		(start 36.115498 -318.460374)
		(end 36.368228 -318.460374)
		(width 0.14478)
		(layer "In11.Cu")
		(net "M_F_CPU1_SB_DQ<31>")
	)
	(segment
		(start 63.593218 -313.208416)
		(end 63.797942 -313.208416)
		(width 0.14478)
		(layer "In11.Cu")
		(net "M_F_CPU1_SB_DQ<31>")
	)
	(segment
		(start 23.347934 -318.460374)
		(end 23.595584 -318.460374)
		(width 0.14478)
		(layer "In11.Cu")
		(net "M_F_CPU1_SB_DQ<31>")
	)
	(segment
		(start 24.460454 -318.460374)
		(end 26.622502 -318.460374)
		(width 0.14478)
		(layer "In11.Cu")
		(net "M_F_CPU1_SB_DQ<31>")
	)
	(segment
		(start 18.341594 -318.768984)
		(end 18.589244 -318.768984)
		(width 0.14478)
		(layer "In11.Cu")
		(net "M_F_CPU1_SB_DQ<31>")
	)
	(segment
		(start 21.370544 -318.460374)
		(end 21.679154 -318.768984)
		(width 0.14478)
		(layer "In11.Cu")
		(net "M_F_CPU1_SB_DQ<31>")
	)
	(segment
		(start 22.235414 -318.460374)
		(end 22.483064 -318.460374)
		(width 0.14478)
		(layer "In11.Cu")
		(net "M_F_CPU1_SB_DQ<31>")
	)
	(segment
		(start 80.873854 -295.633648)
		(end 80.876394 -295.632124)
		(width 0.0889)
		(layer "In11.Cu")
		(net "M_F_CPU1_SB_DQ<31>")
	)
	(segment
		(start 84.196936 -293.26078)
		(end 84.351114 -293.52621)
		(width 0.0889)
		(layer "In11.Cu")
		(net "M_F_CPU1_SB_DQ<31>")
	)
	(segment
		(start 28.291282 -318.776604)
		(end 28.607512 -318.460374)
		(width 0.14478)
		(layer "In11.Cu")
		(net "M_F_CPU1_SB_DQ<31>")
	)
	(segment
		(start 23.039324 -318.768984)
		(end 23.347934 -318.460374)
		(width 0.14478)
		(layer "In11.Cu")
		(net "M_F_CPU1_SB_DQ<31>")
	)
	(segment
		(start 30.276292 -318.776604)
		(end 30.516322 -318.776604)
		(width 0.14478)
		(layer "In11.Cu")
		(net "M_F_CPU1_SB_DQ<31>")
	)
	(segment
		(start 81.312258 -294.84193)
		(end 81.344008 -294.823642)
		(width 0.0889)
		(layer "In11.Cu")
		(net "M_F_CPU1_SB_DQ<31>")
	)
	(segment
		(start 39.149528 -318.763904)
		(end 39.453058 -318.460374)
		(width 0.14478)
		(layer "In11.Cu")
		(net "M_F_CPU1_SB_DQ<31>")
	)
	(segment
		(start 34.143188 -318.460374)
		(end 34.446718 -318.763904)
		(width 0.14478)
		(layer "In11.Cu")
		(net "M_F_CPU1_SB_DQ<31>")
	)
	(segment
		(start 17.608042 -318.035432)
		(end 18.341594 -318.768984)
		(width 0.14478)
		(layer "In11.Cu")
		(net "M_F_CPU1_SB_DQ<31>")
	)
	(segment
		(start 36.368228 -318.460374)
		(end 36.671758 -318.763904)
		(width 0.14478)
		(layer "In11.Cu")
		(net "M_F_CPU1_SB_DQ<31>")
	)
	(segment
		(start 60.310776 -318.460374)
		(end 62.754002 -316.017148)
		(width 0.14478)
		(layer "In11.Cu")
		(net "M_F_CPU1_SB_DQ<31>")
	)
	(segment
		(start 30.516322 -318.776604)
		(end 30.832552 -318.460374)
		(width 0.14478)
		(layer "In11.Cu")
		(net "M_F_CPU1_SB_DQ<31>")
	)
	(segment
		(start 64.207644 -312.59399)
		(end 80.224884 -296.57675)
		(width 0.14478)
		(layer "In11.Cu")
		(net "M_F_CPU1_SB_DQ<31>")
	)
	(segment
		(start 30.832552 -318.460374)
		(end 34.143188 -318.460374)
		(width 0.14478)
		(layer "In11.Cu")
		(net "M_F_CPU1_SB_DQ<31>")
	)
	(segment
		(start 64.207644 -312.798714)
		(end 64.207644 -312.59399)
		(width 0.14478)
		(layer "In11.Cu")
		(net "M_F_CPU1_SB_DQ<31>")
	)
	(segment
		(start 22.483064 -318.460374)
		(end 22.791674 -318.768984)
		(width 0.14478)
		(layer "In11.Cu")
		(net "M_F_CPU1_SB_DQ<31>")
	)
	(segment
		(start 37.228018 -318.460374)
		(end 37.480748 -318.460374)
		(width 0.14478)
		(layer "In11.Cu")
		(net "M_F_CPU1_SB_DQ<31>")
	)
	(segment
		(start 28.607512 -318.460374)
		(end 28.847542 -318.460374)
		(width 0.14478)
		(layer "In11.Cu")
		(net "M_F_CPU1_SB_DQ<31>")
	)
	(segment
		(start 64.391794 -313.187588)
		(end 64.391794 -312.982864)
		(width 0.14478)
		(layer "In11.Cu")
		(net "M_F_CPU1_SB_DQ<31>")
	)
	(segment
		(start 37.784278 -318.763904)
		(end 38.037008 -318.763904)
		(width 0.14478)
		(layer "In11.Cu")
		(net "M_F_CPU1_SB_DQ<31>")
	)
	(segment
		(start 39.453058 -318.460374)
		(end 60.310776 -318.460374)
		(width 0.14478)
		(layer "In11.Cu")
		(net "M_F_CPU1_SB_DQ<31>")
	)
	(segment
		(start 29.403802 -318.776604)
		(end 29.720032 -318.460374)
		(width 0.14478)
		(layer "In11.Cu")
		(net "M_F_CPU1_SB_DQ<31>")
	)
	(segment
		(start 38.037008 -318.763904)
		(end 38.340538 -318.460374)
		(width 0.14478)
		(layer "In11.Cu")
		(net "M_F_CPU1_SB_DQ<31>")
	)
	(segment
		(start 38.340538 -318.460374)
		(end 38.593268 -318.460374)
		(width 0.14478)
		(layer "In11.Cu")
		(net "M_F_CPU1_SB_DQ<31>")
	)
	(segment
		(start 21.122894 -318.460374)
		(end 21.370544 -318.460374)
		(width 0.14478)
		(layer "In11.Cu")
		(net "M_F_CPU1_SB_DQ<31>")
	)
	(segment
		(start 19.701764 -318.768984)
		(end 20.010374 -318.460374)
		(width 0.14478)
		(layer "In11.Cu")
		(net "M_F_CPU1_SB_DQ<31>")
	)
	(segment
		(start 82.281268 -293.205408)
		(end 82.284062 -293.20363)
		(width 0.0889)
		(layer "In11.Cu")
		(net "M_F_CPU1_SB_DQ<31>")
	)
	(segment
		(start 22.791674 -318.768984)
		(end 23.039324 -318.768984)
		(width 0.14478)
		(layer "In11.Cu")
		(net "M_F_CPU1_SB_DQ<31>")
	)
	(segment
		(start 27.178762 -318.776604)
		(end 27.494992 -318.460374)
		(width 0.14478)
		(layer "In11.Cu")
		(net "M_F_CPU1_SB_DQ<31>")
	)
	(segment
		(start 21.926804 -318.768984)
		(end 22.235414 -318.460374)
		(width 0.14478)
		(layer "In11.Cu")
		(net "M_F_CPU1_SB_DQ<31>")
	)
	(segment
		(start 38.896798 -318.763904)
		(end 39.149528 -318.763904)
		(width 0.14478)
		(layer "In11.Cu")
		(net "M_F_CPU1_SB_DQ<31>")
	)
	(segment
		(start 20.258024 -318.460374)
		(end 20.566634 -318.768984)
		(width 0.14478)
		(layer "In11.Cu")
		(net "M_F_CPU1_SB_DQ<31>")
	)
	(segment
		(start 84.10067 -293.23538)
		(end 84.196936 -293.26078)
		(width 0.0889)
		(layer "In11.Cu")
		(net "M_F_CPU1_SB_DQ<31>")
	)
	(segment
		(start 35.559238 -318.763904)
		(end 35.811968 -318.763904)
		(width 0.14478)
		(layer "In11.Cu")
		(net "M_F_CPU1_SB_DQ<31>")
	)
	(segment
		(start 26.938732 -318.776604)
		(end 27.178762 -318.776604)
		(width 0.14478)
		(layer "In11.Cu")
		(net "M_F_CPU1_SB_DQ<31>")
	)
	(segment
		(start 27.494992 -318.460374)
		(end 27.735022 -318.460374)
		(width 0.14478)
		(layer "In11.Cu")
		(net "M_F_CPU1_SB_DQ<31>")
	)
	(segment
		(start 81.344008 -294.823642)
		(end 81.346548 -294.822118)
		(width 0.0889)
		(layer "In11.Cu")
		(net "M_F_CPU1_SB_DQ<31>")
	)
	(segment
		(start 23.904194 -318.768984)
		(end 24.151844 -318.768984)
		(width 0.14478)
		(layer "In11.Cu")
		(net "M_F_CPU1_SB_DQ<31>")
	)
	(segment
		(start 28.051252 -318.776604)
		(end 28.291282 -318.776604)
		(width 0.14478)
		(layer "In11.Cu")
		(net "M_F_CPU1_SB_DQ<31>")
	)
	(segment
		(start 64.186816 -313.392566)
		(end 64.391794 -313.187588)
		(width 0.14478)
		(layer "In11.Cu")
		(net "M_F_CPU1_SB_DQ<31>")
	)
	(segment
		(start 37.480748 -318.460374)
		(end 37.784278 -318.763904)
		(width 0.14478)
		(layer "In11.Cu")
		(net "M_F_CPU1_SB_DQ<31>")
	)
	(segment
		(start 64.391794 -312.982864)
		(end 64.207644 -312.798714)
		(width 0.14478)
		(layer "In11.Cu")
		(net "M_F_CPU1_SB_DQ<31>")
	)
	(segment
		(start 81.783428 -294.031416)
		(end 81.813908 -294.013636)
		(width 0.0889)
		(layer "In11.Cu")
		(net "M_F_CPU1_SB_DQ<31>")
	)
	(segment
		(start 36.671758 -318.763904)
		(end 36.924488 -318.763904)
		(width 0.14478)
		(layer "In11.Cu")
		(net "M_F_CPU1_SB_DQ<31>")
	)
	(segment
		(start 29.720032 -318.460374)
		(end 29.960062 -318.460374)
		(width 0.14478)
		(layer "In11.Cu")
		(net "M_F_CPU1_SB_DQ<31>")
	)
	(segment
		(start 63.797942 -313.208416)
		(end 63.982092 -313.392566)
		(width 0.14478)
		(layer "In11.Cu")
		(net "M_F_CPU1_SB_DQ<31>")
	)
	(segment
		(start 24.151844 -318.768984)
		(end 24.460454 -318.460374)
		(width 0.14478)
		(layer "In11.Cu")
		(net "M_F_CPU1_SB_DQ<31>")
	)
	(segment
		(start 19.454114 -318.768984)
		(end 19.701764 -318.768984)
		(width 0.14478)
		(layer "In11.Cu")
		(net "M_F_CPU1_SB_DQ<31>")
	)
	(segment
		(start 83.589622 -293.198804)
		(end 83.598004 -293.20363)
		(width 0.0889)
		(layer "In11.Cu")
		(net "M_F_CPU1_SB_DQ<31>")
	)
	(segment
		(start 34.699448 -318.763904)
		(end 35.002978 -318.460374)
		(width 0.14478)
		(layer "In11.Cu")
		(net "M_F_CPU1_SB_DQ<31>")
	)
	(segment
		(start 20.566634 -318.768984)
		(end 20.814284 -318.768984)
		(width 0.14478)
		(layer "In11.Cu")
		(net "M_F_CPU1_SB_DQ<31>")
	)
	(segment
		(start 62.754002 -316.017148)
		(end 62.754002 -314.047632)
		(width 0.14478)
		(layer "In11.Cu")
		(net "M_F_CPU1_SB_DQ<31>")
	)
	(segment
		(start 35.002978 -318.460374)
		(end 35.255708 -318.460374)
		(width 0.14478)
		(layer "In11.Cu")
		(net "M_F_CPU1_SB_DQ<31>")
	)
	(segment
		(start 18.897854 -318.460374)
		(end 19.145504 -318.460374)
		(width 0.14478)
		(layer "In11.Cu")
		(net "M_F_CPU1_SB_DQ<31>")
	)
	(segment
		(start 20.814284 -318.768984)
		(end 21.122894 -318.460374)
		(width 0.14478)
		(layer "In11.Cu")
		(net "M_F_CPU1_SB_DQ<31>")
	)
	(segment
		(start 36.924488 -318.763904)
		(end 37.228018 -318.460374)
		(width 0.14478)
		(layer "In11.Cu")
		(net "M_F_CPU1_SB_DQ<31>")
	)
	(segment
		(start 80.842104 -295.651936)
		(end 80.873854 -295.633648)
		(width 0.0889)
		(layer "In11.Cu")
		(net "M_F_CPU1_SB_DQ<31>")
	)
	(segment
		(start 62.754002 -314.047632)
		(end 63.593218 -313.208416)
		(width 0.14478)
		(layer "In11.Cu")
		(net "M_F_CPU1_SB_DQ<31>")
	)
	(segment
		(start 29.960062 -318.460374)
		(end 30.276292 -318.776604)
		(width 0.14478)
		(layer "In11.Cu")
		(net "M_F_CPU1_SB_DQ<31>")
	)
	(arc
		(start 81.626456 -294.336216)
		(mid 81.668005 -294.164794)
		(end 81.783428 -294.031416)
		(width 0.0889)
		(layer "In11.Cu")
		(net "M_F_CPU1_SB_DQ<31>")
	)
	(arc
		(start 81.156302 -295.146222)
		(mid 81.197557 -294.975251)
		(end 81.312258 -294.84193)
		(width 0.0889)
		(layer "In11.Cu")
		(net "M_F_CPU1_SB_DQ<31>")
	)
	(arc
		(start 81.853024 -293.990776)
		(mid 82.031837 -293.788426)
		(end 82.096356 -293.52621)
		(width 0.0889)
		(layer "In11.Cu")
		(net "M_F_CPU1_SB_DQ<31>")
	)
	(arc
		(start 82.284062 -293.20363)
		(mid 82.471006 -293.153375)
		(end 82.65795 -293.20363)
		(width 0.0889)
		(layer "In11.Cu")
		(net "M_F_CPU1_SB_DQ<31>")
	)
	(arc
		(start 82.65795 -293.20363)
		(mid 82.940906 -293.279807)
		(end 83.223862 -293.20363)
		(width 0.0889)
		(layer "In11.Cu")
		(net "M_F_CPU1_SB_DQ<31>")
	)
	(arc
		(start 80.40624 -296.44213)
		(mid 80.611204 -296.23662)
		(end 80.686148 -295.956228)
		(width 0.0889)
		(layer "In11.Cu")
		(net "M_F_CPU1_SB_DQ<31>")
	)
	(arc
		(start 83.598004 -293.20363)
		(mid 83.8456 -293.278808)
		(end 84.10067 -293.23538)
		(width 0.0889)
		(layer "In11.Cu")
		(net "M_F_CPU1_SB_DQ<31>")
	)
	(arc
		(start 80.686148 -295.956228)
		(mid 80.727403 -295.785257)
		(end 80.842104 -295.651936)
		(width 0.0889)
		(layer "In11.Cu")
		(net "M_F_CPU1_SB_DQ<31>")
	)
	(arc
		(start 81.346548 -294.822118)
		(mid 81.551512 -294.616608)
		(end 81.626456 -294.336216)
		(width 0.0889)
		(layer "In11.Cu")
		(net "M_F_CPU1_SB_DQ<31>")
	)
	(arc
		(start 83.223862 -293.20363)
		(mid 83.406113 -293.15328)
		(end 83.589622 -293.198804)
		(width 0.0889)
		(layer "In11.Cu")
		(net "M_F_CPU1_SB_DQ<31>")
	)
	(arc
		(start 82.096356 -293.52621)
		(mid 82.145885 -293.341057)
		(end 82.281268 -293.205408)
		(width 0.0889)
		(layer "In11.Cu")
		(net "M_F_CPU1_SB_DQ<31>")
	)
	(arc
		(start 80.876394 -295.632124)
		(mid 81.081358 -295.426614)
		(end 81.156302 -295.146222)
		(width 0.0889)
		(layer "In11.Cu")
		(net "M_F_CPU1_SB_DQ<31>")
	)
	(segment
		(start 85.287866 -292.450266)
		(end 84.821014 -292.716204)
		(width 0.10668)
		(layer "F.Cu")
		(net "M_F_CPU1_SB_DQ<30>")
	)
	(segment
		(start 82.18805 -292.393624)
		(end 82.179668 -292.388798)
		(width 0.0889)
		(layer "In11.Cu")
		(net "M_F_CPU1_SB_DQ<30>")
	)
	(segment
		(start 19.701764 -317.496444)
		(end 19.471132 -317.496444)
		(width 0.14478)
		(layer "In11.Cu")
		(net "M_F_CPU1_SB_DQ<30>")
	)
	(segment
		(start 80.406494 -293.201852)
		(end 80.403954 -293.20363)
		(width 0.0889)
		(layer "In11.Cu")
		(net "M_F_CPU1_SB_DQ<30>")
	)
	(segment
		(start 79.463646 -294.823642)
		(end 79.431896 -294.84193)
		(width 0.0889)
		(layer "In11.Cu")
		(net "M_F_CPU1_SB_DQ<30>")
	)
	(segment
		(start 20.977098 -316.923166)
		(end 20.977098 -317.33363)
		(width 0.14478)
		(layer "In11.Cu")
		(net "M_F_CPU1_SB_DQ<30>")
	)
	(segment
		(start 79.27594 -295.342564)
		(end 78.608936 -296.009568)
		(width 0.0889)
		(layer "In11.Cu")
		(net "M_F_CPU1_SB_DQ<30>")
	)
	(segment
		(start 19.308318 -317.33363)
		(end 19.308318 -316.923166)
		(width 0.14478)
		(layer "In11.Cu")
		(net "M_F_CPU1_SB_DQ<30>")
	)
	(segment
		(start 57.592468 -316.529466)
		(end 57.361582 -316.760352)
		(width 0.14478)
		(layer "In11.Cu")
		(net "M_F_CPU1_SB_DQ<30>")
	)
	(segment
		(start 19.864578 -317.33363)
		(end 19.701764 -317.496444)
		(width 0.14478)
		(layer "In11.Cu")
		(net "M_F_CPU1_SB_DQ<30>")
	)
	(segment
		(start 18.358612 -317.496444)
		(end 18.195798 -317.33363)
		(width 0.14478)
		(layer "In11.Cu")
		(net "M_F_CPU1_SB_DQ<30>")
	)
	(segment
		(start 84.66709 -292.450774)
		(end 84.571078 -292.425374)
		(width 0.0889)
		(layer "In11.Cu")
		(net "M_F_CPU1_SB_DQ<30>")
	)
	(segment
		(start 79.934054 -294.013636)
		(end 79.900272 -294.033194)
		(width 0.0889)
		(layer "In11.Cu")
		(net "M_F_CPU1_SB_DQ<30>")
	)
	(segment
		(start 18.195798 -317.33363)
		(end 18.195798 -316.923166)
		(width 0.14478)
		(layer "In11.Cu")
		(net "M_F_CPU1_SB_DQ<30>")
	)
	(segment
		(start 83.702398 -292.388798)
		(end 83.694016 -292.393624)
		(width 0.0889)
		(layer "In11.Cu")
		(net "M_F_CPU1_SB_DQ<30>")
	)
	(segment
		(start 61.74867 -315.297566)
		(end 60.285884 -316.760352)
		(width 0.14478)
		(layer "In11.Cu")
		(net "M_F_CPU1_SB_DQ<30>")
	)
	(segment
		(start 20.420838 -316.923166)
		(end 20.258024 -316.760352)
		(width 0.14478)
		(layer "In11.Cu")
		(net "M_F_CPU1_SB_DQ<30>")
	)
	(segment
		(start 19.471132 -317.496444)
		(end 19.308318 -317.33363)
		(width 0.14478)
		(layer "In11.Cu")
		(net "M_F_CPU1_SB_DQ<30>")
	)
	(segment
		(start 78.608936 -296.009568)
		(end 78.608936 -296.90695)
		(width 0.14478)
		(layer "In11.Cu")
		(net "M_F_CPU1_SB_DQ<30>")
	)
	(segment
		(start 57.361582 -316.760352)
		(end 57.041034 -316.760352)
		(width 0.14478)
		(layer "In11.Cu")
		(net "M_F_CPU1_SB_DQ<30>")
	)
	(segment
		(start 82.762344 -292.388798)
		(end 82.753962 -292.393624)
		(width 0.0889)
		(layer "In11.Cu")
		(net "M_F_CPU1_SB_DQ<30>")
	)
	(segment
		(start 56.258714 -316.760352)
		(end 21.139912 -316.760352)
		(width 0.14478)
		(layer "In11.Cu")
		(net "M_F_CPU1_SB_DQ<30>")
	)
	(segment
		(start 79.27594 -295.146222)
		(end 79.27594 -295.342564)
		(width 0.0889)
		(layer "In11.Cu")
		(net "M_F_CPU1_SB_DQ<30>")
	)
	(segment
		(start 20.977098 -317.33363)
		(end 20.814284 -317.496444)
		(width 0.14478)
		(layer "In11.Cu")
		(net "M_F_CPU1_SB_DQ<30>")
	)
	(segment
		(start 79.502762 -294.800782)
		(end 79.463646 -294.823642)
		(width 0.0889)
		(layer "In11.Cu")
		(net "M_F_CPU1_SB_DQ<30>")
	)
	(segment
		(start 20.027392 -316.760352)
		(end 19.864578 -316.923166)
		(width 0.14478)
		(layer "In11.Cu")
		(net "M_F_CPU1_SB_DQ<30>")
	)
	(segment
		(start 78.608936 -296.90695)
		(end 61.74867 -313.767216)
		(width 0.14478)
		(layer "In11.Cu")
		(net "M_F_CPU1_SB_DQ<30>")
	)
	(segment
		(start 80.403954 -293.20363)
		(end 80.373474 -293.22141)
		(width 0.0889)
		(layer "In11.Cu")
		(net "M_F_CPU1_SB_DQ<30>")
	)
	(segment
		(start 79.97317 -293.990776)
		(end 79.934054 -294.013636)
		(width 0.0889)
		(layer "In11.Cu")
		(net "M_F_CPU1_SB_DQ<30>")
	)
	(segment
		(start 84.821014 -292.716204)
		(end 84.66709 -292.450774)
		(width 0.0889)
		(layer "In11.Cu")
		(net "M_F_CPU1_SB_DQ<30>")
	)
	(segment
		(start 80.874108 -292.393624)
		(end 80.871314 -292.395402)
		(width 0.0889)
		(layer "In11.Cu")
		(net "M_F_CPU1_SB_DQ<30>")
	)
	(segment
		(start 56.810148 -316.529466)
		(end 56.4896 -316.529466)
		(width 0.14478)
		(layer "In11.Cu")
		(net "M_F_CPU1_SB_DQ<30>")
	)
	(segment
		(start 20.420838 -317.33363)
		(end 20.420838 -316.923166)
		(width 0.14478)
		(layer "In11.Cu")
		(net "M_F_CPU1_SB_DQ<30>")
	)
	(segment
		(start 60.285884 -316.760352)
		(end 58.143902 -316.760352)
		(width 0.14478)
		(layer "In11.Cu")
		(net "M_F_CPU1_SB_DQ<30>")
	)
	(segment
		(start 18.195798 -316.923166)
		(end 17.608042 -316.33541)
		(width 0.14478)
		(layer "In11.Cu")
		(net "M_F_CPU1_SB_DQ<30>")
	)
	(segment
		(start 57.041034 -316.760352)
		(end 56.810148 -316.529466)
		(width 0.14478)
		(layer "In11.Cu")
		(net "M_F_CPU1_SB_DQ<30>")
	)
	(segment
		(start 61.74867 -313.767216)
		(end 61.74867 -315.297566)
		(width 0.14478)
		(layer "In11.Cu")
		(net "M_F_CPU1_SB_DQ<30>")
	)
	(segment
		(start 58.143902 -316.760352)
		(end 57.913016 -316.529466)
		(width 0.14478)
		(layer "In11.Cu")
		(net "M_F_CPU1_SB_DQ<30>")
	)
	(segment
		(start 18.914872 -316.760352)
		(end 18.752058 -316.923166)
		(width 0.14478)
		(layer "In11.Cu")
		(net "M_F_CPU1_SB_DQ<30>")
	)
	(segment
		(start 57.913016 -316.529466)
		(end 57.592468 -316.529466)
		(width 0.14478)
		(layer "In11.Cu")
		(net "M_F_CPU1_SB_DQ<30>")
	)
	(segment
		(start 19.864578 -316.923166)
		(end 19.864578 -317.33363)
		(width 0.14478)
		(layer "In11.Cu")
		(net "M_F_CPU1_SB_DQ<30>")
	)
	(segment
		(start 18.752058 -317.33363)
		(end 18.589244 -317.496444)
		(width 0.14478)
		(layer "In11.Cu")
		(net "M_F_CPU1_SB_DQ<30>")
	)
	(segment
		(start 56.4896 -316.529466)
		(end 56.258714 -316.760352)
		(width 0.14478)
		(layer "In11.Cu")
		(net "M_F_CPU1_SB_DQ<30>")
	)
	(segment
		(start 19.308318 -316.923166)
		(end 19.145504 -316.760352)
		(width 0.14478)
		(layer "In11.Cu")
		(net "M_F_CPU1_SB_DQ<30>")
	)
	(segment
		(start 20.258024 -316.760352)
		(end 20.027392 -316.760352)
		(width 0.14478)
		(layer "In11.Cu")
		(net "M_F_CPU1_SB_DQ<30>")
	)
	(segment
		(start 18.752058 -316.923166)
		(end 18.752058 -317.33363)
		(width 0.14478)
		(layer "In11.Cu")
		(net "M_F_CPU1_SB_DQ<30>")
	)
	(segment
		(start 19.145504 -316.760352)
		(end 18.914872 -316.760352)
		(width 0.14478)
		(layer "In11.Cu")
		(net "M_F_CPU1_SB_DQ<30>")
	)
	(segment
		(start 20.814284 -317.496444)
		(end 20.583652 -317.496444)
		(width 0.14478)
		(layer "In11.Cu")
		(net "M_F_CPU1_SB_DQ<30>")
	)
	(segment
		(start 18.589244 -317.496444)
		(end 18.358612 -317.496444)
		(width 0.14478)
		(layer "In11.Cu")
		(net "M_F_CPU1_SB_DQ<30>")
	)
	(segment
		(start 21.139912 -316.760352)
		(end 20.977098 -316.923166)
		(width 0.14478)
		(layer "In11.Cu")
		(net "M_F_CPU1_SB_DQ<30>")
	)
	(segment
		(start 20.583652 -317.496444)
		(end 20.420838 -317.33363)
		(width 0.14478)
		(layer "In11.Cu")
		(net "M_F_CPU1_SB_DQ<30>")
	)
	(arc
		(start 79.900272 -294.033194)
		(mid 79.786865 -294.166224)
		(end 79.746094 -294.336216)
		(width 0.0889)
		(layer "In11.Cu")
		(net "M_F_CPU1_SB_DQ<30>")
	)
	(arc
		(start 80.871314 -292.395402)
		(mid 80.735977 -292.531078)
		(end 80.686402 -292.716204)
		(width 0.0889)
		(layer "In11.Cu")
		(net "M_F_CPU1_SB_DQ<30>")
	)
	(arc
		(start 83.128104 -292.393624)
		(mid 82.945853 -292.343274)
		(end 82.762344 -292.388798)
		(width 0.0889)
		(layer "In11.Cu")
		(net "M_F_CPU1_SB_DQ<30>")
	)
	(arc
		(start 80.686402 -292.716204)
		(mid 80.611348 -292.996426)
		(end 80.406494 -293.201852)
		(width 0.0889)
		(layer "In11.Cu")
		(net "M_F_CPU1_SB_DQ<30>")
	)
	(arc
		(start 84.571078 -292.425374)
		(mid 84.31587 -292.468851)
		(end 84.068158 -292.393624)
		(width 0.0889)
		(layer "In11.Cu")
		(net "M_F_CPU1_SB_DQ<30>")
	)
	(arc
		(start 84.068158 -292.393624)
		(mid 83.885907 -292.343274)
		(end 83.702398 -292.388798)
		(width 0.0889)
		(layer "In11.Cu")
		(net "M_F_CPU1_SB_DQ<30>")
	)
	(arc
		(start 81.813908 -292.393624)
		(mid 81.530952 -292.469801)
		(end 81.247996 -292.393624)
		(width 0.0889)
		(layer "In11.Cu")
		(net "M_F_CPU1_SB_DQ<30>")
	)
	(arc
		(start 80.373474 -293.22141)
		(mid 80.258047 -293.354786)
		(end 80.216502 -293.52621)
		(width 0.0889)
		(layer "In11.Cu")
		(net "M_F_CPU1_SB_DQ<30>")
	)
	(arc
		(start 79.746094 -294.336216)
		(mid 79.681579 -294.598435)
		(end 79.502762 -294.800782)
		(width 0.0889)
		(layer "In11.Cu")
		(net "M_F_CPU1_SB_DQ<30>")
	)
	(arc
		(start 80.216502 -293.52621)
		(mid 80.151987 -293.788429)
		(end 79.97317 -293.990776)
		(width 0.0889)
		(layer "In11.Cu")
		(net "M_F_CPU1_SB_DQ<30>")
	)
	(arc
		(start 82.179668 -292.388798)
		(mid 81.99616 -292.343304)
		(end 81.813908 -292.393624)
		(width 0.0889)
		(layer "In11.Cu")
		(net "M_F_CPU1_SB_DQ<30>")
	)
	(arc
		(start 79.431896 -294.84193)
		(mid 79.31722 -294.975264)
		(end 79.27594 -295.146222)
		(width 0.0889)
		(layer "In11.Cu")
		(net "M_F_CPU1_SB_DQ<30>")
	)
	(arc
		(start 81.247996 -292.393624)
		(mid 81.061052 -292.343369)
		(end 80.874108 -292.393624)
		(width 0.0889)
		(layer "In11.Cu")
		(net "M_F_CPU1_SB_DQ<30>")
	)
	(arc
		(start 83.694016 -292.393624)
		(mid 83.41106 -292.469801)
		(end 83.128104 -292.393624)
		(width 0.0889)
		(layer "In11.Cu")
		(net "M_F_CPU1_SB_DQ<30>")
	)
	(arc
		(start 82.753962 -292.393624)
		(mid 82.471006 -292.469801)
		(end 82.18805 -292.393624)
		(width 0.0889)
		(layer "In11.Cu")
		(net "M_F_CPU1_SB_DQ<30>")
	)
	(segment
		(start 85.287866 -274.630388)
		(end 84.821014 -274.896326)
		(width 0.10668)
		(layer "F.Cu")
		(net "M_F_CPU1_SB_DQ<2>")
	)
	(segment
		(start 19.37639 -282.374086)
		(end 19.37639 -283.146754)
		(width 0.14478)
		(layer "In11.Cu")
		(net "M_F_CPU1_SB_DQ<2>")
	)
	(segment
		(start 46.259242 -282.76042)
		(end 49.273714 -282.76042)
		(width 0.14478)
		(layer "In11.Cu")
		(net "M_F_CPU1_SB_DQ<2>")
	)
	(segment
		(start 84.571078 -274.605496)
		(end 84.66709 -274.630896)
		(width 0.0889)
		(layer "In11.Cu")
		(net "M_F_CPU1_SB_DQ<2>")
	)
	(segment
		(start 82.179668 -274.56892)
		(end 82.18805 -274.573746)
		(width 0.0889)
		(layer "In11.Cu")
		(net "M_F_CPU1_SB_DQ<2>")
	)
	(segment
		(start 79.357474 -274.566888)
		(end 79.369158 -274.573746)
		(width 0.0889)
		(layer "In11.Cu")
		(net "M_F_CPU1_SB_DQ<2>")
	)
	(segment
		(start 57.507124 -281.910282)
		(end 59.376564 -281.910282)
		(width 0.14478)
		(layer "In11.Cu")
		(net "M_F_CPU1_SB_DQ<2>")
	)
	(segment
		(start 31.349442 -282.76042)
		(end 34.23793 -282.76042)
		(width 0.14478)
		(layer "In11.Cu")
		(net "M_F_CPU1_SB_DQ<2>")
	)
	(segment
		(start 19.783044 -283.291534)
		(end 19.927824 -283.146754)
		(width 0.14478)
		(layer "In11.Cu")
		(net "M_F_CPU1_SB_DQ<2>")
	)
	(segment
		(start 52.978304 -281.910282)
		(end 53.828442 -282.76042)
		(width 0.14478)
		(layer "In11.Cu")
		(net "M_F_CPU1_SB_DQ<2>")
	)
	(segment
		(start 19.52117 -283.291534)
		(end 19.783044 -283.291534)
		(width 0.14478)
		(layer "In11.Cu")
		(net "M_F_CPU1_SB_DQ<2>")
	)
	(segment
		(start 56.656986 -282.76042)
		(end 57.507124 -281.910282)
		(width 0.14478)
		(layer "In11.Cu")
		(net "M_F_CPU1_SB_DQ<2>")
	)
	(segment
		(start 18.969736 -282.229306)
		(end 19.23161 -282.229306)
		(width 0.14478)
		(layer "In11.Cu")
		(net "M_F_CPU1_SB_DQ<2>")
	)
	(segment
		(start 19.37639 -283.146754)
		(end 19.52117 -283.291534)
		(width 0.14478)
		(layer "In11.Cu")
		(net "M_F_CPU1_SB_DQ<2>")
	)
	(segment
		(start 82.753962 -274.573746)
		(end 82.762344 -274.56892)
		(width 0.0889)
		(layer "In11.Cu")
		(net "M_F_CPU1_SB_DQ<2>")
	)
	(segment
		(start 75.985116 -273.675094)
		(end 77.502766 -273.675094)
		(width 0.0889)
		(layer "In11.Cu")
		(net "M_F_CPU1_SB_DQ<2>")
	)
	(segment
		(start 83.694016 -274.573746)
		(end 83.702398 -274.56892)
		(width 0.0889)
		(layer "In11.Cu")
		(net "M_F_CPU1_SB_DQ<2>")
	)
	(segment
		(start 67.611752 -273.675094)
		(end 75.985116 -273.675094)
		(width 0.14478)
		(layer "In11.Cu")
		(net "M_F_CPU1_SB_DQ<2>")
	)
	(segment
		(start 19.927824 -283.146754)
		(end 19.927824 -282.374086)
		(width 0.14478)
		(layer "In11.Cu")
		(net "M_F_CPU1_SB_DQ<2>")
	)
	(segment
		(start 30.499304 -281.910282)
		(end 31.349442 -282.76042)
		(width 0.14478)
		(layer "In11.Cu")
		(net "M_F_CPU1_SB_DQ<2>")
	)
	(segment
		(start 19.927824 -282.374086)
		(end 20.072604 -282.229306)
		(width 0.14478)
		(layer "In11.Cu")
		(net "M_F_CPU1_SB_DQ<2>")
	)
	(segment
		(start 28.001468 -281.910282)
		(end 30.499304 -281.910282)
		(width 0.14478)
		(layer "In11.Cu")
		(net "M_F_CPU1_SB_DQ<2>")
	)
	(segment
		(start 42.16273 -282.76042)
		(end 43.012868 -281.910282)
		(width 0.14478)
		(layer "In11.Cu")
		(net "M_F_CPU1_SB_DQ<2>")
	)
	(segment
		(start 45.409104 -281.910282)
		(end 46.259242 -282.76042)
		(width 0.14478)
		(layer "In11.Cu")
		(net "M_F_CPU1_SB_DQ<2>")
	)
	(segment
		(start 77.502766 -273.675094)
		(end 78.312518 -274.484846)
		(width 0.0889)
		(layer "In11.Cu")
		(net "M_F_CPU1_SB_DQ<2>")
	)
	(segment
		(start 43.012868 -281.910282)
		(end 45.409104 -281.910282)
		(width 0.14478)
		(layer "In11.Cu")
		(net "M_F_CPU1_SB_DQ<2>")
	)
	(segment
		(start 53.828442 -282.76042)
		(end 56.656986 -282.76042)
		(width 0.14478)
		(layer "In11.Cu")
		(net "M_F_CPU1_SB_DQ<2>")
	)
	(segment
		(start 59.376564 -281.910282)
		(end 67.611752 -273.675094)
		(width 0.14478)
		(layer "In11.Cu")
		(net "M_F_CPU1_SB_DQ<2>")
	)
	(segment
		(start 34.23793 -282.76042)
		(end 35.088068 -281.910282)
		(width 0.14478)
		(layer "In11.Cu")
		(net "M_F_CPU1_SB_DQ<2>")
	)
	(segment
		(start 27.15133 -282.76042)
		(end 28.001468 -281.910282)
		(width 0.14478)
		(layer "In11.Cu")
		(net "M_F_CPU1_SB_DQ<2>")
	)
	(segment
		(start 18.033238 -282.76042)
		(end 18.680176 -282.76042)
		(width 0.14478)
		(layer "In11.Cu")
		(net "M_F_CPU1_SB_DQ<2>")
	)
	(segment
		(start 20.479258 -282.61564)
		(end 20.624038 -282.76042)
		(width 0.14478)
		(layer "In11.Cu")
		(net "M_F_CPU1_SB_DQ<2>")
	)
	(segment
		(start 18.824956 -282.61564)
		(end 18.824956 -282.374086)
		(width 0.14478)
		(layer "In11.Cu")
		(net "M_F_CPU1_SB_DQ<2>")
	)
	(segment
		(start 35.088068 -281.910282)
		(end 37.763704 -281.910282)
		(width 0.14478)
		(layer "In11.Cu")
		(net "M_F_CPU1_SB_DQ<2>")
	)
	(segment
		(start 20.624038 -282.76042)
		(end 27.15133 -282.76042)
		(width 0.14478)
		(layer "In11.Cu")
		(net "M_F_CPU1_SB_DQ<2>")
	)
	(segment
		(start 84.66709 -274.630896)
		(end 84.821014 -274.896326)
		(width 0.0889)
		(layer "In11.Cu")
		(net "M_F_CPU1_SB_DQ<2>")
	)
	(segment
		(start 17.608042 -282.335224)
		(end 18.033238 -282.76042)
		(width 0.14478)
		(layer "In11.Cu")
		(net "M_F_CPU1_SB_DQ<2>")
	)
	(segment
		(start 50.123852 -281.910282)
		(end 52.978304 -281.910282)
		(width 0.14478)
		(layer "In11.Cu")
		(net "M_F_CPU1_SB_DQ<2>")
	)
	(segment
		(start 18.680176 -282.76042)
		(end 18.824956 -282.61564)
		(width 0.14478)
		(layer "In11.Cu")
		(net "M_F_CPU1_SB_DQ<2>")
	)
	(segment
		(start 19.23161 -282.229306)
		(end 19.37639 -282.374086)
		(width 0.14478)
		(layer "In11.Cu")
		(net "M_F_CPU1_SB_DQ<2>")
	)
	(segment
		(start 20.334478 -282.229306)
		(end 20.479258 -282.374086)
		(width 0.14478)
		(layer "In11.Cu")
		(net "M_F_CPU1_SB_DQ<2>")
	)
	(segment
		(start 18.824956 -282.374086)
		(end 18.969736 -282.229306)
		(width 0.14478)
		(layer "In11.Cu")
		(net "M_F_CPU1_SB_DQ<2>")
	)
	(segment
		(start 78.42885 -274.574)
		(end 78.45044 -274.586446)
		(width 0.0889)
		(layer "In11.Cu")
		(net "M_F_CPU1_SB_DQ<2>")
	)
	(segment
		(start 38.613842 -282.76042)
		(end 42.16273 -282.76042)
		(width 0.14478)
		(layer "In11.Cu")
		(net "M_F_CPU1_SB_DQ<2>")
	)
	(segment
		(start 79.934308 -274.574)
		(end 79.950564 -274.564602)
		(width 0.0889)
		(layer "In11.Cu")
		(net "M_F_CPU1_SB_DQ<2>")
	)
	(segment
		(start 79.92237 -274.580858)
		(end 79.934308 -274.574)
		(width 0.0889)
		(layer "In11.Cu")
		(net "M_F_CPU1_SB_DQ<2>")
	)
	(segment
		(start 49.273714 -282.76042)
		(end 50.123852 -281.910282)
		(width 0.14478)
		(layer "In11.Cu")
		(net "M_F_CPU1_SB_DQ<2>")
	)
	(segment
		(start 37.763704 -281.910282)
		(end 38.613842 -282.76042)
		(width 0.14478)
		(layer "In11.Cu")
		(net "M_F_CPU1_SB_DQ<2>")
	)
	(segment
		(start 20.072604 -282.229306)
		(end 20.334478 -282.229306)
		(width 0.14478)
		(layer "In11.Cu")
		(net "M_F_CPU1_SB_DQ<2>")
	)
	(segment
		(start 20.479258 -282.374086)
		(end 20.479258 -282.61564)
		(width 0.14478)
		(layer "In11.Cu")
		(net "M_F_CPU1_SB_DQ<2>")
	)
	(arc
		(start 82.762344 -274.56892)
		(mid 82.945852 -274.523426)
		(end 83.128104 -274.573746)
		(width 0.0889)
		(layer "In11.Cu")
		(net "M_F_CPU1_SB_DQ<2>")
	)
	(arc
		(start 80.308196 -274.573746)
		(mid 80.591152 -274.649923)
		(end 80.874108 -274.573746)
		(width 0.0889)
		(layer "In11.Cu")
		(net "M_F_CPU1_SB_DQ<2>")
	)
	(arc
		(start 80.874108 -274.573746)
		(mid 81.061052 -274.523491)
		(end 81.247996 -274.573746)
		(width 0.0889)
		(layer "In11.Cu")
		(net "M_F_CPU1_SB_DQ<2>")
	)
	(arc
		(start 83.128104 -274.573746)
		(mid 83.41106 -274.649923)
		(end 83.694016 -274.573746)
		(width 0.0889)
		(layer "In11.Cu")
		(net "M_F_CPU1_SB_DQ<2>")
	)
	(arc
		(start 83.702398 -274.56892)
		(mid 83.885906 -274.523426)
		(end 84.068158 -274.573746)
		(width 0.0889)
		(layer "In11.Cu")
		(net "M_F_CPU1_SB_DQ<2>")
	)
	(arc
		(start 79.950564 -274.564602)
		(mid 80.130546 -274.523502)
		(end 80.308196 -274.573746)
		(width 0.0889)
		(layer "In11.Cu")
		(net "M_F_CPU1_SB_DQ<2>")
	)
	(arc
		(start 81.247996 -274.573746)
		(mid 81.530952 -274.649923)
		(end 81.813908 -274.573746)
		(width 0.0889)
		(layer "In11.Cu")
		(net "M_F_CPU1_SB_DQ<2>")
	)
	(arc
		(start 82.18805 -274.573746)
		(mid 82.471006 -274.649923)
		(end 82.753962 -274.573746)
		(width 0.0889)
		(layer "In11.Cu")
		(net "M_F_CPU1_SB_DQ<2>")
	)
	(arc
		(start 78.994762 -274.573746)
		(mid 79.17522 -274.523302)
		(end 79.357474 -274.566888)
		(width 0.0889)
		(layer "In11.Cu")
		(net "M_F_CPU1_SB_DQ<2>")
	)
	(arc
		(start 78.45044 -274.586446)
		(mid 78.72423 -274.650117)
		(end 78.994762 -274.573746)
		(width 0.0889)
		(layer "In11.Cu")
		(net "M_F_CPU1_SB_DQ<2>")
	)
	(arc
		(start 78.312518 -274.484846)
		(mid 78.367768 -274.533228)
		(end 78.42885 -274.574)
		(width 0.0889)
		(layer "In11.Cu")
		(net "M_F_CPU1_SB_DQ<2>")
	)
	(arc
		(start 79.369158 -274.573746)
		(mid 79.644836 -274.649876)
		(end 79.92237 -274.580858)
		(width 0.0889)
		(layer "In11.Cu")
		(net "M_F_CPU1_SB_DQ<2>")
	)
	(arc
		(start 84.068158 -274.573746)
		(mid 84.315871 -274.648966)
		(end 84.571078 -274.605496)
		(width 0.0889)
		(layer "In11.Cu")
		(net "M_F_CPU1_SB_DQ<2>")
	)
	(arc
		(start 81.813908 -274.573746)
		(mid 81.996159 -274.523396)
		(end 82.179668 -274.56892)
		(width 0.0889)
		(layer "In11.Cu")
		(net "M_F_CPU1_SB_DQ<2>")
	)
	(segment
		(start 86.22792 -292.450266)
		(end 85.761068 -292.716204)
		(width 0.10668)
		(layer "F.Cu")
		(net "M_F_CPU1_SB_DQ<29>")
	)
	(segment
		(start 26.83129 -318.042544)
		(end 26.668476 -317.87973)
		(width 0.14478)
		(layer "In11.Cu")
		(net "M_F_CPU1_SB_DQ<29>")
	)
	(segment
		(start 80.338676 -294.641016)
		(end 80.308196 -294.658796)
		(width 0.0889)
		(layer "In11.Cu")
		(net "M_F_CPU1_SB_DQ<29>")
	)
	(segment
		(start 34.119566 -317.61049)
		(end 33.817052 -317.913004)
		(width 0.14478)
		(layer "In11.Cu")
		(net "M_F_CPU1_SB_DQ<29>")
	)
	(segment
		(start 23.465536 -317.38316)
		(end 23.302722 -317.220346)
		(width 0.14478)
		(layer "In11.Cu")
		(net "M_F_CPU1_SB_DQ<29>")
	)
	(segment
		(start 80.778096 -293.84879)
		(end 80.73898 -293.87165)
		(width 0.0889)
		(layer "In11.Cu")
		(net "M_F_CPU1_SB_DQ<29>")
	)
	(segment
		(start 62.299342 -315.608208)
		(end 60.29706 -317.61049)
		(width 0.14478)
		(layer "In11.Cu")
		(net "M_F_CPU1_SB_DQ<29>")
	)
	(segment
		(start 58.065924 -317.370206)
		(end 57.754774 -317.370206)
		(width 0.14478)
		(layer "In11.Cu")
		(net "M_F_CPU1_SB_DQ<29>")
	)
	(segment
		(start 27.780996 -317.37935)
		(end 27.618182 -317.216536)
		(width 0.14478)
		(layer "In11.Cu")
		(net "M_F_CPU1_SB_DQ<29>")
	)
	(segment
		(start 28.337256 -317.438024)
		(end 28.337256 -317.87973)
		(width 0.14478)
		(layer "In11.Cu")
		(net "M_F_CPU1_SB_DQ<29>")
	)
	(segment
		(start 60.29706 -317.61049)
		(end 58.306208 -317.61049)
		(width 0.14478)
		(layer "In11.Cu")
		(net "M_F_CPU1_SB_DQ<29>")
	)
	(segment
		(start 23.465536 -317.8302)
		(end 23.465536 -317.38316)
		(width 0.14478)
		(layer "In11.Cu")
		(net "M_F_CPU1_SB_DQ<29>")
	)
	(segment
		(start 31.85668 -317.61049)
		(end 31.546546 -317.920624)
		(width 0.14478)
		(layer "In11.Cu")
		(net "M_F_CPU1_SB_DQ<29>")
	)
	(segment
		(start 79.368142 -296.278808)
		(end 79.368142 -296.78376)
		(width 0.0889)
		(layer "In11.Cu")
		(net "M_F_CPU1_SB_DQ<29>")
	)
	(segment
		(start 62.299342 -313.85256)
		(end 62.299342 -315.608208)
		(width 0.14478)
		(layer "In11.Cu")
		(net "M_F_CPU1_SB_DQ<29>")
	)
	(segment
		(start 80.78089 -293.847012)
		(end 80.778096 -293.84879)
		(width 0.0889)
		(layer "In11.Cu")
		(net "M_F_CPU1_SB_DQ<29>")
	)
	(segment
		(start 24.021796 -317.38316)
		(end 24.021796 -317.8302)
		(width 0.14478)
		(layer "In11.Cu")
		(net "M_F_CPU1_SB_DQ<29>")
	)
	(segment
		(start 28.725876 -317.280036)
		(end 28.495244 -317.280036)
		(width 0.14478)
		(layer "In11.Cu")
		(net "M_F_CPU1_SB_DQ<29>")
	)
	(segment
		(start 81.24825 -293.038784)
		(end 81.24571 -293.040308)
		(width 0.0889)
		(layer "In11.Cu")
		(net "M_F_CPU1_SB_DQ<29>")
	)
	(segment
		(start 30.1879 -317.920624)
		(end 29.877766 -317.61049)
		(width 0.14478)
		(layer "In11.Cu")
		(net "M_F_CPU1_SB_DQ<29>")
	)
	(segment
		(start 79.838296 -295.468802)
		(end 79.79918 -295.491662)
		(width 0.0889)
		(layer "In11.Cu")
		(net "M_F_CPU1_SB_DQ<29>")
	)
	(segment
		(start 23.07209 -317.220346)
		(end 22.909276 -317.38316)
		(width 0.14478)
		(layer "In11.Cu")
		(net "M_F_CPU1_SB_DQ<29>")
	)
	(segment
		(start 29.877766 -317.61049)
		(end 29.05633 -317.61049)
		(width 0.14478)
		(layer "In11.Cu")
		(net "M_F_CPU1_SB_DQ<29>")
	)
	(segment
		(start 79.368142 -296.78376)
		(end 62.299342 -313.85256)
		(width 0.14478)
		(layer "In11.Cu")
		(net "M_F_CPU1_SB_DQ<29>")
	)
	(segment
		(start 31.546546 -317.920624)
		(end 31.30042 -317.920624)
		(width 0.14478)
		(layer "In11.Cu")
		(net "M_F_CPU1_SB_DQ<29>")
	)
	(segment
		(start 22.909276 -317.8302)
		(end 22.746462 -317.993014)
		(width 0.14478)
		(layer "In11.Cu")
		(net "M_F_CPU1_SB_DQ<29>")
	)
	(segment
		(start 31.30042 -317.920624)
		(end 30.990286 -317.61049)
		(width 0.14478)
		(layer "In11.Cu")
		(net "M_F_CPU1_SB_DQ<29>")
	)
	(segment
		(start 27.780996 -317.87973)
		(end 27.780996 -317.37935)
		(width 0.14478)
		(layer "In11.Cu")
		(net "M_F_CPU1_SB_DQ<29>")
	)
	(segment
		(start 33.563306 -317.913004)
		(end 33.260792 -317.61049)
		(width 0.14478)
		(layer "In11.Cu")
		(net "M_F_CPU1_SB_DQ<29>")
	)
	(segment
		(start 23.858982 -317.993014)
		(end 23.62835 -317.993014)
		(width 0.14478)
		(layer "In11.Cu")
		(net "M_F_CPU1_SB_DQ<29>")
	)
	(segment
		(start 24.18461 -317.220346)
		(end 24.021796 -317.38316)
		(width 0.14478)
		(layer "In11.Cu")
		(net "M_F_CPU1_SB_DQ<29>")
	)
	(segment
		(start 79.870046 -295.450514)
		(end 79.838296 -295.468802)
		(width 0.0889)
		(layer "In11.Cu")
		(net "M_F_CPU1_SB_DQ<29>")
	)
	(segment
		(start 28.495244 -317.280036)
		(end 28.337256 -317.438024)
		(width 0.14478)
		(layer "In11.Cu")
		(net "M_F_CPU1_SB_DQ<29>")
	)
	(segment
		(start 22.909276 -317.38316)
		(end 22.909276 -317.8302)
		(width 0.14478)
		(layer "In11.Cu")
		(net "M_F_CPU1_SB_DQ<29>")
	)
	(segment
		(start 33.817052 -317.913004)
		(end 33.563306 -317.913004)
		(width 0.14478)
		(layer "In11.Cu")
		(net "M_F_CPU1_SB_DQ<29>")
	)
	(segment
		(start 27.224736 -317.87973)
		(end 27.061922 -318.042544)
		(width 0.14478)
		(layer "In11.Cu")
		(net "M_F_CPU1_SB_DQ<29>")
	)
	(segment
		(start 26.112216 -317.37935)
		(end 26.112216 -317.780924)
		(width 0.14478)
		(layer "In11.Cu")
		(net "M_F_CPU1_SB_DQ<29>")
	)
	(segment
		(start 30.990286 -317.61049)
		(end 30.74416 -317.61049)
		(width 0.14478)
		(layer "In11.Cu")
		(net "M_F_CPU1_SB_DQ<29>")
	)
	(segment
		(start 28.174442 -318.042544)
		(end 27.94381 -318.042544)
		(width 0.14478)
		(layer "In11.Cu")
		(net "M_F_CPU1_SB_DQ<29>")
	)
	(segment
		(start 26.112216 -317.780924)
		(end 25.953212 -317.939928)
		(width 0.14478)
		(layer "In11.Cu")
		(net "M_F_CPU1_SB_DQ<29>")
	)
	(segment
		(start 79.400908 -296.259758)
		(end 79.368142 -296.278808)
		(width 0.0889)
		(layer "In11.Cu")
		(net "M_F_CPU1_SB_DQ<29>")
	)
	(segment
		(start 82.762344 -293.04361)
		(end 82.753962 -293.038784)
		(width 0.0889)
		(layer "In11.Cu")
		(net "M_F_CPU1_SB_DQ<29>")
	)
	(segment
		(start 27.618182 -317.216536)
		(end 27.38755 -317.216536)
		(width 0.14478)
		(layer "In11.Cu")
		(net "M_F_CPU1_SB_DQ<29>")
	)
	(segment
		(start 25.393142 -317.61049)
		(end 24.805386 -317.61049)
		(width 0.14478)
		(layer "In11.Cu")
		(net "M_F_CPU1_SB_DQ<29>")
	)
	(segment
		(start 23.62835 -317.993014)
		(end 23.465536 -317.8302)
		(width 0.14478)
		(layer "In11.Cu")
		(net "M_F_CPU1_SB_DQ<29>")
	)
	(segment
		(start 29.05633 -317.61049)
		(end 28.725876 -317.280036)
		(width 0.14478)
		(layer "In11.Cu")
		(net "M_F_CPU1_SB_DQ<29>")
	)
	(segment
		(start 57.51449 -317.61049)
		(end 34.119566 -317.61049)
		(width 0.14478)
		(layer "In11.Cu")
		(net "M_F_CPU1_SB_DQ<29>")
	)
	(segment
		(start 22.51583 -317.993014)
		(end 21.70811 -317.185294)
		(width 0.14478)
		(layer "In11.Cu")
		(net "M_F_CPU1_SB_DQ<29>")
	)
	(segment
		(start 25.72258 -317.939928)
		(end 25.393142 -317.61049)
		(width 0.14478)
		(layer "In11.Cu")
		(net "M_F_CPU1_SB_DQ<29>")
	)
	(segment
		(start 22.746462 -317.993014)
		(end 22.51583 -317.993014)
		(width 0.14478)
		(layer "In11.Cu")
		(net "M_F_CPU1_SB_DQ<29>")
	)
	(segment
		(start 33.260792 -317.61049)
		(end 31.85668 -317.61049)
		(width 0.14478)
		(layer "In11.Cu")
		(net "M_F_CPU1_SB_DQ<29>")
	)
	(segment
		(start 26.668476 -317.87973)
		(end 26.668476 -317.37935)
		(width 0.14478)
		(layer "In11.Cu")
		(net "M_F_CPU1_SB_DQ<29>")
	)
	(segment
		(start 85.007958 -293.038784)
		(end 84.999576 -293.04361)
		(width 0.0889)
		(layer "In11.Cu")
		(net "M_F_CPU1_SB_DQ<29>")
	)
	(segment
		(start 27.38755 -317.216536)
		(end 27.224736 -317.37935)
		(width 0.14478)
		(layer "In11.Cu")
		(net "M_F_CPU1_SB_DQ<29>")
	)
	(segment
		(start 85.914992 -292.981634)
		(end 85.89264 -293.064946)
		(width 0.0889)
		(layer "In11.Cu")
		(net "M_F_CPU1_SB_DQ<29>")
	)
	(segment
		(start 30.74416 -317.61049)
		(end 30.434026 -317.920624)
		(width 0.14478)
		(layer "In11.Cu")
		(net "M_F_CPU1_SB_DQ<29>")
	)
	(segment
		(start 27.94381 -318.042544)
		(end 27.780996 -317.87973)
		(width 0.14478)
		(layer "In11.Cu")
		(net "M_F_CPU1_SB_DQ<29>")
	)
	(segment
		(start 28.337256 -317.87973)
		(end 28.174442 -318.042544)
		(width 0.14478)
		(layer "In11.Cu")
		(net "M_F_CPU1_SB_DQ<29>")
	)
	(segment
		(start 82.18805 -293.038784)
		(end 82.187796 -293.038784)
		(width 0.0889)
		(layer "In11.Cu")
		(net "M_F_CPU1_SB_DQ<29>")
	)
	(segment
		(start 23.302722 -317.220346)
		(end 23.07209 -317.220346)
		(width 0.14478)
		(layer "In11.Cu")
		(net "M_F_CPU1_SB_DQ<29>")
	)
	(segment
		(start 80.308196 -294.658796)
		(end 80.271874 -294.679878)
		(width 0.0889)
		(layer "In11.Cu")
		(net "M_F_CPU1_SB_DQ<29>")
	)
	(segment
		(start 26.505662 -317.216536)
		(end 26.27503 -317.216536)
		(width 0.14478)
		(layer "In11.Cu")
		(net "M_F_CPU1_SB_DQ<29>")
	)
	(segment
		(start 26.668476 -317.37935)
		(end 26.505662 -317.216536)
		(width 0.14478)
		(layer "In11.Cu")
		(net "M_F_CPU1_SB_DQ<29>")
	)
	(segment
		(start 27.061922 -318.042544)
		(end 26.83129 -318.042544)
		(width 0.14478)
		(layer "In11.Cu")
		(net "M_F_CPU1_SB_DQ<29>")
	)
	(segment
		(start 57.754774 -317.370206)
		(end 57.51449 -317.61049)
		(width 0.14478)
		(layer "In11.Cu")
		(net "M_F_CPU1_SB_DQ<29>")
	)
	(segment
		(start 85.761068 -292.716204)
		(end 85.914992 -292.981634)
		(width 0.0889)
		(layer "In11.Cu")
		(net "M_F_CPU1_SB_DQ<29>")
	)
	(segment
		(start 30.434026 -317.920624)
		(end 30.1879 -317.920624)
		(width 0.14478)
		(layer "In11.Cu")
		(net "M_F_CPU1_SB_DQ<29>")
	)
	(segment
		(start 25.953212 -317.939928)
		(end 25.72258 -317.939928)
		(width 0.14478)
		(layer "In11.Cu")
		(net "M_F_CPU1_SB_DQ<29>")
	)
	(segment
		(start 27.224736 -317.37935)
		(end 27.224736 -317.87973)
		(width 0.14478)
		(layer "In11.Cu")
		(net "M_F_CPU1_SB_DQ<29>")
	)
	(segment
		(start 26.27503 -317.216536)
		(end 26.112216 -317.37935)
		(width 0.14478)
		(layer "In11.Cu")
		(net "M_F_CPU1_SB_DQ<29>")
	)
	(segment
		(start 58.306208 -317.61049)
		(end 58.065924 -317.370206)
		(width 0.14478)
		(layer "In11.Cu")
		(net "M_F_CPU1_SB_DQ<29>")
	)
	(segment
		(start 24.021796 -317.8302)
		(end 23.858982 -317.993014)
		(width 0.14478)
		(layer "In11.Cu")
		(net "M_F_CPU1_SB_DQ<29>")
	)
	(segment
		(start 24.805386 -317.61049)
		(end 24.415242 -317.220346)
		(width 0.14478)
		(layer "In11.Cu")
		(net "M_F_CPU1_SB_DQ<29>")
	)
	(segment
		(start 24.415242 -317.220346)
		(end 24.18461 -317.220346)
		(width 0.14478)
		(layer "In11.Cu")
		(net "M_F_CPU1_SB_DQ<29>")
	)
	(arc
		(start 80.026002 -295.146222)
		(mid 79.984747 -295.317193)
		(end 79.870046 -295.450514)
		(width 0.0889)
		(layer "In11.Cu")
		(net "M_F_CPU1_SB_DQ<29>")
	)
	(arc
		(start 81.24571 -293.040308)
		(mid 81.040746 -293.245818)
		(end 80.965802 -293.52621)
		(width 0.0889)
		(layer "In11.Cu")
		(net "M_F_CPU1_SB_DQ<29>")
	)
	(arc
		(start 85.57387 -293.038784)
		(mid 85.290914 -292.962607)
		(end 85.007958 -293.038784)
		(width 0.0889)
		(layer "In11.Cu")
		(net "M_F_CPU1_SB_DQ<29>")
	)
	(arc
		(start 84.633816 -293.038784)
		(mid 84.35086 -292.962607)
		(end 84.067904 -293.038784)
		(width 0.0889)
		(layer "In11.Cu")
		(net "M_F_CPU1_SB_DQ<29>")
	)
	(arc
		(start 80.271874 -294.679878)
		(mid 80.091222 -294.882623)
		(end 80.026002 -295.146222)
		(width 0.0889)
		(layer "In11.Cu")
		(net "M_F_CPU1_SB_DQ<29>")
	)
	(arc
		(start 83.694016 -293.038784)
		(mid 83.41106 -292.962607)
		(end 83.128104 -293.038784)
		(width 0.0889)
		(layer "In11.Cu")
		(net "M_F_CPU1_SB_DQ<29>")
	)
	(arc
		(start 81.813908 -293.038784)
		(mid 81.531096 -292.962735)
		(end 81.24825 -293.038784)
		(width 0.0889)
		(layer "In11.Cu")
		(net "M_F_CPU1_SB_DQ<29>")
	)
	(arc
		(start 80.495648 -294.336216)
		(mid 80.454099 -294.507638)
		(end 80.338676 -294.641016)
		(width 0.0889)
		(layer "In11.Cu")
		(net "M_F_CPU1_SB_DQ<29>")
	)
	(arc
		(start 79.79918 -295.491662)
		(mid 79.620367 -295.694012)
		(end 79.555848 -295.956228)
		(width 0.0889)
		(layer "In11.Cu")
		(net "M_F_CPU1_SB_DQ<29>")
	)
	(arc
		(start 84.999576 -293.04361)
		(mid 84.816068 -293.089104)
		(end 84.633816 -293.038784)
		(width 0.0889)
		(layer "In11.Cu")
		(net "M_F_CPU1_SB_DQ<29>")
	)
	(arc
		(start 82.753962 -293.038784)
		(mid 82.471006 -292.962607)
		(end 82.18805 -293.038784)
		(width 0.0889)
		(layer "In11.Cu")
		(net "M_F_CPU1_SB_DQ<29>")
	)
	(arc
		(start 85.89264 -293.064946)
		(mid 85.730308 -293.087764)
		(end 85.57387 -293.038784)
		(width 0.0889)
		(layer "In11.Cu")
		(net "M_F_CPU1_SB_DQ<29>")
	)
	(arc
		(start 82.187796 -293.038784)
		(mid 82.000852 -293.089108)
		(end 81.813908 -293.038784)
		(width 0.0889)
		(layer "In11.Cu")
		(net "M_F_CPU1_SB_DQ<29>")
	)
	(arc
		(start 80.73898 -293.87165)
		(mid 80.560167 -294.074)
		(end 80.495648 -294.336216)
		(width 0.0889)
		(layer "In11.Cu")
		(net "M_F_CPU1_SB_DQ<29>")
	)
	(arc
		(start 79.555848 -295.956228)
		(mid 79.514882 -296.126634)
		(end 79.400908 -296.259758)
		(width 0.0889)
		(layer "In11.Cu")
		(net "M_F_CPU1_SB_DQ<29>")
	)
	(arc
		(start 80.965802 -293.52621)
		(mid 80.916273 -293.711363)
		(end 80.78089 -293.847012)
		(width 0.0889)
		(layer "In11.Cu")
		(net "M_F_CPU1_SB_DQ<29>")
	)
	(arc
		(start 84.067904 -293.038784)
		(mid 83.88096 -293.089039)
		(end 83.694016 -293.038784)
		(width 0.0889)
		(layer "In11.Cu")
		(net "M_F_CPU1_SB_DQ<29>")
	)
	(arc
		(start 83.128104 -293.038784)
		(mid 82.945853 -293.089134)
		(end 82.762344 -293.04361)
		(width 0.0889)
		(layer "In11.Cu")
		(net "M_F_CPU1_SB_DQ<29>")
	)
	(segment
		(start 84.817966 -291.64026)
		(end 84.351114 -291.906198)
		(width 0.10668)
		(layer "F.Cu")
		(net "M_F_CPU1_SB_DQ<28>")
	)
	(segment
		(start 60.874148 -314.005722)
		(end 60.874148 -314.210446)
		(width 0.14478)
		(layer "In11.Cu")
		(net "M_F_CPU1_SB_DQ<28>")
	)
	(segment
		(start 35.807904 -316.208664)
		(end 35.54984 -316.208664)
		(width 0.14478)
		(layer "In11.Cu")
		(net "M_F_CPU1_SB_DQ<28>")
	)
	(segment
		(start 22.527768 -316.30493)
		(end 21.70811 -315.485272)
		(width 0.14478)
		(layer "In11.Cu")
		(net "M_F_CPU1_SB_DQ<28>")
	)
	(segment
		(start 45.971968 -315.980064)
		(end 45.564552 -315.980064)
		(width 0.14478)
		(layer "In11.Cu")
		(net "M_F_CPU1_SB_DQ<28>")
	)
	(segment
		(start 60.903612 -315.01969)
		(end 60.484258 -314.600336)
		(width 0.14478)
		(layer "In11.Cu")
		(net "M_F_CPU1_SB_DQ<28>")
	)
	(segment
		(start 27.092402 -315.566806)
		(end 26.947622 -315.711586)
		(width 0.14478)
		(layer "In11.Cu")
		(net "M_F_CPU1_SB_DQ<28>")
	)
	(segment
		(start 59.6138 -315.26607)
		(end 59.153552 -315.26607)
		(width 0.14478)
		(layer "In11.Cu")
		(net "M_F_CPU1_SB_DQ<28>")
	)
	(segment
		(start 60.874148 -314.210446)
		(end 61.293502 -314.6298)
		(width 0.14478)
		(layer "In11.Cu")
		(net "M_F_CPU1_SB_DQ<28>")
	)
	(segment
		(start 29.99359 -316.145164)
		(end 29.672026 -316.145164)
		(width 0.14478)
		(layer "In11.Cu")
		(net "M_F_CPU1_SB_DQ<28>")
	)
	(segment
		(start 42.571162 -315.910468)
		(end 42.260266 -316.221364)
		(width 0.14478)
		(layer "In11.Cu")
		(net "M_F_CPU1_SB_DQ<28>")
	)
	(segment
		(start 38.36162 -315.910468)
		(end 38.116256 -315.910468)
		(width 0.14478)
		(layer "In11.Cu")
		(net "M_F_CPU1_SB_DQ<28>")
	)
	(segment
		(start 23.477474 -316.142116)
		(end 23.477474 -315.756544)
		(width 0.14478)
		(layer "In11.Cu")
		(net "M_F_CPU1_SB_DQ<28>")
	)
	(segment
		(start 50.937922 -316.228984)
		(end 50.700178 -316.228984)
		(width 0.14478)
		(layer "In11.Cu")
		(net "M_F_CPU1_SB_DQ<28>")
	)
	(segment
		(start 41.704006 -315.910468)
		(end 41.458642 -315.910468)
		(width 0.14478)
		(layer "In11.Cu")
		(net "M_F_CPU1_SB_DQ<28>")
	)
	(segment
		(start 24.25573 -315.92012)
		(end 23.87092 -316.30493)
		(width 0.14478)
		(layer "In11.Cu")
		(net "M_F_CPU1_SB_DQ<28>")
	)
	(segment
		(start 34.695384 -316.208664)
		(end 34.43732 -316.208664)
		(width 0.14478)
		(layer "In11.Cu")
		(net "M_F_CPU1_SB_DQ<28>")
	)
	(segment
		(start 42.816526 -315.910468)
		(end 42.571162 -315.910468)
		(width 0.14478)
		(layer "In11.Cu")
		(net "M_F_CPU1_SB_DQ<28>")
	)
	(segment
		(start 37.559996 -316.221364)
		(end 37.2491 -315.910468)
		(width 0.14478)
		(layer "In11.Cu")
		(net "M_F_CPU1_SB_DQ<28>")
	)
	(segment
		(start 31.897066 -316.145164)
		(end 31.731966 -315.980064)
		(width 0.14478)
		(layer "In11.Cu")
		(net "M_F_CPU1_SB_DQ<28>")
	)
	(segment
		(start 42.014902 -316.221364)
		(end 41.704006 -315.910468)
		(width 0.14478)
		(layer "In11.Cu")
		(net "M_F_CPU1_SB_DQ<28>")
	)
	(segment
		(start 46.737016 -315.92012)
		(end 46.458632 -316.198504)
		(width 0.14478)
		(layer "In11.Cu")
		(net "M_F_CPU1_SB_DQ<28>")
	)
	(segment
		(start 58.509154 -315.910468)
		(end 53.158898 -315.910468)
		(width 0.14478)
		(layer "In11.Cu")
		(net "M_F_CPU1_SB_DQ<28>")
	)
	(segment
		(start 50.381662 -315.910468)
		(end 50.143918 -315.910468)
		(width 0.14478)
		(layer "In11.Cu")
		(net "M_F_CPU1_SB_DQ<28>")
	)
	(segment
		(start 84.351114 -291.906198)
		(end 84.505038 -292.171628)
		(width 0.0889)
		(layer "In11.Cu")
		(net "M_F_CPU1_SB_DQ<28>")
	)
	(segment
		(start 79.838042 -292.228778)
		(end 79.835502 -292.230302)
		(width 0.0889)
		(layer "In11.Cu")
		(net "M_F_CPU1_SB_DQ<28>")
	)
	(segment
		(start 81.35239 -292.233604)
		(end 81.344008 -292.228778)
		(width 0.0889)
		(layer "In11.Cu")
		(net "M_F_CPU1_SB_DQ<28>")
	)
	(segment
		(start 49.587658 -316.228984)
		(end 49.269142 -315.910468)
		(width 0.14478)
		(layer "In11.Cu")
		(net "M_F_CPU1_SB_DQ<28>")
	)
	(segment
		(start 60.484258 -314.600336)
		(end 60.279534 -314.600336)
		(width 0.14478)
		(layer "In11.Cu")
		(net "M_F_CPU1_SB_DQ<28>")
	)
	(segment
		(start 44.789852 -315.910468)
		(end 43.683682 -315.910468)
		(width 0.14478)
		(layer "In11.Cu")
		(net "M_F_CPU1_SB_DQ<28>")
	)
	(segment
		(start 27.503882 -316.13983)
		(end 27.503882 -315.711586)
		(width 0.14478)
		(layer "In11.Cu")
		(net "M_F_CPU1_SB_DQ<28>")
	)
	(segment
		(start 43.127422 -316.221364)
		(end 42.816526 -315.910468)
		(width 0.14478)
		(layer "In11.Cu")
		(net "M_F_CPU1_SB_DQ<28>")
	)
	(segment
		(start 61.293502 -314.6298)
		(end 61.293502 -314.834524)
		(width 0.14478)
		(layer "In11.Cu")
		(net "M_F_CPU1_SB_DQ<28>")
	)
	(segment
		(start 50.700178 -316.228984)
		(end 50.381662 -315.910468)
		(width 0.14478)
		(layer "In11.Cu")
		(net "M_F_CPU1_SB_DQ<28>")
	)
	(segment
		(start 35.251644 -315.910468)
		(end 34.99358 -315.910468)
		(width 0.14478)
		(layer "In11.Cu")
		(net "M_F_CPU1_SB_DQ<28>")
	)
	(segment
		(start 34.43732 -316.208664)
		(end 34.139124 -315.910468)
		(width 0.14478)
		(layer "In11.Cu")
		(net "M_F_CPU1_SB_DQ<28>")
	)
	(segment
		(start 41.458642 -315.910468)
		(end 41.147746 -316.221364)
		(width 0.14478)
		(layer "In11.Cu")
		(net "M_F_CPU1_SB_DQ<28>")
	)
	(segment
		(start 52.602638 -316.198504)
		(end 52.314602 -315.910468)
		(width 0.14478)
		(layer "In11.Cu")
		(net "M_F_CPU1_SB_DQ<28>")
	)
	(segment
		(start 61.293502 -314.834524)
		(end 61.108336 -315.01969)
		(width 0.14478)
		(layer "In11.Cu")
		(net "M_F_CPU1_SB_DQ<28>")
	)
	(segment
		(start 35.54984 -316.208664)
		(end 35.251644 -315.910468)
		(width 0.14478)
		(layer "In11.Cu")
		(net "M_F_CPU1_SB_DQ<28>")
	)
	(segment
		(start 23.31466 -315.59373)
		(end 23.084028 -315.59373)
		(width 0.14478)
		(layer "In11.Cu")
		(net "M_F_CPU1_SB_DQ<28>")
	)
	(segment
		(start 26.554176 -316.297564)
		(end 26.176732 -315.92012)
		(width 0.14478)
		(layer "In11.Cu")
		(net "M_F_CPU1_SB_DQ<28>")
	)
	(segment
		(start 34.139124 -315.910468)
		(end 33.88106 -315.910468)
		(width 0.14478)
		(layer "In11.Cu")
		(net "M_F_CPU1_SB_DQ<28>")
	)
	(segment
		(start 49.825402 -316.228984)
		(end 49.587658 -316.228984)
		(width 0.14478)
		(layer "In11.Cu")
		(net "M_F_CPU1_SB_DQ<28>")
	)
	(segment
		(start 28.927044 -315.910468)
		(end 28.453588 -315.437012)
		(width 0.14478)
		(layer "In11.Cu")
		(net "M_F_CPU1_SB_DQ<28>")
	)
	(segment
		(start 77.648054 -297.231816)
		(end 60.874148 -314.005722)
		(width 0.14478)
		(layer "In11.Cu")
		(net "M_F_CPU1_SB_DQ<28>")
	)
	(segment
		(start 31.731966 -315.980064)
		(end 31.27121 -315.980064)
		(width 0.14478)
		(layer "In11.Cu")
		(net "M_F_CPU1_SB_DQ<28>")
	)
	(segment
		(start 28.060142 -315.599826)
		(end 28.060142 -316.13983)
		(width 0.14478)
		(layer "In11.Cu")
		(net "M_F_CPU1_SB_DQ<28>")
	)
	(segment
		(start 45.564552 -315.980064)
		(end 45.346112 -316.198504)
		(width 0.14478)
		(layer "In11.Cu")
		(net "M_F_CPU1_SB_DQ<28>")
	)
	(segment
		(start 41.147746 -316.221364)
		(end 40.902382 -316.221364)
		(width 0.14478)
		(layer "In11.Cu")
		(net "M_F_CPU1_SB_DQ<28>")
	)
	(segment
		(start 40.902382 -316.221364)
		(end 40.601138 -315.92012)
		(width 0.14478)
		(layer "In11.Cu")
		(net "M_F_CPU1_SB_DQ<28>")
	)
	(segment
		(start 29.672026 -316.145164)
		(end 29.43733 -315.910468)
		(width 0.14478)
		(layer "In11.Cu")
		(net "M_F_CPU1_SB_DQ<28>")
	)
	(segment
		(start 78.427834 -294.658796)
		(end 78.387448 -294.682418)
		(width 0.0889)
		(layer "In11.Cu")
		(net "M_F_CPU1_SB_DQ<28>")
	)
	(segment
		(start 39.219124 -315.92012)
		(end 38.91788 -316.221364)
		(width 0.14478)
		(layer "In11.Cu")
		(net "M_F_CPU1_SB_DQ<28>")
	)
	(segment
		(start 78.458568 -294.641016)
		(end 78.427834 -294.658796)
		(width 0.0889)
		(layer "In11.Cu")
		(net "M_F_CPU1_SB_DQ<28>")
	)
	(segment
		(start 28.060142 -316.13983)
		(end 27.897328 -316.302644)
		(width 0.14478)
		(layer "In11.Cu")
		(net "M_F_CPU1_SB_DQ<28>")
	)
	(segment
		(start 30.228286 -315.910468)
		(end 29.99359 -316.145164)
		(width 0.14478)
		(layer "In11.Cu")
		(net "M_F_CPU1_SB_DQ<28>")
	)
	(segment
		(start 37.2491 -315.910468)
		(end 36.1061 -315.910468)
		(width 0.14478)
		(layer "In11.Cu")
		(net "M_F_CPU1_SB_DQ<28>")
	)
	(segment
		(start 46.190408 -316.198504)
		(end 45.971968 -315.980064)
		(width 0.14478)
		(layer "In11.Cu")
		(net "M_F_CPU1_SB_DQ<28>")
	)
	(segment
		(start 53.158898 -315.910468)
		(end 52.870862 -316.198504)
		(width 0.14478)
		(layer "In11.Cu")
		(net "M_F_CPU1_SB_DQ<28>")
	)
	(segment
		(start 80.778096 -292.228778)
		(end 80.777842 -292.228778)
		(width 0.0889)
		(layer "In11.Cu")
		(net "M_F_CPU1_SB_DQ<28>")
	)
	(segment
		(start 22.921214 -315.756544)
		(end 22.921214 -316.142116)
		(width 0.14478)
		(layer "In11.Cu")
		(net "M_F_CPU1_SB_DQ<28>")
	)
	(segment
		(start 46.458632 -316.198504)
		(end 46.190408 -316.198504)
		(width 0.14478)
		(layer "In11.Cu")
		(net "M_F_CPU1_SB_DQ<28>")
	)
	(segment
		(start 51.256438 -315.910468)
		(end 50.937922 -316.228984)
		(width 0.14478)
		(layer "In11.Cu")
		(net "M_F_CPU1_SB_DQ<28>")
	)
	(segment
		(start 38.116256 -315.910468)
		(end 37.80536 -316.221364)
		(width 0.14478)
		(layer "In11.Cu")
		(net "M_F_CPU1_SB_DQ<28>")
	)
	(segment
		(start 33.582864 -316.208664)
		(end 33.3248 -316.208664)
		(width 0.14478)
		(layer "In11.Cu")
		(net "M_F_CPU1_SB_DQ<28>")
	)
	(segment
		(start 32.21863 -316.145164)
		(end 31.897066 -316.145164)
		(width 0.14478)
		(layer "In11.Cu")
		(net "M_F_CPU1_SB_DQ<28>")
	)
	(segment
		(start 52.870862 -316.198504)
		(end 52.602638 -316.198504)
		(width 0.14478)
		(layer "In11.Cu")
		(net "M_F_CPU1_SB_DQ<28>")
	)
	(segment
		(start 26.176732 -315.92012)
		(end 24.25573 -315.92012)
		(width 0.14478)
		(layer "In11.Cu")
		(net "M_F_CPU1_SB_DQ<28>")
	)
	(segment
		(start 33.036256 -315.92012)
		(end 32.443674 -315.92012)
		(width 0.14478)
		(layer "In11.Cu")
		(net "M_F_CPU1_SB_DQ<28>")
	)
	(segment
		(start 27.359102 -315.566806)
		(end 27.092402 -315.566806)
		(width 0.14478)
		(layer "In11.Cu")
		(net "M_F_CPU1_SB_DQ<28>")
	)
	(segment
		(start 43.372786 -316.221364)
		(end 43.127422 -316.221364)
		(width 0.14478)
		(layer "In11.Cu")
		(net "M_F_CPU1_SB_DQ<28>")
	)
	(segment
		(start 45.346112 -316.198504)
		(end 45.077888 -316.198504)
		(width 0.14478)
		(layer "In11.Cu")
		(net "M_F_CPU1_SB_DQ<28>")
	)
	(segment
		(start 31.10611 -316.145164)
		(end 30.784546 -316.145164)
		(width 0.14478)
		(layer "In11.Cu")
		(net "M_F_CPU1_SB_DQ<28>")
	)
	(segment
		(start 43.683682 -315.910468)
		(end 43.372786 -316.221364)
		(width 0.14478)
		(layer "In11.Cu")
		(net "M_F_CPU1_SB_DQ<28>")
	)
	(segment
		(start 78.245208 -294.885872)
		(end 78.245208 -295.790112)
		(width 0.0889)
		(layer "In11.Cu")
		(net "M_F_CPU1_SB_DQ<28>")
	)
	(segment
		(start 78.897988 -293.84879)
		(end 78.860142 -293.870634)
		(width 0.0889)
		(layer "In11.Cu")
		(net "M_F_CPU1_SB_DQ<28>")
	)
	(segment
		(start 60.279534 -314.600336)
		(end 59.6138 -315.26607)
		(width 0.14478)
		(layer "In11.Cu")
		(net "M_F_CPU1_SB_DQ<28>")
	)
	(segment
		(start 48.166274 -315.92012)
		(end 46.737016 -315.92012)
		(width 0.14478)
		(layer "In11.Cu")
		(net "M_F_CPU1_SB_DQ<28>")
	)
	(segment
		(start 61.108336 -315.01969)
		(end 60.903612 -315.01969)
		(width 0.14478)
		(layer "In11.Cu")
		(net "M_F_CPU1_SB_DQ<28>")
	)
	(segment
		(start 38.672516 -316.221364)
		(end 38.36162 -315.910468)
		(width 0.14478)
		(layer "In11.Cu")
		(net "M_F_CPU1_SB_DQ<28>")
	)
	(segment
		(start 49.031398 -315.910468)
		(end 48.712882 -316.228984)
		(width 0.14478)
		(layer "In11.Cu")
		(net "M_F_CPU1_SB_DQ<28>")
	)
	(segment
		(start 34.99358 -315.910468)
		(end 34.695384 -316.208664)
		(width 0.14478)
		(layer "In11.Cu")
		(net "M_F_CPU1_SB_DQ<28>")
	)
	(segment
		(start 36.1061 -315.910468)
		(end 35.807904 -316.208664)
		(width 0.14478)
		(layer "In11.Cu")
		(net "M_F_CPU1_SB_DQ<28>")
	)
	(segment
		(start 33.3248 -316.208664)
		(end 33.036256 -315.92012)
		(width 0.14478)
		(layer "In11.Cu")
		(net "M_F_CPU1_SB_DQ<28>")
	)
	(segment
		(start 38.91788 -316.221364)
		(end 38.672516 -316.221364)
		(width 0.14478)
		(layer "In11.Cu")
		(net "M_F_CPU1_SB_DQ<28>")
	)
	(segment
		(start 23.084028 -315.59373)
		(end 22.921214 -315.756544)
		(width 0.14478)
		(layer "In11.Cu")
		(net "M_F_CPU1_SB_DQ<28>")
	)
	(segment
		(start 27.666696 -316.302644)
		(end 27.503882 -316.13983)
		(width 0.14478)
		(layer "In11.Cu")
		(net "M_F_CPU1_SB_DQ<28>")
	)
	(segment
		(start 79.368142 -293.038784)
		(end 79.329026 -293.061644)
		(width 0.0889)
		(layer "In11.Cu")
		(net "M_F_CPU1_SB_DQ<28>")
	)
	(segment
		(start 45.077888 -316.198504)
		(end 44.789852 -315.910468)
		(width 0.14478)
		(layer "In11.Cu")
		(net "M_F_CPU1_SB_DQ<28>")
	)
	(segment
		(start 27.503882 -315.711586)
		(end 27.359102 -315.566806)
		(width 0.14478)
		(layer "In11.Cu")
		(net "M_F_CPU1_SB_DQ<28>")
	)
	(segment
		(start 48.712882 -316.228984)
		(end 48.475138 -316.228984)
		(width 0.14478)
		(layer "In11.Cu")
		(net "M_F_CPU1_SB_DQ<28>")
	)
	(segment
		(start 22.7584 -316.30493)
		(end 22.527768 -316.30493)
		(width 0.14478)
		(layer "In11.Cu")
		(net "M_F_CPU1_SB_DQ<28>")
	)
	(segment
		(start 23.87092 -316.30493)
		(end 23.640288 -316.30493)
		(width 0.14478)
		(layer "In11.Cu")
		(net "M_F_CPU1_SB_DQ<28>")
	)
	(segment
		(start 83.598004 -292.228778)
		(end 83.589622 -292.233604)
		(width 0.0889)
		(layer "In11.Cu")
		(net "M_F_CPU1_SB_DQ<28>")
	)
	(segment
		(start 42.260266 -316.221364)
		(end 42.014902 -316.221364)
		(width 0.14478)
		(layer "In11.Cu")
		(net "M_F_CPU1_SB_DQ<28>")
	)
	(segment
		(start 23.640288 -316.30493)
		(end 23.477474 -316.142116)
		(width 0.14478)
		(layer "In11.Cu")
		(net "M_F_CPU1_SB_DQ<28>")
	)
	(segment
		(start 26.784808 -316.297564)
		(end 26.554176 -316.297564)
		(width 0.14478)
		(layer "In11.Cu")
		(net "M_F_CPU1_SB_DQ<28>")
	)
	(segment
		(start 32.443674 -315.92012)
		(end 32.21863 -316.145164)
		(width 0.14478)
		(layer "In11.Cu")
		(net "M_F_CPU1_SB_DQ<28>")
	)
	(segment
		(start 27.897328 -316.302644)
		(end 27.666696 -316.302644)
		(width 0.14478)
		(layer "In11.Cu")
		(net "M_F_CPU1_SB_DQ<28>")
	)
	(segment
		(start 50.143918 -315.910468)
		(end 49.825402 -316.228984)
		(width 0.14478)
		(layer "In11.Cu")
		(net "M_F_CPU1_SB_DQ<28>")
	)
	(segment
		(start 23.477474 -315.756544)
		(end 23.31466 -315.59373)
		(width 0.14478)
		(layer "In11.Cu")
		(net "M_F_CPU1_SB_DQ<28>")
	)
	(segment
		(start 84.505038 -292.171628)
		(end 84.482686 -292.25494)
		(width 0.0889)
		(layer "In11.Cu")
		(net "M_F_CPU1_SB_DQ<28>")
	)
	(segment
		(start 52.314602 -315.910468)
		(end 51.256438 -315.910468)
		(width 0.14478)
		(layer "In11.Cu")
		(net "M_F_CPU1_SB_DQ<28>")
	)
	(segment
		(start 37.80536 -316.221364)
		(end 37.559996 -316.221364)
		(width 0.14478)
		(layer "In11.Cu")
		(net "M_F_CPU1_SB_DQ<28>")
	)
	(segment
		(start 30.54985 -315.910468)
		(end 30.228286 -315.910468)
		(width 0.14478)
		(layer "In11.Cu")
		(net "M_F_CPU1_SB_DQ<28>")
	)
	(segment
		(start 31.27121 -315.980064)
		(end 31.10611 -316.145164)
		(width 0.14478)
		(layer "In11.Cu")
		(net "M_F_CPU1_SB_DQ<28>")
	)
	(segment
		(start 28.222956 -315.437012)
		(end 28.060142 -315.599826)
		(width 0.14478)
		(layer "In11.Cu")
		(net "M_F_CPU1_SB_DQ<28>")
	)
	(segment
		(start 33.88106 -315.910468)
		(end 33.582864 -316.208664)
		(width 0.14478)
		(layer "In11.Cu")
		(net "M_F_CPU1_SB_DQ<28>")
	)
	(segment
		(start 28.453588 -315.437012)
		(end 28.222956 -315.437012)
		(width 0.14478)
		(layer "In11.Cu")
		(net "M_F_CPU1_SB_DQ<28>")
	)
	(segment
		(start 78.929738 -293.830502)
		(end 78.897988 -293.84879)
		(width 0.0889)
		(layer "In11.Cu")
		(net "M_F_CPU1_SB_DQ<28>")
	)
	(segment
		(start 22.921214 -316.142116)
		(end 22.7584 -316.30493)
		(width 0.14478)
		(layer "In11.Cu")
		(net "M_F_CPU1_SB_DQ<28>")
	)
	(segment
		(start 26.947622 -315.711586)
		(end 26.947622 -316.13475)
		(width 0.14478)
		(layer "In11.Cu")
		(net "M_F_CPU1_SB_DQ<28>")
	)
	(segment
		(start 30.784546 -316.145164)
		(end 30.54985 -315.910468)
		(width 0.14478)
		(layer "In11.Cu")
		(net "M_F_CPU1_SB_DQ<28>")
	)
	(segment
		(start 48.475138 -316.228984)
		(end 48.166274 -315.92012)
		(width 0.14478)
		(layer "In11.Cu")
		(net "M_F_CPU1_SB_DQ<28>")
	)
	(segment
		(start 49.269142 -315.910468)
		(end 49.031398 -315.910468)
		(width 0.14478)
		(layer "In11.Cu")
		(net "M_F_CPU1_SB_DQ<28>")
	)
	(segment
		(start 29.43733 -315.910468)
		(end 28.927044 -315.910468)
		(width 0.14478)
		(layer "In11.Cu")
		(net "M_F_CPU1_SB_DQ<28>")
	)
	(segment
		(start 40.601138 -315.92012)
		(end 39.219124 -315.92012)
		(width 0.14478)
		(layer "In11.Cu")
		(net "M_F_CPU1_SB_DQ<28>")
	)
	(segment
		(start 59.153552 -315.26607)
		(end 58.509154 -315.910468)
		(width 0.14478)
		(layer "In11.Cu")
		(net "M_F_CPU1_SB_DQ<28>")
	)
	(segment
		(start 79.398622 -293.021004)
		(end 79.368142 -293.038784)
		(width 0.0889)
		(layer "In11.Cu")
		(net "M_F_CPU1_SB_DQ<28>")
	)
	(segment
		(start 26.947622 -316.13475)
		(end 26.784808 -316.297564)
		(width 0.14478)
		(layer "In11.Cu")
		(net "M_F_CPU1_SB_DQ<28>")
	)
	(arc
		(start 79.329026 -293.061644)
		(mid 79.150213 -293.263994)
		(end 79.085694 -293.52621)
		(width 0.0889)
		(layer "In11.Cu")
		(net "M_F_CPU1_SB_DQ<28>")
	)
	(arc
		(start 83.589622 -292.233604)
		(mid 83.406114 -292.279098)
		(end 83.223862 -292.228778)
		(width 0.0889)
		(layer "In11.Cu")
		(net "M_F_CPU1_SB_DQ<28>")
	)
	(arc
		(start 78.61554 -294.336216)
		(mid 78.573991 -294.507638)
		(end 78.458568 -294.641016)
		(width 0.0889)
		(layer "In11.Cu")
		(net "M_F_CPU1_SB_DQ<28>")
	)
	(arc
		(start 80.403954 -292.228778)
		(mid 80.120998 -292.152601)
		(end 79.838042 -292.228778)
		(width 0.0889)
		(layer "In11.Cu")
		(net "M_F_CPU1_SB_DQ<28>")
	)
	(arc
		(start 84.482686 -292.25494)
		(mid 84.320354 -292.277758)
		(end 84.163916 -292.228778)
		(width 0.0889)
		(layer "In11.Cu")
		(net "M_F_CPU1_SB_DQ<28>")
	)
	(arc
		(start 83.223862 -292.228778)
		(mid 82.940906 -292.152601)
		(end 82.65795 -292.228778)
		(width 0.0889)
		(layer "In11.Cu")
		(net "M_F_CPU1_SB_DQ<28>")
	)
	(arc
		(start 82.284062 -292.228778)
		(mid 82.001106 -292.152601)
		(end 81.71815 -292.228778)
		(width 0.0889)
		(layer "In11.Cu")
		(net "M_F_CPU1_SB_DQ<28>")
	)
	(arc
		(start 79.555594 -292.716204)
		(mid 79.514045 -292.887626)
		(end 79.398622 -293.021004)
		(width 0.0889)
		(layer "In11.Cu")
		(net "M_F_CPU1_SB_DQ<28>")
	)
	(arc
		(start 79.835502 -292.230302)
		(mid 79.630538 -292.435812)
		(end 79.555594 -292.716204)
		(width 0.0889)
		(layer "In11.Cu")
		(net "M_F_CPU1_SB_DQ<28>")
	)
	(arc
		(start 78.245208 -295.790112)
		(mid 78.090009 -296.570349)
		(end 77.648054 -297.231816)
		(width 0.0889)
		(layer "In11.Cu")
		(net "M_F_CPU1_SB_DQ<28>")
	)
	(arc
		(start 84.163916 -292.228778)
		(mid 83.88096 -292.152601)
		(end 83.598004 -292.228778)
		(width 0.0889)
		(layer "In11.Cu")
		(net "M_F_CPU1_SB_DQ<28>")
	)
	(arc
		(start 80.777842 -292.228778)
		(mid 80.590898 -292.279102)
		(end 80.403954 -292.228778)
		(width 0.0889)
		(layer "In11.Cu")
		(net "M_F_CPU1_SB_DQ<28>")
	)
	(arc
		(start 78.29042 -294.767762)
		(mid 78.256865 -294.822624)
		(end 78.245208 -294.885872)
		(width 0.0889)
		(layer "In11.Cu")
		(net "M_F_CPU1_SB_DQ<28>")
	)
	(arc
		(start 78.860142 -293.870634)
		(mid 78.680413 -294.073254)
		(end 78.61554 -294.336216)
		(width 0.0889)
		(layer "In11.Cu")
		(net "M_F_CPU1_SB_DQ<28>")
	)
	(arc
		(start 82.65795 -292.228778)
		(mid 82.471006 -292.279033)
		(end 82.284062 -292.228778)
		(width 0.0889)
		(layer "In11.Cu")
		(net "M_F_CPU1_SB_DQ<28>")
	)
	(arc
		(start 78.387448 -294.682418)
		(mid 78.336485 -294.722306)
		(end 78.29042 -294.767762)
		(width 0.0889)
		(layer "In11.Cu")
		(net "M_F_CPU1_SB_DQ<28>")
	)
	(arc
		(start 79.085694 -293.52621)
		(mid 79.044439 -293.697181)
		(end 78.929738 -293.830502)
		(width 0.0889)
		(layer "In11.Cu")
		(net "M_F_CPU1_SB_DQ<28>")
	)
	(arc
		(start 81.344008 -292.228778)
		(mid 81.061052 -292.152601)
		(end 80.778096 -292.228778)
		(width 0.0889)
		(layer "In11.Cu")
		(net "M_F_CPU1_SB_DQ<28>")
	)
	(arc
		(start 81.71815 -292.228778)
		(mid 81.535899 -292.279128)
		(end 81.35239 -292.233604)
		(width 0.0889)
		(layer "In11.Cu")
		(net "M_F_CPU1_SB_DQ<28>")
	)
	(segment
		(start 86.69782 -290.020248)
		(end 86.230968 -290.286186)
		(width 0.10668)
		(layer "F.Cu")
		(net "M_F_CPU1_SB_DQ<27>")
	)
	(segment
		(start 35.21837 -311.650634)
		(end 34.368486 -312.500518)
		(width 0.14478)
		(layer "In11.Cu")
		(net "M_F_CPU1_SB_DQ<27>")
	)
	(segment
		(start 34.368486 -312.500518)
		(end 31.383986 -312.500518)
		(width 0.14478)
		(layer "In11.Cu")
		(net "M_F_CPU1_SB_DQ<27>")
	)
	(segment
		(start 20.83943 -312.50128)
		(end 19.393662 -312.50128)
		(width 0.14478)
		(layer "In11.Cu")
		(net "M_F_CPU1_SB_DQ<27>")
	)
	(segment
		(start 50.249582 -311.650634)
		(end 49.399698 -312.500518)
		(width 0.14478)
		(layer "In11.Cu")
		(net "M_F_CPU1_SB_DQ<27>")
	)
	(segment
		(start 18.697448 -312.059066)
		(end 18.697448 -312.3565)
		(width 0.14478)
		(layer "In11.Cu")
		(net "M_F_CPU1_SB_DQ<27>")
	)
	(segment
		(start 86.230968 -290.286186)
		(end 86.077044 -290.020756)
		(width 0.0889)
		(layer "In11.Cu")
		(net "M_F_CPU1_SB_DQ<27>")
	)
	(segment
		(start 85.112352 -289.95878)
		(end 85.10397 -289.963606)
		(width 0.0889)
		(layer "In11.Cu")
		(net "M_F_CPU1_SB_DQ<27>")
	)
	(segment
		(start 20.98421 -312.3565)
		(end 20.83943 -312.50128)
		(width 0.14478)
		(layer "In11.Cu")
		(net "M_F_CPU1_SB_DQ<27>")
	)
	(segment
		(start 83.598004 -289.963606)
		(end 83.589622 -289.95878)
		(width 0.0889)
		(layer "In11.Cu")
		(net "M_F_CPU1_SB_DQ<27>")
	)
	(segment
		(start 78.317852 -291.07765)
		(end 77.606144 -291.789358)
		(width 0.0889)
		(layer "In11.Cu")
		(net "M_F_CPU1_SB_DQ<27>")
	)
	(segment
		(start 18.552668 -312.50128)
		(end 18.024094 -312.50128)
		(width 0.14478)
		(layer "In11.Cu")
		(net "M_F_CPU1_SB_DQ<27>")
	)
	(segment
		(start 18.024094 -312.50128)
		(end 17.608042 -312.085228)
		(width 0.14478)
		(layer "In11.Cu")
		(net "M_F_CPU1_SB_DQ<27>")
	)
	(segment
		(start 18.697448 -312.3565)
		(end 18.552668 -312.50128)
		(width 0.14478)
		(layer "In11.Cu")
		(net "M_F_CPU1_SB_DQ<27>")
	)
	(segment
		(start 19.393662 -312.50128)
		(end 19.248882 -312.3565)
		(width 0.14478)
		(layer "In11.Cu")
		(net "M_F_CPU1_SB_DQ<27>")
	)
	(segment
		(start 38.95344 -312.500518)
		(end 38.103556 -311.650634)
		(width 0.14478)
		(layer "In11.Cu")
		(net "M_F_CPU1_SB_DQ<27>")
	)
	(segment
		(start 77.606144 -291.789358)
		(end 77.606144 -292.454076)
		(width 0.0889)
		(layer "In11.Cu")
		(net "M_F_CPU1_SB_DQ<27>")
	)
	(segment
		(start 49.399698 -312.500518)
		(end 46.458886 -312.500518)
		(width 0.14478)
		(layer "In11.Cu")
		(net "M_F_CPU1_SB_DQ<27>")
	)
	(segment
		(start 31.383986 -312.500518)
		(end 30.534102 -311.650634)
		(width 0.14478)
		(layer "In11.Cu")
		(net "M_F_CPU1_SB_DQ<27>")
	)
	(segment
		(start 77.606144 -292.454076)
		(end 77.238352 -292.821868)
		(width 0.0889)
		(layer "In11.Cu")
		(net "M_F_CPU1_SB_DQ<27>")
	)
	(segment
		(start 86.077044 -290.020756)
		(end 85.981032 -289.995356)
		(width 0.0889)
		(layer "In11.Cu")
		(net "M_F_CPU1_SB_DQ<27>")
	)
	(segment
		(start 30.534102 -311.650634)
		(end 27.659076 -311.650634)
		(width 0.14478)
		(layer "In11.Cu")
		(net "M_F_CPU1_SB_DQ<27>")
	)
	(segment
		(start 79.53502 -289.961574)
		(end 78.977744 -290.51885)
		(width 0.0889)
		(layer "In11.Cu")
		(net "M_F_CPU1_SB_DQ<27>")
	)
	(segment
		(start 19.248882 -312.059066)
		(end 19.104102 -311.914286)
		(width 0.14478)
		(layer "In11.Cu")
		(net "M_F_CPU1_SB_DQ<27>")
	)
	(segment
		(start 80.778096 -289.963606)
		(end 80.769714 -289.95878)
		(width 0.0889)
		(layer "In11.Cu")
		(net "M_F_CPU1_SB_DQ<27>")
	)
	(segment
		(start 59.680602 -311.660286)
		(end 57.389776 -311.660286)
		(width 0.14478)
		(layer "In11.Cu")
		(net "M_F_CPU1_SB_DQ<27>")
	)
	(segment
		(start 62.529466 -307.254148)
		(end 62.529466 -308.811422)
		(width 0.14478)
		(layer "In11.Cu")
		(net "M_F_CPU1_SB_DQ<27>")
	)
	(segment
		(start 77.238352 -292.821868)
		(end 76.961746 -292.821868)
		(width 0.0889)
		(layer "In11.Cu")
		(net "M_F_CPU1_SB_DQ<27>")
	)
	(segment
		(start 21.680424 -312.50128)
		(end 21.535644 -312.3565)
		(width 0.14478)
		(layer "In11.Cu")
		(net "M_F_CPU1_SB_DQ<27>")
	)
	(segment
		(start 84.538058 -289.963606)
		(end 84.529676 -289.95878)
		(width 0.0889)
		(layer "In11.Cu")
		(net "M_F_CPU1_SB_DQ<27>")
	)
	(segment
		(start 21.535644 -312.221626)
		(end 21.390864 -312.076846)
		(width 0.14478)
		(layer "In11.Cu")
		(net "M_F_CPU1_SB_DQ<27>")
	)
	(segment
		(start 57.389776 -311.660286)
		(end 56.935116 -312.114946)
		(width 0.14478)
		(layer "In11.Cu")
		(net "M_F_CPU1_SB_DQ<27>")
	)
	(segment
		(start 76.78674 -292.996874)
		(end 62.529466 -307.254148)
		(width 0.14478)
		(layer "In11.Cu")
		(net "M_F_CPU1_SB_DQ<27>")
	)
	(segment
		(start 27.659076 -311.650634)
		(end 26.80843 -312.50128)
		(width 0.14478)
		(layer "In11.Cu")
		(net "M_F_CPU1_SB_DQ<27>")
	)
	(segment
		(start 46.458886 -312.500518)
		(end 45.609002 -311.650634)
		(width 0.14478)
		(layer "In11.Cu")
		(net "M_F_CPU1_SB_DQ<27>")
	)
	(segment
		(start 18.842228 -311.914286)
		(end 18.697448 -312.059066)
		(width 0.14478)
		(layer "In11.Cu")
		(net "M_F_CPU1_SB_DQ<27>")
	)
	(segment
		(start 41.901872 -312.500518)
		(end 38.95344 -312.500518)
		(width 0.14478)
		(layer "In11.Cu")
		(net "M_F_CPU1_SB_DQ<27>")
	)
	(segment
		(start 42.751756 -311.650634)
		(end 41.901872 -312.500518)
		(width 0.14478)
		(layer "In11.Cu")
		(net "M_F_CPU1_SB_DQ<27>")
	)
	(segment
		(start 80.403954 -289.963606)
		(end 80.39354 -289.969702)
		(width 0.0889)
		(layer "In11.Cu")
		(net "M_F_CPU1_SB_DQ<27>")
	)
	(segment
		(start 56.935116 -312.114946)
		(end 53.609748 -312.114946)
		(width 0.14478)
		(layer "In11.Cu")
		(net "M_F_CPU1_SB_DQ<27>")
	)
	(segment
		(start 20.98421 -312.221626)
		(end 20.98421 -312.3565)
		(width 0.14478)
		(layer "In11.Cu")
		(net "M_F_CPU1_SB_DQ<27>")
	)
	(segment
		(start 21.535644 -312.3565)
		(end 21.535644 -312.221626)
		(width 0.14478)
		(layer "In11.Cu")
		(net "M_F_CPU1_SB_DQ<27>")
	)
	(segment
		(start 53.609748 -312.114946)
		(end 53.145436 -311.650634)
		(width 0.14478)
		(layer "In11.Cu")
		(net "M_F_CPU1_SB_DQ<27>")
	)
	(segment
		(start 45.609002 -311.650634)
		(end 42.751756 -311.650634)
		(width 0.14478)
		(layer "In11.Cu")
		(net "M_F_CPU1_SB_DQ<27>")
	)
	(segment
		(start 78.521306 -290.794186)
		(end 78.374748 -290.940744)
		(width 0.0889)
		(layer "In11.Cu")
		(net "M_F_CPU1_SB_DQ<27>")
	)
	(segment
		(start 21.390864 -312.076846)
		(end 21.12899 -312.076846)
		(width 0.14478)
		(layer "In11.Cu")
		(net "M_F_CPU1_SB_DQ<27>")
	)
	(segment
		(start 21.12899 -312.076846)
		(end 20.98421 -312.221626)
		(width 0.14478)
		(layer "In11.Cu")
		(net "M_F_CPU1_SB_DQ<27>")
	)
	(segment
		(start 76.961746 -292.821868)
		(end 76.78674 -292.996874)
		(width 0.0889)
		(layer "In11.Cu")
		(net "M_F_CPU1_SB_DQ<27>")
	)
	(segment
		(start 81.35239 -289.95878)
		(end 81.344008 -289.963606)
		(width 0.0889)
		(layer "In11.Cu")
		(net "M_F_CPU1_SB_DQ<27>")
	)
	(segment
		(start 38.103556 -311.650634)
		(end 35.21837 -311.650634)
		(width 0.14478)
		(layer "In11.Cu")
		(net "M_F_CPU1_SB_DQ<27>")
	)
	(segment
		(start 26.80843 -312.50128)
		(end 21.680424 -312.50128)
		(width 0.14478)
		(layer "In11.Cu")
		(net "M_F_CPU1_SB_DQ<27>")
	)
	(segment
		(start 62.529466 -308.811422)
		(end 59.680602 -311.660286)
		(width 0.14478)
		(layer "In11.Cu")
		(net "M_F_CPU1_SB_DQ<27>")
	)
	(segment
		(start 19.248882 -312.3565)
		(end 19.248882 -312.059066)
		(width 0.14478)
		(layer "In11.Cu")
		(net "M_F_CPU1_SB_DQ<27>")
	)
	(segment
		(start 19.104102 -311.914286)
		(end 18.842228 -311.914286)
		(width 0.14478)
		(layer "In11.Cu")
		(net "M_F_CPU1_SB_DQ<27>")
	)
	(segment
		(start 53.145436 -311.650634)
		(end 50.249582 -311.650634)
		(width 0.14478)
		(layer "In11.Cu")
		(net "M_F_CPU1_SB_DQ<27>")
	)
	(arc
		(start 78.977744 -290.51885)
		(mid 78.930375 -290.560806)
		(end 78.878176 -290.596574)
		(width 0.0889)
		(layer "In11.Cu")
		(net "M_F_CPU1_SB_DQ<27>")
	)
	(arc
		(start 81.71815 -289.963606)
		(mid 81.535899 -289.913256)
		(end 81.35239 -289.95878)
		(width 0.0889)
		(layer "In11.Cu")
		(net "M_F_CPU1_SB_DQ<27>")
	)
	(arc
		(start 79.652114 -289.91306)
		(mid 79.588702 -289.925575)
		(end 79.53502 -289.961574)
		(width 0.0889)
		(layer "In11.Cu")
		(net "M_F_CPU1_SB_DQ<27>")
	)
	(arc
		(start 78.374748 -290.940744)
		(mid 78.355383 -290.969631)
		(end 78.348586 -291.003736)
		(width 0.0889)
		(layer "In11.Cu")
		(net "M_F_CPU1_SB_DQ<27>")
	)
	(arc
		(start 85.478112 -289.963606)
		(mid 85.295861 -289.913256)
		(end 85.112352 -289.95878)
		(width 0.0889)
		(layer "In11.Cu")
		(net "M_F_CPU1_SB_DQ<27>")
	)
	(arc
		(start 85.10397 -289.963606)
		(mid 84.821014 -290.039783)
		(end 84.538058 -289.963606)
		(width 0.0889)
		(layer "In11.Cu")
		(net "M_F_CPU1_SB_DQ<27>")
	)
	(arc
		(start 78.348586 -291.003736)
		(mid 78.34059 -291.043754)
		(end 78.317852 -291.07765)
		(width 0.0889)
		(layer "In11.Cu")
		(net "M_F_CPU1_SB_DQ<27>")
	)
	(arc
		(start 83.589622 -289.95878)
		(mid 83.406114 -289.913286)
		(end 83.223862 -289.963606)
		(width 0.0889)
		(layer "In11.Cu")
		(net "M_F_CPU1_SB_DQ<27>")
	)
	(arc
		(start 81.344008 -289.963606)
		(mid 81.061052 -290.039783)
		(end 80.778096 -289.963606)
		(width 0.0889)
		(layer "In11.Cu")
		(net "M_F_CPU1_SB_DQ<27>")
	)
	(arc
		(start 84.163916 -289.963606)
		(mid 83.88096 -290.039783)
		(end 83.598004 -289.963606)
		(width 0.0889)
		(layer "In11.Cu")
		(net "M_F_CPU1_SB_DQ<27>")
	)
	(arc
		(start 83.223862 -289.963606)
		(mid 82.940906 -290.039783)
		(end 82.65795 -289.963606)
		(width 0.0889)
		(layer "In11.Cu")
		(net "M_F_CPU1_SB_DQ<27>")
	)
	(arc
		(start 78.756764 -290.651184)
		(mid 78.630452 -290.708553)
		(end 78.521306 -290.794186)
		(width 0.0889)
		(layer "In11.Cu")
		(net "M_F_CPU1_SB_DQ<27>")
	)
	(arc
		(start 79.837788 -289.963606)
		(mid 79.748267 -289.926152)
		(end 79.652114 -289.91306)
		(width 0.0889)
		(layer "In11.Cu")
		(net "M_F_CPU1_SB_DQ<27>")
	)
	(arc
		(start 84.529676 -289.95878)
		(mid 84.346168 -289.913286)
		(end 84.163916 -289.963606)
		(width 0.0889)
		(layer "In11.Cu")
		(net "M_F_CPU1_SB_DQ<27>")
	)
	(arc
		(start 82.65795 -289.963606)
		(mid 82.471006 -289.913351)
		(end 82.284062 -289.963606)
		(width 0.0889)
		(layer "In11.Cu")
		(net "M_F_CPU1_SB_DQ<27>")
	)
	(arc
		(start 85.981032 -289.995356)
		(mid 85.725824 -290.038833)
		(end 85.478112 -289.963606)
		(width 0.0889)
		(layer "In11.Cu")
		(net "M_F_CPU1_SB_DQ<27>")
	)
	(arc
		(start 78.878176 -290.596574)
		(mid 78.819041 -290.627374)
		(end 78.756764 -290.651184)
		(width 0.0889)
		(layer "In11.Cu")
		(net "M_F_CPU1_SB_DQ<27>")
	)
	(arc
		(start 80.769714 -289.95878)
		(mid 80.586206 -289.913286)
		(end 80.403954 -289.963606)
		(width 0.0889)
		(layer "In11.Cu")
		(net "M_F_CPU1_SB_DQ<27>")
	)
	(arc
		(start 80.39354 -289.969702)
		(mid 80.114854 -290.039922)
		(end 79.837788 -289.963606)
		(width 0.0889)
		(layer "In11.Cu")
		(net "M_F_CPU1_SB_DQ<27>")
	)
	(arc
		(start 82.284062 -289.963606)
		(mid 82.001106 -290.039783)
		(end 81.71815 -289.963606)
		(width 0.0889)
		(layer "In11.Cu")
		(net "M_F_CPU1_SB_DQ<27>")
	)
	(segment
		(start 85.287866 -289.210242)
		(end 84.821014 -289.47618)
		(width 0.10668)
		(layer "F.Cu")
		(net "M_F_CPU1_SB_DQ<26>")
	)
	(segment
		(start 46.34357 -310.810402)
		(end 45.493432 -309.960264)
		(width 0.14478)
		(layer "In11.Cu")
		(net "M_F_CPU1_SB_DQ<26>")
	)
	(segment
		(start 43.03014 -309.960264)
		(end 42.180002 -310.810402)
		(width 0.14478)
		(layer "In11.Cu")
		(net "M_F_CPU1_SB_DQ<26>")
	)
	(segment
		(start 18.5166 -310.810402)
		(end 18.033238 -310.810402)
		(width 0.14478)
		(layer "In11.Cu")
		(net "M_F_CPU1_SB_DQ<26>")
	)
	(segment
		(start 79.369158 -289.1536)
		(end 79.357474 -289.146742)
		(width 0.0889)
		(layer "In11.Cu")
		(net "M_F_CPU1_SB_DQ<26>")
	)
	(segment
		(start 84.66709 -289.21075)
		(end 84.571078 -289.18535)
		(width 0.0889)
		(layer "In11.Cu")
		(net "M_F_CPU1_SB_DQ<26>")
	)
	(segment
		(start 18.66138 -310.955182)
		(end 18.5166 -310.810402)
		(width 0.14478)
		(layer "In11.Cu")
		(net "M_F_CPU1_SB_DQ<26>")
	)
	(segment
		(start 20.722336 -310.331866)
		(end 20.460462 -310.331866)
		(width 0.14478)
		(layer "In11.Cu")
		(net "M_F_CPU1_SB_DQ<26>")
	)
	(segment
		(start 82.18805 -289.1536)
		(end 82.179668 -289.148774)
		(width 0.0889)
		(layer "In11.Cu")
		(net "M_F_CPU1_SB_DQ<26>")
	)
	(segment
		(start 84.821014 -289.47618)
		(end 84.66709 -289.21075)
		(width 0.0889)
		(layer "In11.Cu")
		(net "M_F_CPU1_SB_DQ<26>")
	)
	(segment
		(start 19.068034 -311.288938)
		(end 18.80616 -311.288938)
		(width 0.14478)
		(layer "In11.Cu")
		(net "M_F_CPU1_SB_DQ<26>")
	)
	(segment
		(start 20.460462 -310.331866)
		(end 20.315682 -310.476646)
		(width 0.14478)
		(layer "In11.Cu")
		(net "M_F_CPU1_SB_DQ<26>")
	)
	(segment
		(start 57.793636 -309.969916)
		(end 56.95315 -310.810402)
		(width 0.14478)
		(layer "In11.Cu")
		(net "M_F_CPU1_SB_DQ<26>")
	)
	(segment
		(start 61.40069 -306.805838)
		(end 61.40069 -308.364128)
		(width 0.14478)
		(layer "In11.Cu")
		(net "M_F_CPU1_SB_DQ<26>")
	)
	(segment
		(start 31.17977 -310.810402)
		(end 30.329632 -309.960264)
		(width 0.14478)
		(layer "In11.Cu")
		(net "M_F_CPU1_SB_DQ<26>")
	)
	(segment
		(start 26.850594 -310.810402)
		(end 21.011896 -310.810402)
		(width 0.14478)
		(layer "In11.Cu")
		(net "M_F_CPU1_SB_DQ<26>")
	)
	(segment
		(start 50.284888 -309.960264)
		(end 49.43475 -310.810402)
		(width 0.14478)
		(layer "In11.Cu")
		(net "M_F_CPU1_SB_DQ<26>")
	)
	(segment
		(start 78.608682 -289.355784)
		(end 77.64145 -290.323016)
		(width 0.0889)
		(layer "In11.Cu")
		(net "M_F_CPU1_SB_DQ<26>")
	)
	(segment
		(start 30.329632 -309.960264)
		(end 27.700732 -309.960264)
		(width 0.14478)
		(layer "In11.Cu")
		(net "M_F_CPU1_SB_DQ<26>")
	)
	(segment
		(start 38.647878 -310.810402)
		(end 37.79774 -309.960264)
		(width 0.14478)
		(layer "In11.Cu")
		(net "M_F_CPU1_SB_DQ<26>")
	)
	(segment
		(start 19.909028 -311.288938)
		(end 19.764248 -311.144158)
		(width 0.14478)
		(layer "In11.Cu")
		(net "M_F_CPU1_SB_DQ<26>")
	)
	(segment
		(start 54.26583 -310.810402)
		(end 53.415692 -309.960264)
		(width 0.14478)
		(layer "In11.Cu")
		(net "M_F_CPU1_SB_DQ<26>")
	)
	(segment
		(start 53.415692 -309.960264)
		(end 50.284888 -309.960264)
		(width 0.14478)
		(layer "In11.Cu")
		(net "M_F_CPU1_SB_DQ<26>")
	)
	(segment
		(start 61.40069 -308.364128)
		(end 59.794902 -309.969916)
		(width 0.14478)
		(layer "In11.Cu")
		(net "M_F_CPU1_SB_DQ<26>")
	)
	(segment
		(start 19.212814 -310.476646)
		(end 19.212814 -311.144158)
		(width 0.14478)
		(layer "In11.Cu")
		(net "M_F_CPU1_SB_DQ<26>")
	)
	(segment
		(start 37.79774 -309.960264)
		(end 35.43554 -309.960264)
		(width 0.14478)
		(layer "In11.Cu")
		(net "M_F_CPU1_SB_DQ<26>")
	)
	(segment
		(start 21.011896 -310.810402)
		(end 20.867116 -310.665622)
		(width 0.14478)
		(layer "In11.Cu")
		(net "M_F_CPU1_SB_DQ<26>")
	)
	(segment
		(start 76.763626 -291.442902)
		(end 76.262484 -291.944044)
		(width 0.0889)
		(layer "In11.Cu")
		(net "M_F_CPU1_SB_DQ<26>")
	)
	(segment
		(start 77.487526 -290.959032)
		(end 77.003656 -291.442902)
		(width 0.0889)
		(layer "In11.Cu")
		(net "M_F_CPU1_SB_DQ<26>")
	)
	(segment
		(start 59.794902 -309.969916)
		(end 57.793636 -309.969916)
		(width 0.14478)
		(layer "In11.Cu")
		(net "M_F_CPU1_SB_DQ<26>")
	)
	(segment
		(start 35.43554 -309.960264)
		(end 34.585402 -310.810402)
		(width 0.14478)
		(layer "In11.Cu")
		(net "M_F_CPU1_SB_DQ<26>")
	)
	(segment
		(start 20.867116 -310.476646)
		(end 20.722336 -310.331866)
		(width 0.14478)
		(layer "In11.Cu")
		(net "M_F_CPU1_SB_DQ<26>")
	)
	(segment
		(start 19.619468 -310.331866)
		(end 19.357594 -310.331866)
		(width 0.14478)
		(layer "In11.Cu")
		(net "M_F_CPU1_SB_DQ<26>")
	)
	(segment
		(start 19.764248 -311.144158)
		(end 19.764248 -310.476646)
		(width 0.14478)
		(layer "In11.Cu")
		(net "M_F_CPU1_SB_DQ<26>")
	)
	(segment
		(start 20.315682 -311.144158)
		(end 20.170902 -311.288938)
		(width 0.14478)
		(layer "In11.Cu")
		(net "M_F_CPU1_SB_DQ<26>")
	)
	(segment
		(start 83.702398 -289.148774)
		(end 83.694016 -289.1536)
		(width 0.0889)
		(layer "In11.Cu")
		(net "M_F_CPU1_SB_DQ<26>")
	)
	(segment
		(start 77.487526 -290.694364)
		(end 77.487526 -290.959032)
		(width 0.0889)
		(layer "In11.Cu")
		(net "M_F_CPU1_SB_DQ<26>")
	)
	(segment
		(start 45.493432 -309.960264)
		(end 43.03014 -309.960264)
		(width 0.14478)
		(layer "In11.Cu")
		(net "M_F_CPU1_SB_DQ<26>")
	)
	(segment
		(start 19.212814 -311.144158)
		(end 19.068034 -311.288938)
		(width 0.14478)
		(layer "In11.Cu")
		(net "M_F_CPU1_SB_DQ<26>")
	)
	(segment
		(start 76.262484 -291.944044)
		(end 61.40069 -306.805838)
		(width 0.14478)
		(layer "In11.Cu")
		(net "M_F_CPU1_SB_DQ<26>")
	)
	(segment
		(start 77.003656 -291.442902)
		(end 76.763626 -291.442902)
		(width 0.0889)
		(layer "In11.Cu")
		(net "M_F_CPU1_SB_DQ<26>")
	)
	(segment
		(start 20.170902 -311.288938)
		(end 19.909028 -311.288938)
		(width 0.14478)
		(layer "In11.Cu")
		(net "M_F_CPU1_SB_DQ<26>")
	)
	(segment
		(start 18.80616 -311.288938)
		(end 18.66138 -311.144158)
		(width 0.14478)
		(layer "In11.Cu")
		(net "M_F_CPU1_SB_DQ<26>")
	)
	(segment
		(start 56.95315 -310.810402)
		(end 54.26583 -310.810402)
		(width 0.14478)
		(layer "In11.Cu")
		(net "M_F_CPU1_SB_DQ<26>")
	)
	(segment
		(start 49.43475 -310.810402)
		(end 46.34357 -310.810402)
		(width 0.14478)
		(layer "In11.Cu")
		(net "M_F_CPU1_SB_DQ<26>")
	)
	(segment
		(start 19.357594 -310.331866)
		(end 19.212814 -310.476646)
		(width 0.14478)
		(layer "In11.Cu")
		(net "M_F_CPU1_SB_DQ<26>")
	)
	(segment
		(start 20.867116 -310.665622)
		(end 20.867116 -310.476646)
		(width 0.14478)
		(layer "In11.Cu")
		(net "M_F_CPU1_SB_DQ<26>")
	)
	(segment
		(start 20.315682 -310.476646)
		(end 20.315682 -311.144158)
		(width 0.14478)
		(layer "In11.Cu")
		(net "M_F_CPU1_SB_DQ<26>")
	)
	(segment
		(start 79.950564 -289.144456)
		(end 79.934308 -289.153854)
		(width 0.0889)
		(layer "In11.Cu")
		(net "M_F_CPU1_SB_DQ<26>")
	)
	(segment
		(start 19.764248 -310.476646)
		(end 19.619468 -310.331866)
		(width 0.14478)
		(layer "In11.Cu")
		(net "M_F_CPU1_SB_DQ<26>")
	)
	(segment
		(start 27.700732 -309.960264)
		(end 26.850594 -310.810402)
		(width 0.14478)
		(layer "In11.Cu")
		(net "M_F_CPU1_SB_DQ<26>")
	)
	(segment
		(start 18.033238 -310.810402)
		(end 17.608042 -310.385206)
		(width 0.14478)
		(layer "In11.Cu")
		(net "M_F_CPU1_SB_DQ<26>")
	)
	(segment
		(start 18.66138 -311.144158)
		(end 18.66138 -310.955182)
		(width 0.14478)
		(layer "In11.Cu")
		(net "M_F_CPU1_SB_DQ<26>")
	)
	(segment
		(start 82.762344 -289.148774)
		(end 82.753962 -289.1536)
		(width 0.0889)
		(layer "In11.Cu")
		(net "M_F_CPU1_SB_DQ<26>")
	)
	(segment
		(start 79.934308 -289.153854)
		(end 79.92237 -289.160712)
		(width 0.0889)
		(layer "In11.Cu")
		(net "M_F_CPU1_SB_DQ<26>")
	)
	(segment
		(start 34.585402 -310.810402)
		(end 31.17977 -310.810402)
		(width 0.14478)
		(layer "In11.Cu")
		(net "M_F_CPU1_SB_DQ<26>")
	)
	(segment
		(start 42.180002 -310.810402)
		(end 38.647878 -310.810402)
		(width 0.14478)
		(layer "In11.Cu")
		(net "M_F_CPU1_SB_DQ<26>")
	)
	(arc
		(start 80.874108 -289.1536)
		(mid 80.591152 -289.229777)
		(end 80.308196 -289.1536)
		(width 0.0889)
		(layer "In11.Cu")
		(net "M_F_CPU1_SB_DQ<26>")
	)
	(arc
		(start 83.694016 -289.1536)
		(mid 83.41106 -289.229777)
		(end 83.128104 -289.1536)
		(width 0.0889)
		(layer "In11.Cu")
		(net "M_F_CPU1_SB_DQ<26>")
	)
	(arc
		(start 84.068158 -289.1536)
		(mid 83.885907 -289.10325)
		(end 83.702398 -289.148774)
		(width 0.0889)
		(layer "In11.Cu")
		(net "M_F_CPU1_SB_DQ<26>")
	)
	(arc
		(start 79.92237 -289.160712)
		(mid 79.644836 -289.229693)
		(end 79.369158 -289.1536)
		(width 0.0889)
		(layer "In11.Cu")
		(net "M_F_CPU1_SB_DQ<26>")
	)
	(arc
		(start 84.571078 -289.18535)
		(mid 84.31587 -289.228827)
		(end 84.068158 -289.1536)
		(width 0.0889)
		(layer "In11.Cu")
		(net "M_F_CPU1_SB_DQ<26>")
	)
	(arc
		(start 83.128104 -289.1536)
		(mid 82.945853 -289.10325)
		(end 82.762344 -289.148774)
		(width 0.0889)
		(layer "In11.Cu")
		(net "M_F_CPU1_SB_DQ<26>")
	)
	(arc
		(start 81.813908 -289.1536)
		(mid 81.530952 -289.229777)
		(end 81.247996 -289.1536)
		(width 0.0889)
		(layer "In11.Cu")
		(net "M_F_CPU1_SB_DQ<26>")
	)
	(arc
		(start 77.64145 -290.323016)
		(mid 77.527555 -290.493378)
		(end 77.487526 -290.694364)
		(width 0.0889)
		(layer "In11.Cu")
		(net "M_F_CPU1_SB_DQ<26>")
	)
	(arc
		(start 82.753962 -289.1536)
		(mid 82.471006 -289.229777)
		(end 82.18805 -289.1536)
		(width 0.0889)
		(layer "In11.Cu")
		(net "M_F_CPU1_SB_DQ<26>")
	)
	(arc
		(start 81.247996 -289.1536)
		(mid 81.061052 -289.103345)
		(end 80.874108 -289.1536)
		(width 0.0889)
		(layer "In11.Cu")
		(net "M_F_CPU1_SB_DQ<26>")
	)
	(arc
		(start 78.859634 -289.210242)
		(mid 78.724632 -289.26659)
		(end 78.608682 -289.355784)
		(width 0.0889)
		(layer "In11.Cu")
		(net "M_F_CPU1_SB_DQ<26>")
	)
	(arc
		(start 80.308196 -289.1536)
		(mid 80.130546 -289.10334)
		(end 79.950564 -289.144456)
		(width 0.0889)
		(layer "In11.Cu")
		(net "M_F_CPU1_SB_DQ<26>")
	)
	(arc
		(start 79.357474 -289.146742)
		(mid 79.175219 -289.103089)
		(end 78.994762 -289.1536)
		(width 0.0889)
		(layer "In11.Cu")
		(net "M_F_CPU1_SB_DQ<26>")
	)
	(arc
		(start 82.179668 -289.148774)
		(mid 81.99616 -289.10328)
		(end 81.813908 -289.1536)
		(width 0.0889)
		(layer "In11.Cu")
		(net "M_F_CPU1_SB_DQ<26>")
	)
	(arc
		(start 78.994762 -289.1536)
		(mid 78.929044 -289.186324)
		(end 78.859634 -289.210242)
		(width 0.0889)
		(layer "In11.Cu")
		(net "M_F_CPU1_SB_DQ<26>")
	)
	(segment
		(start 86.22792 -289.210242)
		(end 85.761068 -289.47618)
		(width 0.10668)
		(layer "F.Cu")
		(net "M_F_CPU1_SB_DQ<25>")
	)
	(segment
		(start 23.31339 -311.279032)
		(end 23.082758 -311.279032)
		(width 0.14478)
		(layer "In11.Cu")
		(net "M_F_CPU1_SB_DQ<25>")
	)
	(segment
		(start 76.303378 -292.690804)
		(end 61.968888 -307.025294)
		(width 0.14478)
		(layer "In11.Cu")
		(net "M_F_CPU1_SB_DQ<25>")
	)
	(segment
		(start 58.40349 -310.41975)
		(end 58.141616 -310.41975)
		(width 0.14478)
		(layer "In11.Cu")
		(net "M_F_CPU1_SB_DQ<25>")
	)
	(segment
		(start 58.954924 -311.200546)
		(end 58.69305 -311.200546)
		(width 0.14478)
		(layer "In11.Cu")
		(net "M_F_CPU1_SB_DQ<25>")
	)
	(segment
		(start 34.236152 -311.971944)
		(end 33.99155 -311.971944)
		(width 0.14478)
		(layer "In11.Cu")
		(net "M_F_CPU1_SB_DQ<25>")
	)
	(segment
		(start 58.54827 -311.055766)
		(end 58.54827 -310.56453)
		(width 0.14478)
		(layer "In11.Cu")
		(net "M_F_CPU1_SB_DQ<25>")
	)
	(segment
		(start 26.198576 -311.429908)
		(end 26.035762 -311.267094)
		(width 0.14478)
		(layer "In11.Cu")
		(net "M_F_CPU1_SB_DQ<25>")
	)
	(segment
		(start 42.865548 -310.810148)
		(end 41.703752 -311.971944)
		(width 0.14478)
		(layer "In11.Cu")
		(net "M_F_CPU1_SB_DQ<25>")
	)
	(segment
		(start 24.812752 -311.658254)
		(end 24.42591 -311.271412)
		(width 0.14478)
		(layer "In11.Cu")
		(net "M_F_CPU1_SB_DQ<25>")
	)
	(segment
		(start 39.6875 -311.660286)
		(end 39.368222 -311.979564)
		(width 0.14478)
		(layer "In11.Cu")
		(net "M_F_CPU1_SB_DQ<25>")
	)
	(segment
		(start 24.032464 -311.434226)
		(end 24.032464 -311.875678)
		(width 0.14478)
		(layer "In11.Cu")
		(net "M_F_CPU1_SB_DQ<25>")
	)
	(segment
		(start 78.911196 -289.84321)
		(end 78.623414 -289.922712)
		(width 0.0889)
		(layer "In11.Cu")
		(net "M_F_CPU1_SB_DQ<25>")
	)
	(segment
		(start 58.54827 -310.56453)
		(end 58.40349 -310.41975)
		(width 0.14478)
		(layer "In11.Cu")
		(net "M_F_CPU1_SB_DQ<25>")
	)
	(segment
		(start 58.141616 -310.41975)
		(end 57.996836 -310.56453)
		(width 0.14478)
		(layer "In11.Cu")
		(net "M_F_CPU1_SB_DQ<25>")
	)
	(segment
		(start 78.515464 -289.985704)
		(end 77.954632 -290.546536)
		(width 0.0889)
		(layer "In11.Cu")
		(net "M_F_CPU1_SB_DQ<25>")
	)
	(segment
		(start 23.639018 -312.038492)
		(end 23.476204 -311.875678)
		(width 0.14478)
		(layer "In11.Cu")
		(net "M_F_CPU1_SB_DQ<25>")
	)
	(segment
		(start 41.147492 -311.660286)
		(end 39.6875 -311.660286)
		(width 0.14478)
		(layer "In11.Cu")
		(net "M_F_CPU1_SB_DQ<25>")
	)
	(segment
		(start 59.099704 -311.055766)
		(end 58.954924 -311.200546)
		(width 0.14478)
		(layer "In11.Cu")
		(net "M_F_CPU1_SB_DQ<25>")
	)
	(segment
		(start 53.622448 -310.810148)
		(end 53.302408 -310.810148)
		(width 0.14478)
		(layer "In11.Cu")
		(net "M_F_CPU1_SB_DQ<25>")
	)
	(segment
		(start 79.378048 -289.792664)
		(end 79.367634 -289.79876)
		(width 0.0889)
		(layer "In11.Cu")
		(net "M_F_CPU1_SB_DQ<25>")
	)
	(segment
		(start 22.511258 -312.038492)
		(end 21.70811 -311.235344)
		(width 0.14478)
		(layer "In11.Cu")
		(net "M_F_CPU1_SB_DQ<25>")
	)
	(segment
		(start 59.244484 -310.810148)
		(end 59.099704 -310.954928)
		(width 0.14478)
		(layer "In11.Cu")
		(net "M_F_CPU1_SB_DQ<25>")
	)
	(segment
		(start 51.146456 -310.665368)
		(end 51.146456 -310.555386)
		(width 0.14478)
		(layer "In11.Cu")
		(net "M_F_CPU1_SB_DQ<25>")
	)
	(segment
		(start 26.198576 -311.748424)
		(end 26.198576 -311.429908)
		(width 0.14478)
		(layer "In11.Cu")
		(net "M_F_CPU1_SB_DQ<25>")
	)
	(segment
		(start 45.607224 -310.810148)
		(end 42.865548 -310.810148)
		(width 0.14478)
		(layer "In11.Cu")
		(net "M_F_CPU1_SB_DQ<25>")
	)
	(segment
		(start 56.746394 -311.660286)
		(end 54.472586 -311.660286)
		(width 0.14478)
		(layer "In11.Cu")
		(net "M_F_CPU1_SB_DQ<25>")
	)
	(segment
		(start 26.035762 -311.267094)
		(end 25.80513 -311.267094)
		(width 0.14478)
		(layer "In11.Cu")
		(net "M_F_CPU1_SB_DQ<25>")
	)
	(segment
		(start 51.001676 -310.410606)
		(end 50.739802 -310.410606)
		(width 0.14478)
		(layer "In11.Cu")
		(net "M_F_CPU1_SB_DQ<25>")
	)
	(segment
		(start 50.595022 -310.555386)
		(end 50.595022 -310.665368)
		(width 0.14478)
		(layer "In11.Cu")
		(net "M_F_CPU1_SB_DQ<25>")
	)
	(segment
		(start 33.679892 -311.660286)
		(end 32.1437 -311.660286)
		(width 0.14478)
		(layer "In11.Cu")
		(net "M_F_CPU1_SB_DQ<25>")
	)
	(segment
		(start 26.348436 -311.898284)
		(end 26.198576 -311.748424)
		(width 0.14478)
		(layer "In11.Cu")
		(net "M_F_CPU1_SB_DQ<25>")
	)
	(segment
		(start 57.852056 -311.210706)
		(end 57.195974 -311.210706)
		(width 0.14478)
		(layer "In11.Cu")
		(net "M_F_CPU1_SB_DQ<25>")
	)
	(segment
		(start 31.58744 -311.954164)
		(end 30.443424 -310.810148)
		(width 0.14478)
		(layer "In11.Cu")
		(net "M_F_CPU1_SB_DQ<25>")
	)
	(segment
		(start 23.476204 -311.441846)
		(end 23.31339 -311.279032)
		(width 0.14478)
		(layer "In11.Cu")
		(net "M_F_CPU1_SB_DQ<25>")
	)
	(segment
		(start 32.1437 -311.660286)
		(end 31.849822 -311.954164)
		(width 0.14478)
		(layer "In11.Cu")
		(net "M_F_CPU1_SB_DQ<25>")
	)
	(segment
		(start 50.450242 -310.810148)
		(end 50.078132 -310.810148)
		(width 0.14478)
		(layer "In11.Cu")
		(net "M_F_CPU1_SB_DQ<25>")
	)
	(segment
		(start 53.302408 -310.810148)
		(end 53.157628 -310.665368)
		(width 0.14478)
		(layer "In11.Cu")
		(net "M_F_CPU1_SB_DQ<25>")
	)
	(segment
		(start 76.89723 -292.096952)
		(end 76.303378 -292.690804)
		(width 0.0889)
		(layer "In11.Cu")
		(net "M_F_CPU1_SB_DQ<25>")
	)
	(segment
		(start 53.157628 -310.563006)
		(end 53.012848 -310.418226)
		(width 0.14478)
		(layer "In11.Cu")
		(net "M_F_CPU1_SB_DQ<25>")
	)
	(segment
		(start 57.996836 -311.065926)
		(end 57.852056 -311.210706)
		(width 0.14478)
		(layer "In11.Cu")
		(net "M_F_CPU1_SB_DQ<25>")
	)
	(segment
		(start 50.078132 -310.810148)
		(end 49.227994 -311.660286)
		(width 0.14478)
		(layer "In11.Cu")
		(net "M_F_CPU1_SB_DQ<25>")
	)
	(segment
		(start 83.702398 -289.803586)
		(end 83.694016 -289.79876)
		(width 0.0889)
		(layer "In11.Cu")
		(net "M_F_CPU1_SB_DQ<25>")
	)
	(segment
		(start 54.472586 -311.660286)
		(end 53.622448 -310.810148)
		(width 0.14478)
		(layer "In11.Cu")
		(net "M_F_CPU1_SB_DQ<25>")
	)
	(segment
		(start 49.227994 -311.660286)
		(end 46.457362 -311.660286)
		(width 0.14478)
		(layer "In11.Cu")
		(net "M_F_CPU1_SB_DQ<25>")
	)
	(segment
		(start 77.907642 -290.660074)
		(end 77.907642 -291.060632)
		(width 0.0889)
		(layer "In11.Cu")
		(net "M_F_CPU1_SB_DQ<25>")
	)
	(segment
		(start 41.703752 -311.971944)
		(end 41.45915 -311.971944)
		(width 0.14478)
		(layer "In11.Cu")
		(net "M_F_CPU1_SB_DQ<25>")
	)
	(segment
		(start 23.86965 -312.038492)
		(end 23.639018 -312.038492)
		(width 0.14478)
		(layer "In11.Cu")
		(net "M_F_CPU1_SB_DQ<25>")
	)
	(segment
		(start 59.099704 -310.954928)
		(end 59.099704 -311.055766)
		(width 0.14478)
		(layer "In11.Cu")
		(net "M_F_CPU1_SB_DQ<25>")
	)
	(segment
		(start 50.595022 -310.665368)
		(end 50.450242 -310.810148)
		(width 0.14478)
		(layer "In11.Cu")
		(net "M_F_CPU1_SB_DQ<25>")
	)
	(segment
		(start 30.443424 -310.810148)
		(end 27.648916 -310.810148)
		(width 0.14478)
		(layer "In11.Cu")
		(net "M_F_CPU1_SB_DQ<25>")
	)
	(segment
		(start 57.996836 -310.56453)
		(end 57.996836 -311.065926)
		(width 0.14478)
		(layer "In11.Cu")
		(net "M_F_CPU1_SB_DQ<25>")
	)
	(segment
		(start 33.99155 -311.971944)
		(end 33.679892 -311.660286)
		(width 0.14478)
		(layer "In11.Cu")
		(net "M_F_CPU1_SB_DQ<25>")
	)
	(segment
		(start 57.195974 -311.210706)
		(end 56.746394 -311.660286)
		(width 0.14478)
		(layer "In11.Cu")
		(net "M_F_CPU1_SB_DQ<25>")
	)
	(segment
		(start 26.56078 -311.898284)
		(end 26.348436 -311.898284)
		(width 0.14478)
		(layer "In11.Cu")
		(net "M_F_CPU1_SB_DQ<25>")
	)
	(segment
		(start 58.69305 -311.200546)
		(end 58.54827 -311.055766)
		(width 0.14478)
		(layer "In11.Cu")
		(net "M_F_CPU1_SB_DQ<25>")
	)
	(segment
		(start 52.750974 -310.418226)
		(end 52.606194 -310.563006)
		(width 0.14478)
		(layer "In11.Cu")
		(net "M_F_CPU1_SB_DQ<25>")
	)
	(segment
		(start 76.89723 -292.071044)
		(end 76.89723 -292.096952)
		(width 0.0889)
		(layer "In11.Cu")
		(net "M_F_CPU1_SB_DQ<25>")
	)
	(segment
		(start 27.648916 -310.810148)
		(end 26.56078 -311.898284)
		(width 0.14478)
		(layer "In11.Cu")
		(net "M_F_CPU1_SB_DQ<25>")
	)
	(segment
		(start 53.012848 -310.418226)
		(end 52.750974 -310.418226)
		(width 0.14478)
		(layer "In11.Cu")
		(net "M_F_CPU1_SB_DQ<25>")
	)
	(segment
		(start 61.968888 -307.025294)
		(end 61.968888 -308.582568)
		(width 0.14478)
		(layer "In11.Cu")
		(net "M_F_CPU1_SB_DQ<25>")
	)
	(segment
		(start 22.919944 -311.441846)
		(end 22.919944 -311.875678)
		(width 0.14478)
		(layer "In11.Cu")
		(net "M_F_CPU1_SB_DQ<25>")
	)
	(segment
		(start 82.18805 -289.79876)
		(end 82.179668 -289.803586)
		(width 0.0889)
		(layer "In11.Cu")
		(net "M_F_CPU1_SB_DQ<25>")
	)
	(segment
		(start 59.741308 -310.810148)
		(end 59.244484 -310.810148)
		(width 0.14478)
		(layer "In11.Cu")
		(net "M_F_CPU1_SB_DQ<25>")
	)
	(segment
		(start 25.80513 -311.267094)
		(end 25.41397 -311.658254)
		(width 0.14478)
		(layer "In11.Cu")
		(net "M_F_CPU1_SB_DQ<25>")
	)
	(segment
		(start 77.907642 -291.060632)
		(end 76.89723 -292.071044)
		(width 0.0889)
		(layer "In11.Cu")
		(net "M_F_CPU1_SB_DQ<25>")
	)
	(segment
		(start 53.157628 -310.665368)
		(end 53.157628 -310.563006)
		(width 0.14478)
		(layer "In11.Cu")
		(net "M_F_CPU1_SB_DQ<25>")
	)
	(segment
		(start 51.146456 -310.555386)
		(end 51.001676 -310.410606)
		(width 0.14478)
		(layer "In11.Cu")
		(net "M_F_CPU1_SB_DQ<25>")
	)
	(segment
		(start 39.368222 -311.979564)
		(end 39.13124 -311.979564)
		(width 0.14478)
		(layer "In11.Cu")
		(net "M_F_CPU1_SB_DQ<25>")
	)
	(segment
		(start 23.082758 -311.279032)
		(end 22.919944 -311.441846)
		(width 0.14478)
		(layer "In11.Cu")
		(net "M_F_CPU1_SB_DQ<25>")
	)
	(segment
		(start 85.761068 -289.47618)
		(end 85.914992 -289.74161)
		(width 0.0889)
		(layer "In11.Cu")
		(net "M_F_CPU1_SB_DQ<25>")
	)
	(segment
		(start 35.397948 -310.810148)
		(end 34.236152 -311.971944)
		(width 0.14478)
		(layer "In11.Cu")
		(net "M_F_CPU1_SB_DQ<25>")
	)
	(segment
		(start 24.195278 -311.271412)
		(end 24.032464 -311.434226)
		(width 0.14478)
		(layer "In11.Cu")
		(net "M_F_CPU1_SB_DQ<25>")
	)
	(segment
		(start 82.762344 -289.803586)
		(end 82.753962 -289.79876)
		(width 0.0889)
		(layer "In11.Cu")
		(net "M_F_CPU1_SB_DQ<25>")
	)
	(segment
		(start 52.606194 -310.665368)
		(end 52.461414 -310.810148)
		(width 0.14478)
		(layer "In11.Cu")
		(net "M_F_CPU1_SB_DQ<25>")
	)
	(segment
		(start 52.461414 -310.810148)
		(end 51.291236 -310.810148)
		(width 0.14478)
		(layer "In11.Cu")
		(net "M_F_CPU1_SB_DQ<25>")
	)
	(segment
		(start 37.961824 -310.810148)
		(end 35.397948 -310.810148)
		(width 0.14478)
		(layer "In11.Cu")
		(net "M_F_CPU1_SB_DQ<25>")
	)
	(segment
		(start 61.968888 -308.582568)
		(end 59.741308 -310.810148)
		(width 0.14478)
		(layer "In11.Cu")
		(net "M_F_CPU1_SB_DQ<25>")
	)
	(segment
		(start 22.919944 -311.875678)
		(end 22.75713 -312.038492)
		(width 0.14478)
		(layer "In11.Cu")
		(net "M_F_CPU1_SB_DQ<25>")
	)
	(segment
		(start 85.914992 -289.74161)
		(end 85.89264 -289.824922)
		(width 0.0889)
		(layer "In11.Cu")
		(net "M_F_CPU1_SB_DQ<25>")
	)
	(segment
		(start 23.476204 -311.875678)
		(end 23.476204 -311.441846)
		(width 0.14478)
		(layer "In11.Cu")
		(net "M_F_CPU1_SB_DQ<25>")
	)
	(segment
		(start 51.291236 -310.810148)
		(end 51.146456 -310.665368)
		(width 0.14478)
		(layer "In11.Cu")
		(net "M_F_CPU1_SB_DQ<25>")
	)
	(segment
		(start 41.45915 -311.971944)
		(end 41.147492 -311.660286)
		(width 0.14478)
		(layer "In11.Cu")
		(net "M_F_CPU1_SB_DQ<25>")
	)
	(segment
		(start 24.032464 -311.875678)
		(end 23.86965 -312.038492)
		(width 0.14478)
		(layer "In11.Cu")
		(net "M_F_CPU1_SB_DQ<25>")
	)
	(segment
		(start 50.739802 -310.410606)
		(end 50.595022 -310.555386)
		(width 0.14478)
		(layer "In11.Cu")
		(net "M_F_CPU1_SB_DQ<25>")
	)
	(segment
		(start 25.41397 -311.658254)
		(end 24.812752 -311.658254)
		(width 0.14478)
		(layer "In11.Cu")
		(net "M_F_CPU1_SB_DQ<25>")
	)
	(segment
		(start 22.75713 -312.038492)
		(end 22.511258 -312.038492)
		(width 0.14478)
		(layer "In11.Cu")
		(net "M_F_CPU1_SB_DQ<25>")
	)
	(segment
		(start 24.42591 -311.271412)
		(end 24.195278 -311.271412)
		(width 0.14478)
		(layer "In11.Cu")
		(net "M_F_CPU1_SB_DQ<25>")
	)
	(segment
		(start 39.13124 -311.979564)
		(end 37.961824 -310.810148)
		(width 0.14478)
		(layer "In11.Cu")
		(net "M_F_CPU1_SB_DQ<25>")
	)
	(segment
		(start 52.606194 -310.563006)
		(end 52.606194 -310.665368)
		(width 0.14478)
		(layer "In11.Cu")
		(net "M_F_CPU1_SB_DQ<25>")
	)
	(segment
		(start 46.457362 -311.660286)
		(end 45.607224 -310.810148)
		(width 0.14478)
		(layer "In11.Cu")
		(net "M_F_CPU1_SB_DQ<25>")
	)
	(segment
		(start 31.849822 -311.954164)
		(end 31.58744 -311.954164)
		(width 0.14478)
		(layer "In11.Cu")
		(net "M_F_CPU1_SB_DQ<25>")
	)
	(arc
		(start 84.63407 -289.79876)
		(mid 84.351114 -289.722583)
		(end 84.068158 -289.79876)
		(width 0.0889)
		(layer "In11.Cu")
		(net "M_F_CPU1_SB_DQ<25>")
	)
	(arc
		(start 81.247996 -289.79876)
		(mid 81.061052 -289.849015)
		(end 80.874108 -289.79876)
		(width 0.0889)
		(layer "In11.Cu")
		(net "M_F_CPU1_SB_DQ<25>")
	)
	(arc
		(start 82.179668 -289.803586)
		(mid 81.99616 -289.84908)
		(end 81.813908 -289.79876)
		(width 0.0889)
		(layer "In11.Cu")
		(net "M_F_CPU1_SB_DQ<25>")
	)
	(arc
		(start 83.694016 -289.79876)
		(mid 83.41106 -289.722583)
		(end 83.128104 -289.79876)
		(width 0.0889)
		(layer "In11.Cu")
		(net "M_F_CPU1_SB_DQ<25>")
	)
	(arc
		(start 79.367634 -289.79876)
		(mid 79.235503 -289.845087)
		(end 79.0956 -289.8394)
		(width 0.0889)
		(layer "In11.Cu")
		(net "M_F_CPU1_SB_DQ<25>")
	)
	(arc
		(start 79.0956 -289.8394)
		(mid 79.003155 -289.829695)
		(end 78.911196 -289.84321)
		(width 0.0889)
		(layer "In11.Cu")
		(net "M_F_CPU1_SB_DQ<25>")
	)
	(arc
		(start 85.89264 -289.824922)
		(mid 85.730308 -289.84774)
		(end 85.57387 -289.79876)
		(width 0.0889)
		(layer "In11.Cu")
		(net "M_F_CPU1_SB_DQ<25>")
	)
	(arc
		(start 79.9338 -289.79876)
		(mid 79.656733 -289.722489)
		(end 79.378048 -289.792664)
		(width 0.0889)
		(layer "In11.Cu")
		(net "M_F_CPU1_SB_DQ<25>")
	)
	(arc
		(start 82.753962 -289.79876)
		(mid 82.471006 -289.722583)
		(end 82.18805 -289.79876)
		(width 0.0889)
		(layer "In11.Cu")
		(net "M_F_CPU1_SB_DQ<25>")
	)
	(arc
		(start 77.954632 -290.546536)
		(mid 77.919879 -290.598642)
		(end 77.907642 -290.660074)
		(width 0.0889)
		(layer "In11.Cu")
		(net "M_F_CPU1_SB_DQ<25>")
	)
	(arc
		(start 81.813908 -289.79876)
		(mid 81.530952 -289.722583)
		(end 81.247996 -289.79876)
		(width 0.0889)
		(layer "In11.Cu")
		(net "M_F_CPU1_SB_DQ<25>")
	)
	(arc
		(start 78.623414 -289.922712)
		(mid 78.565343 -289.947192)
		(end 78.515464 -289.985704)
		(width 0.0889)
		(layer "In11.Cu")
		(net "M_F_CPU1_SB_DQ<25>")
	)
	(arc
		(start 84.068158 -289.79876)
		(mid 83.885907 -289.84911)
		(end 83.702398 -289.803586)
		(width 0.0889)
		(layer "In11.Cu")
		(net "M_F_CPU1_SB_DQ<25>")
	)
	(arc
		(start 85.007958 -289.79876)
		(mid 84.821014 -289.849015)
		(end 84.63407 -289.79876)
		(width 0.0889)
		(layer "In11.Cu")
		(net "M_F_CPU1_SB_DQ<25>")
	)
	(arc
		(start 83.128104 -289.79876)
		(mid 82.945853 -289.84911)
		(end 82.762344 -289.803586)
		(width 0.0889)
		(layer "In11.Cu")
		(net "M_F_CPU1_SB_DQ<25>")
	)
	(arc
		(start 85.57387 -289.79876)
		(mid 85.290914 -289.722583)
		(end 85.007958 -289.79876)
		(width 0.0889)
		(layer "In11.Cu")
		(net "M_F_CPU1_SB_DQ<25>")
	)
	(arc
		(start 80.308196 -289.79876)
		(mid 80.120998 -289.849142)
		(end 79.9338 -289.79876)
		(width 0.0889)
		(layer "In11.Cu")
		(net "M_F_CPU1_SB_DQ<25>")
	)
	(arc
		(start 80.874108 -289.79876)
		(mid 80.591152 -289.722583)
		(end 80.308196 -289.79876)
		(width 0.0889)
		(layer "In11.Cu")
		(net "M_F_CPU1_SB_DQ<25>")
	)
	(segment
		(start 84.817966 -288.400236)
		(end 84.351114 -288.666174)
		(width 0.10668)
		(layer "F.Cu")
		(net "M_F_CPU1_SB_DQ<24>")
	)
	(segment
		(start 26.14041 -310.16829)
		(end 25.977596 -310.331104)
		(width 0.14478)
		(layer "In11.Cu")
		(net "M_F_CPU1_SB_DQ<24>")
	)
	(segment
		(start 52.741576 -309.424324)
		(end 52.49926 -309.424324)
		(width 0.14478)
		(layer "In11.Cu")
		(net "M_F_CPU1_SB_DQ<24>")
	)
	(segment
		(start 33.824672 -309.960518)
		(end 32.07004 -309.960518)
		(width 0.14478)
		(layer "In11.Cu")
		(net "M_F_CPU1_SB_DQ<24>")
	)
	(segment
		(start 55.065168 -309.960518)
		(end 54.758082 -310.267604)
		(width 0.14478)
		(layer "In11.Cu")
		(net "M_F_CPU1_SB_DQ<24>")
	)
	(segment
		(start 60.702952 -308.425596)
		(end 60.498228 -308.425596)
		(width 0.14478)
		(layer "In11.Cu")
		(net "M_F_CPU1_SB_DQ<24>")
	)
	(segment
		(start 58.415682 -308.698646)
		(end 58.415682 -309.375556)
		(width 0.14478)
		(layer "In11.Cu")
		(net "M_F_CPU1_SB_DQ<24>")
	)
	(segment
		(start 58.822336 -308.553866)
		(end 58.560462 -308.553866)
		(width 0.14478)
		(layer "In11.Cu")
		(net "M_F_CPU1_SB_DQ<24>")
	)
	(segment
		(start 75.955906 -291.614606)
		(end 60.95111 -306.619402)
		(width 0.14478)
		(layer "In11.Cu")
		(net "M_F_CPU1_SB_DQ<24>")
	)
	(segment
		(start 49.32172 -310.280304)
		(end 49.085246 -310.280304)
		(width 0.14478)
		(layer "In11.Cu")
		(net "M_F_CPU1_SB_DQ<24>")
	)
	(segment
		(start 26.14041 -309.833518)
		(end 26.14041 -310.16829)
		(width 0.14478)
		(layer "In11.Cu")
		(net "M_F_CPU1_SB_DQ<24>")
	)
	(segment
		(start 58.560462 -308.553866)
		(end 58.415682 -308.698646)
		(width 0.14478)
		(layer "In11.Cu")
		(net "M_F_CPU1_SB_DQ<24>")
	)
	(segment
		(start 60.193682 -308.325774)
		(end 60.008262 -308.511194)
		(width 0.14478)
		(layer "In11.Cu")
		(net "M_F_CPU1_SB_DQ<24>")
	)
	(segment
		(start 45.431456 -309.11038)
		(end 43.219116 -309.11038)
		(width 0.14478)
		(layer "In11.Cu")
		(net "M_F_CPU1_SB_DQ<24>")
	)
	(segment
		(start 24.030432 -310.181244)
		(end 23.867618 -310.344058)
		(width 0.14478)
		(layer "In11.Cu")
		(net "M_F_CPU1_SB_DQ<24>")
	)
	(segment
		(start 30.343856 -309.11038)
		(end 27.902916 -309.11038)
		(width 0.14478)
		(layer "In11.Cu")
		(net "M_F_CPU1_SB_DQ<24>")
	)
	(segment
		(start 41.256458 -309.960518)
		(end 40.974772 -310.242204)
		(width 0.14478)
		(layer "In11.Cu")
		(net "M_F_CPU1_SB_DQ<24>")
	)
	(segment
		(start 60.108084 -308.81574)
		(end 60.108084 -309.020464)
		(width 0.14478)
		(layer "In11.Cu")
		(net "M_F_CPU1_SB_DQ<24>")
	)
	(segment
		(start 54.125114 -309.27167)
		(end 53.92039 -309.27167)
		(width 0.14478)
		(layer "In11.Cu")
		(net "M_F_CPU1_SB_DQ<24>")
	)
	(segment
		(start 84.351114 -288.666174)
		(end 84.505038 -288.931604)
		(width 0.0889)
		(layer "In11.Cu")
		(net "M_F_CPU1_SB_DQ<24>")
	)
	(segment
		(start 80.778096 -288.988754)
		(end 80.769714 -288.99358)
		(width 0.0889)
		(layer "In11.Cu")
		(net "M_F_CPU1_SB_DQ<24>")
	)
	(segment
		(start 34.380932 -310.252364)
		(end 34.116518 -310.252364)
		(width 0.14478)
		(layer "In11.Cu")
		(net "M_F_CPU1_SB_DQ<24>")
	)
	(segment
		(start 59.672474 -309.456074)
		(end 59.111896 -309.456074)
		(width 0.14478)
		(layer "In11.Cu")
		(net "M_F_CPU1_SB_DQ<24>")
	)
	(segment
		(start 27.052778 -309.960518)
		(end 26.82367 -309.960518)
		(width 0.14478)
		(layer "In11.Cu")
		(net "M_F_CPU1_SB_DQ<24>")
	)
	(segment
		(start 23.080726 -309.679086)
		(end 22.917912 -309.8419)
		(width 0.14478)
		(layer "In11.Cu")
		(net "M_F_CPU1_SB_DQ<24>")
	)
	(segment
		(start 34.116518 -310.252364)
		(end 33.824672 -309.960518)
		(width 0.14478)
		(layer "In11.Cu")
		(net "M_F_CPU1_SB_DQ<24>")
	)
	(segment
		(start 60.108084 -309.020464)
		(end 59.672474 -309.456074)
		(width 0.14478)
		(layer "In11.Cu")
		(net "M_F_CPU1_SB_DQ<24>")
	)
	(segment
		(start 55.621428 -310.267604)
		(end 55.314342 -309.960518)
		(width 0.14478)
		(layer "In11.Cu")
		(net "M_F_CPU1_SB_DQ<24>")
	)
	(segment
		(start 24.70531 -309.960518)
		(end 24.423878 -309.679086)
		(width 0.14478)
		(layer "In11.Cu")
		(net "M_F_CPU1_SB_DQ<24>")
	)
	(segment
		(start 54.209188 -309.967884)
		(end 54.209188 -309.76316)
		(width 0.14478)
		(layer "In11.Cu")
		(net "M_F_CPU1_SB_DQ<24>")
	)
	(segment
		(start 43.219116 -309.11038)
		(end 42.087292 -310.242204)
		(width 0.14478)
		(layer "In11.Cu")
		(net "M_F_CPU1_SB_DQ<24>")
	)
	(segment
		(start 24.423878 -309.679086)
		(end 24.193246 -309.679086)
		(width 0.14478)
		(layer "In11.Cu")
		(net "M_F_CPU1_SB_DQ<24>")
	)
	(segment
		(start 35.522916 -309.11038)
		(end 34.380932 -310.252364)
		(width 0.14478)
		(layer "In11.Cu")
		(net "M_F_CPU1_SB_DQ<24>")
	)
	(segment
		(start 57.600088 -309.520336)
		(end 57.159906 -309.960518)
		(width 0.14478)
		(layer "In11.Cu")
		(net "M_F_CPU1_SB_DQ<24>")
	)
	(segment
		(start 78.408276 -289.039554)
		(end 76.700126 -290.747704)
		(width 0.0889)
		(layer "In11.Cu")
		(net "M_F_CPU1_SB_DQ<24>")
	)
	(segment
		(start 40.974772 -310.242204)
		(end 40.700198 -310.242204)
		(width 0.14478)
		(layer "In11.Cu")
		(net "M_F_CPU1_SB_DQ<24>")
	)
	(segment
		(start 38.98138 -310.280304)
		(end 37.811456 -309.11038)
		(width 0.14478)
		(layer "In11.Cu")
		(net "M_F_CPU1_SB_DQ<24>")
	)
	(segment
		(start 23.474172 -309.8419)
		(end 23.311358 -309.679086)
		(width 0.14478)
		(layer "In11.Cu")
		(net "M_F_CPU1_SB_DQ<24>")
	)
	(segment
		(start 27.902916 -309.11038)
		(end 27.052778 -309.960518)
		(width 0.14478)
		(layer "In11.Cu")
		(net "M_F_CPU1_SB_DQ<24>")
	)
	(segment
		(start 58.415682 -309.375556)
		(end 58.270902 -309.520336)
		(width 0.14478)
		(layer "In11.Cu")
		(net "M_F_CPU1_SB_DQ<24>")
	)
	(segment
		(start 48.76546 -309.960518)
		(end 47.16018 -309.960518)
		(width 0.14478)
		(layer "In11.Cu")
		(net "M_F_CPU1_SB_DQ<24>")
	)
	(segment
		(start 53.351684 -309.11038)
		(end 53.05552 -309.11038)
		(width 0.14478)
		(layer "In11.Cu")
		(net "M_F_CPU1_SB_DQ<24>")
	)
	(segment
		(start 60.95111 -306.619402)
		(end 60.95111 -308.177438)
		(width 0.14478)
		(layer "In11.Cu")
		(net "M_F_CPU1_SB_DQ<24>")
	)
	(segment
		(start 26.303224 -309.670704)
		(end 26.14041 -309.833518)
		(width 0.14478)
		(layer "In11.Cu")
		(net "M_F_CPU1_SB_DQ<24>")
	)
	(segment
		(start 50.83302 -309.11038)
		(end 50.491644 -309.11038)
		(width 0.14478)
		(layer "In11.Cu")
		(net "M_F_CPU1_SB_DQ<24>")
	)
	(segment
		(start 40.418512 -309.960518)
		(end 39.53764 -309.960518)
		(width 0.14478)
		(layer "In11.Cu")
		(net "M_F_CPU1_SB_DQ<24>")
	)
	(segment
		(start 40.700198 -310.242204)
		(end 40.418512 -309.960518)
		(width 0.14478)
		(layer "In11.Cu")
		(net "M_F_CPU1_SB_DQ<24>")
	)
	(segment
		(start 53.819044 -309.373016)
		(end 53.61432 -309.373016)
		(width 0.14478)
		(layer "In11.Cu")
		(net "M_F_CPU1_SB_DQ<24>")
	)
	(segment
		(start 79.46517 -288.988754)
		(end 79.447136 -288.978086)
		(width 0.0889)
		(layer "In11.Cu")
		(net "M_F_CPU1_SB_DQ<24>")
	)
	(segment
		(start 49.085246 -310.280304)
		(end 48.76546 -309.960518)
		(width 0.14478)
		(layer "In11.Cu")
		(net "M_F_CPU1_SB_DQ<24>")
	)
	(segment
		(start 51.38928 -309.426864)
		(end 51.149504 -309.426864)
		(width 0.14478)
		(layer "In11.Cu")
		(net "M_F_CPU1_SB_DQ<24>")
	)
	(segment
		(start 39.217854 -310.280304)
		(end 38.98138 -310.280304)
		(width 0.14478)
		(layer "In11.Cu")
		(net "M_F_CPU1_SB_DQ<24>")
	)
	(segment
		(start 57.159906 -309.960518)
		(end 56.177688 -309.960518)
		(width 0.14478)
		(layer "In11.Cu")
		(net "M_F_CPU1_SB_DQ<24>")
	)
	(segment
		(start 22.917912 -310.188864)
		(end 22.755098 -310.351678)
		(width 0.14478)
		(layer "In11.Cu")
		(net "M_F_CPU1_SB_DQ<24>")
	)
	(segment
		(start 39.53764 -309.960518)
		(end 39.217854 -310.280304)
		(width 0.14478)
		(layer "In11.Cu")
		(net "M_F_CPU1_SB_DQ<24>")
	)
	(segment
		(start 53.61432 -309.373016)
		(end 53.351684 -309.11038)
		(width 0.14478)
		(layer "In11.Cu")
		(net "M_F_CPU1_SB_DQ<24>")
	)
	(segment
		(start 23.311358 -309.679086)
		(end 23.080726 -309.679086)
		(width 0.14478)
		(layer "In11.Cu")
		(net "M_F_CPU1_SB_DQ<24>")
	)
	(segment
		(start 25.746964 -310.331104)
		(end 25.376378 -309.960518)
		(width 0.14478)
		(layer "In11.Cu")
		(net "M_F_CPU1_SB_DQ<24>")
	)
	(segment
		(start 52.185316 -309.11038)
		(end 51.705764 -309.11038)
		(width 0.14478)
		(layer "In11.Cu")
		(net "M_F_CPU1_SB_DQ<24>")
	)
	(segment
		(start 81.35239 -288.99358)
		(end 81.344008 -288.988754)
		(width 0.0889)
		(layer "In11.Cu")
		(net "M_F_CPU1_SB_DQ<24>")
	)
	(segment
		(start 55.870602 -310.267604)
		(end 55.621428 -310.267604)
		(width 0.14478)
		(layer "In11.Cu")
		(net "M_F_CPU1_SB_DQ<24>")
	)
	(segment
		(start 22.524466 -310.351678)
		(end 21.70811 -309.535322)
		(width 0.14478)
		(layer "In11.Cu")
		(net "M_F_CPU1_SB_DQ<24>")
	)
	(segment
		(start 58.967116 -308.698646)
		(end 58.822336 -308.553866)
		(width 0.14478)
		(layer "In11.Cu")
		(net "M_F_CPU1_SB_DQ<24>")
	)
	(segment
		(start 37.811456 -309.11038)
		(end 35.522916 -309.11038)
		(width 0.14478)
		(layer "In11.Cu")
		(net "M_F_CPU1_SB_DQ<24>")
	)
	(segment
		(start 54.508908 -310.267604)
		(end 54.209188 -309.967884)
		(width 0.14478)
		(layer "In11.Cu")
		(net "M_F_CPU1_SB_DQ<24>")
	)
	(segment
		(start 58.270902 -309.520336)
		(end 57.600088 -309.520336)
		(width 0.14478)
		(layer "In11.Cu")
		(net "M_F_CPU1_SB_DQ<24>")
	)
	(segment
		(start 54.758082 -310.267604)
		(end 54.508908 -310.267604)
		(width 0.14478)
		(layer "In11.Cu")
		(net "M_F_CPU1_SB_DQ<24>")
	)
	(segment
		(start 47.16018 -309.960518)
		(end 46.837854 -310.282844)
		(width 0.14478)
		(layer "In11.Cu")
		(net "M_F_CPU1_SB_DQ<24>")
	)
	(segment
		(start 25.376378 -309.960518)
		(end 24.70531 -309.960518)
		(width 0.14478)
		(layer "In11.Cu")
		(net "M_F_CPU1_SB_DQ<24>")
	)
	(segment
		(start 76.700126 -290.747704)
		(end 76.700126 -290.870386)
		(width 0.0889)
		(layer "In11.Cu")
		(net "M_F_CPU1_SB_DQ<24>")
	)
	(segment
		(start 60.498228 -308.425596)
		(end 60.398406 -308.325774)
		(width 0.14478)
		(layer "In11.Cu")
		(net "M_F_CPU1_SB_DQ<24>")
	)
	(segment
		(start 23.636986 -310.344058)
		(end 23.474172 -310.181244)
		(width 0.14478)
		(layer "In11.Cu")
		(net "M_F_CPU1_SB_DQ<24>")
	)
	(segment
		(start 83.598004 -288.988754)
		(end 83.589622 -288.99358)
		(width 0.0889)
		(layer "In11.Cu")
		(net "M_F_CPU1_SB_DQ<24>")
	)
	(segment
		(start 26.82367 -309.960518)
		(end 26.533856 -309.670704)
		(width 0.14478)
		(layer "In11.Cu")
		(net "M_F_CPU1_SB_DQ<24>")
	)
	(segment
		(start 23.867618 -310.344058)
		(end 23.636986 -310.344058)
		(width 0.14478)
		(layer "In11.Cu")
		(net "M_F_CPU1_SB_DQ<24>")
	)
	(segment
		(start 55.314342 -309.960518)
		(end 55.065168 -309.960518)
		(width 0.14478)
		(layer "In11.Cu")
		(net "M_F_CPU1_SB_DQ<24>")
	)
	(segment
		(start 53.05552 -309.11038)
		(end 52.741576 -309.424324)
		(width 0.14478)
		(layer "In11.Cu")
		(net "M_F_CPU1_SB_DQ<24>")
	)
	(segment
		(start 42.087292 -310.242204)
		(end 41.812718 -310.242204)
		(width 0.14478)
		(layer "In11.Cu")
		(net "M_F_CPU1_SB_DQ<24>")
	)
	(segment
		(start 51.705764 -309.11038)
		(end 51.38928 -309.426864)
		(width 0.14478)
		(layer "In11.Cu")
		(net "M_F_CPU1_SB_DQ<24>")
	)
	(segment
		(start 52.49926 -309.424324)
		(end 52.185316 -309.11038)
		(width 0.14478)
		(layer "In11.Cu")
		(net "M_F_CPU1_SB_DQ<24>")
	)
	(segment
		(start 25.977596 -310.331104)
		(end 25.746964 -310.331104)
		(width 0.14478)
		(layer "In11.Cu")
		(net "M_F_CPU1_SB_DQ<24>")
	)
	(segment
		(start 84.505038 -288.931604)
		(end 84.482686 -289.014916)
		(width 0.0889)
		(layer "In11.Cu")
		(net "M_F_CPU1_SB_DQ<24>")
	)
	(segment
		(start 60.008262 -308.511194)
		(end 60.008262 -308.715918)
		(width 0.14478)
		(layer "In11.Cu")
		(net "M_F_CPU1_SB_DQ<24>")
	)
	(segment
		(start 41.531032 -309.960518)
		(end 41.256458 -309.960518)
		(width 0.14478)
		(layer "In11.Cu")
		(net "M_F_CPU1_SB_DQ<24>")
	)
	(segment
		(start 46.60392 -310.282844)
		(end 45.431456 -309.11038)
		(width 0.14478)
		(layer "In11.Cu")
		(net "M_F_CPU1_SB_DQ<24>")
	)
	(segment
		(start 79.838804 -288.9885)
		(end 79.825088 -288.996374)
		(width 0.0889)
		(layer "In11.Cu")
		(net "M_F_CPU1_SB_DQ<24>")
	)
	(segment
		(start 54.310534 -309.45709)
		(end 54.125114 -309.27167)
		(width 0.14478)
		(layer "In11.Cu")
		(net "M_F_CPU1_SB_DQ<24>")
	)
	(segment
		(start 53.92039 -309.27167)
		(end 53.819044 -309.373016)
		(width 0.14478)
		(layer "In11.Cu")
		(net "M_F_CPU1_SB_DQ<24>")
	)
	(segment
		(start 46.837854 -310.282844)
		(end 46.60392 -310.282844)
		(width 0.14478)
		(layer "In11.Cu")
		(net "M_F_CPU1_SB_DQ<24>")
	)
	(segment
		(start 41.812718 -310.242204)
		(end 41.531032 -309.960518)
		(width 0.14478)
		(layer "In11.Cu")
		(net "M_F_CPU1_SB_DQ<24>")
	)
	(segment
		(start 56.177688 -309.960518)
		(end 55.870602 -310.267604)
		(width 0.14478)
		(layer "In11.Cu")
		(net "M_F_CPU1_SB_DQ<24>")
	)
	(segment
		(start 79.850742 -288.981642)
		(end 79.838804 -288.9885)
		(width 0.0889)
		(layer "In11.Cu")
		(net "M_F_CPU1_SB_DQ<24>")
	)
	(segment
		(start 78.711044 -289.039554)
		(end 78.408276 -289.039554)
		(width 0.0889)
		(layer "In11.Cu")
		(net "M_F_CPU1_SB_DQ<24>")
	)
	(segment
		(start 23.474172 -310.181244)
		(end 23.474172 -309.8419)
		(width 0.14478)
		(layer "In11.Cu")
		(net "M_F_CPU1_SB_DQ<24>")
	)
	(segment
		(start 22.755098 -310.351678)
		(end 22.524466 -310.351678)
		(width 0.14478)
		(layer "In11.Cu")
		(net "M_F_CPU1_SB_DQ<24>")
	)
	(segment
		(start 54.209188 -309.76316)
		(end 54.310534 -309.661814)
		(width 0.14478)
		(layer "In11.Cu")
		(net "M_F_CPU1_SB_DQ<24>")
	)
	(segment
		(start 26.533856 -309.670704)
		(end 26.303224 -309.670704)
		(width 0.14478)
		(layer "In11.Cu")
		(net "M_F_CPU1_SB_DQ<24>")
	)
	(segment
		(start 76.700126 -290.870386)
		(end 75.955906 -291.614606)
		(width 0.0889)
		(layer "In11.Cu")
		(net "M_F_CPU1_SB_DQ<24>")
	)
	(segment
		(start 24.193246 -309.679086)
		(end 24.030432 -309.8419)
		(width 0.14478)
		(layer "In11.Cu")
		(net "M_F_CPU1_SB_DQ<24>")
	)
	(segment
		(start 60.008262 -308.715918)
		(end 60.108084 -308.81574)
		(width 0.14478)
		(layer "In11.Cu")
		(net "M_F_CPU1_SB_DQ<24>")
	)
	(segment
		(start 50.491644 -309.11038)
		(end 49.32172 -310.280304)
		(width 0.14478)
		(layer "In11.Cu")
		(net "M_F_CPU1_SB_DQ<24>")
	)
	(segment
		(start 60.398406 -308.325774)
		(end 60.193682 -308.325774)
		(width 0.14478)
		(layer "In11.Cu")
		(net "M_F_CPU1_SB_DQ<24>")
	)
	(segment
		(start 31.51378 -310.280304)
		(end 30.343856 -309.11038)
		(width 0.14478)
		(layer "In11.Cu")
		(net "M_F_CPU1_SB_DQ<24>")
	)
	(segment
		(start 59.111896 -309.456074)
		(end 58.967116 -309.311294)
		(width 0.14478)
		(layer "In11.Cu")
		(net "M_F_CPU1_SB_DQ<24>")
	)
	(segment
		(start 60.95111 -308.177438)
		(end 60.702952 -308.425596)
		(width 0.14478)
		(layer "In11.Cu")
		(net "M_F_CPU1_SB_DQ<24>")
	)
	(segment
		(start 22.917912 -309.8419)
		(end 22.917912 -310.188864)
		(width 0.14478)
		(layer "In11.Cu")
		(net "M_F_CPU1_SB_DQ<24>")
	)
	(segment
		(start 58.967116 -309.311294)
		(end 58.967116 -308.698646)
		(width 0.14478)
		(layer "In11.Cu")
		(net "M_F_CPU1_SB_DQ<24>")
	)
	(segment
		(start 24.030432 -309.8419)
		(end 24.030432 -310.181244)
		(width 0.14478)
		(layer "In11.Cu")
		(net "M_F_CPU1_SB_DQ<24>")
	)
	(segment
		(start 51.149504 -309.426864)
		(end 50.83302 -309.11038)
		(width 0.14478)
		(layer "In11.Cu")
		(net "M_F_CPU1_SB_DQ<24>")
	)
	(segment
		(start 31.750254 -310.280304)
		(end 31.51378 -310.280304)
		(width 0.14478)
		(layer "In11.Cu")
		(net "M_F_CPU1_SB_DQ<24>")
	)
	(segment
		(start 32.07004 -309.960518)
		(end 31.750254 -310.280304)
		(width 0.14478)
		(layer "In11.Cu")
		(net "M_F_CPU1_SB_DQ<24>")
	)
	(segment
		(start 54.310534 -309.661814)
		(end 54.310534 -309.45709)
		(width 0.14478)
		(layer "In11.Cu")
		(net "M_F_CPU1_SB_DQ<24>")
	)
	(arc
		(start 79.825088 -288.996374)
		(mid 79.644158 -289.038852)
		(end 79.46517 -288.988754)
		(width 0.0889)
		(layer "In11.Cu")
		(net "M_F_CPU1_SB_DQ<24>")
	)
	(arc
		(start 78.898496 -288.988754)
		(mid 78.808133 -289.026564)
		(end 78.711044 -289.039554)
		(width 0.0889)
		(layer "In11.Cu")
		(net "M_F_CPU1_SB_DQ<24>")
	)
	(arc
		(start 81.344008 -288.988754)
		(mid 81.061052 -288.912577)
		(end 80.778096 -288.988754)
		(width 0.0889)
		(layer "In11.Cu")
		(net "M_F_CPU1_SB_DQ<24>")
	)
	(arc
		(start 82.284062 -288.988754)
		(mid 82.001106 -288.912577)
		(end 81.71815 -288.988754)
		(width 0.0889)
		(layer "In11.Cu")
		(net "M_F_CPU1_SB_DQ<24>")
	)
	(arc
		(start 79.447136 -288.978086)
		(mid 79.171441 -288.912243)
		(end 78.898496 -288.988754)
		(width 0.0889)
		(layer "In11.Cu")
		(net "M_F_CPU1_SB_DQ<24>")
	)
	(arc
		(start 81.71815 -288.988754)
		(mid 81.535899 -289.039104)
		(end 81.35239 -288.99358)
		(width 0.0889)
		(layer "In11.Cu")
		(net "M_F_CPU1_SB_DQ<24>")
	)
	(arc
		(start 80.769714 -288.99358)
		(mid 80.586206 -289.039074)
		(end 80.403954 -288.988754)
		(width 0.0889)
		(layer "In11.Cu")
		(net "M_F_CPU1_SB_DQ<24>")
	)
	(arc
		(start 84.482686 -289.014916)
		(mid 84.320354 -289.037734)
		(end 84.163916 -288.988754)
		(width 0.0889)
		(layer "In11.Cu")
		(net "M_F_CPU1_SB_DQ<24>")
	)
	(arc
		(start 80.403954 -288.988754)
		(mid 80.128276 -288.912624)
		(end 79.850742 -288.981642)
		(width 0.0889)
		(layer "In11.Cu")
		(net "M_F_CPU1_SB_DQ<24>")
	)
	(arc
		(start 83.223862 -288.988754)
		(mid 82.940906 -288.912577)
		(end 82.65795 -288.988754)
		(width 0.0889)
		(layer "In11.Cu")
		(net "M_F_CPU1_SB_DQ<24>")
	)
	(arc
		(start 82.65795 -288.988754)
		(mid 82.471006 -289.039009)
		(end 82.284062 -288.988754)
		(width 0.0889)
		(layer "In11.Cu")
		(net "M_F_CPU1_SB_DQ<24>")
	)
	(arc
		(start 84.163916 -288.988754)
		(mid 83.88096 -288.912577)
		(end 83.598004 -288.988754)
		(width 0.0889)
		(layer "In11.Cu")
		(net "M_F_CPU1_SB_DQ<24>")
	)
	(arc
		(start 83.589622 -288.99358)
		(mid 83.406114 -289.039074)
		(end 83.223862 -288.988754)
		(width 0.0889)
		(layer "In11.Cu")
		(net "M_F_CPU1_SB_DQ<24>")
	)
	(segment
		(start 86.69782 -288.400236)
		(end 86.230968 -288.666174)
		(width 0.10668)
		(layer "F.Cu")
		(net "M_F_CPU1_SB_DQ<23>")
	)
	(segment
		(start 60.39993 -306.390802)
		(end 76.306426 -290.484306)
		(width 0.14478)
		(layer "In11.Cu")
		(net "M_F_CPU1_SB_DQ<23>")
	)
	(segment
		(start 31.480252 -309.11038)
		(end 34.46399 -309.11038)
		(width 0.14478)
		(layer "In11.Cu")
		(net "M_F_CPU1_SB_DQ<23>")
	)
	(segment
		(start 18.032984 -309.11038)
		(end 18.764504 -309.11038)
		(width 0.14478)
		(layer "In11.Cu")
		(net "M_F_CPU1_SB_DQ<23>")
	)
	(segment
		(start 37.717984 -308.260242)
		(end 38.990016 -309.11038)
		(width 0.14478)
		(layer "In11.Cu")
		(net "M_F_CPU1_SB_DQ<23>")
	)
	(segment
		(start 59.885326 -307.859938)
		(end 60.39993 -307.345334)
		(width 0.14478)
		(layer "In11.Cu")
		(net "M_F_CPU1_SB_DQ<23>")
	)
	(segment
		(start 50.758598 -308.260242)
		(end 53.08727 -308.260242)
		(width 0.14478)
		(layer "In11.Cu")
		(net "M_F_CPU1_SB_DQ<23>")
	)
	(segment
		(start 43.38955 -308.260242)
		(end 45.322236 -308.260242)
		(width 0.14478)
		(layer "In11.Cu")
		(net "M_F_CPU1_SB_DQ<23>")
	)
	(segment
		(start 46.594776 -309.11038)
		(end 49.486566 -309.11038)
		(width 0.14478)
		(layer "In11.Cu")
		(net "M_F_CPU1_SB_DQ<23>")
	)
	(segment
		(start 45.322236 -308.260242)
		(end 46.594776 -309.11038)
		(width 0.14478)
		(layer "In11.Cu")
		(net "M_F_CPU1_SB_DQ<23>")
	)
	(segment
		(start 53.76799 -308.715156)
		(end 57.61101 -308.715156)
		(width 0.14478)
		(layer "In11.Cu")
		(net "M_F_CPU1_SB_DQ<23>")
	)
	(segment
		(start 28.35275 -308.260242)
		(end 30.207966 -308.260242)
		(width 0.14478)
		(layer "In11.Cu")
		(net "M_F_CPU1_SB_DQ<23>")
	)
	(segment
		(start 83.589622 -288.339022)
		(end 83.598004 -288.343848)
		(width 0.0889)
		(layer "In11.Cu")
		(net "M_F_CPU1_SB_DQ<23>")
	)
	(segment
		(start 81.344008 -288.343848)
		(end 81.35239 -288.339022)
		(width 0.0889)
		(layer "In11.Cu")
		(net "M_F_CPU1_SB_DQ<23>")
	)
	(segment
		(start 78.586838 -288.298128)
		(end 79.610712 -288.298128)
		(width 0.0889)
		(layer "In11.Cu")
		(net "M_F_CPU1_SB_DQ<23>")
	)
	(segment
		(start 17.608042 -308.685438)
		(end 18.032984 -309.11038)
		(width 0.14478)
		(layer "In11.Cu")
		(net "M_F_CPU1_SB_DQ<23>")
	)
	(segment
		(start 57.61101 -308.715156)
		(end 58.466228 -307.859938)
		(width 0.14478)
		(layer "In11.Cu")
		(net "M_F_CPU1_SB_DQ<23>")
	)
	(segment
		(start 19.343624 -308.408324)
		(end 19.488404 -308.553104)
		(width 0.14478)
		(layer "In11.Cu")
		(net "M_F_CPU1_SB_DQ<23>")
	)
	(segment
		(start 49.486566 -309.11038)
		(end 50.758598 -308.260242)
		(width 0.14478)
		(layer "In11.Cu")
		(net "M_F_CPU1_SB_DQ<23>")
	)
	(segment
		(start 80.39354 -288.349944)
		(end 80.403954 -288.343848)
		(width 0.0889)
		(layer "In11.Cu")
		(net "M_F_CPU1_SB_DQ<23>")
	)
	(segment
		(start 19.054064 -308.408324)
		(end 19.343624 -308.408324)
		(width 0.14478)
		(layer "In11.Cu")
		(net "M_F_CPU1_SB_DQ<23>")
	)
	(segment
		(start 58.466228 -307.859938)
		(end 59.885326 -307.859938)
		(width 0.14478)
		(layer "In11.Cu")
		(net "M_F_CPU1_SB_DQ<23>")
	)
	(segment
		(start 19.488404 -308.9656)
		(end 19.633184 -309.11038)
		(width 0.14478)
		(layer "In11.Cu")
		(net "M_F_CPU1_SB_DQ<23>")
	)
	(segment
		(start 77.12075 -289.697668)
		(end 78.4733 -288.345118)
		(width 0.0889)
		(layer "In11.Cu")
		(net "M_F_CPU1_SB_DQ<23>")
	)
	(segment
		(start 19.488404 -308.553104)
		(end 19.488404 -308.9656)
		(width 0.14478)
		(layer "In11.Cu")
		(net "M_F_CPU1_SB_DQ<23>")
	)
	(segment
		(start 18.764504 -309.11038)
		(end 18.909284 -308.9656)
		(width 0.14478)
		(layer "In11.Cu")
		(net "M_F_CPU1_SB_DQ<23>")
	)
	(segment
		(start 26.300176 -309.11038)
		(end 28.35275 -308.260242)
		(width 0.14478)
		(layer "In11.Cu")
		(net "M_F_CPU1_SB_DQ<23>")
	)
	(segment
		(start 18.909284 -308.9656)
		(end 18.909284 -308.553104)
		(width 0.14478)
		(layer "In11.Cu")
		(net "M_F_CPU1_SB_DQ<23>")
	)
	(segment
		(start 85.981286 -288.375344)
		(end 86.077044 -288.400744)
		(width 0.0889)
		(layer "In11.Cu")
		(net "M_F_CPU1_SB_DQ<23>")
	)
	(segment
		(start 77.093064 -289.697668)
		(end 77.12075 -289.697668)
		(width 0.0889)
		(layer "In11.Cu")
		(net "M_F_CPU1_SB_DQ<23>")
	)
	(segment
		(start 38.990016 -309.11038)
		(end 42.117264 -309.11038)
		(width 0.14478)
		(layer "In11.Cu")
		(net "M_F_CPU1_SB_DQ<23>")
	)
	(segment
		(start 84.529676 -288.339022)
		(end 84.538058 -288.343848)
		(width 0.0889)
		(layer "In11.Cu")
		(net "M_F_CPU1_SB_DQ<23>")
	)
	(segment
		(start 80.769714 -288.339022)
		(end 80.778096 -288.343848)
		(width 0.0889)
		(layer "In11.Cu")
		(net "M_F_CPU1_SB_DQ<23>")
	)
	(segment
		(start 30.207966 -308.260242)
		(end 31.480252 -309.11038)
		(width 0.14478)
		(layer "In11.Cu")
		(net "M_F_CPU1_SB_DQ<23>")
	)
	(segment
		(start 53.08727 -308.260242)
		(end 53.76799 -308.715156)
		(width 0.14478)
		(layer "In11.Cu")
		(net "M_F_CPU1_SB_DQ<23>")
	)
	(segment
		(start 76.306426 -290.484306)
		(end 77.093064 -289.697668)
		(width 0.0889)
		(layer "In11.Cu")
		(net "M_F_CPU1_SB_DQ<23>")
	)
	(segment
		(start 35.736022 -308.260242)
		(end 37.717984 -308.260242)
		(width 0.14478)
		(layer "In11.Cu")
		(net "M_F_CPU1_SB_DQ<23>")
	)
	(segment
		(start 60.39993 -307.345334)
		(end 60.39993 -306.390802)
		(width 0.14478)
		(layer "In11.Cu")
		(net "M_F_CPU1_SB_DQ<23>")
	)
	(segment
		(start 86.077044 -288.400744)
		(end 86.230968 -288.666174)
		(width 0.0889)
		(layer "In11.Cu")
		(net "M_F_CPU1_SB_DQ<23>")
	)
	(segment
		(start 18.909284 -308.553104)
		(end 19.054064 -308.408324)
		(width 0.14478)
		(layer "In11.Cu")
		(net "M_F_CPU1_SB_DQ<23>")
	)
	(segment
		(start 42.117264 -309.11038)
		(end 43.38955 -308.260242)
		(width 0.14478)
		(layer "In11.Cu")
		(net "M_F_CPU1_SB_DQ<23>")
	)
	(segment
		(start 85.10397 -288.343848)
		(end 85.112352 -288.339022)
		(width 0.0889)
		(layer "In11.Cu")
		(net "M_F_CPU1_SB_DQ<23>")
	)
	(segment
		(start 34.46399 -309.11038)
		(end 35.736022 -308.260242)
		(width 0.14478)
		(layer "In11.Cu")
		(net "M_F_CPU1_SB_DQ<23>")
	)
	(segment
		(start 19.633184 -309.11038)
		(end 26.300176 -309.11038)
		(width 0.14478)
		(layer "In11.Cu")
		(net "M_F_CPU1_SB_DQ<23>")
	)
	(arc
		(start 82.65795 -288.343848)
		(mid 82.940906 -288.420025)
		(end 83.223862 -288.343848)
		(width 0.0889)
		(layer "In11.Cu")
		(net "M_F_CPU1_SB_DQ<23>")
	)
	(arc
		(start 83.598004 -288.343848)
		(mid 83.88096 -288.420025)
		(end 84.163916 -288.343848)
		(width 0.0889)
		(layer "In11.Cu")
		(net "M_F_CPU1_SB_DQ<23>")
	)
	(arc
		(start 82.284062 -288.343848)
		(mid 82.471006 -288.293559)
		(end 82.65795 -288.343848)
		(width 0.0889)
		(layer "In11.Cu")
		(net "M_F_CPU1_SB_DQ<23>")
	)
	(arc
		(start 84.163916 -288.343848)
		(mid 84.346167 -288.293464)
		(end 84.529676 -288.339022)
		(width 0.0889)
		(layer "In11.Cu")
		(net "M_F_CPU1_SB_DQ<23>")
	)
	(arc
		(start 84.538058 -288.343848)
		(mid 84.821014 -288.420025)
		(end 85.10397 -288.343848)
		(width 0.0889)
		(layer "In11.Cu")
		(net "M_F_CPU1_SB_DQ<23>")
	)
	(arc
		(start 79.610712 -288.298128)
		(mid 79.741824 -288.313711)
		(end 79.865728 -288.359342)
		(width 0.0889)
		(layer "In11.Cu")
		(net "M_F_CPU1_SB_DQ<23>")
	)
	(arc
		(start 85.478112 -288.343848)
		(mid 85.725972 -288.418931)
		(end 85.981286 -288.375344)
		(width 0.0889)
		(layer "In11.Cu")
		(net "M_F_CPU1_SB_DQ<23>")
	)
	(arc
		(start 81.35239 -288.339022)
		(mid 81.535898 -288.293497)
		(end 81.71815 -288.343848)
		(width 0.0889)
		(layer "In11.Cu")
		(net "M_F_CPU1_SB_DQ<23>")
	)
	(arc
		(start 80.403954 -288.343848)
		(mid 80.586205 -288.293464)
		(end 80.769714 -288.339022)
		(width 0.0889)
		(layer "In11.Cu")
		(net "M_F_CPU1_SB_DQ<23>")
	)
	(arc
		(start 81.71815 -288.343848)
		(mid 82.001106 -288.420025)
		(end 82.284062 -288.343848)
		(width 0.0889)
		(layer "In11.Cu")
		(net "M_F_CPU1_SB_DQ<23>")
	)
	(arc
		(start 78.4733 -288.345118)
		(mid 78.525406 -288.310365)
		(end 78.586838 -288.298128)
		(width 0.0889)
		(layer "In11.Cu")
		(net "M_F_CPU1_SB_DQ<23>")
	)
	(arc
		(start 85.112352 -288.339022)
		(mid 85.29586 -288.293497)
		(end 85.478112 -288.343848)
		(width 0.0889)
		(layer "In11.Cu")
		(net "M_F_CPU1_SB_DQ<23>")
	)
	(arc
		(start 80.778096 -288.343848)
		(mid 81.061052 -288.420025)
		(end 81.344008 -288.343848)
		(width 0.0889)
		(layer "In11.Cu")
		(net "M_F_CPU1_SB_DQ<23>")
	)
	(arc
		(start 79.865728 -288.359342)
		(mid 80.130799 -288.420241)
		(end 80.39354 -288.349944)
		(width 0.0889)
		(layer "In11.Cu")
		(net "M_F_CPU1_SB_DQ<23>")
	)
	(arc
		(start 83.223862 -288.343848)
		(mid 83.406113 -288.293464)
		(end 83.589622 -288.339022)
		(width 0.0889)
		(layer "In11.Cu")
		(net "M_F_CPU1_SB_DQ<23>")
	)
	(segment
		(start 85.287866 -287.590484)
		(end 84.821014 -287.856422)
		(width 0.10668)
		(layer "F.Cu")
		(net "M_F_CPU1_SB_DQ<22>")
	)
	(segment
		(start 30.992826 -307.410358)
		(end 30.142688 -306.56022)
		(width 0.14478)
		(layer "In11.Cu")
		(net "M_F_CPU1_SB_DQ<22>")
	)
	(segment
		(start 37.801296 -306.56022)
		(end 35.863276 -306.56022)
		(width 0.14478)
		(layer "In11.Cu")
		(net "M_F_CPU1_SB_DQ<22>")
	)
	(segment
		(start 57.429654 -307.410358)
		(end 53.725318 -307.410358)
		(width 0.14478)
		(layer "In11.Cu")
		(net "M_F_CPU1_SB_DQ<22>")
	)
	(segment
		(start 20.380198 -307.007006)
		(end 20.235418 -306.862226)
		(width 0.14478)
		(layer "In11.Cu")
		(net "M_F_CPU1_SB_DQ<22>")
	)
	(segment
		(start 77.313536 -288.346134)
		(end 76.937616 -288.346134)
		(width 0.0889)
		(layer "In11.Cu")
		(net "M_F_CPU1_SB_DQ<22>")
	)
	(segment
		(start 45.268896 -306.56022)
		(end 43.559476 -306.56022)
		(width 0.14478)
		(layer "In11.Cu")
		(net "M_F_CPU1_SB_DQ<22>")
	)
	(segment
		(start 20.380198 -307.265578)
		(end 20.380198 -307.007006)
		(width 0.14478)
		(layer "In11.Cu")
		(net "M_F_CPU1_SB_DQ<22>")
	)
	(segment
		(start 76.481686 -289.029648)
		(end 75.934824 -289.57651)
		(width 0.0889)
		(layer "In11.Cu")
		(net "M_F_CPU1_SB_DQ<22>")
	)
	(segment
		(start 19.42211 -307.410358)
		(end 19.27733 -307.265578)
		(width 0.14478)
		(layer "In11.Cu")
		(net "M_F_CPU1_SB_DQ<22>")
	)
	(segment
		(start 79.945992 -287.526984)
		(end 79.934308 -287.533842)
		(width 0.0889)
		(layer "In11.Cu")
		(net "M_F_CPU1_SB_DQ<22>")
	)
	(segment
		(start 19.27733 -307.265578)
		(end 19.27733 -307.007006)
		(width 0.14478)
		(layer "In11.Cu")
		(net "M_F_CPU1_SB_DQ<22>")
	)
	(segment
		(start 50.968148 -306.56022)
		(end 50.11801 -307.410358)
		(width 0.14478)
		(layer "In11.Cu")
		(net "M_F_CPU1_SB_DQ<22>")
	)
	(segment
		(start 19.683984 -307.410358)
		(end 19.42211 -307.410358)
		(width 0.14478)
		(layer "In11.Cu")
		(net "M_F_CPU1_SB_DQ<22>")
	)
	(segment
		(start 82.18805 -287.533842)
		(end 82.179668 -287.529016)
		(width 0.0889)
		(layer "In11.Cu")
		(net "M_F_CPU1_SB_DQ<22>")
	)
	(segment
		(start 27.248866 -307.410358)
		(end 20.524978 -307.410358)
		(width 0.14478)
		(layer "In11.Cu")
		(net "M_F_CPU1_SB_DQ<22>")
	)
	(segment
		(start 18.725896 -307.007006)
		(end 18.725896 -307.265578)
		(width 0.14478)
		(layer "In11.Cu")
		(net "M_F_CPU1_SB_DQ<22>")
	)
	(segment
		(start 76.937616 -288.346134)
		(end 76.481686 -288.802064)
		(width 0.0889)
		(layer "In11.Cu")
		(net "M_F_CPU1_SB_DQ<22>")
	)
	(segment
		(start 19.973544 -306.862226)
		(end 19.828764 -307.007006)
		(width 0.14478)
		(layer "In11.Cu")
		(net "M_F_CPU1_SB_DQ<22>")
	)
	(segment
		(start 18.581116 -307.410358)
		(end 18.032984 -307.410358)
		(width 0.14478)
		(layer "In11.Cu")
		(net "M_F_CPU1_SB_DQ<22>")
	)
	(segment
		(start 30.142688 -306.56022)
		(end 28.099004 -306.56022)
		(width 0.14478)
		(layer "In11.Cu")
		(net "M_F_CPU1_SB_DQ<22>")
	)
	(segment
		(start 19.828764 -307.007006)
		(end 19.828764 -307.265578)
		(width 0.14478)
		(layer "In11.Cu")
		(net "M_F_CPU1_SB_DQ<22>")
	)
	(segment
		(start 84.66709 -287.590992)
		(end 84.571078 -287.565592)
		(width 0.0889)
		(layer "In11.Cu")
		(net "M_F_CPU1_SB_DQ<22>")
	)
	(segment
		(start 79.369158 -287.533842)
		(end 79.357474 -287.526984)
		(width 0.0889)
		(layer "In11.Cu")
		(net "M_F_CPU1_SB_DQ<22>")
	)
	(segment
		(start 53.725318 -307.410358)
		(end 52.87518 -306.56022)
		(width 0.14478)
		(layer "In11.Cu")
		(net "M_F_CPU1_SB_DQ<22>")
	)
	(segment
		(start 42.709338 -307.410358)
		(end 38.651434 -307.410358)
		(width 0.14478)
		(layer "In11.Cu")
		(net "M_F_CPU1_SB_DQ<22>")
	)
	(segment
		(start 43.559476 -306.56022)
		(end 42.709338 -307.410358)
		(width 0.14478)
		(layer "In11.Cu")
		(net "M_F_CPU1_SB_DQ<22>")
	)
	(segment
		(start 18.870676 -306.862226)
		(end 18.725896 -307.007006)
		(width 0.14478)
		(layer "In11.Cu")
		(net "M_F_CPU1_SB_DQ<22>")
	)
	(segment
		(start 76.481686 -288.802064)
		(end 76.481686 -289.029648)
		(width 0.0889)
		(layer "In11.Cu")
		(net "M_F_CPU1_SB_DQ<22>")
	)
	(segment
		(start 20.235418 -306.862226)
		(end 19.973544 -306.862226)
		(width 0.14478)
		(layer "In11.Cu")
		(net "M_F_CPU1_SB_DQ<22>")
	)
	(segment
		(start 79.934308 -287.533842)
		(end 79.916274 -287.544256)
		(width 0.0889)
		(layer "In11.Cu")
		(net "M_F_CPU1_SB_DQ<22>")
	)
	(segment
		(start 18.032984 -307.410358)
		(end 17.608042 -306.985416)
		(width 0.14478)
		(layer "In11.Cu")
		(net "M_F_CPU1_SB_DQ<22>")
	)
	(segment
		(start 18.725896 -307.265578)
		(end 18.581116 -307.410358)
		(width 0.14478)
		(layer "In11.Cu")
		(net "M_F_CPU1_SB_DQ<22>")
	)
	(segment
		(start 78.661514 -287.707578)
		(end 78.01864 -287.707578)
		(width 0.0889)
		(layer "In11.Cu")
		(net "M_F_CPU1_SB_DQ<22>")
	)
	(segment
		(start 35.013138 -307.410358)
		(end 30.992826 -307.410358)
		(width 0.14478)
		(layer "In11.Cu")
		(net "M_F_CPU1_SB_DQ<22>")
	)
	(segment
		(start 75.934824 -289.57651)
		(end 58.951114 -306.56022)
		(width 0.14478)
		(layer "In11.Cu")
		(net "M_F_CPU1_SB_DQ<22>")
	)
	(segment
		(start 28.099004 -306.56022)
		(end 27.248866 -307.410358)
		(width 0.14478)
		(layer "In11.Cu")
		(net "M_F_CPU1_SB_DQ<22>")
	)
	(segment
		(start 38.651434 -307.410358)
		(end 37.801296 -306.56022)
		(width 0.14478)
		(layer "In11.Cu")
		(net "M_F_CPU1_SB_DQ<22>")
	)
	(segment
		(start 19.27733 -307.007006)
		(end 19.13255 -306.862226)
		(width 0.14478)
		(layer "In11.Cu")
		(net "M_F_CPU1_SB_DQ<22>")
	)
	(segment
		(start 52.87518 -306.56022)
		(end 50.968148 -306.56022)
		(width 0.14478)
		(layer "In11.Cu")
		(net "M_F_CPU1_SB_DQ<22>")
	)
	(segment
		(start 82.762344 -287.529016)
		(end 82.753962 -287.533842)
		(width 0.0889)
		(layer "In11.Cu")
		(net "M_F_CPU1_SB_DQ<22>")
	)
	(segment
		(start 35.863276 -306.56022)
		(end 35.013138 -307.410358)
		(width 0.14478)
		(layer "In11.Cu")
		(net "M_F_CPU1_SB_DQ<22>")
	)
	(segment
		(start 58.279792 -306.56022)
		(end 57.429654 -307.410358)
		(width 0.14478)
		(layer "In11.Cu")
		(net "M_F_CPU1_SB_DQ<22>")
	)
	(segment
		(start 83.702398 -287.529016)
		(end 83.694016 -287.533842)
		(width 0.0889)
		(layer "In11.Cu")
		(net "M_F_CPU1_SB_DQ<22>")
	)
	(segment
		(start 58.951114 -306.56022)
		(end 58.279792 -306.56022)
		(width 0.14478)
		(layer "In11.Cu")
		(net "M_F_CPU1_SB_DQ<22>")
	)
	(segment
		(start 20.524978 -307.410358)
		(end 20.380198 -307.265578)
		(width 0.14478)
		(layer "In11.Cu")
		(net "M_F_CPU1_SB_DQ<22>")
	)
	(segment
		(start 79.094584 -287.511998)
		(end 78.842108 -287.65881)
		(width 0.0889)
		(layer "In11.Cu")
		(net "M_F_CPU1_SB_DQ<22>")
	)
	(segment
		(start 46.119034 -307.410358)
		(end 45.268896 -306.56022)
		(width 0.14478)
		(layer "In11.Cu")
		(net "M_F_CPU1_SB_DQ<22>")
	)
	(segment
		(start 50.11801 -307.410358)
		(end 46.119034 -307.410358)
		(width 0.14478)
		(layer "In11.Cu")
		(net "M_F_CPU1_SB_DQ<22>")
	)
	(segment
		(start 19.828764 -307.265578)
		(end 19.683984 -307.410358)
		(width 0.14478)
		(layer "In11.Cu")
		(net "M_F_CPU1_SB_DQ<22>")
	)
	(segment
		(start 84.821014 -287.856422)
		(end 84.66709 -287.590992)
		(width 0.0889)
		(layer "In11.Cu")
		(net "M_F_CPU1_SB_DQ<22>")
	)
	(segment
		(start 77.905102 -287.754568)
		(end 77.313536 -288.346134)
		(width 0.0889)
		(layer "In11.Cu")
		(net "M_F_CPU1_SB_DQ<22>")
	)
	(segment
		(start 19.13255 -306.862226)
		(end 18.870676 -306.862226)
		(width 0.14478)
		(layer "In11.Cu")
		(net "M_F_CPU1_SB_DQ<22>")
	)
	(arc
		(start 79.916274 -287.544256)
		(mid 79.64137 -287.609866)
		(end 79.369158 -287.533842)
		(width 0.0889)
		(layer "In11.Cu")
		(net "M_F_CPU1_SB_DQ<22>")
	)
	(arc
		(start 79.218028 -287.48482)
		(mid 79.154168 -287.488706)
		(end 79.094584 -287.511998)
		(width 0.0889)
		(layer "In11.Cu")
		(net "M_F_CPU1_SB_DQ<22>")
	)
	(arc
		(start 84.068158 -287.533842)
		(mid 83.885907 -287.483492)
		(end 83.702398 -287.529016)
		(width 0.0889)
		(layer "In11.Cu")
		(net "M_F_CPU1_SB_DQ<22>")
	)
	(arc
		(start 83.694016 -287.533842)
		(mid 83.41106 -287.609985)
		(end 83.128104 -287.533842)
		(width 0.0889)
		(layer "In11.Cu")
		(net "M_F_CPU1_SB_DQ<22>")
	)
	(arc
		(start 79.357474 -287.526984)
		(mid 79.289825 -287.499051)
		(end 79.218028 -287.48482)
		(width 0.0889)
		(layer "In11.Cu")
		(net "M_F_CPU1_SB_DQ<22>")
	)
	(arc
		(start 84.571078 -287.565592)
		(mid 84.31587 -287.609049)
		(end 84.068158 -287.533842)
		(width 0.0889)
		(layer "In11.Cu")
		(net "M_F_CPU1_SB_DQ<22>")
	)
	(arc
		(start 80.874108 -287.533842)
		(mid 80.591152 -287.609985)
		(end 80.308196 -287.533842)
		(width 0.0889)
		(layer "In11.Cu")
		(net "M_F_CPU1_SB_DQ<22>")
	)
	(arc
		(start 82.179668 -287.529016)
		(mid 81.99616 -287.483522)
		(end 81.813908 -287.533842)
		(width 0.0889)
		(layer "In11.Cu")
		(net "M_F_CPU1_SB_DQ<22>")
	)
	(arc
		(start 81.813908 -287.533842)
		(mid 81.530952 -287.609985)
		(end 81.247996 -287.533842)
		(width 0.0889)
		(layer "In11.Cu")
		(net "M_F_CPU1_SB_DQ<22>")
	)
	(arc
		(start 83.128104 -287.533842)
		(mid 82.945853 -287.483492)
		(end 82.762344 -287.529016)
		(width 0.0889)
		(layer "In11.Cu")
		(net "M_F_CPU1_SB_DQ<22>")
	)
	(arc
		(start 78.842108 -287.65881)
		(mid 78.755042 -287.695169)
		(end 78.661514 -287.707578)
		(width 0.0889)
		(layer "In11.Cu")
		(net "M_F_CPU1_SB_DQ<22>")
	)
	(arc
		(start 80.308196 -287.533842)
		(mid 80.127991 -287.483525)
		(end 79.945992 -287.526984)
		(width 0.0889)
		(layer "In11.Cu")
		(net "M_F_CPU1_SB_DQ<22>")
	)
	(arc
		(start 81.247996 -287.533842)
		(mid 81.061052 -287.483587)
		(end 80.874108 -287.533842)
		(width 0.0889)
		(layer "In11.Cu")
		(net "M_F_CPU1_SB_DQ<22>")
	)
	(arc
		(start 82.753962 -287.533842)
		(mid 82.471006 -287.609985)
		(end 82.18805 -287.533842)
		(width 0.0889)
		(layer "In11.Cu")
		(net "M_F_CPU1_SB_DQ<22>")
	)
	(arc
		(start 78.01864 -287.707578)
		(mid 77.957194 -287.719782)
		(end 77.905102 -287.754568)
		(width 0.0889)
		(layer "In11.Cu")
		(net "M_F_CPU1_SB_DQ<22>")
	)
	(segment
		(start 86.22792 -287.590484)
		(end 85.761068 -287.856422)
		(width 0.10668)
		(layer "F.Cu")
		(net "M_F_CPU1_SB_DQ<21>")
	)
	(segment
		(start 24.800814 -308.260496)
		(end 24.411686 -307.871368)
		(width 0.14478)
		(layer "In11.Cu")
		(net "M_F_CPU1_SB_DQ<21>")
	)
	(segment
		(start 54.859682 -308.015386)
		(end 54.714902 -307.870606)
		(width 0.14478)
		(layer "In11.Cu")
		(net "M_F_CPU1_SB_DQ<21>")
	)
	(segment
		(start 38.612318 -308.260496)
		(end 37.76218 -307.410358)
		(width 0.14478)
		(layer "In11.Cu")
		(net "M_F_CPU1_SB_DQ<21>")
	)
	(segment
		(start 22.512274 -308.639464)
		(end 21.70811 -307.8353)
		(width 0.14478)
		(layer "In11.Cu")
		(net "M_F_CPU1_SB_DQ<21>")
	)
	(segment
		(start 76.944982 -288.770568)
		(end 76.728066 -288.987484)
		(width 0.0889)
		(layer "In11.Cu")
		(net "M_F_CPU1_SB_DQ<21>")
	)
	(segment
		(start 79.700882 -288.073084)
		(end 79.550768 -288.023046)
		(width 0.0889)
		(layer "In11.Cu")
		(net "M_F_CPU1_SB_DQ<21>")
	)
	(segment
		(start 56.247538 -308.115716)
		(end 56.102758 -308.260496)
		(width 0.14478)
		(layer "In11.Cu")
		(net "M_F_CPU1_SB_DQ<21>")
	)
	(segment
		(start 53.081936 -307.410358)
		(end 50.761392 -307.410358)
		(width 0.14478)
		(layer "In11.Cu")
		(net "M_F_CPU1_SB_DQ<21>")
	)
	(segment
		(start 37.76218 -307.410358)
		(end 35.699192 -307.410358)
		(width 0.14478)
		(layer "In11.Cu")
		(net "M_F_CPU1_SB_DQ<21>")
	)
	(segment
		(start 76.728066 -288.987484)
		(end 76.728066 -289.419538)
		(width 0.0889)
		(layer "In11.Cu")
		(net "M_F_CPU1_SB_DQ<21>")
	)
	(segment
		(start 56.798972 -308.115716)
		(end 56.798972 -308.015386)
		(width 0.14478)
		(layer "In11.Cu")
		(net "M_F_CPU1_SB_DQ<21>")
	)
	(segment
		(start 25.97912 -308.581044)
		(end 25.658572 -308.260496)
		(width 0.14478)
		(layer "In11.Cu")
		(net "M_F_CPU1_SB_DQ<21>")
	)
	(segment
		(start 23.068534 -307.871368)
		(end 22.90572 -308.034182)
		(width 0.14478)
		(layer "In11.Cu")
		(net "M_F_CPU1_SB_DQ<21>")
	)
	(segment
		(start 58.279792 -307.410358)
		(end 57.429654 -308.260496)
		(width 0.14478)
		(layer "In11.Cu")
		(net "M_F_CPU1_SB_DQ<21>")
	)
	(segment
		(start 27.076654 -308.260496)
		(end 26.53538 -308.260496)
		(width 0.14478)
		(layer "In11.Cu")
		(net "M_F_CPU1_SB_DQ<21>")
	)
	(segment
		(start 54.163468 -308.260496)
		(end 53.932074 -308.260496)
		(width 0.14478)
		(layer "In11.Cu")
		(net "M_F_CPU1_SB_DQ<21>")
	)
	(segment
		(start 23.299166 -307.871368)
		(end 23.068534 -307.871368)
		(width 0.14478)
		(layer "In11.Cu")
		(net "M_F_CPU1_SB_DQ<21>")
	)
	(segment
		(start 83.702398 -288.183574)
		(end 83.694016 -288.178748)
		(width 0.0889)
		(layer "In11.Cu")
		(net "M_F_CPU1_SB_DQ<21>")
	)
	(segment
		(start 54.308248 -308.115716)
		(end 54.163468 -308.260496)
		(width 0.14478)
		(layer "In11.Cu")
		(net "M_F_CPU1_SB_DQ<21>")
	)
	(segment
		(start 31.119318 -308.260496)
		(end 30.26918 -307.410358)
		(width 0.14478)
		(layer "In11.Cu")
		(net "M_F_CPU1_SB_DQ<21>")
	)
	(segment
		(start 27.926792 -307.410358)
		(end 27.076654 -308.260496)
		(width 0.14478)
		(layer "In11.Cu")
		(net "M_F_CPU1_SB_DQ<21>")
	)
	(segment
		(start 46.308518 -308.260496)
		(end 45.45838 -307.410358)
		(width 0.14478)
		(layer "In11.Cu")
		(net "M_F_CPU1_SB_DQ<21>")
	)
	(segment
		(start 54.308248 -308.015386)
		(end 54.308248 -308.115716)
		(width 0.14478)
		(layer "In11.Cu")
		(net "M_F_CPU1_SB_DQ<21>")
	)
	(segment
		(start 77.352144 -288.723578)
		(end 77.05852 -288.723578)
		(width 0.0889)
		(layer "In11.Cu")
		(net "M_F_CPU1_SB_DQ<21>")
	)
	(segment
		(start 24.181054 -307.871368)
		(end 24.01824 -308.034182)
		(width 0.14478)
		(layer "In11.Cu")
		(net "M_F_CPU1_SB_DQ<21>")
	)
	(segment
		(start 23.46198 -308.47665)
		(end 23.46198 -308.034182)
		(width 0.14478)
		(layer "In11.Cu")
		(net "M_F_CPU1_SB_DQ<21>")
	)
	(segment
		(start 50.761392 -307.410358)
		(end 49.911254 -308.260496)
		(width 0.14478)
		(layer "In11.Cu")
		(net "M_F_CPU1_SB_DQ<21>")
	)
	(segment
		(start 33.010348 -308.260496)
		(end 31.119318 -308.260496)
		(width 0.14478)
		(layer "In11.Cu")
		(net "M_F_CPU1_SB_DQ<21>")
	)
	(segment
		(start 26.214832 -308.581044)
		(end 25.97912 -308.581044)
		(width 0.14478)
		(layer "In11.Cu")
		(net "M_F_CPU1_SB_DQ<21>")
	)
	(segment
		(start 79.426562 -288.00298)
		(end 78.205838 -288.00298)
		(width 0.0889)
		(layer "In11.Cu")
		(net "M_F_CPU1_SB_DQ<21>")
	)
	(segment
		(start 24.01824 -308.034182)
		(end 24.01824 -308.47665)
		(width 0.14478)
		(layer "In11.Cu")
		(net "M_F_CPU1_SB_DQ<21>")
	)
	(segment
		(start 26.53538 -308.260496)
		(end 26.214832 -308.581044)
		(width 0.14478)
		(layer "In11.Cu")
		(net "M_F_CPU1_SB_DQ<21>")
	)
	(segment
		(start 56.247538 -308.015386)
		(end 56.247538 -308.115716)
		(width 0.14478)
		(layer "In11.Cu")
		(net "M_F_CPU1_SB_DQ<21>")
	)
	(segment
		(start 57.429654 -308.260496)
		(end 56.943752 -308.260496)
		(width 0.14478)
		(layer "In11.Cu")
		(net "M_F_CPU1_SB_DQ<21>")
	)
	(segment
		(start 45.45838 -307.410358)
		(end 43.395392 -307.410358)
		(width 0.14478)
		(layer "In11.Cu")
		(net "M_F_CPU1_SB_DQ<21>")
	)
	(segment
		(start 75.957684 -290.18992)
		(end 59.95035 -306.197254)
		(width 0.14478)
		(layer "In11.Cu")
		(net "M_F_CPU1_SB_DQ<21>")
	)
	(segment
		(start 22.90572 -308.47665)
		(end 22.742906 -308.639464)
		(width 0.14478)
		(layer "In11.Cu")
		(net "M_F_CPU1_SB_DQ<21>")
	)
	(segment
		(start 59.698636 -307.410358)
		(end 58.279792 -307.410358)
		(width 0.14478)
		(layer "In11.Cu")
		(net "M_F_CPU1_SB_DQ<21>")
	)
	(segment
		(start 59.95035 -306.197254)
		(end 59.95035 -307.158644)
		(width 0.14478)
		(layer "In11.Cu")
		(net "M_F_CPU1_SB_DQ<21>")
	)
	(segment
		(start 33.333436 -308.583584)
		(end 33.010348 -308.260496)
		(width 0.14478)
		(layer "In11.Cu")
		(net "M_F_CPU1_SB_DQ<21>")
	)
	(segment
		(start 85.761068 -287.856422)
		(end 85.914992 -288.121852)
		(width 0.0889)
		(layer "In11.Cu")
		(net "M_F_CPU1_SB_DQ<21>")
	)
	(segment
		(start 59.95035 -307.158644)
		(end 59.698636 -307.410358)
		(width 0.14478)
		(layer "In11.Cu")
		(net "M_F_CPU1_SB_DQ<21>")
	)
	(segment
		(start 54.714902 -307.870606)
		(end 54.453028 -307.870606)
		(width 0.14478)
		(layer "In11.Cu")
		(net "M_F_CPU1_SB_DQ<21>")
	)
	(segment
		(start 49.911254 -308.260496)
		(end 46.308518 -308.260496)
		(width 0.14478)
		(layer "In11.Cu")
		(net "M_F_CPU1_SB_DQ<21>")
	)
	(segment
		(start 54.859682 -308.115716)
		(end 54.859682 -308.015386)
		(width 0.14478)
		(layer "In11.Cu")
		(net "M_F_CPU1_SB_DQ<21>")
	)
	(segment
		(start 56.798972 -308.015386)
		(end 56.654192 -307.870606)
		(width 0.14478)
		(layer "In11.Cu")
		(net "M_F_CPU1_SB_DQ<21>")
	)
	(segment
		(start 56.654192 -307.870606)
		(end 56.392318 -307.870606)
		(width 0.14478)
		(layer "In11.Cu")
		(net "M_F_CPU1_SB_DQ<21>")
	)
	(segment
		(start 23.46198 -308.034182)
		(end 23.299166 -307.871368)
		(width 0.14478)
		(layer "In11.Cu")
		(net "M_F_CPU1_SB_DQ<21>")
	)
	(segment
		(start 34.849054 -308.260496)
		(end 33.889696 -308.260496)
		(width 0.14478)
		(layer "In11.Cu")
		(net "M_F_CPU1_SB_DQ<21>")
	)
	(segment
		(start 33.889696 -308.260496)
		(end 33.566608 -308.583584)
		(width 0.14478)
		(layer "In11.Cu")
		(net "M_F_CPU1_SB_DQ<21>")
	)
	(segment
		(start 56.392318 -307.870606)
		(end 56.247538 -308.015386)
		(width 0.14478)
		(layer "In11.Cu")
		(net "M_F_CPU1_SB_DQ<21>")
	)
	(segment
		(start 42.545254 -308.260496)
		(end 38.612318 -308.260496)
		(width 0.14478)
		(layer "In11.Cu")
		(net "M_F_CPU1_SB_DQ<21>")
	)
	(segment
		(start 54.453028 -307.870606)
		(end 54.308248 -308.015386)
		(width 0.14478)
		(layer "In11.Cu")
		(net "M_F_CPU1_SB_DQ<21>")
	)
	(segment
		(start 56.943752 -308.260496)
		(end 56.798972 -308.115716)
		(width 0.14478)
		(layer "In11.Cu")
		(net "M_F_CPU1_SB_DQ<21>")
	)
	(segment
		(start 30.26918 -307.410358)
		(end 27.926792 -307.410358)
		(width 0.14478)
		(layer "In11.Cu")
		(net "M_F_CPU1_SB_DQ<21>")
	)
	(segment
		(start 33.566608 -308.583584)
		(end 33.333436 -308.583584)
		(width 0.14478)
		(layer "In11.Cu")
		(net "M_F_CPU1_SB_DQ<21>")
	)
	(segment
		(start 22.90572 -308.034182)
		(end 22.90572 -308.47665)
		(width 0.14478)
		(layer "In11.Cu")
		(net "M_F_CPU1_SB_DQ<21>")
	)
	(segment
		(start 55.004462 -308.260496)
		(end 54.859682 -308.115716)
		(width 0.14478)
		(layer "In11.Cu")
		(net "M_F_CPU1_SB_DQ<21>")
	)
	(segment
		(start 25.658572 -308.260496)
		(end 24.800814 -308.260496)
		(width 0.14478)
		(layer "In11.Cu")
		(net "M_F_CPU1_SB_DQ<21>")
	)
	(segment
		(start 82.18805 -288.178748)
		(end 82.179668 -288.183574)
		(width 0.0889)
		(layer "In11.Cu")
		(net "M_F_CPU1_SB_DQ<21>")
	)
	(segment
		(start 24.01824 -308.47665)
		(end 23.855426 -308.639464)
		(width 0.14478)
		(layer "In11.Cu")
		(net "M_F_CPU1_SB_DQ<21>")
	)
	(segment
		(start 24.411686 -307.871368)
		(end 24.181054 -307.871368)
		(width 0.14478)
		(layer "In11.Cu")
		(net "M_F_CPU1_SB_DQ<21>")
	)
	(segment
		(start 35.699192 -307.410358)
		(end 34.849054 -308.260496)
		(width 0.14478)
		(layer "In11.Cu")
		(net "M_F_CPU1_SB_DQ<21>")
	)
	(segment
		(start 53.932074 -308.260496)
		(end 53.081936 -307.410358)
		(width 0.14478)
		(layer "In11.Cu")
		(net "M_F_CPU1_SB_DQ<21>")
	)
	(segment
		(start 23.624794 -308.639464)
		(end 23.46198 -308.47665)
		(width 0.14478)
		(layer "In11.Cu")
		(net "M_F_CPU1_SB_DQ<21>")
	)
	(segment
		(start 82.762344 -288.183574)
		(end 82.753962 -288.178748)
		(width 0.0889)
		(layer "In11.Cu")
		(net "M_F_CPU1_SB_DQ<21>")
	)
	(segment
		(start 85.914992 -288.121852)
		(end 85.89264 -288.20491)
		(width 0.0889)
		(layer "In11.Cu")
		(net "M_F_CPU1_SB_DQ<21>")
	)
	(segment
		(start 76.728066 -289.419538)
		(end 75.957684 -290.18992)
		(width 0.0889)
		(layer "In11.Cu")
		(net "M_F_CPU1_SB_DQ<21>")
	)
	(segment
		(start 23.855426 -308.639464)
		(end 23.624794 -308.639464)
		(width 0.14478)
		(layer "In11.Cu")
		(net "M_F_CPU1_SB_DQ<21>")
	)
	(segment
		(start 22.742906 -308.639464)
		(end 22.512274 -308.639464)
		(width 0.14478)
		(layer "In11.Cu")
		(net "M_F_CPU1_SB_DQ<21>")
	)
	(segment
		(start 56.102758 -308.260496)
		(end 55.004462 -308.260496)
		(width 0.14478)
		(layer "In11.Cu")
		(net "M_F_CPU1_SB_DQ<21>")
	)
	(segment
		(start 78.0923 -288.04997)
		(end 77.465682 -288.676588)
		(width 0.0889)
		(layer "In11.Cu")
		(net "M_F_CPU1_SB_DQ<21>")
	)
	(segment
		(start 43.395392 -307.410358)
		(end 42.545254 -308.260496)
		(width 0.14478)
		(layer "In11.Cu")
		(net "M_F_CPU1_SB_DQ<21>")
	)
	(arc
		(start 80.874108 -288.178748)
		(mid 80.591152 -288.102571)
		(end 80.308196 -288.178748)
		(width 0.0889)
		(layer "In11.Cu")
		(net "M_F_CPU1_SB_DQ<21>")
	)
	(arc
		(start 85.57387 -288.178748)
		(mid 85.290914 -288.102571)
		(end 85.007958 -288.178748)
		(width 0.0889)
		(layer "In11.Cu")
		(net "M_F_CPU1_SB_DQ<21>")
	)
	(arc
		(start 83.694016 -288.178748)
		(mid 83.41106 -288.102571)
		(end 83.128104 -288.178748)
		(width 0.0889)
		(layer "In11.Cu")
		(net "M_F_CPU1_SB_DQ<21>")
	)
	(arc
		(start 82.179668 -288.183574)
		(mid 81.99616 -288.229099)
		(end 81.813908 -288.178748)
		(width 0.0889)
		(layer "In11.Cu")
		(net "M_F_CPU1_SB_DQ<21>")
	)
	(arc
		(start 85.89264 -288.20491)
		(mid 85.730308 -288.227744)
		(end 85.57387 -288.178748)
		(width 0.0889)
		(layer "In11.Cu")
		(net "M_F_CPU1_SB_DQ<21>")
	)
	(arc
		(start 84.068158 -288.178748)
		(mid 83.885907 -288.229132)
		(end 83.702398 -288.183574)
		(width 0.0889)
		(layer "In11.Cu")
		(net "M_F_CPU1_SB_DQ<21>")
	)
	(arc
		(start 77.465682 -288.676588)
		(mid 77.413576 -288.711341)
		(end 77.352144 -288.723578)
		(width 0.0889)
		(layer "In11.Cu")
		(net "M_F_CPU1_SB_DQ<21>")
	)
	(arc
		(start 81.247996 -288.178748)
		(mid 81.061052 -288.229037)
		(end 80.874108 -288.178748)
		(width 0.0889)
		(layer "In11.Cu")
		(net "M_F_CPU1_SB_DQ<21>")
	)
	(arc
		(start 79.550768 -288.023046)
		(mid 79.489473 -288.008011)
		(end 79.426562 -288.00298)
		(width 0.0889)
		(layer "In11.Cu")
		(net "M_F_CPU1_SB_DQ<21>")
	)
	(arc
		(start 82.753962 -288.178748)
		(mid 82.471006 -288.102571)
		(end 82.18805 -288.178748)
		(width 0.0889)
		(layer "In11.Cu")
		(net "M_F_CPU1_SB_DQ<21>")
	)
	(arc
		(start 78.205838 -288.00298)
		(mid 78.144392 -288.015184)
		(end 78.0923 -288.04997)
		(width 0.0889)
		(layer "In11.Cu")
		(net "M_F_CPU1_SB_DQ<21>")
	)
	(arc
		(start 84.63407 -288.178748)
		(mid 84.351114 -288.102571)
		(end 84.068158 -288.178748)
		(width 0.0889)
		(layer "In11.Cu")
		(net "M_F_CPU1_SB_DQ<21>")
	)
	(arc
		(start 85.007958 -288.178748)
		(mid 84.821014 -288.229037)
		(end 84.63407 -288.178748)
		(width 0.0889)
		(layer "In11.Cu")
		(net "M_F_CPU1_SB_DQ<21>")
	)
	(arc
		(start 81.813908 -288.178748)
		(mid 81.530952 -288.102571)
		(end 81.247996 -288.178748)
		(width 0.0889)
		(layer "In11.Cu")
		(net "M_F_CPU1_SB_DQ<21>")
	)
	(arc
		(start 77.05852 -288.723578)
		(mid 76.997074 -288.735782)
		(end 76.944982 -288.770568)
		(width 0.0889)
		(layer "In11.Cu")
		(net "M_F_CPU1_SB_DQ<21>")
	)
	(arc
		(start 79.9338 -288.178748)
		(mid 79.820071 -288.119897)
		(end 79.700882 -288.073084)
		(width 0.0889)
		(layer "In11.Cu")
		(net "M_F_CPU1_SB_DQ<21>")
	)
	(arc
		(start 83.128104 -288.178748)
		(mid 82.945853 -288.229132)
		(end 82.762344 -288.183574)
		(width 0.0889)
		(layer "In11.Cu")
		(net "M_F_CPU1_SB_DQ<21>")
	)
	(arc
		(start 80.308196 -288.178748)
		(mid 80.120998 -288.229165)
		(end 79.9338 -288.178748)
		(width 0.0889)
		(layer "In11.Cu")
		(net "M_F_CPU1_SB_DQ<21>")
	)
	(segment
		(start 84.817966 -286.780478)
		(end 84.351114 -287.046162)
		(width 0.10668)
		(layer "F.Cu")
		(net "M_F_CPU1_SB_DQ<20>")
	)
	(segment
		(start 23.861776 -306.789582)
		(end 23.861776 -306.723288)
		(width 0.14478)
		(layer "In11.Cu")
		(net "M_F_CPU1_SB_DQ<20>")
	)
	(segment
		(start 80.778096 -287.368742)
		(end 80.769714 -287.373568)
		(width 0.0889)
		(layer "In11.Cu")
		(net "M_F_CPU1_SB_DQ<20>")
	)
	(segment
		(start 50.74285 -305.933602)
		(end 50.74285 -305.873404)
		(width 0.14478)
		(layer "In11.Cu")
		(net "M_F_CPU1_SB_DQ<20>")
	)
	(segment
		(start 77.787754 -287.419796)
		(end 77.256386 -287.951164)
		(width 0.0889)
		(layer "In11.Cu")
		(net "M_F_CPU1_SB_DQ<20>")
	)
	(segment
		(start 41.044876 -306.789582)
		(end 41.044876 -306.723288)
		(width 0.14478)
		(layer "In11.Cu")
		(net "M_F_CPU1_SB_DQ<20>")
	)
	(segment
		(start 28.792932 -305.719988)
		(end 28.639516 -305.873404)
		(width 0.14478)
		(layer "In11.Cu")
		(net "M_F_CPU1_SB_DQ<20>")
	)
	(segment
		(start 38.956996 -306.714652)
		(end 37.962332 -305.719988)
		(width 0.14478)
		(layer "In11.Cu")
		(net "M_F_CPU1_SB_DQ<20>")
	)
	(segment
		(start 51.45278 -305.719988)
		(end 51.299364 -305.873404)
		(width 0.14478)
		(layer "In11.Cu")
		(net "M_F_CPU1_SB_DQ<20>")
	)
	(segment
		(start 31.475172 -306.813966)
		(end 31.475172 -306.714652)
		(width 0.14478)
		(layer "In11.Cu")
		(net "M_F_CPU1_SB_DQ<20>")
	)
	(segment
		(start 76.922122 -287.951164)
		(end 75.970384 -288.902902)
		(width 0.0889)
		(layer "In11.Cu")
		(net "M_F_CPU1_SB_DQ<20>")
	)
	(segment
		(start 24.41829 -306.789582)
		(end 24.255222 -306.95265)
		(width 0.14478)
		(layer "In11.Cu")
		(net "M_F_CPU1_SB_DQ<20>")
	)
	(segment
		(start 23.698708 -306.56022)
		(end 23.165308 -306.56022)
		(width 0.14478)
		(layer "In11.Cu")
		(net "M_F_CPU1_SB_DQ<20>")
	)
	(segment
		(start 43.58894 -306.09667)
		(end 43.358562 -306.09667)
		(width 0.14478)
		(layer "In11.Cu")
		(net "M_F_CPU1_SB_DQ<20>")
	)
	(segment
		(start 38.956996 -306.813966)
		(end 38.956996 -306.714652)
		(width 0.14478)
		(layer "In11.Cu")
		(net "M_F_CPU1_SB_DQ<20>")
	)
	(segment
		(start 22.282658 -306.56022)
		(end 22.133052 -306.56022)
		(width 0.14478)
		(layer "In11.Cu")
		(net "M_F_CPU1_SB_DQ<20>")
	)
	(segment
		(start 49.448974 -306.56022)
		(end 49.216056 -306.56022)
		(width 0.14478)
		(layer "In11.Cu")
		(net "M_F_CPU1_SB_DQ<20>")
	)
	(segment
		(start 28.476448 -306.10429)
		(end 28.24607 -306.10429)
		(width 0.14478)
		(layer "In11.Cu")
		(net "M_F_CPU1_SB_DQ<20>")
	)
	(segment
		(start 56.299862 -306.858924)
		(end 56.042052 -306.858924)
		(width 0.14478)
		(layer "In11.Cu")
		(net "M_F_CPU1_SB_DQ<20>")
	)
	(segment
		(start 83.598004 -287.368742)
		(end 83.589622 -287.373568)
		(width 0.0889)
		(layer "In11.Cu")
		(net "M_F_CPU1_SB_DQ<20>")
	)
	(segment
		(start 22.839172 -305.82997)
		(end 22.608794 -305.82997)
		(width 0.14478)
		(layer "In11.Cu")
		(net "M_F_CPU1_SB_DQ<20>")
	)
	(segment
		(start 53.962046 -306.560474)
		(end 53.12156 -305.719988)
		(width 0.14478)
		(layer "In11.Cu")
		(net "M_F_CPU1_SB_DQ<20>")
	)
	(segment
		(start 28.24607 -306.10429)
		(end 28.083002 -305.941222)
		(width 0.14478)
		(layer "In11.Cu")
		(net "M_F_CPU1_SB_DQ<20>")
	)
	(segment
		(start 54.929532 -306.858924)
		(end 54.631082 -306.560474)
		(width 0.14478)
		(layer "In11.Cu")
		(net "M_F_CPU1_SB_DQ<20>")
	)
	(segment
		(start 40.89146 -306.569872)
		(end 39.65321 -306.569872)
		(width 0.14478)
		(layer "In11.Cu")
		(net "M_F_CPU1_SB_DQ<20>")
	)
	(segment
		(start 43.905424 -305.719988)
		(end 43.752008 -305.873404)
		(width 0.14478)
		(layer "In11.Cu")
		(net "M_F_CPU1_SB_DQ<20>")
	)
	(segment
		(start 54.631082 -306.560474)
		(end 53.962046 -306.560474)
		(width 0.14478)
		(layer "In11.Cu")
		(net "M_F_CPU1_SB_DQ<20>")
	)
	(segment
		(start 48.496474 -306.723288)
		(end 48.343058 -306.569872)
		(width 0.14478)
		(layer "In11.Cu")
		(net "M_F_CPU1_SB_DQ<20>")
	)
	(segment
		(start 42.792904 -305.710336)
		(end 41.94302 -306.56022)
		(width 0.14478)
		(layer "In11.Cu")
		(net "M_F_CPU1_SB_DQ<20>")
	)
	(segment
		(start 22.133052 -306.56022)
		(end 21.70811 -306.135278)
		(width 0.14478)
		(layer "In11.Cu")
		(net "M_F_CPU1_SB_DQ<20>")
	)
	(segment
		(start 75.970384 -288.902902)
		(end 58.767726 -306.10556)
		(width 0.14478)
		(layer "In11.Cu")
		(net "M_F_CPU1_SB_DQ<20>")
	)
	(segment
		(start 50.298858 -305.710336)
		(end 49.448974 -306.56022)
		(width 0.14478)
		(layer "In11.Cu")
		(net "M_F_CPU1_SB_DQ<20>")
	)
	(segment
		(start 26.805128 -306.569872)
		(end 24.571706 -306.569872)
		(width 0.14478)
		(layer "In11.Cu")
		(net "M_F_CPU1_SB_DQ<20>")
	)
	(segment
		(start 28.639516 -305.873404)
		(end 28.639516 -305.941222)
		(width 0.14478)
		(layer "In11.Cu")
		(net "M_F_CPU1_SB_DQ<20>")
	)
	(segment
		(start 24.255222 -306.95265)
		(end 24.024844 -306.95265)
		(width 0.14478)
		(layer "In11.Cu")
		(net "M_F_CPU1_SB_DQ<20>")
	)
	(segment
		(start 41.764458 -306.56022)
		(end 41.60139 -306.723288)
		(width 0.14478)
		(layer "In11.Cu")
		(net "M_F_CPU1_SB_DQ<20>")
	)
	(segment
		(start 43.195494 -305.873404)
		(end 43.032426 -305.710336)
		(width 0.14478)
		(layer "In11.Cu")
		(net "M_F_CPU1_SB_DQ<20>")
	)
	(segment
		(start 36.174934 -305.941222)
		(end 36.011866 -306.10429)
		(width 0.14478)
		(layer "In11.Cu")
		(net "M_F_CPU1_SB_DQ<20>")
	)
	(segment
		(start 39.50843 -306.714652)
		(end 39.50843 -306.813966)
		(width 0.14478)
		(layer "In11.Cu")
		(net "M_F_CPU1_SB_DQ<20>")
	)
	(segment
		(start 37.962332 -305.719988)
		(end 36.32835 -305.719988)
		(width 0.14478)
		(layer "In11.Cu")
		(net "M_F_CPU1_SB_DQ<20>")
	)
	(segment
		(start 48.496474 -306.789582)
		(end 48.496474 -306.723288)
		(width 0.14478)
		(layer "In11.Cu")
		(net "M_F_CPU1_SB_DQ<20>")
	)
	(segment
		(start 39.65321 -306.569872)
		(end 39.50843 -306.714652)
		(width 0.14478)
		(layer "In11.Cu")
		(net "M_F_CPU1_SB_DQ<20>")
	)
	(segment
		(start 79.856838 -287.358328)
		(end 79.838804 -287.368742)
		(width 0.0889)
		(layer "In11.Cu")
		(net "M_F_CPU1_SB_DQ<20>")
	)
	(segment
		(start 50.74285 -305.873404)
		(end 50.579782 -305.710336)
		(width 0.14478)
		(layer "In11.Cu")
		(net "M_F_CPU1_SB_DQ<20>")
	)
	(segment
		(start 50.579782 -305.710336)
		(end 50.298858 -305.710336)
		(width 0.14478)
		(layer "In11.Cu")
		(net "M_F_CPU1_SB_DQ<20>")
	)
	(segment
		(start 55.743602 -306.560474)
		(end 55.485792 -306.560474)
		(width 0.14478)
		(layer "In11.Cu")
		(net "M_F_CPU1_SB_DQ<20>")
	)
	(segment
		(start 47.268384 -306.569872)
		(end 47.123604 -306.714652)
		(width 0.14478)
		(layer "In11.Cu")
		(net "M_F_CPU1_SB_DQ<20>")
	)
	(segment
		(start 46.71695 -306.958746)
		(end 46.57217 -306.813966)
		(width 0.14478)
		(layer "In11.Cu")
		(net "M_F_CPU1_SB_DQ<20>")
	)
	(segment
		(start 41.60139 -306.723288)
		(end 41.60139 -306.789582)
		(width 0.14478)
		(layer "In11.Cu")
		(net "M_F_CPU1_SB_DQ<20>")
	)
	(segment
		(start 55.485792 -306.560474)
		(end 55.187342 -306.858924)
		(width 0.14478)
		(layer "In11.Cu")
		(net "M_F_CPU1_SB_DQ<20>")
	)
	(segment
		(start 36.174934 -305.873404)
		(end 36.174934 -305.941222)
		(width 0.14478)
		(layer "In11.Cu")
		(net "M_F_CPU1_SB_DQ<20>")
	)
	(segment
		(start 78.711044 -287.419796)
		(end 77.787754 -287.419796)
		(width 0.0889)
		(layer "In11.Cu")
		(net "M_F_CPU1_SB_DQ<20>")
	)
	(segment
		(start 33.897062 -306.95265)
		(end 33.666684 -306.95265)
		(width 0.14478)
		(layer "In11.Cu")
		(net "M_F_CPU1_SB_DQ<20>")
	)
	(segment
		(start 28.639516 -305.941222)
		(end 28.476448 -306.10429)
		(width 0.14478)
		(layer "In11.Cu")
		(net "M_F_CPU1_SB_DQ<20>")
	)
	(segment
		(start 33.666684 -306.95265)
		(end 33.503616 -306.789582)
		(width 0.14478)
		(layer "In11.Cu")
		(net "M_F_CPU1_SB_DQ<20>")
	)
	(segment
		(start 49.216056 -306.56022)
		(end 49.052988 -306.723288)
		(width 0.14478)
		(layer "In11.Cu")
		(net "M_F_CPU1_SB_DQ<20>")
	)
	(segment
		(start 35.455352 -305.710336)
		(end 35.233102 -305.710336)
		(width 0.14478)
		(layer "In11.Cu")
		(net "M_F_CPU1_SB_DQ<20>")
	)
	(segment
		(start 46.57217 -306.714652)
		(end 45.577506 -305.719988)
		(width 0.14478)
		(layer "In11.Cu")
		(net "M_F_CPU1_SB_DQ<20>")
	)
	(segment
		(start 47.123604 -306.813966)
		(end 46.978824 -306.958746)
		(width 0.14478)
		(layer "In11.Cu")
		(net "M_F_CPU1_SB_DQ<20>")
	)
	(segment
		(start 51.136296 -306.09667)
		(end 50.905918 -306.09667)
		(width 0.14478)
		(layer "In11.Cu")
		(net "M_F_CPU1_SB_DQ<20>")
	)
	(segment
		(start 43.195494 -305.933602)
		(end 43.195494 -305.873404)
		(width 0.14478)
		(layer "In11.Cu")
		(net "M_F_CPU1_SB_DQ<20>")
	)
	(segment
		(start 33.503616 -306.789582)
		(end 33.503616 -306.723288)
		(width 0.14478)
		(layer "In11.Cu")
		(net "M_F_CPU1_SB_DQ<20>")
	)
	(segment
		(start 41.94302 -306.56022)
		(end 41.764458 -306.56022)
		(width 0.14478)
		(layer "In11.Cu")
		(net "M_F_CPU1_SB_DQ<20>")
	)
	(segment
		(start 79.838804 -287.368742)
		(end 79.830422 -287.373568)
		(width 0.0889)
		(layer "In11.Cu")
		(net "M_F_CPU1_SB_DQ<20>")
	)
	(segment
		(start 39.101776 -306.958746)
		(end 38.956996 -306.813966)
		(width 0.14478)
		(layer "In11.Cu")
		(net "M_F_CPU1_SB_DQ<20>")
	)
	(segment
		(start 35.61842 -305.941222)
		(end 35.61842 -305.873404)
		(width 0.14478)
		(layer "In11.Cu")
		(net "M_F_CPU1_SB_DQ<20>")
	)
	(segment
		(start 33.503616 -306.723288)
		(end 33.3502 -306.569872)
		(width 0.14478)
		(layer "In11.Cu")
		(net "M_F_CPU1_SB_DQ<20>")
	)
	(segment
		(start 27.919934 -305.710336)
		(end 27.664664 -305.710336)
		(width 0.14478)
		(layer "In11.Cu")
		(net "M_F_CPU1_SB_DQ<20>")
	)
	(segment
		(start 34.383218 -306.56022)
		(end 34.223198 -306.56022)
		(width 0.14478)
		(layer "In11.Cu")
		(net "M_F_CPU1_SB_DQ<20>")
	)
	(segment
		(start 28.083002 -305.873404)
		(end 27.919934 -305.710336)
		(width 0.14478)
		(layer "In11.Cu")
		(net "M_F_CPU1_SB_DQ<20>")
	)
	(segment
		(start 49.052988 -306.723288)
		(end 49.052988 -306.789582)
		(width 0.14478)
		(layer "In11.Cu")
		(net "M_F_CPU1_SB_DQ<20>")
	)
	(segment
		(start 33.3502 -306.569872)
		(end 32.171386 -306.569872)
		(width 0.14478)
		(layer "In11.Cu")
		(net "M_F_CPU1_SB_DQ<20>")
	)
	(segment
		(start 34.06013 -306.723288)
		(end 34.06013 -306.789582)
		(width 0.14478)
		(layer "In11.Cu")
		(net "M_F_CPU1_SB_DQ<20>")
	)
	(segment
		(start 56.042052 -306.858924)
		(end 55.743602 -306.560474)
		(width 0.14478)
		(layer "In11.Cu")
		(net "M_F_CPU1_SB_DQ<20>")
	)
	(segment
		(start 43.032426 -305.710336)
		(end 42.792904 -305.710336)
		(width 0.14478)
		(layer "In11.Cu")
		(net "M_F_CPU1_SB_DQ<20>")
	)
	(segment
		(start 23.165308 -306.56022)
		(end 23.00224 -306.397152)
		(width 0.14478)
		(layer "In11.Cu")
		(net "M_F_CPU1_SB_DQ<20>")
	)
	(segment
		(start 57.63641 -306.560474)
		(end 56.598312 -306.560474)
		(width 0.14478)
		(layer "In11.Cu")
		(net "M_F_CPU1_SB_DQ<20>")
	)
	(segment
		(start 31.619952 -306.958746)
		(end 31.475172 -306.813966)
		(width 0.14478)
		(layer "In11.Cu")
		(net "M_F_CPU1_SB_DQ<20>")
	)
	(segment
		(start 35.61842 -305.873404)
		(end 35.455352 -305.710336)
		(width 0.14478)
		(layer "In11.Cu")
		(net "M_F_CPU1_SB_DQ<20>")
	)
	(segment
		(start 47.123604 -306.714652)
		(end 47.123604 -306.813966)
		(width 0.14478)
		(layer "In11.Cu")
		(net "M_F_CPU1_SB_DQ<20>")
	)
	(segment
		(start 55.187342 -306.858924)
		(end 54.929532 -306.858924)
		(width 0.14478)
		(layer "In11.Cu")
		(net "M_F_CPU1_SB_DQ<20>")
	)
	(segment
		(start 34.06013 -306.789582)
		(end 33.897062 -306.95265)
		(width 0.14478)
		(layer "In11.Cu")
		(net "M_F_CPU1_SB_DQ<20>")
	)
	(segment
		(start 32.026606 -306.813966)
		(end 31.881826 -306.958746)
		(width 0.14478)
		(layer "In11.Cu")
		(net "M_F_CPU1_SB_DQ<20>")
	)
	(segment
		(start 39.36365 -306.958746)
		(end 39.101776 -306.958746)
		(width 0.14478)
		(layer "In11.Cu")
		(net "M_F_CPU1_SB_DQ<20>")
	)
	(segment
		(start 41.60139 -306.789582)
		(end 41.438322 -306.95265)
		(width 0.14478)
		(layer "In11.Cu")
		(net "M_F_CPU1_SB_DQ<20>")
	)
	(segment
		(start 35.781488 -306.10429)
		(end 35.61842 -305.941222)
		(width 0.14478)
		(layer "In11.Cu")
		(net "M_F_CPU1_SB_DQ<20>")
	)
	(segment
		(start 30.480508 -305.719988)
		(end 28.792932 -305.719988)
		(width 0.14478)
		(layer "In11.Cu")
		(net "M_F_CPU1_SB_DQ<20>")
	)
	(segment
		(start 46.57217 -306.813966)
		(end 46.57217 -306.714652)
		(width 0.14478)
		(layer "In11.Cu")
		(net "M_F_CPU1_SB_DQ<20>")
	)
	(segment
		(start 84.505038 -287.311592)
		(end 84.482686 -287.394904)
		(width 0.0889)
		(layer "In11.Cu")
		(net "M_F_CPU1_SB_DQ<20>")
	)
	(segment
		(start 39.50843 -306.813966)
		(end 39.36365 -306.958746)
		(width 0.14478)
		(layer "In11.Cu")
		(net "M_F_CPU1_SB_DQ<20>")
	)
	(segment
		(start 58.767726 -306.10556)
		(end 58.091324 -306.10556)
		(width 0.14478)
		(layer "In11.Cu")
		(net "M_F_CPU1_SB_DQ<20>")
	)
	(segment
		(start 23.00224 -306.397152)
		(end 23.00224 -305.993038)
		(width 0.14478)
		(layer "In11.Cu")
		(net "M_F_CPU1_SB_DQ<20>")
	)
	(segment
		(start 31.881826 -306.958746)
		(end 31.619952 -306.958746)
		(width 0.14478)
		(layer "In11.Cu")
		(net "M_F_CPU1_SB_DQ<20>")
	)
	(segment
		(start 43.358562 -306.09667)
		(end 43.195494 -305.933602)
		(width 0.14478)
		(layer "In11.Cu")
		(net "M_F_CPU1_SB_DQ<20>")
	)
	(segment
		(start 35.233102 -305.710336)
		(end 34.383218 -306.56022)
		(width 0.14478)
		(layer "In11.Cu")
		(net "M_F_CPU1_SB_DQ<20>")
	)
	(segment
		(start 43.752008 -305.933602)
		(end 43.58894 -306.09667)
		(width 0.14478)
		(layer "In11.Cu")
		(net "M_F_CPU1_SB_DQ<20>")
	)
	(segment
		(start 41.438322 -306.95265)
		(end 41.207944 -306.95265)
		(width 0.14478)
		(layer "In11.Cu")
		(net "M_F_CPU1_SB_DQ<20>")
	)
	(segment
		(start 53.12156 -305.719988)
		(end 51.45278 -305.719988)
		(width 0.14478)
		(layer "In11.Cu")
		(net "M_F_CPU1_SB_DQ<20>")
	)
	(segment
		(start 50.905918 -306.09667)
		(end 50.74285 -305.933602)
		(width 0.14478)
		(layer "In11.Cu")
		(net "M_F_CPU1_SB_DQ<20>")
	)
	(segment
		(start 79.46517 -287.368742)
		(end 79.447136 -287.358074)
		(width 0.0889)
		(layer "In11.Cu")
		(net "M_F_CPU1_SB_DQ<20>")
	)
	(segment
		(start 32.026606 -306.714652)
		(end 32.026606 -306.813966)
		(width 0.14478)
		(layer "In11.Cu")
		(net "M_F_CPU1_SB_DQ<20>")
	)
	(segment
		(start 45.577506 -305.719988)
		(end 43.905424 -305.719988)
		(width 0.14478)
		(layer "In11.Cu")
		(net "M_F_CPU1_SB_DQ<20>")
	)
	(segment
		(start 43.752008 -305.873404)
		(end 43.752008 -305.933602)
		(width 0.14478)
		(layer "In11.Cu")
		(net "M_F_CPU1_SB_DQ<20>")
	)
	(segment
		(start 28.083002 -305.941222)
		(end 28.083002 -305.873404)
		(width 0.14478)
		(layer "In11.Cu")
		(net "M_F_CPU1_SB_DQ<20>")
	)
	(segment
		(start 22.608794 -305.82997)
		(end 22.445726 -305.993038)
		(width 0.14478)
		(layer "In11.Cu")
		(net "M_F_CPU1_SB_DQ<20>")
	)
	(segment
		(start 48.343058 -306.569872)
		(end 47.268384 -306.569872)
		(width 0.14478)
		(layer "In11.Cu")
		(net "M_F_CPU1_SB_DQ<20>")
	)
	(segment
		(start 56.598312 -306.560474)
		(end 56.299862 -306.858924)
		(width 0.14478)
		(layer "In11.Cu")
		(net "M_F_CPU1_SB_DQ<20>")
	)
	(segment
		(start 36.32835 -305.719988)
		(end 36.174934 -305.873404)
		(width 0.14478)
		(layer "In11.Cu")
		(net "M_F_CPU1_SB_DQ<20>")
	)
	(segment
		(start 36.011866 -306.10429)
		(end 35.781488 -306.10429)
		(width 0.14478)
		(layer "In11.Cu")
		(net "M_F_CPU1_SB_DQ<20>")
	)
	(segment
		(start 46.978824 -306.958746)
		(end 46.71695 -306.958746)
		(width 0.14478)
		(layer "In11.Cu")
		(net "M_F_CPU1_SB_DQ<20>")
	)
	(segment
		(start 22.445726 -306.397152)
		(end 22.282658 -306.56022)
		(width 0.14478)
		(layer "In11.Cu")
		(net "M_F_CPU1_SB_DQ<20>")
	)
	(segment
		(start 58.091324 -306.10556)
		(end 57.63641 -306.560474)
		(width 0.14478)
		(layer "In11.Cu")
		(net "M_F_CPU1_SB_DQ<20>")
	)
	(segment
		(start 51.299364 -305.873404)
		(end 51.299364 -305.933602)
		(width 0.14478)
		(layer "In11.Cu")
		(net "M_F_CPU1_SB_DQ<20>")
	)
	(segment
		(start 84.351114 -287.046162)
		(end 84.505038 -287.311592)
		(width 0.0889)
		(layer "In11.Cu")
		(net "M_F_CPU1_SB_DQ<20>")
	)
	(segment
		(start 48.88992 -306.95265)
		(end 48.659542 -306.95265)
		(width 0.14478)
		(layer "In11.Cu")
		(net "M_F_CPU1_SB_DQ<20>")
	)
	(segment
		(start 31.475172 -306.714652)
		(end 30.480508 -305.719988)
		(width 0.14478)
		(layer "In11.Cu")
		(net "M_F_CPU1_SB_DQ<20>")
	)
	(segment
		(start 24.024844 -306.95265)
		(end 23.861776 -306.789582)
		(width 0.14478)
		(layer "In11.Cu")
		(net "M_F_CPU1_SB_DQ<20>")
	)
	(segment
		(start 48.659542 -306.95265)
		(end 48.496474 -306.789582)
		(width 0.14478)
		(layer "In11.Cu")
		(net "M_F_CPU1_SB_DQ<20>")
	)
	(segment
		(start 24.41829 -306.723288)
		(end 24.41829 -306.789582)
		(width 0.14478)
		(layer "In11.Cu")
		(net "M_F_CPU1_SB_DQ<20>")
	)
	(segment
		(start 49.052988 -306.789582)
		(end 48.88992 -306.95265)
		(width 0.14478)
		(layer "In11.Cu")
		(net "M_F_CPU1_SB_DQ<20>")
	)
	(segment
		(start 23.00224 -305.993038)
		(end 22.839172 -305.82997)
		(width 0.14478)
		(layer "In11.Cu")
		(net "M_F_CPU1_SB_DQ<20>")
	)
	(segment
		(start 32.171386 -306.569872)
		(end 32.026606 -306.714652)
		(width 0.14478)
		(layer "In11.Cu")
		(net "M_F_CPU1_SB_DQ<20>")
	)
	(segment
		(start 77.256386 -287.951164)
		(end 76.922122 -287.951164)
		(width 0.0889)
		(layer "In11.Cu")
		(net "M_F_CPU1_SB_DQ<20>")
	)
	(segment
		(start 34.223198 -306.56022)
		(end 34.06013 -306.723288)
		(width 0.14478)
		(layer "In11.Cu")
		(net "M_F_CPU1_SB_DQ<20>")
	)
	(segment
		(start 24.571706 -306.569872)
		(end 24.41829 -306.723288)
		(width 0.14478)
		(layer "In11.Cu")
		(net "M_F_CPU1_SB_DQ<20>")
	)
	(segment
		(start 81.35239 -287.373568)
		(end 81.344008 -287.368742)
		(width 0.0889)
		(layer "In11.Cu")
		(net "M_F_CPU1_SB_DQ<20>")
	)
	(segment
		(start 41.044876 -306.723288)
		(end 40.89146 -306.569872)
		(width 0.14478)
		(layer "In11.Cu")
		(net "M_F_CPU1_SB_DQ<20>")
	)
	(segment
		(start 23.861776 -306.723288)
		(end 23.698708 -306.56022)
		(width 0.14478)
		(layer "In11.Cu")
		(net "M_F_CPU1_SB_DQ<20>")
	)
	(segment
		(start 22.445726 -305.993038)
		(end 22.445726 -306.397152)
		(width 0.14478)
		(layer "In11.Cu")
		(net "M_F_CPU1_SB_DQ<20>")
	)
	(segment
		(start 51.299364 -305.933602)
		(end 51.136296 -306.09667)
		(width 0.14478)
		(layer "In11.Cu")
		(net "M_F_CPU1_SB_DQ<20>")
	)
	(segment
		(start 27.664664 -305.710336)
		(end 26.805128 -306.569872)
		(width 0.14478)
		(layer "In11.Cu")
		(net "M_F_CPU1_SB_DQ<20>")
	)
	(segment
		(start 41.207944 -306.95265)
		(end 41.044876 -306.789582)
		(width 0.14478)
		(layer "In11.Cu")
		(net "M_F_CPU1_SB_DQ<20>")
	)
	(arc
		(start 80.769714 -287.373568)
		(mid 80.586206 -287.419062)
		(end 80.403954 -287.368742)
		(width 0.0889)
		(layer "In11.Cu")
		(net "M_F_CPU1_SB_DQ<20>")
	)
	(arc
		(start 83.223862 -287.368742)
		(mid 82.940906 -287.292599)
		(end 82.65795 -287.368742)
		(width 0.0889)
		(layer "In11.Cu")
		(net "M_F_CPU1_SB_DQ<20>")
	)
	(arc
		(start 80.403954 -287.368742)
		(mid 80.131742 -287.292702)
		(end 79.856838 -287.358328)
		(width 0.0889)
		(layer "In11.Cu")
		(net "M_F_CPU1_SB_DQ<20>")
	)
	(arc
		(start 81.71815 -287.368742)
		(mid 81.535899 -287.419092)
		(end 81.35239 -287.373568)
		(width 0.0889)
		(layer "In11.Cu")
		(net "M_F_CPU1_SB_DQ<20>")
	)
	(arc
		(start 84.163916 -287.368742)
		(mid 83.88096 -287.292599)
		(end 83.598004 -287.368742)
		(width 0.0889)
		(layer "In11.Cu")
		(net "M_F_CPU1_SB_DQ<20>")
	)
	(arc
		(start 82.284062 -287.368742)
		(mid 82.001106 -287.292599)
		(end 81.71815 -287.368742)
		(width 0.0889)
		(layer "In11.Cu")
		(net "M_F_CPU1_SB_DQ<20>")
	)
	(arc
		(start 79.830422 -287.373568)
		(mid 79.647168 -287.418941)
		(end 79.46517 -287.368742)
		(width 0.0889)
		(layer "In11.Cu")
		(net "M_F_CPU1_SB_DQ<20>")
	)
	(arc
		(start 81.344008 -287.368742)
		(mid 81.061052 -287.292599)
		(end 80.778096 -287.368742)
		(width 0.0889)
		(layer "In11.Cu")
		(net "M_F_CPU1_SB_DQ<20>")
	)
	(arc
		(start 84.482686 -287.394904)
		(mid 84.320354 -287.417722)
		(end 84.163916 -287.368742)
		(width 0.0889)
		(layer "In11.Cu")
		(net "M_F_CPU1_SB_DQ<20>")
	)
	(arc
		(start 82.65795 -287.368742)
		(mid 82.471006 -287.418997)
		(end 82.284062 -287.368742)
		(width 0.0889)
		(layer "In11.Cu")
		(net "M_F_CPU1_SB_DQ<20>")
	)
	(arc
		(start 79.447136 -287.358074)
		(mid 79.171441 -287.29226)
		(end 78.898496 -287.368742)
		(width 0.0889)
		(layer "In11.Cu")
		(net "M_F_CPU1_SB_DQ<20>")
	)
	(arc
		(start 78.898496 -287.368742)
		(mid 78.808149 -287.406675)
		(end 78.711044 -287.419796)
		(width 0.0889)
		(layer "In11.Cu")
		(net "M_F_CPU1_SB_DQ<20>")
	)
	(arc
		(start 83.589622 -287.373568)
		(mid 83.406114 -287.419062)
		(end 83.223862 -287.368742)
		(width 0.0889)
		(layer "In11.Cu")
		(net "M_F_CPU1_SB_DQ<20>")
	)
	(segment
		(start 86.22792 -274.630388)
		(end 85.761068 -274.896326)
		(width 0.10668)
		(layer "F.Cu")
		(net "M_F_CPU1_SB_DQ<1>")
	)
	(segment
		(start 66.387218 -275.963888)
		(end 66.387218 -275.568664)
		(width 0.14478)
		(layer "In11.Cu")
		(net "M_F_CPU1_SB_DQ<1>")
	)
	(segment
		(start 63.266066 -278.689816)
		(end 63.458598 -278.497284)
		(width 0.14478)
		(layer "In11.Cu")
		(net "M_F_CPU1_SB_DQ<1>")
	)
	(segment
		(start 78.450186 -275.098764)
		(end 79.488284 -275.098764)
		(width 0.0889)
		(layer "In11.Cu")
		(net "M_F_CPU1_SB_DQ<1>")
	)
	(segment
		(start 60.144914 -281.810968)
		(end 60.337446 -281.618436)
		(width 0.14478)
		(layer "In11.Cu")
		(net "M_F_CPU1_SB_DQ<1>")
	)
	(segment
		(start 64.238886 -277.716996)
		(end 64.63411 -277.716996)
		(width 0.14478)
		(layer "In11.Cu")
		(net "M_F_CPU1_SB_DQ<1>")
	)
	(segment
		(start 60.925202 -281.425904)
		(end 60.925202 -281.03068)
		(width 0.14478)
		(layer "In11.Cu")
		(net "M_F_CPU1_SB_DQ<1>")
	)
	(segment
		(start 59.59094 -282.760166)
		(end 60.144914 -282.206192)
		(width 0.14478)
		(layer "In11.Cu")
		(net "M_F_CPU1_SB_DQ<1>")
	)
	(segment
		(start 63.266066 -279.08504)
		(end 63.266066 -278.689816)
		(width 0.14478)
		(layer "In11.Cu")
		(net "M_F_CPU1_SB_DQ<1>")
	)
	(segment
		(start 22.397212 -283.987748)
		(end 22.741128 -283.987748)
		(width 0.14478)
		(layer "In11.Cu")
		(net "M_F_CPU1_SB_DQ<1>")
	)
	(segment
		(start 23.297388 -283.215588)
		(end 23.460202 -283.378402)
		(width 0.14478)
		(layer "In11.Cu")
		(net "M_F_CPU1_SB_DQ<1>")
	)
	(segment
		(start 63.073534 -279.277572)
		(end 63.266066 -279.08504)
		(width 0.14478)
		(layer "In11.Cu")
		(net "M_F_CPU1_SB_DQ<1>")
	)
	(segment
		(start 60.337446 -281.618436)
		(end 60.73267 -281.618436)
		(width 0.14478)
		(layer "In11.Cu")
		(net "M_F_CPU1_SB_DQ<1>")
	)
	(segment
		(start 21.70811 -283.185362)
		(end 21.70811 -283.298646)
		(width 0.14478)
		(layer "In11.Cu")
		(net "M_F_CPU1_SB_DQ<1>")
	)
	(segment
		(start 31.310326 -283.610304)
		(end 34.226246 -283.610304)
		(width 0.14478)
		(layer "In11.Cu")
		(net "M_F_CPU1_SB_DQ<1>")
	)
	(segment
		(start 23.460202 -283.824934)
		(end 23.623016 -283.987748)
		(width 0.14478)
		(layer "In11.Cu")
		(net "M_F_CPU1_SB_DQ<1>")
	)
	(segment
		(start 82.753962 -275.218906)
		(end 82.762344 -275.223732)
		(width 0.0889)
		(layer "In11.Cu")
		(net "M_F_CPU1_SB_DQ<1>")
	)
	(segment
		(start 49.066958 -283.610304)
		(end 49.917096 -282.760166)
		(width 0.14478)
		(layer "In11.Cu")
		(net "M_F_CPU1_SB_DQ<1>")
	)
	(segment
		(start 53.916326 -283.610304)
		(end 56.45023 -283.610304)
		(width 0.14478)
		(layer "In11.Cu")
		(net "M_F_CPU1_SB_DQ<1>")
	)
	(segment
		(start 22.903942 -283.378402)
		(end 23.066756 -283.215588)
		(width 0.14478)
		(layer "In11.Cu")
		(net "M_F_CPU1_SB_DQ<1>")
	)
	(segment
		(start 85.89264 -275.245068)
		(end 85.914992 -275.161756)
		(width 0.0889)
		(layer "In11.Cu")
		(net "M_F_CPU1_SB_DQ<1>")
	)
	(segment
		(start 22.903942 -283.824934)
		(end 22.903942 -283.378402)
		(width 0.14478)
		(layer "In11.Cu")
		(net "M_F_CPU1_SB_DQ<1>")
	)
	(segment
		(start 25.848056 -283.292804)
		(end 26.086816 -283.292804)
		(width 0.14478)
		(layer "In11.Cu")
		(net "M_F_CPU1_SB_DQ<1>")
	)
	(segment
		(start 64.046354 -278.304752)
		(end 64.046354 -277.909528)
		(width 0.14478)
		(layer "In11.Cu")
		(net "M_F_CPU1_SB_DQ<1>")
	)
	(segment
		(start 22.741128 -283.987748)
		(end 22.903942 -283.824934)
		(width 0.14478)
		(layer "In11.Cu")
		(net "M_F_CPU1_SB_DQ<1>")
	)
	(segment
		(start 65.60693 -276.744176)
		(end 65.60693 -276.348952)
		(width 0.14478)
		(layer "In11.Cu")
		(net "M_F_CPU1_SB_DQ<1>")
	)
	(segment
		(start 65.799462 -276.15642)
		(end 66.194686 -276.15642)
		(width 0.14478)
		(layer "In11.Cu")
		(net "M_F_CPU1_SB_DQ<1>")
	)
	(segment
		(start 62.67831 -279.277572)
		(end 63.073534 -279.277572)
		(width 0.14478)
		(layer "In11.Cu")
		(net "M_F_CPU1_SB_DQ<1>")
	)
	(segment
		(start 66.387218 -275.568664)
		(end 66.57975 -275.376132)
		(width 0.14478)
		(layer "In11.Cu")
		(net "M_F_CPU1_SB_DQ<1>")
	)
	(segment
		(start 24.179276 -283.215588)
		(end 24.409908 -283.215588)
		(width 0.14478)
		(layer "In11.Cu")
		(net "M_F_CPU1_SB_DQ<1>")
	)
	(segment
		(start 68.221352 -274.129754)
		(end 76.234036 -274.129754)
		(width 0.14478)
		(layer "In11.Cu")
		(net "M_F_CPU1_SB_DQ<1>")
	)
	(segment
		(start 76.234036 -274.129754)
		(end 76.331826 -274.031964)
		(width 0.0889)
		(layer "In11.Cu")
		(net "M_F_CPU1_SB_DQ<1>")
	)
	(segment
		(start 28.076906 -282.495244)
		(end 28.368244 -282.495244)
		(width 0.14478)
		(layer "In11.Cu")
		(net "M_F_CPU1_SB_DQ<1>")
	)
	(segment
		(start 23.460202 -283.378402)
		(end 23.460202 -283.824934)
		(width 0.14478)
		(layer "In11.Cu")
		(net "M_F_CPU1_SB_DQ<1>")
	)
	(segment
		(start 30.460188 -282.760166)
		(end 31.310326 -283.610304)
		(width 0.14478)
		(layer "In11.Cu")
		(net "M_F_CPU1_SB_DQ<1>")
	)
	(segment
		(start 62.485778 -279.470104)
		(end 62.67831 -279.277572)
		(width 0.14478)
		(layer "In11.Cu")
		(net "M_F_CPU1_SB_DQ<1>")
	)
	(segment
		(start 45.573188 -282.760166)
		(end 46.423326 -283.610304)
		(width 0.14478)
		(layer "In11.Cu")
		(net "M_F_CPU1_SB_DQ<1>")
	)
	(segment
		(start 23.066756 -283.215588)
		(end 23.297388 -283.215588)
		(width 0.14478)
		(layer "In11.Cu")
		(net "M_F_CPU1_SB_DQ<1>")
	)
	(segment
		(start 62.293246 -280.05786)
		(end 62.485778 -279.865328)
		(width 0.14478)
		(layer "In11.Cu")
		(net "M_F_CPU1_SB_DQ<1>")
	)
	(segment
		(start 26.961846 -283.610304)
		(end 28.076906 -282.495244)
		(width 0.14478)
		(layer "In11.Cu")
		(net "M_F_CPU1_SB_DQ<1>")
	)
	(segment
		(start 77.383386 -274.031964)
		(end 78.450186 -275.098764)
		(width 0.0889)
		(layer "In11.Cu")
		(net "M_F_CPU1_SB_DQ<1>")
	)
	(segment
		(start 38.803326 -283.610304)
		(end 41.973246 -283.610304)
		(width 0.14478)
		(layer "In11.Cu")
		(net "M_F_CPU1_SB_DQ<1>")
	)
	(segment
		(start 37.953188 -282.760166)
		(end 38.803326 -283.610304)
		(width 0.14478)
		(layer "In11.Cu")
		(net "M_F_CPU1_SB_DQ<1>")
	)
	(segment
		(start 21.70811 -283.298646)
		(end 22.397212 -283.987748)
		(width 0.14478)
		(layer "In11.Cu")
		(net "M_F_CPU1_SB_DQ<1>")
	)
	(segment
		(start 56.45023 -283.610304)
		(end 57.300368 -282.760166)
		(width 0.14478)
		(layer "In11.Cu")
		(net "M_F_CPU1_SB_DQ<1>")
	)
	(segment
		(start 63.853822 -278.497284)
		(end 64.046354 -278.304752)
		(width 0.14478)
		(layer "In11.Cu")
		(net "M_F_CPU1_SB_DQ<1>")
	)
	(segment
		(start 24.016462 -283.824934)
		(end 24.016462 -283.378402)
		(width 0.14478)
		(layer "In11.Cu")
		(net "M_F_CPU1_SB_DQ<1>")
	)
	(segment
		(start 65.60693 -276.348952)
		(end 65.799462 -276.15642)
		(width 0.14478)
		(layer "In11.Cu")
		(net "M_F_CPU1_SB_DQ<1>")
	)
	(segment
		(start 61.898022 -280.05786)
		(end 62.293246 -280.05786)
		(width 0.14478)
		(layer "In11.Cu")
		(net "M_F_CPU1_SB_DQ<1>")
	)
	(segment
		(start 53.066188 -282.760166)
		(end 53.916326 -283.610304)
		(width 0.14478)
		(layer "In11.Cu")
		(net "M_F_CPU1_SB_DQ<1>")
	)
	(segment
		(start 67.167506 -274.788376)
		(end 67.360038 -274.595844)
		(width 0.14478)
		(layer "In11.Cu")
		(net "M_F_CPU1_SB_DQ<1>")
	)
	(segment
		(start 26.404316 -283.610304)
		(end 26.961846 -283.610304)
		(width 0.14478)
		(layer "In11.Cu")
		(net "M_F_CPU1_SB_DQ<1>")
	)
	(segment
		(start 64.046354 -277.909528)
		(end 64.238886 -277.716996)
		(width 0.14478)
		(layer "In11.Cu")
		(net "M_F_CPU1_SB_DQ<1>")
	)
	(segment
		(start 24.409908 -283.215588)
		(end 24.804624 -283.610304)
		(width 0.14478)
		(layer "In11.Cu")
		(net "M_F_CPU1_SB_DQ<1>")
	)
	(segment
		(start 67.755262 -274.595844)
		(end 68.221352 -274.129754)
		(width 0.14478)
		(layer "In11.Cu")
		(net "M_F_CPU1_SB_DQ<1>")
	)
	(segment
		(start 65.019174 -276.936708)
		(end 65.414398 -276.936708)
		(width 0.14478)
		(layer "In11.Cu")
		(net "M_F_CPU1_SB_DQ<1>")
	)
	(segment
		(start 66.974974 -275.376132)
		(end 67.167506 -275.1836)
		(width 0.14478)
		(layer "In11.Cu")
		(net "M_F_CPU1_SB_DQ<1>")
	)
	(segment
		(start 23.623016 -283.987748)
		(end 23.853648 -283.987748)
		(width 0.14478)
		(layer "In11.Cu")
		(net "M_F_CPU1_SB_DQ<1>")
	)
	(segment
		(start 64.826642 -277.12924)
		(end 65.019174 -276.936708)
		(width 0.14478)
		(layer "In11.Cu")
		(net "M_F_CPU1_SB_DQ<1>")
	)
	(segment
		(start 83.694016 -275.218906)
		(end 83.702398 -275.223732)
		(width 0.0889)
		(layer "In11.Cu")
		(net "M_F_CPU1_SB_DQ<1>")
	)
	(segment
		(start 34.226246 -283.610304)
		(end 35.076384 -282.760166)
		(width 0.14478)
		(layer "In11.Cu")
		(net "M_F_CPU1_SB_DQ<1>")
	)
	(segment
		(start 35.076384 -282.760166)
		(end 37.953188 -282.760166)
		(width 0.14478)
		(layer "In11.Cu")
		(net "M_F_CPU1_SB_DQ<1>")
	)
	(segment
		(start 64.63411 -277.716996)
		(end 64.826642 -277.524464)
		(width 0.14478)
		(layer "In11.Cu")
		(net "M_F_CPU1_SB_DQ<1>")
	)
	(segment
		(start 63.458598 -278.497284)
		(end 63.853822 -278.497284)
		(width 0.14478)
		(layer "In11.Cu")
		(net "M_F_CPU1_SB_DQ<1>")
	)
	(segment
		(start 24.016462 -283.378402)
		(end 24.179276 -283.215588)
		(width 0.14478)
		(layer "In11.Cu")
		(net "M_F_CPU1_SB_DQ<1>")
	)
	(segment
		(start 28.368244 -282.495244)
		(end 28.633166 -282.760166)
		(width 0.14478)
		(layer "In11.Cu")
		(net "M_F_CPU1_SB_DQ<1>")
	)
	(segment
		(start 60.73267 -281.618436)
		(end 60.925202 -281.425904)
		(width 0.14478)
		(layer "In11.Cu")
		(net "M_F_CPU1_SB_DQ<1>")
	)
	(segment
		(start 25.530556 -283.610304)
		(end 25.848056 -283.292804)
		(width 0.14478)
		(layer "In11.Cu")
		(net "M_F_CPU1_SB_DQ<1>")
	)
	(segment
		(start 61.512958 -280.838148)
		(end 61.70549 -280.645616)
		(width 0.14478)
		(layer "In11.Cu")
		(net "M_F_CPU1_SB_DQ<1>")
	)
	(segment
		(start 67.167506 -275.1836)
		(end 67.167506 -274.788376)
		(width 0.14478)
		(layer "In11.Cu")
		(net "M_F_CPU1_SB_DQ<1>")
	)
	(segment
		(start 24.804624 -283.610304)
		(end 25.530556 -283.610304)
		(width 0.14478)
		(layer "In11.Cu")
		(net "M_F_CPU1_SB_DQ<1>")
	)
	(segment
		(start 57.300368 -282.760166)
		(end 59.59094 -282.760166)
		(width 0.14478)
		(layer "In11.Cu")
		(net "M_F_CPU1_SB_DQ<1>")
	)
	(segment
		(start 42.823384 -282.760166)
		(end 45.573188 -282.760166)
		(width 0.14478)
		(layer "In11.Cu")
		(net "M_F_CPU1_SB_DQ<1>")
	)
	(segment
		(start 76.331826 -274.031964)
		(end 77.383386 -274.031964)
		(width 0.0889)
		(layer "In11.Cu")
		(net "M_F_CPU1_SB_DQ<1>")
	)
	(segment
		(start 61.70549 -280.250392)
		(end 61.898022 -280.05786)
		(width 0.14478)
		(layer "In11.Cu")
		(net "M_F_CPU1_SB_DQ<1>")
	)
	(segment
		(start 41.973246 -283.610304)
		(end 42.823384 -282.760166)
		(width 0.14478)
		(layer "In11.Cu")
		(net "M_F_CPU1_SB_DQ<1>")
	)
	(segment
		(start 23.853648 -283.987748)
		(end 24.016462 -283.824934)
		(width 0.14478)
		(layer "In11.Cu")
		(net "M_F_CPU1_SB_DQ<1>")
	)
	(segment
		(start 67.360038 -274.595844)
		(end 67.755262 -274.595844)
		(width 0.14478)
		(layer "In11.Cu")
		(net "M_F_CPU1_SB_DQ<1>")
	)
	(segment
		(start 60.144914 -282.206192)
		(end 60.144914 -281.810968)
		(width 0.14478)
		(layer "In11.Cu")
		(net "M_F_CPU1_SB_DQ<1>")
	)
	(segment
		(start 26.086816 -283.292804)
		(end 26.404316 -283.610304)
		(width 0.14478)
		(layer "In11.Cu")
		(net "M_F_CPU1_SB_DQ<1>")
	)
	(segment
		(start 64.826642 -277.524464)
		(end 64.826642 -277.12924)
		(width 0.14478)
		(layer "In11.Cu")
		(net "M_F_CPU1_SB_DQ<1>")
	)
	(segment
		(start 61.117734 -280.838148)
		(end 61.512958 -280.838148)
		(width 0.14478)
		(layer "In11.Cu")
		(net "M_F_CPU1_SB_DQ<1>")
	)
	(segment
		(start 28.633166 -282.760166)
		(end 30.460188 -282.760166)
		(width 0.14478)
		(layer "In11.Cu")
		(net "M_F_CPU1_SB_DQ<1>")
	)
	(segment
		(start 65.414398 -276.936708)
		(end 65.60693 -276.744176)
		(width 0.14478)
		(layer "In11.Cu")
		(net "M_F_CPU1_SB_DQ<1>")
	)
	(segment
		(start 49.917096 -282.760166)
		(end 53.066188 -282.760166)
		(width 0.14478)
		(layer "In11.Cu")
		(net "M_F_CPU1_SB_DQ<1>")
	)
	(segment
		(start 62.485778 -279.865328)
		(end 62.485778 -279.470104)
		(width 0.14478)
		(layer "In11.Cu")
		(net "M_F_CPU1_SB_DQ<1>")
	)
	(segment
		(start 66.57975 -275.376132)
		(end 66.974974 -275.376132)
		(width 0.14478)
		(layer "In11.Cu")
		(net "M_F_CPU1_SB_DQ<1>")
	)
	(segment
		(start 46.423326 -283.610304)
		(end 49.066958 -283.610304)
		(width 0.14478)
		(layer "In11.Cu")
		(net "M_F_CPU1_SB_DQ<1>")
	)
	(segment
		(start 66.194686 -276.15642)
		(end 66.387218 -275.963888)
		(width 0.14478)
		(layer "In11.Cu")
		(net "M_F_CPU1_SB_DQ<1>")
	)
	(segment
		(start 60.925202 -281.03068)
		(end 61.117734 -280.838148)
		(width 0.14478)
		(layer "In11.Cu")
		(net "M_F_CPU1_SB_DQ<1>")
	)
	(segment
		(start 82.179668 -275.223732)
		(end 82.18805 -275.218906)
		(width 0.0889)
		(layer "In11.Cu")
		(net "M_F_CPU1_SB_DQ<1>")
	)
	(segment
		(start 61.70549 -280.645616)
		(end 61.70549 -280.250392)
		(width 0.14478)
		(layer "In11.Cu")
		(net "M_F_CPU1_SB_DQ<1>")
	)
	(segment
		(start 85.914992 -275.161756)
		(end 85.761068 -274.896326)
		(width 0.0889)
		(layer "In11.Cu")
		(net "M_F_CPU1_SB_DQ<1>")
	)
	(arc
		(start 80.874108 -275.218906)
		(mid 81.061052 -275.269161)
		(end 81.247996 -275.218906)
		(width 0.0889)
		(layer "In11.Cu")
		(net "M_F_CPU1_SB_DQ<1>")
	)
	(arc
		(start 85.007958 -275.218906)
		(mid 85.290914 -275.142729)
		(end 85.57387 -275.218906)
		(width 0.0889)
		(layer "In11.Cu")
		(net "M_F_CPU1_SB_DQ<1>")
	)
	(arc
		(start 79.488284 -275.098764)
		(mid 79.718997 -275.129332)
		(end 79.9338 -275.218906)
		(width 0.0889)
		(layer "In11.Cu")
		(net "M_F_CPU1_SB_DQ<1>")
	)
	(arc
		(start 79.9338 -275.218906)
		(mid 80.120998 -275.269288)
		(end 80.308196 -275.218906)
		(width 0.0889)
		(layer "In11.Cu")
		(net "M_F_CPU1_SB_DQ<1>")
	)
	(arc
		(start 81.247996 -275.218906)
		(mid 81.530952 -275.142729)
		(end 81.813908 -275.218906)
		(width 0.0889)
		(layer "In11.Cu")
		(net "M_F_CPU1_SB_DQ<1>")
	)
	(arc
		(start 84.068158 -275.218906)
		(mid 84.351114 -275.142729)
		(end 84.63407 -275.218906)
		(width 0.0889)
		(layer "In11.Cu")
		(net "M_F_CPU1_SB_DQ<1>")
	)
	(arc
		(start 82.762344 -275.223732)
		(mid 82.945852 -275.269226)
		(end 83.128104 -275.218906)
		(width 0.0889)
		(layer "In11.Cu")
		(net "M_F_CPU1_SB_DQ<1>")
	)
	(arc
		(start 81.813908 -275.218906)
		(mid 81.996159 -275.269256)
		(end 82.179668 -275.223732)
		(width 0.0889)
		(layer "In11.Cu")
		(net "M_F_CPU1_SB_DQ<1>")
	)
	(arc
		(start 80.308196 -275.218906)
		(mid 80.591152 -275.142729)
		(end 80.874108 -275.218906)
		(width 0.0889)
		(layer "In11.Cu")
		(net "M_F_CPU1_SB_DQ<1>")
	)
	(arc
		(start 85.57387 -275.218906)
		(mid 85.730308 -275.267877)
		(end 85.89264 -275.245068)
		(width 0.0889)
		(layer "In11.Cu")
		(net "M_F_CPU1_SB_DQ<1>")
	)
	(arc
		(start 84.63407 -275.218906)
		(mid 84.821014 -275.269161)
		(end 85.007958 -275.218906)
		(width 0.0889)
		(layer "In11.Cu")
		(net "M_F_CPU1_SB_DQ<1>")
	)
	(arc
		(start 82.18805 -275.218906)
		(mid 82.471006 -275.142729)
		(end 82.753962 -275.218906)
		(width 0.0889)
		(layer "In11.Cu")
		(net "M_F_CPU1_SB_DQ<1>")
	)
	(arc
		(start 83.702398 -275.223732)
		(mid 83.885906 -275.269226)
		(end 84.068158 -275.218906)
		(width 0.0889)
		(layer "In11.Cu")
		(net "M_F_CPU1_SB_DQ<1>")
	)
	(arc
		(start 83.128104 -275.218906)
		(mid 83.41106 -275.142729)
		(end 83.694016 -275.218906)
		(width 0.0889)
		(layer "In11.Cu")
		(net "M_F_CPU1_SB_DQ<1>")
	)
	(segment
		(start 86.69782 -285.160466)
		(end 86.230968 -285.426404)
		(width 0.10668)
		(layer "F.Cu")
		(net "M_F_CPU1_SB_DQ<19>")
	)
	(segment
		(start 58.882788 -302.023272)
		(end 58.621168 -302.023272)
		(width 0.14478)
		(layer "In11.Cu")
		(net "M_F_CPU1_SB_DQ<19>")
	)
	(segment
		(start 38.95344 -303.150524)
		(end 38.103556 -302.30064)
		(width 0.14478)
		(layer "In11.Cu")
		(net "M_F_CPU1_SB_DQ<19>")
	)
	(segment
		(start 58.476388 -301.595282)
		(end 58.331608 -301.450502)
		(width 0.14478)
		(layer "In11.Cu")
		(net "M_F_CPU1_SB_DQ<19>")
	)
	(segment
		(start 84.538058 -285.103824)
		(end 84.529676 -285.098998)
		(width 0.0889)
		(layer "In11.Cu")
		(net "M_F_CPU1_SB_DQ<19>")
	)
	(segment
		(start 86.077044 -285.160974)
		(end 85.981032 -285.135574)
		(width 0.0889)
		(layer "In11.Cu")
		(net "M_F_CPU1_SB_DQ<19>")
	)
	(segment
		(start 26.809192 -303.150524)
		(end 19.378422 -303.150524)
		(width 0.14478)
		(layer "In11.Cu")
		(net "M_F_CPU1_SB_DQ<19>")
	)
	(segment
		(start 78.897988 -285.103824)
		(end 78.889606 -285.098998)
		(width 0.0889)
		(layer "In11.Cu")
		(net "M_F_CPU1_SB_DQ<19>")
	)
	(segment
		(start 46.458886 -303.150524)
		(end 45.609002 -302.30064)
		(width 0.14478)
		(layer "In11.Cu")
		(net "M_F_CPU1_SB_DQ<19>")
	)
	(segment
		(start 53.145436 -302.30064)
		(end 50.249582 -302.30064)
		(width 0.14478)
		(layer "In11.Cu")
		(net "M_F_CPU1_SB_DQ<19>")
	)
	(segment
		(start 19.22526 -302.630078)
		(end 19.062192 -302.46701)
		(width 0.14478)
		(layer "In11.Cu")
		(net "M_F_CPU1_SB_DQ<19>")
	)
	(segment
		(start 59.172348 -301.450502)
		(end 59.027568 -301.595282)
		(width 0.14478)
		(layer "In11.Cu")
		(net "M_F_CPU1_SB_DQ<19>")
	)
	(segment
		(start 30.534102 -302.30064)
		(end 27.659076 -302.30064)
		(width 0.14478)
		(layer "In11.Cu")
		(net "M_F_CPU1_SB_DQ<19>")
	)
	(segment
		(start 53.609748 -302.764952)
		(end 53.145436 -302.30064)
		(width 0.14478)
		(layer "In11.Cu")
		(net "M_F_CPU1_SB_DQ<19>")
	)
	(segment
		(start 77.527404 -285.580074)
		(end 76.92517 -285.580074)
		(width 0.0889)
		(layer "In11.Cu")
		(net "M_F_CPU1_SB_DQ<19>")
	)
	(segment
		(start 76.92517 -285.580074)
		(end 76.67371 -285.831534)
		(width 0.0889)
		(layer "In11.Cu")
		(net "M_F_CPU1_SB_DQ<19>")
	)
	(segment
		(start 41.901872 -303.150524)
		(end 38.95344 -303.150524)
		(width 0.14478)
		(layer "In11.Cu")
		(net "M_F_CPU1_SB_DQ<19>")
	)
	(segment
		(start 49.399698 -303.150524)
		(end 46.458886 -303.150524)
		(width 0.14478)
		(layer "In11.Cu")
		(net "M_F_CPU1_SB_DQ<19>")
	)
	(segment
		(start 34.368486 -303.150524)
		(end 31.383986 -303.150524)
		(width 0.14478)
		(layer "In11.Cu")
		(net "M_F_CPU1_SB_DQ<19>")
	)
	(segment
		(start 80.403954 -285.103824)
		(end 80.39354 -285.10992)
		(width 0.0889)
		(layer "In11.Cu")
		(net "M_F_CPU1_SB_DQ<19>")
	)
	(segment
		(start 72.311768 -288.507678)
		(end 59.843416 -300.97603)
		(width 0.14478)
		(layer "In11.Cu")
		(net "M_F_CPU1_SB_DQ<19>")
	)
	(segment
		(start 19.062192 -302.46701)
		(end 18.831814 -302.46701)
		(width 0.14478)
		(layer "In11.Cu")
		(net "M_F_CPU1_SB_DQ<19>")
	)
	(segment
		(start 42.751756 -302.30064)
		(end 41.901872 -303.150524)
		(width 0.14478)
		(layer "In11.Cu")
		(net "M_F_CPU1_SB_DQ<19>")
	)
	(segment
		(start 83.598004 -285.103824)
		(end 83.589622 -285.098998)
		(width 0.0889)
		(layer "In11.Cu")
		(net "M_F_CPU1_SB_DQ<19>")
	)
	(segment
		(start 58.476388 -301.878492)
		(end 58.476388 -301.595282)
		(width 0.14478)
		(layer "In11.Cu")
		(net "M_F_CPU1_SB_DQ<19>")
	)
	(segment
		(start 35.21837 -302.30064)
		(end 34.368486 -303.150524)
		(width 0.14478)
		(layer "In11.Cu")
		(net "M_F_CPU1_SB_DQ<19>")
	)
	(segment
		(start 78.908402 -285.10992)
		(end 78.897988 -285.103824)
		(width 0.0889)
		(layer "In11.Cu")
		(net "M_F_CPU1_SB_DQ<19>")
	)
	(segment
		(start 81.35239 -285.098998)
		(end 81.344008 -285.103824)
		(width 0.0889)
		(layer "In11.Cu")
		(net "M_F_CPU1_SB_DQ<19>")
	)
	(segment
		(start 73.121012 -288.507678)
		(end 72.311768 -288.507678)
		(width 0.14478)
		(layer "In11.Cu")
		(net "M_F_CPU1_SB_DQ<19>")
	)
	(segment
		(start 31.383986 -303.150524)
		(end 30.534102 -302.30064)
		(width 0.14478)
		(layer "In11.Cu")
		(net "M_F_CPU1_SB_DQ<19>")
	)
	(segment
		(start 19.22526 -302.997362)
		(end 19.22526 -302.630078)
		(width 0.14478)
		(layer "In11.Cu")
		(net "M_F_CPU1_SB_DQ<19>")
	)
	(segment
		(start 18.668746 -302.997362)
		(end 18.505678 -303.16043)
		(width 0.14478)
		(layer "In11.Cu")
		(net "M_F_CPU1_SB_DQ<19>")
	)
	(segment
		(start 59.632596 -301.450502)
		(end 59.172348 -301.450502)
		(width 0.14478)
		(layer "In11.Cu")
		(net "M_F_CPU1_SB_DQ<19>")
	)
	(segment
		(start 59.843416 -301.239682)
		(end 59.632596 -301.450502)
		(width 0.14478)
		(layer "In11.Cu")
		(net "M_F_CPU1_SB_DQ<19>")
	)
	(segment
		(start 79.472028 -285.098998)
		(end 79.463646 -285.103824)
		(width 0.0889)
		(layer "In11.Cu")
		(net "M_F_CPU1_SB_DQ<19>")
	)
	(segment
		(start 45.609002 -302.30064)
		(end 42.751756 -302.30064)
		(width 0.14478)
		(layer "In11.Cu")
		(net "M_F_CPU1_SB_DQ<19>")
	)
	(segment
		(start 27.659076 -302.30064)
		(end 26.809192 -303.150524)
		(width 0.14478)
		(layer "In11.Cu")
		(net "M_F_CPU1_SB_DQ<19>")
	)
	(segment
		(start 59.843416 -300.97603)
		(end 59.843416 -301.239682)
		(width 0.14478)
		(layer "In11.Cu")
		(net "M_F_CPU1_SB_DQ<19>")
	)
	(segment
		(start 18.033238 -303.16043)
		(end 17.608042 -302.735234)
		(width 0.14478)
		(layer "In11.Cu")
		(net "M_F_CPU1_SB_DQ<19>")
	)
	(segment
		(start 85.112352 -285.098998)
		(end 85.10397 -285.103824)
		(width 0.0889)
		(layer "In11.Cu")
		(net "M_F_CPU1_SB_DQ<19>")
	)
	(segment
		(start 18.831814 -302.46701)
		(end 18.668746 -302.630078)
		(width 0.14478)
		(layer "In11.Cu")
		(net "M_F_CPU1_SB_DQ<19>")
	)
	(segment
		(start 59.027568 -301.595282)
		(end 59.027568 -301.878492)
		(width 0.14478)
		(layer "In11.Cu")
		(net "M_F_CPU1_SB_DQ<19>")
	)
	(segment
		(start 18.505678 -303.16043)
		(end 18.033238 -303.16043)
		(width 0.14478)
		(layer "In11.Cu")
		(net "M_F_CPU1_SB_DQ<19>")
	)
	(segment
		(start 80.778096 -285.103824)
		(end 80.769714 -285.098998)
		(width 0.0889)
		(layer "In11.Cu")
		(net "M_F_CPU1_SB_DQ<19>")
	)
	(segment
		(start 58.331608 -301.450502)
		(end 58.048906 -301.450502)
		(width 0.14478)
		(layer "In11.Cu")
		(net "M_F_CPU1_SB_DQ<19>")
	)
	(segment
		(start 76.67371 -285.831534)
		(end 75.921616 -285.831534)
		(width 0.0889)
		(layer "In11.Cu")
		(net "M_F_CPU1_SB_DQ<19>")
	)
	(segment
		(start 59.027568 -301.878492)
		(end 58.882788 -302.023272)
		(width 0.14478)
		(layer "In11.Cu")
		(net "M_F_CPU1_SB_DQ<19>")
	)
	(segment
		(start 58.048906 -301.450502)
		(end 56.734456 -302.764952)
		(width 0.14478)
		(layer "In11.Cu")
		(net "M_F_CPU1_SB_DQ<19>")
	)
	(segment
		(start 18.668746 -302.630078)
		(end 18.668746 -302.997362)
		(width 0.14478)
		(layer "In11.Cu")
		(net "M_F_CPU1_SB_DQ<19>")
	)
	(segment
		(start 75.921616 -285.831534)
		(end 75.797156 -285.831534)
		(width 0.14478)
		(layer "In11.Cu")
		(net "M_F_CPU1_SB_DQ<19>")
	)
	(segment
		(start 56.734456 -302.764952)
		(end 53.609748 -302.764952)
		(width 0.14478)
		(layer "In11.Cu")
		(net "M_F_CPU1_SB_DQ<19>")
	)
	(segment
		(start 78.24089 -285.180024)
		(end 77.927454 -285.180024)
		(width 0.0889)
		(layer "In11.Cu")
		(net "M_F_CPU1_SB_DQ<19>")
	)
	(segment
		(start 75.797156 -285.831534)
		(end 73.121012 -288.507678)
		(width 0.14478)
		(layer "In11.Cu")
		(net "M_F_CPU1_SB_DQ<19>")
	)
	(segment
		(start 38.103556 -302.30064)
		(end 35.21837 -302.30064)
		(width 0.14478)
		(layer "In11.Cu")
		(net "M_F_CPU1_SB_DQ<19>")
	)
	(segment
		(start 58.621168 -302.023272)
		(end 58.476388 -301.878492)
		(width 0.14478)
		(layer "In11.Cu")
		(net "M_F_CPU1_SB_DQ<19>")
	)
	(segment
		(start 19.378422 -303.150524)
		(end 19.22526 -302.997362)
		(width 0.14478)
		(layer "In11.Cu")
		(net "M_F_CPU1_SB_DQ<19>")
	)
	(segment
		(start 86.230968 -285.426404)
		(end 86.077044 -285.160974)
		(width 0.0889)
		(layer "In11.Cu")
		(net "M_F_CPU1_SB_DQ<19>")
	)
	(segment
		(start 77.927454 -285.180024)
		(end 77.527404 -285.580074)
		(width 0.0889)
		(layer "In11.Cu")
		(net "M_F_CPU1_SB_DQ<19>")
	)
	(segment
		(start 50.249582 -302.30064)
		(end 49.399698 -303.150524)
		(width 0.14478)
		(layer "In11.Cu")
		(net "M_F_CPU1_SB_DQ<19>")
	)
	(arc
		(start 84.163916 -285.103824)
		(mid 83.88096 -285.180001)
		(end 83.598004 -285.103824)
		(width 0.0889)
		(layer "In11.Cu")
		(net "M_F_CPU1_SB_DQ<19>")
	)
	(arc
		(start 79.837788 -285.103824)
		(mid 79.655537 -285.053474)
		(end 79.472028 -285.098998)
		(width 0.0889)
		(layer "In11.Cu")
		(net "M_F_CPU1_SB_DQ<19>")
	)
	(arc
		(start 85.478112 -285.103824)
		(mid 85.295861 -285.053474)
		(end 85.112352 -285.098998)
		(width 0.0889)
		(layer "In11.Cu")
		(net "M_F_CPU1_SB_DQ<19>")
	)
	(arc
		(start 85.10397 -285.103824)
		(mid 84.821014 -285.180001)
		(end 84.538058 -285.103824)
		(width 0.0889)
		(layer "In11.Cu")
		(net "M_F_CPU1_SB_DQ<19>")
	)
	(arc
		(start 78.523846 -285.103824)
		(mid 78.387401 -285.160598)
		(end 78.24089 -285.180024)
		(width 0.0889)
		(layer "In11.Cu")
		(net "M_F_CPU1_SB_DQ<19>")
	)
	(arc
		(start 78.889606 -285.098998)
		(mid 78.706098 -285.053504)
		(end 78.523846 -285.103824)
		(width 0.0889)
		(layer "In11.Cu")
		(net "M_F_CPU1_SB_DQ<19>")
	)
	(arc
		(start 82.284062 -285.103824)
		(mid 82.001106 -285.180001)
		(end 81.71815 -285.103824)
		(width 0.0889)
		(layer "In11.Cu")
		(net "M_F_CPU1_SB_DQ<19>")
	)
	(arc
		(start 85.981032 -285.135574)
		(mid 85.725824 -285.179051)
		(end 85.478112 -285.103824)
		(width 0.0889)
		(layer "In11.Cu")
		(net "M_F_CPU1_SB_DQ<19>")
	)
	(arc
		(start 80.39354 -285.10992)
		(mid 80.114854 -285.18014)
		(end 79.837788 -285.103824)
		(width 0.0889)
		(layer "In11.Cu")
		(net "M_F_CPU1_SB_DQ<19>")
	)
	(arc
		(start 81.344008 -285.103824)
		(mid 81.061052 -285.180001)
		(end 80.778096 -285.103824)
		(width 0.0889)
		(layer "In11.Cu")
		(net "M_F_CPU1_SB_DQ<19>")
	)
	(arc
		(start 81.71815 -285.103824)
		(mid 81.535899 -285.053474)
		(end 81.35239 -285.098998)
		(width 0.0889)
		(layer "In11.Cu")
		(net "M_F_CPU1_SB_DQ<19>")
	)
	(arc
		(start 83.223862 -285.103824)
		(mid 82.940906 -285.180001)
		(end 82.65795 -285.103824)
		(width 0.0889)
		(layer "In11.Cu")
		(net "M_F_CPU1_SB_DQ<19>")
	)
	(arc
		(start 79.463646 -285.103824)
		(mid 79.186833 -285.179967)
		(end 78.908402 -285.10992)
		(width 0.0889)
		(layer "In11.Cu")
		(net "M_F_CPU1_SB_DQ<19>")
	)
	(arc
		(start 80.769714 -285.098998)
		(mid 80.586206 -285.053504)
		(end 80.403954 -285.103824)
		(width 0.0889)
		(layer "In11.Cu")
		(net "M_F_CPU1_SB_DQ<19>")
	)
	(arc
		(start 83.589622 -285.098998)
		(mid 83.406114 -285.053504)
		(end 83.223862 -285.103824)
		(width 0.0889)
		(layer "In11.Cu")
		(net "M_F_CPU1_SB_DQ<19>")
	)
	(arc
		(start 84.529676 -285.098998)
		(mid 84.346168 -285.053504)
		(end 84.163916 -285.103824)
		(width 0.0889)
		(layer "In11.Cu")
		(net "M_F_CPU1_SB_DQ<19>")
	)
	(arc
		(start 82.65795 -285.103824)
		(mid 82.471006 -285.053569)
		(end 82.284062 -285.103824)
		(width 0.0889)
		(layer "In11.Cu")
		(net "M_F_CPU1_SB_DQ<19>")
	)
	(segment
		(start 85.287866 -284.35046)
		(end 84.821014 -284.616398)
		(width 0.10668)
		(layer "F.Cu")
		(net "M_F_CPU1_SB_DQ<18>")
	)
	(segment
		(start 18.033238 -301.460408)
		(end 17.608042 -301.035212)
		(width 0.14478)
		(layer "In11.Cu")
		(net "M_F_CPU1_SB_DQ<18>")
	)
	(segment
		(start 46.151292 -300.61027)
		(end 42.52468 -300.61027)
		(width 0.14478)
		(layer "In11.Cu")
		(net "M_F_CPU1_SB_DQ<18>")
	)
	(segment
		(start 30.123892 -300.61027)
		(end 27.84348 -300.61027)
		(width 0.14478)
		(layer "In11.Cu")
		(net "M_F_CPU1_SB_DQ<18>")
	)
	(segment
		(start 19.810476 -301.85741)
		(end 19.810476 -301.063406)
		(width 0.14478)
		(layer "In11.Cu")
		(net "M_F_CPU1_SB_DQ<18>")
	)
	(segment
		(start 20.36191 -301.063406)
		(end 20.36191 -301.85741)
		(width 0.14478)
		(layer "In11.Cu")
		(net "M_F_CPU1_SB_DQ<18>")
	)
	(segment
		(start 77.24394 -284.922214)
		(end 75.880976 -284.922214)
		(width 0.0889)
		(layer "In11.Cu")
		(net "M_F_CPU1_SB_DQ<18>")
	)
	(segment
		(start 20.768564 -300.918626)
		(end 20.50669 -300.918626)
		(width 0.14478)
		(layer "In11.Cu")
		(net "M_F_CPU1_SB_DQ<18>")
	)
	(segment
		(start 27.84348 -300.61027)
		(end 26.993342 -301.460408)
		(width 0.14478)
		(layer "In11.Cu")
		(net "M_F_CPU1_SB_DQ<18>")
	)
	(segment
		(start 56.766714 -301.460408)
		(end 54.26583 -301.460408)
		(width 0.14478)
		(layer "In11.Cu")
		(net "M_F_CPU1_SB_DQ<18>")
	)
	(segment
		(start 53.415692 -300.61027)
		(end 50.284888 -300.61027)
		(width 0.14478)
		(layer "In11.Cu")
		(net "M_F_CPU1_SB_DQ<18>")
	)
	(segment
		(start 34.562542 -301.460408)
		(end 30.97403 -301.460408)
		(width 0.14478)
		(layer "In11.Cu")
		(net "M_F_CPU1_SB_DQ<18>")
	)
	(segment
		(start 79.950564 -284.284674)
		(end 79.934308 -284.294072)
		(width 0.0889)
		(layer "In11.Cu")
		(net "M_F_CPU1_SB_DQ<18>")
	)
	(segment
		(start 26.993342 -301.460408)
		(end 21.058124 -301.460408)
		(width 0.14478)
		(layer "In11.Cu")
		(net "M_F_CPU1_SB_DQ<18>")
	)
	(segment
		(start 20.21713 -302.00219)
		(end 19.955256 -302.00219)
		(width 0.14478)
		(layer "In11.Cu")
		(net "M_F_CPU1_SB_DQ<18>")
	)
	(segment
		(start 20.913344 -301.315628)
		(end 20.913344 -301.063406)
		(width 0.14478)
		(layer "In11.Cu")
		(net "M_F_CPU1_SB_DQ<18>")
	)
	(segment
		(start 19.259042 -301.063406)
		(end 19.259042 -301.85741)
		(width 0.14478)
		(layer "In11.Cu")
		(net "M_F_CPU1_SB_DQ<18>")
	)
	(segment
		(start 18.562828 -301.460408)
		(end 18.033238 -301.460408)
		(width 0.14478)
		(layer "In11.Cu")
		(net "M_F_CPU1_SB_DQ<18>")
	)
	(segment
		(start 50.284888 -300.61027)
		(end 49.43475 -301.460408)
		(width 0.14478)
		(layer "In11.Cu")
		(net "M_F_CPU1_SB_DQ<18>")
	)
	(segment
		(start 84.66709 -284.350968)
		(end 84.571078 -284.325568)
		(width 0.0889)
		(layer "In11.Cu")
		(net "M_F_CPU1_SB_DQ<18>")
	)
	(segment
		(start 77.545946 -284.620208)
		(end 77.24394 -284.922214)
		(width 0.0889)
		(layer "In11.Cu")
		(net "M_F_CPU1_SB_DQ<18>")
	)
	(segment
		(start 35.41268 -300.61027)
		(end 34.562542 -301.460408)
		(width 0.14478)
		(layer "In11.Cu")
		(net "M_F_CPU1_SB_DQ<18>")
	)
	(segment
		(start 58.476388 -299.750734)
		(end 56.766714 -301.460408)
		(width 0.14478)
		(layer "In11.Cu")
		(net "M_F_CPU1_SB_DQ<18>")
	)
	(segment
		(start 84.821014 -284.616398)
		(end 84.66709 -284.350968)
		(width 0.0889)
		(layer "In11.Cu")
		(net "M_F_CPU1_SB_DQ<18>")
	)
	(segment
		(start 19.259042 -301.85741)
		(end 19.114262 -302.00219)
		(width 0.14478)
		(layer "In11.Cu")
		(net "M_F_CPU1_SB_DQ<18>")
	)
	(segment
		(start 20.50669 -300.918626)
		(end 20.36191 -301.063406)
		(width 0.14478)
		(layer "In11.Cu")
		(net "M_F_CPU1_SB_DQ<18>")
	)
	(segment
		(start 49.43475 -301.460408)
		(end 47.00143 -301.460408)
		(width 0.14478)
		(layer "In11.Cu")
		(net "M_F_CPU1_SB_DQ<18>")
	)
	(segment
		(start 30.97403 -301.460408)
		(end 30.123892 -300.61027)
		(width 0.14478)
		(layer "In11.Cu")
		(net "M_F_CPU1_SB_DQ<18>")
	)
	(segment
		(start 78.567788 -284.549088)
		(end 77.71765 -284.549088)
		(width 0.0889)
		(layer "In11.Cu")
		(net "M_F_CPU1_SB_DQ<18>")
	)
	(segment
		(start 19.403822 -300.918626)
		(end 19.259042 -301.063406)
		(width 0.14478)
		(layer "In11.Cu")
		(net "M_F_CPU1_SB_DQ<18>")
	)
	(segment
		(start 75.880976 -284.922214)
		(end 75.434444 -284.922214)
		(width 0.14478)
		(layer "In11.Cu")
		(net "M_F_CPU1_SB_DQ<18>")
	)
	(segment
		(start 79.144622 -284.29712)
		(end 78.83525 -284.476952)
		(width 0.0889)
		(layer "In11.Cu")
		(net "M_F_CPU1_SB_DQ<18>")
	)
	(segment
		(start 79.391002 -284.30601)
		(end 79.364586 -284.292294)
		(width 0.0889)
		(layer "In11.Cu")
		(net "M_F_CPU1_SB_DQ<18>")
	)
	(segment
		(start 71.938642 -287.608518)
		(end 59.796426 -299.750734)
		(width 0.14478)
		(layer "In11.Cu")
		(net "M_F_CPU1_SB_DQ<18>")
	)
	(segment
		(start 75.434444 -284.922214)
		(end 72.74814 -287.608518)
		(width 0.14478)
		(layer "In11.Cu")
		(net "M_F_CPU1_SB_DQ<18>")
	)
	(segment
		(start 41.674542 -301.460408)
		(end 38.79723 -301.460408)
		(width 0.14478)
		(layer "In11.Cu")
		(net "M_F_CPU1_SB_DQ<18>")
	)
	(segment
		(start 18.707608 -301.605188)
		(end 18.562828 -301.460408)
		(width 0.14478)
		(layer "In11.Cu")
		(net "M_F_CPU1_SB_DQ<18>")
	)
	(segment
		(start 18.707608 -301.85741)
		(end 18.707608 -301.605188)
		(width 0.14478)
		(layer "In11.Cu")
		(net "M_F_CPU1_SB_DQ<18>")
	)
	(segment
		(start 19.665696 -300.918626)
		(end 19.403822 -300.918626)
		(width 0.14478)
		(layer "In11.Cu")
		(net "M_F_CPU1_SB_DQ<18>")
	)
	(segment
		(start 82.18805 -284.293818)
		(end 82.179668 -284.288992)
		(width 0.0889)
		(layer "In11.Cu")
		(net "M_F_CPU1_SB_DQ<18>")
	)
	(segment
		(start 47.00143 -301.460408)
		(end 46.151292 -300.61027)
		(width 0.14478)
		(layer "In11.Cu")
		(net "M_F_CPU1_SB_DQ<18>")
	)
	(segment
		(start 79.934308 -284.294072)
		(end 79.92237 -284.30093)
		(width 0.0889)
		(layer "In11.Cu")
		(net "M_F_CPU1_SB_DQ<18>")
	)
	(segment
		(start 19.114262 -302.00219)
		(end 18.852388 -302.00219)
		(width 0.14478)
		(layer "In11.Cu")
		(net "M_F_CPU1_SB_DQ<18>")
	)
	(segment
		(start 83.702398 -284.288992)
		(end 83.694016 -284.293818)
		(width 0.0889)
		(layer "In11.Cu")
		(net "M_F_CPU1_SB_DQ<18>")
	)
	(segment
		(start 82.762344 -284.288992)
		(end 82.753962 -284.293818)
		(width 0.0889)
		(layer "In11.Cu")
		(net "M_F_CPU1_SB_DQ<18>")
	)
	(segment
		(start 20.36191 -301.85741)
		(end 20.21713 -302.00219)
		(width 0.14478)
		(layer "In11.Cu")
		(net "M_F_CPU1_SB_DQ<18>")
	)
	(segment
		(start 54.26583 -301.460408)
		(end 53.415692 -300.61027)
		(width 0.14478)
		(layer "In11.Cu")
		(net "M_F_CPU1_SB_DQ<18>")
	)
	(segment
		(start 37.947092 -300.61027)
		(end 35.41268 -300.61027)
		(width 0.14478)
		(layer "In11.Cu")
		(net "M_F_CPU1_SB_DQ<18>")
	)
	(segment
		(start 19.810476 -301.063406)
		(end 19.665696 -300.918626)
		(width 0.14478)
		(layer "In11.Cu")
		(net "M_F_CPU1_SB_DQ<18>")
	)
	(segment
		(start 59.796426 -299.750734)
		(end 58.476388 -299.750734)
		(width 0.14478)
		(layer "In11.Cu")
		(net "M_F_CPU1_SB_DQ<18>")
	)
	(segment
		(start 72.74814 -287.608518)
		(end 71.938642 -287.608518)
		(width 0.14478)
		(layer "In11.Cu")
		(net "M_F_CPU1_SB_DQ<18>")
	)
	(segment
		(start 38.79723 -301.460408)
		(end 37.947092 -300.61027)
		(width 0.14478)
		(layer "In11.Cu")
		(net "M_F_CPU1_SB_DQ<18>")
	)
	(segment
		(start 18.852388 -302.00219)
		(end 18.707608 -301.85741)
		(width 0.14478)
		(layer "In11.Cu")
		(net "M_F_CPU1_SB_DQ<18>")
	)
	(segment
		(start 19.955256 -302.00219)
		(end 19.810476 -301.85741)
		(width 0.14478)
		(layer "In11.Cu")
		(net "M_F_CPU1_SB_DQ<18>")
	)
	(segment
		(start 21.058124 -301.460408)
		(end 20.913344 -301.315628)
		(width 0.14478)
		(layer "In11.Cu")
		(net "M_F_CPU1_SB_DQ<18>")
	)
	(segment
		(start 42.52468 -300.61027)
		(end 41.674542 -301.460408)
		(width 0.14478)
		(layer "In11.Cu")
		(net "M_F_CPU1_SB_DQ<18>")
	)
	(segment
		(start 20.913344 -301.063406)
		(end 20.768564 -300.918626)
		(width 0.14478)
		(layer "In11.Cu")
		(net "M_F_CPU1_SB_DQ<18>")
	)
	(arc
		(start 81.247996 -284.293818)
		(mid 81.061052 -284.243563)
		(end 80.874108 -284.293818)
		(width 0.0889)
		(layer "In11.Cu")
		(net "M_F_CPU1_SB_DQ<18>")
	)
	(arc
		(start 78.83525 -284.476952)
		(mid 78.706298 -284.530741)
		(end 78.567788 -284.549088)
		(width 0.0889)
		(layer "In11.Cu")
		(net "M_F_CPU1_SB_DQ<18>")
	)
	(arc
		(start 84.068158 -284.293818)
		(mid 83.885907 -284.243468)
		(end 83.702398 -284.288992)
		(width 0.0889)
		(layer "In11.Cu")
		(net "M_F_CPU1_SB_DQ<18>")
	)
	(arc
		(start 79.364586 -284.292294)
		(mid 79.253975 -284.266373)
		(end 79.144622 -284.29712)
		(width 0.0889)
		(layer "In11.Cu")
		(net "M_F_CPU1_SB_DQ<18>")
	)
	(arc
		(start 84.571078 -284.325568)
		(mid 84.31587 -284.369045)
		(end 84.068158 -284.293818)
		(width 0.0889)
		(layer "In11.Cu")
		(net "M_F_CPU1_SB_DQ<18>")
	)
	(arc
		(start 83.694016 -284.293818)
		(mid 83.41106 -284.369995)
		(end 83.128104 -284.293818)
		(width 0.0889)
		(layer "In11.Cu")
		(net "M_F_CPU1_SB_DQ<18>")
	)
	(arc
		(start 80.308196 -284.293818)
		(mid 80.130546 -284.243558)
		(end 79.950564 -284.284674)
		(width 0.0889)
		(layer "In11.Cu")
		(net "M_F_CPU1_SB_DQ<18>")
	)
	(arc
		(start 81.813908 -284.293818)
		(mid 81.530952 -284.369995)
		(end 81.247996 -284.293818)
		(width 0.0889)
		(layer "In11.Cu")
		(net "M_F_CPU1_SB_DQ<18>")
	)
	(arc
		(start 82.179668 -284.288992)
		(mid 81.99616 -284.243498)
		(end 81.813908 -284.293818)
		(width 0.0889)
		(layer "In11.Cu")
		(net "M_F_CPU1_SB_DQ<18>")
	)
	(arc
		(start 82.753962 -284.293818)
		(mid 82.471006 -284.369995)
		(end 82.18805 -284.293818)
		(width 0.0889)
		(layer "In11.Cu")
		(net "M_F_CPU1_SB_DQ<18>")
	)
	(arc
		(start 79.92237 -284.30093)
		(mid 79.657314 -284.370053)
		(end 79.391002 -284.30601)
		(width 0.0889)
		(layer "In11.Cu")
		(net "M_F_CPU1_SB_DQ<18>")
	)
	(arc
		(start 83.128104 -284.293818)
		(mid 82.945853 -284.243468)
		(end 82.762344 -284.288992)
		(width 0.0889)
		(layer "In11.Cu")
		(net "M_F_CPU1_SB_DQ<18>")
	)
	(arc
		(start 77.71765 -284.549088)
		(mid 77.624725 -284.567572)
		(end 77.545946 -284.620208)
		(width 0.0889)
		(layer "In11.Cu")
		(net "M_F_CPU1_SB_DQ<18>")
	)
	(arc
		(start 80.874108 -284.293818)
		(mid 80.591152 -284.369995)
		(end 80.308196 -284.293818)
		(width 0.0889)
		(layer "In11.Cu")
		(net "M_F_CPU1_SB_DQ<18>")
	)
	(segment
		(start 86.22792 -284.35046)
		(end 85.761068 -284.616398)
		(width 0.10668)
		(layer "F.Cu")
		(net "M_F_CPU1_SB_DQ<17>")
	)
	(segment
		(start 72.934576 -288.058098)
		(end 72.125332 -288.058098)
		(width 0.14478)
		(layer "In11.Cu")
		(net "M_F_CPU1_SB_DQ<17>")
	)
	(segment
		(start 58.662824 -300.200314)
		(end 56.552846 -302.310292)
		(width 0.14478)
		(layer "In11.Cu")
		(net "M_F_CPU1_SB_DQ<17>")
	)
	(segment
		(start 45.327062 -301.060866)
		(end 45.182282 -301.205646)
		(width 0.14478)
		(layer "In11.Cu")
		(net "M_F_CPU1_SB_DQ<17>")
	)
	(segment
		(start 42.850816 -301.460408)
		(end 42.487342 -301.460408)
		(width 0.14478)
		(layer "In11.Cu")
		(net "M_F_CPU1_SB_DQ<17>")
	)
	(segment
		(start 54.472586 -302.310292)
		(end 53.622448 -301.460154)
		(width 0.14478)
		(layer "In11.Cu")
		(net "M_F_CPU1_SB_DQ<17>")
	)
	(segment
		(start 35.534346 -301.149004)
		(end 34.061146 -302.622204)
		(width 0.14478)
		(layer "In11.Cu")
		(net "M_F_CPU1_SB_DQ<17>")
	)
	(segment
		(start 45.733716 -301.205646)
		(end 45.588936 -301.060866)
		(width 0.14478)
		(layer "In11.Cu")
		(net "M_F_CPU1_SB_DQ<17>")
	)
	(segment
		(start 53.143658 -301.315374)
		(end 53.143658 -301.205646)
		(width 0.14478)
		(layer "In11.Cu")
		(net "M_F_CPU1_SB_DQ<17>")
	)
	(segment
		(start 28.614116 -301.149004)
		(end 28.142946 -301.149004)
		(width 0.14478)
		(layer "In11.Cu")
		(net "M_F_CPU1_SB_DQ<17>")
	)
	(segment
		(start 31.914846 -302.310292)
		(end 31.652464 -302.572674)
		(width 0.14478)
		(layer "In11.Cu")
		(net "M_F_CPU1_SB_DQ<17>")
	)
	(segment
		(start 34.061146 -302.622204)
		(end 33.816798 -302.622204)
		(width 0.14478)
		(layer "In11.Cu")
		(net "M_F_CPU1_SB_DQ<17>")
	)
	(segment
		(start 25.80132 -301.942754)
		(end 25.433782 -302.310292)
		(width 0.14478)
		(layer "In11.Cu")
		(net "M_F_CPU1_SB_DQ<17>")
	)
	(segment
		(start 50.624486 -301.205646)
		(end 50.624486 -301.315374)
		(width 0.14478)
		(layer "In11.Cu")
		(net "M_F_CPU1_SB_DQ<17>")
	)
	(segment
		(start 37.625274 -301.159164)
		(end 37.300916 -301.159164)
		(width 0.14478)
		(layer "In11.Cu")
		(net "M_F_CPU1_SB_DQ<17>")
	)
	(segment
		(start 25.433782 -302.310292)
		(end 24.813768 -302.310292)
		(width 0.14478)
		(layer "In11.Cu")
		(net "M_F_CPU1_SB_DQ<17>")
	)
	(segment
		(start 45.588936 -301.060866)
		(end 45.327062 -301.060866)
		(width 0.14478)
		(layer "In11.Cu")
		(net "M_F_CPU1_SB_DQ<17>")
	)
	(segment
		(start 31.652464 -302.572674)
		(end 31.447232 -302.572674)
		(width 0.14478)
		(layer "In11.Cu")
		(net "M_F_CPU1_SB_DQ<17>")
	)
	(segment
		(start 56.552846 -302.310292)
		(end 54.472586 -302.310292)
		(width 0.14478)
		(layer "In11.Cu")
		(net "M_F_CPU1_SB_DQ<17>")
	)
	(segment
		(start 24.032718 -302.085502)
		(end 24.032718 -302.531018)
		(width 0.14478)
		(layer "In11.Cu")
		(net "M_F_CPU1_SB_DQ<17>")
	)
	(segment
		(start 35.779456 -301.149004)
		(end 35.534346 -301.149004)
		(width 0.14478)
		(layer "In11.Cu")
		(net "M_F_CPU1_SB_DQ<17>")
	)
	(segment
		(start 43.54703 -301.315628)
		(end 43.54703 -301.205646)
		(width 0.14478)
		(layer "In11.Cu")
		(net "M_F_CPU1_SB_DQ<17>")
	)
	(segment
		(start 24.426164 -301.922688)
		(end 24.195532 -301.922688)
		(width 0.14478)
		(layer "In11.Cu")
		(net "M_F_CPU1_SB_DQ<17>")
	)
	(segment
		(start 82.762344 -284.943804)
		(end 82.753962 -284.938978)
		(width 0.0889)
		(layer "In11.Cu")
		(net "M_F_CPU1_SB_DQ<17>")
	)
	(segment
		(start 52.998878 -301.060866)
		(end 52.737004 -301.060866)
		(width 0.14478)
		(layer "In11.Cu")
		(net "M_F_CPU1_SB_DQ<17>")
	)
	(segment
		(start 22.514052 -302.691292)
		(end 21.70811 -301.88535)
		(width 0.14478)
		(layer "In11.Cu")
		(net "M_F_CPU1_SB_DQ<17>")
	)
	(segment
		(start 42.487342 -301.460408)
		(end 41.637458 -302.310292)
		(width 0.14478)
		(layer "In11.Cu")
		(net "M_F_CPU1_SB_DQ<17>")
	)
	(segment
		(start 43.40225 -301.060866)
		(end 43.140376 -301.060866)
		(width 0.14478)
		(layer "In11.Cu")
		(net "M_F_CPU1_SB_DQ<17>")
	)
	(segment
		(start 51.03114 -301.060866)
		(end 50.769266 -301.060866)
		(width 0.14478)
		(layer "In11.Cu")
		(net "M_F_CPU1_SB_DQ<17>")
	)
	(segment
		(start 50.479706 -301.460154)
		(end 50.078132 -301.460154)
		(width 0.14478)
		(layer "In11.Cu")
		(net "M_F_CPU1_SB_DQ<17>")
	)
	(segment
		(start 37.300916 -301.159164)
		(end 36.999926 -301.460154)
		(width 0.14478)
		(layer "In11.Cu")
		(net "M_F_CPU1_SB_DQ<17>")
	)
	(segment
		(start 38.776402 -302.310292)
		(end 37.625274 -301.159164)
		(width 0.14478)
		(layer "In11.Cu")
		(net "M_F_CPU1_SB_DQ<17>")
	)
	(segment
		(start 46.21403 -301.460408)
		(end 45.878496 -301.460408)
		(width 0.14478)
		(layer "In11.Cu")
		(net "M_F_CPU1_SB_DQ<17>")
	)
	(segment
		(start 82.18805 -284.938978)
		(end 82.179668 -284.943804)
		(width 0.0889)
		(layer "In11.Cu")
		(net "M_F_CPU1_SB_DQ<17>")
	)
	(segment
		(start 43.140376 -301.060866)
		(end 42.995596 -301.205646)
		(width 0.14478)
		(layer "In11.Cu")
		(net "M_F_CPU1_SB_DQ<17>")
	)
	(segment
		(start 28.142946 -301.149004)
		(end 26.600404 -302.691546)
		(width 0.14478)
		(layer "In11.Cu")
		(net "M_F_CPU1_SB_DQ<17>")
	)
	(segment
		(start 50.624486 -301.315374)
		(end 50.479706 -301.460154)
		(width 0.14478)
		(layer "In11.Cu")
		(net "M_F_CPU1_SB_DQ<17>")
	)
	(segment
		(start 53.622448 -301.460154)
		(end 53.288438 -301.460154)
		(width 0.14478)
		(layer "In11.Cu")
		(net "M_F_CPU1_SB_DQ<17>")
	)
	(segment
		(start 24.032718 -302.531018)
		(end 23.872444 -302.691292)
		(width 0.14478)
		(layer "In11.Cu")
		(net "M_F_CPU1_SB_DQ<17>")
	)
	(segment
		(start 77.443076 -285.376874)
		(end 76.002896 -285.376874)
		(width 0.0889)
		(layer "In11.Cu")
		(net "M_F_CPU1_SB_DQ<17>")
	)
	(segment
		(start 33.816798 -302.622204)
		(end 33.504886 -302.310292)
		(width 0.14478)
		(layer "In11.Cu")
		(net "M_F_CPU1_SB_DQ<17>")
	)
	(segment
		(start 52.447444 -301.460154)
		(end 51.3207 -301.460154)
		(width 0.14478)
		(layer "In11.Cu")
		(net "M_F_CPU1_SB_DQ<17>")
	)
	(segment
		(start 22.759924 -302.691292)
		(end 22.514052 -302.691292)
		(width 0.14478)
		(layer "In11.Cu")
		(net "M_F_CPU1_SB_DQ<17>")
	)
	(segment
		(start 45.182282 -301.315628)
		(end 45.037502 -301.460408)
		(width 0.14478)
		(layer "In11.Cu")
		(net "M_F_CPU1_SB_DQ<17>")
	)
	(segment
		(start 78.993746 -284.938978)
		(end 78.979014 -284.930342)
		(width 0.0889)
		(layer "In11.Cu")
		(net "M_F_CPU1_SB_DQ<17>")
	)
	(segment
		(start 53.288438 -301.460154)
		(end 53.143658 -301.315374)
		(width 0.14478)
		(layer "In11.Cu")
		(net "M_F_CPU1_SB_DQ<17>")
	)
	(segment
		(start 75.6158 -285.376874)
		(end 72.934576 -288.058098)
		(width 0.14478)
		(layer "In11.Cu")
		(net "M_F_CPU1_SB_DQ<17>")
	)
	(segment
		(start 45.733716 -301.315628)
		(end 45.733716 -301.205646)
		(width 0.14478)
		(layer "In11.Cu")
		(net "M_F_CPU1_SB_DQ<17>")
	)
	(segment
		(start 41.637458 -302.310292)
		(end 38.776402 -302.310292)
		(width 0.14478)
		(layer "In11.Cu")
		(net "M_F_CPU1_SB_DQ<17>")
	)
	(segment
		(start 23.641812 -302.691292)
		(end 23.476458 -302.525938)
		(width 0.14478)
		(layer "In11.Cu")
		(net "M_F_CPU1_SB_DQ<17>")
	)
	(segment
		(start 30.334712 -301.460154)
		(end 28.925266 -301.460154)
		(width 0.14478)
		(layer "In11.Cu")
		(net "M_F_CPU1_SB_DQ<17>")
	)
	(segment
		(start 45.878496 -301.460408)
		(end 45.733716 -301.315628)
		(width 0.14478)
		(layer "In11.Cu")
		(net "M_F_CPU1_SB_DQ<17>")
	)
	(segment
		(start 23.083012 -301.922688)
		(end 22.920198 -302.085502)
		(width 0.14478)
		(layer "In11.Cu")
		(net "M_F_CPU1_SB_DQ<17>")
	)
	(segment
		(start 42.995596 -301.315628)
		(end 42.850816 -301.460408)
		(width 0.14478)
		(layer "In11.Cu")
		(net "M_F_CPU1_SB_DQ<17>")
	)
	(segment
		(start 83.702398 -284.943804)
		(end 83.694016 -284.938978)
		(width 0.0889)
		(layer "In11.Cu")
		(net "M_F_CPU1_SB_DQ<17>")
	)
	(segment
		(start 26.194766 -302.105568)
		(end 26.031952 -301.942754)
		(width 0.14478)
		(layer "In11.Cu")
		(net "M_F_CPU1_SB_DQ<17>")
	)
	(segment
		(start 22.920198 -302.085502)
		(end 22.920198 -302.531018)
		(width 0.14478)
		(layer "In11.Cu")
		(net "M_F_CPU1_SB_DQ<17>")
	)
	(segment
		(start 42.995596 -301.205646)
		(end 42.995596 -301.315628)
		(width 0.14478)
		(layer "In11.Cu")
		(net "M_F_CPU1_SB_DQ<17>")
	)
	(segment
		(start 45.182282 -301.205646)
		(end 45.182282 -301.315628)
		(width 0.14478)
		(layer "In11.Cu")
		(net "M_F_CPU1_SB_DQ<17>")
	)
	(segment
		(start 45.037502 -301.460408)
		(end 43.69181 -301.460408)
		(width 0.14478)
		(layer "In11.Cu")
		(net "M_F_CPU1_SB_DQ<17>")
	)
	(segment
		(start 79.378048 -284.932882)
		(end 79.367634 -284.938978)
		(width 0.0889)
		(layer "In11.Cu")
		(net "M_F_CPU1_SB_DQ<17>")
	)
	(segment
		(start 59.983116 -300.200314)
		(end 58.662824 -300.200314)
		(width 0.14478)
		(layer "In11.Cu")
		(net "M_F_CPU1_SB_DQ<17>")
	)
	(segment
		(start 43.54703 -301.205646)
		(end 43.40225 -301.060866)
		(width 0.14478)
		(layer "In11.Cu")
		(net "M_F_CPU1_SB_DQ<17>")
	)
	(segment
		(start 23.872444 -302.691292)
		(end 23.641812 -302.691292)
		(width 0.14478)
		(layer "In11.Cu")
		(net "M_F_CPU1_SB_DQ<17>")
	)
	(segment
		(start 24.195532 -301.922688)
		(end 24.032718 -302.085502)
		(width 0.14478)
		(layer "In11.Cu")
		(net "M_F_CPU1_SB_DQ<17>")
	)
	(segment
		(start 52.592224 -301.205646)
		(end 52.592224 -301.315374)
		(width 0.14478)
		(layer "In11.Cu")
		(net "M_F_CPU1_SB_DQ<17>")
	)
	(segment
		(start 50.769266 -301.060866)
		(end 50.624486 -301.205646)
		(width 0.14478)
		(layer "In11.Cu")
		(net "M_F_CPU1_SB_DQ<17>")
	)
	(segment
		(start 22.920198 -302.531018)
		(end 22.759924 -302.691292)
		(width 0.14478)
		(layer "In11.Cu")
		(net "M_F_CPU1_SB_DQ<17>")
	)
	(segment
		(start 52.592224 -301.315374)
		(end 52.447444 -301.460154)
		(width 0.14478)
		(layer "In11.Cu")
		(net "M_F_CPU1_SB_DQ<17>")
	)
	(segment
		(start 31.447232 -302.572674)
		(end 30.334712 -301.460154)
		(width 0.14478)
		(layer "In11.Cu")
		(net "M_F_CPU1_SB_DQ<17>")
	)
	(segment
		(start 26.600404 -302.691546)
		(end 26.345388 -302.691546)
		(width 0.14478)
		(layer "In11.Cu")
		(net "M_F_CPU1_SB_DQ<17>")
	)
	(segment
		(start 85.914992 -284.881828)
		(end 85.89264 -284.96514)
		(width 0.0889)
		(layer "In11.Cu")
		(net "M_F_CPU1_SB_DQ<17>")
	)
	(segment
		(start 36.090606 -301.460154)
		(end 35.779456 -301.149004)
		(width 0.14478)
		(layer "In11.Cu")
		(net "M_F_CPU1_SB_DQ<17>")
	)
	(segment
		(start 78.240636 -284.989524)
		(end 77.830426 -284.989524)
		(width 0.0889)
		(layer "In11.Cu")
		(net "M_F_CPU1_SB_DQ<17>")
	)
	(segment
		(start 26.194766 -302.540924)
		(end 26.194766 -302.105568)
		(width 0.14478)
		(layer "In11.Cu")
		(net "M_F_CPU1_SB_DQ<17>")
	)
	(segment
		(start 50.078132 -301.460154)
		(end 49.227994 -302.310292)
		(width 0.14478)
		(layer "In11.Cu")
		(net "M_F_CPU1_SB_DQ<17>")
	)
	(segment
		(start 72.125332 -288.058098)
		(end 59.983116 -300.200314)
		(width 0.14478)
		(layer "In11.Cu")
		(net "M_F_CPU1_SB_DQ<17>")
	)
	(segment
		(start 76.002896 -285.376874)
		(end 75.6158 -285.376874)
		(width 0.14478)
		(layer "In11.Cu")
		(net "M_F_CPU1_SB_DQ<17>")
	)
	(segment
		(start 33.504886 -302.310292)
		(end 31.914846 -302.310292)
		(width 0.14478)
		(layer "In11.Cu")
		(net "M_F_CPU1_SB_DQ<17>")
	)
	(segment
		(start 28.925266 -301.460154)
		(end 28.614116 -301.149004)
		(width 0.14478)
		(layer "In11.Cu")
		(net "M_F_CPU1_SB_DQ<17>")
	)
	(segment
		(start 51.17592 -301.205646)
		(end 51.03114 -301.060866)
		(width 0.14478)
		(layer "In11.Cu")
		(net "M_F_CPU1_SB_DQ<17>")
	)
	(segment
		(start 52.737004 -301.060866)
		(end 52.592224 -301.205646)
		(width 0.14478)
		(layer "In11.Cu")
		(net "M_F_CPU1_SB_DQ<17>")
	)
	(segment
		(start 23.313644 -301.922688)
		(end 23.083012 -301.922688)
		(width 0.14478)
		(layer "In11.Cu")
		(net "M_F_CPU1_SB_DQ<17>")
	)
	(segment
		(start 24.813768 -302.310292)
		(end 24.426164 -301.922688)
		(width 0.14478)
		(layer "In11.Cu")
		(net "M_F_CPU1_SB_DQ<17>")
	)
	(segment
		(start 23.476458 -302.085502)
		(end 23.313644 -301.922688)
		(width 0.14478)
		(layer "In11.Cu")
		(net "M_F_CPU1_SB_DQ<17>")
	)
	(segment
		(start 36.999926 -301.460154)
		(end 36.090606 -301.460154)
		(width 0.14478)
		(layer "In11.Cu")
		(net "M_F_CPU1_SB_DQ<17>")
	)
	(segment
		(start 49.227994 -302.310292)
		(end 47.063914 -302.310292)
		(width 0.14478)
		(layer "In11.Cu")
		(net "M_F_CPU1_SB_DQ<17>")
	)
	(segment
		(start 43.69181 -301.460408)
		(end 43.54703 -301.315628)
		(width 0.14478)
		(layer "In11.Cu")
		(net "M_F_CPU1_SB_DQ<17>")
	)
	(segment
		(start 51.17592 -301.315374)
		(end 51.17592 -301.205646)
		(width 0.14478)
		(layer "In11.Cu")
		(net "M_F_CPU1_SB_DQ<17>")
	)
	(segment
		(start 51.3207 -301.460154)
		(end 51.17592 -301.315374)
		(width 0.14478)
		(layer "In11.Cu")
		(net "M_F_CPU1_SB_DQ<17>")
	)
	(segment
		(start 77.830426 -284.989524)
		(end 77.443076 -285.376874)
		(width 0.0889)
		(layer "In11.Cu")
		(net "M_F_CPU1_SB_DQ<17>")
	)
	(segment
		(start 85.761068 -284.616398)
		(end 85.914992 -284.881828)
		(width 0.0889)
		(layer "In11.Cu")
		(net "M_F_CPU1_SB_DQ<17>")
	)
	(segment
		(start 23.476458 -302.525938)
		(end 23.476458 -302.085502)
		(width 0.14478)
		(layer "In11.Cu")
		(net "M_F_CPU1_SB_DQ<17>")
	)
	(segment
		(start 26.345388 -302.691546)
		(end 26.194766 -302.540924)
		(width 0.14478)
		(layer "In11.Cu")
		(net "M_F_CPU1_SB_DQ<17>")
	)
	(segment
		(start 53.143658 -301.205646)
		(end 52.998878 -301.060866)
		(width 0.14478)
		(layer "In11.Cu")
		(net "M_F_CPU1_SB_DQ<17>")
	)
	(segment
		(start 26.031952 -301.942754)
		(end 25.80132 -301.942754)
		(width 0.14478)
		(layer "In11.Cu")
		(net "M_F_CPU1_SB_DQ<17>")
	)
	(segment
		(start 47.063914 -302.310292)
		(end 46.21403 -301.460408)
		(width 0.14478)
		(layer "In11.Cu")
		(net "M_F_CPU1_SB_DQ<17>")
	)
	(arc
		(start 79.9338 -284.938978)
		(mid 79.656733 -284.862707)
		(end 79.378048 -284.932882)
		(width 0.0889)
		(layer "In11.Cu")
		(net "M_F_CPU1_SB_DQ<17>")
	)
	(arc
		(start 80.874108 -284.938978)
		(mid 80.591152 -284.862801)
		(end 80.308196 -284.938978)
		(width 0.0889)
		(layer "In11.Cu")
		(net "M_F_CPU1_SB_DQ<17>")
	)
	(arc
		(start 85.89264 -284.96514)
		(mid 85.730308 -284.987958)
		(end 85.57387 -284.938978)
		(width 0.0889)
		(layer "In11.Cu")
		(net "M_F_CPU1_SB_DQ<17>")
	)
	(arc
		(start 81.247996 -284.938978)
		(mid 81.061052 -284.989233)
		(end 80.874108 -284.938978)
		(width 0.0889)
		(layer "In11.Cu")
		(net "M_F_CPU1_SB_DQ<17>")
	)
	(arc
		(start 83.128104 -284.938978)
		(mid 82.945853 -284.989328)
		(end 82.762344 -284.943804)
		(width 0.0889)
		(layer "In11.Cu")
		(net "M_F_CPU1_SB_DQ<17>")
	)
	(arc
		(start 84.63407 -284.938978)
		(mid 84.351114 -284.862801)
		(end 84.068158 -284.938978)
		(width 0.0889)
		(layer "In11.Cu")
		(net "M_F_CPU1_SB_DQ<17>")
	)
	(arc
		(start 82.179668 -284.943804)
		(mid 81.99616 -284.989298)
		(end 81.813908 -284.938978)
		(width 0.0889)
		(layer "In11.Cu")
		(net "M_F_CPU1_SB_DQ<17>")
	)
	(arc
		(start 81.813908 -284.938978)
		(mid 81.530952 -284.862801)
		(end 81.247996 -284.938978)
		(width 0.0889)
		(layer "In11.Cu")
		(net "M_F_CPU1_SB_DQ<17>")
	)
	(arc
		(start 85.007958 -284.938978)
		(mid 84.821014 -284.989233)
		(end 84.63407 -284.938978)
		(width 0.0889)
		(layer "In11.Cu")
		(net "M_F_CPU1_SB_DQ<17>")
	)
	(arc
		(start 80.308196 -284.938978)
		(mid 80.120998 -284.98936)
		(end 79.9338 -284.938978)
		(width 0.0889)
		(layer "In11.Cu")
		(net "M_F_CPU1_SB_DQ<17>")
	)
	(arc
		(start 78.979014 -284.930342)
		(mid 78.702285 -284.862659)
		(end 78.427834 -284.938978)
		(width 0.0889)
		(layer "In11.Cu")
		(net "M_F_CPU1_SB_DQ<17>")
	)
	(arc
		(start 78.427834 -284.938978)
		(mid 78.337574 -284.976606)
		(end 78.240636 -284.989524)
		(width 0.0889)
		(layer "In11.Cu")
		(net "M_F_CPU1_SB_DQ<17>")
	)
	(arc
		(start 84.068158 -284.938978)
		(mid 83.885907 -284.989328)
		(end 83.702398 -284.943804)
		(width 0.0889)
		(layer "In11.Cu")
		(net "M_F_CPU1_SB_DQ<17>")
	)
	(arc
		(start 83.694016 -284.938978)
		(mid 83.41106 -284.862801)
		(end 83.128104 -284.938978)
		(width 0.0889)
		(layer "In11.Cu")
		(net "M_F_CPU1_SB_DQ<17>")
	)
	(arc
		(start 85.57387 -284.938978)
		(mid 85.290914 -284.862801)
		(end 85.007958 -284.938978)
		(width 0.0889)
		(layer "In11.Cu")
		(net "M_F_CPU1_SB_DQ<17>")
	)
	(arc
		(start 79.367634 -284.938978)
		(mid 79.18069 -284.989233)
		(end 78.993746 -284.938978)
		(width 0.0889)
		(layer "In11.Cu")
		(net "M_F_CPU1_SB_DQ<17>")
	)
	(arc
		(start 82.753962 -284.938978)
		(mid 82.471006 -284.862801)
		(end 82.18805 -284.938978)
		(width 0.0889)
		(layer "In11.Cu")
		(net "M_F_CPU1_SB_DQ<17>")
	)
	(segment
		(start 84.817966 -283.540454)
		(end 84.351114 -283.806392)
		(width 0.10668)
		(layer "F.Cu")
		(net "M_F_CPU1_SB_DQ<16>")
	)
	(segment
		(start 73.469246 -285.296356)
		(end 73.283826 -285.481776)
		(width 0.14478)
		(layer "In11.Cu")
		(net "M_F_CPU1_SB_DQ<16>")
	)
	(segment
		(start 84.351114 -283.806392)
		(end 84.505038 -284.071822)
		(width 0.0889)
		(layer "In11.Cu")
		(net "M_F_CPU1_SB_DQ<16>")
	)
	(segment
		(start 83.598004 -284.128972)
		(end 83.589622 -284.133798)
		(width 0.0889)
		(layer "In11.Cu")
		(net "M_F_CPU1_SB_DQ<16>")
	)
	(segment
		(start 74.064114 -284.906212)
		(end 74.26452 -285.106618)
		(width 0.14478)
		(layer "In11.Cu")
		(net "M_F_CPU1_SB_DQ<16>")
	)
	(segment
		(start 43.67911 -300.082204)
		(end 43.444668 -300.082204)
		(width 0.14478)
		(layer "In11.Cu")
		(net "M_F_CPU1_SB_DQ<16>")
	)
	(segment
		(start 39.392606 -300.930564)
		(end 39.156386 -300.930564)
		(width 0.14478)
		(layer "In11.Cu")
		(net "M_F_CPU1_SB_DQ<16>")
	)
	(segment
		(start 24.010366 -300.489112)
		(end 24.010366 -300.818804)
		(width 0.14478)
		(layer "In11.Cu")
		(net "M_F_CPU1_SB_DQ<16>")
	)
	(segment
		(start 46.837346 -300.610524)
		(end 45.987208 -299.760386)
		(width 0.14478)
		(layer "In11.Cu")
		(net "M_F_CPU1_SB_DQ<16>")
	)
	(segment
		(start 33.667954 -300.610524)
		(end 31.876746 -300.610524)
		(width 0.14478)
		(layer "In11.Cu")
		(net "M_F_CPU1_SB_DQ<16>")
	)
	(segment
		(start 74.292968 -284.472634)
		(end 74.064114 -284.701488)
		(width 0.14478)
		(layer "In11.Cu")
		(net "M_F_CPU1_SB_DQ<16>")
	)
	(segment
		(start 31.876746 -300.610524)
		(end 31.569406 -300.917864)
		(width 0.14478)
		(layer "In11.Cu")
		(net "M_F_CPU1_SB_DQ<16>")
	)
	(segment
		(start 50.775362 -299.760386)
		(end 50.491644 -299.760386)
		(width 0.14478)
		(layer "In11.Cu")
		(net "M_F_CPU1_SB_DQ<16>")
	)
	(segment
		(start 84.505038 -284.071822)
		(end 84.482686 -284.155134)
		(width 0.0889)
		(layer "In11.Cu")
		(net "M_F_CPU1_SB_DQ<16>")
	)
	(segment
		(start 27.880564 -299.760386)
		(end 26.638758 -301.002192)
		(width 0.14478)
		(layer "In11.Cu")
		(net "M_F_CPU1_SB_DQ<16>")
	)
	(segment
		(start 74.064114 -284.701488)
		(end 74.064114 -284.906212)
		(width 0.14478)
		(layer "In11.Cu")
		(net "M_F_CPU1_SB_DQ<16>")
	)
	(segment
		(start 39.156386 -300.930564)
		(end 37.986208 -299.760386)
		(width 0.14478)
		(layer "In11.Cu")
		(net "M_F_CPU1_SB_DQ<16>")
	)
	(segment
		(start 72.113394 -286.856932)
		(end 71.90867 -286.856932)
		(width 0.14478)
		(layer "In11.Cu")
		(net "M_F_CPU1_SB_DQ<16>")
	)
	(segment
		(start 30.163008 -299.760386)
		(end 27.880564 -299.760386)
		(width 0.14478)
		(layer "In11.Cu")
		(net "M_F_CPU1_SB_DQ<16>")
	)
	(segment
		(start 50.491644 -299.760386)
		(end 49.641506 -300.610524)
		(width 0.14478)
		(layer "In11.Cu")
		(net "M_F_CPU1_SB_DQ<16>")
	)
	(segment
		(start 26.638758 -301.002192)
		(end 26.408126 -301.002192)
		(width 0.14478)
		(layer "In11.Cu")
		(net "M_F_CPU1_SB_DQ<16>")
	)
	(segment
		(start 53.054758 -299.760386)
		(end 52.74564 -300.069504)
		(width 0.14478)
		(layer "In11.Cu")
		(net "M_F_CPU1_SB_DQ<16>")
	)
	(segment
		(start 37.986208 -299.760386)
		(end 35.487864 -299.760386)
		(width 0.14478)
		(layer "In11.Cu")
		(net "M_F_CPU1_SB_DQ<16>")
	)
	(segment
		(start 76.817982 -283.969968)
		(end 76.315316 -284.472634)
		(width 0.0889)
		(layer "In11.Cu")
		(net "M_F_CPU1_SB_DQ<16>")
	)
	(segment
		(start 43.444668 -300.082204)
		(end 43.12285 -299.760386)
		(width 0.14478)
		(layer "In11.Cu")
		(net "M_F_CPU1_SB_DQ<16>")
	)
	(segment
		(start 23.454106 -300.818804)
		(end 23.454106 -300.489112)
		(width 0.14478)
		(layer "In11.Cu")
		(net "M_F_CPU1_SB_DQ<16>")
	)
	(segment
		(start 56.0324 -300.922944)
		(end 55.71998 -300.610524)
		(width 0.14478)
		(layer "In11.Cu")
		(net "M_F_CPU1_SB_DQ<16>")
	)
	(segment
		(start 23.06066 -300.326298)
		(end 22.897846 -300.489112)
		(width 0.14478)
		(layer "In11.Cu")
		(net "M_F_CPU1_SB_DQ<16>")
	)
	(segment
		(start 41.282366 -300.917864)
		(end 40.975026 -300.610524)
		(width 0.14478)
		(layer "In11.Cu")
		(net "M_F_CPU1_SB_DQ<16>")
	)
	(segment
		(start 72.3138 -287.057338)
		(end 72.113394 -286.856932)
		(width 0.14478)
		(layer "In11.Cu")
		(net "M_F_CPU1_SB_DQ<16>")
	)
	(segment
		(start 51.64836 -299.760386)
		(end 51.331622 -300.077124)
		(width 0.14478)
		(layer "In11.Cu")
		(net "M_F_CPU1_SB_DQ<16>")
	)
	(segment
		(start 42.688764 -299.760386)
		(end 41.531286 -300.917864)
		(width 0.14478)
		(layer "In11.Cu")
		(net "M_F_CPU1_SB_DQ<16>")
	)
	(segment
		(start 73.484232 -285.886906)
		(end 73.484232 -286.09163)
		(width 0.14478)
		(layer "In11.Cu")
		(net "M_F_CPU1_SB_DQ<16>")
	)
	(segment
		(start 73.484232 -286.09163)
		(end 73.298812 -286.27705)
		(width 0.14478)
		(layer "In11.Cu")
		(net "M_F_CPU1_SB_DQ<16>")
	)
	(segment
		(start 45.26026 -300.077124)
		(end 45.020738 -300.077124)
		(width 0.14478)
		(layer "In11.Cu")
		(net "M_F_CPU1_SB_DQ<16>")
	)
	(segment
		(start 34.330386 -300.917864)
		(end 33.975294 -300.917864)
		(width 0.14478)
		(layer "In11.Cu")
		(net "M_F_CPU1_SB_DQ<16>")
	)
	(segment
		(start 26.245312 -300.517306)
		(end 26.04897 -300.320964)
		(width 0.14478)
		(layer "In11.Cu")
		(net "M_F_CPU1_SB_DQ<16>")
	)
	(segment
		(start 60.16371 -298.601892)
		(end 58.989214 -298.601892)
		(width 0.14478)
		(layer "In11.Cu")
		(net "M_F_CPU1_SB_DQ<16>")
	)
	(segment
		(start 76.315316 -284.472634)
		(end 74.292968 -284.472634)
		(width 0.14478)
		(layer "In11.Cu")
		(net "M_F_CPU1_SB_DQ<16>")
	)
	(segment
		(start 73.874376 -285.496762)
		(end 73.67397 -285.296356)
		(width 0.14478)
		(layer "In11.Cu")
		(net "M_F_CPU1_SB_DQ<16>")
	)
	(segment
		(start 54.201822 -300.610524)
		(end 53.351684 -299.760386)
		(width 0.14478)
		(layer "In11.Cu")
		(net "M_F_CPU1_SB_DQ<16>")
	)
	(segment
		(start 81.35239 -284.133798)
		(end 81.344008 -284.128972)
		(width 0.0889)
		(layer "In11.Cu")
		(net "M_F_CPU1_SB_DQ<16>")
	)
	(segment
		(start 35.487864 -299.760386)
		(end 34.330386 -300.917864)
		(width 0.14478)
		(layer "In11.Cu")
		(net "M_F_CPU1_SB_DQ<16>")
	)
	(segment
		(start 24.688038 -300.610524)
		(end 24.403812 -300.326298)
		(width 0.14478)
		(layer "In11.Cu")
		(net "M_F_CPU1_SB_DQ<16>")
	)
	(segment
		(start 45.020738 -300.077124)
		(end 44.704 -299.760386)
		(width 0.14478)
		(layer "In11.Cu")
		(net "M_F_CPU1_SB_DQ<16>")
	)
	(segment
		(start 72.518524 -287.057338)
		(end 72.3138 -287.057338)
		(width 0.14478)
		(layer "In11.Cu")
		(net "M_F_CPU1_SB_DQ<16>")
	)
	(segment
		(start 52.18938 -299.760386)
		(end 51.64836 -299.760386)
		(width 0.14478)
		(layer "In11.Cu")
		(net "M_F_CPU1_SB_DQ<16>")
	)
	(segment
		(start 45.576998 -299.760386)
		(end 45.26026 -300.077124)
		(width 0.14478)
		(layer "In11.Cu")
		(net "M_F_CPU1_SB_DQ<16>")
	)
	(segment
		(start 25.528778 -300.610524)
		(end 24.688038 -300.610524)
		(width 0.14478)
		(layer "In11.Cu")
		(net "M_F_CPU1_SB_DQ<16>")
	)
	(segment
		(start 79.838804 -284.128718)
		(end 79.825088 -284.136592)
		(width 0.0889)
		(layer "In11.Cu")
		(net "M_F_CPU1_SB_DQ<16>")
	)
	(segment
		(start 48.959262 -300.610524)
		(end 48.644302 -300.925484)
		(width 0.14478)
		(layer "In11.Cu")
		(net "M_F_CPU1_SB_DQ<16>")
	)
	(segment
		(start 23.454106 -300.489112)
		(end 23.291292 -300.326298)
		(width 0.14478)
		(layer "In11.Cu")
		(net "M_F_CPU1_SB_DQ<16>")
	)
	(segment
		(start 45.987208 -299.760386)
		(end 45.576998 -299.760386)
		(width 0.14478)
		(layer "In11.Cu")
		(net "M_F_CPU1_SB_DQ<16>")
	)
	(segment
		(start 54.91988 -300.922944)
		(end 54.60746 -300.610524)
		(width 0.14478)
		(layer "In11.Cu")
		(net "M_F_CPU1_SB_DQ<16>")
	)
	(segment
		(start 44.000928 -299.760386)
		(end 43.67911 -300.082204)
		(width 0.14478)
		(layer "In11.Cu")
		(net "M_F_CPU1_SB_DQ<16>")
	)
	(segment
		(start 73.094088 -286.27705)
		(end 72.893682 -286.076644)
		(width 0.14478)
		(layer "In11.Cu")
		(net "M_F_CPU1_SB_DQ<16>")
	)
	(segment
		(start 73.298812 -286.27705)
		(end 73.094088 -286.27705)
		(width 0.14478)
		(layer "In11.Cu")
		(net "M_F_CPU1_SB_DQ<16>")
	)
	(segment
		(start 72.688958 -286.076644)
		(end 72.503538 -286.262064)
		(width 0.14478)
		(layer "In11.Cu")
		(net "M_F_CPU1_SB_DQ<16>")
	)
	(segment
		(start 26.04897 -300.320964)
		(end 25.818338 -300.320964)
		(width 0.14478)
		(layer "In11.Cu")
		(net "M_F_CPU1_SB_DQ<16>")
	)
	(segment
		(start 41.531286 -300.917864)
		(end 41.282366 -300.917864)
		(width 0.14478)
		(layer "In11.Cu")
		(net "M_F_CPU1_SB_DQ<16>")
	)
	(segment
		(start 51.331622 -300.077124)
		(end 51.0921 -300.077124)
		(width 0.14478)
		(layer "In11.Cu")
		(net "M_F_CPU1_SB_DQ<16>")
	)
	(segment
		(start 80.778096 -284.128972)
		(end 80.769714 -284.133798)
		(width 0.0889)
		(layer "In11.Cu")
		(net "M_F_CPU1_SB_DQ<16>")
	)
	(segment
		(start 54.60746 -300.610524)
		(end 54.201822 -300.610524)
		(width 0.14478)
		(layer "In11.Cu")
		(net "M_F_CPU1_SB_DQ<16>")
	)
	(segment
		(start 55.16372 -300.922944)
		(end 54.91988 -300.922944)
		(width 0.14478)
		(layer "In11.Cu")
		(net "M_F_CPU1_SB_DQ<16>")
	)
	(segment
		(start 79.850742 -284.12186)
		(end 79.838804 -284.128718)
		(width 0.0889)
		(layer "In11.Cu")
		(net "M_F_CPU1_SB_DQ<16>")
	)
	(segment
		(start 48.088042 -300.610524)
		(end 46.837346 -300.610524)
		(width 0.14478)
		(layer "In11.Cu")
		(net "M_F_CPU1_SB_DQ<16>")
	)
	(segment
		(start 78.750922 -284.15742)
		(end 77.945996 -284.15742)
		(width 0.0889)
		(layer "In11.Cu")
		(net "M_F_CPU1_SB_DQ<16>")
	)
	(segment
		(start 55.47614 -300.610524)
		(end 55.16372 -300.922944)
		(width 0.14478)
		(layer "In11.Cu")
		(net "M_F_CPU1_SB_DQ<16>")
	)
	(segment
		(start 40.975026 -300.610524)
		(end 39.712646 -300.610524)
		(width 0.14478)
		(layer "In11.Cu")
		(net "M_F_CPU1_SB_DQ<16>")
	)
	(segment
		(start 24.403812 -300.326298)
		(end 24.17318 -300.326298)
		(width 0.14478)
		(layer "In11.Cu")
		(net "M_F_CPU1_SB_DQ<16>")
	)
	(segment
		(start 79.47533 -284.134814)
		(end 79.397098 -284.09265)
		(width 0.0889)
		(layer "In11.Cu")
		(net "M_F_CPU1_SB_DQ<16>")
	)
	(segment
		(start 72.503538 -286.466788)
		(end 72.703944 -286.667194)
		(width 0.14478)
		(layer "In11.Cu")
		(net "M_F_CPU1_SB_DQ<16>")
	)
	(segment
		(start 24.010366 -300.818804)
		(end 23.847552 -300.981618)
		(width 0.14478)
		(layer "In11.Cu")
		(net "M_F_CPU1_SB_DQ<16>")
	)
	(segment
		(start 58.989214 -298.601892)
		(end 56.980582 -300.610524)
		(width 0.14478)
		(layer "In11.Cu")
		(net "M_F_CPU1_SB_DQ<16>")
	)
	(segment
		(start 71.90867 -286.856932)
		(end 60.16371 -298.601892)
		(width 0.14478)
		(layer "In11.Cu")
		(net "M_F_CPU1_SB_DQ<16>")
	)
	(segment
		(start 31.569406 -300.917864)
		(end 31.320486 -300.917864)
		(width 0.14478)
		(layer "In11.Cu")
		(net "M_F_CPU1_SB_DQ<16>")
	)
	(segment
		(start 31.320486 -300.917864)
		(end 30.163008 -299.760386)
		(width 0.14478)
		(layer "In11.Cu")
		(net "M_F_CPU1_SB_DQ<16>")
	)
	(segment
		(start 53.351684 -299.760386)
		(end 53.054758 -299.760386)
		(width 0.14478)
		(layer "In11.Cu")
		(net "M_F_CPU1_SB_DQ<16>")
	)
	(segment
		(start 74.0791 -285.496762)
		(end 73.874376 -285.496762)
		(width 0.14478)
		(layer "In11.Cu")
		(net "M_F_CPU1_SB_DQ<16>")
	)
	(segment
		(start 56.58866 -300.610524)
		(end 56.27624 -300.922944)
		(width 0.14478)
		(layer "In11.Cu")
		(net "M_F_CPU1_SB_DQ<16>")
	)
	(segment
		(start 25.818338 -300.320964)
		(end 25.528778 -300.610524)
		(width 0.14478)
		(layer "In11.Cu")
		(net "M_F_CPU1_SB_DQ<16>")
	)
	(segment
		(start 22.897846 -300.818804)
		(end 22.735032 -300.981618)
		(width 0.14478)
		(layer "In11.Cu")
		(net "M_F_CPU1_SB_DQ<16>")
	)
	(segment
		(start 72.703944 -286.667194)
		(end 72.703944 -286.871918)
		(width 0.14478)
		(layer "In11.Cu")
		(net "M_F_CPU1_SB_DQ<16>")
	)
	(segment
		(start 22.735032 -300.981618)
		(end 22.5044 -300.981618)
		(width 0.14478)
		(layer "In11.Cu")
		(net "M_F_CPU1_SB_DQ<16>")
	)
	(segment
		(start 79.218028 -284.066234)
		(end 78.796388 -284.152848)
		(width 0.0889)
		(layer "In11.Cu")
		(net "M_F_CPU1_SB_DQ<16>")
	)
	(segment
		(start 72.703944 -286.871918)
		(end 72.518524 -287.057338)
		(width 0.14478)
		(layer "In11.Cu")
		(net "M_F_CPU1_SB_DQ<16>")
	)
	(segment
		(start 23.61692 -300.981618)
		(end 23.454106 -300.818804)
		(width 0.14478)
		(layer "In11.Cu")
		(net "M_F_CPU1_SB_DQ<16>")
	)
	(segment
		(start 44.704 -299.760386)
		(end 44.000928 -299.760386)
		(width 0.14478)
		(layer "In11.Cu")
		(net "M_F_CPU1_SB_DQ<16>")
	)
	(segment
		(start 77.493114 -283.969968)
		(end 76.817982 -283.969968)
		(width 0.0889)
		(layer "In11.Cu")
		(net "M_F_CPU1_SB_DQ<16>")
	)
	(segment
		(start 52.74564 -300.069504)
		(end 52.498498 -300.069504)
		(width 0.14478)
		(layer "In11.Cu")
		(net "M_F_CPU1_SB_DQ<16>")
	)
	(segment
		(start 48.644302 -300.925484)
		(end 48.403002 -300.925484)
		(width 0.14478)
		(layer "In11.Cu")
		(net "M_F_CPU1_SB_DQ<16>")
	)
	(segment
		(start 33.975294 -300.917864)
		(end 33.667954 -300.610524)
		(width 0.14478)
		(layer "In11.Cu")
		(net "M_F_CPU1_SB_DQ<16>")
	)
	(segment
		(start 73.283826 -285.6865)
		(end 73.484232 -285.886906)
		(width 0.14478)
		(layer "In11.Cu")
		(net "M_F_CPU1_SB_DQ<16>")
	)
	(segment
		(start 48.403002 -300.925484)
		(end 48.088042 -300.610524)
		(width 0.14478)
		(layer "In11.Cu")
		(net "M_F_CPU1_SB_DQ<16>")
	)
	(segment
		(start 56.980582 -300.610524)
		(end 56.58866 -300.610524)
		(width 0.14478)
		(layer "In11.Cu")
		(net "M_F_CPU1_SB_DQ<16>")
	)
	(segment
		(start 26.245312 -300.839378)
		(end 26.245312 -300.517306)
		(width 0.14478)
		(layer "In11.Cu")
		(net "M_F_CPU1_SB_DQ<16>")
	)
	(segment
		(start 51.0921 -300.077124)
		(end 50.775362 -299.760386)
		(width 0.14478)
		(layer "In11.Cu")
		(net "M_F_CPU1_SB_DQ<16>")
	)
	(segment
		(start 74.26452 -285.311342)
		(end 74.0791 -285.496762)
		(width 0.14478)
		(layer "In11.Cu")
		(net "M_F_CPU1_SB_DQ<16>")
	)
	(segment
		(start 56.27624 -300.922944)
		(end 56.0324 -300.922944)
		(width 0.14478)
		(layer "In11.Cu")
		(net "M_F_CPU1_SB_DQ<16>")
	)
	(segment
		(start 22.897846 -300.489112)
		(end 22.897846 -300.818804)
		(width 0.14478)
		(layer "In11.Cu")
		(net "M_F_CPU1_SB_DQ<16>")
	)
	(segment
		(start 23.847552 -300.981618)
		(end 23.61692 -300.981618)
		(width 0.14478)
		(layer "In11.Cu")
		(net "M_F_CPU1_SB_DQ<16>")
	)
	(segment
		(start 72.503538 -286.262064)
		(end 72.503538 -286.466788)
		(width 0.14478)
		(layer "In11.Cu")
		(net "M_F_CPU1_SB_DQ<16>")
	)
	(segment
		(start 52.498498 -300.069504)
		(end 52.18938 -299.760386)
		(width 0.14478)
		(layer "In11.Cu")
		(net "M_F_CPU1_SB_DQ<16>")
	)
	(segment
		(start 43.12285 -299.760386)
		(end 42.688764 -299.760386)
		(width 0.14478)
		(layer "In11.Cu")
		(net "M_F_CPU1_SB_DQ<16>")
	)
	(segment
		(start 39.712646 -300.610524)
		(end 39.392606 -300.930564)
		(width 0.14478)
		(layer "In11.Cu")
		(net "M_F_CPU1_SB_DQ<16>")
	)
	(segment
		(start 49.641506 -300.610524)
		(end 48.959262 -300.610524)
		(width 0.14478)
		(layer "In11.Cu")
		(net "M_F_CPU1_SB_DQ<16>")
	)
	(segment
		(start 73.283826 -285.481776)
		(end 73.283826 -285.6865)
		(width 0.14478)
		(layer "In11.Cu")
		(net "M_F_CPU1_SB_DQ<16>")
	)
	(segment
		(start 24.17318 -300.326298)
		(end 24.010366 -300.489112)
		(width 0.14478)
		(layer "In11.Cu")
		(net "M_F_CPU1_SB_DQ<16>")
	)
	(segment
		(start 55.71998 -300.610524)
		(end 55.47614 -300.610524)
		(width 0.14478)
		(layer "In11.Cu")
		(net "M_F_CPU1_SB_DQ<16>")
	)
	(segment
		(start 23.291292 -300.326298)
		(end 23.06066 -300.326298)
		(width 0.14478)
		(layer "In11.Cu")
		(net "M_F_CPU1_SB_DQ<16>")
	)
	(segment
		(start 72.893682 -286.076644)
		(end 72.688958 -286.076644)
		(width 0.14478)
		(layer "In11.Cu")
		(net "M_F_CPU1_SB_DQ<16>")
	)
	(segment
		(start 22.5044 -300.981618)
		(end 21.70811 -300.185328)
		(width 0.14478)
		(layer "In11.Cu")
		(net "M_F_CPU1_SB_DQ<16>")
	)
	(segment
		(start 26.408126 -301.002192)
		(end 26.245312 -300.839378)
		(width 0.14478)
		(layer "In11.Cu")
		(net "M_F_CPU1_SB_DQ<16>")
	)
	(segment
		(start 74.26452 -285.106618)
		(end 74.26452 -285.311342)
		(width 0.14478)
		(layer "In11.Cu")
		(net "M_F_CPU1_SB_DQ<16>")
	)
	(segment
		(start 73.67397 -285.296356)
		(end 73.469246 -285.296356)
		(width 0.14478)
		(layer "In11.Cu")
		(net "M_F_CPU1_SB_DQ<16>")
	)
	(arc
		(start 77.945996 -284.15742)
		(mid 77.781045 -284.124609)
		(end 77.641196 -284.031182)
		(width 0.0889)
		(layer "In11.Cu")
		(net "M_F_CPU1_SB_DQ<16>")
	)
	(arc
		(start 79.825088 -284.136592)
		(mid 79.649985 -284.179268)
		(end 79.47533 -284.134814)
		(width 0.0889)
		(layer "In11.Cu")
		(net "M_F_CPU1_SB_DQ<16>")
	)
	(arc
		(start 81.344008 -284.128972)
		(mid 81.061052 -284.052795)
		(end 80.778096 -284.128972)
		(width 0.0889)
		(layer "In11.Cu")
		(net "M_F_CPU1_SB_DQ<16>")
	)
	(arc
		(start 84.163916 -284.128972)
		(mid 83.88096 -284.052795)
		(end 83.598004 -284.128972)
		(width 0.0889)
		(layer "In11.Cu")
		(net "M_F_CPU1_SB_DQ<16>")
	)
	(arc
		(start 78.796388 -284.152848)
		(mid 78.773768 -284.156255)
		(end 78.750922 -284.15742)
		(width 0.0889)
		(layer "In11.Cu")
		(net "M_F_CPU1_SB_DQ<16>")
	)
	(arc
		(start 81.71815 -284.128972)
		(mid 81.535899 -284.179322)
		(end 81.35239 -284.133798)
		(width 0.0889)
		(layer "In11.Cu")
		(net "M_F_CPU1_SB_DQ<16>")
	)
	(arc
		(start 80.769714 -284.133798)
		(mid 80.586206 -284.179292)
		(end 80.403954 -284.128972)
		(width 0.0889)
		(layer "In11.Cu")
		(net "M_F_CPU1_SB_DQ<16>")
	)
	(arc
		(start 84.482686 -284.155134)
		(mid 84.320354 -284.177952)
		(end 84.163916 -284.128972)
		(width 0.0889)
		(layer "In11.Cu")
		(net "M_F_CPU1_SB_DQ<16>")
	)
	(arc
		(start 82.284062 -284.128972)
		(mid 82.001106 -284.052795)
		(end 81.71815 -284.128972)
		(width 0.0889)
		(layer "In11.Cu")
		(net "M_F_CPU1_SB_DQ<16>")
	)
	(arc
		(start 80.403954 -284.128972)
		(mid 80.128276 -284.052842)
		(end 79.850742 -284.12186)
		(width 0.0889)
		(layer "In11.Cu")
		(net "M_F_CPU1_SB_DQ<16>")
	)
	(arc
		(start 79.397098 -284.09265)
		(mid 79.309887 -284.063643)
		(end 79.218028 -284.066234)
		(width 0.0889)
		(layer "In11.Cu")
		(net "M_F_CPU1_SB_DQ<16>")
	)
	(arc
		(start 77.641196 -284.031182)
		(mid 77.57324 -283.985869)
		(end 77.493114 -283.969968)
		(width 0.0889)
		(layer "In11.Cu")
		(net "M_F_CPU1_SB_DQ<16>")
	)
	(arc
		(start 82.65795 -284.128972)
		(mid 82.471006 -284.179227)
		(end 82.284062 -284.128972)
		(width 0.0889)
		(layer "In11.Cu")
		(net "M_F_CPU1_SB_DQ<16>")
	)
	(arc
		(start 83.223862 -284.128972)
		(mid 82.940906 -284.052795)
		(end 82.65795 -284.128972)
		(width 0.0889)
		(layer "In11.Cu")
		(net "M_F_CPU1_SB_DQ<16>")
	)
	(arc
		(start 83.589622 -284.133798)
		(mid 83.406114 -284.179292)
		(end 83.223862 -284.128972)
		(width 0.0889)
		(layer "In11.Cu")
		(net "M_F_CPU1_SB_DQ<16>")
	)
	(segment
		(start 86.69782 -283.540454)
		(end 86.230968 -283.806392)
		(width 0.10668)
		(layer "F.Cu")
		(net "M_F_CPU1_SB_DQ<15>")
	)
	(segment
		(start 74.074528 -283.911294)
		(end 75.963526 -283.911294)
		(width 0.14478)
		(layer "In11.Cu")
		(net "M_F_CPU1_SB_DQ<15>")
	)
	(segment
		(start 80.39354 -283.489908)
		(end 80.403954 -283.483812)
		(width 0.0889)
		(layer "In11.Cu")
		(net "M_F_CPU1_SB_DQ<15>")
	)
	(segment
		(start 20.083272 -299.760386)
		(end 20.228052 -299.615606)
		(width 0.14478)
		(layer "In11.Cu")
		(net "M_F_CPU1_SB_DQ<15>")
	)
	(segment
		(start 19.125184 -299.511466)
		(end 19.269964 -299.366686)
		(width 0.14478)
		(layer "In11.Cu")
		(net "M_F_CPU1_SB_DQ<15>")
	)
	(segment
		(start 85.981032 -283.515562)
		(end 86.077044 -283.540962)
		(width 0.0889)
		(layer "In11.Cu")
		(net "M_F_CPU1_SB_DQ<15>")
	)
	(segment
		(start 50.730912 -298.910248)
		(end 53.095398 -298.910248)
		(width 0.14478)
		(layer "In11.Cu")
		(net "M_F_CPU1_SB_DQ<15>")
	)
	(segment
		(start 19.125184 -299.615606)
		(end 19.125184 -299.511466)
		(width 0.14478)
		(layer "In11.Cu")
		(net "M_F_CPU1_SB_DQ<15>")
	)
	(segment
		(start 41.59631 -299.760386)
		(end 42.863008 -298.914058)
		(width 0.14478)
		(layer "In11.Cu")
		(net "M_F_CPU1_SB_DQ<15>")
	)
	(segment
		(start 19.676618 -299.511466)
		(end 19.676618 -299.615606)
		(width 0.14478)
		(layer "In11.Cu")
		(net "M_F_CPU1_SB_DQ<15>")
	)
	(segment
		(start 20.779486 -299.615606)
		(end 20.924266 -299.760386)
		(width 0.14478)
		(layer "In11.Cu")
		(net "M_F_CPU1_SB_DQ<15>")
	)
	(segment
		(start 45.745654 -298.914058)
		(end 47.012098 -299.760386)
		(width 0.14478)
		(layer "In11.Cu")
		(net "M_F_CPU1_SB_DQ<15>")
	)
	(segment
		(start 31.448756 -299.760386)
		(end 34.485834 -299.760386)
		(width 0.14478)
		(layer "In11.Cu")
		(net "M_F_CPU1_SB_DQ<15>")
	)
	(segment
		(start 59.93511 -298.050712)
		(end 74.074528 -283.911294)
		(width 0.14478)
		(layer "In11.Cu")
		(net "M_F_CPU1_SB_DQ<15>")
	)
	(segment
		(start 18.032984 -299.760386)
		(end 18.980404 -299.760386)
		(width 0.14478)
		(layer "In11.Cu")
		(net "M_F_CPU1_SB_DQ<15>")
	)
	(segment
		(start 75.963526 -283.911294)
		(end 76.480416 -283.911294)
		(width 0.0889)
		(layer "In11.Cu")
		(net "M_F_CPU1_SB_DQ<15>")
	)
	(segment
		(start 19.531838 -299.366686)
		(end 19.676618 -299.511466)
		(width 0.14478)
		(layer "In11.Cu")
		(net "M_F_CPU1_SB_DQ<15>")
	)
	(segment
		(start 18.980404 -299.760386)
		(end 19.125184 -299.615606)
		(width 0.14478)
		(layer "In11.Cu")
		(net "M_F_CPU1_SB_DQ<15>")
	)
	(segment
		(start 49.458626 -299.760386)
		(end 50.730912 -298.910248)
		(width 0.14478)
		(layer "In11.Cu")
		(net "M_F_CPU1_SB_DQ<15>")
	)
	(segment
		(start 76.480416 -283.911294)
		(end 76.831698 -283.560012)
		(width 0.0889)
		(layer "In11.Cu")
		(net "M_F_CPU1_SB_DQ<15>")
	)
	(segment
		(start 57.051194 -299.760386)
		(end 58.760868 -298.050712)
		(width 0.14478)
		(layer "In11.Cu")
		(net "M_F_CPU1_SB_DQ<15>")
	)
	(segment
		(start 58.760868 -298.050712)
		(end 59.93511 -298.050712)
		(width 0.14478)
		(layer "In11.Cu")
		(net "M_F_CPU1_SB_DQ<15>")
	)
	(segment
		(start 47.012098 -299.760386)
		(end 49.458626 -299.760386)
		(width 0.14478)
		(layer "In11.Cu")
		(net "M_F_CPU1_SB_DQ<15>")
	)
	(segment
		(start 79.463646 -283.483812)
		(end 79.472028 -283.478986)
		(width 0.0889)
		(layer "In11.Cu")
		(net "M_F_CPU1_SB_DQ<15>")
	)
	(segment
		(start 35.75812 -298.910248)
		(end 37.869622 -298.910248)
		(width 0.14478)
		(layer "In11.Cu")
		(net "M_F_CPU1_SB_DQ<15>")
	)
	(segment
		(start 20.779486 -299.511466)
		(end 20.779486 -299.615606)
		(width 0.14478)
		(layer "In11.Cu")
		(net "M_F_CPU1_SB_DQ<15>")
	)
	(segment
		(start 39.142162 -299.760386)
		(end 41.59631 -299.760386)
		(width 0.14478)
		(layer "In11.Cu")
		(net "M_F_CPU1_SB_DQ<15>")
	)
	(segment
		(start 76.831698 -283.560012)
		(end 78.24089 -283.560012)
		(width 0.0889)
		(layer "In11.Cu")
		(net "M_F_CPU1_SB_DQ<15>")
	)
	(segment
		(start 34.485834 -299.760386)
		(end 35.75812 -298.910248)
		(width 0.14478)
		(layer "In11.Cu")
		(net "M_F_CPU1_SB_DQ<15>")
	)
	(segment
		(start 30.176216 -298.910248)
		(end 31.448756 -299.760386)
		(width 0.14478)
		(layer "In11.Cu")
		(net "M_F_CPU1_SB_DQ<15>")
	)
	(segment
		(start 78.889606 -283.478986)
		(end 78.897988 -283.483812)
		(width 0.0889)
		(layer "In11.Cu")
		(net "M_F_CPU1_SB_DQ<15>")
	)
	(segment
		(start 28.071064 -298.910248)
		(end 30.176216 -298.910248)
		(width 0.14478)
		(layer "In11.Cu")
		(net "M_F_CPU1_SB_DQ<15>")
	)
	(segment
		(start 42.863008 -298.914058)
		(end 45.745654 -298.914058)
		(width 0.14478)
		(layer "In11.Cu")
		(net "M_F_CPU1_SB_DQ<15>")
	)
	(segment
		(start 37.869622 -298.910248)
		(end 39.142162 -299.760386)
		(width 0.14478)
		(layer "In11.Cu")
		(net "M_F_CPU1_SB_DQ<15>")
	)
	(segment
		(start 19.676618 -299.615606)
		(end 19.821398 -299.760386)
		(width 0.14478)
		(layer "In11.Cu")
		(net "M_F_CPU1_SB_DQ<15>")
	)
	(segment
		(start 83.589622 -283.478986)
		(end 83.598004 -283.483812)
		(width 0.0889)
		(layer "In11.Cu")
		(net "M_F_CPU1_SB_DQ<15>")
	)
	(segment
		(start 54.367938 -299.760386)
		(end 57.051194 -299.760386)
		(width 0.14478)
		(layer "In11.Cu")
		(net "M_F_CPU1_SB_DQ<15>")
	)
	(segment
		(start 19.821398 -299.760386)
		(end 20.083272 -299.760386)
		(width 0.14478)
		(layer "In11.Cu")
		(net "M_F_CPU1_SB_DQ<15>")
	)
	(segment
		(start 20.924266 -299.760386)
		(end 26.798524 -299.760386)
		(width 0.14478)
		(layer "In11.Cu")
		(net "M_F_CPU1_SB_DQ<15>")
	)
	(segment
		(start 86.077044 -283.540962)
		(end 86.230968 -283.806392)
		(width 0.0889)
		(layer "In11.Cu")
		(net "M_F_CPU1_SB_DQ<15>")
	)
	(segment
		(start 53.095398 -298.910248)
		(end 54.367938 -299.760386)
		(width 0.14478)
		(layer "In11.Cu")
		(net "M_F_CPU1_SB_DQ<15>")
	)
	(segment
		(start 20.228052 -299.511466)
		(end 20.372832 -299.366686)
		(width 0.14478)
		(layer "In11.Cu")
		(net "M_F_CPU1_SB_DQ<15>")
	)
	(segment
		(start 20.372832 -299.366686)
		(end 20.634706 -299.366686)
		(width 0.14478)
		(layer "In11.Cu")
		(net "M_F_CPU1_SB_DQ<15>")
	)
	(segment
		(start 81.344008 -283.483812)
		(end 81.35239 -283.478986)
		(width 0.0889)
		(layer "In11.Cu")
		(net "M_F_CPU1_SB_DQ<15>")
	)
	(segment
		(start 19.269964 -299.366686)
		(end 19.531838 -299.366686)
		(width 0.14478)
		(layer "In11.Cu")
		(net "M_F_CPU1_SB_DQ<15>")
	)
	(segment
		(start 17.608042 -299.335444)
		(end 18.032984 -299.760386)
		(width 0.14478)
		(layer "In11.Cu")
		(net "M_F_CPU1_SB_DQ<15>")
	)
	(segment
		(start 20.634706 -299.366686)
		(end 20.779486 -299.511466)
		(width 0.14478)
		(layer "In11.Cu")
		(net "M_F_CPU1_SB_DQ<15>")
	)
	(segment
		(start 85.10397 -283.483812)
		(end 85.112352 -283.478986)
		(width 0.0889)
		(layer "In11.Cu")
		(net "M_F_CPU1_SB_DQ<15>")
	)
	(segment
		(start 80.769714 -283.478986)
		(end 80.778096 -283.483812)
		(width 0.0889)
		(layer "In11.Cu")
		(net "M_F_CPU1_SB_DQ<15>")
	)
	(segment
		(start 78.897988 -283.483812)
		(end 78.908402 -283.489908)
		(width 0.0889)
		(layer "In11.Cu")
		(net "M_F_CPU1_SB_DQ<15>")
	)
	(segment
		(start 84.529676 -283.478986)
		(end 84.538058 -283.483812)
		(width 0.0889)
		(layer "In11.Cu")
		(net "M_F_CPU1_SB_DQ<15>")
	)
	(segment
		(start 20.228052 -299.615606)
		(end 20.228052 -299.511466)
		(width 0.14478)
		(layer "In11.Cu")
		(net "M_F_CPU1_SB_DQ<15>")
	)
	(segment
		(start 26.798524 -299.760386)
		(end 28.071064 -298.910248)
		(width 0.14478)
		(layer "In11.Cu")
		(net "M_F_CPU1_SB_DQ<15>")
	)
	(arc
		(start 80.403954 -283.483812)
		(mid 80.586205 -283.433462)
		(end 80.769714 -283.478986)
		(width 0.0889)
		(layer "In11.Cu")
		(net "M_F_CPU1_SB_DQ<15>")
	)
	(arc
		(start 85.112352 -283.478986)
		(mid 85.29586 -283.433492)
		(end 85.478112 -283.483812)
		(width 0.0889)
		(layer "In11.Cu")
		(net "M_F_CPU1_SB_DQ<15>")
	)
	(arc
		(start 84.538058 -283.483812)
		(mid 84.821014 -283.559989)
		(end 85.10397 -283.483812)
		(width 0.0889)
		(layer "In11.Cu")
		(net "M_F_CPU1_SB_DQ<15>")
	)
	(arc
		(start 78.24089 -283.560012)
		(mid 78.387416 -283.540642)
		(end 78.523846 -283.483812)
		(width 0.0889)
		(layer "In11.Cu")
		(net "M_F_CPU1_SB_DQ<15>")
	)
	(arc
		(start 80.778096 -283.483812)
		(mid 81.061052 -283.559989)
		(end 81.344008 -283.483812)
		(width 0.0889)
		(layer "In11.Cu")
		(net "M_F_CPU1_SB_DQ<15>")
	)
	(arc
		(start 83.598004 -283.483812)
		(mid 83.88096 -283.559989)
		(end 84.163916 -283.483812)
		(width 0.0889)
		(layer "In11.Cu")
		(net "M_F_CPU1_SB_DQ<15>")
	)
	(arc
		(start 78.523846 -283.483812)
		(mid 78.706097 -283.433462)
		(end 78.889606 -283.478986)
		(width 0.0889)
		(layer "In11.Cu")
		(net "M_F_CPU1_SB_DQ<15>")
	)
	(arc
		(start 78.908402 -283.489908)
		(mid 79.186834 -283.560006)
		(end 79.463646 -283.483812)
		(width 0.0889)
		(layer "In11.Cu")
		(net "M_F_CPU1_SB_DQ<15>")
	)
	(arc
		(start 84.163916 -283.483812)
		(mid 84.346167 -283.433462)
		(end 84.529676 -283.478986)
		(width 0.0889)
		(layer "In11.Cu")
		(net "M_F_CPU1_SB_DQ<15>")
	)
	(arc
		(start 82.65795 -283.483812)
		(mid 82.940906 -283.559989)
		(end 83.223862 -283.483812)
		(width 0.0889)
		(layer "In11.Cu")
		(net "M_F_CPU1_SB_DQ<15>")
	)
	(arc
		(start 81.35239 -283.478986)
		(mid 81.535898 -283.433492)
		(end 81.71815 -283.483812)
		(width 0.0889)
		(layer "In11.Cu")
		(net "M_F_CPU1_SB_DQ<15>")
	)
	(arc
		(start 85.478112 -283.483812)
		(mid 85.725825 -283.559032)
		(end 85.981032 -283.515562)
		(width 0.0889)
		(layer "In11.Cu")
		(net "M_F_CPU1_SB_DQ<15>")
	)
	(arc
		(start 79.472028 -283.478986)
		(mid 79.655536 -283.433492)
		(end 79.837788 -283.483812)
		(width 0.0889)
		(layer "In11.Cu")
		(net "M_F_CPU1_SB_DQ<15>")
	)
	(arc
		(start 81.71815 -283.483812)
		(mid 82.001106 -283.559989)
		(end 82.284062 -283.483812)
		(width 0.0889)
		(layer "In11.Cu")
		(net "M_F_CPU1_SB_DQ<15>")
	)
	(arc
		(start 79.837788 -283.483812)
		(mid 80.114855 -283.560083)
		(end 80.39354 -283.489908)
		(width 0.0889)
		(layer "In11.Cu")
		(net "M_F_CPU1_SB_DQ<15>")
	)
	(arc
		(start 82.284062 -283.483812)
		(mid 82.471006 -283.433557)
		(end 82.65795 -283.483812)
		(width 0.0889)
		(layer "In11.Cu")
		(net "M_F_CPU1_SB_DQ<15>")
	)
	(arc
		(start 83.223862 -283.483812)
		(mid 83.406113 -283.433462)
		(end 83.589622 -283.478986)
		(width 0.0889)
		(layer "In11.Cu")
		(net "M_F_CPU1_SB_DQ<15>")
	)
	(segment
		(start 85.287866 -282.730448)
		(end 84.821014 -282.996386)
		(width 0.10668)
		(layer "F.Cu")
		(net "M_F_CPU1_SB_DQ<14>")
	)
	(segment
		(start 82.179668 -282.66898)
		(end 82.18805 -282.673806)
		(width 0.0889)
		(layer "In11.Cu")
		(net "M_F_CPU1_SB_DQ<14>")
	)
	(segment
		(start 50.11801 -298.060364)
		(end 50.968148 -297.210226)
		(width 0.14478)
		(layer "In11.Cu")
		(net "M_F_CPU1_SB_DQ<14>")
	)
	(segment
		(start 53.725318 -298.060364)
		(end 57.429654 -298.060364)
		(width 0.14478)
		(layer "In11.Cu")
		(net "M_F_CPU1_SB_DQ<14>")
	)
	(segment
		(start 20.471384 -297.565826)
		(end 20.733258 -297.565826)
		(width 0.14478)
		(layer "In11.Cu")
		(net "M_F_CPU1_SB_DQ<14>")
	)
	(segment
		(start 84.66709 -282.730956)
		(end 84.821014 -282.996386)
		(width 0.0889)
		(layer "In11.Cu")
		(net "M_F_CPU1_SB_DQ<14>")
	)
	(segment
		(start 46.524926 -298.060364)
		(end 50.11801 -298.060364)
		(width 0.14478)
		(layer "In11.Cu")
		(net "M_F_CPU1_SB_DQ<14>")
	)
	(segment
		(start 77.781658 -282.363164)
		(end 78.168754 -282.75026)
		(width 0.0889)
		(layer "In11.Cu")
		(net "M_F_CPU1_SB_DQ<14>")
	)
	(segment
		(start 20.878038 -297.915584)
		(end 21.022818 -298.060364)
		(width 0.14478)
		(layer "In11.Cu")
		(net "M_F_CPU1_SB_DQ<14>")
	)
	(segment
		(start 30.053788 -297.210226)
		(end 30.903926 -298.060364)
		(width 0.14478)
		(layer "In11.Cu")
		(net "M_F_CPU1_SB_DQ<14>")
	)
	(segment
		(start 20.733258 -297.565826)
		(end 20.878038 -297.710606)
		(width 0.14478)
		(layer "In11.Cu")
		(net "M_F_CPU1_SB_DQ<14>")
	)
	(segment
		(start 19.77517 -297.915584)
		(end 19.91995 -298.060364)
		(width 0.14478)
		(layer "In11.Cu")
		(net "M_F_CPU1_SB_DQ<14>")
	)
	(segment
		(start 19.91995 -298.060364)
		(end 20.181824 -298.060364)
		(width 0.14478)
		(layer "In11.Cu")
		(net "M_F_CPU1_SB_DQ<14>")
	)
	(segment
		(start 20.878038 -297.710606)
		(end 20.878038 -297.915584)
		(width 0.14478)
		(layer "In11.Cu")
		(net "M_F_CPU1_SB_DQ<14>")
	)
	(segment
		(start 60.249054 -296.464736)
		(end 73.711816 -283.001974)
		(width 0.14478)
		(layer "In11.Cu")
		(net "M_F_CPU1_SB_DQ<14>")
	)
	(segment
		(start 21.022818 -298.060364)
		(end 27.319986 -298.060364)
		(width 0.14478)
		(layer "In11.Cu")
		(net "M_F_CPU1_SB_DQ<14>")
	)
	(segment
		(start 43.029124 -297.210226)
		(end 45.674788 -297.210226)
		(width 0.14478)
		(layer "In11.Cu")
		(net "M_F_CPU1_SB_DQ<14>")
	)
	(segment
		(start 18.032984 -298.060364)
		(end 19.078956 -298.060364)
		(width 0.14478)
		(layer "In11.Cu")
		(net "M_F_CPU1_SB_DQ<14>")
	)
	(segment
		(start 34.965386 -298.060364)
		(end 35.815524 -297.210226)
		(width 0.14478)
		(layer "In11.Cu")
		(net "M_F_CPU1_SB_DQ<14>")
	)
	(segment
		(start 20.326604 -297.710606)
		(end 20.471384 -297.565826)
		(width 0.14478)
		(layer "In11.Cu")
		(net "M_F_CPU1_SB_DQ<14>")
	)
	(segment
		(start 38.001448 -297.210226)
		(end 38.851586 -298.060364)
		(width 0.14478)
		(layer "In11.Cu")
		(net "M_F_CPU1_SB_DQ<14>")
	)
	(segment
		(start 27.319986 -298.060364)
		(end 28.170124 -297.210226)
		(width 0.14478)
		(layer "In11.Cu")
		(net "M_F_CPU1_SB_DQ<14>")
	)
	(segment
		(start 76.903072 -282.363164)
		(end 77.781658 -282.363164)
		(width 0.0889)
		(layer "In11.Cu")
		(net "M_F_CPU1_SB_DQ<14>")
	)
	(segment
		(start 35.815524 -297.210226)
		(end 38.001448 -297.210226)
		(width 0.14478)
		(layer "In11.Cu")
		(net "M_F_CPU1_SB_DQ<14>")
	)
	(segment
		(start 28.170124 -297.210226)
		(end 30.053788 -297.210226)
		(width 0.14478)
		(layer "In11.Cu")
		(net "M_F_CPU1_SB_DQ<14>")
	)
	(segment
		(start 19.368516 -297.565826)
		(end 19.63039 -297.565826)
		(width 0.14478)
		(layer "In11.Cu")
		(net "M_F_CPU1_SB_DQ<14>")
	)
	(segment
		(start 20.181824 -298.060364)
		(end 20.326604 -297.915584)
		(width 0.14478)
		(layer "In11.Cu")
		(net "M_F_CPU1_SB_DQ<14>")
	)
	(segment
		(start 20.326604 -297.915584)
		(end 20.326604 -297.710606)
		(width 0.14478)
		(layer "In11.Cu")
		(net "M_F_CPU1_SB_DQ<14>")
	)
	(segment
		(start 82.753962 -282.673806)
		(end 82.762344 -282.66898)
		(width 0.0889)
		(layer "In11.Cu")
		(net "M_F_CPU1_SB_DQ<14>")
	)
	(segment
		(start 73.711816 -283.001974)
		(end 75.966066 -283.001974)
		(width 0.14478)
		(layer "In11.Cu")
		(net "M_F_CPU1_SB_DQ<14>")
	)
	(segment
		(start 84.571078 -282.705556)
		(end 84.66709 -282.730956)
		(width 0.0889)
		(layer "In11.Cu")
		(net "M_F_CPU1_SB_DQ<14>")
	)
	(segment
		(start 79.92237 -282.680918)
		(end 79.934308 -282.67406)
		(width 0.0889)
		(layer "In11.Cu")
		(net "M_F_CPU1_SB_DQ<14>")
	)
	(segment
		(start 79.357474 -282.666948)
		(end 79.369158 -282.673806)
		(width 0.0889)
		(layer "In11.Cu")
		(net "M_F_CPU1_SB_DQ<14>")
	)
	(segment
		(start 75.966066 -283.001974)
		(end 76.264262 -283.001974)
		(width 0.0889)
		(layer "In11.Cu")
		(net "M_F_CPU1_SB_DQ<14>")
	)
	(segment
		(start 30.903926 -298.060364)
		(end 34.965386 -298.060364)
		(width 0.14478)
		(layer "In11.Cu")
		(net "M_F_CPU1_SB_DQ<14>")
	)
	(segment
		(start 52.87518 -297.210226)
		(end 53.725318 -298.060364)
		(width 0.14478)
		(layer "In11.Cu")
		(net "M_F_CPU1_SB_DQ<14>")
	)
	(segment
		(start 83.694016 -282.673806)
		(end 83.702398 -282.66898)
		(width 0.0889)
		(layer "In11.Cu")
		(net "M_F_CPU1_SB_DQ<14>")
	)
	(segment
		(start 19.078956 -298.060364)
		(end 19.223736 -297.915584)
		(width 0.14478)
		(layer "In11.Cu")
		(net "M_F_CPU1_SB_DQ<14>")
	)
	(segment
		(start 57.429654 -298.060364)
		(end 59.025282 -296.464736)
		(width 0.14478)
		(layer "In11.Cu")
		(net "M_F_CPU1_SB_DQ<14>")
	)
	(segment
		(start 45.674788 -297.210226)
		(end 46.524926 -298.060364)
		(width 0.14478)
		(layer "In11.Cu")
		(net "M_F_CPU1_SB_DQ<14>")
	)
	(segment
		(start 19.63039 -297.565826)
		(end 19.77517 -297.710606)
		(width 0.14478)
		(layer "In11.Cu")
		(net "M_F_CPU1_SB_DQ<14>")
	)
	(segment
		(start 79.934308 -282.67406)
		(end 79.950564 -282.664662)
		(width 0.0889)
		(layer "In11.Cu")
		(net "M_F_CPU1_SB_DQ<14>")
	)
	(segment
		(start 76.264262 -283.001974)
		(end 76.903072 -282.363164)
		(width 0.0889)
		(layer "In11.Cu")
		(net "M_F_CPU1_SB_DQ<14>")
	)
	(segment
		(start 50.968148 -297.210226)
		(end 52.87518 -297.210226)
		(width 0.14478)
		(layer "In11.Cu")
		(net "M_F_CPU1_SB_DQ<14>")
	)
	(segment
		(start 19.223736 -297.710606)
		(end 19.368516 -297.565826)
		(width 0.14478)
		(layer "In11.Cu")
		(net "M_F_CPU1_SB_DQ<14>")
	)
	(segment
		(start 17.608042 -297.635422)
		(end 18.032984 -298.060364)
		(width 0.14478)
		(layer "In11.Cu")
		(net "M_F_CPU1_SB_DQ<14>")
	)
	(segment
		(start 38.851586 -298.060364)
		(end 42.178986 -298.060364)
		(width 0.14478)
		(layer "In11.Cu")
		(net "M_F_CPU1_SB_DQ<14>")
	)
	(segment
		(start 78.168754 -282.75026)
		(end 78.711044 -282.75026)
		(width 0.0889)
		(layer "In11.Cu")
		(net "M_F_CPU1_SB_DQ<14>")
	)
	(segment
		(start 19.77517 -297.710606)
		(end 19.77517 -297.915584)
		(width 0.14478)
		(layer "In11.Cu")
		(net "M_F_CPU1_SB_DQ<14>")
	)
	(segment
		(start 59.025282 -296.464736)
		(end 60.249054 -296.464736)
		(width 0.14478)
		(layer "In11.Cu")
		(net "M_F_CPU1_SB_DQ<14>")
	)
	(segment
		(start 42.178986 -298.060364)
		(end 43.029124 -297.210226)
		(width 0.14478)
		(layer "In11.Cu")
		(net "M_F_CPU1_SB_DQ<14>")
	)
	(segment
		(start 19.223736 -297.915584)
		(end 19.223736 -297.710606)
		(width 0.14478)
		(layer "In11.Cu")
		(net "M_F_CPU1_SB_DQ<14>")
	)
	(arc
		(start 81.247996 -282.673806)
		(mid 81.530952 -282.749983)
		(end 81.813908 -282.673806)
		(width 0.0889)
		(layer "In11.Cu")
		(net "M_F_CPU1_SB_DQ<14>")
	)
	(arc
		(start 82.762344 -282.66898)
		(mid 82.945852 -282.623486)
		(end 83.128104 -282.673806)
		(width 0.0889)
		(layer "In11.Cu")
		(net "M_F_CPU1_SB_DQ<14>")
	)
	(arc
		(start 81.813908 -282.673806)
		(mid 81.996159 -282.623456)
		(end 82.179668 -282.66898)
		(width 0.0889)
		(layer "In11.Cu")
		(net "M_F_CPU1_SB_DQ<14>")
	)
	(arc
		(start 80.308196 -282.673806)
		(mid 80.591152 -282.749983)
		(end 80.874108 -282.673806)
		(width 0.0889)
		(layer "In11.Cu")
		(net "M_F_CPU1_SB_DQ<14>")
	)
	(arc
		(start 79.369158 -282.673806)
		(mid 79.644836 -282.749936)
		(end 79.92237 -282.680918)
		(width 0.0889)
		(layer "In11.Cu")
		(net "M_F_CPU1_SB_DQ<14>")
	)
	(arc
		(start 78.711044 -282.75026)
		(mid 78.857975 -282.730849)
		(end 78.994762 -282.673806)
		(width 0.0889)
		(layer "In11.Cu")
		(net "M_F_CPU1_SB_DQ<14>")
	)
	(arc
		(start 80.874108 -282.673806)
		(mid 81.061052 -282.623551)
		(end 81.247996 -282.673806)
		(width 0.0889)
		(layer "In11.Cu")
		(net "M_F_CPU1_SB_DQ<14>")
	)
	(arc
		(start 83.128104 -282.673806)
		(mid 83.41106 -282.749983)
		(end 83.694016 -282.673806)
		(width 0.0889)
		(layer "In11.Cu")
		(net "M_F_CPU1_SB_DQ<14>")
	)
	(arc
		(start 84.068158 -282.673806)
		(mid 84.315871 -282.749026)
		(end 84.571078 -282.705556)
		(width 0.0889)
		(layer "In11.Cu")
		(net "M_F_CPU1_SB_DQ<14>")
	)
	(arc
		(start 78.994762 -282.673806)
		(mid 79.17522 -282.623362)
		(end 79.357474 -282.666948)
		(width 0.0889)
		(layer "In11.Cu")
		(net "M_F_CPU1_SB_DQ<14>")
	)
	(arc
		(start 83.702398 -282.66898)
		(mid 83.885906 -282.623486)
		(end 84.068158 -282.673806)
		(width 0.0889)
		(layer "In11.Cu")
		(net "M_F_CPU1_SB_DQ<14>")
	)
	(arc
		(start 82.18805 -282.673806)
		(mid 82.471006 -282.749983)
		(end 82.753962 -282.673806)
		(width 0.0889)
		(layer "In11.Cu")
		(net "M_F_CPU1_SB_DQ<14>")
	)
	(arc
		(start 79.950564 -282.664662)
		(mid 80.130546 -282.623562)
		(end 80.308196 -282.673806)
		(width 0.0889)
		(layer "In11.Cu")
		(net "M_F_CPU1_SB_DQ<14>")
	)
	(segment
		(start 86.22792 -282.730448)
		(end 85.761068 -282.996386)
		(width 0.10668)
		(layer "F.Cu")
		(net "M_F_CPU1_SB_DQ<13>")
	)
	(segment
		(start 82.179668 -283.323792)
		(end 82.18805 -283.318966)
		(width 0.0889)
		(layer "In11.Cu")
		(net "M_F_CPU1_SB_DQ<13>")
	)
	(segment
		(start 23.28418 -298.52112)
		(end 23.446994 -298.683934)
		(width 0.14478)
		(layer "In11.Cu")
		(net "M_F_CPU1_SB_DQ<13>")
	)
	(segment
		(start 55.983124 -298.910502)
		(end 56.127904 -298.765722)
		(width 0.14478)
		(layer "In11.Cu")
		(net "M_F_CPU1_SB_DQ<13>")
	)
	(segment
		(start 24.786082 -298.910502)
		(end 25.333198 -298.910502)
		(width 0.14478)
		(layer "In11.Cu")
		(net "M_F_CPU1_SB_DQ<13>")
	)
	(segment
		(start 23.446994 -299.11167)
		(end 23.609808 -299.274484)
		(width 0.14478)
		(layer "In11.Cu")
		(net "M_F_CPU1_SB_DQ<13>")
	)
	(segment
		(start 24.003254 -299.11167)
		(end 24.003254 -298.683934)
		(width 0.14478)
		(layer "In11.Cu")
		(net "M_F_CPU1_SB_DQ<13>")
	)
	(segment
		(start 26.504392 -299.294804)
		(end 26.888694 -298.910502)
		(width 0.14478)
		(layer "In11.Cu")
		(net "M_F_CPU1_SB_DQ<13>")
	)
	(segment
		(start 24.166068 -298.52112)
		(end 24.3967 -298.52112)
		(width 0.14478)
		(layer "In11.Cu")
		(net "M_F_CPU1_SB_DQ<13>")
	)
	(segment
		(start 83.694016 -283.318966)
		(end 83.702398 -283.323792)
		(width 0.0889)
		(layer "In11.Cu")
		(net "M_F_CPU1_SB_DQ<13>")
	)
	(segment
		(start 56.679338 -298.658026)
		(end 56.679338 -298.765722)
		(width 0.14478)
		(layer "In11.Cu")
		(net "M_F_CPU1_SB_DQ<13>")
	)
	(segment
		(start 56.824118 -298.910502)
		(end 57.265062 -298.910502)
		(width 0.14478)
		(layer "In11.Cu")
		(net "M_F_CPU1_SB_DQ<13>")
	)
	(segment
		(start 41.988994 -298.910502)
		(end 42.839132 -298.060364)
		(width 0.14478)
		(layer "In11.Cu")
		(net "M_F_CPU1_SB_DQ<13>")
	)
	(segment
		(start 23.446994 -298.683934)
		(end 23.446994 -299.11167)
		(width 0.14478)
		(layer "In11.Cu")
		(net "M_F_CPU1_SB_DQ<13>")
	)
	(segment
		(start 48.745902 -298.658026)
		(end 48.890682 -298.513246)
		(width 0.14478)
		(layer "In11.Cu")
		(net "M_F_CPU1_SB_DQ<13>")
	)
	(segment
		(start 23.053548 -298.52112)
		(end 23.28418 -298.52112)
		(width 0.14478)
		(layer "In11.Cu")
		(net "M_F_CPU1_SB_DQ<13>")
	)
	(segment
		(start 50.761392 -298.060364)
		(end 53.081936 -298.060364)
		(width 0.14478)
		(layer "In11.Cu")
		(net "M_F_CPU1_SB_DQ<13>")
	)
	(segment
		(start 26.27376 -299.294804)
		(end 26.504392 -299.294804)
		(width 0.14478)
		(layer "In11.Cu")
		(net "M_F_CPU1_SB_DQ<13>")
	)
	(segment
		(start 49.911254 -298.910502)
		(end 50.761392 -298.060364)
		(width 0.14478)
		(layer "In11.Cu")
		(net "M_F_CPU1_SB_DQ<13>")
	)
	(segment
		(start 48.745902 -298.765722)
		(end 48.745902 -298.658026)
		(width 0.14478)
		(layer "In11.Cu")
		(net "M_F_CPU1_SB_DQ<13>")
	)
	(segment
		(start 26.110946 -299.13199)
		(end 26.27376 -299.294804)
		(width 0.14478)
		(layer "In11.Cu")
		(net "M_F_CPU1_SB_DQ<13>")
	)
	(segment
		(start 22.890734 -298.683934)
		(end 23.053548 -298.52112)
		(width 0.14478)
		(layer "In11.Cu")
		(net "M_F_CPU1_SB_DQ<13>")
	)
	(segment
		(start 28.056332 -298.060364)
		(end 30.16504 -298.060364)
		(width 0.14478)
		(layer "In11.Cu")
		(net "M_F_CPU1_SB_DQ<13>")
	)
	(segment
		(start 33.820862 -299.203364)
		(end 34.113724 -298.910502)
		(width 0.14478)
		(layer "In11.Cu")
		(net "M_F_CPU1_SB_DQ<13>")
	)
	(segment
		(start 22.890734 -299.11167)
		(end 22.890734 -298.683934)
		(width 0.14478)
		(layer "In11.Cu")
		(net "M_F_CPU1_SB_DQ<13>")
	)
	(segment
		(start 54.869588 -298.765722)
		(end 55.014368 -298.910502)
		(width 0.14478)
		(layer "In11.Cu")
		(net "M_F_CPU1_SB_DQ<13>")
	)
	(segment
		(start 73.893172 -283.456634)
		(end 75.973686 -283.456634)
		(width 0.14478)
		(layer "In11.Cu")
		(net "M_F_CPU1_SB_DQ<13>")
	)
	(segment
		(start 53.932074 -298.910502)
		(end 54.173374 -298.910502)
		(width 0.14478)
		(layer "In11.Cu")
		(net "M_F_CPU1_SB_DQ<13>")
	)
	(segment
		(start 76.373736 -283.456634)
		(end 76.460858 -283.369512)
		(width 0.0889)
		(layer "In11.Cu")
		(net "M_F_CPU1_SB_DQ<13>")
	)
	(segment
		(start 49.297336 -298.765722)
		(end 49.442116 -298.910502)
		(width 0.14478)
		(layer "In11.Cu")
		(net "M_F_CPU1_SB_DQ<13>")
	)
	(segment
		(start 33.264602 -298.910502)
		(end 33.557464 -299.203364)
		(width 0.14478)
		(layer "In11.Cu")
		(net "M_F_CPU1_SB_DQ<13>")
	)
	(segment
		(start 57.265062 -298.910502)
		(end 59.261248 -296.914316)
		(width 0.14478)
		(layer "In11.Cu")
		(net "M_F_CPU1_SB_DQ<13>")
	)
	(segment
		(start 24.3967 -298.52112)
		(end 24.786082 -298.910502)
		(width 0.14478)
		(layer "In11.Cu")
		(net "M_F_CPU1_SB_DQ<13>")
	)
	(segment
		(start 38.990778 -298.910502)
		(end 41.988994 -298.910502)
		(width 0.14478)
		(layer "In11.Cu")
		(net "M_F_CPU1_SB_DQ<13>")
	)
	(segment
		(start 56.127904 -298.658026)
		(end 56.272684 -298.513246)
		(width 0.14478)
		(layer "In11.Cu")
		(net "M_F_CPU1_SB_DQ<13>")
	)
	(segment
		(start 56.534558 -298.513246)
		(end 56.679338 -298.658026)
		(width 0.14478)
		(layer "In11.Cu")
		(net "M_F_CPU1_SB_DQ<13>")
	)
	(segment
		(start 54.462934 -298.523406)
		(end 54.724808 -298.523406)
		(width 0.14478)
		(layer "In11.Cu")
		(net "M_F_CPU1_SB_DQ<13>")
	)
	(segment
		(start 22.72792 -299.274484)
		(end 22.890734 -299.11167)
		(width 0.14478)
		(layer "In11.Cu")
		(net "M_F_CPU1_SB_DQ<13>")
	)
	(segment
		(start 21.70811 -298.485306)
		(end 22.497288 -299.274484)
		(width 0.14478)
		(layer "In11.Cu")
		(net "M_F_CPU1_SB_DQ<13>")
	)
	(segment
		(start 33.557464 -299.203364)
		(end 33.820862 -299.203364)
		(width 0.14478)
		(layer "In11.Cu")
		(net "M_F_CPU1_SB_DQ<13>")
	)
	(segment
		(start 82.753962 -283.318966)
		(end 82.762344 -283.323792)
		(width 0.0889)
		(layer "In11.Cu")
		(net "M_F_CPU1_SB_DQ<13>")
	)
	(segment
		(start 25.948132 -298.5262)
		(end 26.110946 -298.689014)
		(width 0.14478)
		(layer "In11.Cu")
		(net "M_F_CPU1_SB_DQ<13>")
	)
	(segment
		(start 31.015178 -298.910502)
		(end 33.264602 -298.910502)
		(width 0.14478)
		(layer "In11.Cu")
		(net "M_F_CPU1_SB_DQ<13>")
	)
	(segment
		(start 42.839132 -298.060364)
		(end 45.83684 -298.060364)
		(width 0.14478)
		(layer "In11.Cu")
		(net "M_F_CPU1_SB_DQ<13>")
	)
	(segment
		(start 38.14064 -298.060364)
		(end 38.990778 -298.910502)
		(width 0.14478)
		(layer "In11.Cu")
		(net "M_F_CPU1_SB_DQ<13>")
	)
	(segment
		(start 54.318154 -298.668186)
		(end 54.462934 -298.523406)
		(width 0.14478)
		(layer "In11.Cu")
		(net "M_F_CPU1_SB_DQ<13>")
	)
	(segment
		(start 75.973686 -283.456634)
		(end 76.373736 -283.456634)
		(width 0.0889)
		(layer "In11.Cu")
		(net "M_F_CPU1_SB_DQ<13>")
	)
	(segment
		(start 48.601122 -298.910502)
		(end 48.745902 -298.765722)
		(width 0.14478)
		(layer "In11.Cu")
		(net "M_F_CPU1_SB_DQ<13>")
	)
	(segment
		(start 56.272684 -298.513246)
		(end 56.534558 -298.513246)
		(width 0.14478)
		(layer "In11.Cu")
		(net "M_F_CPU1_SB_DQ<13>")
	)
	(segment
		(start 78.979014 -283.31033)
		(end 78.993746 -283.318966)
		(width 0.0889)
		(layer "In11.Cu")
		(net "M_F_CPU1_SB_DQ<13>")
	)
	(segment
		(start 35.676332 -298.060364)
		(end 38.14064 -298.060364)
		(width 0.14478)
		(layer "In11.Cu")
		(net "M_F_CPU1_SB_DQ<13>")
	)
	(segment
		(start 53.081936 -298.060364)
		(end 53.932074 -298.910502)
		(width 0.14478)
		(layer "In11.Cu")
		(net "M_F_CPU1_SB_DQ<13>")
	)
	(segment
		(start 26.110946 -298.689014)
		(end 26.110946 -299.13199)
		(width 0.14478)
		(layer "In11.Cu")
		(net "M_F_CPU1_SB_DQ<13>")
	)
	(segment
		(start 24.003254 -298.683934)
		(end 24.166068 -298.52112)
		(width 0.14478)
		(layer "In11.Cu")
		(net "M_F_CPU1_SB_DQ<13>")
	)
	(segment
		(start 34.826194 -298.910502)
		(end 35.676332 -298.060364)
		(width 0.14478)
		(layer "In11.Cu")
		(net "M_F_CPU1_SB_DQ<13>")
	)
	(segment
		(start 27.206194 -298.910502)
		(end 28.056332 -298.060364)
		(width 0.14478)
		(layer "In11.Cu")
		(net "M_F_CPU1_SB_DQ<13>")
	)
	(segment
		(start 59.261248 -296.914316)
		(end 60.43549 -296.914316)
		(width 0.14478)
		(layer "In11.Cu")
		(net "M_F_CPU1_SB_DQ<13>")
	)
	(segment
		(start 76.460858 -283.369512)
		(end 78.240636 -283.369512)
		(width 0.0889)
		(layer "In11.Cu")
		(net "M_F_CPU1_SB_DQ<13>")
	)
	(segment
		(start 26.888694 -298.910502)
		(end 27.206194 -298.910502)
		(width 0.14478)
		(layer "In11.Cu")
		(net "M_F_CPU1_SB_DQ<13>")
	)
	(segment
		(start 22.497288 -299.274484)
		(end 22.72792 -299.274484)
		(width 0.14478)
		(layer "In11.Cu")
		(net "M_F_CPU1_SB_DQ<13>")
	)
	(segment
		(start 49.297336 -298.658026)
		(end 49.297336 -298.765722)
		(width 0.14478)
		(layer "In11.Cu")
		(net "M_F_CPU1_SB_DQ<13>")
	)
	(segment
		(start 23.84044 -299.274484)
		(end 24.003254 -299.11167)
		(width 0.14478)
		(layer "In11.Cu")
		(net "M_F_CPU1_SB_DQ<13>")
	)
	(segment
		(start 49.152556 -298.513246)
		(end 49.297336 -298.658026)
		(width 0.14478)
		(layer "In11.Cu")
		(net "M_F_CPU1_SB_DQ<13>")
	)
	(segment
		(start 55.014368 -298.910502)
		(end 55.983124 -298.910502)
		(width 0.14478)
		(layer "In11.Cu")
		(net "M_F_CPU1_SB_DQ<13>")
	)
	(segment
		(start 23.609808 -299.274484)
		(end 23.84044 -299.274484)
		(width 0.14478)
		(layer "In11.Cu")
		(net "M_F_CPU1_SB_DQ<13>")
	)
	(segment
		(start 54.173374 -298.910502)
		(end 54.318154 -298.765722)
		(width 0.14478)
		(layer "In11.Cu")
		(net "M_F_CPU1_SB_DQ<13>")
	)
	(segment
		(start 49.442116 -298.910502)
		(end 49.911254 -298.910502)
		(width 0.14478)
		(layer "In11.Cu")
		(net "M_F_CPU1_SB_DQ<13>")
	)
	(segment
		(start 25.333198 -298.910502)
		(end 25.7175 -298.5262)
		(width 0.14478)
		(layer "In11.Cu")
		(net "M_F_CPU1_SB_DQ<13>")
	)
	(segment
		(start 79.367634 -283.318966)
		(end 79.378048 -283.31287)
		(width 0.0889)
		(layer "In11.Cu")
		(net "M_F_CPU1_SB_DQ<13>")
	)
	(segment
		(start 54.869588 -298.668186)
		(end 54.869588 -298.765722)
		(width 0.14478)
		(layer "In11.Cu")
		(net "M_F_CPU1_SB_DQ<13>")
	)
	(segment
		(start 60.43549 -296.914316)
		(end 73.893172 -283.456634)
		(width 0.14478)
		(layer "In11.Cu")
		(net "M_F_CPU1_SB_DQ<13>")
	)
	(segment
		(start 85.914992 -283.261816)
		(end 85.761068 -282.996386)
		(width 0.0889)
		(layer "In11.Cu")
		(net "M_F_CPU1_SB_DQ<13>")
	)
	(segment
		(start 56.679338 -298.765722)
		(end 56.824118 -298.910502)
		(width 0.14478)
		(layer "In11.Cu")
		(net "M_F_CPU1_SB_DQ<13>")
	)
	(segment
		(start 85.89264 -283.345128)
		(end 85.914992 -283.261816)
		(width 0.0889)
		(layer "In11.Cu")
		(net "M_F_CPU1_SB_DQ<13>")
	)
	(segment
		(start 30.16504 -298.060364)
		(end 31.015178 -298.910502)
		(width 0.14478)
		(layer "In11.Cu")
		(net "M_F_CPU1_SB_DQ<13>")
	)
	(segment
		(start 25.7175 -298.5262)
		(end 25.948132 -298.5262)
		(width 0.14478)
		(layer "In11.Cu")
		(net "M_F_CPU1_SB_DQ<13>")
	)
	(segment
		(start 54.724808 -298.523406)
		(end 54.869588 -298.668186)
		(width 0.14478)
		(layer "In11.Cu")
		(net "M_F_CPU1_SB_DQ<13>")
	)
	(segment
		(start 54.318154 -298.765722)
		(end 54.318154 -298.668186)
		(width 0.14478)
		(layer "In11.Cu")
		(net "M_F_CPU1_SB_DQ<13>")
	)
	(segment
		(start 46.686978 -298.910502)
		(end 48.601122 -298.910502)
		(width 0.14478)
		(layer "In11.Cu")
		(net "M_F_CPU1_SB_DQ<13>")
	)
	(segment
		(start 56.127904 -298.765722)
		(end 56.127904 -298.658026)
		(width 0.14478)
		(layer "In11.Cu")
		(net "M_F_CPU1_SB_DQ<13>")
	)
	(segment
		(start 45.83684 -298.060364)
		(end 46.686978 -298.910502)
		(width 0.14478)
		(layer "In11.Cu")
		(net "M_F_CPU1_SB_DQ<13>")
	)
	(segment
		(start 48.890682 -298.513246)
		(end 49.152556 -298.513246)
		(width 0.14478)
		(layer "In11.Cu")
		(net "M_F_CPU1_SB_DQ<13>")
	)
	(segment
		(start 34.113724 -298.910502)
		(end 34.826194 -298.910502)
		(width 0.14478)
		(layer "In11.Cu")
		(net "M_F_CPU1_SB_DQ<13>")
	)
	(arc
		(start 84.068158 -283.318966)
		(mid 84.351114 -283.242789)
		(end 84.63407 -283.318966)
		(width 0.0889)
		(layer "In11.Cu")
		(net "M_F_CPU1_SB_DQ<13>")
	)
	(arc
		(start 79.378048 -283.31287)
		(mid 79.656734 -283.24265)
		(end 79.9338 -283.318966)
		(width 0.0889)
		(layer "In11.Cu")
		(net "M_F_CPU1_SB_DQ<13>")
	)
	(arc
		(start 83.702398 -283.323792)
		(mid 83.885906 -283.369286)
		(end 84.068158 -283.318966)
		(width 0.0889)
		(layer "In11.Cu")
		(net "M_F_CPU1_SB_DQ<13>")
	)
	(arc
		(start 78.240636 -283.369512)
		(mid 78.337583 -283.356629)
		(end 78.427834 -283.318966)
		(width 0.0889)
		(layer "In11.Cu")
		(net "M_F_CPU1_SB_DQ<13>")
	)
	(arc
		(start 78.427834 -283.318966)
		(mid 78.702286 -283.24273)
		(end 78.979014 -283.31033)
		(width 0.0889)
		(layer "In11.Cu")
		(net "M_F_CPU1_SB_DQ<13>")
	)
	(arc
		(start 84.63407 -283.318966)
		(mid 84.821014 -283.369221)
		(end 85.007958 -283.318966)
		(width 0.0889)
		(layer "In11.Cu")
		(net "M_F_CPU1_SB_DQ<13>")
	)
	(arc
		(start 82.762344 -283.323792)
		(mid 82.945852 -283.369286)
		(end 83.128104 -283.318966)
		(width 0.0889)
		(layer "In11.Cu")
		(net "M_F_CPU1_SB_DQ<13>")
	)
	(arc
		(start 79.9338 -283.318966)
		(mid 80.120998 -283.369348)
		(end 80.308196 -283.318966)
		(width 0.0889)
		(layer "In11.Cu")
		(net "M_F_CPU1_SB_DQ<13>")
	)
	(arc
		(start 85.007958 -283.318966)
		(mid 85.290914 -283.242789)
		(end 85.57387 -283.318966)
		(width 0.0889)
		(layer "In11.Cu")
		(net "M_F_CPU1_SB_DQ<13>")
	)
	(arc
		(start 81.813908 -283.318966)
		(mid 81.996159 -283.369316)
		(end 82.179668 -283.323792)
		(width 0.0889)
		(layer "In11.Cu")
		(net "M_F_CPU1_SB_DQ<13>")
	)
	(arc
		(start 81.247996 -283.318966)
		(mid 81.530952 -283.242789)
		(end 81.813908 -283.318966)
		(width 0.0889)
		(layer "In11.Cu")
		(net "M_F_CPU1_SB_DQ<13>")
	)
	(arc
		(start 82.18805 -283.318966)
		(mid 82.471006 -283.242789)
		(end 82.753962 -283.318966)
		(width 0.0889)
		(layer "In11.Cu")
		(net "M_F_CPU1_SB_DQ<13>")
	)
	(arc
		(start 80.874108 -283.318966)
		(mid 81.061052 -283.369221)
		(end 81.247996 -283.318966)
		(width 0.0889)
		(layer "In11.Cu")
		(net "M_F_CPU1_SB_DQ<13>")
	)
	(arc
		(start 78.993746 -283.318966)
		(mid 79.18069 -283.369221)
		(end 79.367634 -283.318966)
		(width 0.0889)
		(layer "In11.Cu")
		(net "M_F_CPU1_SB_DQ<13>")
	)
	(arc
		(start 80.308196 -283.318966)
		(mid 80.591152 -283.242789)
		(end 80.874108 -283.318966)
		(width 0.0889)
		(layer "In11.Cu")
		(net "M_F_CPU1_SB_DQ<13>")
	)
	(arc
		(start 83.128104 -283.318966)
		(mid 83.41106 -283.242789)
		(end 83.694016 -283.318966)
		(width 0.0889)
		(layer "In11.Cu")
		(net "M_F_CPU1_SB_DQ<13>")
	)
	(arc
		(start 85.57387 -283.318966)
		(mid 85.730308 -283.367937)
		(end 85.89264 -283.345128)
		(width 0.0889)
		(layer "In11.Cu")
		(net "M_F_CPU1_SB_DQ<13>")
	)
	(segment
		(start 84.817966 -281.920442)
		(end 84.351114 -282.18638)
		(width 0.10668)
		(layer "F.Cu")
		(net "M_F_CPU1_SB_DQ<12>")
	)
	(segment
		(start 76.0349 -282.547314)
		(end 76.42225 -282.159964)
		(width 0.0889)
		(layer "In11.Cu")
		(net "M_F_CPU1_SB_DQ<12>")
	)
	(segment
		(start 56.044846 -297.511724)
		(end 56.299862 -297.511724)
		(width 0.14478)
		(layer "In11.Cu")
		(net "M_F_CPU1_SB_DQ<12>")
	)
	(segment
		(start 28.639516 -296.52341)
		(end 28.792932 -296.369994)
		(width 0.14478)
		(layer "In11.Cu")
		(net "M_F_CPU1_SB_DQ<12>")
	)
	(segment
		(start 28.476448 -296.754296)
		(end 28.639516 -296.591228)
		(width 0.14478)
		(layer "In11.Cu")
		(net "M_F_CPU1_SB_DQ<12>")
	)
	(segment
		(start 30.480508 -296.369994)
		(end 31.475172 -297.364658)
		(width 0.14478)
		(layer "In11.Cu")
		(net "M_F_CPU1_SB_DQ<12>")
	)
	(segment
		(start 23.861776 -297.373294)
		(end 23.861776 -297.439588)
		(width 0.14478)
		(layer "In11.Cu")
		(net "M_F_CPU1_SB_DQ<12>")
	)
	(segment
		(start 51.136296 -296.746676)
		(end 51.299364 -296.583608)
		(width 0.14478)
		(layer "In11.Cu")
		(net "M_F_CPU1_SB_DQ<12>")
	)
	(segment
		(start 26.660348 -297.464226)
		(end 26.660348 -297.364658)
		(width 0.14478)
		(layer "In11.Cu")
		(net "M_F_CPU1_SB_DQ<12>")
	)
	(segment
		(start 26.253694 -297.609006)
		(end 26.515568 -297.609006)
		(width 0.14478)
		(layer "In11.Cu")
		(net "M_F_CPU1_SB_DQ<12>")
	)
	(segment
		(start 22.282658 -297.210226)
		(end 22.445726 -297.047158)
		(width 0.14478)
		(layer "In11.Cu")
		(net "M_F_CPU1_SB_DQ<12>")
	)
	(segment
		(start 54.932326 -297.511724)
		(end 55.187342 -297.511724)
		(width 0.14478)
		(layer "In11.Cu")
		(net "M_F_CPU1_SB_DQ<12>")
	)
	(segment
		(start 22.445726 -297.047158)
		(end 22.445726 -296.643044)
		(width 0.14478)
		(layer "In11.Cu")
		(net "M_F_CPU1_SB_DQ<12>")
	)
	(segment
		(start 31.475172 -297.364658)
		(end 31.475172 -297.464226)
		(width 0.14478)
		(layer "In11.Cu")
		(net "M_F_CPU1_SB_DQ<12>")
	)
	(segment
		(start 22.133052 -297.210226)
		(end 22.282658 -297.210226)
		(width 0.14478)
		(layer "In11.Cu")
		(net "M_F_CPU1_SB_DQ<12>")
	)
	(segment
		(start 34.06013 -297.373294)
		(end 34.223198 -297.210226)
		(width 0.14478)
		(layer "In11.Cu")
		(net "M_F_CPU1_SB_DQ<12>")
	)
	(segment
		(start 39.50843 -297.464226)
		(end 39.50843 -297.364658)
		(width 0.14478)
		(layer "In11.Cu")
		(net "M_F_CPU1_SB_DQ<12>")
	)
	(segment
		(start 28.792932 -296.369994)
		(end 30.480508 -296.369994)
		(width 0.14478)
		(layer "In11.Cu")
		(net "M_F_CPU1_SB_DQ<12>")
	)
	(segment
		(start 26.515568 -297.609006)
		(end 26.660348 -297.464226)
		(width 0.14478)
		(layer "In11.Cu")
		(net "M_F_CPU1_SB_DQ<12>")
	)
	(segment
		(start 53.12156 -296.369994)
		(end 53.962046 -297.21048)
		(width 0.14478)
		(layer "In11.Cu")
		(net "M_F_CPU1_SB_DQ<12>")
	)
	(segment
		(start 83.589622 -282.513786)
		(end 83.598004 -282.50896)
		(width 0.0889)
		(layer "In11.Cu")
		(net "M_F_CPU1_SB_DQ<12>")
	)
	(segment
		(start 35.781488 -296.754296)
		(end 36.011866 -296.754296)
		(width 0.14478)
		(layer "In11.Cu")
		(net "M_F_CPU1_SB_DQ<12>")
	)
	(segment
		(start 38.956996 -297.364658)
		(end 38.956996 -297.464226)
		(width 0.14478)
		(layer "In11.Cu")
		(net "M_F_CPU1_SB_DQ<12>")
	)
	(segment
		(start 80.769714 -282.513786)
		(end 80.778096 -282.50896)
		(width 0.0889)
		(layer "In11.Cu")
		(net "M_F_CPU1_SB_DQ<12>")
	)
	(segment
		(start 33.503616 -297.439588)
		(end 33.666684 -297.602656)
		(width 0.14478)
		(layer "In11.Cu")
		(net "M_F_CPU1_SB_DQ<12>")
	)
	(segment
		(start 43.195494 -296.52341)
		(end 43.195494 -296.583608)
		(width 0.14478)
		(layer "In11.Cu")
		(net "M_F_CPU1_SB_DQ<12>")
	)
	(segment
		(start 43.752008 -296.583608)
		(end 43.752008 -296.52341)
		(width 0.14478)
		(layer "In11.Cu")
		(net "M_F_CPU1_SB_DQ<12>")
	)
	(segment
		(start 41.044876 -297.373294)
		(end 41.044876 -297.439588)
		(width 0.14478)
		(layer "In11.Cu")
		(net "M_F_CPU1_SB_DQ<12>")
	)
	(segment
		(start 41.60139 -297.439588)
		(end 41.60139 -297.373294)
		(width 0.14478)
		(layer "In11.Cu")
		(net "M_F_CPU1_SB_DQ<12>")
	)
	(segment
		(start 23.00224 -297.047158)
		(end 23.165308 -297.210226)
		(width 0.14478)
		(layer "In11.Cu")
		(net "M_F_CPU1_SB_DQ<12>")
	)
	(segment
		(start 46.42739 -297.219878)
		(end 48.343058 -297.219878)
		(width 0.14478)
		(layer "In11.Cu")
		(net "M_F_CPU1_SB_DQ<12>")
	)
	(segment
		(start 36.32835 -296.369994)
		(end 37.962332 -296.369994)
		(width 0.14478)
		(layer "In11.Cu")
		(net "M_F_CPU1_SB_DQ<12>")
	)
	(segment
		(start 49.448974 -297.210226)
		(end 50.298858 -296.360342)
		(width 0.14478)
		(layer "In11.Cu")
		(net "M_F_CPU1_SB_DQ<12>")
	)
	(segment
		(start 33.503616 -297.373294)
		(end 33.503616 -297.439588)
		(width 0.14478)
		(layer "In11.Cu")
		(net "M_F_CPU1_SB_DQ<12>")
	)
	(segment
		(start 55.743602 -297.21048)
		(end 56.044846 -297.511724)
		(width 0.14478)
		(layer "In11.Cu")
		(net "M_F_CPU1_SB_DQ<12>")
	)
	(segment
		(start 79.447136 -282.498292)
		(end 79.46517 -282.50896)
		(width 0.0889)
		(layer "In11.Cu")
		(net "M_F_CPU1_SB_DQ<12>")
	)
	(segment
		(start 42.792904 -296.360342)
		(end 43.032426 -296.360342)
		(width 0.14478)
		(layer "In11.Cu")
		(net "M_F_CPU1_SB_DQ<12>")
	)
	(segment
		(start 43.752008 -296.52341)
		(end 43.905424 -296.369994)
		(width 0.14478)
		(layer "In11.Cu")
		(net "M_F_CPU1_SB_DQ<12>")
	)
	(segment
		(start 23.00224 -296.643044)
		(end 23.00224 -297.047158)
		(width 0.14478)
		(layer "In11.Cu")
		(net "M_F_CPU1_SB_DQ<12>")
	)
	(segment
		(start 51.299364 -296.52341)
		(end 51.45278 -296.369994)
		(width 0.14478)
		(layer "In11.Cu")
		(net "M_F_CPU1_SB_DQ<12>")
	)
	(segment
		(start 50.905918 -296.746676)
		(end 51.136296 -296.746676)
		(width 0.14478)
		(layer "In11.Cu")
		(net "M_F_CPU1_SB_DQ<12>")
	)
	(segment
		(start 50.579782 -296.360342)
		(end 50.74285 -296.52341)
		(width 0.14478)
		(layer "In11.Cu")
		(net "M_F_CPU1_SB_DQ<12>")
	)
	(segment
		(start 34.06013 -297.439588)
		(end 34.06013 -297.373294)
		(width 0.14478)
		(layer "In11.Cu")
		(net "M_F_CPU1_SB_DQ<12>")
	)
	(segment
		(start 43.905424 -296.369994)
		(end 45.577506 -296.369994)
		(width 0.14478)
		(layer "In11.Cu")
		(net "M_F_CPU1_SB_DQ<12>")
	)
	(segment
		(start 39.50843 -297.364658)
		(end 39.65321 -297.219878)
		(width 0.14478)
		(layer "In11.Cu")
		(net "M_F_CPU1_SB_DQ<12>")
	)
	(segment
		(start 24.571706 -297.219878)
		(end 25.964134 -297.219878)
		(width 0.14478)
		(layer "In11.Cu")
		(net "M_F_CPU1_SB_DQ<12>")
	)
	(segment
		(start 34.223198 -297.210226)
		(end 34.383218 -297.210226)
		(width 0.14478)
		(layer "In11.Cu")
		(net "M_F_CPU1_SB_DQ<12>")
	)
	(segment
		(start 31.619952 -297.609006)
		(end 31.881826 -297.609006)
		(width 0.14478)
		(layer "In11.Cu")
		(net "M_F_CPU1_SB_DQ<12>")
	)
	(segment
		(start 23.165308 -297.210226)
		(end 23.698708 -297.210226)
		(width 0.14478)
		(layer "In11.Cu")
		(net "M_F_CPU1_SB_DQ<12>")
	)
	(segment
		(start 28.639516 -296.591228)
		(end 28.639516 -296.52341)
		(width 0.14478)
		(layer "In11.Cu")
		(net "M_F_CPU1_SB_DQ<12>")
	)
	(segment
		(start 28.083002 -296.591228)
		(end 28.24607 -296.754296)
		(width 0.14478)
		(layer "In11.Cu")
		(net "M_F_CPU1_SB_DQ<12>")
	)
	(segment
		(start 56.299862 -297.511724)
		(end 56.601106 -297.21048)
		(width 0.14478)
		(layer "In11.Cu")
		(net "M_F_CPU1_SB_DQ<12>")
	)
	(segment
		(start 50.74285 -296.583608)
		(end 50.905918 -296.746676)
		(width 0.14478)
		(layer "In11.Cu")
		(net "M_F_CPU1_SB_DQ<12>")
	)
	(segment
		(start 51.45278 -296.369994)
		(end 53.12156 -296.369994)
		(width 0.14478)
		(layer "In11.Cu")
		(net "M_F_CPU1_SB_DQ<12>")
	)
	(segment
		(start 41.438322 -297.602656)
		(end 41.60139 -297.439588)
		(width 0.14478)
		(layer "In11.Cu")
		(net "M_F_CPU1_SB_DQ<12>")
	)
	(segment
		(start 25.964134 -297.219878)
		(end 26.108914 -297.364658)
		(width 0.14478)
		(layer "In11.Cu")
		(net "M_F_CPU1_SB_DQ<12>")
	)
	(segment
		(start 32.026606 -297.364658)
		(end 32.171386 -297.219878)
		(width 0.14478)
		(layer "In11.Cu")
		(net "M_F_CPU1_SB_DQ<12>")
	)
	(segment
		(start 48.88992 -297.602656)
		(end 49.052988 -297.439588)
		(width 0.14478)
		(layer "In11.Cu")
		(net "M_F_CPU1_SB_DQ<12>")
	)
	(segment
		(start 48.343058 -297.219878)
		(end 48.496474 -297.373294)
		(width 0.14478)
		(layer "In11.Cu")
		(net "M_F_CPU1_SB_DQ<12>")
	)
	(segment
		(start 56.601106 -297.21048)
		(end 57.63641 -297.21048)
		(width 0.14478)
		(layer "In11.Cu")
		(net "M_F_CPU1_SB_DQ<12>")
	)
	(segment
		(start 41.764458 -297.210226)
		(end 41.94302 -297.210226)
		(width 0.14478)
		(layer "In11.Cu")
		(net "M_F_CPU1_SB_DQ<12>")
	)
	(segment
		(start 24.255222 -297.602656)
		(end 24.41829 -297.439588)
		(width 0.14478)
		(layer "In11.Cu")
		(net "M_F_CPU1_SB_DQ<12>")
	)
	(segment
		(start 43.358562 -296.746676)
		(end 43.58894 -296.746676)
		(width 0.14478)
		(layer "In11.Cu")
		(net "M_F_CPU1_SB_DQ<12>")
	)
	(segment
		(start 51.299364 -296.583608)
		(end 51.299364 -296.52341)
		(width 0.14478)
		(layer "In11.Cu")
		(net "M_F_CPU1_SB_DQ<12>")
	)
	(segment
		(start 48.496474 -297.439588)
		(end 48.659542 -297.602656)
		(width 0.14478)
		(layer "In11.Cu")
		(net "M_F_CPU1_SB_DQ<12>")
	)
	(segment
		(start 31.881826 -297.609006)
		(end 32.026606 -297.464226)
		(width 0.14478)
		(layer "In11.Cu")
		(net "M_F_CPU1_SB_DQ<12>")
	)
	(segment
		(start 60.062618 -296.015156)
		(end 73.53046 -282.547314)
		(width 0.14478)
		(layer "In11.Cu")
		(net "M_F_CPU1_SB_DQ<12>")
	)
	(segment
		(start 53.962046 -297.21048)
		(end 54.631082 -297.21048)
		(width 0.14478)
		(layer "In11.Cu")
		(net "M_F_CPU1_SB_DQ<12>")
	)
	(segment
		(start 33.3502 -297.219878)
		(end 33.503616 -297.373294)
		(width 0.14478)
		(layer "In11.Cu")
		(net "M_F_CPU1_SB_DQ<12>")
	)
	(segment
		(start 48.659542 -297.602656)
		(end 48.88992 -297.602656)
		(width 0.14478)
		(layer "In11.Cu")
		(net "M_F_CPU1_SB_DQ<12>")
	)
	(segment
		(start 41.044876 -297.439588)
		(end 41.207944 -297.602656)
		(width 0.14478)
		(layer "In11.Cu")
		(net "M_F_CPU1_SB_DQ<12>")
	)
	(segment
		(start 21.70811 -296.785284)
		(end 22.133052 -297.210226)
		(width 0.14478)
		(layer "In11.Cu")
		(net "M_F_CPU1_SB_DQ<12>")
	)
	(segment
		(start 28.24607 -296.754296)
		(end 28.476448 -296.754296)
		(width 0.14478)
		(layer "In11.Cu")
		(net "M_F_CPU1_SB_DQ<12>")
	)
	(segment
		(start 34.383218 -297.210226)
		(end 35.233102 -296.360342)
		(width 0.14478)
		(layer "In11.Cu")
		(net "M_F_CPU1_SB_DQ<12>")
	)
	(segment
		(start 28.083002 -296.52341)
		(end 28.083002 -296.591228)
		(width 0.14478)
		(layer "In11.Cu")
		(net "M_F_CPU1_SB_DQ<12>")
	)
	(segment
		(start 23.861776 -297.439588)
		(end 24.024844 -297.602656)
		(width 0.14478)
		(layer "In11.Cu")
		(net "M_F_CPU1_SB_DQ<12>")
	)
	(segment
		(start 36.174934 -296.52341)
		(end 36.32835 -296.369994)
		(width 0.14478)
		(layer "In11.Cu")
		(net "M_F_CPU1_SB_DQ<12>")
	)
	(segment
		(start 41.207944 -297.602656)
		(end 41.438322 -297.602656)
		(width 0.14478)
		(layer "In11.Cu")
		(net "M_F_CPU1_SB_DQ<12>")
	)
	(segment
		(start 37.962332 -296.369994)
		(end 38.956996 -297.364658)
		(width 0.14478)
		(layer "In11.Cu")
		(net "M_F_CPU1_SB_DQ<12>")
	)
	(segment
		(start 36.011866 -296.754296)
		(end 36.174934 -296.591228)
		(width 0.14478)
		(layer "In11.Cu")
		(net "M_F_CPU1_SB_DQ<12>")
	)
	(segment
		(start 49.052988 -297.439588)
		(end 49.052988 -297.373294)
		(width 0.14478)
		(layer "In11.Cu")
		(net "M_F_CPU1_SB_DQ<12>")
	)
	(segment
		(start 32.171386 -297.219878)
		(end 33.3502 -297.219878)
		(width 0.14478)
		(layer "In11.Cu")
		(net "M_F_CPU1_SB_DQ<12>")
	)
	(segment
		(start 55.187342 -297.511724)
		(end 55.488586 -297.21048)
		(width 0.14478)
		(layer "In11.Cu")
		(net "M_F_CPU1_SB_DQ<12>")
	)
	(segment
		(start 32.026606 -297.464226)
		(end 32.026606 -297.364658)
		(width 0.14478)
		(layer "In11.Cu")
		(net "M_F_CPU1_SB_DQ<12>")
	)
	(segment
		(start 57.63641 -297.21048)
		(end 58.831734 -296.015156)
		(width 0.14478)
		(layer "In11.Cu")
		(net "M_F_CPU1_SB_DQ<12>")
	)
	(segment
		(start 49.052988 -297.373294)
		(end 49.216056 -297.210226)
		(width 0.14478)
		(layer "In11.Cu")
		(net "M_F_CPU1_SB_DQ<12>")
	)
	(segment
		(start 41.60139 -297.373294)
		(end 41.764458 -297.210226)
		(width 0.14478)
		(layer "In11.Cu")
		(net "M_F_CPU1_SB_DQ<12>")
	)
	(segment
		(start 45.577506 -296.369994)
		(end 46.42739 -297.219878)
		(width 0.14478)
		(layer "In11.Cu")
		(net "M_F_CPU1_SB_DQ<12>")
	)
	(segment
		(start 35.455352 -296.360342)
		(end 35.61842 -296.52341)
		(width 0.14478)
		(layer "In11.Cu")
		(net "M_F_CPU1_SB_DQ<12>")
	)
	(segment
		(start 54.631082 -297.21048)
		(end 54.932326 -297.511724)
		(width 0.14478)
		(layer "In11.Cu")
		(net "M_F_CPU1_SB_DQ<12>")
	)
	(segment
		(start 77.865986 -282.159964)
		(end 78.265782 -282.55976)
		(width 0.0889)
		(layer "In11.Cu")
		(net "M_F_CPU1_SB_DQ<12>")
	)
	(segment
		(start 73.53046 -282.547314)
		(end 76.0349 -282.547314)
		(width 0.14478)
		(layer "In11.Cu")
		(net "M_F_CPU1_SB_DQ<12>")
	)
	(segment
		(start 33.666684 -297.602656)
		(end 33.897062 -297.602656)
		(width 0.14478)
		(layer "In11.Cu")
		(net "M_F_CPU1_SB_DQ<12>")
	)
	(segment
		(start 43.032426 -296.360342)
		(end 43.195494 -296.52341)
		(width 0.14478)
		(layer "In11.Cu")
		(net "M_F_CPU1_SB_DQ<12>")
	)
	(segment
		(start 35.233102 -296.360342)
		(end 35.455352 -296.360342)
		(width 0.14478)
		(layer "In11.Cu")
		(net "M_F_CPU1_SB_DQ<12>")
	)
	(segment
		(start 22.445726 -296.643044)
		(end 22.608794 -296.479976)
		(width 0.14478)
		(layer "In11.Cu")
		(net "M_F_CPU1_SB_DQ<12>")
	)
	(segment
		(start 84.482686 -282.535122)
		(end 84.505038 -282.45181)
		(width 0.0889)
		(layer "In11.Cu")
		(net "M_F_CPU1_SB_DQ<12>")
	)
	(segment
		(start 27.919934 -296.360342)
		(end 28.083002 -296.52341)
		(width 0.14478)
		(layer "In11.Cu")
		(net "M_F_CPU1_SB_DQ<12>")
	)
	(segment
		(start 58.831734 -296.015156)
		(end 60.062618 -296.015156)
		(width 0.14478)
		(layer "In11.Cu")
		(net "M_F_CPU1_SB_DQ<12>")
	)
	(segment
		(start 24.41829 -297.373294)
		(end 24.571706 -297.219878)
		(width 0.14478)
		(layer "In11.Cu")
		(net "M_F_CPU1_SB_DQ<12>")
	)
	(segment
		(start 39.65321 -297.219878)
		(end 40.89146 -297.219878)
		(width 0.14478)
		(layer "In11.Cu")
		(net "M_F_CPU1_SB_DQ<12>")
	)
	(segment
		(start 55.488586 -297.21048)
		(end 55.743602 -297.21048)
		(width 0.14478)
		(layer "In11.Cu")
		(net "M_F_CPU1_SB_DQ<12>")
	)
	(segment
		(start 22.839172 -296.479976)
		(end 23.00224 -296.643044)
		(width 0.14478)
		(layer "In11.Cu")
		(net "M_F_CPU1_SB_DQ<12>")
	)
	(segment
		(start 79.825088 -282.51658)
		(end 79.838804 -282.508706)
		(width 0.0889)
		(layer "In11.Cu")
		(net "M_F_CPU1_SB_DQ<12>")
	)
	(segment
		(start 26.108914 -297.364658)
		(end 26.108914 -297.464226)
		(width 0.14478)
		(layer "In11.Cu")
		(net "M_F_CPU1_SB_DQ<12>")
	)
	(segment
		(start 26.108914 -297.464226)
		(end 26.253694 -297.609006)
		(width 0.14478)
		(layer "In11.Cu")
		(net "M_F_CPU1_SB_DQ<12>")
	)
	(segment
		(start 81.344008 -282.50896)
		(end 81.35239 -282.513786)
		(width 0.0889)
		(layer "In11.Cu")
		(net "M_F_CPU1_SB_DQ<12>")
	)
	(segment
		(start 84.505038 -282.45181)
		(end 84.351114 -282.18638)
		(width 0.0889)
		(layer "In11.Cu")
		(net "M_F_CPU1_SB_DQ<12>")
	)
	(segment
		(start 36.174934 -296.591228)
		(end 36.174934 -296.52341)
		(width 0.14478)
		(layer "In11.Cu")
		(net "M_F_CPU1_SB_DQ<12>")
	)
	(segment
		(start 39.36365 -297.609006)
		(end 39.50843 -297.464226)
		(width 0.14478)
		(layer "In11.Cu")
		(net "M_F_CPU1_SB_DQ<12>")
	)
	(segment
		(start 26.660348 -297.364658)
		(end 27.664664 -296.360342)
		(width 0.14478)
		(layer "In11.Cu")
		(net "M_F_CPU1_SB_DQ<12>")
	)
	(segment
		(start 35.61842 -296.52341)
		(end 35.61842 -296.591228)
		(width 0.14478)
		(layer "In11.Cu")
		(net "M_F_CPU1_SB_DQ<12>")
	)
	(segment
		(start 49.216056 -297.210226)
		(end 49.448974 -297.210226)
		(width 0.14478)
		(layer "In11.Cu")
		(net "M_F_CPU1_SB_DQ<12>")
	)
	(segment
		(start 40.89146 -297.219878)
		(end 41.044876 -297.373294)
		(width 0.14478)
		(layer "In11.Cu")
		(net "M_F_CPU1_SB_DQ<12>")
	)
	(segment
		(start 48.496474 -297.373294)
		(end 48.496474 -297.439588)
		(width 0.14478)
		(layer "In11.Cu")
		(net "M_F_CPU1_SB_DQ<12>")
	)
	(segment
		(start 38.956996 -297.464226)
		(end 39.101776 -297.609006)
		(width 0.14478)
		(layer "In11.Cu")
		(net "M_F_CPU1_SB_DQ<12>")
	)
	(segment
		(start 76.42225 -282.159964)
		(end 77.865986 -282.159964)
		(width 0.0889)
		(layer "In11.Cu")
		(net "M_F_CPU1_SB_DQ<12>")
	)
	(segment
		(start 24.41829 -297.439588)
		(end 24.41829 -297.373294)
		(width 0.14478)
		(layer "In11.Cu")
		(net "M_F_CPU1_SB_DQ<12>")
	)
	(segment
		(start 27.664664 -296.360342)
		(end 27.919934 -296.360342)
		(width 0.14478)
		(layer "In11.Cu")
		(net "M_F_CPU1_SB_DQ<12>")
	)
	(segment
		(start 78.265782 -282.55976)
		(end 78.711044 -282.55976)
		(width 0.0889)
		(layer "In11.Cu")
		(net "M_F_CPU1_SB_DQ<12>")
	)
	(segment
		(start 35.61842 -296.591228)
		(end 35.781488 -296.754296)
		(width 0.14478)
		(layer "In11.Cu")
		(net "M_F_CPU1_SB_DQ<12>")
	)
	(segment
		(start 33.897062 -297.602656)
		(end 34.06013 -297.439588)
		(width 0.14478)
		(layer "In11.Cu")
		(net "M_F_CPU1_SB_DQ<12>")
	)
	(segment
		(start 31.475172 -297.464226)
		(end 31.619952 -297.609006)
		(width 0.14478)
		(layer "In11.Cu")
		(net "M_F_CPU1_SB_DQ<12>")
	)
	(segment
		(start 43.58894 -296.746676)
		(end 43.752008 -296.583608)
		(width 0.14478)
		(layer "In11.Cu")
		(net "M_F_CPU1_SB_DQ<12>")
	)
	(segment
		(start 50.74285 -296.52341)
		(end 50.74285 -296.583608)
		(width 0.14478)
		(layer "In11.Cu")
		(net "M_F_CPU1_SB_DQ<12>")
	)
	(segment
		(start 50.298858 -296.360342)
		(end 50.579782 -296.360342)
		(width 0.14478)
		(layer "In11.Cu")
		(net "M_F_CPU1_SB_DQ<12>")
	)
	(segment
		(start 23.698708 -297.210226)
		(end 23.861776 -297.373294)
		(width 0.14478)
		(layer "In11.Cu")
		(net "M_F_CPU1_SB_DQ<12>")
	)
	(segment
		(start 79.838804 -282.508706)
		(end 79.850742 -282.501848)
		(width 0.0889)
		(layer "In11.Cu")
		(net "M_F_CPU1_SB_DQ<12>")
	)
	(segment
		(start 22.608794 -296.479976)
		(end 22.839172 -296.479976)
		(width 0.14478)
		(layer "In11.Cu")
		(net "M_F_CPU1_SB_DQ<12>")
	)
	(segment
		(start 43.195494 -296.583608)
		(end 43.358562 -296.746676)
		(width 0.14478)
		(layer "In11.Cu")
		(net "M_F_CPU1_SB_DQ<12>")
	)
	(segment
		(start 39.101776 -297.609006)
		(end 39.36365 -297.609006)
		(width 0.14478)
		(layer "In11.Cu")
		(net "M_F_CPU1_SB_DQ<12>")
	)
	(segment
		(start 24.024844 -297.602656)
		(end 24.255222 -297.602656)
		(width 0.14478)
		(layer "In11.Cu")
		(net "M_F_CPU1_SB_DQ<12>")
	)
	(segment
		(start 41.94302 -297.210226)
		(end 42.792904 -296.360342)
		(width 0.14478)
		(layer "In11.Cu")
		(net "M_F_CPU1_SB_DQ<12>")
	)
	(arc
		(start 83.223862 -282.50896)
		(mid 83.406113 -282.55931)
		(end 83.589622 -282.513786)
		(width 0.0889)
		(layer "In11.Cu")
		(net "M_F_CPU1_SB_DQ<12>")
	)
	(arc
		(start 80.778096 -282.50896)
		(mid 81.061052 -282.432783)
		(end 81.344008 -282.50896)
		(width 0.0889)
		(layer "In11.Cu")
		(net "M_F_CPU1_SB_DQ<12>")
	)
	(arc
		(start 78.711044 -282.55976)
		(mid 78.808133 -282.54677)
		(end 78.898496 -282.50896)
		(width 0.0889)
		(layer "In11.Cu")
		(net "M_F_CPU1_SB_DQ<12>")
	)
	(arc
		(start 81.35239 -282.513786)
		(mid 81.535898 -282.55928)
		(end 81.71815 -282.50896)
		(width 0.0889)
		(layer "In11.Cu")
		(net "M_F_CPU1_SB_DQ<12>")
	)
	(arc
		(start 82.284062 -282.50896)
		(mid 82.471006 -282.559215)
		(end 82.65795 -282.50896)
		(width 0.0889)
		(layer "In11.Cu")
		(net "M_F_CPU1_SB_DQ<12>")
	)
	(arc
		(start 80.403954 -282.50896)
		(mid 80.586205 -282.55931)
		(end 80.769714 -282.513786)
		(width 0.0889)
		(layer "In11.Cu")
		(net "M_F_CPU1_SB_DQ<12>")
	)
	(arc
		(start 78.898496 -282.50896)
		(mid 79.17144 -282.43238)
		(end 79.447136 -282.498292)
		(width 0.0889)
		(layer "In11.Cu")
		(net "M_F_CPU1_SB_DQ<12>")
	)
	(arc
		(start 79.850742 -282.501848)
		(mid 80.128276 -282.432867)
		(end 80.403954 -282.50896)
		(width 0.0889)
		(layer "In11.Cu")
		(net "M_F_CPU1_SB_DQ<12>")
	)
	(arc
		(start 84.163916 -282.50896)
		(mid 84.320354 -282.557931)
		(end 84.482686 -282.535122)
		(width 0.0889)
		(layer "In11.Cu")
		(net "M_F_CPU1_SB_DQ<12>")
	)
	(arc
		(start 81.71815 -282.50896)
		(mid 82.001106 -282.432783)
		(end 82.284062 -282.50896)
		(width 0.0889)
		(layer "In11.Cu")
		(net "M_F_CPU1_SB_DQ<12>")
	)
	(arc
		(start 82.65795 -282.50896)
		(mid 82.940906 -282.432783)
		(end 83.223862 -282.50896)
		(width 0.0889)
		(layer "In11.Cu")
		(net "M_F_CPU1_SB_DQ<12>")
	)
	(arc
		(start 83.598004 -282.50896)
		(mid 83.88096 -282.432783)
		(end 84.163916 -282.50896)
		(width 0.0889)
		(layer "In11.Cu")
		(net "M_F_CPU1_SB_DQ<12>")
	)
	(arc
		(start 79.46517 -282.50896)
		(mid 79.644157 -282.55913)
		(end 79.825088 -282.51658)
		(width 0.0889)
		(layer "In11.Cu")
		(net "M_F_CPU1_SB_DQ<12>")
	)
	(segment
		(start 86.69782 -280.30043)
		(end 86.230968 -280.566368)
		(width 0.10668)
		(layer "F.Cu")
		(net "M_F_CPU1_SB_DQ<11>")
	)
	(segment
		(start 35.21837 -292.950646)
		(end 38.103556 -292.950646)
		(width 0.14478)
		(layer "In11.Cu")
		(net "M_F_CPU1_SB_DQ<11>")
	)
	(segment
		(start 26.737564 -293.80053)
		(end 27.587448 -292.950646)
		(width 0.14478)
		(layer "In11.Cu")
		(net "M_F_CPU1_SB_DQ<11>")
	)
	(segment
		(start 18.033238 -293.810436)
		(end 18.505678 -293.810436)
		(width 0.14478)
		(layer "In11.Cu")
		(net "M_F_CPU1_SB_DQ<11>")
	)
	(segment
		(start 46.458886 -293.80053)
		(end 49.399698 -293.80053)
		(width 0.14478)
		(layer "In11.Cu")
		(net "M_F_CPU1_SB_DQ<11>")
	)
	(segment
		(start 75.966066 -280.207974)
		(end 76.160376 -280.207974)
		(width 0.0889)
		(layer "In11.Cu")
		(net "M_F_CPU1_SB_DQ<11>")
	)
	(segment
		(start 68.845176 -283.393896)
		(end 72.031098 -280.207974)
		(width 0.14478)
		(layer "In11.Cu")
		(net "M_F_CPU1_SB_DQ<11>")
	)
	(segment
		(start 86.077044 -280.300938)
		(end 86.230968 -280.566368)
		(width 0.0889)
		(layer "In11.Cu")
		(net "M_F_CPU1_SB_DQ<11>")
	)
	(segment
		(start 18.668746 -293.647368)
		(end 18.668746 -293.280084)
		(width 0.14478)
		(layer "In11.Cu")
		(net "M_F_CPU1_SB_DQ<11>")
	)
	(segment
		(start 76.160376 -280.207974)
		(end 76.240386 -280.127964)
		(width 0.0889)
		(layer "In11.Cu")
		(net "M_F_CPU1_SB_DQ<11>")
	)
	(segment
		(start 60.39993 -291.937186)
		(end 60.39993 -291.509958)
		(width 0.14478)
		(layer "In11.Cu")
		(net "M_F_CPU1_SB_DQ<11>")
	)
	(segment
		(start 18.505678 -293.810436)
		(end 18.668746 -293.647368)
		(width 0.14478)
		(layer "In11.Cu")
		(net "M_F_CPU1_SB_DQ<11>")
	)
	(segment
		(start 17.608042 -293.38524)
		(end 18.033238 -293.810436)
		(width 0.14478)
		(layer "In11.Cu")
		(net "M_F_CPU1_SB_DQ<11>")
	)
	(segment
		(start 34.368486 -293.80053)
		(end 35.21837 -292.950646)
		(width 0.14478)
		(layer "In11.Cu")
		(net "M_F_CPU1_SB_DQ<11>")
	)
	(segment
		(start 27.587448 -292.950646)
		(end 30.534102 -292.950646)
		(width 0.14478)
		(layer "In11.Cu")
		(net "M_F_CPU1_SB_DQ<11>")
	)
	(segment
		(start 38.95344 -293.80053)
		(end 41.901872 -293.80053)
		(width 0.14478)
		(layer "In11.Cu")
		(net "M_F_CPU1_SB_DQ<11>")
	)
	(segment
		(start 85.981032 -280.275538)
		(end 86.077044 -280.300938)
		(width 0.0889)
		(layer "In11.Cu")
		(net "M_F_CPU1_SB_DQ<11>")
	)
	(segment
		(start 18.831814 -293.117016)
		(end 19.062192 -293.117016)
		(width 0.14478)
		(layer "In11.Cu")
		(net "M_F_CPU1_SB_DQ<11>")
	)
	(segment
		(start 19.062192 -293.117016)
		(end 19.22526 -293.280084)
		(width 0.14478)
		(layer "In11.Cu")
		(net "M_F_CPU1_SB_DQ<11>")
	)
	(segment
		(start 42.751756 -292.950646)
		(end 45.609002 -292.950646)
		(width 0.14478)
		(layer "In11.Cu")
		(net "M_F_CPU1_SB_DQ<11>")
	)
	(segment
		(start 49.399698 -293.80053)
		(end 50.249582 -292.950646)
		(width 0.14478)
		(layer "In11.Cu")
		(net "M_F_CPU1_SB_DQ<11>")
	)
	(segment
		(start 18.668746 -293.280084)
		(end 18.831814 -293.117016)
		(width 0.14478)
		(layer "In11.Cu")
		(net "M_F_CPU1_SB_DQ<11>")
	)
	(segment
		(start 53.145436 -292.950646)
		(end 53.609748 -293.414958)
		(width 0.14478)
		(layer "In11.Cu")
		(net "M_F_CPU1_SB_DQ<11>")
	)
	(segment
		(start 50.249582 -292.950646)
		(end 53.145436 -292.950646)
		(width 0.14478)
		(layer "In11.Cu")
		(net "M_F_CPU1_SB_DQ<11>")
	)
	(segment
		(start 41.901872 -293.80053)
		(end 42.751756 -292.950646)
		(width 0.14478)
		(layer "In11.Cu")
		(net "M_F_CPU1_SB_DQ<11>")
	)
	(segment
		(start 68.515992 -283.393896)
		(end 68.845176 -283.393896)
		(width 0.14478)
		(layer "In11.Cu")
		(net "M_F_CPU1_SB_DQ<11>")
	)
	(segment
		(start 19.378422 -293.80053)
		(end 26.737564 -293.80053)
		(width 0.14478)
		(layer "In11.Cu")
		(net "M_F_CPU1_SB_DQ<11>")
	)
	(segment
		(start 81.344008 -280.243788)
		(end 81.35239 -280.238962)
		(width 0.0889)
		(layer "In11.Cu")
		(net "M_F_CPU1_SB_DQ<11>")
	)
	(segment
		(start 31.383986 -293.80053)
		(end 34.368486 -293.80053)
		(width 0.14478)
		(layer "In11.Cu")
		(net "M_F_CPU1_SB_DQ<11>")
	)
	(segment
		(start 80.39354 -280.249884)
		(end 80.403954 -280.243788)
		(width 0.0889)
		(layer "In11.Cu")
		(net "M_F_CPU1_SB_DQ<11>")
	)
	(segment
		(start 38.103556 -292.950646)
		(end 38.95344 -293.80053)
		(width 0.14478)
		(layer "In11.Cu")
		(net "M_F_CPU1_SB_DQ<11>")
	)
	(segment
		(start 72.031098 -280.207974)
		(end 75.966066 -280.207974)
		(width 0.14478)
		(layer "In11.Cu")
		(net "M_F_CPU1_SB_DQ<11>")
	)
	(segment
		(start 85.10397 -280.243788)
		(end 85.112352 -280.238962)
		(width 0.0889)
		(layer "In11.Cu")
		(net "M_F_CPU1_SB_DQ<11>")
	)
	(segment
		(start 19.22526 -293.280084)
		(end 19.22526 -293.647368)
		(width 0.14478)
		(layer "In11.Cu")
		(net "M_F_CPU1_SB_DQ<11>")
	)
	(segment
		(start 83.589622 -280.238962)
		(end 83.598004 -280.243788)
		(width 0.0889)
		(layer "In11.Cu")
		(net "M_F_CPU1_SB_DQ<11>")
	)
	(segment
		(start 45.609002 -292.950646)
		(end 46.458886 -293.80053)
		(width 0.14478)
		(layer "In11.Cu")
		(net "M_F_CPU1_SB_DQ<11>")
	)
	(segment
		(start 60.39993 -291.509958)
		(end 68.515992 -283.393896)
		(width 0.14478)
		(layer "In11.Cu")
		(net "M_F_CPU1_SB_DQ<11>")
	)
	(segment
		(start 80.769714 -280.238962)
		(end 80.778096 -280.243788)
		(width 0.0889)
		(layer "In11.Cu")
		(net "M_F_CPU1_SB_DQ<11>")
	)
	(segment
		(start 59.653932 -292.683184)
		(end 60.39993 -291.937186)
		(width 0.14478)
		(layer "In11.Cu")
		(net "M_F_CPU1_SB_DQ<11>")
	)
	(segment
		(start 57.66689 -292.683184)
		(end 59.653932 -292.683184)
		(width 0.14478)
		(layer "In11.Cu")
		(net "M_F_CPU1_SB_DQ<11>")
	)
	(segment
		(start 53.609748 -293.414958)
		(end 56.935116 -293.414958)
		(width 0.14478)
		(layer "In11.Cu")
		(net "M_F_CPU1_SB_DQ<11>")
	)
	(segment
		(start 30.534102 -292.950646)
		(end 31.383986 -293.80053)
		(width 0.14478)
		(layer "In11.Cu")
		(net "M_F_CPU1_SB_DQ<11>")
	)
	(segment
		(start 19.22526 -293.647368)
		(end 19.378422 -293.80053)
		(width 0.14478)
		(layer "In11.Cu")
		(net "M_F_CPU1_SB_DQ<11>")
	)
	(segment
		(start 84.529676 -280.238962)
		(end 84.538058 -280.243788)
		(width 0.0889)
		(layer "In11.Cu")
		(net "M_F_CPU1_SB_DQ<11>")
	)
	(segment
		(start 76.240386 -280.127964)
		(end 79.40929 -280.127964)
		(width 0.0889)
		(layer "In11.Cu")
		(net "M_F_CPU1_SB_DQ<11>")
	)
	(segment
		(start 56.935116 -293.414958)
		(end 57.66689 -292.683184)
		(width 0.14478)
		(layer "In11.Cu")
		(net "M_F_CPU1_SB_DQ<11>")
	)
	(arc
		(start 79.40929 -280.127964)
		(mid 79.631234 -280.157419)
		(end 79.837788 -280.243788)
		(width 0.0889)
		(layer "In11.Cu")
		(net "M_F_CPU1_SB_DQ<11>")
	)
	(arc
		(start 79.837788 -280.243788)
		(mid 80.114855 -280.320059)
		(end 80.39354 -280.249884)
		(width 0.0889)
		(layer "In11.Cu")
		(net "M_F_CPU1_SB_DQ<11>")
	)
	(arc
		(start 83.598004 -280.243788)
		(mid 83.88096 -280.319965)
		(end 84.163916 -280.243788)
		(width 0.0889)
		(layer "In11.Cu")
		(net "M_F_CPU1_SB_DQ<11>")
	)
	(arc
		(start 82.284062 -280.243788)
		(mid 82.471006 -280.193533)
		(end 82.65795 -280.243788)
		(width 0.0889)
		(layer "In11.Cu")
		(net "M_F_CPU1_SB_DQ<11>")
	)
	(arc
		(start 80.403954 -280.243788)
		(mid 80.586205 -280.193438)
		(end 80.769714 -280.238962)
		(width 0.0889)
		(layer "In11.Cu")
		(net "M_F_CPU1_SB_DQ<11>")
	)
	(arc
		(start 83.223862 -280.243788)
		(mid 83.406113 -280.193438)
		(end 83.589622 -280.238962)
		(width 0.0889)
		(layer "In11.Cu")
		(net "M_F_CPU1_SB_DQ<11>")
	)
	(arc
		(start 80.778096 -280.243788)
		(mid 81.061052 -280.319965)
		(end 81.344008 -280.243788)
		(width 0.0889)
		(layer "In11.Cu")
		(net "M_F_CPU1_SB_DQ<11>")
	)
	(arc
		(start 81.71815 -280.243788)
		(mid 82.001106 -280.319965)
		(end 82.284062 -280.243788)
		(width 0.0889)
		(layer "In11.Cu")
		(net "M_F_CPU1_SB_DQ<11>")
	)
	(arc
		(start 85.112352 -280.238962)
		(mid 85.29586 -280.193468)
		(end 85.478112 -280.243788)
		(width 0.0889)
		(layer "In11.Cu")
		(net "M_F_CPU1_SB_DQ<11>")
	)
	(arc
		(start 84.163916 -280.243788)
		(mid 84.346167 -280.193438)
		(end 84.529676 -280.238962)
		(width 0.0889)
		(layer "In11.Cu")
		(net "M_F_CPU1_SB_DQ<11>")
	)
	(arc
		(start 82.65795 -280.243788)
		(mid 82.940906 -280.319965)
		(end 83.223862 -280.243788)
		(width 0.0889)
		(layer "In11.Cu")
		(net "M_F_CPU1_SB_DQ<11>")
	)
	(arc
		(start 85.478112 -280.243788)
		(mid 85.725825 -280.319008)
		(end 85.981032 -280.275538)
		(width 0.0889)
		(layer "In11.Cu")
		(net "M_F_CPU1_SB_DQ<11>")
	)
	(arc
		(start 81.35239 -280.238962)
		(mid 81.535898 -280.193468)
		(end 81.71815 -280.243788)
		(width 0.0889)
		(layer "In11.Cu")
		(net "M_F_CPU1_SB_DQ<11>")
	)
	(arc
		(start 84.538058 -280.243788)
		(mid 84.821014 -280.319965)
		(end 85.10397 -280.243788)
		(width 0.0889)
		(layer "In11.Cu")
		(net "M_F_CPU1_SB_DQ<11>")
	)
	(segment
		(start 85.287866 -279.490424)
		(end 84.821014 -279.756362)
		(width 0.10668)
		(layer "F.Cu")
		(net "M_F_CPU1_SB_DQ<10>")
	)
	(segment
		(start 83.694016 -279.433782)
		(end 83.702398 -279.428956)
		(width 0.0889)
		(layer "In11.Cu")
		(net "M_F_CPU1_SB_DQ<10>")
	)
	(segment
		(start 35.491928 -291.260276)
		(end 37.898832 -291.260276)
		(width 0.14478)
		(layer "In11.Cu")
		(net "M_F_CPU1_SB_DQ<10>")
	)
	(segment
		(start 53.211984 -291.260276)
		(end 54.062122 -292.110414)
		(width 0.14478)
		(layer "In11.Cu")
		(net "M_F_CPU1_SB_DQ<10>")
	)
	(segment
		(start 19.623786 -292.110414)
		(end 19.88566 -292.110414)
		(width 0.14478)
		(layer "In11.Cu")
		(net "M_F_CPU1_SB_DQ<10>")
	)
	(segment
		(start 18.033238 -292.110414)
		(end 18.782792 -292.110414)
		(width 0.14478)
		(layer "In11.Cu")
		(net "M_F_CPU1_SB_DQ<10>")
	)
	(segment
		(start 54.062122 -292.110414)
		(end 56.95315 -292.110414)
		(width 0.14478)
		(layer "In11.Cu")
		(net "M_F_CPU1_SB_DQ<10>")
	)
	(segment
		(start 45.335952 -291.260276)
		(end 46.18609 -292.110414)
		(width 0.14478)
		(layer "In11.Cu")
		(net "M_F_CPU1_SB_DQ<10>")
	)
	(segment
		(start 18.927572 -291.965634)
		(end 18.927572 -291.495226)
		(width 0.14478)
		(layer "In11.Cu")
		(net "M_F_CPU1_SB_DQ<10>")
	)
	(segment
		(start 82.179668 -279.428956)
		(end 82.18805 -279.433782)
		(width 0.0889)
		(layer "In11.Cu")
		(net "M_F_CPU1_SB_DQ<10>")
	)
	(segment
		(start 20.17522 -291.350446)
		(end 20.437094 -291.350446)
		(width 0.14478)
		(layer "In11.Cu")
		(net "M_F_CPU1_SB_DQ<10>")
	)
	(segment
		(start 71.338948 -279.298654)
		(end 76.378816 -279.298654)
		(width 0.14478)
		(layer "In11.Cu")
		(net "M_F_CPU1_SB_DQ<10>")
	)
	(segment
		(start 76.630276 -279.047194)
		(end 78.01483 -279.047194)
		(width 0.0889)
		(layer "In11.Cu")
		(net "M_F_CPU1_SB_DQ<10>")
	)
	(segment
		(start 27.072082 -292.110414)
		(end 27.92222 -291.260276)
		(width 0.14478)
		(layer "In11.Cu")
		(net "M_F_CPU1_SB_DQ<10>")
	)
	(segment
		(start 42.032682 -292.110414)
		(end 42.88282 -291.260276)
		(width 0.14478)
		(layer "In11.Cu")
		(net "M_F_CPU1_SB_DQ<10>")
	)
	(segment
		(start 38.74897 -292.110414)
		(end 42.032682 -292.110414)
		(width 0.14478)
		(layer "In11.Cu")
		(net "M_F_CPU1_SB_DQ<10>")
	)
	(segment
		(start 84.571078 -279.465532)
		(end 84.66709 -279.490932)
		(width 0.0889)
		(layer "In11.Cu")
		(net "M_F_CPU1_SB_DQ<10>")
	)
	(segment
		(start 42.88282 -291.260276)
		(end 45.335952 -291.260276)
		(width 0.14478)
		(layer "In11.Cu")
		(net "M_F_CPU1_SB_DQ<10>")
	)
	(segment
		(start 78.42885 -279.434036)
		(end 78.45044 -279.446482)
		(width 0.0889)
		(layer "In11.Cu")
		(net "M_F_CPU1_SB_DQ<10>")
	)
	(segment
		(start 20.437094 -291.350446)
		(end 20.581874 -291.495226)
		(width 0.14478)
		(layer "In11.Cu")
		(net "M_F_CPU1_SB_DQ<10>")
	)
	(segment
		(start 19.479006 -291.495226)
		(end 19.479006 -291.965634)
		(width 0.14478)
		(layer "In11.Cu")
		(net "M_F_CPU1_SB_DQ<10>")
	)
	(segment
		(start 19.072352 -291.350446)
		(end 19.334226 -291.350446)
		(width 0.14478)
		(layer "In11.Cu")
		(net "M_F_CPU1_SB_DQ<10>")
	)
	(segment
		(start 18.782792 -292.110414)
		(end 18.927572 -291.965634)
		(width 0.14478)
		(layer "In11.Cu")
		(net "M_F_CPU1_SB_DQ<10>")
	)
	(segment
		(start 49.43475 -292.110414)
		(end 50.284888 -291.260276)
		(width 0.14478)
		(layer "In11.Cu")
		(net "M_F_CPU1_SB_DQ<10>")
	)
	(segment
		(start 20.03044 -291.495226)
		(end 20.17522 -291.350446)
		(width 0.14478)
		(layer "In11.Cu")
		(net "M_F_CPU1_SB_DQ<10>")
	)
	(segment
		(start 27.92222 -291.260276)
		(end 30.324552 -291.260276)
		(width 0.14478)
		(layer "In11.Cu")
		(net "M_F_CPU1_SB_DQ<10>")
	)
	(segment
		(start 50.284888 -291.260276)
		(end 53.211984 -291.260276)
		(width 0.14478)
		(layer "In11.Cu")
		(net "M_F_CPU1_SB_DQ<10>")
	)
	(segment
		(start 17.608042 -291.685218)
		(end 18.033238 -292.110414)
		(width 0.14478)
		(layer "In11.Cu")
		(net "M_F_CPU1_SB_DQ<10>")
	)
	(segment
		(start 19.479006 -291.965634)
		(end 19.623786 -292.110414)
		(width 0.14478)
		(layer "In11.Cu")
		(net "M_F_CPU1_SB_DQ<10>")
	)
	(segment
		(start 18.927572 -291.495226)
		(end 19.072352 -291.350446)
		(width 0.14478)
		(layer "In11.Cu")
		(net "M_F_CPU1_SB_DQ<10>")
	)
	(segment
		(start 46.18609 -292.110414)
		(end 49.43475 -292.110414)
		(width 0.14478)
		(layer "In11.Cu")
		(net "M_F_CPU1_SB_DQ<10>")
	)
	(segment
		(start 57.803288 -291.260276)
		(end 59.377326 -291.260276)
		(width 0.14478)
		(layer "In11.Cu")
		(net "M_F_CPU1_SB_DQ<10>")
	)
	(segment
		(start 76.378816 -279.298654)
		(end 76.630276 -279.047194)
		(width 0.0889)
		(layer "In11.Cu")
		(net "M_F_CPU1_SB_DQ<10>")
	)
	(segment
		(start 20.03044 -291.965634)
		(end 20.03044 -291.495226)
		(width 0.14478)
		(layer "In11.Cu")
		(net "M_F_CPU1_SB_DQ<10>")
	)
	(segment
		(start 37.898832 -291.260276)
		(end 38.74897 -292.110414)
		(width 0.14478)
		(layer "In11.Cu")
		(net "M_F_CPU1_SB_DQ<10>")
	)
	(segment
		(start 56.95315 -292.110414)
		(end 57.803288 -291.260276)
		(width 0.14478)
		(layer "In11.Cu")
		(net "M_F_CPU1_SB_DQ<10>")
	)
	(segment
		(start 19.88566 -292.110414)
		(end 20.03044 -291.965634)
		(width 0.14478)
		(layer "In11.Cu")
		(net "M_F_CPU1_SB_DQ<10>")
	)
	(segment
		(start 20.581874 -291.965634)
		(end 20.726654 -292.110414)
		(width 0.14478)
		(layer "In11.Cu")
		(net "M_F_CPU1_SB_DQ<10>")
	)
	(segment
		(start 82.753962 -279.433782)
		(end 82.762344 -279.428956)
		(width 0.0889)
		(layer "In11.Cu")
		(net "M_F_CPU1_SB_DQ<10>")
	)
	(segment
		(start 20.726654 -292.110414)
		(end 27.072082 -292.110414)
		(width 0.14478)
		(layer "In11.Cu")
		(net "M_F_CPU1_SB_DQ<10>")
	)
	(segment
		(start 84.66709 -279.490932)
		(end 84.821014 -279.756362)
		(width 0.0889)
		(layer "In11.Cu")
		(net "M_F_CPU1_SB_DQ<10>")
	)
	(segment
		(start 34.64179 -292.110414)
		(end 35.491928 -291.260276)
		(width 0.14478)
		(layer "In11.Cu")
		(net "M_F_CPU1_SB_DQ<10>")
	)
	(segment
		(start 20.581874 -291.495226)
		(end 20.581874 -291.965634)
		(width 0.14478)
		(layer "In11.Cu")
		(net "M_F_CPU1_SB_DQ<10>")
	)
	(segment
		(start 79.357474 -279.426924)
		(end 79.369158 -279.433782)
		(width 0.0889)
		(layer "In11.Cu")
		(net "M_F_CPU1_SB_DQ<10>")
	)
	(segment
		(start 79.92237 -279.440894)
		(end 79.934308 -279.434036)
		(width 0.0889)
		(layer "In11.Cu")
		(net "M_F_CPU1_SB_DQ<10>")
	)
	(segment
		(start 59.377326 -291.260276)
		(end 71.338948 -279.298654)
		(width 0.14478)
		(layer "In11.Cu")
		(net "M_F_CPU1_SB_DQ<10>")
	)
	(segment
		(start 31.17469 -292.110414)
		(end 34.64179 -292.110414)
		(width 0.14478)
		(layer "In11.Cu")
		(net "M_F_CPU1_SB_DQ<10>")
	)
	(segment
		(start 30.324552 -291.260276)
		(end 31.17469 -292.110414)
		(width 0.14478)
		(layer "In11.Cu")
		(net "M_F_CPU1_SB_DQ<10>")
	)
	(segment
		(start 19.334226 -291.350446)
		(end 19.479006 -291.495226)
		(width 0.14478)
		(layer "In11.Cu")
		(net "M_F_CPU1_SB_DQ<10>")
	)
	(segment
		(start 78.01483 -279.047194)
		(end 78.312518 -279.344882)
		(width 0.0889)
		(layer "In11.Cu")
		(net "M_F_CPU1_SB_DQ<10>")
	)
	(segment
		(start 79.934308 -279.434036)
		(end 79.950564 -279.424638)
		(width 0.0889)
		(layer "In11.Cu")
		(net "M_F_CPU1_SB_DQ<10>")
	)
	(arc
		(start 78.45044 -279.446482)
		(mid 78.72423 -279.510153)
		(end 78.994762 -279.433782)
		(width 0.0889)
		(layer "In11.Cu")
		(net "M_F_CPU1_SB_DQ<10>")
	)
	(arc
		(start 78.312518 -279.344882)
		(mid 78.367768 -279.393264)
		(end 78.42885 -279.434036)
		(width 0.0889)
		(layer "In11.Cu")
		(net "M_F_CPU1_SB_DQ<10>")
	)
	(arc
		(start 82.762344 -279.428956)
		(mid 82.945852 -279.383462)
		(end 83.128104 -279.433782)
		(width 0.0889)
		(layer "In11.Cu")
		(net "M_F_CPU1_SB_DQ<10>")
	)
	(arc
		(start 79.950564 -279.424638)
		(mid 80.130546 -279.383538)
		(end 80.308196 -279.433782)
		(width 0.0889)
		(layer "In11.Cu")
		(net "M_F_CPU1_SB_DQ<10>")
	)
	(arc
		(start 80.308196 -279.433782)
		(mid 80.591152 -279.509959)
		(end 80.874108 -279.433782)
		(width 0.0889)
		(layer "In11.Cu")
		(net "M_F_CPU1_SB_DQ<10>")
	)
	(arc
		(start 83.702398 -279.428956)
		(mid 83.885906 -279.383462)
		(end 84.068158 -279.433782)
		(width 0.0889)
		(layer "In11.Cu")
		(net "M_F_CPU1_SB_DQ<10>")
	)
	(arc
		(start 78.994762 -279.433782)
		(mid 79.17522 -279.383338)
		(end 79.357474 -279.426924)
		(width 0.0889)
		(layer "In11.Cu")
		(net "M_F_CPU1_SB_DQ<10>")
	)
	(arc
		(start 81.247996 -279.433782)
		(mid 81.530952 -279.509959)
		(end 81.813908 -279.433782)
		(width 0.0889)
		(layer "In11.Cu")
		(net "M_F_CPU1_SB_DQ<10>")
	)
	(arc
		(start 80.874108 -279.433782)
		(mid 81.061052 -279.383527)
		(end 81.247996 -279.433782)
		(width 0.0889)
		(layer "In11.Cu")
		(net "M_F_CPU1_SB_DQ<10>")
	)
	(arc
		(start 84.068158 -279.433782)
		(mid 84.315871 -279.509002)
		(end 84.571078 -279.465532)
		(width 0.0889)
		(layer "In11.Cu")
		(net "M_F_CPU1_SB_DQ<10>")
	)
	(arc
		(start 81.813908 -279.433782)
		(mid 81.996159 -279.383432)
		(end 82.179668 -279.428956)
		(width 0.0889)
		(layer "In11.Cu")
		(net "M_F_CPU1_SB_DQ<10>")
	)
	(arc
		(start 82.18805 -279.433782)
		(mid 82.471006 -279.509959)
		(end 82.753962 -279.433782)
		(width 0.0889)
		(layer "In11.Cu")
		(net "M_F_CPU1_SB_DQ<10>")
	)
	(arc
		(start 79.369158 -279.433782)
		(mid 79.644836 -279.509912)
		(end 79.92237 -279.440894)
		(width 0.0889)
		(layer "In11.Cu")
		(net "M_F_CPU1_SB_DQ<10>")
	)
	(arc
		(start 83.128104 -279.433782)
		(mid 83.41106 -279.509959)
		(end 83.694016 -279.433782)
		(width 0.0889)
		(layer "In11.Cu")
		(net "M_F_CPU1_SB_DQ<10>")
	)
	(segment
		(start 84.817966 -273.820382)
		(end 84.351114 -274.08632)
		(width 0.10668)
		(layer "F.Cu")
		(net "M_F_CPU1_SB_DQ<0>")
	)
	(segment
		(start 61.431932 -278.683212)
		(end 61.617606 -278.497538)
		(width 0.14478)
		(layer "In11.Cu")
		(net "M_F_CPU1_SB_DQ<0>")
	)
	(segment
		(start 39.965122 -281.910282)
		(end 40.835072 -281.910282)
		(width 0.14478)
		(layer "In11.Cu")
		(net "M_F_CPU1_SB_DQ<0>")
	)
	(segment
		(start 24.717248 -281.910282)
		(end 25.60193 -281.910282)
		(width 0.14478)
		(layer "In11.Cu")
		(net "M_F_CPU1_SB_DQ<0>")
	)
	(segment
		(start 84.482686 -274.435062)
		(end 84.505038 -274.35175)
		(width 0.0889)
		(layer "In11.Cu")
		(net "M_F_CPU1_SB_DQ<0>")
	)
	(segment
		(start 63.95847 -276.156674)
		(end 64.163194 -276.156674)
		(width 0.14478)
		(layer "In11.Cu")
		(net "M_F_CPU1_SB_DQ<0>")
	)
	(segment
		(start 41.126664 -281.61869)
		(end 41.357296 -281.61869)
		(width 0.14478)
		(layer "In11.Cu")
		(net "M_F_CPU1_SB_DQ<0>")
	)
	(segment
		(start 61.495432 -279.155398)
		(end 61.495432 -278.950674)
		(width 0.14478)
		(layer "In11.Cu")
		(net "M_F_CPU1_SB_DQ<0>")
	)
	(segment
		(start 76.976986 -273.473164)
		(end 77.57033 -273.473164)
		(width 0.0889)
		(layer "In11.Cu")
		(net "M_F_CPU1_SB_DQ<0>")
	)
	(segment
		(start 39.279322 -282.133294)
		(end 39.279322 -281.780742)
		(width 0.14478)
		(layer "In11.Cu")
		(net "M_F_CPU1_SB_DQ<0>")
	)
	(segment
		(start 39.279322 -281.780742)
		(end 39.442136 -281.617928)
		(width 0.14478)
		(layer "In11.Cu")
		(net "M_F_CPU1_SB_DQ<0>")
	)
	(segment
		(start 61.82233 -278.497538)
		(end 61.885576 -278.560784)
		(width 0.14478)
		(layer "In11.Cu")
		(net "M_F_CPU1_SB_DQ<0>")
	)
	(segment
		(start 25.893268 -281.618944)
		(end 26.1239 -281.618944)
		(width 0.14478)
		(layer "In11.Cu")
		(net "M_F_CPU1_SB_DQ<0>")
	)
	(segment
		(start 45.219112 -281.060144)
		(end 46.06925 -281.910282)
		(width 0.14478)
		(layer "In11.Cu")
		(net "M_F_CPU1_SB_DQ<0>")
	)
	(segment
		(start 53.71465 -281.910282)
		(end 56.863742 -281.910282)
		(width 0.14478)
		(layer "In11.Cu")
		(net "M_F_CPU1_SB_DQ<0>")
	)
	(segment
		(start 67.430396 -273.220434)
		(end 75.987656 -273.220434)
		(width 0.14478)
		(layer "In11.Cu")
		(net "M_F_CPU1_SB_DQ<0>")
	)
	(segment
		(start 26.286714 -282.12923)
		(end 26.449528 -282.292044)
		(width 0.14478)
		(layer "In11.Cu")
		(net "M_F_CPU1_SB_DQ<0>")
	)
	(segment
		(start 21.70811 -281.48534)
		(end 22.527514 -282.304744)
		(width 0.14478)
		(layer "In11.Cu")
		(net "M_F_CPU1_SB_DQ<0>")
	)
	(segment
		(start 41.521888 -281.783282)
		(end 41.521888 -282.134056)
		(width 0.14478)
		(layer "In11.Cu")
		(net "M_F_CPU1_SB_DQ<0>")
	)
	(segment
		(start 61.495432 -278.950674)
		(end 61.432186 -278.887428)
		(width 0.14478)
		(layer "In11.Cu")
		(net "M_F_CPU1_SB_DQ<0>")
	)
	(segment
		(start 52.864512 -281.060144)
		(end 53.71465 -281.910282)
		(width 0.14478)
		(layer "In11.Cu")
		(net "M_F_CPU1_SB_DQ<0>")
	)
	(segment
		(start 63.178182 -276.936962)
		(end 63.382906 -276.936962)
		(width 0.14478)
		(layer "In11.Cu")
		(net "M_F_CPU1_SB_DQ<0>")
	)
	(segment
		(start 26.449528 -282.292044)
		(end 26.68016 -282.292044)
		(width 0.14478)
		(layer "In11.Cu")
		(net "M_F_CPU1_SB_DQ<0>")
	)
	(segment
		(start 22.92096 -281.782774)
		(end 23.083774 -281.61996)
		(width 0.14478)
		(layer "In11.Cu")
		(net "M_F_CPU1_SB_DQ<0>")
	)
	(segment
		(start 35.8775 -281.204924)
		(end 36.02228 -281.349704)
		(width 0.14478)
		(layer "In11.Cu")
		(net "M_F_CPU1_SB_DQ<0>")
	)
	(segment
		(start 78.447138 -274.349972)
		(end 78.447392 -274.349972)
		(width 0.0889)
		(layer "In11.Cu")
		(net "M_F_CPU1_SB_DQ<0>")
	)
	(segment
		(start 24.426926 -281.61996)
		(end 24.717248 -281.910282)
		(width 0.14478)
		(layer "In11.Cu")
		(net "M_F_CPU1_SB_DQ<0>")
	)
	(segment
		(start 65.006728 -275.439632)
		(end 65.211452 -275.439378)
		(width 0.14478)
		(layer "In11.Cu")
		(net "M_F_CPU1_SB_DQ<0>")
	)
	(segment
		(start 79.825088 -274.41652)
		(end 79.838804 -274.408646)
		(width 0.0889)
		(layer "In11.Cu")
		(net "M_F_CPU1_SB_DQ<0>")
	)
	(segment
		(start 40.835072 -281.910282)
		(end 41.126664 -281.61869)
		(width 0.14478)
		(layer "In11.Cu")
		(net "M_F_CPU1_SB_DQ<0>")
	)
	(segment
		(start 57.71388 -281.060144)
		(end 59.590686 -281.060144)
		(width 0.14478)
		(layer "In11.Cu")
		(net "M_F_CPU1_SB_DQ<0>")
	)
	(segment
		(start 79.447136 -274.398232)
		(end 79.46517 -274.4089)
		(width 0.0889)
		(layer "In11.Cu")
		(net "M_F_CPU1_SB_DQ<0>")
	)
	(segment
		(start 35.46602 -280.770584)
		(end 35.73272 -280.770584)
		(width 0.14478)
		(layer "In11.Cu")
		(net "M_F_CPU1_SB_DQ<0>")
	)
	(segment
		(start 61.617606 -278.497538)
		(end 61.82233 -278.497538)
		(width 0.14478)
		(layer "In11.Cu")
		(net "M_F_CPU1_SB_DQ<0>")
	)
	(segment
		(start 63.650876 -276.999954)
		(end 63.836296 -276.814534)
		(width 0.14478)
		(layer "In11.Cu")
		(net "M_F_CPU1_SB_DQ<0>")
	)
	(segment
		(start 84.505038 -274.35175)
		(end 84.351114 -274.08632)
		(width 0.0889)
		(layer "In11.Cu")
		(net "M_F_CPU1_SB_DQ<0>")
	)
	(segment
		(start 63.836296 -276.814534)
		(end 63.836296 -276.60981)
		(width 0.14478)
		(layer "In11.Cu")
		(net "M_F_CPU1_SB_DQ<0>")
	)
	(segment
		(start 23.47722 -282.14193)
		(end 23.640034 -282.304744)
		(width 0.14478)
		(layer "In11.Cu")
		(net "M_F_CPU1_SB_DQ<0>")
	)
	(segment
		(start 27.91206 -281.060144)
		(end 30.588712 -281.060144)
		(width 0.14478)
		(layer "In11.Cu")
		(net "M_F_CPU1_SB_DQ<0>")
	)
	(segment
		(start 24.03348 -281.782774)
		(end 24.196294 -281.61996)
		(width 0.14478)
		(layer "In11.Cu")
		(net "M_F_CPU1_SB_DQ<0>")
	)
	(segment
		(start 61.885576 -278.560784)
		(end 62.0903 -278.56053)
		(width 0.14478)
		(layer "In11.Cu")
		(net "M_F_CPU1_SB_DQ<0>")
	)
	(segment
		(start 62.27572 -278.170386)
		(end 62.212474 -278.10714)
		(width 0.14478)
		(layer "In11.Cu")
		(net "M_F_CPU1_SB_DQ<0>")
	)
	(segment
		(start 43.15206 -281.060144)
		(end 45.219112 -281.060144)
		(width 0.14478)
		(layer "In11.Cu")
		(net "M_F_CPU1_SB_DQ<0>")
	)
	(segment
		(start 35.73272 -280.770584)
		(end 35.8775 -280.915364)
		(width 0.14478)
		(layer "In11.Cu")
		(net "M_F_CPU1_SB_DQ<0>")
	)
	(segment
		(start 22.527514 -282.304744)
		(end 22.758146 -282.304744)
		(width 0.14478)
		(layer "In11.Cu")
		(net "M_F_CPU1_SB_DQ<0>")
	)
	(segment
		(start 41.357296 -281.61869)
		(end 41.521888 -281.783282)
		(width 0.14478)
		(layer "In11.Cu")
		(net "M_F_CPU1_SB_DQ<0>")
	)
	(segment
		(start 41.521888 -282.134056)
		(end 41.684702 -282.29687)
		(width 0.14478)
		(layer "In11.Cu")
		(net "M_F_CPU1_SB_DQ<0>")
	)
	(segment
		(start 62.665864 -277.780496)
		(end 62.870588 -277.780242)
		(width 0.14478)
		(layer "In11.Cu")
		(net "M_F_CPU1_SB_DQ<0>")
	)
	(segment
		(start 50.330608 -281.060144)
		(end 52.864512 -281.060144)
		(width 0.14478)
		(layer "In11.Cu")
		(net "M_F_CPU1_SB_DQ<0>")
	)
	(segment
		(start 75.987656 -273.220434)
		(end 76.724256 -273.220434)
		(width 0.0889)
		(layer "In11.Cu")
		(net "M_F_CPU1_SB_DQ<0>")
	)
	(segment
		(start 59.590686 -281.060144)
		(end 61.495432 -279.155398)
		(width 0.14478)
		(layer "In11.Cu")
		(net "M_F_CPU1_SB_DQ<0>")
	)
	(segment
		(start 39.442136 -281.617928)
		(end 39.672768 -281.617928)
		(width 0.14478)
		(layer "In11.Cu")
		(net "M_F_CPU1_SB_DQ<0>")
	)
	(segment
		(start 36.02228 -281.349704)
		(end 36.28898 -281.349704)
		(width 0.14478)
		(layer "In11.Cu")
		(net "M_F_CPU1_SB_DQ<0>")
	)
	(segment
		(start 80.769714 -274.413726)
		(end 80.778096 -274.4089)
		(width 0.0889)
		(layer "In11.Cu")
		(net "M_F_CPU1_SB_DQ<0>")
	)
	(segment
		(start 38.885876 -282.296108)
		(end 39.116508 -282.296108)
		(width 0.14478)
		(layer "In11.Cu")
		(net "M_F_CPU1_SB_DQ<0>")
	)
	(segment
		(start 23.083774 -281.61996)
		(end 23.314406 -281.61996)
		(width 0.14478)
		(layer "In11.Cu")
		(net "M_F_CPU1_SB_DQ<0>")
	)
	(segment
		(start 64.616584 -275.829522)
		(end 64.553338 -275.766276)
		(width 0.14478)
		(layer "In11.Cu")
		(net "M_F_CPU1_SB_DQ<0>")
	)
	(segment
		(start 49.48047 -281.910282)
		(end 50.330608 -281.060144)
		(width 0.14478)
		(layer "In11.Cu")
		(net "M_F_CPU1_SB_DQ<0>")
	)
	(segment
		(start 22.758146 -282.304744)
		(end 22.92096 -282.14193)
		(width 0.14478)
		(layer "In11.Cu")
		(net "M_F_CPU1_SB_DQ<0>")
	)
	(segment
		(start 41.915334 -282.29687)
		(end 43.15206 -281.060144)
		(width 0.14478)
		(layer "In11.Cu")
		(net "M_F_CPU1_SB_DQ<0>")
	)
	(segment
		(start 64.738758 -275.376386)
		(end 64.943482 -275.376386)
		(width 0.14478)
		(layer "In11.Cu")
		(net "M_F_CPU1_SB_DQ<0>")
	)
	(segment
		(start 81.344008 -274.4089)
		(end 81.35239 -274.413726)
		(width 0.0889)
		(layer "In11.Cu")
		(net "M_F_CPU1_SB_DQ<0>")
	)
	(segment
		(start 63.056008 -277.390098)
		(end 62.992762 -277.326852)
		(width 0.14478)
		(layer "In11.Cu")
		(net "M_F_CPU1_SB_DQ<0>")
	)
	(segment
		(start 64.163194 -276.156674)
		(end 64.22644 -276.21992)
		(width 0.14478)
		(layer "In11.Cu")
		(net "M_F_CPU1_SB_DQ<0>")
	)
	(segment
		(start 62.27572 -278.37511)
		(end 62.27572 -278.170386)
		(width 0.14478)
		(layer "In11.Cu")
		(net "M_F_CPU1_SB_DQ<0>")
	)
	(segment
		(start 62.21222 -277.902924)
		(end 62.397894 -277.71725)
		(width 0.14478)
		(layer "In11.Cu")
		(net "M_F_CPU1_SB_DQ<0>")
	)
	(segment
		(start 26.286714 -281.781758)
		(end 26.286714 -282.12923)
		(width 0.14478)
		(layer "In11.Cu")
		(net "M_F_CPU1_SB_DQ<0>")
	)
	(segment
		(start 22.92096 -282.14193)
		(end 22.92096 -281.782774)
		(width 0.14478)
		(layer "In11.Cu")
		(net "M_F_CPU1_SB_DQ<0>")
	)
	(segment
		(start 34.326322 -281.910282)
		(end 35.46602 -280.770584)
		(width 0.14478)
		(layer "In11.Cu")
		(net "M_F_CPU1_SB_DQ<0>")
	)
	(segment
		(start 31.43885 -281.910282)
		(end 34.326322 -281.910282)
		(width 0.14478)
		(layer "In11.Cu")
		(net "M_F_CPU1_SB_DQ<0>")
	)
	(segment
		(start 62.212474 -278.10714)
		(end 62.21222 -277.902924)
		(width 0.14478)
		(layer "In11.Cu")
		(net "M_F_CPU1_SB_DQ<0>")
	)
	(segment
		(start 26.68016 -282.292044)
		(end 27.91206 -281.060144)
		(width 0.14478)
		(layer "In11.Cu")
		(net "M_F_CPU1_SB_DQ<0>")
	)
	(segment
		(start 62.870588 -277.780242)
		(end 63.056008 -277.594822)
		(width 0.14478)
		(layer "In11.Cu")
		(net "M_F_CPU1_SB_DQ<0>")
	)
	(segment
		(start 36.57854 -281.060144)
		(end 37.649912 -281.060144)
		(width 0.14478)
		(layer "In11.Cu")
		(net "M_F_CPU1_SB_DQ<0>")
	)
	(segment
		(start 56.863742 -281.910282)
		(end 57.71388 -281.060144)
		(width 0.14478)
		(layer "In11.Cu")
		(net "M_F_CPU1_SB_DQ<0>")
	)
	(segment
		(start 63.382906 -276.936962)
		(end 63.446152 -277.000208)
		(width 0.14478)
		(layer "In11.Cu")
		(net "M_F_CPU1_SB_DQ<0>")
	)
	(segment
		(start 64.553338 -275.766276)
		(end 64.553084 -275.56206)
		(width 0.14478)
		(layer "In11.Cu")
		(net "M_F_CPU1_SB_DQ<0>")
	)
	(segment
		(start 62.992508 -277.122636)
		(end 63.178182 -276.936962)
		(width 0.14478)
		(layer "In11.Cu")
		(net "M_F_CPU1_SB_DQ<0>")
	)
	(segment
		(start 62.0903 -278.56053)
		(end 62.27572 -278.37511)
		(width 0.14478)
		(layer "In11.Cu")
		(net "M_F_CPU1_SB_DQ<0>")
	)
	(segment
		(start 26.1239 -281.618944)
		(end 26.286714 -281.781758)
		(width 0.14478)
		(layer "In11.Cu")
		(net "M_F_CPU1_SB_DQ<0>")
	)
	(segment
		(start 64.431164 -276.219666)
		(end 64.616584 -276.034246)
		(width 0.14478)
		(layer "In11.Cu")
		(net "M_F_CPU1_SB_DQ<0>")
	)
	(segment
		(start 76.724256 -273.220434)
		(end 76.976986 -273.473164)
		(width 0.0889)
		(layer "In11.Cu")
		(net "M_F_CPU1_SB_DQ<0>")
	)
	(segment
		(start 30.588712 -281.060144)
		(end 31.43885 -281.910282)
		(width 0.14478)
		(layer "In11.Cu")
		(net "M_F_CPU1_SB_DQ<0>")
	)
	(segment
		(start 63.772796 -276.342348)
		(end 63.95847 -276.156674)
		(width 0.14478)
		(layer "In11.Cu")
		(net "M_F_CPU1_SB_DQ<0>")
	)
	(segment
		(start 63.77305 -276.546564)
		(end 63.772796 -276.342348)
		(width 0.14478)
		(layer "In11.Cu")
		(net "M_F_CPU1_SB_DQ<0>")
	)
	(segment
		(start 64.616584 -276.034246)
		(end 64.616584 -275.829522)
		(width 0.14478)
		(layer "In11.Cu")
		(net "M_F_CPU1_SB_DQ<0>")
	)
	(segment
		(start 46.06925 -281.910282)
		(end 49.48047 -281.910282)
		(width 0.14478)
		(layer "In11.Cu")
		(net "M_F_CPU1_SB_DQ<0>")
	)
	(segment
		(start 39.672768 -281.617928)
		(end 39.965122 -281.910282)
		(width 0.14478)
		(layer "In11.Cu")
		(net "M_F_CPU1_SB_DQ<0>")
	)
	(segment
		(start 24.196294 -281.61996)
		(end 24.426926 -281.61996)
		(width 0.14478)
		(layer "In11.Cu")
		(net "M_F_CPU1_SB_DQ<0>")
	)
	(segment
		(start 78.524608 -274.408646)
		(end 78.544674 -274.420076)
		(width 0.0889)
		(layer "In11.Cu")
		(net "M_F_CPU1_SB_DQ<0>")
	)
	(segment
		(start 62.397894 -277.71725)
		(end 62.602618 -277.71725)
		(width 0.14478)
		(layer "In11.Cu")
		(net "M_F_CPU1_SB_DQ<0>")
	)
	(segment
		(start 61.432186 -278.887428)
		(end 61.431932 -278.683212)
		(width 0.14478)
		(layer "In11.Cu")
		(net "M_F_CPU1_SB_DQ<0>")
	)
	(segment
		(start 25.60193 -281.910282)
		(end 25.893268 -281.618944)
		(width 0.14478)
		(layer "In11.Cu")
		(net "M_F_CPU1_SB_DQ<0>")
	)
	(segment
		(start 62.602618 -277.71725)
		(end 62.665864 -277.780496)
		(width 0.14478)
		(layer "In11.Cu")
		(net "M_F_CPU1_SB_DQ<0>")
	)
	(segment
		(start 83.589622 -274.413726)
		(end 83.598004 -274.4089)
		(width 0.0889)
		(layer "In11.Cu")
		(net "M_F_CPU1_SB_DQ<0>")
	)
	(segment
		(start 77.57033 -273.473164)
		(end 78.447138 -274.349972)
		(width 0.0889)
		(layer "In11.Cu")
		(net "M_F_CPU1_SB_DQ<0>")
	)
	(segment
		(start 64.22644 -276.21992)
		(end 64.431164 -276.219666)
		(width 0.14478)
		(layer "In11.Cu")
		(net "M_F_CPU1_SB_DQ<0>")
	)
	(segment
		(start 23.314406 -281.61996)
		(end 23.47722 -281.782774)
		(width 0.14478)
		(layer "In11.Cu")
		(net "M_F_CPU1_SB_DQ<0>")
	)
	(segment
		(start 37.649912 -281.060144)
		(end 38.885876 -282.296108)
		(width 0.14478)
		(layer "In11.Cu")
		(net "M_F_CPU1_SB_DQ<0>")
	)
	(segment
		(start 23.640034 -282.304744)
		(end 23.870666 -282.304744)
		(width 0.14478)
		(layer "In11.Cu")
		(net "M_F_CPU1_SB_DQ<0>")
	)
	(segment
		(start 64.553084 -275.56206)
		(end 64.738758 -275.376386)
		(width 0.14478)
		(layer "In11.Cu")
		(net "M_F_CPU1_SB_DQ<0>")
	)
	(segment
		(start 41.684702 -282.29687)
		(end 41.915334 -282.29687)
		(width 0.14478)
		(layer "In11.Cu")
		(net "M_F_CPU1_SB_DQ<0>")
	)
	(segment
		(start 79.838804 -274.408646)
		(end 79.850742 -274.401788)
		(width 0.0889)
		(layer "In11.Cu")
		(net "M_F_CPU1_SB_DQ<0>")
	)
	(segment
		(start 64.943482 -275.376386)
		(end 65.006728 -275.439632)
		(width 0.14478)
		(layer "In11.Cu")
		(net "M_F_CPU1_SB_DQ<0>")
	)
	(segment
		(start 63.836296 -276.60981)
		(end 63.77305 -276.546564)
		(width 0.14478)
		(layer "In11.Cu")
		(net "M_F_CPU1_SB_DQ<0>")
	)
	(segment
		(start 36.28898 -281.349704)
		(end 36.57854 -281.060144)
		(width 0.14478)
		(layer "In11.Cu")
		(net "M_F_CPU1_SB_DQ<0>")
	)
	(segment
		(start 65.211452 -275.439378)
		(end 67.430396 -273.220434)
		(width 0.14478)
		(layer "In11.Cu")
		(net "M_F_CPU1_SB_DQ<0>")
	)
	(segment
		(start 24.03348 -282.14193)
		(end 24.03348 -281.782774)
		(width 0.14478)
		(layer "In11.Cu")
		(net "M_F_CPU1_SB_DQ<0>")
	)
	(segment
		(start 62.992762 -277.326852)
		(end 62.992508 -277.122636)
		(width 0.14478)
		(layer "In11.Cu")
		(net "M_F_CPU1_SB_DQ<0>")
	)
	(segment
		(start 39.116508 -282.296108)
		(end 39.279322 -282.133294)
		(width 0.14478)
		(layer "In11.Cu")
		(net "M_F_CPU1_SB_DQ<0>")
	)
	(segment
		(start 23.47722 -281.782774)
		(end 23.47722 -282.14193)
		(width 0.14478)
		(layer "In11.Cu")
		(net "M_F_CPU1_SB_DQ<0>")
	)
	(segment
		(start 35.8775 -280.915364)
		(end 35.8775 -281.204924)
		(width 0.14478)
		(layer "In11.Cu")
		(net "M_F_CPU1_SB_DQ<0>")
	)
	(segment
		(start 63.056008 -277.594822)
		(end 63.056008 -277.390098)
		(width 0.14478)
		(layer "In11.Cu")
		(net "M_F_CPU1_SB_DQ<0>")
	)
	(segment
		(start 23.870666 -282.304744)
		(end 24.03348 -282.14193)
		(width 0.14478)
		(layer "In11.Cu")
		(net "M_F_CPU1_SB_DQ<0>")
	)
	(segment
		(start 63.446152 -277.000208)
		(end 63.650876 -276.999954)
		(width 0.14478)
		(layer "In11.Cu")
		(net "M_F_CPU1_SB_DQ<0>")
	)
	(arc
		(start 78.544674 -274.420076)
		(mid 78.723006 -274.459173)
		(end 78.898496 -274.4089)
		(width 0.0889)
		(layer "In11.Cu")
		(net "M_F_CPU1_SB_DQ<0>")
	)
	(arc
		(start 78.898496 -274.4089)
		(mid 79.17144 -274.33232)
		(end 79.447136 -274.398232)
		(width 0.0889)
		(layer "In11.Cu")
		(net "M_F_CPU1_SB_DQ<0>")
	)
	(arc
		(start 81.35239 -274.413726)
		(mid 81.535898 -274.45922)
		(end 81.71815 -274.4089)
		(width 0.0889)
		(layer "In11.Cu")
		(net "M_F_CPU1_SB_DQ<0>")
	)
	(arc
		(start 82.284062 -274.4089)
		(mid 82.471006 -274.459155)
		(end 82.65795 -274.4089)
		(width 0.0889)
		(layer "In11.Cu")
		(net "M_F_CPU1_SB_DQ<0>")
	)
	(arc
		(start 83.598004 -274.4089)
		(mid 83.88096 -274.332723)
		(end 84.163916 -274.4089)
		(width 0.0889)
		(layer "In11.Cu")
		(net "M_F_CPU1_SB_DQ<0>")
	)
	(arc
		(start 83.223862 -274.4089)
		(mid 83.406113 -274.45925)
		(end 83.589622 -274.413726)
		(width 0.0889)
		(layer "In11.Cu")
		(net "M_F_CPU1_SB_DQ<0>")
	)
	(arc
		(start 81.71815 -274.4089)
		(mid 82.001106 -274.332723)
		(end 82.284062 -274.4089)
		(width 0.0889)
		(layer "In11.Cu")
		(net "M_F_CPU1_SB_DQ<0>")
	)
	(arc
		(start 80.778096 -274.4089)
		(mid 81.061052 -274.332723)
		(end 81.344008 -274.4089)
		(width 0.0889)
		(layer "In11.Cu")
		(net "M_F_CPU1_SB_DQ<0>")
	)
	(arc
		(start 79.46517 -274.4089)
		(mid 79.644157 -274.45907)
		(end 79.825088 -274.41652)
		(width 0.0889)
		(layer "In11.Cu")
		(net "M_F_CPU1_SB_DQ<0>")
	)
	(arc
		(start 80.403954 -274.4089)
		(mid 80.586205 -274.45925)
		(end 80.769714 -274.413726)
		(width 0.0889)
		(layer "In11.Cu")
		(net "M_F_CPU1_SB_DQ<0>")
	)
	(arc
		(start 84.163916 -274.4089)
		(mid 84.320354 -274.457871)
		(end 84.482686 -274.435062)
		(width 0.0889)
		(layer "In11.Cu")
		(net "M_F_CPU1_SB_DQ<0>")
	)
	(arc
		(start 78.447392 -274.349972)
		(mid 78.484088 -274.381825)
		(end 78.524608 -274.408646)
		(width 0.0889)
		(layer "In11.Cu")
		(net "M_F_CPU1_SB_DQ<0>")
	)
	(arc
		(start 82.65795 -274.4089)
		(mid 82.940906 -274.332723)
		(end 83.223862 -274.4089)
		(width 0.0889)
		(layer "In11.Cu")
		(net "M_F_CPU1_SB_DQ<0>")
	)
	(arc
		(start 79.850742 -274.401788)
		(mid 80.128276 -274.332807)
		(end 80.403954 -274.4089)
		(width 0.0889)
		(layer "In11.Cu")
		(net "M_F_CPU1_SB_DQ<0>")
	)
	(segment
		(start 85.287866 -266.530328)
		(end 84.821014 -266.796266)
		(width 0.10668)
		(layer "F.Cu")
		(net "M_F_CPU1_SB_CS_N<1>")
	)
	(segment
		(start 82.179668 -266.46886)
		(end 82.18805 -266.473686)
		(width 0.0889)
		(layer "In11.Cu")
		(net "M_F_CPU1_SB_CS_N<1>")
	)
	(segment
		(start 84.571078 -266.505436)
		(end 84.66709 -266.530836)
		(width 0.0889)
		(layer "In11.Cu")
		(net "M_F_CPU1_SB_CS_N<1>")
	)
	(segment
		(start 84.66709 -266.530836)
		(end 84.821014 -266.796266)
		(width 0.0889)
		(layer "In11.Cu")
		(net "M_F_CPU1_SB_CS_N<1>")
	)
	(segment
		(start 17.608042 -268.735302)
		(end 18.032984 -268.31036)
		(width 0.14478)
		(layer "In11.Cu")
		(net "M_F_CPU1_SB_CS_N<1>")
	)
	(segment
		(start 82.753962 -266.473686)
		(end 82.762344 -266.46886)
		(width 0.0889)
		(layer "In11.Cu")
		(net "M_F_CPU1_SB_CS_N<1>")
	)
	(segment
		(start 62.571376 -265.983974)
		(end 75.957176 -265.983974)
		(width 0.14478)
		(layer "In11.Cu")
		(net "M_F_CPU1_SB_CS_N<1>")
	)
	(segment
		(start 60.24499 -268.31036)
		(end 62.571376 -265.983974)
		(width 0.14478)
		(layer "In11.Cu")
		(net "M_F_CPU1_SB_CS_N<1>")
	)
	(segment
		(start 77.895196 -265.983974)
		(end 78.334362 -266.42314)
		(width 0.0889)
		(layer "In11.Cu")
		(net "M_F_CPU1_SB_CS_N<1>")
	)
	(segment
		(start 83.694016 -266.473686)
		(end 83.702398 -266.46886)
		(width 0.0889)
		(layer "In11.Cu")
		(net "M_F_CPU1_SB_CS_N<1>")
	)
	(segment
		(start 18.032984 -268.31036)
		(end 60.24499 -268.31036)
		(width 0.14478)
		(layer "In11.Cu")
		(net "M_F_CPU1_SB_CS_N<1>")
	)
	(segment
		(start 75.957176 -265.983974)
		(end 77.895196 -265.983974)
		(width 0.0889)
		(layer "In11.Cu")
		(net "M_F_CPU1_SB_CS_N<1>")
	)
	(segment
		(start 78.334362 -266.42314)
		(end 80.120998 -266.42314)
		(width 0.0889)
		(layer "In11.Cu")
		(net "M_F_CPU1_SB_CS_N<1>")
	)
	(arc
		(start 80.120998 -266.42314)
		(mid 80.217945 -266.436023)
		(end 80.308196 -266.473686)
		(width 0.0889)
		(layer "In11.Cu")
		(net "M_F_CPU1_SB_CS_N<1>")
	)
	(arc
		(start 82.762344 -266.46886)
		(mid 82.945852 -266.423366)
		(end 83.128104 -266.473686)
		(width 0.0889)
		(layer "In11.Cu")
		(net "M_F_CPU1_SB_CS_N<1>")
	)
	(arc
		(start 81.247996 -266.473686)
		(mid 81.530952 -266.549863)
		(end 81.813908 -266.473686)
		(width 0.0889)
		(layer "In11.Cu")
		(net "M_F_CPU1_SB_CS_N<1>")
	)
	(arc
		(start 84.068158 -266.473686)
		(mid 84.315871 -266.548906)
		(end 84.571078 -266.505436)
		(width 0.0889)
		(layer "In11.Cu")
		(net "M_F_CPU1_SB_CS_N<1>")
	)
	(arc
		(start 82.18805 -266.473686)
		(mid 82.471006 -266.549863)
		(end 82.753962 -266.473686)
		(width 0.0889)
		(layer "In11.Cu")
		(net "M_F_CPU1_SB_CS_N<1>")
	)
	(arc
		(start 83.702398 -266.46886)
		(mid 83.885906 -266.423366)
		(end 84.068158 -266.473686)
		(width 0.0889)
		(layer "In11.Cu")
		(net "M_F_CPU1_SB_CS_N<1>")
	)
	(arc
		(start 83.128104 -266.473686)
		(mid 83.41106 -266.549863)
		(end 83.694016 -266.473686)
		(width 0.0889)
		(layer "In11.Cu")
		(net "M_F_CPU1_SB_CS_N<1>")
	)
	(arc
		(start 80.874108 -266.473686)
		(mid 81.061052 -266.423431)
		(end 81.247996 -266.473686)
		(width 0.0889)
		(layer "In11.Cu")
		(net "M_F_CPU1_SB_CS_N<1>")
	)
	(arc
		(start 81.813908 -266.473686)
		(mid 81.996159 -266.423336)
		(end 82.179668 -266.46886)
		(width 0.0889)
		(layer "In11.Cu")
		(net "M_F_CPU1_SB_CS_N<1>")
	)
	(arc
		(start 80.308196 -266.473686)
		(mid 80.591152 -266.549863)
		(end 80.874108 -266.473686)
		(width 0.0889)
		(layer "In11.Cu")
		(net "M_F_CPU1_SB_CS_N<1>")
	)
	(segment
		(start 86.69782 -265.720322)
		(end 86.230968 -265.98626)
		(width 0.10668)
		(layer "F.Cu")
		(net "M_F_CPU1_SB_CS_N<0>")
	)
	(segment
		(start 60.205874 -267.460476)
		(end 62.137036 -265.529314)
		(width 0.14478)
		(layer "In11.Cu")
		(net "M_F_CPU1_SB_CS_N<0>")
	)
	(segment
		(start 23.613872 -267.092176)
		(end 23.844504 -267.092176)
		(width 0.14478)
		(layer "In11.Cu")
		(net "M_F_CPU1_SB_CS_N<0>")
	)
	(segment
		(start 23.844504 -267.092176)
		(end 24.007318 -267.25499)
		(width 0.14478)
		(layer "In11.Cu")
		(net "M_F_CPU1_SB_CS_N<0>")
	)
	(segment
		(start 22.894798 -267.25499)
		(end 22.894798 -267.690346)
		(width 0.14478)
		(layer "In11.Cu")
		(net "M_F_CPU1_SB_CS_N<0>")
	)
	(segment
		(start 62.137036 -265.529314)
		(end 76.119736 -265.529314)
		(width 0.14478)
		(layer "In11.Cu")
		(net "M_F_CPU1_SB_CS_N<0>")
	)
	(segment
		(start 22.501352 -267.092176)
		(end 22.731984 -267.092176)
		(width 0.14478)
		(layer "In11.Cu")
		(net "M_F_CPU1_SB_CS_N<0>")
	)
	(segment
		(start 22.731984 -267.092176)
		(end 22.894798 -267.25499)
		(width 0.14478)
		(layer "In11.Cu")
		(net "M_F_CPU1_SB_CS_N<0>")
	)
	(segment
		(start 24.007318 -267.690346)
		(end 24.170132 -267.85316)
		(width 0.14478)
		(layer "In11.Cu")
		(net "M_F_CPU1_SB_CS_N<0>")
	)
	(segment
		(start 80.769714 -265.658854)
		(end 80.778096 -265.66368)
		(width 0.0889)
		(layer "In11.Cu")
		(net "M_F_CPU1_SB_CS_N<0>")
	)
	(segment
		(start 24.007318 -267.25499)
		(end 24.007318 -267.690346)
		(width 0.14478)
		(layer "In11.Cu")
		(net "M_F_CPU1_SB_CS_N<0>")
	)
	(segment
		(start 23.451058 -267.25499)
		(end 23.613872 -267.092176)
		(width 0.14478)
		(layer "In11.Cu")
		(net "M_F_CPU1_SB_CS_N<0>")
	)
	(segment
		(start 24.170132 -267.85316)
		(end 24.400764 -267.85316)
		(width 0.14478)
		(layer "In11.Cu")
		(net "M_F_CPU1_SB_CS_N<0>")
	)
	(segment
		(start 85.10397 -265.66368)
		(end 85.112352 -265.658854)
		(width 0.0889)
		(layer "In11.Cu")
		(net "M_F_CPU1_SB_CS_N<0>")
	)
	(segment
		(start 80.39354 -265.669776)
		(end 80.403954 -265.66368)
		(width 0.0889)
		(layer "In11.Cu")
		(net "M_F_CPU1_SB_CS_N<0>")
	)
	(segment
		(start 21.70811 -267.885418)
		(end 22.501352 -267.092176)
		(width 0.14478)
		(layer "In11.Cu")
		(net "M_F_CPU1_SB_CS_N<0>")
	)
	(segment
		(start 85.981032 -265.69543)
		(end 86.077044 -265.72083)
		(width 0.0889)
		(layer "In11.Cu")
		(net "M_F_CPU1_SB_CS_N<0>")
	)
	(segment
		(start 23.451058 -267.690346)
		(end 23.451058 -267.25499)
		(width 0.14478)
		(layer "In11.Cu")
		(net "M_F_CPU1_SB_CS_N<0>")
	)
	(segment
		(start 22.894798 -267.690346)
		(end 23.057612 -267.85316)
		(width 0.14478)
		(layer "In11.Cu")
		(net "M_F_CPU1_SB_CS_N<0>")
	)
	(segment
		(start 84.529676 -265.658854)
		(end 84.538058 -265.66368)
		(width 0.0889)
		(layer "In11.Cu")
		(net "M_F_CPU1_SB_CS_N<0>")
	)
	(segment
		(start 76.119736 -265.529314)
		(end 79.340456 -265.529314)
		(width 0.0889)
		(layer "In11.Cu")
		(net "M_F_CPU1_SB_CS_N<0>")
	)
	(segment
		(start 24.793448 -267.460476)
		(end 60.205874 -267.460476)
		(width 0.14478)
		(layer "In11.Cu")
		(net "M_F_CPU1_SB_CS_N<0>")
	)
	(segment
		(start 23.057612 -267.85316)
		(end 23.288244 -267.85316)
		(width 0.14478)
		(layer "In11.Cu")
		(net "M_F_CPU1_SB_CS_N<0>")
	)
	(segment
		(start 86.077044 -265.72083)
		(end 86.230968 -265.98626)
		(width 0.0889)
		(layer "In11.Cu")
		(net "M_F_CPU1_SB_CS_N<0>")
	)
	(segment
		(start 23.288244 -267.85316)
		(end 23.451058 -267.690346)
		(width 0.14478)
		(layer "In11.Cu")
		(net "M_F_CPU1_SB_CS_N<0>")
	)
	(segment
		(start 24.400764 -267.85316)
		(end 24.793448 -267.460476)
		(width 0.14478)
		(layer "In11.Cu")
		(net "M_F_CPU1_SB_CS_N<0>")
	)
	(segment
		(start 82.284062 -265.66368)
		(end 82.292444 -265.658854)
		(width 0.0889)
		(layer "In11.Cu")
		(net "M_F_CPU1_SB_CS_N<0>")
	)
	(segment
		(start 81.344008 -265.66368)
		(end 81.35239 -265.658854)
		(width 0.0889)
		(layer "In11.Cu")
		(net "M_F_CPU1_SB_CS_N<0>")
	)
	(arc
		(start 85.478112 -265.66368)
		(mid 85.725825 -265.7389)
		(end 85.981032 -265.69543)
		(width 0.0889)
		(layer "In11.Cu")
		(net "M_F_CPU1_SB_CS_N<0>")
	)
	(arc
		(start 83.598004 -265.66368)
		(mid 83.88096 -265.739857)
		(end 84.163916 -265.66368)
		(width 0.0889)
		(layer "In11.Cu")
		(net "M_F_CPU1_SB_CS_N<0>")
	)
	(arc
		(start 80.778096 -265.66368)
		(mid 81.061052 -265.739857)
		(end 81.344008 -265.66368)
		(width 0.0889)
		(layer "In11.Cu")
		(net "M_F_CPU1_SB_CS_N<0>")
	)
	(arc
		(start 84.163916 -265.66368)
		(mid 84.346167 -265.61333)
		(end 84.529676 -265.658854)
		(width 0.0889)
		(layer "In11.Cu")
		(net "M_F_CPU1_SB_CS_N<0>")
	)
	(arc
		(start 82.658204 -265.66368)
		(mid 82.94116 -265.739857)
		(end 83.224116 -265.66368)
		(width 0.0889)
		(layer "In11.Cu")
		(net "M_F_CPU1_SB_CS_N<0>")
	)
	(arc
		(start 83.224116 -265.66368)
		(mid 83.41106 -265.613425)
		(end 83.598004 -265.66368)
		(width 0.0889)
		(layer "In11.Cu")
		(net "M_F_CPU1_SB_CS_N<0>")
	)
	(arc
		(start 81.71815 -265.66368)
		(mid 82.001106 -265.739857)
		(end 82.284062 -265.66368)
		(width 0.0889)
		(layer "In11.Cu")
		(net "M_F_CPU1_SB_CS_N<0>")
	)
	(arc
		(start 79.837788 -265.66368)
		(mid 80.114855 -265.739951)
		(end 80.39354 -265.669776)
		(width 0.0889)
		(layer "In11.Cu")
		(net "M_F_CPU1_SB_CS_N<0>")
	)
	(arc
		(start 84.538058 -265.66368)
		(mid 84.821014 -265.739857)
		(end 85.10397 -265.66368)
		(width 0.0889)
		(layer "In11.Cu")
		(net "M_F_CPU1_SB_CS_N<0>")
	)
	(arc
		(start 85.112352 -265.658854)
		(mid 85.29586 -265.61336)
		(end 85.478112 -265.66368)
		(width 0.0889)
		(layer "In11.Cu")
		(net "M_F_CPU1_SB_CS_N<0>")
	)
	(arc
		(start 82.292444 -265.658854)
		(mid 82.475952 -265.61336)
		(end 82.658204 -265.66368)
		(width 0.0889)
		(layer "In11.Cu")
		(net "M_F_CPU1_SB_CS_N<0>")
	)
	(arc
		(start 80.403954 -265.66368)
		(mid 80.586205 -265.61333)
		(end 80.769714 -265.658854)
		(width 0.0889)
		(layer "In11.Cu")
		(net "M_F_CPU1_SB_CS_N<0>")
	)
	(arc
		(start 81.35239 -265.658854)
		(mid 81.535898 -265.61336)
		(end 81.71815 -265.66368)
		(width 0.0889)
		(layer "In11.Cu")
		(net "M_F_CPU1_SB_CS_N<0>")
	)
	(arc
		(start 79.340456 -265.529314)
		(mid 79.598033 -265.563506)
		(end 79.837788 -265.66368)
		(width 0.0889)
		(layer "In11.Cu")
		(net "M_F_CPU1_SB_CS_N<0>")
	)
	(segment
		(start 86.69782 -270.580358)
		(end 86.230968 -270.846296)
		(width 0.10668)
		(layer "F.Cu")
		(net "M_F_CPU1_SB_CB<7>")
	)
	(segment
		(start 78.387448 -270.362172)
		(end 79.239872 -270.362172)
		(width 0.0889)
		(layer "In11.Cu")
		(net "M_F_CPU1_SB_CB<7>")
	)
	(segment
		(start 21.139912 -274.26031)
		(end 26.22804 -274.26031)
		(width 0.14478)
		(layer "In11.Cu")
		(net "M_F_CPU1_SB_CB<7>")
	)
	(segment
		(start 19.308318 -273.524218)
		(end 19.471132 -273.361404)
		(width 0.14478)
		(layer "In11.Cu")
		(net "M_F_CPU1_SB_CB<7>")
	)
	(segment
		(start 19.471132 -273.361404)
		(end 19.701764 -273.361404)
		(width 0.14478)
		(layer "In11.Cu")
		(net "M_F_CPU1_SB_CB<7>")
	)
	(segment
		(start 18.752058 -274.097496)
		(end 18.914872 -274.26031)
		(width 0.14478)
		(layer "In11.Cu")
		(net "M_F_CPU1_SB_CB<7>")
	)
	(segment
		(start 19.701764 -273.361404)
		(end 19.864578 -273.524218)
		(width 0.14478)
		(layer "In11.Cu")
		(net "M_F_CPU1_SB_CB<7>")
	)
	(segment
		(start 84.529676 -270.51889)
		(end 84.538058 -270.523716)
		(width 0.0889)
		(layer "In11.Cu")
		(net "M_F_CPU1_SB_CB<7>")
	)
	(segment
		(start 76.198476 -268.960854)
		(end 76.341986 -269.104364)
		(width 0.0889)
		(layer "In11.Cu")
		(net "M_F_CPU1_SB_CB<7>")
	)
	(segment
		(start 20.420838 -273.524218)
		(end 20.583652 -273.361404)
		(width 0.14478)
		(layer "In11.Cu")
		(net "M_F_CPU1_SB_CB<7>")
	)
	(segment
		(start 81.344008 -270.523716)
		(end 81.35239 -270.51889)
		(width 0.0889)
		(layer "In11.Cu")
		(net "M_F_CPU1_SB_CB<7>")
	)
	(segment
		(start 80.769714 -270.51889)
		(end 80.778096 -270.523716)
		(width 0.0889)
		(layer "In11.Cu")
		(net "M_F_CPU1_SB_CB<7>")
	)
	(segment
		(start 86.077044 -270.580866)
		(end 86.230968 -270.846296)
		(width 0.0889)
		(layer "In11.Cu")
		(net "M_F_CPU1_SB_CB<7>")
	)
	(segment
		(start 19.145504 -274.26031)
		(end 19.308318 -274.097496)
		(width 0.14478)
		(layer "In11.Cu")
		(net "M_F_CPU1_SB_CB<7>")
	)
	(segment
		(start 83.589622 -270.51889)
		(end 83.598004 -270.523716)
		(width 0.0889)
		(layer "In11.Cu")
		(net "M_F_CPU1_SB_CB<7>")
	)
	(segment
		(start 85.10397 -270.523716)
		(end 85.112352 -270.51889)
		(width 0.0889)
		(layer "In11.Cu")
		(net "M_F_CPU1_SB_CB<7>")
	)
	(segment
		(start 20.977098 -274.097496)
		(end 21.139912 -274.26031)
		(width 0.14478)
		(layer "In11.Cu")
		(net "M_F_CPU1_SB_CB<7>")
	)
	(segment
		(start 60.339732 -273.410426)
		(end 64.789304 -268.960854)
		(width 0.14478)
		(layer "In11.Cu")
		(net "M_F_CPU1_SB_CB<7>")
	)
	(segment
		(start 18.589244 -273.531584)
		(end 18.752058 -273.694398)
		(width 0.14478)
		(layer "In11.Cu")
		(net "M_F_CPU1_SB_CB<7>")
	)
	(segment
		(start 20.258024 -274.26031)
		(end 20.420838 -274.097496)
		(width 0.14478)
		(layer "In11.Cu")
		(net "M_F_CPU1_SB_CB<7>")
	)
	(segment
		(start 18.358612 -273.531584)
		(end 18.589244 -273.531584)
		(width 0.14478)
		(layer "In11.Cu")
		(net "M_F_CPU1_SB_CB<7>")
	)
	(segment
		(start 18.195798 -274.097496)
		(end 18.195798 -273.694398)
		(width 0.14478)
		(layer "In11.Cu")
		(net "M_F_CPU1_SB_CB<7>")
	)
	(segment
		(start 26.22804 -274.26031)
		(end 27.077924 -273.410426)
		(width 0.14478)
		(layer "In11.Cu")
		(net "M_F_CPU1_SB_CB<7>")
	)
	(segment
		(start 80.39354 -270.529812)
		(end 80.403954 -270.523716)
		(width 0.0889)
		(layer "In11.Cu")
		(net "M_F_CPU1_SB_CB<7>")
	)
	(segment
		(start 19.864578 -273.524218)
		(end 19.864578 -274.097496)
		(width 0.14478)
		(layer "In11.Cu")
		(net "M_F_CPU1_SB_CB<7>")
	)
	(segment
		(start 64.789304 -268.960854)
		(end 75.934824 -268.960854)
		(width 0.14478)
		(layer "In11.Cu")
		(net "M_F_CPU1_SB_CB<7>")
	)
	(segment
		(start 18.752058 -273.694398)
		(end 18.752058 -274.097496)
		(width 0.14478)
		(layer "In11.Cu")
		(net "M_F_CPU1_SB_CB<7>")
	)
	(segment
		(start 20.583652 -273.361404)
		(end 20.814284 -273.361404)
		(width 0.14478)
		(layer "In11.Cu")
		(net "M_F_CPU1_SB_CB<7>")
	)
	(segment
		(start 18.195798 -273.694398)
		(end 18.358612 -273.531584)
		(width 0.14478)
		(layer "In11.Cu")
		(net "M_F_CPU1_SB_CB<7>")
	)
	(segment
		(start 76.341986 -269.104364)
		(end 77.08265 -269.104364)
		(width 0.0889)
		(layer "In11.Cu")
		(net "M_F_CPU1_SB_CB<7>")
	)
	(segment
		(start 75.934824 -268.960854)
		(end 76.198476 -268.960854)
		(width 0.0889)
		(layer "In11.Cu")
		(net "M_F_CPU1_SB_CB<7>")
	)
	(segment
		(start 20.814284 -273.361404)
		(end 20.977098 -273.524218)
		(width 0.14478)
		(layer "In11.Cu")
		(net "M_F_CPU1_SB_CB<7>")
	)
	(segment
		(start 20.420838 -274.097496)
		(end 20.420838 -273.524218)
		(width 0.14478)
		(layer "In11.Cu")
		(net "M_F_CPU1_SB_CB<7>")
	)
	(segment
		(start 85.981032 -270.555466)
		(end 86.077044 -270.580866)
		(width 0.0889)
		(layer "In11.Cu")
		(net "M_F_CPU1_SB_CB<7>")
	)
	(segment
		(start 20.977098 -273.524218)
		(end 20.977098 -274.097496)
		(width 0.14478)
		(layer "In11.Cu")
		(net "M_F_CPU1_SB_CB<7>")
	)
	(segment
		(start 77.08265 -269.104364)
		(end 78.307184 -270.328898)
		(width 0.0889)
		(layer "In11.Cu")
		(net "M_F_CPU1_SB_CB<7>")
	)
	(segment
		(start 17.608042 -274.685252)
		(end 18.195798 -274.097496)
		(width 0.14478)
		(layer "In11.Cu")
		(net "M_F_CPU1_SB_CB<7>")
	)
	(segment
		(start 27.077924 -273.410426)
		(end 60.339732 -273.410426)
		(width 0.14478)
		(layer "In11.Cu")
		(net "M_F_CPU1_SB_CB<7>")
	)
	(segment
		(start 20.027392 -274.26031)
		(end 20.258024 -274.26031)
		(width 0.14478)
		(layer "In11.Cu")
		(net "M_F_CPU1_SB_CB<7>")
	)
	(segment
		(start 19.864578 -274.097496)
		(end 20.027392 -274.26031)
		(width 0.14478)
		(layer "In11.Cu")
		(net "M_F_CPU1_SB_CB<7>")
	)
	(segment
		(start 19.308318 -274.097496)
		(end 19.308318 -273.524218)
		(width 0.14478)
		(layer "In11.Cu")
		(net "M_F_CPU1_SB_CB<7>")
	)
	(segment
		(start 18.914872 -274.26031)
		(end 19.145504 -274.26031)
		(width 0.14478)
		(layer "In11.Cu")
		(net "M_F_CPU1_SB_CB<7>")
	)
	(arc
		(start 85.112352 -270.51889)
		(mid 85.29586 -270.473396)
		(end 85.478112 -270.523716)
		(width 0.0889)
		(layer "In11.Cu")
		(net "M_F_CPU1_SB_CB<7>")
	)
	(arc
		(start 81.71815 -270.523716)
		(mid 82.001106 -270.599893)
		(end 82.284062 -270.523716)
		(width 0.0889)
		(layer "In11.Cu")
		(net "M_F_CPU1_SB_CB<7>")
	)
	(arc
		(start 81.35239 -270.51889)
		(mid 81.535898 -270.473396)
		(end 81.71815 -270.523716)
		(width 0.0889)
		(layer "In11.Cu")
		(net "M_F_CPU1_SB_CB<7>")
	)
	(arc
		(start 84.163916 -270.523716)
		(mid 84.346167 -270.473366)
		(end 84.529676 -270.51889)
		(width 0.0889)
		(layer "In11.Cu")
		(net "M_F_CPU1_SB_CB<7>")
	)
	(arc
		(start 82.284062 -270.523716)
		(mid 82.471006 -270.473461)
		(end 82.65795 -270.523716)
		(width 0.0889)
		(layer "In11.Cu")
		(net "M_F_CPU1_SB_CB<7>")
	)
	(arc
		(start 82.65795 -270.523716)
		(mid 82.940906 -270.599893)
		(end 83.223862 -270.523716)
		(width 0.0889)
		(layer "In11.Cu")
		(net "M_F_CPU1_SB_CB<7>")
	)
	(arc
		(start 84.538058 -270.523716)
		(mid 84.821014 -270.599893)
		(end 85.10397 -270.523716)
		(width 0.0889)
		(layer "In11.Cu")
		(net "M_F_CPU1_SB_CB<7>")
	)
	(arc
		(start 83.598004 -270.523716)
		(mid 83.88096 -270.599893)
		(end 84.163916 -270.523716)
		(width 0.0889)
		(layer "In11.Cu")
		(net "M_F_CPU1_SB_CB<7>")
	)
	(arc
		(start 83.223862 -270.523716)
		(mid 83.406113 -270.473366)
		(end 83.589622 -270.51889)
		(width 0.0889)
		(layer "In11.Cu")
		(net "M_F_CPU1_SB_CB<7>")
	)
	(arc
		(start 78.307184 -270.328898)
		(mid 78.343995 -270.353558)
		(end 78.387448 -270.362172)
		(width 0.0889)
		(layer "In11.Cu")
		(net "M_F_CPU1_SB_CB<7>")
	)
	(arc
		(start 80.778096 -270.523716)
		(mid 81.061052 -270.599893)
		(end 81.344008 -270.523716)
		(width 0.0889)
		(layer "In11.Cu")
		(net "M_F_CPU1_SB_CB<7>")
	)
	(arc
		(start 79.837788 -270.523716)
		(mid 80.114855 -270.599987)
		(end 80.39354 -270.529812)
		(width 0.0889)
		(layer "In11.Cu")
		(net "M_F_CPU1_SB_CB<7>")
	)
	(arc
		(start 79.239872 -270.362172)
		(mid 79.549543 -270.40328)
		(end 79.837788 -270.523716)
		(width 0.0889)
		(layer "In11.Cu")
		(net "M_F_CPU1_SB_CB<7>")
	)
	(arc
		(start 85.478112 -270.523716)
		(mid 85.725825 -270.598936)
		(end 85.981032 -270.555466)
		(width 0.0889)
		(layer "In11.Cu")
		(net "M_F_CPU1_SB_CB<7>")
	)
	(arc
		(start 80.403954 -270.523716)
		(mid 80.586205 -270.473366)
		(end 80.769714 -270.51889)
		(width 0.0889)
		(layer "In11.Cu")
		(net "M_F_CPU1_SB_CB<7>")
	)
	(segment
		(start 85.287866 -269.770352)
		(end 84.821014 -270.03629)
		(width 0.10668)
		(layer "F.Cu")
		(net "M_F_CPU1_SB_CB<6>")
	)
	(segment
		(start 83.694016 -269.71371)
		(end 83.702398 -269.708884)
		(width 0.0889)
		(layer "In11.Cu")
		(net "M_F_CPU1_SB_CB<6>")
	)
	(segment
		(start 19.455892 -271.453864)
		(end 19.661124 -271.453864)
		(width 0.14478)
		(layer "In11.Cu")
		(net "M_F_CPU1_SB_CB<6>")
	)
	(segment
		(start 18.195798 -271.601438)
		(end 18.358612 -271.438624)
		(width 0.14478)
		(layer "In11.Cu")
		(net "M_F_CPU1_SB_CB<6>")
	)
	(segment
		(start 19.864578 -271.657318)
		(end 19.864578 -272.397474)
		(width 0.14478)
		(layer "In11.Cu")
		(net "M_F_CPU1_SB_CB<6>")
	)
	(segment
		(start 19.661124 -271.453864)
		(end 19.864578 -271.657318)
		(width 0.14478)
		(layer "In11.Cu")
		(net "M_F_CPU1_SB_CB<6>")
	)
	(segment
		(start 20.977098 -272.397474)
		(end 21.139912 -272.560288)
		(width 0.14478)
		(layer "In11.Cu")
		(net "M_F_CPU1_SB_CB<6>")
	)
	(segment
		(start 84.571078 -269.74546)
		(end 84.66709 -269.77086)
		(width 0.0889)
		(layer "In11.Cu")
		(net "M_F_CPU1_SB_CB<6>")
	)
	(segment
		(start 18.358612 -271.438624)
		(end 18.589244 -271.438624)
		(width 0.14478)
		(layer "In11.Cu")
		(net "M_F_CPU1_SB_CB<6>")
	)
	(segment
		(start 60.767722 -271.710404)
		(end 64.426592 -268.051534)
		(width 0.14478)
		(layer "In11.Cu")
		(net "M_F_CPU1_SB_CB<6>")
	)
	(segment
		(start 79.934054 -269.71371)
		(end 79.942436 -269.708884)
		(width 0.0889)
		(layer "In11.Cu")
		(net "M_F_CPU1_SB_CB<6>")
	)
	(segment
		(start 18.589244 -271.438624)
		(end 18.752058 -271.601438)
		(width 0.14478)
		(layer "In11.Cu")
		(net "M_F_CPU1_SB_CB<6>")
	)
	(segment
		(start 82.179668 -269.708884)
		(end 82.18805 -269.71371)
		(width 0.0889)
		(layer "In11.Cu")
		(net "M_F_CPU1_SB_CB<6>")
	)
	(segment
		(start 20.420838 -272.397474)
		(end 20.420838 -271.601438)
		(width 0.14478)
		(layer "In11.Cu")
		(net "M_F_CPU1_SB_CB<6>")
	)
	(segment
		(start 17.608042 -272.98523)
		(end 18.195798 -272.397474)
		(width 0.14478)
		(layer "In11.Cu")
		(net "M_F_CPU1_SB_CB<6>")
	)
	(segment
		(start 18.752058 -272.397474)
		(end 18.914872 -272.560288)
		(width 0.14478)
		(layer "In11.Cu")
		(net "M_F_CPU1_SB_CB<6>")
	)
	(segment
		(start 19.864578 -272.397474)
		(end 20.027392 -272.560288)
		(width 0.14478)
		(layer "In11.Cu")
		(net "M_F_CPU1_SB_CB<6>")
	)
	(segment
		(start 78.42885 -269.713964)
		(end 78.45044 -269.72641)
		(width 0.0889)
		(layer "In11.Cu")
		(net "M_F_CPU1_SB_CB<6>")
	)
	(segment
		(start 19.308318 -272.397474)
		(end 19.308318 -271.601438)
		(width 0.14478)
		(layer "In11.Cu")
		(net "M_F_CPU1_SB_CB<6>")
	)
	(segment
		(start 75.974956 -268.051534)
		(end 76.228956 -268.051534)
		(width 0.0889)
		(layer "In11.Cu")
		(net "M_F_CPU1_SB_CB<6>")
	)
	(segment
		(start 19.145504 -272.560288)
		(end 19.308318 -272.397474)
		(width 0.14478)
		(layer "In11.Cu")
		(net "M_F_CPU1_SB_CB<6>")
	)
	(segment
		(start 76.743814 -268.566392)
		(end 77.2541 -268.566392)
		(width 0.0889)
		(layer "In11.Cu")
		(net "M_F_CPU1_SB_CB<6>")
	)
	(segment
		(start 26.872946 -271.710404)
		(end 60.767722 -271.710404)
		(width 0.14478)
		(layer "In11.Cu")
		(net "M_F_CPU1_SB_CB<6>")
	)
	(segment
		(start 20.814284 -271.438624)
		(end 20.977098 -271.601438)
		(width 0.14478)
		(layer "In11.Cu")
		(net "M_F_CPU1_SB_CB<6>")
	)
	(segment
		(start 20.027392 -272.560288)
		(end 20.258024 -272.560288)
		(width 0.14478)
		(layer "In11.Cu")
		(net "M_F_CPU1_SB_CB<6>")
	)
	(segment
		(start 26.023062 -272.560288)
		(end 26.872946 -271.710404)
		(width 0.14478)
		(layer "In11.Cu")
		(net "M_F_CPU1_SB_CB<6>")
	)
	(segment
		(start 64.426592 -268.051534)
		(end 75.974956 -268.051534)
		(width 0.14478)
		(layer "In11.Cu")
		(net "M_F_CPU1_SB_CB<6>")
	)
	(segment
		(start 18.195798 -272.397474)
		(end 18.195798 -271.601438)
		(width 0.14478)
		(layer "In11.Cu")
		(net "M_F_CPU1_SB_CB<6>")
	)
	(segment
		(start 77.2541 -268.566392)
		(end 78.312518 -269.62481)
		(width 0.0889)
		(layer "In11.Cu")
		(net "M_F_CPU1_SB_CB<6>")
	)
	(segment
		(start 20.977098 -271.601438)
		(end 20.977098 -272.397474)
		(width 0.14478)
		(layer "In11.Cu")
		(net "M_F_CPU1_SB_CB<6>")
	)
	(segment
		(start 20.420838 -271.601438)
		(end 20.583652 -271.438624)
		(width 0.14478)
		(layer "In11.Cu")
		(net "M_F_CPU1_SB_CB<6>")
	)
	(segment
		(start 84.66709 -269.77086)
		(end 84.821014 -270.03629)
		(width 0.0889)
		(layer "In11.Cu")
		(net "M_F_CPU1_SB_CB<6>")
	)
	(segment
		(start 79.350616 -269.70355)
		(end 79.368904 -269.713964)
		(width 0.0889)
		(layer "In11.Cu")
		(net "M_F_CPU1_SB_CB<6>")
	)
	(segment
		(start 21.139912 -272.560288)
		(end 26.023062 -272.560288)
		(width 0.14478)
		(layer "In11.Cu")
		(net "M_F_CPU1_SB_CB<6>")
	)
	(segment
		(start 79.368904 -269.713964)
		(end 79.380842 -269.720822)
		(width 0.0889)
		(layer "In11.Cu")
		(net "M_F_CPU1_SB_CB<6>")
	)
	(segment
		(start 20.583652 -271.438624)
		(end 20.814284 -271.438624)
		(width 0.14478)
		(layer "In11.Cu")
		(net "M_F_CPU1_SB_CB<6>")
	)
	(segment
		(start 82.753962 -269.71371)
		(end 82.762344 -269.708884)
		(width 0.0889)
		(layer "In11.Cu")
		(net "M_F_CPU1_SB_CB<6>")
	)
	(segment
		(start 20.258024 -272.560288)
		(end 20.420838 -272.397474)
		(width 0.14478)
		(layer "In11.Cu")
		(net "M_F_CPU1_SB_CB<6>")
	)
	(segment
		(start 19.308318 -271.601438)
		(end 19.455892 -271.453864)
		(width 0.14478)
		(layer "In11.Cu")
		(net "M_F_CPU1_SB_CB<6>")
	)
	(segment
		(start 18.914872 -272.560288)
		(end 19.145504 -272.560288)
		(width 0.14478)
		(layer "In11.Cu")
		(net "M_F_CPU1_SB_CB<6>")
	)
	(segment
		(start 76.228956 -268.051534)
		(end 76.743814 -268.566392)
		(width 0.0889)
		(layer "In11.Cu")
		(net "M_F_CPU1_SB_CB<6>")
	)
	(segment
		(start 18.752058 -271.601438)
		(end 18.752058 -272.397474)
		(width 0.14478)
		(layer "In11.Cu")
		(net "M_F_CPU1_SB_CB<6>")
	)
	(arc
		(start 78.45044 -269.72641)
		(mid 78.72423 -269.790081)
		(end 78.994762 -269.71371)
		(width 0.0889)
		(layer "In11.Cu")
		(net "M_F_CPU1_SB_CB<6>")
	)
	(arc
		(start 80.308196 -269.71371)
		(mid 80.591152 -269.789887)
		(end 80.874108 -269.71371)
		(width 0.0889)
		(layer "In11.Cu")
		(net "M_F_CPU1_SB_CB<6>")
	)
	(arc
		(start 81.813908 -269.71371)
		(mid 81.996159 -269.66336)
		(end 82.179668 -269.708884)
		(width 0.0889)
		(layer "In11.Cu")
		(net "M_F_CPU1_SB_CB<6>")
	)
	(arc
		(start 80.874108 -269.71371)
		(mid 81.061052 -269.663455)
		(end 81.247996 -269.71371)
		(width 0.0889)
		(layer "In11.Cu")
		(net "M_F_CPU1_SB_CB<6>")
	)
	(arc
		(start 81.247996 -269.71371)
		(mid 81.530952 -269.789887)
		(end 81.813908 -269.71371)
		(width 0.0889)
		(layer "In11.Cu")
		(net "M_F_CPU1_SB_CB<6>")
	)
	(arc
		(start 82.762344 -269.708884)
		(mid 82.945852 -269.66339)
		(end 83.128104 -269.71371)
		(width 0.0889)
		(layer "In11.Cu")
		(net "M_F_CPU1_SB_CB<6>")
	)
	(arc
		(start 78.312518 -269.62481)
		(mid 78.367768 -269.673192)
		(end 78.42885 -269.713964)
		(width 0.0889)
		(layer "In11.Cu")
		(net "M_F_CPU1_SB_CB<6>")
	)
	(arc
		(start 84.068158 -269.71371)
		(mid 84.315871 -269.78893)
		(end 84.571078 -269.74546)
		(width 0.0889)
		(layer "In11.Cu")
		(net "M_F_CPU1_SB_CB<6>")
	)
	(arc
		(start 83.128104 -269.71371)
		(mid 83.41106 -269.789887)
		(end 83.694016 -269.71371)
		(width 0.0889)
		(layer "In11.Cu")
		(net "M_F_CPU1_SB_CB<6>")
	)
	(arc
		(start 82.18805 -269.71371)
		(mid 82.471006 -269.789887)
		(end 82.753962 -269.71371)
		(width 0.0889)
		(layer "In11.Cu")
		(net "M_F_CPU1_SB_CB<6>")
	)
	(arc
		(start 83.702398 -269.708884)
		(mid 83.885906 -269.66339)
		(end 84.068158 -269.71371)
		(width 0.0889)
		(layer "In11.Cu")
		(net "M_F_CPU1_SB_CB<6>")
	)
	(arc
		(start 78.994762 -269.71371)
		(mid 79.17139 -269.663477)
		(end 79.350616 -269.70355)
		(width 0.0889)
		(layer "In11.Cu")
		(net "M_F_CPU1_SB_CB<6>")
	)
	(arc
		(start 79.942436 -269.708884)
		(mid 80.125944 -269.66339)
		(end 80.308196 -269.71371)
		(width 0.0889)
		(layer "In11.Cu")
		(net "M_F_CPU1_SB_CB<6>")
	)
	(arc
		(start 79.380842 -269.720822)
		(mid 79.658376 -269.789803)
		(end 79.934054 -269.71371)
		(width 0.0889)
		(layer "In11.Cu")
		(net "M_F_CPU1_SB_CB<6>")
	)
	(segment
		(start 86.22792 -269.770352)
		(end 85.761068 -270.03629)
		(width 0.10668)
		(layer "F.Cu")
		(net "M_F_CPU1_SB_CB<5>")
	)
	(segment
		(start 45.086778 -272.873724)
		(end 45.329602 -272.873724)
		(width 0.14478)
		(layer "In11.Cu")
		(net "M_F_CPU1_SB_CB<5>")
	)
	(segment
		(start 46.199298 -272.873724)
		(end 46.442122 -272.873724)
		(width 0.14478)
		(layer "In11.Cu")
		(net "M_F_CPU1_SB_CB<5>")
	)
	(segment
		(start 42.154348 -272.876264)
		(end 42.470324 -272.560288)
		(width 0.14478)
		(layer "In11.Cu")
		(net "M_F_CPU1_SB_CB<5>")
	)
	(segment
		(start 42.710608 -272.560288)
		(end 43.026584 -272.876264)
		(width 0.14478)
		(layer "In11.Cu")
		(net "M_F_CPU1_SB_CB<5>")
	)
	(segment
		(start 50.081434 -272.560288)
		(end 50.329338 -272.560288)
		(width 0.14478)
		(layer "In11.Cu")
		(net "M_F_CPU1_SB_CB<5>")
	)
	(segment
		(start 29.9339 -272.861024)
		(end 30.189424 -272.861024)
		(width 0.14478)
		(layer "In11.Cu")
		(net "M_F_CPU1_SB_CB<5>")
	)
	(segment
		(start 24.424132 -273.802602)
		(end 24.816308 -273.410426)
		(width 0.14478)
		(layer "In11.Cu")
		(net "M_F_CPU1_SB_CB<5>")
	)
	(segment
		(start 23.63724 -273.018758)
		(end 23.867872 -273.018758)
		(width 0.14478)
		(layer "In11.Cu")
		(net "M_F_CPU1_SB_CB<5>")
	)
	(segment
		(start 34.14522 -272.560288)
		(end 34.451036 -272.866104)
		(width 0.14478)
		(layer "In11.Cu")
		(net "M_F_CPU1_SB_CB<5>")
	)
	(segment
		(start 56.8706 -272.429986)
		(end 57.132474 -272.429986)
		(width 0.14478)
		(layer "In11.Cu")
		(net "M_F_CPU1_SB_CB<5>")
	)
	(segment
		(start 53.134514 -272.560288)
		(end 53.367178 -272.560288)
		(width 0.14478)
		(layer "In11.Cu")
		(net "M_F_CPU1_SB_CB<5>")
	)
	(segment
		(start 82.179668 -270.363696)
		(end 82.18805 -270.35887)
		(width 0.0889)
		(layer "In11.Cu")
		(net "M_F_CPU1_SB_CB<5>")
	)
	(segment
		(start 21.70811 -273.835368)
		(end 22.52472 -273.018758)
		(width 0.14478)
		(layer "In11.Cu")
		(net "M_F_CPU1_SB_CB<5>")
	)
	(segment
		(start 41.914064 -272.876264)
		(end 42.154348 -272.876264)
		(width 0.14478)
		(layer "In11.Cu")
		(net "M_F_CPU1_SB_CB<5>")
	)
	(segment
		(start 33.338516 -272.866104)
		(end 33.58896 -272.866104)
		(width 0.14478)
		(layer "In11.Cu")
		(net "M_F_CPU1_SB_CB<5>")
	)
	(segment
		(start 27.448764 -272.560288)
		(end 27.75458 -272.866104)
		(width 0.14478)
		(layer "In11.Cu")
		(net "M_F_CPU1_SB_CB<5>")
	)
	(segment
		(start 56.58104 -272.883884)
		(end 56.72582 -272.739104)
		(width 0.14478)
		(layer "In11.Cu")
		(net "M_F_CPU1_SB_CB<5>")
	)
	(segment
		(start 46.755558 -272.560288)
		(end 48.104298 -272.560288)
		(width 0.14478)
		(layer "In11.Cu")
		(net "M_F_CPU1_SB_CB<5>")
	)
	(segment
		(start 41.357804 -272.560288)
		(end 41.598088 -272.560288)
		(width 0.14478)
		(layer "In11.Cu")
		(net "M_F_CPU1_SB_CB<5>")
	)
	(segment
		(start 28.005024 -272.866104)
		(end 28.31084 -272.560288)
		(width 0.14478)
		(layer "In11.Cu")
		(net "M_F_CPU1_SB_CB<5>")
	)
	(segment
		(start 35.25774 -272.560288)
		(end 35.563556 -272.866104)
		(width 0.14478)
		(layer "In11.Cu")
		(net "M_F_CPU1_SB_CB<5>")
	)
	(segment
		(start 51.193954 -272.560288)
		(end 52.254658 -272.560288)
		(width 0.14478)
		(layer "In11.Cu")
		(net "M_F_CPU1_SB_CB<5>")
	)
	(segment
		(start 38.775132 -272.881344)
		(end 39.096188 -272.560288)
		(width 0.14478)
		(layer "In11.Cu")
		(net "M_F_CPU1_SB_CB<5>")
	)
	(segment
		(start 57.132474 -272.429986)
		(end 57.277254 -272.574766)
		(width 0.14478)
		(layer "In11.Cu")
		(net "M_F_CPU1_SB_CB<5>")
	)
	(segment
		(start 23.08098 -273.802602)
		(end 23.311612 -273.802602)
		(width 0.14478)
		(layer "In11.Cu")
		(net "M_F_CPU1_SB_CB<5>")
	)
	(segment
		(start 49.773078 -272.868644)
		(end 50.081434 -272.560288)
		(width 0.14478)
		(layer "In11.Cu")
		(net "M_F_CPU1_SB_CB<5>")
	)
	(segment
		(start 28.31084 -272.560288)
		(end 29.633164 -272.560288)
		(width 0.14478)
		(layer "In11.Cu")
		(net "M_F_CPU1_SB_CB<5>")
	)
	(segment
		(start 57.277254 -272.739104)
		(end 57.422034 -272.883884)
		(width 0.14478)
		(layer "In11.Cu")
		(net "M_F_CPU1_SB_CB<5>")
	)
	(segment
		(start 35.814 -272.866104)
		(end 36.119816 -272.560288)
		(width 0.14478)
		(layer "In11.Cu")
		(net "M_F_CPU1_SB_CB<5>")
	)
	(segment
		(start 48.104298 -272.560288)
		(end 48.412654 -272.868644)
		(width 0.14478)
		(layer "In11.Cu")
		(net "M_F_CPU1_SB_CB<5>")
	)
	(segment
		(start 35.007296 -272.560288)
		(end 35.25774 -272.560288)
		(width 0.14478)
		(layer "In11.Cu")
		(net "M_F_CPU1_SB_CB<5>")
	)
	(segment
		(start 23.311612 -273.802602)
		(end 23.474426 -273.639788)
		(width 0.14478)
		(layer "In11.Cu")
		(net "M_F_CPU1_SB_CB<5>")
	)
	(segment
		(start 43.582844 -272.560288)
		(end 44.773342 -272.560288)
		(width 0.14478)
		(layer "In11.Cu")
		(net "M_F_CPU1_SB_CB<5>")
	)
	(segment
		(start 50.885598 -272.868644)
		(end 51.193954 -272.560288)
		(width 0.14478)
		(layer "In11.Cu")
		(net "M_F_CPU1_SB_CB<5>")
	)
	(segment
		(start 50.637694 -272.868644)
		(end 50.885598 -272.868644)
		(width 0.14478)
		(layer "In11.Cu")
		(net "M_F_CPU1_SB_CB<5>")
	)
	(segment
		(start 59.189874 -272.560288)
		(end 60.553854 -272.560288)
		(width 0.14478)
		(layer "In11.Cu")
		(net "M_F_CPU1_SB_CB<5>")
	)
	(segment
		(start 31.301944 -272.861024)
		(end 31.60268 -272.560288)
		(width 0.14478)
		(layer "In11.Cu")
		(net "M_F_CPU1_SB_CB<5>")
	)
	(segment
		(start 57.828688 -272.574766)
		(end 57.973468 -272.429986)
		(width 0.14478)
		(layer "In11.Cu")
		(net "M_F_CPU1_SB_CB<5>")
	)
	(segment
		(start 46.442122 -272.873724)
		(end 46.755558 -272.560288)
		(width 0.14478)
		(layer "In11.Cu")
		(net "M_F_CPU1_SB_CB<5>")
	)
	(segment
		(start 37.662612 -272.881344)
		(end 37.983668 -272.560288)
		(width 0.14478)
		(layer "In11.Cu")
		(net "M_F_CPU1_SB_CB<5>")
	)
	(segment
		(start 56.72582 -272.739104)
		(end 56.72582 -272.574766)
		(width 0.14478)
		(layer "In11.Cu")
		(net "M_F_CPU1_SB_CB<5>")
	)
	(segment
		(start 57.683908 -272.883884)
		(end 57.828688 -272.739104)
		(width 0.14478)
		(layer "In11.Cu")
		(net "M_F_CPU1_SB_CB<5>")
	)
	(segment
		(start 33.894776 -272.560288)
		(end 34.14522 -272.560288)
		(width 0.14478)
		(layer "In11.Cu")
		(net "M_F_CPU1_SB_CB<5>")
	)
	(segment
		(start 29.633164 -272.560288)
		(end 29.9339 -272.861024)
		(width 0.14478)
		(layer "In11.Cu")
		(net "M_F_CPU1_SB_CB<5>")
	)
	(segment
		(start 48.412654 -272.868644)
		(end 48.660558 -272.868644)
		(width 0.14478)
		(layer "In11.Cu")
		(net "M_F_CPU1_SB_CB<5>")
	)
	(segment
		(start 34.451036 -272.866104)
		(end 34.70148 -272.866104)
		(width 0.14478)
		(layer "In11.Cu")
		(net "M_F_CPU1_SB_CB<5>")
	)
	(segment
		(start 22.755352 -273.018758)
		(end 22.918166 -273.181572)
		(width 0.14478)
		(layer "In11.Cu")
		(net "M_F_CPU1_SB_CB<5>")
	)
	(segment
		(start 54.479698 -272.560288)
		(end 54.803294 -272.883884)
		(width 0.14478)
		(layer "In11.Cu")
		(net "M_F_CPU1_SB_CB<5>")
	)
	(segment
		(start 64.607948 -268.506194)
		(end 75.947016 -268.506194)
		(width 0.14478)
		(layer "In11.Cu")
		(net "M_F_CPU1_SB_CB<5>")
	)
	(segment
		(start 23.867872 -273.018758)
		(end 24.030686 -273.181572)
		(width 0.14478)
		(layer "In11.Cu")
		(net "M_F_CPU1_SB_CB<5>")
	)
	(segment
		(start 57.828688 -272.739104)
		(end 57.828688 -272.574766)
		(width 0.14478)
		(layer "In11.Cu")
		(net "M_F_CPU1_SB_CB<5>")
	)
	(segment
		(start 83.694016 -270.35887)
		(end 83.702398 -270.363696)
		(width 0.0889)
		(layer "In11.Cu")
		(net "M_F_CPU1_SB_CB<5>")
	)
	(segment
		(start 24.816308 -273.410426)
		(end 26.163778 -273.410426)
		(width 0.14478)
		(layer "In11.Cu")
		(net "M_F_CPU1_SB_CB<5>")
	)
	(segment
		(start 45.885862 -272.560288)
		(end 46.199298 -272.873724)
		(width 0.14478)
		(layer "In11.Cu")
		(net "M_F_CPU1_SB_CB<5>")
	)
	(segment
		(start 85.89264 -270.385032)
		(end 85.914992 -270.30172)
		(width 0.0889)
		(layer "In11.Cu")
		(net "M_F_CPU1_SB_CB<5>")
	)
	(segment
		(start 52.810918 -272.883884)
		(end 53.134514 -272.560288)
		(width 0.14478)
		(layer "In11.Cu")
		(net "M_F_CPU1_SB_CB<5>")
	)
	(segment
		(start 38.218872 -272.560288)
		(end 38.539928 -272.881344)
		(width 0.14478)
		(layer "In11.Cu")
		(net "M_F_CPU1_SB_CB<5>")
	)
	(segment
		(start 85.914992 -270.30172)
		(end 85.761068 -270.03629)
		(width 0.0889)
		(layer "In11.Cu")
		(net "M_F_CPU1_SB_CB<5>")
	)
	(segment
		(start 41.041828 -272.876264)
		(end 41.357804 -272.560288)
		(width 0.14478)
		(layer "In11.Cu")
		(net "M_F_CPU1_SB_CB<5>")
	)
	(segment
		(start 76.251816 -268.506194)
		(end 76.570586 -268.824964)
		(width 0.0889)
		(layer "In11.Cu")
		(net "M_F_CPU1_SB_CB<5>")
	)
	(segment
		(start 33.58896 -272.866104)
		(end 33.894776 -272.560288)
		(width 0.14478)
		(layer "In11.Cu")
		(net "M_F_CPU1_SB_CB<5>")
	)
	(segment
		(start 57.277254 -272.574766)
		(end 57.277254 -272.739104)
		(width 0.14478)
		(layer "In11.Cu")
		(net "M_F_CPU1_SB_CB<5>")
	)
	(segment
		(start 36.119816 -272.560288)
		(end 37.106352 -272.560288)
		(width 0.14478)
		(layer "In11.Cu")
		(net "M_F_CPU1_SB_CB<5>")
	)
	(segment
		(start 42.470324 -272.560288)
		(end 42.710608 -272.560288)
		(width 0.14478)
		(layer "In11.Cu")
		(net "M_F_CPU1_SB_CB<5>")
	)
	(segment
		(start 27.013916 -272.560288)
		(end 27.448764 -272.560288)
		(width 0.14478)
		(layer "In11.Cu")
		(net "M_F_CPU1_SB_CB<5>")
	)
	(segment
		(start 48.968914 -272.560288)
		(end 49.216818 -272.560288)
		(width 0.14478)
		(layer "In11.Cu")
		(net "M_F_CPU1_SB_CB<5>")
	)
	(segment
		(start 58.380122 -272.739104)
		(end 58.524902 -272.883884)
		(width 0.14478)
		(layer "In11.Cu")
		(net "M_F_CPU1_SB_CB<5>")
	)
	(segment
		(start 40.801544 -272.876264)
		(end 41.041828 -272.876264)
		(width 0.14478)
		(layer "In11.Cu")
		(net "M_F_CPU1_SB_CB<5>")
	)
	(segment
		(start 57.422034 -272.883884)
		(end 57.683908 -272.883884)
		(width 0.14478)
		(layer "In11.Cu")
		(net "M_F_CPU1_SB_CB<5>")
	)
	(segment
		(start 60.553854 -272.560288)
		(end 64.607948 -268.506194)
		(width 0.14478)
		(layer "In11.Cu")
		(net "M_F_CPU1_SB_CB<5>")
	)
	(segment
		(start 58.524902 -272.883884)
		(end 58.866278 -272.883884)
		(width 0.14478)
		(layer "In11.Cu")
		(net "M_F_CPU1_SB_CB<5>")
	)
	(segment
		(start 26.163778 -273.410426)
		(end 27.013916 -272.560288)
		(width 0.14478)
		(layer "In11.Cu")
		(net "M_F_CPU1_SB_CB<5>")
	)
	(segment
		(start 56.72582 -272.574766)
		(end 56.8706 -272.429986)
		(width 0.14478)
		(layer "In11.Cu")
		(net "M_F_CPU1_SB_CB<5>")
	)
	(segment
		(start 45.643038 -272.560288)
		(end 45.885862 -272.560288)
		(width 0.14478)
		(layer "In11.Cu")
		(net "M_F_CPU1_SB_CB<5>")
	)
	(segment
		(start 58.380122 -272.574766)
		(end 58.380122 -272.739104)
		(width 0.14478)
		(layer "In11.Cu")
		(net "M_F_CPU1_SB_CB<5>")
	)
	(segment
		(start 49.216818 -272.560288)
		(end 49.525174 -272.868644)
		(width 0.14478)
		(layer "In11.Cu")
		(net "M_F_CPU1_SB_CB<5>")
	)
	(segment
		(start 24.030686 -273.181572)
		(end 24.030686 -273.639788)
		(width 0.14478)
		(layer "In11.Cu")
		(net "M_F_CPU1_SB_CB<5>")
	)
	(segment
		(start 41.598088 -272.560288)
		(end 41.914064 -272.876264)
		(width 0.14478)
		(layer "In11.Cu")
		(net "M_F_CPU1_SB_CB<5>")
	)
	(segment
		(start 27.75458 -272.866104)
		(end 28.005024 -272.866104)
		(width 0.14478)
		(layer "In11.Cu")
		(net "M_F_CPU1_SB_CB<5>")
	)
	(segment
		(start 57.973468 -272.429986)
		(end 58.235342 -272.429986)
		(width 0.14478)
		(layer "In11.Cu")
		(net "M_F_CPU1_SB_CB<5>")
	)
	(segment
		(start 30.189424 -272.861024)
		(end 30.49016 -272.560288)
		(width 0.14478)
		(layer "In11.Cu")
		(net "M_F_CPU1_SB_CB<5>")
	)
	(segment
		(start 54.803294 -272.883884)
		(end 56.58104 -272.883884)
		(width 0.14478)
		(layer "In11.Cu")
		(net "M_F_CPU1_SB_CB<5>")
	)
	(segment
		(start 37.106352 -272.560288)
		(end 37.427408 -272.881344)
		(width 0.14478)
		(layer "In11.Cu")
		(net "M_F_CPU1_SB_CB<5>")
	)
	(segment
		(start 43.026584 -272.876264)
		(end 43.266868 -272.876264)
		(width 0.14478)
		(layer "In11.Cu")
		(net "M_F_CPU1_SB_CB<5>")
	)
	(segment
		(start 77.090778 -268.824964)
		(end 78.391512 -270.125698)
		(width 0.0889)
		(layer "In11.Cu")
		(net "M_F_CPU1_SB_CB<5>")
	)
	(segment
		(start 30.745684 -272.560288)
		(end 31.04642 -272.861024)
		(width 0.14478)
		(layer "In11.Cu")
		(net "M_F_CPU1_SB_CB<5>")
	)
	(segment
		(start 52.578254 -272.883884)
		(end 52.810918 -272.883884)
		(width 0.14478)
		(layer "In11.Cu")
		(net "M_F_CPU1_SB_CB<5>")
	)
	(segment
		(start 49.525174 -272.868644)
		(end 49.773078 -272.868644)
		(width 0.14478)
		(layer "In11.Cu")
		(net "M_F_CPU1_SB_CB<5>")
	)
	(segment
		(start 23.474426 -273.181572)
		(end 23.63724 -273.018758)
		(width 0.14478)
		(layer "In11.Cu")
		(net "M_F_CPU1_SB_CB<5>")
	)
	(segment
		(start 31.04642 -272.861024)
		(end 31.301944 -272.861024)
		(width 0.14478)
		(layer "In11.Cu")
		(net "M_F_CPU1_SB_CB<5>")
	)
	(segment
		(start 39.096188 -272.560288)
		(end 40.485568 -272.560288)
		(width 0.14478)
		(layer "In11.Cu")
		(net "M_F_CPU1_SB_CB<5>")
	)
	(segment
		(start 22.52472 -273.018758)
		(end 22.755352 -273.018758)
		(width 0.14478)
		(layer "In11.Cu")
		(net "M_F_CPU1_SB_CB<5>")
	)
	(segment
		(start 22.918166 -273.639788)
		(end 23.08098 -273.802602)
		(width 0.14478)
		(layer "In11.Cu")
		(net "M_F_CPU1_SB_CB<5>")
	)
	(segment
		(start 52.254658 -272.560288)
		(end 52.578254 -272.883884)
		(width 0.14478)
		(layer "In11.Cu")
		(net "M_F_CPU1_SB_CB<5>")
	)
	(segment
		(start 78.471776 -270.158972)
		(end 79.192628 -270.158972)
		(width 0.0889)
		(layer "In11.Cu")
		(net "M_F_CPU1_SB_CB<5>")
	)
	(segment
		(start 38.539928 -272.881344)
		(end 38.775132 -272.881344)
		(width 0.14478)
		(layer "In11.Cu")
		(net "M_F_CPU1_SB_CB<5>")
	)
	(segment
		(start 44.773342 -272.560288)
		(end 45.086778 -272.873724)
		(width 0.14478)
		(layer "In11.Cu")
		(net "M_F_CPU1_SB_CB<5>")
	)
	(segment
		(start 43.266868 -272.876264)
		(end 43.582844 -272.560288)
		(width 0.14478)
		(layer "In11.Cu")
		(net "M_F_CPU1_SB_CB<5>")
	)
	(segment
		(start 24.030686 -273.639788)
		(end 24.1935 -273.802602)
		(width 0.14478)
		(layer "In11.Cu")
		(net "M_F_CPU1_SB_CB<5>")
	)
	(segment
		(start 53.923438 -272.883884)
		(end 54.247034 -272.560288)
		(width 0.14478)
		(layer "In11.Cu")
		(net "M_F_CPU1_SB_CB<5>")
	)
	(segment
		(start 50.329338 -272.560288)
		(end 50.637694 -272.868644)
		(width 0.14478)
		(layer "In11.Cu")
		(net "M_F_CPU1_SB_CB<5>")
	)
	(segment
		(start 76.570586 -268.824964)
		(end 77.090778 -268.824964)
		(width 0.0889)
		(layer "In11.Cu")
		(net "M_F_CPU1_SB_CB<5>")
	)
	(segment
		(start 53.690774 -272.883884)
		(end 53.923438 -272.883884)
		(width 0.14478)
		(layer "In11.Cu")
		(net "M_F_CPU1_SB_CB<5>")
	)
	(segment
		(start 22.918166 -273.181572)
		(end 22.918166 -273.639788)
		(width 0.14478)
		(layer "In11.Cu")
		(net "M_F_CPU1_SB_CB<5>")
	)
	(segment
		(start 48.660558 -272.868644)
		(end 48.968914 -272.560288)
		(width 0.14478)
		(layer "In11.Cu")
		(net "M_F_CPU1_SB_CB<5>")
	)
	(segment
		(start 58.235342 -272.429986)
		(end 58.380122 -272.574766)
		(width 0.14478)
		(layer "In11.Cu")
		(net "M_F_CPU1_SB_CB<5>")
	)
	(segment
		(start 34.70148 -272.866104)
		(end 35.007296 -272.560288)
		(width 0.14478)
		(layer "In11.Cu")
		(net "M_F_CPU1_SB_CB<5>")
	)
	(segment
		(start 53.367178 -272.560288)
		(end 53.690774 -272.883884)
		(width 0.14478)
		(layer "In11.Cu")
		(net "M_F_CPU1_SB_CB<5>")
	)
	(segment
		(start 24.1935 -273.802602)
		(end 24.424132 -273.802602)
		(width 0.14478)
		(layer "In11.Cu")
		(net "M_F_CPU1_SB_CB<5>")
	)
	(segment
		(start 37.983668 -272.560288)
		(end 38.218872 -272.560288)
		(width 0.14478)
		(layer "In11.Cu")
		(net "M_F_CPU1_SB_CB<5>")
	)
	(segment
		(start 31.60268 -272.560288)
		(end 33.0327 -272.560288)
		(width 0.14478)
		(layer "In11.Cu")
		(net "M_F_CPU1_SB_CB<5>")
	)
	(segment
		(start 33.0327 -272.560288)
		(end 33.338516 -272.866104)
		(width 0.14478)
		(layer "In11.Cu")
		(net "M_F_CPU1_SB_CB<5>")
	)
	(segment
		(start 40.485568 -272.560288)
		(end 40.801544 -272.876264)
		(width 0.14478)
		(layer "In11.Cu")
		(net "M_F_CPU1_SB_CB<5>")
	)
	(segment
		(start 30.49016 -272.560288)
		(end 30.745684 -272.560288)
		(width 0.14478)
		(layer "In11.Cu")
		(net "M_F_CPU1_SB_CB<5>")
	)
	(segment
		(start 37.427408 -272.881344)
		(end 37.662612 -272.881344)
		(width 0.14478)
		(layer "In11.Cu")
		(net "M_F_CPU1_SB_CB<5>")
	)
	(segment
		(start 82.753962 -270.35887)
		(end 82.762344 -270.363696)
		(width 0.0889)
		(layer "In11.Cu")
		(net "M_F_CPU1_SB_CB<5>")
	)
	(segment
		(start 54.247034 -272.560288)
		(end 54.479698 -272.560288)
		(width 0.14478)
		(layer "In11.Cu")
		(net "M_F_CPU1_SB_CB<5>")
	)
	(segment
		(start 45.329602 -272.873724)
		(end 45.643038 -272.560288)
		(width 0.14478)
		(layer "In11.Cu")
		(net "M_F_CPU1_SB_CB<5>")
	)
	(segment
		(start 58.866278 -272.883884)
		(end 59.189874 -272.560288)
		(width 0.14478)
		(layer "In11.Cu")
		(net "M_F_CPU1_SB_CB<5>")
	)
	(segment
		(start 35.563556 -272.866104)
		(end 35.814 -272.866104)
		(width 0.14478)
		(layer "In11.Cu")
		(net "M_F_CPU1_SB_CB<5>")
	)
	(segment
		(start 75.947016 -268.506194)
		(end 76.251816 -268.506194)
		(width 0.0889)
		(layer "In11.Cu")
		(net "M_F_CPU1_SB_CB<5>")
	)
	(segment
		(start 23.474426 -273.639788)
		(end 23.474426 -273.181572)
		(width 0.14478)
		(layer "In11.Cu")
		(net "M_F_CPU1_SB_CB<5>")
	)
	(arc
		(start 79.9338 -270.35887)
		(mid 80.120998 -270.409252)
		(end 80.308196 -270.35887)
		(width 0.0889)
		(layer "In11.Cu")
		(net "M_F_CPU1_SB_CB<5>")
	)
	(arc
		(start 80.874108 -270.35887)
		(mid 81.061052 -270.409125)
		(end 81.247996 -270.35887)
		(width 0.0889)
		(layer "In11.Cu")
		(net "M_F_CPU1_SB_CB<5>")
	)
	(arc
		(start 85.57387 -270.35887)
		(mid 85.730308 -270.407841)
		(end 85.89264 -270.385032)
		(width 0.0889)
		(layer "In11.Cu")
		(net "M_F_CPU1_SB_CB<5>")
	)
	(arc
		(start 85.007958 -270.35887)
		(mid 85.290914 -270.282693)
		(end 85.57387 -270.35887)
		(width 0.0889)
		(layer "In11.Cu")
		(net "M_F_CPU1_SB_CB<5>")
	)
	(arc
		(start 78.391512 -270.125698)
		(mid 78.428323 -270.150358)
		(end 78.471776 -270.158972)
		(width 0.0889)
		(layer "In11.Cu")
		(net "M_F_CPU1_SB_CB<5>")
	)
	(arc
		(start 79.192628 -270.158972)
		(mid 79.57646 -270.209817)
		(end 79.9338 -270.35887)
		(width 0.0889)
		(layer "In11.Cu")
		(net "M_F_CPU1_SB_CB<5>")
	)
	(arc
		(start 82.762344 -270.363696)
		(mid 82.945852 -270.40919)
		(end 83.128104 -270.35887)
		(width 0.0889)
		(layer "In11.Cu")
		(net "M_F_CPU1_SB_CB<5>")
	)
	(arc
		(start 83.128104 -270.35887)
		(mid 83.41106 -270.282693)
		(end 83.694016 -270.35887)
		(width 0.0889)
		(layer "In11.Cu")
		(net "M_F_CPU1_SB_CB<5>")
	)
	(arc
		(start 81.247996 -270.35887)
		(mid 81.530952 -270.282693)
		(end 81.813908 -270.35887)
		(width 0.0889)
		(layer "In11.Cu")
		(net "M_F_CPU1_SB_CB<5>")
	)
	(arc
		(start 82.18805 -270.35887)
		(mid 82.471006 -270.282693)
		(end 82.753962 -270.35887)
		(width 0.0889)
		(layer "In11.Cu")
		(net "M_F_CPU1_SB_CB<5>")
	)
	(arc
		(start 80.308196 -270.35887)
		(mid 80.591152 -270.282693)
		(end 80.874108 -270.35887)
		(width 0.0889)
		(layer "In11.Cu")
		(net "M_F_CPU1_SB_CB<5>")
	)
	(arc
		(start 83.702398 -270.363696)
		(mid 83.885906 -270.40919)
		(end 84.068158 -270.35887)
		(width 0.0889)
		(layer "In11.Cu")
		(net "M_F_CPU1_SB_CB<5>")
	)
	(arc
		(start 84.63407 -270.35887)
		(mid 84.821014 -270.409125)
		(end 85.007958 -270.35887)
		(width 0.0889)
		(layer "In11.Cu")
		(net "M_F_CPU1_SB_CB<5>")
	)
	(arc
		(start 84.068158 -270.35887)
		(mid 84.351114 -270.282693)
		(end 84.63407 -270.35887)
		(width 0.0889)
		(layer "In11.Cu")
		(net "M_F_CPU1_SB_CB<5>")
	)
	(arc
		(start 81.813908 -270.35887)
		(mid 81.996159 -270.40922)
		(end 82.179668 -270.363696)
		(width 0.0889)
		(layer "In11.Cu")
		(net "M_F_CPU1_SB_CB<5>")
	)
	(segment
		(start 84.817966 -268.960346)
		(end 84.351114 -269.226284)
		(width 0.10668)
		(layer "F.Cu")
		(net "M_F_CPU1_SB_CB<4>")
	)
	(segment
		(start 50.349658 -270.860266)
		(end 50.666396 -271.177004)
		(width 0.14478)
		(layer "In11.Cu")
		(net "M_F_CPU1_SB_CB<4>")
	)
	(segment
		(start 58.72607 -270.860266)
		(end 60.44438 -270.860266)
		(width 0.14478)
		(layer "In11.Cu")
		(net "M_F_CPU1_SB_CB<4>")
	)
	(segment
		(start 61.92774 -269.58163)
		(end 61.92774 -269.376906)
		(width 0.14478)
		(layer "In11.Cu")
		(net "M_F_CPU1_SB_CB<4>")
	)
	(segment
		(start 27.302968 -270.860266)
		(end 27.612086 -271.169384)
		(width 0.14478)
		(layer "In11.Cu")
		(net "M_F_CPU1_SB_CB<4>")
	)
	(segment
		(start 35.285934 -270.860266)
		(end 35.600132 -271.174464)
		(width 0.14478)
		(layer "In11.Cu")
		(net "M_F_CPU1_SB_CB<4>")
	)
	(segment
		(start 34.487612 -271.174464)
		(end 34.729674 -271.174464)
		(width 0.14478)
		(layer "In11.Cu")
		(net "M_F_CPU1_SB_CB<4>")
	)
	(segment
		(start 84.505038 -269.491714)
		(end 84.351114 -269.226284)
		(width 0.0889)
		(layer "In11.Cu")
		(net "M_F_CPU1_SB_CB<4>")
	)
	(segment
		(start 24.203406 -272.09623)
		(end 24.434038 -272.09623)
		(width 0.14478)
		(layer "In11.Cu")
		(net "M_F_CPU1_SB_CB<4>")
	)
	(segment
		(start 28.168346 -270.860266)
		(end 29.645356 -270.860266)
		(width 0.14478)
		(layer "In11.Cu")
		(net "M_F_CPU1_SB_CB<4>")
	)
	(segment
		(start 63.552324 -268.289786)
		(end 63.552324 -268.085062)
		(width 0.14478)
		(layer "In11.Cu")
		(net "M_F_CPU1_SB_CB<4>")
	)
	(segment
		(start 23.877778 -271.30883)
		(end 24.040592 -271.471644)
		(width 0.14478)
		(layer "In11.Cu")
		(net "M_F_CPU1_SB_CB<4>")
	)
	(segment
		(start 62.772036 -268.86535)
		(end 62.708028 -268.801342)
		(width 0.14478)
		(layer "In11.Cu")
		(net "M_F_CPU1_SB_CB<4>")
	)
	(segment
		(start 81.344008 -269.548864)
		(end 81.35239 -269.55369)
		(width 0.0889)
		(layer "In11.Cu")
		(net "M_F_CPU1_SB_CB<4>")
	)
	(segment
		(start 49.793398 -271.177004)
		(end 50.110136 -270.860266)
		(width 0.14478)
		(layer "In11.Cu")
		(net "M_F_CPU1_SB_CB<4>")
	)
	(segment
		(start 62.893448 -268.411198)
		(end 63.098172 -268.411198)
		(width 0.14478)
		(layer "In11.Cu")
		(net "M_F_CPU1_SB_CB<4>")
	)
	(segment
		(start 25.9588 -271.710404)
		(end 26.808938 -270.860266)
		(width 0.14478)
		(layer "In11.Cu")
		(net "M_F_CPU1_SB_CB<4>")
	)
	(segment
		(start 63.552324 -268.085062)
		(end 63.488316 -268.021054)
		(width 0.14478)
		(layer "In11.Cu")
		(net "M_F_CPU1_SB_CB<4>")
	)
	(segment
		(start 50.905918 -271.177004)
		(end 51.222656 -270.860266)
		(width 0.14478)
		(layer "In11.Cu")
		(net "M_F_CPU1_SB_CB<4>")
	)
	(segment
		(start 55.94477 -271.164304)
		(end 56.196992 -271.164304)
		(width 0.14478)
		(layer "In11.Cu")
		(net "M_F_CPU1_SB_CB<4>")
	)
	(segment
		(start 53.71973 -271.164304)
		(end 53.971952 -271.164304)
		(width 0.14478)
		(layer "In11.Cu")
		(net "M_F_CPU1_SB_CB<4>")
	)
	(segment
		(start 79.464408 -269.54861)
		(end 79.478124 -269.556484)
		(width 0.0889)
		(layer "In11.Cu")
		(net "M_F_CPU1_SB_CB<4>")
	)
	(segment
		(start 46.42612 -271.184624)
		(end 46.750478 -270.860266)
		(width 0.14478)
		(layer "In11.Cu")
		(net "M_F_CPU1_SB_CB<4>")
	)
	(segment
		(start 84.482686 -269.575026)
		(end 84.505038 -269.491714)
		(width 0.0889)
		(layer "In11.Cu")
		(net "M_F_CPU1_SB_CB<4>")
	)
	(segment
		(start 24.819864 -271.710404)
		(end 25.9588 -271.710404)
		(width 0.14478)
		(layer "In11.Cu")
		(net "M_F_CPU1_SB_CB<4>")
	)
	(segment
		(start 61.147452 -270.361918)
		(end 61.147452 -270.157194)
		(width 0.14478)
		(layer "In11.Cu")
		(net "M_F_CPU1_SB_CB<4>")
	)
	(segment
		(start 42.291508 -271.184624)
		(end 42.615866 -270.860266)
		(width 0.14478)
		(layer "In11.Cu")
		(net "M_F_CPU1_SB_CB<4>")
	)
	(segment
		(start 77.481176 -267.982954)
		(end 77.481176 -268.523974)
		(width 0.0889)
		(layer "In11.Cu")
		(net "M_F_CPU1_SB_CB<4>")
	)
	(segment
		(start 61.02604 -270.81607)
		(end 61.21146 -270.63065)
		(width 0.14478)
		(layer "In11.Cu")
		(net "M_F_CPU1_SB_CB<4>")
	)
	(segment
		(start 34.173414 -270.860266)
		(end 34.487612 -271.174464)
		(width 0.14478)
		(layer "In11.Cu")
		(net "M_F_CPU1_SB_CB<4>")
	)
	(segment
		(start 31.061914 -271.164304)
		(end 31.314136 -271.164304)
		(width 0.14478)
		(layer "In11.Cu")
		(net "M_F_CPU1_SB_CB<4>")
	)
	(segment
		(start 52.859432 -271.164304)
		(end 53.16347 -270.860266)
		(width 0.14478)
		(layer "In11.Cu")
		(net "M_F_CPU1_SB_CB<4>")
	)
	(segment
		(start 45.081698 -271.184624)
		(end 45.3136 -271.184624)
		(width 0.14478)
		(layer "In11.Cu")
		(net "M_F_CPU1_SB_CB<4>")
	)
	(segment
		(start 42.847768 -270.860266)
		(end 43.172126 -271.184624)
		(width 0.14478)
		(layer "In11.Cu")
		(net "M_F_CPU1_SB_CB<4>")
	)
	(segment
		(start 80.769714 -269.55369)
		(end 80.778096 -269.548864)
		(width 0.0889)
		(layer "In11.Cu")
		(net "M_F_CPU1_SB_CB<4>")
	)
	(segment
		(start 36.156392 -270.860266)
		(end 37.239702 -270.860266)
		(width 0.14478)
		(layer "In11.Cu")
		(net "M_F_CPU1_SB_CB<4>")
	)
	(segment
		(start 38.12032 -270.860266)
		(end 38.352222 -270.860266)
		(width 0.14478)
		(layer "In11.Cu")
		(net "M_F_CPU1_SB_CB<4>")
	)
	(segment
		(start 62.708028 -268.801342)
		(end 62.708028 -268.596618)
		(width 0.14478)
		(layer "In11.Cu")
		(net "M_F_CPU1_SB_CB<4>")
	)
	(segment
		(start 31.314136 -271.164304)
		(end 31.618174 -270.860266)
		(width 0.14478)
		(layer "In11.Cu")
		(net "M_F_CPU1_SB_CB<4>")
	)
	(segment
		(start 79.442818 -269.536164)
		(end 79.464408 -269.54861)
		(width 0.0889)
		(layer "In11.Cu")
		(net "M_F_CPU1_SB_CB<4>")
	)
	(segment
		(start 60.44438 -270.860266)
		(end 60.552584 -270.752062)
		(width 0.14478)
		(layer "In11.Cu")
		(net "M_F_CPU1_SB_CB<4>")
	)
	(segment
		(start 26.808938 -270.860266)
		(end 27.302968 -270.860266)
		(width 0.14478)
		(layer "In11.Cu")
		(net "M_F_CPU1_SB_CB<4>")
	)
	(segment
		(start 30.505654 -270.860266)
		(end 30.757876 -270.860266)
		(width 0.14478)
		(layer "In11.Cu")
		(net "M_F_CPU1_SB_CB<4>")
	)
	(segment
		(start 62.317884 -269.191486)
		(end 62.381892 -269.255494)
		(width 0.14478)
		(layer "In11.Cu")
		(net "M_F_CPU1_SB_CB<4>")
	)
	(segment
		(start 40.947086 -271.184624)
		(end 41.178988 -271.184624)
		(width 0.14478)
		(layer "In11.Cu")
		(net "M_F_CPU1_SB_CB<4>")
	)
	(segment
		(start 38.67658 -271.184624)
		(end 38.908482 -271.184624)
		(width 0.14478)
		(layer "In11.Cu")
		(net "M_F_CPU1_SB_CB<4>")
	)
	(segment
		(start 58.16981 -271.164304)
		(end 58.422032 -271.164304)
		(width 0.14478)
		(layer "In11.Cu")
		(net "M_F_CPU1_SB_CB<4>")
	)
	(segment
		(start 63.488316 -267.81633)
		(end 63.707772 -267.596874)
		(width 0.14478)
		(layer "In11.Cu")
		(net "M_F_CPU1_SB_CB<4>")
	)
	(segment
		(start 22.765258 -271.30883)
		(end 22.928072 -271.471644)
		(width 0.14478)
		(layer "In11.Cu")
		(net "M_F_CPU1_SB_CB<4>")
	)
	(segment
		(start 48.124618 -270.860266)
		(end 48.441356 -271.177004)
		(width 0.14478)
		(layer "In11.Cu")
		(net "M_F_CPU1_SB_CB<4>")
	)
	(segment
		(start 35.842194 -271.174464)
		(end 36.156392 -270.860266)
		(width 0.14478)
		(layer "In11.Cu")
		(net "M_F_CPU1_SB_CB<4>")
	)
	(segment
		(start 52.303172 -270.860266)
		(end 52.60721 -271.164304)
		(width 0.14478)
		(layer "In11.Cu")
		(net "M_F_CPU1_SB_CB<4>")
	)
	(segment
		(start 57.61355 -270.860266)
		(end 57.865772 -270.860266)
		(width 0.14478)
		(layer "In11.Cu")
		(net "M_F_CPU1_SB_CB<4>")
	)
	(segment
		(start 57.05729 -271.164304)
		(end 57.309512 -271.164304)
		(width 0.14478)
		(layer "In11.Cu")
		(net "M_F_CPU1_SB_CB<4>")
	)
	(segment
		(start 62.586616 -269.255494)
		(end 62.772036 -269.070074)
		(width 0.14478)
		(layer "In11.Cu")
		(net "M_F_CPU1_SB_CB<4>")
	)
	(segment
		(start 51.222656 -270.860266)
		(end 52.303172 -270.860266)
		(width 0.14478)
		(layer "In11.Cu")
		(net "M_F_CPU1_SB_CB<4>")
	)
	(segment
		(start 61.991748 -269.850362)
		(end 61.991748 -269.645638)
		(width 0.14478)
		(layer "In11.Cu")
		(net "M_F_CPU1_SB_CB<4>")
	)
	(segment
		(start 29.949394 -271.164304)
		(end 30.201616 -271.164304)
		(width 0.14478)
		(layer "In11.Cu")
		(net "M_F_CPU1_SB_CB<4>")
	)
	(segment
		(start 83.589622 -269.55369)
		(end 83.598004 -269.548864)
		(width 0.0889)
		(layer "In11.Cu")
		(net "M_F_CPU1_SB_CB<4>")
	)
	(segment
		(start 23.484332 -271.471644)
		(end 23.647146 -271.30883)
		(width 0.14478)
		(layer "In11.Cu")
		(net "M_F_CPU1_SB_CB<4>")
	)
	(segment
		(start 61.21146 -270.425926)
		(end 61.147452 -270.361918)
		(width 0.14478)
		(layer "In11.Cu")
		(net "M_F_CPU1_SB_CB<4>")
	)
	(segment
		(start 33.931352 -270.860266)
		(end 34.173414 -270.860266)
		(width 0.14478)
		(layer "In11.Cu")
		(net "M_F_CPU1_SB_CB<4>")
	)
	(segment
		(start 41.735248 -270.860266)
		(end 42.059606 -271.184624)
		(width 0.14478)
		(layer "In11.Cu")
		(net "M_F_CPU1_SB_CB<4>")
	)
	(segment
		(start 56.196992 -271.164304)
		(end 56.50103 -270.860266)
		(width 0.14478)
		(layer "In11.Cu")
		(net "M_F_CPU1_SB_CB<4>")
	)
	(segment
		(start 30.757876 -270.860266)
		(end 31.061914 -271.164304)
		(width 0.14478)
		(layer "In11.Cu")
		(net "M_F_CPU1_SB_CB<4>")
	)
	(segment
		(start 61.92774 -269.376906)
		(end 62.11316 -269.191486)
		(width 0.14478)
		(layer "In11.Cu")
		(net "M_F_CPU1_SB_CB<4>")
	)
	(segment
		(start 41.503346 -270.860266)
		(end 41.735248 -270.860266)
		(width 0.14478)
		(layer "In11.Cu")
		(net "M_F_CPU1_SB_CB<4>")
	)
	(segment
		(start 34.729674 -271.174464)
		(end 35.043872 -270.860266)
		(width 0.14478)
		(layer "In11.Cu")
		(net "M_F_CPU1_SB_CB<4>")
	)
	(segment
		(start 78.447138 -269.489936)
		(end 78.447392 -269.489936)
		(width 0.0889)
		(layer "In11.Cu")
		(net "M_F_CPU1_SB_CB<4>")
	)
	(segment
		(start 78.524608 -269.54861)
		(end 78.544674 -269.56004)
		(width 0.0889)
		(layer "In11.Cu")
		(net "M_F_CPU1_SB_CB<4>")
	)
	(segment
		(start 54.27599 -270.860266)
		(end 54.528212 -270.860266)
		(width 0.14478)
		(layer "In11.Cu")
		(net "M_F_CPU1_SB_CB<4>")
	)
	(segment
		(start 48.441356 -271.177004)
		(end 48.680878 -271.177004)
		(width 0.14478)
		(layer "In11.Cu")
		(net "M_F_CPU1_SB_CB<4>")
	)
	(segment
		(start 23.647146 -271.30883)
		(end 23.877778 -271.30883)
		(width 0.14478)
		(layer "In11.Cu")
		(net "M_F_CPU1_SB_CB<4>")
	)
	(segment
		(start 42.059606 -271.184624)
		(end 42.291508 -271.184624)
		(width 0.14478)
		(layer "In11.Cu")
		(net "M_F_CPU1_SB_CB<4>")
	)
	(segment
		(start 24.434038 -272.09623)
		(end 24.819864 -271.710404)
		(width 0.14478)
		(layer "In11.Cu")
		(net "M_F_CPU1_SB_CB<4>")
	)
	(segment
		(start 57.309512 -271.164304)
		(end 57.61355 -270.860266)
		(width 0.14478)
		(layer "In11.Cu")
		(net "M_F_CPU1_SB_CB<4>")
	)
	(segment
		(start 45.86986 -270.860266)
		(end 46.194218 -271.184624)
		(width 0.14478)
		(layer "In11.Cu")
		(net "M_F_CPU1_SB_CB<4>")
	)
	(segment
		(start 41.178988 -271.184624)
		(end 41.503346 -270.860266)
		(width 0.14478)
		(layer "In11.Cu")
		(net "M_F_CPU1_SB_CB<4>")
	)
	(segment
		(start 46.750478 -270.860266)
		(end 48.124618 -270.860266)
		(width 0.14478)
		(layer "In11.Cu")
		(net "M_F_CPU1_SB_CB<4>")
	)
	(segment
		(start 24.040592 -271.933416)
		(end 24.203406 -272.09623)
		(width 0.14478)
		(layer "In11.Cu")
		(net "M_F_CPU1_SB_CB<4>")
	)
	(segment
		(start 49.237138 -270.860266)
		(end 49.553876 -271.177004)
		(width 0.14478)
		(layer "In11.Cu")
		(net "M_F_CPU1_SB_CB<4>")
	)
	(segment
		(start 63.488316 -268.021054)
		(end 63.488316 -267.81633)
		(width 0.14478)
		(layer "In11.Cu")
		(net "M_F_CPU1_SB_CB<4>")
	)
	(segment
		(start 22.534626 -271.30883)
		(end 22.765258 -271.30883)
		(width 0.14478)
		(layer "In11.Cu")
		(net "M_F_CPU1_SB_CB<4>")
	)
	(segment
		(start 63.366904 -268.475206)
		(end 63.552324 -268.289786)
		(width 0.14478)
		(layer "In11.Cu")
		(net "M_F_CPU1_SB_CB<4>")
	)
	(segment
		(start 60.552584 -270.752062)
		(end 60.757308 -270.752062)
		(width 0.14478)
		(layer "In11.Cu")
		(net "M_F_CPU1_SB_CB<4>")
	)
	(segment
		(start 23.321518 -272.09623)
		(end 23.484332 -271.933416)
		(width 0.14478)
		(layer "In11.Cu")
		(net "M_F_CPU1_SB_CB<4>")
	)
	(segment
		(start 53.415692 -270.860266)
		(end 53.71973 -271.164304)
		(width 0.14478)
		(layer "In11.Cu")
		(net "M_F_CPU1_SB_CB<4>")
	)
	(segment
		(start 62.381892 -269.255494)
		(end 62.586616 -269.255494)
		(width 0.14478)
		(layer "In11.Cu")
		(net "M_F_CPU1_SB_CB<4>")
	)
	(segment
		(start 61.21146 -270.63065)
		(end 61.21146 -270.425926)
		(width 0.14478)
		(layer "In11.Cu")
		(net "M_F_CPU1_SB_CB<4>")
	)
	(segment
		(start 75.969876 -267.596874)
		(end 77.095096 -267.596874)
		(width 0.0889)
		(layer "In11.Cu")
		(net "M_F_CPU1_SB_CB<4>")
	)
	(segment
		(start 60.757308 -270.752062)
		(end 60.821316 -270.81607)
		(width 0.14478)
		(layer "In11.Cu")
		(net "M_F_CPU1_SB_CB<4>")
	)
	(segment
		(start 45.637958 -270.860266)
		(end 45.86986 -270.860266)
		(width 0.14478)
		(layer "In11.Cu")
		(net "M_F_CPU1_SB_CB<4>")
	)
	(segment
		(start 38.908482 -271.184624)
		(end 39.23284 -270.860266)
		(width 0.14478)
		(layer "In11.Cu")
		(net "M_F_CPU1_SB_CB<4>")
	)
	(segment
		(start 35.043872 -270.860266)
		(end 35.285934 -270.860266)
		(width 0.14478)
		(layer "In11.Cu")
		(net "M_F_CPU1_SB_CB<4>")
	)
	(segment
		(start 27.859228 -271.169384)
		(end 28.168346 -270.860266)
		(width 0.14478)
		(layer "In11.Cu")
		(net "M_F_CPU1_SB_CB<4>")
	)
	(segment
		(start 50.110136 -270.860266)
		(end 50.349658 -270.860266)
		(width 0.14478)
		(layer "In11.Cu")
		(net "M_F_CPU1_SB_CB<4>")
	)
	(segment
		(start 62.708028 -268.596618)
		(end 62.893448 -268.411198)
		(width 0.14478)
		(layer "In11.Cu")
		(net "M_F_CPU1_SB_CB<4>")
	)
	(segment
		(start 37.795962 -271.184624)
		(end 38.12032 -270.860266)
		(width 0.14478)
		(layer "In11.Cu")
		(net "M_F_CPU1_SB_CB<4>")
	)
	(segment
		(start 21.70811 -272.135346)
		(end 22.534626 -271.30883)
		(width 0.14478)
		(layer "In11.Cu")
		(net "M_F_CPU1_SB_CB<4>")
	)
	(segment
		(start 23.484332 -271.933416)
		(end 23.484332 -271.471644)
		(width 0.14478)
		(layer "In11.Cu")
		(net "M_F_CPU1_SB_CB<4>")
	)
	(segment
		(start 56.753252 -270.860266)
		(end 57.05729 -271.164304)
		(width 0.14478)
		(layer "In11.Cu")
		(net "M_F_CPU1_SB_CB<4>")
	)
	(segment
		(start 49.553876 -271.177004)
		(end 49.793398 -271.177004)
		(width 0.14478)
		(layer "In11.Cu")
		(net "M_F_CPU1_SB_CB<4>")
	)
	(segment
		(start 33.060894 -270.860266)
		(end 33.375092 -271.174464)
		(width 0.14478)
		(layer "In11.Cu")
		(net "M_F_CPU1_SB_CB<4>")
	)
	(segment
		(start 45.3136 -271.184624)
		(end 45.637958 -270.860266)
		(width 0.14478)
		(layer "In11.Cu")
		(net "M_F_CPU1_SB_CB<4>")
	)
	(segment
		(start 63.16218 -268.475206)
		(end 63.366904 -268.475206)
		(width 0.14478)
		(layer "In11.Cu")
		(net "M_F_CPU1_SB_CB<4>")
	)
	(segment
		(start 37.56406 -271.184624)
		(end 37.795962 -271.184624)
		(width 0.14478)
		(layer "In11.Cu")
		(net "M_F_CPU1_SB_CB<4>")
	)
	(segment
		(start 55.640732 -270.860266)
		(end 55.94477 -271.164304)
		(width 0.14478)
		(layer "In11.Cu")
		(net "M_F_CPU1_SB_CB<4>")
	)
	(segment
		(start 27.612086 -271.169384)
		(end 27.859228 -271.169384)
		(width 0.14478)
		(layer "In11.Cu")
		(net "M_F_CPU1_SB_CB<4>")
	)
	(segment
		(start 48.997616 -270.860266)
		(end 49.237138 -270.860266)
		(width 0.14478)
		(layer "In11.Cu")
		(net "M_F_CPU1_SB_CB<4>")
	)
	(segment
		(start 23.090886 -272.09623)
		(end 23.321518 -272.09623)
		(width 0.14478)
		(layer "In11.Cu")
		(net "M_F_CPU1_SB_CB<4>")
	)
	(segment
		(start 38.352222 -270.860266)
		(end 38.67658 -271.184624)
		(width 0.14478)
		(layer "In11.Cu")
		(net "M_F_CPU1_SB_CB<4>")
	)
	(segment
		(start 33.375092 -271.174464)
		(end 33.617154 -271.174464)
		(width 0.14478)
		(layer "In11.Cu")
		(net "M_F_CPU1_SB_CB<4>")
	)
	(segment
		(start 63.098172 -268.411198)
		(end 63.16218 -268.475206)
		(width 0.14478)
		(layer "In11.Cu")
		(net "M_F_CPU1_SB_CB<4>")
	)
	(segment
		(start 77.481176 -268.523974)
		(end 78.447138 -269.489936)
		(width 0.0889)
		(layer "In11.Cu")
		(net "M_F_CPU1_SB_CB<4>")
	)
	(segment
		(start 61.537596 -269.971774)
		(end 61.601604 -270.035782)
		(width 0.14478)
		(layer "In11.Cu")
		(net "M_F_CPU1_SB_CB<4>")
	)
	(segment
		(start 39.23284 -270.860266)
		(end 40.622728 -270.860266)
		(width 0.14478)
		(layer "In11.Cu")
		(net "M_F_CPU1_SB_CB<4>")
	)
	(segment
		(start 31.618174 -270.860266)
		(end 33.060894 -270.860266)
		(width 0.14478)
		(layer "In11.Cu")
		(net "M_F_CPU1_SB_CB<4>")
	)
	(segment
		(start 52.60721 -271.164304)
		(end 52.859432 -271.164304)
		(width 0.14478)
		(layer "In11.Cu")
		(net "M_F_CPU1_SB_CB<4>")
	)
	(segment
		(start 54.83225 -271.164304)
		(end 55.084472 -271.164304)
		(width 0.14478)
		(layer "In11.Cu")
		(net "M_F_CPU1_SB_CB<4>")
	)
	(segment
		(start 43.728386 -270.860266)
		(end 44.75734 -270.860266)
		(width 0.14478)
		(layer "In11.Cu")
		(net "M_F_CPU1_SB_CB<4>")
	)
	(segment
		(start 42.615866 -270.860266)
		(end 42.847768 -270.860266)
		(width 0.14478)
		(layer "In11.Cu")
		(net "M_F_CPU1_SB_CB<4>")
	)
	(segment
		(start 57.865772 -270.860266)
		(end 58.16981 -271.164304)
		(width 0.14478)
		(layer "In11.Cu")
		(net "M_F_CPU1_SB_CB<4>")
	)
	(segment
		(start 61.601604 -270.035782)
		(end 61.806328 -270.035782)
		(width 0.14478)
		(layer "In11.Cu")
		(net "M_F_CPU1_SB_CB<4>")
	)
	(segment
		(start 77.095096 -267.596874)
		(end 77.481176 -267.982954)
		(width 0.0889)
		(layer "In11.Cu")
		(net "M_F_CPU1_SB_CB<4>")
	)
	(segment
		(start 37.239702 -270.860266)
		(end 37.56406 -271.184624)
		(width 0.14478)
		(layer "In11.Cu")
		(net "M_F_CPU1_SB_CB<4>")
	)
	(segment
		(start 61.332872 -269.971774)
		(end 61.537596 -269.971774)
		(width 0.14478)
		(layer "In11.Cu")
		(net "M_F_CPU1_SB_CB<4>")
	)
	(segment
		(start 33.617154 -271.174464)
		(end 33.931352 -270.860266)
		(width 0.14478)
		(layer "In11.Cu")
		(net "M_F_CPU1_SB_CB<4>")
	)
	(segment
		(start 55.38851 -270.860266)
		(end 55.640732 -270.860266)
		(width 0.14478)
		(layer "In11.Cu")
		(net "M_F_CPU1_SB_CB<4>")
	)
	(segment
		(start 53.16347 -270.860266)
		(end 53.415692 -270.860266)
		(width 0.14478)
		(layer "In11.Cu")
		(net "M_F_CPU1_SB_CB<4>")
	)
	(segment
		(start 44.75734 -270.860266)
		(end 45.081698 -271.184624)
		(width 0.14478)
		(layer "In11.Cu")
		(net "M_F_CPU1_SB_CB<4>")
	)
	(segment
		(start 54.528212 -270.860266)
		(end 54.83225 -271.164304)
		(width 0.14478)
		(layer "In11.Cu")
		(net "M_F_CPU1_SB_CB<4>")
	)
	(segment
		(start 35.600132 -271.174464)
		(end 35.842194 -271.174464)
		(width 0.14478)
		(layer "In11.Cu")
		(net "M_F_CPU1_SB_CB<4>")
	)
	(segment
		(start 30.201616 -271.164304)
		(end 30.505654 -270.860266)
		(width 0.14478)
		(layer "In11.Cu")
		(net "M_F_CPU1_SB_CB<4>")
	)
	(segment
		(start 50.666396 -271.177004)
		(end 50.905918 -271.177004)
		(width 0.14478)
		(layer "In11.Cu")
		(net "M_F_CPU1_SB_CB<4>")
	)
	(segment
		(start 22.928072 -271.933416)
		(end 23.090886 -272.09623)
		(width 0.14478)
		(layer "In11.Cu")
		(net "M_F_CPU1_SB_CB<4>")
	)
	(segment
		(start 22.928072 -271.471644)
		(end 22.928072 -271.933416)
		(width 0.14478)
		(layer "In11.Cu")
		(net "M_F_CPU1_SB_CB<4>")
	)
	(segment
		(start 43.172126 -271.184624)
		(end 43.404028 -271.184624)
		(width 0.14478)
		(layer "In11.Cu")
		(net "M_F_CPU1_SB_CB<4>")
	)
	(segment
		(start 61.991748 -269.645638)
		(end 61.92774 -269.58163)
		(width 0.14478)
		(layer "In11.Cu")
		(net "M_F_CPU1_SB_CB<4>")
	)
	(segment
		(start 48.680878 -271.177004)
		(end 48.997616 -270.860266)
		(width 0.14478)
		(layer "In11.Cu")
		(net "M_F_CPU1_SB_CB<4>")
	)
	(segment
		(start 58.422032 -271.164304)
		(end 58.72607 -270.860266)
		(width 0.14478)
		(layer "In11.Cu")
		(net "M_F_CPU1_SB_CB<4>")
	)
	(segment
		(start 55.084472 -271.164304)
		(end 55.38851 -270.860266)
		(width 0.14478)
		(layer "In11.Cu")
		(net "M_F_CPU1_SB_CB<4>")
	)
	(segment
		(start 60.821316 -270.81607)
		(end 61.02604 -270.81607)
		(width 0.14478)
		(layer "In11.Cu")
		(net "M_F_CPU1_SB_CB<4>")
	)
	(segment
		(start 63.707772 -267.596874)
		(end 75.969876 -267.596874)
		(width 0.14478)
		(layer "In11.Cu")
		(net "M_F_CPU1_SB_CB<4>")
	)
	(segment
		(start 56.50103 -270.860266)
		(end 56.753252 -270.860266)
		(width 0.14478)
		(layer "In11.Cu")
		(net "M_F_CPU1_SB_CB<4>")
	)
	(segment
		(start 24.040592 -271.471644)
		(end 24.040592 -271.933416)
		(width 0.14478)
		(layer "In11.Cu")
		(net "M_F_CPU1_SB_CB<4>")
	)
	(segment
		(start 43.404028 -271.184624)
		(end 43.728386 -270.860266)
		(width 0.14478)
		(layer "In11.Cu")
		(net "M_F_CPU1_SB_CB<4>")
	)
	(segment
		(start 62.772036 -269.070074)
		(end 62.772036 -268.86535)
		(width 0.14478)
		(layer "In11.Cu")
		(net "M_F_CPU1_SB_CB<4>")
	)
	(segment
		(start 29.645356 -270.860266)
		(end 29.949394 -271.164304)
		(width 0.14478)
		(layer "In11.Cu")
		(net "M_F_CPU1_SB_CB<4>")
	)
	(segment
		(start 53.971952 -271.164304)
		(end 54.27599 -270.860266)
		(width 0.14478)
		(layer "In11.Cu")
		(net "M_F_CPU1_SB_CB<4>")
	)
	(segment
		(start 61.806328 -270.035782)
		(end 61.991748 -269.850362)
		(width 0.14478)
		(layer "In11.Cu")
		(net "M_F_CPU1_SB_CB<4>")
	)
	(segment
		(start 46.194218 -271.184624)
		(end 46.42612 -271.184624)
		(width 0.14478)
		(layer "In11.Cu")
		(net "M_F_CPU1_SB_CB<4>")
	)
	(segment
		(start 40.622728 -270.860266)
		(end 40.947086 -271.184624)
		(width 0.14478)
		(layer "In11.Cu")
		(net "M_F_CPU1_SB_CB<4>")
	)
	(segment
		(start 61.147452 -270.157194)
		(end 61.332872 -269.971774)
		(width 0.14478)
		(layer "In11.Cu")
		(net "M_F_CPU1_SB_CB<4>")
	)
	(segment
		(start 62.11316 -269.191486)
		(end 62.317884 -269.191486)
		(width 0.14478)
		(layer "In11.Cu")
		(net "M_F_CPU1_SB_CB<4>")
	)
	(arc
		(start 79.478124 -269.556484)
		(mid 79.659054 -269.598962)
		(end 79.838042 -269.548864)
		(width 0.0889)
		(layer "In11.Cu")
		(net "M_F_CPU1_SB_CB<4>")
	)
	(arc
		(start 81.71815 -269.548864)
		(mid 82.001106 -269.472687)
		(end 82.284062 -269.548864)
		(width 0.0889)
		(layer "In11.Cu")
		(net "M_F_CPU1_SB_CB<4>")
	)
	(arc
		(start 78.898496 -269.548864)
		(mid 79.169027 -269.472458)
		(end 79.442818 -269.536164)
		(width 0.0889)
		(layer "In11.Cu")
		(net "M_F_CPU1_SB_CB<4>")
	)
	(arc
		(start 79.838042 -269.548864)
		(mid 80.120998 -269.472687)
		(end 80.403954 -269.548864)
		(width 0.0889)
		(layer "In11.Cu")
		(net "M_F_CPU1_SB_CB<4>")
	)
	(arc
		(start 78.447392 -269.489936)
		(mid 78.484088 -269.521789)
		(end 78.524608 -269.54861)
		(width 0.0889)
		(layer "In11.Cu")
		(net "M_F_CPU1_SB_CB<4>")
	)
	(arc
		(start 80.403954 -269.548864)
		(mid 80.586205 -269.599214)
		(end 80.769714 -269.55369)
		(width 0.0889)
		(layer "In11.Cu")
		(net "M_F_CPU1_SB_CB<4>")
	)
	(arc
		(start 78.544674 -269.56004)
		(mid 78.723006 -269.599137)
		(end 78.898496 -269.548864)
		(width 0.0889)
		(layer "In11.Cu")
		(net "M_F_CPU1_SB_CB<4>")
	)
	(arc
		(start 80.778096 -269.548864)
		(mid 81.061052 -269.472687)
		(end 81.344008 -269.548864)
		(width 0.0889)
		(layer "In11.Cu")
		(net "M_F_CPU1_SB_CB<4>")
	)
	(arc
		(start 83.223862 -269.548864)
		(mid 83.406113 -269.599214)
		(end 83.589622 -269.55369)
		(width 0.0889)
		(layer "In11.Cu")
		(net "M_F_CPU1_SB_CB<4>")
	)
	(arc
		(start 82.284062 -269.548864)
		(mid 82.471006 -269.599119)
		(end 82.65795 -269.548864)
		(width 0.0889)
		(layer "In11.Cu")
		(net "M_F_CPU1_SB_CB<4>")
	)
	(arc
		(start 83.598004 -269.548864)
		(mid 83.88096 -269.472687)
		(end 84.163916 -269.548864)
		(width 0.0889)
		(layer "In11.Cu")
		(net "M_F_CPU1_SB_CB<4>")
	)
	(arc
		(start 82.65795 -269.548864)
		(mid 82.940906 -269.472687)
		(end 83.223862 -269.548864)
		(width 0.0889)
		(layer "In11.Cu")
		(net "M_F_CPU1_SB_CB<4>")
	)
	(arc
		(start 81.35239 -269.55369)
		(mid 81.535898 -269.599184)
		(end 81.71815 -269.548864)
		(width 0.0889)
		(layer "In11.Cu")
		(net "M_F_CPU1_SB_CB<4>")
	)
	(arc
		(start 84.163916 -269.548864)
		(mid 84.320354 -269.597835)
		(end 84.482686 -269.575026)
		(width 0.0889)
		(layer "In11.Cu")
		(net "M_F_CPU1_SB_CB<4>")
	)
	(segment
		(start 86.69782 -273.820382)
		(end 86.230968 -274.08632)
		(width 0.10668)
		(layer "F.Cu")
		(net "M_F_CPU1_SB_CB<3>")
	)
	(segment
		(start 66.922904 -272.664174)
		(end 76.221336 -272.664174)
		(width 0.14478)
		(layer "In11.Cu")
		(net "M_F_CPU1_SB_CB<3>")
	)
	(segment
		(start 42.103802 -281.060398)
		(end 43.373548 -280.212038)
		(width 0.14478)
		(layer "In11.Cu")
		(net "M_F_CPU1_SB_CB<3>")
	)
	(segment
		(start 54.01945 -281.060398)
		(end 56.68899 -281.060398)
		(width 0.14478)
		(layer "In11.Cu")
		(net "M_F_CPU1_SB_CB<3>")
	)
	(segment
		(start 85.981032 -273.79549)
		(end 86.077044 -273.82089)
		(width 0.0889)
		(layer "In11.Cu")
		(net "M_F_CPU1_SB_CB<3>")
	)
	(segment
		(start 17.608042 -280.635202)
		(end 18.033238 -281.060398)
		(width 0.14478)
		(layer "In11.Cu")
		(net "M_F_CPU1_SB_CB<3>")
	)
	(segment
		(start 83.589622 -273.758914)
		(end 83.598004 -273.76374)
		(width 0.0889)
		(layer "In11.Cu")
		(net "M_F_CPU1_SB_CB<3>")
	)
	(segment
		(start 86.077044 -273.82089)
		(end 86.230968 -274.08632)
		(width 0.0889)
		(layer "In11.Cu")
		(net "M_F_CPU1_SB_CB<3>")
	)
	(segment
		(start 49.325022 -281.060398)
		(end 50.597308 -280.21026)
		(width 0.14478)
		(layer "In11.Cu")
		(net "M_F_CPU1_SB_CB<3>")
	)
	(segment
		(start 56.68899 -281.060398)
		(end 57.961022 -280.21026)
		(width 0.14478)
		(layer "In11.Cu")
		(net "M_F_CPU1_SB_CB<3>")
	)
	(segment
		(start 45.052488 -280.212038)
		(end 46.32198 -281.060398)
		(width 0.14478)
		(layer "In11.Cu")
		(net "M_F_CPU1_SB_CB<3>")
	)
	(segment
		(start 46.32198 -281.060398)
		(end 49.325022 -281.060398)
		(width 0.14478)
		(layer "In11.Cu")
		(net "M_F_CPU1_SB_CB<3>")
	)
	(segment
		(start 81.344008 -273.76374)
		(end 81.35239 -273.758914)
		(width 0.0889)
		(layer "In11.Cu")
		(net "M_F_CPU1_SB_CB<3>")
	)
	(segment
		(start 19.804634 -280.915618)
		(end 19.804634 -280.789126)
		(width 0.14478)
		(layer "In11.Cu")
		(net "M_F_CPU1_SB_CB<3>")
	)
	(segment
		(start 76.377546 -272.507964)
		(end 77.222858 -272.507964)
		(width 0.0889)
		(layer "In11.Cu")
		(net "M_F_CPU1_SB_CB<3>")
	)
	(segment
		(start 76.221336 -272.664174)
		(end 76.377546 -272.507964)
		(width 0.0889)
		(layer "In11.Cu")
		(net "M_F_CPU1_SB_CB<3>")
	)
	(segment
		(start 18.033238 -281.060398)
		(end 19.659854 -281.060398)
		(width 0.14478)
		(layer "In11.Cu")
		(net "M_F_CPU1_SB_CB<3>")
	)
	(segment
		(start 35.273742 -280.21026)
		(end 37.427154 -280.21026)
		(width 0.14478)
		(layer "In11.Cu")
		(net "M_F_CPU1_SB_CB<3>")
	)
	(segment
		(start 31.80969 -281.060398)
		(end 34.001202 -281.060398)
		(width 0.14478)
		(layer "In11.Cu")
		(net "M_F_CPU1_SB_CB<3>")
	)
	(segment
		(start 65.21323 -274.373848)
		(end 66.922904 -272.664174)
		(width 0.14478)
		(layer "In11.Cu")
		(net "M_F_CPU1_SB_CB<3>")
	)
	(segment
		(start 64.526668 -274.373848)
		(end 65.21323 -274.373848)
		(width 0.14478)
		(layer "In11.Cu")
		(net "M_F_CPU1_SB_CB<3>")
	)
	(segment
		(start 77.222858 -272.507964)
		(end 78.427834 -273.71294)
		(width 0.0889)
		(layer "In11.Cu")
		(net "M_F_CPU1_SB_CB<3>")
	)
	(segment
		(start 57.961022 -280.21026)
		(end 59.376818 -280.21026)
		(width 0.14478)
		(layer "In11.Cu")
		(net "M_F_CPU1_SB_CB<3>")
	)
	(segment
		(start 78.427834 -273.71294)
		(end 79.650336 -273.71294)
		(width 0.0889)
		(layer "In11.Cu")
		(net "M_F_CPU1_SB_CB<3>")
	)
	(segment
		(start 59.376818 -280.21026)
		(end 60.37199 -279.215088)
		(width 0.14478)
		(layer "In11.Cu")
		(net "M_F_CPU1_SB_CB<3>")
	)
	(segment
		(start 26.804112 -281.060398)
		(end 28.076652 -280.21026)
		(width 0.14478)
		(layer "In11.Cu")
		(net "M_F_CPU1_SB_CB<3>")
	)
	(segment
		(start 38.699186 -281.060398)
		(end 42.103802 -281.060398)
		(width 0.14478)
		(layer "In11.Cu")
		(net "M_F_CPU1_SB_CB<3>")
	)
	(segment
		(start 19.659854 -281.060398)
		(end 19.804634 -280.915618)
		(width 0.14478)
		(layer "In11.Cu")
		(net "M_F_CPU1_SB_CB<3>")
	)
	(segment
		(start 37.427154 -280.21026)
		(end 38.699186 -281.060398)
		(width 0.14478)
		(layer "In11.Cu")
		(net "M_F_CPU1_SB_CB<3>")
	)
	(segment
		(start 60.37199 -279.215088)
		(end 60.37199 -278.528526)
		(width 0.14478)
		(layer "In11.Cu")
		(net "M_F_CPU1_SB_CB<3>")
	)
	(segment
		(start 34.001202 -281.060398)
		(end 35.273742 -280.21026)
		(width 0.14478)
		(layer "In11.Cu")
		(net "M_F_CPU1_SB_CB<3>")
	)
	(segment
		(start 20.211288 -280.644346)
		(end 20.356068 -280.789126)
		(width 0.14478)
		(layer "In11.Cu")
		(net "M_F_CPU1_SB_CB<3>")
	)
	(segment
		(start 85.10397 -273.76374)
		(end 85.112352 -273.758914)
		(width 0.0889)
		(layer "In11.Cu")
		(net "M_F_CPU1_SB_CB<3>")
	)
	(segment
		(start 20.356068 -280.789126)
		(end 20.356068 -280.915618)
		(width 0.14478)
		(layer "In11.Cu")
		(net "M_F_CPU1_SB_CB<3>")
	)
	(segment
		(start 50.597308 -280.21026)
		(end 52.747164 -280.21026)
		(width 0.14478)
		(layer "In11.Cu")
		(net "M_F_CPU1_SB_CB<3>")
	)
	(segment
		(start 43.373548 -280.212038)
		(end 45.052488 -280.212038)
		(width 0.14478)
		(layer "In11.Cu")
		(net "M_F_CPU1_SB_CB<3>")
	)
	(segment
		(start 28.076652 -280.21026)
		(end 30.53715 -280.21026)
		(width 0.14478)
		(layer "In11.Cu")
		(net "M_F_CPU1_SB_CB<3>")
	)
	(segment
		(start 80.39354 -273.769836)
		(end 80.403954 -273.76374)
		(width 0.0889)
		(layer "In11.Cu")
		(net "M_F_CPU1_SB_CB<3>")
	)
	(segment
		(start 60.37199 -278.528526)
		(end 64.526668 -274.373848)
		(width 0.14478)
		(layer "In11.Cu")
		(net "M_F_CPU1_SB_CB<3>")
	)
	(segment
		(start 19.804634 -280.789126)
		(end 19.949414 -280.644346)
		(width 0.14478)
		(layer "In11.Cu")
		(net "M_F_CPU1_SB_CB<3>")
	)
	(segment
		(start 80.769714 -273.758914)
		(end 80.778096 -273.76374)
		(width 0.0889)
		(layer "In11.Cu")
		(net "M_F_CPU1_SB_CB<3>")
	)
	(segment
		(start 19.949414 -280.644346)
		(end 20.211288 -280.644346)
		(width 0.14478)
		(layer "In11.Cu")
		(net "M_F_CPU1_SB_CB<3>")
	)
	(segment
		(start 30.53715 -280.21026)
		(end 31.80969 -281.060398)
		(width 0.14478)
		(layer "In11.Cu")
		(net "M_F_CPU1_SB_CB<3>")
	)
	(segment
		(start 20.500848 -281.060398)
		(end 26.804112 -281.060398)
		(width 0.14478)
		(layer "In11.Cu")
		(net "M_F_CPU1_SB_CB<3>")
	)
	(segment
		(start 84.529676 -273.758914)
		(end 84.538058 -273.76374)
		(width 0.0889)
		(layer "In11.Cu")
		(net "M_F_CPU1_SB_CB<3>")
	)
	(segment
		(start 20.356068 -280.915618)
		(end 20.500848 -281.060398)
		(width 0.14478)
		(layer "In11.Cu")
		(net "M_F_CPU1_SB_CB<3>")
	)
	(segment
		(start 52.747164 -280.21026)
		(end 54.01945 -281.060398)
		(width 0.14478)
		(layer "In11.Cu")
		(net "M_F_CPU1_SB_CB<3>")
	)
	(arc
		(start 80.403954 -273.76374)
		(mid 80.586205 -273.71339)
		(end 80.769714 -273.758914)
		(width 0.0889)
		(layer "In11.Cu")
		(net "M_F_CPU1_SB_CB<3>")
	)
	(arc
		(start 79.650336 -273.71294)
		(mid 79.747425 -273.72593)
		(end 79.837788 -273.76374)
		(width 0.0889)
		(layer "In11.Cu")
		(net "M_F_CPU1_SB_CB<3>")
	)
	(arc
		(start 85.478112 -273.76374)
		(mid 85.725825 -273.83896)
		(end 85.981032 -273.79549)
		(width 0.0889)
		(layer "In11.Cu")
		(net "M_F_CPU1_SB_CB<3>")
	)
	(arc
		(start 79.837788 -273.76374)
		(mid 80.114855 -273.840011)
		(end 80.39354 -273.769836)
		(width 0.0889)
		(layer "In11.Cu")
		(net "M_F_CPU1_SB_CB<3>")
	)
	(arc
		(start 81.71815 -273.76374)
		(mid 82.001106 -273.839917)
		(end 82.284062 -273.76374)
		(width 0.0889)
		(layer "In11.Cu")
		(net "M_F_CPU1_SB_CB<3>")
	)
	(arc
		(start 84.163916 -273.76374)
		(mid 84.346167 -273.71339)
		(end 84.529676 -273.758914)
		(width 0.0889)
		(layer "In11.Cu")
		(net "M_F_CPU1_SB_CB<3>")
	)
	(arc
		(start 84.538058 -273.76374)
		(mid 84.821014 -273.839917)
		(end 85.10397 -273.76374)
		(width 0.0889)
		(layer "In11.Cu")
		(net "M_F_CPU1_SB_CB<3>")
	)
	(arc
		(start 81.35239 -273.758914)
		(mid 81.535898 -273.71342)
		(end 81.71815 -273.76374)
		(width 0.0889)
		(layer "In11.Cu")
		(net "M_F_CPU1_SB_CB<3>")
	)
	(arc
		(start 83.598004 -273.76374)
		(mid 83.88096 -273.839917)
		(end 84.163916 -273.76374)
		(width 0.0889)
		(layer "In11.Cu")
		(net "M_F_CPU1_SB_CB<3>")
	)
	(arc
		(start 80.778096 -273.76374)
		(mid 81.061052 -273.839917)
		(end 81.344008 -273.76374)
		(width 0.0889)
		(layer "In11.Cu")
		(net "M_F_CPU1_SB_CB<3>")
	)
	(arc
		(start 85.112352 -273.758914)
		(mid 85.29586 -273.71342)
		(end 85.478112 -273.76374)
		(width 0.0889)
		(layer "In11.Cu")
		(net "M_F_CPU1_SB_CB<3>")
	)
	(arc
		(start 82.65795 -273.76374)
		(mid 82.940906 -273.839917)
		(end 83.223862 -273.76374)
		(width 0.0889)
		(layer "In11.Cu")
		(net "M_F_CPU1_SB_CB<3>")
	)
	(arc
		(start 82.284062 -273.76374)
		(mid 82.471006 -273.713485)
		(end 82.65795 -273.76374)
		(width 0.0889)
		(layer "In11.Cu")
		(net "M_F_CPU1_SB_CB<3>")
	)
	(arc
		(start 83.223862 -273.76374)
		(mid 83.406113 -273.71339)
		(end 83.589622 -273.758914)
		(width 0.0889)
		(layer "In11.Cu")
		(net "M_F_CPU1_SB_CB<3>")
	)
	(segment
		(start 85.287866 -273.010376)
		(end 84.821014 -273.276314)
		(width 0.10668)
		(layer "F.Cu")
		(net "M_F_CPU1_SB_CB<2>")
	)
	(segment
		(start 84.66709 -273.010884)
		(end 84.821014 -273.276314)
		(width 0.0889)
		(layer "In11.Cu")
		(net "M_F_CPU1_SB_CB<2>")
	)
	(segment
		(start 19.974052 -279.215596)
		(end 19.974052 -278.912066)
		(width 0.14478)
		(layer "In11.Cu")
		(net "M_F_CPU1_SB_CB<2>")
	)
	(segment
		(start 82.179668 -272.948908)
		(end 82.18805 -272.953734)
		(width 0.0889)
		(layer "In11.Cu")
		(net "M_F_CPU1_SB_CB<2>")
	)
	(segment
		(start 82.753962 -272.953734)
		(end 82.762344 -272.948908)
		(width 0.0889)
		(layer "In11.Cu")
		(net "M_F_CPU1_SB_CB<2>")
	)
	(segment
		(start 58.190384 -278.510238)
		(end 59.11342 -278.510238)
		(width 0.14478)
		(layer "In11.Cu")
		(net "M_F_CPU1_SB_CB<2>")
	)
	(segment
		(start 84.571078 -272.985484)
		(end 84.66709 -273.010884)
		(width 0.0889)
		(layer "In11.Cu")
		(net "M_F_CPU1_SB_CB<2>")
	)
	(segment
		(start 46.059598 -279.360376)
		(end 49.956974 -279.360376)
		(width 0.14478)
		(layer "In11.Cu")
		(net "M_F_CPU1_SB_CB<2>")
	)
	(segment
		(start 31.251398 -279.360376)
		(end 34.564574 -279.360376)
		(width 0.14478)
		(layer "In11.Cu")
		(net "M_F_CPU1_SB_CB<2>")
	)
	(segment
		(start 18.726404 -279.360376)
		(end 18.871184 -279.215596)
		(width 0.14478)
		(layer "In11.Cu")
		(net "M_F_CPU1_SB_CB<2>")
	)
	(segment
		(start 79.357474 -272.946876)
		(end 79.369158 -272.953734)
		(width 0.0889)
		(layer "In11.Cu")
		(net "M_F_CPU1_SB_CB<2>")
	)
	(segment
		(start 38.470586 -279.360376)
		(end 42.667174 -279.360376)
		(width 0.14478)
		(layer "In11.Cu")
		(net "M_F_CPU1_SB_CB<2>")
	)
	(segment
		(start 19.422618 -279.215596)
		(end 19.567398 -279.360376)
		(width 0.14478)
		(layer "In11.Cu")
		(net "M_F_CPU1_SB_CB<2>")
	)
	(segment
		(start 49.956974 -279.360376)
		(end 50.807112 -278.510238)
		(width 0.14478)
		(layer "In11.Cu")
		(net "M_F_CPU1_SB_CB<2>")
	)
	(segment
		(start 50.807112 -278.510238)
		(end 52.82946 -278.510238)
		(width 0.14478)
		(layer "In11.Cu")
		(net "M_F_CPU1_SB_CB<2>")
	)
	(segment
		(start 53.679598 -279.360376)
		(end 57.340246 -279.360376)
		(width 0.14478)
		(layer "In11.Cu")
		(net "M_F_CPU1_SB_CB<2>")
	)
	(segment
		(start 27.972512 -278.510238)
		(end 30.40126 -278.510238)
		(width 0.14478)
		(layer "In11.Cu")
		(net "M_F_CPU1_SB_CB<2>")
	)
	(segment
		(start 18.871184 -278.912066)
		(end 19.015964 -278.767286)
		(width 0.14478)
		(layer "In11.Cu")
		(net "M_F_CPU1_SB_CB<2>")
	)
	(segment
		(start 34.564574 -279.360376)
		(end 35.414712 -278.510238)
		(width 0.14478)
		(layer "In11.Cu")
		(net "M_F_CPU1_SB_CB<2>")
	)
	(segment
		(start 35.414712 -278.510238)
		(end 37.620448 -278.510238)
		(width 0.14478)
		(layer "In11.Cu")
		(net "M_F_CPU1_SB_CB<2>")
	)
	(segment
		(start 43.517312 -278.510238)
		(end 45.20946 -278.510238)
		(width 0.14478)
		(layer "In11.Cu")
		(net "M_F_CPU1_SB_CB<2>")
	)
	(segment
		(start 17.608042 -278.935434)
		(end 18.032984 -279.360376)
		(width 0.14478)
		(layer "In11.Cu")
		(net "M_F_CPU1_SB_CB<2>")
	)
	(segment
		(start 30.40126 -278.510238)
		(end 31.251398 -279.360376)
		(width 0.14478)
		(layer "In11.Cu")
		(net "M_F_CPU1_SB_CB<2>")
	)
	(segment
		(start 19.422618 -278.912066)
		(end 19.422618 -279.215596)
		(width 0.14478)
		(layer "In11.Cu")
		(net "M_F_CPU1_SB_CB<2>")
	)
	(segment
		(start 65.868804 -271.754854)
		(end 75.960986 -271.754854)
		(width 0.14478)
		(layer "In11.Cu")
		(net "M_F_CPU1_SB_CB<2>")
	)
	(segment
		(start 79.92237 -272.960846)
		(end 79.934308 -272.953988)
		(width 0.0889)
		(layer "In11.Cu")
		(net "M_F_CPU1_SB_CB<2>")
	)
	(segment
		(start 19.015964 -278.767286)
		(end 19.277838 -278.767286)
		(width 0.14478)
		(layer "In11.Cu")
		(net "M_F_CPU1_SB_CB<2>")
	)
	(segment
		(start 76.81214 -271.944846)
		(end 77.39253 -271.944846)
		(width 0.0889)
		(layer "In11.Cu")
		(net "M_F_CPU1_SB_CB<2>")
	)
	(segment
		(start 37.620448 -278.510238)
		(end 38.470586 -279.360376)
		(width 0.14478)
		(layer "In11.Cu")
		(net "M_F_CPU1_SB_CB<2>")
	)
	(segment
		(start 19.829272 -279.360376)
		(end 19.974052 -279.215596)
		(width 0.14478)
		(layer "In11.Cu")
		(net "M_F_CPU1_SB_CB<2>")
	)
	(segment
		(start 83.694016 -272.953734)
		(end 83.702398 -272.948908)
		(width 0.0889)
		(layer "In11.Cu")
		(net "M_F_CPU1_SB_CB<2>")
	)
	(segment
		(start 45.20946 -278.510238)
		(end 46.059598 -279.360376)
		(width 0.14478)
		(layer "In11.Cu")
		(net "M_F_CPU1_SB_CB<2>")
	)
	(segment
		(start 19.974052 -278.912066)
		(end 20.118832 -278.767286)
		(width 0.14478)
		(layer "In11.Cu")
		(net "M_F_CPU1_SB_CB<2>")
	)
	(segment
		(start 19.277838 -278.767286)
		(end 19.422618 -278.912066)
		(width 0.14478)
		(layer "In11.Cu")
		(net "M_F_CPU1_SB_CB<2>")
	)
	(segment
		(start 79.934308 -272.953988)
		(end 79.950564 -272.94459)
		(width 0.0889)
		(layer "In11.Cu")
		(net "M_F_CPU1_SB_CB<2>")
	)
	(segment
		(start 78.42885 -272.953988)
		(end 78.45044 -272.966434)
		(width 0.0889)
		(layer "In11.Cu")
		(net "M_F_CPU1_SB_CB<2>")
	)
	(segment
		(start 20.118832 -278.767286)
		(end 20.380706 -278.767286)
		(width 0.14478)
		(layer "In11.Cu")
		(net "M_F_CPU1_SB_CB<2>")
	)
	(segment
		(start 52.82946 -278.510238)
		(end 53.679598 -279.360376)
		(width 0.14478)
		(layer "In11.Cu")
		(net "M_F_CPU1_SB_CB<2>")
	)
	(segment
		(start 75.960986 -271.754854)
		(end 76.622148 -271.754854)
		(width 0.0889)
		(layer "In11.Cu")
		(net "M_F_CPU1_SB_CB<2>")
	)
	(segment
		(start 20.380706 -278.767286)
		(end 20.525486 -278.912066)
		(width 0.14478)
		(layer "In11.Cu")
		(net "M_F_CPU1_SB_CB<2>")
	)
	(segment
		(start 77.39253 -271.944846)
		(end 78.312518 -272.864834)
		(width 0.0889)
		(layer "In11.Cu")
		(net "M_F_CPU1_SB_CB<2>")
	)
	(segment
		(start 20.525486 -278.912066)
		(end 20.525486 -279.215596)
		(width 0.14478)
		(layer "In11.Cu")
		(net "M_F_CPU1_SB_CB<2>")
	)
	(segment
		(start 18.032984 -279.360376)
		(end 18.726404 -279.360376)
		(width 0.14478)
		(layer "In11.Cu")
		(net "M_F_CPU1_SB_CB<2>")
	)
	(segment
		(start 20.670266 -279.360376)
		(end 27.122374 -279.360376)
		(width 0.14478)
		(layer "In11.Cu")
		(net "M_F_CPU1_SB_CB<2>")
	)
	(segment
		(start 27.122374 -279.360376)
		(end 27.972512 -278.510238)
		(width 0.14478)
		(layer "In11.Cu")
		(net "M_F_CPU1_SB_CB<2>")
	)
	(segment
		(start 42.667174 -279.360376)
		(end 43.517312 -278.510238)
		(width 0.14478)
		(layer "In11.Cu")
		(net "M_F_CPU1_SB_CB<2>")
	)
	(segment
		(start 76.622148 -271.754854)
		(end 76.81214 -271.944846)
		(width 0.0889)
		(layer "In11.Cu")
		(net "M_F_CPU1_SB_CB<2>")
	)
	(segment
		(start 19.567398 -279.360376)
		(end 19.829272 -279.360376)
		(width 0.14478)
		(layer "In11.Cu")
		(net "M_F_CPU1_SB_CB<2>")
	)
	(segment
		(start 57.340246 -279.360376)
		(end 58.190384 -278.510238)
		(width 0.14478)
		(layer "In11.Cu")
		(net "M_F_CPU1_SB_CB<2>")
	)
	(segment
		(start 20.525486 -279.215596)
		(end 20.670266 -279.360376)
		(width 0.14478)
		(layer "In11.Cu")
		(net "M_F_CPU1_SB_CB<2>")
	)
	(segment
		(start 18.871184 -279.215596)
		(end 18.871184 -278.912066)
		(width 0.14478)
		(layer "In11.Cu")
		(net "M_F_CPU1_SB_CB<2>")
	)
	(segment
		(start 59.11342 -278.510238)
		(end 65.868804 -271.754854)
		(width 0.14478)
		(layer "In11.Cu")
		(net "M_F_CPU1_SB_CB<2>")
	)
	(arc
		(start 83.128104 -272.953734)
		(mid 83.41106 -273.029911)
		(end 83.694016 -272.953734)
		(width 0.0889)
		(layer "In11.Cu")
		(net "M_F_CPU1_SB_CB<2>")
	)
	(arc
		(start 78.45044 -272.966434)
		(mid 78.72423 -273.030105)
		(end 78.994762 -272.953734)
		(width 0.0889)
		(layer "In11.Cu")
		(net "M_F_CPU1_SB_CB<2>")
	)
	(arc
		(start 80.308196 -272.953734)
		(mid 80.591152 -273.029911)
		(end 80.874108 -272.953734)
		(width 0.0889)
		(layer "In11.Cu")
		(net "M_F_CPU1_SB_CB<2>")
	)
	(arc
		(start 79.950564 -272.94459)
		(mid 80.130546 -272.90349)
		(end 80.308196 -272.953734)
		(width 0.0889)
		(layer "In11.Cu")
		(net "M_F_CPU1_SB_CB<2>")
	)
	(arc
		(start 84.068158 -272.953734)
		(mid 84.315871 -273.028954)
		(end 84.571078 -272.985484)
		(width 0.0889)
		(layer "In11.Cu")
		(net "M_F_CPU1_SB_CB<2>")
	)
	(arc
		(start 83.702398 -272.948908)
		(mid 83.885906 -272.903414)
		(end 84.068158 -272.953734)
		(width 0.0889)
		(layer "In11.Cu")
		(net "M_F_CPU1_SB_CB<2>")
	)
	(arc
		(start 82.762344 -272.948908)
		(mid 82.945852 -272.903414)
		(end 83.128104 -272.953734)
		(width 0.0889)
		(layer "In11.Cu")
		(net "M_F_CPU1_SB_CB<2>")
	)
	(arc
		(start 80.874108 -272.953734)
		(mid 81.061052 -272.903479)
		(end 81.247996 -272.953734)
		(width 0.0889)
		(layer "In11.Cu")
		(net "M_F_CPU1_SB_CB<2>")
	)
	(arc
		(start 81.813908 -272.953734)
		(mid 81.996159 -272.903384)
		(end 82.179668 -272.948908)
		(width 0.0889)
		(layer "In11.Cu")
		(net "M_F_CPU1_SB_CB<2>")
	)
	(arc
		(start 78.312518 -272.864834)
		(mid 78.367768 -272.913216)
		(end 78.42885 -272.953988)
		(width 0.0889)
		(layer "In11.Cu")
		(net "M_F_CPU1_SB_CB<2>")
	)
	(arc
		(start 78.994762 -272.953734)
		(mid 79.17522 -272.90329)
		(end 79.357474 -272.946876)
		(width 0.0889)
		(layer "In11.Cu")
		(net "M_F_CPU1_SB_CB<2>")
	)
	(arc
		(start 82.18805 -272.953734)
		(mid 82.471006 -273.029911)
		(end 82.753962 -272.953734)
		(width 0.0889)
		(layer "In11.Cu")
		(net "M_F_CPU1_SB_CB<2>")
	)
	(arc
		(start 81.247996 -272.953734)
		(mid 81.530952 -273.029911)
		(end 81.813908 -272.953734)
		(width 0.0889)
		(layer "In11.Cu")
		(net "M_F_CPU1_SB_CB<2>")
	)
	(arc
		(start 79.369158 -272.953734)
		(mid 79.644836 -273.029864)
		(end 79.92237 -272.960846)
		(width 0.0889)
		(layer "In11.Cu")
		(net "M_F_CPU1_SB_CB<2>")
	)
	(segment
		(start 86.22792 -273.010376)
		(end 85.761068 -273.276314)
		(width 0.10668)
		(layer "F.Cu")
		(net "M_F_CPU1_SB_CB<1>")
	)
	(segment
		(start 65.822322 -272.641822)
		(end 65.822576 -272.437098)
		(width 0.14478)
		(layer "In11.Cu")
		(net "M_F_CPU1_SB_CB<1>")
	)
	(segment
		(start 37.468048 -279.360122)
		(end 38.318186 -280.21026)
		(width 0.14478)
		(layer "In11.Cu")
		(net "M_F_CPU1_SB_CB<1>")
	)
	(segment
		(start 85.89264 -273.625056)
		(end 85.914992 -273.541744)
		(width 0.0889)
		(layer "In11.Cu")
		(net "M_F_CPU1_SB_CB<1>")
	)
	(segment
		(start 52.917344 -279.360122)
		(end 53.767482 -280.21026)
		(width 0.14478)
		(layer "In11.Cu")
		(net "M_F_CPU1_SB_CB<1>")
	)
	(segment
		(start 83.694016 -273.598894)
		(end 83.702398 -273.60372)
		(width 0.0889)
		(layer "In11.Cu")
		(net "M_F_CPU1_SB_CB<1>")
	)
	(segment
		(start 26.382218 -280.36393)
		(end 26.545032 -280.526744)
		(width 0.14478)
		(layer "In11.Cu")
		(net "M_F_CPU1_SB_CB<1>")
	)
	(segment
		(start 65.227708 -273.031966)
		(end 65.432432 -273.031966)
		(width 0.14478)
		(layer "In11.Cu")
		(net "M_F_CPU1_SB_CB<1>")
	)
	(segment
		(start 22.525228 -280.602436)
		(end 22.75586 -280.602436)
		(width 0.14478)
		(layer "In11.Cu")
		(net "M_F_CPU1_SB_CB<1>")
	)
	(segment
		(start 26.545032 -280.526744)
		(end 26.775664 -280.526744)
		(width 0.14478)
		(layer "In11.Cu")
		(net "M_F_CPU1_SB_CB<1>")
	)
	(segment
		(start 49.750218 -280.21026)
		(end 50.600356 -279.360122)
		(width 0.14478)
		(layer "In11.Cu")
		(net "M_F_CPU1_SB_CB<1>")
	)
	(segment
		(start 24.42464 -279.819608)
		(end 24.815292 -280.21026)
		(width 0.14478)
		(layer "In11.Cu")
		(net "M_F_CPU1_SB_CB<1>")
	)
	(segment
		(start 64.96812 -273.924268)
		(end 65.153794 -273.738594)
		(width 0.14478)
		(layer "In11.Cu")
		(net "M_F_CPU1_SB_CB<1>")
	)
	(segment
		(start 65.153794 -273.53387)
		(end 65.042034 -273.42211)
		(width 0.14478)
		(layer "In11.Cu")
		(net "M_F_CPU1_SB_CB<1>")
	)
	(segment
		(start 22.918674 -280.439622)
		(end 22.918674 -279.982422)
		(width 0.14478)
		(layer "In11.Cu")
		(net "M_F_CPU1_SB_CB<1>")
	)
	(segment
		(start 65.822576 -272.437098)
		(end 66.05016 -272.209514)
		(width 0.14478)
		(layer "In11.Cu")
		(net "M_F_CPU1_SB_CB<1>")
	)
	(segment
		(start 26.382218 -279.978612)
		(end 26.382218 -280.36393)
		(width 0.14478)
		(layer "In11.Cu")
		(net "M_F_CPU1_SB_CB<1>")
	)
	(segment
		(start 22.75586 -280.602436)
		(end 22.918674 -280.439622)
		(width 0.14478)
		(layer "In11.Cu")
		(net "M_F_CPU1_SB_CB<1>")
	)
	(segment
		(start 35.301428 -279.360122)
		(end 37.468048 -279.360122)
		(width 0.14478)
		(layer "In11.Cu")
		(net "M_F_CPU1_SB_CB<1>")
	)
	(segment
		(start 59.92241 -278.337264)
		(end 64.44742 -273.812254)
		(width 0.14478)
		(layer "In11.Cu")
		(net "M_F_CPU1_SB_CB<1>")
	)
	(segment
		(start 24.031194 -279.982422)
		(end 24.194008 -279.819608)
		(width 0.14478)
		(layer "In11.Cu")
		(net "M_F_CPU1_SB_CB<1>")
	)
	(segment
		(start 23.86838 -280.602436)
		(end 24.031194 -280.439622)
		(width 0.14478)
		(layer "In11.Cu")
		(net "M_F_CPU1_SB_CB<1>")
	)
	(segment
		(start 78.524862 -273.52244)
		(end 79.65059 -273.52244)
		(width 0.0889)
		(layer "In11.Cu")
		(net "M_F_CPU1_SB_CB<1>")
	)
	(segment
		(start 42.55389 -280.21026)
		(end 43.40225 -279.3619)
		(width 0.14478)
		(layer "In11.Cu")
		(net "M_F_CPU1_SB_CB<1>")
	)
	(segment
		(start 65.432432 -273.031966)
		(end 65.544192 -273.143726)
		(width 0.14478)
		(layer "In11.Cu")
		(net "M_F_CPU1_SB_CB<1>")
	)
	(segment
		(start 45.172122 -279.3619)
		(end 46.020482 -280.21026)
		(width 0.14478)
		(layer "In11.Cu")
		(net "M_F_CPU1_SB_CB<1>")
	)
	(segment
		(start 23.31212 -279.819608)
		(end 23.474934 -279.982422)
		(width 0.14478)
		(layer "In11.Cu")
		(net "M_F_CPU1_SB_CB<1>")
	)
	(segment
		(start 65.934082 -272.958306)
		(end 65.934082 -272.753582)
		(width 0.14478)
		(layer "In11.Cu")
		(net "M_F_CPU1_SB_CB<1>")
	)
	(segment
		(start 64.44742 -273.812254)
		(end 64.652144 -273.812254)
		(width 0.14478)
		(layer "In11.Cu")
		(net "M_F_CPU1_SB_CB<1>")
	)
	(segment
		(start 64.763904 -273.924014)
		(end 64.96812 -273.924268)
		(width 0.14478)
		(layer "In11.Cu")
		(net "M_F_CPU1_SB_CB<1>")
	)
	(segment
		(start 64.652144 -273.812254)
		(end 64.763904 -273.924014)
		(width 0.14478)
		(layer "In11.Cu")
		(net "M_F_CPU1_SB_CB<1>")
	)
	(segment
		(start 66.05016 -272.209514)
		(end 75.960986 -272.209514)
		(width 0.14478)
		(layer "In11.Cu")
		(net "M_F_CPU1_SB_CB<1>")
	)
	(segment
		(start 46.020482 -280.21026)
		(end 49.750218 -280.21026)
		(width 0.14478)
		(layer "In11.Cu")
		(net "M_F_CPU1_SB_CB<1>")
	)
	(segment
		(start 82.753962 -273.598894)
		(end 82.762344 -273.60372)
		(width 0.0889)
		(layer "In11.Cu")
		(net "M_F_CPU1_SB_CB<1>")
	)
	(segment
		(start 65.042034 -273.42211)
		(end 65.042288 -273.217386)
		(width 0.14478)
		(layer "In11.Cu")
		(net "M_F_CPU1_SB_CB<1>")
	)
	(segment
		(start 57.13349 -280.21026)
		(end 57.983628 -279.360122)
		(width 0.14478)
		(layer "In11.Cu")
		(net "M_F_CPU1_SB_CB<1>")
	)
	(segment
		(start 34.45129 -280.21026)
		(end 35.301428 -279.360122)
		(width 0.14478)
		(layer "In11.Cu")
		(net "M_F_CPU1_SB_CB<1>")
	)
	(segment
		(start 24.815292 -280.21026)
		(end 25.59431 -280.21026)
		(width 0.14478)
		(layer "In11.Cu")
		(net "M_F_CPU1_SB_CB<1>")
	)
	(segment
		(start 43.40225 -279.3619)
		(end 45.172122 -279.3619)
		(width 0.14478)
		(layer "In11.Cu")
		(net "M_F_CPU1_SB_CB<1>")
	)
	(segment
		(start 65.153794 -273.738594)
		(end 65.153794 -273.53387)
		(width 0.14478)
		(layer "In11.Cu")
		(net "M_F_CPU1_SB_CB<1>")
	)
	(segment
		(start 57.983628 -279.360122)
		(end 59.59094 -279.360122)
		(width 0.14478)
		(layer "In11.Cu")
		(net "M_F_CPU1_SB_CB<1>")
	)
	(segment
		(start 50.600356 -279.360122)
		(end 52.917344 -279.360122)
		(width 0.14478)
		(layer "In11.Cu")
		(net "M_F_CPU1_SB_CB<1>")
	)
	(segment
		(start 65.042288 -273.217386)
		(end 65.227708 -273.031966)
		(width 0.14478)
		(layer "In11.Cu")
		(net "M_F_CPU1_SB_CB<1>")
	)
	(segment
		(start 22.918674 -279.982422)
		(end 23.081488 -279.819608)
		(width 0.14478)
		(layer "In11.Cu")
		(net "M_F_CPU1_SB_CB<1>")
	)
	(segment
		(start 59.92241 -279.028652)
		(end 59.92241 -278.337264)
		(width 0.14478)
		(layer "In11.Cu")
		(net "M_F_CPU1_SB_CB<1>")
	)
	(segment
		(start 31.415482 -280.21026)
		(end 34.45129 -280.21026)
		(width 0.14478)
		(layer "In11.Cu")
		(net "M_F_CPU1_SB_CB<1>")
	)
	(segment
		(start 23.474934 -279.982422)
		(end 23.474934 -280.439622)
		(width 0.14478)
		(layer "In11.Cu")
		(net "M_F_CPU1_SB_CB<1>")
	)
	(segment
		(start 23.474934 -280.439622)
		(end 23.637748 -280.602436)
		(width 0.14478)
		(layer "In11.Cu")
		(net "M_F_CPU1_SB_CB<1>")
	)
	(segment
		(start 82.179668 -273.60372)
		(end 82.18805 -273.598894)
		(width 0.0889)
		(layer "In11.Cu")
		(net "M_F_CPU1_SB_CB<1>")
	)
	(segment
		(start 38.318186 -280.21026)
		(end 42.55389 -280.21026)
		(width 0.14478)
		(layer "In11.Cu")
		(net "M_F_CPU1_SB_CB<1>")
	)
	(segment
		(start 65.748408 -273.14398)
		(end 65.934082 -272.958306)
		(width 0.14478)
		(layer "In11.Cu")
		(net "M_F_CPU1_SB_CB<1>")
	)
	(segment
		(start 26.219404 -279.815798)
		(end 26.382218 -279.978612)
		(width 0.14478)
		(layer "In11.Cu")
		(net "M_F_CPU1_SB_CB<1>")
	)
	(segment
		(start 75.960986 -272.209514)
		(end 77.211936 -272.209514)
		(width 0.0889)
		(layer "In11.Cu")
		(net "M_F_CPU1_SB_CB<1>")
	)
	(segment
		(start 24.194008 -279.819608)
		(end 24.42464 -279.819608)
		(width 0.14478)
		(layer "In11.Cu")
		(net "M_F_CPU1_SB_CB<1>")
	)
	(segment
		(start 65.934082 -272.753582)
		(end 65.822322 -272.641822)
		(width 0.14478)
		(layer "In11.Cu")
		(net "M_F_CPU1_SB_CB<1>")
	)
	(segment
		(start 30.565344 -279.360122)
		(end 31.415482 -280.21026)
		(width 0.14478)
		(layer "In11.Cu")
		(net "M_F_CPU1_SB_CB<1>")
	)
	(segment
		(start 25.988772 -279.815798)
		(end 26.219404 -279.815798)
		(width 0.14478)
		(layer "In11.Cu")
		(net "M_F_CPU1_SB_CB<1>")
	)
	(segment
		(start 23.081488 -279.819608)
		(end 23.31212 -279.819608)
		(width 0.14478)
		(layer "In11.Cu")
		(net "M_F_CPU1_SB_CB<1>")
	)
	(segment
		(start 85.914992 -273.541744)
		(end 85.761068 -273.276314)
		(width 0.0889)
		(layer "In11.Cu")
		(net "M_F_CPU1_SB_CB<1>")
	)
	(segment
		(start 77.211936 -272.209514)
		(end 78.524862 -273.52244)
		(width 0.0889)
		(layer "In11.Cu")
		(net "M_F_CPU1_SB_CB<1>")
	)
	(segment
		(start 53.767482 -280.21026)
		(end 57.13349 -280.21026)
		(width 0.14478)
		(layer "In11.Cu")
		(net "M_F_CPU1_SB_CB<1>")
	)
	(segment
		(start 23.637748 -280.602436)
		(end 23.86838 -280.602436)
		(width 0.14478)
		(layer "In11.Cu")
		(net "M_F_CPU1_SB_CB<1>")
	)
	(segment
		(start 26.775664 -280.526744)
		(end 27.942286 -279.360122)
		(width 0.14478)
		(layer "In11.Cu")
		(net "M_F_CPU1_SB_CB<1>")
	)
	(segment
		(start 59.59094 -279.360122)
		(end 59.92241 -279.028652)
		(width 0.14478)
		(layer "In11.Cu")
		(net "M_F_CPU1_SB_CB<1>")
	)
	(segment
		(start 27.942286 -279.360122)
		(end 30.565344 -279.360122)
		(width 0.14478)
		(layer "In11.Cu")
		(net "M_F_CPU1_SB_CB<1>")
	)
	(segment
		(start 65.544192 -273.143726)
		(end 65.748408 -273.14398)
		(width 0.14478)
		(layer "In11.Cu")
		(net "M_F_CPU1_SB_CB<1>")
	)
	(segment
		(start 21.70811 -279.785318)
		(end 22.525228 -280.602436)
		(width 0.14478)
		(layer "In11.Cu")
		(net "M_F_CPU1_SB_CB<1>")
	)
	(segment
		(start 24.031194 -280.439622)
		(end 24.031194 -279.982422)
		(width 0.14478)
		(layer "In11.Cu")
		(net "M_F_CPU1_SB_CB<1>")
	)
	(segment
		(start 25.59431 -280.21026)
		(end 25.988772 -279.815798)
		(width 0.14478)
		(layer "In11.Cu")
		(net "M_F_CPU1_SB_CB<1>")
	)
	(arc
		(start 84.63407 -273.598894)
		(mid 84.821014 -273.649149)
		(end 85.007958 -273.598894)
		(width 0.0889)
		(layer "In11.Cu")
		(net "M_F_CPU1_SB_CB<1>")
	)
	(arc
		(start 80.874108 -273.598894)
		(mid 81.061052 -273.649149)
		(end 81.247996 -273.598894)
		(width 0.0889)
		(layer "In11.Cu")
		(net "M_F_CPU1_SB_CB<1>")
	)
	(arc
		(start 82.18805 -273.598894)
		(mid 82.471006 -273.522717)
		(end 82.753962 -273.598894)
		(width 0.0889)
		(layer "In11.Cu")
		(net "M_F_CPU1_SB_CB<1>")
	)
	(arc
		(start 79.9338 -273.598894)
		(mid 80.120998 -273.649276)
		(end 80.308196 -273.598894)
		(width 0.0889)
		(layer "In11.Cu")
		(net "M_F_CPU1_SB_CB<1>")
	)
	(arc
		(start 79.65059 -273.52244)
		(mid 79.797258 -273.541917)
		(end 79.9338 -273.598894)
		(width 0.0889)
		(layer "In11.Cu")
		(net "M_F_CPU1_SB_CB<1>")
	)
	(arc
		(start 83.128104 -273.598894)
		(mid 83.41106 -273.522717)
		(end 83.694016 -273.598894)
		(width 0.0889)
		(layer "In11.Cu")
		(net "M_F_CPU1_SB_CB<1>")
	)
	(arc
		(start 85.57387 -273.598894)
		(mid 85.730308 -273.647865)
		(end 85.89264 -273.625056)
		(width 0.0889)
		(layer "In11.Cu")
		(net "M_F_CPU1_SB_CB<1>")
	)
	(arc
		(start 81.247996 -273.598894)
		(mid 81.530952 -273.522717)
		(end 81.813908 -273.598894)
		(width 0.0889)
		(layer "In11.Cu")
		(net "M_F_CPU1_SB_CB<1>")
	)
	(arc
		(start 85.007958 -273.598894)
		(mid 85.290914 -273.522717)
		(end 85.57387 -273.598894)
		(width 0.0889)
		(layer "In11.Cu")
		(net "M_F_CPU1_SB_CB<1>")
	)
	(arc
		(start 83.702398 -273.60372)
		(mid 83.885906 -273.649214)
		(end 84.068158 -273.598894)
		(width 0.0889)
		(layer "In11.Cu")
		(net "M_F_CPU1_SB_CB<1>")
	)
	(arc
		(start 84.068158 -273.598894)
		(mid 84.351114 -273.522717)
		(end 84.63407 -273.598894)
		(width 0.0889)
		(layer "In11.Cu")
		(net "M_F_CPU1_SB_CB<1>")
	)
	(arc
		(start 82.762344 -273.60372)
		(mid 82.945852 -273.649214)
		(end 83.128104 -273.598894)
		(width 0.0889)
		(layer "In11.Cu")
		(net "M_F_CPU1_SB_CB<1>")
	)
	(arc
		(start 80.308196 -273.598894)
		(mid 80.591152 -273.522717)
		(end 80.874108 -273.598894)
		(width 0.0889)
		(layer "In11.Cu")
		(net "M_F_CPU1_SB_CB<1>")
	)
	(arc
		(start 81.813908 -273.598894)
		(mid 81.996159 -273.649244)
		(end 82.179668 -273.60372)
		(width 0.0889)
		(layer "In11.Cu")
		(net "M_F_CPU1_SB_CB<1>")
	)
	(segment
		(start 84.817966 -272.20037)
		(end 84.351114 -272.466308)
		(width 0.10668)
		(layer "F.Cu")
		(net "M_F_CPU1_SB_CB<0>")
	)
	(segment
		(start 23.861776 -278.673306)
		(end 23.861776 -278.7396)
		(width 0.14478)
		(layer "In11.Cu")
		(net "M_F_CPU1_SB_CB<0>")
	)
	(segment
		(start 24.571706 -278.51989)
		(end 26.805128 -278.51989)
		(width 0.14478)
		(layer "In11.Cu")
		(net "M_F_CPU1_SB_CB<0>")
	)
	(segment
		(start 40.89146 -278.51989)
		(end 41.044876 -278.673306)
		(width 0.14478)
		(layer "In11.Cu")
		(net "M_F_CPU1_SB_CB<0>")
	)
	(segment
		(start 35.61842 -277.89124)
		(end 35.781488 -278.054308)
		(width 0.14478)
		(layer "In11.Cu")
		(net "M_F_CPU1_SB_CB<0>")
	)
	(segment
		(start 36.174934 -277.823422)
		(end 36.32835 -277.670006)
		(width 0.14478)
		(layer "In11.Cu")
		(net "M_F_CPU1_SB_CB<0>")
	)
	(segment
		(start 48.343058 -278.51989)
		(end 48.496474 -278.673306)
		(width 0.14478)
		(layer "In11.Cu")
		(net "M_F_CPU1_SB_CB<0>")
	)
	(segment
		(start 46.42739 -278.51989)
		(end 48.343058 -278.51989)
		(width 0.14478)
		(layer "In11.Cu")
		(net "M_F_CPU1_SB_CB<0>")
	)
	(segment
		(start 53.975254 -278.797004)
		(end 54.23408 -278.797004)
		(width 0.14478)
		(layer "In11.Cu")
		(net "M_F_CPU1_SB_CB<0>")
	)
	(segment
		(start 48.88992 -278.902668)
		(end 49.052988 -278.7396)
		(width 0.14478)
		(layer "In11.Cu")
		(net "M_F_CPU1_SB_CB<0>")
	)
	(segment
		(start 54.37886 -278.652224)
		(end 54.37886 -278.416766)
		(width 0.14478)
		(layer "In11.Cu")
		(net "M_F_CPU1_SB_CB<0>")
	)
	(segment
		(start 33.503616 -278.7396)
		(end 33.666684 -278.902668)
		(width 0.14478)
		(layer "In11.Cu")
		(net "M_F_CPU1_SB_CB<0>")
	)
	(segment
		(start 55.075074 -278.797004)
		(end 55.336948 -278.797004)
		(width 0.14478)
		(layer "In11.Cu")
		(net "M_F_CPU1_SB_CB<0>")
	)
	(segment
		(start 23.861776 -278.7396)
		(end 24.024844 -278.902668)
		(width 0.14478)
		(layer "In11.Cu")
		(net "M_F_CPU1_SB_CB<0>")
	)
	(segment
		(start 50.905918 -278.046688)
		(end 51.136296 -278.046688)
		(width 0.14478)
		(layer "In11.Cu")
		(net "M_F_CPU1_SB_CB<0>")
	)
	(segment
		(start 28.792932 -277.670006)
		(end 30.480508 -277.670006)
		(width 0.14478)
		(layer "In11.Cu")
		(net "M_F_CPU1_SB_CB<0>")
	)
	(segment
		(start 41.044876 -278.7396)
		(end 41.207944 -278.902668)
		(width 0.14478)
		(layer "In11.Cu")
		(net "M_F_CPU1_SB_CB<0>")
	)
	(segment
		(start 57.865772 -278.055578)
		(end 58.932064 -278.055578)
		(width 0.14478)
		(layer "In11.Cu")
		(net "M_F_CPU1_SB_CB<0>")
	)
	(segment
		(start 79.447136 -272.77822)
		(end 79.46517 -272.788888)
		(width 0.0889)
		(layer "In11.Cu")
		(net "M_F_CPU1_SB_CB<0>")
	)
	(segment
		(start 55.336948 -278.797004)
		(end 55.481728 -278.652224)
		(width 0.14478)
		(layer "In11.Cu")
		(net "M_F_CPU1_SB_CB<0>")
	)
	(segment
		(start 54.23408 -278.797004)
		(end 54.37886 -278.652224)
		(width 0.14478)
		(layer "In11.Cu")
		(net "M_F_CPU1_SB_CB<0>")
	)
	(segment
		(start 49.448974 -278.510238)
		(end 50.298858 -277.660354)
		(width 0.14478)
		(layer "In11.Cu")
		(net "M_F_CPU1_SB_CB<0>")
	)
	(segment
		(start 54.930294 -278.652224)
		(end 55.075074 -278.797004)
		(width 0.14478)
		(layer "In11.Cu")
		(net "M_F_CPU1_SB_CB<0>")
	)
	(segment
		(start 43.195494 -277.823422)
		(end 43.195494 -277.88362)
		(width 0.14478)
		(layer "In11.Cu")
		(net "M_F_CPU1_SB_CB<0>")
	)
	(segment
		(start 65.687448 -271.300194)
		(end 75.960986 -271.300194)
		(width 0.14478)
		(layer "In11.Cu")
		(net "M_F_CPU1_SB_CB<0>")
	)
	(segment
		(start 35.233102 -277.660354)
		(end 35.455352 -277.660354)
		(width 0.14478)
		(layer "In11.Cu")
		(net "M_F_CPU1_SB_CB<0>")
	)
	(segment
		(start 23.00224 -278.34717)
		(end 23.165308 -278.510238)
		(width 0.14478)
		(layer "In11.Cu")
		(net "M_F_CPU1_SB_CB<0>")
	)
	(segment
		(start 27.664664 -277.660354)
		(end 27.919934 -277.660354)
		(width 0.14478)
		(layer "In11.Cu")
		(net "M_F_CPU1_SB_CB<0>")
	)
	(segment
		(start 28.639516 -277.89124)
		(end 28.639516 -277.823422)
		(width 0.14478)
		(layer "In11.Cu")
		(net "M_F_CPU1_SB_CB<0>")
	)
	(segment
		(start 24.255222 -278.902668)
		(end 24.41829 -278.7396)
		(width 0.14478)
		(layer "In11.Cu")
		(net "M_F_CPU1_SB_CB<0>")
	)
	(segment
		(start 50.579782 -277.660354)
		(end 50.74285 -277.823422)
		(width 0.14478)
		(layer "In11.Cu")
		(net "M_F_CPU1_SB_CB<0>")
	)
	(segment
		(start 21.70811 -278.085296)
		(end 22.133052 -278.510238)
		(width 0.14478)
		(layer "In11.Cu")
		(net "M_F_CPU1_SB_CB<0>")
	)
	(segment
		(start 23.165308 -278.510238)
		(end 23.698708 -278.510238)
		(width 0.14478)
		(layer "In11.Cu")
		(net "M_F_CPU1_SB_CB<0>")
	)
	(segment
		(start 26.805128 -278.51989)
		(end 27.664664 -277.660354)
		(width 0.14478)
		(layer "In11.Cu")
		(net "M_F_CPU1_SB_CB<0>")
	)
	(segment
		(start 36.011866 -278.054308)
		(end 36.174934 -277.89124)
		(width 0.14478)
		(layer "In11.Cu")
		(net "M_F_CPU1_SB_CB<0>")
	)
	(segment
		(start 49.052988 -278.7396)
		(end 49.052988 -278.673306)
		(width 0.14478)
		(layer "In11.Cu")
		(net "M_F_CPU1_SB_CB<0>")
	)
	(segment
		(start 24.024844 -278.902668)
		(end 24.255222 -278.902668)
		(width 0.14478)
		(layer "In11.Cu")
		(net "M_F_CPU1_SB_CB<0>")
	)
	(segment
		(start 43.032426 -277.660354)
		(end 43.195494 -277.823422)
		(width 0.14478)
		(layer "In11.Cu")
		(net "M_F_CPU1_SB_CB<0>")
	)
	(segment
		(start 83.589622 -272.793714)
		(end 83.598004 -272.788888)
		(width 0.0889)
		(layer "In11.Cu")
		(net "M_F_CPU1_SB_CB<0>")
	)
	(segment
		(start 22.445726 -278.34717)
		(end 22.445726 -277.943056)
		(width 0.14478)
		(layer "In11.Cu")
		(net "M_F_CPU1_SB_CB<0>")
	)
	(segment
		(start 28.083002 -277.89124)
		(end 28.24607 -278.054308)
		(width 0.14478)
		(layer "In11.Cu")
		(net "M_F_CPU1_SB_CB<0>")
	)
	(segment
		(start 43.195494 -277.88362)
		(end 43.358562 -278.046688)
		(width 0.14478)
		(layer "In11.Cu")
		(net "M_F_CPU1_SB_CB<0>")
	)
	(segment
		(start 28.476448 -278.054308)
		(end 28.639516 -277.89124)
		(width 0.14478)
		(layer "In11.Cu")
		(net "M_F_CPU1_SB_CB<0>")
	)
	(segment
		(start 51.299364 -277.88362)
		(end 51.299364 -277.823422)
		(width 0.14478)
		(layer "In11.Cu")
		(net "M_F_CPU1_SB_CB<0>")
	)
	(segment
		(start 41.60139 -278.7396)
		(end 41.60139 -278.673306)
		(width 0.14478)
		(layer "In11.Cu")
		(net "M_F_CPU1_SB_CB<0>")
	)
	(segment
		(start 56.033162 -278.416766)
		(end 56.033162 -278.652224)
		(width 0.14478)
		(layer "In11.Cu")
		(net "M_F_CPU1_SB_CB<0>")
	)
	(segment
		(start 84.505038 -272.731738)
		(end 84.351114 -272.466308)
		(width 0.0889)
		(layer "In11.Cu")
		(net "M_F_CPU1_SB_CB<0>")
	)
	(segment
		(start 23.00224 -277.943056)
		(end 23.00224 -278.34717)
		(width 0.14478)
		(layer "In11.Cu")
		(net "M_F_CPU1_SB_CB<0>")
	)
	(segment
		(start 41.60139 -278.673306)
		(end 41.764458 -278.510238)
		(width 0.14478)
		(layer "In11.Cu")
		(net "M_F_CPU1_SB_CB<0>")
	)
	(segment
		(start 34.223198 -278.510238)
		(end 34.383218 -278.510238)
		(width 0.14478)
		(layer "In11.Cu")
		(net "M_F_CPU1_SB_CB<0>")
	)
	(segment
		(start 28.083002 -277.823422)
		(end 28.083002 -277.89124)
		(width 0.14478)
		(layer "In11.Cu")
		(net "M_F_CPU1_SB_CB<0>")
	)
	(segment
		(start 51.45278 -277.670006)
		(end 52.848256 -277.670006)
		(width 0.14478)
		(layer "In11.Cu")
		(net "M_F_CPU1_SB_CB<0>")
	)
	(segment
		(start 78.447138 -272.72996)
		(end 78.447392 -272.72996)
		(width 0.0889)
		(layer "In11.Cu")
		(net "M_F_CPU1_SB_CB<0>")
	)
	(segment
		(start 49.216056 -278.510238)
		(end 49.448974 -278.510238)
		(width 0.14478)
		(layer "In11.Cu")
		(net "M_F_CPU1_SB_CB<0>")
	)
	(segment
		(start 43.752008 -277.88362)
		(end 43.752008 -277.823422)
		(width 0.14478)
		(layer "In11.Cu")
		(net "M_F_CPU1_SB_CB<0>")
	)
	(segment
		(start 33.897062 -278.902668)
		(end 34.06013 -278.7396)
		(width 0.14478)
		(layer "In11.Cu")
		(net "M_F_CPU1_SB_CB<0>")
	)
	(segment
		(start 54.37886 -278.416766)
		(end 54.52364 -278.271986)
		(width 0.14478)
		(layer "In11.Cu")
		(net "M_F_CPU1_SB_CB<0>")
	)
	(segment
		(start 54.930294 -278.416766)
		(end 54.930294 -278.652224)
		(width 0.14478)
		(layer "In11.Cu")
		(net "M_F_CPU1_SB_CB<0>")
	)
	(segment
		(start 79.838804 -272.788634)
		(end 79.850742 -272.781776)
		(width 0.0889)
		(layer "In11.Cu")
		(net "M_F_CPU1_SB_CB<0>")
	)
	(segment
		(start 35.781488 -278.054308)
		(end 36.011866 -278.054308)
		(width 0.14478)
		(layer "In11.Cu")
		(net "M_F_CPU1_SB_CB<0>")
	)
	(segment
		(start 43.358562 -278.046688)
		(end 43.58894 -278.046688)
		(width 0.14478)
		(layer "In11.Cu")
		(net "M_F_CPU1_SB_CB<0>")
	)
	(segment
		(start 54.52364 -278.271986)
		(end 54.785514 -278.271986)
		(width 0.14478)
		(layer "In11.Cu")
		(net "M_F_CPU1_SB_CB<0>")
	)
	(segment
		(start 51.136296 -278.046688)
		(end 51.299364 -277.88362)
		(width 0.14478)
		(layer "In11.Cu")
		(net "M_F_CPU1_SB_CB<0>")
	)
	(segment
		(start 54.785514 -278.271986)
		(end 54.930294 -278.416766)
		(width 0.14478)
		(layer "In11.Cu")
		(net "M_F_CPU1_SB_CB<0>")
	)
	(segment
		(start 50.74285 -277.88362)
		(end 50.905918 -278.046688)
		(width 0.14478)
		(layer "In11.Cu")
		(net "M_F_CPU1_SB_CB<0>")
	)
	(segment
		(start 35.61842 -277.823422)
		(end 35.61842 -277.89124)
		(width 0.14478)
		(layer "In11.Cu")
		(net "M_F_CPU1_SB_CB<0>")
	)
	(segment
		(start 41.207944 -278.902668)
		(end 41.438322 -278.902668)
		(width 0.14478)
		(layer "In11.Cu")
		(net "M_F_CPU1_SB_CB<0>")
	)
	(segment
		(start 24.41829 -278.673306)
		(end 24.571706 -278.51989)
		(width 0.14478)
		(layer "In11.Cu")
		(net "M_F_CPU1_SB_CB<0>")
	)
	(segment
		(start 48.659542 -278.902668)
		(end 48.88992 -278.902668)
		(width 0.14478)
		(layer "In11.Cu")
		(net "M_F_CPU1_SB_CB<0>")
	)
	(segment
		(start 22.608794 -277.779988)
		(end 22.839172 -277.779988)
		(width 0.14478)
		(layer "In11.Cu")
		(net "M_F_CPU1_SB_CB<0>")
	)
	(segment
		(start 43.58894 -278.046688)
		(end 43.752008 -277.88362)
		(width 0.14478)
		(layer "In11.Cu")
		(net "M_F_CPU1_SB_CB<0>")
	)
	(segment
		(start 28.24607 -278.054308)
		(end 28.476448 -278.054308)
		(width 0.14478)
		(layer "In11.Cu")
		(net "M_F_CPU1_SB_CB<0>")
	)
	(segment
		(start 55.481728 -278.652224)
		(end 55.481728 -278.416766)
		(width 0.14478)
		(layer "In11.Cu")
		(net "M_F_CPU1_SB_CB<0>")
	)
	(segment
		(start 30.480508 -277.670006)
		(end 31.330392 -278.51989)
		(width 0.14478)
		(layer "In11.Cu")
		(net "M_F_CPU1_SB_CB<0>")
	)
	(segment
		(start 34.06013 -278.7396)
		(end 34.06013 -278.673306)
		(width 0.14478)
		(layer "In11.Cu")
		(net "M_F_CPU1_SB_CB<0>")
	)
	(segment
		(start 50.74285 -277.823422)
		(end 50.74285 -277.88362)
		(width 0.14478)
		(layer "In11.Cu")
		(net "M_F_CPU1_SB_CB<0>")
	)
	(segment
		(start 23.698708 -278.510238)
		(end 23.861776 -278.673306)
		(width 0.14478)
		(layer "In11.Cu")
		(net "M_F_CPU1_SB_CB<0>")
	)
	(segment
		(start 33.666684 -278.902668)
		(end 33.897062 -278.902668)
		(width 0.14478)
		(layer "In11.Cu")
		(net "M_F_CPU1_SB_CB<0>")
	)
	(segment
		(start 33.503616 -278.673306)
		(end 33.503616 -278.7396)
		(width 0.14478)
		(layer "In11.Cu")
		(net "M_F_CPU1_SB_CB<0>")
	)
	(segment
		(start 79.825088 -272.796508)
		(end 79.838804 -272.788634)
		(width 0.0889)
		(layer "In11.Cu")
		(net "M_F_CPU1_SB_CB<0>")
	)
	(segment
		(start 52.848256 -277.670006)
		(end 53.975254 -278.797004)
		(width 0.14478)
		(layer "In11.Cu")
		(net "M_F_CPU1_SB_CB<0>")
	)
	(segment
		(start 35.455352 -277.660354)
		(end 35.61842 -277.823422)
		(width 0.14478)
		(layer "In11.Cu")
		(net "M_F_CPU1_SB_CB<0>")
	)
	(segment
		(start 38.812216 -278.51989)
		(end 40.89146 -278.51989)
		(width 0.14478)
		(layer "In11.Cu")
		(net "M_F_CPU1_SB_CB<0>")
	)
	(segment
		(start 37.962332 -277.670006)
		(end 38.812216 -278.51989)
		(width 0.14478)
		(layer "In11.Cu")
		(net "M_F_CPU1_SB_CB<0>")
	)
	(segment
		(start 36.174934 -277.89124)
		(end 36.174934 -277.823422)
		(width 0.14478)
		(layer "In11.Cu")
		(net "M_F_CPU1_SB_CB<0>")
	)
	(segment
		(start 75.960986 -271.300194)
		(end 76.455016 -271.300194)
		(width 0.0889)
		(layer "In11.Cu")
		(net "M_F_CPU1_SB_CB<0>")
	)
	(segment
		(start 41.94302 -278.510238)
		(end 42.792904 -277.660354)
		(width 0.14478)
		(layer "In11.Cu")
		(net "M_F_CPU1_SB_CB<0>")
	)
	(segment
		(start 76.455016 -271.300194)
		(end 76.900786 -271.745964)
		(width 0.0889)
		(layer "In11.Cu")
		(net "M_F_CPU1_SB_CB<0>")
	)
	(segment
		(start 50.298858 -277.660354)
		(end 50.579782 -277.660354)
		(width 0.14478)
		(layer "In11.Cu")
		(net "M_F_CPU1_SB_CB<0>")
	)
	(segment
		(start 22.445726 -277.943056)
		(end 22.608794 -277.779988)
		(width 0.14478)
		(layer "In11.Cu")
		(net "M_F_CPU1_SB_CB<0>")
	)
	(segment
		(start 56.033162 -278.652224)
		(end 56.177942 -278.797004)
		(width 0.14478)
		(layer "In11.Cu")
		(net "M_F_CPU1_SB_CB<0>")
	)
	(segment
		(start 49.052988 -278.673306)
		(end 49.216056 -278.510238)
		(width 0.14478)
		(layer "In11.Cu")
		(net "M_F_CPU1_SB_CB<0>")
	)
	(segment
		(start 78.524608 -272.788634)
		(end 78.544674 -272.800064)
		(width 0.0889)
		(layer "In11.Cu")
		(net "M_F_CPU1_SB_CB<0>")
	)
	(segment
		(start 55.626508 -278.271986)
		(end 55.888382 -278.271986)
		(width 0.14478)
		(layer "In11.Cu")
		(net "M_F_CPU1_SB_CB<0>")
	)
	(segment
		(start 22.839172 -277.779988)
		(end 23.00224 -277.943056)
		(width 0.14478)
		(layer "In11.Cu")
		(net "M_F_CPU1_SB_CB<0>")
	)
	(segment
		(start 34.383218 -278.510238)
		(end 35.233102 -277.660354)
		(width 0.14478)
		(layer "In11.Cu")
		(net "M_F_CPU1_SB_CB<0>")
	)
	(segment
		(start 36.32835 -277.670006)
		(end 37.962332 -277.670006)
		(width 0.14478)
		(layer "In11.Cu")
		(net "M_F_CPU1_SB_CB<0>")
	)
	(segment
		(start 51.299364 -277.823422)
		(end 51.45278 -277.670006)
		(width 0.14478)
		(layer "In11.Cu")
		(net "M_F_CPU1_SB_CB<0>")
	)
	(segment
		(start 76.900786 -271.745964)
		(end 77.463142 -271.745964)
		(width 0.0889)
		(layer "In11.Cu")
		(net "M_F_CPU1_SB_CB<0>")
	)
	(segment
		(start 43.752008 -277.823422)
		(end 43.905424 -277.670006)
		(width 0.14478)
		(layer "In11.Cu")
		(net "M_F_CPU1_SB_CB<0>")
	)
	(segment
		(start 80.769714 -272.793714)
		(end 80.778096 -272.788888)
		(width 0.0889)
		(layer "In11.Cu")
		(net "M_F_CPU1_SB_CB<0>")
	)
	(segment
		(start 84.482686 -272.81505)
		(end 84.505038 -272.731738)
		(width 0.0889)
		(layer "In11.Cu")
		(net "M_F_CPU1_SB_CB<0>")
	)
	(segment
		(start 48.496474 -278.7396)
		(end 48.659542 -278.902668)
		(width 0.14478)
		(layer "In11.Cu")
		(net "M_F_CPU1_SB_CB<0>")
	)
	(segment
		(start 33.3502 -278.51989)
		(end 33.503616 -278.673306)
		(width 0.14478)
		(layer "In11.Cu")
		(net "M_F_CPU1_SB_CB<0>")
	)
	(segment
		(start 31.330392 -278.51989)
		(end 33.3502 -278.51989)
		(width 0.14478)
		(layer "In11.Cu")
		(net "M_F_CPU1_SB_CB<0>")
	)
	(segment
		(start 48.496474 -278.673306)
		(end 48.496474 -278.7396)
		(width 0.14478)
		(layer "In11.Cu")
		(net "M_F_CPU1_SB_CB<0>")
	)
	(segment
		(start 41.438322 -278.902668)
		(end 41.60139 -278.7396)
		(width 0.14478)
		(layer "In11.Cu")
		(net "M_F_CPU1_SB_CB<0>")
	)
	(segment
		(start 28.639516 -277.823422)
		(end 28.792932 -277.670006)
		(width 0.14478)
		(layer "In11.Cu")
		(net "M_F_CPU1_SB_CB<0>")
	)
	(segment
		(start 24.41829 -278.7396)
		(end 24.41829 -278.673306)
		(width 0.14478)
		(layer "In11.Cu")
		(net "M_F_CPU1_SB_CB<0>")
	)
	(segment
		(start 77.463142 -271.745964)
		(end 78.447138 -272.72996)
		(width 0.0889)
		(layer "In11.Cu")
		(net "M_F_CPU1_SB_CB<0>")
	)
	(segment
		(start 58.932064 -278.055578)
		(end 65.687448 -271.300194)
		(width 0.14478)
		(layer "In11.Cu")
		(net "M_F_CPU1_SB_CB<0>")
	)
	(segment
		(start 22.282658 -278.510238)
		(end 22.445726 -278.34717)
		(width 0.14478)
		(layer "In11.Cu")
		(net "M_F_CPU1_SB_CB<0>")
	)
	(segment
		(start 56.177942 -278.797004)
		(end 57.124346 -278.797004)
		(width 0.14478)
		(layer "In11.Cu")
		(net "M_F_CPU1_SB_CB<0>")
	)
	(segment
		(start 43.905424 -277.670006)
		(end 45.577506 -277.670006)
		(width 0.14478)
		(layer "In11.Cu")
		(net "M_F_CPU1_SB_CB<0>")
	)
	(segment
		(start 34.06013 -278.673306)
		(end 34.223198 -278.510238)
		(width 0.14478)
		(layer "In11.Cu")
		(net "M_F_CPU1_SB_CB<0>")
	)
	(segment
		(start 27.919934 -277.660354)
		(end 28.083002 -277.823422)
		(width 0.14478)
		(layer "In11.Cu")
		(net "M_F_CPU1_SB_CB<0>")
	)
	(segment
		(start 22.133052 -278.510238)
		(end 22.282658 -278.510238)
		(width 0.14478)
		(layer "In11.Cu")
		(net "M_F_CPU1_SB_CB<0>")
	)
	(segment
		(start 55.481728 -278.416766)
		(end 55.626508 -278.271986)
		(width 0.14478)
		(layer "In11.Cu")
		(net "M_F_CPU1_SB_CB<0>")
	)
	(segment
		(start 41.764458 -278.510238)
		(end 41.94302 -278.510238)
		(width 0.14478)
		(layer "In11.Cu")
		(net "M_F_CPU1_SB_CB<0>")
	)
	(segment
		(start 41.044876 -278.673306)
		(end 41.044876 -278.7396)
		(width 0.14478)
		(layer "In11.Cu")
		(net "M_F_CPU1_SB_CB<0>")
	)
	(segment
		(start 55.888382 -278.271986)
		(end 56.033162 -278.416766)
		(width 0.14478)
		(layer "In11.Cu")
		(net "M_F_CPU1_SB_CB<0>")
	)
	(segment
		(start 45.577506 -277.670006)
		(end 46.42739 -278.51989)
		(width 0.14478)
		(layer "In11.Cu")
		(net "M_F_CPU1_SB_CB<0>")
	)
	(segment
		(start 81.344008 -272.788888)
		(end 81.35239 -272.793714)
		(width 0.0889)
		(layer "In11.Cu")
		(net "M_F_CPU1_SB_CB<0>")
	)
	(segment
		(start 57.124346 -278.797004)
		(end 57.865772 -278.055578)
		(width 0.14478)
		(layer "In11.Cu")
		(net "M_F_CPU1_SB_CB<0>")
	)
	(segment
		(start 42.792904 -277.660354)
		(end 43.032426 -277.660354)
		(width 0.14478)
		(layer "In11.Cu")
		(net "M_F_CPU1_SB_CB<0>")
	)
	(arc
		(start 84.163916 -272.788888)
		(mid 84.320354 -272.837859)
		(end 84.482686 -272.81505)
		(width 0.0889)
		(layer "In11.Cu")
		(net "M_F_CPU1_SB_CB<0>")
	)
	(arc
		(start 81.71815 -272.788888)
		(mid 82.001106 -272.712711)
		(end 82.284062 -272.788888)
		(width 0.0889)
		(layer "In11.Cu")
		(net "M_F_CPU1_SB_CB<0>")
	)
	(arc
		(start 82.65795 -272.788888)
		(mid 82.940906 -272.712711)
		(end 83.223862 -272.788888)
		(width 0.0889)
		(layer "In11.Cu")
		(net "M_F_CPU1_SB_CB<0>")
	)
	(arc
		(start 83.598004 -272.788888)
		(mid 83.88096 -272.712711)
		(end 84.163916 -272.788888)
		(width 0.0889)
		(layer "In11.Cu")
		(net "M_F_CPU1_SB_CB<0>")
	)
	(arc
		(start 80.403954 -272.788888)
		(mid 80.586205 -272.839238)
		(end 80.769714 -272.793714)
		(width 0.0889)
		(layer "In11.Cu")
		(net "M_F_CPU1_SB_CB<0>")
	)
	(arc
		(start 79.850742 -272.781776)
		(mid 80.128276 -272.712795)
		(end 80.403954 -272.788888)
		(width 0.0889)
		(layer "In11.Cu")
		(net "M_F_CPU1_SB_CB<0>")
	)
	(arc
		(start 83.223862 -272.788888)
		(mid 83.406113 -272.839238)
		(end 83.589622 -272.793714)
		(width 0.0889)
		(layer "In11.Cu")
		(net "M_F_CPU1_SB_CB<0>")
	)
	(arc
		(start 78.447392 -272.72996)
		(mid 78.484088 -272.761813)
		(end 78.524608 -272.788634)
		(width 0.0889)
		(layer "In11.Cu")
		(net "M_F_CPU1_SB_CB<0>")
	)
	(arc
		(start 79.46517 -272.788888)
		(mid 79.644157 -272.839058)
		(end 79.825088 -272.796508)
		(width 0.0889)
		(layer "In11.Cu")
		(net "M_F_CPU1_SB_CB<0>")
	)
	(arc
		(start 78.898496 -272.788888)
		(mid 79.17144 -272.712308)
		(end 79.447136 -272.77822)
		(width 0.0889)
		(layer "In11.Cu")
		(net "M_F_CPU1_SB_CB<0>")
	)
	(arc
		(start 80.778096 -272.788888)
		(mid 81.061052 -272.712711)
		(end 81.344008 -272.788888)
		(width 0.0889)
		(layer "In11.Cu")
		(net "M_F_CPU1_SB_CB<0>")
	)
	(arc
		(start 81.35239 -272.793714)
		(mid 81.535898 -272.839208)
		(end 81.71815 -272.788888)
		(width 0.0889)
		(layer "In11.Cu")
		(net "M_F_CPU1_SB_CB<0>")
	)
	(arc
		(start 78.544674 -272.800064)
		(mid 78.723006 -272.839161)
		(end 78.898496 -272.788888)
		(width 0.0889)
		(layer "In11.Cu")
		(net "M_F_CPU1_SB_CB<0>")
	)
	(arc
		(start 82.284062 -272.788888)
		(mid 82.471006 -272.839143)
		(end 82.65795 -272.788888)
		(width 0.0889)
		(layer "In11.Cu")
		(net "M_F_CPU1_SB_CB<0>")
	)
	(segment
		(start 84.817966 -264.10031)
		(end 84.351114 -264.366248)
		(width 0.10668)
		(layer "F.Cu")
		(net "M_F_CPU1_SB_CA<6>")
	)
	(segment
		(start 22.527514 -265.365992)
		(end 22.758146 -265.365992)
		(width 0.14478)
		(layer "In11.Cu")
		(net "M_F_CPU1_SB_CA<6>")
	)
	(segment
		(start 23.870666 -265.365992)
		(end 24.03348 -265.528806)
		(width 0.14478)
		(layer "In11.Cu")
		(net "M_F_CPU1_SB_CA<6>")
	)
	(segment
		(start 22.92096 -265.982958)
		(end 23.083774 -266.145772)
		(width 0.14478)
		(layer "In11.Cu")
		(net "M_F_CPU1_SB_CA<6>")
	)
	(segment
		(start 23.47722 -265.528806)
		(end 23.640034 -265.365992)
		(width 0.14478)
		(layer "In11.Cu")
		(net "M_F_CPU1_SB_CA<6>")
	)
	(segment
		(start 23.47722 -265.982958)
		(end 23.47722 -265.528806)
		(width 0.14478)
		(layer "In11.Cu")
		(net "M_F_CPU1_SB_CA<6>")
	)
	(segment
		(start 79.838804 -264.688574)
		(end 79.850742 -264.681716)
		(width 0.0889)
		(layer "In11.Cu")
		(net "M_F_CPU1_SB_CA<6>")
	)
	(segment
		(start 21.70811 -266.185396)
		(end 22.527514 -265.365992)
		(width 0.14478)
		(layer "In11.Cu")
		(net "M_F_CPU1_SB_CA<6>")
	)
	(segment
		(start 61.360812 -264.619994)
		(end 75.996546 -264.619994)
		(width 0.14478)
		(layer "In11.Cu")
		(net "M_F_CPU1_SB_CA<6>")
	)
	(segment
		(start 26.005282 -266.150344)
		(end 26.235914 -266.150344)
		(width 0.14478)
		(layer "In11.Cu")
		(net "M_F_CPU1_SB_CA<6>")
	)
	(segment
		(start 27.348434 -266.150344)
		(end 27.738324 -265.760454)
		(width 0.14478)
		(layer "In11.Cu")
		(net "M_F_CPU1_SB_CA<6>")
	)
	(segment
		(start 24.426926 -266.145772)
		(end 24.812244 -265.760454)
		(width 0.14478)
		(layer "In11.Cu")
		(net "M_F_CPU1_SB_CA<6>")
	)
	(segment
		(start 77.76845 -264.612628)
		(end 78.242668 -264.612628)
		(width 0.0889)
		(layer "In11.Cu")
		(net "M_F_CPU1_SB_CA<6>")
	)
	(segment
		(start 26.398728 -265.98753)
		(end 26.398728 -265.533378)
		(width 0.14478)
		(layer "In11.Cu")
		(net "M_F_CPU1_SB_CA<6>")
	)
	(segment
		(start 24.03348 -265.982958)
		(end 24.196294 -266.145772)
		(width 0.14478)
		(layer "In11.Cu")
		(net "M_F_CPU1_SB_CA<6>")
	)
	(segment
		(start 60.220352 -265.760454)
		(end 61.360812 -264.619994)
		(width 0.14478)
		(layer "In11.Cu")
		(net "M_F_CPU1_SB_CA<6>")
	)
	(segment
		(start 24.812244 -265.760454)
		(end 25.615392 -265.760454)
		(width 0.14478)
		(layer "In11.Cu")
		(net "M_F_CPU1_SB_CA<6>")
	)
	(segment
		(start 84.482686 -264.71499)
		(end 84.505038 -264.631678)
		(width 0.0889)
		(layer "In11.Cu")
		(net "M_F_CPU1_SB_CA<6>")
	)
	(segment
		(start 79.825088 -264.696448)
		(end 79.838804 -264.688574)
		(width 0.0889)
		(layer "In11.Cu")
		(net "M_F_CPU1_SB_CA<6>")
	)
	(segment
		(start 25.615392 -265.760454)
		(end 26.005282 -266.150344)
		(width 0.14478)
		(layer "In11.Cu")
		(net "M_F_CPU1_SB_CA<6>")
	)
	(segment
		(start 26.398728 -265.533378)
		(end 26.561542 -265.370564)
		(width 0.14478)
		(layer "In11.Cu")
		(net "M_F_CPU1_SB_CA<6>")
	)
	(segment
		(start 76.575666 -264.303764)
		(end 77.459586 -264.303764)
		(width 0.0889)
		(layer "In11.Cu")
		(net "M_F_CPU1_SB_CA<6>")
	)
	(segment
		(start 27.738324 -265.760454)
		(end 60.220352 -265.760454)
		(width 0.14478)
		(layer "In11.Cu")
		(net "M_F_CPU1_SB_CA<6>")
	)
	(segment
		(start 26.954988 -265.98753)
		(end 27.117802 -266.150344)
		(width 0.14478)
		(layer "In11.Cu")
		(net "M_F_CPU1_SB_CA<6>")
	)
	(segment
		(start 81.344008 -264.688828)
		(end 81.35239 -264.693654)
		(width 0.0889)
		(layer "In11.Cu")
		(net "M_F_CPU1_SB_CA<6>")
	)
	(segment
		(start 80.769714 -264.693654)
		(end 80.778096 -264.688828)
		(width 0.0889)
		(layer "In11.Cu")
		(net "M_F_CPU1_SB_CA<6>")
	)
	(segment
		(start 26.954988 -265.533378)
		(end 26.954988 -265.98753)
		(width 0.14478)
		(layer "In11.Cu")
		(net "M_F_CPU1_SB_CA<6>")
	)
	(segment
		(start 26.235914 -266.150344)
		(end 26.398728 -265.98753)
		(width 0.14478)
		(layer "In11.Cu")
		(net "M_F_CPU1_SB_CA<6>")
	)
	(segment
		(start 24.196294 -266.145772)
		(end 24.426926 -266.145772)
		(width 0.14478)
		(layer "In11.Cu")
		(net "M_F_CPU1_SB_CA<6>")
	)
	(segment
		(start 22.758146 -265.365992)
		(end 22.92096 -265.528806)
		(width 0.14478)
		(layer "In11.Cu")
		(net "M_F_CPU1_SB_CA<6>")
	)
	(segment
		(start 26.792174 -265.370564)
		(end 26.954988 -265.533378)
		(width 0.14478)
		(layer "In11.Cu")
		(net "M_F_CPU1_SB_CA<6>")
	)
	(segment
		(start 78.524608 -264.688574)
		(end 78.544674 -264.700004)
		(width 0.0889)
		(layer "In11.Cu")
		(net "M_F_CPU1_SB_CA<6>")
	)
	(segment
		(start 24.03348 -265.528806)
		(end 24.03348 -265.982958)
		(width 0.14478)
		(layer "In11.Cu")
		(net "M_F_CPU1_SB_CA<6>")
	)
	(segment
		(start 77.459586 -264.303764)
		(end 77.76845 -264.612628)
		(width 0.0889)
		(layer "In11.Cu")
		(net "M_F_CPU1_SB_CA<6>")
	)
	(segment
		(start 22.92096 -265.528806)
		(end 22.92096 -265.982958)
		(width 0.14478)
		(layer "In11.Cu")
		(net "M_F_CPU1_SB_CA<6>")
	)
	(segment
		(start 26.561542 -265.370564)
		(end 26.792174 -265.370564)
		(width 0.14478)
		(layer "In11.Cu")
		(net "M_F_CPU1_SB_CA<6>")
	)
	(segment
		(start 75.996546 -264.619994)
		(end 76.259436 -264.619994)
		(width 0.0889)
		(layer "In11.Cu")
		(net "M_F_CPU1_SB_CA<6>")
	)
	(segment
		(start 79.447136 -264.67816)
		(end 79.46517 -264.688828)
		(width 0.0889)
		(layer "In11.Cu")
		(net "M_F_CPU1_SB_CA<6>")
	)
	(segment
		(start 23.083774 -266.145772)
		(end 23.314406 -266.145772)
		(width 0.14478)
		(layer "In11.Cu")
		(net "M_F_CPU1_SB_CA<6>")
	)
	(segment
		(start 84.505038 -264.631678)
		(end 84.351114 -264.366248)
		(width 0.0889)
		(layer "In11.Cu")
		(net "M_F_CPU1_SB_CA<6>")
	)
	(segment
		(start 23.314406 -266.145772)
		(end 23.47722 -265.982958)
		(width 0.14478)
		(layer "In11.Cu")
		(net "M_F_CPU1_SB_CA<6>")
	)
	(segment
		(start 23.640034 -265.365992)
		(end 23.870666 -265.365992)
		(width 0.14478)
		(layer "In11.Cu")
		(net "M_F_CPU1_SB_CA<6>")
	)
	(segment
		(start 76.259436 -264.619994)
		(end 76.575666 -264.303764)
		(width 0.0889)
		(layer "In11.Cu")
		(net "M_F_CPU1_SB_CA<6>")
	)
	(segment
		(start 82.284062 -264.688828)
		(end 82.292444 -264.693654)
		(width 0.0889)
		(layer "In11.Cu")
		(net "M_F_CPU1_SB_CA<6>")
	)
	(segment
		(start 27.117802 -266.150344)
		(end 27.348434 -266.150344)
		(width 0.14478)
		(layer "In11.Cu")
		(net "M_F_CPU1_SB_CA<6>")
	)
	(arc
		(start 83.224116 -264.688828)
		(mid 83.41106 -264.739083)
		(end 83.598004 -264.688828)
		(width 0.0889)
		(layer "In11.Cu")
		(net "M_F_CPU1_SB_CA<6>")
	)
	(arc
		(start 79.850742 -264.681716)
		(mid 80.128276 -264.612735)
		(end 80.403954 -264.688828)
		(width 0.0889)
		(layer "In11.Cu")
		(net "M_F_CPU1_SB_CA<6>")
	)
	(arc
		(start 80.403954 -264.688828)
		(mid 80.586205 -264.739178)
		(end 80.769714 -264.693654)
		(width 0.0889)
		(layer "In11.Cu")
		(net "M_F_CPU1_SB_CA<6>")
	)
	(arc
		(start 81.35239 -264.693654)
		(mid 81.535898 -264.739148)
		(end 81.71815 -264.688828)
		(width 0.0889)
		(layer "In11.Cu")
		(net "M_F_CPU1_SB_CA<6>")
	)
	(arc
		(start 78.544674 -264.700004)
		(mid 78.723006 -264.739101)
		(end 78.898496 -264.688828)
		(width 0.0889)
		(layer "In11.Cu")
		(net "M_F_CPU1_SB_CA<6>")
	)
	(arc
		(start 82.658204 -264.688828)
		(mid 82.94116 -264.612651)
		(end 83.224116 -264.688828)
		(width 0.0889)
		(layer "In11.Cu")
		(net "M_F_CPU1_SB_CA<6>")
	)
	(arc
		(start 80.778096 -264.688828)
		(mid 81.061052 -264.612651)
		(end 81.344008 -264.688828)
		(width 0.0889)
		(layer "In11.Cu")
		(net "M_F_CPU1_SB_CA<6>")
	)
	(arc
		(start 81.71815 -264.688828)
		(mid 82.001106 -264.612651)
		(end 82.284062 -264.688828)
		(width 0.0889)
		(layer "In11.Cu")
		(net "M_F_CPU1_SB_CA<6>")
	)
	(arc
		(start 83.598004 -264.688828)
		(mid 83.88096 -264.612651)
		(end 84.163916 -264.688828)
		(width 0.0889)
		(layer "In11.Cu")
		(net "M_F_CPU1_SB_CA<6>")
	)
	(arc
		(start 78.242668 -264.612628)
		(mid 78.25677 -264.61283)
		(end 78.270862 -264.61339)
		(width 0.0889)
		(layer "In11.Cu")
		(net "M_F_CPU1_SB_CA<6>")
	)
	(arc
		(start 82.292444 -264.693654)
		(mid 82.475952 -264.739148)
		(end 82.658204 -264.688828)
		(width 0.0889)
		(layer "In11.Cu")
		(net "M_F_CPU1_SB_CA<6>")
	)
	(arc
		(start 78.898496 -264.688828)
		(mid 79.17144 -264.612248)
		(end 79.447136 -264.67816)
		(width 0.0889)
		(layer "In11.Cu")
		(net "M_F_CPU1_SB_CA<6>")
	)
	(arc
		(start 78.270862 -264.61339)
		(mid 78.402216 -264.635864)
		(end 78.524608 -264.688574)
		(width 0.0889)
		(layer "In11.Cu")
		(net "M_F_CPU1_SB_CA<6>")
	)
	(arc
		(start 84.163916 -264.688828)
		(mid 84.320354 -264.737799)
		(end 84.482686 -264.71499)
		(width 0.0889)
		(layer "In11.Cu")
		(net "M_F_CPU1_SB_CA<6>")
	)
	(arc
		(start 79.46517 -264.688828)
		(mid 79.644157 -264.738998)
		(end 79.825088 -264.696448)
		(width 0.0889)
		(layer "In11.Cu")
		(net "M_F_CPU1_SB_CA<6>")
	)
	(segment
		(start 86.69782 -264.10031)
		(end 86.230968 -264.366248)
		(width 0.10668)
		(layer "F.Cu")
		(net "M_F_CPU1_SB_CA<5>")
	)
	(segment
		(start 86.077044 -264.100818)
		(end 86.230968 -264.366248)
		(width 0.0889)
		(layer "In11.Cu")
		(net "M_F_CPU1_SB_CA<5>")
	)
	(segment
		(start 85.10397 -264.043668)
		(end 85.112352 -264.038842)
		(width 0.0889)
		(layer "In11.Cu")
		(net "M_F_CPU1_SB_CA<5>")
	)
	(segment
		(start 83.589622 -264.038842)
		(end 83.598004 -264.043668)
		(width 0.0889)
		(layer "In11.Cu")
		(net "M_F_CPU1_SB_CA<5>")
	)
	(segment
		(start 76.386182 -264.009124)
		(end 79.643986 -264.013696)
		(width 0.0889)
		(layer "In11.Cu")
		(net "M_F_CPU1_SB_CA<5>")
	)
	(segment
		(start 76.004166 -264.165334)
		(end 76.135992 -264.165334)
		(width 0.0889)
		(layer "In11.Cu")
		(net "M_F_CPU1_SB_CA<5>")
	)
	(segment
		(start 18.032984 -264.910316)
		(end 60.1599 -264.910316)
		(width 0.14478)
		(layer "In11.Cu")
		(net "M_F_CPU1_SB_CA<5>")
	)
	(segment
		(start 80.39354 -264.049764)
		(end 80.403954 -264.043668)
		(width 0.0889)
		(layer "In11.Cu")
		(net "M_F_CPU1_SB_CA<5>")
	)
	(segment
		(start 60.1599 -264.910316)
		(end 60.904882 -264.165334)
		(width 0.14478)
		(layer "In11.Cu")
		(net "M_F_CPU1_SB_CA<5>")
	)
	(segment
		(start 17.608042 -265.335258)
		(end 18.032984 -264.910316)
		(width 0.14478)
		(layer "In11.Cu")
		(net "M_F_CPU1_SB_CA<5>")
	)
	(segment
		(start 81.344008 -264.043668)
		(end 81.35239 -264.038842)
		(width 0.0889)
		(layer "In11.Cu")
		(net "M_F_CPU1_SB_CA<5>")
	)
	(segment
		(start 85.981032 -264.075418)
		(end 86.077044 -264.100818)
		(width 0.0889)
		(layer "In11.Cu")
		(net "M_F_CPU1_SB_CA<5>")
	)
	(segment
		(start 80.769714 -264.038842)
		(end 80.778096 -264.043668)
		(width 0.0889)
		(layer "In11.Cu")
		(net "M_F_CPU1_SB_CA<5>")
	)
	(segment
		(start 60.904882 -264.165334)
		(end 76.004166 -264.165334)
		(width 0.14478)
		(layer "In11.Cu")
		(net "M_F_CPU1_SB_CA<5>")
	)
	(segment
		(start 84.529676 -264.038842)
		(end 84.538058 -264.043668)
		(width 0.0889)
		(layer "In11.Cu")
		(net "M_F_CPU1_SB_CA<5>")
	)
	(segment
		(start 76.216256 -264.13206)
		(end 76.306172 -264.042144)
		(width 0.0889)
		(layer "In11.Cu")
		(net "M_F_CPU1_SB_CA<5>")
	)
	(arc
		(start 84.538058 -264.043668)
		(mid 84.821014 -264.119845)
		(end 85.10397 -264.043668)
		(width 0.0889)
		(layer "In11.Cu")
		(net "M_F_CPU1_SB_CA<5>")
	)
	(arc
		(start 84.163916 -264.043668)
		(mid 84.346167 -263.993318)
		(end 84.529676 -264.038842)
		(width 0.0889)
		(layer "In11.Cu")
		(net "M_F_CPU1_SB_CA<5>")
	)
	(arc
		(start 81.35239 -264.038842)
		(mid 81.535898 -263.993348)
		(end 81.71815 -264.043668)
		(width 0.0889)
		(layer "In11.Cu")
		(net "M_F_CPU1_SB_CA<5>")
	)
	(arc
		(start 76.135992 -264.165334)
		(mid 76.179427 -264.156676)
		(end 76.216256 -264.13206)
		(width 0.0889)
		(layer "In11.Cu")
		(net "M_F_CPU1_SB_CA<5>")
	)
	(arc
		(start 79.643986 -264.013696)
		(mid 79.76591 -264.027323)
		(end 79.881984 -264.067036)
		(width 0.0889)
		(layer "In11.Cu")
		(net "M_F_CPU1_SB_CA<5>")
	)
	(arc
		(start 83.223862 -264.043668)
		(mid 83.406113 -263.993318)
		(end 83.589622 -264.038842)
		(width 0.0889)
		(layer "In11.Cu")
		(net "M_F_CPU1_SB_CA<5>")
	)
	(arc
		(start 76.306172 -264.042144)
		(mid 76.342896 -264.017699)
		(end 76.386182 -264.009124)
		(width 0.0889)
		(layer "In11.Cu")
		(net "M_F_CPU1_SB_CA<5>")
	)
	(arc
		(start 82.65795 -264.043668)
		(mid 82.940906 -264.119845)
		(end 83.223862 -264.043668)
		(width 0.0889)
		(layer "In11.Cu")
		(net "M_F_CPU1_SB_CA<5>")
	)
	(arc
		(start 85.112352 -264.038842)
		(mid 85.29586 -263.993348)
		(end 85.478112 -264.043668)
		(width 0.0889)
		(layer "In11.Cu")
		(net "M_F_CPU1_SB_CA<5>")
	)
	(arc
		(start 85.478112 -264.043668)
		(mid 85.725825 -264.118888)
		(end 85.981032 -264.075418)
		(width 0.0889)
		(layer "In11.Cu")
		(net "M_F_CPU1_SB_CA<5>")
	)
	(arc
		(start 80.403954 -264.043668)
		(mid 80.586205 -263.993318)
		(end 80.769714 -264.038842)
		(width 0.0889)
		(layer "In11.Cu")
		(net "M_F_CPU1_SB_CA<5>")
	)
	(arc
		(start 82.284062 -264.043668)
		(mid 82.471006 -263.993413)
		(end 82.65795 -264.043668)
		(width 0.0889)
		(layer "In11.Cu")
		(net "M_F_CPU1_SB_CA<5>")
	)
	(arc
		(start 81.71815 -264.043668)
		(mid 82.001106 -264.119845)
		(end 82.284062 -264.043668)
		(width 0.0889)
		(layer "In11.Cu")
		(net "M_F_CPU1_SB_CA<5>")
	)
	(arc
		(start 83.598004 -264.043668)
		(mid 83.88096 -264.119845)
		(end 84.163916 -264.043668)
		(width 0.0889)
		(layer "In11.Cu")
		(net "M_F_CPU1_SB_CA<5>")
	)
	(arc
		(start 79.881984 -264.067036)
		(mid 80.139827 -264.11976)
		(end 80.39354 -264.049764)
		(width 0.0889)
		(layer "In11.Cu")
		(net "M_F_CPU1_SB_CA<5>")
	)
	(arc
		(start 80.778096 -264.043668)
		(mid 81.061052 -264.119845)
		(end 81.344008 -264.043668)
		(width 0.0889)
		(layer "In11.Cu")
		(net "M_F_CPU1_SB_CA<5>")
	)
	(segment
		(start 86.22792 -263.290304)
		(end 85.761068 -263.556242)
		(width 0.10668)
		(layer "F.Cu")
		(net "M_F_CPU1_SB_CA<4>")
	)
	(segment
		(start 22.91461 -263.835134)
		(end 22.91461 -264.292334)
		(width 0.14478)
		(layer "In11.Cu")
		(net "M_F_CPU1_SB_CA<4>")
	)
	(segment
		(start 21.70811 -264.485374)
		(end 22.521164 -263.67232)
		(width 0.14478)
		(layer "In11.Cu")
		(net "M_F_CPU1_SB_CA<4>")
	)
	(segment
		(start 24.02713 -264.292334)
		(end 24.189944 -264.455148)
		(width 0.14478)
		(layer "In11.Cu")
		(net "M_F_CPU1_SB_CA<4>")
	)
	(segment
		(start 83.694016 -263.878822)
		(end 83.702398 -263.883648)
		(width 0.0889)
		(layer "In11.Cu")
		(net "M_F_CPU1_SB_CA<4>")
	)
	(segment
		(start 23.864316 -263.67232)
		(end 24.02713 -263.835134)
		(width 0.14478)
		(layer "In11.Cu")
		(net "M_F_CPU1_SB_CA<4>")
	)
	(segment
		(start 23.47087 -264.292334)
		(end 23.47087 -263.835134)
		(width 0.14478)
		(layer "In11.Cu")
		(net "M_F_CPU1_SB_CA<4>")
	)
	(segment
		(start 60.569602 -263.710674)
		(end 75.952096 -263.710674)
		(width 0.14478)
		(layer "In11.Cu")
		(net "M_F_CPU1_SB_CA<4>")
	)
	(segment
		(start 25.564592 -264.060178)
		(end 25.952958 -264.448544)
		(width 0.14478)
		(layer "In11.Cu")
		(net "M_F_CPU1_SB_CA<4>")
	)
	(segment
		(start 60.220098 -264.060178)
		(end 60.569602 -263.710674)
		(width 0.14478)
		(layer "In11.Cu")
		(net "M_F_CPU1_SB_CA<4>")
	)
	(segment
		(start 85.914992 -263.821672)
		(end 85.761068 -263.556242)
		(width 0.0889)
		(layer "In11.Cu")
		(net "M_F_CPU1_SB_CA<4>")
	)
	(segment
		(start 26.346404 -263.834626)
		(end 26.509218 -263.671812)
		(width 0.14478)
		(layer "In11.Cu")
		(net "M_F_CPU1_SB_CA<4>")
	)
	(segment
		(start 26.18359 -264.448544)
		(end 26.346404 -264.28573)
		(width 0.14478)
		(layer "In11.Cu")
		(net "M_F_CPU1_SB_CA<4>")
	)
	(segment
		(start 22.521164 -263.67232)
		(end 22.751796 -263.67232)
		(width 0.14478)
		(layer "In11.Cu")
		(net "M_F_CPU1_SB_CA<4>")
	)
	(segment
		(start 24.189944 -264.455148)
		(end 24.420576 -264.455148)
		(width 0.14478)
		(layer "In11.Cu")
		(net "M_F_CPU1_SB_CA<4>")
	)
	(segment
		(start 82.753962 -263.878822)
		(end 82.762344 -263.883648)
		(width 0.0889)
		(layer "In11.Cu")
		(net "M_F_CPU1_SB_CA<4>")
	)
	(segment
		(start 24.420576 -264.455148)
		(end 24.815546 -264.060178)
		(width 0.14478)
		(layer "In11.Cu")
		(net "M_F_CPU1_SB_CA<4>")
	)
	(segment
		(start 23.077424 -264.455148)
		(end 23.308056 -264.455148)
		(width 0.14478)
		(layer "In11.Cu")
		(net "M_F_CPU1_SB_CA<4>")
	)
	(segment
		(start 82.179668 -263.883648)
		(end 82.18805 -263.878822)
		(width 0.0889)
		(layer "In11.Cu")
		(net "M_F_CPU1_SB_CA<4>")
	)
	(segment
		(start 25.952958 -264.448544)
		(end 26.18359 -264.448544)
		(width 0.14478)
		(layer "In11.Cu")
		(net "M_F_CPU1_SB_CA<4>")
	)
	(segment
		(start 75.952096 -263.710674)
		(end 79.31023 -263.710674)
		(width 0.0889)
		(layer "In11.Cu")
		(net "M_F_CPU1_SB_CA<4>")
	)
	(segment
		(start 24.02713 -263.835134)
		(end 24.02713 -264.292334)
		(width 0.14478)
		(layer "In11.Cu")
		(net "M_F_CPU1_SB_CA<4>")
	)
	(segment
		(start 23.308056 -264.455148)
		(end 23.47087 -264.292334)
		(width 0.14478)
		(layer "In11.Cu")
		(net "M_F_CPU1_SB_CA<4>")
	)
	(segment
		(start 26.73985 -263.671812)
		(end 27.128216 -264.060178)
		(width 0.14478)
		(layer "In11.Cu")
		(net "M_F_CPU1_SB_CA<4>")
	)
	(segment
		(start 26.346404 -264.28573)
		(end 26.346404 -263.834626)
		(width 0.14478)
		(layer "In11.Cu")
		(net "M_F_CPU1_SB_CA<4>")
	)
	(segment
		(start 23.47087 -263.835134)
		(end 23.633684 -263.67232)
		(width 0.14478)
		(layer "In11.Cu")
		(net "M_F_CPU1_SB_CA<4>")
	)
	(segment
		(start 22.751796 -263.67232)
		(end 22.91461 -263.835134)
		(width 0.14478)
		(layer "In11.Cu")
		(net "M_F_CPU1_SB_CA<4>")
	)
	(segment
		(start 22.91461 -264.292334)
		(end 23.077424 -264.455148)
		(width 0.14478)
		(layer "In11.Cu")
		(net "M_F_CPU1_SB_CA<4>")
	)
	(segment
		(start 27.128216 -264.060178)
		(end 60.220098 -264.060178)
		(width 0.14478)
		(layer "In11.Cu")
		(net "M_F_CPU1_SB_CA<4>")
	)
	(segment
		(start 23.633684 -263.67232)
		(end 23.864316 -263.67232)
		(width 0.14478)
		(layer "In11.Cu")
		(net "M_F_CPU1_SB_CA<4>")
	)
	(segment
		(start 24.815546 -264.060178)
		(end 25.564592 -264.060178)
		(width 0.14478)
		(layer "In11.Cu")
		(net "M_F_CPU1_SB_CA<4>")
	)
	(segment
		(start 26.509218 -263.671812)
		(end 26.73985 -263.671812)
		(width 0.14478)
		(layer "In11.Cu")
		(net "M_F_CPU1_SB_CA<4>")
	)
	(segment
		(start 85.89264 -263.904984)
		(end 85.914992 -263.821672)
		(width 0.0889)
		(layer "In11.Cu")
		(net "M_F_CPU1_SB_CA<4>")
	)
	(arc
		(start 85.007958 -263.878822)
		(mid 85.290914 -263.802645)
		(end 85.57387 -263.878822)
		(width 0.0889)
		(layer "In11.Cu")
		(net "M_F_CPU1_SB_CA<4>")
	)
	(arc
		(start 82.18805 -263.878822)
		(mid 82.471006 -263.802645)
		(end 82.753962 -263.878822)
		(width 0.0889)
		(layer "In11.Cu")
		(net "M_F_CPU1_SB_CA<4>")
	)
	(arc
		(start 81.247996 -263.878822)
		(mid 81.530952 -263.802645)
		(end 81.813908 -263.878822)
		(width 0.0889)
		(layer "In11.Cu")
		(net "M_F_CPU1_SB_CA<4>")
	)
	(arc
		(start 83.128104 -263.878822)
		(mid 83.41106 -263.802645)
		(end 83.694016 -263.878822)
		(width 0.0889)
		(layer "In11.Cu")
		(net "M_F_CPU1_SB_CA<4>")
	)
	(arc
		(start 82.762344 -263.883648)
		(mid 82.945852 -263.929142)
		(end 83.128104 -263.878822)
		(width 0.0889)
		(layer "In11.Cu")
		(net "M_F_CPU1_SB_CA<4>")
	)
	(arc
		(start 85.57387 -263.878822)
		(mid 85.730308 -263.927793)
		(end 85.89264 -263.904984)
		(width 0.0889)
		(layer "In11.Cu")
		(net "M_F_CPU1_SB_CA<4>")
	)
	(arc
		(start 79.31023 -263.710674)
		(mid 79.633146 -263.753457)
		(end 79.9338 -263.878822)
		(width 0.0889)
		(layer "In11.Cu")
		(net "M_F_CPU1_SB_CA<4>")
	)
	(arc
		(start 84.63407 -263.878822)
		(mid 84.821014 -263.929077)
		(end 85.007958 -263.878822)
		(width 0.0889)
		(layer "In11.Cu")
		(net "M_F_CPU1_SB_CA<4>")
	)
	(arc
		(start 80.874108 -263.878822)
		(mid 81.061052 -263.929077)
		(end 81.247996 -263.878822)
		(width 0.0889)
		(layer "In11.Cu")
		(net "M_F_CPU1_SB_CA<4>")
	)
	(arc
		(start 81.813908 -263.878822)
		(mid 81.996159 -263.929172)
		(end 82.179668 -263.883648)
		(width 0.0889)
		(layer "In11.Cu")
		(net "M_F_CPU1_SB_CA<4>")
	)
	(arc
		(start 80.308196 -263.878822)
		(mid 80.591152 -263.802645)
		(end 80.874108 -263.878822)
		(width 0.0889)
		(layer "In11.Cu")
		(net "M_F_CPU1_SB_CA<4>")
	)
	(arc
		(start 83.702398 -263.883648)
		(mid 83.885906 -263.929142)
		(end 84.068158 -263.878822)
		(width 0.0889)
		(layer "In11.Cu")
		(net "M_F_CPU1_SB_CA<4>")
	)
	(arc
		(start 79.9338 -263.878822)
		(mid 80.120998 -263.929204)
		(end 80.308196 -263.878822)
		(width 0.0889)
		(layer "In11.Cu")
		(net "M_F_CPU1_SB_CA<4>")
	)
	(arc
		(start 84.068158 -263.878822)
		(mid 84.351114 -263.802645)
		(end 84.63407 -263.878822)
		(width 0.0889)
		(layer "In11.Cu")
		(net "M_F_CPU1_SB_CA<4>")
	)
	(segment
		(start 85.287866 -263.290304)
		(end 84.821014 -263.556242)
		(width 0.10668)
		(layer "F.Cu")
		(net "M_F_CPU1_SB_CA<3>")
	)
	(segment
		(start 83.694016 -263.233662)
		(end 83.702398 -263.228836)
		(width 0.0889)
		(layer "In11.Cu")
		(net "M_F_CPU1_SB_CA<3>")
	)
	(segment
		(start 84.66709 -263.290812)
		(end 84.821014 -263.556242)
		(width 0.0889)
		(layer "In11.Cu")
		(net "M_F_CPU1_SB_CA<3>")
	)
	(segment
		(start 75.978766 -263.210294)
		(end 76.518516 -263.210294)
		(width 0.0889)
		(layer "In11.Cu")
		(net "M_F_CPU1_SB_CA<3>")
	)
	(segment
		(start 17.608042 -263.635236)
		(end 18.032984 -263.210294)
		(width 0.14478)
		(layer "In11.Cu")
		(net "M_F_CPU1_SB_CA<3>")
	)
	(segment
		(start 76.518516 -263.210294)
		(end 76.827126 -262.901684)
		(width 0.0889)
		(layer "In11.Cu")
		(net "M_F_CPU1_SB_CA<3>")
	)
	(segment
		(start 82.179668 -263.228836)
		(end 82.18805 -263.233662)
		(width 0.0889)
		(layer "In11.Cu")
		(net "M_F_CPU1_SB_CA<3>")
	)
	(segment
		(start 18.032984 -263.210294)
		(end 75.978766 -263.210294)
		(width 0.14478)
		(layer "In11.Cu")
		(net "M_F_CPU1_SB_CA<3>")
	)
	(segment
		(start 79.934308 -263.233916)
		(end 79.950564 -263.224518)
		(width 0.0889)
		(layer "In11.Cu")
		(net "M_F_CPU1_SB_CA<3>")
	)
	(segment
		(start 78.333854 -263.309862)
		(end 79.65186 -263.309862)
		(width 0.0889)
		(layer "In11.Cu")
		(net "M_F_CPU1_SB_CA<3>")
	)
	(segment
		(start 77.925676 -262.901684)
		(end 78.333854 -263.309862)
		(width 0.0889)
		(layer "In11.Cu")
		(net "M_F_CPU1_SB_CA<3>")
	)
	(segment
		(start 84.571078 -263.265412)
		(end 84.66709 -263.290812)
		(width 0.0889)
		(layer "In11.Cu")
		(net "M_F_CPU1_SB_CA<3>")
	)
	(segment
		(start 76.827126 -262.901684)
		(end 77.925676 -262.901684)
		(width 0.0889)
		(layer "In11.Cu")
		(net "M_F_CPU1_SB_CA<3>")
	)
	(segment
		(start 82.753962 -263.233662)
		(end 82.762344 -263.228836)
		(width 0.0889)
		(layer "In11.Cu")
		(net "M_F_CPU1_SB_CA<3>")
	)
	(arc
		(start 80.308196 -263.233662)
		(mid 80.591152 -263.309839)
		(end 80.874108 -263.233662)
		(width 0.0889)
		(layer "In11.Cu")
		(net "M_F_CPU1_SB_CA<3>")
	)
	(arc
		(start 81.247996 -263.233662)
		(mid 81.530952 -263.309839)
		(end 81.813908 -263.233662)
		(width 0.0889)
		(layer "In11.Cu")
		(net "M_F_CPU1_SB_CA<3>")
	)
	(arc
		(start 84.068158 -263.233662)
		(mid 84.315871 -263.308882)
		(end 84.571078 -263.265412)
		(width 0.0889)
		(layer "In11.Cu")
		(net "M_F_CPU1_SB_CA<3>")
	)
	(arc
		(start 79.65186 -263.309862)
		(mid 79.798108 -263.290557)
		(end 79.934308 -263.233916)
		(width 0.0889)
		(layer "In11.Cu")
		(net "M_F_CPU1_SB_CA<3>")
	)
	(arc
		(start 81.813908 -263.233662)
		(mid 81.996159 -263.183312)
		(end 82.179668 -263.228836)
		(width 0.0889)
		(layer "In11.Cu")
		(net "M_F_CPU1_SB_CA<3>")
	)
	(arc
		(start 83.128104 -263.233662)
		(mid 83.41106 -263.309839)
		(end 83.694016 -263.233662)
		(width 0.0889)
		(layer "In11.Cu")
		(net "M_F_CPU1_SB_CA<3>")
	)
	(arc
		(start 79.950564 -263.224518)
		(mid 80.130546 -263.183418)
		(end 80.308196 -263.233662)
		(width 0.0889)
		(layer "In11.Cu")
		(net "M_F_CPU1_SB_CA<3>")
	)
	(arc
		(start 82.762344 -263.228836)
		(mid 82.945852 -263.183342)
		(end 83.128104 -263.233662)
		(width 0.0889)
		(layer "In11.Cu")
		(net "M_F_CPU1_SB_CA<3>")
	)
	(arc
		(start 82.18805 -263.233662)
		(mid 82.471006 -263.309839)
		(end 82.753962 -263.233662)
		(width 0.0889)
		(layer "In11.Cu")
		(net "M_F_CPU1_SB_CA<3>")
	)
	(arc
		(start 80.874108 -263.233662)
		(mid 81.061052 -263.183407)
		(end 81.247996 -263.233662)
		(width 0.0889)
		(layer "In11.Cu")
		(net "M_F_CPU1_SB_CA<3>")
	)
	(arc
		(start 83.702398 -263.228836)
		(mid 83.885906 -263.183342)
		(end 84.068158 -263.233662)
		(width 0.0889)
		(layer "In11.Cu")
		(net "M_F_CPU1_SB_CA<3>")
	)
	(segment
		(start 84.817966 -262.480298)
		(end 84.351114 -262.746236)
		(width 0.10668)
		(layer "F.Cu")
		(net "M_F_CPU1_SB_CA<2>")
	)
	(segment
		(start 24.408638 -262.754872)
		(end 24.795988 -262.367522)
		(width 0.14478)
		(layer "In11.Cu")
		(net "M_F_CPU1_SB_CA<2>")
	)
	(segment
		(start 22.739858 -261.984236)
		(end 22.902672 -262.14705)
		(width 0.14478)
		(layer "In11.Cu")
		(net "M_F_CPU1_SB_CA<2>")
	)
	(segment
		(start 28.12542 -262.749284)
		(end 28.356052 -262.749284)
		(width 0.14478)
		(layer "In11.Cu")
		(net "M_F_CPU1_SB_CA<2>")
	)
	(segment
		(start 78.474824 -263.105646)
		(end 79.629 -263.105646)
		(width 0.0889)
		(layer "In11.Cu")
		(net "M_F_CPU1_SB_CA<2>")
	)
	(segment
		(start 23.852378 -261.984236)
		(end 24.015192 -262.14705)
		(width 0.14478)
		(layer "In11.Cu")
		(net "M_F_CPU1_SB_CA<2>")
	)
	(segment
		(start 84.482686 -263.094978)
		(end 84.505038 -263.011666)
		(width 0.0889)
		(layer "In11.Cu")
		(net "M_F_CPU1_SB_CA<2>")
	)
	(segment
		(start 27.243532 -262.749284)
		(end 27.406346 -262.58647)
		(width 0.14478)
		(layer "In11.Cu")
		(net "M_F_CPU1_SB_CA<2>")
	)
	(segment
		(start 75.981052 -262.767826)
		(end 76.35113 -262.767826)
		(width 0.0889)
		(layer "In11.Cu")
		(net "M_F_CPU1_SB_CA<2>")
	)
	(segment
		(start 27.799792 -261.98576)
		(end 27.962606 -262.148574)
		(width 0.14478)
		(layer "In11.Cu")
		(net "M_F_CPU1_SB_CA<2>")
	)
	(segment
		(start 77.922374 -262.600186)
		(end 78.39456 -263.072372)
		(width 0.0889)
		(layer "In11.Cu")
		(net "M_F_CPU1_SB_CA<2>")
	)
	(segment
		(start 28.356052 -262.749284)
		(end 28.737814 -262.367522)
		(width 0.14478)
		(layer "In11.Cu")
		(net "M_F_CPU1_SB_CA<2>")
	)
	(segment
		(start 81.344008 -263.068816)
		(end 81.35239 -263.073642)
		(width 0.0889)
		(layer "In11.Cu")
		(net "M_F_CPU1_SB_CA<2>")
	)
	(segment
		(start 27.962606 -262.148574)
		(end 27.962606 -262.58647)
		(width 0.14478)
		(layer "In11.Cu")
		(net "M_F_CPU1_SB_CA<2>")
	)
	(segment
		(start 27.406346 -262.148574)
		(end 27.56916 -261.98576)
		(width 0.14478)
		(layer "In11.Cu")
		(net "M_F_CPU1_SB_CA<2>")
	)
	(segment
		(start 22.902672 -262.592058)
		(end 23.065486 -262.754872)
		(width 0.14478)
		(layer "In11.Cu")
		(net "M_F_CPU1_SB_CA<2>")
	)
	(segment
		(start 27.0129 -262.749284)
		(end 27.243532 -262.749284)
		(width 0.14478)
		(layer "In11.Cu")
		(net "M_F_CPU1_SB_CA<2>")
	)
	(segment
		(start 26.850086 -262.58647)
		(end 27.0129 -262.749284)
		(width 0.14478)
		(layer "In11.Cu")
		(net "M_F_CPU1_SB_CA<2>")
	)
	(segment
		(start 24.795988 -262.367522)
		(end 25.518618 -262.367522)
		(width 0.14478)
		(layer "In11.Cu")
		(net "M_F_CPU1_SB_CA<2>")
	)
	(segment
		(start 83.589622 -263.073642)
		(end 83.598004 -263.068816)
		(width 0.0889)
		(layer "In11.Cu")
		(net "M_F_CPU1_SB_CA<2>")
	)
	(segment
		(start 27.406346 -262.58647)
		(end 27.406346 -262.148574)
		(width 0.14478)
		(layer "In11.Cu")
		(net "M_F_CPU1_SB_CA<2>")
	)
	(segment
		(start 25.518618 -262.367522)
		(end 25.90038 -262.749284)
		(width 0.14478)
		(layer "In11.Cu")
		(net "M_F_CPU1_SB_CA<2>")
	)
	(segment
		(start 23.621746 -261.984236)
		(end 23.852378 -261.984236)
		(width 0.14478)
		(layer "In11.Cu")
		(net "M_F_CPU1_SB_CA<2>")
	)
	(segment
		(start 60.822332 -262.367522)
		(end 61.21019 -262.75538)
		(width 0.14478)
		(layer "In11.Cu")
		(net "M_F_CPU1_SB_CA<2>")
	)
	(segment
		(start 23.458932 -262.592058)
		(end 23.458932 -262.14705)
		(width 0.14478)
		(layer "In11.Cu")
		(net "M_F_CPU1_SB_CA<2>")
	)
	(segment
		(start 25.90038 -262.749284)
		(end 26.131012 -262.749284)
		(width 0.14478)
		(layer "In11.Cu")
		(net "M_F_CPU1_SB_CA<2>")
	)
	(segment
		(start 24.015192 -262.14705)
		(end 24.015192 -262.592058)
		(width 0.14478)
		(layer "In11.Cu")
		(net "M_F_CPU1_SB_CA<2>")
	)
	(segment
		(start 24.015192 -262.592058)
		(end 24.178006 -262.754872)
		(width 0.14478)
		(layer "In11.Cu")
		(net "M_F_CPU1_SB_CA<2>")
	)
	(segment
		(start 26.293826 -262.58647)
		(end 26.293826 -262.148574)
		(width 0.14478)
		(layer "In11.Cu")
		(net "M_F_CPU1_SB_CA<2>")
	)
	(segment
		(start 23.065486 -262.754872)
		(end 23.296118 -262.754872)
		(width 0.14478)
		(layer "In11.Cu")
		(net "M_F_CPU1_SB_CA<2>")
	)
	(segment
		(start 80.769714 -263.073642)
		(end 80.778096 -263.068816)
		(width 0.0889)
		(layer "In11.Cu")
		(net "M_F_CPU1_SB_CA<2>")
	)
	(segment
		(start 75.968606 -262.75538)
		(end 75.981052 -262.767826)
		(width 0.0889)
		(layer "In11.Cu")
		(net "M_F_CPU1_SB_CA<2>")
	)
	(segment
		(start 76.35113 -262.767826)
		(end 76.51877 -262.600186)
		(width 0.0889)
		(layer "In11.Cu")
		(net "M_F_CPU1_SB_CA<2>")
	)
	(segment
		(start 84.505038 -263.011666)
		(end 84.351114 -262.746236)
		(width 0.0889)
		(layer "In11.Cu")
		(net "M_F_CPU1_SB_CA<2>")
	)
	(segment
		(start 76.51877 -262.600186)
		(end 77.922374 -262.600186)
		(width 0.0889)
		(layer "In11.Cu")
		(net "M_F_CPU1_SB_CA<2>")
	)
	(segment
		(start 27.962606 -262.58647)
		(end 28.12542 -262.749284)
		(width 0.14478)
		(layer "In11.Cu")
		(net "M_F_CPU1_SB_CA<2>")
	)
	(segment
		(start 27.56916 -261.98576)
		(end 27.799792 -261.98576)
		(width 0.14478)
		(layer "In11.Cu")
		(net "M_F_CPU1_SB_CA<2>")
	)
	(segment
		(start 22.509226 -261.984236)
		(end 22.739858 -261.984236)
		(width 0.14478)
		(layer "In11.Cu")
		(net "M_F_CPU1_SB_CA<2>")
	)
	(segment
		(start 23.296118 -262.754872)
		(end 23.458932 -262.592058)
		(width 0.14478)
		(layer "In11.Cu")
		(net "M_F_CPU1_SB_CA<2>")
	)
	(segment
		(start 26.850086 -262.148574)
		(end 26.850086 -262.58647)
		(width 0.14478)
		(layer "In11.Cu")
		(net "M_F_CPU1_SB_CA<2>")
	)
	(segment
		(start 22.902672 -262.14705)
		(end 22.902672 -262.592058)
		(width 0.14478)
		(layer "In11.Cu")
		(net "M_F_CPU1_SB_CA<2>")
	)
	(segment
		(start 61.21019 -262.75538)
		(end 75.968606 -262.75538)
		(width 0.14478)
		(layer "In11.Cu")
		(net "M_F_CPU1_SB_CA<2>")
	)
	(segment
		(start 21.70811 -262.785352)
		(end 22.509226 -261.984236)
		(width 0.14478)
		(layer "In11.Cu")
		(net "M_F_CPU1_SB_CA<2>")
	)
	(segment
		(start 26.293826 -262.148574)
		(end 26.45664 -261.98576)
		(width 0.14478)
		(layer "In11.Cu")
		(net "M_F_CPU1_SB_CA<2>")
	)
	(segment
		(start 26.45664 -261.98576)
		(end 26.687272 -261.98576)
		(width 0.14478)
		(layer "In11.Cu")
		(net "M_F_CPU1_SB_CA<2>")
	)
	(segment
		(start 24.178006 -262.754872)
		(end 24.408638 -262.754872)
		(width 0.14478)
		(layer "In11.Cu")
		(net "M_F_CPU1_SB_CA<2>")
	)
	(segment
		(start 26.687272 -261.98576)
		(end 26.850086 -262.148574)
		(width 0.14478)
		(layer "In11.Cu")
		(net "M_F_CPU1_SB_CA<2>")
	)
	(segment
		(start 28.737814 -262.367522)
		(end 60.822332 -262.367522)
		(width 0.14478)
		(layer "In11.Cu")
		(net "M_F_CPU1_SB_CA<2>")
	)
	(segment
		(start 26.131012 -262.749284)
		(end 26.293826 -262.58647)
		(width 0.14478)
		(layer "In11.Cu")
		(net "M_F_CPU1_SB_CA<2>")
	)
	(segment
		(start 23.458932 -262.14705)
		(end 23.621746 -261.984236)
		(width 0.14478)
		(layer "In11.Cu")
		(net "M_F_CPU1_SB_CA<2>")
	)
	(arc
		(start 78.39456 -263.072372)
		(mid 78.431371 -263.097032)
		(end 78.474824 -263.105646)
		(width 0.0889)
		(layer "In11.Cu")
		(net "M_F_CPU1_SB_CA<2>")
	)
	(arc
		(start 84.163916 -263.068816)
		(mid 84.320354 -263.117787)
		(end 84.482686 -263.094978)
		(width 0.0889)
		(layer "In11.Cu")
		(net "M_F_CPU1_SB_CA<2>")
	)
	(arc
		(start 81.35239 -263.073642)
		(mid 81.535898 -263.119136)
		(end 81.71815 -263.068816)
		(width 0.0889)
		(layer "In11.Cu")
		(net "M_F_CPU1_SB_CA<2>")
	)
	(arc
		(start 80.403954 -263.068816)
		(mid 80.586205 -263.119166)
		(end 80.769714 -263.073642)
		(width 0.0889)
		(layer "In11.Cu")
		(net "M_F_CPU1_SB_CA<2>")
	)
	(arc
		(start 83.223862 -263.068816)
		(mid 83.406113 -263.119166)
		(end 83.589622 -263.073642)
		(width 0.0889)
		(layer "In11.Cu")
		(net "M_F_CPU1_SB_CA<2>")
	)
	(arc
		(start 82.284062 -263.068816)
		(mid 82.471006 -263.119071)
		(end 82.65795 -263.068816)
		(width 0.0889)
		(layer "In11.Cu")
		(net "M_F_CPU1_SB_CA<2>")
	)
	(arc
		(start 79.874872 -263.049004)
		(mid 80.141878 -262.992951)
		(end 80.403954 -263.068816)
		(width 0.0889)
		(layer "In11.Cu")
		(net "M_F_CPU1_SB_CA<2>")
	)
	(arc
		(start 82.65795 -263.068816)
		(mid 82.940906 -262.992639)
		(end 83.223862 -263.068816)
		(width 0.0889)
		(layer "In11.Cu")
		(net "M_F_CPU1_SB_CA<2>")
	)
	(arc
		(start 79.629 -263.105646)
		(mid 79.755153 -263.091282)
		(end 79.874872 -263.049004)
		(width 0.0889)
		(layer "In11.Cu")
		(net "M_F_CPU1_SB_CA<2>")
	)
	(arc
		(start 81.71815 -263.068816)
		(mid 82.001106 -262.992639)
		(end 82.284062 -263.068816)
		(width 0.0889)
		(layer "In11.Cu")
		(net "M_F_CPU1_SB_CA<2>")
	)
	(arc
		(start 83.598004 -263.068816)
		(mid 83.88096 -262.992639)
		(end 84.163916 -263.068816)
		(width 0.0889)
		(layer "In11.Cu")
		(net "M_F_CPU1_SB_CA<2>")
	)
	(arc
		(start 80.778096 -263.068816)
		(mid 81.061052 -262.992639)
		(end 81.344008 -263.068816)
		(width 0.0889)
		(layer "In11.Cu")
		(net "M_F_CPU1_SB_CA<2>")
	)
	(segment
		(start 86.69782 -262.480298)
		(end 86.230968 -262.746236)
		(width 0.10668)
		(layer "F.Cu")
		(net "M_F_CPU1_SB_CA<1>")
	)
	(segment
		(start 61.420502 -262.246364)
		(end 75.986386 -262.246364)
		(width 0.14478)
		(layer "In11.Cu")
		(net "M_F_CPU1_SB_CA<1>")
	)
	(segment
		(start 60.68441 -261.510272)
		(end 61.420502 -262.246364)
		(width 0.14478)
		(layer "In11.Cu")
		(net "M_F_CPU1_SB_CA<1>")
	)
	(segment
		(start 81.344008 -262.423656)
		(end 81.35239 -262.41883)
		(width 0.0889)
		(layer "In11.Cu")
		(net "M_F_CPU1_SB_CA<1>")
	)
	(segment
		(start 17.608042 -261.935214)
		(end 18.032984 -261.510272)
		(width 0.14478)
		(layer "In11.Cu")
		(net "M_F_CPU1_SB_CA<1>")
	)
	(segment
		(start 18.032984 -261.510272)
		(end 60.68441 -261.510272)
		(width 0.14478)
		(layer "In11.Cu")
		(net "M_F_CPU1_SB_CA<1>")
	)
	(segment
		(start 80.39354 -262.429752)
		(end 80.403954 -262.423656)
		(width 0.0889)
		(layer "In11.Cu")
		(net "M_F_CPU1_SB_CA<1>")
	)
	(segment
		(start 75.986386 -262.246364)
		(end 75.993244 -262.239506)
		(width 0.0889)
		(layer "In11.Cu")
		(net "M_F_CPU1_SB_CA<1>")
	)
	(segment
		(start 84.529676 -262.41883)
		(end 84.538058 -262.423656)
		(width 0.0889)
		(layer "In11.Cu")
		(net "M_F_CPU1_SB_CA<1>")
	)
	(segment
		(start 86.077044 -262.480806)
		(end 86.230968 -262.746236)
		(width 0.0889)
		(layer "In11.Cu")
		(net "M_F_CPU1_SB_CA<1>")
	)
	(segment
		(start 85.981032 -262.455406)
		(end 86.077044 -262.480806)
		(width 0.0889)
		(layer "In11.Cu")
		(net "M_F_CPU1_SB_CA<1>")
	)
	(segment
		(start 83.589622 -262.41883)
		(end 83.598004 -262.423656)
		(width 0.0889)
		(layer "In11.Cu")
		(net "M_F_CPU1_SB_CA<1>")
	)
	(segment
		(start 80.769714 -262.41883)
		(end 80.778096 -262.423656)
		(width 0.0889)
		(layer "In11.Cu")
		(net "M_F_CPU1_SB_CA<1>")
	)
	(segment
		(start 85.10397 -262.423656)
		(end 85.112352 -262.41883)
		(width 0.0889)
		(layer "In11.Cu")
		(net "M_F_CPU1_SB_CA<1>")
	)
	(segment
		(start 75.993244 -262.239506)
		(end 79.156306 -262.239506)
		(width 0.0889)
		(layer "In11.Cu")
		(net "M_F_CPU1_SB_CA<1>")
	)
	(arc
		(start 82.284062 -262.423656)
		(mid 82.471006 -262.373401)
		(end 82.65795 -262.423656)
		(width 0.0889)
		(layer "In11.Cu")
		(net "M_F_CPU1_SB_CA<1>")
	)
	(arc
		(start 83.598004 -262.423656)
		(mid 83.88096 -262.499833)
		(end 84.163916 -262.423656)
		(width 0.0889)
		(layer "In11.Cu")
		(net "M_F_CPU1_SB_CA<1>")
	)
	(arc
		(start 85.112352 -262.41883)
		(mid 85.29586 -262.373336)
		(end 85.478112 -262.423656)
		(width 0.0889)
		(layer "In11.Cu")
		(net "M_F_CPU1_SB_CA<1>")
	)
	(arc
		(start 85.478112 -262.423656)
		(mid 85.725825 -262.498876)
		(end 85.981032 -262.455406)
		(width 0.0889)
		(layer "In11.Cu")
		(net "M_F_CPU1_SB_CA<1>")
	)
	(arc
		(start 80.778096 -262.423656)
		(mid 81.061052 -262.499833)
		(end 81.344008 -262.423656)
		(width 0.0889)
		(layer "In11.Cu")
		(net "M_F_CPU1_SB_CA<1>")
	)
	(arc
		(start 81.35239 -262.41883)
		(mid 81.535898 -262.373336)
		(end 81.71815 -262.423656)
		(width 0.0889)
		(layer "In11.Cu")
		(net "M_F_CPU1_SB_CA<1>")
	)
	(arc
		(start 79.837788 -262.423656)
		(mid 80.114855 -262.499927)
		(end 80.39354 -262.429752)
		(width 0.0889)
		(layer "In11.Cu")
		(net "M_F_CPU1_SB_CA<1>")
	)
	(arc
		(start 80.403954 -262.423656)
		(mid 80.586205 -262.373306)
		(end 80.769714 -262.41883)
		(width 0.0889)
		(layer "In11.Cu")
		(net "M_F_CPU1_SB_CA<1>")
	)
	(arc
		(start 79.156306 -262.239506)
		(mid 79.509268 -262.286354)
		(end 79.837788 -262.423656)
		(width 0.0889)
		(layer "In11.Cu")
		(net "M_F_CPU1_SB_CA<1>")
	)
	(arc
		(start 81.71815 -262.423656)
		(mid 82.001106 -262.499833)
		(end 82.284062 -262.423656)
		(width 0.0889)
		(layer "In11.Cu")
		(net "M_F_CPU1_SB_CA<1>")
	)
	(arc
		(start 84.163916 -262.423656)
		(mid 84.346167 -262.373306)
		(end 84.529676 -262.41883)
		(width 0.0889)
		(layer "In11.Cu")
		(net "M_F_CPU1_SB_CA<1>")
	)
	(arc
		(start 84.538058 -262.423656)
		(mid 84.821014 -262.499833)
		(end 85.10397 -262.423656)
		(width 0.0889)
		(layer "In11.Cu")
		(net "M_F_CPU1_SB_CA<1>")
	)
	(arc
		(start 83.223862 -262.423656)
		(mid 83.406113 -262.373306)
		(end 83.589622 -262.41883)
		(width 0.0889)
		(layer "In11.Cu")
		(net "M_F_CPU1_SB_CA<1>")
	)
	(arc
		(start 82.65795 -262.423656)
		(mid 82.940906 -262.499833)
		(end 83.223862 -262.423656)
		(width 0.0889)
		(layer "In11.Cu")
		(net "M_F_CPU1_SB_CA<1>")
	)
	(segment
		(start 86.22792 -261.670292)
		(end 85.761068 -261.93623)
		(width 0.10668)
		(layer "F.Cu")
		(net "M_F_CPU1_SB_CA<0>")
	)
	(segment
		(start 25.153874 -260.885686)
		(end 25.316688 -261.0485)
		(width 0.14478)
		(layer "In11.Cu")
		(net "M_F_CPU1_SB_CA<0>")
	)
	(segment
		(start 25.153874 -260.420866)
		(end 25.153874 -260.885686)
		(width 0.14478)
		(layer "In11.Cu")
		(net "M_F_CPU1_SB_CA<0>")
	)
	(segment
		(start 75.948032 -261.77621)
		(end 75.949048 -261.777226)
		(width 0.0889)
		(layer "In11.Cu")
		(net "M_F_CPU1_SB_CA<0>")
	)
	(segment
		(start 25.710134 -260.805168)
		(end 25.854914 -260.660388)
		(width 0.14478)
		(layer "In11.Cu")
		(net "M_F_CPU1_SB_CA<0>")
	)
	(segment
		(start 61.763148 -261.77621)
		(end 75.948032 -261.77621)
		(width 0.14478)
		(layer "In11.Cu")
		(net "M_F_CPU1_SB_CA<0>")
	)
	(segment
		(start 85.914992 -262.20166)
		(end 85.761068 -261.93623)
		(width 0.0889)
		(layer "In11.Cu")
		(net "M_F_CPU1_SB_CA<0>")
	)
	(segment
		(start 25.54732 -261.0485)
		(end 25.710134 -260.885686)
		(width 0.14478)
		(layer "In11.Cu")
		(net "M_F_CPU1_SB_CA<0>")
	)
	(segment
		(start 75.949048 -261.777226)
		(end 76.53147 -261.777226)
		(width 0.0889)
		(layer "In11.Cu")
		(net "M_F_CPU1_SB_CA<0>")
	)
	(segment
		(start 24.204168 -261.0485)
		(end 24.4348 -261.0485)
		(width 0.14478)
		(layer "In11.Cu")
		(net "M_F_CPU1_SB_CA<0>")
	)
	(segment
		(start 25.710134 -260.885686)
		(end 25.710134 -260.805168)
		(width 0.14478)
		(layer "In11.Cu")
		(net "M_F_CPU1_SB_CA<0>")
	)
	(segment
		(start 24.4348 -261.0485)
		(end 24.597614 -260.885686)
		(width 0.14478)
		(layer "In11.Cu")
		(net "M_F_CPU1_SB_CA<0>")
	)
	(segment
		(start 23.485094 -260.420866)
		(end 23.647908 -260.258052)
		(width 0.14478)
		(layer "In11.Cu")
		(net "M_F_CPU1_SB_CA<0>")
	)
	(segment
		(start 24.597614 -260.420866)
		(end 24.760428 -260.258052)
		(width 0.14478)
		(layer "In11.Cu")
		(net "M_F_CPU1_SB_CA<0>")
	)
	(segment
		(start 82.179668 -262.263636)
		(end 82.18805 -262.25881)
		(width 0.0889)
		(layer "In11.Cu")
		(net "M_F_CPU1_SB_CA<0>")
	)
	(segment
		(start 22.535388 -260.258052)
		(end 22.76602 -260.258052)
		(width 0.14478)
		(layer "In11.Cu")
		(net "M_F_CPU1_SB_CA<0>")
	)
	(segment
		(start 85.89264 -262.284972)
		(end 85.914992 -262.20166)
		(width 0.0889)
		(layer "In11.Cu")
		(net "M_F_CPU1_SB_CA<0>")
	)
	(segment
		(start 24.041354 -260.885686)
		(end 24.204168 -261.0485)
		(width 0.14478)
		(layer "In11.Cu")
		(net "M_F_CPU1_SB_CA<0>")
	)
	(segment
		(start 24.99106 -260.258052)
		(end 25.153874 -260.420866)
		(width 0.14478)
		(layer "In11.Cu")
		(net "M_F_CPU1_SB_CA<0>")
	)
	(segment
		(start 25.316688 -261.0485)
		(end 25.54732 -261.0485)
		(width 0.14478)
		(layer "In11.Cu")
		(net "M_F_CPU1_SB_CA<0>")
	)
	(segment
		(start 23.647908 -260.258052)
		(end 23.87854 -260.258052)
		(width 0.14478)
		(layer "In11.Cu")
		(net "M_F_CPU1_SB_CA<0>")
	)
	(segment
		(start 82.753962 -262.25881)
		(end 82.762344 -262.263636)
		(width 0.0889)
		(layer "In11.Cu")
		(net "M_F_CPU1_SB_CA<0>")
	)
	(segment
		(start 23.87854 -260.258052)
		(end 24.041354 -260.420866)
		(width 0.14478)
		(layer "In11.Cu")
		(net "M_F_CPU1_SB_CA<0>")
	)
	(segment
		(start 23.485094 -260.885686)
		(end 23.485094 -260.420866)
		(width 0.14478)
		(layer "In11.Cu")
		(net "M_F_CPU1_SB_CA<0>")
	)
	(segment
		(start 24.597614 -260.885686)
		(end 24.597614 -260.420866)
		(width 0.14478)
		(layer "In11.Cu")
		(net "M_F_CPU1_SB_CA<0>")
	)
	(segment
		(start 76.53147 -261.777226)
		(end 76.764896 -262.010652)
		(width 0.0889)
		(layer "In11.Cu")
		(net "M_F_CPU1_SB_CA<0>")
	)
	(segment
		(start 83.694016 -262.25881)
		(end 83.702398 -262.263636)
		(width 0.0889)
		(layer "In11.Cu")
		(net "M_F_CPU1_SB_CA<0>")
	)
	(segment
		(start 23.32228 -261.0485)
		(end 23.485094 -260.885686)
		(width 0.14478)
		(layer "In11.Cu")
		(net "M_F_CPU1_SB_CA<0>")
	)
	(segment
		(start 22.76602 -260.258052)
		(end 22.928834 -260.420866)
		(width 0.14478)
		(layer "In11.Cu")
		(net "M_F_CPU1_SB_CA<0>")
	)
	(segment
		(start 24.760428 -260.258052)
		(end 24.99106 -260.258052)
		(width 0.14478)
		(layer "In11.Cu")
		(net "M_F_CPU1_SB_CA<0>")
	)
	(segment
		(start 25.854914 -260.660388)
		(end 60.647326 -260.660388)
		(width 0.14478)
		(layer "In11.Cu")
		(net "M_F_CPU1_SB_CA<0>")
	)
	(segment
		(start 21.70811 -261.08533)
		(end 22.535388 -260.258052)
		(width 0.14478)
		(layer "In11.Cu")
		(net "M_F_CPU1_SB_CA<0>")
	)
	(segment
		(start 24.041354 -260.420866)
		(end 24.041354 -260.885686)
		(width 0.14478)
		(layer "In11.Cu")
		(net "M_F_CPU1_SB_CA<0>")
	)
	(segment
		(start 22.928834 -260.420866)
		(end 22.928834 -260.885686)
		(width 0.14478)
		(layer "In11.Cu")
		(net "M_F_CPU1_SB_CA<0>")
	)
	(segment
		(start 22.928834 -260.885686)
		(end 23.091648 -261.0485)
		(width 0.14478)
		(layer "In11.Cu")
		(net "M_F_CPU1_SB_CA<0>")
	)
	(segment
		(start 23.091648 -261.0485)
		(end 23.32228 -261.0485)
		(width 0.14478)
		(layer "In11.Cu")
		(net "M_F_CPU1_SB_CA<0>")
	)
	(segment
		(start 60.647326 -260.660388)
		(end 61.763148 -261.77621)
		(width 0.14478)
		(layer "In11.Cu")
		(net "M_F_CPU1_SB_CA<0>")
	)
	(segment
		(start 76.84516 -262.043926)
		(end 79.137002 -262.043926)
		(width 0.0889)
		(layer "In11.Cu")
		(net "M_F_CPU1_SB_CA<0>")
	)
	(arc
		(start 76.764896 -262.010652)
		(mid 76.801707 -262.035312)
		(end 76.84516 -262.043926)
		(width 0.0889)
		(layer "In11.Cu")
		(net "M_F_CPU1_SB_CA<0>")
	)
	(arc
		(start 84.068158 -262.25881)
		(mid 84.351114 -262.182633)
		(end 84.63407 -262.25881)
		(width 0.0889)
		(layer "In11.Cu")
		(net "M_F_CPU1_SB_CA<0>")
	)
	(arc
		(start 81.813908 -262.25881)
		(mid 81.996159 -262.30916)
		(end 82.179668 -262.263636)
		(width 0.0889)
		(layer "In11.Cu")
		(net "M_F_CPU1_SB_CA<0>")
	)
	(arc
		(start 83.702398 -262.263636)
		(mid 83.885906 -262.30913)
		(end 84.068158 -262.25881)
		(width 0.0889)
		(layer "In11.Cu")
		(net "M_F_CPU1_SB_CA<0>")
	)
	(arc
		(start 79.9338 -262.25881)
		(mid 80.120998 -262.309192)
		(end 80.308196 -262.25881)
		(width 0.0889)
		(layer "In11.Cu")
		(net "M_F_CPU1_SB_CA<0>")
	)
	(arc
		(start 81.247996 -262.25881)
		(mid 81.530952 -262.182633)
		(end 81.813908 -262.25881)
		(width 0.0889)
		(layer "In11.Cu")
		(net "M_F_CPU1_SB_CA<0>")
	)
	(arc
		(start 80.308196 -262.25881)
		(mid 80.591152 -262.182633)
		(end 80.874108 -262.25881)
		(width 0.0889)
		(layer "In11.Cu")
		(net "M_F_CPU1_SB_CA<0>")
	)
	(arc
		(start 79.137002 -262.043926)
		(mid 79.549634 -262.09859)
		(end 79.9338 -262.25881)
		(width 0.0889)
		(layer "In11.Cu")
		(net "M_F_CPU1_SB_CA<0>")
	)
	(arc
		(start 84.63407 -262.25881)
		(mid 84.821014 -262.309065)
		(end 85.007958 -262.25881)
		(width 0.0889)
		(layer "In11.Cu")
		(net "M_F_CPU1_SB_CA<0>")
	)
	(arc
		(start 83.128104 -262.25881)
		(mid 83.41106 -262.182633)
		(end 83.694016 -262.25881)
		(width 0.0889)
		(layer "In11.Cu")
		(net "M_F_CPU1_SB_CA<0>")
	)
	(arc
		(start 85.007958 -262.25881)
		(mid 85.290914 -262.182633)
		(end 85.57387 -262.25881)
		(width 0.0889)
		(layer "In11.Cu")
		(net "M_F_CPU1_SB_CA<0>")
	)
	(arc
		(start 82.762344 -262.263636)
		(mid 82.945852 -262.30913)
		(end 83.128104 -262.25881)
		(width 0.0889)
		(layer "In11.Cu")
		(net "M_F_CPU1_SB_CA<0>")
	)
	(arc
		(start 80.874108 -262.25881)
		(mid 81.061052 -262.309065)
		(end 81.247996 -262.25881)
		(width 0.0889)
		(layer "In11.Cu")
		(net "M_F_CPU1_SB_CA<0>")
	)
	(arc
		(start 82.18805 -262.25881)
		(mid 82.471006 -262.182633)
		(end 82.753962 -262.25881)
		(width 0.0889)
		(layer "In11.Cu")
		(net "M_F_CPU1_SB_CA<0>")
	)
	(arc
		(start 85.57387 -262.25881)
		(mid 85.730308 -262.307781)
		(end 85.89264 -262.284972)
		(width 0.0889)
		(layer "In11.Cu")
		(net "M_F_CPU1_SB_CA<0>")
	)
	(segment
		(start 86.22792 -266.530328)
		(end 85.761068 -266.796266)
		(width 0.10668)
		(layer "F.Cu")
		(net "M_F_CPU1_SA_RSP<0>")
	)
	(segment
		(start 22.636734 -269.503398)
		(end 22.79142 -269.658084)
		(width 0.11684)
		(layer "In11.Cu")
		(net "M_F_CPU1_SA_RSP<0>")
	)
	(segment
		(start 23.31974 -269.160244)
		(end 23.538688 -269.160244)
		(width 0.11684)
		(layer "In11.Cu")
		(net "M_F_CPU1_SA_RSP<0>")
	)
	(segment
		(start 23.538688 -269.160244)
		(end 23.693374 -269.31493)
		(width 0.11684)
		(layer "In11.Cu")
		(net "M_F_CPU1_SA_RSP<0>")
	)
	(segment
		(start 83.694016 -267.118846)
		(end 83.702398 -267.123672)
		(width 0.0889)
		(layer "In11.Cu")
		(net "M_F_CPU1_SA_RSP<0>")
	)
	(segment
		(start 62.994286 -266.424664)
		(end 76.049886 -266.424664)
		(width 0.11684)
		(layer "In11.Cu")
		(net "M_F_CPU1_SA_RSP<0>")
	)
	(segment
		(start 60.258706 -269.160244)
		(end 62.994286 -266.424664)
		(width 0.11684)
		(layer "In11.Cu")
		(net "M_F_CPU1_SA_RSP<0>")
	)
	(segment
		(start 85.914992 -267.061696)
		(end 85.761068 -266.796266)
		(width 0.0889)
		(layer "In11.Cu")
		(net "M_F_CPU1_SA_RSP<0>")
	)
	(segment
		(start 82.753962 -267.118846)
		(end 82.762344 -267.123672)
		(width 0.0889)
		(layer "In11.Cu")
		(net "M_F_CPU1_SA_RSP<0>")
	)
	(segment
		(start 22.79142 -269.658084)
		(end 23.010368 -269.658084)
		(width 0.11684)
		(layer "In11.Cu")
		(net "M_F_CPU1_SA_RSP<0>")
	)
	(segment
		(start 23.165054 -269.503398)
		(end 23.165054 -269.31493)
		(width 0.11684)
		(layer "In11.Cu")
		(net "M_F_CPU1_SA_RSP<0>")
	)
	(segment
		(start 76.492608 -266.424664)
		(end 77.195934 -267.12799)
		(width 0.0889)
		(layer "In11.Cu")
		(net "M_F_CPU1_SA_RSP<0>")
	)
	(segment
		(start 77.195934 -267.12799)
		(end 79.950564 -267.12799)
		(width 0.0889)
		(layer "In11.Cu")
		(net "M_F_CPU1_SA_RSP<0>")
	)
	(segment
		(start 22.133306 -269.160244)
		(end 22.482048 -269.160244)
		(width 0.11684)
		(layer "In11.Cu")
		(net "M_F_CPU1_SA_RSP<0>")
	)
	(segment
		(start 24.37638 -269.160244)
		(end 60.258706 -269.160244)
		(width 0.11684)
		(layer "In11.Cu")
		(net "M_F_CPU1_SA_RSP<0>")
	)
	(segment
		(start 23.693374 -269.31493)
		(end 23.693374 -269.503398)
		(width 0.11684)
		(layer "In11.Cu")
		(net "M_F_CPU1_SA_RSP<0>")
	)
	(segment
		(start 24.067008 -269.658084)
		(end 24.221694 -269.503398)
		(width 0.11684)
		(layer "In11.Cu")
		(net "M_F_CPU1_SA_RSP<0>")
	)
	(segment
		(start 82.179668 -267.123672)
		(end 82.18805 -267.118846)
		(width 0.0889)
		(layer "In11.Cu")
		(net "M_F_CPU1_SA_RSP<0>")
	)
	(segment
		(start 76.049886 -266.424664)
		(end 76.492608 -266.424664)
		(width 0.0889)
		(layer "In11.Cu")
		(net "M_F_CPU1_SA_RSP<0>")
	)
	(segment
		(start 22.636734 -269.31493)
		(end 22.636734 -269.503398)
		(width 0.11684)
		(layer "In11.Cu")
		(net "M_F_CPU1_SA_RSP<0>")
	)
	(segment
		(start 21.70811 -269.58544)
		(end 22.133306 -269.160244)
		(width 0.11684)
		(layer "In11.Cu")
		(net "M_F_CPU1_SA_RSP<0>")
	)
	(segment
		(start 85.89264 -267.145008)
		(end 85.914992 -267.061696)
		(width 0.0889)
		(layer "In11.Cu")
		(net "M_F_CPU1_SA_RSP<0>")
	)
	(segment
		(start 23.84806 -269.658084)
		(end 24.067008 -269.658084)
		(width 0.11684)
		(layer "In11.Cu")
		(net "M_F_CPU1_SA_RSP<0>")
	)
	(segment
		(start 23.165054 -269.31493)
		(end 23.31974 -269.160244)
		(width 0.11684)
		(layer "In11.Cu")
		(net "M_F_CPU1_SA_RSP<0>")
	)
	(segment
		(start 24.221694 -269.503398)
		(end 24.221694 -269.31493)
		(width 0.11684)
		(layer "In11.Cu")
		(net "M_F_CPU1_SA_RSP<0>")
	)
	(segment
		(start 24.221694 -269.31493)
		(end 24.37638 -269.160244)
		(width 0.11684)
		(layer "In11.Cu")
		(net "M_F_CPU1_SA_RSP<0>")
	)
	(segment
		(start 23.693374 -269.503398)
		(end 23.84806 -269.658084)
		(width 0.11684)
		(layer "In11.Cu")
		(net "M_F_CPU1_SA_RSP<0>")
	)
	(segment
		(start 23.010368 -269.658084)
		(end 23.165054 -269.503398)
		(width 0.11684)
		(layer "In11.Cu")
		(net "M_F_CPU1_SA_RSP<0>")
	)
	(segment
		(start 22.482048 -269.160244)
		(end 22.636734 -269.31493)
		(width 0.11684)
		(layer "In11.Cu")
		(net "M_F_CPU1_SA_RSP<0>")
	)
	(arc
		(start 80.308196 -267.118846)
		(mid 80.591152 -267.042669)
		(end 80.874108 -267.118846)
		(width 0.0889)
		(layer "In11.Cu")
		(net "M_F_CPU1_SA_RSP<0>")
	)
	(arc
		(start 79.950564 -267.12799)
		(mid 80.130546 -267.16909)
		(end 80.308196 -267.118846)
		(width 0.0889)
		(layer "In11.Cu")
		(net "M_F_CPU1_SA_RSP<0>")
	)
	(arc
		(start 83.702398 -267.123672)
		(mid 83.885906 -267.169166)
		(end 84.068158 -267.118846)
		(width 0.0889)
		(layer "In11.Cu")
		(net "M_F_CPU1_SA_RSP<0>")
	)
	(arc
		(start 85.007958 -267.118846)
		(mid 85.290914 -267.042669)
		(end 85.57387 -267.118846)
		(width 0.0889)
		(layer "In11.Cu")
		(net "M_F_CPU1_SA_RSP<0>")
	)
	(arc
		(start 81.813908 -267.118846)
		(mid 81.996159 -267.169196)
		(end 82.179668 -267.123672)
		(width 0.0889)
		(layer "In11.Cu")
		(net "M_F_CPU1_SA_RSP<0>")
	)
	(arc
		(start 82.18805 -267.118846)
		(mid 82.471006 -267.042669)
		(end 82.753962 -267.118846)
		(width 0.0889)
		(layer "In11.Cu")
		(net "M_F_CPU1_SA_RSP<0>")
	)
	(arc
		(start 80.874108 -267.118846)
		(mid 81.061052 -267.169101)
		(end 81.247996 -267.118846)
		(width 0.0889)
		(layer "In11.Cu")
		(net "M_F_CPU1_SA_RSP<0>")
	)
	(arc
		(start 85.57387 -267.118846)
		(mid 85.730308 -267.167817)
		(end 85.89264 -267.145008)
		(width 0.0889)
		(layer "In11.Cu")
		(net "M_F_CPU1_SA_RSP<0>")
	)
	(arc
		(start 82.762344 -267.123672)
		(mid 82.945852 -267.169166)
		(end 83.128104 -267.118846)
		(width 0.0889)
		(layer "In11.Cu")
		(net "M_F_CPU1_SA_RSP<0>")
	)
	(arc
		(start 84.63407 -267.118846)
		(mid 84.821014 -267.169101)
		(end 85.007958 -267.118846)
		(width 0.0889)
		(layer "In11.Cu")
		(net "M_F_CPU1_SA_RSP<0>")
	)
	(arc
		(start 83.128104 -267.118846)
		(mid 83.41106 -267.042669)
		(end 83.694016 -267.118846)
		(width 0.0889)
		(layer "In11.Cu")
		(net "M_F_CPU1_SA_RSP<0>")
	)
	(arc
		(start 84.068158 -267.118846)
		(mid 84.351114 -267.042669)
		(end 84.63407 -267.118846)
		(width 0.0889)
		(layer "In11.Cu")
		(net "M_F_CPU1_SA_RSP<0>")
	)
	(arc
		(start 81.247996 -267.118846)
		(mid 81.530952 -267.042669)
		(end 81.813908 -267.118846)
		(width 0.0889)
		(layer "In11.Cu")
		(net "M_F_CPU1_SA_RSP<0>")
	)
	(segment
		(start 85.927946 -256.09042)
		(end 85.461094 -255.824482)
		(width 0.10668)
		(layer "F.Cu")
		(net "M_F_CPU1_SA_PAR")
	)
	(segment
		(start 78.54315 -255.652524)
		(end 78.693772 -255.501902)
		(width 0.0889)
		(layer "In11.Cu")
		(net "M_F_CPU1_SA_PAR")
	)
	(segment
		(start 82.453988 -255.501902)
		(end 82.46237 -255.497076)
		(width 0.0889)
		(layer "In11.Cu")
		(net "M_F_CPU1_SA_PAR")
	)
	(segment
		(start 27.358086 -255.580896)
		(end 27.358086 -255.368552)
		(width 0.14478)
		(layer "In11.Cu")
		(net "M_F_CPU1_SA_PAR")
	)
	(segment
		(start 26.801572 -255.368552)
		(end 26.801572 -255.580896)
		(width 0.14478)
		(layer "In11.Cu")
		(net "M_F_CPU1_SA_PAR")
	)
	(segment
		(start 76.796646 -256.668524)
		(end 77.812646 -255.652524)
		(width 0.0889)
		(layer "In11.Cu")
		(net "M_F_CPU1_SA_PAR")
	)
	(segment
		(start 27.9146 -255.580896)
		(end 28.077668 -255.743964)
		(width 0.14478)
		(layer "In11.Cu")
		(net "M_F_CPU1_SA_PAR")
	)
	(segment
		(start 76.054966 -256.668524)
		(end 76.796646 -256.668524)
		(width 0.0889)
		(layer "In11.Cu")
		(net "M_F_CPU1_SA_PAR")
	)
	(segment
		(start 28.077668 -255.743964)
		(end 64.985646 -255.743964)
		(width 0.14478)
		(layer "In11.Cu")
		(net "M_F_CPU1_SA_PAR")
	)
	(segment
		(start 85.615018 -255.559052)
		(end 85.461094 -255.824482)
		(width 0.0889)
		(layer "In11.Cu")
		(net "M_F_CPU1_SA_PAR")
	)
	(segment
		(start 23.166832 -255.743964)
		(end 26.08199 -255.743964)
		(width 0.14478)
		(layer "In11.Cu")
		(net "M_F_CPU1_SA_PAR")
	)
	(segment
		(start 26.638504 -255.205484)
		(end 26.801572 -255.368552)
		(width 0.14478)
		(layer "In11.Cu")
		(net "M_F_CPU1_SA_PAR")
	)
	(segment
		(start 26.96464 -255.743964)
		(end 27.195018 -255.743964)
		(width 0.14478)
		(layer "In11.Cu")
		(net "M_F_CPU1_SA_PAR")
	)
	(segment
		(start 65.574926 -255.154684)
		(end 71.534274 -255.154684)
		(width 0.14478)
		(layer "In11.Cu")
		(net "M_F_CPU1_SA_PAR")
	)
	(segment
		(start 81.879694 -255.497076)
		(end 81.888076 -255.501902)
		(width 0.0889)
		(layer "In11.Cu")
		(net "M_F_CPU1_SA_PAR")
	)
	(segment
		(start 27.751532 -255.205484)
		(end 27.9146 -255.368552)
		(width 0.14478)
		(layer "In11.Cu")
		(net "M_F_CPU1_SA_PAR")
	)
	(segment
		(start 64.985646 -255.743964)
		(end 65.574926 -255.154684)
		(width 0.14478)
		(layer "In11.Cu")
		(net "M_F_CPU1_SA_PAR")
	)
	(segment
		(start 27.358086 -255.368552)
		(end 27.521154 -255.205484)
		(width 0.14478)
		(layer "In11.Cu")
		(net "M_F_CPU1_SA_PAR")
	)
	(segment
		(start 26.801572 -255.580896)
		(end 26.96464 -255.743964)
		(width 0.14478)
		(layer "In11.Cu")
		(net "M_F_CPU1_SA_PAR")
	)
	(segment
		(start 73.048114 -256.668524)
		(end 76.054966 -256.668524)
		(width 0.14478)
		(layer "In11.Cu")
		(net "M_F_CPU1_SA_PAR")
	)
	(segment
		(start 77.812646 -255.652524)
		(end 78.54315 -255.652524)
		(width 0.0889)
		(layer "In11.Cu")
		(net "M_F_CPU1_SA_PAR")
	)
	(segment
		(start 21.70811 -254.285242)
		(end 23.166832 -255.743964)
		(width 0.14478)
		(layer "In11.Cu")
		(net "M_F_CPU1_SA_PAR")
	)
	(segment
		(start 26.245058 -255.368552)
		(end 26.408126 -255.205484)
		(width 0.14478)
		(layer "In11.Cu")
		(net "M_F_CPU1_SA_PAR")
	)
	(segment
		(start 27.9146 -255.368552)
		(end 27.9146 -255.580896)
		(width 0.14478)
		(layer "In11.Cu")
		(net "M_F_CPU1_SA_PAR")
	)
	(segment
		(start 27.195018 -255.743964)
		(end 27.358086 -255.580896)
		(width 0.14478)
		(layer "In11.Cu")
		(net "M_F_CPU1_SA_PAR")
	)
	(segment
		(start 78.693772 -255.501902)
		(end 78.705456 -255.495044)
		(width 0.0889)
		(layer "In11.Cu")
		(net "M_F_CPU1_SA_PAR")
	)
	(segment
		(start 83.394042 -255.501902)
		(end 83.402424 -255.497076)
		(width 0.0889)
		(layer "In11.Cu")
		(net "M_F_CPU1_SA_PAR")
	)
	(segment
		(start 79.06766 -255.501902)
		(end 79.078074 -255.507998)
		(width 0.0889)
		(layer "In11.Cu")
		(net "M_F_CPU1_SA_PAR")
	)
	(segment
		(start 27.521154 -255.205484)
		(end 27.751532 -255.205484)
		(width 0.14478)
		(layer "In11.Cu")
		(net "M_F_CPU1_SA_PAR")
	)
	(segment
		(start 26.245058 -255.580896)
		(end 26.245058 -255.368552)
		(width 0.14478)
		(layer "In11.Cu")
		(net "M_F_CPU1_SA_PAR")
	)
	(segment
		(start 26.08199 -255.743964)
		(end 26.245058 -255.580896)
		(width 0.14478)
		(layer "In11.Cu")
		(net "M_F_CPU1_SA_PAR")
	)
	(segment
		(start 26.408126 -255.205484)
		(end 26.638504 -255.205484)
		(width 0.14478)
		(layer "In11.Cu")
		(net "M_F_CPU1_SA_PAR")
	)
	(segment
		(start 85.592666 -255.47574)
		(end 85.615018 -255.559052)
		(width 0.0889)
		(layer "In11.Cu")
		(net "M_F_CPU1_SA_PAR")
	)
	(segment
		(start 71.534274 -255.154684)
		(end 73.048114 -256.668524)
		(width 0.14478)
		(layer "In11.Cu")
		(net "M_F_CPU1_SA_PAR")
	)
	(arc
		(start 84.707984 -255.501902)
		(mid 84.99094 -255.578079)
		(end 85.273896 -255.501902)
		(width 0.0889)
		(layer "In11.Cu")
		(net "M_F_CPU1_SA_PAR")
	)
	(arc
		(start 80.008222 -255.501902)
		(mid 80.291178 -255.578079)
		(end 80.574134 -255.501902)
		(width 0.0889)
		(layer "In11.Cu")
		(net "M_F_CPU1_SA_PAR")
	)
	(arc
		(start 85.273896 -255.501902)
		(mid 85.430334 -255.452931)
		(end 85.592666 -255.47574)
		(width 0.0889)
		(layer "In11.Cu")
		(net "M_F_CPU1_SA_PAR")
	)
	(arc
		(start 81.888076 -255.501902)
		(mid 82.171032 -255.578079)
		(end 82.453988 -255.501902)
		(width 0.0889)
		(layer "In11.Cu")
		(net "M_F_CPU1_SA_PAR")
	)
	(arc
		(start 83.402424 -255.497076)
		(mid 83.585932 -255.451582)
		(end 83.768184 -255.501902)
		(width 0.0889)
		(layer "In11.Cu")
		(net "M_F_CPU1_SA_PAR")
	)
	(arc
		(start 83.768184 -255.501902)
		(mid 84.05114 -255.578079)
		(end 84.334096 -255.501902)
		(width 0.0889)
		(layer "In11.Cu")
		(net "M_F_CPU1_SA_PAR")
	)
	(arc
		(start 79.078074 -255.507998)
		(mid 79.35676 -255.578218)
		(end 79.633826 -255.501902)
		(width 0.0889)
		(layer "In11.Cu")
		(net "M_F_CPU1_SA_PAR")
	)
	(arc
		(start 79.633826 -255.501902)
		(mid 79.821024 -255.45152)
		(end 80.008222 -255.501902)
		(width 0.0889)
		(layer "In11.Cu")
		(net "M_F_CPU1_SA_PAR")
	)
	(arc
		(start 81.513934 -255.501902)
		(mid 81.696185 -255.451552)
		(end 81.879694 -255.497076)
		(width 0.0889)
		(layer "In11.Cu")
		(net "M_F_CPU1_SA_PAR")
	)
	(arc
		(start 80.574134 -255.501902)
		(mid 80.761078 -255.451647)
		(end 80.948022 -255.501902)
		(width 0.0889)
		(layer "In11.Cu")
		(net "M_F_CPU1_SA_PAR")
	)
	(arc
		(start 84.334096 -255.501902)
		(mid 84.52104 -255.451647)
		(end 84.707984 -255.501902)
		(width 0.0889)
		(layer "In11.Cu")
		(net "M_F_CPU1_SA_PAR")
	)
	(arc
		(start 80.948022 -255.501902)
		(mid 81.230978 -255.578079)
		(end 81.513934 -255.501902)
		(width 0.0889)
		(layer "In11.Cu")
		(net "M_F_CPU1_SA_PAR")
	)
	(arc
		(start 82.46237 -255.497076)
		(mid 82.645878 -255.451582)
		(end 82.82813 -255.501902)
		(width 0.0889)
		(layer "In11.Cu")
		(net "M_F_CPU1_SA_PAR")
	)
	(arc
		(start 78.705456 -255.495044)
		(mid 78.887457 -255.451511)
		(end 79.06766 -255.501902)
		(width 0.0889)
		(layer "In11.Cu")
		(net "M_F_CPU1_SA_PAR")
	)
	(arc
		(start 82.82813 -255.501902)
		(mid 83.111086 -255.578079)
		(end 83.394042 -255.501902)
		(width 0.0889)
		(layer "In11.Cu")
		(net "M_F_CPU1_SA_PAR")
	)
	(segment
		(start 85.927946 -247.99036)
		(end 85.461094 -247.724422)
		(width 0.12954)
		(layer "F.Cu")
		(net "M_F_CPU1_SA_DQS_DP<9>")
	)
	(segment
		(start 21.58492 -239.742218)
		(end 21.70176 -239.859058)
		(width 0.16002)
		(layer "In11.Cu")
		(net "M_F_CPU1_SA_DQS_DP<9>")
	)
	(segment
		(start 85.59165 -247.372124)
		(end 85.615018 -247.458992)
		(width 0.09525)
		(layer "In11.Cu")
		(net "M_F_CPU1_SA_DQS_DP<9>")
	)
	(segment
		(start 19.926808 -239.395762)
		(end 20.516088 -239.395762)
		(width 0.16002)
		(layer "In11.Cu")
		(net "M_F_CPU1_SA_DQS_DP<9>")
	)
	(segment
		(start 39.125906 -240.560606)
		(end 41.121838 -240.560606)
		(width 0.16002)
		(layer "In11.Cu")
		(net "M_F_CPU1_SA_DQS_DP<9>")
	)
	(segment
		(start 17.882108 -239.56137)
		(end 19.7612 -239.56137)
		(width 0.16002)
		(layer "In11.Cu")
		(net "M_F_CPU1_SA_DQS_DP<9>")
	)
	(segment
		(start 78.673706 -247.409462)
		(end 78.685644 -247.402604)
		(width 0.09525)
		(layer "In11.Cu")
		(net "M_F_CPU1_SA_DQS_DP<9>")
	)
	(segment
		(start 34.375344 -240.240566)
		(end 35.259518 -239.356392)
		(width 0.16002)
		(layer "In11.Cu")
		(net "M_F_CPU1_SA_DQS_DP<9>")
	)
	(segment
		(start 43.105578 -239.356392)
		(end 43.459654 -239.710468)
		(width 0.16002)
		(layer "In11.Cu")
		(net "M_F_CPU1_SA_DQS_DP<9>")
	)
	(segment
		(start 59.397138 -240.906046)
		(end 65.693798 -247.202706)
		(width 0.16002)
		(layer "In11.Cu")
		(net "M_F_CPU1_SA_DQS_DP<9>")
	)
	(segment
		(start 78.692502 -247.399048)
		(end 78.69809 -247.396)
		(width 0.09525)
		(layer "In11.Cu")
		(net "M_F_CPU1_SA_DQS_DP<9>")
	)
	(segment
		(start 57.839102 -240.906046)
		(end 59.397138 -240.906046)
		(width 0.16002)
		(layer "In11.Cu")
		(net "M_F_CPU1_SA_DQS_DP<9>")
	)
	(segment
		(start 78.69809 -247.396)
		(end 78.699106 -247.395492)
		(width 0.09525)
		(layer "In11.Cu")
		(net "M_F_CPU1_SA_DQS_DP<9>")
	)
	(segment
		(start 35.259518 -239.356392)
		(end 35.561524 -239.356392)
		(width 0.16002)
		(layer "In11.Cu")
		(net "M_F_CPU1_SA_DQS_DP<9>")
	)
	(segment
		(start 49.463452 -240.240566)
		(end 50.347626 -239.356392)
		(width 0.16002)
		(layer "In11.Cu")
		(net "M_F_CPU1_SA_DQS_DP<9>")
	)
	(segment
		(start 75.955906 -247.682258)
		(end 75.979528 -247.682258)
		(width 0.09525)
		(layer "In11.Cu")
		(net "M_F_CPU1_SA_DQS_DP<9>")
	)
	(segment
		(start 50.649632 -239.356392)
		(end 51.003708 -239.710468)
		(width 0.16002)
		(layer "In11.Cu")
		(net "M_F_CPU1_SA_DQS_DP<9>")
	)
	(segment
		(start 19.7612 -239.56137)
		(end 19.926808 -239.395762)
		(width 0.16002)
		(layer "In11.Cu")
		(net "M_F_CPU1_SA_DQS_DP<9>")
	)
	(segment
		(start 20.862544 -239.742218)
		(end 21.58492 -239.742218)
		(width 0.16002)
		(layer "In11.Cu")
		(net "M_F_CPU1_SA_DQS_DP<9>")
	)
	(segment
		(start 20.516088 -239.395762)
		(end 20.862544 -239.742218)
		(width 0.16002)
		(layer "In11.Cu")
		(net "M_F_CPU1_SA_DQS_DP<9>")
	)
	(segment
		(start 74.816208 -247.202706)
		(end 75.29576 -247.682258)
		(width 0.16002)
		(layer "In11.Cu")
		(net "M_F_CPU1_SA_DQS_DP<9>")
	)
	(segment
		(start 51.003708 -239.710468)
		(end 53.363876 -239.710468)
		(width 0.16002)
		(layer "In11.Cu")
		(net "M_F_CPU1_SA_DQS_DP<9>")
	)
	(segment
		(start 23.252684 -239.742218)
		(end 24.071072 -240.560606)
		(width 0.16002)
		(layer "In11.Cu")
		(net "M_F_CPU1_SA_DQS_DP<9>")
	)
	(segment
		(start 33.577784 -240.560606)
		(end 33.897824 -240.240566)
		(width 0.16002)
		(layer "In11.Cu")
		(net "M_F_CPU1_SA_DQS_DP<9>")
	)
	(segment
		(start 57.173622 -240.240566)
		(end 57.839102 -240.906046)
		(width 0.16002)
		(layer "In11.Cu")
		(net "M_F_CPU1_SA_DQS_DP<9>")
	)
	(segment
		(start 50.347626 -239.356392)
		(end 50.649632 -239.356392)
		(width 0.16002)
		(layer "In11.Cu")
		(net "M_F_CPU1_SA_DQS_DP<9>")
	)
	(segment
		(start 83.392518 -247.399302)
		(end 83.4009 -247.394476)
		(width 0.09525)
		(layer "In11.Cu")
		(net "M_F_CPU1_SA_DQS_DP<9>")
	)
	(segment
		(start 26.83129 -240.240566)
		(end 27.715464 -239.356392)
		(width 0.16002)
		(layer "In11.Cu")
		(net "M_F_CPU1_SA_DQS_DP<9>")
	)
	(segment
		(start 26.35377 -240.240566)
		(end 26.83129 -240.240566)
		(width 0.16002)
		(layer "In11.Cu")
		(net "M_F_CPU1_SA_DQS_DP<9>")
	)
	(segment
		(start 53.893974 -240.240566)
		(end 57.173622 -240.240566)
		(width 0.16002)
		(layer "In11.Cu")
		(net "M_F_CPU1_SA_DQS_DP<9>")
	)
	(segment
		(start 33.897824 -240.240566)
		(end 34.375344 -240.240566)
		(width 0.16002)
		(layer "In11.Cu")
		(net "M_F_CPU1_SA_DQS_DP<9>")
	)
	(segment
		(start 75.29576 -247.682258)
		(end 75.955906 -247.682258)
		(width 0.16002)
		(layer "In11.Cu")
		(net "M_F_CPU1_SA_DQS_DP<9>")
	)
	(segment
		(start 45.819822 -239.710468)
		(end 46.66996 -240.560606)
		(width 0.16002)
		(layer "In11.Cu")
		(net "M_F_CPU1_SA_DQS_DP<9>")
	)
	(segment
		(start 48.665892 -240.560606)
		(end 48.985932 -240.240566)
		(width 0.16002)
		(layer "In11.Cu")
		(net "M_F_CPU1_SA_DQS_DP<9>")
	)
	(segment
		(start 78.691994 -247.398794)
		(end 78.692502 -247.399048)
		(width 0.09525)
		(layer "In11.Cu")
		(net "M_F_CPU1_SA_DQS_DP<9>")
	)
	(segment
		(start 78.701138 -247.394222)
		(end 78.704186 -247.392444)
		(width 0.09525)
		(layer "In11.Cu")
		(net "M_F_CPU1_SA_DQS_DP<9>")
	)
	(segment
		(start 46.66996 -240.560606)
		(end 48.665892 -240.560606)
		(width 0.16002)
		(layer "In11.Cu")
		(net "M_F_CPU1_SA_DQS_DP<9>")
	)
	(segment
		(start 85.615018 -247.458992)
		(end 85.461094 -247.724422)
		(width 0.09525)
		(layer "In11.Cu")
		(net "M_F_CPU1_SA_DQS_DP<9>")
	)
	(segment
		(start 22.18182 -239.859058)
		(end 22.29866 -239.742218)
		(width 0.16002)
		(layer "In11.Cu")
		(net "M_F_CPU1_SA_DQS_DP<9>")
	)
	(segment
		(start 81.881218 -247.394476)
		(end 81.8896 -247.399302)
		(width 0.09525)
		(layer "In11.Cu")
		(net "M_F_CPU1_SA_DQS_DP<9>")
	)
	(segment
		(start 21.70176 -239.859058)
		(end 22.18182 -239.859058)
		(width 0.16002)
		(layer "In11.Cu")
		(net "M_F_CPU1_SA_DQS_DP<9>")
	)
	(segment
		(start 17.608042 -239.835436)
		(end 17.882108 -239.56137)
		(width 0.16002)
		(layer "In11.Cu")
		(net "M_F_CPU1_SA_DQS_DP<9>")
	)
	(segment
		(start 35.561524 -239.356392)
		(end 35.9156 -239.710468)
		(width 0.16002)
		(layer "In11.Cu")
		(net "M_F_CPU1_SA_DQS_DP<9>")
	)
	(segment
		(start 41.919398 -240.240566)
		(end 42.803572 -239.356392)
		(width 0.16002)
		(layer "In11.Cu")
		(net "M_F_CPU1_SA_DQS_DP<9>")
	)
	(segment
		(start 22.29866 -239.742218)
		(end 23.252684 -239.742218)
		(width 0.16002)
		(layer "In11.Cu")
		(net "M_F_CPU1_SA_DQS_DP<9>")
	)
	(segment
		(start 65.693798 -247.202706)
		(end 74.816208 -247.202706)
		(width 0.16002)
		(layer "In11.Cu")
		(net "M_F_CPU1_SA_DQS_DP<9>")
	)
	(segment
		(start 79.069184 -247.399302)
		(end 79.079598 -247.405398)
		(width 0.09525)
		(layer "In11.Cu")
		(net "M_F_CPU1_SA_DQS_DP<9>")
	)
	(segment
		(start 26.03373 -240.560606)
		(end 26.35377 -240.240566)
		(width 0.16002)
		(layer "In11.Cu")
		(net "M_F_CPU1_SA_DQS_DP<9>")
	)
	(segment
		(start 76.038456 -247.62333)
		(end 77.509116 -247.62333)
		(width 0.09525)
		(layer "In11.Cu")
		(net "M_F_CPU1_SA_DQS_DP<9>")
	)
	(segment
		(start 77.509116 -247.62333)
		(end 77.674216 -247.45823)
		(width 0.09525)
		(layer "In11.Cu")
		(net "M_F_CPU1_SA_DQS_DP<9>")
	)
	(segment
		(start 38.275768 -239.710468)
		(end 39.125906 -240.560606)
		(width 0.16002)
		(layer "In11.Cu")
		(net "M_F_CPU1_SA_DQS_DP<9>")
	)
	(segment
		(start 30.731714 -239.710468)
		(end 31.581852 -240.560606)
		(width 0.16002)
		(layer "In11.Cu")
		(net "M_F_CPU1_SA_DQS_DP<9>")
	)
	(segment
		(start 28.371546 -239.710468)
		(end 30.731714 -239.710468)
		(width 0.16002)
		(layer "In11.Cu")
		(net "M_F_CPU1_SA_DQS_DP<9>")
	)
	(segment
		(start 78.699106 -247.395492)
		(end 78.701138 -247.394222)
		(width 0.09525)
		(layer "In11.Cu")
		(net "M_F_CPU1_SA_DQS_DP<9>")
	)
	(segment
		(start 48.985932 -240.240566)
		(end 49.463452 -240.240566)
		(width 0.16002)
		(layer "In11.Cu")
		(net "M_F_CPU1_SA_DQS_DP<9>")
	)
	(segment
		(start 27.715464 -239.356392)
		(end 28.01747 -239.356392)
		(width 0.16002)
		(layer "In11.Cu")
		(net "M_F_CPU1_SA_DQS_DP<9>")
	)
	(segment
		(start 31.581852 -240.560606)
		(end 33.577784 -240.560606)
		(width 0.16002)
		(layer "In11.Cu")
		(net "M_F_CPU1_SA_DQS_DP<9>")
	)
	(segment
		(start 24.071072 -240.560606)
		(end 26.03373 -240.560606)
		(width 0.16002)
		(layer "In11.Cu")
		(net "M_F_CPU1_SA_DQS_DP<9>")
	)
	(segment
		(start 42.803572 -239.356392)
		(end 43.105578 -239.356392)
		(width 0.16002)
		(layer "In11.Cu")
		(net "M_F_CPU1_SA_DQS_DP<9>")
	)
	(segment
		(start 43.459654 -239.710468)
		(end 45.819822 -239.710468)
		(width 0.16002)
		(layer "In11.Cu")
		(net "M_F_CPU1_SA_DQS_DP<9>")
	)
	(segment
		(start 35.9156 -239.710468)
		(end 38.275768 -239.710468)
		(width 0.16002)
		(layer "In11.Cu")
		(net "M_F_CPU1_SA_DQS_DP<9>")
	)
	(segment
		(start 78.685644 -247.402604)
		(end 78.691994 -247.398794)
		(width 0.09525)
		(layer "In11.Cu")
		(net "M_F_CPU1_SA_DQS_DP<9>")
	)
	(segment
		(start 41.441878 -240.240566)
		(end 41.919398 -240.240566)
		(width 0.16002)
		(layer "In11.Cu")
		(net "M_F_CPU1_SA_DQS_DP<9>")
	)
	(segment
		(start 41.121838 -240.560606)
		(end 41.441878 -240.240566)
		(width 0.16002)
		(layer "In11.Cu")
		(net "M_F_CPU1_SA_DQS_DP<9>")
	)
	(segment
		(start 75.979528 -247.682258)
		(end 76.038456 -247.62333)
		(width 0.09525)
		(layer "In11.Cu")
		(net "M_F_CPU1_SA_DQS_DP<9>")
	)
	(segment
		(start 28.01747 -239.356392)
		(end 28.371546 -239.710468)
		(width 0.16002)
		(layer "In11.Cu")
		(net "M_F_CPU1_SA_DQS_DP<9>")
	)
	(segment
		(start 82.452464 -247.399302)
		(end 82.460846 -247.394476)
		(width 0.09525)
		(layer "In11.Cu")
		(net "M_F_CPU1_SA_DQS_DP<9>")
	)
	(segment
		(start 53.363876 -239.710468)
		(end 53.893974 -240.240566)
		(width 0.16002)
		(layer "In11.Cu")
		(net "M_F_CPU1_SA_DQS_DP<9>")
	)
	(arc
		(start 83.769708 -247.399302)
		(mid 84.05114 -247.475057)
		(end 84.332572 -247.399302)
		(width 0.09525)
		(layer "In11.Cu")
		(net "M_F_CPU1_SA_DQS_DP<9>")
	)
	(arc
		(start 81.8896 -247.399302)
		(mid 82.171032 -247.475057)
		(end 82.452464 -247.399302)
		(width 0.09525)
		(layer "In11.Cu")
		(net "M_F_CPU1_SA_DQS_DP<9>")
	)
	(arc
		(start 83.4009 -247.394476)
		(mid 83.585932 -247.348562)
		(end 83.769708 -247.399302)
		(width 0.09525)
		(layer "In11.Cu")
		(net "M_F_CPU1_SA_DQS_DP<9>")
	)
	(arc
		(start 82.460846 -247.394476)
		(mid 82.645878 -247.348562)
		(end 82.829654 -247.399302)
		(width 0.09525)
		(layer "In11.Cu")
		(net "M_F_CPU1_SA_DQS_DP<9>")
	)
	(arc
		(start 80.009746 -247.399302)
		(mid 80.291178 -247.475057)
		(end 80.57261 -247.399302)
		(width 0.09525)
		(layer "In11.Cu")
		(net "M_F_CPU1_SA_DQS_DP<9>")
	)
	(arc
		(start 77.674216 -247.45823)
		(mid 77.891862 -247.351113)
		(end 78.129638 -247.399048)
		(width 0.09525)
		(layer "In11.Cu")
		(net "M_F_CPU1_SA_DQS_DP<9>")
	)
	(arc
		(start 85.272372 -247.399302)
		(mid 85.42897 -247.350013)
		(end 85.59165 -247.372124)
		(width 0.09525)
		(layer "In11.Cu")
		(net "M_F_CPU1_SA_DQS_DP<9>")
	)
	(arc
		(start 82.829654 -247.399302)
		(mid 83.111086 -247.475057)
		(end 83.392518 -247.399302)
		(width 0.09525)
		(layer "In11.Cu")
		(net "M_F_CPU1_SA_DQS_DP<9>")
	)
	(arc
		(start 79.632302 -247.399302)
		(mid 79.821024 -247.348498)
		(end 80.009746 -247.399302)
		(width 0.09525)
		(layer "In11.Cu")
		(net "M_F_CPU1_SA_DQS_DP<9>")
	)
	(arc
		(start 80.57261 -247.399302)
		(mid 80.761078 -247.348625)
		(end 80.949546 -247.399302)
		(width 0.09525)
		(layer "In11.Cu")
		(net "M_F_CPU1_SA_DQS_DP<9>")
	)
	(arc
		(start 81.51241 -247.399302)
		(mid 81.696185 -247.34853)
		(end 81.881218 -247.394476)
		(width 0.09525)
		(layer "In11.Cu")
		(net "M_F_CPU1_SA_DQS_DP<9>")
	)
	(arc
		(start 84.332572 -247.399302)
		(mid 84.52104 -247.348625)
		(end 84.709508 -247.399302)
		(width 0.09525)
		(layer "In11.Cu")
		(net "M_F_CPU1_SA_DQS_DP<9>")
	)
	(arc
		(start 79.079598 -247.405398)
		(mid 79.35676 -247.475198)
		(end 79.632302 -247.399302)
		(width 0.09525)
		(layer "In11.Cu")
		(net "M_F_CPU1_SA_DQS_DP<9>")
	)
	(arc
		(start 84.709508 -247.399302)
		(mid 84.99094 -247.475057)
		(end 85.272372 -247.399302)
		(width 0.09525)
		(layer "In11.Cu")
		(net "M_F_CPU1_SA_DQS_DP<9>")
	)
	(arc
		(start 78.704186 -247.392444)
		(mid 78.887567 -247.348613)
		(end 79.069184 -247.399302)
		(width 0.09525)
		(layer "In11.Cu")
		(net "M_F_CPU1_SA_DQS_DP<9>")
	)
	(arc
		(start 80.949546 -247.399302)
		(mid 81.230978 -247.475057)
		(end 81.51241 -247.399302)
		(width 0.09525)
		(layer "In11.Cu")
		(net "M_F_CPU1_SA_DQS_DP<9>")
	)
	(arc
		(start 78.129638 -247.399048)
		(mid 78.400326 -247.474734)
		(end 78.673706 -247.409462)
		(width 0.09525)
		(layer "In11.Cu")
		(net "M_F_CPU1_SA_DQS_DP<9>")
	)
	(segment
		(start 85.927946 -243.130324)
		(end 85.461094 -242.864386)
		(width 0.12954)
		(layer "F.Cu")
		(net "M_F_CPU1_SA_DQS_DP<8>")
	)
	(segment
		(start 77.398626 -242.157504)
		(end 77.728826 -242.487704)
		(width 0.09525)
		(layer "In11.Cu")
		(net "M_F_CPU1_SA_DQS_DP<8>")
	)
	(segment
		(start 34.375344 -230.890572)
		(end 35.259518 -230.006398)
		(width 0.16002)
		(layer "In11.Cu")
		(net "M_F_CPU1_SA_DQS_DP<8>")
	)
	(segment
		(start 50.347626 -230.006398)
		(end 50.649632 -230.006398)
		(width 0.16002)
		(layer "In11.Cu")
		(net "M_F_CPU1_SA_DQS_DP<8>")
	)
	(segment
		(start 27.715464 -230.006398)
		(end 28.01747 -230.006398)
		(width 0.16002)
		(layer "In11.Cu")
		(net "M_F_CPU1_SA_DQS_DP<8>")
	)
	(segment
		(start 17.882108 -230.211376)
		(end 18.5674 -230.211376)
		(width 0.16002)
		(layer "In11.Cu")
		(net "M_F_CPU1_SA_DQS_DP<8>")
	)
	(segment
		(start 26.03373 -231.210612)
		(end 26.35377 -230.890572)
		(width 0.16002)
		(layer "In11.Cu")
		(net "M_F_CPU1_SA_DQS_DP<8>")
	)
	(segment
		(start 39.125906 -231.210612)
		(end 41.121838 -231.210612)
		(width 0.16002)
		(layer "In11.Cu")
		(net "M_F_CPU1_SA_DQS_DP<8>")
	)
	(segment
		(start 33.897824 -230.890572)
		(end 34.375344 -230.890572)
		(width 0.16002)
		(layer "In11.Cu")
		(net "M_F_CPU1_SA_DQS_DP<8>")
	)
	(segment
		(start 76.039726 -241.536982)
		(end 76.660248 -242.157504)
		(width 0.09525)
		(layer "In11.Cu")
		(net "M_F_CPU1_SA_DQS_DP<8>")
	)
	(segment
		(start 26.35377 -230.890572)
		(end 26.83129 -230.890572)
		(width 0.16002)
		(layer "In11.Cu")
		(net "M_F_CPU1_SA_DQS_DP<8>")
	)
	(segment
		(start 42.803572 -230.006398)
		(end 43.105578 -230.006398)
		(width 0.16002)
		(layer "In11.Cu")
		(net "M_F_CPU1_SA_DQS_DP<8>")
	)
	(segment
		(start 75.805792 -241.596164)
		(end 75.864974 -241.536982)
		(width 0.09525)
		(layer "In11.Cu")
		(net "M_F_CPU1_SA_DQS_DP<8>")
	)
	(segment
		(start 38.275768 -230.360474)
		(end 39.125906 -231.210612)
		(width 0.16002)
		(layer "In11.Cu")
		(net "M_F_CPU1_SA_DQS_DP<8>")
	)
	(segment
		(start 57.007252 -230.890572)
		(end 57.891426 -230.006398)
		(width 0.16002)
		(layer "In11.Cu")
		(net "M_F_CPU1_SA_DQS_DP<8>")
	)
	(segment
		(start 75.864974 -241.536982)
		(end 76.039726 -241.536982)
		(width 0.09525)
		(layer "In11.Cu")
		(net "M_F_CPU1_SA_DQS_DP<8>")
	)
	(segment
		(start 20.516088 -230.045768)
		(end 20.862544 -230.392224)
		(width 0.16002)
		(layer "In11.Cu")
		(net "M_F_CPU1_SA_DQS_DP<8>")
	)
	(segment
		(start 18.5674 -230.211376)
		(end 18.68424 -230.328216)
		(width 0.16002)
		(layer "In11.Cu")
		(net "M_F_CPU1_SA_DQS_DP<8>")
	)
	(segment
		(start 28.371546 -230.360474)
		(end 30.731714 -230.360474)
		(width 0.16002)
		(layer "In11.Cu")
		(net "M_F_CPU1_SA_DQS_DP<8>")
	)
	(segment
		(start 81.881218 -242.53444)
		(end 81.8896 -242.539266)
		(width 0.09525)
		(layer "In11.Cu")
		(net "M_F_CPU1_SA_DQS_DP<8>")
	)
	(segment
		(start 31.581852 -231.210612)
		(end 33.577784 -231.210612)
		(width 0.16002)
		(layer "In11.Cu")
		(net "M_F_CPU1_SA_DQS_DP<8>")
	)
	(segment
		(start 28.01747 -230.006398)
		(end 28.371546 -230.360474)
		(width 0.16002)
		(layer "In11.Cu")
		(net "M_F_CPU1_SA_DQS_DP<8>")
	)
	(segment
		(start 20.862544 -230.392224)
		(end 23.252684 -230.392224)
		(width 0.16002)
		(layer "In11.Cu")
		(net "M_F_CPU1_SA_DQS_DP<8>")
	)
	(segment
		(start 45.819822 -230.360474)
		(end 46.66996 -231.210612)
		(width 0.16002)
		(layer "In11.Cu")
		(net "M_F_CPU1_SA_DQS_DP<8>")
	)
	(segment
		(start 53.893974 -230.890572)
		(end 57.007252 -230.890572)
		(width 0.16002)
		(layer "In11.Cu")
		(net "M_F_CPU1_SA_DQS_DP<8>")
	)
	(segment
		(start 17.608042 -230.485442)
		(end 17.882108 -230.211376)
		(width 0.16002)
		(layer "In11.Cu")
		(net "M_F_CPU1_SA_DQS_DP<8>")
	)
	(segment
		(start 57.891426 -230.006398)
		(end 58.748422 -230.006398)
		(width 0.16002)
		(layer "In11.Cu")
		(net "M_F_CPU1_SA_DQS_DP<8>")
	)
	(segment
		(start 43.105578 -230.006398)
		(end 43.459654 -230.360474)
		(width 0.16002)
		(layer "In11.Cu")
		(net "M_F_CPU1_SA_DQS_DP<8>")
	)
	(segment
		(start 24.071072 -231.210612)
		(end 26.03373 -231.210612)
		(width 0.16002)
		(layer "In11.Cu")
		(net "M_F_CPU1_SA_DQS_DP<8>")
	)
	(segment
		(start 30.731714 -230.360474)
		(end 31.581852 -231.210612)
		(width 0.16002)
		(layer "In11.Cu")
		(net "M_F_CPU1_SA_DQS_DP<8>")
	)
	(segment
		(start 50.649632 -230.006398)
		(end 51.003708 -230.360474)
		(width 0.16002)
		(layer "In11.Cu")
		(net "M_F_CPU1_SA_DQS_DP<8>")
	)
	(segment
		(start 35.561524 -230.006398)
		(end 35.9156 -230.360474)
		(width 0.16002)
		(layer "In11.Cu")
		(net "M_F_CPU1_SA_DQS_DP<8>")
	)
	(segment
		(start 77.728826 -242.487704)
		(end 77.940408 -242.487704)
		(width 0.09525)
		(layer "In11.Cu")
		(net "M_F_CPU1_SA_DQS_DP<8>")
	)
	(segment
		(start 19.926808 -230.045768)
		(end 20.516088 -230.045768)
		(width 0.16002)
		(layer "In11.Cu")
		(net "M_F_CPU1_SA_DQS_DP<8>")
	)
	(segment
		(start 19.7612 -230.211376)
		(end 19.926808 -230.045768)
		(width 0.16002)
		(layer "In11.Cu")
		(net "M_F_CPU1_SA_DQS_DP<8>")
	)
	(segment
		(start 19.1643 -230.328216)
		(end 19.28114 -230.211376)
		(width 0.16002)
		(layer "In11.Cu")
		(net "M_F_CPU1_SA_DQS_DP<8>")
	)
	(segment
		(start 82.452464 -242.539266)
		(end 82.460846 -242.53444)
		(width 0.09525)
		(layer "In11.Cu")
		(net "M_F_CPU1_SA_DQS_DP<8>")
	)
	(segment
		(start 33.577784 -231.210612)
		(end 33.897824 -230.890572)
		(width 0.16002)
		(layer "In11.Cu")
		(net "M_F_CPU1_SA_DQS_DP<8>")
	)
	(segment
		(start 75.78217 -241.596164)
		(end 75.805792 -241.596164)
		(width 0.09525)
		(layer "In11.Cu")
		(net "M_F_CPU1_SA_DQS_DP<8>")
	)
	(segment
		(start 35.9156 -230.360474)
		(end 38.275768 -230.360474)
		(width 0.16002)
		(layer "In11.Cu")
		(net "M_F_CPU1_SA_DQS_DP<8>")
	)
	(segment
		(start 41.121838 -231.210612)
		(end 41.441878 -230.890572)
		(width 0.16002)
		(layer "In11.Cu")
		(net "M_F_CPU1_SA_DQS_DP<8>")
	)
	(segment
		(start 19.28114 -230.211376)
		(end 19.7612 -230.211376)
		(width 0.16002)
		(layer "In11.Cu")
		(net "M_F_CPU1_SA_DQS_DP<8>")
	)
	(segment
		(start 26.83129 -230.890572)
		(end 27.715464 -230.006398)
		(width 0.16002)
		(layer "In11.Cu")
		(net "M_F_CPU1_SA_DQS_DP<8>")
	)
	(segment
		(start 41.441878 -230.890572)
		(end 41.919398 -230.890572)
		(width 0.16002)
		(layer "In11.Cu")
		(net "M_F_CPU1_SA_DQS_DP<8>")
	)
	(segment
		(start 49.463452 -230.890572)
		(end 50.347626 -230.006398)
		(width 0.16002)
		(layer "In11.Cu")
		(net "M_F_CPU1_SA_DQS_DP<8>")
	)
	(segment
		(start 83.392518 -242.539266)
		(end 83.4009 -242.53444)
		(width 0.09525)
		(layer "In11.Cu")
		(net "M_F_CPU1_SA_DQS_DP<8>")
	)
	(segment
		(start 43.459654 -230.360474)
		(end 45.819822 -230.360474)
		(width 0.16002)
		(layer "In11.Cu")
		(net "M_F_CPU1_SA_DQS_DP<8>")
	)
	(segment
		(start 78.677516 -242.547902)
		(end 78.692248 -242.539266)
		(width 0.09525)
		(layer "In11.Cu")
		(net "M_F_CPU1_SA_DQS_DP<8>")
	)
	(segment
		(start 23.252684 -230.392224)
		(end 24.071072 -231.210612)
		(width 0.16002)
		(layer "In11.Cu")
		(net "M_F_CPU1_SA_DQS_DP<8>")
	)
	(segment
		(start 68.665852 -241.596164)
		(end 75.78217 -241.596164)
		(width 0.16002)
		(layer "In11.Cu")
		(net "M_F_CPU1_SA_DQS_DP<8>")
	)
	(segment
		(start 62.427866 -233.685842)
		(end 62.427866 -235.358178)
		(width 0.16002)
		(layer "In11.Cu")
		(net "M_F_CPU1_SA_DQS_DP<8>")
	)
	(segment
		(start 53.363876 -230.360474)
		(end 53.893974 -230.890572)
		(width 0.16002)
		(layer "In11.Cu")
		(net "M_F_CPU1_SA_DQS_DP<8>")
	)
	(segment
		(start 46.66996 -231.210612)
		(end 48.665892 -231.210612)
		(width 0.16002)
		(layer "In11.Cu")
		(net "M_F_CPU1_SA_DQS_DP<8>")
	)
	(segment
		(start 41.919398 -230.890572)
		(end 42.803572 -230.006398)
		(width 0.16002)
		(layer "In11.Cu")
		(net "M_F_CPU1_SA_DQS_DP<8>")
	)
	(segment
		(start 48.665892 -231.210612)
		(end 48.985932 -230.890572)
		(width 0.16002)
		(layer "In11.Cu")
		(net "M_F_CPU1_SA_DQS_DP<8>")
	)
	(segment
		(start 51.003708 -230.360474)
		(end 53.363876 -230.360474)
		(width 0.16002)
		(layer "In11.Cu")
		(net "M_F_CPU1_SA_DQS_DP<8>")
	)
	(segment
		(start 35.259518 -230.006398)
		(end 35.561524 -230.006398)
		(width 0.16002)
		(layer "In11.Cu")
		(net "M_F_CPU1_SA_DQS_DP<8>")
	)
	(segment
		(start 85.615018 -242.598956)
		(end 85.461094 -242.864386)
		(width 0.09525)
		(layer "In11.Cu")
		(net "M_F_CPU1_SA_DQS_DP<8>")
	)
	(segment
		(start 48.985932 -230.890572)
		(end 49.463452 -230.890572)
		(width 0.16002)
		(layer "In11.Cu")
		(net "M_F_CPU1_SA_DQS_DP<8>")
	)
	(segment
		(start 85.59165 -242.512088)
		(end 85.615018 -242.598956)
		(width 0.09525)
		(layer "In11.Cu")
		(net "M_F_CPU1_SA_DQS_DP<8>")
	)
	(segment
		(start 76.660248 -242.157504)
		(end 77.398626 -242.157504)
		(width 0.09525)
		(layer "In11.Cu")
		(net "M_F_CPU1_SA_DQS_DP<8>")
	)
	(segment
		(start 78.692248 -242.539266)
		(end 78.704186 -242.532408)
		(width 0.09525)
		(layer "In11.Cu")
		(net "M_F_CPU1_SA_DQS_DP<8>")
	)
	(segment
		(start 62.427866 -235.358178)
		(end 68.665852 -241.596164)
		(width 0.16002)
		(layer "In11.Cu")
		(net "M_F_CPU1_SA_DQS_DP<8>")
	)
	(segment
		(start 18.68424 -230.328216)
		(end 19.1643 -230.328216)
		(width 0.16002)
		(layer "In11.Cu")
		(net "M_F_CPU1_SA_DQS_DP<8>")
	)
	(segment
		(start 58.748422 -230.006398)
		(end 62.427866 -233.685842)
		(width 0.16002)
		(layer "In11.Cu")
		(net "M_F_CPU1_SA_DQS_DP<8>")
	)
	(segment
		(start 79.069184 -242.539266)
		(end 79.079598 -242.545362)
		(width 0.09525)
		(layer "In11.Cu")
		(net "M_F_CPU1_SA_DQS_DP<8>")
	)
	(arc
		(start 83.4009 -242.53444)
		(mid 83.585932 -242.488526)
		(end 83.769708 -242.539266)
		(width 0.09525)
		(layer "In11.Cu")
		(net "M_F_CPU1_SA_DQS_DP<8>")
	)
	(arc
		(start 78.704186 -242.532408)
		(mid 78.887567 -242.488577)
		(end 79.069184 -242.539266)
		(width 0.09525)
		(layer "In11.Cu")
		(net "M_F_CPU1_SA_DQS_DP<8>")
	)
	(arc
		(start 84.332572 -242.539266)
		(mid 84.52104 -242.488589)
		(end 84.709508 -242.539266)
		(width 0.09525)
		(layer "In11.Cu")
		(net "M_F_CPU1_SA_DQS_DP<8>")
	)
	(arc
		(start 79.632302 -242.539266)
		(mid 79.821024 -242.488462)
		(end 80.009746 -242.539266)
		(width 0.09525)
		(layer "In11.Cu")
		(net "M_F_CPU1_SA_DQS_DP<8>")
	)
	(arc
		(start 83.769708 -242.539266)
		(mid 84.05114 -242.615021)
		(end 84.332572 -242.539266)
		(width 0.09525)
		(layer "In11.Cu")
		(net "M_F_CPU1_SA_DQS_DP<8>")
	)
	(arc
		(start 84.709508 -242.539266)
		(mid 84.99094 -242.615021)
		(end 85.272372 -242.539266)
		(width 0.09525)
		(layer "In11.Cu")
		(net "M_F_CPU1_SA_DQS_DP<8>")
	)
	(arc
		(start 77.940408 -242.487704)
		(mid 78.038305 -242.50099)
		(end 78.129384 -242.539266)
		(width 0.09525)
		(layer "In11.Cu")
		(net "M_F_CPU1_SA_DQS_DP<8>")
	)
	(arc
		(start 81.51241 -242.539266)
		(mid 81.696185 -242.488494)
		(end 81.881218 -242.53444)
		(width 0.09525)
		(layer "In11.Cu")
		(net "M_F_CPU1_SA_DQS_DP<8>")
	)
	(arc
		(start 79.079598 -242.545362)
		(mid 79.35676 -242.615162)
		(end 79.632302 -242.539266)
		(width 0.09525)
		(layer "In11.Cu")
		(net "M_F_CPU1_SA_DQS_DP<8>")
	)
	(arc
		(start 80.949546 -242.539266)
		(mid 81.230978 -242.615021)
		(end 81.51241 -242.539266)
		(width 0.09525)
		(layer "In11.Cu")
		(net "M_F_CPU1_SA_DQS_DP<8>")
	)
	(arc
		(start 78.129384 -242.539266)
		(mid 78.402312 -242.61508)
		(end 78.677516 -242.547902)
		(width 0.09525)
		(layer "In11.Cu")
		(net "M_F_CPU1_SA_DQS_DP<8>")
	)
	(arc
		(start 85.272372 -242.539266)
		(mid 85.42897 -242.489977)
		(end 85.59165 -242.512088)
		(width 0.09525)
		(layer "In11.Cu")
		(net "M_F_CPU1_SA_DQS_DP<8>")
	)
	(arc
		(start 80.009746 -242.539266)
		(mid 80.291178 -242.615021)
		(end 80.57261 -242.539266)
		(width 0.09525)
		(layer "In11.Cu")
		(net "M_F_CPU1_SA_DQS_DP<8>")
	)
	(arc
		(start 80.57261 -242.539266)
		(mid 80.761078 -242.488589)
		(end 80.949546 -242.539266)
		(width 0.09525)
		(layer "In11.Cu")
		(net "M_F_CPU1_SA_DQS_DP<8>")
	)
	(arc
		(start 82.829654 -242.539266)
		(mid 83.111086 -242.615021)
		(end 83.392518 -242.539266)
		(width 0.09525)
		(layer "In11.Cu")
		(net "M_F_CPU1_SA_DQS_DP<8>")
	)
	(arc
		(start 82.460846 -242.53444)
		(mid 82.645878 -242.488526)
		(end 82.829654 -242.539266)
		(width 0.09525)
		(layer "In11.Cu")
		(net "M_F_CPU1_SA_DQS_DP<8>")
	)
	(arc
		(start 81.8896 -242.539266)
		(mid 82.171032 -242.615021)
		(end 82.452464 -242.539266)
		(width 0.09525)
		(layer "In11.Cu")
		(net "M_F_CPU1_SA_DQS_DP<8>")
	)
	(segment
		(start 85.927946 -238.270288)
		(end 85.461094 -238.00435)
		(width 0.12954)
		(layer "F.Cu")
		(net "M_F_CPU1_SA_DQS_DP<7>")
	)
	(segment
		(start 18.66646 -220.978222)
		(end 19.14652 -220.978222)
		(width 0.16002)
		(layer "In11.Cu")
		(net "M_F_CPU1_SA_DQS_DP<7>")
	)
	(segment
		(start 46.66996 -221.860618)
		(end 48.665892 -221.860618)
		(width 0.16002)
		(layer "In11.Cu")
		(net "M_F_CPU1_SA_DQS_DP<7>")
	)
	(segment
		(start 62.36081 -224.919794)
		(end 73.39711 -235.956094)
		(width 0.16002)
		(layer "In11.Cu")
		(net "M_F_CPU1_SA_DQS_DP<7>")
	)
	(segment
		(start 28.01747 -220.656404)
		(end 28.371546 -221.01048)
		(width 0.16002)
		(layer "In11.Cu")
		(net "M_F_CPU1_SA_DQS_DP<7>")
	)
	(segment
		(start 85.615018 -237.73892)
		(end 85.461094 -238.00435)
		(width 0.09525)
		(layer "In11.Cu")
		(net "M_F_CPU1_SA_DQS_DP<7>")
	)
	(segment
		(start 20.516088 -220.695774)
		(end 20.862544 -221.04223)
		(width 0.16002)
		(layer "In11.Cu")
		(net "M_F_CPU1_SA_DQS_DP<7>")
	)
	(segment
		(start 35.259518 -220.656404)
		(end 35.561524 -220.656404)
		(width 0.16002)
		(layer "In11.Cu")
		(net "M_F_CPU1_SA_DQS_DP<7>")
	)
	(segment
		(start 19.26336 -220.861382)
		(end 19.7612 -220.861382)
		(width 0.16002)
		(layer "In11.Cu")
		(net "M_F_CPU1_SA_DQS_DP<7>")
	)
	(segment
		(start 43.105578 -220.656404)
		(end 43.459654 -221.01048)
		(width 0.16002)
		(layer "In11.Cu")
		(net "M_F_CPU1_SA_DQS_DP<7>")
	)
	(segment
		(start 19.926808 -220.695774)
		(end 20.516088 -220.695774)
		(width 0.16002)
		(layer "In11.Cu")
		(net "M_F_CPU1_SA_DQS_DP<7>")
	)
	(segment
		(start 31.581852 -221.860618)
		(end 33.577784 -221.860618)
		(width 0.16002)
		(layer "In11.Cu")
		(net "M_F_CPU1_SA_DQS_DP<7>")
	)
	(segment
		(start 41.919398 -221.540578)
		(end 42.803572 -220.656404)
		(width 0.16002)
		(layer "In11.Cu")
		(net "M_F_CPU1_SA_DQS_DP<7>")
	)
	(segment
		(start 76.976986 -236.287564)
		(end 77.205586 -236.516164)
		(width 0.09525)
		(layer "In11.Cu")
		(net "M_F_CPU1_SA_DQS_DP<7>")
	)
	(segment
		(start 58.571892 -221.830646)
		(end 59.802014 -221.830646)
		(width 0.16002)
		(layer "In11.Cu")
		(net "M_F_CPU1_SA_DQS_DP<7>")
	)
	(segment
		(start 18.54962 -220.861382)
		(end 18.66646 -220.978222)
		(width 0.16002)
		(layer "In11.Cu")
		(net "M_F_CPU1_SA_DQS_DP<7>")
	)
	(segment
		(start 17.608042 -221.135194)
		(end 17.881854 -220.861382)
		(width 0.16002)
		(layer "In11.Cu")
		(net "M_F_CPU1_SA_DQS_DP<7>")
	)
	(segment
		(start 77.205586 -236.781848)
		(end 78.014576 -237.590838)
		(width 0.09525)
		(layer "In11.Cu")
		(net "M_F_CPU1_SA_DQS_DP<7>")
	)
	(segment
		(start 77.205586 -236.516164)
		(end 77.205586 -236.781848)
		(width 0.09525)
		(layer "In11.Cu")
		(net "M_F_CPU1_SA_DQS_DP<7>")
	)
	(segment
		(start 78.680818 -237.685834)
		(end 78.704186 -237.672372)
		(width 0.09525)
		(layer "In11.Cu")
		(net "M_F_CPU1_SA_DQS_DP<7>")
	)
	(segment
		(start 57.10936 -221.540578)
		(end 57.645808 -222.077026)
		(width 0.16002)
		(layer "In11.Cu")
		(net "M_F_CPU1_SA_DQS_DP<7>")
	)
	(segment
		(start 19.7612 -220.861382)
		(end 19.926808 -220.695774)
		(width 0.16002)
		(layer "In11.Cu")
		(net "M_F_CPU1_SA_DQS_DP<7>")
	)
	(segment
		(start 73.39711 -235.956094)
		(end 75.955906 -235.956094)
		(width 0.16002)
		(layer "In11.Cu")
		(net "M_F_CPU1_SA_DQS_DP<7>")
	)
	(segment
		(start 48.665892 -221.860618)
		(end 48.985932 -221.540578)
		(width 0.16002)
		(layer "In11.Cu")
		(net "M_F_CPU1_SA_DQS_DP<7>")
	)
	(segment
		(start 33.897824 -221.540578)
		(end 34.375344 -221.540578)
		(width 0.16002)
		(layer "In11.Cu")
		(net "M_F_CPU1_SA_DQS_DP<7>")
	)
	(segment
		(start 78.677516 -237.687866)
		(end 78.679802 -237.686342)
		(width 0.09525)
		(layer "In11.Cu")
		(net "M_F_CPU1_SA_DQS_DP<7>")
	)
	(segment
		(start 23.252684 -221.04223)
		(end 24.071072 -221.860618)
		(width 0.16002)
		(layer "In11.Cu")
		(net "M_F_CPU1_SA_DQS_DP<7>")
	)
	(segment
		(start 76.038456 -235.897166)
		(end 76.199238 -235.897166)
		(width 0.09525)
		(layer "In11.Cu")
		(net "M_F_CPU1_SA_DQS_DP<7>")
	)
	(segment
		(start 39.125906 -221.860618)
		(end 41.121838 -221.860618)
		(width 0.16002)
		(layer "In11.Cu")
		(net "M_F_CPU1_SA_DQS_DP<7>")
	)
	(segment
		(start 79.069184 -237.67923)
		(end 79.079598 -237.685326)
		(width 0.09525)
		(layer "In11.Cu")
		(net "M_F_CPU1_SA_DQS_DP<7>")
	)
	(segment
		(start 26.35377 -221.540578)
		(end 26.83129 -221.540578)
		(width 0.16002)
		(layer "In11.Cu")
		(net "M_F_CPU1_SA_DQS_DP<7>")
	)
	(segment
		(start 62.36081 -224.389442)
		(end 62.36081 -224.919794)
		(width 0.16002)
		(layer "In11.Cu")
		(net "M_F_CPU1_SA_DQS_DP<7>")
	)
	(segment
		(start 78.679802 -237.686342)
		(end 78.680818 -237.685834)
		(width 0.09525)
		(layer "In11.Cu")
		(net "M_F_CPU1_SA_DQS_DP<7>")
	)
	(segment
		(start 49.463452 -221.540578)
		(end 50.347626 -220.656404)
		(width 0.16002)
		(layer "In11.Cu")
		(net "M_F_CPU1_SA_DQS_DP<7>")
	)
	(segment
		(start 24.071072 -221.860618)
		(end 26.03373 -221.860618)
		(width 0.16002)
		(layer "In11.Cu")
		(net "M_F_CPU1_SA_DQS_DP<7>")
	)
	(segment
		(start 33.577784 -221.860618)
		(end 33.897824 -221.540578)
		(width 0.16002)
		(layer "In11.Cu")
		(net "M_F_CPU1_SA_DQS_DP<7>")
	)
	(segment
		(start 76.589636 -236.287564)
		(end 76.976986 -236.287564)
		(width 0.09525)
		(layer "In11.Cu")
		(net "M_F_CPU1_SA_DQS_DP<7>")
	)
	(segment
		(start 50.347626 -220.656404)
		(end 50.649632 -220.656404)
		(width 0.16002)
		(layer "In11.Cu")
		(net "M_F_CPU1_SA_DQS_DP<7>")
	)
	(segment
		(start 75.979528 -235.956094)
		(end 76.038456 -235.897166)
		(width 0.09525)
		(layer "In11.Cu")
		(net "M_F_CPU1_SA_DQS_DP<7>")
	)
	(segment
		(start 81.881218 -237.674404)
		(end 81.8896 -237.67923)
		(width 0.09525)
		(layer "In11.Cu")
		(net "M_F_CPU1_SA_DQS_DP<7>")
	)
	(segment
		(start 26.83129 -221.540578)
		(end 27.715464 -220.656404)
		(width 0.16002)
		(layer "In11.Cu")
		(net "M_F_CPU1_SA_DQS_DP<7>")
	)
	(segment
		(start 83.392518 -237.67923)
		(end 83.4009 -237.674404)
		(width 0.09525)
		(layer "In11.Cu")
		(net "M_F_CPU1_SA_DQS_DP<7>")
	)
	(segment
		(start 50.649632 -220.656404)
		(end 51.003708 -221.01048)
		(width 0.16002)
		(layer "In11.Cu")
		(net "M_F_CPU1_SA_DQS_DP<7>")
	)
	(segment
		(start 57.645808 -222.077026)
		(end 58.325512 -222.077026)
		(width 0.16002)
		(layer "In11.Cu")
		(net "M_F_CPU1_SA_DQS_DP<7>")
	)
	(segment
		(start 53.893974 -221.540578)
		(end 57.10936 -221.540578)
		(width 0.16002)
		(layer "In11.Cu")
		(net "M_F_CPU1_SA_DQS_DP<7>")
	)
	(segment
		(start 59.802014 -221.830646)
		(end 62.36081 -224.389442)
		(width 0.16002)
		(layer "In11.Cu")
		(net "M_F_CPU1_SA_DQS_DP<7>")
	)
	(segment
		(start 42.803572 -220.656404)
		(end 43.105578 -220.656404)
		(width 0.16002)
		(layer "In11.Cu")
		(net "M_F_CPU1_SA_DQS_DP<7>")
	)
	(segment
		(start 76.199238 -235.897166)
		(end 76.589636 -236.287564)
		(width 0.09525)
		(layer "In11.Cu")
		(net "M_F_CPU1_SA_DQS_DP<7>")
	)
	(segment
		(start 38.275768 -221.01048)
		(end 39.125906 -221.860618)
		(width 0.16002)
		(layer "In11.Cu")
		(net "M_F_CPU1_SA_DQS_DP<7>")
	)
	(segment
		(start 75.955906 -235.956094)
		(end 75.979528 -235.956094)
		(width 0.09525)
		(layer "In11.Cu")
		(net "M_F_CPU1_SA_DQS_DP<7>")
	)
	(segment
		(start 30.731714 -221.01048)
		(end 31.581852 -221.860618)
		(width 0.16002)
		(layer "In11.Cu")
		(net "M_F_CPU1_SA_DQS_DP<7>")
	)
	(segment
		(start 26.03373 -221.860618)
		(end 26.35377 -221.540578)
		(width 0.16002)
		(layer "In11.Cu")
		(net "M_F_CPU1_SA_DQS_DP<7>")
	)
	(segment
		(start 51.003708 -221.01048)
		(end 53.363876 -221.01048)
		(width 0.16002)
		(layer "In11.Cu")
		(net "M_F_CPU1_SA_DQS_DP<7>")
	)
	(segment
		(start 85.59165 -237.652052)
		(end 85.615018 -237.73892)
		(width 0.09525)
		(layer "In11.Cu")
		(net "M_F_CPU1_SA_DQS_DP<7>")
	)
	(segment
		(start 43.459654 -221.01048)
		(end 45.819822 -221.01048)
		(width 0.16002)
		(layer "In11.Cu")
		(net "M_F_CPU1_SA_DQS_DP<7>")
	)
	(segment
		(start 34.375344 -221.540578)
		(end 35.259518 -220.656404)
		(width 0.16002)
		(layer "In11.Cu")
		(net "M_F_CPU1_SA_DQS_DP<7>")
	)
	(segment
		(start 48.985932 -221.540578)
		(end 49.463452 -221.540578)
		(width 0.16002)
		(layer "In11.Cu")
		(net "M_F_CPU1_SA_DQS_DP<7>")
	)
	(segment
		(start 19.14652 -220.978222)
		(end 19.26336 -220.861382)
		(width 0.16002)
		(layer "In11.Cu")
		(net "M_F_CPU1_SA_DQS_DP<7>")
	)
	(segment
		(start 82.452464 -237.67923)
		(end 82.460846 -237.674404)
		(width 0.09525)
		(layer "In11.Cu")
		(net "M_F_CPU1_SA_DQS_DP<7>")
	)
	(segment
		(start 45.819822 -221.01048)
		(end 46.66996 -221.860618)
		(width 0.16002)
		(layer "In11.Cu")
		(net "M_F_CPU1_SA_DQS_DP<7>")
	)
	(segment
		(start 58.325512 -222.077026)
		(end 58.571892 -221.830646)
		(width 0.16002)
		(layer "In11.Cu")
		(net "M_F_CPU1_SA_DQS_DP<7>")
	)
	(segment
		(start 27.715464 -220.656404)
		(end 28.01747 -220.656404)
		(width 0.16002)
		(layer "In11.Cu")
		(net "M_F_CPU1_SA_DQS_DP<7>")
	)
	(segment
		(start 20.862544 -221.04223)
		(end 23.252684 -221.04223)
		(width 0.16002)
		(layer "In11.Cu")
		(net "M_F_CPU1_SA_DQS_DP<7>")
	)
	(segment
		(start 28.371546 -221.01048)
		(end 30.731714 -221.01048)
		(width 0.16002)
		(layer "In11.Cu")
		(net "M_F_CPU1_SA_DQS_DP<7>")
	)
	(segment
		(start 35.9156 -221.01048)
		(end 38.275768 -221.01048)
		(width 0.16002)
		(layer "In11.Cu")
		(net "M_F_CPU1_SA_DQS_DP<7>")
	)
	(segment
		(start 41.121838 -221.860618)
		(end 41.441878 -221.540578)
		(width 0.16002)
		(layer "In11.Cu")
		(net "M_F_CPU1_SA_DQS_DP<7>")
	)
	(segment
		(start 53.363876 -221.01048)
		(end 53.893974 -221.540578)
		(width 0.16002)
		(layer "In11.Cu")
		(net "M_F_CPU1_SA_DQS_DP<7>")
	)
	(segment
		(start 17.881854 -220.861382)
		(end 18.54962 -220.861382)
		(width 0.16002)
		(layer "In11.Cu")
		(net "M_F_CPU1_SA_DQS_DP<7>")
	)
	(segment
		(start 35.561524 -220.656404)
		(end 35.9156 -221.01048)
		(width 0.16002)
		(layer "In11.Cu")
		(net "M_F_CPU1_SA_DQS_DP<7>")
	)
	(segment
		(start 41.441878 -221.540578)
		(end 41.919398 -221.540578)
		(width 0.16002)
		(layer "In11.Cu")
		(net "M_F_CPU1_SA_DQS_DP<7>")
	)
	(arc
		(start 84.709508 -237.67923)
		(mid 84.99094 -237.754985)
		(end 85.272372 -237.67923)
		(width 0.09525)
		(layer "In11.Cu")
		(net "M_F_CPU1_SA_DQS_DP<7>")
	)
	(arc
		(start 79.079598 -237.685326)
		(mid 79.35676 -237.755126)
		(end 79.632302 -237.67923)
		(width 0.09525)
		(layer "In11.Cu")
		(net "M_F_CPU1_SA_DQS_DP<7>")
	)
	(arc
		(start 85.272372 -237.67923)
		(mid 85.42897 -237.629941)
		(end 85.59165 -237.652052)
		(width 0.09525)
		(layer "In11.Cu")
		(net "M_F_CPU1_SA_DQS_DP<7>")
	)
	(arc
		(start 80.949546 -237.67923)
		(mid 81.230978 -237.754985)
		(end 81.51241 -237.67923)
		(width 0.09525)
		(layer "In11.Cu")
		(net "M_F_CPU1_SA_DQS_DP<7>")
	)
	(arc
		(start 84.332572 -237.67923)
		(mid 84.52104 -237.628553)
		(end 84.709508 -237.67923)
		(width 0.09525)
		(layer "In11.Cu")
		(net "M_F_CPU1_SA_DQS_DP<7>")
	)
	(arc
		(start 81.51241 -237.67923)
		(mid 81.696185 -237.628458)
		(end 81.881218 -237.674404)
		(width 0.09525)
		(layer "In11.Cu")
		(net "M_F_CPU1_SA_DQS_DP<7>")
	)
	(arc
		(start 78.704186 -237.672372)
		(mid 78.887567 -237.628541)
		(end 79.069184 -237.67923)
		(width 0.09525)
		(layer "In11.Cu")
		(net "M_F_CPU1_SA_DQS_DP<7>")
	)
	(arc
		(start 81.8896 -237.67923)
		(mid 82.171032 -237.754985)
		(end 82.452464 -237.67923)
		(width 0.09525)
		(layer "In11.Cu")
		(net "M_F_CPU1_SA_DQS_DP<7>")
	)
	(arc
		(start 80.57261 -237.67923)
		(mid 80.761078 -237.628553)
		(end 80.949546 -237.67923)
		(width 0.09525)
		(layer "In11.Cu")
		(net "M_F_CPU1_SA_DQS_DP<7>")
	)
	(arc
		(start 82.460846 -237.674404)
		(mid 82.645878 -237.62849)
		(end 82.829654 -237.67923)
		(width 0.09525)
		(layer "In11.Cu")
		(net "M_F_CPU1_SA_DQS_DP<7>")
	)
	(arc
		(start 80.009746 -237.67923)
		(mid 80.291178 -237.754985)
		(end 80.57261 -237.67923)
		(width 0.09525)
		(layer "In11.Cu")
		(net "M_F_CPU1_SA_DQS_DP<7>")
	)
	(arc
		(start 78.014576 -237.590838)
		(mid 78.329951 -237.749173)
		(end 78.677516 -237.687866)
		(width 0.09525)
		(layer "In11.Cu")
		(net "M_F_CPU1_SA_DQS_DP<7>")
	)
	(arc
		(start 82.829654 -237.67923)
		(mid 83.111086 -237.754985)
		(end 83.392518 -237.67923)
		(width 0.09525)
		(layer "In11.Cu")
		(net "M_F_CPU1_SA_DQS_DP<7>")
	)
	(arc
		(start 79.632302 -237.67923)
		(mid 79.821024 -237.628426)
		(end 80.009746 -237.67923)
		(width 0.09525)
		(layer "In11.Cu")
		(net "M_F_CPU1_SA_DQS_DP<7>")
	)
	(arc
		(start 83.4009 -237.674404)
		(mid 83.585932 -237.62849)
		(end 83.769708 -237.67923)
		(width 0.09525)
		(layer "In11.Cu")
		(net "M_F_CPU1_SA_DQS_DP<7>")
	)
	(arc
		(start 83.769708 -237.67923)
		(mid 84.05114 -237.754985)
		(end 84.332572 -237.67923)
		(width 0.09525)
		(layer "In11.Cu")
		(net "M_F_CPU1_SA_DQS_DP<7>")
	)
	(segment
		(start 85.927946 -233.410252)
		(end 85.461094 -233.144314)
		(width 0.12954)
		(layer "F.Cu")
		(net "M_F_CPU1_SA_DQS_DP<6>")
	)
	(segment
		(start 83.392518 -232.819194)
		(end 83.4009 -232.814368)
		(width 0.09525)
		(layer "In11.Cu")
		(net "M_F_CPU1_SA_DQS_DP<6>")
	)
	(segment
		(start 77.10043 -231.225344)
		(end 77.392276 -231.51719)
		(width 0.09525)
		(layer "In11.Cu")
		(net "M_F_CPU1_SA_DQS_DP<6>")
	)
	(segment
		(start 76.25969 -230.650796)
		(end 76.834238 -231.225344)
		(width 0.09525)
		(layer "In11.Cu")
		(net "M_F_CPU1_SA_DQS_DP<6>")
	)
	(segment
		(start 78.677516 -232.82783)
		(end 78.704186 -232.812336)
		(width 0.09525)
		(layer "In11.Cu")
		(net "M_F_CPU1_SA_DQS_DP<6>")
	)
	(segment
		(start 76.25969 -230.337106)
		(end 76.25969 -230.650796)
		(width 0.09525)
		(layer "In11.Cu")
		(net "M_F_CPU1_SA_DQS_DP<6>")
	)
	(segment
		(start 76.038456 -230.241856)
		(end 76.16444 -230.241856)
		(width 0.09525)
		(layer "In11.Cu")
		(net "M_F_CPU1_SA_DQS_DP<6>")
	)
	(segment
		(start 76.834238 -231.225344)
		(end 77.10043 -231.225344)
		(width 0.09525)
		(layer "In11.Cu")
		(net "M_F_CPU1_SA_DQS_DP<6>")
	)
	(segment
		(start 20.862544 -211.692236)
		(end 23.252684 -211.692236)
		(width 0.16002)
		(layer "In11.Cu")
		(net "M_F_CPU1_SA_DQS_DP<6>")
	)
	(segment
		(start 68.05549 -222.6818)
		(end 75.674474 -230.300784)
		(width 0.16002)
		(layer "In11.Cu")
		(net "M_F_CPU1_SA_DQS_DP<6>")
	)
	(segment
		(start 43.105578 -211.30641)
		(end 43.459654 -211.660486)
		(width 0.16002)
		(layer "In11.Cu")
		(net "M_F_CPU1_SA_DQS_DP<6>")
	)
	(segment
		(start 48.665892 -212.510624)
		(end 48.985932 -212.190584)
		(width 0.16002)
		(layer "In11.Cu")
		(net "M_F_CPU1_SA_DQS_DP<6>")
	)
	(segment
		(start 81.881218 -232.814368)
		(end 81.8896 -232.819194)
		(width 0.09525)
		(layer "In11.Cu")
		(net "M_F_CPU1_SA_DQS_DP<6>")
	)
	(segment
		(start 26.83129 -212.190584)
		(end 27.715464 -211.30641)
		(width 0.16002)
		(layer "In11.Cu")
		(net "M_F_CPU1_SA_DQS_DP<6>")
	)
	(segment
		(start 35.259518 -211.30641)
		(end 35.561524 -211.30641)
		(width 0.16002)
		(layer "In11.Cu")
		(net "M_F_CPU1_SA_DQS_DP<6>")
	)
	(segment
		(start 75.979528 -230.300784)
		(end 76.038456 -230.241856)
		(width 0.09525)
		(layer "In11.Cu")
		(net "M_F_CPU1_SA_DQS_DP<6>")
	)
	(segment
		(start 57.891426 -211.30641)
		(end 59.354974 -211.30641)
		(width 0.16002)
		(layer "In11.Cu")
		(net "M_F_CPU1_SA_DQS_DP<6>")
	)
	(segment
		(start 50.347626 -211.30641)
		(end 50.649632 -211.30641)
		(width 0.16002)
		(layer "In11.Cu")
		(net "M_F_CPU1_SA_DQS_DP<6>")
	)
	(segment
		(start 38.275768 -211.660486)
		(end 39.125906 -212.510624)
		(width 0.16002)
		(layer "In11.Cu")
		(net "M_F_CPU1_SA_DQS_DP<6>")
	)
	(segment
		(start 17.608042 -211.7852)
		(end 17.881854 -211.511388)
		(width 0.16002)
		(layer "In11.Cu")
		(net "M_F_CPU1_SA_DQS_DP<6>")
	)
	(segment
		(start 68.05549 -221.34703)
		(end 68.05549 -222.6818)
		(width 0.16002)
		(layer "In11.Cu")
		(net "M_F_CPU1_SA_DQS_DP<6>")
	)
	(segment
		(start 35.561524 -211.30641)
		(end 35.9156 -211.660486)
		(width 0.16002)
		(layer "In11.Cu")
		(net "M_F_CPU1_SA_DQS_DP<6>")
	)
	(segment
		(start 39.125906 -212.510624)
		(end 41.121838 -212.510624)
		(width 0.16002)
		(layer "In11.Cu")
		(net "M_F_CPU1_SA_DQS_DP<6>")
	)
	(segment
		(start 41.441878 -212.190584)
		(end 41.919398 -212.190584)
		(width 0.16002)
		(layer "In11.Cu")
		(net "M_F_CPU1_SA_DQS_DP<6>")
	)
	(segment
		(start 59.354974 -211.30641)
		(end 62.84087 -214.792306)
		(width 0.16002)
		(layer "In11.Cu")
		(net "M_F_CPU1_SA_DQS_DP<6>")
	)
	(segment
		(start 48.985932 -212.190584)
		(end 49.463452 -212.190584)
		(width 0.16002)
		(layer "In11.Cu")
		(net "M_F_CPU1_SA_DQS_DP<6>")
	)
	(segment
		(start 42.803572 -211.30641)
		(end 43.105578 -211.30641)
		(width 0.16002)
		(layer "In11.Cu")
		(net "M_F_CPU1_SA_DQS_DP<6>")
	)
	(segment
		(start 19.926808 -211.34578)
		(end 20.516088 -211.34578)
		(width 0.16002)
		(layer "In11.Cu")
		(net "M_F_CPU1_SA_DQS_DP<6>")
	)
	(segment
		(start 33.577784 -212.510624)
		(end 33.897824 -212.190584)
		(width 0.16002)
		(layer "In11.Cu")
		(net "M_F_CPU1_SA_DQS_DP<6>")
	)
	(segment
		(start 82.452464 -232.819194)
		(end 82.460846 -232.814368)
		(width 0.09525)
		(layer "In11.Cu")
		(net "M_F_CPU1_SA_DQS_DP<6>")
	)
	(segment
		(start 85.59165 -232.792016)
		(end 85.615018 -232.878884)
		(width 0.09525)
		(layer "In11.Cu")
		(net "M_F_CPU1_SA_DQS_DP<6>")
	)
	(segment
		(start 41.919398 -212.190584)
		(end 42.803572 -211.30641)
		(width 0.16002)
		(layer "In11.Cu")
		(net "M_F_CPU1_SA_DQS_DP<6>")
	)
	(segment
		(start 24.071072 -212.510624)
		(end 26.03373 -212.510624)
		(width 0.16002)
		(layer "In11.Cu")
		(net "M_F_CPU1_SA_DQS_DP<6>")
	)
	(segment
		(start 46.66996 -212.510624)
		(end 48.665892 -212.510624)
		(width 0.16002)
		(layer "In11.Cu")
		(net "M_F_CPU1_SA_DQS_DP<6>")
	)
	(segment
		(start 77.392276 -231.51719)
		(end 77.392276 -232.108502)
		(width 0.09525)
		(layer "In11.Cu")
		(net "M_F_CPU1_SA_DQS_DP<6>")
	)
	(segment
		(start 75.674474 -230.300784)
		(end 75.955906 -230.300784)
		(width 0.16002)
		(layer "In11.Cu")
		(net "M_F_CPU1_SA_DQS_DP<6>")
	)
	(segment
		(start 30.731714 -211.660486)
		(end 31.581852 -212.510624)
		(width 0.16002)
		(layer "In11.Cu")
		(net "M_F_CPU1_SA_DQS_DP<6>")
	)
	(segment
		(start 35.9156 -211.660486)
		(end 38.275768 -211.660486)
		(width 0.16002)
		(layer "In11.Cu")
		(net "M_F_CPU1_SA_DQS_DP<6>")
	)
	(segment
		(start 51.003708 -211.660486)
		(end 53.363876 -211.660486)
		(width 0.16002)
		(layer "In11.Cu")
		(net "M_F_CPU1_SA_DQS_DP<6>")
	)
	(segment
		(start 20.516088 -211.34578)
		(end 20.862544 -211.692236)
		(width 0.16002)
		(layer "In11.Cu")
		(net "M_F_CPU1_SA_DQS_DP<6>")
	)
	(segment
		(start 34.375344 -212.190584)
		(end 35.259518 -211.30641)
		(width 0.16002)
		(layer "In11.Cu")
		(net "M_F_CPU1_SA_DQS_DP<6>")
	)
	(segment
		(start 19.1643 -211.628228)
		(end 19.28114 -211.511388)
		(width 0.16002)
		(layer "In11.Cu")
		(net "M_F_CPU1_SA_DQS_DP<6>")
	)
	(segment
		(start 28.371546 -211.660486)
		(end 30.731714 -211.660486)
		(width 0.16002)
		(layer "In11.Cu")
		(net "M_F_CPU1_SA_DQS_DP<6>")
	)
	(segment
		(start 85.615018 -232.878884)
		(end 85.461094 -233.144314)
		(width 0.09525)
		(layer "In11.Cu")
		(net "M_F_CPU1_SA_DQS_DP<6>")
	)
	(segment
		(start 79.069184 -232.819194)
		(end 79.079598 -232.82529)
		(width 0.09525)
		(layer "In11.Cu")
		(net "M_F_CPU1_SA_DQS_DP<6>")
	)
	(segment
		(start 43.459654 -211.660486)
		(end 45.819822 -211.660486)
		(width 0.16002)
		(layer "In11.Cu")
		(net "M_F_CPU1_SA_DQS_DP<6>")
	)
	(segment
		(start 31.581852 -212.510624)
		(end 33.577784 -212.510624)
		(width 0.16002)
		(layer "In11.Cu")
		(net "M_F_CPU1_SA_DQS_DP<6>")
	)
	(segment
		(start 26.03373 -212.510624)
		(end 26.35377 -212.190584)
		(width 0.16002)
		(layer "In11.Cu")
		(net "M_F_CPU1_SA_DQS_DP<6>")
	)
	(segment
		(start 33.897824 -212.190584)
		(end 34.375344 -212.190584)
		(width 0.16002)
		(layer "In11.Cu")
		(net "M_F_CPU1_SA_DQS_DP<6>")
	)
	(segment
		(start 53.893974 -212.190584)
		(end 57.007252 -212.190584)
		(width 0.16002)
		(layer "In11.Cu")
		(net "M_F_CPU1_SA_DQS_DP<6>")
	)
	(segment
		(start 57.007252 -212.190584)
		(end 57.891426 -211.30641)
		(width 0.16002)
		(layer "In11.Cu")
		(net "M_F_CPU1_SA_DQS_DP<6>")
	)
	(segment
		(start 50.649632 -211.30641)
		(end 51.003708 -211.660486)
		(width 0.16002)
		(layer "In11.Cu")
		(net "M_F_CPU1_SA_DQS_DP<6>")
	)
	(segment
		(start 26.35377 -212.190584)
		(end 26.83129 -212.190584)
		(width 0.16002)
		(layer "In11.Cu")
		(net "M_F_CPU1_SA_DQS_DP<6>")
	)
	(segment
		(start 49.463452 -212.190584)
		(end 50.347626 -211.30641)
		(width 0.16002)
		(layer "In11.Cu")
		(net "M_F_CPU1_SA_DQS_DP<6>")
	)
	(segment
		(start 23.252684 -211.692236)
		(end 24.071072 -212.510624)
		(width 0.16002)
		(layer "In11.Cu")
		(net "M_F_CPU1_SA_DQS_DP<6>")
	)
	(segment
		(start 77.392276 -232.108502)
		(end 78.014576 -232.730802)
		(width 0.09525)
		(layer "In11.Cu")
		(net "M_F_CPU1_SA_DQS_DP<6>")
	)
	(segment
		(start 19.28114 -211.511388)
		(end 19.7612 -211.511388)
		(width 0.16002)
		(layer "In11.Cu")
		(net "M_F_CPU1_SA_DQS_DP<6>")
	)
	(segment
		(start 75.955906 -230.300784)
		(end 75.979528 -230.300784)
		(width 0.09525)
		(layer "In11.Cu")
		(net "M_F_CPU1_SA_DQS_DP<6>")
	)
	(segment
		(start 41.121838 -212.510624)
		(end 41.441878 -212.190584)
		(width 0.16002)
		(layer "In11.Cu")
		(net "M_F_CPU1_SA_DQS_DP<6>")
	)
	(segment
		(start 76.16444 -230.241856)
		(end 76.25969 -230.337106)
		(width 0.09525)
		(layer "In11.Cu")
		(net "M_F_CPU1_SA_DQS_DP<6>")
	)
	(segment
		(start 53.363876 -211.660486)
		(end 53.893974 -212.190584)
		(width 0.16002)
		(layer "In11.Cu")
		(net "M_F_CPU1_SA_DQS_DP<6>")
	)
	(segment
		(start 28.01747 -211.30641)
		(end 28.371546 -211.660486)
		(width 0.16002)
		(layer "In11.Cu")
		(net "M_F_CPU1_SA_DQS_DP<6>")
	)
	(segment
		(start 18.5674 -211.511388)
		(end 18.68424 -211.628228)
		(width 0.16002)
		(layer "In11.Cu")
		(net "M_F_CPU1_SA_DQS_DP<6>")
	)
	(segment
		(start 62.84087 -216.13241)
		(end 68.05549 -221.34703)
		(width 0.16002)
		(layer "In11.Cu")
		(net "M_F_CPU1_SA_DQS_DP<6>")
	)
	(segment
		(start 62.84087 -214.792306)
		(end 62.84087 -216.13241)
		(width 0.16002)
		(layer "In11.Cu")
		(net "M_F_CPU1_SA_DQS_DP<6>")
	)
	(segment
		(start 19.7612 -211.511388)
		(end 19.926808 -211.34578)
		(width 0.16002)
		(layer "In11.Cu")
		(net "M_F_CPU1_SA_DQS_DP<6>")
	)
	(segment
		(start 18.68424 -211.628228)
		(end 19.1643 -211.628228)
		(width 0.16002)
		(layer "In11.Cu")
		(net "M_F_CPU1_SA_DQS_DP<6>")
	)
	(segment
		(start 27.715464 -211.30641)
		(end 28.01747 -211.30641)
		(width 0.16002)
		(layer "In11.Cu")
		(net "M_F_CPU1_SA_DQS_DP<6>")
	)
	(segment
		(start 17.881854 -211.511388)
		(end 18.5674 -211.511388)
		(width 0.16002)
		(layer "In11.Cu")
		(net "M_F_CPU1_SA_DQS_DP<6>")
	)
	(segment
		(start 45.819822 -211.660486)
		(end 46.66996 -212.510624)
		(width 0.16002)
		(layer "In11.Cu")
		(net "M_F_CPU1_SA_DQS_DP<6>")
	)
	(arc
		(start 80.009746 -232.819194)
		(mid 80.291178 -232.894949)
		(end 80.57261 -232.819194)
		(width 0.09525)
		(layer "In11.Cu")
		(net "M_F_CPU1_SA_DQS_DP<6>")
	)
	(arc
		(start 80.57261 -232.819194)
		(mid 80.761078 -232.768517)
		(end 80.949546 -232.819194)
		(width 0.09525)
		(layer "In11.Cu")
		(net "M_F_CPU1_SA_DQS_DP<6>")
	)
	(arc
		(start 83.769708 -232.819194)
		(mid 84.05114 -232.894949)
		(end 84.332572 -232.819194)
		(width 0.09525)
		(layer "In11.Cu")
		(net "M_F_CPU1_SA_DQS_DP<6>")
	)
	(arc
		(start 78.704186 -232.812336)
		(mid 78.887567 -232.768505)
		(end 79.069184 -232.819194)
		(width 0.09525)
		(layer "In11.Cu")
		(net "M_F_CPU1_SA_DQS_DP<6>")
	)
	(arc
		(start 78.014576 -232.730802)
		(mid 78.068986 -232.778715)
		(end 78.12913 -232.819194)
		(width 0.09525)
		(layer "In11.Cu")
		(net "M_F_CPU1_SA_DQS_DP<6>")
	)
	(arc
		(start 79.079598 -232.82529)
		(mid 79.35676 -232.89509)
		(end 79.632302 -232.819194)
		(width 0.09525)
		(layer "In11.Cu")
		(net "M_F_CPU1_SA_DQS_DP<6>")
	)
	(arc
		(start 83.4009 -232.814368)
		(mid 83.585932 -232.768454)
		(end 83.769708 -232.819194)
		(width 0.09525)
		(layer "In11.Cu")
		(net "M_F_CPU1_SA_DQS_DP<6>")
	)
	(arc
		(start 80.949546 -232.819194)
		(mid 81.230978 -232.894949)
		(end 81.51241 -232.819194)
		(width 0.09525)
		(layer "In11.Cu")
		(net "M_F_CPU1_SA_DQS_DP<6>")
	)
	(arc
		(start 84.332572 -232.819194)
		(mid 84.52104 -232.768517)
		(end 84.709508 -232.819194)
		(width 0.09525)
		(layer "In11.Cu")
		(net "M_F_CPU1_SA_DQS_DP<6>")
	)
	(arc
		(start 82.829654 -232.819194)
		(mid 83.111086 -232.894949)
		(end 83.392518 -232.819194)
		(width 0.09525)
		(layer "In11.Cu")
		(net "M_F_CPU1_SA_DQS_DP<6>")
	)
	(arc
		(start 79.632302 -232.819194)
		(mid 79.821024 -232.76839)
		(end 80.009746 -232.819194)
		(width 0.09525)
		(layer "In11.Cu")
		(net "M_F_CPU1_SA_DQS_DP<6>")
	)
	(arc
		(start 85.272372 -232.819194)
		(mid 85.42897 -232.769905)
		(end 85.59165 -232.792016)
		(width 0.09525)
		(layer "In11.Cu")
		(net "M_F_CPU1_SA_DQS_DP<6>")
	)
	(arc
		(start 82.460846 -232.814368)
		(mid 82.645878 -232.768454)
		(end 82.829654 -232.819194)
		(width 0.09525)
		(layer "In11.Cu")
		(net "M_F_CPU1_SA_DQS_DP<6>")
	)
	(arc
		(start 81.51241 -232.819194)
		(mid 81.696185 -232.768422)
		(end 81.881218 -232.814368)
		(width 0.09525)
		(layer "In11.Cu")
		(net "M_F_CPU1_SA_DQS_DP<6>")
	)
	(arc
		(start 78.12913 -232.819194)
		(mid 78.402201 -232.895134)
		(end 78.677516 -232.82783)
		(width 0.09525)
		(layer "In11.Cu")
		(net "M_F_CPU1_SA_DQS_DP<6>")
	)
	(arc
		(start 81.8896 -232.819194)
		(mid 82.171032 -232.894949)
		(end 82.452464 -232.819194)
		(width 0.09525)
		(layer "In11.Cu")
		(net "M_F_CPU1_SA_DQS_DP<6>")
	)
	(arc
		(start 84.709508 -232.819194)
		(mid 84.99094 -232.894949)
		(end 85.272372 -232.819194)
		(width 0.09525)
		(layer "In11.Cu")
		(net "M_F_CPU1_SA_DQS_DP<6>")
	)
	(segment
		(start 85.927946 -228.55047)
		(end 85.461094 -228.284532)
		(width 0.12954)
		(layer "F.Cu")
		(net "M_F_CPU1_SA_DQS_DP<5>")
	)
	(segment
		(start 26.03373 -203.16063)
		(end 26.35377 -202.84059)
		(width 0.16002)
		(layer "In11.Cu")
		(net "M_F_CPU1_SA_DQS_DP<5>")
	)
	(segment
		(start 28.01747 -201.956416)
		(end 28.371546 -202.310492)
		(width 0.16002)
		(layer "In11.Cu")
		(net "M_F_CPU1_SA_DQS_DP<5>")
	)
	(segment
		(start 41.919398 -202.84059)
		(end 42.803572 -201.956416)
		(width 0.16002)
		(layer "In11.Cu")
		(net "M_F_CPU1_SA_DQS_DP<5>")
	)
	(segment
		(start 19.1643 -202.278234)
		(end 19.28114 -202.161394)
		(width 0.16002)
		(layer "In11.Cu")
		(net "M_F_CPU1_SA_DQS_DP<5>")
	)
	(segment
		(start 26.35377 -202.84059)
		(end 26.83129 -202.84059)
		(width 0.16002)
		(layer "In11.Cu")
		(net "M_F_CPU1_SA_DQS_DP<5>")
	)
	(segment
		(start 57.891426 -201.956416)
		(end 59.83732 -201.956416)
		(width 0.16002)
		(layer "In11.Cu")
		(net "M_F_CPU1_SA_DQS_DP<5>")
	)
	(segment
		(start 79.029306 -227.576888)
		(end 79.16037 -227.708206)
		(width 0.09525)
		(layer "In11.Cu")
		(net "M_F_CPU1_SA_DQS_DP<5>")
	)
	(segment
		(start 51.003708 -202.310492)
		(end 53.363876 -202.310492)
		(width 0.16002)
		(layer "In11.Cu")
		(net "M_F_CPU1_SA_DQS_DP<5>")
	)
	(segment
		(start 21.939504 -202.459082)
		(end 22.056344 -202.342242)
		(width 0.16002)
		(layer "In11.Cu")
		(net "M_F_CPU1_SA_DQS_DP<5>")
	)
	(segment
		(start 46.66996 -203.16063)
		(end 48.665892 -203.16063)
		(width 0.16002)
		(layer "In11.Cu")
		(net "M_F_CPU1_SA_DQS_DP<5>")
	)
	(segment
		(start 77.378814 -223.216216)
		(end 77.378814 -223.424496)
		(width 0.09525)
		(layer "In11.Cu")
		(net "M_F_CPU1_SA_DQS_DP<5>")
	)
	(segment
		(start 53.893974 -202.84059)
		(end 57.007252 -202.84059)
		(width 0.16002)
		(layer "In11.Cu")
		(net "M_F_CPU1_SA_DQS_DP<5>")
	)
	(segment
		(start 76.953364 -222.874586)
		(end 76.970128 -222.89135)
		(width 0.09525)
		(layer "In11.Cu")
		(net "M_F_CPU1_SA_DQS_DP<5>")
	)
	(segment
		(start 82.452464 -227.959412)
		(end 82.460846 -227.954586)
		(width 0.09525)
		(layer "In11.Cu")
		(net "M_F_CPU1_SA_DQS_DP<5>")
	)
	(segment
		(start 34.375344 -202.84059)
		(end 35.259518 -201.956416)
		(width 0.16002)
		(layer "In11.Cu")
		(net "M_F_CPU1_SA_DQS_DP<5>")
	)
	(segment
		(start 48.665892 -203.16063)
		(end 48.985932 -202.84059)
		(width 0.16002)
		(layer "In11.Cu")
		(net "M_F_CPU1_SA_DQS_DP<5>")
	)
	(segment
		(start 41.121838 -203.16063)
		(end 41.441878 -202.84059)
		(width 0.16002)
		(layer "In11.Cu")
		(net "M_F_CPU1_SA_DQS_DP<5>")
	)
	(segment
		(start 21.459444 -202.459082)
		(end 21.939504 -202.459082)
		(width 0.16002)
		(layer "In11.Cu")
		(net "M_F_CPU1_SA_DQS_DP<5>")
	)
	(segment
		(start 20.516088 -201.995786)
		(end 20.862544 -202.342242)
		(width 0.16002)
		(layer "In11.Cu")
		(net "M_F_CPU1_SA_DQS_DP<5>")
	)
	(segment
		(start 73.87463 -217.477086)
		(end 73.87463 -219.795852)
		(width 0.16002)
		(layer "In11.Cu")
		(net "M_F_CPU1_SA_DQS_DP<5>")
	)
	(segment
		(start 17.881854 -202.161394)
		(end 18.5674 -202.161394)
		(width 0.16002)
		(layer "In11.Cu")
		(net "M_F_CPU1_SA_DQS_DP<5>")
	)
	(segment
		(start 19.7612 -202.161394)
		(end 19.926808 -201.995786)
		(width 0.16002)
		(layer "In11.Cu")
		(net "M_F_CPU1_SA_DQS_DP<5>")
	)
	(segment
		(start 33.897824 -202.84059)
		(end 34.375344 -202.84059)
		(width 0.16002)
		(layer "In11.Cu")
		(net "M_F_CPU1_SA_DQS_DP<5>")
	)
	(segment
		(start 23.252684 -202.342242)
		(end 24.071072 -203.16063)
		(width 0.16002)
		(layer "In11.Cu")
		(net "M_F_CPU1_SA_DQS_DP<5>")
	)
	(segment
		(start 26.83129 -202.84059)
		(end 27.715464 -201.956416)
		(width 0.16002)
		(layer "In11.Cu")
		(net "M_F_CPU1_SA_DQS_DP<5>")
	)
	(segment
		(start 27.715464 -201.956416)
		(end 28.01747 -201.956416)
		(width 0.16002)
		(layer "In11.Cu")
		(net "M_F_CPU1_SA_DQS_DP<5>")
	)
	(segment
		(start 30.731714 -202.310492)
		(end 31.581852 -203.16063)
		(width 0.16002)
		(layer "In11.Cu")
		(net "M_F_CPU1_SA_DQS_DP<5>")
	)
	(segment
		(start 81.881218 -227.954586)
		(end 81.8896 -227.959412)
		(width 0.09525)
		(layer "In11.Cu")
		(net "M_F_CPU1_SA_DQS_DP<5>")
	)
	(segment
		(start 43.105578 -201.956416)
		(end 43.459654 -202.310492)
		(width 0.16002)
		(layer "In11.Cu")
		(net "M_F_CPU1_SA_DQS_DP<5>")
	)
	(segment
		(start 63.38443 -205.503526)
		(end 63.38443 -206.986886)
		(width 0.16002)
		(layer "In11.Cu")
		(net "M_F_CPU1_SA_DQS_DP<5>")
	)
	(segment
		(start 78.64221 -227.16109)
		(end 78.731364 -227.19157)
		(width 0.09525)
		(layer "In11.Cu")
		(net "M_F_CPU1_SA_DQS_DP<5>")
	)
	(segment
		(start 28.371546 -202.310492)
		(end 30.731714 -202.310492)
		(width 0.16002)
		(layer "In11.Cu")
		(net "M_F_CPU1_SA_DQS_DP<5>")
	)
	(segment
		(start 33.577784 -203.16063)
		(end 33.897824 -202.84059)
		(width 0.16002)
		(layer "In11.Cu")
		(net "M_F_CPU1_SA_DQS_DP<5>")
	)
	(segment
		(start 35.9156 -202.310492)
		(end 38.275768 -202.310492)
		(width 0.16002)
		(layer "In11.Cu")
		(net "M_F_CPU1_SA_DQS_DP<5>")
	)
	(segment
		(start 18.68424 -202.278234)
		(end 19.1643 -202.278234)
		(width 0.16002)
		(layer "In11.Cu")
		(net "M_F_CPU1_SA_DQS_DP<5>")
	)
	(segment
		(start 78.491588 -227.070412)
		(end 78.49235 -227.07092)
		(width 0.09525)
		(layer "In11.Cu")
		(net "M_F_CPU1_SA_DQS_DP<5>")
	)
	(segment
		(start 20.862544 -202.342242)
		(end 21.342604 -202.342242)
		(width 0.16002)
		(layer "In11.Cu")
		(net "M_F_CPU1_SA_DQS_DP<5>")
	)
	(segment
		(start 35.561524 -201.956416)
		(end 35.9156 -202.310492)
		(width 0.16002)
		(layer "In11.Cu")
		(net "M_F_CPU1_SA_DQS_DP<5>")
	)
	(segment
		(start 45.819822 -202.310492)
		(end 46.66996 -203.16063)
		(width 0.16002)
		(layer "In11.Cu")
		(net "M_F_CPU1_SA_DQS_DP<5>")
	)
	(segment
		(start 42.803572 -201.956416)
		(end 43.105578 -201.956416)
		(width 0.16002)
		(layer "In11.Cu")
		(net "M_F_CPU1_SA_DQS_DP<5>")
	)
	(segment
		(start 53.363876 -202.310492)
		(end 53.893974 -202.84059)
		(width 0.16002)
		(layer "In11.Cu")
		(net "M_F_CPU1_SA_DQS_DP<5>")
	)
	(segment
		(start 31.581852 -203.16063)
		(end 33.577784 -203.16063)
		(width 0.16002)
		(layer "In11.Cu")
		(net "M_F_CPU1_SA_DQS_DP<5>")
	)
	(segment
		(start 77.053948 -222.89135)
		(end 77.378814 -223.216216)
		(width 0.09525)
		(layer "In11.Cu")
		(net "M_F_CPU1_SA_DQS_DP<5>")
	)
	(segment
		(start 77.848714 -224.234502)
		(end 77.848714 -225.855276)
		(width 0.09525)
		(layer "In11.Cu")
		(net "M_F_CPU1_SA_DQS_DP<5>")
	)
	(segment
		(start 83.392518 -227.959412)
		(end 83.4009 -227.954586)
		(width 0.09525)
		(layer "In11.Cu")
		(net "M_F_CPU1_SA_DQS_DP<5>")
	)
	(segment
		(start 85.59165 -227.932234)
		(end 85.615018 -228.019102)
		(width 0.09525)
		(layer "In11.Cu")
		(net "M_F_CPU1_SA_DQS_DP<5>")
	)
	(segment
		(start 24.071072 -203.16063)
		(end 26.03373 -203.16063)
		(width 0.16002)
		(layer "In11.Cu")
		(net "M_F_CPU1_SA_DQS_DP<5>")
	)
	(segment
		(start 48.985932 -202.84059)
		(end 49.463452 -202.84059)
		(width 0.16002)
		(layer "In11.Cu")
		(net "M_F_CPU1_SA_DQS_DP<5>")
	)
	(segment
		(start 49.463452 -202.84059)
		(end 50.347626 -201.956416)
		(width 0.16002)
		(layer "In11.Cu")
		(net "M_F_CPU1_SA_DQS_DP<5>")
	)
	(segment
		(start 17.608042 -202.435206)
		(end 17.881854 -202.161394)
		(width 0.16002)
		(layer "In11.Cu")
		(net "M_F_CPU1_SA_DQS_DP<5>")
	)
	(segment
		(start 19.28114 -202.161394)
		(end 19.7612 -202.161394)
		(width 0.16002)
		(layer "In11.Cu")
		(net "M_F_CPU1_SA_DQS_DP<5>")
	)
	(segment
		(start 18.5674 -202.161394)
		(end 18.68424 -202.278234)
		(width 0.16002)
		(layer "In11.Cu")
		(net "M_F_CPU1_SA_DQS_DP<5>")
	)
	(segment
		(start 79.64297 -227.908104)
		(end 79.821024 -227.908104)
		(width 0.09525)
		(layer "In11.Cu")
		(net "M_F_CPU1_SA_DQS_DP<5>")
	)
	(segment
		(start 21.342604 -202.342242)
		(end 21.459444 -202.459082)
		(width 0.16002)
		(layer "In11.Cu")
		(net "M_F_CPU1_SA_DQS_DP<5>")
	)
	(segment
		(start 38.275768 -202.310492)
		(end 39.125906 -203.16063)
		(width 0.16002)
		(layer "In11.Cu")
		(net "M_F_CPU1_SA_DQS_DP<5>")
	)
	(segment
		(start 50.347626 -201.956416)
		(end 50.649632 -201.956416)
		(width 0.16002)
		(layer "In11.Cu")
		(net "M_F_CPU1_SA_DQS_DP<5>")
	)
	(segment
		(start 39.125906 -203.16063)
		(end 41.121838 -203.16063)
		(width 0.16002)
		(layer "In11.Cu")
		(net "M_F_CPU1_SA_DQS_DP<5>")
	)
	(segment
		(start 19.926808 -201.995786)
		(end 20.516088 -201.995786)
		(width 0.16002)
		(layer "In11.Cu")
		(net "M_F_CPU1_SA_DQS_DP<5>")
	)
	(segment
		(start 50.649632 -201.956416)
		(end 51.003708 -202.310492)
		(width 0.16002)
		(layer "In11.Cu")
		(net "M_F_CPU1_SA_DQS_DP<5>")
	)
	(segment
		(start 63.38443 -206.986886)
		(end 73.87463 -217.477086)
		(width 0.16002)
		(layer "In11.Cu")
		(net "M_F_CPU1_SA_DQS_DP<5>")
	)
	(segment
		(start 22.056344 -202.342242)
		(end 23.252684 -202.342242)
		(width 0.16002)
		(layer "In11.Cu")
		(net "M_F_CPU1_SA_DQS_DP<5>")
	)
	(segment
		(start 59.83732 -201.956416)
		(end 63.38443 -205.503526)
		(width 0.16002)
		(layer "In11.Cu")
		(net "M_F_CPU1_SA_DQS_DP<5>")
	)
	(segment
		(start 41.441878 -202.84059)
		(end 41.919398 -202.84059)
		(width 0.16002)
		(layer "In11.Cu")
		(net "M_F_CPU1_SA_DQS_DP<5>")
	)
	(segment
		(start 57.007252 -202.84059)
		(end 57.891426 -201.956416)
		(width 0.16002)
		(layer "In11.Cu")
		(net "M_F_CPU1_SA_DQS_DP<5>")
	)
	(segment
		(start 43.459654 -202.310492)
		(end 45.819822 -202.310492)
		(width 0.16002)
		(layer "In11.Cu")
		(net "M_F_CPU1_SA_DQS_DP<5>")
	)
	(segment
		(start 73.87463 -219.795852)
		(end 76.953364 -222.874586)
		(width 0.16002)
		(layer "In11.Cu")
		(net "M_F_CPU1_SA_DQS_DP<5>")
	)
	(segment
		(start 77.621638 -223.887284)
		(end 77.691234 -223.92767)
		(width 0.09525)
		(layer "In11.Cu")
		(net "M_F_CPU1_SA_DQS_DP<5>")
	)
	(segment
		(start 35.259518 -201.956416)
		(end 35.561524 -201.956416)
		(width 0.16002)
		(layer "In11.Cu")
		(net "M_F_CPU1_SA_DQS_DP<5>")
	)
	(segment
		(start 76.970128 -222.89135)
		(end 77.053948 -222.89135)
		(width 0.09525)
		(layer "In11.Cu")
		(net "M_F_CPU1_SA_DQS_DP<5>")
	)
	(segment
		(start 85.615018 -228.019102)
		(end 85.461094 -228.284532)
		(width 0.09525)
		(layer "In11.Cu")
		(net "M_F_CPU1_SA_DQS_DP<5>")
	)
	(segment
		(start 78.016354 -226.241356)
		(end 78.144624 -226.36099)
		(width 0.09525)
		(layer "In11.Cu")
		(net "M_F_CPU1_SA_DQS_DP<5>")
	)
	(arc
		(start 78.731364 -227.19157)
		(mid 78.738467 -227.19401)
		(end 78.745588 -227.196396)
		(width 0.09525)
		(layer "In11.Cu")
		(net "M_F_CPU1_SA_DQS_DP<5>")
	)
	(arc
		(start 79.821024 -227.908104)
		(mid 79.91877 -227.921299)
		(end 80.009746 -227.959412)
		(width 0.09525)
		(layer "In11.Cu")
		(net "M_F_CPU1_SA_DQS_DP<5>")
	)
	(arc
		(start 78.144624 -226.36099)
		(mid 78.265311 -226.523578)
		(end 78.320646 -226.718368)
		(width 0.09525)
		(layer "In11.Cu")
		(net "M_F_CPU1_SA_DQS_DP<5>")
	)
	(arc
		(start 78.745588 -227.196396)
		(mid 78.79523 -227.219573)
		(end 78.83652 -227.255578)
		(width 0.09525)
		(layer "In11.Cu")
		(net "M_F_CPU1_SA_DQS_DP<5>")
	)
	(arc
		(start 78.904338 -227.360226)
		(mid 78.920016 -227.399422)
		(end 78.936088 -227.438458)
		(width 0.09525)
		(layer "In11.Cu")
		(net "M_F_CPU1_SA_DQS_DP<5>")
	)
	(arc
		(start 83.769708 -227.959412)
		(mid 84.05114 -228.035167)
		(end 84.332572 -227.959412)
		(width 0.09525)
		(layer "In11.Cu")
		(net "M_F_CPU1_SA_DQS_DP<5>")
	)
	(arc
		(start 85.272372 -227.959412)
		(mid 85.42897 -227.910123)
		(end 85.59165 -227.932234)
		(width 0.09525)
		(layer "In11.Cu")
		(net "M_F_CPU1_SA_DQS_DP<5>")
	)
	(arc
		(start 81.8896 -227.959412)
		(mid 82.171032 -228.035167)
		(end 82.452464 -227.959412)
		(width 0.09525)
		(layer "In11.Cu")
		(net "M_F_CPU1_SA_DQS_DP<5>")
	)
	(arc
		(start 77.848714 -225.855276)
		(mid 77.892315 -226.065792)
		(end 78.016354 -226.241356)
		(width 0.09525)
		(layer "In11.Cu")
		(net "M_F_CPU1_SA_DQS_DP<5>")
	)
	(arc
		(start 78.936088 -227.438458)
		(mid 78.975943 -227.51222)
		(end 79.029306 -227.576888)
		(width 0.09525)
		(layer "In11.Cu")
		(net "M_F_CPU1_SA_DQS_DP<5>")
	)
	(arc
		(start 78.880208 -227.312474)
		(mid 78.893503 -227.335729)
		(end 78.904338 -227.360226)
		(width 0.09525)
		(layer "In11.Cu")
		(net "M_F_CPU1_SA_DQS_DP<5>")
	)
	(arc
		(start 82.829654 -227.959412)
		(mid 83.111086 -228.035167)
		(end 83.392518 -227.959412)
		(width 0.09525)
		(layer "In11.Cu")
		(net "M_F_CPU1_SA_DQS_DP<5>")
	)
	(arc
		(start 77.378814 -223.424496)
		(mid 77.443211 -223.685802)
		(end 77.621638 -223.887284)
		(width 0.09525)
		(layer "In11.Cu")
		(net "M_F_CPU1_SA_DQS_DP<5>")
	)
	(arc
		(start 82.460846 -227.954586)
		(mid 82.645878 -227.908672)
		(end 82.829654 -227.959412)
		(width 0.09525)
		(layer "In11.Cu")
		(net "M_F_CPU1_SA_DQS_DP<5>")
	)
	(arc
		(start 80.949546 -227.959412)
		(mid 81.230978 -228.035167)
		(end 81.51241 -227.959412)
		(width 0.09525)
		(layer "In11.Cu")
		(net "M_F_CPU1_SA_DQS_DP<5>")
	)
	(arc
		(start 83.4009 -227.954586)
		(mid 83.585932 -227.908672)
		(end 83.769708 -227.959412)
		(width 0.09525)
		(layer "In11.Cu")
		(net "M_F_CPU1_SA_DQS_DP<5>")
	)
	(arc
		(start 84.332572 -227.959412)
		(mid 84.52104 -227.908735)
		(end 84.709508 -227.959412)
		(width 0.09525)
		(layer "In11.Cu")
		(net "M_F_CPU1_SA_DQS_DP<5>")
	)
	(arc
		(start 78.320646 -226.718368)
		(mid 78.374525 -226.909727)
		(end 78.491588 -227.070412)
		(width 0.09525)
		(layer "In11.Cu")
		(net "M_F_CPU1_SA_DQS_DP<5>")
	)
	(arc
		(start 77.691234 -223.92767)
		(mid 77.807032 -224.062064)
		(end 77.848714 -224.234502)
		(width 0.09525)
		(layer "In11.Cu")
		(net "M_F_CPU1_SA_DQS_DP<5>")
	)
	(arc
		(start 84.709508 -227.959412)
		(mid 84.99094 -228.035167)
		(end 85.272372 -227.959412)
		(width 0.09525)
		(layer "In11.Cu")
		(net "M_F_CPU1_SA_DQS_DP<5>")
	)
	(arc
		(start 78.83652 -227.255578)
		(mid 78.85909 -227.283469)
		(end 78.880208 -227.312474)
		(width 0.09525)
		(layer "In11.Cu")
		(net "M_F_CPU1_SA_DQS_DP<5>")
	)
	(arc
		(start 78.49235 -227.07092)
		(mid 78.562359 -227.12418)
		(end 78.64221 -227.16109)
		(width 0.09525)
		(layer "In11.Cu")
		(net "M_F_CPU1_SA_DQS_DP<5>")
	)
	(arc
		(start 81.51241 -227.959412)
		(mid 81.696185 -227.90864)
		(end 81.881218 -227.954586)
		(width 0.09525)
		(layer "In11.Cu")
		(net "M_F_CPU1_SA_DQS_DP<5>")
	)
	(arc
		(start 79.16037 -227.708206)
		(mid 79.381789 -227.856153)
		(end 79.64297 -227.908104)
		(width 0.09525)
		(layer "In11.Cu")
		(net "M_F_CPU1_SA_DQS_DP<5>")
	)
	(arc
		(start 80.57261 -227.959412)
		(mid 80.761078 -227.908735)
		(end 80.949546 -227.959412)
		(width 0.09525)
		(layer "In11.Cu")
		(net "M_F_CPU1_SA_DQS_DP<5>")
	)
	(arc
		(start 80.009746 -227.959412)
		(mid 80.291178 -228.035167)
		(end 80.57261 -227.959412)
		(width 0.09525)
		(layer "In11.Cu")
		(net "M_F_CPU1_SA_DQS_DP<5>")
	)
	(segment
		(start 84.987892 -246.370348)
		(end 84.52104 -246.10441)
		(width 0.12954)
		(layer "F.Cu")
		(net "M_F_CPU1_SA_DQS_DP<4>")
	)
	(segment
		(start 77.988668 -246.476774)
		(end 77.99197 -246.476774)
		(width 0.09525)
		(layer "In11.Cu")
		(net "M_F_CPU1_SA_DQS_DP<4>")
	)
	(segment
		(start 59.223656 -238.892334)
		(end 58.862468 -239.253522)
		(width 0.16002)
		(layer "In11.Cu")
		(net "M_F_CPU1_SA_DQS_DP<4>")
	)
	(segment
		(start 64.893444 -244.085618)
		(end 64.893444 -244.725698)
		(width 0.16002)
		(layer "In11.Cu")
		(net "M_F_CPU1_SA_DQS_DP<4>")
	)
	(segment
		(start 51.020726 -237.410244)
		(end 52.877466 -237.410244)
		(width 0.16002)
		(layer "In11.Cu")
		(net "M_F_CPU1_SA_DQS_DP<4>")
	)
	(segment
		(start 61.684154 -240.876328)
		(end 62.140592 -241.332766)
		(width 0.16002)
		(layer "In11.Cu")
		(net "M_F_CPU1_SA_DQS_DP<4>")
	)
	(segment
		(start 50.20691 -237.779306)
		(end 50.651664 -237.779306)
		(width 0.16002)
		(layer "In11.Cu")
		(net "M_F_CPU1_SA_DQS_DP<4>")
	)
	(segment
		(start 21.70811 -238.135414)
		(end 21.981922 -238.409226)
		(width 0.16002)
		(layer "In11.Cu")
		(net "M_F_CPU1_SA_DQS_DP<4>")
	)
	(segment
		(start 79.63281 -246.42953)
		(end 79.644748 -246.436388)
		(width 0.09525)
		(layer "In11.Cu")
		(net "M_F_CPU1_SA_DQS_DP<4>")
	)
	(segment
		(start 28.019502 -237.779306)
		(end 28.388564 -237.410244)
		(width 0.16002)
		(layer "In11.Cu")
		(net "M_F_CPU1_SA_DQS_DP<4>")
	)
	(segment
		(start 60.764166 -239.95634)
		(end 60.764166 -240.59642)
		(width 0.16002)
		(layer "In11.Cu")
		(net "M_F_CPU1_SA_DQS_DP<4>")
	)
	(segment
		(start 35.563556 -237.779306)
		(end 35.932618 -237.410244)
		(width 0.16002)
		(layer "In11.Cu")
		(net "M_F_CPU1_SA_DQS_DP<4>")
	)
	(segment
		(start 62.140592 -241.332766)
		(end 62.140592 -241.972846)
		(width 0.16002)
		(layer "In11.Cu")
		(net "M_F_CPU1_SA_DQS_DP<4>")
	)
	(segment
		(start 79.05877 -246.436388)
		(end 79.070708 -246.42953)
		(width 0.09525)
		(layer "In11.Cu")
		(net "M_F_CPU1_SA_DQS_DP<4>")
	)
	(segment
		(start 78.1304 -246.42953)
		(end 78.1558 -246.414798)
		(width 0.09525)
		(layer "In11.Cu")
		(net "M_F_CPU1_SA_DQS_DP<4>")
	)
	(segment
		(start 55.206138 -237.888526)
		(end 55.807102 -237.888526)
		(width 0.16002)
		(layer "In11.Cu")
		(net "M_F_CPU1_SA_DQS_DP<4>")
	)
	(segment
		(start 75.312778 -246.006366)
		(end 75.800458 -246.494046)
		(width 0.16002)
		(layer "In11.Cu")
		(net "M_F_CPU1_SA_DQS_DP<4>")
	)
	(segment
		(start 76.476098 -246.552974)
		(end 76.66101 -246.737886)
		(width 0.09525)
		(layer "In11.Cu")
		(net "M_F_CPU1_SA_DQS_DP<4>")
	)
	(segment
		(start 75.800458 -246.494046)
		(end 75.955906 -246.494046)
		(width 0.16002)
		(layer "In11.Cu")
		(net "M_F_CPU1_SA_DQS_DP<4>")
	)
	(segment
		(start 54.86908 -238.225584)
		(end 55.206138 -237.888526)
		(width 0.16002)
		(layer "In11.Cu")
		(net "M_F_CPU1_SA_DQS_DP<4>")
	)
	(segment
		(start 33.894014 -238.604806)
		(end 34.293302 -238.604806)
		(width 0.16002)
		(layer "In11.Cu")
		(net "M_F_CPU1_SA_DQS_DP<4>")
	)
	(segment
		(start 43.476672 -237.410244)
		(end 45.333412 -237.410244)
		(width 0.16002)
		(layer "In11.Cu")
		(net "M_F_CPU1_SA_DQS_DP<4>")
	)
	(segment
		(start 35.932618 -237.410244)
		(end 37.789358 -237.410244)
		(width 0.16002)
		(layer "In11.Cu")
		(net "M_F_CPU1_SA_DQS_DP<4>")
	)
	(segment
		(start 76.038456 -246.552974)
		(end 76.476098 -246.552974)
		(width 0.09525)
		(layer "In11.Cu")
		(net "M_F_CPU1_SA_DQS_DP<4>")
	)
	(segment
		(start 54.428898 -238.604806)
		(end 54.70906 -238.604806)
		(width 0.16002)
		(layer "In11.Cu")
		(net "M_F_CPU1_SA_DQS_DP<4>")
	)
	(segment
		(start 65.173352 -245.005606)
		(end 65.813432 -245.005606)
		(width 0.16002)
		(layer "In11.Cu")
		(net "M_F_CPU1_SA_DQS_DP<4>")
	)
	(segment
		(start 58.862468 -239.253522)
		(end 58.862468 -239.479582)
		(width 0.16002)
		(layer "In11.Cu")
		(net "M_F_CPU1_SA_DQS_DP<4>")
	)
	(segment
		(start 42.662856 -237.779306)
		(end 43.10761 -237.779306)
		(width 0.16002)
		(layer "In11.Cu")
		(net "M_F_CPU1_SA_DQS_DP<4>")
	)
	(segment
		(start 59.698382 -239.36706)
		(end 60.174886 -239.36706)
		(width 0.16002)
		(layer "In11.Cu")
		(net "M_F_CPU1_SA_DQS_DP<4>")
	)
	(segment
		(start 28.388564 -237.410244)
		(end 30.245304 -237.410244)
		(width 0.16002)
		(layer "In11.Cu")
		(net "M_F_CPU1_SA_DQS_DP<4>")
	)
	(segment
		(start 63.517018 -242.709192)
		(end 63.517018 -243.349272)
		(width 0.16002)
		(layer "In11.Cu")
		(net "M_F_CPU1_SA_DQS_DP<4>")
	)
	(segment
		(start 27.574748 -237.779306)
		(end 28.019502 -237.779306)
		(width 0.16002)
		(layer "In11.Cu")
		(net "M_F_CPU1_SA_DQS_DP<4>")
	)
	(segment
		(start 33.549336 -238.260128)
		(end 33.894014 -238.604806)
		(width 0.16002)
		(layer "In11.Cu")
		(net "M_F_CPU1_SA_DQS_DP<4>")
	)
	(segment
		(start 58.587132 -237.779306)
		(end 59.223656 -238.41583)
		(width 0.16002)
		(layer "In11.Cu")
		(net "M_F_CPU1_SA_DQS_DP<4>")
	)
	(segment
		(start 56.14416 -238.909606)
		(end 56.30418 -239.069626)
		(width 0.16002)
		(layer "In11.Cu")
		(net "M_F_CPU1_SA_DQS_DP<4>")
	)
	(segment
		(start 49.38141 -238.604806)
		(end 50.20691 -237.779306)
		(width 0.16002)
		(layer "In11.Cu")
		(net "M_F_CPU1_SA_DQS_DP<4>")
	)
	(segment
		(start 26.34996 -238.604806)
		(end 26.749248 -238.604806)
		(width 0.16002)
		(layer "In11.Cu")
		(net "M_F_CPU1_SA_DQS_DP<4>")
	)
	(segment
		(start 60.174886 -239.36706)
		(end 60.764166 -239.95634)
		(width 0.16002)
		(layer "In11.Cu")
		(net "M_F_CPU1_SA_DQS_DP<4>")
	)
	(segment
		(start 45.333412 -237.410244)
		(end 46.183296 -238.260128)
		(width 0.16002)
		(layer "In11.Cu")
		(net "M_F_CPU1_SA_DQS_DP<4>")
	)
	(segment
		(start 37.789358 -237.410244)
		(end 38.639242 -238.260128)
		(width 0.16002)
		(layer "In11.Cu")
		(net "M_F_CPU1_SA_DQS_DP<4>")
	)
	(segment
		(start 52.877466 -237.410244)
		(end 53.520086 -238.052864)
		(width 0.16002)
		(layer "In11.Cu")
		(net "M_F_CPU1_SA_DQS_DP<4>")
	)
	(segment
		(start 59.111134 -239.728248)
		(end 59.337194 -239.728248)
		(width 0.16002)
		(layer "In11.Cu")
		(net "M_F_CPU1_SA_DQS_DP<4>")
	)
	(segment
		(start 30.245304 -237.410244)
		(end 31.095188 -238.260128)
		(width 0.16002)
		(layer "In11.Cu")
		(net "M_F_CPU1_SA_DQS_DP<4>")
	)
	(segment
		(start 50.651664 -237.779306)
		(end 51.020726 -237.410244)
		(width 0.16002)
		(layer "In11.Cu")
		(net "M_F_CPU1_SA_DQS_DP<4>")
	)
	(segment
		(start 84.367116 -246.36984)
		(end 84.52104 -246.10441)
		(width 0.09525)
		(layer "In11.Cu")
		(net "M_F_CPU1_SA_DQS_DP<4>")
	)
	(segment
		(start 58.06567 -237.779306)
		(end 58.587132 -237.779306)
		(width 0.16002)
		(layer "In11.Cu")
		(net "M_F_CPU1_SA_DQS_DP<4>")
	)
	(segment
		(start 66.814192 -246.006366)
		(end 75.312778 -246.006366)
		(width 0.16002)
		(layer "In11.Cu")
		(net "M_F_CPU1_SA_DQS_DP<4>")
	)
	(segment
		(start 56.30418 -239.069626)
		(end 56.77535 -239.069626)
		(width 0.16002)
		(layer "In11.Cu")
		(net "M_F_CPU1_SA_DQS_DP<4>")
	)
	(segment
		(start 62.140592 -241.972846)
		(end 62.4205 -242.252754)
		(width 0.16002)
		(layer "In11.Cu")
		(net "M_F_CPU1_SA_DQS_DP<4>")
	)
	(segment
		(start 81.881218 -246.434356)
		(end 81.8896 -246.42953)
		(width 0.09525)
		(layer "In11.Cu")
		(net "M_F_CPU1_SA_DQS_DP<4>")
	)
	(segment
		(start 41.837356 -238.604806)
		(end 42.662856 -237.779306)
		(width 0.16002)
		(layer "In11.Cu")
		(net "M_F_CPU1_SA_DQS_DP<4>")
	)
	(segment
		(start 46.183296 -238.260128)
		(end 48.637444 -238.260128)
		(width 0.16002)
		(layer "In11.Cu")
		(net "M_F_CPU1_SA_DQS_DP<4>")
	)
	(segment
		(start 84.266278 -246.39651)
		(end 84.367116 -246.36984)
		(width 0.09525)
		(layer "In11.Cu")
		(net "M_F_CPU1_SA_DQS_DP<4>")
	)
	(segment
		(start 64.437006 -243.62918)
		(end 64.893444 -244.085618)
		(width 0.16002)
		(layer "In11.Cu")
		(net "M_F_CPU1_SA_DQS_DP<4>")
	)
	(segment
		(start 48.982122 -238.604806)
		(end 49.38141 -238.604806)
		(width 0.16002)
		(layer "In11.Cu")
		(net "M_F_CPU1_SA_DQS_DP<4>")
	)
	(segment
		(start 82.452464 -246.42953)
		(end 82.460846 -246.434356)
		(width 0.09525)
		(layer "In11.Cu")
		(net "M_F_CPU1_SA_DQS_DP<4>")
	)
	(segment
		(start 77.01153 -246.737886)
		(end 77.280516 -246.4689)
		(width 0.09525)
		(layer "In11.Cu")
		(net "M_F_CPU1_SA_DQS_DP<4>")
	)
	(segment
		(start 48.637444 -238.260128)
		(end 48.982122 -238.604806)
		(width 0.16002)
		(layer "In11.Cu")
		(net "M_F_CPU1_SA_DQS_DP<4>")
	)
	(segment
		(start 63.517018 -243.349272)
		(end 63.796926 -243.62918)
		(width 0.16002)
		(layer "In11.Cu")
		(net "M_F_CPU1_SA_DQS_DP<4>")
	)
	(segment
		(start 83.392518 -246.42953)
		(end 83.4009 -246.434356)
		(width 0.09525)
		(layer "In11.Cu")
		(net "M_F_CPU1_SA_DQS_DP<4>")
	)
	(segment
		(start 56.77535 -239.069626)
		(end 58.06567 -237.779306)
		(width 0.16002)
		(layer "In11.Cu")
		(net "M_F_CPU1_SA_DQS_DP<4>")
	)
	(segment
		(start 53.876956 -238.052864)
		(end 54.428898 -238.604806)
		(width 0.16002)
		(layer "In11.Cu")
		(net "M_F_CPU1_SA_DQS_DP<4>")
	)
	(segment
		(start 21.981922 -238.409226)
		(end 24.006302 -238.409226)
		(width 0.16002)
		(layer "In11.Cu")
		(net "M_F_CPU1_SA_DQS_DP<4>")
	)
	(segment
		(start 63.06058 -242.252754)
		(end 63.517018 -242.709192)
		(width 0.16002)
		(layer "In11.Cu")
		(net "M_F_CPU1_SA_DQS_DP<4>")
	)
	(segment
		(start 75.955906 -246.494046)
		(end 75.979528 -246.494046)
		(width 0.09525)
		(layer "In11.Cu")
		(net "M_F_CPU1_SA_DQS_DP<4>")
	)
	(segment
		(start 31.095188 -238.260128)
		(end 33.549336 -238.260128)
		(width 0.16002)
		(layer "In11.Cu")
		(net "M_F_CPU1_SA_DQS_DP<4>")
	)
	(segment
		(start 79.614776 -246.419116)
		(end 79.63281 -246.42953)
		(width 0.09525)
		(layer "In11.Cu")
		(net "M_F_CPU1_SA_DQS_DP<4>")
	)
	(segment
		(start 56.14416 -238.225584)
		(end 56.14416 -238.909606)
		(width 0.16002)
		(layer "In11.Cu")
		(net "M_F_CPU1_SA_DQS_DP<4>")
	)
	(segment
		(start 59.223656 -238.41583)
		(end 59.223656 -238.892334)
		(width 0.16002)
		(layer "In11.Cu")
		(net "M_F_CPU1_SA_DQS_DP<4>")
	)
	(segment
		(start 54.86908 -238.444786)
		(end 54.86908 -238.225584)
		(width 0.16002)
		(layer "In11.Cu")
		(net "M_F_CPU1_SA_DQS_DP<4>")
	)
	(segment
		(start 59.337194 -239.728248)
		(end 59.698382 -239.36706)
		(width 0.16002)
		(layer "In11.Cu")
		(net "M_F_CPU1_SA_DQS_DP<4>")
	)
	(segment
		(start 61.044074 -240.876328)
		(end 61.684154 -240.876328)
		(width 0.16002)
		(layer "In11.Cu")
		(net "M_F_CPU1_SA_DQS_DP<4>")
	)
	(segment
		(start 34.293302 -238.604806)
		(end 35.118802 -237.779306)
		(width 0.16002)
		(layer "In11.Cu")
		(net "M_F_CPU1_SA_DQS_DP<4>")
	)
	(segment
		(start 76.66101 -246.737886)
		(end 77.01153 -246.737886)
		(width 0.09525)
		(layer "In11.Cu")
		(net "M_F_CPU1_SA_DQS_DP<4>")
	)
	(segment
		(start 77.761846 -246.4689)
		(end 77.988668 -246.476774)
		(width 0.09525)
		(layer "In11.Cu")
		(net "M_F_CPU1_SA_DQS_DP<4>")
	)
	(segment
		(start 26.005282 -238.260128)
		(end 26.34996 -238.604806)
		(width 0.16002)
		(layer "In11.Cu")
		(net "M_F_CPU1_SA_DQS_DP<4>")
	)
	(segment
		(start 78.118462 -246.436388)
		(end 78.1304 -246.42953)
		(width 0.09525)
		(layer "In11.Cu")
		(net "M_F_CPU1_SA_DQS_DP<4>")
	)
	(segment
		(start 26.749248 -238.604806)
		(end 27.574748 -237.779306)
		(width 0.16002)
		(layer "In11.Cu")
		(net "M_F_CPU1_SA_DQS_DP<4>")
	)
	(segment
		(start 53.520086 -238.052864)
		(end 53.876956 -238.052864)
		(width 0.16002)
		(layer "In11.Cu")
		(net "M_F_CPU1_SA_DQS_DP<4>")
	)
	(segment
		(start 54.70906 -238.604806)
		(end 54.86908 -238.444786)
		(width 0.16002)
		(layer "In11.Cu")
		(net "M_F_CPU1_SA_DQS_DP<4>")
	)
	(segment
		(start 24.1554 -238.260128)
		(end 26.005282 -238.260128)
		(width 0.16002)
		(layer "In11.Cu")
		(net "M_F_CPU1_SA_DQS_DP<4>")
	)
	(segment
		(start 24.006302 -238.409226)
		(end 24.1554 -238.260128)
		(width 0.16002)
		(layer "In11.Cu")
		(net "M_F_CPU1_SA_DQS_DP<4>")
	)
	(segment
		(start 63.796926 -243.62918)
		(end 64.437006 -243.62918)
		(width 0.16002)
		(layer "In11.Cu")
		(net "M_F_CPU1_SA_DQS_DP<4>")
	)
	(segment
		(start 43.10761 -237.779306)
		(end 43.476672 -237.410244)
		(width 0.16002)
		(layer "In11.Cu")
		(net "M_F_CPU1_SA_DQS_DP<4>")
	)
	(segment
		(start 65.813432 -245.005606)
		(end 66.814192 -246.006366)
		(width 0.16002)
		(layer "In11.Cu")
		(net "M_F_CPU1_SA_DQS_DP<4>")
	)
	(segment
		(start 38.639242 -238.260128)
		(end 41.09339 -238.260128)
		(width 0.16002)
		(layer "In11.Cu")
		(net "M_F_CPU1_SA_DQS_DP<4>")
	)
	(segment
		(start 41.09339 -238.260128)
		(end 41.438068 -238.604806)
		(width 0.16002)
		(layer "In11.Cu")
		(net "M_F_CPU1_SA_DQS_DP<4>")
	)
	(segment
		(start 55.807102 -237.888526)
		(end 56.14416 -238.225584)
		(width 0.16002)
		(layer "In11.Cu")
		(net "M_F_CPU1_SA_DQS_DP<4>")
	)
	(segment
		(start 64.893444 -244.725698)
		(end 65.173352 -245.005606)
		(width 0.16002)
		(layer "In11.Cu")
		(net "M_F_CPU1_SA_DQS_DP<4>")
	)
	(segment
		(start 58.862468 -239.479582)
		(end 59.111134 -239.728248)
		(width 0.16002)
		(layer "In11.Cu")
		(net "M_F_CPU1_SA_DQS_DP<4>")
	)
	(segment
		(start 77.280516 -246.4689)
		(end 77.761846 -246.4689)
		(width 0.09525)
		(layer "In11.Cu")
		(net "M_F_CPU1_SA_DQS_DP<4>")
	)
	(segment
		(start 41.438068 -238.604806)
		(end 41.837356 -238.604806)
		(width 0.16002)
		(layer "In11.Cu")
		(net "M_F_CPU1_SA_DQS_DP<4>")
	)
	(segment
		(start 35.118802 -237.779306)
		(end 35.563556 -237.779306)
		(width 0.16002)
		(layer "In11.Cu")
		(net "M_F_CPU1_SA_DQS_DP<4>")
	)
	(segment
		(start 75.979528 -246.494046)
		(end 76.038456 -246.552974)
		(width 0.09525)
		(layer "In11.Cu")
		(net "M_F_CPU1_SA_DQS_DP<4>")
	)
	(segment
		(start 62.4205 -242.252754)
		(end 63.06058 -242.252754)
		(width 0.16002)
		(layer "In11.Cu")
		(net "M_F_CPU1_SA_DQS_DP<4>")
	)
	(segment
		(start 60.764166 -240.59642)
		(end 61.044074 -240.876328)
		(width 0.16002)
		(layer "In11.Cu")
		(net "M_F_CPU1_SA_DQS_DP<4>")
	)
	(arc
		(start 78.1558 -246.414798)
		(mid 78.426416 -246.353573)
		(end 78.693264 -246.42953)
		(width 0.09525)
		(layer "In11.Cu")
		(net "M_F_CPU1_SA_DQS_DP<4>")
	)
	(arc
		(start 78.693264 -246.42953)
		(mid 78.875134 -246.480395)
		(end 79.05877 -246.436388)
		(width 0.09525)
		(layer "In11.Cu")
		(net "M_F_CPU1_SA_DQS_DP<4>")
	)
	(arc
		(start 80.009746 -246.42953)
		(mid 80.291178 -246.353775)
		(end 80.57261 -246.42953)
		(width 0.09525)
		(layer "In11.Cu")
		(net "M_F_CPU1_SA_DQS_DP<4>")
	)
	(arc
		(start 77.99197 -246.476774)
		(mid 78.057014 -246.462211)
		(end 78.118462 -246.436388)
		(width 0.09525)
		(layer "In11.Cu")
		(net "M_F_CPU1_SA_DQS_DP<4>")
	)
	(arc
		(start 83.4009 -246.434356)
		(mid 83.585932 -246.48027)
		(end 83.769708 -246.42953)
		(width 0.09525)
		(layer "In11.Cu")
		(net "M_F_CPU1_SA_DQS_DP<4>")
	)
	(arc
		(start 84.245958 -246.388636)
		(mid 84.256157 -246.392473)
		(end 84.266278 -246.39651)
		(width 0.09525)
		(layer "In11.Cu")
		(net "M_F_CPU1_SA_DQS_DP<4>")
	)
	(arc
		(start 82.460846 -246.434356)
		(mid 82.645878 -246.48027)
		(end 82.829654 -246.42953)
		(width 0.09525)
		(layer "In11.Cu")
		(net "M_F_CPU1_SA_DQS_DP<4>")
	)
	(arc
		(start 82.829654 -246.42953)
		(mid 83.111086 -246.353775)
		(end 83.392518 -246.42953)
		(width 0.09525)
		(layer "In11.Cu")
		(net "M_F_CPU1_SA_DQS_DP<4>")
	)
	(arc
		(start 81.51241 -246.42953)
		(mid 81.696185 -246.480302)
		(end 81.881218 -246.434356)
		(width 0.09525)
		(layer "In11.Cu")
		(net "M_F_CPU1_SA_DQS_DP<4>")
	)
	(arc
		(start 79.070708 -246.42953)
		(mid 79.341396 -246.353878)
		(end 79.614776 -246.419116)
		(width 0.09525)
		(layer "In11.Cu")
		(net "M_F_CPU1_SA_DQS_DP<4>")
	)
	(arc
		(start 81.8896 -246.42953)
		(mid 82.171032 -246.353775)
		(end 82.452464 -246.42953)
		(width 0.09525)
		(layer "In11.Cu")
		(net "M_F_CPU1_SA_DQS_DP<4>")
	)
	(arc
		(start 83.769708 -246.42953)
		(mid 84.003252 -246.355824)
		(end 84.245958 -246.388636)
		(width 0.09525)
		(layer "In11.Cu")
		(net "M_F_CPU1_SA_DQS_DP<4>")
	)
	(arc
		(start 80.57261 -246.42953)
		(mid 80.761078 -246.480207)
		(end 80.949546 -246.42953)
		(width 0.09525)
		(layer "In11.Cu")
		(net "M_F_CPU1_SA_DQS_DP<4>")
	)
	(arc
		(start 80.949546 -246.42953)
		(mid 81.230978 -246.353775)
		(end 81.51241 -246.42953)
		(width 0.09525)
		(layer "In11.Cu")
		(net "M_F_CPU1_SA_DQS_DP<4>")
	)
	(arc
		(start 79.644748 -246.436388)
		(mid 79.828129 -246.480219)
		(end 80.009746 -246.42953)
		(width 0.09525)
		(layer "In11.Cu")
		(net "M_F_CPU1_SA_DQS_DP<4>")
	)
	(segment
		(start 84.987892 -241.510312)
		(end 84.52104 -241.244374)
		(width 0.12954)
		(layer "F.Cu")
		(net "M_F_CPU1_SA_DQS_DP<3>")
	)
	(segment
		(start 33.549336 -228.910134)
		(end 33.894014 -229.254812)
		(width 0.16002)
		(layer "In11.Cu")
		(net "M_F_CPU1_SA_DQS_DP<3>")
	)
	(segment
		(start 65.617598 -235.392722)
		(end 65.617598 -235.869226)
		(width 0.16002)
		(layer "In11.Cu")
		(net "M_F_CPU1_SA_DQS_DP<3>")
	)
	(segment
		(start 28.388564 -228.06025)
		(end 30.245304 -228.06025)
		(width 0.16002)
		(layer "In11.Cu")
		(net "M_F_CPU1_SA_DQS_DP<3>")
	)
	(segment
		(start 41.837356 -229.254812)
		(end 42.662856 -228.429312)
		(width 0.16002)
		(layer "In11.Cu")
		(net "M_F_CPU1_SA_DQS_DP<3>")
	)
	(segment
		(start 24.006302 -229.059232)
		(end 24.1554 -228.910134)
		(width 0.16002)
		(layer "In11.Cu")
		(net "M_F_CPU1_SA_DQS_DP<3>")
	)
	(segment
		(start 50.20691 -228.429312)
		(end 50.651664 -228.429312)
		(width 0.16002)
		(layer "In11.Cu")
		(net "M_F_CPU1_SA_DQS_DP<3>")
	)
	(segment
		(start 67.96659 -239.240568)
		(end 69.116956 -240.390934)
		(width 0.16002)
		(layer "In11.Cu")
		(net "M_F_CPU1_SA_DQS_DP<3>")
	)
	(segment
		(start 69.116956 -240.390934)
		(end 75.955906 -240.390934)
		(width 0.16002)
		(layer "In11.Cu")
		(net "M_F_CPU1_SA_DQS_DP<3>")
	)
	(segment
		(start 43.476672 -228.06025)
		(end 45.333412 -228.06025)
		(width 0.16002)
		(layer "In11.Cu")
		(net "M_F_CPU1_SA_DQS_DP<3>")
	)
	(segment
		(start 37.789358 -228.06025)
		(end 38.639242 -228.910134)
		(width 0.16002)
		(layer "In11.Cu")
		(net "M_F_CPU1_SA_DQS_DP<3>")
	)
	(segment
		(start 79.63281 -241.569494)
		(end 79.644748 -241.576352)
		(width 0.09525)
		(layer "In11.Cu")
		(net "M_F_CPU1_SA_DQS_DP<3>")
	)
	(segment
		(start 66.839592 -238.11357)
		(end 67.065652 -238.11357)
		(width 0.16002)
		(layer "In11.Cu")
		(net "M_F_CPU1_SA_DQS_DP<3>")
	)
	(segment
		(start 57.75071 -228.429312)
		(end 58.85307 -228.429312)
		(width 0.16002)
		(layer "In11.Cu")
		(net "M_F_CPU1_SA_DQS_DP<3>")
	)
	(segment
		(start 35.118802 -228.429312)
		(end 35.563556 -228.429312)
		(width 0.16002)
		(layer "In11.Cu")
		(net "M_F_CPU1_SA_DQS_DP<3>")
	)
	(segment
		(start 28.019502 -228.429312)
		(end 28.388564 -228.06025)
		(width 0.16002)
		(layer "In11.Cu")
		(net "M_F_CPU1_SA_DQS_DP<3>")
	)
	(segment
		(start 51.020726 -228.06025)
		(end 52.877466 -228.06025)
		(width 0.16002)
		(layer "In11.Cu")
		(net "M_F_CPU1_SA_DQS_DP<3>")
	)
	(segment
		(start 77.018642 -240.920778)
		(end 77.591666 -241.493802)
		(width 0.09525)
		(layer "In11.Cu")
		(net "M_F_CPU1_SA_DQS_DP<3>")
	)
	(segment
		(start 43.10761 -228.429312)
		(end 43.476672 -228.06025)
		(width 0.16002)
		(layer "In11.Cu")
		(net "M_F_CPU1_SA_DQS_DP<3>")
	)
	(segment
		(start 41.438068 -229.254812)
		(end 41.837356 -229.254812)
		(width 0.16002)
		(layer "In11.Cu")
		(net "M_F_CPU1_SA_DQS_DP<3>")
	)
	(segment
		(start 67.940428 -237.715552)
		(end 68.364862 -238.139986)
		(width 0.16002)
		(layer "In11.Cu")
		(net "M_F_CPU1_SA_DQS_DP<3>")
	)
	(segment
		(start 65.69202 -236.739938)
		(end 66.090292 -236.34192)
		(width 0.16002)
		(layer "In11.Cu")
		(net "M_F_CPU1_SA_DQS_DP<3>")
	)
	(segment
		(start 21.981922 -229.059232)
		(end 24.006302 -229.059232)
		(width 0.16002)
		(layer "In11.Cu")
		(net "M_F_CPU1_SA_DQS_DP<3>")
	)
	(segment
		(start 65.219326 -236.493304)
		(end 65.46596 -236.739938)
		(width 0.16002)
		(layer "In11.Cu")
		(net "M_F_CPU1_SA_DQS_DP<3>")
	)
	(segment
		(start 67.463924 -237.715552)
		(end 67.940428 -237.715552)
		(width 0.16002)
		(layer "In11.Cu")
		(net "M_F_CPU1_SA_DQS_DP<3>")
	)
	(segment
		(start 65.617598 -235.869226)
		(end 65.219326 -236.267244)
		(width 0.16002)
		(layer "In11.Cu")
		(net "M_F_CPU1_SA_DQS_DP<3>")
	)
	(segment
		(start 79.05877 -241.576352)
		(end 79.070708 -241.569494)
		(width 0.09525)
		(layer "In11.Cu")
		(net "M_F_CPU1_SA_DQS_DP<3>")
	)
	(segment
		(start 68.364862 -238.139986)
		(end 68.364862 -238.61649)
		(width 0.16002)
		(layer "In11.Cu")
		(net "M_F_CPU1_SA_DQS_DP<3>")
	)
	(segment
		(start 64.092328 -235.366306)
		(end 64.318388 -235.366306)
		(width 0.16002)
		(layer "In11.Cu")
		(net "M_F_CPU1_SA_DQS_DP<3>")
	)
	(segment
		(start 76.252832 -240.449862)
		(end 76.723748 -240.920778)
		(width 0.09525)
		(layer "In11.Cu")
		(net "M_F_CPU1_SA_DQS_DP<3>")
	)
	(segment
		(start 65.46596 -236.739938)
		(end 65.69202 -236.739938)
		(width 0.16002)
		(layer "In11.Cu")
		(net "M_F_CPU1_SA_DQS_DP<3>")
	)
	(segment
		(start 76.723748 -240.920778)
		(end 77.018642 -240.920778)
		(width 0.09525)
		(layer "In11.Cu")
		(net "M_F_CPU1_SA_DQS_DP<3>")
	)
	(segment
		(start 63.598806 -233.175048)
		(end 63.598806 -234.872784)
		(width 0.16002)
		(layer "In11.Cu")
		(net "M_F_CPU1_SA_DQS_DP<3>")
	)
	(segment
		(start 45.333412 -228.06025)
		(end 46.183296 -228.910134)
		(width 0.16002)
		(layer "In11.Cu")
		(net "M_F_CPU1_SA_DQS_DP<3>")
	)
	(segment
		(start 31.095188 -228.910134)
		(end 33.549336 -228.910134)
		(width 0.16002)
		(layer "In11.Cu")
		(net "M_F_CPU1_SA_DQS_DP<3>")
	)
	(segment
		(start 35.932618 -228.06025)
		(end 37.789358 -228.06025)
		(width 0.16002)
		(layer "In11.Cu")
		(net "M_F_CPU1_SA_DQS_DP<3>")
	)
	(segment
		(start 33.894014 -229.254812)
		(end 34.293302 -229.254812)
		(width 0.16002)
		(layer "In11.Cu")
		(net "M_F_CPU1_SA_DQS_DP<3>")
	)
	(segment
		(start 48.637444 -228.910134)
		(end 48.982122 -229.254812)
		(width 0.16002)
		(layer "In11.Cu")
		(net "M_F_CPU1_SA_DQS_DP<3>")
	)
	(segment
		(start 66.566796 -236.34192)
		(end 66.99123 -236.766354)
		(width 0.16002)
		(layer "In11.Cu")
		(net "M_F_CPU1_SA_DQS_DP<3>")
	)
	(segment
		(start 78.316582 -241.493294)
		(end 78.411324 -241.493294)
		(width 0.09525)
		(layer "In11.Cu")
		(net "M_F_CPU1_SA_DQS_DP<3>")
	)
	(segment
		(start 67.065652 -238.11357)
		(end 67.463924 -237.715552)
		(width 0.16002)
		(layer "In11.Cu")
		(net "M_F_CPU1_SA_DQS_DP<3>")
	)
	(segment
		(start 26.749248 -229.254812)
		(end 27.574748 -228.429312)
		(width 0.16002)
		(layer "In11.Cu")
		(net "M_F_CPU1_SA_DQS_DP<3>")
	)
	(segment
		(start 67.96659 -239.014508)
		(end 67.96659 -239.240568)
		(width 0.16002)
		(layer "In11.Cu")
		(net "M_F_CPU1_SA_DQS_DP<3>")
	)
	(segment
		(start 75.955906 -240.390934)
		(end 75.979528 -240.390934)
		(width 0.09525)
		(layer "In11.Cu")
		(net "M_F_CPU1_SA_DQS_DP<3>")
	)
	(segment
		(start 26.34996 -229.254812)
		(end 26.749248 -229.254812)
		(width 0.16002)
		(layer "In11.Cu")
		(net "M_F_CPU1_SA_DQS_DP<3>")
	)
	(segment
		(start 42.662856 -228.429312)
		(end 43.10761 -228.429312)
		(width 0.16002)
		(layer "In11.Cu")
		(net "M_F_CPU1_SA_DQS_DP<3>")
	)
	(segment
		(start 64.71666 -234.968288)
		(end 65.193164 -234.968288)
		(width 0.16002)
		(layer "In11.Cu")
		(net "M_F_CPU1_SA_DQS_DP<3>")
	)
	(segment
		(start 41.09339 -228.910134)
		(end 41.438068 -229.254812)
		(width 0.16002)
		(layer "In11.Cu")
		(net "M_F_CPU1_SA_DQS_DP<3>")
	)
	(segment
		(start 48.982122 -229.254812)
		(end 49.38141 -229.254812)
		(width 0.16002)
		(layer "In11.Cu")
		(net "M_F_CPU1_SA_DQS_DP<3>")
	)
	(segment
		(start 49.38141 -229.254812)
		(end 50.20691 -228.429312)
		(width 0.16002)
		(layer "In11.Cu")
		(net "M_F_CPU1_SA_DQS_DP<3>")
	)
	(segment
		(start 66.592958 -237.640876)
		(end 66.592958 -237.866936)
		(width 0.16002)
		(layer "In11.Cu")
		(net "M_F_CPU1_SA_DQS_DP<3>")
	)
	(segment
		(start 21.70811 -228.78542)
		(end 21.981922 -229.059232)
		(width 0.16002)
		(layer "In11.Cu")
		(net "M_F_CPU1_SA_DQS_DP<3>")
	)
	(segment
		(start 83.392518 -241.569494)
		(end 83.4009 -241.57432)
		(width 0.09525)
		(layer "In11.Cu")
		(net "M_F_CPU1_SA_DQS_DP<3>")
	)
	(segment
		(start 68.364862 -238.61649)
		(end 67.96659 -239.014508)
		(width 0.16002)
		(layer "In11.Cu")
		(net "M_F_CPU1_SA_DQS_DP<3>")
	)
	(segment
		(start 56.952896 -229.227126)
		(end 57.75071 -228.429312)
		(width 0.16002)
		(layer "In11.Cu")
		(net "M_F_CPU1_SA_DQS_DP<3>")
	)
	(segment
		(start 75.979528 -240.390934)
		(end 76.038456 -240.449862)
		(width 0.09525)
		(layer "In11.Cu")
		(net "M_F_CPU1_SA_DQS_DP<3>")
	)
	(segment
		(start 84.266278 -241.536474)
		(end 84.367116 -241.509804)
		(width 0.09525)
		(layer "In11.Cu")
		(net "M_F_CPU1_SA_DQS_DP<3>")
	)
	(segment
		(start 82.452464 -241.569494)
		(end 82.460846 -241.57432)
		(width 0.09525)
		(layer "In11.Cu")
		(net "M_F_CPU1_SA_DQS_DP<3>")
	)
	(segment
		(start 34.293302 -229.254812)
		(end 35.118802 -228.429312)
		(width 0.16002)
		(layer "In11.Cu")
		(net "M_F_CPU1_SA_DQS_DP<3>")
	)
	(segment
		(start 66.090292 -236.34192)
		(end 66.566796 -236.34192)
		(width 0.16002)
		(layer "In11.Cu")
		(net "M_F_CPU1_SA_DQS_DP<3>")
	)
	(segment
		(start 66.592958 -237.866936)
		(end 66.839592 -238.11357)
		(width 0.16002)
		(layer "In11.Cu")
		(net "M_F_CPU1_SA_DQS_DP<3>")
	)
	(segment
		(start 50.651664 -228.429312)
		(end 51.020726 -228.06025)
		(width 0.16002)
		(layer "In11.Cu")
		(net "M_F_CPU1_SA_DQS_DP<3>")
	)
	(segment
		(start 30.245304 -228.06025)
		(end 31.095188 -228.910134)
		(width 0.16002)
		(layer "In11.Cu")
		(net "M_F_CPU1_SA_DQS_DP<3>")
	)
	(segment
		(start 35.563556 -228.429312)
		(end 35.932618 -228.06025)
		(width 0.16002)
		(layer "In11.Cu")
		(net "M_F_CPU1_SA_DQS_DP<3>")
	)
	(segment
		(start 64.318388 -235.366306)
		(end 64.71666 -234.968288)
		(width 0.16002)
		(layer "In11.Cu")
		(net "M_F_CPU1_SA_DQS_DP<3>")
	)
	(segment
		(start 26.005282 -228.910134)
		(end 26.34996 -229.254812)
		(width 0.16002)
		(layer "In11.Cu")
		(net "M_F_CPU1_SA_DQS_DP<3>")
	)
	(segment
		(start 65.219326 -236.267244)
		(end 65.219326 -236.493304)
		(width 0.16002)
		(layer "In11.Cu")
		(net "M_F_CPU1_SA_DQS_DP<3>")
	)
	(segment
		(start 81.881218 -241.57432)
		(end 81.8896 -241.569494)
		(width 0.09525)
		(layer "In11.Cu")
		(net "M_F_CPU1_SA_DQS_DP<3>")
	)
	(segment
		(start 76.038456 -240.449862)
		(end 76.252832 -240.449862)
		(width 0.09525)
		(layer "In11.Cu")
		(net "M_F_CPU1_SA_DQS_DP<3>")
	)
	(segment
		(start 27.574748 -228.429312)
		(end 28.019502 -228.429312)
		(width 0.16002)
		(layer "In11.Cu")
		(net "M_F_CPU1_SA_DQS_DP<3>")
	)
	(segment
		(start 84.367116 -241.509804)
		(end 84.52104 -241.244374)
		(width 0.09525)
		(layer "In11.Cu")
		(net "M_F_CPU1_SA_DQS_DP<3>")
	)
	(segment
		(start 58.85307 -228.429312)
		(end 63.598806 -233.175048)
		(width 0.16002)
		(layer "In11.Cu")
		(net "M_F_CPU1_SA_DQS_DP<3>")
	)
	(segment
		(start 54.044342 -229.227126)
		(end 56.952896 -229.227126)
		(width 0.16002)
		(layer "In11.Cu")
		(net "M_F_CPU1_SA_DQS_DP<3>")
	)
	(segment
		(start 52.877466 -228.06025)
		(end 54.044342 -229.227126)
		(width 0.16002)
		(layer "In11.Cu")
		(net "M_F_CPU1_SA_DQS_DP<3>")
	)
	(segment
		(start 66.99123 -236.766354)
		(end 66.99123 -237.242858)
		(width 0.16002)
		(layer "In11.Cu")
		(net "M_F_CPU1_SA_DQS_DP<3>")
	)
	(segment
		(start 66.99123 -237.242858)
		(end 66.592958 -237.640876)
		(width 0.16002)
		(layer "In11.Cu")
		(net "M_F_CPU1_SA_DQS_DP<3>")
	)
	(segment
		(start 24.1554 -228.910134)
		(end 26.005282 -228.910134)
		(width 0.16002)
		(layer "In11.Cu")
		(net "M_F_CPU1_SA_DQS_DP<3>")
	)
	(segment
		(start 79.614776 -241.55908)
		(end 79.63281 -241.569494)
		(width 0.09525)
		(layer "In11.Cu")
		(net "M_F_CPU1_SA_DQS_DP<3>")
	)
	(segment
		(start 46.183296 -228.910134)
		(end 48.637444 -228.910134)
		(width 0.16002)
		(layer "In11.Cu")
		(net "M_F_CPU1_SA_DQS_DP<3>")
	)
	(segment
		(start 38.639242 -228.910134)
		(end 41.09339 -228.910134)
		(width 0.16002)
		(layer "In11.Cu")
		(net "M_F_CPU1_SA_DQS_DP<3>")
	)
	(segment
		(start 63.598806 -234.872784)
		(end 64.092328 -235.366306)
		(width 0.16002)
		(layer "In11.Cu")
		(net "M_F_CPU1_SA_DQS_DP<3>")
	)
	(segment
		(start 65.193164 -234.968288)
		(end 65.617598 -235.392722)
		(width 0.16002)
		(layer "In11.Cu")
		(net "M_F_CPU1_SA_DQS_DP<3>")
	)
	(segment
		(start 77.591666 -241.493802)
		(end 78.316074 -241.493802)
		(width 0.09525)
		(layer "In11.Cu")
		(net "M_F_CPU1_SA_DQS_DP<3>")
	)
	(segment
		(start 78.316074 -241.493802)
		(end 78.316582 -241.493294)
		(width 0.09525)
		(layer "In11.Cu")
		(net "M_F_CPU1_SA_DQS_DP<3>")
	)
	(arc
		(start 84.245958 -241.5286)
		(mid 84.256157 -241.532437)
		(end 84.266278 -241.536474)
		(width 0.09525)
		(layer "In11.Cu")
		(net "M_F_CPU1_SA_DQS_DP<3>")
	)
	(arc
		(start 82.460846 -241.57432)
		(mid 82.645878 -241.620234)
		(end 82.829654 -241.569494)
		(width 0.09525)
		(layer "In11.Cu")
		(net "M_F_CPU1_SA_DQS_DP<3>")
	)
	(arc
		(start 78.411324 -241.493294)
		(mid 78.557351 -241.512698)
		(end 78.693264 -241.569494)
		(width 0.09525)
		(layer "In11.Cu")
		(net "M_F_CPU1_SA_DQS_DP<3>")
	)
	(arc
		(start 80.009746 -241.569494)
		(mid 80.291178 -241.493739)
		(end 80.57261 -241.569494)
		(width 0.09525)
		(layer "In11.Cu")
		(net "M_F_CPU1_SA_DQS_DP<3>")
	)
	(arc
		(start 83.4009 -241.57432)
		(mid 83.585932 -241.620234)
		(end 83.769708 -241.569494)
		(width 0.09525)
		(layer "In11.Cu")
		(net "M_F_CPU1_SA_DQS_DP<3>")
	)
	(arc
		(start 78.693264 -241.569494)
		(mid 78.875134 -241.620359)
		(end 79.05877 -241.576352)
		(width 0.09525)
		(layer "In11.Cu")
		(net "M_F_CPU1_SA_DQS_DP<3>")
	)
	(arc
		(start 79.070708 -241.569494)
		(mid 79.341396 -241.493842)
		(end 79.614776 -241.55908)
		(width 0.09525)
		(layer "In11.Cu")
		(net "M_F_CPU1_SA_DQS_DP<3>")
	)
	(arc
		(start 79.644748 -241.576352)
		(mid 79.828129 -241.620183)
		(end 80.009746 -241.569494)
		(width 0.09525)
		(layer "In11.Cu")
		(net "M_F_CPU1_SA_DQS_DP<3>")
	)
	(arc
		(start 82.829654 -241.569494)
		(mid 83.111086 -241.493739)
		(end 83.392518 -241.569494)
		(width 0.09525)
		(layer "In11.Cu")
		(net "M_F_CPU1_SA_DQS_DP<3>")
	)
	(arc
		(start 81.51241 -241.569494)
		(mid 81.696185 -241.620266)
		(end 81.881218 -241.57432)
		(width 0.09525)
		(layer "In11.Cu")
		(net "M_F_CPU1_SA_DQS_DP<3>")
	)
	(arc
		(start 80.57261 -241.569494)
		(mid 80.761078 -241.620171)
		(end 80.949546 -241.569494)
		(width 0.09525)
		(layer "In11.Cu")
		(net "M_F_CPU1_SA_DQS_DP<3>")
	)
	(arc
		(start 81.8896 -241.569494)
		(mid 82.171032 -241.493739)
		(end 82.452464 -241.569494)
		(width 0.09525)
		(layer "In11.Cu")
		(net "M_F_CPU1_SA_DQS_DP<3>")
	)
	(arc
		(start 80.949546 -241.569494)
		(mid 81.230978 -241.493739)
		(end 81.51241 -241.569494)
		(width 0.09525)
		(layer "In11.Cu")
		(net "M_F_CPU1_SA_DQS_DP<3>")
	)
	(arc
		(start 83.769708 -241.569494)
		(mid 84.003252 -241.495788)
		(end 84.245958 -241.5286)
		(width 0.09525)
		(layer "In11.Cu")
		(net "M_F_CPU1_SA_DQS_DP<3>")
	)
	(segment
		(start 84.987892 -236.650276)
		(end 84.52104 -236.384338)
		(width 0.12954)
		(layer "F.Cu")
		(net "M_F_CPU1_SA_DQS_DP<2>")
	)
	(segment
		(start 76.03871 -234.798616)
		(end 76.22159 -234.798616)
		(width 0.09525)
		(layer "In11.Cu")
		(net "M_F_CPU1_SA_DQS_DP<2>")
	)
	(segment
		(start 37.789358 -218.710256)
		(end 38.639242 -219.56014)
		(width 0.16002)
		(layer "In11.Cu")
		(net "M_F_CPU1_SA_DQS_DP<2>")
	)
	(segment
		(start 75.955906 -234.739434)
		(end 75.979528 -234.739434)
		(width 0.09525)
		(layer "In11.Cu")
		(net "M_F_CPU1_SA_DQS_DP<2>")
	)
	(segment
		(start 76.22159 -234.798616)
		(end 76.424536 -235.001562)
		(width 0.09525)
		(layer "In11.Cu")
		(net "M_F_CPU1_SA_DQS_DP<2>")
	)
	(segment
		(start 48.637444 -219.56014)
		(end 48.982122 -219.904818)
		(width 0.16002)
		(layer "In11.Cu")
		(net "M_F_CPU1_SA_DQS_DP<2>")
	)
	(segment
		(start 26.130504 -220.238066)
		(end 26.416 -220.238066)
		(width 0.16002)
		(layer "In11.Cu")
		(net "M_F_CPU1_SA_DQS_DP<2>")
	)
	(segment
		(start 60.07989 -220.452188)
		(end 60.368942 -220.74124)
		(width 0.16002)
		(layer "In11.Cu")
		(net "M_F_CPU1_SA_DQS_DP<2>")
	)
	(segment
		(start 43.10761 -219.079318)
		(end 43.476672 -218.710256)
		(width 0.16002)
		(layer "In11.Cu")
		(net "M_F_CPU1_SA_DQS_DP<2>")
	)
	(segment
		(start 54.451504 -219.843604)
		(end 54.611524 -219.683584)
		(width 0.16002)
		(layer "In11.Cu")
		(net "M_F_CPU1_SA_DQS_DP<2>")
	)
	(segment
		(start 53.682392 -219.843604)
		(end 54.451504 -219.843604)
		(width 0.16002)
		(layer "In11.Cu")
		(net "M_F_CPU1_SA_DQS_DP<2>")
	)
	(segment
		(start 57.30875 -220.209618)
		(end 57.30875 -219.416376)
		(width 0.16002)
		(layer "In11.Cu")
		(net "M_F_CPU1_SA_DQS_DP<2>")
	)
	(segment
		(start 63.54445 -223.916748)
		(end 63.54445 -224.447354)
		(width 0.16002)
		(layer "In11.Cu")
		(net "M_F_CPU1_SA_DQS_DP<2>")
	)
	(segment
		(start 73.83653 -234.739434)
		(end 75.955906 -234.739434)
		(width 0.16002)
		(layer "In11.Cu")
		(net "M_F_CPU1_SA_DQS_DP<2>")
	)
	(segment
		(start 51.020726 -218.710256)
		(end 52.877466 -218.710256)
		(width 0.16002)
		(layer "In11.Cu")
		(net "M_F_CPU1_SA_DQS_DP<2>")
	)
	(segment
		(start 61.742574 -222.114872)
		(end 62.360302 -222.114872)
		(width 0.16002)
		(layer "In11.Cu")
		(net "M_F_CPU1_SA_DQS_DP<2>")
	)
	(segment
		(start 63.54445 -224.447354)
		(end 73.83653 -234.739434)
		(width 0.16002)
		(layer "In11.Cu")
		(net "M_F_CPU1_SA_DQS_DP<2>")
	)
	(segment
		(start 24.1554 -219.56014)
		(end 25.452578 -219.56014)
		(width 0.16002)
		(layer "In11.Cu")
		(net "M_F_CPU1_SA_DQS_DP<2>")
	)
	(segment
		(start 79.05877 -236.716316)
		(end 79.070708 -236.709458)
		(width 0.09525)
		(layer "In11.Cu")
		(net "M_F_CPU1_SA_DQS_DP<2>")
	)
	(segment
		(start 42.662856 -219.079318)
		(end 43.10761 -219.079318)
		(width 0.16002)
		(layer "In11.Cu")
		(net "M_F_CPU1_SA_DQS_DP<2>")
	)
	(segment
		(start 75.979528 -234.739434)
		(end 76.03871 -234.798616)
		(width 0.09525)
		(layer "In11.Cu")
		(net "M_F_CPU1_SA_DQS_DP<2>")
	)
	(segment
		(start 53.291232 -219.124022)
		(end 53.291232 -219.452444)
		(width 0.16002)
		(layer "In11.Cu")
		(net "M_F_CPU1_SA_DQS_DP<2>")
	)
	(segment
		(start 61.453522 -221.208092)
		(end 61.453522 -221.82582)
		(width 0.16002)
		(layer "In11.Cu")
		(net "M_F_CPU1_SA_DQS_DP<2>")
	)
	(segment
		(start 57.14873 -220.369638)
		(end 57.30875 -220.209618)
		(width 0.16002)
		(layer "In11.Cu")
		(net "M_F_CPU1_SA_DQS_DP<2>")
	)
	(segment
		(start 55.54726 -219.168726)
		(end 55.884318 -219.505784)
		(width 0.16002)
		(layer "In11.Cu")
		(net "M_F_CPU1_SA_DQS_DP<2>")
	)
	(segment
		(start 52.877466 -218.710256)
		(end 53.291232 -219.124022)
		(width 0.16002)
		(layer "In11.Cu")
		(net "M_F_CPU1_SA_DQS_DP<2>")
	)
	(segment
		(start 62.827154 -222.581724)
		(end 62.827154 -223.199452)
		(width 0.16002)
		(layer "In11.Cu")
		(net "M_F_CPU1_SA_DQS_DP<2>")
	)
	(segment
		(start 24.006302 -219.709238)
		(end 24.1554 -219.56014)
		(width 0.16002)
		(layer "In11.Cu")
		(net "M_F_CPU1_SA_DQS_DP<2>")
	)
	(segment
		(start 27.574748 -219.079318)
		(end 28.019502 -219.079318)
		(width 0.16002)
		(layer "In11.Cu")
		(net "M_F_CPU1_SA_DQS_DP<2>")
	)
	(segment
		(start 82.452464 -236.709458)
		(end 82.460846 -236.714284)
		(width 0.09525)
		(layer "In11.Cu")
		(net "M_F_CPU1_SA_DQS_DP<2>")
	)
	(segment
		(start 26.416 -220.238066)
		(end 27.574748 -219.079318)
		(width 0.16002)
		(layer "In11.Cu")
		(net "M_F_CPU1_SA_DQS_DP<2>")
	)
	(segment
		(start 60.07989 -219.83446)
		(end 60.07989 -220.452188)
		(width 0.16002)
		(layer "In11.Cu")
		(net "M_F_CPU1_SA_DQS_DP<2>")
	)
	(segment
		(start 33.93059 -220.26753)
		(end 35.118802 -219.079318)
		(width 0.16002)
		(layer "In11.Cu")
		(net "M_F_CPU1_SA_DQS_DP<2>")
	)
	(segment
		(start 50.651664 -219.079318)
		(end 51.020726 -218.710256)
		(width 0.16002)
		(layer "In11.Cu")
		(net "M_F_CPU1_SA_DQS_DP<2>")
	)
	(segment
		(start 41.474644 -220.26753)
		(end 42.662856 -219.079318)
		(width 0.16002)
		(layer "In11.Cu")
		(net "M_F_CPU1_SA_DQS_DP<2>")
	)
	(segment
		(start 59.613038 -219.367608)
		(end 60.07989 -219.83446)
		(width 0.16002)
		(layer "In11.Cu")
		(net "M_F_CPU1_SA_DQS_DP<2>")
	)
	(segment
		(start 56.044338 -220.369638)
		(end 57.14873 -220.369638)
		(width 0.16002)
		(layer "In11.Cu")
		(net "M_F_CPU1_SA_DQS_DP<2>")
	)
	(segment
		(start 77.154786 -235.593636)
		(end 78.194408 -236.633258)
		(width 0.09525)
		(layer "In11.Cu")
		(net "M_F_CPU1_SA_DQS_DP<2>")
	)
	(segment
		(start 30.245304 -218.710256)
		(end 31.095188 -219.56014)
		(width 0.16002)
		(layer "In11.Cu")
		(net "M_F_CPU1_SA_DQS_DP<2>")
	)
	(segment
		(start 53.291232 -219.452444)
		(end 53.682392 -219.843604)
		(width 0.16002)
		(layer "In11.Cu")
		(net "M_F_CPU1_SA_DQS_DP<2>")
	)
	(segment
		(start 28.019502 -219.079318)
		(end 28.388564 -218.710256)
		(width 0.16002)
		(layer "In11.Cu")
		(net "M_F_CPU1_SA_DQS_DP<2>")
	)
	(segment
		(start 21.70811 -219.435426)
		(end 21.981922 -219.709238)
		(width 0.16002)
		(layer "In11.Cu")
		(net "M_F_CPU1_SA_DQS_DP<2>")
	)
	(segment
		(start 60.98667 -220.74124)
		(end 61.453522 -221.208092)
		(width 0.16002)
		(layer "In11.Cu")
		(net "M_F_CPU1_SA_DQS_DP<2>")
	)
	(segment
		(start 84.367116 -236.649768)
		(end 84.52104 -236.384338)
		(width 0.09525)
		(layer "In11.Cu")
		(net "M_F_CPU1_SA_DQS_DP<2>")
	)
	(segment
		(start 35.118802 -219.079318)
		(end 35.563556 -219.079318)
		(width 0.16002)
		(layer "In11.Cu")
		(net "M_F_CPU1_SA_DQS_DP<2>")
	)
	(segment
		(start 49.38141 -219.904818)
		(end 50.20691 -219.079318)
		(width 0.16002)
		(layer "In11.Cu")
		(net "M_F_CPU1_SA_DQS_DP<2>")
	)
	(segment
		(start 55.884318 -220.209618)
		(end 56.044338 -220.369638)
		(width 0.16002)
		(layer "In11.Cu")
		(net "M_F_CPU1_SA_DQS_DP<2>")
	)
	(segment
		(start 84.266278 -236.676438)
		(end 84.367116 -236.649768)
		(width 0.09525)
		(layer "In11.Cu")
		(net "M_F_CPU1_SA_DQS_DP<2>")
	)
	(segment
		(start 41.248076 -220.26753)
		(end 41.474644 -220.26753)
		(width 0.16002)
		(layer "In11.Cu")
		(net "M_F_CPU1_SA_DQS_DP<2>")
	)
	(segment
		(start 43.476672 -218.710256)
		(end 45.333412 -218.710256)
		(width 0.16002)
		(layer "In11.Cu")
		(net "M_F_CPU1_SA_DQS_DP<2>")
	)
	(segment
		(start 45.333412 -218.710256)
		(end 46.183296 -219.56014)
		(width 0.16002)
		(layer "In11.Cu")
		(net "M_F_CPU1_SA_DQS_DP<2>")
	)
	(segment
		(start 62.827154 -223.199452)
		(end 63.54445 -223.916748)
		(width 0.16002)
		(layer "In11.Cu")
		(net "M_F_CPU1_SA_DQS_DP<2>")
	)
	(segment
		(start 33.704022 -220.26753)
		(end 33.93059 -220.26753)
		(width 0.16002)
		(layer "In11.Cu")
		(net "M_F_CPU1_SA_DQS_DP<2>")
	)
	(segment
		(start 55.884318 -219.505784)
		(end 55.884318 -220.209618)
		(width 0.16002)
		(layer "In11.Cu")
		(net "M_F_CPU1_SA_DQS_DP<2>")
	)
	(segment
		(start 76.424536 -235.001562)
		(end 76.424536 -235.244386)
		(width 0.09525)
		(layer "In11.Cu")
		(net "M_F_CPU1_SA_DQS_DP<2>")
	)
	(segment
		(start 57.30875 -219.416376)
		(end 57.645808 -219.079318)
		(width 0.16002)
		(layer "In11.Cu")
		(net "M_F_CPU1_SA_DQS_DP<2>")
	)
	(segment
		(start 46.183296 -219.56014)
		(end 48.637444 -219.56014)
		(width 0.16002)
		(layer "In11.Cu")
		(net "M_F_CPU1_SA_DQS_DP<2>")
	)
	(segment
		(start 31.095188 -219.56014)
		(end 32.996632 -219.56014)
		(width 0.16002)
		(layer "In11.Cu")
		(net "M_F_CPU1_SA_DQS_DP<2>")
	)
	(segment
		(start 79.614776 -236.699044)
		(end 79.63281 -236.709458)
		(width 0.09525)
		(layer "In11.Cu")
		(net "M_F_CPU1_SA_DQS_DP<2>")
	)
	(segment
		(start 58.99531 -219.367608)
		(end 59.613038 -219.367608)
		(width 0.16002)
		(layer "In11.Cu")
		(net "M_F_CPU1_SA_DQS_DP<2>")
	)
	(segment
		(start 48.982122 -219.904818)
		(end 49.38141 -219.904818)
		(width 0.16002)
		(layer "In11.Cu")
		(net "M_F_CPU1_SA_DQS_DP<2>")
	)
	(segment
		(start 35.563556 -219.079318)
		(end 35.932618 -218.710256)
		(width 0.16002)
		(layer "In11.Cu")
		(net "M_F_CPU1_SA_DQS_DP<2>")
	)
	(segment
		(start 62.360302 -222.114872)
		(end 62.827154 -222.581724)
		(width 0.16002)
		(layer "In11.Cu")
		(net "M_F_CPU1_SA_DQS_DP<2>")
	)
	(segment
		(start 76.773786 -235.593636)
		(end 77.154786 -235.593636)
		(width 0.09525)
		(layer "In11.Cu")
		(net "M_F_CPU1_SA_DQS_DP<2>")
	)
	(segment
		(start 38.639242 -219.56014)
		(end 40.540686 -219.56014)
		(width 0.16002)
		(layer "In11.Cu")
		(net "M_F_CPU1_SA_DQS_DP<2>")
	)
	(segment
		(start 21.981922 -219.709238)
		(end 24.006302 -219.709238)
		(width 0.16002)
		(layer "In11.Cu")
		(net "M_F_CPU1_SA_DQS_DP<2>")
	)
	(segment
		(start 40.540686 -219.56014)
		(end 41.248076 -220.26753)
		(width 0.16002)
		(layer "In11.Cu")
		(net "M_F_CPU1_SA_DQS_DP<2>")
	)
	(segment
		(start 54.611524 -219.683584)
		(end 54.611524 -219.505784)
		(width 0.16002)
		(layer "In11.Cu")
		(net "M_F_CPU1_SA_DQS_DP<2>")
	)
	(segment
		(start 25.452578 -219.56014)
		(end 26.130504 -220.238066)
		(width 0.16002)
		(layer "In11.Cu")
		(net "M_F_CPU1_SA_DQS_DP<2>")
	)
	(segment
		(start 54.611524 -219.505784)
		(end 54.948582 -219.168726)
		(width 0.16002)
		(layer "In11.Cu")
		(net "M_F_CPU1_SA_DQS_DP<2>")
	)
	(segment
		(start 60.368942 -220.74124)
		(end 60.98667 -220.74124)
		(width 0.16002)
		(layer "In11.Cu")
		(net "M_F_CPU1_SA_DQS_DP<2>")
	)
	(segment
		(start 81.881218 -236.714284)
		(end 81.8896 -236.709458)
		(width 0.09525)
		(layer "In11.Cu")
		(net "M_F_CPU1_SA_DQS_DP<2>")
	)
	(segment
		(start 78.194408 -236.633258)
		(end 78.41107 -236.633258)
		(width 0.09525)
		(layer "In11.Cu")
		(net "M_F_CPU1_SA_DQS_DP<2>")
	)
	(segment
		(start 35.932618 -218.710256)
		(end 37.789358 -218.710256)
		(width 0.16002)
		(layer "In11.Cu")
		(net "M_F_CPU1_SA_DQS_DP<2>")
	)
	(segment
		(start 50.20691 -219.079318)
		(end 50.651664 -219.079318)
		(width 0.16002)
		(layer "In11.Cu")
		(net "M_F_CPU1_SA_DQS_DP<2>")
	)
	(segment
		(start 57.645808 -219.079318)
		(end 58.70702 -219.079318)
		(width 0.16002)
		(layer "In11.Cu")
		(net "M_F_CPU1_SA_DQS_DP<2>")
	)
	(segment
		(start 79.63281 -236.709458)
		(end 79.644748 -236.716316)
		(width 0.09525)
		(layer "In11.Cu")
		(net "M_F_CPU1_SA_DQS_DP<2>")
	)
	(segment
		(start 76.424536 -235.244386)
		(end 76.773786 -235.593636)
		(width 0.09525)
		(layer "In11.Cu")
		(net "M_F_CPU1_SA_DQS_DP<2>")
	)
	(segment
		(start 54.948582 -219.168726)
		(end 55.54726 -219.168726)
		(width 0.16002)
		(layer "In11.Cu")
		(net "M_F_CPU1_SA_DQS_DP<2>")
	)
	(segment
		(start 28.388564 -218.710256)
		(end 30.245304 -218.710256)
		(width 0.16002)
		(layer "In11.Cu")
		(net "M_F_CPU1_SA_DQS_DP<2>")
	)
	(segment
		(start 61.453522 -221.82582)
		(end 61.742574 -222.114872)
		(width 0.16002)
		(layer "In11.Cu")
		(net "M_F_CPU1_SA_DQS_DP<2>")
	)
	(segment
		(start 58.70702 -219.079318)
		(end 58.99531 -219.367608)
		(width 0.16002)
		(layer "In11.Cu")
		(net "M_F_CPU1_SA_DQS_DP<2>")
	)
	(segment
		(start 32.996632 -219.56014)
		(end 33.704022 -220.26753)
		(width 0.16002)
		(layer "In11.Cu")
		(net "M_F_CPU1_SA_DQS_DP<2>")
	)
	(segment
		(start 83.392518 -236.709458)
		(end 83.4009 -236.714284)
		(width 0.09525)
		(layer "In11.Cu")
		(net "M_F_CPU1_SA_DQS_DP<2>")
	)
	(arc
		(start 80.949546 -236.709458)
		(mid 81.230978 -236.633703)
		(end 81.51241 -236.709458)
		(width 0.09525)
		(layer "In11.Cu")
		(net "M_F_CPU1_SA_DQS_DP<2>")
	)
	(arc
		(start 83.769708 -236.709458)
		(mid 84.003252 -236.635752)
		(end 84.245958 -236.668564)
		(width 0.09525)
		(layer "In11.Cu")
		(net "M_F_CPU1_SA_DQS_DP<2>")
	)
	(arc
		(start 81.51241 -236.709458)
		(mid 81.696185 -236.76023)
		(end 81.881218 -236.714284)
		(width 0.09525)
		(layer "In11.Cu")
		(net "M_F_CPU1_SA_DQS_DP<2>")
	)
	(arc
		(start 81.8896 -236.709458)
		(mid 82.171032 -236.633703)
		(end 82.452464 -236.709458)
		(width 0.09525)
		(layer "In11.Cu")
		(net "M_F_CPU1_SA_DQS_DP<2>")
	)
	(arc
		(start 78.693264 -236.709458)
		(mid 78.875134 -236.760323)
		(end 79.05877 -236.716316)
		(width 0.09525)
		(layer "In11.Cu")
		(net "M_F_CPU1_SA_DQS_DP<2>")
	)
	(arc
		(start 80.57261 -236.709458)
		(mid 80.761078 -236.760135)
		(end 80.949546 -236.709458)
		(width 0.09525)
		(layer "In11.Cu")
		(net "M_F_CPU1_SA_DQS_DP<2>")
	)
	(arc
		(start 84.245958 -236.668564)
		(mid 84.256157 -236.672401)
		(end 84.266278 -236.676438)
		(width 0.09525)
		(layer "In11.Cu")
		(net "M_F_CPU1_SA_DQS_DP<2>")
	)
	(arc
		(start 79.070708 -236.709458)
		(mid 79.341396 -236.633806)
		(end 79.614776 -236.699044)
		(width 0.09525)
		(layer "In11.Cu")
		(net "M_F_CPU1_SA_DQS_DP<2>")
	)
	(arc
		(start 79.644748 -236.716316)
		(mid 79.828129 -236.760147)
		(end 80.009746 -236.709458)
		(width 0.09525)
		(layer "In11.Cu")
		(net "M_F_CPU1_SA_DQS_DP<2>")
	)
	(arc
		(start 82.829654 -236.709458)
		(mid 83.111086 -236.633703)
		(end 83.392518 -236.709458)
		(width 0.09525)
		(layer "In11.Cu")
		(net "M_F_CPU1_SA_DQS_DP<2>")
	)
	(arc
		(start 83.4009 -236.714284)
		(mid 83.585932 -236.760198)
		(end 83.769708 -236.709458)
		(width 0.09525)
		(layer "In11.Cu")
		(net "M_F_CPU1_SA_DQS_DP<2>")
	)
	(arc
		(start 78.41107 -236.633258)
		(mid 78.557229 -236.652629)
		(end 78.693264 -236.709458)
		(width 0.09525)
		(layer "In11.Cu")
		(net "M_F_CPU1_SA_DQS_DP<2>")
	)
	(arc
		(start 82.460846 -236.714284)
		(mid 82.645878 -236.760198)
		(end 82.829654 -236.709458)
		(width 0.09525)
		(layer "In11.Cu")
		(net "M_F_CPU1_SA_DQS_DP<2>")
	)
	(arc
		(start 80.009746 -236.709458)
		(mid 80.291178 -236.633703)
		(end 80.57261 -236.709458)
		(width 0.09525)
		(layer "In11.Cu")
		(net "M_F_CPU1_SA_DQS_DP<2>")
	)
	(segment
		(start 84.987892 -231.79024)
		(end 84.52104 -231.524302)
		(width 0.12954)
		(layer "F.Cu")
		(net "M_F_CPU1_SA_DQS_DP<1>")
	)
	(segment
		(start 64.68872 -216.319354)
		(end 64.936116 -216.56675)
		(width 0.16002)
		(layer "In11.Cu")
		(net "M_F_CPU1_SA_DQS_DP<1>")
	)
	(segment
		(start 54.727348 -210.225386)
		(end 55.501286 -210.225386)
		(width 0.16002)
		(layer "In11.Cu")
		(net "M_F_CPU1_SA_DQS_DP<1>")
	)
	(segment
		(start 24.006302 -210.359244)
		(end 24.1554 -210.210146)
		(width 0.16002)
		(layer "In11.Cu")
		(net "M_F_CPU1_SA_DQS_DP<1>")
	)
	(segment
		(start 67.435984 -219.066618)
		(end 67.68338 -219.314014)
		(width 0.16002)
		(layer "In11.Cu")
		(net "M_F_CPU1_SA_DQS_DP<1>")
	)
	(segment
		(start 65.019428 -215.762586)
		(end 64.68872 -216.093294)
		(width 0.16002)
		(layer "In11.Cu")
		(net "M_F_CPU1_SA_DQS_DP<1>")
	)
	(segment
		(start 67.435984 -218.840558)
		(end 67.435984 -219.066618)
		(width 0.16002)
		(layer "In11.Cu")
		(net "M_F_CPU1_SA_DQS_DP<1>")
	)
	(segment
		(start 26.005282 -210.210146)
		(end 26.34996 -210.554824)
		(width 0.16002)
		(layer "In11.Cu")
		(net "M_F_CPU1_SA_DQS_DP<1>")
	)
	(segment
		(start 54.072028 -210.554824)
		(end 54.39791 -210.554824)
		(width 0.16002)
		(layer "In11.Cu")
		(net "M_F_CPU1_SA_DQS_DP<1>")
	)
	(segment
		(start 28.019502 -209.729324)
		(end 28.388564 -209.360262)
		(width 0.16002)
		(layer "In11.Cu")
		(net "M_F_CPU1_SA_DQS_DP<1>")
	)
	(segment
		(start 49.38141 -210.554824)
		(end 50.20691 -209.729324)
		(width 0.16002)
		(layer "In11.Cu")
		(net "M_F_CPU1_SA_DQS_DP<1>")
	)
	(segment
		(start 33.894014 -210.554824)
		(end 34.293302 -210.554824)
		(width 0.16002)
		(layer "In11.Cu")
		(net "M_F_CPU1_SA_DQS_DP<1>")
	)
	(segment
		(start 35.118802 -209.729324)
		(end 35.563556 -209.729324)
		(width 0.16002)
		(layer "In11.Cu")
		(net "M_F_CPU1_SA_DQS_DP<1>")
	)
	(segment
		(start 59.46267 -209.729324)
		(end 65.019428 -215.286082)
		(width 0.16002)
		(layer "In11.Cu")
		(net "M_F_CPU1_SA_DQS_DP<1>")
	)
	(segment
		(start 65.969388 -216.236042)
		(end 66.39306 -216.659714)
		(width 0.16002)
		(layer "In11.Cu")
		(net "M_F_CPU1_SA_DQS_DP<1>")
	)
	(segment
		(start 43.476672 -209.360262)
		(end 45.333412 -209.360262)
		(width 0.16002)
		(layer "In11.Cu")
		(net "M_F_CPU1_SA_DQS_DP<1>")
	)
	(segment
		(start 75.97267 -229.003606)
		(end 76.595224 -229.626414)
		(width 0.09525)
		(layer "In11.Cu")
		(net "M_F_CPU1_SA_DQS_DP<1>")
	)
	(segment
		(start 48.637444 -210.210146)
		(end 48.982122 -210.554824)
		(width 0.16002)
		(layer "In11.Cu")
		(net "M_F_CPU1_SA_DQS_DP<1>")
	)
	(segment
		(start 42.662856 -209.729324)
		(end 43.10761 -209.729324)
		(width 0.16002)
		(layer "In11.Cu")
		(net "M_F_CPU1_SA_DQS_DP<1>")
	)
	(segment
		(start 79.614776 -231.839008)
		(end 79.63281 -231.849422)
		(width 0.09525)
		(layer "In11.Cu")
		(net "M_F_CPU1_SA_DQS_DP<1>")
	)
	(segment
		(start 37.789358 -209.360262)
		(end 38.639242 -210.210146)
		(width 0.16002)
		(layer "In11.Cu")
		(net "M_F_CPU1_SA_DQS_DP<1>")
	)
	(segment
		(start 57.75071 -209.729324)
		(end 59.46267 -209.729324)
		(width 0.16002)
		(layer "In11.Cu")
		(net "M_F_CPU1_SA_DQS_DP<1>")
	)
	(segment
		(start 41.837356 -210.554824)
		(end 42.662856 -209.729324)
		(width 0.16002)
		(layer "In11.Cu")
		(net "M_F_CPU1_SA_DQS_DP<1>")
	)
	(segment
		(start 76.595224 -229.626414)
		(end 77.03312 -229.626414)
		(width 0.09525)
		(layer "In11.Cu")
		(net "M_F_CPU1_SA_DQS_DP<1>")
	)
	(segment
		(start 66.309748 -217.940382)
		(end 66.535808 -217.940382)
		(width 0.16002)
		(layer "In11.Cu")
		(net "M_F_CPU1_SA_DQS_DP<1>")
	)
	(segment
		(start 66.535808 -217.940382)
		(end 66.866516 -217.609674)
		(width 0.16002)
		(layer "In11.Cu")
		(net "M_F_CPU1_SA_DQS_DP<1>")
	)
	(segment
		(start 56.21909 -210.94319)
		(end 56.536844 -210.94319)
		(width 0.16002)
		(layer "In11.Cu")
		(net "M_F_CPU1_SA_DQS_DP<1>")
	)
	(segment
		(start 69.23151 -219.498164)
		(end 69.23151 -222.179642)
		(width 0.16002)
		(layer "In11.Cu")
		(net "M_F_CPU1_SA_DQS_DP<1>")
	)
	(segment
		(start 24.1554 -210.210146)
		(end 26.005282 -210.210146)
		(width 0.16002)
		(layer "In11.Cu")
		(net "M_F_CPU1_SA_DQS_DP<1>")
	)
	(segment
		(start 79.05877 -231.85628)
		(end 79.070708 -231.849422)
		(width 0.09525)
		(layer "In11.Cu")
		(net "M_F_CPU1_SA_DQS_DP<1>")
	)
	(segment
		(start 77.478636 -230.07193)
		(end 77.478636 -230.775256)
		(width 0.09525)
		(layer "In11.Cu")
		(net "M_F_CPU1_SA_DQS_DP<1>")
	)
	(segment
		(start 67.34302 -217.609674)
		(end 67.766692 -218.033346)
		(width 0.16002)
		(layer "In11.Cu")
		(net "M_F_CPU1_SA_DQS_DP<1>")
	)
	(segment
		(start 68.240148 -218.983306)
		(end 68.716652 -218.983306)
		(width 0.16002)
		(layer "In11.Cu")
		(net "M_F_CPU1_SA_DQS_DP<1>")
	)
	(segment
		(start 82.452464 -231.849422)
		(end 82.460846 -231.854248)
		(width 0.09525)
		(layer "In11.Cu")
		(net "M_F_CPU1_SA_DQS_DP<1>")
	)
	(segment
		(start 77.03312 -229.626414)
		(end 77.478636 -230.07193)
		(width 0.09525)
		(layer "In11.Cu")
		(net "M_F_CPU1_SA_DQS_DP<1>")
	)
	(segment
		(start 65.162176 -216.56675)
		(end 65.492884 -216.236042)
		(width 0.16002)
		(layer "In11.Cu")
		(net "M_F_CPU1_SA_DQS_DP<1>")
	)
	(segment
		(start 51.020726 -209.360262)
		(end 52.877466 -209.360262)
		(width 0.16002)
		(layer "In11.Cu")
		(net "M_F_CPU1_SA_DQS_DP<1>")
	)
	(segment
		(start 33.549336 -210.210146)
		(end 33.894014 -210.554824)
		(width 0.16002)
		(layer "In11.Cu")
		(net "M_F_CPU1_SA_DQS_DP<1>")
	)
	(segment
		(start 35.563556 -209.729324)
		(end 35.932618 -209.360262)
		(width 0.16002)
		(layer "In11.Cu")
		(net "M_F_CPU1_SA_DQS_DP<1>")
	)
	(segment
		(start 27.574748 -209.729324)
		(end 28.019502 -209.729324)
		(width 0.16002)
		(layer "In11.Cu")
		(net "M_F_CPU1_SA_DQS_DP<1>")
	)
	(segment
		(start 52.877466 -209.360262)
		(end 54.072028 -210.554824)
		(width 0.16002)
		(layer "In11.Cu")
		(net "M_F_CPU1_SA_DQS_DP<1>")
	)
	(segment
		(start 30.245304 -209.360262)
		(end 31.095188 -210.210146)
		(width 0.16002)
		(layer "In11.Cu")
		(net "M_F_CPU1_SA_DQS_DP<1>")
	)
	(segment
		(start 66.062352 -217.466926)
		(end 66.062352 -217.692986)
		(width 0.16002)
		(layer "In11.Cu")
		(net "M_F_CPU1_SA_DQS_DP<1>")
	)
	(segment
		(start 83.392518 -231.849422)
		(end 83.4009 -231.854248)
		(width 0.09525)
		(layer "In11.Cu")
		(net "M_F_CPU1_SA_DQS_DP<1>")
	)
	(segment
		(start 66.39306 -216.659714)
		(end 66.39306 -217.136218)
		(width 0.16002)
		(layer "In11.Cu")
		(net "M_F_CPU1_SA_DQS_DP<1>")
	)
	(segment
		(start 21.70811 -210.085432)
		(end 21.981922 -210.359244)
		(width 0.16002)
		(layer "In11.Cu")
		(net "M_F_CPU1_SA_DQS_DP<1>")
	)
	(segment
		(start 67.766692 -218.50985)
		(end 67.435984 -218.840558)
		(width 0.16002)
		(layer "In11.Cu")
		(net "M_F_CPU1_SA_DQS_DP<1>")
	)
	(segment
		(start 64.68872 -216.093294)
		(end 64.68872 -216.319354)
		(width 0.16002)
		(layer "In11.Cu")
		(net "M_F_CPU1_SA_DQS_DP<1>")
	)
	(segment
		(start 79.63281 -231.849422)
		(end 79.644748 -231.85628)
		(width 0.09525)
		(layer "In11.Cu")
		(net "M_F_CPU1_SA_DQS_DP<1>")
	)
	(segment
		(start 48.982122 -210.554824)
		(end 49.38141 -210.554824)
		(width 0.16002)
		(layer "In11.Cu")
		(net "M_F_CPU1_SA_DQS_DP<1>")
	)
	(segment
		(start 38.639242 -210.210146)
		(end 41.09339 -210.210146)
		(width 0.16002)
		(layer "In11.Cu")
		(net "M_F_CPU1_SA_DQS_DP<1>")
	)
	(segment
		(start 78.326996 -231.623616)
		(end 78.448662 -231.623616)
		(width 0.09525)
		(layer "In11.Cu")
		(net "M_F_CPU1_SA_DQS_DP<1>")
	)
	(segment
		(start 50.651664 -209.729324)
		(end 51.020726 -209.360262)
		(width 0.16002)
		(layer "In11.Cu")
		(net "M_F_CPU1_SA_DQS_DP<1>")
	)
	(segment
		(start 35.932618 -209.360262)
		(end 37.789358 -209.360262)
		(width 0.16002)
		(layer "In11.Cu")
		(net "M_F_CPU1_SA_DQS_DP<1>")
	)
	(segment
		(start 84.367116 -231.789732)
		(end 84.52104 -231.524302)
		(width 0.09525)
		(layer "In11.Cu")
		(net "M_F_CPU1_SA_DQS_DP<1>")
	)
	(segment
		(start 31.095188 -210.210146)
		(end 33.549336 -210.210146)
		(width 0.16002)
		(layer "In11.Cu")
		(net "M_F_CPU1_SA_DQS_DP<1>")
	)
	(segment
		(start 77.478636 -230.775256)
		(end 78.326996 -231.623616)
		(width 0.09525)
		(layer "In11.Cu")
		(net "M_F_CPU1_SA_DQS_DP<1>")
	)
	(segment
		(start 84.266278 -231.816402)
		(end 84.367116 -231.789732)
		(width 0.09525)
		(layer "In11.Cu")
		(net "M_F_CPU1_SA_DQS_DP<1>")
	)
	(segment
		(start 26.34996 -210.554824)
		(end 26.749248 -210.554824)
		(width 0.16002)
		(layer "In11.Cu")
		(net "M_F_CPU1_SA_DQS_DP<1>")
	)
	(segment
		(start 46.183296 -210.210146)
		(end 48.637444 -210.210146)
		(width 0.16002)
		(layer "In11.Cu")
		(net "M_F_CPU1_SA_DQS_DP<1>")
	)
	(segment
		(start 66.062352 -217.692986)
		(end 66.309748 -217.940382)
		(width 0.16002)
		(layer "In11.Cu")
		(net "M_F_CPU1_SA_DQS_DP<1>")
	)
	(segment
		(start 69.23151 -222.179642)
		(end 75.955906 -228.904038)
		(width 0.16002)
		(layer "In11.Cu")
		(net "M_F_CPU1_SA_DQS_DP<1>")
	)
	(segment
		(start 65.492884 -216.236042)
		(end 65.969388 -216.236042)
		(width 0.16002)
		(layer "In11.Cu")
		(net "M_F_CPU1_SA_DQS_DP<1>")
	)
	(segment
		(start 67.68338 -219.314014)
		(end 67.90944 -219.314014)
		(width 0.16002)
		(layer "In11.Cu")
		(net "M_F_CPU1_SA_DQS_DP<1>")
	)
	(segment
		(start 81.881218 -231.854248)
		(end 81.8896 -231.849422)
		(width 0.09525)
		(layer "In11.Cu")
		(net "M_F_CPU1_SA_DQS_DP<1>")
	)
	(segment
		(start 41.09339 -210.210146)
		(end 41.438068 -210.554824)
		(width 0.16002)
		(layer "In11.Cu")
		(net "M_F_CPU1_SA_DQS_DP<1>")
	)
	(segment
		(start 67.90944 -219.314014)
		(end 68.240148 -218.983306)
		(width 0.16002)
		(layer "In11.Cu")
		(net "M_F_CPU1_SA_DQS_DP<1>")
	)
	(segment
		(start 75.955906 -228.904038)
		(end 75.97267 -228.920802)
		(width 0.09525)
		(layer "In11.Cu")
		(net "M_F_CPU1_SA_DQS_DP<1>")
	)
	(segment
		(start 28.388564 -209.360262)
		(end 30.245304 -209.360262)
		(width 0.16002)
		(layer "In11.Cu")
		(net "M_F_CPU1_SA_DQS_DP<1>")
	)
	(segment
		(start 65.019428 -215.286082)
		(end 65.019428 -215.762586)
		(width 0.16002)
		(layer "In11.Cu")
		(net "M_F_CPU1_SA_DQS_DP<1>")
	)
	(segment
		(start 64.936116 -216.56675)
		(end 65.162176 -216.56675)
		(width 0.16002)
		(layer "In11.Cu")
		(net "M_F_CPU1_SA_DQS_DP<1>")
	)
	(segment
		(start 43.10761 -209.729324)
		(end 43.476672 -209.360262)
		(width 0.16002)
		(layer "In11.Cu")
		(net "M_F_CPU1_SA_DQS_DP<1>")
	)
	(segment
		(start 45.333412 -209.360262)
		(end 46.183296 -210.210146)
		(width 0.16002)
		(layer "In11.Cu")
		(net "M_F_CPU1_SA_DQS_DP<1>")
	)
	(segment
		(start 67.766692 -218.033346)
		(end 67.766692 -218.50985)
		(width 0.16002)
		(layer "In11.Cu")
		(net "M_F_CPU1_SA_DQS_DP<1>")
	)
	(segment
		(start 21.981922 -210.359244)
		(end 24.006302 -210.359244)
		(width 0.16002)
		(layer "In11.Cu")
		(net "M_F_CPU1_SA_DQS_DP<1>")
	)
	(segment
		(start 26.749248 -210.554824)
		(end 27.574748 -209.729324)
		(width 0.16002)
		(layer "In11.Cu")
		(net "M_F_CPU1_SA_DQS_DP<1>")
	)
	(segment
		(start 41.438068 -210.554824)
		(end 41.837356 -210.554824)
		(width 0.16002)
		(layer "In11.Cu")
		(net "M_F_CPU1_SA_DQS_DP<1>")
	)
	(segment
		(start 50.20691 -209.729324)
		(end 50.651664 -209.729324)
		(width 0.16002)
		(layer "In11.Cu")
		(net "M_F_CPU1_SA_DQS_DP<1>")
	)
	(segment
		(start 66.39306 -217.136218)
		(end 66.062352 -217.466926)
		(width 0.16002)
		(layer "In11.Cu")
		(net "M_F_CPU1_SA_DQS_DP<1>")
	)
	(segment
		(start 56.536844 -210.94319)
		(end 57.75071 -209.729324)
		(width 0.16002)
		(layer "In11.Cu")
		(net "M_F_CPU1_SA_DQS_DP<1>")
	)
	(segment
		(start 66.866516 -217.609674)
		(end 67.34302 -217.609674)
		(width 0.16002)
		(layer "In11.Cu")
		(net "M_F_CPU1_SA_DQS_DP<1>")
	)
	(segment
		(start 55.501286 -210.225386)
		(end 56.21909 -210.94319)
		(width 0.16002)
		(layer "In11.Cu")
		(net "M_F_CPU1_SA_DQS_DP<1>")
	)
	(segment
		(start 78.448662 -231.623616)
		(end 78.615794 -231.790748)
		(width 0.09525)
		(layer "In11.Cu")
		(net "M_F_CPU1_SA_DQS_DP<1>")
	)
	(segment
		(start 54.39791 -210.554824)
		(end 54.727348 -210.225386)
		(width 0.16002)
		(layer "In11.Cu")
		(net "M_F_CPU1_SA_DQS_DP<1>")
	)
	(segment
		(start 34.293302 -210.554824)
		(end 35.118802 -209.729324)
		(width 0.16002)
		(layer "In11.Cu")
		(net "M_F_CPU1_SA_DQS_DP<1>")
	)
	(segment
		(start 68.716652 -218.983306)
		(end 69.23151 -219.498164)
		(width 0.16002)
		(layer "In11.Cu")
		(net "M_F_CPU1_SA_DQS_DP<1>")
	)
	(segment
		(start 75.97267 -228.920802)
		(end 75.97267 -229.003606)
		(width 0.09525)
		(layer "In11.Cu")
		(net "M_F_CPU1_SA_DQS_DP<1>")
	)
	(arc
		(start 84.245958 -231.808528)
		(mid 84.256157 -231.812365)
		(end 84.266278 -231.816402)
		(width 0.09525)
		(layer "In11.Cu")
		(net "M_F_CPU1_SA_DQS_DP<1>")
	)
	(arc
		(start 79.644748 -231.85628)
		(mid 79.828129 -231.900111)
		(end 80.009746 -231.849422)
		(width 0.09525)
		(layer "In11.Cu")
		(net "M_F_CPU1_SA_DQS_DP<1>")
	)
	(arc
		(start 79.070708 -231.849422)
		(mid 79.341396 -231.77377)
		(end 79.614776 -231.839008)
		(width 0.09525)
		(layer "In11.Cu")
		(net "M_F_CPU1_SA_DQS_DP<1>")
	)
	(arc
		(start 83.4009 -231.854248)
		(mid 83.585932 -231.900162)
		(end 83.769708 -231.849422)
		(width 0.09525)
		(layer "In11.Cu")
		(net "M_F_CPU1_SA_DQS_DP<1>")
	)
	(arc
		(start 78.615794 -231.790748)
		(mid 78.652624 -231.8226)
		(end 78.693264 -231.849422)
		(width 0.09525)
		(layer "In11.Cu")
		(net "M_F_CPU1_SA_DQS_DP<1>")
	)
	(arc
		(start 80.009746 -231.849422)
		(mid 80.291178 -231.773667)
		(end 80.57261 -231.849422)
		(width 0.09525)
		(layer "In11.Cu")
		(net "M_F_CPU1_SA_DQS_DP<1>")
	)
	(arc
		(start 80.949546 -231.849422)
		(mid 81.230978 -231.773667)
		(end 81.51241 -231.849422)
		(width 0.09525)
		(layer "In11.Cu")
		(net "M_F_CPU1_SA_DQS_DP<1>")
	)
	(arc
		(start 81.8896 -231.849422)
		(mid 82.171032 -231.773667)
		(end 82.452464 -231.849422)
		(width 0.09525)
		(layer "In11.Cu")
		(net "M_F_CPU1_SA_DQS_DP<1>")
	)
	(arc
		(start 82.829654 -231.849422)
		(mid 83.111086 -231.773667)
		(end 83.392518 -231.849422)
		(width 0.09525)
		(layer "In11.Cu")
		(net "M_F_CPU1_SA_DQS_DP<1>")
	)
	(arc
		(start 78.693264 -231.849422)
		(mid 78.875134 -231.900287)
		(end 79.05877 -231.85628)
		(width 0.09525)
		(layer "In11.Cu")
		(net "M_F_CPU1_SA_DQS_DP<1>")
	)
	(arc
		(start 81.51241 -231.849422)
		(mid 81.696185 -231.900194)
		(end 81.881218 -231.854248)
		(width 0.09525)
		(layer "In11.Cu")
		(net "M_F_CPU1_SA_DQS_DP<1>")
	)
	(arc
		(start 83.769708 -231.849422)
		(mid 84.003252 -231.775716)
		(end 84.245958 -231.808528)
		(width 0.09525)
		(layer "In11.Cu")
		(net "M_F_CPU1_SA_DQS_DP<1>")
	)
	(arc
		(start 80.57261 -231.849422)
		(mid 80.761078 -231.900099)
		(end 80.949546 -231.849422)
		(width 0.09525)
		(layer "In11.Cu")
		(net "M_F_CPU1_SA_DQS_DP<1>")
	)
	(arc
		(start 82.460846 -231.854248)
		(mid 82.645878 -231.900162)
		(end 82.829654 -231.849422)
		(width 0.09525)
		(layer "In11.Cu")
		(net "M_F_CPU1_SA_DQS_DP<1>")
	)
	(segment
		(start 84.987892 -226.930458)
		(end 84.52104 -226.66452)
		(width 0.12954)
		(layer "F.Cu")
		(net "M_F_CPU1_SA_DQS_DP<0>")
	)
	(segment
		(start 67.339972 -207.839056)
		(end 67.764406 -208.26349)
		(width 0.16002)
		(layer "In11.Cu")
		(net "M_F_CPU1_SA_DQS_DP<0>")
	)
	(segment
		(start 75.04557 -219.26677)
		(end 77.803248 -222.024448)
		(width 0.16002)
		(layer "In11.Cu")
		(net "M_F_CPU1_SA_DQS_DP<0>")
	)
	(segment
		(start 21.981922 -201.00925)
		(end 24.006302 -201.00925)
		(width 0.16002)
		(layer "In11.Cu")
		(net "M_F_CPU1_SA_DQS_DP<0>")
	)
	(segment
		(start 79.194914 -226.19843)
		(end 79.197708 -226.200208)
		(width 0.09525)
		(layer "In11.Cu")
		(net "M_F_CPU1_SA_DQS_DP<0>")
	)
	(segment
		(start 48.982122 -201.20483)
		(end 49.38141 -201.20483)
		(width 0.16002)
		(layer "In11.Cu")
		(net "M_F_CPU1_SA_DQS_DP<0>")
	)
	(segment
		(start 26.005282 -200.860152)
		(end 26.34996 -201.20483)
		(width 0.16002)
		(layer "In11.Cu")
		(net "M_F_CPU1_SA_DQS_DP<0>")
	)
	(segment
		(start 82.452464 -226.98964)
		(end 82.460846 -226.994466)
		(width 0.09525)
		(layer "In11.Cu")
		(net "M_F_CPU1_SA_DQS_DP<0>")
	)
	(segment
		(start 41.837356 -201.20483)
		(end 42.662856 -200.37933)
		(width 0.16002)
		(layer "In11.Cu")
		(net "M_F_CPU1_SA_DQS_DP<0>")
	)
	(segment
		(start 41.438068 -201.20483)
		(end 41.837356 -201.20483)
		(width 0.16002)
		(layer "In11.Cu")
		(net "M_F_CPU1_SA_DQS_DP<0>")
	)
	(segment
		(start 68.796408 -210.681062)
		(end 75.04557 -216.930224)
		(width 0.16002)
		(layer "In11.Cu")
		(net "M_F_CPU1_SA_DQS_DP<0>")
	)
	(segment
		(start 77.820012 -222.124524)
		(end 78.033372 -222.337884)
		(width 0.09525)
		(layer "In11.Cu")
		(net "M_F_CPU1_SA_DQS_DP<0>")
	)
	(segment
		(start 35.932618 -200.010268)
		(end 37.789358 -200.010268)
		(width 0.16002)
		(layer "In11.Cu")
		(net "M_F_CPU1_SA_DQS_DP<0>")
	)
	(segment
		(start 31.095188 -200.860152)
		(end 33.549336 -200.860152)
		(width 0.16002)
		(layer "In11.Cu")
		(net "M_F_CPU1_SA_DQS_DP<0>")
	)
	(segment
		(start 69.138038 -209.637122)
		(end 69.138038 -210.113626)
		(width 0.16002)
		(layer "In11.Cu")
		(net "M_F_CPU1_SA_DQS_DP<0>")
	)
	(segment
		(start 84.367116 -226.92995)
		(end 84.52104 -226.66452)
		(width 0.09525)
		(layer "In11.Cu")
		(net "M_F_CPU1_SA_DQS_DP<0>")
	)
	(segment
		(start 66.390774 -206.889858)
		(end 66.390774 -207.366362)
		(width 0.16002)
		(layer "In11.Cu")
		(net "M_F_CPU1_SA_DQS_DP<0>")
	)
	(segment
		(start 35.563556 -200.37933)
		(end 35.932618 -200.010268)
		(width 0.16002)
		(layer "In11.Cu")
		(net "M_F_CPU1_SA_DQS_DP<0>")
	)
	(segment
		(start 66.295778 -208.180432)
		(end 66.521838 -208.180432)
		(width 0.16002)
		(layer "In11.Cu")
		(net "M_F_CPU1_SA_DQS_DP<0>")
	)
	(segment
		(start 83.392518 -226.98964)
		(end 83.4009 -226.994466)
		(width 0.09525)
		(layer "In11.Cu")
		(net "M_F_CPU1_SA_DQS_DP<0>")
	)
	(segment
		(start 78.709774 -224.708974)
		(end 78.709266 -224.709228)
		(width 0.09525)
		(layer "In11.Cu")
		(net "M_F_CPU1_SA_DQS_DP<0>")
	)
	(segment
		(start 79.63281 -226.98964)
		(end 79.644748 -226.996498)
		(width 0.09525)
		(layer "In11.Cu")
		(net "M_F_CPU1_SA_DQS_DP<0>")
	)
	(segment
		(start 77.803248 -222.024448)
		(end 77.820012 -222.041212)
		(width 0.09525)
		(layer "In11.Cu")
		(net "M_F_CPU1_SA_DQS_DP<0>")
	)
	(segment
		(start 33.549336 -200.860152)
		(end 33.894014 -201.20483)
		(width 0.16002)
		(layer "In11.Cu")
		(net "M_F_CPU1_SA_DQS_DP<0>")
	)
	(segment
		(start 79.600044 -226.970844)
		(end 79.632556 -226.98964)
		(width 0.09525)
		(layer "In11.Cu")
		(net "M_F_CPU1_SA_DQS_DP<0>")
	)
	(segment
		(start 78.6765 -225.360484)
		(end 78.730602 -225.391726)
		(width 0.09525)
		(layer "In11.Cu")
		(net "M_F_CPU1_SA_DQS_DP<0>")
	)
	(segment
		(start 38.639242 -200.860152)
		(end 41.09339 -200.860152)
		(width 0.16002)
		(layer "In11.Cu")
		(net "M_F_CPU1_SA_DQS_DP<0>")
	)
	(segment
		(start 50.651664 -200.37933)
		(end 51.020726 -200.010268)
		(width 0.16002)
		(layer "In11.Cu")
		(net "M_F_CPU1_SA_DQS_DP<0>")
	)
	(segment
		(start 66.521838 -208.180432)
		(end 66.863468 -207.839056)
		(width 0.16002)
		(layer "In11.Cu")
		(net "M_F_CPU1_SA_DQS_DP<0>")
	)
	(segment
		(start 64.922146 -206.8068)
		(end 65.148206 -206.8068)
		(width 0.16002)
		(layer "In11.Cu")
		(net "M_F_CPU1_SA_DQS_DP<0>")
	)
	(segment
		(start 65.489836 -206.465424)
		(end 65.96634 -206.465424)
		(width 0.16002)
		(layer "In11.Cu")
		(net "M_F_CPU1_SA_DQS_DP<0>")
	)
	(segment
		(start 24.1554 -200.860152)
		(end 26.005282 -200.860152)
		(width 0.16002)
		(layer "In11.Cu")
		(net "M_F_CPU1_SA_DQS_DP<0>")
	)
	(segment
		(start 78.033372 -222.337884)
		(end 78.033372 -222.636334)
		(width 0.09525)
		(layer "In11.Cu")
		(net "M_F_CPU1_SA_DQS_DP<0>")
	)
	(segment
		(start 78.730602 -224.69729)
		(end 78.709774 -224.708974)
		(width 0.09525)
		(layer "In11.Cu")
		(net "M_F_CPU1_SA_DQS_DP<0>")
	)
	(segment
		(start 79.632556 -226.98964)
		(end 79.63281 -226.98964)
		(width 0.09525)
		(layer "In11.Cu")
		(net "M_F_CPU1_SA_DQS_DP<0>")
	)
	(segment
		(start 69.138038 -210.113626)
		(end 68.796408 -210.455002)
		(width 0.16002)
		(layer "In11.Cu")
		(net "M_F_CPU1_SA_DQS_DP<0>")
	)
	(segment
		(start 66.390774 -207.366362)
		(end 66.049144 -207.707738)
		(width 0.16002)
		(layer "In11.Cu")
		(net "M_F_CPU1_SA_DQS_DP<0>")
	)
	(segment
		(start 78.709266 -224.709228)
		(end 78.691994 -224.719134)
		(width 0.09525)
		(layer "In11.Cu")
		(net "M_F_CPU1_SA_DQS_DP<0>")
	)
	(segment
		(start 54.072028 -201.20483)
		(end 56.92521 -201.20483)
		(width 0.16002)
		(layer "In11.Cu")
		(net "M_F_CPU1_SA_DQS_DP<0>")
	)
	(segment
		(start 75.04557 -216.930224)
		(end 75.04557 -219.26677)
		(width 0.16002)
		(layer "In11.Cu")
		(net "M_F_CPU1_SA_DQS_DP<0>")
	)
	(segment
		(start 68.2371 -209.212688)
		(end 68.713604 -209.212688)
		(width 0.16002)
		(layer "In11.Cu")
		(net "M_F_CPU1_SA_DQS_DP<0>")
	)
	(segment
		(start 68.796408 -210.455002)
		(end 68.796408 -210.681062)
		(width 0.16002)
		(layer "In11.Cu")
		(net "M_F_CPU1_SA_DQS_DP<0>")
	)
	(segment
		(start 64.64173 -206.526384)
		(end 64.922146 -206.8068)
		(width 0.16002)
		(layer "In11.Cu")
		(net "M_F_CPU1_SA_DQS_DP<0>")
	)
	(segment
		(start 57.75071 -200.37933)
		(end 59.955176 -200.37933)
		(width 0.16002)
		(layer "In11.Cu")
		(net "M_F_CPU1_SA_DQS_DP<0>")
	)
	(segment
		(start 59.955176 -200.37933)
		(end 64.64173 -205.065884)
		(width 0.16002)
		(layer "In11.Cu")
		(net "M_F_CPU1_SA_DQS_DP<0>")
	)
	(segment
		(start 67.764406 -208.739994)
		(end 67.422776 -209.08137)
		(width 0.16002)
		(layer "In11.Cu")
		(net "M_F_CPU1_SA_DQS_DP<0>")
	)
	(segment
		(start 65.96634 -206.465424)
		(end 66.390774 -206.889858)
		(width 0.16002)
		(layer "In11.Cu")
		(net "M_F_CPU1_SA_DQS_DP<0>")
	)
	(segment
		(start 66.863468 -207.839056)
		(end 67.339972 -207.839056)
		(width 0.16002)
		(layer "In11.Cu")
		(net "M_F_CPU1_SA_DQS_DP<0>")
	)
	(segment
		(start 33.894014 -201.20483)
		(end 34.293302 -201.20483)
		(width 0.16002)
		(layer "In11.Cu")
		(net "M_F_CPU1_SA_DQS_DP<0>")
	)
	(segment
		(start 26.749248 -201.20483)
		(end 27.574748 -200.37933)
		(width 0.16002)
		(layer "In11.Cu")
		(net "M_F_CPU1_SA_DQS_DP<0>")
	)
	(segment
		(start 84.266278 -226.95662)
		(end 84.367116 -226.92995)
		(width 0.09525)
		(layer "In11.Cu")
		(net "M_F_CPU1_SA_DQS_DP<0>")
	)
	(segment
		(start 78.692502 -223.749616)
		(end 78.730602 -223.771714)
		(width 0.09525)
		(layer "In11.Cu")
		(net "M_F_CPU1_SA_DQS_DP<0>")
	)
	(segment
		(start 51.020726 -200.010268)
		(end 52.877466 -200.010268)
		(width 0.16002)
		(layer "In11.Cu")
		(net "M_F_CPU1_SA_DQS_DP<0>")
	)
	(segment
		(start 65.148206 -206.8068)
		(end 65.489836 -206.465424)
		(width 0.16002)
		(layer "In11.Cu")
		(net "M_F_CPU1_SA_DQS_DP<0>")
	)
	(segment
		(start 41.09339 -200.860152)
		(end 41.438068 -201.20483)
		(width 0.16002)
		(layer "In11.Cu")
		(net "M_F_CPU1_SA_DQS_DP<0>")
	)
	(segment
		(start 81.881218 -226.994466)
		(end 81.8896 -226.98964)
		(width 0.09525)
		(layer "In11.Cu")
		(net "M_F_CPU1_SA_DQS_DP<0>")
	)
	(segment
		(start 43.10761 -200.37933)
		(end 43.476672 -200.010268)
		(width 0.16002)
		(layer "In11.Cu")
		(net "M_F_CPU1_SA_DQS_DP<0>")
	)
	(segment
		(start 67.422776 -209.30743)
		(end 67.66941 -209.554064)
		(width 0.16002)
		(layer "In11.Cu")
		(net "M_F_CPU1_SA_DQS_DP<0>")
	)
	(segment
		(start 67.66941 -209.554064)
		(end 67.89547 -209.554064)
		(width 0.16002)
		(layer "In11.Cu")
		(net "M_F_CPU1_SA_DQS_DP<0>")
	)
	(segment
		(start 68.713604 -209.212688)
		(end 69.138038 -209.637122)
		(width 0.16002)
		(layer "In11.Cu")
		(net "M_F_CPU1_SA_DQS_DP<0>")
	)
	(segment
		(start 78.230984 -222.944436)
		(end 78.23835 -222.949262)
		(width 0.09525)
		(layer "In11.Cu")
		(net "M_F_CPU1_SA_DQS_DP<0>")
	)
	(segment
		(start 67.764406 -208.26349)
		(end 67.764406 -208.739994)
		(width 0.16002)
		(layer "In11.Cu")
		(net "M_F_CPU1_SA_DQS_DP<0>")
	)
	(segment
		(start 49.38141 -201.20483)
		(end 50.20691 -200.37933)
		(width 0.16002)
		(layer "In11.Cu")
		(net "M_F_CPU1_SA_DQS_DP<0>")
	)
	(segment
		(start 37.789358 -200.010268)
		(end 38.639242 -200.860152)
		(width 0.16002)
		(layer "In11.Cu")
		(net "M_F_CPU1_SA_DQS_DP<0>")
	)
	(segment
		(start 52.877466 -200.010268)
		(end 54.072028 -201.20483)
		(width 0.16002)
		(layer "In11.Cu")
		(net "M_F_CPU1_SA_DQS_DP<0>")
	)
	(segment
		(start 43.476672 -200.010268)
		(end 45.333412 -200.010268)
		(width 0.16002)
		(layer "In11.Cu")
		(net "M_F_CPU1_SA_DQS_DP<0>")
	)
	(segment
		(start 66.049144 -207.933798)
		(end 66.295778 -208.180432)
		(width 0.16002)
		(layer "In11.Cu")
		(net "M_F_CPU1_SA_DQS_DP<0>")
	)
	(segment
		(start 78.661006 -225.351848)
		(end 78.675992 -225.360738)
		(width 0.09525)
		(layer "In11.Cu")
		(net "M_F_CPU1_SA_DQS_DP<0>")
	)
	(segment
		(start 67.422776 -209.08137)
		(end 67.422776 -209.30743)
		(width 0.16002)
		(layer "In11.Cu")
		(net "M_F_CPU1_SA_DQS_DP<0>")
	)
	(segment
		(start 35.118802 -200.37933)
		(end 35.563556 -200.37933)
		(width 0.16002)
		(layer "In11.Cu")
		(net "M_F_CPU1_SA_DQS_DP<0>")
	)
	(segment
		(start 78.65999 -223.73082)
		(end 78.692502 -223.749616)
		(width 0.09525)
		(layer "In11.Cu")
		(net "M_F_CPU1_SA_DQS_DP<0>")
	)
	(segment
		(start 27.574748 -200.37933)
		(end 28.019502 -200.37933)
		(width 0.16002)
		(layer "In11.Cu")
		(net "M_F_CPU1_SA_DQS_DP<0>")
	)
	(segment
		(start 34.293302 -201.20483)
		(end 35.118802 -200.37933)
		(width 0.16002)
		(layer "In11.Cu")
		(net "M_F_CPU1_SA_DQS_DP<0>")
	)
	(segment
		(start 42.662856 -200.37933)
		(end 43.10761 -200.37933)
		(width 0.16002)
		(layer "In11.Cu")
		(net "M_F_CPU1_SA_DQS_DP<0>")
	)
	(segment
		(start 46.183296 -200.860152)
		(end 48.637444 -200.860152)
		(width 0.16002)
		(layer "In11.Cu")
		(net "M_F_CPU1_SA_DQS_DP<0>")
	)
	(segment
		(start 78.675992 -225.360738)
		(end 78.6765 -225.360484)
		(width 0.09525)
		(layer "In11.Cu")
		(net "M_F_CPU1_SA_DQS_DP<0>")
	)
	(segment
		(start 79.162656 -226.179634)
		(end 79.194914 -226.19843)
		(width 0.09525)
		(layer "In11.Cu")
		(net "M_F_CPU1_SA_DQS_DP<0>")
	)
	(segment
		(start 64.64173 -205.065884)
		(end 64.64173 -206.526384)
		(width 0.16002)
		(layer "In11.Cu")
		(net "M_F_CPU1_SA_DQS_DP<0>")
	)
	(segment
		(start 28.388564 -200.010268)
		(end 30.245304 -200.010268)
		(width 0.16002)
		(layer "In11.Cu")
		(net "M_F_CPU1_SA_DQS_DP<0>")
	)
	(segment
		(start 78.23835 -222.949262)
		(end 78.238858 -222.949008)
		(width 0.09525)
		(layer "In11.Cu")
		(net "M_F_CPU1_SA_DQS_DP<0>")
	)
	(segment
		(start 24.006302 -201.00925)
		(end 24.1554 -200.860152)
		(width 0.16002)
		(layer "In11.Cu")
		(net "M_F_CPU1_SA_DQS_DP<0>")
	)
	(segment
		(start 45.333412 -200.010268)
		(end 46.183296 -200.860152)
		(width 0.16002)
		(layer "In11.Cu")
		(net "M_F_CPU1_SA_DQS_DP<0>")
	)
	(segment
		(start 28.019502 -200.37933)
		(end 28.388564 -200.010268)
		(width 0.16002)
		(layer "In11.Cu")
		(net "M_F_CPU1_SA_DQS_DP<0>")
	)
	(segment
		(start 78.199488 -222.925894)
		(end 78.230984 -222.944436)
		(width 0.09525)
		(layer "In11.Cu")
		(net "M_F_CPU1_SA_DQS_DP<0>")
	)
	(segment
		(start 50.20691 -200.37933)
		(end 50.651664 -200.37933)
		(width 0.16002)
		(layer "In11.Cu")
		(net "M_F_CPU1_SA_DQS_DP<0>")
	)
	(segment
		(start 30.245304 -200.010268)
		(end 31.095188 -200.860152)
		(width 0.16002)
		(layer "In11.Cu")
		(net "M_F_CPU1_SA_DQS_DP<0>")
	)
	(segment
		(start 48.637444 -200.860152)
		(end 48.982122 -201.20483)
		(width 0.16002)
		(layer "In11.Cu")
		(net "M_F_CPU1_SA_DQS_DP<0>")
	)
	(segment
		(start 66.049144 -207.707738)
		(end 66.049144 -207.933798)
		(width 0.16002)
		(layer "In11.Cu")
		(net "M_F_CPU1_SA_DQS_DP<0>")
	)
	(segment
		(start 67.89547 -209.554064)
		(end 68.2371 -209.212688)
		(width 0.16002)
		(layer "In11.Cu")
		(net "M_F_CPU1_SA_DQS_DP<0>")
	)
	(segment
		(start 56.92521 -201.20483)
		(end 57.75071 -200.37933)
		(width 0.16002)
		(layer "In11.Cu")
		(net "M_F_CPU1_SA_DQS_DP<0>")
	)
	(segment
		(start 78.238858 -222.949008)
		(end 78.256384 -222.959168)
		(width 0.09525)
		(layer "In11.Cu")
		(net "M_F_CPU1_SA_DQS_DP<0>")
	)
	(segment
		(start 78.502764 -225.03892)
		(end 78.502764 -225.044508)
		(width 0.09525)
		(layer "In11.Cu")
		(net "M_F_CPU1_SA_DQS_DP<0>")
	)
	(segment
		(start 26.34996 -201.20483)
		(end 26.749248 -201.20483)
		(width 0.16002)
		(layer "In11.Cu")
		(net "M_F_CPU1_SA_DQS_DP<0>")
	)
	(segment
		(start 78.614778 -224.77857)
		(end 78.608174 -224.78492)
		(width 0.09525)
		(layer "In11.Cu")
		(net "M_F_CPU1_SA_DQS_DP<0>")
	)
	(segment
		(start 77.820012 -222.041212)
		(end 77.820012 -222.124524)
		(width 0.09525)
		(layer "In11.Cu")
		(net "M_F_CPU1_SA_DQS_DP<0>")
	)
	(segment
		(start 21.70811 -200.735438)
		(end 21.981922 -201.00925)
		(width 0.16002)
		(layer "In11.Cu")
		(net "M_F_CPU1_SA_DQS_DP<0>")
	)
	(segment
		(start 79.128874 -226.160076)
		(end 79.162656 -226.179634)
		(width 0.09525)
		(layer "In11.Cu")
		(net "M_F_CPU1_SA_DQS_DP<0>")
	)
	(arc
		(start 78.503272 -223.424496)
		(mid 78.544729 -223.596536)
		(end 78.65999 -223.73082)
		(width 0.09525)
		(layer "In11.Cu")
		(net "M_F_CPU1_SA_DQS_DP<0>")
	)
	(arc
		(start 79.443326 -226.66452)
		(mid 79.484783 -226.83656)
		(end 79.600044 -226.970844)
		(width 0.09525)
		(layer "In11.Cu")
		(net "M_F_CPU1_SA_DQS_DP<0>")
	)
	(arc
		(start 78.256384 -222.959168)
		(mid 78.437763 -223.1611)
		(end 78.503272 -223.424496)
		(width 0.09525)
		(layer "In11.Cu")
		(net "M_F_CPU1_SA_DQS_DP<0>")
	)
	(arc
		(start 83.4009 -226.994466)
		(mid 83.585932 -227.04038)
		(end 83.769708 -226.98964)
		(width 0.09525)
		(layer "In11.Cu")
		(net "M_F_CPU1_SA_DQS_DP<0>")
	)
	(arc
		(start 79.644748 -226.996498)
		(mid 79.828129 -227.040329)
		(end 80.009746 -226.98964)
		(width 0.09525)
		(layer "In11.Cu")
		(net "M_F_CPU1_SA_DQS_DP<0>")
	)
	(arc
		(start 78.973426 -225.854514)
		(mid 79.014528 -226.02592)
		(end 79.128874 -226.160076)
		(width 0.09525)
		(layer "In11.Cu")
		(net "M_F_CPU1_SA_DQS_DP<0>")
	)
	(arc
		(start 80.949546 -226.98964)
		(mid 81.230978 -226.913885)
		(end 81.51241 -226.98964)
		(width 0.09525)
		(layer "In11.Cu")
		(net "M_F_CPU1_SA_DQS_DP<0>")
	)
	(arc
		(start 83.769708 -226.98964)
		(mid 84.003252 -226.915934)
		(end 84.245958 -226.948746)
		(width 0.09525)
		(layer "In11.Cu")
		(net "M_F_CPU1_SA_DQS_DP<0>")
	)
	(arc
		(start 78.730602 -225.391726)
		(mid 78.909052 -225.593196)
		(end 78.973426 -225.854514)
		(width 0.09525)
		(layer "In11.Cu")
		(net "M_F_CPU1_SA_DQS_DP<0>")
	)
	(arc
		(start 82.460846 -226.994466)
		(mid 82.645878 -227.04038)
		(end 82.829654 -226.98964)
		(width 0.09525)
		(layer "In11.Cu")
		(net "M_F_CPU1_SA_DQS_DP<0>")
	)
	(arc
		(start 78.502764 -225.044508)
		(mid 78.544692 -225.217335)
		(end 78.661006 -225.351848)
		(width 0.09525)
		(layer "In11.Cu")
		(net "M_F_CPU1_SA_DQS_DP<0>")
	)
	(arc
		(start 78.608174 -224.78492)
		(mid 78.53017 -224.901427)
		(end 78.502764 -225.03892)
		(width 0.09525)
		(layer "In11.Cu")
		(net "M_F_CPU1_SA_DQS_DP<0>")
	)
	(arc
		(start 78.033372 -222.636334)
		(mid 78.077841 -222.80326)
		(end 78.199488 -222.925894)
		(width 0.09525)
		(layer "In11.Cu")
		(net "M_F_CPU1_SA_DQS_DP<0>")
	)
	(arc
		(start 78.730602 -223.771714)
		(mid 78.973452 -224.234502)
		(end 78.730602 -224.69729)
		(width 0.09525)
		(layer "In11.Cu")
		(net "M_F_CPU1_SA_DQS_DP<0>")
	)
	(arc
		(start 82.829654 -226.98964)
		(mid 83.111086 -226.913885)
		(end 83.392518 -226.98964)
		(width 0.09525)
		(layer "In11.Cu")
		(net "M_F_CPU1_SA_DQS_DP<0>")
	)
	(arc
		(start 80.57261 -226.98964)
		(mid 80.761078 -227.040317)
		(end 80.949546 -226.98964)
		(width 0.09525)
		(layer "In11.Cu")
		(net "M_F_CPU1_SA_DQS_DP<0>")
	)
	(arc
		(start 79.197708 -226.200208)
		(mid 79.378163 -226.401874)
		(end 79.443326 -226.66452)
		(width 0.09525)
		(layer "In11.Cu")
		(net "M_F_CPU1_SA_DQS_DP<0>")
	)
	(arc
		(start 80.009746 -226.98964)
		(mid 80.291178 -226.913885)
		(end 80.57261 -226.98964)
		(width 0.09525)
		(layer "In11.Cu")
		(net "M_F_CPU1_SA_DQS_DP<0>")
	)
	(arc
		(start 78.691994 -224.719134)
		(mid 78.651454 -224.746342)
		(end 78.614778 -224.77857)
		(width 0.09525)
		(layer "In11.Cu")
		(net "M_F_CPU1_SA_DQS_DP<0>")
	)
	(arc
		(start 84.245958 -226.948746)
		(mid 84.256157 -226.952583)
		(end 84.266278 -226.95662)
		(width 0.09525)
		(layer "In11.Cu")
		(net "M_F_CPU1_SA_DQS_DP<0>")
	)
	(arc
		(start 81.8896 -226.98964)
		(mid 82.171032 -226.913885)
		(end 82.452464 -226.98964)
		(width 0.09525)
		(layer "In11.Cu")
		(net "M_F_CPU1_SA_DQS_DP<0>")
	)
	(arc
		(start 81.51241 -226.98964)
		(mid 81.696185 -227.040412)
		(end 81.881218 -226.994466)
		(width 0.09525)
		(layer "In11.Cu")
		(net "M_F_CPU1_SA_DQS_DP<0>")
	)
	(segment
		(start 86.397846 -247.180354)
		(end 85.930994 -246.914416)
		(width 0.12954)
		(layer "F.Cu")
		(net "M_F_CPU1_SA_DQS_DN<9>")
	)
	(segment
		(start 57.964324 -240.603786)
		(end 59.52236 -240.603786)
		(width 0.16002)
		(layer "In11.Cu")
		(net "M_F_CPU1_SA_DQS_DN<9>")
	)
	(segment
		(start 80.471264 -247.244362)
		(end 80.479646 -247.239536)
		(width 0.09525)
		(layer "In11.Cu")
		(net "M_F_CPU1_SA_DQS_DN<9>")
	)
	(segment
		(start 57.298844 -239.938306)
		(end 57.964324 -240.603786)
		(width 0.16002)
		(layer "In11.Cu")
		(net "M_F_CPU1_SA_DQS_DN<9>")
	)
	(segment
		(start 42.67835 -239.054132)
		(end 43.2308 -239.054132)
		(width 0.16002)
		(layer "In11.Cu")
		(net "M_F_CPU1_SA_DQS_DN<9>")
	)
	(segment
		(start 25.908508 -240.258346)
		(end 26.228548 -239.938306)
		(width 0.16002)
		(layer "In11.Cu")
		(net "M_F_CPU1_SA_DQS_DN<9>")
	)
	(segment
		(start 85.676232 -247.206516)
		(end 85.77707 -247.179846)
		(width 0.09525)
		(layer "In11.Cu")
		(net "M_F_CPU1_SA_DQS_DN<9>")
	)
	(segment
		(start 77.432662 -247.43918)
		(end 77.543914 -247.327928)
		(width 0.09525)
		(layer "In11.Cu")
		(net "M_F_CPU1_SA_DQS_DN<9>")
	)
	(segment
		(start 84.231226 -247.244362)
		(end 84.239608 -247.239536)
		(width 0.09525)
		(layer "In11.Cu")
		(net "M_F_CPU1_SA_DQS_DN<9>")
	)
	(segment
		(start 26.706068 -239.938306)
		(end 27.590242 -239.054132)
		(width 0.16002)
		(layer "In11.Cu")
		(net "M_F_CPU1_SA_DQS_DN<9>")
	)
	(segment
		(start 19.635978 -239.25911)
		(end 19.801586 -239.093502)
		(width 0.16002)
		(layer "In11.Cu")
		(net "M_F_CPU1_SA_DQS_DN<9>")
	)
	(segment
		(start 34.250122 -239.938306)
		(end 35.134296 -239.054132)
		(width 0.16002)
		(layer "In11.Cu")
		(net "M_F_CPU1_SA_DQS_DN<9>")
	)
	(segment
		(start 33.452562 -240.258346)
		(end 33.772602 -239.938306)
		(width 0.16002)
		(layer "In11.Cu")
		(net "M_F_CPU1_SA_DQS_DN<9>")
	)
	(segment
		(start 41.316656 -239.938306)
		(end 41.794176 -239.938306)
		(width 0.16002)
		(layer "In11.Cu")
		(net "M_F_CPU1_SA_DQS_DN<9>")
	)
	(segment
		(start 48.54067 -240.258346)
		(end 48.86071 -239.938306)
		(width 0.16002)
		(layer "In11.Cu")
		(net "M_F_CPU1_SA_DQS_DN<9>")
	)
	(segment
		(start 80.092042 -247.23344)
		(end 80.102456 -247.239536)
		(width 0.09525)
		(layer "In11.Cu")
		(net "M_F_CPU1_SA_DQS_DN<9>")
	)
	(segment
		(start 54.019196 -239.938306)
		(end 57.298844 -239.938306)
		(width 0.16002)
		(layer "In11.Cu")
		(net "M_F_CPU1_SA_DQS_DN<9>")
	)
	(segment
		(start 83.291172 -247.244362)
		(end 83.299554 -247.239536)
		(width 0.09525)
		(layer "In11.Cu")
		(net "M_F_CPU1_SA_DQS_DN<9>")
	)
	(segment
		(start 59.52236 -240.603786)
		(end 65.81902 -246.900446)
		(width 0.16002)
		(layer "In11.Cu")
		(net "M_F_CPU1_SA_DQS_DN<9>")
	)
	(segment
		(start 20.987766 -239.439958)
		(end 23.377906 -239.439958)
		(width 0.16002)
		(layer "In11.Cu")
		(net "M_F_CPU1_SA_DQS_DN<9>")
	)
	(segment
		(start 75.955906 -247.379998)
		(end 75.979528 -247.379998)
		(width 0.09525)
		(layer "In11.Cu")
		(net "M_F_CPU1_SA_DQS_DN<9>")
	)
	(segment
		(start 17.608042 -238.985298)
		(end 17.881854 -239.25911)
		(width 0.16002)
		(layer "In11.Cu")
		(net "M_F_CPU1_SA_DQS_DN<9>")
	)
	(segment
		(start 35.686746 -239.054132)
		(end 36.040822 -239.408208)
		(width 0.16002)
		(layer "In11.Cu")
		(net "M_F_CPU1_SA_DQS_DN<9>")
	)
	(segment
		(start 30.856936 -239.408208)
		(end 31.707074 -240.258346)
		(width 0.16002)
		(layer "In11.Cu")
		(net "M_F_CPU1_SA_DQS_DN<9>")
	)
	(segment
		(start 23.377906 -239.439958)
		(end 24.196294 -240.258346)
		(width 0.16002)
		(layer "In11.Cu")
		(net "M_F_CPU1_SA_DQS_DN<9>")
	)
	(segment
		(start 24.196294 -240.258346)
		(end 25.908508 -240.258346)
		(width 0.16002)
		(layer "In11.Cu")
		(net "M_F_CPU1_SA_DQS_DN<9>")
	)
	(segment
		(start 35.134296 -239.054132)
		(end 35.686746 -239.054132)
		(width 0.16002)
		(layer "In11.Cu")
		(net "M_F_CPU1_SA_DQS_DN<9>")
	)
	(segment
		(start 74.94143 -246.900446)
		(end 75.420982 -247.379998)
		(width 0.16002)
		(layer "In11.Cu")
		(net "M_F_CPU1_SA_DQS_DN<9>")
	)
	(segment
		(start 36.040822 -239.408208)
		(end 38.40099 -239.408208)
		(width 0.16002)
		(layer "In11.Cu")
		(net "M_F_CPU1_SA_DQS_DN<9>")
	)
	(segment
		(start 33.772602 -239.938306)
		(end 34.250122 -239.938306)
		(width 0.16002)
		(layer "In11.Cu")
		(net "M_F_CPU1_SA_DQS_DN<9>")
	)
	(segment
		(start 28.496768 -239.408208)
		(end 30.856936 -239.408208)
		(width 0.16002)
		(layer "In11.Cu")
		(net "M_F_CPU1_SA_DQS_DN<9>")
	)
	(segment
		(start 65.81902 -246.900446)
		(end 74.94143 -246.900446)
		(width 0.16002)
		(layer "In11.Cu")
		(net "M_F_CPU1_SA_DQS_DN<9>")
	)
	(segment
		(start 27.590242 -239.054132)
		(end 28.142692 -239.054132)
		(width 0.16002)
		(layer "In11.Cu")
		(net "M_F_CPU1_SA_DQS_DN<9>")
	)
	(segment
		(start 43.2308 -239.054132)
		(end 43.584876 -239.408208)
		(width 0.16002)
		(layer "In11.Cu")
		(net "M_F_CPU1_SA_DQS_DN<9>")
	)
	(segment
		(start 20.64131 -239.093502)
		(end 20.987766 -239.439958)
		(width 0.16002)
		(layer "In11.Cu")
		(net "M_F_CPU1_SA_DQS_DN<9>")
	)
	(segment
		(start 50.774854 -239.054132)
		(end 51.12893 -239.408208)
		(width 0.16002)
		(layer "In11.Cu")
		(net "M_F_CPU1_SA_DQS_DN<9>")
	)
	(segment
		(start 26.228548 -239.938306)
		(end 26.706068 -239.938306)
		(width 0.16002)
		(layer "In11.Cu")
		(net "M_F_CPU1_SA_DQS_DN<9>")
	)
	(segment
		(start 85.77707 -247.179846)
		(end 85.930994 -246.914416)
		(width 0.09525)
		(layer "In11.Cu")
		(net "M_F_CPU1_SA_DQS_DN<9>")
	)
	(segment
		(start 49.33823 -239.938306)
		(end 50.222404 -239.054132)
		(width 0.16002)
		(layer "In11.Cu")
		(net "M_F_CPU1_SA_DQS_DN<9>")
	)
	(segment
		(start 31.707074 -240.258346)
		(end 33.452562 -240.258346)
		(width 0.16002)
		(layer "In11.Cu")
		(net "M_F_CPU1_SA_DQS_DN<9>")
	)
	(segment
		(start 75.979528 -247.379998)
		(end 76.03871 -247.43918)
		(width 0.09525)
		(layer "In11.Cu")
		(net "M_F_CPU1_SA_DQS_DN<9>")
	)
	(segment
		(start 43.584876 -239.408208)
		(end 45.945044 -239.408208)
		(width 0.16002)
		(layer "In11.Cu")
		(net "M_F_CPU1_SA_DQS_DN<9>")
	)
	(segment
		(start 48.86071 -239.938306)
		(end 49.33823 -239.938306)
		(width 0.16002)
		(layer "In11.Cu")
		(net "M_F_CPU1_SA_DQS_DN<9>")
	)
	(segment
		(start 45.945044 -239.408208)
		(end 46.795182 -240.258346)
		(width 0.16002)
		(layer "In11.Cu")
		(net "M_F_CPU1_SA_DQS_DN<9>")
	)
	(segment
		(start 39.251128 -240.258346)
		(end 40.996616 -240.258346)
		(width 0.16002)
		(layer "In11.Cu")
		(net "M_F_CPU1_SA_DQS_DN<9>")
	)
	(segment
		(start 19.801586 -239.093502)
		(end 20.64131 -239.093502)
		(width 0.16002)
		(layer "In11.Cu")
		(net "M_F_CPU1_SA_DQS_DN<9>")
	)
	(segment
		(start 81.04251 -247.239536)
		(end 81.050892 -247.244362)
		(width 0.09525)
		(layer "In11.Cu")
		(net "M_F_CPU1_SA_DQS_DN<9>")
	)
	(segment
		(start 51.12893 -239.408208)
		(end 53.489098 -239.408208)
		(width 0.16002)
		(layer "In11.Cu")
		(net "M_F_CPU1_SA_DQS_DN<9>")
	)
	(segment
		(start 76.03871 -247.43918)
		(end 77.432662 -247.43918)
		(width 0.09525)
		(layer "In11.Cu")
		(net "M_F_CPU1_SA_DQS_DN<9>")
	)
	(segment
		(start 50.222404 -239.054132)
		(end 50.774854 -239.054132)
		(width 0.16002)
		(layer "In11.Cu")
		(net "M_F_CPU1_SA_DQS_DN<9>")
	)
	(segment
		(start 38.40099 -239.408208)
		(end 39.251128 -240.258346)
		(width 0.16002)
		(layer "In11.Cu")
		(net "M_F_CPU1_SA_DQS_DN<9>")
	)
	(segment
		(start 46.795182 -240.258346)
		(end 48.54067 -240.258346)
		(width 0.16002)
		(layer "In11.Cu")
		(net "M_F_CPU1_SA_DQS_DN<9>")
	)
	(segment
		(start 75.420982 -247.379998)
		(end 75.955906 -247.379998)
		(width 0.16002)
		(layer "In11.Cu")
		(net "M_F_CPU1_SA_DQS_DN<9>")
	)
	(segment
		(start 17.881854 -239.25911)
		(end 19.635978 -239.25911)
		(width 0.16002)
		(layer "In11.Cu")
		(net "M_F_CPU1_SA_DQS_DN<9>")
	)
	(segment
		(start 40.996616 -240.258346)
		(end 41.316656 -239.938306)
		(width 0.16002)
		(layer "In11.Cu")
		(net "M_F_CPU1_SA_DQS_DN<9>")
	)
	(segment
		(start 84.802472 -247.239536)
		(end 84.810854 -247.244362)
		(width 0.09525)
		(layer "In11.Cu")
		(net "M_F_CPU1_SA_DQS_DN<9>")
	)
	(segment
		(start 28.142692 -239.054132)
		(end 28.496768 -239.408208)
		(width 0.16002)
		(layer "In11.Cu")
		(net "M_F_CPU1_SA_DQS_DN<9>")
	)
	(segment
		(start 78.584806 -247.247918)
		(end 78.609698 -247.23344)
		(width 0.09525)
		(layer "In11.Cu")
		(net "M_F_CPU1_SA_DQS_DN<9>")
	)
	(segment
		(start 53.489098 -239.408208)
		(end 54.019196 -239.938306)
		(width 0.16002)
		(layer "In11.Cu")
		(net "M_F_CPU1_SA_DQS_DN<9>")
	)
	(segment
		(start 41.794176 -239.938306)
		(end 42.67835 -239.054132)
		(width 0.16002)
		(layer "In11.Cu")
		(net "M_F_CPU1_SA_DQS_DN<9>")
	)
	(arc
		(start 79.161894 -247.239536)
		(mid 79.350616 -247.29034)
		(end 79.539338 -247.239536)
		(width 0.09525)
		(layer "In11.Cu")
		(net "M_F_CPU1_SA_DQS_DN<9>")
	)
	(arc
		(start 79.539338 -247.239536)
		(mid 79.814881 -247.163687)
		(end 80.092042 -247.23344)
		(width 0.09525)
		(layer "In11.Cu")
		(net "M_F_CPU1_SA_DQS_DN<9>")
	)
	(arc
		(start 80.102456 -247.239536)
		(mid 80.286231 -247.290308)
		(end 80.471264 -247.244362)
		(width 0.09525)
		(layer "In11.Cu")
		(net "M_F_CPU1_SA_DQS_DN<9>")
	)
	(arc
		(start 81.982564 -247.239536)
		(mid 82.171032 -247.290213)
		(end 82.3595 -247.239536)
		(width 0.09525)
		(layer "In11.Cu")
		(net "M_F_CPU1_SA_DQS_DN<9>")
	)
	(arc
		(start 81.050892 -247.244362)
		(mid 81.235924 -247.290276)
		(end 81.4197 -247.239536)
		(width 0.09525)
		(layer "In11.Cu")
		(net "M_F_CPU1_SA_DQS_DN<9>")
	)
	(arc
		(start 80.479646 -247.239536)
		(mid 80.761078 -247.163781)
		(end 81.04251 -247.239536)
		(width 0.09525)
		(layer "In11.Cu")
		(net "M_F_CPU1_SA_DQS_DN<9>")
	)
	(arc
		(start 78.609698 -247.23344)
		(mid 78.886606 -247.163763)
		(end 79.161894 -247.239536)
		(width 0.09525)
		(layer "In11.Cu")
		(net "M_F_CPU1_SA_DQS_DN<9>")
	)
	(arc
		(start 84.810854 -247.244362)
		(mid 84.995886 -247.290276)
		(end 85.179662 -247.239536)
		(width 0.09525)
		(layer "In11.Cu")
		(net "M_F_CPU1_SA_DQS_DN<9>")
	)
	(arc
		(start 85.655912 -247.198642)
		(mid 85.666111 -247.202479)
		(end 85.676232 -247.206516)
		(width 0.09525)
		(layer "In11.Cu")
		(net "M_F_CPU1_SA_DQS_DN<9>")
	)
	(arc
		(start 83.299554 -247.239536)
		(mid 83.580986 -247.163781)
		(end 83.862418 -247.239536)
		(width 0.09525)
		(layer "In11.Cu")
		(net "M_F_CPU1_SA_DQS_DN<9>")
	)
	(arc
		(start 82.922364 -247.239536)
		(mid 83.106139 -247.290308)
		(end 83.291172 -247.244362)
		(width 0.09525)
		(layer "In11.Cu")
		(net "M_F_CPU1_SA_DQS_DN<9>")
	)
	(arc
		(start 84.239608 -247.239536)
		(mid 84.52104 -247.163781)
		(end 84.802472 -247.239536)
		(width 0.09525)
		(layer "In11.Cu")
		(net "M_F_CPU1_SA_DQS_DN<9>")
	)
	(arc
		(start 78.222094 -247.239536)
		(mid 78.402373 -247.290367)
		(end 78.584806 -247.247918)
		(width 0.09525)
		(layer "In11.Cu")
		(net "M_F_CPU1_SA_DQS_DN<9>")
	)
	(arc
		(start 81.4197 -247.239536)
		(mid 81.701132 -247.163781)
		(end 81.982564 -247.239536)
		(width 0.09525)
		(layer "In11.Cu")
		(net "M_F_CPU1_SA_DQS_DN<9>")
	)
	(arc
		(start 83.862418 -247.239536)
		(mid 84.046193 -247.290308)
		(end 84.231226 -247.244362)
		(width 0.09525)
		(layer "In11.Cu")
		(net "M_F_CPU1_SA_DQS_DN<9>")
	)
	(arc
		(start 82.3595 -247.239536)
		(mid 82.640932 -247.163781)
		(end 82.922364 -247.239536)
		(width 0.09525)
		(layer "In11.Cu")
		(net "M_F_CPU1_SA_DQS_DN<9>")
	)
	(arc
		(start 77.543914 -247.327928)
		(mid 77.867964 -247.168394)
		(end 78.222094 -247.239536)
		(width 0.09525)
		(layer "In11.Cu")
		(net "M_F_CPU1_SA_DQS_DN<9>")
	)
	(arc
		(start 85.179662 -247.239536)
		(mid 85.413206 -247.16583)
		(end 85.655912 -247.198642)
		(width 0.09525)
		(layer "In11.Cu")
		(net "M_F_CPU1_SA_DQS_DN<9>")
	)
	(segment
		(start 86.397846 -242.320318)
		(end 85.930994 -242.05438)
		(width 0.12954)
		(layer "F.Cu")
		(net "M_F_CPU1_SA_DQS_DN<8>")
	)
	(segment
		(start 34.250122 -230.588312)
		(end 35.134296 -229.704138)
		(width 0.16002)
		(layer "In11.Cu")
		(net "M_F_CPU1_SA_DQS_DN<8>")
	)
	(segment
		(start 75.805792 -241.293904)
		(end 75.86472 -241.352832)
		(width 0.09525)
		(layer "In11.Cu")
		(net "M_F_CPU1_SA_DQS_DN<8>")
	)
	(segment
		(start 40.996616 -230.908352)
		(end 41.316656 -230.588312)
		(width 0.16002)
		(layer "In11.Cu")
		(net "M_F_CPU1_SA_DQS_DN<8>")
	)
	(segment
		(start 43.584876 -230.058214)
		(end 45.945044 -230.058214)
		(width 0.16002)
		(layer "In11.Cu")
		(net "M_F_CPU1_SA_DQS_DN<8>")
	)
	(segment
		(start 76.736702 -241.973354)
		(end 77.47508 -241.973354)
		(width 0.09525)
		(layer "In11.Cu")
		(net "M_F_CPU1_SA_DQS_DN<8>")
	)
	(segment
		(start 35.686746 -229.704138)
		(end 36.040822 -230.058214)
		(width 0.16002)
		(layer "In11.Cu")
		(net "M_F_CPU1_SA_DQS_DN<8>")
	)
	(segment
		(start 58.873644 -229.704138)
		(end 62.730126 -233.56062)
		(width 0.16002)
		(layer "In11.Cu")
		(net "M_F_CPU1_SA_DQS_DN<8>")
	)
	(segment
		(start 80.471264 -242.384326)
		(end 80.479646 -242.3795)
		(width 0.09525)
		(layer "In11.Cu")
		(net "M_F_CPU1_SA_DQS_DN<8>")
	)
	(segment
		(start 78.584806 -242.387882)
		(end 78.599284 -242.3795)
		(width 0.09525)
		(layer "In11.Cu")
		(net "M_F_CPU1_SA_DQS_DN<8>")
	)
	(segment
		(start 17.881854 -229.909116)
		(end 19.635978 -229.909116)
		(width 0.16002)
		(layer "In11.Cu")
		(net "M_F_CPU1_SA_DQS_DN<8>")
	)
	(segment
		(start 42.67835 -229.704138)
		(end 43.2308 -229.704138)
		(width 0.16002)
		(layer "In11.Cu")
		(net "M_F_CPU1_SA_DQS_DN<8>")
	)
	(segment
		(start 56.88203 -230.588312)
		(end 57.766204 -229.704138)
		(width 0.16002)
		(layer "In11.Cu")
		(net "M_F_CPU1_SA_DQS_DN<8>")
	)
	(segment
		(start 77.80528 -242.303554)
		(end 77.940408 -242.303554)
		(width 0.09525)
		(layer "In11.Cu")
		(net "M_F_CPU1_SA_DQS_DN<8>")
	)
	(segment
		(start 31.707074 -230.908352)
		(end 33.452562 -230.908352)
		(width 0.16002)
		(layer "In11.Cu")
		(net "M_F_CPU1_SA_DQS_DN<8>")
	)
	(segment
		(start 68.791074 -241.293904)
		(end 75.78217 -241.293904)
		(width 0.16002)
		(layer "In11.Cu")
		(net "M_F_CPU1_SA_DQS_DN<8>")
	)
	(segment
		(start 83.291172 -242.384326)
		(end 83.299554 -242.3795)
		(width 0.09525)
		(layer "In11.Cu")
		(net "M_F_CPU1_SA_DQS_DN<8>")
	)
	(segment
		(start 84.231226 -242.384326)
		(end 84.239608 -242.3795)
		(width 0.09525)
		(layer "In11.Cu")
		(net "M_F_CPU1_SA_DQS_DN<8>")
	)
	(segment
		(start 53.489098 -230.058214)
		(end 54.019196 -230.588312)
		(width 0.16002)
		(layer "In11.Cu")
		(net "M_F_CPU1_SA_DQS_DN<8>")
	)
	(segment
		(start 41.794176 -230.588312)
		(end 42.67835 -229.704138)
		(width 0.16002)
		(layer "In11.Cu")
		(net "M_F_CPU1_SA_DQS_DN<8>")
	)
	(segment
		(start 30.856936 -230.058214)
		(end 31.707074 -230.908352)
		(width 0.16002)
		(layer "In11.Cu")
		(net "M_F_CPU1_SA_DQS_DN<8>")
	)
	(segment
		(start 57.766204 -229.704138)
		(end 58.873644 -229.704138)
		(width 0.16002)
		(layer "In11.Cu")
		(net "M_F_CPU1_SA_DQS_DN<8>")
	)
	(segment
		(start 41.316656 -230.588312)
		(end 41.794176 -230.588312)
		(width 0.16002)
		(layer "In11.Cu")
		(net "M_F_CPU1_SA_DQS_DN<8>")
	)
	(segment
		(start 50.774854 -229.704138)
		(end 51.12893 -230.058214)
		(width 0.16002)
		(layer "In11.Cu")
		(net "M_F_CPU1_SA_DQS_DN<8>")
	)
	(segment
		(start 38.40099 -230.058214)
		(end 39.251128 -230.908352)
		(width 0.16002)
		(layer "In11.Cu")
		(net "M_F_CPU1_SA_DQS_DN<8>")
	)
	(segment
		(start 20.987766 -230.089964)
		(end 23.377906 -230.089964)
		(width 0.16002)
		(layer "In11.Cu")
		(net "M_F_CPU1_SA_DQS_DN<8>")
	)
	(segment
		(start 76.11618 -241.352832)
		(end 76.736702 -241.973354)
		(width 0.09525)
		(layer "In11.Cu")
		(net "M_F_CPU1_SA_DQS_DN<8>")
	)
	(segment
		(start 51.12893 -230.058214)
		(end 53.489098 -230.058214)
		(width 0.16002)
		(layer "In11.Cu")
		(net "M_F_CPU1_SA_DQS_DN<8>")
	)
	(segment
		(start 28.496768 -230.058214)
		(end 30.856936 -230.058214)
		(width 0.16002)
		(layer "In11.Cu")
		(net "M_F_CPU1_SA_DQS_DN<8>")
	)
	(segment
		(start 46.795182 -230.908352)
		(end 48.54067 -230.908352)
		(width 0.16002)
		(layer "In11.Cu")
		(net "M_F_CPU1_SA_DQS_DN<8>")
	)
	(segment
		(start 23.377906 -230.089964)
		(end 24.196294 -230.908352)
		(width 0.16002)
		(layer "In11.Cu")
		(net "M_F_CPU1_SA_DQS_DN<8>")
	)
	(segment
		(start 27.590242 -229.704138)
		(end 28.142692 -229.704138)
		(width 0.16002)
		(layer "In11.Cu")
		(net "M_F_CPU1_SA_DQS_DN<8>")
	)
	(segment
		(start 62.730126 -235.232956)
		(end 68.791074 -241.293904)
		(width 0.16002)
		(layer "In11.Cu")
		(net "M_F_CPU1_SA_DQS_DN<8>")
	)
	(segment
		(start 36.040822 -230.058214)
		(end 38.40099 -230.058214)
		(width 0.16002)
		(layer "In11.Cu")
		(net "M_F_CPU1_SA_DQS_DN<8>")
	)
	(segment
		(start 80.092042 -242.373404)
		(end 80.102456 -242.3795)
		(width 0.09525)
		(layer "In11.Cu")
		(net "M_F_CPU1_SA_DQS_DN<8>")
	)
	(segment
		(start 77.47508 -241.973354)
		(end 77.80528 -242.303554)
		(width 0.09525)
		(layer "In11.Cu")
		(net "M_F_CPU1_SA_DQS_DN<8>")
	)
	(segment
		(start 85.676232 -242.34648)
		(end 85.77707 -242.31981)
		(width 0.09525)
		(layer "In11.Cu")
		(net "M_F_CPU1_SA_DQS_DN<8>")
	)
	(segment
		(start 43.2308 -229.704138)
		(end 43.584876 -230.058214)
		(width 0.16002)
		(layer "In11.Cu")
		(net "M_F_CPU1_SA_DQS_DN<8>")
	)
	(segment
		(start 85.77707 -242.31981)
		(end 85.930994 -242.05438)
		(width 0.09525)
		(layer "In11.Cu")
		(net "M_F_CPU1_SA_DQS_DN<8>")
	)
	(segment
		(start 54.019196 -230.588312)
		(end 56.88203 -230.588312)
		(width 0.16002)
		(layer "In11.Cu")
		(net "M_F_CPU1_SA_DQS_DN<8>")
	)
	(segment
		(start 48.54067 -230.908352)
		(end 48.86071 -230.588312)
		(width 0.16002)
		(layer "In11.Cu")
		(net "M_F_CPU1_SA_DQS_DN<8>")
	)
	(segment
		(start 81.04251 -242.3795)
		(end 81.050892 -242.384326)
		(width 0.09525)
		(layer "In11.Cu")
		(net "M_F_CPU1_SA_DQS_DN<8>")
	)
	(segment
		(start 39.251128 -230.908352)
		(end 40.996616 -230.908352)
		(width 0.16002)
		(layer "In11.Cu")
		(net "M_F_CPU1_SA_DQS_DN<8>")
	)
	(segment
		(start 78.599284 -242.3795)
		(end 78.609698 -242.373404)
		(width 0.09525)
		(layer "In11.Cu")
		(net "M_F_CPU1_SA_DQS_DN<8>")
	)
	(segment
		(start 33.452562 -230.908352)
		(end 33.772602 -230.588312)
		(width 0.16002)
		(layer "In11.Cu")
		(net "M_F_CPU1_SA_DQS_DN<8>")
	)
	(segment
		(start 33.772602 -230.588312)
		(end 34.250122 -230.588312)
		(width 0.16002)
		(layer "In11.Cu")
		(net "M_F_CPU1_SA_DQS_DN<8>")
	)
	(segment
		(start 75.78217 -241.293904)
		(end 75.805792 -241.293904)
		(width 0.09525)
		(layer "In11.Cu")
		(net "M_F_CPU1_SA_DQS_DN<8>")
	)
	(segment
		(start 49.33823 -230.588312)
		(end 50.222404 -229.704138)
		(width 0.16002)
		(layer "In11.Cu")
		(net "M_F_CPU1_SA_DQS_DN<8>")
	)
	(segment
		(start 45.945044 -230.058214)
		(end 46.795182 -230.908352)
		(width 0.16002)
		(layer "In11.Cu")
		(net "M_F_CPU1_SA_DQS_DN<8>")
	)
	(segment
		(start 75.86472 -241.352832)
		(end 76.11618 -241.352832)
		(width 0.09525)
		(layer "In11.Cu")
		(net "M_F_CPU1_SA_DQS_DN<8>")
	)
	(segment
		(start 26.228548 -230.588312)
		(end 26.706068 -230.588312)
		(width 0.16002)
		(layer "In11.Cu")
		(net "M_F_CPU1_SA_DQS_DN<8>")
	)
	(segment
		(start 28.142692 -229.704138)
		(end 28.496768 -230.058214)
		(width 0.16002)
		(layer "In11.Cu")
		(net "M_F_CPU1_SA_DQS_DN<8>")
	)
	(segment
		(start 62.730126 -233.56062)
		(end 62.730126 -235.232956)
		(width 0.16002)
		(layer "In11.Cu")
		(net "M_F_CPU1_SA_DQS_DN<8>")
	)
	(segment
		(start 17.608042 -229.635304)
		(end 17.881854 -229.909116)
		(width 0.16002)
		(layer "In11.Cu")
		(net "M_F_CPU1_SA_DQS_DN<8>")
	)
	(segment
		(start 20.64131 -229.743508)
		(end 20.987766 -230.089964)
		(width 0.16002)
		(layer "In11.Cu")
		(net "M_F_CPU1_SA_DQS_DN<8>")
	)
	(segment
		(start 84.802472 -242.3795)
		(end 84.810854 -242.384326)
		(width 0.09525)
		(layer "In11.Cu")
		(net "M_F_CPU1_SA_DQS_DN<8>")
	)
	(segment
		(start 25.908508 -230.908352)
		(end 26.228548 -230.588312)
		(width 0.16002)
		(layer "In11.Cu")
		(net "M_F_CPU1_SA_DQS_DN<8>")
	)
	(segment
		(start 48.86071 -230.588312)
		(end 49.33823 -230.588312)
		(width 0.16002)
		(layer "In11.Cu")
		(net "M_F_CPU1_SA_DQS_DN<8>")
	)
	(segment
		(start 35.134296 -229.704138)
		(end 35.686746 -229.704138)
		(width 0.16002)
		(layer "In11.Cu")
		(net "M_F_CPU1_SA_DQS_DN<8>")
	)
	(segment
		(start 19.801586 -229.743508)
		(end 20.64131 -229.743508)
		(width 0.16002)
		(layer "In11.Cu")
		(net "M_F_CPU1_SA_DQS_DN<8>")
	)
	(segment
		(start 24.196294 -230.908352)
		(end 25.908508 -230.908352)
		(width 0.16002)
		(layer "In11.Cu")
		(net "M_F_CPU1_SA_DQS_DN<8>")
	)
	(segment
		(start 19.635978 -229.909116)
		(end 19.801586 -229.743508)
		(width 0.16002)
		(layer "In11.Cu")
		(net "M_F_CPU1_SA_DQS_DN<8>")
	)
	(segment
		(start 26.706068 -230.588312)
		(end 27.590242 -229.704138)
		(width 0.16002)
		(layer "In11.Cu")
		(net "M_F_CPU1_SA_DQS_DN<8>")
	)
	(segment
		(start 50.222404 -229.704138)
		(end 50.774854 -229.704138)
		(width 0.16002)
		(layer "In11.Cu")
		(net "M_F_CPU1_SA_DQS_DN<8>")
	)
	(arc
		(start 78.609698 -242.373404)
		(mid 78.886606 -242.303727)
		(end 79.161894 -242.3795)
		(width 0.09525)
		(layer "In11.Cu")
		(net "M_F_CPU1_SA_DQS_DN<8>")
	)
	(arc
		(start 81.050892 -242.384326)
		(mid 81.235924 -242.43024)
		(end 81.4197 -242.3795)
		(width 0.09525)
		(layer "In11.Cu")
		(net "M_F_CPU1_SA_DQS_DN<8>")
	)
	(arc
		(start 77.940408 -242.303554)
		(mid 78.086268 -242.322913)
		(end 78.222094 -242.3795)
		(width 0.09525)
		(layer "In11.Cu")
		(net "M_F_CPU1_SA_DQS_DN<8>")
	)
	(arc
		(start 85.179662 -242.3795)
		(mid 85.413206 -242.305794)
		(end 85.655912 -242.338606)
		(width 0.09525)
		(layer "In11.Cu")
		(net "M_F_CPU1_SA_DQS_DN<8>")
	)
	(arc
		(start 81.982564 -242.3795)
		(mid 82.171032 -242.430177)
		(end 82.3595 -242.3795)
		(width 0.09525)
		(layer "In11.Cu")
		(net "M_F_CPU1_SA_DQS_DN<8>")
	)
	(arc
		(start 84.239608 -242.3795)
		(mid 84.52104 -242.303745)
		(end 84.802472 -242.3795)
		(width 0.09525)
		(layer "In11.Cu")
		(net "M_F_CPU1_SA_DQS_DN<8>")
	)
	(arc
		(start 79.161894 -242.3795)
		(mid 79.350616 -242.430304)
		(end 79.539338 -242.3795)
		(width 0.09525)
		(layer "In11.Cu")
		(net "M_F_CPU1_SA_DQS_DN<8>")
	)
	(arc
		(start 82.3595 -242.3795)
		(mid 82.640932 -242.303745)
		(end 82.922364 -242.3795)
		(width 0.09525)
		(layer "In11.Cu")
		(net "M_F_CPU1_SA_DQS_DN<8>")
	)
	(arc
		(start 81.4197 -242.3795)
		(mid 81.701132 -242.303745)
		(end 81.982564 -242.3795)
		(width 0.09525)
		(layer "In11.Cu")
		(net "M_F_CPU1_SA_DQS_DN<8>")
	)
	(arc
		(start 83.862418 -242.3795)
		(mid 84.046193 -242.430272)
		(end 84.231226 -242.384326)
		(width 0.09525)
		(layer "In11.Cu")
		(net "M_F_CPU1_SA_DQS_DN<8>")
	)
	(arc
		(start 80.102456 -242.3795)
		(mid 80.286231 -242.430272)
		(end 80.471264 -242.384326)
		(width 0.09525)
		(layer "In11.Cu")
		(net "M_F_CPU1_SA_DQS_DN<8>")
	)
	(arc
		(start 79.539338 -242.3795)
		(mid 79.814881 -242.303651)
		(end 80.092042 -242.373404)
		(width 0.09525)
		(layer "In11.Cu")
		(net "M_F_CPU1_SA_DQS_DN<8>")
	)
	(arc
		(start 80.479646 -242.3795)
		(mid 80.761078 -242.303745)
		(end 81.04251 -242.3795)
		(width 0.09525)
		(layer "In11.Cu")
		(net "M_F_CPU1_SA_DQS_DN<8>")
	)
	(arc
		(start 84.810854 -242.384326)
		(mid 84.995886 -242.43024)
		(end 85.179662 -242.3795)
		(width 0.09525)
		(layer "In11.Cu")
		(net "M_F_CPU1_SA_DQS_DN<8>")
	)
	(arc
		(start 83.299554 -242.3795)
		(mid 83.580986 -242.303745)
		(end 83.862418 -242.3795)
		(width 0.09525)
		(layer "In11.Cu")
		(net "M_F_CPU1_SA_DQS_DN<8>")
	)
	(arc
		(start 82.922364 -242.3795)
		(mid 83.106139 -242.430272)
		(end 83.291172 -242.384326)
		(width 0.09525)
		(layer "In11.Cu")
		(net "M_F_CPU1_SA_DQS_DN<8>")
	)
	(arc
		(start 78.222094 -242.3795)
		(mid 78.402373 -242.430331)
		(end 78.584806 -242.387882)
		(width 0.09525)
		(layer "In11.Cu")
		(net "M_F_CPU1_SA_DQS_DN<8>")
	)
	(arc
		(start 85.655912 -242.338606)
		(mid 85.666111 -242.342443)
		(end 85.676232 -242.34648)
		(width 0.09525)
		(layer "In11.Cu")
		(net "M_F_CPU1_SA_DQS_DN<8>")
	)
	(segment
		(start 86.397846 -237.460282)
		(end 85.930994 -237.194344)
		(width 0.12954)
		(layer "F.Cu")
		(net "M_F_CPU1_SA_DQS_DN<7>")
	)
	(segment
		(start 81.04251 -237.519464)
		(end 81.050892 -237.52429)
		(width 0.09525)
		(layer "In11.Cu")
		(net "M_F_CPU1_SA_DQS_DN<7>")
	)
	(segment
		(start 77.389736 -236.705394)
		(end 78.144878 -237.460536)
		(width 0.09525)
		(layer "In11.Cu")
		(net "M_F_CPU1_SA_DQS_DN<7>")
	)
	(segment
		(start 31.707074 -221.558358)
		(end 33.452562 -221.558358)
		(width 0.16002)
		(layer "In11.Cu")
		(net "M_F_CPU1_SA_DQS_DN<7>")
	)
	(segment
		(start 85.676232 -237.486444)
		(end 85.77707 -237.459774)
		(width 0.09525)
		(layer "In11.Cu")
		(net "M_F_CPU1_SA_DQS_DN<7>")
	)
	(segment
		(start 77.05344 -236.103414)
		(end 77.389736 -236.43971)
		(width 0.09525)
		(layer "In11.Cu")
		(net "M_F_CPU1_SA_DQS_DN<7>")
	)
	(segment
		(start 84.802472 -237.519464)
		(end 84.810854 -237.52429)
		(width 0.09525)
		(layer "In11.Cu")
		(net "M_F_CPU1_SA_DQS_DN<7>")
	)
	(segment
		(start 76.66609 -236.103414)
		(end 77.05344 -236.103414)
		(width 0.09525)
		(layer "In11.Cu")
		(net "M_F_CPU1_SA_DQS_DN<7>")
	)
	(segment
		(start 75.955906 -235.653834)
		(end 75.979528 -235.653834)
		(width 0.09525)
		(layer "In11.Cu")
		(net "M_F_CPU1_SA_DQS_DN<7>")
	)
	(segment
		(start 28.496768 -220.70822)
		(end 30.856936 -220.70822)
		(width 0.16002)
		(layer "In11.Cu")
		(net "M_F_CPU1_SA_DQS_DN<7>")
	)
	(segment
		(start 26.706068 -221.238318)
		(end 27.590242 -220.354144)
		(width 0.16002)
		(layer "In11.Cu")
		(net "M_F_CPU1_SA_DQS_DN<7>")
	)
	(segment
		(start 50.222404 -220.354144)
		(end 50.774854 -220.354144)
		(width 0.16002)
		(layer "In11.Cu")
		(net "M_F_CPU1_SA_DQS_DN<7>")
	)
	(segment
		(start 46.795182 -221.558358)
		(end 48.54067 -221.558358)
		(width 0.16002)
		(layer "In11.Cu")
		(net "M_F_CPU1_SA_DQS_DN<7>")
	)
	(segment
		(start 85.77707 -237.459774)
		(end 85.930994 -237.194344)
		(width 0.09525)
		(layer "In11.Cu")
		(net "M_F_CPU1_SA_DQS_DN<7>")
	)
	(segment
		(start 25.908508 -221.558358)
		(end 26.228548 -221.238318)
		(width 0.16002)
		(layer "In11.Cu")
		(net "M_F_CPU1_SA_DQS_DN<7>")
	)
	(segment
		(start 39.251128 -221.558358)
		(end 40.996616 -221.558358)
		(width 0.16002)
		(layer "In11.Cu")
		(net "M_F_CPU1_SA_DQS_DN<7>")
	)
	(segment
		(start 73.522332 -235.653834)
		(end 75.955906 -235.653834)
		(width 0.16002)
		(layer "In11.Cu")
		(net "M_F_CPU1_SA_DQS_DN<7>")
	)
	(segment
		(start 26.228548 -221.238318)
		(end 26.706068 -221.238318)
		(width 0.16002)
		(layer "In11.Cu")
		(net "M_F_CPU1_SA_DQS_DN<7>")
	)
	(segment
		(start 33.772602 -221.238318)
		(end 34.250122 -221.238318)
		(width 0.16002)
		(layer "In11.Cu")
		(net "M_F_CPU1_SA_DQS_DN<7>")
	)
	(segment
		(start 76.03871 -235.713016)
		(end 76.275692 -235.713016)
		(width 0.09525)
		(layer "In11.Cu")
		(net "M_F_CPU1_SA_DQS_DN<7>")
	)
	(segment
		(start 41.794176 -221.238318)
		(end 42.67835 -220.354144)
		(width 0.16002)
		(layer "In11.Cu")
		(net "M_F_CPU1_SA_DQS_DN<7>")
	)
	(segment
		(start 17.881854 -220.559122)
		(end 19.635978 -220.559122)
		(width 0.16002)
		(layer "In11.Cu")
		(net "M_F_CPU1_SA_DQS_DN<7>")
	)
	(segment
		(start 62.66307 -224.794572)
		(end 73.522332 -235.653834)
		(width 0.16002)
		(layer "In11.Cu")
		(net "M_F_CPU1_SA_DQS_DN<7>")
	)
	(segment
		(start 50.774854 -220.354144)
		(end 51.12893 -220.70822)
		(width 0.16002)
		(layer "In11.Cu")
		(net "M_F_CPU1_SA_DQS_DN<7>")
	)
	(segment
		(start 17.608042 -220.28531)
		(end 17.881854 -220.559122)
		(width 0.16002)
		(layer "In11.Cu")
		(net "M_F_CPU1_SA_DQS_DN<7>")
	)
	(segment
		(start 19.801586 -220.393514)
		(end 20.64131 -220.393514)
		(width 0.16002)
		(layer "In11.Cu")
		(net "M_F_CPU1_SA_DQS_DN<7>")
	)
	(segment
		(start 36.040822 -220.70822)
		(end 38.40099 -220.70822)
		(width 0.16002)
		(layer "In11.Cu")
		(net "M_F_CPU1_SA_DQS_DN<7>")
	)
	(segment
		(start 78.584806 -237.527846)
		(end 78.58633 -237.52683)
		(width 0.09525)
		(layer "In11.Cu")
		(net "M_F_CPU1_SA_DQS_DN<7>")
	)
	(segment
		(start 48.54067 -221.558358)
		(end 48.86071 -221.238318)
		(width 0.16002)
		(layer "In11.Cu")
		(net "M_F_CPU1_SA_DQS_DN<7>")
	)
	(segment
		(start 24.196294 -221.558358)
		(end 25.908508 -221.558358)
		(width 0.16002)
		(layer "In11.Cu")
		(net "M_F_CPU1_SA_DQS_DN<7>")
	)
	(segment
		(start 58.20029 -221.774766)
		(end 58.44667 -221.528386)
		(width 0.16002)
		(layer "In11.Cu")
		(net "M_F_CPU1_SA_DQS_DN<7>")
	)
	(segment
		(start 19.635978 -220.559122)
		(end 19.801586 -220.393514)
		(width 0.16002)
		(layer "In11.Cu")
		(net "M_F_CPU1_SA_DQS_DN<7>")
	)
	(segment
		(start 35.686746 -220.354144)
		(end 36.040822 -220.70822)
		(width 0.16002)
		(layer "In11.Cu")
		(net "M_F_CPU1_SA_DQS_DN<7>")
	)
	(segment
		(start 48.86071 -221.238318)
		(end 49.33823 -221.238318)
		(width 0.16002)
		(layer "In11.Cu")
		(net "M_F_CPU1_SA_DQS_DN<7>")
	)
	(segment
		(start 57.234582 -221.238318)
		(end 57.77103 -221.774766)
		(width 0.16002)
		(layer "In11.Cu")
		(net "M_F_CPU1_SA_DQS_DN<7>")
	)
	(segment
		(start 43.2308 -220.354144)
		(end 43.584876 -220.70822)
		(width 0.16002)
		(layer "In11.Cu")
		(net "M_F_CPU1_SA_DQS_DN<7>")
	)
	(segment
		(start 75.979528 -235.653834)
		(end 76.03871 -235.713016)
		(width 0.09525)
		(layer "In11.Cu")
		(net "M_F_CPU1_SA_DQS_DN<7>")
	)
	(segment
		(start 23.377906 -220.73997)
		(end 24.196294 -221.558358)
		(width 0.16002)
		(layer "In11.Cu")
		(net "M_F_CPU1_SA_DQS_DN<7>")
	)
	(segment
		(start 62.66307 -224.26422)
		(end 62.66307 -224.794572)
		(width 0.16002)
		(layer "In11.Cu")
		(net "M_F_CPU1_SA_DQS_DN<7>")
	)
	(segment
		(start 40.996616 -221.558358)
		(end 41.316656 -221.238318)
		(width 0.16002)
		(layer "In11.Cu")
		(net "M_F_CPU1_SA_DQS_DN<7>")
	)
	(segment
		(start 83.291172 -237.52429)
		(end 83.299554 -237.519464)
		(width 0.09525)
		(layer "In11.Cu")
		(net "M_F_CPU1_SA_DQS_DN<7>")
	)
	(segment
		(start 54.019196 -221.238318)
		(end 57.234582 -221.238318)
		(width 0.16002)
		(layer "In11.Cu")
		(net "M_F_CPU1_SA_DQS_DN<7>")
	)
	(segment
		(start 43.584876 -220.70822)
		(end 45.945044 -220.70822)
		(width 0.16002)
		(layer "In11.Cu")
		(net "M_F_CPU1_SA_DQS_DN<7>")
	)
	(segment
		(start 38.40099 -220.70822)
		(end 39.251128 -221.558358)
		(width 0.16002)
		(layer "In11.Cu")
		(net "M_F_CPU1_SA_DQS_DN<7>")
	)
	(segment
		(start 35.134296 -220.354144)
		(end 35.686746 -220.354144)
		(width 0.16002)
		(layer "In11.Cu")
		(net "M_F_CPU1_SA_DQS_DN<7>")
	)
	(segment
		(start 28.142692 -220.354144)
		(end 28.496768 -220.70822)
		(width 0.16002)
		(layer "In11.Cu")
		(net "M_F_CPU1_SA_DQS_DN<7>")
	)
	(segment
		(start 30.856936 -220.70822)
		(end 31.707074 -221.558358)
		(width 0.16002)
		(layer "In11.Cu")
		(net "M_F_CPU1_SA_DQS_DN<7>")
	)
	(segment
		(start 45.945044 -220.70822)
		(end 46.795182 -221.558358)
		(width 0.16002)
		(layer "In11.Cu")
		(net "M_F_CPU1_SA_DQS_DN<7>")
	)
	(segment
		(start 41.316656 -221.238318)
		(end 41.794176 -221.238318)
		(width 0.16002)
		(layer "In11.Cu")
		(net "M_F_CPU1_SA_DQS_DN<7>")
	)
	(segment
		(start 59.927236 -221.528386)
		(end 62.66307 -224.26422)
		(width 0.16002)
		(layer "In11.Cu")
		(net "M_F_CPU1_SA_DQS_DN<7>")
	)
	(segment
		(start 78.599284 -237.519464)
		(end 78.609698 -237.513368)
		(width 0.09525)
		(layer "In11.Cu")
		(net "M_F_CPU1_SA_DQS_DN<7>")
	)
	(segment
		(start 27.590242 -220.354144)
		(end 28.142692 -220.354144)
		(width 0.16002)
		(layer "In11.Cu")
		(net "M_F_CPU1_SA_DQS_DN<7>")
	)
	(segment
		(start 57.77103 -221.774766)
		(end 58.20029 -221.774766)
		(width 0.16002)
		(layer "In11.Cu")
		(net "M_F_CPU1_SA_DQS_DN<7>")
	)
	(segment
		(start 80.092042 -237.513368)
		(end 80.102456 -237.519464)
		(width 0.09525)
		(layer "In11.Cu")
		(net "M_F_CPU1_SA_DQS_DN<7>")
	)
	(segment
		(start 78.58633 -237.52683)
		(end 78.599284 -237.519464)
		(width 0.09525)
		(layer "In11.Cu")
		(net "M_F_CPU1_SA_DQS_DN<7>")
	)
	(segment
		(start 77.389736 -236.43971)
		(end 77.389736 -236.705394)
		(width 0.09525)
		(layer "In11.Cu")
		(net "M_F_CPU1_SA_DQS_DN<7>")
	)
	(segment
		(start 84.231226 -237.52429)
		(end 84.239608 -237.519464)
		(width 0.09525)
		(layer "In11.Cu")
		(net "M_F_CPU1_SA_DQS_DN<7>")
	)
	(segment
		(start 34.250122 -221.238318)
		(end 35.134296 -220.354144)
		(width 0.16002)
		(layer "In11.Cu")
		(net "M_F_CPU1_SA_DQS_DN<7>")
	)
	(segment
		(start 42.67835 -220.354144)
		(end 43.2308 -220.354144)
		(width 0.16002)
		(layer "In11.Cu")
		(net "M_F_CPU1_SA_DQS_DN<7>")
	)
	(segment
		(start 49.33823 -221.238318)
		(end 50.222404 -220.354144)
		(width 0.16002)
		(layer "In11.Cu")
		(net "M_F_CPU1_SA_DQS_DN<7>")
	)
	(segment
		(start 51.12893 -220.70822)
		(end 53.489098 -220.70822)
		(width 0.16002)
		(layer "In11.Cu")
		(net "M_F_CPU1_SA_DQS_DN<7>")
	)
	(segment
		(start 20.987766 -220.73997)
		(end 23.377906 -220.73997)
		(width 0.16002)
		(layer "In11.Cu")
		(net "M_F_CPU1_SA_DQS_DN<7>")
	)
	(segment
		(start 76.275692 -235.713016)
		(end 76.66609 -236.103414)
		(width 0.09525)
		(layer "In11.Cu")
		(net "M_F_CPU1_SA_DQS_DN<7>")
	)
	(segment
		(start 58.44667 -221.528386)
		(end 59.927236 -221.528386)
		(width 0.16002)
		(layer "In11.Cu")
		(net "M_F_CPU1_SA_DQS_DN<7>")
	)
	(segment
		(start 78.144878 -237.460536)
		(end 78.145386 -237.460282)
		(width 0.09525)
		(layer "In11.Cu")
		(net "M_F_CPU1_SA_DQS_DN<7>")
	)
	(segment
		(start 53.489098 -220.70822)
		(end 54.019196 -221.238318)
		(width 0.16002)
		(layer "In11.Cu")
		(net "M_F_CPU1_SA_DQS_DN<7>")
	)
	(segment
		(start 20.64131 -220.393514)
		(end 20.987766 -220.73997)
		(width 0.16002)
		(layer "In11.Cu")
		(net "M_F_CPU1_SA_DQS_DN<7>")
	)
	(segment
		(start 33.452562 -221.558358)
		(end 33.772602 -221.238318)
		(width 0.16002)
		(layer "In11.Cu")
		(net "M_F_CPU1_SA_DQS_DN<7>")
	)
	(segment
		(start 80.471264 -237.52429)
		(end 80.479646 -237.519464)
		(width 0.09525)
		(layer "In11.Cu")
		(net "M_F_CPU1_SA_DQS_DN<7>")
	)
	(arc
		(start 81.982564 -237.519464)
		(mid 82.171032 -237.570141)
		(end 82.3595 -237.519464)
		(width 0.09525)
		(layer "In11.Cu")
		(net "M_F_CPU1_SA_DQS_DN<7>")
	)
	(arc
		(start 84.239608 -237.519464)
		(mid 84.52104 -237.443709)
		(end 84.802472 -237.519464)
		(width 0.09525)
		(layer "In11.Cu")
		(net "M_F_CPU1_SA_DQS_DN<7>")
	)
	(arc
		(start 80.102456 -237.519464)
		(mid 80.286231 -237.570236)
		(end 80.471264 -237.52429)
		(width 0.09525)
		(layer "In11.Cu")
		(net "M_F_CPU1_SA_DQS_DN<7>")
	)
	(arc
		(start 79.161894 -237.519464)
		(mid 79.350616 -237.570268)
		(end 79.539338 -237.519464)
		(width 0.09525)
		(layer "In11.Cu")
		(net "M_F_CPU1_SA_DQS_DN<7>")
	)
	(arc
		(start 81.4197 -237.519464)
		(mid 81.701132 -237.443709)
		(end 81.982564 -237.519464)
		(width 0.09525)
		(layer "In11.Cu")
		(net "M_F_CPU1_SA_DQS_DN<7>")
	)
	(arc
		(start 83.862418 -237.519464)
		(mid 84.046193 -237.570236)
		(end 84.231226 -237.52429)
		(width 0.09525)
		(layer "In11.Cu")
		(net "M_F_CPU1_SA_DQS_DN<7>")
	)
	(arc
		(start 79.539338 -237.519464)
		(mid 79.814881 -237.443615)
		(end 80.092042 -237.513368)
		(width 0.09525)
		(layer "In11.Cu")
		(net "M_F_CPU1_SA_DQS_DN<7>")
	)
	(arc
		(start 81.050892 -237.52429)
		(mid 81.235924 -237.570204)
		(end 81.4197 -237.519464)
		(width 0.09525)
		(layer "In11.Cu")
		(net "M_F_CPU1_SA_DQS_DN<7>")
	)
	(arc
		(start 80.479646 -237.519464)
		(mid 80.761078 -237.443709)
		(end 81.04251 -237.519464)
		(width 0.09525)
		(layer "In11.Cu")
		(net "M_F_CPU1_SA_DQS_DN<7>")
	)
	(arc
		(start 82.3595 -237.519464)
		(mid 82.640932 -237.443709)
		(end 82.922364 -237.519464)
		(width 0.09525)
		(layer "In11.Cu")
		(net "M_F_CPU1_SA_DQS_DN<7>")
	)
	(arc
		(start 78.609698 -237.513368)
		(mid 78.886606 -237.443691)
		(end 79.161894 -237.519464)
		(width 0.09525)
		(layer "In11.Cu")
		(net "M_F_CPU1_SA_DQS_DN<7>")
	)
	(arc
		(start 84.810854 -237.52429)
		(mid 84.995886 -237.570204)
		(end 85.179662 -237.519464)
		(width 0.09525)
		(layer "In11.Cu")
		(net "M_F_CPU1_SA_DQS_DN<7>")
	)
	(arc
		(start 78.145386 -237.460282)
		(mid 78.181825 -237.492356)
		(end 78.222094 -237.519464)
		(width 0.09525)
		(layer "In11.Cu")
		(net "M_F_CPU1_SA_DQS_DN<7>")
	)
	(arc
		(start 85.655912 -237.47857)
		(mid 85.666111 -237.482407)
		(end 85.676232 -237.486444)
		(width 0.09525)
		(layer "In11.Cu")
		(net "M_F_CPU1_SA_DQS_DN<7>")
	)
	(arc
		(start 78.222094 -237.519464)
		(mid 78.402373 -237.570295)
		(end 78.584806 -237.527846)
		(width 0.09525)
		(layer "In11.Cu")
		(net "M_F_CPU1_SA_DQS_DN<7>")
	)
	(arc
		(start 82.922364 -237.519464)
		(mid 83.106139 -237.570236)
		(end 83.291172 -237.52429)
		(width 0.09525)
		(layer "In11.Cu")
		(net "M_F_CPU1_SA_DQS_DN<7>")
	)
	(arc
		(start 83.299554 -237.519464)
		(mid 83.580986 -237.443709)
		(end 83.862418 -237.519464)
		(width 0.09525)
		(layer "In11.Cu")
		(net "M_F_CPU1_SA_DQS_DN<7>")
	)
	(arc
		(start 85.179662 -237.519464)
		(mid 85.413206 -237.445758)
		(end 85.655912 -237.47857)
		(width 0.09525)
		(layer "In11.Cu")
		(net "M_F_CPU1_SA_DQS_DN<7>")
	)
	(segment
		(start 86.397846 -232.600246)
		(end 85.930994 -232.334308)
		(width 0.12954)
		(layer "F.Cu")
		(net "M_F_CPU1_SA_DQS_DN<6>")
	)
	(segment
		(start 76.240894 -230.057706)
		(end 76.44384 -230.260652)
		(width 0.09525)
		(layer "In11.Cu")
		(net "M_F_CPU1_SA_DQS_DN<6>")
	)
	(segment
		(start 48.86071 -211.888324)
		(end 49.33823 -211.888324)
		(width 0.16002)
		(layer "In11.Cu")
		(net "M_F_CPU1_SA_DQS_DN<6>")
	)
	(segment
		(start 48.54067 -212.208364)
		(end 48.86071 -211.888324)
		(width 0.16002)
		(layer "In11.Cu")
		(net "M_F_CPU1_SA_DQS_DN<6>")
	)
	(segment
		(start 23.377906 -211.389976)
		(end 24.196294 -212.208364)
		(width 0.16002)
		(layer "In11.Cu")
		(net "M_F_CPU1_SA_DQS_DN<6>")
	)
	(segment
		(start 43.584876 -211.358226)
		(end 45.945044 -211.358226)
		(width 0.16002)
		(layer "In11.Cu")
		(net "M_F_CPU1_SA_DQS_DN<6>")
	)
	(segment
		(start 78.599284 -232.659428)
		(end 78.609698 -232.653332)
		(width 0.09525)
		(layer "In11.Cu")
		(net "M_F_CPU1_SA_DQS_DN<6>")
	)
	(segment
		(start 42.67835 -211.00415)
		(end 43.2308 -211.00415)
		(width 0.16002)
		(layer "In11.Cu")
		(net "M_F_CPU1_SA_DQS_DN<6>")
	)
	(segment
		(start 56.88203 -211.888324)
		(end 57.766204 -211.00415)
		(width 0.16002)
		(layer "In11.Cu")
		(net "M_F_CPU1_SA_DQS_DN<6>")
	)
	(segment
		(start 17.608042 -210.935316)
		(end 17.881854 -211.209128)
		(width 0.16002)
		(layer "In11.Cu")
		(net "M_F_CPU1_SA_DQS_DN<6>")
	)
	(segment
		(start 17.881854 -211.209128)
		(end 19.635978 -211.209128)
		(width 0.16002)
		(layer "In11.Cu")
		(net "M_F_CPU1_SA_DQS_DN<6>")
	)
	(segment
		(start 30.856936 -211.358226)
		(end 31.707074 -212.208364)
		(width 0.16002)
		(layer "In11.Cu")
		(net "M_F_CPU1_SA_DQS_DN<6>")
	)
	(segment
		(start 68.35775 -222.556578)
		(end 75.799696 -229.998524)
		(width 0.16002)
		(layer "In11.Cu")
		(net "M_F_CPU1_SA_DQS_DN<6>")
	)
	(segment
		(start 75.955906 -229.998524)
		(end 75.979528 -229.998524)
		(width 0.09525)
		(layer "In11.Cu")
		(net "M_F_CPU1_SA_DQS_DN<6>")
	)
	(segment
		(start 76.03871 -230.057706)
		(end 76.240894 -230.057706)
		(width 0.09525)
		(layer "In11.Cu")
		(net "M_F_CPU1_SA_DQS_DN<6>")
	)
	(segment
		(start 54.019196 -211.888324)
		(end 56.88203 -211.888324)
		(width 0.16002)
		(layer "In11.Cu")
		(net "M_F_CPU1_SA_DQS_DN<6>")
	)
	(segment
		(start 28.496768 -211.358226)
		(end 30.856936 -211.358226)
		(width 0.16002)
		(layer "In11.Cu")
		(net "M_F_CPU1_SA_DQS_DN<6>")
	)
	(segment
		(start 50.774854 -211.00415)
		(end 51.12893 -211.358226)
		(width 0.16002)
		(layer "In11.Cu")
		(net "M_F_CPU1_SA_DQS_DN<6>")
	)
	(segment
		(start 59.480196 -211.00415)
		(end 63.14313 -214.667084)
		(width 0.16002)
		(layer "In11.Cu")
		(net "M_F_CPU1_SA_DQS_DN<6>")
	)
	(segment
		(start 76.44384 -230.574342)
		(end 76.910692 -231.041194)
		(width 0.09525)
		(layer "In11.Cu")
		(net "M_F_CPU1_SA_DQS_DN<6>")
	)
	(segment
		(start 84.802472 -232.659428)
		(end 84.810854 -232.664254)
		(width 0.09525)
		(layer "In11.Cu")
		(net "M_F_CPU1_SA_DQS_DN<6>")
	)
	(segment
		(start 26.706068 -211.888324)
		(end 27.590242 -211.00415)
		(width 0.16002)
		(layer "In11.Cu")
		(net "M_F_CPU1_SA_DQS_DN<6>")
	)
	(segment
		(start 85.77707 -232.599738)
		(end 85.930994 -232.334308)
		(width 0.09525)
		(layer "In11.Cu")
		(net "M_F_CPU1_SA_DQS_DN<6>")
	)
	(segment
		(start 35.134296 -211.00415)
		(end 35.686746 -211.00415)
		(width 0.16002)
		(layer "In11.Cu")
		(net "M_F_CPU1_SA_DQS_DN<6>")
	)
	(segment
		(start 24.196294 -212.208364)
		(end 25.908508 -212.208364)
		(width 0.16002)
		(layer "In11.Cu")
		(net "M_F_CPU1_SA_DQS_DN<6>")
	)
	(segment
		(start 19.635978 -211.209128)
		(end 19.801586 -211.04352)
		(width 0.16002)
		(layer "In11.Cu")
		(net "M_F_CPU1_SA_DQS_DN<6>")
	)
	(segment
		(start 35.686746 -211.00415)
		(end 36.040822 -211.358226)
		(width 0.16002)
		(layer "In11.Cu")
		(net "M_F_CPU1_SA_DQS_DN<6>")
	)
	(segment
		(start 75.979528 -229.998524)
		(end 76.03871 -230.057706)
		(width 0.09525)
		(layer "In11.Cu")
		(net "M_F_CPU1_SA_DQS_DN<6>")
	)
	(segment
		(start 49.33823 -211.888324)
		(end 50.222404 -211.00415)
		(width 0.16002)
		(layer "In11.Cu")
		(net "M_F_CPU1_SA_DQS_DN<6>")
	)
	(segment
		(start 34.250122 -211.888324)
		(end 35.134296 -211.00415)
		(width 0.16002)
		(layer "In11.Cu")
		(net "M_F_CPU1_SA_DQS_DN<6>")
	)
	(segment
		(start 57.766204 -211.00415)
		(end 59.480196 -211.00415)
		(width 0.16002)
		(layer "In11.Cu")
		(net "M_F_CPU1_SA_DQS_DN<6>")
	)
	(segment
		(start 63.14313 -214.667084)
		(end 63.14313 -216.007188)
		(width 0.16002)
		(layer "In11.Cu")
		(net "M_F_CPU1_SA_DQS_DN<6>")
	)
	(segment
		(start 83.291172 -232.664254)
		(end 83.299554 -232.659428)
		(width 0.09525)
		(layer "In11.Cu")
		(net "M_F_CPU1_SA_DQS_DN<6>")
	)
	(segment
		(start 85.676232 -232.626408)
		(end 85.77707 -232.599738)
		(width 0.09525)
		(layer "In11.Cu")
		(net "M_F_CPU1_SA_DQS_DN<6>")
	)
	(segment
		(start 33.452562 -212.208364)
		(end 33.772602 -211.888324)
		(width 0.16002)
		(layer "In11.Cu")
		(net "M_F_CPU1_SA_DQS_DN<6>")
	)
	(segment
		(start 45.945044 -211.358226)
		(end 46.795182 -212.208364)
		(width 0.16002)
		(layer "In11.Cu")
		(net "M_F_CPU1_SA_DQS_DN<6>")
	)
	(segment
		(start 53.489098 -211.358226)
		(end 54.019196 -211.888324)
		(width 0.16002)
		(layer "In11.Cu")
		(net "M_F_CPU1_SA_DQS_DN<6>")
	)
	(segment
		(start 26.228548 -211.888324)
		(end 26.706068 -211.888324)
		(width 0.16002)
		(layer "In11.Cu")
		(net "M_F_CPU1_SA_DQS_DN<6>")
	)
	(segment
		(start 31.707074 -212.208364)
		(end 33.452562 -212.208364)
		(width 0.16002)
		(layer "In11.Cu")
		(net "M_F_CPU1_SA_DQS_DN<6>")
	)
	(segment
		(start 46.795182 -212.208364)
		(end 48.54067 -212.208364)
		(width 0.16002)
		(layer "In11.Cu")
		(net "M_F_CPU1_SA_DQS_DN<6>")
	)
	(segment
		(start 75.799696 -229.998524)
		(end 75.955906 -229.998524)
		(width 0.16002)
		(layer "In11.Cu")
		(net "M_F_CPU1_SA_DQS_DN<6>")
	)
	(segment
		(start 76.910692 -231.041194)
		(end 77.176884 -231.041194)
		(width 0.09525)
		(layer "In11.Cu")
		(net "M_F_CPU1_SA_DQS_DN<6>")
	)
	(segment
		(start 77.176884 -231.041194)
		(end 77.576426 -231.440736)
		(width 0.09525)
		(layer "In11.Cu")
		(net "M_F_CPU1_SA_DQS_DN<6>")
	)
	(segment
		(start 28.142692 -211.00415)
		(end 28.496768 -211.358226)
		(width 0.16002)
		(layer "In11.Cu")
		(net "M_F_CPU1_SA_DQS_DN<6>")
	)
	(segment
		(start 76.44384 -230.260652)
		(end 76.44384 -230.574342)
		(width 0.09525)
		(layer "In11.Cu")
		(net "M_F_CPU1_SA_DQS_DN<6>")
	)
	(segment
		(start 41.794176 -211.888324)
		(end 42.67835 -211.00415)
		(width 0.16002)
		(layer "In11.Cu")
		(net "M_F_CPU1_SA_DQS_DN<6>")
	)
	(segment
		(start 80.092042 -232.653332)
		(end 80.102456 -232.659428)
		(width 0.09525)
		(layer "In11.Cu")
		(net "M_F_CPU1_SA_DQS_DN<6>")
	)
	(segment
		(start 80.471264 -232.664254)
		(end 80.479646 -232.659428)
		(width 0.09525)
		(layer "In11.Cu")
		(net "M_F_CPU1_SA_DQS_DN<6>")
	)
	(segment
		(start 78.144878 -232.6005)
		(end 78.145386 -232.600246)
		(width 0.09525)
		(layer "In11.Cu")
		(net "M_F_CPU1_SA_DQS_DN<6>")
	)
	(segment
		(start 68.35775 -221.221808)
		(end 68.35775 -222.556578)
		(width 0.16002)
		(layer "In11.Cu")
		(net "M_F_CPU1_SA_DQS_DN<6>")
	)
	(segment
		(start 51.12893 -211.358226)
		(end 53.489098 -211.358226)
		(width 0.16002)
		(layer "In11.Cu")
		(net "M_F_CPU1_SA_DQS_DN<6>")
	)
	(segment
		(start 40.996616 -212.208364)
		(end 41.316656 -211.888324)
		(width 0.16002)
		(layer "In11.Cu")
		(net "M_F_CPU1_SA_DQS_DN<6>")
	)
	(segment
		(start 19.801586 -211.04352)
		(end 20.64131 -211.04352)
		(width 0.16002)
		(layer "In11.Cu")
		(net "M_F_CPU1_SA_DQS_DN<6>")
	)
	(segment
		(start 36.040822 -211.358226)
		(end 38.40099 -211.358226)
		(width 0.16002)
		(layer "In11.Cu")
		(net "M_F_CPU1_SA_DQS_DN<6>")
	)
	(segment
		(start 33.772602 -211.888324)
		(end 34.250122 -211.888324)
		(width 0.16002)
		(layer "In11.Cu")
		(net "M_F_CPU1_SA_DQS_DN<6>")
	)
	(segment
		(start 20.64131 -211.04352)
		(end 20.987766 -211.389976)
		(width 0.16002)
		(layer "In11.Cu")
		(net "M_F_CPU1_SA_DQS_DN<6>")
	)
	(segment
		(start 77.576426 -231.440736)
		(end 77.576426 -232.032048)
		(width 0.09525)
		(layer "In11.Cu")
		(net "M_F_CPU1_SA_DQS_DN<6>")
	)
	(segment
		(start 81.04251 -232.659428)
		(end 81.050892 -232.664254)
		(width 0.09525)
		(layer "In11.Cu")
		(net "M_F_CPU1_SA_DQS_DN<6>")
	)
	(segment
		(start 25.908508 -212.208364)
		(end 26.228548 -211.888324)
		(width 0.16002)
		(layer "In11.Cu")
		(net "M_F_CPU1_SA_DQS_DN<6>")
	)
	(segment
		(start 50.222404 -211.00415)
		(end 50.774854 -211.00415)
		(width 0.16002)
		(layer "In11.Cu")
		(net "M_F_CPU1_SA_DQS_DN<6>")
	)
	(segment
		(start 63.14313 -216.007188)
		(end 68.35775 -221.221808)
		(width 0.16002)
		(layer "In11.Cu")
		(net "M_F_CPU1_SA_DQS_DN<6>")
	)
	(segment
		(start 41.316656 -211.888324)
		(end 41.794176 -211.888324)
		(width 0.16002)
		(layer "In11.Cu")
		(net "M_F_CPU1_SA_DQS_DN<6>")
	)
	(segment
		(start 43.2308 -211.00415)
		(end 43.584876 -211.358226)
		(width 0.16002)
		(layer "In11.Cu")
		(net "M_F_CPU1_SA_DQS_DN<6>")
	)
	(segment
		(start 20.987766 -211.389976)
		(end 23.377906 -211.389976)
		(width 0.16002)
		(layer "In11.Cu")
		(net "M_F_CPU1_SA_DQS_DN<6>")
	)
	(segment
		(start 77.576426 -232.032048)
		(end 78.144878 -232.6005)
		(width 0.09525)
		(layer "In11.Cu")
		(net "M_F_CPU1_SA_DQS_DN<6>")
	)
	(segment
		(start 39.251128 -212.208364)
		(end 40.996616 -212.208364)
		(width 0.16002)
		(layer "In11.Cu")
		(net "M_F_CPU1_SA_DQS_DN<6>")
	)
	(segment
		(start 84.231226 -232.664254)
		(end 84.239608 -232.659428)
		(width 0.09525)
		(layer "In11.Cu")
		(net "M_F_CPU1_SA_DQS_DN<6>")
	)
	(segment
		(start 78.584806 -232.66781)
		(end 78.599284 -232.659428)
		(width 0.09525)
		(layer "In11.Cu")
		(net "M_F_CPU1_SA_DQS_DN<6>")
	)
	(segment
		(start 38.40099 -211.358226)
		(end 39.251128 -212.208364)
		(width 0.16002)
		(layer "In11.Cu")
		(net "M_F_CPU1_SA_DQS_DN<6>")
	)
	(segment
		(start 27.590242 -211.00415)
		(end 28.142692 -211.00415)
		(width 0.16002)
		(layer "In11.Cu")
		(net "M_F_CPU1_SA_DQS_DN<6>")
	)
	(arc
		(start 82.3595 -232.659428)
		(mid 82.640932 -232.583673)
		(end 82.922364 -232.659428)
		(width 0.09525)
		(layer "In11.Cu")
		(net "M_F_CPU1_SA_DQS_DN<6>")
	)
	(arc
		(start 84.810854 -232.664254)
		(mid 84.995886 -232.710168)
		(end 85.179662 -232.659428)
		(width 0.09525)
		(layer "In11.Cu")
		(net "M_F_CPU1_SA_DQS_DN<6>")
	)
	(arc
		(start 81.982564 -232.659428)
		(mid 82.171032 -232.710105)
		(end 82.3595 -232.659428)
		(width 0.09525)
		(layer "In11.Cu")
		(net "M_F_CPU1_SA_DQS_DN<6>")
	)
	(arc
		(start 80.479646 -232.659428)
		(mid 80.761078 -232.583673)
		(end 81.04251 -232.659428)
		(width 0.09525)
		(layer "In11.Cu")
		(net "M_F_CPU1_SA_DQS_DN<6>")
	)
	(arc
		(start 83.862418 -232.659428)
		(mid 84.046193 -232.7102)
		(end 84.231226 -232.664254)
		(width 0.09525)
		(layer "In11.Cu")
		(net "M_F_CPU1_SA_DQS_DN<6>")
	)
	(arc
		(start 82.922364 -232.659428)
		(mid 83.106139 -232.7102)
		(end 83.291172 -232.664254)
		(width 0.09525)
		(layer "In11.Cu")
		(net "M_F_CPU1_SA_DQS_DN<6>")
	)
	(arc
		(start 78.145386 -232.600246)
		(mid 78.181825 -232.63232)
		(end 78.222094 -232.659428)
		(width 0.09525)
		(layer "In11.Cu")
		(net "M_F_CPU1_SA_DQS_DN<6>")
	)
	(arc
		(start 85.179662 -232.659428)
		(mid 85.413206 -232.585722)
		(end 85.655912 -232.618534)
		(width 0.09525)
		(layer "In11.Cu")
		(net "M_F_CPU1_SA_DQS_DN<6>")
	)
	(arc
		(start 84.239608 -232.659428)
		(mid 84.52104 -232.583673)
		(end 84.802472 -232.659428)
		(width 0.09525)
		(layer "In11.Cu")
		(net "M_F_CPU1_SA_DQS_DN<6>")
	)
	(arc
		(start 81.050892 -232.664254)
		(mid 81.235924 -232.710168)
		(end 81.4197 -232.659428)
		(width 0.09525)
		(layer "In11.Cu")
		(net "M_F_CPU1_SA_DQS_DN<6>")
	)
	(arc
		(start 79.161894 -232.659428)
		(mid 79.350616 -232.710232)
		(end 79.539338 -232.659428)
		(width 0.09525)
		(layer "In11.Cu")
		(net "M_F_CPU1_SA_DQS_DN<6>")
	)
	(arc
		(start 81.4197 -232.659428)
		(mid 81.701132 -232.583673)
		(end 81.982564 -232.659428)
		(width 0.09525)
		(layer "In11.Cu")
		(net "M_F_CPU1_SA_DQS_DN<6>")
	)
	(arc
		(start 78.609698 -232.653332)
		(mid 78.886606 -232.583655)
		(end 79.161894 -232.659428)
		(width 0.09525)
		(layer "In11.Cu")
		(net "M_F_CPU1_SA_DQS_DN<6>")
	)
	(arc
		(start 80.102456 -232.659428)
		(mid 80.286231 -232.7102)
		(end 80.471264 -232.664254)
		(width 0.09525)
		(layer "In11.Cu")
		(net "M_F_CPU1_SA_DQS_DN<6>")
	)
	(arc
		(start 79.539338 -232.659428)
		(mid 79.814881 -232.583579)
		(end 80.092042 -232.653332)
		(width 0.09525)
		(layer "In11.Cu")
		(net "M_F_CPU1_SA_DQS_DN<6>")
	)
	(arc
		(start 85.655912 -232.618534)
		(mid 85.666111 -232.622371)
		(end 85.676232 -232.626408)
		(width 0.09525)
		(layer "In11.Cu")
		(net "M_F_CPU1_SA_DQS_DN<6>")
	)
	(arc
		(start 78.222094 -232.659428)
		(mid 78.402373 -232.710259)
		(end 78.584806 -232.66781)
		(width 0.09525)
		(layer "In11.Cu")
		(net "M_F_CPU1_SA_DQS_DN<6>")
	)
	(arc
		(start 83.299554 -232.659428)
		(mid 83.580986 -232.583673)
		(end 83.862418 -232.659428)
		(width 0.09525)
		(layer "In11.Cu")
		(net "M_F_CPU1_SA_DQS_DN<6>")
	)
	(segment
		(start 86.397846 -227.740464)
		(end 85.930994 -227.474526)
		(width 0.12954)
		(layer "F.Cu")
		(net "M_F_CPU1_SA_DQS_DN<5>")
	)
	(segment
		(start 43.2308 -201.654156)
		(end 43.584876 -202.008232)
		(width 0.16002)
		(layer "In11.Cu")
		(net "M_F_CPU1_SA_DQS_DN<5>")
	)
	(segment
		(start 39.251128 -202.85837)
		(end 40.996616 -202.85837)
		(width 0.16002)
		(layer "In11.Cu")
		(net "M_F_CPU1_SA_DQS_DN<5>")
	)
	(segment
		(start 20.987766 -202.039982)
		(end 23.377906 -202.039982)
		(width 0.16002)
		(layer "In11.Cu")
		(net "M_F_CPU1_SA_DQS_DN<5>")
	)
	(segment
		(start 78.032864 -224.23501)
		(end 78.032864 -225.85553)
		(width 0.09525)
		(layer "In11.Cu")
		(net "M_F_CPU1_SA_DQS_DN<5>")
	)
	(segment
		(start 33.772602 -202.53833)
		(end 34.250122 -202.53833)
		(width 0.16002)
		(layer "In11.Cu")
		(net "M_F_CPU1_SA_DQS_DN<5>")
	)
	(segment
		(start 77.183996 -222.760794)
		(end 77.562964 -223.139762)
		(width 0.09525)
		(layer "In11.Cu")
		(net "M_F_CPU1_SA_DQS_DN<5>")
	)
	(segment
		(start 23.377906 -202.039982)
		(end 24.196294 -202.85837)
		(width 0.16002)
		(layer "In11.Cu")
		(net "M_F_CPU1_SA_DQS_DN<5>")
	)
	(segment
		(start 41.316656 -202.53833)
		(end 41.794176 -202.53833)
		(width 0.16002)
		(layer "In11.Cu")
		(net "M_F_CPU1_SA_DQS_DN<5>")
	)
	(segment
		(start 56.88203 -202.53833)
		(end 57.766204 -201.654156)
		(width 0.16002)
		(layer "In11.Cu")
		(net "M_F_CPU1_SA_DQS_DN<5>")
	)
	(segment
		(start 38.40099 -202.008232)
		(end 39.251128 -202.85837)
		(width 0.16002)
		(layer "In11.Cu")
		(net "M_F_CPU1_SA_DQS_DN<5>")
	)
	(segment
		(start 17.608042 -201.585322)
		(end 17.881854 -201.859134)
		(width 0.16002)
		(layer "In11.Cu")
		(net "M_F_CPU1_SA_DQS_DN<5>")
	)
	(segment
		(start 78.033372 -224.234502)
		(end 78.032864 -224.23501)
		(width 0.09525)
		(layer "In11.Cu")
		(net "M_F_CPU1_SA_DQS_DN<5>")
	)
	(segment
		(start 35.134296 -201.654156)
		(end 35.686746 -201.654156)
		(width 0.16002)
		(layer "In11.Cu")
		(net "M_F_CPU1_SA_DQS_DN<5>")
	)
	(segment
		(start 85.676232 -227.766626)
		(end 85.77707 -227.739956)
		(width 0.09525)
		(layer "In11.Cu")
		(net "M_F_CPU1_SA_DQS_DN<5>")
	)
	(segment
		(start 78.70063 -226.986338)
		(end 78.791816 -227.01758)
		(width 0.09525)
		(layer "In11.Cu")
		(net "M_F_CPU1_SA_DQS_DN<5>")
	)
	(segment
		(start 84.802472 -227.799646)
		(end 84.810854 -227.804472)
		(width 0.09525)
		(layer "In11.Cu")
		(net "M_F_CPU1_SA_DQS_DN<5>")
	)
	(segment
		(start 63.68669 -205.378304)
		(end 63.68669 -206.861664)
		(width 0.16002)
		(layer "In11.Cu")
		(net "M_F_CPU1_SA_DQS_DN<5>")
	)
	(segment
		(start 50.222404 -201.654156)
		(end 50.774854 -201.654156)
		(width 0.16002)
		(layer "In11.Cu")
		(net "M_F_CPU1_SA_DQS_DN<5>")
	)
	(segment
		(start 53.489098 -202.008232)
		(end 54.019196 -202.53833)
		(width 0.16002)
		(layer "In11.Cu")
		(net "M_F_CPU1_SA_DQS_DN<5>")
	)
	(segment
		(start 77.183996 -222.677482)
		(end 77.183996 -222.760794)
		(width 0.09525)
		(layer "In11.Cu")
		(net "M_F_CPU1_SA_DQS_DN<5>")
	)
	(segment
		(start 54.019196 -202.53833)
		(end 56.88203 -202.53833)
		(width 0.16002)
		(layer "In11.Cu")
		(net "M_F_CPU1_SA_DQS_DN<5>")
	)
	(segment
		(start 28.142692 -201.654156)
		(end 28.496768 -202.008232)
		(width 0.16002)
		(layer "In11.Cu")
		(net "M_F_CPU1_SA_DQS_DN<5>")
	)
	(segment
		(start 78.142084 -226.106736)
		(end 78.270354 -226.22637)
		(width 0.09525)
		(layer "In11.Cu")
		(net "M_F_CPU1_SA_DQS_DN<5>")
	)
	(segment
		(start 25.908508 -202.85837)
		(end 26.228548 -202.53833)
		(width 0.16002)
		(layer "In11.Cu")
		(net "M_F_CPU1_SA_DQS_DN<5>")
	)
	(segment
		(start 20.64131 -201.693526)
		(end 20.987766 -202.039982)
		(width 0.16002)
		(layer "In11.Cu")
		(net "M_F_CPU1_SA_DQS_DN<5>")
	)
	(segment
		(start 24.196294 -202.85837)
		(end 25.908508 -202.85837)
		(width 0.16002)
		(layer "In11.Cu")
		(net "M_F_CPU1_SA_DQS_DN<5>")
	)
	(segment
		(start 42.67835 -201.654156)
		(end 43.2308 -201.654156)
		(width 0.16002)
		(layer "In11.Cu")
		(net "M_F_CPU1_SA_DQS_DN<5>")
	)
	(segment
		(start 80.471264 -227.804472)
		(end 80.479646 -227.799646)
		(width 0.09525)
		(layer "In11.Cu")
		(net "M_F_CPU1_SA_DQS_DN<5>")
	)
	(segment
		(start 57.766204 -201.654156)
		(end 59.962542 -201.654156)
		(width 0.16002)
		(layer "In11.Cu")
		(net "M_F_CPU1_SA_DQS_DN<5>")
	)
	(segment
		(start 81.04251 -227.799646)
		(end 81.050892 -227.804472)
		(width 0.09525)
		(layer "In11.Cu")
		(net "M_F_CPU1_SA_DQS_DN<5>")
	)
	(segment
		(start 50.774854 -201.654156)
		(end 51.12893 -202.008232)
		(width 0.16002)
		(layer "In11.Cu")
		(net "M_F_CPU1_SA_DQS_DN<5>")
	)
	(segment
		(start 51.12893 -202.008232)
		(end 53.489098 -202.008232)
		(width 0.16002)
		(layer "In11.Cu")
		(net "M_F_CPU1_SA_DQS_DN<5>")
	)
	(segment
		(start 43.584876 -202.008232)
		(end 45.945044 -202.008232)
		(width 0.16002)
		(layer "In11.Cu")
		(net "M_F_CPU1_SA_DQS_DN<5>")
	)
	(segment
		(start 35.686746 -201.654156)
		(end 36.040822 -202.008232)
		(width 0.16002)
		(layer "In11.Cu")
		(net "M_F_CPU1_SA_DQS_DN<5>")
	)
	(segment
		(start 77.167232 -222.660718)
		(end 77.183996 -222.677482)
		(width 0.09525)
		(layer "In11.Cu")
		(net "M_F_CPU1_SA_DQS_DN<5>")
	)
	(segment
		(start 45.945044 -202.008232)
		(end 46.795182 -202.85837)
		(width 0.16002)
		(layer "In11.Cu")
		(net "M_F_CPU1_SA_DQS_DN<5>")
	)
	(segment
		(start 19.635978 -201.859134)
		(end 19.801586 -201.693526)
		(width 0.16002)
		(layer "In11.Cu")
		(net "M_F_CPU1_SA_DQS_DN<5>")
	)
	(segment
		(start 40.996616 -202.85837)
		(end 41.316656 -202.53833)
		(width 0.16002)
		(layer "In11.Cu")
		(net "M_F_CPU1_SA_DQS_DN<5>")
	)
	(segment
		(start 83.291172 -227.804472)
		(end 83.299554 -227.799646)
		(width 0.09525)
		(layer "In11.Cu")
		(net "M_F_CPU1_SA_DQS_DN<5>")
	)
	(segment
		(start 79.159354 -227.446332)
		(end 79.290672 -227.577904)
		(width 0.09525)
		(layer "In11.Cu")
		(net "M_F_CPU1_SA_DQS_DN<5>")
	)
	(segment
		(start 27.590242 -201.654156)
		(end 28.142692 -201.654156)
		(width 0.16002)
		(layer "In11.Cu")
		(net "M_F_CPU1_SA_DQS_DN<5>")
	)
	(segment
		(start 74.17689 -219.670376)
		(end 77.167232 -222.660718)
		(width 0.16002)
		(layer "In11.Cu")
		(net "M_F_CPU1_SA_DQS_DN<5>")
	)
	(segment
		(start 36.040822 -202.008232)
		(end 38.40099 -202.008232)
		(width 0.16002)
		(layer "In11.Cu")
		(net "M_F_CPU1_SA_DQS_DN<5>")
	)
	(segment
		(start 26.706068 -202.53833)
		(end 27.590242 -201.654156)
		(width 0.16002)
		(layer "In11.Cu")
		(net "M_F_CPU1_SA_DQS_DN<5>")
	)
	(segment
		(start 77.721206 -223.731836)
		(end 77.790548 -223.771714)
		(width 0.09525)
		(layer "In11.Cu")
		(net "M_F_CPU1_SA_DQS_DN<5>")
	)
	(segment
		(start 63.68669 -206.861664)
		(end 74.17689 -217.351864)
		(width 0.16002)
		(layer "In11.Cu")
		(net "M_F_CPU1_SA_DQS_DN<5>")
	)
	(segment
		(start 30.856936 -202.008232)
		(end 31.707074 -202.85837)
		(width 0.16002)
		(layer "In11.Cu")
		(net "M_F_CPU1_SA_DQS_DN<5>")
	)
	(segment
		(start 79.64297 -227.723954)
		(end 79.821024 -227.723954)
		(width 0.09525)
		(layer "In11.Cu")
		(net "M_F_CPU1_SA_DQS_DN<5>")
	)
	(segment
		(start 26.228548 -202.53833)
		(end 26.706068 -202.53833)
		(width 0.16002)
		(layer "In11.Cu")
		(net "M_F_CPU1_SA_DQS_DN<5>")
	)
	(segment
		(start 28.496768 -202.008232)
		(end 30.856936 -202.008232)
		(width 0.16002)
		(layer "In11.Cu")
		(net "M_F_CPU1_SA_DQS_DN<5>")
	)
	(segment
		(start 84.231226 -227.804472)
		(end 84.239608 -227.799646)
		(width 0.09525)
		(layer "In11.Cu")
		(net "M_F_CPU1_SA_DQS_DN<5>")
	)
	(segment
		(start 41.794176 -202.53833)
		(end 42.67835 -201.654156)
		(width 0.16002)
		(layer "In11.Cu")
		(net "M_F_CPU1_SA_DQS_DN<5>")
	)
	(segment
		(start 48.86071 -202.53833)
		(end 49.33823 -202.53833)
		(width 0.16002)
		(layer "In11.Cu")
		(net "M_F_CPU1_SA_DQS_DN<5>")
	)
	(segment
		(start 59.962542 -201.654156)
		(end 63.68669 -205.378304)
		(width 0.16002)
		(layer "In11.Cu")
		(net "M_F_CPU1_SA_DQS_DN<5>")
	)
	(segment
		(start 46.795182 -202.85837)
		(end 48.54067 -202.85837)
		(width 0.16002)
		(layer "In11.Cu")
		(net "M_F_CPU1_SA_DQS_DN<5>")
	)
	(segment
		(start 34.250122 -202.53833)
		(end 35.134296 -201.654156)
		(width 0.16002)
		(layer "In11.Cu")
		(net "M_F_CPU1_SA_DQS_DN<5>")
	)
	(segment
		(start 17.881854 -201.859134)
		(end 19.635978 -201.859134)
		(width 0.16002)
		(layer "In11.Cu")
		(net "M_F_CPU1_SA_DQS_DN<5>")
	)
	(segment
		(start 85.77707 -227.739956)
		(end 85.930994 -227.474526)
		(width 0.09525)
		(layer "In11.Cu")
		(net "M_F_CPU1_SA_DQS_DN<5>")
	)
	(segment
		(start 33.452562 -202.85837)
		(end 33.772602 -202.53833)
		(width 0.16002)
		(layer "In11.Cu")
		(net "M_F_CPU1_SA_DQS_DN<5>")
	)
	(segment
		(start 77.562964 -223.139762)
		(end 77.562964 -223.424496)
		(width 0.09525)
		(layer "In11.Cu")
		(net "M_F_CPU1_SA_DQS_DN<5>")
	)
	(segment
		(start 31.707074 -202.85837)
		(end 33.452562 -202.85837)
		(width 0.16002)
		(layer "In11.Cu")
		(net "M_F_CPU1_SA_DQS_DN<5>")
	)
	(segment
		(start 49.33823 -202.53833)
		(end 50.222404 -201.654156)
		(width 0.16002)
		(layer "In11.Cu")
		(net "M_F_CPU1_SA_DQS_DN<5>")
	)
	(segment
		(start 74.17689 -217.351864)
		(end 74.17689 -219.670376)
		(width 0.16002)
		(layer "In11.Cu")
		(net "M_F_CPU1_SA_DQS_DN<5>")
	)
	(segment
		(start 19.801586 -201.693526)
		(end 20.64131 -201.693526)
		(width 0.16002)
		(layer "In11.Cu")
		(net "M_F_CPU1_SA_DQS_DN<5>")
	)
	(segment
		(start 48.54067 -202.85837)
		(end 48.86071 -202.53833)
		(width 0.16002)
		(layer "In11.Cu")
		(net "M_F_CPU1_SA_DQS_DN<5>")
	)
	(arc
		(start 83.862418 -227.799646)
		(mid 84.046193 -227.850418)
		(end 84.231226 -227.804472)
		(width 0.09525)
		(layer "In11.Cu")
		(net "M_F_CPU1_SA_DQS_DN<5>")
	)
	(arc
		(start 79.290672 -227.577904)
		(mid 79.452293 -227.685988)
		(end 79.64297 -227.723954)
		(width 0.09525)
		(layer "In11.Cu")
		(net "M_F_CPU1_SA_DQS_DN<5>")
	)
	(arc
		(start 79.821024 -227.723954)
		(mid 79.966732 -227.743222)
		(end 80.102456 -227.799646)
		(width 0.09525)
		(layer "In11.Cu")
		(net "M_F_CPU1_SA_DQS_DN<5>")
	)
	(arc
		(start 81.050892 -227.804472)
		(mid 81.235924 -227.850386)
		(end 81.4197 -227.799646)
		(width 0.09525)
		(layer "In11.Cu")
		(net "M_F_CPU1_SA_DQS_DN<5>")
	)
	(arc
		(start 79.02321 -227.195126)
		(mid 79.052699 -227.242622)
		(end 79.076042 -227.293424)
		(width 0.09525)
		(layer "In11.Cu")
		(net "M_F_CPU1_SA_DQS_DN<5>")
	)
	(arc
		(start 77.790548 -223.771714)
		(mid 77.968998 -223.973184)
		(end 78.033372 -224.234502)
		(width 0.09525)
		(layer "In11.Cu")
		(net "M_F_CPU1_SA_DQS_DN<5>")
	)
	(arc
		(start 77.562964 -223.424496)
		(mid 77.604892 -223.597323)
		(end 77.721206 -223.731836)
		(width 0.09525)
		(layer "In11.Cu")
		(net "M_F_CPU1_SA_DQS_DN<5>")
	)
	(arc
		(start 78.619096 -226.937316)
		(mid 78.65719 -226.966274)
		(end 78.70063 -226.986338)
		(width 0.09525)
		(layer "In11.Cu")
		(net "M_F_CPU1_SA_DQS_DN<5>")
	)
	(arc
		(start 79.076042 -227.293424)
		(mid 79.090843 -227.330456)
		(end 79.106014 -227.367338)
		(width 0.09525)
		(layer "In11.Cu")
		(net "M_F_CPU1_SA_DQS_DN<5>")
	)
	(arc
		(start 85.179662 -227.799646)
		(mid 85.413206 -227.72594)
		(end 85.655912 -227.758752)
		(width 0.09525)
		(layer "In11.Cu")
		(net "M_F_CPU1_SA_DQS_DN<5>")
	)
	(arc
		(start 82.922364 -227.799646)
		(mid 83.106139 -227.850418)
		(end 83.291172 -227.804472)
		(width 0.09525)
		(layer "In11.Cu")
		(net "M_F_CPU1_SA_DQS_DN<5>")
	)
	(arc
		(start 79.106014 -227.367338)
		(mid 79.128818 -227.409449)
		(end 79.159354 -227.446332)
		(width 0.09525)
		(layer "In11.Cu")
		(net "M_F_CPU1_SA_DQS_DN<5>")
	)
	(arc
		(start 81.4197 -227.799646)
		(mid 81.701132 -227.723891)
		(end 81.982564 -227.799646)
		(width 0.09525)
		(layer "In11.Cu")
		(net "M_F_CPU1_SA_DQS_DN<5>")
	)
	(arc
		(start 78.795626 -227.01885)
		(mid 78.798925 -227.020001)
		(end 78.80223 -227.021136)
		(width 0.09525)
		(layer "In11.Cu")
		(net "M_F_CPU1_SA_DQS_DN<5>")
	)
	(arc
		(start 78.270354 -226.22637)
		(mid 78.430522 -226.442117)
		(end 78.504034 -226.700588)
		(width 0.09525)
		(layer "In11.Cu")
		(net "M_F_CPU1_SA_DQS_DN<5>")
	)
	(arc
		(start 84.810854 -227.804472)
		(mid 84.995886 -227.850386)
		(end 85.179662 -227.799646)
		(width 0.09525)
		(layer "In11.Cu")
		(net "M_F_CPU1_SA_DQS_DN<5>")
	)
	(arc
		(start 80.102456 -227.799646)
		(mid 80.286231 -227.850418)
		(end 80.471264 -227.804472)
		(width 0.09525)
		(layer "In11.Cu")
		(net "M_F_CPU1_SA_DQS_DN<5>")
	)
	(arc
		(start 78.97622 -227.135436)
		(mid 79.000355 -227.164777)
		(end 79.02321 -227.195126)
		(width 0.09525)
		(layer "In11.Cu")
		(net "M_F_CPU1_SA_DQS_DN<5>")
	)
	(arc
		(start 85.655912 -227.758752)
		(mid 85.666111 -227.762589)
		(end 85.676232 -227.766626)
		(width 0.09525)
		(layer "In11.Cu")
		(net "M_F_CPU1_SA_DQS_DN<5>")
	)
	(arc
		(start 81.982564 -227.799646)
		(mid 82.171032 -227.850323)
		(end 82.3595 -227.799646)
		(width 0.09525)
		(layer "In11.Cu")
		(net "M_F_CPU1_SA_DQS_DN<5>")
	)
	(arc
		(start 83.299554 -227.799646)
		(mid 83.580986 -227.723891)
		(end 83.862418 -227.799646)
		(width 0.09525)
		(layer "In11.Cu")
		(net "M_F_CPU1_SA_DQS_DN<5>")
	)
	(arc
		(start 80.479646 -227.799646)
		(mid 80.761078 -227.723891)
		(end 81.04251 -227.799646)
		(width 0.09525)
		(layer "In11.Cu")
		(net "M_F_CPU1_SA_DQS_DN<5>")
	)
	(arc
		(start 78.791816 -227.01758)
		(mid 78.79372 -227.018218)
		(end 78.795626 -227.01885)
		(width 0.09525)
		(layer "In11.Cu")
		(net "M_F_CPU1_SA_DQS_DN<5>")
	)
	(arc
		(start 84.239608 -227.799646)
		(mid 84.52104 -227.723891)
		(end 84.802472 -227.799646)
		(width 0.09525)
		(layer "In11.Cu")
		(net "M_F_CPU1_SA_DQS_DN<5>")
	)
	(arc
		(start 78.80223 -227.021136)
		(mid 78.897214 -227.066131)
		(end 78.97622 -227.135436)
		(width 0.09525)
		(layer "In11.Cu")
		(net "M_F_CPU1_SA_DQS_DN<5>")
	)
	(arc
		(start 78.504034 -226.700588)
		(mid 78.54029 -226.829296)
		(end 78.619096 -226.937316)
		(width 0.09525)
		(layer "In11.Cu")
		(net "M_F_CPU1_SA_DQS_DN<5>")
	)
	(arc
		(start 82.3595 -227.799646)
		(mid 82.640932 -227.723891)
		(end 82.922364 -227.799646)
		(width 0.09525)
		(layer "In11.Cu")
		(net "M_F_CPU1_SA_DQS_DN<5>")
	)
	(arc
		(start 78.032864 -225.85553)
		(mid 78.061356 -225.992486)
		(end 78.142084 -226.106736)
		(width 0.09525)
		(layer "In11.Cu")
		(net "M_F_CPU1_SA_DQS_DN<5>")
	)
	(segment
		(start 84.517992 -247.180354)
		(end 84.05114 -246.914416)
		(width 0.12954)
		(layer "F.Cu")
		(net "M_F_CPU1_SA_DQS_DN<4>")
	)
	(segment
		(start 65.68821 -245.307866)
		(end 66.68897 -246.308626)
		(width 0.16002)
		(layer "In11.Cu")
		(net "M_F_CPU1_SA_DQS_DN<4>")
	)
	(segment
		(start 84.181696 -246.562118)
		(end 84.205064 -246.648986)
		(width 0.09525)
		(layer "In11.Cu")
		(net "M_F_CPU1_SA_DQS_DN<4>")
	)
	(segment
		(start 28.144724 -238.081566)
		(end 28.513786 -237.712504)
		(width 0.16002)
		(layer "In11.Cu")
		(net "M_F_CPU1_SA_DQS_DN<4>")
	)
	(segment
		(start 22.61108 -238.711486)
		(end 22.72792 -238.828326)
		(width 0.16002)
		(layer "In11.Cu")
		(net "M_F_CPU1_SA_DQS_DN<4>")
	)
	(segment
		(start 21.70811 -238.985298)
		(end 21.981922 -238.711486)
		(width 0.16002)
		(layer "In11.Cu")
		(net "M_F_CPU1_SA_DQS_DN<4>")
	)
	(segment
		(start 54.303676 -238.907066)
		(end 54.834282 -238.907066)
		(width 0.16002)
		(layer "In11.Cu")
		(net "M_F_CPU1_SA_DQS_DN<4>")
	)
	(segment
		(start 28.513786 -237.712504)
		(end 30.120082 -237.712504)
		(width 0.16002)
		(layer "In11.Cu")
		(net "M_F_CPU1_SA_DQS_DN<4>")
	)
	(segment
		(start 58.985912 -240.030508)
		(end 59.462416 -240.030508)
		(width 0.16002)
		(layer "In11.Cu")
		(net "M_F_CPU1_SA_DQS_DN<4>")
	)
	(segment
		(start 23.20798 -238.828326)
		(end 23.32482 -238.711486)
		(width 0.16002)
		(layer "In11.Cu")
		(net "M_F_CPU1_SA_DQS_DN<4>")
	)
	(segment
		(start 58.560208 -239.1283)
		(end 58.560208 -239.604804)
		(width 0.16002)
		(layer "In11.Cu")
		(net "M_F_CPU1_SA_DQS_DN<4>")
	)
	(segment
		(start 48.8569 -238.907066)
		(end 49.506632 -238.907066)
		(width 0.16002)
		(layer "In11.Cu")
		(net "M_F_CPU1_SA_DQS_DN<4>")
	)
	(segment
		(start 33.424114 -238.562388)
		(end 33.768792 -238.907066)
		(width 0.16002)
		(layer "In11.Cu")
		(net "M_F_CPU1_SA_DQS_DN<4>")
	)
	(segment
		(start 64.591184 -244.21084)
		(end 64.591184 -244.85092)
		(width 0.16002)
		(layer "In11.Cu")
		(net "M_F_CPU1_SA_DQS_DN<4>")
	)
	(segment
		(start 61.838332 -242.098068)
		(end 62.295278 -242.555014)
		(width 0.16002)
		(layer "In11.Cu")
		(net "M_F_CPU1_SA_DQS_DN<4>")
	)
	(segment
		(start 24.280622 -238.562388)
		(end 25.88006 -238.562388)
		(width 0.16002)
		(layer "In11.Cu")
		(net "M_F_CPU1_SA_DQS_DN<4>")
	)
	(segment
		(start 77.758544 -246.65305)
		(end 77.982318 -246.660924)
		(width 0.09525)
		(layer "In11.Cu")
		(net "M_F_CPU1_SA_DQS_DN<4>")
	)
	(segment
		(start 53.751734 -238.355124)
		(end 54.303676 -238.907066)
		(width 0.16002)
		(layer "In11.Cu")
		(net "M_F_CPU1_SA_DQS_DN<4>")
	)
	(segment
		(start 60.918852 -241.178588)
		(end 61.558932 -241.178588)
		(width 0.16002)
		(layer "In11.Cu")
		(net "M_F_CPU1_SA_DQS_DN<4>")
	)
	(segment
		(start 43.232832 -238.081566)
		(end 43.601894 -237.712504)
		(width 0.16002)
		(layer "In11.Cu")
		(net "M_F_CPU1_SA_DQS_DN<4>")
	)
	(segment
		(start 52.752244 -237.712504)
		(end 53.394864 -238.355124)
		(width 0.16002)
		(layer "In11.Cu")
		(net "M_F_CPU1_SA_DQS_DN<4>")
	)
	(segment
		(start 83.291172 -246.58447)
		(end 83.299554 -246.589296)
		(width 0.09525)
		(layer "In11.Cu")
		(net "M_F_CPU1_SA_DQS_DN<4>")
	)
	(segment
		(start 55.33136 -238.190786)
		(end 55.68188 -238.190786)
		(width 0.16002)
		(layer "In11.Cu")
		(net "M_F_CPU1_SA_DQS_DN<4>")
	)
	(segment
		(start 55.8419 -239.034828)
		(end 56.178958 -239.371886)
		(width 0.16002)
		(layer "In11.Cu")
		(net "M_F_CPU1_SA_DQS_DN<4>")
	)
	(segment
		(start 65.04813 -245.307866)
		(end 65.68821 -245.307866)
		(width 0.16002)
		(layer "In11.Cu")
		(net "M_F_CPU1_SA_DQS_DN<4>")
	)
	(segment
		(start 64.311784 -243.93144)
		(end 64.591184 -244.21084)
		(width 0.16002)
		(layer "In11.Cu")
		(net "M_F_CPU1_SA_DQS_DN<4>")
	)
	(segment
		(start 62.935358 -242.555014)
		(end 63.214758 -242.834414)
		(width 0.16002)
		(layer "In11.Cu")
		(net "M_F_CPU1_SA_DQS_DN<4>")
	)
	(segment
		(start 77.35697 -246.65305)
		(end 77.758544 -246.65305)
		(width 0.09525)
		(layer "In11.Cu")
		(net "M_F_CPU1_SA_DQS_DN<4>")
	)
	(segment
		(start 42.788078 -238.081566)
		(end 43.232832 -238.081566)
		(width 0.16002)
		(layer "In11.Cu")
		(net "M_F_CPU1_SA_DQS_DN<4>")
	)
	(segment
		(start 79.145638 -246.59971)
		(end 79.163672 -246.589296)
		(width 0.09525)
		(layer "In11.Cu")
		(net "M_F_CPU1_SA_DQS_DN<4>")
	)
	(segment
		(start 27.69997 -238.081566)
		(end 28.144724 -238.081566)
		(width 0.16002)
		(layer "In11.Cu")
		(net "M_F_CPU1_SA_DQS_DN<4>")
	)
	(segment
		(start 77.087984 -246.922036)
		(end 77.35697 -246.65305)
		(width 0.09525)
		(layer "In11.Cu")
		(net "M_F_CPU1_SA_DQS_DN<4>")
	)
	(segment
		(start 60.461906 -240.081562)
		(end 60.461906 -240.721642)
		(width 0.16002)
		(layer "In11.Cu")
		(net "M_F_CPU1_SA_DQS_DN<4>")
	)
	(segment
		(start 23.32482 -238.711486)
		(end 24.131524 -238.711486)
		(width 0.16002)
		(layer "In11.Cu")
		(net "M_F_CPU1_SA_DQS_DN<4>")
	)
	(segment
		(start 75.675236 -246.796306)
		(end 75.955906 -246.796306)
		(width 0.16002)
		(layer "In11.Cu")
		(net "M_F_CPU1_SA_DQS_DN<4>")
	)
	(segment
		(start 41.312846 -238.907066)
		(end 41.962578 -238.907066)
		(width 0.16002)
		(layer "In11.Cu")
		(net "M_F_CPU1_SA_DQS_DN<4>")
	)
	(segment
		(start 25.88006 -238.562388)
		(end 26.224738 -238.907066)
		(width 0.16002)
		(layer "In11.Cu")
		(net "M_F_CPU1_SA_DQS_DN<4>")
	)
	(segment
		(start 50.776886 -238.081566)
		(end 51.145948 -237.712504)
		(width 0.16002)
		(layer "In11.Cu")
		(net "M_F_CPU1_SA_DQS_DN<4>")
	)
	(segment
		(start 41.962578 -238.907066)
		(end 42.788078 -238.081566)
		(width 0.16002)
		(layer "In11.Cu")
		(net "M_F_CPU1_SA_DQS_DN<4>")
	)
	(segment
		(start 64.591184 -244.85092)
		(end 65.04813 -245.307866)
		(width 0.16002)
		(layer "In11.Cu")
		(net "M_F_CPU1_SA_DQS_DN<4>")
	)
	(segment
		(start 75.187556 -246.308626)
		(end 75.675236 -246.796306)
		(width 0.16002)
		(layer "In11.Cu")
		(net "M_F_CPU1_SA_DQS_DN<4>")
	)
	(segment
		(start 58.190892 -238.081566)
		(end 58.46191 -238.081566)
		(width 0.16002)
		(layer "In11.Cu")
		(net "M_F_CPU1_SA_DQS_DN<4>")
	)
	(segment
		(start 50.332132 -238.081566)
		(end 50.776886 -238.081566)
		(width 0.16002)
		(layer "In11.Cu")
		(net "M_F_CPU1_SA_DQS_DN<4>")
	)
	(segment
		(start 21.981922 -238.711486)
		(end 22.61108 -238.711486)
		(width 0.16002)
		(layer "In11.Cu")
		(net "M_F_CPU1_SA_DQS_DN<4>")
	)
	(segment
		(start 63.671704 -243.93144)
		(end 64.311784 -243.93144)
		(width 0.16002)
		(layer "In11.Cu")
		(net "M_F_CPU1_SA_DQS_DN<4>")
	)
	(segment
		(start 53.394864 -238.355124)
		(end 53.751734 -238.355124)
		(width 0.16002)
		(layer "In11.Cu")
		(net "M_F_CPU1_SA_DQS_DN<4>")
	)
	(segment
		(start 66.68897 -246.308626)
		(end 75.187556 -246.308626)
		(width 0.16002)
		(layer "In11.Cu")
		(net "M_F_CPU1_SA_DQS_DN<4>")
	)
	(segment
		(start 43.601894 -237.712504)
		(end 45.20819 -237.712504)
		(width 0.16002)
		(layer "In11.Cu")
		(net "M_F_CPU1_SA_DQS_DN<4>")
	)
	(segment
		(start 75.955906 -246.796306)
		(end 75.979528 -246.796306)
		(width 0.09525)
		(layer "In11.Cu")
		(net "M_F_CPU1_SA_DQS_DN<4>")
	)
	(segment
		(start 58.560208 -239.604804)
		(end 58.985912 -240.030508)
		(width 0.16002)
		(layer "In11.Cu")
		(net "M_F_CPU1_SA_DQS_DN<4>")
	)
	(segment
		(start 40.968168 -238.562388)
		(end 41.312846 -238.907066)
		(width 0.16002)
		(layer "In11.Cu")
		(net "M_F_CPU1_SA_DQS_DN<4>")
	)
	(segment
		(start 35.688778 -238.081566)
		(end 36.05784 -237.712504)
		(width 0.16002)
		(layer "In11.Cu")
		(net "M_F_CPU1_SA_DQS_DN<4>")
	)
	(segment
		(start 76.399644 -246.737124)
		(end 76.584556 -246.922036)
		(width 0.09525)
		(layer "In11.Cu")
		(net "M_F_CPU1_SA_DQS_DN<4>")
	)
	(segment
		(start 58.921396 -238.541052)
		(end 58.921396 -238.767112)
		(width 0.16002)
		(layer "In11.Cu")
		(net "M_F_CPU1_SA_DQS_DN<4>")
	)
	(segment
		(start 80.471264 -246.58447)
		(end 80.479646 -246.589296)
		(width 0.09525)
		(layer "In11.Cu")
		(net "M_F_CPU1_SA_DQS_DN<4>")
	)
	(segment
		(start 78.22311 -246.589296)
		(end 78.239874 -246.579644)
		(width 0.09525)
		(layer "In11.Cu")
		(net "M_F_CPU1_SA_DQS_DN<4>")
	)
	(segment
		(start 60.461906 -240.721642)
		(end 60.918852 -241.178588)
		(width 0.16002)
		(layer "In11.Cu")
		(net "M_F_CPU1_SA_DQS_DN<4>")
	)
	(segment
		(start 61.558932 -241.178588)
		(end 61.838332 -241.457988)
		(width 0.16002)
		(layer "In11.Cu")
		(net "M_F_CPU1_SA_DQS_DN<4>")
	)
	(segment
		(start 61.838332 -241.457988)
		(end 61.838332 -242.098068)
		(width 0.16002)
		(layer "In11.Cu")
		(net "M_F_CPU1_SA_DQS_DN<4>")
	)
	(segment
		(start 59.462416 -240.030508)
		(end 59.823604 -239.66932)
		(width 0.16002)
		(layer "In11.Cu")
		(net "M_F_CPU1_SA_DQS_DN<4>")
	)
	(segment
		(start 59.823604 -239.66932)
		(end 60.049664 -239.66932)
		(width 0.16002)
		(layer "In11.Cu")
		(net "M_F_CPU1_SA_DQS_DN<4>")
	)
	(segment
		(start 76.584556 -246.922036)
		(end 77.087984 -246.922036)
		(width 0.09525)
		(layer "In11.Cu")
		(net "M_F_CPU1_SA_DQS_DN<4>")
	)
	(segment
		(start 34.418524 -238.907066)
		(end 35.244024 -238.081566)
		(width 0.16002)
		(layer "In11.Cu")
		(net "M_F_CPU1_SA_DQS_DN<4>")
	)
	(segment
		(start 45.20819 -237.712504)
		(end 46.058074 -238.562388)
		(width 0.16002)
		(layer "In11.Cu")
		(net "M_F_CPU1_SA_DQS_DN<4>")
	)
	(segment
		(start 77.982318 -246.660924)
		(end 77.984604 -246.663464)
		(width 0.09525)
		(layer "In11.Cu")
		(net "M_F_CPU1_SA_DQS_DN<4>")
	)
	(segment
		(start 33.768792 -238.907066)
		(end 34.418524 -238.907066)
		(width 0.16002)
		(layer "In11.Cu")
		(net "M_F_CPU1_SA_DQS_DN<4>")
	)
	(segment
		(start 84.205064 -246.648986)
		(end 84.05114 -246.914416)
		(width 0.09525)
		(layer "In11.Cu")
		(net "M_F_CPU1_SA_DQS_DN<4>")
	)
	(segment
		(start 58.921396 -238.767112)
		(end 58.560208 -239.1283)
		(width 0.16002)
		(layer "In11.Cu")
		(net "M_F_CPU1_SA_DQS_DN<4>")
	)
	(segment
		(start 48.512222 -238.562388)
		(end 48.8569 -238.907066)
		(width 0.16002)
		(layer "In11.Cu")
		(net "M_F_CPU1_SA_DQS_DN<4>")
	)
	(segment
		(start 49.506632 -238.907066)
		(end 50.332132 -238.081566)
		(width 0.16002)
		(layer "In11.Cu")
		(net "M_F_CPU1_SA_DQS_DN<4>")
	)
	(segment
		(start 46.058074 -238.562388)
		(end 48.512222 -238.562388)
		(width 0.16002)
		(layer "In11.Cu")
		(net "M_F_CPU1_SA_DQS_DN<4>")
	)
	(segment
		(start 58.46191 -238.081566)
		(end 58.921396 -238.541052)
		(width 0.16002)
		(layer "In11.Cu")
		(net "M_F_CPU1_SA_DQS_DN<4>")
	)
	(segment
		(start 55.17134 -238.350806)
		(end 55.33136 -238.190786)
		(width 0.16002)
		(layer "In11.Cu")
		(net "M_F_CPU1_SA_DQS_DN<4>")
	)
	(segment
		(start 79.540354 -246.589296)
		(end 79.558388 -246.59971)
		(width 0.09525)
		(layer "In11.Cu")
		(net "M_F_CPU1_SA_DQS_DN<4>")
	)
	(segment
		(start 62.295278 -242.555014)
		(end 62.935358 -242.555014)
		(width 0.16002)
		(layer "In11.Cu")
		(net "M_F_CPU1_SA_DQS_DN<4>")
	)
	(segment
		(start 54.834282 -238.907066)
		(end 55.17134 -238.570008)
		(width 0.16002)
		(layer "In11.Cu")
		(net "M_F_CPU1_SA_DQS_DN<4>")
	)
	(segment
		(start 26.224738 -238.907066)
		(end 26.87447 -238.907066)
		(width 0.16002)
		(layer "In11.Cu")
		(net "M_F_CPU1_SA_DQS_DN<4>")
	)
	(segment
		(start 56.900572 -239.371886)
		(end 58.190892 -238.081566)
		(width 0.16002)
		(layer "In11.Cu")
		(net "M_F_CPU1_SA_DQS_DN<4>")
	)
	(segment
		(start 55.8419 -238.350806)
		(end 55.8419 -239.034828)
		(width 0.16002)
		(layer "In11.Cu")
		(net "M_F_CPU1_SA_DQS_DN<4>")
	)
	(segment
		(start 22.72792 -238.828326)
		(end 23.20798 -238.828326)
		(width 0.16002)
		(layer "In11.Cu")
		(net "M_F_CPU1_SA_DQS_DN<4>")
	)
	(segment
		(start 36.05784 -237.712504)
		(end 37.664136 -237.712504)
		(width 0.16002)
		(layer "In11.Cu")
		(net "M_F_CPU1_SA_DQS_DN<4>")
	)
	(segment
		(start 30.969966 -238.562388)
		(end 33.424114 -238.562388)
		(width 0.16002)
		(layer "In11.Cu")
		(net "M_F_CPU1_SA_DQS_DN<4>")
	)
	(segment
		(start 24.131524 -238.711486)
		(end 24.280622 -238.562388)
		(width 0.16002)
		(layer "In11.Cu")
		(net "M_F_CPU1_SA_DQS_DN<4>")
	)
	(segment
		(start 56.178958 -239.371886)
		(end 56.900572 -239.371886)
		(width 0.16002)
		(layer "In11.Cu")
		(net "M_F_CPU1_SA_DQS_DN<4>")
	)
	(segment
		(start 37.664136 -237.712504)
		(end 38.51402 -238.562388)
		(width 0.16002)
		(layer "In11.Cu")
		(net "M_F_CPU1_SA_DQS_DN<4>")
	)
	(segment
		(start 63.214758 -243.474494)
		(end 63.671704 -243.93144)
		(width 0.16002)
		(layer "In11.Cu")
		(net "M_F_CPU1_SA_DQS_DN<4>")
	)
	(segment
		(start 63.214758 -242.834414)
		(end 63.214758 -243.474494)
		(width 0.16002)
		(layer "In11.Cu")
		(net "M_F_CPU1_SA_DQS_DN<4>")
	)
	(segment
		(start 30.120082 -237.712504)
		(end 30.969966 -238.562388)
		(width 0.16002)
		(layer "In11.Cu")
		(net "M_F_CPU1_SA_DQS_DN<4>")
	)
	(segment
		(start 35.244024 -238.081566)
		(end 35.688778 -238.081566)
		(width 0.16002)
		(layer "In11.Cu")
		(net "M_F_CPU1_SA_DQS_DN<4>")
	)
	(segment
		(start 26.87447 -238.907066)
		(end 27.69997 -238.081566)
		(width 0.16002)
		(layer "In11.Cu")
		(net "M_F_CPU1_SA_DQS_DN<4>")
	)
	(segment
		(start 79.531972 -246.58447)
		(end 79.540354 -246.589296)
		(width 0.09525)
		(layer "In11.Cu")
		(net "M_F_CPU1_SA_DQS_DN<4>")
	)
	(segment
		(start 55.68188 -238.190786)
		(end 55.8419 -238.350806)
		(width 0.16002)
		(layer "In11.Cu")
		(net "M_F_CPU1_SA_DQS_DN<4>")
	)
	(segment
		(start 55.17134 -238.570008)
		(end 55.17134 -238.350806)
		(width 0.16002)
		(layer "In11.Cu")
		(net "M_F_CPU1_SA_DQS_DN<4>")
	)
	(segment
		(start 75.979528 -246.796306)
		(end 76.03871 -246.737124)
		(width 0.09525)
		(layer "In11.Cu")
		(net "M_F_CPU1_SA_DQS_DN<4>")
	)
	(segment
		(start 81.04251 -246.589296)
		(end 81.050892 -246.58447)
		(width 0.09525)
		(layer "In11.Cu")
		(net "M_F_CPU1_SA_DQS_DN<4>")
	)
	(segment
		(start 38.51402 -238.562388)
		(end 40.968168 -238.562388)
		(width 0.16002)
		(layer "In11.Cu")
		(net "M_F_CPU1_SA_DQS_DN<4>")
	)
	(segment
		(start 76.03871 -246.737124)
		(end 76.399644 -246.737124)
		(width 0.09525)
		(layer "In11.Cu")
		(net "M_F_CPU1_SA_DQS_DN<4>")
	)
	(segment
		(start 51.145948 -237.712504)
		(end 52.752244 -237.712504)
		(width 0.16002)
		(layer "In11.Cu")
		(net "M_F_CPU1_SA_DQS_DN<4>")
	)
	(segment
		(start 78.205076 -246.59971)
		(end 78.22311 -246.589296)
		(width 0.09525)
		(layer "In11.Cu")
		(net "M_F_CPU1_SA_DQS_DN<4>")
	)
	(segment
		(start 60.049664 -239.66932)
		(end 60.461906 -240.081562)
		(width 0.16002)
		(layer "In11.Cu")
		(net "M_F_CPU1_SA_DQS_DN<4>")
	)
	(arc
		(start 81.4197 -246.589296)
		(mid 81.701132 -246.665051)
		(end 81.982564 -246.589296)
		(width 0.09525)
		(layer "In11.Cu")
		(net "M_F_CPU1_SA_DQS_DN<4>")
	)
	(arc
		(start 82.3595 -246.589296)
		(mid 82.640932 -246.665051)
		(end 82.922364 -246.589296)
		(width 0.09525)
		(layer "In11.Cu")
		(net "M_F_CPU1_SA_DQS_DN<4>")
	)
	(arc
		(start 78.239874 -246.579644)
		(mid 78.421185 -246.538546)
		(end 78.600046 -246.589296)
		(width 0.09525)
		(layer "In11.Cu")
		(net "M_F_CPU1_SA_DQS_DN<4>")
	)
	(arc
		(start 79.558388 -246.59971)
		(mid 79.831768 -246.664931)
		(end 80.102456 -246.589296)
		(width 0.09525)
		(layer "In11.Cu")
		(net "M_F_CPU1_SA_DQS_DN<4>")
	)
	(arc
		(start 78.600046 -246.589296)
		(mid 78.871496 -246.665331)
		(end 79.145638 -246.59971)
		(width 0.09525)
		(layer "In11.Cu")
		(net "M_F_CPU1_SA_DQS_DN<4>")
	)
	(arc
		(start 83.862418 -246.589296)
		(mid 84.019016 -246.540007)
		(end 84.181696 -246.562118)
		(width 0.09525)
		(layer "In11.Cu")
		(net "M_F_CPU1_SA_DQS_DN<4>")
	)
	(arc
		(start 82.922364 -246.589296)
		(mid 83.106139 -246.538524)
		(end 83.291172 -246.58447)
		(width 0.09525)
		(layer "In11.Cu")
		(net "M_F_CPU1_SA_DQS_DN<4>")
	)
	(arc
		(start 77.984604 -246.663464)
		(mid 78.098141 -246.642998)
		(end 78.205076 -246.59971)
		(width 0.09525)
		(layer "In11.Cu")
		(net "M_F_CPU1_SA_DQS_DN<4>")
	)
	(arc
		(start 81.982564 -246.589296)
		(mid 82.171032 -246.538619)
		(end 82.3595 -246.589296)
		(width 0.09525)
		(layer "In11.Cu")
		(net "M_F_CPU1_SA_DQS_DN<4>")
	)
	(arc
		(start 79.163672 -246.589296)
		(mid 79.347193 -246.538652)
		(end 79.531972 -246.58447)
		(width 0.09525)
		(layer "In11.Cu")
		(net "M_F_CPU1_SA_DQS_DN<4>")
	)
	(arc
		(start 83.299554 -246.589296)
		(mid 83.580986 -246.665051)
		(end 83.862418 -246.589296)
		(width 0.09525)
		(layer "In11.Cu")
		(net "M_F_CPU1_SA_DQS_DN<4>")
	)
	(arc
		(start 80.102456 -246.589296)
		(mid 80.286231 -246.538524)
		(end 80.471264 -246.58447)
		(width 0.09525)
		(layer "In11.Cu")
		(net "M_F_CPU1_SA_DQS_DN<4>")
	)
	(arc
		(start 80.479646 -246.589296)
		(mid 80.761078 -246.665051)
		(end 81.04251 -246.589296)
		(width 0.09525)
		(layer "In11.Cu")
		(net "M_F_CPU1_SA_DQS_DN<4>")
	)
	(arc
		(start 81.050892 -246.58447)
		(mid 81.235924 -246.538556)
		(end 81.4197 -246.589296)
		(width 0.09525)
		(layer "In11.Cu")
		(net "M_F_CPU1_SA_DQS_DN<4>")
	)
	(segment
		(start 84.517992 -242.320318)
		(end 84.05114 -242.05438)
		(width 0.12954)
		(layer "F.Cu")
		(net "M_F_CPU1_SA_DQS_DN<3>")
	)
	(segment
		(start 83.291172 -241.724434)
		(end 83.299554 -241.72926)
		(width 0.09525)
		(layer "In11.Cu")
		(net "M_F_CPU1_SA_DQS_DN<3>")
	)
	(segment
		(start 25.88006 -229.212394)
		(end 26.224738 -229.557072)
		(width 0.16002)
		(layer "In11.Cu")
		(net "M_F_CPU1_SA_DQS_DN<3>")
	)
	(segment
		(start 66.71437 -238.41583)
		(end 67.190874 -238.41583)
		(width 0.16002)
		(layer "In11.Cu")
		(net "M_F_CPU1_SA_DQS_DN<3>")
	)
	(segment
		(start 22.85492 -229.478332)
		(end 23.33498 -229.478332)
		(width 0.16002)
		(layer "In11.Cu")
		(net "M_F_CPU1_SA_DQS_DN<3>")
	)
	(segment
		(start 26.224738 -229.557072)
		(end 26.87447 -229.557072)
		(width 0.16002)
		(layer "In11.Cu")
		(net "M_F_CPU1_SA_DQS_DN<3>")
	)
	(segment
		(start 45.20819 -228.36251)
		(end 46.058074 -229.212394)
		(width 0.16002)
		(layer "In11.Cu")
		(net "M_F_CPU1_SA_DQS_DN<3>")
	)
	(segment
		(start 65.315338 -235.74375)
		(end 64.917066 -236.141768)
		(width 0.16002)
		(layer "In11.Cu")
		(net "M_F_CPU1_SA_DQS_DN<3>")
	)
	(segment
		(start 64.917066 -236.618526)
		(end 65.340738 -237.042198)
		(width 0.16002)
		(layer "In11.Cu")
		(net "M_F_CPU1_SA_DQS_DN<3>")
	)
	(segment
		(start 66.68897 -237.117382)
		(end 66.290698 -237.5154)
		(width 0.16002)
		(layer "In11.Cu")
		(net "M_F_CPU1_SA_DQS_DN<3>")
	)
	(segment
		(start 23.45182 -229.361492)
		(end 24.131524 -229.361492)
		(width 0.16002)
		(layer "In11.Cu")
		(net "M_F_CPU1_SA_DQS_DN<3>")
	)
	(segment
		(start 64.841882 -235.270548)
		(end 65.067942 -235.270548)
		(width 0.16002)
		(layer "In11.Cu")
		(net "M_F_CPU1_SA_DQS_DN<3>")
	)
	(segment
		(start 81.04251 -241.72926)
		(end 81.050892 -241.724434)
		(width 0.09525)
		(layer "In11.Cu")
		(net "M_F_CPU1_SA_DQS_DN<3>")
	)
	(segment
		(start 67.815206 -238.017812)
		(end 68.062602 -238.265208)
		(width 0.16002)
		(layer "In11.Cu")
		(net "M_F_CPU1_SA_DQS_DN<3>")
	)
	(segment
		(start 66.441574 -236.64418)
		(end 66.68897 -236.891576)
		(width 0.16002)
		(layer "In11.Cu")
		(net "M_F_CPU1_SA_DQS_DN<3>")
	)
	(segment
		(start 57.078118 -229.529386)
		(end 57.875932 -228.731572)
		(width 0.16002)
		(layer "In11.Cu")
		(net "M_F_CPU1_SA_DQS_DN<3>")
	)
	(segment
		(start 76.647294 -241.104928)
		(end 76.942188 -241.104928)
		(width 0.09525)
		(layer "In11.Cu")
		(net "M_F_CPU1_SA_DQS_DN<3>")
	)
	(segment
		(start 24.131524 -229.361492)
		(end 24.280622 -229.212394)
		(width 0.16002)
		(layer "In11.Cu")
		(net "M_F_CPU1_SA_DQS_DN<3>")
	)
	(segment
		(start 75.979528 -240.693194)
		(end 76.03871 -240.634012)
		(width 0.09525)
		(layer "In11.Cu")
		(net "M_F_CPU1_SA_DQS_DN<3>")
	)
	(segment
		(start 27.69997 -228.731572)
		(end 28.144724 -228.731572)
		(width 0.16002)
		(layer "In11.Cu")
		(net "M_F_CPU1_SA_DQS_DN<3>")
	)
	(segment
		(start 79.145638 -241.739674)
		(end 79.163672 -241.72926)
		(width 0.09525)
		(layer "In11.Cu")
		(net "M_F_CPU1_SA_DQS_DN<3>")
	)
	(segment
		(start 41.312846 -229.557072)
		(end 41.962578 -229.557072)
		(width 0.16002)
		(layer "In11.Cu")
		(net "M_F_CPU1_SA_DQS_DN<3>")
	)
	(segment
		(start 66.290698 -237.5154)
		(end 66.290698 -237.992158)
		(width 0.16002)
		(layer "In11.Cu")
		(net "M_F_CPU1_SA_DQS_DN<3>")
	)
	(segment
		(start 67.66433 -238.889032)
		(end 67.66433 -239.36579)
		(width 0.16002)
		(layer "In11.Cu")
		(net "M_F_CPU1_SA_DQS_DN<3>")
	)
	(segment
		(start 28.144724 -228.731572)
		(end 28.513786 -228.36251)
		(width 0.16002)
		(layer "In11.Cu")
		(net "M_F_CPU1_SA_DQS_DN<3>")
	)
	(segment
		(start 63.296546 -234.998006)
		(end 63.967106 -235.668566)
		(width 0.16002)
		(layer "In11.Cu")
		(net "M_F_CPU1_SA_DQS_DN<3>")
	)
	(segment
		(start 48.8569 -229.557072)
		(end 49.506632 -229.557072)
		(width 0.16002)
		(layer "In11.Cu")
		(net "M_F_CPU1_SA_DQS_DN<3>")
	)
	(segment
		(start 21.70811 -229.635304)
		(end 21.981922 -229.361492)
		(width 0.16002)
		(layer "In11.Cu")
		(net "M_F_CPU1_SA_DQS_DN<3>")
	)
	(segment
		(start 79.540354 -241.72926)
		(end 79.558388 -241.739674)
		(width 0.09525)
		(layer "In11.Cu")
		(net "M_F_CPU1_SA_DQS_DN<3>")
	)
	(segment
		(start 68.062602 -238.265208)
		(end 68.062602 -238.491014)
		(width 0.16002)
		(layer "In11.Cu")
		(net "M_F_CPU1_SA_DQS_DN<3>")
	)
	(segment
		(start 36.05784 -228.36251)
		(end 37.664136 -228.36251)
		(width 0.16002)
		(layer "In11.Cu")
		(net "M_F_CPU1_SA_DQS_DN<3>")
	)
	(segment
		(start 76.942188 -241.104928)
		(end 77.515212 -241.677952)
		(width 0.09525)
		(layer "In11.Cu")
		(net "M_F_CPU1_SA_DQS_DN<3>")
	)
	(segment
		(start 53.91912 -229.529386)
		(end 57.078118 -229.529386)
		(width 0.16002)
		(layer "In11.Cu")
		(net "M_F_CPU1_SA_DQS_DN<3>")
	)
	(segment
		(start 38.51402 -229.212394)
		(end 40.968168 -229.212394)
		(width 0.16002)
		(layer "In11.Cu")
		(net "M_F_CPU1_SA_DQS_DN<3>")
	)
	(segment
		(start 28.513786 -228.36251)
		(end 30.120082 -228.36251)
		(width 0.16002)
		(layer "In11.Cu")
		(net "M_F_CPU1_SA_DQS_DN<3>")
	)
	(segment
		(start 77.515212 -241.677952)
		(end 78.316074 -241.677952)
		(width 0.09525)
		(layer "In11.Cu")
		(net "M_F_CPU1_SA_DQS_DN<3>")
	)
	(segment
		(start 78.316074 -241.677952)
		(end 78.316582 -241.67846)
		(width 0.09525)
		(layer "In11.Cu")
		(net "M_F_CPU1_SA_DQS_DN<3>")
	)
	(segment
		(start 57.875932 -228.731572)
		(end 58.727848 -228.731572)
		(width 0.16002)
		(layer "In11.Cu")
		(net "M_F_CPU1_SA_DQS_DN<3>")
	)
	(segment
		(start 33.768792 -229.557072)
		(end 34.418524 -229.557072)
		(width 0.16002)
		(layer "In11.Cu")
		(net "M_F_CPU1_SA_DQS_DN<3>")
	)
	(segment
		(start 58.727848 -228.731572)
		(end 63.296546 -233.30027)
		(width 0.16002)
		(layer "In11.Cu")
		(net "M_F_CPU1_SA_DQS_DN<3>")
	)
	(segment
		(start 75.955906 -240.693194)
		(end 75.979528 -240.693194)
		(width 0.09525)
		(layer "In11.Cu")
		(net "M_F_CPU1_SA_DQS_DN<3>")
	)
	(segment
		(start 30.969966 -229.212394)
		(end 33.424114 -229.212394)
		(width 0.16002)
		(layer "In11.Cu")
		(net "M_F_CPU1_SA_DQS_DN<3>")
	)
	(segment
		(start 49.506632 -229.557072)
		(end 50.332132 -228.731572)
		(width 0.16002)
		(layer "In11.Cu")
		(net "M_F_CPU1_SA_DQS_DN<3>")
	)
	(segment
		(start 22.73808 -229.361492)
		(end 22.85492 -229.478332)
		(width 0.16002)
		(layer "In11.Cu")
		(net "M_F_CPU1_SA_DQS_DN<3>")
	)
	(segment
		(start 52.752244 -228.36251)
		(end 53.91912 -229.529386)
		(width 0.16002)
		(layer "In11.Cu")
		(net "M_F_CPU1_SA_DQS_DN<3>")
	)
	(segment
		(start 46.058074 -229.212394)
		(end 48.512222 -229.212394)
		(width 0.16002)
		(layer "In11.Cu")
		(net "M_F_CPU1_SA_DQS_DN<3>")
	)
	(segment
		(start 67.589146 -238.017812)
		(end 67.815206 -238.017812)
		(width 0.16002)
		(layer "In11.Cu")
		(net "M_F_CPU1_SA_DQS_DN<3>")
	)
	(segment
		(start 35.244024 -228.731572)
		(end 35.688778 -228.731572)
		(width 0.16002)
		(layer "In11.Cu")
		(net "M_F_CPU1_SA_DQS_DN<3>")
	)
	(segment
		(start 66.290698 -237.992158)
		(end 66.71437 -238.41583)
		(width 0.16002)
		(layer "In11.Cu")
		(net "M_F_CPU1_SA_DQS_DN<3>")
	)
	(segment
		(start 41.962578 -229.557072)
		(end 42.788078 -228.731572)
		(width 0.16002)
		(layer "In11.Cu")
		(net "M_F_CPU1_SA_DQS_DN<3>")
	)
	(segment
		(start 68.062602 -238.491014)
		(end 67.66433 -238.889032)
		(width 0.16002)
		(layer "In11.Cu")
		(net "M_F_CPU1_SA_DQS_DN<3>")
	)
	(segment
		(start 24.280622 -229.212394)
		(end 25.88006 -229.212394)
		(width 0.16002)
		(layer "In11.Cu")
		(net "M_F_CPU1_SA_DQS_DN<3>")
	)
	(segment
		(start 34.418524 -229.557072)
		(end 35.244024 -228.731572)
		(width 0.16002)
		(layer "In11.Cu")
		(net "M_F_CPU1_SA_DQS_DN<3>")
	)
	(segment
		(start 64.44361 -235.668566)
		(end 64.841882 -235.270548)
		(width 0.16002)
		(layer "In11.Cu")
		(net "M_F_CPU1_SA_DQS_DN<3>")
	)
	(segment
		(start 23.33498 -229.478332)
		(end 23.45182 -229.361492)
		(width 0.16002)
		(layer "In11.Cu")
		(net "M_F_CPU1_SA_DQS_DN<3>")
	)
	(segment
		(start 42.788078 -228.731572)
		(end 43.232832 -228.731572)
		(width 0.16002)
		(layer "In11.Cu")
		(net "M_F_CPU1_SA_DQS_DN<3>")
	)
	(segment
		(start 37.664136 -228.36251)
		(end 38.51402 -229.212394)
		(width 0.16002)
		(layer "In11.Cu")
		(net "M_F_CPU1_SA_DQS_DN<3>")
	)
	(segment
		(start 33.424114 -229.212394)
		(end 33.768792 -229.557072)
		(width 0.16002)
		(layer "In11.Cu")
		(net "M_F_CPU1_SA_DQS_DN<3>")
	)
	(segment
		(start 79.531972 -241.724434)
		(end 79.540354 -241.72926)
		(width 0.09525)
		(layer "In11.Cu")
		(net "M_F_CPU1_SA_DQS_DN<3>")
	)
	(segment
		(start 63.296546 -233.30027)
		(end 63.296546 -234.998006)
		(width 0.16002)
		(layer "In11.Cu")
		(net "M_F_CPU1_SA_DQS_DN<3>")
	)
	(segment
		(start 65.315338 -235.517944)
		(end 65.315338 -235.74375)
		(width 0.16002)
		(layer "In11.Cu")
		(net "M_F_CPU1_SA_DQS_DN<3>")
	)
	(segment
		(start 43.601894 -228.36251)
		(end 45.20819 -228.36251)
		(width 0.16002)
		(layer "In11.Cu")
		(net "M_F_CPU1_SA_DQS_DN<3>")
	)
	(segment
		(start 68.991734 -240.693194)
		(end 75.955906 -240.693194)
		(width 0.16002)
		(layer "In11.Cu")
		(net "M_F_CPU1_SA_DQS_DN<3>")
	)
	(segment
		(start 78.316582 -241.67846)
		(end 78.411324 -241.67846)
		(width 0.09525)
		(layer "In11.Cu")
		(net "M_F_CPU1_SA_DQS_DN<3>")
	)
	(segment
		(start 65.067942 -235.270548)
		(end 65.315338 -235.517944)
		(width 0.16002)
		(layer "In11.Cu")
		(net "M_F_CPU1_SA_DQS_DN<3>")
	)
	(segment
		(start 76.03871 -240.634012)
		(end 76.176378 -240.634012)
		(width 0.09525)
		(layer "In11.Cu")
		(net "M_F_CPU1_SA_DQS_DN<3>")
	)
	(segment
		(start 43.232832 -228.731572)
		(end 43.601894 -228.36251)
		(width 0.16002)
		(layer "In11.Cu")
		(net "M_F_CPU1_SA_DQS_DN<3>")
	)
	(segment
		(start 66.68897 -236.891576)
		(end 66.68897 -237.117382)
		(width 0.16002)
		(layer "In11.Cu")
		(net "M_F_CPU1_SA_DQS_DN<3>")
	)
	(segment
		(start 76.176378 -240.634012)
		(end 76.647294 -241.104928)
		(width 0.09525)
		(layer "In11.Cu")
		(net "M_F_CPU1_SA_DQS_DN<3>")
	)
	(segment
		(start 80.471264 -241.724434)
		(end 80.479646 -241.72926)
		(width 0.09525)
		(layer "In11.Cu")
		(net "M_F_CPU1_SA_DQS_DN<3>")
	)
	(segment
		(start 84.181696 -241.702082)
		(end 84.205064 -241.78895)
		(width 0.09525)
		(layer "In11.Cu")
		(net "M_F_CPU1_SA_DQS_DN<3>")
	)
	(segment
		(start 84.205064 -241.78895)
		(end 84.05114 -242.05438)
		(width 0.09525)
		(layer "In11.Cu")
		(net "M_F_CPU1_SA_DQS_DN<3>")
	)
	(segment
		(start 65.340738 -237.042198)
		(end 65.817242 -237.042198)
		(width 0.16002)
		(layer "In11.Cu")
		(net "M_F_CPU1_SA_DQS_DN<3>")
	)
	(segment
		(start 51.145948 -228.36251)
		(end 52.752244 -228.36251)
		(width 0.16002)
		(layer "In11.Cu")
		(net "M_F_CPU1_SA_DQS_DN<3>")
	)
	(segment
		(start 63.967106 -235.668566)
		(end 64.44361 -235.668566)
		(width 0.16002)
		(layer "In11.Cu")
		(net "M_F_CPU1_SA_DQS_DN<3>")
	)
	(segment
		(start 40.968168 -229.212394)
		(end 41.312846 -229.557072)
		(width 0.16002)
		(layer "In11.Cu")
		(net "M_F_CPU1_SA_DQS_DN<3>")
	)
	(segment
		(start 50.332132 -228.731572)
		(end 50.776886 -228.731572)
		(width 0.16002)
		(layer "In11.Cu")
		(net "M_F_CPU1_SA_DQS_DN<3>")
	)
	(segment
		(start 35.688778 -228.731572)
		(end 36.05784 -228.36251)
		(width 0.16002)
		(layer "In11.Cu")
		(net "M_F_CPU1_SA_DQS_DN<3>")
	)
	(segment
		(start 21.981922 -229.361492)
		(end 22.73808 -229.361492)
		(width 0.16002)
		(layer "In11.Cu")
		(net "M_F_CPU1_SA_DQS_DN<3>")
	)
	(segment
		(start 26.87447 -229.557072)
		(end 27.69997 -228.731572)
		(width 0.16002)
		(layer "In11.Cu")
		(net "M_F_CPU1_SA_DQS_DN<3>")
	)
	(segment
		(start 30.120082 -228.36251)
		(end 30.969966 -229.212394)
		(width 0.16002)
		(layer "In11.Cu")
		(net "M_F_CPU1_SA_DQS_DN<3>")
	)
	(segment
		(start 48.512222 -229.212394)
		(end 48.8569 -229.557072)
		(width 0.16002)
		(layer "In11.Cu")
		(net "M_F_CPU1_SA_DQS_DN<3>")
	)
	(segment
		(start 64.917066 -236.141768)
		(end 64.917066 -236.618526)
		(width 0.16002)
		(layer "In11.Cu")
		(net "M_F_CPU1_SA_DQS_DN<3>")
	)
	(segment
		(start 67.190874 -238.41583)
		(end 67.589146 -238.017812)
		(width 0.16002)
		(layer "In11.Cu")
		(net "M_F_CPU1_SA_DQS_DN<3>")
	)
	(segment
		(start 50.776886 -228.731572)
		(end 51.145948 -228.36251)
		(width 0.16002)
		(layer "In11.Cu")
		(net "M_F_CPU1_SA_DQS_DN<3>")
	)
	(segment
		(start 65.817242 -237.042198)
		(end 66.215514 -236.64418)
		(width 0.16002)
		(layer "In11.Cu")
		(net "M_F_CPU1_SA_DQS_DN<3>")
	)
	(segment
		(start 66.215514 -236.64418)
		(end 66.441574 -236.64418)
		(width 0.16002)
		(layer "In11.Cu")
		(net "M_F_CPU1_SA_DQS_DN<3>")
	)
	(segment
		(start 67.66433 -239.36579)
		(end 68.991734 -240.693194)
		(width 0.16002)
		(layer "In11.Cu")
		(net "M_F_CPU1_SA_DQS_DN<3>")
	)
	(arc
		(start 80.102456 -241.72926)
		(mid 80.286231 -241.678488)
		(end 80.471264 -241.724434)
		(width 0.09525)
		(layer "In11.Cu")
		(net "M_F_CPU1_SA_DQS_DN<3>")
	)
	(arc
		(start 81.982564 -241.72926)
		(mid 82.171032 -241.678583)
		(end 82.3595 -241.72926)
		(width 0.09525)
		(layer "In11.Cu")
		(net "M_F_CPU1_SA_DQS_DN<3>")
	)
	(arc
		(start 79.163672 -241.72926)
		(mid 79.347193 -241.678616)
		(end 79.531972 -241.724434)
		(width 0.09525)
		(layer "In11.Cu")
		(net "M_F_CPU1_SA_DQS_DN<3>")
	)
	(arc
		(start 83.862418 -241.72926)
		(mid 84.019016 -241.679971)
		(end 84.181696 -241.702082)
		(width 0.09525)
		(layer "In11.Cu")
		(net "M_F_CPU1_SA_DQS_DN<3>")
	)
	(arc
		(start 79.558388 -241.739674)
		(mid 79.831768 -241.804895)
		(end 80.102456 -241.72926)
		(width 0.09525)
		(layer "In11.Cu")
		(net "M_F_CPU1_SA_DQS_DN<3>")
	)
	(arc
		(start 83.299554 -241.72926)
		(mid 83.580986 -241.805015)
		(end 83.862418 -241.72926)
		(width 0.09525)
		(layer "In11.Cu")
		(net "M_F_CPU1_SA_DQS_DN<3>")
	)
	(arc
		(start 82.3595 -241.72926)
		(mid 82.640932 -241.805015)
		(end 82.922364 -241.72926)
		(width 0.09525)
		(layer "In11.Cu")
		(net "M_F_CPU1_SA_DQS_DN<3>")
	)
	(arc
		(start 78.600046 -241.72926)
		(mid 78.871496 -241.805295)
		(end 79.145638 -241.739674)
		(width 0.09525)
		(layer "In11.Cu")
		(net "M_F_CPU1_SA_DQS_DN<3>")
	)
	(arc
		(start 81.050892 -241.724434)
		(mid 81.235924 -241.67852)
		(end 81.4197 -241.72926)
		(width 0.09525)
		(layer "In11.Cu")
		(net "M_F_CPU1_SA_DQS_DN<3>")
	)
	(arc
		(start 81.4197 -241.72926)
		(mid 81.701132 -241.805015)
		(end 81.982564 -241.72926)
		(width 0.09525)
		(layer "In11.Cu")
		(net "M_F_CPU1_SA_DQS_DN<3>")
	)
	(arc
		(start 78.411324 -241.67846)
		(mid 78.509043 -241.691383)
		(end 78.600046 -241.72926)
		(width 0.09525)
		(layer "In11.Cu")
		(net "M_F_CPU1_SA_DQS_DN<3>")
	)
	(arc
		(start 80.479646 -241.72926)
		(mid 80.761078 -241.805015)
		(end 81.04251 -241.72926)
		(width 0.09525)
		(layer "In11.Cu")
		(net "M_F_CPU1_SA_DQS_DN<3>")
	)
	(arc
		(start 82.922364 -241.72926)
		(mid 83.106139 -241.678488)
		(end 83.291172 -241.724434)
		(width 0.09525)
		(layer "In11.Cu")
		(net "M_F_CPU1_SA_DQS_DN<3>")
	)
	(segment
		(start 84.517992 -237.460282)
		(end 84.05114 -237.194344)
		(width 0.12954)
		(layer "F.Cu")
		(net "M_F_CPU1_SA_DQS_DN<2>")
	)
	(segment
		(start 51.145948 -219.012516)
		(end 52.752244 -219.012516)
		(width 0.16002)
		(layer "In11.Cu")
		(net "M_F_CPU1_SA_DQS_DN<2>")
	)
	(segment
		(start 77.078332 -235.777786)
		(end 78.117954 -236.817408)
		(width 0.09525)
		(layer "In11.Cu")
		(net "M_F_CPU1_SA_DQS_DN<2>")
	)
	(segment
		(start 42.788078 -219.381578)
		(end 43.232832 -219.381578)
		(width 0.16002)
		(layer "In11.Cu")
		(net "M_F_CPU1_SA_DQS_DN<2>")
	)
	(segment
		(start 84.205064 -236.928914)
		(end 84.05114 -237.194344)
		(width 0.09525)
		(layer "In11.Cu")
		(net "M_F_CPU1_SA_DQS_DN<2>")
	)
	(segment
		(start 54.913784 -219.808806)
		(end 54.913784 -219.631006)
		(width 0.16002)
		(layer "In11.Cu")
		(net "M_F_CPU1_SA_DQS_DN<2>")
	)
	(segment
		(start 62.23508 -222.417132)
		(end 62.524894 -222.706946)
		(width 0.16002)
		(layer "In11.Cu")
		(net "M_F_CPU1_SA_DQS_DN<2>")
	)
	(segment
		(start 63.24219 -224.572576)
		(end 73.711308 -235.041694)
		(width 0.16002)
		(layer "In11.Cu")
		(net "M_F_CPU1_SA_DQS_DN<2>")
	)
	(segment
		(start 21.70811 -220.28531)
		(end 21.981922 -220.011498)
		(width 0.16002)
		(layer "In11.Cu")
		(net "M_F_CPU1_SA_DQS_DN<2>")
	)
	(segment
		(start 76.240386 -235.078016)
		(end 76.240386 -235.32084)
		(width 0.09525)
		(layer "In11.Cu")
		(net "M_F_CPU1_SA_DQS_DN<2>")
	)
	(segment
		(start 61.151262 -221.951042)
		(end 61.617352 -222.417132)
		(width 0.16002)
		(layer "In11.Cu")
		(net "M_F_CPU1_SA_DQS_DN<2>")
	)
	(segment
		(start 79.145638 -236.879638)
		(end 79.163672 -236.869224)
		(width 0.09525)
		(layer "In11.Cu")
		(net "M_F_CPU1_SA_DQS_DN<2>")
	)
	(segment
		(start 55.582058 -219.631006)
		(end 55.582058 -220.33484)
		(width 0.16002)
		(layer "In11.Cu")
		(net "M_F_CPU1_SA_DQS_DN<2>")
	)
	(segment
		(start 52.752244 -219.012516)
		(end 52.988972 -219.249244)
		(width 0.16002)
		(layer "In11.Cu")
		(net "M_F_CPU1_SA_DQS_DN<2>")
	)
	(segment
		(start 26.541222 -220.540326)
		(end 27.69997 -219.381578)
		(width 0.16002)
		(layer "In11.Cu")
		(net "M_F_CPU1_SA_DQS_DN<2>")
	)
	(segment
		(start 43.601894 -219.012516)
		(end 45.20819 -219.012516)
		(width 0.16002)
		(layer "In11.Cu")
		(net "M_F_CPU1_SA_DQS_DN<2>")
	)
	(segment
		(start 49.506632 -220.207078)
		(end 50.332132 -219.381578)
		(width 0.16002)
		(layer "In11.Cu")
		(net "M_F_CPU1_SA_DQS_DN<2>")
	)
	(segment
		(start 50.332132 -219.381578)
		(end 50.776886 -219.381578)
		(width 0.16002)
		(layer "In11.Cu")
		(net "M_F_CPU1_SA_DQS_DN<2>")
	)
	(segment
		(start 30.120082 -219.012516)
		(end 30.969966 -219.8624)
		(width 0.16002)
		(layer "In11.Cu")
		(net "M_F_CPU1_SA_DQS_DN<2>")
	)
	(segment
		(start 52.988972 -219.577666)
		(end 53.55717 -220.145864)
		(width 0.16002)
		(layer "In11.Cu")
		(net "M_F_CPU1_SA_DQS_DN<2>")
	)
	(segment
		(start 33.5788 -220.56979)
		(end 34.055812 -220.56979)
		(width 0.16002)
		(layer "In11.Cu")
		(net "M_F_CPU1_SA_DQS_DN<2>")
	)
	(segment
		(start 28.513786 -219.012516)
		(end 30.120082 -219.012516)
		(width 0.16002)
		(layer "In11.Cu")
		(net "M_F_CPU1_SA_DQS_DN<2>")
	)
	(segment
		(start 59.487816 -219.669868)
		(end 59.77763 -219.959682)
		(width 0.16002)
		(layer "In11.Cu")
		(net "M_F_CPU1_SA_DQS_DN<2>")
	)
	(segment
		(start 57.61101 -220.33484)
		(end 57.61101 -219.541598)
		(width 0.16002)
		(layer "In11.Cu")
		(net "M_F_CPU1_SA_DQS_DN<2>")
	)
	(segment
		(start 24.131524 -220.011498)
		(end 24.280622 -219.8624)
		(width 0.16002)
		(layer "In11.Cu")
		(net "M_F_CPU1_SA_DQS_DN<2>")
	)
	(segment
		(start 80.471264 -236.864398)
		(end 80.479646 -236.869224)
		(width 0.09525)
		(layer "In11.Cu")
		(net "M_F_CPU1_SA_DQS_DN<2>")
	)
	(segment
		(start 46.058074 -219.8624)
		(end 48.512222 -219.8624)
		(width 0.16002)
		(layer "In11.Cu")
		(net "M_F_CPU1_SA_DQS_DN<2>")
	)
	(segment
		(start 59.77763 -219.959682)
		(end 59.77763 -220.57741)
		(width 0.16002)
		(layer "In11.Cu")
		(net "M_F_CPU1_SA_DQS_DN<2>")
	)
	(segment
		(start 61.151262 -221.333314)
		(end 61.151262 -221.951042)
		(width 0.16002)
		(layer "In11.Cu")
		(net "M_F_CPU1_SA_DQS_DN<2>")
	)
	(segment
		(start 48.512222 -219.8624)
		(end 48.8569 -220.207078)
		(width 0.16002)
		(layer "In11.Cu")
		(net "M_F_CPU1_SA_DQS_DN<2>")
	)
	(segment
		(start 63.24219 -224.04197)
		(end 63.24219 -224.572576)
		(width 0.16002)
		(layer "In11.Cu")
		(net "M_F_CPU1_SA_DQS_DN<2>")
	)
	(segment
		(start 30.969966 -219.8624)
		(end 32.87141 -219.8624)
		(width 0.16002)
		(layer "In11.Cu")
		(net "M_F_CPU1_SA_DQS_DN<2>")
	)
	(segment
		(start 23.46452 -220.011498)
		(end 24.131524 -220.011498)
		(width 0.16002)
		(layer "In11.Cu")
		(net "M_F_CPU1_SA_DQS_DN<2>")
	)
	(segment
		(start 79.531972 -236.864398)
		(end 79.540354 -236.869224)
		(width 0.09525)
		(layer "In11.Cu")
		(net "M_F_CPU1_SA_DQS_DN<2>")
	)
	(segment
		(start 53.55717 -220.145864)
		(end 54.576726 -220.145864)
		(width 0.16002)
		(layer "In11.Cu")
		(net "M_F_CPU1_SA_DQS_DN<2>")
	)
	(segment
		(start 84.181696 -236.842046)
		(end 84.205064 -236.928914)
		(width 0.09525)
		(layer "In11.Cu")
		(net "M_F_CPU1_SA_DQS_DN<2>")
	)
	(segment
		(start 22.86762 -220.128338)
		(end 23.34768 -220.128338)
		(width 0.16002)
		(layer "In11.Cu")
		(net "M_F_CPU1_SA_DQS_DN<2>")
	)
	(segment
		(start 59.77763 -220.57741)
		(end 60.24372 -221.0435)
		(width 0.16002)
		(layer "In11.Cu")
		(net "M_F_CPU1_SA_DQS_DN<2>")
	)
	(segment
		(start 58.870088 -219.669868)
		(end 59.487816 -219.669868)
		(width 0.16002)
		(layer "In11.Cu")
		(net "M_F_CPU1_SA_DQS_DN<2>")
	)
	(segment
		(start 76.145136 -234.982766)
		(end 76.240386 -235.078016)
		(width 0.09525)
		(layer "In11.Cu")
		(net "M_F_CPU1_SA_DQS_DN<2>")
	)
	(segment
		(start 57.61101 -219.541598)
		(end 57.77103 -219.381578)
		(width 0.16002)
		(layer "In11.Cu")
		(net "M_F_CPU1_SA_DQS_DN<2>")
	)
	(segment
		(start 81.04251 -236.869224)
		(end 81.050892 -236.864398)
		(width 0.09525)
		(layer "In11.Cu")
		(net "M_F_CPU1_SA_DQS_DN<2>")
	)
	(segment
		(start 40.415464 -219.8624)
		(end 41.122854 -220.56979)
		(width 0.16002)
		(layer "In11.Cu")
		(net "M_F_CPU1_SA_DQS_DN<2>")
	)
	(segment
		(start 55.422038 -219.470986)
		(end 55.582058 -219.631006)
		(width 0.16002)
		(layer "In11.Cu")
		(net "M_F_CPU1_SA_DQS_DN<2>")
	)
	(segment
		(start 41.599866 -220.56979)
		(end 42.788078 -219.381578)
		(width 0.16002)
		(layer "In11.Cu")
		(net "M_F_CPU1_SA_DQS_DN<2>")
	)
	(segment
		(start 26.005282 -220.540326)
		(end 26.541222 -220.540326)
		(width 0.16002)
		(layer "In11.Cu")
		(net "M_F_CPU1_SA_DQS_DN<2>")
	)
	(segment
		(start 45.20819 -219.012516)
		(end 46.058074 -219.8624)
		(width 0.16002)
		(layer "In11.Cu")
		(net "M_F_CPU1_SA_DQS_DN<2>")
	)
	(segment
		(start 55.919116 -220.671898)
		(end 57.273952 -220.671898)
		(width 0.16002)
		(layer "In11.Cu")
		(net "M_F_CPU1_SA_DQS_DN<2>")
	)
	(segment
		(start 35.244024 -219.381578)
		(end 35.688778 -219.381578)
		(width 0.16002)
		(layer "In11.Cu")
		(net "M_F_CPU1_SA_DQS_DN<2>")
	)
	(segment
		(start 62.524894 -222.706946)
		(end 62.524894 -223.324674)
		(width 0.16002)
		(layer "In11.Cu")
		(net "M_F_CPU1_SA_DQS_DN<2>")
	)
	(segment
		(start 75.979528 -235.041694)
		(end 76.038456 -234.982766)
		(width 0.09525)
		(layer "In11.Cu")
		(net "M_F_CPU1_SA_DQS_DN<2>")
	)
	(segment
		(start 76.240386 -235.32084)
		(end 76.697332 -235.777786)
		(width 0.09525)
		(layer "In11.Cu")
		(net "M_F_CPU1_SA_DQS_DN<2>")
	)
	(segment
		(start 23.34768 -220.128338)
		(end 23.46452 -220.011498)
		(width 0.16002)
		(layer "In11.Cu")
		(net "M_F_CPU1_SA_DQS_DN<2>")
	)
	(segment
		(start 50.776886 -219.381578)
		(end 51.145948 -219.012516)
		(width 0.16002)
		(layer "In11.Cu")
		(net "M_F_CPU1_SA_DQS_DN<2>")
	)
	(segment
		(start 25.327356 -219.8624)
		(end 26.005282 -220.540326)
		(width 0.16002)
		(layer "In11.Cu")
		(net "M_F_CPU1_SA_DQS_DN<2>")
	)
	(segment
		(start 36.05784 -219.012516)
		(end 37.664136 -219.012516)
		(width 0.16002)
		(layer "In11.Cu")
		(net "M_F_CPU1_SA_DQS_DN<2>")
	)
	(segment
		(start 76.697332 -235.777786)
		(end 77.078332 -235.777786)
		(width 0.09525)
		(layer "In11.Cu")
		(net "M_F_CPU1_SA_DQS_DN<2>")
	)
	(segment
		(start 58.581798 -219.381578)
		(end 58.870088 -219.669868)
		(width 0.16002)
		(layer "In11.Cu")
		(net "M_F_CPU1_SA_DQS_DN<2>")
	)
	(segment
		(start 79.540354 -236.869224)
		(end 79.558388 -236.879638)
		(width 0.09525)
		(layer "In11.Cu")
		(net "M_F_CPU1_SA_DQS_DN<2>")
	)
	(segment
		(start 60.24372 -221.0435)
		(end 60.861448 -221.0435)
		(width 0.16002)
		(layer "In11.Cu")
		(net "M_F_CPU1_SA_DQS_DN<2>")
	)
	(segment
		(start 52.988972 -219.249244)
		(end 52.988972 -219.577666)
		(width 0.16002)
		(layer "In11.Cu")
		(net "M_F_CPU1_SA_DQS_DN<2>")
	)
	(segment
		(start 54.913784 -219.631006)
		(end 55.073804 -219.470986)
		(width 0.16002)
		(layer "In11.Cu")
		(net "M_F_CPU1_SA_DQS_DN<2>")
	)
	(segment
		(start 61.617352 -222.417132)
		(end 62.23508 -222.417132)
		(width 0.16002)
		(layer "In11.Cu")
		(net "M_F_CPU1_SA_DQS_DN<2>")
	)
	(segment
		(start 76.038456 -234.982766)
		(end 76.145136 -234.982766)
		(width 0.09525)
		(layer "In11.Cu")
		(net "M_F_CPU1_SA_DQS_DN<2>")
	)
	(segment
		(start 43.232832 -219.381578)
		(end 43.601894 -219.012516)
		(width 0.16002)
		(layer "In11.Cu")
		(net "M_F_CPU1_SA_DQS_DN<2>")
	)
	(segment
		(start 24.280622 -219.8624)
		(end 25.327356 -219.8624)
		(width 0.16002)
		(layer "In11.Cu")
		(net "M_F_CPU1_SA_DQS_DN<2>")
	)
	(segment
		(start 37.664136 -219.012516)
		(end 38.51402 -219.8624)
		(width 0.16002)
		(layer "In11.Cu")
		(net "M_F_CPU1_SA_DQS_DN<2>")
	)
	(segment
		(start 57.273952 -220.671898)
		(end 57.61101 -220.33484)
		(width 0.16002)
		(layer "In11.Cu")
		(net "M_F_CPU1_SA_DQS_DN<2>")
	)
	(segment
		(start 35.688778 -219.381578)
		(end 36.05784 -219.012516)
		(width 0.16002)
		(layer "In11.Cu")
		(net "M_F_CPU1_SA_DQS_DN<2>")
	)
	(segment
		(start 57.77103 -219.381578)
		(end 58.581798 -219.381578)
		(width 0.16002)
		(layer "In11.Cu")
		(net "M_F_CPU1_SA_DQS_DN<2>")
	)
	(segment
		(start 60.861448 -221.0435)
		(end 61.151262 -221.333314)
		(width 0.16002)
		(layer "In11.Cu")
		(net "M_F_CPU1_SA_DQS_DN<2>")
	)
	(segment
		(start 83.291172 -236.864398)
		(end 83.299554 -236.869224)
		(width 0.09525)
		(layer "In11.Cu")
		(net "M_F_CPU1_SA_DQS_DN<2>")
	)
	(segment
		(start 32.87141 -219.8624)
		(end 33.5788 -220.56979)
		(width 0.16002)
		(layer "In11.Cu")
		(net "M_F_CPU1_SA_DQS_DN<2>")
	)
	(segment
		(start 73.711308 -235.041694)
		(end 75.955906 -235.041694)
		(width 0.16002)
		(layer "In11.Cu")
		(net "M_F_CPU1_SA_DQS_DN<2>")
	)
	(segment
		(start 75.955906 -235.041694)
		(end 75.979528 -235.041694)
		(width 0.09525)
		(layer "In11.Cu")
		(net "M_F_CPU1_SA_DQS_DN<2>")
	)
	(segment
		(start 55.073804 -219.470986)
		(end 55.422038 -219.470986)
		(width 0.16002)
		(layer "In11.Cu")
		(net "M_F_CPU1_SA_DQS_DN<2>")
	)
	(segment
		(start 34.055812 -220.56979)
		(end 35.244024 -219.381578)
		(width 0.16002)
		(layer "In11.Cu")
		(net "M_F_CPU1_SA_DQS_DN<2>")
	)
	(segment
		(start 22.75078 -220.011498)
		(end 22.86762 -220.128338)
		(width 0.16002)
		(layer "In11.Cu")
		(net "M_F_CPU1_SA_DQS_DN<2>")
	)
	(segment
		(start 41.122854 -220.56979)
		(end 41.599866 -220.56979)
		(width 0.16002)
		(layer "In11.Cu")
		(net "M_F_CPU1_SA_DQS_DN<2>")
	)
	(segment
		(start 48.8569 -220.207078)
		(end 49.506632 -220.207078)
		(width 0.16002)
		(layer "In11.Cu")
		(net "M_F_CPU1_SA_DQS_DN<2>")
	)
	(segment
		(start 78.117954 -236.817408)
		(end 78.41107 -236.817408)
		(width 0.09525)
		(layer "In11.Cu")
		(net "M_F_CPU1_SA_DQS_DN<2>")
	)
	(segment
		(start 62.524894 -223.324674)
		(end 63.24219 -224.04197)
		(width 0.16002)
		(layer "In11.Cu")
		(net "M_F_CPU1_SA_DQS_DN<2>")
	)
	(segment
		(start 27.69997 -219.381578)
		(end 28.144724 -219.381578)
		(width 0.16002)
		(layer "In11.Cu")
		(net "M_F_CPU1_SA_DQS_DN<2>")
	)
	(segment
		(start 21.981922 -220.011498)
		(end 22.75078 -220.011498)
		(width 0.16002)
		(layer "In11.Cu")
		(net "M_F_CPU1_SA_DQS_DN<2>")
	)
	(segment
		(start 38.51402 -219.8624)
		(end 40.415464 -219.8624)
		(width 0.16002)
		(layer "In11.Cu")
		(net "M_F_CPU1_SA_DQS_DN<2>")
	)
	(segment
		(start 55.582058 -220.33484)
		(end 55.919116 -220.671898)
		(width 0.16002)
		(layer "In11.Cu")
		(net "M_F_CPU1_SA_DQS_DN<2>")
	)
	(segment
		(start 54.576726 -220.145864)
		(end 54.913784 -219.808806)
		(width 0.16002)
		(layer "In11.Cu")
		(net "M_F_CPU1_SA_DQS_DN<2>")
	)
	(segment
		(start 28.144724 -219.381578)
		(end 28.513786 -219.012516)
		(width 0.16002)
		(layer "In11.Cu")
		(net "M_F_CPU1_SA_DQS_DN<2>")
	)
	(arc
		(start 81.050892 -236.864398)
		(mid 81.235924 -236.818484)
		(end 81.4197 -236.869224)
		(width 0.09525)
		(layer "In11.Cu")
		(net "M_F_CPU1_SA_DQS_DN<2>")
	)
	(arc
		(start 83.299554 -236.869224)
		(mid 83.580986 -236.944979)
		(end 83.862418 -236.869224)
		(width 0.09525)
		(layer "In11.Cu")
		(net "M_F_CPU1_SA_DQS_DN<2>")
	)
	(arc
		(start 78.41107 -236.817408)
		(mid 78.508999 -236.83078)
		(end 78.600046 -236.869224)
		(width 0.09525)
		(layer "In11.Cu")
		(net "M_F_CPU1_SA_DQS_DN<2>")
	)
	(arc
		(start 79.163672 -236.869224)
		(mid 79.347193 -236.81858)
		(end 79.531972 -236.864398)
		(width 0.09525)
		(layer "In11.Cu")
		(net "M_F_CPU1_SA_DQS_DN<2>")
	)
	(arc
		(start 82.3595 -236.869224)
		(mid 82.640932 -236.944979)
		(end 82.922364 -236.869224)
		(width 0.09525)
		(layer "In11.Cu")
		(net "M_F_CPU1_SA_DQS_DN<2>")
	)
	(arc
		(start 80.102456 -236.869224)
		(mid 80.286231 -236.818452)
		(end 80.471264 -236.864398)
		(width 0.09525)
		(layer "In11.Cu")
		(net "M_F_CPU1_SA_DQS_DN<2>")
	)
	(arc
		(start 81.982564 -236.869224)
		(mid 82.171032 -236.818547)
		(end 82.3595 -236.869224)
		(width 0.09525)
		(layer "In11.Cu")
		(net "M_F_CPU1_SA_DQS_DN<2>")
	)
	(arc
		(start 83.862418 -236.869224)
		(mid 84.019016 -236.819935)
		(end 84.181696 -236.842046)
		(width 0.09525)
		(layer "In11.Cu")
		(net "M_F_CPU1_SA_DQS_DN<2>")
	)
	(arc
		(start 79.558388 -236.879638)
		(mid 79.831768 -236.944859)
		(end 80.102456 -236.869224)
		(width 0.09525)
		(layer "In11.Cu")
		(net "M_F_CPU1_SA_DQS_DN<2>")
	)
	(arc
		(start 80.479646 -236.869224)
		(mid 80.761078 -236.944979)
		(end 81.04251 -236.869224)
		(width 0.09525)
		(layer "In11.Cu")
		(net "M_F_CPU1_SA_DQS_DN<2>")
	)
	(arc
		(start 81.4197 -236.869224)
		(mid 81.701132 -236.944979)
		(end 81.982564 -236.869224)
		(width 0.09525)
		(layer "In11.Cu")
		(net "M_F_CPU1_SA_DQS_DN<2>")
	)
	(arc
		(start 82.922364 -236.869224)
		(mid 83.106139 -236.818452)
		(end 83.291172 -236.864398)
		(width 0.09525)
		(layer "In11.Cu")
		(net "M_F_CPU1_SA_DQS_DN<2>")
	)
	(arc
		(start 78.600046 -236.869224)
		(mid 78.871496 -236.945259)
		(end 79.145638 -236.879638)
		(width 0.09525)
		(layer "In11.Cu")
		(net "M_F_CPU1_SA_DQS_DN<2>")
	)
	(segment
		(start 84.517992 -232.600246)
		(end 84.05114 -232.334308)
		(width 0.12954)
		(layer "F.Cu")
		(net "M_F_CPU1_SA_DQS_DN<1>")
	)
	(segment
		(start 76.51877 -229.810564)
		(end 76.956666 -229.810564)
		(width 0.09525)
		(layer "In11.Cu")
		(net "M_F_CPU1_SA_DQS_DN<1>")
	)
	(segment
		(start 66.0908 -216.784936)
		(end 66.0908 -217.010996)
		(width 0.16002)
		(layer "In11.Cu")
		(net "M_F_CPU1_SA_DQS_DN<1>")
	)
	(segment
		(start 67.464432 -218.158568)
		(end 67.464432 -218.384628)
		(width 0.16002)
		(layer "In11.Cu")
		(net "M_F_CPU1_SA_DQS_DN<1>")
	)
	(segment
		(start 65.844166 -216.538302)
		(end 66.0908 -216.784936)
		(width 0.16002)
		(layer "In11.Cu")
		(net "M_F_CPU1_SA_DQS_DN<1>")
	)
	(segment
		(start 41.962578 -210.857084)
		(end 42.788078 -210.031584)
		(width 0.16002)
		(layer "In11.Cu")
		(net "M_F_CPU1_SA_DQS_DN<1>")
	)
	(segment
		(start 65.760092 -217.818208)
		(end 66.184526 -218.242642)
		(width 0.16002)
		(layer "In11.Cu")
		(net "M_F_CPU1_SA_DQS_DN<1>")
	)
	(segment
		(start 79.540354 -232.009188)
		(end 79.558388 -232.019602)
		(width 0.09525)
		(layer "In11.Cu")
		(net "M_F_CPU1_SA_DQS_DN<1>")
	)
	(segment
		(start 31.566866 -210.629246)
		(end 32.046926 -210.629246)
		(width 0.16002)
		(layer "In11.Cu")
		(net "M_F_CPU1_SA_DQS_DN<1>")
	)
	(segment
		(start 32.163766 -210.512406)
		(end 33.424114 -210.512406)
		(width 0.16002)
		(layer "In11.Cu")
		(net "M_F_CPU1_SA_DQS_DN<1>")
	)
	(segment
		(start 68.034662 -219.616274)
		(end 68.36537 -219.285566)
		(width 0.16002)
		(layer "In11.Cu")
		(net "M_F_CPU1_SA_DQS_DN<1>")
	)
	(segment
		(start 56.093868 -211.24545)
		(end 56.662066 -211.24545)
		(width 0.16002)
		(layer "In11.Cu")
		(net "M_F_CPU1_SA_DQS_DN<1>")
	)
	(segment
		(start 55.376064 -210.527646)
		(end 56.093868 -211.24545)
		(width 0.16002)
		(layer "In11.Cu")
		(net "M_F_CPU1_SA_DQS_DN<1>")
	)
	(segment
		(start 67.133724 -219.19184)
		(end 67.558158 -219.616274)
		(width 0.16002)
		(layer "In11.Cu")
		(net "M_F_CPU1_SA_DQS_DN<1>")
	)
	(segment
		(start 34.418524 -210.857084)
		(end 35.244024 -210.031584)
		(width 0.16002)
		(layer "In11.Cu")
		(net "M_F_CPU1_SA_DQS_DN<1>")
	)
	(segment
		(start 75.758802 -229.134416)
		(end 75.842622 -229.134416)
		(width 0.09525)
		(layer "In11.Cu")
		(net "M_F_CPU1_SA_DQS_DN<1>")
	)
	(segment
		(start 50.776886 -210.031584)
		(end 51.145948 -209.662522)
		(width 0.16002)
		(layer "In11.Cu")
		(net "M_F_CPU1_SA_DQS_DN<1>")
	)
	(segment
		(start 43.232832 -210.031584)
		(end 43.601894 -209.662522)
		(width 0.16002)
		(layer "In11.Cu")
		(net "M_F_CPU1_SA_DQS_DN<1>")
	)
	(segment
		(start 66.991738 -217.911934)
		(end 67.217798 -217.911934)
		(width 0.16002)
		(layer "In11.Cu")
		(net "M_F_CPU1_SA_DQS_DN<1>")
	)
	(segment
		(start 53.946806 -210.857084)
		(end 54.523132 -210.857084)
		(width 0.16002)
		(layer "In11.Cu")
		(net "M_F_CPU1_SA_DQS_DN<1>")
	)
	(segment
		(start 32.046926 -210.629246)
		(end 32.163766 -210.512406)
		(width 0.16002)
		(layer "In11.Cu")
		(net "M_F_CPU1_SA_DQS_DN<1>")
	)
	(segment
		(start 81.04251 -232.009188)
		(end 81.050892 -232.004362)
		(width 0.09525)
		(layer "In11.Cu")
		(net "M_F_CPU1_SA_DQS_DN<1>")
	)
	(segment
		(start 77.294486 -230.85171)
		(end 78.250542 -231.807766)
		(width 0.09525)
		(layer "In11.Cu")
		(net "M_F_CPU1_SA_DQS_DN<1>")
	)
	(segment
		(start 59.337448 -210.031584)
		(end 64.717168 -215.411304)
		(width 0.16002)
		(layer "In11.Cu")
		(net "M_F_CPU1_SA_DQS_DN<1>")
	)
	(segment
		(start 45.20819 -209.662522)
		(end 46.058074 -210.512406)
		(width 0.16002)
		(layer "In11.Cu")
		(net "M_F_CPU1_SA_DQS_DN<1>")
	)
	(segment
		(start 35.688778 -210.031584)
		(end 36.05784 -209.662522)
		(width 0.16002)
		(layer "In11.Cu")
		(net "M_F_CPU1_SA_DQS_DN<1>")
	)
	(segment
		(start 49.506632 -210.857084)
		(end 50.332132 -210.031584)
		(width 0.16002)
		(layer "In11.Cu")
		(net "M_F_CPU1_SA_DQS_DN<1>")
	)
	(segment
		(start 75.742038 -229.117652)
		(end 75.758802 -229.134416)
		(width 0.09525)
		(layer "In11.Cu")
		(net "M_F_CPU1_SA_DQS_DN<1>")
	)
	(segment
		(start 79.145638 -232.019602)
		(end 79.163672 -232.009188)
		(width 0.09525)
		(layer "In11.Cu")
		(net "M_F_CPU1_SA_DQS_DN<1>")
	)
	(segment
		(start 64.717168 -215.637364)
		(end 64.38646 -215.968072)
		(width 0.16002)
		(layer "In11.Cu")
		(net "M_F_CPU1_SA_DQS_DN<1>")
	)
	(segment
		(start 68.59143 -219.285566)
		(end 68.92925 -219.623386)
		(width 0.16002)
		(layer "In11.Cu")
		(net "M_F_CPU1_SA_DQS_DN<1>")
	)
	(segment
		(start 77.294486 -230.148384)
		(end 77.294486 -230.85171)
		(width 0.09525)
		(layer "In11.Cu")
		(net "M_F_CPU1_SA_DQS_DN<1>")
	)
	(segment
		(start 37.664136 -209.662522)
		(end 38.51402 -210.512406)
		(width 0.16002)
		(layer "In11.Cu")
		(net "M_F_CPU1_SA_DQS_DN<1>")
	)
	(segment
		(start 83.291172 -232.004362)
		(end 83.299554 -232.009188)
		(width 0.09525)
		(layer "In11.Cu")
		(net "M_F_CPU1_SA_DQS_DN<1>")
	)
	(segment
		(start 50.332132 -210.031584)
		(end 50.776886 -210.031584)
		(width 0.16002)
		(layer "In11.Cu")
		(net "M_F_CPU1_SA_DQS_DN<1>")
	)
	(segment
		(start 40.968168 -210.512406)
		(end 41.312846 -210.857084)
		(width 0.16002)
		(layer "In11.Cu")
		(net "M_F_CPU1_SA_DQS_DN<1>")
	)
	(segment
		(start 67.217798 -217.911934)
		(end 67.464432 -218.158568)
		(width 0.16002)
		(layer "In11.Cu")
		(net "M_F_CPU1_SA_DQS_DN<1>")
	)
	(segment
		(start 75.842622 -229.134416)
		(end 76.51877 -229.810564)
		(width 0.09525)
		(layer "In11.Cu")
		(net "M_F_CPU1_SA_DQS_DN<1>")
	)
	(segment
		(start 67.464432 -218.384628)
		(end 67.133724 -218.715336)
		(width 0.16002)
		(layer "In11.Cu")
		(net "M_F_CPU1_SA_DQS_DN<1>")
	)
	(segment
		(start 43.601894 -209.662522)
		(end 45.20819 -209.662522)
		(width 0.16002)
		(layer "In11.Cu")
		(net "M_F_CPU1_SA_DQS_DN<1>")
	)
	(segment
		(start 84.181696 -231.98201)
		(end 84.205064 -232.068878)
		(width 0.09525)
		(layer "In11.Cu")
		(net "M_F_CPU1_SA_DQS_DN<1>")
	)
	(segment
		(start 68.92925 -219.623386)
		(end 68.92925 -222.304864)
		(width 0.16002)
		(layer "In11.Cu")
		(net "M_F_CPU1_SA_DQS_DN<1>")
	)
	(segment
		(start 66.0908 -217.010996)
		(end 65.760092 -217.341704)
		(width 0.16002)
		(layer "In11.Cu")
		(net "M_F_CPU1_SA_DQS_DN<1>")
	)
	(segment
		(start 65.287398 -216.86901)
		(end 65.618106 -216.538302)
		(width 0.16002)
		(layer "In11.Cu")
		(net "M_F_CPU1_SA_DQS_DN<1>")
	)
	(segment
		(start 68.92925 -222.304864)
		(end 75.742038 -229.117652)
		(width 0.16002)
		(layer "In11.Cu")
		(net "M_F_CPU1_SA_DQS_DN<1>")
	)
	(segment
		(start 21.70811 -210.935316)
		(end 21.981922 -210.661504)
		(width 0.16002)
		(layer "In11.Cu")
		(net "M_F_CPU1_SA_DQS_DN<1>")
	)
	(segment
		(start 79.531972 -232.004362)
		(end 79.540354 -232.009188)
		(width 0.09525)
		(layer "In11.Cu")
		(net "M_F_CPU1_SA_DQS_DN<1>")
	)
	(segment
		(start 24.131524 -210.661504)
		(end 24.280622 -210.512406)
		(width 0.16002)
		(layer "In11.Cu")
		(net "M_F_CPU1_SA_DQS_DN<1>")
	)
	(segment
		(start 66.184526 -218.242642)
		(end 66.66103 -218.242642)
		(width 0.16002)
		(layer "In11.Cu")
		(net "M_F_CPU1_SA_DQS_DN<1>")
	)
	(segment
		(start 41.312846 -210.857084)
		(end 41.962578 -210.857084)
		(width 0.16002)
		(layer "In11.Cu")
		(net "M_F_CPU1_SA_DQS_DN<1>")
	)
	(segment
		(start 24.280622 -210.512406)
		(end 25.88006 -210.512406)
		(width 0.16002)
		(layer "In11.Cu")
		(net "M_F_CPU1_SA_DQS_DN<1>")
	)
	(segment
		(start 26.224738 -210.857084)
		(end 26.87447 -210.857084)
		(width 0.16002)
		(layer "In11.Cu")
		(net "M_F_CPU1_SA_DQS_DN<1>")
	)
	(segment
		(start 22.81682 -210.778344)
		(end 23.29688 -210.778344)
		(width 0.16002)
		(layer "In11.Cu")
		(net "M_F_CPU1_SA_DQS_DN<1>")
	)
	(segment
		(start 27.69997 -210.031584)
		(end 28.144724 -210.031584)
		(width 0.16002)
		(layer "In11.Cu")
		(net "M_F_CPU1_SA_DQS_DN<1>")
	)
	(segment
		(start 57.875932 -210.031584)
		(end 59.337448 -210.031584)
		(width 0.16002)
		(layer "In11.Cu")
		(net "M_F_CPU1_SA_DQS_DN<1>")
	)
	(segment
		(start 66.66103 -218.242642)
		(end 66.991738 -217.911934)
		(width 0.16002)
		(layer "In11.Cu")
		(net "M_F_CPU1_SA_DQS_DN<1>")
	)
	(segment
		(start 21.981922 -210.661504)
		(end 22.69998 -210.661504)
		(width 0.16002)
		(layer "In11.Cu")
		(net "M_F_CPU1_SA_DQS_DN<1>")
	)
	(segment
		(start 48.8569 -210.857084)
		(end 49.506632 -210.857084)
		(width 0.16002)
		(layer "In11.Cu")
		(net "M_F_CPU1_SA_DQS_DN<1>")
	)
	(segment
		(start 65.618106 -216.538302)
		(end 65.844166 -216.538302)
		(width 0.16002)
		(layer "In11.Cu")
		(net "M_F_CPU1_SA_DQS_DN<1>")
	)
	(segment
		(start 30.969966 -210.512406)
		(end 31.450026 -210.512406)
		(width 0.16002)
		(layer "In11.Cu")
		(net "M_F_CPU1_SA_DQS_DN<1>")
	)
	(segment
		(start 31.450026 -210.512406)
		(end 31.566866 -210.629246)
		(width 0.16002)
		(layer "In11.Cu")
		(net "M_F_CPU1_SA_DQS_DN<1>")
	)
	(segment
		(start 67.133724 -218.715336)
		(end 67.133724 -219.19184)
		(width 0.16002)
		(layer "In11.Cu")
		(net "M_F_CPU1_SA_DQS_DN<1>")
	)
	(segment
		(start 54.85257 -210.527646)
		(end 55.376064 -210.527646)
		(width 0.16002)
		(layer "In11.Cu")
		(net "M_F_CPU1_SA_DQS_DN<1>")
	)
	(segment
		(start 80.471264 -232.004362)
		(end 80.479646 -232.009188)
		(width 0.09525)
		(layer "In11.Cu")
		(net "M_F_CPU1_SA_DQS_DN<1>")
	)
	(segment
		(start 25.88006 -210.512406)
		(end 26.224738 -210.857084)
		(width 0.16002)
		(layer "In11.Cu")
		(net "M_F_CPU1_SA_DQS_DN<1>")
	)
	(segment
		(start 84.205064 -232.068878)
		(end 84.05114 -232.334308)
		(width 0.09525)
		(layer "In11.Cu")
		(net "M_F_CPU1_SA_DQS_DN<1>")
	)
	(segment
		(start 76.956666 -229.810564)
		(end 77.294486 -230.148384)
		(width 0.09525)
		(layer "In11.Cu")
		(net "M_F_CPU1_SA_DQS_DN<1>")
	)
	(segment
		(start 54.523132 -210.857084)
		(end 54.85257 -210.527646)
		(width 0.16002)
		(layer "In11.Cu")
		(net "M_F_CPU1_SA_DQS_DN<1>")
	)
	(segment
		(start 68.36537 -219.285566)
		(end 68.59143 -219.285566)
		(width 0.16002)
		(layer "In11.Cu")
		(net "M_F_CPU1_SA_DQS_DN<1>")
	)
	(segment
		(start 36.05784 -209.662522)
		(end 37.664136 -209.662522)
		(width 0.16002)
		(layer "In11.Cu")
		(net "M_F_CPU1_SA_DQS_DN<1>")
	)
	(segment
		(start 22.69998 -210.661504)
		(end 22.81682 -210.778344)
		(width 0.16002)
		(layer "In11.Cu")
		(net "M_F_CPU1_SA_DQS_DN<1>")
	)
	(segment
		(start 33.768792 -210.857084)
		(end 34.418524 -210.857084)
		(width 0.16002)
		(layer "In11.Cu")
		(net "M_F_CPU1_SA_DQS_DN<1>")
	)
	(segment
		(start 64.717168 -215.411304)
		(end 64.717168 -215.637364)
		(width 0.16002)
		(layer "In11.Cu")
		(net "M_F_CPU1_SA_DQS_DN<1>")
	)
	(segment
		(start 48.512222 -210.512406)
		(end 48.8569 -210.857084)
		(width 0.16002)
		(layer "In11.Cu")
		(net "M_F_CPU1_SA_DQS_DN<1>")
	)
	(segment
		(start 42.788078 -210.031584)
		(end 43.232832 -210.031584)
		(width 0.16002)
		(layer "In11.Cu")
		(net "M_F_CPU1_SA_DQS_DN<1>")
	)
	(segment
		(start 38.51402 -210.512406)
		(end 40.968168 -210.512406)
		(width 0.16002)
		(layer "In11.Cu")
		(net "M_F_CPU1_SA_DQS_DN<1>")
	)
	(segment
		(start 67.558158 -219.616274)
		(end 68.034662 -219.616274)
		(width 0.16002)
		(layer "In11.Cu")
		(net "M_F_CPU1_SA_DQS_DN<1>")
	)
	(segment
		(start 30.120082 -209.662522)
		(end 30.969966 -210.512406)
		(width 0.16002)
		(layer "In11.Cu")
		(net "M_F_CPU1_SA_DQS_DN<1>")
	)
	(segment
		(start 56.662066 -211.24545)
		(end 57.875932 -210.031584)
		(width 0.16002)
		(layer "In11.Cu")
		(net "M_F_CPU1_SA_DQS_DN<1>")
	)
	(segment
		(start 65.760092 -217.341704)
		(end 65.760092 -217.818208)
		(width 0.16002)
		(layer "In11.Cu")
		(net "M_F_CPU1_SA_DQS_DN<1>")
	)
	(segment
		(start 78.372208 -231.807766)
		(end 78.485492 -231.92105)
		(width 0.09525)
		(layer "In11.Cu")
		(net "M_F_CPU1_SA_DQS_DN<1>")
	)
	(segment
		(start 28.144724 -210.031584)
		(end 28.513786 -209.662522)
		(width 0.16002)
		(layer "In11.Cu")
		(net "M_F_CPU1_SA_DQS_DN<1>")
	)
	(segment
		(start 64.810894 -216.86901)
		(end 65.287398 -216.86901)
		(width 0.16002)
		(layer "In11.Cu")
		(net "M_F_CPU1_SA_DQS_DN<1>")
	)
	(segment
		(start 35.244024 -210.031584)
		(end 35.688778 -210.031584)
		(width 0.16002)
		(layer "In11.Cu")
		(net "M_F_CPU1_SA_DQS_DN<1>")
	)
	(segment
		(start 51.145948 -209.662522)
		(end 52.752244 -209.662522)
		(width 0.16002)
		(layer "In11.Cu")
		(net "M_F_CPU1_SA_DQS_DN<1>")
	)
	(segment
		(start 52.752244 -209.662522)
		(end 53.946806 -210.857084)
		(width 0.16002)
		(layer "In11.Cu")
		(net "M_F_CPU1_SA_DQS_DN<1>")
	)
	(segment
		(start 64.38646 -216.444576)
		(end 64.810894 -216.86901)
		(width 0.16002)
		(layer "In11.Cu")
		(net "M_F_CPU1_SA_DQS_DN<1>")
	)
	(segment
		(start 33.424114 -210.512406)
		(end 33.768792 -210.857084)
		(width 0.16002)
		(layer "In11.Cu")
		(net "M_F_CPU1_SA_DQS_DN<1>")
	)
	(segment
		(start 23.41372 -210.661504)
		(end 24.131524 -210.661504)
		(width 0.16002)
		(layer "In11.Cu")
		(net "M_F_CPU1_SA_DQS_DN<1>")
	)
	(segment
		(start 23.29688 -210.778344)
		(end 23.41372 -210.661504)
		(width 0.16002)
		(layer "In11.Cu")
		(net "M_F_CPU1_SA_DQS_DN<1>")
	)
	(segment
		(start 64.38646 -215.968072)
		(end 64.38646 -216.444576)
		(width 0.16002)
		(layer "In11.Cu")
		(net "M_F_CPU1_SA_DQS_DN<1>")
	)
	(segment
		(start 78.250542 -231.807766)
		(end 78.372208 -231.807766)
		(width 0.09525)
		(layer "In11.Cu")
		(net "M_F_CPU1_SA_DQS_DN<1>")
	)
	(segment
		(start 46.058074 -210.512406)
		(end 48.512222 -210.512406)
		(width 0.16002)
		(layer "In11.Cu")
		(net "M_F_CPU1_SA_DQS_DN<1>")
	)
	(segment
		(start 28.513786 -209.662522)
		(end 30.120082 -209.662522)
		(width 0.16002)
		(layer "In11.Cu")
		(net "M_F_CPU1_SA_DQS_DN<1>")
	)
	(segment
		(start 26.87447 -210.857084)
		(end 27.69997 -210.031584)
		(width 0.16002)
		(layer "In11.Cu")
		(net "M_F_CPU1_SA_DQS_DN<1>")
	)
	(arc
		(start 82.3595 -232.009188)
		(mid 82.640932 -232.084943)
		(end 82.922364 -232.009188)
		(width 0.09525)
		(layer "In11.Cu")
		(net "M_F_CPU1_SA_DQS_DN<1>")
	)
	(arc
		(start 83.862418 -232.009188)
		(mid 84.019016 -231.959899)
		(end 84.181696 -231.98201)
		(width 0.09525)
		(layer "In11.Cu")
		(net "M_F_CPU1_SA_DQS_DN<1>")
	)
	(arc
		(start 81.982564 -232.009188)
		(mid 82.171032 -231.958511)
		(end 82.3595 -232.009188)
		(width 0.09525)
		(layer "In11.Cu")
		(net "M_F_CPU1_SA_DQS_DN<1>")
	)
	(arc
		(start 79.163672 -232.009188)
		(mid 79.347193 -231.958544)
		(end 79.531972 -232.004362)
		(width 0.09525)
		(layer "In11.Cu")
		(net "M_F_CPU1_SA_DQS_DN<1>")
	)
	(arc
		(start 83.299554 -232.009188)
		(mid 83.580986 -232.084943)
		(end 83.862418 -232.009188)
		(width 0.09525)
		(layer "In11.Cu")
		(net "M_F_CPU1_SA_DQS_DN<1>")
	)
	(arc
		(start 80.102456 -232.009188)
		(mid 80.286231 -231.958416)
		(end 80.471264 -232.004362)
		(width 0.09525)
		(layer "In11.Cu")
		(net "M_F_CPU1_SA_DQS_DN<1>")
	)
	(arc
		(start 81.4197 -232.009188)
		(mid 81.701132 -232.084943)
		(end 81.982564 -232.009188)
		(width 0.09525)
		(layer "In11.Cu")
		(net "M_F_CPU1_SA_DQS_DN<1>")
	)
	(arc
		(start 78.485492 -231.92105)
		(mid 78.799325 -232.079228)
		(end 79.145638 -232.019602)
		(width 0.09525)
		(layer "In11.Cu")
		(net "M_F_CPU1_SA_DQS_DN<1>")
	)
	(arc
		(start 81.050892 -232.004362)
		(mid 81.235924 -231.958448)
		(end 81.4197 -232.009188)
		(width 0.09525)
		(layer "In11.Cu")
		(net "M_F_CPU1_SA_DQS_DN<1>")
	)
	(arc
		(start 79.558388 -232.019602)
		(mid 79.831768 -232.084823)
		(end 80.102456 -232.009188)
		(width 0.09525)
		(layer "In11.Cu")
		(net "M_F_CPU1_SA_DQS_DN<1>")
	)
	(arc
		(start 82.922364 -232.009188)
		(mid 83.106139 -231.958416)
		(end 83.291172 -232.004362)
		(width 0.09525)
		(layer "In11.Cu")
		(net "M_F_CPU1_SA_DQS_DN<1>")
	)
	(arc
		(start 80.479646 -232.009188)
		(mid 80.761078 -232.084943)
		(end 81.04251 -232.009188)
		(width 0.09525)
		(layer "In11.Cu")
		(net "M_F_CPU1_SA_DQS_DN<1>")
	)
	(segment
		(start 84.517992 -227.740464)
		(end 84.05114 -227.474526)
		(width 0.12954)
		(layer "F.Cu")
		(net "M_F_CPU1_SA_DQS_DN<0>")
	)
	(segment
		(start 67.544188 -209.856324)
		(end 68.020692 -209.856324)
		(width 0.16002)
		(layer "In11.Cu")
		(net "M_F_CPU1_SA_DQS_DN<0>")
	)
	(segment
		(start 21.70811 -201.585322)
		(end 21.981922 -201.31151)
		(width 0.16002)
		(layer "In11.Cu")
		(net "M_F_CPU1_SA_DQS_DN<0>")
	)
	(segment
		(start 78.137512 -223.10344)
		(end 78.137512 -223.103694)
		(width 0.09525)
		(layer "In11.Cu")
		(net "M_F_CPU1_SA_DQS_DN<0>")
	)
	(segment
		(start 32.046926 -201.279252)
		(end 32.163766 -201.162412)
		(width 0.16002)
		(layer "In11.Cu")
		(net "M_F_CPU1_SA_DQS_DN<0>")
	)
	(segment
		(start 78.564486 -223.888808)
		(end 78.566518 -223.890078)
		(width 0.09525)
		(layer "In11.Cu")
		(net "M_F_CPU1_SA_DQS_DN<0>")
	)
	(segment
		(start 21.981922 -201.31151)
		(end 22.461982 -201.31151)
		(width 0.16002)
		(layer "In11.Cu")
		(net "M_F_CPU1_SA_DQS_DN<0>")
	)
	(segment
		(start 36.05784 -200.312528)
		(end 37.664136 -200.312528)
		(width 0.16002)
		(layer "In11.Cu")
		(net "M_F_CPU1_SA_DQS_DN<0>")
	)
	(segment
		(start 28.513786 -200.312528)
		(end 30.120082 -200.312528)
		(width 0.16002)
		(layer "In11.Cu")
		(net "M_F_CPU1_SA_DQS_DN<0>")
	)
	(segment
		(start 77.606144 -222.25508)
		(end 77.689964 -222.25508)
		(width 0.09525)
		(layer "In11.Cu")
		(net "M_F_CPU1_SA_DQS_DN<0>")
	)
	(segment
		(start 80.471264 -227.14458)
		(end 80.479646 -227.149406)
		(width 0.09525)
		(layer "In11.Cu")
		(net "M_F_CPU1_SA_DQS_DN<0>")
	)
	(segment
		(start 26.224738 -201.50709)
		(end 26.87447 -201.50709)
		(width 0.16002)
		(layer "In11.Cu")
		(net "M_F_CPU1_SA_DQS_DN<0>")
	)
	(segment
		(start 48.512222 -201.162412)
		(end 48.8569 -201.50709)
		(width 0.16002)
		(layer "In11.Cu")
		(net "M_F_CPU1_SA_DQS_DN<0>")
	)
	(segment
		(start 67.120516 -209.432652)
		(end 67.544188 -209.856324)
		(width 0.16002)
		(layer "In11.Cu")
		(net "M_F_CPU1_SA_DQS_DN<0>")
	)
	(segment
		(start 78.566518 -223.890078)
		(end 78.599538 -223.909382)
		(width 0.09525)
		(layer "In11.Cu")
		(net "M_F_CPU1_SA_DQS_DN<0>")
	)
	(segment
		(start 78.13802 -223.103948)
		(end 78.153514 -223.113092)
		(width 0.09525)
		(layer "In11.Cu")
		(net "M_F_CPU1_SA_DQS_DN<0>")
	)
	(segment
		(start 68.020692 -209.856324)
		(end 68.362322 -209.514948)
		(width 0.16002)
		(layer "In11.Cu")
		(net "M_F_CPU1_SA_DQS_DN<0>")
	)
	(segment
		(start 79.540354 -227.149406)
		(end 79.558388 -227.15982)
		(width 0.09525)
		(layer "In11.Cu")
		(net "M_F_CPU1_SA_DQS_DN<0>")
	)
	(segment
		(start 84.205064 -227.209096)
		(end 84.05114 -227.474526)
		(width 0.09525)
		(layer "In11.Cu")
		(net "M_F_CPU1_SA_DQS_DN<0>")
	)
	(segment
		(start 67.462146 -208.388712)
		(end 67.462146 -208.614518)
		(width 0.16002)
		(layer "In11.Cu")
		(net "M_F_CPU1_SA_DQS_DN<0>")
	)
	(segment
		(start 24.280622 -201.162412)
		(end 25.88006 -201.162412)
		(width 0.16002)
		(layer "In11.Cu")
		(net "M_F_CPU1_SA_DQS_DN<0>")
	)
	(segment
		(start 77.58938 -222.238316)
		(end 77.606144 -222.25508)
		(width 0.09525)
		(layer "In11.Cu")
		(net "M_F_CPU1_SA_DQS_DN<0>")
	)
	(segment
		(start 22.461982 -201.31151)
		(end 22.578822 -201.42835)
		(width 0.16002)
		(layer "In11.Cu")
		(net "M_F_CPU1_SA_DQS_DN<0>")
	)
	(segment
		(start 67.120516 -208.955894)
		(end 67.120516 -209.432652)
		(width 0.16002)
		(layer "In11.Cu")
		(net "M_F_CPU1_SA_DQS_DN<0>")
	)
	(segment
		(start 57.875932 -200.68159)
		(end 59.829954 -200.68159)
		(width 0.16002)
		(layer "In11.Cu")
		(net "M_F_CPU1_SA_DQS_DN<0>")
	)
	(segment
		(start 27.69997 -200.68159)
		(end 28.144724 -200.68159)
		(width 0.16002)
		(layer "In11.Cu")
		(net "M_F_CPU1_SA_DQS_DN<0>")
	)
	(segment
		(start 59.829954 -200.68159)
		(end 64.33947 -205.191106)
		(width 0.16002)
		(layer "In11.Cu")
		(net "M_F_CPU1_SA_DQS_DN<0>")
	)
	(segment
		(start 65.746884 -208.05902)
		(end 66.170556 -208.482692)
		(width 0.16002)
		(layer "In11.Cu")
		(net "M_F_CPU1_SA_DQS_DN<0>")
	)
	(segment
		(start 23.175722 -201.31151)
		(end 24.131524 -201.31151)
		(width 0.16002)
		(layer "In11.Cu")
		(net "M_F_CPU1_SA_DQS_DN<0>")
	)
	(segment
		(start 23.058882 -201.42835)
		(end 23.175722 -201.31151)
		(width 0.16002)
		(layer "In11.Cu")
		(net "M_F_CPU1_SA_DQS_DN<0>")
	)
	(segment
		(start 84.181696 -227.122228)
		(end 84.205064 -227.209096)
		(width 0.09525)
		(layer "In11.Cu")
		(net "M_F_CPU1_SA_DQS_DN<0>")
	)
	(segment
		(start 74.74331 -217.055446)
		(end 74.74331 -219.392246)
		(width 0.16002)
		(layer "In11.Cu")
		(net "M_F_CPU1_SA_DQS_DN<0>")
	)
	(segment
		(start 79.031846 -226.317302)
		(end 79.069946 -226.3394)
		(width 0.09525)
		(layer "In11.Cu")
		(net "M_F_CPU1_SA_DQS_DN<0>")
	)
	(segment
		(start 79.50327 -227.12807)
		(end 79.539846 -227.149406)
		(width 0.09525)
		(layer "In11.Cu")
		(net "M_F_CPU1_SA_DQS_DN<0>")
	)
	(segment
		(start 33.424114 -201.162412)
		(end 33.768792 -201.50709)
		(width 0.16002)
		(layer "In11.Cu")
		(net "M_F_CPU1_SA_DQS_DN<0>")
	)
	(segment
		(start 41.312846 -201.50709)
		(end 41.962578 -201.50709)
		(width 0.16002)
		(layer "In11.Cu")
		(net "M_F_CPU1_SA_DQS_DN<0>")
	)
	(segment
		(start 66.170556 -208.482692)
		(end 66.64706 -208.482692)
		(width 0.16002)
		(layer "In11.Cu")
		(net "M_F_CPU1_SA_DQS_DN<0>")
	)
	(segment
		(start 67.21475 -208.141316)
		(end 67.462146 -208.388712)
		(width 0.16002)
		(layer "In11.Cu")
		(net "M_F_CPU1_SA_DQS_DN<0>")
	)
	(segment
		(start 35.688778 -200.68159)
		(end 36.05784 -200.312528)
		(width 0.16002)
		(layer "In11.Cu")
		(net "M_F_CPU1_SA_DQS_DN<0>")
	)
	(segment
		(start 78.634336 -224.539556)
		(end 78.599538 -224.559622)
		(width 0.09525)
		(layer "In11.Cu")
		(net "M_F_CPU1_SA_DQS_DN<0>")
	)
	(segment
		(start 31.566866 -201.279252)
		(end 32.046926 -201.279252)
		(width 0.16002)
		(layer "In11.Cu")
		(net "M_F_CPU1_SA_DQS_DN<0>")
	)
	(segment
		(start 77.689964 -222.25508)
		(end 77.849222 -222.414338)
		(width 0.09525)
		(layer "In11.Cu")
		(net "M_F_CPU1_SA_DQS_DN<0>")
	)
	(segment
		(start 68.835778 -209.98815)
		(end 68.494148 -210.329526)
		(width 0.16002)
		(layer "In11.Cu")
		(net "M_F_CPU1_SA_DQS_DN<0>")
	)
	(segment
		(start 78.153514 -223.113092)
		(end 78.161388 -223.117664)
		(width 0.09525)
		(layer "In11.Cu")
		(net "M_F_CPU1_SA_DQS_DN<0>")
	)
	(segment
		(start 50.332132 -200.68159)
		(end 50.776886 -200.68159)
		(width 0.16002)
		(layer "In11.Cu")
		(net "M_F_CPU1_SA_DQS_DN<0>")
	)
	(segment
		(start 42.788078 -200.68159)
		(end 43.232832 -200.68159)
		(width 0.16002)
		(layer "In11.Cu")
		(net "M_F_CPU1_SA_DQS_DN<0>")
	)
	(segment
		(start 64.33947 -206.651606)
		(end 64.796924 -207.10906)
		(width 0.16002)
		(layer "In11.Cu")
		(net "M_F_CPU1_SA_DQS_DN<0>")
	)
	(segment
		(start 74.74331 -219.392246)
		(end 77.58938 -222.238316)
		(width 0.16002)
		(layer "In11.Cu")
		(net "M_F_CPU1_SA_DQS_DN<0>")
	)
	(segment
		(start 38.51402 -201.162412)
		(end 40.968168 -201.162412)
		(width 0.16002)
		(layer "In11.Cu")
		(net "M_F_CPU1_SA_DQS_DN<0>")
	)
	(segment
		(start 64.796924 -207.10906)
		(end 65.273428 -207.10906)
		(width 0.16002)
		(layer "In11.Cu")
		(net "M_F_CPU1_SA_DQS_DN<0>")
	)
	(segment
		(start 33.768792 -201.50709)
		(end 34.418524 -201.50709)
		(width 0.16002)
		(layer "In11.Cu")
		(net "M_F_CPU1_SA_DQS_DN<0>")
	)
	(segment
		(start 68.494148 -210.806284)
		(end 74.74331 -217.055446)
		(width 0.16002)
		(layer "In11.Cu")
		(net "M_F_CPU1_SA_DQS_DN<0>")
	)
	(segment
		(start 35.244024 -200.68159)
		(end 35.688778 -200.68159)
		(width 0.16002)
		(layer "In11.Cu")
		(net "M_F_CPU1_SA_DQS_DN<0>")
	)
	(segment
		(start 28.144724 -200.68159)
		(end 28.513786 -200.312528)
		(width 0.16002)
		(layer "In11.Cu")
		(net "M_F_CPU1_SA_DQS_DN<0>")
	)
	(segment
		(start 34.418524 -201.50709)
		(end 35.244024 -200.68159)
		(width 0.16002)
		(layer "In11.Cu")
		(net "M_F_CPU1_SA_DQS_DN<0>")
	)
	(segment
		(start 32.163766 -201.162412)
		(end 33.424114 -201.162412)
		(width 0.16002)
		(layer "In11.Cu")
		(net "M_F_CPU1_SA_DQS_DN<0>")
	)
	(segment
		(start 67.462146 -208.614518)
		(end 67.120516 -208.955894)
		(width 0.16002)
		(layer "In11.Cu")
		(net "M_F_CPU1_SA_DQS_DN<0>")
	)
	(segment
		(start 22.578822 -201.42835)
		(end 23.058882 -201.42835)
		(width 0.16002)
		(layer "In11.Cu")
		(net "M_F_CPU1_SA_DQS_DN<0>")
	)
	(segment
		(start 24.131524 -201.31151)
		(end 24.280622 -201.162412)
		(width 0.16002)
		(layer "In11.Cu")
		(net "M_F_CPU1_SA_DQS_DN<0>")
	)
	(segment
		(start 30.969966 -201.162412)
		(end 31.450026 -201.162412)
		(width 0.16002)
		(layer "In11.Cu")
		(net "M_F_CPU1_SA_DQS_DN<0>")
	)
	(segment
		(start 30.120082 -200.312528)
		(end 30.969966 -201.162412)
		(width 0.16002)
		(layer "In11.Cu")
		(net "M_F_CPU1_SA_DQS_DN<0>")
	)
	(segment
		(start 65.841118 -206.767684)
		(end 66.088514 -207.01508)
		(width 0.16002)
		(layer "In11.Cu")
		(net "M_F_CPU1_SA_DQS_DN<0>")
	)
	(segment
		(start 48.8569 -201.50709)
		(end 49.506632 -201.50709)
		(width 0.16002)
		(layer "In11.Cu")
		(net "M_F_CPU1_SA_DQS_DN<0>")
	)
	(segment
		(start 78.561438 -225.507296)
		(end 78.634336 -225.54946)
		(width 0.09525)
		(layer "In11.Cu")
		(net "M_F_CPU1_SA_DQS_DN<0>")
	)
	(segment
		(start 40.968168 -201.162412)
		(end 41.312846 -201.50709)
		(width 0.16002)
		(layer "In11.Cu")
		(net "M_F_CPU1_SA_DQS_DN<0>")
	)
	(segment
		(start 79.539846 -227.149406)
		(end 79.540354 -227.149406)
		(width 0.09525)
		(layer "In11.Cu")
		(net "M_F_CPU1_SA_DQS_DN<0>")
	)
	(segment
		(start 50.776886 -200.68159)
		(end 51.145948 -200.312528)
		(width 0.16002)
		(layer "In11.Cu")
		(net "M_F_CPU1_SA_DQS_DN<0>")
	)
	(segment
		(start 65.746884 -207.582262)
		(end 65.746884 -208.05902)
		(width 0.16002)
		(layer "In11.Cu")
		(net "M_F_CPU1_SA_DQS_DN<0>")
	)
	(segment
		(start 66.98869 -208.141316)
		(end 67.21475 -208.141316)
		(width 0.16002)
		(layer "In11.Cu")
		(net "M_F_CPU1_SA_DQS_DN<0>")
	)
	(segment
		(start 68.362322 -209.514948)
		(end 68.588382 -209.514948)
		(width 0.16002)
		(layer "In11.Cu")
		(net "M_F_CPU1_SA_DQS_DN<0>")
	)
	(segment
		(start 53.946806 -201.50709)
		(end 57.050432 -201.50709)
		(width 0.16002)
		(layer "In11.Cu")
		(net "M_F_CPU1_SA_DQS_DN<0>")
	)
	(segment
		(start 78.106016 -223.084898)
		(end 78.137004 -223.103186)
		(width 0.09525)
		(layer "In11.Cu")
		(net "M_F_CPU1_SA_DQS_DN<0>")
	)
	(segment
		(start 65.615058 -206.767684)
		(end 65.841118 -206.767684)
		(width 0.16002)
		(layer "In11.Cu")
		(net "M_F_CPU1_SA_DQS_DN<0>")
	)
	(segment
		(start 37.664136 -200.312528)
		(end 38.51402 -201.162412)
		(width 0.16002)
		(layer "In11.Cu")
		(net "M_F_CPU1_SA_DQS_DN<0>")
	)
	(segment
		(start 79.070708 -226.339908)
		(end 79.101442 -226.357688)
		(width 0.09525)
		(layer "In11.Cu")
		(net "M_F_CPU1_SA_DQS_DN<0>")
	)
	(segment
		(start 25.88006 -201.162412)
		(end 26.224738 -201.50709)
		(width 0.16002)
		(layer "In11.Cu")
		(net "M_F_CPU1_SA_DQS_DN<0>")
	)
	(segment
		(start 66.088514 -207.01508)
		(end 66.088514 -207.240886)
		(width 0.16002)
		(layer "In11.Cu")
		(net "M_F_CPU1_SA_DQS_DN<0>")
	)
	(segment
		(start 68.588382 -209.514948)
		(end 68.835778 -209.762344)
		(width 0.16002)
		(layer "In11.Cu")
		(net "M_F_CPU1_SA_DQS_DN<0>")
	)
	(segment
		(start 26.87447 -201.50709)
		(end 27.69997 -200.68159)
		(width 0.16002)
		(layer "In11.Cu")
		(net "M_F_CPU1_SA_DQS_DN<0>")
	)
	(segment
		(start 46.058074 -201.162412)
		(end 48.512222 -201.162412)
		(width 0.16002)
		(layer "In11.Cu")
		(net "M_F_CPU1_SA_DQS_DN<0>")
	)
	(segment
		(start 43.232832 -200.68159)
		(end 43.601894 -200.312528)
		(width 0.16002)
		(layer "In11.Cu")
		(net "M_F_CPU1_SA_DQS_DN<0>")
	)
	(segment
		(start 77.849222 -222.414338)
		(end 77.849222 -222.636334)
		(width 0.09525)
		(layer "In11.Cu")
		(net "M_F_CPU1_SA_DQS_DN<0>")
	)
	(segment
		(start 52.752244 -200.312528)
		(end 53.946806 -201.50709)
		(width 0.16002)
		(layer "In11.Cu")
		(net "M_F_CPU1_SA_DQS_DN<0>")
	)
	(segment
		(start 78.137004 -223.103186)
		(end 78.137512 -223.10344)
		(width 0.09525)
		(layer "In11.Cu")
		(net "M_F_CPU1_SA_DQS_DN<0>")
	)
	(segment
		(start 41.962578 -201.50709)
		(end 42.788078 -200.68159)
		(width 0.16002)
		(layer "In11.Cu")
		(net "M_F_CPU1_SA_DQS_DN<0>")
	)
	(segment
		(start 31.450026 -201.162412)
		(end 31.566866 -201.279252)
		(width 0.16002)
		(layer "In11.Cu")
		(net "M_F_CPU1_SA_DQS_DN<0>")
	)
	(segment
		(start 81.04251 -227.149406)
		(end 81.050892 -227.14458)
		(width 0.09525)
		(layer "In11.Cu")
		(net "M_F_CPU1_SA_DQS_DN<0>")
	)
	(segment
		(start 78.599538 -223.909382)
		(end 78.634336 -223.929448)
		(width 0.09525)
		(layer "In11.Cu")
		(net "M_F_CPU1_SA_DQS_DN<0>")
	)
	(segment
		(start 79.069946 -226.3394)
		(end 79.070708 -226.339908)
		(width 0.09525)
		(layer "In11.Cu")
		(net "M_F_CPU1_SA_DQS_DN<0>")
	)
	(segment
		(start 45.20819 -200.312528)
		(end 46.058074 -201.162412)
		(width 0.16002)
		(layer "In11.Cu")
		(net "M_F_CPU1_SA_DQS_DN<0>")
	)
	(segment
		(start 65.273428 -207.10906)
		(end 65.615058 -206.767684)
		(width 0.16002)
		(layer "In11.Cu")
		(net "M_F_CPU1_SA_DQS_DN<0>")
	)
	(segment
		(start 68.494148 -210.329526)
		(end 68.494148 -210.806284)
		(width 0.16002)
		(layer "In11.Cu")
		(net "M_F_CPU1_SA_DQS_DN<0>")
	)
	(segment
		(start 43.601894 -200.312528)
		(end 45.20819 -200.312528)
		(width 0.16002)
		(layer "In11.Cu")
		(net "M_F_CPU1_SA_DQS_DN<0>")
	)
	(segment
		(start 57.050432 -201.50709)
		(end 57.875932 -200.68159)
		(width 0.16002)
		(layer "In11.Cu")
		(net "M_F_CPU1_SA_DQS_DN<0>")
	)
	(segment
		(start 66.088514 -207.240886)
		(end 65.746884 -207.582262)
		(width 0.16002)
		(layer "In11.Cu")
		(net "M_F_CPU1_SA_DQS_DN<0>")
	)
	(segment
		(start 64.33947 -205.191106)
		(end 64.33947 -206.651606)
		(width 0.16002)
		(layer "In11.Cu")
		(net "M_F_CPU1_SA_DQS_DN<0>")
	)
	(segment
		(start 68.835778 -209.762344)
		(end 68.835778 -209.98815)
		(width 0.16002)
		(layer "In11.Cu")
		(net "M_F_CPU1_SA_DQS_DN<0>")
	)
	(segment
		(start 51.145948 -200.312528)
		(end 52.752244 -200.312528)
		(width 0.16002)
		(layer "In11.Cu")
		(net "M_F_CPU1_SA_DQS_DN<0>")
	)
	(segment
		(start 78.137512 -223.103694)
		(end 78.13802 -223.103948)
		(width 0.09525)
		(layer "In11.Cu")
		(net "M_F_CPU1_SA_DQS_DN<0>")
	)
	(segment
		(start 66.64706 -208.482692)
		(end 66.98869 -208.141316)
		(width 0.16002)
		(layer "In11.Cu")
		(net "M_F_CPU1_SA_DQS_DN<0>")
	)
	(segment
		(start 78.318614 -225.03892)
		(end 78.318614 -225.044508)
		(width 0.09525)
		(layer "In11.Cu")
		(net "M_F_CPU1_SA_DQS_DN<0>")
	)
	(segment
		(start 78.484476 -224.648014)
		(end 78.477872 -224.654618)
		(width 0.09525)
		(layer "In11.Cu")
		(net "M_F_CPU1_SA_DQS_DN<0>")
	)
	(segment
		(start 49.506632 -201.50709)
		(end 50.332132 -200.68159)
		(width 0.16002)
		(layer "In11.Cu")
		(net "M_F_CPU1_SA_DQS_DN<0>")
	)
	(segment
		(start 83.291172 -227.14458)
		(end 83.299554 -227.149406)
		(width 0.09525)
		(layer "In11.Cu")
		(net "M_F_CPU1_SA_DQS_DN<0>")
	)
	(arc
		(start 81.4197 -227.149406)
		(mid 81.701132 -227.225161)
		(end 81.982564 -227.149406)
		(width 0.09525)
		(layer "In11.Cu")
		(net "M_F_CPU1_SA_DQS_DN<0>")
	)
	(arc
		(start 79.258922 -226.66452)
		(mid 79.323751 -226.926522)
		(end 79.50327 -227.12807)
		(width 0.09525)
		(layer "In11.Cu")
		(net "M_F_CPU1_SA_DQS_DN<0>")
	)
	(arc
		(start 79.101442 -226.357688)
		(mid 79.21724 -226.492082)
		(end 79.258922 -226.66452)
		(width 0.09525)
		(layer "In11.Cu")
		(net "M_F_CPU1_SA_DQS_DN<0>")
	)
	(arc
		(start 80.102456 -227.149406)
		(mid 80.286231 -227.098634)
		(end 80.471264 -227.14458)
		(width 0.09525)
		(layer "In11.Cu")
		(net "M_F_CPU1_SA_DQS_DN<0>")
	)
	(arc
		(start 78.318868 -223.424496)
		(mid 78.384061 -223.687125)
		(end 78.564486 -223.888808)
		(width 0.09525)
		(layer "In11.Cu")
		(net "M_F_CPU1_SA_DQS_DN<0>")
	)
	(arc
		(start 81.982564 -227.149406)
		(mid 82.171032 -227.098729)
		(end 82.3595 -227.149406)
		(width 0.09525)
		(layer "In11.Cu")
		(net "M_F_CPU1_SA_DQS_DN<0>")
	)
	(arc
		(start 77.849222 -222.636334)
		(mid 77.917907 -222.894797)
		(end 78.106016 -223.084898)
		(width 0.09525)
		(layer "In11.Cu")
		(net "M_F_CPU1_SA_DQS_DN<0>")
	)
	(arc
		(start 83.299554 -227.149406)
		(mid 83.580986 -227.225161)
		(end 83.862418 -227.149406)
		(width 0.09525)
		(layer "In11.Cu")
		(net "M_F_CPU1_SA_DQS_DN<0>")
	)
	(arc
		(start 80.479646 -227.149406)
		(mid 80.761078 -227.225161)
		(end 81.04251 -227.149406)
		(width 0.09525)
		(layer "In11.Cu")
		(net "M_F_CPU1_SA_DQS_DN<0>")
	)
	(arc
		(start 81.050892 -227.14458)
		(mid 81.235924 -227.098666)
		(end 81.4197 -227.149406)
		(width 0.09525)
		(layer "In11.Cu")
		(net "M_F_CPU1_SA_DQS_DN<0>")
	)
	(arc
		(start 78.599538 -224.559622)
		(mid 78.539134 -224.600078)
		(end 78.484476 -224.648014)
		(width 0.09525)
		(layer "In11.Cu")
		(net "M_F_CPU1_SA_DQS_DN<0>")
	)
	(arc
		(start 78.161388 -223.117664)
		(mid 78.277186 -223.252058)
		(end 78.318868 -223.424496)
		(width 0.09525)
		(layer "In11.Cu")
		(net "M_F_CPU1_SA_DQS_DN<0>")
	)
	(arc
		(start 78.634336 -225.54946)
		(mid 78.748121 -225.683504)
		(end 78.789022 -225.854514)
		(width 0.09525)
		(layer "In11.Cu")
		(net "M_F_CPU1_SA_DQS_DN<0>")
	)
	(arc
		(start 78.477872 -224.654618)
		(mid 78.360006 -224.830923)
		(end 78.318614 -225.03892)
		(width 0.09525)
		(layer "In11.Cu")
		(net "M_F_CPU1_SA_DQS_DN<0>")
	)
	(arc
		(start 82.3595 -227.149406)
		(mid 82.640932 -227.225161)
		(end 82.922364 -227.149406)
		(width 0.09525)
		(layer "In11.Cu")
		(net "M_F_CPU1_SA_DQS_DN<0>")
	)
	(arc
		(start 82.922364 -227.149406)
		(mid 83.106139 -227.098634)
		(end 83.291172 -227.14458)
		(width 0.09525)
		(layer "In11.Cu")
		(net "M_F_CPU1_SA_DQS_DN<0>")
	)
	(arc
		(start 78.789022 -225.854514)
		(mid 78.853419 -226.11582)
		(end 79.031846 -226.317302)
		(width 0.09525)
		(layer "In11.Cu")
		(net "M_F_CPU1_SA_DQS_DN<0>")
	)
	(arc
		(start 79.558388 -227.15982)
		(mid 79.831768 -227.225041)
		(end 80.102456 -227.149406)
		(width 0.09525)
		(layer "In11.Cu")
		(net "M_F_CPU1_SA_DQS_DN<0>")
	)
	(arc
		(start 78.318614 -225.044508)
		(mid 78.383011 -225.305814)
		(end 78.561438 -225.507296)
		(width 0.09525)
		(layer "In11.Cu")
		(net "M_F_CPU1_SA_DQS_DN<0>")
	)
	(arc
		(start 78.634336 -223.929448)
		(mid 78.788995 -224.234502)
		(end 78.634336 -224.539556)
		(width 0.09525)
		(layer "In11.Cu")
		(net "M_F_CPU1_SA_DQS_DN<0>")
	)
	(arc
		(start 83.862418 -227.149406)
		(mid 84.019016 -227.100117)
		(end 84.181696 -227.122228)
		(width 0.09525)
		(layer "In11.Cu")
		(net "M_F_CPU1_SA_DQS_DN<0>")
	)
	(segment
		(start 86.397846 -230.980234)
		(end 85.930994 -230.71455)
		(width 0.10668)
		(layer "F.Cu")
		(net "M_F_CPU1_SA_DQ<9>")
	)
	(segment
		(start 41.94302 -208.810352)
		(end 42.792904 -207.960468)
		(width 0.14478)
		(layer "In11.Cu")
		(net "M_F_CPU1_SA_DQ<9>")
	)
	(segment
		(start 37.95268 -207.960468)
		(end 38.802564 -208.810352)
		(width 0.14478)
		(layer "In11.Cu")
		(net "M_F_CPU1_SA_DQ<9>")
	)
	(segment
		(start 26.405332 -208.97342)
		(end 26.5684 -208.810352)
		(width 0.14478)
		(layer "In11.Cu")
		(net "M_F_CPU1_SA_DQ<9>")
	)
	(segment
		(start 49.138586 -208.810352)
		(end 49.448974 -208.810352)
		(width 0.14478)
		(layer "In11.Cu")
		(net "M_F_CPU1_SA_DQ<9>")
	)
	(segment
		(start 40.583358 -208.810352)
		(end 40.746426 -208.97342)
		(width 0.14478)
		(layer "In11.Cu")
		(net "M_F_CPU1_SA_DQ<9>")
	)
	(segment
		(start 24.499062 -208.810352)
		(end 25.68575 -208.810352)
		(width 0.14478)
		(layer "In11.Cu")
		(net "M_F_CPU1_SA_DQ<9>")
	)
	(segment
		(start 33.270952 -208.97342)
		(end 33.270952 -209.037936)
		(width 0.14478)
		(layer "In11.Cu")
		(net "M_F_CPU1_SA_DQ<9>")
	)
	(segment
		(start 41.139872 -209.188304)
		(end 41.30294 -209.025236)
		(width 0.14478)
		(layer "In11.Cu")
		(net "M_F_CPU1_SA_DQ<9>")
	)
	(segment
		(start 35.233102 -207.960468)
		(end 35.497262 -207.960468)
		(width 0.14478)
		(layer "In11.Cu")
		(net "M_F_CPU1_SA_DQ<9>")
	)
	(segment
		(start 26.011886 -209.201004)
		(end 26.242264 -209.201004)
		(width 0.14478)
		(layer "In11.Cu")
		(net "M_F_CPU1_SA_DQ<9>")
	)
	(segment
		(start 56.375808 -209.037936)
		(end 56.375808 -208.97342)
		(width 0.14478)
		(layer "In11.Cu")
		(net "M_F_CPU1_SA_DQ<9>")
	)
	(segment
		(start 84.229702 -231.041702)
		(end 84.238084 -231.036876)
		(width 0.0889)
		(layer "In11.Cu")
		(net "M_F_CPU1_SA_DQ<9>")
	)
	(segment
		(start 54.706266 -208.97342)
		(end 54.706266 -209.037936)
		(width 0.14478)
		(layer "In11.Cu")
		(net "M_F_CPU1_SA_DQ<9>")
	)
	(segment
		(start 28.75915 -208.123536)
		(end 28.922218 -207.960468)
		(width 0.14478)
		(layer "In11.Cu")
		(net "M_F_CPU1_SA_DQ<9>")
	)
	(segment
		(start 35.497262 -207.960468)
		(end 35.66033 -208.123536)
		(width 0.14478)
		(layer "In11.Cu")
		(net "M_F_CPU1_SA_DQ<9>")
	)
	(segment
		(start 78.13929 -230.083106)
		(end 78.650084 -230.083106)
		(width 0.0889)
		(layer "In11.Cu")
		(net "M_F_CPU1_SA_DQ<9>")
	)
	(segment
		(start 51.359054 -208.181956)
		(end 51.359054 -208.123536)
		(width 0.14478)
		(layer "In11.Cu")
		(net "M_F_CPU1_SA_DQ<9>")
	)
	(segment
		(start 25.848818 -209.037936)
		(end 26.011886 -209.201004)
		(width 0.14478)
		(layer "In11.Cu")
		(net "M_F_CPU1_SA_DQ<9>")
	)
	(segment
		(start 57.804558 -207.960468)
		(end 59.215274 -207.960468)
		(width 0.14478)
		(layer "In11.Cu")
		(net "M_F_CPU1_SA_DQ<9>")
	)
	(segment
		(start 53.111908 -207.960468)
		(end 53.961792 -208.810352)
		(width 0.14478)
		(layer "In11.Cu")
		(net "M_F_CPU1_SA_DQ<9>")
	)
	(segment
		(start 28.202636 -208.189576)
		(end 28.356306 -208.343246)
		(width 0.14478)
		(layer "In11.Cu")
		(net "M_F_CPU1_SA_DQ<9>")
	)
	(segment
		(start 48.419004 -208.97342)
		(end 48.419004 -209.037936)
		(width 0.14478)
		(layer "In11.Cu")
		(net "M_F_CPU1_SA_DQ<9>")
	)
	(segment
		(start 24.172926 -209.188304)
		(end 24.335994 -209.025236)
		(width 0.14478)
		(layer "In11.Cu")
		(net "M_F_CPU1_SA_DQ<9>")
	)
	(segment
		(start 56.954674 -208.810352)
		(end 57.804558 -207.960468)
		(width 0.14478)
		(layer "In11.Cu")
		(net "M_F_CPU1_SA_DQ<9>")
	)
	(segment
		(start 21.70811 -208.38541)
		(end 22.133052 -208.810352)
		(width 0.14478)
		(layer "In11.Cu")
		(net "M_F_CPU1_SA_DQ<9>")
	)
	(segment
		(start 43.745912 -208.189576)
		(end 43.745912 -208.123536)
		(width 0.14478)
		(layer "In11.Cu")
		(net "M_F_CPU1_SA_DQ<9>")
	)
	(segment
		(start 76.442316 -227.936806)
		(end 76.442316 -228.709474)
		(width 0.0889)
		(layer "In11.Cu")
		(net "M_F_CPU1_SA_DQ<9>")
	)
	(segment
		(start 33.990534 -208.810352)
		(end 34.383218 -208.810352)
		(width 0.14478)
		(layer "In11.Cu")
		(net "M_F_CPU1_SA_DQ<9>")
	)
	(segment
		(start 43.597322 -208.338166)
		(end 43.745912 -208.189576)
		(width 0.14478)
		(layer "In11.Cu")
		(net "M_F_CPU1_SA_DQ<9>")
	)
	(segment
		(start 54.706266 -209.037936)
		(end 54.869334 -209.201004)
		(width 0.14478)
		(layer "In11.Cu")
		(net "M_F_CPU1_SA_DQ<9>")
	)
	(segment
		(start 33.43402 -209.201004)
		(end 33.664398 -209.201004)
		(width 0.14478)
		(layer "In11.Cu")
		(net "M_F_CPU1_SA_DQ<9>")
	)
	(segment
		(start 28.202636 -208.123536)
		(end 28.202636 -208.189576)
		(width 0.14478)
		(layer "In11.Cu")
		(net "M_F_CPU1_SA_DQ<9>")
	)
	(segment
		(start 26.81478 -208.810352)
		(end 27.664664 -207.960468)
		(width 0.14478)
		(layer "In11.Cu")
		(net "M_F_CPU1_SA_DQ<9>")
	)
	(segment
		(start 23.6347 -208.810352)
		(end 23.77948 -208.955132)
		(width 0.14478)
		(layer "In11.Cu")
		(net "M_F_CPU1_SA_DQ<9>")
	)
	(segment
		(start 70.251066 -218.99626)
		(end 70.251066 -221.745556)
		(width 0.14478)
		(layer "In11.Cu")
		(net "M_F_CPU1_SA_DQ<9>")
	)
	(segment
		(start 36.216844 -208.123536)
		(end 36.379912 -207.960468)
		(width 0.14478)
		(layer "In11.Cu")
		(net "M_F_CPU1_SA_DQ<9>")
	)
	(segment
		(start 48.582072 -209.201004)
		(end 48.81245 -209.201004)
		(width 0.14478)
		(layer "In11.Cu")
		(net "M_F_CPU1_SA_DQ<9>")
	)
	(segment
		(start 41.30294 -208.97342)
		(end 41.466008 -208.810352)
		(width 0.14478)
		(layer "In11.Cu")
		(net "M_F_CPU1_SA_DQ<9>")
	)
	(segment
		(start 81.044034 -231.036876)
		(end 81.052416 -231.041702)
		(width 0.0889)
		(layer "In11.Cu")
		(net "M_F_CPU1_SA_DQ<9>")
	)
	(segment
		(start 33.107884 -208.810352)
		(end 33.270952 -208.97342)
		(width 0.14478)
		(layer "In11.Cu")
		(net "M_F_CPU1_SA_DQ<9>")
	)
	(segment
		(start 30.470856 -207.960468)
		(end 31.32074 -208.810352)
		(width 0.14478)
		(layer "In11.Cu")
		(net "M_F_CPU1_SA_DQ<9>")
	)
	(segment
		(start 23.942548 -209.188304)
		(end 24.172926 -209.188304)
		(width 0.14478)
		(layer "In11.Cu")
		(net "M_F_CPU1_SA_DQ<9>")
	)
	(segment
		(start 26.405332 -209.037936)
		(end 26.405332 -208.97342)
		(width 0.14478)
		(layer "In11.Cu")
		(net "M_F_CPU1_SA_DQ<9>")
	)
	(segment
		(start 42.792904 -207.960468)
		(end 43.02633 -207.960468)
		(width 0.14478)
		(layer "In11.Cu")
		(net "M_F_CPU1_SA_DQ<9>")
	)
	(segment
		(start 49.448974 -208.810352)
		(end 50.298858 -207.960468)
		(width 0.14478)
		(layer "In11.Cu")
		(net "M_F_CPU1_SA_DQ<9>")
	)
	(segment
		(start 34.383218 -208.810352)
		(end 35.233102 -207.960468)
		(width 0.14478)
		(layer "In11.Cu")
		(net "M_F_CPU1_SA_DQ<9>")
	)
	(segment
		(start 28.039568 -207.960468)
		(end 28.202636 -208.123536)
		(width 0.14478)
		(layer "In11.Cu")
		(net "M_F_CPU1_SA_DQ<9>")
	)
	(segment
		(start 28.922218 -207.960468)
		(end 30.470856 -207.960468)
		(width 0.14478)
		(layer "In11.Cu")
		(net "M_F_CPU1_SA_DQ<9>")
	)
	(segment
		(start 80.46974 -231.041702)
		(end 80.478122 -231.036876)
		(width 0.0889)
		(layer "In11.Cu")
		(net "M_F_CPU1_SA_DQ<9>")
	)
	(segment
		(start 75.851766 -227.346256)
		(end 76.442316 -227.936806)
		(width 0.0889)
		(layer "In11.Cu")
		(net "M_F_CPU1_SA_DQ<9>")
	)
	(segment
		(start 54.869334 -209.201004)
		(end 55.099712 -209.201004)
		(width 0.14478)
		(layer "In11.Cu")
		(net "M_F_CPU1_SA_DQ<9>")
	)
	(segment
		(start 27.664664 -207.960468)
		(end 28.039568 -207.960468)
		(width 0.14478)
		(layer "In11.Cu")
		(net "M_F_CPU1_SA_DQ<9>")
	)
	(segment
		(start 36.063174 -208.343246)
		(end 36.216844 -208.189576)
		(width 0.14478)
		(layer "In11.Cu")
		(net "M_F_CPU1_SA_DQ<9>")
	)
	(segment
		(start 76.908406 -229.175564)
		(end 77.23124 -229.175564)
		(width 0.0889)
		(layer "In11.Cu")
		(net "M_F_CPU1_SA_DQ<9>")
	)
	(segment
		(start 41.30294 -209.025236)
		(end 41.30294 -208.97342)
		(width 0.14478)
		(layer "In11.Cu")
		(net "M_F_CPU1_SA_DQ<9>")
	)
	(segment
		(start 54.543198 -208.810352)
		(end 54.706266 -208.97342)
		(width 0.14478)
		(layer "In11.Cu")
		(net "M_F_CPU1_SA_DQ<9>")
	)
	(segment
		(start 85.77707 -230.97998)
		(end 85.930994 -230.71455)
		(width 0.0889)
		(layer "In11.Cu")
		(net "M_F_CPU1_SA_DQ<9>")
	)
	(segment
		(start 38.802564 -208.810352)
		(end 40.583358 -208.810352)
		(width 0.14478)
		(layer "In11.Cu")
		(net "M_F_CPU1_SA_DQ<9>")
	)
	(segment
		(start 50.639472 -207.960468)
		(end 50.80254 -208.123536)
		(width 0.14478)
		(layer "In11.Cu")
		(net "M_F_CPU1_SA_DQ<9>")
	)
	(segment
		(start 55.26278 -209.037936)
		(end 55.26278 -208.97342)
		(width 0.14478)
		(layer "In11.Cu")
		(net "M_F_CPU1_SA_DQ<9>")
	)
	(segment
		(start 70.251066 -221.745556)
		(end 75.851766 -227.346256)
		(width 0.14478)
		(layer "In11.Cu")
		(net "M_F_CPU1_SA_DQ<9>")
	)
	(segment
		(start 50.80254 -208.181956)
		(end 50.965608 -208.345024)
		(width 0.14478)
		(layer "In11.Cu")
		(net "M_F_CPU1_SA_DQ<9>")
	)
	(segment
		(start 36.216844 -208.189576)
		(end 36.216844 -208.123536)
		(width 0.14478)
		(layer "In11.Cu")
		(net "M_F_CPU1_SA_DQ<9>")
	)
	(segment
		(start 35.814 -208.343246)
		(end 36.063174 -208.343246)
		(width 0.14478)
		(layer "In11.Cu")
		(net "M_F_CPU1_SA_DQ<9>")
	)
	(segment
		(start 48.419004 -209.037936)
		(end 48.582072 -209.201004)
		(width 0.14478)
		(layer "In11.Cu")
		(net "M_F_CPU1_SA_DQ<9>")
	)
	(segment
		(start 51.195986 -208.345024)
		(end 51.359054 -208.181956)
		(width 0.14478)
		(layer "In11.Cu")
		(net "M_F_CPU1_SA_DQ<9>")
	)
	(segment
		(start 40.746426 -208.97342)
		(end 40.746426 -209.025236)
		(width 0.14478)
		(layer "In11.Cu")
		(net "M_F_CPU1_SA_DQ<9>")
	)
	(segment
		(start 50.965608 -208.345024)
		(end 51.195986 -208.345024)
		(width 0.14478)
		(layer "In11.Cu")
		(net "M_F_CPU1_SA_DQ<9>")
	)
	(segment
		(start 55.425848 -208.810352)
		(end 55.656226 -208.810352)
		(width 0.14478)
		(layer "In11.Cu")
		(net "M_F_CPU1_SA_DQ<9>")
	)
	(segment
		(start 56.21274 -209.201004)
		(end 56.375808 -209.037936)
		(width 0.14478)
		(layer "In11.Cu")
		(net "M_F_CPU1_SA_DQ<9>")
	)
	(segment
		(start 33.827466 -208.97342)
		(end 33.990534 -208.810352)
		(width 0.14478)
		(layer "In11.Cu")
		(net "M_F_CPU1_SA_DQ<9>")
	)
	(segment
		(start 77.23124 -229.175564)
		(end 78.13929 -230.083106)
		(width 0.0889)
		(layer "In11.Cu")
		(net "M_F_CPU1_SA_DQ<9>")
	)
	(segment
		(start 28.60548 -208.343246)
		(end 28.75915 -208.189576)
		(width 0.14478)
		(layer "In11.Cu")
		(net "M_F_CPU1_SA_DQ<9>")
	)
	(segment
		(start 55.982362 -209.201004)
		(end 56.21274 -209.201004)
		(width 0.14478)
		(layer "In11.Cu")
		(net "M_F_CPU1_SA_DQ<9>")
	)
	(segment
		(start 40.909494 -209.188304)
		(end 41.139872 -209.188304)
		(width 0.14478)
		(layer "In11.Cu")
		(net "M_F_CPU1_SA_DQ<9>")
	)
	(segment
		(start 53.961792 -208.810352)
		(end 54.543198 -208.810352)
		(width 0.14478)
		(layer "In11.Cu")
		(net "M_F_CPU1_SA_DQ<9>")
	)
	(segment
		(start 43.745912 -208.123536)
		(end 43.90898 -207.960468)
		(width 0.14478)
		(layer "In11.Cu")
		(net "M_F_CPU1_SA_DQ<9>")
	)
	(segment
		(start 26.242264 -209.201004)
		(end 26.405332 -209.037936)
		(width 0.14478)
		(layer "In11.Cu")
		(net "M_F_CPU1_SA_DQ<9>")
	)
	(segment
		(start 83.289648 -231.041702)
		(end 83.29803 -231.036876)
		(width 0.0889)
		(layer "In11.Cu")
		(net "M_F_CPU1_SA_DQ<9>")
	)
	(segment
		(start 45.567854 -207.960468)
		(end 46.417738 -208.810352)
		(width 0.14478)
		(layer "In11.Cu")
		(net "M_F_CPU1_SA_DQ<9>")
	)
	(segment
		(start 51.522122 -207.960468)
		(end 53.111908 -207.960468)
		(width 0.14478)
		(layer "In11.Cu")
		(net "M_F_CPU1_SA_DQ<9>")
	)
	(segment
		(start 33.827466 -209.037936)
		(end 33.827466 -208.97342)
		(width 0.14478)
		(layer "In11.Cu")
		(net "M_F_CPU1_SA_DQ<9>")
	)
	(segment
		(start 41.466008 -208.810352)
		(end 41.94302 -208.810352)
		(width 0.14478)
		(layer "In11.Cu")
		(net "M_F_CPU1_SA_DQ<9>")
	)
	(segment
		(start 24.335994 -209.025236)
		(end 24.335994 -208.97342)
		(width 0.14478)
		(layer "In11.Cu")
		(net "M_F_CPU1_SA_DQ<9>")
	)
	(segment
		(start 50.298858 -207.960468)
		(end 50.639472 -207.960468)
		(width 0.14478)
		(layer "In11.Cu")
		(net "M_F_CPU1_SA_DQ<9>")
	)
	(segment
		(start 28.356306 -208.343246)
		(end 28.60548 -208.343246)
		(width 0.14478)
		(layer "In11.Cu")
		(net "M_F_CPU1_SA_DQ<9>")
	)
	(segment
		(start 48.975518 -208.97342)
		(end 49.138586 -208.810352)
		(width 0.14478)
		(layer "In11.Cu")
		(net "M_F_CPU1_SA_DQ<9>")
	)
	(segment
		(start 59.215274 -207.960468)
		(end 70.251066 -218.99626)
		(width 0.14478)
		(layer "In11.Cu")
		(net "M_F_CPU1_SA_DQ<9>")
	)
	(segment
		(start 23.77948 -209.025236)
		(end 23.942548 -209.188304)
		(width 0.14478)
		(layer "In11.Cu")
		(net "M_F_CPU1_SA_DQ<9>")
	)
	(segment
		(start 85.681312 -231.00538)
		(end 85.77707 -230.97998)
		(width 0.0889)
		(layer "In11.Cu")
		(net "M_F_CPU1_SA_DQ<9>")
	)
	(segment
		(start 43.189398 -208.123536)
		(end 43.189398 -208.189576)
		(width 0.14478)
		(layer "In11.Cu")
		(net "M_F_CPU1_SA_DQ<9>")
	)
	(segment
		(start 36.379912 -207.960468)
		(end 37.95268 -207.960468)
		(width 0.14478)
		(layer "In11.Cu")
		(net "M_F_CPU1_SA_DQ<9>")
	)
	(segment
		(start 33.270952 -209.037936)
		(end 33.43402 -209.201004)
		(width 0.14478)
		(layer "In11.Cu")
		(net "M_F_CPU1_SA_DQ<9>")
	)
	(segment
		(start 78.650084 -230.083106)
		(end 79.364078 -230.7971)
		(width 0.0889)
		(layer "In11.Cu")
		(net "M_F_CPU1_SA_DQ<9>")
	)
	(segment
		(start 43.337988 -208.338166)
		(end 43.597322 -208.338166)
		(width 0.14478)
		(layer "In11.Cu")
		(net "M_F_CPU1_SA_DQ<9>")
	)
	(segment
		(start 48.81245 -209.201004)
		(end 48.975518 -209.037936)
		(width 0.14478)
		(layer "In11.Cu")
		(net "M_F_CPU1_SA_DQ<9>")
	)
	(segment
		(start 55.26278 -208.97342)
		(end 55.425848 -208.810352)
		(width 0.14478)
		(layer "In11.Cu")
		(net "M_F_CPU1_SA_DQ<9>")
	)
	(segment
		(start 23.77948 -208.955132)
		(end 23.77948 -209.025236)
		(width 0.14478)
		(layer "In11.Cu")
		(net "M_F_CPU1_SA_DQ<9>")
	)
	(segment
		(start 24.335994 -208.97342)
		(end 24.499062 -208.810352)
		(width 0.14478)
		(layer "In11.Cu")
		(net "M_F_CPU1_SA_DQ<9>")
	)
	(segment
		(start 51.359054 -208.123536)
		(end 51.522122 -207.960468)
		(width 0.14478)
		(layer "In11.Cu")
		(net "M_F_CPU1_SA_DQ<9>")
	)
	(segment
		(start 48.255936 -208.810352)
		(end 48.419004 -208.97342)
		(width 0.14478)
		(layer "In11.Cu")
		(net "M_F_CPU1_SA_DQ<9>")
	)
	(segment
		(start 43.90898 -207.960468)
		(end 45.567854 -207.960468)
		(width 0.14478)
		(layer "In11.Cu")
		(net "M_F_CPU1_SA_DQ<9>")
	)
	(segment
		(start 76.442316 -228.709474)
		(end 76.908406 -229.175564)
		(width 0.0889)
		(layer "In11.Cu")
		(net "M_F_CPU1_SA_DQ<9>")
	)
	(segment
		(start 55.819294 -208.97342)
		(end 55.819294 -209.037936)
		(width 0.14478)
		(layer "In11.Cu")
		(net "M_F_CPU1_SA_DQ<9>")
	)
	(segment
		(start 43.02633 -207.960468)
		(end 43.189398 -208.123536)
		(width 0.14478)
		(layer "In11.Cu")
		(net "M_F_CPU1_SA_DQ<9>")
	)
	(segment
		(start 55.099712 -209.201004)
		(end 55.26278 -209.037936)
		(width 0.14478)
		(layer "In11.Cu")
		(net "M_F_CPU1_SA_DQ<9>")
	)
	(segment
		(start 84.803996 -231.036876)
		(end 84.812378 -231.041702)
		(width 0.0889)
		(layer "In11.Cu")
		(net "M_F_CPU1_SA_DQ<9>")
	)
	(segment
		(start 40.746426 -209.025236)
		(end 40.909494 -209.188304)
		(width 0.14478)
		(layer "In11.Cu")
		(net "M_F_CPU1_SA_DQ<9>")
	)
	(segment
		(start 56.538876 -208.810352)
		(end 56.954674 -208.810352)
		(width 0.14478)
		(layer "In11.Cu")
		(net "M_F_CPU1_SA_DQ<9>")
	)
	(segment
		(start 43.189398 -208.189576)
		(end 43.337988 -208.338166)
		(width 0.14478)
		(layer "In11.Cu")
		(net "M_F_CPU1_SA_DQ<9>")
	)
	(segment
		(start 33.664398 -209.201004)
		(end 33.827466 -209.037936)
		(width 0.14478)
		(layer "In11.Cu")
		(net "M_F_CPU1_SA_DQ<9>")
	)
	(segment
		(start 50.80254 -208.123536)
		(end 50.80254 -208.181956)
		(width 0.14478)
		(layer "In11.Cu")
		(net "M_F_CPU1_SA_DQ<9>")
	)
	(segment
		(start 28.75915 -208.189576)
		(end 28.75915 -208.123536)
		(width 0.14478)
		(layer "In11.Cu")
		(net "M_F_CPU1_SA_DQ<9>")
	)
	(segment
		(start 26.5684 -208.810352)
		(end 26.81478 -208.810352)
		(width 0.14478)
		(layer "In11.Cu")
		(net "M_F_CPU1_SA_DQ<9>")
	)
	(segment
		(start 35.66033 -208.123536)
		(end 35.66033 -208.189576)
		(width 0.14478)
		(layer "In11.Cu")
		(net "M_F_CPU1_SA_DQ<9>")
	)
	(segment
		(start 35.66033 -208.189576)
		(end 35.814 -208.343246)
		(width 0.14478)
		(layer "In11.Cu")
		(net "M_F_CPU1_SA_DQ<9>")
	)
	(segment
		(start 46.417738 -208.810352)
		(end 48.255936 -208.810352)
		(width 0.14478)
		(layer "In11.Cu")
		(net "M_F_CPU1_SA_DQ<9>")
	)
	(segment
		(start 48.975518 -209.037936)
		(end 48.975518 -208.97342)
		(width 0.14478)
		(layer "In11.Cu")
		(net "M_F_CPU1_SA_DQ<9>")
	)
	(segment
		(start 56.375808 -208.97342)
		(end 56.538876 -208.810352)
		(width 0.14478)
		(layer "In11.Cu")
		(net "M_F_CPU1_SA_DQ<9>")
	)
	(segment
		(start 22.133052 -208.810352)
		(end 23.6347 -208.810352)
		(width 0.14478)
		(layer "In11.Cu")
		(net "M_F_CPU1_SA_DQ<9>")
	)
	(segment
		(start 25.848818 -208.97342)
		(end 25.848818 -209.037936)
		(width 0.14478)
		(layer "In11.Cu")
		(net "M_F_CPU1_SA_DQ<9>")
	)
	(segment
		(start 55.656226 -208.810352)
		(end 55.819294 -208.97342)
		(width 0.14478)
		(layer "In11.Cu")
		(net "M_F_CPU1_SA_DQ<9>")
	)
	(segment
		(start 55.819294 -209.037936)
		(end 55.982362 -209.201004)
		(width 0.14478)
		(layer "In11.Cu")
		(net "M_F_CPU1_SA_DQ<9>")
	)
	(segment
		(start 31.32074 -208.810352)
		(end 33.107884 -208.810352)
		(width 0.14478)
		(layer "In11.Cu")
		(net "M_F_CPU1_SA_DQ<9>")
	)
	(segment
		(start 25.68575 -208.810352)
		(end 25.848818 -208.97342)
		(width 0.14478)
		(layer "In11.Cu")
		(net "M_F_CPU1_SA_DQ<9>")
	)
	(arc
		(start 79.364078 -230.7971)
		(mid 79.560493 -230.924689)
		(end 79.791814 -230.961438)
		(width 0.0889)
		(layer "In11.Cu")
		(net "M_F_CPU1_SA_DQ<9>")
	)
	(arc
		(start 81.052416 -231.041702)
		(mid 81.235924 -231.087227)
		(end 81.418176 -231.036876)
		(width 0.0889)
		(layer "In11.Cu")
		(net "M_F_CPU1_SA_DQ<9>")
	)
	(arc
		(start 84.238084 -231.036876)
		(mid 84.52104 -230.960699)
		(end 84.803996 -231.036876)
		(width 0.0889)
		(layer "In11.Cu")
		(net "M_F_CPU1_SA_DQ<9>")
	)
	(arc
		(start 80.10398 -231.036876)
		(mid 80.286231 -231.08726)
		(end 80.46974 -231.041702)
		(width 0.0889)
		(layer "In11.Cu")
		(net "M_F_CPU1_SA_DQ<9>")
	)
	(arc
		(start 82.357976 -231.036876)
		(mid 82.640932 -230.960699)
		(end 82.923888 -231.036876)
		(width 0.0889)
		(layer "In11.Cu")
		(net "M_F_CPU1_SA_DQ<9>")
	)
	(arc
		(start 81.418176 -231.036876)
		(mid 81.701132 -230.960699)
		(end 81.984088 -231.036876)
		(width 0.0889)
		(layer "In11.Cu")
		(net "M_F_CPU1_SA_DQ<9>")
	)
	(arc
		(start 80.478122 -231.036876)
		(mid 80.761078 -230.960699)
		(end 81.044034 -231.036876)
		(width 0.0889)
		(layer "In11.Cu")
		(net "M_F_CPU1_SA_DQ<9>")
	)
	(arc
		(start 82.923888 -231.036876)
		(mid 83.106139 -231.08726)
		(end 83.289648 -231.041702)
		(width 0.0889)
		(layer "In11.Cu")
		(net "M_F_CPU1_SA_DQ<9>")
	)
	(arc
		(start 84.812378 -231.041702)
		(mid 84.995886 -231.087227)
		(end 85.178138 -231.036876)
		(width 0.0889)
		(layer "In11.Cu")
		(net "M_F_CPU1_SA_DQ<9>")
	)
	(arc
		(start 85.178138 -231.036876)
		(mid 85.425998 -230.961793)
		(end 85.681312 -231.00538)
		(width 0.0889)
		(layer "In11.Cu")
		(net "M_F_CPU1_SA_DQ<9>")
	)
	(arc
		(start 79.791814 -230.961438)
		(mid 79.953387 -230.976443)
		(end 80.10398 -231.036876)
		(width 0.0889)
		(layer "In11.Cu")
		(net "M_F_CPU1_SA_DQ<9>")
	)
	(arc
		(start 81.984088 -231.036876)
		(mid 82.171032 -231.087165)
		(end 82.357976 -231.036876)
		(width 0.0889)
		(layer "In11.Cu")
		(net "M_F_CPU1_SA_DQ<9>")
	)
	(arc
		(start 83.863942 -231.036876)
		(mid 84.046193 -231.08726)
		(end 84.229702 -231.041702)
		(width 0.0889)
		(layer "In11.Cu")
		(net "M_F_CPU1_SA_DQ<9>")
	)
	(arc
		(start 83.29803 -231.036876)
		(mid 83.580986 -230.960699)
		(end 83.863942 -231.036876)
		(width 0.0889)
		(layer "In11.Cu")
		(net "M_F_CPU1_SA_DQ<9>")
	)
	(segment
		(start 84.987892 -230.170228)
		(end 84.52104 -229.90429)
		(width 0.10668)
		(layer "F.Cu")
		(net "M_F_CPU1_SA_DQ<8>")
	)
	(segment
		(start 53.111908 -206.260446)
		(end 53.961792 -207.11033)
		(width 0.14478)
		(layer "In11.Cu")
		(net "M_F_CPU1_SA_DQ<8>")
	)
	(segment
		(start 40.877744 -207.336136)
		(end 41.040812 -207.499204)
		(width 0.14478)
		(layer "In11.Cu")
		(net "M_F_CPU1_SA_DQ<8>")
	)
	(segment
		(start 23.646638 -207.11033)
		(end 23.791418 -207.25511)
		(width 0.14478)
		(layer "In11.Cu")
		(net "M_F_CPU1_SA_DQ<8>")
	)
	(segment
		(start 26.075386 -207.499204)
		(end 26.238454 -207.336136)
		(width 0.14478)
		(layer "In11.Cu")
		(net "M_F_CPU1_SA_DQ<8>")
	)
	(segment
		(start 25.68194 -207.336136)
		(end 25.845008 -207.499204)
		(width 0.14478)
		(layer "In11.Cu")
		(net "M_F_CPU1_SA_DQ<8>")
	)
	(segment
		(start 48.964596 -207.273398)
		(end 49.127664 -207.11033)
		(width 0.14478)
		(layer "In11.Cu")
		(net "M_F_CPU1_SA_DQ<8>")
	)
	(segment
		(start 26.81478 -207.11033)
		(end 27.664664 -206.260446)
		(width 0.14478)
		(layer "In11.Cu")
		(net "M_F_CPU1_SA_DQ<8>")
	)
	(segment
		(start 41.434258 -207.273398)
		(end 41.597326 -207.11033)
		(width 0.14478)
		(layer "In11.Cu")
		(net "M_F_CPU1_SA_DQ<8>")
	)
	(segment
		(start 54.765956 -207.273398)
		(end 54.765956 -207.328516)
		(width 0.14478)
		(layer "In11.Cu")
		(net "M_F_CPU1_SA_DQ<8>")
	)
	(segment
		(start 27.98572 -206.260446)
		(end 28.148788 -206.423514)
		(width 0.14478)
		(layer "In11.Cu")
		(net "M_F_CPU1_SA_DQ<8>")
	)
	(segment
		(start 27.664664 -206.260446)
		(end 27.98572 -206.260446)
		(width 0.14478)
		(layer "In11.Cu")
		(net "M_F_CPU1_SA_DQ<8>")
	)
	(segment
		(start 59.030362 -206.487776)
		(end 59.030362 -206.423514)
		(width 0.14478)
		(layer "In11.Cu")
		(net "M_F_CPU1_SA_DQ<8>")
	)
	(segment
		(start 33.767776 -207.273398)
		(end 33.930844 -207.11033)
		(width 0.14478)
		(layer "In11.Cu")
		(net "M_F_CPU1_SA_DQ<8>")
	)
	(segment
		(start 71.160386 -221.36862)
		(end 76.095098 -226.303332)
		(width 0.14478)
		(layer "In11.Cu")
		(net "M_F_CPU1_SA_DQ<8>")
	)
	(segment
		(start 26.238454 -207.336136)
		(end 26.238454 -207.273398)
		(width 0.14478)
		(layer "In11.Cu")
		(net "M_F_CPU1_SA_DQ<8>")
	)
	(segment
		(start 78.363826 -229.609904)
		(end 78.99908 -229.609904)
		(width 0.0889)
		(layer "In11.Cu")
		(net "M_F_CPU1_SA_DQ<8>")
	)
	(segment
		(start 57.804558 -206.260446)
		(end 58.31078 -206.260446)
		(width 0.14478)
		(layer "In11.Cu")
		(net "M_F_CPU1_SA_DQ<8>")
	)
	(segment
		(start 33.211262 -207.323436)
		(end 33.37433 -207.486504)
		(width 0.14478)
		(layer "In11.Cu")
		(net "M_F_CPU1_SA_DQ<8>")
	)
	(segment
		(start 35.731958 -206.423514)
		(end 35.731958 -206.480156)
		(width 0.14478)
		(layer "In11.Cu")
		(net "M_F_CPU1_SA_DQ<8>")
	)
	(segment
		(start 36.125404 -206.643224)
		(end 36.288472 -206.480156)
		(width 0.14478)
		(layer "In11.Cu")
		(net "M_F_CPU1_SA_DQ<8>")
	)
	(segment
		(start 60.44311 -207.902048)
		(end 71.160386 -218.619324)
		(width 0.14478)
		(layer "In11.Cu")
		(net "M_F_CPU1_SA_DQ<8>")
	)
	(segment
		(start 48.964596 -207.341216)
		(end 48.964596 -207.273398)
		(width 0.14478)
		(layer "In11.Cu")
		(net "M_F_CPU1_SA_DQ<8>")
	)
	(segment
		(start 50.298858 -206.260446)
		(end 50.681382 -206.260446)
		(width 0.14478)
		(layer "In11.Cu")
		(net "M_F_CPU1_SA_DQ<8>")
	)
	(segment
		(start 77.396086 -228.642164)
		(end 78.363826 -229.609904)
		(width 0.0889)
		(layer "In11.Cu")
		(net "M_F_CPU1_SA_DQ<8>")
	)
	(segment
		(start 26.238454 -207.273398)
		(end 26.401522 -207.11033)
		(width 0.14478)
		(layer "In11.Cu")
		(net "M_F_CPU1_SA_DQ<8>")
	)
	(segment
		(start 78.99908 -229.609904)
		(end 79.557118 -230.167942)
		(width 0.0889)
		(layer "In11.Cu")
		(net "M_F_CPU1_SA_DQ<8>")
	)
	(segment
		(start 40.877744 -207.273398)
		(end 40.877744 -207.336136)
		(width 0.14478)
		(layer "In11.Cu")
		(net "M_F_CPU1_SA_DQ<8>")
	)
	(segment
		(start 51.007518 -206.650844)
		(end 51.237896 -206.650844)
		(width 0.14478)
		(layer "In11.Cu")
		(net "M_F_CPU1_SA_DQ<8>")
	)
	(segment
		(start 55.159402 -207.491584)
		(end 55.32247 -207.328516)
		(width 0.14478)
		(layer "In11.Cu")
		(net "M_F_CPU1_SA_DQ<8>")
	)
	(segment
		(start 45.567854 -206.260446)
		(end 46.417738 -207.11033)
		(width 0.14478)
		(layer "In11.Cu")
		(net "M_F_CPU1_SA_DQ<8>")
	)
	(segment
		(start 24.347932 -207.336136)
		(end 24.347932 -207.273398)
		(width 0.14478)
		(layer "In11.Cu")
		(net "M_F_CPU1_SA_DQ<8>")
	)
	(segment
		(start 43.4721 -206.643224)
		(end 43.702478 -206.643224)
		(width 0.14478)
		(layer "In11.Cu")
		(net "M_F_CPU1_SA_DQ<8>")
	)
	(segment
		(start 76.976986 -227.743004)
		(end 77.396086 -228.162104)
		(width 0.0889)
		(layer "In11.Cu")
		(net "M_F_CPU1_SA_DQ<8>")
	)
	(segment
		(start 54.765956 -207.328516)
		(end 54.929024 -207.491584)
		(width 0.14478)
		(layer "In11.Cu")
		(net "M_F_CPU1_SA_DQ<8>")
	)
	(segment
		(start 22.133052 -207.11033)
		(end 23.646638 -207.11033)
		(width 0.14478)
		(layer "In11.Cu")
		(net "M_F_CPU1_SA_DQ<8>")
	)
	(segment
		(start 51.237896 -206.650844)
		(end 51.400964 -206.487776)
		(width 0.14478)
		(layer "In11.Cu")
		(net "M_F_CPU1_SA_DQ<8>")
	)
	(segment
		(start 43.702478 -206.643224)
		(end 43.865546 -206.480156)
		(width 0.14478)
		(layer "In11.Cu")
		(net "M_F_CPU1_SA_DQ<8>")
	)
	(segment
		(start 56.435498 -207.328516)
		(end 56.435498 -207.273398)
		(width 0.14478)
		(layer "In11.Cu")
		(net "M_F_CPU1_SA_DQ<8>")
	)
	(segment
		(start 59.67095 -206.260446)
		(end 60.44311 -207.032606)
		(width 0.14478)
		(layer "In11.Cu")
		(net "M_F_CPU1_SA_DQ<8>")
	)
	(segment
		(start 41.27119 -207.499204)
		(end 41.434258 -207.336136)
		(width 0.14478)
		(layer "In11.Cu")
		(net "M_F_CPU1_SA_DQ<8>")
	)
	(segment
		(start 55.32247 -207.273398)
		(end 55.485538 -207.11033)
		(width 0.14478)
		(layer "In11.Cu")
		(net "M_F_CPU1_SA_DQ<8>")
	)
	(segment
		(start 28.86837 -206.260446)
		(end 30.470856 -206.260446)
		(width 0.14478)
		(layer "In11.Cu")
		(net "M_F_CPU1_SA_DQ<8>")
	)
	(segment
		(start 37.95268 -206.260446)
		(end 38.802564 -207.11033)
		(width 0.14478)
		(layer "In11.Cu")
		(net "M_F_CPU1_SA_DQ<8>")
	)
	(segment
		(start 76.381102 -227.00488)
		(end 76.976986 -227.600764)
		(width 0.0889)
		(layer "In11.Cu")
		(net "M_F_CPU1_SA_DQ<8>")
	)
	(segment
		(start 25.845008 -207.499204)
		(end 26.075386 -207.499204)
		(width 0.14478)
		(layer "In11.Cu")
		(net "M_F_CPU1_SA_DQ<8>")
	)
	(segment
		(start 56.435498 -207.273398)
		(end 56.598566 -207.11033)
		(width 0.14478)
		(layer "In11.Cu")
		(net "M_F_CPU1_SA_DQ<8>")
	)
	(segment
		(start 55.715916 -207.11033)
		(end 55.878984 -207.273398)
		(width 0.14478)
		(layer "In11.Cu")
		(net "M_F_CPU1_SA_DQ<8>")
	)
	(segment
		(start 58.473848 -206.487776)
		(end 58.636916 -206.650844)
		(width 0.14478)
		(layer "In11.Cu")
		(net "M_F_CPU1_SA_DQ<8>")
	)
	(segment
		(start 58.473848 -206.423514)
		(end 58.473848 -206.487776)
		(width 0.14478)
		(layer "In11.Cu")
		(net "M_F_CPU1_SA_DQ<8>")
	)
	(segment
		(start 71.160386 -218.619324)
		(end 71.160386 -221.36862)
		(width 0.14478)
		(layer "In11.Cu")
		(net "M_F_CPU1_SA_DQ<8>")
	)
	(segment
		(start 36.288472 -206.423514)
		(end 36.45154 -206.260446)
		(width 0.14478)
		(layer "In11.Cu")
		(net "M_F_CPU1_SA_DQ<8>")
	)
	(segment
		(start 44.028614 -206.260446)
		(end 45.567854 -206.260446)
		(width 0.14478)
		(layer "In11.Cu")
		(net "M_F_CPU1_SA_DQ<8>")
	)
	(segment
		(start 59.030362 -206.423514)
		(end 59.19343 -206.260446)
		(width 0.14478)
		(layer "In11.Cu")
		(net "M_F_CPU1_SA_DQ<8>")
	)
	(segment
		(start 56.598566 -207.11033)
		(end 56.954674 -207.11033)
		(width 0.14478)
		(layer "In11.Cu")
		(net "M_F_CPU1_SA_DQ<8>")
	)
	(segment
		(start 28.148788 -206.423514)
		(end 28.148788 -206.475076)
		(width 0.14478)
		(layer "In11.Cu")
		(net "M_F_CPU1_SA_DQ<8>")
	)
	(segment
		(start 81.879694 -230.231696)
		(end 81.888076 -230.22687)
		(width 0.0889)
		(layer "In11.Cu")
		(net "M_F_CPU1_SA_DQ<8>")
	)
	(segment
		(start 77.396086 -228.162104)
		(end 77.396086 -228.642164)
		(width 0.0889)
		(layer "In11.Cu")
		(net "M_F_CPU1_SA_DQ<8>")
	)
	(segment
		(start 28.148788 -206.475076)
		(end 28.311856 -206.638144)
		(width 0.14478)
		(layer "In11.Cu")
		(net "M_F_CPU1_SA_DQ<8>")
	)
	(segment
		(start 54.929024 -207.491584)
		(end 55.159402 -207.491584)
		(width 0.14478)
		(layer "In11.Cu")
		(net "M_F_CPU1_SA_DQ<8>")
	)
	(segment
		(start 28.542234 -206.638144)
		(end 28.705302 -206.475076)
		(width 0.14478)
		(layer "In11.Cu")
		(net "M_F_CPU1_SA_DQ<8>")
	)
	(segment
		(start 34.383218 -207.11033)
		(end 35.233102 -206.260446)
		(width 0.14478)
		(layer "In11.Cu")
		(net "M_F_CPU1_SA_DQ<8>")
	)
	(segment
		(start 33.37433 -207.486504)
		(end 33.604708 -207.486504)
		(width 0.14478)
		(layer "In11.Cu")
		(net "M_F_CPU1_SA_DQ<8>")
	)
	(segment
		(start 58.31078 -206.260446)
		(end 58.473848 -206.423514)
		(width 0.14478)
		(layer "In11.Cu")
		(net "M_F_CPU1_SA_DQ<8>")
	)
	(segment
		(start 25.518872 -207.11033)
		(end 25.68194 -207.273398)
		(width 0.14478)
		(layer "In11.Cu")
		(net "M_F_CPU1_SA_DQ<8>")
	)
	(segment
		(start 23.954486 -207.499204)
		(end 24.184864 -207.499204)
		(width 0.14478)
		(layer "In11.Cu")
		(net "M_F_CPU1_SA_DQ<8>")
	)
	(segment
		(start 53.961792 -207.11033)
		(end 54.602888 -207.11033)
		(width 0.14478)
		(layer "In11.Cu")
		(net "M_F_CPU1_SA_DQ<8>")
	)
	(segment
		(start 48.245014 -207.11033)
		(end 48.408082 -207.273398)
		(width 0.14478)
		(layer "In11.Cu")
		(net "M_F_CPU1_SA_DQ<8>")
	)
	(segment
		(start 33.211262 -207.273398)
		(end 33.211262 -207.323436)
		(width 0.14478)
		(layer "In11.Cu")
		(net "M_F_CPU1_SA_DQ<8>")
	)
	(segment
		(start 48.408082 -207.341216)
		(end 48.57115 -207.504284)
		(width 0.14478)
		(layer "In11.Cu")
		(net "M_F_CPU1_SA_DQ<8>")
	)
	(segment
		(start 23.791418 -207.25511)
		(end 23.791418 -207.336136)
		(width 0.14478)
		(layer "In11.Cu")
		(net "M_F_CPU1_SA_DQ<8>")
	)
	(segment
		(start 28.705302 -206.423514)
		(end 28.86837 -206.260446)
		(width 0.14478)
		(layer "In11.Cu")
		(net "M_F_CPU1_SA_DQ<8>")
	)
	(segment
		(start 41.040812 -207.499204)
		(end 41.27119 -207.499204)
		(width 0.14478)
		(layer "In11.Cu")
		(net "M_F_CPU1_SA_DQ<8>")
	)
	(segment
		(start 56.042052 -207.491584)
		(end 56.27243 -207.491584)
		(width 0.14478)
		(layer "In11.Cu")
		(net "M_F_CPU1_SA_DQ<8>")
	)
	(segment
		(start 50.84445 -206.423514)
		(end 50.84445 -206.487776)
		(width 0.14478)
		(layer "In11.Cu")
		(net "M_F_CPU1_SA_DQ<8>")
	)
	(segment
		(start 40.714676 -207.11033)
		(end 40.877744 -207.273398)
		(width 0.14478)
		(layer "In11.Cu")
		(net "M_F_CPU1_SA_DQ<8>")
	)
	(segment
		(start 35.731958 -206.480156)
		(end 35.895026 -206.643224)
		(width 0.14478)
		(layer "In11.Cu")
		(net "M_F_CPU1_SA_DQ<8>")
	)
	(segment
		(start 21.70811 -206.685388)
		(end 22.133052 -207.11033)
		(width 0.14478)
		(layer "In11.Cu")
		(net "M_F_CPU1_SA_DQ<8>")
	)
	(segment
		(start 84.271104 -230.19512)
		(end 84.367116 -230.16972)
		(width 0.0889)
		(layer "In11.Cu")
		(net "M_F_CPU1_SA_DQ<8>")
	)
	(segment
		(start 55.32247 -207.328516)
		(end 55.32247 -207.273398)
		(width 0.14478)
		(layer "In11.Cu")
		(net "M_F_CPU1_SA_DQ<8>")
	)
	(segment
		(start 49.448974 -207.11033)
		(end 50.298858 -206.260446)
		(width 0.14478)
		(layer "In11.Cu")
		(net "M_F_CPU1_SA_DQ<8>")
	)
	(segment
		(start 48.801528 -207.504284)
		(end 48.964596 -207.341216)
		(width 0.14478)
		(layer "In11.Cu")
		(net "M_F_CPU1_SA_DQ<8>")
	)
	(segment
		(start 28.311856 -206.638144)
		(end 28.542234 -206.638144)
		(width 0.14478)
		(layer "In11.Cu")
		(net "M_F_CPU1_SA_DQ<8>")
	)
	(segment
		(start 50.84445 -206.487776)
		(end 51.007518 -206.650844)
		(width 0.14478)
		(layer "In11.Cu")
		(net "M_F_CPU1_SA_DQ<8>")
	)
	(segment
		(start 58.867294 -206.650844)
		(end 59.030362 -206.487776)
		(width 0.14478)
		(layer "In11.Cu")
		(net "M_F_CPU1_SA_DQ<8>")
	)
	(segment
		(start 43.865546 -206.423514)
		(end 44.028614 -206.260446)
		(width 0.14478)
		(layer "In11.Cu")
		(net "M_F_CPU1_SA_DQ<8>")
	)
	(segment
		(start 51.564032 -206.260446)
		(end 53.111908 -206.260446)
		(width 0.14478)
		(layer "In11.Cu")
		(net "M_F_CPU1_SA_DQ<8>")
	)
	(segment
		(start 51.400964 -206.423514)
		(end 51.564032 -206.260446)
		(width 0.14478)
		(layer "In11.Cu")
		(net "M_F_CPU1_SA_DQ<8>")
	)
	(segment
		(start 83.394042 -230.22687)
		(end 83.402424 -230.231696)
		(width 0.0889)
		(layer "In11.Cu")
		(net "M_F_CPU1_SA_DQ<8>")
	)
	(segment
		(start 24.184864 -207.499204)
		(end 24.347932 -207.336136)
		(width 0.14478)
		(layer "In11.Cu")
		(net "M_F_CPU1_SA_DQ<8>")
	)
	(segment
		(start 79.634334 -230.22687)
		(end 79.646018 -230.233728)
		(width 0.0889)
		(layer "In11.Cu")
		(net "M_F_CPU1_SA_DQ<8>")
	)
	(segment
		(start 41.434258 -207.336136)
		(end 41.434258 -207.273398)
		(width 0.14478)
		(layer "In11.Cu")
		(net "M_F_CPU1_SA_DQ<8>")
	)
	(segment
		(start 23.791418 -207.336136)
		(end 23.954486 -207.499204)
		(width 0.14478)
		(layer "In11.Cu")
		(net "M_F_CPU1_SA_DQ<8>")
	)
	(segment
		(start 58.636916 -206.650844)
		(end 58.867294 -206.650844)
		(width 0.14478)
		(layer "In11.Cu")
		(net "M_F_CPU1_SA_DQ<8>")
	)
	(segment
		(start 35.233102 -206.260446)
		(end 35.56889 -206.260446)
		(width 0.14478)
		(layer "In11.Cu")
		(net "M_F_CPU1_SA_DQ<8>")
	)
	(segment
		(start 33.604708 -207.486504)
		(end 33.767776 -207.323436)
		(width 0.14478)
		(layer "In11.Cu")
		(net "M_F_CPU1_SA_DQ<8>")
	)
	(segment
		(start 56.27243 -207.491584)
		(end 56.435498 -207.328516)
		(width 0.14478)
		(layer "In11.Cu")
		(net "M_F_CPU1_SA_DQ<8>")
	)
	(segment
		(start 28.705302 -206.475076)
		(end 28.705302 -206.423514)
		(width 0.14478)
		(layer "In11.Cu")
		(net "M_F_CPU1_SA_DQ<8>")
	)
	(segment
		(start 48.57115 -207.504284)
		(end 48.801528 -207.504284)
		(width 0.14478)
		(layer "In11.Cu")
		(net "M_F_CPU1_SA_DQ<8>")
	)
	(segment
		(start 43.865546 -206.480156)
		(end 43.865546 -206.423514)
		(width 0.14478)
		(layer "In11.Cu")
		(net "M_F_CPU1_SA_DQ<8>")
	)
	(segment
		(start 33.767776 -207.323436)
		(end 33.767776 -207.273398)
		(width 0.14478)
		(layer "In11.Cu")
		(net "M_F_CPU1_SA_DQ<8>")
	)
	(segment
		(start 26.401522 -207.11033)
		(end 26.81478 -207.11033)
		(width 0.14478)
		(layer "In11.Cu")
		(net "M_F_CPU1_SA_DQ<8>")
	)
	(segment
		(start 55.878984 -207.328516)
		(end 56.042052 -207.491584)
		(width 0.14478)
		(layer "In11.Cu")
		(net "M_F_CPU1_SA_DQ<8>")
	)
	(segment
		(start 56.954674 -207.11033)
		(end 57.804558 -206.260446)
		(width 0.14478)
		(layer "In11.Cu")
		(net "M_F_CPU1_SA_DQ<8>")
	)
	(segment
		(start 76.976986 -227.600764)
		(end 76.976986 -227.743004)
		(width 0.0889)
		(layer "In11.Cu")
		(net "M_F_CPU1_SA_DQ<8>")
	)
	(segment
		(start 76.381102 -226.589336)
		(end 76.381102 -227.00488)
		(width 0.0889)
		(layer "In11.Cu")
		(net "M_F_CPU1_SA_DQ<8>")
	)
	(segment
		(start 30.470856 -206.260446)
		(end 31.32074 -207.11033)
		(width 0.14478)
		(layer "In11.Cu")
		(net "M_F_CPU1_SA_DQ<8>")
	)
	(segment
		(start 84.367116 -230.16972)
		(end 84.52104 -229.90429)
		(width 0.0889)
		(layer "In11.Cu")
		(net "M_F_CPU1_SA_DQ<8>")
	)
	(segment
		(start 35.56889 -206.260446)
		(end 35.731958 -206.423514)
		(width 0.14478)
		(layer "In11.Cu")
		(net "M_F_CPU1_SA_DQ<8>")
	)
	(segment
		(start 82.453988 -230.22687)
		(end 82.46237 -230.231696)
		(width 0.0889)
		(layer "In11.Cu")
		(net "M_F_CPU1_SA_DQ<8>")
	)
	(segment
		(start 49.127664 -207.11033)
		(end 49.448974 -207.11033)
		(width 0.14478)
		(layer "In11.Cu")
		(net "M_F_CPU1_SA_DQ<8>")
	)
	(segment
		(start 50.681382 -206.260446)
		(end 50.84445 -206.423514)
		(width 0.14478)
		(layer "In11.Cu")
		(net "M_F_CPU1_SA_DQ<8>")
	)
	(segment
		(start 35.895026 -206.643224)
		(end 36.125404 -206.643224)
		(width 0.14478)
		(layer "In11.Cu")
		(net "M_F_CPU1_SA_DQ<8>")
	)
	(segment
		(start 48.408082 -207.273398)
		(end 48.408082 -207.341216)
		(width 0.14478)
		(layer "In11.Cu")
		(net "M_F_CPU1_SA_DQ<8>")
	)
	(segment
		(start 36.45154 -206.260446)
		(end 37.95268 -206.260446)
		(width 0.14478)
		(layer "In11.Cu")
		(net "M_F_CPU1_SA_DQ<8>")
	)
	(segment
		(start 60.44311 -207.032606)
		(end 60.44311 -207.902048)
		(width 0.14478)
		(layer "In11.Cu")
		(net "M_F_CPU1_SA_DQ<8>")
	)
	(segment
		(start 43.309032 -206.423514)
		(end 43.309032 -206.480156)
		(width 0.14478)
		(layer "In11.Cu")
		(net "M_F_CPU1_SA_DQ<8>")
	)
	(segment
		(start 33.048194 -207.11033)
		(end 33.211262 -207.273398)
		(width 0.14478)
		(layer "In11.Cu")
		(net "M_F_CPU1_SA_DQ<8>")
	)
	(segment
		(start 31.32074 -207.11033)
		(end 33.048194 -207.11033)
		(width 0.14478)
		(layer "In11.Cu")
		(net "M_F_CPU1_SA_DQ<8>")
	)
	(segment
		(start 24.511 -207.11033)
		(end 25.518872 -207.11033)
		(width 0.14478)
		(layer "In11.Cu")
		(net "M_F_CPU1_SA_DQ<8>")
	)
	(segment
		(start 33.930844 -207.11033)
		(end 34.383218 -207.11033)
		(width 0.14478)
		(layer "In11.Cu")
		(net "M_F_CPU1_SA_DQ<8>")
	)
	(segment
		(start 38.802564 -207.11033)
		(end 40.714676 -207.11033)
		(width 0.14478)
		(layer "In11.Cu")
		(net "M_F_CPU1_SA_DQ<8>")
	)
	(segment
		(start 76.095098 -226.303332)
		(end 76.381102 -226.589336)
		(width 0.0889)
		(layer "In11.Cu")
		(net "M_F_CPU1_SA_DQ<8>")
	)
	(segment
		(start 42.792904 -206.260446)
		(end 43.145964 -206.260446)
		(width 0.14478)
		(layer "In11.Cu")
		(net "M_F_CPU1_SA_DQ<8>")
	)
	(segment
		(start 59.19343 -206.260446)
		(end 59.67095 -206.260446)
		(width 0.14478)
		(layer "In11.Cu")
		(net "M_F_CPU1_SA_DQ<8>")
	)
	(segment
		(start 25.68194 -207.273398)
		(end 25.68194 -207.336136)
		(width 0.14478)
		(layer "In11.Cu")
		(net "M_F_CPU1_SA_DQ<8>")
	)
	(segment
		(start 55.485538 -207.11033)
		(end 55.715916 -207.11033)
		(width 0.14478)
		(layer "In11.Cu")
		(net "M_F_CPU1_SA_DQ<8>")
	)
	(segment
		(start 55.878984 -207.273398)
		(end 55.878984 -207.328516)
		(width 0.14478)
		(layer "In11.Cu")
		(net "M_F_CPU1_SA_DQ<8>")
	)
	(segment
		(start 24.347932 -207.273398)
		(end 24.511 -207.11033)
		(width 0.14478)
		(layer "In11.Cu")
		(net "M_F_CPU1_SA_DQ<8>")
	)
	(segment
		(start 41.94302 -207.11033)
		(end 42.792904 -206.260446)
		(width 0.14478)
		(layer "In11.Cu")
		(net "M_F_CPU1_SA_DQ<8>")
	)
	(segment
		(start 79.63408 -230.22687)
		(end 79.634334 -230.22687)
		(width 0.0889)
		(layer "In11.Cu")
		(net "M_F_CPU1_SA_DQ<8>")
	)
	(segment
		(start 43.145964 -206.260446)
		(end 43.309032 -206.423514)
		(width 0.14478)
		(layer "In11.Cu")
		(net "M_F_CPU1_SA_DQ<8>")
	)
	(segment
		(start 51.400964 -206.487776)
		(end 51.400964 -206.423514)
		(width 0.14478)
		(layer "In11.Cu")
		(net "M_F_CPU1_SA_DQ<8>")
	)
	(segment
		(start 43.309032 -206.480156)
		(end 43.4721 -206.643224)
		(width 0.14478)
		(layer "In11.Cu")
		(net "M_F_CPU1_SA_DQ<8>")
	)
	(segment
		(start 41.597326 -207.11033)
		(end 41.94302 -207.11033)
		(width 0.14478)
		(layer "In11.Cu")
		(net "M_F_CPU1_SA_DQ<8>")
	)
	(segment
		(start 54.602888 -207.11033)
		(end 54.765956 -207.273398)
		(width 0.14478)
		(layer "In11.Cu")
		(net "M_F_CPU1_SA_DQ<8>")
	)
	(segment
		(start 36.288472 -206.480156)
		(end 36.288472 -206.423514)
		(width 0.14478)
		(layer "In11.Cu")
		(net "M_F_CPU1_SA_DQ<8>")
	)
	(segment
		(start 46.417738 -207.11033)
		(end 48.245014 -207.11033)
		(width 0.14478)
		(layer "In11.Cu")
		(net "M_F_CPU1_SA_DQ<8>")
	)
	(arc
		(start 83.768184 -230.22687)
		(mid 84.015897 -230.151684)
		(end 84.271104 -230.19512)
		(width 0.0889)
		(layer "In11.Cu")
		(net "M_F_CPU1_SA_DQ<8>")
	)
	(arc
		(start 82.82813 -230.22687)
		(mid 83.111086 -230.150727)
		(end 83.394042 -230.22687)
		(width 0.0889)
		(layer "In11.Cu")
		(net "M_F_CPU1_SA_DQ<8>")
	)
	(arc
		(start 80.948022 -230.22687)
		(mid 81.230978 -230.150727)
		(end 81.513934 -230.22687)
		(width 0.0889)
		(layer "In11.Cu")
		(net "M_F_CPU1_SA_DQ<8>")
	)
	(arc
		(start 79.557118 -230.167942)
		(mid 79.593671 -230.199925)
		(end 79.63408 -230.22687)
		(width 0.0889)
		(layer "In11.Cu")
		(net "M_F_CPU1_SA_DQ<8>")
	)
	(arc
		(start 81.888076 -230.22687)
		(mid 82.171032 -230.150727)
		(end 82.453988 -230.22687)
		(width 0.0889)
		(layer "In11.Cu")
		(net "M_F_CPU1_SA_DQ<8>")
	)
	(arc
		(start 82.46237 -230.231696)
		(mid 82.645878 -230.27719)
		(end 82.82813 -230.22687)
		(width 0.0889)
		(layer "In11.Cu")
		(net "M_F_CPU1_SA_DQ<8>")
	)
	(arc
		(start 83.402424 -230.231696)
		(mid 83.585932 -230.27719)
		(end 83.768184 -230.22687)
		(width 0.0889)
		(layer "In11.Cu")
		(net "M_F_CPU1_SA_DQ<8>")
	)
	(arc
		(start 80.008222 -230.22687)
		(mid 80.291178 -230.150727)
		(end 80.574134 -230.22687)
		(width 0.0889)
		(layer "In11.Cu")
		(net "M_F_CPU1_SA_DQ<8>")
	)
	(arc
		(start 80.574134 -230.22687)
		(mid 80.761078 -230.277125)
		(end 80.948022 -230.22687)
		(width 0.0889)
		(layer "In11.Cu")
		(net "M_F_CPU1_SA_DQ<8>")
	)
	(arc
		(start 79.646018 -230.233728)
		(mid 79.828019 -230.277261)
		(end 80.008222 -230.22687)
		(width 0.0889)
		(layer "In11.Cu")
		(net "M_F_CPU1_SA_DQ<8>")
	)
	(arc
		(start 81.513934 -230.22687)
		(mid 81.696185 -230.27722)
		(end 81.879694 -230.231696)
		(width 0.0889)
		(layer "In11.Cu")
		(net "M_F_CPU1_SA_DQ<8>")
	)
	(segment
		(start 85.927946 -230.170228)
		(end 85.461094 -229.90429)
		(width 0.10668)
		(layer "F.Cu")
		(net "M_F_CPU1_SA_DQ<7>")
	)
	(segment
		(start 19.30019 -206.097378)
		(end 19.463258 -206.260446)
		(width 0.14478)
		(layer "In11.Cu")
		(net "M_F_CPU1_SA_DQ<7>")
	)
	(segment
		(start 20.576286 -206.260446)
		(end 26.727658 -206.260446)
		(width 0.14478)
		(layer "In11.Cu")
		(net "M_F_CPU1_SA_DQ<7>")
	)
	(segment
		(start 83.394042 -229.581964)
		(end 83.402424 -229.577138)
		(width 0.0889)
		(layer "In11.Cu")
		(net "M_F_CPU1_SA_DQ<7>")
	)
	(segment
		(start 61.21273 -206.935832)
		(end 61.21273 -207.869536)
		(width 0.14478)
		(layer "In11.Cu")
		(net "M_F_CPU1_SA_DQ<7>")
	)
	(segment
		(start 38.113208 -205.410308)
		(end 38.963346 -206.260446)
		(width 0.14478)
		(layer "In11.Cu")
		(net "M_F_CPU1_SA_DQ<7>")
	)
	(segment
		(start 20.413218 -205.528672)
		(end 20.413218 -206.097378)
		(width 0.14478)
		(layer "In11.Cu")
		(net "M_F_CPU1_SA_DQ<7>")
	)
	(segment
		(start 50.23993 -205.410308)
		(end 53.155088 -205.410308)
		(width 0.14478)
		(layer "In11.Cu")
		(net "M_F_CPU1_SA_DQ<7>")
	)
	(segment
		(start 82.453988 -229.581964)
		(end 82.46237 -229.577138)
		(width 0.0889)
		(layer "In11.Cu")
		(net "M_F_CPU1_SA_DQ<7>")
	)
	(segment
		(start 77.236066 -227.542344)
		(end 77.236066 -227.679504)
		(width 0.0889)
		(layer "In11.Cu")
		(net "M_F_CPU1_SA_DQ<7>")
	)
	(segment
		(start 42.742104 -205.410308)
		(end 45.618654 -205.410308)
		(width 0.14478)
		(layer "In11.Cu")
		(net "M_F_CPU1_SA_DQ<7>")
	)
	(segment
		(start 53.155088 -205.410308)
		(end 54.005226 -206.260446)
		(width 0.14478)
		(layer "In11.Cu")
		(net "M_F_CPU1_SA_DQ<7>")
	)
	(segment
		(start 76.641706 -226.058984)
		(end 76.641706 -226.947984)
		(width 0.0889)
		(layer "In11.Cu")
		(net "M_F_CPU1_SA_DQ<7>")
	)
	(segment
		(start 79.369666 -229.531164)
		(end 79.821024 -229.531164)
		(width 0.0889)
		(layer "In11.Cu")
		(net "M_F_CPU1_SA_DQ<7>")
	)
	(segment
		(start 85.592666 -229.555802)
		(end 85.615018 -229.63886)
		(width 0.0889)
		(layer "In11.Cu")
		(net "M_F_CPU1_SA_DQ<7>")
	)
	(segment
		(start 31.393892 -206.260446)
		(end 34.35858 -206.260446)
		(width 0.14478)
		(layer "In11.Cu")
		(net "M_F_CPU1_SA_DQ<7>")
	)
	(segment
		(start 19.856704 -206.097378)
		(end 19.856704 -205.528672)
		(width 0.14478)
		(layer "In11.Cu")
		(net "M_F_CPU1_SA_DQ<7>")
	)
	(segment
		(start 54.005226 -206.260446)
		(end 56.936132 -206.260446)
		(width 0.14478)
		(layer "In11.Cu")
		(net "M_F_CPU1_SA_DQ<7>")
	)
	(segment
		(start 78.569566 -228.731064)
		(end 79.369666 -229.531164)
		(width 0.0889)
		(layer "In11.Cu")
		(net "M_F_CPU1_SA_DQ<7>")
	)
	(segment
		(start 18.580608 -206.260446)
		(end 18.743676 -206.097378)
		(width 0.14478)
		(layer "In11.Cu")
		(net "M_F_CPU1_SA_DQ<7>")
	)
	(segment
		(start 18.906744 -205.365604)
		(end 19.137122 -205.365604)
		(width 0.14478)
		(layer "In11.Cu")
		(net "M_F_CPU1_SA_DQ<7>")
	)
	(segment
		(start 19.137122 -205.365604)
		(end 19.30019 -205.528672)
		(width 0.14478)
		(layer "In11.Cu")
		(net "M_F_CPU1_SA_DQ<7>")
	)
	(segment
		(start 35.208718 -205.410308)
		(end 38.113208 -205.410308)
		(width 0.14478)
		(layer "In11.Cu")
		(net "M_F_CPU1_SA_DQ<7>")
	)
	(segment
		(start 41.891966 -206.260446)
		(end 42.742104 -205.410308)
		(width 0.14478)
		(layer "In11.Cu")
		(net "M_F_CPU1_SA_DQ<7>")
	)
	(segment
		(start 71.722234 -218.37904)
		(end 71.722234 -221.139512)
		(width 0.14478)
		(layer "In11.Cu")
		(net "M_F_CPU1_SA_DQ<7>")
	)
	(segment
		(start 18.743676 -206.097378)
		(end 18.743676 -205.528672)
		(width 0.14478)
		(layer "In11.Cu")
		(net "M_F_CPU1_SA_DQ<7>")
	)
	(segment
		(start 61.21273 -207.869536)
		(end 71.722234 -218.37904)
		(width 0.14478)
		(layer "In11.Cu")
		(net "M_F_CPU1_SA_DQ<7>")
	)
	(segment
		(start 20.413218 -206.097378)
		(end 20.576286 -206.260446)
		(width 0.14478)
		(layer "In11.Cu")
		(net "M_F_CPU1_SA_DQ<7>")
	)
	(segment
		(start 45.618654 -205.410308)
		(end 46.468792 -206.260446)
		(width 0.14478)
		(layer "In11.Cu")
		(net "M_F_CPU1_SA_DQ<7>")
	)
	(segment
		(start 19.856704 -205.528672)
		(end 20.019772 -205.365604)
		(width 0.14478)
		(layer "In11.Cu")
		(net "M_F_CPU1_SA_DQ<7>")
	)
	(segment
		(start 57.78627 -205.410308)
		(end 59.687206 -205.410308)
		(width 0.14478)
		(layer "In11.Cu")
		(net "M_F_CPU1_SA_DQ<7>")
	)
	(segment
		(start 46.468792 -206.260446)
		(end 49.389792 -206.260446)
		(width 0.14478)
		(layer "In11.Cu")
		(net "M_F_CPU1_SA_DQ<7>")
	)
	(segment
		(start 49.389792 -206.260446)
		(end 50.23993 -205.410308)
		(width 0.14478)
		(layer "In11.Cu")
		(net "M_F_CPU1_SA_DQ<7>")
	)
	(segment
		(start 38.963346 -206.260446)
		(end 41.891966 -206.260446)
		(width 0.14478)
		(layer "In11.Cu")
		(net "M_F_CPU1_SA_DQ<7>")
	)
	(segment
		(start 19.30019 -205.528672)
		(end 19.30019 -206.097378)
		(width 0.14478)
		(layer "In11.Cu")
		(net "M_F_CPU1_SA_DQ<7>")
	)
	(segment
		(start 85.615018 -229.63886)
		(end 85.461094 -229.90429)
		(width 0.0889)
		(layer "In11.Cu")
		(net "M_F_CPU1_SA_DQ<7>")
	)
	(segment
		(start 59.687206 -205.410308)
		(end 61.21273 -206.935832)
		(width 0.14478)
		(layer "In11.Cu")
		(net "M_F_CPU1_SA_DQ<7>")
	)
	(segment
		(start 20.25015 -205.365604)
		(end 20.413218 -205.528672)
		(width 0.14478)
		(layer "In11.Cu")
		(net "M_F_CPU1_SA_DQ<7>")
	)
	(segment
		(start 26.727658 -206.260446)
		(end 27.577796 -205.410308)
		(width 0.14478)
		(layer "In11.Cu")
		(net "M_F_CPU1_SA_DQ<7>")
	)
	(segment
		(start 76.641706 -226.947984)
		(end 77.236066 -227.542344)
		(width 0.0889)
		(layer "In11.Cu")
		(net "M_F_CPU1_SA_DQ<7>")
	)
	(segment
		(start 27.577796 -205.410308)
		(end 30.543754 -205.410308)
		(width 0.14478)
		(layer "In11.Cu")
		(net "M_F_CPU1_SA_DQ<7>")
	)
	(segment
		(start 71.722234 -221.139512)
		(end 75.85837 -225.275648)
		(width 0.14478)
		(layer "In11.Cu")
		(net "M_F_CPU1_SA_DQ<7>")
	)
	(segment
		(start 19.463258 -206.260446)
		(end 19.693636 -206.260446)
		(width 0.14478)
		(layer "In11.Cu")
		(net "M_F_CPU1_SA_DQ<7>")
	)
	(segment
		(start 75.85837 -225.275648)
		(end 76.641706 -226.058984)
		(width 0.0889)
		(layer "In11.Cu")
		(net "M_F_CPU1_SA_DQ<7>")
	)
	(segment
		(start 17.608042 -205.83525)
		(end 18.033238 -206.260446)
		(width 0.14478)
		(layer "In11.Cu")
		(net "M_F_CPU1_SA_DQ<7>")
	)
	(segment
		(start 81.879694 -229.577138)
		(end 81.888076 -229.581964)
		(width 0.0889)
		(layer "In11.Cu")
		(net "M_F_CPU1_SA_DQ<7>")
	)
	(segment
		(start 18.033238 -206.260446)
		(end 18.580608 -206.260446)
		(width 0.14478)
		(layer "In11.Cu")
		(net "M_F_CPU1_SA_DQ<7>")
	)
	(segment
		(start 34.35858 -206.260446)
		(end 35.208718 -205.410308)
		(width 0.14478)
		(layer "In11.Cu")
		(net "M_F_CPU1_SA_DQ<7>")
	)
	(segment
		(start 77.236066 -227.679504)
		(end 78.287626 -228.731064)
		(width 0.0889)
		(layer "In11.Cu")
		(net "M_F_CPU1_SA_DQ<7>")
	)
	(segment
		(start 30.543754 -205.410308)
		(end 31.393892 -206.260446)
		(width 0.14478)
		(layer "In11.Cu")
		(net "M_F_CPU1_SA_DQ<7>")
	)
	(segment
		(start 19.693636 -206.260446)
		(end 19.856704 -206.097378)
		(width 0.14478)
		(layer "In11.Cu")
		(net "M_F_CPU1_SA_DQ<7>")
	)
	(segment
		(start 20.019772 -205.365604)
		(end 20.25015 -205.365604)
		(width 0.14478)
		(layer "In11.Cu")
		(net "M_F_CPU1_SA_DQ<7>")
	)
	(segment
		(start 18.743676 -205.528672)
		(end 18.906744 -205.365604)
		(width 0.14478)
		(layer "In11.Cu")
		(net "M_F_CPU1_SA_DQ<7>")
	)
	(segment
		(start 78.287626 -228.731064)
		(end 78.569566 -228.731064)
		(width 0.0889)
		(layer "In11.Cu")
		(net "M_F_CPU1_SA_DQ<7>")
	)
	(segment
		(start 56.936132 -206.260446)
		(end 57.78627 -205.410308)
		(width 0.14478)
		(layer "In11.Cu")
		(net "M_F_CPU1_SA_DQ<7>")
	)
	(arc
		(start 84.334096 -229.581964)
		(mid 84.52104 -229.531675)
		(end 84.707984 -229.581964)
		(width 0.0889)
		(layer "In11.Cu")
		(net "M_F_CPU1_SA_DQ<7>")
	)
	(arc
		(start 83.768184 -229.581964)
		(mid 84.05114 -229.658141)
		(end 84.334096 -229.581964)
		(width 0.0889)
		(layer "In11.Cu")
		(net "M_F_CPU1_SA_DQ<7>")
	)
	(arc
		(start 80.574134 -229.581964)
		(mid 80.761078 -229.531675)
		(end 80.948022 -229.581964)
		(width 0.0889)
		(layer "In11.Cu")
		(net "M_F_CPU1_SA_DQ<7>")
	)
	(arc
		(start 83.402424 -229.577138)
		(mid 83.585932 -229.531613)
		(end 83.768184 -229.581964)
		(width 0.0889)
		(layer "In11.Cu")
		(net "M_F_CPU1_SA_DQ<7>")
	)
	(arc
		(start 82.82813 -229.581964)
		(mid 83.111086 -229.658141)
		(end 83.394042 -229.581964)
		(width 0.0889)
		(layer "In11.Cu")
		(net "M_F_CPU1_SA_DQ<7>")
	)
	(arc
		(start 81.888076 -229.581964)
		(mid 82.171032 -229.658141)
		(end 82.453988 -229.581964)
		(width 0.0889)
		(layer "In11.Cu")
		(net "M_F_CPU1_SA_DQ<7>")
	)
	(arc
		(start 80.008222 -229.581964)
		(mid 80.291178 -229.658141)
		(end 80.574134 -229.581964)
		(width 0.0889)
		(layer "In11.Cu")
		(net "M_F_CPU1_SA_DQ<7>")
	)
	(arc
		(start 84.707984 -229.581964)
		(mid 84.99094 -229.658141)
		(end 85.273896 -229.581964)
		(width 0.0889)
		(layer "In11.Cu")
		(net "M_F_CPU1_SA_DQ<7>")
	)
	(arc
		(start 82.46237 -229.577138)
		(mid 82.645878 -229.531613)
		(end 82.82813 -229.581964)
		(width 0.0889)
		(layer "In11.Cu")
		(net "M_F_CPU1_SA_DQ<7>")
	)
	(arc
		(start 79.821024 -229.531164)
		(mid 79.917977 -229.544195)
		(end 80.008222 -229.581964)
		(width 0.0889)
		(layer "In11.Cu")
		(net "M_F_CPU1_SA_DQ<7>")
	)
	(arc
		(start 81.513934 -229.581964)
		(mid 81.696185 -229.53158)
		(end 81.879694 -229.577138)
		(width 0.0889)
		(layer "In11.Cu")
		(net "M_F_CPU1_SA_DQ<7>")
	)
	(arc
		(start 80.948022 -229.581964)
		(mid 81.230978 -229.658141)
		(end 81.513934 -229.581964)
		(width 0.0889)
		(layer "In11.Cu")
		(net "M_F_CPU1_SA_DQ<7>")
	)
	(arc
		(start 85.273896 -229.581964)
		(mid 85.430334 -229.532959)
		(end 85.592666 -229.555802)
		(width 0.0889)
		(layer "In11.Cu")
		(net "M_F_CPU1_SA_DQ<7>")
	)
	(segment
		(start 84.517992 -229.360476)
		(end 84.05114 -229.094538)
		(width 0.10668)
		(layer "F.Cu")
		(net "M_F_CPU1_SA_DQ<6>")
	)
	(segment
		(start 84.205064 -228.829108)
		(end 84.05114 -229.094538)
		(width 0.0889)
		(layer "In11.Cu")
		(net "M_F_CPU1_SA_DQ<6>")
	)
	(segment
		(start 27.577796 -203.710286)
		(end 30.543754 -203.710286)
		(width 0.14478)
		(layer "In11.Cu")
		(net "M_F_CPU1_SA_DQ<6>")
	)
	(segment
		(start 59.811666 -203.710286)
		(end 62.125606 -206.024226)
		(width 0.14478)
		(layer "In11.Cu")
		(net "M_F_CPU1_SA_DQ<6>")
	)
	(segment
		(start 20.513802 -203.635864)
		(end 20.74418 -203.635864)
		(width 0.14478)
		(layer "In11.Cu")
		(net "M_F_CPU1_SA_DQ<6>")
	)
	(segment
		(start 19.237706 -203.798932)
		(end 19.400774 -203.635864)
		(width 0.14478)
		(layer "In11.Cu")
		(net "M_F_CPU1_SA_DQ<6>")
	)
	(segment
		(start 76.418948 -224.421446)
		(end 76.639166 -224.641664)
		(width 0.0889)
		(layer "In11.Cu")
		(net "M_F_CPU1_SA_DQ<6>")
	)
	(segment
		(start 30.543754 -203.710286)
		(end 31.393892 -204.560424)
		(width 0.14478)
		(layer "In11.Cu")
		(net "M_F_CPU1_SA_DQ<6>")
	)
	(segment
		(start 20.187666 -204.560424)
		(end 20.350734 -204.397356)
		(width 0.14478)
		(layer "In11.Cu")
		(net "M_F_CPU1_SA_DQ<6>")
	)
	(segment
		(start 34.35858 -204.560424)
		(end 35.208718 -203.710286)
		(width 0.14478)
		(layer "In11.Cu")
		(net "M_F_CPU1_SA_DQ<6>")
	)
	(segment
		(start 77.515466 -226.302824)
		(end 77.794866 -226.977702)
		(width 0.0889)
		(layer "In11.Cu")
		(net "M_F_CPU1_SA_DQ<6>")
	)
	(segment
		(start 17.608042 -204.135228)
		(end 18.033238 -204.560424)
		(width 0.14478)
		(layer "In11.Cu")
		(net "M_F_CPU1_SA_DQ<6>")
	)
	(segment
		(start 19.631152 -203.635864)
		(end 19.79422 -203.798932)
		(width 0.14478)
		(layer "In11.Cu")
		(net "M_F_CPU1_SA_DQ<6>")
	)
	(segment
		(start 38.963346 -204.560424)
		(end 41.891966 -204.560424)
		(width 0.14478)
		(layer "In11.Cu")
		(net "M_F_CPU1_SA_DQ<6>")
	)
	(segment
		(start 78.772258 -228.167184)
		(end 79.453232 -228.848158)
		(width 0.0889)
		(layer "In11.Cu")
		(net "M_F_CPU1_SA_DQ<6>")
	)
	(segment
		(start 35.208718 -203.710286)
		(end 38.113208 -203.710286)
		(width 0.14478)
		(layer "In11.Cu")
		(net "M_F_CPU1_SA_DQ<6>")
	)
	(segment
		(start 56.936132 -204.560424)
		(end 57.78627 -203.710286)
		(width 0.14478)
		(layer "In11.Cu")
		(net "M_F_CPU1_SA_DQ<6>")
	)
	(segment
		(start 19.957288 -204.560424)
		(end 20.187666 -204.560424)
		(width 0.14478)
		(layer "In11.Cu")
		(net "M_F_CPU1_SA_DQ<6>")
	)
	(segment
		(start 19.79422 -204.397356)
		(end 19.957288 -204.560424)
		(width 0.14478)
		(layer "In11.Cu")
		(net "M_F_CPU1_SA_DQ<6>")
	)
	(segment
		(start 21.070316 -204.560424)
		(end 26.727658 -204.560424)
		(width 0.14478)
		(layer "In11.Cu")
		(net "M_F_CPU1_SA_DQ<6>")
	)
	(segment
		(start 62.125606 -207.367632)
		(end 72.722486 -217.964512)
		(width 0.14478)
		(layer "In11.Cu")
		(net "M_F_CPU1_SA_DQ<6>")
	)
	(segment
		(start 77.794866 -227.656644)
		(end 78.305406 -228.167184)
		(width 0.0889)
		(layer "In11.Cu")
		(net "M_F_CPU1_SA_DQ<6>")
	)
	(segment
		(start 57.78627 -203.710286)
		(end 59.811666 -203.710286)
		(width 0.14478)
		(layer "In11.Cu")
		(net "M_F_CPU1_SA_DQ<6>")
	)
	(segment
		(start 53.155088 -203.710286)
		(end 54.005226 -204.560424)
		(width 0.14478)
		(layer "In11.Cu")
		(net "M_F_CPU1_SA_DQ<6>")
	)
	(segment
		(start 72.722486 -220.724984)
		(end 76.418948 -224.421446)
		(width 0.14478)
		(layer "In11.Cu")
		(net "M_F_CPU1_SA_DQ<6>")
	)
	(segment
		(start 20.350734 -203.798932)
		(end 20.513802 -203.635864)
		(width 0.14478)
		(layer "In11.Cu")
		(net "M_F_CPU1_SA_DQ<6>")
	)
	(segment
		(start 20.907248 -203.798932)
		(end 20.907248 -204.397356)
		(width 0.14478)
		(layer "In11.Cu")
		(net "M_F_CPU1_SA_DQ<6>")
	)
	(segment
		(start 18.033238 -204.560424)
		(end 19.074638 -204.560424)
		(width 0.14478)
		(layer "In11.Cu")
		(net "M_F_CPU1_SA_DQ<6>")
	)
	(segment
		(start 76.639166 -224.641664)
		(end 76.639166 -225.426524)
		(width 0.0889)
		(layer "In11.Cu")
		(net "M_F_CPU1_SA_DQ<6>")
	)
	(segment
		(start 38.113208 -203.710286)
		(end 38.963346 -204.560424)
		(width 0.14478)
		(layer "In11.Cu")
		(net "M_F_CPU1_SA_DQ<6>")
	)
	(segment
		(start 76.639166 -225.426524)
		(end 77.515466 -226.302824)
		(width 0.0889)
		(layer "In11.Cu")
		(net "M_F_CPU1_SA_DQ<6>")
	)
	(segment
		(start 19.400774 -203.635864)
		(end 19.631152 -203.635864)
		(width 0.14478)
		(layer "In11.Cu")
		(net "M_F_CPU1_SA_DQ<6>")
	)
	(segment
		(start 79.453232 -228.848158)
		(end 79.821024 -228.848158)
		(width 0.0889)
		(layer "In11.Cu")
		(net "M_F_CPU1_SA_DQ<6>")
	)
	(segment
		(start 81.044034 -228.771958)
		(end 81.052416 -228.767132)
		(width 0.0889)
		(layer "In11.Cu")
		(net "M_F_CPU1_SA_DQ<6>")
	)
	(segment
		(start 19.237706 -204.397356)
		(end 19.237706 -203.798932)
		(width 0.14478)
		(layer "In11.Cu")
		(net "M_F_CPU1_SA_DQ<6>")
	)
	(segment
		(start 83.289648 -228.767132)
		(end 83.29803 -228.771958)
		(width 0.0889)
		(layer "In11.Cu")
		(net "M_F_CPU1_SA_DQ<6>")
	)
	(segment
		(start 80.46974 -228.767132)
		(end 80.478122 -228.771958)
		(width 0.0889)
		(layer "In11.Cu")
		(net "M_F_CPU1_SA_DQ<6>")
	)
	(segment
		(start 62.125606 -206.024226)
		(end 62.125606 -207.367632)
		(width 0.14478)
		(layer "In11.Cu")
		(net "M_F_CPU1_SA_DQ<6>")
	)
	(segment
		(start 54.005226 -204.560424)
		(end 56.936132 -204.560424)
		(width 0.14478)
		(layer "In11.Cu")
		(net "M_F_CPU1_SA_DQ<6>")
	)
	(segment
		(start 19.79422 -203.798932)
		(end 19.79422 -204.397356)
		(width 0.14478)
		(layer "In11.Cu")
		(net "M_F_CPU1_SA_DQ<6>")
	)
	(segment
		(start 42.742104 -203.710286)
		(end 45.618654 -203.710286)
		(width 0.14478)
		(layer "In11.Cu")
		(net "M_F_CPU1_SA_DQ<6>")
	)
	(segment
		(start 31.393892 -204.560424)
		(end 34.35858 -204.560424)
		(width 0.14478)
		(layer "In11.Cu")
		(net "M_F_CPU1_SA_DQ<6>")
	)
	(segment
		(start 26.727658 -204.560424)
		(end 27.577796 -203.710286)
		(width 0.14478)
		(layer "In11.Cu")
		(net "M_F_CPU1_SA_DQ<6>")
	)
	(segment
		(start 46.468792 -204.560424)
		(end 49.389792 -204.560424)
		(width 0.14478)
		(layer "In11.Cu")
		(net "M_F_CPU1_SA_DQ<6>")
	)
	(segment
		(start 20.350734 -204.397356)
		(end 20.350734 -203.798932)
		(width 0.14478)
		(layer "In11.Cu")
		(net "M_F_CPU1_SA_DQ<6>")
	)
	(segment
		(start 50.23993 -203.710286)
		(end 53.155088 -203.710286)
		(width 0.14478)
		(layer "In11.Cu")
		(net "M_F_CPU1_SA_DQ<6>")
	)
	(segment
		(start 20.907248 -204.397356)
		(end 21.070316 -204.560424)
		(width 0.14478)
		(layer "In11.Cu")
		(net "M_F_CPU1_SA_DQ<6>")
	)
	(segment
		(start 45.618654 -203.710286)
		(end 46.468792 -204.560424)
		(width 0.14478)
		(layer "In11.Cu")
		(net "M_F_CPU1_SA_DQ<6>")
	)
	(segment
		(start 49.389792 -204.560424)
		(end 50.23993 -203.710286)
		(width 0.14478)
		(layer "In11.Cu")
		(net "M_F_CPU1_SA_DQ<6>")
	)
	(segment
		(start 19.074638 -204.560424)
		(end 19.237706 -204.397356)
		(width 0.14478)
		(layer "In11.Cu")
		(net "M_F_CPU1_SA_DQ<6>")
	)
	(segment
		(start 72.722486 -217.964512)
		(end 72.722486 -220.724984)
		(width 0.14478)
		(layer "In11.Cu")
		(net "M_F_CPU1_SA_DQ<6>")
	)
	(segment
		(start 20.74418 -203.635864)
		(end 20.907248 -203.798932)
		(width 0.14478)
		(layer "In11.Cu")
		(net "M_F_CPU1_SA_DQ<6>")
	)
	(segment
		(start 84.182712 -228.745796)
		(end 84.205064 -228.829108)
		(width 0.0889)
		(layer "In11.Cu")
		(net "M_F_CPU1_SA_DQ<6>")
	)
	(segment
		(start 41.891966 -204.560424)
		(end 42.742104 -203.710286)
		(width 0.14478)
		(layer "In11.Cu")
		(net "M_F_CPU1_SA_DQ<6>")
	)
	(segment
		(start 78.305406 -228.167184)
		(end 78.772258 -228.167184)
		(width 0.0889)
		(layer "In11.Cu")
		(net "M_F_CPU1_SA_DQ<6>")
	)
	(segment
		(start 77.794866 -226.977702)
		(end 77.794866 -227.656644)
		(width 0.0889)
		(layer "In11.Cu")
		(net "M_F_CPU1_SA_DQ<6>")
	)
	(arc
		(start 81.052416 -228.767132)
		(mid 81.235924 -228.721638)
		(end 81.418176 -228.771958)
		(width 0.0889)
		(layer "In11.Cu")
		(net "M_F_CPU1_SA_DQ<6>")
	)
	(arc
		(start 80.478122 -228.771958)
		(mid 80.761078 -228.848135)
		(end 81.044034 -228.771958)
		(width 0.0889)
		(layer "In11.Cu")
		(net "M_F_CPU1_SA_DQ<6>")
	)
	(arc
		(start 82.357976 -228.771958)
		(mid 82.640932 -228.848135)
		(end 82.923888 -228.771958)
		(width 0.0889)
		(layer "In11.Cu")
		(net "M_F_CPU1_SA_DQ<6>")
	)
	(arc
		(start 81.418176 -228.771958)
		(mid 81.701132 -228.848135)
		(end 81.984088 -228.771958)
		(width 0.0889)
		(layer "In11.Cu")
		(net "M_F_CPU1_SA_DQ<6>")
	)
	(arc
		(start 80.10398 -228.771958)
		(mid 80.286231 -228.721608)
		(end 80.46974 -228.767132)
		(width 0.0889)
		(layer "In11.Cu")
		(net "M_F_CPU1_SA_DQ<6>")
	)
	(arc
		(start 83.863942 -228.771958)
		(mid 84.02038 -228.722987)
		(end 84.182712 -228.745796)
		(width 0.0889)
		(layer "In11.Cu")
		(net "M_F_CPU1_SA_DQ<6>")
	)
	(arc
		(start 81.984088 -228.771958)
		(mid 82.171032 -228.721703)
		(end 82.357976 -228.771958)
		(width 0.0889)
		(layer "In11.Cu")
		(net "M_F_CPU1_SA_DQ<6>")
	)
	(arc
		(start 82.923888 -228.771958)
		(mid 83.106139 -228.721608)
		(end 83.289648 -228.767132)
		(width 0.0889)
		(layer "In11.Cu")
		(net "M_F_CPU1_SA_DQ<6>")
	)
	(arc
		(start 83.29803 -228.771958)
		(mid 83.580986 -228.848135)
		(end 83.863942 -228.771958)
		(width 0.0889)
		(layer "In11.Cu")
		(net "M_F_CPU1_SA_DQ<6>")
	)
	(arc
		(start 79.821024 -228.848158)
		(mid 79.967541 -228.828772)
		(end 80.10398 -228.771958)
		(width 0.0889)
		(layer "In11.Cu")
		(net "M_F_CPU1_SA_DQ<6>")
	)
	(segment
		(start 86.397846 -229.360476)
		(end 85.930994 -229.094538)
		(width 0.10668)
		(layer "F.Cu")
		(net "M_F_CPU1_SA_DQ<5>")
	)
	(segment
		(start 61.66485 -207.663796)
		(end 72.187308 -218.186254)
		(width 0.14478)
		(layer "In11.Cu")
		(net "M_F_CPU1_SA_DQ<5>")
	)
	(segment
		(start 59.080654 -204.79258)
		(end 59.080654 -204.723492)
		(width 0.14478)
		(layer "In11.Cu")
		(net "M_F_CPU1_SA_DQ<5>")
	)
	(segment
		(start 22.982428 -205.802484)
		(end 23.145496 -205.639416)
		(width 0.14478)
		(layer "In11.Cu")
		(net "M_F_CPU1_SA_DQ<5>")
	)
	(segment
		(start 36.095432 -204.954124)
		(end 36.2585 -204.791056)
		(width 0.14478)
		(layer "In11.Cu")
		(net "M_F_CPU1_SA_DQ<5>")
	)
	(segment
		(start 56.480456 -205.636876)
		(end 56.480456 -205.573376)
		(width 0.14478)
		(layer "In11.Cu")
		(net "M_F_CPU1_SA_DQ<5>")
	)
	(segment
		(start 61.66485 -206.413608)
		(end 61.66485 -207.663796)
		(width 0.14478)
		(layer "In11.Cu")
		(net "M_F_CPU1_SA_DQ<5>")
	)
	(segment
		(start 78.734666 -228.520244)
		(end 79.548736 -229.334314)
		(width 0.0889)
		(layer "In11.Cu")
		(net "M_F_CPU1_SA_DQ<5>")
	)
	(segment
		(start 41.277286 -205.802484)
		(end 41.440354 -205.639416)
		(width 0.14478)
		(layer "In11.Cu")
		(net "M_F_CPU1_SA_DQ<5>")
	)
	(segment
		(start 55.923942 -205.573376)
		(end 55.923942 -205.636876)
		(width 0.14478)
		(layer "In11.Cu")
		(net "M_F_CPU1_SA_DQ<5>")
	)
	(segment
		(start 76.402946 -225.509836)
		(end 77.285342 -226.392232)
		(width 0.0889)
		(layer "In11.Cu")
		(net "M_F_CPU1_SA_DQ<5>")
	)
	(segment
		(start 54.810914 -205.636876)
		(end 54.973982 -205.799944)
		(width 0.14478)
		(layer "In11.Cu")
		(net "M_F_CPU1_SA_DQ<5>")
	)
	(segment
		(start 22.75205 -205.802484)
		(end 22.982428 -205.802484)
		(width 0.14478)
		(layer "In11.Cu")
		(net "M_F_CPU1_SA_DQ<5>")
	)
	(segment
		(start 38.802564 -205.410308)
		(end 40.720772 -205.410308)
		(width 0.14478)
		(layer "In11.Cu")
		(net "M_F_CPU1_SA_DQ<5>")
	)
	(segment
		(start 34.062162 -205.410308)
		(end 34.383218 -205.410308)
		(width 0.14478)
		(layer "In11.Cu")
		(net "M_F_CPU1_SA_DQ<5>")
	)
	(segment
		(start 37.95268 -204.560424)
		(end 38.802564 -205.410308)
		(width 0.14478)
		(layer "In11.Cu")
		(net "M_F_CPU1_SA_DQ<5>")
	)
	(segment
		(start 76.192126 -224.951544)
		(end 76.402946 -225.162364)
		(width 0.0889)
		(layer "In11.Cu")
		(net "M_F_CPU1_SA_DQ<5>")
	)
	(segment
		(start 27.98572 -204.560424)
		(end 28.148788 -204.723492)
		(width 0.14478)
		(layer "In11.Cu")
		(net "M_F_CPU1_SA_DQ<5>")
	)
	(segment
		(start 77.538326 -227.689664)
		(end 78.368906 -228.520244)
		(width 0.0889)
		(layer "In11.Cu")
		(net "M_F_CPU1_SA_DQ<5>")
	)
	(segment
		(start 21.70811 -204.985366)
		(end 22.133052 -205.410308)
		(width 0.14478)
		(layer "In11.Cu")
		(net "M_F_CPU1_SA_DQ<5>")
	)
	(segment
		(start 72.187308 -220.946726)
		(end 76.192126 -224.951544)
		(width 0.14478)
		(layer "In11.Cu")
		(net "M_F_CPU1_SA_DQ<5>")
	)
	(segment
		(start 24.258524 -205.639416)
		(end 24.258524 -205.573376)
		(width 0.14478)
		(layer "In11.Cu")
		(net "M_F_CPU1_SA_DQ<5>")
	)
	(segment
		(start 51.337972 -204.723492)
		(end 51.50104 -204.560424)
		(width 0.14478)
		(layer "In11.Cu")
		(net "M_F_CPU1_SA_DQ<5>")
	)
	(segment
		(start 42.792904 -204.560424)
		(end 43.06824 -204.560424)
		(width 0.14478)
		(layer "In11.Cu")
		(net "M_F_CPU1_SA_DQ<5>")
	)
	(segment
		(start 26.2382 -205.573376)
		(end 26.401268 -205.410308)
		(width 0.14478)
		(layer "In11.Cu")
		(net "M_F_CPU1_SA_DQ<5>")
	)
	(segment
		(start 33.736026 -205.802484)
		(end 33.899094 -205.639416)
		(width 0.14478)
		(layer "In11.Cu")
		(net "M_F_CPU1_SA_DQ<5>")
	)
	(segment
		(start 57.804558 -204.560424)
		(end 58.361072 -204.560424)
		(width 0.14478)
		(layer "In11.Cu")
		(net "M_F_CPU1_SA_DQ<5>")
	)
	(segment
		(start 35.701986 -204.723492)
		(end 35.701986 -204.791056)
		(width 0.14478)
		(layer "In11.Cu")
		(net "M_F_CPU1_SA_DQ<5>")
	)
	(segment
		(start 49.102772 -205.410308)
		(end 49.448974 -205.410308)
		(width 0.14478)
		(layer "In11.Cu")
		(net "M_F_CPU1_SA_DQ<5>")
	)
	(segment
		(start 35.538918 -204.560424)
		(end 35.701986 -204.723492)
		(width 0.14478)
		(layer "In11.Cu")
		(net "M_F_CPU1_SA_DQ<5>")
	)
	(segment
		(start 41.046908 -205.802484)
		(end 41.277286 -205.802484)
		(width 0.14478)
		(layer "In11.Cu")
		(net "M_F_CPU1_SA_DQ<5>")
	)
	(segment
		(start 55.367428 -205.573376)
		(end 55.530496 -205.410308)
		(width 0.14478)
		(layer "In11.Cu")
		(net "M_F_CPU1_SA_DQ<5>")
	)
	(segment
		(start 81.044034 -229.416864)
		(end 81.052416 -229.42169)
		(width 0.0889)
		(layer "In11.Cu")
		(net "M_F_CPU1_SA_DQ<5>")
	)
	(segment
		(start 80.46974 -229.42169)
		(end 80.478122 -229.416864)
		(width 0.0889)
		(layer "In11.Cu")
		(net "M_F_CPU1_SA_DQ<5>")
	)
	(segment
		(start 55.530496 -205.410308)
		(end 55.760874 -205.410308)
		(width 0.14478)
		(layer "In11.Cu")
		(net "M_F_CPU1_SA_DQ<5>")
	)
	(segment
		(start 23.145496 -205.639416)
		(end 23.145496 -205.1812)
		(width 0.14478)
		(layer "In11.Cu")
		(net "M_F_CPU1_SA_DQ<5>")
	)
	(segment
		(start 55.367428 -205.636876)
		(end 55.367428 -205.573376)
		(width 0.14478)
		(layer "In11.Cu")
		(net "M_F_CPU1_SA_DQ<5>")
	)
	(segment
		(start 27.664664 -204.560424)
		(end 27.98572 -204.560424)
		(width 0.14478)
		(layer "In11.Cu")
		(net "M_F_CPU1_SA_DQ<5>")
	)
	(segment
		(start 22.425914 -205.410308)
		(end 22.588982 -205.573376)
		(width 0.14478)
		(layer "In11.Cu")
		(net "M_F_CPU1_SA_DQ<5>")
	)
	(segment
		(start 59.811666 -204.560424)
		(end 61.66485 -206.413608)
		(width 0.14478)
		(layer "In11.Cu")
		(net "M_F_CPU1_SA_DQ<5>")
	)
	(segment
		(start 30.470856 -204.560424)
		(end 31.32074 -205.410308)
		(width 0.14478)
		(layer "In11.Cu")
		(net "M_F_CPU1_SA_DQ<5>")
	)
	(segment
		(start 84.229702 -229.42169)
		(end 84.238084 -229.416864)
		(width 0.0889)
		(layer "In11.Cu")
		(net "M_F_CPU1_SA_DQ<5>")
	)
	(segment
		(start 51.337972 -204.788516)
		(end 51.337972 -204.723492)
		(width 0.14478)
		(layer "In11.Cu")
		(net "M_F_CPU1_SA_DQ<5>")
	)
	(segment
		(start 36.421568 -204.560424)
		(end 37.95268 -204.560424)
		(width 0.14478)
		(layer "In11.Cu")
		(net "M_F_CPU1_SA_DQ<5>")
	)
	(segment
		(start 79.69123 -229.340664)
		(end 79.821278 -229.340664)
		(width 0.0889)
		(layer "In11.Cu")
		(net "M_F_CPU1_SA_DQ<5>")
	)
	(segment
		(start 76.402946 -225.162364)
		(end 76.402946 -225.509836)
		(width 0.0889)
		(layer "In11.Cu")
		(net "M_F_CPU1_SA_DQ<5>")
	)
	(segment
		(start 28.86837 -204.560424)
		(end 30.470856 -204.560424)
		(width 0.14478)
		(layer "In11.Cu")
		(net "M_F_CPU1_SA_DQ<5>")
	)
	(segment
		(start 78.368906 -228.520244)
		(end 78.734666 -228.520244)
		(width 0.0889)
		(layer "In11.Cu")
		(net "M_F_CPU1_SA_DQ<5>")
	)
	(segment
		(start 56.317388 -205.799944)
		(end 56.480456 -205.636876)
		(width 0.14478)
		(layer "In11.Cu")
		(net "M_F_CPU1_SA_DQ<5>")
	)
	(segment
		(start 54.647846 -205.410308)
		(end 54.810914 -205.573376)
		(width 0.14478)
		(layer "In11.Cu")
		(net "M_F_CPU1_SA_DQ<5>")
	)
	(segment
		(start 26.2382 -205.639416)
		(end 26.2382 -205.573376)
		(width 0.14478)
		(layer "In11.Cu")
		(net "M_F_CPU1_SA_DQ<5>")
	)
	(segment
		(start 43.06824 -204.560424)
		(end 43.231308 -204.723492)
		(width 0.14478)
		(layer "In11.Cu")
		(net "M_F_CPU1_SA_DQ<5>")
	)
	(segment
		(start 53.961792 -205.410308)
		(end 54.647846 -205.410308)
		(width 0.14478)
		(layer "In11.Cu")
		(net "M_F_CPU1_SA_DQ<5>")
	)
	(segment
		(start 77.285342 -226.392232)
		(end 77.538326 -227.00361)
		(width 0.0889)
		(layer "In11.Cu")
		(net "M_F_CPU1_SA_DQ<5>")
	)
	(segment
		(start 55.20436 -205.799944)
		(end 55.367428 -205.636876)
		(width 0.14478)
		(layer "In11.Cu")
		(net "M_F_CPU1_SA_DQ<5>")
	)
	(segment
		(start 50.781458 -204.788516)
		(end 50.944526 -204.951584)
		(width 0.14478)
		(layer "In11.Cu")
		(net "M_F_CPU1_SA_DQ<5>")
	)
	(segment
		(start 54.810914 -205.573376)
		(end 54.810914 -205.636876)
		(width 0.14478)
		(layer "In11.Cu")
		(net "M_F_CPU1_SA_DQ<5>")
	)
	(segment
		(start 26.401268 -205.410308)
		(end 26.81478 -205.410308)
		(width 0.14478)
		(layer "In11.Cu")
		(net "M_F_CPU1_SA_DQ<5>")
	)
	(segment
		(start 59.243722 -204.560424)
		(end 59.811666 -204.560424)
		(width 0.14478)
		(layer "In11.Cu")
		(net "M_F_CPU1_SA_DQ<5>")
	)
	(segment
		(start 50.298858 -204.560424)
		(end 50.61839 -204.560424)
		(width 0.14478)
		(layer "In11.Cu")
		(net "M_F_CPU1_SA_DQ<5>")
	)
	(segment
		(start 40.88384 -205.639416)
		(end 41.046908 -205.802484)
		(width 0.14478)
		(layer "In11.Cu")
		(net "M_F_CPU1_SA_DQ<5>")
	)
	(segment
		(start 22.588982 -205.639416)
		(end 22.75205 -205.802484)
		(width 0.14478)
		(layer "In11.Cu")
		(net "M_F_CPU1_SA_DQ<5>")
	)
	(segment
		(start 84.803996 -229.416864)
		(end 84.812378 -229.42169)
		(width 0.0889)
		(layer "In11.Cu")
		(net "M_F_CPU1_SA_DQ<5>")
	)
	(segment
		(start 48.38319 -205.573376)
		(end 48.38319 -205.639416)
		(width 0.14478)
		(layer "In11.Cu")
		(net "M_F_CPU1_SA_DQ<5>")
	)
	(segment
		(start 31.32074 -205.410308)
		(end 33.179512 -205.410308)
		(width 0.14478)
		(layer "In11.Cu")
		(net "M_F_CPU1_SA_DQ<5>")
	)
	(segment
		(start 56.643524 -205.410308)
		(end 56.954674 -205.410308)
		(width 0.14478)
		(layer "In11.Cu")
		(net "M_F_CPU1_SA_DQ<5>")
	)
	(segment
		(start 23.308564 -205.018132)
		(end 23.538942 -205.018132)
		(width 0.14478)
		(layer "In11.Cu")
		(net "M_F_CPU1_SA_DQ<5>")
	)
	(segment
		(start 48.939704 -205.639416)
		(end 48.939704 -205.573376)
		(width 0.14478)
		(layer "In11.Cu")
		(net "M_F_CPU1_SA_DQ<5>")
	)
	(segment
		(start 26.075132 -205.802484)
		(end 26.2382 -205.639416)
		(width 0.14478)
		(layer "In11.Cu")
		(net "M_F_CPU1_SA_DQ<5>")
	)
	(segment
		(start 56.480456 -205.573376)
		(end 56.643524 -205.410308)
		(width 0.14478)
		(layer "In11.Cu")
		(net "M_F_CPU1_SA_DQ<5>")
	)
	(segment
		(start 25.681686 -205.639416)
		(end 25.844754 -205.802484)
		(width 0.14478)
		(layer "In11.Cu")
		(net "M_F_CPU1_SA_DQ<5>")
	)
	(segment
		(start 43.231308 -204.791056)
		(end 43.394376 -204.954124)
		(width 0.14478)
		(layer "In11.Cu")
		(net "M_F_CPU1_SA_DQ<5>")
	)
	(segment
		(start 43.394376 -204.954124)
		(end 43.624754 -204.954124)
		(width 0.14478)
		(layer "In11.Cu")
		(net "M_F_CPU1_SA_DQ<5>")
	)
	(segment
		(start 33.505648 -205.802484)
		(end 33.736026 -205.802484)
		(width 0.14478)
		(layer "In11.Cu")
		(net "M_F_CPU1_SA_DQ<5>")
	)
	(segment
		(start 85.681312 -229.385368)
		(end 85.77707 -229.359968)
		(width 0.0889)
		(layer "In11.Cu")
		(net "M_F_CPU1_SA_DQ<5>")
	)
	(segment
		(start 22.588982 -205.573376)
		(end 22.588982 -205.639416)
		(width 0.14478)
		(layer "In11.Cu")
		(net "M_F_CPU1_SA_DQ<5>")
	)
	(segment
		(start 43.787822 -204.723492)
		(end 43.95089 -204.560424)
		(width 0.14478)
		(layer "In11.Cu")
		(net "M_F_CPU1_SA_DQ<5>")
	)
	(segment
		(start 28.705302 -204.785976)
		(end 28.705302 -204.723492)
		(width 0.14478)
		(layer "In11.Cu")
		(net "M_F_CPU1_SA_DQ<5>")
	)
	(segment
		(start 24.095456 -205.802484)
		(end 24.258524 -205.639416)
		(width 0.14478)
		(layer "In11.Cu")
		(net "M_F_CPU1_SA_DQ<5>")
	)
	(segment
		(start 51.174904 -204.951584)
		(end 51.337972 -204.788516)
		(width 0.14478)
		(layer "In11.Cu")
		(net "M_F_CPU1_SA_DQ<5>")
	)
	(segment
		(start 24.258524 -205.573376)
		(end 24.421592 -205.410308)
		(width 0.14478)
		(layer "In11.Cu")
		(net "M_F_CPU1_SA_DQ<5>")
	)
	(segment
		(start 55.923942 -205.636876)
		(end 56.08701 -205.799944)
		(width 0.14478)
		(layer "In11.Cu")
		(net "M_F_CPU1_SA_DQ<5>")
	)
	(segment
		(start 33.899094 -205.573376)
		(end 34.062162 -205.410308)
		(width 0.14478)
		(layer "In11.Cu")
		(net "M_F_CPU1_SA_DQ<5>")
	)
	(segment
		(start 23.538942 -205.018132)
		(end 23.70201 -205.1812)
		(width 0.14478)
		(layer "In11.Cu")
		(net "M_F_CPU1_SA_DQ<5>")
	)
	(segment
		(start 58.52414 -204.723492)
		(end 58.52414 -204.79258)
		(width 0.14478)
		(layer "In11.Cu")
		(net "M_F_CPU1_SA_DQ<5>")
	)
	(segment
		(start 33.179512 -205.410308)
		(end 33.34258 -205.573376)
		(width 0.14478)
		(layer "In11.Cu")
		(net "M_F_CPU1_SA_DQ<5>")
	)
	(segment
		(start 41.94302 -205.410308)
		(end 42.792904 -204.560424)
		(width 0.14478)
		(layer "In11.Cu")
		(net "M_F_CPU1_SA_DQ<5>")
	)
	(segment
		(start 48.220122 -205.410308)
		(end 48.38319 -205.573376)
		(width 0.14478)
		(layer "In11.Cu")
		(net "M_F_CPU1_SA_DQ<5>")
	)
	(segment
		(start 33.899094 -205.639416)
		(end 33.899094 -205.573376)
		(width 0.14478)
		(layer "In11.Cu")
		(net "M_F_CPU1_SA_DQ<5>")
	)
	(segment
		(start 72.187308 -218.186254)
		(end 72.187308 -220.946726)
		(width 0.14478)
		(layer "In11.Cu")
		(net "M_F_CPU1_SA_DQ<5>")
	)
	(segment
		(start 48.546258 -205.802484)
		(end 48.776636 -205.802484)
		(width 0.14478)
		(layer "In11.Cu")
		(net "M_F_CPU1_SA_DQ<5>")
	)
	(segment
		(start 23.70201 -205.639416)
		(end 23.865078 -205.802484)
		(width 0.14478)
		(layer "In11.Cu")
		(net "M_F_CPU1_SA_DQ<5>")
	)
	(segment
		(start 51.50104 -204.560424)
		(end 53.111908 -204.560424)
		(width 0.14478)
		(layer "In11.Cu")
		(net "M_F_CPU1_SA_DQ<5>")
	)
	(segment
		(start 46.417738 -205.410308)
		(end 48.220122 -205.410308)
		(width 0.14478)
		(layer "In11.Cu")
		(net "M_F_CPU1_SA_DQ<5>")
	)
	(segment
		(start 34.383218 -205.410308)
		(end 35.233102 -204.560424)
		(width 0.14478)
		(layer "In11.Cu")
		(net "M_F_CPU1_SA_DQ<5>")
	)
	(segment
		(start 28.705302 -204.723492)
		(end 28.86837 -204.560424)
		(width 0.14478)
		(layer "In11.Cu")
		(net "M_F_CPU1_SA_DQ<5>")
	)
	(segment
		(start 41.440354 -205.573376)
		(end 41.603422 -205.410308)
		(width 0.14478)
		(layer "In11.Cu")
		(net "M_F_CPU1_SA_DQ<5>")
	)
	(segment
		(start 33.34258 -205.639416)
		(end 33.505648 -205.802484)
		(width 0.14478)
		(layer "In11.Cu")
		(net "M_F_CPU1_SA_DQ<5>")
	)
	(segment
		(start 56.954674 -205.410308)
		(end 57.804558 -204.560424)
		(width 0.14478)
		(layer "In11.Cu")
		(net "M_F_CPU1_SA_DQ<5>")
	)
	(segment
		(start 23.865078 -205.802484)
		(end 24.095456 -205.802484)
		(width 0.14478)
		(layer "In11.Cu")
		(net "M_F_CPU1_SA_DQ<5>")
	)
	(segment
		(start 43.624754 -204.954124)
		(end 43.787822 -204.791056)
		(width 0.14478)
		(layer "In11.Cu")
		(net "M_F_CPU1_SA_DQ<5>")
	)
	(segment
		(start 28.311856 -204.949044)
		(end 28.542234 -204.949044)
		(width 0.14478)
		(layer "In11.Cu")
		(net "M_F_CPU1_SA_DQ<5>")
	)
	(segment
		(start 48.939704 -205.573376)
		(end 49.102772 -205.410308)
		(width 0.14478)
		(layer "In11.Cu")
		(net "M_F_CPU1_SA_DQ<5>")
	)
	(segment
		(start 40.720772 -205.410308)
		(end 40.88384 -205.573376)
		(width 0.14478)
		(layer "In11.Cu")
		(net "M_F_CPU1_SA_DQ<5>")
	)
	(segment
		(start 40.88384 -205.573376)
		(end 40.88384 -205.639416)
		(width 0.14478)
		(layer "In11.Cu")
		(net "M_F_CPU1_SA_DQ<5>")
	)
	(segment
		(start 56.08701 -205.799944)
		(end 56.317388 -205.799944)
		(width 0.14478)
		(layer "In11.Cu")
		(net "M_F_CPU1_SA_DQ<5>")
	)
	(segment
		(start 43.231308 -204.723492)
		(end 43.231308 -204.791056)
		(width 0.14478)
		(layer "In11.Cu")
		(net "M_F_CPU1_SA_DQ<5>")
	)
	(segment
		(start 36.2585 -204.723492)
		(end 36.421568 -204.560424)
		(width 0.14478)
		(layer "In11.Cu")
		(net "M_F_CPU1_SA_DQ<5>")
	)
	(segment
		(start 48.776636 -205.802484)
		(end 48.939704 -205.639416)
		(width 0.14478)
		(layer "In11.Cu")
		(net "M_F_CPU1_SA_DQ<5>")
	)
	(segment
		(start 25.844754 -205.802484)
		(end 26.075132 -205.802484)
		(width 0.14478)
		(layer "In11.Cu")
		(net "M_F_CPU1_SA_DQ<5>")
	)
	(segment
		(start 41.440354 -205.639416)
		(end 41.440354 -205.573376)
		(width 0.14478)
		(layer "In11.Cu")
		(net "M_F_CPU1_SA_DQ<5>")
	)
	(segment
		(start 24.421592 -205.410308)
		(end 25.518618 -205.410308)
		(width 0.14478)
		(layer "In11.Cu")
		(net "M_F_CPU1_SA_DQ<5>")
	)
	(segment
		(start 49.448974 -205.410308)
		(end 50.298858 -204.560424)
		(width 0.14478)
		(layer "In11.Cu")
		(net "M_F_CPU1_SA_DQ<5>")
	)
	(segment
		(start 79.548736 -229.334314)
		(end 79.69123 -229.340664)
		(width 0.0889)
		(layer "In11.Cu")
		(net "M_F_CPU1_SA_DQ<5>")
	)
	(segment
		(start 23.70201 -205.1812)
		(end 23.70201 -205.639416)
		(width 0.14478)
		(layer "In11.Cu")
		(net "M_F_CPU1_SA_DQ<5>")
	)
	(segment
		(start 55.760874 -205.410308)
		(end 55.923942 -205.573376)
		(width 0.14478)
		(layer "In11.Cu")
		(net "M_F_CPU1_SA_DQ<5>")
	)
	(segment
		(start 28.148788 -204.723492)
		(end 28.148788 -204.785976)
		(width 0.14478)
		(layer "In11.Cu")
		(net "M_F_CPU1_SA_DQ<5>")
	)
	(segment
		(start 54.973982 -205.799944)
		(end 55.20436 -205.799944)
		(width 0.14478)
		(layer "In11.Cu")
		(net "M_F_CPU1_SA_DQ<5>")
	)
	(segment
		(start 25.518618 -205.410308)
		(end 25.681686 -205.573376)
		(width 0.14478)
		(layer "In11.Cu")
		(net "M_F_CPU1_SA_DQ<5>")
	)
	(segment
		(start 50.944526 -204.951584)
		(end 51.174904 -204.951584)
		(width 0.14478)
		(layer "In11.Cu")
		(net "M_F_CPU1_SA_DQ<5>")
	)
	(segment
		(start 35.701986 -204.791056)
		(end 35.865054 -204.954124)
		(width 0.14478)
		(layer "In11.Cu")
		(net "M_F_CPU1_SA_DQ<5>")
	)
	(segment
		(start 26.81478 -205.410308)
		(end 27.664664 -204.560424)
		(width 0.14478)
		(layer "In11.Cu")
		(net "M_F_CPU1_SA_DQ<5>")
	)
	(segment
		(start 45.567854 -204.560424)
		(end 46.417738 -205.410308)
		(width 0.14478)
		(layer "In11.Cu")
		(net "M_F_CPU1_SA_DQ<5>")
	)
	(segment
		(start 25.681686 -205.573376)
		(end 25.681686 -205.639416)
		(width 0.14478)
		(layer "In11.Cu")
		(net "M_F_CPU1_SA_DQ<5>")
	)
	(segment
		(start 59.080654 -204.723492)
		(end 59.243722 -204.560424)
		(width 0.14478)
		(layer "In11.Cu")
		(net "M_F_CPU1_SA_DQ<5>")
	)
	(segment
		(start 33.34258 -205.573376)
		(end 33.34258 -205.639416)
		(width 0.14478)
		(layer "In11.Cu")
		(net "M_F_CPU1_SA_DQ<5>")
	)
	(segment
		(start 41.603422 -205.410308)
		(end 41.94302 -205.410308)
		(width 0.14478)
		(layer "In11.Cu")
		(net "M_F_CPU1_SA_DQ<5>")
	)
	(segment
		(start 50.61839 -204.560424)
		(end 50.781458 -204.723492)
		(width 0.14478)
		(layer "In11.Cu")
		(net "M_F_CPU1_SA_DQ<5>")
	)
	(segment
		(start 28.148788 -204.785976)
		(end 28.311856 -204.949044)
		(width 0.14478)
		(layer "In11.Cu")
		(net "M_F_CPU1_SA_DQ<5>")
	)
	(segment
		(start 58.361072 -204.560424)
		(end 58.52414 -204.723492)
		(width 0.14478)
		(layer "In11.Cu")
		(net "M_F_CPU1_SA_DQ<5>")
	)
	(segment
		(start 43.95089 -204.560424)
		(end 45.567854 -204.560424)
		(width 0.14478)
		(layer "In11.Cu")
		(net "M_F_CPU1_SA_DQ<5>")
	)
	(segment
		(start 50.781458 -204.723492)
		(end 50.781458 -204.788516)
		(width 0.14478)
		(layer "In11.Cu")
		(net "M_F_CPU1_SA_DQ<5>")
	)
	(segment
		(start 35.233102 -204.560424)
		(end 35.538918 -204.560424)
		(width 0.14478)
		(layer "In11.Cu")
		(net "M_F_CPU1_SA_DQ<5>")
	)
	(segment
		(start 43.787822 -204.791056)
		(end 43.787822 -204.723492)
		(width 0.14478)
		(layer "In11.Cu")
		(net "M_F_CPU1_SA_DQ<5>")
	)
	(segment
		(start 48.38319 -205.639416)
		(end 48.546258 -205.802484)
		(width 0.14478)
		(layer "In11.Cu")
		(net "M_F_CPU1_SA_DQ<5>")
	)
	(segment
		(start 58.52414 -204.79258)
		(end 58.687208 -204.955648)
		(width 0.14478)
		(layer "In11.Cu")
		(net "M_F_CPU1_SA_DQ<5>")
	)
	(segment
		(start 58.917586 -204.955648)
		(end 59.080654 -204.79258)
		(width 0.14478)
		(layer "In11.Cu")
		(net "M_F_CPU1_SA_DQ<5>")
	)
	(segment
		(start 22.133052 -205.410308)
		(end 22.425914 -205.410308)
		(width 0.14478)
		(layer "In11.Cu")
		(net "M_F_CPU1_SA_DQ<5>")
	)
	(segment
		(start 58.687208 -204.955648)
		(end 58.917586 -204.955648)
		(width 0.14478)
		(layer "In11.Cu")
		(net "M_F_CPU1_SA_DQ<5>")
	)
	(segment
		(start 23.145496 -205.1812)
		(end 23.308564 -205.018132)
		(width 0.14478)
		(layer "In11.Cu")
		(net "M_F_CPU1_SA_DQ<5>")
	)
	(segment
		(start 53.111908 -204.560424)
		(end 53.961792 -205.410308)
		(width 0.14478)
		(layer "In11.Cu")
		(net "M_F_CPU1_SA_DQ<5>")
	)
	(segment
		(start 85.77707 -229.359968)
		(end 85.930994 -229.094538)
		(width 0.0889)
		(layer "In11.Cu")
		(net "M_F_CPU1_SA_DQ<5>")
	)
	(segment
		(start 83.289648 -229.42169)
		(end 83.29803 -229.416864)
		(width 0.0889)
		(layer "In11.Cu")
		(net "M_F_CPU1_SA_DQ<5>")
	)
	(segment
		(start 36.2585 -204.791056)
		(end 36.2585 -204.723492)
		(width 0.14478)
		(layer "In11.Cu")
		(net "M_F_CPU1_SA_DQ<5>")
	)
	(segment
		(start 28.542234 -204.949044)
		(end 28.705302 -204.785976)
		(width 0.14478)
		(layer "In11.Cu")
		(net "M_F_CPU1_SA_DQ<5>")
	)
	(segment
		(start 77.538326 -227.00361)
		(end 77.538326 -227.689664)
		(width 0.0889)
		(layer "In11.Cu")
		(net "M_F_CPU1_SA_DQ<5>")
	)
	(segment
		(start 35.865054 -204.954124)
		(end 36.095432 -204.954124)
		(width 0.14478)
		(layer "In11.Cu")
		(net "M_F_CPU1_SA_DQ<5>")
	)
	(arc
		(start 80.10398 -229.416864)
		(mid 80.286231 -229.467248)
		(end 80.46974 -229.42169)
		(width 0.0889)
		(layer "In11.Cu")
		(net "M_F_CPU1_SA_DQ<5>")
	)
	(arc
		(start 81.418176 -229.416864)
		(mid 81.701132 -229.340687)
		(end 81.984088 -229.416864)
		(width 0.0889)
		(layer "In11.Cu")
		(net "M_F_CPU1_SA_DQ<5>")
	)
	(arc
		(start 81.052416 -229.42169)
		(mid 81.235924 -229.467215)
		(end 81.418176 -229.416864)
		(width 0.0889)
		(layer "In11.Cu")
		(net "M_F_CPU1_SA_DQ<5>")
	)
	(arc
		(start 83.863942 -229.416864)
		(mid 84.046193 -229.467248)
		(end 84.229702 -229.42169)
		(width 0.0889)
		(layer "In11.Cu")
		(net "M_F_CPU1_SA_DQ<5>")
	)
	(arc
		(start 81.984088 -229.416864)
		(mid 82.171032 -229.467153)
		(end 82.357976 -229.416864)
		(width 0.0889)
		(layer "In11.Cu")
		(net "M_F_CPU1_SA_DQ<5>")
	)
	(arc
		(start 82.357976 -229.416864)
		(mid 82.640932 -229.340687)
		(end 82.923888 -229.416864)
		(width 0.0889)
		(layer "In11.Cu")
		(net "M_F_CPU1_SA_DQ<5>")
	)
	(arc
		(start 85.178138 -229.416864)
		(mid 85.425998 -229.341781)
		(end 85.681312 -229.385368)
		(width 0.0889)
		(layer "In11.Cu")
		(net "M_F_CPU1_SA_DQ<5>")
	)
	(arc
		(start 79.821278 -229.340664)
		(mid 79.967668 -229.360075)
		(end 80.10398 -229.416864)
		(width 0.0889)
		(layer "In11.Cu")
		(net "M_F_CPU1_SA_DQ<5>")
	)
	(arc
		(start 83.29803 -229.416864)
		(mid 83.580986 -229.340687)
		(end 83.863942 -229.416864)
		(width 0.0889)
		(layer "In11.Cu")
		(net "M_F_CPU1_SA_DQ<5>")
	)
	(arc
		(start 80.478122 -229.416864)
		(mid 80.761078 -229.340687)
		(end 81.044034 -229.416864)
		(width 0.0889)
		(layer "In11.Cu")
		(net "M_F_CPU1_SA_DQ<5>")
	)
	(arc
		(start 82.923888 -229.416864)
		(mid 83.106139 -229.467248)
		(end 83.289648 -229.42169)
		(width 0.0889)
		(layer "In11.Cu")
		(net "M_F_CPU1_SA_DQ<5>")
	)
	(arc
		(start 84.812378 -229.42169)
		(mid 84.995886 -229.467215)
		(end 85.178138 -229.416864)
		(width 0.0889)
		(layer "In11.Cu")
		(net "M_F_CPU1_SA_DQ<5>")
	)
	(arc
		(start 84.238084 -229.416864)
		(mid 84.52104 -229.340687)
		(end 84.803996 -229.416864)
		(width 0.0889)
		(layer "In11.Cu")
		(net "M_F_CPU1_SA_DQ<5>")
	)
	(segment
		(start 84.987892 -228.55047)
		(end 84.52104 -228.284532)
		(width 0.10668)
		(layer "F.Cu")
		(net "M_F_CPU1_SA_DQ<4>")
	)
	(segment
		(start 23.82012 -203.873354)
		(end 23.82012 -203.937616)
		(width 0.14478)
		(layer "In11.Cu")
		(net "M_F_CPU1_SA_DQ<4>")
	)
	(segment
		(start 58.96483 -203.084176)
		(end 58.96483 -203.02347)
		(width 0.14478)
		(layer "In11.Cu")
		(net "M_F_CPU1_SA_DQ<4>")
	)
	(segment
		(start 43.624754 -203.242164)
		(end 43.787822 -203.079096)
		(width 0.14478)
		(layer "In11.Cu")
		(net "M_F_CPU1_SA_DQ<4>")
	)
	(segment
		(start 50.298858 -202.860402)
		(end 50.621438 -202.860402)
		(width 0.14478)
		(layer "In11.Cu")
		(net "M_F_CPU1_SA_DQ<4>")
	)
	(segment
		(start 54.998112 -204.105764)
		(end 55.16118 -203.942696)
		(width 0.14478)
		(layer "In11.Cu")
		(net "M_F_CPU1_SA_DQ<4>")
	)
	(segment
		(start 82.453988 -228.607112)
		(end 82.46237 -228.611938)
		(width 0.0889)
		(layer "In11.Cu")
		(net "M_F_CPU1_SA_DQ<4>")
	)
	(segment
		(start 49.198276 -203.710286)
		(end 49.448974 -203.710286)
		(width 0.14478)
		(layer "In11.Cu")
		(net "M_F_CPU1_SA_DQ<4>")
	)
	(segment
		(start 84.367116 -228.549962)
		(end 84.52104 -228.284532)
		(width 0.0889)
		(layer "In11.Cu")
		(net "M_F_CPU1_SA_DQ<4>")
	)
	(segment
		(start 56.437276 -203.710286)
		(end 56.954674 -203.710286)
		(width 0.14478)
		(layer "In11.Cu")
		(net "M_F_CPU1_SA_DQ<4>")
	)
	(segment
		(start 56.274208 -203.942696)
		(end 56.274208 -203.873354)
		(width 0.14478)
		(layer "In11.Cu")
		(net "M_F_CPU1_SA_DQ<4>")
	)
	(segment
		(start 48.478694 -203.937616)
		(end 48.641762 -204.100684)
		(width 0.14478)
		(layer "In11.Cu")
		(net "M_F_CPU1_SA_DQ<4>")
	)
	(segment
		(start 28.276042 -203.247244)
		(end 28.50642 -203.247244)
		(width 0.14478)
		(layer "In11.Cu")
		(net "M_F_CPU1_SA_DQ<4>")
	)
	(segment
		(start 43.231308 -203.079096)
		(end 43.394376 -203.242164)
		(width 0.14478)
		(layer "In11.Cu")
		(net "M_F_CPU1_SA_DQ<4>")
	)
	(segment
		(start 26.405332 -203.873354)
		(end 26.5684 -203.710286)
		(width 0.14478)
		(layer "In11.Cu")
		(net "M_F_CPU1_SA_DQ<4>")
	)
	(segment
		(start 59.590178 -203.092304)
		(end 60.11291 -203.092304)
		(width 0.14478)
		(layer "In11.Cu")
		(net "M_F_CPU1_SA_DQ<4>")
	)
	(segment
		(start 24.213566 -204.100684)
		(end 24.376634 -203.937616)
		(width 0.14478)
		(layer "In11.Cu")
		(net "M_F_CPU1_SA_DQ<4>")
	)
	(segment
		(start 33.425892 -203.937616)
		(end 33.58896 -204.100684)
		(width 0.14478)
		(layer "In11.Cu")
		(net "M_F_CPU1_SA_DQ<4>")
	)
	(segment
		(start 43.787822 -203.079096)
		(end 43.787822 -203.02347)
		(width 0.14478)
		(layer "In11.Cu")
		(net "M_F_CPU1_SA_DQ<4>")
	)
	(segment
		(start 51.177952 -203.242164)
		(end 51.34102 -203.079096)
		(width 0.14478)
		(layer "In11.Cu")
		(net "M_F_CPU1_SA_DQ<4>")
	)
	(segment
		(start 73.299066 -220.467936)
		(end 76.92644 -224.09531)
		(width 0.14478)
		(layer "In11.Cu")
		(net "M_F_CPU1_SA_DQ<4>")
	)
	(segment
		(start 43.787822 -203.02347)
		(end 43.941238 -202.870054)
		(width 0.14478)
		(layer "In11.Cu")
		(net "M_F_CPU1_SA_DQ<4>")
	)
	(segment
		(start 79.55026 -228.657658)
		(end 79.821024 -228.657658)
		(width 0.0889)
		(layer "In11.Cu")
		(net "M_F_CPU1_SA_DQ<4>")
	)
	(segment
		(start 59.358276 -202.860402)
		(end 59.590178 -203.092304)
		(width 0.14478)
		(layer "In11.Cu")
		(net "M_F_CPU1_SA_DQ<4>")
	)
	(segment
		(start 43.394376 -203.242164)
		(end 43.624754 -203.242164)
		(width 0.14478)
		(layer "In11.Cu")
		(net "M_F_CPU1_SA_DQ<4>")
	)
	(segment
		(start 41.106598 -204.105764)
		(end 41.336976 -204.105764)
		(width 0.14478)
		(layer "In11.Cu")
		(net "M_F_CPU1_SA_DQ<4>")
	)
	(segment
		(start 22.722078 -202.998324)
		(end 22.952456 -202.998324)
		(width 0.14478)
		(layer "In11.Cu")
		(net "M_F_CPU1_SA_DQ<4>")
	)
	(segment
		(start 53.961792 -203.710286)
		(end 54.441598 -203.710286)
		(width 0.14478)
		(layer "In11.Cu")
		(net "M_F_CPU1_SA_DQ<4>")
	)
	(segment
		(start 50.621438 -202.860402)
		(end 50.784506 -203.02347)
		(width 0.14478)
		(layer "In11.Cu")
		(net "M_F_CPU1_SA_DQ<4>")
	)
	(segment
		(start 56.954674 -203.710286)
		(end 57.804558 -202.860402)
		(width 0.14478)
		(layer "In11.Cu")
		(net "M_F_CPU1_SA_DQ<4>")
	)
	(segment
		(start 43.941238 -202.870054)
		(end 45.577506 -202.870054)
		(width 0.14478)
		(layer "In11.Cu")
		(net "M_F_CPU1_SA_DQ<4>")
	)
	(segment
		(start 77.613002 -224.969832)
		(end 77.613002 -225.676968)
		(width 0.0889)
		(layer "In11.Cu")
		(net "M_F_CPU1_SA_DQ<4>")
	)
	(segment
		(start 22.55901 -203.547218)
		(end 22.55901 -203.161392)
		(width 0.14478)
		(layer "In11.Cu")
		(net "M_F_CPU1_SA_DQ<4>")
	)
	(segment
		(start 22.395942 -203.710286)
		(end 22.55901 -203.547218)
		(width 0.14478)
		(layer "In11.Cu")
		(net "M_F_CPU1_SA_DQ<4>")
	)
	(segment
		(start 33.425892 -203.873354)
		(end 33.425892 -203.937616)
		(width 0.14478)
		(layer "In11.Cu")
		(net "M_F_CPU1_SA_DQ<4>")
	)
	(segment
		(start 77.613002 -225.676968)
		(end 77.540866 -225.749104)
		(width 0.0889)
		(layer "In11.Cu")
		(net "M_F_CPU1_SA_DQ<4>")
	)
	(segment
		(start 73.299066 -217.725244)
		(end 73.299066 -220.467936)
		(width 0.14478)
		(layer "In11.Cu")
		(net "M_F_CPU1_SA_DQ<4>")
	)
	(segment
		(start 78.856586 -227.963984)
		(end 79.55026 -228.657658)
		(width 0.0889)
		(layer "In11.Cu")
		(net "M_F_CPU1_SA_DQ<4>")
	)
	(segment
		(start 24.376634 -203.937616)
		(end 24.376634 -203.873354)
		(width 0.14478)
		(layer "In11.Cu")
		(net "M_F_CPU1_SA_DQ<4>")
	)
	(segment
		(start 55.16118 -203.942696)
		(end 55.16118 -203.662534)
		(width 0.14478)
		(layer "In11.Cu")
		(net "M_F_CPU1_SA_DQ<4>")
	)
	(segment
		(start 50.784506 -203.02347)
		(end 50.784506 -203.079096)
		(width 0.14478)
		(layer "In11.Cu")
		(net "M_F_CPU1_SA_DQ<4>")
	)
	(segment
		(start 55.717694 -203.662534)
		(end 55.717694 -203.942696)
		(width 0.14478)
		(layer "In11.Cu")
		(net "M_F_CPU1_SA_DQ<4>")
	)
	(segment
		(start 26.81478 -203.710286)
		(end 27.664664 -202.860402)
		(width 0.14478)
		(layer "In11.Cu")
		(net "M_F_CPU1_SA_DQ<4>")
	)
	(segment
		(start 48.325278 -203.719938)
		(end 48.478694 -203.873354)
		(width 0.14478)
		(layer "In11.Cu")
		(net "M_F_CPU1_SA_DQ<4>")
	)
	(segment
		(start 25.848818 -203.932536)
		(end 26.011886 -204.095604)
		(width 0.14478)
		(layer "In11.Cu")
		(net "M_F_CPU1_SA_DQ<4>")
	)
	(segment
		(start 77.540866 -226.035108)
		(end 77.721968 -226.21621)
		(width 0.0889)
		(layer "In11.Cu")
		(net "M_F_CPU1_SA_DQ<4>")
	)
	(segment
		(start 40.790114 -203.719938)
		(end 40.94353 -203.873354)
		(width 0.14478)
		(layer "In11.Cu")
		(net "M_F_CPU1_SA_DQ<4>")
	)
	(segment
		(start 28.669488 -203.02347)
		(end 28.822904 -202.870054)
		(width 0.14478)
		(layer "In11.Cu")
		(net "M_F_CPU1_SA_DQ<4>")
	)
	(segment
		(start 48.478694 -203.873354)
		(end 48.478694 -203.937616)
		(width 0.14478)
		(layer "In11.Cu")
		(net "M_F_CPU1_SA_DQ<4>")
	)
	(segment
		(start 24.376634 -203.873354)
		(end 24.53005 -203.719938)
		(width 0.14478)
		(layer "In11.Cu")
		(net "M_F_CPU1_SA_DQ<4>")
	)
	(segment
		(start 28.50642 -203.247244)
		(end 28.669488 -203.084176)
		(width 0.14478)
		(layer "In11.Cu")
		(net "M_F_CPU1_SA_DQ<4>")
	)
	(segment
		(start 35.690048 -203.02347)
		(end 35.690048 -203.084176)
		(width 0.14478)
		(layer "In11.Cu")
		(net "M_F_CPU1_SA_DQ<4>")
	)
	(segment
		(start 50.947574 -203.242164)
		(end 51.177952 -203.242164)
		(width 0.14478)
		(layer "In11.Cu")
		(net "M_F_CPU1_SA_DQ<4>")
	)
	(segment
		(start 36.083494 -203.247244)
		(end 36.246562 -203.084176)
		(width 0.14478)
		(layer "In11.Cu")
		(net "M_F_CPU1_SA_DQ<4>")
	)
	(segment
		(start 35.52698 -202.860402)
		(end 35.690048 -203.02347)
		(width 0.14478)
		(layer "In11.Cu")
		(net "M_F_CPU1_SA_DQ<4>")
	)
	(segment
		(start 24.53005 -203.719938)
		(end 25.695402 -203.719938)
		(width 0.14478)
		(layer "In11.Cu")
		(net "M_F_CPU1_SA_DQ<4>")
	)
	(segment
		(start 62.702186 -205.68158)
		(end 62.702186 -207.128364)
		(width 0.14478)
		(layer "In11.Cu")
		(net "M_F_CPU1_SA_DQ<4>")
	)
	(segment
		(start 56.274208 -203.873354)
		(end 56.437276 -203.710286)
		(width 0.14478)
		(layer "In11.Cu")
		(net "M_F_CPU1_SA_DQ<4>")
	)
	(segment
		(start 31.330392 -203.719938)
		(end 33.272476 -203.719938)
		(width 0.14478)
		(layer "In11.Cu")
		(net "M_F_CPU1_SA_DQ<4>")
	)
	(segment
		(start 26.011886 -204.095604)
		(end 26.242264 -204.095604)
		(width 0.14478)
		(layer "In11.Cu")
		(net "M_F_CPU1_SA_DQ<4>")
	)
	(segment
		(start 33.272476 -203.719938)
		(end 33.425892 -203.873354)
		(width 0.14478)
		(layer "In11.Cu")
		(net "M_F_CPU1_SA_DQ<4>")
	)
	(segment
		(start 59.127898 -202.860402)
		(end 59.358276 -202.860402)
		(width 0.14478)
		(layer "In11.Cu")
		(net "M_F_CPU1_SA_DQ<4>")
	)
	(segment
		(start 51.34102 -203.02347)
		(end 51.494436 -202.870054)
		(width 0.14478)
		(layer "In11.Cu")
		(net "M_F_CPU1_SA_DQ<4>")
	)
	(segment
		(start 54.767734 -204.105764)
		(end 54.998112 -204.105764)
		(width 0.14478)
		(layer "In11.Cu")
		(net "M_F_CPU1_SA_DQ<4>")
	)
	(segment
		(start 36.399978 -202.870054)
		(end 37.962332 -202.870054)
		(width 0.14478)
		(layer "In11.Cu")
		(net "M_F_CPU1_SA_DQ<4>")
	)
	(segment
		(start 58.801762 -203.247244)
		(end 58.96483 -203.084176)
		(width 0.14478)
		(layer "In11.Cu")
		(net "M_F_CPU1_SA_DQ<4>")
	)
	(segment
		(start 26.5684 -203.710286)
		(end 26.81478 -203.710286)
		(width 0.14478)
		(layer "In11.Cu")
		(net "M_F_CPU1_SA_DQ<4>")
	)
	(segment
		(start 41.500044 -203.942696)
		(end 41.500044 -203.873354)
		(width 0.14478)
		(layer "In11.Cu")
		(net "M_F_CPU1_SA_DQ<4>")
	)
	(segment
		(start 23.278592 -203.710286)
		(end 23.657052 -203.710286)
		(width 0.14478)
		(layer "In11.Cu")
		(net "M_F_CPU1_SA_DQ<4>")
	)
	(segment
		(start 27.664664 -202.860402)
		(end 27.949906 -202.860402)
		(width 0.14478)
		(layer "In11.Cu")
		(net "M_F_CPU1_SA_DQ<4>")
	)
	(segment
		(start 58.245248 -202.860402)
		(end 58.408316 -203.02347)
		(width 0.14478)
		(layer "In11.Cu")
		(net "M_F_CPU1_SA_DQ<4>")
	)
	(segment
		(start 55.324248 -203.499466)
		(end 55.554626 -203.499466)
		(width 0.14478)
		(layer "In11.Cu")
		(net "M_F_CPU1_SA_DQ<4>")
	)
	(segment
		(start 78.033626 -227.605844)
		(end 78.391766 -227.963984)
		(width 0.0889)
		(layer "In11.Cu")
		(net "M_F_CPU1_SA_DQ<4>")
	)
	(segment
		(start 35.690048 -203.084176)
		(end 35.853116 -203.247244)
		(width 0.14478)
		(layer "In11.Cu")
		(net "M_F_CPU1_SA_DQ<4>")
	)
	(segment
		(start 76.92644 -224.28327)
		(end 77.613002 -224.969832)
		(width 0.0889)
		(layer "In11.Cu")
		(net "M_F_CPU1_SA_DQ<4>")
	)
	(segment
		(start 48.641762 -204.100684)
		(end 48.87214 -204.100684)
		(width 0.14478)
		(layer "In11.Cu")
		(net "M_F_CPU1_SA_DQ<4>")
	)
	(segment
		(start 84.271104 -228.575362)
		(end 84.367116 -228.549962)
		(width 0.0889)
		(layer "In11.Cu")
		(net "M_F_CPU1_SA_DQ<4>")
	)
	(segment
		(start 21.70811 -203.285344)
		(end 22.133052 -203.710286)
		(width 0.14478)
		(layer "In11.Cu")
		(net "M_F_CPU1_SA_DQ<4>")
	)
	(segment
		(start 35.233102 -202.860402)
		(end 35.52698 -202.860402)
		(width 0.14478)
		(layer "In11.Cu")
		(net "M_F_CPU1_SA_DQ<4>")
	)
	(segment
		(start 51.494436 -202.870054)
		(end 53.12156 -202.870054)
		(width 0.14478)
		(layer "In11.Cu")
		(net "M_F_CPU1_SA_DQ<4>")
	)
	(segment
		(start 62.702186 -207.128364)
		(end 73.299066 -217.725244)
		(width 0.14478)
		(layer "In11.Cu")
		(net "M_F_CPU1_SA_DQ<4>")
	)
	(segment
		(start 41.94302 -203.710286)
		(end 42.792904 -202.860402)
		(width 0.14478)
		(layer "In11.Cu")
		(net "M_F_CPU1_SA_DQ<4>")
	)
	(segment
		(start 58.96483 -203.02347)
		(end 59.127898 -202.860402)
		(width 0.14478)
		(layer "In11.Cu")
		(net "M_F_CPU1_SA_DQ<4>")
	)
	(segment
		(start 28.822904 -202.870054)
		(end 30.480508 -202.870054)
		(width 0.14478)
		(layer "In11.Cu")
		(net "M_F_CPU1_SA_DQ<4>")
	)
	(segment
		(start 54.441598 -203.710286)
		(end 54.604666 -203.873354)
		(width 0.14478)
		(layer "In11.Cu")
		(net "M_F_CPU1_SA_DQ<4>")
	)
	(segment
		(start 38.812216 -203.719938)
		(end 40.790114 -203.719938)
		(width 0.14478)
		(layer "In11.Cu")
		(net "M_F_CPU1_SA_DQ<4>")
	)
	(segment
		(start 35.853116 -203.247244)
		(end 36.083494 -203.247244)
		(width 0.14478)
		(layer "In11.Cu")
		(net "M_F_CPU1_SA_DQ<4>")
	)
	(segment
		(start 36.246562 -203.084176)
		(end 36.246562 -203.02347)
		(width 0.14478)
		(layer "In11.Cu")
		(net "M_F_CPU1_SA_DQ<4>")
	)
	(segment
		(start 43.231308 -203.02347)
		(end 43.231308 -203.079096)
		(width 0.14478)
		(layer "In11.Cu")
		(net "M_F_CPU1_SA_DQ<4>")
	)
	(segment
		(start 26.242264 -204.095604)
		(end 26.405332 -203.932536)
		(width 0.14478)
		(layer "In11.Cu")
		(net "M_F_CPU1_SA_DQ<4>")
	)
	(segment
		(start 40.94353 -203.873354)
		(end 40.94353 -203.942696)
		(width 0.14478)
		(layer "In11.Cu")
		(net "M_F_CPU1_SA_DQ<4>")
	)
	(segment
		(start 53.12156 -202.870054)
		(end 53.961792 -203.710286)
		(width 0.14478)
		(layer "In11.Cu")
		(net "M_F_CPU1_SA_DQ<4>")
	)
	(segment
		(start 30.480508 -202.870054)
		(end 31.330392 -203.719938)
		(width 0.14478)
		(layer "In11.Cu")
		(net "M_F_CPU1_SA_DQ<4>")
	)
	(segment
		(start 45.577506 -202.870054)
		(end 46.42739 -203.719938)
		(width 0.14478)
		(layer "In11.Cu")
		(net "M_F_CPU1_SA_DQ<4>")
	)
	(segment
		(start 54.604666 -203.942696)
		(end 54.767734 -204.105764)
		(width 0.14478)
		(layer "In11.Cu")
		(net "M_F_CPU1_SA_DQ<4>")
	)
	(segment
		(start 23.115524 -203.161392)
		(end 23.115524 -203.547218)
		(width 0.14478)
		(layer "In11.Cu")
		(net "M_F_CPU1_SA_DQ<4>")
	)
	(segment
		(start 78.391766 -227.963984)
		(end 78.856586 -227.963984)
		(width 0.0889)
		(layer "In11.Cu")
		(net "M_F_CPU1_SA_DQ<4>")
	)
	(segment
		(start 34.145474 -203.710286)
		(end 34.383218 -203.710286)
		(width 0.14478)
		(layer "In11.Cu")
		(net "M_F_CPU1_SA_DQ<4>")
	)
	(segment
		(start 50.784506 -203.079096)
		(end 50.947574 -203.242164)
		(width 0.14478)
		(layer "In11.Cu")
		(net "M_F_CPU1_SA_DQ<4>")
	)
	(segment
		(start 46.42739 -203.719938)
		(end 48.325278 -203.719938)
		(width 0.14478)
		(layer "In11.Cu")
		(net "M_F_CPU1_SA_DQ<4>")
	)
	(segment
		(start 23.82012 -203.937616)
		(end 23.983188 -204.100684)
		(width 0.14478)
		(layer "In11.Cu")
		(net "M_F_CPU1_SA_DQ<4>")
	)
	(segment
		(start 41.663112 -203.710286)
		(end 41.94302 -203.710286)
		(width 0.14478)
		(layer "In11.Cu")
		(net "M_F_CPU1_SA_DQ<4>")
	)
	(segment
		(start 55.880762 -204.105764)
		(end 56.11114 -204.105764)
		(width 0.14478)
		(layer "In11.Cu")
		(net "M_F_CPU1_SA_DQ<4>")
	)
	(segment
		(start 58.408316 -203.084176)
		(end 58.571384 -203.247244)
		(width 0.14478)
		(layer "In11.Cu")
		(net "M_F_CPU1_SA_DQ<4>")
	)
	(segment
		(start 34.383218 -203.710286)
		(end 35.233102 -202.860402)
		(width 0.14478)
		(layer "In11.Cu")
		(net "M_F_CPU1_SA_DQ<4>")
	)
	(segment
		(start 55.16118 -203.662534)
		(end 55.324248 -203.499466)
		(width 0.14478)
		(layer "In11.Cu")
		(net "M_F_CPU1_SA_DQ<4>")
	)
	(segment
		(start 28.112974 -203.02347)
		(end 28.112974 -203.084176)
		(width 0.14478)
		(layer "In11.Cu")
		(net "M_F_CPU1_SA_DQ<4>")
	)
	(segment
		(start 51.34102 -203.079096)
		(end 51.34102 -203.02347)
		(width 0.14478)
		(layer "In11.Cu")
		(net "M_F_CPU1_SA_DQ<4>")
	)
	(segment
		(start 33.982406 -203.937616)
		(end 33.982406 -203.873354)
		(width 0.14478)
		(layer "In11.Cu")
		(net "M_F_CPU1_SA_DQ<4>")
	)
	(segment
		(start 27.949906 -202.860402)
		(end 28.112974 -203.02347)
		(width 0.14478)
		(layer "In11.Cu")
		(net "M_F_CPU1_SA_DQ<4>")
	)
	(segment
		(start 42.792904 -202.860402)
		(end 43.06824 -202.860402)
		(width 0.14478)
		(layer "In11.Cu")
		(net "M_F_CPU1_SA_DQ<4>")
	)
	(segment
		(start 23.983188 -204.100684)
		(end 24.213566 -204.100684)
		(width 0.14478)
		(layer "In11.Cu")
		(net "M_F_CPU1_SA_DQ<4>")
	)
	(segment
		(start 33.819338 -204.100684)
		(end 33.982406 -203.937616)
		(width 0.14478)
		(layer "In11.Cu")
		(net "M_F_CPU1_SA_DQ<4>")
	)
	(segment
		(start 60.11291 -203.092304)
		(end 62.702186 -205.68158)
		(width 0.14478)
		(layer "In11.Cu")
		(net "M_F_CPU1_SA_DQ<4>")
	)
	(segment
		(start 48.87214 -204.100684)
		(end 49.035208 -203.937616)
		(width 0.14478)
		(layer "In11.Cu")
		(net "M_F_CPU1_SA_DQ<4>")
	)
	(segment
		(start 77.721968 -226.21621)
		(end 78.033626 -226.968558)
		(width 0.0889)
		(layer "In11.Cu")
		(net "M_F_CPU1_SA_DQ<4>")
	)
	(segment
		(start 23.115524 -203.547218)
		(end 23.278592 -203.710286)
		(width 0.14478)
		(layer "In11.Cu")
		(net "M_F_CPU1_SA_DQ<4>")
	)
	(segment
		(start 56.11114 -204.105764)
		(end 56.274208 -203.942696)
		(width 0.14478)
		(layer "In11.Cu")
		(net "M_F_CPU1_SA_DQ<4>")
	)
	(segment
		(start 36.246562 -203.02347)
		(end 36.399978 -202.870054)
		(width 0.14478)
		(layer "In11.Cu")
		(net "M_F_CPU1_SA_DQ<4>")
	)
	(segment
		(start 41.336976 -204.105764)
		(end 41.500044 -203.942696)
		(width 0.14478)
		(layer "In11.Cu")
		(net "M_F_CPU1_SA_DQ<4>")
	)
	(segment
		(start 23.657052 -203.710286)
		(end 23.82012 -203.873354)
		(width 0.14478)
		(layer "In11.Cu")
		(net "M_F_CPU1_SA_DQ<4>")
	)
	(segment
		(start 49.035208 -203.937616)
		(end 49.035208 -203.873354)
		(width 0.14478)
		(layer "In11.Cu")
		(net "M_F_CPU1_SA_DQ<4>")
	)
	(segment
		(start 76.92644 -224.09531)
		(end 76.92644 -224.28327)
		(width 0.14478)
		(layer "In11.Cu")
		(net "M_F_CPU1_SA_DQ<4>")
	)
	(segment
		(start 43.06824 -202.860402)
		(end 43.231308 -203.02347)
		(width 0.14478)
		(layer "In11.Cu")
		(net "M_F_CPU1_SA_DQ<4>")
	)
	(segment
		(start 25.848818 -203.873354)
		(end 25.848818 -203.932536)
		(width 0.14478)
		(layer "In11.Cu")
		(net "M_F_CPU1_SA_DQ<4>")
	)
	(segment
		(start 33.58896 -204.100684)
		(end 33.819338 -204.100684)
		(width 0.14478)
		(layer "In11.Cu")
		(net "M_F_CPU1_SA_DQ<4>")
	)
	(segment
		(start 77.540866 -225.749104)
		(end 77.540866 -226.035108)
		(width 0.0889)
		(layer "In11.Cu")
		(net "M_F_CPU1_SA_DQ<4>")
	)
	(segment
		(start 55.554626 -203.499466)
		(end 55.717694 -203.662534)
		(width 0.14478)
		(layer "In11.Cu")
		(net "M_F_CPU1_SA_DQ<4>")
	)
	(segment
		(start 40.94353 -203.942696)
		(end 41.106598 -204.105764)
		(width 0.14478)
		(layer "In11.Cu")
		(net "M_F_CPU1_SA_DQ<4>")
	)
	(segment
		(start 58.408316 -203.02347)
		(end 58.408316 -203.084176)
		(width 0.14478)
		(layer "In11.Cu")
		(net "M_F_CPU1_SA_DQ<4>")
	)
	(segment
		(start 37.962332 -202.870054)
		(end 38.812216 -203.719938)
		(width 0.14478)
		(layer "In11.Cu")
		(net "M_F_CPU1_SA_DQ<4>")
	)
	(segment
		(start 78.033626 -226.968558)
		(end 78.033626 -227.605844)
		(width 0.0889)
		(layer "In11.Cu")
		(net "M_F_CPU1_SA_DQ<4>")
	)
	(segment
		(start 25.695402 -203.719938)
		(end 25.848818 -203.873354)
		(width 0.14478)
		(layer "In11.Cu")
		(net "M_F_CPU1_SA_DQ<4>")
	)
	(segment
		(start 58.571384 -203.247244)
		(end 58.801762 -203.247244)
		(width 0.14478)
		(layer "In11.Cu")
		(net "M_F_CPU1_SA_DQ<4>")
	)
	(segment
		(start 57.804558 -202.860402)
		(end 58.245248 -202.860402)
		(width 0.14478)
		(layer "In11.Cu")
		(net "M_F_CPU1_SA_DQ<4>")
	)
	(segment
		(start 55.717694 -203.942696)
		(end 55.880762 -204.105764)
		(width 0.14478)
		(layer "In11.Cu")
		(net "M_F_CPU1_SA_DQ<4>")
	)
	(segment
		(start 41.500044 -203.873354)
		(end 41.663112 -203.710286)
		(width 0.14478)
		(layer "In11.Cu")
		(net "M_F_CPU1_SA_DQ<4>")
	)
	(segment
		(start 28.112974 -203.084176)
		(end 28.276042 -203.247244)
		(width 0.14478)
		(layer "In11.Cu")
		(net "M_F_CPU1_SA_DQ<4>")
	)
	(segment
		(start 26.405332 -203.932536)
		(end 26.405332 -203.873354)
		(width 0.14478)
		(layer "In11.Cu")
		(net "M_F_CPU1_SA_DQ<4>")
	)
	(segment
		(start 49.035208 -203.873354)
		(end 49.198276 -203.710286)
		(width 0.14478)
		(layer "In11.Cu")
		(net "M_F_CPU1_SA_DQ<4>")
	)
	(segment
		(start 83.394042 -228.607112)
		(end 83.402424 -228.611938)
		(width 0.0889)
		(layer "In11.Cu")
		(net "M_F_CPU1_SA_DQ<4>")
	)
	(segment
		(start 22.952456 -202.998324)
		(end 23.115524 -203.161392)
		(width 0.14478)
		(layer "In11.Cu")
		(net "M_F_CPU1_SA_DQ<4>")
	)
	(segment
		(start 54.604666 -203.873354)
		(end 54.604666 -203.942696)
		(width 0.14478)
		(layer "In11.Cu")
		(net "M_F_CPU1_SA_DQ<4>")
	)
	(segment
		(start 22.55901 -203.161392)
		(end 22.722078 -202.998324)
		(width 0.14478)
		(layer "In11.Cu")
		(net "M_F_CPU1_SA_DQ<4>")
	)
	(segment
		(start 22.133052 -203.710286)
		(end 22.395942 -203.710286)
		(width 0.14478)
		(layer "In11.Cu")
		(net "M_F_CPU1_SA_DQ<4>")
	)
	(segment
		(start 49.448974 -203.710286)
		(end 50.298858 -202.860402)
		(width 0.14478)
		(layer "In11.Cu")
		(net "M_F_CPU1_SA_DQ<4>")
	)
	(segment
		(start 33.982406 -203.873354)
		(end 34.145474 -203.710286)
		(width 0.14478)
		(layer "In11.Cu")
		(net "M_F_CPU1_SA_DQ<4>")
	)
	(segment
		(start 81.879694 -228.611938)
		(end 81.888076 -228.607112)
		(width 0.0889)
		(layer "In11.Cu")
		(net "M_F_CPU1_SA_DQ<4>")
	)
	(segment
		(start 28.669488 -203.084176)
		(end 28.669488 -203.02347)
		(width 0.14478)
		(layer "In11.Cu")
		(net "M_F_CPU1_SA_DQ<4>")
	)
	(arc
		(start 83.768184 -228.607112)
		(mid 84.015897 -228.531892)
		(end 84.271104 -228.575362)
		(width 0.0889)
		(layer "In11.Cu")
		(net "M_F_CPU1_SA_DQ<4>")
	)
	(arc
		(start 80.008222 -228.607112)
		(mid 80.291178 -228.530935)
		(end 80.574134 -228.607112)
		(width 0.0889)
		(layer "In11.Cu")
		(net "M_F_CPU1_SA_DQ<4>")
	)
	(arc
		(start 79.821024 -228.657658)
		(mid 79.917966 -228.644767)
		(end 80.008222 -228.607112)
		(width 0.0889)
		(layer "In11.Cu")
		(net "M_F_CPU1_SA_DQ<4>")
	)
	(arc
		(start 81.888076 -228.607112)
		(mid 82.171032 -228.530935)
		(end 82.453988 -228.607112)
		(width 0.0889)
		(layer "In11.Cu")
		(net "M_F_CPU1_SA_DQ<4>")
	)
	(arc
		(start 83.402424 -228.611938)
		(mid 83.585932 -228.657432)
		(end 83.768184 -228.607112)
		(width 0.0889)
		(layer "In11.Cu")
		(net "M_F_CPU1_SA_DQ<4>")
	)
	(arc
		(start 82.82813 -228.607112)
		(mid 83.111086 -228.530935)
		(end 83.394042 -228.607112)
		(width 0.0889)
		(layer "In11.Cu")
		(net "M_F_CPU1_SA_DQ<4>")
	)
	(arc
		(start 80.574134 -228.607112)
		(mid 80.761078 -228.657367)
		(end 80.948022 -228.607112)
		(width 0.0889)
		(layer "In11.Cu")
		(net "M_F_CPU1_SA_DQ<4>")
	)
	(arc
		(start 82.46237 -228.611938)
		(mid 82.645878 -228.657432)
		(end 82.82813 -228.607112)
		(width 0.0889)
		(layer "In11.Cu")
		(net "M_F_CPU1_SA_DQ<4>")
	)
	(arc
		(start 81.513934 -228.607112)
		(mid 81.696185 -228.657462)
		(end 81.879694 -228.611938)
		(width 0.0889)
		(layer "In11.Cu")
		(net "M_F_CPU1_SA_DQ<4>")
	)
	(arc
		(start 80.948022 -228.607112)
		(mid 81.230978 -228.530935)
		(end 81.513934 -228.607112)
		(width 0.0889)
		(layer "In11.Cu")
		(net "M_F_CPU1_SA_DQ<4>")
	)
	(segment
		(start 85.927946 -226.930458)
		(end 85.461094 -226.66452)
		(width 0.10668)
		(layer "F.Cu")
		(net "M_F_CPU1_SA_DQ<3>")
	)
	(segment
		(start 27.587448 -199.450706)
		(end 30.534102 -199.450706)
		(width 0.14478)
		(layer "In11.Cu")
		(net "M_F_CPU1_SA_DQ<3>")
	)
	(segment
		(start 78.05801 -221.465648)
		(end 78.241906 -221.649544)
		(width 0.0889)
		(layer "In11.Cu")
		(net "M_F_CPU1_SA_DQ<3>")
	)
	(segment
		(start 82.453988 -226.34194)
		(end 82.46237 -226.337114)
		(width 0.0889)
		(layer "In11.Cu")
		(net "M_F_CPU1_SA_DQ<3>")
	)
	(segment
		(start 69.956426 -210.9978)
		(end 75.615546 -216.65692)
		(width 0.14478)
		(layer "In11.Cu")
		(net "M_F_CPU1_SA_DQ<3>")
	)
	(segment
		(start 54.005226 -200.310496)
		(end 56.936132 -200.310496)
		(width 0.14478)
		(layer "In11.Cu")
		(net "M_F_CPU1_SA_DQ<3>")
	)
	(segment
		(start 79.538322 -225.531934)
		(end 79.570072 -225.550222)
		(width 0.0889)
		(layer "In11.Cu")
		(net "M_F_CPU1_SA_DQ<3>")
	)
	(segment
		(start 60.133484 -199.460358)
		(end 69.956426 -209.2833)
		(width 0.14478)
		(layer "In11.Cu")
		(net "M_F_CPU1_SA_DQ<3>")
	)
	(segment
		(start 26.737564 -200.30059)
		(end 27.587448 -199.450706)
		(width 0.14478)
		(layer "In11.Cu")
		(net "M_F_CPU1_SA_DQ<3>")
	)
	(segment
		(start 35.21837 -199.450706)
		(end 38.103556 -199.450706)
		(width 0.14478)
		(layer "In11.Cu")
		(net "M_F_CPU1_SA_DQ<3>")
	)
	(segment
		(start 42.751756 -199.450706)
		(end 45.609002 -199.450706)
		(width 0.14478)
		(layer "In11.Cu")
		(net "M_F_CPU1_SA_DQ<3>")
	)
	(segment
		(start 19.442176 -200.30059)
		(end 26.737564 -200.30059)
		(width 0.14478)
		(layer "In11.Cu")
		(net "M_F_CPU1_SA_DQ<3>")
	)
	(segment
		(start 75.615546 -216.65692)
		(end 75.615546 -219.023184)
		(width 0.14478)
		(layer "In11.Cu")
		(net "M_F_CPU1_SA_DQ<3>")
	)
	(segment
		(start 75.615546 -219.023184)
		(end 78.05801 -221.465648)
		(width 0.14478)
		(layer "In11.Cu")
		(net "M_F_CPU1_SA_DQ<3>")
	)
	(segment
		(start 38.95344 -200.30059)
		(end 41.901872 -200.30059)
		(width 0.14478)
		(layer "In11.Cu")
		(net "M_F_CPU1_SA_DQ<3>")
	)
	(segment
		(start 79.570072 -224.538794)
		(end 79.538322 -224.557082)
		(width 0.0889)
		(layer "In11.Cu")
		(net "M_F_CPU1_SA_DQ<3>")
	)
	(segment
		(start 46.458886 -200.30059)
		(end 49.399698 -200.30059)
		(width 0.14478)
		(layer "In11.Cu")
		(net "M_F_CPU1_SA_DQ<3>")
	)
	(segment
		(start 53.145436 -199.450706)
		(end 54.005226 -200.310496)
		(width 0.14478)
		(layer "In11.Cu")
		(net "M_F_CPU1_SA_DQ<3>")
	)
	(segment
		(start 79.538322 -223.911922)
		(end 79.570072 -223.93021)
		(width 0.0889)
		(layer "In11.Cu")
		(net "M_F_CPU1_SA_DQ<3>")
	)
	(segment
		(start 81.879694 -226.337114)
		(end 81.888076 -226.34194)
		(width 0.0889)
		(layer "In11.Cu")
		(net "M_F_CPU1_SA_DQ<3>")
	)
	(segment
		(start 78.241906 -221.649544)
		(end 78.241906 -222.078804)
		(width 0.0889)
		(layer "In11.Cu")
		(net "M_F_CPU1_SA_DQ<3>")
	)
	(segment
		(start 50.249582 -199.450706)
		(end 53.145436 -199.450706)
		(width 0.14478)
		(layer "In11.Cu")
		(net "M_F_CPU1_SA_DQ<3>")
	)
	(segment
		(start 78.241906 -222.078804)
		(end 78.41107 -222.247968)
		(width 0.0889)
		(layer "In11.Cu")
		(net "M_F_CPU1_SA_DQ<3>")
	)
	(segment
		(start 85.615018 -226.39909)
		(end 85.461094 -226.66452)
		(width 0.0889)
		(layer "In11.Cu")
		(net "M_F_CPU1_SA_DQ<3>")
	)
	(segment
		(start 18.033238 -200.310496)
		(end 18.569432 -200.310496)
		(width 0.14478)
		(layer "In11.Cu")
		(net "M_F_CPU1_SA_DQ<3>")
	)
	(segment
		(start 18.7325 -200.147428)
		(end 18.7325 -200.100692)
		(width 0.14478)
		(layer "In11.Cu")
		(net "M_F_CPU1_SA_DQ<3>")
	)
	(segment
		(start 79.497936 -225.508312)
		(end 79.538322 -225.531934)
		(width 0.0889)
		(layer "In11.Cu")
		(net "M_F_CPU1_SA_DQ<3>")
	)
	(segment
		(start 18.7325 -200.100692)
		(end 18.895568 -199.937624)
		(width 0.14478)
		(layer "In11.Cu")
		(net "M_F_CPU1_SA_DQ<3>")
	)
	(segment
		(start 30.534102 -199.450706)
		(end 31.383986 -200.30059)
		(width 0.14478)
		(layer "In11.Cu")
		(net "M_F_CPU1_SA_DQ<3>")
	)
	(segment
		(start 79.068168 -223.101916)
		(end 79.100934 -223.120966)
		(width 0.0889)
		(layer "In11.Cu")
		(net "M_F_CPU1_SA_DQ<3>")
	)
	(segment
		(start 17.608042 -199.8853)
		(end 18.033238 -200.310496)
		(width 0.14478)
		(layer "In11.Cu")
		(net "M_F_CPU1_SA_DQ<3>")
	)
	(segment
		(start 56.936132 -200.310496)
		(end 57.78627 -199.460358)
		(width 0.14478)
		(layer "In11.Cu")
		(net "M_F_CPU1_SA_DQ<3>")
	)
	(segment
		(start 79.9719 -226.320858)
		(end 80.008222 -226.34194)
		(width 0.0889)
		(layer "In11.Cu")
		(net "M_F_CPU1_SA_DQ<3>")
	)
	(segment
		(start 19.289014 -200.100692)
		(end 19.289014 -200.147428)
		(width 0.14478)
		(layer "In11.Cu")
		(net "M_F_CPU1_SA_DQ<3>")
	)
	(segment
		(start 57.78627 -199.460358)
		(end 60.133484 -199.460358)
		(width 0.14478)
		(layer "In11.Cu")
		(net "M_F_CPU1_SA_DQ<3>")
	)
	(segment
		(start 34.368486 -200.30059)
		(end 35.21837 -199.450706)
		(width 0.14478)
		(layer "In11.Cu")
		(net "M_F_CPU1_SA_DQ<3>")
	)
	(segment
		(start 85.592666 -226.315778)
		(end 85.615018 -226.39909)
		(width 0.0889)
		(layer "In11.Cu")
		(net "M_F_CPU1_SA_DQ<3>")
	)
	(segment
		(start 69.956426 -209.2833)
		(end 69.956426 -210.9978)
		(width 0.14478)
		(layer "In11.Cu")
		(net "M_F_CPU1_SA_DQ<3>")
	)
	(segment
		(start 19.289014 -200.147428)
		(end 19.442176 -200.30059)
		(width 0.14478)
		(layer "In11.Cu")
		(net "M_F_CPU1_SA_DQ<3>")
	)
	(segment
		(start 79.499206 -223.889062)
		(end 79.538322 -223.911922)
		(width 0.0889)
		(layer "In11.Cu")
		(net "M_F_CPU1_SA_DQ<3>")
	)
	(segment
		(start 49.399698 -200.30059)
		(end 50.249582 -199.450706)
		(width 0.14478)
		(layer "In11.Cu")
		(net "M_F_CPU1_SA_DQ<3>")
	)
	(segment
		(start 83.394042 -226.34194)
		(end 83.402424 -226.337114)
		(width 0.0889)
		(layer "In11.Cu")
		(net "M_F_CPU1_SA_DQ<3>")
	)
	(segment
		(start 79.03337 -223.081596)
		(end 79.068168 -223.101916)
		(width 0.0889)
		(layer "In11.Cu")
		(net "M_F_CPU1_SA_DQ<3>")
	)
	(segment
		(start 78.41107 -222.247968)
		(end 78.436216 -222.247968)
		(width 0.0889)
		(layer "In11.Cu")
		(net "M_F_CPU1_SA_DQ<3>")
	)
	(segment
		(start 38.103556 -199.450706)
		(end 38.95344 -200.30059)
		(width 0.14478)
		(layer "In11.Cu")
		(net "M_F_CPU1_SA_DQ<3>")
	)
	(segment
		(start 31.383986 -200.30059)
		(end 34.368486 -200.30059)
		(width 0.14478)
		(layer "In11.Cu")
		(net "M_F_CPU1_SA_DQ<3>")
	)
	(segment
		(start 41.901872 -200.30059)
		(end 42.751756 -199.450706)
		(width 0.14478)
		(layer "In11.Cu")
		(net "M_F_CPU1_SA_DQ<3>")
	)
	(segment
		(start 79.538322 -224.557082)
		(end 79.497936 -224.580704)
		(width 0.0889)
		(layer "In11.Cu")
		(net "M_F_CPU1_SA_DQ<3>")
	)
	(segment
		(start 19.125946 -199.937624)
		(end 19.289014 -200.100692)
		(width 0.14478)
		(layer "In11.Cu")
		(net "M_F_CPU1_SA_DQ<3>")
	)
	(segment
		(start 18.569432 -200.310496)
		(end 18.7325 -200.147428)
		(width 0.14478)
		(layer "In11.Cu")
		(net "M_F_CPU1_SA_DQ<3>")
	)
	(segment
		(start 45.609002 -199.450706)
		(end 46.458886 -200.30059)
		(width 0.14478)
		(layer "In11.Cu")
		(net "M_F_CPU1_SA_DQ<3>")
	)
	(segment
		(start 18.895568 -199.937624)
		(end 19.125946 -199.937624)
		(width 0.14478)
		(layer "In11.Cu")
		(net "M_F_CPU1_SA_DQ<3>")
	)
	(arc
		(start 79.100934 -223.120966)
		(mid 79.214863 -223.254113)
		(end 79.255874 -223.424496)
		(width 0.0889)
		(layer "In11.Cu")
		(net "M_F_CPU1_SA_DQ<3>")
	)
	(arc
		(start 79.497936 -224.580704)
		(mid 79.319871 -224.782881)
		(end 79.25562 -225.044508)
		(width 0.0889)
		(layer "In11.Cu")
		(net "M_F_CPU1_SA_DQ<3>")
	)
	(arc
		(start 78.786228 -222.61449)
		(mid 78.851829 -222.878709)
		(end 79.03337 -223.081596)
		(width 0.0889)
		(layer "In11.Cu")
		(net "M_F_CPU1_SA_DQ<3>")
	)
	(arc
		(start 82.46237 -226.337114)
		(mid 82.645878 -226.29162)
		(end 82.82813 -226.34194)
		(width 0.0889)
		(layer "In11.Cu")
		(net "M_F_CPU1_SA_DQ<3>")
	)
	(arc
		(start 79.255874 -223.424496)
		(mid 79.320389 -223.686715)
		(end 79.499206 -223.889062)
		(width 0.0889)
		(layer "In11.Cu")
		(net "M_F_CPU1_SA_DQ<3>")
	)
	(arc
		(start 80.008222 -226.34194)
		(mid 80.291178 -226.418117)
		(end 80.574134 -226.34194)
		(width 0.0889)
		(layer "In11.Cu")
		(net "M_F_CPU1_SA_DQ<3>")
	)
	(arc
		(start 80.948022 -226.34194)
		(mid 81.230978 -226.418117)
		(end 81.513934 -226.34194)
		(width 0.0889)
		(layer "In11.Cu")
		(net "M_F_CPU1_SA_DQ<3>")
	)
	(arc
		(start 79.570072 -225.550222)
		(mid 79.684748 -225.683556)
		(end 79.726028 -225.854514)
		(width 0.0889)
		(layer "In11.Cu")
		(net "M_F_CPU1_SA_DQ<3>")
	)
	(arc
		(start 80.574134 -226.34194)
		(mid 80.761078 -226.291685)
		(end 80.948022 -226.34194)
		(width 0.0889)
		(layer "In11.Cu")
		(net "M_F_CPU1_SA_DQ<3>")
	)
	(arc
		(start 82.82813 -226.34194)
		(mid 83.111086 -226.418117)
		(end 83.394042 -226.34194)
		(width 0.0889)
		(layer "In11.Cu")
		(net "M_F_CPU1_SA_DQ<3>")
	)
	(arc
		(start 84.707984 -226.34194)
		(mid 84.99094 -226.418117)
		(end 85.273896 -226.34194)
		(width 0.0889)
		(layer "In11.Cu")
		(net "M_F_CPU1_SA_DQ<3>")
	)
	(arc
		(start 84.334096 -226.34194)
		(mid 84.52104 -226.291685)
		(end 84.707984 -226.34194)
		(width 0.0889)
		(layer "In11.Cu")
		(net "M_F_CPU1_SA_DQ<3>")
	)
	(arc
		(start 81.513934 -226.34194)
		(mid 81.696185 -226.29159)
		(end 81.879694 -226.337114)
		(width 0.0889)
		(layer "In11.Cu")
		(net "M_F_CPU1_SA_DQ<3>")
	)
	(arc
		(start 78.624684 -222.306896)
		(mid 78.631897 -222.311392)
		(end 78.638654 -222.316548)
		(width 0.0889)
		(layer "In11.Cu")
		(net "M_F_CPU1_SA_DQ<3>")
	)
	(arc
		(start 79.726028 -225.854514)
		(mid 79.791264 -226.118105)
		(end 79.9719 -226.320858)
		(width 0.0889)
		(layer "In11.Cu")
		(net "M_F_CPU1_SA_DQ<3>")
	)
	(arc
		(start 79.570072 -223.93021)
		(mid 79.726 -224.234502)
		(end 79.570072 -224.538794)
		(width 0.0889)
		(layer "In11.Cu")
		(net "M_F_CPU1_SA_DQ<3>")
	)
	(arc
		(start 83.402424 -226.337114)
		(mid 83.585932 -226.29162)
		(end 83.768184 -226.34194)
		(width 0.0889)
		(layer "In11.Cu")
		(net "M_F_CPU1_SA_DQ<3>")
	)
	(arc
		(start 79.25562 -225.044508)
		(mid 79.319913 -225.306113)
		(end 79.497936 -225.508312)
		(width 0.0889)
		(layer "In11.Cu")
		(net "M_F_CPU1_SA_DQ<3>")
	)
	(arc
		(start 85.273896 -226.34194)
		(mid 85.430334 -226.292969)
		(end 85.592666 -226.315778)
		(width 0.0889)
		(layer "In11.Cu")
		(net "M_F_CPU1_SA_DQ<3>")
	)
	(arc
		(start 78.436216 -222.247968)
		(mid 78.533574 -222.267435)
		(end 78.624684 -222.306896)
		(width 0.0889)
		(layer "In11.Cu")
		(net "M_F_CPU1_SA_DQ<3>")
	)
	(arc
		(start 78.638654 -222.316548)
		(mid 78.742931 -222.450421)
		(end 78.786228 -222.61449)
		(width 0.0889)
		(layer "In11.Cu")
		(net "M_F_CPU1_SA_DQ<3>")
	)
	(arc
		(start 81.888076 -226.34194)
		(mid 82.171032 -226.418117)
		(end 82.453988 -226.34194)
		(width 0.0889)
		(layer "In11.Cu")
		(net "M_F_CPU1_SA_DQ<3>")
	)
	(arc
		(start 83.768184 -226.34194)
		(mid 84.05114 -226.418117)
		(end 84.334096 -226.34194)
		(width 0.0889)
		(layer "In11.Cu")
		(net "M_F_CPU1_SA_DQ<3>")
	)
	(segment
		(start 85.927946 -244.750336)
		(end 85.461094 -244.484398)
		(width 0.10668)
		(layer "F.Cu")
		(net "M_F_CPU1_SA_DQ<31>")
	)
	(segment
		(start 81.879694 -244.156992)
		(end 81.888076 -244.161818)
		(width 0.0889)
		(layer "In11.Cu")
		(net "M_F_CPU1_SA_DQ<31>")
	)
	(segment
		(start 77.814678 -244.237764)
		(end 78.41107 -244.237764)
		(width 0.0889)
		(layer "In11.Cu")
		(net "M_F_CPU1_SA_DQ<31>")
	)
	(segment
		(start 83.394042 -244.161818)
		(end 83.402424 -244.156992)
		(width 0.0889)
		(layer "In11.Cu")
		(net "M_F_CPU1_SA_DQ<31>")
	)
	(segment
		(start 59.659266 -234.310428)
		(end 60.46343 -235.114592)
		(width 0.14478)
		(layer "In11.Cu")
		(net "M_F_CPU1_SA_DQ<31>")
	)
	(segment
		(start 60.46343 -236.113828)
		(end 67.871086 -243.521484)
		(width 0.14478)
		(layer "In11.Cu")
		(net "M_F_CPU1_SA_DQ<31>")
	)
	(segment
		(start 35.208718 -233.46029)
		(end 38.113208 -233.46029)
		(width 0.14478)
		(layer "In11.Cu")
		(net "M_F_CPU1_SA_DQ<31>")
	)
	(segment
		(start 20.713446 -234.310428)
		(end 26.727658 -234.310428)
		(width 0.14478)
		(layer "In11.Cu")
		(net "M_F_CPU1_SA_DQ<31>")
	)
	(segment
		(start 18.880836 -233.676952)
		(end 19.043904 -233.513884)
		(width 0.14478)
		(layer "In11.Cu")
		(net "M_F_CPU1_SA_DQ<31>")
	)
	(segment
		(start 38.113208 -233.46029)
		(end 38.963346 -234.310428)
		(width 0.14478)
		(layer "In11.Cu")
		(net "M_F_CPU1_SA_DQ<31>")
	)
	(segment
		(start 31.393892 -234.310428)
		(end 34.35858 -234.310428)
		(width 0.14478)
		(layer "In11.Cu")
		(net "M_F_CPU1_SA_DQ<31>")
	)
	(segment
		(start 78.693772 -244.161818)
		(end 78.705456 -244.15496)
		(width 0.0889)
		(layer "In11.Cu")
		(net "M_F_CPU1_SA_DQ<31>")
	)
	(segment
		(start 19.274282 -233.513884)
		(end 19.43735 -233.676952)
		(width 0.14478)
		(layer "In11.Cu")
		(net "M_F_CPU1_SA_DQ<31>")
	)
	(segment
		(start 46.468792 -234.310428)
		(end 49.389792 -234.310428)
		(width 0.14478)
		(layer "In11.Cu")
		(net "M_F_CPU1_SA_DQ<31>")
	)
	(segment
		(start 76.207366 -243.521484)
		(end 76.499466 -243.813584)
		(width 0.0889)
		(layer "In11.Cu")
		(net "M_F_CPU1_SA_DQ<31>")
	)
	(segment
		(start 19.993864 -234.14736)
		(end 19.993864 -233.676952)
		(width 0.14478)
		(layer "In11.Cu")
		(net "M_F_CPU1_SA_DQ<31>")
	)
	(segment
		(start 41.891966 -234.310428)
		(end 42.742104 -233.46029)
		(width 0.14478)
		(layer "In11.Cu")
		(net "M_F_CPU1_SA_DQ<31>")
	)
	(segment
		(start 18.880836 -234.14736)
		(end 18.880836 -233.676952)
		(width 0.14478)
		(layer "In11.Cu")
		(net "M_F_CPU1_SA_DQ<31>")
	)
	(segment
		(start 50.23993 -233.46029)
		(end 53.155088 -233.46029)
		(width 0.14478)
		(layer "In11.Cu")
		(net "M_F_CPU1_SA_DQ<31>")
	)
	(segment
		(start 20.156932 -233.513884)
		(end 20.38731 -233.513884)
		(width 0.14478)
		(layer "In11.Cu")
		(net "M_F_CPU1_SA_DQ<31>")
	)
	(segment
		(start 67.871086 -243.521484)
		(end 75.930506 -243.521484)
		(width 0.14478)
		(layer "In11.Cu")
		(net "M_F_CPU1_SA_DQ<31>")
	)
	(segment
		(start 60.46343 -235.114592)
		(end 60.46343 -236.113828)
		(width 0.14478)
		(layer "In11.Cu")
		(net "M_F_CPU1_SA_DQ<31>")
	)
	(segment
		(start 19.043904 -233.513884)
		(end 19.274282 -233.513884)
		(width 0.14478)
		(layer "In11.Cu")
		(net "M_F_CPU1_SA_DQ<31>")
	)
	(segment
		(start 18.033238 -234.310428)
		(end 18.717768 -234.310428)
		(width 0.14478)
		(layer "In11.Cu")
		(net "M_F_CPU1_SA_DQ<31>")
	)
	(segment
		(start 54.005226 -234.310428)
		(end 59.659266 -234.310428)
		(width 0.14478)
		(layer "In11.Cu")
		(net "M_F_CPU1_SA_DQ<31>")
	)
	(segment
		(start 82.453988 -244.161818)
		(end 82.46237 -244.156992)
		(width 0.0889)
		(layer "In11.Cu")
		(net "M_F_CPU1_SA_DQ<31>")
	)
	(segment
		(start 49.389792 -234.310428)
		(end 50.23993 -233.46029)
		(width 0.14478)
		(layer "In11.Cu")
		(net "M_F_CPU1_SA_DQ<31>")
	)
	(segment
		(start 27.577796 -233.46029)
		(end 30.543754 -233.46029)
		(width 0.14478)
		(layer "In11.Cu")
		(net "M_F_CPU1_SA_DQ<31>")
	)
	(segment
		(start 53.155088 -233.46029)
		(end 54.005226 -234.310428)
		(width 0.14478)
		(layer "In11.Cu")
		(net "M_F_CPU1_SA_DQ<31>")
	)
	(segment
		(start 17.608042 -233.885232)
		(end 18.033238 -234.310428)
		(width 0.14478)
		(layer "In11.Cu")
		(net "M_F_CPU1_SA_DQ<31>")
	)
	(segment
		(start 18.717768 -234.310428)
		(end 18.880836 -234.14736)
		(width 0.14478)
		(layer "In11.Cu")
		(net "M_F_CPU1_SA_DQ<31>")
	)
	(segment
		(start 34.35858 -234.310428)
		(end 35.208718 -233.46029)
		(width 0.14478)
		(layer "In11.Cu")
		(net "M_F_CPU1_SA_DQ<31>")
	)
	(segment
		(start 19.993864 -233.676952)
		(end 20.156932 -233.513884)
		(width 0.14478)
		(layer "In11.Cu")
		(net "M_F_CPU1_SA_DQ<31>")
	)
	(segment
		(start 85.592666 -244.135656)
		(end 85.615018 -244.218968)
		(width 0.0889)
		(layer "In11.Cu")
		(net "M_F_CPU1_SA_DQ<31>")
	)
	(segment
		(start 75.930506 -243.521484)
		(end 76.207366 -243.521484)
		(width 0.0889)
		(layer "In11.Cu")
		(net "M_F_CPU1_SA_DQ<31>")
	)
	(segment
		(start 45.618654 -233.46029)
		(end 46.468792 -234.310428)
		(width 0.14478)
		(layer "In11.Cu")
		(net "M_F_CPU1_SA_DQ<31>")
	)
	(segment
		(start 42.742104 -233.46029)
		(end 45.618654 -233.46029)
		(width 0.14478)
		(layer "In11.Cu")
		(net "M_F_CPU1_SA_DQ<31>")
	)
	(segment
		(start 19.43735 -234.14736)
		(end 19.600418 -234.310428)
		(width 0.14478)
		(layer "In11.Cu")
		(net "M_F_CPU1_SA_DQ<31>")
	)
	(segment
		(start 19.830796 -234.310428)
		(end 19.993864 -234.14736)
		(width 0.14478)
		(layer "In11.Cu")
		(net "M_F_CPU1_SA_DQ<31>")
	)
	(segment
		(start 20.550378 -233.676952)
		(end 20.550378 -234.14736)
		(width 0.14478)
		(layer "In11.Cu")
		(net "M_F_CPU1_SA_DQ<31>")
	)
	(segment
		(start 77.390498 -243.813584)
		(end 77.814678 -244.237764)
		(width 0.0889)
		(layer "In11.Cu")
		(net "M_F_CPU1_SA_DQ<31>")
	)
	(segment
		(start 20.550378 -234.14736)
		(end 20.713446 -234.310428)
		(width 0.14478)
		(layer "In11.Cu")
		(net "M_F_CPU1_SA_DQ<31>")
	)
	(segment
		(start 19.43735 -233.676952)
		(end 19.43735 -234.14736)
		(width 0.14478)
		(layer "In11.Cu")
		(net "M_F_CPU1_SA_DQ<31>")
	)
	(segment
		(start 20.38731 -233.513884)
		(end 20.550378 -233.676952)
		(width 0.14478)
		(layer "In11.Cu")
		(net "M_F_CPU1_SA_DQ<31>")
	)
	(segment
		(start 38.963346 -234.310428)
		(end 41.891966 -234.310428)
		(width 0.14478)
		(layer "In11.Cu")
		(net "M_F_CPU1_SA_DQ<31>")
	)
	(segment
		(start 19.600418 -234.310428)
		(end 19.830796 -234.310428)
		(width 0.14478)
		(layer "In11.Cu")
		(net "M_F_CPU1_SA_DQ<31>")
	)
	(segment
		(start 26.727658 -234.310428)
		(end 27.577796 -233.46029)
		(width 0.14478)
		(layer "In11.Cu")
		(net "M_F_CPU1_SA_DQ<31>")
	)
	(segment
		(start 85.615018 -244.218968)
		(end 85.461094 -244.484398)
		(width 0.0889)
		(layer "In11.Cu")
		(net "M_F_CPU1_SA_DQ<31>")
	)
	(segment
		(start 76.499466 -243.813584)
		(end 77.390498 -243.813584)
		(width 0.0889)
		(layer "In11.Cu")
		(net "M_F_CPU1_SA_DQ<31>")
	)
	(segment
		(start 30.543754 -233.46029)
		(end 31.393892 -234.310428)
		(width 0.14478)
		(layer "In11.Cu")
		(net "M_F_CPU1_SA_DQ<31>")
	)
	(segment
		(start 79.06766 -244.161818)
		(end 79.078074 -244.167914)
		(width 0.0889)
		(layer "In11.Cu")
		(net "M_F_CPU1_SA_DQ<31>")
	)
	(arc
		(start 78.41107 -244.237764)
		(mid 78.557445 -244.218485)
		(end 78.693772 -244.161818)
		(width 0.0889)
		(layer "In11.Cu")
		(net "M_F_CPU1_SA_DQ<31>")
	)
	(arc
		(start 83.402424 -244.156992)
		(mid 83.585932 -244.111498)
		(end 83.768184 -244.161818)
		(width 0.0889)
		(layer "In11.Cu")
		(net "M_F_CPU1_SA_DQ<31>")
	)
	(arc
		(start 80.574134 -244.161818)
		(mid 80.761078 -244.111563)
		(end 80.948022 -244.161818)
		(width 0.0889)
		(layer "In11.Cu")
		(net "M_F_CPU1_SA_DQ<31>")
	)
	(arc
		(start 79.078074 -244.167914)
		(mid 79.35676 -244.238134)
		(end 79.633826 -244.161818)
		(width 0.0889)
		(layer "In11.Cu")
		(net "M_F_CPU1_SA_DQ<31>")
	)
	(arc
		(start 80.948022 -244.161818)
		(mid 81.230978 -244.237995)
		(end 81.513934 -244.161818)
		(width 0.0889)
		(layer "In11.Cu")
		(net "M_F_CPU1_SA_DQ<31>")
	)
	(arc
		(start 82.46237 -244.156992)
		(mid 82.645878 -244.111498)
		(end 82.82813 -244.161818)
		(width 0.0889)
		(layer "In11.Cu")
		(net "M_F_CPU1_SA_DQ<31>")
	)
	(arc
		(start 84.707984 -244.161818)
		(mid 84.99094 -244.237995)
		(end 85.273896 -244.161818)
		(width 0.0889)
		(layer "In11.Cu")
		(net "M_F_CPU1_SA_DQ<31>")
	)
	(arc
		(start 85.273896 -244.161818)
		(mid 85.430334 -244.112847)
		(end 85.592666 -244.135656)
		(width 0.0889)
		(layer "In11.Cu")
		(net "M_F_CPU1_SA_DQ<31>")
	)
	(arc
		(start 84.334096 -244.161818)
		(mid 84.52104 -244.111563)
		(end 84.707984 -244.161818)
		(width 0.0889)
		(layer "In11.Cu")
		(net "M_F_CPU1_SA_DQ<31>")
	)
	(arc
		(start 78.705456 -244.15496)
		(mid 78.887457 -244.111427)
		(end 79.06766 -244.161818)
		(width 0.0889)
		(layer "In11.Cu")
		(net "M_F_CPU1_SA_DQ<31>")
	)
	(arc
		(start 83.768184 -244.161818)
		(mid 84.05114 -244.237995)
		(end 84.334096 -244.161818)
		(width 0.0889)
		(layer "In11.Cu")
		(net "M_F_CPU1_SA_DQ<31>")
	)
	(arc
		(start 80.008222 -244.161818)
		(mid 80.291178 -244.237995)
		(end 80.574134 -244.161818)
		(width 0.0889)
		(layer "In11.Cu")
		(net "M_F_CPU1_SA_DQ<31>")
	)
	(arc
		(start 79.633826 -244.161818)
		(mid 79.821024 -244.111436)
		(end 80.008222 -244.161818)
		(width 0.0889)
		(layer "In11.Cu")
		(net "M_F_CPU1_SA_DQ<31>")
	)
	(arc
		(start 81.513934 -244.161818)
		(mid 81.696185 -244.111468)
		(end 81.879694 -244.156992)
		(width 0.0889)
		(layer "In11.Cu")
		(net "M_F_CPU1_SA_DQ<31>")
	)
	(arc
		(start 81.888076 -244.161818)
		(mid 82.171032 -244.237995)
		(end 82.453988 -244.161818)
		(width 0.0889)
		(layer "In11.Cu")
		(net "M_F_CPU1_SA_DQ<31>")
	)
	(arc
		(start 82.82813 -244.161818)
		(mid 83.111086 -244.237995)
		(end 83.394042 -244.161818)
		(width 0.0889)
		(layer "In11.Cu")
		(net "M_F_CPU1_SA_DQ<31>")
	)
	(segment
		(start 84.517992 -243.94033)
		(end 84.05114 -243.674392)
		(width 0.10668)
		(layer "F.Cu")
		(net "M_F_CPU1_SA_DQ<30>")
	)
	(segment
		(start 20.775676 -231.663494)
		(end 20.775676 -232.447338)
		(width 0.14478)
		(layer "In11.Cu")
		(net "M_F_CPU1_SA_DQ<30>")
	)
	(segment
		(start 20.219162 -232.634536)
		(end 20.219162 -231.663494)
		(width 0.14478)
		(layer "In11.Cu")
		(net "M_F_CPU1_SA_DQ<30>")
	)
	(segment
		(start 20.219162 -231.663494)
		(end 20.38223 -231.500426)
		(width 0.14478)
		(layer "In11.Cu")
		(net "M_F_CPU1_SA_DQ<30>")
	)
	(segment
		(start 18.634964 -232.610406)
		(end 18.798032 -232.447338)
		(width 0.14478)
		(layer "In11.Cu")
		(net "M_F_CPU1_SA_DQ<30>")
	)
	(segment
		(start 81.044034 -243.351812)
		(end 81.052416 -243.346986)
		(width 0.0889)
		(layer "In11.Cu")
		(net "M_F_CPU1_SA_DQ<30>")
	)
	(segment
		(start 20.38223 -231.500426)
		(end 20.612608 -231.500426)
		(width 0.14478)
		(layer "In11.Cu")
		(net "M_F_CPU1_SA_DQ<30>")
	)
	(segment
		(start 84.182712 -243.32565)
		(end 84.205064 -243.408962)
		(width 0.0889)
		(layer "In11.Cu")
		(net "M_F_CPU1_SA_DQ<30>")
	)
	(segment
		(start 19.354546 -231.957372)
		(end 19.354546 -232.634536)
		(width 0.14478)
		(layer "In11.Cu")
		(net "M_F_CPU1_SA_DQ<30>")
	)
	(segment
		(start 84.205064 -243.408962)
		(end 84.05114 -243.674392)
		(width 0.0889)
		(layer "In11.Cu")
		(net "M_F_CPU1_SA_DQ<30>")
	)
	(segment
		(start 50.23993 -231.760268)
		(end 53.155088 -231.760268)
		(width 0.14478)
		(layer "In11.Cu")
		(net "M_F_CPU1_SA_DQ<30>")
	)
	(segment
		(start 76.430886 -242.769644)
		(end 77.098906 -242.769644)
		(width 0.0889)
		(layer "In11.Cu")
		(net "M_F_CPU1_SA_DQ<30>")
	)
	(segment
		(start 19.354546 -232.634536)
		(end 19.517614 -232.797604)
		(width 0.14478)
		(layer "In11.Cu")
		(net "M_F_CPU1_SA_DQ<30>")
	)
	(segment
		(start 17.608042 -232.18521)
		(end 18.033238 -232.610406)
		(width 0.14478)
		(layer "In11.Cu")
		(net "M_F_CPU1_SA_DQ<30>")
	)
	(segment
		(start 38.113208 -231.760268)
		(end 38.963346 -232.610406)
		(width 0.14478)
		(layer "In11.Cu")
		(net "M_F_CPU1_SA_DQ<30>")
	)
	(segment
		(start 18.9611 -231.794304)
		(end 19.191478 -231.794304)
		(width 0.14478)
		(layer "In11.Cu")
		(net "M_F_CPU1_SA_DQ<30>")
	)
	(segment
		(start 31.393892 -232.610406)
		(end 34.35858 -232.610406)
		(width 0.14478)
		(layer "In11.Cu")
		(net "M_F_CPU1_SA_DQ<30>")
	)
	(segment
		(start 61.414406 -235.778548)
		(end 68.248022 -242.612164)
		(width 0.14478)
		(layer "In11.Cu")
		(net "M_F_CPU1_SA_DQ<30>")
	)
	(segment
		(start 20.938744 -232.610406)
		(end 26.727658 -232.610406)
		(width 0.14478)
		(layer "In11.Cu")
		(net "M_F_CPU1_SA_DQ<30>")
	)
	(segment
		(start 34.35858 -232.610406)
		(end 35.208718 -231.760268)
		(width 0.14478)
		(layer "In11.Cu")
		(net "M_F_CPU1_SA_DQ<30>")
	)
	(segment
		(start 19.517614 -232.797604)
		(end 20.056094 -232.797604)
		(width 0.14478)
		(layer "In11.Cu")
		(net "M_F_CPU1_SA_DQ<30>")
	)
	(segment
		(start 77.098906 -242.769644)
		(end 77.630782 -243.30152)
		(width 0.0889)
		(layer "In11.Cu")
		(net "M_F_CPU1_SA_DQ<30>")
	)
	(segment
		(start 80.46974 -243.346986)
		(end 80.478122 -243.351812)
		(width 0.0889)
		(layer "In11.Cu")
		(net "M_F_CPU1_SA_DQ<30>")
	)
	(segment
		(start 27.577796 -231.760268)
		(end 30.543754 -231.760268)
		(width 0.14478)
		(layer "In11.Cu")
		(net "M_F_CPU1_SA_DQ<30>")
	)
	(segment
		(start 38.963346 -232.610406)
		(end 41.891966 -232.610406)
		(width 0.14478)
		(layer "In11.Cu")
		(net "M_F_CPU1_SA_DQ<30>")
	)
	(segment
		(start 26.727658 -232.610406)
		(end 27.577796 -231.760268)
		(width 0.14478)
		(layer "In11.Cu")
		(net "M_F_CPU1_SA_DQ<30>")
	)
	(segment
		(start 59.493404 -232.610406)
		(end 61.414406 -234.531408)
		(width 0.14478)
		(layer "In11.Cu")
		(net "M_F_CPU1_SA_DQ<30>")
	)
	(segment
		(start 79.53883 -243.352066)
		(end 79.550768 -243.358924)
		(width 0.0889)
		(layer "In11.Cu")
		(net "M_F_CPU1_SA_DQ<30>")
	)
	(segment
		(start 79.525114 -243.344192)
		(end 79.53883 -243.352066)
		(width 0.0889)
		(layer "In11.Cu")
		(net "M_F_CPU1_SA_DQ<30>")
	)
	(segment
		(start 77.630782 -243.30152)
		(end 78.41107 -243.30152)
		(width 0.0889)
		(layer "In11.Cu")
		(net "M_F_CPU1_SA_DQ<30>")
	)
	(segment
		(start 18.033238 -232.610406)
		(end 18.634964 -232.610406)
		(width 0.14478)
		(layer "In11.Cu")
		(net "M_F_CPU1_SA_DQ<30>")
	)
	(segment
		(start 20.612608 -231.500426)
		(end 20.775676 -231.663494)
		(width 0.14478)
		(layer "In11.Cu")
		(net "M_F_CPU1_SA_DQ<30>")
	)
	(segment
		(start 19.191478 -231.794304)
		(end 19.354546 -231.957372)
		(width 0.14478)
		(layer "In11.Cu")
		(net "M_F_CPU1_SA_DQ<30>")
	)
	(segment
		(start 79.147162 -243.36248)
		(end 79.165196 -243.351812)
		(width 0.0889)
		(layer "In11.Cu")
		(net "M_F_CPU1_SA_DQ<30>")
	)
	(segment
		(start 49.389792 -232.610406)
		(end 50.23993 -231.760268)
		(width 0.14478)
		(layer "In11.Cu")
		(net "M_F_CPU1_SA_DQ<30>")
	)
	(segment
		(start 68.248022 -242.612164)
		(end 75.978766 -242.612164)
		(width 0.14478)
		(layer "In11.Cu")
		(net "M_F_CPU1_SA_DQ<30>")
	)
	(segment
		(start 42.742104 -231.760268)
		(end 45.618654 -231.760268)
		(width 0.14478)
		(layer "In11.Cu")
		(net "M_F_CPU1_SA_DQ<30>")
	)
	(segment
		(start 18.798032 -231.957372)
		(end 18.9611 -231.794304)
		(width 0.14478)
		(layer "In11.Cu")
		(net "M_F_CPU1_SA_DQ<30>")
	)
	(segment
		(start 46.468792 -232.610406)
		(end 49.389792 -232.610406)
		(width 0.14478)
		(layer "In11.Cu")
		(net "M_F_CPU1_SA_DQ<30>")
	)
	(segment
		(start 45.618654 -231.760268)
		(end 46.468792 -232.610406)
		(width 0.14478)
		(layer "In11.Cu")
		(net "M_F_CPU1_SA_DQ<30>")
	)
	(segment
		(start 20.056094 -232.797604)
		(end 20.219162 -232.634536)
		(width 0.14478)
		(layer "In11.Cu")
		(net "M_F_CPU1_SA_DQ<30>")
	)
	(segment
		(start 61.414406 -234.531408)
		(end 61.414406 -235.778548)
		(width 0.14478)
		(layer "In11.Cu")
		(net "M_F_CPU1_SA_DQ<30>")
	)
	(segment
		(start 54.005226 -232.610406)
		(end 59.493404 -232.610406)
		(width 0.14478)
		(layer "In11.Cu")
		(net "M_F_CPU1_SA_DQ<30>")
	)
	(segment
		(start 83.289648 -243.346986)
		(end 83.29803 -243.351812)
		(width 0.0889)
		(layer "In11.Cu")
		(net "M_F_CPU1_SA_DQ<30>")
	)
	(segment
		(start 30.543754 -231.760268)
		(end 31.393892 -232.610406)
		(width 0.14478)
		(layer "In11.Cu")
		(net "M_F_CPU1_SA_DQ<30>")
	)
	(segment
		(start 53.155088 -231.760268)
		(end 54.005226 -232.610406)
		(width 0.14478)
		(layer "In11.Cu")
		(net "M_F_CPU1_SA_DQ<30>")
	)
	(segment
		(start 76.273406 -242.612164)
		(end 76.430886 -242.769644)
		(width 0.0889)
		(layer "In11.Cu")
		(net "M_F_CPU1_SA_DQ<30>")
	)
	(segment
		(start 18.798032 -232.447338)
		(end 18.798032 -231.957372)
		(width 0.14478)
		(layer "In11.Cu")
		(net "M_F_CPU1_SA_DQ<30>")
	)
	(segment
		(start 75.978766 -242.612164)
		(end 76.273406 -242.612164)
		(width 0.0889)
		(layer "In11.Cu")
		(net "M_F_CPU1_SA_DQ<30>")
	)
	(segment
		(start 20.775676 -232.447338)
		(end 20.938744 -232.610406)
		(width 0.14478)
		(layer "In11.Cu")
		(net "M_F_CPU1_SA_DQ<30>")
	)
	(segment
		(start 35.208718 -231.760268)
		(end 38.113208 -231.760268)
		(width 0.14478)
		(layer "In11.Cu")
		(net "M_F_CPU1_SA_DQ<30>")
	)
	(segment
		(start 41.891966 -232.610406)
		(end 42.742104 -231.760268)
		(width 0.14478)
		(layer "In11.Cu")
		(net "M_F_CPU1_SA_DQ<30>")
	)
	(arc
		(start 81.418176 -243.351812)
		(mid 81.701132 -243.427989)
		(end 81.984088 -243.351812)
		(width 0.0889)
		(layer "In11.Cu")
		(net "M_F_CPU1_SA_DQ<30>")
	)
	(arc
		(start 78.41107 -243.30152)
		(mid 78.508133 -243.314238)
		(end 78.598522 -243.351812)
		(width 0.0889)
		(layer "In11.Cu")
		(net "M_F_CPU1_SA_DQ<30>")
	)
	(arc
		(start 79.550768 -243.358924)
		(mid 79.828302 -243.427905)
		(end 80.10398 -243.351812)
		(width 0.0889)
		(layer "In11.Cu")
		(net "M_F_CPU1_SA_DQ<30>")
	)
	(arc
		(start 81.984088 -243.351812)
		(mid 82.171032 -243.301557)
		(end 82.357976 -243.351812)
		(width 0.0889)
		(layer "In11.Cu")
		(net "M_F_CPU1_SA_DQ<30>")
	)
	(arc
		(start 79.165196 -243.351812)
		(mid 79.344183 -243.301642)
		(end 79.525114 -243.344192)
		(width 0.0889)
		(layer "In11.Cu")
		(net "M_F_CPU1_SA_DQ<30>")
	)
	(arc
		(start 80.10398 -243.351812)
		(mid 80.286231 -243.301462)
		(end 80.46974 -243.346986)
		(width 0.0889)
		(layer "In11.Cu")
		(net "M_F_CPU1_SA_DQ<30>")
	)
	(arc
		(start 80.478122 -243.351812)
		(mid 80.761078 -243.427989)
		(end 81.044034 -243.351812)
		(width 0.0889)
		(layer "In11.Cu")
		(net "M_F_CPU1_SA_DQ<30>")
	)
	(arc
		(start 82.923888 -243.351812)
		(mid 83.106139 -243.301462)
		(end 83.289648 -243.346986)
		(width 0.0889)
		(layer "In11.Cu")
		(net "M_F_CPU1_SA_DQ<30>")
	)
	(arc
		(start 78.598522 -243.351812)
		(mid 78.871466 -243.428392)
		(end 79.147162 -243.36248)
		(width 0.0889)
		(layer "In11.Cu")
		(net "M_F_CPU1_SA_DQ<30>")
	)
	(arc
		(start 83.863942 -243.351812)
		(mid 84.02038 -243.302841)
		(end 84.182712 -243.32565)
		(width 0.0889)
		(layer "In11.Cu")
		(net "M_F_CPU1_SA_DQ<30>")
	)
	(arc
		(start 82.357976 -243.351812)
		(mid 82.640932 -243.427989)
		(end 82.923888 -243.351812)
		(width 0.0889)
		(layer "In11.Cu")
		(net "M_F_CPU1_SA_DQ<30>")
	)
	(arc
		(start 83.29803 -243.351812)
		(mid 83.580986 -243.427989)
		(end 83.863942 -243.351812)
		(width 0.0889)
		(layer "In11.Cu")
		(net "M_F_CPU1_SA_DQ<30>")
	)
	(arc
		(start 81.052416 -243.346986)
		(mid 81.235924 -243.301492)
		(end 81.418176 -243.351812)
		(width 0.0889)
		(layer "In11.Cu")
		(net "M_F_CPU1_SA_DQ<30>")
	)
	(segment
		(start 84.517992 -226.120452)
		(end 84.05114 -225.854514)
		(width 0.10668)
		(layer "F.Cu")
		(net "M_F_CPU1_SA_DQ<2>")
	)
	(segment
		(start 41.891966 -198.610474)
		(end 42.742104 -197.760336)
		(width 0.14478)
		(layer "In11.Cu")
		(net "M_F_CPU1_SA_DQ<2>")
	)
	(segment
		(start 27.577796 -197.760336)
		(end 30.543754 -197.760336)
		(width 0.14478)
		(layer "In11.Cu")
		(net "M_F_CPU1_SA_DQ<2>")
	)
	(segment
		(start 54.005226 -198.610474)
		(end 56.936132 -198.610474)
		(width 0.14478)
		(layer "In11.Cu")
		(net "M_F_CPU1_SA_DQ<2>")
	)
	(segment
		(start 18.033238 -198.610474)
		(end 18.631662 -198.610474)
		(width 0.14478)
		(layer "In11.Cu")
		(net "M_F_CPU1_SA_DQ<2>")
	)
	(segment
		(start 45.618654 -197.760336)
		(end 46.468792 -198.610474)
		(width 0.14478)
		(layer "In11.Cu")
		(net "M_F_CPU1_SA_DQ<2>")
	)
	(segment
		(start 26.727658 -198.610474)
		(end 27.577796 -197.760336)
		(width 0.14478)
		(layer "In11.Cu")
		(net "M_F_CPU1_SA_DQ<2>")
	)
	(segment
		(start 79.497936 -222.268288)
		(end 79.538322 -222.29191)
		(width 0.0889)
		(layer "In11.Cu")
		(net "M_F_CPU1_SA_DQ<2>")
	)
	(segment
		(start 53.155088 -197.760336)
		(end 54.005226 -198.610474)
		(width 0.14478)
		(layer "In11.Cu")
		(net "M_F_CPU1_SA_DQ<2>")
	)
	(segment
		(start 81.044034 -225.531934)
		(end 81.052416 -225.527108)
		(width 0.0889)
		(layer "In11.Cu")
		(net "M_F_CPU1_SA_DQ<2>")
	)
	(segment
		(start 79.049626 -221.080584)
		(end 79.049626 -221.258384)
		(width 0.14478)
		(layer "In11.Cu")
		(net "M_F_CPU1_SA_DQ<2>")
	)
	(segment
		(start 56.936132 -198.610474)
		(end 57.78627 -197.760336)
		(width 0.14478)
		(layer "In11.Cu")
		(net "M_F_CPU1_SA_DQ<2>")
	)
	(segment
		(start 31.393892 -198.610474)
		(end 34.35858 -198.610474)
		(width 0.14478)
		(layer "In11.Cu")
		(net "M_F_CPU1_SA_DQ<2>")
	)
	(segment
		(start 83.289648 -225.527108)
		(end 83.29803 -225.531934)
		(width 0.0889)
		(layer "In11.Cu")
		(net "M_F_CPU1_SA_DQ<2>")
	)
	(segment
		(start 79.049626 -221.416372)
		(end 79.25562 -221.622366)
		(width 0.0889)
		(layer "In11.Cu")
		(net "M_F_CPU1_SA_DQ<2>")
	)
	(segment
		(start 59.798458 -197.760336)
		(end 76.585826 -214.547704)
		(width 0.14478)
		(layer "In11.Cu")
		(net "M_F_CPU1_SA_DQ<2>")
	)
	(segment
		(start 80.4418 -223.89084)
		(end 80.478122 -223.911922)
		(width 0.0889)
		(layer "In11.Cu")
		(net "M_F_CPU1_SA_DQ<2>")
	)
	(segment
		(start 18.79473 -197.939152)
		(end 18.957798 -197.776084)
		(width 0.14478)
		(layer "In11.Cu")
		(net "M_F_CPU1_SA_DQ<2>")
	)
	(segment
		(start 80.509872 -224.538794)
		(end 80.478122 -224.557082)
		(width 0.0889)
		(layer "In11.Cu")
		(net "M_F_CPU1_SA_DQ<2>")
	)
	(segment
		(start 80.478122 -224.557082)
		(end 80.439006 -224.579942)
		(width 0.0889)
		(layer "In11.Cu")
		(net "M_F_CPU1_SA_DQ<2>")
	)
	(segment
		(start 19.351244 -198.447406)
		(end 19.514312 -198.610474)
		(width 0.14478)
		(layer "In11.Cu")
		(net "M_F_CPU1_SA_DQ<2>")
	)
	(segment
		(start 76.585826 -214.547704)
		(end 76.585826 -218.616784)
		(width 0.14478)
		(layer "In11.Cu")
		(net "M_F_CPU1_SA_DQ<2>")
	)
	(segment
		(start 84.205064 -225.589084)
		(end 84.05114 -225.854514)
		(width 0.0889)
		(layer "In11.Cu")
		(net "M_F_CPU1_SA_DQ<2>")
	)
	(segment
		(start 80.478122 -223.911922)
		(end 80.509872 -223.93021)
		(width 0.0889)
		(layer "In11.Cu")
		(net "M_F_CPU1_SA_DQ<2>")
	)
	(segment
		(start 80.439006 -225.509074)
		(end 80.478122 -225.531934)
		(width 0.0889)
		(layer "In11.Cu")
		(net "M_F_CPU1_SA_DQ<2>")
	)
	(segment
		(start 84.182712 -225.505772)
		(end 84.205064 -225.589084)
		(width 0.0889)
		(layer "In11.Cu")
		(net "M_F_CPU1_SA_DQ<2>")
	)
	(segment
		(start 35.208718 -197.760336)
		(end 38.113208 -197.760336)
		(width 0.14478)
		(layer "In11.Cu")
		(net "M_F_CPU1_SA_DQ<2>")
	)
	(segment
		(start 19.514312 -198.610474)
		(end 26.727658 -198.610474)
		(width 0.14478)
		(layer "In11.Cu")
		(net "M_F_CPU1_SA_DQ<2>")
	)
	(segment
		(start 18.957798 -197.776084)
		(end 19.188176 -197.776084)
		(width 0.14478)
		(layer "In11.Cu")
		(net "M_F_CPU1_SA_DQ<2>")
	)
	(segment
		(start 79.049626 -221.258384)
		(end 79.049626 -221.416372)
		(width 0.0889)
		(layer "In11.Cu")
		(net "M_F_CPU1_SA_DQ<2>")
	)
	(segment
		(start 46.468792 -198.610474)
		(end 49.389792 -198.610474)
		(width 0.14478)
		(layer "In11.Cu")
		(net "M_F_CPU1_SA_DQ<2>")
	)
	(segment
		(start 19.351244 -197.939152)
		(end 19.351244 -198.447406)
		(width 0.14478)
		(layer "In11.Cu")
		(net "M_F_CPU1_SA_DQ<2>")
	)
	(segment
		(start 79.9719 -223.080834)
		(end 80.008222 -223.101916)
		(width 0.0889)
		(layer "In11.Cu")
		(net "M_F_CPU1_SA_DQ<2>")
	)
	(segment
		(start 79.25562 -221.622366)
		(end 79.25562 -221.804484)
		(width 0.0889)
		(layer "In11.Cu")
		(net "M_F_CPU1_SA_DQ<2>")
	)
	(segment
		(start 18.631662 -198.610474)
		(end 18.79473 -198.447406)
		(width 0.14478)
		(layer "In11.Cu")
		(net "M_F_CPU1_SA_DQ<2>")
	)
	(segment
		(start 42.742104 -197.760336)
		(end 45.618654 -197.760336)
		(width 0.14478)
		(layer "In11.Cu")
		(net "M_F_CPU1_SA_DQ<2>")
	)
	(segment
		(start 50.23993 -197.760336)
		(end 53.155088 -197.760336)
		(width 0.14478)
		(layer "In11.Cu")
		(net "M_F_CPU1_SA_DQ<2>")
	)
	(segment
		(start 57.78627 -197.760336)
		(end 59.798458 -197.760336)
		(width 0.14478)
		(layer "In11.Cu")
		(net "M_F_CPU1_SA_DQ<2>")
	)
	(segment
		(start 38.963346 -198.610474)
		(end 41.891966 -198.610474)
		(width 0.14478)
		(layer "In11.Cu")
		(net "M_F_CPU1_SA_DQ<2>")
	)
	(segment
		(start 19.188176 -197.776084)
		(end 19.351244 -197.939152)
		(width 0.14478)
		(layer "In11.Cu")
		(net "M_F_CPU1_SA_DQ<2>")
	)
	(segment
		(start 34.35858 -198.610474)
		(end 35.208718 -197.760336)
		(width 0.14478)
		(layer "In11.Cu")
		(net "M_F_CPU1_SA_DQ<2>")
	)
	(segment
		(start 49.389792 -198.610474)
		(end 50.23993 -197.760336)
		(width 0.14478)
		(layer "In11.Cu")
		(net "M_F_CPU1_SA_DQ<2>")
	)
	(segment
		(start 17.608042 -198.185278)
		(end 18.033238 -198.610474)
		(width 0.14478)
		(layer "In11.Cu")
		(net "M_F_CPU1_SA_DQ<2>")
	)
	(segment
		(start 80.008222 -223.101916)
		(end 80.039972 -223.120204)
		(width 0.0889)
		(layer "In11.Cu")
		(net "M_F_CPU1_SA_DQ<2>")
	)
	(segment
		(start 30.543754 -197.760336)
		(end 31.393892 -198.610474)
		(width 0.14478)
		(layer "In11.Cu")
		(net "M_F_CPU1_SA_DQ<2>")
	)
	(segment
		(start 76.585826 -218.616784)
		(end 79.049626 -221.080584)
		(width 0.14478)
		(layer "In11.Cu")
		(net "M_F_CPU1_SA_DQ<2>")
	)
	(segment
		(start 38.113208 -197.760336)
		(end 38.963346 -198.610474)
		(width 0.14478)
		(layer "In11.Cu")
		(net "M_F_CPU1_SA_DQ<2>")
	)
	(segment
		(start 79.538322 -222.29191)
		(end 79.570072 -222.310198)
		(width 0.0889)
		(layer "In11.Cu")
		(net "M_F_CPU1_SA_DQ<2>")
	)
	(segment
		(start 18.79473 -198.447406)
		(end 18.79473 -197.939152)
		(width 0.14478)
		(layer "In11.Cu")
		(net "M_F_CPU1_SA_DQ<2>")
	)
	(arc
		(start 83.29803 -225.531934)
		(mid 83.580986 -225.608111)
		(end 83.863942 -225.531934)
		(width 0.0889)
		(layer "In11.Cu")
		(net "M_F_CPU1_SA_DQ<2>")
	)
	(arc
		(start 79.726028 -222.61449)
		(mid 79.791264 -222.878081)
		(end 79.9719 -223.080834)
		(width 0.0889)
		(layer "In11.Cu")
		(net "M_F_CPU1_SA_DQ<2>")
	)
	(arc
		(start 79.570072 -222.310198)
		(mid 79.684748 -222.443532)
		(end 79.726028 -222.61449)
		(width 0.0889)
		(layer "In11.Cu")
		(net "M_F_CPU1_SA_DQ<2>")
	)
	(arc
		(start 79.25562 -221.804484)
		(mid 79.319913 -222.066089)
		(end 79.497936 -222.268288)
		(width 0.0889)
		(layer "In11.Cu")
		(net "M_F_CPU1_SA_DQ<2>")
	)
	(arc
		(start 82.923888 -225.531934)
		(mid 83.106139 -225.481584)
		(end 83.289648 -225.527108)
		(width 0.0889)
		(layer "In11.Cu")
		(net "M_F_CPU1_SA_DQ<2>")
	)
	(arc
		(start 80.195928 -223.424496)
		(mid 80.261164 -223.688087)
		(end 80.4418 -223.89084)
		(width 0.0889)
		(layer "In11.Cu")
		(net "M_F_CPU1_SA_DQ<2>")
	)
	(arc
		(start 81.418176 -225.531934)
		(mid 81.701132 -225.608111)
		(end 81.984088 -225.531934)
		(width 0.0889)
		(layer "In11.Cu")
		(net "M_F_CPU1_SA_DQ<2>")
	)
	(arc
		(start 80.478122 -225.531934)
		(mid 80.761078 -225.608111)
		(end 81.044034 -225.531934)
		(width 0.0889)
		(layer "In11.Cu")
		(net "M_F_CPU1_SA_DQ<2>")
	)
	(arc
		(start 81.984088 -225.531934)
		(mid 82.171032 -225.481679)
		(end 82.357976 -225.531934)
		(width 0.0889)
		(layer "In11.Cu")
		(net "M_F_CPU1_SA_DQ<2>")
	)
	(arc
		(start 81.052416 -225.527108)
		(mid 81.235924 -225.481614)
		(end 81.418176 -225.531934)
		(width 0.0889)
		(layer "In11.Cu")
		(net "M_F_CPU1_SA_DQ<2>")
	)
	(arc
		(start 80.039972 -223.120204)
		(mid 80.154648 -223.253538)
		(end 80.195928 -223.424496)
		(width 0.0889)
		(layer "In11.Cu")
		(net "M_F_CPU1_SA_DQ<2>")
	)
	(arc
		(start 80.439006 -224.579942)
		(mid 80.195679 -225.044508)
		(end 80.439006 -225.509074)
		(width 0.0889)
		(layer "In11.Cu")
		(net "M_F_CPU1_SA_DQ<2>")
	)
	(arc
		(start 80.509872 -223.93021)
		(mid 80.6658 -224.234502)
		(end 80.509872 -224.538794)
		(width 0.0889)
		(layer "In11.Cu")
		(net "M_F_CPU1_SA_DQ<2>")
	)
	(arc
		(start 83.863942 -225.531934)
		(mid 84.02038 -225.482963)
		(end 84.182712 -225.505772)
		(width 0.0889)
		(layer "In11.Cu")
		(net "M_F_CPU1_SA_DQ<2>")
	)
	(arc
		(start 82.357976 -225.531934)
		(mid 82.640932 -225.608111)
		(end 82.923888 -225.531934)
		(width 0.0889)
		(layer "In11.Cu")
		(net "M_F_CPU1_SA_DQ<2>")
	)
	(segment
		(start 86.397846 -243.94033)
		(end 85.930994 -243.674392)
		(width 0.10668)
		(layer "F.Cu")
		(net "M_F_CPU1_SA_DQ<29>")
	)
	(segment
		(start 75.955906 -243.066824)
		(end 76.187046 -243.066824)
		(width 0.0889)
		(layer "In11.Cu")
		(net "M_F_CPU1_SA_DQ<29>")
	)
	(segment
		(start 53.961792 -233.46029)
		(end 55.597044 -233.46029)
		(width 0.14478)
		(layer "In11.Cu")
		(net "M_F_CPU1_SA_DQ<29>")
	)
	(segment
		(start 51.293268 -232.773474)
		(end 51.456336 -232.610406)
		(width 0.14478)
		(layer "In11.Cu")
		(net "M_F_CPU1_SA_DQ<29>")
	)
	(segment
		(start 41.615106 -233.46029)
		(end 41.94302 -233.46029)
		(width 0.14478)
		(layer "In11.Cu")
		(net "M_F_CPU1_SA_DQ<29>")
	)
	(segment
		(start 25.705816 -233.683556)
		(end 25.868884 -233.846624)
		(width 0.14478)
		(layer "In11.Cu")
		(net "M_F_CPU1_SA_DQ<29>")
	)
	(segment
		(start 33.839404 -233.691176)
		(end 33.839404 -233.623358)
		(width 0.14478)
		(layer "In11.Cu")
		(net "M_F_CPU1_SA_DQ<29>")
	)
	(segment
		(start 24.04999 -233.854244)
		(end 24.280368 -233.854244)
		(width 0.14478)
		(layer "In11.Cu")
		(net "M_F_CPU1_SA_DQ<29>")
	)
	(segment
		(start 33.839404 -233.623358)
		(end 34.002472 -233.46029)
		(width 0.14478)
		(layer "In11.Cu")
		(net "M_F_CPU1_SA_DQ<29>")
	)
	(segment
		(start 24.606504 -233.46029)
		(end 25.542748 -233.46029)
		(width 0.14478)
		(layer "In11.Cu")
		(net "M_F_CPU1_SA_DQ<29>")
	)
	(segment
		(start 56.148478 -233.857546)
		(end 56.293258 -233.712766)
		(width 0.14478)
		(layer "In11.Cu")
		(net "M_F_CPU1_SA_DQ<29>")
	)
	(segment
		(start 33.28289 -233.691176)
		(end 33.445958 -233.854244)
		(width 0.14478)
		(layer "In11.Cu")
		(net "M_F_CPU1_SA_DQ<29>")
	)
	(segment
		(start 26.81478 -233.46029)
		(end 27.664664 -232.610406)
		(width 0.14478)
		(layer "In11.Cu")
		(net "M_F_CPU1_SA_DQ<29>")
	)
	(segment
		(start 35.69589 -232.837736)
		(end 35.858958 -233.000804)
		(width 0.14478)
		(layer "In11.Cu")
		(net "M_F_CPU1_SA_DQ<29>")
	)
	(segment
		(start 81.044034 -243.996972)
		(end 81.052416 -244.001798)
		(width 0.0889)
		(layer "In11.Cu")
		(net "M_F_CPU1_SA_DQ<29>")
	)
	(segment
		(start 26.26233 -233.623358)
		(end 26.425398 -233.46029)
		(width 0.14478)
		(layer "In11.Cu")
		(net "M_F_CPU1_SA_DQ<29>")
	)
	(segment
		(start 57.396126 -233.712766)
		(end 57.396126 -233.60507)
		(width 0.14478)
		(layer "In11.Cu")
		(net "M_F_CPU1_SA_DQ<29>")
	)
	(segment
		(start 48.448722 -233.683556)
		(end 48.61179 -233.846624)
		(width 0.14478)
		(layer "In11.Cu")
		(net "M_F_CPU1_SA_DQ<29>")
	)
	(segment
		(start 34.002472 -233.46029)
		(end 34.383218 -233.46029)
		(width 0.14478)
		(layer "In11.Cu")
		(net "M_F_CPU1_SA_DQ<29>")
	)
	(segment
		(start 22.773894 -233.623358)
		(end 22.773894 -233.691176)
		(width 0.14478)
		(layer "In11.Cu")
		(net "M_F_CPU1_SA_DQ<29>")
	)
	(segment
		(start 60.96381 -234.769406)
		(end 60.96381 -235.97108)
		(width 0.14478)
		(layer "In11.Cu")
		(net "M_F_CPU1_SA_DQ<29>")
	)
	(segment
		(start 23.330408 -233.229404)
		(end 23.493476 -233.066336)
		(width 0.14478)
		(layer "In11.Cu")
		(net "M_F_CPU1_SA_DQ<29>")
	)
	(segment
		(start 51.456336 -232.610406)
		(end 53.111908 -232.610406)
		(width 0.14478)
		(layer "In11.Cu")
		(net "M_F_CPU1_SA_DQ<29>")
	)
	(segment
		(start 77.911706 -244.047264)
		(end 78.410816 -244.047264)
		(width 0.0889)
		(layer "In11.Cu")
		(net "M_F_CPU1_SA_DQ<29>")
	)
	(segment
		(start 48.61179 -233.846624)
		(end 48.842168 -233.846624)
		(width 0.14478)
		(layer "In11.Cu")
		(net "M_F_CPU1_SA_DQ<29>")
	)
	(segment
		(start 21.70811 -233.035348)
		(end 22.133052 -233.46029)
		(width 0.14478)
		(layer "In11.Cu")
		(net "M_F_CPU1_SA_DQ<29>")
	)
	(segment
		(start 50.899822 -232.993184)
		(end 51.1302 -232.993184)
		(width 0.14478)
		(layer "In11.Cu")
		(net "M_F_CPU1_SA_DQ<29>")
	)
	(segment
		(start 30.470856 -232.610406)
		(end 31.32074 -233.46029)
		(width 0.14478)
		(layer "In11.Cu")
		(net "M_F_CPU1_SA_DQ<29>")
	)
	(segment
		(start 25.705816 -233.623358)
		(end 25.705816 -233.683556)
		(width 0.14478)
		(layer "In11.Cu")
		(net "M_F_CPU1_SA_DQ<29>")
	)
	(segment
		(start 43.382438 -233.000804)
		(end 43.612816 -233.000804)
		(width 0.14478)
		(layer "In11.Cu")
		(net "M_F_CPU1_SA_DQ<29>")
	)
	(segment
		(start 28.814776 -232.610406)
		(end 30.470856 -232.610406)
		(width 0.14478)
		(layer "In11.Cu")
		(net "M_F_CPU1_SA_DQ<29>")
	)
	(segment
		(start 58.643774 -233.46029)
		(end 59.654694 -233.46029)
		(width 0.14478)
		(layer "In11.Cu")
		(net "M_F_CPU1_SA_DQ<29>")
	)
	(segment
		(start 84.229702 -244.001798)
		(end 84.238084 -243.996972)
		(width 0.0889)
		(layer "In11.Cu")
		(net "M_F_CPU1_SA_DQ<29>")
	)
	(segment
		(start 68.059554 -243.066824)
		(end 75.955906 -243.066824)
		(width 0.14478)
		(layer "In11.Cu")
		(net "M_F_CPU1_SA_DQ<29>")
	)
	(segment
		(start 28.651708 -232.830116)
		(end 28.651708 -232.773474)
		(width 0.14478)
		(layer "In11.Cu")
		(net "M_F_CPU1_SA_DQ<29>")
	)
	(segment
		(start 76.187046 -243.066824)
		(end 76.616306 -243.496084)
		(width 0.0889)
		(layer "In11.Cu")
		(net "M_F_CPU1_SA_DQ<29>")
	)
	(segment
		(start 43.21937 -232.773474)
		(end 43.21937 -232.837736)
		(width 0.14478)
		(layer "In11.Cu")
		(net "M_F_CPU1_SA_DQ<29>")
	)
	(segment
		(start 80.093566 -243.990876)
		(end 80.10398 -243.996972)
		(width 0.0889)
		(layer "In11.Cu")
		(net "M_F_CPU1_SA_DQ<29>")
	)
	(segment
		(start 57.251346 -233.857546)
		(end 57.396126 -233.712766)
		(width 0.14478)
		(layer "In11.Cu")
		(net "M_F_CPU1_SA_DQ<29>")
	)
	(segment
		(start 23.886922 -233.229404)
		(end 23.886922 -233.691176)
		(width 0.14478)
		(layer "In11.Cu")
		(net "M_F_CPU1_SA_DQ<29>")
	)
	(segment
		(start 56.699912 -233.46029)
		(end 56.844692 -233.60507)
		(width 0.14478)
		(layer "In11.Cu")
		(net "M_F_CPU1_SA_DQ<29>")
	)
	(segment
		(start 36.252404 -232.773474)
		(end 36.415472 -232.610406)
		(width 0.14478)
		(layer "In11.Cu")
		(net "M_F_CPU1_SA_DQ<29>")
	)
	(segment
		(start 27.932126 -232.610406)
		(end 28.095194 -232.773474)
		(width 0.14478)
		(layer "In11.Cu")
		(net "M_F_CPU1_SA_DQ<29>")
	)
	(segment
		(start 56.293258 -233.60507)
		(end 56.438038 -233.46029)
		(width 0.14478)
		(layer "In11.Cu")
		(net "M_F_CPU1_SA_DQ<29>")
	)
	(segment
		(start 85.681058 -243.965222)
		(end 85.77707 -243.939822)
		(width 0.0889)
		(layer "In11.Cu")
		(net "M_F_CPU1_SA_DQ<29>")
	)
	(segment
		(start 41.058592 -233.854244)
		(end 41.28897 -233.854244)
		(width 0.14478)
		(layer "In11.Cu")
		(net "M_F_CPU1_SA_DQ<29>")
	)
	(segment
		(start 22.133052 -233.46029)
		(end 22.610826 -233.46029)
		(width 0.14478)
		(layer "In11.Cu")
		(net "M_F_CPU1_SA_DQ<29>")
	)
	(segment
		(start 43.775884 -232.773474)
		(end 43.938952 -232.610406)
		(width 0.14478)
		(layer "In11.Cu")
		(net "M_F_CPU1_SA_DQ<29>")
	)
	(segment
		(start 78.410816 -244.047264)
		(end 78.41107 -244.04701)
		(width 0.0889)
		(layer "In11.Cu")
		(net "M_F_CPU1_SA_DQ<29>")
	)
	(segment
		(start 33.28289 -233.623358)
		(end 33.28289 -233.691176)
		(width 0.14478)
		(layer "In11.Cu")
		(net "M_F_CPU1_SA_DQ<29>")
	)
	(segment
		(start 36.089336 -233.000804)
		(end 36.252404 -232.837736)
		(width 0.14478)
		(layer "In11.Cu")
		(net "M_F_CPU1_SA_DQ<29>")
	)
	(segment
		(start 40.895524 -233.623358)
		(end 40.895524 -233.691176)
		(width 0.14478)
		(layer "In11.Cu")
		(net "M_F_CPU1_SA_DQ<29>")
	)
	(segment
		(start 49.005236 -233.623358)
		(end 49.168304 -233.46029)
		(width 0.14478)
		(layer "In11.Cu")
		(net "M_F_CPU1_SA_DQ<29>")
	)
	(segment
		(start 57.80278 -233.46029)
		(end 57.94756 -233.60507)
		(width 0.14478)
		(layer "In11.Cu")
		(net "M_F_CPU1_SA_DQ<29>")
	)
	(segment
		(start 43.21937 -232.837736)
		(end 43.382438 -233.000804)
		(width 0.14478)
		(layer "In11.Cu")
		(net "M_F_CPU1_SA_DQ<29>")
	)
	(segment
		(start 51.293268 -232.830116)
		(end 51.293268 -232.773474)
		(width 0.14478)
		(layer "In11.Cu")
		(net "M_F_CPU1_SA_DQ<29>")
	)
	(segment
		(start 49.005236 -233.683556)
		(end 49.005236 -233.623358)
		(width 0.14478)
		(layer "In11.Cu")
		(net "M_F_CPU1_SA_DQ<29>")
	)
	(segment
		(start 41.28897 -233.854244)
		(end 41.452038 -233.691176)
		(width 0.14478)
		(layer "In11.Cu")
		(net "M_F_CPU1_SA_DQ<29>")
	)
	(segment
		(start 55.741824 -233.60507)
		(end 55.741824 -233.712766)
		(width 0.14478)
		(layer "In11.Cu")
		(net "M_F_CPU1_SA_DQ<29>")
	)
	(segment
		(start 33.445958 -233.854244)
		(end 33.676336 -233.854244)
		(width 0.14478)
		(layer "In11.Cu")
		(net "M_F_CPU1_SA_DQ<29>")
	)
	(segment
		(start 56.293258 -233.712766)
		(end 56.293258 -233.60507)
		(width 0.14478)
		(layer "In11.Cu")
		(net "M_F_CPU1_SA_DQ<29>")
	)
	(segment
		(start 58.09234 -233.857546)
		(end 58.354214 -233.857546)
		(width 0.14478)
		(layer "In11.Cu")
		(net "M_F_CPU1_SA_DQ<29>")
	)
	(segment
		(start 77.360526 -243.496084)
		(end 77.911706 -244.047264)
		(width 0.0889)
		(layer "In11.Cu")
		(net "M_F_CPU1_SA_DQ<29>")
	)
	(segment
		(start 23.493476 -233.066336)
		(end 23.723854 -233.066336)
		(width 0.14478)
		(layer "In11.Cu")
		(net "M_F_CPU1_SA_DQ<29>")
	)
	(segment
		(start 48.448722 -233.623358)
		(end 48.448722 -233.683556)
		(width 0.14478)
		(layer "In11.Cu")
		(net "M_F_CPU1_SA_DQ<29>")
	)
	(segment
		(start 35.858958 -233.000804)
		(end 36.089336 -233.000804)
		(width 0.14478)
		(layer "In11.Cu")
		(net "M_F_CPU1_SA_DQ<29>")
	)
	(segment
		(start 35.532822 -232.610406)
		(end 35.69589 -232.773474)
		(width 0.14478)
		(layer "In11.Cu")
		(net "M_F_CPU1_SA_DQ<29>")
	)
	(segment
		(start 28.48864 -232.993184)
		(end 28.651708 -232.830116)
		(width 0.14478)
		(layer "In11.Cu")
		(net "M_F_CPU1_SA_DQ<29>")
	)
	(segment
		(start 45.567854 -232.610406)
		(end 46.417738 -233.46029)
		(width 0.14478)
		(layer "In11.Cu")
		(net "M_F_CPU1_SA_DQ<29>")
	)
	(segment
		(start 24.280368 -233.854244)
		(end 24.443436 -233.691176)
		(width 0.14478)
		(layer "In11.Cu")
		(net "M_F_CPU1_SA_DQ<29>")
	)
	(segment
		(start 80.46974 -244.001798)
		(end 80.478122 -243.996972)
		(width 0.0889)
		(layer "In11.Cu")
		(net "M_F_CPU1_SA_DQ<29>")
	)
	(segment
		(start 51.1302 -232.993184)
		(end 51.293268 -232.830116)
		(width 0.14478)
		(layer "In11.Cu")
		(net "M_F_CPU1_SA_DQ<29>")
	)
	(segment
		(start 48.842168 -233.846624)
		(end 49.005236 -233.683556)
		(width 0.14478)
		(layer "In11.Cu")
		(net "M_F_CPU1_SA_DQ<29>")
	)
	(segment
		(start 23.330408 -233.691176)
		(end 23.330408 -233.229404)
		(width 0.14478)
		(layer "In11.Cu")
		(net "M_F_CPU1_SA_DQ<29>")
	)
	(segment
		(start 37.95268 -232.610406)
		(end 38.802564 -233.46029)
		(width 0.14478)
		(layer "In11.Cu")
		(net "M_F_CPU1_SA_DQ<29>")
	)
	(segment
		(start 24.443436 -233.691176)
		(end 24.443436 -233.623358)
		(width 0.14478)
		(layer "In11.Cu")
		(net "M_F_CPU1_SA_DQ<29>")
	)
	(segment
		(start 24.443436 -233.623358)
		(end 24.606504 -233.46029)
		(width 0.14478)
		(layer "In11.Cu")
		(net "M_F_CPU1_SA_DQ<29>")
	)
	(segment
		(start 84.803996 -243.996972)
		(end 84.812378 -244.001798)
		(width 0.0889)
		(layer "In11.Cu")
		(net "M_F_CPU1_SA_DQ<29>")
	)
	(segment
		(start 55.886604 -233.857546)
		(end 56.148478 -233.857546)
		(width 0.14478)
		(layer "In11.Cu")
		(net "M_F_CPU1_SA_DQ<29>")
	)
	(segment
		(start 56.989472 -233.857546)
		(end 57.251346 -233.857546)
		(width 0.14478)
		(layer "In11.Cu")
		(net "M_F_CPU1_SA_DQ<29>")
	)
	(segment
		(start 58.498994 -233.712766)
		(end 58.498994 -233.60507)
		(width 0.14478)
		(layer "In11.Cu")
		(net "M_F_CPU1_SA_DQ<29>")
	)
	(segment
		(start 23.723854 -233.066336)
		(end 23.886922 -233.229404)
		(width 0.14478)
		(layer "In11.Cu")
		(net "M_F_CPU1_SA_DQ<29>")
	)
	(segment
		(start 49.448974 -233.46029)
		(end 50.298858 -232.610406)
		(width 0.14478)
		(layer "In11.Cu")
		(net "M_F_CPU1_SA_DQ<29>")
	)
	(segment
		(start 85.77707 -243.939822)
		(end 85.930994 -243.674392)
		(width 0.0889)
		(layer "In11.Cu")
		(net "M_F_CPU1_SA_DQ<29>")
	)
	(segment
		(start 59.654694 -233.46029)
		(end 60.96381 -234.769406)
		(width 0.14478)
		(layer "In11.Cu")
		(net "M_F_CPU1_SA_DQ<29>")
	)
	(segment
		(start 41.94302 -233.46029)
		(end 42.792904 -232.610406)
		(width 0.14478)
		(layer "In11.Cu")
		(net "M_F_CPU1_SA_DQ<29>")
	)
	(segment
		(start 36.252404 -232.837736)
		(end 36.252404 -232.773474)
		(width 0.14478)
		(layer "In11.Cu")
		(net "M_F_CPU1_SA_DQ<29>")
	)
	(segment
		(start 83.289648 -244.001798)
		(end 83.29803 -243.996972)
		(width 0.0889)
		(layer "In11.Cu")
		(net "M_F_CPU1_SA_DQ<29>")
	)
	(segment
		(start 48.285654 -233.46029)
		(end 48.448722 -233.623358)
		(width 0.14478)
		(layer "In11.Cu")
		(net "M_F_CPU1_SA_DQ<29>")
	)
	(segment
		(start 26.099262 -233.846624)
		(end 26.26233 -233.683556)
		(width 0.14478)
		(layer "In11.Cu")
		(net "M_F_CPU1_SA_DQ<29>")
	)
	(segment
		(start 23.16734 -233.854244)
		(end 23.330408 -233.691176)
		(width 0.14478)
		(layer "In11.Cu")
		(net "M_F_CPU1_SA_DQ<29>")
	)
	(segment
		(start 53.111908 -232.610406)
		(end 53.961792 -233.46029)
		(width 0.14478)
		(layer "In11.Cu")
		(net "M_F_CPU1_SA_DQ<29>")
	)
	(segment
		(start 26.425398 -233.46029)
		(end 26.81478 -233.46029)
		(width 0.14478)
		(layer "In11.Cu")
		(net "M_F_CPU1_SA_DQ<29>")
	)
	(segment
		(start 22.610826 -233.46029)
		(end 22.773894 -233.623358)
		(width 0.14478)
		(layer "In11.Cu")
		(net "M_F_CPU1_SA_DQ<29>")
	)
	(segment
		(start 50.573686 -232.610406)
		(end 50.736754 -232.773474)
		(width 0.14478)
		(layer "In11.Cu")
		(net "M_F_CPU1_SA_DQ<29>")
	)
	(segment
		(start 60.96381 -235.97108)
		(end 68.059554 -243.066824)
		(width 0.14478)
		(layer "In11.Cu")
		(net "M_F_CPU1_SA_DQ<29>")
	)
	(segment
		(start 38.802564 -233.46029)
		(end 40.732456 -233.46029)
		(width 0.14478)
		(layer "In11.Cu")
		(net "M_F_CPU1_SA_DQ<29>")
	)
	(segment
		(start 35.233102 -232.610406)
		(end 35.532822 -232.610406)
		(width 0.14478)
		(layer "In11.Cu")
		(net "M_F_CPU1_SA_DQ<29>")
	)
	(segment
		(start 57.540906 -233.46029)
		(end 57.80278 -233.46029)
		(width 0.14478)
		(layer "In11.Cu")
		(net "M_F_CPU1_SA_DQ<29>")
	)
	(segment
		(start 56.844692 -233.60507)
		(end 56.844692 -233.712766)
		(width 0.14478)
		(layer "In11.Cu")
		(net "M_F_CPU1_SA_DQ<29>")
	)
	(segment
		(start 28.258262 -232.993184)
		(end 28.48864 -232.993184)
		(width 0.14478)
		(layer "In11.Cu")
		(net "M_F_CPU1_SA_DQ<29>")
	)
	(segment
		(start 58.354214 -233.857546)
		(end 58.498994 -233.712766)
		(width 0.14478)
		(layer "In11.Cu")
		(net "M_F_CPU1_SA_DQ<29>")
	)
	(segment
		(start 40.895524 -233.691176)
		(end 41.058592 -233.854244)
		(width 0.14478)
		(layer "In11.Cu")
		(net "M_F_CPU1_SA_DQ<29>")
	)
	(segment
		(start 50.736754 -232.773474)
		(end 50.736754 -232.830116)
		(width 0.14478)
		(layer "In11.Cu")
		(net "M_F_CPU1_SA_DQ<29>")
	)
	(segment
		(start 42.792904 -232.610406)
		(end 43.056302 -232.610406)
		(width 0.14478)
		(layer "In11.Cu")
		(net "M_F_CPU1_SA_DQ<29>")
	)
	(segment
		(start 43.612816 -233.000804)
		(end 43.775884 -232.837736)
		(width 0.14478)
		(layer "In11.Cu")
		(net "M_F_CPU1_SA_DQ<29>")
	)
	(segment
		(start 43.056302 -232.610406)
		(end 43.21937 -232.773474)
		(width 0.14478)
		(layer "In11.Cu")
		(net "M_F_CPU1_SA_DQ<29>")
	)
	(segment
		(start 25.542748 -233.46029)
		(end 25.705816 -233.623358)
		(width 0.14478)
		(layer "In11.Cu")
		(net "M_F_CPU1_SA_DQ<29>")
	)
	(segment
		(start 40.732456 -233.46029)
		(end 40.895524 -233.623358)
		(width 0.14478)
		(layer "In11.Cu")
		(net "M_F_CPU1_SA_DQ<29>")
	)
	(segment
		(start 22.773894 -233.691176)
		(end 22.936962 -233.854244)
		(width 0.14478)
		(layer "In11.Cu")
		(net "M_F_CPU1_SA_DQ<29>")
	)
	(segment
		(start 22.936962 -233.854244)
		(end 23.16734 -233.854244)
		(width 0.14478)
		(layer "In11.Cu")
		(net "M_F_CPU1_SA_DQ<29>")
	)
	(segment
		(start 58.498994 -233.60507)
		(end 58.643774 -233.46029)
		(width 0.14478)
		(layer "In11.Cu")
		(net "M_F_CPU1_SA_DQ<29>")
	)
	(segment
		(start 46.417738 -233.46029)
		(end 48.285654 -233.46029)
		(width 0.14478)
		(layer "In11.Cu")
		(net "M_F_CPU1_SA_DQ<29>")
	)
	(segment
		(start 57.94756 -233.60507)
		(end 57.94756 -233.712766)
		(width 0.14478)
		(layer "In11.Cu")
		(net "M_F_CPU1_SA_DQ<29>")
	)
	(segment
		(start 41.452038 -233.623358)
		(end 41.615106 -233.46029)
		(width 0.14478)
		(layer "In11.Cu")
		(net "M_F_CPU1_SA_DQ<29>")
	)
	(segment
		(start 50.736754 -232.830116)
		(end 50.899822 -232.993184)
		(width 0.14478)
		(layer "In11.Cu")
		(net "M_F_CPU1_SA_DQ<29>")
	)
	(segment
		(start 33.119822 -233.46029)
		(end 33.28289 -233.623358)
		(width 0.14478)
		(layer "In11.Cu")
		(net "M_F_CPU1_SA_DQ<29>")
	)
	(segment
		(start 56.844692 -233.712766)
		(end 56.989472 -233.857546)
		(width 0.14478)
		(layer "In11.Cu")
		(net "M_F_CPU1_SA_DQ<29>")
	)
	(segment
		(start 36.415472 -232.610406)
		(end 37.95268 -232.610406)
		(width 0.14478)
		(layer "In11.Cu")
		(net "M_F_CPU1_SA_DQ<29>")
	)
	(segment
		(start 33.676336 -233.854244)
		(end 33.839404 -233.691176)
		(width 0.14478)
		(layer "In11.Cu")
		(net "M_F_CPU1_SA_DQ<29>")
	)
	(segment
		(start 26.26233 -233.683556)
		(end 26.26233 -233.623358)
		(width 0.14478)
		(layer "In11.Cu")
		(net "M_F_CPU1_SA_DQ<29>")
	)
	(segment
		(start 57.94756 -233.712766)
		(end 58.09234 -233.857546)
		(width 0.14478)
		(layer "In11.Cu")
		(net "M_F_CPU1_SA_DQ<29>")
	)
	(segment
		(start 50.298858 -232.610406)
		(end 50.573686 -232.610406)
		(width 0.14478)
		(layer "In11.Cu")
		(net "M_F_CPU1_SA_DQ<29>")
	)
	(segment
		(start 28.095194 -232.830116)
		(end 28.258262 -232.993184)
		(width 0.14478)
		(layer "In11.Cu")
		(net "M_F_CPU1_SA_DQ<29>")
	)
	(segment
		(start 25.868884 -233.846624)
		(end 26.099262 -233.846624)
		(width 0.14478)
		(layer "In11.Cu")
		(net "M_F_CPU1_SA_DQ<29>")
	)
	(segment
		(start 76.616306 -243.496084)
		(end 77.360526 -243.496084)
		(width 0.0889)
		(layer "In11.Cu")
		(net "M_F_CPU1_SA_DQ<29>")
	)
	(segment
		(start 57.396126 -233.60507)
		(end 57.540906 -233.46029)
		(width 0.14478)
		(layer "In11.Cu")
		(net "M_F_CPU1_SA_DQ<29>")
	)
	(segment
		(start 28.095194 -232.773474)
		(end 28.095194 -232.830116)
		(width 0.14478)
		(layer "In11.Cu")
		(net "M_F_CPU1_SA_DQ<29>")
	)
	(segment
		(start 31.32074 -233.46029)
		(end 33.119822 -233.46029)
		(width 0.14478)
		(layer "In11.Cu")
		(net "M_F_CPU1_SA_DQ<29>")
	)
	(segment
		(start 23.886922 -233.691176)
		(end 24.04999 -233.854244)
		(width 0.14478)
		(layer "In11.Cu")
		(net "M_F_CPU1_SA_DQ<29>")
	)
	(segment
		(start 41.452038 -233.691176)
		(end 41.452038 -233.623358)
		(width 0.14478)
		(layer "In11.Cu")
		(net "M_F_CPU1_SA_DQ<29>")
	)
	(segment
		(start 49.168304 -233.46029)
		(end 49.448974 -233.46029)
		(width 0.14478)
		(layer "In11.Cu")
		(net "M_F_CPU1_SA_DQ<29>")
	)
	(segment
		(start 27.664664 -232.610406)
		(end 27.932126 -232.610406)
		(width 0.14478)
		(layer "In11.Cu")
		(net "M_F_CPU1_SA_DQ<29>")
	)
	(segment
		(start 55.597044 -233.46029)
		(end 55.741824 -233.60507)
		(width 0.14478)
		(layer "In11.Cu")
		(net "M_F_CPU1_SA_DQ<29>")
	)
	(segment
		(start 56.438038 -233.46029)
		(end 56.699912 -233.46029)
		(width 0.14478)
		(layer "In11.Cu")
		(net "M_F_CPU1_SA_DQ<29>")
	)
	(segment
		(start 78.59776 -243.996972)
		(end 78.608174 -243.990876)
		(width 0.0889)
		(layer "In11.Cu")
		(net "M_F_CPU1_SA_DQ<29>")
	)
	(segment
		(start 43.938952 -232.610406)
		(end 45.567854 -232.610406)
		(width 0.14478)
		(layer "In11.Cu")
		(net "M_F_CPU1_SA_DQ<29>")
	)
	(segment
		(start 55.741824 -233.712766)
		(end 55.886604 -233.857546)
		(width 0.14478)
		(layer "In11.Cu")
		(net "M_F_CPU1_SA_DQ<29>")
	)
	(segment
		(start 34.383218 -233.46029)
		(end 35.233102 -232.610406)
		(width 0.14478)
		(layer "In11.Cu")
		(net "M_F_CPU1_SA_DQ<29>")
	)
	(segment
		(start 43.775884 -232.837736)
		(end 43.775884 -232.773474)
		(width 0.14478)
		(layer "In11.Cu")
		(net "M_F_CPU1_SA_DQ<29>")
	)
	(segment
		(start 28.651708 -232.773474)
		(end 28.814776 -232.610406)
		(width 0.14478)
		(layer "In11.Cu")
		(net "M_F_CPU1_SA_DQ<29>")
	)
	(segment
		(start 35.69589 -232.773474)
		(end 35.69589 -232.837736)
		(width 0.14478)
		(layer "In11.Cu")
		(net "M_F_CPU1_SA_DQ<29>")
	)
	(arc
		(start 82.923888 -243.996972)
		(mid 83.106139 -244.047322)
		(end 83.289648 -244.001798)
		(width 0.0889)
		(layer "In11.Cu")
		(net "M_F_CPU1_SA_DQ<29>")
	)
	(arc
		(start 78.41107 -244.04701)
		(mid 78.507723 -244.034325)
		(end 78.59776 -243.996972)
		(width 0.0889)
		(layer "In11.Cu")
		(net "M_F_CPU1_SA_DQ<29>")
	)
	(arc
		(start 78.608174 -243.990876)
		(mid 78.886606 -243.920778)
		(end 79.163418 -243.996972)
		(width 0.0889)
		(layer "In11.Cu")
		(net "M_F_CPU1_SA_DQ<29>")
	)
	(arc
		(start 81.984088 -243.996972)
		(mid 82.171032 -244.047227)
		(end 82.357976 -243.996972)
		(width 0.0889)
		(layer "In11.Cu")
		(net "M_F_CPU1_SA_DQ<29>")
	)
	(arc
		(start 80.478122 -243.996972)
		(mid 80.761078 -243.920795)
		(end 81.044034 -243.996972)
		(width 0.0889)
		(layer "In11.Cu")
		(net "M_F_CPU1_SA_DQ<29>")
	)
	(arc
		(start 79.537814 -243.996972)
		(mid 79.814881 -243.920701)
		(end 80.093566 -243.990876)
		(width 0.0889)
		(layer "In11.Cu")
		(net "M_F_CPU1_SA_DQ<29>")
	)
	(arc
		(start 81.418176 -243.996972)
		(mid 81.701132 -243.920795)
		(end 81.984088 -243.996972)
		(width 0.0889)
		(layer "In11.Cu")
		(net "M_F_CPU1_SA_DQ<29>")
	)
	(arc
		(start 83.29803 -243.996972)
		(mid 83.580986 -243.920795)
		(end 83.863942 -243.996972)
		(width 0.0889)
		(layer "In11.Cu")
		(net "M_F_CPU1_SA_DQ<29>")
	)
	(arc
		(start 84.238084 -243.996972)
		(mid 84.52104 -243.920795)
		(end 84.803996 -243.996972)
		(width 0.0889)
		(layer "In11.Cu")
		(net "M_F_CPU1_SA_DQ<29>")
	)
	(arc
		(start 81.052416 -244.001798)
		(mid 81.235924 -244.047292)
		(end 81.418176 -243.996972)
		(width 0.0889)
		(layer "In11.Cu")
		(net "M_F_CPU1_SA_DQ<29>")
	)
	(arc
		(start 80.10398 -243.996972)
		(mid 80.286231 -244.047322)
		(end 80.46974 -244.001798)
		(width 0.0889)
		(layer "In11.Cu")
		(net "M_F_CPU1_SA_DQ<29>")
	)
	(arc
		(start 84.812378 -244.001798)
		(mid 84.995886 -244.047292)
		(end 85.178138 -243.996972)
		(width 0.0889)
		(layer "In11.Cu")
		(net "M_F_CPU1_SA_DQ<29>")
	)
	(arc
		(start 85.178138 -243.996972)
		(mid 85.425851 -243.921752)
		(end 85.681058 -243.965222)
		(width 0.0889)
		(layer "In11.Cu")
		(net "M_F_CPU1_SA_DQ<29>")
	)
	(arc
		(start 79.163418 -243.996972)
		(mid 79.350616 -244.047354)
		(end 79.537814 -243.996972)
		(width 0.0889)
		(layer "In11.Cu")
		(net "M_F_CPU1_SA_DQ<29>")
	)
	(arc
		(start 82.357976 -243.996972)
		(mid 82.640932 -243.920795)
		(end 82.923888 -243.996972)
		(width 0.0889)
		(layer "In11.Cu")
		(net "M_F_CPU1_SA_DQ<29>")
	)
	(arc
		(start 83.863942 -243.996972)
		(mid 84.046193 -244.047322)
		(end 84.229702 -244.001798)
		(width 0.0889)
		(layer "In11.Cu")
		(net "M_F_CPU1_SA_DQ<29>")
	)
	(segment
		(start 84.987892 -243.130324)
		(end 84.52104 -242.864386)
		(width 0.10668)
		(layer "F.Cu")
		(net "M_F_CPU1_SA_DQ<28>")
	)
	(segment
		(start 51.136296 -231.296718)
		(end 51.299364 -231.13365)
		(width 0.14478)
		(layer "In11.Cu")
		(net "M_F_CPU1_SA_DQ<28>")
	)
	(segment
		(start 58.749692 -231.365806)
		(end 59.317128 -231.365806)
		(width 0.14478)
		(layer "In11.Cu")
		(net "M_F_CPU1_SA_DQ<28>")
	)
	(segment
		(start 46.42739 -231.76992)
		(end 48.343058 -231.76992)
		(width 0.14478)
		(layer "In11.Cu")
		(net "M_F_CPU1_SA_DQ<28>")
	)
	(segment
		(start 84.367116 -243.129816)
		(end 84.52104 -242.864386)
		(width 0.0889)
		(layer "In11.Cu")
		(net "M_F_CPU1_SA_DQ<28>")
	)
	(segment
		(start 55.233062 -231.647492)
		(end 55.39613 -231.484424)
		(width 0.14478)
		(layer "In11.Cu")
		(net "M_F_CPU1_SA_DQ<28>")
	)
	(segment
		(start 41.207944 -232.152698)
		(end 41.438322 -232.152698)
		(width 0.14478)
		(layer "In11.Cu")
		(net "M_F_CPU1_SA_DQ<28>")
	)
	(segment
		(start 54.676548 -231.923336)
		(end 54.676548 -231.981756)
		(width 0.14478)
		(layer "In11.Cu")
		(net "M_F_CPU1_SA_DQ<28>")
	)
	(segment
		(start 34.223198 -231.760268)
		(end 34.383218 -231.760268)
		(width 0.14478)
		(layer "In11.Cu")
		(net "M_F_CPU1_SA_DQ<28>")
	)
	(segment
		(start 54.51348 -231.760268)
		(end 54.676548 -231.923336)
		(width 0.14478)
		(layer "In11.Cu")
		(net "M_F_CPU1_SA_DQ<28>")
	)
	(segment
		(start 77.721714 -243.110766)
		(end 78.41107 -243.110512)
		(width 0.0889)
		(layer "In11.Cu")
		(net "M_F_CPU1_SA_DQ<28>")
	)
	(segment
		(start 43.752008 -231.13365)
		(end 43.752008 -231.073452)
		(width 0.14478)
		(layer "In11.Cu")
		(net "M_F_CPU1_SA_DQ<28>")
	)
	(segment
		(start 22.839172 -231.030018)
		(end 23.00224 -231.193086)
		(width 0.14478)
		(layer "In11.Cu")
		(net "M_F_CPU1_SA_DQ<28>")
	)
	(segment
		(start 43.032426 -230.910384)
		(end 43.195494 -231.073452)
		(width 0.14478)
		(layer "In11.Cu")
		(net "M_F_CPU1_SA_DQ<28>")
	)
	(segment
		(start 24.571706 -231.76992)
		(end 26.805128 -231.76992)
		(width 0.14478)
		(layer "In11.Cu")
		(net "M_F_CPU1_SA_DQ<28>")
	)
	(segment
		(start 41.044876 -231.923336)
		(end 41.044876 -231.98963)
		(width 0.14478)
		(layer "In11.Cu")
		(net "M_F_CPU1_SA_DQ<28>")
	)
	(segment
		(start 61.869066 -235.59008)
		(end 68.43649 -242.157504)
		(width 0.14478)
		(layer "In11.Cu")
		(net "M_F_CPU1_SA_DQ<28>")
	)
	(segment
		(start 43.58894 -231.296718)
		(end 43.752008 -231.13365)
		(width 0.14478)
		(layer "In11.Cu")
		(net "M_F_CPU1_SA_DQ<28>")
	)
	(segment
		(start 41.94302 -231.760268)
		(end 42.792904 -230.910384)
		(width 0.14478)
		(layer "In11.Cu")
		(net "M_F_CPU1_SA_DQ<28>")
	)
	(segment
		(start 41.60139 -231.923336)
		(end 41.764458 -231.760268)
		(width 0.14478)
		(layer "In11.Cu")
		(net "M_F_CPU1_SA_DQ<28>")
	)
	(segment
		(start 58.604912 -231.916986)
		(end 58.604912 -231.510586)
		(width 0.14478)
		(layer "In11.Cu")
		(net "M_F_CPU1_SA_DQ<28>")
	)
	(segment
		(start 33.666684 -232.152698)
		(end 33.897062 -232.152698)
		(width 0.14478)
		(layer "In11.Cu")
		(net "M_F_CPU1_SA_DQ<28>")
	)
	(segment
		(start 48.88992 -232.152698)
		(end 49.052988 -231.98963)
		(width 0.14478)
		(layer "In11.Cu")
		(net "M_F_CPU1_SA_DQ<28>")
	)
	(segment
		(start 42.792904 -230.910384)
		(end 43.032426 -230.910384)
		(width 0.14478)
		(layer "In11.Cu")
		(net "M_F_CPU1_SA_DQ<28>")
	)
	(segment
		(start 51.299364 -231.073452)
		(end 51.45278 -230.920036)
		(width 0.14478)
		(layer "In11.Cu")
		(net "M_F_CPU1_SA_DQ<28>")
	)
	(segment
		(start 55.233062 -231.981756)
		(end 55.233062 -231.647492)
		(width 0.14478)
		(layer "In11.Cu")
		(net "M_F_CPU1_SA_DQ<28>")
	)
	(segment
		(start 58.604912 -231.510586)
		(end 58.749692 -231.365806)
		(width 0.14478)
		(layer "In11.Cu")
		(net "M_F_CPU1_SA_DQ<28>")
	)
	(segment
		(start 49.448974 -231.760268)
		(end 50.298858 -230.910384)
		(width 0.14478)
		(layer "In11.Cu")
		(net "M_F_CPU1_SA_DQ<28>")
	)
	(segment
		(start 22.445726 -231.193086)
		(end 22.608794 -231.030018)
		(width 0.14478)
		(layer "In11.Cu")
		(net "M_F_CPU1_SA_DQ<28>")
	)
	(segment
		(start 56.954674 -231.760268)
		(end 57.349136 -231.365806)
		(width 0.14478)
		(layer "In11.Cu")
		(net "M_F_CPU1_SA_DQ<28>")
	)
	(segment
		(start 43.195494 -231.13365)
		(end 43.358562 -231.296718)
		(width 0.14478)
		(layer "In11.Cu")
		(net "M_F_CPU1_SA_DQ<28>")
	)
	(segment
		(start 35.61842 -231.14127)
		(end 35.781488 -231.304338)
		(width 0.14478)
		(layer "In11.Cu")
		(net "M_F_CPU1_SA_DQ<28>")
	)
	(segment
		(start 30.480508 -230.920036)
		(end 31.330392 -231.76992)
		(width 0.14478)
		(layer "In11.Cu")
		(net "M_F_CPU1_SA_DQ<28>")
	)
	(segment
		(start 49.216056 -231.760268)
		(end 49.448974 -231.760268)
		(width 0.14478)
		(layer "In11.Cu")
		(net "M_F_CPU1_SA_DQ<28>")
	)
	(segment
		(start 50.579782 -230.910384)
		(end 50.74285 -231.073452)
		(width 0.14478)
		(layer "In11.Cu")
		(net "M_F_CPU1_SA_DQ<28>")
	)
	(segment
		(start 51.45278 -230.920036)
		(end 53.12156 -230.920036)
		(width 0.14478)
		(layer "In11.Cu")
		(net "M_F_CPU1_SA_DQ<28>")
	)
	(segment
		(start 23.00224 -231.5972)
		(end 23.165308 -231.760268)
		(width 0.14478)
		(layer "In11.Cu")
		(net "M_F_CPU1_SA_DQ<28>")
	)
	(segment
		(start 26.805128 -231.76992)
		(end 27.664664 -230.910384)
		(width 0.14478)
		(layer "In11.Cu")
		(net "M_F_CPU1_SA_DQ<28>")
	)
	(segment
		(start 24.024844 -232.152698)
		(end 24.255222 -232.152698)
		(width 0.14478)
		(layer "In11.Cu")
		(net "M_F_CPU1_SA_DQ<28>")
	)
	(segment
		(start 79.634334 -243.186712)
		(end 79.65059 -243.19611)
		(width 0.0889)
		(layer "In11.Cu")
		(net "M_F_CPU1_SA_DQ<28>")
	)
	(segment
		(start 55.069994 -232.144824)
		(end 55.233062 -231.981756)
		(width 0.14478)
		(layer "In11.Cu")
		(net "M_F_CPU1_SA_DQ<28>")
	)
	(segment
		(start 45.577506 -230.920036)
		(end 46.42739 -231.76992)
		(width 0.14478)
		(layer "In11.Cu")
		(net "M_F_CPU1_SA_DQ<28>")
	)
	(segment
		(start 56.34609 -231.981756)
		(end 56.34609 -231.923336)
		(width 0.14478)
		(layer "In11.Cu")
		(net "M_F_CPU1_SA_DQ<28>")
	)
	(segment
		(start 57.349136 -231.365806)
		(end 57.908698 -231.365806)
		(width 0.14478)
		(layer "In11.Cu")
		(net "M_F_CPU1_SA_DQ<28>")
	)
	(segment
		(start 43.905424 -230.920036)
		(end 45.577506 -230.920036)
		(width 0.14478)
		(layer "In11.Cu")
		(net "M_F_CPU1_SA_DQ<28>")
	)
	(segment
		(start 35.61842 -231.073452)
		(end 35.61842 -231.14127)
		(width 0.14478)
		(layer "In11.Cu")
		(net "M_F_CPU1_SA_DQ<28>")
	)
	(segment
		(start 34.06013 -231.923336)
		(end 34.223198 -231.760268)
		(width 0.14478)
		(layer "In11.Cu")
		(net "M_F_CPU1_SA_DQ<28>")
	)
	(segment
		(start 41.044876 -231.98963)
		(end 41.207944 -232.152698)
		(width 0.14478)
		(layer "In11.Cu")
		(net "M_F_CPU1_SA_DQ<28>")
	)
	(segment
		(start 75.966066 -242.157504)
		(end 76.199746 -242.157504)
		(width 0.0889)
		(layer "In11.Cu")
		(net "M_F_CPU1_SA_DQ<28>")
	)
	(segment
		(start 41.60139 -231.98963)
		(end 41.60139 -231.923336)
		(width 0.14478)
		(layer "In11.Cu")
		(net "M_F_CPU1_SA_DQ<28>")
	)
	(segment
		(start 36.174934 -231.14127)
		(end 36.174934 -231.073452)
		(width 0.14478)
		(layer "In11.Cu")
		(net "M_F_CPU1_SA_DQ<28>")
	)
	(segment
		(start 76.199746 -242.157504)
		(end 76.547472 -242.50523)
		(width 0.0889)
		(layer "In11.Cu")
		(net "M_F_CPU1_SA_DQ<28>")
	)
	(segment
		(start 48.659542 -232.152698)
		(end 48.88992 -232.152698)
		(width 0.14478)
		(layer "In11.Cu")
		(net "M_F_CPU1_SA_DQ<28>")
	)
	(segment
		(start 55.789576 -231.981756)
		(end 55.952644 -232.144824)
		(width 0.14478)
		(layer "In11.Cu")
		(net "M_F_CPU1_SA_DQ<28>")
	)
	(segment
		(start 23.165308 -231.760268)
		(end 23.698708 -231.760268)
		(width 0.14478)
		(layer "In11.Cu")
		(net "M_F_CPU1_SA_DQ<28>")
	)
	(segment
		(start 21.70811 -231.335326)
		(end 22.133052 -231.760268)
		(width 0.14478)
		(layer "In11.Cu")
		(net "M_F_CPU1_SA_DQ<28>")
	)
	(segment
		(start 35.233102 -230.910384)
		(end 35.455352 -230.910384)
		(width 0.14478)
		(layer "In11.Cu")
		(net "M_F_CPU1_SA_DQ<28>")
	)
	(segment
		(start 54.839616 -232.144824)
		(end 55.069994 -232.144824)
		(width 0.14478)
		(layer "In11.Cu")
		(net "M_F_CPU1_SA_DQ<28>")
	)
	(segment
		(start 50.74285 -231.073452)
		(end 50.74285 -231.13365)
		(width 0.14478)
		(layer "In11.Cu")
		(net "M_F_CPU1_SA_DQ<28>")
	)
	(segment
		(start 28.476448 -231.304338)
		(end 28.639516 -231.14127)
		(width 0.14478)
		(layer "In11.Cu")
		(net "M_F_CPU1_SA_DQ<28>")
	)
	(segment
		(start 36.32835 -230.920036)
		(end 37.962332 -230.920036)
		(width 0.14478)
		(layer "In11.Cu")
		(net "M_F_CPU1_SA_DQ<28>")
	)
	(segment
		(start 33.897062 -232.152698)
		(end 34.06013 -231.98963)
		(width 0.14478)
		(layer "In11.Cu")
		(net "M_F_CPU1_SA_DQ<28>")
	)
	(segment
		(start 27.664664 -230.910384)
		(end 27.919934 -230.910384)
		(width 0.14478)
		(layer "In11.Cu")
		(net "M_F_CPU1_SA_DQ<28>")
	)
	(segment
		(start 51.299364 -231.13365)
		(end 51.299364 -231.073452)
		(width 0.14478)
		(layer "In11.Cu")
		(net "M_F_CPU1_SA_DQ<28>")
	)
	(segment
		(start 83.394042 -243.186966)
		(end 83.402424 -243.191792)
		(width 0.0889)
		(layer "In11.Cu")
		(net "M_F_CPU1_SA_DQ<28>")
	)
	(segment
		(start 27.919934 -230.910384)
		(end 28.083002 -231.073452)
		(width 0.14478)
		(layer "In11.Cu")
		(net "M_F_CPU1_SA_DQ<28>")
	)
	(segment
		(start 23.861776 -231.98963)
		(end 24.024844 -232.152698)
		(width 0.14478)
		(layer "In11.Cu")
		(net "M_F_CPU1_SA_DQ<28>")
	)
	(segment
		(start 54.676548 -231.981756)
		(end 54.839616 -232.144824)
		(width 0.14478)
		(layer "In11.Cu")
		(net "M_F_CPU1_SA_DQ<28>")
	)
	(segment
		(start 58.460132 -232.061766)
		(end 58.604912 -231.916986)
		(width 0.14478)
		(layer "In11.Cu")
		(net "M_F_CPU1_SA_DQ<28>")
	)
	(segment
		(start 40.89146 -231.76992)
		(end 41.044876 -231.923336)
		(width 0.14478)
		(layer "In11.Cu")
		(net "M_F_CPU1_SA_DQ<28>")
	)
	(segment
		(start 48.496474 -231.98963)
		(end 48.659542 -232.152698)
		(width 0.14478)
		(layer "In11.Cu")
		(net "M_F_CPU1_SA_DQ<28>")
	)
	(segment
		(start 34.383218 -231.760268)
		(end 35.233102 -230.910384)
		(width 0.14478)
		(layer "In11.Cu")
		(net "M_F_CPU1_SA_DQ<28>")
	)
	(segment
		(start 77.116178 -242.50523)
		(end 77.721714 -243.110766)
		(width 0.0889)
		(layer "In11.Cu")
		(net "M_F_CPU1_SA_DQ<28>")
	)
	(segment
		(start 58.053478 -231.510586)
		(end 58.053478 -231.916986)
		(width 0.14478)
		(layer "In11.Cu")
		(net "M_F_CPU1_SA_DQ<28>")
	)
	(segment
		(start 81.879694 -243.191792)
		(end 81.888076 -243.186966)
		(width 0.0889)
		(layer "In11.Cu")
		(net "M_F_CPU1_SA_DQ<28>")
	)
	(segment
		(start 49.052988 -231.98963)
		(end 49.052988 -231.923336)
		(width 0.14478)
		(layer "In11.Cu")
		(net "M_F_CPU1_SA_DQ<28>")
	)
	(segment
		(start 43.752008 -231.073452)
		(end 43.905424 -230.920036)
		(width 0.14478)
		(layer "In11.Cu")
		(net "M_F_CPU1_SA_DQ<28>")
	)
	(segment
		(start 33.3502 -231.76992)
		(end 33.503616 -231.923336)
		(width 0.14478)
		(layer "In11.Cu")
		(net "M_F_CPU1_SA_DQ<28>")
	)
	(segment
		(start 23.698708 -231.760268)
		(end 23.861776 -231.923336)
		(width 0.14478)
		(layer "In11.Cu")
		(net "M_F_CPU1_SA_DQ<28>")
	)
	(segment
		(start 58.053478 -231.916986)
		(end 58.198258 -232.061766)
		(width 0.14478)
		(layer "In11.Cu")
		(net "M_F_CPU1_SA_DQ<28>")
	)
	(segment
		(start 56.34609 -231.923336)
		(end 56.509158 -231.760268)
		(width 0.14478)
		(layer "In11.Cu")
		(net "M_F_CPU1_SA_DQ<28>")
	)
	(segment
		(start 56.183022 -232.144824)
		(end 56.34609 -231.981756)
		(width 0.14478)
		(layer "In11.Cu")
		(net "M_F_CPU1_SA_DQ<28>")
	)
	(segment
		(start 36.011866 -231.304338)
		(end 36.174934 -231.14127)
		(width 0.14478)
		(layer "In11.Cu")
		(net "M_F_CPU1_SA_DQ<28>")
	)
	(segment
		(start 76.547472 -242.50523)
		(end 77.116178 -242.50523)
		(width 0.0889)
		(layer "In11.Cu")
		(net "M_F_CPU1_SA_DQ<28>")
	)
	(segment
		(start 48.343058 -231.76992)
		(end 48.496474 -231.923336)
		(width 0.14478)
		(layer "In11.Cu")
		(net "M_F_CPU1_SA_DQ<28>")
	)
	(segment
		(start 50.298858 -230.910384)
		(end 50.579782 -230.910384)
		(width 0.14478)
		(layer "In11.Cu")
		(net "M_F_CPU1_SA_DQ<28>")
	)
	(segment
		(start 59.317128 -231.365806)
		(end 61.869066 -233.917744)
		(width 0.14478)
		(layer "In11.Cu")
		(net "M_F_CPU1_SA_DQ<28>")
	)
	(segment
		(start 22.282658 -231.760268)
		(end 22.445726 -231.5972)
		(width 0.14478)
		(layer "In11.Cu")
		(net "M_F_CPU1_SA_DQ<28>")
	)
	(segment
		(start 28.24607 -231.304338)
		(end 28.476448 -231.304338)
		(width 0.14478)
		(layer "In11.Cu")
		(net "M_F_CPU1_SA_DQ<28>")
	)
	(segment
		(start 43.358562 -231.296718)
		(end 43.58894 -231.296718)
		(width 0.14478)
		(layer "In11.Cu")
		(net "M_F_CPU1_SA_DQ<28>")
	)
	(segment
		(start 24.41829 -231.923336)
		(end 24.571706 -231.76992)
		(width 0.14478)
		(layer "In11.Cu")
		(net "M_F_CPU1_SA_DQ<28>")
	)
	(segment
		(start 28.639516 -231.14127)
		(end 28.639516 -231.073452)
		(width 0.14478)
		(layer "In11.Cu")
		(net "M_F_CPU1_SA_DQ<28>")
	)
	(segment
		(start 56.509158 -231.760268)
		(end 56.954674 -231.760268)
		(width 0.14478)
		(layer "In11.Cu")
		(net "M_F_CPU1_SA_DQ<28>")
	)
	(segment
		(start 35.781488 -231.304338)
		(end 36.011866 -231.304338)
		(width 0.14478)
		(layer "In11.Cu")
		(net "M_F_CPU1_SA_DQ<28>")
	)
	(segment
		(start 68.43649 -242.157504)
		(end 75.966066 -242.157504)
		(width 0.14478)
		(layer "In11.Cu")
		(net "M_F_CPU1_SA_DQ<28>")
	)
	(segment
		(start 37.962332 -230.920036)
		(end 38.812216 -231.76992)
		(width 0.14478)
		(layer "In11.Cu")
		(net "M_F_CPU1_SA_DQ<28>")
	)
	(segment
		(start 23.00224 -231.193086)
		(end 23.00224 -231.5972)
		(width 0.14478)
		(layer "In11.Cu")
		(net "M_F_CPU1_SA_DQ<28>")
	)
	(segment
		(start 28.083002 -231.14127)
		(end 28.24607 -231.304338)
		(width 0.14478)
		(layer "In11.Cu")
		(net "M_F_CPU1_SA_DQ<28>")
	)
	(segment
		(start 33.503616 -231.923336)
		(end 33.503616 -231.98963)
		(width 0.14478)
		(layer "In11.Cu")
		(net "M_F_CPU1_SA_DQ<28>")
	)
	(segment
		(start 41.438322 -232.152698)
		(end 41.60139 -231.98963)
		(width 0.14478)
		(layer "In11.Cu")
		(net "M_F_CPU1_SA_DQ<28>")
	)
	(segment
		(start 28.083002 -231.073452)
		(end 28.083002 -231.14127)
		(width 0.14478)
		(layer "In11.Cu")
		(net "M_F_CPU1_SA_DQ<28>")
	)
	(segment
		(start 33.503616 -231.98963)
		(end 33.666684 -232.152698)
		(width 0.14478)
		(layer "In11.Cu")
		(net "M_F_CPU1_SA_DQ<28>")
	)
	(segment
		(start 34.06013 -231.98963)
		(end 34.06013 -231.923336)
		(width 0.14478)
		(layer "In11.Cu")
		(net "M_F_CPU1_SA_DQ<28>")
	)
	(segment
		(start 38.812216 -231.76992)
		(end 40.89146 -231.76992)
		(width 0.14478)
		(layer "In11.Cu")
		(net "M_F_CPU1_SA_DQ<28>")
	)
	(segment
		(start 50.905918 -231.296718)
		(end 51.136296 -231.296718)
		(width 0.14478)
		(layer "In11.Cu")
		(net "M_F_CPU1_SA_DQ<28>")
	)
	(segment
		(start 55.39613 -231.484424)
		(end 55.626508 -231.484424)
		(width 0.14478)
		(layer "In11.Cu")
		(net "M_F_CPU1_SA_DQ<28>")
	)
	(segment
		(start 53.961792 -231.760268)
		(end 54.51348 -231.760268)
		(width 0.14478)
		(layer "In11.Cu")
		(net "M_F_CPU1_SA_DQ<28>")
	)
	(segment
		(start 22.133052 -231.760268)
		(end 22.282658 -231.760268)
		(width 0.14478)
		(layer "In11.Cu")
		(net "M_F_CPU1_SA_DQ<28>")
	)
	(segment
		(start 24.255222 -232.152698)
		(end 24.41829 -231.98963)
		(width 0.14478)
		(layer "In11.Cu")
		(net "M_F_CPU1_SA_DQ<28>")
	)
	(segment
		(start 61.869066 -233.917744)
		(end 61.869066 -235.59008)
		(width 0.14478)
		(layer "In11.Cu")
		(net "M_F_CPU1_SA_DQ<28>")
	)
	(segment
		(start 28.639516 -231.073452)
		(end 28.792932 -230.920036)
		(width 0.14478)
		(layer "In11.Cu")
		(net "M_F_CPU1_SA_DQ<28>")
	)
	(segment
		(start 79.622396 -243.179854)
		(end 79.634334 -243.186712)
		(width 0.0889)
		(layer "In11.Cu")
		(net "M_F_CPU1_SA_DQ<28>")
	)
	(segment
		(start 79.0575 -243.193824)
		(end 79.069184 -243.186966)
		(width 0.0889)
		(layer "In11.Cu")
		(net "M_F_CPU1_SA_DQ<28>")
	)
	(segment
		(start 55.626508 -231.484424)
		(end 55.789576 -231.647492)
		(width 0.14478)
		(layer "In11.Cu")
		(net "M_F_CPU1_SA_DQ<28>")
	)
	(segment
		(start 57.908698 -231.365806)
		(end 58.053478 -231.510586)
		(width 0.14478)
		(layer "In11.Cu")
		(net "M_F_CPU1_SA_DQ<28>")
	)
	(segment
		(start 48.496474 -231.923336)
		(end 48.496474 -231.98963)
		(width 0.14478)
		(layer "In11.Cu")
		(net "M_F_CPU1_SA_DQ<28>")
	)
	(segment
		(start 50.74285 -231.13365)
		(end 50.905918 -231.296718)
		(width 0.14478)
		(layer "In11.Cu")
		(net "M_F_CPU1_SA_DQ<28>")
	)
	(segment
		(start 53.12156 -230.920036)
		(end 53.961792 -231.760268)
		(width 0.14478)
		(layer "In11.Cu")
		(net "M_F_CPU1_SA_DQ<28>")
	)
	(segment
		(start 49.052988 -231.923336)
		(end 49.216056 -231.760268)
		(width 0.14478)
		(layer "In11.Cu")
		(net "M_F_CPU1_SA_DQ<28>")
	)
	(segment
		(start 31.330392 -231.76992)
		(end 33.3502 -231.76992)
		(width 0.14478)
		(layer "In11.Cu")
		(net "M_F_CPU1_SA_DQ<28>")
	)
	(segment
		(start 22.445726 -231.5972)
		(end 22.445726 -231.193086)
		(width 0.14478)
		(layer "In11.Cu")
		(net "M_F_CPU1_SA_DQ<28>")
	)
	(segment
		(start 28.792932 -230.920036)
		(end 30.480508 -230.920036)
		(width 0.14478)
		(layer "In11.Cu")
		(net "M_F_CPU1_SA_DQ<28>")
	)
	(segment
		(start 55.952644 -232.144824)
		(end 56.183022 -232.144824)
		(width 0.14478)
		(layer "In11.Cu")
		(net "M_F_CPU1_SA_DQ<28>")
	)
	(segment
		(start 84.271104 -243.155216)
		(end 84.367116 -243.129816)
		(width 0.0889)
		(layer "In11.Cu")
		(net "M_F_CPU1_SA_DQ<28>")
	)
	(segment
		(start 23.861776 -231.923336)
		(end 23.861776 -231.98963)
		(width 0.14478)
		(layer "In11.Cu")
		(net "M_F_CPU1_SA_DQ<28>")
	)
	(segment
		(start 36.174934 -231.073452)
		(end 36.32835 -230.920036)
		(width 0.14478)
		(layer "In11.Cu")
		(net "M_F_CPU1_SA_DQ<28>")
	)
	(segment
		(start 43.195494 -231.073452)
		(end 43.195494 -231.13365)
		(width 0.14478)
		(layer "In11.Cu")
		(net "M_F_CPU1_SA_DQ<28>")
	)
	(segment
		(start 55.789576 -231.647492)
		(end 55.789576 -231.981756)
		(width 0.14478)
		(layer "In11.Cu")
		(net "M_F_CPU1_SA_DQ<28>")
	)
	(segment
		(start 41.764458 -231.760268)
		(end 41.94302 -231.760268)
		(width 0.14478)
		(layer "In11.Cu")
		(net "M_F_CPU1_SA_DQ<28>")
	)
	(segment
		(start 35.455352 -230.910384)
		(end 35.61842 -231.073452)
		(width 0.14478)
		(layer "In11.Cu")
		(net "M_F_CPU1_SA_DQ<28>")
	)
	(segment
		(start 22.608794 -231.030018)
		(end 22.839172 -231.030018)
		(width 0.14478)
		(layer "In11.Cu")
		(net "M_F_CPU1_SA_DQ<28>")
	)
	(segment
		(start 58.198258 -232.061766)
		(end 58.460132 -232.061766)
		(width 0.14478)
		(layer "In11.Cu")
		(net "M_F_CPU1_SA_DQ<28>")
	)
	(segment
		(start 82.453988 -243.186966)
		(end 82.46237 -243.191792)
		(width 0.0889)
		(layer "In11.Cu")
		(net "M_F_CPU1_SA_DQ<28>")
	)
	(segment
		(start 24.41829 -231.98963)
		(end 24.41829 -231.923336)
		(width 0.14478)
		(layer "In11.Cu")
		(net "M_F_CPU1_SA_DQ<28>")
	)
	(arc
		(start 81.513934 -243.186966)
		(mid 81.696185 -243.237316)
		(end 81.879694 -243.191792)
		(width 0.0889)
		(layer "In11.Cu")
		(net "M_F_CPU1_SA_DQ<28>")
	)
	(arc
		(start 82.46237 -243.191792)
		(mid 82.645878 -243.237286)
		(end 82.82813 -243.186966)
		(width 0.0889)
		(layer "In11.Cu")
		(net "M_F_CPU1_SA_DQ<28>")
	)
	(arc
		(start 80.948022 -243.186966)
		(mid 81.230978 -243.110789)
		(end 81.513934 -243.186966)
		(width 0.0889)
		(layer "In11.Cu")
		(net "M_F_CPU1_SA_DQ<28>")
	)
	(arc
		(start 78.694788 -243.186966)
		(mid 78.875246 -243.23741)
		(end 79.0575 -243.193824)
		(width 0.0889)
		(layer "In11.Cu")
		(net "M_F_CPU1_SA_DQ<28>")
	)
	(arc
		(start 79.65059 -243.19611)
		(mid 79.830572 -243.23721)
		(end 80.008222 -243.186966)
		(width 0.0889)
		(layer "In11.Cu")
		(net "M_F_CPU1_SA_DQ<28>")
	)
	(arc
		(start 80.008222 -243.186966)
		(mid 80.291178 -243.110789)
		(end 80.574134 -243.186966)
		(width 0.0889)
		(layer "In11.Cu")
		(net "M_F_CPU1_SA_DQ<28>")
	)
	(arc
		(start 81.888076 -243.186966)
		(mid 82.171032 -243.110789)
		(end 82.453988 -243.186966)
		(width 0.0889)
		(layer "In11.Cu")
		(net "M_F_CPU1_SA_DQ<28>")
	)
	(arc
		(start 83.402424 -243.191792)
		(mid 83.585932 -243.237286)
		(end 83.768184 -243.186966)
		(width 0.0889)
		(layer "In11.Cu")
		(net "M_F_CPU1_SA_DQ<28>")
	)
	(arc
		(start 79.069184 -243.186966)
		(mid 79.344862 -243.110836)
		(end 79.622396 -243.179854)
		(width 0.0889)
		(layer "In11.Cu")
		(net "M_F_CPU1_SA_DQ<28>")
	)
	(arc
		(start 80.574134 -243.186966)
		(mid 80.761078 -243.237221)
		(end 80.948022 -243.186966)
		(width 0.0889)
		(layer "In11.Cu")
		(net "M_F_CPU1_SA_DQ<28>")
	)
	(arc
		(start 78.41107 -243.110512)
		(mid 78.558001 -243.129923)
		(end 78.694788 -243.186966)
		(width 0.0889)
		(layer "In11.Cu")
		(net "M_F_CPU1_SA_DQ<28>")
	)
	(arc
		(start 83.768184 -243.186966)
		(mid 84.015897 -243.111746)
		(end 84.271104 -243.155216)
		(width 0.0889)
		(layer "In11.Cu")
		(net "M_F_CPU1_SA_DQ<28>")
	)
	(arc
		(start 82.82813 -243.186966)
		(mid 83.111086 -243.110789)
		(end 83.394042 -243.186966)
		(width 0.0889)
		(layer "In11.Cu")
		(net "M_F_CPU1_SA_DQ<28>")
	)
	(segment
		(start 85.927946 -241.510312)
		(end 85.461094 -241.244374)
		(width 0.10668)
		(layer "F.Cu")
		(net "M_F_CPU1_SA_DQ<27>")
	)
	(segment
		(start 35.21837 -227.500688)
		(end 38.103556 -227.500688)
		(width 0.14478)
		(layer "In11.Cu")
		(net "M_F_CPU1_SA_DQ<27>")
	)
	(segment
		(start 18.668746 -228.19741)
		(end 18.668746 -227.569014)
		(width 0.14478)
		(layer "In11.Cu")
		(net "M_F_CPU1_SA_DQ<27>")
	)
	(segment
		(start 85.592666 -240.895632)
		(end 85.615018 -240.978944)
		(width 0.0889)
		(layer "In11.Cu")
		(net "M_F_CPU1_SA_DQ<27>")
	)
	(segment
		(start 17.608042 -227.935282)
		(end 18.033238 -228.360478)
		(width 0.14478)
		(layer "In11.Cu")
		(net "M_F_CPU1_SA_DQ<27>")
	)
	(segment
		(start 41.901872 -228.350572)
		(end 42.751756 -227.500688)
		(width 0.14478)
		(layer "In11.Cu")
		(net "M_F_CPU1_SA_DQ<27>")
	)
	(segment
		(start 19.22526 -227.569014)
		(end 19.22526 -228.19741)
		(width 0.14478)
		(layer "In11.Cu")
		(net "M_F_CPU1_SA_DQ<27>")
	)
	(segment
		(start 76.181966 -239.818164)
		(end 76.651866 -240.288064)
		(width 0.0889)
		(layer "In11.Cu")
		(net "M_F_CPU1_SA_DQ<27>")
	)
	(segment
		(start 78.692502 -240.922048)
		(end 78.712568 -240.910618)
		(width 0.0889)
		(layer "In11.Cu")
		(net "M_F_CPU1_SA_DQ<27>")
	)
	(segment
		(start 18.505678 -228.360478)
		(end 18.668746 -228.19741)
		(width 0.14478)
		(layer "In11.Cu")
		(net "M_F_CPU1_SA_DQ<27>")
	)
	(segment
		(start 71.151242 -239.818164)
		(end 75.991466 -239.818164)
		(width 0.14478)
		(layer "In11.Cu")
		(net "M_F_CPU1_SA_DQ<27>")
	)
	(segment
		(start 31.383986 -228.350572)
		(end 34.368486 -228.350572)
		(width 0.14478)
		(layer "In11.Cu")
		(net "M_F_CPU1_SA_DQ<27>")
	)
	(segment
		(start 81.879694 -240.916968)
		(end 81.888076 -240.921794)
		(width 0.0889)
		(layer "In11.Cu")
		(net "M_F_CPU1_SA_DQ<27>")
	)
	(segment
		(start 38.95344 -228.350572)
		(end 41.901872 -228.350572)
		(width 0.14478)
		(layer "In11.Cu")
		(net "M_F_CPU1_SA_DQ<27>")
	)
	(segment
		(start 57.330086 -227.966524)
		(end 57.78627 -227.51034)
		(width 0.14478)
		(layer "In11.Cu")
		(net "M_F_CPU1_SA_DQ<27>")
	)
	(segment
		(start 49.399698 -228.350572)
		(end 50.249582 -227.500688)
		(width 0.14478)
		(layer "In11.Cu")
		(net "M_F_CPU1_SA_DQ<27>")
	)
	(segment
		(start 77.766926 -241.039904)
		(end 78.232762 -241.039904)
		(width 0.0889)
		(layer "In11.Cu")
		(net "M_F_CPU1_SA_DQ<27>")
	)
	(segment
		(start 45.609002 -227.500688)
		(end 46.458886 -228.350572)
		(width 0.14478)
		(layer "In11.Cu")
		(net "M_F_CPU1_SA_DQ<27>")
	)
	(segment
		(start 19.22526 -228.19741)
		(end 19.378422 -228.350572)
		(width 0.14478)
		(layer "In11.Cu")
		(net "M_F_CPU1_SA_DQ<27>")
	)
	(segment
		(start 75.991466 -239.818164)
		(end 76.181966 -239.818164)
		(width 0.0889)
		(layer "In11.Cu")
		(net "M_F_CPU1_SA_DQ<27>")
	)
	(segment
		(start 50.249582 -227.500688)
		(end 53.145436 -227.500688)
		(width 0.14478)
		(layer "In11.Cu")
		(net "M_F_CPU1_SA_DQ<27>")
	)
	(segment
		(start 76.651866 -240.288064)
		(end 77.015086 -240.288064)
		(width 0.0889)
		(layer "In11.Cu")
		(net "M_F_CPU1_SA_DQ<27>")
	)
	(segment
		(start 18.831814 -227.405946)
		(end 19.062192 -227.405946)
		(width 0.14478)
		(layer "In11.Cu")
		(net "M_F_CPU1_SA_DQ<27>")
	)
	(segment
		(start 79.065882 -240.921794)
		(end 79.08925 -240.93551)
		(width 0.0889)
		(layer "In11.Cu")
		(net "M_F_CPU1_SA_DQ<27>")
	)
	(segment
		(start 30.534102 -227.500688)
		(end 31.383986 -228.350572)
		(width 0.14478)
		(layer "In11.Cu")
		(net "M_F_CPU1_SA_DQ<27>")
	)
	(segment
		(start 18.668746 -227.569014)
		(end 18.831814 -227.405946)
		(width 0.14478)
		(layer "In11.Cu")
		(net "M_F_CPU1_SA_DQ<27>")
	)
	(segment
		(start 77.015086 -240.288064)
		(end 77.766926 -241.039904)
		(width 0.0889)
		(layer "In11.Cu")
		(net "M_F_CPU1_SA_DQ<27>")
	)
	(segment
		(start 53.145436 -227.500688)
		(end 53.611272 -227.966524)
		(width 0.14478)
		(layer "In11.Cu")
		(net "M_F_CPU1_SA_DQ<27>")
	)
	(segment
		(start 46.458886 -228.350572)
		(end 49.399698 -228.350572)
		(width 0.14478)
		(layer "In11.Cu")
		(net "M_F_CPU1_SA_DQ<27>")
	)
	(segment
		(start 26.737564 -228.350572)
		(end 27.587448 -227.500688)
		(width 0.14478)
		(layer "In11.Cu")
		(net "M_F_CPU1_SA_DQ<27>")
	)
	(segment
		(start 78.658974 -240.941352)
		(end 78.692502 -240.922048)
		(width 0.0889)
		(layer "In11.Cu")
		(net "M_F_CPU1_SA_DQ<27>")
	)
	(segment
		(start 42.751756 -227.500688)
		(end 45.609002 -227.500688)
		(width 0.14478)
		(layer "In11.Cu")
		(net "M_F_CPU1_SA_DQ<27>")
	)
	(segment
		(start 85.615018 -240.978944)
		(end 85.461094 -241.244374)
		(width 0.0889)
		(layer "In11.Cu")
		(net "M_F_CPU1_SA_DQ<27>")
	)
	(segment
		(start 18.033238 -228.360478)
		(end 18.505678 -228.360478)
		(width 0.14478)
		(layer "In11.Cu")
		(net "M_F_CPU1_SA_DQ<27>")
	)
	(segment
		(start 82.453988 -240.921794)
		(end 82.46237 -240.916968)
		(width 0.0889)
		(layer "In11.Cu")
		(net "M_F_CPU1_SA_DQ<27>")
	)
	(segment
		(start 19.378422 -228.350572)
		(end 26.737564 -228.350572)
		(width 0.14478)
		(layer "In11.Cu")
		(net "M_F_CPU1_SA_DQ<27>")
	)
	(segment
		(start 38.103556 -227.500688)
		(end 38.95344 -228.350572)
		(width 0.14478)
		(layer "In11.Cu")
		(net "M_F_CPU1_SA_DQ<27>")
	)
	(segment
		(start 58.843418 -227.51034)
		(end 71.151242 -239.818164)
		(width 0.14478)
		(layer "In11.Cu")
		(net "M_F_CPU1_SA_DQ<27>")
	)
	(segment
		(start 83.394042 -240.921794)
		(end 83.402424 -240.916968)
		(width 0.0889)
		(layer "In11.Cu")
		(net "M_F_CPU1_SA_DQ<27>")
	)
	(segment
		(start 57.78627 -227.51034)
		(end 58.843418 -227.51034)
		(width 0.14478)
		(layer "In11.Cu")
		(net "M_F_CPU1_SA_DQ<27>")
	)
	(segment
		(start 79.993744 -240.913412)
		(end 80.008222 -240.921794)
		(width 0.0889)
		(layer "In11.Cu")
		(net "M_F_CPU1_SA_DQ<27>")
	)
	(segment
		(start 34.368486 -228.350572)
		(end 35.21837 -227.500688)
		(width 0.14478)
		(layer "In11.Cu")
		(net "M_F_CPU1_SA_DQ<27>")
	)
	(segment
		(start 27.587448 -227.500688)
		(end 30.534102 -227.500688)
		(width 0.14478)
		(layer "In11.Cu")
		(net "M_F_CPU1_SA_DQ<27>")
	)
	(segment
		(start 19.062192 -227.405946)
		(end 19.22526 -227.569014)
		(width 0.14478)
		(layer "In11.Cu")
		(net "M_F_CPU1_SA_DQ<27>")
	)
	(segment
		(start 53.611272 -227.966524)
		(end 57.330086 -227.966524)
		(width 0.14478)
		(layer "In11.Cu")
		(net "M_F_CPU1_SA_DQ<27>")
	)
	(arc
		(start 84.334096 -240.921794)
		(mid 84.52104 -240.871539)
		(end 84.707984 -240.921794)
		(width 0.0889)
		(layer "In11.Cu")
		(net "M_F_CPU1_SA_DQ<27>")
	)
	(arc
		(start 84.707984 -240.921794)
		(mid 84.99094 -240.997971)
		(end 85.273896 -240.921794)
		(width 0.0889)
		(layer "In11.Cu")
		(net "M_F_CPU1_SA_DQ<27>")
	)
	(arc
		(start 81.513934 -240.921794)
		(mid 81.696185 -240.871444)
		(end 81.879694 -240.916968)
		(width 0.0889)
		(layer "In11.Cu")
		(net "M_F_CPU1_SA_DQ<27>")
	)
	(arc
		(start 81.888076 -240.921794)
		(mid 82.171032 -240.997971)
		(end 82.453988 -240.921794)
		(width 0.0889)
		(layer "In11.Cu")
		(net "M_F_CPU1_SA_DQ<27>")
	)
	(arc
		(start 79.633064 -240.921794)
		(mid 79.812327 -240.87113)
		(end 79.993744 -240.913412)
		(width 0.0889)
		(layer "In11.Cu")
		(net "M_F_CPU1_SA_DQ<27>")
	)
	(arc
		(start 85.273896 -240.921794)
		(mid 85.430334 -240.872823)
		(end 85.592666 -240.895632)
		(width 0.0889)
		(layer "In11.Cu")
		(net "M_F_CPU1_SA_DQ<27>")
	)
	(arc
		(start 80.948022 -240.921794)
		(mid 81.230978 -240.997971)
		(end 81.513934 -240.921794)
		(width 0.0889)
		(layer "In11.Cu")
		(net "M_F_CPU1_SA_DQ<27>")
	)
	(arc
		(start 78.712568 -240.910618)
		(mid 78.890646 -240.871634)
		(end 79.065882 -240.921794)
		(width 0.0889)
		(layer "In11.Cu")
		(net "M_F_CPU1_SA_DQ<27>")
	)
	(arc
		(start 82.46237 -240.916968)
		(mid 82.645878 -240.871474)
		(end 82.82813 -240.921794)
		(width 0.0889)
		(layer "In11.Cu")
		(net "M_F_CPU1_SA_DQ<27>")
	)
	(arc
		(start 83.768184 -240.921794)
		(mid 84.05114 -240.997971)
		(end 84.334096 -240.921794)
		(width 0.0889)
		(layer "In11.Cu")
		(net "M_F_CPU1_SA_DQ<27>")
	)
	(arc
		(start 82.82813 -240.921794)
		(mid 83.111086 -240.997971)
		(end 83.394042 -240.921794)
		(width 0.0889)
		(layer "In11.Cu")
		(net "M_F_CPU1_SA_DQ<27>")
	)
	(arc
		(start 80.008222 -240.921794)
		(mid 80.291178 -240.997971)
		(end 80.574134 -240.921794)
		(width 0.0889)
		(layer "In11.Cu")
		(net "M_F_CPU1_SA_DQ<27>")
	)
	(arc
		(start 78.232762 -241.039904)
		(mid 78.451489 -241.014942)
		(end 78.658974 -240.941352)
		(width 0.0889)
		(layer "In11.Cu")
		(net "M_F_CPU1_SA_DQ<27>")
	)
	(arc
		(start 80.574134 -240.921794)
		(mid 80.761078 -240.871539)
		(end 80.948022 -240.921794)
		(width 0.0889)
		(layer "In11.Cu")
		(net "M_F_CPU1_SA_DQ<27>")
	)
	(arc
		(start 79.08925 -240.93551)
		(mid 79.362904 -240.998453)
		(end 79.633064 -240.921794)
		(width 0.0889)
		(layer "In11.Cu")
		(net "M_F_CPU1_SA_DQ<27>")
	)
	(arc
		(start 83.402424 -240.916968)
		(mid 83.585932 -240.871474)
		(end 83.768184 -240.921794)
		(width 0.0889)
		(layer "In11.Cu")
		(net "M_F_CPU1_SA_DQ<27>")
	)
	(segment
		(start 84.517992 -240.700306)
		(end 84.05114 -240.434368)
		(width 0.10668)
		(layer "F.Cu")
		(net "M_F_CPU1_SA_DQ<26>")
	)
	(segment
		(start 46.468792 -226.660456)
		(end 49.389792 -226.660456)
		(width 0.14478)
		(layer "In11.Cu")
		(net "M_F_CPU1_SA_DQ<26>")
	)
	(segment
		(start 76.369926 -238.903764)
		(end 76.507086 -239.040924)
		(width 0.0889)
		(layer "In11.Cu")
		(net "M_F_CPU1_SA_DQ<26>")
	)
	(segment
		(start 77.985366 -240.062004)
		(end 77.991208 -240.062004)
		(width 0.0889)
		(layer "In11.Cu")
		(net "M_F_CPU1_SA_DQ<26>")
	)
	(segment
		(start 27.577796 -225.810318)
		(end 30.543754 -225.810318)
		(width 0.14478)
		(layer "In11.Cu")
		(net "M_F_CPU1_SA_DQ<26>")
	)
	(segment
		(start 50.23993 -225.810318)
		(end 53.155088 -225.810318)
		(width 0.14478)
		(layer "In11.Cu")
		(net "M_F_CPU1_SA_DQ<26>")
	)
	(segment
		(start 57.122822 -226.473766)
		(end 59.078876 -226.473766)
		(width 0.14478)
		(layer "In11.Cu")
		(net "M_F_CPU1_SA_DQ<26>")
	)
	(segment
		(start 18.674588 -226.497388)
		(end 18.674588 -225.904552)
		(width 0.14478)
		(layer "In11.Cu")
		(net "M_F_CPU1_SA_DQ<26>")
	)
	(segment
		(start 31.393892 -226.660456)
		(end 34.35858 -226.660456)
		(width 0.14478)
		(layer "In11.Cu")
		(net "M_F_CPU1_SA_DQ<26>")
	)
	(segment
		(start 71.508874 -238.903764)
		(end 75.978766 -238.903764)
		(width 0.14478)
		(layer "In11.Cu")
		(net "M_F_CPU1_SA_DQ<26>")
	)
	(segment
		(start 20.507198 -226.660456)
		(end 26.727658 -226.660456)
		(width 0.14478)
		(layer "In11.Cu")
		(net "M_F_CPU1_SA_DQ<26>")
	)
	(segment
		(start 41.891966 -226.660456)
		(end 42.742104 -225.810318)
		(width 0.14478)
		(layer "In11.Cu")
		(net "M_F_CPU1_SA_DQ<26>")
	)
	(segment
		(start 34.35858 -226.660456)
		(end 35.208718 -225.810318)
		(width 0.14478)
		(layer "In11.Cu")
		(net "M_F_CPU1_SA_DQ<26>")
	)
	(segment
		(start 42.742104 -225.810318)
		(end 45.618654 -225.810318)
		(width 0.14478)
		(layer "In11.Cu")
		(net "M_F_CPU1_SA_DQ<26>")
	)
	(segment
		(start 79.525114 -240.104168)
		(end 79.53883 -240.112042)
		(width 0.0889)
		(layer "In11.Cu")
		(net "M_F_CPU1_SA_DQ<26>")
	)
	(segment
		(start 81.044034 -240.111788)
		(end 81.052416 -240.106962)
		(width 0.0889)
		(layer "In11.Cu")
		(net "M_F_CPU1_SA_DQ<26>")
	)
	(segment
		(start 76.507086 -239.040924)
		(end 76.964286 -239.040924)
		(width 0.0889)
		(layer "In11.Cu")
		(net "M_F_CPU1_SA_DQ<26>")
	)
	(segment
		(start 30.543754 -225.810318)
		(end 31.393892 -226.660456)
		(width 0.14478)
		(layer "In11.Cu")
		(net "M_F_CPU1_SA_DQ<26>")
	)
	(segment
		(start 19.39417 -226.660456)
		(end 19.624548 -226.660456)
		(width 0.14478)
		(layer "In11.Cu")
		(net "M_F_CPU1_SA_DQ<26>")
	)
	(segment
		(start 38.113208 -225.810318)
		(end 38.963346 -226.660456)
		(width 0.14478)
		(layer "In11.Cu")
		(net "M_F_CPU1_SA_DQ<26>")
	)
	(segment
		(start 35.208718 -225.810318)
		(end 38.113208 -225.810318)
		(width 0.14478)
		(layer "In11.Cu")
		(net "M_F_CPU1_SA_DQ<26>")
	)
	(segment
		(start 19.787616 -226.497388)
		(end 19.787616 -225.904552)
		(width 0.14478)
		(layer "In11.Cu")
		(net "M_F_CPU1_SA_DQ<26>")
	)
	(segment
		(start 18.674588 -225.904552)
		(end 18.837656 -225.741484)
		(width 0.14478)
		(layer "In11.Cu")
		(net "M_F_CPU1_SA_DQ<26>")
	)
	(segment
		(start 19.068034 -225.741484)
		(end 19.231102 -225.904552)
		(width 0.14478)
		(layer "In11.Cu")
		(net "M_F_CPU1_SA_DQ<26>")
	)
	(segment
		(start 54.005226 -226.660456)
		(end 56.936132 -226.660456)
		(width 0.14478)
		(layer "In11.Cu")
		(net "M_F_CPU1_SA_DQ<26>")
	)
	(segment
		(start 77.991208 -240.062004)
		(end 78.41107 -240.061496)
		(width 0.0889)
		(layer "In11.Cu")
		(net "M_F_CPU1_SA_DQ<26>")
	)
	(segment
		(start 76.964286 -239.040924)
		(end 77.985366 -240.062004)
		(width 0.0889)
		(layer "In11.Cu")
		(net "M_F_CPU1_SA_DQ<26>")
	)
	(segment
		(start 26.727658 -226.660456)
		(end 27.577796 -225.810318)
		(width 0.14478)
		(layer "In11.Cu")
		(net "M_F_CPU1_SA_DQ<26>")
	)
	(segment
		(start 19.624548 -226.660456)
		(end 19.787616 -226.497388)
		(width 0.14478)
		(layer "In11.Cu")
		(net "M_F_CPU1_SA_DQ<26>")
	)
	(segment
		(start 19.231102 -225.904552)
		(end 19.231102 -226.497388)
		(width 0.14478)
		(layer "In11.Cu")
		(net "M_F_CPU1_SA_DQ<26>")
	)
	(segment
		(start 79.147162 -240.122456)
		(end 79.165196 -240.111788)
		(width 0.0889)
		(layer "In11.Cu")
		(net "M_F_CPU1_SA_DQ<26>")
	)
	(segment
		(start 75.978766 -238.903764)
		(end 76.369926 -238.903764)
		(width 0.0889)
		(layer "In11.Cu")
		(net "M_F_CPU1_SA_DQ<26>")
	)
	(segment
		(start 79.53883 -240.112042)
		(end 79.550768 -240.1189)
		(width 0.0889)
		(layer "In11.Cu")
		(net "M_F_CPU1_SA_DQ<26>")
	)
	(segment
		(start 17.608042 -226.23526)
		(end 18.033238 -226.660456)
		(width 0.14478)
		(layer "In11.Cu")
		(net "M_F_CPU1_SA_DQ<26>")
	)
	(segment
		(start 49.389792 -226.660456)
		(end 50.23993 -225.810318)
		(width 0.14478)
		(layer "In11.Cu")
		(net "M_F_CPU1_SA_DQ<26>")
	)
	(segment
		(start 56.936132 -226.660456)
		(end 57.122822 -226.473766)
		(width 0.14478)
		(layer "In11.Cu")
		(net "M_F_CPU1_SA_DQ<26>")
	)
	(segment
		(start 20.34413 -226.497388)
		(end 20.507198 -226.660456)
		(width 0.14478)
		(layer "In11.Cu")
		(net "M_F_CPU1_SA_DQ<26>")
	)
	(segment
		(start 83.289648 -240.106962)
		(end 83.29803 -240.111788)
		(width 0.0889)
		(layer "In11.Cu")
		(net "M_F_CPU1_SA_DQ<26>")
	)
	(segment
		(start 45.618654 -225.810318)
		(end 46.468792 -226.660456)
		(width 0.14478)
		(layer "In11.Cu")
		(net "M_F_CPU1_SA_DQ<26>")
	)
	(segment
		(start 84.182712 -240.085626)
		(end 84.205064 -240.168938)
		(width 0.0889)
		(layer "In11.Cu")
		(net "M_F_CPU1_SA_DQ<26>")
	)
	(segment
		(start 19.231102 -226.497388)
		(end 19.39417 -226.660456)
		(width 0.14478)
		(layer "In11.Cu")
		(net "M_F_CPU1_SA_DQ<26>")
	)
	(segment
		(start 18.033238 -226.660456)
		(end 18.51152 -226.660456)
		(width 0.14478)
		(layer "In11.Cu")
		(net "M_F_CPU1_SA_DQ<26>")
	)
	(segment
		(start 18.51152 -226.660456)
		(end 18.674588 -226.497388)
		(width 0.14478)
		(layer "In11.Cu")
		(net "M_F_CPU1_SA_DQ<26>")
	)
	(segment
		(start 53.155088 -225.810318)
		(end 54.005226 -226.660456)
		(width 0.14478)
		(layer "In11.Cu")
		(net "M_F_CPU1_SA_DQ<26>")
	)
	(segment
		(start 80.46974 -240.106962)
		(end 80.478122 -240.111788)
		(width 0.0889)
		(layer "In11.Cu")
		(net "M_F_CPU1_SA_DQ<26>")
	)
	(segment
		(start 38.963346 -226.660456)
		(end 41.891966 -226.660456)
		(width 0.14478)
		(layer "In11.Cu")
		(net "M_F_CPU1_SA_DQ<26>")
	)
	(segment
		(start 19.950684 -225.741484)
		(end 20.181062 -225.741484)
		(width 0.14478)
		(layer "In11.Cu")
		(net "M_F_CPU1_SA_DQ<26>")
	)
	(segment
		(start 84.205064 -240.168938)
		(end 84.05114 -240.434368)
		(width 0.0889)
		(layer "In11.Cu")
		(net "M_F_CPU1_SA_DQ<26>")
	)
	(segment
		(start 20.34413 -225.904552)
		(end 20.34413 -226.497388)
		(width 0.14478)
		(layer "In11.Cu")
		(net "M_F_CPU1_SA_DQ<26>")
	)
	(segment
		(start 18.837656 -225.741484)
		(end 19.068034 -225.741484)
		(width 0.14478)
		(layer "In11.Cu")
		(net "M_F_CPU1_SA_DQ<26>")
	)
	(segment
		(start 59.078876 -226.473766)
		(end 71.508874 -238.903764)
		(width 0.14478)
		(layer "In11.Cu")
		(net "M_F_CPU1_SA_DQ<26>")
	)
	(segment
		(start 19.787616 -225.904552)
		(end 19.950684 -225.741484)
		(width 0.14478)
		(layer "In11.Cu")
		(net "M_F_CPU1_SA_DQ<26>")
	)
	(segment
		(start 20.181062 -225.741484)
		(end 20.34413 -225.904552)
		(width 0.14478)
		(layer "In11.Cu")
		(net "M_F_CPU1_SA_DQ<26>")
	)
	(arc
		(start 79.550768 -240.1189)
		(mid 79.828302 -240.187881)
		(end 80.10398 -240.111788)
		(width 0.0889)
		(layer "In11.Cu")
		(net "M_F_CPU1_SA_DQ<26>")
	)
	(arc
		(start 81.052416 -240.106962)
		(mid 81.235924 -240.061468)
		(end 81.418176 -240.111788)
		(width 0.0889)
		(layer "In11.Cu")
		(net "M_F_CPU1_SA_DQ<26>")
	)
	(arc
		(start 82.923888 -240.111788)
		(mid 83.106139 -240.061438)
		(end 83.289648 -240.106962)
		(width 0.0889)
		(layer "In11.Cu")
		(net "M_F_CPU1_SA_DQ<26>")
	)
	(arc
		(start 81.418176 -240.111788)
		(mid 81.701132 -240.187965)
		(end 81.984088 -240.111788)
		(width 0.0889)
		(layer "In11.Cu")
		(net "M_F_CPU1_SA_DQ<26>")
	)
	(arc
		(start 80.10398 -240.111788)
		(mid 80.286231 -240.061438)
		(end 80.46974 -240.106962)
		(width 0.0889)
		(layer "In11.Cu")
		(net "M_F_CPU1_SA_DQ<26>")
	)
	(arc
		(start 78.598522 -240.111788)
		(mid 78.871466 -240.188368)
		(end 79.147162 -240.122456)
		(width 0.0889)
		(layer "In11.Cu")
		(net "M_F_CPU1_SA_DQ<26>")
	)
	(arc
		(start 79.165196 -240.111788)
		(mid 79.344183 -240.061618)
		(end 79.525114 -240.104168)
		(width 0.0889)
		(layer "In11.Cu")
		(net "M_F_CPU1_SA_DQ<26>")
	)
	(arc
		(start 78.41107 -240.061496)
		(mid 78.508133 -240.074214)
		(end 78.598522 -240.111788)
		(width 0.0889)
		(layer "In11.Cu")
		(net "M_F_CPU1_SA_DQ<26>")
	)
	(arc
		(start 81.984088 -240.111788)
		(mid 82.171032 -240.061533)
		(end 82.357976 -240.111788)
		(width 0.0889)
		(layer "In11.Cu")
		(net "M_F_CPU1_SA_DQ<26>")
	)
	(arc
		(start 83.863942 -240.111788)
		(mid 84.02038 -240.062817)
		(end 84.182712 -240.085626)
		(width 0.0889)
		(layer "In11.Cu")
		(net "M_F_CPU1_SA_DQ<26>")
	)
	(arc
		(start 82.357976 -240.111788)
		(mid 82.640932 -240.187965)
		(end 82.923888 -240.111788)
		(width 0.0889)
		(layer "In11.Cu")
		(net "M_F_CPU1_SA_DQ<26>")
	)
	(arc
		(start 80.478122 -240.111788)
		(mid 80.761078 -240.187965)
		(end 81.044034 -240.111788)
		(width 0.0889)
		(layer "In11.Cu")
		(net "M_F_CPU1_SA_DQ<26>")
	)
	(arc
		(start 83.29803 -240.111788)
		(mid 83.580986 -240.187965)
		(end 83.863942 -240.111788)
		(width 0.0889)
		(layer "In11.Cu")
		(net "M_F_CPU1_SA_DQ<26>")
	)
	(segment
		(start 86.397846 -240.700306)
		(end 85.930994 -240.434368)
		(width 0.10668)
		(layer "F.Cu")
		(net "M_F_CPU1_SA_DQ<25>")
	)
	(segment
		(start 48.33366 -227.51034)
		(end 48.496728 -227.673408)
		(width 0.14478)
		(layer "In11.Cu")
		(net "M_F_CPU1_SA_DQ<25>")
	)
	(segment
		(start 71.332598 -239.363504)
		(end 75.988926 -239.363504)
		(width 0.14478)
		(layer "In11.Cu")
		(net "M_F_CPU1_SA_DQ<25>")
	)
	(segment
		(start 28.269184 -227.045266)
		(end 28.513278 -227.045266)
		(width 0.14478)
		(layer "In11.Cu")
		(net "M_F_CPU1_SA_DQ<25>")
	)
	(segment
		(start 24.346154 -227.892864)
		(end 24.728678 -227.51034)
		(width 0.14478)
		(layer "In11.Cu")
		(net "M_F_CPU1_SA_DQ<25>")
	)
	(segment
		(start 51.46802 -226.660456)
		(end 53.111908 -226.660456)
		(width 0.14478)
		(layer "In11.Cu")
		(net "M_F_CPU1_SA_DQ<25>")
	)
	(segment
		(start 76.484226 -239.460024)
		(end 76.925932 -239.460024)
		(width 0.0889)
		(layer "In11.Cu")
		(net "M_F_CPU1_SA_DQ<25>")
	)
	(segment
		(start 33.869122 -227.673408)
		(end 34.03219 -227.51034)
		(width 0.14478)
		(layer "In11.Cu")
		(net "M_F_CPU1_SA_DQ<25>")
	)
	(segment
		(start 35.861498 -227.042726)
		(end 36.110672 -227.042726)
		(width 0.14478)
		(layer "In11.Cu")
		(net "M_F_CPU1_SA_DQ<25>")
	)
	(segment
		(start 41.33342 -227.891086)
		(end 41.48201 -227.742496)
		(width 0.14478)
		(layer "In11.Cu")
		(net "M_F_CPU1_SA_DQ<25>")
	)
	(segment
		(start 28.832556 -226.660456)
		(end 30.470856 -226.660456)
		(width 0.14478)
		(layer "In11.Cu")
		(net "M_F_CPU1_SA_DQ<25>")
	)
	(segment
		(start 41.48201 -227.742496)
		(end 41.48201 -227.673408)
		(width 0.14478)
		(layer "In11.Cu")
		(net "M_F_CPU1_SA_DQ<25>")
	)
	(segment
		(start 22.272498 -227.520246)
		(end 22.417278 -227.375466)
		(width 0.14478)
		(layer "In11.Cu")
		(net "M_F_CPU1_SA_DQ<25>")
	)
	(segment
		(start 33.869122 -227.742496)
		(end 33.869122 -227.673408)
		(width 0.14478)
		(layer "In11.Cu")
		(net "M_F_CPU1_SA_DQ<25>")
	)
	(segment
		(start 31.32074 -227.51034)
		(end 33.14954 -227.51034)
		(width 0.14478)
		(layer "In11.Cu")
		(net "M_F_CPU1_SA_DQ<25>")
	)
	(segment
		(start 25.753568 -227.673408)
		(end 25.753568 -227.734876)
		(width 0.14478)
		(layer "In11.Cu")
		(net "M_F_CPU1_SA_DQ<25>")
	)
	(segment
		(start 81.044034 -240.756948)
		(end 81.052416 -240.761774)
		(width 0.0889)
		(layer "In11.Cu")
		(net "M_F_CPU1_SA_DQ<25>")
	)
	(segment
		(start 40.925496 -227.742496)
		(end 41.074086 -227.891086)
		(width 0.14478)
		(layer "In11.Cu")
		(net "M_F_CPU1_SA_DQ<25>")
	)
	(segment
		(start 51.304952 -226.823524)
		(end 51.46802 -226.660456)
		(width 0.14478)
		(layer "In11.Cu")
		(net "M_F_CPU1_SA_DQ<25>")
	)
	(segment
		(start 33.312608 -227.673408)
		(end 33.312608 -227.742496)
		(width 0.14478)
		(layer "In11.Cu")
		(net "M_F_CPU1_SA_DQ<25>")
	)
	(segment
		(start 46.417738 -227.51034)
		(end 48.33366 -227.51034)
		(width 0.14478)
		(layer "In11.Cu")
		(net "M_F_CPU1_SA_DQ<25>")
	)
	(segment
		(start 25.916636 -227.897944)
		(end 26.147014 -227.897944)
		(width 0.14478)
		(layer "In11.Cu")
		(net "M_F_CPU1_SA_DQ<25>")
	)
	(segment
		(start 43.781726 -226.823524)
		(end 43.944794 -226.660456)
		(width 0.14478)
		(layer "In11.Cu")
		(net "M_F_CPU1_SA_DQ<25>")
	)
	(segment
		(start 23.78202 -227.375466)
		(end 23.9268 -227.520246)
		(width 0.14478)
		(layer "In11.Cu")
		(net "M_F_CPU1_SA_DQ<25>")
	)
	(segment
		(start 50.748438 -226.823524)
		(end 50.748438 -226.882706)
		(width 0.14478)
		(layer "In11.Cu")
		(net "M_F_CPU1_SA_DQ<25>")
	)
	(segment
		(start 24.728678 -227.51034)
		(end 25.5905 -227.51034)
		(width 0.14478)
		(layer "In11.Cu")
		(net "M_F_CPU1_SA_DQ<25>")
	)
	(segment
		(start 76.925932 -239.460024)
		(end 78.222856 -240.756948)
		(width 0.0889)
		(layer "In11.Cu")
		(net "M_F_CPU1_SA_DQ<25>")
	)
	(segment
		(start 43.062144 -226.660456)
		(end 43.225212 -226.823524)
		(width 0.14478)
		(layer "In11.Cu")
		(net "M_F_CPU1_SA_DQ<25>")
	)
	(segment
		(start 26.81478 -227.51034)
		(end 27.664664 -226.660456)
		(width 0.14478)
		(layer "In11.Cu")
		(net "M_F_CPU1_SA_DQ<25>")
	)
	(segment
		(start 78.57109 -240.77168)
		(end 78.597252 -240.756694)
		(width 0.0889)
		(layer "In11.Cu")
		(net "M_F_CPU1_SA_DQ<25>")
	)
	(segment
		(start 48.650398 -227.896166)
		(end 48.899572 -227.896166)
		(width 0.14478)
		(layer "In11.Cu")
		(net "M_F_CPU1_SA_DQ<25>")
	)
	(segment
		(start 79.16164 -240.756948)
		(end 79.176118 -240.76533)
		(width 0.0889)
		(layer "In11.Cu")
		(net "M_F_CPU1_SA_DQ<25>")
	)
	(segment
		(start 78.597252 -240.756694)
		(end 78.618842 -240.744248)
		(width 0.0889)
		(layer "In11.Cu")
		(net "M_F_CPU1_SA_DQ<25>")
	)
	(segment
		(start 22.417278 -227.375466)
		(end 22.679152 -227.375466)
		(width 0.14478)
		(layer "In11.Cu")
		(net "M_F_CPU1_SA_DQ<25>")
	)
	(segment
		(start 28.112974 -226.889056)
		(end 28.269184 -227.045266)
		(width 0.14478)
		(layer "In11.Cu")
		(net "M_F_CPU1_SA_DQ<25>")
	)
	(segment
		(start 50.58537 -226.660456)
		(end 50.748438 -226.823524)
		(width 0.14478)
		(layer "In11.Cu")
		(net "M_F_CPU1_SA_DQ<25>")
	)
	(segment
		(start 30.470856 -226.660456)
		(end 31.32074 -227.51034)
		(width 0.14478)
		(layer "In11.Cu")
		(net "M_F_CPU1_SA_DQ<25>")
	)
	(segment
		(start 33.312608 -227.742496)
		(end 33.463738 -227.893626)
		(width 0.14478)
		(layer "In11.Cu")
		(net "M_F_CPU1_SA_DQ<25>")
	)
	(segment
		(start 84.803996 -240.756948)
		(end 84.812378 -240.761774)
		(width 0.0889)
		(layer "In11.Cu")
		(net "M_F_CPU1_SA_DQ<25>")
	)
	(segment
		(start 43.383962 -227.047806)
		(end 43.622976 -227.047806)
		(width 0.14478)
		(layer "In11.Cu")
		(net "M_F_CPU1_SA_DQ<25>")
	)
	(segment
		(start 45.567854 -226.660456)
		(end 46.417738 -227.51034)
		(width 0.14478)
		(layer "In11.Cu")
		(net "M_F_CPU1_SA_DQ<25>")
	)
	(segment
		(start 49.21631 -227.51034)
		(end 49.448974 -227.51034)
		(width 0.14478)
		(layer "In11.Cu")
		(net "M_F_CPU1_SA_DQ<25>")
	)
	(segment
		(start 22.679152 -227.375466)
		(end 22.823932 -227.520246)
		(width 0.14478)
		(layer "In11.Cu")
		(net "M_F_CPU1_SA_DQ<25>")
	)
	(segment
		(start 22.823932 -227.520246)
		(end 22.823932 -227.748084)
		(width 0.14478)
		(layer "In11.Cu")
		(net "M_F_CPU1_SA_DQ<25>")
	)
	(segment
		(start 53.111908 -226.660456)
		(end 53.961792 -227.51034)
		(width 0.14478)
		(layer "In11.Cu")
		(net "M_F_CPU1_SA_DQ<25>")
	)
	(segment
		(start 36.110672 -227.042726)
		(end 36.264342 -226.889056)
		(width 0.14478)
		(layer "In11.Cu")
		(net "M_F_CPU1_SA_DQ<25>")
	)
	(segment
		(start 50.748438 -226.882706)
		(end 50.893218 -227.027486)
		(width 0.14478)
		(layer "In11.Cu")
		(net "M_F_CPU1_SA_DQ<25>")
	)
	(segment
		(start 34.383218 -227.51034)
		(end 35.233102 -226.660456)
		(width 0.14478)
		(layer "In11.Cu")
		(net "M_F_CPU1_SA_DQ<25>")
	)
	(segment
		(start 41.645078 -227.51034)
		(end 41.94302 -227.51034)
		(width 0.14478)
		(layer "In11.Cu")
		(net "M_F_CPU1_SA_DQ<25>")
	)
	(segment
		(start 43.622976 -227.047806)
		(end 43.781726 -226.889056)
		(width 0.14478)
		(layer "In11.Cu")
		(net "M_F_CPU1_SA_DQ<25>")
	)
	(segment
		(start 48.496728 -227.673408)
		(end 48.496728 -227.742496)
		(width 0.14478)
		(layer "In11.Cu")
		(net "M_F_CPU1_SA_DQ<25>")
	)
	(segment
		(start 41.94302 -227.51034)
		(end 42.792904 -226.660456)
		(width 0.14478)
		(layer "In11.Cu")
		(net "M_F_CPU1_SA_DQ<25>")
	)
	(segment
		(start 26.47315 -227.51034)
		(end 26.81478 -227.51034)
		(width 0.14478)
		(layer "In11.Cu")
		(net "M_F_CPU1_SA_DQ<25>")
	)
	(segment
		(start 25.753568 -227.734876)
		(end 25.916636 -227.897944)
		(width 0.14478)
		(layer "In11.Cu")
		(net "M_F_CPU1_SA_DQ<25>")
	)
	(segment
		(start 21.85289 -227.892864)
		(end 22.127718 -227.892864)
		(width 0.14478)
		(layer "In11.Cu")
		(net "M_F_CPU1_SA_DQ<25>")
	)
	(segment
		(start 35.233102 -226.660456)
		(end 35.54476 -226.660456)
		(width 0.14478)
		(layer "In11.Cu")
		(net "M_F_CPU1_SA_DQ<25>")
	)
	(segment
		(start 33.717992 -227.893626)
		(end 33.869122 -227.742496)
		(width 0.14478)
		(layer "In11.Cu")
		(net "M_F_CPU1_SA_DQ<25>")
	)
	(segment
		(start 21.70811 -227.748084)
		(end 21.85289 -227.892864)
		(width 0.14478)
		(layer "In11.Cu")
		(net "M_F_CPU1_SA_DQ<25>")
	)
	(segment
		(start 85.681058 -240.725198)
		(end 85.77707 -240.699798)
		(width 0.0889)
		(layer "In11.Cu")
		(net "M_F_CPU1_SA_DQ<25>")
	)
	(segment
		(start 51.304952 -226.882706)
		(end 51.304952 -226.823524)
		(width 0.14478)
		(layer "In11.Cu")
		(net "M_F_CPU1_SA_DQ<25>")
	)
	(segment
		(start 43.225212 -226.823524)
		(end 43.225212 -226.889056)
		(width 0.14478)
		(layer "In11.Cu")
		(net "M_F_CPU1_SA_DQ<25>")
	)
	(segment
		(start 23.375366 -227.520246)
		(end 23.520146 -227.375466)
		(width 0.14478)
		(layer "In11.Cu")
		(net "M_F_CPU1_SA_DQ<25>")
	)
	(segment
		(start 43.225212 -226.889056)
		(end 43.383962 -227.047806)
		(width 0.14478)
		(layer "In11.Cu")
		(net "M_F_CPU1_SA_DQ<25>")
	)
	(segment
		(start 26.310082 -227.673408)
		(end 26.47315 -227.51034)
		(width 0.14478)
		(layer "In11.Cu")
		(net "M_F_CPU1_SA_DQ<25>")
	)
	(segment
		(start 21.70811 -227.085398)
		(end 21.70811 -227.748084)
		(width 0.14478)
		(layer "In11.Cu")
		(net "M_F_CPU1_SA_DQ<25>")
	)
	(segment
		(start 26.147014 -227.897944)
		(end 26.310082 -227.734876)
		(width 0.14478)
		(layer "In11.Cu")
		(net "M_F_CPU1_SA_DQ<25>")
	)
	(segment
		(start 23.520146 -227.375466)
		(end 23.78202 -227.375466)
		(width 0.14478)
		(layer "In11.Cu")
		(net "M_F_CPU1_SA_DQ<25>")
	)
	(segment
		(start 35.54476 -226.660456)
		(end 35.707828 -226.823524)
		(width 0.14478)
		(layer "In11.Cu")
		(net "M_F_CPU1_SA_DQ<25>")
	)
	(segment
		(start 59.0042 -227.035106)
		(end 71.332598 -239.363504)
		(width 0.14478)
		(layer "In11.Cu")
		(net "M_F_CPU1_SA_DQ<25>")
	)
	(segment
		(start 80.080612 -240.743232)
		(end 80.10398 -240.756948)
		(width 0.0889)
		(layer "In11.Cu")
		(net "M_F_CPU1_SA_DQ<25>")
	)
	(segment
		(start 23.9268 -227.520246)
		(end 23.9268 -227.748084)
		(width 0.14478)
		(layer "In11.Cu")
		(net "M_F_CPU1_SA_DQ<25>")
	)
	(segment
		(start 26.310082 -227.734876)
		(end 26.310082 -227.673408)
		(width 0.14478)
		(layer "In11.Cu")
		(net "M_F_CPU1_SA_DQ<25>")
	)
	(segment
		(start 25.5905 -227.51034)
		(end 25.753568 -227.673408)
		(width 0.14478)
		(layer "In11.Cu")
		(net "M_F_CPU1_SA_DQ<25>")
	)
	(segment
		(start 22.823932 -227.748084)
		(end 22.968712 -227.892864)
		(width 0.14478)
		(layer "In11.Cu")
		(net "M_F_CPU1_SA_DQ<25>")
	)
	(segment
		(start 43.781726 -226.889056)
		(end 43.781726 -226.823524)
		(width 0.14478)
		(layer "In11.Cu")
		(net "M_F_CPU1_SA_DQ<25>")
	)
	(segment
		(start 28.669488 -226.823524)
		(end 28.832556 -226.660456)
		(width 0.14478)
		(layer "In11.Cu")
		(net "M_F_CPU1_SA_DQ<25>")
	)
	(segment
		(start 27.664664 -226.660456)
		(end 27.949906 -226.660456)
		(width 0.14478)
		(layer "In11.Cu")
		(net "M_F_CPU1_SA_DQ<25>")
	)
	(segment
		(start 22.272498 -227.748084)
		(end 22.272498 -227.520246)
		(width 0.14478)
		(layer "In11.Cu")
		(net "M_F_CPU1_SA_DQ<25>")
	)
	(segment
		(start 28.513278 -227.045266)
		(end 28.669488 -226.889056)
		(width 0.14478)
		(layer "In11.Cu")
		(net "M_F_CPU1_SA_DQ<25>")
	)
	(segment
		(start 35.707828 -226.823524)
		(end 35.707828 -226.889056)
		(width 0.14478)
		(layer "In11.Cu")
		(net "M_F_CPU1_SA_DQ<25>")
	)
	(segment
		(start 49.053242 -227.673408)
		(end 49.21631 -227.51034)
		(width 0.14478)
		(layer "In11.Cu")
		(net "M_F_CPU1_SA_DQ<25>")
	)
	(segment
		(start 33.14954 -227.51034)
		(end 33.312608 -227.673408)
		(width 0.14478)
		(layer "In11.Cu")
		(net "M_F_CPU1_SA_DQ<25>")
	)
	(segment
		(start 41.074086 -227.891086)
		(end 41.33342 -227.891086)
		(width 0.14478)
		(layer "In11.Cu")
		(net "M_F_CPU1_SA_DQ<25>")
	)
	(segment
		(start 28.669488 -226.889056)
		(end 28.669488 -226.823524)
		(width 0.14478)
		(layer "In11.Cu")
		(net "M_F_CPU1_SA_DQ<25>")
	)
	(segment
		(start 35.707828 -226.889056)
		(end 35.861498 -227.042726)
		(width 0.14478)
		(layer "In11.Cu")
		(net "M_F_CPU1_SA_DQ<25>")
	)
	(segment
		(start 51.160172 -227.027486)
		(end 51.304952 -226.882706)
		(width 0.14478)
		(layer "In11.Cu")
		(net "M_F_CPU1_SA_DQ<25>")
	)
	(segment
		(start 27.949906 -226.660456)
		(end 28.112974 -226.823524)
		(width 0.14478)
		(layer "In11.Cu")
		(net "M_F_CPU1_SA_DQ<25>")
	)
	(segment
		(start 33.463738 -227.893626)
		(end 33.717992 -227.893626)
		(width 0.14478)
		(layer "In11.Cu")
		(net "M_F_CPU1_SA_DQ<25>")
	)
	(segment
		(start 24.07158 -227.892864)
		(end 24.346154 -227.892864)
		(width 0.14478)
		(layer "In11.Cu")
		(net "M_F_CPU1_SA_DQ<25>")
	)
	(segment
		(start 80.46974 -240.761774)
		(end 80.478122 -240.756948)
		(width 0.0889)
		(layer "In11.Cu")
		(net "M_F_CPU1_SA_DQ<25>")
	)
	(segment
		(start 49.448974 -227.51034)
		(end 50.298858 -226.660456)
		(width 0.14478)
		(layer "In11.Cu")
		(net "M_F_CPU1_SA_DQ<25>")
	)
	(segment
		(start 23.230586 -227.892864)
		(end 23.375366 -227.748084)
		(width 0.14478)
		(layer "In11.Cu")
		(net "M_F_CPU1_SA_DQ<25>")
	)
	(segment
		(start 42.792904 -226.660456)
		(end 43.062144 -226.660456)
		(width 0.14478)
		(layer "In11.Cu")
		(net "M_F_CPU1_SA_DQ<25>")
	)
	(segment
		(start 48.899572 -227.896166)
		(end 49.053242 -227.742496)
		(width 0.14478)
		(layer "In11.Cu")
		(net "M_F_CPU1_SA_DQ<25>")
	)
	(segment
		(start 36.42741 -226.660456)
		(end 37.95268 -226.660456)
		(width 0.14478)
		(layer "In11.Cu")
		(net "M_F_CPU1_SA_DQ<25>")
	)
	(segment
		(start 57.429908 -227.035106)
		(end 59.0042 -227.035106)
		(width 0.14478)
		(layer "In11.Cu")
		(net "M_F_CPU1_SA_DQ<25>")
	)
	(segment
		(start 49.053242 -227.742496)
		(end 49.053242 -227.673408)
		(width 0.14478)
		(layer "In11.Cu")
		(net "M_F_CPU1_SA_DQ<25>")
	)
	(segment
		(start 22.968712 -227.892864)
		(end 23.230586 -227.892864)
		(width 0.14478)
		(layer "In11.Cu")
		(net "M_F_CPU1_SA_DQ<25>")
	)
	(segment
		(start 76.387706 -239.363504)
		(end 76.484226 -239.460024)
		(width 0.0889)
		(layer "In11.Cu")
		(net "M_F_CPU1_SA_DQ<25>")
	)
	(segment
		(start 84.229702 -240.761774)
		(end 84.238084 -240.756948)
		(width 0.0889)
		(layer "In11.Cu")
		(net "M_F_CPU1_SA_DQ<25>")
	)
	(segment
		(start 23.375366 -227.748084)
		(end 23.375366 -227.520246)
		(width 0.14478)
		(layer "In11.Cu")
		(net "M_F_CPU1_SA_DQ<25>")
	)
	(segment
		(start 85.77707 -240.699798)
		(end 85.930994 -240.434368)
		(width 0.0889)
		(layer "In11.Cu")
		(net "M_F_CPU1_SA_DQ<25>")
	)
	(segment
		(start 40.925496 -227.673408)
		(end 40.925496 -227.742496)
		(width 0.14478)
		(layer "In11.Cu")
		(net "M_F_CPU1_SA_DQ<25>")
	)
	(segment
		(start 40.762428 -227.51034)
		(end 40.925496 -227.673408)
		(width 0.14478)
		(layer "In11.Cu")
		(net "M_F_CPU1_SA_DQ<25>")
	)
	(segment
		(start 50.298858 -226.660456)
		(end 50.58537 -226.660456)
		(width 0.14478)
		(layer "In11.Cu")
		(net "M_F_CPU1_SA_DQ<25>")
	)
	(segment
		(start 34.03219 -227.51034)
		(end 34.383218 -227.51034)
		(width 0.14478)
		(layer "In11.Cu")
		(net "M_F_CPU1_SA_DQ<25>")
	)
	(segment
		(start 28.112974 -226.823524)
		(end 28.112974 -226.889056)
		(width 0.14478)
		(layer "In11.Cu")
		(net "M_F_CPU1_SA_DQ<25>")
	)
	(segment
		(start 75.988926 -239.363504)
		(end 76.387706 -239.363504)
		(width 0.0889)
		(layer "In11.Cu")
		(net "M_F_CPU1_SA_DQ<25>")
	)
	(segment
		(start 50.893218 -227.027486)
		(end 51.160172 -227.027486)
		(width 0.14478)
		(layer "In11.Cu")
		(net "M_F_CPU1_SA_DQ<25>")
	)
	(segment
		(start 37.95268 -226.660456)
		(end 38.802564 -227.51034)
		(width 0.14478)
		(layer "In11.Cu")
		(net "M_F_CPU1_SA_DQ<25>")
	)
	(segment
		(start 23.9268 -227.748084)
		(end 24.07158 -227.892864)
		(width 0.14478)
		(layer "In11.Cu")
		(net "M_F_CPU1_SA_DQ<25>")
	)
	(segment
		(start 36.264342 -226.823524)
		(end 36.42741 -226.660456)
		(width 0.14478)
		(layer "In11.Cu")
		(net "M_F_CPU1_SA_DQ<25>")
	)
	(segment
		(start 38.802564 -227.51034)
		(end 40.762428 -227.51034)
		(width 0.14478)
		(layer "In11.Cu")
		(net "M_F_CPU1_SA_DQ<25>")
	)
	(segment
		(start 43.944794 -226.660456)
		(end 45.567854 -226.660456)
		(width 0.14478)
		(layer "In11.Cu")
		(net "M_F_CPU1_SA_DQ<25>")
	)
	(segment
		(start 41.48201 -227.673408)
		(end 41.645078 -227.51034)
		(width 0.14478)
		(layer "In11.Cu")
		(net "M_F_CPU1_SA_DQ<25>")
	)
	(segment
		(start 36.264342 -226.889056)
		(end 36.264342 -226.823524)
		(width 0.14478)
		(layer "In11.Cu")
		(net "M_F_CPU1_SA_DQ<25>")
	)
	(segment
		(start 53.961792 -227.51034)
		(end 56.954674 -227.51034)
		(width 0.14478)
		(layer "In11.Cu")
		(net "M_F_CPU1_SA_DQ<25>")
	)
	(segment
		(start 22.127718 -227.892864)
		(end 22.272498 -227.748084)
		(width 0.14478)
		(layer "In11.Cu")
		(net "M_F_CPU1_SA_DQ<25>")
	)
	(segment
		(start 56.954674 -227.51034)
		(end 57.429908 -227.035106)
		(width 0.14478)
		(layer "In11.Cu")
		(net "M_F_CPU1_SA_DQ<25>")
	)
	(segment
		(start 48.496728 -227.742496)
		(end 48.650398 -227.896166)
		(width 0.14478)
		(layer "In11.Cu")
		(net "M_F_CPU1_SA_DQ<25>")
	)
	(segment
		(start 83.289648 -240.761774)
		(end 83.29803 -240.756948)
		(width 0.0889)
		(layer "In11.Cu")
		(net "M_F_CPU1_SA_DQ<25>")
	)
	(arc
		(start 82.357976 -240.756948)
		(mid 82.640932 -240.680771)
		(end 82.923888 -240.756948)
		(width 0.0889)
		(layer "In11.Cu")
		(net "M_F_CPU1_SA_DQ<25>")
	)
	(arc
		(start 81.984088 -240.756948)
		(mid 82.171032 -240.807203)
		(end 82.357976 -240.756948)
		(width 0.0889)
		(layer "In11.Cu")
		(net "M_F_CPU1_SA_DQ<25>")
	)
	(arc
		(start 84.812378 -240.761774)
		(mid 84.995886 -240.807268)
		(end 85.178138 -240.756948)
		(width 0.0889)
		(layer "In11.Cu")
		(net "M_F_CPU1_SA_DQ<25>")
	)
	(arc
		(start 80.478122 -240.756948)
		(mid 80.761078 -240.680771)
		(end 81.044034 -240.756948)
		(width 0.0889)
		(layer "In11.Cu")
		(net "M_F_CPU1_SA_DQ<25>")
	)
	(arc
		(start 83.29803 -240.756948)
		(mid 83.580986 -240.680771)
		(end 83.863942 -240.756948)
		(width 0.0889)
		(layer "In11.Cu")
		(net "M_F_CPU1_SA_DQ<25>")
	)
	(arc
		(start 82.923888 -240.756948)
		(mid 83.106139 -240.807298)
		(end 83.289648 -240.761774)
		(width 0.0889)
		(layer "In11.Cu")
		(net "M_F_CPU1_SA_DQ<25>")
	)
	(arc
		(start 81.418176 -240.756948)
		(mid 81.701132 -240.680771)
		(end 81.984088 -240.756948)
		(width 0.0889)
		(layer "In11.Cu")
		(net "M_F_CPU1_SA_DQ<25>")
	)
	(arc
		(start 80.10398 -240.756948)
		(mid 80.286231 -240.807298)
		(end 80.46974 -240.761774)
		(width 0.0889)
		(layer "In11.Cu")
		(net "M_F_CPU1_SA_DQ<25>")
	)
	(arc
		(start 78.618842 -240.744248)
		(mid 78.891871 -240.680929)
		(end 79.16164 -240.756948)
		(width 0.0889)
		(layer "In11.Cu")
		(net "M_F_CPU1_SA_DQ<25>")
	)
	(arc
		(start 81.052416 -240.761774)
		(mid 81.235924 -240.807268)
		(end 81.418176 -240.756948)
		(width 0.0889)
		(layer "In11.Cu")
		(net "M_F_CPU1_SA_DQ<25>")
	)
	(arc
		(start 78.222856 -240.756948)
		(mid 78.395138 -240.807384)
		(end 78.57109 -240.77168)
		(width 0.0889)
		(layer "In11.Cu")
		(net "M_F_CPU1_SA_DQ<25>")
	)
	(arc
		(start 84.238084 -240.756948)
		(mid 84.52104 -240.680771)
		(end 84.803996 -240.756948)
		(width 0.0889)
		(layer "In11.Cu")
		(net "M_F_CPU1_SA_DQ<25>")
	)
	(arc
		(start 85.178138 -240.756948)
		(mid 85.425851 -240.681728)
		(end 85.681058 -240.725198)
		(width 0.0889)
		(layer "In11.Cu")
		(net "M_F_CPU1_SA_DQ<25>")
	)
	(arc
		(start 79.176118 -240.76533)
		(mid 79.357534 -240.807587)
		(end 79.536798 -240.756948)
		(width 0.0889)
		(layer "In11.Cu")
		(net "M_F_CPU1_SA_DQ<25>")
	)
	(arc
		(start 79.536798 -240.756948)
		(mid 79.806955 -240.680186)
		(end 80.080612 -240.743232)
		(width 0.0889)
		(layer "In11.Cu")
		(net "M_F_CPU1_SA_DQ<25>")
	)
	(arc
		(start 83.863942 -240.756948)
		(mid 84.046193 -240.807298)
		(end 84.229702 -240.761774)
		(width 0.0889)
		(layer "In11.Cu")
		(net "M_F_CPU1_SA_DQ<25>")
	)
	(segment
		(start 84.987892 -239.8903)
		(end 84.52104 -239.624362)
		(width 0.10668)
		(layer "F.Cu")
		(net "M_F_CPU1_SA_DQ<24>")
	)
	(segment
		(start 43.847512 -225.182176)
		(end 43.847512 -225.123502)
		(width 0.14478)
		(layer "In11.Cu")
		(net "M_F_CPU1_SA_DQ<24>")
	)
	(segment
		(start 58.553858 -226.019106)
		(end 58.815732 -226.019106)
		(width 0.14478)
		(layer "In11.Cu")
		(net "M_F_CPU1_SA_DQ<24>")
	)
	(segment
		(start 50.561748 -224.960434)
		(end 50.724816 -225.123502)
		(width 0.14478)
		(layer "In11.Cu")
		(net "M_F_CPU1_SA_DQ<24>")
	)
	(segment
		(start 41.662858 -225.810318)
		(end 41.94302 -225.810318)
		(width 0.14478)
		(layer "In11.Cu")
		(net "M_F_CPU1_SA_DQ<24>")
	)
	(segment
		(start 54.68239 -225.973386)
		(end 54.68239 -226.035616)
		(width 0.14478)
		(layer "In11.Cu")
		(net "M_F_CPU1_SA_DQ<24>")
	)
	(segment
		(start 41.106344 -226.193604)
		(end 41.336722 -226.193604)
		(width 0.14478)
		(layer "In11.Cu")
		(net "M_F_CPU1_SA_DQ<24>")
	)
	(segment
		(start 48.689514 -226.198684)
		(end 48.919892 -226.198684)
		(width 0.14478)
		(layer "In11.Cu")
		(net "M_F_CPU1_SA_DQ<24>")
	)
	(segment
		(start 41.336722 -226.193604)
		(end 41.49979 -226.030536)
		(width 0.14478)
		(layer "In11.Cu")
		(net "M_F_CPU1_SA_DQ<24>")
	)
	(segment
		(start 48.919892 -226.198684)
		(end 49.08296 -226.035616)
		(width 0.14478)
		(layer "In11.Cu")
		(net "M_F_CPU1_SA_DQ<24>")
	)
	(segment
		(start 30.470856 -224.960434)
		(end 31.32074 -225.810318)
		(width 0.14478)
		(layer "In11.Cu")
		(net "M_F_CPU1_SA_DQ<24>")
	)
	(segment
		(start 28.705302 -225.192336)
		(end 28.705302 -225.123502)
		(width 0.14478)
		(layer "In11.Cu")
		(net "M_F_CPU1_SA_DQ<24>")
	)
	(segment
		(start 43.290998 -225.123502)
		(end 43.290998 -225.182176)
		(width 0.14478)
		(layer "In11.Cu")
		(net "M_F_CPU1_SA_DQ<24>")
	)
	(segment
		(start 33.848294 -226.035616)
		(end 33.848294 -225.973386)
		(width 0.14478)
		(layer "In11.Cu")
		(net "M_F_CPU1_SA_DQ<24>")
	)
	(segment
		(start 35.88893 -225.350324)
		(end 36.119308 -225.350324)
		(width 0.14478)
		(layer "In11.Cu")
		(net "M_F_CPU1_SA_DQ<24>")
	)
	(segment
		(start 51.444398 -224.960434)
		(end 53.111908 -224.960434)
		(width 0.14478)
		(layer "In11.Cu")
		(net "M_F_CPU1_SA_DQ<24>")
	)
	(segment
		(start 50.887884 -225.345244)
		(end 51.118262 -225.345244)
		(width 0.14478)
		(layer "In11.Cu")
		(net "M_F_CPU1_SA_DQ<24>")
	)
	(segment
		(start 51.28133 -225.182176)
		(end 51.28133 -225.123502)
		(width 0.14478)
		(layer "In11.Cu")
		(net "M_F_CPU1_SA_DQ<24>")
	)
	(segment
		(start 55.401972 -225.810318)
		(end 55.63235 -225.810318)
		(width 0.14478)
		(layer "In11.Cu")
		(net "M_F_CPU1_SA_DQ<24>")
	)
	(segment
		(start 45.567854 -224.960434)
		(end 46.417738 -225.810318)
		(width 0.14478)
		(layer "In11.Cu")
		(net "M_F_CPU1_SA_DQ<24>")
	)
	(segment
		(start 56.188864 -226.198684)
		(end 56.351932 -226.035616)
		(width 0.14478)
		(layer "In11.Cu")
		(net "M_F_CPU1_SA_DQ<24>")
	)
	(segment
		(start 75.933046 -238.449104)
		(end 76.428346 -238.449104)
		(width 0.0889)
		(layer "In11.Cu")
		(net "M_F_CPU1_SA_DQ<24>")
	)
	(segment
		(start 36.282376 -225.187256)
		(end 36.282376 -225.123502)
		(width 0.14478)
		(layer "In11.Cu")
		(net "M_F_CPU1_SA_DQ<24>")
	)
	(segment
		(start 27.98572 -224.960434)
		(end 28.148788 -225.123502)
		(width 0.14478)
		(layer "In11.Cu")
		(net "M_F_CPU1_SA_DQ<24>")
	)
	(segment
		(start 26.81478 -225.810318)
		(end 27.664664 -224.960434)
		(width 0.14478)
		(layer "In11.Cu")
		(net "M_F_CPU1_SA_DQ<24>")
	)
	(segment
		(start 35.725862 -225.123502)
		(end 35.725862 -225.187256)
		(width 0.14478)
		(layer "In11.Cu")
		(net "M_F_CPU1_SA_DQ<24>")
	)
	(segment
		(start 35.233102 -224.960434)
		(end 35.562794 -224.960434)
		(width 0.14478)
		(layer "In11.Cu")
		(net "M_F_CPU1_SA_DQ<24>")
	)
	(segment
		(start 35.562794 -224.960434)
		(end 35.725862 -225.123502)
		(width 0.14478)
		(layer "In11.Cu")
		(net "M_F_CPU1_SA_DQ<24>")
	)
	(segment
		(start 28.705302 -225.123502)
		(end 28.86837 -224.960434)
		(width 0.14478)
		(layer "In11.Cu")
		(net "M_F_CPU1_SA_DQ<24>")
	)
	(segment
		(start 50.724816 -225.123502)
		(end 50.724816 -225.182176)
		(width 0.14478)
		(layer "In11.Cu")
		(net "M_F_CPU1_SA_DQ<24>")
	)
	(segment
		(start 41.49979 -226.030536)
		(end 41.49979 -225.973386)
		(width 0.14478)
		(layer "In11.Cu")
		(net "M_F_CPU1_SA_DQ<24>")
	)
	(segment
		(start 57.857644 -225.874326)
		(end 57.857644 -225.656394)
		(width 0.14478)
		(layer "In11.Cu")
		(net "M_F_CPU1_SA_DQ<24>")
	)
	(segment
		(start 55.958486 -226.198684)
		(end 56.188864 -226.198684)
		(width 0.14478)
		(layer "In11.Cu")
		(net "M_F_CPU1_SA_DQ<24>")
	)
	(segment
		(start 43.454066 -225.345244)
		(end 43.684444 -225.345244)
		(width 0.14478)
		(layer "In11.Cu")
		(net "M_F_CPU1_SA_DQ<24>")
	)
	(segment
		(start 48.526446 -226.035616)
		(end 48.689514 -226.198684)
		(width 0.14478)
		(layer "In11.Cu")
		(net "M_F_CPU1_SA_DQ<24>")
	)
	(segment
		(start 35.725862 -225.187256)
		(end 35.88893 -225.350324)
		(width 0.14478)
		(layer "In11.Cu")
		(net "M_F_CPU1_SA_DQ<24>")
	)
	(segment
		(start 33.128712 -225.810318)
		(end 33.29178 -225.973386)
		(width 0.14478)
		(layer "In11.Cu")
		(net "M_F_CPU1_SA_DQ<24>")
	)
	(segment
		(start 79.622396 -239.93983)
		(end 79.634334 -239.946688)
		(width 0.0889)
		(layer "In11.Cu")
		(net "M_F_CPU1_SA_DQ<24>")
	)
	(segment
		(start 54.845458 -226.198684)
		(end 55.075836 -226.198684)
		(width 0.14478)
		(layer "In11.Cu")
		(net "M_F_CPU1_SA_DQ<24>")
	)
	(segment
		(start 25.735788 -226.038156)
		(end 25.898856 -226.201224)
		(width 0.14478)
		(layer "In11.Cu")
		(net "M_F_CPU1_SA_DQ<24>")
	)
	(segment
		(start 44.01058 -224.960434)
		(end 45.567854 -224.960434)
		(width 0.14478)
		(layer "In11.Cu")
		(net "M_F_CPU1_SA_DQ<24>")
	)
	(segment
		(start 23.134574 -226.210876)
		(end 23.366984 -225.978466)
		(width 0.14478)
		(layer "In11.Cu")
		(net "M_F_CPU1_SA_DQ<24>")
	)
	(segment
		(start 26.292302 -226.038156)
		(end 26.292302 -225.973386)
		(width 0.14478)
		(layer "In11.Cu")
		(net "M_F_CPU1_SA_DQ<24>")
	)
	(segment
		(start 36.445444 -224.960434)
		(end 37.95268 -224.960434)
		(width 0.14478)
		(layer "In11.Cu")
		(net "M_F_CPU1_SA_DQ<24>")
	)
	(segment
		(start 58.002424 -225.511614)
		(end 58.264298 -225.511614)
		(width 0.14478)
		(layer "In11.Cu")
		(net "M_F_CPU1_SA_DQ<24>")
	)
	(segment
		(start 53.111908 -224.960434)
		(end 53.961792 -225.810318)
		(width 0.14478)
		(layer "In11.Cu")
		(net "M_F_CPU1_SA_DQ<24>")
	)
	(segment
		(start 36.119308 -225.350324)
		(end 36.282376 -225.187256)
		(width 0.14478)
		(layer "In11.Cu")
		(net "M_F_CPU1_SA_DQ<24>")
	)
	(segment
		(start 54.68239 -226.035616)
		(end 54.845458 -226.198684)
		(width 0.14478)
		(layer "In11.Cu")
		(net "M_F_CPU1_SA_DQ<24>")
	)
	(segment
		(start 55.075836 -226.198684)
		(end 55.238904 -226.035616)
		(width 0.14478)
		(layer "In11.Cu")
		(net "M_F_CPU1_SA_DQ<24>")
	)
	(segment
		(start 57.30621 -225.874326)
		(end 57.45099 -226.019106)
		(width 0.14478)
		(layer "In11.Cu")
		(net "M_F_CPU1_SA_DQ<24>")
	)
	(segment
		(start 25.898856 -226.201224)
		(end 26.129234 -226.201224)
		(width 0.14478)
		(layer "In11.Cu")
		(net "M_F_CPU1_SA_DQ<24>")
	)
	(segment
		(start 55.795418 -226.035616)
		(end 55.958486 -226.198684)
		(width 0.14478)
		(layer "In11.Cu")
		(net "M_F_CPU1_SA_DQ<24>")
	)
	(segment
		(start 28.148788 -225.192336)
		(end 28.311856 -225.355404)
		(width 0.14478)
		(layer "In11.Cu")
		(net "M_F_CPU1_SA_DQ<24>")
	)
	(segment
		(start 59.524392 -225.511614)
		(end 59.86907 -225.856292)
		(width 0.14478)
		(layer "In11.Cu")
		(net "M_F_CPU1_SA_DQ<24>")
	)
	(segment
		(start 56.351932 -225.656394)
		(end 56.496712 -225.511614)
		(width 0.14478)
		(layer "In11.Cu")
		(net "M_F_CPU1_SA_DQ<24>")
	)
	(segment
		(start 84.271104 -239.915192)
		(end 84.367116 -239.889792)
		(width 0.0889)
		(layer "In11.Cu")
		(net "M_F_CPU1_SA_DQ<24>")
	)
	(segment
		(start 55.63235 -225.810318)
		(end 55.795418 -225.973386)
		(width 0.14478)
		(layer "In11.Cu")
		(net "M_F_CPU1_SA_DQ<24>")
	)
	(segment
		(start 36.282376 -225.123502)
		(end 36.445444 -224.960434)
		(width 0.14478)
		(layer "In11.Cu")
		(net "M_F_CPU1_SA_DQ<24>")
	)
	(segment
		(start 28.311856 -225.355404)
		(end 28.542234 -225.355404)
		(width 0.14478)
		(layer "In11.Cu")
		(net "M_F_CPU1_SA_DQ<24>")
	)
	(segment
		(start 43.290998 -225.182176)
		(end 43.454066 -225.345244)
		(width 0.14478)
		(layer "In11.Cu")
		(net "M_F_CPU1_SA_DQ<24>")
	)
	(segment
		(start 50.298858 -224.960434)
		(end 50.561748 -224.960434)
		(width 0.14478)
		(layer "In11.Cu")
		(net "M_F_CPU1_SA_DQ<24>")
	)
	(segment
		(start 28.86837 -224.960434)
		(end 30.470856 -224.960434)
		(width 0.14478)
		(layer "In11.Cu")
		(net "M_F_CPU1_SA_DQ<24>")
	)
	(segment
		(start 59.86907 -225.856292)
		(end 59.86907 -226.535996)
		(width 0.14478)
		(layer "In11.Cu")
		(net "M_F_CPU1_SA_DQ<24>")
	)
	(segment
		(start 48.526446 -225.973386)
		(end 48.526446 -226.035616)
		(width 0.14478)
		(layer "In11.Cu")
		(net "M_F_CPU1_SA_DQ<24>")
	)
	(segment
		(start 34.383218 -225.810318)
		(end 35.233102 -224.960434)
		(width 0.14478)
		(layer "In11.Cu")
		(net "M_F_CPU1_SA_DQ<24>")
	)
	(segment
		(start 28.148788 -225.123502)
		(end 28.148788 -225.192336)
		(width 0.14478)
		(layer "In11.Cu")
		(net "M_F_CPU1_SA_DQ<24>")
	)
	(segment
		(start 57.45099 -226.019106)
		(end 57.712864 -226.019106)
		(width 0.14478)
		(layer "In11.Cu")
		(net "M_F_CPU1_SA_DQ<24>")
	)
	(segment
		(start 40.943276 -226.030536)
		(end 41.106344 -226.193604)
		(width 0.14478)
		(layer "In11.Cu")
		(net "M_F_CPU1_SA_DQ<24>")
	)
	(segment
		(start 40.780208 -225.810318)
		(end 40.943276 -225.973386)
		(width 0.14478)
		(layer "In11.Cu")
		(net "M_F_CPU1_SA_DQ<24>")
	)
	(segment
		(start 25.57272 -225.810318)
		(end 25.735788 -225.973386)
		(width 0.14478)
		(layer "In11.Cu")
		(net "M_F_CPU1_SA_DQ<24>")
	)
	(segment
		(start 25.735788 -225.973386)
		(end 25.735788 -226.038156)
		(width 0.14478)
		(layer "In11.Cu")
		(net "M_F_CPU1_SA_DQ<24>")
	)
	(segment
		(start 34.011362 -225.810318)
		(end 34.383218 -225.810318)
		(width 0.14478)
		(layer "In11.Cu")
		(net "M_F_CPU1_SA_DQ<24>")
	)
	(segment
		(start 43.847512 -225.123502)
		(end 44.01058 -224.960434)
		(width 0.14478)
		(layer "In11.Cu")
		(net "M_F_CPU1_SA_DQ<24>")
	)
	(segment
		(start 38.802564 -225.810318)
		(end 40.780208 -225.810318)
		(width 0.14478)
		(layer "In11.Cu")
		(net "M_F_CPU1_SA_DQ<24>")
	)
	(segment
		(start 57.16143 -225.511614)
		(end 57.30621 -225.656394)
		(width 0.14478)
		(layer "In11.Cu")
		(net "M_F_CPU1_SA_DQ<24>")
	)
	(segment
		(start 76.629006 -238.649764)
		(end 76.945744 -238.649764)
		(width 0.0889)
		(layer "In11.Cu")
		(net "M_F_CPU1_SA_DQ<24>")
	)
	(segment
		(start 26.292302 -225.973386)
		(end 26.45537 -225.810318)
		(width 0.14478)
		(layer "In11.Cu")
		(net "M_F_CPU1_SA_DQ<24>")
	)
	(segment
		(start 79.634334 -239.946688)
		(end 79.65059 -239.956086)
		(width 0.0889)
		(layer "In11.Cu")
		(net "M_F_CPU1_SA_DQ<24>")
	)
	(segment
		(start 55.238904 -225.973386)
		(end 55.401972 -225.810318)
		(width 0.14478)
		(layer "In11.Cu")
		(net "M_F_CPU1_SA_DQ<24>")
	)
	(segment
		(start 50.724816 -225.182176)
		(end 50.887884 -225.345244)
		(width 0.14478)
		(layer "In11.Cu")
		(net "M_F_CPU1_SA_DQ<24>")
	)
	(segment
		(start 48.363378 -225.810318)
		(end 48.526446 -225.973386)
		(width 0.14478)
		(layer "In11.Cu")
		(net "M_F_CPU1_SA_DQ<24>")
	)
	(segment
		(start 58.960512 -225.656394)
		(end 59.105292 -225.511614)
		(width 0.14478)
		(layer "In11.Cu")
		(net "M_F_CPU1_SA_DQ<24>")
	)
	(segment
		(start 22.271482 -226.210876)
		(end 23.134574 -226.210876)
		(width 0.14478)
		(layer "In11.Cu")
		(net "M_F_CPU1_SA_DQ<24>")
	)
	(segment
		(start 33.685226 -226.198684)
		(end 33.848294 -226.035616)
		(width 0.14478)
		(layer "In11.Cu")
		(net "M_F_CPU1_SA_DQ<24>")
	)
	(segment
		(start 51.118262 -225.345244)
		(end 51.28133 -225.182176)
		(width 0.14478)
		(layer "In11.Cu")
		(net "M_F_CPU1_SA_DQ<24>")
	)
	(segment
		(start 23.918418 -226.210876)
		(end 24.55418 -226.210876)
		(width 0.14478)
		(layer "In11.Cu")
		(net "M_F_CPU1_SA_DQ<24>")
	)
	(segment
		(start 71.782178 -238.449104)
		(end 75.933046 -238.449104)
		(width 0.14478)
		(layer "In11.Cu")
		(net "M_F_CPU1_SA_DQ<24>")
	)
	(segment
		(start 58.409078 -225.874326)
		(end 58.553858 -226.019106)
		(width 0.14478)
		(layer "In11.Cu")
		(net "M_F_CPU1_SA_DQ<24>")
	)
	(segment
		(start 51.28133 -225.123502)
		(end 51.444398 -224.960434)
		(width 0.14478)
		(layer "In11.Cu")
		(net "M_F_CPU1_SA_DQ<24>")
	)
	(segment
		(start 31.32074 -225.810318)
		(end 33.128712 -225.810318)
		(width 0.14478)
		(layer "In11.Cu")
		(net "M_F_CPU1_SA_DQ<24>")
	)
	(segment
		(start 40.943276 -225.973386)
		(end 40.943276 -226.030536)
		(width 0.14478)
		(layer "In11.Cu")
		(net "M_F_CPU1_SA_DQ<24>")
	)
	(segment
		(start 49.08296 -226.035616)
		(end 49.08296 -225.973386)
		(width 0.14478)
		(layer "In11.Cu")
		(net "M_F_CPU1_SA_DQ<24>")
	)
	(segment
		(start 82.453988 -239.946942)
		(end 82.46237 -239.951768)
		(width 0.0889)
		(layer "In11.Cu")
		(net "M_F_CPU1_SA_DQ<24>")
	)
	(segment
		(start 57.30621 -225.656394)
		(end 57.30621 -225.874326)
		(width 0.14478)
		(layer "In11.Cu")
		(net "M_F_CPU1_SA_DQ<24>")
	)
	(segment
		(start 41.49979 -225.973386)
		(end 41.662858 -225.810318)
		(width 0.14478)
		(layer "In11.Cu")
		(net "M_F_CPU1_SA_DQ<24>")
	)
	(segment
		(start 28.542234 -225.355404)
		(end 28.705302 -225.192336)
		(width 0.14478)
		(layer "In11.Cu")
		(net "M_F_CPU1_SA_DQ<24>")
	)
	(segment
		(start 58.264298 -225.511614)
		(end 58.409078 -225.656394)
		(width 0.14478)
		(layer "In11.Cu")
		(net "M_F_CPU1_SA_DQ<24>")
	)
	(segment
		(start 76.945744 -238.649764)
		(end 78.166468 -239.870488)
		(width 0.0889)
		(layer "In11.Cu")
		(net "M_F_CPU1_SA_DQ<24>")
	)
	(segment
		(start 58.815732 -226.019106)
		(end 58.960512 -225.874326)
		(width 0.14478)
		(layer "In11.Cu")
		(net "M_F_CPU1_SA_DQ<24>")
	)
	(segment
		(start 33.29178 -225.973386)
		(end 33.29178 -226.035616)
		(width 0.14478)
		(layer "In11.Cu")
		(net "M_F_CPU1_SA_DQ<24>")
	)
	(segment
		(start 21.70811 -225.385376)
		(end 21.70811 -225.647504)
		(width 0.14478)
		(layer "In11.Cu")
		(net "M_F_CPU1_SA_DQ<24>")
	)
	(segment
		(start 49.448974 -225.810318)
		(end 50.298858 -224.960434)
		(width 0.14478)
		(layer "In11.Cu")
		(net "M_F_CPU1_SA_DQ<24>")
	)
	(segment
		(start 81.879694 -239.951768)
		(end 81.888076 -239.946942)
		(width 0.0889)
		(layer "In11.Cu")
		(net "M_F_CPU1_SA_DQ<24>")
	)
	(segment
		(start 59.86907 -226.535996)
		(end 71.782178 -238.449104)
		(width 0.14478)
		(layer "In11.Cu")
		(net "M_F_CPU1_SA_DQ<24>")
	)
	(segment
		(start 23.366984 -225.978466)
		(end 23.686008 -225.978466)
		(width 0.14478)
		(layer "In11.Cu")
		(net "M_F_CPU1_SA_DQ<24>")
	)
	(segment
		(start 33.29178 -226.035616)
		(end 33.454848 -226.198684)
		(width 0.14478)
		(layer "In11.Cu")
		(net "M_F_CPU1_SA_DQ<24>")
	)
	(segment
		(start 37.95268 -224.960434)
		(end 38.802564 -225.810318)
		(width 0.14478)
		(layer "In11.Cu")
		(net "M_F_CPU1_SA_DQ<24>")
	)
	(segment
		(start 24.55418 -226.210876)
		(end 24.954738 -225.810318)
		(width 0.14478)
		(layer "In11.Cu")
		(net "M_F_CPU1_SA_DQ<24>")
	)
	(segment
		(start 21.70811 -225.647504)
		(end 22.271482 -226.210876)
		(width 0.14478)
		(layer "In11.Cu")
		(net "M_F_CPU1_SA_DQ<24>")
	)
	(segment
		(start 59.105292 -225.511614)
		(end 59.524392 -225.511614)
		(width 0.14478)
		(layer "In11.Cu")
		(net "M_F_CPU1_SA_DQ<24>")
	)
	(segment
		(start 46.417738 -225.810318)
		(end 48.363378 -225.810318)
		(width 0.14478)
		(layer "In11.Cu")
		(net "M_F_CPU1_SA_DQ<24>")
	)
	(segment
		(start 24.954738 -225.810318)
		(end 25.57272 -225.810318)
		(width 0.14478)
		(layer "In11.Cu")
		(net "M_F_CPU1_SA_DQ<24>")
	)
	(segment
		(start 42.792904 -224.960434)
		(end 43.12793 -224.960434)
		(width 0.14478)
		(layer "In11.Cu")
		(net "M_F_CPU1_SA_DQ<24>")
	)
	(segment
		(start 43.684444 -225.345244)
		(end 43.847512 -225.182176)
		(width 0.14478)
		(layer "In11.Cu")
		(net "M_F_CPU1_SA_DQ<24>")
	)
	(segment
		(start 27.664664 -224.960434)
		(end 27.98572 -224.960434)
		(width 0.14478)
		(layer "In11.Cu")
		(net "M_F_CPU1_SA_DQ<24>")
	)
	(segment
		(start 26.45537 -225.810318)
		(end 26.81478 -225.810318)
		(width 0.14478)
		(layer "In11.Cu")
		(net "M_F_CPU1_SA_DQ<24>")
	)
	(segment
		(start 54.519322 -225.810318)
		(end 54.68239 -225.973386)
		(width 0.14478)
		(layer "In11.Cu")
		(net "M_F_CPU1_SA_DQ<24>")
	)
	(segment
		(start 83.394042 -239.946942)
		(end 83.402424 -239.951768)
		(width 0.0889)
		(layer "In11.Cu")
		(net "M_F_CPU1_SA_DQ<24>")
	)
	(segment
		(start 33.848294 -225.973386)
		(end 34.011362 -225.810318)
		(width 0.14478)
		(layer "In11.Cu")
		(net "M_F_CPU1_SA_DQ<24>")
	)
	(segment
		(start 57.712864 -226.019106)
		(end 57.857644 -225.874326)
		(width 0.14478)
		(layer "In11.Cu")
		(net "M_F_CPU1_SA_DQ<24>")
	)
	(segment
		(start 84.367116 -239.889792)
		(end 84.52104 -239.624362)
		(width 0.0889)
		(layer "In11.Cu")
		(net "M_F_CPU1_SA_DQ<24>")
	)
	(segment
		(start 76.428346 -238.449104)
		(end 76.629006 -238.649764)
		(width 0.0889)
		(layer "In11.Cu")
		(net "M_F_CPU1_SA_DQ<24>")
	)
	(segment
		(start 58.960512 -225.874326)
		(end 58.960512 -225.656394)
		(width 0.14478)
		(layer "In11.Cu")
		(net "M_F_CPU1_SA_DQ<24>")
	)
	(segment
		(start 56.351932 -226.035616)
		(end 56.351932 -225.656394)
		(width 0.14478)
		(layer "In11.Cu")
		(net "M_F_CPU1_SA_DQ<24>")
	)
	(segment
		(start 41.94302 -225.810318)
		(end 42.792904 -224.960434)
		(width 0.14478)
		(layer "In11.Cu")
		(net "M_F_CPU1_SA_DQ<24>")
	)
	(segment
		(start 23.686008 -225.978466)
		(end 23.918418 -226.210876)
		(width 0.14478)
		(layer "In11.Cu")
		(net "M_F_CPU1_SA_DQ<24>")
	)
	(segment
		(start 56.496712 -225.511614)
		(end 57.16143 -225.511614)
		(width 0.14478)
		(layer "In11.Cu")
		(net "M_F_CPU1_SA_DQ<24>")
	)
	(segment
		(start 55.238904 -226.035616)
		(end 55.238904 -225.973386)
		(width 0.14478)
		(layer "In11.Cu")
		(net "M_F_CPU1_SA_DQ<24>")
	)
	(segment
		(start 78.166468 -239.870488)
		(end 78.41107 -239.870488)
		(width 0.0889)
		(layer "In11.Cu")
		(net "M_F_CPU1_SA_DQ<24>")
	)
	(segment
		(start 26.129234 -226.201224)
		(end 26.292302 -226.038156)
		(width 0.14478)
		(layer "In11.Cu")
		(net "M_F_CPU1_SA_DQ<24>")
	)
	(segment
		(start 49.08296 -225.973386)
		(end 49.246028 -225.810318)
		(width 0.14478)
		(layer "In11.Cu")
		(net "M_F_CPU1_SA_DQ<24>")
	)
	(segment
		(start 53.961792 -225.810318)
		(end 54.519322 -225.810318)
		(width 0.14478)
		(layer "In11.Cu")
		(net "M_F_CPU1_SA_DQ<24>")
	)
	(segment
		(start 49.246028 -225.810318)
		(end 49.448974 -225.810318)
		(width 0.14478)
		(layer "In11.Cu")
		(net "M_F_CPU1_SA_DQ<24>")
	)
	(segment
		(start 43.12793 -224.960434)
		(end 43.290998 -225.123502)
		(width 0.14478)
		(layer "In11.Cu")
		(net "M_F_CPU1_SA_DQ<24>")
	)
	(segment
		(start 57.857644 -225.656394)
		(end 58.002424 -225.511614)
		(width 0.14478)
		(layer "In11.Cu")
		(net "M_F_CPU1_SA_DQ<24>")
	)
	(segment
		(start 55.795418 -225.973386)
		(end 55.795418 -226.035616)
		(width 0.14478)
		(layer "In11.Cu")
		(net "M_F_CPU1_SA_DQ<24>")
	)
	(segment
		(start 79.0575 -239.9538)
		(end 79.069184 -239.946942)
		(width 0.0889)
		(layer "In11.Cu")
		(net "M_F_CPU1_SA_DQ<24>")
	)
	(segment
		(start 33.454848 -226.198684)
		(end 33.685226 -226.198684)
		(width 0.14478)
		(layer "In11.Cu")
		(net "M_F_CPU1_SA_DQ<24>")
	)
	(segment
		(start 58.409078 -225.656394)
		(end 58.409078 -225.874326)
		(width 0.14478)
		(layer "In11.Cu")
		(net "M_F_CPU1_SA_DQ<24>")
	)
	(arc
		(start 81.513934 -239.946942)
		(mid 81.696185 -239.997292)
		(end 81.879694 -239.951768)
		(width 0.0889)
		(layer "In11.Cu")
		(net "M_F_CPU1_SA_DQ<24>")
	)
	(arc
		(start 78.694788 -239.946942)
		(mid 78.875246 -239.997386)
		(end 79.0575 -239.9538)
		(width 0.0889)
		(layer "In11.Cu")
		(net "M_F_CPU1_SA_DQ<24>")
	)
	(arc
		(start 80.574134 -239.946942)
		(mid 80.761078 -239.997197)
		(end 80.948022 -239.946942)
		(width 0.0889)
		(layer "In11.Cu")
		(net "M_F_CPU1_SA_DQ<24>")
	)
	(arc
		(start 79.65059 -239.956086)
		(mid 79.830572 -239.997186)
		(end 80.008222 -239.946942)
		(width 0.0889)
		(layer "In11.Cu")
		(net "M_F_CPU1_SA_DQ<24>")
	)
	(arc
		(start 80.948022 -239.946942)
		(mid 81.230978 -239.870765)
		(end 81.513934 -239.946942)
		(width 0.0889)
		(layer "In11.Cu")
		(net "M_F_CPU1_SA_DQ<24>")
	)
	(arc
		(start 79.069184 -239.946942)
		(mid 79.344862 -239.870812)
		(end 79.622396 -239.93983)
		(width 0.0889)
		(layer "In11.Cu")
		(net "M_F_CPU1_SA_DQ<24>")
	)
	(arc
		(start 83.768184 -239.946942)
		(mid 84.015897 -239.871722)
		(end 84.271104 -239.915192)
		(width 0.0889)
		(layer "In11.Cu")
		(net "M_F_CPU1_SA_DQ<24>")
	)
	(arc
		(start 82.82813 -239.946942)
		(mid 83.111086 -239.870765)
		(end 83.394042 -239.946942)
		(width 0.0889)
		(layer "In11.Cu")
		(net "M_F_CPU1_SA_DQ<24>")
	)
	(arc
		(start 81.888076 -239.946942)
		(mid 82.171032 -239.870765)
		(end 82.453988 -239.946942)
		(width 0.0889)
		(layer "In11.Cu")
		(net "M_F_CPU1_SA_DQ<24>")
	)
	(arc
		(start 83.402424 -239.951768)
		(mid 83.585932 -239.997262)
		(end 83.768184 -239.946942)
		(width 0.0889)
		(layer "In11.Cu")
		(net "M_F_CPU1_SA_DQ<24>")
	)
	(arc
		(start 78.41107 -239.870488)
		(mid 78.558001 -239.889899)
		(end 78.694788 -239.946942)
		(width 0.0889)
		(layer "In11.Cu")
		(net "M_F_CPU1_SA_DQ<24>")
	)
	(arc
		(start 80.008222 -239.946942)
		(mid 80.291178 -239.870765)
		(end 80.574134 -239.946942)
		(width 0.0889)
		(layer "In11.Cu")
		(net "M_F_CPU1_SA_DQ<24>")
	)
	(arc
		(start 82.46237 -239.951768)
		(mid 82.645878 -239.997262)
		(end 82.82813 -239.946942)
		(width 0.0889)
		(layer "In11.Cu")
		(net "M_F_CPU1_SA_DQ<24>")
	)
	(segment
		(start 85.927946 -239.8903)
		(end 85.461094 -239.624362)
		(width 0.10668)
		(layer "F.Cu")
		(net "M_F_CPU1_SA_DQ<23>")
	)
	(segment
		(start 19.509994 -224.960434)
		(end 19.771868 -224.960434)
		(width 0.14478)
		(layer "In11.Cu")
		(net "M_F_CPU1_SA_DQ<23>")
	)
	(segment
		(start 19.365214 -224.584006)
		(end 19.365214 -224.815654)
		(width 0.14478)
		(layer "In11.Cu")
		(net "M_F_CPU1_SA_DQ<23>")
	)
	(segment
		(start 54.005226 -224.960434)
		(end 59.775598 -224.960434)
		(width 0.14478)
		(layer "In11.Cu")
		(net "M_F_CPU1_SA_DQ<23>")
	)
	(segment
		(start 19.916648 -224.815654)
		(end 19.916648 -224.584006)
		(width 0.14478)
		(layer "In11.Cu")
		(net "M_F_CPU1_SA_DQ<23>")
	)
	(segment
		(start 31.393892 -224.960434)
		(end 34.35858 -224.960434)
		(width 0.14478)
		(layer "In11.Cu")
		(net "M_F_CPU1_SA_DQ<23>")
	)
	(segment
		(start 27.577796 -224.110296)
		(end 30.543754 -224.110296)
		(width 0.14478)
		(layer "In11.Cu")
		(net "M_F_CPU1_SA_DQ<23>")
	)
	(segment
		(start 75.968606 -237.892844)
		(end 77.004926 -237.892844)
		(width 0.0889)
		(layer "In11.Cu")
		(net "M_F_CPU1_SA_DQ<23>")
	)
	(segment
		(start 77.464666 -238.352584)
		(end 77.464666 -238.780828)
		(width 0.0889)
		(layer "In11.Cu")
		(net "M_F_CPU1_SA_DQ<23>")
	)
	(segment
		(start 17.608042 -224.535238)
		(end 18.033238 -224.960434)
		(width 0.14478)
		(layer "In11.Cu")
		(net "M_F_CPU1_SA_DQ<23>")
	)
	(segment
		(start 19.771868 -224.960434)
		(end 19.916648 -224.815654)
		(width 0.14478)
		(layer "In11.Cu")
		(net "M_F_CPU1_SA_DQ<23>")
	)
	(segment
		(start 20.468082 -224.815654)
		(end 20.612862 -224.960434)
		(width 0.14478)
		(layer "In11.Cu")
		(net "M_F_CPU1_SA_DQ<23>")
	)
	(segment
		(start 20.323302 -224.439226)
		(end 20.468082 -224.584006)
		(width 0.14478)
		(layer "In11.Cu")
		(net "M_F_CPU1_SA_DQ<23>")
	)
	(segment
		(start 19.365214 -224.815654)
		(end 19.509994 -224.960434)
		(width 0.14478)
		(layer "In11.Cu")
		(net "M_F_CPU1_SA_DQ<23>")
	)
	(segment
		(start 38.963346 -224.960434)
		(end 41.891966 -224.960434)
		(width 0.14478)
		(layer "In11.Cu")
		(net "M_F_CPU1_SA_DQ<23>")
	)
	(segment
		(start 83.394042 -239.301782)
		(end 83.402424 -239.296956)
		(width 0.0889)
		(layer "In11.Cu")
		(net "M_F_CPU1_SA_DQ<23>")
	)
	(segment
		(start 34.35858 -224.960434)
		(end 35.208718 -224.110296)
		(width 0.14478)
		(layer "In11.Cu")
		(net "M_F_CPU1_SA_DQ<23>")
	)
	(segment
		(start 72.005698 -237.892844)
		(end 75.968606 -237.892844)
		(width 0.14478)
		(layer "In11.Cu")
		(net "M_F_CPU1_SA_DQ<23>")
	)
	(segment
		(start 42.742104 -224.110296)
		(end 45.618654 -224.110296)
		(width 0.14478)
		(layer "In11.Cu")
		(net "M_F_CPU1_SA_DQ<23>")
	)
	(segment
		(start 60.42533 -226.312476)
		(end 72.005698 -237.892844)
		(width 0.14478)
		(layer "In11.Cu")
		(net "M_F_CPU1_SA_DQ<23>")
	)
	(segment
		(start 26.727658 -224.960434)
		(end 27.577796 -224.110296)
		(width 0.14478)
		(layer "In11.Cu")
		(net "M_F_CPU1_SA_DQ<23>")
	)
	(segment
		(start 85.615018 -239.358932)
		(end 85.461094 -239.624362)
		(width 0.0889)
		(layer "In11.Cu")
		(net "M_F_CPU1_SA_DQ<23>")
	)
	(segment
		(start 35.208718 -224.110296)
		(end 38.113208 -224.110296)
		(width 0.14478)
		(layer "In11.Cu")
		(net "M_F_CPU1_SA_DQ<23>")
	)
	(segment
		(start 60.42533 -225.610166)
		(end 60.42533 -226.312476)
		(width 0.14478)
		(layer "In11.Cu")
		(net "M_F_CPU1_SA_DQ<23>")
	)
	(segment
		(start 41.891966 -224.960434)
		(end 42.742104 -224.110296)
		(width 0.14478)
		(layer "In11.Cu")
		(net "M_F_CPU1_SA_DQ<23>")
	)
	(segment
		(start 18.81378 -224.584006)
		(end 18.95856 -224.439226)
		(width 0.14478)
		(layer "In11.Cu")
		(net "M_F_CPU1_SA_DQ<23>")
	)
	(segment
		(start 78.67904 -239.310418)
		(end 78.693772 -239.301782)
		(width 0.0889)
		(layer "In11.Cu")
		(net "M_F_CPU1_SA_DQ<23>")
	)
	(segment
		(start 46.468792 -224.960434)
		(end 49.389792 -224.960434)
		(width 0.14478)
		(layer "In11.Cu")
		(net "M_F_CPU1_SA_DQ<23>")
	)
	(segment
		(start 82.453988 -239.301782)
		(end 82.46237 -239.296956)
		(width 0.0889)
		(layer "In11.Cu")
		(net "M_F_CPU1_SA_DQ<23>")
	)
	(segment
		(start 20.612862 -224.960434)
		(end 26.727658 -224.960434)
		(width 0.14478)
		(layer "In11.Cu")
		(net "M_F_CPU1_SA_DQ<23>")
	)
	(segment
		(start 81.879694 -239.296956)
		(end 81.888076 -239.301782)
		(width 0.0889)
		(layer "In11.Cu")
		(net "M_F_CPU1_SA_DQ<23>")
	)
	(segment
		(start 78.693772 -239.301782)
		(end 78.705456 -239.294924)
		(width 0.0889)
		(layer "In11.Cu")
		(net "M_F_CPU1_SA_DQ<23>")
	)
	(segment
		(start 18.81378 -224.815654)
		(end 18.81378 -224.584006)
		(width 0.14478)
		(layer "In11.Cu")
		(net "M_F_CPU1_SA_DQ<23>")
	)
	(segment
		(start 18.95856 -224.439226)
		(end 19.220434 -224.439226)
		(width 0.14478)
		(layer "In11.Cu")
		(net "M_F_CPU1_SA_DQ<23>")
	)
	(segment
		(start 19.916648 -224.584006)
		(end 20.061428 -224.439226)
		(width 0.14478)
		(layer "In11.Cu")
		(net "M_F_CPU1_SA_DQ<23>")
	)
	(segment
		(start 18.669 -224.960434)
		(end 18.81378 -224.815654)
		(width 0.14478)
		(layer "In11.Cu")
		(net "M_F_CPU1_SA_DQ<23>")
	)
	(segment
		(start 79.06766 -239.301782)
		(end 79.078074 -239.307878)
		(width 0.0889)
		(layer "In11.Cu")
		(net "M_F_CPU1_SA_DQ<23>")
	)
	(segment
		(start 78.016354 -239.259872)
		(end 78.165706 -239.321848)
		(width 0.0889)
		(layer "In11.Cu")
		(net "M_F_CPU1_SA_DQ<23>")
	)
	(segment
		(start 49.389792 -224.960434)
		(end 50.23993 -224.110296)
		(width 0.14478)
		(layer "In11.Cu")
		(net "M_F_CPU1_SA_DQ<23>")
	)
	(segment
		(start 77.941424 -239.257586)
		(end 78.004162 -239.257586)
		(width 0.0889)
		(layer "In11.Cu")
		(net "M_F_CPU1_SA_DQ<23>")
	)
	(segment
		(start 85.592666 -239.27562)
		(end 85.615018 -239.358932)
		(width 0.0889)
		(layer "In11.Cu")
		(net "M_F_CPU1_SA_DQ<23>")
	)
	(segment
		(start 59.775598 -224.960434)
		(end 60.42533 -225.610166)
		(width 0.14478)
		(layer "In11.Cu")
		(net "M_F_CPU1_SA_DQ<23>")
	)
	(segment
		(start 77.004926 -237.892844)
		(end 77.464666 -238.352584)
		(width 0.0889)
		(layer "In11.Cu")
		(net "M_F_CPU1_SA_DQ<23>")
	)
	(segment
		(start 77.464666 -238.780828)
		(end 77.941424 -239.257586)
		(width 0.0889)
		(layer "In11.Cu")
		(net "M_F_CPU1_SA_DQ<23>")
	)
	(segment
		(start 20.468082 -224.584006)
		(end 20.468082 -224.815654)
		(width 0.14478)
		(layer "In11.Cu")
		(net "M_F_CPU1_SA_DQ<23>")
	)
	(segment
		(start 20.061428 -224.439226)
		(end 20.323302 -224.439226)
		(width 0.14478)
		(layer "In11.Cu")
		(net "M_F_CPU1_SA_DQ<23>")
	)
	(segment
		(start 19.220434 -224.439226)
		(end 19.365214 -224.584006)
		(width 0.14478)
		(layer "In11.Cu")
		(net "M_F_CPU1_SA_DQ<23>")
	)
	(segment
		(start 50.23993 -224.110296)
		(end 53.155088 -224.110296)
		(width 0.14478)
		(layer "In11.Cu")
		(net "M_F_CPU1_SA_DQ<23>")
	)
	(segment
		(start 53.155088 -224.110296)
		(end 54.005226 -224.960434)
		(width 0.14478)
		(layer "In11.Cu")
		(net "M_F_CPU1_SA_DQ<23>")
	)
	(segment
		(start 18.033238 -224.960434)
		(end 18.669 -224.960434)
		(width 0.14478)
		(layer "In11.Cu")
		(net "M_F_CPU1_SA_DQ<23>")
	)
	(segment
		(start 38.113208 -224.110296)
		(end 38.963346 -224.960434)
		(width 0.14478)
		(layer "In11.Cu")
		(net "M_F_CPU1_SA_DQ<23>")
	)
	(segment
		(start 30.543754 -224.110296)
		(end 31.393892 -224.960434)
		(width 0.14478)
		(layer "In11.Cu")
		(net "M_F_CPU1_SA_DQ<23>")
	)
	(segment
		(start 45.618654 -224.110296)
		(end 46.468792 -224.960434)
		(width 0.14478)
		(layer "In11.Cu")
		(net "M_F_CPU1_SA_DQ<23>")
	)
	(arc
		(start 82.82813 -239.301782)
		(mid 83.111086 -239.377959)
		(end 83.394042 -239.301782)
		(width 0.0889)
		(layer "In11.Cu")
		(net "M_F_CPU1_SA_DQ<23>")
	)
	(arc
		(start 85.273896 -239.301782)
		(mid 85.430334 -239.252811)
		(end 85.592666 -239.27562)
		(width 0.0889)
		(layer "In11.Cu")
		(net "M_F_CPU1_SA_DQ<23>")
	)
	(arc
		(start 83.402424 -239.296956)
		(mid 83.585932 -239.251462)
		(end 83.768184 -239.301782)
		(width 0.0889)
		(layer "In11.Cu")
		(net "M_F_CPU1_SA_DQ<23>")
	)
	(arc
		(start 81.513934 -239.301782)
		(mid 81.696185 -239.251432)
		(end 81.879694 -239.296956)
		(width 0.0889)
		(layer "In11.Cu")
		(net "M_F_CPU1_SA_DQ<23>")
	)
	(arc
		(start 79.078074 -239.307878)
		(mid 79.35676 -239.378098)
		(end 79.633826 -239.301782)
		(width 0.0889)
		(layer "In11.Cu")
		(net "M_F_CPU1_SA_DQ<23>")
	)
	(arc
		(start 84.707984 -239.301782)
		(mid 84.99094 -239.377959)
		(end 85.273896 -239.301782)
		(width 0.0889)
		(layer "In11.Cu")
		(net "M_F_CPU1_SA_DQ<23>")
	)
	(arc
		(start 83.768184 -239.301782)
		(mid 84.05114 -239.377959)
		(end 84.334096 -239.301782)
		(width 0.0889)
		(layer "In11.Cu")
		(net "M_F_CPU1_SA_DQ<23>")
	)
	(arc
		(start 79.633826 -239.301782)
		(mid 79.821024 -239.2514)
		(end 80.008222 -239.301782)
		(width 0.0889)
		(layer "In11.Cu")
		(net "M_F_CPU1_SA_DQ<23>")
	)
	(arc
		(start 78.165706 -239.321848)
		(mid 78.423765 -239.378024)
		(end 78.67904 -239.310418)
		(width 0.0889)
		(layer "In11.Cu")
		(net "M_F_CPU1_SA_DQ<23>")
	)
	(arc
		(start 80.008222 -239.301782)
		(mid 80.291178 -239.377959)
		(end 80.574134 -239.301782)
		(width 0.0889)
		(layer "In11.Cu")
		(net "M_F_CPU1_SA_DQ<23>")
	)
	(arc
		(start 78.705456 -239.294924)
		(mid 78.887457 -239.251391)
		(end 79.06766 -239.301782)
		(width 0.0889)
		(layer "In11.Cu")
		(net "M_F_CPU1_SA_DQ<23>")
	)
	(arc
		(start 78.004162 -239.257586)
		(mid 78.010365 -239.258147)
		(end 78.016354 -239.259872)
		(width 0.0889)
		(layer "In11.Cu")
		(net "M_F_CPU1_SA_DQ<23>")
	)
	(arc
		(start 81.888076 -239.301782)
		(mid 82.171032 -239.377959)
		(end 82.453988 -239.301782)
		(width 0.0889)
		(layer "In11.Cu")
		(net "M_F_CPU1_SA_DQ<23>")
	)
	(arc
		(start 80.948022 -239.301782)
		(mid 81.230978 -239.377959)
		(end 81.513934 -239.301782)
		(width 0.0889)
		(layer "In11.Cu")
		(net "M_F_CPU1_SA_DQ<23>")
	)
	(arc
		(start 82.46237 -239.296956)
		(mid 82.645878 -239.251462)
		(end 82.82813 -239.301782)
		(width 0.0889)
		(layer "In11.Cu")
		(net "M_F_CPU1_SA_DQ<23>")
	)
	(arc
		(start 84.334096 -239.301782)
		(mid 84.52104 -239.251527)
		(end 84.707984 -239.301782)
		(width 0.0889)
		(layer "In11.Cu")
		(net "M_F_CPU1_SA_DQ<23>")
	)
	(arc
		(start 80.574134 -239.301782)
		(mid 80.761078 -239.251527)
		(end 80.948022 -239.301782)
		(width 0.0889)
		(layer "In11.Cu")
		(net "M_F_CPU1_SA_DQ<23>")
	)
	(segment
		(start 84.517992 -239.080294)
		(end 84.05114 -238.814356)
		(width 0.10668)
		(layer "F.Cu")
		(net "M_F_CPU1_SA_DQ<22>")
	)
	(segment
		(start 76.024486 -236.983524)
		(end 76.189586 -236.983524)
		(width 0.0889)
		(layer "In11.Cu")
		(net "M_F_CPU1_SA_DQ<22>")
	)
	(segment
		(start 20.639532 -223.260412)
		(end 26.727658 -223.260412)
		(width 0.14478)
		(layer "In11.Cu")
		(net "M_F_CPU1_SA_DQ<22>")
	)
	(segment
		(start 77.046074 -237.280704)
		(end 78.206346 -238.440976)
		(width 0.0889)
		(layer "In11.Cu")
		(net "M_F_CPU1_SA_DQ<22>")
	)
	(segment
		(start 38.113208 -222.410274)
		(end 38.963346 -223.260412)
		(width 0.14478)
		(layer "In11.Cu")
		(net "M_F_CPU1_SA_DQ<22>")
	)
	(segment
		(start 61.33465 -225.949764)
		(end 72.36841 -236.983524)
		(width 0.14478)
		(layer "In11.Cu")
		(net "M_F_CPU1_SA_DQ<22>")
	)
	(segment
		(start 35.208718 -222.410274)
		(end 38.113208 -222.410274)
		(width 0.14478)
		(layer "In11.Cu")
		(net "M_F_CPU1_SA_DQ<22>")
	)
	(segment
		(start 61.33465 -225.180906)
		(end 61.33465 -225.949764)
		(width 0.14478)
		(layer "In11.Cu")
		(net "M_F_CPU1_SA_DQ<22>")
	)
	(segment
		(start 18.84045 -222.615506)
		(end 18.98523 -222.470726)
		(width 0.14478)
		(layer "In11.Cu")
		(net "M_F_CPU1_SA_DQ<22>")
	)
	(segment
		(start 18.98523 -222.470726)
		(end 19.247104 -222.470726)
		(width 0.14478)
		(layer "In11.Cu")
		(net "M_F_CPU1_SA_DQ<22>")
	)
	(segment
		(start 84.182712 -238.465614)
		(end 84.205064 -238.548926)
		(width 0.0889)
		(layer "In11.Cu")
		(net "M_F_CPU1_SA_DQ<22>")
	)
	(segment
		(start 54.005226 -223.260412)
		(end 59.414156 -223.260412)
		(width 0.14478)
		(layer "In11.Cu")
		(net "M_F_CPU1_SA_DQ<22>")
	)
	(segment
		(start 83.289648 -238.48695)
		(end 83.29803 -238.491776)
		(width 0.0889)
		(layer "In11.Cu")
		(net "M_F_CPU1_SA_DQ<22>")
	)
	(segment
		(start 46.468792 -223.260412)
		(end 49.389792 -223.260412)
		(width 0.14478)
		(layer "In11.Cu")
		(net "M_F_CPU1_SA_DQ<22>")
	)
	(segment
		(start 20.494752 -222.615506)
		(end 20.494752 -223.115632)
		(width 0.14478)
		(layer "In11.Cu")
		(net "M_F_CPU1_SA_DQ<22>")
	)
	(segment
		(start 19.247104 -222.470726)
		(end 19.391884 -222.615506)
		(width 0.14478)
		(layer "In11.Cu")
		(net "M_F_CPU1_SA_DQ<22>")
	)
	(segment
		(start 53.155088 -222.410274)
		(end 54.005226 -223.260412)
		(width 0.14478)
		(layer "In11.Cu")
		(net "M_F_CPU1_SA_DQ<22>")
	)
	(segment
		(start 19.391884 -222.615506)
		(end 19.391884 -223.235266)
		(width 0.14478)
		(layer "In11.Cu")
		(net "M_F_CPU1_SA_DQ<22>")
	)
	(segment
		(start 30.543754 -222.410274)
		(end 31.393892 -223.260412)
		(width 0.14478)
		(layer "In11.Cu")
		(net "M_F_CPU1_SA_DQ<22>")
	)
	(segment
		(start 80.46974 -238.48695)
		(end 80.478122 -238.491776)
		(width 0.0889)
		(layer "In11.Cu")
		(net "M_F_CPU1_SA_DQ<22>")
	)
	(segment
		(start 18.69567 -223.260412)
		(end 18.84045 -223.115632)
		(width 0.14478)
		(layer "In11.Cu")
		(net "M_F_CPU1_SA_DQ<22>")
	)
	(segment
		(start 19.943318 -223.235266)
		(end 19.943318 -222.615506)
		(width 0.14478)
		(layer "In11.Cu")
		(net "M_F_CPU1_SA_DQ<22>")
	)
	(segment
		(start 20.088098 -222.470726)
		(end 20.349972 -222.470726)
		(width 0.14478)
		(layer "In11.Cu")
		(net "M_F_CPU1_SA_DQ<22>")
	)
	(segment
		(start 19.536664 -223.380046)
		(end 19.798538 -223.380046)
		(width 0.14478)
		(layer "In11.Cu")
		(net "M_F_CPU1_SA_DQ<22>")
	)
	(segment
		(start 72.36841 -236.983524)
		(end 76.024486 -236.983524)
		(width 0.14478)
		(layer "In11.Cu")
		(net "M_F_CPU1_SA_DQ<22>")
	)
	(segment
		(start 81.044034 -238.491776)
		(end 81.052416 -238.48695)
		(width 0.0889)
		(layer "In11.Cu")
		(net "M_F_CPU1_SA_DQ<22>")
	)
	(segment
		(start 19.391884 -223.235266)
		(end 19.536664 -223.380046)
		(width 0.14478)
		(layer "In11.Cu")
		(net "M_F_CPU1_SA_DQ<22>")
	)
	(segment
		(start 34.35858 -223.260412)
		(end 35.208718 -222.410274)
		(width 0.14478)
		(layer "In11.Cu")
		(net "M_F_CPU1_SA_DQ<22>")
	)
	(segment
		(start 76.486766 -237.280704)
		(end 77.046074 -237.280704)
		(width 0.0889)
		(layer "In11.Cu")
		(net "M_F_CPU1_SA_DQ<22>")
	)
	(segment
		(start 50.23993 -222.410274)
		(end 53.155088 -222.410274)
		(width 0.14478)
		(layer "In11.Cu")
		(net "M_F_CPU1_SA_DQ<22>")
	)
	(segment
		(start 45.618654 -222.410274)
		(end 46.468792 -223.260412)
		(width 0.14478)
		(layer "In11.Cu")
		(net "M_F_CPU1_SA_DQ<22>")
	)
	(segment
		(start 41.891966 -223.260412)
		(end 42.742104 -222.410274)
		(width 0.14478)
		(layer "In11.Cu")
		(net "M_F_CPU1_SA_DQ<22>")
	)
	(segment
		(start 38.963346 -223.260412)
		(end 41.891966 -223.260412)
		(width 0.14478)
		(layer "In11.Cu")
		(net "M_F_CPU1_SA_DQ<22>")
	)
	(segment
		(start 42.742104 -222.410274)
		(end 45.618654 -222.410274)
		(width 0.14478)
		(layer "In11.Cu")
		(net "M_F_CPU1_SA_DQ<22>")
	)
	(segment
		(start 18.033238 -223.260412)
		(end 18.69567 -223.260412)
		(width 0.14478)
		(layer "In11.Cu")
		(net "M_F_CPU1_SA_DQ<22>")
	)
	(segment
		(start 79.147162 -238.502444)
		(end 79.165196 -238.491776)
		(width 0.0889)
		(layer "In11.Cu")
		(net "M_F_CPU1_SA_DQ<22>")
	)
	(segment
		(start 49.389792 -223.260412)
		(end 50.23993 -222.410274)
		(width 0.14478)
		(layer "In11.Cu")
		(net "M_F_CPU1_SA_DQ<22>")
	)
	(segment
		(start 18.84045 -223.115632)
		(end 18.84045 -222.615506)
		(width 0.14478)
		(layer "In11.Cu")
		(net "M_F_CPU1_SA_DQ<22>")
	)
	(segment
		(start 26.727658 -223.260412)
		(end 27.577796 -222.410274)
		(width 0.14478)
		(layer "In11.Cu")
		(net "M_F_CPU1_SA_DQ<22>")
	)
	(segment
		(start 20.349972 -222.470726)
		(end 20.494752 -222.615506)
		(width 0.14478)
		(layer "In11.Cu")
		(net "M_F_CPU1_SA_DQ<22>")
	)
	(segment
		(start 84.205064 -238.548926)
		(end 84.05114 -238.814356)
		(width 0.0889)
		(layer "In11.Cu")
		(net "M_F_CPU1_SA_DQ<22>")
	)
	(segment
		(start 78.206346 -238.440976)
		(end 78.41107 -238.440976)
		(width 0.0889)
		(layer "In11.Cu")
		(net "M_F_CPU1_SA_DQ<22>")
	)
	(segment
		(start 19.943318 -222.615506)
		(end 20.088098 -222.470726)
		(width 0.14478)
		(layer "In11.Cu")
		(net "M_F_CPU1_SA_DQ<22>")
	)
	(segment
		(start 17.608042 -222.835216)
		(end 18.033238 -223.260412)
		(width 0.14478)
		(layer "In11.Cu")
		(net "M_F_CPU1_SA_DQ<22>")
	)
	(segment
		(start 19.798538 -223.380046)
		(end 19.943318 -223.235266)
		(width 0.14478)
		(layer "In11.Cu")
		(net "M_F_CPU1_SA_DQ<22>")
	)
	(segment
		(start 31.393892 -223.260412)
		(end 34.35858 -223.260412)
		(width 0.14478)
		(layer "In11.Cu")
		(net "M_F_CPU1_SA_DQ<22>")
	)
	(segment
		(start 59.414156 -223.260412)
		(end 61.33465 -225.180906)
		(width 0.14478)
		(layer "In11.Cu")
		(net "M_F_CPU1_SA_DQ<22>")
	)
	(segment
		(start 79.53883 -238.49203)
		(end 79.550768 -238.498888)
		(width 0.0889)
		(layer "In11.Cu")
		(net "M_F_CPU1_SA_DQ<22>")
	)
	(segment
		(start 20.494752 -223.115632)
		(end 20.639532 -223.260412)
		(width 0.14478)
		(layer "In11.Cu")
		(net "M_F_CPU1_SA_DQ<22>")
	)
	(segment
		(start 79.525114 -238.484156)
		(end 79.53883 -238.49203)
		(width 0.0889)
		(layer "In11.Cu")
		(net "M_F_CPU1_SA_DQ<22>")
	)
	(segment
		(start 27.577796 -222.410274)
		(end 30.543754 -222.410274)
		(width 0.14478)
		(layer "In11.Cu")
		(net "M_F_CPU1_SA_DQ<22>")
	)
	(segment
		(start 76.189586 -236.983524)
		(end 76.486766 -237.280704)
		(width 0.0889)
		(layer "In11.Cu")
		(net "M_F_CPU1_SA_DQ<22>")
	)
	(arc
		(start 78.41107 -238.440976)
		(mid 78.508159 -238.453966)
		(end 78.598522 -238.491776)
		(width 0.0889)
		(layer "In11.Cu")
		(net "M_F_CPU1_SA_DQ<22>")
	)
	(arc
		(start 82.357976 -238.491776)
		(mid 82.640932 -238.567953)
		(end 82.923888 -238.491776)
		(width 0.0889)
		(layer "In11.Cu")
		(net "M_F_CPU1_SA_DQ<22>")
	)
	(arc
		(start 80.10398 -238.491776)
		(mid 80.286231 -238.441426)
		(end 80.46974 -238.48695)
		(width 0.0889)
		(layer "In11.Cu")
		(net "M_F_CPU1_SA_DQ<22>")
	)
	(arc
		(start 81.052416 -238.48695)
		(mid 81.235924 -238.441456)
		(end 81.418176 -238.491776)
		(width 0.0889)
		(layer "In11.Cu")
		(net "M_F_CPU1_SA_DQ<22>")
	)
	(arc
		(start 79.165196 -238.491776)
		(mid 79.344183 -238.441606)
		(end 79.525114 -238.484156)
		(width 0.0889)
		(layer "In11.Cu")
		(net "M_F_CPU1_SA_DQ<22>")
	)
	(arc
		(start 82.923888 -238.491776)
		(mid 83.106139 -238.441426)
		(end 83.289648 -238.48695)
		(width 0.0889)
		(layer "In11.Cu")
		(net "M_F_CPU1_SA_DQ<22>")
	)
	(arc
		(start 81.418176 -238.491776)
		(mid 81.701132 -238.567953)
		(end 81.984088 -238.491776)
		(width 0.0889)
		(layer "In11.Cu")
		(net "M_F_CPU1_SA_DQ<22>")
	)
	(arc
		(start 83.863942 -238.491776)
		(mid 84.02038 -238.442805)
		(end 84.182712 -238.465614)
		(width 0.0889)
		(layer "In11.Cu")
		(net "M_F_CPU1_SA_DQ<22>")
	)
	(arc
		(start 83.29803 -238.491776)
		(mid 83.580986 -238.567953)
		(end 83.863942 -238.491776)
		(width 0.0889)
		(layer "In11.Cu")
		(net "M_F_CPU1_SA_DQ<22>")
	)
	(arc
		(start 81.984088 -238.491776)
		(mid 82.171032 -238.441521)
		(end 82.357976 -238.491776)
		(width 0.0889)
		(layer "In11.Cu")
		(net "M_F_CPU1_SA_DQ<22>")
	)
	(arc
		(start 80.478122 -238.491776)
		(mid 80.761078 -238.567953)
		(end 81.044034 -238.491776)
		(width 0.0889)
		(layer "In11.Cu")
		(net "M_F_CPU1_SA_DQ<22>")
	)
	(arc
		(start 78.598522 -238.491776)
		(mid 78.871466 -238.568356)
		(end 79.147162 -238.502444)
		(width 0.0889)
		(layer "In11.Cu")
		(net "M_F_CPU1_SA_DQ<22>")
	)
	(arc
		(start 79.550768 -238.498888)
		(mid 79.828302 -238.567869)
		(end 80.10398 -238.491776)
		(width 0.0889)
		(layer "In11.Cu")
		(net "M_F_CPU1_SA_DQ<22>")
	)
	(segment
		(start 86.397846 -239.080294)
		(end 85.930994 -238.814356)
		(width 0.10668)
		(layer "F.Cu")
		(net "M_F_CPU1_SA_DQ<21>")
	)
	(segment
		(start 83.289648 -239.141762)
		(end 83.29803 -239.136936)
		(width 0.0889)
		(layer "In11.Cu")
		(net "M_F_CPU1_SA_DQ<21>")
	)
	(segment
		(start 28.71724 -223.485456)
		(end 28.71724 -223.42348)
		(width 0.14478)
		(layer "In11.Cu")
		(net "M_F_CPU1_SA_DQ<21>")
	)
	(segment
		(start 40.835834 -224.273364)
		(end 40.835834 -224.333816)
		(width 0.14478)
		(layer "In11.Cu")
		(net "M_F_CPU1_SA_DQ<21>")
	)
	(segment
		(start 23.39721 -224.192846)
		(end 23.659084 -224.192846)
		(width 0.14478)
		(layer "In11.Cu")
		(net "M_F_CPU1_SA_DQ<21>")
	)
	(segment
		(start 23.25243 -224.048066)
		(end 23.39721 -224.192846)
		(width 0.14478)
		(layer "In11.Cu")
		(net "M_F_CPU1_SA_DQ<21>")
	)
	(segment
		(start 54.902862 -224.504504)
		(end 55.06593 -224.341436)
		(width 0.14478)
		(layer "In11.Cu")
		(net "M_F_CPU1_SA_DQ<21>")
	)
	(segment
		(start 55.06593 -224.273364)
		(end 55.228998 -224.110296)
		(width 0.14478)
		(layer "In11.Cu")
		(net "M_F_CPU1_SA_DQ<21>")
	)
	(segment
		(start 36.023804 -223.648524)
		(end 36.186872 -223.485456)
		(width 0.14478)
		(layer "In11.Cu")
		(net "M_F_CPU1_SA_DQ<21>")
	)
	(segment
		(start 23.948644 -223.735646)
		(end 24.210518 -223.735646)
		(width 0.14478)
		(layer "In11.Cu")
		(net "M_F_CPU1_SA_DQ<21>")
	)
	(segment
		(start 25.795224 -224.341436)
		(end 25.958292 -224.504504)
		(width 0.14478)
		(layer "In11.Cu")
		(net "M_F_CPU1_SA_DQ<21>")
	)
	(segment
		(start 55.459376 -224.110296)
		(end 55.622444 -224.273364)
		(width 0.14478)
		(layer "In11.Cu")
		(net "M_F_CPU1_SA_DQ<21>")
	)
	(segment
		(start 33.797494 -224.273364)
		(end 33.960562 -224.110296)
		(width 0.14478)
		(layer "In11.Cu")
		(net "M_F_CPU1_SA_DQ<21>")
	)
	(segment
		(start 33.960562 -224.110296)
		(end 34.383218 -224.110296)
		(width 0.14478)
		(layer "In11.Cu")
		(net "M_F_CPU1_SA_DQ<21>")
	)
	(segment
		(start 25.632156 -224.110296)
		(end 25.795224 -224.273364)
		(width 0.14478)
		(layer "In11.Cu")
		(net "M_F_CPU1_SA_DQ<21>")
	)
	(segment
		(start 22.700996 -223.965516)
		(end 22.700996 -223.880426)
		(width 0.14478)
		(layer "In11.Cu")
		(net "M_F_CPU1_SA_DQ<21>")
	)
	(segment
		(start 43.630596 -223.648524)
		(end 43.793664 -223.485456)
		(width 0.14478)
		(layer "In11.Cu")
		(net "M_F_CPU1_SA_DQ<21>")
	)
	(segment
		(start 78.59776 -239.136936)
		(end 78.608174 -239.13084)
		(width 0.0889)
		(layer "In11.Cu")
		(net "M_F_CPU1_SA_DQ<21>")
	)
	(segment
		(start 23.803864 -224.048066)
		(end 23.803864 -223.880426)
		(width 0.14478)
		(layer "In11.Cu")
		(net "M_F_CPU1_SA_DQ<21>")
	)
	(segment
		(start 56.178958 -224.273364)
		(end 56.342026 -224.110296)
		(width 0.14478)
		(layer "In11.Cu")
		(net "M_F_CPU1_SA_DQ<21>")
	)
	(segment
		(start 28.554172 -223.648524)
		(end 28.71724 -223.485456)
		(width 0.14478)
		(layer "In11.Cu")
		(net "M_F_CPU1_SA_DQ<21>")
	)
	(segment
		(start 33.077912 -224.110296)
		(end 33.24098 -224.273364)
		(width 0.14478)
		(layer "In11.Cu")
		(net "M_F_CPU1_SA_DQ<21>")
	)
	(segment
		(start 76.154026 -237.438184)
		(end 76.319126 -237.603284)
		(width 0.0889)
		(layer "In11.Cu")
		(net "M_F_CPU1_SA_DQ<21>")
	)
	(segment
		(start 22.700996 -223.880426)
		(end 22.845776 -223.735646)
		(width 0.14478)
		(layer "In11.Cu")
		(net "M_F_CPU1_SA_DQ<21>")
	)
	(segment
		(start 55.06593 -224.341436)
		(end 55.06593 -224.273364)
		(width 0.14478)
		(layer "In11.Cu")
		(net "M_F_CPU1_SA_DQ<21>")
	)
	(segment
		(start 56.178958 -224.341436)
		(end 56.178958 -224.273364)
		(width 0.14478)
		(layer "In11.Cu")
		(net "M_F_CPU1_SA_DQ<21>")
	)
	(segment
		(start 33.634426 -224.504504)
		(end 33.797494 -224.341436)
		(width 0.14478)
		(layer "In11.Cu")
		(net "M_F_CPU1_SA_DQ<21>")
	)
	(segment
		(start 41.94302 -224.110296)
		(end 42.792904 -223.260412)
		(width 0.14478)
		(layer "In11.Cu")
		(net "M_F_CPU1_SA_DQ<21>")
	)
	(segment
		(start 48.788574 -224.504504)
		(end 48.951642 -224.341436)
		(width 0.14478)
		(layer "In11.Cu")
		(net "M_F_CPU1_SA_DQ<21>")
	)
	(segment
		(start 43.956732 -223.260412)
		(end 45.567854 -223.260412)
		(width 0.14478)
		(layer "In11.Cu")
		(net "M_F_CPU1_SA_DQ<21>")
	)
	(segment
		(start 48.558196 -224.504504)
		(end 48.788574 -224.504504)
		(width 0.14478)
		(layer "In11.Cu")
		(net "M_F_CPU1_SA_DQ<21>")
	)
	(segment
		(start 27.664664 -223.260412)
		(end 27.997658 -223.260412)
		(width 0.14478)
		(layer "In11.Cu")
		(net "M_F_CPU1_SA_DQ<21>")
	)
	(segment
		(start 21.70811 -223.685354)
		(end 22.133052 -224.110296)
		(width 0.14478)
		(layer "In11.Cu")
		(net "M_F_CPU1_SA_DQ<21>")
	)
	(segment
		(start 50.808382 -223.480376)
		(end 50.97145 -223.643444)
		(width 0.14478)
		(layer "In11.Cu")
		(net "M_F_CPU1_SA_DQ<21>")
	)
	(segment
		(start 45.567854 -223.260412)
		(end 46.417738 -224.110296)
		(width 0.14478)
		(layer "In11.Cu")
		(net "M_F_CPU1_SA_DQ<21>")
	)
	(segment
		(start 35.630358 -223.485456)
		(end 35.793426 -223.648524)
		(width 0.14478)
		(layer "In11.Cu")
		(net "M_F_CPU1_SA_DQ<21>")
	)
	(segment
		(start 48.23206 -224.110296)
		(end 48.395128 -224.273364)
		(width 0.14478)
		(layer "In11.Cu")
		(net "M_F_CPU1_SA_DQ<21>")
	)
	(segment
		(start 35.793426 -223.648524)
		(end 36.023804 -223.648524)
		(width 0.14478)
		(layer "In11.Cu")
		(net "M_F_CPU1_SA_DQ<21>")
	)
	(segment
		(start 72.187054 -237.438184)
		(end 75.945746 -237.438184)
		(width 0.14478)
		(layer "In11.Cu")
		(net "M_F_CPU1_SA_DQ<21>")
	)
	(segment
		(start 54.509416 -224.273364)
		(end 54.509416 -224.341436)
		(width 0.14478)
		(layer "In11.Cu")
		(net "M_F_CPU1_SA_DQ<21>")
	)
	(segment
		(start 35.46729 -223.260412)
		(end 35.630358 -223.42348)
		(width 0.14478)
		(layer "In11.Cu")
		(net "M_F_CPU1_SA_DQ<21>")
	)
	(segment
		(start 49.448974 -224.110296)
		(end 50.298858 -223.260412)
		(width 0.14478)
		(layer "In11.Cu")
		(net "M_F_CPU1_SA_DQ<21>")
	)
	(segment
		(start 77.037946 -237.603284)
		(end 77.744066 -238.309404)
		(width 0.0889)
		(layer "In11.Cu")
		(net "M_F_CPU1_SA_DQ<21>")
	)
	(segment
		(start 26.514806 -224.110296)
		(end 26.81478 -224.110296)
		(width 0.14478)
		(layer "In11.Cu")
		(net "M_F_CPU1_SA_DQ<21>")
	)
	(segment
		(start 80.093566 -239.13084)
		(end 80.10398 -239.136936)
		(width 0.0889)
		(layer "In11.Cu")
		(net "M_F_CPU1_SA_DQ<21>")
	)
	(segment
		(start 53.961792 -224.110296)
		(end 54.346348 -224.110296)
		(width 0.14478)
		(layer "In11.Cu")
		(net "M_F_CPU1_SA_DQ<21>")
	)
	(segment
		(start 41.392348 -224.333816)
		(end 41.392348 -224.273364)
		(width 0.14478)
		(layer "In11.Cu")
		(net "M_F_CPU1_SA_DQ<21>")
	)
	(segment
		(start 41.392348 -224.273364)
		(end 41.555416 -224.110296)
		(width 0.14478)
		(layer "In11.Cu")
		(net "M_F_CPU1_SA_DQ<21>")
	)
	(segment
		(start 49.11471 -224.110296)
		(end 49.448974 -224.110296)
		(width 0.14478)
		(layer "In11.Cu")
		(net "M_F_CPU1_SA_DQ<21>")
	)
	(segment
		(start 31.32074 -224.110296)
		(end 33.077912 -224.110296)
		(width 0.14478)
		(layer "In11.Cu")
		(net "M_F_CPU1_SA_DQ<21>")
	)
	(segment
		(start 28.880308 -223.260412)
		(end 30.470856 -223.260412)
		(width 0.14478)
		(layer "In11.Cu")
		(net "M_F_CPU1_SA_DQ<21>")
	)
	(segment
		(start 56.342026 -224.110296)
		(end 56.954674 -224.110296)
		(width 0.14478)
		(layer "In11.Cu")
		(net "M_F_CPU1_SA_DQ<21>")
	)
	(segment
		(start 55.622444 -224.341436)
		(end 55.785512 -224.504504)
		(width 0.14478)
		(layer "In11.Cu")
		(net "M_F_CPU1_SA_DQ<21>")
	)
	(segment
		(start 28.160726 -223.485456)
		(end 28.323794 -223.648524)
		(width 0.14478)
		(layer "In11.Cu")
		(net "M_F_CPU1_SA_DQ<21>")
	)
	(segment
		(start 36.186872 -223.42348)
		(end 36.34994 -223.260412)
		(width 0.14478)
		(layer "In11.Cu")
		(net "M_F_CPU1_SA_DQ<21>")
	)
	(segment
		(start 50.808382 -223.42348)
		(end 50.808382 -223.480376)
		(width 0.14478)
		(layer "In11.Cu")
		(net "M_F_CPU1_SA_DQ<21>")
	)
	(segment
		(start 56.954674 -224.110296)
		(end 57.115964 -223.949006)
		(width 0.14478)
		(layer "In11.Cu")
		(net "M_F_CPU1_SA_DQ<21>")
	)
	(segment
		(start 51.364896 -223.42348)
		(end 51.527964 -223.260412)
		(width 0.14478)
		(layer "In11.Cu")
		(net "M_F_CPU1_SA_DQ<21>")
	)
	(segment
		(start 48.951642 -224.273364)
		(end 49.11471 -224.110296)
		(width 0.14478)
		(layer "In11.Cu")
		(net "M_F_CPU1_SA_DQ<21>")
	)
	(segment
		(start 23.10765 -223.735646)
		(end 23.25243 -223.880426)
		(width 0.14478)
		(layer "In11.Cu")
		(net "M_F_CPU1_SA_DQ<21>")
	)
	(segment
		(start 56.01589 -224.504504)
		(end 56.178958 -224.341436)
		(width 0.14478)
		(layer "In11.Cu")
		(net "M_F_CPU1_SA_DQ<21>")
	)
	(segment
		(start 85.77707 -239.079786)
		(end 85.930994 -238.814356)
		(width 0.0889)
		(layer "In11.Cu")
		(net "M_F_CPU1_SA_DQ<21>")
	)
	(segment
		(start 25.795224 -224.273364)
		(end 25.795224 -224.341436)
		(width 0.14478)
		(layer "In11.Cu")
		(net "M_F_CPU1_SA_DQ<21>")
	)
	(segment
		(start 50.97145 -223.643444)
		(end 51.201828 -223.643444)
		(width 0.14478)
		(layer "In11.Cu")
		(net "M_F_CPU1_SA_DQ<21>")
	)
	(segment
		(start 77.744066 -238.657384)
		(end 78.223618 -239.136936)
		(width 0.0889)
		(layer "In11.Cu")
		(net "M_F_CPU1_SA_DQ<21>")
	)
	(segment
		(start 76.319126 -237.603284)
		(end 77.037946 -237.603284)
		(width 0.0889)
		(layer "In11.Cu")
		(net "M_F_CPU1_SA_DQ<21>")
	)
	(segment
		(start 43.23715 -223.485456)
		(end 43.400218 -223.648524)
		(width 0.14478)
		(layer "In11.Cu")
		(net "M_F_CPU1_SA_DQ<21>")
	)
	(segment
		(start 43.793664 -223.42348)
		(end 43.956732 -223.260412)
		(width 0.14478)
		(layer "In11.Cu")
		(net "M_F_CPU1_SA_DQ<21>")
	)
	(segment
		(start 37.95268 -223.260412)
		(end 38.802564 -224.110296)
		(width 0.14478)
		(layer "In11.Cu")
		(net "M_F_CPU1_SA_DQ<21>")
	)
	(segment
		(start 38.802564 -224.110296)
		(end 40.672766 -224.110296)
		(width 0.14478)
		(layer "In11.Cu")
		(net "M_F_CPU1_SA_DQ<21>")
	)
	(segment
		(start 48.395128 -224.341436)
		(end 48.558196 -224.504504)
		(width 0.14478)
		(layer "In11.Cu")
		(net "M_F_CPU1_SA_DQ<21>")
	)
	(segment
		(start 75.945746 -237.438184)
		(end 76.154026 -237.438184)
		(width 0.0889)
		(layer "In11.Cu")
		(net "M_F_CPU1_SA_DQ<21>")
	)
	(segment
		(start 28.160726 -223.42348)
		(end 28.160726 -223.485456)
		(width 0.14478)
		(layer "In11.Cu")
		(net "M_F_CPU1_SA_DQ<21>")
	)
	(segment
		(start 22.845776 -223.735646)
		(end 23.10765 -223.735646)
		(width 0.14478)
		(layer "In11.Cu")
		(net "M_F_CPU1_SA_DQ<21>")
	)
	(segment
		(start 53.111908 -223.260412)
		(end 53.961792 -224.110296)
		(width 0.14478)
		(layer "In11.Cu")
		(net "M_F_CPU1_SA_DQ<21>")
	)
	(segment
		(start 80.46974 -239.141762)
		(end 80.478122 -239.136936)
		(width 0.0889)
		(layer "In11.Cu")
		(net "M_F_CPU1_SA_DQ<21>")
	)
	(segment
		(start 51.527964 -223.260412)
		(end 53.111908 -223.260412)
		(width 0.14478)
		(layer "In11.Cu")
		(net "M_F_CPU1_SA_DQ<21>")
	)
	(segment
		(start 23.659084 -224.192846)
		(end 23.803864 -224.048066)
		(width 0.14478)
		(layer "In11.Cu")
		(net "M_F_CPU1_SA_DQ<21>")
	)
	(segment
		(start 81.044034 -239.136936)
		(end 81.052416 -239.141762)
		(width 0.0889)
		(layer "In11.Cu")
		(net "M_F_CPU1_SA_DQ<21>")
	)
	(segment
		(start 42.792904 -223.260412)
		(end 43.074082 -223.260412)
		(width 0.14478)
		(layer "In11.Cu")
		(net "M_F_CPU1_SA_DQ<21>")
	)
	(segment
		(start 28.323794 -223.648524)
		(end 28.554172 -223.648524)
		(width 0.14478)
		(layer "In11.Cu")
		(net "M_F_CPU1_SA_DQ<21>")
	)
	(segment
		(start 57.115964 -223.949006)
		(end 59.45251 -223.949006)
		(width 0.14478)
		(layer "In11.Cu")
		(net "M_F_CPU1_SA_DQ<21>")
	)
	(segment
		(start 54.346348 -224.110296)
		(end 54.509416 -224.273364)
		(width 0.14478)
		(layer "In11.Cu")
		(net "M_F_CPU1_SA_DQ<21>")
	)
	(segment
		(start 35.630358 -223.42348)
		(end 35.630358 -223.485456)
		(width 0.14478)
		(layer "In11.Cu")
		(net "M_F_CPU1_SA_DQ<21>")
	)
	(segment
		(start 51.364896 -223.480376)
		(end 51.364896 -223.42348)
		(width 0.14478)
		(layer "In11.Cu")
		(net "M_F_CPU1_SA_DQ<21>")
	)
	(segment
		(start 36.186872 -223.485456)
		(end 36.186872 -223.42348)
		(width 0.14478)
		(layer "In11.Cu")
		(net "M_F_CPU1_SA_DQ<21>")
	)
	(segment
		(start 85.681058 -239.105186)
		(end 85.77707 -239.079786)
		(width 0.0889)
		(layer "In11.Cu")
		(net "M_F_CPU1_SA_DQ<21>")
	)
	(segment
		(start 33.797494 -224.341436)
		(end 33.797494 -224.273364)
		(width 0.14478)
		(layer "In11.Cu")
		(net "M_F_CPU1_SA_DQ<21>")
	)
	(segment
		(start 43.23715 -223.42348)
		(end 43.23715 -223.485456)
		(width 0.14478)
		(layer "In11.Cu")
		(net "M_F_CPU1_SA_DQ<21>")
	)
	(segment
		(start 84.229702 -239.141762)
		(end 84.238084 -239.136936)
		(width 0.0889)
		(layer "In11.Cu")
		(net "M_F_CPU1_SA_DQ<21>")
	)
	(segment
		(start 24.355298 -223.880426)
		(end 24.355298 -223.965516)
		(width 0.14478)
		(layer "In11.Cu")
		(net "M_F_CPU1_SA_DQ<21>")
	)
	(segment
		(start 55.785512 -224.504504)
		(end 56.01589 -224.504504)
		(width 0.14478)
		(layer "In11.Cu")
		(net "M_F_CPU1_SA_DQ<21>")
	)
	(segment
		(start 48.951642 -224.341436)
		(end 48.951642 -224.273364)
		(width 0.14478)
		(layer "In11.Cu")
		(net "M_F_CPU1_SA_DQ<21>")
	)
	(segment
		(start 55.228998 -224.110296)
		(end 55.459376 -224.110296)
		(width 0.14478)
		(layer "In11.Cu")
		(net "M_F_CPU1_SA_DQ<21>")
	)
	(segment
		(start 41.22928 -224.496884)
		(end 41.392348 -224.333816)
		(width 0.14478)
		(layer "In11.Cu")
		(net "M_F_CPU1_SA_DQ<21>")
	)
	(segment
		(start 60.87491 -225.371406)
		(end 60.87491 -226.12604)
		(width 0.14478)
		(layer "In11.Cu")
		(net "M_F_CPU1_SA_DQ<21>")
	)
	(segment
		(start 24.355298 -223.965516)
		(end 24.500078 -224.110296)
		(width 0.14478)
		(layer "In11.Cu")
		(net "M_F_CPU1_SA_DQ<21>")
	)
	(segment
		(start 30.470856 -223.260412)
		(end 31.32074 -224.110296)
		(width 0.14478)
		(layer "In11.Cu")
		(net "M_F_CPU1_SA_DQ<21>")
	)
	(segment
		(start 54.509416 -224.341436)
		(end 54.672484 -224.504504)
		(width 0.14478)
		(layer "In11.Cu")
		(net "M_F_CPU1_SA_DQ<21>")
	)
	(segment
		(start 48.395128 -224.273364)
		(end 48.395128 -224.341436)
		(width 0.14478)
		(layer "In11.Cu")
		(net "M_F_CPU1_SA_DQ<21>")
	)
	(segment
		(start 50.298858 -223.260412)
		(end 50.645314 -223.260412)
		(width 0.14478)
		(layer "In11.Cu")
		(net "M_F_CPU1_SA_DQ<21>")
	)
	(segment
		(start 51.201828 -223.643444)
		(end 51.364896 -223.480376)
		(width 0.14478)
		(layer "In11.Cu")
		(net "M_F_CPU1_SA_DQ<21>")
	)
	(segment
		(start 59.45251 -223.949006)
		(end 60.87491 -225.371406)
		(width 0.14478)
		(layer "In11.Cu")
		(net "M_F_CPU1_SA_DQ<21>")
	)
	(segment
		(start 78.583282 -239.145318)
		(end 78.59776 -239.136936)
		(width 0.0889)
		(layer "In11.Cu")
		(net "M_F_CPU1_SA_DQ<21>")
	)
	(segment
		(start 26.351738 -224.341436)
		(end 26.351738 -224.273364)
		(width 0.14478)
		(layer "In11.Cu")
		(net "M_F_CPU1_SA_DQ<21>")
	)
	(segment
		(start 33.404048 -224.504504)
		(end 33.634426 -224.504504)
		(width 0.14478)
		(layer "In11.Cu")
		(net "M_F_CPU1_SA_DQ<21>")
	)
	(segment
		(start 34.383218 -224.110296)
		(end 35.233102 -223.260412)
		(width 0.14478)
		(layer "In11.Cu")
		(net "M_F_CPU1_SA_DQ<21>")
	)
	(segment
		(start 27.997658 -223.260412)
		(end 28.160726 -223.42348)
		(width 0.14478)
		(layer "In11.Cu")
		(net "M_F_CPU1_SA_DQ<21>")
	)
	(segment
		(start 24.500078 -224.110296)
		(end 25.632156 -224.110296)
		(width 0.14478)
		(layer "In11.Cu")
		(net "M_F_CPU1_SA_DQ<21>")
	)
	(segment
		(start 24.210518 -223.735646)
		(end 24.355298 -223.880426)
		(width 0.14478)
		(layer "In11.Cu")
		(net "M_F_CPU1_SA_DQ<21>")
	)
	(segment
		(start 25.958292 -224.504504)
		(end 26.18867 -224.504504)
		(width 0.14478)
		(layer "In11.Cu")
		(net "M_F_CPU1_SA_DQ<21>")
	)
	(segment
		(start 26.351738 -224.273364)
		(end 26.514806 -224.110296)
		(width 0.14478)
		(layer "In11.Cu")
		(net "M_F_CPU1_SA_DQ<21>")
	)
	(segment
		(start 84.803996 -239.136936)
		(end 84.812378 -239.141762)
		(width 0.0889)
		(layer "In11.Cu")
		(net "M_F_CPU1_SA_DQ<21>")
	)
	(segment
		(start 60.87491 -226.12604)
		(end 72.187054 -237.438184)
		(width 0.14478)
		(layer "In11.Cu")
		(net "M_F_CPU1_SA_DQ<21>")
	)
	(segment
		(start 33.24098 -224.273364)
		(end 33.24098 -224.341436)
		(width 0.14478)
		(layer "In11.Cu")
		(net "M_F_CPU1_SA_DQ<21>")
	)
	(segment
		(start 35.233102 -223.260412)
		(end 35.46729 -223.260412)
		(width 0.14478)
		(layer "In11.Cu")
		(net "M_F_CPU1_SA_DQ<21>")
	)
	(segment
		(start 40.835834 -224.333816)
		(end 40.998902 -224.496884)
		(width 0.14478)
		(layer "In11.Cu")
		(net "M_F_CPU1_SA_DQ<21>")
	)
	(segment
		(start 41.555416 -224.110296)
		(end 41.94302 -224.110296)
		(width 0.14478)
		(layer "In11.Cu")
		(net "M_F_CPU1_SA_DQ<21>")
	)
	(segment
		(start 77.744066 -238.309404)
		(end 77.744066 -238.657384)
		(width 0.0889)
		(layer "In11.Cu")
		(net "M_F_CPU1_SA_DQ<21>")
	)
	(segment
		(start 22.556216 -224.110296)
		(end 22.700996 -223.965516)
		(width 0.14478)
		(layer "In11.Cu")
		(net "M_F_CPU1_SA_DQ<21>")
	)
	(segment
		(start 26.81478 -224.110296)
		(end 27.664664 -223.260412)
		(width 0.14478)
		(layer "In11.Cu")
		(net "M_F_CPU1_SA_DQ<21>")
	)
	(segment
		(start 26.18867 -224.504504)
		(end 26.351738 -224.341436)
		(width 0.14478)
		(layer "In11.Cu")
		(net "M_F_CPU1_SA_DQ<21>")
	)
	(segment
		(start 55.622444 -224.273364)
		(end 55.622444 -224.341436)
		(width 0.14478)
		(layer "In11.Cu")
		(net "M_F_CPU1_SA_DQ<21>")
	)
	(segment
		(start 23.25243 -223.880426)
		(end 23.25243 -224.048066)
		(width 0.14478)
		(layer "In11.Cu")
		(net "M_F_CPU1_SA_DQ<21>")
	)
	(segment
		(start 40.672766 -224.110296)
		(end 40.835834 -224.273364)
		(width 0.14478)
		(layer "In11.Cu")
		(net "M_F_CPU1_SA_DQ<21>")
	)
	(segment
		(start 22.133052 -224.110296)
		(end 22.556216 -224.110296)
		(width 0.14478)
		(layer "In11.Cu")
		(net "M_F_CPU1_SA_DQ<21>")
	)
	(segment
		(start 23.803864 -223.880426)
		(end 23.948644 -223.735646)
		(width 0.14478)
		(layer "In11.Cu")
		(net "M_F_CPU1_SA_DQ<21>")
	)
	(segment
		(start 36.34994 -223.260412)
		(end 37.95268 -223.260412)
		(width 0.14478)
		(layer "In11.Cu")
		(net "M_F_CPU1_SA_DQ<21>")
	)
	(segment
		(start 43.793664 -223.485456)
		(end 43.793664 -223.42348)
		(width 0.14478)
		(layer "In11.Cu")
		(net "M_F_CPU1_SA_DQ<21>")
	)
	(segment
		(start 50.645314 -223.260412)
		(end 50.808382 -223.42348)
		(width 0.14478)
		(layer "In11.Cu")
		(net "M_F_CPU1_SA_DQ<21>")
	)
	(segment
		(start 40.998902 -224.496884)
		(end 41.22928 -224.496884)
		(width 0.14478)
		(layer "In11.Cu")
		(net "M_F_CPU1_SA_DQ<21>")
	)
	(segment
		(start 43.074082 -223.260412)
		(end 43.23715 -223.42348)
		(width 0.14478)
		(layer "In11.Cu")
		(net "M_F_CPU1_SA_DQ<21>")
	)
	(segment
		(start 28.71724 -223.42348)
		(end 28.880308 -223.260412)
		(width 0.14478)
		(layer "In11.Cu")
		(net "M_F_CPU1_SA_DQ<21>")
	)
	(segment
		(start 33.24098 -224.341436)
		(end 33.404048 -224.504504)
		(width 0.14478)
		(layer "In11.Cu")
		(net "M_F_CPU1_SA_DQ<21>")
	)
	(segment
		(start 46.417738 -224.110296)
		(end 48.23206 -224.110296)
		(width 0.14478)
		(layer "In11.Cu")
		(net "M_F_CPU1_SA_DQ<21>")
	)
	(segment
		(start 54.672484 -224.504504)
		(end 54.902862 -224.504504)
		(width 0.14478)
		(layer "In11.Cu")
		(net "M_F_CPU1_SA_DQ<21>")
	)
	(segment
		(start 43.400218 -223.648524)
		(end 43.630596 -223.648524)
		(width 0.14478)
		(layer "In11.Cu")
		(net "M_F_CPU1_SA_DQ<21>")
	)
	(arc
		(start 82.357976 -239.136936)
		(mid 82.640932 -239.060759)
		(end 82.923888 -239.136936)
		(width 0.0889)
		(layer "In11.Cu")
		(net "M_F_CPU1_SA_DQ<21>")
	)
	(arc
		(start 79.537814 -239.136936)
		(mid 79.814881 -239.060665)
		(end 80.093566 -239.13084)
		(width 0.0889)
		(layer "In11.Cu")
		(net "M_F_CPU1_SA_DQ<21>")
	)
	(arc
		(start 82.923888 -239.136936)
		(mid 83.106139 -239.187286)
		(end 83.289648 -239.141762)
		(width 0.0889)
		(layer "In11.Cu")
		(net "M_F_CPU1_SA_DQ<21>")
	)
	(arc
		(start 84.238084 -239.136936)
		(mid 84.52104 -239.060759)
		(end 84.803996 -239.136936)
		(width 0.0889)
		(layer "In11.Cu")
		(net "M_F_CPU1_SA_DQ<21>")
	)
	(arc
		(start 81.984088 -239.136936)
		(mid 82.171032 -239.187191)
		(end 82.357976 -239.136936)
		(width 0.0889)
		(layer "In11.Cu")
		(net "M_F_CPU1_SA_DQ<21>")
	)
	(arc
		(start 78.223618 -239.136936)
		(mid 78.402373 -239.187345)
		(end 78.583282 -239.145318)
		(width 0.0889)
		(layer "In11.Cu")
		(net "M_F_CPU1_SA_DQ<21>")
	)
	(arc
		(start 79.163418 -239.136936)
		(mid 79.350616 -239.187318)
		(end 79.537814 -239.136936)
		(width 0.0889)
		(layer "In11.Cu")
		(net "M_F_CPU1_SA_DQ<21>")
	)
	(arc
		(start 85.178138 -239.136936)
		(mid 85.425851 -239.061716)
		(end 85.681058 -239.105186)
		(width 0.0889)
		(layer "In11.Cu")
		(net "M_F_CPU1_SA_DQ<21>")
	)
	(arc
		(start 83.863942 -239.136936)
		(mid 84.046193 -239.187286)
		(end 84.229702 -239.141762)
		(width 0.0889)
		(layer "In11.Cu")
		(net "M_F_CPU1_SA_DQ<21>")
	)
	(arc
		(start 84.812378 -239.141762)
		(mid 84.995886 -239.187256)
		(end 85.178138 -239.136936)
		(width 0.0889)
		(layer "In11.Cu")
		(net "M_F_CPU1_SA_DQ<21>")
	)
	(arc
		(start 80.10398 -239.136936)
		(mid 80.286231 -239.187286)
		(end 80.46974 -239.141762)
		(width 0.0889)
		(layer "In11.Cu")
		(net "M_F_CPU1_SA_DQ<21>")
	)
	(arc
		(start 83.29803 -239.136936)
		(mid 83.580986 -239.060759)
		(end 83.863942 -239.136936)
		(width 0.0889)
		(layer "In11.Cu")
		(net "M_F_CPU1_SA_DQ<21>")
	)
	(arc
		(start 81.418176 -239.136936)
		(mid 81.701132 -239.060759)
		(end 81.984088 -239.136936)
		(width 0.0889)
		(layer "In11.Cu")
		(net "M_F_CPU1_SA_DQ<21>")
	)
	(arc
		(start 78.608174 -239.13084)
		(mid 78.886606 -239.060742)
		(end 79.163418 -239.136936)
		(width 0.0889)
		(layer "In11.Cu")
		(net "M_F_CPU1_SA_DQ<21>")
	)
	(arc
		(start 81.052416 -239.141762)
		(mid 81.235924 -239.187256)
		(end 81.418176 -239.136936)
		(width 0.0889)
		(layer "In11.Cu")
		(net "M_F_CPU1_SA_DQ<21>")
	)
	(arc
		(start 80.478122 -239.136936)
		(mid 80.761078 -239.060759)
		(end 81.044034 -239.136936)
		(width 0.0889)
		(layer "In11.Cu")
		(net "M_F_CPU1_SA_DQ<21>")
	)
	(segment
		(start 84.987892 -238.270288)
		(end 84.52104 -238.00435)
		(width 0.10668)
		(layer "F.Cu")
		(net "M_F_CPU1_SA_DQ<20>")
	)
	(segment
		(start 38.812216 -222.419926)
		(end 40.89146 -222.419926)
		(width 0.14478)
		(layer "In11.Cu")
		(net "M_F_CPU1_SA_DQ<20>")
	)
	(segment
		(start 61.78677 -224.606104)
		(end 61.78677 -225.765868)
		(width 0.14478)
		(layer "In11.Cu")
		(net "M_F_CPU1_SA_DQ<20>")
	)
	(segment
		(start 43.752008 -221.723458)
		(end 43.905424 -221.570042)
		(width 0.14478)
		(layer "In11.Cu")
		(net "M_F_CPU1_SA_DQ<20>")
	)
	(segment
		(start 84.367116 -238.26978)
		(end 84.52104 -238.00435)
		(width 0.0889)
		(layer "In11.Cu")
		(net "M_F_CPU1_SA_DQ<20>")
	)
	(segment
		(start 34.06013 -222.573342)
		(end 34.223198 -222.410274)
		(width 0.14478)
		(layer "In11.Cu")
		(net "M_F_CPU1_SA_DQ<20>")
	)
	(segment
		(start 23.130256 -221.787466)
		(end 23.130256 -222.653606)
		(width 0.14478)
		(layer "In11.Cu")
		(net "M_F_CPU1_SA_DQ<20>")
	)
	(segment
		(start 23.130256 -222.653606)
		(end 23.275036 -222.798386)
		(width 0.14478)
		(layer "In11.Cu")
		(net "M_F_CPU1_SA_DQ<20>")
	)
	(segment
		(start 75.994006 -236.528864)
		(end 76.184506 -236.528864)
		(width 0.0889)
		(layer "In11.Cu")
		(net "M_F_CPU1_SA_DQ<20>")
	)
	(segment
		(start 55.23484 -222.144844)
		(end 55.465218 -222.144844)
		(width 0.14478)
		(layer "In11.Cu")
		(net "M_F_CPU1_SA_DQ<20>")
	)
	(segment
		(start 58.826908 -222.410274)
		(end 59.59094 -222.410274)
		(width 0.14478)
		(layer "In11.Cu")
		(net "M_F_CPU1_SA_DQ<20>")
	)
	(segment
		(start 49.052988 -222.639636)
		(end 49.052988 -222.573342)
		(width 0.14478)
		(layer "In11.Cu")
		(net "M_F_CPU1_SA_DQ<20>")
	)
	(segment
		(start 42.792904 -221.56039)
		(end 43.032426 -221.56039)
		(width 0.14478)
		(layer "In11.Cu")
		(net "M_F_CPU1_SA_DQ<20>")
	)
	(segment
		(start 55.791354 -222.802704)
		(end 58.434478 -222.802704)
		(width 0.14478)
		(layer "In11.Cu")
		(net "M_F_CPU1_SA_DQ<20>")
	)
	(segment
		(start 27.664664 -221.56039)
		(end 27.919934 -221.56039)
		(width 0.14478)
		(layer "In11.Cu")
		(net "M_F_CPU1_SA_DQ<20>")
	)
	(segment
		(start 79.622396 -238.319818)
		(end 79.634334 -238.326676)
		(width 0.0889)
		(layer "In11.Cu")
		(net "M_F_CPU1_SA_DQ<20>")
	)
	(segment
		(start 51.136296 -221.946724)
		(end 51.299364 -221.783656)
		(width 0.14478)
		(layer "In11.Cu")
		(net "M_F_CPU1_SA_DQ<20>")
	)
	(segment
		(start 28.639516 -221.723458)
		(end 28.792932 -221.570042)
		(width 0.14478)
		(layer "In11.Cu")
		(net "M_F_CPU1_SA_DQ<20>")
	)
	(segment
		(start 58.434478 -222.802704)
		(end 58.826908 -222.410274)
		(width 0.14478)
		(layer "In11.Cu")
		(net "M_F_CPU1_SA_DQ<20>")
	)
	(segment
		(start 50.74285 -221.783656)
		(end 50.905918 -221.946724)
		(width 0.14478)
		(layer "In11.Cu")
		(net "M_F_CPU1_SA_DQ<20>")
	)
	(segment
		(start 79.634334 -238.326676)
		(end 79.65059 -238.336074)
		(width 0.0889)
		(layer "In11.Cu")
		(net "M_F_CPU1_SA_DQ<20>")
	)
	(segment
		(start 33.503616 -222.639636)
		(end 33.666684 -222.802704)
		(width 0.14478)
		(layer "In11.Cu")
		(net "M_F_CPU1_SA_DQ<20>")
	)
	(segment
		(start 54.515258 -222.573342)
		(end 54.515258 -222.639636)
		(width 0.14478)
		(layer "In11.Cu")
		(net "M_F_CPU1_SA_DQ<20>")
	)
	(segment
		(start 24.11603 -222.419926)
		(end 26.805128 -222.419926)
		(width 0.14478)
		(layer "In11.Cu")
		(net "M_F_CPU1_SA_DQ<20>")
	)
	(segment
		(start 54.35219 -222.410274)
		(end 54.515258 -222.573342)
		(width 0.14478)
		(layer "In11.Cu")
		(net "M_F_CPU1_SA_DQ<20>")
	)
	(segment
		(start 28.792932 -221.570042)
		(end 30.480508 -221.570042)
		(width 0.14478)
		(layer "In11.Cu")
		(net "M_F_CPU1_SA_DQ<20>")
	)
	(segment
		(start 43.032426 -221.56039)
		(end 43.195494 -221.723458)
		(width 0.14478)
		(layer "In11.Cu")
		(net "M_F_CPU1_SA_DQ<20>")
	)
	(segment
		(start 76.184506 -236.528864)
		(end 76.669646 -237.014004)
		(width 0.0889)
		(layer "In11.Cu")
		(net "M_F_CPU1_SA_DQ<20>")
	)
	(segment
		(start 26.805128 -222.419926)
		(end 27.664664 -221.56039)
		(width 0.14478)
		(layer "In11.Cu")
		(net "M_F_CPU1_SA_DQ<20>")
	)
	(segment
		(start 33.666684 -222.802704)
		(end 33.897062 -222.802704)
		(width 0.14478)
		(layer "In11.Cu")
		(net "M_F_CPU1_SA_DQ<20>")
	)
	(segment
		(start 59.59094 -222.410274)
		(end 61.78677 -224.606104)
		(width 0.14478)
		(layer "In11.Cu")
		(net "M_F_CPU1_SA_DQ<20>")
	)
	(segment
		(start 50.74285 -221.723458)
		(end 50.74285 -221.783656)
		(width 0.14478)
		(layer "In11.Cu")
		(net "M_F_CPU1_SA_DQ<20>")
	)
	(segment
		(start 79.0575 -238.333788)
		(end 79.069184 -238.32693)
		(width 0.0889)
		(layer "In11.Cu")
		(net "M_F_CPU1_SA_DQ<20>")
	)
	(segment
		(start 54.678326 -222.802704)
		(end 54.908704 -222.802704)
		(width 0.14478)
		(layer "In11.Cu")
		(net "M_F_CPU1_SA_DQ<20>")
	)
	(segment
		(start 78.28534 -238.250476)
		(end 78.41107 -238.250476)
		(width 0.0889)
		(layer "In11.Cu")
		(net "M_F_CPU1_SA_DQ<20>")
	)
	(segment
		(start 36.011866 -221.954344)
		(end 36.174934 -221.791276)
		(width 0.14478)
		(layer "In11.Cu")
		(net "M_F_CPU1_SA_DQ<20>")
	)
	(segment
		(start 48.88992 -222.802704)
		(end 49.052988 -222.639636)
		(width 0.14478)
		(layer "In11.Cu")
		(net "M_F_CPU1_SA_DQ<20>")
	)
	(segment
		(start 55.071772 -222.639636)
		(end 55.071772 -222.307912)
		(width 0.14478)
		(layer "In11.Cu")
		(net "M_F_CPU1_SA_DQ<20>")
	)
	(segment
		(start 72.549766 -236.528864)
		(end 75.994006 -236.528864)
		(width 0.14478)
		(layer "In11.Cu")
		(net "M_F_CPU1_SA_DQ<20>")
	)
	(segment
		(start 76.669646 -237.014004)
		(end 77.048868 -237.014004)
		(width 0.0889)
		(layer "In11.Cu")
		(net "M_F_CPU1_SA_DQ<20>")
	)
	(segment
		(start 41.60139 -222.573342)
		(end 41.764458 -222.410274)
		(width 0.14478)
		(layer "In11.Cu")
		(net "M_F_CPU1_SA_DQ<20>")
	)
	(segment
		(start 33.3502 -222.419926)
		(end 33.503616 -222.573342)
		(width 0.14478)
		(layer "In11.Cu")
		(net "M_F_CPU1_SA_DQ<20>")
	)
	(segment
		(start 23.275036 -222.798386)
		(end 23.82647 -222.798386)
		(width 0.14478)
		(layer "In11.Cu")
		(net "M_F_CPU1_SA_DQ<20>")
	)
	(segment
		(start 55.628286 -222.639636)
		(end 55.791354 -222.802704)
		(width 0.14478)
		(layer "In11.Cu")
		(net "M_F_CPU1_SA_DQ<20>")
	)
	(segment
		(start 43.358562 -221.946724)
		(end 43.58894 -221.946724)
		(width 0.14478)
		(layer "In11.Cu")
		(net "M_F_CPU1_SA_DQ<20>")
	)
	(segment
		(start 28.639516 -221.791276)
		(end 28.639516 -221.723458)
		(width 0.14478)
		(layer "In11.Cu")
		(net "M_F_CPU1_SA_DQ<20>")
	)
	(segment
		(start 30.480508 -221.570042)
		(end 31.330392 -222.419926)
		(width 0.14478)
		(layer "In11.Cu")
		(net "M_F_CPU1_SA_DQ<20>")
	)
	(segment
		(start 34.223198 -222.410274)
		(end 34.383218 -222.410274)
		(width 0.14478)
		(layer "In11.Cu")
		(net "M_F_CPU1_SA_DQ<20>")
	)
	(segment
		(start 82.453988 -238.32693)
		(end 82.46237 -238.331756)
		(width 0.0889)
		(layer "In11.Cu")
		(net "M_F_CPU1_SA_DQ<20>")
	)
	(segment
		(start 50.905918 -221.946724)
		(end 51.136296 -221.946724)
		(width 0.14478)
		(layer "In11.Cu")
		(net "M_F_CPU1_SA_DQ<20>")
	)
	(segment
		(start 33.503616 -222.573342)
		(end 33.503616 -222.639636)
		(width 0.14478)
		(layer "In11.Cu")
		(net "M_F_CPU1_SA_DQ<20>")
	)
	(segment
		(start 43.752008 -221.783656)
		(end 43.752008 -221.723458)
		(width 0.14478)
		(layer "In11.Cu")
		(net "M_F_CPU1_SA_DQ<20>")
	)
	(segment
		(start 41.60139 -222.639636)
		(end 41.60139 -222.573342)
		(width 0.14478)
		(layer "In11.Cu")
		(net "M_F_CPU1_SA_DQ<20>")
	)
	(segment
		(start 28.083002 -221.791276)
		(end 28.24607 -221.954344)
		(width 0.14478)
		(layer "In11.Cu")
		(net "M_F_CPU1_SA_DQ<20>")
	)
	(segment
		(start 55.465218 -222.144844)
		(end 55.628286 -222.307912)
		(width 0.14478)
		(layer "In11.Cu")
		(net "M_F_CPU1_SA_DQ<20>")
	)
	(segment
		(start 40.89146 -222.419926)
		(end 41.044876 -222.573342)
		(width 0.14478)
		(layer "In11.Cu")
		(net "M_F_CPU1_SA_DQ<20>")
	)
	(segment
		(start 48.659542 -222.802704)
		(end 48.88992 -222.802704)
		(width 0.14478)
		(layer "In11.Cu")
		(net "M_F_CPU1_SA_DQ<20>")
	)
	(segment
		(start 28.083002 -221.723458)
		(end 28.083002 -221.791276)
		(width 0.14478)
		(layer "In11.Cu")
		(net "M_F_CPU1_SA_DQ<20>")
	)
	(segment
		(start 55.628286 -222.307912)
		(end 55.628286 -222.639636)
		(width 0.14478)
		(layer "In11.Cu")
		(net "M_F_CPU1_SA_DQ<20>")
	)
	(segment
		(start 53.961792 -222.410274)
		(end 54.35219 -222.410274)
		(width 0.14478)
		(layer "In11.Cu")
		(net "M_F_CPU1_SA_DQ<20>")
	)
	(segment
		(start 45.577506 -221.570042)
		(end 46.42739 -222.419926)
		(width 0.14478)
		(layer "In11.Cu")
		(net "M_F_CPU1_SA_DQ<20>")
	)
	(segment
		(start 49.052988 -222.573342)
		(end 49.216056 -222.410274)
		(width 0.14478)
		(layer "In11.Cu")
		(net "M_F_CPU1_SA_DQ<20>")
	)
	(segment
		(start 54.515258 -222.639636)
		(end 54.678326 -222.802704)
		(width 0.14478)
		(layer "In11.Cu")
		(net "M_F_CPU1_SA_DQ<20>")
	)
	(segment
		(start 35.455352 -221.56039)
		(end 35.61842 -221.723458)
		(width 0.14478)
		(layer "In11.Cu")
		(net "M_F_CPU1_SA_DQ<20>")
	)
	(segment
		(start 23.97125 -222.564706)
		(end 24.11603 -222.419926)
		(width 0.14478)
		(layer "In11.Cu")
		(net "M_F_CPU1_SA_DQ<20>")
	)
	(segment
		(start 61.78677 -225.765868)
		(end 72.549766 -236.528864)
		(width 0.14478)
		(layer "In11.Cu")
		(net "M_F_CPU1_SA_DQ<20>")
	)
	(segment
		(start 41.044876 -222.639636)
		(end 41.207944 -222.802704)
		(width 0.14478)
		(layer "In11.Cu")
		(net "M_F_CPU1_SA_DQ<20>")
	)
	(segment
		(start 49.216056 -222.410274)
		(end 49.448974 -222.410274)
		(width 0.14478)
		(layer "In11.Cu")
		(net "M_F_CPU1_SA_DQ<20>")
	)
	(segment
		(start 23.97125 -222.653606)
		(end 23.97125 -222.564706)
		(width 0.14478)
		(layer "In11.Cu")
		(net "M_F_CPU1_SA_DQ<20>")
	)
	(segment
		(start 36.32835 -221.570042)
		(end 37.962332 -221.570042)
		(width 0.14478)
		(layer "In11.Cu")
		(net "M_F_CPU1_SA_DQ<20>")
	)
	(segment
		(start 34.06013 -222.639636)
		(end 34.06013 -222.573342)
		(width 0.14478)
		(layer "In11.Cu")
		(net "M_F_CPU1_SA_DQ<20>")
	)
	(segment
		(start 22.985476 -221.642686)
		(end 23.130256 -221.787466)
		(width 0.14478)
		(layer "In11.Cu")
		(net "M_F_CPU1_SA_DQ<20>")
	)
	(segment
		(start 35.61842 -221.791276)
		(end 35.781488 -221.954344)
		(width 0.14478)
		(layer "In11.Cu")
		(net "M_F_CPU1_SA_DQ<20>")
	)
	(segment
		(start 36.174934 -221.723458)
		(end 36.32835 -221.570042)
		(width 0.14478)
		(layer "In11.Cu")
		(net "M_F_CPU1_SA_DQ<20>")
	)
	(segment
		(start 37.962332 -221.570042)
		(end 38.812216 -222.419926)
		(width 0.14478)
		(layer "In11.Cu")
		(net "M_F_CPU1_SA_DQ<20>")
	)
	(segment
		(start 43.195494 -221.783656)
		(end 43.358562 -221.946724)
		(width 0.14478)
		(layer "In11.Cu")
		(net "M_F_CPU1_SA_DQ<20>")
	)
	(segment
		(start 21.882862 -221.985332)
		(end 22.027642 -222.130112)
		(width 0.14478)
		(layer "In11.Cu")
		(net "M_F_CPU1_SA_DQ<20>")
	)
	(segment
		(start 41.207944 -222.802704)
		(end 41.438322 -222.802704)
		(width 0.14478)
		(layer "In11.Cu")
		(net "M_F_CPU1_SA_DQ<20>")
	)
	(segment
		(start 33.897062 -222.802704)
		(end 34.06013 -222.639636)
		(width 0.14478)
		(layer "In11.Cu")
		(net "M_F_CPU1_SA_DQ<20>")
	)
	(segment
		(start 43.195494 -221.723458)
		(end 43.195494 -221.783656)
		(width 0.14478)
		(layer "In11.Cu")
		(net "M_F_CPU1_SA_DQ<20>")
	)
	(segment
		(start 22.027642 -222.537528)
		(end 22.172422 -222.682308)
		(width 0.14478)
		(layer "In11.Cu")
		(net "M_F_CPU1_SA_DQ<20>")
	)
	(segment
		(start 83.394042 -238.32693)
		(end 83.402424 -238.331756)
		(width 0.0889)
		(layer "In11.Cu")
		(net "M_F_CPU1_SA_DQ<20>")
	)
	(segment
		(start 50.298858 -221.56039)
		(end 50.579782 -221.56039)
		(width 0.14478)
		(layer "In11.Cu")
		(net "M_F_CPU1_SA_DQ<20>")
	)
	(segment
		(start 41.764458 -222.410274)
		(end 41.94302 -222.410274)
		(width 0.14478)
		(layer "In11.Cu")
		(net "M_F_CPU1_SA_DQ<20>")
	)
	(segment
		(start 81.879694 -238.331756)
		(end 81.888076 -238.32693)
		(width 0.0889)
		(layer "In11.Cu")
		(net "M_F_CPU1_SA_DQ<20>")
	)
	(segment
		(start 41.044876 -222.573342)
		(end 41.044876 -222.639636)
		(width 0.14478)
		(layer "In11.Cu")
		(net "M_F_CPU1_SA_DQ<20>")
	)
	(segment
		(start 48.496474 -222.639636)
		(end 48.659542 -222.802704)
		(width 0.14478)
		(layer "In11.Cu")
		(net "M_F_CPU1_SA_DQ<20>")
	)
	(segment
		(start 41.438322 -222.802704)
		(end 41.60139 -222.639636)
		(width 0.14478)
		(layer "In11.Cu")
		(net "M_F_CPU1_SA_DQ<20>")
	)
	(segment
		(start 28.476448 -221.954344)
		(end 28.639516 -221.791276)
		(width 0.14478)
		(layer "In11.Cu")
		(net "M_F_CPU1_SA_DQ<20>")
	)
	(segment
		(start 34.383218 -222.410274)
		(end 35.233102 -221.56039)
		(width 0.14478)
		(layer "In11.Cu")
		(net "M_F_CPU1_SA_DQ<20>")
	)
	(segment
		(start 22.578822 -221.787466)
		(end 22.723602 -221.642686)
		(width 0.14478)
		(layer "In11.Cu")
		(net "M_F_CPU1_SA_DQ<20>")
	)
	(segment
		(start 54.908704 -222.802704)
		(end 55.071772 -222.639636)
		(width 0.14478)
		(layer "In11.Cu")
		(net "M_F_CPU1_SA_DQ<20>")
	)
	(segment
		(start 28.24607 -221.954344)
		(end 28.476448 -221.954344)
		(width 0.14478)
		(layer "In11.Cu")
		(net "M_F_CPU1_SA_DQ<20>")
	)
	(segment
		(start 22.434042 -222.682308)
		(end 22.578822 -222.537528)
		(width 0.14478)
		(layer "In11.Cu")
		(net "M_F_CPU1_SA_DQ<20>")
	)
	(segment
		(start 41.94302 -222.410274)
		(end 42.792904 -221.56039)
		(width 0.14478)
		(layer "In11.Cu")
		(net "M_F_CPU1_SA_DQ<20>")
	)
	(segment
		(start 84.271104 -238.29518)
		(end 84.367116 -238.26978)
		(width 0.0889)
		(layer "In11.Cu")
		(net "M_F_CPU1_SA_DQ<20>")
	)
	(segment
		(start 46.42739 -222.419926)
		(end 48.343058 -222.419926)
		(width 0.14478)
		(layer "In11.Cu")
		(net "M_F_CPU1_SA_DQ<20>")
	)
	(segment
		(start 22.027642 -222.130112)
		(end 22.027642 -222.537528)
		(width 0.14478)
		(layer "In11.Cu")
		(net "M_F_CPU1_SA_DQ<20>")
	)
	(segment
		(start 31.330392 -222.419926)
		(end 33.3502 -222.419926)
		(width 0.14478)
		(layer "In11.Cu")
		(net "M_F_CPU1_SA_DQ<20>")
	)
	(segment
		(start 55.071772 -222.307912)
		(end 55.23484 -222.144844)
		(width 0.14478)
		(layer "In11.Cu")
		(net "M_F_CPU1_SA_DQ<20>")
	)
	(segment
		(start 77.048868 -237.014004)
		(end 78.28534 -238.250476)
		(width 0.0889)
		(layer "In11.Cu")
		(net "M_F_CPU1_SA_DQ<20>")
	)
	(segment
		(start 51.299364 -221.723458)
		(end 51.45278 -221.570042)
		(width 0.14478)
		(layer "In11.Cu")
		(net "M_F_CPU1_SA_DQ<20>")
	)
	(segment
		(start 35.233102 -221.56039)
		(end 35.455352 -221.56039)
		(width 0.14478)
		(layer "In11.Cu")
		(net "M_F_CPU1_SA_DQ<20>")
	)
	(segment
		(start 48.343058 -222.419926)
		(end 48.496474 -222.573342)
		(width 0.14478)
		(layer "In11.Cu")
		(net "M_F_CPU1_SA_DQ<20>")
	)
	(segment
		(start 23.82647 -222.798386)
		(end 23.97125 -222.653606)
		(width 0.14478)
		(layer "In11.Cu")
		(net "M_F_CPU1_SA_DQ<20>")
	)
	(segment
		(start 51.299364 -221.783656)
		(end 51.299364 -221.723458)
		(width 0.14478)
		(layer "In11.Cu")
		(net "M_F_CPU1_SA_DQ<20>")
	)
	(segment
		(start 50.579782 -221.56039)
		(end 50.74285 -221.723458)
		(width 0.14478)
		(layer "In11.Cu")
		(net "M_F_CPU1_SA_DQ<20>")
	)
	(segment
		(start 35.61842 -221.723458)
		(end 35.61842 -221.791276)
		(width 0.14478)
		(layer "In11.Cu")
		(net "M_F_CPU1_SA_DQ<20>")
	)
	(segment
		(start 43.905424 -221.570042)
		(end 45.577506 -221.570042)
		(width 0.14478)
		(layer "In11.Cu")
		(net "M_F_CPU1_SA_DQ<20>")
	)
	(segment
		(start 43.58894 -221.946724)
		(end 43.752008 -221.783656)
		(width 0.14478)
		(layer "In11.Cu")
		(net "M_F_CPU1_SA_DQ<20>")
	)
	(segment
		(start 53.12156 -221.570042)
		(end 53.961792 -222.410274)
		(width 0.14478)
		(layer "In11.Cu")
		(net "M_F_CPU1_SA_DQ<20>")
	)
	(segment
		(start 22.723602 -221.642686)
		(end 22.985476 -221.642686)
		(width 0.14478)
		(layer "In11.Cu")
		(net "M_F_CPU1_SA_DQ<20>")
	)
	(segment
		(start 35.781488 -221.954344)
		(end 36.011866 -221.954344)
		(width 0.14478)
		(layer "In11.Cu")
		(net "M_F_CPU1_SA_DQ<20>")
	)
	(segment
		(start 27.919934 -221.56039)
		(end 28.083002 -221.723458)
		(width 0.14478)
		(layer "In11.Cu")
		(net "M_F_CPU1_SA_DQ<20>")
	)
	(segment
		(start 49.448974 -222.410274)
		(end 50.298858 -221.56039)
		(width 0.14478)
		(layer "In11.Cu")
		(net "M_F_CPU1_SA_DQ<20>")
	)
	(segment
		(start 51.45278 -221.570042)
		(end 53.12156 -221.570042)
		(width 0.14478)
		(layer "In11.Cu")
		(net "M_F_CPU1_SA_DQ<20>")
	)
	(segment
		(start 48.496474 -222.573342)
		(end 48.496474 -222.639636)
		(width 0.14478)
		(layer "In11.Cu")
		(net "M_F_CPU1_SA_DQ<20>")
	)
	(segment
		(start 22.578822 -222.537528)
		(end 22.578822 -221.787466)
		(width 0.14478)
		(layer "In11.Cu")
		(net "M_F_CPU1_SA_DQ<20>")
	)
	(segment
		(start 36.174934 -221.791276)
		(end 36.174934 -221.723458)
		(width 0.14478)
		(layer "In11.Cu")
		(net "M_F_CPU1_SA_DQ<20>")
	)
	(segment
		(start 22.172422 -222.682308)
		(end 22.434042 -222.682308)
		(width 0.14478)
		(layer "In11.Cu")
		(net "M_F_CPU1_SA_DQ<20>")
	)
	(segment
		(start 21.70811 -221.985332)
		(end 21.882862 -221.985332)
		(width 0.14478)
		(layer "In11.Cu")
		(net "M_F_CPU1_SA_DQ<20>")
	)
	(arc
		(start 81.513934 -238.32693)
		(mid 81.696185 -238.37728)
		(end 81.879694 -238.331756)
		(width 0.0889)
		(layer "In11.Cu")
		(net "M_F_CPU1_SA_DQ<20>")
	)
	(arc
		(start 79.65059 -238.336074)
		(mid 79.830572 -238.377174)
		(end 80.008222 -238.32693)
		(width 0.0889)
		(layer "In11.Cu")
		(net "M_F_CPU1_SA_DQ<20>")
	)
	(arc
		(start 78.41107 -238.250476)
		(mid 78.558001 -238.269887)
		(end 78.694788 -238.32693)
		(width 0.0889)
		(layer "In11.Cu")
		(net "M_F_CPU1_SA_DQ<20>")
	)
	(arc
		(start 79.069184 -238.32693)
		(mid 79.344862 -238.2508)
		(end 79.622396 -238.319818)
		(width 0.0889)
		(layer "In11.Cu")
		(net "M_F_CPU1_SA_DQ<20>")
	)
	(arc
		(start 80.574134 -238.32693)
		(mid 80.761078 -238.377185)
		(end 80.948022 -238.32693)
		(width 0.0889)
		(layer "In11.Cu")
		(net "M_F_CPU1_SA_DQ<20>")
	)
	(arc
		(start 82.82813 -238.32693)
		(mid 83.111086 -238.250753)
		(end 83.394042 -238.32693)
		(width 0.0889)
		(layer "In11.Cu")
		(net "M_F_CPU1_SA_DQ<20>")
	)
	(arc
		(start 83.402424 -238.331756)
		(mid 83.585932 -238.37725)
		(end 83.768184 -238.32693)
		(width 0.0889)
		(layer "In11.Cu")
		(net "M_F_CPU1_SA_DQ<20>")
	)
	(arc
		(start 78.694788 -238.32693)
		(mid 78.875246 -238.377374)
		(end 79.0575 -238.333788)
		(width 0.0889)
		(layer "In11.Cu")
		(net "M_F_CPU1_SA_DQ<20>")
	)
	(arc
		(start 81.888076 -238.32693)
		(mid 82.171032 -238.250753)
		(end 82.453988 -238.32693)
		(width 0.0889)
		(layer "In11.Cu")
		(net "M_F_CPU1_SA_DQ<20>")
	)
	(arc
		(start 80.008222 -238.32693)
		(mid 80.291178 -238.250753)
		(end 80.574134 -238.32693)
		(width 0.0889)
		(layer "In11.Cu")
		(net "M_F_CPU1_SA_DQ<20>")
	)
	(arc
		(start 82.46237 -238.331756)
		(mid 82.645878 -238.37725)
		(end 82.82813 -238.32693)
		(width 0.0889)
		(layer "In11.Cu")
		(net "M_F_CPU1_SA_DQ<20>")
	)
	(arc
		(start 80.948022 -238.32693)
		(mid 81.230978 -238.250753)
		(end 81.513934 -238.32693)
		(width 0.0889)
		(layer "In11.Cu")
		(net "M_F_CPU1_SA_DQ<20>")
	)
	(arc
		(start 83.768184 -238.32693)
		(mid 84.015897 -238.25171)
		(end 84.271104 -238.29518)
		(width 0.0889)
		(layer "In11.Cu")
		(net "M_F_CPU1_SA_DQ<20>")
	)
	(segment
		(start 86.397846 -226.120452)
		(end 85.930994 -225.854514)
		(width 0.10668)
		(layer "F.Cu")
		(net "M_F_CPU1_SA_DQ<1>")
	)
	(segment
		(start 37.95268 -198.610474)
		(end 38.802564 -199.460358)
		(width 0.14478)
		(layer "In11.Cu")
		(net "M_F_CPU1_SA_DQ<1>")
	)
	(segment
		(start 22.133052 -199.460358)
		(end 25.941274 -199.460358)
		(width 0.14478)
		(layer "In11.Cu")
		(net "M_F_CPU1_SA_DQ<1>")
	)
	(segment
		(start 73.54062 -213.15299)
		(end 73.771252 -213.15299)
		(width 0.14478)
		(layer "In11.Cu")
		(net "M_F_CPU1_SA_DQ<1>")
	)
	(segment
		(start 30.136338 -198.610474)
		(end 30.70733 -198.846948)
		(width 0.14478)
		(layer "In11.Cu")
		(net "M_F_CPU1_SA_DQ<1>")
	)
	(segment
		(start 71.4629 -211.850478)
		(end 71.693532 -211.850478)
		(width 0.14478)
		(layer "In11.Cu")
		(net "M_F_CPU1_SA_DQ<1>")
	)
	(segment
		(start 41.94302 -199.460358)
		(end 42.792904 -198.610474)
		(width 0.14478)
		(layer "In11.Cu")
		(net "M_F_CPU1_SA_DQ<1>")
	)
	(segment
		(start 71.693532 -211.850478)
		(end 71.96582 -211.57819)
		(width 0.14478)
		(layer "In11.Cu")
		(net "M_F_CPU1_SA_DQ<1>")
	)
	(segment
		(start 73.662032 -213.818978)
		(end 73.662032 -214.04961)
		(width 0.14478)
		(layer "In11.Cu")
		(net "M_F_CPU1_SA_DQ<1>")
	)
	(segment
		(start 72.087232 -212.244178)
		(end 72.087232 -212.47481)
		(width 0.14478)
		(layer "In11.Cu")
		(net "M_F_CPU1_SA_DQ<1>")
	)
	(segment
		(start 79.16418 -222.93707)
		(end 79.201772 -222.958914)
		(width 0.0889)
		(layer "In11.Cu")
		(net "M_F_CPU1_SA_DQ<1>")
	)
	(segment
		(start 84.229702 -226.18192)
		(end 84.238084 -226.177094)
		(width 0.0889)
		(layer "In11.Cu")
		(net "M_F_CPU1_SA_DQ<1>")
	)
	(segment
		(start 85.681058 -226.145344)
		(end 85.77707 -226.119944)
		(width 0.0889)
		(layer "In11.Cu")
		(net "M_F_CPU1_SA_DQ<1>")
	)
	(segment
		(start 73.662032 -214.04961)
		(end 76.077826 -216.465404)
		(width 0.14478)
		(layer "In11.Cu")
		(net "M_F_CPU1_SA_DQ<1>")
	)
	(segment
		(start 53.111908 -198.610474)
		(end 53.961792 -199.460358)
		(width 0.14478)
		(layer "In11.Cu")
		(net "M_F_CPU1_SA_DQ<1>")
	)
	(segment
		(start 85.77707 -226.119944)
		(end 85.930994 -225.854514)
		(width 0.0889)
		(layer "In11.Cu")
		(net "M_F_CPU1_SA_DQ<1>")
	)
	(segment
		(start 76.077826 -216.465404)
		(end 76.077826 -218.814904)
		(width 0.14478)
		(layer "In11.Cu")
		(net "M_F_CPU1_SA_DQ<1>")
	)
	(segment
		(start 71.299832 -211.456778)
		(end 71.299832 -211.68741)
		(width 0.14478)
		(layer "In11.Cu")
		(net "M_F_CPU1_SA_DQ<1>")
	)
	(segment
		(start 78.69428 -222.127064)
		(end 78.732126 -222.148908)
		(width 0.0889)
		(layer "In11.Cu")
		(net "M_F_CPU1_SA_DQ<1>")
	)
	(segment
		(start 71.409052 -210.79079)
		(end 71.57212 -210.953858)
		(width 0.14478)
		(layer "In11.Cu")
		(net "M_F_CPU1_SA_DQ<1>")
	)
	(segment
		(start 73.93432 -213.316058)
		(end 73.93432 -213.54669)
		(width 0.14478)
		(layer "In11.Cu")
		(net "M_F_CPU1_SA_DQ<1>")
	)
	(segment
		(start 72.35952 -211.741258)
		(end 72.35952 -211.97189)
		(width 0.14478)
		(layer "In11.Cu")
		(net "M_F_CPU1_SA_DQ<1>")
	)
	(segment
		(start 71.96582 -211.57819)
		(end 72.196452 -211.57819)
		(width 0.14478)
		(layer "In11.Cu")
		(net "M_F_CPU1_SA_DQ<1>")
	)
	(segment
		(start 79.60233 -225.3488)
		(end 79.63408 -225.367088)
		(width 0.0889)
		(layer "In11.Cu")
		(net "M_F_CPU1_SA_DQ<1>")
	)
	(segment
		(start 76.077826 -218.814904)
		(end 78.523846 -221.260924)
		(width 0.14478)
		(layer "In11.Cu")
		(net "M_F_CPU1_SA_DQ<1>")
	)
	(segment
		(start 73.93432 -213.54669)
		(end 73.662032 -213.818978)
		(width 0.14478)
		(layer "In11.Cu")
		(net "M_F_CPU1_SA_DQ<1>")
	)
	(segment
		(start 78.555088 -222.068644)
		(end 78.583282 -222.077788)
		(width 0.0889)
		(layer "In11.Cu")
		(net "M_F_CPU1_SA_DQ<1>")
	)
	(segment
		(start 72.983852 -212.36559)
		(end 73.14692 -212.528658)
		(width 0.14478)
		(layer "In11.Cu")
		(net "M_F_CPU1_SA_DQ<1>")
	)
	(segment
		(start 83.289648 -226.18192)
		(end 83.29803 -226.177094)
		(width 0.0889)
		(layer "In11.Cu")
		(net "M_F_CPU1_SA_DQ<1>")
	)
	(segment
		(start 72.2503 -212.637878)
		(end 72.480932 -212.637878)
		(width 0.14478)
		(layer "In11.Cu")
		(net "M_F_CPU1_SA_DQ<1>")
	)
	(segment
		(start 79.63408 -224.721928)
		(end 79.60233 -224.740216)
		(width 0.0889)
		(layer "In11.Cu")
		(net "M_F_CPU1_SA_DQ<1>")
	)
	(segment
		(start 71.299832 -211.68741)
		(end 71.4629 -211.850478)
		(width 0.14478)
		(layer "In11.Cu")
		(net "M_F_CPU1_SA_DQ<1>")
	)
	(segment
		(start 72.75322 -212.36559)
		(end 72.983852 -212.36559)
		(width 0.14478)
		(layer "In11.Cu")
		(net "M_F_CPU1_SA_DQ<1>")
	)
	(segment
		(start 45.567854 -198.610474)
		(end 46.417738 -199.460358)
		(width 0.14478)
		(layer "In11.Cu")
		(net "M_F_CPU1_SA_DQ<1>")
	)
	(segment
		(start 84.803996 -226.177094)
		(end 84.812378 -226.18192)
		(width 0.0889)
		(layer "In11.Cu")
		(net "M_F_CPU1_SA_DQ<1>")
	)
	(segment
		(start 56.954674 -199.460358)
		(end 57.804558 -198.610474)
		(width 0.14478)
		(layer "In11.Cu")
		(net "M_F_CPU1_SA_DQ<1>")
	)
	(segment
		(start 27.993086 -198.610474)
		(end 30.136338 -198.610474)
		(width 0.14478)
		(layer "In11.Cu")
		(net "M_F_CPU1_SA_DQ<1>")
	)
	(segment
		(start 79.63408 -225.367088)
		(end 79.671926 -225.388932)
		(width 0.0889)
		(layer "In11.Cu")
		(net "M_F_CPU1_SA_DQ<1>")
	)
	(segment
		(start 78.523846 -222.008192)
		(end 78.555088 -222.068644)
		(width 0.0889)
		(layer "In11.Cu")
		(net "M_F_CPU1_SA_DQ<1>")
	)
	(segment
		(start 72.874632 -213.26221)
		(end 73.0377 -213.425278)
		(width 0.14478)
		(layer "In11.Cu")
		(net "M_F_CPU1_SA_DQ<1>")
	)
	(segment
		(start 71.57212 -211.18449)
		(end 71.299832 -211.456778)
		(width 0.14478)
		(layer "In11.Cu")
		(net "M_F_CPU1_SA_DQ<1>")
	)
	(segment
		(start 72.480932 -212.637878)
		(end 72.75322 -212.36559)
		(width 0.14478)
		(layer "In11.Cu")
		(net "M_F_CPU1_SA_DQ<1>")
	)
	(segment
		(start 80.0735 -226.159314)
		(end 80.10398 -226.177094)
		(width 0.0889)
		(layer "In11.Cu")
		(net "M_F_CPU1_SA_DQ<1>")
	)
	(segment
		(start 80.46974 -226.18192)
		(end 80.478122 -226.177094)
		(width 0.0889)
		(layer "In11.Cu")
		(net "M_F_CPU1_SA_DQ<1>")
	)
	(segment
		(start 70.6755 -211.063078)
		(end 70.906132 -211.063078)
		(width 0.14478)
		(layer "In11.Cu")
		(net "M_F_CPU1_SA_DQ<1>")
	)
	(segment
		(start 21.70811 -199.035416)
		(end 22.133052 -199.460358)
		(width 0.14478)
		(layer "In11.Cu")
		(net "M_F_CPU1_SA_DQ<1>")
	)
	(segment
		(start 70.411086 -210.798664)
		(end 70.6755 -211.063078)
		(width 0.14478)
		(layer "In11.Cu")
		(net "M_F_CPU1_SA_DQ<1>")
	)
	(segment
		(start 73.14692 -212.75929)
		(end 72.874632 -213.031578)
		(width 0.14478)
		(layer "In11.Cu")
		(net "M_F_CPU1_SA_DQ<1>")
	)
	(segment
		(start 35.233102 -198.610474)
		(end 37.95268 -198.610474)
		(width 0.14478)
		(layer "In11.Cu")
		(net "M_F_CPU1_SA_DQ<1>")
	)
	(segment
		(start 57.804558 -198.610474)
		(end 59.937396 -198.610474)
		(width 0.14478)
		(layer "In11.Cu")
		(net "M_F_CPU1_SA_DQ<1>")
	)
	(segment
		(start 42.792904 -198.610474)
		(end 45.567854 -198.610474)
		(width 0.14478)
		(layer "In11.Cu")
		(net "M_F_CPU1_SA_DQ<1>")
	)
	(segment
		(start 79.600552 -223.727518)
		(end 79.634334 -223.747076)
		(width 0.0889)
		(layer "In11.Cu")
		(net "M_F_CPU1_SA_DQ<1>")
	)
	(segment
		(start 73.0377 -213.425278)
		(end 73.268332 -213.425278)
		(width 0.14478)
		(layer "In11.Cu")
		(net "M_F_CPU1_SA_DQ<1>")
	)
	(segment
		(start 32.18815 -199.460358)
		(end 34.383218 -199.460358)
		(width 0.14478)
		(layer "In11.Cu")
		(net "M_F_CPU1_SA_DQ<1>")
	)
	(segment
		(start 72.35952 -211.97189)
		(end 72.087232 -212.244178)
		(width 0.14478)
		(layer "In11.Cu")
		(net "M_F_CPU1_SA_DQ<1>")
	)
	(segment
		(start 70.411086 -209.084164)
		(end 70.411086 -210.798664)
		(width 0.14478)
		(layer "In11.Cu")
		(net "M_F_CPU1_SA_DQ<1>")
	)
	(segment
		(start 49.448974 -199.460358)
		(end 50.298858 -198.610474)
		(width 0.14478)
		(layer "In11.Cu")
		(net "M_F_CPU1_SA_DQ<1>")
	)
	(segment
		(start 73.268332 -213.425278)
		(end 73.54062 -213.15299)
		(width 0.14478)
		(layer "In11.Cu")
		(net "M_F_CPU1_SA_DQ<1>")
	)
	(segment
		(start 81.044034 -226.177094)
		(end 81.052416 -226.18192)
		(width 0.0889)
		(layer "In11.Cu")
		(net "M_F_CPU1_SA_DQ<1>")
	)
	(segment
		(start 30.70733 -198.846948)
		(end 32.18815 -199.460358)
		(width 0.14478)
		(layer "In11.Cu")
		(net "M_F_CPU1_SA_DQ<1>")
	)
	(segment
		(start 59.937396 -198.610474)
		(end 70.411086 -209.084164)
		(width 0.14478)
		(layer "In11.Cu")
		(net "M_F_CPU1_SA_DQ<1>")
	)
	(segment
		(start 46.417738 -199.460358)
		(end 49.448974 -199.460358)
		(width 0.14478)
		(layer "In11.Cu")
		(net "M_F_CPU1_SA_DQ<1>")
	)
	(segment
		(start 78.523846 -221.260924)
		(end 78.523846 -222.008192)
		(width 0.0889)
		(layer "In11.Cu")
		(net "M_F_CPU1_SA_DQ<1>")
	)
	(segment
		(start 73.14692 -212.528658)
		(end 73.14692 -212.75929)
		(width 0.14478)
		(layer "In11.Cu")
		(net "M_F_CPU1_SA_DQ<1>")
	)
	(segment
		(start 72.874632 -213.031578)
		(end 72.874632 -213.26221)
		(width 0.14478)
		(layer "In11.Cu")
		(net "M_F_CPU1_SA_DQ<1>")
	)
	(segment
		(start 53.961792 -199.460358)
		(end 56.954674 -199.460358)
		(width 0.14478)
		(layer "In11.Cu")
		(net "M_F_CPU1_SA_DQ<1>")
	)
	(segment
		(start 38.802564 -199.460358)
		(end 41.94302 -199.460358)
		(width 0.14478)
		(layer "In11.Cu")
		(net "M_F_CPU1_SA_DQ<1>")
	)
	(segment
		(start 73.771252 -213.15299)
		(end 73.93432 -213.316058)
		(width 0.14478)
		(layer "In11.Cu")
		(net "M_F_CPU1_SA_DQ<1>")
	)
	(segment
		(start 79.634334 -223.747076)
		(end 79.670656 -223.768158)
		(width 0.0889)
		(layer "In11.Cu")
		(net "M_F_CPU1_SA_DQ<1>")
	)
	(segment
		(start 79.1337 -222.91929)
		(end 79.16418 -222.93707)
		(width 0.0889)
		(layer "In11.Cu")
		(net "M_F_CPU1_SA_DQ<1>")
	)
	(segment
		(start 34.383218 -199.460358)
		(end 35.233102 -198.610474)
		(width 0.14478)
		(layer "In11.Cu")
		(net "M_F_CPU1_SA_DQ<1>")
	)
	(segment
		(start 71.57212 -210.953858)
		(end 71.57212 -211.18449)
		(width 0.14478)
		(layer "In11.Cu")
		(net "M_F_CPU1_SA_DQ<1>")
	)
	(segment
		(start 50.298858 -198.610474)
		(end 53.111908 -198.610474)
		(width 0.14478)
		(layer "In11.Cu")
		(net "M_F_CPU1_SA_DQ<1>")
	)
	(segment
		(start 25.941274 -199.460358)
		(end 27.993086 -198.610474)
		(width 0.14478)
		(layer "In11.Cu")
		(net "M_F_CPU1_SA_DQ<1>")
	)
	(segment
		(start 71.17842 -210.79079)
		(end 71.409052 -210.79079)
		(width 0.14478)
		(layer "In11.Cu")
		(net "M_F_CPU1_SA_DQ<1>")
	)
	(segment
		(start 72.196452 -211.57819)
		(end 72.35952 -211.741258)
		(width 0.14478)
		(layer "In11.Cu")
		(net "M_F_CPU1_SA_DQ<1>")
	)
	(segment
		(start 70.906132 -211.063078)
		(end 71.17842 -210.79079)
		(width 0.14478)
		(layer "In11.Cu")
		(net "M_F_CPU1_SA_DQ<1>")
	)
	(segment
		(start 79.671926 -224.700084)
		(end 79.63408 -224.721928)
		(width 0.0889)
		(layer "In11.Cu")
		(net "M_F_CPU1_SA_DQ<1>")
	)
	(segment
		(start 72.087232 -212.47481)
		(end 72.2503 -212.637878)
		(width 0.14478)
		(layer "In11.Cu")
		(net "M_F_CPU1_SA_DQ<1>")
	)
	(arc
		(start 78.732126 -222.148908)
		(mid 78.911855 -222.351528)
		(end 78.976728 -222.61449)
		(width 0.0889)
		(layer "In11.Cu")
		(net "M_F_CPU1_SA_DQ<1>")
	)
	(arc
		(start 79.201772 -222.958914)
		(mid 79.381501 -223.161534)
		(end 79.446374 -223.424496)
		(width 0.0889)
		(layer "In11.Cu")
		(net "M_F_CPU1_SA_DQ<1>")
	)
	(arc
		(start 83.29803 -226.177094)
		(mid 83.580986 -226.100917)
		(end 83.863942 -226.177094)
		(width 0.0889)
		(layer "In11.Cu")
		(net "M_F_CPU1_SA_DQ<1>")
	)
	(arc
		(start 84.812378 -226.18192)
		(mid 84.995886 -226.227414)
		(end 85.178138 -226.177094)
		(width 0.0889)
		(layer "In11.Cu")
		(net "M_F_CPU1_SA_DQ<1>")
	)
	(arc
		(start 78.976728 -222.61449)
		(mid 79.018277 -222.785912)
		(end 79.1337 -222.91929)
		(width 0.0889)
		(layer "In11.Cu")
		(net "M_F_CPU1_SA_DQ<1>")
	)
	(arc
		(start 83.863942 -226.177094)
		(mid 84.046193 -226.227444)
		(end 84.229702 -226.18192)
		(width 0.0889)
		(layer "In11.Cu")
		(net "M_F_CPU1_SA_DQ<1>")
	)
	(arc
		(start 81.052416 -226.18192)
		(mid 81.235924 -226.227414)
		(end 81.418176 -226.177094)
		(width 0.0889)
		(layer "In11.Cu")
		(net "M_F_CPU1_SA_DQ<1>")
	)
	(arc
		(start 85.178138 -226.177094)
		(mid 85.425851 -226.101874)
		(end 85.681058 -226.145344)
		(width 0.0889)
		(layer "In11.Cu")
		(net "M_F_CPU1_SA_DQ<1>")
	)
	(arc
		(start 79.671926 -225.388932)
		(mid 79.851655 -225.591552)
		(end 79.916528 -225.854514)
		(width 0.0889)
		(layer "In11.Cu")
		(net "M_F_CPU1_SA_DQ<1>")
	)
	(arc
		(start 79.446374 -223.424496)
		(mid 79.487132 -223.594494)
		(end 79.600552 -223.727518)
		(width 0.0889)
		(layer "In11.Cu")
		(net "M_F_CPU1_SA_DQ<1>")
	)
	(arc
		(start 79.916528 -225.854514)
		(mid 79.958077 -226.025936)
		(end 80.0735 -226.159314)
		(width 0.0889)
		(layer "In11.Cu")
		(net "M_F_CPU1_SA_DQ<1>")
	)
	(arc
		(start 82.357976 -226.177094)
		(mid 82.640932 -226.100917)
		(end 82.923888 -226.177094)
		(width 0.0889)
		(layer "In11.Cu")
		(net "M_F_CPU1_SA_DQ<1>")
	)
	(arc
		(start 80.10398 -226.177094)
		(mid 80.286231 -226.227444)
		(end 80.46974 -226.18192)
		(width 0.0889)
		(layer "In11.Cu")
		(net "M_F_CPU1_SA_DQ<1>")
	)
	(arc
		(start 79.916528 -224.234502)
		(mid 79.851656 -224.497465)
		(end 79.671926 -224.700084)
		(width 0.0889)
		(layer "In11.Cu")
		(net "M_F_CPU1_SA_DQ<1>")
	)
	(arc
		(start 78.583282 -222.077788)
		(mid 78.640118 -222.099416)
		(end 78.69428 -222.127064)
		(width 0.0889)
		(layer "In11.Cu")
		(net "M_F_CPU1_SA_DQ<1>")
	)
	(arc
		(start 81.984088 -226.177094)
		(mid 82.171032 -226.227349)
		(end 82.357976 -226.177094)
		(width 0.0889)
		(layer "In11.Cu")
		(net "M_F_CPU1_SA_DQ<1>")
	)
	(arc
		(start 81.418176 -226.177094)
		(mid 81.701132 -226.100917)
		(end 81.984088 -226.177094)
		(width 0.0889)
		(layer "In11.Cu")
		(net "M_F_CPU1_SA_DQ<1>")
	)
	(arc
		(start 79.670656 -223.768158)
		(mid 79.851308 -223.970903)
		(end 79.916528 -224.234502)
		(width 0.0889)
		(layer "In11.Cu")
		(net "M_F_CPU1_SA_DQ<1>")
	)
	(arc
		(start 82.923888 -226.177094)
		(mid 83.106139 -226.227444)
		(end 83.289648 -226.18192)
		(width 0.0889)
		(layer "In11.Cu")
		(net "M_F_CPU1_SA_DQ<1>")
	)
	(arc
		(start 84.238084 -226.177094)
		(mid 84.52104 -226.100917)
		(end 84.803996 -226.177094)
		(width 0.0889)
		(layer "In11.Cu")
		(net "M_F_CPU1_SA_DQ<1>")
	)
	(arc
		(start 79.60233 -224.740216)
		(mid 79.446402 -225.044508)
		(end 79.60233 -225.3488)
		(width 0.0889)
		(layer "In11.Cu")
		(net "M_F_CPU1_SA_DQ<1>")
	)
	(arc
		(start 80.478122 -226.177094)
		(mid 80.761078 -226.100917)
		(end 81.044034 -226.177094)
		(width 0.0889)
		(layer "In11.Cu")
		(net "M_F_CPU1_SA_DQ<1>")
	)
	(segment
		(start 85.927946 -236.650276)
		(end 85.461094 -236.384338)
		(width 0.10668)
		(layer "F.Cu")
		(net "M_F_CPU1_SA_DQ<19>")
	)
	(segment
		(start 30.534102 -218.150694)
		(end 31.383986 -219.000578)
		(width 0.14478)
		(layer "In11.Cu")
		(net "M_F_CPU1_SA_DQ<19>")
	)
	(segment
		(start 75.628246 -234.166664)
		(end 76.037186 -234.166664)
		(width 0.0889)
		(layer "In11.Cu")
		(net "M_F_CPU1_SA_DQ<19>")
	)
	(segment
		(start 77.180186 -235.1405)
		(end 78.012544 -235.972858)
		(width 0.0889)
		(layer "In11.Cu")
		(net "M_F_CPU1_SA_DQ<19>")
	)
	(segment
		(start 46.458886 -219.000578)
		(end 49.399698 -219.000578)
		(width 0.14478)
		(layer "In11.Cu")
		(net "M_F_CPU1_SA_DQ<19>")
	)
	(segment
		(start 18.023332 -219.000578)
		(end 26.737564 -219.000578)
		(width 0.14478)
		(layer "In11.Cu")
		(net "M_F_CPU1_SA_DQ<19>")
	)
	(segment
		(start 85.615018 -236.118908)
		(end 85.461094 -236.384338)
		(width 0.0889)
		(layer "In11.Cu")
		(net "M_F_CPU1_SA_DQ<19>")
	)
	(segment
		(start 78.693772 -236.061758)
		(end 78.705456 -236.0549)
		(width 0.0889)
		(layer "In11.Cu")
		(net "M_F_CPU1_SA_DQ<19>")
	)
	(segment
		(start 27.587448 -218.150694)
		(end 30.534102 -218.150694)
		(width 0.14478)
		(layer "In11.Cu")
		(net "M_F_CPU1_SA_DQ<19>")
	)
	(segment
		(start 76.037186 -234.166664)
		(end 76.545186 -234.674664)
		(width 0.0889)
		(layer "In11.Cu")
		(net "M_F_CPU1_SA_DQ<19>")
	)
	(segment
		(start 35.21837 -218.150694)
		(end 38.103556 -218.150694)
		(width 0.14478)
		(layer "In11.Cu")
		(net "M_F_CPU1_SA_DQ<19>")
	)
	(segment
		(start 17.608042 -218.585288)
		(end 18.023332 -219.000578)
		(width 0.14478)
		(layer "In11.Cu")
		(net "M_F_CPU1_SA_DQ<19>")
	)
	(segment
		(start 45.609002 -218.150694)
		(end 46.458886 -219.000578)
		(width 0.14478)
		(layer "In11.Cu")
		(net "M_F_CPU1_SA_DQ<19>")
	)
	(segment
		(start 64.132206 -223.096328)
		(end 64.132206 -224.244408)
		(width 0.14478)
		(layer "In11.Cu")
		(net "M_F_CPU1_SA_DQ<19>")
	)
	(segment
		(start 57.33669 -218.609926)
		(end 57.78627 -218.160346)
		(width 0.14478)
		(layer "In11.Cu")
		(net "M_F_CPU1_SA_DQ<19>")
	)
	(segment
		(start 49.399698 -219.000578)
		(end 50.249582 -218.150694)
		(width 0.14478)
		(layer "In11.Cu")
		(net "M_F_CPU1_SA_DQ<19>")
	)
	(segment
		(start 26.737564 -219.000578)
		(end 27.587448 -218.150694)
		(width 0.14478)
		(layer "In11.Cu")
		(net "M_F_CPU1_SA_DQ<19>")
	)
	(segment
		(start 79.06766 -236.061758)
		(end 79.078074 -236.067854)
		(width 0.0889)
		(layer "In11.Cu")
		(net "M_F_CPU1_SA_DQ<19>")
	)
	(segment
		(start 57.78627 -218.160346)
		(end 59.196224 -218.160346)
		(width 0.14478)
		(layer "In11.Cu")
		(net "M_F_CPU1_SA_DQ<19>")
	)
	(segment
		(start 76.964286 -234.674664)
		(end 77.180186 -234.890564)
		(width 0.0889)
		(layer "In11.Cu")
		(net "M_F_CPU1_SA_DQ<19>")
	)
	(segment
		(start 85.592666 -236.035596)
		(end 85.615018 -236.118908)
		(width 0.0889)
		(layer "In11.Cu")
		(net "M_F_CPU1_SA_DQ<19>")
	)
	(segment
		(start 83.394042 -236.061758)
		(end 83.402424 -236.056932)
		(width 0.0889)
		(layer "In11.Cu")
		(net "M_F_CPU1_SA_DQ<19>")
	)
	(segment
		(start 76.545186 -234.674664)
		(end 76.964286 -234.674664)
		(width 0.0889)
		(layer "In11.Cu")
		(net "M_F_CPU1_SA_DQ<19>")
	)
	(segment
		(start 74.054462 -234.166664)
		(end 75.628246 -234.166664)
		(width 0.14478)
		(layer "In11.Cu")
		(net "M_F_CPU1_SA_DQ<19>")
	)
	(segment
		(start 31.383986 -219.000578)
		(end 34.368486 -219.000578)
		(width 0.14478)
		(layer "In11.Cu")
		(net "M_F_CPU1_SA_DQ<19>")
	)
	(segment
		(start 53.145436 -218.150694)
		(end 53.604668 -218.609926)
		(width 0.14478)
		(layer "In11.Cu")
		(net "M_F_CPU1_SA_DQ<19>")
	)
	(segment
		(start 38.95344 -219.000578)
		(end 41.901872 -219.000578)
		(width 0.14478)
		(layer "In11.Cu")
		(net "M_F_CPU1_SA_DQ<19>")
	)
	(segment
		(start 81.879694 -236.056932)
		(end 81.888076 -236.061758)
		(width 0.0889)
		(layer "In11.Cu")
		(net "M_F_CPU1_SA_DQ<19>")
	)
	(segment
		(start 77.180186 -234.890564)
		(end 77.180186 -235.1405)
		(width 0.0889)
		(layer "In11.Cu")
		(net "M_F_CPU1_SA_DQ<19>")
	)
	(segment
		(start 34.368486 -219.000578)
		(end 35.21837 -218.150694)
		(width 0.14478)
		(layer "In11.Cu")
		(net "M_F_CPU1_SA_DQ<19>")
	)
	(segment
		(start 42.751756 -218.150694)
		(end 45.609002 -218.150694)
		(width 0.14478)
		(layer "In11.Cu")
		(net "M_F_CPU1_SA_DQ<19>")
	)
	(segment
		(start 53.604668 -218.609926)
		(end 57.33669 -218.609926)
		(width 0.14478)
		(layer "In11.Cu")
		(net "M_F_CPU1_SA_DQ<19>")
	)
	(segment
		(start 64.132206 -224.244408)
		(end 74.054462 -234.166664)
		(width 0.14478)
		(layer "In11.Cu")
		(net "M_F_CPU1_SA_DQ<19>")
	)
	(segment
		(start 78.67904 -236.070394)
		(end 78.693772 -236.061758)
		(width 0.0889)
		(layer "In11.Cu")
		(net "M_F_CPU1_SA_DQ<19>")
	)
	(segment
		(start 38.103556 -218.150694)
		(end 38.95344 -219.000578)
		(width 0.14478)
		(layer "In11.Cu")
		(net "M_F_CPU1_SA_DQ<19>")
	)
	(segment
		(start 50.249582 -218.150694)
		(end 53.145436 -218.150694)
		(width 0.14478)
		(layer "In11.Cu")
		(net "M_F_CPU1_SA_DQ<19>")
	)
	(segment
		(start 82.453988 -236.061758)
		(end 82.46237 -236.056932)
		(width 0.0889)
		(layer "In11.Cu")
		(net "M_F_CPU1_SA_DQ<19>")
	)
	(segment
		(start 59.196224 -218.160346)
		(end 64.132206 -223.096328)
		(width 0.14478)
		(layer "In11.Cu")
		(net "M_F_CPU1_SA_DQ<19>")
	)
	(segment
		(start 41.901872 -219.000578)
		(end 42.751756 -218.150694)
		(width 0.14478)
		(layer "In11.Cu")
		(net "M_F_CPU1_SA_DQ<19>")
	)
	(arc
		(start 80.008222 -236.061758)
		(mid 80.291178 -236.137935)
		(end 80.574134 -236.061758)
		(width 0.0889)
		(layer "In11.Cu")
		(net "M_F_CPU1_SA_DQ<19>")
	)
	(arc
		(start 82.46237 -236.056932)
		(mid 82.645878 -236.011438)
		(end 82.82813 -236.061758)
		(width 0.0889)
		(layer "In11.Cu")
		(net "M_F_CPU1_SA_DQ<19>")
	)
	(arc
		(start 83.402424 -236.056932)
		(mid 83.585932 -236.011438)
		(end 83.768184 -236.061758)
		(width 0.0889)
		(layer "In11.Cu")
		(net "M_F_CPU1_SA_DQ<19>")
	)
	(arc
		(start 84.707984 -236.061758)
		(mid 84.99094 -236.137935)
		(end 85.273896 -236.061758)
		(width 0.0889)
		(layer "In11.Cu")
		(net "M_F_CPU1_SA_DQ<19>")
	)
	(arc
		(start 82.82813 -236.061758)
		(mid 83.111086 -236.137935)
		(end 83.394042 -236.061758)
		(width 0.0889)
		(layer "In11.Cu")
		(net "M_F_CPU1_SA_DQ<19>")
	)
	(arc
		(start 83.768184 -236.061758)
		(mid 84.05114 -236.137935)
		(end 84.334096 -236.061758)
		(width 0.0889)
		(layer "In11.Cu")
		(net "M_F_CPU1_SA_DQ<19>")
	)
	(arc
		(start 78.705456 -236.0549)
		(mid 78.887457 -236.011367)
		(end 79.06766 -236.061758)
		(width 0.0889)
		(layer "In11.Cu")
		(net "M_F_CPU1_SA_DQ<19>")
	)
	(arc
		(start 80.948022 -236.061758)
		(mid 81.230978 -236.137935)
		(end 81.513934 -236.061758)
		(width 0.0889)
		(layer "In11.Cu")
		(net "M_F_CPU1_SA_DQ<19>")
	)
	(arc
		(start 85.273896 -236.061758)
		(mid 85.430334 -236.012787)
		(end 85.592666 -236.035596)
		(width 0.0889)
		(layer "In11.Cu")
		(net "M_F_CPU1_SA_DQ<19>")
	)
	(arc
		(start 79.633826 -236.061758)
		(mid 79.821024 -236.011376)
		(end 80.008222 -236.061758)
		(width 0.0889)
		(layer "In11.Cu")
		(net "M_F_CPU1_SA_DQ<19>")
	)
	(arc
		(start 79.078074 -236.067854)
		(mid 79.35676 -236.138074)
		(end 79.633826 -236.061758)
		(width 0.0889)
		(layer "In11.Cu")
		(net "M_F_CPU1_SA_DQ<19>")
	)
	(arc
		(start 81.513934 -236.061758)
		(mid 81.696185 -236.011408)
		(end 81.879694 -236.056932)
		(width 0.0889)
		(layer "In11.Cu")
		(net "M_F_CPU1_SA_DQ<19>")
	)
	(arc
		(start 78.012544 -235.972858)
		(mid 78.067316 -236.021052)
		(end 78.12786 -236.061758)
		(width 0.0889)
		(layer "In11.Cu")
		(net "M_F_CPU1_SA_DQ<19>")
	)
	(arc
		(start 78.12786 -236.061758)
		(mid 78.402312 -236.137994)
		(end 78.67904 -236.070394)
		(width 0.0889)
		(layer "In11.Cu")
		(net "M_F_CPU1_SA_DQ<19>")
	)
	(arc
		(start 80.574134 -236.061758)
		(mid 80.761078 -236.011503)
		(end 80.948022 -236.061758)
		(width 0.0889)
		(layer "In11.Cu")
		(net "M_F_CPU1_SA_DQ<19>")
	)
	(arc
		(start 84.334096 -236.061758)
		(mid 84.52104 -236.011503)
		(end 84.707984 -236.061758)
		(width 0.0889)
		(layer "In11.Cu")
		(net "M_F_CPU1_SA_DQ<19>")
	)
	(arc
		(start 81.888076 -236.061758)
		(mid 82.171032 -236.137935)
		(end 82.453988 -236.061758)
		(width 0.0889)
		(layer "In11.Cu")
		(net "M_F_CPU1_SA_DQ<19>")
	)
	(segment
		(start 84.517992 -235.84027)
		(end 84.05114 -235.574332)
		(width 0.10668)
		(layer "F.Cu")
		(net "M_F_CPU1_SA_DQ<18>")
	)
	(segment
		(start 59.88177 -217.486992)
		(end 65.061846 -222.667068)
		(width 0.14478)
		(layer "In11.Cu")
		(net "M_F_CPU1_SA_DQ<18>")
	)
	(segment
		(start 56.936132 -217.310462)
		(end 57.78627 -216.460324)
		(width 0.14478)
		(layer "In11.Cu")
		(net "M_F_CPU1_SA_DQ<18>")
	)
	(segment
		(start 45.618654 -216.460324)
		(end 46.468792 -217.310462)
		(width 0.14478)
		(layer "In11.Cu")
		(net "M_F_CPU1_SA_DQ<18>")
	)
	(segment
		(start 74.431398 -233.257344)
		(end 75.628246 -233.257344)
		(width 0.14478)
		(layer "In11.Cu")
		(net "M_F_CPU1_SA_DQ<18>")
	)
	(segment
		(start 79.525114 -235.244132)
		(end 79.53883 -235.252006)
		(width 0.0889)
		(layer "In11.Cu")
		(net "M_F_CPU1_SA_DQ<18>")
	)
	(segment
		(start 76.240386 -233.654092)
		(end 76.689458 -234.103164)
		(width 0.0889)
		(layer "In11.Cu")
		(net "M_F_CPU1_SA_DQ<18>")
	)
	(segment
		(start 57.78627 -216.460324)
		(end 59.632342 -216.460324)
		(width 0.14478)
		(layer "In11.Cu")
		(net "M_F_CPU1_SA_DQ<18>")
	)
	(segment
		(start 80.46974 -235.246926)
		(end 80.478122 -235.251752)
		(width 0.0889)
		(layer "In11.Cu")
		(net "M_F_CPU1_SA_DQ<18>")
	)
	(segment
		(start 59.88177 -216.709752)
		(end 59.88177 -217.486992)
		(width 0.14478)
		(layer "In11.Cu")
		(net "M_F_CPU1_SA_DQ<18>")
	)
	(segment
		(start 79.53883 -235.252006)
		(end 79.550768 -235.258864)
		(width 0.0889)
		(layer "In11.Cu")
		(net "M_F_CPU1_SA_DQ<18>")
	)
	(segment
		(start 81.044034 -235.251752)
		(end 81.052416 -235.246926)
		(width 0.0889)
		(layer "In11.Cu")
		(net "M_F_CPU1_SA_DQ<18>")
	)
	(segment
		(start 78.14945 -235.201714)
		(end 78.411324 -235.20146)
		(width 0.0889)
		(layer "In11.Cu")
		(net "M_F_CPU1_SA_DQ<18>")
	)
	(segment
		(start 38.113208 -216.460324)
		(end 38.963346 -217.310462)
		(width 0.14478)
		(layer "In11.Cu")
		(net "M_F_CPU1_SA_DQ<18>")
	)
	(segment
		(start 20.069302 -217.144346)
		(end 20.235418 -217.310462)
		(width 0.14478)
		(layer "In11.Cu")
		(net "M_F_CPU1_SA_DQ<18>")
	)
	(segment
		(start 35.208718 -216.460324)
		(end 38.113208 -216.460324)
		(width 0.14478)
		(layer "In11.Cu")
		(net "M_F_CPU1_SA_DQ<18>")
	)
	(segment
		(start 31.393892 -217.310462)
		(end 34.35858 -217.310462)
		(width 0.14478)
		(layer "In11.Cu")
		(net "M_F_CPU1_SA_DQ<18>")
	)
	(segment
		(start 84.205064 -235.308902)
		(end 84.05114 -235.574332)
		(width 0.0889)
		(layer "In11.Cu")
		(net "M_F_CPU1_SA_DQ<18>")
	)
	(segment
		(start 65.061846 -223.887792)
		(end 74.431398 -233.257344)
		(width 0.14478)
		(layer "In11.Cu")
		(net "M_F_CPU1_SA_DQ<18>")
	)
	(segment
		(start 50.23993 -216.460324)
		(end 53.155088 -216.460324)
		(width 0.14478)
		(layer "In11.Cu")
		(net "M_F_CPU1_SA_DQ<18>")
	)
	(segment
		(start 76.240386 -233.544364)
		(end 76.240386 -233.654092)
		(width 0.0889)
		(layer "In11.Cu")
		(net "M_F_CPU1_SA_DQ<18>")
	)
	(segment
		(start 79.147162 -235.26242)
		(end 79.165196 -235.251752)
		(width 0.0889)
		(layer "In11.Cu")
		(net "M_F_CPU1_SA_DQ<18>")
	)
	(segment
		(start 53.155088 -216.460324)
		(end 54.005226 -217.310462)
		(width 0.14478)
		(layer "In11.Cu")
		(net "M_F_CPU1_SA_DQ<18>")
	)
	(segment
		(start 42.742104 -216.460324)
		(end 45.618654 -216.460324)
		(width 0.14478)
		(layer "In11.Cu")
		(net "M_F_CPU1_SA_DQ<18>")
	)
	(segment
		(start 34.35858 -217.310462)
		(end 35.208718 -216.460324)
		(width 0.14478)
		(layer "In11.Cu")
		(net "M_F_CPU1_SA_DQ<18>")
	)
	(segment
		(start 65.061846 -222.667068)
		(end 65.061846 -223.887792)
		(width 0.14478)
		(layer "In11.Cu")
		(net "M_F_CPU1_SA_DQ<18>")
	)
	(segment
		(start 17.608042 -216.885266)
		(end 18.033238 -217.310462)
		(width 0.14478)
		(layer "In11.Cu")
		(net "M_F_CPU1_SA_DQ<18>")
	)
	(segment
		(start 20.235418 -217.310462)
		(end 26.727658 -217.310462)
		(width 0.14478)
		(layer "In11.Cu")
		(net "M_F_CPU1_SA_DQ<18>")
	)
	(segment
		(start 18.033238 -217.310462)
		(end 19.517868 -217.310462)
		(width 0.14478)
		(layer "In11.Cu")
		(net "M_F_CPU1_SA_DQ<18>")
	)
	(segment
		(start 84.182712 -235.22559)
		(end 84.205064 -235.308902)
		(width 0.0889)
		(layer "In11.Cu")
		(net "M_F_CPU1_SA_DQ<18>")
	)
	(segment
		(start 76.689458 -234.103164)
		(end 77.045058 -234.103164)
		(width 0.0889)
		(layer "In11.Cu")
		(net "M_F_CPU1_SA_DQ<18>")
	)
	(segment
		(start 19.517868 -217.310462)
		(end 19.683984 -217.144346)
		(width 0.14478)
		(layer "In11.Cu")
		(net "M_F_CPU1_SA_DQ<18>")
	)
	(segment
		(start 59.632342 -216.460324)
		(end 59.88177 -216.709752)
		(width 0.14478)
		(layer "In11.Cu")
		(net "M_F_CPU1_SA_DQ<18>")
	)
	(segment
		(start 30.543754 -216.460324)
		(end 31.393892 -217.310462)
		(width 0.14478)
		(layer "In11.Cu")
		(net "M_F_CPU1_SA_DQ<18>")
	)
	(segment
		(start 49.389792 -217.310462)
		(end 50.23993 -216.460324)
		(width 0.14478)
		(layer "In11.Cu")
		(net "M_F_CPU1_SA_DQ<18>")
	)
	(segment
		(start 75.628246 -233.257344)
		(end 75.953366 -233.257344)
		(width 0.0889)
		(layer "In11.Cu")
		(net "M_F_CPU1_SA_DQ<18>")
	)
	(segment
		(start 46.468792 -217.310462)
		(end 49.389792 -217.310462)
		(width 0.14478)
		(layer "In11.Cu")
		(net "M_F_CPU1_SA_DQ<18>")
	)
	(segment
		(start 38.963346 -217.310462)
		(end 41.891966 -217.310462)
		(width 0.14478)
		(layer "In11.Cu")
		(net "M_F_CPU1_SA_DQ<18>")
	)
	(segment
		(start 41.891966 -217.310462)
		(end 42.742104 -216.460324)
		(width 0.14478)
		(layer "In11.Cu")
		(net "M_F_CPU1_SA_DQ<18>")
	)
	(segment
		(start 26.727658 -217.310462)
		(end 27.577796 -216.460324)
		(width 0.14478)
		(layer "In11.Cu")
		(net "M_F_CPU1_SA_DQ<18>")
	)
	(segment
		(start 27.577796 -216.460324)
		(end 30.543754 -216.460324)
		(width 0.14478)
		(layer "In11.Cu")
		(net "M_F_CPU1_SA_DQ<18>")
	)
	(segment
		(start 75.953366 -233.257344)
		(end 76.240386 -233.544364)
		(width 0.0889)
		(layer "In11.Cu")
		(net "M_F_CPU1_SA_DQ<18>")
	)
	(segment
		(start 77.045058 -234.103164)
		(end 78.143608 -235.201714)
		(width 0.0889)
		(layer "In11.Cu")
		(net "M_F_CPU1_SA_DQ<18>")
	)
	(segment
		(start 19.683984 -217.144346)
		(end 20.069302 -217.144346)
		(width 0.14478)
		(layer "In11.Cu")
		(net "M_F_CPU1_SA_DQ<18>")
	)
	(segment
		(start 78.143608 -235.201714)
		(end 78.14945 -235.201714)
		(width 0.0889)
		(layer "In11.Cu")
		(net "M_F_CPU1_SA_DQ<18>")
	)
	(segment
		(start 54.005226 -217.310462)
		(end 56.936132 -217.310462)
		(width 0.14478)
		(layer "In11.Cu")
		(net "M_F_CPU1_SA_DQ<18>")
	)
	(segment
		(start 83.289648 -235.246926)
		(end 83.29803 -235.251752)
		(width 0.0889)
		(layer "In11.Cu")
		(net "M_F_CPU1_SA_DQ<18>")
	)
	(arc
		(start 81.418176 -235.251752)
		(mid 81.701132 -235.327929)
		(end 81.984088 -235.251752)
		(width 0.0889)
		(layer "In11.Cu")
		(net "M_F_CPU1_SA_DQ<18>")
	)
	(arc
		(start 82.357976 -235.251752)
		(mid 82.640932 -235.327929)
		(end 82.923888 -235.251752)
		(width 0.0889)
		(layer "In11.Cu")
		(net "M_F_CPU1_SA_DQ<18>")
	)
	(arc
		(start 79.165196 -235.251752)
		(mid 79.344183 -235.201582)
		(end 79.525114 -235.244132)
		(width 0.0889)
		(layer "In11.Cu")
		(net "M_F_CPU1_SA_DQ<18>")
	)
	(arc
		(start 80.478122 -235.251752)
		(mid 80.761078 -235.327929)
		(end 81.044034 -235.251752)
		(width 0.0889)
		(layer "In11.Cu")
		(net "M_F_CPU1_SA_DQ<18>")
	)
	(arc
		(start 83.863942 -235.251752)
		(mid 84.02038 -235.202781)
		(end 84.182712 -235.22559)
		(width 0.0889)
		(layer "In11.Cu")
		(net "M_F_CPU1_SA_DQ<18>")
	)
	(arc
		(start 83.29803 -235.251752)
		(mid 83.580986 -235.327929)
		(end 83.863942 -235.251752)
		(width 0.0889)
		(layer "In11.Cu")
		(net "M_F_CPU1_SA_DQ<18>")
	)
	(arc
		(start 81.052416 -235.246926)
		(mid 81.235924 -235.201432)
		(end 81.418176 -235.251752)
		(width 0.0889)
		(layer "In11.Cu")
		(net "M_F_CPU1_SA_DQ<18>")
	)
	(arc
		(start 78.411324 -235.20146)
		(mid 78.508256 -235.214211)
		(end 78.598522 -235.251752)
		(width 0.0889)
		(layer "In11.Cu")
		(net "M_F_CPU1_SA_DQ<18>")
	)
	(arc
		(start 81.984088 -235.251752)
		(mid 82.171032 -235.201497)
		(end 82.357976 -235.251752)
		(width 0.0889)
		(layer "In11.Cu")
		(net "M_F_CPU1_SA_DQ<18>")
	)
	(arc
		(start 80.10398 -235.251752)
		(mid 80.286231 -235.201402)
		(end 80.46974 -235.246926)
		(width 0.0889)
		(layer "In11.Cu")
		(net "M_F_CPU1_SA_DQ<18>")
	)
	(arc
		(start 79.550768 -235.258864)
		(mid 79.828302 -235.327845)
		(end 80.10398 -235.251752)
		(width 0.0889)
		(layer "In11.Cu")
		(net "M_F_CPU1_SA_DQ<18>")
	)
	(arc
		(start 78.598522 -235.251752)
		(mid 78.871466 -235.328332)
		(end 79.147162 -235.26242)
		(width 0.0889)
		(layer "In11.Cu")
		(net "M_F_CPU1_SA_DQ<18>")
	)
	(arc
		(start 82.923888 -235.251752)
		(mid 83.106139 -235.201402)
		(end 83.289648 -235.246926)
		(width 0.0889)
		(layer "In11.Cu")
		(net "M_F_CPU1_SA_DQ<18>")
	)
	(segment
		(start 86.397846 -235.84027)
		(end 85.930994 -235.574332)
		(width 0.10668)
		(layer "F.Cu")
		(net "M_F_CPU1_SA_DQ<17>")
	)
	(segment
		(start 49.19345 -218.160346)
		(end 49.448974 -218.160346)
		(width 0.14478)
		(layer "In11.Cu")
		(net "M_F_CPU1_SA_DQ<17>")
	)
	(segment
		(start 50.80254 -217.47353)
		(end 50.80254 -217.539316)
		(width 0.14478)
		(layer "In11.Cu")
		(net "M_F_CPU1_SA_DQ<17>")
	)
	(segment
		(start 36.09721 -217.700606)
		(end 36.2585 -217.539316)
		(width 0.14478)
		(layer "In11.Cu")
		(net "M_F_CPU1_SA_DQ<17>")
	)
	(segment
		(start 37.95268 -217.310462)
		(end 38.802564 -218.160346)
		(width 0.14478)
		(layer "In11.Cu")
		(net "M_F_CPU1_SA_DQ<17>")
	)
	(segment
		(start 53.961792 -218.160346)
		(end 56.954674 -218.160346)
		(width 0.14478)
		(layer "In11.Cu")
		(net "M_F_CPU1_SA_DQ<17>")
	)
	(segment
		(start 28.844748 -217.310462)
		(end 30.470856 -217.310462)
		(width 0.14478)
		(layer "In11.Cu")
		(net "M_F_CPU1_SA_DQ<17>")
	)
	(segment
		(start 35.701986 -217.47353)
		(end 35.701986 -217.539316)
		(width 0.14478)
		(layer "In11.Cu")
		(net "M_F_CPU1_SA_DQ<17>")
	)
	(segment
		(start 76.695046 -234.458764)
		(end 77.078586 -234.458764)
		(width 0.0889)
		(layer "In11.Cu")
		(net "M_F_CPU1_SA_DQ<17>")
	)
	(segment
		(start 48.3108 -218.160346)
		(end 48.473868 -218.323414)
		(width 0.14478)
		(layer "In11.Cu")
		(net "M_F_CPU1_SA_DQ<17>")
	)
	(segment
		(start 59.03722 -217.310462)
		(end 64.586866 -222.860108)
		(width 0.14478)
		(layer "In11.Cu")
		(net "M_F_CPU1_SA_DQ<17>")
	)
	(segment
		(start 57.804558 -217.310462)
		(end 59.03722 -217.310462)
		(width 0.14478)
		(layer "In11.Cu")
		(net "M_F_CPU1_SA_DQ<17>")
	)
	(segment
		(start 33.470596 -218.550744)
		(end 33.700974 -218.550744)
		(width 0.14478)
		(layer "In11.Cu")
		(net "M_F_CPU1_SA_DQ<17>")
	)
	(segment
		(start 41.512998 -218.323414)
		(end 41.676066 -218.160346)
		(width 0.14478)
		(layer "In11.Cu")
		(net "M_F_CPU1_SA_DQ<17>")
	)
	(segment
		(start 49.448974 -218.160346)
		(end 50.298858 -217.310462)
		(width 0.14478)
		(layer "In11.Cu")
		(net "M_F_CPU1_SA_DQ<17>")
	)
	(segment
		(start 84.803996 -235.896912)
		(end 84.812378 -235.901738)
		(width 0.0889)
		(layer "In11.Cu")
		(net "M_F_CPU1_SA_DQ<17>")
	)
	(segment
		(start 48.473868 -218.391486)
		(end 48.618648 -218.536266)
		(width 0.14478)
		(layer "In11.Cu")
		(net "M_F_CPU1_SA_DQ<17>")
	)
	(segment
		(start 48.885602 -218.536266)
		(end 49.030382 -218.391486)
		(width 0.14478)
		(layer "In11.Cu")
		(net "M_F_CPU1_SA_DQ<17>")
	)
	(segment
		(start 35.863276 -217.700606)
		(end 36.09721 -217.700606)
		(width 0.14478)
		(layer "In11.Cu")
		(net "M_F_CPU1_SA_DQ<17>")
	)
	(segment
		(start 51.213004 -217.685366)
		(end 51.359054 -217.539316)
		(width 0.14478)
		(layer "In11.Cu")
		(net "M_F_CPU1_SA_DQ<17>")
	)
	(segment
		(start 35.233102 -217.310462)
		(end 35.538918 -217.310462)
		(width 0.14478)
		(layer "In11.Cu")
		(net "M_F_CPU1_SA_DQ<17>")
	)
	(segment
		(start 84.229702 -235.901738)
		(end 84.238084 -235.896912)
		(width 0.0889)
		(layer "In11.Cu")
		(net "M_F_CPU1_SA_DQ<17>")
	)
	(segment
		(start 42.792904 -217.310462)
		(end 43.044364 -217.310462)
		(width 0.14478)
		(layer "In11.Cu")
		(net "M_F_CPU1_SA_DQ<17>")
	)
	(segment
		(start 77.383386 -234.763564)
		(end 77.383386 -235.074206)
		(width 0.0889)
		(layer "In11.Cu")
		(net "M_F_CPU1_SA_DQ<17>")
	)
	(segment
		(start 80.093566 -235.890816)
		(end 80.10398 -235.896912)
		(width 0.0889)
		(layer "In11.Cu")
		(net "M_F_CPU1_SA_DQ<17>")
	)
	(segment
		(start 33.307528 -218.323414)
		(end 33.307528 -218.387676)
		(width 0.14478)
		(layer "In11.Cu")
		(net "M_F_CPU1_SA_DQ<17>")
	)
	(segment
		(start 33.700974 -218.550744)
		(end 33.864042 -218.387676)
		(width 0.14478)
		(layer "In11.Cu")
		(net "M_F_CPU1_SA_DQ<17>")
	)
	(segment
		(start 77.078586 -234.458764)
		(end 77.383386 -234.763564)
		(width 0.0889)
		(layer "In11.Cu")
		(net "M_F_CPU1_SA_DQ<17>")
	)
	(segment
		(start 64.586866 -222.860108)
		(end 64.586866 -224.05594)
		(width 0.14478)
		(layer "In11.Cu")
		(net "M_F_CPU1_SA_DQ<17>")
	)
	(segment
		(start 50.298858 -217.310462)
		(end 50.639472 -217.310462)
		(width 0.14478)
		(layer "In11.Cu")
		(net "M_F_CPU1_SA_DQ<17>")
	)
	(segment
		(start 41.512998 -218.392756)
		(end 41.512998 -218.323414)
		(width 0.14478)
		(layer "In11.Cu")
		(net "M_F_CPU1_SA_DQ<17>")
	)
	(segment
		(start 26.538682 -218.160346)
		(end 26.81478 -218.160346)
		(width 0.14478)
		(layer "In11.Cu")
		(net "M_F_CPU1_SA_DQ<17>")
	)
	(segment
		(start 41.105074 -218.541346)
		(end 41.364408 -218.541346)
		(width 0.14478)
		(layer "In11.Cu")
		(net "M_F_CPU1_SA_DQ<17>")
	)
	(segment
		(start 28.68168 -217.47353)
		(end 28.844748 -217.310462)
		(width 0.14478)
		(layer "In11.Cu")
		(net "M_F_CPU1_SA_DQ<17>")
	)
	(segment
		(start 49.030382 -218.323414)
		(end 49.19345 -218.160346)
		(width 0.14478)
		(layer "In11.Cu")
		(net "M_F_CPU1_SA_DQ<17>")
	)
	(segment
		(start 81.044034 -235.896912)
		(end 81.052416 -235.901738)
		(width 0.0889)
		(layer "In11.Cu")
		(net "M_F_CPU1_SA_DQ<17>")
	)
	(segment
		(start 41.364408 -218.541346)
		(end 41.512998 -218.392756)
		(width 0.14478)
		(layer "In11.Cu")
		(net "M_F_CPU1_SA_DQ<17>")
	)
	(segment
		(start 33.864042 -218.323414)
		(end 34.02711 -218.160346)
		(width 0.14478)
		(layer "In11.Cu")
		(net "M_F_CPU1_SA_DQ<17>")
	)
	(segment
		(start 26.224484 -218.543886)
		(end 26.375614 -218.392756)
		(width 0.14478)
		(layer "In11.Cu")
		(net "M_F_CPU1_SA_DQ<17>")
	)
	(segment
		(start 53.111908 -217.310462)
		(end 53.961792 -218.160346)
		(width 0.14478)
		(layer "In11.Cu")
		(net "M_F_CPU1_SA_DQ<17>")
	)
	(segment
		(start 33.307528 -218.387676)
		(end 33.470596 -218.550744)
		(width 0.14478)
		(layer "In11.Cu")
		(net "M_F_CPU1_SA_DQ<17>")
	)
	(segment
		(start 50.94859 -217.685366)
		(end 51.213004 -217.685366)
		(width 0.14478)
		(layer "In11.Cu")
		(net "M_F_CPU1_SA_DQ<17>")
	)
	(segment
		(start 46.417738 -218.160346)
		(end 48.3108 -218.160346)
		(width 0.14478)
		(layer "In11.Cu")
		(net "M_F_CPU1_SA_DQ<17>")
	)
	(segment
		(start 28.68168 -217.539316)
		(end 28.68168 -217.47353)
		(width 0.14478)
		(layer "In11.Cu")
		(net "M_F_CPU1_SA_DQ<17>")
	)
	(segment
		(start 80.46974 -235.901738)
		(end 80.478122 -235.896912)
		(width 0.0889)
		(layer "In11.Cu")
		(net "M_F_CPU1_SA_DQ<17>")
	)
	(segment
		(start 51.359054 -217.539316)
		(end 51.359054 -217.47353)
		(width 0.14478)
		(layer "In11.Cu")
		(net "M_F_CPU1_SA_DQ<17>")
	)
	(segment
		(start 83.289648 -235.901738)
		(end 83.29803 -235.896912)
		(width 0.0889)
		(layer "In11.Cu")
		(net "M_F_CPU1_SA_DQ<17>")
	)
	(segment
		(start 21.70811 -217.735404)
		(end 22.133052 -218.160346)
		(width 0.14478)
		(layer "In11.Cu")
		(net "M_F_CPU1_SA_DQ<17>")
	)
	(segment
		(start 45.567854 -217.310462)
		(end 46.417738 -218.160346)
		(width 0.14478)
		(layer "In11.Cu")
		(net "M_F_CPU1_SA_DQ<17>")
	)
	(segment
		(start 27.664664 -217.310462)
		(end 27.962098 -217.310462)
		(width 0.14478)
		(layer "In11.Cu")
		(net "M_F_CPU1_SA_DQ<17>")
	)
	(segment
		(start 48.618648 -218.536266)
		(end 48.885602 -218.536266)
		(width 0.14478)
		(layer "In11.Cu")
		(net "M_F_CPU1_SA_DQ<17>")
	)
	(segment
		(start 35.701986 -217.539316)
		(end 35.863276 -217.700606)
		(width 0.14478)
		(layer "In11.Cu")
		(net "M_F_CPU1_SA_DQ<17>")
	)
	(segment
		(start 51.522122 -217.310462)
		(end 53.111908 -217.310462)
		(width 0.14478)
		(layer "In11.Cu")
		(net "M_F_CPU1_SA_DQ<17>")
	)
	(segment
		(start 51.359054 -217.47353)
		(end 51.522122 -217.310462)
		(width 0.14478)
		(layer "In11.Cu")
		(net "M_F_CPU1_SA_DQ<17>")
	)
	(segment
		(start 48.473868 -218.323414)
		(end 48.473868 -218.391486)
		(width 0.14478)
		(layer "In11.Cu")
		(net "M_F_CPU1_SA_DQ<17>")
	)
	(segment
		(start 28.125166 -217.539316)
		(end 28.273756 -217.687906)
		(width 0.14478)
		(layer "In11.Cu")
		(net "M_F_CPU1_SA_DQ<17>")
	)
	(segment
		(start 31.32074 -218.160346)
		(end 33.14446 -218.160346)
		(width 0.14478)
		(layer "In11.Cu")
		(net "M_F_CPU1_SA_DQ<17>")
	)
	(segment
		(start 28.53309 -217.687906)
		(end 28.68168 -217.539316)
		(width 0.14478)
		(layer "In11.Cu")
		(net "M_F_CPU1_SA_DQ<17>")
	)
	(segment
		(start 36.2585 -217.47353)
		(end 36.421568 -217.310462)
		(width 0.14478)
		(layer "In11.Cu")
		(net "M_F_CPU1_SA_DQ<17>")
	)
	(segment
		(start 75.948286 -233.712004)
		(end 76.695046 -234.458764)
		(width 0.0889)
		(layer "In11.Cu")
		(net "M_F_CPU1_SA_DQ<17>")
	)
	(segment
		(start 34.383218 -218.160346)
		(end 35.233102 -217.310462)
		(width 0.14478)
		(layer "In11.Cu")
		(net "M_F_CPU1_SA_DQ<17>")
	)
	(segment
		(start 64.586866 -224.05594)
		(end 74.24293 -233.712004)
		(width 0.14478)
		(layer "In11.Cu")
		(net "M_F_CPU1_SA_DQ<17>")
	)
	(segment
		(start 36.2585 -217.539316)
		(end 36.2585 -217.47353)
		(width 0.14478)
		(layer "In11.Cu")
		(net "M_F_CPU1_SA_DQ<17>")
	)
	(segment
		(start 34.02711 -218.160346)
		(end 34.383218 -218.160346)
		(width 0.14478)
		(layer "In11.Cu")
		(net "M_F_CPU1_SA_DQ<17>")
	)
	(segment
		(start 50.80254 -217.539316)
		(end 50.94859 -217.685366)
		(width 0.14478)
		(layer "In11.Cu")
		(net "M_F_CPU1_SA_DQ<17>")
	)
	(segment
		(start 26.81478 -218.160346)
		(end 27.664664 -217.310462)
		(width 0.14478)
		(layer "In11.Cu")
		(net "M_F_CPU1_SA_DQ<17>")
	)
	(segment
		(start 24.23414 -218.160346)
		(end 25.656032 -218.160346)
		(width 0.14478)
		(layer "In11.Cu")
		(net "M_F_CPU1_SA_DQ<17>")
	)
	(segment
		(start 75.628246 -233.712004)
		(end 75.948286 -233.712004)
		(width 0.0889)
		(layer "In11.Cu")
		(net "M_F_CPU1_SA_DQ<17>")
	)
	(segment
		(start 33.14446 -218.160346)
		(end 33.307528 -218.323414)
		(width 0.14478)
		(layer "In11.Cu")
		(net "M_F_CPU1_SA_DQ<17>")
	)
	(segment
		(start 49.030382 -218.391486)
		(end 49.030382 -218.323414)
		(width 0.14478)
		(layer "In11.Cu")
		(net "M_F_CPU1_SA_DQ<17>")
	)
	(segment
		(start 56.954674 -218.160346)
		(end 57.804558 -217.310462)
		(width 0.14478)
		(layer "In11.Cu")
		(net "M_F_CPU1_SA_DQ<17>")
	)
	(segment
		(start 25.8191 -218.323414)
		(end 25.8191 -218.392756)
		(width 0.14478)
		(layer "In11.Cu")
		(net "M_F_CPU1_SA_DQ<17>")
	)
	(segment
		(start 40.956484 -218.323414)
		(end 40.956484 -218.392756)
		(width 0.14478)
		(layer "In11.Cu")
		(net "M_F_CPU1_SA_DQ<17>")
	)
	(segment
		(start 25.97023 -218.543886)
		(end 26.224484 -218.543886)
		(width 0.14478)
		(layer "In11.Cu")
		(net "M_F_CPU1_SA_DQ<17>")
	)
	(segment
		(start 23.682706 -218.343226)
		(end 24.05126 -218.343226)
		(width 0.14478)
		(layer "In11.Cu")
		(net "M_F_CPU1_SA_DQ<17>")
	)
	(segment
		(start 43.366182 -217.698066)
		(end 43.605196 -217.698066)
		(width 0.14478)
		(layer "In11.Cu")
		(net "M_F_CPU1_SA_DQ<17>")
	)
	(segment
		(start 78.583282 -235.905294)
		(end 78.608174 -235.890816)
		(width 0.0889)
		(layer "In11.Cu")
		(net "M_F_CPU1_SA_DQ<17>")
	)
	(segment
		(start 23.499826 -218.160346)
		(end 23.682706 -218.343226)
		(width 0.14478)
		(layer "In11.Cu")
		(net "M_F_CPU1_SA_DQ<17>")
	)
	(segment
		(start 25.656032 -218.160346)
		(end 25.8191 -218.323414)
		(width 0.14478)
		(layer "In11.Cu")
		(net "M_F_CPU1_SA_DQ<17>")
	)
	(segment
		(start 85.77707 -235.839762)
		(end 85.930994 -235.574332)
		(width 0.0889)
		(layer "In11.Cu")
		(net "M_F_CPU1_SA_DQ<17>")
	)
	(segment
		(start 43.207432 -217.47353)
		(end 43.207432 -217.539316)
		(width 0.14478)
		(layer "In11.Cu")
		(net "M_F_CPU1_SA_DQ<17>")
	)
	(segment
		(start 43.044364 -217.310462)
		(end 43.207432 -217.47353)
		(width 0.14478)
		(layer "In11.Cu")
		(net "M_F_CPU1_SA_DQ<17>")
	)
	(segment
		(start 43.605196 -217.698066)
		(end 43.763946 -217.539316)
		(width 0.14478)
		(layer "In11.Cu")
		(net "M_F_CPU1_SA_DQ<17>")
	)
	(segment
		(start 43.763946 -217.539316)
		(end 43.763946 -217.47353)
		(width 0.14478)
		(layer "In11.Cu")
		(net "M_F_CPU1_SA_DQ<17>")
	)
	(segment
		(start 77.383386 -235.074206)
		(end 78.147418 -235.838238)
		(width 0.0889)
		(layer "In11.Cu")
		(net "M_F_CPU1_SA_DQ<17>")
	)
	(segment
		(start 41.676066 -218.160346)
		(end 41.94302 -218.160346)
		(width 0.14478)
		(layer "In11.Cu")
		(net "M_F_CPU1_SA_DQ<17>")
	)
	(segment
		(start 50.639472 -217.310462)
		(end 50.80254 -217.47353)
		(width 0.14478)
		(layer "In11.Cu")
		(net "M_F_CPU1_SA_DQ<17>")
	)
	(segment
		(start 85.681058 -235.865162)
		(end 85.77707 -235.839762)
		(width 0.0889)
		(layer "In11.Cu")
		(net "M_F_CPU1_SA_DQ<17>")
	)
	(segment
		(start 28.125166 -217.47353)
		(end 28.125166 -217.539316)
		(width 0.14478)
		(layer "In11.Cu")
		(net "M_F_CPU1_SA_DQ<17>")
	)
	(segment
		(start 43.763946 -217.47353)
		(end 43.927014 -217.310462)
		(width 0.14478)
		(layer "In11.Cu")
		(net "M_F_CPU1_SA_DQ<17>")
	)
	(segment
		(start 25.8191 -218.392756)
		(end 25.97023 -218.543886)
		(width 0.14478)
		(layer "In11.Cu")
		(net "M_F_CPU1_SA_DQ<17>")
	)
	(segment
		(start 30.470856 -217.310462)
		(end 31.32074 -218.160346)
		(width 0.14478)
		(layer "In11.Cu")
		(net "M_F_CPU1_SA_DQ<17>")
	)
	(segment
		(start 26.375614 -218.392756)
		(end 26.375614 -218.323414)
		(width 0.14478)
		(layer "In11.Cu")
		(net "M_F_CPU1_SA_DQ<17>")
	)
	(segment
		(start 43.927014 -217.310462)
		(end 45.567854 -217.310462)
		(width 0.14478)
		(layer "In11.Cu")
		(net "M_F_CPU1_SA_DQ<17>")
	)
	(segment
		(start 26.375614 -218.323414)
		(end 26.538682 -218.160346)
		(width 0.14478)
		(layer "In11.Cu")
		(net "M_F_CPU1_SA_DQ<17>")
	)
	(segment
		(start 24.05126 -218.343226)
		(end 24.23414 -218.160346)
		(width 0.14478)
		(layer "In11.Cu")
		(net "M_F_CPU1_SA_DQ<17>")
	)
	(segment
		(start 43.207432 -217.539316)
		(end 43.366182 -217.698066)
		(width 0.14478)
		(layer "In11.Cu")
		(net "M_F_CPU1_SA_DQ<17>")
	)
	(segment
		(start 38.802564 -218.160346)
		(end 40.793416 -218.160346)
		(width 0.14478)
		(layer "In11.Cu")
		(net "M_F_CPU1_SA_DQ<17>")
	)
	(segment
		(start 36.421568 -217.310462)
		(end 37.95268 -217.310462)
		(width 0.14478)
		(layer "In11.Cu")
		(net "M_F_CPU1_SA_DQ<17>")
	)
	(segment
		(start 33.864042 -218.387676)
		(end 33.864042 -218.323414)
		(width 0.14478)
		(layer "In11.Cu")
		(net "M_F_CPU1_SA_DQ<17>")
	)
	(segment
		(start 74.24293 -233.712004)
		(end 75.628246 -233.712004)
		(width 0.14478)
		(layer "In11.Cu")
		(net "M_F_CPU1_SA_DQ<17>")
	)
	(segment
		(start 35.538918 -217.310462)
		(end 35.701986 -217.47353)
		(width 0.14478)
		(layer "In11.Cu")
		(net "M_F_CPU1_SA_DQ<17>")
	)
	(segment
		(start 28.273756 -217.687906)
		(end 28.53309 -217.687906)
		(width 0.14478)
		(layer "In11.Cu")
		(net "M_F_CPU1_SA_DQ<17>")
	)
	(segment
		(start 40.793416 -218.160346)
		(end 40.956484 -218.323414)
		(width 0.14478)
		(layer "In11.Cu")
		(net "M_F_CPU1_SA_DQ<17>")
	)
	(segment
		(start 27.962098 -217.310462)
		(end 28.125166 -217.47353)
		(width 0.14478)
		(layer "In11.Cu")
		(net "M_F_CPU1_SA_DQ<17>")
	)
	(segment
		(start 22.133052 -218.160346)
		(end 23.499826 -218.160346)
		(width 0.14478)
		(layer "In11.Cu")
		(net "M_F_CPU1_SA_DQ<17>")
	)
	(segment
		(start 40.956484 -218.392756)
		(end 41.105074 -218.541346)
		(width 0.14478)
		(layer "In11.Cu")
		(net "M_F_CPU1_SA_DQ<17>")
	)
	(segment
		(start 41.94302 -218.160346)
		(end 42.792904 -217.310462)
		(width 0.14478)
		(layer "In11.Cu")
		(net "M_F_CPU1_SA_DQ<17>")
	)
	(arc
		(start 84.238084 -235.896912)
		(mid 84.52104 -235.820735)
		(end 84.803996 -235.896912)
		(width 0.0889)
		(layer "In11.Cu")
		(net "M_F_CPU1_SA_DQ<17>")
	)
	(arc
		(start 80.478122 -235.896912)
		(mid 80.761078 -235.820735)
		(end 81.044034 -235.896912)
		(width 0.0889)
		(layer "In11.Cu")
		(net "M_F_CPU1_SA_DQ<17>")
	)
	(arc
		(start 78.147418 -235.838238)
		(mid 78.354377 -235.943039)
		(end 78.583282 -235.905294)
		(width 0.0889)
		(layer "In11.Cu")
		(net "M_F_CPU1_SA_DQ<17>")
	)
	(arc
		(start 82.923888 -235.896912)
		(mid 83.106139 -235.947262)
		(end 83.289648 -235.901738)
		(width 0.0889)
		(layer "In11.Cu")
		(net "M_F_CPU1_SA_DQ<17>")
	)
	(arc
		(start 78.608174 -235.890816)
		(mid 78.886606 -235.820718)
		(end 79.163418 -235.896912)
		(width 0.0889)
		(layer "In11.Cu")
		(net "M_F_CPU1_SA_DQ<17>")
	)
	(arc
		(start 79.537814 -235.896912)
		(mid 79.814881 -235.820641)
		(end 80.093566 -235.890816)
		(width 0.0889)
		(layer "In11.Cu")
		(net "M_F_CPU1_SA_DQ<17>")
	)
	(arc
		(start 82.357976 -235.896912)
		(mid 82.640932 -235.820735)
		(end 82.923888 -235.896912)
		(width 0.0889)
		(layer "In11.Cu")
		(net "M_F_CPU1_SA_DQ<17>")
	)
	(arc
		(start 81.052416 -235.901738)
		(mid 81.235924 -235.947232)
		(end 81.418176 -235.896912)
		(width 0.0889)
		(layer "In11.Cu")
		(net "M_F_CPU1_SA_DQ<17>")
	)
	(arc
		(start 83.29803 -235.896912)
		(mid 83.580986 -235.820735)
		(end 83.863942 -235.896912)
		(width 0.0889)
		(layer "In11.Cu")
		(net "M_F_CPU1_SA_DQ<17>")
	)
	(arc
		(start 85.178138 -235.896912)
		(mid 85.425851 -235.821692)
		(end 85.681058 -235.865162)
		(width 0.0889)
		(layer "In11.Cu")
		(net "M_F_CPU1_SA_DQ<17>")
	)
	(arc
		(start 79.163418 -235.896912)
		(mid 79.350616 -235.947294)
		(end 79.537814 -235.896912)
		(width 0.0889)
		(layer "In11.Cu")
		(net "M_F_CPU1_SA_DQ<17>")
	)
	(arc
		(start 81.984088 -235.896912)
		(mid 82.171032 -235.947167)
		(end 82.357976 -235.896912)
		(width 0.0889)
		(layer "In11.Cu")
		(net "M_F_CPU1_SA_DQ<17>")
	)
	(arc
		(start 83.863942 -235.896912)
		(mid 84.046193 -235.947262)
		(end 84.229702 -235.901738)
		(width 0.0889)
		(layer "In11.Cu")
		(net "M_F_CPU1_SA_DQ<17>")
	)
	(arc
		(start 80.10398 -235.896912)
		(mid 80.286231 -235.947262)
		(end 80.46974 -235.901738)
		(width 0.0889)
		(layer "In11.Cu")
		(net "M_F_CPU1_SA_DQ<17>")
	)
	(arc
		(start 81.418176 -235.896912)
		(mid 81.701132 -235.820735)
		(end 81.984088 -235.896912)
		(width 0.0889)
		(layer "In11.Cu")
		(net "M_F_CPU1_SA_DQ<17>")
	)
	(arc
		(start 84.812378 -235.901738)
		(mid 84.995886 -235.947232)
		(end 85.178138 -235.896912)
		(width 0.0889)
		(layer "In11.Cu")
		(net "M_F_CPU1_SA_DQ<17>")
	)
	(segment
		(start 84.987892 -235.030264)
		(end 84.52104 -234.764326)
		(width 0.10668)
		(layer "F.Cu")
		(net "M_F_CPU1_SA_DQ<16>")
	)
	(segment
		(start 26.147014 -216.846404)
		(end 26.310082 -216.683336)
		(width 0.14478)
		(layer "In11.Cu")
		(net "M_F_CPU1_SA_DQ<16>")
	)
	(segment
		(start 33.28289 -216.690956)
		(end 33.445958 -216.854024)
		(width 0.14478)
		(layer "In11.Cu")
		(net "M_F_CPU1_SA_DQ<16>")
	)
	(segment
		(start 55.35422 -216.460324)
		(end 56.954674 -216.460324)
		(width 0.14478)
		(layer "In11.Cu")
		(net "M_F_CPU1_SA_DQ<16>")
	)
	(segment
		(start 43.297094 -215.837516)
		(end 43.460162 -216.000584)
		(width 0.14478)
		(layer "In11.Cu")
		(net "M_F_CPU1_SA_DQ<16>")
	)
	(segment
		(start 56.954674 -216.460324)
		(end 57.804558 -215.61044)
		(width 0.14478)
		(layer "In11.Cu")
		(net "M_F_CPU1_SA_DQ<16>")
	)
	(segment
		(start 79.0575 -235.093764)
		(end 79.069184 -235.086906)
		(width 0.0889)
		(layer "In11.Cu")
		(net "M_F_CPU1_SA_DQ<16>")
	)
	(segment
		(start 43.853608 -215.773508)
		(end 44.016676 -215.61044)
		(width 0.14478)
		(layer "In11.Cu")
		(net "M_F_CPU1_SA_DQ<16>")
	)
	(segment
		(start 25.753568 -216.623392)
		(end 25.753568 -216.683336)
		(width 0.14478)
		(layer "In11.Cu")
		(net "M_F_CPU1_SA_DQ<16>")
	)
	(segment
		(start 43.69054 -216.000584)
		(end 43.853608 -215.837516)
		(width 0.14478)
		(layer "In11.Cu")
		(net "M_F_CPU1_SA_DQ<16>")
	)
	(segment
		(start 36.294314 -215.773508)
		(end 36.457382 -215.61044)
		(width 0.14478)
		(layer "In11.Cu")
		(net "M_F_CPU1_SA_DQ<16>")
	)
	(segment
		(start 74.619866 -232.802684)
		(end 75.628246 -232.802684)
		(width 0.14478)
		(layer "In11.Cu")
		(net "M_F_CPU1_SA_DQ<16>")
	)
	(segment
		(start 76.448666 -233.574844)
		(end 76.773786 -233.899964)
		(width 0.0889)
		(layer "In11.Cu")
		(net "M_F_CPU1_SA_DQ<16>")
	)
	(segment
		(start 65.531746 -223.714564)
		(end 74.619866 -232.802684)
		(width 0.14478)
		(layer "In11.Cu")
		(net "M_F_CPU1_SA_DQ<16>")
	)
	(segment
		(start 35.233102 -215.61044)
		(end 35.574732 -215.61044)
		(width 0.14478)
		(layer "In11.Cu")
		(net "M_F_CPU1_SA_DQ<16>")
	)
	(segment
		(start 41.010332 -216.623392)
		(end 41.010332 -216.685876)
		(width 0.14478)
		(layer "In11.Cu")
		(net "M_F_CPU1_SA_DQ<16>")
	)
	(segment
		(start 54.634638 -216.623392)
		(end 54.634638 -216.690956)
		(width 0.14478)
		(layer "In11.Cu")
		(net "M_F_CPU1_SA_DQ<16>")
	)
	(segment
		(start 76.448666 -233.270044)
		(end 76.448666 -233.574844)
		(width 0.0889)
		(layer "In11.Cu")
		(net "M_F_CPU1_SA_DQ<16>")
	)
	(segment
		(start 42.792904 -215.61044)
		(end 43.134026 -215.61044)
		(width 0.14478)
		(layer "In11.Cu")
		(net "M_F_CPU1_SA_DQ<16>")
	)
	(segment
		(start 27.664664 -215.61044)
		(end 28.04541 -215.61044)
		(width 0.14478)
		(layer "In11.Cu")
		(net "M_F_CPU1_SA_DQ<16>")
	)
	(segment
		(start 35.7378 -215.842596)
		(end 35.900868 -216.005664)
		(width 0.14478)
		(layer "In11.Cu")
		(net "M_F_CPU1_SA_DQ<16>")
	)
	(segment
		(start 51.32324 -215.837516)
		(end 51.32324 -215.773508)
		(width 0.14478)
		(layer "In11.Cu")
		(net "M_F_CPU1_SA_DQ<16>")
	)
	(segment
		(start 51.32324 -215.773508)
		(end 51.486308 -215.61044)
		(width 0.14478)
		(layer "In11.Cu")
		(net "M_F_CPU1_SA_DQ<16>")
	)
	(segment
		(start 37.95268 -215.61044)
		(end 38.802564 -216.460324)
		(width 0.14478)
		(layer "In11.Cu")
		(net "M_F_CPU1_SA_DQ<16>")
	)
	(segment
		(start 41.403778 -216.848944)
		(end 41.566846 -216.685876)
		(width 0.14478)
		(layer "In11.Cu")
		(net "M_F_CPU1_SA_DQ<16>")
	)
	(segment
		(start 28.92806 -215.61044)
		(end 30.470856 -215.61044)
		(width 0.14478)
		(layer "In11.Cu")
		(net "M_F_CPU1_SA_DQ<16>")
	)
	(segment
		(start 33.676336 -216.854024)
		(end 33.839404 -216.690956)
		(width 0.14478)
		(layer "In11.Cu")
		(net "M_F_CPU1_SA_DQ<16>")
	)
	(segment
		(start 46.417738 -216.460324)
		(end 48.26889 -216.460324)
		(width 0.14478)
		(layer "In11.Cu")
		(net "M_F_CPU1_SA_DQ<16>")
	)
	(segment
		(start 41.1734 -216.848944)
		(end 41.403778 -216.848944)
		(width 0.14478)
		(layer "In11.Cu")
		(net "M_F_CPU1_SA_DQ<16>")
	)
	(segment
		(start 83.394042 -235.086906)
		(end 83.402424 -235.091732)
		(width 0.0889)
		(layer "In11.Cu")
		(net "M_F_CPU1_SA_DQ<16>")
	)
	(segment
		(start 45.567854 -215.61044)
		(end 46.417738 -216.460324)
		(width 0.14478)
		(layer "In11.Cu")
		(net "M_F_CPU1_SA_DQ<16>")
	)
	(segment
		(start 84.367116 -235.029756)
		(end 84.52104 -234.764326)
		(width 0.0889)
		(layer "In11.Cu")
		(net "M_F_CPU1_SA_DQ<16>")
	)
	(segment
		(start 53.961792 -216.460324)
		(end 54.47157 -216.460324)
		(width 0.14478)
		(layer "In11.Cu")
		(net "M_F_CPU1_SA_DQ<16>")
	)
	(segment
		(start 50.929794 -216.000584)
		(end 51.160172 -216.000584)
		(width 0.14478)
		(layer "In11.Cu")
		(net "M_F_CPU1_SA_DQ<16>")
	)
	(segment
		(start 23.69693 -216.618566)
		(end 24.090122 -216.618566)
		(width 0.14478)
		(layer "In11.Cu")
		(net "M_F_CPU1_SA_DQ<16>")
	)
	(segment
		(start 33.445958 -216.854024)
		(end 33.676336 -216.854024)
		(width 0.14478)
		(layer "In11.Cu")
		(net "M_F_CPU1_SA_DQ<16>")
	)
	(segment
		(start 49.448974 -216.460324)
		(end 50.298858 -215.61044)
		(width 0.14478)
		(layer "In11.Cu")
		(net "M_F_CPU1_SA_DQ<16>")
	)
	(segment
		(start 40.847264 -216.460324)
		(end 41.010332 -216.623392)
		(width 0.14478)
		(layer "In11.Cu")
		(net "M_F_CPU1_SA_DQ<16>")
	)
	(segment
		(start 41.566846 -216.623392)
		(end 41.729914 -216.460324)
		(width 0.14478)
		(layer "In11.Cu")
		(net "M_F_CPU1_SA_DQ<16>")
	)
	(segment
		(start 79.622396 -235.079794)
		(end 79.634334 -235.086652)
		(width 0.0889)
		(layer "In11.Cu")
		(net "M_F_CPU1_SA_DQ<16>")
	)
	(segment
		(start 76.773786 -233.899964)
		(end 77.123544 -233.899964)
		(width 0.0889)
		(layer "In11.Cu")
		(net "M_F_CPU1_SA_DQ<16>")
	)
	(segment
		(start 24.090122 -216.618566)
		(end 24.248364 -216.460324)
		(width 0.14478)
		(layer "In11.Cu")
		(net "M_F_CPU1_SA_DQ<16>")
	)
	(segment
		(start 35.7378 -215.773508)
		(end 35.7378 -215.842596)
		(width 0.14478)
		(layer "In11.Cu")
		(net "M_F_CPU1_SA_DQ<16>")
	)
	(segment
		(start 48.431958 -216.690956)
		(end 48.595026 -216.854024)
		(width 0.14478)
		(layer "In11.Cu")
		(net "M_F_CPU1_SA_DQ<16>")
	)
	(segment
		(start 57.804558 -215.61044)
		(end 59.74715 -215.61044)
		(width 0.14478)
		(layer "In11.Cu")
		(net "M_F_CPU1_SA_DQ<16>")
	)
	(segment
		(start 28.764992 -215.832436)
		(end 28.764992 -215.773508)
		(width 0.14478)
		(layer "In11.Cu")
		(net "M_F_CPU1_SA_DQ<16>")
	)
	(segment
		(start 24.248364 -216.460324)
		(end 25.5905 -216.460324)
		(width 0.14478)
		(layer "In11.Cu")
		(net "M_F_CPU1_SA_DQ<16>")
	)
	(segment
		(start 33.839404 -216.623392)
		(end 34.002472 -216.460324)
		(width 0.14478)
		(layer "In11.Cu")
		(net "M_F_CPU1_SA_DQ<16>")
	)
	(segment
		(start 22.133052 -216.460324)
		(end 23.538688 -216.460324)
		(width 0.14478)
		(layer "In11.Cu")
		(net "M_F_CPU1_SA_DQ<16>")
	)
	(segment
		(start 75.628246 -232.802684)
		(end 75.981306 -232.802684)
		(width 0.0889)
		(layer "In11.Cu")
		(net "M_F_CPU1_SA_DQ<16>")
	)
	(segment
		(start 77.123544 -233.899964)
		(end 78.234032 -235.010452)
		(width 0.0889)
		(layer "In11.Cu")
		(net "M_F_CPU1_SA_DQ<16>")
	)
	(segment
		(start 33.28289 -216.623392)
		(end 33.28289 -216.690956)
		(width 0.14478)
		(layer "In11.Cu")
		(net "M_F_CPU1_SA_DQ<16>")
	)
	(segment
		(start 28.764992 -215.773508)
		(end 28.92806 -215.61044)
		(width 0.14478)
		(layer "In11.Cu")
		(net "M_F_CPU1_SA_DQ<16>")
	)
	(segment
		(start 54.634638 -216.690956)
		(end 54.797706 -216.854024)
		(width 0.14478)
		(layer "In11.Cu")
		(net "M_F_CPU1_SA_DQ<16>")
	)
	(segment
		(start 35.574732 -215.61044)
		(end 35.7378 -215.773508)
		(width 0.14478)
		(layer "In11.Cu")
		(net "M_F_CPU1_SA_DQ<16>")
	)
	(segment
		(start 36.294314 -215.842596)
		(end 36.294314 -215.773508)
		(width 0.14478)
		(layer "In11.Cu")
		(net "M_F_CPU1_SA_DQ<16>")
	)
	(segment
		(start 79.634334 -235.086652)
		(end 79.65059 -235.09605)
		(width 0.0889)
		(layer "In11.Cu")
		(net "M_F_CPU1_SA_DQ<16>")
	)
	(segment
		(start 26.81478 -216.460324)
		(end 27.664664 -215.61044)
		(width 0.14478)
		(layer "In11.Cu")
		(net "M_F_CPU1_SA_DQ<16>")
	)
	(segment
		(start 21.70811 -216.035382)
		(end 22.133052 -216.460324)
		(width 0.14478)
		(layer "In11.Cu")
		(net "M_F_CPU1_SA_DQ<16>")
	)
	(segment
		(start 26.47315 -216.460324)
		(end 26.81478 -216.460324)
		(width 0.14478)
		(layer "In11.Cu")
		(net "M_F_CPU1_SA_DQ<16>")
	)
	(segment
		(start 30.470856 -215.61044)
		(end 31.32074 -216.460324)
		(width 0.14478)
		(layer "In11.Cu")
		(net "M_F_CPU1_SA_DQ<16>")
	)
	(segment
		(start 28.04541 -215.61044)
		(end 28.208478 -215.773508)
		(width 0.14478)
		(layer "In11.Cu")
		(net "M_F_CPU1_SA_DQ<16>")
	)
	(segment
		(start 31.32074 -216.460324)
		(end 33.119822 -216.460324)
		(width 0.14478)
		(layer "In11.Cu")
		(net "M_F_CPU1_SA_DQ<16>")
	)
	(segment
		(start 48.26889 -216.460324)
		(end 48.431958 -216.623392)
		(width 0.14478)
		(layer "In11.Cu")
		(net "M_F_CPU1_SA_DQ<16>")
	)
	(segment
		(start 50.298858 -215.61044)
		(end 50.603658 -215.61044)
		(width 0.14478)
		(layer "In11.Cu")
		(net "M_F_CPU1_SA_DQ<16>")
	)
	(segment
		(start 28.601924 -215.995504)
		(end 28.764992 -215.832436)
		(width 0.14478)
		(layer "In11.Cu")
		(net "M_F_CPU1_SA_DQ<16>")
	)
	(segment
		(start 59.74715 -215.61044)
		(end 60.35675 -216.22004)
		(width 0.14478)
		(layer "In11.Cu")
		(net "M_F_CPU1_SA_DQ<16>")
	)
	(segment
		(start 65.531746 -222.430848)
		(end 65.531746 -223.714564)
		(width 0.14478)
		(layer "In11.Cu")
		(net "M_F_CPU1_SA_DQ<16>")
	)
	(segment
		(start 25.916636 -216.846404)
		(end 26.147014 -216.846404)
		(width 0.14478)
		(layer "In11.Cu")
		(net "M_F_CPU1_SA_DQ<16>")
	)
	(segment
		(start 41.010332 -216.685876)
		(end 41.1734 -216.848944)
		(width 0.14478)
		(layer "In11.Cu")
		(net "M_F_CPU1_SA_DQ<16>")
	)
	(segment
		(start 50.603658 -215.61044)
		(end 50.766726 -215.773508)
		(width 0.14478)
		(layer "In11.Cu")
		(net "M_F_CPU1_SA_DQ<16>")
	)
	(segment
		(start 28.371546 -215.995504)
		(end 28.601924 -215.995504)
		(width 0.14478)
		(layer "In11.Cu")
		(net "M_F_CPU1_SA_DQ<16>")
	)
	(segment
		(start 33.839404 -216.690956)
		(end 33.839404 -216.623392)
		(width 0.14478)
		(layer "In11.Cu")
		(net "M_F_CPU1_SA_DQ<16>")
	)
	(segment
		(start 36.131246 -216.005664)
		(end 36.294314 -215.842596)
		(width 0.14478)
		(layer "In11.Cu")
		(net "M_F_CPU1_SA_DQ<16>")
	)
	(segment
		(start 48.595026 -216.854024)
		(end 48.825404 -216.854024)
		(width 0.14478)
		(layer "In11.Cu")
		(net "M_F_CPU1_SA_DQ<16>")
	)
	(segment
		(start 54.797706 -216.854024)
		(end 55.028084 -216.854024)
		(width 0.14478)
		(layer "In11.Cu")
		(net "M_F_CPU1_SA_DQ<16>")
	)
	(segment
		(start 55.191152 -216.623392)
		(end 55.35422 -216.460324)
		(width 0.14478)
		(layer "In11.Cu")
		(net "M_F_CPU1_SA_DQ<16>")
	)
	(segment
		(start 33.119822 -216.460324)
		(end 33.28289 -216.623392)
		(width 0.14478)
		(layer "In11.Cu")
		(net "M_F_CPU1_SA_DQ<16>")
	)
	(segment
		(start 48.988472 -216.623392)
		(end 49.15154 -216.460324)
		(width 0.14478)
		(layer "In11.Cu")
		(net "M_F_CPU1_SA_DQ<16>")
	)
	(segment
		(start 81.879694 -235.091732)
		(end 81.888076 -235.086906)
		(width 0.0889)
		(layer "In11.Cu")
		(net "M_F_CPU1_SA_DQ<16>")
	)
	(segment
		(start 51.160172 -216.000584)
		(end 51.32324 -215.837516)
		(width 0.14478)
		(layer "In11.Cu")
		(net "M_F_CPU1_SA_DQ<16>")
	)
	(segment
		(start 43.853608 -215.837516)
		(end 43.853608 -215.773508)
		(width 0.14478)
		(layer "In11.Cu")
		(net "M_F_CPU1_SA_DQ<16>")
	)
	(segment
		(start 84.271104 -235.055156)
		(end 84.367116 -235.029756)
		(width 0.0889)
		(layer "In11.Cu")
		(net "M_F_CPU1_SA_DQ<16>")
	)
	(segment
		(start 48.825404 -216.854024)
		(end 48.988472 -216.690956)
		(width 0.14478)
		(layer "In11.Cu")
		(net "M_F_CPU1_SA_DQ<16>")
	)
	(segment
		(start 36.457382 -215.61044)
		(end 37.95268 -215.61044)
		(width 0.14478)
		(layer "In11.Cu")
		(net "M_F_CPU1_SA_DQ<16>")
	)
	(segment
		(start 41.94302 -216.460324)
		(end 42.792904 -215.61044)
		(width 0.14478)
		(layer "In11.Cu")
		(net "M_F_CPU1_SA_DQ<16>")
	)
	(segment
		(start 23.538688 -216.460324)
		(end 23.69693 -216.618566)
		(width 0.14478)
		(layer "In11.Cu")
		(net "M_F_CPU1_SA_DQ<16>")
	)
	(segment
		(start 34.002472 -216.460324)
		(end 34.383218 -216.460324)
		(width 0.14478)
		(layer "In11.Cu")
		(net "M_F_CPU1_SA_DQ<16>")
	)
	(segment
		(start 28.208478 -215.773508)
		(end 28.208478 -215.832436)
		(width 0.14478)
		(layer "In11.Cu")
		(net "M_F_CPU1_SA_DQ<16>")
	)
	(segment
		(start 55.028084 -216.854024)
		(end 55.191152 -216.690956)
		(width 0.14478)
		(layer "In11.Cu")
		(net "M_F_CPU1_SA_DQ<16>")
	)
	(segment
		(start 25.5905 -216.460324)
		(end 25.753568 -216.623392)
		(width 0.14478)
		(layer "In11.Cu")
		(net "M_F_CPU1_SA_DQ<16>")
	)
	(segment
		(start 50.766726 -215.837516)
		(end 50.929794 -216.000584)
		(width 0.14478)
		(layer "In11.Cu")
		(net "M_F_CPU1_SA_DQ<16>")
	)
	(segment
		(start 60.35675 -216.22004)
		(end 60.35675 -217.255852)
		(width 0.14478)
		(layer "In11.Cu")
		(net "M_F_CPU1_SA_DQ<16>")
	)
	(segment
		(start 51.486308 -215.61044)
		(end 53.111908 -215.61044)
		(width 0.14478)
		(layer "In11.Cu")
		(net "M_F_CPU1_SA_DQ<16>")
	)
	(segment
		(start 48.988472 -216.690956)
		(end 48.988472 -216.623392)
		(width 0.14478)
		(layer "In11.Cu")
		(net "M_F_CPU1_SA_DQ<16>")
	)
	(segment
		(start 75.981306 -232.802684)
		(end 76.448666 -233.270044)
		(width 0.0889)
		(layer "In11.Cu")
		(net "M_F_CPU1_SA_DQ<16>")
	)
	(segment
		(start 25.753568 -216.683336)
		(end 25.916636 -216.846404)
		(width 0.14478)
		(layer "In11.Cu")
		(net "M_F_CPU1_SA_DQ<16>")
	)
	(segment
		(start 43.460162 -216.000584)
		(end 43.69054 -216.000584)
		(width 0.14478)
		(layer "In11.Cu")
		(net "M_F_CPU1_SA_DQ<16>")
	)
	(segment
		(start 26.310082 -216.623392)
		(end 26.47315 -216.460324)
		(width 0.14478)
		(layer "In11.Cu")
		(net "M_F_CPU1_SA_DQ<16>")
	)
	(segment
		(start 26.310082 -216.683336)
		(end 26.310082 -216.623392)
		(width 0.14478)
		(layer "In11.Cu")
		(net "M_F_CPU1_SA_DQ<16>")
	)
	(segment
		(start 35.900868 -216.005664)
		(end 36.131246 -216.005664)
		(width 0.14478)
		(layer "In11.Cu")
		(net "M_F_CPU1_SA_DQ<16>")
	)
	(segment
		(start 54.47157 -216.460324)
		(end 54.634638 -216.623392)
		(width 0.14478)
		(layer "In11.Cu")
		(net "M_F_CPU1_SA_DQ<16>")
	)
	(segment
		(start 82.453988 -235.086906)
		(end 82.46237 -235.091732)
		(width 0.0889)
		(layer "In11.Cu")
		(net "M_F_CPU1_SA_DQ<16>")
	)
	(segment
		(start 34.383218 -216.460324)
		(end 35.233102 -215.61044)
		(width 0.14478)
		(layer "In11.Cu")
		(net "M_F_CPU1_SA_DQ<16>")
	)
	(segment
		(start 28.208478 -215.832436)
		(end 28.371546 -215.995504)
		(width 0.14478)
		(layer "In11.Cu")
		(net "M_F_CPU1_SA_DQ<16>")
	)
	(segment
		(start 43.297094 -215.773508)
		(end 43.297094 -215.837516)
		(width 0.14478)
		(layer "In11.Cu")
		(net "M_F_CPU1_SA_DQ<16>")
	)
	(segment
		(start 60.35675 -217.255852)
		(end 65.531746 -222.430848)
		(width 0.14478)
		(layer "In11.Cu")
		(net "M_F_CPU1_SA_DQ<16>")
	)
	(segment
		(start 53.111908 -215.61044)
		(end 53.961792 -216.460324)
		(width 0.14478)
		(layer "In11.Cu")
		(net "M_F_CPU1_SA_DQ<16>")
	)
	(segment
		(start 49.15154 -216.460324)
		(end 49.448974 -216.460324)
		(width 0.14478)
		(layer "In11.Cu")
		(net "M_F_CPU1_SA_DQ<16>")
	)
	(segment
		(start 55.191152 -216.690956)
		(end 55.191152 -216.623392)
		(width 0.14478)
		(layer "In11.Cu")
		(net "M_F_CPU1_SA_DQ<16>")
	)
	(segment
		(start 38.802564 -216.460324)
		(end 40.847264 -216.460324)
		(width 0.14478)
		(layer "In11.Cu")
		(net "M_F_CPU1_SA_DQ<16>")
	)
	(segment
		(start 43.134026 -215.61044)
		(end 43.297094 -215.773508)
		(width 0.14478)
		(layer "In11.Cu")
		(net "M_F_CPU1_SA_DQ<16>")
	)
	(segment
		(start 41.729914 -216.460324)
		(end 41.94302 -216.460324)
		(width 0.14478)
		(layer "In11.Cu")
		(net "M_F_CPU1_SA_DQ<16>")
	)
	(segment
		(start 41.566846 -216.685876)
		(end 41.566846 -216.623392)
		(width 0.14478)
		(layer "In11.Cu")
		(net "M_F_CPU1_SA_DQ<16>")
	)
	(segment
		(start 78.234032 -235.010452)
		(end 78.41107 -235.010452)
		(width 0.0889)
		(layer "In11.Cu")
		(net "M_F_CPU1_SA_DQ<16>")
	)
	(segment
		(start 50.766726 -215.773508)
		(end 50.766726 -215.837516)
		(width 0.14478)
		(layer "In11.Cu")
		(net "M_F_CPU1_SA_DQ<16>")
	)
	(segment
		(start 48.431958 -216.623392)
		(end 48.431958 -216.690956)
		(width 0.14478)
		(layer "In11.Cu")
		(net "M_F_CPU1_SA_DQ<16>")
	)
	(segment
		(start 44.016676 -215.61044)
		(end 45.567854 -215.61044)
		(width 0.14478)
		(layer "In11.Cu")
		(net "M_F_CPU1_SA_DQ<16>")
	)
	(arc
		(start 78.41107 -235.010452)
		(mid 78.558001 -235.029863)
		(end 78.694788 -235.086906)
		(width 0.0889)
		(layer "In11.Cu")
		(net "M_F_CPU1_SA_DQ<16>")
	)
	(arc
		(start 78.694788 -235.086906)
		(mid 78.875246 -235.13735)
		(end 79.0575 -235.093764)
		(width 0.0889)
		(layer "In11.Cu")
		(net "M_F_CPU1_SA_DQ<16>")
	)
	(arc
		(start 80.008222 -235.086906)
		(mid 80.291178 -235.010729)
		(end 80.574134 -235.086906)
		(width 0.0889)
		(layer "In11.Cu")
		(net "M_F_CPU1_SA_DQ<16>")
	)
	(arc
		(start 82.82813 -235.086906)
		(mid 83.111086 -235.010729)
		(end 83.394042 -235.086906)
		(width 0.0889)
		(layer "In11.Cu")
		(net "M_F_CPU1_SA_DQ<16>")
	)
	(arc
		(start 81.513934 -235.086906)
		(mid 81.696185 -235.137256)
		(end 81.879694 -235.091732)
		(width 0.0889)
		(layer "In11.Cu")
		(net "M_F_CPU1_SA_DQ<16>")
	)
	(arc
		(start 83.768184 -235.086906)
		(mid 84.015897 -235.011686)
		(end 84.271104 -235.055156)
		(width 0.0889)
		(layer "In11.Cu")
		(net "M_F_CPU1_SA_DQ<16>")
	)
	(arc
		(start 83.402424 -235.091732)
		(mid 83.585932 -235.137226)
		(end 83.768184 -235.086906)
		(width 0.0889)
		(layer "In11.Cu")
		(net "M_F_CPU1_SA_DQ<16>")
	)
	(arc
		(start 80.948022 -235.086906)
		(mid 81.230978 -235.010729)
		(end 81.513934 -235.086906)
		(width 0.0889)
		(layer "In11.Cu")
		(net "M_F_CPU1_SA_DQ<16>")
	)
	(arc
		(start 82.46237 -235.091732)
		(mid 82.645878 -235.137226)
		(end 82.82813 -235.086906)
		(width 0.0889)
		(layer "In11.Cu")
		(net "M_F_CPU1_SA_DQ<16>")
	)
	(arc
		(start 81.888076 -235.086906)
		(mid 82.171032 -235.010729)
		(end 82.453988 -235.086906)
		(width 0.0889)
		(layer "In11.Cu")
		(net "M_F_CPU1_SA_DQ<16>")
	)
	(arc
		(start 79.65059 -235.09605)
		(mid 79.830572 -235.13715)
		(end 80.008222 -235.086906)
		(width 0.0889)
		(layer "In11.Cu")
		(net "M_F_CPU1_SA_DQ<16>")
	)
	(arc
		(start 80.574134 -235.086906)
		(mid 80.761078 -235.137161)
		(end 80.948022 -235.086906)
		(width 0.0889)
		(layer "In11.Cu")
		(net "M_F_CPU1_SA_DQ<16>")
	)
	(arc
		(start 79.069184 -235.086906)
		(mid 79.344862 -235.010776)
		(end 79.622396 -235.079794)
		(width 0.0889)
		(layer "In11.Cu")
		(net "M_F_CPU1_SA_DQ<16>")
	)
	(segment
		(start 85.927946 -235.030264)
		(end 85.461094 -234.764326)
		(width 0.10668)
		(layer "F.Cu")
		(net "M_F_CPU1_SA_DQ<15>")
	)
	(segment
		(start 66.090546 -223.479868)
		(end 74.857102 -232.246424)
		(width 0.14478)
		(layer "In11.Cu")
		(net "M_F_CPU1_SA_DQ<15>")
	)
	(segment
		(start 19.044158 -214.679784)
		(end 19.207226 -214.842852)
		(width 0.14478)
		(layer "In11.Cu")
		(net "M_F_CPU1_SA_DQ<15>")
	)
	(segment
		(start 19.207226 -215.447372)
		(end 19.370294 -215.61044)
		(width 0.14478)
		(layer "In11.Cu")
		(net "M_F_CPU1_SA_DQ<15>")
	)
	(segment
		(start 42.742104 -214.760302)
		(end 45.618654 -214.760302)
		(width 0.14478)
		(layer "In11.Cu")
		(net "M_F_CPU1_SA_DQ<15>")
	)
	(segment
		(start 76.728574 -233.03992)
		(end 76.992734 -233.03992)
		(width 0.0889)
		(layer "In11.Cu")
		(net "M_F_CPU1_SA_DQ<15>")
	)
	(segment
		(start 85.615018 -234.498896)
		(end 85.461094 -234.764326)
		(width 0.0889)
		(layer "In11.Cu")
		(net "M_F_CPU1_SA_DQ<15>")
	)
	(segment
		(start 74.857102 -232.246424)
		(end 75.628246 -232.246424)
		(width 0.14478)
		(layer "In11.Cu")
		(net "M_F_CPU1_SA_DQ<15>")
	)
	(segment
		(start 18.033238 -215.61044)
		(end 18.487644 -215.61044)
		(width 0.14478)
		(layer "In11.Cu")
		(net "M_F_CPU1_SA_DQ<15>")
	)
	(segment
		(start 78.67904 -234.450382)
		(end 78.693772 -234.441746)
		(width 0.0889)
		(layer "In11.Cu")
		(net "M_F_CPU1_SA_DQ<15>")
	)
	(segment
		(start 41.891966 -215.61044)
		(end 42.742104 -214.760302)
		(width 0.14478)
		(layer "In11.Cu")
		(net "M_F_CPU1_SA_DQ<15>")
	)
	(segment
		(start 75.935078 -232.246424)
		(end 76.728574 -233.03992)
		(width 0.0889)
		(layer "In11.Cu")
		(net "M_F_CPU1_SA_DQ<15>")
	)
	(segment
		(start 31.393892 -215.61044)
		(end 34.35858 -215.61044)
		(width 0.14478)
		(layer "In11.Cu")
		(net "M_F_CPU1_SA_DQ<15>")
	)
	(segment
		(start 60.91301 -216.963752)
		(end 66.090546 -222.141288)
		(width 0.14478)
		(layer "In11.Cu")
		(net "M_F_CPU1_SA_DQ<15>")
	)
	(segment
		(start 83.394042 -234.441746)
		(end 83.402424 -234.43692)
		(width 0.0889)
		(layer "In11.Cu")
		(net "M_F_CPU1_SA_DQ<15>")
	)
	(segment
		(start 19.76374 -215.447372)
		(end 19.76374 -214.842852)
		(width 0.14478)
		(layer "In11.Cu")
		(net "M_F_CPU1_SA_DQ<15>")
	)
	(segment
		(start 56.936132 -215.61044)
		(end 57.78627 -214.760302)
		(width 0.14478)
		(layer "In11.Cu")
		(net "M_F_CPU1_SA_DQ<15>")
	)
	(segment
		(start 38.113208 -214.760302)
		(end 38.963346 -215.61044)
		(width 0.14478)
		(layer "In11.Cu")
		(net "M_F_CPU1_SA_DQ<15>")
	)
	(segment
		(start 34.35858 -215.61044)
		(end 35.208718 -214.760302)
		(width 0.14478)
		(layer "In11.Cu")
		(net "M_F_CPU1_SA_DQ<15>")
	)
	(segment
		(start 76.992734 -233.03992)
		(end 77.17663 -233.223816)
		(width 0.0889)
		(layer "In11.Cu")
		(net "M_F_CPU1_SA_DQ<15>")
	)
	(segment
		(start 20.320254 -215.447372)
		(end 20.483322 -215.61044)
		(width 0.14478)
		(layer "In11.Cu")
		(net "M_F_CPU1_SA_DQ<15>")
	)
	(segment
		(start 26.727658 -215.61044)
		(end 27.577796 -214.760302)
		(width 0.14478)
		(layer "In11.Cu")
		(net "M_F_CPU1_SA_DQ<15>")
	)
	(segment
		(start 19.926808 -214.679784)
		(end 20.157186 -214.679784)
		(width 0.14478)
		(layer "In11.Cu")
		(net "M_F_CPU1_SA_DQ<15>")
	)
	(segment
		(start 19.370294 -215.61044)
		(end 19.600672 -215.61044)
		(width 0.14478)
		(layer "In11.Cu")
		(net "M_F_CPU1_SA_DQ<15>")
	)
	(segment
		(start 60.91301 -215.959182)
		(end 60.91301 -216.963752)
		(width 0.14478)
		(layer "In11.Cu")
		(net "M_F_CPU1_SA_DQ<15>")
	)
	(segment
		(start 20.483322 -215.61044)
		(end 26.727658 -215.61044)
		(width 0.14478)
		(layer "In11.Cu")
		(net "M_F_CPU1_SA_DQ<15>")
	)
	(segment
		(start 18.650712 -215.447372)
		(end 18.650712 -214.842852)
		(width 0.14478)
		(layer "In11.Cu")
		(net "M_F_CPU1_SA_DQ<15>")
	)
	(segment
		(start 54.005226 -215.61044)
		(end 56.936132 -215.61044)
		(width 0.14478)
		(layer "In11.Cu")
		(net "M_F_CPU1_SA_DQ<15>")
	)
	(segment
		(start 57.78627 -214.760302)
		(end 59.71413 -214.760302)
		(width 0.14478)
		(layer "In11.Cu")
		(net "M_F_CPU1_SA_DQ<15>")
	)
	(segment
		(start 50.23993 -214.760302)
		(end 53.155088 -214.760302)
		(width 0.14478)
		(layer "In11.Cu")
		(net "M_F_CPU1_SA_DQ<15>")
	)
	(segment
		(start 75.628246 -232.246424)
		(end 75.935078 -232.246424)
		(width 0.0889)
		(layer "In11.Cu")
		(net "M_F_CPU1_SA_DQ<15>")
	)
	(segment
		(start 59.71413 -214.760302)
		(end 60.91301 -215.959182)
		(width 0.14478)
		(layer "In11.Cu")
		(net "M_F_CPU1_SA_DQ<15>")
	)
	(segment
		(start 79.06766 -234.441746)
		(end 79.078074 -234.447842)
		(width 0.0889)
		(layer "In11.Cu")
		(net "M_F_CPU1_SA_DQ<15>")
	)
	(segment
		(start 77.17663 -233.516932)
		(end 78.012544 -234.352846)
		(width 0.0889)
		(layer "In11.Cu")
		(net "M_F_CPU1_SA_DQ<15>")
	)
	(segment
		(start 18.650712 -214.842852)
		(end 18.81378 -214.679784)
		(width 0.14478)
		(layer "In11.Cu")
		(net "M_F_CPU1_SA_DQ<15>")
	)
	(segment
		(start 81.879694 -234.43692)
		(end 81.888076 -234.441746)
		(width 0.0889)
		(layer "In11.Cu")
		(net "M_F_CPU1_SA_DQ<15>")
	)
	(segment
		(start 27.577796 -214.760302)
		(end 30.543754 -214.760302)
		(width 0.14478)
		(layer "In11.Cu")
		(net "M_F_CPU1_SA_DQ<15>")
	)
	(segment
		(start 45.618654 -214.760302)
		(end 46.468792 -215.61044)
		(width 0.14478)
		(layer "In11.Cu")
		(net "M_F_CPU1_SA_DQ<15>")
	)
	(segment
		(start 19.207226 -214.842852)
		(end 19.207226 -215.447372)
		(width 0.14478)
		(layer "In11.Cu")
		(net "M_F_CPU1_SA_DQ<15>")
	)
	(segment
		(start 30.543754 -214.760302)
		(end 31.393892 -215.61044)
		(width 0.14478)
		(layer "In11.Cu")
		(net "M_F_CPU1_SA_DQ<15>")
	)
	(segment
		(start 53.155088 -214.760302)
		(end 54.005226 -215.61044)
		(width 0.14478)
		(layer "In11.Cu")
		(net "M_F_CPU1_SA_DQ<15>")
	)
	(segment
		(start 46.468792 -215.61044)
		(end 49.389792 -215.61044)
		(width 0.14478)
		(layer "In11.Cu")
		(net "M_F_CPU1_SA_DQ<15>")
	)
	(segment
		(start 17.608042 -215.185244)
		(end 18.033238 -215.61044)
		(width 0.14478)
		(layer "In11.Cu")
		(net "M_F_CPU1_SA_DQ<15>")
	)
	(segment
		(start 66.090546 -222.141288)
		(end 66.090546 -223.479868)
		(width 0.14478)
		(layer "In11.Cu")
		(net "M_F_CPU1_SA_DQ<15>")
	)
	(segment
		(start 85.592666 -234.415584)
		(end 85.615018 -234.498896)
		(width 0.0889)
		(layer "In11.Cu")
		(net "M_F_CPU1_SA_DQ<15>")
	)
	(segment
		(start 18.487644 -215.61044)
		(end 18.650712 -215.447372)
		(width 0.14478)
		(layer "In11.Cu")
		(net "M_F_CPU1_SA_DQ<15>")
	)
	(segment
		(start 82.453988 -234.441746)
		(end 82.46237 -234.43692)
		(width 0.0889)
		(layer "In11.Cu")
		(net "M_F_CPU1_SA_DQ<15>")
	)
	(segment
		(start 19.600672 -215.61044)
		(end 19.76374 -215.447372)
		(width 0.14478)
		(layer "In11.Cu")
		(net "M_F_CPU1_SA_DQ<15>")
	)
	(segment
		(start 35.208718 -214.760302)
		(end 38.113208 -214.760302)
		(width 0.14478)
		(layer "In11.Cu")
		(net "M_F_CPU1_SA_DQ<15>")
	)
	(segment
		(start 49.389792 -215.61044)
		(end 50.23993 -214.760302)
		(width 0.14478)
		(layer "In11.Cu")
		(net "M_F_CPU1_SA_DQ<15>")
	)
	(segment
		(start 77.17663 -233.223816)
		(end 77.17663 -233.516932)
		(width 0.0889)
		(layer "In11.Cu")
		(net "M_F_CPU1_SA_DQ<15>")
	)
	(segment
		(start 38.963346 -215.61044)
		(end 41.891966 -215.61044)
		(width 0.14478)
		(layer "In11.Cu")
		(net "M_F_CPU1_SA_DQ<15>")
	)
	(segment
		(start 18.81378 -214.679784)
		(end 19.044158 -214.679784)
		(width 0.14478)
		(layer "In11.Cu")
		(net "M_F_CPU1_SA_DQ<15>")
	)
	(segment
		(start 20.320254 -214.842852)
		(end 20.320254 -215.447372)
		(width 0.14478)
		(layer "In11.Cu")
		(net "M_F_CPU1_SA_DQ<15>")
	)
	(segment
		(start 19.76374 -214.842852)
		(end 19.926808 -214.679784)
		(width 0.14478)
		(layer "In11.Cu")
		(net "M_F_CPU1_SA_DQ<15>")
	)
	(segment
		(start 20.157186 -214.679784)
		(end 20.320254 -214.842852)
		(width 0.14478)
		(layer "In11.Cu")
		(net "M_F_CPU1_SA_DQ<15>")
	)
	(segment
		(start 78.693772 -234.441746)
		(end 78.705456 -234.434888)
		(width 0.0889)
		(layer "In11.Cu")
		(net "M_F_CPU1_SA_DQ<15>")
	)
	(arc
		(start 82.82813 -234.441746)
		(mid 83.111086 -234.517923)
		(end 83.394042 -234.441746)
		(width 0.0889)
		(layer "In11.Cu")
		(net "M_F_CPU1_SA_DQ<15>")
	)
	(arc
		(start 79.633826 -234.441746)
		(mid 79.821024 -234.391364)
		(end 80.008222 -234.441746)
		(width 0.0889)
		(layer "In11.Cu")
		(net "M_F_CPU1_SA_DQ<15>")
	)
	(arc
		(start 81.513934 -234.441746)
		(mid 81.696185 -234.391396)
		(end 81.879694 -234.43692)
		(width 0.0889)
		(layer "In11.Cu")
		(net "M_F_CPU1_SA_DQ<15>")
	)
	(arc
		(start 85.273896 -234.441746)
		(mid 85.430334 -234.392775)
		(end 85.592666 -234.415584)
		(width 0.0889)
		(layer "In11.Cu")
		(net "M_F_CPU1_SA_DQ<15>")
	)
	(arc
		(start 80.948022 -234.441746)
		(mid 81.230978 -234.517923)
		(end 81.513934 -234.441746)
		(width 0.0889)
		(layer "In11.Cu")
		(net "M_F_CPU1_SA_DQ<15>")
	)
	(arc
		(start 83.768184 -234.441746)
		(mid 84.05114 -234.517923)
		(end 84.334096 -234.441746)
		(width 0.0889)
		(layer "In11.Cu")
		(net "M_F_CPU1_SA_DQ<15>")
	)
	(arc
		(start 78.705456 -234.434888)
		(mid 78.887457 -234.391355)
		(end 79.06766 -234.441746)
		(width 0.0889)
		(layer "In11.Cu")
		(net "M_F_CPU1_SA_DQ<15>")
	)
	(arc
		(start 79.078074 -234.447842)
		(mid 79.35676 -234.518062)
		(end 79.633826 -234.441746)
		(width 0.0889)
		(layer "In11.Cu")
		(net "M_F_CPU1_SA_DQ<15>")
	)
	(arc
		(start 84.707984 -234.441746)
		(mid 84.99094 -234.517923)
		(end 85.273896 -234.441746)
		(width 0.0889)
		(layer "In11.Cu")
		(net "M_F_CPU1_SA_DQ<15>")
	)
	(arc
		(start 78.012544 -234.352846)
		(mid 78.067316 -234.40104)
		(end 78.12786 -234.441746)
		(width 0.0889)
		(layer "In11.Cu")
		(net "M_F_CPU1_SA_DQ<15>")
	)
	(arc
		(start 84.334096 -234.441746)
		(mid 84.52104 -234.391491)
		(end 84.707984 -234.441746)
		(width 0.0889)
		(layer "In11.Cu")
		(net "M_F_CPU1_SA_DQ<15>")
	)
	(arc
		(start 80.574134 -234.441746)
		(mid 80.761078 -234.391491)
		(end 80.948022 -234.441746)
		(width 0.0889)
		(layer "In11.Cu")
		(net "M_F_CPU1_SA_DQ<15>")
	)
	(arc
		(start 82.46237 -234.43692)
		(mid 82.645878 -234.391426)
		(end 82.82813 -234.441746)
		(width 0.0889)
		(layer "In11.Cu")
		(net "M_F_CPU1_SA_DQ<15>")
	)
	(arc
		(start 80.008222 -234.441746)
		(mid 80.291178 -234.517923)
		(end 80.574134 -234.441746)
		(width 0.0889)
		(layer "In11.Cu")
		(net "M_F_CPU1_SA_DQ<15>")
	)
	(arc
		(start 81.888076 -234.441746)
		(mid 82.171032 -234.517923)
		(end 82.453988 -234.441746)
		(width 0.0889)
		(layer "In11.Cu")
		(net "M_F_CPU1_SA_DQ<15>")
	)
	(arc
		(start 78.12786 -234.441746)
		(mid 78.402312 -234.517982)
		(end 78.67904 -234.450382)
		(width 0.0889)
		(layer "In11.Cu")
		(net "M_F_CPU1_SA_DQ<15>")
	)
	(arc
		(start 83.402424 -234.43692)
		(mid 83.585932 -234.391426)
		(end 83.768184 -234.441746)
		(width 0.0889)
		(layer "In11.Cu")
		(net "M_F_CPU1_SA_DQ<15>")
	)
	(segment
		(start 84.517992 -234.220258)
		(end 84.05114 -233.95432)
		(width 0.10668)
		(layer "F.Cu")
		(net "M_F_CPU1_SA_DQ<14>")
	)
	(segment
		(start 79.53883 -233.631994)
		(end 79.550768 -233.638852)
		(width 0.0889)
		(layer "In11.Cu")
		(net "M_F_CPU1_SA_DQ<14>")
	)
	(segment
		(start 53.155088 -213.06028)
		(end 54.005226 -213.910418)
		(width 0.14478)
		(layer "In11.Cu")
		(net "M_F_CPU1_SA_DQ<14>")
	)
	(segment
		(start 19.428968 -212.907372)
		(end 19.592036 -212.744304)
		(width 0.14478)
		(layer "In11.Cu")
		(net "M_F_CPU1_SA_DQ<14>")
	)
	(segment
		(start 84.205064 -233.68889)
		(end 84.05114 -233.95432)
		(width 0.0889)
		(layer "In11.Cu")
		(net "M_F_CPU1_SA_DQ<14>")
	)
	(segment
		(start 20.14855 -213.910418)
		(end 20.378928 -213.910418)
		(width 0.14478)
		(layer "In11.Cu")
		(net "M_F_CPU1_SA_DQ<14>")
	)
	(segment
		(start 18.033238 -213.910418)
		(end 19.2659 -213.910418)
		(width 0.14478)
		(layer "In11.Cu")
		(net "M_F_CPU1_SA_DQ<14>")
	)
	(segment
		(start 21.261578 -213.910418)
		(end 26.727658 -213.910418)
		(width 0.14478)
		(layer "In11.Cu")
		(net "M_F_CPU1_SA_DQ<14>")
	)
	(segment
		(start 54.005226 -213.910418)
		(end 56.936132 -213.910418)
		(width 0.14478)
		(layer "In11.Cu")
		(net "M_F_CPU1_SA_DQ<14>")
	)
	(segment
		(start 34.35858 -213.910418)
		(end 35.208718 -213.06028)
		(width 0.14478)
		(layer "In11.Cu")
		(net "M_F_CPU1_SA_DQ<14>")
	)
	(segment
		(start 35.208718 -213.06028)
		(end 38.113208 -213.06028)
		(width 0.14478)
		(layer "In11.Cu")
		(net "M_F_CPU1_SA_DQ<14>")
	)
	(segment
		(start 38.113208 -213.06028)
		(end 38.963346 -213.910418)
		(width 0.14478)
		(layer "In11.Cu")
		(net "M_F_CPU1_SA_DQ<14>")
	)
	(segment
		(start 59.626246 -213.06028)
		(end 61.82487 -215.258904)
		(width 0.14478)
		(layer "In11.Cu")
		(net "M_F_CPU1_SA_DQ<14>")
	)
	(segment
		(start 17.608042 -213.485222)
		(end 18.033238 -213.910418)
		(width 0.14478)
		(layer "In11.Cu")
		(net "M_F_CPU1_SA_DQ<14>")
	)
	(segment
		(start 26.727658 -213.910418)
		(end 27.577796 -213.06028)
		(width 0.14478)
		(layer "In11.Cu")
		(net "M_F_CPU1_SA_DQ<14>")
	)
	(segment
		(start 75.963526 -231.337104)
		(end 76.443586 -231.817164)
		(width 0.0889)
		(layer "In11.Cu")
		(net "M_F_CPU1_SA_DQ<14>")
	)
	(segment
		(start 76.443586 -232.084372)
		(end 76.938378 -232.579164)
		(width 0.0889)
		(layer "In11.Cu")
		(net "M_F_CPU1_SA_DQ<14>")
	)
	(segment
		(start 75.628246 -231.337104)
		(end 75.963526 -231.337104)
		(width 0.0889)
		(layer "In11.Cu")
		(net "M_F_CPU1_SA_DQ<14>")
	)
	(segment
		(start 19.592036 -212.744304)
		(end 19.822414 -212.744304)
		(width 0.14478)
		(layer "In11.Cu")
		(net "M_F_CPU1_SA_DQ<14>")
	)
	(segment
		(start 21.09851 -213.74735)
		(end 21.261578 -213.910418)
		(width 0.14478)
		(layer "In11.Cu")
		(net "M_F_CPU1_SA_DQ<14>")
	)
	(segment
		(start 20.541996 -212.907372)
		(end 20.705064 -212.744304)
		(width 0.14478)
		(layer "In11.Cu")
		(net "M_F_CPU1_SA_DQ<14>")
	)
	(segment
		(start 49.389792 -213.910418)
		(end 50.23993 -213.06028)
		(width 0.14478)
		(layer "In11.Cu")
		(net "M_F_CPU1_SA_DQ<14>")
	)
	(segment
		(start 57.78627 -213.06028)
		(end 59.626246 -213.06028)
		(width 0.14478)
		(layer "In11.Cu")
		(net "M_F_CPU1_SA_DQ<14>")
	)
	(segment
		(start 19.985482 -213.74735)
		(end 20.14855 -213.910418)
		(width 0.14478)
		(layer "In11.Cu")
		(net "M_F_CPU1_SA_DQ<14>")
	)
	(segment
		(start 27.577796 -213.06028)
		(end 30.543754 -213.06028)
		(width 0.14478)
		(layer "In11.Cu")
		(net "M_F_CPU1_SA_DQ<14>")
	)
	(segment
		(start 76.443586 -231.817164)
		(end 76.443586 -232.084372)
		(width 0.0889)
		(layer "In11.Cu")
		(net "M_F_CPU1_SA_DQ<14>")
	)
	(segment
		(start 20.935442 -212.744304)
		(end 21.09851 -212.907372)
		(width 0.14478)
		(layer "In11.Cu")
		(net "M_F_CPU1_SA_DQ<14>")
	)
	(segment
		(start 83.289648 -233.626914)
		(end 83.29803 -233.63174)
		(width 0.0889)
		(layer "In11.Cu")
		(net "M_F_CPU1_SA_DQ<14>")
	)
	(segment
		(start 20.378928 -213.910418)
		(end 20.541996 -213.74735)
		(width 0.14478)
		(layer "In11.Cu")
		(net "M_F_CPU1_SA_DQ<14>")
	)
	(segment
		(start 31.393892 -213.910418)
		(end 34.35858 -213.910418)
		(width 0.14478)
		(layer "In11.Cu")
		(net "M_F_CPU1_SA_DQ<14>")
	)
	(segment
		(start 19.985482 -212.907372)
		(end 19.985482 -213.74735)
		(width 0.14478)
		(layer "In11.Cu")
		(net "M_F_CPU1_SA_DQ<14>")
	)
	(segment
		(start 21.09851 -212.907372)
		(end 21.09851 -213.74735)
		(width 0.14478)
		(layer "In11.Cu")
		(net "M_F_CPU1_SA_DQ<14>")
	)
	(segment
		(start 81.044034 -233.63174)
		(end 81.052416 -233.626914)
		(width 0.0889)
		(layer "In11.Cu")
		(net "M_F_CPU1_SA_DQ<14>")
	)
	(segment
		(start 42.742104 -213.06028)
		(end 45.618654 -213.06028)
		(width 0.14478)
		(layer "In11.Cu")
		(net "M_F_CPU1_SA_DQ<14>")
	)
	(segment
		(start 20.705064 -212.744304)
		(end 20.935442 -212.744304)
		(width 0.14478)
		(layer "In11.Cu")
		(net "M_F_CPU1_SA_DQ<14>")
	)
	(segment
		(start 38.963346 -213.910418)
		(end 41.891966 -213.910418)
		(width 0.14478)
		(layer "In11.Cu")
		(net "M_F_CPU1_SA_DQ<14>")
	)
	(segment
		(start 56.936132 -213.910418)
		(end 57.78627 -213.06028)
		(width 0.14478)
		(layer "In11.Cu")
		(net "M_F_CPU1_SA_DQ<14>")
	)
	(segment
		(start 67.002406 -221.727776)
		(end 67.002406 -223.105472)
		(width 0.14478)
		(layer "In11.Cu")
		(net "M_F_CPU1_SA_DQ<14>")
	)
	(segment
		(start 84.182712 -233.605578)
		(end 84.205064 -233.68889)
		(width 0.0889)
		(layer "In11.Cu")
		(net "M_F_CPU1_SA_DQ<14>")
	)
	(segment
		(start 19.2659 -213.910418)
		(end 19.428968 -213.74735)
		(width 0.14478)
		(layer "In11.Cu")
		(net "M_F_CPU1_SA_DQ<14>")
	)
	(segment
		(start 79.147162 -233.642408)
		(end 79.165196 -233.63174)
		(width 0.0889)
		(layer "In11.Cu")
		(net "M_F_CPU1_SA_DQ<14>")
	)
	(segment
		(start 30.543754 -213.06028)
		(end 31.393892 -213.910418)
		(width 0.14478)
		(layer "In11.Cu")
		(net "M_F_CPU1_SA_DQ<14>")
	)
	(segment
		(start 80.46974 -233.626914)
		(end 80.478122 -233.63174)
		(width 0.0889)
		(layer "In11.Cu")
		(net "M_F_CPU1_SA_DQ<14>")
	)
	(segment
		(start 20.541996 -213.74735)
		(end 20.541996 -212.907372)
		(width 0.14478)
		(layer "In11.Cu")
		(net "M_F_CPU1_SA_DQ<14>")
	)
	(segment
		(start 78.173834 -233.58094)
		(end 78.41107 -233.58094)
		(width 0.0889)
		(layer "In11.Cu")
		(net "M_F_CPU1_SA_DQ<14>")
	)
	(segment
		(start 61.82487 -215.258904)
		(end 61.82487 -216.55024)
		(width 0.14478)
		(layer "In11.Cu")
		(net "M_F_CPU1_SA_DQ<14>")
	)
	(segment
		(start 41.891966 -213.910418)
		(end 42.742104 -213.06028)
		(width 0.14478)
		(layer "In11.Cu")
		(net "M_F_CPU1_SA_DQ<14>")
	)
	(segment
		(start 50.23993 -213.06028)
		(end 53.155088 -213.06028)
		(width 0.14478)
		(layer "In11.Cu")
		(net "M_F_CPU1_SA_DQ<14>")
	)
	(segment
		(start 61.82487 -216.55024)
		(end 67.002406 -221.727776)
		(width 0.14478)
		(layer "In11.Cu")
		(net "M_F_CPU1_SA_DQ<14>")
	)
	(segment
		(start 45.618654 -213.06028)
		(end 46.468792 -213.910418)
		(width 0.14478)
		(layer "In11.Cu")
		(net "M_F_CPU1_SA_DQ<14>")
	)
	(segment
		(start 79.525114 -233.62412)
		(end 79.53883 -233.631994)
		(width 0.0889)
		(layer "In11.Cu")
		(net "M_F_CPU1_SA_DQ<14>")
	)
	(segment
		(start 76.938378 -232.579164)
		(end 77.172058 -232.579164)
		(width 0.0889)
		(layer "In11.Cu")
		(net "M_F_CPU1_SA_DQ<14>")
	)
	(segment
		(start 46.468792 -213.910418)
		(end 49.389792 -213.910418)
		(width 0.14478)
		(layer "In11.Cu")
		(net "M_F_CPU1_SA_DQ<14>")
	)
	(segment
		(start 67.002406 -223.105472)
		(end 75.234038 -231.337104)
		(width 0.14478)
		(layer "In11.Cu")
		(net "M_F_CPU1_SA_DQ<14>")
	)
	(segment
		(start 19.822414 -212.744304)
		(end 19.985482 -212.907372)
		(width 0.14478)
		(layer "In11.Cu")
		(net "M_F_CPU1_SA_DQ<14>")
	)
	(segment
		(start 77.172058 -232.579164)
		(end 78.173834 -233.58094)
		(width 0.0889)
		(layer "In11.Cu")
		(net "M_F_CPU1_SA_DQ<14>")
	)
	(segment
		(start 75.234038 -231.337104)
		(end 75.628246 -231.337104)
		(width 0.14478)
		(layer "In11.Cu")
		(net "M_F_CPU1_SA_DQ<14>")
	)
	(segment
		(start 19.428968 -213.74735)
		(end 19.428968 -212.907372)
		(width 0.14478)
		(layer "In11.Cu")
		(net "M_F_CPU1_SA_DQ<14>")
	)
	(arc
		(start 83.863942 -233.63174)
		(mid 84.02038 -233.582769)
		(end 84.182712 -233.605578)
		(width 0.0889)
		(layer "In11.Cu")
		(net "M_F_CPU1_SA_DQ<14>")
	)
	(arc
		(start 80.10398 -233.63174)
		(mid 80.286231 -233.58139)
		(end 80.46974 -233.626914)
		(width 0.0889)
		(layer "In11.Cu")
		(net "M_F_CPU1_SA_DQ<14>")
	)
	(arc
		(start 82.357976 -233.63174)
		(mid 82.640932 -233.707917)
		(end 82.923888 -233.63174)
		(width 0.0889)
		(layer "In11.Cu")
		(net "M_F_CPU1_SA_DQ<14>")
	)
	(arc
		(start 80.478122 -233.63174)
		(mid 80.761078 -233.707917)
		(end 81.044034 -233.63174)
		(width 0.0889)
		(layer "In11.Cu")
		(net "M_F_CPU1_SA_DQ<14>")
	)
	(arc
		(start 78.598522 -233.63174)
		(mid 78.871466 -233.70832)
		(end 79.147162 -233.642408)
		(width 0.0889)
		(layer "In11.Cu")
		(net "M_F_CPU1_SA_DQ<14>")
	)
	(arc
		(start 81.984088 -233.63174)
		(mid 82.171032 -233.581485)
		(end 82.357976 -233.63174)
		(width 0.0889)
		(layer "In11.Cu")
		(net "M_F_CPU1_SA_DQ<14>")
	)
	(arc
		(start 82.923888 -233.63174)
		(mid 83.106139 -233.58139)
		(end 83.289648 -233.626914)
		(width 0.0889)
		(layer "In11.Cu")
		(net "M_F_CPU1_SA_DQ<14>")
	)
	(arc
		(start 78.41107 -233.58094)
		(mid 78.508159 -233.59393)
		(end 78.598522 -233.63174)
		(width 0.0889)
		(layer "In11.Cu")
		(net "M_F_CPU1_SA_DQ<14>")
	)
	(arc
		(start 83.29803 -233.63174)
		(mid 83.580986 -233.707917)
		(end 83.863942 -233.63174)
		(width 0.0889)
		(layer "In11.Cu")
		(net "M_F_CPU1_SA_DQ<14>")
	)
	(arc
		(start 81.052416 -233.626914)
		(mid 81.235924 -233.58142)
		(end 81.418176 -233.63174)
		(width 0.0889)
		(layer "In11.Cu")
		(net "M_F_CPU1_SA_DQ<14>")
	)
	(arc
		(start 81.418176 -233.63174)
		(mid 81.701132 -233.707917)
		(end 81.984088 -233.63174)
		(width 0.0889)
		(layer "In11.Cu")
		(net "M_F_CPU1_SA_DQ<14>")
	)
	(arc
		(start 79.550768 -233.638852)
		(mid 79.828302 -233.707833)
		(end 80.10398 -233.63174)
		(width 0.0889)
		(layer "In11.Cu")
		(net "M_F_CPU1_SA_DQ<14>")
	)
	(arc
		(start 79.165196 -233.63174)
		(mid 79.344183 -233.58157)
		(end 79.525114 -233.62412)
		(width 0.0889)
		(layer "In11.Cu")
		(net "M_F_CPU1_SA_DQ<14>")
	)
	(segment
		(start 86.397846 -234.220258)
		(end 85.930994 -233.95432)
		(width 0.10668)
		(layer "F.Cu")
		(net "M_F_CPU1_SA_DQ<13>")
	)
	(segment
		(start 55.952644 -215.147144)
		(end 56.183022 -215.147144)
		(width 0.14478)
		(layer "In11.Cu")
		(net "M_F_CPU1_SA_DQ<13>")
	)
	(segment
		(start 56.183022 -215.147144)
		(end 56.34609 -214.984076)
		(width 0.14478)
		(layer "In11.Cu")
		(net "M_F_CPU1_SA_DQ<13>")
	)
	(segment
		(start 33.372298 -214.989156)
		(end 33.535366 -215.152224)
		(width 0.14478)
		(layer "In11.Cu")
		(net "M_F_CPU1_SA_DQ<13>")
	)
	(segment
		(start 78.583282 -234.285282)
		(end 78.608174 -234.270804)
		(width 0.0889)
		(layer "In11.Cu")
		(net "M_F_CPU1_SA_DQ<13>")
	)
	(segment
		(start 76.197714 -232.127552)
		(end 76.903326 -232.833164)
		(width 0.0889)
		(layer "In11.Cu")
		(net "M_F_CPU1_SA_DQ<13>")
	)
	(segment
		(start 22.684486 -214.92337)
		(end 22.684486 -214.984076)
		(width 0.14478)
		(layer "In11.Cu")
		(net "M_F_CPU1_SA_DQ<13>")
	)
	(segment
		(start 34.09188 -214.760302)
		(end 34.383218 -214.760302)
		(width 0.14478)
		(layer "In11.Cu")
		(net "M_F_CPU1_SA_DQ<13>")
	)
	(segment
		(start 85.77707 -234.21975)
		(end 85.930994 -233.95432)
		(width 0.0889)
		(layer "In11.Cu")
		(net "M_F_CPU1_SA_DQ<13>")
	)
	(segment
		(start 43.050206 -213.910418)
		(end 43.213274 -214.073486)
		(width 0.14478)
		(layer "In11.Cu")
		(net "M_F_CPU1_SA_DQ<13>")
	)
	(segment
		(start 51.255422 -214.298784)
		(end 51.41849 -214.135716)
		(width 0.14478)
		(layer "In11.Cu")
		(net "M_F_CPU1_SA_DQ<13>")
	)
	(segment
		(start 23.241 -214.536528)
		(end 23.404068 -214.37346)
		(width 0.14478)
		(layer "In11.Cu")
		(net "M_F_CPU1_SA_DQ<13>")
	)
	(segment
		(start 66.547746 -223.29394)
		(end 75.04557 -231.791764)
		(width 0.14478)
		(layer "In11.Cu")
		(net "M_F_CPU1_SA_DQ<13>")
	)
	(segment
		(start 61.37021 -216.738708)
		(end 66.547746 -221.916244)
		(width 0.14478)
		(layer "In11.Cu")
		(net "M_F_CPU1_SA_DQ<13>")
	)
	(segment
		(start 33.928812 -214.989156)
		(end 33.928812 -214.92337)
		(width 0.14478)
		(layer "In11.Cu")
		(net "M_F_CPU1_SA_DQ<13>")
	)
	(segment
		(start 33.535366 -215.152224)
		(end 33.765744 -215.152224)
		(width 0.14478)
		(layer "In11.Cu")
		(net "M_F_CPU1_SA_DQ<13>")
	)
	(segment
		(start 75.968606 -231.791764)
		(end 76.197714 -232.020872)
		(width 0.0889)
		(layer "In11.Cu")
		(net "M_F_CPU1_SA_DQ<13>")
	)
	(segment
		(start 59.012582 -214.073486)
		(end 59.17565 -213.910418)
		(width 0.14478)
		(layer "In11.Cu")
		(net "M_F_CPU1_SA_DQ<13>")
	)
	(segment
		(start 49.448974 -214.760302)
		(end 50.298858 -213.910418)
		(width 0.14478)
		(layer "In11.Cu")
		(net "M_F_CPU1_SA_DQ<13>")
	)
	(segment
		(start 43.60672 -214.298784)
		(end 43.769788 -214.135716)
		(width 0.14478)
		(layer "In11.Cu")
		(net "M_F_CPU1_SA_DQ<13>")
	)
	(segment
		(start 50.698908 -213.910418)
		(end 50.861976 -214.073486)
		(width 0.14478)
		(layer "In11.Cu")
		(net "M_F_CPU1_SA_DQ<13>")
	)
	(segment
		(start 55.069994 -215.147144)
		(end 55.233062 -214.984076)
		(width 0.14478)
		(layer "In11.Cu")
		(net "M_F_CPU1_SA_DQ<13>")
	)
	(segment
		(start 80.093566 -234.270804)
		(end 80.10398 -234.2769)
		(width 0.0889)
		(layer "In11.Cu")
		(net "M_F_CPU1_SA_DQ<13>")
	)
	(segment
		(start 76.903326 -232.833164)
		(end 77.078586 -232.833164)
		(width 0.0889)
		(layer "In11.Cu")
		(net "M_F_CPU1_SA_DQ<13>")
	)
	(segment
		(start 33.372298 -214.92337)
		(end 33.372298 -214.989156)
		(width 0.14478)
		(layer "In11.Cu")
		(net "M_F_CPU1_SA_DQ<13>")
	)
	(segment
		(start 55.233062 -214.984076)
		(end 55.233062 -214.92337)
		(width 0.14478)
		(layer "In11.Cu")
		(net "M_F_CPU1_SA_DQ<13>")
	)
	(segment
		(start 28.154884 -214.135716)
		(end 28.317952 -214.298784)
		(width 0.14478)
		(layer "In11.Cu")
		(net "M_F_CPU1_SA_DQ<13>")
	)
	(segment
		(start 40.67302 -214.760302)
		(end 40.836088 -214.92337)
		(width 0.14478)
		(layer "In11.Cu")
		(net "M_F_CPU1_SA_DQ<13>")
	)
	(segment
		(start 26.393648 -214.989156)
		(end 26.393648 -214.92337)
		(width 0.14478)
		(layer "In11.Cu")
		(net "M_F_CPU1_SA_DQ<13>")
	)
	(segment
		(start 58.456068 -214.135716)
		(end 58.619136 -214.298784)
		(width 0.14478)
		(layer "In11.Cu")
		(net "M_F_CPU1_SA_DQ<13>")
	)
	(segment
		(start 83.289648 -234.281726)
		(end 83.29803 -234.2769)
		(width 0.0889)
		(layer "In11.Cu")
		(net "M_F_CPU1_SA_DQ<13>")
	)
	(segment
		(start 54.51348 -214.760302)
		(end 54.676548 -214.92337)
		(width 0.14478)
		(layer "In11.Cu")
		(net "M_F_CPU1_SA_DQ<13>")
	)
	(segment
		(start 75.628246 -231.791764)
		(end 75.968606 -231.791764)
		(width 0.0889)
		(layer "In11.Cu")
		(net "M_F_CPU1_SA_DQ<13>")
	)
	(segment
		(start 23.077932 -215.147144)
		(end 23.241 -214.984076)
		(width 0.14478)
		(layer "In11.Cu")
		(net "M_F_CPU1_SA_DQ<13>")
	)
	(segment
		(start 51.41849 -214.073486)
		(end 51.581558 -213.910418)
		(width 0.14478)
		(layer "In11.Cu")
		(net "M_F_CPU1_SA_DQ<13>")
	)
	(segment
		(start 77.078586 -232.833164)
		(end 77.383386 -233.137964)
		(width 0.0889)
		(layer "In11.Cu")
		(net "M_F_CPU1_SA_DQ<13>")
	)
	(segment
		(start 24.354028 -214.92337)
		(end 24.517096 -214.760302)
		(width 0.14478)
		(layer "In11.Cu")
		(net "M_F_CPU1_SA_DQ<13>")
	)
	(segment
		(start 56.509158 -214.760302)
		(end 56.954674 -214.760302)
		(width 0.14478)
		(layer "In11.Cu")
		(net "M_F_CPU1_SA_DQ<13>")
	)
	(segment
		(start 40.836088 -214.92337)
		(end 40.836088 -214.989156)
		(width 0.14478)
		(layer "In11.Cu")
		(net "M_F_CPU1_SA_DQ<13>")
	)
	(segment
		(start 22.521418 -214.760302)
		(end 22.684486 -214.92337)
		(width 0.14478)
		(layer "In11.Cu")
		(net "M_F_CPU1_SA_DQ<13>")
	)
	(segment
		(start 26.393648 -214.92337)
		(end 26.556716 -214.760302)
		(width 0.14478)
		(layer "In11.Cu")
		(net "M_F_CPU1_SA_DQ<13>")
	)
	(segment
		(start 36.415726 -213.910418)
		(end 37.95268 -213.910418)
		(width 0.14478)
		(layer "In11.Cu")
		(net "M_F_CPU1_SA_DQ<13>")
	)
	(segment
		(start 35.233102 -213.910418)
		(end 35.533076 -213.910418)
		(width 0.14478)
		(layer "In11.Cu")
		(net "M_F_CPU1_SA_DQ<13>")
	)
	(segment
		(start 59.406028 -213.910418)
		(end 59.569096 -214.073486)
		(width 0.14478)
		(layer "In11.Cu")
		(net "M_F_CPU1_SA_DQ<13>")
	)
	(segment
		(start 55.39613 -214.760302)
		(end 55.626508 -214.760302)
		(width 0.14478)
		(layer "In11.Cu")
		(net "M_F_CPU1_SA_DQ<13>")
	)
	(segment
		(start 48.975518 -214.978996)
		(end 48.975518 -214.92337)
		(width 0.14478)
		(layer "In11.Cu")
		(net "M_F_CPU1_SA_DQ<13>")
	)
	(segment
		(start 36.08959 -214.293704)
		(end 36.252658 -214.130636)
		(width 0.14478)
		(layer "In11.Cu")
		(net "M_F_CPU1_SA_DQ<13>")
	)
	(segment
		(start 41.229534 -215.152224)
		(end 41.392602 -214.989156)
		(width 0.14478)
		(layer "In11.Cu")
		(net "M_F_CPU1_SA_DQ<13>")
	)
	(segment
		(start 24.517096 -214.760302)
		(end 25.674066 -214.760302)
		(width 0.14478)
		(layer "In11.Cu")
		(net "M_F_CPU1_SA_DQ<13>")
	)
	(segment
		(start 37.95268 -213.910418)
		(end 38.802564 -214.760302)
		(width 0.14478)
		(layer "In11.Cu")
		(net "M_F_CPU1_SA_DQ<13>")
	)
	(segment
		(start 60.020454 -214.298784)
		(end 61.37021 -215.64854)
		(width 0.14478)
		(layer "In11.Cu")
		(net "M_F_CPU1_SA_DQ<13>")
	)
	(segment
		(start 28.711398 -214.073486)
		(end 28.874466 -213.910418)
		(width 0.14478)
		(layer "In11.Cu")
		(net "M_F_CPU1_SA_DQ<13>")
	)
	(segment
		(start 28.154884 -214.073486)
		(end 28.154884 -214.135716)
		(width 0.14478)
		(layer "In11.Cu")
		(net "M_F_CPU1_SA_DQ<13>")
	)
	(segment
		(start 56.954674 -214.760302)
		(end 57.804558 -213.910418)
		(width 0.14478)
		(layer "In11.Cu")
		(net "M_F_CPU1_SA_DQ<13>")
	)
	(segment
		(start 33.928812 -214.92337)
		(end 34.09188 -214.760302)
		(width 0.14478)
		(layer "In11.Cu")
		(net "M_F_CPU1_SA_DQ<13>")
	)
	(segment
		(start 36.252658 -214.073486)
		(end 36.415726 -213.910418)
		(width 0.14478)
		(layer "In11.Cu")
		(net "M_F_CPU1_SA_DQ<13>")
	)
	(segment
		(start 48.81245 -215.142064)
		(end 48.975518 -214.978996)
		(width 0.14478)
		(layer "In11.Cu")
		(net "M_F_CPU1_SA_DQ<13>")
	)
	(segment
		(start 21.70811 -214.33536)
		(end 22.133052 -214.760302)
		(width 0.14478)
		(layer "In11.Cu")
		(net "M_F_CPU1_SA_DQ<13>")
	)
	(segment
		(start 55.233062 -214.92337)
		(end 55.39613 -214.760302)
		(width 0.14478)
		(layer "In11.Cu")
		(net "M_F_CPU1_SA_DQ<13>")
	)
	(segment
		(start 48.975518 -214.92337)
		(end 49.138586 -214.760302)
		(width 0.14478)
		(layer "In11.Cu")
		(net "M_F_CPU1_SA_DQ<13>")
	)
	(segment
		(start 76.197714 -232.020872)
		(end 76.197714 -232.127552)
		(width 0.0889)
		(layer "In11.Cu")
		(net "M_F_CPU1_SA_DQ<13>")
	)
	(segment
		(start 23.241 -214.984076)
		(end 23.241 -214.536528)
		(width 0.14478)
		(layer "In11.Cu")
		(net "M_F_CPU1_SA_DQ<13>")
	)
	(segment
		(start 40.836088 -214.989156)
		(end 40.999156 -215.152224)
		(width 0.14478)
		(layer "In11.Cu")
		(net "M_F_CPU1_SA_DQ<13>")
	)
	(segment
		(start 51.581558 -213.910418)
		(end 53.111908 -213.910418)
		(width 0.14478)
		(layer "In11.Cu")
		(net "M_F_CPU1_SA_DQ<13>")
	)
	(segment
		(start 28.54833 -214.298784)
		(end 28.711398 -214.135716)
		(width 0.14478)
		(layer "In11.Cu")
		(net "M_F_CPU1_SA_DQ<13>")
	)
	(segment
		(start 35.696144 -214.073486)
		(end 35.696144 -214.130636)
		(width 0.14478)
		(layer "In11.Cu")
		(net "M_F_CPU1_SA_DQ<13>")
	)
	(segment
		(start 54.676548 -214.984076)
		(end 54.839616 -215.147144)
		(width 0.14478)
		(layer "In11.Cu")
		(net "M_F_CPU1_SA_DQ<13>")
	)
	(segment
		(start 27.991816 -213.910418)
		(end 28.154884 -214.073486)
		(width 0.14478)
		(layer "In11.Cu")
		(net "M_F_CPU1_SA_DQ<13>")
	)
	(segment
		(start 28.874466 -213.910418)
		(end 30.470856 -213.910418)
		(width 0.14478)
		(layer "In11.Cu")
		(net "M_F_CPU1_SA_DQ<13>")
	)
	(segment
		(start 48.419004 -214.978996)
		(end 48.582072 -215.142064)
		(width 0.14478)
		(layer "In11.Cu")
		(net "M_F_CPU1_SA_DQ<13>")
	)
	(segment
		(start 41.94302 -214.760302)
		(end 42.792904 -213.910418)
		(width 0.14478)
		(layer "In11.Cu")
		(net "M_F_CPU1_SA_DQ<13>")
	)
	(segment
		(start 85.681058 -234.24515)
		(end 85.77707 -234.21975)
		(width 0.0889)
		(layer "In11.Cu")
		(net "M_F_CPU1_SA_DQ<13>")
	)
	(segment
		(start 77.383386 -233.137964)
		(end 77.383386 -233.454194)
		(width 0.0889)
		(layer "In11.Cu")
		(net "M_F_CPU1_SA_DQ<13>")
	)
	(segment
		(start 34.383218 -214.760302)
		(end 35.233102 -213.910418)
		(width 0.14478)
		(layer "In11.Cu")
		(net "M_F_CPU1_SA_DQ<13>")
	)
	(segment
		(start 53.111908 -213.910418)
		(end 53.961792 -214.760302)
		(width 0.14478)
		(layer "In11.Cu")
		(net "M_F_CPU1_SA_DQ<13>")
	)
	(segment
		(start 27.664664 -213.910418)
		(end 27.991816 -213.910418)
		(width 0.14478)
		(layer "In11.Cu")
		(net "M_F_CPU1_SA_DQ<13>")
	)
	(segment
		(start 35.696144 -214.130636)
		(end 35.859212 -214.293704)
		(width 0.14478)
		(layer "In11.Cu")
		(net "M_F_CPU1_SA_DQ<13>")
	)
	(segment
		(start 33.20923 -214.760302)
		(end 33.372298 -214.92337)
		(width 0.14478)
		(layer "In11.Cu")
		(net "M_F_CPU1_SA_DQ<13>")
	)
	(segment
		(start 75.04557 -231.791764)
		(end 75.628246 -231.791764)
		(width 0.14478)
		(layer "In11.Cu")
		(net "M_F_CPU1_SA_DQ<13>")
	)
	(segment
		(start 61.37021 -215.64854)
		(end 61.37021 -216.738708)
		(width 0.14478)
		(layer "In11.Cu")
		(net "M_F_CPU1_SA_DQ<13>")
	)
	(segment
		(start 43.376342 -214.298784)
		(end 43.60672 -214.298784)
		(width 0.14478)
		(layer "In11.Cu")
		(net "M_F_CPU1_SA_DQ<13>")
	)
	(segment
		(start 41.392602 -214.92337)
		(end 41.55567 -214.760302)
		(width 0.14478)
		(layer "In11.Cu")
		(net "M_F_CPU1_SA_DQ<13>")
	)
	(segment
		(start 25.674066 -214.760302)
		(end 25.837134 -214.92337)
		(width 0.14478)
		(layer "In11.Cu")
		(net "M_F_CPU1_SA_DQ<13>")
	)
	(segment
		(start 59.17565 -213.910418)
		(end 59.406028 -213.910418)
		(width 0.14478)
		(layer "In11.Cu")
		(net "M_F_CPU1_SA_DQ<13>")
	)
	(segment
		(start 41.392602 -214.989156)
		(end 41.392602 -214.92337)
		(width 0.14478)
		(layer "In11.Cu")
		(net "M_F_CPU1_SA_DQ<13>")
	)
	(segment
		(start 51.41849 -214.135716)
		(end 51.41849 -214.073486)
		(width 0.14478)
		(layer "In11.Cu")
		(net "M_F_CPU1_SA_DQ<13>")
	)
	(segment
		(start 25.837134 -214.92337)
		(end 25.837134 -214.989156)
		(width 0.14478)
		(layer "In11.Cu")
		(net "M_F_CPU1_SA_DQ<13>")
	)
	(segment
		(start 57.804558 -213.910418)
		(end 58.293 -213.910418)
		(width 0.14478)
		(layer "In11.Cu")
		(net "M_F_CPU1_SA_DQ<13>")
	)
	(segment
		(start 23.634446 -214.37346)
		(end 23.797514 -214.536528)
		(width 0.14478)
		(layer "In11.Cu")
		(net "M_F_CPU1_SA_DQ<13>")
	)
	(segment
		(start 51.025044 -214.298784)
		(end 51.255422 -214.298784)
		(width 0.14478)
		(layer "In11.Cu")
		(net "M_F_CPU1_SA_DQ<13>")
	)
	(segment
		(start 58.293 -213.910418)
		(end 58.456068 -214.073486)
		(width 0.14478)
		(layer "In11.Cu")
		(net "M_F_CPU1_SA_DQ<13>")
	)
	(segment
		(start 43.769788 -214.073486)
		(end 43.932856 -213.910418)
		(width 0.14478)
		(layer "In11.Cu")
		(net "M_F_CPU1_SA_DQ<13>")
	)
	(segment
		(start 43.213274 -214.073486)
		(end 43.213274 -214.135716)
		(width 0.14478)
		(layer "In11.Cu")
		(net "M_F_CPU1_SA_DQ<13>")
	)
	(segment
		(start 23.797514 -214.984076)
		(end 23.960582 -215.147144)
		(width 0.14478)
		(layer "In11.Cu")
		(net "M_F_CPU1_SA_DQ<13>")
	)
	(segment
		(start 84.803996 -234.2769)
		(end 84.812378 -234.281726)
		(width 0.0889)
		(layer "In11.Cu")
		(net "M_F_CPU1_SA_DQ<13>")
	)
	(segment
		(start 59.012582 -214.135716)
		(end 59.012582 -214.073486)
		(width 0.14478)
		(layer "In11.Cu")
		(net "M_F_CPU1_SA_DQ<13>")
	)
	(segment
		(start 35.533076 -213.910418)
		(end 35.696144 -214.073486)
		(width 0.14478)
		(layer "In11.Cu")
		(net "M_F_CPU1_SA_DQ<13>")
	)
	(segment
		(start 24.19096 -215.147144)
		(end 24.354028 -214.984076)
		(width 0.14478)
		(layer "In11.Cu")
		(net "M_F_CPU1_SA_DQ<13>")
	)
	(segment
		(start 48.419004 -214.92337)
		(end 48.419004 -214.978996)
		(width 0.14478)
		(layer "In11.Cu")
		(net "M_F_CPU1_SA_DQ<13>")
	)
	(segment
		(start 25.837134 -214.989156)
		(end 26.000202 -215.152224)
		(width 0.14478)
		(layer "In11.Cu")
		(net "M_F_CPU1_SA_DQ<13>")
	)
	(segment
		(start 59.732164 -214.298784)
		(end 60.020454 -214.298784)
		(width 0.14478)
		(layer "In11.Cu")
		(net "M_F_CPU1_SA_DQ<13>")
	)
	(segment
		(start 50.861976 -214.135716)
		(end 51.025044 -214.298784)
		(width 0.14478)
		(layer "In11.Cu")
		(net "M_F_CPU1_SA_DQ<13>")
	)
	(segment
		(start 55.789576 -214.984076)
		(end 55.952644 -215.147144)
		(width 0.14478)
		(layer "In11.Cu")
		(net "M_F_CPU1_SA_DQ<13>")
	)
	(segment
		(start 45.567854 -213.910418)
		(end 46.417738 -214.760302)
		(width 0.14478)
		(layer "In11.Cu")
		(net "M_F_CPU1_SA_DQ<13>")
	)
	(segment
		(start 58.619136 -214.298784)
		(end 58.849514 -214.298784)
		(width 0.14478)
		(layer "In11.Cu")
		(net "M_F_CPU1_SA_DQ<13>")
	)
	(segment
		(start 49.138586 -214.760302)
		(end 49.448974 -214.760302)
		(width 0.14478)
		(layer "In11.Cu")
		(net "M_F_CPU1_SA_DQ<13>")
	)
	(segment
		(start 24.354028 -214.984076)
		(end 24.354028 -214.92337)
		(width 0.14478)
		(layer "In11.Cu")
		(net "M_F_CPU1_SA_DQ<13>")
	)
	(segment
		(start 26.23058 -215.152224)
		(end 26.393648 -214.989156)
		(width 0.14478)
		(layer "In11.Cu")
		(net "M_F_CPU1_SA_DQ<13>")
	)
	(segment
		(start 30.470856 -213.910418)
		(end 31.32074 -214.760302)
		(width 0.14478)
		(layer "In11.Cu")
		(net "M_F_CPU1_SA_DQ<13>")
	)
	(segment
		(start 56.34609 -214.92337)
		(end 56.509158 -214.760302)
		(width 0.14478)
		(layer "In11.Cu")
		(net "M_F_CPU1_SA_DQ<13>")
	)
	(segment
		(start 81.044034 -234.2769)
		(end 81.052416 -234.281726)
		(width 0.0889)
		(layer "In11.Cu")
		(net "M_F_CPU1_SA_DQ<13>")
	)
	(segment
		(start 84.229702 -234.281726)
		(end 84.238084 -234.2769)
		(width 0.0889)
		(layer "In11.Cu")
		(net "M_F_CPU1_SA_DQ<13>")
	)
	(segment
		(start 54.676548 -214.92337)
		(end 54.676548 -214.984076)
		(width 0.14478)
		(layer "In11.Cu")
		(net "M_F_CPU1_SA_DQ<13>")
	)
	(segment
		(start 31.32074 -214.760302)
		(end 33.20923 -214.760302)
		(width 0.14478)
		(layer "In11.Cu")
		(net "M_F_CPU1_SA_DQ<13>")
	)
	(segment
		(start 80.46974 -234.281726)
		(end 80.478122 -234.2769)
		(width 0.0889)
		(layer "In11.Cu")
		(net "M_F_CPU1_SA_DQ<13>")
	)
	(segment
		(start 26.000202 -215.152224)
		(end 26.23058 -215.152224)
		(width 0.14478)
		(layer "In11.Cu")
		(net "M_F_CPU1_SA_DQ<13>")
	)
	(segment
		(start 43.769788 -214.135716)
		(end 43.769788 -214.073486)
		(width 0.14478)
		(layer "In11.Cu")
		(net "M_F_CPU1_SA_DQ<13>")
	)
	(segment
		(start 53.961792 -214.760302)
		(end 54.51348 -214.760302)
		(width 0.14478)
		(layer "In11.Cu")
		(net "M_F_CPU1_SA_DQ<13>")
	)
	(segment
		(start 26.556716 -214.760302)
		(end 26.81478 -214.760302)
		(width 0.14478)
		(layer "In11.Cu")
		(net "M_F_CPU1_SA_DQ<13>")
	)
	(segment
		(start 66.547746 -221.916244)
		(end 66.547746 -223.29394)
		(width 0.14478)
		(layer "In11.Cu")
		(net "M_F_CPU1_SA_DQ<13>")
	)
	(segment
		(start 40.999156 -215.152224)
		(end 41.229534 -215.152224)
		(width 0.14478)
		(layer "In11.Cu")
		(net "M_F_CPU1_SA_DQ<13>")
	)
	(segment
		(start 46.417738 -214.760302)
		(end 48.255936 -214.760302)
		(width 0.14478)
		(layer "In11.Cu")
		(net "M_F_CPU1_SA_DQ<13>")
	)
	(segment
		(start 36.252658 -214.130636)
		(end 36.252658 -214.073486)
		(width 0.14478)
		(layer "In11.Cu")
		(net "M_F_CPU1_SA_DQ<13>")
	)
	(segment
		(start 23.960582 -215.147144)
		(end 24.19096 -215.147144)
		(width 0.14478)
		(layer "In11.Cu")
		(net "M_F_CPU1_SA_DQ<13>")
	)
	(segment
		(start 58.849514 -214.298784)
		(end 59.012582 -214.135716)
		(width 0.14478)
		(layer "In11.Cu")
		(net "M_F_CPU1_SA_DQ<13>")
	)
	(segment
		(start 38.802564 -214.760302)
		(end 40.67302 -214.760302)
		(width 0.14478)
		(layer "In11.Cu")
		(net "M_F_CPU1_SA_DQ<13>")
	)
	(segment
		(start 55.626508 -214.760302)
		(end 55.789576 -214.92337)
		(width 0.14478)
		(layer "In11.Cu")
		(net "M_F_CPU1_SA_DQ<13>")
	)
	(segment
		(start 48.582072 -215.142064)
		(end 48.81245 -215.142064)
		(width 0.14478)
		(layer "In11.Cu")
		(net "M_F_CPU1_SA_DQ<13>")
	)
	(segment
		(start 35.859212 -214.293704)
		(end 36.08959 -214.293704)
		(width 0.14478)
		(layer "In11.Cu")
		(net "M_F_CPU1_SA_DQ<13>")
	)
	(segment
		(start 50.861976 -214.073486)
		(end 50.861976 -214.135716)
		(width 0.14478)
		(layer "In11.Cu")
		(net "M_F_CPU1_SA_DQ<13>")
	)
	(segment
		(start 55.789576 -214.92337)
		(end 55.789576 -214.984076)
		(width 0.14478)
		(layer "In11.Cu")
		(net "M_F_CPU1_SA_DQ<13>")
	)
	(segment
		(start 43.213274 -214.135716)
		(end 43.376342 -214.298784)
		(width 0.14478)
		(layer "In11.Cu")
		(net "M_F_CPU1_SA_DQ<13>")
	)
	(segment
		(start 43.932856 -213.910418)
		(end 45.567854 -213.910418)
		(width 0.14478)
		(layer "In11.Cu")
		(net "M_F_CPU1_SA_DQ<13>")
	)
	(segment
		(start 54.839616 -215.147144)
		(end 55.069994 -215.147144)
		(width 0.14478)
		(layer "In11.Cu")
		(net "M_F_CPU1_SA_DQ<13>")
	)
	(segment
		(start 59.569096 -214.135716)
		(end 59.732164 -214.298784)
		(width 0.14478)
		(layer "In11.Cu")
		(net "M_F_CPU1_SA_DQ<13>")
	)
	(segment
		(start 22.847554 -215.147144)
		(end 23.077932 -215.147144)
		(width 0.14478)
		(layer "In11.Cu")
		(net "M_F_CPU1_SA_DQ<13>")
	)
	(segment
		(start 22.133052 -214.760302)
		(end 22.521418 -214.760302)
		(width 0.14478)
		(layer "In11.Cu")
		(net "M_F_CPU1_SA_DQ<13>")
	)
	(segment
		(start 22.684486 -214.984076)
		(end 22.847554 -215.147144)
		(width 0.14478)
		(layer "In11.Cu")
		(net "M_F_CPU1_SA_DQ<13>")
	)
	(segment
		(start 48.255936 -214.760302)
		(end 48.419004 -214.92337)
		(width 0.14478)
		(layer "In11.Cu")
		(net "M_F_CPU1_SA_DQ<13>")
	)
	(segment
		(start 58.456068 -214.073486)
		(end 58.456068 -214.135716)
		(width 0.14478)
		(layer "In11.Cu")
		(net "M_F_CPU1_SA_DQ<13>")
	)
	(segment
		(start 28.711398 -214.135716)
		(end 28.711398 -214.073486)
		(width 0.14478)
		(layer "In11.Cu")
		(net "M_F_CPU1_SA_DQ<13>")
	)
	(segment
		(start 41.55567 -214.760302)
		(end 41.94302 -214.760302)
		(width 0.14478)
		(layer "In11.Cu")
		(net "M_F_CPU1_SA_DQ<13>")
	)
	(segment
		(start 23.404068 -214.37346)
		(end 23.634446 -214.37346)
		(width 0.14478)
		(layer "In11.Cu")
		(net "M_F_CPU1_SA_DQ<13>")
	)
	(segment
		(start 33.765744 -215.152224)
		(end 33.928812 -214.989156)
		(width 0.14478)
		(layer "In11.Cu")
		(net "M_F_CPU1_SA_DQ<13>")
	)
	(segment
		(start 77.383386 -233.454194)
		(end 78.147418 -234.218226)
		(width 0.0889)
		(layer "In11.Cu")
		(net "M_F_CPU1_SA_DQ<13>")
	)
	(segment
		(start 59.569096 -214.073486)
		(end 59.569096 -214.135716)
		(width 0.14478)
		(layer "In11.Cu")
		(net "M_F_CPU1_SA_DQ<13>")
	)
	(segment
		(start 56.34609 -214.984076)
		(end 56.34609 -214.92337)
		(width 0.14478)
		(layer "In11.Cu")
		(net "M_F_CPU1_SA_DQ<13>")
	)
	(segment
		(start 23.797514 -214.536528)
		(end 23.797514 -214.984076)
		(width 0.14478)
		(layer "In11.Cu")
		(net "M_F_CPU1_SA_DQ<13>")
	)
	(segment
		(start 26.81478 -214.760302)
		(end 27.664664 -213.910418)
		(width 0.14478)
		(layer "In11.Cu")
		(net "M_F_CPU1_SA_DQ<13>")
	)
	(segment
		(start 28.317952 -214.298784)
		(end 28.54833 -214.298784)
		(width 0.14478)
		(layer "In11.Cu")
		(net "M_F_CPU1_SA_DQ<13>")
	)
	(segment
		(start 50.298858 -213.910418)
		(end 50.698908 -213.910418)
		(width 0.14478)
		(layer "In11.Cu")
		(net "M_F_CPU1_SA_DQ<13>")
	)
	(segment
		(start 42.792904 -213.910418)
		(end 43.050206 -213.910418)
		(width 0.14478)
		(layer "In11.Cu")
		(net "M_F_CPU1_SA_DQ<13>")
	)
	(arc
		(start 80.10398 -234.2769)
		(mid 80.286231 -234.32725)
		(end 80.46974 -234.281726)
		(width 0.0889)
		(layer "In11.Cu")
		(net "M_F_CPU1_SA_DQ<13>")
	)
	(arc
		(start 85.178138 -234.2769)
		(mid 85.425851 -234.20168)
		(end 85.681058 -234.24515)
		(width 0.0889)
		(layer "In11.Cu")
		(net "M_F_CPU1_SA_DQ<13>")
	)
	(arc
		(start 84.812378 -234.281726)
		(mid 84.995886 -234.32722)
		(end 85.178138 -234.2769)
		(width 0.0889)
		(layer "In11.Cu")
		(net "M_F_CPU1_SA_DQ<13>")
	)
	(arc
		(start 82.923888 -234.2769)
		(mid 83.106139 -234.32725)
		(end 83.289648 -234.281726)
		(width 0.0889)
		(layer "In11.Cu")
		(net "M_F_CPU1_SA_DQ<13>")
	)
	(arc
		(start 78.608174 -234.270804)
		(mid 78.886606 -234.200706)
		(end 79.163418 -234.2769)
		(width 0.0889)
		(layer "In11.Cu")
		(net "M_F_CPU1_SA_DQ<13>")
	)
	(arc
		(start 78.147418 -234.218226)
		(mid 78.354377 -234.323027)
		(end 78.583282 -234.285282)
		(width 0.0889)
		(layer "In11.Cu")
		(net "M_F_CPU1_SA_DQ<13>")
	)
	(arc
		(start 81.418176 -234.2769)
		(mid 81.701132 -234.200723)
		(end 81.984088 -234.2769)
		(width 0.0889)
		(layer "In11.Cu")
		(net "M_F_CPU1_SA_DQ<13>")
	)
	(arc
		(start 83.29803 -234.2769)
		(mid 83.580986 -234.200723)
		(end 83.863942 -234.2769)
		(width 0.0889)
		(layer "In11.Cu")
		(net "M_F_CPU1_SA_DQ<13>")
	)
	(arc
		(start 79.537814 -234.2769)
		(mid 79.814881 -234.200629)
		(end 80.093566 -234.270804)
		(width 0.0889)
		(layer "In11.Cu")
		(net "M_F_CPU1_SA_DQ<13>")
	)
	(arc
		(start 84.238084 -234.2769)
		(mid 84.52104 -234.200723)
		(end 84.803996 -234.2769)
		(width 0.0889)
		(layer "In11.Cu")
		(net "M_F_CPU1_SA_DQ<13>")
	)
	(arc
		(start 82.357976 -234.2769)
		(mid 82.640932 -234.200723)
		(end 82.923888 -234.2769)
		(width 0.0889)
		(layer "In11.Cu")
		(net "M_F_CPU1_SA_DQ<13>")
	)
	(arc
		(start 80.478122 -234.2769)
		(mid 80.761078 -234.200723)
		(end 81.044034 -234.2769)
		(width 0.0889)
		(layer "In11.Cu")
		(net "M_F_CPU1_SA_DQ<13>")
	)
	(arc
		(start 79.163418 -234.2769)
		(mid 79.350616 -234.327282)
		(end 79.537814 -234.2769)
		(width 0.0889)
		(layer "In11.Cu")
		(net "M_F_CPU1_SA_DQ<13>")
	)
	(arc
		(start 83.863942 -234.2769)
		(mid 84.046193 -234.32725)
		(end 84.229702 -234.281726)
		(width 0.0889)
		(layer "In11.Cu")
		(net "M_F_CPU1_SA_DQ<13>")
	)
	(arc
		(start 81.984088 -234.2769)
		(mid 82.171032 -234.327155)
		(end 82.357976 -234.2769)
		(width 0.0889)
		(layer "In11.Cu")
		(net "M_F_CPU1_SA_DQ<13>")
	)
	(arc
		(start 81.052416 -234.281726)
		(mid 81.235924 -234.32722)
		(end 81.418176 -234.2769)
		(width 0.0889)
		(layer "In11.Cu")
		(net "M_F_CPU1_SA_DQ<13>")
	)
	(segment
		(start 84.987892 -233.410252)
		(end 84.52104 -233.144314)
		(width 0.10668)
		(layer "F.Cu")
		(net "M_F_CPU1_SA_DQ<12>")
	)
	(segment
		(start 51.28133 -212.438996)
		(end 51.28133 -212.373464)
		(width 0.14478)
		(layer "In11.Cu")
		(net "M_F_CPU1_SA_DQ<12>")
	)
	(segment
		(start 58.827416 -212.373464)
		(end 58.990484 -212.210396)
		(width 0.14478)
		(layer "In11.Cu")
		(net "M_F_CPU1_SA_DQ<12>")
	)
	(segment
		(start 30.480508 -212.220048)
		(end 31.330392 -213.069932)
		(width 0.14478)
		(layer "In11.Cu")
		(net "M_F_CPU1_SA_DQ<12>")
	)
	(segment
		(start 79.622396 -233.459782)
		(end 79.634334 -233.46664)
		(width 0.0889)
		(layer "In11.Cu")
		(net "M_F_CPU1_SA_DQ<12>")
	)
	(segment
		(start 28.029408 -212.373464)
		(end 28.029408 -212.428836)
		(width 0.14478)
		(layer "In11.Cu")
		(net "M_F_CPU1_SA_DQ<12>")
	)
	(segment
		(start 34.01822 -213.282276)
		(end 34.01822 -213.223348)
		(width 0.14478)
		(layer "In11.Cu")
		(net "M_F_CPU1_SA_DQ<12>")
	)
	(segment
		(start 50.887884 -212.602064)
		(end 51.118262 -212.602064)
		(width 0.14478)
		(layer "In11.Cu")
		(net "M_F_CPU1_SA_DQ<12>")
	)
	(segment
		(start 28.739338 -212.220048)
		(end 30.480508 -212.220048)
		(width 0.14478)
		(layer "In11.Cu")
		(net "M_F_CPU1_SA_DQ<12>")
	)
	(segment
		(start 28.422854 -212.591904)
		(end 28.585922 -212.428836)
		(width 0.14478)
		(layer "In11.Cu")
		(net "M_F_CPU1_SA_DQ<12>")
	)
	(segment
		(start 55.012082 -213.287356)
		(end 55.012082 -212.927692)
		(width 0.14478)
		(layer "In11.Cu")
		(net "M_F_CPU1_SA_DQ<12>")
	)
	(segment
		(start 53.961792 -213.06028)
		(end 54.2925 -213.06028)
		(width 0.14478)
		(layer "In11.Cu")
		(net "M_F_CPU1_SA_DQ<12>")
	)
	(segment
		(start 23.000208 -212.266784)
		(end 23.163276 -212.429852)
		(width 0.14478)
		(layer "In11.Cu")
		(net "M_F_CPU1_SA_DQ<12>")
	)
	(segment
		(start 28.585922 -212.428836)
		(end 28.585922 -212.373464)
		(width 0.14478)
		(layer "In11.Cu")
		(net "M_F_CPU1_SA_DQ<12>")
	)
	(segment
		(start 34.383218 -213.06028)
		(end 35.233102 -212.210396)
		(width 0.14478)
		(layer "In11.Cu")
		(net "M_F_CPU1_SA_DQ<12>")
	)
	(segment
		(start 35.906964 -212.596984)
		(end 36.137342 -212.596984)
		(width 0.14478)
		(layer "In11.Cu")
		(net "M_F_CPU1_SA_DQ<12>")
	)
	(segment
		(start 43.618658 -212.604604)
		(end 43.781726 -212.441536)
		(width 0.14478)
		(layer "In11.Cu")
		(net "M_F_CPU1_SA_DQ<12>")
	)
	(segment
		(start 67.457066 -222.917004)
		(end 75.422506 -230.882444)
		(width 0.14478)
		(layer "In11.Cu")
		(net "M_F_CPU1_SA_DQ<12>")
	)
	(segment
		(start 41.308782 -213.223348)
		(end 41.47185 -213.06028)
		(width 0.14478)
		(layer "In11.Cu")
		(net "M_F_CPU1_SA_DQ<12>")
	)
	(segment
		(start 22.443694 -213.06028)
		(end 22.606762 -212.897212)
		(width 0.14478)
		(layer "In11.Cu")
		(net "M_F_CPU1_SA_DQ<12>")
	)
	(segment
		(start 23.163276 -212.429852)
		(end 23.163276 -212.897212)
		(width 0.14478)
		(layer "In11.Cu")
		(net "M_F_CPU1_SA_DQ<12>")
	)
	(segment
		(start 23.163276 -212.897212)
		(end 23.326344 -213.06028)
		(width 0.14478)
		(layer "In11.Cu")
		(net "M_F_CPU1_SA_DQ<12>")
	)
	(segment
		(start 23.866602 -213.223348)
		(end 23.866602 -213.287356)
		(width 0.14478)
		(layer "In11.Cu")
		(net "M_F_CPU1_SA_DQ<12>")
	)
	(segment
		(start 76.508102 -231.43464)
		(end 76.972922 -231.43464)
		(width 0.0889)
		(layer "In11.Cu")
		(net "M_F_CPU1_SA_DQ<12>")
	)
	(segment
		(start 35.743896 -212.373464)
		(end 35.743896 -212.433916)
		(width 0.14478)
		(layer "In11.Cu")
		(net "M_F_CPU1_SA_DQ<12>")
	)
	(segment
		(start 58.990484 -212.210396)
		(end 59.220862 -212.210396)
		(width 0.14478)
		(layer "In11.Cu")
		(net "M_F_CPU1_SA_DQ<12>")
	)
	(segment
		(start 58.827416 -212.441536)
		(end 58.827416 -212.373464)
		(width 0.14478)
		(layer "In11.Cu")
		(net "M_F_CPU1_SA_DQ<12>")
	)
	(segment
		(start 81.879694 -233.47172)
		(end 81.888076 -233.466894)
		(width 0.0889)
		(layer "In11.Cu")
		(net "M_F_CPU1_SA_DQ<12>")
	)
	(segment
		(start 53.12156 -212.220048)
		(end 53.961792 -213.06028)
		(width 0.14478)
		(layer "In11.Cu")
		(net "M_F_CPU1_SA_DQ<12>")
	)
	(segment
		(start 49.175416 -213.06028)
		(end 49.448974 -213.06028)
		(width 0.14478)
		(layer "In11.Cu")
		(net "M_F_CPU1_SA_DQ<12>")
	)
	(segment
		(start 55.17515 -212.764624)
		(end 55.405528 -212.764624)
		(width 0.14478)
		(layer "In11.Cu")
		(net "M_F_CPU1_SA_DQ<12>")
	)
	(segment
		(start 43.225212 -212.441536)
		(end 43.38828 -212.604604)
		(width 0.14478)
		(layer "In11.Cu")
		(net "M_F_CPU1_SA_DQ<12>")
	)
	(segment
		(start 54.618636 -213.450424)
		(end 54.849014 -213.450424)
		(width 0.14478)
		(layer "In11.Cu")
		(net "M_F_CPU1_SA_DQ<12>")
	)
	(segment
		(start 59.220862 -212.210396)
		(end 59.38393 -212.373464)
		(width 0.14478)
		(layer "In11.Cu")
		(net "M_F_CPU1_SA_DQ<12>")
	)
	(segment
		(start 59.38393 -212.441536)
		(end 59.546998 -212.604604)
		(width 0.14478)
		(layer "In11.Cu")
		(net "M_F_CPU1_SA_DQ<12>")
	)
	(segment
		(start 55.962042 -213.450424)
		(end 56.12511 -213.287356)
		(width 0.14478)
		(layer "In11.Cu")
		(net "M_F_CPU1_SA_DQ<12>")
	)
	(segment
		(start 55.568596 -212.927692)
		(end 55.568596 -213.287356)
		(width 0.14478)
		(layer "In11.Cu")
		(net "M_F_CPU1_SA_DQ<12>")
	)
	(segment
		(start 40.598852 -213.069932)
		(end 40.752268 -213.223348)
		(width 0.14478)
		(layer "In11.Cu")
		(net "M_F_CPU1_SA_DQ<12>")
	)
	(segment
		(start 45.577506 -212.220048)
		(end 46.42739 -213.069932)
		(width 0.14478)
		(layer "In11.Cu")
		(net "M_F_CPU1_SA_DQ<12>")
	)
	(segment
		(start 50.724816 -212.373464)
		(end 50.724816 -212.438996)
		(width 0.14478)
		(layer "In11.Cu")
		(net "M_F_CPU1_SA_DQ<12>")
	)
	(segment
		(start 22.133052 -213.06028)
		(end 22.443694 -213.06028)
		(width 0.14478)
		(layer "In11.Cu")
		(net "M_F_CPU1_SA_DQ<12>")
	)
	(segment
		(start 83.394042 -233.466894)
		(end 83.402424 -233.47172)
		(width 0.0889)
		(layer "In11.Cu")
		(net "M_F_CPU1_SA_DQ<12>")
	)
	(segment
		(start 40.915336 -213.450424)
		(end 41.145714 -213.450424)
		(width 0.14478)
		(layer "In11.Cu")
		(net "M_F_CPU1_SA_DQ<12>")
	)
	(segment
		(start 75.422506 -230.882444)
		(end 75.628246 -230.882444)
		(width 0.14478)
		(layer "In11.Cu")
		(net "M_F_CPU1_SA_DQ<12>")
	)
	(segment
		(start 25.944576 -213.223348)
		(end 25.944576 -213.282276)
		(width 0.14478)
		(layer "In11.Cu")
		(net "M_F_CPU1_SA_DQ<12>")
	)
	(segment
		(start 23.703534 -213.06028)
		(end 23.866602 -213.223348)
		(width 0.14478)
		(layer "In11.Cu")
		(net "M_F_CPU1_SA_DQ<12>")
	)
	(segment
		(start 49.012348 -213.223348)
		(end 49.175416 -213.06028)
		(width 0.14478)
		(layer "In11.Cu")
		(net "M_F_CPU1_SA_DQ<12>")
	)
	(segment
		(start 48.84928 -213.450424)
		(end 49.012348 -213.287356)
		(width 0.14478)
		(layer "In11.Cu")
		(net "M_F_CPU1_SA_DQ<12>")
	)
	(segment
		(start 23.326344 -213.06028)
		(end 23.703534 -213.06028)
		(width 0.14478)
		(layer "In11.Cu")
		(net "M_F_CPU1_SA_DQ<12>")
	)
	(segment
		(start 22.606762 -212.897212)
		(end 22.606762 -212.429852)
		(width 0.14478)
		(layer "In11.Cu")
		(net "M_F_CPU1_SA_DQ<12>")
	)
	(segment
		(start 43.38828 -212.604604)
		(end 43.618658 -212.604604)
		(width 0.14478)
		(layer "In11.Cu")
		(net "M_F_CPU1_SA_DQ<12>")
	)
	(segment
		(start 59.546998 -212.604604)
		(end 59.821826 -212.604604)
		(width 0.14478)
		(layer "In11.Cu")
		(net "M_F_CPU1_SA_DQ<12>")
	)
	(segment
		(start 41.94302 -213.06028)
		(end 42.792904 -212.210396)
		(width 0.14478)
		(layer "In11.Cu")
		(net "M_F_CPU1_SA_DQ<12>")
	)
	(segment
		(start 43.935142 -212.220048)
		(end 45.577506 -212.220048)
		(width 0.14478)
		(layer "In11.Cu")
		(net "M_F_CPU1_SA_DQ<12>")
	)
	(segment
		(start 27.664664 -212.210396)
		(end 27.86634 -212.210396)
		(width 0.14478)
		(layer "In11.Cu")
		(net "M_F_CPU1_SA_DQ<12>")
	)
	(segment
		(start 76.972922 -231.43464)
		(end 77.168502 -231.63022)
		(width 0.0889)
		(layer "In11.Cu")
		(net "M_F_CPU1_SA_DQ<12>")
	)
	(segment
		(start 62.28207 -216.364312)
		(end 67.457066 -221.539308)
		(width 0.14478)
		(layer "In11.Cu")
		(net "M_F_CPU1_SA_DQ<12>")
	)
	(segment
		(start 43.781726 -212.441536)
		(end 43.781726 -212.373464)
		(width 0.14478)
		(layer "In11.Cu")
		(net "M_F_CPU1_SA_DQ<12>")
	)
	(segment
		(start 23.866602 -213.287356)
		(end 24.02967 -213.450424)
		(width 0.14478)
		(layer "In11.Cu")
		(net "M_F_CPU1_SA_DQ<12>")
	)
	(segment
		(start 40.752268 -213.223348)
		(end 40.752268 -213.287356)
		(width 0.14478)
		(layer "In11.Cu")
		(net "M_F_CPU1_SA_DQ<12>")
	)
	(segment
		(start 36.453826 -212.220048)
		(end 37.962332 -212.220048)
		(width 0.14478)
		(layer "In11.Cu")
		(net "M_F_CPU1_SA_DQ<12>")
	)
	(segment
		(start 67.457066 -221.539308)
		(end 67.457066 -222.917004)
		(width 0.14478)
		(layer "In11.Cu")
		(net "M_F_CPU1_SA_DQ<12>")
	)
	(segment
		(start 50.298858 -212.210396)
		(end 50.561748 -212.210396)
		(width 0.14478)
		(layer "In11.Cu")
		(net "M_F_CPU1_SA_DQ<12>")
	)
	(segment
		(start 36.137342 -212.596984)
		(end 36.30041 -212.433916)
		(width 0.14478)
		(layer "In11.Cu")
		(net "M_F_CPU1_SA_DQ<12>")
	)
	(segment
		(start 58.270902 -212.373464)
		(end 58.270902 -212.441536)
		(width 0.14478)
		(layer "In11.Cu")
		(net "M_F_CPU1_SA_DQ<12>")
	)
	(segment
		(start 24.02967 -213.450424)
		(end 24.260048 -213.450424)
		(width 0.14478)
		(layer "In11.Cu")
		(net "M_F_CPU1_SA_DQ<12>")
	)
	(segment
		(start 58.664348 -212.604604)
		(end 58.827416 -212.441536)
		(width 0.14478)
		(layer "In11.Cu")
		(net "M_F_CPU1_SA_DQ<12>")
	)
	(segment
		(start 26.338022 -213.445344)
		(end 26.50109 -213.282276)
		(width 0.14478)
		(layer "In11.Cu")
		(net "M_F_CPU1_SA_DQ<12>")
	)
	(segment
		(start 54.455568 -213.287356)
		(end 54.618636 -213.450424)
		(width 0.14478)
		(layer "In11.Cu")
		(net "M_F_CPU1_SA_DQ<12>")
	)
	(segment
		(start 38.812216 -213.069932)
		(end 40.598852 -213.069932)
		(width 0.14478)
		(layer "In11.Cu")
		(net "M_F_CPU1_SA_DQ<12>")
	)
	(segment
		(start 54.849014 -213.450424)
		(end 55.012082 -213.287356)
		(width 0.14478)
		(layer "In11.Cu")
		(net "M_F_CPU1_SA_DQ<12>")
	)
	(segment
		(start 21.70811 -212.635338)
		(end 22.133052 -213.06028)
		(width 0.14478)
		(layer "In11.Cu")
		(net "M_F_CPU1_SA_DQ<12>")
	)
	(segment
		(start 26.81478 -213.06028)
		(end 27.664664 -212.210396)
		(width 0.14478)
		(layer "In11.Cu")
		(net "M_F_CPU1_SA_DQ<12>")
	)
	(segment
		(start 48.302418 -213.069932)
		(end 48.455834 -213.223348)
		(width 0.14478)
		(layer "In11.Cu")
		(net "M_F_CPU1_SA_DQ<12>")
	)
	(segment
		(start 75.628246 -230.882444)
		(end 75.955906 -230.882444)
		(width 0.0889)
		(layer "In11.Cu")
		(net "M_F_CPU1_SA_DQ<12>")
	)
	(segment
		(start 27.86634 -212.210396)
		(end 28.029408 -212.373464)
		(width 0.14478)
		(layer "In11.Cu")
		(net "M_F_CPU1_SA_DQ<12>")
	)
	(segment
		(start 24.576532 -213.069932)
		(end 25.79116 -213.069932)
		(width 0.14478)
		(layer "In11.Cu")
		(net "M_F_CPU1_SA_DQ<12>")
	)
	(segment
		(start 26.664158 -213.06028)
		(end 26.81478 -213.06028)
		(width 0.14478)
		(layer "In11.Cu")
		(net "M_F_CPU1_SA_DQ<12>")
	)
	(segment
		(start 25.79116 -213.069932)
		(end 25.944576 -213.223348)
		(width 0.14478)
		(layer "In11.Cu")
		(net "M_F_CPU1_SA_DQ<12>")
	)
	(segment
		(start 43.062144 -212.210396)
		(end 43.225212 -212.373464)
		(width 0.14478)
		(layer "In11.Cu")
		(net "M_F_CPU1_SA_DQ<12>")
	)
	(segment
		(start 24.260048 -213.450424)
		(end 24.423116 -213.287356)
		(width 0.14478)
		(layer "In11.Cu")
		(net "M_F_CPU1_SA_DQ<12>")
	)
	(segment
		(start 48.455834 -213.287356)
		(end 48.618902 -213.450424)
		(width 0.14478)
		(layer "In11.Cu")
		(net "M_F_CPU1_SA_DQ<12>")
	)
	(segment
		(start 42.792904 -212.210396)
		(end 43.062144 -212.210396)
		(width 0.14478)
		(layer "In11.Cu")
		(net "M_F_CPU1_SA_DQ<12>")
	)
	(segment
		(start 40.752268 -213.287356)
		(end 40.915336 -213.450424)
		(width 0.14478)
		(layer "In11.Cu")
		(net "M_F_CPU1_SA_DQ<12>")
	)
	(segment
		(start 26.50109 -213.282276)
		(end 26.50109 -213.223348)
		(width 0.14478)
		(layer "In11.Cu")
		(net "M_F_CPU1_SA_DQ<12>")
	)
	(segment
		(start 33.461706 -213.282276)
		(end 33.624774 -213.445344)
		(width 0.14478)
		(layer "In11.Cu")
		(net "M_F_CPU1_SA_DQ<12>")
	)
	(segment
		(start 58.270902 -212.441536)
		(end 58.43397 -212.604604)
		(width 0.14478)
		(layer "In11.Cu")
		(net "M_F_CPU1_SA_DQ<12>")
	)
	(segment
		(start 41.145714 -213.450424)
		(end 41.308782 -213.287356)
		(width 0.14478)
		(layer "In11.Cu")
		(net "M_F_CPU1_SA_DQ<12>")
	)
	(segment
		(start 36.30041 -212.433916)
		(end 36.30041 -212.373464)
		(width 0.14478)
		(layer "In11.Cu")
		(net "M_F_CPU1_SA_DQ<12>")
	)
	(segment
		(start 26.107644 -213.445344)
		(end 26.338022 -213.445344)
		(width 0.14478)
		(layer "In11.Cu")
		(net "M_F_CPU1_SA_DQ<12>")
	)
	(segment
		(start 55.568596 -213.287356)
		(end 55.731664 -213.450424)
		(width 0.14478)
		(layer "In11.Cu")
		(net "M_F_CPU1_SA_DQ<12>")
	)
	(segment
		(start 51.434746 -212.220048)
		(end 53.12156 -212.220048)
		(width 0.14478)
		(layer "In11.Cu")
		(net "M_F_CPU1_SA_DQ<12>")
	)
	(segment
		(start 43.781726 -212.373464)
		(end 43.935142 -212.220048)
		(width 0.14478)
		(layer "In11.Cu")
		(net "M_F_CPU1_SA_DQ<12>")
	)
	(segment
		(start 59.821826 -212.604604)
		(end 62.28207 -215.064848)
		(width 0.14478)
		(layer "In11.Cu")
		(net "M_F_CPU1_SA_DQ<12>")
	)
	(segment
		(start 55.012082 -212.927692)
		(end 55.17515 -212.764624)
		(width 0.14478)
		(layer "In11.Cu")
		(net "M_F_CPU1_SA_DQ<12>")
	)
	(segment
		(start 26.50109 -213.223348)
		(end 26.664158 -213.06028)
		(width 0.14478)
		(layer "In11.Cu")
		(net "M_F_CPU1_SA_DQ<12>")
	)
	(segment
		(start 79.0575 -233.473752)
		(end 79.069184 -233.466894)
		(width 0.0889)
		(layer "In11.Cu")
		(net "M_F_CPU1_SA_DQ<12>")
	)
	(segment
		(start 41.47185 -213.06028)
		(end 41.94302 -213.06028)
		(width 0.14478)
		(layer "In11.Cu")
		(net "M_F_CPU1_SA_DQ<12>")
	)
	(segment
		(start 49.012348 -213.287356)
		(end 49.012348 -213.223348)
		(width 0.14478)
		(layer "In11.Cu")
		(net "M_F_CPU1_SA_DQ<12>")
	)
	(segment
		(start 59.38393 -212.373464)
		(end 59.38393 -212.441536)
		(width 0.14478)
		(layer "In11.Cu")
		(net "M_F_CPU1_SA_DQ<12>")
	)
	(segment
		(start 50.724816 -212.438996)
		(end 50.887884 -212.602064)
		(width 0.14478)
		(layer "In11.Cu")
		(net "M_F_CPU1_SA_DQ<12>")
	)
	(segment
		(start 84.271104 -233.435144)
		(end 84.367116 -233.409744)
		(width 0.0889)
		(layer "In11.Cu")
		(net "M_F_CPU1_SA_DQ<12>")
	)
	(segment
		(start 36.30041 -212.373464)
		(end 36.453826 -212.220048)
		(width 0.14478)
		(layer "In11.Cu")
		(net "M_F_CPU1_SA_DQ<12>")
	)
	(segment
		(start 35.743896 -212.433916)
		(end 35.906964 -212.596984)
		(width 0.14478)
		(layer "In11.Cu")
		(net "M_F_CPU1_SA_DQ<12>")
	)
	(segment
		(start 24.423116 -213.223348)
		(end 24.576532 -213.069932)
		(width 0.14478)
		(layer "In11.Cu")
		(net "M_F_CPU1_SA_DQ<12>")
	)
	(segment
		(start 51.28133 -212.373464)
		(end 51.434746 -212.220048)
		(width 0.14478)
		(layer "In11.Cu")
		(net "M_F_CPU1_SA_DQ<12>")
	)
	(segment
		(start 37.962332 -212.220048)
		(end 38.812216 -213.069932)
		(width 0.14478)
		(layer "In11.Cu")
		(net "M_F_CPU1_SA_DQ<12>")
	)
	(segment
		(start 55.405528 -212.764624)
		(end 55.568596 -212.927692)
		(width 0.14478)
		(layer "In11.Cu")
		(net "M_F_CPU1_SA_DQ<12>")
	)
	(segment
		(start 49.448974 -213.06028)
		(end 50.298858 -212.210396)
		(width 0.14478)
		(layer "In11.Cu")
		(net "M_F_CPU1_SA_DQ<12>")
	)
	(segment
		(start 58.107834 -212.210396)
		(end 58.270902 -212.373464)
		(width 0.14478)
		(layer "In11.Cu")
		(net "M_F_CPU1_SA_DQ<12>")
	)
	(segment
		(start 51.118262 -212.602064)
		(end 51.28133 -212.438996)
		(width 0.14478)
		(layer "In11.Cu")
		(net "M_F_CPU1_SA_DQ<12>")
	)
	(segment
		(start 84.367116 -233.409744)
		(end 84.52104 -233.144314)
		(width 0.0889)
		(layer "In11.Cu")
		(net "M_F_CPU1_SA_DQ<12>")
	)
	(segment
		(start 48.618902 -213.450424)
		(end 48.84928 -213.450424)
		(width 0.14478)
		(layer "In11.Cu")
		(net "M_F_CPU1_SA_DQ<12>")
	)
	(segment
		(start 77.168502 -232.28808)
		(end 78.270862 -233.39044)
		(width 0.0889)
		(layer "In11.Cu")
		(net "M_F_CPU1_SA_DQ<12>")
	)
	(segment
		(start 82.453988 -233.466894)
		(end 82.46237 -233.47172)
		(width 0.0889)
		(layer "In11.Cu")
		(net "M_F_CPU1_SA_DQ<12>")
	)
	(segment
		(start 56.12511 -213.287356)
		(end 56.12511 -213.223348)
		(width 0.14478)
		(layer "In11.Cu")
		(net "M_F_CPU1_SA_DQ<12>")
	)
	(segment
		(start 33.855152 -213.445344)
		(end 34.01822 -213.282276)
		(width 0.14478)
		(layer "In11.Cu")
		(net "M_F_CPU1_SA_DQ<12>")
	)
	(segment
		(start 34.181288 -213.06028)
		(end 34.383218 -213.06028)
		(width 0.14478)
		(layer "In11.Cu")
		(net "M_F_CPU1_SA_DQ<12>")
	)
	(segment
		(start 56.12511 -213.223348)
		(end 56.288178 -213.06028)
		(width 0.14478)
		(layer "In11.Cu")
		(net "M_F_CPU1_SA_DQ<12>")
	)
	(segment
		(start 77.168502 -231.63022)
		(end 77.168502 -232.28808)
		(width 0.0889)
		(layer "In11.Cu")
		(net "M_F_CPU1_SA_DQ<12>")
	)
	(segment
		(start 28.585922 -212.373464)
		(end 28.739338 -212.220048)
		(width 0.14478)
		(layer "In11.Cu")
		(net "M_F_CPU1_SA_DQ<12>")
	)
	(segment
		(start 33.461706 -213.223348)
		(end 33.461706 -213.282276)
		(width 0.14478)
		(layer "In11.Cu")
		(net "M_F_CPU1_SA_DQ<12>")
	)
	(segment
		(start 57.804558 -212.210396)
		(end 58.107834 -212.210396)
		(width 0.14478)
		(layer "In11.Cu")
		(net "M_F_CPU1_SA_DQ<12>")
	)
	(segment
		(start 43.225212 -212.373464)
		(end 43.225212 -212.441536)
		(width 0.14478)
		(layer "In11.Cu")
		(net "M_F_CPU1_SA_DQ<12>")
	)
	(segment
		(start 55.731664 -213.450424)
		(end 55.962042 -213.450424)
		(width 0.14478)
		(layer "In11.Cu")
		(net "M_F_CPU1_SA_DQ<12>")
	)
	(segment
		(start 28.029408 -212.428836)
		(end 28.192476 -212.591904)
		(width 0.14478)
		(layer "In11.Cu")
		(net "M_F_CPU1_SA_DQ<12>")
	)
	(segment
		(start 41.308782 -213.287356)
		(end 41.308782 -213.223348)
		(width 0.14478)
		(layer "In11.Cu")
		(net "M_F_CPU1_SA_DQ<12>")
	)
	(segment
		(start 56.288178 -213.06028)
		(end 56.954674 -213.06028)
		(width 0.14478)
		(layer "In11.Cu")
		(net "M_F_CPU1_SA_DQ<12>")
	)
	(segment
		(start 54.2925 -213.06028)
		(end 54.455568 -213.223348)
		(width 0.14478)
		(layer "In11.Cu")
		(net "M_F_CPU1_SA_DQ<12>")
	)
	(segment
		(start 33.30829 -213.069932)
		(end 33.461706 -213.223348)
		(width 0.14478)
		(layer "In11.Cu")
		(net "M_F_CPU1_SA_DQ<12>")
	)
	(segment
		(start 28.192476 -212.591904)
		(end 28.422854 -212.591904)
		(width 0.14478)
		(layer "In11.Cu")
		(net "M_F_CPU1_SA_DQ<12>")
	)
	(segment
		(start 62.28207 -215.064848)
		(end 62.28207 -216.364312)
		(width 0.14478)
		(layer "In11.Cu")
		(net "M_F_CPU1_SA_DQ<12>")
	)
	(segment
		(start 24.423116 -213.287356)
		(end 24.423116 -213.223348)
		(width 0.14478)
		(layer "In11.Cu")
		(net "M_F_CPU1_SA_DQ<12>")
	)
	(segment
		(start 22.76983 -212.266784)
		(end 23.000208 -212.266784)
		(width 0.14478)
		(layer "In11.Cu")
		(net "M_F_CPU1_SA_DQ<12>")
	)
	(segment
		(start 46.42739 -213.069932)
		(end 48.302418 -213.069932)
		(width 0.14478)
		(layer "In11.Cu")
		(net "M_F_CPU1_SA_DQ<12>")
	)
	(segment
		(start 35.233102 -212.210396)
		(end 35.580828 -212.210396)
		(width 0.14478)
		(layer "In11.Cu")
		(net "M_F_CPU1_SA_DQ<12>")
	)
	(segment
		(start 75.955906 -230.882444)
		(end 76.508102 -231.43464)
		(width 0.0889)
		(layer "In11.Cu")
		(net "M_F_CPU1_SA_DQ<12>")
	)
	(segment
		(start 79.634334 -233.46664)
		(end 79.65059 -233.476038)
		(width 0.0889)
		(layer "In11.Cu")
		(net "M_F_CPU1_SA_DQ<12>")
	)
	(segment
		(start 48.455834 -213.223348)
		(end 48.455834 -213.287356)
		(width 0.14478)
		(layer "In11.Cu")
		(net "M_F_CPU1_SA_DQ<12>")
	)
	(segment
		(start 33.624774 -213.445344)
		(end 33.855152 -213.445344)
		(width 0.14478)
		(layer "In11.Cu")
		(net "M_F_CPU1_SA_DQ<12>")
	)
	(segment
		(start 31.330392 -213.069932)
		(end 33.30829 -213.069932)
		(width 0.14478)
		(layer "In11.Cu")
		(net "M_F_CPU1_SA_DQ<12>")
	)
	(segment
		(start 56.954674 -213.06028)
		(end 57.804558 -212.210396)
		(width 0.14478)
		(layer "In11.Cu")
		(net "M_F_CPU1_SA_DQ<12>")
	)
	(segment
		(start 58.43397 -212.604604)
		(end 58.664348 -212.604604)
		(width 0.14478)
		(layer "In11.Cu")
		(net "M_F_CPU1_SA_DQ<12>")
	)
	(segment
		(start 34.01822 -213.223348)
		(end 34.181288 -213.06028)
		(width 0.14478)
		(layer "In11.Cu")
		(net "M_F_CPU1_SA_DQ<12>")
	)
	(segment
		(start 54.455568 -213.223348)
		(end 54.455568 -213.287356)
		(width 0.14478)
		(layer "In11.Cu")
		(net "M_F_CPU1_SA_DQ<12>")
	)
	(segment
		(start 35.580828 -212.210396)
		(end 35.743896 -212.373464)
		(width 0.14478)
		(layer "In11.Cu")
		(net "M_F_CPU1_SA_DQ<12>")
	)
	(segment
		(start 78.270862 -233.39044)
		(end 78.41107 -233.39044)
		(width 0.0889)
		(layer "In11.Cu")
		(net "M_F_CPU1_SA_DQ<12>")
	)
	(segment
		(start 22.606762 -212.429852)
		(end 22.76983 -212.266784)
		(width 0.14478)
		(layer "In11.Cu")
		(net "M_F_CPU1_SA_DQ<12>")
	)
	(segment
		(start 25.944576 -213.282276)
		(end 26.107644 -213.445344)
		(width 0.14478)
		(layer "In11.Cu")
		(net "M_F_CPU1_SA_DQ<12>")
	)
	(segment
		(start 50.561748 -212.210396)
		(end 50.724816 -212.373464)
		(width 0.14478)
		(layer "In11.Cu")
		(net "M_F_CPU1_SA_DQ<12>")
	)
	(arc
		(start 82.82813 -233.466894)
		(mid 83.111086 -233.390717)
		(end 83.394042 -233.466894)
		(width 0.0889)
		(layer "In11.Cu")
		(net "M_F_CPU1_SA_DQ<12>")
	)
	(arc
		(start 83.768184 -233.466894)
		(mid 84.015897 -233.391674)
		(end 84.271104 -233.435144)
		(width 0.0889)
		(layer "In11.Cu")
		(net "M_F_CPU1_SA_DQ<12>")
	)
	(arc
		(start 81.888076 -233.466894)
		(mid 82.171032 -233.390717)
		(end 82.453988 -233.466894)
		(width 0.0889)
		(layer "In11.Cu")
		(net "M_F_CPU1_SA_DQ<12>")
	)
	(arc
		(start 82.46237 -233.47172)
		(mid 82.645878 -233.517214)
		(end 82.82813 -233.466894)
		(width 0.0889)
		(layer "In11.Cu")
		(net "M_F_CPU1_SA_DQ<12>")
	)
	(arc
		(start 81.513934 -233.466894)
		(mid 81.696185 -233.517244)
		(end 81.879694 -233.47172)
		(width 0.0889)
		(layer "In11.Cu")
		(net "M_F_CPU1_SA_DQ<12>")
	)
	(arc
		(start 79.069184 -233.466894)
		(mid 79.344862 -233.390764)
		(end 79.622396 -233.459782)
		(width 0.0889)
		(layer "In11.Cu")
		(net "M_F_CPU1_SA_DQ<12>")
	)
	(arc
		(start 80.574134 -233.466894)
		(mid 80.761078 -233.517149)
		(end 80.948022 -233.466894)
		(width 0.0889)
		(layer "In11.Cu")
		(net "M_F_CPU1_SA_DQ<12>")
	)
	(arc
		(start 80.948022 -233.466894)
		(mid 81.230978 -233.390717)
		(end 81.513934 -233.466894)
		(width 0.0889)
		(layer "In11.Cu")
		(net "M_F_CPU1_SA_DQ<12>")
	)
	(arc
		(start 79.65059 -233.476038)
		(mid 79.830572 -233.517138)
		(end 80.008222 -233.466894)
		(width 0.0889)
		(layer "In11.Cu")
		(net "M_F_CPU1_SA_DQ<12>")
	)
	(arc
		(start 78.694788 -233.466894)
		(mid 78.875246 -233.517338)
		(end 79.0575 -233.473752)
		(width 0.0889)
		(layer "In11.Cu")
		(net "M_F_CPU1_SA_DQ<12>")
	)
	(arc
		(start 83.402424 -233.47172)
		(mid 83.585932 -233.517214)
		(end 83.768184 -233.466894)
		(width 0.0889)
		(layer "In11.Cu")
		(net "M_F_CPU1_SA_DQ<12>")
	)
	(arc
		(start 78.41107 -233.39044)
		(mid 78.558001 -233.409851)
		(end 78.694788 -233.466894)
		(width 0.0889)
		(layer "In11.Cu")
		(net "M_F_CPU1_SA_DQ<12>")
	)
	(arc
		(start 80.008222 -233.466894)
		(mid 80.291178 -233.390717)
		(end 80.574134 -233.466894)
		(width 0.0889)
		(layer "In11.Cu")
		(net "M_F_CPU1_SA_DQ<12>")
	)
	(segment
		(start 85.927946 -231.79024)
		(end 85.461094 -231.524302)
		(width 0.10668)
		(layer "F.Cu")
		(net "M_F_CPU1_SA_DQ<11>")
	)
	(segment
		(start 79.58709 -231.146604)
		(end 79.654908 -231.156256)
		(width 0.0889)
		(layer "In11.Cu")
		(net "M_F_CPU1_SA_DQ<11>")
	)
	(segment
		(start 42.751756 -208.8007)
		(end 45.609002 -208.8007)
		(width 0.14478)
		(layer "In11.Cu")
		(net "M_F_CPU1_SA_DQ<11>")
	)
	(segment
		(start 50.249582 -208.8007)
		(end 53.145436 -208.8007)
		(width 0.14478)
		(layer "In11.Cu")
		(net "M_F_CPU1_SA_DQ<11>")
	)
	(segment
		(start 19.65325 -209.497422)
		(end 19.806412 -209.650584)
		(width 0.14478)
		(layer "In11.Cu")
		(net "M_F_CPU1_SA_DQ<11>")
	)
	(segment
		(start 27.587448 -208.8007)
		(end 30.534102 -208.8007)
		(width 0.14478)
		(layer "In11.Cu")
		(net "M_F_CPU1_SA_DQ<11>")
	)
	(segment
		(start 76.801726 -229.388924)
		(end 77.172566 -229.388924)
		(width 0.0889)
		(layer "In11.Cu")
		(net "M_F_CPU1_SA_DQ<11>")
	)
	(segment
		(start 53.145436 -208.8007)
		(end 54.005226 -209.66049)
		(width 0.14478)
		(layer "In11.Cu")
		(net "M_F_CPU1_SA_DQ<11>")
	)
	(segment
		(start 81.879694 -231.19715)
		(end 81.888076 -231.201976)
		(width 0.0889)
		(layer "In11.Cu")
		(net "M_F_CPU1_SA_DQ<11>")
	)
	(segment
		(start 38.103556 -208.8007)
		(end 38.95344 -209.650584)
		(width 0.14478)
		(layer "In11.Cu")
		(net "M_F_CPU1_SA_DQ<11>")
	)
	(segment
		(start 45.609002 -208.8007)
		(end 46.458886 -209.650584)
		(width 0.14478)
		(layer "In11.Cu")
		(net "M_F_CPU1_SA_DQ<11>")
	)
	(segment
		(start 19.096736 -209.497422)
		(end 19.096736 -209.044032)
		(width 0.14478)
		(layer "In11.Cu")
		(net "M_F_CPU1_SA_DQ<11>")
	)
	(segment
		(start 38.95344 -209.650584)
		(end 41.901872 -209.650584)
		(width 0.14478)
		(layer "In11.Cu")
		(net "M_F_CPU1_SA_DQ<11>")
	)
	(segment
		(start 82.453988 -231.201976)
		(end 82.46237 -231.19715)
		(width 0.0889)
		(layer "In11.Cu")
		(net "M_F_CPU1_SA_DQ<11>")
	)
	(segment
		(start 59.42203 -208.810352)
		(end 69.796406 -219.184728)
		(width 0.14478)
		(layer "In11.Cu")
		(net "M_F_CPU1_SA_DQ<11>")
	)
	(segment
		(start 26.737564 -209.650584)
		(end 27.587448 -208.8007)
		(width 0.14478)
		(layer "In11.Cu")
		(net "M_F_CPU1_SA_DQ<11>")
	)
	(segment
		(start 57.78627 -208.810352)
		(end 59.42203 -208.810352)
		(width 0.14478)
		(layer "In11.Cu")
		(net "M_F_CPU1_SA_DQ<11>")
	)
	(segment
		(start 76.239116 -228.826314)
		(end 76.801726 -229.388924)
		(width 0.0889)
		(layer "In11.Cu")
		(net "M_F_CPU1_SA_DQ<11>")
	)
	(segment
		(start 56.936132 -209.66049)
		(end 57.78627 -208.810352)
		(width 0.14478)
		(layer "In11.Cu")
		(net "M_F_CPU1_SA_DQ<11>")
	)
	(segment
		(start 78.057248 -230.273606)
		(end 78.57109 -230.273606)
		(width 0.0889)
		(layer "In11.Cu")
		(net "M_F_CPU1_SA_DQ<11>")
	)
	(segment
		(start 76.006706 -228.144324)
		(end 76.239116 -228.376734)
		(width 0.0889)
		(layer "In11.Cu")
		(net "M_F_CPU1_SA_DQ<11>")
	)
	(segment
		(start 19.806412 -209.650584)
		(end 26.737564 -209.650584)
		(width 0.14478)
		(layer "In11.Cu")
		(net "M_F_CPU1_SA_DQ<11>")
	)
	(segment
		(start 85.592666 -231.175814)
		(end 85.615018 -231.258872)
		(width 0.0889)
		(layer "In11.Cu")
		(net "M_F_CPU1_SA_DQ<11>")
	)
	(segment
		(start 19.259804 -208.880964)
		(end 19.490182 -208.880964)
		(width 0.14478)
		(layer "In11.Cu")
		(net "M_F_CPU1_SA_DQ<11>")
	)
	(segment
		(start 85.615018 -231.258872)
		(end 85.461094 -231.524302)
		(width 0.0889)
		(layer "In11.Cu")
		(net "M_F_CPU1_SA_DQ<11>")
	)
	(segment
		(start 69.796406 -219.184728)
		(end 69.796406 -221.934024)
		(width 0.14478)
		(layer "In11.Cu")
		(net "M_F_CPU1_SA_DQ<11>")
	)
	(segment
		(start 69.796406 -221.934024)
		(end 76.006706 -228.144324)
		(width 0.14478)
		(layer "In11.Cu")
		(net "M_F_CPU1_SA_DQ<11>")
	)
	(segment
		(start 46.458886 -209.650584)
		(end 49.399698 -209.650584)
		(width 0.14478)
		(layer "In11.Cu")
		(net "M_F_CPU1_SA_DQ<11>")
	)
	(segment
		(start 83.394042 -231.201976)
		(end 83.402424 -231.19715)
		(width 0.0889)
		(layer "In11.Cu")
		(net "M_F_CPU1_SA_DQ<11>")
	)
	(segment
		(start 35.21837 -208.8007)
		(end 38.103556 -208.8007)
		(width 0.14478)
		(layer "In11.Cu")
		(net "M_F_CPU1_SA_DQ<11>")
	)
	(segment
		(start 19.096736 -209.044032)
		(end 19.259804 -208.880964)
		(width 0.14478)
		(layer "In11.Cu")
		(net "M_F_CPU1_SA_DQ<11>")
	)
	(segment
		(start 17.608042 -209.235294)
		(end 18.033238 -209.66049)
		(width 0.14478)
		(layer "In11.Cu")
		(net "M_F_CPU1_SA_DQ<11>")
	)
	(segment
		(start 41.901872 -209.650584)
		(end 42.751756 -208.8007)
		(width 0.14478)
		(layer "In11.Cu")
		(net "M_F_CPU1_SA_DQ<11>")
	)
	(segment
		(start 49.399698 -209.650584)
		(end 50.249582 -208.8007)
		(width 0.14478)
		(layer "In11.Cu")
		(net "M_F_CPU1_SA_DQ<11>")
	)
	(segment
		(start 18.933668 -209.66049)
		(end 19.096736 -209.497422)
		(width 0.14478)
		(layer "In11.Cu")
		(net "M_F_CPU1_SA_DQ<11>")
	)
	(segment
		(start 34.368486 -209.650584)
		(end 35.21837 -208.8007)
		(width 0.14478)
		(layer "In11.Cu")
		(net "M_F_CPU1_SA_DQ<11>")
	)
	(segment
		(start 19.490182 -208.880964)
		(end 19.65325 -209.044032)
		(width 0.14478)
		(layer "In11.Cu")
		(net "M_F_CPU1_SA_DQ<11>")
	)
	(segment
		(start 31.383986 -209.650584)
		(end 34.368486 -209.650584)
		(width 0.14478)
		(layer "In11.Cu")
		(net "M_F_CPU1_SA_DQ<11>")
	)
	(segment
		(start 19.65325 -209.044032)
		(end 19.65325 -209.497422)
		(width 0.14478)
		(layer "In11.Cu")
		(net "M_F_CPU1_SA_DQ<11>")
	)
	(segment
		(start 30.534102 -208.8007)
		(end 31.383986 -209.650584)
		(width 0.14478)
		(layer "In11.Cu")
		(net "M_F_CPU1_SA_DQ<11>")
	)
	(segment
		(start 54.005226 -209.66049)
		(end 56.936132 -209.66049)
		(width 0.14478)
		(layer "In11.Cu")
		(net "M_F_CPU1_SA_DQ<11>")
	)
	(segment
		(start 78.57109 -230.273606)
		(end 79.30134 -231.003856)
		(width 0.0889)
		(layer "In11.Cu")
		(net "M_F_CPU1_SA_DQ<11>")
	)
	(segment
		(start 76.239116 -228.376734)
		(end 76.239116 -228.826314)
		(width 0.0889)
		(layer "In11.Cu")
		(net "M_F_CPU1_SA_DQ<11>")
	)
	(segment
		(start 77.172566 -229.388924)
		(end 78.057248 -230.273606)
		(width 0.0889)
		(layer "In11.Cu")
		(net "M_F_CPU1_SA_DQ<11>")
	)
	(segment
		(start 18.033238 -209.66049)
		(end 18.933668 -209.66049)
		(width 0.14478)
		(layer "In11.Cu")
		(net "M_F_CPU1_SA_DQ<11>")
	)
	(arc
		(start 79.30134 -231.003856)
		(mid 79.432618 -231.098451)
		(end 79.58709 -231.146604)
		(width 0.0889)
		(layer "In11.Cu")
		(net "M_F_CPU1_SA_DQ<11>")
	)
	(arc
		(start 83.402424 -231.19715)
		(mid 83.585932 -231.151625)
		(end 83.768184 -231.201976)
		(width 0.0889)
		(layer "In11.Cu")
		(net "M_F_CPU1_SA_DQ<11>")
	)
	(arc
		(start 84.334096 -231.201976)
		(mid 84.52104 -231.151687)
		(end 84.707984 -231.201976)
		(width 0.0889)
		(layer "In11.Cu")
		(net "M_F_CPU1_SA_DQ<11>")
	)
	(arc
		(start 80.574134 -231.201976)
		(mid 80.761078 -231.151687)
		(end 80.948022 -231.201976)
		(width 0.0889)
		(layer "In11.Cu")
		(net "M_F_CPU1_SA_DQ<11>")
	)
	(arc
		(start 82.46237 -231.19715)
		(mid 82.645878 -231.151625)
		(end 82.82813 -231.201976)
		(width 0.0889)
		(layer "In11.Cu")
		(net "M_F_CPU1_SA_DQ<11>")
	)
	(arc
		(start 82.82813 -231.201976)
		(mid 83.111086 -231.278153)
		(end 83.394042 -231.201976)
		(width 0.0889)
		(layer "In11.Cu")
		(net "M_F_CPU1_SA_DQ<11>")
	)
	(arc
		(start 85.273896 -231.201976)
		(mid 85.430334 -231.152971)
		(end 85.592666 -231.175814)
		(width 0.0889)
		(layer "In11.Cu")
		(net "M_F_CPU1_SA_DQ<11>")
	)
	(arc
		(start 79.764382 -231.155748)
		(mid 79.890256 -231.157992)
		(end 80.008222 -231.201976)
		(width 0.0889)
		(layer "In11.Cu")
		(net "M_F_CPU1_SA_DQ<11>")
	)
	(arc
		(start 80.948022 -231.201976)
		(mid 81.230978 -231.278153)
		(end 81.513934 -231.201976)
		(width 0.0889)
		(layer "In11.Cu")
		(net "M_F_CPU1_SA_DQ<11>")
	)
	(arc
		(start 84.707984 -231.201976)
		(mid 84.99094 -231.278153)
		(end 85.273896 -231.201976)
		(width 0.0889)
		(layer "In11.Cu")
		(net "M_F_CPU1_SA_DQ<11>")
	)
	(arc
		(start 80.008222 -231.201976)
		(mid 80.291178 -231.278153)
		(end 80.574134 -231.201976)
		(width 0.0889)
		(layer "In11.Cu")
		(net "M_F_CPU1_SA_DQ<11>")
	)
	(arc
		(start 81.888076 -231.201976)
		(mid 82.171032 -231.278153)
		(end 82.453988 -231.201976)
		(width 0.0889)
		(layer "In11.Cu")
		(net "M_F_CPU1_SA_DQ<11>")
	)
	(arc
		(start 83.768184 -231.201976)
		(mid 84.05114 -231.278153)
		(end 84.334096 -231.201976)
		(width 0.0889)
		(layer "In11.Cu")
		(net "M_F_CPU1_SA_DQ<11>")
	)
	(arc
		(start 81.513934 -231.201976)
		(mid 81.696185 -231.151592)
		(end 81.879694 -231.19715)
		(width 0.0889)
		(layer "In11.Cu")
		(net "M_F_CPU1_SA_DQ<11>")
	)
	(arc
		(start 79.654908 -231.156256)
		(mid 79.709664 -231.160053)
		(end 79.764382 -231.155748)
		(width 0.0889)
		(layer "In11.Cu")
		(net "M_F_CPU1_SA_DQ<11>")
	)
	(segment
		(start 84.517992 -230.980234)
		(end 84.05114 -230.71455)
		(width 0.10668)
		(layer "F.Cu")
		(net "M_F_CPU1_SA_DQ<10>")
	)
	(segment
		(start 75.960224 -226.797362)
		(end 76.179426 -227.016564)
		(width 0.0889)
		(layer "In11.Cu")
		(net "M_F_CPU1_SA_DQ<10>")
	)
	(segment
		(start 27.577796 -207.11033)
		(end 30.543754 -207.11033)
		(width 0.14478)
		(layer "In11.Cu")
		(net "M_F_CPU1_SA_DQ<10>")
	)
	(segment
		(start 57.78627 -207.11033)
		(end 59.70143 -207.11033)
		(width 0.14478)
		(layer "In11.Cu")
		(net "M_F_CPU1_SA_DQ<10>")
	)
	(segment
		(start 83.289648 -230.387144)
		(end 83.29803 -230.39197)
		(width 0.0889)
		(layer "In11.Cu")
		(net "M_F_CPU1_SA_DQ<10>")
	)
	(segment
		(start 19.740118 -207.7974)
		(end 19.740118 -207.395572)
		(width 0.14478)
		(layer "In11.Cu")
		(net "M_F_CPU1_SA_DQ<10>")
	)
	(segment
		(start 34.35858 -207.960468)
		(end 35.208718 -207.11033)
		(width 0.14478)
		(layer "In11.Cu")
		(net "M_F_CPU1_SA_DQ<10>")
	)
	(segment
		(start 77.400912 -228.934518)
		(end 78.274926 -229.808532)
		(width 0.0889)
		(layer "In11.Cu")
		(net "M_F_CPU1_SA_DQ<10>")
	)
	(segment
		(start 54.005226 -207.960468)
		(end 56.936132 -207.960468)
		(width 0.14478)
		(layer "In11.Cu")
		(net "M_F_CPU1_SA_DQ<10>")
	)
	(segment
		(start 19.903186 -207.232504)
		(end 20.133564 -207.232504)
		(width 0.14478)
		(layer "In11.Cu")
		(net "M_F_CPU1_SA_DQ<10>")
	)
	(segment
		(start 70.705726 -221.557088)
		(end 75.946 -226.797362)
		(width 0.14478)
		(layer "In11.Cu")
		(net "M_F_CPU1_SA_DQ<10>")
	)
	(segment
		(start 18.033238 -207.960468)
		(end 19.57705 -207.960468)
		(width 0.14478)
		(layer "In11.Cu")
		(net "M_F_CPU1_SA_DQ<10>")
	)
	(segment
		(start 17.608042 -207.535272)
		(end 18.033238 -207.960468)
		(width 0.14478)
		(layer "In11.Cu")
		(net "M_F_CPU1_SA_DQ<10>")
	)
	(segment
		(start 19.57705 -207.960468)
		(end 19.740118 -207.7974)
		(width 0.14478)
		(layer "In11.Cu")
		(net "M_F_CPU1_SA_DQ<10>")
	)
	(segment
		(start 76.179426 -227.016564)
		(end 76.179426 -227.105464)
		(width 0.0889)
		(layer "In11.Cu")
		(net "M_F_CPU1_SA_DQ<10>")
	)
	(segment
		(start 59.99353 -208.095596)
		(end 70.705726 -218.807792)
		(width 0.14478)
		(layer "In11.Cu")
		(net "M_F_CPU1_SA_DQ<10>")
	)
	(segment
		(start 56.936132 -207.960468)
		(end 57.78627 -207.11033)
		(width 0.14478)
		(layer "In11.Cu")
		(net "M_F_CPU1_SA_DQ<10>")
	)
	(segment
		(start 78.928214 -229.808532)
		(end 79.422498 -230.302816)
		(width 0.0889)
		(layer "In11.Cu")
		(net "M_F_CPU1_SA_DQ<10>")
	)
	(segment
		(start 30.543754 -207.11033)
		(end 31.393892 -207.960468)
		(width 0.14478)
		(layer "In11.Cu")
		(net "M_F_CPU1_SA_DQ<10>")
	)
	(segment
		(start 76.98994 -228.934518)
		(end 77.400912 -228.934518)
		(width 0.0889)
		(layer "In11.Cu")
		(net "M_F_CPU1_SA_DQ<10>")
	)
	(segment
		(start 59.99353 -207.40243)
		(end 59.99353 -208.095596)
		(width 0.14478)
		(layer "In11.Cu")
		(net "M_F_CPU1_SA_DQ<10>")
	)
	(segment
		(start 84.182712 -230.365808)
		(end 84.205064 -230.44912)
		(width 0.0889)
		(layer "In11.Cu")
		(net "M_F_CPU1_SA_DQ<10>")
	)
	(segment
		(start 41.891966 -207.960468)
		(end 42.742104 -207.11033)
		(width 0.14478)
		(layer "In11.Cu")
		(net "M_F_CPU1_SA_DQ<10>")
	)
	(segment
		(start 19.740118 -207.395572)
		(end 19.903186 -207.232504)
		(width 0.14478)
		(layer "In11.Cu")
		(net "M_F_CPU1_SA_DQ<10>")
	)
	(segment
		(start 75.946 -226.797362)
		(end 75.960224 -226.797362)
		(width 0.0889)
		(layer "In11.Cu")
		(net "M_F_CPU1_SA_DQ<10>")
	)
	(segment
		(start 76.645516 -227.571554)
		(end 76.645516 -228.590094)
		(width 0.0889)
		(layer "In11.Cu")
		(net "M_F_CPU1_SA_DQ<10>")
	)
	(segment
		(start 76.179426 -227.105464)
		(end 76.645516 -227.571554)
		(width 0.0889)
		(layer "In11.Cu")
		(net "M_F_CPU1_SA_DQ<10>")
	)
	(segment
		(start 81.044034 -230.39197)
		(end 81.052416 -230.387144)
		(width 0.0889)
		(layer "In11.Cu")
		(net "M_F_CPU1_SA_DQ<10>")
	)
	(segment
		(start 49.389792 -207.960468)
		(end 50.23993 -207.11033)
		(width 0.14478)
		(layer "In11.Cu")
		(net "M_F_CPU1_SA_DQ<10>")
	)
	(segment
		(start 80.46974 -230.387144)
		(end 80.478122 -230.39197)
		(width 0.0889)
		(layer "In11.Cu")
		(net "M_F_CPU1_SA_DQ<10>")
	)
	(segment
		(start 35.208718 -207.11033)
		(end 38.113208 -207.11033)
		(width 0.14478)
		(layer "In11.Cu")
		(net "M_F_CPU1_SA_DQ<10>")
	)
	(segment
		(start 45.618654 -207.11033)
		(end 46.468792 -207.960468)
		(width 0.14478)
		(layer "In11.Cu")
		(net "M_F_CPU1_SA_DQ<10>")
	)
	(segment
		(start 84.205064 -230.44912)
		(end 84.05114 -230.71455)
		(width 0.0889)
		(layer "In11.Cu")
		(net "M_F_CPU1_SA_DQ<10>")
	)
	(segment
		(start 31.393892 -207.960468)
		(end 34.35858 -207.960468)
		(width 0.14478)
		(layer "In11.Cu")
		(net "M_F_CPU1_SA_DQ<10>")
	)
	(segment
		(start 59.70143 -207.11033)
		(end 59.99353 -207.40243)
		(width 0.14478)
		(layer "In11.Cu")
		(net "M_F_CPU1_SA_DQ<10>")
	)
	(segment
		(start 20.296632 -207.395572)
		(end 20.296632 -207.7974)
		(width 0.14478)
		(layer "In11.Cu")
		(net "M_F_CPU1_SA_DQ<10>")
	)
	(segment
		(start 79.53883 -230.39197)
		(end 79.556864 -230.402384)
		(width 0.0889)
		(layer "In11.Cu")
		(net "M_F_CPU1_SA_DQ<10>")
	)
	(segment
		(start 26.727658 -207.960468)
		(end 27.577796 -207.11033)
		(width 0.14478)
		(layer "In11.Cu")
		(net "M_F_CPU1_SA_DQ<10>")
	)
	(segment
		(start 53.155088 -207.11033)
		(end 54.005226 -207.960468)
		(width 0.14478)
		(layer "In11.Cu")
		(net "M_F_CPU1_SA_DQ<10>")
	)
	(segment
		(start 78.274926 -229.808532)
		(end 78.928214 -229.808532)
		(width 0.0889)
		(layer "In11.Cu")
		(net "M_F_CPU1_SA_DQ<10>")
	)
	(segment
		(start 70.705726 -218.807792)
		(end 70.705726 -221.557088)
		(width 0.14478)
		(layer "In11.Cu")
		(net "M_F_CPU1_SA_DQ<10>")
	)
	(segment
		(start 50.23993 -207.11033)
		(end 53.155088 -207.11033)
		(width 0.14478)
		(layer "In11.Cu")
		(net "M_F_CPU1_SA_DQ<10>")
	)
	(segment
		(start 38.963346 -207.960468)
		(end 41.891966 -207.960468)
		(width 0.14478)
		(layer "In11.Cu")
		(net "M_F_CPU1_SA_DQ<10>")
	)
	(segment
		(start 46.468792 -207.960468)
		(end 49.389792 -207.960468)
		(width 0.14478)
		(layer "In11.Cu")
		(net "M_F_CPU1_SA_DQ<10>")
	)
	(segment
		(start 38.113208 -207.11033)
		(end 38.963346 -207.960468)
		(width 0.14478)
		(layer "In11.Cu")
		(net "M_F_CPU1_SA_DQ<10>")
	)
	(segment
		(start 76.645516 -228.590094)
		(end 76.98994 -228.934518)
		(width 0.0889)
		(layer "In11.Cu")
		(net "M_F_CPU1_SA_DQ<10>")
	)
	(segment
		(start 20.133564 -207.232504)
		(end 20.296632 -207.395572)
		(width 0.14478)
		(layer "In11.Cu")
		(net "M_F_CPU1_SA_DQ<10>")
	)
	(segment
		(start 42.742104 -207.11033)
		(end 45.618654 -207.11033)
		(width 0.14478)
		(layer "In11.Cu")
		(net "M_F_CPU1_SA_DQ<10>")
	)
	(segment
		(start 20.4597 -207.960468)
		(end 26.727658 -207.960468)
		(width 0.14478)
		(layer "In11.Cu")
		(net "M_F_CPU1_SA_DQ<10>")
	)
	(segment
		(start 20.296632 -207.7974)
		(end 20.4597 -207.960468)
		(width 0.14478)
		(layer "In11.Cu")
		(net "M_F_CPU1_SA_DQ<10>")
	)
	(arc
		(start 79.422498 -230.302816)
		(mid 79.477748 -230.351198)
		(end 79.53883 -230.39197)
		(width 0.0889)
		(layer "In11.Cu")
		(net "M_F_CPU1_SA_DQ<10>")
	)
	(arc
		(start 83.863942 -230.39197)
		(mid 84.02038 -230.342999)
		(end 84.182712 -230.365808)
		(width 0.0889)
		(layer "In11.Cu")
		(net "M_F_CPU1_SA_DQ<10>")
	)
	(arc
		(start 81.418176 -230.39197)
		(mid 81.701132 -230.468113)
		(end 81.984088 -230.39197)
		(width 0.0889)
		(layer "In11.Cu")
		(net "M_F_CPU1_SA_DQ<10>")
	)
	(arc
		(start 83.29803 -230.39197)
		(mid 83.580986 -230.468113)
		(end 83.863942 -230.39197)
		(width 0.0889)
		(layer "In11.Cu")
		(net "M_F_CPU1_SA_DQ<10>")
	)
	(arc
		(start 80.10398 -230.39197)
		(mid 80.286231 -230.34162)
		(end 80.46974 -230.387144)
		(width 0.0889)
		(layer "In11.Cu")
		(net "M_F_CPU1_SA_DQ<10>")
	)
	(arc
		(start 82.357976 -230.39197)
		(mid 82.640932 -230.468113)
		(end 82.923888 -230.39197)
		(width 0.0889)
		(layer "In11.Cu")
		(net "M_F_CPU1_SA_DQ<10>")
	)
	(arc
		(start 81.052416 -230.387144)
		(mid 81.235924 -230.34165)
		(end 81.418176 -230.39197)
		(width 0.0889)
		(layer "In11.Cu")
		(net "M_F_CPU1_SA_DQ<10>")
	)
	(arc
		(start 80.478122 -230.39197)
		(mid 80.761078 -230.468113)
		(end 81.044034 -230.39197)
		(width 0.0889)
		(layer "In11.Cu")
		(net "M_F_CPU1_SA_DQ<10>")
	)
	(arc
		(start 82.923888 -230.39197)
		(mid 83.106139 -230.34162)
		(end 83.289648 -230.387144)
		(width 0.0889)
		(layer "In11.Cu")
		(net "M_F_CPU1_SA_DQ<10>")
	)
	(arc
		(start 79.556864 -230.402384)
		(mid 79.831768 -230.467994)
		(end 80.10398 -230.39197)
		(width 0.0889)
		(layer "In11.Cu")
		(net "M_F_CPU1_SA_DQ<10>")
	)
	(arc
		(start 81.984088 -230.39197)
		(mid 82.171032 -230.341715)
		(end 82.357976 -230.39197)
		(width 0.0889)
		(layer "In11.Cu")
		(net "M_F_CPU1_SA_DQ<10>")
	)
	(segment
		(start 84.987892 -225.310446)
		(end 84.52104 -225.044508)
		(width 0.10668)
		(layer "F.Cu")
		(net "M_F_CPU1_SA_DQ<0>")
	)
	(segment
		(start 84.367116 -225.309938)
		(end 84.52104 -225.044508)
		(width 0.0889)
		(layer "In11.Cu")
		(net "M_F_CPU1_SA_DQ<0>")
	)
	(segment
		(start 25.926288 -196.950584)
		(end 26.156666 -196.950584)
		(width 0.14478)
		(layer "In11.Cu")
		(net "M_F_CPU1_SA_DQ<0>")
	)
	(segment
		(start 80.574134 -223.747076)
		(end 80.610456 -223.768158)
		(width 0.0889)
		(layer "In11.Cu")
		(net "M_F_CPU1_SA_DQ<0>")
	)
	(segment
		(start 56.954674 -197.760336)
		(end 57.804558 -196.910452)
		(width 0.14478)
		(layer "In11.Cu")
		(net "M_F_CPU1_SA_DQ<0>")
	)
	(segment
		(start 80.542384 -225.3488)
		(end 80.574134 -225.367088)
		(width 0.0889)
		(layer "In11.Cu")
		(net "M_F_CPU1_SA_DQ<0>")
	)
	(segment
		(start 84.271104 -225.335338)
		(end 84.367116 -225.309938)
		(width 0.0889)
		(layer "In11.Cu")
		(net "M_F_CPU1_SA_DQ<0>")
	)
	(segment
		(start 21.70811 -197.335394)
		(end 22.133052 -197.760336)
		(width 0.14478)
		(layer "In11.Cu")
		(net "M_F_CPU1_SA_DQ<0>")
	)
	(segment
		(start 26.319734 -197.597268)
		(end 26.482802 -197.760336)
		(width 0.14478)
		(layer "In11.Cu")
		(net "M_F_CPU1_SA_DQ<0>")
	)
	(segment
		(start 79.562706 -221.446344)
		(end 79.44612 -221.56293)
		(width 0.0889)
		(layer "In11.Cu")
		(net "M_F_CPU1_SA_DQ<0>")
	)
	(segment
		(start 23.86965 -197.760336)
		(end 24.032718 -197.597268)
		(width 0.14478)
		(layer "In11.Cu")
		(net "M_F_CPU1_SA_DQ<0>")
	)
	(segment
		(start 24.589232 -196.897752)
		(end 24.589232 -197.597268)
		(width 0.14478)
		(layer "In11.Cu")
		(net "M_F_CPU1_SA_DQ<0>")
	)
	(segment
		(start 23.476204 -197.597268)
		(end 23.639272 -197.760336)
		(width 0.14478)
		(layer "In11.Cu")
		(net "M_F_CPU1_SA_DQ<0>")
	)
	(segment
		(start 24.589232 -197.597268)
		(end 24.7523 -197.760336)
		(width 0.14478)
		(layer "In11.Cu")
		(net "M_F_CPU1_SA_DQ<0>")
	)
	(segment
		(start 23.476204 -196.897752)
		(end 23.476204 -197.597268)
		(width 0.14478)
		(layer "In11.Cu")
		(net "M_F_CPU1_SA_DQ<0>")
	)
	(segment
		(start 23.082758 -196.734684)
		(end 23.313136 -196.734684)
		(width 0.14478)
		(layer "In11.Cu")
		(net "M_F_CPU1_SA_DQ<0>")
	)
	(segment
		(start 31.32074 -197.760336)
		(end 34.383218 -197.760336)
		(width 0.14478)
		(layer "In11.Cu")
		(net "M_F_CPU1_SA_DQ<0>")
	)
	(segment
		(start 46.417738 -197.760336)
		(end 49.448974 -197.760336)
		(width 0.14478)
		(layer "In11.Cu")
		(net "M_F_CPU1_SA_DQ<0>")
	)
	(segment
		(start 82.453988 -225.367088)
		(end 82.46237 -225.371914)
		(width 0.0889)
		(layer "In11.Cu")
		(net "M_F_CPU1_SA_DQ<0>")
	)
	(segment
		(start 80.542384 -223.728788)
		(end 80.574134 -223.747076)
		(width 0.0889)
		(layer "In11.Cu")
		(net "M_F_CPU1_SA_DQ<0>")
	)
	(segment
		(start 24.426164 -196.734684)
		(end 24.589232 -196.897752)
		(width 0.14478)
		(layer "In11.Cu")
		(net "M_F_CPU1_SA_DQ<0>")
	)
	(segment
		(start 79.562706 -221.232984)
		(end 79.562706 -221.446344)
		(width 0.0889)
		(layer "In11.Cu")
		(net "M_F_CPU1_SA_DQ<0>")
	)
	(segment
		(start 77.045566 -214.105744)
		(end 77.045566 -218.426284)
		(width 0.14478)
		(layer "In11.Cu")
		(net "M_F_CPU1_SA_DQ<0>")
	)
	(segment
		(start 26.482802 -197.760336)
		(end 26.81478 -197.760336)
		(width 0.14478)
		(layer "In11.Cu")
		(net "M_F_CPU1_SA_DQ<0>")
	)
	(segment
		(start 50.298858 -196.910452)
		(end 53.111908 -196.910452)
		(width 0.14478)
		(layer "In11.Cu")
		(net "M_F_CPU1_SA_DQ<0>")
	)
	(segment
		(start 45.567854 -196.910452)
		(end 46.417738 -197.760336)
		(width 0.14478)
		(layer "In11.Cu")
		(net "M_F_CPU1_SA_DQ<0>")
	)
	(segment
		(start 26.319734 -197.113652)
		(end 26.319734 -197.597268)
		(width 0.14478)
		(layer "In11.Cu")
		(net "M_F_CPU1_SA_DQ<0>")
	)
	(segment
		(start 26.81478 -197.760336)
		(end 27.664664 -196.910452)
		(width 0.14478)
		(layer "In11.Cu")
		(net "M_F_CPU1_SA_DQ<0>")
	)
	(segment
		(start 25.76322 -197.113652)
		(end 25.926288 -196.950584)
		(width 0.14478)
		(layer "In11.Cu")
		(net "M_F_CPU1_SA_DQ<0>")
	)
	(segment
		(start 79.44612 -221.56293)
		(end 79.44612 -221.80423)
		(width 0.0889)
		(layer "In11.Cu")
		(net "M_F_CPU1_SA_DQ<0>")
	)
	(segment
		(start 24.7523 -197.760336)
		(end 25.600152 -197.760336)
		(width 0.14478)
		(layer "In11.Cu")
		(net "M_F_CPU1_SA_DQ<0>")
	)
	(segment
		(start 80.610456 -224.700846)
		(end 80.574134 -224.721928)
		(width 0.0889)
		(layer "In11.Cu")
		(net "M_F_CPU1_SA_DQ<0>")
	)
	(segment
		(start 26.156666 -196.950584)
		(end 26.319734 -197.113652)
		(width 0.14478)
		(layer "In11.Cu")
		(net "M_F_CPU1_SA_DQ<0>")
	)
	(segment
		(start 81.879694 -225.371914)
		(end 81.888076 -225.367088)
		(width 0.0889)
		(layer "In11.Cu")
		(net "M_F_CPU1_SA_DQ<0>")
	)
	(segment
		(start 77.045566 -218.426284)
		(end 79.562706 -220.943424)
		(width 0.14478)
		(layer "In11.Cu")
		(net "M_F_CPU1_SA_DQ<0>")
	)
	(segment
		(start 38.802564 -197.760336)
		(end 41.94302 -197.760336)
		(width 0.14478)
		(layer "In11.Cu")
		(net "M_F_CPU1_SA_DQ<0>")
	)
	(segment
		(start 22.91969 -196.897752)
		(end 23.082758 -196.734684)
		(width 0.14478)
		(layer "In11.Cu")
		(net "M_F_CPU1_SA_DQ<0>")
	)
	(segment
		(start 80.104234 -222.93707)
		(end 80.140556 -222.958152)
		(width 0.0889)
		(layer "In11.Cu")
		(net "M_F_CPU1_SA_DQ<0>")
	)
	(segment
		(start 25.76322 -197.597268)
		(end 25.76322 -197.113652)
		(width 0.14478)
		(layer "In11.Cu")
		(net "M_F_CPU1_SA_DQ<0>")
	)
	(segment
		(start 24.032718 -197.597268)
		(end 24.032718 -196.897752)
		(width 0.14478)
		(layer "In11.Cu")
		(net "M_F_CPU1_SA_DQ<0>")
	)
	(segment
		(start 80.072484 -222.918782)
		(end 80.104234 -222.93707)
		(width 0.0889)
		(layer "In11.Cu")
		(net "M_F_CPU1_SA_DQ<0>")
	)
	(segment
		(start 34.383218 -197.760336)
		(end 35.233102 -196.910452)
		(width 0.14478)
		(layer "In11.Cu")
		(net "M_F_CPU1_SA_DQ<0>")
	)
	(segment
		(start 25.600152 -197.760336)
		(end 25.76322 -197.597268)
		(width 0.14478)
		(layer "In11.Cu")
		(net "M_F_CPU1_SA_DQ<0>")
	)
	(segment
		(start 57.804558 -196.910452)
		(end 59.850274 -196.910452)
		(width 0.14478)
		(layer "In11.Cu")
		(net "M_F_CPU1_SA_DQ<0>")
	)
	(segment
		(start 22.756622 -197.760336)
		(end 22.91969 -197.597268)
		(width 0.14478)
		(layer "In11.Cu")
		(net "M_F_CPU1_SA_DQ<0>")
	)
	(segment
		(start 42.792904 -196.910452)
		(end 45.567854 -196.910452)
		(width 0.14478)
		(layer "In11.Cu")
		(net "M_F_CPU1_SA_DQ<0>")
	)
	(segment
		(start 79.562706 -220.943424)
		(end 79.562706 -221.232984)
		(width 0.14478)
		(layer "In11.Cu")
		(net "M_F_CPU1_SA_DQ<0>")
	)
	(segment
		(start 24.032718 -196.897752)
		(end 24.195786 -196.734684)
		(width 0.14478)
		(layer "In11.Cu")
		(net "M_F_CPU1_SA_DQ<0>")
	)
	(segment
		(start 23.639272 -197.760336)
		(end 23.86965 -197.760336)
		(width 0.14478)
		(layer "In11.Cu")
		(net "M_F_CPU1_SA_DQ<0>")
	)
	(segment
		(start 37.95268 -196.910452)
		(end 38.802564 -197.760336)
		(width 0.14478)
		(layer "In11.Cu")
		(net "M_F_CPU1_SA_DQ<0>")
	)
	(segment
		(start 22.133052 -197.760336)
		(end 22.756622 -197.760336)
		(width 0.14478)
		(layer "In11.Cu")
		(net "M_F_CPU1_SA_DQ<0>")
	)
	(segment
		(start 53.111908 -196.910452)
		(end 53.961792 -197.760336)
		(width 0.14478)
		(layer "In11.Cu")
		(net "M_F_CPU1_SA_DQ<0>")
	)
	(segment
		(start 80.574134 -224.721928)
		(end 80.542384 -224.740216)
		(width 0.0889)
		(layer "In11.Cu")
		(net "M_F_CPU1_SA_DQ<0>")
	)
	(segment
		(start 30.470856 -196.910452)
		(end 31.32074 -197.760336)
		(width 0.14478)
		(layer "In11.Cu")
		(net "M_F_CPU1_SA_DQ<0>")
	)
	(segment
		(start 83.394042 -225.367088)
		(end 83.402424 -225.371914)
		(width 0.0889)
		(layer "In11.Cu")
		(net "M_F_CPU1_SA_DQ<0>")
	)
	(segment
		(start 41.94302 -197.760336)
		(end 42.792904 -196.910452)
		(width 0.14478)
		(layer "In11.Cu")
		(net "M_F_CPU1_SA_DQ<0>")
	)
	(segment
		(start 79.60233 -222.108776)
		(end 79.671926 -222.148908)
		(width 0.0889)
		(layer "In11.Cu")
		(net "M_F_CPU1_SA_DQ<0>")
	)
	(segment
		(start 49.448974 -197.760336)
		(end 50.298858 -196.910452)
		(width 0.14478)
		(layer "In11.Cu")
		(net "M_F_CPU1_SA_DQ<0>")
	)
	(segment
		(start 24.195786 -196.734684)
		(end 24.426164 -196.734684)
		(width 0.14478)
		(layer "In11.Cu")
		(net "M_F_CPU1_SA_DQ<0>")
	)
	(segment
		(start 22.91969 -197.597268)
		(end 22.91969 -196.897752)
		(width 0.14478)
		(layer "In11.Cu")
		(net "M_F_CPU1_SA_DQ<0>")
	)
	(segment
		(start 53.961792 -197.760336)
		(end 56.954674 -197.760336)
		(width 0.14478)
		(layer "In11.Cu")
		(net "M_F_CPU1_SA_DQ<0>")
	)
	(segment
		(start 27.664664 -196.910452)
		(end 30.470856 -196.910452)
		(width 0.14478)
		(layer "In11.Cu")
		(net "M_F_CPU1_SA_DQ<0>")
	)
	(segment
		(start 23.313136 -196.734684)
		(end 23.476204 -196.897752)
		(width 0.14478)
		(layer "In11.Cu")
		(net "M_F_CPU1_SA_DQ<0>")
	)
	(segment
		(start 35.233102 -196.910452)
		(end 37.95268 -196.910452)
		(width 0.14478)
		(layer "In11.Cu")
		(net "M_F_CPU1_SA_DQ<0>")
	)
	(segment
		(start 59.850274 -196.910452)
		(end 77.045566 -214.105744)
		(width 0.14478)
		(layer "In11.Cu")
		(net "M_F_CPU1_SA_DQ<0>")
	)
	(arc
		(start 81.888076 -225.367088)
		(mid 82.171032 -225.290911)
		(end 82.453988 -225.367088)
		(width 0.0889)
		(layer "In11.Cu")
		(net "M_F_CPU1_SA_DQ<0>")
	)
	(arc
		(start 80.542384 -224.740216)
		(mid 80.386456 -225.044508)
		(end 80.542384 -225.3488)
		(width 0.0889)
		(layer "In11.Cu")
		(net "M_F_CPU1_SA_DQ<0>")
	)
	(arc
		(start 80.574134 -225.367088)
		(mid 80.761078 -225.417343)
		(end 80.948022 -225.367088)
		(width 0.0889)
		(layer "In11.Cu")
		(net "M_F_CPU1_SA_DQ<0>")
	)
	(arc
		(start 80.386428 -223.424496)
		(mid 80.427683 -223.595467)
		(end 80.542384 -223.728788)
		(width 0.0889)
		(layer "In11.Cu")
		(net "M_F_CPU1_SA_DQ<0>")
	)
	(arc
		(start 81.513934 -225.367088)
		(mid 81.696185 -225.417438)
		(end 81.879694 -225.371914)
		(width 0.0889)
		(layer "In11.Cu")
		(net "M_F_CPU1_SA_DQ<0>")
	)
	(arc
		(start 79.581502 -222.09252)
		(mid 79.591772 -222.100832)
		(end 79.60233 -222.108776)
		(width 0.0889)
		(layer "In11.Cu")
		(net "M_F_CPU1_SA_DQ<0>")
	)
	(arc
		(start 82.82813 -225.367088)
		(mid 83.111086 -225.290911)
		(end 83.394042 -225.367088)
		(width 0.0889)
		(layer "In11.Cu")
		(net "M_F_CPU1_SA_DQ<0>")
	)
	(arc
		(start 80.948022 -225.367088)
		(mid 81.230978 -225.290911)
		(end 81.513934 -225.367088)
		(width 0.0889)
		(layer "In11.Cu")
		(net "M_F_CPU1_SA_DQ<0>")
	)
	(arc
		(start 79.916528 -222.61449)
		(mid 79.957783 -222.785461)
		(end 80.072484 -222.918782)
		(width 0.0889)
		(layer "In11.Cu")
		(net "M_F_CPU1_SA_DQ<0>")
	)
	(arc
		(start 83.402424 -225.371914)
		(mid 83.585932 -225.417408)
		(end 83.768184 -225.367088)
		(width 0.0889)
		(layer "In11.Cu")
		(net "M_F_CPU1_SA_DQ<0>")
	)
	(arc
		(start 82.46237 -225.371914)
		(mid 82.645878 -225.417408)
		(end 82.82813 -225.367088)
		(width 0.0889)
		(layer "In11.Cu")
		(net "M_F_CPU1_SA_DQ<0>")
	)
	(arc
		(start 80.610456 -223.768158)
		(mid 80.856346 -224.234502)
		(end 80.610456 -224.700846)
		(width 0.0889)
		(layer "In11.Cu")
		(net "M_F_CPU1_SA_DQ<0>")
	)
	(arc
		(start 83.768184 -225.367088)
		(mid 84.015897 -225.291868)
		(end 84.271104 -225.335338)
		(width 0.0889)
		(layer "In11.Cu")
		(net "M_F_CPU1_SA_DQ<0>")
	)
	(arc
		(start 79.44612 -221.80423)
		(mid 79.48165 -221.963478)
		(end 79.581502 -222.09252)
		(width 0.0889)
		(layer "In11.Cu")
		(net "M_F_CPU1_SA_DQ<0>")
	)
	(arc
		(start 80.140556 -222.958152)
		(mid 80.321208 -223.160897)
		(end 80.386428 -223.424496)
		(width 0.0889)
		(layer "In11.Cu")
		(net "M_F_CPU1_SA_DQ<0>")
	)
	(arc
		(start 79.671926 -222.148908)
		(mid 79.851655 -222.351528)
		(end 79.916528 -222.61449)
		(width 0.0889)
		(layer "In11.Cu")
		(net "M_F_CPU1_SA_DQ<0>")
	)
	(segment
		(start 85.927946 -252.850396)
		(end 85.461094 -252.584458)
		(width 0.10668)
		(layer "F.Cu")
		(net "M_F_CPU1_SA_CS_N<1>")
	)
	(segment
		(start 77.157326 -252.462284)
		(end 77.352144 -252.267466)
		(width 0.0889)
		(layer "In11.Cu")
		(net "M_F_CPU1_SA_CS_N<1>")
	)
	(segment
		(start 59.387486 -248.760234)
		(end 62.144656 -251.517404)
		(width 0.14478)
		(layer "In11.Cu")
		(net "M_F_CPU1_SA_CS_N<1>")
	)
	(segment
		(start 79.06766 -252.261878)
		(end 79.078074 -252.267974)
		(width 0.0889)
		(layer "In11.Cu")
		(net "M_F_CPU1_SA_CS_N<1>")
	)
	(segment
		(start 85.615018 -252.319028)
		(end 85.461094 -252.584458)
		(width 0.0889)
		(layer "In11.Cu")
		(net "M_F_CPU1_SA_CS_N<1>")
	)
	(segment
		(start 22.069044 -247.060212)
		(end 23.769066 -248.760234)
		(width 0.14478)
		(layer "In11.Cu")
		(net "M_F_CPU1_SA_CS_N<1>")
	)
	(segment
		(start 78.67904 -252.270514)
		(end 78.693772 -252.261878)
		(width 0.0889)
		(layer "In11.Cu")
		(net "M_F_CPU1_SA_CS_N<1>")
	)
	(segment
		(start 75.976226 -252.833124)
		(end 76.278486 -252.833124)
		(width 0.0889)
		(layer "In11.Cu")
		(net "M_F_CPU1_SA_CS_N<1>")
	)
	(segment
		(start 83.394042 -252.261878)
		(end 83.402424 -252.257052)
		(width 0.0889)
		(layer "In11.Cu")
		(net "M_F_CPU1_SA_CS_N<1>")
	)
	(segment
		(start 76.649326 -252.462284)
		(end 77.157326 -252.462284)
		(width 0.0889)
		(layer "In11.Cu")
		(net "M_F_CPU1_SA_CS_N<1>")
	)
	(segment
		(start 17.608042 -246.63527)
		(end 18.032984 -247.060212)
		(width 0.14478)
		(layer "In11.Cu")
		(net "M_F_CPU1_SA_CS_N<1>")
	)
	(segment
		(start 81.879694 -252.257052)
		(end 81.888076 -252.261878)
		(width 0.0889)
		(layer "In11.Cu")
		(net "M_F_CPU1_SA_CS_N<1>")
	)
	(segment
		(start 18.032984 -247.060212)
		(end 22.069044 -247.060212)
		(width 0.14478)
		(layer "In11.Cu")
		(net "M_F_CPU1_SA_CS_N<1>")
	)
	(segment
		(start 23.769066 -248.760234)
		(end 59.387486 -248.760234)
		(width 0.14478)
		(layer "In11.Cu")
		(net "M_F_CPU1_SA_CS_N<1>")
	)
	(segment
		(start 76.278486 -252.833124)
		(end 76.649326 -252.462284)
		(width 0.0889)
		(layer "In11.Cu")
		(net "M_F_CPU1_SA_CS_N<1>")
	)
	(segment
		(start 73.042018 -251.517404)
		(end 74.357738 -252.833124)
		(width 0.14478)
		(layer "In11.Cu")
		(net "M_F_CPU1_SA_CS_N<1>")
	)
	(segment
		(start 82.453988 -252.261878)
		(end 82.46237 -252.257052)
		(width 0.0889)
		(layer "In11.Cu")
		(net "M_F_CPU1_SA_CS_N<1>")
	)
	(segment
		(start 78.693772 -252.261878)
		(end 78.705456 -252.25502)
		(width 0.0889)
		(layer "In11.Cu")
		(net "M_F_CPU1_SA_CS_N<1>")
	)
	(segment
		(start 62.144656 -251.517404)
		(end 73.042018 -251.517404)
		(width 0.14478)
		(layer "In11.Cu")
		(net "M_F_CPU1_SA_CS_N<1>")
	)
	(segment
		(start 74.357738 -252.833124)
		(end 75.976226 -252.833124)
		(width 0.14478)
		(layer "In11.Cu")
		(net "M_F_CPU1_SA_CS_N<1>")
	)
	(segment
		(start 77.352144 -252.267466)
		(end 77.747876 -252.267466)
		(width 0.0889)
		(layer "In11.Cu")
		(net "M_F_CPU1_SA_CS_N<1>")
	)
	(segment
		(start 85.592666 -252.235716)
		(end 85.615018 -252.319028)
		(width 0.0889)
		(layer "In11.Cu")
		(net "M_F_CPU1_SA_CS_N<1>")
	)
	(segment
		(start 77.753464 -252.261878)
		(end 77.765148 -252.25502)
		(width 0.0889)
		(layer "In11.Cu")
		(net "M_F_CPU1_SA_CS_N<1>")
	)
	(segment
		(start 77.747876 -252.267466)
		(end 77.753464 -252.261878)
		(width 0.0889)
		(layer "In11.Cu")
		(net "M_F_CPU1_SA_CS_N<1>")
	)
	(arc
		(start 82.82813 -252.261878)
		(mid 83.111086 -252.338055)
		(end 83.394042 -252.261878)
		(width 0.0889)
		(layer "In11.Cu")
		(net "M_F_CPU1_SA_CS_N<1>")
	)
	(arc
		(start 79.633826 -252.261878)
		(mid 79.821024 -252.211496)
		(end 80.008222 -252.261878)
		(width 0.0889)
		(layer "In11.Cu")
		(net "M_F_CPU1_SA_CS_N<1>")
	)
	(arc
		(start 77.765148 -252.25502)
		(mid 77.947403 -252.211367)
		(end 78.12786 -252.261878)
		(width 0.0889)
		(layer "In11.Cu")
		(net "M_F_CPU1_SA_CS_N<1>")
	)
	(arc
		(start 81.513934 -252.261878)
		(mid 81.696185 -252.211528)
		(end 81.879694 -252.257052)
		(width 0.0889)
		(layer "In11.Cu")
		(net "M_F_CPU1_SA_CS_N<1>")
	)
	(arc
		(start 83.402424 -252.257052)
		(mid 83.585932 -252.211558)
		(end 83.768184 -252.261878)
		(width 0.0889)
		(layer "In11.Cu")
		(net "M_F_CPU1_SA_CS_N<1>")
	)
	(arc
		(start 81.888076 -252.261878)
		(mid 82.171032 -252.338055)
		(end 82.453988 -252.261878)
		(width 0.0889)
		(layer "In11.Cu")
		(net "M_F_CPU1_SA_CS_N<1>")
	)
	(arc
		(start 84.707984 -252.261878)
		(mid 84.99094 -252.338055)
		(end 85.273896 -252.261878)
		(width 0.0889)
		(layer "In11.Cu")
		(net "M_F_CPU1_SA_CS_N<1>")
	)
	(arc
		(start 82.46237 -252.257052)
		(mid 82.645878 -252.211558)
		(end 82.82813 -252.261878)
		(width 0.0889)
		(layer "In11.Cu")
		(net "M_F_CPU1_SA_CS_N<1>")
	)
	(arc
		(start 85.273896 -252.261878)
		(mid 85.430334 -252.212907)
		(end 85.592666 -252.235716)
		(width 0.0889)
		(layer "In11.Cu")
		(net "M_F_CPU1_SA_CS_N<1>")
	)
	(arc
		(start 80.008222 -252.261878)
		(mid 80.291178 -252.338055)
		(end 80.574134 -252.261878)
		(width 0.0889)
		(layer "In11.Cu")
		(net "M_F_CPU1_SA_CS_N<1>")
	)
	(arc
		(start 80.948022 -252.261878)
		(mid 81.230978 -252.338055)
		(end 81.513934 -252.261878)
		(width 0.0889)
		(layer "In11.Cu")
		(net "M_F_CPU1_SA_CS_N<1>")
	)
	(arc
		(start 83.768184 -252.261878)
		(mid 84.05114 -252.338055)
		(end 84.334096 -252.261878)
		(width 0.0889)
		(layer "In11.Cu")
		(net "M_F_CPU1_SA_CS_N<1>")
	)
	(arc
		(start 79.078074 -252.267974)
		(mid 79.35676 -252.338194)
		(end 79.633826 -252.261878)
		(width 0.0889)
		(layer "In11.Cu")
		(net "M_F_CPU1_SA_CS_N<1>")
	)
	(arc
		(start 78.705456 -252.25502)
		(mid 78.887457 -252.211487)
		(end 79.06766 -252.261878)
		(width 0.0889)
		(layer "In11.Cu")
		(net "M_F_CPU1_SA_CS_N<1>")
	)
	(arc
		(start 78.12786 -252.261878)
		(mid 78.402312 -252.338114)
		(end 78.67904 -252.270514)
		(width 0.0889)
		(layer "In11.Cu")
		(net "M_F_CPU1_SA_CS_N<1>")
	)
	(arc
		(start 80.574134 -252.261878)
		(mid 80.761078 -252.211623)
		(end 80.948022 -252.261878)
		(width 0.0889)
		(layer "In11.Cu")
		(net "M_F_CPU1_SA_CS_N<1>")
	)
	(arc
		(start 84.334096 -252.261878)
		(mid 84.52104 -252.211623)
		(end 84.707984 -252.261878)
		(width 0.0889)
		(layer "In11.Cu")
		(net "M_F_CPU1_SA_CS_N<1>")
	)
	(segment
		(start 84.517992 -252.04039)
		(end 84.05114 -251.774452)
		(width 0.10668)
		(layer "F.Cu")
		(net "M_F_CPU1_SA_CS_N<0>")
	)
	(segment
		(start 78.598014 -251.451872)
		(end 78.616048 -251.46254)
		(width 0.0889)
		(layer "In11.Cu")
		(net "M_F_CPU1_SA_CS_N<0>")
	)
	(segment
		(start 35.70478 -247.91035)
		(end 37.802058 -247.91035)
		(width 0.14478)
		(layer "In11.Cu")
		(net "M_F_CPU1_SA_CS_N<0>")
	)
	(segment
		(start 27.965146 -248.141236)
		(end 27.965146 -248.073418)
		(width 0.14478)
		(layer "In11.Cu")
		(net "M_F_CPU1_SA_CS_N<0>")
	)
	(segment
		(start 34.428684 -248.073418)
		(end 34.591752 -247.91035)
		(width 0.14478)
		(layer "In11.Cu")
		(net "M_F_CPU1_SA_CS_N<0>")
	)
	(segment
		(start 35.541712 -248.133616)
		(end 35.541712 -248.073418)
		(width 0.14478)
		(layer "In11.Cu")
		(net "M_F_CPU1_SA_CS_N<0>")
	)
	(segment
		(start 27.408632 -248.141236)
		(end 27.5717 -248.304304)
		(width 0.14478)
		(layer "In11.Cu")
		(net "M_F_CPU1_SA_CS_N<0>")
	)
	(segment
		(start 31.353506 -248.141236)
		(end 31.353506 -248.073418)
		(width 0.14478)
		(layer "In11.Cu")
		(net "M_F_CPU1_SA_CS_N<0>")
	)
	(segment
		(start 84.205064 -251.509022)
		(end 84.05114 -251.774452)
		(width 0.0889)
		(layer "In11.Cu")
		(net "M_F_CPU1_SA_CS_N<0>")
	)
	(segment
		(start 77.70495 -251.459746)
		(end 78.217014 -251.459746)
		(width 0.0889)
		(layer "In11.Cu")
		(net "M_F_CPU1_SA_CS_N<0>")
	)
	(segment
		(start 74.546206 -252.378464)
		(end 75.986132 -252.378464)
		(width 0.14478)
		(layer "In11.Cu")
		(net "M_F_CPU1_SA_CS_N<0>")
	)
	(segment
		(start 37.965126 -248.073418)
		(end 37.965126 -248.141236)
		(width 0.14478)
		(layer "In11.Cu")
		(net "M_F_CPU1_SA_CS_N<0>")
	)
	(segment
		(start 27.965146 -248.073418)
		(end 28.128214 -247.91035)
		(width 0.14478)
		(layer "In11.Cu")
		(net "M_F_CPU1_SA_CS_N<0>")
	)
	(segment
		(start 35.378644 -248.296684)
		(end 35.541712 -248.133616)
		(width 0.14478)
		(layer "In11.Cu")
		(net "M_F_CPU1_SA_CS_N<0>")
	)
	(segment
		(start 27.408632 -248.073418)
		(end 27.408632 -248.141236)
		(width 0.14478)
		(layer "In11.Cu")
		(net "M_F_CPU1_SA_CS_N<0>")
	)
	(segment
		(start 35.541712 -248.073418)
		(end 35.70478 -247.91035)
		(width 0.14478)
		(layer "In11.Cu")
		(net "M_F_CPU1_SA_CS_N<0>")
	)
	(segment
		(start 37.802058 -247.91035)
		(end 37.965126 -248.073418)
		(width 0.14478)
		(layer "In11.Cu")
		(net "M_F_CPU1_SA_CS_N<0>")
	)
	(segment
		(start 33.87217 -248.073418)
		(end 33.87217 -248.133616)
		(width 0.14478)
		(layer "In11.Cu")
		(net "M_F_CPU1_SA_CS_N<0>")
	)
	(segment
		(start 34.428684 -248.133616)
		(end 34.428684 -248.073418)
		(width 0.14478)
		(layer "In11.Cu")
		(net "M_F_CPU1_SA_CS_N<0>")
	)
	(segment
		(start 27.015186 -247.91035)
		(end 27.245564 -247.91035)
		(width 0.14478)
		(layer "In11.Cu")
		(net "M_F_CPU1_SA_CS_N<0>")
	)
	(segment
		(start 79.53883 -251.452126)
		(end 79.550768 -251.458984)
		(width 0.0889)
		(layer "In11.Cu")
		(net "M_F_CPU1_SA_CS_N<0>")
	)
	(segment
		(start 34.591752 -247.91035)
		(end 34.82213 -247.91035)
		(width 0.14478)
		(layer "In11.Cu")
		(net "M_F_CPU1_SA_CS_N<0>")
	)
	(segment
		(start 27.802078 -248.304304)
		(end 27.965146 -248.141236)
		(width 0.14478)
		(layer "In11.Cu")
		(net "M_F_CPU1_SA_CS_N<0>")
	)
	(segment
		(start 38.52164 -248.141236)
		(end 38.52164 -248.073418)
		(width 0.14478)
		(layer "In11.Cu")
		(net "M_F_CPU1_SA_CS_N<0>")
	)
	(segment
		(start 30.796992 -248.073418)
		(end 30.796992 -248.141236)
		(width 0.14478)
		(layer "In11.Cu")
		(net "M_F_CPU1_SA_CS_N<0>")
	)
	(segment
		(start 34.82213 -247.91035)
		(end 34.985198 -248.073418)
		(width 0.14478)
		(layer "In11.Cu")
		(net "M_F_CPU1_SA_CS_N<0>")
	)
	(segment
		(start 23.833074 -247.91035)
		(end 26.132536 -247.91035)
		(width 0.14478)
		(layer "In11.Cu")
		(net "M_F_CPU1_SA_CS_N<0>")
	)
	(segment
		(start 21.70811 -245.785386)
		(end 23.833074 -247.91035)
		(width 0.14478)
		(layer "In11.Cu")
		(net "M_F_CPU1_SA_CS_N<0>")
	)
	(segment
		(start 38.128194 -248.304304)
		(end 38.358572 -248.304304)
		(width 0.14478)
		(layer "In11.Cu")
		(net "M_F_CPU1_SA_CS_N<0>")
	)
	(segment
		(start 73.230486 -251.062744)
		(end 74.546206 -252.378464)
		(width 0.14478)
		(layer "In11.Cu")
		(net "M_F_CPU1_SA_CS_N<0>")
	)
	(segment
		(start 26.295604 -248.141236)
		(end 26.458672 -248.304304)
		(width 0.14478)
		(layer "In11.Cu")
		(net "M_F_CPU1_SA_CS_N<0>")
	)
	(segment
		(start 83.289648 -251.447046)
		(end 83.29803 -251.451872)
		(width 0.0889)
		(layer "In11.Cu")
		(net "M_F_CPU1_SA_CS_N<0>")
	)
	(segment
		(start 26.68905 -248.304304)
		(end 26.852118 -248.141236)
		(width 0.14478)
		(layer "In11.Cu")
		(net "M_F_CPU1_SA_CS_N<0>")
	)
	(segment
		(start 33.709102 -247.91035)
		(end 33.87217 -248.073418)
		(width 0.14478)
		(layer "In11.Cu")
		(net "M_F_CPU1_SA_CS_N<0>")
	)
	(segment
		(start 28.128214 -247.91035)
		(end 30.633924 -247.91035)
		(width 0.14478)
		(layer "In11.Cu")
		(net "M_F_CPU1_SA_CS_N<0>")
	)
	(segment
		(start 27.5717 -248.304304)
		(end 27.802078 -248.304304)
		(width 0.14478)
		(layer "In11.Cu")
		(net "M_F_CPU1_SA_CS_N<0>")
	)
	(segment
		(start 27.245564 -247.91035)
		(end 27.408632 -248.073418)
		(width 0.14478)
		(layer "In11.Cu")
		(net "M_F_CPU1_SA_CS_N<0>")
	)
	(segment
		(start 34.265616 -248.296684)
		(end 34.428684 -248.133616)
		(width 0.14478)
		(layer "In11.Cu")
		(net "M_F_CPU1_SA_CS_N<0>")
	)
	(segment
		(start 34.985198 -248.133616)
		(end 35.148266 -248.296684)
		(width 0.14478)
		(layer "In11.Cu")
		(net "M_F_CPU1_SA_CS_N<0>")
	)
	(segment
		(start 30.796992 -248.141236)
		(end 30.96006 -248.304304)
		(width 0.14478)
		(layer "In11.Cu")
		(net "M_F_CPU1_SA_CS_N<0>")
	)
	(segment
		(start 80.46974 -251.447046)
		(end 80.478122 -251.451872)
		(width 0.0889)
		(layer "In11.Cu")
		(net "M_F_CPU1_SA_CS_N<0>")
	)
	(segment
		(start 78.217014 -251.459746)
		(end 78.224634 -251.452126)
		(width 0.0889)
		(layer "In11.Cu")
		(net "M_F_CPU1_SA_CS_N<0>")
	)
	(segment
		(start 34.985198 -248.073418)
		(end 34.985198 -248.133616)
		(width 0.14478)
		(layer "In11.Cu")
		(net "M_F_CPU1_SA_CS_N<0>")
	)
	(segment
		(start 26.458672 -248.304304)
		(end 26.68905 -248.304304)
		(width 0.14478)
		(layer "In11.Cu")
		(net "M_F_CPU1_SA_CS_N<0>")
	)
	(segment
		(start 31.353506 -248.073418)
		(end 31.516574 -247.91035)
		(width 0.14478)
		(layer "In11.Cu")
		(net "M_F_CPU1_SA_CS_N<0>")
	)
	(segment
		(start 62.746636 -251.062744)
		(end 73.230486 -251.062744)
		(width 0.14478)
		(layer "In11.Cu")
		(net "M_F_CPU1_SA_CS_N<0>")
	)
	(segment
		(start 33.87217 -248.133616)
		(end 34.035238 -248.296684)
		(width 0.14478)
		(layer "In11.Cu")
		(net "M_F_CPU1_SA_CS_N<0>")
	)
	(segment
		(start 26.295604 -248.073418)
		(end 26.295604 -248.141236)
		(width 0.14478)
		(layer "In11.Cu")
		(net "M_F_CPU1_SA_CS_N<0>")
	)
	(segment
		(start 31.190438 -248.304304)
		(end 31.353506 -248.141236)
		(width 0.14478)
		(layer "In11.Cu")
		(net "M_F_CPU1_SA_CS_N<0>")
	)
	(segment
		(start 75.986132 -252.378464)
		(end 76.29017 -252.074426)
		(width 0.0889)
		(layer "In11.Cu")
		(net "M_F_CPU1_SA_CS_N<0>")
	)
	(segment
		(start 38.52164 -248.073418)
		(end 38.684708 -247.91035)
		(width 0.14478)
		(layer "In11.Cu")
		(net "M_F_CPU1_SA_CS_N<0>")
	)
	(segment
		(start 38.684708 -247.91035)
		(end 59.594242 -247.91035)
		(width 0.14478)
		(layer "In11.Cu")
		(net "M_F_CPU1_SA_CS_N<0>")
	)
	(segment
		(start 77.09027 -252.074426)
		(end 77.70495 -251.459746)
		(width 0.0889)
		(layer "In11.Cu")
		(net "M_F_CPU1_SA_CS_N<0>")
	)
	(segment
		(start 76.29017 -252.074426)
		(end 77.09027 -252.074426)
		(width 0.0889)
		(layer "In11.Cu")
		(net "M_F_CPU1_SA_CS_N<0>")
	)
	(segment
		(start 30.633924 -247.91035)
		(end 30.796992 -248.073418)
		(width 0.14478)
		(layer "In11.Cu")
		(net "M_F_CPU1_SA_CS_N<0>")
	)
	(segment
		(start 30.96006 -248.304304)
		(end 31.190438 -248.304304)
		(width 0.14478)
		(layer "In11.Cu")
		(net "M_F_CPU1_SA_CS_N<0>")
	)
	(segment
		(start 35.148266 -248.296684)
		(end 35.378644 -248.296684)
		(width 0.14478)
		(layer "In11.Cu")
		(net "M_F_CPU1_SA_CS_N<0>")
	)
	(segment
		(start 79.520542 -251.441712)
		(end 79.53883 -251.452126)
		(width 0.0889)
		(layer "In11.Cu")
		(net "M_F_CPU1_SA_CS_N<0>")
	)
	(segment
		(start 31.516574 -247.91035)
		(end 33.709102 -247.91035)
		(width 0.14478)
		(layer "In11.Cu")
		(net "M_F_CPU1_SA_CS_N<0>")
	)
	(segment
		(start 81.044034 -251.451872)
		(end 81.052416 -251.447046)
		(width 0.0889)
		(layer "In11.Cu")
		(net "M_F_CPU1_SA_CS_N<0>")
	)
	(segment
		(start 26.852118 -248.073418)
		(end 27.015186 -247.91035)
		(width 0.14478)
		(layer "In11.Cu")
		(net "M_F_CPU1_SA_CS_N<0>")
	)
	(segment
		(start 37.965126 -248.141236)
		(end 38.128194 -248.304304)
		(width 0.14478)
		(layer "In11.Cu")
		(net "M_F_CPU1_SA_CS_N<0>")
	)
	(segment
		(start 59.594242 -247.91035)
		(end 62.746636 -251.062744)
		(width 0.14478)
		(layer "In11.Cu")
		(net "M_F_CPU1_SA_CS_N<0>")
	)
	(segment
		(start 26.852118 -248.141236)
		(end 26.852118 -248.073418)
		(width 0.14478)
		(layer "In11.Cu")
		(net "M_F_CPU1_SA_CS_N<0>")
	)
	(segment
		(start 34.035238 -248.296684)
		(end 34.265616 -248.296684)
		(width 0.14478)
		(layer "In11.Cu")
		(net "M_F_CPU1_SA_CS_N<0>")
	)
	(segment
		(start 78.224634 -251.452126)
		(end 78.24089 -251.442728)
		(width 0.0889)
		(layer "In11.Cu")
		(net "M_F_CPU1_SA_CS_N<0>")
	)
	(segment
		(start 84.182712 -251.42571)
		(end 84.205064 -251.509022)
		(width 0.0889)
		(layer "In11.Cu")
		(net "M_F_CPU1_SA_CS_N<0>")
	)
	(segment
		(start 26.132536 -247.91035)
		(end 26.295604 -248.073418)
		(width 0.14478)
		(layer "In11.Cu")
		(net "M_F_CPU1_SA_CS_N<0>")
	)
	(segment
		(start 38.358572 -248.304304)
		(end 38.52164 -248.141236)
		(width 0.14478)
		(layer "In11.Cu")
		(net "M_F_CPU1_SA_CS_N<0>")
	)
	(arc
		(start 83.29803 -251.451872)
		(mid 83.580986 -251.528049)
		(end 83.863942 -251.451872)
		(width 0.0889)
		(layer "In11.Cu")
		(net "M_F_CPU1_SA_CS_N<0>")
	)
	(arc
		(start 78.616048 -251.46254)
		(mid 78.891743 -251.528383)
		(end 79.164688 -251.451872)
		(width 0.0889)
		(layer "In11.Cu")
		(net "M_F_CPU1_SA_CS_N<0>")
	)
	(arc
		(start 78.24089 -251.442728)
		(mid 78.420618 -251.401744)
		(end 78.598014 -251.451872)
		(width 0.0889)
		(layer "In11.Cu")
		(net "M_F_CPU1_SA_CS_N<0>")
	)
	(arc
		(start 83.863942 -251.451872)
		(mid 84.02038 -251.402901)
		(end 84.182712 -251.42571)
		(width 0.0889)
		(layer "In11.Cu")
		(net "M_F_CPU1_SA_CS_N<0>")
	)
	(arc
		(start 80.478122 -251.451872)
		(mid 80.761078 -251.528049)
		(end 81.044034 -251.451872)
		(width 0.0889)
		(layer "In11.Cu")
		(net "M_F_CPU1_SA_CS_N<0>")
	)
	(arc
		(start 79.550768 -251.458984)
		(mid 79.828302 -251.527965)
		(end 80.10398 -251.451872)
		(width 0.0889)
		(layer "In11.Cu")
		(net "M_F_CPU1_SA_CS_N<0>")
	)
	(arc
		(start 81.052416 -251.447046)
		(mid 81.235924 -251.401552)
		(end 81.418176 -251.451872)
		(width 0.0889)
		(layer "In11.Cu")
		(net "M_F_CPU1_SA_CS_N<0>")
	)
	(arc
		(start 81.984088 -251.451872)
		(mid 82.171032 -251.401617)
		(end 82.357976 -251.451872)
		(width 0.0889)
		(layer "In11.Cu")
		(net "M_F_CPU1_SA_CS_N<0>")
	)
	(arc
		(start 82.357976 -251.451872)
		(mid 82.640932 -251.528049)
		(end 82.923888 -251.451872)
		(width 0.0889)
		(layer "In11.Cu")
		(net "M_F_CPU1_SA_CS_N<0>")
	)
	(arc
		(start 82.923888 -251.451872)
		(mid 83.106139 -251.401522)
		(end 83.289648 -251.447046)
		(width 0.0889)
		(layer "In11.Cu")
		(net "M_F_CPU1_SA_CS_N<0>")
	)
	(arc
		(start 79.164688 -251.451872)
		(mid 79.341316 -251.401639)
		(end 79.520542 -251.441712)
		(width 0.0889)
		(layer "In11.Cu")
		(net "M_F_CPU1_SA_CS_N<0>")
	)
	(arc
		(start 80.10398 -251.451872)
		(mid 80.286231 -251.401522)
		(end 80.46974 -251.447046)
		(width 0.0889)
		(layer "In11.Cu")
		(net "M_F_CPU1_SA_CS_N<0>")
	)
	(arc
		(start 81.418176 -251.451872)
		(mid 81.701132 -251.528049)
		(end 81.984088 -251.451872)
		(width 0.0889)
		(layer "In11.Cu")
		(net "M_F_CPU1_SA_CS_N<0>")
	)
	(segment
		(start 85.927946 -249.610372)
		(end 85.461094 -249.344434)
		(width 0.10668)
		(layer "F.Cu")
		(net "M_F_CPU1_SA_CB<7>")
	)
	(segment
		(start 28.389834 -243.615464)
		(end 28.552902 -243.778532)
		(width 0.14478)
		(layer "In11.Cu")
		(net "M_F_CPU1_SA_CB<7>")
	)
	(segment
		(start 82.453988 -249.021854)
		(end 82.46237 -249.017028)
		(width 0.0889)
		(layer "In11.Cu")
		(net "M_F_CPU1_SA_CB<7>")
	)
	(segment
		(start 28.552902 -245.197376)
		(end 28.71597 -245.360444)
		(width 0.14478)
		(layer "In11.Cu")
		(net "M_F_CPU1_SA_CB<7>")
	)
	(segment
		(start 85.615018 -249.079004)
		(end 85.461094 -249.344434)
		(width 0.0889)
		(layer "In11.Cu")
		(net "M_F_CPU1_SA_CB<7>")
	)
	(segment
		(start 32.001206 -245.197376)
		(end 32.164274 -245.360444)
		(width 0.14478)
		(layer "In11.Cu")
		(net "M_F_CPU1_SA_CB<7>")
	)
	(segment
		(start 25.45969 -243.660422)
		(end 27.159712 -245.360444)
		(width 0.14478)
		(layer "In11.Cu")
		(net "M_F_CPU1_SA_CB<7>")
	)
	(segment
		(start 74.025506 -249.145044)
		(end 74.848466 -249.968004)
		(width 0.14478)
		(layer "In11.Cu")
		(net "M_F_CPU1_SA_CB<7>")
	)
	(segment
		(start 27.996388 -243.778532)
		(end 28.159456 -243.615464)
		(width 0.14478)
		(layer "In11.Cu")
		(net "M_F_CPU1_SA_CB<7>")
	)
	(segment
		(start 77.747622 -249.968004)
		(end 78.693772 -249.021854)
		(width 0.0889)
		(layer "In11.Cu")
		(net "M_F_CPU1_SA_CB<7>")
	)
	(segment
		(start 27.996388 -245.197376)
		(end 27.996388 -243.778532)
		(width 0.14478)
		(layer "In11.Cu")
		(net "M_F_CPU1_SA_CB<7>")
	)
	(segment
		(start 31.838138 -244.082824)
		(end 32.001206 -244.245892)
		(width 0.14478)
		(layer "In11.Cu")
		(net "M_F_CPU1_SA_CB<7>")
	)
	(segment
		(start 60.568586 -245.360444)
		(end 64.353186 -249.145044)
		(width 0.14478)
		(layer "In11.Cu")
		(net "M_F_CPU1_SA_CB<7>")
	)
	(segment
		(start 27.83332 -245.360444)
		(end 27.996388 -245.197376)
		(width 0.14478)
		(layer "In11.Cu")
		(net "M_F_CPU1_SA_CB<7>")
	)
	(segment
		(start 31.60776 -244.082824)
		(end 31.838138 -244.082824)
		(width 0.14478)
		(layer "In11.Cu")
		(net "M_F_CPU1_SA_CB<7>")
	)
	(segment
		(start 28.71597 -245.360444)
		(end 31.281624 -245.360444)
		(width 0.14478)
		(layer "In11.Cu")
		(net "M_F_CPU1_SA_CB<7>")
	)
	(segment
		(start 78.693772 -249.021854)
		(end 78.705456 -249.014996)
		(width 0.0889)
		(layer "In11.Cu")
		(net "M_F_CPU1_SA_CB<7>")
	)
	(segment
		(start 83.394042 -249.021854)
		(end 83.402424 -249.017028)
		(width 0.0889)
		(layer "In11.Cu")
		(net "M_F_CPU1_SA_CB<7>")
	)
	(segment
		(start 74.848466 -249.968004)
		(end 76.248006 -249.968004)
		(width 0.14478)
		(layer "In11.Cu")
		(net "M_F_CPU1_SA_CB<7>")
	)
	(segment
		(start 31.444692 -244.245892)
		(end 31.60776 -244.082824)
		(width 0.14478)
		(layer "In11.Cu")
		(net "M_F_CPU1_SA_CB<7>")
	)
	(segment
		(start 27.159712 -245.360444)
		(end 27.83332 -245.360444)
		(width 0.14478)
		(layer "In11.Cu")
		(net "M_F_CPU1_SA_CB<7>")
	)
	(segment
		(start 79.06766 -249.021854)
		(end 79.078074 -249.02795)
		(width 0.0889)
		(layer "In11.Cu")
		(net "M_F_CPU1_SA_CB<7>")
	)
	(segment
		(start 32.001206 -244.245892)
		(end 32.001206 -245.197376)
		(width 0.14478)
		(layer "In11.Cu")
		(net "M_F_CPU1_SA_CB<7>")
	)
	(segment
		(start 31.281624 -245.360444)
		(end 31.444692 -245.197376)
		(width 0.14478)
		(layer "In11.Cu")
		(net "M_F_CPU1_SA_CB<7>")
	)
	(segment
		(start 81.879694 -249.017028)
		(end 81.888076 -249.021854)
		(width 0.0889)
		(layer "In11.Cu")
		(net "M_F_CPU1_SA_CB<7>")
	)
	(segment
		(start 32.164274 -245.360444)
		(end 60.568586 -245.360444)
		(width 0.14478)
		(layer "In11.Cu")
		(net "M_F_CPU1_SA_CB<7>")
	)
	(segment
		(start 31.444692 -245.197376)
		(end 31.444692 -244.245892)
		(width 0.14478)
		(layer "In11.Cu")
		(net "M_F_CPU1_SA_CB<7>")
	)
	(segment
		(start 28.552902 -243.778532)
		(end 28.552902 -245.197376)
		(width 0.14478)
		(layer "In11.Cu")
		(net "M_F_CPU1_SA_CB<7>")
	)
	(segment
		(start 17.608042 -243.235226)
		(end 18.033238 -243.660422)
		(width 0.14478)
		(layer "In11.Cu")
		(net "M_F_CPU1_SA_CB<7>")
	)
	(segment
		(start 76.248006 -249.968004)
		(end 77.747622 -249.968004)
		(width 0.0889)
		(layer "In11.Cu")
		(net "M_F_CPU1_SA_CB<7>")
	)
	(segment
		(start 28.159456 -243.615464)
		(end 28.389834 -243.615464)
		(width 0.14478)
		(layer "In11.Cu")
		(net "M_F_CPU1_SA_CB<7>")
	)
	(segment
		(start 18.033238 -243.660422)
		(end 25.45969 -243.660422)
		(width 0.14478)
		(layer "In11.Cu")
		(net "M_F_CPU1_SA_CB<7>")
	)
	(segment
		(start 85.592666 -248.995692)
		(end 85.615018 -249.079004)
		(width 0.0889)
		(layer "In11.Cu")
		(net "M_F_CPU1_SA_CB<7>")
	)
	(segment
		(start 64.353186 -249.145044)
		(end 74.025506 -249.145044)
		(width 0.14478)
		(layer "In11.Cu")
		(net "M_F_CPU1_SA_CB<7>")
	)
	(arc
		(start 85.273896 -249.021854)
		(mid 85.430334 -248.972883)
		(end 85.592666 -248.995692)
		(width 0.0889)
		(layer "In11.Cu")
		(net "M_F_CPU1_SA_CB<7>")
	)
	(arc
		(start 80.574134 -249.021854)
		(mid 80.761078 -248.971599)
		(end 80.948022 -249.021854)
		(width 0.0889)
		(layer "In11.Cu")
		(net "M_F_CPU1_SA_CB<7>")
	)
	(arc
		(start 83.768184 -249.021854)
		(mid 84.05114 -249.098031)
		(end 84.334096 -249.021854)
		(width 0.0889)
		(layer "In11.Cu")
		(net "M_F_CPU1_SA_CB<7>")
	)
	(arc
		(start 81.888076 -249.021854)
		(mid 82.171032 -249.098031)
		(end 82.453988 -249.021854)
		(width 0.0889)
		(layer "In11.Cu")
		(net "M_F_CPU1_SA_CB<7>")
	)
	(arc
		(start 84.334096 -249.021854)
		(mid 84.52104 -248.971599)
		(end 84.707984 -249.021854)
		(width 0.0889)
		(layer "In11.Cu")
		(net "M_F_CPU1_SA_CB<7>")
	)
	(arc
		(start 82.82813 -249.021854)
		(mid 83.111086 -249.098031)
		(end 83.394042 -249.021854)
		(width 0.0889)
		(layer "In11.Cu")
		(net "M_F_CPU1_SA_CB<7>")
	)
	(arc
		(start 84.707984 -249.021854)
		(mid 84.99094 -249.098031)
		(end 85.273896 -249.021854)
		(width 0.0889)
		(layer "In11.Cu")
		(net "M_F_CPU1_SA_CB<7>")
	)
	(arc
		(start 79.078074 -249.02795)
		(mid 79.35676 -249.09817)
		(end 79.633826 -249.021854)
		(width 0.0889)
		(layer "In11.Cu")
		(net "M_F_CPU1_SA_CB<7>")
	)
	(arc
		(start 78.705456 -249.014996)
		(mid 78.887457 -248.971463)
		(end 79.06766 -249.021854)
		(width 0.0889)
		(layer "In11.Cu")
		(net "M_F_CPU1_SA_CB<7>")
	)
	(arc
		(start 81.513934 -249.021854)
		(mid 81.696185 -248.971504)
		(end 81.879694 -249.017028)
		(width 0.0889)
		(layer "In11.Cu")
		(net "M_F_CPU1_SA_CB<7>")
	)
	(arc
		(start 82.46237 -249.017028)
		(mid 82.645878 -248.971534)
		(end 82.82813 -249.021854)
		(width 0.0889)
		(layer "In11.Cu")
		(net "M_F_CPU1_SA_CB<7>")
	)
	(arc
		(start 80.008222 -249.021854)
		(mid 80.291178 -249.098031)
		(end 80.574134 -249.021854)
		(width 0.0889)
		(layer "In11.Cu")
		(net "M_F_CPU1_SA_CB<7>")
	)
	(arc
		(start 79.633826 -249.021854)
		(mid 79.821024 -248.971472)
		(end 80.008222 -249.021854)
		(width 0.0889)
		(layer "In11.Cu")
		(net "M_F_CPU1_SA_CB<7>")
	)
	(arc
		(start 80.948022 -249.021854)
		(mid 81.230978 -249.098031)
		(end 81.513934 -249.021854)
		(width 0.0889)
		(layer "In11.Cu")
		(net "M_F_CPU1_SA_CB<7>")
	)
	(arc
		(start 83.402424 -249.017028)
		(mid 83.585932 -248.971534)
		(end 83.768184 -249.021854)
		(width 0.0889)
		(layer "In11.Cu")
		(net "M_F_CPU1_SA_CB<7>")
	)
	(segment
		(start 84.517992 -248.800366)
		(end 84.05114 -248.534428)
		(width 0.10668)
		(layer "F.Cu")
		(net "M_F_CPU1_SA_CB<6>")
	)
	(segment
		(start 45.968158 -243.515388)
		(end 45.968158 -242.739926)
		(width 0.14478)
		(layer "In11.Cu")
		(net "M_F_CPU1_SA_CB<6>")
	)
	(segment
		(start 46.519592 -243.515388)
		(end 46.664372 -243.660168)
		(width 0.14478)
		(layer "In11.Cu")
		(net "M_F_CPU1_SA_CB<6>")
	)
	(segment
		(start 59.713368 -242.691666)
		(end 65.257426 -248.235724)
		(width 0.14478)
		(layer "In11.Cu")
		(net "M_F_CPU1_SA_CB<6>")
	)
	(segment
		(start 49.800002 -243.515388)
		(end 49.944782 -243.660168)
		(width 0.14478)
		(layer "In11.Cu")
		(net "M_F_CPU1_SA_CB<6>")
	)
	(segment
		(start 45.968158 -242.739926)
		(end 46.112938 -242.595146)
		(width 0.14478)
		(layer "In11.Cu")
		(net "M_F_CPU1_SA_CB<6>")
	)
	(segment
		(start 49.103788 -243.660168)
		(end 49.248568 -243.515388)
		(width 0.14478)
		(layer "In11.Cu")
		(net "M_F_CPU1_SA_CB<6>")
	)
	(segment
		(start 74.967338 -248.80062)
		(end 76.011786 -248.80062)
		(width 0.14478)
		(layer "In11.Cu")
		(net "M_F_CPU1_SA_CB<6>")
	)
	(segment
		(start 74.402442 -248.235724)
		(end 74.967338 -248.80062)
		(width 0.14478)
		(layer "In11.Cu")
		(net "M_F_CPU1_SA_CB<6>")
	)
	(segment
		(start 79.525114 -248.204228)
		(end 79.53883 -248.212102)
		(width 0.0889)
		(layer "In11.Cu")
		(net "M_F_CPU1_SA_CB<6>")
	)
	(segment
		(start 43.079416 -243.660168)
		(end 45.823378 -243.660168)
		(width 0.14478)
		(layer "In11.Cu")
		(net "M_F_CPU1_SA_CB<6>")
	)
	(segment
		(start 84.205064 -248.268998)
		(end 84.05114 -248.534428)
		(width 0.0889)
		(layer "In11.Cu")
		(net "M_F_CPU1_SA_CB<6>")
	)
	(segment
		(start 50.90287 -242.856766)
		(end 50.90287 -243.515388)
		(width 0.14478)
		(layer "In11.Cu")
		(net "M_F_CPU1_SA_CB<6>")
	)
	(segment
		(start 50.351436 -242.856766)
		(end 50.496216 -242.711986)
		(width 0.14478)
		(layer "In11.Cu")
		(net "M_F_CPU1_SA_CB<6>")
	)
	(segment
		(start 18.033238 -241.9604)
		(end 41.379648 -241.9604)
		(width 0.14478)
		(layer "In11.Cu")
		(net "M_F_CPU1_SA_CB<6>")
	)
	(segment
		(start 50.75809 -242.711986)
		(end 50.90287 -242.856766)
		(width 0.14478)
		(layer "In11.Cu")
		(net "M_F_CPU1_SA_CB<6>")
	)
	(segment
		(start 49.393348 -242.711986)
		(end 49.655222 -242.711986)
		(width 0.14478)
		(layer "In11.Cu")
		(net "M_F_CPU1_SA_CB<6>")
	)
	(segment
		(start 41.379648 -241.9604)
		(end 43.079416 -243.660168)
		(width 0.14478)
		(layer "In11.Cu")
		(net "M_F_CPU1_SA_CB<6>")
	)
	(segment
		(start 17.608042 -241.535204)
		(end 18.033238 -241.9604)
		(width 0.14478)
		(layer "In11.Cu")
		(net "M_F_CPU1_SA_CB<6>")
	)
	(segment
		(start 49.248568 -242.856766)
		(end 49.393348 -242.711986)
		(width 0.14478)
		(layer "In11.Cu")
		(net "M_F_CPU1_SA_CB<6>")
	)
	(segment
		(start 58.011568 -243.660168)
		(end 58.98007 -242.691666)
		(width 0.14478)
		(layer "In11.Cu")
		(net "M_F_CPU1_SA_CB<6>")
	)
	(segment
		(start 50.496216 -242.711986)
		(end 50.75809 -242.711986)
		(width 0.14478)
		(layer "In11.Cu")
		(net "M_F_CPU1_SA_CB<6>")
	)
	(segment
		(start 76.011786 -248.80062)
		(end 77.636116 -248.80062)
		(width 0.0889)
		(layer "In11.Cu")
		(net "M_F_CPU1_SA_CB<6>")
	)
	(segment
		(start 49.944782 -243.660168)
		(end 50.206656 -243.660168)
		(width 0.14478)
		(layer "In11.Cu")
		(net "M_F_CPU1_SA_CB<6>")
	)
	(segment
		(start 49.800002 -242.856766)
		(end 49.800002 -243.515388)
		(width 0.14478)
		(layer "In11.Cu")
		(net "M_F_CPU1_SA_CB<6>")
	)
	(segment
		(start 50.351436 -243.515388)
		(end 50.351436 -242.856766)
		(width 0.14478)
		(layer "In11.Cu")
		(net "M_F_CPU1_SA_CB<6>")
	)
	(segment
		(start 46.664372 -243.660168)
		(end 49.103788 -243.660168)
		(width 0.14478)
		(layer "In11.Cu")
		(net "M_F_CPU1_SA_CB<6>")
	)
	(segment
		(start 49.655222 -242.711986)
		(end 49.800002 -242.856766)
		(width 0.14478)
		(layer "In11.Cu")
		(net "M_F_CPU1_SA_CB<6>")
	)
	(segment
		(start 79.53883 -248.212102)
		(end 79.550768 -248.21896)
		(width 0.0889)
		(layer "In11.Cu")
		(net "M_F_CPU1_SA_CB<6>")
	)
	(segment
		(start 65.257426 -248.235724)
		(end 74.402442 -248.235724)
		(width 0.14478)
		(layer "In11.Cu")
		(net "M_F_CPU1_SA_CB<6>")
	)
	(segment
		(start 46.519592 -242.739926)
		(end 46.519592 -243.515388)
		(width 0.14478)
		(layer "In11.Cu")
		(net "M_F_CPU1_SA_CB<6>")
	)
	(segment
		(start 49.248568 -243.515388)
		(end 49.248568 -242.856766)
		(width 0.14478)
		(layer "In11.Cu")
		(net "M_F_CPU1_SA_CB<6>")
	)
	(segment
		(start 46.374812 -242.595146)
		(end 46.519592 -242.739926)
		(width 0.14478)
		(layer "In11.Cu")
		(net "M_F_CPU1_SA_CB<6>")
	)
	(segment
		(start 81.044034 -248.211848)
		(end 81.052416 -248.207022)
		(width 0.0889)
		(layer "In11.Cu")
		(net "M_F_CPU1_SA_CB<6>")
	)
	(segment
		(start 50.206656 -243.660168)
		(end 50.351436 -243.515388)
		(width 0.14478)
		(layer "In11.Cu")
		(net "M_F_CPU1_SA_CB<6>")
	)
	(segment
		(start 80.46974 -248.207022)
		(end 80.478122 -248.211848)
		(width 0.0889)
		(layer "In11.Cu")
		(net "M_F_CPU1_SA_CB<6>")
	)
	(segment
		(start 79.147162 -248.222516)
		(end 79.165196 -248.211848)
		(width 0.0889)
		(layer "In11.Cu")
		(net "M_F_CPU1_SA_CB<6>")
	)
	(segment
		(start 77.636116 -248.80062)
		(end 78.224634 -248.212102)
		(width 0.0889)
		(layer "In11.Cu")
		(net "M_F_CPU1_SA_CB<6>")
	)
	(segment
		(start 45.823378 -243.660168)
		(end 45.968158 -243.515388)
		(width 0.14478)
		(layer "In11.Cu")
		(net "M_F_CPU1_SA_CB<6>")
	)
	(segment
		(start 46.112938 -242.595146)
		(end 46.374812 -242.595146)
		(width 0.14478)
		(layer "In11.Cu")
		(net "M_F_CPU1_SA_CB<6>")
	)
	(segment
		(start 51.04765 -243.660168)
		(end 58.011568 -243.660168)
		(width 0.14478)
		(layer "In11.Cu")
		(net "M_F_CPU1_SA_CB<6>")
	)
	(segment
		(start 50.90287 -243.515388)
		(end 51.04765 -243.660168)
		(width 0.14478)
		(layer "In11.Cu")
		(net "M_F_CPU1_SA_CB<6>")
	)
	(segment
		(start 78.224634 -248.212102)
		(end 78.2447 -248.200672)
		(width 0.0889)
		(layer "In11.Cu")
		(net "M_F_CPU1_SA_CB<6>")
	)
	(segment
		(start 84.182712 -248.185686)
		(end 84.205064 -248.268998)
		(width 0.0889)
		(layer "In11.Cu")
		(net "M_F_CPU1_SA_CB<6>")
	)
	(segment
		(start 83.289648 -248.207022)
		(end 83.29803 -248.211848)
		(width 0.0889)
		(layer "In11.Cu")
		(net "M_F_CPU1_SA_CB<6>")
	)
	(segment
		(start 58.98007 -242.691666)
		(end 59.713368 -242.691666)
		(width 0.14478)
		(layer "In11.Cu")
		(net "M_F_CPU1_SA_CB<6>")
	)
	(arc
		(start 81.418176 -248.211848)
		(mid 81.701132 -248.288025)
		(end 81.984088 -248.211848)
		(width 0.0889)
		(layer "In11.Cu")
		(net "M_F_CPU1_SA_CB<6>")
	)
	(arc
		(start 80.10398 -248.211848)
		(mid 80.286231 -248.161498)
		(end 80.46974 -248.207022)
		(width 0.0889)
		(layer "In11.Cu")
		(net "M_F_CPU1_SA_CB<6>")
	)
	(arc
		(start 81.984088 -248.211848)
		(mid 82.171032 -248.161593)
		(end 82.357976 -248.211848)
		(width 0.0889)
		(layer "In11.Cu")
		(net "M_F_CPU1_SA_CB<6>")
	)
	(arc
		(start 79.165196 -248.211848)
		(mid 79.344183 -248.161678)
		(end 79.525114 -248.204228)
		(width 0.0889)
		(layer "In11.Cu")
		(net "M_F_CPU1_SA_CB<6>")
	)
	(arc
		(start 81.052416 -248.207022)
		(mid 81.235924 -248.161528)
		(end 81.418176 -248.211848)
		(width 0.0889)
		(layer "In11.Cu")
		(net "M_F_CPU1_SA_CB<6>")
	)
	(arc
		(start 78.2447 -248.200672)
		(mid 78.423032 -248.161575)
		(end 78.598522 -248.211848)
		(width 0.0889)
		(layer "In11.Cu")
		(net "M_F_CPU1_SA_CB<6>")
	)
	(arc
		(start 78.598522 -248.211848)
		(mid 78.871466 -248.288428)
		(end 79.147162 -248.222516)
		(width 0.0889)
		(layer "In11.Cu")
		(net "M_F_CPU1_SA_CB<6>")
	)
	(arc
		(start 82.357976 -248.211848)
		(mid 82.640932 -248.288025)
		(end 82.923888 -248.211848)
		(width 0.0889)
		(layer "In11.Cu")
		(net "M_F_CPU1_SA_CB<6>")
	)
	(arc
		(start 83.29803 -248.211848)
		(mid 83.580986 -248.288025)
		(end 83.863942 -248.211848)
		(width 0.0889)
		(layer "In11.Cu")
		(net "M_F_CPU1_SA_CB<6>")
	)
	(arc
		(start 82.923888 -248.211848)
		(mid 83.106139 -248.161498)
		(end 83.289648 -248.207022)
		(width 0.0889)
		(layer "In11.Cu")
		(net "M_F_CPU1_SA_CB<6>")
	)
	(arc
		(start 83.863942 -248.211848)
		(mid 84.02038 -248.162877)
		(end 84.182712 -248.185686)
		(width 0.0889)
		(layer "In11.Cu")
		(net "M_F_CPU1_SA_CB<6>")
	)
	(arc
		(start 79.550768 -248.21896)
		(mid 79.828302 -248.287941)
		(end 80.10398 -248.211848)
		(width 0.0889)
		(layer "In11.Cu")
		(net "M_F_CPU1_SA_CB<6>")
	)
	(arc
		(start 80.478122 -248.211848)
		(mid 80.761078 -248.288025)
		(end 81.044034 -248.211848)
		(width 0.0889)
		(layer "In11.Cu")
		(net "M_F_CPU1_SA_CB<6>")
	)
	(segment
		(start 86.397846 -248.800366)
		(end 85.930994 -248.534428)
		(width 0.10668)
		(layer "F.Cu")
		(net "M_F_CPU1_SA_CB<5>")
	)
	(segment
		(start 84.803996 -248.857008)
		(end 84.812378 -248.861834)
		(width 0.0889)
		(layer "In11.Cu")
		(net "M_F_CPU1_SA_CB<5>")
	)
	(segment
		(start 41.035732 -243.336572)
		(end 41.1988 -243.173504)
		(width 0.14478)
		(layer "In11.Cu")
		(net "M_F_CPU1_SA_CB<5>")
	)
	(segment
		(start 22.133052 -242.810284)
		(end 33.034732 -242.810284)
		(width 0.14478)
		(layer "In11.Cu")
		(net "M_F_CPU1_SA_CB<5>")
	)
	(segment
		(start 83.289648 -248.861834)
		(end 83.29803 -248.857008)
		(width 0.0889)
		(layer "In11.Cu")
		(net "M_F_CPU1_SA_CB<5>")
	)
	(segment
		(start 39.765224 -244.510306)
		(end 40.872664 -244.510306)
		(width 0.14478)
		(layer "In11.Cu")
		(net "M_F_CPU1_SA_CB<5>")
	)
	(segment
		(start 35.549586 -242.668552)
		(end 35.712654 -242.505484)
		(width 0.14478)
		(layer "In11.Cu")
		(net "M_F_CPU1_SA_CB<5>")
	)
	(segment
		(start 40.872664 -244.510306)
		(end 41.035732 -244.347238)
		(width 0.14478)
		(layer "In11.Cu")
		(net "M_F_CPU1_SA_CB<5>")
	)
	(segment
		(start 75.941428 -249.315986)
		(end 76.49083 -249.315986)
		(width 0.0889)
		(layer "In11.Cu")
		(net "M_F_CPU1_SA_CB<5>")
	)
	(segment
		(start 74.838814 -249.315224)
		(end 75.940666 -249.315224)
		(width 0.14478)
		(layer "In11.Cu")
		(net "M_F_CPU1_SA_CB<5>")
	)
	(segment
		(start 33.034732 -242.810284)
		(end 34.734754 -244.510306)
		(width 0.14478)
		(layer "In11.Cu")
		(net "M_F_CPU1_SA_CB<5>")
	)
	(segment
		(start 41.429178 -243.173504)
		(end 41.592246 -243.336572)
		(width 0.14478)
		(layer "In11.Cu")
		(net "M_F_CPU1_SA_CB<5>")
	)
	(segment
		(start 36.1061 -244.347238)
		(end 36.269168 -244.510306)
		(width 0.14478)
		(layer "In11.Cu")
		(net "M_F_CPU1_SA_CB<5>")
	)
	(segment
		(start 76.49083 -249.315986)
		(end 76.56449 -249.242326)
		(width 0.0889)
		(layer "In11.Cu")
		(net "M_F_CPU1_SA_CB<5>")
	)
	(segment
		(start 21.70811 -242.385342)
		(end 22.133052 -242.810284)
		(width 0.14478)
		(layer "In11.Cu")
		(net "M_F_CPU1_SA_CB<5>")
	)
	(segment
		(start 35.549586 -244.347238)
		(end 35.549586 -242.668552)
		(width 0.14478)
		(layer "In11.Cu")
		(net "M_F_CPU1_SA_CB<5>")
	)
	(segment
		(start 77.941932 -249.242326)
		(end 77.945234 -249.239024)
		(width 0.0889)
		(layer "In11.Cu")
		(net "M_F_CPU1_SA_CB<5>")
	)
	(segment
		(start 84.229702 -248.861834)
		(end 84.238084 -248.857008)
		(width 0.0889)
		(layer "In11.Cu")
		(net "M_F_CPU1_SA_CB<5>")
	)
	(segment
		(start 76.56449 -249.242326)
		(end 77.941932 -249.242326)
		(width 0.0889)
		(layer "In11.Cu")
		(net "M_F_CPU1_SA_CB<5>")
	)
	(segment
		(start 75.940666 -249.315224)
		(end 75.941428 -249.315986)
		(width 0.0889)
		(layer "In11.Cu")
		(net "M_F_CPU1_SA_CB<5>")
	)
	(segment
		(start 41.755314 -244.510306)
		(end 60.597288 -244.510306)
		(width 0.14478)
		(layer "In11.Cu")
		(net "M_F_CPU1_SA_CB<5>")
	)
	(segment
		(start 35.712654 -242.505484)
		(end 35.943032 -242.505484)
		(width 0.14478)
		(layer "In11.Cu")
		(net "M_F_CPU1_SA_CB<5>")
	)
	(segment
		(start 41.592246 -243.336572)
		(end 41.592246 -244.347238)
		(width 0.14478)
		(layer "In11.Cu")
		(net "M_F_CPU1_SA_CB<5>")
	)
	(segment
		(start 36.1061 -242.668552)
		(end 36.1061 -244.347238)
		(width 0.14478)
		(layer "In11.Cu")
		(net "M_F_CPU1_SA_CB<5>")
	)
	(segment
		(start 85.681058 -248.825258)
		(end 85.77707 -248.799858)
		(width 0.0889)
		(layer "In11.Cu")
		(net "M_F_CPU1_SA_CB<5>")
	)
	(segment
		(start 35.386518 -244.510306)
		(end 35.549586 -244.347238)
		(width 0.14478)
		(layer "In11.Cu")
		(net "M_F_CPU1_SA_CB<5>")
	)
	(segment
		(start 85.77707 -248.799858)
		(end 85.930994 -248.534428)
		(width 0.0889)
		(layer "In11.Cu")
		(net "M_F_CPU1_SA_CB<5>")
	)
	(segment
		(start 36.269168 -244.510306)
		(end 38.882574 -244.510306)
		(width 0.14478)
		(layer "In11.Cu")
		(net "M_F_CPU1_SA_CB<5>")
	)
	(segment
		(start 39.20871 -242.553744)
		(end 39.439088 -242.553744)
		(width 0.14478)
		(layer "In11.Cu")
		(net "M_F_CPU1_SA_CB<5>")
	)
	(segment
		(start 80.093566 -248.850912)
		(end 80.10398 -248.857008)
		(width 0.0889)
		(layer "In11.Cu")
		(net "M_F_CPU1_SA_CB<5>")
	)
	(segment
		(start 38.882574 -244.510306)
		(end 39.045642 -244.347238)
		(width 0.14478)
		(layer "In11.Cu")
		(net "M_F_CPU1_SA_CB<5>")
	)
	(segment
		(start 35.943032 -242.505484)
		(end 36.1061 -242.668552)
		(width 0.14478)
		(layer "In11.Cu")
		(net "M_F_CPU1_SA_CB<5>")
	)
	(segment
		(start 39.439088 -242.553744)
		(end 39.602156 -242.716812)
		(width 0.14478)
		(layer "In11.Cu")
		(net "M_F_CPU1_SA_CB<5>")
	)
	(segment
		(start 80.46974 -248.861834)
		(end 80.478122 -248.857008)
		(width 0.0889)
		(layer "In11.Cu")
		(net "M_F_CPU1_SA_CB<5>")
	)
	(segment
		(start 77.945234 -249.239024)
		(end 78.608174 -248.850912)
		(width 0.0889)
		(layer "In11.Cu")
		(net "M_F_CPU1_SA_CB<5>")
	)
	(segment
		(start 41.592246 -244.347238)
		(end 41.755314 -244.510306)
		(width 0.14478)
		(layer "In11.Cu")
		(net "M_F_CPU1_SA_CB<5>")
	)
	(segment
		(start 74.213974 -248.690384)
		(end 74.838814 -249.315224)
		(width 0.14478)
		(layer "In11.Cu")
		(net "M_F_CPU1_SA_CB<5>")
	)
	(segment
		(start 60.597288 -244.510306)
		(end 64.777366 -248.690384)
		(width 0.14478)
		(layer "In11.Cu")
		(net "M_F_CPU1_SA_CB<5>")
	)
	(segment
		(start 81.044034 -248.857008)
		(end 81.052416 -248.861834)
		(width 0.0889)
		(layer "In11.Cu")
		(net "M_F_CPU1_SA_CB<5>")
	)
	(segment
		(start 41.035732 -244.347238)
		(end 41.035732 -243.336572)
		(width 0.14478)
		(layer "In11.Cu")
		(net "M_F_CPU1_SA_CB<5>")
	)
	(segment
		(start 39.045642 -244.347238)
		(end 39.045642 -242.716812)
		(width 0.14478)
		(layer "In11.Cu")
		(net "M_F_CPU1_SA_CB<5>")
	)
	(segment
		(start 39.602156 -244.347238)
		(end 39.765224 -244.510306)
		(width 0.14478)
		(layer "In11.Cu")
		(net "M_F_CPU1_SA_CB<5>")
	)
	(segment
		(start 39.602156 -242.716812)
		(end 39.602156 -244.347238)
		(width 0.14478)
		(layer "In11.Cu")
		(net "M_F_CPU1_SA_CB<5>")
	)
	(segment
		(start 41.1988 -243.173504)
		(end 41.429178 -243.173504)
		(width 0.14478)
		(layer "In11.Cu")
		(net "M_F_CPU1_SA_CB<5>")
	)
	(segment
		(start 39.045642 -242.716812)
		(end 39.20871 -242.553744)
		(width 0.14478)
		(layer "In11.Cu")
		(net "M_F_CPU1_SA_CB<5>")
	)
	(segment
		(start 64.777366 -248.690384)
		(end 74.213974 -248.690384)
		(width 0.14478)
		(layer "In11.Cu")
		(net "M_F_CPU1_SA_CB<5>")
	)
	(segment
		(start 34.734754 -244.510306)
		(end 35.386518 -244.510306)
		(width 0.14478)
		(layer "In11.Cu")
		(net "M_F_CPU1_SA_CB<5>")
	)
	(arc
		(start 78.608174 -248.850912)
		(mid 78.886606 -248.780814)
		(end 79.163418 -248.857008)
		(width 0.0889)
		(layer "In11.Cu")
		(net "M_F_CPU1_SA_CB<5>")
	)
	(arc
		(start 84.238084 -248.857008)
		(mid 84.52104 -248.780831)
		(end 84.803996 -248.857008)
		(width 0.0889)
		(layer "In11.Cu")
		(net "M_F_CPU1_SA_CB<5>")
	)
	(arc
		(start 83.29803 -248.857008)
		(mid 83.580986 -248.780831)
		(end 83.863942 -248.857008)
		(width 0.0889)
		(layer "In11.Cu")
		(net "M_F_CPU1_SA_CB<5>")
	)
	(arc
		(start 80.478122 -248.857008)
		(mid 80.761078 -248.780831)
		(end 81.044034 -248.857008)
		(width 0.0889)
		(layer "In11.Cu")
		(net "M_F_CPU1_SA_CB<5>")
	)
	(arc
		(start 80.10398 -248.857008)
		(mid 80.286231 -248.907358)
		(end 80.46974 -248.861834)
		(width 0.0889)
		(layer "In11.Cu")
		(net "M_F_CPU1_SA_CB<5>")
	)
	(arc
		(start 83.863942 -248.857008)
		(mid 84.046193 -248.907358)
		(end 84.229702 -248.861834)
		(width 0.0889)
		(layer "In11.Cu")
		(net "M_F_CPU1_SA_CB<5>")
	)
	(arc
		(start 79.537814 -248.857008)
		(mid 79.814881 -248.780737)
		(end 80.093566 -248.850912)
		(width 0.0889)
		(layer "In11.Cu")
		(net "M_F_CPU1_SA_CB<5>")
	)
	(arc
		(start 82.357976 -248.857008)
		(mid 82.640932 -248.780831)
		(end 82.923888 -248.857008)
		(width 0.0889)
		(layer "In11.Cu")
		(net "M_F_CPU1_SA_CB<5>")
	)
	(arc
		(start 81.052416 -248.861834)
		(mid 81.235924 -248.907328)
		(end 81.418176 -248.857008)
		(width 0.0889)
		(layer "In11.Cu")
		(net "M_F_CPU1_SA_CB<5>")
	)
	(arc
		(start 81.984088 -248.857008)
		(mid 82.171032 -248.907263)
		(end 82.357976 -248.857008)
		(width 0.0889)
		(layer "In11.Cu")
		(net "M_F_CPU1_SA_CB<5>")
	)
	(arc
		(start 85.178138 -248.857008)
		(mid 85.425851 -248.781788)
		(end 85.681058 -248.825258)
		(width 0.0889)
		(layer "In11.Cu")
		(net "M_F_CPU1_SA_CB<5>")
	)
	(arc
		(start 79.163418 -248.857008)
		(mid 79.350616 -248.90739)
		(end 79.537814 -248.857008)
		(width 0.0889)
		(layer "In11.Cu")
		(net "M_F_CPU1_SA_CB<5>")
	)
	(arc
		(start 82.923888 -248.857008)
		(mid 83.106139 -248.907358)
		(end 83.289648 -248.861834)
		(width 0.0889)
		(layer "In11.Cu")
		(net "M_F_CPU1_SA_CB<5>")
	)
	(arc
		(start 84.812378 -248.861834)
		(mid 84.995886 -248.907328)
		(end 85.178138 -248.857008)
		(width 0.0889)
		(layer "In11.Cu")
		(net "M_F_CPU1_SA_CB<5>")
	)
	(arc
		(start 81.418176 -248.857008)
		(mid 81.701132 -248.780831)
		(end 81.984088 -248.857008)
		(width 0.0889)
		(layer "In11.Cu")
		(net "M_F_CPU1_SA_CB<5>")
	)
	(segment
		(start 84.987892 -247.99036)
		(end 84.52104 -247.724422)
		(width 0.10668)
		(layer "F.Cu")
		(net "M_F_CPU1_SA_CB<4>")
	)
	(segment
		(start 79.622396 -248.03989)
		(end 79.634334 -248.046748)
		(width 0.0889)
		(layer "In11.Cu")
		(net "M_F_CPU1_SA_CB<4>")
	)
	(segment
		(start 53.804312 -242.687856)
		(end 53.96738 -242.850924)
		(width 0.14478)
		(layer "In11.Cu")
		(net "M_F_CPU1_SA_CB<4>")
	)
	(segment
		(start 52.691284 -242.687856)
		(end 52.854352 -242.850924)
		(width 0.14478)
		(layer "In11.Cu")
		(net "M_F_CPU1_SA_CB<4>")
	)
	(segment
		(start 83.394042 -248.047002)
		(end 83.402424 -248.051828)
		(width 0.0889)
		(layer "In11.Cu")
		(net "M_F_CPU1_SA_CB<4>")
	)
	(segment
		(start 53.247798 -241.27333)
		(end 53.410866 -241.110262)
		(width 0.14478)
		(layer "In11.Cu")
		(net "M_F_CPU1_SA_CB<4>")
	)
	(segment
		(start 56.17845 -241.27333)
		(end 56.17845 -242.653058)
		(width 0.14478)
		(layer "In11.Cu")
		(net "M_F_CPU1_SA_CB<4>")
	)
	(segment
		(start 75.155806 -248.34596)
		(end 76.029566 -248.34596)
		(width 0.14478)
		(layer "In11.Cu")
		(net "M_F_CPU1_SA_CB<4>")
	)
	(segment
		(start 54.360826 -241.27333)
		(end 54.523894 -241.110262)
		(width 0.14478)
		(layer "In11.Cu")
		(net "M_F_CPU1_SA_CB<4>")
	)
	(segment
		(start 84.367116 -247.989852)
		(end 84.52104 -247.724422)
		(width 0.0889)
		(layer "In11.Cu")
		(net "M_F_CPU1_SA_CB<4>")
	)
	(segment
		(start 52.691284 -241.27333)
		(end 52.691284 -242.687856)
		(width 0.14478)
		(layer "In11.Cu")
		(net "M_F_CPU1_SA_CB<4>")
	)
	(segment
		(start 59.792616 -242.127786)
		(end 65.445894 -247.781064)
		(width 0.14478)
		(layer "In11.Cu")
		(net "M_F_CPU1_SA_CB<4>")
	)
	(segment
		(start 56.341518 -242.816126)
		(end 56.571896 -242.816126)
		(width 0.14478)
		(layer "In11.Cu")
		(net "M_F_CPU1_SA_CB<4>")
	)
	(segment
		(start 84.271104 -248.015252)
		(end 84.367116 -247.989852)
		(width 0.0889)
		(layer "In11.Cu")
		(net "M_F_CPU1_SA_CB<4>")
	)
	(segment
		(start 56.734964 -242.653058)
		(end 56.734964 -241.27333)
		(width 0.14478)
		(layer "In11.Cu")
		(net "M_F_CPU1_SA_CB<4>")
	)
	(segment
		(start 81.879694 -248.051828)
		(end 81.888076 -248.047002)
		(width 0.0889)
		(layer "In11.Cu")
		(net "M_F_CPU1_SA_CB<4>")
	)
	(segment
		(start 76.034392 -248.350786)
		(end 77.643228 -248.350786)
		(width 0.0889)
		(layer "In11.Cu")
		(net "M_F_CPU1_SA_CB<4>")
	)
	(segment
		(start 52.537868 -241.119914)
		(end 52.691284 -241.27333)
		(width 0.14478)
		(layer "In11.Cu")
		(net "M_F_CPU1_SA_CB<4>")
	)
	(segment
		(start 56.17845 -242.653058)
		(end 56.341518 -242.816126)
		(width 0.14478)
		(layer "In11.Cu")
		(net "M_F_CPU1_SA_CB<4>")
	)
	(segment
		(start 56.734964 -241.27333)
		(end 56.898032 -241.110262)
		(width 0.14478)
		(layer "In11.Cu")
		(net "M_F_CPU1_SA_CB<4>")
	)
	(segment
		(start 53.96738 -242.850924)
		(end 54.197758 -242.850924)
		(width 0.14478)
		(layer "In11.Cu")
		(net "M_F_CPU1_SA_CB<4>")
	)
	(segment
		(start 82.453988 -248.047002)
		(end 82.46237 -248.051828)
		(width 0.0889)
		(layer "In11.Cu")
		(net "M_F_CPU1_SA_CB<4>")
	)
	(segment
		(start 57.12841 -241.110262)
		(end 57.291478 -241.27333)
		(width 0.14478)
		(layer "In11.Cu")
		(net "M_F_CPU1_SA_CB<4>")
	)
	(segment
		(start 57.291478 -241.983006)
		(end 57.436258 -242.127786)
		(width 0.14478)
		(layer "In11.Cu")
		(net "M_F_CPU1_SA_CB<4>")
	)
	(segment
		(start 21.70811 -240.68532)
		(end 22.142704 -241.119914)
		(width 0.14478)
		(layer "In11.Cu")
		(net "M_F_CPU1_SA_CB<4>")
	)
	(segment
		(start 53.247798 -242.687856)
		(end 53.247798 -241.27333)
		(width 0.14478)
		(layer "In11.Cu")
		(net "M_F_CPU1_SA_CB<4>")
	)
	(segment
		(start 54.360826 -242.687856)
		(end 54.360826 -241.27333)
		(width 0.14478)
		(layer "In11.Cu")
		(net "M_F_CPU1_SA_CB<4>")
	)
	(segment
		(start 53.08473 -242.850924)
		(end 53.247798 -242.687856)
		(width 0.14478)
		(layer "In11.Cu")
		(net "M_F_CPU1_SA_CB<4>")
	)
	(segment
		(start 22.142704 -241.119914)
		(end 52.537868 -241.119914)
		(width 0.14478)
		(layer "In11.Cu")
		(net "M_F_CPU1_SA_CB<4>")
	)
	(segment
		(start 77.643228 -248.350786)
		(end 78.086458 -248.062242)
		(width 0.0889)
		(layer "In11.Cu")
		(net "M_F_CPU1_SA_CB<4>")
	)
	(segment
		(start 56.571896 -242.816126)
		(end 56.734964 -242.653058)
		(width 0.14478)
		(layer "In11.Cu")
		(net "M_F_CPU1_SA_CB<4>")
	)
	(segment
		(start 54.197758 -242.850924)
		(end 54.360826 -242.687856)
		(width 0.14478)
		(layer "In11.Cu")
		(net "M_F_CPU1_SA_CB<4>")
	)
	(segment
		(start 79.0575 -248.05386)
		(end 79.069184 -248.047002)
		(width 0.0889)
		(layer "In11.Cu")
		(net "M_F_CPU1_SA_CB<4>")
	)
	(segment
		(start 53.410866 -241.110262)
		(end 53.641244 -241.110262)
		(width 0.14478)
		(layer "In11.Cu")
		(net "M_F_CPU1_SA_CB<4>")
	)
	(segment
		(start 79.634334 -248.046748)
		(end 79.65059 -248.056146)
		(width 0.0889)
		(layer "In11.Cu")
		(net "M_F_CPU1_SA_CB<4>")
	)
	(segment
		(start 57.436258 -242.127786)
		(end 59.792616 -242.127786)
		(width 0.14478)
		(layer "In11.Cu")
		(net "M_F_CPU1_SA_CB<4>")
	)
	(segment
		(start 54.523894 -241.110262)
		(end 56.015382 -241.110262)
		(width 0.14478)
		(layer "In11.Cu")
		(net "M_F_CPU1_SA_CB<4>")
	)
	(segment
		(start 56.898032 -241.110262)
		(end 57.12841 -241.110262)
		(width 0.14478)
		(layer "In11.Cu")
		(net "M_F_CPU1_SA_CB<4>")
	)
	(segment
		(start 56.015382 -241.110262)
		(end 56.17845 -241.27333)
		(width 0.14478)
		(layer "In11.Cu")
		(net "M_F_CPU1_SA_CB<4>")
	)
	(segment
		(start 74.59091 -247.781064)
		(end 75.155806 -248.34596)
		(width 0.14478)
		(layer "In11.Cu")
		(net "M_F_CPU1_SA_CB<4>")
	)
	(segment
		(start 52.854352 -242.850924)
		(end 53.08473 -242.850924)
		(width 0.14478)
		(layer "In11.Cu")
		(net "M_F_CPU1_SA_CB<4>")
	)
	(segment
		(start 65.445894 -247.781064)
		(end 74.59091 -247.781064)
		(width 0.14478)
		(layer "In11.Cu")
		(net "M_F_CPU1_SA_CB<4>")
	)
	(segment
		(start 76.029566 -248.34596)
		(end 76.034392 -248.350786)
		(width 0.0889)
		(layer "In11.Cu")
		(net "M_F_CPU1_SA_CB<4>")
	)
	(segment
		(start 53.804312 -241.27333)
		(end 53.804312 -242.687856)
		(width 0.14478)
		(layer "In11.Cu")
		(net "M_F_CPU1_SA_CB<4>")
	)
	(segment
		(start 57.291478 -241.27333)
		(end 57.291478 -241.983006)
		(width 0.14478)
		(layer "In11.Cu")
		(net "M_F_CPU1_SA_CB<4>")
	)
	(segment
		(start 53.641244 -241.110262)
		(end 53.804312 -241.27333)
		(width 0.14478)
		(layer "In11.Cu")
		(net "M_F_CPU1_SA_CB<4>")
	)
	(arc
		(start 81.888076 -248.047002)
		(mid 82.171032 -247.970825)
		(end 82.453988 -248.047002)
		(width 0.0889)
		(layer "In11.Cu")
		(net "M_F_CPU1_SA_CB<4>")
	)
	(arc
		(start 78.694788 -248.047002)
		(mid 78.875246 -248.097446)
		(end 79.0575 -248.05386)
		(width 0.0889)
		(layer "In11.Cu")
		(net "M_F_CPU1_SA_CB<4>")
	)
	(arc
		(start 82.46237 -248.051828)
		(mid 82.645878 -248.097322)
		(end 82.82813 -248.047002)
		(width 0.0889)
		(layer "In11.Cu")
		(net "M_F_CPU1_SA_CB<4>")
	)
	(arc
		(start 80.948022 -248.047002)
		(mid 81.230978 -247.970825)
		(end 81.513934 -248.047002)
		(width 0.0889)
		(layer "In11.Cu")
		(net "M_F_CPU1_SA_CB<4>")
	)
	(arc
		(start 80.008222 -248.047002)
		(mid 80.291178 -247.970825)
		(end 80.574134 -248.047002)
		(width 0.0889)
		(layer "In11.Cu")
		(net "M_F_CPU1_SA_CB<4>")
	)
	(arc
		(start 82.82813 -248.047002)
		(mid 83.111086 -247.970825)
		(end 83.394042 -248.047002)
		(width 0.0889)
		(layer "In11.Cu")
		(net "M_F_CPU1_SA_CB<4>")
	)
	(arc
		(start 78.086458 -248.062242)
		(mid 78.388457 -247.968484)
		(end 78.694788 -248.047002)
		(width 0.0889)
		(layer "In11.Cu")
		(net "M_F_CPU1_SA_CB<4>")
	)
	(arc
		(start 81.513934 -248.047002)
		(mid 81.696185 -248.097352)
		(end 81.879694 -248.051828)
		(width 0.0889)
		(layer "In11.Cu")
		(net "M_F_CPU1_SA_CB<4>")
	)
	(arc
		(start 80.574134 -248.047002)
		(mid 80.761078 -248.097257)
		(end 80.948022 -248.047002)
		(width 0.0889)
		(layer "In11.Cu")
		(net "M_F_CPU1_SA_CB<4>")
	)
	(arc
		(start 83.402424 -248.051828)
		(mid 83.585932 -248.097322)
		(end 83.768184 -248.047002)
		(width 0.0889)
		(layer "In11.Cu")
		(net "M_F_CPU1_SA_CB<4>")
	)
	(arc
		(start 79.65059 -248.056146)
		(mid 79.830572 -248.097246)
		(end 80.008222 -248.047002)
		(width 0.0889)
		(layer "In11.Cu")
		(net "M_F_CPU1_SA_CB<4>")
	)
	(arc
		(start 79.069184 -248.047002)
		(mid 79.344862 -247.970872)
		(end 79.622396 -248.03989)
		(width 0.0889)
		(layer "In11.Cu")
		(net "M_F_CPU1_SA_CB<4>")
	)
	(arc
		(start 83.768184 -248.047002)
		(mid 84.015897 -247.971782)
		(end 84.271104 -248.015252)
		(width 0.0889)
		(layer "In11.Cu")
		(net "M_F_CPU1_SA_CB<4>")
	)
	(segment
		(start 85.927946 -246.370348)
		(end 85.461094 -246.10441)
		(width 0.10668)
		(layer "F.Cu")
		(net "M_F_CPU1_SA_CB<3>")
	)
	(segment
		(start 76.065888 -245.874286)
		(end 78.601316 -245.874286)
		(width 0.0889)
		(layer "In11.Cu")
		(net "M_F_CPU1_SA_CB<3>")
	)
	(segment
		(start 27.587448 -236.850682)
		(end 30.534102 -236.850682)
		(width 0.14478)
		(layer "In11.Cu")
		(net "M_F_CPU1_SA_CB<3>")
	)
	(segment
		(start 75.633326 -245.441724)
		(end 75.999086 -245.807484)
		(width 0.14478)
		(layer "In11.Cu")
		(net "M_F_CPU1_SA_CB<3>")
	)
	(segment
		(start 19.040094 -236.839252)
		(end 19.203162 -236.676184)
		(width 0.14478)
		(layer "In11.Cu")
		(net "M_F_CPU1_SA_CB<3>")
	)
	(segment
		(start 78.693772 -245.78183)
		(end 78.705456 -245.774972)
		(width 0.0889)
		(layer "In11.Cu")
		(net "M_F_CPU1_SA_CB<3>")
	)
	(segment
		(start 49.399698 -237.700566)
		(end 50.249582 -236.850682)
		(width 0.14478)
		(layer "In11.Cu")
		(net "M_F_CPU1_SA_CB<3>")
	)
	(segment
		(start 83.394042 -245.78183)
		(end 83.402424 -245.777004)
		(width 0.0889)
		(layer "In11.Cu")
		(net "M_F_CPU1_SA_CB<3>")
	)
	(segment
		(start 38.95344 -237.700566)
		(end 41.901872 -237.700566)
		(width 0.14478)
		(layer "In11.Cu")
		(net "M_F_CPU1_SA_CB<3>")
	)
	(segment
		(start 53.616098 -237.321344)
		(end 57.32526 -237.321344)
		(width 0.14478)
		(layer "In11.Cu")
		(net "M_F_CPU1_SA_CB<3>")
	)
	(segment
		(start 53.145436 -236.850682)
		(end 53.616098 -237.321344)
		(width 0.14478)
		(layer "In11.Cu")
		(net "M_F_CPU1_SA_CB<3>")
	)
	(segment
		(start 57.78627 -236.860334)
		(end 58.500772 -236.860334)
		(width 0.14478)
		(layer "In11.Cu")
		(net "M_F_CPU1_SA_CB<3>")
	)
	(segment
		(start 45.609002 -236.850682)
		(end 46.458886 -237.700566)
		(width 0.14478)
		(layer "In11.Cu")
		(net "M_F_CPU1_SA_CB<3>")
	)
	(segment
		(start 19.596608 -236.839252)
		(end 19.596608 -237.547404)
		(width 0.14478)
		(layer "In11.Cu")
		(net "M_F_CPU1_SA_CB<3>")
	)
	(segment
		(start 67.082162 -245.441724)
		(end 75.633326 -245.441724)
		(width 0.14478)
		(layer "In11.Cu")
		(net "M_F_CPU1_SA_CB<3>")
	)
	(segment
		(start 50.249582 -236.850682)
		(end 53.145436 -236.850682)
		(width 0.14478)
		(layer "In11.Cu")
		(net "M_F_CPU1_SA_CB<3>")
	)
	(segment
		(start 34.368486 -237.700566)
		(end 35.21837 -236.850682)
		(width 0.14478)
		(layer "In11.Cu")
		(net "M_F_CPU1_SA_CB<3>")
	)
	(segment
		(start 82.453988 -245.78183)
		(end 82.46237 -245.777004)
		(width 0.0889)
		(layer "In11.Cu")
		(net "M_F_CPU1_SA_CB<3>")
	)
	(segment
		(start 85.615018 -245.83898)
		(end 85.461094 -246.10441)
		(width 0.0889)
		(layer "In11.Cu")
		(net "M_F_CPU1_SA_CB<3>")
	)
	(segment
		(start 19.203162 -236.676184)
		(end 19.43354 -236.676184)
		(width 0.14478)
		(layer "In11.Cu")
		(net "M_F_CPU1_SA_CB<3>")
	)
	(segment
		(start 31.383986 -237.700566)
		(end 34.368486 -237.700566)
		(width 0.14478)
		(layer "In11.Cu")
		(net "M_F_CPU1_SA_CB<3>")
	)
	(segment
		(start 19.040094 -237.547404)
		(end 19.040094 -236.839252)
		(width 0.14478)
		(layer "In11.Cu")
		(net "M_F_CPU1_SA_CB<3>")
	)
	(segment
		(start 26.737564 -237.700566)
		(end 27.587448 -236.850682)
		(width 0.14478)
		(layer "In11.Cu")
		(net "M_F_CPU1_SA_CB<3>")
	)
	(segment
		(start 42.751756 -236.850682)
		(end 45.609002 -236.850682)
		(width 0.14478)
		(layer "In11.Cu")
		(net "M_F_CPU1_SA_CB<3>")
	)
	(segment
		(start 41.901872 -237.700566)
		(end 42.751756 -236.850682)
		(width 0.14478)
		(layer "In11.Cu")
		(net "M_F_CPU1_SA_CB<3>")
	)
	(segment
		(start 19.74977 -237.700566)
		(end 26.737564 -237.700566)
		(width 0.14478)
		(layer "In11.Cu")
		(net "M_F_CPU1_SA_CB<3>")
	)
	(segment
		(start 75.999086 -245.807484)
		(end 76.065888 -245.874286)
		(width 0.0889)
		(layer "In11.Cu")
		(net "M_F_CPU1_SA_CB<3>")
	)
	(segment
		(start 17.608042 -237.285276)
		(end 18.033238 -237.710472)
		(width 0.14478)
		(layer "In11.Cu")
		(net "M_F_CPU1_SA_CB<3>")
	)
	(segment
		(start 78.601316 -245.874286)
		(end 78.693772 -245.78183)
		(width 0.0889)
		(layer "In11.Cu")
		(net "M_F_CPU1_SA_CB<3>")
	)
	(segment
		(start 46.458886 -237.700566)
		(end 49.399698 -237.700566)
		(width 0.14478)
		(layer "In11.Cu")
		(net "M_F_CPU1_SA_CB<3>")
	)
	(segment
		(start 79.06766 -245.78183)
		(end 79.078074 -245.787926)
		(width 0.0889)
		(layer "In11.Cu")
		(net "M_F_CPU1_SA_CB<3>")
	)
	(segment
		(start 35.21837 -236.850682)
		(end 38.103556 -236.850682)
		(width 0.14478)
		(layer "In11.Cu")
		(net "M_F_CPU1_SA_CB<3>")
	)
	(segment
		(start 19.596608 -237.547404)
		(end 19.74977 -237.700566)
		(width 0.14478)
		(layer "In11.Cu")
		(net "M_F_CPU1_SA_CB<3>")
	)
	(segment
		(start 30.534102 -236.850682)
		(end 31.383986 -237.700566)
		(width 0.14478)
		(layer "In11.Cu")
		(net "M_F_CPU1_SA_CB<3>")
	)
	(segment
		(start 19.43354 -236.676184)
		(end 19.596608 -236.839252)
		(width 0.14478)
		(layer "In11.Cu")
		(net "M_F_CPU1_SA_CB<3>")
	)
	(segment
		(start 85.592666 -245.755668)
		(end 85.615018 -245.83898)
		(width 0.0889)
		(layer "In11.Cu")
		(net "M_F_CPU1_SA_CB<3>")
	)
	(segment
		(start 57.32526 -237.321344)
		(end 57.78627 -236.860334)
		(width 0.14478)
		(layer "In11.Cu")
		(net "M_F_CPU1_SA_CB<3>")
	)
	(segment
		(start 38.103556 -236.850682)
		(end 38.95344 -237.700566)
		(width 0.14478)
		(layer "In11.Cu")
		(net "M_F_CPU1_SA_CB<3>")
	)
	(segment
		(start 58.500772 -236.860334)
		(end 67.082162 -245.441724)
		(width 0.14478)
		(layer "In11.Cu")
		(net "M_F_CPU1_SA_CB<3>")
	)
	(segment
		(start 18.877026 -237.710472)
		(end 19.040094 -237.547404)
		(width 0.14478)
		(layer "In11.Cu")
		(net "M_F_CPU1_SA_CB<3>")
	)
	(segment
		(start 18.033238 -237.710472)
		(end 18.877026 -237.710472)
		(width 0.14478)
		(layer "In11.Cu")
		(net "M_F_CPU1_SA_CB<3>")
	)
	(segment
		(start 81.879694 -245.777004)
		(end 81.888076 -245.78183)
		(width 0.0889)
		(layer "In11.Cu")
		(net "M_F_CPU1_SA_CB<3>")
	)
	(arc
		(start 81.888076 -245.78183)
		(mid 82.171032 -245.858007)
		(end 82.453988 -245.78183)
		(width 0.0889)
		(layer "In11.Cu")
		(net "M_F_CPU1_SA_CB<3>")
	)
	(arc
		(start 84.707984 -245.78183)
		(mid 84.99094 -245.858007)
		(end 85.273896 -245.78183)
		(width 0.0889)
		(layer "In11.Cu")
		(net "M_F_CPU1_SA_CB<3>")
	)
	(arc
		(start 80.574134 -245.78183)
		(mid 80.761078 -245.731575)
		(end 80.948022 -245.78183)
		(width 0.0889)
		(layer "In11.Cu")
		(net "M_F_CPU1_SA_CB<3>")
	)
	(arc
		(start 82.82813 -245.78183)
		(mid 83.111086 -245.858007)
		(end 83.394042 -245.78183)
		(width 0.0889)
		(layer "In11.Cu")
		(net "M_F_CPU1_SA_CB<3>")
	)
	(arc
		(start 82.46237 -245.777004)
		(mid 82.645878 -245.73151)
		(end 82.82813 -245.78183)
		(width 0.0889)
		(layer "In11.Cu")
		(net "M_F_CPU1_SA_CB<3>")
	)
	(arc
		(start 78.705456 -245.774972)
		(mid 78.887457 -245.731439)
		(end 79.06766 -245.78183)
		(width 0.0889)
		(layer "In11.Cu")
		(net "M_F_CPU1_SA_CB<3>")
	)
	(arc
		(start 79.078074 -245.787926)
		(mid 79.35676 -245.858146)
		(end 79.633826 -245.78183)
		(width 0.0889)
		(layer "In11.Cu")
		(net "M_F_CPU1_SA_CB<3>")
	)
	(arc
		(start 80.948022 -245.78183)
		(mid 81.230978 -245.858007)
		(end 81.513934 -245.78183)
		(width 0.0889)
		(layer "In11.Cu")
		(net "M_F_CPU1_SA_CB<3>")
	)
	(arc
		(start 83.768184 -245.78183)
		(mid 84.05114 -245.858007)
		(end 84.334096 -245.78183)
		(width 0.0889)
		(layer "In11.Cu")
		(net "M_F_CPU1_SA_CB<3>")
	)
	(arc
		(start 80.008222 -245.78183)
		(mid 80.291178 -245.858007)
		(end 80.574134 -245.78183)
		(width 0.0889)
		(layer "In11.Cu")
		(net "M_F_CPU1_SA_CB<3>")
	)
	(arc
		(start 85.273896 -245.78183)
		(mid 85.430334 -245.732859)
		(end 85.592666 -245.755668)
		(width 0.0889)
		(layer "In11.Cu")
		(net "M_F_CPU1_SA_CB<3>")
	)
	(arc
		(start 84.334096 -245.78183)
		(mid 84.52104 -245.731575)
		(end 84.707984 -245.78183)
		(width 0.0889)
		(layer "In11.Cu")
		(net "M_F_CPU1_SA_CB<3>")
	)
	(arc
		(start 79.633826 -245.78183)
		(mid 79.821024 -245.731448)
		(end 80.008222 -245.78183)
		(width 0.0889)
		(layer "In11.Cu")
		(net "M_F_CPU1_SA_CB<3>")
	)
	(arc
		(start 81.513934 -245.78183)
		(mid 81.696185 -245.73148)
		(end 81.879694 -245.777004)
		(width 0.0889)
		(layer "In11.Cu")
		(net "M_F_CPU1_SA_CB<3>")
	)
	(arc
		(start 83.402424 -245.777004)
		(mid 83.585932 -245.73151)
		(end 83.768184 -245.78183)
		(width 0.0889)
		(layer "In11.Cu")
		(net "M_F_CPU1_SA_CB<3>")
	)
	(segment
		(start 84.517992 -245.560342)
		(end 84.05114 -245.294404)
		(width 0.10668)
		(layer "F.Cu")
		(net "M_F_CPU1_SA_CB<2>")
	)
	(segment
		(start 38.113208 -235.160312)
		(end 38.963346 -236.01045)
		(width 0.14478)
		(layer "In11.Cu")
		(net "M_F_CPU1_SA_CB<2>")
	)
	(segment
		(start 34.35858 -236.01045)
		(end 35.208718 -235.160312)
		(width 0.14478)
		(layer "In11.Cu")
		(net "M_F_CPU1_SA_CB<2>")
	)
	(segment
		(start 84.205064 -245.028974)
		(end 84.05114 -245.294404)
		(width 0.0889)
		(layer "In11.Cu")
		(net "M_F_CPU1_SA_CB<2>")
	)
	(segment
		(start 45.618654 -235.160312)
		(end 46.468792 -236.01045)
		(width 0.14478)
		(layer "In11.Cu")
		(net "M_F_CPU1_SA_CB<2>")
	)
	(segment
		(start 53.155088 -235.160312)
		(end 54.005226 -236.01045)
		(width 0.14478)
		(layer "In11.Cu")
		(net "M_F_CPU1_SA_CB<2>")
	)
	(segment
		(start 67.459098 -244.532404)
		(end 75.933046 -244.532404)
		(width 0.14478)
		(layer "In11.Cu")
		(net "M_F_CPU1_SA_CB<2>")
	)
	(segment
		(start 77.167486 -245.233444)
		(end 77.352906 -245.048024)
		(width 0.0889)
		(layer "In11.Cu")
		(net "M_F_CPU1_SA_CB<2>")
	)
	(segment
		(start 38.963346 -236.01045)
		(end 41.891966 -236.01045)
		(width 0.14478)
		(layer "In11.Cu")
		(net "M_F_CPU1_SA_CB<2>")
	)
	(segment
		(start 20.683728 -236.01045)
		(end 26.727658 -236.01045)
		(width 0.14478)
		(layer "In11.Cu")
		(net "M_F_CPU1_SA_CB<2>")
	)
	(segment
		(start 19.407632 -235.396532)
		(end 19.407632 -235.847382)
		(width 0.14478)
		(layer "In11.Cu")
		(net "M_F_CPU1_SA_CB<2>")
	)
	(segment
		(start 35.208718 -235.160312)
		(end 38.113208 -235.160312)
		(width 0.14478)
		(layer "In11.Cu")
		(net "M_F_CPU1_SA_CB<2>")
	)
	(segment
		(start 18.851118 -235.847382)
		(end 18.851118 -235.396532)
		(width 0.14478)
		(layer "In11.Cu")
		(net "M_F_CPU1_SA_CB<2>")
	)
	(segment
		(start 19.964146 -235.847382)
		(end 19.964146 -235.396532)
		(width 0.14478)
		(layer "In11.Cu")
		(net "M_F_CPU1_SA_CB<2>")
	)
	(segment
		(start 49.389792 -236.01045)
		(end 50.23993 -235.160312)
		(width 0.14478)
		(layer "In11.Cu")
		(net "M_F_CPU1_SA_CB<2>")
	)
	(segment
		(start 54.005226 -236.01045)
		(end 56.936132 -236.01045)
		(width 0.14478)
		(layer "In11.Cu")
		(net "M_F_CPU1_SA_CB<2>")
	)
	(segment
		(start 50.23993 -235.160312)
		(end 53.155088 -235.160312)
		(width 0.14478)
		(layer "In11.Cu")
		(net "M_F_CPU1_SA_CB<2>")
	)
	(segment
		(start 79.53883 -244.972078)
		(end 79.550768 -244.978936)
		(width 0.0889)
		(layer "In11.Cu")
		(net "M_F_CPU1_SA_CB<2>")
	)
	(segment
		(start 79.525114 -244.964204)
		(end 79.53883 -244.972078)
		(width 0.0889)
		(layer "In11.Cu")
		(net "M_F_CPU1_SA_CB<2>")
	)
	(segment
		(start 46.468792 -236.01045)
		(end 49.389792 -236.01045)
		(width 0.14478)
		(layer "In11.Cu")
		(net "M_F_CPU1_SA_CB<2>")
	)
	(segment
		(start 20.52066 -235.396532)
		(end 20.52066 -235.847382)
		(width 0.14478)
		(layer "In11.Cu")
		(net "M_F_CPU1_SA_CB<2>")
	)
	(segment
		(start 19.964146 -235.396532)
		(end 20.127214 -235.233464)
		(width 0.14478)
		(layer "In11.Cu")
		(net "M_F_CPU1_SA_CB<2>")
	)
	(segment
		(start 26.727658 -236.01045)
		(end 27.577796 -235.160312)
		(width 0.14478)
		(layer "In11.Cu")
		(net "M_F_CPU1_SA_CB<2>")
	)
	(segment
		(start 56.936132 -236.01045)
		(end 57.196736 -235.749846)
		(width 0.14478)
		(layer "In11.Cu")
		(net "M_F_CPU1_SA_CB<2>")
	)
	(segment
		(start 31.393892 -236.01045)
		(end 34.35858 -236.01045)
		(width 0.14478)
		(layer "In11.Cu")
		(net "M_F_CPU1_SA_CB<2>")
	)
	(segment
		(start 27.577796 -235.160312)
		(end 30.543754 -235.160312)
		(width 0.14478)
		(layer "In11.Cu")
		(net "M_F_CPU1_SA_CB<2>")
	)
	(segment
		(start 78.212696 -244.978936)
		(end 78.224634 -244.972078)
		(width 0.0889)
		(layer "In11.Cu")
		(net "M_F_CPU1_SA_CB<2>")
	)
	(segment
		(start 81.044034 -244.971824)
		(end 81.052416 -244.966998)
		(width 0.0889)
		(layer "In11.Cu")
		(net "M_F_CPU1_SA_CB<2>")
	)
	(segment
		(start 19.801078 -236.01045)
		(end 19.964146 -235.847382)
		(width 0.14478)
		(layer "In11.Cu")
		(net "M_F_CPU1_SA_CB<2>")
	)
	(segment
		(start 79.147162 -244.982492)
		(end 79.165196 -244.971824)
		(width 0.0889)
		(layer "In11.Cu")
		(net "M_F_CPU1_SA_CB<2>")
	)
	(segment
		(start 17.608042 -235.585254)
		(end 18.033238 -236.01045)
		(width 0.14478)
		(layer "In11.Cu")
		(net "M_F_CPU1_SA_CB<2>")
	)
	(segment
		(start 19.014186 -235.233464)
		(end 19.244564 -235.233464)
		(width 0.14478)
		(layer "In11.Cu")
		(net "M_F_CPU1_SA_CB<2>")
	)
	(segment
		(start 18.033238 -236.01045)
		(end 18.68805 -236.01045)
		(width 0.14478)
		(layer "In11.Cu")
		(net "M_F_CPU1_SA_CB<2>")
	)
	(segment
		(start 84.182712 -244.945662)
		(end 84.205064 -245.028974)
		(width 0.0889)
		(layer "In11.Cu")
		(net "M_F_CPU1_SA_CB<2>")
	)
	(segment
		(start 76.075286 -244.532404)
		(end 76.776326 -245.233444)
		(width 0.0889)
		(layer "In11.Cu")
		(net "M_F_CPU1_SA_CB<2>")
	)
	(segment
		(start 20.52066 -235.847382)
		(end 20.683728 -236.01045)
		(width 0.14478)
		(layer "In11.Cu")
		(net "M_F_CPU1_SA_CB<2>")
	)
	(segment
		(start 19.244564 -235.233464)
		(end 19.407632 -235.396532)
		(width 0.14478)
		(layer "In11.Cu")
		(net "M_F_CPU1_SA_CB<2>")
	)
	(segment
		(start 78.224634 -244.972078)
		(end 78.2447 -244.960648)
		(width 0.0889)
		(layer "In11.Cu")
		(net "M_F_CPU1_SA_CB<2>")
	)
	(segment
		(start 76.776326 -245.233444)
		(end 77.167486 -245.233444)
		(width 0.0889)
		(layer "In11.Cu")
		(net "M_F_CPU1_SA_CB<2>")
	)
	(segment
		(start 75.933046 -244.532404)
		(end 76.075286 -244.532404)
		(width 0.0889)
		(layer "In11.Cu")
		(net "M_F_CPU1_SA_CB<2>")
	)
	(segment
		(start 30.543754 -235.160312)
		(end 31.393892 -236.01045)
		(width 0.14478)
		(layer "In11.Cu")
		(net "M_F_CPU1_SA_CB<2>")
	)
	(segment
		(start 80.46974 -244.966998)
		(end 80.478122 -244.971824)
		(width 0.0889)
		(layer "In11.Cu")
		(net "M_F_CPU1_SA_CB<2>")
	)
	(segment
		(start 42.742104 -235.160312)
		(end 45.618654 -235.160312)
		(width 0.14478)
		(layer "In11.Cu")
		(net "M_F_CPU1_SA_CB<2>")
	)
	(segment
		(start 41.891966 -236.01045)
		(end 42.742104 -235.160312)
		(width 0.14478)
		(layer "In11.Cu")
		(net "M_F_CPU1_SA_CB<2>")
	)
	(segment
		(start 20.127214 -235.233464)
		(end 20.357592 -235.233464)
		(width 0.14478)
		(layer "In11.Cu")
		(net "M_F_CPU1_SA_CB<2>")
	)
	(segment
		(start 19.5707 -236.01045)
		(end 19.801078 -236.01045)
		(width 0.14478)
		(layer "In11.Cu")
		(net "M_F_CPU1_SA_CB<2>")
	)
	(segment
		(start 57.196736 -235.749846)
		(end 58.67654 -235.749846)
		(width 0.14478)
		(layer "In11.Cu")
		(net "M_F_CPU1_SA_CB<2>")
	)
	(segment
		(start 19.407632 -235.847382)
		(end 19.5707 -236.01045)
		(width 0.14478)
		(layer "In11.Cu")
		(net "M_F_CPU1_SA_CB<2>")
	)
	(segment
		(start 77.352906 -245.048024)
		(end 77.9399 -245.048024)
		(width 0.0889)
		(layer "In11.Cu")
		(net "M_F_CPU1_SA_CB<2>")
	)
	(segment
		(start 58.67654 -235.749846)
		(end 67.459098 -244.532404)
		(width 0.14478)
		(layer "In11.Cu")
		(net "M_F_CPU1_SA_CB<2>")
	)
	(segment
		(start 18.851118 -235.396532)
		(end 19.014186 -235.233464)
		(width 0.14478)
		(layer "In11.Cu")
		(net "M_F_CPU1_SA_CB<2>")
	)
	(segment
		(start 83.289648 -244.966998)
		(end 83.29803 -244.971824)
		(width 0.0889)
		(layer "In11.Cu")
		(net "M_F_CPU1_SA_CB<2>")
	)
	(segment
		(start 20.357592 -235.233464)
		(end 20.52066 -235.396532)
		(width 0.14478)
		(layer "In11.Cu")
		(net "M_F_CPU1_SA_CB<2>")
	)
	(segment
		(start 18.68805 -236.01045)
		(end 18.851118 -235.847382)
		(width 0.14478)
		(layer "In11.Cu")
		(net "M_F_CPU1_SA_CB<2>")
	)
	(arc
		(start 79.550768 -244.978936)
		(mid 79.828302 -245.047917)
		(end 80.10398 -244.971824)
		(width 0.0889)
		(layer "In11.Cu")
		(net "M_F_CPU1_SA_CB<2>")
	)
	(arc
		(start 82.357976 -244.971824)
		(mid 82.640932 -245.048001)
		(end 82.923888 -244.971824)
		(width 0.0889)
		(layer "In11.Cu")
		(net "M_F_CPU1_SA_CB<2>")
	)
	(arc
		(start 81.052416 -244.966998)
		(mid 81.235924 -244.921504)
		(end 81.418176 -244.971824)
		(width 0.0889)
		(layer "In11.Cu")
		(net "M_F_CPU1_SA_CB<2>")
	)
	(arc
		(start 78.2447 -244.960648)
		(mid 78.423032 -244.921551)
		(end 78.598522 -244.971824)
		(width 0.0889)
		(layer "In11.Cu")
		(net "M_F_CPU1_SA_CB<2>")
	)
	(arc
		(start 80.478122 -244.971824)
		(mid 80.761078 -245.048001)
		(end 81.044034 -244.971824)
		(width 0.0889)
		(layer "In11.Cu")
		(net "M_F_CPU1_SA_CB<2>")
	)
	(arc
		(start 81.418176 -244.971824)
		(mid 81.701132 -245.048001)
		(end 81.984088 -244.971824)
		(width 0.0889)
		(layer "In11.Cu")
		(net "M_F_CPU1_SA_CB<2>")
	)
	(arc
		(start 79.165196 -244.971824)
		(mid 79.344183 -244.921654)
		(end 79.525114 -244.964204)
		(width 0.0889)
		(layer "In11.Cu")
		(net "M_F_CPU1_SA_CB<2>")
	)
	(arc
		(start 83.29803 -244.971824)
		(mid 83.580986 -245.048001)
		(end 83.863942 -244.971824)
		(width 0.0889)
		(layer "In11.Cu")
		(net "M_F_CPU1_SA_CB<2>")
	)
	(arc
		(start 80.10398 -244.971824)
		(mid 80.286231 -244.921474)
		(end 80.46974 -244.966998)
		(width 0.0889)
		(layer "In11.Cu")
		(net "M_F_CPU1_SA_CB<2>")
	)
	(arc
		(start 83.863942 -244.971824)
		(mid 84.02038 -244.922853)
		(end 84.182712 -244.945662)
		(width 0.0889)
		(layer "In11.Cu")
		(net "M_F_CPU1_SA_CB<2>")
	)
	(arc
		(start 77.9399 -245.048024)
		(mid 78.080668 -245.030751)
		(end 78.212696 -244.978936)
		(width 0.0889)
		(layer "In11.Cu")
		(net "M_F_CPU1_SA_CB<2>")
	)
	(arc
		(start 82.923888 -244.971824)
		(mid 83.106139 -244.921474)
		(end 83.289648 -244.966998)
		(width 0.0889)
		(layer "In11.Cu")
		(net "M_F_CPU1_SA_CB<2>")
	)
	(arc
		(start 78.598522 -244.971824)
		(mid 78.871466 -245.048404)
		(end 79.147162 -244.982492)
		(width 0.0889)
		(layer "In11.Cu")
		(net "M_F_CPU1_SA_CB<2>")
	)
	(arc
		(start 81.984088 -244.971824)
		(mid 82.171032 -244.921569)
		(end 82.357976 -244.971824)
		(width 0.0889)
		(layer "In11.Cu")
		(net "M_F_CPU1_SA_CB<2>")
	)
	(segment
		(start 86.397846 -245.560342)
		(end 85.930994 -245.294404)
		(width 0.10668)
		(layer "F.Cu")
		(net "M_F_CPU1_SA_CB<1>")
	)
	(segment
		(start 28.862274 -236.01045)
		(end 30.470856 -236.01045)
		(width 0.14478)
		(layer "In11.Cu")
		(net "M_F_CPU1_SA_CB<1>")
	)
	(segment
		(start 58.607452 -236.323886)
		(end 67.27063 -244.987064)
		(width 0.14478)
		(layer "In11.Cu")
		(net "M_F_CPU1_SA_CB<1>")
	)
	(segment
		(start 42.792904 -236.01045)
		(end 43.041316 -236.01045)
		(width 0.14478)
		(layer "In11.Cu")
		(net "M_F_CPU1_SA_CB<1>")
	)
	(segment
		(start 43.363134 -236.397546)
		(end 43.602148 -236.397546)
		(width 0.14478)
		(layer "In11.Cu")
		(net "M_F_CPU1_SA_CB<1>")
	)
	(segment
		(start 30.470856 -236.01045)
		(end 31.32074 -236.860334)
		(width 0.14478)
		(layer "In11.Cu")
		(net "M_F_CPU1_SA_CB<1>")
	)
	(segment
		(start 67.27063 -244.987064)
		(end 75.839066 -244.987064)
		(width 0.14478)
		(layer "In11.Cu")
		(net "M_F_CPU1_SA_CB<1>")
	)
	(segment
		(start 33.892998 -237.087156)
		(end 33.892998 -237.023402)
		(width 0.14478)
		(layer "In11.Cu")
		(net "M_F_CPU1_SA_CB<1>")
	)
	(segment
		(start 43.760898 -236.238796)
		(end 43.760898 -236.173518)
		(width 0.14478)
		(layer "In11.Cu")
		(net "M_F_CPU1_SA_CB<1>")
	)
	(segment
		(start 48.311308 -237.087156)
		(end 48.474376 -237.250224)
		(width 0.14478)
		(layer "In11.Cu")
		(net "M_F_CPU1_SA_CB<1>")
	)
	(segment
		(start 35.654234 -236.173518)
		(end 35.654234 -236.233716)
		(width 0.14478)
		(layer "In11.Cu")
		(net "M_F_CPU1_SA_CB<1>")
	)
	(segment
		(start 23.682452 -237.005114)
		(end 23.682452 -237.096046)
		(width 0.14478)
		(layer "In11.Cu")
		(net "M_F_CPU1_SA_CB<1>")
	)
	(segment
		(start 41.585388 -236.860334)
		(end 41.94302 -236.860334)
		(width 0.14478)
		(layer "In11.Cu")
		(net "M_F_CPU1_SA_CB<1>")
	)
	(segment
		(start 36.210748 -236.173518)
		(end 36.373816 -236.01045)
		(width 0.14478)
		(layer "In11.Cu")
		(net "M_F_CPU1_SA_CB<1>")
	)
	(segment
		(start 50.938938 -236.396784)
		(end 51.169316 -236.396784)
		(width 0.14478)
		(layer "In11.Cu")
		(net "M_F_CPU1_SA_CB<1>")
	)
	(segment
		(start 43.204384 -236.173518)
		(end 43.204384 -236.238796)
		(width 0.14478)
		(layer "In11.Cu")
		(net "M_F_CPU1_SA_CB<1>")
	)
	(segment
		(start 24.089106 -237.240826)
		(end 24.233886 -237.096046)
		(width 0.14478)
		(layer "In11.Cu")
		(net "M_F_CPU1_SA_CB<1>")
	)
	(segment
		(start 35.491166 -236.01045)
		(end 35.654234 -236.173518)
		(width 0.14478)
		(layer "In11.Cu")
		(net "M_F_CPU1_SA_CB<1>")
	)
	(segment
		(start 80.46974 -245.62181)
		(end 80.478122 -245.616984)
		(width 0.0889)
		(layer "In11.Cu")
		(net "M_F_CPU1_SA_CB<1>")
	)
	(segment
		(start 27.664664 -236.01045)
		(end 27.979624 -236.01045)
		(width 0.14478)
		(layer "In11.Cu")
		(net "M_F_CPU1_SA_CB<1>")
	)
	(segment
		(start 43.602148 -236.397546)
		(end 43.760898 -236.238796)
		(width 0.14478)
		(layer "In11.Cu")
		(net "M_F_CPU1_SA_CB<1>")
	)
	(segment
		(start 83.289648 -245.62181)
		(end 83.29803 -245.616984)
		(width 0.0889)
		(layer "In11.Cu")
		(net "M_F_CPU1_SA_CB<1>")
	)
	(segment
		(start 55.922926 -236.630972)
		(end 56.085994 -236.467904)
		(width 0.14478)
		(layer "In11.Cu")
		(net "M_F_CPU1_SA_CB<1>")
	)
	(segment
		(start 78.527148 -245.658386)
		(end 78.608174 -245.610888)
		(width 0.0889)
		(layer "In11.Cu")
		(net "M_F_CPU1_SA_CB<1>")
	)
	(segment
		(start 53.961792 -236.860334)
		(end 55.759858 -236.860334)
		(width 0.14478)
		(layer "In11.Cu")
		(net "M_F_CPU1_SA_CB<1>")
	)
	(segment
		(start 33.336484 -237.087156)
		(end 33.499552 -237.250224)
		(width 0.14478)
		(layer "In11.Cu")
		(net "M_F_CPU1_SA_CB<1>")
	)
	(segment
		(start 28.699206 -236.233716)
		(end 28.699206 -236.173518)
		(width 0.14478)
		(layer "In11.Cu")
		(net "M_F_CPU1_SA_CB<1>")
	)
	(segment
		(start 50.77587 -236.173518)
		(end 50.77587 -236.233716)
		(width 0.14478)
		(layer "In11.Cu")
		(net "M_F_CPU1_SA_CB<1>")
	)
	(segment
		(start 36.373816 -236.01045)
		(end 37.95268 -236.01045)
		(width 0.14478)
		(layer "In11.Cu")
		(net "M_F_CPU1_SA_CB<1>")
	)
	(segment
		(start 48.474376 -237.250224)
		(end 48.704754 -237.250224)
		(width 0.14478)
		(layer "In11.Cu")
		(net "M_F_CPU1_SA_CB<1>")
	)
	(segment
		(start 28.30576 -236.396784)
		(end 28.536138 -236.396784)
		(width 0.14478)
		(layer "In11.Cu")
		(net "M_F_CPU1_SA_CB<1>")
	)
	(segment
		(start 56.47944 -236.697266)
		(end 56.642508 -236.860334)
		(width 0.14478)
		(layer "In11.Cu")
		(net "M_F_CPU1_SA_CB<1>")
	)
	(segment
		(start 84.229702 -245.62181)
		(end 84.238084 -245.616984)
		(width 0.0889)
		(layer "In11.Cu")
		(net "M_F_CPU1_SA_CB<1>")
	)
	(segment
		(start 56.316372 -236.467904)
		(end 56.47944 -236.630972)
		(width 0.14478)
		(layer "In11.Cu")
		(net "M_F_CPU1_SA_CB<1>")
	)
	(segment
		(start 37.95268 -236.01045)
		(end 38.802564 -236.860334)
		(width 0.14478)
		(layer "In11.Cu")
		(net "M_F_CPU1_SA_CB<1>")
	)
	(segment
		(start 36.210748 -236.233716)
		(end 36.210748 -236.173518)
		(width 0.14478)
		(layer "In11.Cu")
		(net "M_F_CPU1_SA_CB<1>")
	)
	(segment
		(start 48.14824 -236.860334)
		(end 48.311308 -237.023402)
		(width 0.14478)
		(layer "In11.Cu")
		(net "M_F_CPU1_SA_CB<1>")
	)
	(segment
		(start 51.332384 -236.173518)
		(end 51.495452 -236.01045)
		(width 0.14478)
		(layer "In11.Cu")
		(net "M_F_CPU1_SA_CB<1>")
	)
	(segment
		(start 49.03089 -236.860334)
		(end 49.448974 -236.860334)
		(width 0.14478)
		(layer "In11.Cu")
		(net "M_F_CPU1_SA_CB<1>")
	)
	(segment
		(start 23.131018 -237.005114)
		(end 23.275798 -236.860334)
		(width 0.14478)
		(layer "In11.Cu")
		(net "M_F_CPU1_SA_CB<1>")
	)
	(segment
		(start 76.039726 -245.187724)
		(end 76.039726 -245.193312)
		(width 0.0889)
		(layer "In11.Cu")
		(net "M_F_CPU1_SA_CB<1>")
	)
	(segment
		(start 57.491122 -236.323886)
		(end 58.607452 -236.323886)
		(width 0.14478)
		(layer "In11.Cu")
		(net "M_F_CPU1_SA_CB<1>")
	)
	(segment
		(start 53.111908 -236.01045)
		(end 53.961792 -236.860334)
		(width 0.14478)
		(layer "In11.Cu")
		(net "M_F_CPU1_SA_CB<1>")
	)
	(segment
		(start 33.173416 -236.860334)
		(end 33.336484 -237.023402)
		(width 0.14478)
		(layer "In11.Cu")
		(net "M_F_CPU1_SA_CB<1>")
	)
	(segment
		(start 33.72993 -237.250224)
		(end 33.892998 -237.087156)
		(width 0.14478)
		(layer "In11.Cu")
		(net "M_F_CPU1_SA_CB<1>")
	)
	(segment
		(start 21.70811 -236.435392)
		(end 22.133052 -236.860334)
		(width 0.14478)
		(layer "In11.Cu")
		(net "M_F_CPU1_SA_CB<1>")
	)
	(segment
		(start 23.827232 -237.240826)
		(end 24.089106 -237.240826)
		(width 0.14478)
		(layer "In11.Cu")
		(net "M_F_CPU1_SA_CB<1>")
	)
	(segment
		(start 78.25867 -245.616984)
		(end 78.300072 -245.658386)
		(width 0.0889)
		(layer "In11.Cu")
		(net "M_F_CPU1_SA_CB<1>")
	)
	(segment
		(start 25.976834 -236.860334)
		(end 26.263346 -237.146846)
		(width 0.14478)
		(layer "In11.Cu")
		(net "M_F_CPU1_SA_CB<1>")
	)
	(segment
		(start 43.923966 -236.01045)
		(end 45.567854 -236.01045)
		(width 0.14478)
		(layer "In11.Cu")
		(net "M_F_CPU1_SA_CB<1>")
	)
	(segment
		(start 84.803996 -245.616984)
		(end 84.812378 -245.62181)
		(width 0.0889)
		(layer "In11.Cu")
		(net "M_F_CPU1_SA_CB<1>")
	)
	(segment
		(start 40.865806 -237.023402)
		(end 40.865806 -237.087156)
		(width 0.14478)
		(layer "In11.Cu")
		(net "M_F_CPU1_SA_CB<1>")
	)
	(segment
		(start 48.311308 -237.023402)
		(end 48.311308 -237.087156)
		(width 0.14478)
		(layer "In11.Cu")
		(net "M_F_CPU1_SA_CB<1>")
	)
	(segment
		(start 35.654234 -236.233716)
		(end 35.817302 -236.396784)
		(width 0.14478)
		(layer "In11.Cu")
		(net "M_F_CPU1_SA_CB<1>")
	)
	(segment
		(start 56.47944 -236.630972)
		(end 56.47944 -236.697266)
		(width 0.14478)
		(layer "In11.Cu")
		(net "M_F_CPU1_SA_CB<1>")
	)
	(segment
		(start 43.760898 -236.173518)
		(end 43.923966 -236.01045)
		(width 0.14478)
		(layer "In11.Cu")
		(net "M_F_CPU1_SA_CB<1>")
	)
	(segment
		(start 23.682452 -237.096046)
		(end 23.827232 -237.240826)
		(width 0.14478)
		(layer "In11.Cu")
		(net "M_F_CPU1_SA_CB<1>")
	)
	(segment
		(start 33.336484 -237.023402)
		(end 33.336484 -237.087156)
		(width 0.14478)
		(layer "In11.Cu")
		(net "M_F_CPU1_SA_CB<1>")
	)
	(segment
		(start 55.922926 -236.697266)
		(end 55.922926 -236.630972)
		(width 0.14478)
		(layer "In11.Cu")
		(net "M_F_CPU1_SA_CB<1>")
	)
	(segment
		(start 50.298858 -236.01045)
		(end 50.612802 -236.01045)
		(width 0.14478)
		(layer "In11.Cu")
		(net "M_F_CPU1_SA_CB<1>")
	)
	(segment
		(start 22.133052 -236.860334)
		(end 22.434804 -236.860334)
		(width 0.14478)
		(layer "In11.Cu")
		(net "M_F_CPU1_SA_CB<1>")
	)
	(segment
		(start 33.499552 -237.250224)
		(end 33.72993 -237.250224)
		(width 0.14478)
		(layer "In11.Cu")
		(net "M_F_CPU1_SA_CB<1>")
	)
	(segment
		(start 22.434804 -236.860334)
		(end 22.579584 -237.005114)
		(width 0.14478)
		(layer "In11.Cu")
		(net "M_F_CPU1_SA_CB<1>")
	)
	(segment
		(start 26.263346 -237.146846)
		(end 26.528268 -237.146846)
		(width 0.14478)
		(layer "In11.Cu")
		(net "M_F_CPU1_SA_CB<1>")
	)
	(segment
		(start 56.085994 -236.467904)
		(end 56.316372 -236.467904)
		(width 0.14478)
		(layer "In11.Cu")
		(net "M_F_CPU1_SA_CB<1>")
	)
	(segment
		(start 45.567854 -236.01045)
		(end 46.417738 -236.860334)
		(width 0.14478)
		(layer "In11.Cu")
		(net "M_F_CPU1_SA_CB<1>")
	)
	(segment
		(start 41.259252 -237.250224)
		(end 41.42232 -237.087156)
		(width 0.14478)
		(layer "In11.Cu")
		(net "M_F_CPU1_SA_CB<1>")
	)
	(segment
		(start 56.954674 -236.860334)
		(end 57.491122 -236.323886)
		(width 0.14478)
		(layer "In11.Cu")
		(net "M_F_CPU1_SA_CB<1>")
	)
	(segment
		(start 48.867822 -237.023402)
		(end 49.03089 -236.860334)
		(width 0.14478)
		(layer "In11.Cu")
		(net "M_F_CPU1_SA_CB<1>")
	)
	(segment
		(start 85.77707 -245.559834)
		(end 85.930994 -245.294404)
		(width 0.0889)
		(layer "In11.Cu")
		(net "M_F_CPU1_SA_CB<1>")
	)
	(segment
		(start 36.04768 -236.396784)
		(end 36.210748 -236.233716)
		(width 0.14478)
		(layer "In11.Cu")
		(net "M_F_CPU1_SA_CB<1>")
	)
	(segment
		(start 34.056066 -236.860334)
		(end 34.383218 -236.860334)
		(width 0.14478)
		(layer "In11.Cu")
		(net "M_F_CPU1_SA_CB<1>")
	)
	(segment
		(start 40.702738 -236.860334)
		(end 40.865806 -237.023402)
		(width 0.14478)
		(layer "In11.Cu")
		(net "M_F_CPU1_SA_CB<1>")
	)
	(segment
		(start 41.42232 -237.023402)
		(end 41.585388 -236.860334)
		(width 0.14478)
		(layer "In11.Cu")
		(net "M_F_CPU1_SA_CB<1>")
	)
	(segment
		(start 50.612802 -236.01045)
		(end 50.77587 -236.173518)
		(width 0.14478)
		(layer "In11.Cu")
		(net "M_F_CPU1_SA_CB<1>")
	)
	(segment
		(start 41.42232 -237.087156)
		(end 41.42232 -237.023402)
		(width 0.14478)
		(layer "In11.Cu")
		(net "M_F_CPU1_SA_CB<1>")
	)
	(segment
		(start 48.704754 -237.250224)
		(end 48.867822 -237.087156)
		(width 0.14478)
		(layer "In11.Cu")
		(net "M_F_CPU1_SA_CB<1>")
	)
	(segment
		(start 35.817302 -236.396784)
		(end 36.04768 -236.396784)
		(width 0.14478)
		(layer "In11.Cu")
		(net "M_F_CPU1_SA_CB<1>")
	)
	(segment
		(start 50.77587 -236.233716)
		(end 50.938938 -236.396784)
		(width 0.14478)
		(layer "In11.Cu")
		(net "M_F_CPU1_SA_CB<1>")
	)
	(segment
		(start 76.039726 -245.193312)
		(end 76.463398 -245.616984)
		(width 0.0889)
		(layer "In11.Cu")
		(net "M_F_CPU1_SA_CB<1>")
	)
	(segment
		(start 48.867822 -237.087156)
		(end 48.867822 -237.023402)
		(width 0.14478)
		(layer "In11.Cu")
		(net "M_F_CPU1_SA_CB<1>")
	)
	(segment
		(start 41.94302 -236.860334)
		(end 42.792904 -236.01045)
		(width 0.14478)
		(layer "In11.Cu")
		(net "M_F_CPU1_SA_CB<1>")
	)
	(segment
		(start 22.579584 -237.096046)
		(end 22.724364 -237.240826)
		(width 0.14478)
		(layer "In11.Cu")
		(net "M_F_CPU1_SA_CB<1>")
	)
	(segment
		(start 27.979624 -236.01045)
		(end 28.142692 -236.173518)
		(width 0.14478)
		(layer "In11.Cu")
		(net "M_F_CPU1_SA_CB<1>")
	)
	(segment
		(start 55.759858 -236.860334)
		(end 55.922926 -236.697266)
		(width 0.14478)
		(layer "In11.Cu")
		(net "M_F_CPU1_SA_CB<1>")
	)
	(segment
		(start 22.724364 -237.240826)
		(end 22.986238 -237.240826)
		(width 0.14478)
		(layer "In11.Cu")
		(net "M_F_CPU1_SA_CB<1>")
	)
	(segment
		(start 23.131018 -237.096046)
		(end 23.131018 -237.005114)
		(width 0.14478)
		(layer "In11.Cu")
		(net "M_F_CPU1_SA_CB<1>")
	)
	(segment
		(start 23.537672 -236.860334)
		(end 23.682452 -237.005114)
		(width 0.14478)
		(layer "In11.Cu")
		(net "M_F_CPU1_SA_CB<1>")
	)
	(segment
		(start 78.300072 -245.658386)
		(end 78.527148 -245.658386)
		(width 0.0889)
		(layer "In11.Cu")
		(net "M_F_CPU1_SA_CB<1>")
	)
	(segment
		(start 81.044034 -245.616984)
		(end 81.052416 -245.62181)
		(width 0.0889)
		(layer "In11.Cu")
		(net "M_F_CPU1_SA_CB<1>")
	)
	(segment
		(start 35.233102 -236.01045)
		(end 35.491166 -236.01045)
		(width 0.14478)
		(layer "In11.Cu")
		(net "M_F_CPU1_SA_CB<1>")
	)
	(segment
		(start 51.332384 -236.233716)
		(end 51.332384 -236.173518)
		(width 0.14478)
		(layer "In11.Cu")
		(net "M_F_CPU1_SA_CB<1>")
	)
	(segment
		(start 22.986238 -237.240826)
		(end 23.131018 -237.096046)
		(width 0.14478)
		(layer "In11.Cu")
		(net "M_F_CPU1_SA_CB<1>")
	)
	(segment
		(start 28.699206 -236.173518)
		(end 28.862274 -236.01045)
		(width 0.14478)
		(layer "In11.Cu")
		(net "M_F_CPU1_SA_CB<1>")
	)
	(segment
		(start 24.378666 -236.860334)
		(end 25.976834 -236.860334)
		(width 0.14478)
		(layer "In11.Cu")
		(net "M_F_CPU1_SA_CB<1>")
	)
	(segment
		(start 51.495452 -236.01045)
		(end 53.111908 -236.01045)
		(width 0.14478)
		(layer "In11.Cu")
		(net "M_F_CPU1_SA_CB<1>")
	)
	(segment
		(start 33.892998 -237.023402)
		(end 34.056066 -236.860334)
		(width 0.14478)
		(layer "In11.Cu")
		(net "M_F_CPU1_SA_CB<1>")
	)
	(segment
		(start 38.802564 -236.860334)
		(end 40.702738 -236.860334)
		(width 0.14478)
		(layer "In11.Cu")
		(net "M_F_CPU1_SA_CB<1>")
	)
	(segment
		(start 43.204384 -236.238796)
		(end 43.363134 -236.397546)
		(width 0.14478)
		(layer "In11.Cu")
		(net "M_F_CPU1_SA_CB<1>")
	)
	(segment
		(start 80.093566 -245.610888)
		(end 80.10398 -245.616984)
		(width 0.0889)
		(layer "In11.Cu")
		(net "M_F_CPU1_SA_CB<1>")
	)
	(segment
		(start 28.142692 -236.173518)
		(end 28.142692 -236.233716)
		(width 0.14478)
		(layer "In11.Cu")
		(net "M_F_CPU1_SA_CB<1>")
	)
	(segment
		(start 31.32074 -236.860334)
		(end 33.173416 -236.860334)
		(width 0.14478)
		(layer "In11.Cu")
		(net "M_F_CPU1_SA_CB<1>")
	)
	(segment
		(start 51.169316 -236.396784)
		(end 51.332384 -236.233716)
		(width 0.14478)
		(layer "In11.Cu")
		(net "M_F_CPU1_SA_CB<1>")
	)
	(segment
		(start 75.839066 -244.987064)
		(end 76.039726 -245.187724)
		(width 0.14478)
		(layer "In11.Cu")
		(net "M_F_CPU1_SA_CB<1>")
	)
	(segment
		(start 22.579584 -237.005114)
		(end 22.579584 -237.096046)
		(width 0.14478)
		(layer "In11.Cu")
		(net "M_F_CPU1_SA_CB<1>")
	)
	(segment
		(start 76.463398 -245.616984)
		(end 78.25867 -245.616984)
		(width 0.0889)
		(layer "In11.Cu")
		(net "M_F_CPU1_SA_CB<1>")
	)
	(segment
		(start 46.417738 -236.860334)
		(end 48.14824 -236.860334)
		(width 0.14478)
		(layer "In11.Cu")
		(net "M_F_CPU1_SA_CB<1>")
	)
	(segment
		(start 49.448974 -236.860334)
		(end 50.298858 -236.01045)
		(width 0.14478)
		(layer "In11.Cu")
		(net "M_F_CPU1_SA_CB<1>")
	)
	(segment
		(start 24.233886 -237.005114)
		(end 24.378666 -236.860334)
		(width 0.14478)
		(layer "In11.Cu")
		(net "M_F_CPU1_SA_CB<1>")
	)
	(segment
		(start 40.865806 -237.087156)
		(end 41.028874 -237.250224)
		(width 0.14478)
		(layer "In11.Cu")
		(net "M_F_CPU1_SA_CB<1>")
	)
	(segment
		(start 26.528268 -237.146846)
		(end 27.664664 -236.01045)
		(width 0.14478)
		(layer "In11.Cu")
		(net "M_F_CPU1_SA_CB<1>")
	)
	(segment
		(start 85.681058 -245.585234)
		(end 85.77707 -245.559834)
		(width 0.0889)
		(layer "In11.Cu")
		(net "M_F_CPU1_SA_CB<1>")
	)
	(segment
		(start 41.028874 -237.250224)
		(end 41.259252 -237.250224)
		(width 0.14478)
		(layer "In11.Cu")
		(net "M_F_CPU1_SA_CB<1>")
	)
	(segment
		(start 34.383218 -236.860334)
		(end 35.233102 -236.01045)
		(width 0.14478)
		(layer "In11.Cu")
		(net "M_F_CPU1_SA_CB<1>")
	)
	(segment
		(start 56.642508 -236.860334)
		(end 56.954674 -236.860334)
		(width 0.14478)
		(layer "In11.Cu")
		(net "M_F_CPU1_SA_CB<1>")
	)
	(segment
		(start 24.233886 -237.096046)
		(end 24.233886 -237.005114)
		(width 0.14478)
		(layer "In11.Cu")
		(net "M_F_CPU1_SA_CB<1>")
	)
	(segment
		(start 43.041316 -236.01045)
		(end 43.204384 -236.173518)
		(width 0.14478)
		(layer "In11.Cu")
		(net "M_F_CPU1_SA_CB<1>")
	)
	(segment
		(start 28.536138 -236.396784)
		(end 28.699206 -236.233716)
		(width 0.14478)
		(layer "In11.Cu")
		(net "M_F_CPU1_SA_CB<1>")
	)
	(segment
		(start 23.275798 -236.860334)
		(end 23.537672 -236.860334)
		(width 0.14478)
		(layer "In11.Cu")
		(net "M_F_CPU1_SA_CB<1>")
	)
	(segment
		(start 28.142692 -236.233716)
		(end 28.30576 -236.396784)
		(width 0.14478)
		(layer "In11.Cu")
		(net "M_F_CPU1_SA_CB<1>")
	)
	(arc
		(start 83.863942 -245.616984)
		(mid 84.046193 -245.667334)
		(end 84.229702 -245.62181)
		(width 0.0889)
		(layer "In11.Cu")
		(net "M_F_CPU1_SA_CB<1>")
	)
	(arc
		(start 80.478122 -245.616984)
		(mid 80.761078 -245.540807)
		(end 81.044034 -245.616984)
		(width 0.0889)
		(layer "In11.Cu")
		(net "M_F_CPU1_SA_CB<1>")
	)
	(arc
		(start 85.178138 -245.616984)
		(mid 85.425851 -245.541764)
		(end 85.681058 -245.585234)
		(width 0.0889)
		(layer "In11.Cu")
		(net "M_F_CPU1_SA_CB<1>")
	)
	(arc
		(start 84.238084 -245.616984)
		(mid 84.52104 -245.540807)
		(end 84.803996 -245.616984)
		(width 0.0889)
		(layer "In11.Cu")
		(net "M_F_CPU1_SA_CB<1>")
	)
	(arc
		(start 79.163418 -245.616984)
		(mid 79.350616 -245.667366)
		(end 79.537814 -245.616984)
		(width 0.0889)
		(layer "In11.Cu")
		(net "M_F_CPU1_SA_CB<1>")
	)
	(arc
		(start 82.357976 -245.616984)
		(mid 82.640932 -245.540807)
		(end 82.923888 -245.616984)
		(width 0.0889)
		(layer "In11.Cu")
		(net "M_F_CPU1_SA_CB<1>")
	)
	(arc
		(start 78.608174 -245.610888)
		(mid 78.886606 -245.54079)
		(end 79.163418 -245.616984)
		(width 0.0889)
		(layer "In11.Cu")
		(net "M_F_CPU1_SA_CB<1>")
	)
	(arc
		(start 80.10398 -245.616984)
		(mid 80.286231 -245.667334)
		(end 80.46974 -245.62181)
		(width 0.0889)
		(layer "In11.Cu")
		(net "M_F_CPU1_SA_CB<1>")
	)
	(arc
		(start 81.984088 -245.616984)
		(mid 82.171032 -245.667239)
		(end 82.357976 -245.616984)
		(width 0.0889)
		(layer "In11.Cu")
		(net "M_F_CPU1_SA_CB<1>")
	)
	(arc
		(start 81.418176 -245.616984)
		(mid 81.701132 -245.540807)
		(end 81.984088 -245.616984)
		(width 0.0889)
		(layer "In11.Cu")
		(net "M_F_CPU1_SA_CB<1>")
	)
	(arc
		(start 83.29803 -245.616984)
		(mid 83.580986 -245.540807)
		(end 83.863942 -245.616984)
		(width 0.0889)
		(layer "In11.Cu")
		(net "M_F_CPU1_SA_CB<1>")
	)
	(arc
		(start 79.537814 -245.616984)
		(mid 79.814881 -245.540713)
		(end 80.093566 -245.610888)
		(width 0.0889)
		(layer "In11.Cu")
		(net "M_F_CPU1_SA_CB<1>")
	)
	(arc
		(start 82.923888 -245.616984)
		(mid 83.106139 -245.667334)
		(end 83.289648 -245.62181)
		(width 0.0889)
		(layer "In11.Cu")
		(net "M_F_CPU1_SA_CB<1>")
	)
	(arc
		(start 81.052416 -245.62181)
		(mid 81.235924 -245.667304)
		(end 81.418176 -245.616984)
		(width 0.0889)
		(layer "In11.Cu")
		(net "M_F_CPU1_SA_CB<1>")
	)
	(arc
		(start 84.812378 -245.62181)
		(mid 84.995886 -245.667304)
		(end 85.178138 -245.616984)
		(width 0.0889)
		(layer "In11.Cu")
		(net "M_F_CPU1_SA_CB<1>")
	)
	(segment
		(start 84.987892 -244.750336)
		(end 84.52104 -244.484398)
		(width 0.10668)
		(layer "F.Cu")
		(net "M_F_CPU1_SA_CB<0>")
	)
	(segment
		(start 33.874964 -235.32338)
		(end 34.038032 -235.160312)
		(width 0.14478)
		(layer "In11.Cu")
		(net "M_F_CPU1_SA_CB<0>")
	)
	(segment
		(start 53.111908 -234.310428)
		(end 53.961792 -235.160312)
		(width 0.14478)
		(layer "In11.Cu")
		(net "M_F_CPU1_SA_CB<0>")
	)
	(segment
		(start 27.937968 -234.310428)
		(end 28.101036 -234.473496)
		(width 0.14478)
		(layer "In11.Cu")
		(net "M_F_CPU1_SA_CB<0>")
	)
	(segment
		(start 35.876992 -234.694984)
		(end 36.10737 -234.694984)
		(width 0.14478)
		(layer "In11.Cu")
		(net "M_F_CPU1_SA_CB<0>")
	)
	(segment
		(start 78.128876 -244.806724)
		(end 78.150466 -244.794278)
		(width 0.0889)
		(layer "In11.Cu")
		(net "M_F_CPU1_SA_CB<0>")
	)
	(segment
		(start 48.758602 -235.548424)
		(end 48.92167 -235.385356)
		(width 0.14478)
		(layer "In11.Cu")
		(net "M_F_CPU1_SA_CB<0>")
	)
	(segment
		(start 24.288242 -235.385356)
		(end 24.288242 -235.32338)
		(width 0.14478)
		(layer "In11.Cu")
		(net "M_F_CPU1_SA_CB<0>")
	)
	(segment
		(start 31.32074 -235.160312)
		(end 33.155382 -235.160312)
		(width 0.14478)
		(layer "In11.Cu")
		(net "M_F_CPU1_SA_CB<0>")
	)
	(segment
		(start 76.258166 -244.077744)
		(end 76.476606 -244.296184)
		(width 0.0889)
		(layer "In11.Cu")
		(net "M_F_CPU1_SA_CB<0>")
	)
	(segment
		(start 22.6187 -235.385356)
		(end 22.781768 -235.548424)
		(width 0.14478)
		(layer "In11.Cu")
		(net "M_F_CPU1_SA_CB<0>")
	)
	(segment
		(start 28.494482 -234.702604)
		(end 28.65755 -234.539536)
		(width 0.14478)
		(layer "In11.Cu")
		(net "M_F_CPU1_SA_CB<0>")
	)
	(segment
		(start 79.0575 -244.813836)
		(end 79.069184 -244.806978)
		(width 0.0889)
		(layer "In11.Cu")
		(net "M_F_CPU1_SA_CB<0>")
	)
	(segment
		(start 37.95268 -234.310428)
		(end 38.802564 -235.160312)
		(width 0.14478)
		(layer "In11.Cu")
		(net "M_F_CPU1_SA_CB<0>")
	)
	(segment
		(start 48.92167 -235.32338)
		(end 49.084738 -235.160312)
		(width 0.14478)
		(layer "In11.Cu")
		(net "M_F_CPU1_SA_CB<0>")
	)
	(segment
		(start 42.792904 -234.310428)
		(end 43.175682 -234.310428)
		(width 0.14478)
		(layer "In11.Cu")
		(net "M_F_CPU1_SA_CB<0>")
	)
	(segment
		(start 34.038032 -235.160312)
		(end 34.383218 -235.160312)
		(width 0.14478)
		(layer "In11.Cu")
		(net "M_F_CPU1_SA_CB<0>")
	)
	(segment
		(start 48.365156 -235.32338)
		(end 48.365156 -235.385356)
		(width 0.14478)
		(layer "In11.Cu")
		(net "M_F_CPU1_SA_CB<0>")
	)
	(segment
		(start 34.383218 -235.160312)
		(end 35.233102 -234.310428)
		(width 0.14478)
		(layer "In11.Cu")
		(net "M_F_CPU1_SA_CB<0>")
	)
	(segment
		(start 56.270144 -235.160312)
		(end 56.954674 -235.160312)
		(width 0.14478)
		(layer "In11.Cu")
		(net "M_F_CPU1_SA_CB<0>")
	)
	(segment
		(start 44.058332 -234.310428)
		(end 45.567854 -234.310428)
		(width 0.14478)
		(layer "In11.Cu")
		(net "M_F_CPU1_SA_CB<0>")
	)
	(segment
		(start 53.961792 -235.160312)
		(end 54.274466 -235.160312)
		(width 0.14478)
		(layer "In11.Cu")
		(net "M_F_CPU1_SA_CB<0>")
	)
	(segment
		(start 51.001422 -234.694984)
		(end 51.2318 -234.694984)
		(width 0.14478)
		(layer "In11.Cu")
		(net "M_F_CPU1_SA_CB<0>")
	)
	(segment
		(start 36.270438 -234.473496)
		(end 36.433506 -234.310428)
		(width 0.14478)
		(layer "In11.Cu")
		(net "M_F_CPU1_SA_CB<0>")
	)
	(segment
		(start 46.417738 -235.160312)
		(end 48.202088 -235.160312)
		(width 0.14478)
		(layer "In11.Cu")
		(net "M_F_CPU1_SA_CB<0>")
	)
	(segment
		(start 41.342818 -235.548424)
		(end 41.505886 -235.385356)
		(width 0.14478)
		(layer "In11.Cu")
		(net "M_F_CPU1_SA_CB<0>")
	)
	(segment
		(start 36.270438 -234.531916)
		(end 36.270438 -234.473496)
		(width 0.14478)
		(layer "In11.Cu")
		(net "M_F_CPU1_SA_CB<0>")
	)
	(segment
		(start 54.994048 -235.375196)
		(end 54.994048 -235.32338)
		(width 0.14478)
		(layer "In11.Cu")
		(net "M_F_CPU1_SA_CB<0>")
	)
	(segment
		(start 84.271104 -244.775228)
		(end 84.367116 -244.749828)
		(width 0.0889)
		(layer "In11.Cu")
		(net "M_F_CPU1_SA_CB<0>")
	)
	(segment
		(start 54.437534 -235.32338)
		(end 54.437534 -235.375196)
		(width 0.14478)
		(layer "In11.Cu")
		(net "M_F_CPU1_SA_CB<0>")
	)
	(segment
		(start 28.101036 -234.473496)
		(end 28.101036 -234.539536)
		(width 0.14478)
		(layer "In11.Cu")
		(net "M_F_CPU1_SA_CB<0>")
	)
	(segment
		(start 50.838354 -234.473496)
		(end 50.838354 -234.531916)
		(width 0.14478)
		(layer "In11.Cu")
		(net "M_F_CPU1_SA_CB<0>")
	)
	(segment
		(start 82.453988 -244.806978)
		(end 82.46237 -244.811804)
		(width 0.0889)
		(layer "In11.Cu")
		(net "M_F_CPU1_SA_CB<0>")
	)
	(segment
		(start 49.084738 -235.160312)
		(end 49.448974 -235.160312)
		(width 0.14478)
		(layer "In11.Cu")
		(net "M_F_CPU1_SA_CB<0>")
	)
	(segment
		(start 57.09666 -235.018326)
		(end 59.531504 -235.018326)
		(width 0.14478)
		(layer "In11.Cu")
		(net "M_F_CPU1_SA_CB<0>")
	)
	(segment
		(start 55.550562 -235.32338)
		(end 55.550562 -235.375196)
		(width 0.14478)
		(layer "In11.Cu")
		(net "M_F_CPU1_SA_CB<0>")
	)
	(segment
		(start 40.786304 -235.160312)
		(end 40.949372 -235.32338)
		(width 0.14478)
		(layer "In11.Cu")
		(net "M_F_CPU1_SA_CB<0>")
	)
	(segment
		(start 75.950826 -244.077744)
		(end 76.258166 -244.077744)
		(width 0.0889)
		(layer "In11.Cu")
		(net "M_F_CPU1_SA_CB<0>")
	)
	(segment
		(start 54.600602 -235.538264)
		(end 54.83098 -235.538264)
		(width 0.14478)
		(layer "In11.Cu")
		(net "M_F_CPU1_SA_CB<0>")
	)
	(segment
		(start 50.675286 -234.310428)
		(end 50.838354 -234.473496)
		(width 0.14478)
		(layer "In11.Cu")
		(net "M_F_CPU1_SA_CB<0>")
	)
	(segment
		(start 56.954674 -235.160312)
		(end 57.09666 -235.018326)
		(width 0.14478)
		(layer "In11.Cu")
		(net "M_F_CPU1_SA_CB<0>")
	)
	(segment
		(start 23.338282 -234.861608)
		(end 23.56866 -234.861608)
		(width 0.14478)
		(layer "In11.Cu")
		(net "M_F_CPU1_SA_CB<0>")
	)
	(segment
		(start 33.31845 -235.380276)
		(end 33.481518 -235.543344)
		(width 0.14478)
		(layer "In11.Cu")
		(net "M_F_CPU1_SA_CB<0>")
	)
	(segment
		(start 30.470856 -234.310428)
		(end 31.32074 -235.160312)
		(width 0.14478)
		(layer "In11.Cu")
		(net "M_F_CPU1_SA_CB<0>")
	)
	(segment
		(start 26.81478 -235.160312)
		(end 27.664664 -234.310428)
		(width 0.14478)
		(layer "In11.Cu")
		(net "M_F_CPU1_SA_CB<0>")
	)
	(segment
		(start 25.693624 -235.32338)
		(end 25.693624 -235.385356)
		(width 0.14478)
		(layer "In11.Cu")
		(net "M_F_CPU1_SA_CB<0>")
	)
	(segment
		(start 22.781768 -235.548424)
		(end 23.012146 -235.548424)
		(width 0.14478)
		(layer "In11.Cu")
		(net "M_F_CPU1_SA_CB<0>")
	)
	(segment
		(start 67.647566 -244.077744)
		(end 75.950826 -244.077744)
		(width 0.14478)
		(layer "In11.Cu")
		(net "M_F_CPU1_SA_CB<0>")
	)
	(segment
		(start 26.08707 -235.548424)
		(end 26.250138 -235.385356)
		(width 0.14478)
		(layer "In11.Cu")
		(net "M_F_CPU1_SA_CB<0>")
	)
	(segment
		(start 24.45131 -235.160312)
		(end 25.530556 -235.160312)
		(width 0.14478)
		(layer "In11.Cu")
		(net "M_F_CPU1_SA_CB<0>")
	)
	(segment
		(start 33.481518 -235.543344)
		(end 33.711896 -235.543344)
		(width 0.14478)
		(layer "In11.Cu")
		(net "M_F_CPU1_SA_CB<0>")
	)
	(segment
		(start 56.107076 -235.32338)
		(end 56.270144 -235.160312)
		(width 0.14478)
		(layer "In11.Cu")
		(net "M_F_CPU1_SA_CB<0>")
	)
	(segment
		(start 55.550562 -235.375196)
		(end 55.71363 -235.538264)
		(width 0.14478)
		(layer "In11.Cu")
		(net "M_F_CPU1_SA_CB<0>")
	)
	(segment
		(start 25.856692 -235.548424)
		(end 26.08707 -235.548424)
		(width 0.14478)
		(layer "In11.Cu")
		(net "M_F_CPU1_SA_CB<0>")
	)
	(segment
		(start 49.448974 -235.160312)
		(end 50.298858 -234.310428)
		(width 0.14478)
		(layer "In11.Cu")
		(net "M_F_CPU1_SA_CB<0>")
	)
	(segment
		(start 23.175214 -235.385356)
		(end 23.175214 -235.024676)
		(width 0.14478)
		(layer "In11.Cu")
		(net "M_F_CPU1_SA_CB<0>")
	)
	(segment
		(start 40.949372 -235.32338)
		(end 40.949372 -235.385356)
		(width 0.14478)
		(layer "In11.Cu")
		(net "M_F_CPU1_SA_CB<0>")
	)
	(segment
		(start 36.433506 -234.310428)
		(end 37.95268 -234.310428)
		(width 0.14478)
		(layer "In11.Cu")
		(net "M_F_CPU1_SA_CB<0>")
	)
	(segment
		(start 45.567854 -234.310428)
		(end 46.417738 -235.160312)
		(width 0.14478)
		(layer "In11.Cu")
		(net "M_F_CPU1_SA_CB<0>")
	)
	(segment
		(start 55.71363 -235.538264)
		(end 55.944008 -235.538264)
		(width 0.14478)
		(layer "In11.Cu")
		(net "M_F_CPU1_SA_CB<0>")
	)
	(segment
		(start 28.820618 -234.310428)
		(end 30.470856 -234.310428)
		(width 0.14478)
		(layer "In11.Cu")
		(net "M_F_CPU1_SA_CB<0>")
	)
	(segment
		(start 77.591412 -244.85727)
		(end 77.939646 -244.85727)
		(width 0.0889)
		(layer "In11.Cu")
		(net "M_F_CPU1_SA_CB<0>")
	)
	(segment
		(start 59.531504 -235.018326)
		(end 59.89701 -235.383832)
		(width 0.14478)
		(layer "In11.Cu")
		(net "M_F_CPU1_SA_CB<0>")
	)
	(segment
		(start 28.65755 -234.473496)
		(end 28.820618 -234.310428)
		(width 0.14478)
		(layer "In11.Cu")
		(net "M_F_CPU1_SA_CB<0>")
	)
	(segment
		(start 35.550856 -234.310428)
		(end 35.713924 -234.473496)
		(width 0.14478)
		(layer "In11.Cu")
		(net "M_F_CPU1_SA_CB<0>")
	)
	(segment
		(start 48.202088 -235.160312)
		(end 48.365156 -235.32338)
		(width 0.14478)
		(layer "In11.Cu")
		(net "M_F_CPU1_SA_CB<0>")
	)
	(segment
		(start 54.83098 -235.538264)
		(end 54.994048 -235.375196)
		(width 0.14478)
		(layer "In11.Cu")
		(net "M_F_CPU1_SA_CB<0>")
	)
	(segment
		(start 33.874964 -235.380276)
		(end 33.874964 -235.32338)
		(width 0.14478)
		(layer "In11.Cu")
		(net "M_F_CPU1_SA_CB<0>")
	)
	(segment
		(start 43.895264 -234.473496)
		(end 44.058332 -234.310428)
		(width 0.14478)
		(layer "In11.Cu")
		(net "M_F_CPU1_SA_CB<0>")
	)
	(segment
		(start 41.505886 -235.32338)
		(end 41.668954 -235.160312)
		(width 0.14478)
		(layer "In11.Cu")
		(net "M_F_CPU1_SA_CB<0>")
	)
	(segment
		(start 26.413206 -235.160312)
		(end 26.81478 -235.160312)
		(width 0.14478)
		(layer "In11.Cu")
		(net "M_F_CPU1_SA_CB<0>")
	)
	(segment
		(start 51.2318 -234.694984)
		(end 51.394868 -234.531916)
		(width 0.14478)
		(layer "In11.Cu")
		(net "M_F_CPU1_SA_CB<0>")
	)
	(segment
		(start 41.668954 -235.160312)
		(end 41.94302 -235.160312)
		(width 0.14478)
		(layer "In11.Cu")
		(net "M_F_CPU1_SA_CB<0>")
	)
	(segment
		(start 43.33875 -234.539536)
		(end 43.501818 -234.702604)
		(width 0.14478)
		(layer "In11.Cu")
		(net "M_F_CPU1_SA_CB<0>")
	)
	(segment
		(start 48.528224 -235.548424)
		(end 48.758602 -235.548424)
		(width 0.14478)
		(layer "In11.Cu")
		(net "M_F_CPU1_SA_CB<0>")
	)
	(segment
		(start 41.94302 -235.160312)
		(end 42.792904 -234.310428)
		(width 0.14478)
		(layer "In11.Cu")
		(net "M_F_CPU1_SA_CB<0>")
	)
	(segment
		(start 43.501818 -234.702604)
		(end 43.732196 -234.702604)
		(width 0.14478)
		(layer "In11.Cu")
		(net "M_F_CPU1_SA_CB<0>")
	)
	(segment
		(start 25.530556 -235.160312)
		(end 25.693624 -235.32338)
		(width 0.14478)
		(layer "In11.Cu")
		(net "M_F_CPU1_SA_CB<0>")
	)
	(segment
		(start 51.394868 -234.531916)
		(end 51.394868 -234.473496)
		(width 0.14478)
		(layer "In11.Cu")
		(net "M_F_CPU1_SA_CB<0>")
	)
	(segment
		(start 22.455632 -235.160312)
		(end 22.6187 -235.32338)
		(width 0.14478)
		(layer "In11.Cu")
		(net "M_F_CPU1_SA_CB<0>")
	)
	(segment
		(start 84.367116 -244.749828)
		(end 84.52104 -244.484398)
		(width 0.0889)
		(layer "In11.Cu")
		(net "M_F_CPU1_SA_CB<0>")
	)
	(segment
		(start 38.802564 -235.160312)
		(end 40.786304 -235.160312)
		(width 0.14478)
		(layer "In11.Cu")
		(net "M_F_CPU1_SA_CB<0>")
	)
	(segment
		(start 76.476606 -244.296184)
		(end 77.030326 -244.296184)
		(width 0.0889)
		(layer "In11.Cu")
		(net "M_F_CPU1_SA_CB<0>")
	)
	(segment
		(start 79.622396 -244.799866)
		(end 79.634334 -244.806724)
		(width 0.0889)
		(layer "In11.Cu")
		(net "M_F_CPU1_SA_CB<0>")
	)
	(segment
		(start 83.394042 -244.806978)
		(end 83.402424 -244.811804)
		(width 0.0889)
		(layer "In11.Cu")
		(net "M_F_CPU1_SA_CB<0>")
	)
	(segment
		(start 36.10737 -234.694984)
		(end 36.270438 -234.531916)
		(width 0.14478)
		(layer "In11.Cu")
		(net "M_F_CPU1_SA_CB<0>")
	)
	(segment
		(start 56.107076 -235.375196)
		(end 56.107076 -235.32338)
		(width 0.14478)
		(layer "In11.Cu")
		(net "M_F_CPU1_SA_CB<0>")
	)
	(segment
		(start 78.11262 -244.816122)
		(end 78.128876 -244.806724)
		(width 0.0889)
		(layer "In11.Cu")
		(net "M_F_CPU1_SA_CB<0>")
	)
	(segment
		(start 43.33875 -234.473496)
		(end 43.33875 -234.539536)
		(width 0.14478)
		(layer "In11.Cu")
		(net "M_F_CPU1_SA_CB<0>")
	)
	(segment
		(start 51.557936 -234.310428)
		(end 53.111908 -234.310428)
		(width 0.14478)
		(layer "In11.Cu")
		(net "M_F_CPU1_SA_CB<0>")
	)
	(segment
		(start 23.56866 -234.861608)
		(end 23.731728 -235.024676)
		(width 0.14478)
		(layer "In11.Cu")
		(net "M_F_CPU1_SA_CB<0>")
	)
	(segment
		(start 35.233102 -234.310428)
		(end 35.550856 -234.310428)
		(width 0.14478)
		(layer "In11.Cu")
		(net "M_F_CPU1_SA_CB<0>")
	)
	(segment
		(start 23.731728 -235.024676)
		(end 23.731728 -235.385356)
		(width 0.14478)
		(layer "In11.Cu")
		(net "M_F_CPU1_SA_CB<0>")
	)
	(segment
		(start 48.92167 -235.385356)
		(end 48.92167 -235.32338)
		(width 0.14478)
		(layer "In11.Cu")
		(net "M_F_CPU1_SA_CB<0>")
	)
	(segment
		(start 77.030326 -244.296184)
		(end 77.591412 -244.85727)
		(width 0.0889)
		(layer "In11.Cu")
		(net "M_F_CPU1_SA_CB<0>")
	)
	(segment
		(start 23.731728 -235.385356)
		(end 23.894796 -235.548424)
		(width 0.14478)
		(layer "In11.Cu")
		(net "M_F_CPU1_SA_CB<0>")
	)
	(segment
		(start 59.89701 -236.327188)
		(end 67.647566 -244.077744)
		(width 0.14478)
		(layer "In11.Cu")
		(net "M_F_CPU1_SA_CB<0>")
	)
	(segment
		(start 33.155382 -235.160312)
		(end 33.31845 -235.32338)
		(width 0.14478)
		(layer "In11.Cu")
		(net "M_F_CPU1_SA_CB<0>")
	)
	(segment
		(start 79.634334 -244.806724)
		(end 79.65059 -244.816122)
		(width 0.0889)
		(layer "In11.Cu")
		(net "M_F_CPU1_SA_CB<0>")
	)
	(segment
		(start 35.713924 -234.473496)
		(end 35.713924 -234.531916)
		(width 0.14478)
		(layer "In11.Cu")
		(net "M_F_CPU1_SA_CB<0>")
	)
	(segment
		(start 81.879694 -244.811804)
		(end 81.888076 -244.806978)
		(width 0.0889)
		(layer "In11.Cu")
		(net "M_F_CPU1_SA_CB<0>")
	)
	(segment
		(start 22.133052 -235.160312)
		(end 22.455632 -235.160312)
		(width 0.14478)
		(layer "In11.Cu")
		(net "M_F_CPU1_SA_CB<0>")
	)
	(segment
		(start 33.711896 -235.543344)
		(end 33.874964 -235.380276)
		(width 0.14478)
		(layer "In11.Cu")
		(net "M_F_CPU1_SA_CB<0>")
	)
	(segment
		(start 24.288242 -235.32338)
		(end 24.45131 -235.160312)
		(width 0.14478)
		(layer "In11.Cu")
		(net "M_F_CPU1_SA_CB<0>")
	)
	(segment
		(start 27.664664 -234.310428)
		(end 27.937968 -234.310428)
		(width 0.14478)
		(layer "In11.Cu")
		(net "M_F_CPU1_SA_CB<0>")
	)
	(segment
		(start 40.949372 -235.385356)
		(end 41.11244 -235.548424)
		(width 0.14478)
		(layer "In11.Cu")
		(net "M_F_CPU1_SA_CB<0>")
	)
	(segment
		(start 54.437534 -235.375196)
		(end 54.600602 -235.538264)
		(width 0.14478)
		(layer "In11.Cu")
		(net "M_F_CPU1_SA_CB<0>")
	)
	(segment
		(start 23.012146 -235.548424)
		(end 23.175214 -235.385356)
		(width 0.14478)
		(layer "In11.Cu")
		(net "M_F_CPU1_SA_CB<0>")
	)
	(segment
		(start 54.994048 -235.32338)
		(end 55.157116 -235.160312)
		(width 0.14478)
		(layer "In11.Cu")
		(net "M_F_CPU1_SA_CB<0>")
	)
	(segment
		(start 50.838354 -234.531916)
		(end 51.001422 -234.694984)
		(width 0.14478)
		(layer "In11.Cu")
		(net "M_F_CPU1_SA_CB<0>")
	)
	(segment
		(start 43.732196 -234.702604)
		(end 43.895264 -234.539536)
		(width 0.14478)
		(layer "In11.Cu")
		(net "M_F_CPU1_SA_CB<0>")
	)
	(segment
		(start 55.944008 -235.538264)
		(end 56.107076 -235.375196)
		(width 0.14478)
		(layer "In11.Cu")
		(net "M_F_CPU1_SA_CB<0>")
	)
	(segment
		(start 25.693624 -235.385356)
		(end 25.856692 -235.548424)
		(width 0.14478)
		(layer "In11.Cu")
		(net "M_F_CPU1_SA_CB<0>")
	)
	(segment
		(start 24.125174 -235.548424)
		(end 24.288242 -235.385356)
		(width 0.14478)
		(layer "In11.Cu")
		(net "M_F_CPU1_SA_CB<0>")
	)
	(segment
		(start 48.365156 -235.385356)
		(end 48.528224 -235.548424)
		(width 0.14478)
		(layer "In11.Cu")
		(net "M_F_CPU1_SA_CB<0>")
	)
	(segment
		(start 23.894796 -235.548424)
		(end 24.125174 -235.548424)
		(width 0.14478)
		(layer "In11.Cu")
		(net "M_F_CPU1_SA_CB<0>")
	)
	(segment
		(start 26.250138 -235.385356)
		(end 26.250138 -235.32338)
		(width 0.14478)
		(layer "In11.Cu")
		(net "M_F_CPU1_SA_CB<0>")
	)
	(segment
		(start 43.175682 -234.310428)
		(end 43.33875 -234.473496)
		(width 0.14478)
		(layer "In11.Cu")
		(net "M_F_CPU1_SA_CB<0>")
	)
	(segment
		(start 55.157116 -235.160312)
		(end 55.387494 -235.160312)
		(width 0.14478)
		(layer "In11.Cu")
		(net "M_F_CPU1_SA_CB<0>")
	)
	(segment
		(start 54.274466 -235.160312)
		(end 54.437534 -235.32338)
		(width 0.14478)
		(layer "In11.Cu")
		(net "M_F_CPU1_SA_CB<0>")
	)
	(segment
		(start 22.6187 -235.32338)
		(end 22.6187 -235.385356)
		(width 0.14478)
		(layer "In11.Cu")
		(net "M_F_CPU1_SA_CB<0>")
	)
	(segment
		(start 35.713924 -234.531916)
		(end 35.876992 -234.694984)
		(width 0.14478)
		(layer "In11.Cu")
		(net "M_F_CPU1_SA_CB<0>")
	)
	(segment
		(start 28.101036 -234.539536)
		(end 28.264104 -234.702604)
		(width 0.14478)
		(layer "In11.Cu")
		(net "M_F_CPU1_SA_CB<0>")
	)
	(segment
		(start 50.298858 -234.310428)
		(end 50.675286 -234.310428)
		(width 0.14478)
		(layer "In11.Cu")
		(net "M_F_CPU1_SA_CB<0>")
	)
	(segment
		(start 41.505886 -235.385356)
		(end 41.505886 -235.32338)
		(width 0.14478)
		(layer "In11.Cu")
		(net "M_F_CPU1_SA_CB<0>")
	)
	(segment
		(start 28.65755 -234.539536)
		(end 28.65755 -234.473496)
		(width 0.14478)
		(layer "In11.Cu")
		(net "M_F_CPU1_SA_CB<0>")
	)
	(segment
		(start 55.387494 -235.160312)
		(end 55.550562 -235.32338)
		(width 0.14478)
		(layer "In11.Cu")
		(net "M_F_CPU1_SA_CB<0>")
	)
	(segment
		(start 23.175214 -235.024676)
		(end 23.338282 -234.861608)
		(width 0.14478)
		(layer "In11.Cu")
		(net "M_F_CPU1_SA_CB<0>")
	)
	(segment
		(start 41.11244 -235.548424)
		(end 41.342818 -235.548424)
		(width 0.14478)
		(layer "In11.Cu")
		(net "M_F_CPU1_SA_CB<0>")
	)
	(segment
		(start 33.31845 -235.32338)
		(end 33.31845 -235.380276)
		(width 0.14478)
		(layer "In11.Cu")
		(net "M_F_CPU1_SA_CB<0>")
	)
	(segment
		(start 28.264104 -234.702604)
		(end 28.494482 -234.702604)
		(width 0.14478)
		(layer "In11.Cu")
		(net "M_F_CPU1_SA_CB<0>")
	)
	(segment
		(start 21.70811 -234.73537)
		(end 22.133052 -235.160312)
		(width 0.14478)
		(layer "In11.Cu")
		(net "M_F_CPU1_SA_CB<0>")
	)
	(segment
		(start 26.250138 -235.32338)
		(end 26.413206 -235.160312)
		(width 0.14478)
		(layer "In11.Cu")
		(net "M_F_CPU1_SA_CB<0>")
	)
	(segment
		(start 51.394868 -234.473496)
		(end 51.557936 -234.310428)
		(width 0.14478)
		(layer "In11.Cu")
		(net "M_F_CPU1_SA_CB<0>")
	)
	(segment
		(start 43.895264 -234.539536)
		(end 43.895264 -234.473496)
		(width 0.14478)
		(layer "In11.Cu")
		(net "M_F_CPU1_SA_CB<0>")
	)
	(segment
		(start 59.89701 -235.383832)
		(end 59.89701 -236.327188)
		(width 0.14478)
		(layer "In11.Cu")
		(net "M_F_CPU1_SA_CB<0>")
	)
	(arc
		(start 82.82813 -244.806978)
		(mid 83.111086 -244.730801)
		(end 83.394042 -244.806978)
		(width 0.0889)
		(layer "In11.Cu")
		(net "M_F_CPU1_SA_CB<0>")
	)
	(arc
		(start 81.513934 -244.806978)
		(mid 81.696185 -244.857328)
		(end 81.879694 -244.811804)
		(width 0.0889)
		(layer "In11.Cu")
		(net "M_F_CPU1_SA_CB<0>")
	)
	(arc
		(start 80.574134 -244.806978)
		(mid 80.761078 -244.857233)
		(end 80.948022 -244.806978)
		(width 0.0889)
		(layer "In11.Cu")
		(net "M_F_CPU1_SA_CB<0>")
	)
	(arc
		(start 80.948022 -244.806978)
		(mid 81.230978 -244.730801)
		(end 81.513934 -244.806978)
		(width 0.0889)
		(layer "In11.Cu")
		(net "M_F_CPU1_SA_CB<0>")
	)
	(arc
		(start 78.150466 -244.794278)
		(mid 78.424256 -244.730607)
		(end 78.694788 -244.806978)
		(width 0.0889)
		(layer "In11.Cu")
		(net "M_F_CPU1_SA_CB<0>")
	)
	(arc
		(start 81.888076 -244.806978)
		(mid 82.171032 -244.730801)
		(end 82.453988 -244.806978)
		(width 0.0889)
		(layer "In11.Cu")
		(net "M_F_CPU1_SA_CB<0>")
	)
	(arc
		(start 78.694788 -244.806978)
		(mid 78.875246 -244.857422)
		(end 79.0575 -244.813836)
		(width 0.0889)
		(layer "In11.Cu")
		(net "M_F_CPU1_SA_CB<0>")
	)
	(arc
		(start 82.46237 -244.811804)
		(mid 82.645878 -244.857298)
		(end 82.82813 -244.806978)
		(width 0.0889)
		(layer "In11.Cu")
		(net "M_F_CPU1_SA_CB<0>")
	)
	(arc
		(start 83.402424 -244.811804)
		(mid 83.585932 -244.857298)
		(end 83.768184 -244.806978)
		(width 0.0889)
		(layer "In11.Cu")
		(net "M_F_CPU1_SA_CB<0>")
	)
	(arc
		(start 83.768184 -244.806978)
		(mid 84.015897 -244.731758)
		(end 84.271104 -244.775228)
		(width 0.0889)
		(layer "In11.Cu")
		(net "M_F_CPU1_SA_CB<0>")
	)
	(arc
		(start 79.65059 -244.816122)
		(mid 79.830572 -244.857222)
		(end 80.008222 -244.806978)
		(width 0.0889)
		(layer "In11.Cu")
		(net "M_F_CPU1_SA_CB<0>")
	)
	(arc
		(start 77.939646 -244.85727)
		(mid 78.028631 -244.847182)
		(end 78.11262 -244.816122)
		(width 0.0889)
		(layer "In11.Cu")
		(net "M_F_CPU1_SA_CB<0>")
	)
	(arc
		(start 80.008222 -244.806978)
		(mid 80.291178 -244.730801)
		(end 80.574134 -244.806978)
		(width 0.0889)
		(layer "In11.Cu")
		(net "M_F_CPU1_SA_CB<0>")
	)
	(arc
		(start 79.069184 -244.806978)
		(mid 79.344862 -244.730848)
		(end 79.622396 -244.799866)
		(width 0.0889)
		(layer "In11.Cu")
		(net "M_F_CPU1_SA_CB<0>")
	)
	(segment
		(start 86.397846 -255.280414)
		(end 85.930994 -255.014476)
		(width 0.10668)
		(layer "F.Cu")
		(net "M_F_CPU1_SA_CA<6>")
	)
	(segment
		(start 80.093566 -255.33096)
		(end 80.10398 -255.337056)
		(width 0.0889)
		(layer "In11.Cu")
		(net "M_F_CPU1_SA_CA<6>")
	)
	(segment
		(start 22.33041 -254.172974)
		(end 22.561042 -254.173228)
		(width 0.14478)
		(layer "In11.Cu")
		(net "M_F_CPU1_SA_CA<6>")
	)
	(segment
		(start 60.65774 -254.700024)
		(end 71.722742 -254.700024)
		(width 0.14478)
		(layer "In11.Cu")
		(net "M_F_CPU1_SA_CA<6>")
	)
	(segment
		(start 23.206964 -254.314452)
		(end 22.954742 -254.566674)
		(width 0.14478)
		(layer "In11.Cu")
		(net "M_F_CPU1_SA_CA<6>")
	)
	(segment
		(start 80.46974 -255.341882)
		(end 80.478122 -255.337056)
		(width 0.0889)
		(layer "In11.Cu")
		(net "M_F_CPU1_SA_CA<6>")
	)
	(segment
		(start 22.419818 -253.296928)
		(end 22.419564 -253.527052)
		(width 0.14478)
		(layer "In11.Cu")
		(net "M_F_CPU1_SA_CA<6>")
	)
	(segment
		(start 21.70811 -252.58522)
		(end 22.419818 -253.296928)
		(width 0.14478)
		(layer "In11.Cu")
		(net "M_F_CPU1_SA_CA<6>")
	)
	(segment
		(start 84.229702 -255.341882)
		(end 84.238084 -255.337056)
		(width 0.0889)
		(layer "In11.Cu")
		(net "M_F_CPU1_SA_CA<6>")
	)
	(segment
		(start 78.18882 -255.28778)
		(end 78.239112 -255.338072)
		(width 0.0889)
		(layer "In11.Cu")
		(net "M_F_CPU1_SA_CA<6>")
	)
	(segment
		(start 23.043896 -253.921006)
		(end 23.207218 -254.084328)
		(width 0.14478)
		(layer "In11.Cu")
		(net "M_F_CPU1_SA_CA<6>")
	)
	(segment
		(start 81.044034 -255.337056)
		(end 81.052416 -255.341882)
		(width 0.0889)
		(layer "In11.Cu")
		(net "M_F_CPU1_SA_CA<6>")
	)
	(segment
		(start 22.167342 -254.009906)
		(end 22.33041 -254.172974)
		(width 0.14478)
		(layer "In11.Cu")
		(net "M_F_CPU1_SA_CA<6>")
	)
	(segment
		(start 60.647326 -254.710438)
		(end 60.65774 -254.700024)
		(width 0.14478)
		(layer "In11.Cu")
		(net "M_F_CPU1_SA_CA<6>")
	)
	(segment
		(start 22.561042 -254.173228)
		(end 22.813264 -253.921006)
		(width 0.14478)
		(layer "In11.Cu")
		(net "M_F_CPU1_SA_CA<6>")
	)
	(segment
		(start 85.77707 -255.279906)
		(end 85.930994 -255.014476)
		(width 0.0889)
		(layer "In11.Cu")
		(net "M_F_CPU1_SA_CA<6>")
	)
	(segment
		(start 23.348442 -254.960628)
		(end 23.598632 -254.710438)
		(width 0.14478)
		(layer "In11.Cu")
		(net "M_F_CPU1_SA_CA<6>")
	)
	(segment
		(start 77.46365 -255.28778)
		(end 78.18882 -255.28778)
		(width 0.0889)
		(layer "In11.Cu")
		(net "M_F_CPU1_SA_CA<6>")
	)
	(segment
		(start 76.682346 -255.589024)
		(end 77.162406 -255.589024)
		(width 0.0889)
		(layer "In11.Cu")
		(net "M_F_CPU1_SA_CA<6>")
	)
	(segment
		(start 83.289648 -255.341882)
		(end 83.29803 -255.337056)
		(width 0.0889)
		(layer "In11.Cu")
		(net "M_F_CPU1_SA_CA<6>")
	)
	(segment
		(start 22.419564 -253.527052)
		(end 22.167342 -253.779274)
		(width 0.14478)
		(layer "In11.Cu")
		(net "M_F_CPU1_SA_CA<6>")
	)
	(segment
		(start 77.162406 -255.589024)
		(end 77.46365 -255.28778)
		(width 0.0889)
		(layer "In11.Cu")
		(net "M_F_CPU1_SA_CA<6>")
	)
	(segment
		(start 23.598632 -254.710438)
		(end 60.647326 -254.710438)
		(width 0.14478)
		(layer "In11.Cu")
		(net "M_F_CPU1_SA_CA<6>")
	)
	(segment
		(start 85.681058 -255.305306)
		(end 85.77707 -255.279906)
		(width 0.0889)
		(layer "In11.Cu")
		(net "M_F_CPU1_SA_CA<6>")
	)
	(segment
		(start 71.722742 -254.700024)
		(end 73.068942 -256.046224)
		(width 0.14478)
		(layer "In11.Cu")
		(net "M_F_CPU1_SA_CA<6>")
	)
	(segment
		(start 78.53172 -255.375664)
		(end 78.608174 -255.33096)
		(width 0.0889)
		(layer "In11.Cu")
		(net "M_F_CPU1_SA_CA<6>")
	)
	(segment
		(start 22.167342 -253.779274)
		(end 22.167342 -254.009906)
		(width 0.14478)
		(layer "In11.Cu")
		(net "M_F_CPU1_SA_CA<6>")
	)
	(segment
		(start 73.068942 -256.046224)
		(end 76.001626 -256.046224)
		(width 0.14478)
		(layer "In11.Cu")
		(net "M_F_CPU1_SA_CA<6>")
	)
	(segment
		(start 76.225146 -256.046224)
		(end 76.682346 -255.589024)
		(width 0.0889)
		(layer "In11.Cu")
		(net "M_F_CPU1_SA_CA<6>")
	)
	(segment
		(start 23.11781 -254.960374)
		(end 23.348442 -254.960628)
		(width 0.14478)
		(layer "In11.Cu")
		(net "M_F_CPU1_SA_CA<6>")
	)
	(segment
		(start 22.954742 -254.797306)
		(end 23.11781 -254.960374)
		(width 0.14478)
		(layer "In11.Cu")
		(net "M_F_CPU1_SA_CA<6>")
	)
	(segment
		(start 22.813264 -253.921006)
		(end 23.043896 -253.921006)
		(width 0.14478)
		(layer "In11.Cu")
		(net "M_F_CPU1_SA_CA<6>")
	)
	(segment
		(start 22.954742 -254.566674)
		(end 22.954742 -254.797306)
		(width 0.14478)
		(layer "In11.Cu")
		(net "M_F_CPU1_SA_CA<6>")
	)
	(segment
		(start 84.803996 -255.337056)
		(end 84.812378 -255.341882)
		(width 0.0889)
		(layer "In11.Cu")
		(net "M_F_CPU1_SA_CA<6>")
	)
	(segment
		(start 23.207218 -254.084328)
		(end 23.206964 -254.314452)
		(width 0.14478)
		(layer "In11.Cu")
		(net "M_F_CPU1_SA_CA<6>")
	)
	(segment
		(start 76.001626 -256.046224)
		(end 76.225146 -256.046224)
		(width 0.0889)
		(layer "In11.Cu")
		(net "M_F_CPU1_SA_CA<6>")
	)
	(arc
		(start 83.29803 -255.337056)
		(mid 83.580986 -255.260879)
		(end 83.863942 -255.337056)
		(width 0.0889)
		(layer "In11.Cu")
		(net "M_F_CPU1_SA_CA<6>")
	)
	(arc
		(start 80.478122 -255.337056)
		(mid 80.761078 -255.260879)
		(end 81.044034 -255.337056)
		(width 0.0889)
		(layer "In11.Cu")
		(net "M_F_CPU1_SA_CA<6>")
	)
	(arc
		(start 81.052416 -255.341882)
		(mid 81.235924 -255.387376)
		(end 81.418176 -255.337056)
		(width 0.0889)
		(layer "In11.Cu")
		(net "M_F_CPU1_SA_CA<6>")
	)
	(arc
		(start 82.923888 -255.337056)
		(mid 83.106139 -255.387406)
		(end 83.289648 -255.341882)
		(width 0.0889)
		(layer "In11.Cu")
		(net "M_F_CPU1_SA_CA<6>")
	)
	(arc
		(start 79.537814 -255.337056)
		(mid 79.814881 -255.260785)
		(end 80.093566 -255.33096)
		(width 0.0889)
		(layer "In11.Cu")
		(net "M_F_CPU1_SA_CA<6>")
	)
	(arc
		(start 84.238084 -255.337056)
		(mid 84.52104 -255.260879)
		(end 84.803996 -255.337056)
		(width 0.0889)
		(layer "In11.Cu")
		(net "M_F_CPU1_SA_CA<6>")
	)
	(arc
		(start 79.163418 -255.337056)
		(mid 79.350616 -255.387438)
		(end 79.537814 -255.337056)
		(width 0.0889)
		(layer "In11.Cu")
		(net "M_F_CPU1_SA_CA<6>")
	)
	(arc
		(start 85.178138 -255.337056)
		(mid 85.425851 -255.261836)
		(end 85.681058 -255.305306)
		(width 0.0889)
		(layer "In11.Cu")
		(net "M_F_CPU1_SA_CA<6>")
	)
	(arc
		(start 83.863942 -255.337056)
		(mid 84.046193 -255.387406)
		(end 84.229702 -255.341882)
		(width 0.0889)
		(layer "In11.Cu")
		(net "M_F_CPU1_SA_CA<6>")
	)
	(arc
		(start 82.357976 -255.337056)
		(mid 82.640932 -255.260879)
		(end 82.923888 -255.337056)
		(width 0.0889)
		(layer "In11.Cu")
		(net "M_F_CPU1_SA_CA<6>")
	)
	(arc
		(start 81.418176 -255.337056)
		(mid 81.701132 -255.260879)
		(end 81.984088 -255.337056)
		(width 0.0889)
		(layer "In11.Cu")
		(net "M_F_CPU1_SA_CA<6>")
	)
	(arc
		(start 80.10398 -255.337056)
		(mid 80.286231 -255.387406)
		(end 80.46974 -255.341882)
		(width 0.0889)
		(layer "In11.Cu")
		(net "M_F_CPU1_SA_CA<6>")
	)
	(arc
		(start 78.608174 -255.33096)
		(mid 78.886606 -255.260862)
		(end 79.163418 -255.337056)
		(width 0.0889)
		(layer "In11.Cu")
		(net "M_F_CPU1_SA_CA<6>")
	)
	(arc
		(start 78.239112 -255.338072)
		(mid 78.379009 -255.406801)
		(end 78.53172 -255.375664)
		(width 0.0889)
		(layer "In11.Cu")
		(net "M_F_CPU1_SA_CA<6>")
	)
	(arc
		(start 81.984088 -255.337056)
		(mid 82.171032 -255.387311)
		(end 82.357976 -255.337056)
		(width 0.0889)
		(layer "In11.Cu")
		(net "M_F_CPU1_SA_CA<6>")
	)
	(arc
		(start 84.812378 -255.341882)
		(mid 84.995886 -255.387376)
		(end 85.178138 -255.337056)
		(width 0.0889)
		(layer "In11.Cu")
		(net "M_F_CPU1_SA_CA<6>")
	)
	(segment
		(start 84.517992 -255.280414)
		(end 84.05114 -255.014476)
		(width 0.10668)
		(layer "F.Cu")
		(net "M_F_CPU1_SA_CA<5>")
	)
	(segment
		(start 78.224634 -254.69215)
		(end 78.2447 -254.68072)
		(width 0.0889)
		(layer "In11.Cu")
		(net "M_F_CPU1_SA_CA<5>")
	)
	(segment
		(start 84.182712 -254.665734)
		(end 84.205064 -254.749046)
		(width 0.0889)
		(layer "In11.Cu")
		(net "M_F_CPU1_SA_CA<5>")
	)
	(segment
		(start 79.147162 -254.702564)
		(end 79.165196 -254.691896)
		(width 0.0889)
		(layer "In11.Cu")
		(net "M_F_CPU1_SA_CA<5>")
	)
	(segment
		(start 81.044034 -254.691896)
		(end 81.052416 -254.68707)
		(width 0.0889)
		(layer "In11.Cu")
		(net "M_F_CPU1_SA_CA<5>")
	)
	(segment
		(start 18.032984 -252.160278)
		(end 22.069044 -252.160278)
		(width 0.14478)
		(layer "In11.Cu")
		(net "M_F_CPU1_SA_CA<5>")
	)
	(segment
		(start 23.769066 -253.8603)
		(end 59.933078 -253.8603)
		(width 0.14478)
		(layer "In11.Cu")
		(net "M_F_CPU1_SA_CA<5>")
	)
	(segment
		(start 60.318142 -254.245364)
		(end 71.91121 -254.245364)
		(width 0.14478)
		(layer "In11.Cu")
		(net "M_F_CPU1_SA_CA<5>")
	)
	(segment
		(start 84.205064 -254.749046)
		(end 84.05114 -255.014476)
		(width 0.0889)
		(layer "In11.Cu")
		(net "M_F_CPU1_SA_CA<5>")
	)
	(segment
		(start 76.646786 -255.098804)
		(end 77.126846 -255.098804)
		(width 0.0889)
		(layer "In11.Cu")
		(net "M_F_CPU1_SA_CA<5>")
	)
	(segment
		(start 77.126846 -255.098804)
		(end 77.457554 -254.768096)
		(width 0.0889)
		(layer "In11.Cu")
		(net "M_F_CPU1_SA_CA<5>")
	)
	(segment
		(start 59.933078 -253.8603)
		(end 60.318142 -254.245364)
		(width 0.14478)
		(layer "In11.Cu")
		(net "M_F_CPU1_SA_CA<5>")
	)
	(segment
		(start 71.91121 -254.245364)
		(end 73.22693 -255.561084)
		(width 0.14478)
		(layer "In11.Cu")
		(net "M_F_CPU1_SA_CA<5>")
	)
	(segment
		(start 79.525114 -254.684276)
		(end 79.53883 -254.69215)
		(width 0.0889)
		(layer "In11.Cu")
		(net "M_F_CPU1_SA_CA<5>")
	)
	(segment
		(start 80.46974 -254.68707)
		(end 80.478122 -254.691896)
		(width 0.0889)
		(layer "In11.Cu")
		(net "M_F_CPU1_SA_CA<5>")
	)
	(segment
		(start 73.22693 -255.561084)
		(end 75.991466 -255.561084)
		(width 0.14478)
		(layer "In11.Cu")
		(net "M_F_CPU1_SA_CA<5>")
	)
	(segment
		(start 22.069044 -252.160278)
		(end 23.769066 -253.8603)
		(width 0.14478)
		(layer "In11.Cu")
		(net "M_F_CPU1_SA_CA<5>")
	)
	(segment
		(start 76.184506 -255.561084)
		(end 76.646786 -255.098804)
		(width 0.0889)
		(layer "In11.Cu")
		(net "M_F_CPU1_SA_CA<5>")
	)
	(segment
		(start 77.457554 -254.768096)
		(end 77.942186 -254.768096)
		(width 0.0889)
		(layer "In11.Cu")
		(net "M_F_CPU1_SA_CA<5>")
	)
	(segment
		(start 83.289648 -254.68707)
		(end 83.29803 -254.691896)
		(width 0.0889)
		(layer "In11.Cu")
		(net "M_F_CPU1_SA_CA<5>")
	)
	(segment
		(start 17.608042 -251.735336)
		(end 18.032984 -252.160278)
		(width 0.14478)
		(layer "In11.Cu")
		(net "M_F_CPU1_SA_CA<5>")
	)
	(segment
		(start 79.53883 -254.69215)
		(end 79.550768 -254.699008)
		(width 0.0889)
		(layer "In11.Cu")
		(net "M_F_CPU1_SA_CA<5>")
	)
	(segment
		(start 75.991466 -255.561084)
		(end 76.184506 -255.561084)
		(width 0.0889)
		(layer "In11.Cu")
		(net "M_F_CPU1_SA_CA<5>")
	)
	(arc
		(start 78.598522 -254.691896)
		(mid 78.871466 -254.768476)
		(end 79.147162 -254.702564)
		(width 0.0889)
		(layer "In11.Cu")
		(net "M_F_CPU1_SA_CA<5>")
	)
	(arc
		(start 82.357976 -254.691896)
		(mid 82.640932 -254.768073)
		(end 82.923888 -254.691896)
		(width 0.0889)
		(layer "In11.Cu")
		(net "M_F_CPU1_SA_CA<5>")
	)
	(arc
		(start 83.29803 -254.691896)
		(mid 83.580986 -254.768073)
		(end 83.863942 -254.691896)
		(width 0.0889)
		(layer "In11.Cu")
		(net "M_F_CPU1_SA_CA<5>")
	)
	(arc
		(start 83.863942 -254.691896)
		(mid 84.02038 -254.642925)
		(end 84.182712 -254.665734)
		(width 0.0889)
		(layer "In11.Cu")
		(net "M_F_CPU1_SA_CA<5>")
	)
	(arc
		(start 81.418176 -254.691896)
		(mid 81.701132 -254.768073)
		(end 81.984088 -254.691896)
		(width 0.0889)
		(layer "In11.Cu")
		(net "M_F_CPU1_SA_CA<5>")
	)
	(arc
		(start 78.2447 -254.68072)
		(mid 78.423032 -254.641623)
		(end 78.598522 -254.691896)
		(width 0.0889)
		(layer "In11.Cu")
		(net "M_F_CPU1_SA_CA<5>")
	)
	(arc
		(start 80.10398 -254.691896)
		(mid 80.286231 -254.641546)
		(end 80.46974 -254.68707)
		(width 0.0889)
		(layer "In11.Cu")
		(net "M_F_CPU1_SA_CA<5>")
	)
	(arc
		(start 79.550768 -254.699008)
		(mid 79.828302 -254.767989)
		(end 80.10398 -254.691896)
		(width 0.0889)
		(layer "In11.Cu")
		(net "M_F_CPU1_SA_CA<5>")
	)
	(arc
		(start 82.923888 -254.691896)
		(mid 83.106139 -254.641546)
		(end 83.289648 -254.68707)
		(width 0.0889)
		(layer "In11.Cu")
		(net "M_F_CPU1_SA_CA<5>")
	)
	(arc
		(start 81.052416 -254.68707)
		(mid 81.235924 -254.641576)
		(end 81.418176 -254.691896)
		(width 0.0889)
		(layer "In11.Cu")
		(net "M_F_CPU1_SA_CA<5>")
	)
	(arc
		(start 81.984088 -254.691896)
		(mid 82.171032 -254.641641)
		(end 82.357976 -254.691896)
		(width 0.0889)
		(layer "In11.Cu")
		(net "M_F_CPU1_SA_CA<5>")
	)
	(arc
		(start 77.942186 -254.768096)
		(mid 78.088434 -254.748791)
		(end 78.224634 -254.69215)
		(width 0.0889)
		(layer "In11.Cu")
		(net "M_F_CPU1_SA_CA<5>")
	)
	(arc
		(start 79.165196 -254.691896)
		(mid 79.344183 -254.641726)
		(end 79.525114 -254.684276)
		(width 0.0889)
		(layer "In11.Cu")
		(net "M_F_CPU1_SA_CA<5>")
	)
	(arc
		(start 80.478122 -254.691896)
		(mid 80.761078 -254.768073)
		(end 81.044034 -254.691896)
		(width 0.0889)
		(layer "In11.Cu")
		(net "M_F_CPU1_SA_CA<5>")
	)
	(segment
		(start 84.987892 -254.470408)
		(end 84.52104 -254.20447)
		(width 0.10668)
		(layer "F.Cu")
		(net "M_F_CPU1_SA_CA<4>")
	)
	(segment
		(start 38.396926 -253.399544)
		(end 38.559994 -253.236476)
		(width 0.14478)
		(layer "In11.Cu")
		(net "M_F_CPU1_SA_CA<4>")
	)
	(segment
		(start 27.493976 -253.402084)
		(end 27.657044 -253.239016)
		(width 0.14478)
		(layer "In11.Cu")
		(net "M_F_CPU1_SA_CA<4>")
	)
	(segment
		(start 76.441046 -254.854964)
		(end 77.020166 -254.854964)
		(width 0.0889)
		(layer "In11.Cu")
		(net "M_F_CPU1_SA_CA<4>")
	)
	(segment
		(start 25.987502 -253.239016)
		(end 26.15057 -253.402084)
		(width 0.14478)
		(layer "In11.Cu")
		(net "M_F_CPU1_SA_CA<4>")
	)
	(segment
		(start 35.510978 -253.17323)
		(end 35.674046 -253.010162)
		(width 0.14478)
		(layer "In11.Cu")
		(net "M_F_CPU1_SA_CA<4>")
	)
	(segment
		(start 30.82925 -253.17323)
		(end 30.992318 -253.010162)
		(width 0.14478)
		(layer "In11.Cu")
		(net "M_F_CPU1_SA_CA<4>")
	)
	(segment
		(start 38.00348 -253.17323)
		(end 38.00348 -253.236476)
		(width 0.14478)
		(layer "In11.Cu")
		(net "M_F_CPU1_SA_CA<4>")
	)
	(segment
		(start 26.937462 -253.010162)
		(end 27.10053 -253.17323)
		(width 0.14478)
		(layer "In11.Cu")
		(net "M_F_CPU1_SA_CA<4>")
	)
	(segment
		(start 27.657044 -253.239016)
		(end 27.657044 -253.17323)
		(width 0.14478)
		(layer "In11.Cu")
		(net "M_F_CPU1_SA_CA<4>")
	)
	(segment
		(start 35.674046 -253.010162)
		(end 37.840412 -253.010162)
		(width 0.14478)
		(layer "In11.Cu")
		(net "M_F_CPU1_SA_CA<4>")
	)
	(segment
		(start 30.272736 -253.239016)
		(end 30.435804 -253.402084)
		(width 0.14478)
		(layer "In11.Cu")
		(net "M_F_CPU1_SA_CA<4>")
	)
	(segment
		(start 25.824434 -253.010162)
		(end 25.987502 -253.17323)
		(width 0.14478)
		(layer "In11.Cu")
		(net "M_F_CPU1_SA_CA<4>")
	)
	(segment
		(start 77.020166 -254.854964)
		(end 77.297534 -254.577596)
		(width 0.0889)
		(layer "In11.Cu")
		(net "M_F_CPU1_SA_CA<4>")
	)
	(segment
		(start 38.00348 -253.236476)
		(end 38.166548 -253.399544)
		(width 0.14478)
		(layer "In11.Cu")
		(net "M_F_CPU1_SA_CA<4>")
	)
	(segment
		(start 25.987502 -253.17323)
		(end 25.987502 -253.239016)
		(width 0.14478)
		(layer "In11.Cu")
		(net "M_F_CPU1_SA_CA<4>")
	)
	(segment
		(start 31.77921 -253.402084)
		(end 31.942278 -253.239016)
		(width 0.14478)
		(layer "In11.Cu")
		(net "M_F_CPU1_SA_CA<4>")
	)
	(segment
		(start 31.548832 -253.402084)
		(end 31.77921 -253.402084)
		(width 0.14478)
		(layer "In11.Cu")
		(net "M_F_CPU1_SA_CA<4>")
	)
	(segment
		(start 34.004504 -253.402084)
		(end 34.234882 -253.402084)
		(width 0.14478)
		(layer "In11.Cu")
		(net "M_F_CPU1_SA_CA<4>")
	)
	(segment
		(start 72.099678 -253.790704)
		(end 73.415398 -255.106424)
		(width 0.14478)
		(layer "In11.Cu")
		(net "M_F_CPU1_SA_CA<4>")
	)
	(segment
		(start 26.544016 -253.17323)
		(end 26.707084 -253.010162)
		(width 0.14478)
		(layer "In11.Cu")
		(net "M_F_CPU1_SA_CA<4>")
	)
	(segment
		(start 26.707084 -253.010162)
		(end 26.937462 -253.010162)
		(width 0.14478)
		(layer "In11.Cu")
		(net "M_F_CPU1_SA_CA<4>")
	)
	(segment
		(start 79.0575 -254.533908)
		(end 79.069184 -254.52705)
		(width 0.0889)
		(layer "In11.Cu")
		(net "M_F_CPU1_SA_CA<4>")
	)
	(segment
		(start 76.189586 -255.106424)
		(end 76.441046 -254.854964)
		(width 0.0889)
		(layer "In11.Cu")
		(net "M_F_CPU1_SA_CA<4>")
	)
	(segment
		(start 30.109668 -253.010162)
		(end 30.272736 -253.17323)
		(width 0.14478)
		(layer "In11.Cu")
		(net "M_F_CPU1_SA_CA<4>")
	)
	(segment
		(start 30.992318 -253.010162)
		(end 31.222696 -253.010162)
		(width 0.14478)
		(layer "In11.Cu")
		(net "M_F_CPU1_SA_CA<4>")
	)
	(segment
		(start 35.34791 -253.402084)
		(end 35.510978 -253.239016)
		(width 0.14478)
		(layer "In11.Cu")
		(net "M_F_CPU1_SA_CA<4>")
	)
	(segment
		(start 31.942278 -253.239016)
		(end 31.942278 -253.17323)
		(width 0.14478)
		(layer "In11.Cu")
		(net "M_F_CPU1_SA_CA<4>")
	)
	(segment
		(start 38.166548 -253.399544)
		(end 38.396926 -253.399544)
		(width 0.14478)
		(layer "In11.Cu")
		(net "M_F_CPU1_SA_CA<4>")
	)
	(segment
		(start 35.510978 -253.239016)
		(end 35.510978 -253.17323)
		(width 0.14478)
		(layer "In11.Cu")
		(net "M_F_CPU1_SA_CA<4>")
	)
	(segment
		(start 26.15057 -253.402084)
		(end 26.380948 -253.402084)
		(width 0.14478)
		(layer "In11.Cu")
		(net "M_F_CPU1_SA_CA<4>")
	)
	(segment
		(start 37.840412 -253.010162)
		(end 38.00348 -253.17323)
		(width 0.14478)
		(layer "In11.Cu")
		(net "M_F_CPU1_SA_CA<4>")
	)
	(segment
		(start 38.559994 -253.236476)
		(end 38.559994 -253.17323)
		(width 0.14478)
		(layer "In11.Cu")
		(net "M_F_CPU1_SA_CA<4>")
	)
	(segment
		(start 34.39795 -253.239016)
		(end 34.39795 -253.17323)
		(width 0.14478)
		(layer "In11.Cu")
		(net "M_F_CPU1_SA_CA<4>")
	)
	(segment
		(start 30.82925 -253.239016)
		(end 30.82925 -253.17323)
		(width 0.14478)
		(layer "In11.Cu")
		(net "M_F_CPU1_SA_CA<4>")
	)
	(segment
		(start 34.954464 -253.17323)
		(end 34.954464 -253.239016)
		(width 0.14478)
		(layer "In11.Cu")
		(net "M_F_CPU1_SA_CA<4>")
	)
	(segment
		(start 32.105346 -253.010162)
		(end 33.678368 -253.010162)
		(width 0.14478)
		(layer "In11.Cu")
		(net "M_F_CPU1_SA_CA<4>")
	)
	(segment
		(start 30.666182 -253.402084)
		(end 30.82925 -253.239016)
		(width 0.14478)
		(layer "In11.Cu")
		(net "M_F_CPU1_SA_CA<4>")
	)
	(segment
		(start 59.74588 -253.010162)
		(end 60.526422 -253.790704)
		(width 0.14478)
		(layer "In11.Cu")
		(net "M_F_CPU1_SA_CA<4>")
	)
	(segment
		(start 26.380948 -253.402084)
		(end 26.544016 -253.239016)
		(width 0.14478)
		(layer "In11.Cu")
		(net "M_F_CPU1_SA_CA<4>")
	)
	(segment
		(start 34.954464 -253.239016)
		(end 35.117532 -253.402084)
		(width 0.14478)
		(layer "In11.Cu")
		(net "M_F_CPU1_SA_CA<4>")
	)
	(segment
		(start 79.622396 -254.519938)
		(end 79.634334 -254.526796)
		(width 0.0889)
		(layer "In11.Cu")
		(net "M_F_CPU1_SA_CA<4>")
	)
	(segment
		(start 34.234882 -253.402084)
		(end 34.39795 -253.239016)
		(width 0.14478)
		(layer "In11.Cu")
		(net "M_F_CPU1_SA_CA<4>")
	)
	(segment
		(start 27.10053 -253.239016)
		(end 27.263598 -253.402084)
		(width 0.14478)
		(layer "In11.Cu")
		(net "M_F_CPU1_SA_CA<4>")
	)
	(segment
		(start 31.222696 -253.010162)
		(end 31.385764 -253.17323)
		(width 0.14478)
		(layer "In11.Cu")
		(net "M_F_CPU1_SA_CA<4>")
	)
	(segment
		(start 31.942278 -253.17323)
		(end 32.105346 -253.010162)
		(width 0.14478)
		(layer "In11.Cu")
		(net "M_F_CPU1_SA_CA<4>")
	)
	(segment
		(start 73.415398 -255.106424)
		(end 75.978766 -255.106424)
		(width 0.14478)
		(layer "In11.Cu")
		(net "M_F_CPU1_SA_CA<4>")
	)
	(segment
		(start 34.39795 -253.17323)
		(end 34.561018 -253.010162)
		(width 0.14478)
		(layer "In11.Cu")
		(net "M_F_CPU1_SA_CA<4>")
	)
	(segment
		(start 27.263598 -253.402084)
		(end 27.493976 -253.402084)
		(width 0.14478)
		(layer "In11.Cu")
		(net "M_F_CPU1_SA_CA<4>")
	)
	(segment
		(start 33.678368 -253.010162)
		(end 33.841436 -253.17323)
		(width 0.14478)
		(layer "In11.Cu")
		(net "M_F_CPU1_SA_CA<4>")
	)
	(segment
		(start 81.879694 -254.531876)
		(end 81.888076 -254.52705)
		(width 0.0889)
		(layer "In11.Cu")
		(net "M_F_CPU1_SA_CA<4>")
	)
	(segment
		(start 26.544016 -253.239016)
		(end 26.544016 -253.17323)
		(width 0.14478)
		(layer "In11.Cu")
		(net "M_F_CPU1_SA_CA<4>")
	)
	(segment
		(start 78.128876 -254.526796)
		(end 78.150466 -254.51435)
		(width 0.0889)
		(layer "In11.Cu")
		(net "M_F_CPU1_SA_CA<4>")
	)
	(segment
		(start 38.559994 -253.17323)
		(end 38.723062 -253.010162)
		(width 0.14478)
		(layer "In11.Cu")
		(net "M_F_CPU1_SA_CA<4>")
	)
	(segment
		(start 30.435804 -253.402084)
		(end 30.666182 -253.402084)
		(width 0.14478)
		(layer "In11.Cu")
		(net "M_F_CPU1_SA_CA<4>")
	)
	(segment
		(start 31.385764 -253.239016)
		(end 31.548832 -253.402084)
		(width 0.14478)
		(layer "In11.Cu")
		(net "M_F_CPU1_SA_CA<4>")
	)
	(segment
		(start 33.841436 -253.17323)
		(end 33.841436 -253.239016)
		(width 0.14478)
		(layer "In11.Cu")
		(net "M_F_CPU1_SA_CA<4>")
	)
	(segment
		(start 31.385764 -253.17323)
		(end 31.385764 -253.239016)
		(width 0.14478)
		(layer "In11.Cu")
		(net "M_F_CPU1_SA_CA<4>")
	)
	(segment
		(start 83.394042 -254.52705)
		(end 83.402424 -254.531876)
		(width 0.0889)
		(layer "In11.Cu")
		(net "M_F_CPU1_SA_CA<4>")
	)
	(segment
		(start 84.367116 -254.4699)
		(end 84.52104 -254.20447)
		(width 0.0889)
		(layer "In11.Cu")
		(net "M_F_CPU1_SA_CA<4>")
	)
	(segment
		(start 34.791396 -253.010162)
		(end 34.954464 -253.17323)
		(width 0.14478)
		(layer "In11.Cu")
		(net "M_F_CPU1_SA_CA<4>")
	)
	(segment
		(start 84.271104 -254.4953)
		(end 84.367116 -254.4699)
		(width 0.0889)
		(layer "In11.Cu")
		(net "M_F_CPU1_SA_CA<4>")
	)
	(segment
		(start 38.723062 -253.010162)
		(end 59.74588 -253.010162)
		(width 0.14478)
		(layer "In11.Cu")
		(net "M_F_CPU1_SA_CA<4>")
	)
	(segment
		(start 27.10053 -253.17323)
		(end 27.10053 -253.239016)
		(width 0.14478)
		(layer "In11.Cu")
		(net "M_F_CPU1_SA_CA<4>")
	)
	(segment
		(start 79.634334 -254.526796)
		(end 79.65059 -254.536194)
		(width 0.0889)
		(layer "In11.Cu")
		(net "M_F_CPU1_SA_CA<4>")
	)
	(segment
		(start 75.978766 -255.106424)
		(end 76.189586 -255.106424)
		(width 0.0889)
		(layer "In11.Cu")
		(net "M_F_CPU1_SA_CA<4>")
	)
	(segment
		(start 82.453988 -254.52705)
		(end 82.46237 -254.531876)
		(width 0.0889)
		(layer "In11.Cu")
		(net "M_F_CPU1_SA_CA<4>")
	)
	(segment
		(start 30.272736 -253.17323)
		(end 30.272736 -253.239016)
		(width 0.14478)
		(layer "In11.Cu")
		(net "M_F_CPU1_SA_CA<4>")
	)
	(segment
		(start 27.820112 -253.010162)
		(end 30.109668 -253.010162)
		(width 0.14478)
		(layer "In11.Cu")
		(net "M_F_CPU1_SA_CA<4>")
	)
	(segment
		(start 27.657044 -253.17323)
		(end 27.820112 -253.010162)
		(width 0.14478)
		(layer "In11.Cu")
		(net "M_F_CPU1_SA_CA<4>")
	)
	(segment
		(start 34.561018 -253.010162)
		(end 34.791396 -253.010162)
		(width 0.14478)
		(layer "In11.Cu")
		(net "M_F_CPU1_SA_CA<4>")
	)
	(segment
		(start 21.70811 -250.885198)
		(end 23.833074 -253.010162)
		(width 0.14478)
		(layer "In11.Cu")
		(net "M_F_CPU1_SA_CA<4>")
	)
	(segment
		(start 23.833074 -253.010162)
		(end 25.824434 -253.010162)
		(width 0.14478)
		(layer "In11.Cu")
		(net "M_F_CPU1_SA_CA<4>")
	)
	(segment
		(start 35.117532 -253.402084)
		(end 35.34791 -253.402084)
		(width 0.14478)
		(layer "In11.Cu")
		(net "M_F_CPU1_SA_CA<4>")
	)
	(segment
		(start 33.841436 -253.239016)
		(end 34.004504 -253.402084)
		(width 0.14478)
		(layer "In11.Cu")
		(net "M_F_CPU1_SA_CA<4>")
	)
	(segment
		(start 60.526422 -253.790704)
		(end 72.099678 -253.790704)
		(width 0.14478)
		(layer "In11.Cu")
		(net "M_F_CPU1_SA_CA<4>")
	)
	(segment
		(start 77.297534 -254.577596)
		(end 77.941932 -254.577596)
		(width 0.0889)
		(layer "In11.Cu")
		(net "M_F_CPU1_SA_CA<4>")
	)
	(arc
		(start 81.888076 -254.52705)
		(mid 82.171032 -254.450873)
		(end 82.453988 -254.52705)
		(width 0.0889)
		(layer "In11.Cu")
		(net "M_F_CPU1_SA_CA<4>")
	)
	(arc
		(start 78.150466 -254.51435)
		(mid 78.424256 -254.450679)
		(end 78.694788 -254.52705)
		(width 0.0889)
		(layer "In11.Cu")
		(net "M_F_CPU1_SA_CA<4>")
	)
	(arc
		(start 78.694788 -254.52705)
		(mid 78.875246 -254.577494)
		(end 79.0575 -254.533908)
		(width 0.0889)
		(layer "In11.Cu")
		(net "M_F_CPU1_SA_CA<4>")
	)
	(arc
		(start 79.069184 -254.52705)
		(mid 79.344862 -254.45092)
		(end 79.622396 -254.519938)
		(width 0.0889)
		(layer "In11.Cu")
		(net "M_F_CPU1_SA_CA<4>")
	)
	(arc
		(start 82.82813 -254.52705)
		(mid 83.111086 -254.450873)
		(end 83.394042 -254.52705)
		(width 0.0889)
		(layer "In11.Cu")
		(net "M_F_CPU1_SA_CA<4>")
	)
	(arc
		(start 79.65059 -254.536194)
		(mid 79.830572 -254.577294)
		(end 80.008222 -254.52705)
		(width 0.0889)
		(layer "In11.Cu")
		(net "M_F_CPU1_SA_CA<4>")
	)
	(arc
		(start 80.948022 -254.52705)
		(mid 81.230978 -254.450873)
		(end 81.513934 -254.52705)
		(width 0.0889)
		(layer "In11.Cu")
		(net "M_F_CPU1_SA_CA<4>")
	)
	(arc
		(start 80.008222 -254.52705)
		(mid 80.291178 -254.450873)
		(end 80.574134 -254.52705)
		(width 0.0889)
		(layer "In11.Cu")
		(net "M_F_CPU1_SA_CA<4>")
	)
	(arc
		(start 81.513934 -254.52705)
		(mid 81.696185 -254.5774)
		(end 81.879694 -254.531876)
		(width 0.0889)
		(layer "In11.Cu")
		(net "M_F_CPU1_SA_CA<4>")
	)
	(arc
		(start 77.941932 -254.577596)
		(mid 78.03875 -254.564525)
		(end 78.128876 -254.526796)
		(width 0.0889)
		(layer "In11.Cu")
		(net "M_F_CPU1_SA_CA<4>")
	)
	(arc
		(start 83.402424 -254.531876)
		(mid 83.585932 -254.57737)
		(end 83.768184 -254.52705)
		(width 0.0889)
		(layer "In11.Cu")
		(net "M_F_CPU1_SA_CA<4>")
	)
	(arc
		(start 83.768184 -254.52705)
		(mid 84.015897 -254.45183)
		(end 84.271104 -254.4953)
		(width 0.0889)
		(layer "In11.Cu")
		(net "M_F_CPU1_SA_CA<4>")
	)
	(arc
		(start 82.46237 -254.531876)
		(mid 82.645878 -254.57737)
		(end 82.82813 -254.52705)
		(width 0.0889)
		(layer "In11.Cu")
		(net "M_F_CPU1_SA_CA<4>")
	)
	(arc
		(start 80.574134 -254.52705)
		(mid 80.761078 -254.577305)
		(end 80.948022 -254.52705)
		(width 0.0889)
		(layer "In11.Cu")
		(net "M_F_CPU1_SA_CA<4>")
	)
	(segment
		(start 85.927946 -254.470408)
		(end 85.461094 -254.20447)
		(width 0.10668)
		(layer "F.Cu")
		(net "M_F_CPU1_SA_CA<3>")
	)
	(segment
		(start 76.171806 -254.651764)
		(end 76.344526 -254.479044)
		(width 0.0889)
		(layer "In11.Cu")
		(net "M_F_CPU1_SA_CA<3>")
	)
	(segment
		(start 82.453988 -253.88189)
		(end 82.46237 -253.877064)
		(width 0.0889)
		(layer "In11.Cu")
		(net "M_F_CPU1_SA_CA<3>")
	)
	(segment
		(start 60.736734 -253.336044)
		(end 72.288146 -253.336044)
		(width 0.14478)
		(layer "In11.Cu")
		(net "M_F_CPU1_SA_CA<3>")
	)
	(segment
		(start 79.06766 -253.88189)
		(end 79.078074 -253.887986)
		(width 0.0889)
		(layer "In11.Cu")
		(net "M_F_CPU1_SA_CA<3>")
	)
	(segment
		(start 72.288146 -253.336044)
		(end 73.603866 -254.651764)
		(width 0.14478)
		(layer "In11.Cu")
		(net "M_F_CPU1_SA_CA<3>")
	)
	(segment
		(start 18.032984 -250.460256)
		(end 22.069044 -250.460256)
		(width 0.14478)
		(layer "In11.Cu")
		(net "M_F_CPU1_SA_CA<3>")
	)
	(segment
		(start 85.592666 -253.855728)
		(end 85.615018 -253.93904)
		(width 0.0889)
		(layer "In11.Cu")
		(net "M_F_CPU1_SA_CA<3>")
	)
	(segment
		(start 77.57033 -254.065024)
		(end 77.753464 -253.88189)
		(width 0.0889)
		(layer "In11.Cu")
		(net "M_F_CPU1_SA_CA<3>")
	)
	(segment
		(start 76.667106 -254.065024)
		(end 77.57033 -254.065024)
		(width 0.0889)
		(layer "In11.Cu")
		(net "M_F_CPU1_SA_CA<3>")
	)
	(segment
		(start 77.753464 -253.88189)
		(end 77.765148 -253.875032)
		(width 0.0889)
		(layer "In11.Cu")
		(net "M_F_CPU1_SA_CA<3>")
	)
	(segment
		(start 59.560968 -252.160278)
		(end 60.736734 -253.336044)
		(width 0.14478)
		(layer "In11.Cu")
		(net "M_F_CPU1_SA_CA<3>")
	)
	(segment
		(start 78.67904 -253.890526)
		(end 78.693772 -253.88189)
		(width 0.0889)
		(layer "In11.Cu")
		(net "M_F_CPU1_SA_CA<3>")
	)
	(segment
		(start 85.615018 -253.93904)
		(end 85.461094 -254.20447)
		(width 0.0889)
		(layer "In11.Cu")
		(net "M_F_CPU1_SA_CA<3>")
	)
	(segment
		(start 78.693772 -253.88189)
		(end 78.705456 -253.875032)
		(width 0.0889)
		(layer "In11.Cu")
		(net "M_F_CPU1_SA_CA<3>")
	)
	(segment
		(start 76.344526 -254.387604)
		(end 76.667106 -254.065024)
		(width 0.0889)
		(layer "In11.Cu")
		(net "M_F_CPU1_SA_CA<3>")
	)
	(segment
		(start 76.344526 -254.479044)
		(end 76.344526 -254.387604)
		(width 0.0889)
		(layer "In11.Cu")
		(net "M_F_CPU1_SA_CA<3>")
	)
	(segment
		(start 75.981306 -254.651764)
		(end 76.171806 -254.651764)
		(width 0.0889)
		(layer "In11.Cu")
		(net "M_F_CPU1_SA_CA<3>")
	)
	(segment
		(start 23.769066 -252.160278)
		(end 59.560968 -252.160278)
		(width 0.14478)
		(layer "In11.Cu")
		(net "M_F_CPU1_SA_CA<3>")
	)
	(segment
		(start 83.394042 -253.88189)
		(end 83.402424 -253.877064)
		(width 0.0889)
		(layer "In11.Cu")
		(net "M_F_CPU1_SA_CA<3>")
	)
	(segment
		(start 17.608042 -250.035314)
		(end 18.032984 -250.460256)
		(width 0.14478)
		(layer "In11.Cu")
		(net "M_F_CPU1_SA_CA<3>")
	)
	(segment
		(start 73.603866 -254.651764)
		(end 75.981306 -254.651764)
		(width 0.14478)
		(layer "In11.Cu")
		(net "M_F_CPU1_SA_CA<3>")
	)
	(segment
		(start 22.069044 -250.460256)
		(end 23.769066 -252.160278)
		(width 0.14478)
		(layer "In11.Cu")
		(net "M_F_CPU1_SA_CA<3>")
	)
	(segment
		(start 81.879694 -253.877064)
		(end 81.888076 -253.88189)
		(width 0.0889)
		(layer "In11.Cu")
		(net "M_F_CPU1_SA_CA<3>")
	)
	(arc
		(start 81.888076 -253.88189)
		(mid 82.171032 -253.958067)
		(end 82.453988 -253.88189)
		(width 0.0889)
		(layer "In11.Cu")
		(net "M_F_CPU1_SA_CA<3>")
	)
	(arc
		(start 80.008222 -253.88189)
		(mid 80.291178 -253.958067)
		(end 80.574134 -253.88189)
		(width 0.0889)
		(layer "In11.Cu")
		(net "M_F_CPU1_SA_CA<3>")
	)
	(arc
		(start 84.334096 -253.88189)
		(mid 84.52104 -253.831635)
		(end 84.707984 -253.88189)
		(width 0.0889)
		(layer "In11.Cu")
		(net "M_F_CPU1_SA_CA<3>")
	)
	(arc
		(start 79.633826 -253.88189)
		(mid 79.821024 -253.831508)
		(end 80.008222 -253.88189)
		(width 0.0889)
		(layer "In11.Cu")
		(net "M_F_CPU1_SA_CA<3>")
	)
	(arc
		(start 79.078074 -253.887986)
		(mid 79.35676 -253.958206)
		(end 79.633826 -253.88189)
		(width 0.0889)
		(layer "In11.Cu")
		(net "M_F_CPU1_SA_CA<3>")
	)
	(arc
		(start 83.768184 -253.88189)
		(mid 84.05114 -253.958067)
		(end 84.334096 -253.88189)
		(width 0.0889)
		(layer "In11.Cu")
		(net "M_F_CPU1_SA_CA<3>")
	)
	(arc
		(start 78.705456 -253.875032)
		(mid 78.887457 -253.831499)
		(end 79.06766 -253.88189)
		(width 0.0889)
		(layer "In11.Cu")
		(net "M_F_CPU1_SA_CA<3>")
	)
	(arc
		(start 77.765148 -253.875032)
		(mid 77.947403 -253.831379)
		(end 78.12786 -253.88189)
		(width 0.0889)
		(layer "In11.Cu")
		(net "M_F_CPU1_SA_CA<3>")
	)
	(arc
		(start 78.12786 -253.88189)
		(mid 78.402312 -253.958126)
		(end 78.67904 -253.890526)
		(width 0.0889)
		(layer "In11.Cu")
		(net "M_F_CPU1_SA_CA<3>")
	)
	(arc
		(start 84.707984 -253.88189)
		(mid 84.99094 -253.958067)
		(end 85.273896 -253.88189)
		(width 0.0889)
		(layer "In11.Cu")
		(net "M_F_CPU1_SA_CA<3>")
	)
	(arc
		(start 81.513934 -253.88189)
		(mid 81.696185 -253.83154)
		(end 81.879694 -253.877064)
		(width 0.0889)
		(layer "In11.Cu")
		(net "M_F_CPU1_SA_CA<3>")
	)
	(arc
		(start 80.574134 -253.88189)
		(mid 80.761078 -253.831635)
		(end 80.948022 -253.88189)
		(width 0.0889)
		(layer "In11.Cu")
		(net "M_F_CPU1_SA_CA<3>")
	)
	(arc
		(start 82.46237 -253.877064)
		(mid 82.645878 -253.83157)
		(end 82.82813 -253.88189)
		(width 0.0889)
		(layer "In11.Cu")
		(net "M_F_CPU1_SA_CA<3>")
	)
	(arc
		(start 83.402424 -253.877064)
		(mid 83.585932 -253.83157)
		(end 83.768184 -253.88189)
		(width 0.0889)
		(layer "In11.Cu")
		(net "M_F_CPU1_SA_CA<3>")
	)
	(arc
		(start 85.273896 -253.88189)
		(mid 85.430334 -253.832919)
		(end 85.592666 -253.855728)
		(width 0.0889)
		(layer "In11.Cu")
		(net "M_F_CPU1_SA_CA<3>")
	)
	(arc
		(start 80.948022 -253.88189)
		(mid 81.230978 -253.958067)
		(end 81.513934 -253.88189)
		(width 0.0889)
		(layer "In11.Cu")
		(net "M_F_CPU1_SA_CA<3>")
	)
	(arc
		(start 82.82813 -253.88189)
		(mid 83.111086 -253.958067)
		(end 83.394042 -253.88189)
		(width 0.0889)
		(layer "In11.Cu")
		(net "M_F_CPU1_SA_CA<3>")
	)
	(segment
		(start 86.397846 -253.660402)
		(end 85.930994 -253.394464)
		(width 0.10668)
		(layer "F.Cu")
		(net "M_F_CPU1_SA_CA<2>")
	)
	(segment
		(start 31.063184 -251.702824)
		(end 31.226252 -251.539756)
		(width 0.14478)
		(layer "In11.Cu")
		(net "M_F_CPU1_SA_CA<2>")
	)
	(segment
		(start 85.681058 -253.685294)
		(end 85.77707 -253.659894)
		(width 0.0889)
		(layer "In11.Cu")
		(net "M_F_CPU1_SA_CA<2>")
	)
	(segment
		(start 30.50667 -251.31014)
		(end 30.669738 -251.473208)
		(width 0.14478)
		(layer "In11.Cu")
		(net "M_F_CPU1_SA_CA<2>")
	)
	(segment
		(start 31.226252 -251.473208)
		(end 31.38932 -251.31014)
		(width 0.14478)
		(layer "In11.Cu")
		(net "M_F_CPU1_SA_CA<2>")
	)
	(segment
		(start 26.095198 -251.473208)
		(end 26.095198 -251.539756)
		(width 0.14478)
		(layer "In11.Cu")
		(net "M_F_CPU1_SA_CA<2>")
	)
	(segment
		(start 27.208226 -251.473208)
		(end 27.208226 -251.539756)
		(width 0.14478)
		(layer "In11.Cu")
		(net "M_F_CPU1_SA_CA<2>")
	)
	(segment
		(start 27.371294 -251.702824)
		(end 27.601672 -251.702824)
		(width 0.14478)
		(layer "In11.Cu")
		(net "M_F_CPU1_SA_CA<2>")
	)
	(segment
		(start 76.184506 -254.197104)
		(end 76.560426 -253.821184)
		(width 0.0889)
		(layer "In11.Cu")
		(net "M_F_CPU1_SA_CA<2>")
	)
	(segment
		(start 31.38932 -251.31014)
		(end 59.638946 -251.31014)
		(width 0.14478)
		(layer "In11.Cu")
		(net "M_F_CPU1_SA_CA<2>")
	)
	(segment
		(start 80.093566 -253.710948)
		(end 80.10398 -253.717044)
		(width 0.0889)
		(layer "In11.Cu")
		(net "M_F_CPU1_SA_CA<2>")
	)
	(segment
		(start 31.226252 -251.539756)
		(end 31.226252 -251.473208)
		(width 0.14478)
		(layer "In11.Cu")
		(net "M_F_CPU1_SA_CA<2>")
	)
	(segment
		(start 23.83282 -251.31014)
		(end 25.93213 -251.31014)
		(width 0.14478)
		(layer "In11.Cu")
		(net "M_F_CPU1_SA_CA<2>")
	)
	(segment
		(start 73.792334 -254.197104)
		(end 75.978766 -254.197104)
		(width 0.14478)
		(layer "In11.Cu")
		(net "M_F_CPU1_SA_CA<2>")
	)
	(segment
		(start 21.70811 -249.18543)
		(end 23.83282 -251.31014)
		(width 0.14478)
		(layer "In11.Cu")
		(net "M_F_CPU1_SA_CA<2>")
	)
	(segment
		(start 26.095198 -251.539756)
		(end 26.258266 -251.702824)
		(width 0.14478)
		(layer "In11.Cu")
		(net "M_F_CPU1_SA_CA<2>")
	)
	(segment
		(start 27.208226 -251.539756)
		(end 27.371294 -251.702824)
		(width 0.14478)
		(layer "In11.Cu")
		(net "M_F_CPU1_SA_CA<2>")
	)
	(segment
		(start 83.289648 -253.72187)
		(end 83.29803 -253.717044)
		(width 0.0889)
		(layer "In11.Cu")
		(net "M_F_CPU1_SA_CA<2>")
	)
	(segment
		(start 26.81478 -251.31014)
		(end 27.045158 -251.31014)
		(width 0.14478)
		(layer "In11.Cu")
		(net "M_F_CPU1_SA_CA<2>")
	)
	(segment
		(start 30.669738 -251.473208)
		(end 30.669738 -251.539756)
		(width 0.14478)
		(layer "In11.Cu")
		(net "M_F_CPU1_SA_CA<2>")
	)
	(segment
		(start 26.651712 -251.539756)
		(end 26.651712 -251.473208)
		(width 0.14478)
		(layer "In11.Cu")
		(net "M_F_CPU1_SA_CA<2>")
	)
	(segment
		(start 84.803996 -253.717044)
		(end 84.812378 -253.72187)
		(width 0.0889)
		(layer "In11.Cu")
		(net "M_F_CPU1_SA_CA<2>")
	)
	(segment
		(start 81.044034 -253.717044)
		(end 81.052416 -253.72187)
		(width 0.0889)
		(layer "In11.Cu")
		(net "M_F_CPU1_SA_CA<2>")
	)
	(segment
		(start 27.601672 -251.702824)
		(end 27.76474 -251.539756)
		(width 0.14478)
		(layer "In11.Cu")
		(net "M_F_CPU1_SA_CA<2>")
	)
	(segment
		(start 26.651712 -251.473208)
		(end 26.81478 -251.31014)
		(width 0.14478)
		(layer "In11.Cu")
		(net "M_F_CPU1_SA_CA<2>")
	)
	(segment
		(start 72.476614 -252.881384)
		(end 73.792334 -254.197104)
		(width 0.14478)
		(layer "In11.Cu")
		(net "M_F_CPU1_SA_CA<2>")
	)
	(segment
		(start 27.76474 -251.539756)
		(end 27.76474 -251.473208)
		(width 0.14478)
		(layer "In11.Cu")
		(net "M_F_CPU1_SA_CA<2>")
	)
	(segment
		(start 30.669738 -251.539756)
		(end 30.832806 -251.702824)
		(width 0.14478)
		(layer "In11.Cu")
		(net "M_F_CPU1_SA_CA<2>")
	)
	(segment
		(start 84.229702 -253.72187)
		(end 84.238084 -253.717044)
		(width 0.0889)
		(layer "In11.Cu")
		(net "M_F_CPU1_SA_CA<2>")
	)
	(segment
		(start 77.126846 -253.821184)
		(end 77.230986 -253.717044)
		(width 0.0889)
		(layer "In11.Cu")
		(net "M_F_CPU1_SA_CA<2>")
	)
	(segment
		(start 78.59776 -253.717044)
		(end 78.608174 -253.710948)
		(width 0.0889)
		(layer "In11.Cu")
		(net "M_F_CPU1_SA_CA<2>")
	)
	(segment
		(start 85.77707 -253.659894)
		(end 85.930994 -253.394464)
		(width 0.0889)
		(layer "In11.Cu")
		(net "M_F_CPU1_SA_CA<2>")
	)
	(segment
		(start 27.045158 -251.31014)
		(end 27.208226 -251.473208)
		(width 0.14478)
		(layer "In11.Cu")
		(net "M_F_CPU1_SA_CA<2>")
	)
	(segment
		(start 80.46974 -253.72187)
		(end 80.478122 -253.717044)
		(width 0.0889)
		(layer "In11.Cu")
		(net "M_F_CPU1_SA_CA<2>")
	)
	(segment
		(start 25.93213 -251.31014)
		(end 26.095198 -251.473208)
		(width 0.14478)
		(layer "In11.Cu")
		(net "M_F_CPU1_SA_CA<2>")
	)
	(segment
		(start 75.978766 -254.197104)
		(end 76.184506 -254.197104)
		(width 0.0889)
		(layer "In11.Cu")
		(net "M_F_CPU1_SA_CA<2>")
	)
	(segment
		(start 76.560426 -253.821184)
		(end 77.126846 -253.821184)
		(width 0.0889)
		(layer "In11.Cu")
		(net "M_F_CPU1_SA_CA<2>")
	)
	(segment
		(start 77.230986 -253.717044)
		(end 77.657452 -253.717044)
		(width 0.0889)
		(layer "In11.Cu")
		(net "M_F_CPU1_SA_CA<2>")
	)
	(segment
		(start 26.258266 -251.702824)
		(end 26.488644 -251.702824)
		(width 0.14478)
		(layer "In11.Cu")
		(net "M_F_CPU1_SA_CA<2>")
	)
	(segment
		(start 59.638946 -251.31014)
		(end 61.21019 -252.881384)
		(width 0.14478)
		(layer "In11.Cu")
		(net "M_F_CPU1_SA_CA<2>")
	)
	(segment
		(start 78.583282 -253.725426)
		(end 78.59776 -253.717044)
		(width 0.0889)
		(layer "In11.Cu")
		(net "M_F_CPU1_SA_CA<2>")
	)
	(segment
		(start 61.21019 -252.881384)
		(end 72.476614 -252.881384)
		(width 0.14478)
		(layer "In11.Cu")
		(net "M_F_CPU1_SA_CA<2>")
	)
	(segment
		(start 77.657452 -253.717044)
		(end 77.667866 -253.710948)
		(width 0.0889)
		(layer "In11.Cu")
		(net "M_F_CPU1_SA_CA<2>")
	)
	(segment
		(start 26.488644 -251.702824)
		(end 26.651712 -251.539756)
		(width 0.14478)
		(layer "In11.Cu")
		(net "M_F_CPU1_SA_CA<2>")
	)
	(segment
		(start 27.76474 -251.473208)
		(end 27.927808 -251.31014)
		(width 0.14478)
		(layer "In11.Cu")
		(net "M_F_CPU1_SA_CA<2>")
	)
	(segment
		(start 30.832806 -251.702824)
		(end 31.063184 -251.702824)
		(width 0.14478)
		(layer "In11.Cu")
		(net "M_F_CPU1_SA_CA<2>")
	)
	(segment
		(start 27.927808 -251.31014)
		(end 30.50667 -251.31014)
		(width 0.14478)
		(layer "In11.Cu")
		(net "M_F_CPU1_SA_CA<2>")
	)
	(arc
		(start 83.863942 -253.717044)
		(mid 84.046193 -253.767394)
		(end 84.229702 -253.72187)
		(width 0.0889)
		(layer "In11.Cu")
		(net "M_F_CPU1_SA_CA<2>")
	)
	(arc
		(start 81.984088 -253.717044)
		(mid 82.171032 -253.767299)
		(end 82.357976 -253.717044)
		(width 0.0889)
		(layer "In11.Cu")
		(net "M_F_CPU1_SA_CA<2>")
	)
	(arc
		(start 77.667866 -253.710948)
		(mid 77.946552 -253.640728)
		(end 78.223618 -253.717044)
		(width 0.0889)
		(layer "In11.Cu")
		(net "M_F_CPU1_SA_CA<2>")
	)
	(arc
		(start 84.238084 -253.717044)
		(mid 84.52104 -253.640867)
		(end 84.803996 -253.717044)
		(width 0.0889)
		(layer "In11.Cu")
		(net "M_F_CPU1_SA_CA<2>")
	)
	(arc
		(start 80.10398 -253.717044)
		(mid 80.286231 -253.767394)
		(end 80.46974 -253.72187)
		(width 0.0889)
		(layer "In11.Cu")
		(net "M_F_CPU1_SA_CA<2>")
	)
	(arc
		(start 81.052416 -253.72187)
		(mid 81.235924 -253.767364)
		(end 81.418176 -253.717044)
		(width 0.0889)
		(layer "In11.Cu")
		(net "M_F_CPU1_SA_CA<2>")
	)
	(arc
		(start 80.478122 -253.717044)
		(mid 80.761078 -253.640867)
		(end 81.044034 -253.717044)
		(width 0.0889)
		(layer "In11.Cu")
		(net "M_F_CPU1_SA_CA<2>")
	)
	(arc
		(start 82.357976 -253.717044)
		(mid 82.640932 -253.640867)
		(end 82.923888 -253.717044)
		(width 0.0889)
		(layer "In11.Cu")
		(net "M_F_CPU1_SA_CA<2>")
	)
	(arc
		(start 81.418176 -253.717044)
		(mid 81.701132 -253.640867)
		(end 81.984088 -253.717044)
		(width 0.0889)
		(layer "In11.Cu")
		(net "M_F_CPU1_SA_CA<2>")
	)
	(arc
		(start 79.163418 -253.717044)
		(mid 79.350616 -253.767426)
		(end 79.537814 -253.717044)
		(width 0.0889)
		(layer "In11.Cu")
		(net "M_F_CPU1_SA_CA<2>")
	)
	(arc
		(start 79.537814 -253.717044)
		(mid 79.814881 -253.640773)
		(end 80.093566 -253.710948)
		(width 0.0889)
		(layer "In11.Cu")
		(net "M_F_CPU1_SA_CA<2>")
	)
	(arc
		(start 78.223618 -253.717044)
		(mid 78.402373 -253.767453)
		(end 78.583282 -253.725426)
		(width 0.0889)
		(layer "In11.Cu")
		(net "M_F_CPU1_SA_CA<2>")
	)
	(arc
		(start 83.29803 -253.717044)
		(mid 83.580986 -253.640867)
		(end 83.863942 -253.717044)
		(width 0.0889)
		(layer "In11.Cu")
		(net "M_F_CPU1_SA_CA<2>")
	)
	(arc
		(start 78.608174 -253.710948)
		(mid 78.886606 -253.64085)
		(end 79.163418 -253.717044)
		(width 0.0889)
		(layer "In11.Cu")
		(net "M_F_CPU1_SA_CA<2>")
	)
	(arc
		(start 84.812378 -253.72187)
		(mid 84.995886 -253.767364)
		(end 85.178138 -253.717044)
		(width 0.0889)
		(layer "In11.Cu")
		(net "M_F_CPU1_SA_CA<2>")
	)
	(arc
		(start 82.923888 -253.717044)
		(mid 83.106139 -253.767394)
		(end 83.289648 -253.72187)
		(width 0.0889)
		(layer "In11.Cu")
		(net "M_F_CPU1_SA_CA<2>")
	)
	(arc
		(start 85.178138 -253.717044)
		(mid 85.425851 -253.641824)
		(end 85.681058 -253.685294)
		(width 0.0889)
		(layer "In11.Cu")
		(net "M_F_CPU1_SA_CA<2>")
	)
	(segment
		(start 84.517992 -253.660402)
		(end 84.05114 -253.394464)
		(width 0.10668)
		(layer "F.Cu")
		(net "M_F_CPU1_SA_CA<1>")
	)
	(segment
		(start 61.497718 -252.426724)
		(end 72.665082 -252.426724)
		(width 0.14478)
		(layer "In11.Cu")
		(net "M_F_CPU1_SA_CA<1>")
	)
	(segment
		(start 18.032984 -248.760234)
		(end 22.069044 -248.760234)
		(width 0.14478)
		(layer "In11.Cu")
		(net "M_F_CPU1_SA_CA<1>")
	)
	(segment
		(start 79.53883 -253.072138)
		(end 79.550768 -253.078996)
		(width 0.0889)
		(layer "In11.Cu")
		(net "M_F_CPU1_SA_CA<1>")
	)
	(segment
		(start 17.608042 -248.335292)
		(end 18.032984 -248.760234)
		(width 0.14478)
		(layer "In11.Cu")
		(net "M_F_CPU1_SA_CA<1>")
	)
	(segment
		(start 84.205064 -253.129034)
		(end 84.05114 -253.394464)
		(width 0.0889)
		(layer "In11.Cu")
		(net "M_F_CPU1_SA_CA<1>")
	)
	(segment
		(start 83.289648 -253.067058)
		(end 83.29803 -253.071884)
		(width 0.0889)
		(layer "In11.Cu")
		(net "M_F_CPU1_SA_CA<1>")
	)
	(segment
		(start 79.147162 -253.082552)
		(end 79.165196 -253.071884)
		(width 0.0889)
		(layer "In11.Cu")
		(net "M_F_CPU1_SA_CA<1>")
	)
	(segment
		(start 75.986386 -253.742444)
		(end 76.171806 -253.742444)
		(width 0.0889)
		(layer "In11.Cu")
		(net "M_F_CPU1_SA_CA<1>")
	)
	(segment
		(start 59.53125 -250.460256)
		(end 61.497718 -252.426724)
		(width 0.14478)
		(layer "In11.Cu")
		(net "M_F_CPU1_SA_CA<1>")
	)
	(segment
		(start 79.525114 -253.064264)
		(end 79.53883 -253.072138)
		(width 0.0889)
		(layer "In11.Cu")
		(net "M_F_CPU1_SA_CA<1>")
	)
	(segment
		(start 73.980802 -253.742444)
		(end 75.986386 -253.742444)
		(width 0.14478)
		(layer "In11.Cu")
		(net "M_F_CPU1_SA_CA<1>")
	)
	(segment
		(start 80.46974 -253.067058)
		(end 80.478122 -253.071884)
		(width 0.0889)
		(layer "In11.Cu")
		(net "M_F_CPU1_SA_CA<1>")
	)
	(segment
		(start 84.182712 -253.045722)
		(end 84.205064 -253.129034)
		(width 0.0889)
		(layer "In11.Cu")
		(net "M_F_CPU1_SA_CA<1>")
	)
	(segment
		(start 76.385166 -253.529084)
		(end 77.114146 -253.529084)
		(width 0.0889)
		(layer "In11.Cu")
		(net "M_F_CPU1_SA_CA<1>")
	)
	(segment
		(start 78.224634 -253.072138)
		(end 78.2447 -253.060708)
		(width 0.0889)
		(layer "In11.Cu")
		(net "M_F_CPU1_SA_CA<1>")
	)
	(segment
		(start 77.495146 -253.148084)
		(end 77.942186 -253.148084)
		(width 0.0889)
		(layer "In11.Cu")
		(net "M_F_CPU1_SA_CA<1>")
	)
	(segment
		(start 77.114146 -253.529084)
		(end 77.495146 -253.148084)
		(width 0.0889)
		(layer "In11.Cu")
		(net "M_F_CPU1_SA_CA<1>")
	)
	(segment
		(start 72.665082 -252.426724)
		(end 73.980802 -253.742444)
		(width 0.14478)
		(layer "In11.Cu")
		(net "M_F_CPU1_SA_CA<1>")
	)
	(segment
		(start 22.069044 -248.760234)
		(end 23.769066 -250.460256)
		(width 0.14478)
		(layer "In11.Cu")
		(net "M_F_CPU1_SA_CA<1>")
	)
	(segment
		(start 76.171806 -253.742444)
		(end 76.385166 -253.529084)
		(width 0.0889)
		(layer "In11.Cu")
		(net "M_F_CPU1_SA_CA<1>")
	)
	(segment
		(start 81.044034 -253.071884)
		(end 81.052416 -253.067058)
		(width 0.0889)
		(layer "In11.Cu")
		(net "M_F_CPU1_SA_CA<1>")
	)
	(segment
		(start 23.769066 -250.460256)
		(end 59.53125 -250.460256)
		(width 0.14478)
		(layer "In11.Cu")
		(net "M_F_CPU1_SA_CA<1>")
	)
	(arc
		(start 81.984088 -253.071884)
		(mid 82.171032 -253.021629)
		(end 82.357976 -253.071884)
		(width 0.0889)
		(layer "In11.Cu")
		(net "M_F_CPU1_SA_CA<1>")
	)
	(arc
		(start 80.478122 -253.071884)
		(mid 80.761078 -253.148061)
		(end 81.044034 -253.071884)
		(width 0.0889)
		(layer "In11.Cu")
		(net "M_F_CPU1_SA_CA<1>")
	)
	(arc
		(start 83.29803 -253.071884)
		(mid 83.580986 -253.148061)
		(end 83.863942 -253.071884)
		(width 0.0889)
		(layer "In11.Cu")
		(net "M_F_CPU1_SA_CA<1>")
	)
	(arc
		(start 78.598522 -253.071884)
		(mid 78.871466 -253.148464)
		(end 79.147162 -253.082552)
		(width 0.0889)
		(layer "In11.Cu")
		(net "M_F_CPU1_SA_CA<1>")
	)
	(arc
		(start 83.863942 -253.071884)
		(mid 84.02038 -253.022913)
		(end 84.182712 -253.045722)
		(width 0.0889)
		(layer "In11.Cu")
		(net "M_F_CPU1_SA_CA<1>")
	)
	(arc
		(start 79.165196 -253.071884)
		(mid 79.344183 -253.021714)
		(end 79.525114 -253.064264)
		(width 0.0889)
		(layer "In11.Cu")
		(net "M_F_CPU1_SA_CA<1>")
	)
	(arc
		(start 80.10398 -253.071884)
		(mid 80.286231 -253.021534)
		(end 80.46974 -253.067058)
		(width 0.0889)
		(layer "In11.Cu")
		(net "M_F_CPU1_SA_CA<1>")
	)
	(arc
		(start 81.052416 -253.067058)
		(mid 81.235924 -253.021564)
		(end 81.418176 -253.071884)
		(width 0.0889)
		(layer "In11.Cu")
		(net "M_F_CPU1_SA_CA<1>")
	)
	(arc
		(start 78.2447 -253.060708)
		(mid 78.423032 -253.021611)
		(end 78.598522 -253.071884)
		(width 0.0889)
		(layer "In11.Cu")
		(net "M_F_CPU1_SA_CA<1>")
	)
	(arc
		(start 79.550768 -253.078996)
		(mid 79.828302 -253.147977)
		(end 80.10398 -253.071884)
		(width 0.0889)
		(layer "In11.Cu")
		(net "M_F_CPU1_SA_CA<1>")
	)
	(arc
		(start 82.357976 -253.071884)
		(mid 82.640932 -253.148061)
		(end 82.923888 -253.071884)
		(width 0.0889)
		(layer "In11.Cu")
		(net "M_F_CPU1_SA_CA<1>")
	)
	(arc
		(start 81.418176 -253.071884)
		(mid 81.701132 -253.148061)
		(end 81.984088 -253.071884)
		(width 0.0889)
		(layer "In11.Cu")
		(net "M_F_CPU1_SA_CA<1>")
	)
	(arc
		(start 77.942186 -253.148084)
		(mid 78.088434 -253.128779)
		(end 78.224634 -253.072138)
		(width 0.0889)
		(layer "In11.Cu")
		(net "M_F_CPU1_SA_CA<1>")
	)
	(arc
		(start 82.923888 -253.071884)
		(mid 83.106139 -253.021534)
		(end 83.289648 -253.067058)
		(width 0.0889)
		(layer "In11.Cu")
		(net "M_F_CPU1_SA_CA<1>")
	)
	(segment
		(start 84.987892 -252.850396)
		(end 84.52104 -252.584458)
		(width 0.10668)
		(layer "F.Cu")
		(net "M_F_CPU1_SA_CA<0>")
	)
	(segment
		(start 79.622396 -252.899926)
		(end 79.634334 -252.906784)
		(width 0.0889)
		(layer "In11.Cu")
		(net "M_F_CPU1_SA_CA<0>")
	)
	(segment
		(start 34.684208 -249.610372)
		(end 34.914586 -249.610372)
		(width 0.14478)
		(layer "In11.Cu")
		(net "M_F_CPU1_SA_CA<0>")
	)
	(segment
		(start 26.527252 -250.001024)
		(end 26.69032 -249.837956)
		(width 0.14478)
		(layer "In11.Cu")
		(net "M_F_CPU1_SA_CA<0>")
	)
	(segment
		(start 26.133806 -249.77344)
		(end 26.133806 -249.837956)
		(width 0.14478)
		(layer "In11.Cu")
		(net "M_F_CPU1_SA_CA<0>")
	)
	(segment
		(start 27.246834 -249.77344)
		(end 27.246834 -249.837956)
		(width 0.14478)
		(layer "In11.Cu")
		(net "M_F_CPU1_SA_CA<0>")
	)
	(segment
		(start 79.634334 -252.906784)
		(end 79.65059 -252.916182)
		(width 0.0889)
		(layer "In11.Cu")
		(net "M_F_CPU1_SA_CA<0>")
	)
	(segment
		(start 27.409902 -250.001024)
		(end 27.64028 -250.001024)
		(width 0.14478)
		(layer "In11.Cu")
		(net "M_F_CPU1_SA_CA<0>")
	)
	(segment
		(start 38.54831 -249.840496)
		(end 38.54831 -249.77344)
		(width 0.14478)
		(layer "In11.Cu")
		(net "M_F_CPU1_SA_CA<0>")
	)
	(segment
		(start 27.803348 -249.837956)
		(end 27.803348 -249.77344)
		(width 0.14478)
		(layer "In11.Cu")
		(net "M_F_CPU1_SA_CA<0>")
	)
	(segment
		(start 31.399734 -249.77344)
		(end 31.562802 -249.610372)
		(width 0.14478)
		(layer "In11.Cu")
		(net "M_F_CPU1_SA_CA<0>")
	)
	(segment
		(start 35.634168 -249.840496)
		(end 35.634168 -249.77344)
		(width 0.14478)
		(layer "In11.Cu")
		(net "M_F_CPU1_SA_CA<0>")
	)
	(segment
		(start 79.0575 -252.913896)
		(end 79.069184 -252.907038)
		(width 0.0889)
		(layer "In11.Cu")
		(net "M_F_CPU1_SA_CA<0>")
	)
	(segment
		(start 84.367116 -252.849888)
		(end 84.52104 -252.584458)
		(width 0.0889)
		(layer "In11.Cu")
		(net "M_F_CPU1_SA_CA<0>")
	)
	(segment
		(start 81.879694 -252.911864)
		(end 81.888076 -252.907038)
		(width 0.0889)
		(layer "In11.Cu")
		(net "M_F_CPU1_SA_CA<0>")
	)
	(segment
		(start 37.991796 -249.77344)
		(end 37.991796 -249.840496)
		(width 0.14478)
		(layer "In11.Cu")
		(net "M_F_CPU1_SA_CA<0>")
	)
	(segment
		(start 26.296874 -250.001024)
		(end 26.527252 -250.001024)
		(width 0.14478)
		(layer "In11.Cu")
		(net "M_F_CPU1_SA_CA<0>")
	)
	(segment
		(start 37.828728 -249.610372)
		(end 37.991796 -249.77344)
		(width 0.14478)
		(layer "In11.Cu")
		(net "M_F_CPU1_SA_CA<0>")
	)
	(segment
		(start 33.964626 -249.840496)
		(end 34.127694 -250.003564)
		(width 0.14478)
		(layer "In11.Cu")
		(net "M_F_CPU1_SA_CA<0>")
	)
	(segment
		(start 35.797236 -249.610372)
		(end 37.828728 -249.610372)
		(width 0.14478)
		(layer "In11.Cu")
		(net "M_F_CPU1_SA_CA<0>")
	)
	(segment
		(start 76.946506 -253.254764)
		(end 77.243686 -252.957584)
		(width 0.0889)
		(layer "In11.Cu")
		(net "M_F_CPU1_SA_CA<0>")
	)
	(segment
		(start 26.69032 -249.837956)
		(end 26.69032 -249.77344)
		(width 0.14478)
		(layer "In11.Cu")
		(net "M_F_CPU1_SA_CA<0>")
	)
	(segment
		(start 27.966416 -249.610372)
		(end 30.680152 -249.610372)
		(width 0.14478)
		(layer "In11.Cu")
		(net "M_F_CPU1_SA_CA<0>")
	)
	(segment
		(start 34.358072 -250.003564)
		(end 34.52114 -249.840496)
		(width 0.14478)
		(layer "In11.Cu")
		(net "M_F_CPU1_SA_CA<0>")
	)
	(segment
		(start 72.85355 -251.972064)
		(end 74.16927 -253.287784)
		(width 0.14478)
		(layer "In11.Cu")
		(net "M_F_CPU1_SA_CA<0>")
	)
	(segment
		(start 31.006288 -250.001024)
		(end 31.236666 -250.001024)
		(width 0.14478)
		(layer "In11.Cu")
		(net "M_F_CPU1_SA_CA<0>")
	)
	(segment
		(start 30.84322 -249.837956)
		(end 31.006288 -250.001024)
		(width 0.14478)
		(layer "In11.Cu")
		(net "M_F_CPU1_SA_CA<0>")
	)
	(segment
		(start 77.243686 -252.957584)
		(end 77.941932 -252.957584)
		(width 0.0889)
		(layer "In11.Cu")
		(net "M_F_CPU1_SA_CA<0>")
	)
	(segment
		(start 37.991796 -249.840496)
		(end 38.154864 -250.003564)
		(width 0.14478)
		(layer "In11.Cu")
		(net "M_F_CPU1_SA_CA<0>")
	)
	(segment
		(start 31.236666 -250.001024)
		(end 31.399734 -249.837956)
		(width 0.14478)
		(layer "In11.Cu")
		(net "M_F_CPU1_SA_CA<0>")
	)
	(segment
		(start 27.803348 -249.77344)
		(end 27.966416 -249.610372)
		(width 0.14478)
		(layer "In11.Cu")
		(net "M_F_CPU1_SA_CA<0>")
	)
	(segment
		(start 31.562802 -249.610372)
		(end 33.801558 -249.610372)
		(width 0.14478)
		(layer "In11.Cu")
		(net "M_F_CPU1_SA_CA<0>")
	)
	(segment
		(start 84.271104 -252.875288)
		(end 84.367116 -252.849888)
		(width 0.0889)
		(layer "In11.Cu")
		(net "M_F_CPU1_SA_CA<0>")
	)
	(segment
		(start 38.385242 -250.003564)
		(end 38.54831 -249.840496)
		(width 0.14478)
		(layer "In11.Cu")
		(net "M_F_CPU1_SA_CA<0>")
	)
	(segment
		(start 83.394042 -252.907038)
		(end 83.402424 -252.911864)
		(width 0.0889)
		(layer "In11.Cu")
		(net "M_F_CPU1_SA_CA<0>")
	)
	(segment
		(start 35.634168 -249.77344)
		(end 35.797236 -249.610372)
		(width 0.14478)
		(layer "In11.Cu")
		(net "M_F_CPU1_SA_CA<0>")
	)
	(segment
		(start 21.70811 -247.485408)
		(end 23.833074 -249.610372)
		(width 0.14478)
		(layer "In11.Cu")
		(net "M_F_CPU1_SA_CA<0>")
	)
	(segment
		(start 76.202286 -253.254764)
		(end 76.946506 -253.254764)
		(width 0.0889)
		(layer "In11.Cu")
		(net "M_F_CPU1_SA_CA<0>")
	)
	(segment
		(start 59.594242 -249.610372)
		(end 61.955934 -251.972064)
		(width 0.14478)
		(layer "In11.Cu")
		(net "M_F_CPU1_SA_CA<0>")
	)
	(segment
		(start 35.077654 -249.77344)
		(end 35.077654 -249.840496)
		(width 0.14478)
		(layer "In11.Cu")
		(net "M_F_CPU1_SA_CA<0>")
	)
	(segment
		(start 30.84322 -249.77344)
		(end 30.84322 -249.837956)
		(width 0.14478)
		(layer "In11.Cu")
		(net "M_F_CPU1_SA_CA<0>")
	)
	(segment
		(start 27.083766 -249.610372)
		(end 27.246834 -249.77344)
		(width 0.14478)
		(layer "In11.Cu")
		(net "M_F_CPU1_SA_CA<0>")
	)
	(segment
		(start 26.133806 -249.837956)
		(end 26.296874 -250.001024)
		(width 0.14478)
		(layer "In11.Cu")
		(net "M_F_CPU1_SA_CA<0>")
	)
	(segment
		(start 30.680152 -249.610372)
		(end 30.84322 -249.77344)
		(width 0.14478)
		(layer "In11.Cu")
		(net "M_F_CPU1_SA_CA<0>")
	)
	(segment
		(start 38.54831 -249.77344)
		(end 38.711378 -249.610372)
		(width 0.14478)
		(layer "In11.Cu")
		(net "M_F_CPU1_SA_CA<0>")
	)
	(segment
		(start 35.4711 -250.003564)
		(end 35.634168 -249.840496)
		(width 0.14478)
		(layer "In11.Cu")
		(net "M_F_CPU1_SA_CA<0>")
	)
	(segment
		(start 27.246834 -249.837956)
		(end 27.409902 -250.001024)
		(width 0.14478)
		(layer "In11.Cu")
		(net "M_F_CPU1_SA_CA<0>")
	)
	(segment
		(start 76.169266 -253.287784)
		(end 76.202286 -253.254764)
		(width 0.0889)
		(layer "In11.Cu")
		(net "M_F_CPU1_SA_CA<0>")
	)
	(segment
		(start 34.52114 -249.840496)
		(end 34.52114 -249.77344)
		(width 0.14478)
		(layer "In11.Cu")
		(net "M_F_CPU1_SA_CA<0>")
	)
	(segment
		(start 26.69032 -249.77344)
		(end 26.853388 -249.610372)
		(width 0.14478)
		(layer "In11.Cu")
		(net "M_F_CPU1_SA_CA<0>")
	)
	(segment
		(start 35.240722 -250.003564)
		(end 35.4711 -250.003564)
		(width 0.14478)
		(layer "In11.Cu")
		(net "M_F_CPU1_SA_CA<0>")
	)
	(segment
		(start 33.801558 -249.610372)
		(end 33.964626 -249.77344)
		(width 0.14478)
		(layer "In11.Cu")
		(net "M_F_CPU1_SA_CA<0>")
	)
	(segment
		(start 78.128876 -252.906784)
		(end 78.150466 -252.894338)
		(width 0.0889)
		(layer "In11.Cu")
		(net "M_F_CPU1_SA_CA<0>")
	)
	(segment
		(start 33.964626 -249.77344)
		(end 33.964626 -249.840496)
		(width 0.14478)
		(layer "In11.Cu")
		(net "M_F_CPU1_SA_CA<0>")
	)
	(segment
		(start 74.16927 -253.287784)
		(end 75.958446 -253.287784)
		(width 0.14478)
		(layer "In11.Cu")
		(net "M_F_CPU1_SA_CA<0>")
	)
	(segment
		(start 25.970738 -249.610372)
		(end 26.133806 -249.77344)
		(width 0.14478)
		(layer "In11.Cu")
		(net "M_F_CPU1_SA_CA<0>")
	)
	(segment
		(start 27.64028 -250.001024)
		(end 27.803348 -249.837956)
		(width 0.14478)
		(layer "In11.Cu")
		(net "M_F_CPU1_SA_CA<0>")
	)
	(segment
		(start 61.955934 -251.972064)
		(end 72.85355 -251.972064)
		(width 0.14478)
		(layer "In11.Cu")
		(net "M_F_CPU1_SA_CA<0>")
	)
	(segment
		(start 31.399734 -249.837956)
		(end 31.399734 -249.77344)
		(width 0.14478)
		(layer "In11.Cu")
		(net "M_F_CPU1_SA_CA<0>")
	)
	(segment
		(start 23.833074 -249.610372)
		(end 25.970738 -249.610372)
		(width 0.14478)
		(layer "In11.Cu")
		(net "M_F_CPU1_SA_CA<0>")
	)
	(segment
		(start 35.077654 -249.840496)
		(end 35.240722 -250.003564)
		(width 0.14478)
		(layer "In11.Cu")
		(net "M_F_CPU1_SA_CA<0>")
	)
	(segment
		(start 34.127694 -250.003564)
		(end 34.358072 -250.003564)
		(width 0.14478)
		(layer "In11.Cu")
		(net "M_F_CPU1_SA_CA<0>")
	)
	(segment
		(start 34.914586 -249.610372)
		(end 35.077654 -249.77344)
		(width 0.14478)
		(layer "In11.Cu")
		(net "M_F_CPU1_SA_CA<0>")
	)
	(segment
		(start 26.853388 -249.610372)
		(end 27.083766 -249.610372)
		(width 0.14478)
		(layer "In11.Cu")
		(net "M_F_CPU1_SA_CA<0>")
	)
	(segment
		(start 75.958446 -253.287784)
		(end 76.169266 -253.287784)
		(width 0.0889)
		(layer "In11.Cu")
		(net "M_F_CPU1_SA_CA<0>")
	)
	(segment
		(start 34.52114 -249.77344)
		(end 34.684208 -249.610372)
		(width 0.14478)
		(layer "In11.Cu")
		(net "M_F_CPU1_SA_CA<0>")
	)
	(segment
		(start 82.453988 -252.907038)
		(end 82.46237 -252.911864)
		(width 0.0889)
		(layer "In11.Cu")
		(net "M_F_CPU1_SA_CA<0>")
	)
	(segment
		(start 38.154864 -250.003564)
		(end 38.385242 -250.003564)
		(width 0.14478)
		(layer "In11.Cu")
		(net "M_F_CPU1_SA_CA<0>")
	)
	(segment
		(start 38.711378 -249.610372)
		(end 59.594242 -249.610372)
		(width 0.14478)
		(layer "In11.Cu")
		(net "M_F_CPU1_SA_CA<0>")
	)
	(arc
		(start 79.069184 -252.907038)
		(mid 79.344862 -252.830908)
		(end 79.622396 -252.899926)
		(width 0.0889)
		(layer "In11.Cu")
		(net "M_F_CPU1_SA_CA<0>")
	)
	(arc
		(start 80.574134 -252.907038)
		(mid 80.761078 -252.957293)
		(end 80.948022 -252.907038)
		(width 0.0889)
		(layer "In11.Cu")
		(net "M_F_CPU1_SA_CA<0>")
	)
	(arc
		(start 80.948022 -252.907038)
		(mid 81.230978 -252.830861)
		(end 81.513934 -252.907038)
		(width 0.0889)
		(layer "In11.Cu")
		(net "M_F_CPU1_SA_CA<0>")
	)
	(arc
		(start 82.82813 -252.907038)
		(mid 83.111086 -252.830861)
		(end 83.394042 -252.907038)
		(width 0.0889)
		(layer "In11.Cu")
		(net "M_F_CPU1_SA_CA<0>")
	)
	(arc
		(start 81.888076 -252.907038)
		(mid 82.171032 -252.830861)
		(end 82.453988 -252.907038)
		(width 0.0889)
		(layer "In11.Cu")
		(net "M_F_CPU1_SA_CA<0>")
	)
	(arc
		(start 82.46237 -252.911864)
		(mid 82.645878 -252.957358)
		(end 82.82813 -252.907038)
		(width 0.0889)
		(layer "In11.Cu")
		(net "M_F_CPU1_SA_CA<0>")
	)
	(arc
		(start 78.150466 -252.894338)
		(mid 78.424256 -252.830667)
		(end 78.694788 -252.907038)
		(width 0.0889)
		(layer "In11.Cu")
		(net "M_F_CPU1_SA_CA<0>")
	)
	(arc
		(start 80.008222 -252.907038)
		(mid 80.291178 -252.830861)
		(end 80.574134 -252.907038)
		(width 0.0889)
		(layer "In11.Cu")
		(net "M_F_CPU1_SA_CA<0>")
	)
	(arc
		(start 81.513934 -252.907038)
		(mid 81.696185 -252.957388)
		(end 81.879694 -252.911864)
		(width 0.0889)
		(layer "In11.Cu")
		(net "M_F_CPU1_SA_CA<0>")
	)
	(arc
		(start 83.402424 -252.911864)
		(mid 83.585932 -252.957358)
		(end 83.768184 -252.907038)
		(width 0.0889)
		(layer "In11.Cu")
		(net "M_F_CPU1_SA_CA<0>")
	)
	(arc
		(start 78.694788 -252.907038)
		(mid 78.875246 -252.957482)
		(end 79.0575 -252.913896)
		(width 0.0889)
		(layer "In11.Cu")
		(net "M_F_CPU1_SA_CA<0>")
	)
	(arc
		(start 77.941932 -252.957584)
		(mid 78.03875 -252.944513)
		(end 78.128876 -252.906784)
		(width 0.0889)
		(layer "In11.Cu")
		(net "M_F_CPU1_SA_CA<0>")
	)
	(arc
		(start 83.768184 -252.907038)
		(mid 84.015897 -252.831818)
		(end 84.271104 -252.875288)
		(width 0.0889)
		(layer "In11.Cu")
		(net "M_F_CPU1_SA_CA<0>")
	)
	(arc
		(start 79.65059 -252.916182)
		(mid 79.830572 -252.957282)
		(end 80.008222 -252.907038)
		(width 0.0889)
		(layer "In11.Cu")
		(net "M_F_CPU1_SA_CA<0>")
	)
	(segment
		(start 85.927946 -251.230384)
		(end 85.461094 -250.964446)
		(width 0.10668)
		(layer "F.Cu")
		(net "M_F_CPU1_RESET_N")
	)
	(segment
		(start 22.592284 -245.36019)
		(end 24.292306 -247.060212)
		(width 0.11684)
		(layer "In11.Cu")
		(net "M_F_CPU1_RESET_N")
	)
	(segment
		(start 85.592666 -250.615704)
		(end 85.615018 -250.699016)
		(width 0.0889)
		(layer "In11.Cu")
		(net "M_F_CPU1_RESET_N")
	)
	(segment
		(start 81.879694 -250.63704)
		(end 81.888076 -250.641866)
		(width 0.0889)
		(layer "In11.Cu")
		(net "M_F_CPU1_RESET_N")
	)
	(segment
		(start 78.215998 -250.717558)
		(end 78.38567 -250.717558)
		(width 0.0889)
		(layer "In11.Cu")
		(net "M_F_CPU1_RESET_N")
	)
	(segment
		(start 79.63408 -250.641866)
		(end 79.642462 -250.63704)
		(width 0.0889)
		(layer "In11.Cu")
		(net "M_F_CPU1_RESET_N")
	)
	(segment
		(start 77.88275 -251.050806)
		(end 78.215998 -250.717558)
		(width 0.0889)
		(layer "In11.Cu")
		(net "M_F_CPU1_RESET_N")
	)
	(segment
		(start 76.96327 -251.612146)
		(end 77.52461 -251.050806)
		(width 0.0889)
		(layer "In11.Cu")
		(net "M_F_CPU1_RESET_N")
	)
	(segment
		(start 82.453988 -250.641866)
		(end 82.46237 -250.63704)
		(width 0.0889)
		(layer "In11.Cu")
		(net "M_F_CPU1_RESET_N")
	)
	(segment
		(start 18.032984 -245.36019)
		(end 22.592284 -245.36019)
		(width 0.11684)
		(layer "In11.Cu")
		(net "M_F_CPU1_RESET_N")
	)
	(segment
		(start 73.539604 -250.317254)
		(end 74.841354 -251.619004)
		(width 0.11684)
		(layer "In11.Cu")
		(net "M_F_CPU1_RESET_N")
	)
	(segment
		(start 63.075312 -250.317254)
		(end 73.539604 -250.317254)
		(width 0.11684)
		(layer "In11.Cu")
		(net "M_F_CPU1_RESET_N")
	)
	(segment
		(start 24.292306 -247.060212)
		(end 59.81827 -247.060212)
		(width 0.11684)
		(layer "In11.Cu")
		(net "M_F_CPU1_RESET_N")
	)
	(segment
		(start 76.140056 -251.619004)
		(end 76.146914 -251.612146)
		(width 0.0889)
		(layer "In11.Cu")
		(net "M_F_CPU1_RESET_N")
	)
	(segment
		(start 76.146914 -251.612146)
		(end 76.96327 -251.612146)
		(width 0.0889)
		(layer "In11.Cu")
		(net "M_F_CPU1_RESET_N")
	)
	(segment
		(start 17.608042 -244.935248)
		(end 18.032984 -245.36019)
		(width 0.11684)
		(layer "In11.Cu")
		(net "M_F_CPU1_RESET_N")
	)
	(segment
		(start 78.683612 -250.647962)
		(end 78.694026 -250.641866)
		(width 0.0889)
		(layer "In11.Cu")
		(net "M_F_CPU1_RESET_N")
	)
	(segment
		(start 77.52461 -251.050806)
		(end 77.88275 -251.050806)
		(width 0.0889)
		(layer "In11.Cu")
		(net "M_F_CPU1_RESET_N")
	)
	(segment
		(start 78.694026 -250.641866)
		(end 78.702408 -250.63704)
		(width 0.0889)
		(layer "In11.Cu")
		(net "M_F_CPU1_RESET_N")
	)
	(segment
		(start 83.394042 -250.641866)
		(end 83.402424 -250.63704)
		(width 0.0889)
		(layer "In11.Cu")
		(net "M_F_CPU1_RESET_N")
	)
	(segment
		(start 85.615018 -250.699016)
		(end 85.461094 -250.964446)
		(width 0.0889)
		(layer "In11.Cu")
		(net "M_F_CPU1_RESET_N")
	)
	(segment
		(start 59.81827 -247.060212)
		(end 63.075312 -250.317254)
		(width 0.11684)
		(layer "In11.Cu")
		(net "M_F_CPU1_RESET_N")
	)
	(segment
		(start 74.841354 -251.619004)
		(end 76.140056 -251.619004)
		(width 0.11684)
		(layer "In11.Cu")
		(net "M_F_CPU1_RESET_N")
	)
	(arc
		(start 81.513934 -250.641866)
		(mid 81.696185 -250.591516)
		(end 81.879694 -250.63704)
		(width 0.0889)
		(layer "In11.Cu")
		(net "M_F_CPU1_RESET_N")
	)
	(arc
		(start 78.702408 -250.63704)
		(mid 78.885916 -250.591546)
		(end 79.068168 -250.641866)
		(width 0.0889)
		(layer "In11.Cu")
		(net "M_F_CPU1_RESET_N")
	)
	(arc
		(start 82.82813 -250.641866)
		(mid 83.111086 -250.718043)
		(end 83.394042 -250.641866)
		(width 0.0889)
		(layer "In11.Cu")
		(net "M_F_CPU1_RESET_N")
	)
	(arc
		(start 84.334096 -250.641866)
		(mid 84.52104 -250.591611)
		(end 84.707984 -250.641866)
		(width 0.0889)
		(layer "In11.Cu")
		(net "M_F_CPU1_RESET_N")
	)
	(arc
		(start 83.402424 -250.63704)
		(mid 83.585932 -250.591546)
		(end 83.768184 -250.641866)
		(width 0.0889)
		(layer "In11.Cu")
		(net "M_F_CPU1_RESET_N")
	)
	(arc
		(start 79.642462 -250.63704)
		(mid 79.82597 -250.591546)
		(end 80.008222 -250.641866)
		(width 0.0889)
		(layer "In11.Cu")
		(net "M_F_CPU1_RESET_N")
	)
	(arc
		(start 84.707984 -250.641866)
		(mid 84.99094 -250.718043)
		(end 85.273896 -250.641866)
		(width 0.0889)
		(layer "In11.Cu")
		(net "M_F_CPU1_RESET_N")
	)
	(arc
		(start 83.768184 -250.641866)
		(mid 84.05114 -250.718043)
		(end 84.334096 -250.641866)
		(width 0.0889)
		(layer "In11.Cu")
		(net "M_F_CPU1_RESET_N")
	)
	(arc
		(start 80.574134 -250.641866)
		(mid 80.761078 -250.591611)
		(end 80.948022 -250.641866)
		(width 0.0889)
		(layer "In11.Cu")
		(net "M_F_CPU1_RESET_N")
	)
	(arc
		(start 80.008222 -250.641866)
		(mid 80.291178 -250.718043)
		(end 80.574134 -250.641866)
		(width 0.0889)
		(layer "In11.Cu")
		(net "M_F_CPU1_RESET_N")
	)
	(arc
		(start 81.888076 -250.641866)
		(mid 82.171032 -250.718043)
		(end 82.453988 -250.641866)
		(width 0.0889)
		(layer "In11.Cu")
		(net "M_F_CPU1_RESET_N")
	)
	(arc
		(start 79.068168 -250.641866)
		(mid 79.351124 -250.718043)
		(end 79.63408 -250.641866)
		(width 0.0889)
		(layer "In11.Cu")
		(net "M_F_CPU1_RESET_N")
	)
	(arc
		(start 82.46237 -250.63704)
		(mid 82.645878 -250.591546)
		(end 82.82813 -250.641866)
		(width 0.0889)
		(layer "In11.Cu")
		(net "M_F_CPU1_RESET_N")
	)
	(arc
		(start 85.273896 -250.641866)
		(mid 85.430334 -250.592895)
		(end 85.592666 -250.615704)
		(width 0.0889)
		(layer "In11.Cu")
		(net "M_F_CPU1_RESET_N")
	)
	(arc
		(start 78.38567 -250.717558)
		(mid 78.539462 -250.703385)
		(end 78.683612 -250.647962)
		(width 0.0889)
		(layer "In11.Cu")
		(net "M_F_CPU1_RESET_N")
	)
	(arc
		(start 80.948022 -250.641866)
		(mid 81.230978 -250.718043)
		(end 81.513934 -250.641866)
		(width 0.0889)
		(layer "In11.Cu")
		(net "M_F_CPU1_RESET_N")
	)
	(segment
		(start 84.987892 -256.09042)
		(end 84.52104 -255.824482)
		(width 0.14732)
		(layer "F.Cu")
		(net "M_F_CPU1_CLK_DP<0>")
	)
	(segment
		(start 17.608042 -253.435358)
		(end 17.881854 -253.70917)
		(width 0.16002)
		(layer "In11.Cu")
		(net "M_F_CPU1_CLK_DP<0>")
	)
	(segment
		(start 76.851002 -257.402076)
		(end 78.01483 -256.238248)
		(width 0.09525)
		(layer "In11.Cu")
		(net "M_F_CPU1_CLK_DP<0>")
	)
	(segment
		(start 83.392518 -256.149602)
		(end 83.4009 -256.154428)
		(width 0.09525)
		(layer "In11.Cu")
		(net "M_F_CPU1_CLK_DP<0>")
	)
	(segment
		(start 78.1304 -256.149602)
		(end 78.1558 -256.13487)
		(width 0.09525)
		(layer "In11.Cu")
		(net "M_F_CPU1_CLK_DP<0>")
	)
	(segment
		(start 18.767044 -253.70917)
		(end 21.474938 -256.417064)
		(width 0.16002)
		(layer "In11.Cu")
		(net "M_F_CPU1_CLK_DP<0>")
	)
	(segment
		(start 71.175118 -255.822704)
		(end 72.695308 -257.342894)
		(width 0.16002)
		(layer "In11.Cu")
		(net "M_F_CPU1_CLK_DP<0>")
	)
	(segment
		(start 75.979528 -257.342894)
		(end 76.03871 -257.402076)
		(width 0.09525)
		(layer "In11.Cu")
		(net "M_F_CPU1_CLK_DP<0>")
	)
	(segment
		(start 17.881854 -253.70917)
		(end 18.767044 -253.70917)
		(width 0.16002)
		(layer "In11.Cu")
		(net "M_F_CPU1_CLK_DP<0>")
	)
	(segment
		(start 66.021966 -255.822704)
		(end 71.175118 -255.822704)
		(width 0.16002)
		(layer "In11.Cu")
		(net "M_F_CPU1_CLK_DP<0>")
	)
	(segment
		(start 76.03871 -257.402076)
		(end 76.851002 -257.402076)
		(width 0.09525)
		(layer "In11.Cu")
		(net "M_F_CPU1_CLK_DP<0>")
	)
	(segment
		(start 84.266278 -256.116582)
		(end 84.367116 -256.089912)
		(width 0.09525)
		(layer "In11.Cu")
		(net "M_F_CPU1_CLK_DP<0>")
	)
	(segment
		(start 21.474938 -256.417064)
		(end 65.427606 -256.417064)
		(width 0.16002)
		(layer "In11.Cu")
		(net "M_F_CPU1_CLK_DP<0>")
	)
	(segment
		(start 72.695308 -257.342894)
		(end 75.955906 -257.342894)
		(width 0.16002)
		(layer "In11.Cu")
		(net "M_F_CPU1_CLK_DP<0>")
	)
	(segment
		(start 82.452464 -256.149602)
		(end 82.460846 -256.154428)
		(width 0.09525)
		(layer "In11.Cu")
		(net "M_F_CPU1_CLK_DP<0>")
	)
	(segment
		(start 79.632556 -256.149602)
		(end 79.640938 -256.154428)
		(width 0.09525)
		(layer "In11.Cu")
		(net "M_F_CPU1_CLK_DP<0>")
	)
	(segment
		(start 84.367116 -256.089912)
		(end 84.52104 -255.824482)
		(width 0.09525)
		(layer "In11.Cu")
		(net "M_F_CPU1_CLK_DP<0>")
	)
	(segment
		(start 75.955906 -257.342894)
		(end 75.979528 -257.342894)
		(width 0.09525)
		(layer "In11.Cu")
		(net "M_F_CPU1_CLK_DP<0>")
	)
	(segment
		(start 65.427606 -256.417064)
		(end 66.021966 -255.822704)
		(width 0.16002)
		(layer "In11.Cu")
		(net "M_F_CPU1_CLK_DP<0>")
	)
	(segment
		(start 81.881218 -256.154428)
		(end 81.8896 -256.149602)
		(width 0.09525)
		(layer "In11.Cu")
		(net "M_F_CPU1_CLK_DP<0>")
	)
	(segment
		(start 79.070454 -256.149602)
		(end 79.088488 -256.139188)
		(width 0.09525)
		(layer "In11.Cu")
		(net "M_F_CPU1_CLK_DP<0>")
	)
	(segment
		(start 79.055976 -256.157984)
		(end 79.070454 -256.149602)
		(width 0.09525)
		(layer "In11.Cu")
		(net "M_F_CPU1_CLK_DP<0>")
	)
	(arc
		(start 82.829654 -256.149602)
		(mid 83.111086 -256.073847)
		(end 83.392518 -256.149602)
		(width 0.09525)
		(layer "In11.Cu")
		(net "M_F_CPU1_CLK_DP<0>")
	)
	(arc
		(start 80.57261 -256.149602)
		(mid 80.761078 -256.200279)
		(end 80.949546 -256.149602)
		(width 0.09525)
		(layer "In11.Cu")
		(net "M_F_CPU1_CLK_DP<0>")
	)
	(arc
		(start 78.1558 -256.13487)
		(mid 78.426416 -256.073645)
		(end 78.693264 -256.149602)
		(width 0.09525)
		(layer "In11.Cu")
		(net "M_F_CPU1_CLK_DP<0>")
	)
	(arc
		(start 80.009746 -256.149602)
		(mid 80.291178 -256.073847)
		(end 80.57261 -256.149602)
		(width 0.09525)
		(layer "In11.Cu")
		(net "M_F_CPU1_CLK_DP<0>")
	)
	(arc
		(start 79.640938 -256.154428)
		(mid 79.82597 -256.200342)
		(end 80.009746 -256.149602)
		(width 0.09525)
		(layer "In11.Cu")
		(net "M_F_CPU1_CLK_DP<0>")
	)
	(arc
		(start 82.460846 -256.154428)
		(mid 82.645878 -256.200342)
		(end 82.829654 -256.149602)
		(width 0.09525)
		(layer "In11.Cu")
		(net "M_F_CPU1_CLK_DP<0>")
	)
	(arc
		(start 81.8896 -256.149602)
		(mid 82.171032 -256.073847)
		(end 82.452464 -256.149602)
		(width 0.09525)
		(layer "In11.Cu")
		(net "M_F_CPU1_CLK_DP<0>")
	)
	(arc
		(start 83.4009 -256.154428)
		(mid 83.585932 -256.200342)
		(end 83.769708 -256.149602)
		(width 0.09525)
		(layer "In11.Cu")
		(net "M_F_CPU1_CLK_DP<0>")
	)
	(arc
		(start 79.088488 -256.139188)
		(mid 79.361868 -256.073967)
		(end 79.632556 -256.149602)
		(width 0.09525)
		(layer "In11.Cu")
		(net "M_F_CPU1_CLK_DP<0>")
	)
	(arc
		(start 81.51241 -256.149602)
		(mid 81.696185 -256.200374)
		(end 81.881218 -256.154428)
		(width 0.09525)
		(layer "In11.Cu")
		(net "M_F_CPU1_CLK_DP<0>")
	)
	(arc
		(start 78.693264 -256.149602)
		(mid 78.873543 -256.200433)
		(end 79.055976 -256.157984)
		(width 0.09525)
		(layer "In11.Cu")
		(net "M_F_CPU1_CLK_DP<0>")
	)
	(arc
		(start 80.949546 -256.149602)
		(mid 81.230978 -256.073847)
		(end 81.51241 -256.149602)
		(width 0.09525)
		(layer "In11.Cu")
		(net "M_F_CPU1_CLK_DP<0>")
	)
	(arc
		(start 83.769708 -256.149602)
		(mid 84.014134 -256.074959)
		(end 84.266278 -256.116582)
		(width 0.09525)
		(layer "In11.Cu")
		(net "M_F_CPU1_CLK_DP<0>")
	)
	(arc
		(start 78.01483 -256.238248)
		(mid 78.069718 -256.190147)
		(end 78.1304 -256.149602)
		(width 0.09525)
		(layer "In11.Cu")
		(net "M_F_CPU1_CLK_DP<0>")
	)
	(segment
		(start 84.517992 -256.900426)
		(end 84.05114 -256.634488)
		(width 0.14732)
		(layer "F.Cu")
		(net "M_F_CPU1_CLK_DN<0>")
	)
	(segment
		(start 84.205064 -256.369058)
		(end 84.05114 -256.634488)
		(width 0.09525)
		(layer "In11.Cu")
		(net "M_F_CPU1_CLK_DN<0>")
	)
	(segment
		(start 65.552828 -256.719324)
		(end 66.147188 -256.124964)
		(width 0.16002)
		(layer "In11.Cu")
		(net "M_F_CPU1_CLK_DN<0>")
	)
	(segment
		(start 17.608042 -254.285242)
		(end 17.881854 -254.01143)
		(width 0.16002)
		(layer "In11.Cu")
		(net "M_F_CPU1_CLK_DN<0>")
	)
	(segment
		(start 76.927456 -257.586226)
		(end 78.145132 -256.36855)
		(width 0.09525)
		(layer "In11.Cu")
		(net "M_F_CPU1_CLK_DN<0>")
	)
	(segment
		(start 63.10884 -256.836164)
		(end 63.5889 -256.836164)
		(width 0.16002)
		(layer "In11.Cu")
		(net "M_F_CPU1_CLK_DN<0>")
	)
	(segment
		(start 71.049896 -256.124964)
		(end 72.570086 -257.645154)
		(width 0.16002)
		(layer "In11.Cu")
		(net "M_F_CPU1_CLK_DN<0>")
	)
	(segment
		(start 63.70574 -256.719324)
		(end 65.552828 -256.719324)
		(width 0.16002)
		(layer "In11.Cu")
		(net "M_F_CPU1_CLK_DN<0>")
	)
	(segment
		(start 18.641822 -254.01143)
		(end 21.349716 -256.719324)
		(width 0.16002)
		(layer "In11.Cu")
		(net "M_F_CPU1_CLK_DN<0>")
	)
	(segment
		(start 84.181696 -256.28219)
		(end 84.205064 -256.369058)
		(width 0.09525)
		(layer "In11.Cu")
		(net "M_F_CPU1_CLK_DN<0>")
	)
	(segment
		(start 72.570086 -257.645154)
		(end 75.955906 -257.645154)
		(width 0.16002)
		(layer "In11.Cu")
		(net "M_F_CPU1_CLK_DN<0>")
	)
	(segment
		(start 21.349716 -256.719324)
		(end 62.992 -256.719324)
		(width 0.16002)
		(layer "In11.Cu")
		(net "M_F_CPU1_CLK_DN<0>")
	)
	(segment
		(start 78.22311 -256.309368)
		(end 78.239874 -256.299716)
		(width 0.09525)
		(layer "In11.Cu")
		(net "M_F_CPU1_CLK_DN<0>")
	)
	(segment
		(start 75.955906 -257.645154)
		(end 75.979528 -257.645154)
		(width 0.09525)
		(layer "In11.Cu")
		(net "M_F_CPU1_CLK_DN<0>")
	)
	(segment
		(start 66.147188 -256.124964)
		(end 71.049896 -256.124964)
		(width 0.16002)
		(layer "In11.Cu")
		(net "M_F_CPU1_CLK_DN<0>")
	)
	(segment
		(start 79.16291 -256.309368)
		(end 79.171292 -256.304542)
		(width 0.09525)
		(layer "In11.Cu")
		(net "M_F_CPU1_CLK_DN<0>")
	)
	(segment
		(start 63.5889 -256.836164)
		(end 63.70574 -256.719324)
		(width 0.16002)
		(layer "In11.Cu")
		(net "M_F_CPU1_CLK_DN<0>")
	)
	(segment
		(start 83.291172 -256.304542)
		(end 83.299554 -256.309368)
		(width 0.09525)
		(layer "In11.Cu")
		(net "M_F_CPU1_CLK_DN<0>")
	)
	(segment
		(start 81.04251 -256.309368)
		(end 81.050892 -256.304542)
		(width 0.09525)
		(layer "In11.Cu")
		(net "M_F_CPU1_CLK_DN<0>")
	)
	(segment
		(start 79.13751 -256.3241)
		(end 79.16291 -256.309368)
		(width 0.09525)
		(layer "In11.Cu")
		(net "M_F_CPU1_CLK_DN<0>")
	)
	(segment
		(start 80.471264 -256.304542)
		(end 80.479646 -256.309368)
		(width 0.09525)
		(layer "In11.Cu")
		(net "M_F_CPU1_CLK_DN<0>")
	)
	(segment
		(start 75.979528 -257.645154)
		(end 76.038456 -257.586226)
		(width 0.09525)
		(layer "In11.Cu")
		(net "M_F_CPU1_CLK_DN<0>")
	)
	(segment
		(start 76.038456 -257.586226)
		(end 76.927456 -257.586226)
		(width 0.09525)
		(layer "In11.Cu")
		(net "M_F_CPU1_CLK_DN<0>")
	)
	(segment
		(start 17.881854 -254.01143)
		(end 18.641822 -254.01143)
		(width 0.16002)
		(layer "In11.Cu")
		(net "M_F_CPU1_CLK_DN<0>")
	)
	(segment
		(start 62.992 -256.719324)
		(end 63.10884 -256.836164)
		(width 0.16002)
		(layer "In11.Cu")
		(net "M_F_CPU1_CLK_DN<0>")
	)
	(arc
		(start 78.600046 -256.309368)
		(mid 78.866895 -256.385296)
		(end 79.13751 -256.3241)
		(width 0.09525)
		(layer "In11.Cu")
		(net "M_F_CPU1_CLK_DN<0>")
	)
	(arc
		(start 83.862418 -256.309368)
		(mid 84.019016 -256.260079)
		(end 84.181696 -256.28219)
		(width 0.09525)
		(layer "In11.Cu")
		(net "M_F_CPU1_CLK_DN<0>")
	)
	(arc
		(start 79.171292 -256.304542)
		(mid 79.35607 -256.258749)
		(end 79.539592 -256.309368)
		(width 0.09525)
		(layer "In11.Cu")
		(net "M_F_CPU1_CLK_DN<0>")
	)
	(arc
		(start 78.145132 -256.36855)
		(mid 78.18219 -256.336416)
		(end 78.22311 -256.309368)
		(width 0.09525)
		(layer "In11.Cu")
		(net "M_F_CPU1_CLK_DN<0>")
	)
	(arc
		(start 81.982564 -256.309368)
		(mid 82.171032 -256.258691)
		(end 82.3595 -256.309368)
		(width 0.09525)
		(layer "In11.Cu")
		(net "M_F_CPU1_CLK_DN<0>")
	)
	(arc
		(start 78.239874 -256.299716)
		(mid 78.421185 -256.258618)
		(end 78.600046 -256.309368)
		(width 0.09525)
		(layer "In11.Cu")
		(net "M_F_CPU1_CLK_DN<0>")
	)
	(arc
		(start 81.050892 -256.304542)
		(mid 81.235924 -256.258628)
		(end 81.4197 -256.309368)
		(width 0.09525)
		(layer "In11.Cu")
		(net "M_F_CPU1_CLK_DN<0>")
	)
	(arc
		(start 81.4197 -256.309368)
		(mid 81.701132 -256.385123)
		(end 81.982564 -256.309368)
		(width 0.09525)
		(layer "In11.Cu")
		(net "M_F_CPU1_CLK_DN<0>")
	)
	(arc
		(start 80.479646 -256.309368)
		(mid 80.761078 -256.385123)
		(end 81.04251 -256.309368)
		(width 0.09525)
		(layer "In11.Cu")
		(net "M_F_CPU1_CLK_DN<0>")
	)
	(arc
		(start 80.102456 -256.309368)
		(mid 80.286231 -256.258596)
		(end 80.471264 -256.304542)
		(width 0.09525)
		(layer "In11.Cu")
		(net "M_F_CPU1_CLK_DN<0>")
	)
	(arc
		(start 82.3595 -256.309368)
		(mid 82.640932 -256.385123)
		(end 82.922364 -256.309368)
		(width 0.09525)
		(layer "In11.Cu")
		(net "M_F_CPU1_CLK_DN<0>")
	)
	(arc
		(start 79.539592 -256.309368)
		(mid 79.821024 -256.385123)
		(end 80.102456 -256.309368)
		(width 0.09525)
		(layer "In11.Cu")
		(net "M_F_CPU1_CLK_DN<0>")
	)
	(arc
		(start 82.922364 -256.309368)
		(mid 83.106139 -256.258596)
		(end 83.291172 -256.304542)
		(width 0.09525)
		(layer "In11.Cu")
		(net "M_F_CPU1_CLK_DN<0>")
	)
	(arc
		(start 83.299554 -256.309368)
		(mid 83.580986 -256.385123)
		(end 83.862418 -256.309368)
		(width 0.09525)
		(layer "In11.Cu")
		(net "M_F_CPU1_CLK_DN<0>")
	)
	(segment
		(start 86.397846 -250.420378)
		(end 85.930994 -250.15444)
		(width 0.10668)
		(layer "F.Cu")
		(net "M_F_CPU1_ALERT_R_N")
	)
	(segment
		(start 78.58633 -250.483878)
		(end 78.598014 -250.47702)
		(width 0.0889)
		(layer "In11.Cu")
		(net "M_F_CPU1_ALERT_R_N")
	)
	(segment
		(start 23.10511 -244.085364)
		(end 23.10511 -244.821202)
		(width 0.11684)
		(layer "In11.Cu")
		(net "M_F_CPU1_ALERT_R_N")
	)
	(segment
		(start 60.12053 -246.210328)
		(end 63.800736 -249.890534)
		(width 0.11684)
		(layer "In11.Cu")
		(net "M_F_CPU1_ALERT_R_N")
	)
	(segment
		(start 81.044034 -250.47702)
		(end 81.052416 -250.481846)
		(width 0.0889)
		(layer "In11.Cu")
		(net "M_F_CPU1_ALERT_R_N")
	)
	(segment
		(start 83.289648 -250.481846)
		(end 83.29803 -250.47702)
		(width 0.0889)
		(layer "In11.Cu")
		(net "M_F_CPU1_ALERT_R_N")
	)
	(segment
		(start 78.024228 -250.525788)
		(end 78.375764 -250.525788)
		(width 0.0889)
		(layer "In11.Cu")
		(net "M_F_CPU1_ALERT_R_N")
	)
	(segment
		(start 74.708258 -250.882404)
		(end 76.517246 -250.882404)
		(width 0.11684)
		(layer "In11.Cu")
		(net "M_F_CPU1_ALERT_R_N")
	)
	(segment
		(start 84.229702 -250.481846)
		(end 84.238084 -250.47702)
		(width 0.0889)
		(layer "In11.Cu")
		(net "M_F_CPU1_ALERT_R_N")
	)
	(segment
		(start 80.46974 -250.481846)
		(end 80.478122 -250.47702)
		(width 0.0889)
		(layer "In11.Cu")
		(net "M_F_CPU1_ALERT_R_N")
	)
	(segment
		(start 23.10511 -244.821202)
		(end 24.494236 -246.210328)
		(width 0.11684)
		(layer "In11.Cu")
		(net "M_F_CPU1_ALERT_R_N")
	)
	(segment
		(start 85.681058 -250.44527)
		(end 85.77707 -250.41987)
		(width 0.0889)
		(layer "In11.Cu")
		(net "M_F_CPU1_ALERT_R_N")
	)
	(segment
		(start 63.800736 -249.890534)
		(end 73.716388 -249.890534)
		(width 0.11684)
		(layer "In11.Cu")
		(net "M_F_CPU1_ALERT_R_N")
	)
	(segment
		(start 73.716388 -249.890534)
		(end 74.708258 -250.882404)
		(width 0.11684)
		(layer "In11.Cu")
		(net "M_F_CPU1_ALERT_R_N")
	)
	(segment
		(start 76.687426 -250.712224)
		(end 76.689204 -250.710446)
		(width 0.0889)
		(layer "In11.Cu")
		(net "M_F_CPU1_ALERT_R_N")
	)
	(segment
		(start 76.517246 -250.882404)
		(end 76.687426 -250.712224)
		(width 0.11684)
		(layer "In11.Cu")
		(net "M_F_CPU1_ALERT_R_N")
	)
	(segment
		(start 84.803996 -250.47702)
		(end 84.812378 -250.481846)
		(width 0.0889)
		(layer "In11.Cu")
		(net "M_F_CPU1_ALERT_R_N")
	)
	(segment
		(start 77.83957 -250.710446)
		(end 78.024228 -250.525788)
		(width 0.0889)
		(layer "In11.Cu")
		(net "M_F_CPU1_ALERT_R_N")
	)
	(segment
		(start 24.494236 -246.210328)
		(end 60.12053 -246.210328)
		(width 0.11684)
		(layer "In11.Cu")
		(net "M_F_CPU1_ALERT_R_N")
	)
	(segment
		(start 76.689204 -250.710446)
		(end 77.83957 -250.710446)
		(width 0.0889)
		(layer "In11.Cu")
		(net "M_F_CPU1_ALERT_R_N")
	)
	(segment
		(start 85.77707 -250.41987)
		(end 85.930994 -250.15444)
		(width 0.0889)
		(layer "In11.Cu")
		(net "M_F_CPU1_ALERT_R_N")
	)
	(segment
		(start 79.529686 -250.481846)
		(end 79.538068 -250.47702)
		(width 0.0889)
		(layer "In11.Cu")
		(net "M_F_CPU1_ALERT_R_N")
	)
	(arc
		(start 83.29803 -250.47702)
		(mid 83.580986 -250.400843)
		(end 83.863942 -250.47702)
		(width 0.0889)
		(layer "In11.Cu")
		(net "M_F_CPU1_ALERT_R_N")
	)
	(arc
		(start 82.923888 -250.47702)
		(mid 83.106139 -250.52737)
		(end 83.289648 -250.481846)
		(width 0.0889)
		(layer "In11.Cu")
		(net "M_F_CPU1_ALERT_R_N")
	)
	(arc
		(start 78.375764 -250.525788)
		(mid 78.484129 -250.520313)
		(end 78.58633 -250.483878)
		(width 0.0889)
		(layer "In11.Cu")
		(net "M_F_CPU1_ALERT_R_N")
	)
	(arc
		(start 78.598014 -250.47702)
		(mid 78.88097 -250.400843)
		(end 79.163926 -250.47702)
		(width 0.0889)
		(layer "In11.Cu")
		(net "M_F_CPU1_ALERT_R_N")
	)
	(arc
		(start 81.052416 -250.481846)
		(mid 81.235924 -250.52734)
		(end 81.418176 -250.47702)
		(width 0.0889)
		(layer "In11.Cu")
		(net "M_F_CPU1_ALERT_R_N")
	)
	(arc
		(start 84.238084 -250.47702)
		(mid 84.52104 -250.400843)
		(end 84.803996 -250.47702)
		(width 0.0889)
		(layer "In11.Cu")
		(net "M_F_CPU1_ALERT_R_N")
	)
	(arc
		(start 82.357976 -250.47702)
		(mid 82.640932 -250.400843)
		(end 82.923888 -250.47702)
		(width 0.0889)
		(layer "In11.Cu")
		(net "M_F_CPU1_ALERT_R_N")
	)
	(arc
		(start 81.984088 -250.47702)
		(mid 82.171032 -250.527275)
		(end 82.357976 -250.47702)
		(width 0.0889)
		(layer "In11.Cu")
		(net "M_F_CPU1_ALERT_R_N")
	)
	(arc
		(start 81.418176 -250.47702)
		(mid 81.701132 -250.400843)
		(end 81.984088 -250.47702)
		(width 0.0889)
		(layer "In11.Cu")
		(net "M_F_CPU1_ALERT_R_N")
	)
	(arc
		(start 79.538068 -250.47702)
		(mid 79.821024 -250.400843)
		(end 80.10398 -250.47702)
		(width 0.0889)
		(layer "In11.Cu")
		(net "M_F_CPU1_ALERT_R_N")
	)
	(arc
		(start 80.10398 -250.47702)
		(mid 80.286231 -250.52737)
		(end 80.46974 -250.481846)
		(width 0.0889)
		(layer "In11.Cu")
		(net "M_F_CPU1_ALERT_R_N")
	)
	(arc
		(start 85.178138 -250.47702)
		(mid 85.425851 -250.4018)
		(end 85.681058 -250.44527)
		(width 0.0889)
		(layer "In11.Cu")
		(net "M_F_CPU1_ALERT_R_N")
	)
	(arc
		(start 84.812378 -250.481846)
		(mid 84.995886 -250.52734)
		(end 85.178138 -250.47702)
		(width 0.0889)
		(layer "In11.Cu")
		(net "M_F_CPU1_ALERT_R_N")
	)
	(arc
		(start 80.478122 -250.47702)
		(mid 80.761078 -250.400843)
		(end 81.044034 -250.47702)
		(width 0.0889)
		(layer "In11.Cu")
		(net "M_F_CPU1_ALERT_R_N")
	)
	(arc
		(start 79.163926 -250.47702)
		(mid 79.346177 -250.52737)
		(end 79.529686 -250.481846)
		(width 0.0889)
		(layer "In11.Cu")
		(net "M_F_CPU1_ALERT_R_N")
	)
	(arc
		(start 83.863942 -250.47702)
		(mid 84.046193 -250.52737)
		(end 84.229702 -250.481846)
		(width 0.0889)
		(layer "In11.Cu")
		(net "M_F_CPU1_ALERT_R_N")
	)
	(via
		(at 21.70811 -244.085364)
		(size 0.4826)
		(drill 0.254)
		(layers "F.Cu" "B.Cu")
		(net "M_F_CPU1_ALERT_N")
	)
	(segment
		(start 22.30501 -244.085364)
		(end 21.70811 -244.085364)
		(width 0.10668)
		(layer "B.Cu")
		(net "M_F_CPU1_ALERT_N")
	)
	(segment
		(start 332.758034 -267.34008)
		(end 332.291182 -267.606018)
		(width 0.10668)
		(layer "F.Cu")
		(net "M_F_CPU0_SB_RSP<0>")
	)
	(segment
		(start 270.631412 -270.164814)
		(end 270.631412 -270.399764)
		(width 0.11684)
		(layer "In11.Cu")
		(net "M_F_CPU0_SB_RSP<0>")
	)
	(segment
		(start 271.005046 -270.55445)
		(end 271.159732 -270.399764)
		(width 0.11684)
		(layer "In11.Cu")
		(net "M_F_CPU0_SB_RSP<0>")
	)
	(segment
		(start 272.061686 -270.55445)
		(end 272.216372 -270.399764)
		(width 0.11684)
		(layer "In11.Cu")
		(net "M_F_CPU0_SB_RSP<0>")
	)
	(segment
		(start 324.371716 -266.85113)
		(end 324.88505 -267.364464)
		(width 0.0889)
		(layer "In11.Cu")
		(net "M_F_CPU0_SB_RSP<0>")
	)
	(segment
		(start 274.212812 -270.164814)
		(end 274.367498 -270.010128)
		(width 0.11684)
		(layer "In11.Cu")
		(net "M_F_CPU0_SB_RSP<0>")
	)
	(segment
		(start 275.698966 -270.010128)
		(end 275.935948 -270.010128)
		(width 0.11684)
		(layer "In11.Cu")
		(net "M_F_CPU0_SB_RSP<0>")
	)
	(segment
		(start 271.688052 -270.164814)
		(end 271.688052 -270.399764)
		(width 0.11684)
		(layer "In11.Cu")
		(net "M_F_CPU0_SB_RSP<0>")
	)
	(segment
		(start 275.935948 -270.010128)
		(end 276.227286 -269.71879)
		(width 0.11684)
		(layer "In11.Cu")
		(net "M_F_CPU0_SB_RSP<0>")
	)
	(segment
		(start 328.709782 -267.933424)
		(end 328.718164 -267.928598)
		(width 0.0889)
		(layer "In11.Cu")
		(net "M_F_CPU0_SB_RSP<0>")
	)
	(segment
		(start 275.170646 -269.71879)
		(end 275.407628 -269.71879)
		(width 0.11684)
		(layer "In11.Cu")
		(net "M_F_CPU0_SB_RSP<0>")
	)
	(segment
		(start 273.839178 -270.47317)
		(end 274.058126 -270.47317)
		(width 0.11684)
		(layer "In11.Cu")
		(net "M_F_CPU0_SB_RSP<0>")
	)
	(segment
		(start 273.684492 -270.318484)
		(end 273.839178 -270.47317)
		(width 0.11684)
		(layer "In11.Cu")
		(net "M_F_CPU0_SB_RSP<0>")
	)
	(segment
		(start 324.88505 -267.364464)
		(end 325.364602 -267.364464)
		(width 0.0889)
		(layer "In11.Cu")
		(net "M_F_CPU0_SB_RSP<0>")
	)
	(segment
		(start 276.227286 -269.71879)
		(end 276.464268 -269.71879)
		(width 0.11684)
		(layer "In11.Cu")
		(net "M_F_CPU0_SB_RSP<0>")
	)
	(segment
		(start 270.631412 -270.399764)
		(end 270.786098 -270.55445)
		(width 0.11684)
		(layer "In11.Cu")
		(net "M_F_CPU0_SB_RSP<0>")
	)
	(segment
		(start 325.364602 -267.364464)
		(end 326.480678 -267.937742)
		(width 0.0889)
		(layer "In11.Cu")
		(net "M_F_CPU0_SB_RSP<0>")
	)
	(segment
		(start 271.159732 -270.399764)
		(end 271.159732 -270.164814)
		(width 0.11684)
		(layer "In11.Cu")
		(net "M_F_CPU0_SB_RSP<0>")
	)
	(segment
		(start 271.842738 -270.55445)
		(end 272.061686 -270.55445)
		(width 0.11684)
		(layer "In11.Cu")
		(net "M_F_CPU0_SB_RSP<0>")
	)
	(segment
		(start 332.422754 -267.95476)
		(end 332.445106 -267.871448)
		(width 0.0889)
		(layer "In11.Cu")
		(net "M_F_CPU0_SB_RSP<0>")
	)
	(segment
		(start 270.07312 -270.010128)
		(end 270.476726 -270.010128)
		(width 0.11684)
		(layer "In11.Cu")
		(net "M_F_CPU0_SB_RSP<0>")
	)
	(segment
		(start 330.22413 -267.928598)
		(end 330.232512 -267.933424)
		(width 0.0889)
		(layer "In11.Cu")
		(net "M_F_CPU0_SB_RSP<0>")
	)
	(segment
		(start 275.407628 -269.71879)
		(end 275.698966 -270.010128)
		(width 0.11684)
		(layer "In11.Cu")
		(net "M_F_CPU0_SB_RSP<0>")
	)
	(segment
		(start 271.314418 -270.010128)
		(end 271.533366 -270.010128)
		(width 0.11684)
		(layer "In11.Cu")
		(net "M_F_CPU0_SB_RSP<0>")
	)
	(segment
		(start 270.476726 -270.010128)
		(end 270.631412 -270.164814)
		(width 0.11684)
		(layer "In11.Cu")
		(net "M_F_CPU0_SB_RSP<0>")
	)
	(segment
		(start 323.908674 -266.85113)
		(end 324.371716 -266.85113)
		(width 0.0889)
		(layer "In11.Cu")
		(net "M_F_CPU0_SB_RSP<0>")
	)
	(segment
		(start 269.648178 -270.43507)
		(end 270.07312 -270.010128)
		(width 0.11684)
		(layer "In11.Cu")
		(net "M_F_CPU0_SB_RSP<0>")
	)
	(segment
		(start 272.216372 -270.164814)
		(end 272.371058 -270.010128)
		(width 0.11684)
		(layer "In11.Cu")
		(net "M_F_CPU0_SB_RSP<0>")
	)
	(segment
		(start 273.529806 -270.010128)
		(end 273.684492 -270.164814)
		(width 0.11684)
		(layer "In11.Cu")
		(net "M_F_CPU0_SB_RSP<0>")
	)
	(segment
		(start 274.212812 -270.318484)
		(end 274.212812 -270.164814)
		(width 0.11684)
		(layer "In11.Cu")
		(net "M_F_CPU0_SB_RSP<0>")
	)
	(segment
		(start 311.345834 -266.85113)
		(end 323.908674 -266.85113)
		(width 0.11684)
		(layer "In11.Cu")
		(net "M_F_CPU0_SB_RSP<0>")
	)
	(segment
		(start 332.445106 -267.871448)
		(end 332.291182 -267.606018)
		(width 0.0889)
		(layer "In11.Cu")
		(net "M_F_CPU0_SB_RSP<0>")
	)
	(segment
		(start 308.186836 -270.010128)
		(end 311.345834 -266.85113)
		(width 0.11684)
		(layer "In11.Cu")
		(net "M_F_CPU0_SB_RSP<0>")
	)
	(segment
		(start 276.755606 -270.010128)
		(end 308.186836 -270.010128)
		(width 0.11684)
		(layer "In11.Cu")
		(net "M_F_CPU0_SB_RSP<0>")
	)
	(segment
		(start 276.464268 -269.71879)
		(end 276.755606 -270.010128)
		(width 0.11684)
		(layer "In11.Cu")
		(net "M_F_CPU0_SB_RSP<0>")
	)
	(segment
		(start 272.216372 -270.399764)
		(end 272.216372 -270.164814)
		(width 0.11684)
		(layer "In11.Cu")
		(net "M_F_CPU0_SB_RSP<0>")
	)
	(segment
		(start 271.159732 -270.164814)
		(end 271.314418 -270.010128)
		(width 0.11684)
		(layer "In11.Cu")
		(net "M_F_CPU0_SB_RSP<0>")
	)
	(segment
		(start 329.284076 -267.928598)
		(end 329.292458 -267.933424)
		(width 0.0889)
		(layer "In11.Cu")
		(net "M_F_CPU0_SB_RSP<0>")
	)
	(segment
		(start 272.371058 -270.010128)
		(end 273.529806 -270.010128)
		(width 0.11684)
		(layer "In11.Cu")
		(net "M_F_CPU0_SB_RSP<0>")
	)
	(segment
		(start 274.879308 -270.010128)
		(end 275.170646 -269.71879)
		(width 0.11684)
		(layer "In11.Cu")
		(net "M_F_CPU0_SB_RSP<0>")
	)
	(segment
		(start 274.058126 -270.47317)
		(end 274.212812 -270.318484)
		(width 0.11684)
		(layer "In11.Cu")
		(net "M_F_CPU0_SB_RSP<0>")
	)
	(segment
		(start 271.533366 -270.010128)
		(end 271.688052 -270.164814)
		(width 0.11684)
		(layer "In11.Cu")
		(net "M_F_CPU0_SB_RSP<0>")
	)
	(segment
		(start 273.684492 -270.164814)
		(end 273.684492 -270.318484)
		(width 0.11684)
		(layer "In11.Cu")
		(net "M_F_CPU0_SB_RSP<0>")
	)
	(segment
		(start 271.688052 -270.399764)
		(end 271.842738 -270.55445)
		(width 0.11684)
		(layer "In11.Cu")
		(net "M_F_CPU0_SB_RSP<0>")
	)
	(segment
		(start 274.367498 -270.010128)
		(end 274.879308 -270.010128)
		(width 0.11684)
		(layer "In11.Cu")
		(net "M_F_CPU0_SB_RSP<0>")
	)
	(segment
		(start 270.786098 -270.55445)
		(end 271.005046 -270.55445)
		(width 0.11684)
		(layer "In11.Cu")
		(net "M_F_CPU0_SB_RSP<0>")
	)
	(arc
		(start 331.164184 -267.928598)
		(mid 331.351128 -267.978853)
		(end 331.538072 -267.928598)
		(width 0.0889)
		(layer "In11.Cu")
		(net "M_F_CPU0_SB_RSP<0>")
	)
	(arc
		(start 327.77811 -267.928598)
		(mid 328.061066 -267.852421)
		(end 328.344022 -267.928598)
		(width 0.0889)
		(layer "In11.Cu")
		(net "M_F_CPU0_SB_RSP<0>")
	)
	(arc
		(start 328.344022 -267.928598)
		(mid 328.526273 -267.978948)
		(end 328.709782 -267.933424)
		(width 0.0889)
		(layer "In11.Cu")
		(net "M_F_CPU0_SB_RSP<0>")
	)
	(arc
		(start 331.538072 -267.928598)
		(mid 331.821028 -267.852421)
		(end 332.103984 -267.928598)
		(width 0.0889)
		(layer "In11.Cu")
		(net "M_F_CPU0_SB_RSP<0>")
	)
	(arc
		(start 326.480678 -267.937742)
		(mid 326.66066 -267.978842)
		(end 326.83831 -267.928598)
		(width 0.0889)
		(layer "In11.Cu")
		(net "M_F_CPU0_SB_RSP<0>")
	)
	(arc
		(start 328.718164 -267.928598)
		(mid 329.00112 -267.852421)
		(end 329.284076 -267.928598)
		(width 0.0889)
		(layer "In11.Cu")
		(net "M_F_CPU0_SB_RSP<0>")
	)
	(arc
		(start 329.292458 -267.933424)
		(mid 329.475966 -267.978918)
		(end 329.658218 -267.928598)
		(width 0.0889)
		(layer "In11.Cu")
		(net "M_F_CPU0_SB_RSP<0>")
	)
	(arc
		(start 327.404222 -267.928598)
		(mid 327.591166 -267.978853)
		(end 327.77811 -267.928598)
		(width 0.0889)
		(layer "In11.Cu")
		(net "M_F_CPU0_SB_RSP<0>")
	)
	(arc
		(start 326.83831 -267.928598)
		(mid 327.121266 -267.852421)
		(end 327.404222 -267.928598)
		(width 0.0889)
		(layer "In11.Cu")
		(net "M_F_CPU0_SB_RSP<0>")
	)
	(arc
		(start 330.598272 -267.928598)
		(mid 330.881228 -267.852421)
		(end 331.164184 -267.928598)
		(width 0.0889)
		(layer "In11.Cu")
		(net "M_F_CPU0_SB_RSP<0>")
	)
	(arc
		(start 330.232512 -267.933424)
		(mid 330.41602 -267.978918)
		(end 330.598272 -267.928598)
		(width 0.0889)
		(layer "In11.Cu")
		(net "M_F_CPU0_SB_RSP<0>")
	)
	(arc
		(start 332.103984 -267.928598)
		(mid 332.260422 -267.977569)
		(end 332.422754 -267.95476)
		(width 0.0889)
		(layer "In11.Cu")
		(net "M_F_CPU0_SB_RSP<0>")
	)
	(arc
		(start 329.658218 -267.928598)
		(mid 329.941174 -267.852421)
		(end 330.22413 -267.928598)
		(width 0.0889)
		(layer "In11.Cu")
		(net "M_F_CPU0_SB_RSP<0>")
	)
	(segment
		(start 333.227934 -264.910062)
		(end 332.761082 -265.176)
		(width 0.10668)
		(layer "F.Cu")
		(net "M_F_CPU0_SB_PAR")
	)
	(segment
		(start 324.820534 -264.50671)
		(end 325.315326 -264.50671)
		(width 0.0889)
		(layer "In11.Cu")
		(net "M_F_CPU0_SB_PAR")
	)
	(segment
		(start 309.769764 -265.0744)
		(end 323.903594 -265.0744)
		(width 0.14478)
		(layer "In11.Cu")
		(net "M_F_CPU0_SB_PAR")
	)
	(segment
		(start 327.874376 -264.853674)
		(end 327.890632 -264.844276)
		(width 0.0889)
		(layer "In11.Cu")
		(net "M_F_CPU0_SB_PAR")
	)
	(segment
		(start 327.297542 -264.846562)
		(end 327.309226 -264.85342)
		(width 0.0889)
		(layer "In11.Cu")
		(net "M_F_CPU0_SB_PAR")
	)
	(segment
		(start 327.862438 -264.860532)
		(end 327.874376 -264.853674)
		(width 0.0889)
		(layer "In11.Cu")
		(net "M_F_CPU0_SB_PAR")
	)
	(segment
		(start 332.511146 -264.88517)
		(end 332.607158 -264.91057)
		(width 0.0889)
		(layer "In11.Cu")
		(net "M_F_CPU0_SB_PAR")
	)
	(segment
		(start 331.05979 -264.848594)
		(end 331.068172 -264.85342)
		(width 0.0889)
		(layer "In11.Cu")
		(net "M_F_CPU0_SB_PAR")
	)
	(segment
		(start 324.252844 -265.0744)
		(end 324.820534 -264.50671)
		(width 0.0889)
		(layer "In11.Cu")
		(net "M_F_CPU0_SB_PAR")
	)
	(segment
		(start 265.54811 -267.035026)
		(end 265.973052 -266.610084)
		(width 0.14478)
		(layer "In11.Cu")
		(net "M_F_CPU0_SB_PAR")
	)
	(segment
		(start 265.973052 -266.610084)
		(end 308.23408 -266.610084)
		(width 0.14478)
		(layer "In11.Cu")
		(net "M_F_CPU0_SB_PAR")
	)
	(segment
		(start 325.61149 -264.802874)
		(end 326.182228 -264.802874)
		(width 0.0889)
		(layer "In11.Cu")
		(net "M_F_CPU0_SB_PAR")
	)
	(segment
		(start 331.634084 -264.85342)
		(end 331.642466 -264.848594)
		(width 0.0889)
		(layer "In11.Cu")
		(net "M_F_CPU0_SB_PAR")
	)
	(segment
		(start 326.368918 -264.853674)
		(end 326.390508 -264.86612)
		(width 0.0889)
		(layer "In11.Cu")
		(net "M_F_CPU0_SB_PAR")
	)
	(segment
		(start 332.607158 -264.91057)
		(end 332.761082 -265.176)
		(width 0.0889)
		(layer "In11.Cu")
		(net "M_F_CPU0_SB_PAR")
	)
	(segment
		(start 308.23408 -266.610084)
		(end 309.769764 -265.0744)
		(width 0.14478)
		(layer "In11.Cu")
		(net "M_F_CPU0_SB_PAR")
	)
	(segment
		(start 323.903594 -265.0744)
		(end 324.252844 -265.0744)
		(width 0.0889)
		(layer "In11.Cu")
		(net "M_F_CPU0_SB_PAR")
	)
	(segment
		(start 325.315326 -264.50671)
		(end 325.61149 -264.802874)
		(width 0.0889)
		(layer "In11.Cu")
		(net "M_F_CPU0_SB_PAR")
	)
	(segment
		(start 330.119736 -264.848594)
		(end 330.128118 -264.85342)
		(width 0.0889)
		(layer "In11.Cu")
		(net "M_F_CPU0_SB_PAR")
	)
	(arc
		(start 329.188064 -264.85342)
		(mid 329.47102 -264.929597)
		(end 329.753976 -264.85342)
		(width 0.0889)
		(layer "In11.Cu")
		(net "M_F_CPU0_SB_PAR")
	)
	(arc
		(start 326.182228 -264.802874)
		(mid 326.278919 -264.81597)
		(end 326.368918 -264.853674)
		(width 0.0889)
		(layer "In11.Cu")
		(net "M_F_CPU0_SB_PAR")
	)
	(arc
		(start 327.890632 -264.844276)
		(mid 328.070614 -264.803176)
		(end 328.248264 -264.85342)
		(width 0.0889)
		(layer "In11.Cu")
		(net "M_F_CPU0_SB_PAR")
	)
	(arc
		(start 332.008226 -264.85342)
		(mid 332.255939 -264.92864)
		(end 332.511146 -264.88517)
		(width 0.0889)
		(layer "In11.Cu")
		(net "M_F_CPU0_SB_PAR")
	)
	(arc
		(start 330.128118 -264.85342)
		(mid 330.411074 -264.929597)
		(end 330.69403 -264.85342)
		(width 0.0889)
		(layer "In11.Cu")
		(net "M_F_CPU0_SB_PAR")
	)
	(arc
		(start 328.814176 -264.85342)
		(mid 329.00112 -264.803165)
		(end 329.188064 -264.85342)
		(width 0.0889)
		(layer "In11.Cu")
		(net "M_F_CPU0_SB_PAR")
	)
	(arc
		(start 330.69403 -264.85342)
		(mid 330.876281 -264.80307)
		(end 331.05979 -264.848594)
		(width 0.0889)
		(layer "In11.Cu")
		(net "M_F_CPU0_SB_PAR")
	)
	(arc
		(start 326.93483 -264.85342)
		(mid 327.115288 -264.802976)
		(end 327.297542 -264.846562)
		(width 0.0889)
		(layer "In11.Cu")
		(net "M_F_CPU0_SB_PAR")
	)
	(arc
		(start 331.642466 -264.848594)
		(mid 331.825974 -264.8031)
		(end 332.008226 -264.85342)
		(width 0.0889)
		(layer "In11.Cu")
		(net "M_F_CPU0_SB_PAR")
	)
	(arc
		(start 326.390508 -264.86612)
		(mid 326.664298 -264.929791)
		(end 326.93483 -264.85342)
		(width 0.0889)
		(layer "In11.Cu")
		(net "M_F_CPU0_SB_PAR")
	)
	(arc
		(start 328.248264 -264.85342)
		(mid 328.53122 -264.929597)
		(end 328.814176 -264.85342)
		(width 0.0889)
		(layer "In11.Cu")
		(net "M_F_CPU0_SB_PAR")
	)
	(arc
		(start 331.068172 -264.85342)
		(mid 331.351128 -264.929597)
		(end 331.634084 -264.85342)
		(width 0.0889)
		(layer "In11.Cu")
		(net "M_F_CPU0_SB_PAR")
	)
	(arc
		(start 327.309226 -264.85342)
		(mid 327.584904 -264.92955)
		(end 327.862438 -264.860532)
		(width 0.0889)
		(layer "In11.Cu")
		(net "M_F_CPU0_SB_PAR")
	)
	(arc
		(start 329.753976 -264.85342)
		(mid 329.936227 -264.80307)
		(end 330.119736 -264.848594)
		(width 0.0889)
		(layer "In11.Cu")
		(net "M_F_CPU0_SB_PAR")
	)
	(segment
		(start 332.758034 -270.580104)
		(end 332.291182 -270.846042)
		(width 0.12954)
		(layer "F.Cu")
		(net "M_F_CPU0_SB_DQS_DP<9>")
	)
	(segment
		(start 286.309308 -275.49983)
		(end 286.309308 -274.64385)
		(width 0.16002)
		(layer "In11.Cu")
		(net "M_F_CPU0_SB_DQS_DP<9>")
	)
	(segment
		(start 275.514816 -275.179028)
		(end 275.95957 -275.179028)
		(width 0.16002)
		(layer "In11.Cu")
		(net "M_F_CPU0_SB_DQS_DP<9>")
	)
	(segment
		(start 276.328632 -274.809966)
		(end 277.492968 -274.809966)
		(width 0.16002)
		(layer "In11.Cu")
		(net "M_F_CPU0_SB_DQS_DP<9>")
	)
	(segment
		(start 281.489404 -275.65985)
		(end 281.834082 -276.004528)
		(width 0.16002)
		(layer "In11.Cu")
		(net "M_F_CPU0_SB_DQS_DP<9>")
	)
	(segment
		(start 331.531214 -271.175988)
		(end 331.539596 -271.171162)
		(width 0.09525)
		(layer "In11.Cu")
		(net "M_F_CPU0_SB_DQS_DP<9>")
	)
	(segment
		(start 280.113486 -275.65985)
		(end 281.489404 -275.65985)
		(width 0.16002)
		(layer "In11.Cu")
		(net "M_F_CPU0_SB_DQS_DP<9>")
	)
	(segment
		(start 304.865278 -276.004528)
		(end 305.690778 -275.179028)
		(width 0.16002)
		(layer "In11.Cu")
		(net "M_F_CPU0_SB_DQS_DP<9>")
	)
	(segment
		(start 279.953466 -274.33143)
		(end 279.953466 -275.49983)
		(width 0.16002)
		(layer "In11.Cu")
		(net "M_F_CPU0_SB_DQS_DP<9>")
	)
	(segment
		(start 300.817534 -274.809966)
		(end 301.460154 -275.452586)
		(width 0.16002)
		(layer "In11.Cu")
		(net "M_F_CPU0_SB_DQS_DP<9>")
	)
	(segment
		(start 289.378136 -276.004528)
		(end 289.777424 -276.004528)
		(width 0.16002)
		(layer "In11.Cu")
		(net "M_F_CPU0_SB_DQS_DP<9>")
	)
	(segment
		(start 286.646366 -274.306792)
		(end 287.245044 -274.306792)
		(width 0.16002)
		(layer "In11.Cu")
		(net "M_F_CPU0_SB_DQS_DP<9>")
	)
	(segment
		(start 279.616408 -273.994372)
		(end 279.953466 -274.33143)
		(width 0.16002)
		(layer "In11.Cu")
		(net "M_F_CPU0_SB_DQS_DP<9>")
	)
	(segment
		(start 285.904178 -275.65985)
		(end 286.149288 -275.65985)
		(width 0.16002)
		(layer "In11.Cu")
		(net "M_F_CPU0_SB_DQS_DP<9>")
	)
	(segment
		(start 294.123364 -275.65985)
		(end 296.577512 -275.65985)
		(width 0.16002)
		(layer "In11.Cu")
		(net "M_F_CPU0_SB_DQS_DP<9>")
	)
	(segment
		(start 305.690778 -275.179028)
		(end 307.301646 -275.179028)
		(width 0.16002)
		(layer "In11.Cu")
		(net "M_F_CPU0_SB_DQS_DP<9>")
	)
	(segment
		(start 273.94535 -275.65985)
		(end 274.290028 -276.004528)
		(width 0.16002)
		(layer "In11.Cu")
		(net "M_F_CPU0_SB_DQS_DP<9>")
	)
	(segment
		(start 287.582102 -275.49983)
		(end 287.742122 -275.65985)
		(width 0.16002)
		(layer "In11.Cu")
		(net "M_F_CPU0_SB_DQS_DP<9>")
	)
	(segment
		(start 312.947304 -269.53337)
		(end 323.895974 -269.53337)
		(width 0.16002)
		(layer "In11.Cu")
		(net "M_F_CPU0_SB_DQS_DP<9>")
	)
	(segment
		(start 270.670528 -275.692108)
		(end 271.150588 -275.692108)
		(width 0.16002)
		(layer "In11.Cu")
		(net "M_F_CPU0_SB_DQS_DP<9>")
	)
	(segment
		(start 290.602924 -275.179028)
		(end 291.047678 -275.179028)
		(width 0.16002)
		(layer "In11.Cu")
		(net "M_F_CPU0_SB_DQS_DP<9>")
	)
	(segment
		(start 289.777424 -276.004528)
		(end 290.602924 -275.179028)
		(width 0.16002)
		(layer "In11.Cu")
		(net "M_F_CPU0_SB_DQS_DP<9>")
	)
	(segment
		(start 270.553688 -275.808948)
		(end 270.670528 -275.692108)
		(width 0.16002)
		(layer "In11.Cu")
		(net "M_F_CPU0_SB_DQS_DP<9>")
	)
	(segment
		(start 278.680672 -274.33143)
		(end 279.01773 -273.994372)
		(width 0.16002)
		(layer "In11.Cu")
		(net "M_F_CPU0_SB_DQS_DP<9>")
	)
	(segment
		(start 289.033458 -275.65985)
		(end 289.378136 -276.004528)
		(width 0.16002)
		(layer "In11.Cu")
		(net "M_F_CPU0_SB_DQS_DP<9>")
	)
	(segment
		(start 274.689316 -276.004528)
		(end 275.514816 -275.179028)
		(width 0.16002)
		(layer "In11.Cu")
		(net "M_F_CPU0_SB_DQS_DP<9>")
	)
	(segment
		(start 269.648178 -275.535136)
		(end 269.92199 -275.808948)
		(width 0.16002)
		(layer "In11.Cu")
		(net "M_F_CPU0_SB_DQS_DP<9>")
	)
	(segment
		(start 307.301646 -275.179028)
		(end 312.947304 -269.53337)
		(width 0.16002)
		(layer "In11.Cu")
		(net "M_F_CPU0_SB_DQS_DP<9>")
	)
	(segment
		(start 283.05887 -275.179028)
		(end 283.503624 -275.179028)
		(width 0.16002)
		(layer "In11.Cu")
		(net "M_F_CPU0_SB_DQS_DP<9>")
	)
	(segment
		(start 269.92199 -275.808948)
		(end 270.553688 -275.808948)
		(width 0.16002)
		(layer "In11.Cu")
		(net "M_F_CPU0_SB_DQS_DP<9>")
	)
	(segment
		(start 271.94637 -275.808948)
		(end 272.095468 -275.65985)
		(width 0.16002)
		(layer "In11.Cu")
		(net "M_F_CPU0_SB_DQS_DP<9>")
	)
	(segment
		(start 287.742122 -275.65985)
		(end 289.033458 -275.65985)
		(width 0.16002)
		(layer "In11.Cu")
		(net "M_F_CPU0_SB_DQS_DP<9>")
	)
	(segment
		(start 296.577512 -275.65985)
		(end 296.92219 -276.004528)
		(width 0.16002)
		(layer "In11.Cu")
		(net "M_F_CPU0_SB_DQS_DP<9>")
	)
	(segment
		(start 291.41674 -274.809966)
		(end 293.27348 -274.809966)
		(width 0.16002)
		(layer "In11.Cu")
		(net "M_F_CPU0_SB_DQS_DP<9>")
	)
	(segment
		(start 274.290028 -276.004528)
		(end 274.689316 -276.004528)
		(width 0.16002)
		(layer "In11.Cu")
		(net "M_F_CPU0_SB_DQS_DP<9>")
	)
	(segment
		(start 298.146978 -275.179028)
		(end 298.591732 -275.179028)
		(width 0.16002)
		(layer "In11.Cu")
		(net "M_F_CPU0_SB_DQS_DP<9>")
	)
	(segment
		(start 325.406004 -270.14551)
		(end 326.48271 -271.222216)
		(width 0.09525)
		(layer "In11.Cu")
		(net "M_F_CPU0_SB_DQS_DP<9>")
	)
	(segment
		(start 278.342852 -275.65985)
		(end 278.520652 -275.65985)
		(width 0.16002)
		(layer "In11.Cu")
		(net "M_F_CPU0_SB_DQS_DP<9>")
	)
	(segment
		(start 282.23337 -276.004528)
		(end 283.05887 -275.179028)
		(width 0.16002)
		(layer "In11.Cu")
		(net "M_F_CPU0_SB_DQS_DP<9>")
	)
	(segment
		(start 291.047678 -275.179028)
		(end 291.41674 -274.809966)
		(width 0.16002)
		(layer "In11.Cu")
		(net "M_F_CPU0_SB_DQS_DP<9>")
	)
	(segment
		(start 293.27348 -274.809966)
		(end 294.123364 -275.65985)
		(width 0.16002)
		(layer "In11.Cu")
		(net "M_F_CPU0_SB_DQS_DP<9>")
	)
	(segment
		(start 296.92219 -276.004528)
		(end 297.321478 -276.004528)
		(width 0.16002)
		(layer "In11.Cu")
		(net "M_F_CPU0_SB_DQS_DP<9>")
	)
	(segment
		(start 327.78065 -271.171162)
		(end 327.780396 -271.171162)
		(width 0.09525)
		(layer "In11.Cu")
		(net "M_F_CPU0_SB_DQS_DP<9>")
	)
	(segment
		(start 324.34657 -269.592298)
		(end 324.899782 -270.14551)
		(width 0.09525)
		(layer "In11.Cu")
		(net "M_F_CPU0_SB_DQS_DP<9>")
	)
	(segment
		(start 326.48271 -271.222216)
		(end 327.592182 -271.222216)
		(width 0.09525)
		(layer "In11.Cu")
		(net "M_F_CPU0_SB_DQS_DP<9>")
	)
	(segment
		(start 279.953466 -275.49983)
		(end 280.113486 -275.65985)
		(width 0.16002)
		(layer "In11.Cu")
		(net "M_F_CPU0_SB_DQS_DP<9>")
	)
	(segment
		(start 298.591732 -275.179028)
		(end 298.960794 -274.809966)
		(width 0.16002)
		(layer "In11.Cu")
		(net "M_F_CPU0_SB_DQS_DP<9>")
	)
	(segment
		(start 285.054294 -274.809966)
		(end 285.904178 -275.65985)
		(width 0.16002)
		(layer "In11.Cu")
		(net "M_F_CPU0_SB_DQS_DP<9>")
	)
	(segment
		(start 287.582102 -274.64385)
		(end 287.582102 -275.49983)
		(width 0.16002)
		(layer "In11.Cu")
		(net "M_F_CPU0_SB_DQS_DP<9>")
	)
	(segment
		(start 272.095468 -275.65985)
		(end 273.94535 -275.65985)
		(width 0.16002)
		(layer "In11.Cu")
		(net "M_F_CPU0_SB_DQS_DP<9>")
	)
	(segment
		(start 298.960794 -274.809966)
		(end 300.817534 -274.809966)
		(width 0.16002)
		(layer "In11.Cu")
		(net "M_F_CPU0_SB_DQS_DP<9>")
	)
	(segment
		(start 301.460154 -275.452586)
		(end 301.817024 -275.452586)
		(width 0.16002)
		(layer "In11.Cu")
		(net "M_F_CPU0_SB_DQS_DP<9>")
	)
	(segment
		(start 301.817024 -275.452586)
		(end 302.368966 -276.004528)
		(width 0.16002)
		(layer "In11.Cu")
		(net "M_F_CPU0_SB_DQS_DP<9>")
	)
	(segment
		(start 271.267428 -275.808948)
		(end 271.94637 -275.808948)
		(width 0.16002)
		(layer "In11.Cu")
		(net "M_F_CPU0_SB_DQS_DP<9>")
	)
	(segment
		(start 286.149288 -275.65985)
		(end 286.309308 -275.49983)
		(width 0.16002)
		(layer "In11.Cu")
		(net "M_F_CPU0_SB_DQS_DP<9>")
	)
	(segment
		(start 287.245044 -274.306792)
		(end 287.582102 -274.64385)
		(width 0.16002)
		(layer "In11.Cu")
		(net "M_F_CPU0_SB_DQS_DP<9>")
	)
	(segment
		(start 302.368966 -276.004528)
		(end 304.865278 -276.004528)
		(width 0.16002)
		(layer "In11.Cu")
		(net "M_F_CPU0_SB_DQS_DP<9>")
	)
	(segment
		(start 324.899782 -270.14551)
		(end 325.406004 -270.14551)
		(width 0.09525)
		(layer "In11.Cu")
		(net "M_F_CPU0_SB_DQS_DP<9>")
	)
	(segment
		(start 332.421738 -271.19834)
		(end 332.445106 -271.111472)
		(width 0.09525)
		(layer "In11.Cu")
		(net "M_F_CPU0_SB_DQS_DP<9>")
	)
	(segment
		(start 278.680672 -275.49983)
		(end 278.680672 -274.33143)
		(width 0.16002)
		(layer "In11.Cu")
		(net "M_F_CPU0_SB_DQS_DP<9>")
	)
	(segment
		(start 323.895974 -269.53337)
		(end 323.919596 -269.53337)
		(width 0.09525)
		(layer "In11.Cu")
		(net "M_F_CPU0_SB_DQS_DP<9>")
	)
	(segment
		(start 275.95957 -275.179028)
		(end 276.328632 -274.809966)
		(width 0.16002)
		(layer "In11.Cu")
		(net "M_F_CPU0_SB_DQS_DP<9>")
	)
	(segment
		(start 297.321478 -276.004528)
		(end 298.146978 -275.179028)
		(width 0.16002)
		(layer "In11.Cu")
		(net "M_F_CPU0_SB_DQS_DP<9>")
	)
	(segment
		(start 277.492968 -274.809966)
		(end 278.342852 -275.65985)
		(width 0.16002)
		(layer "In11.Cu")
		(net "M_F_CPU0_SB_DQS_DP<9>")
	)
	(segment
		(start 332.445106 -271.111472)
		(end 332.291182 -270.846042)
		(width 0.09525)
		(layer "In11.Cu")
		(net "M_F_CPU0_SB_DQS_DP<9>")
	)
	(segment
		(start 281.834082 -276.004528)
		(end 282.23337 -276.004528)
		(width 0.16002)
		(layer "In11.Cu")
		(net "M_F_CPU0_SB_DQS_DP<9>")
	)
	(segment
		(start 327.780396 -271.171416)
		(end 327.78065 -271.171162)
		(width 0.09525)
		(layer "In11.Cu")
		(net "M_F_CPU0_SB_DQS_DP<9>")
	)
	(segment
		(start 323.978524 -269.592298)
		(end 324.34657 -269.592298)
		(width 0.09525)
		(layer "In11.Cu")
		(net "M_F_CPU0_SB_DQS_DP<9>")
	)
	(segment
		(start 327.780396 -271.171162)
		(end 327.79843 -271.160748)
		(width 0.09525)
		(layer "In11.Cu")
		(net "M_F_CPU0_SB_DQS_DP<9>")
	)
	(segment
		(start 283.503624 -275.179028)
		(end 283.872686 -274.809966)
		(width 0.16002)
		(layer "In11.Cu")
		(net "M_F_CPU0_SB_DQS_DP<9>")
	)
	(segment
		(start 283.872686 -274.809966)
		(end 285.054294 -274.809966)
		(width 0.16002)
		(layer "In11.Cu")
		(net "M_F_CPU0_SB_DQS_DP<9>")
	)
	(segment
		(start 323.919596 -269.53337)
		(end 323.978524 -269.592298)
		(width 0.09525)
		(layer "In11.Cu")
		(net "M_F_CPU0_SB_DQS_DP<9>")
	)
	(segment
		(start 279.01773 -273.994372)
		(end 279.616408 -273.994372)
		(width 0.16002)
		(layer "In11.Cu")
		(net "M_F_CPU0_SB_DQS_DP<9>")
	)
	(segment
		(start 286.309308 -274.64385)
		(end 286.646366 -274.306792)
		(width 0.16002)
		(layer "In11.Cu")
		(net "M_F_CPU0_SB_DQS_DP<9>")
	)
	(segment
		(start 328.711306 -271.175988)
		(end 328.719688 -271.171162)
		(width 0.09525)
		(layer "In11.Cu")
		(net "M_F_CPU0_SB_DQS_DP<9>")
	)
	(segment
		(start 329.282552 -271.171162)
		(end 329.290934 -271.175988)
		(width 0.09525)
		(layer "In11.Cu")
		(net "M_F_CPU0_SB_DQS_DP<9>")
	)
	(segment
		(start 271.150588 -275.692108)
		(end 271.267428 -275.808948)
		(width 0.16002)
		(layer "In11.Cu")
		(net "M_F_CPU0_SB_DQS_DP<9>")
	)
	(segment
		(start 278.520652 -275.65985)
		(end 278.680672 -275.49983)
		(width 0.16002)
		(layer "In11.Cu")
		(net "M_F_CPU0_SB_DQS_DP<9>")
	)
	(arc
		(start 330.599542 -271.171162)
		(mid 330.880974 -271.095407)
		(end 331.162406 -271.171162)
		(width 0.09525)
		(layer "In11.Cu")
		(net "M_F_CPU0_SB_DQS_DP<9>")
	)
	(arc
		(start 331.539596 -271.171162)
		(mid 331.821028 -271.095407)
		(end 332.10246 -271.171162)
		(width 0.09525)
		(layer "In11.Cu")
		(net "M_F_CPU0_SB_DQS_DP<9>")
	)
	(arc
		(start 330.222606 -271.171162)
		(mid 330.411074 -271.221839)
		(end 330.599542 -271.171162)
		(width 0.09525)
		(layer "In11.Cu")
		(net "M_F_CPU0_SB_DQS_DP<9>")
	)
	(arc
		(start 327.592182 -271.222216)
		(mid 327.689643 -271.209235)
		(end 327.780396 -271.171416)
		(width 0.09525)
		(layer "In11.Cu")
		(net "M_F_CPU0_SB_DQS_DP<9>")
	)
	(arc
		(start 329.659742 -271.171162)
		(mid 329.941174 -271.095407)
		(end 330.222606 -271.171162)
		(width 0.09525)
		(layer "In11.Cu")
		(net "M_F_CPU0_SB_DQS_DP<9>")
	)
	(arc
		(start 329.290934 -271.175988)
		(mid 329.475966 -271.221902)
		(end 329.659742 -271.171162)
		(width 0.09525)
		(layer "In11.Cu")
		(net "M_F_CPU0_SB_DQS_DP<9>")
	)
	(arc
		(start 332.10246 -271.171162)
		(mid 332.259058 -271.220451)
		(end 332.421738 -271.19834)
		(width 0.09525)
		(layer "In11.Cu")
		(net "M_F_CPU0_SB_DQS_DP<9>")
	)
	(arc
		(start 328.342498 -271.171162)
		(mid 328.526273 -271.221934)
		(end 328.711306 -271.175988)
		(width 0.09525)
		(layer "In11.Cu")
		(net "M_F_CPU0_SB_DQS_DP<9>")
	)
	(arc
		(start 328.719688 -271.171162)
		(mid 329.00112 -271.095407)
		(end 329.282552 -271.171162)
		(width 0.09525)
		(layer "In11.Cu")
		(net "M_F_CPU0_SB_DQS_DP<9>")
	)
	(arc
		(start 331.162406 -271.171162)
		(mid 331.346181 -271.221934)
		(end 331.531214 -271.175988)
		(width 0.09525)
		(layer "In11.Cu")
		(net "M_F_CPU0_SB_DQS_DP<9>")
	)
	(arc
		(start 327.79843 -271.160748)
		(mid 328.07181 -271.095527)
		(end 328.342498 -271.171162)
		(width 0.09525)
		(layer "In11.Cu")
		(net "M_F_CPU0_SB_DQS_DP<9>")
	)
	(segment
		(start 334.637888 -291.640006)
		(end 334.171036 -291.905944)
		(width 0.12954)
		(layer "F.Cu")
		(net "M_F_CPU0_SB_DQS_DP<8>")
	)
	(segment
		(start 325.457312 -296.369232)
		(end 325.457312 -296.286174)
		(width 0.09525)
		(layer "In11.Cu")
		(net "M_F_CPU0_SB_DQS_DP<8>")
	)
	(segment
		(start 307.670454 -314.15609)
		(end 325.440548 -296.385996)
		(width 0.16002)
		(layer "In11.Cu")
		(net "M_F_CPU0_SB_DQS_DP<8>")
	)
	(segment
		(start 334.017112 -291.640514)
		(end 334.171036 -291.905944)
		(width 0.09525)
		(layer "In11.Cu")
		(net "M_F_CPU0_SB_DQS_DP<8>")
	)
	(segment
		(start 328.711306 -291.575998)
		(end 328.719688 -291.580824)
		(width 0.09525)
		(layer "In11.Cu")
		(net "M_F_CPU0_SB_DQS_DP<8>")
	)
	(segment
		(start 298.943776 -314.510166)
		(end 301.303944 -314.510166)
		(width 0.16002)
		(layer "In11.Cu")
		(net "M_F_CPU0_SB_DQS_DP<8>")
	)
	(segment
		(start 282.315412 -315.040264)
		(end 283.199586 -314.15609)
		(width 0.16002)
		(layer "In11.Cu")
		(net "M_F_CPU0_SB_DQS_DP<8>")
	)
	(segment
		(start 268.802612 -314.541916)
		(end 271.192752 -314.541916)
		(width 0.16002)
		(layer "In11.Cu")
		(net "M_F_CPU0_SB_DQS_DP<8>")
	)
	(segment
		(start 275.655532 -314.15609)
		(end 275.957538 -314.15609)
		(width 0.16002)
		(layer "In11.Cu")
		(net "M_F_CPU0_SB_DQS_DP<8>")
	)
	(segment
		(start 267.866876 -314.19546)
		(end 268.456156 -314.19546)
		(width 0.16002)
		(layer "In11.Cu")
		(net "M_F_CPU0_SB_DQS_DP<8>")
	)
	(segment
		(start 274.771358 -315.040264)
		(end 275.655532 -314.15609)
		(width 0.16002)
		(layer "In11.Cu")
		(net "M_F_CPU0_SB_DQS_DP<8>")
	)
	(segment
		(start 271.192752 -314.541916)
		(end 272.01114 -315.360304)
		(width 0.16002)
		(layer "In11.Cu")
		(net "M_F_CPU0_SB_DQS_DP<8>")
	)
	(segment
		(start 281.837892 -315.040264)
		(end 282.315412 -315.040264)
		(width 0.16002)
		(layer "In11.Cu")
		(net "M_F_CPU0_SB_DQS_DP<8>")
	)
	(segment
		(start 275.957538 -314.15609)
		(end 276.311614 -314.510166)
		(width 0.16002)
		(layer "In11.Cu")
		(net "M_F_CPU0_SB_DQS_DP<8>")
	)
	(segment
		(start 290.74364 -314.15609)
		(end 291.045646 -314.15609)
		(width 0.16002)
		(layer "In11.Cu")
		(net "M_F_CPU0_SB_DQS_DP<8>")
	)
	(segment
		(start 267.701268 -314.361068)
		(end 267.866876 -314.19546)
		(width 0.16002)
		(layer "In11.Cu")
		(net "M_F_CPU0_SB_DQS_DP<8>")
	)
	(segment
		(start 305.831494 -314.15609)
		(end 307.670454 -314.15609)
		(width 0.16002)
		(layer "In11.Cu")
		(net "M_F_CPU0_SB_DQS_DP<8>")
	)
	(segment
		(start 281.517852 -315.360304)
		(end 281.837892 -315.040264)
		(width 0.16002)
		(layer "In11.Cu")
		(net "M_F_CPU0_SB_DQS_DP<8>")
	)
	(segment
		(start 272.01114 -315.360304)
		(end 273.973798 -315.360304)
		(width 0.16002)
		(layer "In11.Cu")
		(net "M_F_CPU0_SB_DQS_DP<8>")
	)
	(segment
		(start 297.40352 -315.040264)
		(end 298.287694 -314.15609)
		(width 0.16002)
		(layer "In11.Cu")
		(net "M_F_CPU0_SB_DQS_DP<8>")
	)
	(segment
		(start 291.399722 -314.510166)
		(end 293.75989 -314.510166)
		(width 0.16002)
		(layer "In11.Cu")
		(net "M_F_CPU0_SB_DQS_DP<8>")
	)
	(segment
		(start 289.381946 -315.040264)
		(end 289.859466 -315.040264)
		(width 0.16002)
		(layer "In11.Cu")
		(net "M_F_CPU0_SB_DQS_DP<8>")
	)
	(segment
		(start 325.816468 -295.927018)
		(end 325.816468 -293.71163)
		(width 0.09525)
		(layer "In11.Cu")
		(net "M_F_CPU0_SB_DQS_DP<8>")
	)
	(segment
		(start 329.282552 -291.580824)
		(end 329.290934 -291.575998)
		(width 0.09525)
		(layer "In11.Cu")
		(net "M_F_CPU0_SB_DQS_DP<8>")
	)
	(segment
		(start 278.671782 -314.510166)
		(end 279.52192 -315.360304)
		(width 0.16002)
		(layer "In11.Cu")
		(net "M_F_CPU0_SB_DQS_DP<8>")
	)
	(segment
		(start 289.061906 -315.360304)
		(end 289.381946 -315.040264)
		(width 0.16002)
		(layer "In11.Cu")
		(net "M_F_CPU0_SB_DQS_DP<8>")
	)
	(segment
		(start 287.065974 -315.360304)
		(end 289.061906 -315.360304)
		(width 0.16002)
		(layer "In11.Cu")
		(net "M_F_CPU0_SB_DQS_DP<8>")
	)
	(segment
		(start 291.045646 -314.15609)
		(end 291.399722 -314.510166)
		(width 0.16002)
		(layer "In11.Cu")
		(net "M_F_CPU0_SB_DQS_DP<8>")
	)
	(segment
		(start 286.215836 -314.510166)
		(end 287.065974 -315.360304)
		(width 0.16002)
		(layer "In11.Cu")
		(net "M_F_CPU0_SB_DQS_DP<8>")
	)
	(segment
		(start 283.199586 -314.15609)
		(end 283.501592 -314.15609)
		(width 0.16002)
		(layer "In11.Cu")
		(net "M_F_CPU0_SB_DQS_DP<8>")
	)
	(segment
		(start 333.916274 -291.613844)
		(end 334.017112 -291.640514)
		(width 0.09525)
		(layer "In11.Cu")
		(net "M_F_CPU0_SB_DQS_DP<8>")
	)
	(segment
		(start 304.94732 -315.040264)
		(end 305.831494 -314.15609)
		(width 0.16002)
		(layer "In11.Cu")
		(net "M_F_CPU0_SB_DQS_DP<8>")
	)
	(segment
		(start 268.456156 -314.19546)
		(end 268.802612 -314.541916)
		(width 0.16002)
		(layer "In11.Cu")
		(net "M_F_CPU0_SB_DQS_DP<8>")
	)
	(segment
		(start 301.303944 -314.510166)
		(end 301.834042 -315.040264)
		(width 0.16002)
		(layer "In11.Cu")
		(net "M_F_CPU0_SB_DQS_DP<8>")
	)
	(segment
		(start 279.52192 -315.360304)
		(end 281.517852 -315.360304)
		(width 0.16002)
		(layer "In11.Cu")
		(net "M_F_CPU0_SB_DQS_DP<8>")
	)
	(segment
		(start 296.60596 -315.360304)
		(end 296.926 -315.040264)
		(width 0.16002)
		(layer "In11.Cu")
		(net "M_F_CPU0_SB_DQS_DP<8>")
	)
	(segment
		(start 325.440548 -296.385996)
		(end 325.457312 -296.369232)
		(width 0.09525)
		(layer "In11.Cu")
		(net "M_F_CPU0_SB_DQS_DP<8>")
	)
	(segment
		(start 301.834042 -315.040264)
		(end 304.94732 -315.040264)
		(width 0.16002)
		(layer "In11.Cu")
		(net "M_F_CPU0_SB_DQS_DP<8>")
	)
	(segment
		(start 325.816468 -293.71163)
		(end 327.775316 -291.752782)
		(width 0.09525)
		(layer "In11.Cu")
		(net "M_F_CPU0_SB_DQS_DP<8>")
	)
	(segment
		(start 328.007472 -291.656516)
		(end 328.061066 -291.656516)
		(width 0.09525)
		(layer "In11.Cu")
		(net "M_F_CPU0_SB_DQS_DP<8>")
	)
	(segment
		(start 265.54811 -314.635134)
		(end 265.822176 -314.361068)
		(width 0.16002)
		(layer "In11.Cu")
		(net "M_F_CPU0_SB_DQS_DP<8>")
	)
	(segment
		(start 289.859466 -315.040264)
		(end 290.74364 -314.15609)
		(width 0.16002)
		(layer "In11.Cu")
		(net "M_F_CPU0_SB_DQS_DP<8>")
	)
	(segment
		(start 333.042514 -291.580824)
		(end 333.050896 -291.575998)
		(width 0.09525)
		(layer "In11.Cu")
		(net "M_F_CPU0_SB_DQS_DP<8>")
	)
	(segment
		(start 283.501592 -314.15609)
		(end 283.855668 -314.510166)
		(width 0.16002)
		(layer "In11.Cu")
		(net "M_F_CPU0_SB_DQS_DP<8>")
	)
	(segment
		(start 325.457312 -296.286174)
		(end 325.816468 -295.927018)
		(width 0.09525)
		(layer "In11.Cu")
		(net "M_F_CPU0_SB_DQS_DP<8>")
	)
	(segment
		(start 274.293838 -315.040264)
		(end 274.771358 -315.040264)
		(width 0.16002)
		(layer "In11.Cu")
		(net "M_F_CPU0_SB_DQS_DP<8>")
	)
	(segment
		(start 296.926 -315.040264)
		(end 297.40352 -315.040264)
		(width 0.16002)
		(layer "In11.Cu")
		(net "M_F_CPU0_SB_DQS_DP<8>")
	)
	(segment
		(start 298.287694 -314.15609)
		(end 298.5897 -314.15609)
		(width 0.16002)
		(layer "In11.Cu")
		(net "M_F_CPU0_SB_DQS_DP<8>")
	)
	(segment
		(start 298.5897 -314.15609)
		(end 298.943776 -314.510166)
		(width 0.16002)
		(layer "In11.Cu")
		(net "M_F_CPU0_SB_DQS_DP<8>")
	)
	(segment
		(start 332.471268 -291.575998)
		(end 332.47965 -291.580824)
		(width 0.09525)
		(layer "In11.Cu")
		(net "M_F_CPU0_SB_DQS_DP<8>")
	)
	(segment
		(start 294.610028 -315.360304)
		(end 296.60596 -315.360304)
		(width 0.16002)
		(layer "In11.Cu")
		(net "M_F_CPU0_SB_DQS_DP<8>")
	)
	(segment
		(start 265.822176 -314.361068)
		(end 267.701268 -314.361068)
		(width 0.16002)
		(layer "In11.Cu")
		(net "M_F_CPU0_SB_DQS_DP<8>")
	)
	(segment
		(start 276.311614 -314.510166)
		(end 278.671782 -314.510166)
		(width 0.16002)
		(layer "In11.Cu")
		(net "M_F_CPU0_SB_DQS_DP<8>")
	)
	(segment
		(start 283.855668 -314.510166)
		(end 286.215836 -314.510166)
		(width 0.16002)
		(layer "In11.Cu")
		(net "M_F_CPU0_SB_DQS_DP<8>")
	)
	(segment
		(start 293.75989 -314.510166)
		(end 294.610028 -315.360304)
		(width 0.16002)
		(layer "In11.Cu")
		(net "M_F_CPU0_SB_DQS_DP<8>")
	)
	(segment
		(start 327.775316 -291.752782)
		(end 328.007472 -291.656516)
		(width 0.09525)
		(layer "In11.Cu")
		(net "M_F_CPU0_SB_DQS_DP<8>")
	)
	(segment
		(start 331.531214 -291.575998)
		(end 331.539596 -291.580824)
		(width 0.09525)
		(layer "In11.Cu")
		(net "M_F_CPU0_SB_DQS_DP<8>")
	)
	(segment
		(start 273.973798 -315.360304)
		(end 274.293838 -315.040264)
		(width 0.16002)
		(layer "In11.Cu")
		(net "M_F_CPU0_SB_DQS_DP<8>")
	)
	(arc
		(start 333.419704 -291.580824)
		(mid 333.653248 -291.65453)
		(end 333.895954 -291.621718)
		(width 0.09525)
		(layer "In11.Cu")
		(net "M_F_CPU0_SB_DQS_DP<8>")
	)
	(arc
		(start 330.222606 -291.580824)
		(mid 330.411074 -291.530147)
		(end 330.599542 -291.580824)
		(width 0.09525)
		(layer "In11.Cu")
		(net "M_F_CPU0_SB_DQS_DP<8>")
	)
	(arc
		(start 333.895954 -291.621718)
		(mid 333.906153 -291.617881)
		(end 333.916274 -291.613844)
		(width 0.09525)
		(layer "In11.Cu")
		(net "M_F_CPU0_SB_DQS_DP<8>")
	)
	(arc
		(start 332.10246 -291.580824)
		(mid 332.286235 -291.530052)
		(end 332.471268 -291.575998)
		(width 0.09525)
		(layer "In11.Cu")
		(net "M_F_CPU0_SB_DQS_DP<8>")
	)
	(arc
		(start 331.539596 -291.580824)
		(mid 331.821028 -291.656579)
		(end 332.10246 -291.580824)
		(width 0.09525)
		(layer "In11.Cu")
		(net "M_F_CPU0_SB_DQS_DP<8>")
	)
	(arc
		(start 328.061066 -291.656516)
		(mid 328.206774 -291.637248)
		(end 328.342498 -291.580824)
		(width 0.09525)
		(layer "In11.Cu")
		(net "M_F_CPU0_SB_DQS_DP<8>")
	)
	(arc
		(start 333.050896 -291.575998)
		(mid 333.235928 -291.530084)
		(end 333.419704 -291.580824)
		(width 0.09525)
		(layer "In11.Cu")
		(net "M_F_CPU0_SB_DQS_DP<8>")
	)
	(arc
		(start 328.719688 -291.580824)
		(mid 329.00112 -291.656579)
		(end 329.282552 -291.580824)
		(width 0.09525)
		(layer "In11.Cu")
		(net "M_F_CPU0_SB_DQS_DP<8>")
	)
	(arc
		(start 329.290934 -291.575998)
		(mid 329.475966 -291.530084)
		(end 329.659742 -291.580824)
		(width 0.09525)
		(layer "In11.Cu")
		(net "M_F_CPU0_SB_DQS_DP<8>")
	)
	(arc
		(start 330.599542 -291.580824)
		(mid 330.880974 -291.656579)
		(end 331.162406 -291.580824)
		(width 0.09525)
		(layer "In11.Cu")
		(net "M_F_CPU0_SB_DQS_DP<8>")
	)
	(arc
		(start 331.162406 -291.580824)
		(mid 331.346181 -291.530052)
		(end 331.531214 -291.575998)
		(width 0.09525)
		(layer "In11.Cu")
		(net "M_F_CPU0_SB_DQS_DP<8>")
	)
	(arc
		(start 328.342498 -291.580824)
		(mid 328.526273 -291.530052)
		(end 328.711306 -291.575998)
		(width 0.09525)
		(layer "In11.Cu")
		(net "M_F_CPU0_SB_DQS_DP<8>")
	)
	(arc
		(start 332.47965 -291.580824)
		(mid 332.761082 -291.656579)
		(end 333.042514 -291.580824)
		(width 0.09525)
		(layer "In11.Cu")
		(net "M_F_CPU0_SB_DQS_DP<8>")
	)
	(arc
		(start 329.659742 -291.580824)
		(mid 329.941174 -291.656579)
		(end 330.222606 -291.580824)
		(width 0.09525)
		(layer "In11.Cu")
		(net "M_F_CPU0_SB_DQS_DP<8>")
	)
	(segment
		(start 334.637888 -286.780224)
		(end 334.171036 -287.045908)
		(width 0.12954)
		(layer "F.Cu")
		(net "M_F_CPU0_SB_DQS_DP<7>")
	)
	(segment
		(start 290.74364 -304.806096)
		(end 289.859466 -305.69027)
		(width 0.16002)
		(layer "In11.Cu")
		(net "M_F_CPU0_SB_DQS_DP<7>")
	)
	(segment
		(start 267.701268 -305.011074)
		(end 265.822176 -305.011074)
		(width 0.16002)
		(layer "In11.Cu")
		(net "M_F_CPU0_SB_DQS_DP<7>")
	)
	(segment
		(start 283.855668 -305.160172)
		(end 283.501592 -304.806096)
		(width 0.16002)
		(layer "In11.Cu")
		(net "M_F_CPU0_SB_DQS_DP<7>")
	)
	(segment
		(start 324.827138 -287.113472)
		(end 324.126098 -287.813496)
		(width 0.09525)
		(layer "In11.Cu")
		(net "M_F_CPU0_SB_DQS_DP<7>")
	)
	(segment
		(start 332.47965 -286.720788)
		(end 332.471268 -286.715962)
		(width 0.09525)
		(layer "In11.Cu")
		(net "M_F_CPU0_SB_DQS_DP<7>")
	)
	(segment
		(start 289.061906 -306.01031)
		(end 287.065974 -306.01031)
		(width 0.16002)
		(layer "In11.Cu")
		(net "M_F_CPU0_SB_DQS_DP<7>")
	)
	(segment
		(start 274.771358 -305.69027)
		(end 274.293838 -305.69027)
		(width 0.16002)
		(layer "In11.Cu")
		(net "M_F_CPU0_SB_DQS_DP<7>")
	)
	(segment
		(start 276.311614 -305.160172)
		(end 275.957538 -304.806096)
		(width 0.16002)
		(layer "In11.Cu")
		(net "M_F_CPU0_SB_DQS_DP<7>")
	)
	(segment
		(start 289.381946 -305.69027)
		(end 289.061906 -306.01031)
		(width 0.16002)
		(layer "In11.Cu")
		(net "M_F_CPU0_SB_DQS_DP<7>")
	)
	(segment
		(start 324.125844 -287.896808)
		(end 324.10908 -287.913572)
		(width 0.09525)
		(layer "In11.Cu")
		(net "M_F_CPU0_SB_DQS_DP<7>")
	)
	(segment
		(start 293.75989 -305.160172)
		(end 291.399722 -305.160172)
		(width 0.16002)
		(layer "In11.Cu")
		(net "M_F_CPU0_SB_DQS_DP<7>")
	)
	(segment
		(start 271.192752 -305.191922)
		(end 268.802612 -305.191922)
		(width 0.16002)
		(layer "In11.Cu")
		(net "M_F_CPU0_SB_DQS_DP<7>")
	)
	(segment
		(start 298.943776 -305.160172)
		(end 298.5897 -304.806096)
		(width 0.16002)
		(layer "In11.Cu")
		(net "M_F_CPU0_SB_DQS_DP<7>")
	)
	(segment
		(start 304.94732 -305.69027)
		(end 301.834042 -305.69027)
		(width 0.16002)
		(layer "In11.Cu")
		(net "M_F_CPU0_SB_DQS_DP<7>")
	)
	(segment
		(start 275.655532 -304.806096)
		(end 274.771358 -305.69027)
		(width 0.16002)
		(layer "In11.Cu")
		(net "M_F_CPU0_SB_DQS_DP<7>")
	)
	(segment
		(start 296.926 -305.69027)
		(end 296.60596 -306.01031)
		(width 0.16002)
		(layer "In11.Cu")
		(net "M_F_CPU0_SB_DQS_DP<7>")
	)
	(segment
		(start 287.065974 -306.01031)
		(end 286.215836 -305.160172)
		(width 0.16002)
		(layer "In11.Cu")
		(net "M_F_CPU0_SB_DQS_DP<7>")
	)
	(segment
		(start 286.215836 -305.160172)
		(end 283.855668 -305.160172)
		(width 0.16002)
		(layer "In11.Cu")
		(net "M_F_CPU0_SB_DQS_DP<7>")
	)
	(segment
		(start 329.290934 -286.715962)
		(end 329.282552 -286.720788)
		(width 0.09525)
		(layer "In11.Cu")
		(net "M_F_CPU0_SB_DQS_DP<7>")
	)
	(segment
		(start 268.456156 -304.845466)
		(end 267.866876 -304.845466)
		(width 0.16002)
		(layer "In11.Cu")
		(net "M_F_CPU0_SB_DQS_DP<7>")
	)
	(segment
		(start 331.539596 -286.720788)
		(end 331.531214 -286.715962)
		(width 0.09525)
		(layer "In11.Cu")
		(net "M_F_CPU0_SB_DQS_DP<7>")
	)
	(segment
		(start 327.410572 -286.715962)
		(end 327.40219 -286.720788)
		(width 0.09525)
		(layer "In11.Cu")
		(net "M_F_CPU0_SB_DQS_DP<7>")
	)
	(segment
		(start 282.315412 -305.69027)
		(end 281.837892 -305.69027)
		(width 0.16002)
		(layer "In11.Cu")
		(net "M_F_CPU0_SB_DQS_DP<7>")
	)
	(segment
		(start 291.045646 -304.806096)
		(end 290.74364 -304.806096)
		(width 0.16002)
		(layer "In11.Cu")
		(net "M_F_CPU0_SB_DQS_DP<7>")
	)
	(segment
		(start 279.52192 -306.01031)
		(end 278.671782 -305.160172)
		(width 0.16002)
		(layer "In11.Cu")
		(net "M_F_CPU0_SB_DQS_DP<7>")
	)
	(segment
		(start 307.216556 -304.806096)
		(end 305.831494 -304.806096)
		(width 0.16002)
		(layer "In11.Cu")
		(net "M_F_CPU0_SB_DQS_DP<7>")
	)
	(segment
		(start 326.051164 -287.113472)
		(end 324.827138 -287.113472)
		(width 0.09525)
		(layer "In11.Cu")
		(net "M_F_CPU0_SB_DQS_DP<7>")
	)
	(segment
		(start 272.01114 -306.01031)
		(end 271.192752 -305.191922)
		(width 0.16002)
		(layer "In11.Cu")
		(net "M_F_CPU0_SB_DQS_DP<7>")
	)
	(segment
		(start 283.501592 -304.806096)
		(end 283.199586 -304.806096)
		(width 0.16002)
		(layer "In11.Cu")
		(net "M_F_CPU0_SB_DQS_DP<7>")
	)
	(segment
		(start 267.866876 -304.845466)
		(end 267.701268 -305.011074)
		(width 0.16002)
		(layer "In11.Cu")
		(net "M_F_CPU0_SB_DQS_DP<7>")
	)
	(segment
		(start 326.83958 -286.721042)
		(end 326.82561 -286.713168)
		(width 0.09525)
		(layer "In11.Cu")
		(net "M_F_CPU0_SB_DQS_DP<7>")
	)
	(segment
		(start 326.38492 -286.779716)
		(end 326.051164 -287.113472)
		(width 0.09525)
		(layer "In11.Cu")
		(net "M_F_CPU0_SB_DQS_DP<7>")
	)
	(segment
		(start 297.40352 -305.69027)
		(end 296.926 -305.69027)
		(width 0.16002)
		(layer "In11.Cu")
		(net "M_F_CPU0_SB_DQS_DP<7>")
	)
	(segment
		(start 296.60596 -306.01031)
		(end 294.610028 -306.01031)
		(width 0.16002)
		(layer "In11.Cu")
		(net "M_F_CPU0_SB_DQS_DP<7>")
	)
	(segment
		(start 301.303944 -305.160172)
		(end 298.943776 -305.160172)
		(width 0.16002)
		(layer "In11.Cu")
		(net "M_F_CPU0_SB_DQS_DP<7>")
	)
	(segment
		(start 289.859466 -305.69027)
		(end 289.381946 -305.69027)
		(width 0.16002)
		(layer "In11.Cu")
		(net "M_F_CPU0_SB_DQS_DP<7>")
	)
	(segment
		(start 328.342498 -286.720788)
		(end 328.332084 -286.726884)
		(width 0.09525)
		(layer "In11.Cu")
		(net "M_F_CPU0_SB_DQS_DP<7>")
	)
	(segment
		(start 278.671782 -305.160172)
		(end 276.311614 -305.160172)
		(width 0.16002)
		(layer "In11.Cu")
		(net "M_F_CPU0_SB_DQS_DP<7>")
	)
	(segment
		(start 324.126098 -287.813496)
		(end 324.125844 -287.896808)
		(width 0.09525)
		(layer "In11.Cu")
		(net "M_F_CPU0_SB_DQS_DP<7>")
	)
	(segment
		(start 301.834042 -305.69027)
		(end 301.303944 -305.160172)
		(width 0.16002)
		(layer "In11.Cu")
		(net "M_F_CPU0_SB_DQS_DP<7>")
	)
	(segment
		(start 305.831494 -304.806096)
		(end 304.94732 -305.69027)
		(width 0.16002)
		(layer "In11.Cu")
		(net "M_F_CPU0_SB_DQS_DP<7>")
	)
	(segment
		(start 268.802612 -305.191922)
		(end 268.456156 -304.845466)
		(width 0.16002)
		(layer "In11.Cu")
		(net "M_F_CPU0_SB_DQS_DP<7>")
	)
	(segment
		(start 281.517852 -306.01031)
		(end 279.52192 -306.01031)
		(width 0.16002)
		(layer "In11.Cu")
		(net "M_F_CPU0_SB_DQS_DP<7>")
	)
	(segment
		(start 294.610028 -306.01031)
		(end 293.75989 -305.160172)
		(width 0.16002)
		(layer "In11.Cu")
		(net "M_F_CPU0_SB_DQS_DP<7>")
	)
	(segment
		(start 275.957538 -304.806096)
		(end 275.655532 -304.806096)
		(width 0.16002)
		(layer "In11.Cu")
		(net "M_F_CPU0_SB_DQS_DP<7>")
	)
	(segment
		(start 328.719688 -286.720788)
		(end 328.711306 -286.715962)
		(width 0.09525)
		(layer "In11.Cu")
		(net "M_F_CPU0_SB_DQS_DP<7>")
	)
	(segment
		(start 281.837892 -305.69027)
		(end 281.517852 -306.01031)
		(width 0.16002)
		(layer "In11.Cu")
		(net "M_F_CPU0_SB_DQS_DP<7>")
	)
	(segment
		(start 283.199586 -304.806096)
		(end 282.315412 -305.69027)
		(width 0.16002)
		(layer "In11.Cu")
		(net "M_F_CPU0_SB_DQS_DP<7>")
	)
	(segment
		(start 333.050896 -286.715962)
		(end 333.042514 -286.720788)
		(width 0.09525)
		(layer "In11.Cu")
		(net "M_F_CPU0_SB_DQS_DP<7>")
	)
	(segment
		(start 273.973798 -306.01031)
		(end 272.01114 -306.01031)
		(width 0.16002)
		(layer "In11.Cu")
		(net "M_F_CPU0_SB_DQS_DP<7>")
	)
	(segment
		(start 327.40219 -286.720788)
		(end 327.3933 -286.726122)
		(width 0.09525)
		(layer "In11.Cu")
		(net "M_F_CPU0_SB_DQS_DP<7>")
	)
	(segment
		(start 324.10908 -287.913572)
		(end 307.216556 -304.806096)
		(width 0.16002)
		(layer "In11.Cu")
		(net "M_F_CPU0_SB_DQS_DP<7>")
	)
	(segment
		(start 334.171036 -287.045908)
		(end 334.017112 -286.780478)
		(width 0.09525)
		(layer "In11.Cu")
		(net "M_F_CPU0_SB_DQS_DP<7>")
	)
	(segment
		(start 265.822176 -305.011074)
		(end 265.54811 -305.28514)
		(width 0.16002)
		(layer "In11.Cu")
		(net "M_F_CPU0_SB_DQS_DP<7>")
	)
	(segment
		(start 291.399722 -305.160172)
		(end 291.045646 -304.806096)
		(width 0.16002)
		(layer "In11.Cu")
		(net "M_F_CPU0_SB_DQS_DP<7>")
	)
	(segment
		(start 334.017112 -286.780478)
		(end 333.916274 -286.753808)
		(width 0.09525)
		(layer "In11.Cu")
		(net "M_F_CPU0_SB_DQS_DP<7>")
	)
	(segment
		(start 298.5897 -304.806096)
		(end 298.287694 -304.806096)
		(width 0.16002)
		(layer "In11.Cu")
		(net "M_F_CPU0_SB_DQS_DP<7>")
	)
	(segment
		(start 298.287694 -304.806096)
		(end 297.40352 -305.69027)
		(width 0.16002)
		(layer "In11.Cu")
		(net "M_F_CPU0_SB_DQS_DP<7>")
	)
	(segment
		(start 274.293838 -305.69027)
		(end 273.973798 -306.01031)
		(width 0.16002)
		(layer "In11.Cu")
		(net "M_F_CPU0_SB_DQS_DP<7>")
	)
	(arc
		(start 332.471268 -286.715962)
		(mid 332.286236 -286.670048)
		(end 332.10246 -286.720788)
		(width 0.09525)
		(layer "In11.Cu")
		(net "M_F_CPU0_SB_DQS_DP<7>")
	)
	(arc
		(start 328.332084 -286.726884)
		(mid 328.054922 -286.796716)
		(end 327.77938 -286.720788)
		(width 0.09525)
		(layer "In11.Cu")
		(net "M_F_CPU0_SB_DQS_DP<7>")
	)
	(arc
		(start 333.419704 -286.720788)
		(mid 333.235929 -286.670016)
		(end 333.050896 -286.715962)
		(width 0.09525)
		(layer "In11.Cu")
		(net "M_F_CPU0_SB_DQS_DP<7>")
	)
	(arc
		(start 333.042514 -286.720788)
		(mid 332.761082 -286.796577)
		(end 332.47965 -286.720788)
		(width 0.09525)
		(layer "In11.Cu")
		(net "M_F_CPU0_SB_DQS_DP<7>")
	)
	(arc
		(start 327.3933 -286.726122)
		(mid 327.115783 -286.796674)
		(end 326.83958 -286.721042)
		(width 0.09525)
		(layer "In11.Cu")
		(net "M_F_CPU0_SB_DQS_DP<7>")
	)
	(arc
		(start 326.436228 -286.737044)
		(mid 326.409624 -286.757238)
		(end 326.38492 -286.779716)
		(width 0.09525)
		(layer "In11.Cu")
		(net "M_F_CPU0_SB_DQS_DP<7>")
	)
	(arc
		(start 333.895954 -286.761936)
		(mid 333.653212 -286.794721)
		(end 333.419704 -286.720788)
		(width 0.09525)
		(layer "In11.Cu")
		(net "M_F_CPU0_SB_DQS_DP<7>")
	)
	(arc
		(start 327.77938 -286.720788)
		(mid 327.595605 -286.670016)
		(end 327.410572 -286.715962)
		(width 0.09525)
		(layer "In11.Cu")
		(net "M_F_CPU0_SB_DQS_DP<7>")
	)
	(arc
		(start 332.10246 -286.720788)
		(mid 331.821028 -286.796577)
		(end 331.539596 -286.720788)
		(width 0.09525)
		(layer "In11.Cu")
		(net "M_F_CPU0_SB_DQS_DP<7>")
	)
	(arc
		(start 329.282552 -286.720788)
		(mid 329.00112 -286.796577)
		(end 328.719688 -286.720788)
		(width 0.09525)
		(layer "In11.Cu")
		(net "M_F_CPU0_SB_DQS_DP<7>")
	)
	(arc
		(start 331.162406 -286.720788)
		(mid 330.880974 -286.796577)
		(end 330.599542 -286.720788)
		(width 0.09525)
		(layer "In11.Cu")
		(net "M_F_CPU0_SB_DQS_DP<7>")
	)
	(arc
		(start 326.46239 -286.720788)
		(mid 326.449145 -286.728652)
		(end 326.436228 -286.737044)
		(width 0.09525)
		(layer "In11.Cu")
		(net "M_F_CPU0_SB_DQS_DP<7>")
	)
	(arc
		(start 330.599542 -286.720788)
		(mid 330.411074 -286.670111)
		(end 330.222606 -286.720788)
		(width 0.09525)
		(layer "In11.Cu")
		(net "M_F_CPU0_SB_DQS_DP<7>")
	)
	(arc
		(start 328.711306 -286.715962)
		(mid 328.526274 -286.670048)
		(end 328.342498 -286.720788)
		(width 0.09525)
		(layer "In11.Cu")
		(net "M_F_CPU0_SB_DQS_DP<7>")
	)
	(arc
		(start 333.916274 -286.753808)
		(mid 333.906153 -286.75797)
		(end 333.895954 -286.761936)
		(width 0.09525)
		(layer "In11.Cu")
		(net "M_F_CPU0_SB_DQS_DP<7>")
	)
	(arc
		(start 330.222606 -286.720788)
		(mid 329.941174 -286.796577)
		(end 329.659742 -286.720788)
		(width 0.09525)
		(layer "In11.Cu")
		(net "M_F_CPU0_SB_DQS_DP<7>")
	)
	(arc
		(start 331.531214 -286.715962)
		(mid 331.346182 -286.670048)
		(end 331.162406 -286.720788)
		(width 0.09525)
		(layer "In11.Cu")
		(net "M_F_CPU0_SB_DQS_DP<7>")
	)
	(arc
		(start 326.82561 -286.713168)
		(mid 326.643012 -286.670152)
		(end 326.46239 -286.720788)
		(width 0.09525)
		(layer "In11.Cu")
		(net "M_F_CPU0_SB_DQS_DP<7>")
	)
	(arc
		(start 329.659742 -286.720788)
		(mid 329.475967 -286.670016)
		(end 329.290934 -286.715962)
		(width 0.09525)
		(layer "In11.Cu")
		(net "M_F_CPU0_SB_DQS_DP<7>")
	)
	(segment
		(start 334.637888 -281.920188)
		(end 334.171036 -282.186126)
		(width 0.12954)
		(layer "F.Cu")
		(net "M_F_CPU0_SB_DQS_DP<6>")
	)
	(segment
		(start 289.061906 -296.660316)
		(end 289.381946 -296.340276)
		(width 0.16002)
		(layer "In11.Cu")
		(net "M_F_CPU0_SB_DQS_DP<6>")
	)
	(segment
		(start 301.834042 -296.340276)
		(end 304.94732 -296.340276)
		(width 0.16002)
		(layer "In11.Cu")
		(net "M_F_CPU0_SB_DQS_DP<6>")
	)
	(segment
		(start 323.895974 -281.97429)
		(end 323.919596 -281.97429)
		(width 0.09525)
		(layer "In11.Cu")
		(net "M_F_CPU0_SB_DQS_DP<6>")
	)
	(segment
		(start 328.711306 -281.85618)
		(end 328.719688 -281.861006)
		(width 0.09525)
		(layer "In11.Cu")
		(net "M_F_CPU0_SB_DQS_DP<6>")
	)
	(segment
		(start 296.926 -296.340276)
		(end 297.40352 -296.340276)
		(width 0.16002)
		(layer "In11.Cu")
		(net "M_F_CPU0_SB_DQS_DP<6>")
	)
	(segment
		(start 282.315412 -296.340276)
		(end 283.199586 -295.456102)
		(width 0.16002)
		(layer "In11.Cu")
		(net "M_F_CPU0_SB_DQS_DP<6>")
	)
	(segment
		(start 267.701268 -295.66108)
		(end 267.866876 -295.495472)
		(width 0.16002)
		(layer "In11.Cu")
		(net "M_F_CPU0_SB_DQS_DP<6>")
	)
	(segment
		(start 304.94732 -296.340276)
		(end 305.831494 -295.456102)
		(width 0.16002)
		(layer "In11.Cu")
		(net "M_F_CPU0_SB_DQS_DP<6>")
	)
	(segment
		(start 283.199586 -295.456102)
		(end 283.501592 -295.456102)
		(width 0.16002)
		(layer "In11.Cu")
		(net "M_F_CPU0_SB_DQS_DP<6>")
	)
	(segment
		(start 265.822176 -295.66108)
		(end 267.701268 -295.66108)
		(width 0.16002)
		(layer "In11.Cu")
		(net "M_F_CPU0_SB_DQS_DP<6>")
	)
	(segment
		(start 294.610028 -296.660316)
		(end 296.60596 -296.660316)
		(width 0.16002)
		(layer "In11.Cu")
		(net "M_F_CPU0_SB_DQS_DP<6>")
	)
	(segment
		(start 279.52192 -296.660316)
		(end 281.517852 -296.660316)
		(width 0.16002)
		(layer "In11.Cu")
		(net "M_F_CPU0_SB_DQS_DP<6>")
	)
	(segment
		(start 298.287694 -295.456102)
		(end 298.5897 -295.456102)
		(width 0.16002)
		(layer "In11.Cu")
		(net "M_F_CPU0_SB_DQS_DP<6>")
	)
	(segment
		(start 267.866876 -295.495472)
		(end 268.456156 -295.495472)
		(width 0.16002)
		(layer "In11.Cu")
		(net "M_F_CPU0_SB_DQS_DP<6>")
	)
	(segment
		(start 291.399722 -295.810178)
		(end 293.75989 -295.810178)
		(width 0.16002)
		(layer "In11.Cu")
		(net "M_F_CPU0_SB_DQS_DP<6>")
	)
	(segment
		(start 296.60596 -296.660316)
		(end 296.926 -296.340276)
		(width 0.16002)
		(layer "In11.Cu")
		(net "M_F_CPU0_SB_DQS_DP<6>")
	)
	(segment
		(start 301.303944 -295.810178)
		(end 301.834042 -296.340276)
		(width 0.16002)
		(layer "In11.Cu")
		(net "M_F_CPU0_SB_DQS_DP<6>")
	)
	(segment
		(start 268.802612 -295.841928)
		(end 271.192752 -295.841928)
		(width 0.16002)
		(layer "In11.Cu")
		(net "M_F_CPU0_SB_DQS_DP<6>")
	)
	(segment
		(start 274.771358 -296.340276)
		(end 275.655532 -295.456102)
		(width 0.16002)
		(layer "In11.Cu")
		(net "M_F_CPU0_SB_DQS_DP<6>")
	)
	(segment
		(start 273.973798 -296.660316)
		(end 274.293838 -296.340276)
		(width 0.16002)
		(layer "In11.Cu")
		(net "M_F_CPU0_SB_DQS_DP<6>")
	)
	(segment
		(start 283.855668 -295.810178)
		(end 286.215836 -295.810178)
		(width 0.16002)
		(layer "In11.Cu")
		(net "M_F_CPU0_SB_DQS_DP<6>")
	)
	(segment
		(start 298.5897 -295.456102)
		(end 298.943776 -295.810178)
		(width 0.16002)
		(layer "In11.Cu")
		(net "M_F_CPU0_SB_DQS_DP<6>")
	)
	(segment
		(start 281.517852 -296.660316)
		(end 281.837892 -296.340276)
		(width 0.16002)
		(layer "In11.Cu")
		(net "M_F_CPU0_SB_DQS_DP<6>")
	)
	(segment
		(start 328.332084 -281.867102)
		(end 328.342498 -281.861006)
		(width 0.09525)
		(layer "In11.Cu")
		(net "M_F_CPU0_SB_DQS_DP<6>")
	)
	(segment
		(start 305.831494 -295.456102)
		(end 307.771038 -295.456102)
		(width 0.16002)
		(layer "In11.Cu")
		(net "M_F_CPU0_SB_DQS_DP<6>")
	)
	(segment
		(start 297.40352 -296.340276)
		(end 298.287694 -295.456102)
		(width 0.16002)
		(layer "In11.Cu")
		(net "M_F_CPU0_SB_DQS_DP<6>")
	)
	(segment
		(start 334.017112 -281.920696)
		(end 334.171036 -282.186126)
		(width 0.09525)
		(layer "In11.Cu")
		(net "M_F_CPU0_SB_DQS_DP<6>")
	)
	(segment
		(start 307.771038 -295.456102)
		(end 321.25285 -281.97429)
		(width 0.16002)
		(layer "In11.Cu")
		(net "M_F_CPU0_SB_DQS_DP<6>")
	)
	(segment
		(start 275.655532 -295.456102)
		(end 275.957538 -295.456102)
		(width 0.16002)
		(layer "In11.Cu")
		(net "M_F_CPU0_SB_DQS_DP<6>")
	)
	(segment
		(start 332.471268 -281.85618)
		(end 332.47965 -281.861006)
		(width 0.09525)
		(layer "In11.Cu")
		(net "M_F_CPU0_SB_DQS_DP<6>")
	)
	(segment
		(start 274.293838 -296.340276)
		(end 274.771358 -296.340276)
		(width 0.16002)
		(layer "In11.Cu")
		(net "M_F_CPU0_SB_DQS_DP<6>")
	)
	(segment
		(start 327.619868 -281.72791)
		(end 327.664572 -281.772614)
		(width 0.09525)
		(layer "In11.Cu")
		(net "M_F_CPU0_SB_DQS_DP<6>")
	)
	(segment
		(start 298.943776 -295.810178)
		(end 301.303944 -295.810178)
		(width 0.16002)
		(layer "In11.Cu")
		(net "M_F_CPU0_SB_DQS_DP<6>")
	)
	(segment
		(start 271.192752 -295.841928)
		(end 272.01114 -296.660316)
		(width 0.16002)
		(layer "In11.Cu")
		(net "M_F_CPU0_SB_DQS_DP<6>")
	)
	(segment
		(start 278.671782 -295.810178)
		(end 279.52192 -296.660316)
		(width 0.16002)
		(layer "In11.Cu")
		(net "M_F_CPU0_SB_DQS_DP<6>")
	)
	(segment
		(start 333.042514 -281.861006)
		(end 333.050896 -281.85618)
		(width 0.09525)
		(layer "In11.Cu")
		(net "M_F_CPU0_SB_DQS_DP<6>")
	)
	(segment
		(start 276.311614 -295.810178)
		(end 278.671782 -295.810178)
		(width 0.16002)
		(layer "In11.Cu")
		(net "M_F_CPU0_SB_DQS_DP<6>")
	)
	(segment
		(start 289.859466 -296.340276)
		(end 290.74364 -295.456102)
		(width 0.16002)
		(layer "In11.Cu")
		(net "M_F_CPU0_SB_DQS_DP<6>")
	)
	(segment
		(start 287.065974 -296.660316)
		(end 289.061906 -296.660316)
		(width 0.16002)
		(layer "In11.Cu")
		(net "M_F_CPU0_SB_DQS_DP<6>")
	)
	(segment
		(start 272.01114 -296.660316)
		(end 273.973798 -296.660316)
		(width 0.16002)
		(layer "In11.Cu")
		(net "M_F_CPU0_SB_DQS_DP<6>")
	)
	(segment
		(start 281.837892 -296.340276)
		(end 282.315412 -296.340276)
		(width 0.16002)
		(layer "In11.Cu")
		(net "M_F_CPU0_SB_DQS_DP<6>")
	)
	(segment
		(start 268.456156 -295.495472)
		(end 268.802612 -295.841928)
		(width 0.16002)
		(layer "In11.Cu")
		(net "M_F_CPU0_SB_DQS_DP<6>")
	)
	(segment
		(start 333.916274 -281.894026)
		(end 334.017112 -281.920696)
		(width 0.09525)
		(layer "In11.Cu")
		(net "M_F_CPU0_SB_DQS_DP<6>")
	)
	(segment
		(start 275.957538 -295.456102)
		(end 276.311614 -295.810178)
		(width 0.16002)
		(layer "In11.Cu")
		(net "M_F_CPU0_SB_DQS_DP<6>")
	)
	(segment
		(start 291.045646 -295.456102)
		(end 291.399722 -295.810178)
		(width 0.16002)
		(layer "In11.Cu")
		(net "M_F_CPU0_SB_DQS_DP<6>")
	)
	(segment
		(start 331.531214 -281.85618)
		(end 331.539596 -281.861006)
		(width 0.09525)
		(layer "In11.Cu")
		(net "M_F_CPU0_SB_DQS_DP<6>")
	)
	(segment
		(start 321.25285 -281.97429)
		(end 323.895974 -281.97429)
		(width 0.16002)
		(layer "In11.Cu")
		(net "M_F_CPU0_SB_DQS_DP<6>")
	)
	(segment
		(start 286.215836 -295.810178)
		(end 287.065974 -296.660316)
		(width 0.16002)
		(layer "In11.Cu")
		(net "M_F_CPU0_SB_DQS_DP<6>")
	)
	(segment
		(start 329.282552 -281.861006)
		(end 329.290934 -281.85618)
		(width 0.09525)
		(layer "In11.Cu")
		(net "M_F_CPU0_SB_DQS_DP<6>")
	)
	(segment
		(start 325.24573 -281.915362)
		(end 325.433182 -281.72791)
		(width 0.09525)
		(layer "In11.Cu")
		(net "M_F_CPU0_SB_DQS_DP<6>")
	)
	(segment
		(start 323.978524 -281.915362)
		(end 325.24573 -281.915362)
		(width 0.09525)
		(layer "In11.Cu")
		(net "M_F_CPU0_SB_DQS_DP<6>")
	)
	(segment
		(start 265.54811 -295.935146)
		(end 265.822176 -295.66108)
		(width 0.16002)
		(layer "In11.Cu")
		(net "M_F_CPU0_SB_DQS_DP<6>")
	)
	(segment
		(start 289.381946 -296.340276)
		(end 289.859466 -296.340276)
		(width 0.16002)
		(layer "In11.Cu")
		(net "M_F_CPU0_SB_DQS_DP<6>")
	)
	(segment
		(start 283.501592 -295.456102)
		(end 283.855668 -295.810178)
		(width 0.16002)
		(layer "In11.Cu")
		(net "M_F_CPU0_SB_DQS_DP<6>")
	)
	(segment
		(start 325.433182 -281.72791)
		(end 327.619868 -281.72791)
		(width 0.09525)
		(layer "In11.Cu")
		(net "M_F_CPU0_SB_DQS_DP<6>")
	)
	(segment
		(start 293.75989 -295.810178)
		(end 294.610028 -296.660316)
		(width 0.16002)
		(layer "In11.Cu")
		(net "M_F_CPU0_SB_DQS_DP<6>")
	)
	(segment
		(start 290.74364 -295.456102)
		(end 291.045646 -295.456102)
		(width 0.16002)
		(layer "In11.Cu")
		(net "M_F_CPU0_SB_DQS_DP<6>")
	)
	(segment
		(start 323.919596 -281.97429)
		(end 323.978524 -281.915362)
		(width 0.09525)
		(layer "In11.Cu")
		(net "M_F_CPU0_SB_DQS_DP<6>")
	)
	(arc
		(start 329.659742 -281.861006)
		(mid 329.941174 -281.936761)
		(end 330.222606 -281.861006)
		(width 0.09525)
		(layer "In11.Cu")
		(net "M_F_CPU0_SB_DQS_DP<6>")
	)
	(arc
		(start 330.222606 -281.861006)
		(mid 330.411074 -281.810329)
		(end 330.599542 -281.861006)
		(width 0.09525)
		(layer "In11.Cu")
		(net "M_F_CPU0_SB_DQS_DP<6>")
	)
	(arc
		(start 333.895954 -281.9019)
		(mid 333.906153 -281.898063)
		(end 333.916274 -281.894026)
		(width 0.09525)
		(layer "In11.Cu")
		(net "M_F_CPU0_SB_DQS_DP<6>")
	)
	(arc
		(start 331.162406 -281.861006)
		(mid 331.346181 -281.810234)
		(end 331.531214 -281.85618)
		(width 0.09525)
		(layer "In11.Cu")
		(net "M_F_CPU0_SB_DQS_DP<6>")
	)
	(arc
		(start 329.290934 -281.85618)
		(mid 329.475966 -281.810266)
		(end 329.659742 -281.861006)
		(width 0.09525)
		(layer "In11.Cu")
		(net "M_F_CPU0_SB_DQS_DP<6>")
	)
	(arc
		(start 328.342498 -281.861006)
		(mid 328.526273 -281.810234)
		(end 328.711306 -281.85618)
		(width 0.09525)
		(layer "In11.Cu")
		(net "M_F_CPU0_SB_DQS_DP<6>")
	)
	(arc
		(start 331.539596 -281.861006)
		(mid 331.821028 -281.936761)
		(end 332.10246 -281.861006)
		(width 0.09525)
		(layer "In11.Cu")
		(net "M_F_CPU0_SB_DQS_DP<6>")
	)
	(arc
		(start 332.10246 -281.861006)
		(mid 332.286235 -281.810234)
		(end 332.471268 -281.85618)
		(width 0.09525)
		(layer "In11.Cu")
		(net "M_F_CPU0_SB_DQS_DP<6>")
	)
	(arc
		(start 327.664572 -281.772614)
		(mid 327.982535 -281.931321)
		(end 328.332084 -281.867102)
		(width 0.09525)
		(layer "In11.Cu")
		(net "M_F_CPU0_SB_DQS_DP<6>")
	)
	(arc
		(start 328.719688 -281.861006)
		(mid 329.00112 -281.936761)
		(end 329.282552 -281.861006)
		(width 0.09525)
		(layer "In11.Cu")
		(net "M_F_CPU0_SB_DQS_DP<6>")
	)
	(arc
		(start 333.419704 -281.861006)
		(mid 333.653248 -281.934712)
		(end 333.895954 -281.9019)
		(width 0.09525)
		(layer "In11.Cu")
		(net "M_F_CPU0_SB_DQS_DP<6>")
	)
	(arc
		(start 333.050896 -281.85618)
		(mid 333.235928 -281.810266)
		(end 333.419704 -281.861006)
		(width 0.09525)
		(layer "In11.Cu")
		(net "M_F_CPU0_SB_DQS_DP<6>")
	)
	(arc
		(start 330.599542 -281.861006)
		(mid 330.880974 -281.936761)
		(end 331.162406 -281.861006)
		(width 0.09525)
		(layer "In11.Cu")
		(net "M_F_CPU0_SB_DQS_DP<6>")
	)
	(arc
		(start 332.47965 -281.861006)
		(mid 332.761082 -281.936761)
		(end 333.042514 -281.861006)
		(width 0.09525)
		(layer "In11.Cu")
		(net "M_F_CPU0_SB_DQS_DP<6>")
	)
	(segment
		(start 334.637888 -277.060152)
		(end 334.171036 -277.32609)
		(width 0.12954)
		(layer "F.Cu")
		(net "M_F_CPU0_SB_DQS_DP<5>")
	)
	(segment
		(start 301.834042 -286.990282)
		(end 304.94732 -286.990282)
		(width 0.16002)
		(layer "In11.Cu")
		(net "M_F_CPU0_SB_DQS_DP<5>")
	)
	(segment
		(start 308.308248 -286.106108)
		(end 318.063626 -276.35073)
		(width 0.16002)
		(layer "In11.Cu")
		(net "M_F_CPU0_SB_DQS_DP<5>")
	)
	(segment
		(start 334.017112 -277.06066)
		(end 334.171036 -277.32609)
		(width 0.09525)
		(layer "In11.Cu")
		(net "M_F_CPU0_SB_DQS_DP<5>")
	)
	(segment
		(start 273.973798 -287.310322)
		(end 274.293838 -286.990282)
		(width 0.16002)
		(layer "In11.Cu")
		(net "M_F_CPU0_SB_DQS_DP<5>")
	)
	(segment
		(start 268.456156 -286.145478)
		(end 268.802612 -286.491934)
		(width 0.16002)
		(layer "In11.Cu")
		(net "M_F_CPU0_SB_DQS_DP<5>")
	)
	(segment
		(start 333.042514 -277.00097)
		(end 333.050896 -276.996144)
		(width 0.09525)
		(layer "In11.Cu")
		(net "M_F_CPU0_SB_DQS_DP<5>")
	)
	(segment
		(start 275.655532 -286.106108)
		(end 275.957538 -286.106108)
		(width 0.16002)
		(layer "In11.Cu")
		(net "M_F_CPU0_SB_DQS_DP<5>")
	)
	(segment
		(start 298.5897 -286.106108)
		(end 298.943776 -286.460184)
		(width 0.16002)
		(layer "In11.Cu")
		(net "M_F_CPU0_SB_DQS_DP<5>")
	)
	(segment
		(start 282.315412 -286.990282)
		(end 283.199586 -286.106108)
		(width 0.16002)
		(layer "In11.Cu")
		(net "M_F_CPU0_SB_DQS_DP<5>")
	)
	(segment
		(start 293.75989 -286.460184)
		(end 294.610028 -287.310322)
		(width 0.16002)
		(layer "In11.Cu")
		(net "M_F_CPU0_SB_DQS_DP<5>")
	)
	(segment
		(start 286.215836 -286.460184)
		(end 287.065974 -287.310322)
		(width 0.16002)
		(layer "In11.Cu")
		(net "M_F_CPU0_SB_DQS_DP<5>")
	)
	(segment
		(start 268.802612 -286.491934)
		(end 271.192752 -286.491934)
		(width 0.16002)
		(layer "In11.Cu")
		(net "M_F_CPU0_SB_DQS_DP<5>")
	)
	(segment
		(start 283.199586 -286.106108)
		(end 283.501592 -286.106108)
		(width 0.16002)
		(layer "In11.Cu")
		(net "M_F_CPU0_SB_DQS_DP<5>")
	)
	(segment
		(start 265.822176 -286.311086)
		(end 267.701268 -286.311086)
		(width 0.16002)
		(layer "In11.Cu")
		(net "M_F_CPU0_SB_DQS_DP<5>")
	)
	(segment
		(start 333.916274 -277.03399)
		(end 334.017112 -277.06066)
		(width 0.09525)
		(layer "In11.Cu")
		(net "M_F_CPU0_SB_DQS_DP<5>")
	)
	(segment
		(start 274.293838 -286.990282)
		(end 274.771358 -286.990282)
		(width 0.16002)
		(layer "In11.Cu")
		(net "M_F_CPU0_SB_DQS_DP<5>")
	)
	(segment
		(start 276.311614 -286.460184)
		(end 278.671782 -286.460184)
		(width 0.16002)
		(layer "In11.Cu")
		(net "M_F_CPU0_SB_DQS_DP<5>")
	)
	(segment
		(start 287.065974 -287.310322)
		(end 289.061906 -287.310322)
		(width 0.16002)
		(layer "In11.Cu")
		(net "M_F_CPU0_SB_DQS_DP<5>")
	)
	(segment
		(start 267.866876 -286.145478)
		(end 268.456156 -286.145478)
		(width 0.16002)
		(layer "In11.Cu")
		(net "M_F_CPU0_SB_DQS_DP<5>")
	)
	(segment
		(start 305.831494 -286.106108)
		(end 308.308248 -286.106108)
		(width 0.16002)
		(layer "In11.Cu")
		(net "M_F_CPU0_SB_DQS_DP<5>")
	)
	(segment
		(start 298.943776 -286.460184)
		(end 301.303944 -286.460184)
		(width 0.16002)
		(layer "In11.Cu")
		(net "M_F_CPU0_SB_DQS_DP<5>")
	)
	(segment
		(start 296.926 -286.990282)
		(end 297.40352 -286.990282)
		(width 0.16002)
		(layer "In11.Cu")
		(net "M_F_CPU0_SB_DQS_DP<5>")
	)
	(segment
		(start 283.501592 -286.106108)
		(end 283.855668 -286.460184)
		(width 0.16002)
		(layer "In11.Cu")
		(net "M_F_CPU0_SB_DQS_DP<5>")
	)
	(segment
		(start 279.52192 -287.310322)
		(end 281.517852 -287.310322)
		(width 0.16002)
		(layer "In11.Cu")
		(net "M_F_CPU0_SB_DQS_DP<5>")
	)
	(segment
		(start 323.978524 -276.291802)
		(end 324.256654 -276.291802)
		(width 0.09525)
		(layer "In11.Cu")
		(net "M_F_CPU0_SB_DQS_DP<5>")
	)
	(segment
		(start 304.94732 -286.990282)
		(end 305.831494 -286.106108)
		(width 0.16002)
		(layer "In11.Cu")
		(net "M_F_CPU0_SB_DQS_DP<5>")
	)
	(segment
		(start 324.771512 -276.80666)
		(end 327.06056 -276.80666)
		(width 0.09525)
		(layer "In11.Cu")
		(net "M_F_CPU0_SB_DQS_DP<5>")
	)
	(segment
		(start 271.192752 -286.491934)
		(end 272.01114 -287.310322)
		(width 0.16002)
		(layer "In11.Cu")
		(net "M_F_CPU0_SB_DQS_DP<5>")
	)
	(segment
		(start 289.061906 -287.310322)
		(end 289.381946 -286.990282)
		(width 0.16002)
		(layer "In11.Cu")
		(net "M_F_CPU0_SB_DQS_DP<5>")
	)
	(segment
		(start 332.471268 -276.996144)
		(end 332.47965 -277.00097)
		(width 0.09525)
		(layer "In11.Cu")
		(net "M_F_CPU0_SB_DQS_DP<5>")
	)
	(segment
		(start 291.045646 -286.106108)
		(end 291.399722 -286.460184)
		(width 0.16002)
		(layer "In11.Cu")
		(net "M_F_CPU0_SB_DQS_DP<5>")
	)
	(segment
		(start 289.381946 -286.990282)
		(end 289.859466 -286.990282)
		(width 0.16002)
		(layer "In11.Cu")
		(net "M_F_CPU0_SB_DQS_DP<5>")
	)
	(segment
		(start 274.771358 -286.990282)
		(end 275.655532 -286.106108)
		(width 0.16002)
		(layer "In11.Cu")
		(net "M_F_CPU0_SB_DQS_DP<5>")
	)
	(segment
		(start 275.957538 -286.106108)
		(end 276.311614 -286.460184)
		(width 0.16002)
		(layer "In11.Cu")
		(net "M_F_CPU0_SB_DQS_DP<5>")
	)
	(segment
		(start 291.399722 -286.460184)
		(end 293.75989 -286.460184)
		(width 0.16002)
		(layer "In11.Cu")
		(net "M_F_CPU0_SB_DQS_DP<5>")
	)
	(segment
		(start 328.711306 -276.996144)
		(end 328.719688 -277.00097)
		(width 0.09525)
		(layer "In11.Cu")
		(net "M_F_CPU0_SB_DQS_DP<5>")
	)
	(segment
		(start 323.919596 -276.35073)
		(end 323.978524 -276.291802)
		(width 0.09525)
		(layer "In11.Cu")
		(net "M_F_CPU0_SB_DQS_DP<5>")
	)
	(segment
		(start 331.531214 -276.996144)
		(end 331.539596 -277.00097)
		(width 0.09525)
		(layer "In11.Cu")
		(net "M_F_CPU0_SB_DQS_DP<5>")
	)
	(segment
		(start 267.701268 -286.311086)
		(end 267.866876 -286.145478)
		(width 0.16002)
		(layer "In11.Cu")
		(net "M_F_CPU0_SB_DQS_DP<5>")
	)
	(segment
		(start 296.60596 -287.310322)
		(end 296.926 -286.990282)
		(width 0.16002)
		(layer "In11.Cu")
		(net "M_F_CPU0_SB_DQS_DP<5>")
	)
	(segment
		(start 298.287694 -286.106108)
		(end 298.5897 -286.106108)
		(width 0.16002)
		(layer "In11.Cu")
		(net "M_F_CPU0_SB_DQS_DP<5>")
	)
	(segment
		(start 329.282552 -277.00097)
		(end 329.290934 -276.996144)
		(width 0.09525)
		(layer "In11.Cu")
		(net "M_F_CPU0_SB_DQS_DP<5>")
	)
	(segment
		(start 281.517852 -287.310322)
		(end 281.837892 -286.990282)
		(width 0.16002)
		(layer "In11.Cu")
		(net "M_F_CPU0_SB_DQS_DP<5>")
	)
	(segment
		(start 297.40352 -286.990282)
		(end 298.287694 -286.106108)
		(width 0.16002)
		(layer "In11.Cu")
		(net "M_F_CPU0_SB_DQS_DP<5>")
	)
	(segment
		(start 278.671782 -286.460184)
		(end 279.52192 -287.310322)
		(width 0.16002)
		(layer "In11.Cu")
		(net "M_F_CPU0_SB_DQS_DP<5>")
	)
	(segment
		(start 324.256654 -276.291802)
		(end 324.771512 -276.80666)
		(width 0.09525)
		(layer "In11.Cu")
		(net "M_F_CPU0_SB_DQS_DP<5>")
	)
	(segment
		(start 323.895974 -276.35073)
		(end 323.919596 -276.35073)
		(width 0.09525)
		(layer "In11.Cu")
		(net "M_F_CPU0_SB_DQS_DP<5>")
	)
	(segment
		(start 272.01114 -287.310322)
		(end 273.973798 -287.310322)
		(width 0.16002)
		(layer "In11.Cu")
		(net "M_F_CPU0_SB_DQS_DP<5>")
	)
	(segment
		(start 290.74364 -286.106108)
		(end 291.045646 -286.106108)
		(width 0.16002)
		(layer "In11.Cu")
		(net "M_F_CPU0_SB_DQS_DP<5>")
	)
	(segment
		(start 301.303944 -286.460184)
		(end 301.834042 -286.990282)
		(width 0.16002)
		(layer "In11.Cu")
		(net "M_F_CPU0_SB_DQS_DP<5>")
	)
	(segment
		(start 318.063626 -276.35073)
		(end 323.895974 -276.35073)
		(width 0.16002)
		(layer "In11.Cu")
		(net "M_F_CPU0_SB_DQS_DP<5>")
	)
	(segment
		(start 283.855668 -286.460184)
		(end 286.215836 -286.460184)
		(width 0.16002)
		(layer "In11.Cu")
		(net "M_F_CPU0_SB_DQS_DP<5>")
	)
	(segment
		(start 281.837892 -286.990282)
		(end 282.315412 -286.990282)
		(width 0.16002)
		(layer "In11.Cu")
		(net "M_F_CPU0_SB_DQS_DP<5>")
	)
	(segment
		(start 294.610028 -287.310322)
		(end 296.60596 -287.310322)
		(width 0.16002)
		(layer "In11.Cu")
		(net "M_F_CPU0_SB_DQS_DP<5>")
	)
	(segment
		(start 289.859466 -286.990282)
		(end 290.74364 -286.106108)
		(width 0.16002)
		(layer "In11.Cu")
		(net "M_F_CPU0_SB_DQS_DP<5>")
	)
	(segment
		(start 265.54811 -286.585152)
		(end 265.822176 -286.311086)
		(width 0.16002)
		(layer "In11.Cu")
		(net "M_F_CPU0_SB_DQS_DP<5>")
	)
	(segment
		(start 328.342244 -277.000716)
		(end 328.342498 -277.00097)
		(width 0.09525)
		(layer "In11.Cu")
		(net "M_F_CPU0_SB_DQS_DP<5>")
	)
	(arc
		(start 333.895954 -277.041864)
		(mid 333.906153 -277.038027)
		(end 333.916274 -277.03399)
		(width 0.09525)
		(layer "In11.Cu")
		(net "M_F_CPU0_SB_DQS_DP<5>")
	)
	(arc
		(start 329.659742 -277.00097)
		(mid 329.941174 -277.076725)
		(end 330.222606 -277.00097)
		(width 0.09525)
		(layer "In11.Cu")
		(net "M_F_CPU0_SB_DQS_DP<5>")
	)
	(arc
		(start 333.419704 -277.00097)
		(mid 333.653248 -277.074676)
		(end 333.895954 -277.041864)
		(width 0.09525)
		(layer "In11.Cu")
		(net "M_F_CPU0_SB_DQS_DP<5>")
	)
	(arc
		(start 328.719688 -277.00097)
		(mid 329.00112 -277.076725)
		(end 329.282552 -277.00097)
		(width 0.09525)
		(layer "In11.Cu")
		(net "M_F_CPU0_SB_DQS_DP<5>")
	)
	(arc
		(start 331.539596 -277.00097)
		(mid 331.821028 -277.076725)
		(end 332.10246 -277.00097)
		(width 0.09525)
		(layer "In11.Cu")
		(net "M_F_CPU0_SB_DQS_DP<5>")
	)
	(arc
		(start 330.599542 -277.00097)
		(mid 330.880974 -277.076725)
		(end 331.162406 -277.00097)
		(width 0.09525)
		(layer "In11.Cu")
		(net "M_F_CPU0_SB_DQS_DP<5>")
	)
	(arc
		(start 332.47965 -277.00097)
		(mid 332.761082 -277.076725)
		(end 333.042514 -277.00097)
		(width 0.09525)
		(layer "In11.Cu")
		(net "M_F_CPU0_SB_DQS_DP<5>")
	)
	(arc
		(start 330.222606 -277.00097)
		(mid 330.411074 -276.950293)
		(end 330.599542 -277.00097)
		(width 0.09525)
		(layer "In11.Cu")
		(net "M_F_CPU0_SB_DQS_DP<5>")
	)
	(arc
		(start 327.06056 -276.80666)
		(mid 327.433066 -276.856071)
		(end 327.779888 -277.000716)
		(width 0.09525)
		(layer "In11.Cu")
		(net "M_F_CPU0_SB_DQS_DP<5>")
	)
	(arc
		(start 333.050896 -276.996144)
		(mid 333.235928 -276.95023)
		(end 333.419704 -277.00097)
		(width 0.09525)
		(layer "In11.Cu")
		(net "M_F_CPU0_SB_DQS_DP<5>")
	)
	(arc
		(start 331.162406 -277.00097)
		(mid 331.346181 -276.950198)
		(end 331.531214 -276.996144)
		(width 0.09525)
		(layer "In11.Cu")
		(net "M_F_CPU0_SB_DQS_DP<5>")
	)
	(arc
		(start 327.779888 -277.000716)
		(mid 328.061066 -277.076378)
		(end 328.342244 -277.000716)
		(width 0.09525)
		(layer "In11.Cu")
		(net "M_F_CPU0_SB_DQS_DP<5>")
	)
	(arc
		(start 329.290934 -276.996144)
		(mid 329.475966 -276.95023)
		(end 329.659742 -277.00097)
		(width 0.09525)
		(layer "In11.Cu")
		(net "M_F_CPU0_SB_DQS_DP<5>")
	)
	(arc
		(start 332.10246 -277.00097)
		(mid 332.286235 -276.950198)
		(end 332.471268 -276.996144)
		(width 0.09525)
		(layer "In11.Cu")
		(net "M_F_CPU0_SB_DQS_DP<5>")
	)
	(arc
		(start 328.342498 -277.00097)
		(mid 328.526273 -276.950198)
		(end 328.711306 -276.996144)
		(width 0.09525)
		(layer "In11.Cu")
		(net "M_F_CPU0_SB_DQS_DP<5>")
	)
	(segment
		(start 334.637888 -272.200116)
		(end 334.171036 -272.466054)
		(width 0.12954)
		(layer "F.Cu")
		(net "M_F_CPU0_SB_DQS_DP<4>")
	)
	(segment
		(start 289.061906 -277.960328)
		(end 289.381946 -277.640288)
		(width 0.16002)
		(layer "In11.Cu")
		(net "M_F_CPU0_SB_DQS_DP<4>")
	)
	(segment
		(start 278.671782 -277.11019)
		(end 279.52192 -277.960328)
		(width 0.16002)
		(layer "In11.Cu")
		(net "M_F_CPU0_SB_DQS_DP<4>")
	)
	(segment
		(start 324.221094 -270.668242)
		(end 324.415912 -270.86306)
		(width 0.09525)
		(layer "In11.Cu")
		(net "M_F_CPU0_SB_DQS_DP<4>")
	)
	(segment
		(start 332.471268 -272.136108)
		(end 332.47965 -272.140934)
		(width 0.09525)
		(layer "In11.Cu")
		(net "M_F_CPU0_SB_DQS_DP<4>")
	)
	(segment
		(start 329.282552 -272.140934)
		(end 329.290934 -272.136108)
		(width 0.09525)
		(layer "In11.Cu")
		(net "M_F_CPU0_SB_DQS_DP<4>")
	)
	(segment
		(start 274.293838 -277.640288)
		(end 274.771358 -277.640288)
		(width 0.16002)
		(layer "In11.Cu")
		(net "M_F_CPU0_SB_DQS_DP<4>")
	)
	(segment
		(start 267.866876 -276.795484)
		(end 268.456156 -276.795484)
		(width 0.16002)
		(layer "In11.Cu")
		(net "M_F_CPU0_SB_DQS_DP<4>")
	)
	(segment
		(start 301.834042 -277.640288)
		(end 304.94732 -277.640288)
		(width 0.16002)
		(layer "In11.Cu")
		(net "M_F_CPU0_SB_DQS_DP<4>")
	)
	(segment
		(start 283.501592 -276.756114)
		(end 283.855668 -277.11019)
		(width 0.16002)
		(layer "In11.Cu")
		(net "M_F_CPU0_SB_DQS_DP<4>")
	)
	(segment
		(start 297.40352 -277.640288)
		(end 298.287694 -276.756114)
		(width 0.16002)
		(layer "In11.Cu")
		(net "M_F_CPU0_SB_DQS_DP<4>")
	)
	(segment
		(start 283.199586 -276.756114)
		(end 283.501592 -276.756114)
		(width 0.16002)
		(layer "In11.Cu")
		(net "M_F_CPU0_SB_DQS_DP<4>")
	)
	(segment
		(start 333.042514 -272.140934)
		(end 333.050896 -272.136108)
		(width 0.09525)
		(layer "In11.Cu")
		(net "M_F_CPU0_SB_DQS_DP<4>")
	)
	(segment
		(start 296.60596 -277.960328)
		(end 296.926 -277.640288)
		(width 0.16002)
		(layer "In11.Cu")
		(net "M_F_CPU0_SB_DQS_DP<4>")
	)
	(segment
		(start 268.456156 -276.795484)
		(end 268.802612 -277.14194)
		(width 0.16002)
		(layer "In11.Cu")
		(net "M_F_CPU0_SB_DQS_DP<4>")
	)
	(segment
		(start 301.303944 -277.11019)
		(end 301.834042 -277.640288)
		(width 0.16002)
		(layer "In11.Cu")
		(net "M_F_CPU0_SB_DQS_DP<4>")
	)
	(segment
		(start 273.973798 -277.960328)
		(end 274.293838 -277.640288)
		(width 0.16002)
		(layer "In11.Cu")
		(net "M_F_CPU0_SB_DQS_DP<4>")
	)
	(segment
		(start 324.415912 -270.86306)
		(end 325.255128 -270.86306)
		(width 0.09525)
		(layer "In11.Cu")
		(net "M_F_CPU0_SB_DQS_DP<4>")
	)
	(segment
		(start 326.431148 -272.03908)
		(end 327.403714 -272.03908)
		(width 0.09525)
		(layer "In11.Cu")
		(net "M_F_CPU0_SB_DQS_DP<4>")
	)
	(segment
		(start 296.926 -277.640288)
		(end 297.40352 -277.640288)
		(width 0.16002)
		(layer "In11.Cu")
		(net "M_F_CPU0_SB_DQS_DP<4>")
	)
	(segment
		(start 323.919596 -270.72717)
		(end 323.978524 -270.668242)
		(width 0.09525)
		(layer "In11.Cu")
		(net "M_F_CPU0_SB_DQS_DP<4>")
	)
	(segment
		(start 286.215836 -277.11019)
		(end 287.065974 -277.960328)
		(width 0.16002)
		(layer "In11.Cu")
		(net "M_F_CPU0_SB_DQS_DP<4>")
	)
	(segment
		(start 298.287694 -276.756114)
		(end 298.5897 -276.756114)
		(width 0.16002)
		(layer "In11.Cu")
		(net "M_F_CPU0_SB_DQS_DP<4>")
	)
	(segment
		(start 328.342244 -272.14068)
		(end 328.342498 -272.140934)
		(width 0.09525)
		(layer "In11.Cu")
		(net "M_F_CPU0_SB_DQS_DP<4>")
	)
	(segment
		(start 287.065974 -277.960328)
		(end 289.061906 -277.960328)
		(width 0.16002)
		(layer "In11.Cu")
		(net "M_F_CPU0_SB_DQS_DP<4>")
	)
	(segment
		(start 304.94732 -277.640288)
		(end 305.831494 -276.756114)
		(width 0.16002)
		(layer "In11.Cu")
		(net "M_F_CPU0_SB_DQS_DP<4>")
	)
	(segment
		(start 293.75989 -277.11019)
		(end 294.610028 -277.960328)
		(width 0.16002)
		(layer "In11.Cu")
		(net "M_F_CPU0_SB_DQS_DP<4>")
	)
	(segment
		(start 274.771358 -277.640288)
		(end 275.655532 -276.756114)
		(width 0.16002)
		(layer "In11.Cu")
		(net "M_F_CPU0_SB_DQS_DP<4>")
	)
	(segment
		(start 268.802612 -277.14194)
		(end 271.192752 -277.14194)
		(width 0.16002)
		(layer "In11.Cu")
		(net "M_F_CPU0_SB_DQS_DP<4>")
	)
	(segment
		(start 275.957538 -276.756114)
		(end 276.311614 -277.11019)
		(width 0.16002)
		(layer "In11.Cu")
		(net "M_F_CPU0_SB_DQS_DP<4>")
	)
	(segment
		(start 283.855668 -277.11019)
		(end 286.215836 -277.11019)
		(width 0.16002)
		(layer "In11.Cu")
		(net "M_F_CPU0_SB_DQS_DP<4>")
	)
	(segment
		(start 272.01114 -277.960328)
		(end 273.973798 -277.960328)
		(width 0.16002)
		(layer "In11.Cu")
		(net "M_F_CPU0_SB_DQS_DP<4>")
	)
	(segment
		(start 289.381946 -277.640288)
		(end 289.859466 -277.640288)
		(width 0.16002)
		(layer "In11.Cu")
		(net "M_F_CPU0_SB_DQS_DP<4>")
	)
	(segment
		(start 265.54811 -277.235158)
		(end 265.822176 -276.961092)
		(width 0.16002)
		(layer "In11.Cu")
		(net "M_F_CPU0_SB_DQS_DP<4>")
	)
	(segment
		(start 276.311614 -277.11019)
		(end 278.671782 -277.11019)
		(width 0.16002)
		(layer "In11.Cu")
		(net "M_F_CPU0_SB_DQS_DP<4>")
	)
	(segment
		(start 275.655532 -276.756114)
		(end 275.957538 -276.756114)
		(width 0.16002)
		(layer "In11.Cu")
		(net "M_F_CPU0_SB_DQS_DP<4>")
	)
	(segment
		(start 328.711306 -272.136108)
		(end 328.719688 -272.140934)
		(width 0.09525)
		(layer "In11.Cu")
		(net "M_F_CPU0_SB_DQS_DP<4>")
	)
	(segment
		(start 333.916274 -272.173954)
		(end 334.017112 -272.200624)
		(width 0.09525)
		(layer "In11.Cu")
		(net "M_F_CPU0_SB_DQS_DP<4>")
	)
	(segment
		(start 289.859466 -277.640288)
		(end 290.74364 -276.756114)
		(width 0.16002)
		(layer "In11.Cu")
		(net "M_F_CPU0_SB_DQS_DP<4>")
	)
	(segment
		(start 334.017112 -272.200624)
		(end 334.171036 -272.466054)
		(width 0.09525)
		(layer "In11.Cu")
		(net "M_F_CPU0_SB_DQS_DP<4>")
	)
	(segment
		(start 298.943776 -277.11019)
		(end 301.303944 -277.11019)
		(width 0.16002)
		(layer "In11.Cu")
		(net "M_F_CPU0_SB_DQS_DP<4>")
	)
	(segment
		(start 323.895974 -270.72717)
		(end 323.919596 -270.72717)
		(width 0.09525)
		(layer "In11.Cu")
		(net "M_F_CPU0_SB_DQS_DP<4>")
	)
	(segment
		(start 265.822176 -276.961092)
		(end 267.701268 -276.961092)
		(width 0.16002)
		(layer "In11.Cu")
		(net "M_F_CPU0_SB_DQS_DP<4>")
	)
	(segment
		(start 290.74364 -276.756114)
		(end 291.045646 -276.756114)
		(width 0.16002)
		(layer "In11.Cu")
		(net "M_F_CPU0_SB_DQS_DP<4>")
	)
	(segment
		(start 282.315412 -277.640288)
		(end 283.199586 -276.756114)
		(width 0.16002)
		(layer "In11.Cu")
		(net "M_F_CPU0_SB_DQS_DP<4>")
	)
	(segment
		(start 281.837892 -277.640288)
		(end 282.315412 -277.640288)
		(width 0.16002)
		(layer "In11.Cu")
		(net "M_F_CPU0_SB_DQS_DP<4>")
	)
	(segment
		(start 291.045646 -276.756114)
		(end 291.399722 -277.11019)
		(width 0.16002)
		(layer "In11.Cu")
		(net "M_F_CPU0_SB_DQS_DP<4>")
	)
	(segment
		(start 281.517852 -277.960328)
		(end 281.837892 -277.640288)
		(width 0.16002)
		(layer "In11.Cu")
		(net "M_F_CPU0_SB_DQS_DP<4>")
	)
	(segment
		(start 323.978524 -270.668242)
		(end 324.221094 -270.668242)
		(width 0.09525)
		(layer "In11.Cu")
		(net "M_F_CPU0_SB_DQS_DP<4>")
	)
	(segment
		(start 305.831494 -276.756114)
		(end 307.380894 -276.756114)
		(width 0.16002)
		(layer "In11.Cu")
		(net "M_F_CPU0_SB_DQS_DP<4>")
	)
	(segment
		(start 271.192752 -277.14194)
		(end 272.01114 -277.960328)
		(width 0.16002)
		(layer "In11.Cu")
		(net "M_F_CPU0_SB_DQS_DP<4>")
	)
	(segment
		(start 267.701268 -276.961092)
		(end 267.866876 -276.795484)
		(width 0.16002)
		(layer "In11.Cu")
		(net "M_F_CPU0_SB_DQS_DP<4>")
	)
	(segment
		(start 294.610028 -277.960328)
		(end 296.60596 -277.960328)
		(width 0.16002)
		(layer "In11.Cu")
		(net "M_F_CPU0_SB_DQS_DP<4>")
	)
	(segment
		(start 313.409838 -270.72717)
		(end 323.895974 -270.72717)
		(width 0.16002)
		(layer "In11.Cu")
		(net "M_F_CPU0_SB_DQS_DP<4>")
	)
	(segment
		(start 331.531214 -272.136108)
		(end 331.539596 -272.140934)
		(width 0.09525)
		(layer "In11.Cu")
		(net "M_F_CPU0_SB_DQS_DP<4>")
	)
	(segment
		(start 279.52192 -277.960328)
		(end 281.517852 -277.960328)
		(width 0.16002)
		(layer "In11.Cu")
		(net "M_F_CPU0_SB_DQS_DP<4>")
	)
	(segment
		(start 325.255128 -270.86306)
		(end 326.431148 -272.03908)
		(width 0.09525)
		(layer "In11.Cu")
		(net "M_F_CPU0_SB_DQS_DP<4>")
	)
	(segment
		(start 307.380894 -276.756114)
		(end 313.409838 -270.72717)
		(width 0.16002)
		(layer "In11.Cu")
		(net "M_F_CPU0_SB_DQS_DP<4>")
	)
	(segment
		(start 291.399722 -277.11019)
		(end 293.75989 -277.11019)
		(width 0.16002)
		(layer "In11.Cu")
		(net "M_F_CPU0_SB_DQS_DP<4>")
	)
	(segment
		(start 298.5897 -276.756114)
		(end 298.943776 -277.11019)
		(width 0.16002)
		(layer "In11.Cu")
		(net "M_F_CPU0_SB_DQS_DP<4>")
	)
	(arc
		(start 328.719688 -272.140934)
		(mid 329.00112 -272.216689)
		(end 329.282552 -272.140934)
		(width 0.09525)
		(layer "In11.Cu")
		(net "M_F_CPU0_SB_DQS_DP<4>")
	)
	(arc
		(start 328.342498 -272.140934)
		(mid 328.526273 -272.090162)
		(end 328.711306 -272.136108)
		(width 0.09525)
		(layer "In11.Cu")
		(net "M_F_CPU0_SB_DQS_DP<4>")
	)
	(arc
		(start 333.419704 -272.140934)
		(mid 333.653248 -272.21464)
		(end 333.895954 -272.181828)
		(width 0.09525)
		(layer "In11.Cu")
		(net "M_F_CPU0_SB_DQS_DP<4>")
	)
	(arc
		(start 330.599542 -272.140934)
		(mid 330.880974 -272.216689)
		(end 331.162406 -272.140934)
		(width 0.09525)
		(layer "In11.Cu")
		(net "M_F_CPU0_SB_DQS_DP<4>")
	)
	(arc
		(start 327.779888 -272.14068)
		(mid 328.061066 -272.216342)
		(end 328.342244 -272.14068)
		(width 0.09525)
		(layer "In11.Cu")
		(net "M_F_CPU0_SB_DQS_DP<4>")
	)
	(arc
		(start 329.659742 -272.140934)
		(mid 329.941174 -272.216689)
		(end 330.222606 -272.140934)
		(width 0.09525)
		(layer "In11.Cu")
		(net "M_F_CPU0_SB_DQS_DP<4>")
	)
	(arc
		(start 332.47965 -272.140934)
		(mid 332.761082 -272.216689)
		(end 333.042514 -272.140934)
		(width 0.09525)
		(layer "In11.Cu")
		(net "M_F_CPU0_SB_DQS_DP<4>")
	)
	(arc
		(start 327.403714 -272.03908)
		(mid 327.59853 -272.064963)
		(end 327.779888 -272.14068)
		(width 0.09525)
		(layer "In11.Cu")
		(net "M_F_CPU0_SB_DQS_DP<4>")
	)
	(arc
		(start 332.10246 -272.140934)
		(mid 332.286235 -272.090162)
		(end 332.471268 -272.136108)
		(width 0.09525)
		(layer "In11.Cu")
		(net "M_F_CPU0_SB_DQS_DP<4>")
	)
	(arc
		(start 333.050896 -272.136108)
		(mid 333.235928 -272.090194)
		(end 333.419704 -272.140934)
		(width 0.09525)
		(layer "In11.Cu")
		(net "M_F_CPU0_SB_DQS_DP<4>")
	)
	(arc
		(start 329.290934 -272.136108)
		(mid 329.475966 -272.090194)
		(end 329.659742 -272.140934)
		(width 0.09525)
		(layer "In11.Cu")
		(net "M_F_CPU0_SB_DQS_DP<4>")
	)
	(arc
		(start 333.895954 -272.181828)
		(mid 333.906153 -272.177991)
		(end 333.916274 -272.173954)
		(width 0.09525)
		(layer "In11.Cu")
		(net "M_F_CPU0_SB_DQS_DP<4>")
	)
	(arc
		(start 331.162406 -272.140934)
		(mid 331.346181 -272.090162)
		(end 331.531214 -272.136108)
		(width 0.09525)
		(layer "In11.Cu")
		(net "M_F_CPU0_SB_DQS_DP<4>")
	)
	(arc
		(start 331.539596 -272.140934)
		(mid 331.821028 -272.216689)
		(end 332.10246 -272.140934)
		(width 0.09525)
		(layer "In11.Cu")
		(net "M_F_CPU0_SB_DQS_DP<4>")
	)
	(arc
		(start 330.222606 -272.140934)
		(mid 330.411074 -272.090257)
		(end 330.599542 -272.140934)
		(width 0.09525)
		(layer "In11.Cu")
		(net "M_F_CPU0_SB_DQS_DP<4>")
	)
	(segment
		(start 332.758034 -290.019994)
		(end 332.291182 -290.285932)
		(width 0.12954)
		(layer "F.Cu")
		(net "M_F_CPU0_SB_DQS_DP<3>")
	)
	(segment
		(start 311.369964 -307.703728)
		(end 311.369964 -308.180232)
		(width 0.16002)
		(layer "In11.Cu")
		(net "M_F_CPU0_SB_DQS_DP<3>")
	)
	(segment
		(start 302.368966 -313.404504)
		(end 301.817024 -312.852562)
		(width 0.16002)
		(layer "In11.Cu")
		(net "M_F_CPU0_SB_DQS_DP<3>")
	)
	(segment
		(start 298.591732 -312.579004)
		(end 298.146978 -312.579004)
		(width 0.16002)
		(layer "In11.Cu")
		(net "M_F_CPU0_SB_DQS_DP<3>")
	)
	(segment
		(start 312.81116 -307.101748)
		(end 312.56478 -307.348128)
		(width 0.16002)
		(layer "In11.Cu")
		(net "M_F_CPU0_SB_DQS_DP<3>")
	)
	(segment
		(start 291.41674 -312.209942)
		(end 291.047678 -312.579004)
		(width 0.16002)
		(layer "In11.Cu")
		(net "M_F_CPU0_SB_DQS_DP<3>")
	)
	(segment
		(start 319.607184 -299.943012)
		(end 319.67551 -300.011338)
		(width 0.16002)
		(layer "In11.Cu")
		(net "M_F_CPU0_SB_DQS_DP<3>")
	)
	(segment
		(start 297.321478 -313.404504)
		(end 296.92219 -313.404504)
		(width 0.16002)
		(layer "In11.Cu")
		(net "M_F_CPU0_SB_DQS_DP<3>")
	)
	(segment
		(start 323.253354 -296.296842)
		(end 322.77685 -296.296842)
		(width 0.16002)
		(layer "In11.Cu")
		(net "M_F_CPU0_SB_DQS_DP<3>")
	)
	(segment
		(start 293.27348 -312.209942)
		(end 291.41674 -312.209942)
		(width 0.16002)
		(layer "In11.Cu")
		(net "M_F_CPU0_SB_DQS_DP<3>")
	)
	(segment
		(start 315.488574 -303.585118)
		(end 315.488574 -304.061622)
		(width 0.16002)
		(layer "In11.Cu")
		(net "M_F_CPU0_SB_DQS_DP<3>")
	)
	(segment
		(start 314.18403 -305.502818)
		(end 314.18403 -305.728878)
		(width 0.16002)
		(layer "In11.Cu")
		(net "M_F_CPU0_SB_DQS_DP<3>")
	)
	(segment
		(start 321.40398 -297.669712)
		(end 320.980054 -298.093638)
		(width 0.16002)
		(layer "In11.Cu")
		(net "M_F_CPU0_SB_DQS_DP<3>")
	)
	(segment
		(start 271.11579 -313.208924)
		(end 270.99895 -313.092084)
		(width 0.16002)
		(layer "In11.Cu")
		(net "M_F_CPU0_SB_DQS_DP<3>")
	)
	(segment
		(start 298.146978 -312.579004)
		(end 297.321478 -313.404504)
		(width 0.16002)
		(layer "In11.Cu")
		(net "M_F_CPU0_SB_DQS_DP<3>")
	)
	(segment
		(start 301.460154 -312.852562)
		(end 300.817534 -312.209942)
		(width 0.16002)
		(layer "In11.Cu")
		(net "M_F_CPU0_SB_DQS_DP<3>")
	)
	(segment
		(start 269.92199 -313.208924)
		(end 269.648178 -312.935112)
		(width 0.16002)
		(layer "In11.Cu")
		(net "M_F_CPU0_SB_DQS_DP<3>")
	)
	(segment
		(start 312.33872 -307.348128)
		(end 312.270394 -307.279802)
		(width 0.16002)
		(layer "In11.Cu")
		(net "M_F_CPU0_SB_DQS_DP<3>")
	)
	(segment
		(start 303.469548 -313.404504)
		(end 302.368966 -313.404504)
		(width 0.16002)
		(layer "In11.Cu")
		(net "M_F_CPU0_SB_DQS_DP<3>")
	)
	(segment
		(start 316.68339 -303.229518)
		(end 316.45733 -303.229518)
		(width 0.16002)
		(layer "In11.Cu")
		(net "M_F_CPU0_SB_DQS_DP<3>")
	)
	(segment
		(start 283.503624 -312.579004)
		(end 283.05887 -312.579004)
		(width 0.16002)
		(layer "In11.Cu")
		(net "M_F_CPU0_SB_DQS_DP<3>")
	)
	(segment
		(start 319.607184 -299.466508)
		(end 319.607184 -299.943012)
		(width 0.16002)
		(layer "In11.Cu")
		(net "M_F_CPU0_SB_DQS_DP<3>")
	)
	(segment
		(start 282.23337 -313.404504)
		(end 281.834082 -313.404504)
		(width 0.16002)
		(layer "In11.Cu")
		(net "M_F_CPU0_SB_DQS_DP<3>")
	)
	(segment
		(start 312.742834 -306.330858)
		(end 312.742834 -306.807362)
		(width 0.16002)
		(layer "In11.Cu")
		(net "M_F_CPU0_SB_DQS_DP<3>")
	)
	(segment
		(start 275.514816 -312.579004)
		(end 274.689316 -313.404504)
		(width 0.16002)
		(layer "In11.Cu")
		(net "M_F_CPU0_SB_DQS_DP<3>")
	)
	(segment
		(start 273.94535 -313.059826)
		(end 272.095468 -313.059826)
		(width 0.16002)
		(layer "In11.Cu")
		(net "M_F_CPU0_SB_DQS_DP<3>")
	)
	(segment
		(start 313.16676 -305.906932)
		(end 312.742834 -306.330858)
		(width 0.16002)
		(layer "In11.Cu")
		(net "M_F_CPU0_SB_DQS_DP<3>")
	)
	(segment
		(start 316.45733 -303.229518)
		(end 316.389004 -303.161192)
		(width 0.16002)
		(layer "In11.Cu")
		(net "M_F_CPU0_SB_DQS_DP<3>")
	)
	(segment
		(start 321.04838 -298.638468)
		(end 321.04838 -298.864528)
		(width 0.16002)
		(layer "In11.Cu")
		(net "M_F_CPU0_SB_DQS_DP<3>")
	)
	(segment
		(start 320.03111 -299.042582)
		(end 319.607184 -299.466508)
		(width 0.16002)
		(layer "In11.Cu")
		(net "M_F_CPU0_SB_DQS_DP<3>")
	)
	(segment
		(start 281.834082 -313.404504)
		(end 281.489404 -313.059826)
		(width 0.16002)
		(layer "In11.Cu")
		(net "M_F_CPU0_SB_DQS_DP<3>")
	)
	(segment
		(start 274.689316 -313.404504)
		(end 274.290028 -313.404504)
		(width 0.16002)
		(layer "In11.Cu")
		(net "M_F_CPU0_SB_DQS_DP<3>")
	)
	(segment
		(start 320.980054 -298.570142)
		(end 321.04838 -298.638468)
		(width 0.16002)
		(layer "In11.Cu")
		(net "M_F_CPU0_SB_DQS_DP<3>")
	)
	(segment
		(start 276.328632 -312.209942)
		(end 275.95957 -312.579004)
		(width 0.16002)
		(layer "In11.Cu")
		(net "M_F_CPU0_SB_DQS_DP<3>")
	)
	(segment
		(start 285.729426 -312.209942)
		(end 283.872686 -312.209942)
		(width 0.16002)
		(layer "In11.Cu")
		(net "M_F_CPU0_SB_DQS_DP<3>")
	)
	(segment
		(start 311.43829 -308.647338)
		(end 307.506624 -312.579004)
		(width 0.16002)
		(layer "In11.Cu")
		(net "M_F_CPU0_SB_DQS_DP<3>")
	)
	(segment
		(start 316.389004 -303.161192)
		(end 315.9125 -303.161192)
		(width 0.16002)
		(layer "In11.Cu")
		(net "M_F_CPU0_SB_DQS_DP<3>")
	)
	(segment
		(start 314.115704 -304.957988)
		(end 314.115704 -305.434492)
		(width 0.16002)
		(layer "In11.Cu")
		(net "M_F_CPU0_SB_DQS_DP<3>")
	)
	(segment
		(start 274.290028 -313.404504)
		(end 273.94535 -313.059826)
		(width 0.16002)
		(layer "In11.Cu")
		(net "M_F_CPU0_SB_DQS_DP<3>")
	)
	(segment
		(start 322.17487 -297.738038)
		(end 321.94881 -297.738038)
		(width 0.16002)
		(layer "In11.Cu")
		(net "M_F_CPU0_SB_DQS_DP<3>")
	)
	(segment
		(start 303.586388 -313.287664)
		(end 303.469548 -313.404504)
		(width 0.16002)
		(layer "In11.Cu")
		(net "M_F_CPU0_SB_DQS_DP<3>")
	)
	(segment
		(start 320.507614 -299.042582)
		(end 320.03111 -299.042582)
		(width 0.16002)
		(layer "In11.Cu")
		(net "M_F_CPU0_SB_DQS_DP<3>")
	)
	(segment
		(start 324.430644 -295.566084)
		(end 323.989192 -296.007536)
		(width 0.09525)
		(layer "In11.Cu")
		(net "M_F_CPU0_SB_DQS_DP<3>")
	)
	(segment
		(start 270.40205 -313.208924)
		(end 269.92199 -313.208924)
		(width 0.16002)
		(layer "In11.Cu")
		(net "M_F_CPU0_SB_DQS_DP<3>")
	)
	(segment
		(start 318.05626 -301.856648)
		(end 317.8302 -301.856648)
		(width 0.16002)
		(layer "In11.Cu")
		(net "M_F_CPU0_SB_DQS_DP<3>")
	)
	(segment
		(start 311.369964 -308.180232)
		(end 311.43829 -308.248558)
		(width 0.16002)
		(layer "In11.Cu")
		(net "M_F_CPU0_SB_DQS_DP<3>")
	)
	(segment
		(start 315.5569 -304.129948)
		(end 315.5569 -304.356008)
		(width 0.16002)
		(layer "In11.Cu")
		(net "M_F_CPU0_SB_DQS_DP<3>")
	)
	(segment
		(start 321.94881 -297.738038)
		(end 321.880484 -297.669712)
		(width 0.16002)
		(layer "In11.Cu")
		(net "M_F_CPU0_SB_DQS_DP<3>")
	)
	(segment
		(start 286.57931 -313.059826)
		(end 285.729426 -312.209942)
		(width 0.16002)
		(layer "In11.Cu")
		(net "M_F_CPU0_SB_DQS_DP<3>")
	)
	(segment
		(start 289.033458 -313.059826)
		(end 286.57931 -313.059826)
		(width 0.16002)
		(layer "In11.Cu")
		(net "M_F_CPU0_SB_DQS_DP<3>")
	)
	(segment
		(start 311.79389 -307.279802)
		(end 311.369964 -307.703728)
		(width 0.16002)
		(layer "In11.Cu")
		(net "M_F_CPU0_SB_DQS_DP<3>")
	)
	(segment
		(start 332.445106 -290.551362)
		(end 332.421738 -290.63823)
		(width 0.09525)
		(layer "In11.Cu")
		(net "M_F_CPU0_SB_DQS_DP<3>")
	)
	(segment
		(start 305.690778 -312.579004)
		(end 304.865278 -313.404504)
		(width 0.16002)
		(layer "In11.Cu")
		(net "M_F_CPU0_SB_DQS_DP<3>")
	)
	(segment
		(start 315.488574 -304.061622)
		(end 315.5569 -304.129948)
		(width 0.16002)
		(layer "In11.Cu")
		(net "M_F_CPU0_SB_DQS_DP<3>")
	)
	(segment
		(start 314.53963 -304.534062)
		(end 314.115704 -304.957988)
		(width 0.16002)
		(layer "In11.Cu")
		(net "M_F_CPU0_SB_DQS_DP<3>")
	)
	(segment
		(start 329.290934 -290.615878)
		(end 329.282552 -290.611052)
		(width 0.09525)
		(layer "In11.Cu")
		(net "M_F_CPU0_SB_DQS_DP<3>")
	)
	(segment
		(start 301.817024 -312.852562)
		(end 301.460154 -312.852562)
		(width 0.16002)
		(layer "In11.Cu")
		(net "M_F_CPU0_SB_DQS_DP<3>")
	)
	(segment
		(start 322.352924 -296.720768)
		(end 322.352924 -297.197272)
		(width 0.16002)
		(layer "In11.Cu")
		(net "M_F_CPU0_SB_DQS_DP<3>")
	)
	(segment
		(start 316.861444 -302.212248)
		(end 316.861444 -302.688752)
		(width 0.16002)
		(layer "In11.Cu")
		(net "M_F_CPU0_SB_DQS_DP<3>")
	)
	(segment
		(start 312.742834 -306.807362)
		(end 312.81116 -306.875688)
		(width 0.16002)
		(layer "In11.Cu")
		(net "M_F_CPU0_SB_DQS_DP<3>")
	)
	(segment
		(start 316.92977 -302.757078)
		(end 316.92977 -302.983138)
		(width 0.16002)
		(layer "In11.Cu")
		(net "M_F_CPU0_SB_DQS_DP<3>")
	)
	(segment
		(start 323.989192 -296.007536)
		(end 323.905372 -296.007536)
		(width 0.09525)
		(layer "In11.Cu")
		(net "M_F_CPU0_SB_DQS_DP<3>")
	)
	(segment
		(start 332.291182 -290.285932)
		(end 332.445106 -290.551362)
		(width 0.09525)
		(layer "In11.Cu")
		(net "M_F_CPU0_SB_DQS_DP<3>")
	)
	(segment
		(start 304.865278 -313.404504)
		(end 304.183288 -313.404504)
		(width 0.16002)
		(layer "In11.Cu")
		(net "M_F_CPU0_SB_DQS_DP<3>")
	)
	(segment
		(start 311.43829 -308.248558)
		(end 311.43829 -308.647338)
		(width 0.16002)
		(layer "In11.Cu")
		(net "M_F_CPU0_SB_DQS_DP<3>")
	)
	(segment
		(start 283.05887 -312.579004)
		(end 282.23337 -313.404504)
		(width 0.16002)
		(layer "In11.Cu")
		(net "M_F_CPU0_SB_DQS_DP<3>")
	)
	(segment
		(start 315.9125 -303.161192)
		(end 315.488574 -303.585118)
		(width 0.16002)
		(layer "In11.Cu")
		(net "M_F_CPU0_SB_DQS_DP<3>")
	)
	(segment
		(start 304.183288 -313.404504)
		(end 304.066448 -313.287664)
		(width 0.16002)
		(layer "In11.Cu")
		(net "M_F_CPU0_SB_DQS_DP<3>")
	)
	(segment
		(start 275.95957 -312.579004)
		(end 275.514816 -312.579004)
		(width 0.16002)
		(layer "In11.Cu")
		(net "M_F_CPU0_SB_DQS_DP<3>")
	)
	(segment
		(start 281.489404 -313.059826)
		(end 279.035256 -313.059826)
		(width 0.16002)
		(layer "In11.Cu")
		(net "M_F_CPU0_SB_DQS_DP<3>")
	)
	(segment
		(start 319.67551 -300.237398)
		(end 319.42913 -300.483778)
		(width 0.16002)
		(layer "In11.Cu")
		(net "M_F_CPU0_SB_DQS_DP<3>")
	)
	(segment
		(start 325.840598 -292.021768)
		(end 325.840598 -292.502336)
		(width 0.09525)
		(layer "In11.Cu")
		(net "M_F_CPU0_SB_DQS_DP<3>")
	)
	(segment
		(start 304.066448 -313.287664)
		(end 303.586388 -313.287664)
		(width 0.16002)
		(layer "In11.Cu")
		(net "M_F_CPU0_SB_DQS_DP<3>")
	)
	(segment
		(start 315.31052 -304.602388)
		(end 315.08446 -304.602388)
		(width 0.16002)
		(layer "In11.Cu")
		(net "M_F_CPU0_SB_DQS_DP<3>")
	)
	(segment
		(start 315.5569 -304.356008)
		(end 315.31052 -304.602388)
		(width 0.16002)
		(layer "In11.Cu")
		(net "M_F_CPU0_SB_DQS_DP<3>")
	)
	(segment
		(start 270.51889 -313.092084)
		(end 270.40205 -313.208924)
		(width 0.16002)
		(layer "In11.Cu")
		(net "M_F_CPU0_SB_DQS_DP<3>")
	)
	(segment
		(start 324.430644 -293.91229)
		(end 324.430644 -295.566084)
		(width 0.09525)
		(layer "In11.Cu")
		(net "M_F_CPU0_SB_DQS_DP<3>")
	)
	(segment
		(start 321.04838 -298.864528)
		(end 320.802 -299.110908)
		(width 0.16002)
		(layer "In11.Cu")
		(net "M_F_CPU0_SB_DQS_DP<3>")
	)
	(segment
		(start 318.234314 -300.839378)
		(end 318.234314 -301.315882)
		(width 0.16002)
		(layer "In11.Cu")
		(net "M_F_CPU0_SB_DQS_DP<3>")
	)
	(segment
		(start 296.92219 -313.404504)
		(end 296.577512 -313.059826)
		(width 0.16002)
		(layer "In11.Cu")
		(net "M_F_CPU0_SB_DQS_DP<3>")
	)
	(segment
		(start 272.095468 -313.059826)
		(end 271.94637 -313.208924)
		(width 0.16002)
		(layer "In11.Cu")
		(net "M_F_CPU0_SB_DQS_DP<3>")
	)
	(segment
		(start 323.54774 -296.365168)
		(end 323.32168 -296.365168)
		(width 0.16002)
		(layer "In11.Cu")
		(net "M_F_CPU0_SB_DQS_DP<3>")
	)
	(segment
		(start 312.81116 -306.875688)
		(end 312.81116 -307.101748)
		(width 0.16002)
		(layer "In11.Cu")
		(net "M_F_CPU0_SB_DQS_DP<3>")
	)
	(segment
		(start 322.77685 -296.296842)
		(end 322.352924 -296.720768)
		(width 0.16002)
		(layer "In11.Cu")
		(net "M_F_CPU0_SB_DQS_DP<3>")
	)
	(segment
		(start 328.719688 -290.611052)
		(end 328.711306 -290.615878)
		(width 0.09525)
		(layer "In11.Cu")
		(net "M_F_CPU0_SB_DQS_DP<3>")
	)
	(segment
		(start 291.047678 -312.579004)
		(end 290.602924 -312.579004)
		(width 0.16002)
		(layer "In11.Cu")
		(net "M_F_CPU0_SB_DQS_DP<3>")
	)
	(segment
		(start 315.016134 -304.534062)
		(end 314.53963 -304.534062)
		(width 0.16002)
		(layer "In11.Cu")
		(net "M_F_CPU0_SB_DQS_DP<3>")
	)
	(segment
		(start 278.185372 -312.209942)
		(end 276.328632 -312.209942)
		(width 0.16002)
		(layer "In11.Cu")
		(net "M_F_CPU0_SB_DQS_DP<3>")
	)
	(segment
		(start 322.352924 -297.197272)
		(end 322.42125 -297.265598)
		(width 0.16002)
		(layer "In11.Cu")
		(net "M_F_CPU0_SB_DQS_DP<3>")
	)
	(segment
		(start 271.94637 -313.208924)
		(end 271.11579 -313.208924)
		(width 0.16002)
		(layer "In11.Cu")
		(net "M_F_CPU0_SB_DQS_DP<3>")
	)
	(segment
		(start 317.761874 -301.788322)
		(end 317.28537 -301.788322)
		(width 0.16002)
		(layer "In11.Cu")
		(net "M_F_CPU0_SB_DQS_DP<3>")
	)
	(segment
		(start 313.643264 -305.906932)
		(end 313.16676 -305.906932)
		(width 0.16002)
		(layer "In11.Cu")
		(net "M_F_CPU0_SB_DQS_DP<3>")
	)
	(segment
		(start 314.115704 -305.434492)
		(end 314.18403 -305.502818)
		(width 0.16002)
		(layer "In11.Cu")
		(net "M_F_CPU0_SB_DQS_DP<3>")
	)
	(segment
		(start 317.8302 -301.856648)
		(end 317.761874 -301.788322)
		(width 0.16002)
		(layer "In11.Cu")
		(net "M_F_CPU0_SB_DQS_DP<3>")
	)
	(segment
		(start 316.92977 -302.983138)
		(end 316.68339 -303.229518)
		(width 0.16002)
		(layer "In11.Cu")
		(net "M_F_CPU0_SB_DQS_DP<3>")
	)
	(segment
		(start 313.71159 -305.975258)
		(end 313.643264 -305.906932)
		(width 0.16002)
		(layer "In11.Cu")
		(net "M_F_CPU0_SB_DQS_DP<3>")
	)
	(segment
		(start 318.30264 -301.610268)
		(end 318.05626 -301.856648)
		(width 0.16002)
		(layer "In11.Cu")
		(net "M_F_CPU0_SB_DQS_DP<3>")
	)
	(segment
		(start 296.577512 -313.059826)
		(end 294.123364 -313.059826)
		(width 0.16002)
		(layer "In11.Cu")
		(net "M_F_CPU0_SB_DQS_DP<3>")
	)
	(segment
		(start 307.506624 -312.579004)
		(end 305.690778 -312.579004)
		(width 0.16002)
		(layer "In11.Cu")
		(net "M_F_CPU0_SB_DQS_DP<3>")
	)
	(segment
		(start 319.67551 -300.011338)
		(end 319.67551 -300.237398)
		(width 0.16002)
		(layer "In11.Cu")
		(net "M_F_CPU0_SB_DQS_DP<3>")
	)
	(segment
		(start 283.872686 -312.209942)
		(end 283.503624 -312.579004)
		(width 0.16002)
		(layer "In11.Cu")
		(net "M_F_CPU0_SB_DQS_DP<3>")
	)
	(segment
		(start 325.840598 -292.502336)
		(end 324.430644 -293.91229)
		(width 0.09525)
		(layer "In11.Cu")
		(net "M_F_CPU0_SB_DQS_DP<3>")
	)
	(segment
		(start 322.42125 -297.265598)
		(end 322.42125 -297.491658)
		(width 0.16002)
		(layer "In11.Cu")
		(net "M_F_CPU0_SB_DQS_DP<3>")
	)
	(segment
		(start 319.42913 -300.483778)
		(end 319.20307 -300.483778)
		(width 0.16002)
		(layer "In11.Cu")
		(net "M_F_CPU0_SB_DQS_DP<3>")
	)
	(segment
		(start 294.123364 -313.059826)
		(end 293.27348 -312.209942)
		(width 0.16002)
		(layer "In11.Cu")
		(net "M_F_CPU0_SB_DQS_DP<3>")
	)
	(segment
		(start 312.56478 -307.348128)
		(end 312.33872 -307.348128)
		(width 0.16002)
		(layer "In11.Cu")
		(net "M_F_CPU0_SB_DQS_DP<3>")
	)
	(segment
		(start 318.30264 -301.384208)
		(end 318.30264 -301.610268)
		(width 0.16002)
		(layer "In11.Cu")
		(net "M_F_CPU0_SB_DQS_DP<3>")
	)
	(segment
		(start 314.18403 -305.728878)
		(end 313.93765 -305.975258)
		(width 0.16002)
		(layer "In11.Cu")
		(net "M_F_CPU0_SB_DQS_DP<3>")
	)
	(segment
		(start 279.035256 -313.059826)
		(end 278.185372 -312.209942)
		(width 0.16002)
		(layer "In11.Cu")
		(net "M_F_CPU0_SB_DQS_DP<3>")
	)
	(segment
		(start 323.32168 -296.365168)
		(end 323.253354 -296.296842)
		(width 0.16002)
		(layer "In11.Cu")
		(net "M_F_CPU0_SB_DQS_DP<3>")
	)
	(segment
		(start 331.539596 -290.611052)
		(end 331.531214 -290.615878)
		(width 0.09525)
		(layer "In11.Cu")
		(net "M_F_CPU0_SB_DQS_DP<3>")
	)
	(segment
		(start 290.602924 -312.579004)
		(end 289.777424 -313.404504)
		(width 0.16002)
		(layer "In11.Cu")
		(net "M_F_CPU0_SB_DQS_DP<3>")
	)
	(segment
		(start 315.08446 -304.602388)
		(end 315.016134 -304.534062)
		(width 0.16002)
		(layer "In11.Cu")
		(net "M_F_CPU0_SB_DQS_DP<3>")
	)
	(segment
		(start 300.817534 -312.209942)
		(end 298.960794 -312.209942)
		(width 0.16002)
		(layer "In11.Cu")
		(net "M_F_CPU0_SB_DQS_DP<3>")
	)
	(segment
		(start 318.65824 -300.415452)
		(end 318.234314 -300.839378)
		(width 0.16002)
		(layer "In11.Cu")
		(net "M_F_CPU0_SB_DQS_DP<3>")
	)
	(segment
		(start 322.42125 -297.491658)
		(end 322.17487 -297.738038)
		(width 0.16002)
		(layer "In11.Cu")
		(net "M_F_CPU0_SB_DQS_DP<3>")
	)
	(segment
		(start 326.85863 -290.860734)
		(end 325.94169 -291.777674)
		(width 0.09525)
		(layer "In11.Cu")
		(net "M_F_CPU0_SB_DQS_DP<3>")
	)
	(segment
		(start 270.99895 -313.092084)
		(end 270.51889 -313.092084)
		(width 0.16002)
		(layer "In11.Cu")
		(net "M_F_CPU0_SB_DQS_DP<3>")
	)
	(segment
		(start 323.905372 -296.007536)
		(end 323.888608 -296.0243)
		(width 0.09525)
		(layer "In11.Cu")
		(net "M_F_CPU0_SB_DQS_DP<3>")
	)
	(segment
		(start 317.28537 -301.788322)
		(end 316.861444 -302.212248)
		(width 0.16002)
		(layer "In11.Cu")
		(net "M_F_CPU0_SB_DQS_DP<3>")
	)
	(segment
		(start 318.234314 -301.315882)
		(end 318.30264 -301.384208)
		(width 0.16002)
		(layer "In11.Cu")
		(net "M_F_CPU0_SB_DQS_DP<3>")
	)
	(segment
		(start 320.57594 -299.110908)
		(end 320.507614 -299.042582)
		(width 0.16002)
		(layer "In11.Cu")
		(net "M_F_CPU0_SB_DQS_DP<3>")
	)
	(segment
		(start 319.20307 -300.483778)
		(end 319.134744 -300.415452)
		(width 0.16002)
		(layer "In11.Cu")
		(net "M_F_CPU0_SB_DQS_DP<3>")
	)
	(segment
		(start 321.880484 -297.669712)
		(end 321.40398 -297.669712)
		(width 0.16002)
		(layer "In11.Cu")
		(net "M_F_CPU0_SB_DQS_DP<3>")
	)
	(segment
		(start 320.802 -299.110908)
		(end 320.57594 -299.110908)
		(width 0.16002)
		(layer "In11.Cu")
		(net "M_F_CPU0_SB_DQS_DP<3>")
	)
	(segment
		(start 289.378136 -313.404504)
		(end 289.033458 -313.059826)
		(width 0.16002)
		(layer "In11.Cu")
		(net "M_F_CPU0_SB_DQS_DP<3>")
	)
	(segment
		(start 316.861444 -302.688752)
		(end 316.92977 -302.757078)
		(width 0.16002)
		(layer "In11.Cu")
		(net "M_F_CPU0_SB_DQS_DP<3>")
	)
	(segment
		(start 313.93765 -305.975258)
		(end 313.71159 -305.975258)
		(width 0.16002)
		(layer "In11.Cu")
		(net "M_F_CPU0_SB_DQS_DP<3>")
	)
	(segment
		(start 319.134744 -300.415452)
		(end 318.65824 -300.415452)
		(width 0.16002)
		(layer "In11.Cu")
		(net "M_F_CPU0_SB_DQS_DP<3>")
	)
	(segment
		(start 289.777424 -313.404504)
		(end 289.378136 -313.404504)
		(width 0.16002)
		(layer "In11.Cu")
		(net "M_F_CPU0_SB_DQS_DP<3>")
	)
	(segment
		(start 320.980054 -298.093638)
		(end 320.980054 -298.570142)
		(width 0.16002)
		(layer "In11.Cu")
		(net "M_F_CPU0_SB_DQS_DP<3>")
	)
	(segment
		(start 312.270394 -307.279802)
		(end 311.79389 -307.279802)
		(width 0.16002)
		(layer "In11.Cu")
		(net "M_F_CPU0_SB_DQS_DP<3>")
	)
	(segment
		(start 298.960794 -312.209942)
		(end 298.591732 -312.579004)
		(width 0.16002)
		(layer "In11.Cu")
		(net "M_F_CPU0_SB_DQS_DP<3>")
	)
	(segment
		(start 323.888608 -296.0243)
		(end 323.54774 -296.365168)
		(width 0.16002)
		(layer "In11.Cu")
		(net "M_F_CPU0_SB_DQS_DP<3>")
	)
	(arc
		(start 332.10246 -290.611052)
		(mid 331.821028 -290.535297)
		(end 331.539596 -290.611052)
		(width 0.09525)
		(layer "In11.Cu")
		(net "M_F_CPU0_SB_DQS_DP<3>")
	)
	(arc
		(start 329.282552 -290.611052)
		(mid 329.00112 -290.535297)
		(end 328.719688 -290.611052)
		(width 0.09525)
		(layer "In11.Cu")
		(net "M_F_CPU0_SB_DQS_DP<3>")
	)
	(arc
		(start 328.711306 -290.615878)
		(mid 328.526274 -290.661792)
		(end 328.342498 -290.611052)
		(width 0.09525)
		(layer "In11.Cu")
		(net "M_F_CPU0_SB_DQS_DP<3>")
	)
	(arc
		(start 328.342498 -290.611052)
		(mid 328.078144 -290.535403)
		(end 327.809606 -290.594542)
		(width 0.09525)
		(layer "In11.Cu")
		(net "M_F_CPU0_SB_DQS_DP<3>")
	)
	(arc
		(start 329.659742 -290.611052)
		(mid 329.475967 -290.661824)
		(end 329.290934 -290.615878)
		(width 0.09525)
		(layer "In11.Cu")
		(net "M_F_CPU0_SB_DQS_DP<3>")
	)
	(arc
		(start 332.421738 -290.63823)
		(mid 332.259056 -290.660362)
		(end 332.10246 -290.611052)
		(width 0.09525)
		(layer "In11.Cu")
		(net "M_F_CPU0_SB_DQS_DP<3>")
	)
	(arc
		(start 330.599542 -290.611052)
		(mid 330.411074 -290.661729)
		(end 330.222606 -290.611052)
		(width 0.09525)
		(layer "In11.Cu")
		(net "M_F_CPU0_SB_DQS_DP<3>")
	)
	(arc
		(start 327.809606 -290.594542)
		(mid 327.650905 -290.64639)
		(end 327.483978 -290.649152)
		(width 0.09525)
		(layer "In11.Cu")
		(net "M_F_CPU0_SB_DQS_DP<3>")
	)
	(arc
		(start 331.531214 -290.615878)
		(mid 331.346182 -290.661792)
		(end 331.162406 -290.611052)
		(width 0.09525)
		(layer "In11.Cu")
		(net "M_F_CPU0_SB_DQS_DP<3>")
	)
	(arc
		(start 331.162406 -290.611052)
		(mid 330.880974 -290.535297)
		(end 330.599542 -290.611052)
		(width 0.09525)
		(layer "In11.Cu")
		(net "M_F_CPU0_SB_DQS_DP<3>")
	)
	(arc
		(start 330.222606 -290.611052)
		(mid 329.941174 -290.535297)
		(end 329.659742 -290.611052)
		(width 0.09525)
		(layer "In11.Cu")
		(net "M_F_CPU0_SB_DQS_DP<3>")
	)
	(arc
		(start 327.483978 -290.649152)
		(mid 327.146582 -290.681846)
		(end 326.85863 -290.860734)
		(width 0.09525)
		(layer "In11.Cu")
		(net "M_F_CPU0_SB_DQS_DP<3>")
	)
	(arc
		(start 325.94169 -291.777674)
		(mid 325.866913 -291.88968)
		(end 325.840598 -292.021768)
		(width 0.09525)
		(layer "In11.Cu")
		(net "M_F_CPU0_SB_DQS_DP<3>")
	)
	(segment
		(start 332.758034 -285.160212)
		(end 332.291182 -285.42615)
		(width 0.12954)
		(layer "F.Cu")
		(net "M_F_CPU0_SB_DQS_DP<2>")
	)
	(segment
		(start 308.703472 -301.662846)
		(end 308.227222 -301.662846)
		(width 0.16002)
		(layer "In11.Cu")
		(net "M_F_CPU0_SB_DQS_DP<2>")
	)
	(segment
		(start 312.06821 -297.492674)
		(end 311.644284 -297.9166)
		(width 0.16002)
		(layer "In11.Cu")
		(net "M_F_CPU0_SB_DQS_DP<2>")
	)
	(segment
		(start 271.150588 -303.74209)
		(end 270.670528 -303.74209)
		(width 0.16002)
		(layer "In11.Cu")
		(net "M_F_CPU0_SB_DQS_DP<2>")
	)
	(segment
		(start 324.645528 -286.521398)
		(end 324.586346 -286.462216)
		(width 0.09525)
		(layer "In11.Cu")
		(net "M_F_CPU0_SB_DQS_DP<2>")
	)
	(segment
		(start 317.55969 -292.001194)
		(end 317.135764 -292.42512)
		(width 0.16002)
		(layer "In11.Cu")
		(net "M_F_CPU0_SB_DQS_DP<2>")
	)
	(segment
		(start 275.95957 -303.22901)
		(end 275.514816 -303.22901)
		(width 0.16002)
		(layer "In11.Cu")
		(net "M_F_CPU0_SB_DQS_DP<2>")
	)
	(segment
		(start 315.814202 -294.326056)
		(end 315.814202 -294.552116)
		(width 0.16002)
		(layer "In11.Cu")
		(net "M_F_CPU0_SB_DQS_DP<2>")
	)
	(segment
		(start 302.368966 -304.05451)
		(end 301.817024 -303.502568)
		(width 0.16002)
		(layer "In11.Cu")
		(net "M_F_CPU0_SB_DQS_DP<2>")
	)
	(segment
		(start 291.41674 -302.859948)
		(end 291.047678 -303.22901)
		(width 0.16002)
		(layer "In11.Cu")
		(net "M_F_CPU0_SB_DQS_DP<2>")
	)
	(segment
		(start 291.047678 -303.22901)
		(end 290.602924 -303.22901)
		(width 0.16002)
		(layer "In11.Cu")
		(net "M_F_CPU0_SB_DQS_DP<2>")
	)
	(segment
		(start 313.017154 -297.020234)
		(end 313.068462 -297.071796)
		(width 0.16002)
		(layer "In11.Cu")
		(net "M_F_CPU0_SB_DQS_DP<2>")
	)
	(segment
		(start 301.817024 -303.502568)
		(end 301.460154 -303.502568)
		(width 0.16002)
		(layer "In11.Cu")
		(net "M_F_CPU0_SB_DQS_DP<2>")
	)
	(segment
		(start 323.901308 -286.462216)
		(end 321.10807 -289.255454)
		(width 0.16002)
		(layer "In11.Cu")
		(net "M_F_CPU0_SB_DQS_DP<2>")
	)
	(segment
		(start 311.449212 -298.917106)
		(end 311.223152 -298.917106)
		(width 0.16002)
		(layer "In11.Cu")
		(net "M_F_CPU0_SB_DQS_DP<2>")
	)
	(segment
		(start 310.271414 -299.28947)
		(end 310.271414 -299.765974)
		(width 0.16002)
		(layer "In11.Cu")
		(net "M_F_CPU0_SB_DQS_DP<2>")
	)
	(segment
		(start 318.508634 -291.05225)
		(end 318.508634 -291.528754)
		(width 0.16002)
		(layer "In11.Cu")
		(net "M_F_CPU0_SB_DQS_DP<2>")
	)
	(segment
		(start 317.135764 -292.901624)
		(end 317.187072 -292.953186)
		(width 0.16002)
		(layer "In11.Cu")
		(net "M_F_CPU0_SB_DQS_DP<2>")
	)
	(segment
		(start 327.403714 -285.75127)
		(end 327.38568 -285.740856)
		(width 0.09525)
		(layer "In11.Cu")
		(net "M_F_CPU0_SB_DQS_DP<2>")
	)
	(segment
		(start 327.79843 -285.740856)
		(end 327.780396 -285.75127)
		(width 0.09525)
		(layer "In11.Cu")
		(net "M_F_CPU0_SB_DQS_DP<2>")
	)
	(segment
		(start 324.562724 -286.462216)
		(end 323.901308 -286.462216)
		(width 0.16002)
		(layer "In11.Cu")
		(net "M_F_CPU0_SB_DQS_DP<2>")
	)
	(segment
		(start 314.390024 -295.647364)
		(end 314.441332 -295.698926)
		(width 0.16002)
		(layer "In11.Cu")
		(net "M_F_CPU0_SB_DQS_DP<2>")
	)
	(segment
		(start 318.313562 -292.052756)
		(end 318.087502 -292.052756)
		(width 0.16002)
		(layer "In11.Cu")
		(net "M_F_CPU0_SB_DQS_DP<2>")
	)
	(segment
		(start 329.290934 -285.756096)
		(end 329.282552 -285.75127)
		(width 0.09525)
		(layer "In11.Cu")
		(net "M_F_CPU0_SB_DQS_DP<2>")
	)
	(segment
		(start 309.850282 -300.289976)
		(end 309.79872 -300.238414)
		(width 0.16002)
		(layer "In11.Cu")
		(net "M_F_CPU0_SB_DQS_DP<2>")
	)
	(segment
		(start 294.123364 -303.709832)
		(end 293.27348 -302.859948)
		(width 0.16002)
		(layer "In11.Cu")
		(net "M_F_CPU0_SB_DQS_DP<2>")
	)
	(segment
		(start 319.686432 -290.679886)
		(end 319.460372 -290.679886)
		(width 0.16002)
		(layer "In11.Cu")
		(net "M_F_CPU0_SB_DQS_DP<2>")
	)
	(segment
		(start 272.095468 -303.709832)
		(end 271.94637 -303.85893)
		(width 0.16002)
		(layer "In11.Cu")
		(net "M_F_CPU0_SB_DQS_DP<2>")
	)
	(segment
		(start 318.559942 -291.806376)
		(end 318.313562 -292.052756)
		(width 0.16002)
		(layer "In11.Cu")
		(net "M_F_CPU0_SB_DQS_DP<2>")
	)
	(segment
		(start 321.10807 -289.255454)
		(end 320.30543 -289.255454)
		(width 0.16002)
		(layer "In11.Cu")
		(net "M_F_CPU0_SB_DQS_DP<2>")
	)
	(segment
		(start 270.670528 -303.74209)
		(end 270.553688 -303.85893)
		(width 0.16002)
		(layer "In11.Cu")
		(net "M_F_CPU0_SB_DQS_DP<2>")
	)
	(segment
		(start 310.322722 -299.817536)
		(end 310.322722 -300.043596)
		(width 0.16002)
		(layer "In11.Cu")
		(net "M_F_CPU0_SB_DQS_DP<2>")
	)
	(segment
		(start 311.17159 -298.865544)
		(end 310.69534 -298.865544)
		(width 0.16002)
		(layer "In11.Cu")
		(net "M_F_CPU0_SB_DQS_DP<2>")
	)
	(segment
		(start 317.187072 -292.953186)
		(end 317.187072 -293.179246)
		(width 0.16002)
		(layer "In11.Cu")
		(net "M_F_CPU0_SB_DQS_DP<2>")
	)
	(segment
		(start 315.341762 -294.798496)
		(end 315.2902 -294.746934)
		(width 0.16002)
		(layer "In11.Cu")
		(net "M_F_CPU0_SB_DQS_DP<2>")
	)
	(segment
		(start 311.644284 -297.9166)
		(end 311.644284 -298.393104)
		(width 0.16002)
		(layer "In11.Cu")
		(net "M_F_CPU0_SB_DQS_DP<2>")
	)
	(segment
		(start 328.719688 -285.75127)
		(end 328.711306 -285.756096)
		(width 0.09525)
		(layer "In11.Cu")
		(net "M_F_CPU0_SB_DQS_DP<2>")
	)
	(segment
		(start 310.271414 -299.765974)
		(end 310.322722 -299.817536)
		(width 0.16002)
		(layer "In11.Cu")
		(net "M_F_CPU0_SB_DQS_DP<2>")
	)
	(segment
		(start 313.44108 -296.119804)
		(end 313.017154 -296.54373)
		(width 0.16002)
		(layer "In11.Cu")
		(net "M_F_CPU0_SB_DQS_DP<2>")
	)
	(segment
		(start 293.27348 -302.859948)
		(end 291.41674 -302.859948)
		(width 0.16002)
		(layer "In11.Cu")
		(net "M_F_CPU0_SB_DQS_DP<2>")
	)
	(segment
		(start 311.223152 -298.917106)
		(end 311.17159 -298.865544)
		(width 0.16002)
		(layer "In11.Cu")
		(net "M_F_CPU0_SB_DQS_DP<2>")
	)
	(segment
		(start 298.960794 -302.859948)
		(end 298.591732 -303.22901)
		(width 0.16002)
		(layer "In11.Cu")
		(net "M_F_CPU0_SB_DQS_DP<2>")
	)
	(segment
		(start 320.30543 -289.255454)
		(end 319.881504 -289.67938)
		(width 0.16002)
		(layer "In11.Cu")
		(net "M_F_CPU0_SB_DQS_DP<2>")
	)
	(segment
		(start 314.194952 -296.171366)
		(end 313.968892 -296.171366)
		(width 0.16002)
		(layer "In11.Cu")
		(net "M_F_CPU0_SB_DQS_DP<2>")
	)
	(segment
		(start 327.780396 -285.75127)
		(end 327.772014 -285.756096)
		(width 0.09525)
		(layer "In11.Cu")
		(net "M_F_CPU0_SB_DQS_DP<2>")
	)
	(segment
		(start 325.144892 -286.521398)
		(end 324.645528 -286.521398)
		(width 0.09525)
		(layer "In11.Cu")
		(net "M_F_CPU0_SB_DQS_DP<2>")
	)
	(segment
		(start 316.940692 -293.425626)
		(end 316.714632 -293.425626)
		(width 0.16002)
		(layer "In11.Cu")
		(net "M_F_CPU0_SB_DQS_DP<2>")
	)
	(segment
		(start 276.328632 -302.859948)
		(end 275.95957 -303.22901)
		(width 0.16002)
		(layer "In11.Cu")
		(net "M_F_CPU0_SB_DQS_DP<2>")
	)
	(segment
		(start 317.135764 -292.42512)
		(end 317.135764 -292.901624)
		(width 0.16002)
		(layer "In11.Cu")
		(net "M_F_CPU0_SB_DQS_DP<2>")
	)
	(segment
		(start 332.291182 -285.42615)
		(end 332.445106 -285.69158)
		(width 0.09525)
		(layer "In11.Cu")
		(net "M_F_CPU0_SB_DQS_DP<2>")
	)
	(segment
		(start 319.932812 -290.207446)
		(end 319.932812 -290.433506)
		(width 0.16002)
		(layer "In11.Cu")
		(net "M_F_CPU0_SB_DQS_DP<2>")
	)
	(segment
		(start 318.559942 -291.580316)
		(end 318.559942 -291.806376)
		(width 0.16002)
		(layer "In11.Cu")
		(net "M_F_CPU0_SB_DQS_DP<2>")
	)
	(segment
		(start 269.92199 -303.85893)
		(end 269.648178 -303.585118)
		(width 0.16002)
		(layer "In11.Cu")
		(net "M_F_CPU0_SB_DQS_DP<2>")
	)
	(segment
		(start 274.290028 -304.05451)
		(end 273.94535 -303.709832)
		(width 0.16002)
		(layer "In11.Cu")
		(net "M_F_CPU0_SB_DQS_DP<2>")
	)
	(segment
		(start 289.777424 -304.05451)
		(end 289.378136 -304.05451)
		(width 0.16002)
		(layer "In11.Cu")
		(net "M_F_CPU0_SB_DQS_DP<2>")
	)
	(segment
		(start 325.863204 -285.803086)
		(end 325.144892 -286.521398)
		(width 0.09525)
		(layer "In11.Cu")
		(net "M_F_CPU0_SB_DQS_DP<2>")
	)
	(segment
		(start 296.577512 -303.709832)
		(end 294.123364 -303.709832)
		(width 0.16002)
		(layer "In11.Cu")
		(net "M_F_CPU0_SB_DQS_DP<2>")
	)
	(segment
		(start 313.068462 -297.071796)
		(end 313.068462 -297.297856)
		(width 0.16002)
		(layer "In11.Cu")
		(net "M_F_CPU0_SB_DQS_DP<2>")
	)
	(segment
		(start 312.822082 -297.544236)
		(end 312.596022 -297.544236)
		(width 0.16002)
		(layer "In11.Cu")
		(net "M_F_CPU0_SB_DQS_DP<2>")
	)
	(segment
		(start 326.650858 -285.803086)
		(end 325.863204 -285.803086)
		(width 0.09525)
		(layer "In11.Cu")
		(net "M_F_CPU0_SB_DQS_DP<2>")
	)
	(segment
		(start 316.66307 -293.374064)
		(end 316.18682 -293.374064)
		(width 0.16002)
		(layer "In11.Cu")
		(net "M_F_CPU0_SB_DQS_DP<2>")
	)
	(segment
		(start 308.227222 -301.662846)
		(end 307.576982 -302.313086)
		(width 0.16002)
		(layer "In11.Cu")
		(net "M_F_CPU0_SB_DQS_DP<2>")
	)
	(segment
		(start 307.16601 -303.200308)
		(end 307.096922 -303.22901)
		(width 0.16002)
		(layer "In11.Cu")
		(net "M_F_CPU0_SB_DQS_DP<2>")
	)
	(segment
		(start 281.489404 -303.709832)
		(end 279.035256 -303.709832)
		(width 0.16002)
		(layer "In11.Cu")
		(net "M_F_CPU0_SB_DQS_DP<2>")
	)
	(segment
		(start 289.378136 -304.05451)
		(end 289.033458 -303.709832)
		(width 0.16002)
		(layer "In11.Cu")
		(net "M_F_CPU0_SB_DQS_DP<2>")
	)
	(segment
		(start 317.187072 -293.179246)
		(end 316.940692 -293.425626)
		(width 0.16002)
		(layer "In11.Cu")
		(net "M_F_CPU0_SB_DQS_DP<2>")
	)
	(segment
		(start 318.087502 -292.052756)
		(end 318.03594 -292.001194)
		(width 0.16002)
		(layer "In11.Cu")
		(net "M_F_CPU0_SB_DQS_DP<2>")
	)
	(segment
		(start 313.017154 -296.54373)
		(end 313.017154 -297.020234)
		(width 0.16002)
		(layer "In11.Cu")
		(net "M_F_CPU0_SB_DQS_DP<2>")
	)
	(segment
		(start 318.93256 -290.628324)
		(end 318.508634 -291.05225)
		(width 0.16002)
		(layer "In11.Cu")
		(net "M_F_CPU0_SB_DQS_DP<2>")
	)
	(segment
		(start 308.898544 -301.138844)
		(end 308.949852 -301.190406)
		(width 0.16002)
		(layer "In11.Cu")
		(net "M_F_CPU0_SB_DQS_DP<2>")
	)
	(segment
		(start 313.968892 -296.171366)
		(end 313.91733 -296.119804)
		(width 0.16002)
		(layer "In11.Cu")
		(net "M_F_CPU0_SB_DQS_DP<2>")
	)
	(segment
		(start 271.94637 -303.85893)
		(end 271.267428 -303.85893)
		(width 0.16002)
		(layer "In11.Cu")
		(net "M_F_CPU0_SB_DQS_DP<2>")
	)
	(segment
		(start 270.553688 -303.85893)
		(end 269.92199 -303.85893)
		(width 0.16002)
		(layer "In11.Cu")
		(net "M_F_CPU0_SB_DQS_DP<2>")
	)
	(segment
		(start 283.05887 -303.22901)
		(end 282.23337 -304.05451)
		(width 0.16002)
		(layer "In11.Cu")
		(net "M_F_CPU0_SB_DQS_DP<2>")
	)
	(segment
		(start 308.949852 -301.416466)
		(end 308.703472 -301.662846)
		(width 0.16002)
		(layer "In11.Cu")
		(net "M_F_CPU0_SB_DQS_DP<2>")
	)
	(segment
		(start 279.035256 -303.709832)
		(end 278.185372 -302.859948)
		(width 0.16002)
		(layer "In11.Cu")
		(net "M_F_CPU0_SB_DQS_DP<2>")
	)
	(segment
		(start 315.2902 -294.746934)
		(end 314.81395 -294.746934)
		(width 0.16002)
		(layer "In11.Cu")
		(net "M_F_CPU0_SB_DQS_DP<2>")
	)
	(segment
		(start 318.03594 -292.001194)
		(end 317.55969 -292.001194)
		(width 0.16002)
		(layer "In11.Cu")
		(net "M_F_CPU0_SB_DQS_DP<2>")
	)
	(segment
		(start 271.267428 -303.85893)
		(end 271.150588 -303.74209)
		(width 0.16002)
		(layer "In11.Cu")
		(net "M_F_CPU0_SB_DQS_DP<2>")
	)
	(segment
		(start 312.54446 -297.492674)
		(end 312.06821 -297.492674)
		(width 0.16002)
		(layer "In11.Cu")
		(net "M_F_CPU0_SB_DQS_DP<2>")
	)
	(segment
		(start 319.932812 -290.433506)
		(end 319.686432 -290.679886)
		(width 0.16002)
		(layer "In11.Cu")
		(net "M_F_CPU0_SB_DQS_DP<2>")
	)
	(segment
		(start 315.567822 -294.798496)
		(end 315.341762 -294.798496)
		(width 0.16002)
		(layer "In11.Cu")
		(net "M_F_CPU0_SB_DQS_DP<2>")
	)
	(segment
		(start 305.690778 -303.22901)
		(end 304.865278 -304.05451)
		(width 0.16002)
		(layer "In11.Cu")
		(net "M_F_CPU0_SB_DQS_DP<2>")
	)
	(segment
		(start 310.322722 -300.043596)
		(end 310.076342 -300.289976)
		(width 0.16002)
		(layer "In11.Cu")
		(net "M_F_CPU0_SB_DQS_DP<2>")
	)
	(segment
		(start 313.91733 -296.119804)
		(end 313.44108 -296.119804)
		(width 0.16002)
		(layer "In11.Cu")
		(net "M_F_CPU0_SB_DQS_DP<2>")
	)
	(segment
		(start 301.460154 -303.502568)
		(end 300.817534 -302.859948)
		(width 0.16002)
		(layer "In11.Cu")
		(net "M_F_CPU0_SB_DQS_DP<2>")
	)
	(segment
		(start 319.881504 -290.155884)
		(end 319.932812 -290.207446)
		(width 0.16002)
		(layer "In11.Cu")
		(net "M_F_CPU0_SB_DQS_DP<2>")
	)
	(segment
		(start 309.79872 -300.238414)
		(end 309.32247 -300.238414)
		(width 0.16002)
		(layer "In11.Cu")
		(net "M_F_CPU0_SB_DQS_DP<2>")
	)
	(segment
		(start 310.69534 -298.865544)
		(end 310.271414 -299.28947)
		(width 0.16002)
		(layer "In11.Cu")
		(net "M_F_CPU0_SB_DQS_DP<2>")
	)
	(segment
		(start 316.18682 -293.374064)
		(end 315.762894 -293.79799)
		(width 0.16002)
		(layer "In11.Cu")
		(net "M_F_CPU0_SB_DQS_DP<2>")
	)
	(segment
		(start 304.865278 -304.05451)
		(end 302.368966 -304.05451)
		(width 0.16002)
		(layer "In11.Cu")
		(net "M_F_CPU0_SB_DQS_DP<2>")
	)
	(segment
		(start 307.576982 -302.789336)
		(end 307.16601 -303.200308)
		(width 0.16002)
		(layer "In11.Cu")
		(net "M_F_CPU0_SB_DQS_DP<2>")
	)
	(segment
		(start 300.817534 -302.859948)
		(end 298.960794 -302.859948)
		(width 0.16002)
		(layer "In11.Cu")
		(net "M_F_CPU0_SB_DQS_DP<2>")
	)
	(segment
		(start 281.834082 -304.05451)
		(end 281.489404 -303.709832)
		(width 0.16002)
		(layer "In11.Cu")
		(net "M_F_CPU0_SB_DQS_DP<2>")
	)
	(segment
		(start 278.185372 -302.859948)
		(end 276.328632 -302.859948)
		(width 0.16002)
		(layer "In11.Cu")
		(net "M_F_CPU0_SB_DQS_DP<2>")
	)
	(segment
		(start 311.695592 -298.444666)
		(end 311.695592 -298.670726)
		(width 0.16002)
		(layer "In11.Cu")
		(net "M_F_CPU0_SB_DQS_DP<2>")
	)
	(segment
		(start 289.033458 -303.709832)
		(end 286.57931 -303.709832)
		(width 0.16002)
		(layer "In11.Cu")
		(net "M_F_CPU0_SB_DQS_DP<2>")
	)
	(segment
		(start 315.762894 -294.274494)
		(end 315.814202 -294.326056)
		(width 0.16002)
		(layer "In11.Cu")
		(net "M_F_CPU0_SB_DQS_DP<2>")
	)
	(segment
		(start 285.729426 -302.859948)
		(end 283.872686 -302.859948)
		(width 0.16002)
		(layer "In11.Cu")
		(net "M_F_CPU0_SB_DQS_DP<2>")
	)
	(segment
		(start 273.94535 -303.709832)
		(end 272.095468 -303.709832)
		(width 0.16002)
		(layer "In11.Cu")
		(net "M_F_CPU0_SB_DQS_DP<2>")
	)
	(segment
		(start 310.076342 -300.289976)
		(end 309.850282 -300.289976)
		(width 0.16002)
		(layer "In11.Cu")
		(net "M_F_CPU0_SB_DQS_DP<2>")
	)
	(segment
		(start 312.596022 -297.544236)
		(end 312.54446 -297.492674)
		(width 0.16002)
		(layer "In11.Cu")
		(net "M_F_CPU0_SB_DQS_DP<2>")
	)
	(segment
		(start 315.814202 -294.552116)
		(end 315.567822 -294.798496)
		(width 0.16002)
		(layer "In11.Cu")
		(net "M_F_CPU0_SB_DQS_DP<2>")
	)
	(segment
		(start 298.146978 -303.22901)
		(end 297.321478 -304.05451)
		(width 0.16002)
		(layer "In11.Cu")
		(net "M_F_CPU0_SB_DQS_DP<2>")
	)
	(segment
		(start 283.872686 -302.859948)
		(end 283.503624 -303.22901)
		(width 0.16002)
		(layer "In11.Cu")
		(net "M_F_CPU0_SB_DQS_DP<2>")
	)
	(segment
		(start 314.441332 -295.924986)
		(end 314.194952 -296.171366)
		(width 0.16002)
		(layer "In11.Cu")
		(net "M_F_CPU0_SB_DQS_DP<2>")
	)
	(segment
		(start 311.695592 -298.670726)
		(end 311.449212 -298.917106)
		(width 0.16002)
		(layer "In11.Cu")
		(net "M_F_CPU0_SB_DQS_DP<2>")
	)
	(segment
		(start 298.591732 -303.22901)
		(end 298.146978 -303.22901)
		(width 0.16002)
		(layer "In11.Cu")
		(net "M_F_CPU0_SB_DQS_DP<2>")
	)
	(segment
		(start 275.514816 -303.22901)
		(end 274.689316 -304.05451)
		(width 0.16002)
		(layer "In11.Cu")
		(net "M_F_CPU0_SB_DQS_DP<2>")
	)
	(segment
		(start 319.460372 -290.679886)
		(end 319.40881 -290.628324)
		(width 0.16002)
		(layer "In11.Cu")
		(net "M_F_CPU0_SB_DQS_DP<2>")
	)
	(segment
		(start 319.40881 -290.628324)
		(end 318.93256 -290.628324)
		(width 0.16002)
		(layer "In11.Cu")
		(net "M_F_CPU0_SB_DQS_DP<2>")
	)
	(segment
		(start 297.321478 -304.05451)
		(end 296.92219 -304.05451)
		(width 0.16002)
		(layer "In11.Cu")
		(net "M_F_CPU0_SB_DQS_DP<2>")
	)
	(segment
		(start 274.689316 -304.05451)
		(end 274.290028 -304.05451)
		(width 0.16002)
		(layer "In11.Cu")
		(net "M_F_CPU0_SB_DQS_DP<2>")
	)
	(segment
		(start 316.714632 -293.425626)
		(end 316.66307 -293.374064)
		(width 0.16002)
		(layer "In11.Cu")
		(net "M_F_CPU0_SB_DQS_DP<2>")
	)
	(segment
		(start 331.539596 -285.75127)
		(end 331.531214 -285.756096)
		(width 0.09525)
		(layer "In11.Cu")
		(net "M_F_CPU0_SB_DQS_DP<2>")
	)
	(segment
		(start 313.068462 -297.297856)
		(end 312.822082 -297.544236)
		(width 0.16002)
		(layer "In11.Cu")
		(net "M_F_CPU0_SB_DQS_DP<2>")
	)
	(segment
		(start 319.881504 -289.67938)
		(end 319.881504 -290.155884)
		(width 0.16002)
		(layer "In11.Cu")
		(net "M_F_CPU0_SB_DQS_DP<2>")
	)
	(segment
		(start 307.096922 -303.22901)
		(end 305.690778 -303.22901)
		(width 0.16002)
		(layer "In11.Cu")
		(net "M_F_CPU0_SB_DQS_DP<2>")
	)
	(segment
		(start 315.762894 -293.79799)
		(end 315.762894 -294.274494)
		(width 0.16002)
		(layer "In11.Cu")
		(net "M_F_CPU0_SB_DQS_DP<2>")
	)
	(segment
		(start 308.949852 -301.190406)
		(end 308.949852 -301.416466)
		(width 0.16002)
		(layer "In11.Cu")
		(net "M_F_CPU0_SB_DQS_DP<2>")
	)
	(segment
		(start 318.508634 -291.528754)
		(end 318.559942 -291.580316)
		(width 0.16002)
		(layer "In11.Cu")
		(net "M_F_CPU0_SB_DQS_DP<2>")
	)
	(segment
		(start 309.32247 -300.238414)
		(end 308.898544 -300.66234)
		(width 0.16002)
		(layer "In11.Cu")
		(net "M_F_CPU0_SB_DQS_DP<2>")
	)
	(segment
		(start 307.576982 -302.313086)
		(end 307.576982 -302.789336)
		(width 0.16002)
		(layer "In11.Cu")
		(net "M_F_CPU0_SB_DQS_DP<2>")
	)
	(segment
		(start 286.57931 -303.709832)
		(end 285.729426 -302.859948)
		(width 0.16002)
		(layer "In11.Cu")
		(net "M_F_CPU0_SB_DQS_DP<2>")
	)
	(segment
		(start 290.602924 -303.22901)
		(end 289.777424 -304.05451)
		(width 0.16002)
		(layer "In11.Cu")
		(net "M_F_CPU0_SB_DQS_DP<2>")
	)
	(segment
		(start 311.644284 -298.393104)
		(end 311.695592 -298.444666)
		(width 0.16002)
		(layer "In11.Cu")
		(net "M_F_CPU0_SB_DQS_DP<2>")
	)
	(segment
		(start 314.441332 -295.698926)
		(end 314.441332 -295.924986)
		(width 0.16002)
		(layer "In11.Cu")
		(net "M_F_CPU0_SB_DQS_DP<2>")
	)
	(segment
		(start 283.503624 -303.22901)
		(end 283.05887 -303.22901)
		(width 0.16002)
		(layer "In11.Cu")
		(net "M_F_CPU0_SB_DQS_DP<2>")
	)
	(segment
		(start 314.390024 -295.17086)
		(end 314.390024 -295.647364)
		(width 0.16002)
		(layer "In11.Cu")
		(net "M_F_CPU0_SB_DQS_DP<2>")
	)
	(segment
		(start 308.898544 -300.66234)
		(end 308.898544 -301.138844)
		(width 0.16002)
		(layer "In11.Cu")
		(net "M_F_CPU0_SB_DQS_DP<2>")
	)
	(segment
		(start 314.81395 -294.746934)
		(end 314.390024 -295.17086)
		(width 0.16002)
		(layer "In11.Cu")
		(net "M_F_CPU0_SB_DQS_DP<2>")
	)
	(segment
		(start 282.23337 -304.05451)
		(end 281.834082 -304.05451)
		(width 0.16002)
		(layer "In11.Cu")
		(net "M_F_CPU0_SB_DQS_DP<2>")
	)
	(segment
		(start 296.92219 -304.05451)
		(end 296.577512 -303.709832)
		(width 0.16002)
		(layer "In11.Cu")
		(net "M_F_CPU0_SB_DQS_DP<2>")
	)
	(segment
		(start 332.445106 -285.69158)
		(end 332.421738 -285.778448)
		(width 0.09525)
		(layer "In11.Cu")
		(net "M_F_CPU0_SB_DQS_DP<2>")
	)
	(segment
		(start 324.586346 -286.462216)
		(end 324.562724 -286.462216)
		(width 0.09525)
		(layer "In11.Cu")
		(net "M_F_CPU0_SB_DQS_DP<2>")
	)
	(arc
		(start 326.840088 -285.75127)
		(mid 326.748905 -285.7897)
		(end 326.650858 -285.803086)
		(width 0.09525)
		(layer "In11.Cu")
		(net "M_F_CPU0_SB_DQS_DP<2>")
	)
	(arc
		(start 332.421738 -285.778448)
		(mid 332.259056 -285.80058)
		(end 332.10246 -285.75127)
		(width 0.09525)
		(layer "In11.Cu")
		(net "M_F_CPU0_SB_DQS_DP<2>")
	)
	(arc
		(start 329.282552 -285.75127)
		(mid 329.00112 -285.675515)
		(end 328.719688 -285.75127)
		(width 0.09525)
		(layer "In11.Cu")
		(net "M_F_CPU0_SB_DQS_DP<2>")
	)
	(arc
		(start 330.222606 -285.75127)
		(mid 329.941174 -285.675515)
		(end 329.659742 -285.75127)
		(width 0.09525)
		(layer "In11.Cu")
		(net "M_F_CPU0_SB_DQS_DP<2>")
	)
	(arc
		(start 328.711306 -285.756096)
		(mid 328.526274 -285.80201)
		(end 328.342498 -285.75127)
		(width 0.09525)
		(layer "In11.Cu")
		(net "M_F_CPU0_SB_DQS_DP<2>")
	)
	(arc
		(start 328.342498 -285.75127)
		(mid 328.07181 -285.675618)
		(end 327.79843 -285.740856)
		(width 0.09525)
		(layer "In11.Cu")
		(net "M_F_CPU0_SB_DQS_DP<2>")
	)
	(arc
		(start 329.659742 -285.75127)
		(mid 329.475967 -285.802042)
		(end 329.290934 -285.756096)
		(width 0.09525)
		(layer "In11.Cu")
		(net "M_F_CPU0_SB_DQS_DP<2>")
	)
	(arc
		(start 327.38568 -285.740856)
		(mid 327.111538 -285.675277)
		(end 326.840088 -285.75127)
		(width 0.09525)
		(layer "In11.Cu")
		(net "M_F_CPU0_SB_DQS_DP<2>")
	)
	(arc
		(start 331.531214 -285.756096)
		(mid 331.346182 -285.80201)
		(end 331.162406 -285.75127)
		(width 0.09525)
		(layer "In11.Cu")
		(net "M_F_CPU0_SB_DQS_DP<2>")
	)
	(arc
		(start 330.599542 -285.75127)
		(mid 330.411074 -285.801947)
		(end 330.222606 -285.75127)
		(width 0.09525)
		(layer "In11.Cu")
		(net "M_F_CPU0_SB_DQS_DP<2>")
	)
	(arc
		(start 332.10246 -285.75127)
		(mid 331.821028 -285.675515)
		(end 331.539596 -285.75127)
		(width 0.09525)
		(layer "In11.Cu")
		(net "M_F_CPU0_SB_DQS_DP<2>")
	)
	(arc
		(start 327.772014 -285.756096)
		(mid 327.587236 -285.801889)
		(end 327.403714 -285.75127)
		(width 0.09525)
		(layer "In11.Cu")
		(net "M_F_CPU0_SB_DQS_DP<2>")
	)
	(arc
		(start 331.162406 -285.75127)
		(mid 330.880974 -285.675515)
		(end 330.599542 -285.75127)
		(width 0.09525)
		(layer "In11.Cu")
		(net "M_F_CPU0_SB_DQS_DP<2>")
	)
	(segment
		(start 332.758034 -280.300176)
		(end 332.291182 -280.566114)
		(width 0.12954)
		(layer "F.Cu")
		(net "M_F_CPU0_SB_DQS_DP<1>")
	)
	(segment
		(start 272.095468 -294.359838)
		(end 273.94535 -294.359838)
		(width 0.16002)
		(layer "In11.Cu")
		(net "M_F_CPU0_SB_DQS_DP<1>")
	)
	(segment
		(start 332.421738 -280.918412)
		(end 332.445106 -280.831544)
		(width 0.09525)
		(layer "In11.Cu")
		(net "M_F_CPU0_SB_DQS_DP<1>")
	)
	(segment
		(start 316.940946 -284.630114)
		(end 316.940946 -284.126432)
		(width 0.16002)
		(layer "In11.Cu")
		(net "M_F_CPU0_SB_DQS_DP<1>")
	)
	(segment
		(start 323.895974 -280.78049)
		(end 323.919596 -280.78049)
		(width 0.09525)
		(layer "In11.Cu")
		(net "M_F_CPU0_SB_DQS_DP<1>")
	)
	(segment
		(start 311.199022 -290.372038)
		(end 311.446418 -290.124642)
		(width 0.16002)
		(layer "In11.Cu")
		(net "M_F_CPU0_SB_DQS_DP<1>")
	)
	(segment
		(start 282.23337 -294.704516)
		(end 283.05887 -293.879016)
		(width 0.16002)
		(layer "In11.Cu")
		(net "M_F_CPU0_SB_DQS_DP<1>")
	)
	(segment
		(start 315.87694 -284.763464)
		(end 316.353444 -284.763464)
		(width 0.16002)
		(layer "In11.Cu")
		(net "M_F_CPU0_SB_DQS_DP<1>")
	)
	(segment
		(start 312.706004 -287.9344)
		(end 313.129676 -287.510728)
		(width 0.16002)
		(layer "In11.Cu")
		(net "M_F_CPU0_SB_DQS_DP<1>")
	)
	(segment
		(start 314.193682 -287.377378)
		(end 314.193682 -287.151318)
		(width 0.16002)
		(layer "In11.Cu")
		(net "M_F_CPU0_SB_DQS_DP<1>")
	)
	(segment
		(start 313.720226 -287.624774)
		(end 313.946286 -287.624774)
		(width 0.16002)
		(layer "In11.Cu")
		(net "M_F_CPU0_SB_DQS_DP<1>")
	)
	(segment
		(start 328.711306 -280.89606)
		(end 328.719688 -280.891234)
		(width 0.09525)
		(layer "In11.Cu")
		(net "M_F_CPU0_SB_DQS_DP<1>")
	)
	(segment
		(start 316.69355 -284.87751)
		(end 316.940946 -284.630114)
		(width 0.16002)
		(layer "In11.Cu")
		(net "M_F_CPU0_SB_DQS_DP<1>")
	)
	(segment
		(start 308.699154 -292.368224)
		(end 309.321708 -291.74567)
		(width 0.16002)
		(layer "In11.Cu")
		(net "M_F_CPU0_SB_DQS_DP<1>")
	)
	(segment
		(start 312.572654 -288.998406)
		(end 312.82005 -288.75101)
		(width 0.16002)
		(layer "In11.Cu")
		(net "M_F_CPU0_SB_DQS_DP<1>")
	)
	(segment
		(start 289.777424 -294.704516)
		(end 290.602924 -293.879016)
		(width 0.16002)
		(layer "In11.Cu")
		(net "M_F_CPU0_SB_DQS_DP<1>")
	)
	(segment
		(start 283.503624 -293.879016)
		(end 283.872686 -293.509954)
		(width 0.16002)
		(layer "In11.Cu")
		(net "M_F_CPU0_SB_DQS_DP<1>")
	)
	(segment
		(start 332.445106 -280.831544)
		(end 332.291182 -280.566114)
		(width 0.09525)
		(layer "In11.Cu")
		(net "M_F_CPU0_SB_DQS_DP<1>")
	)
	(segment
		(start 311.446418 -290.124642)
		(end 311.446418 -289.898582)
		(width 0.16002)
		(layer "In11.Cu")
		(net "M_F_CPU0_SB_DQS_DP<1>")
	)
	(segment
		(start 285.729426 -293.509954)
		(end 286.57931 -294.359838)
		(width 0.16002)
		(layer "In11.Cu")
		(net "M_F_CPU0_SB_DQS_DP<1>")
	)
	(segment
		(start 315.453268 -285.66364)
		(end 315.453268 -285.187136)
		(width 0.16002)
		(layer "In11.Cu")
		(net "M_F_CPU0_SB_DQS_DP<1>")
	)
	(segment
		(start 331.531214 -280.89606)
		(end 331.539596 -280.891234)
		(width 0.09525)
		(layer "In11.Cu")
		(net "M_F_CPU0_SB_DQS_DP<1>")
	)
	(segment
		(start 318.067182 -283.503878)
		(end 318.314578 -283.256482)
		(width 0.16002)
		(layer "In11.Cu")
		(net "M_F_CPU0_SB_DQS_DP<1>")
	)
	(segment
		(start 283.872686 -293.509954)
		(end 285.729426 -293.509954)
		(width 0.16002)
		(layer "In11.Cu")
		(net "M_F_CPU0_SB_DQS_DP<1>")
	)
	(segment
		(start 315.093858 -286.251142)
		(end 315.319918 -286.251142)
		(width 0.16002)
		(layer "In11.Cu")
		(net "M_F_CPU0_SB_DQS_DP<1>")
	)
	(segment
		(start 318.314578 -282.7528)
		(end 318.937132 -282.130246)
		(width 0.16002)
		(layer "In11.Cu")
		(net "M_F_CPU0_SB_DQS_DP<1>")
	)
	(segment
		(start 312.706004 -288.410904)
		(end 312.706004 -287.9344)
		(width 0.16002)
		(layer "In11.Cu")
		(net "M_F_CPU0_SB_DQS_DP<1>")
	)
	(segment
		(start 310.972962 -290.372038)
		(end 311.199022 -290.372038)
		(width 0.16002)
		(layer "In11.Cu")
		(net "M_F_CPU0_SB_DQS_DP<1>")
	)
	(segment
		(start 304.865278 -294.704516)
		(end 305.690778 -293.879016)
		(width 0.16002)
		(layer "In11.Cu")
		(net "M_F_CPU0_SB_DQS_DP<1>")
	)
	(segment
		(start 278.185372 -293.509954)
		(end 279.035256 -294.359838)
		(width 0.16002)
		(layer "In11.Cu")
		(net "M_F_CPU0_SB_DQS_DP<1>")
	)
	(segment
		(start 314.079636 -287.037272)
		(end 314.079636 -286.560768)
		(width 0.16002)
		(layer "In11.Cu")
		(net "M_F_CPU0_SB_DQS_DP<1>")
	)
	(segment
		(start 269.648178 -294.235124)
		(end 269.92199 -294.508936)
		(width 0.16002)
		(layer "In11.Cu")
		(net "M_F_CPU0_SB_DQS_DP<1>")
	)
	(segment
		(start 273.94535 -294.359838)
		(end 274.290028 -294.704516)
		(width 0.16002)
		(layer "In11.Cu")
		(net "M_F_CPU0_SB_DQS_DP<1>")
	)
	(segment
		(start 309.82539 -291.74567)
		(end 310.072786 -291.498274)
		(width 0.16002)
		(layer "In11.Cu")
		(net "M_F_CPU0_SB_DQS_DP<1>")
	)
	(segment
		(start 319.68821 -281.379168)
		(end 320.286888 -280.78049)
		(width 0.16002)
		(layer "In11.Cu")
		(net "M_F_CPU0_SB_DQS_DP<1>")
	)
	(segment
		(start 307.188362 -293.879016)
		(end 307.948076 -293.119302)
		(width 0.16002)
		(layer "In11.Cu")
		(net "M_F_CPU0_SB_DQS_DP<1>")
	)
	(segment
		(start 271.409668 -294.508936)
		(end 271.94637 -294.508936)
		(width 0.16002)
		(layer "In11.Cu")
		(net "M_F_CPU0_SB_DQS_DP<1>")
	)
	(segment
		(start 312.82005 -288.75101)
		(end 312.82005 -288.52495)
		(width 0.16002)
		(layer "In11.Cu")
		(net "M_F_CPU0_SB_DQS_DP<1>")
	)
	(segment
		(start 269.92199 -294.508936)
		(end 270.695928 -294.508936)
		(width 0.16002)
		(layer "In11.Cu")
		(net "M_F_CPU0_SB_DQS_DP<1>")
	)
	(segment
		(start 327.38568 -280.88082)
		(end 327.403714 -280.891234)
		(width 0.09525)
		(layer "In11.Cu")
		(net "M_F_CPU0_SB_DQS_DP<1>")
	)
	(segment
		(start 311.756044 -288.88436)
		(end 312.232548 -288.88436)
		(width 0.16002)
		(layer "In11.Cu")
		(net "M_F_CPU0_SB_DQS_DP<1>")
	)
	(segment
		(start 314.503308 -286.137096)
		(end 314.979812 -286.137096)
		(width 0.16002)
		(layer "In11.Cu")
		(net "M_F_CPU0_SB_DQS_DP<1>")
	)
	(segment
		(start 315.319918 -286.251142)
		(end 315.567314 -286.003746)
		(width 0.16002)
		(layer "In11.Cu")
		(net "M_F_CPU0_SB_DQS_DP<1>")
	)
	(segment
		(start 301.817024 -294.152574)
		(end 302.368966 -294.704516)
		(width 0.16002)
		(layer "In11.Cu")
		(net "M_F_CPU0_SB_DQS_DP<1>")
	)
	(segment
		(start 312.346594 -288.998406)
		(end 312.572654 -288.998406)
		(width 0.16002)
		(layer "In11.Cu")
		(net "M_F_CPU0_SB_DQS_DP<1>")
	)
	(segment
		(start 310.072786 -291.498274)
		(end 310.072786 -291.272214)
		(width 0.16002)
		(layer "In11.Cu")
		(net "M_F_CPU0_SB_DQS_DP<1>")
	)
	(segment
		(start 318.314578 -283.256482)
		(end 318.314578 -282.7528)
		(width 0.16002)
		(layer "In11.Cu")
		(net "M_F_CPU0_SB_DQS_DP<1>")
	)
	(segment
		(start 289.033458 -294.359838)
		(end 289.378136 -294.704516)
		(width 0.16002)
		(layer "In11.Cu")
		(net "M_F_CPU0_SB_DQS_DP<1>")
	)
	(segment
		(start 286.57931 -294.359838)
		(end 289.033458 -294.359838)
		(width 0.16002)
		(layer "In11.Cu")
		(net "M_F_CPU0_SB_DQS_DP<1>")
	)
	(segment
		(start 323.919596 -280.78049)
		(end 323.978524 -280.839418)
		(width 0.09525)
		(layer "In11.Cu")
		(net "M_F_CPU0_SB_DQS_DP<1>")
	)
	(segment
		(start 314.079636 -286.560768)
		(end 314.503308 -286.137096)
		(width 0.16002)
		(layer "In11.Cu")
		(net "M_F_CPU0_SB_DQS_DP<1>")
	)
	(segment
		(start 283.05887 -293.879016)
		(end 283.503624 -293.879016)
		(width 0.16002)
		(layer "In11.Cu")
		(net "M_F_CPU0_SB_DQS_DP<1>")
	)
	(segment
		(start 315.567314 -286.003746)
		(end 315.567314 -285.777686)
		(width 0.16002)
		(layer "In11.Cu")
		(net "M_F_CPU0_SB_DQS_DP<1>")
	)
	(segment
		(start 327.780396 -280.891234)
		(end 327.79843 -280.88082)
		(width 0.09525)
		(layer "In11.Cu")
		(net "M_F_CPU0_SB_DQS_DP<1>")
	)
	(segment
		(start 307.948076 -293.119302)
		(end 308.451758 -293.119302)
		(width 0.16002)
		(layer "In11.Cu")
		(net "M_F_CPU0_SB_DQS_DP<1>")
	)
	(segment
		(start 317.5635 -283.503878)
		(end 318.067182 -283.503878)
		(width 0.16002)
		(layer "In11.Cu")
		(net "M_F_CPU0_SB_DQS_DP<1>")
	)
	(segment
		(start 319.440814 -282.130246)
		(end 319.68821 -281.88285)
		(width 0.16002)
		(layer "In11.Cu")
		(net "M_F_CPU0_SB_DQS_DP<1>")
	)
	(segment
		(start 297.321478 -294.704516)
		(end 298.146978 -293.879016)
		(width 0.16002)
		(layer "In11.Cu")
		(net "M_F_CPU0_SB_DQS_DP<1>")
	)
	(segment
		(start 293.27348 -293.509954)
		(end 294.123364 -294.359838)
		(width 0.16002)
		(layer "In11.Cu")
		(net "M_F_CPU0_SB_DQS_DP<1>")
	)
	(segment
		(start 312.82005 -288.52495)
		(end 312.706004 -288.410904)
		(width 0.16002)
		(layer "In11.Cu")
		(net "M_F_CPU0_SB_DQS_DP<1>")
	)
	(segment
		(start 309.95874 -291.158168)
		(end 309.95874 -290.681664)
		(width 0.16002)
		(layer "In11.Cu")
		(net "M_F_CPU0_SB_DQS_DP<1>")
	)
	(segment
		(start 301.460154 -294.152574)
		(end 301.817024 -294.152574)
		(width 0.16002)
		(layer "In11.Cu")
		(net "M_F_CPU0_SB_DQS_DP<1>")
	)
	(segment
		(start 326.463152 -280.891234)
		(end 326.479916 -280.900886)
		(width 0.09525)
		(layer "In11.Cu")
		(net "M_F_CPU0_SB_DQS_DP<1>")
	)
	(segment
		(start 315.453268 -285.187136)
		(end 315.87694 -284.763464)
		(width 0.16002)
		(layer "In11.Cu")
		(net "M_F_CPU0_SB_DQS_DP<1>")
	)
	(segment
		(start 314.193682 -287.151318)
		(end 314.079636 -287.037272)
		(width 0.16002)
		(layer "In11.Cu")
		(net "M_F_CPU0_SB_DQS_DP<1>")
	)
	(segment
		(start 300.817534 -293.509954)
		(end 301.460154 -294.152574)
		(width 0.16002)
		(layer "In11.Cu")
		(net "M_F_CPU0_SB_DQS_DP<1>")
	)
	(segment
		(start 318.937132 -282.130246)
		(end 319.440814 -282.130246)
		(width 0.16002)
		(layer "In11.Cu")
		(net "M_F_CPU0_SB_DQS_DP<1>")
	)
	(segment
		(start 329.282552 -280.891234)
		(end 329.290934 -280.89606)
		(width 0.09525)
		(layer "In11.Cu")
		(net "M_F_CPU0_SB_DQS_DP<1>")
	)
	(segment
		(start 315.567314 -285.777686)
		(end 315.453268 -285.66364)
		(width 0.16002)
		(layer "In11.Cu")
		(net "M_F_CPU0_SB_DQS_DP<1>")
	)
	(segment
		(start 298.960794 -293.509954)
		(end 300.817534 -293.509954)
		(width 0.16002)
		(layer "In11.Cu")
		(net "M_F_CPU0_SB_DQS_DP<1>")
	)
	(segment
		(start 327.772014 -280.89606)
		(end 327.780396 -280.891234)
		(width 0.09525)
		(layer "In11.Cu")
		(net "M_F_CPU0_SB_DQS_DP<1>")
	)
	(segment
		(start 296.92219 -294.704516)
		(end 297.321478 -294.704516)
		(width 0.16002)
		(layer "In11.Cu")
		(net "M_F_CPU0_SB_DQS_DP<1>")
	)
	(segment
		(start 326.106282 -280.55316)
		(end 326.385174 -280.832052)
		(width 0.09525)
		(layer "In11.Cu")
		(net "M_F_CPU0_SB_DQS_DP<1>")
	)
	(segment
		(start 309.95874 -290.681664)
		(end 310.382412 -290.257992)
		(width 0.16002)
		(layer "In11.Cu")
		(net "M_F_CPU0_SB_DQS_DP<1>")
	)
	(segment
		(start 271.94637 -294.508936)
		(end 272.095468 -294.359838)
		(width 0.16002)
		(layer "In11.Cu")
		(net "M_F_CPU0_SB_DQS_DP<1>")
	)
	(segment
		(start 311.446418 -289.898582)
		(end 311.332372 -289.784536)
		(width 0.16002)
		(layer "In11.Cu")
		(net "M_F_CPU0_SB_DQS_DP<1>")
	)
	(segment
		(start 294.123364 -294.359838)
		(end 296.577512 -294.359838)
		(width 0.16002)
		(layer "In11.Cu")
		(net "M_F_CPU0_SB_DQS_DP<1>")
	)
	(segment
		(start 291.41674 -293.509954)
		(end 293.27348 -293.509954)
		(width 0.16002)
		(layer "In11.Cu")
		(net "M_F_CPU0_SB_DQS_DP<1>")
	)
	(segment
		(start 316.353444 -284.763464)
		(end 316.46749 -284.87751)
		(width 0.16002)
		(layer "In11.Cu")
		(net "M_F_CPU0_SB_DQS_DP<1>")
	)
	(segment
		(start 313.946286 -287.624774)
		(end 314.193682 -287.377378)
		(width 0.16002)
		(layer "In11.Cu")
		(net "M_F_CPU0_SB_DQS_DP<1>")
	)
	(segment
		(start 324.3326 -280.839418)
		(end 324.618858 -280.55316)
		(width 0.09525)
		(layer "In11.Cu")
		(net "M_F_CPU0_SB_DQS_DP<1>")
	)
	(segment
		(start 308.451758 -293.119302)
		(end 308.699154 -292.871906)
		(width 0.16002)
		(layer "In11.Cu")
		(net "M_F_CPU0_SB_DQS_DP<1>")
	)
	(segment
		(start 274.689316 -294.704516)
		(end 275.514816 -293.879016)
		(width 0.16002)
		(layer "In11.Cu")
		(net "M_F_CPU0_SB_DQS_DP<1>")
	)
	(segment
		(start 323.978524 -280.839418)
		(end 324.3326 -280.839418)
		(width 0.09525)
		(layer "In11.Cu")
		(net "M_F_CPU0_SB_DQS_DP<1>")
	)
	(segment
		(start 310.382412 -290.257992)
		(end 310.858916 -290.257992)
		(width 0.16002)
		(layer "In11.Cu")
		(net "M_F_CPU0_SB_DQS_DP<1>")
	)
	(segment
		(start 302.368966 -294.704516)
		(end 304.865278 -294.704516)
		(width 0.16002)
		(layer "In11.Cu")
		(net "M_F_CPU0_SB_DQS_DP<1>")
	)
	(segment
		(start 270.695928 -294.508936)
		(end 270.812768 -294.392096)
		(width 0.16002)
		(layer "In11.Cu")
		(net "M_F_CPU0_SB_DQS_DP<1>")
	)
	(segment
		(start 276.328632 -293.509954)
		(end 278.185372 -293.509954)
		(width 0.16002)
		(layer "In11.Cu")
		(net "M_F_CPU0_SB_DQS_DP<1>")
	)
	(segment
		(start 305.690778 -293.879016)
		(end 307.188362 -293.879016)
		(width 0.16002)
		(layer "In11.Cu")
		(net "M_F_CPU0_SB_DQS_DP<1>")
	)
	(segment
		(start 271.292828 -294.392096)
		(end 271.409668 -294.508936)
		(width 0.16002)
		(layer "In11.Cu")
		(net "M_F_CPU0_SB_DQS_DP<1>")
	)
	(segment
		(start 309.321708 -291.74567)
		(end 309.82539 -291.74567)
		(width 0.16002)
		(layer "In11.Cu")
		(net "M_F_CPU0_SB_DQS_DP<1>")
	)
	(segment
		(start 289.378136 -294.704516)
		(end 289.777424 -294.704516)
		(width 0.16002)
		(layer "In11.Cu")
		(net "M_F_CPU0_SB_DQS_DP<1>")
	)
	(segment
		(start 275.514816 -293.879016)
		(end 275.95957 -293.879016)
		(width 0.16002)
		(layer "In11.Cu")
		(net "M_F_CPU0_SB_DQS_DP<1>")
	)
	(segment
		(start 296.577512 -294.359838)
		(end 296.92219 -294.704516)
		(width 0.16002)
		(layer "In11.Cu")
		(net "M_F_CPU0_SB_DQS_DP<1>")
	)
	(segment
		(start 279.035256 -294.359838)
		(end 281.489404 -294.359838)
		(width 0.16002)
		(layer "In11.Cu")
		(net "M_F_CPU0_SB_DQS_DP<1>")
	)
	(segment
		(start 281.489404 -294.359838)
		(end 281.834082 -294.704516)
		(width 0.16002)
		(layer "In11.Cu")
		(net "M_F_CPU0_SB_DQS_DP<1>")
	)
	(segment
		(start 324.618858 -280.55316)
		(end 326.106282 -280.55316)
		(width 0.09525)
		(layer "In11.Cu")
		(net "M_F_CPU0_SB_DQS_DP<1>")
	)
	(segment
		(start 310.858916 -290.257992)
		(end 310.972962 -290.372038)
		(width 0.16002)
		(layer "In11.Cu")
		(net "M_F_CPU0_SB_DQS_DP<1>")
	)
	(segment
		(start 316.46749 -284.87751)
		(end 316.69355 -284.87751)
		(width 0.16002)
		(layer "In11.Cu")
		(net "M_F_CPU0_SB_DQS_DP<1>")
	)
	(segment
		(start 314.979812 -286.137096)
		(end 315.093858 -286.251142)
		(width 0.16002)
		(layer "In11.Cu")
		(net "M_F_CPU0_SB_DQS_DP<1>")
	)
	(segment
		(start 316.940946 -284.126432)
		(end 317.5635 -283.503878)
		(width 0.16002)
		(layer "In11.Cu")
		(net "M_F_CPU0_SB_DQS_DP<1>")
	)
	(segment
		(start 310.072786 -291.272214)
		(end 309.95874 -291.158168)
		(width 0.16002)
		(layer "In11.Cu")
		(net "M_F_CPU0_SB_DQS_DP<1>")
	)
	(segment
		(start 308.699154 -292.871906)
		(end 308.699154 -292.368224)
		(width 0.16002)
		(layer "In11.Cu")
		(net "M_F_CPU0_SB_DQS_DP<1>")
	)
	(segment
		(start 290.602924 -293.879016)
		(end 291.047678 -293.879016)
		(width 0.16002)
		(layer "In11.Cu")
		(net "M_F_CPU0_SB_DQS_DP<1>")
	)
	(segment
		(start 313.60618 -287.510728)
		(end 313.720226 -287.624774)
		(width 0.16002)
		(layer "In11.Cu")
		(net "M_F_CPU0_SB_DQS_DP<1>")
	)
	(segment
		(start 291.047678 -293.879016)
		(end 291.41674 -293.509954)
		(width 0.16002)
		(layer "In11.Cu")
		(net "M_F_CPU0_SB_DQS_DP<1>")
	)
	(segment
		(start 311.332372 -289.308032)
		(end 311.756044 -288.88436)
		(width 0.16002)
		(layer "In11.Cu")
		(net "M_F_CPU0_SB_DQS_DP<1>")
	)
	(segment
		(start 270.812768 -294.392096)
		(end 271.292828 -294.392096)
		(width 0.16002)
		(layer "In11.Cu")
		(net "M_F_CPU0_SB_DQS_DP<1>")
	)
	(segment
		(start 313.129676 -287.510728)
		(end 313.60618 -287.510728)
		(width 0.16002)
		(layer "In11.Cu")
		(net "M_F_CPU0_SB_DQS_DP<1>")
	)
	(segment
		(start 311.332372 -289.784536)
		(end 311.332372 -289.308032)
		(width 0.16002)
		(layer "In11.Cu")
		(net "M_F_CPU0_SB_DQS_DP<1>")
	)
	(segment
		(start 281.834082 -294.704516)
		(end 282.23337 -294.704516)
		(width 0.16002)
		(layer "In11.Cu")
		(net "M_F_CPU0_SB_DQS_DP<1>")
	)
	(segment
		(start 298.146978 -293.879016)
		(end 298.591732 -293.879016)
		(width 0.16002)
		(layer "In11.Cu")
		(net "M_F_CPU0_SB_DQS_DP<1>")
	)
	(segment
		(start 319.68821 -281.88285)
		(end 319.68821 -281.379168)
		(width 0.16002)
		(layer "In11.Cu")
		(net "M_F_CPU0_SB_DQS_DP<1>")
	)
	(segment
		(start 320.286888 -280.78049)
		(end 323.895974 -280.78049)
		(width 0.16002)
		(layer "In11.Cu")
		(net "M_F_CPU0_SB_DQS_DP<1>")
	)
	(segment
		(start 312.232548 -288.88436)
		(end 312.346594 -288.998406)
		(width 0.16002)
		(layer "In11.Cu")
		(net "M_F_CPU0_SB_DQS_DP<1>")
	)
	(segment
		(start 275.95957 -293.879016)
		(end 276.328632 -293.509954)
		(width 0.16002)
		(layer "In11.Cu")
		(net "M_F_CPU0_SB_DQS_DP<1>")
	)
	(segment
		(start 298.591732 -293.879016)
		(end 298.960794 -293.509954)
		(width 0.16002)
		(layer "In11.Cu")
		(net "M_F_CPU0_SB_DQS_DP<1>")
	)
	(segment
		(start 274.290028 -294.704516)
		(end 274.689316 -294.704516)
		(width 0.16002)
		(layer "In11.Cu")
		(net "M_F_CPU0_SB_DQS_DP<1>")
	)
	(arc
		(start 328.342498 -280.891234)
		(mid 328.526273 -280.942006)
		(end 328.711306 -280.89606)
		(width 0.09525)
		(layer "In11.Cu")
		(net "M_F_CPU0_SB_DQS_DP<1>")
	)
	(arc
		(start 326.840088 -280.891234)
		(mid 327.111538 -280.815199)
		(end 327.38568 -280.88082)
		(width 0.09525)
		(layer "In11.Cu")
		(net "M_F_CPU0_SB_DQS_DP<1>")
	)
	(arc
		(start 332.10246 -280.891234)
		(mid 332.259058 -280.940523)
		(end 332.421738 -280.918412)
		(width 0.09525)
		(layer "In11.Cu")
		(net "M_F_CPU0_SB_DQS_DP<1>")
	)
	(arc
		(start 329.659742 -280.891234)
		(mid 329.941174 -280.815479)
		(end 330.222606 -280.891234)
		(width 0.09525)
		(layer "In11.Cu")
		(net "M_F_CPU0_SB_DQS_DP<1>")
	)
	(arc
		(start 326.385174 -280.832052)
		(mid 326.422232 -280.864186)
		(end 326.463152 -280.891234)
		(width 0.09525)
		(layer "In11.Cu")
		(net "M_F_CPU0_SB_DQS_DP<1>")
	)
	(arc
		(start 329.290934 -280.89606)
		(mid 329.475966 -280.941974)
		(end 329.659742 -280.891234)
		(width 0.09525)
		(layer "In11.Cu")
		(net "M_F_CPU0_SB_DQS_DP<1>")
	)
	(arc
		(start 326.479916 -280.900886)
		(mid 326.661227 -280.941984)
		(end 326.840088 -280.891234)
		(width 0.09525)
		(layer "In11.Cu")
		(net "M_F_CPU0_SB_DQS_DP<1>")
	)
	(arc
		(start 331.539596 -280.891234)
		(mid 331.821028 -280.815479)
		(end 332.10246 -280.891234)
		(width 0.09525)
		(layer "In11.Cu")
		(net "M_F_CPU0_SB_DQS_DP<1>")
	)
	(arc
		(start 331.162406 -280.891234)
		(mid 331.346181 -280.942006)
		(end 331.531214 -280.89606)
		(width 0.09525)
		(layer "In11.Cu")
		(net "M_F_CPU0_SB_DQS_DP<1>")
	)
	(arc
		(start 328.719688 -280.891234)
		(mid 329.00112 -280.815479)
		(end 329.282552 -280.891234)
		(width 0.09525)
		(layer "In11.Cu")
		(net "M_F_CPU0_SB_DQS_DP<1>")
	)
	(arc
		(start 327.403714 -280.891234)
		(mid 327.587235 -280.941878)
		(end 327.772014 -280.89606)
		(width 0.09525)
		(layer "In11.Cu")
		(net "M_F_CPU0_SB_DQS_DP<1>")
	)
	(arc
		(start 330.599542 -280.891234)
		(mid 330.880974 -280.815479)
		(end 331.162406 -280.891234)
		(width 0.09525)
		(layer "In11.Cu")
		(net "M_F_CPU0_SB_DQS_DP<1>")
	)
	(arc
		(start 327.79843 -280.88082)
		(mid 328.07181 -280.815599)
		(end 328.342498 -280.891234)
		(width 0.09525)
		(layer "In11.Cu")
		(net "M_F_CPU0_SB_DQS_DP<1>")
	)
	(arc
		(start 330.222606 -280.891234)
		(mid 330.411074 -280.941911)
		(end 330.599542 -280.891234)
		(width 0.09525)
		(layer "In11.Cu")
		(net "M_F_CPU0_SB_DQS_DP<1>")
	)
	(segment
		(start 332.758034 -275.44014)
		(end 332.291182 -275.706078)
		(width 0.12954)
		(layer "F.Cu")
		(net "M_F_CPU0_SB_DQS_DP<0>")
	)
	(segment
		(start 310.988202 -280.729436)
		(end 311.464706 -280.729436)
		(width 0.16002)
		(layer "In11.Cu")
		(net "M_F_CPU0_SB_DQS_DP<0>")
	)
	(segment
		(start 296.577512 -285.009844)
		(end 296.92219 -285.354522)
		(width 0.16002)
		(layer "In11.Cu")
		(net "M_F_CPU0_SB_DQS_DP<0>")
	)
	(segment
		(start 272.095468 -285.009844)
		(end 273.94535 -285.009844)
		(width 0.16002)
		(layer "In11.Cu")
		(net "M_F_CPU0_SB_DQS_DP<0>")
	)
	(segment
		(start 313.311794 -278.882348)
		(end 313.311794 -278.405844)
		(width 0.16002)
		(layer "In11.Cu")
		(net "M_F_CPU0_SB_DQS_DP<0>")
	)
	(segment
		(start 269.648178 -284.88513)
		(end 269.92199 -285.158942)
		(width 0.16002)
		(layer "In11.Cu")
		(net "M_F_CPU0_SB_DQS_DP<0>")
	)
	(segment
		(start 270.652748 -285.158942)
		(end 270.769588 -285.042102)
		(width 0.16002)
		(layer "In11.Cu")
		(net "M_F_CPU0_SB_DQS_DP<0>")
	)
	(segment
		(start 308.717442 -283.4767)
		(end 308.886352 -283.64561)
		(width 0.16002)
		(layer "In11.Cu")
		(net "M_F_CPU0_SB_DQS_DP<0>")
	)
	(segment
		(start 297.321478 -285.354522)
		(end 298.146978 -284.529022)
		(width 0.16002)
		(layer "In11.Cu")
		(net "M_F_CPU0_SB_DQS_DP<0>")
	)
	(segment
		(start 314.21197 -277.982172)
		(end 314.38088 -278.151082)
		(width 0.16002)
		(layer "In11.Cu")
		(net "M_F_CPU0_SB_DQS_DP<0>")
	)
	(segment
		(start 325.152258 -275.215858)
		(end 326.018652 -276.082252)
		(width 0.09525)
		(layer "In11.Cu")
		(net "M_F_CPU0_SB_DQS_DP<0>")
	)
	(segment
		(start 314.685426 -277.508716)
		(end 314.685426 -277.032212)
		(width 0.16002)
		(layer "In11.Cu")
		(net "M_F_CPU0_SB_DQS_DP<0>")
	)
	(segment
		(start 312.838338 -279.355804)
		(end 313.007248 -279.524714)
		(width 0.16002)
		(layer "In11.Cu")
		(net "M_F_CPU0_SB_DQS_DP<0>")
	)
	(segment
		(start 310.73344 -281.798522)
		(end 310.56453 -281.629612)
		(width 0.16002)
		(layer "In11.Cu")
		(net "M_F_CPU0_SB_DQS_DP<0>")
	)
	(segment
		(start 316.227968 -276.303994)
		(end 316.059058 -276.135084)
		(width 0.16002)
		(layer "In11.Cu")
		(net "M_F_CPU0_SB_DQS_DP<0>")
	)
	(segment
		(start 312.107072 -280.42489)
		(end 311.938162 -280.25598)
		(width 0.16002)
		(layer "In11.Cu")
		(net "M_F_CPU0_SB_DQS_DP<0>")
	)
	(segment
		(start 310.56453 -281.629612)
		(end 310.56453 -281.153108)
		(width 0.16002)
		(layer "In11.Cu")
		(net "M_F_CPU0_SB_DQS_DP<0>")
	)
	(segment
		(start 315.585602 -276.60854)
		(end 315.754512 -276.77745)
		(width 0.16002)
		(layer "In11.Cu")
		(net "M_F_CPU0_SB_DQS_DP<0>")
	)
	(segment
		(start 313.480704 -279.051258)
		(end 313.311794 -278.882348)
		(width 0.16002)
		(layer "In11.Cu")
		(net "M_F_CPU0_SB_DQS_DP<0>")
	)
	(segment
		(start 285.729426 -284.15996)
		(end 286.57931 -285.009844)
		(width 0.16002)
		(layer "In11.Cu")
		(net "M_F_CPU0_SB_DQS_DP<0>")
	)
	(segment
		(start 294.123364 -285.009844)
		(end 296.577512 -285.009844)
		(width 0.16002)
		(layer "In11.Cu")
		(net "M_F_CPU0_SB_DQS_DP<0>")
	)
	(segment
		(start 314.854336 -277.677626)
		(end 314.685426 -277.508716)
		(width 0.16002)
		(layer "In11.Cu")
		(net "M_F_CPU0_SB_DQS_DP<0>")
	)
	(segment
		(start 289.378136 -285.354522)
		(end 289.777424 -285.354522)
		(width 0.16002)
		(layer "In11.Cu")
		(net "M_F_CPU0_SB_DQS_DP<0>")
	)
	(segment
		(start 271.366488 -285.158942)
		(end 271.94637 -285.158942)
		(width 0.16002)
		(layer "In11.Cu")
		(net "M_F_CPU0_SB_DQS_DP<0>")
	)
	(segment
		(start 296.92219 -285.354522)
		(end 297.321478 -285.354522)
		(width 0.16002)
		(layer "In11.Cu")
		(net "M_F_CPU0_SB_DQS_DP<0>")
	)
	(segment
		(start 309.61457 -282.103068)
		(end 310.091074 -282.103068)
		(width 0.16002)
		(layer "In11.Cu")
		(net "M_F_CPU0_SB_DQS_DP<0>")
	)
	(segment
		(start 312.107072 -280.65095)
		(end 312.107072 -280.42489)
		(width 0.16002)
		(layer "In11.Cu")
		(net "M_F_CPU0_SB_DQS_DP<0>")
	)
	(segment
		(start 270.769588 -285.042102)
		(end 271.249648 -285.042102)
		(width 0.16002)
		(layer "In11.Cu")
		(net "M_F_CPU0_SB_DQS_DP<0>")
	)
	(segment
		(start 315.980572 -276.77745)
		(end 316.227968 -276.530054)
		(width 0.16002)
		(layer "In11.Cu")
		(net "M_F_CPU0_SB_DQS_DP<0>")
	)
	(segment
		(start 331.531214 -276.036024)
		(end 331.539596 -276.031198)
		(width 0.09525)
		(layer "In11.Cu")
		(net "M_F_CPU0_SB_DQS_DP<0>")
	)
	(segment
		(start 309.112412 -283.64561)
		(end 309.359808 -283.398214)
		(width 0.16002)
		(layer "In11.Cu")
		(net "M_F_CPU0_SB_DQS_DP<0>")
	)
	(segment
		(start 291.047678 -284.529022)
		(end 291.41674 -284.15996)
		(width 0.16002)
		(layer "In11.Cu")
		(net "M_F_CPU0_SB_DQS_DP<0>")
	)
	(segment
		(start 311.464706 -280.729436)
		(end 311.633616 -280.898346)
		(width 0.16002)
		(layer "In11.Cu")
		(net "M_F_CPU0_SB_DQS_DP<0>")
	)
	(segment
		(start 314.38088 -278.151082)
		(end 314.60694 -278.151082)
		(width 0.16002)
		(layer "In11.Cu")
		(net "M_F_CPU0_SB_DQS_DP<0>")
	)
	(segment
		(start 316.059058 -275.65858)
		(end 316.560708 -275.15693)
		(width 0.16002)
		(layer "In11.Cu")
		(net "M_F_CPU0_SB_DQS_DP<0>")
	)
	(segment
		(start 310.486044 -282.271978)
		(end 310.73344 -282.024582)
		(width 0.16002)
		(layer "In11.Cu")
		(net "M_F_CPU0_SB_DQS_DP<0>")
	)
	(segment
		(start 271.249648 -285.042102)
		(end 271.366488 -285.158942)
		(width 0.16002)
		(layer "In11.Cu")
		(net "M_F_CPU0_SB_DQS_DP<0>")
	)
	(segment
		(start 302.368966 -285.354522)
		(end 304.865278 -285.354522)
		(width 0.16002)
		(layer "In11.Cu")
		(net "M_F_CPU0_SB_DQS_DP<0>")
	)
	(segment
		(start 310.56453 -281.153108)
		(end 310.988202 -280.729436)
		(width 0.16002)
		(layer "In11.Cu")
		(net "M_F_CPU0_SB_DQS_DP<0>")
	)
	(segment
		(start 290.602924 -284.529022)
		(end 291.047678 -284.529022)
		(width 0.16002)
		(layer "In11.Cu")
		(net "M_F_CPU0_SB_DQS_DP<0>")
	)
	(segment
		(start 304.865278 -285.354522)
		(end 305.690778 -284.529022)
		(width 0.16002)
		(layer "In11.Cu")
		(net "M_F_CPU0_SB_DQS_DP<0>")
	)
	(segment
		(start 313.480704 -279.277318)
		(end 313.480704 -279.051258)
		(width 0.16002)
		(layer "In11.Cu")
		(net "M_F_CPU0_SB_DQS_DP<0>")
	)
	(segment
		(start 327.78065 -276.031198)
		(end 327.780396 -276.031198)
		(width 0.09525)
		(layer "In11.Cu")
		(net "M_F_CPU0_SB_DQS_DP<0>")
	)
	(segment
		(start 305.690778 -284.529022)
		(end 307.188616 -284.529022)
		(width 0.16002)
		(layer "In11.Cu")
		(net "M_F_CPU0_SB_DQS_DP<0>")
	)
	(segment
		(start 332.421738 -276.058376)
		(end 332.445106 -275.971508)
		(width 0.09525)
		(layer "In11.Cu")
		(net "M_F_CPU0_SB_DQS_DP<0>")
	)
	(segment
		(start 308.886352 -283.64561)
		(end 309.112412 -283.64561)
		(width 0.16002)
		(layer "In11.Cu")
		(net "M_F_CPU0_SB_DQS_DP<0>")
	)
	(segment
		(start 301.460154 -284.80258)
		(end 301.817024 -284.80258)
		(width 0.16002)
		(layer "In11.Cu")
		(net "M_F_CPU0_SB_DQS_DP<0>")
	)
	(segment
		(start 312.361834 -279.355804)
		(end 312.838338 -279.355804)
		(width 0.16002)
		(layer "In11.Cu")
		(net "M_F_CPU0_SB_DQS_DP<0>")
	)
	(segment
		(start 309.359808 -283.172154)
		(end 309.190898 -283.003244)
		(width 0.16002)
		(layer "In11.Cu")
		(net "M_F_CPU0_SB_DQS_DP<0>")
	)
	(segment
		(start 332.445106 -275.971508)
		(end 332.291182 -275.706078)
		(width 0.09525)
		(layer "In11.Cu")
		(net "M_F_CPU0_SB_DQS_DP<0>")
	)
	(segment
		(start 314.60694 -278.151082)
		(end 314.854336 -277.903686)
		(width 0.16002)
		(layer "In11.Cu")
		(net "M_F_CPU0_SB_DQS_DP<0>")
	)
	(segment
		(start 326.018652 -276.082252)
		(end 327.592182 -276.082252)
		(width 0.09525)
		(layer "In11.Cu")
		(net "M_F_CPU0_SB_DQS_DP<0>")
	)
	(segment
		(start 315.754512 -276.77745)
		(end 315.980572 -276.77745)
		(width 0.16002)
		(layer "In11.Cu")
		(net "M_F_CPU0_SB_DQS_DP<0>")
	)
	(segment
		(start 282.23337 -285.354522)
		(end 283.05887 -284.529022)
		(width 0.16002)
		(layer "In11.Cu")
		(net "M_F_CPU0_SB_DQS_DP<0>")
	)
	(segment
		(start 307.188616 -284.529022)
		(end 308.240938 -283.4767)
		(width 0.16002)
		(layer "In11.Cu")
		(net "M_F_CPU0_SB_DQS_DP<0>")
	)
	(segment
		(start 275.514816 -284.529022)
		(end 275.95957 -284.529022)
		(width 0.16002)
		(layer "In11.Cu")
		(net "M_F_CPU0_SB_DQS_DP<0>")
	)
	(segment
		(start 291.41674 -284.15996)
		(end 293.27348 -284.15996)
		(width 0.16002)
		(layer "In11.Cu")
		(net "M_F_CPU0_SB_DQS_DP<0>")
	)
	(segment
		(start 313.311794 -278.405844)
		(end 313.735466 -277.982172)
		(width 0.16002)
		(layer "In11.Cu")
		(net "M_F_CPU0_SB_DQS_DP<0>")
	)
	(segment
		(start 269.92199 -285.158942)
		(end 270.652748 -285.158942)
		(width 0.16002)
		(layer "In11.Cu")
		(net "M_F_CPU0_SB_DQS_DP<0>")
	)
	(segment
		(start 283.05887 -284.529022)
		(end 283.503624 -284.529022)
		(width 0.16002)
		(layer "In11.Cu")
		(net "M_F_CPU0_SB_DQS_DP<0>")
	)
	(segment
		(start 328.711306 -276.036024)
		(end 328.719688 -276.031198)
		(width 0.09525)
		(layer "In11.Cu")
		(net "M_F_CPU0_SB_DQS_DP<0>")
	)
	(segment
		(start 283.872686 -284.15996)
		(end 285.729426 -284.15996)
		(width 0.16002)
		(layer "In11.Cu")
		(net "M_F_CPU0_SB_DQS_DP<0>")
	)
	(segment
		(start 286.57931 -285.009844)
		(end 289.033458 -285.009844)
		(width 0.16002)
		(layer "In11.Cu")
		(net "M_F_CPU0_SB_DQS_DP<0>")
	)
	(segment
		(start 276.328632 -284.15996)
		(end 278.185372 -284.15996)
		(width 0.16002)
		(layer "In11.Cu")
		(net "M_F_CPU0_SB_DQS_DP<0>")
	)
	(segment
		(start 313.233308 -279.524714)
		(end 313.480704 -279.277318)
		(width 0.16002)
		(layer "In11.Cu")
		(net "M_F_CPU0_SB_DQS_DP<0>")
	)
	(segment
		(start 311.938162 -280.25598)
		(end 311.938162 -279.779476)
		(width 0.16002)
		(layer "In11.Cu")
		(net "M_F_CPU0_SB_DQS_DP<0>")
	)
	(segment
		(start 309.190898 -283.003244)
		(end 309.190898 -282.52674)
		(width 0.16002)
		(layer "In11.Cu")
		(net "M_F_CPU0_SB_DQS_DP<0>")
	)
	(segment
		(start 323.927216 -275.15693)
		(end 323.986144 -275.215858)
		(width 0.09525)
		(layer "In11.Cu")
		(net "M_F_CPU0_SB_DQS_DP<0>")
	)
	(segment
		(start 300.817534 -284.15996)
		(end 301.460154 -284.80258)
		(width 0.16002)
		(layer "In11.Cu")
		(net "M_F_CPU0_SB_DQS_DP<0>")
	)
	(segment
		(start 311.633616 -280.898346)
		(end 311.859676 -280.898346)
		(width 0.16002)
		(layer "In11.Cu")
		(net "M_F_CPU0_SB_DQS_DP<0>")
	)
	(segment
		(start 311.938162 -279.779476)
		(end 312.361834 -279.355804)
		(width 0.16002)
		(layer "In11.Cu")
		(net "M_F_CPU0_SB_DQS_DP<0>")
	)
	(segment
		(start 327.780396 -276.031198)
		(end 327.79843 -276.020784)
		(width 0.09525)
		(layer "In11.Cu")
		(net "M_F_CPU0_SB_DQS_DP<0>")
	)
	(segment
		(start 298.960794 -284.15996)
		(end 300.817534 -284.15996)
		(width 0.16002)
		(layer "In11.Cu")
		(net "M_F_CPU0_SB_DQS_DP<0>")
	)
	(segment
		(start 275.95957 -284.529022)
		(end 276.328632 -284.15996)
		(width 0.16002)
		(layer "In11.Cu")
		(net "M_F_CPU0_SB_DQS_DP<0>")
	)
	(segment
		(start 310.73344 -282.024582)
		(end 310.73344 -281.798522)
		(width 0.16002)
		(layer "In11.Cu")
		(net "M_F_CPU0_SB_DQS_DP<0>")
	)
	(segment
		(start 281.834082 -285.354522)
		(end 282.23337 -285.354522)
		(width 0.16002)
		(layer "In11.Cu")
		(net "M_F_CPU0_SB_DQS_DP<0>")
	)
	(segment
		(start 309.359808 -283.398214)
		(end 309.359808 -283.172154)
		(width 0.16002)
		(layer "In11.Cu")
		(net "M_F_CPU0_SB_DQS_DP<0>")
	)
	(segment
		(start 316.059058 -276.135084)
		(end 316.059058 -275.65858)
		(width 0.16002)
		(layer "In11.Cu")
		(net "M_F_CPU0_SB_DQS_DP<0>")
	)
	(segment
		(start 310.259984 -282.271978)
		(end 310.486044 -282.271978)
		(width 0.16002)
		(layer "In11.Cu")
		(net "M_F_CPU0_SB_DQS_DP<0>")
	)
	(segment
		(start 311.859676 -280.898346)
		(end 312.107072 -280.65095)
		(width 0.16002)
		(layer "In11.Cu")
		(net "M_F_CPU0_SB_DQS_DP<0>")
	)
	(segment
		(start 323.986144 -275.215858)
		(end 325.152258 -275.215858)
		(width 0.09525)
		(layer "In11.Cu")
		(net "M_F_CPU0_SB_DQS_DP<0>")
	)
	(segment
		(start 308.240938 -283.4767)
		(end 308.717442 -283.4767)
		(width 0.16002)
		(layer "In11.Cu")
		(net "M_F_CPU0_SB_DQS_DP<0>")
	)
	(segment
		(start 271.94637 -285.158942)
		(end 272.095468 -285.009844)
		(width 0.16002)
		(layer "In11.Cu")
		(net "M_F_CPU0_SB_DQS_DP<0>")
	)
	(segment
		(start 314.685426 -277.032212)
		(end 315.109098 -276.60854)
		(width 0.16002)
		(layer "In11.Cu")
		(net "M_F_CPU0_SB_DQS_DP<0>")
	)
	(segment
		(start 289.777424 -285.354522)
		(end 290.602924 -284.529022)
		(width 0.16002)
		(layer "In11.Cu")
		(net "M_F_CPU0_SB_DQS_DP<0>")
	)
	(segment
		(start 301.817024 -284.80258)
		(end 302.368966 -285.354522)
		(width 0.16002)
		(layer "In11.Cu")
		(net "M_F_CPU0_SB_DQS_DP<0>")
	)
	(segment
		(start 278.185372 -284.15996)
		(end 279.035256 -285.009844)
		(width 0.16002)
		(layer "In11.Cu")
		(net "M_F_CPU0_SB_DQS_DP<0>")
	)
	(segment
		(start 316.560708 -275.15693)
		(end 323.903594 -275.15693)
		(width 0.16002)
		(layer "In11.Cu")
		(net "M_F_CPU0_SB_DQS_DP<0>")
	)
	(segment
		(start 274.290028 -285.354522)
		(end 274.689316 -285.354522)
		(width 0.16002)
		(layer "In11.Cu")
		(net "M_F_CPU0_SB_DQS_DP<0>")
	)
	(segment
		(start 273.94535 -285.009844)
		(end 274.290028 -285.354522)
		(width 0.16002)
		(layer "In11.Cu")
		(net "M_F_CPU0_SB_DQS_DP<0>")
	)
	(segment
		(start 298.146978 -284.529022)
		(end 298.591732 -284.529022)
		(width 0.16002)
		(layer "In11.Cu")
		(net "M_F_CPU0_SB_DQS_DP<0>")
	)
	(segment
		(start 313.007248 -279.524714)
		(end 313.233308 -279.524714)
		(width 0.16002)
		(layer "In11.Cu")
		(net "M_F_CPU0_SB_DQS_DP<0>")
	)
	(segment
		(start 274.689316 -285.354522)
		(end 275.514816 -284.529022)
		(width 0.16002)
		(layer "In11.Cu")
		(net "M_F_CPU0_SB_DQS_DP<0>")
	)
	(segment
		(start 298.591732 -284.529022)
		(end 298.960794 -284.15996)
		(width 0.16002)
		(layer "In11.Cu")
		(net "M_F_CPU0_SB_DQS_DP<0>")
	)
	(segment
		(start 313.735466 -277.982172)
		(end 314.21197 -277.982172)
		(width 0.16002)
		(layer "In11.Cu")
		(net "M_F_CPU0_SB_DQS_DP<0>")
	)
	(segment
		(start 316.227968 -276.530054)
		(end 316.227968 -276.303994)
		(width 0.16002)
		(layer "In11.Cu")
		(net "M_F_CPU0_SB_DQS_DP<0>")
	)
	(segment
		(start 309.190898 -282.52674)
		(end 309.61457 -282.103068)
		(width 0.16002)
		(layer "In11.Cu")
		(net "M_F_CPU0_SB_DQS_DP<0>")
	)
	(segment
		(start 314.854336 -277.903686)
		(end 314.854336 -277.677626)
		(width 0.16002)
		(layer "In11.Cu")
		(net "M_F_CPU0_SB_DQS_DP<0>")
	)
	(segment
		(start 310.091074 -282.103068)
		(end 310.259984 -282.271978)
		(width 0.16002)
		(layer "In11.Cu")
		(net "M_F_CPU0_SB_DQS_DP<0>")
	)
	(segment
		(start 281.489404 -285.009844)
		(end 281.834082 -285.354522)
		(width 0.16002)
		(layer "In11.Cu")
		(net "M_F_CPU0_SB_DQS_DP<0>")
	)
	(segment
		(start 289.033458 -285.009844)
		(end 289.378136 -285.354522)
		(width 0.16002)
		(layer "In11.Cu")
		(net "M_F_CPU0_SB_DQS_DP<0>")
	)
	(segment
		(start 279.035256 -285.009844)
		(end 281.489404 -285.009844)
		(width 0.16002)
		(layer "In11.Cu")
		(net "M_F_CPU0_SB_DQS_DP<0>")
	)
	(segment
		(start 329.282552 -276.031198)
		(end 329.290934 -276.036024)
		(width 0.09525)
		(layer "In11.Cu")
		(net "M_F_CPU0_SB_DQS_DP<0>")
	)
	(segment
		(start 293.27348 -284.15996)
		(end 294.123364 -285.009844)
		(width 0.16002)
		(layer "In11.Cu")
		(net "M_F_CPU0_SB_DQS_DP<0>")
	)
	(segment
		(start 327.780396 -276.031452)
		(end 327.78065 -276.031198)
		(width 0.09525)
		(layer "In11.Cu")
		(net "M_F_CPU0_SB_DQS_DP<0>")
	)
	(segment
		(start 315.109098 -276.60854)
		(end 315.585602 -276.60854)
		(width 0.16002)
		(layer "In11.Cu")
		(net "M_F_CPU0_SB_DQS_DP<0>")
	)
	(segment
		(start 283.503624 -284.529022)
		(end 283.872686 -284.15996)
		(width 0.16002)
		(layer "In11.Cu")
		(net "M_F_CPU0_SB_DQS_DP<0>")
	)
	(segment
		(start 323.903594 -275.15693)
		(end 323.927216 -275.15693)
		(width 0.09525)
		(layer "In11.Cu")
		(net "M_F_CPU0_SB_DQS_DP<0>")
	)
	(arc
		(start 328.719688 -276.031198)
		(mid 329.00112 -275.955443)
		(end 329.282552 -276.031198)
		(width 0.09525)
		(layer "In11.Cu")
		(net "M_F_CPU0_SB_DQS_DP<0>")
	)
	(arc
		(start 330.599542 -276.031198)
		(mid 330.880974 -275.955443)
		(end 331.162406 -276.031198)
		(width 0.09525)
		(layer "In11.Cu")
		(net "M_F_CPU0_SB_DQS_DP<0>")
	)
	(arc
		(start 327.592182 -276.082252)
		(mid 327.689643 -276.069271)
		(end 327.780396 -276.031452)
		(width 0.09525)
		(layer "In11.Cu")
		(net "M_F_CPU0_SB_DQS_DP<0>")
	)
	(arc
		(start 329.659742 -276.031198)
		(mid 329.941174 -275.955443)
		(end 330.222606 -276.031198)
		(width 0.09525)
		(layer "In11.Cu")
		(net "M_F_CPU0_SB_DQS_DP<0>")
	)
	(arc
		(start 331.539596 -276.031198)
		(mid 331.821028 -275.955443)
		(end 332.10246 -276.031198)
		(width 0.09525)
		(layer "In11.Cu")
		(net "M_F_CPU0_SB_DQS_DP<0>")
	)
	(arc
		(start 330.222606 -276.031198)
		(mid 330.411074 -276.081875)
		(end 330.599542 -276.031198)
		(width 0.09525)
		(layer "In11.Cu")
		(net "M_F_CPU0_SB_DQS_DP<0>")
	)
	(arc
		(start 331.162406 -276.031198)
		(mid 331.346181 -276.08197)
		(end 331.531214 -276.036024)
		(width 0.09525)
		(layer "In11.Cu")
		(net "M_F_CPU0_SB_DQS_DP<0>")
	)
	(arc
		(start 332.10246 -276.031198)
		(mid 332.259058 -276.080487)
		(end 332.421738 -276.058376)
		(width 0.09525)
		(layer "In11.Cu")
		(net "M_F_CPU0_SB_DQS_DP<0>")
	)
	(arc
		(start 327.79843 -276.020784)
		(mid 328.07181 -275.955563)
		(end 328.342498 -276.031198)
		(width 0.09525)
		(layer "In11.Cu")
		(net "M_F_CPU0_SB_DQS_DP<0>")
	)
	(arc
		(start 328.342498 -276.031198)
		(mid 328.526273 -276.08197)
		(end 328.711306 -276.036024)
		(width 0.09525)
		(layer "In11.Cu")
		(net "M_F_CPU0_SB_DQS_DP<0>")
	)
	(arc
		(start 329.290934 -276.036024)
		(mid 329.475966 -276.081938)
		(end 329.659742 -276.031198)
		(width 0.09525)
		(layer "In11.Cu")
		(net "M_F_CPU0_SB_DQS_DP<0>")
	)
	(segment
		(start 333.227934 -271.39011)
		(end 332.761082 -271.656048)
		(width 0.12954)
		(layer "F.Cu")
		(net "M_F_CPU0_SB_DQS_DN<9>")
	)
	(segment
		(start 330.692506 -271.330928)
		(end 330.700888 -271.326102)
		(width 0.09525)
		(layer "In11.Cu")
		(net "M_F_CPU0_SB_DQS_DN<9>")
	)
	(segment
		(start 323.895974 -269.83563)
		(end 323.919596 -269.83563)
		(width 0.09525)
		(layer "In11.Cu")
		(net "M_F_CPU0_SB_DQS_DN<9>")
	)
	(segment
		(start 323.978778 -269.776448)
		(end 324.270116 -269.776448)
		(width 0.09525)
		(layer "In11.Cu")
		(net "M_F_CPU0_SB_DQS_DN<9>")
	)
	(segment
		(start 273.820128 -275.96211)
		(end 274.164806 -276.306788)
		(width 0.16002)
		(layer "In11.Cu")
		(net "M_F_CPU0_SB_DQS_DN<9>")
	)
	(segment
		(start 286.611568 -275.625052)
		(end 286.611568 -274.769072)
		(width 0.16002)
		(layer "In11.Cu")
		(net "M_F_CPU0_SB_DQS_DN<9>")
	)
	(segment
		(start 326.406256 -271.406366)
		(end 327.591928 -271.406366)
		(width 0.09525)
		(layer "In11.Cu")
		(net "M_F_CPU0_SB_DQS_DN<9>")
	)
	(segment
		(start 300.692312 -275.112226)
		(end 301.334932 -275.754846)
		(width 0.16002)
		(layer "In11.Cu")
		(net "M_F_CPU0_SB_DQS_DN<9>")
	)
	(segment
		(start 296.45229 -275.96211)
		(end 296.796968 -276.306788)
		(width 0.16002)
		(layer "In11.Cu")
		(net "M_F_CPU0_SB_DQS_DN<9>")
	)
	(segment
		(start 286.771588 -274.609052)
		(end 287.119822 -274.609052)
		(width 0.16002)
		(layer "In11.Cu")
		(net "M_F_CPU0_SB_DQS_DN<9>")
	)
	(segment
		(start 291.541962 -275.112226)
		(end 293.148258 -275.112226)
		(width 0.16002)
		(layer "In11.Cu")
		(net "M_F_CPU0_SB_DQS_DN<9>")
	)
	(segment
		(start 293.998142 -275.96211)
		(end 296.45229 -275.96211)
		(width 0.16002)
		(layer "In11.Cu")
		(net "M_F_CPU0_SB_DQS_DN<9>")
	)
	(segment
		(start 287.119822 -274.609052)
		(end 287.279842 -274.769072)
		(width 0.16002)
		(layer "In11.Cu")
		(net "M_F_CPU0_SB_DQS_DN<9>")
	)
	(segment
		(start 305.816 -275.481288)
		(end 307.426868 -275.481288)
		(width 0.16002)
		(layer "In11.Cu")
		(net "M_F_CPU0_SB_DQS_DN<9>")
	)
	(segment
		(start 281.364182 -275.96211)
		(end 281.70886 -276.306788)
		(width 0.16002)
		(layer "In11.Cu")
		(net "M_F_CPU0_SB_DQS_DN<9>")
	)
	(segment
		(start 287.279842 -274.769072)
		(end 287.279842 -275.625052)
		(width 0.16002)
		(layer "In11.Cu")
		(net "M_F_CPU0_SB_DQS_DN<9>")
	)
	(segment
		(start 279.651206 -275.625052)
		(end 279.988264 -275.96211)
		(width 0.16002)
		(layer "In11.Cu")
		(net "M_F_CPU0_SB_DQS_DN<9>")
	)
	(segment
		(start 283.184092 -275.481288)
		(end 283.628846 -275.481288)
		(width 0.16002)
		(layer "In11.Cu")
		(net "M_F_CPU0_SB_DQS_DN<9>")
	)
	(segment
		(start 277.367746 -275.112226)
		(end 278.21763 -275.96211)
		(width 0.16002)
		(layer "In11.Cu")
		(net "M_F_CPU0_SB_DQS_DN<9>")
	)
	(segment
		(start 279.142952 -274.296632)
		(end 279.491186 -274.296632)
		(width 0.16002)
		(layer "In11.Cu")
		(net "M_F_CPU0_SB_DQS_DN<9>")
	)
	(segment
		(start 269.92199 -276.111208)
		(end 272.071592 -276.111208)
		(width 0.16002)
		(layer "In11.Cu")
		(net "M_F_CPU0_SB_DQS_DN<9>")
	)
	(segment
		(start 287.279842 -275.625052)
		(end 287.6169 -275.96211)
		(width 0.16002)
		(layer "In11.Cu")
		(net "M_F_CPU0_SB_DQS_DN<9>")
	)
	(segment
		(start 332.50632 -271.363948)
		(end 332.607158 -271.390618)
		(width 0.09525)
		(layer "In11.Cu")
		(net "M_F_CPU0_SB_DQS_DN<9>")
	)
	(segment
		(start 272.071592 -276.111208)
		(end 272.22069 -275.96211)
		(width 0.16002)
		(layer "In11.Cu")
		(net "M_F_CPU0_SB_DQS_DN<9>")
	)
	(segment
		(start 272.22069 -275.96211)
		(end 273.820128 -275.96211)
		(width 0.16002)
		(layer "In11.Cu")
		(net "M_F_CPU0_SB_DQS_DN<9>")
	)
	(segment
		(start 282.358592 -276.306788)
		(end 283.184092 -275.481288)
		(width 0.16002)
		(layer "In11.Cu")
		(net "M_F_CPU0_SB_DQS_DN<9>")
	)
	(segment
		(start 291.1729 -275.481288)
		(end 291.541962 -275.112226)
		(width 0.16002)
		(layer "In11.Cu")
		(net "M_F_CPU0_SB_DQS_DN<9>")
	)
	(segment
		(start 269.648178 -276.38502)
		(end 269.92199 -276.111208)
		(width 0.16002)
		(layer "In11.Cu")
		(net "M_F_CPU0_SB_DQS_DN<9>")
	)
	(segment
		(start 276.453854 -275.112226)
		(end 277.367746 -275.112226)
		(width 0.16002)
		(layer "In11.Cu")
		(net "M_F_CPU0_SB_DQS_DN<9>")
	)
	(segment
		(start 274.814538 -276.306788)
		(end 275.640038 -275.481288)
		(width 0.16002)
		(layer "In11.Cu")
		(net "M_F_CPU0_SB_DQS_DN<9>")
	)
	(segment
		(start 297.4467 -276.306788)
		(end 298.2722 -275.481288)
		(width 0.16002)
		(layer "In11.Cu")
		(net "M_F_CPU0_SB_DQS_DN<9>")
	)
	(segment
		(start 301.691802 -275.754846)
		(end 302.243744 -276.306788)
		(width 0.16002)
		(layer "In11.Cu")
		(net "M_F_CPU0_SB_DQS_DN<9>")
	)
	(segment
		(start 298.716954 -275.481288)
		(end 299.086016 -275.112226)
		(width 0.16002)
		(layer "In11.Cu")
		(net "M_F_CPU0_SB_DQS_DN<9>")
	)
	(segment
		(start 276.084792 -275.481288)
		(end 276.453854 -275.112226)
		(width 0.16002)
		(layer "In11.Cu")
		(net "M_F_CPU0_SB_DQS_DN<9>")
	)
	(segment
		(start 332.607158 -271.390618)
		(end 332.761082 -271.656048)
		(width 0.09525)
		(layer "In11.Cu")
		(net "M_F_CPU0_SB_DQS_DN<9>")
	)
	(segment
		(start 274.164806 -276.306788)
		(end 274.814538 -276.306788)
		(width 0.16002)
		(layer "In11.Cu")
		(net "M_F_CPU0_SB_DQS_DN<9>")
	)
	(segment
		(start 290.728146 -275.481288)
		(end 291.1729 -275.481288)
		(width 0.16002)
		(layer "In11.Cu")
		(net "M_F_CPU0_SB_DQS_DN<9>")
	)
	(segment
		(start 323.919596 -269.83563)
		(end 323.978778 -269.776448)
		(width 0.09525)
		(layer "In11.Cu")
		(net "M_F_CPU0_SB_DQS_DN<9>")
	)
	(segment
		(start 278.982932 -275.625052)
		(end 278.982932 -274.456652)
		(width 0.16002)
		(layer "In11.Cu")
		(net "M_F_CPU0_SB_DQS_DN<9>")
	)
	(segment
		(start 330.12126 -271.326102)
		(end 330.129642 -271.330928)
		(width 0.09525)
		(layer "In11.Cu")
		(net "M_F_CPU0_SB_DQS_DN<9>")
	)
	(segment
		(start 286.27451 -275.96211)
		(end 286.611568 -275.625052)
		(width 0.16002)
		(layer "In11.Cu")
		(net "M_F_CPU0_SB_DQS_DN<9>")
	)
	(segment
		(start 301.334932 -275.754846)
		(end 301.691802 -275.754846)
		(width 0.16002)
		(layer "In11.Cu")
		(net "M_F_CPU0_SB_DQS_DN<9>")
	)
	(segment
		(start 288.908236 -275.96211)
		(end 289.252914 -276.306788)
		(width 0.16002)
		(layer "In11.Cu")
		(net "M_F_CPU0_SB_DQS_DN<9>")
	)
	(segment
		(start 298.2722 -275.481288)
		(end 298.716954 -275.481288)
		(width 0.16002)
		(layer "In11.Cu")
		(net "M_F_CPU0_SB_DQS_DN<9>")
	)
	(segment
		(start 299.086016 -275.112226)
		(end 300.692312 -275.112226)
		(width 0.16002)
		(layer "In11.Cu")
		(net "M_F_CPU0_SB_DQS_DN<9>")
	)
	(segment
		(start 324.270116 -269.776448)
		(end 324.823328 -270.32966)
		(width 0.09525)
		(layer "In11.Cu")
		(net "M_F_CPU0_SB_DQS_DN<9>")
	)
	(segment
		(start 289.252914 -276.306788)
		(end 289.902646 -276.306788)
		(width 0.16002)
		(layer "In11.Cu")
		(net "M_F_CPU0_SB_DQS_DN<9>")
	)
	(segment
		(start 283.628846 -275.481288)
		(end 283.997908 -275.112226)
		(width 0.16002)
		(layer "In11.Cu")
		(net "M_F_CPU0_SB_DQS_DN<9>")
	)
	(segment
		(start 279.491186 -274.296632)
		(end 279.651206 -274.456652)
		(width 0.16002)
		(layer "In11.Cu")
		(net "M_F_CPU0_SB_DQS_DN<9>")
	)
	(segment
		(start 283.997908 -275.112226)
		(end 284.929072 -275.112226)
		(width 0.16002)
		(layer "In11.Cu")
		(net "M_F_CPU0_SB_DQS_DN<9>")
	)
	(segment
		(start 307.426868 -275.481288)
		(end 313.072526 -269.83563)
		(width 0.16002)
		(layer "In11.Cu")
		(net "M_F_CPU0_SB_DQS_DN<9>")
	)
	(segment
		(start 313.072526 -269.83563)
		(end 323.895974 -269.83563)
		(width 0.16002)
		(layer "In11.Cu")
		(net "M_F_CPU0_SB_DQS_DN<9>")
	)
	(segment
		(start 327.872852 -271.330928)
		(end 327.88479 -271.32407)
		(width 0.09525)
		(layer "In11.Cu")
		(net "M_F_CPU0_SB_DQS_DN<9>")
	)
	(segment
		(start 287.6169 -275.96211)
		(end 288.908236 -275.96211)
		(width 0.16002)
		(layer "In11.Cu")
		(net "M_F_CPU0_SB_DQS_DN<9>")
	)
	(segment
		(start 278.645874 -275.96211)
		(end 278.982932 -275.625052)
		(width 0.16002)
		(layer "In11.Cu")
		(net "M_F_CPU0_SB_DQS_DN<9>")
	)
	(segment
		(start 279.988264 -275.96211)
		(end 281.364182 -275.96211)
		(width 0.16002)
		(layer "In11.Cu")
		(net "M_F_CPU0_SB_DQS_DN<9>")
	)
	(segment
		(start 302.243744 -276.306788)
		(end 304.9905 -276.306788)
		(width 0.16002)
		(layer "In11.Cu")
		(net "M_F_CPU0_SB_DQS_DN<9>")
	)
	(segment
		(start 325.32955 -270.32966)
		(end 326.406256 -271.406366)
		(width 0.09525)
		(layer "In11.Cu")
		(net "M_F_CPU0_SB_DQS_DN<9>")
	)
	(segment
		(start 275.640038 -275.481288)
		(end 276.084792 -275.481288)
		(width 0.16002)
		(layer "In11.Cu")
		(net "M_F_CPU0_SB_DQS_DN<9>")
	)
	(segment
		(start 279.651206 -274.456652)
		(end 279.651206 -275.625052)
		(width 0.16002)
		(layer "In11.Cu")
		(net "M_F_CPU0_SB_DQS_DN<9>")
	)
	(segment
		(start 285.778956 -275.96211)
		(end 286.27451 -275.96211)
		(width 0.16002)
		(layer "In11.Cu")
		(net "M_F_CPU0_SB_DQS_DN<9>")
	)
	(segment
		(start 281.70886 -276.306788)
		(end 282.358592 -276.306788)
		(width 0.16002)
		(layer "In11.Cu")
		(net "M_F_CPU0_SB_DQS_DN<9>")
	)
	(segment
		(start 304.9905 -276.306788)
		(end 305.816 -275.481288)
		(width 0.16002)
		(layer "In11.Cu")
		(net "M_F_CPU0_SB_DQS_DN<9>")
	)
	(segment
		(start 293.148258 -275.112226)
		(end 293.998142 -275.96211)
		(width 0.16002)
		(layer "In11.Cu")
		(net "M_F_CPU0_SB_DQS_DN<9>")
	)
	(segment
		(start 324.823328 -270.32966)
		(end 325.32955 -270.32966)
		(width 0.09525)
		(layer "In11.Cu")
		(net "M_F_CPU0_SB_DQS_DN<9>")
	)
	(segment
		(start 278.21763 -275.96211)
		(end 278.645874 -275.96211)
		(width 0.16002)
		(layer "In11.Cu")
		(net "M_F_CPU0_SB_DQS_DN<9>")
	)
	(segment
		(start 284.929072 -275.112226)
		(end 285.778956 -275.96211)
		(width 0.16002)
		(layer "In11.Cu")
		(net "M_F_CPU0_SB_DQS_DN<9>")
	)
	(segment
		(start 286.611568 -274.769072)
		(end 286.771588 -274.609052)
		(width 0.16002)
		(layer "In11.Cu")
		(net "M_F_CPU0_SB_DQS_DN<9>")
	)
	(segment
		(start 278.982932 -274.456652)
		(end 279.142952 -274.296632)
		(width 0.16002)
		(layer "In11.Cu")
		(net "M_F_CPU0_SB_DQS_DN<9>")
	)
	(segment
		(start 296.796968 -276.306788)
		(end 297.4467 -276.306788)
		(width 0.16002)
		(layer "In11.Cu")
		(net "M_F_CPU0_SB_DQS_DN<9>")
	)
	(segment
		(start 331.63256 -271.330928)
		(end 331.640942 -271.326102)
		(width 0.09525)
		(layer "In11.Cu")
		(net "M_F_CPU0_SB_DQS_DN<9>")
	)
	(segment
		(start 289.902646 -276.306788)
		(end 290.728146 -275.481288)
		(width 0.16002)
		(layer "In11.Cu")
		(net "M_F_CPU0_SB_DQS_DN<9>")
	)
	(arc
		(start 329.752452 -271.330928)
		(mid 329.936227 -271.280156)
		(end 330.12126 -271.326102)
		(width 0.09525)
		(layer "In11.Cu")
		(net "M_F_CPU0_SB_DQS_DN<9>")
	)
	(arc
		(start 330.700888 -271.326102)
		(mid 330.88592 -271.280188)
		(end 331.069696 -271.330928)
		(width 0.09525)
		(layer "In11.Cu")
		(net "M_F_CPU0_SB_DQS_DN<9>")
	)
	(arc
		(start 332.00975 -271.330928)
		(mid 332.243294 -271.404634)
		(end 332.486 -271.371822)
		(width 0.09525)
		(layer "In11.Cu")
		(net "M_F_CPU0_SB_DQS_DN<9>")
	)
	(arc
		(start 329.189588 -271.330928)
		(mid 329.47102 -271.406683)
		(end 329.752452 -271.330928)
		(width 0.09525)
		(layer "In11.Cu")
		(net "M_F_CPU0_SB_DQS_DN<9>")
	)
	(arc
		(start 331.640942 -271.326102)
		(mid 331.825974 -271.280188)
		(end 332.00975 -271.330928)
		(width 0.09525)
		(layer "In11.Cu")
		(net "M_F_CPU0_SB_DQS_DN<9>")
	)
	(arc
		(start 327.591928 -271.406366)
		(mid 327.737358 -271.387164)
		(end 327.872852 -271.330928)
		(width 0.09525)
		(layer "In11.Cu")
		(net "M_F_CPU0_SB_DQS_DN<9>")
	)
	(arc
		(start 332.486 -271.371822)
		(mid 332.496199 -271.367985)
		(end 332.50632 -271.363948)
		(width 0.09525)
		(layer "In11.Cu")
		(net "M_F_CPU0_SB_DQS_DN<9>")
	)
	(arc
		(start 328.249788 -271.330928)
		(mid 328.53122 -271.406683)
		(end 328.812652 -271.330928)
		(width 0.09525)
		(layer "In11.Cu")
		(net "M_F_CPU0_SB_DQS_DN<9>")
	)
	(arc
		(start 328.812652 -271.330928)
		(mid 329.00112 -271.280251)
		(end 329.189588 -271.330928)
		(width 0.09525)
		(layer "In11.Cu")
		(net "M_F_CPU0_SB_DQS_DN<9>")
	)
	(arc
		(start 327.88479 -271.32407)
		(mid 328.068171 -271.280239)
		(end 328.249788 -271.330928)
		(width 0.09525)
		(layer "In11.Cu")
		(net "M_F_CPU0_SB_DQS_DN<9>")
	)
	(arc
		(start 330.129642 -271.330928)
		(mid 330.411074 -271.406683)
		(end 330.692506 -271.330928)
		(width 0.09525)
		(layer "In11.Cu")
		(net "M_F_CPU0_SB_DQS_DN<9>")
	)
	(arc
		(start 331.069696 -271.330928)
		(mid 331.351128 -271.406683)
		(end 331.63256 -271.330928)
		(width 0.09525)
		(layer "In11.Cu")
		(net "M_F_CPU0_SB_DQS_DN<9>")
	)
	(segment
		(start 334.167988 -290.83)
		(end 333.701136 -291.095938)
		(width 0.12954)
		(layer "F.Cu")
		(net "M_F_CPU0_SB_DQS_DN<8>")
	)
	(segment
		(start 267.576046 -314.058808)
		(end 267.741654 -313.8932)
		(width 0.16002)
		(layer "In11.Cu")
		(net "M_F_CPU0_SB_DQS_DN<8>")
	)
	(segment
		(start 283.98089 -314.207906)
		(end 286.341058 -314.207906)
		(width 0.16002)
		(layer "In11.Cu")
		(net "M_F_CPU0_SB_DQS_DN<8>")
	)
	(segment
		(start 333.85506 -291.361368)
		(end 333.701136 -291.095938)
		(width 0.09525)
		(layer "In11.Cu")
		(net "M_F_CPU0_SB_DQS_DN<8>")
	)
	(segment
		(start 325.632318 -295.850564)
		(end 325.632318 -293.635176)
		(width 0.09525)
		(layer "In11.Cu")
		(net "M_F_CPU0_SB_DQS_DN<8>")
	)
	(segment
		(start 291.170868 -313.85383)
		(end 291.524944 -314.207906)
		(width 0.16002)
		(layer "In11.Cu")
		(net "M_F_CPU0_SB_DQS_DN<8>")
	)
	(segment
		(start 298.714922 -313.85383)
		(end 299.068998 -314.207906)
		(width 0.16002)
		(layer "In11.Cu")
		(net "M_F_CPU0_SB_DQS_DN<8>")
	)
	(segment
		(start 330.692506 -291.421058)
		(end 330.700888 -291.425884)
		(width 0.09525)
		(layer "In11.Cu")
		(net "M_F_CPU0_SB_DQS_DN<8>")
	)
	(segment
		(start 270.187928 -314.099956)
		(end 270.667988 -314.099956)
		(width 0.16002)
		(layer "In11.Cu")
		(net "M_F_CPU0_SB_DQS_DN<8>")
	)
	(segment
		(start 331.63256 -291.421058)
		(end 331.640942 -291.425884)
		(width 0.09525)
		(layer "In11.Cu")
		(net "M_F_CPU0_SB_DQS_DN<8>")
	)
	(segment
		(start 325.243444 -296.155618)
		(end 325.327264 -296.155618)
		(width 0.09525)
		(layer "In11.Cu")
		(net "M_F_CPU0_SB_DQS_DN<8>")
	)
	(segment
		(start 286.341058 -314.207906)
		(end 287.191196 -315.058044)
		(width 0.16002)
		(layer "In11.Cu")
		(net "M_F_CPU0_SB_DQS_DN<8>")
	)
	(segment
		(start 296.800778 -314.738004)
		(end 297.278298 -314.738004)
		(width 0.16002)
		(layer "In11.Cu")
		(net "M_F_CPU0_SB_DQS_DN<8>")
	)
	(segment
		(start 288.936684 -315.058044)
		(end 289.256724 -314.738004)
		(width 0.16002)
		(layer "In11.Cu")
		(net "M_F_CPU0_SB_DQS_DN<8>")
	)
	(segment
		(start 325.22668 -296.172382)
		(end 325.243444 -296.155618)
		(width 0.09525)
		(layer "In11.Cu")
		(net "M_F_CPU0_SB_DQS_DN<8>")
	)
	(segment
		(start 268.927834 -314.239656)
		(end 270.048228 -314.239656)
		(width 0.16002)
		(layer "In11.Cu")
		(net "M_F_CPU0_SB_DQS_DN<8>")
	)
	(segment
		(start 289.734244 -314.738004)
		(end 290.618418 -313.85383)
		(width 0.16002)
		(layer "In11.Cu")
		(net "M_F_CPU0_SB_DQS_DN<8>")
	)
	(segment
		(start 301.429166 -314.207906)
		(end 301.959264 -314.738004)
		(width 0.16002)
		(layer "In11.Cu")
		(net "M_F_CPU0_SB_DQS_DN<8>")
	)
	(segment
		(start 275.53031 -313.85383)
		(end 276.08276 -313.85383)
		(width 0.16002)
		(layer "In11.Cu")
		(net "M_F_CPU0_SB_DQS_DN<8>")
	)
	(segment
		(start 270.807688 -314.239656)
		(end 271.317974 -314.239656)
		(width 0.16002)
		(layer "In11.Cu")
		(net "M_F_CPU0_SB_DQS_DN<8>")
	)
	(segment
		(start 301.959264 -314.738004)
		(end 304.822098 -314.738004)
		(width 0.16002)
		(layer "In11.Cu")
		(net "M_F_CPU0_SB_DQS_DN<8>")
	)
	(segment
		(start 270.048228 -314.239656)
		(end 270.187928 -314.099956)
		(width 0.16002)
		(layer "In11.Cu")
		(net "M_F_CPU0_SB_DQS_DN<8>")
	)
	(segment
		(start 274.646136 -314.738004)
		(end 275.53031 -313.85383)
		(width 0.16002)
		(layer "In11.Cu")
		(net "M_F_CPU0_SB_DQS_DN<8>")
	)
	(segment
		(start 267.741654 -313.8932)
		(end 268.581378 -313.8932)
		(width 0.16002)
		(layer "In11.Cu")
		(net "M_F_CPU0_SB_DQS_DN<8>")
	)
	(segment
		(start 333.831692 -291.448236)
		(end 333.85506 -291.361368)
		(width 0.09525)
		(layer "In11.Cu")
		(net "M_F_CPU0_SB_DQS_DN<8>")
	)
	(segment
		(start 305.706272 -313.85383)
		(end 307.545232 -313.85383)
		(width 0.16002)
		(layer "In11.Cu")
		(net "M_F_CPU0_SB_DQS_DN<8>")
	)
	(segment
		(start 325.327264 -296.155618)
		(end 325.632318 -295.850564)
		(width 0.09525)
		(layer "In11.Cu")
		(net "M_F_CPU0_SB_DQS_DN<8>")
	)
	(segment
		(start 278.797004 -314.207906)
		(end 279.647142 -315.058044)
		(width 0.16002)
		(layer "In11.Cu")
		(net "M_F_CPU0_SB_DQS_DN<8>")
	)
	(segment
		(start 289.256724 -314.738004)
		(end 289.734244 -314.738004)
		(width 0.16002)
		(layer "In11.Cu")
		(net "M_F_CPU0_SB_DQS_DN<8>")
	)
	(segment
		(start 270.667988 -314.099956)
		(end 270.807688 -314.239656)
		(width 0.16002)
		(layer "In11.Cu")
		(net "M_F_CPU0_SB_DQS_DN<8>")
	)
	(segment
		(start 290.618418 -313.85383)
		(end 291.170868 -313.85383)
		(width 0.16002)
		(layer "In11.Cu")
		(net "M_F_CPU0_SB_DQS_DN<8>")
	)
	(segment
		(start 283.074364 -313.85383)
		(end 283.626814 -313.85383)
		(width 0.16002)
		(layer "In11.Cu")
		(net "M_F_CPU0_SB_DQS_DN<8>")
	)
	(segment
		(start 276.436836 -314.207906)
		(end 278.797004 -314.207906)
		(width 0.16002)
		(layer "In11.Cu")
		(net "M_F_CPU0_SB_DQS_DN<8>")
	)
	(segment
		(start 268.581378 -313.8932)
		(end 268.927834 -314.239656)
		(width 0.16002)
		(layer "In11.Cu")
		(net "M_F_CPU0_SB_DQS_DN<8>")
	)
	(segment
		(start 296.480738 -315.058044)
		(end 296.800778 -314.738004)
		(width 0.16002)
		(layer "In11.Cu")
		(net "M_F_CPU0_SB_DQS_DN<8>")
	)
	(segment
		(start 327.970642 -291.472366)
		(end 328.061066 -291.472366)
		(width 0.09525)
		(layer "In11.Cu")
		(net "M_F_CPU0_SB_DQS_DN<8>")
	)
	(segment
		(start 273.848576 -315.058044)
		(end 274.168616 -314.738004)
		(width 0.16002)
		(layer "In11.Cu")
		(net "M_F_CPU0_SB_DQS_DN<8>")
	)
	(segment
		(start 282.19019 -314.738004)
		(end 283.074364 -313.85383)
		(width 0.16002)
		(layer "In11.Cu")
		(net "M_F_CPU0_SB_DQS_DN<8>")
	)
	(segment
		(start 327.670922 -291.596572)
		(end 327.970642 -291.472366)
		(width 0.09525)
		(layer "In11.Cu")
		(net "M_F_CPU0_SB_DQS_DN<8>")
	)
	(segment
		(start 304.822098 -314.738004)
		(end 305.706272 -313.85383)
		(width 0.16002)
		(layer "In11.Cu")
		(net "M_F_CPU0_SB_DQS_DN<8>")
	)
	(segment
		(start 267.015722 -314.058808)
		(end 267.576046 -314.058808)
		(width 0.16002)
		(layer "In11.Cu")
		(net "M_F_CPU0_SB_DQS_DN<8>")
	)
	(segment
		(start 283.626814 -313.85383)
		(end 283.98089 -314.207906)
		(width 0.16002)
		(layer "In11.Cu")
		(net "M_F_CPU0_SB_DQS_DN<8>")
	)
	(segment
		(start 266.898882 -313.941968)
		(end 267.015722 -314.058808)
		(width 0.16002)
		(layer "In11.Cu")
		(net "M_F_CPU0_SB_DQS_DN<8>")
	)
	(segment
		(start 266.418822 -313.941968)
		(end 266.898882 -313.941968)
		(width 0.16002)
		(layer "In11.Cu")
		(net "M_F_CPU0_SB_DQS_DN<8>")
	)
	(segment
		(start 330.12126 -291.425884)
		(end 330.129642 -291.421058)
		(width 0.09525)
		(layer "In11.Cu")
		(net "M_F_CPU0_SB_DQS_DN<8>")
	)
	(segment
		(start 298.162472 -313.85383)
		(end 298.714922 -313.85383)
		(width 0.16002)
		(layer "In11.Cu")
		(net "M_F_CPU0_SB_DQS_DN<8>")
	)
	(segment
		(start 265.54811 -313.784996)
		(end 265.821922 -314.058808)
		(width 0.16002)
		(layer "In11.Cu")
		(net "M_F_CPU0_SB_DQS_DN<8>")
	)
	(segment
		(start 276.08276 -313.85383)
		(end 276.436836 -314.207906)
		(width 0.16002)
		(layer "In11.Cu")
		(net "M_F_CPU0_SB_DQS_DN<8>")
	)
	(segment
		(start 307.545232 -313.85383)
		(end 325.22668 -296.172382)
		(width 0.16002)
		(layer "In11.Cu")
		(net "M_F_CPU0_SB_DQS_DN<8>")
	)
	(segment
		(start 325.632318 -293.635176)
		(end 327.670922 -291.596572)
		(width 0.09525)
		(layer "In11.Cu")
		(net "M_F_CPU0_SB_DQS_DN<8>")
	)
	(segment
		(start 299.068998 -314.207906)
		(end 301.429166 -314.207906)
		(width 0.16002)
		(layer "In11.Cu")
		(net "M_F_CPU0_SB_DQS_DN<8>")
	)
	(segment
		(start 297.278298 -314.738004)
		(end 298.162472 -313.85383)
		(width 0.16002)
		(layer "In11.Cu")
		(net "M_F_CPU0_SB_DQS_DN<8>")
	)
	(segment
		(start 279.647142 -315.058044)
		(end 281.39263 -315.058044)
		(width 0.16002)
		(layer "In11.Cu")
		(net "M_F_CPU0_SB_DQS_DN<8>")
	)
	(segment
		(start 266.301982 -314.058808)
		(end 266.418822 -313.941968)
		(width 0.16002)
		(layer "In11.Cu")
		(net "M_F_CPU0_SB_DQS_DN<8>")
	)
	(segment
		(start 274.168616 -314.738004)
		(end 274.646136 -314.738004)
		(width 0.16002)
		(layer "In11.Cu")
		(net "M_F_CPU0_SB_DQS_DN<8>")
	)
	(segment
		(start 272.136362 -315.058044)
		(end 273.848576 -315.058044)
		(width 0.16002)
		(layer "In11.Cu")
		(net "M_F_CPU0_SB_DQS_DN<8>")
	)
	(segment
		(start 271.317974 -314.239656)
		(end 272.136362 -315.058044)
		(width 0.16002)
		(layer "In11.Cu")
		(net "M_F_CPU0_SB_DQS_DN<8>")
	)
	(segment
		(start 281.71267 -314.738004)
		(end 282.19019 -314.738004)
		(width 0.16002)
		(layer "In11.Cu")
		(net "M_F_CPU0_SB_DQS_DN<8>")
	)
	(segment
		(start 291.524944 -314.207906)
		(end 293.885112 -314.207906)
		(width 0.16002)
		(layer "In11.Cu")
		(net "M_F_CPU0_SB_DQS_DN<8>")
	)
	(segment
		(start 281.39263 -315.058044)
		(end 281.71267 -314.738004)
		(width 0.16002)
		(layer "In11.Cu")
		(net "M_F_CPU0_SB_DQS_DN<8>")
	)
	(segment
		(start 294.73525 -315.058044)
		(end 296.480738 -315.058044)
		(width 0.16002)
		(layer "In11.Cu")
		(net "M_F_CPU0_SB_DQS_DN<8>")
	)
	(segment
		(start 287.191196 -315.058044)
		(end 288.936684 -315.058044)
		(width 0.16002)
		(layer "In11.Cu")
		(net "M_F_CPU0_SB_DQS_DN<8>")
	)
	(segment
		(start 293.885112 -314.207906)
		(end 294.73525 -315.058044)
		(width 0.16002)
		(layer "In11.Cu")
		(net "M_F_CPU0_SB_DQS_DN<8>")
	)
	(segment
		(start 265.821922 -314.058808)
		(end 266.301982 -314.058808)
		(width 0.16002)
		(layer "In11.Cu")
		(net "M_F_CPU0_SB_DQS_DN<8>")
	)
	(arc
		(start 332.00975 -291.421058)
		(mid 332.291182 -291.345303)
		(end 332.572614 -291.421058)
		(width 0.09525)
		(layer "In11.Cu")
		(net "M_F_CPU0_SB_DQS_DN<8>")
	)
	(arc
		(start 329.752452 -291.421058)
		(mid 329.936227 -291.47183)
		(end 330.12126 -291.425884)
		(width 0.09525)
		(layer "In11.Cu")
		(net "M_F_CPU0_SB_DQS_DN<8>")
	)
	(arc
		(start 331.640942 -291.425884)
		(mid 331.825974 -291.471798)
		(end 332.00975 -291.421058)
		(width 0.09525)
		(layer "In11.Cu")
		(net "M_F_CPU0_SB_DQS_DN<8>")
	)
	(arc
		(start 331.069696 -291.421058)
		(mid 331.351128 -291.345303)
		(end 331.63256 -291.421058)
		(width 0.09525)
		(layer "In11.Cu")
		(net "M_F_CPU0_SB_DQS_DN<8>")
	)
	(arc
		(start 332.572614 -291.421058)
		(mid 332.761082 -291.471735)
		(end 332.94955 -291.421058)
		(width 0.09525)
		(layer "In11.Cu")
		(net "M_F_CPU0_SB_DQS_DN<8>")
	)
	(arc
		(start 328.061066 -291.472366)
		(mid 328.158812 -291.459171)
		(end 328.249788 -291.421058)
		(width 0.09525)
		(layer "In11.Cu")
		(net "M_F_CPU0_SB_DQS_DN<8>")
	)
	(arc
		(start 330.700888 -291.425884)
		(mid 330.88592 -291.471798)
		(end 331.069696 -291.421058)
		(width 0.09525)
		(layer "In11.Cu")
		(net "M_F_CPU0_SB_DQS_DN<8>")
	)
	(arc
		(start 329.189588 -291.421058)
		(mid 329.47102 -291.345303)
		(end 329.752452 -291.421058)
		(width 0.09525)
		(layer "In11.Cu")
		(net "M_F_CPU0_SB_DQS_DN<8>")
	)
	(arc
		(start 328.249788 -291.421058)
		(mid 328.53122 -291.345303)
		(end 328.812652 -291.421058)
		(width 0.09525)
		(layer "In11.Cu")
		(net "M_F_CPU0_SB_DQS_DN<8>")
	)
	(arc
		(start 332.94955 -291.421058)
		(mid 333.230982 -291.345303)
		(end 333.512414 -291.421058)
		(width 0.09525)
		(layer "In11.Cu")
		(net "M_F_CPU0_SB_DQS_DN<8>")
	)
	(arc
		(start 333.512414 -291.421058)
		(mid 333.669012 -291.470347)
		(end 333.831692 -291.448236)
		(width 0.09525)
		(layer "In11.Cu")
		(net "M_F_CPU0_SB_DQS_DN<8>")
	)
	(arc
		(start 330.129642 -291.421058)
		(mid 330.411074 -291.345303)
		(end 330.692506 -291.421058)
		(width 0.09525)
		(layer "In11.Cu")
		(net "M_F_CPU0_SB_DQS_DN<8>")
	)
	(arc
		(start 328.812652 -291.421058)
		(mid 329.00112 -291.471735)
		(end 329.189588 -291.421058)
		(width 0.09525)
		(layer "In11.Cu")
		(net "M_F_CPU0_SB_DQS_DN<8>")
	)
	(segment
		(start 334.167988 -285.970218)
		(end 333.701136 -286.236156)
		(width 0.12954)
		(layer "F.Cu")
		(net "M_F_CPU0_SB_DQS_DN<7>")
	)
	(segment
		(start 326.93229 -286.561022)
		(end 326.926702 -286.55772)
		(width 0.09525)
		(layer "In11.Cu")
		(net "M_F_CPU0_SB_DQS_DN<7>")
	)
	(segment
		(start 274.646136 -305.38801)
		(end 274.168616 -305.38801)
		(width 0.16002)
		(layer "In11.Cu")
		(net "M_F_CPU0_SB_DQS_DN<7>")
	)
	(segment
		(start 325.97471 -286.929322)
		(end 324.750684 -286.929322)
		(width 0.09525)
		(layer "In11.Cu")
		(net "M_F_CPU0_SB_DQS_DN<7>")
	)
	(segment
		(start 291.524944 -304.857912)
		(end 291.170868 -304.503836)
		(width 0.16002)
		(layer "In11.Cu")
		(net "M_F_CPU0_SB_DQS_DN<7>")
	)
	(segment
		(start 298.714922 -304.503836)
		(end 298.162472 -304.503836)
		(width 0.16002)
		(layer "In11.Cu")
		(net "M_F_CPU0_SB_DQS_DN<7>")
	)
	(segment
		(start 281.71267 -305.38801)
		(end 281.39263 -305.70805)
		(width 0.16002)
		(layer "In11.Cu")
		(net "M_F_CPU0_SB_DQS_DN<7>")
	)
	(segment
		(start 301.429166 -304.857912)
		(end 299.068998 -304.857912)
		(width 0.16002)
		(layer "In11.Cu")
		(net "M_F_CPU0_SB_DQS_DN<7>")
	)
	(segment
		(start 326.943212 -286.567372)
		(end 326.93229 -286.561022)
		(width 0.09525)
		(layer "In11.Cu")
		(net "M_F_CPU0_SB_DQS_DN<7>")
	)
	(segment
		(start 276.436836 -304.857912)
		(end 276.08276 -304.503836)
		(width 0.16002)
		(layer "In11.Cu")
		(net "M_F_CPU0_SB_DQS_DN<7>")
	)
	(segment
		(start 307.091334 -304.503836)
		(end 305.706272 -304.503836)
		(width 0.16002)
		(layer "In11.Cu")
		(net "M_F_CPU0_SB_DQS_DN<7>")
	)
	(segment
		(start 273.848576 -305.70805)
		(end 272.136362 -305.70805)
		(width 0.16002)
		(layer "In11.Cu")
		(net "M_F_CPU0_SB_DQS_DN<7>")
	)
	(segment
		(start 267.089128 -304.708814)
		(end 266.972288 -304.591974)
		(width 0.16002)
		(layer "In11.Cu")
		(net "M_F_CPU0_SB_DQS_DN<7>")
	)
	(segment
		(start 276.08276 -304.503836)
		(end 275.53031 -304.503836)
		(width 0.16002)
		(layer "In11.Cu")
		(net "M_F_CPU0_SB_DQS_DN<7>")
	)
	(segment
		(start 333.85506 -286.501586)
		(end 333.831692 -286.588454)
		(width 0.09525)
		(layer "In11.Cu")
		(net "M_F_CPU0_SB_DQS_DN<7>")
	)
	(segment
		(start 296.800778 -305.38801)
		(end 296.480738 -305.70805)
		(width 0.16002)
		(layer "In11.Cu")
		(net "M_F_CPU0_SB_DQS_DN<7>")
	)
	(segment
		(start 288.936684 -305.70805)
		(end 287.191196 -305.70805)
		(width 0.16002)
		(layer "In11.Cu")
		(net "M_F_CPU0_SB_DQS_DN<7>")
	)
	(segment
		(start 326.254618 -286.649414)
		(end 325.97471 -286.929322)
		(width 0.09525)
		(layer "In11.Cu")
		(net "M_F_CPU0_SB_DQS_DN<7>")
	)
	(segment
		(start 272.136362 -305.70805)
		(end 271.317974 -304.889662)
		(width 0.16002)
		(layer "In11.Cu")
		(net "M_F_CPU0_SB_DQS_DN<7>")
	)
	(segment
		(start 296.480738 -305.70805)
		(end 294.73525 -305.70805)
		(width 0.16002)
		(layer "In11.Cu")
		(net "M_F_CPU0_SB_DQS_DN<7>")
	)
	(segment
		(start 266.375388 -304.708814)
		(end 265.821922 -304.708814)
		(width 0.16002)
		(layer "In11.Cu")
		(net "M_F_CPU0_SB_DQS_DN<7>")
	)
	(segment
		(start 282.19019 -305.38801)
		(end 281.71267 -305.38801)
		(width 0.16002)
		(layer "In11.Cu")
		(net "M_F_CPU0_SB_DQS_DN<7>")
	)
	(segment
		(start 267.576046 -304.708814)
		(end 267.089128 -304.708814)
		(width 0.16002)
		(layer "In11.Cu")
		(net "M_F_CPU0_SB_DQS_DN<7>")
	)
	(segment
		(start 298.162472 -304.503836)
		(end 297.278298 -305.38801)
		(width 0.16002)
		(layer "In11.Cu")
		(net "M_F_CPU0_SB_DQS_DN<7>")
	)
	(segment
		(start 327.31964 -286.55518)
		(end 327.309226 -286.561276)
		(width 0.09525)
		(layer "In11.Cu")
		(net "M_F_CPU0_SB_DQS_DN<7>")
	)
	(segment
		(start 315.493146 -296.102024)
		(end 307.091334 -304.503836)
		(width 0.16002)
		(layer "In11.Cu")
		(net "M_F_CPU0_SB_DQS_DN<7>")
	)
	(segment
		(start 305.706272 -304.503836)
		(end 304.822098 -305.38801)
		(width 0.16002)
		(layer "In11.Cu")
		(net "M_F_CPU0_SB_DQS_DN<7>")
	)
	(segment
		(start 315.493146 -296.10177)
		(end 315.493146 -296.102024)
		(width 0.16002)
		(layer "In11.Cu")
		(net "M_F_CPU0_SB_DQS_DN<7>")
	)
	(segment
		(start 283.98089 -304.857912)
		(end 283.626814 -304.503836)
		(width 0.16002)
		(layer "In11.Cu")
		(net "M_F_CPU0_SB_DQS_DN<7>")
	)
	(segment
		(start 290.618418 -304.503836)
		(end 289.734244 -305.38801)
		(width 0.16002)
		(layer "In11.Cu")
		(net "M_F_CPU0_SB_DQS_DN<7>")
	)
	(segment
		(start 270.721074 -304.772822)
		(end 270.241014 -304.772822)
		(width 0.16002)
		(layer "In11.Cu")
		(net "M_F_CPU0_SB_DQS_DN<7>")
	)
	(segment
		(start 294.73525 -305.70805)
		(end 293.885112 -304.857912)
		(width 0.16002)
		(layer "In11.Cu")
		(net "M_F_CPU0_SB_DQS_DN<7>")
	)
	(segment
		(start 291.170868 -304.503836)
		(end 290.618418 -304.503836)
		(width 0.16002)
		(layer "In11.Cu")
		(net "M_F_CPU0_SB_DQS_DN<7>")
	)
	(segment
		(start 267.741654 -304.543206)
		(end 267.576046 -304.708814)
		(width 0.16002)
		(layer "In11.Cu")
		(net "M_F_CPU0_SB_DQS_DN<7>")
	)
	(segment
		(start 265.821922 -304.708814)
		(end 265.54811 -304.435002)
		(width 0.16002)
		(layer "In11.Cu")
		(net "M_F_CPU0_SB_DQS_DN<7>")
	)
	(segment
		(start 278.797004 -304.857912)
		(end 276.436836 -304.857912)
		(width 0.16002)
		(layer "In11.Cu")
		(net "M_F_CPU0_SB_DQS_DN<7>")
	)
	(segment
		(start 326.254872 -286.648906)
		(end 326.254618 -286.649414)
		(width 0.09525)
		(layer "In11.Cu")
		(net "M_F_CPU0_SB_DQS_DN<7>")
	)
	(segment
		(start 287.191196 -305.70805)
		(end 286.341058 -304.857912)
		(width 0.16002)
		(layer "In11.Cu")
		(net "M_F_CPU0_SB_DQS_DN<7>")
	)
	(segment
		(start 268.581378 -304.543206)
		(end 267.741654 -304.543206)
		(width 0.16002)
		(layer "In11.Cu")
		(net "M_F_CPU0_SB_DQS_DN<7>")
	)
	(segment
		(start 283.074364 -304.503836)
		(end 282.19019 -305.38801)
		(width 0.16002)
		(layer "In11.Cu")
		(net "M_F_CPU0_SB_DQS_DN<7>")
	)
	(segment
		(start 304.822098 -305.38801)
		(end 301.959264 -305.38801)
		(width 0.16002)
		(layer "In11.Cu")
		(net "M_F_CPU0_SB_DQS_DN<7>")
	)
	(segment
		(start 270.124174 -304.889662)
		(end 268.927834 -304.889662)
		(width 0.16002)
		(layer "In11.Cu")
		(net "M_F_CPU0_SB_DQS_DN<7>")
	)
	(segment
		(start 333.701136 -286.236156)
		(end 333.85506 -286.501586)
		(width 0.09525)
		(layer "In11.Cu")
		(net "M_F_CPU0_SB_DQS_DN<7>")
	)
	(segment
		(start 299.068998 -304.857912)
		(end 298.714922 -304.503836)
		(width 0.16002)
		(layer "In11.Cu")
		(net "M_F_CPU0_SB_DQS_DN<7>")
	)
	(segment
		(start 323.99605 -287.682686)
		(end 323.912738 -287.682178)
		(width 0.09525)
		(layer "In11.Cu")
		(net "M_F_CPU0_SB_DQS_DN<7>")
	)
	(segment
		(start 323.912738 -287.682178)
		(end 323.895974 -287.698942)
		(width 0.09525)
		(layer "In11.Cu")
		(net "M_F_CPU0_SB_DQS_DN<7>")
	)
	(segment
		(start 297.278298 -305.38801)
		(end 296.800778 -305.38801)
		(width 0.16002)
		(layer "In11.Cu")
		(net "M_F_CPU0_SB_DQS_DN<7>")
	)
	(segment
		(start 274.168616 -305.38801)
		(end 273.848576 -305.70805)
		(width 0.16002)
		(layer "In11.Cu")
		(net "M_F_CPU0_SB_DQS_DN<7>")
	)
	(segment
		(start 331.640942 -286.566102)
		(end 331.63256 -286.561276)
		(width 0.09525)
		(layer "In11.Cu")
		(net "M_F_CPU0_SB_DQS_DN<7>")
	)
	(segment
		(start 301.959264 -305.38801)
		(end 301.429166 -304.857912)
		(width 0.16002)
		(layer "In11.Cu")
		(net "M_F_CPU0_SB_DQS_DN<7>")
	)
	(segment
		(start 270.241014 -304.772822)
		(end 270.124174 -304.889662)
		(width 0.16002)
		(layer "In11.Cu")
		(net "M_F_CPU0_SB_DQS_DN<7>")
	)
	(segment
		(start 275.53031 -304.503836)
		(end 274.646136 -305.38801)
		(width 0.16002)
		(layer "In11.Cu")
		(net "M_F_CPU0_SB_DQS_DN<7>")
	)
	(segment
		(start 268.927834 -304.889662)
		(end 268.581378 -304.543206)
		(width 0.16002)
		(layer "In11.Cu")
		(net "M_F_CPU0_SB_DQS_DN<7>")
	)
	(segment
		(start 266.492228 -304.591974)
		(end 266.375388 -304.708814)
		(width 0.16002)
		(layer "In11.Cu")
		(net "M_F_CPU0_SB_DQS_DN<7>")
	)
	(segment
		(start 330.700888 -286.566102)
		(end 330.692506 -286.561276)
		(width 0.09525)
		(layer "In11.Cu")
		(net "M_F_CPU0_SB_DQS_DN<7>")
	)
	(segment
		(start 271.317974 -304.889662)
		(end 270.837914 -304.889662)
		(width 0.16002)
		(layer "In11.Cu")
		(net "M_F_CPU0_SB_DQS_DN<7>")
	)
	(segment
		(start 323.895974 -287.698942)
		(end 315.493146 -296.10177)
		(width 0.16002)
		(layer "In11.Cu")
		(net "M_F_CPU0_SB_DQS_DN<7>")
	)
	(segment
		(start 293.885112 -304.857912)
		(end 291.524944 -304.857912)
		(width 0.16002)
		(layer "In11.Cu")
		(net "M_F_CPU0_SB_DQS_DN<7>")
	)
	(segment
		(start 270.837914 -304.889662)
		(end 270.721074 -304.772822)
		(width 0.16002)
		(layer "In11.Cu")
		(net "M_F_CPU0_SB_DQS_DN<7>")
	)
	(segment
		(start 324.750684 -286.929322)
		(end 323.99605 -287.682686)
		(width 0.09525)
		(layer "In11.Cu")
		(net "M_F_CPU0_SB_DQS_DN<7>")
	)
	(segment
		(start 266.972288 -304.591974)
		(end 266.492228 -304.591974)
		(width 0.16002)
		(layer "In11.Cu")
		(net "M_F_CPU0_SB_DQS_DN<7>")
	)
	(segment
		(start 283.626814 -304.503836)
		(end 283.074364 -304.503836)
		(width 0.16002)
		(layer "In11.Cu")
		(net "M_F_CPU0_SB_DQS_DN<7>")
	)
	(segment
		(start 289.256724 -305.38801)
		(end 288.936684 -305.70805)
		(width 0.16002)
		(layer "In11.Cu")
		(net "M_F_CPU0_SB_DQS_DN<7>")
	)
	(segment
		(start 279.647142 -305.70805)
		(end 278.797004 -304.857912)
		(width 0.16002)
		(layer "In11.Cu")
		(net "M_F_CPU0_SB_DQS_DN<7>")
	)
	(segment
		(start 281.39263 -305.70805)
		(end 279.647142 -305.70805)
		(width 0.16002)
		(layer "In11.Cu")
		(net "M_F_CPU0_SB_DQS_DN<7>")
	)
	(segment
		(start 330.129642 -286.561276)
		(end 330.12126 -286.566102)
		(width 0.09525)
		(layer "In11.Cu")
		(net "M_F_CPU0_SB_DQS_DN<7>")
	)
	(segment
		(start 286.341058 -304.857912)
		(end 283.98089 -304.857912)
		(width 0.16002)
		(layer "In11.Cu")
		(net "M_F_CPU0_SB_DQS_DN<7>")
	)
	(segment
		(start 289.734244 -305.38801)
		(end 289.256724 -305.38801)
		(width 0.16002)
		(layer "In11.Cu")
		(net "M_F_CPU0_SB_DQS_DN<7>")
	)
	(arc
		(start 326.331834 -286.585152)
		(mid 326.291935 -286.615316)
		(end 326.254872 -286.648906)
		(width 0.09525)
		(layer "In11.Cu")
		(net "M_F_CPU0_SB_DQS_DN<7>")
	)
	(arc
		(start 326.369426 -286.561276)
		(mid 326.350393 -286.572841)
		(end 326.331834 -286.585152)
		(width 0.09525)
		(layer "In11.Cu")
		(net "M_F_CPU0_SB_DQS_DN<7>")
	)
	(arc
		(start 333.512414 -286.561276)
		(mid 333.230982 -286.485487)
		(end 332.94955 -286.561276)
		(width 0.09525)
		(layer "In11.Cu")
		(net "M_F_CPU0_SB_DQS_DN<7>")
	)
	(arc
		(start 328.812652 -286.561276)
		(mid 328.53122 -286.485487)
		(end 328.249788 -286.561276)
		(width 0.09525)
		(layer "In11.Cu")
		(net "M_F_CPU0_SB_DQS_DN<7>")
	)
	(arc
		(start 332.00975 -286.561276)
		(mid 331.825975 -286.612048)
		(end 331.640942 -286.566102)
		(width 0.09525)
		(layer "In11.Cu")
		(net "M_F_CPU0_SB_DQS_DN<7>")
	)
	(arc
		(start 326.926702 -286.55772)
		(mid 326.647583 -286.485315)
		(end 326.369426 -286.561276)
		(width 0.09525)
		(layer "In11.Cu")
		(net "M_F_CPU0_SB_DQS_DN<7>")
	)
	(arc
		(start 330.692506 -286.561276)
		(mid 330.411074 -286.485487)
		(end 330.129642 -286.561276)
		(width 0.09525)
		(layer "In11.Cu")
		(net "M_F_CPU0_SB_DQS_DN<7>")
	)
	(arc
		(start 332.94955 -286.561276)
		(mid 332.761082 -286.611953)
		(end 332.572614 -286.561276)
		(width 0.09525)
		(layer "In11.Cu")
		(net "M_F_CPU0_SB_DQS_DN<7>")
	)
	(arc
		(start 329.189588 -286.561276)
		(mid 329.00112 -286.611953)
		(end 328.812652 -286.561276)
		(width 0.09525)
		(layer "In11.Cu")
		(net "M_F_CPU0_SB_DQS_DN<7>")
	)
	(arc
		(start 331.63256 -286.561276)
		(mid 331.351128 -286.485487)
		(end 331.069696 -286.561276)
		(width 0.09525)
		(layer "In11.Cu")
		(net "M_F_CPU0_SB_DQS_DN<7>")
	)
	(arc
		(start 328.249788 -286.561276)
		(mid 328.061066 -286.61208)
		(end 327.872344 -286.561276)
		(width 0.09525)
		(layer "In11.Cu")
		(net "M_F_CPU0_SB_DQS_DN<7>")
	)
	(arc
		(start 332.572614 -286.561276)
		(mid 332.291182 -286.485487)
		(end 332.00975 -286.561276)
		(width 0.09525)
		(layer "In11.Cu")
		(net "M_F_CPU0_SB_DQS_DN<7>")
	)
	(arc
		(start 329.752452 -286.561276)
		(mid 329.47102 -286.485487)
		(end 329.189588 -286.561276)
		(width 0.09525)
		(layer "In11.Cu")
		(net "M_F_CPU0_SB_DQS_DN<7>")
	)
	(arc
		(start 333.831692 -286.588454)
		(mid 333.66901 -286.610586)
		(end 333.512414 -286.561276)
		(width 0.09525)
		(layer "In11.Cu")
		(net "M_F_CPU0_SB_DQS_DN<7>")
	)
	(arc
		(start 327.309226 -286.561276)
		(mid 327.127012 -286.611901)
		(end 326.943212 -286.567372)
		(width 0.09525)
		(layer "In11.Cu")
		(net "M_F_CPU0_SB_DQS_DN<7>")
	)
	(arc
		(start 330.12126 -286.566102)
		(mid 329.936228 -286.612016)
		(end 329.752452 -286.561276)
		(width 0.09525)
		(layer "In11.Cu")
		(net "M_F_CPU0_SB_DQS_DN<7>")
	)
	(arc
		(start 331.069696 -286.561276)
		(mid 330.885921 -286.612048)
		(end 330.700888 -286.566102)
		(width 0.09525)
		(layer "In11.Cu")
		(net "M_F_CPU0_SB_DQS_DN<7>")
	)
	(arc
		(start 327.872344 -286.561276)
		(mid 327.596801 -286.485393)
		(end 327.31964 -286.55518)
		(width 0.09525)
		(layer "In11.Cu")
		(net "M_F_CPU0_SB_DQS_DN<7>")
	)
	(segment
		(start 334.167988 -281.110182)
		(end 333.701136 -281.37612)
		(width 0.12954)
		(layer "F.Cu")
		(net "M_F_CPU0_SB_DQS_DN<6>")
	)
	(segment
		(start 301.429166 -295.507918)
		(end 301.959264 -296.038016)
		(width 0.16002)
		(layer "In11.Cu")
		(net "M_F_CPU0_SB_DQS_DN<6>")
	)
	(segment
		(start 331.63256 -281.70124)
		(end 331.640942 -281.706066)
		(width 0.09525)
		(layer "In11.Cu")
		(net "M_F_CPU0_SB_DQS_DN<6>")
	)
	(segment
		(start 323.895974 -281.67203)
		(end 323.919596 -281.67203)
		(width 0.09525)
		(layer "In11.Cu")
		(net "M_F_CPU0_SB_DQS_DN<6>")
	)
	(segment
		(start 286.341058 -295.507918)
		(end 287.191196 -296.358056)
		(width 0.16002)
		(layer "In11.Cu")
		(net "M_F_CPU0_SB_DQS_DN<6>")
	)
	(segment
		(start 333.85506 -281.64155)
		(end 333.701136 -281.37612)
		(width 0.09525)
		(layer "In11.Cu")
		(net "M_F_CPU0_SB_DQS_DN<6>")
	)
	(segment
		(start 283.98089 -295.507918)
		(end 286.341058 -295.507918)
		(width 0.16002)
		(layer "In11.Cu")
		(net "M_F_CPU0_SB_DQS_DN<6>")
	)
	(segment
		(start 289.256724 -296.038016)
		(end 289.734244 -296.038016)
		(width 0.16002)
		(layer "In11.Cu")
		(net "M_F_CPU0_SB_DQS_DN<6>")
	)
	(segment
		(start 288.936684 -296.358056)
		(end 289.256724 -296.038016)
		(width 0.16002)
		(layer "In11.Cu")
		(net "M_F_CPU0_SB_DQS_DN<6>")
	)
	(segment
		(start 268.581378 -295.193212)
		(end 268.927834 -295.539668)
		(width 0.16002)
		(layer "In11.Cu")
		(net "M_F_CPU0_SB_DQS_DN<6>")
	)
	(segment
		(start 298.162472 -295.153842)
		(end 298.714922 -295.153842)
		(width 0.16002)
		(layer "In11.Cu")
		(net "M_F_CPU0_SB_DQS_DN<6>")
	)
	(segment
		(start 265.54811 -295.085008)
		(end 265.821922 -295.35882)
		(width 0.16002)
		(layer "In11.Cu")
		(net "M_F_CPU0_SB_DQS_DN<6>")
	)
	(segment
		(start 273.848576 -296.358056)
		(end 274.168616 -296.038016)
		(width 0.16002)
		(layer "In11.Cu")
		(net "M_F_CPU0_SB_DQS_DN<6>")
	)
	(segment
		(start 299.068998 -295.507918)
		(end 301.429166 -295.507918)
		(width 0.16002)
		(layer "In11.Cu")
		(net "M_F_CPU0_SB_DQS_DN<6>")
	)
	(segment
		(start 330.692506 -281.70124)
		(end 330.700888 -281.706066)
		(width 0.09525)
		(layer "In11.Cu")
		(net "M_F_CPU0_SB_DQS_DN<6>")
	)
	(segment
		(start 268.927834 -295.539668)
		(end 271.317974 -295.539668)
		(width 0.16002)
		(layer "In11.Cu")
		(net "M_F_CPU0_SB_DQS_DN<6>")
	)
	(segment
		(start 290.618418 -295.153842)
		(end 291.170868 -295.153842)
		(width 0.16002)
		(layer "In11.Cu")
		(net "M_F_CPU0_SB_DQS_DN<6>")
	)
	(segment
		(start 325.169276 -281.731212)
		(end 325.356728 -281.54376)
		(width 0.09525)
		(layer "In11.Cu")
		(net "M_F_CPU0_SB_DQS_DN<6>")
	)
	(segment
		(start 330.12126 -281.706066)
		(end 330.129642 -281.70124)
		(width 0.09525)
		(layer "In11.Cu")
		(net "M_F_CPU0_SB_DQS_DN<6>")
	)
	(segment
		(start 304.822098 -296.038016)
		(end 305.706272 -295.153842)
		(width 0.16002)
		(layer "In11.Cu")
		(net "M_F_CPU0_SB_DQS_DN<6>")
	)
	(segment
		(start 271.317974 -295.539668)
		(end 272.136362 -296.358056)
		(width 0.16002)
		(layer "In11.Cu")
		(net "M_F_CPU0_SB_DQS_DN<6>")
	)
	(segment
		(start 276.436836 -295.507918)
		(end 278.797004 -295.507918)
		(width 0.16002)
		(layer "In11.Cu")
		(net "M_F_CPU0_SB_DQS_DN<6>")
	)
	(segment
		(start 275.53031 -295.153842)
		(end 276.08276 -295.153842)
		(width 0.16002)
		(layer "In11.Cu")
		(net "M_F_CPU0_SB_DQS_DN<6>")
	)
	(segment
		(start 327.696322 -281.54376)
		(end 327.794874 -281.642312)
		(width 0.09525)
		(layer "In11.Cu")
		(net "M_F_CPU0_SB_DQS_DN<6>")
	)
	(segment
		(start 296.800778 -296.038016)
		(end 297.278298 -296.038016)
		(width 0.16002)
		(layer "In11.Cu")
		(net "M_F_CPU0_SB_DQS_DN<6>")
	)
	(segment
		(start 294.73525 -296.358056)
		(end 296.480738 -296.358056)
		(width 0.16002)
		(layer "In11.Cu")
		(net "M_F_CPU0_SB_DQS_DN<6>")
	)
	(segment
		(start 281.39263 -296.358056)
		(end 281.71267 -296.038016)
		(width 0.16002)
		(layer "In11.Cu")
		(net "M_F_CPU0_SB_DQS_DN<6>")
	)
	(segment
		(start 323.919596 -281.67203)
		(end 323.978778 -281.731212)
		(width 0.09525)
		(layer "In11.Cu")
		(net "M_F_CPU0_SB_DQS_DN<6>")
	)
	(segment
		(start 291.170868 -295.153842)
		(end 291.524944 -295.507918)
		(width 0.16002)
		(layer "In11.Cu")
		(net "M_F_CPU0_SB_DQS_DN<6>")
	)
	(segment
		(start 267.741654 -295.193212)
		(end 268.581378 -295.193212)
		(width 0.16002)
		(layer "In11.Cu")
		(net "M_F_CPU0_SB_DQS_DN<6>")
	)
	(segment
		(start 305.706272 -295.153842)
		(end 307.645816 -295.153842)
		(width 0.16002)
		(layer "In11.Cu")
		(net "M_F_CPU0_SB_DQS_DN<6>")
	)
	(segment
		(start 266.499086 -295.24198)
		(end 266.979146 -295.24198)
		(width 0.16002)
		(layer "In11.Cu")
		(net "M_F_CPU0_SB_DQS_DN<6>")
	)
	(segment
		(start 281.71267 -296.038016)
		(end 282.19019 -296.038016)
		(width 0.16002)
		(layer "In11.Cu")
		(net "M_F_CPU0_SB_DQS_DN<6>")
	)
	(segment
		(start 293.885112 -295.507918)
		(end 294.73525 -296.358056)
		(width 0.16002)
		(layer "In11.Cu")
		(net "M_F_CPU0_SB_DQS_DN<6>")
	)
	(segment
		(start 283.626814 -295.153842)
		(end 283.98089 -295.507918)
		(width 0.16002)
		(layer "In11.Cu")
		(net "M_F_CPU0_SB_DQS_DN<6>")
	)
	(segment
		(start 283.074364 -295.153842)
		(end 283.626814 -295.153842)
		(width 0.16002)
		(layer "In11.Cu")
		(net "M_F_CPU0_SB_DQS_DN<6>")
	)
	(segment
		(start 276.08276 -295.153842)
		(end 276.436836 -295.507918)
		(width 0.16002)
		(layer "In11.Cu")
		(net "M_F_CPU0_SB_DQS_DN<6>")
	)
	(segment
		(start 282.19019 -296.038016)
		(end 283.074364 -295.153842)
		(width 0.16002)
		(layer "In11.Cu")
		(net "M_F_CPU0_SB_DQS_DN<6>")
	)
	(segment
		(start 265.821922 -295.35882)
		(end 266.382246 -295.35882)
		(width 0.16002)
		(layer "In11.Cu")
		(net "M_F_CPU0_SB_DQS_DN<6>")
	)
	(segment
		(start 291.524944 -295.507918)
		(end 293.885112 -295.507918)
		(width 0.16002)
		(layer "In11.Cu")
		(net "M_F_CPU0_SB_DQS_DN<6>")
	)
	(segment
		(start 296.480738 -296.358056)
		(end 296.800778 -296.038016)
		(width 0.16002)
		(layer "In11.Cu")
		(net "M_F_CPU0_SB_DQS_DN<6>")
	)
	(segment
		(start 272.136362 -296.358056)
		(end 273.848576 -296.358056)
		(width 0.16002)
		(layer "In11.Cu")
		(net "M_F_CPU0_SB_DQS_DN<6>")
	)
	(segment
		(start 333.831692 -281.728418)
		(end 333.85506 -281.64155)
		(width 0.09525)
		(layer "In11.Cu")
		(net "M_F_CPU0_SB_DQS_DN<6>")
	)
	(segment
		(start 267.095986 -295.35882)
		(end 267.576046 -295.35882)
		(width 0.16002)
		(layer "In11.Cu")
		(net "M_F_CPU0_SB_DQS_DN<6>")
	)
	(segment
		(start 323.978778 -281.731212)
		(end 325.169276 -281.731212)
		(width 0.09525)
		(layer "In11.Cu")
		(net "M_F_CPU0_SB_DQS_DN<6>")
	)
	(segment
		(start 279.647142 -296.358056)
		(end 281.39263 -296.358056)
		(width 0.16002)
		(layer "In11.Cu")
		(net "M_F_CPU0_SB_DQS_DN<6>")
	)
	(segment
		(start 287.191196 -296.358056)
		(end 288.936684 -296.358056)
		(width 0.16002)
		(layer "In11.Cu")
		(net "M_F_CPU0_SB_DQS_DN<6>")
	)
	(segment
		(start 297.278298 -296.038016)
		(end 298.162472 -295.153842)
		(width 0.16002)
		(layer "In11.Cu")
		(net "M_F_CPU0_SB_DQS_DN<6>")
	)
	(segment
		(start 267.576046 -295.35882)
		(end 267.741654 -295.193212)
		(width 0.16002)
		(layer "In11.Cu")
		(net "M_F_CPU0_SB_DQS_DN<6>")
	)
	(segment
		(start 321.127628 -281.67203)
		(end 323.895974 -281.67203)
		(width 0.16002)
		(layer "In11.Cu")
		(net "M_F_CPU0_SB_DQS_DN<6>")
	)
	(segment
		(start 274.646136 -296.038016)
		(end 275.53031 -295.153842)
		(width 0.16002)
		(layer "In11.Cu")
		(net "M_F_CPU0_SB_DQS_DN<6>")
	)
	(segment
		(start 307.645816 -295.153842)
		(end 321.127628 -281.67203)
		(width 0.16002)
		(layer "In11.Cu")
		(net "M_F_CPU0_SB_DQS_DN<6>")
	)
	(segment
		(start 301.959264 -296.038016)
		(end 304.822098 -296.038016)
		(width 0.16002)
		(layer "In11.Cu")
		(net "M_F_CPU0_SB_DQS_DN<6>")
	)
	(segment
		(start 278.797004 -295.507918)
		(end 279.647142 -296.358056)
		(width 0.16002)
		(layer "In11.Cu")
		(net "M_F_CPU0_SB_DQS_DN<6>")
	)
	(segment
		(start 266.979146 -295.24198)
		(end 267.095986 -295.35882)
		(width 0.16002)
		(layer "In11.Cu")
		(net "M_F_CPU0_SB_DQS_DN<6>")
	)
	(segment
		(start 274.168616 -296.038016)
		(end 274.646136 -296.038016)
		(width 0.16002)
		(layer "In11.Cu")
		(net "M_F_CPU0_SB_DQS_DN<6>")
	)
	(segment
		(start 325.356728 -281.54376)
		(end 327.696322 -281.54376)
		(width 0.09525)
		(layer "In11.Cu")
		(net "M_F_CPU0_SB_DQS_DN<6>")
	)
	(segment
		(start 266.382246 -295.35882)
		(end 266.499086 -295.24198)
		(width 0.16002)
		(layer "In11.Cu")
		(net "M_F_CPU0_SB_DQS_DN<6>")
	)
	(segment
		(start 298.714922 -295.153842)
		(end 299.068998 -295.507918)
		(width 0.16002)
		(layer "In11.Cu")
		(net "M_F_CPU0_SB_DQS_DN<6>")
	)
	(segment
		(start 289.734244 -296.038016)
		(end 290.618418 -295.153842)
		(width 0.16002)
		(layer "In11.Cu")
		(net "M_F_CPU0_SB_DQS_DN<6>")
	)
	(arc
		(start 328.812652 -281.70124)
		(mid 329.00112 -281.751917)
		(end 329.189588 -281.70124)
		(width 0.09525)
		(layer "In11.Cu")
		(net "M_F_CPU0_SB_DQS_DN<6>")
	)
	(arc
		(start 332.94955 -281.70124)
		(mid 333.230982 -281.625485)
		(end 333.512414 -281.70124)
		(width 0.09525)
		(layer "In11.Cu")
		(net "M_F_CPU0_SB_DQS_DN<6>")
	)
	(arc
		(start 332.572614 -281.70124)
		(mid 332.761082 -281.751917)
		(end 332.94955 -281.70124)
		(width 0.09525)
		(layer "In11.Cu")
		(net "M_F_CPU0_SB_DQS_DN<6>")
	)
	(arc
		(start 330.700888 -281.706066)
		(mid 330.88592 -281.75198)
		(end 331.069696 -281.70124)
		(width 0.09525)
		(layer "In11.Cu")
		(net "M_F_CPU0_SB_DQS_DN<6>")
	)
	(arc
		(start 332.00975 -281.70124)
		(mid 332.291182 -281.625485)
		(end 332.572614 -281.70124)
		(width 0.09525)
		(layer "In11.Cu")
		(net "M_F_CPU0_SB_DQS_DN<6>")
	)
	(arc
		(start 331.640942 -281.706066)
		(mid 331.825974 -281.75198)
		(end 332.00975 -281.70124)
		(width 0.09525)
		(layer "In11.Cu")
		(net "M_F_CPU0_SB_DQS_DN<6>")
	)
	(arc
		(start 329.752452 -281.70124)
		(mid 329.936227 -281.752012)
		(end 330.12126 -281.706066)
		(width 0.09525)
		(layer "In11.Cu")
		(net "M_F_CPU0_SB_DQS_DN<6>")
	)
	(arc
		(start 328.249788 -281.70124)
		(mid 328.53122 -281.625485)
		(end 328.812652 -281.70124)
		(width 0.09525)
		(layer "In11.Cu")
		(net "M_F_CPU0_SB_DQS_DN<6>")
	)
	(arc
		(start 329.189588 -281.70124)
		(mid 329.47102 -281.625485)
		(end 329.752452 -281.70124)
		(width 0.09525)
		(layer "In11.Cu")
		(net "M_F_CPU0_SB_DQS_DN<6>")
	)
	(arc
		(start 327.872344 -281.70124)
		(mid 328.061066 -281.752044)
		(end 328.249788 -281.70124)
		(width 0.09525)
		(layer "In11.Cu")
		(net "M_F_CPU0_SB_DQS_DN<6>")
	)
	(arc
		(start 330.129642 -281.70124)
		(mid 330.411074 -281.625485)
		(end 330.692506 -281.70124)
		(width 0.09525)
		(layer "In11.Cu")
		(net "M_F_CPU0_SB_DQS_DN<6>")
	)
	(arc
		(start 333.512414 -281.70124)
		(mid 333.669012 -281.750529)
		(end 333.831692 -281.728418)
		(width 0.09525)
		(layer "In11.Cu")
		(net "M_F_CPU0_SB_DQS_DN<6>")
	)
	(arc
		(start 331.069696 -281.70124)
		(mid 331.351128 -281.625485)
		(end 331.63256 -281.70124)
		(width 0.09525)
		(layer "In11.Cu")
		(net "M_F_CPU0_SB_DQS_DN<6>")
	)
	(arc
		(start 327.794874 -281.642312)
		(mid 327.831691 -281.674298)
		(end 327.872344 -281.70124)
		(width 0.09525)
		(layer "In11.Cu")
		(net "M_F_CPU0_SB_DQS_DN<6>")
	)
	(segment
		(start 334.167988 -276.250146)
		(end 333.701136 -276.516084)
		(width 0.12954)
		(layer "F.Cu")
		(net "M_F_CPU0_SB_DQS_DN<5>")
	)
	(segment
		(start 293.885112 -286.157924)
		(end 294.73525 -287.008062)
		(width 0.16002)
		(layer "In11.Cu")
		(net "M_F_CPU0_SB_DQS_DN<5>")
	)
	(segment
		(start 330.12126 -276.84603)
		(end 330.129642 -276.841204)
		(width 0.09525)
		(layer "In11.Cu")
		(net "M_F_CPU0_SB_DQS_DN<5>")
	)
	(segment
		(start 274.168616 -286.688022)
		(end 274.646136 -286.688022)
		(width 0.16002)
		(layer "In11.Cu")
		(net "M_F_CPU0_SB_DQS_DN<5>")
	)
	(segment
		(start 281.71267 -286.688022)
		(end 282.19019 -286.688022)
		(width 0.16002)
		(layer "In11.Cu")
		(net "M_F_CPU0_SB_DQS_DN<5>")
	)
	(segment
		(start 287.191196 -287.008062)
		(end 288.936684 -287.008062)
		(width 0.16002)
		(layer "In11.Cu")
		(net "M_F_CPU0_SB_DQS_DN<5>")
	)
	(segment
		(start 297.278298 -286.688022)
		(end 298.162472 -285.803848)
		(width 0.16002)
		(layer "In11.Cu")
		(net "M_F_CPU0_SB_DQS_DN<5>")
	)
	(segment
		(start 331.63256 -276.841204)
		(end 331.640942 -276.84603)
		(width 0.09525)
		(layer "In11.Cu")
		(net "M_F_CPU0_SB_DQS_DN<5>")
	)
	(segment
		(start 288.936684 -287.008062)
		(end 289.256724 -286.688022)
		(width 0.16002)
		(layer "In11.Cu")
		(net "M_F_CPU0_SB_DQS_DN<5>")
	)
	(segment
		(start 267.576046 -286.008826)
		(end 267.741654 -285.843218)
		(width 0.16002)
		(layer "In11.Cu")
		(net "M_F_CPU0_SB_DQS_DN<5>")
	)
	(segment
		(start 272.136362 -287.008062)
		(end 273.848576 -287.008062)
		(width 0.16002)
		(layer "In11.Cu")
		(net "M_F_CPU0_SB_DQS_DN<5>")
	)
	(segment
		(start 299.068998 -286.157924)
		(end 301.429166 -286.157924)
		(width 0.16002)
		(layer "In11.Cu")
		(net "M_F_CPU0_SB_DQS_DN<5>")
	)
	(segment
		(start 296.480738 -287.008062)
		(end 296.800778 -286.688022)
		(width 0.16002)
		(layer "In11.Cu")
		(net "M_F_CPU0_SB_DQS_DN<5>")
	)
	(segment
		(start 330.692506 -276.841204)
		(end 330.700888 -276.84603)
		(width 0.09525)
		(layer "In11.Cu")
		(net "M_F_CPU0_SB_DQS_DN<5>")
	)
	(segment
		(start 323.919596 -276.04847)
		(end 323.978778 -276.107652)
		(width 0.09525)
		(layer "In11.Cu")
		(net "M_F_CPU0_SB_DQS_DN<5>")
	)
	(segment
		(start 308.183026 -285.803848)
		(end 317.938404 -276.04847)
		(width 0.16002)
		(layer "In11.Cu")
		(net "M_F_CPU0_SB_DQS_DN<5>")
	)
	(segment
		(start 279.647142 -287.008062)
		(end 281.39263 -287.008062)
		(width 0.16002)
		(layer "In11.Cu")
		(net "M_F_CPU0_SB_DQS_DN<5>")
	)
	(segment
		(start 289.256724 -286.688022)
		(end 289.734244 -286.688022)
		(width 0.16002)
		(layer "In11.Cu")
		(net "M_F_CPU0_SB_DQS_DN<5>")
	)
	(segment
		(start 266.382246 -286.008826)
		(end 266.499086 -285.891986)
		(width 0.16002)
		(layer "In11.Cu")
		(net "M_F_CPU0_SB_DQS_DN<5>")
	)
	(segment
		(start 283.626814 -285.803848)
		(end 283.98089 -286.157924)
		(width 0.16002)
		(layer "In11.Cu")
		(net "M_F_CPU0_SB_DQS_DN<5>")
	)
	(segment
		(start 268.581378 -285.843218)
		(end 268.927834 -286.189674)
		(width 0.16002)
		(layer "In11.Cu")
		(net "M_F_CPU0_SB_DQS_DN<5>")
	)
	(segment
		(start 298.714922 -285.803848)
		(end 299.068998 -286.157924)
		(width 0.16002)
		(layer "In11.Cu")
		(net "M_F_CPU0_SB_DQS_DN<5>")
	)
	(segment
		(start 274.646136 -286.688022)
		(end 275.53031 -285.803848)
		(width 0.16002)
		(layer "In11.Cu")
		(net "M_F_CPU0_SB_DQS_DN<5>")
	)
	(segment
		(start 301.429166 -286.157924)
		(end 301.959264 -286.688022)
		(width 0.16002)
		(layer "In11.Cu")
		(net "M_F_CPU0_SB_DQS_DN<5>")
	)
	(segment
		(start 283.98089 -286.157924)
		(end 286.341058 -286.157924)
		(width 0.16002)
		(layer "In11.Cu")
		(net "M_F_CPU0_SB_DQS_DN<5>")
	)
	(segment
		(start 267.095986 -286.008826)
		(end 267.576046 -286.008826)
		(width 0.16002)
		(layer "In11.Cu")
		(net "M_F_CPU0_SB_DQS_DN<5>")
	)
	(segment
		(start 281.39263 -287.008062)
		(end 281.71267 -286.688022)
		(width 0.16002)
		(layer "In11.Cu")
		(net "M_F_CPU0_SB_DQS_DN<5>")
	)
	(segment
		(start 333.85506 -276.781514)
		(end 333.701136 -276.516084)
		(width 0.09525)
		(layer "In11.Cu")
		(net "M_F_CPU0_SB_DQS_DN<5>")
	)
	(segment
		(start 266.979146 -285.891986)
		(end 267.095986 -286.008826)
		(width 0.16002)
		(layer "In11.Cu")
		(net "M_F_CPU0_SB_DQS_DN<5>")
	)
	(segment
		(start 323.978778 -276.107652)
		(end 324.333108 -276.107652)
		(width 0.09525)
		(layer "In11.Cu")
		(net "M_F_CPU0_SB_DQS_DN<5>")
	)
	(segment
		(start 290.618418 -285.803848)
		(end 291.170868 -285.803848)
		(width 0.16002)
		(layer "In11.Cu")
		(net "M_F_CPU0_SB_DQS_DN<5>")
	)
	(segment
		(start 291.524944 -286.157924)
		(end 293.885112 -286.157924)
		(width 0.16002)
		(layer "In11.Cu")
		(net "M_F_CPU0_SB_DQS_DN<5>")
	)
	(segment
		(start 271.317974 -286.189674)
		(end 272.136362 -287.008062)
		(width 0.16002)
		(layer "In11.Cu")
		(net "M_F_CPU0_SB_DQS_DN<5>")
	)
	(segment
		(start 267.741654 -285.843218)
		(end 268.581378 -285.843218)
		(width 0.16002)
		(layer "In11.Cu")
		(net "M_F_CPU0_SB_DQS_DN<5>")
	)
	(segment
		(start 324.847966 -276.62251)
		(end 327.060814 -276.62251)
		(width 0.09525)
		(layer "In11.Cu")
		(net "M_F_CPU0_SB_DQS_DN<5>")
	)
	(segment
		(start 296.800778 -286.688022)
		(end 297.278298 -286.688022)
		(width 0.16002)
		(layer "In11.Cu")
		(net "M_F_CPU0_SB_DQS_DN<5>")
	)
	(segment
		(start 323.895974 -276.04847)
		(end 323.919596 -276.04847)
		(width 0.09525)
		(layer "In11.Cu")
		(net "M_F_CPU0_SB_DQS_DN<5>")
	)
	(segment
		(start 283.074364 -285.803848)
		(end 283.626814 -285.803848)
		(width 0.16002)
		(layer "In11.Cu")
		(net "M_F_CPU0_SB_DQS_DN<5>")
	)
	(segment
		(start 317.938404 -276.04847)
		(end 323.895974 -276.04847)
		(width 0.16002)
		(layer "In11.Cu")
		(net "M_F_CPU0_SB_DQS_DN<5>")
	)
	(segment
		(start 298.162472 -285.803848)
		(end 298.714922 -285.803848)
		(width 0.16002)
		(layer "In11.Cu")
		(net "M_F_CPU0_SB_DQS_DN<5>")
	)
	(segment
		(start 278.797004 -286.157924)
		(end 279.647142 -287.008062)
		(width 0.16002)
		(layer "In11.Cu")
		(net "M_F_CPU0_SB_DQS_DN<5>")
	)
	(segment
		(start 265.821922 -286.008826)
		(end 266.382246 -286.008826)
		(width 0.16002)
		(layer "In11.Cu")
		(net "M_F_CPU0_SB_DQS_DN<5>")
	)
	(segment
		(start 275.53031 -285.803848)
		(end 276.08276 -285.803848)
		(width 0.16002)
		(layer "In11.Cu")
		(net "M_F_CPU0_SB_DQS_DN<5>")
	)
	(segment
		(start 276.436836 -286.157924)
		(end 278.797004 -286.157924)
		(width 0.16002)
		(layer "In11.Cu")
		(net "M_F_CPU0_SB_DQS_DN<5>")
	)
	(segment
		(start 301.959264 -286.688022)
		(end 304.822098 -286.688022)
		(width 0.16002)
		(layer "In11.Cu")
		(net "M_F_CPU0_SB_DQS_DN<5>")
	)
	(segment
		(start 282.19019 -286.688022)
		(end 283.074364 -285.803848)
		(width 0.16002)
		(layer "In11.Cu")
		(net "M_F_CPU0_SB_DQS_DN<5>")
	)
	(segment
		(start 291.170868 -285.803848)
		(end 291.524944 -286.157924)
		(width 0.16002)
		(layer "In11.Cu")
		(net "M_F_CPU0_SB_DQS_DN<5>")
	)
	(segment
		(start 324.333108 -276.107652)
		(end 324.847966 -276.62251)
		(width 0.09525)
		(layer "In11.Cu")
		(net "M_F_CPU0_SB_DQS_DN<5>")
	)
	(segment
		(start 305.706272 -285.803848)
		(end 308.183026 -285.803848)
		(width 0.16002)
		(layer "In11.Cu")
		(net "M_F_CPU0_SB_DQS_DN<5>")
	)
	(segment
		(start 268.927834 -286.189674)
		(end 271.317974 -286.189674)
		(width 0.16002)
		(layer "In11.Cu")
		(net "M_F_CPU0_SB_DQS_DN<5>")
	)
	(segment
		(start 265.54811 -285.735014)
		(end 265.821922 -286.008826)
		(width 0.16002)
		(layer "In11.Cu")
		(net "M_F_CPU0_SB_DQS_DN<5>")
	)
	(segment
		(start 294.73525 -287.008062)
		(end 296.480738 -287.008062)
		(width 0.16002)
		(layer "In11.Cu")
		(net "M_F_CPU0_SB_DQS_DN<5>")
	)
	(segment
		(start 276.08276 -285.803848)
		(end 276.436836 -286.157924)
		(width 0.16002)
		(layer "In11.Cu")
		(net "M_F_CPU0_SB_DQS_DN<5>")
	)
	(segment
		(start 273.848576 -287.008062)
		(end 274.168616 -286.688022)
		(width 0.16002)
		(layer "In11.Cu")
		(net "M_F_CPU0_SB_DQS_DN<5>")
	)
	(segment
		(start 333.831692 -276.868382)
		(end 333.85506 -276.781514)
		(width 0.09525)
		(layer "In11.Cu")
		(net "M_F_CPU0_SB_DQS_DN<5>")
	)
	(segment
		(start 304.822098 -286.688022)
		(end 305.706272 -285.803848)
		(width 0.16002)
		(layer "In11.Cu")
		(net "M_F_CPU0_SB_DQS_DN<5>")
	)
	(segment
		(start 266.499086 -285.891986)
		(end 266.979146 -285.891986)
		(width 0.16002)
		(layer "In11.Cu")
		(net "M_F_CPU0_SB_DQS_DN<5>")
	)
	(segment
		(start 289.734244 -286.688022)
		(end 290.618418 -285.803848)
		(width 0.16002)
		(layer "In11.Cu")
		(net "M_F_CPU0_SB_DQS_DN<5>")
	)
	(segment
		(start 286.341058 -286.157924)
		(end 287.191196 -287.008062)
		(width 0.16002)
		(layer "In11.Cu")
		(net "M_F_CPU0_SB_DQS_DN<5>")
	)
	(arc
		(start 328.812652 -276.841204)
		(mid 329.00112 -276.891881)
		(end 329.189588 -276.841204)
		(width 0.09525)
		(layer "In11.Cu")
		(net "M_F_CPU0_SB_DQS_DN<5>")
	)
	(arc
		(start 328.249788 -276.841204)
		(mid 328.53122 -276.765449)
		(end 328.812652 -276.841204)
		(width 0.09525)
		(layer "In11.Cu")
		(net "M_F_CPU0_SB_DQS_DN<5>")
	)
	(arc
		(start 330.129642 -276.841204)
		(mid 330.411074 -276.765449)
		(end 330.692506 -276.841204)
		(width 0.09525)
		(layer "In11.Cu")
		(net "M_F_CPU0_SB_DQS_DN<5>")
	)
	(arc
		(start 332.00975 -276.841204)
		(mid 332.291182 -276.765449)
		(end 332.572614 -276.841204)
		(width 0.09525)
		(layer "In11.Cu")
		(net "M_F_CPU0_SB_DQS_DN<5>")
	)
	(arc
		(start 327.060814 -276.62251)
		(mid 327.481057 -276.678138)
		(end 327.872344 -276.841204)
		(width 0.09525)
		(layer "In11.Cu")
		(net "M_F_CPU0_SB_DQS_DN<5>")
	)
	(arc
		(start 331.640942 -276.84603)
		(mid 331.825974 -276.891944)
		(end 332.00975 -276.841204)
		(width 0.09525)
		(layer "In11.Cu")
		(net "M_F_CPU0_SB_DQS_DN<5>")
	)
	(arc
		(start 329.752452 -276.841204)
		(mid 329.936227 -276.891976)
		(end 330.12126 -276.84603)
		(width 0.09525)
		(layer "In11.Cu")
		(net "M_F_CPU0_SB_DQS_DN<5>")
	)
	(arc
		(start 333.512414 -276.841204)
		(mid 333.669012 -276.890493)
		(end 333.831692 -276.868382)
		(width 0.09525)
		(layer "In11.Cu")
		(net "M_F_CPU0_SB_DQS_DN<5>")
	)
	(arc
		(start 332.572614 -276.841204)
		(mid 332.761082 -276.891881)
		(end 332.94955 -276.841204)
		(width 0.09525)
		(layer "In11.Cu")
		(net "M_F_CPU0_SB_DQS_DN<5>")
	)
	(arc
		(start 331.069696 -276.841204)
		(mid 331.351128 -276.765449)
		(end 331.63256 -276.841204)
		(width 0.09525)
		(layer "In11.Cu")
		(net "M_F_CPU0_SB_DQS_DN<5>")
	)
	(arc
		(start 329.189588 -276.841204)
		(mid 329.47102 -276.765449)
		(end 329.752452 -276.841204)
		(width 0.09525)
		(layer "In11.Cu")
		(net "M_F_CPU0_SB_DQS_DN<5>")
	)
	(arc
		(start 332.94955 -276.841204)
		(mid 333.230982 -276.765449)
		(end 333.512414 -276.841204)
		(width 0.09525)
		(layer "In11.Cu")
		(net "M_F_CPU0_SB_DQS_DN<5>")
	)
	(arc
		(start 330.700888 -276.84603)
		(mid 330.88592 -276.891944)
		(end 331.069696 -276.841204)
		(width 0.09525)
		(layer "In11.Cu")
		(net "M_F_CPU0_SB_DQS_DN<5>")
	)
	(arc
		(start 327.872344 -276.841204)
		(mid 328.061066 -276.892008)
		(end 328.249788 -276.841204)
		(width 0.09525)
		(layer "In11.Cu")
		(net "M_F_CPU0_SB_DQS_DN<5>")
	)
	(segment
		(start 334.167988 -271.39011)
		(end 333.701136 -271.656048)
		(width 0.12954)
		(layer "F.Cu")
		(net "M_F_CPU0_SB_DQS_DN<4>")
	)
	(segment
		(start 271.317974 -276.83968)
		(end 272.136362 -277.658068)
		(width 0.16002)
		(layer "In11.Cu")
		(net "M_F_CPU0_SB_DQS_DN<4>")
	)
	(segment
		(start 268.581378 -276.493224)
		(end 268.927834 -276.83968)
		(width 0.16002)
		(layer "In11.Cu")
		(net "M_F_CPU0_SB_DQS_DN<4>")
	)
	(segment
		(start 267.576046 -276.658832)
		(end 267.741654 -276.493224)
		(width 0.16002)
		(layer "In11.Cu")
		(net "M_F_CPU0_SB_DQS_DN<4>")
	)
	(segment
		(start 276.436836 -276.80793)
		(end 278.797004 -276.80793)
		(width 0.16002)
		(layer "In11.Cu")
		(net "M_F_CPU0_SB_DQS_DN<4>")
	)
	(segment
		(start 333.85506 -271.921478)
		(end 333.701136 -271.656048)
		(width 0.09525)
		(layer "In11.Cu")
		(net "M_F_CPU0_SB_DQS_DN<4>")
	)
	(segment
		(start 266.979146 -276.541992)
		(end 267.095986 -276.658832)
		(width 0.16002)
		(layer "In11.Cu")
		(net "M_F_CPU0_SB_DQS_DN<4>")
	)
	(segment
		(start 283.074364 -276.453854)
		(end 283.626814 -276.453854)
		(width 0.16002)
		(layer "In11.Cu")
		(net "M_F_CPU0_SB_DQS_DN<4>")
	)
	(segment
		(start 283.98089 -276.80793)
		(end 286.341058 -276.80793)
		(width 0.16002)
		(layer "In11.Cu")
		(net "M_F_CPU0_SB_DQS_DN<4>")
	)
	(segment
		(start 289.734244 -277.338028)
		(end 290.618418 -276.453854)
		(width 0.16002)
		(layer "In11.Cu")
		(net "M_F_CPU0_SB_DQS_DN<4>")
	)
	(segment
		(start 330.692506 -271.981168)
		(end 330.700888 -271.985994)
		(width 0.09525)
		(layer "In11.Cu")
		(net "M_F_CPU0_SB_DQS_DN<4>")
	)
	(segment
		(start 297.278298 -277.338028)
		(end 298.162472 -276.453854)
		(width 0.16002)
		(layer "In11.Cu")
		(net "M_F_CPU0_SB_DQS_DN<4>")
	)
	(segment
		(start 266.499086 -276.541992)
		(end 266.979146 -276.541992)
		(width 0.16002)
		(layer "In11.Cu")
		(net "M_F_CPU0_SB_DQS_DN<4>")
	)
	(segment
		(start 276.08276 -276.453854)
		(end 276.436836 -276.80793)
		(width 0.16002)
		(layer "In11.Cu")
		(net "M_F_CPU0_SB_DQS_DN<4>")
	)
	(segment
		(start 299.068998 -276.80793)
		(end 301.429166 -276.80793)
		(width 0.16002)
		(layer "In11.Cu")
		(net "M_F_CPU0_SB_DQS_DN<4>")
	)
	(segment
		(start 304.822098 -277.338028)
		(end 305.706272 -276.453854)
		(width 0.16002)
		(layer "In11.Cu")
		(net "M_F_CPU0_SB_DQS_DN<4>")
	)
	(segment
		(start 307.255672 -276.453854)
		(end 313.284616 -270.42491)
		(width 0.16002)
		(layer "In11.Cu")
		(net "M_F_CPU0_SB_DQS_DN<4>")
	)
	(segment
		(start 278.797004 -276.80793)
		(end 279.647142 -277.658068)
		(width 0.16002)
		(layer "In11.Cu")
		(net "M_F_CPU0_SB_DQS_DN<4>")
	)
	(segment
		(start 325.331582 -270.67891)
		(end 326.507602 -271.85493)
		(width 0.09525)
		(layer "In11.Cu")
		(net "M_F_CPU0_SB_DQS_DN<4>")
	)
	(segment
		(start 274.646136 -277.338028)
		(end 275.53031 -276.453854)
		(width 0.16002)
		(layer "In11.Cu")
		(net "M_F_CPU0_SB_DQS_DN<4>")
	)
	(segment
		(start 294.73525 -277.658068)
		(end 296.480738 -277.658068)
		(width 0.16002)
		(layer "In11.Cu")
		(net "M_F_CPU0_SB_DQS_DN<4>")
	)
	(segment
		(start 296.480738 -277.658068)
		(end 296.800778 -277.338028)
		(width 0.16002)
		(layer "In11.Cu")
		(net "M_F_CPU0_SB_DQS_DN<4>")
	)
	(segment
		(start 281.39263 -277.658068)
		(end 281.71267 -277.338028)
		(width 0.16002)
		(layer "In11.Cu")
		(net "M_F_CPU0_SB_DQS_DN<4>")
	)
	(segment
		(start 326.507602 -271.85493)
		(end 327.403968 -271.85493)
		(width 0.09525)
		(layer "In11.Cu")
		(net "M_F_CPU0_SB_DQS_DN<4>")
	)
	(segment
		(start 313.284616 -270.42491)
		(end 323.895974 -270.42491)
		(width 0.16002)
		(layer "In11.Cu")
		(net "M_F_CPU0_SB_DQS_DN<4>")
	)
	(segment
		(start 301.429166 -276.80793)
		(end 301.959264 -277.338028)
		(width 0.16002)
		(layer "In11.Cu")
		(net "M_F_CPU0_SB_DQS_DN<4>")
	)
	(segment
		(start 324.492366 -270.67891)
		(end 325.331582 -270.67891)
		(width 0.09525)
		(layer "In11.Cu")
		(net "M_F_CPU0_SB_DQS_DN<4>")
	)
	(segment
		(start 266.382246 -276.658832)
		(end 266.499086 -276.541992)
		(width 0.16002)
		(layer "In11.Cu")
		(net "M_F_CPU0_SB_DQS_DN<4>")
	)
	(segment
		(start 282.19019 -277.338028)
		(end 283.074364 -276.453854)
		(width 0.16002)
		(layer "In11.Cu")
		(net "M_F_CPU0_SB_DQS_DN<4>")
	)
	(segment
		(start 286.341058 -276.80793)
		(end 287.191196 -277.658068)
		(width 0.16002)
		(layer "In11.Cu")
		(net "M_F_CPU0_SB_DQS_DN<4>")
	)
	(segment
		(start 330.12126 -271.985994)
		(end 330.129642 -271.981168)
		(width 0.09525)
		(layer "In11.Cu")
		(net "M_F_CPU0_SB_DQS_DN<4>")
	)
	(segment
		(start 275.53031 -276.453854)
		(end 276.08276 -276.453854)
		(width 0.16002)
		(layer "In11.Cu")
		(net "M_F_CPU0_SB_DQS_DN<4>")
	)
	(segment
		(start 265.54811 -276.38502)
		(end 265.821922 -276.658832)
		(width 0.16002)
		(layer "In11.Cu")
		(net "M_F_CPU0_SB_DQS_DN<4>")
	)
	(segment
		(start 283.626814 -276.453854)
		(end 283.98089 -276.80793)
		(width 0.16002)
		(layer "In11.Cu")
		(net "M_F_CPU0_SB_DQS_DN<4>")
	)
	(segment
		(start 323.919596 -270.42491)
		(end 323.978778 -270.484092)
		(width 0.09525)
		(layer "In11.Cu")
		(net "M_F_CPU0_SB_DQS_DN<4>")
	)
	(segment
		(start 289.256724 -277.338028)
		(end 289.734244 -277.338028)
		(width 0.16002)
		(layer "In11.Cu")
		(net "M_F_CPU0_SB_DQS_DN<4>")
	)
	(segment
		(start 323.895974 -270.42491)
		(end 323.919596 -270.42491)
		(width 0.09525)
		(layer "In11.Cu")
		(net "M_F_CPU0_SB_DQS_DN<4>")
	)
	(segment
		(start 279.647142 -277.658068)
		(end 281.39263 -277.658068)
		(width 0.16002)
		(layer "In11.Cu")
		(net "M_F_CPU0_SB_DQS_DN<4>")
	)
	(segment
		(start 301.959264 -277.338028)
		(end 304.822098 -277.338028)
		(width 0.16002)
		(layer "In11.Cu")
		(net "M_F_CPU0_SB_DQS_DN<4>")
	)
	(segment
		(start 298.714922 -276.453854)
		(end 299.068998 -276.80793)
		(width 0.16002)
		(layer "In11.Cu")
		(net "M_F_CPU0_SB_DQS_DN<4>")
	)
	(segment
		(start 290.618418 -276.453854)
		(end 291.170868 -276.453854)
		(width 0.16002)
		(layer "In11.Cu")
		(net "M_F_CPU0_SB_DQS_DN<4>")
	)
	(segment
		(start 273.848576 -277.658068)
		(end 274.168616 -277.338028)
		(width 0.16002)
		(layer "In11.Cu")
		(net "M_F_CPU0_SB_DQS_DN<4>")
	)
	(segment
		(start 296.800778 -277.338028)
		(end 297.278298 -277.338028)
		(width 0.16002)
		(layer "In11.Cu")
		(net "M_F_CPU0_SB_DQS_DN<4>")
	)
	(segment
		(start 265.821922 -276.658832)
		(end 266.382246 -276.658832)
		(width 0.16002)
		(layer "In11.Cu")
		(net "M_F_CPU0_SB_DQS_DN<4>")
	)
	(segment
		(start 305.706272 -276.453854)
		(end 307.255672 -276.453854)
		(width 0.16002)
		(layer "In11.Cu")
		(net "M_F_CPU0_SB_DQS_DN<4>")
	)
	(segment
		(start 293.885112 -276.80793)
		(end 294.73525 -277.658068)
		(width 0.16002)
		(layer "In11.Cu")
		(net "M_F_CPU0_SB_DQS_DN<4>")
	)
	(segment
		(start 298.162472 -276.453854)
		(end 298.714922 -276.453854)
		(width 0.16002)
		(layer "In11.Cu")
		(net "M_F_CPU0_SB_DQS_DN<4>")
	)
	(segment
		(start 267.741654 -276.493224)
		(end 268.581378 -276.493224)
		(width 0.16002)
		(layer "In11.Cu")
		(net "M_F_CPU0_SB_DQS_DN<4>")
	)
	(segment
		(start 333.831692 -272.008346)
		(end 333.85506 -271.921478)
		(width 0.09525)
		(layer "In11.Cu")
		(net "M_F_CPU0_SB_DQS_DN<4>")
	)
	(segment
		(start 281.71267 -277.338028)
		(end 282.19019 -277.338028)
		(width 0.16002)
		(layer "In11.Cu")
		(net "M_F_CPU0_SB_DQS_DN<4>")
	)
	(segment
		(start 268.927834 -276.83968)
		(end 271.317974 -276.83968)
		(width 0.16002)
		(layer "In11.Cu")
		(net "M_F_CPU0_SB_DQS_DN<4>")
	)
	(segment
		(start 267.095986 -276.658832)
		(end 267.576046 -276.658832)
		(width 0.16002)
		(layer "In11.Cu")
		(net "M_F_CPU0_SB_DQS_DN<4>")
	)
	(segment
		(start 272.136362 -277.658068)
		(end 273.848576 -277.658068)
		(width 0.16002)
		(layer "In11.Cu")
		(net "M_F_CPU0_SB_DQS_DN<4>")
	)
	(segment
		(start 323.978778 -270.484092)
		(end 324.297548 -270.484092)
		(width 0.09525)
		(layer "In11.Cu")
		(net "M_F_CPU0_SB_DQS_DN<4>")
	)
	(segment
		(start 288.936684 -277.658068)
		(end 289.256724 -277.338028)
		(width 0.16002)
		(layer "In11.Cu")
		(net "M_F_CPU0_SB_DQS_DN<4>")
	)
	(segment
		(start 274.168616 -277.338028)
		(end 274.646136 -277.338028)
		(width 0.16002)
		(layer "In11.Cu")
		(net "M_F_CPU0_SB_DQS_DN<4>")
	)
	(segment
		(start 331.63256 -271.981168)
		(end 331.640942 -271.985994)
		(width 0.09525)
		(layer "In11.Cu")
		(net "M_F_CPU0_SB_DQS_DN<4>")
	)
	(segment
		(start 291.524944 -276.80793)
		(end 293.885112 -276.80793)
		(width 0.16002)
		(layer "In11.Cu")
		(net "M_F_CPU0_SB_DQS_DN<4>")
	)
	(segment
		(start 287.191196 -277.658068)
		(end 288.936684 -277.658068)
		(width 0.16002)
		(layer "In11.Cu")
		(net "M_F_CPU0_SB_DQS_DN<4>")
	)
	(segment
		(start 324.297548 -270.484092)
		(end 324.492366 -270.67891)
		(width 0.09525)
		(layer "In11.Cu")
		(net "M_F_CPU0_SB_DQS_DN<4>")
	)
	(segment
		(start 291.170868 -276.453854)
		(end 291.524944 -276.80793)
		(width 0.16002)
		(layer "In11.Cu")
		(net "M_F_CPU0_SB_DQS_DN<4>")
	)
	(arc
		(start 329.189588 -271.981168)
		(mid 329.47102 -271.905413)
		(end 329.752452 -271.981168)
		(width 0.09525)
		(layer "In11.Cu")
		(net "M_F_CPU0_SB_DQS_DN<4>")
	)
	(arc
		(start 327.872344 -271.981168)
		(mid 328.061066 -272.031972)
		(end 328.249788 -271.981168)
		(width 0.09525)
		(layer "In11.Cu")
		(net "M_F_CPU0_SB_DQS_DN<4>")
	)
	(arc
		(start 332.572614 -271.981168)
		(mid 332.761082 -272.031845)
		(end 332.94955 -271.981168)
		(width 0.09525)
		(layer "In11.Cu")
		(net "M_F_CPU0_SB_DQS_DN<4>")
	)
	(arc
		(start 332.00975 -271.981168)
		(mid 332.291182 -271.905413)
		(end 332.572614 -271.981168)
		(width 0.09525)
		(layer "In11.Cu")
		(net "M_F_CPU0_SB_DQS_DN<4>")
	)
	(arc
		(start 330.129642 -271.981168)
		(mid 330.411074 -271.905413)
		(end 330.692506 -271.981168)
		(width 0.09525)
		(layer "In11.Cu")
		(net "M_F_CPU0_SB_DQS_DN<4>")
	)
	(arc
		(start 331.069696 -271.981168)
		(mid 331.351128 -271.905413)
		(end 331.63256 -271.981168)
		(width 0.09525)
		(layer "In11.Cu")
		(net "M_F_CPU0_SB_DQS_DN<4>")
	)
	(arc
		(start 333.512414 -271.981168)
		(mid 333.669012 -272.030457)
		(end 333.831692 -272.008346)
		(width 0.09525)
		(layer "In11.Cu")
		(net "M_F_CPU0_SB_DQS_DN<4>")
	)
	(arc
		(start 329.752452 -271.981168)
		(mid 329.936227 -272.03194)
		(end 330.12126 -271.985994)
		(width 0.09525)
		(layer "In11.Cu")
		(net "M_F_CPU0_SB_DQS_DN<4>")
	)
	(arc
		(start 330.700888 -271.985994)
		(mid 330.88592 -272.031908)
		(end 331.069696 -271.981168)
		(width 0.09525)
		(layer "In11.Cu")
		(net "M_F_CPU0_SB_DQS_DN<4>")
	)
	(arc
		(start 327.403968 -271.85493)
		(mid 327.646516 -271.887038)
		(end 327.872344 -271.981168)
		(width 0.09525)
		(layer "In11.Cu")
		(net "M_F_CPU0_SB_DQS_DN<4>")
	)
	(arc
		(start 328.812652 -271.981168)
		(mid 329.00112 -272.031845)
		(end 329.189588 -271.981168)
		(width 0.09525)
		(layer "In11.Cu")
		(net "M_F_CPU0_SB_DQS_DN<4>")
	)
	(arc
		(start 332.94955 -271.981168)
		(mid 333.230982 -271.905413)
		(end 333.512414 -271.981168)
		(width 0.09525)
		(layer "In11.Cu")
		(net "M_F_CPU0_SB_DQS_DN<4>")
	)
	(arc
		(start 328.249788 -271.981168)
		(mid 328.53122 -271.905413)
		(end 328.812652 -271.981168)
		(width 0.09525)
		(layer "In11.Cu")
		(net "M_F_CPU0_SB_DQS_DN<4>")
	)
	(arc
		(start 331.640942 -271.985994)
		(mid 331.825974 -272.031908)
		(end 332.00975 -271.981168)
		(width 0.09525)
		(layer "In11.Cu")
		(net "M_F_CPU0_SB_DQS_DN<4>")
	)
	(segment
		(start 333.227934 -290.83)
		(end 332.761082 -291.095938)
		(width 0.12954)
		(layer "F.Cu")
		(net "M_F_CPU0_SB_DQS_DN<3>")
	)
	(segment
		(start 322.655184 -297.07205)
		(end 322.72351 -297.140376)
		(width 0.16002)
		(layer "In11.Cu")
		(net "M_F_CPU0_SB_DQS_DN<3>")
	)
	(segment
		(start 324.614794 -293.988744)
		(end 324.614794 -295.642538)
		(width 0.09525)
		(layer "In11.Cu")
		(net "M_F_CPU0_SB_DQS_DN<3>")
	)
	(segment
		(start 332.607158 -290.830508)
		(end 332.50632 -290.803838)
		(width 0.09525)
		(layer "In11.Cu")
		(net "M_F_CPU0_SB_DQS_DN<3>")
	)
	(segment
		(start 313.045094 -306.68214)
		(end 313.11342 -306.750466)
		(width 0.16002)
		(layer "In11.Cu")
		(net "M_F_CPU0_SB_DQS_DN<3>")
	)
	(segment
		(start 321.282314 -298.44492)
		(end 321.35064 -298.513246)
		(width 0.16002)
		(layer "In11.Cu")
		(net "M_F_CPU0_SB_DQS_DN<3>")
	)
	(segment
		(start 331.640942 -290.765992)
		(end 331.63256 -290.770818)
		(width 0.09525)
		(layer "In11.Cu")
		(net "M_F_CPU0_SB_DQS_DN<3>")
	)
	(segment
		(start 318.536574 -300.9646)
		(end 318.536574 -301.19066)
		(width 0.16002)
		(layer "In11.Cu")
		(net "M_F_CPU0_SB_DQS_DN<3>")
	)
	(segment
		(start 322.300092 -298.040298)
		(end 321.823588 -298.040298)
		(width 0.16002)
		(layer "In11.Cu")
		(net "M_F_CPU0_SB_DQS_DN<3>")
	)
	(segment
		(start 314.48629 -305.377596)
		(end 314.48629 -305.8541)
		(width 0.16002)
		(layer "In11.Cu")
		(net "M_F_CPU0_SB_DQS_DN<3>")
	)
	(segment
		(start 283.997908 -312.512202)
		(end 283.628846 -312.881264)
		(width 0.16002)
		(layer "In11.Cu")
		(net "M_F_CPU0_SB_DQS_DN<3>")
	)
	(segment
		(start 300.692312 -312.512202)
		(end 299.086016 -312.512202)
		(width 0.16002)
		(layer "In11.Cu")
		(net "M_F_CPU0_SB_DQS_DN<3>")
	)
	(segment
		(start 314.417964 -305.30927)
		(end 314.48629 -305.377596)
		(width 0.16002)
		(layer "In11.Cu")
		(net "M_F_CPU0_SB_DQS_DN<3>")
	)
	(segment
		(start 314.890912 -304.836322)
		(end 314.664852 -304.836322)
		(width 0.16002)
		(layer "In11.Cu")
		(net "M_F_CPU0_SB_DQS_DN<3>")
	)
	(segment
		(start 283.184092 -312.881264)
		(end 282.358592 -313.706764)
		(width 0.16002)
		(layer "In11.Cu")
		(net "M_F_CPU0_SB_DQS_DN<3>")
	)
	(segment
		(start 320.156332 -299.344842)
		(end 319.909444 -299.59173)
		(width 0.16002)
		(layer "In11.Cu")
		(net "M_F_CPU0_SB_DQS_DN<3>")
	)
	(segment
		(start 297.4467 -313.706764)
		(end 296.796968 -313.706764)
		(width 0.16002)
		(layer "In11.Cu")
		(net "M_F_CPU0_SB_DQS_DN<3>")
	)
	(segment
		(start 283.628846 -312.881264)
		(end 283.184092 -312.881264)
		(width 0.16002)
		(layer "In11.Cu")
		(net "M_F_CPU0_SB_DQS_DN<3>")
	)
	(segment
		(start 322.902072 -296.599102)
		(end 322.655184 -296.84599)
		(width 0.16002)
		(layer "In11.Cu")
		(net "M_F_CPU0_SB_DQS_DN<3>")
	)
	(segment
		(start 321.282314 -298.21886)
		(end 321.282314 -298.44492)
		(width 0.16002)
		(layer "In11.Cu")
		(net "M_F_CPU0_SB_DQS_DN<3>")
	)
	(segment
		(start 319.009522 -300.717712)
		(end 318.783462 -300.717712)
		(width 0.16002)
		(layer "In11.Cu")
		(net "M_F_CPU0_SB_DQS_DN<3>")
	)
	(segment
		(start 313.586368 -306.277518)
		(end 313.518042 -306.209192)
		(width 0.16002)
		(layer "In11.Cu")
		(net "M_F_CPU0_SB_DQS_DN<3>")
	)
	(segment
		(start 326.024748 -292.022022)
		(end 326.024748 -292.57879)
		(width 0.09525)
		(layer "In11.Cu")
		(net "M_F_CPU0_SB_DQS_DN<3>")
	)
	(segment
		(start 278.06015 -312.512202)
		(end 276.453854 -312.512202)
		(width 0.16002)
		(layer "In11.Cu")
		(net "M_F_CPU0_SB_DQS_DN<3>")
	)
	(segment
		(start 301.691802 -313.154822)
		(end 301.334932 -313.154822)
		(width 0.16002)
		(layer "In11.Cu")
		(net "M_F_CPU0_SB_DQS_DN<3>")
	)
	(segment
		(start 317.704978 -302.158908)
		(end 317.636652 -302.090582)
		(width 0.16002)
		(layer "In11.Cu")
		(net "M_F_CPU0_SB_DQS_DN<3>")
	)
	(segment
		(start 304.9905 -313.706764)
		(end 302.243744 -313.706764)
		(width 0.16002)
		(layer "In11.Cu")
		(net "M_F_CPU0_SB_DQS_DN<3>")
	)
	(segment
		(start 313.291982 -306.209192)
		(end 313.045094 -306.45608)
		(width 0.16002)
		(layer "In11.Cu")
		(net "M_F_CPU0_SB_DQS_DN<3>")
	)
	(segment
		(start 311.74055 -308.77256)
		(end 307.631846 -312.881264)
		(width 0.16002)
		(layer "In11.Cu")
		(net "M_F_CPU0_SB_DQS_DN<3>")
	)
	(segment
		(start 269.92199 -313.511184)
		(end 269.648178 -313.784996)
		(width 0.16002)
		(layer "In11.Cu")
		(net "M_F_CPU0_SB_DQS_DN<3>")
	)
	(segment
		(start 326.024748 -292.57879)
		(end 324.614794 -293.988744)
		(width 0.09525)
		(layer "In11.Cu")
		(net "M_F_CPU0_SB_DQS_DN<3>")
	)
	(segment
		(start 326.988932 -290.991036)
		(end 326.071992 -291.907976)
		(width 0.09525)
		(layer "In11.Cu")
		(net "M_F_CPU0_SB_DQS_DN<3>")
	)
	(segment
		(start 305.816 -312.881264)
		(end 304.9905 -313.706764)
		(width 0.16002)
		(layer "In11.Cu")
		(net "M_F_CPU0_SB_DQS_DN<3>")
	)
	(segment
		(start 272.22069 -313.362086)
		(end 272.071592 -313.511184)
		(width 0.16002)
		(layer "In11.Cu")
		(net "M_F_CPU0_SB_DQS_DN<3>")
	)
	(segment
		(start 314.48629 -305.8541)
		(end 314.062872 -306.277518)
		(width 0.16002)
		(layer "In11.Cu")
		(net "M_F_CPU0_SB_DQS_DN<3>")
	)
	(segment
		(start 317.163704 -302.33747)
		(end 317.163704 -302.56353)
		(width 0.16002)
		(layer "In11.Cu")
		(net "M_F_CPU0_SB_DQS_DN<3>")
	)
	(segment
		(start 285.604204 -312.512202)
		(end 283.997908 -312.512202)
		(width 0.16002)
		(layer "In11.Cu")
		(net "M_F_CPU0_SB_DQS_DN<3>")
	)
	(segment
		(start 312.690002 -307.650388)
		(end 312.213498 -307.650388)
		(width 0.16002)
		(layer "In11.Cu")
		(net "M_F_CPU0_SB_DQS_DN<3>")
	)
	(segment
		(start 317.23203 -302.631856)
		(end 317.23203 -303.10836)
		(width 0.16002)
		(layer "In11.Cu")
		(net "M_F_CPU0_SB_DQS_DN<3>")
	)
	(segment
		(start 274.814538 -313.706764)
		(end 274.164806 -313.706764)
		(width 0.16002)
		(layer "In11.Cu")
		(net "M_F_CPU0_SB_DQS_DN<3>")
	)
	(segment
		(start 321.823588 -298.040298)
		(end 321.755262 -297.971972)
		(width 0.16002)
		(layer "In11.Cu")
		(net "M_F_CPU0_SB_DQS_DN<3>")
	)
	(segment
		(start 322.655184 -296.84599)
		(end 322.655184 -297.07205)
		(width 0.16002)
		(layer "In11.Cu")
		(net "M_F_CPU0_SB_DQS_DN<3>")
	)
	(segment
		(start 315.85916 -304.48123)
		(end 315.435742 -304.904648)
		(width 0.16002)
		(layer "In11.Cu")
		(net "M_F_CPU0_SB_DQS_DN<3>")
	)
	(segment
		(start 314.062872 -306.277518)
		(end 313.586368 -306.277518)
		(width 0.16002)
		(layer "In11.Cu")
		(net "M_F_CPU0_SB_DQS_DN<3>")
	)
	(segment
		(start 321.35064 -298.98975)
		(end 320.927222 -299.413168)
		(width 0.16002)
		(layer "In11.Cu")
		(net "M_F_CPU0_SB_DQS_DN<3>")
	)
	(segment
		(start 330.700888 -290.765992)
		(end 330.692506 -290.770818)
		(width 0.09525)
		(layer "In11.Cu")
		(net "M_F_CPU0_SB_DQS_DN<3>")
	)
	(segment
		(start 320.450718 -299.413168)
		(end 320.382392 -299.344842)
		(width 0.16002)
		(layer "In11.Cu")
		(net "M_F_CPU0_SB_DQS_DN<3>")
	)
	(segment
		(start 324.118986 -296.221404)
		(end 324.102222 -296.238168)
		(width 0.09525)
		(layer "In11.Cu")
		(net "M_F_CPU0_SB_DQS_DN<3>")
	)
	(segment
		(start 276.084792 -312.881264)
		(end 275.640038 -312.881264)
		(width 0.16002)
		(layer "In11.Cu")
		(net "M_F_CPU0_SB_DQS_DN<3>")
	)
	(segment
		(start 311.672224 -308.05501)
		(end 311.74055 -308.123336)
		(width 0.16002)
		(layer "In11.Cu")
		(net "M_F_CPU0_SB_DQS_DN<3>")
	)
	(segment
		(start 282.358592 -313.706764)
		(end 281.70886 -313.706764)
		(width 0.16002)
		(layer "In11.Cu")
		(net "M_F_CPU0_SB_DQS_DN<3>")
	)
	(segment
		(start 323.196458 -296.667428)
		(end 323.128132 -296.599102)
		(width 0.16002)
		(layer "In11.Cu")
		(net "M_F_CPU0_SB_DQS_DN<3>")
	)
	(segment
		(start 281.70886 -313.706764)
		(end 281.364182 -313.362086)
		(width 0.16002)
		(layer "In11.Cu")
		(net "M_F_CPU0_SB_DQS_DN<3>")
	)
	(segment
		(start 324.102222 -296.238168)
		(end 323.672962 -296.667428)
		(width 0.16002)
		(layer "In11.Cu")
		(net "M_F_CPU0_SB_DQS_DN<3>")
	)
	(segment
		(start 319.909444 -299.59173)
		(end 319.909444 -299.81779)
		(width 0.16002)
		(layer "In11.Cu")
		(net "M_F_CPU0_SB_DQS_DN<3>")
	)
	(segment
		(start 315.85916 -304.004726)
		(end 315.85916 -304.48123)
		(width 0.16002)
		(layer "In11.Cu")
		(net "M_F_CPU0_SB_DQS_DN<3>")
	)
	(segment
		(start 291.1729 -312.881264)
		(end 290.728146 -312.881264)
		(width 0.16002)
		(layer "In11.Cu")
		(net "M_F_CPU0_SB_DQS_DN<3>")
	)
	(segment
		(start 313.518042 -306.209192)
		(end 313.291982 -306.209192)
		(width 0.16002)
		(layer "In11.Cu")
		(net "M_F_CPU0_SB_DQS_DN<3>")
	)
	(segment
		(start 322.72351 -297.140376)
		(end 322.72351 -297.61688)
		(width 0.16002)
		(layer "In11.Cu")
		(net "M_F_CPU0_SB_DQS_DN<3>")
	)
	(segment
		(start 311.672224 -307.82895)
		(end 311.672224 -308.05501)
		(width 0.16002)
		(layer "In11.Cu")
		(net "M_F_CPU0_SB_DQS_DN<3>")
	)
	(segment
		(start 314.959238 -304.904648)
		(end 314.890912 -304.836322)
		(width 0.16002)
		(layer "In11.Cu")
		(net "M_F_CPU0_SB_DQS_DN<3>")
	)
	(segment
		(start 318.6049 -301.258986)
		(end 318.6049 -301.73549)
		(width 0.16002)
		(layer "In11.Cu")
		(net "M_F_CPU0_SB_DQS_DN<3>")
	)
	(segment
		(start 272.071592 -313.511184)
		(end 269.92199 -313.511184)
		(width 0.16002)
		(layer "In11.Cu")
		(net "M_F_CPU0_SB_DQS_DN<3>")
	)
	(segment
		(start 273.820128 -313.362086)
		(end 272.22069 -313.362086)
		(width 0.16002)
		(layer "In11.Cu")
		(net "M_F_CPU0_SB_DQS_DN<3>")
	)
	(segment
		(start 307.631846 -312.881264)
		(end 305.816 -312.881264)
		(width 0.16002)
		(layer "In11.Cu")
		(net "M_F_CPU0_SB_DQS_DN<3>")
	)
	(segment
		(start 296.45229 -313.362086)
		(end 293.998142 -313.362086)
		(width 0.16002)
		(layer "In11.Cu")
		(net "M_F_CPU0_SB_DQS_DN<3>")
	)
	(segment
		(start 311.919112 -307.582062)
		(end 311.672224 -307.82895)
		(width 0.16002)
		(layer "In11.Cu")
		(net "M_F_CPU0_SB_DQS_DN<3>")
	)
	(segment
		(start 323.672962 -296.667428)
		(end 323.196458 -296.667428)
		(width 0.16002)
		(layer "In11.Cu")
		(net "M_F_CPU0_SB_DQS_DN<3>")
	)
	(segment
		(start 288.908236 -313.362086)
		(end 286.454088 -313.362086)
		(width 0.16002)
		(layer "In11.Cu")
		(net "M_F_CPU0_SB_DQS_DN<3>")
	)
	(segment
		(start 315.435742 -304.904648)
		(end 314.959238 -304.904648)
		(width 0.16002)
		(layer "In11.Cu")
		(net "M_F_CPU0_SB_DQS_DN<3>")
	)
	(segment
		(start 314.664852 -304.836322)
		(end 314.417964 -305.08321)
		(width 0.16002)
		(layer "In11.Cu")
		(net "M_F_CPU0_SB_DQS_DN<3>")
	)
	(segment
		(start 318.6049 -301.73549)
		(end 318.181482 -302.158908)
		(width 0.16002)
		(layer "In11.Cu")
		(net "M_F_CPU0_SB_DQS_DN<3>")
	)
	(segment
		(start 320.927222 -299.413168)
		(end 320.450718 -299.413168)
		(width 0.16002)
		(layer "In11.Cu")
		(net "M_F_CPU0_SB_DQS_DN<3>")
	)
	(segment
		(start 276.453854 -312.512202)
		(end 276.084792 -312.881264)
		(width 0.16002)
		(layer "In11.Cu")
		(net "M_F_CPU0_SB_DQS_DN<3>")
	)
	(segment
		(start 298.716954 -312.881264)
		(end 298.2722 -312.881264)
		(width 0.16002)
		(layer "In11.Cu")
		(net "M_F_CPU0_SB_DQS_DN<3>")
	)
	(segment
		(start 290.728146 -312.881264)
		(end 289.902646 -313.706764)
		(width 0.16002)
		(layer "In11.Cu")
		(net "M_F_CPU0_SB_DQS_DN<3>")
	)
	(segment
		(start 286.454088 -313.362086)
		(end 285.604204 -312.512202)
		(width 0.16002)
		(layer "In11.Cu")
		(net "M_F_CPU0_SB_DQS_DN<3>")
	)
	(segment
		(start 311.74055 -308.123336)
		(end 311.74055 -308.77256)
		(width 0.16002)
		(layer "In11.Cu")
		(net "M_F_CPU0_SB_DQS_DN<3>")
	)
	(segment
		(start 319.554352 -300.786038)
		(end 319.077848 -300.786038)
		(width 0.16002)
		(layer "In11.Cu")
		(net "M_F_CPU0_SB_DQS_DN<3>")
	)
	(segment
		(start 313.11342 -307.22697)
		(end 312.690002 -307.650388)
		(width 0.16002)
		(layer "In11.Cu")
		(net "M_F_CPU0_SB_DQS_DN<3>")
	)
	(segment
		(start 313.11342 -306.750466)
		(end 313.11342 -307.22697)
		(width 0.16002)
		(layer "In11.Cu")
		(net "M_F_CPU0_SB_DQS_DN<3>")
	)
	(segment
		(start 314.417964 -305.08321)
		(end 314.417964 -305.30927)
		(width 0.16002)
		(layer "In11.Cu")
		(net "M_F_CPU0_SB_DQS_DN<3>")
	)
	(segment
		(start 321.529202 -297.971972)
		(end 321.282314 -298.21886)
		(width 0.16002)
		(layer "In11.Cu")
		(net "M_F_CPU0_SB_DQS_DN<3>")
	)
	(segment
		(start 319.97777 -300.36262)
		(end 319.554352 -300.786038)
		(width 0.16002)
		(layer "In11.Cu")
		(net "M_F_CPU0_SB_DQS_DN<3>")
	)
	(segment
		(start 330.129642 -290.770818)
		(end 330.12126 -290.765992)
		(width 0.09525)
		(layer "In11.Cu")
		(net "M_F_CPU0_SB_DQS_DN<3>")
	)
	(segment
		(start 275.640038 -312.881264)
		(end 274.814538 -313.706764)
		(width 0.16002)
		(layer "In11.Cu")
		(net "M_F_CPU0_SB_DQS_DN<3>")
	)
	(segment
		(start 320.382392 -299.344842)
		(end 320.156332 -299.344842)
		(width 0.16002)
		(layer "In11.Cu")
		(net "M_F_CPU0_SB_DQS_DN<3>")
	)
	(segment
		(start 316.263782 -303.463452)
		(end 316.037722 -303.463452)
		(width 0.16002)
		(layer "In11.Cu")
		(net "M_F_CPU0_SB_DQS_DN<3>")
	)
	(segment
		(start 296.796968 -313.706764)
		(end 296.45229 -313.362086)
		(width 0.16002)
		(layer "In11.Cu")
		(net "M_F_CPU0_SB_DQS_DN<3>")
	)
	(segment
		(start 316.808612 -303.531778)
		(end 316.332108 -303.531778)
		(width 0.16002)
		(layer "In11.Cu")
		(net "M_F_CPU0_SB_DQS_DN<3>")
	)
	(segment
		(start 324.118986 -296.138346)
		(end 324.118986 -296.221404)
		(width 0.09525)
		(layer "In11.Cu")
		(net "M_F_CPU0_SB_DQS_DN<3>")
	)
	(segment
		(start 324.614794 -295.642538)
		(end 324.118986 -296.138346)
		(width 0.09525)
		(layer "In11.Cu")
		(net "M_F_CPU0_SB_DQS_DN<3>")
	)
	(segment
		(start 274.164806 -313.706764)
		(end 273.820128 -313.362086)
		(width 0.16002)
		(layer "In11.Cu")
		(net "M_F_CPU0_SB_DQS_DN<3>")
	)
	(segment
		(start 317.23203 -303.10836)
		(end 316.808612 -303.531778)
		(width 0.16002)
		(layer "In11.Cu")
		(net "M_F_CPU0_SB_DQS_DN<3>")
	)
	(segment
		(start 312.213498 -307.650388)
		(end 312.145172 -307.582062)
		(width 0.16002)
		(layer "In11.Cu")
		(net "M_F_CPU0_SB_DQS_DN<3>")
	)
	(segment
		(start 298.2722 -312.881264)
		(end 297.4467 -313.706764)
		(width 0.16002)
		(layer "In11.Cu")
		(net "M_F_CPU0_SB_DQS_DN<3>")
	)
	(segment
		(start 315.790834 -303.9364)
		(end 315.85916 -304.004726)
		(width 0.16002)
		(layer "In11.Cu")
		(net "M_F_CPU0_SB_DQS_DN<3>")
	)
	(segment
		(start 317.163704 -302.56353)
		(end 317.23203 -302.631856)
		(width 0.16002)
		(layer "In11.Cu")
		(net "M_F_CPU0_SB_DQS_DN<3>")
	)
	(segment
		(start 293.148258 -312.512202)
		(end 291.541962 -312.512202)
		(width 0.16002)
		(layer "In11.Cu")
		(net "M_F_CPU0_SB_DQS_DN<3>")
	)
	(segment
		(start 293.998142 -313.362086)
		(end 293.148258 -312.512202)
		(width 0.16002)
		(layer "In11.Cu")
		(net "M_F_CPU0_SB_DQS_DN<3>")
	)
	(segment
		(start 317.636652 -302.090582)
		(end 317.410592 -302.090582)
		(width 0.16002)
		(layer "In11.Cu")
		(net "M_F_CPU0_SB_DQS_DN<3>")
	)
	(segment
		(start 281.364182 -313.362086)
		(end 278.910034 -313.362086)
		(width 0.16002)
		(layer "In11.Cu")
		(net "M_F_CPU0_SB_DQS_DN<3>")
	)
	(segment
		(start 301.334932 -313.154822)
		(end 300.692312 -312.512202)
		(width 0.16002)
		(layer "In11.Cu")
		(net "M_F_CPU0_SB_DQS_DN<3>")
	)
	(segment
		(start 319.97777 -299.886116)
		(end 319.97777 -300.36262)
		(width 0.16002)
		(layer "In11.Cu")
		(net "M_F_CPU0_SB_DQS_DN<3>")
	)
	(segment
		(start 318.783462 -300.717712)
		(end 318.536574 -300.9646)
		(width 0.16002)
		(layer "In11.Cu")
		(net "M_F_CPU0_SB_DQS_DN<3>")
	)
	(segment
		(start 322.72351 -297.61688)
		(end 322.300092 -298.040298)
		(width 0.16002)
		(layer "In11.Cu")
		(net "M_F_CPU0_SB_DQS_DN<3>")
	)
	(segment
		(start 321.755262 -297.971972)
		(end 321.529202 -297.971972)
		(width 0.16002)
		(layer "In11.Cu")
		(net "M_F_CPU0_SB_DQS_DN<3>")
	)
	(segment
		(start 318.536574 -301.19066)
		(end 318.6049 -301.258986)
		(width 0.16002)
		(layer "In11.Cu")
		(net "M_F_CPU0_SB_DQS_DN<3>")
	)
	(segment
		(start 323.128132 -296.599102)
		(end 322.902072 -296.599102)
		(width 0.16002)
		(layer "In11.Cu")
		(net "M_F_CPU0_SB_DQS_DN<3>")
	)
	(segment
		(start 317.410592 -302.090582)
		(end 317.163704 -302.33747)
		(width 0.16002)
		(layer "In11.Cu")
		(net "M_F_CPU0_SB_DQS_DN<3>")
	)
	(segment
		(start 313.045094 -306.45608)
		(end 313.045094 -306.68214)
		(width 0.16002)
		(layer "In11.Cu")
		(net "M_F_CPU0_SB_DQS_DN<3>")
	)
	(segment
		(start 312.145172 -307.582062)
		(end 311.919112 -307.582062)
		(width 0.16002)
		(layer "In11.Cu")
		(net "M_F_CPU0_SB_DQS_DN<3>")
	)
	(segment
		(start 278.910034 -313.362086)
		(end 278.06015 -312.512202)
		(width 0.16002)
		(layer "In11.Cu")
		(net "M_F_CPU0_SB_DQS_DN<3>")
	)
	(segment
		(start 316.332108 -303.531778)
		(end 316.263782 -303.463452)
		(width 0.16002)
		(layer "In11.Cu")
		(net "M_F_CPU0_SB_DQS_DN<3>")
	)
	(segment
		(start 302.243744 -313.706764)
		(end 301.691802 -313.154822)
		(width 0.16002)
		(layer "In11.Cu")
		(net "M_F_CPU0_SB_DQS_DN<3>")
	)
	(segment
		(start 315.790834 -303.71034)
		(end 315.790834 -303.9364)
		(width 0.16002)
		(layer "In11.Cu")
		(net "M_F_CPU0_SB_DQS_DN<3>")
	)
	(segment
		(start 291.541962 -312.512202)
		(end 291.1729 -312.881264)
		(width 0.16002)
		(layer "In11.Cu")
		(net "M_F_CPU0_SB_DQS_DN<3>")
	)
	(segment
		(start 316.037722 -303.463452)
		(end 315.790834 -303.71034)
		(width 0.16002)
		(layer "In11.Cu")
		(net "M_F_CPU0_SB_DQS_DN<3>")
	)
	(segment
		(start 299.086016 -312.512202)
		(end 298.716954 -312.881264)
		(width 0.16002)
		(layer "In11.Cu")
		(net "M_F_CPU0_SB_DQS_DN<3>")
	)
	(segment
		(start 319.077848 -300.786038)
		(end 319.009522 -300.717712)
		(width 0.16002)
		(layer "In11.Cu")
		(net "M_F_CPU0_SB_DQS_DN<3>")
	)
	(segment
		(start 321.35064 -298.513246)
		(end 321.35064 -298.98975)
		(width 0.16002)
		(layer "In11.Cu")
		(net "M_F_CPU0_SB_DQS_DN<3>")
	)
	(segment
		(start 289.252914 -313.706764)
		(end 288.908236 -313.362086)
		(width 0.16002)
		(layer "In11.Cu")
		(net "M_F_CPU0_SB_DQS_DN<3>")
	)
	(segment
		(start 289.902646 -313.706764)
		(end 289.252914 -313.706764)
		(width 0.16002)
		(layer "In11.Cu")
		(net "M_F_CPU0_SB_DQS_DN<3>")
	)
	(segment
		(start 332.761082 -291.095938)
		(end 332.607158 -290.830508)
		(width 0.09525)
		(layer "In11.Cu")
		(net "M_F_CPU0_SB_DQS_DN<3>")
	)
	(segment
		(start 319.909444 -299.81779)
		(end 319.97777 -299.886116)
		(width 0.16002)
		(layer "In11.Cu")
		(net "M_F_CPU0_SB_DQS_DN<3>")
	)
	(segment
		(start 318.181482 -302.158908)
		(end 317.704978 -302.158908)
		(width 0.16002)
		(layer "In11.Cu")
		(net "M_F_CPU0_SB_DQS_DN<3>")
	)
	(arc
		(start 331.069696 -290.770818)
		(mid 330.885921 -290.720046)
		(end 330.700888 -290.765992)
		(width 0.09525)
		(layer "In11.Cu")
		(net "M_F_CPU0_SB_DQS_DN<3>")
	)
	(arc
		(start 332.50632 -290.803838)
		(mid 332.496198 -290.807873)
		(end 332.486 -290.811712)
		(width 0.09525)
		(layer "In11.Cu")
		(net "M_F_CPU0_SB_DQS_DN<3>")
	)
	(arc
		(start 329.189588 -290.770818)
		(mid 329.00112 -290.720141)
		(end 328.812652 -290.770818)
		(width 0.09525)
		(layer "In11.Cu")
		(net "M_F_CPU0_SB_DQS_DN<3>")
	)
	(arc
		(start 331.63256 -290.770818)
		(mid 331.351128 -290.846573)
		(end 331.069696 -290.770818)
		(width 0.09525)
		(layer "In11.Cu")
		(net "M_F_CPU0_SB_DQS_DN<3>")
	)
	(arc
		(start 330.12126 -290.765992)
		(mid 329.936228 -290.720078)
		(end 329.752452 -290.770818)
		(width 0.09525)
		(layer "In11.Cu")
		(net "M_F_CPU0_SB_DQS_DN<3>")
	)
	(arc
		(start 328.249788 -290.770818)
		(mid 328.072458 -290.720306)
		(end 327.89241 -290.76015)
		(width 0.09525)
		(layer "In11.Cu")
		(net "M_F_CPU0_SB_DQS_DN<3>")
	)
	(arc
		(start 332.486 -290.811712)
		(mid 332.243288 -290.844595)
		(end 332.00975 -290.770818)
		(width 0.09525)
		(layer "In11.Cu")
		(net "M_F_CPU0_SB_DQS_DN<3>")
	)
	(arc
		(start 327.892156 -290.759388)
		(mid 327.681325 -290.82815)
		(end 327.459594 -290.831778)
		(width 0.09525)
		(layer "In11.Cu")
		(net "M_F_CPU0_SB_DQS_DN<3>")
	)
	(arc
		(start 327.89241 -290.76015)
		(mid 327.892283 -290.759769)
		(end 327.892156 -290.759388)
		(width 0.09525)
		(layer "In11.Cu")
		(net "M_F_CPU0_SB_DQS_DN<3>")
	)
	(arc
		(start 327.459594 -290.831778)
		(mid 327.205646 -290.856369)
		(end 326.988932 -290.991036)
		(width 0.09525)
		(layer "In11.Cu")
		(net "M_F_CPU0_SB_DQS_DN<3>")
	)
	(arc
		(start 330.692506 -290.770818)
		(mid 330.411074 -290.846573)
		(end 330.129642 -290.770818)
		(width 0.09525)
		(layer "In11.Cu")
		(net "M_F_CPU0_SB_DQS_DN<3>")
	)
	(arc
		(start 326.071992 -291.907976)
		(mid 326.03703 -291.960301)
		(end 326.024748 -292.022022)
		(width 0.09525)
		(layer "In11.Cu")
		(net "M_F_CPU0_SB_DQS_DN<3>")
	)
	(arc
		(start 332.00975 -290.770818)
		(mid 331.825975 -290.720046)
		(end 331.640942 -290.765992)
		(width 0.09525)
		(layer "In11.Cu")
		(net "M_F_CPU0_SB_DQS_DN<3>")
	)
	(arc
		(start 329.752452 -290.770818)
		(mid 329.47102 -290.846573)
		(end 329.189588 -290.770818)
		(width 0.09525)
		(layer "In11.Cu")
		(net "M_F_CPU0_SB_DQS_DN<3>")
	)
	(arc
		(start 328.812652 -290.770818)
		(mid 328.53122 -290.846573)
		(end 328.249788 -290.770818)
		(width 0.09525)
		(layer "In11.Cu")
		(net "M_F_CPU0_SB_DQS_DN<3>")
	)
	(segment
		(start 333.227934 -285.970218)
		(end 332.761082 -286.236156)
		(width 0.12954)
		(layer "F.Cu")
		(net "M_F_CPU0_SB_DQS_DN<2>")
	)
	(segment
		(start 313.566302 -296.422064)
		(end 313.319414 -296.668952)
		(width 0.16002)
		(layer "In11.Cu")
		(net "M_F_CPU0_SB_DQS_DN<2>")
	)
	(segment
		(start 309.200804 -301.013876)
		(end 309.252112 -301.065438)
		(width 0.16002)
		(layer "In11.Cu")
		(net "M_F_CPU0_SB_DQS_DN<2>")
	)
	(segment
		(start 316.116462 -294.677338)
		(end 315.693044 -295.100756)
		(width 0.16002)
		(layer "In11.Cu")
		(net "M_F_CPU0_SB_DQS_DN<2>")
	)
	(segment
		(start 317.910718 -292.303454)
		(end 317.684912 -292.303454)
		(width 0.16002)
		(layer "In11.Cu")
		(net "M_F_CPU0_SB_DQS_DN<2>")
	)
	(segment
		(start 308.352444 -301.965106)
		(end 307.879242 -302.438308)
		(width 0.16002)
		(layer "In11.Cu")
		(net "M_F_CPU0_SB_DQS_DN<2>")
	)
	(segment
		(start 315.21654 -295.100756)
		(end 315.164978 -295.049194)
		(width 0.16002)
		(layer "In11.Cu")
		(net "M_F_CPU0_SB_DQS_DN<2>")
	)
	(segment
		(start 315.164978 -295.049194)
		(end 314.939172 -295.049194)
		(width 0.16002)
		(layer "In11.Cu")
		(net "M_F_CPU0_SB_DQS_DN<2>")
	)
	(segment
		(start 307.33746 -303.456594)
		(end 307.157374 -303.53127)
		(width 0.16002)
		(layer "In11.Cu")
		(net "M_F_CPU0_SB_DQS_DN<2>")
	)
	(segment
		(start 316.116462 -294.201088)
		(end 316.116462 -294.677338)
		(width 0.16002)
		(layer "In11.Cu")
		(net "M_F_CPU0_SB_DQS_DN<2>")
	)
	(segment
		(start 310.624982 -300.168818)
		(end 310.201564 -300.592236)
		(width 0.16002)
		(layer "In11.Cu")
		(net "M_F_CPU0_SB_DQS_DN<2>")
	)
	(segment
		(start 314.743592 -295.573958)
		(end 314.743592 -296.050208)
		(width 0.16002)
		(layer "In11.Cu")
		(net "M_F_CPU0_SB_DQS_DN<2>")
	)
	(segment
		(start 311.946544 -298.268136)
		(end 311.997852 -298.319698)
		(width 0.16002)
		(layer "In11.Cu")
		(net "M_F_CPU0_SB_DQS_DN<2>")
	)
	(segment
		(start 311.997852 -298.319698)
		(end 311.997852 -298.795948)
		(width 0.16002)
		(layer "In11.Cu")
		(net "M_F_CPU0_SB_DQS_DN<2>")
	)
	(segment
		(start 273.820128 -304.012092)
		(end 272.22069 -304.012092)
		(width 0.16002)
		(layer "In11.Cu")
		(net "M_F_CPU0_SB_DQS_DN<2>")
	)
	(segment
		(start 307.879242 -302.438308)
		(end 307.879242 -302.914558)
		(width 0.16002)
		(layer "In11.Cu")
		(net "M_F_CPU0_SB_DQS_DN<2>")
	)
	(segment
		(start 276.453854 -303.162208)
		(end 276.084792 -303.53127)
		(width 0.16002)
		(layer "In11.Cu")
		(net "M_F_CPU0_SB_DQS_DN<2>")
	)
	(segment
		(start 291.1729 -303.53127)
		(end 290.728146 -303.53127)
		(width 0.16002)
		(layer "In11.Cu")
		(net "M_F_CPU0_SB_DQS_DN<2>")
	)
	(segment
		(start 309.252112 -301.065438)
		(end 309.252112 -301.541688)
		(width 0.16002)
		(layer "In11.Cu")
		(net "M_F_CPU0_SB_DQS_DN<2>")
	)
	(segment
		(start 316.312042 -293.676324)
		(end 316.065154 -293.923212)
		(width 0.16002)
		(layer "In11.Cu")
		(net "M_F_CPU0_SB_DQS_DN<2>")
	)
	(segment
		(start 316.065154 -293.923212)
		(end 316.065154 -294.149526)
		(width 0.16002)
		(layer "In11.Cu")
		(net "M_F_CPU0_SB_DQS_DN<2>")
	)
	(segment
		(start 313.319414 -296.895266)
		(end 313.370722 -296.946828)
		(width 0.16002)
		(layer "In11.Cu")
		(net "M_F_CPU0_SB_DQS_DN<2>")
	)
	(segment
		(start 269.92199 -304.16119)
		(end 269.648178 -304.435002)
		(width 0.16002)
		(layer "In11.Cu")
		(net "M_F_CPU0_SB_DQS_DN<2>")
	)
	(segment
		(start 309.252112 -301.541688)
		(end 308.828694 -301.965106)
		(width 0.16002)
		(layer "In11.Cu")
		(net "M_F_CPU0_SB_DQS_DN<2>")
	)
	(segment
		(start 304.9905 -304.35677)
		(end 302.243744 -304.35677)
		(width 0.16002)
		(layer "In11.Cu")
		(net "M_F_CPU0_SB_DQS_DN<2>")
	)
	(segment
		(start 318.862202 -291.931598)
		(end 318.438784 -292.355016)
		(width 0.16002)
		(layer "In11.Cu")
		(net "M_F_CPU0_SB_DQS_DN<2>")
	)
	(segment
		(start 307.157374 -303.53127)
		(end 305.816 -303.53127)
		(width 0.16002)
		(layer "In11.Cu")
		(net "M_F_CPU0_SB_DQS_DN<2>")
	)
	(segment
		(start 324.562724 -286.764476)
		(end 324.02653 -286.764476)
		(width 0.16002)
		(layer "In11.Cu")
		(net "M_F_CPU0_SB_DQS_DN<2>")
	)
	(segment
		(start 317.684912 -292.303454)
		(end 317.438024 -292.550342)
		(width 0.16002)
		(layer "In11.Cu")
		(net "M_F_CPU0_SB_DQS_DN<2>")
	)
	(segment
		(start 318.438784 -292.355016)
		(end 317.96228 -292.355016)
		(width 0.16002)
		(layer "In11.Cu")
		(net "M_F_CPU0_SB_DQS_DN<2>")
	)
	(segment
		(start 315.693044 -295.100756)
		(end 315.21654 -295.100756)
		(width 0.16002)
		(layer "In11.Cu")
		(net "M_F_CPU0_SB_DQS_DN<2>")
	)
	(segment
		(start 309.673498 -300.540674)
		(end 309.447692 -300.540674)
		(width 0.16002)
		(layer "In11.Cu")
		(net "M_F_CPU0_SB_DQS_DN<2>")
	)
	(segment
		(start 314.939172 -295.049194)
		(end 314.692284 -295.296082)
		(width 0.16002)
		(layer "In11.Cu")
		(net "M_F_CPU0_SB_DQS_DN<2>")
	)
	(segment
		(start 307.879242 -302.914558)
		(end 307.33746 -303.456594)
		(width 0.16002)
		(layer "In11.Cu")
		(net "M_F_CPU0_SB_DQS_DN<2>")
	)
	(segment
		(start 313.370722 -297.423078)
		(end 312.947304 -297.846496)
		(width 0.16002)
		(layer "In11.Cu")
		(net "M_F_CPU0_SB_DQS_DN<2>")
	)
	(segment
		(start 283.997908 -303.162208)
		(end 283.628846 -303.53127)
		(width 0.16002)
		(layer "In11.Cu")
		(net "M_F_CPU0_SB_DQS_DN<2>")
	)
	(segment
		(start 286.454088 -304.012092)
		(end 285.604204 -303.162208)
		(width 0.16002)
		(layer "In11.Cu")
		(net "M_F_CPU0_SB_DQS_DN<2>")
	)
	(segment
		(start 309.200804 -300.787562)
		(end 309.200804 -301.013876)
		(width 0.16002)
		(layer "In11.Cu")
		(net "M_F_CPU0_SB_DQS_DN<2>")
	)
	(segment
		(start 320.235072 -290.558728)
		(end 319.811654 -290.982146)
		(width 0.16002)
		(layer "In11.Cu")
		(net "M_F_CPU0_SB_DQS_DN<2>")
	)
	(segment
		(start 300.692312 -303.162208)
		(end 299.086016 -303.162208)
		(width 0.16002)
		(layer "In11.Cu")
		(net "M_F_CPU0_SB_DQS_DN<2>")
	)
	(segment
		(start 314.320174 -296.473626)
		(end 313.84367 -296.473626)
		(width 0.16002)
		(layer "In11.Cu")
		(net "M_F_CPU0_SB_DQS_DN<2>")
	)
	(segment
		(start 319.057782 -290.930584)
		(end 318.810894 -291.177472)
		(width 0.16002)
		(layer "In11.Cu")
		(net "M_F_CPU0_SB_DQS_DN<2>")
	)
	(segment
		(start 332.607158 -285.970726)
		(end 332.50632 -285.944056)
		(width 0.09525)
		(layer "In11.Cu")
		(net "M_F_CPU0_SB_DQS_DN<2>")
	)
	(segment
		(start 316.065154 -294.149526)
		(end 316.116462 -294.201088)
		(width 0.16002)
		(layer "In11.Cu")
		(net "M_F_CPU0_SB_DQS_DN<2>")
	)
	(segment
		(start 318.810894 -291.177472)
		(end 318.810894 -291.403786)
		(width 0.16002)
		(layer "In11.Cu")
		(net "M_F_CPU0_SB_DQS_DN<2>")
	)
	(segment
		(start 296.45229 -304.012092)
		(end 293.998142 -304.012092)
		(width 0.16002)
		(layer "In11.Cu")
		(net "M_F_CPU0_SB_DQS_DN<2>")
	)
	(segment
		(start 313.792108 -296.422064)
		(end 313.566302 -296.422064)
		(width 0.16002)
		(layer "In11.Cu")
		(net "M_F_CPU0_SB_DQS_DN<2>")
	)
	(segment
		(start 321.233292 -289.557714)
		(end 320.430652 -289.557714)
		(width 0.16002)
		(layer "In11.Cu")
		(net "M_F_CPU0_SB_DQS_DN<2>")
	)
	(segment
		(start 327.31075 -285.911036)
		(end 327.298812 -285.904178)
		(width 0.09525)
		(layer "In11.Cu")
		(net "M_F_CPU0_SB_DQS_DN<2>")
	)
	(segment
		(start 311.046368 -299.167804)
		(end 310.820562 -299.167804)
		(width 0.16002)
		(layer "In11.Cu")
		(net "M_F_CPU0_SB_DQS_DN<2>")
	)
	(segment
		(start 301.691802 -303.804828)
		(end 301.334932 -303.804828)
		(width 0.16002)
		(layer "In11.Cu")
		(net "M_F_CPU0_SB_DQS_DN<2>")
	)
	(segment
		(start 289.902646 -304.35677)
		(end 289.252914 -304.35677)
		(width 0.16002)
		(layer "In11.Cu")
		(net "M_F_CPU0_SB_DQS_DN<2>")
	)
	(segment
		(start 330.129642 -285.911036)
		(end 330.12126 -285.90621)
		(width 0.09525)
		(layer "In11.Cu")
		(net "M_F_CPU0_SB_DQS_DN<2>")
	)
	(segment
		(start 272.22069 -304.012092)
		(end 272.071592 -304.16119)
		(width 0.16002)
		(layer "In11.Cu")
		(net "M_F_CPU0_SB_DQS_DN<2>")
	)
	(segment
		(start 319.33515 -290.982146)
		(end 319.283588 -290.930584)
		(width 0.16002)
		(layer "In11.Cu")
		(net "M_F_CPU0_SB_DQS_DN<2>")
	)
	(segment
		(start 320.430652 -289.557714)
		(end 320.183764 -289.804602)
		(width 0.16002)
		(layer "In11.Cu")
		(net "M_F_CPU0_SB_DQS_DN<2>")
	)
	(segment
		(start 281.364182 -304.012092)
		(end 278.910034 -304.012092)
		(width 0.16002)
		(layer "In11.Cu")
		(net "M_F_CPU0_SB_DQS_DN<2>")
	)
	(segment
		(start 272.071592 -304.16119)
		(end 269.92199 -304.16119)
		(width 0.16002)
		(layer "In11.Cu")
		(net "M_F_CPU0_SB_DQS_DN<2>")
	)
	(segment
		(start 332.761082 -286.236156)
		(end 332.607158 -285.970726)
		(width 0.09525)
		(layer "In11.Cu")
		(net "M_F_CPU0_SB_DQS_DN<2>")
	)
	(segment
		(start 310.624982 -299.692568)
		(end 310.624982 -300.168818)
		(width 0.16002)
		(layer "In11.Cu")
		(net "M_F_CPU0_SB_DQS_DN<2>")
	)
	(segment
		(start 305.816 -303.53127)
		(end 304.9905 -304.35677)
		(width 0.16002)
		(layer "In11.Cu")
		(net "M_F_CPU0_SB_DQS_DN<2>")
	)
	(segment
		(start 320.235072 -290.082478)
		(end 320.235072 -290.558728)
		(width 0.16002)
		(layer "In11.Cu")
		(net "M_F_CPU0_SB_DQS_DN<2>")
	)
	(segment
		(start 327.88479 -285.904178)
		(end 327.872852 -285.911036)
		(width 0.09525)
		(layer "In11.Cu")
		(net "M_F_CPU0_SB_DQS_DN<2>")
	)
	(segment
		(start 312.947304 -297.846496)
		(end 312.4708 -297.846496)
		(width 0.16002)
		(layer "In11.Cu")
		(net "M_F_CPU0_SB_DQS_DN<2>")
	)
	(segment
		(start 317.065914 -293.727886)
		(end 316.58941 -293.727886)
		(width 0.16002)
		(layer "In11.Cu")
		(net "M_F_CPU0_SB_DQS_DN<2>")
	)
	(segment
		(start 278.910034 -304.012092)
		(end 278.06015 -303.162208)
		(width 0.16002)
		(layer "In11.Cu")
		(net "M_F_CPU0_SB_DQS_DN<2>")
	)
	(segment
		(start 298.716954 -303.53127)
		(end 298.2722 -303.53127)
		(width 0.16002)
		(layer "In11.Cu")
		(net "M_F_CPU0_SB_DQS_DN<2>")
	)
	(segment
		(start 288.908236 -304.012092)
		(end 286.454088 -304.012092)
		(width 0.16002)
		(layer "In11.Cu")
		(net "M_F_CPU0_SB_DQS_DN<2>")
	)
	(segment
		(start 317.96228 -292.355016)
		(end 317.910718 -292.303454)
		(width 0.16002)
		(layer "In11.Cu")
		(net "M_F_CPU0_SB_DQS_DN<2>")
	)
	(segment
		(start 316.58941 -293.727886)
		(end 316.537848 -293.676324)
		(width 0.16002)
		(layer "In11.Cu")
		(net "M_F_CPU0_SB_DQS_DN<2>")
	)
	(segment
		(start 275.640038 -303.53127)
		(end 274.814538 -304.35677)
		(width 0.16002)
		(layer "In11.Cu")
		(net "M_F_CPU0_SB_DQS_DN<2>")
	)
	(segment
		(start 310.820562 -299.167804)
		(end 310.573674 -299.414692)
		(width 0.16002)
		(layer "In11.Cu")
		(net "M_F_CPU0_SB_DQS_DN<2>")
	)
	(segment
		(start 311.997852 -298.795948)
		(end 311.574434 -299.219366)
		(width 0.16002)
		(layer "In11.Cu")
		(net "M_F_CPU0_SB_DQS_DN<2>")
	)
	(segment
		(start 301.334932 -303.804828)
		(end 300.692312 -303.162208)
		(width 0.16002)
		(layer "In11.Cu")
		(net "M_F_CPU0_SB_DQS_DN<2>")
	)
	(segment
		(start 290.728146 -303.53127)
		(end 289.902646 -304.35677)
		(width 0.16002)
		(layer "In11.Cu")
		(net "M_F_CPU0_SB_DQS_DN<2>")
	)
	(segment
		(start 312.419238 -297.794934)
		(end 312.193432 -297.794934)
		(width 0.16002)
		(layer "In11.Cu")
		(net "M_F_CPU0_SB_DQS_DN<2>")
	)
	(segment
		(start 319.811654 -290.982146)
		(end 319.33515 -290.982146)
		(width 0.16002)
		(layer "In11.Cu")
		(net "M_F_CPU0_SB_DQS_DN<2>")
	)
	(segment
		(start 289.252914 -304.35677)
		(end 288.908236 -304.012092)
		(width 0.16002)
		(layer "In11.Cu")
		(net "M_F_CPU0_SB_DQS_DN<2>")
	)
	(segment
		(start 293.998142 -304.012092)
		(end 293.148258 -303.162208)
		(width 0.16002)
		(layer "In11.Cu")
		(net "M_F_CPU0_SB_DQS_DN<2>")
	)
	(segment
		(start 317.489332 -292.828218)
		(end 317.489332 -293.304468)
		(width 0.16002)
		(layer "In11.Cu")
		(net "M_F_CPU0_SB_DQS_DN<2>")
	)
	(segment
		(start 282.358592 -304.35677)
		(end 281.70886 -304.35677)
		(width 0.16002)
		(layer "In11.Cu")
		(net "M_F_CPU0_SB_DQS_DN<2>")
	)
	(segment
		(start 319.283588 -290.930584)
		(end 319.057782 -290.930584)
		(width 0.16002)
		(layer "In11.Cu")
		(net "M_F_CPU0_SB_DQS_DN<2>")
	)
	(segment
		(start 276.084792 -303.53127)
		(end 275.640038 -303.53127)
		(width 0.16002)
		(layer "In11.Cu")
		(net "M_F_CPU0_SB_DQS_DN<2>")
	)
	(segment
		(start 313.84367 -296.473626)
		(end 313.792108 -296.422064)
		(width 0.16002)
		(layer "In11.Cu")
		(net "M_F_CPU0_SB_DQS_DN<2>")
	)
	(segment
		(start 326.651112 -285.987236)
		(end 325.939658 -285.987236)
		(width 0.09525)
		(layer "In11.Cu")
		(net "M_F_CPU0_SB_DQS_DN<2>")
	)
	(segment
		(start 318.862202 -291.455348)
		(end 318.862202 -291.931598)
		(width 0.16002)
		(layer "In11.Cu")
		(net "M_F_CPU0_SB_DQS_DN<2>")
	)
	(segment
		(start 325.221346 -286.705548)
		(end 324.645274 -286.705548)
		(width 0.09525)
		(layer "In11.Cu")
		(net "M_F_CPU0_SB_DQS_DN<2>")
	)
	(segment
		(start 285.604204 -303.162208)
		(end 283.997908 -303.162208)
		(width 0.16002)
		(layer "In11.Cu")
		(net "M_F_CPU0_SB_DQS_DN<2>")
	)
	(segment
		(start 331.640942 -285.90621)
		(end 331.63256 -285.911036)
		(width 0.09525)
		(layer "In11.Cu")
		(net "M_F_CPU0_SB_DQS_DN<2>")
	)
	(segment
		(start 324.02653 -286.764476)
		(end 321.233292 -289.557714)
		(width 0.16002)
		(layer "In11.Cu")
		(net "M_F_CPU0_SB_DQS_DN<2>")
	)
	(segment
		(start 327.872852 -285.911036)
		(end 327.854818 -285.92145)
		(width 0.09525)
		(layer "In11.Cu")
		(net "M_F_CPU0_SB_DQS_DN<2>")
	)
	(segment
		(start 283.628846 -303.53127)
		(end 283.184092 -303.53127)
		(width 0.16002)
		(layer "In11.Cu")
		(net "M_F_CPU0_SB_DQS_DN<2>")
	)
	(segment
		(start 309.72506 -300.592236)
		(end 309.673498 -300.540674)
		(width 0.16002)
		(layer "In11.Cu")
		(net "M_F_CPU0_SB_DQS_DN<2>")
	)
	(segment
		(start 316.537848 -293.676324)
		(end 316.312042 -293.676324)
		(width 0.16002)
		(layer "In11.Cu")
		(net "M_F_CPU0_SB_DQS_DN<2>")
	)
	(segment
		(start 320.183764 -289.804602)
		(end 320.183764 -290.030916)
		(width 0.16002)
		(layer "In11.Cu")
		(net "M_F_CPU0_SB_DQS_DN<2>")
	)
	(segment
		(start 317.438024 -292.550342)
		(end 317.438024 -292.776656)
		(width 0.16002)
		(layer "In11.Cu")
		(net "M_F_CPU0_SB_DQS_DN<2>")
	)
	(segment
		(start 324.586346 -286.764476)
		(end 324.562724 -286.764476)
		(width 0.09525)
		(layer "In11.Cu")
		(net "M_F_CPU0_SB_DQS_DN<2>")
	)
	(segment
		(start 278.06015 -303.162208)
		(end 276.453854 -303.162208)
		(width 0.16002)
		(layer "In11.Cu")
		(net "M_F_CPU0_SB_DQS_DN<2>")
	)
	(segment
		(start 317.489332 -293.304468)
		(end 317.065914 -293.727886)
		(width 0.16002)
		(layer "In11.Cu")
		(net "M_F_CPU0_SB_DQS_DN<2>")
	)
	(segment
		(start 317.438024 -292.776656)
		(end 317.489332 -292.828218)
		(width 0.16002)
		(layer "In11.Cu")
		(net "M_F_CPU0_SB_DQS_DN<2>")
	)
	(segment
		(start 302.243744 -304.35677)
		(end 301.691802 -303.804828)
		(width 0.16002)
		(layer "In11.Cu")
		(net "M_F_CPU0_SB_DQS_DN<2>")
	)
	(segment
		(start 310.573674 -299.414692)
		(end 310.573674 -299.641006)
		(width 0.16002)
		(layer "In11.Cu")
		(net "M_F_CPU0_SB_DQS_DN<2>")
	)
	(segment
		(start 310.573674 -299.641006)
		(end 310.624982 -299.692568)
		(width 0.16002)
		(layer "In11.Cu")
		(net "M_F_CPU0_SB_DQS_DN<2>")
	)
	(segment
		(start 312.193432 -297.794934)
		(end 311.946544 -298.041822)
		(width 0.16002)
		(layer "In11.Cu")
		(net "M_F_CPU0_SB_DQS_DN<2>")
	)
	(segment
		(start 311.946544 -298.041822)
		(end 311.946544 -298.268136)
		(width 0.16002)
		(layer "In11.Cu")
		(net "M_F_CPU0_SB_DQS_DN<2>")
	)
	(segment
		(start 308.828694 -301.965106)
		(end 308.352444 -301.965106)
		(width 0.16002)
		(layer "In11.Cu")
		(net "M_F_CPU0_SB_DQS_DN<2>")
	)
	(segment
		(start 312.4708 -297.846496)
		(end 312.419238 -297.794934)
		(width 0.16002)
		(layer "In11.Cu")
		(net "M_F_CPU0_SB_DQS_DN<2>")
	)
	(segment
		(start 291.541962 -303.162208)
		(end 291.1729 -303.53127)
		(width 0.16002)
		(layer "In11.Cu")
		(net "M_F_CPU0_SB_DQS_DN<2>")
	)
	(segment
		(start 318.810894 -291.403786)
		(end 318.862202 -291.455348)
		(width 0.16002)
		(layer "In11.Cu")
		(net "M_F_CPU0_SB_DQS_DN<2>")
	)
	(segment
		(start 310.201564 -300.592236)
		(end 309.72506 -300.592236)
		(width 0.16002)
		(layer "In11.Cu")
		(net "M_F_CPU0_SB_DQS_DN<2>")
	)
	(segment
		(start 313.370722 -296.946828)
		(end 313.370722 -297.423078)
		(width 0.16002)
		(layer "In11.Cu")
		(net "M_F_CPU0_SB_DQS_DN<2>")
	)
	(segment
		(start 313.319414 -296.668952)
		(end 313.319414 -296.895266)
		(width 0.16002)
		(layer "In11.Cu")
		(net "M_F_CPU0_SB_DQS_DN<2>")
	)
	(segment
		(start 314.692284 -295.522396)
		(end 314.743592 -295.573958)
		(width 0.16002)
		(layer "In11.Cu")
		(net "M_F_CPU0_SB_DQS_DN<2>")
	)
	(segment
		(start 311.574434 -299.219366)
		(end 311.09793 -299.219366)
		(width 0.16002)
		(layer "In11.Cu")
		(net "M_F_CPU0_SB_DQS_DN<2>")
	)
	(segment
		(start 281.70886 -304.35677)
		(end 281.364182 -304.012092)
		(width 0.16002)
		(layer "In11.Cu")
		(net "M_F_CPU0_SB_DQS_DN<2>")
	)
	(segment
		(start 314.692284 -295.296082)
		(end 314.692284 -295.522396)
		(width 0.16002)
		(layer "In11.Cu")
		(net "M_F_CPU0_SB_DQS_DN<2>")
	)
	(segment
		(start 309.447692 -300.540674)
		(end 309.200804 -300.787562)
		(width 0.16002)
		(layer "In11.Cu")
		(net "M_F_CPU0_SB_DQS_DN<2>")
	)
	(segment
		(start 283.184092 -303.53127)
		(end 282.358592 -304.35677)
		(width 0.16002)
		(layer "In11.Cu")
		(net "M_F_CPU0_SB_DQS_DN<2>")
	)
	(segment
		(start 296.796968 -304.35677)
		(end 296.45229 -304.012092)
		(width 0.16002)
		(layer "In11.Cu")
		(net "M_F_CPU0_SB_DQS_DN<2>")
	)
	(segment
		(start 324.645274 -286.705548)
		(end 324.586346 -286.764476)
		(width 0.09525)
		(layer "In11.Cu")
		(net "M_F_CPU0_SB_DQS_DN<2>")
	)
	(segment
		(start 311.09793 -299.219366)
		(end 311.046368 -299.167804)
		(width 0.16002)
		(layer "In11.Cu")
		(net "M_F_CPU0_SB_DQS_DN<2>")
	)
	(segment
		(start 298.2722 -303.53127)
		(end 297.4467 -304.35677)
		(width 0.16002)
		(layer "In11.Cu")
		(net "M_F_CPU0_SB_DQS_DN<2>")
	)
	(segment
		(start 325.939658 -285.987236)
		(end 325.221346 -286.705548)
		(width 0.09525)
		(layer "In11.Cu")
		(net "M_F_CPU0_SB_DQS_DN<2>")
	)
	(segment
		(start 274.164806 -304.35677)
		(end 273.820128 -304.012092)
		(width 0.16002)
		(layer "In11.Cu")
		(net "M_F_CPU0_SB_DQS_DN<2>")
	)
	(segment
		(start 299.086016 -303.162208)
		(end 298.716954 -303.53127)
		(width 0.16002)
		(layer "In11.Cu")
		(net "M_F_CPU0_SB_DQS_DN<2>")
	)
	(segment
		(start 330.700888 -285.90621)
		(end 330.692506 -285.911036)
		(width 0.09525)
		(layer "In11.Cu")
		(net "M_F_CPU0_SB_DQS_DN<2>")
	)
	(segment
		(start 274.814538 -304.35677)
		(end 274.164806 -304.35677)
		(width 0.16002)
		(layer "In11.Cu")
		(net "M_F_CPU0_SB_DQS_DN<2>")
	)
	(segment
		(start 297.4467 -304.35677)
		(end 296.796968 -304.35677)
		(width 0.16002)
		(layer "In11.Cu")
		(net "M_F_CPU0_SB_DQS_DN<2>")
	)
	(segment
		(start 314.743592 -296.050208)
		(end 314.320174 -296.473626)
		(width 0.16002)
		(layer "In11.Cu")
		(net "M_F_CPU0_SB_DQS_DN<2>")
	)
	(segment
		(start 320.183764 -290.030916)
		(end 320.235072 -290.082478)
		(width 0.16002)
		(layer "In11.Cu")
		(net "M_F_CPU0_SB_DQS_DN<2>")
	)
	(segment
		(start 293.148258 -303.162208)
		(end 291.541962 -303.162208)
		(width 0.16002)
		(layer "In11.Cu")
		(net "M_F_CPU0_SB_DQS_DN<2>")
	)
	(arc
		(start 332.486 -285.95193)
		(mid 332.243288 -285.984813)
		(end 332.00975 -285.911036)
		(width 0.09525)
		(layer "In11.Cu")
		(net "M_F_CPU0_SB_DQS_DN<2>")
	)
	(arc
		(start 327.854818 -285.92145)
		(mid 327.581438 -285.986671)
		(end 327.31075 -285.911036)
		(width 0.09525)
		(layer "In11.Cu")
		(net "M_F_CPU0_SB_DQS_DN<2>")
	)
	(arc
		(start 330.692506 -285.911036)
		(mid 330.411074 -285.986791)
		(end 330.129642 -285.911036)
		(width 0.09525)
		(layer "In11.Cu")
		(net "M_F_CPU0_SB_DQS_DN<2>")
	)
	(arc
		(start 332.50632 -285.944056)
		(mid 332.496198 -285.948091)
		(end 332.486 -285.95193)
		(width 0.09525)
		(layer "In11.Cu")
		(net "M_F_CPU0_SB_DQS_DN<2>")
	)
	(arc
		(start 328.249788 -285.911036)
		(mid 328.068172 -285.860299)
		(end 327.88479 -285.904178)
		(width 0.09525)
		(layer "In11.Cu")
		(net "M_F_CPU0_SB_DQS_DN<2>")
	)
	(arc
		(start 332.00975 -285.911036)
		(mid 331.825975 -285.860264)
		(end 331.640942 -285.90621)
		(width 0.09525)
		(layer "In11.Cu")
		(net "M_F_CPU0_SB_DQS_DN<2>")
	)
	(arc
		(start 329.752452 -285.911036)
		(mid 329.47102 -285.986791)
		(end 329.189588 -285.911036)
		(width 0.09525)
		(layer "In11.Cu")
		(net "M_F_CPU0_SB_DQS_DN<2>")
	)
	(arc
		(start 328.812652 -285.911036)
		(mid 328.53122 -285.986791)
		(end 328.249788 -285.911036)
		(width 0.09525)
		(layer "In11.Cu")
		(net "M_F_CPU0_SB_DQS_DN<2>")
	)
	(arc
		(start 331.63256 -285.911036)
		(mid 331.351128 -285.986791)
		(end 331.069696 -285.911036)
		(width 0.09525)
		(layer "In11.Cu")
		(net "M_F_CPU0_SB_DQS_DN<2>")
	)
	(arc
		(start 326.933306 -285.911036)
		(mid 326.797254 -285.967805)
		(end 326.651112 -285.987236)
		(width 0.09525)
		(layer "In11.Cu")
		(net "M_F_CPU0_SB_DQS_DN<2>")
	)
	(arc
		(start 330.12126 -285.90621)
		(mid 329.936228 -285.860296)
		(end 329.752452 -285.911036)
		(width 0.09525)
		(layer "In11.Cu")
		(net "M_F_CPU0_SB_DQS_DN<2>")
	)
	(arc
		(start 329.189588 -285.911036)
		(mid 329.00112 -285.860359)
		(end 328.812652 -285.911036)
		(width 0.09525)
		(layer "In11.Cu")
		(net "M_F_CPU0_SB_DQS_DN<2>")
	)
	(arc
		(start 327.298812 -285.904178)
		(mid 327.115177 -285.860228)
		(end 326.933306 -285.911036)
		(width 0.09525)
		(layer "In11.Cu")
		(net "M_F_CPU0_SB_DQS_DN<2>")
	)
	(arc
		(start 331.069696 -285.911036)
		(mid 330.885921 -285.860264)
		(end 330.700888 -285.90621)
		(width 0.09525)
		(layer "In11.Cu")
		(net "M_F_CPU0_SB_DQS_DN<2>")
	)
	(segment
		(start 333.227934 -281.110182)
		(end 332.761082 -281.37612)
		(width 0.12954)
		(layer "F.Cu")
		(net "M_F_CPU0_SB_DQS_DN<1>")
	)
	(segment
		(start 275.640038 -294.181276)
		(end 276.084792 -294.181276)
		(width 0.16002)
		(layer "In11.Cu")
		(net "M_F_CPU0_SB_DQS_DN<1>")
	)
	(segment
		(start 299.086016 -293.812214)
		(end 300.692312 -293.812214)
		(width 0.16002)
		(layer "In11.Cu")
		(net "M_F_CPU0_SB_DQS_DN<1>")
	)
	(segment
		(start 313.595004 -287.927034)
		(end 314.071508 -287.927034)
		(width 0.16002)
		(layer "In11.Cu")
		(net "M_F_CPU0_SB_DQS_DN<1>")
	)
	(segment
		(start 330.692506 -281.051)
		(end 330.700888 -281.046174)
		(width 0.09525)
		(layer "In11.Cu")
		(net "M_F_CPU0_SB_DQS_DN<1>")
	)
	(segment
		(start 310.733694 -290.560252)
		(end 310.84774 -290.674298)
		(width 0.16002)
		(layer "In11.Cu")
		(net "M_F_CPU0_SB_DQS_DN<1>")
	)
	(segment
		(start 327.298812 -281.044142)
		(end 327.31075 -281.051)
		(width 0.09525)
		(layer "In11.Cu")
		(net "M_F_CPU0_SB_DQS_DN<1>")
	)
	(segment
		(start 276.084792 -294.181276)
		(end 276.453854 -293.812214)
		(width 0.16002)
		(layer "In11.Cu")
		(net "M_F_CPU0_SB_DQS_DN<1>")
	)
	(segment
		(start 313.008264 -288.059622)
		(end 313.254898 -287.812988)
		(width 0.16002)
		(layer "In11.Cu")
		(net "M_F_CPU0_SB_DQS_DN<1>")
	)
	(segment
		(start 309.001414 -292.997128)
		(end 309.001414 -292.493446)
		(width 0.16002)
		(layer "In11.Cu")
		(net "M_F_CPU0_SB_DQS_DN<1>")
	)
	(segment
		(start 308.57698 -293.421562)
		(end 309.001414 -292.997128)
		(width 0.16002)
		(layer "In11.Cu")
		(net "M_F_CPU0_SB_DQS_DN<1>")
	)
	(segment
		(start 291.1729 -294.181276)
		(end 291.541962 -293.812214)
		(width 0.16002)
		(layer "In11.Cu")
		(net "M_F_CPU0_SB_DQS_DN<1>")
	)
	(segment
		(start 311.324244 -290.674298)
		(end 311.748678 -290.249864)
		(width 0.16002)
		(layer "In11.Cu")
		(net "M_F_CPU0_SB_DQS_DN<1>")
	)
	(segment
		(start 269.648178 -295.085008)
		(end 269.92199 -294.811196)
		(width 0.16002)
		(layer "In11.Cu")
		(net "M_F_CPU0_SB_DQS_DN<1>")
	)
	(segment
		(start 301.334932 -294.454834)
		(end 301.691802 -294.454834)
		(width 0.16002)
		(layer "In11.Cu")
		(net "M_F_CPU0_SB_DQS_DN<1>")
	)
	(segment
		(start 319.566036 -282.432506)
		(end 319.99047 -282.008072)
		(width 0.16002)
		(layer "In11.Cu")
		(net "M_F_CPU0_SB_DQS_DN<1>")
	)
	(segment
		(start 291.541962 -293.812214)
		(end 293.148258 -293.812214)
		(width 0.16002)
		(layer "In11.Cu")
		(net "M_F_CPU0_SB_DQS_DN<1>")
	)
	(segment
		(start 316.002162 -285.065724)
		(end 316.228222 -285.065724)
		(width 0.16002)
		(layer "In11.Cu")
		(net "M_F_CPU0_SB_DQS_DN<1>")
	)
	(segment
		(start 318.616838 -283.381704)
		(end 318.616838 -282.878022)
		(width 0.16002)
		(layer "In11.Cu")
		(net "M_F_CPU0_SB_DQS_DN<1>")
	)
	(segment
		(start 315.869574 -285.652464)
		(end 315.755528 -285.538418)
		(width 0.16002)
		(layer "In11.Cu")
		(net "M_F_CPU0_SB_DQS_DN<1>")
	)
	(segment
		(start 310.375046 -291.146992)
		(end 310.261 -291.032946)
		(width 0.16002)
		(layer "In11.Cu")
		(net "M_F_CPU0_SB_DQS_DN<1>")
	)
	(segment
		(start 327.872852 -281.051)
		(end 327.88479 -281.044142)
		(width 0.09525)
		(layer "In11.Cu")
		(net "M_F_CPU0_SB_DQS_DN<1>")
	)
	(segment
		(start 308.073298 -293.421562)
		(end 308.57698 -293.421562)
		(width 0.16002)
		(layer "In11.Cu")
		(net "M_F_CPU0_SB_DQS_DN<1>")
	)
	(segment
		(start 330.12126 -281.046174)
		(end 330.129642 -281.051)
		(width 0.09525)
		(layer "In11.Cu")
		(net "M_F_CPU0_SB_DQS_DN<1>")
	)
	(segment
		(start 318.616838 -282.878022)
		(end 319.062354 -282.432506)
		(width 0.16002)
		(layer "In11.Cu")
		(net "M_F_CPU0_SB_DQS_DN<1>")
	)
	(segment
		(start 319.062354 -282.432506)
		(end 319.566036 -282.432506)
		(width 0.16002)
		(layer "In11.Cu")
		(net "M_F_CPU0_SB_DQS_DN<1>")
	)
	(segment
		(start 313.254898 -287.812988)
		(end 313.480958 -287.812988)
		(width 0.16002)
		(layer "In11.Cu")
		(net "M_F_CPU0_SB_DQS_DN<1>")
	)
	(segment
		(start 274.164806 -295.006776)
		(end 274.814538 -295.006776)
		(width 0.16002)
		(layer "In11.Cu")
		(net "M_F_CPU0_SB_DQS_DN<1>")
	)
	(segment
		(start 318.192404 -283.806138)
		(end 318.616838 -283.381704)
		(width 0.16002)
		(layer "In11.Cu")
		(net "M_F_CPU0_SB_DQS_DN<1>")
	)
	(segment
		(start 324.409054 -281.023568)
		(end 324.695312 -280.73731)
		(width 0.09525)
		(layer "In11.Cu")
		(net "M_F_CPU0_SB_DQS_DN<1>")
	)
	(segment
		(start 323.919596 -281.08275)
		(end 323.978778 -281.023568)
		(width 0.09525)
		(layer "In11.Cu")
		(net "M_F_CPU0_SB_DQS_DN<1>")
	)
	(segment
		(start 283.997908 -293.812214)
		(end 285.604204 -293.812214)
		(width 0.16002)
		(layer "In11.Cu")
		(net "M_F_CPU0_SB_DQS_DN<1>")
	)
	(segment
		(start 331.63256 -281.051)
		(end 331.640942 -281.046174)
		(width 0.09525)
		(layer "In11.Cu")
		(net "M_F_CPU0_SB_DQS_DN<1>")
	)
	(segment
		(start 314.85459 -286.439356)
		(end 314.968636 -286.553402)
		(width 0.16002)
		(layer "In11.Cu")
		(net "M_F_CPU0_SB_DQS_DN<1>")
	)
	(segment
		(start 314.381896 -286.91205)
		(end 314.381896 -286.68599)
		(width 0.16002)
		(layer "In11.Cu")
		(net "M_F_CPU0_SB_DQS_DN<1>")
	)
	(segment
		(start 309.950612 -292.04793)
		(end 310.375046 -291.623496)
		(width 0.16002)
		(layer "In11.Cu")
		(net "M_F_CPU0_SB_DQS_DN<1>")
	)
	(segment
		(start 274.814538 -295.006776)
		(end 275.640038 -294.181276)
		(width 0.16002)
		(layer "In11.Cu")
		(net "M_F_CPU0_SB_DQS_DN<1>")
	)
	(segment
		(start 323.895974 -281.08275)
		(end 323.919596 -281.08275)
		(width 0.09525)
		(layer "In11.Cu")
		(net "M_F_CPU0_SB_DQS_DN<1>")
	)
	(segment
		(start 314.968636 -286.553402)
		(end 315.44514 -286.553402)
		(width 0.16002)
		(layer "In11.Cu")
		(net "M_F_CPU0_SB_DQS_DN<1>")
	)
	(segment
		(start 332.50632 -281.08402)
		(end 332.607158 -281.11069)
		(width 0.09525)
		(layer "In11.Cu")
		(net "M_F_CPU0_SB_DQS_DN<1>")
	)
	(segment
		(start 320.41211 -281.08275)
		(end 323.895974 -281.08275)
		(width 0.16002)
		(layer "In11.Cu")
		(net "M_F_CPU0_SB_DQS_DN<1>")
	)
	(segment
		(start 312.697876 -289.300666)
		(end 313.12231 -288.876232)
		(width 0.16002)
		(layer "In11.Cu")
		(net "M_F_CPU0_SB_DQS_DN<1>")
	)
	(segment
		(start 314.495942 -287.5026)
		(end 314.495942 -287.026096)
		(width 0.16002)
		(layer "In11.Cu")
		(net "M_F_CPU0_SB_DQS_DN<1>")
	)
	(segment
		(start 319.99047 -281.50439)
		(end 320.41211 -281.08275)
		(width 0.16002)
		(layer "In11.Cu")
		(net "M_F_CPU0_SB_DQS_DN<1>")
	)
	(segment
		(start 315.44514 -286.553402)
		(end 315.869574 -286.128968)
		(width 0.16002)
		(layer "In11.Cu")
		(net "M_F_CPU0_SB_DQS_DN<1>")
	)
	(segment
		(start 315.869574 -286.128968)
		(end 315.869574 -285.652464)
		(width 0.16002)
		(layer "In11.Cu")
		(net "M_F_CPU0_SB_DQS_DN<1>")
	)
	(segment
		(start 281.364182 -294.662098)
		(end 281.70886 -295.006776)
		(width 0.16002)
		(layer "In11.Cu")
		(net "M_F_CPU0_SB_DQS_DN<1>")
	)
	(segment
		(start 311.748678 -290.249864)
		(end 311.748678 -289.77336)
		(width 0.16002)
		(layer "In11.Cu")
		(net "M_F_CPU0_SB_DQS_DN<1>")
	)
	(segment
		(start 310.261 -290.806886)
		(end 310.507634 -290.560252)
		(width 0.16002)
		(layer "In11.Cu")
		(net "M_F_CPU0_SB_DQS_DN<1>")
	)
	(segment
		(start 311.881266 -289.18662)
		(end 312.107326 -289.18662)
		(width 0.16002)
		(layer "In11.Cu")
		(net "M_F_CPU0_SB_DQS_DN<1>")
	)
	(segment
		(start 315.755528 -285.538418)
		(end 315.755528 -285.312358)
		(width 0.16002)
		(layer "In11.Cu")
		(net "M_F_CPU0_SB_DQS_DN<1>")
	)
	(segment
		(start 297.4467 -295.006776)
		(end 298.2722 -294.181276)
		(width 0.16002)
		(layer "In11.Cu")
		(net "M_F_CPU0_SB_DQS_DN<1>")
	)
	(segment
		(start 290.728146 -294.181276)
		(end 291.1729 -294.181276)
		(width 0.16002)
		(layer "In11.Cu")
		(net "M_F_CPU0_SB_DQS_DN<1>")
	)
	(segment
		(start 293.998142 -294.662098)
		(end 296.45229 -294.662098)
		(width 0.16002)
		(layer "In11.Cu")
		(net "M_F_CPU0_SB_DQS_DN<1>")
	)
	(segment
		(start 314.495942 -287.026096)
		(end 314.381896 -286.91205)
		(width 0.16002)
		(layer "In11.Cu")
		(net "M_F_CPU0_SB_DQS_DN<1>")
	)
	(segment
		(start 298.2722 -294.181276)
		(end 298.716954 -294.181276)
		(width 0.16002)
		(layer "In11.Cu")
		(net "M_F_CPU0_SB_DQS_DN<1>")
	)
	(segment
		(start 313.480958 -287.812988)
		(end 313.595004 -287.927034)
		(width 0.16002)
		(layer "In11.Cu")
		(net "M_F_CPU0_SB_DQS_DN<1>")
	)
	(segment
		(start 324.695312 -280.73731)
		(end 326.029828 -280.73731)
		(width 0.09525)
		(layer "In11.Cu")
		(net "M_F_CPU0_SB_DQS_DN<1>")
	)
	(segment
		(start 311.634632 -289.433254)
		(end 311.881266 -289.18662)
		(width 0.16002)
		(layer "In11.Cu")
		(net "M_F_CPU0_SB_DQS_DN<1>")
	)
	(segment
		(start 317.688722 -283.806138)
		(end 318.192404 -283.806138)
		(width 0.16002)
		(layer "In11.Cu")
		(net "M_F_CPU0_SB_DQS_DN<1>")
	)
	(segment
		(start 313.12231 -288.399728)
		(end 313.008264 -288.285682)
		(width 0.16002)
		(layer "In11.Cu")
		(net "M_F_CPU0_SB_DQS_DN<1>")
	)
	(segment
		(start 317.243206 -284.755336)
		(end 317.243206 -284.251654)
		(width 0.16002)
		(layer "In11.Cu")
		(net "M_F_CPU0_SB_DQS_DN<1>")
	)
	(segment
		(start 323.978778 -281.023568)
		(end 324.409054 -281.023568)
		(width 0.09525)
		(layer "In11.Cu")
		(net "M_F_CPU0_SB_DQS_DN<1>")
	)
	(segment
		(start 301.691802 -294.454834)
		(end 302.243744 -295.006776)
		(width 0.16002)
		(layer "In11.Cu")
		(net "M_F_CPU0_SB_DQS_DN<1>")
	)
	(segment
		(start 310.507634 -290.560252)
		(end 310.733694 -290.560252)
		(width 0.16002)
		(layer "In11.Cu")
		(net "M_F_CPU0_SB_DQS_DN<1>")
	)
	(segment
		(start 302.243744 -295.006776)
		(end 304.9905 -295.006776)
		(width 0.16002)
		(layer "In11.Cu")
		(net "M_F_CPU0_SB_DQS_DN<1>")
	)
	(segment
		(start 272.22069 -294.662098)
		(end 273.820128 -294.662098)
		(width 0.16002)
		(layer "In11.Cu")
		(net "M_F_CPU0_SB_DQS_DN<1>")
	)
	(segment
		(start 310.261 -291.032946)
		(end 310.261 -290.806886)
		(width 0.16002)
		(layer "In11.Cu")
		(net "M_F_CPU0_SB_DQS_DN<1>")
	)
	(segment
		(start 282.358592 -295.006776)
		(end 283.184092 -294.181276)
		(width 0.16002)
		(layer "In11.Cu")
		(net "M_F_CPU0_SB_DQS_DN<1>")
	)
	(segment
		(start 272.071592 -294.811196)
		(end 272.22069 -294.662098)
		(width 0.16002)
		(layer "In11.Cu")
		(net "M_F_CPU0_SB_DQS_DN<1>")
	)
	(segment
		(start 283.184092 -294.181276)
		(end 283.628846 -294.181276)
		(width 0.16002)
		(layer "In11.Cu")
		(net "M_F_CPU0_SB_DQS_DN<1>")
	)
	(segment
		(start 314.62853 -286.439356)
		(end 314.85459 -286.439356)
		(width 0.16002)
		(layer "In11.Cu")
		(net "M_F_CPU0_SB_DQS_DN<1>")
	)
	(segment
		(start 283.628846 -294.181276)
		(end 283.997908 -293.812214)
		(width 0.16002)
		(layer "In11.Cu")
		(net "M_F_CPU0_SB_DQS_DN<1>")
	)
	(segment
		(start 315.755528 -285.312358)
		(end 316.002162 -285.065724)
		(width 0.16002)
		(layer "In11.Cu")
		(net "M_F_CPU0_SB_DQS_DN<1>")
	)
	(segment
		(start 317.243206 -284.251654)
		(end 317.688722 -283.806138)
		(width 0.16002)
		(layer "In11.Cu")
		(net "M_F_CPU0_SB_DQS_DN<1>")
	)
	(segment
		(start 296.796968 -295.006776)
		(end 297.4467 -295.006776)
		(width 0.16002)
		(layer "In11.Cu")
		(net "M_F_CPU0_SB_DQS_DN<1>")
	)
	(segment
		(start 311.634632 -289.659314)
		(end 311.634632 -289.433254)
		(width 0.16002)
		(layer "In11.Cu")
		(net "M_F_CPU0_SB_DQS_DN<1>")
	)
	(segment
		(start 326.029828 -280.73731)
		(end 326.255126 -280.962862)
		(width 0.09525)
		(layer "In11.Cu")
		(net "M_F_CPU0_SB_DQS_DN<1>")
	)
	(segment
		(start 311.748678 -289.77336)
		(end 311.634632 -289.659314)
		(width 0.16002)
		(layer "In11.Cu")
		(net "M_F_CPU0_SB_DQS_DN<1>")
	)
	(segment
		(start 310.84774 -290.674298)
		(end 311.324244 -290.674298)
		(width 0.16002)
		(layer "In11.Cu")
		(net "M_F_CPU0_SB_DQS_DN<1>")
	)
	(segment
		(start 326.370442 -281.051)
		(end 326.395842 -281.065732)
		(width 0.09525)
		(layer "In11.Cu")
		(net "M_F_CPU0_SB_DQS_DN<1>")
	)
	(segment
		(start 309.44693 -292.04793)
		(end 309.950612 -292.04793)
		(width 0.16002)
		(layer "In11.Cu")
		(net "M_F_CPU0_SB_DQS_DN<1>")
	)
	(segment
		(start 314.381896 -286.68599)
		(end 314.62853 -286.439356)
		(width 0.16002)
		(layer "In11.Cu")
		(net "M_F_CPU0_SB_DQS_DN<1>")
	)
	(segment
		(start 304.9905 -295.006776)
		(end 305.816 -294.181276)
		(width 0.16002)
		(layer "In11.Cu")
		(net "M_F_CPU0_SB_DQS_DN<1>")
	)
	(segment
		(start 310.375046 -291.623496)
		(end 310.375046 -291.146992)
		(width 0.16002)
		(layer "In11.Cu")
		(net "M_F_CPU0_SB_DQS_DN<1>")
	)
	(segment
		(start 273.820128 -294.662098)
		(end 274.164806 -295.006776)
		(width 0.16002)
		(layer "In11.Cu")
		(net "M_F_CPU0_SB_DQS_DN<1>")
	)
	(segment
		(start 307.313584 -294.181276)
		(end 308.073298 -293.421562)
		(width 0.16002)
		(layer "In11.Cu")
		(net "M_F_CPU0_SB_DQS_DN<1>")
	)
	(segment
		(start 269.92199 -294.811196)
		(end 272.071592 -294.811196)
		(width 0.16002)
		(layer "In11.Cu")
		(net "M_F_CPU0_SB_DQS_DN<1>")
	)
	(segment
		(start 296.45229 -294.662098)
		(end 296.796968 -295.006776)
		(width 0.16002)
		(layer "In11.Cu")
		(net "M_F_CPU0_SB_DQS_DN<1>")
	)
	(segment
		(start 316.818772 -285.17977)
		(end 317.243206 -284.755336)
		(width 0.16002)
		(layer "In11.Cu")
		(net "M_F_CPU0_SB_DQS_DN<1>")
	)
	(segment
		(start 327.854818 -281.061414)
		(end 327.872852 -281.051)
		(width 0.09525)
		(layer "In11.Cu")
		(net "M_F_CPU0_SB_DQS_DN<1>")
	)
	(segment
		(start 314.071508 -287.927034)
		(end 314.495942 -287.5026)
		(width 0.16002)
		(layer "In11.Cu")
		(net "M_F_CPU0_SB_DQS_DN<1>")
	)
	(segment
		(start 278.06015 -293.812214)
		(end 278.910034 -294.662098)
		(width 0.16002)
		(layer "In11.Cu")
		(net "M_F_CPU0_SB_DQS_DN<1>")
	)
	(segment
		(start 313.008264 -288.285682)
		(end 313.008264 -288.059622)
		(width 0.16002)
		(layer "In11.Cu")
		(net "M_F_CPU0_SB_DQS_DN<1>")
	)
	(segment
		(start 288.908236 -294.662098)
		(end 289.252914 -295.006776)
		(width 0.16002)
		(layer "In11.Cu")
		(net "M_F_CPU0_SB_DQS_DN<1>")
	)
	(segment
		(start 293.148258 -293.812214)
		(end 293.998142 -294.662098)
		(width 0.16002)
		(layer "In11.Cu")
		(net "M_F_CPU0_SB_DQS_DN<1>")
	)
	(segment
		(start 298.716954 -294.181276)
		(end 299.086016 -293.812214)
		(width 0.16002)
		(layer "In11.Cu")
		(net "M_F_CPU0_SB_DQS_DN<1>")
	)
	(segment
		(start 305.816 -294.181276)
		(end 307.313584 -294.181276)
		(width 0.16002)
		(layer "In11.Cu")
		(net "M_F_CPU0_SB_DQS_DN<1>")
	)
	(segment
		(start 312.107326 -289.18662)
		(end 312.221372 -289.300666)
		(width 0.16002)
		(layer "In11.Cu")
		(net "M_F_CPU0_SB_DQS_DN<1>")
	)
	(segment
		(start 316.342268 -285.17977)
		(end 316.818772 -285.17977)
		(width 0.16002)
		(layer "In11.Cu")
		(net "M_F_CPU0_SB_DQS_DN<1>")
	)
	(segment
		(start 276.453854 -293.812214)
		(end 278.06015 -293.812214)
		(width 0.16002)
		(layer "In11.Cu")
		(net "M_F_CPU0_SB_DQS_DN<1>")
	)
	(segment
		(start 332.607158 -281.11069)
		(end 332.761082 -281.37612)
		(width 0.09525)
		(layer "In11.Cu")
		(net "M_F_CPU0_SB_DQS_DN<1>")
	)
	(segment
		(start 313.12231 -288.876232)
		(end 313.12231 -288.399728)
		(width 0.16002)
		(layer "In11.Cu")
		(net "M_F_CPU0_SB_DQS_DN<1>")
	)
	(segment
		(start 319.99047 -282.008072)
		(end 319.99047 -281.50439)
		(width 0.16002)
		(layer "In11.Cu")
		(net "M_F_CPU0_SB_DQS_DN<1>")
	)
	(segment
		(start 285.604204 -293.812214)
		(end 286.454088 -294.662098)
		(width 0.16002)
		(layer "In11.Cu")
		(net "M_F_CPU0_SB_DQS_DN<1>")
	)
	(segment
		(start 281.70886 -295.006776)
		(end 282.358592 -295.006776)
		(width 0.16002)
		(layer "In11.Cu")
		(net "M_F_CPU0_SB_DQS_DN<1>")
	)
	(segment
		(start 316.228222 -285.065724)
		(end 316.342268 -285.17977)
		(width 0.16002)
		(layer "In11.Cu")
		(net "M_F_CPU0_SB_DQS_DN<1>")
	)
	(segment
		(start 309.001414 -292.493446)
		(end 309.44693 -292.04793)
		(width 0.16002)
		(layer "In11.Cu")
		(net "M_F_CPU0_SB_DQS_DN<1>")
	)
	(segment
		(start 289.902646 -295.006776)
		(end 290.728146 -294.181276)
		(width 0.16002)
		(layer "In11.Cu")
		(net "M_F_CPU0_SB_DQS_DN<1>")
	)
	(segment
		(start 286.454088 -294.662098)
		(end 288.908236 -294.662098)
		(width 0.16002)
		(layer "In11.Cu")
		(net "M_F_CPU0_SB_DQS_DN<1>")
	)
	(segment
		(start 278.910034 -294.662098)
		(end 281.364182 -294.662098)
		(width 0.16002)
		(layer "In11.Cu")
		(net "M_F_CPU0_SB_DQS_DN<1>")
	)
	(segment
		(start 300.692312 -293.812214)
		(end 301.334932 -294.454834)
		(width 0.16002)
		(layer "In11.Cu")
		(net "M_F_CPU0_SB_DQS_DN<1>")
	)
	(segment
		(start 289.252914 -295.006776)
		(end 289.902646 -295.006776)
		(width 0.16002)
		(layer "In11.Cu")
		(net "M_F_CPU0_SB_DQS_DN<1>")
	)
	(segment
		(start 312.221372 -289.300666)
		(end 312.697876 -289.300666)
		(width 0.16002)
		(layer "In11.Cu")
		(net "M_F_CPU0_SB_DQS_DN<1>")
	)
	(arc
		(start 327.31075 -281.051)
		(mid 327.581438 -281.126652)
		(end 327.854818 -281.061414)
		(width 0.09525)
		(layer "In11.Cu")
		(net "M_F_CPU0_SB_DQS_DN<1>")
	)
	(arc
		(start 328.812652 -281.051)
		(mid 329.00112 -281.000323)
		(end 329.189588 -281.051)
		(width 0.09525)
		(layer "In11.Cu")
		(net "M_F_CPU0_SB_DQS_DN<1>")
	)
	(arc
		(start 329.752452 -281.051)
		(mid 329.936227 -281.000228)
		(end 330.12126 -281.046174)
		(width 0.09525)
		(layer "In11.Cu")
		(net "M_F_CPU0_SB_DQS_DN<1>")
	)
	(arc
		(start 331.069696 -281.051)
		(mid 331.351128 -281.126755)
		(end 331.63256 -281.051)
		(width 0.09525)
		(layer "In11.Cu")
		(net "M_F_CPU0_SB_DQS_DN<1>")
	)
	(arc
		(start 332.00975 -281.051)
		(mid 332.243294 -281.124706)
		(end 332.486 -281.091894)
		(width 0.09525)
		(layer "In11.Cu")
		(net "M_F_CPU0_SB_DQS_DN<1>")
	)
	(arc
		(start 332.486 -281.091894)
		(mid 332.496199 -281.088057)
		(end 332.50632 -281.08402)
		(width 0.09525)
		(layer "In11.Cu")
		(net "M_F_CPU0_SB_DQS_DN<1>")
	)
	(arc
		(start 326.28205 -280.987754)
		(mid 326.324704 -281.021533)
		(end 326.370442 -281.051)
		(width 0.09525)
		(layer "In11.Cu")
		(net "M_F_CPU0_SB_DQS_DN<1>")
	)
	(arc
		(start 329.189588 -281.051)
		(mid 329.47102 -281.126755)
		(end 329.752452 -281.051)
		(width 0.09525)
		(layer "In11.Cu")
		(net "M_F_CPU0_SB_DQS_DN<1>")
	)
	(arc
		(start 327.88479 -281.044142)
		(mid 328.068171 -281.000311)
		(end 328.249788 -281.051)
		(width 0.09525)
		(layer "In11.Cu")
		(net "M_F_CPU0_SB_DQS_DN<1>")
	)
	(arc
		(start 326.395842 -281.065732)
		(mid 326.666458 -281.126957)
		(end 326.933306 -281.051)
		(width 0.09525)
		(layer "In11.Cu")
		(net "M_F_CPU0_SB_DQS_DN<1>")
	)
	(arc
		(start 328.249788 -281.051)
		(mid 328.53122 -281.126755)
		(end 328.812652 -281.051)
		(width 0.09525)
		(layer "In11.Cu")
		(net "M_F_CPU0_SB_DQS_DN<1>")
	)
	(arc
		(start 330.700888 -281.046174)
		(mid 330.88592 -281.00026)
		(end 331.069696 -281.051)
		(width 0.09525)
		(layer "In11.Cu")
		(net "M_F_CPU0_SB_DQS_DN<1>")
	)
	(arc
		(start 330.129642 -281.051)
		(mid 330.411074 -281.126755)
		(end 330.692506 -281.051)
		(width 0.09525)
		(layer "In11.Cu")
		(net "M_F_CPU0_SB_DQS_DN<1>")
	)
	(arc
		(start 331.640942 -281.046174)
		(mid 331.825974 -281.00026)
		(end 332.00975 -281.051)
		(width 0.09525)
		(layer "In11.Cu")
		(net "M_F_CPU0_SB_DQS_DN<1>")
	)
	(arc
		(start 326.933306 -281.051)
		(mid 327.115176 -281.000135)
		(end 327.298812 -281.044142)
		(width 0.09525)
		(layer "In11.Cu")
		(net "M_F_CPU0_SB_DQS_DN<1>")
	)
	(arc
		(start 326.255126 -280.962862)
		(mid 326.268384 -280.975529)
		(end 326.28205 -280.987754)
		(width 0.09525)
		(layer "In11.Cu")
		(net "M_F_CPU0_SB_DQS_DN<1>")
	)
	(segment
		(start 333.227934 -276.250146)
		(end 332.761082 -276.516084)
		(width 0.12954)
		(layer "F.Cu")
		(net "M_F_CPU0_SB_DQS_DN<0>")
	)
	(segment
		(start 310.86679 -281.27833)
		(end 311.113424 -281.031696)
		(width 0.16002)
		(layer "In11.Cu")
		(net "M_F_CPU0_SB_DQS_DN<0>")
	)
	(segment
		(start 307.313838 -284.831282)
		(end 308.36616 -283.77896)
		(width 0.16002)
		(layer "In11.Cu")
		(net "M_F_CPU0_SB_DQS_DN<0>")
	)
	(segment
		(start 310.611266 -282.574238)
		(end 311.0357 -282.149804)
		(width 0.16002)
		(layer "In11.Cu")
		(net "M_F_CPU0_SB_DQS_DN<0>")
	)
	(segment
		(start 314.987686 -277.383494)
		(end 314.987686 -277.157434)
		(width 0.16002)
		(layer "In11.Cu")
		(net "M_F_CPU0_SB_DQS_DN<0>")
	)
	(segment
		(start 311.113424 -281.031696)
		(end 311.339484 -281.031696)
		(width 0.16002)
		(layer "In11.Cu")
		(net "M_F_CPU0_SB_DQS_DN<0>")
	)
	(segment
		(start 298.2722 -284.831282)
		(end 298.716954 -284.831282)
		(width 0.16002)
		(layer "In11.Cu")
		(net "M_F_CPU0_SB_DQS_DN<0>")
	)
	(segment
		(start 276.084792 -284.831282)
		(end 276.453854 -284.46222)
		(width 0.16002)
		(layer "In11.Cu")
		(net "M_F_CPU0_SB_DQS_DN<0>")
	)
	(segment
		(start 316.530228 -276.655276)
		(end 316.530228 -276.178772)
		(width 0.16002)
		(layer "In11.Cu")
		(net "M_F_CPU0_SB_DQS_DN<0>")
	)
	(segment
		(start 278.910034 -285.312104)
		(end 281.364182 -285.312104)
		(width 0.16002)
		(layer "In11.Cu")
		(net "M_F_CPU0_SB_DQS_DN<0>")
	)
	(segment
		(start 283.628846 -284.831282)
		(end 283.997908 -284.46222)
		(width 0.16002)
		(layer "In11.Cu")
		(net "M_F_CPU0_SB_DQS_DN<0>")
	)
	(segment
		(start 314.732162 -278.453342)
		(end 315.156596 -278.028908)
		(width 0.16002)
		(layer "In11.Cu")
		(net "M_F_CPU0_SB_DQS_DN<0>")
	)
	(segment
		(start 313.35853 -279.826974)
		(end 313.782964 -279.40254)
		(width 0.16002)
		(layer "In11.Cu")
		(net "M_F_CPU0_SB_DQS_DN<0>")
	)
	(segment
		(start 302.243744 -285.656782)
		(end 304.9905 -285.656782)
		(width 0.16002)
		(layer "In11.Cu")
		(net "M_F_CPU0_SB_DQS_DN<0>")
	)
	(segment
		(start 316.68593 -275.45919)
		(end 323.903594 -275.45919)
		(width 0.16002)
		(layer "In11.Cu")
		(net "M_F_CPU0_SB_DQS_DN<0>")
	)
	(segment
		(start 308.36616 -283.77896)
		(end 308.59222 -283.77896)
		(width 0.16002)
		(layer "In11.Cu")
		(net "M_F_CPU0_SB_DQS_DN<0>")
	)
	(segment
		(start 315.46038 -276.9108)
		(end 315.62929 -277.07971)
		(width 0.16002)
		(layer "In11.Cu")
		(net "M_F_CPU0_SB_DQS_DN<0>")
	)
	(segment
		(start 314.255658 -278.453342)
		(end 314.732162 -278.453342)
		(width 0.16002)
		(layer "In11.Cu")
		(net "M_F_CPU0_SB_DQS_DN<0>")
	)
	(segment
		(start 293.998142 -285.312104)
		(end 296.45229 -285.312104)
		(width 0.16002)
		(layer "In11.Cu")
		(net "M_F_CPU0_SB_DQS_DN<0>")
	)
	(segment
		(start 296.45229 -285.312104)
		(end 296.796968 -285.656782)
		(width 0.16002)
		(layer "In11.Cu")
		(net "M_F_CPU0_SB_DQS_DN<0>")
	)
	(segment
		(start 281.70886 -285.656782)
		(end 282.358592 -285.656782)
		(width 0.16002)
		(layer "In11.Cu")
		(net "M_F_CPU0_SB_DQS_DN<0>")
	)
	(segment
		(start 309.739792 -282.405328)
		(end 309.965852 -282.405328)
		(width 0.16002)
		(layer "In11.Cu")
		(net "M_F_CPU0_SB_DQS_DN<0>")
	)
	(segment
		(start 315.156596 -278.028908)
		(end 315.156596 -277.552404)
		(width 0.16002)
		(layer "In11.Cu")
		(net "M_F_CPU0_SB_DQS_DN<0>")
	)
	(segment
		(start 296.796968 -285.656782)
		(end 297.4467 -285.656782)
		(width 0.16002)
		(layer "In11.Cu")
		(net "M_F_CPU0_SB_DQS_DN<0>")
	)
	(segment
		(start 313.860688 -278.284432)
		(end 314.086748 -278.284432)
		(width 0.16002)
		(layer "In11.Cu")
		(net "M_F_CPU0_SB_DQS_DN<0>")
	)
	(segment
		(start 275.640038 -284.831282)
		(end 276.084792 -284.831282)
		(width 0.16002)
		(layer "In11.Cu")
		(net "M_F_CPU0_SB_DQS_DN<0>")
	)
	(segment
		(start 308.59222 -283.77896)
		(end 308.76113 -283.94787)
		(width 0.16002)
		(layer "In11.Cu")
		(net "M_F_CPU0_SB_DQS_DN<0>")
	)
	(segment
		(start 332.50632 -276.223984)
		(end 332.607158 -276.250654)
		(width 0.09525)
		(layer "In11.Cu")
		(net "M_F_CPU0_SB_DQS_DN<0>")
	)
	(segment
		(start 330.692506 -276.190964)
		(end 330.700888 -276.186138)
		(width 0.09525)
		(layer "In11.Cu")
		(net "M_F_CPU0_SB_DQS_DN<0>")
	)
	(segment
		(start 314.987686 -277.157434)
		(end 315.23432 -276.9108)
		(width 0.16002)
		(layer "In11.Cu")
		(net "M_F_CPU0_SB_DQS_DN<0>")
	)
	(segment
		(start 314.086748 -278.284432)
		(end 314.255658 -278.453342)
		(width 0.16002)
		(layer "In11.Cu")
		(net "M_F_CPU0_SB_DQS_DN<0>")
	)
	(segment
		(start 332.607158 -276.250654)
		(end 332.761082 -276.516084)
		(width 0.09525)
		(layer "In11.Cu")
		(net "M_F_CPU0_SB_DQS_DN<0>")
	)
	(segment
		(start 312.409332 -280.776172)
		(end 312.409332 -280.299668)
		(width 0.16002)
		(layer "In11.Cu")
		(net "M_F_CPU0_SB_DQS_DN<0>")
	)
	(segment
		(start 300.692312 -284.46222)
		(end 301.334932 -285.10484)
		(width 0.16002)
		(layer "In11.Cu")
		(net "M_F_CPU0_SB_DQS_DN<0>")
	)
	(segment
		(start 273.820128 -285.312104)
		(end 274.164806 -285.656782)
		(width 0.16002)
		(layer "In11.Cu")
		(net "M_F_CPU0_SB_DQS_DN<0>")
	)
	(segment
		(start 311.0357 -281.6733)
		(end 310.86679 -281.50439)
		(width 0.16002)
		(layer "In11.Cu")
		(net "M_F_CPU0_SB_DQS_DN<0>")
	)
	(segment
		(start 291.541962 -284.46222)
		(end 293.148258 -284.46222)
		(width 0.16002)
		(layer "In11.Cu")
		(net "M_F_CPU0_SB_DQS_DN<0>")
	)
	(segment
		(start 310.134762 -282.574238)
		(end 310.611266 -282.574238)
		(width 0.16002)
		(layer "In11.Cu")
		(net "M_F_CPU0_SB_DQS_DN<0>")
	)
	(segment
		(start 312.882026 -279.826974)
		(end 313.35853 -279.826974)
		(width 0.16002)
		(layer "In11.Cu")
		(net "M_F_CPU0_SB_DQS_DN<0>")
	)
	(segment
		(start 304.9905 -285.656782)
		(end 305.816 -284.831282)
		(width 0.16002)
		(layer "In11.Cu")
		(net "M_F_CPU0_SB_DQS_DN<0>")
	)
	(segment
		(start 311.0357 -282.149804)
		(end 311.0357 -281.6733)
		(width 0.16002)
		(layer "In11.Cu")
		(net "M_F_CPU0_SB_DQS_DN<0>")
	)
	(segment
		(start 278.06015 -284.46222)
		(end 278.910034 -285.312104)
		(width 0.16002)
		(layer "In11.Cu")
		(net "M_F_CPU0_SB_DQS_DN<0>")
	)
	(segment
		(start 309.965852 -282.405328)
		(end 310.134762 -282.574238)
		(width 0.16002)
		(layer "In11.Cu")
		(net "M_F_CPU0_SB_DQS_DN<0>")
	)
	(segment
		(start 323.927216 -275.45919)
		(end 323.986398 -275.400008)
		(width 0.09525)
		(layer "In11.Cu")
		(net "M_F_CPU0_SB_DQS_DN<0>")
	)
	(segment
		(start 309.662068 -283.046932)
		(end 309.493158 -282.878022)
		(width 0.16002)
		(layer "In11.Cu")
		(net "M_F_CPU0_SB_DQS_DN<0>")
	)
	(segment
		(start 313.614054 -278.531066)
		(end 313.860688 -278.284432)
		(width 0.16002)
		(layer "In11.Cu")
		(net "M_F_CPU0_SB_DQS_DN<0>")
	)
	(segment
		(start 272.22069 -285.312104)
		(end 273.820128 -285.312104)
		(width 0.16002)
		(layer "In11.Cu")
		(net "M_F_CPU0_SB_DQS_DN<0>")
	)
	(segment
		(start 311.508394 -281.200606)
		(end 311.984898 -281.200606)
		(width 0.16002)
		(layer "In11.Cu")
		(net "M_F_CPU0_SB_DQS_DN<0>")
	)
	(segment
		(start 286.454088 -285.312104)
		(end 288.908236 -285.312104)
		(width 0.16002)
		(layer "In11.Cu")
		(net "M_F_CPU0_SB_DQS_DN<0>")
	)
	(segment
		(start 298.716954 -284.831282)
		(end 299.086016 -284.46222)
		(width 0.16002)
		(layer "In11.Cu")
		(net "M_F_CPU0_SB_DQS_DN<0>")
	)
	(segment
		(start 325.075804 -275.400008)
		(end 325.942198 -276.266402)
		(width 0.09525)
		(layer "In11.Cu")
		(net "M_F_CPU0_SB_DQS_DN<0>")
	)
	(segment
		(start 312.409332 -280.299668)
		(end 312.240422 -280.130758)
		(width 0.16002)
		(layer "In11.Cu")
		(net "M_F_CPU0_SB_DQS_DN<0>")
	)
	(segment
		(start 289.902646 -285.656782)
		(end 290.728146 -284.831282)
		(width 0.16002)
		(layer "In11.Cu")
		(net "M_F_CPU0_SB_DQS_DN<0>")
	)
	(segment
		(start 309.237634 -283.94787)
		(end 309.662068 -283.523436)
		(width 0.16002)
		(layer "In11.Cu")
		(net "M_F_CPU0_SB_DQS_DN<0>")
	)
	(segment
		(start 316.361318 -276.009862)
		(end 316.361318 -275.783802)
		(width 0.16002)
		(layer "In11.Cu")
		(net "M_F_CPU0_SB_DQS_DN<0>")
	)
	(segment
		(start 323.986398 -275.400008)
		(end 325.075804 -275.400008)
		(width 0.09525)
		(layer "In11.Cu")
		(net "M_F_CPU0_SB_DQS_DN<0>")
	)
	(segment
		(start 312.240422 -280.130758)
		(end 312.240422 -279.904698)
		(width 0.16002)
		(layer "In11.Cu")
		(net "M_F_CPU0_SB_DQS_DN<0>")
	)
	(segment
		(start 297.4467 -285.656782)
		(end 298.2722 -284.831282)
		(width 0.16002)
		(layer "In11.Cu")
		(net "M_F_CPU0_SB_DQS_DN<0>")
	)
	(segment
		(start 282.358592 -285.656782)
		(end 283.184092 -284.831282)
		(width 0.16002)
		(layer "In11.Cu")
		(net "M_F_CPU0_SB_DQS_DN<0>")
	)
	(segment
		(start 315.156596 -277.552404)
		(end 314.987686 -277.383494)
		(width 0.16002)
		(layer "In11.Cu")
		(net "M_F_CPU0_SB_DQS_DN<0>")
	)
	(segment
		(start 315.23432 -276.9108)
		(end 315.46038 -276.9108)
		(width 0.16002)
		(layer "In11.Cu")
		(net "M_F_CPU0_SB_DQS_DN<0>")
	)
	(segment
		(start 330.12126 -276.186138)
		(end 330.129642 -276.190964)
		(width 0.09525)
		(layer "In11.Cu")
		(net "M_F_CPU0_SB_DQS_DN<0>")
	)
	(segment
		(start 283.184092 -284.831282)
		(end 283.628846 -284.831282)
		(width 0.16002)
		(layer "In11.Cu")
		(net "M_F_CPU0_SB_DQS_DN<0>")
	)
	(segment
		(start 312.487056 -279.658064)
		(end 312.713116 -279.658064)
		(width 0.16002)
		(layer "In11.Cu")
		(net "M_F_CPU0_SB_DQS_DN<0>")
	)
	(segment
		(start 285.604204 -284.46222)
		(end 286.454088 -285.312104)
		(width 0.16002)
		(layer "In11.Cu")
		(net "M_F_CPU0_SB_DQS_DN<0>")
	)
	(segment
		(start 276.453854 -284.46222)
		(end 278.06015 -284.46222)
		(width 0.16002)
		(layer "In11.Cu")
		(net "M_F_CPU0_SB_DQS_DN<0>")
	)
	(segment
		(start 331.63256 -276.190964)
		(end 331.640942 -276.186138)
		(width 0.09525)
		(layer "In11.Cu")
		(net "M_F_CPU0_SB_DQS_DN<0>")
	)
	(segment
		(start 327.872852 -276.190964)
		(end 327.88479 -276.184106)
		(width 0.09525)
		(layer "In11.Cu")
		(net "M_F_CPU0_SB_DQS_DN<0>")
	)
	(segment
		(start 312.240422 -279.904698)
		(end 312.487056 -279.658064)
		(width 0.16002)
		(layer "In11.Cu")
		(net "M_F_CPU0_SB_DQS_DN<0>")
	)
	(segment
		(start 293.148258 -284.46222)
		(end 293.998142 -285.312104)
		(width 0.16002)
		(layer "In11.Cu")
		(net "M_F_CPU0_SB_DQS_DN<0>")
	)
	(segment
		(start 309.493158 -282.878022)
		(end 309.493158 -282.651962)
		(width 0.16002)
		(layer "In11.Cu")
		(net "M_F_CPU0_SB_DQS_DN<0>")
	)
	(segment
		(start 308.76113 -283.94787)
		(end 309.237634 -283.94787)
		(width 0.16002)
		(layer "In11.Cu")
		(net "M_F_CPU0_SB_DQS_DN<0>")
	)
	(segment
		(start 315.62929 -277.07971)
		(end 316.105794 -277.07971)
		(width 0.16002)
		(layer "In11.Cu")
		(net "M_F_CPU0_SB_DQS_DN<0>")
	)
	(segment
		(start 283.997908 -284.46222)
		(end 285.604204 -284.46222)
		(width 0.16002)
		(layer "In11.Cu")
		(net "M_F_CPU0_SB_DQS_DN<0>")
	)
	(segment
		(start 310.86679 -281.50439)
		(end 310.86679 -281.27833)
		(width 0.16002)
		(layer "In11.Cu")
		(net "M_F_CPU0_SB_DQS_DN<0>")
	)
	(segment
		(start 311.339484 -281.031696)
		(end 311.508394 -281.200606)
		(width 0.16002)
		(layer "In11.Cu")
		(net "M_F_CPU0_SB_DQS_DN<0>")
	)
	(segment
		(start 289.252914 -285.656782)
		(end 289.902646 -285.656782)
		(width 0.16002)
		(layer "In11.Cu")
		(net "M_F_CPU0_SB_DQS_DN<0>")
	)
	(segment
		(start 269.92199 -285.461202)
		(end 272.071592 -285.461202)
		(width 0.16002)
		(layer "In11.Cu")
		(net "M_F_CPU0_SB_DQS_DN<0>")
	)
	(segment
		(start 305.816 -284.831282)
		(end 307.313838 -284.831282)
		(width 0.16002)
		(layer "In11.Cu")
		(net "M_F_CPU0_SB_DQS_DN<0>")
	)
	(segment
		(start 269.648178 -285.735014)
		(end 269.92199 -285.461202)
		(width 0.16002)
		(layer "In11.Cu")
		(net "M_F_CPU0_SB_DQS_DN<0>")
	)
	(segment
		(start 281.364182 -285.312104)
		(end 281.70886 -285.656782)
		(width 0.16002)
		(layer "In11.Cu")
		(net "M_F_CPU0_SB_DQS_DN<0>")
	)
	(segment
		(start 274.814538 -285.656782)
		(end 275.640038 -284.831282)
		(width 0.16002)
		(layer "In11.Cu")
		(net "M_F_CPU0_SB_DQS_DN<0>")
	)
	(segment
		(start 316.361318 -275.783802)
		(end 316.68593 -275.45919)
		(width 0.16002)
		(layer "In11.Cu")
		(net "M_F_CPU0_SB_DQS_DN<0>")
	)
	(segment
		(start 301.691802 -285.10484)
		(end 302.243744 -285.656782)
		(width 0.16002)
		(layer "In11.Cu")
		(net "M_F_CPU0_SB_DQS_DN<0>")
	)
	(segment
		(start 290.728146 -284.831282)
		(end 291.1729 -284.831282)
		(width 0.16002)
		(layer "In11.Cu")
		(net "M_F_CPU0_SB_DQS_DN<0>")
	)
	(segment
		(start 301.334932 -285.10484)
		(end 301.691802 -285.10484)
		(width 0.16002)
		(layer "In11.Cu")
		(net "M_F_CPU0_SB_DQS_DN<0>")
	)
	(segment
		(start 299.086016 -284.46222)
		(end 300.692312 -284.46222)
		(width 0.16002)
		(layer "In11.Cu")
		(net "M_F_CPU0_SB_DQS_DN<0>")
	)
	(segment
		(start 288.908236 -285.312104)
		(end 289.252914 -285.656782)
		(width 0.16002)
		(layer "In11.Cu")
		(net "M_F_CPU0_SB_DQS_DN<0>")
	)
	(segment
		(start 313.782964 -279.40254)
		(end 313.782964 -278.926036)
		(width 0.16002)
		(layer "In11.Cu")
		(net "M_F_CPU0_SB_DQS_DN<0>")
	)
	(segment
		(start 291.1729 -284.831282)
		(end 291.541962 -284.46222)
		(width 0.16002)
		(layer "In11.Cu")
		(net "M_F_CPU0_SB_DQS_DN<0>")
	)
	(segment
		(start 272.071592 -285.461202)
		(end 272.22069 -285.312104)
		(width 0.16002)
		(layer "In11.Cu")
		(net "M_F_CPU0_SB_DQS_DN<0>")
	)
	(segment
		(start 309.662068 -283.523436)
		(end 309.662068 -283.046932)
		(width 0.16002)
		(layer "In11.Cu")
		(net "M_F_CPU0_SB_DQS_DN<0>")
	)
	(segment
		(start 313.782964 -278.926036)
		(end 313.614054 -278.757126)
		(width 0.16002)
		(layer "In11.Cu")
		(net "M_F_CPU0_SB_DQS_DN<0>")
	)
	(segment
		(start 323.903594 -275.45919)
		(end 323.927216 -275.45919)
		(width 0.09525)
		(layer "In11.Cu")
		(net "M_F_CPU0_SB_DQS_DN<0>")
	)
	(segment
		(start 274.164806 -285.656782)
		(end 274.814538 -285.656782)
		(width 0.16002)
		(layer "In11.Cu")
		(net "M_F_CPU0_SB_DQS_DN<0>")
	)
	(segment
		(start 312.713116 -279.658064)
		(end 312.882026 -279.826974)
		(width 0.16002)
		(layer "In11.Cu")
		(net "M_F_CPU0_SB_DQS_DN<0>")
	)
	(segment
		(start 313.614054 -278.757126)
		(end 313.614054 -278.531066)
		(width 0.16002)
		(layer "In11.Cu")
		(net "M_F_CPU0_SB_DQS_DN<0>")
	)
	(segment
		(start 325.942198 -276.266402)
		(end 327.591928 -276.266402)
		(width 0.09525)
		(layer "In11.Cu")
		(net "M_F_CPU0_SB_DQS_DN<0>")
	)
	(segment
		(start 316.530228 -276.178772)
		(end 316.361318 -276.009862)
		(width 0.16002)
		(layer "In11.Cu")
		(net "M_F_CPU0_SB_DQS_DN<0>")
	)
	(segment
		(start 316.105794 -277.07971)
		(end 316.530228 -276.655276)
		(width 0.16002)
		(layer "In11.Cu")
		(net "M_F_CPU0_SB_DQS_DN<0>")
	)
	(segment
		(start 309.493158 -282.651962)
		(end 309.739792 -282.405328)
		(width 0.16002)
		(layer "In11.Cu")
		(net "M_F_CPU0_SB_DQS_DN<0>")
	)
	(segment
		(start 311.984898 -281.200606)
		(end 312.409332 -280.776172)
		(width 0.16002)
		(layer "In11.Cu")
		(net "M_F_CPU0_SB_DQS_DN<0>")
	)
	(arc
		(start 330.700888 -276.186138)
		(mid 330.88592 -276.140224)
		(end 331.069696 -276.190964)
		(width 0.09525)
		(layer "In11.Cu")
		(net "M_F_CPU0_SB_DQS_DN<0>")
	)
	(arc
		(start 328.812652 -276.190964)
		(mid 329.00112 -276.140287)
		(end 329.189588 -276.190964)
		(width 0.09525)
		(layer "In11.Cu")
		(net "M_F_CPU0_SB_DQS_DN<0>")
	)
	(arc
		(start 331.069696 -276.190964)
		(mid 331.351128 -276.266719)
		(end 331.63256 -276.190964)
		(width 0.09525)
		(layer "In11.Cu")
		(net "M_F_CPU0_SB_DQS_DN<0>")
	)
	(arc
		(start 331.640942 -276.186138)
		(mid 331.825974 -276.140224)
		(end 332.00975 -276.190964)
		(width 0.09525)
		(layer "In11.Cu")
		(net "M_F_CPU0_SB_DQS_DN<0>")
	)
	(arc
		(start 332.00975 -276.190964)
		(mid 332.243294 -276.26467)
		(end 332.486 -276.231858)
		(width 0.09525)
		(layer "In11.Cu")
		(net "M_F_CPU0_SB_DQS_DN<0>")
	)
	(arc
		(start 330.129642 -276.190964)
		(mid 330.411074 -276.266719)
		(end 330.692506 -276.190964)
		(width 0.09525)
		(layer "In11.Cu")
		(net "M_F_CPU0_SB_DQS_DN<0>")
	)
	(arc
		(start 332.486 -276.231858)
		(mid 332.496199 -276.228021)
		(end 332.50632 -276.223984)
		(width 0.09525)
		(layer "In11.Cu")
		(net "M_F_CPU0_SB_DQS_DN<0>")
	)
	(arc
		(start 329.189588 -276.190964)
		(mid 329.47102 -276.266719)
		(end 329.752452 -276.190964)
		(width 0.09525)
		(layer "In11.Cu")
		(net "M_F_CPU0_SB_DQS_DN<0>")
	)
	(arc
		(start 327.88479 -276.184106)
		(mid 328.068171 -276.140275)
		(end 328.249788 -276.190964)
		(width 0.09525)
		(layer "In11.Cu")
		(net "M_F_CPU0_SB_DQS_DN<0>")
	)
	(arc
		(start 328.249788 -276.190964)
		(mid 328.53122 -276.266719)
		(end 328.812652 -276.190964)
		(width 0.09525)
		(layer "In11.Cu")
		(net "M_F_CPU0_SB_DQS_DN<0>")
	)
	(arc
		(start 327.591928 -276.266402)
		(mid 327.737358 -276.2472)
		(end 327.872852 -276.190964)
		(width 0.09525)
		(layer "In11.Cu")
		(net "M_F_CPU0_SB_DQS_DN<0>")
	)
	(arc
		(start 329.752452 -276.190964)
		(mid 329.936227 -276.140192)
		(end 330.12126 -276.186138)
		(width 0.09525)
		(layer "In11.Cu")
		(net "M_F_CPU0_SB_DQS_DN<0>")
	)
	(segment
		(start 334.167988 -279.49017)
		(end 333.701136 -279.756108)
		(width 0.10668)
		(layer "F.Cu")
		(net "M_F_CPU0_SB_DQ<9>")
	)
	(segment
		(start 271.802352 -293.346124)
		(end 271.965166 -293.18331)
		(width 0.14478)
		(layer "In11.Cu")
		(net "M_F_CPU0_SB_DQ<9>")
	)
	(segment
		(start 281.57551 -293.26459)
		(end 281.880056 -292.960044)
		(width 0.14478)
		(layer "In11.Cu")
		(net "M_F_CPU0_SB_DQ<9>")
	)
	(segment
		(start 296.336974 -293.25697)
		(end 296.596308 -293.25697)
		(width 0.14478)
		(layer "In11.Cu")
		(net "M_F_CPU0_SB_DQ<9>")
	)
	(segment
		(start 279.125934 -292.960044)
		(end 279.311608 -292.960044)
		(width 0.14478)
		(layer "In11.Cu")
		(net "M_F_CPU0_SB_DQ<9>")
	)
	(segment
		(start 296.040048 -292.960044)
		(end 296.336974 -293.25697)
		(width 0.14478)
		(layer "In11.Cu")
		(net "M_F_CPU0_SB_DQ<9>")
	)
	(segment
		(start 317.379096 -282.163774)
		(end 317.604648 -281.938222)
		(width 0.14478)
		(layer "In11.Cu")
		(net "M_F_CPU0_SB_DQ<9>")
	)
	(segment
		(start 307.890418 -291.750496)
		(end 307.890418 -291.323268)
		(width 0.14478)
		(layer "In11.Cu")
		(net "M_F_CPU0_SB_DQ<9>")
	)
	(segment
		(start 291.098986 -292.109906)
		(end 291.41801 -292.42893)
		(width 0.14478)
		(layer "In11.Cu")
		(net "M_F_CPU0_SB_DQ<9>")
	)
	(segment
		(start 287.325308 -293.27983)
		(end 287.561782 -293.27983)
		(width 0.14478)
		(layer "In11.Cu")
		(net "M_F_CPU0_SB_DQ<9>")
	)
	(segment
		(start 316.269624 -282.944062)
		(end 316.598808 -282.944062)
		(width 0.14478)
		(layer "In11.Cu")
		(net "M_F_CPU0_SB_DQ<9>")
	)
	(segment
		(start 287.881568 -292.960044)
		(end 288.608008 -292.960044)
		(width 0.14478)
		(layer "In11.Cu")
		(net "M_F_CPU0_SB_DQ<9>")
	)
	(segment
		(start 307.531008 -292.109906)
		(end 307.890418 -291.750496)
		(width 0.14478)
		(layer "In11.Cu")
		(net "M_F_CPU0_SB_DQ<9>")
	)
	(segment
		(start 289.456114 -292.960044)
		(end 289.809174 -292.960044)
		(width 0.14478)
		(layer "In11.Cu")
		(net "M_F_CPU0_SB_DQ<9>")
	)
	(segment
		(start 272.12798 -292.569392)
		(end 272.358612 -292.569392)
		(width 0.14478)
		(layer "In11.Cu")
		(net "M_F_CPU0_SB_DQ<9>")
	)
	(segment
		(start 291.655246 -292.42893)
		(end 291.97427 -292.109906)
		(width 0.14478)
		(layer "In11.Cu")
		(net "M_F_CPU0_SB_DQ<9>")
	)
	(segment
		(start 297.168062 -292.960044)
		(end 298.0182 -292.109906)
		(width 0.14478)
		(layer "In11.Cu")
		(net "M_F_CPU0_SB_DQ<9>")
	)
	(segment
		(start 291.97427 -292.109906)
		(end 293.364412 -292.109906)
		(width 0.14478)
		(layer "In11.Cu")
		(net "M_F_CPU0_SB_DQ<9>")
	)
	(segment
		(start 285.946596 -292.109906)
		(end 286.796734 -292.960044)
		(width 0.14478)
		(layer "In11.Cu")
		(net "M_F_CPU0_SB_DQ<9>")
	)
	(segment
		(start 288.608008 -292.960044)
		(end 288.899854 -293.25189)
		(width 0.14478)
		(layer "In11.Cu")
		(net "M_F_CPU0_SB_DQ<9>")
	)
	(segment
		(start 293.364412 -292.109906)
		(end 294.21455 -292.960044)
		(width 0.14478)
		(layer "In11.Cu")
		(net "M_F_CPU0_SB_DQ<9>")
	)
	(segment
		(start 295.09466 -293.27221)
		(end 295.406826 -292.960044)
		(width 0.14478)
		(layer "In11.Cu")
		(net "M_F_CPU0_SB_DQ<9>")
	)
	(segment
		(start 317.604648 -281.938222)
		(end 317.604648 -281.609038)
		(width 0.14478)
		(layer "In11.Cu")
		(net "M_F_CPU0_SB_DQ<9>")
	)
	(segment
		(start 280.187654 -292.960044)
		(end 281.01925 -292.960044)
		(width 0.14478)
		(layer "In11.Cu")
		(net "M_F_CPU0_SB_DQ<9>")
	)
	(segment
		(start 305.5366 -292.109906)
		(end 307.531008 -292.109906)
		(width 0.14478)
		(layer "In11.Cu")
		(net "M_F_CPU0_SB_DQ<9>")
	)
	(segment
		(start 271.965166 -292.732206)
		(end 272.12798 -292.569392)
		(width 0.14478)
		(layer "In11.Cu")
		(net "M_F_CPU0_SB_DQ<9>")
	)
	(segment
		(start 281.01925 -292.960044)
		(end 281.323796 -293.26459)
		(width 0.14478)
		(layer "In11.Cu")
		(net "M_F_CPU0_SB_DQ<9>")
	)
	(segment
		(start 333.832708 -280.10485)
		(end 333.85506 -280.021538)
		(width 0.0889)
		(layer "In11.Cu")
		(net "M_F_CPU0_SB_DQ<9>")
	)
	(segment
		(start 279.631394 -293.27983)
		(end 279.867868 -293.27983)
		(width 0.14478)
		(layer "In11.Cu")
		(net "M_F_CPU0_SB_DQ<9>")
	)
	(segment
		(start 271.965166 -293.18331)
		(end 271.965166 -292.732206)
		(width 0.14478)
		(layer "In11.Cu")
		(net "M_F_CPU0_SB_DQ<9>")
	)
	(segment
		(start 279.867868 -293.27983)
		(end 280.187654 -292.960044)
		(width 0.14478)
		(layer "In11.Cu")
		(net "M_F_CPU0_SB_DQ<9>")
	)
	(segment
		(start 318.610488 -280.603198)
		(end 318.939672 -280.603198)
		(width 0.14478)
		(layer "In11.Cu")
		(net "M_F_CPU0_SB_DQ<9>")
	)
	(segment
		(start 298.0182 -292.109906)
		(end 301.308516 -292.109906)
		(width 0.14478)
		(layer "In11.Cu")
		(net "M_F_CPU0_SB_DQ<9>")
	)
	(segment
		(start 296.596308 -293.25697)
		(end 296.893234 -292.960044)
		(width 0.14478)
		(layer "In11.Cu")
		(net "M_F_CPU0_SB_DQ<9>")
	)
	(segment
		(start 319.460626 -279.75306)
		(end 323.908674 -279.75306)
		(width 0.14478)
		(layer "In11.Cu")
		(net "M_F_CPU0_SB_DQ<9>")
	)
	(segment
		(start 294.5384 -292.960044)
		(end 294.850566 -293.27221)
		(width 0.14478)
		(layer "In11.Cu")
		(net "M_F_CPU0_SB_DQ<9>")
	)
	(segment
		(start 330.69403 -280.078688)
		(end 330.702412 -280.083514)
		(width 0.0889)
		(layer "In11.Cu")
		(net "M_F_CPU0_SB_DQ<9>")
	)
	(segment
		(start 282.417774 -292.960044)
		(end 283.267912 -292.109906)
		(width 0.14478)
		(layer "In11.Cu")
		(net "M_F_CPU0_SB_DQ<9>")
	)
	(segment
		(start 323.908674 -279.75306)
		(end 324.294754 -279.75306)
		(width 0.0889)
		(layer "In11.Cu")
		(net "M_F_CPU0_SB_DQ<9>")
	)
	(segment
		(start 283.574236 -292.109906)
		(end 283.8958 -292.43147)
		(width 0.14478)
		(layer "In11.Cu")
		(net "M_F_CPU0_SB_DQ<9>")
	)
	(segment
		(start 316.82436 -282.71851)
		(end 316.82436 -282.389326)
		(width 0.14478)
		(layer "In11.Cu")
		(net "M_F_CPU0_SB_DQ<9>")
	)
	(segment
		(start 281.323796 -293.26459)
		(end 281.57551 -293.26459)
		(width 0.14478)
		(layer "In11.Cu")
		(net "M_F_CPU0_SB_DQ<9>")
	)
	(segment
		(start 296.893234 -292.960044)
		(end 297.168062 -292.960044)
		(width 0.14478)
		(layer "In11.Cu")
		(net "M_F_CPU0_SB_DQ<9>")
	)
	(segment
		(start 317.049912 -282.163774)
		(end 317.379096 -282.163774)
		(width 0.14478)
		(layer "In11.Cu")
		(net "M_F_CPU0_SB_DQ<9>")
	)
	(segment
		(start 271.01546 -292.569392)
		(end 271.246092 -292.569392)
		(width 0.14478)
		(layer "In11.Cu")
		(net "M_F_CPU0_SB_DQ<9>")
	)
	(segment
		(start 294.21455 -292.960044)
		(end 294.5384 -292.960044)
		(width 0.14478)
		(layer "In11.Cu")
		(net "M_F_CPU0_SB_DQ<9>")
	)
	(segment
		(start 269.648178 -292.535102)
		(end 270.4592 -293.346124)
		(width 0.14478)
		(layer "In11.Cu")
		(net "M_F_CPU0_SB_DQ<9>")
	)
	(segment
		(start 270.689832 -293.346124)
		(end 270.852646 -293.18331)
		(width 0.14478)
		(layer "In11.Cu")
		(net "M_F_CPU0_SB_DQ<9>")
	)
	(segment
		(start 271.408906 -292.732206)
		(end 271.408906 -293.18331)
		(width 0.14478)
		(layer "In11.Cu")
		(net "M_F_CPU0_SB_DQ<9>")
	)
	(segment
		(start 295.406826 -292.960044)
		(end 296.040048 -292.960044)
		(width 0.14478)
		(layer "In11.Cu")
		(net "M_F_CPU0_SB_DQ<9>")
	)
	(segment
		(start 284.45206 -292.109906)
		(end 285.946596 -292.109906)
		(width 0.14478)
		(layer "In11.Cu")
		(net "M_F_CPU0_SB_DQ<9>")
	)
	(segment
		(start 274.823174 -292.960044)
		(end 275.673312 -292.109906)
		(width 0.14478)
		(layer "In11.Cu")
		(net "M_F_CPU0_SB_DQ<9>")
	)
	(segment
		(start 294.850566 -293.27221)
		(end 295.09466 -293.27221)
		(width 0.14478)
		(layer "In11.Cu")
		(net "M_F_CPU0_SB_DQ<9>")
	)
	(segment
		(start 270.852646 -293.18331)
		(end 270.852646 -292.732206)
		(width 0.14478)
		(layer "In11.Cu")
		(net "M_F_CPU0_SB_DQ<9>")
	)
	(segment
		(start 289.164268 -293.25189)
		(end 289.456114 -292.960044)
		(width 0.14478)
		(layer "In11.Cu")
		(net "M_F_CPU0_SB_DQ<9>")
	)
	(segment
		(start 270.4592 -293.346124)
		(end 270.689832 -293.346124)
		(width 0.14478)
		(layer "In11.Cu")
		(net "M_F_CPU0_SB_DQ<9>")
	)
	(segment
		(start 271.246092 -292.569392)
		(end 271.408906 -292.732206)
		(width 0.14478)
		(layer "In11.Cu")
		(net "M_F_CPU0_SB_DQ<9>")
	)
	(segment
		(start 316.598808 -282.944062)
		(end 316.82436 -282.71851)
		(width 0.14478)
		(layer "In11.Cu")
		(net "M_F_CPU0_SB_DQ<9>")
	)
	(segment
		(start 333.85506 -280.021538)
		(end 333.701136 -279.756108)
		(width 0.0889)
		(layer "In11.Cu")
		(net "M_F_CPU0_SB_DQ<9>")
	)
	(segment
		(start 317.604648 -281.609038)
		(end 317.8302 -281.383486)
		(width 0.14478)
		(layer "In11.Cu")
		(net "M_F_CPU0_SB_DQ<9>")
	)
	(segment
		(start 318.159384 -281.383486)
		(end 318.384936 -281.157934)
		(width 0.14478)
		(layer "In11.Cu")
		(net "M_F_CPU0_SB_DQ<9>")
	)
	(segment
		(start 304.686462 -292.960044)
		(end 305.5366 -292.109906)
		(width 0.14478)
		(layer "In11.Cu")
		(net "M_F_CPU0_SB_DQ<9>")
	)
	(segment
		(start 319.165224 -280.377646)
		(end 319.165224 -280.048462)
		(width 0.14478)
		(layer "In11.Cu")
		(net "M_F_CPU0_SB_DQ<9>")
	)
	(segment
		(start 270.852646 -292.732206)
		(end 271.01546 -292.569392)
		(width 0.14478)
		(layer "In11.Cu")
		(net "M_F_CPU0_SB_DQ<9>")
	)
	(segment
		(start 288.899854 -293.25189)
		(end 289.164268 -293.25189)
		(width 0.14478)
		(layer "In11.Cu")
		(net "M_F_CPU0_SB_DQ<9>")
	)
	(segment
		(start 272.358612 -292.569392)
		(end 272.749264 -292.960044)
		(width 0.14478)
		(layer "In11.Cu")
		(net "M_F_CPU0_SB_DQ<9>")
	)
	(segment
		(start 318.384936 -281.157934)
		(end 318.384936 -280.82875)
		(width 0.14478)
		(layer "In11.Cu")
		(net "M_F_CPU0_SB_DQ<9>")
	)
	(segment
		(start 271.57172 -293.346124)
		(end 271.802352 -293.346124)
		(width 0.14478)
		(layer "In11.Cu")
		(net "M_F_CPU0_SB_DQ<9>")
	)
	(segment
		(start 301.308516 -292.109906)
		(end 302.158654 -292.960044)
		(width 0.14478)
		(layer "In11.Cu")
		(net "M_F_CPU0_SB_DQ<9>")
	)
	(segment
		(start 291.41801 -292.42893)
		(end 291.655246 -292.42893)
		(width 0.14478)
		(layer "In11.Cu")
		(net "M_F_CPU0_SB_DQ<9>")
	)
	(segment
		(start 307.890418 -291.323268)
		(end 316.269624 -282.944062)
		(width 0.14478)
		(layer "In11.Cu")
		(net "M_F_CPU0_SB_DQ<9>")
	)
	(segment
		(start 330.119736 -280.083514)
		(end 330.128118 -280.078688)
		(width 0.0889)
		(layer "In11.Cu")
		(net "M_F_CPU0_SB_DQ<9>")
	)
	(segment
		(start 290.659312 -292.109906)
		(end 291.098986 -292.109906)
		(width 0.14478)
		(layer "In11.Cu")
		(net "M_F_CPU0_SB_DQ<9>")
	)
	(segment
		(start 331.634084 -280.078688)
		(end 331.642466 -280.083514)
		(width 0.0889)
		(layer "In11.Cu")
		(net "M_F_CPU0_SB_DQ<9>")
	)
	(segment
		(start 279.311608 -292.960044)
		(end 279.631394 -293.27983)
		(width 0.14478)
		(layer "In11.Cu")
		(net "M_F_CPU0_SB_DQ<9>")
	)
	(segment
		(start 318.939672 -280.603198)
		(end 319.165224 -280.377646)
		(width 0.14478)
		(layer "In11.Cu")
		(net "M_F_CPU0_SB_DQ<9>")
	)
	(segment
		(start 316.82436 -282.389326)
		(end 317.049912 -282.163774)
		(width 0.14478)
		(layer "In11.Cu")
		(net "M_F_CPU0_SB_DQ<9>")
	)
	(segment
		(start 302.158654 -292.960044)
		(end 304.686462 -292.960044)
		(width 0.14478)
		(layer "In11.Cu")
		(net "M_F_CPU0_SB_DQ<9>")
	)
	(segment
		(start 317.8302 -281.383486)
		(end 318.159384 -281.383486)
		(width 0.14478)
		(layer "In11.Cu")
		(net "M_F_CPU0_SB_DQ<9>")
	)
	(segment
		(start 324.513194 -279.92451)
		(end 327.302114 -279.92451)
		(width 0.0889)
		(layer "In11.Cu")
		(net "M_F_CPU0_SB_DQ<9>")
	)
	(segment
		(start 275.673312 -292.109906)
		(end 278.275796 -292.109906)
		(width 0.14478)
		(layer "In11.Cu")
		(net "M_F_CPU0_SB_DQ<9>")
	)
	(segment
		(start 272.749264 -292.960044)
		(end 274.823174 -292.960044)
		(width 0.14478)
		(layer "In11.Cu")
		(net "M_F_CPU0_SB_DQ<9>")
	)
	(segment
		(start 283.8958 -292.43147)
		(end 284.130496 -292.43147)
		(width 0.14478)
		(layer "In11.Cu")
		(net "M_F_CPU0_SB_DQ<9>")
	)
	(segment
		(start 319.165224 -280.048462)
		(end 319.460626 -279.75306)
		(width 0.14478)
		(layer "In11.Cu")
		(net "M_F_CPU0_SB_DQ<9>")
	)
	(segment
		(start 281.880056 -292.960044)
		(end 282.417774 -292.960044)
		(width 0.14478)
		(layer "In11.Cu")
		(net "M_F_CPU0_SB_DQ<9>")
	)
	(segment
		(start 324.294754 -279.75306)
		(end 324.43293 -279.891236)
		(width 0.0889)
		(layer "In11.Cu")
		(net "M_F_CPU0_SB_DQ<9>")
	)
	(segment
		(start 287.561782 -293.27983)
		(end 287.881568 -292.960044)
		(width 0.14478)
		(layer "In11.Cu")
		(net "M_F_CPU0_SB_DQ<9>")
	)
	(segment
		(start 283.267912 -292.109906)
		(end 283.574236 -292.109906)
		(width 0.14478)
		(layer "In11.Cu")
		(net "M_F_CPU0_SB_DQ<9>")
	)
	(segment
		(start 289.809174 -292.960044)
		(end 290.659312 -292.109906)
		(width 0.14478)
		(layer "In11.Cu")
		(net "M_F_CPU0_SB_DQ<9>")
	)
	(segment
		(start 286.796734 -292.960044)
		(end 287.005522 -292.960044)
		(width 0.14478)
		(layer "In11.Cu")
		(net "M_F_CPU0_SB_DQ<9>")
	)
	(segment
		(start 318.384936 -280.82875)
		(end 318.610488 -280.603198)
		(width 0.14478)
		(layer "In11.Cu")
		(net "M_F_CPU0_SB_DQ<9>")
	)
	(segment
		(start 284.130496 -292.43147)
		(end 284.45206 -292.109906)
		(width 0.14478)
		(layer "In11.Cu")
		(net "M_F_CPU0_SB_DQ<9>")
	)
	(segment
		(start 278.275796 -292.109906)
		(end 279.125934 -292.960044)
		(width 0.14478)
		(layer "In11.Cu")
		(net "M_F_CPU0_SB_DQ<9>")
	)
	(segment
		(start 271.408906 -293.18331)
		(end 271.57172 -293.346124)
		(width 0.14478)
		(layer "In11.Cu")
		(net "M_F_CPU0_SB_DQ<9>")
	)
	(segment
		(start 287.005522 -292.960044)
		(end 287.325308 -293.27983)
		(width 0.14478)
		(layer "In11.Cu")
		(net "M_F_CPU0_SB_DQ<9>")
	)
	(arc
		(start 327.873868 -280.078688)
		(mid 328.061066 -280.12907)
		(end 328.248264 -280.078688)
		(width 0.0889)
		(layer "In11.Cu")
		(net "M_F_CPU0_SB_DQ<9>")
	)
	(arc
		(start 332.948026 -280.078688)
		(mid 333.230982 -280.002511)
		(end 333.513938 -280.078688)
		(width 0.0889)
		(layer "In11.Cu")
		(net "M_F_CPU0_SB_DQ<9>")
	)
	(arc
		(start 330.128118 -280.078688)
		(mid 330.411074 -280.002511)
		(end 330.69403 -280.078688)
		(width 0.0889)
		(layer "In11.Cu")
		(net "M_F_CPU0_SB_DQ<9>")
	)
	(arc
		(start 331.642466 -280.083514)
		(mid 331.825974 -280.129008)
		(end 332.008226 -280.078688)
		(width 0.0889)
		(layer "In11.Cu")
		(net "M_F_CPU0_SB_DQ<9>")
	)
	(arc
		(start 331.068172 -280.078688)
		(mid 331.351128 -280.002511)
		(end 331.634084 -280.078688)
		(width 0.0889)
		(layer "In11.Cu")
		(net "M_F_CPU0_SB_DQ<9>")
	)
	(arc
		(start 332.008226 -280.078688)
		(mid 332.291182 -280.002511)
		(end 332.574138 -280.078688)
		(width 0.0889)
		(layer "In11.Cu")
		(net "M_F_CPU0_SB_DQ<9>")
	)
	(arc
		(start 333.513938 -280.078688)
		(mid 333.670376 -280.127659)
		(end 333.832708 -280.10485)
		(width 0.0889)
		(layer "In11.Cu")
		(net "M_F_CPU0_SB_DQ<9>")
	)
	(arc
		(start 332.574138 -280.078688)
		(mid 332.761082 -280.128943)
		(end 332.948026 -280.078688)
		(width 0.0889)
		(layer "In11.Cu")
		(net "M_F_CPU0_SB_DQ<9>")
	)
	(arc
		(start 324.43293 -279.891236)
		(mid 324.469741 -279.915896)
		(end 324.513194 -279.92451)
		(width 0.0889)
		(layer "In11.Cu")
		(net "M_F_CPU0_SB_DQ<9>")
	)
	(arc
		(start 327.302114 -279.92451)
		(mid 327.598201 -279.963733)
		(end 327.873868 -280.078688)
		(width 0.0889)
		(layer "In11.Cu")
		(net "M_F_CPU0_SB_DQ<9>")
	)
	(arc
		(start 328.814176 -280.078688)
		(mid 329.00112 -280.128943)
		(end 329.188064 -280.078688)
		(width 0.0889)
		(layer "In11.Cu")
		(net "M_F_CPU0_SB_DQ<9>")
	)
	(arc
		(start 328.248264 -280.078688)
		(mid 328.53122 -280.002511)
		(end 328.814176 -280.078688)
		(width 0.0889)
		(layer "In11.Cu")
		(net "M_F_CPU0_SB_DQ<9>")
	)
	(arc
		(start 329.188064 -280.078688)
		(mid 329.47102 -280.002511)
		(end 329.753976 -280.078688)
		(width 0.0889)
		(layer "In11.Cu")
		(net "M_F_CPU0_SB_DQ<9>")
	)
	(arc
		(start 329.753976 -280.078688)
		(mid 329.936227 -280.129038)
		(end 330.119736 -280.083514)
		(width 0.0889)
		(layer "In11.Cu")
		(net "M_F_CPU0_SB_DQ<9>")
	)
	(arc
		(start 330.702412 -280.083514)
		(mid 330.88592 -280.129008)
		(end 331.068172 -280.078688)
		(width 0.0889)
		(layer "In11.Cu")
		(net "M_F_CPU0_SB_DQ<9>")
	)
	(segment
		(start 332.758034 -278.680164)
		(end 332.291182 -278.946102)
		(width 0.10668)
		(layer "F.Cu")
		(net "M_F_CPU0_SB_DQ<8>")
	)
	(segment
		(start 269.648178 -290.83508)
		(end 270.444468 -291.63137)
		(width 0.14478)
		(layer "In11.Cu")
		(net "M_F_CPU0_SB_DQ<8>")
	)
	(segment
		(start 294.670226 -291.57549)
		(end 294.98544 -291.260276)
		(width 0.14478)
		(layer "In11.Cu")
		(net "M_F_CPU0_SB_DQ<8>")
	)
	(segment
		(start 304.025554 -291.260276)
		(end 304.338228 -291.57295)
		(width 0.14478)
		(layer "In11.Cu")
		(net "M_F_CPU0_SB_DQ<8>")
	)
	(segment
		(start 326.021192 -278.84374)
		(end 326.387206 -279.209754)
		(width 0.0889)
		(layer "In11.Cu")
		(net "M_F_CPU0_SB_DQ<8>")
	)
	(segment
		(start 274.565872 -290.970208)
		(end 274.85594 -291.260276)
		(width 0.14478)
		(layer "In11.Cu")
		(net "M_F_CPU0_SB_DQ<8>")
	)
	(segment
		(start 307.531008 -290.410138)
		(end 319.097406 -278.84374)
		(width 0.14478)
		(layer "In11.Cu")
		(net "M_F_CPU0_SB_DQ<8>")
	)
	(segment
		(start 301.854616 -290.58235)
		(end 302.040036 -290.76777)
		(width 0.14478)
		(layer "In11.Cu")
		(net "M_F_CPU0_SB_DQ<8>")
	)
	(segment
		(start 300.950376 -290.410138)
		(end 301.283878 -290.74364)
		(width 0.14478)
		(layer "In11.Cu")
		(net "M_F_CPU0_SB_DQ<8>")
	)
	(segment
		(start 294.98544 -291.260276)
		(end 296.71264 -291.260276)
		(width 0.14478)
		(layer "In11.Cu")
		(net "M_F_CPU0_SB_DQ<8>")
	)
	(segment
		(start 304.729642 -290.752276)
		(end 304.915062 -290.566856)
		(width 0.14478)
		(layer "In11.Cu")
		(net "M_F_CPU0_SB_DQ<8>")
	)
	(segment
		(start 306.813712 -290.71697)
		(end 307.120544 -290.410138)
		(width 0.14478)
		(layer "In11.Cu")
		(net "M_F_CPU0_SB_DQ<8>")
	)
	(segment
		(start 297.025314 -291.57295)
		(end 297.2689 -291.57295)
		(width 0.14478)
		(layer "In11.Cu")
		(net "M_F_CPU0_SB_DQ<8>")
	)
	(segment
		(start 305.119786 -290.566856)
		(end 305.297332 -290.744402)
		(width 0.14478)
		(layer "In11.Cu")
		(net "M_F_CPU0_SB_DQ<8>")
	)
	(segment
		(start 302.669448 -291.260276)
		(end 302.913034 -291.260276)
		(width 0.14478)
		(layer "In11.Cu")
		(net "M_F_CPU0_SB_DQ<8>")
	)
	(segment
		(start 328.709782 -279.273508)
		(end 328.718164 -279.268682)
		(width 0.0889)
		(layer "In11.Cu")
		(net "M_F_CPU0_SB_DQ<8>")
	)
	(segment
		(start 323.982334 -278.84374)
		(end 326.021192 -278.84374)
		(width 0.0889)
		(layer "In11.Cu")
		(net "M_F_CPU0_SB_DQ<8>")
	)
	(segment
		(start 271.950434 -291.135816)
		(end 272.113248 -290.973002)
		(width 0.14478)
		(layer "In11.Cu")
		(net "M_F_CPU0_SB_DQ<8>")
	)
	(segment
		(start 332.422754 -279.294844)
		(end 332.445106 -279.211532)
		(width 0.0889)
		(layer "In11.Cu")
		(net "M_F_CPU0_SB_DQ<8>")
	)
	(segment
		(start 274.33524 -290.970208)
		(end 274.565872 -290.970208)
		(width 0.14478)
		(layer "In11.Cu")
		(net "M_F_CPU0_SB_DQ<8>")
	)
	(segment
		(start 271.78762 -291.63137)
		(end 271.950434 -291.468556)
		(width 0.14478)
		(layer "In11.Cu")
		(net "M_F_CPU0_SB_DQ<8>")
	)
	(segment
		(start 303.469294 -291.57295)
		(end 303.781968 -291.260276)
		(width 0.14478)
		(layer "In11.Cu")
		(net "M_F_CPU0_SB_DQ<8>")
	)
	(segment
		(start 294.42918 -291.57549)
		(end 294.670226 -291.57549)
		(width 0.14478)
		(layer "In11.Cu")
		(net "M_F_CPU0_SB_DQ<8>")
	)
	(segment
		(start 299.353732 -290.69665)
		(end 299.640244 -290.410138)
		(width 0.14478)
		(layer "In11.Cu")
		(net "M_F_CPU0_SB_DQ<8>")
	)
	(segment
		(start 301.649892 -290.58235)
		(end 301.854616 -290.58235)
		(width 0.14478)
		(layer "In11.Cu")
		(net "M_F_CPU0_SB_DQ<8>")
	)
	(segment
		(start 302.356774 -291.57295)
		(end 302.669448 -291.260276)
		(width 0.14478)
		(layer "In11.Cu")
		(net "M_F_CPU0_SB_DQ<8>")
	)
	(segment
		(start 278.278336 -290.410138)
		(end 279.441148 -291.57295)
		(width 0.14478)
		(layer "In11.Cu")
		(net "M_F_CPU0_SB_DQ<8>")
	)
	(segment
		(start 327.765156 -279.276302)
		(end 327.778872 -279.268428)
		(width 0.0889)
		(layer "In11.Cu")
		(net "M_F_CPU0_SB_DQ<8>")
	)
	(segment
		(start 272.113248 -290.973002)
		(end 272.34388 -290.973002)
		(width 0.14478)
		(layer "In11.Cu")
		(net "M_F_CPU0_SB_DQ<8>")
	)
	(segment
		(start 327.778872 -279.268428)
		(end 327.79081 -279.26157)
		(width 0.0889)
		(layer "In11.Cu")
		(net "M_F_CPU0_SB_DQ<8>")
	)
	(segment
		(start 270.6751 -291.63137)
		(end 270.837914 -291.468556)
		(width 0.14478)
		(layer "In11.Cu")
		(net "M_F_CPU0_SB_DQ<8>")
	)
	(segment
		(start 270.837914 -291.135816)
		(end 271.000728 -290.973002)
		(width 0.14478)
		(layer "In11.Cu")
		(net "M_F_CPU0_SB_DQ<8>")
	)
	(segment
		(start 281.925268 -291.260276)
		(end 282.164282 -291.49929)
		(width 0.14478)
		(layer "In11.Cu")
		(net "M_F_CPU0_SB_DQ<8>")
	)
	(segment
		(start 273.393408 -291.260276)
		(end 273.77898 -291.645848)
		(width 0.14478)
		(layer "In11.Cu")
		(net "M_F_CPU0_SB_DQ<8>")
	)
	(segment
		(start 271.950434 -291.468556)
		(end 271.950434 -291.135816)
		(width 0.14478)
		(layer "In11.Cu")
		(net "M_F_CPU0_SB_DQ<8>")
	)
	(segment
		(start 306.564284 -290.71697)
		(end 306.813712 -290.71697)
		(width 0.14478)
		(layer "In11.Cu")
		(net "M_F_CPU0_SB_DQ<8>")
	)
	(segment
		(start 304.673254 -291.57295)
		(end 304.906934 -291.33927)
		(width 0.14478)
		(layer "In11.Cu")
		(net "M_F_CPU0_SB_DQ<8>")
	)
	(segment
		(start 326.464676 -279.268428)
		(end 326.484742 -279.279858)
		(width 0.0889)
		(layer "In11.Cu")
		(net "M_F_CPU0_SB_DQ<8>")
	)
	(segment
		(start 302.113188 -291.57295)
		(end 302.356774 -291.57295)
		(width 0.14478)
		(layer "In11.Cu")
		(net "M_F_CPU0_SB_DQ<8>")
	)
	(segment
		(start 293.263828 -290.410138)
		(end 294.42918 -291.57549)
		(width 0.14478)
		(layer "In11.Cu")
		(net "M_F_CPU0_SB_DQ<8>")
	)
	(segment
		(start 286.804608 -291.56533)
		(end 287.055814 -291.56533)
		(width 0.14478)
		(layer "In11.Cu")
		(net "M_F_CPU0_SB_DQ<8>")
	)
	(segment
		(start 270.837914 -291.468556)
		(end 270.837914 -291.135816)
		(width 0.14478)
		(layer "In11.Cu")
		(net "M_F_CPU0_SB_DQ<8>")
	)
	(segment
		(start 279.684734 -291.57295)
		(end 279.997408 -291.260276)
		(width 0.14478)
		(layer "In11.Cu")
		(net "M_F_CPU0_SB_DQ<8>")
	)
	(segment
		(start 273.77898 -291.645848)
		(end 274.009612 -291.645848)
		(width 0.14478)
		(layer "In11.Cu")
		(net "M_F_CPU0_SB_DQ<8>")
	)
	(segment
		(start 271.000728 -290.973002)
		(end 271.23136 -290.973002)
		(width 0.14478)
		(layer "In11.Cu")
		(net "M_F_CPU0_SB_DQ<8>")
	)
	(segment
		(start 298.797472 -290.410138)
		(end 299.083984 -290.69665)
		(width 0.14478)
		(layer "In11.Cu")
		(net "M_F_CPU0_SB_DQ<8>")
	)
	(segment
		(start 299.640244 -290.410138)
		(end 300.950376 -290.410138)
		(width 0.14478)
		(layer "In11.Cu")
		(net "M_F_CPU0_SB_DQ<8>")
	)
	(segment
		(start 270.444468 -291.63137)
		(end 270.6751 -291.63137)
		(width 0.14478)
		(layer "In11.Cu")
		(net "M_F_CPU0_SB_DQ<8>")
	)
	(segment
		(start 290.88588 -290.410138)
		(end 293.263828 -290.410138)
		(width 0.14478)
		(layer "In11.Cu")
		(net "M_F_CPU0_SB_DQ<8>")
	)
	(segment
		(start 274.85594 -291.260276)
		(end 275.151342 -291.260276)
		(width 0.14478)
		(layer "In11.Cu")
		(net "M_F_CPU0_SB_DQ<8>")
	)
	(segment
		(start 281.051762 -291.49929)
		(end 281.369008 -291.49929)
		(width 0.14478)
		(layer "In11.Cu")
		(net "M_F_CPU0_SB_DQ<8>")
	)
	(segment
		(start 301.878746 -291.338508)
		(end 302.113188 -291.57295)
		(width 0.14478)
		(layer "In11.Cu")
		(net "M_F_CPU0_SB_DQ<8>")
	)
	(segment
		(start 285.649416 -290.410138)
		(end 286.804608 -291.56533)
		(width 0.14478)
		(layer "In11.Cu")
		(net "M_F_CPU0_SB_DQ<8>")
	)
	(segment
		(start 319.097406 -278.84374)
		(end 323.982334 -278.84374)
		(width 0.14478)
		(layer "In11.Cu")
		(net "M_F_CPU0_SB_DQ<8>")
	)
	(segment
		(start 282.164282 -291.49929)
		(end 282.481528 -291.49929)
		(width 0.14478)
		(layer "In11.Cu")
		(net "M_F_CPU0_SB_DQ<8>")
	)
	(segment
		(start 283.57068 -290.410138)
		(end 285.649416 -290.410138)
		(width 0.14478)
		(layer "In11.Cu")
		(net "M_F_CPU0_SB_DQ<8>")
	)
	(segment
		(start 304.906934 -291.33927)
		(end 304.906934 -291.134546)
		(width 0.14478)
		(layer "In11.Cu")
		(net "M_F_CPU0_SB_DQ<8>")
	)
	(segment
		(start 289.171888 -291.260276)
		(end 289.479482 -291.56787)
		(width 0.14478)
		(layer "In11.Cu")
		(net "M_F_CPU0_SB_DQ<8>")
	)
	(segment
		(start 305.836066 -290.410138)
		(end 306.257452 -290.410138)
		(width 0.14478)
		(layer "In11.Cu")
		(net "M_F_CPU0_SB_DQ<8>")
	)
	(segment
		(start 274.009612 -291.645848)
		(end 274.172426 -291.483034)
		(width 0.14478)
		(layer "In11.Cu")
		(net "M_F_CPU0_SB_DQ<8>")
	)
	(segment
		(start 306.257452 -290.410138)
		(end 306.564284 -290.71697)
		(width 0.14478)
		(layer "In11.Cu")
		(net "M_F_CPU0_SB_DQ<8>")
	)
	(segment
		(start 281.369008 -291.49929)
		(end 281.608022 -291.260276)
		(width 0.14478)
		(layer "In11.Cu")
		(net "M_F_CPU0_SB_DQ<8>")
	)
	(segment
		(start 302.040036 -290.972494)
		(end 301.878746 -291.133784)
		(width 0.14478)
		(layer "In11.Cu")
		(net "M_F_CPU0_SB_DQ<8>")
	)
	(segment
		(start 304.338228 -291.57295)
		(end 304.673254 -291.57295)
		(width 0.14478)
		(layer "In11.Cu")
		(net "M_F_CPU0_SB_DQ<8>")
	)
	(segment
		(start 271.394174 -291.468556)
		(end 271.556988 -291.63137)
		(width 0.14478)
		(layer "In11.Cu")
		(net "M_F_CPU0_SB_DQ<8>")
	)
	(segment
		(start 287.360868 -291.260276)
		(end 289.171888 -291.260276)
		(width 0.14478)
		(layer "In11.Cu")
		(net "M_F_CPU0_SB_DQ<8>")
	)
	(segment
		(start 329.284076 -279.268682)
		(end 329.292458 -279.273508)
		(width 0.0889)
		(layer "In11.Cu")
		(net "M_F_CPU0_SB_DQ<8>")
	)
	(segment
		(start 326.387206 -279.209754)
		(end 326.38746 -279.209754)
		(width 0.0889)
		(layer "In11.Cu")
		(net "M_F_CPU0_SB_DQ<8>")
	)
	(segment
		(start 302.040036 -290.76777)
		(end 302.040036 -290.972494)
		(width 0.14478)
		(layer "In11.Cu")
		(net "M_F_CPU0_SB_DQ<8>")
	)
	(segment
		(start 272.631154 -291.260276)
		(end 273.393408 -291.260276)
		(width 0.14478)
		(layer "In11.Cu")
		(net "M_F_CPU0_SB_DQ<8>")
	)
	(segment
		(start 297.2689 -291.57295)
		(end 298.431712 -290.410138)
		(width 0.14478)
		(layer "In11.Cu")
		(net "M_F_CPU0_SB_DQ<8>")
	)
	(segment
		(start 271.556988 -291.63137)
		(end 271.78762 -291.63137)
		(width 0.14478)
		(layer "In11.Cu")
		(net "M_F_CPU0_SB_DQ<8>")
	)
	(segment
		(start 304.729388 -290.957)
		(end 304.729642 -290.752276)
		(width 0.14478)
		(layer "In11.Cu")
		(net "M_F_CPU0_SB_DQ<8>")
	)
	(segment
		(start 274.172426 -291.133022)
		(end 274.33524 -290.970208)
		(width 0.14478)
		(layer "In11.Cu")
		(net "M_F_CPU0_SB_DQ<8>")
	)
	(segment
		(start 289.479482 -291.56787)
		(end 289.728148 -291.56787)
		(width 0.14478)
		(layer "In11.Cu")
		(net "M_F_CPU0_SB_DQ<8>")
	)
	(segment
		(start 298.431712 -290.410138)
		(end 298.797472 -290.410138)
		(width 0.14478)
		(layer "In11.Cu")
		(net "M_F_CPU0_SB_DQ<8>")
	)
	(segment
		(start 299.083984 -290.69665)
		(end 299.353732 -290.69665)
		(width 0.14478)
		(layer "In11.Cu")
		(net "M_F_CPU0_SB_DQ<8>")
	)
	(segment
		(start 301.283878 -290.74364)
		(end 301.488602 -290.74364)
		(width 0.14478)
		(layer "In11.Cu")
		(net "M_F_CPU0_SB_DQ<8>")
	)
	(segment
		(start 271.394174 -291.135816)
		(end 271.394174 -291.468556)
		(width 0.14478)
		(layer "In11.Cu")
		(net "M_F_CPU0_SB_DQ<8>")
	)
	(segment
		(start 287.055814 -291.56533)
		(end 287.360868 -291.260276)
		(width 0.14478)
		(layer "In11.Cu")
		(net "M_F_CPU0_SB_DQ<8>")
	)
	(segment
		(start 305.297332 -290.744402)
		(end 305.501548 -290.744656)
		(width 0.14478)
		(layer "In11.Cu")
		(net "M_F_CPU0_SB_DQ<8>")
	)
	(segment
		(start 274.172426 -291.483034)
		(end 274.172426 -291.133022)
		(width 0.14478)
		(layer "In11.Cu")
		(net "M_F_CPU0_SB_DQ<8>")
	)
	(segment
		(start 331.52969 -279.273508)
		(end 331.538072 -279.268682)
		(width 0.0889)
		(layer "In11.Cu")
		(net "M_F_CPU0_SB_DQ<8>")
	)
	(segment
		(start 296.71264 -291.260276)
		(end 297.025314 -291.57295)
		(width 0.14478)
		(layer "In11.Cu")
		(net "M_F_CPU0_SB_DQ<8>")
	)
	(segment
		(start 275.151342 -291.260276)
		(end 276.00148 -290.410138)
		(width 0.14478)
		(layer "In11.Cu")
		(net "M_F_CPU0_SB_DQ<8>")
	)
	(segment
		(start 327.387204 -279.258014)
		(end 327.405238 -279.268682)
		(width 0.0889)
		(layer "In11.Cu")
		(net "M_F_CPU0_SB_DQ<8>")
	)
	(segment
		(start 280.812748 -291.260276)
		(end 281.051762 -291.49929)
		(width 0.14478)
		(layer "In11.Cu")
		(net "M_F_CPU0_SB_DQ<8>")
	)
	(segment
		(start 271.23136 -290.973002)
		(end 271.394174 -291.135816)
		(width 0.14478)
		(layer "In11.Cu")
		(net "M_F_CPU0_SB_DQ<8>")
	)
	(segment
		(start 272.34388 -290.973002)
		(end 272.631154 -291.260276)
		(width 0.14478)
		(layer "In11.Cu")
		(net "M_F_CPU0_SB_DQ<8>")
	)
	(segment
		(start 301.488602 -290.74364)
		(end 301.649892 -290.58235)
		(width 0.14478)
		(layer "In11.Cu")
		(net "M_F_CPU0_SB_DQ<8>")
	)
	(segment
		(start 279.441148 -291.57295)
		(end 279.684734 -291.57295)
		(width 0.14478)
		(layer "In11.Cu")
		(net "M_F_CPU0_SB_DQ<8>")
	)
	(segment
		(start 304.906934 -291.134546)
		(end 304.729388 -290.957)
		(width 0.14478)
		(layer "In11.Cu")
		(net "M_F_CPU0_SB_DQ<8>")
	)
	(segment
		(start 307.120544 -290.410138)
		(end 307.531008 -290.410138)
		(width 0.14478)
		(layer "In11.Cu")
		(net "M_F_CPU0_SB_DQ<8>")
	)
	(segment
		(start 289.728148 -291.56787)
		(end 290.88588 -290.410138)
		(width 0.14478)
		(layer "In11.Cu")
		(net "M_F_CPU0_SB_DQ<8>")
	)
	(segment
		(start 279.997408 -291.260276)
		(end 280.812748 -291.260276)
		(width 0.14478)
		(layer "In11.Cu")
		(net "M_F_CPU0_SB_DQ<8>")
	)
	(segment
		(start 302.913034 -291.260276)
		(end 303.225708 -291.57295)
		(width 0.14478)
		(layer "In11.Cu")
		(net "M_F_CPU0_SB_DQ<8>")
	)
	(segment
		(start 281.608022 -291.260276)
		(end 281.925268 -291.260276)
		(width 0.14478)
		(layer "In11.Cu")
		(net "M_F_CPU0_SB_DQ<8>")
	)
	(segment
		(start 301.878746 -291.133784)
		(end 301.878746 -291.338508)
		(width 0.14478)
		(layer "In11.Cu")
		(net "M_F_CPU0_SB_DQ<8>")
	)
	(segment
		(start 282.481528 -291.49929)
		(end 283.57068 -290.410138)
		(width 0.14478)
		(layer "In11.Cu")
		(net "M_F_CPU0_SB_DQ<8>")
	)
	(segment
		(start 332.445106 -279.211532)
		(end 332.291182 -278.946102)
		(width 0.0889)
		(layer "In11.Cu")
		(net "M_F_CPU0_SB_DQ<8>")
	)
	(segment
		(start 276.00148 -290.410138)
		(end 278.278336 -290.410138)
		(width 0.14478)
		(layer "In11.Cu")
		(net "M_F_CPU0_SB_DQ<8>")
	)
	(segment
		(start 303.225708 -291.57295)
		(end 303.469294 -291.57295)
		(width 0.14478)
		(layer "In11.Cu")
		(net "M_F_CPU0_SB_DQ<8>")
	)
	(segment
		(start 305.501548 -290.744656)
		(end 305.836066 -290.410138)
		(width 0.14478)
		(layer "In11.Cu")
		(net "M_F_CPU0_SB_DQ<8>")
	)
	(segment
		(start 303.781968 -291.260276)
		(end 304.025554 -291.260276)
		(width 0.14478)
		(layer "In11.Cu")
		(net "M_F_CPU0_SB_DQ<8>")
	)
	(segment
		(start 304.915062 -290.566856)
		(end 305.119786 -290.566856)
		(width 0.14478)
		(layer "In11.Cu")
		(net "M_F_CPU0_SB_DQ<8>")
	)
	(arc
		(start 329.658218 -279.268682)
		(mid 329.941174 -279.192505)
		(end 330.22413 -279.268682)
		(width 0.0889)
		(layer "In11.Cu")
		(net "M_F_CPU0_SB_DQ<8>")
	)
	(arc
		(start 326.838564 -279.268682)
		(mid 327.111508 -279.192102)
		(end 327.387204 -279.258014)
		(width 0.0889)
		(layer "In11.Cu")
		(net "M_F_CPU0_SB_DQ<8>")
	)
	(arc
		(start 327.79081 -279.26157)
		(mid 328.068344 -279.192589)
		(end 328.344022 -279.268682)
		(width 0.0889)
		(layer "In11.Cu")
		(net "M_F_CPU0_SB_DQ<8>")
	)
	(arc
		(start 328.718164 -279.268682)
		(mid 329.00112 -279.192505)
		(end 329.284076 -279.268682)
		(width 0.0889)
		(layer "In11.Cu")
		(net "M_F_CPU0_SB_DQ<8>")
	)
	(arc
		(start 328.344022 -279.268682)
		(mid 328.526273 -279.319032)
		(end 328.709782 -279.273508)
		(width 0.0889)
		(layer "In11.Cu")
		(net "M_F_CPU0_SB_DQ<8>")
	)
	(arc
		(start 326.38746 -279.209754)
		(mid 326.424156 -279.241607)
		(end 326.464676 -279.268428)
		(width 0.0889)
		(layer "In11.Cu")
		(net "M_F_CPU0_SB_DQ<8>")
	)
	(arc
		(start 329.292458 -279.273508)
		(mid 329.475966 -279.319002)
		(end 329.658218 -279.268682)
		(width 0.0889)
		(layer "In11.Cu")
		(net "M_F_CPU0_SB_DQ<8>")
	)
	(arc
		(start 331.538072 -279.268682)
		(mid 331.821028 -279.192505)
		(end 332.103984 -279.268682)
		(width 0.0889)
		(layer "In11.Cu")
		(net "M_F_CPU0_SB_DQ<8>")
	)
	(arc
		(start 326.484742 -279.279858)
		(mid 326.663074 -279.318955)
		(end 326.838564 -279.268682)
		(width 0.0889)
		(layer "In11.Cu")
		(net "M_F_CPU0_SB_DQ<8>")
	)
	(arc
		(start 327.405238 -279.268682)
		(mid 327.584225 -279.318852)
		(end 327.765156 -279.276302)
		(width 0.0889)
		(layer "In11.Cu")
		(net "M_F_CPU0_SB_DQ<8>")
	)
	(arc
		(start 330.22413 -279.268682)
		(mid 330.411074 -279.318937)
		(end 330.598018 -279.268682)
		(width 0.0889)
		(layer "In11.Cu")
		(net "M_F_CPU0_SB_DQ<8>")
	)
	(arc
		(start 330.598018 -279.268682)
		(mid 330.880974 -279.192505)
		(end 331.16393 -279.268682)
		(width 0.0889)
		(layer "In11.Cu")
		(net "M_F_CPU0_SB_DQ<8>")
	)
	(arc
		(start 331.16393 -279.268682)
		(mid 331.346181 -279.319032)
		(end 331.52969 -279.273508)
		(width 0.0889)
		(layer "In11.Cu")
		(net "M_F_CPU0_SB_DQ<8>")
	)
	(arc
		(start 332.103984 -279.268682)
		(mid 332.260422 -279.317653)
		(end 332.422754 -279.294844)
		(width 0.0889)
		(layer "In11.Cu")
		(net "M_F_CPU0_SB_DQ<8>")
	)
	(segment
		(start 334.637888 -278.680164)
		(end 334.171036 -278.946102)
		(width 0.10668)
		(layer "F.Cu")
		(net "M_F_CPU0_SB_DQ<7>")
	)
	(segment
		(start 268.111478 -289.963352)
		(end 268.256258 -289.818572)
		(width 0.14478)
		(layer "In11.Cu")
		(net "M_F_CPU0_SB_DQ<7>")
	)
	(segment
		(start 267.560044 -290.265358)
		(end 267.704824 -290.410138)
		(width 0.14478)
		(layer "In11.Cu")
		(net "M_F_CPU0_SB_DQ<7>")
	)
	(segment
		(start 287.222946 -290.410138)
		(end 289.313874 -290.410138)
		(width 0.14478)
		(layer "In11.Cu")
		(net "M_F_CPU0_SB_DQ<7>")
	)
	(segment
		(start 274.392898 -290.410138)
		(end 276.445472 -289.56)
		(width 0.14478)
		(layer "In11.Cu")
		(net "M_F_CPU0_SB_DQ<7>")
	)
	(segment
		(start 324.643496 -278.28748)
		(end 324.807326 -278.45131)
		(width 0.0889)
		(layer "In11.Cu")
		(net "M_F_CPU0_SB_DQ<7>")
	)
	(segment
		(start 301.48403 -290.014914)
		(end 305.390042 -290.014914)
		(width 0.14478)
		(layer "In11.Cu")
		(net "M_F_CPU0_SB_DQ<7>")
	)
	(segment
		(start 296.907458 -290.410138)
		(end 298.960032 -289.56)
		(width 0.14478)
		(layer "In11.Cu")
		(net "M_F_CPU0_SB_DQ<7>")
	)
	(segment
		(start 292.683692 -289.56)
		(end 294.736266 -290.410138)
		(width 0.14478)
		(layer "In11.Cu")
		(net "M_F_CPU0_SB_DQ<7>")
	)
	(segment
		(start 329.284076 -278.623522)
		(end 329.292458 -278.618696)
		(width 0.0889)
		(layer "In11.Cu")
		(net "M_F_CPU0_SB_DQ<7>")
	)
	(segment
		(start 276.445472 -289.56)
		(end 277.89124 -289.56)
		(width 0.14478)
		(layer "In11.Cu")
		(net "M_F_CPU0_SB_DQ<7>")
	)
	(segment
		(start 267.415264 -289.818572)
		(end 267.560044 -289.963352)
		(width 0.14478)
		(layer "In11.Cu")
		(net "M_F_CPU0_SB_DQ<7>")
	)
	(segment
		(start 289.313874 -290.410138)
		(end 291.366448 -289.56)
		(width 0.14478)
		(layer "In11.Cu")
		(net "M_F_CPU0_SB_DQ<7>")
	)
	(segment
		(start 331.52969 -278.618696)
		(end 331.538072 -278.623522)
		(width 0.0889)
		(layer "In11.Cu")
		(net "M_F_CPU0_SB_DQ<7>")
	)
	(segment
		(start 291.366448 -289.56)
		(end 292.683692 -289.56)
		(width 0.14478)
		(layer "In11.Cu")
		(net "M_F_CPU0_SB_DQ<7>")
	)
	(segment
		(start 267.704824 -290.410138)
		(end 267.966698 -290.410138)
		(width 0.14478)
		(layer "In11.Cu")
		(net "M_F_CPU0_SB_DQ<7>")
	)
	(segment
		(start 265.54811 -289.985196)
		(end 265.973052 -290.410138)
		(width 0.14478)
		(layer "In11.Cu")
		(net "M_F_CPU0_SB_DQ<7>")
	)
	(segment
		(start 284.110684 -289.56)
		(end 285.170372 -289.56)
		(width 0.14478)
		(layer "In11.Cu")
		(net "M_F_CPU0_SB_DQ<7>")
	)
	(segment
		(start 267.00861 -290.265358)
		(end 267.00861 -289.963352)
		(width 0.14478)
		(layer "In11.Cu")
		(net "M_F_CPU0_SB_DQ<7>")
	)
	(segment
		(start 305.844956 -289.56)
		(end 307.574442 -289.56)
		(width 0.14478)
		(layer "In11.Cu")
		(net "M_F_CPU0_SB_DQ<7>")
	)
	(segment
		(start 267.966698 -290.410138)
		(end 268.111478 -290.265358)
		(width 0.14478)
		(layer "In11.Cu")
		(net "M_F_CPU0_SB_DQ<7>")
	)
	(segment
		(start 318.846962 -278.28748)
		(end 323.97446 -278.28748)
		(width 0.14478)
		(layer "In11.Cu")
		(net "M_F_CPU0_SB_DQ<7>")
	)
	(segment
		(start 333.044038 -278.623522)
		(end 333.05242 -278.618696)
		(width 0.0889)
		(layer "In11.Cu")
		(net "M_F_CPU0_SB_DQ<7>")
	)
	(segment
		(start 328.709782 -278.618696)
		(end 328.718164 -278.623522)
		(width 0.0889)
		(layer "In11.Cu")
		(net "M_F_CPU0_SB_DQ<7>")
	)
	(segment
		(start 268.662912 -290.265358)
		(end 268.807692 -290.410138)
		(width 0.14478)
		(layer "In11.Cu")
		(net "M_F_CPU0_SB_DQ<7>")
	)
	(segment
		(start 323.97446 -278.28748)
		(end 324.643496 -278.28748)
		(width 0.0889)
		(layer "In11.Cu")
		(net "M_F_CPU0_SB_DQ<7>")
	)
	(segment
		(start 328.333608 -278.629618)
		(end 328.344022 -278.623522)
		(width 0.0889)
		(layer "In11.Cu")
		(net "M_F_CPU0_SB_DQ<7>")
	)
	(segment
		(start 266.86383 -290.410138)
		(end 267.00861 -290.265358)
		(width 0.14478)
		(layer "In11.Cu")
		(net "M_F_CPU0_SB_DQ<7>")
	)
	(segment
		(start 265.973052 -290.410138)
		(end 266.86383 -290.410138)
		(width 0.14478)
		(layer "In11.Cu")
		(net "M_F_CPU0_SB_DQ<7>")
	)
	(segment
		(start 333.9211 -278.655272)
		(end 334.017112 -278.680672)
		(width 0.0889)
		(layer "In11.Cu")
		(net "M_F_CPU0_SB_DQ<7>")
	)
	(segment
		(start 268.256258 -289.818572)
		(end 268.518132 -289.818572)
		(width 0.14478)
		(layer "In11.Cu")
		(net "M_F_CPU0_SB_DQ<7>")
	)
	(segment
		(start 294.736266 -290.410138)
		(end 296.907458 -290.410138)
		(width 0.14478)
		(layer "In11.Cu")
		(net "M_F_CPU0_SB_DQ<7>")
	)
	(segment
		(start 267.15339 -289.818572)
		(end 267.415264 -289.818572)
		(width 0.14478)
		(layer "In11.Cu")
		(net "M_F_CPU0_SB_DQ<7>")
	)
	(segment
		(start 268.807692 -290.410138)
		(end 274.392898 -290.410138)
		(width 0.14478)
		(layer "In11.Cu")
		(net "M_F_CPU0_SB_DQ<7>")
	)
	(segment
		(start 267.560044 -289.963352)
		(end 267.560044 -290.265358)
		(width 0.14478)
		(layer "In11.Cu")
		(net "M_F_CPU0_SB_DQ<7>")
	)
	(segment
		(start 268.518132 -289.818572)
		(end 268.662912 -289.963352)
		(width 0.14478)
		(layer "In11.Cu")
		(net "M_F_CPU0_SB_DQ<7>")
	)
	(segment
		(start 277.89124 -289.56)
		(end 279.943814 -290.410138)
		(width 0.14478)
		(layer "In11.Cu")
		(net "M_F_CPU0_SB_DQ<7>")
	)
	(segment
		(start 324.807326 -278.45131)
		(end 327.14057 -278.45131)
		(width 0.0889)
		(layer "In11.Cu")
		(net "M_F_CPU0_SB_DQ<7>")
	)
	(segment
		(start 285.170372 -289.56)
		(end 287.222946 -290.410138)
		(width 0.14478)
		(layer "In11.Cu")
		(net "M_F_CPU0_SB_DQ<7>")
	)
	(segment
		(start 307.574442 -289.56)
		(end 318.846962 -278.28748)
		(width 0.14478)
		(layer "In11.Cu")
		(net "M_F_CPU0_SB_DQ<7>")
	)
	(segment
		(start 268.662912 -289.963352)
		(end 268.662912 -290.265358)
		(width 0.14478)
		(layer "In11.Cu")
		(net "M_F_CPU0_SB_DQ<7>")
	)
	(segment
		(start 267.00861 -289.963352)
		(end 267.15339 -289.818572)
		(width 0.14478)
		(layer "In11.Cu")
		(net "M_F_CPU0_SB_DQ<7>")
	)
	(segment
		(start 300.385734 -289.56)
		(end 301.48403 -290.014914)
		(width 0.14478)
		(layer "In11.Cu")
		(net "M_F_CPU0_SB_DQ<7>")
	)
	(segment
		(start 298.960032 -289.56)
		(end 300.385734 -289.56)
		(width 0.14478)
		(layer "In11.Cu")
		(net "M_F_CPU0_SB_DQ<7>")
	)
	(segment
		(start 334.017112 -278.680672)
		(end 334.171036 -278.946102)
		(width 0.0889)
		(layer "In11.Cu")
		(net "M_F_CPU0_SB_DQ<7>")
	)
	(segment
		(start 279.943814 -290.410138)
		(end 282.05811 -290.410138)
		(width 0.14478)
		(layer "In11.Cu")
		(net "M_F_CPU0_SB_DQ<7>")
	)
	(segment
		(start 305.390042 -290.014914)
		(end 305.844956 -289.56)
		(width 0.14478)
		(layer "In11.Cu")
		(net "M_F_CPU0_SB_DQ<7>")
	)
	(segment
		(start 282.05811 -290.410138)
		(end 284.110684 -289.56)
		(width 0.14478)
		(layer "In11.Cu")
		(net "M_F_CPU0_SB_DQ<7>")
	)
	(segment
		(start 332.469744 -278.618696)
		(end 332.478126 -278.623522)
		(width 0.0889)
		(layer "In11.Cu")
		(net "M_F_CPU0_SB_DQ<7>")
	)
	(segment
		(start 268.111478 -290.265358)
		(end 268.111478 -289.963352)
		(width 0.14478)
		(layer "In11.Cu")
		(net "M_F_CPU0_SB_DQ<7>")
	)
	(arc
		(start 328.718164 -278.623522)
		(mid 329.00112 -278.699699)
		(end 329.284076 -278.623522)
		(width 0.0889)
		(layer "In11.Cu")
		(net "M_F_CPU0_SB_DQ<7>")
	)
	(arc
		(start 332.478126 -278.623522)
		(mid 332.761082 -278.699699)
		(end 333.044038 -278.623522)
		(width 0.0889)
		(layer "In11.Cu")
		(net "M_F_CPU0_SB_DQ<7>")
	)
	(arc
		(start 333.05242 -278.618696)
		(mid 333.235928 -278.573202)
		(end 333.41818 -278.623522)
		(width 0.0889)
		(layer "In11.Cu")
		(net "M_F_CPU0_SB_DQ<7>")
	)
	(arc
		(start 333.41818 -278.623522)
		(mid 333.665893 -278.698742)
		(end 333.9211 -278.655272)
		(width 0.0889)
		(layer "In11.Cu")
		(net "M_F_CPU0_SB_DQ<7>")
	)
	(arc
		(start 327.777856 -278.623522)
		(mid 328.054923 -278.699793)
		(end 328.333608 -278.629618)
		(width 0.0889)
		(layer "In11.Cu")
		(net "M_F_CPU0_SB_DQ<7>")
	)
	(arc
		(start 331.538072 -278.623522)
		(mid 331.821028 -278.699699)
		(end 332.103984 -278.623522)
		(width 0.0889)
		(layer "In11.Cu")
		(net "M_F_CPU0_SB_DQ<7>")
	)
	(arc
		(start 327.14057 -278.45131)
		(mid 327.47064 -278.495125)
		(end 327.777856 -278.623522)
		(width 0.0889)
		(layer "In11.Cu")
		(net "M_F_CPU0_SB_DQ<7>")
	)
	(arc
		(start 330.22413 -278.623522)
		(mid 330.411074 -278.573267)
		(end 330.598018 -278.623522)
		(width 0.0889)
		(layer "In11.Cu")
		(net "M_F_CPU0_SB_DQ<7>")
	)
	(arc
		(start 328.344022 -278.623522)
		(mid 328.526273 -278.573172)
		(end 328.709782 -278.618696)
		(width 0.0889)
		(layer "In11.Cu")
		(net "M_F_CPU0_SB_DQ<7>")
	)
	(arc
		(start 330.598018 -278.623522)
		(mid 330.880974 -278.699699)
		(end 331.16393 -278.623522)
		(width 0.0889)
		(layer "In11.Cu")
		(net "M_F_CPU0_SB_DQ<7>")
	)
	(arc
		(start 329.292458 -278.618696)
		(mid 329.475966 -278.573202)
		(end 329.658218 -278.623522)
		(width 0.0889)
		(layer "In11.Cu")
		(net "M_F_CPU0_SB_DQ<7>")
	)
	(arc
		(start 331.16393 -278.623522)
		(mid 331.346181 -278.573172)
		(end 331.52969 -278.618696)
		(width 0.0889)
		(layer "In11.Cu")
		(net "M_F_CPU0_SB_DQ<7>")
	)
	(arc
		(start 329.658218 -278.623522)
		(mid 329.941174 -278.699699)
		(end 330.22413 -278.623522)
		(width 0.0889)
		(layer "In11.Cu")
		(net "M_F_CPU0_SB_DQ<7>")
	)
	(arc
		(start 332.103984 -278.623522)
		(mid 332.286235 -278.573172)
		(end 332.469744 -278.618696)
		(width 0.0889)
		(layer "In11.Cu")
		(net "M_F_CPU0_SB_DQ<7>")
	)
	(segment
		(start 333.227934 -277.870158)
		(end 332.761082 -278.136096)
		(width 0.10668)
		(layer "F.Cu")
		(net "M_F_CPU0_SB_DQ<6>")
	)
	(segment
		(start 268.57452 -288.101532)
		(end 268.7193 -288.246312)
		(width 0.14478)
		(layer "In11.Cu")
		(net "M_F_CPU0_SB_DQ<6>")
	)
	(segment
		(start 330.69403 -277.813516)
		(end 330.702412 -277.80869)
		(width 0.0889)
		(layer "In11.Cu")
		(net "M_F_CPU0_SB_DQ<6>")
	)
	(segment
		(start 318.469772 -277.37816)
		(end 323.894704 -277.37816)
		(width 0.14478)
		(layer "In11.Cu")
		(net "M_F_CPU0_SB_DQ<6>")
	)
	(segment
		(start 275.313902 -288.710116)
		(end 276.16404 -287.859978)
		(width 0.14478)
		(layer "In11.Cu")
		(net "M_F_CPU0_SB_DQ<6>")
	)
	(segment
		(start 267.616432 -288.565336)
		(end 267.761212 -288.710116)
		(width 0.14478)
		(layer "In11.Cu")
		(net "M_F_CPU0_SB_DQ<6>")
	)
	(segment
		(start 268.86408 -288.710116)
		(end 275.313902 -288.710116)
		(width 0.14478)
		(layer "In11.Cu")
		(net "M_F_CPU0_SB_DQ<6>")
	)
	(segment
		(start 307.987954 -287.859978)
		(end 318.469772 -277.37816)
		(width 0.14478)
		(layer "In11.Cu")
		(net "M_F_CPU0_SB_DQ<6>")
	)
	(segment
		(start 276.16404 -287.859978)
		(end 278.084788 -287.859978)
		(width 0.14478)
		(layer "In11.Cu")
		(net "M_F_CPU0_SB_DQ<6>")
	)
	(segment
		(start 297.879262 -288.710116)
		(end 298.7294 -287.859978)
		(width 0.14478)
		(layer "In11.Cu")
		(net "M_F_CPU0_SB_DQ<6>")
	)
	(segment
		(start 268.167866 -288.565336)
		(end 268.167866 -288.246312)
		(width 0.14478)
		(layer "In11.Cu")
		(net "M_F_CPU0_SB_DQ<6>")
	)
	(segment
		(start 286.372554 -288.710116)
		(end 290.249102 -288.710116)
		(width 0.14478)
		(layer "In11.Cu")
		(net "M_F_CPU0_SB_DQ<6>")
	)
	(segment
		(start 267.616432 -288.246312)
		(end 267.616432 -288.565336)
		(width 0.14478)
		(layer "In11.Cu")
		(net "M_F_CPU0_SB_DQ<6>")
	)
	(segment
		(start 267.761212 -288.710116)
		(end 268.023086 -288.710116)
		(width 0.14478)
		(layer "In11.Cu")
		(net "M_F_CPU0_SB_DQ<6>")
	)
	(segment
		(start 278.934926 -288.710116)
		(end 283.057854 -288.710116)
		(width 0.14478)
		(layer "In11.Cu")
		(net "M_F_CPU0_SB_DQ<6>")
	)
	(segment
		(start 290.249102 -288.710116)
		(end 291.09924 -287.859978)
		(width 0.14478)
		(layer "In11.Cu")
		(net "M_F_CPU0_SB_DQ<6>")
	)
	(segment
		(start 265.54811 -288.285174)
		(end 265.973052 -288.710116)
		(width 0.14478)
		(layer "In11.Cu")
		(net "M_F_CPU0_SB_DQ<6>")
	)
	(segment
		(start 268.167866 -288.246312)
		(end 268.312646 -288.101532)
		(width 0.14478)
		(layer "In11.Cu")
		(net "M_F_CPU0_SB_DQ<6>")
	)
	(segment
		(start 267.209778 -288.101532)
		(end 267.471652 -288.101532)
		(width 0.14478)
		(layer "In11.Cu")
		(net "M_F_CPU0_SB_DQ<6>")
	)
	(segment
		(start 327.297542 -277.806658)
		(end 327.309226 -277.813516)
		(width 0.0889)
		(layer "In11.Cu")
		(net "M_F_CPU0_SB_DQ<6>")
	)
	(segment
		(start 267.471652 -288.101532)
		(end 267.616432 -288.246312)
		(width 0.14478)
		(layer "In11.Cu")
		(net "M_F_CPU0_SB_DQ<6>")
	)
	(segment
		(start 325.90105 -277.374604)
		(end 326.416416 -277.88997)
		(width 0.0889)
		(layer "In11.Cu")
		(net "M_F_CPU0_SB_DQ<6>")
	)
	(segment
		(start 278.084788 -287.859978)
		(end 278.934926 -288.710116)
		(width 0.14478)
		(layer "In11.Cu")
		(net "M_F_CPU0_SB_DQ<6>")
	)
	(segment
		(start 301.396146 -288.710116)
		(end 305.113182 -288.710116)
		(width 0.14478)
		(layer "In11.Cu")
		(net "M_F_CPU0_SB_DQ<6>")
	)
	(segment
		(start 326.416416 -277.88997)
		(end 326.651112 -277.88997)
		(width 0.0889)
		(layer "In11.Cu")
		(net "M_F_CPU0_SB_DQ<6>")
	)
	(segment
		(start 330.119736 -277.80869)
		(end 330.128118 -277.813516)
		(width 0.0889)
		(layer "In11.Cu")
		(net "M_F_CPU0_SB_DQ<6>")
	)
	(segment
		(start 305.96332 -287.859978)
		(end 307.987954 -287.859978)
		(width 0.14478)
		(layer "In11.Cu")
		(net "M_F_CPU0_SB_DQ<6>")
	)
	(segment
		(start 283.907992 -287.859978)
		(end 285.522416 -287.859978)
		(width 0.14478)
		(layer "In11.Cu")
		(net "M_F_CPU0_SB_DQ<6>")
	)
	(segment
		(start 293.875206 -288.710116)
		(end 297.879262 -288.710116)
		(width 0.14478)
		(layer "In11.Cu")
		(net "M_F_CPU0_SB_DQ<6>")
	)
	(segment
		(start 298.7294 -287.859978)
		(end 300.546008 -287.859978)
		(width 0.14478)
		(layer "In11.Cu")
		(net "M_F_CPU0_SB_DQ<6>")
	)
	(segment
		(start 267.064998 -288.246312)
		(end 267.209778 -288.101532)
		(width 0.14478)
		(layer "In11.Cu")
		(net "M_F_CPU0_SB_DQ<6>")
	)
	(segment
		(start 305.113182 -288.710116)
		(end 305.96332 -287.859978)
		(width 0.14478)
		(layer "In11.Cu")
		(net "M_F_CPU0_SB_DQ<6>")
	)
	(segment
		(start 323.89826 -277.374604)
		(end 325.90105 -277.374604)
		(width 0.0889)
		(layer "In11.Cu")
		(net "M_F_CPU0_SB_DQ<6>")
	)
	(segment
		(start 267.064998 -288.565336)
		(end 267.064998 -288.246312)
		(width 0.14478)
		(layer "In11.Cu")
		(net "M_F_CPU0_SB_DQ<6>")
	)
	(segment
		(start 265.973052 -288.710116)
		(end 266.920218 -288.710116)
		(width 0.14478)
		(layer "In11.Cu")
		(net "M_F_CPU0_SB_DQ<6>")
	)
	(segment
		(start 300.546008 -287.859978)
		(end 301.396146 -288.710116)
		(width 0.14478)
		(layer "In11.Cu")
		(net "M_F_CPU0_SB_DQ<6>")
	)
	(segment
		(start 266.920218 -288.710116)
		(end 267.064998 -288.565336)
		(width 0.14478)
		(layer "In11.Cu")
		(net "M_F_CPU0_SB_DQ<6>")
	)
	(segment
		(start 268.7193 -288.565336)
		(end 268.86408 -288.710116)
		(width 0.14478)
		(layer "In11.Cu")
		(net "M_F_CPU0_SB_DQ<6>")
	)
	(segment
		(start 285.522416 -287.859978)
		(end 286.372554 -288.710116)
		(width 0.14478)
		(layer "In11.Cu")
		(net "M_F_CPU0_SB_DQ<6>")
	)
	(segment
		(start 268.312646 -288.101532)
		(end 268.57452 -288.101532)
		(width 0.14478)
		(layer "In11.Cu")
		(net "M_F_CPU0_SB_DQ<6>")
	)
	(segment
		(start 327.874376 -277.81377)
		(end 327.890632 -277.804372)
		(width 0.0889)
		(layer "In11.Cu")
		(net "M_F_CPU0_SB_DQ<6>")
	)
	(segment
		(start 332.511146 -277.845266)
		(end 332.607158 -277.870666)
		(width 0.0889)
		(layer "In11.Cu")
		(net "M_F_CPU0_SB_DQ<6>")
	)
	(segment
		(start 323.894704 -277.37816)
		(end 323.89826 -277.374604)
		(width 0.0889)
		(layer "In11.Cu")
		(net "M_F_CPU0_SB_DQ<6>")
	)
	(segment
		(start 268.023086 -288.710116)
		(end 268.167866 -288.565336)
		(width 0.14478)
		(layer "In11.Cu")
		(net "M_F_CPU0_SB_DQ<6>")
	)
	(segment
		(start 283.057854 -288.710116)
		(end 283.907992 -287.859978)
		(width 0.14478)
		(layer "In11.Cu")
		(net "M_F_CPU0_SB_DQ<6>")
	)
	(segment
		(start 331.634084 -277.813516)
		(end 331.642466 -277.80869)
		(width 0.0889)
		(layer "In11.Cu")
		(net "M_F_CPU0_SB_DQ<6>")
	)
	(segment
		(start 327.862438 -277.820628)
		(end 327.874376 -277.81377)
		(width 0.0889)
		(layer "In11.Cu")
		(net "M_F_CPU0_SB_DQ<6>")
	)
	(segment
		(start 291.09924 -287.859978)
		(end 293.025068 -287.859978)
		(width 0.14478)
		(layer "In11.Cu")
		(net "M_F_CPU0_SB_DQ<6>")
	)
	(segment
		(start 332.607158 -277.870666)
		(end 332.761082 -278.136096)
		(width 0.0889)
		(layer "In11.Cu")
		(net "M_F_CPU0_SB_DQ<6>")
	)
	(segment
		(start 293.025068 -287.859978)
		(end 293.875206 -288.710116)
		(width 0.14478)
		(layer "In11.Cu")
		(net "M_F_CPU0_SB_DQ<6>")
	)
	(segment
		(start 268.7193 -288.246312)
		(end 268.7193 -288.565336)
		(width 0.14478)
		(layer "In11.Cu")
		(net "M_F_CPU0_SB_DQ<6>")
	)
	(arc
		(start 328.248264 -277.813516)
		(mid 328.53122 -277.889693)
		(end 328.814176 -277.813516)
		(width 0.0889)
		(layer "In11.Cu")
		(net "M_F_CPU0_SB_DQ<6>")
	)
	(arc
		(start 329.753976 -277.813516)
		(mid 329.936227 -277.763166)
		(end 330.119736 -277.80869)
		(width 0.0889)
		(layer "In11.Cu")
		(net "M_F_CPU0_SB_DQ<6>")
	)
	(arc
		(start 332.008226 -277.813516)
		(mid 332.255939 -277.888736)
		(end 332.511146 -277.845266)
		(width 0.0889)
		(layer "In11.Cu")
		(net "M_F_CPU0_SB_DQ<6>")
	)
	(arc
		(start 331.068172 -277.813516)
		(mid 331.351128 -277.889693)
		(end 331.634084 -277.813516)
		(width 0.0889)
		(layer "In11.Cu")
		(net "M_F_CPU0_SB_DQ<6>")
	)
	(arc
		(start 329.188064 -277.813516)
		(mid 329.47102 -277.889693)
		(end 329.753976 -277.813516)
		(width 0.0889)
		(layer "In11.Cu")
		(net "M_F_CPU0_SB_DQ<6>")
	)
	(arc
		(start 328.814176 -277.813516)
		(mid 329.00112 -277.763261)
		(end 329.188064 -277.813516)
		(width 0.0889)
		(layer "In11.Cu")
		(net "M_F_CPU0_SB_DQ<6>")
	)
	(arc
		(start 331.642466 -277.80869)
		(mid 331.825974 -277.763196)
		(end 332.008226 -277.813516)
		(width 0.0889)
		(layer "In11.Cu")
		(net "M_F_CPU0_SB_DQ<6>")
	)
	(arc
		(start 327.309226 -277.813516)
		(mid 327.584904 -277.889646)
		(end 327.862438 -277.820628)
		(width 0.0889)
		(layer "In11.Cu")
		(net "M_F_CPU0_SB_DQ<6>")
	)
	(arc
		(start 330.702412 -277.80869)
		(mid 330.88592 -277.763196)
		(end 331.068172 -277.813516)
		(width 0.0889)
		(layer "In11.Cu")
		(net "M_F_CPU0_SB_DQ<6>")
	)
	(arc
		(start 327.890632 -277.804372)
		(mid 328.070614 -277.763272)
		(end 328.248264 -277.813516)
		(width 0.0889)
		(layer "In11.Cu")
		(net "M_F_CPU0_SB_DQ<6>")
	)
	(arc
		(start 326.651112 -277.88997)
		(mid 326.798043 -277.870559)
		(end 326.93483 -277.813516)
		(width 0.0889)
		(layer "In11.Cu")
		(net "M_F_CPU0_SB_DQ<6>")
	)
	(arc
		(start 330.128118 -277.813516)
		(mid 330.411074 -277.889693)
		(end 330.69403 -277.813516)
		(width 0.0889)
		(layer "In11.Cu")
		(net "M_F_CPU0_SB_DQ<6>")
	)
	(arc
		(start 326.93483 -277.813516)
		(mid 327.115288 -277.763072)
		(end 327.297542 -277.806658)
		(width 0.0889)
		(layer "In11.Cu")
		(net "M_F_CPU0_SB_DQ<6>")
	)
	(segment
		(start 334.167988 -277.870158)
		(end 333.701136 -278.136096)
		(width 0.10668)
		(layer "F.Cu")
		(net "M_F_CPU0_SB_DQ<5>")
	)
	(segment
		(start 289.435794 -289.168332)
		(end 289.580574 -289.313112)
		(width 0.14478)
		(layer "In11.Cu")
		(net "M_F_CPU0_SB_DQ<5>")
	)
	(segment
		(start 333.85506 -278.401526)
		(end 333.701136 -278.136096)
		(width 0.0889)
		(layer "In11.Cu")
		(net "M_F_CPU0_SB_DQ<5>")
	)
	(segment
		(start 293.03726 -288.710116)
		(end 293.887398 -289.560254)
		(width 0.14478)
		(layer "In11.Cu")
		(net "M_F_CPU0_SB_DQ<5>")
	)
	(segment
		(start 274.72513 -289.415474)
		(end 274.86991 -289.560254)
		(width 0.14478)
		(layer "In11.Cu")
		(net "M_F_CPU0_SB_DQ<5>")
	)
	(segment
		(start 271.012666 -289.166554)
		(end 271.243298 -289.166554)
		(width 0.14478)
		(layer "In11.Cu")
		(net "M_F_CPU0_SB_DQ<5>")
	)
	(segment
		(start 330.69403 -278.458676)
		(end 330.702412 -278.463502)
		(width 0.0889)
		(layer "In11.Cu")
		(net "M_F_CPU0_SB_DQ<5>")
	)
	(segment
		(start 324.476364 -277.83282)
		(end 324.891654 -278.24811)
		(width 0.0889)
		(layer "In11.Cu")
		(net "M_F_CPU0_SB_DQ<5>")
	)
	(segment
		(start 270.849852 -289.780472)
		(end 270.849852 -289.329368)
		(width 0.14478)
		(layer "In11.Cu")
		(net "M_F_CPU0_SB_DQ<5>")
	)
	(segment
		(start 287.091882 -289.160712)
		(end 287.353756 -289.160712)
		(width 0.14478)
		(layer "In11.Cu")
		(net "M_F_CPU0_SB_DQ<5>")
	)
	(segment
		(start 279.88006 -289.175952)
		(end 280.02484 -289.320732)
		(width 0.14478)
		(layer "In11.Cu")
		(net "M_F_CPU0_SB_DQ<5>")
	)
	(segment
		(start 276.101048 -288.710116)
		(end 278.25446 -288.710116)
		(width 0.14478)
		(layer "In11.Cu")
		(net "M_F_CPU0_SB_DQ<5>")
	)
	(segment
		(start 280.16962 -289.560254)
		(end 281.749246 -289.560254)
		(width 0.14478)
		(layer "In11.Cu")
		(net "M_F_CPU0_SB_DQ<5>")
	)
	(segment
		(start 287.643316 -289.560254)
		(end 288.88436 -289.560254)
		(width 0.14478)
		(layer "In11.Cu")
		(net "M_F_CPU0_SB_DQ<5>")
	)
	(segment
		(start 307.781198 -288.710116)
		(end 318.658494 -277.83282)
		(width 0.14478)
		(layer "In11.Cu")
		(net "M_F_CPU0_SB_DQ<5>")
	)
	(segment
		(start 282.44546 -289.415474)
		(end 282.59024 -289.560254)
		(width 0.14478)
		(layer "In11.Cu")
		(net "M_F_CPU0_SB_DQ<5>")
	)
	(segment
		(start 274.58035 -289.168332)
		(end 274.72513 -289.313112)
		(width 0.14478)
		(layer "In11.Cu")
		(net "M_F_CPU0_SB_DQ<5>")
	)
	(segment
		(start 274.86991 -289.560254)
		(end 275.25091 -289.560254)
		(width 0.14478)
		(layer "In11.Cu")
		(net "M_F_CPU0_SB_DQ<5>")
	)
	(segment
		(start 275.25091 -289.560254)
		(end 276.101048 -288.710116)
		(width 0.14478)
		(layer "In11.Cu")
		(net "M_F_CPU0_SB_DQ<5>")
	)
	(segment
		(start 271.962372 -289.780472)
		(end 271.962372 -289.329368)
		(width 0.14478)
		(layer "In11.Cu")
		(net "M_F_CPU0_SB_DQ<5>")
	)
	(segment
		(start 286.802322 -289.560254)
		(end 286.947102 -289.415474)
		(width 0.14478)
		(layer "In11.Cu")
		(net "M_F_CPU0_SB_DQ<5>")
	)
	(segment
		(start 281.749246 -289.560254)
		(end 281.894026 -289.415474)
		(width 0.14478)
		(layer "In11.Cu")
		(net "M_F_CPU0_SB_DQ<5>")
	)
	(segment
		(start 283.746448 -288.710116)
		(end 285.58236 -288.710116)
		(width 0.14478)
		(layer "In11.Cu")
		(net "M_F_CPU0_SB_DQ<5>")
	)
	(segment
		(start 269.648178 -289.135058)
		(end 270.456406 -289.943286)
		(width 0.14478)
		(layer "In11.Cu")
		(net "M_F_CPU0_SB_DQ<5>")
	)
	(segment
		(start 297.67403 -289.560254)
		(end 298.524168 -288.710116)
		(width 0.14478)
		(layer "In11.Cu")
		(net "M_F_CPU0_SB_DQ<5>")
	)
	(segment
		(start 289.02914 -289.415474)
		(end 289.02914 -289.313112)
		(width 0.14478)
		(layer "In11.Cu")
		(net "M_F_CPU0_SB_DQ<5>")
	)
	(segment
		(start 274.72513 -289.313112)
		(end 274.72513 -289.415474)
		(width 0.14478)
		(layer "In11.Cu")
		(net "M_F_CPU0_SB_DQ<5>")
	)
	(segment
		(start 289.580574 -289.415474)
		(end 289.725354 -289.560254)
		(width 0.14478)
		(layer "In11.Cu")
		(net "M_F_CPU0_SB_DQ<5>")
	)
	(segment
		(start 270.849852 -289.329368)
		(end 271.012666 -289.166554)
		(width 0.14478)
		(layer "In11.Cu")
		(net "M_F_CPU0_SB_DQ<5>")
	)
	(segment
		(start 287.353756 -289.160712)
		(end 287.498536 -289.305492)
		(width 0.14478)
		(layer "In11.Cu")
		(net "M_F_CPU0_SB_DQ<5>")
	)
	(segment
		(start 333.832708 -278.484838)
		(end 333.85506 -278.401526)
		(width 0.0889)
		(layer "In11.Cu")
		(net "M_F_CPU0_SB_DQ<5>")
	)
	(segment
		(start 282.038806 -289.175952)
		(end 282.30068 -289.175952)
		(width 0.14478)
		(layer "In11.Cu")
		(net "M_F_CPU0_SB_DQ<5>")
	)
	(segment
		(start 286.432498 -289.560254)
		(end 286.802322 -289.560254)
		(width 0.14478)
		(layer "In11.Cu")
		(net "M_F_CPU0_SB_DQ<5>")
	)
	(segment
		(start 324.891654 -278.24811)
		(end 327.093072 -278.24811)
		(width 0.0889)
		(layer "In11.Cu")
		(net "M_F_CPU0_SB_DQ<5>")
	)
	(segment
		(start 272.125186 -289.166554)
		(end 272.355818 -289.166554)
		(width 0.14478)
		(layer "In11.Cu")
		(net "M_F_CPU0_SB_DQ<5>")
	)
	(segment
		(start 274.318476 -289.168332)
		(end 274.58035 -289.168332)
		(width 0.14478)
		(layer "In11.Cu")
		(net "M_F_CPU0_SB_DQ<5>")
	)
	(segment
		(start 282.44546 -289.320732)
		(end 282.44546 -289.415474)
		(width 0.14478)
		(layer "In11.Cu")
		(net "M_F_CPU0_SB_DQ<5>")
	)
	(segment
		(start 290.934648 -288.710116)
		(end 293.03726 -288.710116)
		(width 0.14478)
		(layer "In11.Cu")
		(net "M_F_CPU0_SB_DQ<5>")
	)
	(segment
		(start 287.498536 -289.415474)
		(end 287.643316 -289.560254)
		(width 0.14478)
		(layer "In11.Cu")
		(net "M_F_CPU0_SB_DQ<5>")
	)
	(segment
		(start 272.749518 -289.560254)
		(end 274.028916 -289.560254)
		(width 0.14478)
		(layer "In11.Cu")
		(net "M_F_CPU0_SB_DQ<5>")
	)
	(segment
		(start 293.887398 -289.560254)
		(end 297.67403 -289.560254)
		(width 0.14478)
		(layer "In11.Cu")
		(net "M_F_CPU0_SB_DQ<5>")
	)
	(segment
		(start 279.618186 -289.175952)
		(end 279.88006 -289.175952)
		(width 0.14478)
		(layer "In11.Cu")
		(net "M_F_CPU0_SB_DQ<5>")
	)
	(segment
		(start 289.580574 -289.313112)
		(end 289.580574 -289.415474)
		(width 0.14478)
		(layer "In11.Cu")
		(net "M_F_CPU0_SB_DQ<5>")
	)
	(segment
		(start 274.173696 -289.415474)
		(end 274.173696 -289.313112)
		(width 0.14478)
		(layer "In11.Cu")
		(net "M_F_CPU0_SB_DQ<5>")
	)
	(segment
		(start 286.947102 -289.305492)
		(end 287.091882 -289.160712)
		(width 0.14478)
		(layer "In11.Cu")
		(net "M_F_CPU0_SB_DQ<5>")
	)
	(segment
		(start 281.894026 -289.320732)
		(end 282.038806 -289.175952)
		(width 0.14478)
		(layer "In11.Cu")
		(net "M_F_CPU0_SB_DQ<5>")
	)
	(segment
		(start 271.406112 -289.329368)
		(end 271.406112 -289.780472)
		(width 0.14478)
		(layer "In11.Cu")
		(net "M_F_CPU0_SB_DQ<5>")
	)
	(segment
		(start 274.028916 -289.560254)
		(end 274.173696 -289.415474)
		(width 0.14478)
		(layer "In11.Cu")
		(net "M_F_CPU0_SB_DQ<5>")
	)
	(segment
		(start 281.894026 -289.415474)
		(end 281.894026 -289.320732)
		(width 0.14478)
		(layer "In11.Cu")
		(net "M_F_CPU0_SB_DQ<5>")
	)
	(segment
		(start 331.634084 -278.458676)
		(end 331.642466 -278.463502)
		(width 0.0889)
		(layer "In11.Cu")
		(net "M_F_CPU0_SB_DQ<5>")
	)
	(segment
		(start 298.524168 -288.710116)
		(end 300.73346 -288.710116)
		(width 0.14478)
		(layer "In11.Cu")
		(net "M_F_CPU0_SB_DQ<5>")
	)
	(segment
		(start 285.58236 -288.710116)
		(end 286.432498 -289.560254)
		(width 0.14478)
		(layer "In11.Cu")
		(net "M_F_CPU0_SB_DQ<5>")
	)
	(segment
		(start 330.119736 -278.463502)
		(end 330.128118 -278.458676)
		(width 0.0889)
		(layer "In11.Cu")
		(net "M_F_CPU0_SB_DQ<5>")
	)
	(segment
		(start 271.568926 -289.943286)
		(end 271.799558 -289.943286)
		(width 0.14478)
		(layer "In11.Cu")
		(net "M_F_CPU0_SB_DQ<5>")
	)
	(segment
		(start 270.456406 -289.943286)
		(end 270.687038 -289.943286)
		(width 0.14478)
		(layer "In11.Cu")
		(net "M_F_CPU0_SB_DQ<5>")
	)
	(segment
		(start 300.73346 -288.710116)
		(end 301.583598 -289.560254)
		(width 0.14478)
		(layer "In11.Cu")
		(net "M_F_CPU0_SB_DQ<5>")
	)
	(segment
		(start 289.17392 -289.168332)
		(end 289.435794 -289.168332)
		(width 0.14478)
		(layer "In11.Cu")
		(net "M_F_CPU0_SB_DQ<5>")
	)
	(segment
		(start 305.10861 -289.560254)
		(end 305.958748 -288.710116)
		(width 0.14478)
		(layer "In11.Cu")
		(net "M_F_CPU0_SB_DQ<5>")
	)
	(segment
		(start 301.583598 -289.560254)
		(end 305.10861 -289.560254)
		(width 0.14478)
		(layer "In11.Cu")
		(net "M_F_CPU0_SB_DQ<5>")
	)
	(segment
		(start 289.725354 -289.560254)
		(end 290.08451 -289.560254)
		(width 0.14478)
		(layer "In11.Cu")
		(net "M_F_CPU0_SB_DQ<5>")
	)
	(segment
		(start 287.498536 -289.305492)
		(end 287.498536 -289.415474)
		(width 0.14478)
		(layer "In11.Cu")
		(net "M_F_CPU0_SB_DQ<5>")
	)
	(segment
		(start 271.243298 -289.166554)
		(end 271.406112 -289.329368)
		(width 0.14478)
		(layer "In11.Cu")
		(net "M_F_CPU0_SB_DQ<5>")
	)
	(segment
		(start 279.473406 -289.415474)
		(end 279.473406 -289.320732)
		(width 0.14478)
		(layer "In11.Cu")
		(net "M_F_CPU0_SB_DQ<5>")
	)
	(segment
		(start 271.962372 -289.329368)
		(end 272.125186 -289.166554)
		(width 0.14478)
		(layer "In11.Cu")
		(net "M_F_CPU0_SB_DQ<5>")
	)
	(segment
		(start 305.958748 -288.710116)
		(end 307.781198 -288.710116)
		(width 0.14478)
		(layer "In11.Cu")
		(net "M_F_CPU0_SB_DQ<5>")
	)
	(segment
		(start 282.59024 -289.560254)
		(end 282.89631 -289.560254)
		(width 0.14478)
		(layer "In11.Cu")
		(net "M_F_CPU0_SB_DQ<5>")
	)
	(segment
		(start 318.658494 -277.83282)
		(end 323.97446 -277.83282)
		(width 0.14478)
		(layer "In11.Cu")
		(net "M_F_CPU0_SB_DQ<5>")
	)
	(segment
		(start 279.473406 -289.320732)
		(end 279.618186 -289.175952)
		(width 0.14478)
		(layer "In11.Cu")
		(net "M_F_CPU0_SB_DQ<5>")
	)
	(segment
		(start 280.02484 -289.320732)
		(end 280.02484 -289.415474)
		(width 0.14478)
		(layer "In11.Cu")
		(net "M_F_CPU0_SB_DQ<5>")
	)
	(segment
		(start 279.328626 -289.560254)
		(end 279.473406 -289.415474)
		(width 0.14478)
		(layer "In11.Cu")
		(net "M_F_CPU0_SB_DQ<5>")
	)
	(segment
		(start 282.89631 -289.560254)
		(end 283.746448 -288.710116)
		(width 0.14478)
		(layer "In11.Cu")
		(net "M_F_CPU0_SB_DQ<5>")
	)
	(segment
		(start 289.02914 -289.313112)
		(end 289.17392 -289.168332)
		(width 0.14478)
		(layer "In11.Cu")
		(net "M_F_CPU0_SB_DQ<5>")
	)
	(segment
		(start 274.173696 -289.313112)
		(end 274.318476 -289.168332)
		(width 0.14478)
		(layer "In11.Cu")
		(net "M_F_CPU0_SB_DQ<5>")
	)
	(segment
		(start 271.406112 -289.780472)
		(end 271.568926 -289.943286)
		(width 0.14478)
		(layer "In11.Cu")
		(net "M_F_CPU0_SB_DQ<5>")
	)
	(segment
		(start 270.687038 -289.943286)
		(end 270.849852 -289.780472)
		(width 0.14478)
		(layer "In11.Cu")
		(net "M_F_CPU0_SB_DQ<5>")
	)
	(segment
		(start 282.30068 -289.175952)
		(end 282.44546 -289.320732)
		(width 0.14478)
		(layer "In11.Cu")
		(net "M_F_CPU0_SB_DQ<5>")
	)
	(segment
		(start 280.02484 -289.415474)
		(end 280.16962 -289.560254)
		(width 0.14478)
		(layer "In11.Cu")
		(net "M_F_CPU0_SB_DQ<5>")
	)
	(segment
		(start 279.104598 -289.560254)
		(end 279.328626 -289.560254)
		(width 0.14478)
		(layer "In11.Cu")
		(net "M_F_CPU0_SB_DQ<5>")
	)
	(segment
		(start 278.25446 -288.710116)
		(end 279.104598 -289.560254)
		(width 0.14478)
		(layer "In11.Cu")
		(net "M_F_CPU0_SB_DQ<5>")
	)
	(segment
		(start 272.355818 -289.166554)
		(end 272.749518 -289.560254)
		(width 0.14478)
		(layer "In11.Cu")
		(net "M_F_CPU0_SB_DQ<5>")
	)
	(segment
		(start 271.799558 -289.943286)
		(end 271.962372 -289.780472)
		(width 0.14478)
		(layer "In11.Cu")
		(net "M_F_CPU0_SB_DQ<5>")
	)
	(segment
		(start 290.08451 -289.560254)
		(end 290.934648 -288.710116)
		(width 0.14478)
		(layer "In11.Cu")
		(net "M_F_CPU0_SB_DQ<5>")
	)
	(segment
		(start 323.97446 -277.83282)
		(end 324.476364 -277.83282)
		(width 0.0889)
		(layer "In11.Cu")
		(net "M_F_CPU0_SB_DQ<5>")
	)
	(segment
		(start 288.88436 -289.560254)
		(end 289.02914 -289.415474)
		(width 0.14478)
		(layer "In11.Cu")
		(net "M_F_CPU0_SB_DQ<5>")
	)
	(segment
		(start 286.947102 -289.415474)
		(end 286.947102 -289.305492)
		(width 0.14478)
		(layer "In11.Cu")
		(net "M_F_CPU0_SB_DQ<5>")
	)
	(arc
		(start 330.702412 -278.463502)
		(mid 330.88592 -278.508996)
		(end 331.068172 -278.458676)
		(width 0.0889)
		(layer "In11.Cu")
		(net "M_F_CPU0_SB_DQ<5>")
	)
	(arc
		(start 330.128118 -278.458676)
		(mid 330.411074 -278.382499)
		(end 330.69403 -278.458676)
		(width 0.0889)
		(layer "In11.Cu")
		(net "M_F_CPU0_SB_DQ<5>")
	)
	(arc
		(start 327.873868 -278.458676)
		(mid 328.061066 -278.509058)
		(end 328.248264 -278.458676)
		(width 0.0889)
		(layer "In11.Cu")
		(net "M_F_CPU0_SB_DQ<5>")
	)
	(arc
		(start 333.513938 -278.458676)
		(mid 333.670376 -278.507647)
		(end 333.832708 -278.484838)
		(width 0.0889)
		(layer "In11.Cu")
		(net "M_F_CPU0_SB_DQ<5>")
	)
	(arc
		(start 332.574138 -278.458676)
		(mid 332.761082 -278.508931)
		(end 332.948026 -278.458676)
		(width 0.0889)
		(layer "In11.Cu")
		(net "M_F_CPU0_SB_DQ<5>")
	)
	(arc
		(start 331.068172 -278.458676)
		(mid 331.351128 -278.382499)
		(end 331.634084 -278.458676)
		(width 0.0889)
		(layer "In11.Cu")
		(net "M_F_CPU0_SB_DQ<5>")
	)
	(arc
		(start 328.248264 -278.458676)
		(mid 328.53122 -278.382499)
		(end 328.814176 -278.458676)
		(width 0.0889)
		(layer "In11.Cu")
		(net "M_F_CPU0_SB_DQ<5>")
	)
	(arc
		(start 328.814176 -278.458676)
		(mid 329.00112 -278.508931)
		(end 329.188064 -278.458676)
		(width 0.0889)
		(layer "In11.Cu")
		(net "M_F_CPU0_SB_DQ<5>")
	)
	(arc
		(start 332.008226 -278.458676)
		(mid 332.291182 -278.382499)
		(end 332.574138 -278.458676)
		(width 0.0889)
		(layer "In11.Cu")
		(net "M_F_CPU0_SB_DQ<5>")
	)
	(arc
		(start 332.948026 -278.458676)
		(mid 333.230982 -278.382499)
		(end 333.513938 -278.458676)
		(width 0.0889)
		(layer "In11.Cu")
		(net "M_F_CPU0_SB_DQ<5>")
	)
	(arc
		(start 331.642466 -278.463502)
		(mid 331.825974 -278.508996)
		(end 332.008226 -278.458676)
		(width 0.0889)
		(layer "In11.Cu")
		(net "M_F_CPU0_SB_DQ<5>")
	)
	(arc
		(start 329.188064 -278.458676)
		(mid 329.47102 -278.382499)
		(end 329.753976 -278.458676)
		(width 0.0889)
		(layer "In11.Cu")
		(net "M_F_CPU0_SB_DQ<5>")
	)
	(arc
		(start 327.093072 -278.24811)
		(mid 327.497418 -278.301674)
		(end 327.873868 -278.458676)
		(width 0.0889)
		(layer "In11.Cu")
		(net "M_F_CPU0_SB_DQ<5>")
	)
	(arc
		(start 329.753976 -278.458676)
		(mid 329.936227 -278.509026)
		(end 330.119736 -278.463502)
		(width 0.0889)
		(layer "In11.Cu")
		(net "M_F_CPU0_SB_DQ<5>")
	)
	(segment
		(start 332.758034 -277.060152)
		(end 332.291182 -277.32609)
		(width 0.10668)
		(layer "F.Cu")
		(net "M_F_CPU0_SB_DQ<4>")
	)
	(segment
		(start 307.343048 -286.836612)
		(end 307.343048 -287.260538)
		(width 0.14478)
		(layer "In11.Cu")
		(net "M_F_CPU0_SB_DQ<4>")
	)
	(segment
		(start 291.135562 -287.23336)
		(end 291.29863 -287.396428)
		(width 0.14478)
		(layer "In11.Cu")
		(net "M_F_CPU0_SB_DQ<4>")
	)
	(segment
		(start 296.436542 -288.08934)
		(end 296.59961 -288.252408)
		(width 0.14478)
		(layer "In11.Cu")
		(net "M_F_CPU0_SB_DQ<4>")
	)
	(segment
		(start 271.964912 -288.252408)
		(end 272.19529 -288.252408)
		(width 0.14478)
		(layer "In11.Cu")
		(net "M_F_CPU0_SB_DQ<4>")
	)
	(segment
		(start 282.000198 -288.023046)
		(end 282.163266 -287.859978)
		(width 0.14478)
		(layer "In11.Cu")
		(net "M_F_CPU0_SB_DQ<4>")
	)
	(segment
		(start 331.52969 -277.653496)
		(end 331.538072 -277.64867)
		(width 0.0889)
		(layer "In11.Cu")
		(net "M_F_CPU0_SB_DQ<4>")
	)
	(segment
		(start 273.91106 -287.86963)
		(end 274.193762 -288.152332)
		(width 0.14478)
		(layer "In11.Cu")
		(net "M_F_CPU0_SB_DQ<4>")
	)
	(segment
		(start 281.443684 -288.08934)
		(end 281.606752 -288.252408)
		(width 0.14478)
		(layer "In11.Cu")
		(net "M_F_CPU0_SB_DQ<4>")
	)
	(segment
		(start 306.791614 -287.260538)
		(end 306.791614 -286.836612)
		(width 0.14478)
		(layer "In11.Cu")
		(net "M_F_CPU0_SB_DQ<4>")
	)
	(segment
		(start 281.290268 -287.86963)
		(end 281.443684 -288.023046)
		(width 0.14478)
		(layer "In11.Cu")
		(net "M_F_CPU0_SB_DQ<4>")
	)
	(segment
		(start 304.383948 -287.860232)
		(end 305.276758 -287.860232)
		(width 0.14478)
		(layer "In11.Cu")
		(net "M_F_CPU0_SB_DQ<4>")
	)
	(segment
		(start 288.984944 -288.08934)
		(end 289.148012 -288.252408)
		(width 0.14478)
		(layer "In11.Cu")
		(net "M_F_CPU0_SB_DQ<4>")
	)
	(segment
		(start 298.51985 -287.010094)
		(end 298.682918 -287.173162)
		(width 0.14478)
		(layer "In11.Cu")
		(net "M_F_CPU0_SB_DQ<4>")
	)
	(segment
		(start 284.268418 -287.019746)
		(end 285.9024 -287.019746)
		(width 0.14478)
		(layer "In11.Cu")
		(net "M_F_CPU0_SB_DQ<4>")
	)
	(segment
		(start 276.579584 -287.173162)
		(end 276.733 -287.019746)
		(width 0.14478)
		(layer "In11.Cu")
		(net "M_F_CPU0_SB_DQ<4>")
	)
	(segment
		(start 332.422754 -277.674832)
		(end 332.445106 -277.59152)
		(width 0.0889)
		(layer "In11.Cu")
		(net "M_F_CPU0_SB_DQ<4>")
	)
	(segment
		(start 270.942308 -287.292796)
		(end 270.942308 -287.69691)
		(width 0.14478)
		(layer "In11.Cu")
		(net "M_F_CPU0_SB_DQ<4>")
	)
	(segment
		(start 289.704526 -287.859978)
		(end 289.883088 -287.859978)
		(width 0.14478)
		(layer "In11.Cu")
		(net "M_F_CPU0_SB_DQ<4>")
	)
	(segment
		(start 318.281304 -276.9235)
		(end 323.897244 -276.9235)
		(width 0.14478)
		(layer "In11.Cu")
		(net "M_F_CPU0_SB_DQ<4>")
	)
	(segment
		(start 274.193762 -288.152332)
		(end 274.462494 -288.152332)
		(width 0.14478)
		(layer "In11.Cu")
		(net "M_F_CPU0_SB_DQ<4>")
	)
	(segment
		(start 303.99101 -288.25317)
		(end 304.383948 -287.860232)
		(width 0.14478)
		(layer "In11.Cu")
		(net "M_F_CPU0_SB_DQ<4>")
	)
	(segment
		(start 276.02307 -287.173162)
		(end 276.02307 -287.24098)
		(width 0.14478)
		(layer "In11.Cu")
		(net "M_F_CPU0_SB_DQ<4>")
	)
	(segment
		(start 276.579584 -287.24098)
		(end 276.579584 -287.173162)
		(width 0.14478)
		(layer "In11.Cu")
		(net "M_F_CPU0_SB_DQ<4>")
	)
	(segment
		(start 307.799486 -287.405318)
		(end 318.281304 -276.9235)
		(width 0.14478)
		(layer "In11.Cu")
		(net "M_F_CPU0_SB_DQ<4>")
	)
	(segment
		(start 305.731672 -287.405318)
		(end 306.646834 -287.405318)
		(width 0.14478)
		(layer "In11.Cu")
		(net "M_F_CPU0_SB_DQ<4>")
	)
	(segment
		(start 290.972494 -287.010094)
		(end 291.135562 -287.173162)
		(width 0.14478)
		(layer "In11.Cu")
		(net "M_F_CPU0_SB_DQ<4>")
	)
	(segment
		(start 283.721556 -287.404048)
		(end 283.951934 -287.404048)
		(width 0.14478)
		(layer "In11.Cu")
		(net "M_F_CPU0_SB_DQ<4>")
	)
	(segment
		(start 327.778872 -277.648416)
		(end 327.79081 -277.641558)
		(width 0.0889)
		(layer "In11.Cu")
		(net "M_F_CPU0_SB_DQ<4>")
	)
	(segment
		(start 298.845986 -287.396428)
		(end 299.076364 -287.396428)
		(width 0.14478)
		(layer "In11.Cu")
		(net "M_F_CPU0_SB_DQ<4>")
	)
	(segment
		(start 271.801844 -288.023046)
		(end 271.801844 -288.08934)
		(width 0.14478)
		(layer "In11.Cu")
		(net "M_F_CPU0_SB_DQ<4>")
	)
	(segment
		(start 307.487828 -287.405318)
		(end 307.799486 -287.405318)
		(width 0.14478)
		(layer "In11.Cu")
		(net "M_F_CPU0_SB_DQ<4>")
	)
	(segment
		(start 293.517574 -287.019746)
		(end 294.367458 -287.86963)
		(width 0.14478)
		(layer "In11.Cu")
		(net "M_F_CPU0_SB_DQ<4>")
	)
	(segment
		(start 332.445106 -277.59152)
		(end 332.291182 -277.32609)
		(width 0.0889)
		(layer "In11.Cu")
		(net "M_F_CPU0_SB_DQ<4>")
	)
	(segment
		(start 305.276758 -287.860232)
		(end 305.731672 -287.405318)
		(width 0.14478)
		(layer "In11.Cu")
		(net "M_F_CPU0_SB_DQ<4>")
	)
	(segment
		(start 296.993056 -288.08934)
		(end 296.993056 -288.023046)
		(width 0.14478)
		(layer "In11.Cu")
		(net "M_F_CPU0_SB_DQ<4>")
	)
	(segment
		(start 283.558488 -287.24098)
		(end 283.721556 -287.404048)
		(width 0.14478)
		(layer "In11.Cu")
		(net "M_F_CPU0_SB_DQ<4>")
	)
	(segment
		(start 302.295052 -288.25317)
		(end 303.99101 -288.25317)
		(width 0.14478)
		(layer "In11.Cu")
		(net "M_F_CPU0_SB_DQ<4>")
	)
	(segment
		(start 291.29863 -287.396428)
		(end 291.529008 -287.396428)
		(width 0.14478)
		(layer "In11.Cu")
		(net "M_F_CPU0_SB_DQ<4>")
	)
	(segment
		(start 289.541458 -288.023046)
		(end 289.704526 -287.859978)
		(width 0.14478)
		(layer "In11.Cu")
		(net "M_F_CPU0_SB_DQ<4>")
	)
	(segment
		(start 272.511774 -287.86963)
		(end 273.91106 -287.86963)
		(width 0.14478)
		(layer "In11.Cu")
		(net "M_F_CPU0_SB_DQ<4>")
	)
	(segment
		(start 270.385794 -287.69691)
		(end 270.385794 -287.292796)
		(width 0.14478)
		(layer "In11.Cu")
		(net "M_F_CPU0_SB_DQ<4>")
	)
	(segment
		(start 275.604732 -287.010094)
		(end 275.860002 -287.010094)
		(width 0.14478)
		(layer "In11.Cu")
		(net "M_F_CPU0_SB_DQ<4>")
	)
	(segment
		(start 283.39542 -287.010094)
		(end 283.558488 -287.173162)
		(width 0.14478)
		(layer "In11.Cu")
		(net "M_F_CPU0_SB_DQ<4>")
	)
	(segment
		(start 298.682918 -287.23336)
		(end 298.845986 -287.396428)
		(width 0.14478)
		(layer "In11.Cu")
		(net "M_F_CPU0_SB_DQ<4>")
	)
	(segment
		(start 307.198268 -286.691832)
		(end 307.343048 -286.836612)
		(width 0.14478)
		(layer "In11.Cu")
		(net "M_F_CPU0_SB_DQ<4>")
	)
	(segment
		(start 281.606752 -288.252408)
		(end 281.83713 -288.252408)
		(width 0.14478)
		(layer "In11.Cu")
		(net "M_F_CPU0_SB_DQ<4>")
	)
	(segment
		(start 284.115002 -287.24098)
		(end 284.115002 -287.173162)
		(width 0.14478)
		(layer "In11.Cu")
		(net "M_F_CPU0_SB_DQ<4>")
	)
	(segment
		(start 291.529008 -287.396428)
		(end 291.692076 -287.23336)
		(width 0.14478)
		(layer "In11.Cu")
		(net "M_F_CPU0_SB_DQ<4>")
	)
	(segment
		(start 327.765156 -277.65629)
		(end 327.778872 -277.648416)
		(width 0.0889)
		(layer "In11.Cu")
		(net "M_F_CPU0_SB_DQ<4>")
	)
	(segment
		(start 275.860002 -287.010094)
		(end 276.02307 -287.173162)
		(width 0.14478)
		(layer "In11.Cu")
		(net "M_F_CPU0_SB_DQ<4>")
	)
	(segment
		(start 291.692076 -287.173162)
		(end 291.845492 -287.019746)
		(width 0.14478)
		(layer "In11.Cu")
		(net "M_F_CPU0_SB_DQ<4>")
	)
	(segment
		(start 270.222726 -287.859978)
		(end 270.385794 -287.69691)
		(width 0.14478)
		(layer "In11.Cu")
		(net "M_F_CPU0_SB_DQ<4>")
	)
	(segment
		(start 283.951934 -287.404048)
		(end 284.115002 -287.24098)
		(width 0.14478)
		(layer "In11.Cu")
		(net "M_F_CPU0_SB_DQ<4>")
	)
	(segment
		(start 299.239432 -287.23336)
		(end 299.239432 -287.173162)
		(width 0.14478)
		(layer "In11.Cu")
		(net "M_F_CPU0_SB_DQ<4>")
	)
	(segment
		(start 282.323286 -287.859978)
		(end 283.17317 -287.010094)
		(width 0.14478)
		(layer "In11.Cu")
		(net "M_F_CPU0_SB_DQ<4>")
	)
	(segment
		(start 301.061628 -287.019746)
		(end 302.295052 -288.25317)
		(width 0.14478)
		(layer "In11.Cu")
		(net "M_F_CPU0_SB_DQ<4>")
	)
	(segment
		(start 281.83713 -288.252408)
		(end 282.000198 -288.08934)
		(width 0.14478)
		(layer "In11.Cu")
		(net "M_F_CPU0_SB_DQ<4>")
	)
	(segment
		(start 291.845492 -287.019746)
		(end 293.517574 -287.019746)
		(width 0.14478)
		(layer "In11.Cu")
		(net "M_F_CPU0_SB_DQ<4>")
	)
	(segment
		(start 270.942308 -287.69691)
		(end 271.105376 -287.859978)
		(width 0.14478)
		(layer "In11.Cu")
		(net "M_F_CPU0_SB_DQ<4>")
	)
	(segment
		(start 281.443684 -288.023046)
		(end 281.443684 -288.08934)
		(width 0.14478)
		(layer "In11.Cu")
		(net "M_F_CPU0_SB_DQ<4>")
	)
	(segment
		(start 307.343048 -287.260538)
		(end 307.487828 -287.405318)
		(width 0.14478)
		(layer "In11.Cu")
		(net "M_F_CPU0_SB_DQ<4>")
	)
	(segment
		(start 296.436542 -288.023046)
		(end 296.436542 -288.08934)
		(width 0.14478)
		(layer "In11.Cu")
		(net "M_F_CPU0_SB_DQ<4>")
	)
	(segment
		(start 276.02307 -287.24098)
		(end 276.186138 -287.404048)
		(width 0.14478)
		(layer "In11.Cu")
		(net "M_F_CPU0_SB_DQ<4>")
	)
	(segment
		(start 274.462494 -288.152332)
		(end 275.604732 -287.010094)
		(width 0.14478)
		(layer "In11.Cu")
		(net "M_F_CPU0_SB_DQ<4>")
	)
	(segment
		(start 269.648178 -287.435036)
		(end 270.07312 -287.859978)
		(width 0.14478)
		(layer "In11.Cu")
		(net "M_F_CPU0_SB_DQ<4>")
	)
	(segment
		(start 271.105376 -287.859978)
		(end 271.638776 -287.859978)
		(width 0.14478)
		(layer "In11.Cu")
		(net "M_F_CPU0_SB_DQ<4>")
	)
	(segment
		(start 306.791614 -286.836612)
		(end 306.936394 -286.691832)
		(width 0.14478)
		(layer "In11.Cu")
		(net "M_F_CPU0_SB_DQ<4>")
	)
	(segment
		(start 306.646834 -287.405318)
		(end 306.791614 -287.260538)
		(width 0.14478)
		(layer "In11.Cu")
		(net "M_F_CPU0_SB_DQ<4>")
	)
	(segment
		(start 272.358358 -288.023046)
		(end 272.511774 -287.86963)
		(width 0.14478)
		(layer "In11.Cu")
		(net "M_F_CPU0_SB_DQ<4>")
	)
	(segment
		(start 296.283126 -287.86963)
		(end 296.436542 -288.023046)
		(width 0.14478)
		(layer "In11.Cu")
		(net "M_F_CPU0_SB_DQ<4>")
	)
	(segment
		(start 272.358358 -288.08934)
		(end 272.358358 -288.023046)
		(width 0.14478)
		(layer "In11.Cu")
		(net "M_F_CPU0_SB_DQ<4>")
	)
	(segment
		(start 328.709782 -277.653496)
		(end 328.718164 -277.64867)
		(width 0.0889)
		(layer "In11.Cu")
		(net "M_F_CPU0_SB_DQ<4>")
	)
	(segment
		(start 289.883088 -287.859978)
		(end 290.732972 -287.010094)
		(width 0.14478)
		(layer "In11.Cu")
		(net "M_F_CPU0_SB_DQ<4>")
	)
	(segment
		(start 282.000198 -288.08934)
		(end 282.000198 -288.023046)
		(width 0.14478)
		(layer "In11.Cu")
		(net "M_F_CPU0_SB_DQ<4>")
	)
	(segment
		(start 278.420576 -287.019746)
		(end 279.27046 -287.86963)
		(width 0.14478)
		(layer "In11.Cu")
		(net "M_F_CPU0_SB_DQ<4>")
	)
	(segment
		(start 323.897244 -276.9235)
		(end 324.354444 -276.9235)
		(width 0.0889)
		(layer "In11.Cu")
		(net "M_F_CPU0_SB_DQ<4>")
	)
	(segment
		(start 299.239432 -287.173162)
		(end 299.392848 -287.019746)
		(width 0.14478)
		(layer "In11.Cu")
		(net "M_F_CPU0_SB_DQ<4>")
	)
	(segment
		(start 294.367458 -287.86963)
		(end 296.283126 -287.86963)
		(width 0.14478)
		(layer "In11.Cu")
		(net "M_F_CPU0_SB_DQ<4>")
	)
	(segment
		(start 291.692076 -287.23336)
		(end 291.692076 -287.173162)
		(width 0.14478)
		(layer "In11.Cu")
		(net "M_F_CPU0_SB_DQ<4>")
	)
	(segment
		(start 329.284076 -277.64867)
		(end 329.292458 -277.653496)
		(width 0.0889)
		(layer "In11.Cu")
		(net "M_F_CPU0_SB_DQ<4>")
	)
	(segment
		(start 296.829988 -288.252408)
		(end 296.993056 -288.08934)
		(width 0.14478)
		(layer "In11.Cu")
		(net "M_F_CPU0_SB_DQ<4>")
	)
	(segment
		(start 324.510654 -277.07971)
		(end 325.87565 -277.07971)
		(width 0.0889)
		(layer "In11.Cu")
		(net "M_F_CPU0_SB_DQ<4>")
	)
	(segment
		(start 296.59961 -288.252408)
		(end 296.829988 -288.252408)
		(width 0.14478)
		(layer "In11.Cu")
		(net "M_F_CPU0_SB_DQ<4>")
	)
	(segment
		(start 270.385794 -287.292796)
		(end 270.548862 -287.129728)
		(width 0.14478)
		(layer "In11.Cu")
		(net "M_F_CPU0_SB_DQ<4>")
	)
	(segment
		(start 296.993056 -288.023046)
		(end 297.156124 -287.859978)
		(width 0.14478)
		(layer "In11.Cu")
		(net "M_F_CPU0_SB_DQ<4>")
	)
	(segment
		(start 298.682918 -287.173162)
		(end 298.682918 -287.23336)
		(width 0.14478)
		(layer "In11.Cu")
		(net "M_F_CPU0_SB_DQ<4>")
	)
	(segment
		(start 326.49541 -277.69947)
		(end 326.651112 -277.69947)
		(width 0.0889)
		(layer "In11.Cu")
		(net "M_F_CPU0_SB_DQ<4>")
	)
	(segment
		(start 291.135562 -287.173162)
		(end 291.135562 -287.23336)
		(width 0.14478)
		(layer "In11.Cu")
		(net "M_F_CPU0_SB_DQ<4>")
	)
	(segment
		(start 288.831528 -287.86963)
		(end 288.984944 -288.023046)
		(width 0.14478)
		(layer "In11.Cu")
		(net "M_F_CPU0_SB_DQ<4>")
	)
	(segment
		(start 299.392848 -287.019746)
		(end 301.061628 -287.019746)
		(width 0.14478)
		(layer "In11.Cu")
		(net "M_F_CPU0_SB_DQ<4>")
	)
	(segment
		(start 297.389042 -287.859978)
		(end 298.238926 -287.010094)
		(width 0.14478)
		(layer "In11.Cu")
		(net "M_F_CPU0_SB_DQ<4>")
	)
	(segment
		(start 298.238926 -287.010094)
		(end 298.51985 -287.010094)
		(width 0.14478)
		(layer "In11.Cu")
		(net "M_F_CPU0_SB_DQ<4>")
	)
	(segment
		(start 299.076364 -287.396428)
		(end 299.239432 -287.23336)
		(width 0.14478)
		(layer "In11.Cu")
		(net "M_F_CPU0_SB_DQ<4>")
	)
	(segment
		(start 282.163266 -287.859978)
		(end 282.323286 -287.859978)
		(width 0.14478)
		(layer "In11.Cu")
		(net "M_F_CPU0_SB_DQ<4>")
	)
	(segment
		(start 283.558488 -287.173162)
		(end 283.558488 -287.24098)
		(width 0.14478)
		(layer "In11.Cu")
		(net "M_F_CPU0_SB_DQ<4>")
	)
	(segment
		(start 327.387204 -277.638002)
		(end 327.405238 -277.64867)
		(width 0.0889)
		(layer "In11.Cu")
		(net "M_F_CPU0_SB_DQ<4>")
	)
	(segment
		(start 289.37839 -288.252408)
		(end 289.541458 -288.08934)
		(width 0.14478)
		(layer "In11.Cu")
		(net "M_F_CPU0_SB_DQ<4>")
	)
	(segment
		(start 276.733 -287.019746)
		(end 278.420576 -287.019746)
		(width 0.14478)
		(layer "In11.Cu")
		(net "M_F_CPU0_SB_DQ<4>")
	)
	(segment
		(start 289.541458 -288.08934)
		(end 289.541458 -288.023046)
		(width 0.14478)
		(layer "In11.Cu")
		(net "M_F_CPU0_SB_DQ<4>")
	)
	(segment
		(start 271.638776 -287.859978)
		(end 271.801844 -288.023046)
		(width 0.14478)
		(layer "In11.Cu")
		(net "M_F_CPU0_SB_DQ<4>")
	)
	(segment
		(start 283.17317 -287.010094)
		(end 283.39542 -287.010094)
		(width 0.14478)
		(layer "In11.Cu")
		(net "M_F_CPU0_SB_DQ<4>")
	)
	(segment
		(start 271.801844 -288.08934)
		(end 271.964912 -288.252408)
		(width 0.14478)
		(layer "In11.Cu")
		(net "M_F_CPU0_SB_DQ<4>")
	)
	(segment
		(start 290.732972 -287.010094)
		(end 290.972494 -287.010094)
		(width 0.14478)
		(layer "In11.Cu")
		(net "M_F_CPU0_SB_DQ<4>")
	)
	(segment
		(start 297.156124 -287.859978)
		(end 297.389042 -287.859978)
		(width 0.14478)
		(layer "In11.Cu")
		(net "M_F_CPU0_SB_DQ<4>")
	)
	(segment
		(start 276.186138 -287.404048)
		(end 276.416516 -287.404048)
		(width 0.14478)
		(layer "In11.Cu")
		(net "M_F_CPU0_SB_DQ<4>")
	)
	(segment
		(start 270.07312 -287.859978)
		(end 270.222726 -287.859978)
		(width 0.14478)
		(layer "In11.Cu")
		(net "M_F_CPU0_SB_DQ<4>")
	)
	(segment
		(start 306.936394 -286.691832)
		(end 307.198268 -286.691832)
		(width 0.14478)
		(layer "In11.Cu")
		(net "M_F_CPU0_SB_DQ<4>")
	)
	(segment
		(start 325.87565 -277.07971)
		(end 326.49541 -277.69947)
		(width 0.0889)
		(layer "In11.Cu")
		(net "M_F_CPU0_SB_DQ<4>")
	)
	(segment
		(start 285.9024 -287.019746)
		(end 286.752284 -287.86963)
		(width 0.14478)
		(layer "In11.Cu")
		(net "M_F_CPU0_SB_DQ<4>")
	)
	(segment
		(start 286.752284 -287.86963)
		(end 288.831528 -287.86963)
		(width 0.14478)
		(layer "In11.Cu")
		(net "M_F_CPU0_SB_DQ<4>")
	)
	(segment
		(start 279.27046 -287.86963)
		(end 281.290268 -287.86963)
		(width 0.14478)
		(layer "In11.Cu")
		(net "M_F_CPU0_SB_DQ<4>")
	)
	(segment
		(start 289.148012 -288.252408)
		(end 289.37839 -288.252408)
		(width 0.14478)
		(layer "In11.Cu")
		(net "M_F_CPU0_SB_DQ<4>")
	)
	(segment
		(start 270.548862 -287.129728)
		(end 270.77924 -287.129728)
		(width 0.14478)
		(layer "In11.Cu")
		(net "M_F_CPU0_SB_DQ<4>")
	)
	(segment
		(start 324.354444 -276.9235)
		(end 324.510654 -277.07971)
		(width 0.0889)
		(layer "In11.Cu")
		(net "M_F_CPU0_SB_DQ<4>")
	)
	(segment
		(start 270.77924 -287.129728)
		(end 270.942308 -287.292796)
		(width 0.14478)
		(layer "In11.Cu")
		(net "M_F_CPU0_SB_DQ<4>")
	)
	(segment
		(start 272.19529 -288.252408)
		(end 272.358358 -288.08934)
		(width 0.14478)
		(layer "In11.Cu")
		(net "M_F_CPU0_SB_DQ<4>")
	)
	(segment
		(start 288.984944 -288.023046)
		(end 288.984944 -288.08934)
		(width 0.14478)
		(layer "In11.Cu")
		(net "M_F_CPU0_SB_DQ<4>")
	)
	(segment
		(start 276.416516 -287.404048)
		(end 276.579584 -287.24098)
		(width 0.14478)
		(layer "In11.Cu")
		(net "M_F_CPU0_SB_DQ<4>")
	)
	(segment
		(start 284.115002 -287.173162)
		(end 284.268418 -287.019746)
		(width 0.14478)
		(layer "In11.Cu")
		(net "M_F_CPU0_SB_DQ<4>")
	)
	(arc
		(start 326.651112 -277.69947)
		(mid 326.748201 -277.68648)
		(end 326.838564 -277.64867)
		(width 0.0889)
		(layer "In11.Cu")
		(net "M_F_CPU0_SB_DQ<4>")
	)
	(arc
		(start 327.405238 -277.64867)
		(mid 327.584225 -277.69884)
		(end 327.765156 -277.65629)
		(width 0.0889)
		(layer "In11.Cu")
		(net "M_F_CPU0_SB_DQ<4>")
	)
	(arc
		(start 329.658218 -277.64867)
		(mid 329.941174 -277.572493)
		(end 330.22413 -277.64867)
		(width 0.0889)
		(layer "In11.Cu")
		(net "M_F_CPU0_SB_DQ<4>")
	)
	(arc
		(start 331.538072 -277.64867)
		(mid 331.821028 -277.572493)
		(end 332.103984 -277.64867)
		(width 0.0889)
		(layer "In11.Cu")
		(net "M_F_CPU0_SB_DQ<4>")
	)
	(arc
		(start 327.79081 -277.641558)
		(mid 328.068344 -277.572577)
		(end 328.344022 -277.64867)
		(width 0.0889)
		(layer "In11.Cu")
		(net "M_F_CPU0_SB_DQ<4>")
	)
	(arc
		(start 329.292458 -277.653496)
		(mid 329.475966 -277.69899)
		(end 329.658218 -277.64867)
		(width 0.0889)
		(layer "In11.Cu")
		(net "M_F_CPU0_SB_DQ<4>")
	)
	(arc
		(start 328.718164 -277.64867)
		(mid 329.00112 -277.572493)
		(end 329.284076 -277.64867)
		(width 0.0889)
		(layer "In11.Cu")
		(net "M_F_CPU0_SB_DQ<4>")
	)
	(arc
		(start 328.344022 -277.64867)
		(mid 328.526273 -277.69902)
		(end 328.709782 -277.653496)
		(width 0.0889)
		(layer "In11.Cu")
		(net "M_F_CPU0_SB_DQ<4>")
	)
	(arc
		(start 331.16393 -277.64867)
		(mid 331.346181 -277.69902)
		(end 331.52969 -277.653496)
		(width 0.0889)
		(layer "In11.Cu")
		(net "M_F_CPU0_SB_DQ<4>")
	)
	(arc
		(start 330.22413 -277.64867)
		(mid 330.411074 -277.698925)
		(end 330.598018 -277.64867)
		(width 0.0889)
		(layer "In11.Cu")
		(net "M_F_CPU0_SB_DQ<4>")
	)
	(arc
		(start 326.838564 -277.64867)
		(mid 327.111508 -277.57209)
		(end 327.387204 -277.638002)
		(width 0.0889)
		(layer "In11.Cu")
		(net "M_F_CPU0_SB_DQ<4>")
	)
	(arc
		(start 330.598018 -277.64867)
		(mid 330.880974 -277.572493)
		(end 331.16393 -277.64867)
		(width 0.0889)
		(layer "In11.Cu")
		(net "M_F_CPU0_SB_DQ<4>")
	)
	(arc
		(start 332.103984 -277.64867)
		(mid 332.260422 -277.697641)
		(end 332.422754 -277.674832)
		(width 0.0889)
		(layer "In11.Cu")
		(net "M_F_CPU0_SB_DQ<4>")
	)
	(segment
		(start 334.637888 -275.44014)
		(end 334.171036 -275.706078)
		(width 0.10668)
		(layer "F.Cu")
		(net "M_F_CPU0_SB_DQ<3>")
	)
	(segment
		(start 283.158438 -283.600398)
		(end 286.043624 -283.600398)
		(width 0.14478)
		(layer "In11.Cu")
		(net "M_F_CPU0_SB_DQ<3>")
	)
	(segment
		(start 293.54907 -283.600398)
		(end 294.398954 -284.450282)
		(width 0.14478)
		(layer "In11.Cu")
		(net "M_F_CPU0_SB_DQ<3>")
	)
	(segment
		(start 265.54811 -284.034992)
		(end 265.9634 -284.450282)
		(width 0.14478)
		(layer "In11.Cu")
		(net "M_F_CPU0_SB_DQ<3>")
	)
	(segment
		(start 294.398954 -284.450282)
		(end 297.339766 -284.450282)
		(width 0.14478)
		(layer "In11.Cu")
		(net "M_F_CPU0_SB_DQ<3>")
	)
	(segment
		(start 301.549816 -284.06471)
		(end 304.57902 -284.06471)
		(width 0.14478)
		(layer "In11.Cu")
		(net "M_F_CPU0_SB_DQ<3>")
	)
	(segment
		(start 279.324054 -284.450282)
		(end 282.308554 -284.450282)
		(width 0.14478)
		(layer "In11.Cu")
		(net "M_F_CPU0_SB_DQ<3>")
	)
	(segment
		(start 275.556472 -283.600398)
		(end 278.47417 -283.600398)
		(width 0.14478)
		(layer "In11.Cu")
		(net "M_F_CPU0_SB_DQ<3>")
	)
	(segment
		(start 333.044038 -275.383498)
		(end 333.05242 -275.378672)
		(width 0.0889)
		(layer "In11.Cu")
		(net "M_F_CPU0_SB_DQ<3>")
	)
	(segment
		(start 267.166852 -283.963872)
		(end 267.166852 -284.305502)
		(width 0.14478)
		(layer "In11.Cu")
		(net "M_F_CPU0_SB_DQ<3>")
	)
	(segment
		(start 316.342776 -274.58416)
		(end 324.412864 -274.58416)
		(width 0.14478)
		(layer "In11.Cu")
		(net "M_F_CPU0_SB_DQ<3>")
	)
	(segment
		(start 332.469744 -275.378672)
		(end 332.478126 -275.383498)
		(width 0.0889)
		(layer "In11.Cu")
		(net "M_F_CPU0_SB_DQ<3>")
	)
	(segment
		(start 290.691824 -283.600398)
		(end 293.54907 -283.600398)
		(width 0.14478)
		(layer "In11.Cu")
		(net "M_F_CPU0_SB_DQ<3>")
	)
	(segment
		(start 307.677566 -283.24937)
		(end 316.342776 -274.58416)
		(width 0.14478)
		(layer "In11.Cu")
		(net "M_F_CPU0_SB_DQ<3>")
	)
	(segment
		(start 298.18965 -283.600398)
		(end 301.085504 -283.600398)
		(width 0.14478)
		(layer "In11.Cu")
		(net "M_F_CPU0_SB_DQ<3>")
	)
	(segment
		(start 278.47417 -283.600398)
		(end 279.324054 -284.450282)
		(width 0.14478)
		(layer "In11.Cu")
		(net "M_F_CPU0_SB_DQ<3>")
	)
	(segment
		(start 286.893508 -284.450282)
		(end 289.84194 -284.450282)
		(width 0.14478)
		(layer "In11.Cu")
		(net "M_F_CPU0_SB_DQ<3>")
	)
	(segment
		(start 331.52969 -275.378672)
		(end 331.538072 -275.383498)
		(width 0.0889)
		(layer "In11.Cu")
		(net "M_F_CPU0_SB_DQ<3>")
	)
	(segment
		(start 328.333608 -275.389594)
		(end 328.344022 -275.383498)
		(width 0.0889)
		(layer "In11.Cu")
		(net "M_F_CPU0_SB_DQ<3>")
	)
	(segment
		(start 267.022072 -283.819092)
		(end 267.166852 -283.963872)
		(width 0.14478)
		(layer "In11.Cu")
		(net "M_F_CPU0_SB_DQ<3>")
	)
	(segment
		(start 289.84194 -284.450282)
		(end 290.691824 -283.600398)
		(width 0.14478)
		(layer "In11.Cu")
		(net "M_F_CPU0_SB_DQ<3>")
	)
	(segment
		(start 325.239126 -274.23491)
		(end 326.305926 -275.30171)
		(width 0.0889)
		(layer "In11.Cu")
		(net "M_F_CPU0_SB_DQ<3>")
	)
	(segment
		(start 326.305926 -275.30171)
		(end 327.475088 -275.30171)
		(width 0.0889)
		(layer "In11.Cu")
		(net "M_F_CPU0_SB_DQ<3>")
	)
	(segment
		(start 266.615418 -284.305502)
		(end 266.615418 -283.963872)
		(width 0.14478)
		(layer "In11.Cu")
		(net "M_F_CPU0_SB_DQ<3>")
	)
	(segment
		(start 274.706588 -284.450282)
		(end 275.556472 -283.600398)
		(width 0.14478)
		(layer "In11.Cu")
		(net "M_F_CPU0_SB_DQ<3>")
	)
	(segment
		(start 266.615418 -283.963872)
		(end 266.760198 -283.819092)
		(width 0.14478)
		(layer "In11.Cu")
		(net "M_F_CPU0_SB_DQ<3>")
	)
	(segment
		(start 265.9634 -284.450282)
		(end 266.470638 -284.450282)
		(width 0.14478)
		(layer "In11.Cu")
		(net "M_F_CPU0_SB_DQ<3>")
	)
	(segment
		(start 324.412864 -274.58416)
		(end 324.762114 -274.23491)
		(width 0.0889)
		(layer "In11.Cu")
		(net "M_F_CPU0_SB_DQ<3>")
	)
	(segment
		(start 304.57902 -284.06471)
		(end 306.54752 -283.24937)
		(width 0.14478)
		(layer "In11.Cu")
		(net "M_F_CPU0_SB_DQ<3>")
	)
	(segment
		(start 329.284076 -275.383498)
		(end 329.292458 -275.378672)
		(width 0.0889)
		(layer "In11.Cu")
		(net "M_F_CPU0_SB_DQ<3>")
	)
	(segment
		(start 301.085504 -283.600398)
		(end 301.549816 -284.06471)
		(width 0.14478)
		(layer "In11.Cu")
		(net "M_F_CPU0_SB_DQ<3>")
	)
	(segment
		(start 306.54752 -283.24937)
		(end 307.677566 -283.24937)
		(width 0.14478)
		(layer "In11.Cu")
		(net "M_F_CPU0_SB_DQ<3>")
	)
	(segment
		(start 324.762114 -274.23491)
		(end 325.239126 -274.23491)
		(width 0.0889)
		(layer "In11.Cu")
		(net "M_F_CPU0_SB_DQ<3>")
	)
	(segment
		(start 328.709782 -275.378672)
		(end 328.718164 -275.383498)
		(width 0.0889)
		(layer "In11.Cu")
		(net "M_F_CPU0_SB_DQ<3>")
	)
	(segment
		(start 333.9211 -275.415248)
		(end 334.017112 -275.440648)
		(width 0.0889)
		(layer "In11.Cu")
		(net "M_F_CPU0_SB_DQ<3>")
	)
	(segment
		(start 266.760198 -283.819092)
		(end 267.022072 -283.819092)
		(width 0.14478)
		(layer "In11.Cu")
		(net "M_F_CPU0_SB_DQ<3>")
	)
	(segment
		(start 267.311632 -284.450282)
		(end 274.706588 -284.450282)
		(width 0.14478)
		(layer "In11.Cu")
		(net "M_F_CPU0_SB_DQ<3>")
	)
	(segment
		(start 286.043624 -283.600398)
		(end 286.893508 -284.450282)
		(width 0.14478)
		(layer "In11.Cu")
		(net "M_F_CPU0_SB_DQ<3>")
	)
	(segment
		(start 267.166852 -284.305502)
		(end 267.311632 -284.450282)
		(width 0.14478)
		(layer "In11.Cu")
		(net "M_F_CPU0_SB_DQ<3>")
	)
	(segment
		(start 266.470638 -284.450282)
		(end 266.615418 -284.305502)
		(width 0.14478)
		(layer "In11.Cu")
		(net "M_F_CPU0_SB_DQ<3>")
	)
	(segment
		(start 334.017112 -275.440648)
		(end 334.171036 -275.706078)
		(width 0.0889)
		(layer "In11.Cu")
		(net "M_F_CPU0_SB_DQ<3>")
	)
	(segment
		(start 282.308554 -284.450282)
		(end 283.158438 -283.600398)
		(width 0.14478)
		(layer "In11.Cu")
		(net "M_F_CPU0_SB_DQ<3>")
	)
	(segment
		(start 297.339766 -284.450282)
		(end 298.18965 -283.600398)
		(width 0.14478)
		(layer "In11.Cu")
		(net "M_F_CPU0_SB_DQ<3>")
	)
	(arc
		(start 330.598018 -275.383498)
		(mid 330.880974 -275.459675)
		(end 331.16393 -275.383498)
		(width 0.0889)
		(layer "In11.Cu")
		(net "M_F_CPU0_SB_DQ<3>")
	)
	(arc
		(start 329.658218 -275.383498)
		(mid 329.941174 -275.459675)
		(end 330.22413 -275.383498)
		(width 0.0889)
		(layer "In11.Cu")
		(net "M_F_CPU0_SB_DQ<3>")
	)
	(arc
		(start 333.41818 -275.383498)
		(mid 333.665893 -275.458718)
		(end 333.9211 -275.415248)
		(width 0.0889)
		(layer "In11.Cu")
		(net "M_F_CPU0_SB_DQ<3>")
	)
	(arc
		(start 333.05242 -275.378672)
		(mid 333.235928 -275.333178)
		(end 333.41818 -275.383498)
		(width 0.0889)
		(layer "In11.Cu")
		(net "M_F_CPU0_SB_DQ<3>")
	)
	(arc
		(start 327.475088 -275.30171)
		(mid 327.631892 -275.322527)
		(end 327.777856 -275.383498)
		(width 0.0889)
		(layer "In11.Cu")
		(net "M_F_CPU0_SB_DQ<3>")
	)
	(arc
		(start 331.538072 -275.383498)
		(mid 331.821028 -275.459675)
		(end 332.103984 -275.383498)
		(width 0.0889)
		(layer "In11.Cu")
		(net "M_F_CPU0_SB_DQ<3>")
	)
	(arc
		(start 328.344022 -275.383498)
		(mid 328.526273 -275.333148)
		(end 328.709782 -275.378672)
		(width 0.0889)
		(layer "In11.Cu")
		(net "M_F_CPU0_SB_DQ<3>")
	)
	(arc
		(start 331.16393 -275.383498)
		(mid 331.346181 -275.333148)
		(end 331.52969 -275.378672)
		(width 0.0889)
		(layer "In11.Cu")
		(net "M_F_CPU0_SB_DQ<3>")
	)
	(arc
		(start 330.22413 -275.383498)
		(mid 330.411074 -275.333243)
		(end 330.598018 -275.383498)
		(width 0.0889)
		(layer "In11.Cu")
		(net "M_F_CPU0_SB_DQ<3>")
	)
	(arc
		(start 327.777856 -275.383498)
		(mid 328.054923 -275.459769)
		(end 328.333608 -275.389594)
		(width 0.0889)
		(layer "In11.Cu")
		(net "M_F_CPU0_SB_DQ<3>")
	)
	(arc
		(start 329.292458 -275.378672)
		(mid 329.475966 -275.333178)
		(end 329.658218 -275.383498)
		(width 0.0889)
		(layer "In11.Cu")
		(net "M_F_CPU0_SB_DQ<3>")
	)
	(arc
		(start 328.718164 -275.383498)
		(mid 329.00112 -275.459675)
		(end 329.284076 -275.383498)
		(width 0.0889)
		(layer "In11.Cu")
		(net "M_F_CPU0_SB_DQ<3>")
	)
	(arc
		(start 332.478126 -275.383498)
		(mid 332.761082 -275.459675)
		(end 333.044038 -275.383498)
		(width 0.0889)
		(layer "In11.Cu")
		(net "M_F_CPU0_SB_DQ<3>")
	)
	(arc
		(start 332.103984 -275.383498)
		(mid 332.286235 -275.333148)
		(end 332.469744 -275.378672)
		(width 0.0889)
		(layer "In11.Cu")
		(net "M_F_CPU0_SB_DQ<3>")
	)
	(segment
		(start 332.758034 -293.260018)
		(end 332.291182 -293.525956)
		(width 0.10668)
		(layer "F.Cu")
		(net "M_F_CPU0_SB_DQ<31>")
	)
	(segment
		(start 267.950442 -318.46012)
		(end 268.198092 -318.46012)
		(width 0.14478)
		(layer "In11.Cu")
		(net "M_F_CPU0_SB_DQ<31>")
	)
	(segment
		(start 268.506702 -318.76873)
		(end 268.754352 -318.76873)
		(width 0.14478)
		(layer "In11.Cu")
		(net "M_F_CPU0_SB_DQ<31>")
	)
	(segment
		(start 284.308296 -318.46012)
		(end 284.611826 -318.76365)
		(width 0.14478)
		(layer "In11.Cu")
		(net "M_F_CPU0_SB_DQ<31>")
	)
	(segment
		(start 271.288002 -318.46012)
		(end 271.535652 -318.46012)
		(width 0.14478)
		(layer "In11.Cu")
		(net "M_F_CPU0_SB_DQ<31>")
	)
	(segment
		(start 267.641832 -318.76873)
		(end 267.950442 -318.46012)
		(width 0.14478)
		(layer "In11.Cu")
		(net "M_F_CPU0_SB_DQ<31>")
	)
	(segment
		(start 287.393126 -318.46012)
		(end 308.250844 -318.46012)
		(width 0.14478)
		(layer "In11.Cu")
		(net "M_F_CPU0_SB_DQ<31>")
	)
	(segment
		(start 277.34387 -318.77635)
		(end 277.6601 -318.46012)
		(width 0.14478)
		(layer "In11.Cu")
		(net "M_F_CPU0_SB_DQ<31>")
	)
	(segment
		(start 283.752036 -318.76365)
		(end 284.055566 -318.46012)
		(width 0.14478)
		(layer "In11.Cu")
		(net "M_F_CPU0_SB_DQ<31>")
	)
	(segment
		(start 268.198092 -318.46012)
		(end 268.506702 -318.76873)
		(width 0.14478)
		(layer "In11.Cu")
		(net "M_F_CPU0_SB_DQ<31>")
	)
	(segment
		(start 312.331862 -312.98261)
		(end 312.147712 -312.79846)
		(width 0.14478)
		(layer "In11.Cu")
		(net "M_F_CPU0_SB_DQ<31>")
	)
	(segment
		(start 312.147712 -312.593736)
		(end 328.164952 -296.576496)
		(width 0.14478)
		(layer "In11.Cu")
		(net "M_F_CPU0_SB_DQ<31>")
	)
	(segment
		(start 310.69407 -314.047378)
		(end 311.533286 -313.208162)
		(width 0.14478)
		(layer "In11.Cu")
		(net "M_F_CPU0_SB_DQ<31>")
	)
	(segment
		(start 266.837922 -318.46012)
		(end 267.085572 -318.46012)
		(width 0.14478)
		(layer "In11.Cu")
		(net "M_F_CPU0_SB_DQ<31>")
	)
	(segment
		(start 328.782172 -295.651682)
		(end 328.813922 -295.633394)
		(width 0.0889)
		(layer "In11.Cu")
		(net "M_F_CPU0_SB_DQ<31>")
	)
	(segment
		(start 284.611826 -318.76365)
		(end 284.864556 -318.76365)
		(width 0.14478)
		(layer "In11.Cu")
		(net "M_F_CPU0_SB_DQ<31>")
	)
	(segment
		(start 271.844262 -318.76873)
		(end 272.091912 -318.76873)
		(width 0.14478)
		(layer "In11.Cu")
		(net "M_F_CPU0_SB_DQ<31>")
	)
	(segment
		(start 269.310612 -318.46012)
		(end 269.619222 -318.76873)
		(width 0.14478)
		(layer "In11.Cu")
		(net "M_F_CPU0_SB_DQ<31>")
	)
	(segment
		(start 267.394182 -318.76873)
		(end 267.641832 -318.76873)
		(width 0.14478)
		(layer "In11.Cu")
		(net "M_F_CPU0_SB_DQ<31>")
	)
	(segment
		(start 328.164952 -296.576496)
		(end 328.346308 -296.441876)
		(width 0.0889)
		(layer "In11.Cu")
		(net "M_F_CPU0_SB_DQ<31>")
	)
	(segment
		(start 274.56257 -318.46012)
		(end 274.8788 -318.77635)
		(width 0.14478)
		(layer "In11.Cu")
		(net "M_F_CPU0_SB_DQ<31>")
	)
	(segment
		(start 330.221336 -293.205154)
		(end 330.22413 -293.203376)
		(width 0.0889)
		(layer "In11.Cu")
		(net "M_F_CPU0_SB_DQ<31>")
	)
	(segment
		(start 278.21636 -318.77635)
		(end 278.45639 -318.77635)
		(width 0.14478)
		(layer "In11.Cu")
		(net "M_F_CPU0_SB_DQ<31>")
	)
	(segment
		(start 329.284076 -294.823388)
		(end 329.286616 -294.821864)
		(width 0.0889)
		(layer "In11.Cu")
		(net "M_F_CPU0_SB_DQ<31>")
	)
	(segment
		(start 267.085572 -318.46012)
		(end 267.394182 -318.76873)
		(width 0.14478)
		(layer "In11.Cu")
		(net "M_F_CPU0_SB_DQ<31>")
	)
	(segment
		(start 269.619222 -318.76873)
		(end 269.866872 -318.76873)
		(width 0.14478)
		(layer "In11.Cu")
		(net "M_F_CPU0_SB_DQ<31>")
	)
	(segment
		(start 276.23135 -318.77635)
		(end 276.54758 -318.46012)
		(width 0.14478)
		(layer "In11.Cu")
		(net "M_F_CPU0_SB_DQ<31>")
	)
	(segment
		(start 285.168086 -318.46012)
		(end 285.420816 -318.46012)
		(width 0.14478)
		(layer "In11.Cu")
		(net "M_F_CPU0_SB_DQ<31>")
	)
	(segment
		(start 312.126884 -313.392312)
		(end 312.331862 -313.187334)
		(width 0.14478)
		(layer "In11.Cu")
		(net "M_F_CPU0_SB_DQ<31>")
	)
	(segment
		(start 284.864556 -318.76365)
		(end 285.168086 -318.46012)
		(width 0.14478)
		(layer "In11.Cu")
		(net "M_F_CPU0_SB_DQ<31>")
	)
	(segment
		(start 276.78761 -318.46012)
		(end 277.10384 -318.77635)
		(width 0.14478)
		(layer "In11.Cu")
		(net "M_F_CPU0_SB_DQ<31>")
	)
	(segment
		(start 282.943046 -318.46012)
		(end 283.195776 -318.46012)
		(width 0.14478)
		(layer "In11.Cu")
		(net "M_F_CPU0_SB_DQ<31>")
	)
	(segment
		(start 270.979392 -318.76873)
		(end 271.288002 -318.46012)
		(width 0.14478)
		(layer "In11.Cu")
		(net "M_F_CPU0_SB_DQ<31>")
	)
	(segment
		(start 286.836866 -318.76365)
		(end 287.089596 -318.76365)
		(width 0.14478)
		(layer "In11.Cu")
		(net "M_F_CPU0_SB_DQ<31>")
	)
	(segment
		(start 329.252326 -294.841676)
		(end 329.284076 -294.823388)
		(width 0.0889)
		(layer "In11.Cu")
		(net "M_F_CPU0_SB_DQ<31>")
	)
	(segment
		(start 332.040738 -293.235126)
		(end 332.137004 -293.260526)
		(width 0.0889)
		(layer "In11.Cu")
		(net "M_F_CPU0_SB_DQ<31>")
	)
	(segment
		(start 283.499306 -318.76365)
		(end 283.752036 -318.76365)
		(width 0.14478)
		(layer "In11.Cu")
		(net "M_F_CPU0_SB_DQ<31>")
	)
	(segment
		(start 276.54758 -318.46012)
		(end 276.78761 -318.46012)
		(width 0.14478)
		(layer "In11.Cu")
		(net "M_F_CPU0_SB_DQ<31>")
	)
	(segment
		(start 282.083256 -318.46012)
		(end 282.386786 -318.76365)
		(width 0.14478)
		(layer "In11.Cu")
		(net "M_F_CPU0_SB_DQ<31>")
	)
	(segment
		(start 270.423132 -318.46012)
		(end 270.731742 -318.76873)
		(width 0.14478)
		(layer "In11.Cu")
		(net "M_F_CPU0_SB_DQ<31>")
	)
	(segment
		(start 275.43506 -318.46012)
		(end 275.67509 -318.46012)
		(width 0.14478)
		(layer "In11.Cu")
		(net "M_F_CPU0_SB_DQ<31>")
	)
	(segment
		(start 284.055566 -318.46012)
		(end 284.308296 -318.46012)
		(width 0.14478)
		(layer "In11.Cu")
		(net "M_F_CPU0_SB_DQ<31>")
	)
	(segment
		(start 270.175482 -318.46012)
		(end 270.423132 -318.46012)
		(width 0.14478)
		(layer "In11.Cu")
		(net "M_F_CPU0_SB_DQ<31>")
	)
	(segment
		(start 285.977076 -318.76365)
		(end 286.280606 -318.46012)
		(width 0.14478)
		(layer "In11.Cu")
		(net "M_F_CPU0_SB_DQ<31>")
	)
	(segment
		(start 311.73801 -313.208162)
		(end 311.92216 -313.392312)
		(width 0.14478)
		(layer "In11.Cu")
		(net "M_F_CPU0_SB_DQ<31>")
	)
	(segment
		(start 278.77262 -318.46012)
		(end 282.083256 -318.46012)
		(width 0.14478)
		(layer "In11.Cu")
		(net "M_F_CPU0_SB_DQ<31>")
	)
	(segment
		(start 286.533336 -318.46012)
		(end 286.836866 -318.76365)
		(width 0.14478)
		(layer "In11.Cu")
		(net "M_F_CPU0_SB_DQ<31>")
	)
	(segment
		(start 310.69407 -316.016894)
		(end 310.69407 -314.047378)
		(width 0.14478)
		(layer "In11.Cu")
		(net "M_F_CPU0_SB_DQ<31>")
	)
	(segment
		(start 311.533286 -313.208162)
		(end 311.73801 -313.208162)
		(width 0.14478)
		(layer "In11.Cu")
		(net "M_F_CPU0_SB_DQ<31>")
	)
	(segment
		(start 266.281662 -318.76873)
		(end 266.529312 -318.76873)
		(width 0.14478)
		(layer "In11.Cu")
		(net "M_F_CPU0_SB_DQ<31>")
	)
	(segment
		(start 270.731742 -318.76873)
		(end 270.979392 -318.76873)
		(width 0.14478)
		(layer "In11.Cu")
		(net "M_F_CPU0_SB_DQ<31>")
	)
	(segment
		(start 277.90013 -318.46012)
		(end 278.21636 -318.77635)
		(width 0.14478)
		(layer "In11.Cu")
		(net "M_F_CPU0_SB_DQ<31>")
	)
	(segment
		(start 278.45639 -318.77635)
		(end 278.77262 -318.46012)
		(width 0.14478)
		(layer "In11.Cu")
		(net "M_F_CPU0_SB_DQ<31>")
	)
	(segment
		(start 282.386786 -318.76365)
		(end 282.639516 -318.76365)
		(width 0.14478)
		(layer "In11.Cu")
		(net "M_F_CPU0_SB_DQ<31>")
	)
	(segment
		(start 285.724346 -318.76365)
		(end 285.977076 -318.76365)
		(width 0.14478)
		(layer "In11.Cu")
		(net "M_F_CPU0_SB_DQ<31>")
	)
	(segment
		(start 311.92216 -313.392312)
		(end 312.126884 -313.392312)
		(width 0.14478)
		(layer "In11.Cu")
		(net "M_F_CPU0_SB_DQ<31>")
	)
	(segment
		(start 269.866872 -318.76873)
		(end 270.175482 -318.46012)
		(width 0.14478)
		(layer "In11.Cu")
		(net "M_F_CPU0_SB_DQ<31>")
	)
	(segment
		(start 328.813922 -295.633394)
		(end 328.816462 -295.63187)
		(width 0.0889)
		(layer "In11.Cu")
		(net "M_F_CPU0_SB_DQ<31>")
	)
	(segment
		(start 274.8788 -318.77635)
		(end 275.11883 -318.77635)
		(width 0.14478)
		(layer "In11.Cu")
		(net "M_F_CPU0_SB_DQ<31>")
	)
	(segment
		(start 312.147712 -312.79846)
		(end 312.147712 -312.593736)
		(width 0.14478)
		(layer "In11.Cu")
		(net "M_F_CPU0_SB_DQ<31>")
	)
	(segment
		(start 275.67509 -318.46012)
		(end 275.99132 -318.77635)
		(width 0.14478)
		(layer "In11.Cu")
		(net "M_F_CPU0_SB_DQ<31>")
	)
	(segment
		(start 268.754352 -318.76873)
		(end 269.062962 -318.46012)
		(width 0.14478)
		(layer "In11.Cu")
		(net "M_F_CPU0_SB_DQ<31>")
	)
	(segment
		(start 266.529312 -318.76873)
		(end 266.837922 -318.46012)
		(width 0.14478)
		(layer "In11.Cu")
		(net "M_F_CPU0_SB_DQ<31>")
	)
	(segment
		(start 287.089596 -318.76365)
		(end 287.393126 -318.46012)
		(width 0.14478)
		(layer "In11.Cu")
		(net "M_F_CPU0_SB_DQ<31>")
	)
	(segment
		(start 329.723496 -294.031162)
		(end 329.753976 -294.013382)
		(width 0.0889)
		(layer "In11.Cu")
		(net "M_F_CPU0_SB_DQ<31>")
	)
	(segment
		(start 331.52969 -293.19855)
		(end 331.538072 -293.203376)
		(width 0.0889)
		(layer "In11.Cu")
		(net "M_F_CPU0_SB_DQ<31>")
	)
	(segment
		(start 332.137004 -293.260526)
		(end 332.291182 -293.525956)
		(width 0.0889)
		(layer "In11.Cu")
		(net "M_F_CPU0_SB_DQ<31>")
	)
	(segment
		(start 271.535652 -318.46012)
		(end 271.844262 -318.76873)
		(width 0.14478)
		(layer "In11.Cu")
		(net "M_F_CPU0_SB_DQ<31>")
	)
	(segment
		(start 275.99132 -318.77635)
		(end 276.23135 -318.77635)
		(width 0.14478)
		(layer "In11.Cu")
		(net "M_F_CPU0_SB_DQ<31>")
	)
	(segment
		(start 312.331862 -313.187334)
		(end 312.331862 -312.98261)
		(width 0.14478)
		(layer "In11.Cu")
		(net "M_F_CPU0_SB_DQ<31>")
	)
	(segment
		(start 269.062962 -318.46012)
		(end 269.310612 -318.46012)
		(width 0.14478)
		(layer "In11.Cu")
		(net "M_F_CPU0_SB_DQ<31>")
	)
	(segment
		(start 329.753976 -294.013382)
		(end 329.793092 -293.990522)
		(width 0.0889)
		(layer "In11.Cu")
		(net "M_F_CPU0_SB_DQ<31>")
	)
	(segment
		(start 282.639516 -318.76365)
		(end 282.943046 -318.46012)
		(width 0.14478)
		(layer "In11.Cu")
		(net "M_F_CPU0_SB_DQ<31>")
	)
	(segment
		(start 272.091912 -318.76873)
		(end 272.400522 -318.46012)
		(width 0.14478)
		(layer "In11.Cu")
		(net "M_F_CPU0_SB_DQ<31>")
	)
	(segment
		(start 277.6601 -318.46012)
		(end 277.90013 -318.46012)
		(width 0.14478)
		(layer "In11.Cu")
		(net "M_F_CPU0_SB_DQ<31>")
	)
	(segment
		(start 265.54811 -318.035178)
		(end 266.281662 -318.76873)
		(width 0.14478)
		(layer "In11.Cu")
		(net "M_F_CPU0_SB_DQ<31>")
	)
	(segment
		(start 275.11883 -318.77635)
		(end 275.43506 -318.46012)
		(width 0.14478)
		(layer "In11.Cu")
		(net "M_F_CPU0_SB_DQ<31>")
	)
	(segment
		(start 308.250844 -318.46012)
		(end 310.69407 -316.016894)
		(width 0.14478)
		(layer "In11.Cu")
		(net "M_F_CPU0_SB_DQ<31>")
	)
	(segment
		(start 272.400522 -318.46012)
		(end 274.56257 -318.46012)
		(width 0.14478)
		(layer "In11.Cu")
		(net "M_F_CPU0_SB_DQ<31>")
	)
	(segment
		(start 283.195776 -318.46012)
		(end 283.499306 -318.76365)
		(width 0.14478)
		(layer "In11.Cu")
		(net "M_F_CPU0_SB_DQ<31>")
	)
	(segment
		(start 285.420816 -318.46012)
		(end 285.724346 -318.76365)
		(width 0.14478)
		(layer "In11.Cu")
		(net "M_F_CPU0_SB_DQ<31>")
	)
	(segment
		(start 277.10384 -318.77635)
		(end 277.34387 -318.77635)
		(width 0.14478)
		(layer "In11.Cu")
		(net "M_F_CPU0_SB_DQ<31>")
	)
	(segment
		(start 286.280606 -318.46012)
		(end 286.533336 -318.46012)
		(width 0.14478)
		(layer "In11.Cu")
		(net "M_F_CPU0_SB_DQ<31>")
	)
	(arc
		(start 329.793092 -293.990522)
		(mid 329.971905 -293.788172)
		(end 330.036424 -293.525956)
		(width 0.0889)
		(layer "In11.Cu")
		(net "M_F_CPU0_SB_DQ<31>")
	)
	(arc
		(start 328.816462 -295.63187)
		(mid 329.021426 -295.42636)
		(end 329.09637 -295.145968)
		(width 0.0889)
		(layer "In11.Cu")
		(net "M_F_CPU0_SB_DQ<31>")
	)
	(arc
		(start 330.22413 -293.203376)
		(mid 330.411074 -293.153121)
		(end 330.598018 -293.203376)
		(width 0.0889)
		(layer "In11.Cu")
		(net "M_F_CPU0_SB_DQ<31>")
	)
	(arc
		(start 328.626216 -295.955974)
		(mid 328.667471 -295.785003)
		(end 328.782172 -295.651682)
		(width 0.0889)
		(layer "In11.Cu")
		(net "M_F_CPU0_SB_DQ<31>")
	)
	(arc
		(start 329.09637 -295.145968)
		(mid 329.137625 -294.974997)
		(end 329.252326 -294.841676)
		(width 0.0889)
		(layer "In11.Cu")
		(net "M_F_CPU0_SB_DQ<31>")
	)
	(arc
		(start 331.16393 -293.203376)
		(mid 331.346181 -293.153026)
		(end 331.52969 -293.19855)
		(width 0.0889)
		(layer "In11.Cu")
		(net "M_F_CPU0_SB_DQ<31>")
	)
	(arc
		(start 329.286616 -294.821864)
		(mid 329.49158 -294.616354)
		(end 329.566524 -294.335962)
		(width 0.0889)
		(layer "In11.Cu")
		(net "M_F_CPU0_SB_DQ<31>")
	)
	(arc
		(start 330.036424 -293.525956)
		(mid 330.085953 -293.340803)
		(end 330.221336 -293.205154)
		(width 0.0889)
		(layer "In11.Cu")
		(net "M_F_CPU0_SB_DQ<31>")
	)
	(arc
		(start 330.598018 -293.203376)
		(mid 330.880974 -293.279553)
		(end 331.16393 -293.203376)
		(width 0.0889)
		(layer "In11.Cu")
		(net "M_F_CPU0_SB_DQ<31>")
	)
	(arc
		(start 328.346308 -296.441876)
		(mid 328.551272 -296.236366)
		(end 328.626216 -295.955974)
		(width 0.0889)
		(layer "In11.Cu")
		(net "M_F_CPU0_SB_DQ<31>")
	)
	(arc
		(start 329.566524 -294.335962)
		(mid 329.608073 -294.16454)
		(end 329.723496 -294.031162)
		(width 0.0889)
		(layer "In11.Cu")
		(net "M_F_CPU0_SB_DQ<31>")
	)
	(arc
		(start 331.538072 -293.203376)
		(mid 331.785668 -293.278554)
		(end 332.040738 -293.235126)
		(width 0.0889)
		(layer "In11.Cu")
		(net "M_F_CPU0_SB_DQ<31>")
	)
	(segment
		(start 333.227934 -292.450012)
		(end 332.761082 -292.71595)
		(width 0.10668)
		(layer "F.Cu")
		(net "M_F_CPU0_SB_DQ<30>")
	)
	(segment
		(start 308.225952 -316.760098)
		(end 306.08397 -316.760098)
		(width 0.14478)
		(layer "In11.Cu")
		(net "M_F_CPU0_SB_DQ<30>")
	)
	(segment
		(start 304.429668 -316.529212)
		(end 304.198782 -316.760098)
		(width 0.14478)
		(layer "In11.Cu")
		(net "M_F_CPU0_SB_DQ<30>")
	)
	(segment
		(start 309.688738 -313.766962)
		(end 309.688738 -315.297312)
		(width 0.14478)
		(layer "In11.Cu")
		(net "M_F_CPU0_SB_DQ<30>")
	)
	(segment
		(start 326.549004 -296.009314)
		(end 326.549004 -296.906696)
		(width 0.14478)
		(layer "In11.Cu")
		(net "M_F_CPU0_SB_DQ<30>")
	)
	(segment
		(start 331.642466 -292.388544)
		(end 331.634084 -292.39337)
		(width 0.0889)
		(layer "In11.Cu")
		(net "M_F_CPU0_SB_DQ<30>")
	)
	(segment
		(start 327.216008 -295.34231)
		(end 326.549004 -296.009314)
		(width 0.0889)
		(layer "In11.Cu")
		(net "M_F_CPU0_SB_DQ<30>")
	)
	(segment
		(start 268.754352 -317.49619)
		(end 268.52372 -317.49619)
		(width 0.14478)
		(layer "In11.Cu")
		(net "M_F_CPU0_SB_DQ<30>")
	)
	(segment
		(start 266.135866 -317.333376)
		(end 266.135866 -316.922912)
		(width 0.14478)
		(layer "In11.Cu")
		(net "M_F_CPU0_SB_DQ<30>")
	)
	(segment
		(start 327.913238 -293.990522)
		(end 327.874122 -294.013382)
		(width 0.0889)
		(layer "In11.Cu")
		(net "M_F_CPU0_SB_DQ<30>")
	)
	(segment
		(start 268.917166 -317.333376)
		(end 268.754352 -317.49619)
		(width 0.14478)
		(layer "In11.Cu")
		(net "M_F_CPU0_SB_DQ<30>")
	)
	(segment
		(start 330.702412 -292.388544)
		(end 330.69403 -292.39337)
		(width 0.0889)
		(layer "In11.Cu")
		(net "M_F_CPU0_SB_DQ<30>")
	)
	(segment
		(start 267.641832 -317.49619)
		(end 267.4112 -317.49619)
		(width 0.14478)
		(layer "In11.Cu")
		(net "M_F_CPU0_SB_DQ<30>")
	)
	(segment
		(start 268.360906 -317.333376)
		(end 268.360906 -316.922912)
		(width 0.14478)
		(layer "In11.Cu")
		(net "M_F_CPU0_SB_DQ<30>")
	)
	(segment
		(start 326.549004 -296.906696)
		(end 309.688738 -313.766962)
		(width 0.14478)
		(layer "In11.Cu")
		(net "M_F_CPU0_SB_DQ<30>")
	)
	(segment
		(start 266.29868 -317.49619)
		(end 266.135866 -317.333376)
		(width 0.14478)
		(layer "In11.Cu")
		(net "M_F_CPU0_SB_DQ<30>")
	)
	(segment
		(start 268.917166 -316.922912)
		(end 268.917166 -317.333376)
		(width 0.14478)
		(layer "In11.Cu")
		(net "M_F_CPU0_SB_DQ<30>")
	)
	(segment
		(start 266.85494 -316.760098)
		(end 266.692126 -316.922912)
		(width 0.14478)
		(layer "In11.Cu")
		(net "M_F_CPU0_SB_DQ<30>")
	)
	(segment
		(start 305.30165 -316.760098)
		(end 304.981102 -316.760098)
		(width 0.14478)
		(layer "In11.Cu")
		(net "M_F_CPU0_SB_DQ<30>")
	)
	(segment
		(start 268.198092 -316.760098)
		(end 267.96746 -316.760098)
		(width 0.14478)
		(layer "In11.Cu")
		(net "M_F_CPU0_SB_DQ<30>")
	)
	(segment
		(start 304.198782 -316.760098)
		(end 269.07998 -316.760098)
		(width 0.14478)
		(layer "In11.Cu")
		(net "M_F_CPU0_SB_DQ<30>")
	)
	(segment
		(start 306.08397 -316.760098)
		(end 305.853084 -316.529212)
		(width 0.14478)
		(layer "In11.Cu")
		(net "M_F_CPU0_SB_DQ<30>")
	)
	(segment
		(start 309.688738 -315.297312)
		(end 308.225952 -316.760098)
		(width 0.14478)
		(layer "In11.Cu")
		(net "M_F_CPU0_SB_DQ<30>")
	)
	(segment
		(start 304.981102 -316.760098)
		(end 304.750216 -316.529212)
		(width 0.14478)
		(layer "In11.Cu")
		(net "M_F_CPU0_SB_DQ<30>")
	)
	(segment
		(start 327.216008 -295.145968)
		(end 327.216008 -295.34231)
		(width 0.0889)
		(layer "In11.Cu")
		(net "M_F_CPU0_SB_DQ<30>")
	)
	(segment
		(start 328.344022 -293.203376)
		(end 328.313542 -293.221156)
		(width 0.0889)
		(layer "In11.Cu")
		(net "M_F_CPU0_SB_DQ<30>")
	)
	(segment
		(start 328.346562 -293.201598)
		(end 328.344022 -293.203376)
		(width 0.0889)
		(layer "In11.Cu")
		(net "M_F_CPU0_SB_DQ<30>")
	)
	(segment
		(start 305.853084 -316.529212)
		(end 305.532536 -316.529212)
		(width 0.14478)
		(layer "In11.Cu")
		(net "M_F_CPU0_SB_DQ<30>")
	)
	(segment
		(start 330.128118 -292.39337)
		(end 330.119736 -292.388544)
		(width 0.0889)
		(layer "In11.Cu")
		(net "M_F_CPU0_SB_DQ<30>")
	)
	(segment
		(start 268.360906 -316.922912)
		(end 268.198092 -316.760098)
		(width 0.14478)
		(layer "In11.Cu")
		(net "M_F_CPU0_SB_DQ<30>")
	)
	(segment
		(start 266.135866 -316.922912)
		(end 265.54811 -316.335156)
		(width 0.14478)
		(layer "In11.Cu")
		(net "M_F_CPU0_SB_DQ<30>")
	)
	(segment
		(start 305.532536 -316.529212)
		(end 305.30165 -316.760098)
		(width 0.14478)
		(layer "In11.Cu")
		(net "M_F_CPU0_SB_DQ<30>")
	)
	(segment
		(start 327.874122 -294.013382)
		(end 327.84034 -294.03294)
		(width 0.0889)
		(layer "In11.Cu")
		(net "M_F_CPU0_SB_DQ<30>")
	)
	(segment
		(start 269.07998 -316.760098)
		(end 268.917166 -316.922912)
		(width 0.14478)
		(layer "In11.Cu")
		(net "M_F_CPU0_SB_DQ<30>")
	)
	(segment
		(start 328.814176 -292.39337)
		(end 328.811382 -292.395148)
		(width 0.0889)
		(layer "In11.Cu")
		(net "M_F_CPU0_SB_DQ<30>")
	)
	(segment
		(start 266.529312 -317.49619)
		(end 266.29868 -317.49619)
		(width 0.14478)
		(layer "In11.Cu")
		(net "M_F_CPU0_SB_DQ<30>")
	)
	(segment
		(start 266.692126 -317.333376)
		(end 266.529312 -317.49619)
		(width 0.14478)
		(layer "In11.Cu")
		(net "M_F_CPU0_SB_DQ<30>")
	)
	(segment
		(start 267.96746 -316.760098)
		(end 267.804646 -316.922912)
		(width 0.14478)
		(layer "In11.Cu")
		(net "M_F_CPU0_SB_DQ<30>")
	)
	(segment
		(start 332.607158 -292.45052)
		(end 332.511146 -292.42512)
		(width 0.0889)
		(layer "In11.Cu")
		(net "M_F_CPU0_SB_DQ<30>")
	)
	(segment
		(start 266.692126 -316.922912)
		(end 266.692126 -317.333376)
		(width 0.14478)
		(layer "In11.Cu")
		(net "M_F_CPU0_SB_DQ<30>")
	)
	(segment
		(start 267.248386 -317.333376)
		(end 267.248386 -316.922912)
		(width 0.14478)
		(layer "In11.Cu")
		(net "M_F_CPU0_SB_DQ<30>")
	)
	(segment
		(start 304.750216 -316.529212)
		(end 304.429668 -316.529212)
		(width 0.14478)
		(layer "In11.Cu")
		(net "M_F_CPU0_SB_DQ<30>")
	)
	(segment
		(start 267.804646 -317.333376)
		(end 267.641832 -317.49619)
		(width 0.14478)
		(layer "In11.Cu")
		(net "M_F_CPU0_SB_DQ<30>")
	)
	(segment
		(start 267.804646 -316.922912)
		(end 267.804646 -317.333376)
		(width 0.14478)
		(layer "In11.Cu")
		(net "M_F_CPU0_SB_DQ<30>")
	)
	(segment
		(start 332.761082 -292.71595)
		(end 332.607158 -292.45052)
		(width 0.0889)
		(layer "In11.Cu")
		(net "M_F_CPU0_SB_DQ<30>")
	)
	(segment
		(start 267.4112 -317.49619)
		(end 267.248386 -317.333376)
		(width 0.14478)
		(layer "In11.Cu")
		(net "M_F_CPU0_SB_DQ<30>")
	)
	(segment
		(start 267.248386 -316.922912)
		(end 267.085572 -316.760098)
		(width 0.14478)
		(layer "In11.Cu")
		(net "M_F_CPU0_SB_DQ<30>")
	)
	(segment
		(start 267.085572 -316.760098)
		(end 266.85494 -316.760098)
		(width 0.14478)
		(layer "In11.Cu")
		(net "M_F_CPU0_SB_DQ<30>")
	)
	(segment
		(start 268.52372 -317.49619)
		(end 268.360906 -317.333376)
		(width 0.14478)
		(layer "In11.Cu")
		(net "M_F_CPU0_SB_DQ<30>")
	)
	(segment
		(start 327.403714 -294.823388)
		(end 327.371964 -294.841676)
		(width 0.0889)
		(layer "In11.Cu")
		(net "M_F_CPU0_SB_DQ<30>")
	)
	(segment
		(start 327.44283 -294.800528)
		(end 327.403714 -294.823388)
		(width 0.0889)
		(layer "In11.Cu")
		(net "M_F_CPU0_SB_DQ<30>")
	)
	(arc
		(start 332.008226 -292.39337)
		(mid 331.825975 -292.34302)
		(end 331.642466 -292.388544)
		(width 0.0889)
		(layer "In11.Cu")
		(net "M_F_CPU0_SB_DQ<30>")
	)
	(arc
		(start 331.068172 -292.39337)
		(mid 330.885921 -292.34302)
		(end 330.702412 -292.388544)
		(width 0.0889)
		(layer "In11.Cu")
		(net "M_F_CPU0_SB_DQ<30>")
	)
	(arc
		(start 331.634084 -292.39337)
		(mid 331.351128 -292.469547)
		(end 331.068172 -292.39337)
		(width 0.0889)
		(layer "In11.Cu")
		(net "M_F_CPU0_SB_DQ<30>")
	)
	(arc
		(start 330.119736 -292.388544)
		(mid 329.936228 -292.34305)
		(end 329.753976 -292.39337)
		(width 0.0889)
		(layer "In11.Cu")
		(net "M_F_CPU0_SB_DQ<30>")
	)
	(arc
		(start 329.188064 -292.39337)
		(mid 329.00112 -292.343115)
		(end 328.814176 -292.39337)
		(width 0.0889)
		(layer "In11.Cu")
		(net "M_F_CPU0_SB_DQ<30>")
	)
	(arc
		(start 328.15657 -293.525956)
		(mid 328.092055 -293.788175)
		(end 327.913238 -293.990522)
		(width 0.0889)
		(layer "In11.Cu")
		(net "M_F_CPU0_SB_DQ<30>")
	)
	(arc
		(start 329.753976 -292.39337)
		(mid 329.47102 -292.469547)
		(end 329.188064 -292.39337)
		(width 0.0889)
		(layer "In11.Cu")
		(net "M_F_CPU0_SB_DQ<30>")
	)
	(arc
		(start 327.686162 -294.335962)
		(mid 327.621647 -294.598181)
		(end 327.44283 -294.800528)
		(width 0.0889)
		(layer "In11.Cu")
		(net "M_F_CPU0_SB_DQ<30>")
	)
	(arc
		(start 328.811382 -292.395148)
		(mid 328.676045 -292.530824)
		(end 328.62647 -292.71595)
		(width 0.0889)
		(layer "In11.Cu")
		(net "M_F_CPU0_SB_DQ<30>")
	)
	(arc
		(start 330.69403 -292.39337)
		(mid 330.411074 -292.469547)
		(end 330.128118 -292.39337)
		(width 0.0889)
		(layer "In11.Cu")
		(net "M_F_CPU0_SB_DQ<30>")
	)
	(arc
		(start 327.371964 -294.841676)
		(mid 327.257288 -294.97501)
		(end 327.216008 -295.145968)
		(width 0.0889)
		(layer "In11.Cu")
		(net "M_F_CPU0_SB_DQ<30>")
	)
	(arc
		(start 327.84034 -294.03294)
		(mid 327.726933 -294.16597)
		(end 327.686162 -294.335962)
		(width 0.0889)
		(layer "In11.Cu")
		(net "M_F_CPU0_SB_DQ<30>")
	)
	(arc
		(start 328.62647 -292.71595)
		(mid 328.551416 -292.996172)
		(end 328.346562 -293.201598)
		(width 0.0889)
		(layer "In11.Cu")
		(net "M_F_CPU0_SB_DQ<30>")
	)
	(arc
		(start 332.511146 -292.42512)
		(mid 332.255938 -292.468597)
		(end 332.008226 -292.39337)
		(width 0.0889)
		(layer "In11.Cu")
		(net "M_F_CPU0_SB_DQ<30>")
	)
	(arc
		(start 328.313542 -293.221156)
		(mid 328.198115 -293.354532)
		(end 328.15657 -293.525956)
		(width 0.0889)
		(layer "In11.Cu")
		(net "M_F_CPU0_SB_DQ<30>")
	)
	(segment
		(start 333.227934 -274.630134)
		(end 332.761082 -274.896072)
		(width 0.10668)
		(layer "F.Cu")
		(net "M_F_CPU0_SB_DQ<2>")
	)
	(segment
		(start 267.461238 -283.29128)
		(end 267.723112 -283.29128)
		(width 0.14478)
		(layer "In11.Cu")
		(net "M_F_CPU0_SB_DQ<2>")
	)
	(segment
		(start 282.177998 -282.760166)
		(end 283.028136 -281.910028)
		(width 0.14478)
		(layer "In11.Cu")
		(net "M_F_CPU0_SB_DQ<2>")
	)
	(segment
		(start 266.909804 -282.229052)
		(end 267.171678 -282.229052)
		(width 0.14478)
		(layer "In11.Cu")
		(net "M_F_CPU0_SB_DQ<2>")
	)
	(segment
		(start 300.918372 -281.910028)
		(end 301.76851 -282.760166)
		(width 0.14478)
		(layer "In11.Cu")
		(net "M_F_CPU0_SB_DQ<2>")
	)
	(segment
		(start 278.439372 -281.910028)
		(end 279.28951 -282.760166)
		(width 0.14478)
		(layer "In11.Cu")
		(net "M_F_CPU0_SB_DQ<2>")
	)
	(segment
		(start 290.952936 -281.910028)
		(end 293.349172 -281.910028)
		(width 0.14478)
		(layer "In11.Cu")
		(net "M_F_CPU0_SB_DQ<2>")
	)
	(segment
		(start 267.316458 -283.1465)
		(end 267.461238 -283.29128)
		(width 0.14478)
		(layer "In11.Cu")
		(net "M_F_CPU0_SB_DQ<2>")
	)
	(segment
		(start 267.867892 -282.373832)
		(end 268.012672 -282.229052)
		(width 0.14478)
		(layer "In11.Cu")
		(net "M_F_CPU0_SB_DQ<2>")
	)
	(segment
		(start 331.634084 -274.573492)
		(end 331.642466 -274.568666)
		(width 0.0889)
		(layer "In11.Cu")
		(net "M_F_CPU0_SB_DQ<2>")
	)
	(segment
		(start 265.973306 -282.760166)
		(end 266.620244 -282.760166)
		(width 0.14478)
		(layer "In11.Cu")
		(net "M_F_CPU0_SB_DQ<2>")
	)
	(segment
		(start 268.012672 -282.229052)
		(end 268.274546 -282.229052)
		(width 0.14478)
		(layer "In11.Cu")
		(net "M_F_CPU0_SB_DQ<2>")
	)
	(segment
		(start 301.76851 -282.760166)
		(end 304.597054 -282.760166)
		(width 0.14478)
		(layer "In11.Cu")
		(net "M_F_CPU0_SB_DQ<2>")
	)
	(segment
		(start 327.297542 -274.566634)
		(end 327.309226 -274.573492)
		(width 0.0889)
		(layer "In11.Cu")
		(net "M_F_CPU0_SB_DQ<2>")
	)
	(segment
		(start 286.55391 -282.760166)
		(end 290.102798 -282.760166)
		(width 0.14478)
		(layer "In11.Cu")
		(net "M_F_CPU0_SB_DQ<2>")
	)
	(segment
		(start 315.55182 -273.67484)
		(end 323.925184 -273.67484)
		(width 0.14478)
		(layer "In11.Cu")
		(net "M_F_CPU0_SB_DQ<2>")
	)
	(segment
		(start 266.765024 -282.615386)
		(end 266.765024 -282.373832)
		(width 0.14478)
		(layer "In11.Cu")
		(net "M_F_CPU0_SB_DQ<2>")
	)
	(segment
		(start 266.620244 -282.760166)
		(end 266.765024 -282.615386)
		(width 0.14478)
		(layer "In11.Cu")
		(net "M_F_CPU0_SB_DQ<2>")
	)
	(segment
		(start 325.442834 -273.67484)
		(end 326.252586 -274.484592)
		(width 0.0889)
		(layer "In11.Cu")
		(net "M_F_CPU0_SB_DQ<2>")
	)
	(segment
		(start 279.28951 -282.760166)
		(end 282.177998 -282.760166)
		(width 0.14478)
		(layer "In11.Cu")
		(net "M_F_CPU0_SB_DQ<2>")
	)
	(segment
		(start 290.102798 -282.760166)
		(end 290.952936 -281.910028)
		(width 0.14478)
		(layer "In11.Cu")
		(net "M_F_CPU0_SB_DQ<2>")
	)
	(segment
		(start 298.06392 -281.910028)
		(end 300.918372 -281.910028)
		(width 0.14478)
		(layer "In11.Cu")
		(net "M_F_CPU0_SB_DQ<2>")
	)
	(segment
		(start 267.723112 -283.29128)
		(end 267.867892 -283.1465)
		(width 0.14478)
		(layer "In11.Cu")
		(net "M_F_CPU0_SB_DQ<2>")
	)
	(segment
		(start 297.213782 -282.760166)
		(end 298.06392 -281.910028)
		(width 0.14478)
		(layer "In11.Cu")
		(net "M_F_CPU0_SB_DQ<2>")
	)
	(segment
		(start 275.091398 -282.760166)
		(end 275.941536 -281.910028)
		(width 0.14478)
		(layer "In11.Cu")
		(net "M_F_CPU0_SB_DQ<2>")
	)
	(segment
		(start 268.419326 -282.615386)
		(end 268.564106 -282.760166)
		(width 0.14478)
		(layer "In11.Cu")
		(net "M_F_CPU0_SB_DQ<2>")
	)
	(segment
		(start 268.274546 -282.229052)
		(end 268.419326 -282.373832)
		(width 0.14478)
		(layer "In11.Cu")
		(net "M_F_CPU0_SB_DQ<2>")
	)
	(segment
		(start 265.54811 -282.33497)
		(end 265.973306 -282.760166)
		(width 0.14478)
		(layer "In11.Cu")
		(net "M_F_CPU0_SB_DQ<2>")
	)
	(segment
		(start 330.119736 -274.568666)
		(end 330.128118 -274.573492)
		(width 0.0889)
		(layer "In11.Cu")
		(net "M_F_CPU0_SB_DQ<2>")
	)
	(segment
		(start 267.171678 -282.229052)
		(end 267.316458 -282.373832)
		(width 0.14478)
		(layer "In11.Cu")
		(net "M_F_CPU0_SB_DQ<2>")
	)
	(segment
		(start 294.19931 -282.760166)
		(end 297.213782 -282.760166)
		(width 0.14478)
		(layer "In11.Cu")
		(net "M_F_CPU0_SB_DQ<2>")
	)
	(segment
		(start 330.69403 -274.573492)
		(end 330.702412 -274.568666)
		(width 0.0889)
		(layer "In11.Cu")
		(net "M_F_CPU0_SB_DQ<2>")
	)
	(segment
		(start 304.597054 -282.760166)
		(end 305.447192 -281.910028)
		(width 0.14478)
		(layer "In11.Cu")
		(net "M_F_CPU0_SB_DQ<2>")
	)
	(segment
		(start 267.316458 -282.373832)
		(end 267.316458 -283.1465)
		(width 0.14478)
		(layer "In11.Cu")
		(net "M_F_CPU0_SB_DQ<2>")
	)
	(segment
		(start 323.925184 -273.67484)
		(end 325.442834 -273.67484)
		(width 0.0889)
		(layer "In11.Cu")
		(net "M_F_CPU0_SB_DQ<2>")
	)
	(segment
		(start 266.765024 -282.373832)
		(end 266.909804 -282.229052)
		(width 0.14478)
		(layer "In11.Cu")
		(net "M_F_CPU0_SB_DQ<2>")
	)
	(segment
		(start 283.028136 -281.910028)
		(end 285.703772 -281.910028)
		(width 0.14478)
		(layer "In11.Cu")
		(net "M_F_CPU0_SB_DQ<2>")
	)
	(segment
		(start 275.941536 -281.910028)
		(end 278.439372 -281.910028)
		(width 0.14478)
		(layer "In11.Cu")
		(net "M_F_CPU0_SB_DQ<2>")
	)
	(segment
		(start 267.867892 -283.1465)
		(end 267.867892 -282.373832)
		(width 0.14478)
		(layer "In11.Cu")
		(net "M_F_CPU0_SB_DQ<2>")
	)
	(segment
		(start 285.703772 -281.910028)
		(end 286.55391 -282.760166)
		(width 0.14478)
		(layer "In11.Cu")
		(net "M_F_CPU0_SB_DQ<2>")
	)
	(segment
		(start 327.874376 -274.573746)
		(end 327.890632 -274.564348)
		(width 0.0889)
		(layer "In11.Cu")
		(net "M_F_CPU0_SB_DQ<2>")
	)
	(segment
		(start 293.349172 -281.910028)
		(end 294.19931 -282.760166)
		(width 0.14478)
		(layer "In11.Cu")
		(net "M_F_CPU0_SB_DQ<2>")
	)
	(segment
		(start 332.511146 -274.605242)
		(end 332.607158 -274.630642)
		(width 0.0889)
		(layer "In11.Cu")
		(net "M_F_CPU0_SB_DQ<2>")
	)
	(segment
		(start 305.447192 -281.910028)
		(end 307.316632 -281.910028)
		(width 0.14478)
		(layer "In11.Cu")
		(net "M_F_CPU0_SB_DQ<2>")
	)
	(segment
		(start 332.607158 -274.630642)
		(end 332.761082 -274.896072)
		(width 0.0889)
		(layer "In11.Cu")
		(net "M_F_CPU0_SB_DQ<2>")
	)
	(segment
		(start 327.862438 -274.580604)
		(end 327.874376 -274.573746)
		(width 0.0889)
		(layer "In11.Cu")
		(net "M_F_CPU0_SB_DQ<2>")
	)
	(segment
		(start 307.316632 -281.910028)
		(end 315.55182 -273.67484)
		(width 0.14478)
		(layer "In11.Cu")
		(net "M_F_CPU0_SB_DQ<2>")
	)
	(segment
		(start 326.368918 -274.573746)
		(end 326.390508 -274.586192)
		(width 0.0889)
		(layer "In11.Cu")
		(net "M_F_CPU0_SB_DQ<2>")
	)
	(segment
		(start 268.564106 -282.760166)
		(end 275.091398 -282.760166)
		(width 0.14478)
		(layer "In11.Cu")
		(net "M_F_CPU0_SB_DQ<2>")
	)
	(segment
		(start 268.419326 -282.373832)
		(end 268.419326 -282.615386)
		(width 0.14478)
		(layer "In11.Cu")
		(net "M_F_CPU0_SB_DQ<2>")
	)
	(arc
		(start 327.890632 -274.564348)
		(mid 328.070614 -274.523248)
		(end 328.248264 -274.573492)
		(width 0.0889)
		(layer "In11.Cu")
		(net "M_F_CPU0_SB_DQ<2>")
	)
	(arc
		(start 326.252586 -274.484592)
		(mid 326.307836 -274.532974)
		(end 326.368918 -274.573746)
		(width 0.0889)
		(layer "In11.Cu")
		(net "M_F_CPU0_SB_DQ<2>")
	)
	(arc
		(start 328.248264 -274.573492)
		(mid 328.53122 -274.649669)
		(end 328.814176 -274.573492)
		(width 0.0889)
		(layer "In11.Cu")
		(net "M_F_CPU0_SB_DQ<2>")
	)
	(arc
		(start 329.188064 -274.573492)
		(mid 329.47102 -274.649669)
		(end 329.753976 -274.573492)
		(width 0.0889)
		(layer "In11.Cu")
		(net "M_F_CPU0_SB_DQ<2>")
	)
	(arc
		(start 330.128118 -274.573492)
		(mid 330.411074 -274.649669)
		(end 330.69403 -274.573492)
		(width 0.0889)
		(layer "In11.Cu")
		(net "M_F_CPU0_SB_DQ<2>")
	)
	(arc
		(start 330.702412 -274.568666)
		(mid 330.88592 -274.523172)
		(end 331.068172 -274.573492)
		(width 0.0889)
		(layer "In11.Cu")
		(net "M_F_CPU0_SB_DQ<2>")
	)
	(arc
		(start 326.93483 -274.573492)
		(mid 327.115288 -274.523048)
		(end 327.297542 -274.566634)
		(width 0.0889)
		(layer "In11.Cu")
		(net "M_F_CPU0_SB_DQ<2>")
	)
	(arc
		(start 327.309226 -274.573492)
		(mid 327.584904 -274.649622)
		(end 327.862438 -274.580604)
		(width 0.0889)
		(layer "In11.Cu")
		(net "M_F_CPU0_SB_DQ<2>")
	)
	(arc
		(start 328.814176 -274.573492)
		(mid 329.00112 -274.523237)
		(end 329.188064 -274.573492)
		(width 0.0889)
		(layer "In11.Cu")
		(net "M_F_CPU0_SB_DQ<2>")
	)
	(arc
		(start 329.753976 -274.573492)
		(mid 329.936227 -274.523142)
		(end 330.119736 -274.568666)
		(width 0.0889)
		(layer "In11.Cu")
		(net "M_F_CPU0_SB_DQ<2>")
	)
	(arc
		(start 331.642466 -274.568666)
		(mid 331.825974 -274.523172)
		(end 332.008226 -274.573492)
		(width 0.0889)
		(layer "In11.Cu")
		(net "M_F_CPU0_SB_DQ<2>")
	)
	(arc
		(start 331.068172 -274.573492)
		(mid 331.351128 -274.649669)
		(end 331.634084 -274.573492)
		(width 0.0889)
		(layer "In11.Cu")
		(net "M_F_CPU0_SB_DQ<2>")
	)
	(arc
		(start 326.390508 -274.586192)
		(mid 326.664298 -274.649863)
		(end 326.93483 -274.573492)
		(width 0.0889)
		(layer "In11.Cu")
		(net "M_F_CPU0_SB_DQ<2>")
	)
	(arc
		(start 332.008226 -274.573492)
		(mid 332.255939 -274.648712)
		(end 332.511146 -274.605242)
		(width 0.0889)
		(layer "In11.Cu")
		(net "M_F_CPU0_SB_DQ<2>")
	)
	(segment
		(start 334.167988 -292.450012)
		(end 333.701136 -292.71595)
		(width 0.10668)
		(layer "F.Cu")
		(net "M_F_CPU0_SB_DQ<29>")
	)
	(segment
		(start 328.248264 -294.658542)
		(end 328.211942 -294.679624)
		(width 0.0889)
		(layer "In11.Cu")
		(net "M_F_CPU0_SB_DQ<29>")
	)
	(segment
		(start 270.68653 -317.99276)
		(end 270.455898 -317.99276)
		(width 0.14478)
		(layer "In11.Cu")
		(net "M_F_CPU0_SB_DQ<29>")
	)
	(segment
		(start 310.23941 -315.607954)
		(end 308.237128 -317.610236)
		(width 0.14478)
		(layer "In11.Cu")
		(net "M_F_CPU0_SB_DQ<29>")
	)
	(segment
		(start 275.327618 -317.216282)
		(end 275.164804 -317.379096)
		(width 0.14478)
		(layer "In11.Cu")
		(net "M_F_CPU0_SB_DQ<29>")
	)
	(segment
		(start 276.277324 -317.43777)
		(end 276.277324 -317.879476)
		(width 0.14478)
		(layer "In11.Cu")
		(net "M_F_CPU0_SB_DQ<29>")
	)
	(segment
		(start 272.124678 -317.220092)
		(end 271.961864 -317.382906)
		(width 0.14478)
		(layer "In11.Cu")
		(net "M_F_CPU0_SB_DQ<29>")
	)
	(segment
		(start 271.405604 -317.382906)
		(end 271.24279 -317.220092)
		(width 0.14478)
		(layer "In11.Cu")
		(net "M_F_CPU0_SB_DQ<29>")
	)
	(segment
		(start 327.30821 -296.278554)
		(end 327.30821 -296.783506)
		(width 0.0889)
		(layer "In11.Cu")
		(net "M_F_CPU0_SB_DQ<29>")
	)
	(segment
		(start 273.33321 -317.610236)
		(end 272.745454 -317.610236)
		(width 0.14478)
		(layer "In11.Cu")
		(net "M_F_CPU0_SB_DQ<29>")
	)
	(segment
		(start 279.240488 -317.92037)
		(end 278.930354 -317.610236)
		(width 0.14478)
		(layer "In11.Cu")
		(net "M_F_CPU0_SB_DQ<29>")
	)
	(segment
		(start 276.996398 -317.610236)
		(end 276.665944 -317.279782)
		(width 0.14478)
		(layer "In11.Cu")
		(net "M_F_CPU0_SB_DQ<29>")
	)
	(segment
		(start 327.340976 -296.259504)
		(end 327.30821 -296.278554)
		(width 0.0889)
		(layer "In11.Cu")
		(net "M_F_CPU0_SB_DQ<29>")
	)
	(segment
		(start 271.24279 -317.220092)
		(end 271.012158 -317.220092)
		(width 0.14478)
		(layer "In11.Cu")
		(net "M_F_CPU0_SB_DQ<29>")
	)
	(segment
		(start 305.694842 -317.369952)
		(end 305.454558 -317.610236)
		(width 0.14478)
		(layer "In11.Cu")
		(net "M_F_CPU0_SB_DQ<29>")
	)
	(segment
		(start 281.503374 -317.91275)
		(end 281.20086 -317.610236)
		(width 0.14478)
		(layer "In11.Cu")
		(net "M_F_CPU0_SB_DQ<29>")
	)
	(segment
		(start 275.00199 -318.04229)
		(end 274.771358 -318.04229)
		(width 0.14478)
		(layer "In11.Cu")
		(net "M_F_CPU0_SB_DQ<29>")
	)
	(segment
		(start 274.771358 -318.04229)
		(end 274.608544 -317.879476)
		(width 0.14478)
		(layer "In11.Cu")
		(net "M_F_CPU0_SB_DQ<29>")
	)
	(segment
		(start 327.778364 -295.468548)
		(end 327.739248 -295.491408)
		(width 0.0889)
		(layer "In11.Cu")
		(net "M_F_CPU0_SB_DQ<29>")
	)
	(segment
		(start 332.948026 -293.03853)
		(end 332.939644 -293.043356)
		(width 0.0889)
		(layer "In11.Cu")
		(net "M_F_CPU0_SB_DQ<29>")
	)
	(segment
		(start 281.20086 -317.610236)
		(end 279.796748 -317.610236)
		(width 0.14478)
		(layer "In11.Cu")
		(net "M_F_CPU0_SB_DQ<29>")
	)
	(segment
		(start 330.702412 -293.043356)
		(end 330.69403 -293.03853)
		(width 0.0889)
		(layer "In11.Cu")
		(net "M_F_CPU0_SB_DQ<29>")
	)
	(segment
		(start 273.662648 -317.939674)
		(end 273.33321 -317.610236)
		(width 0.14478)
		(layer "In11.Cu")
		(net "M_F_CPU0_SB_DQ<29>")
	)
	(segment
		(start 271.79905 -317.99276)
		(end 271.568418 -317.99276)
		(width 0.14478)
		(layer "In11.Cu")
		(net "M_F_CPU0_SB_DQ<29>")
	)
	(segment
		(start 271.405604 -317.829946)
		(end 271.405604 -317.382906)
		(width 0.14478)
		(layer "In11.Cu")
		(net "M_F_CPU0_SB_DQ<29>")
	)
	(segment
		(start 330.128118 -293.03853)
		(end 330.127864 -293.03853)
		(width 0.0889)
		(layer "In11.Cu")
		(net "M_F_CPU0_SB_DQ<29>")
	)
	(segment
		(start 276.277324 -317.879476)
		(end 276.11451 -318.04229)
		(width 0.14478)
		(layer "In11.Cu")
		(net "M_F_CPU0_SB_DQ<29>")
	)
	(segment
		(start 272.35531 -317.220092)
		(end 272.124678 -317.220092)
		(width 0.14478)
		(layer "In11.Cu")
		(net "M_F_CPU0_SB_DQ<29>")
	)
	(segment
		(start 274.052284 -317.78067)
		(end 273.89328 -317.939674)
		(width 0.14478)
		(layer "In11.Cu")
		(net "M_F_CPU0_SB_DQ<29>")
	)
	(segment
		(start 329.188318 -293.03853)
		(end 329.185778 -293.040054)
		(width 0.0889)
		(layer "In11.Cu")
		(net "M_F_CPU0_SB_DQ<29>")
	)
	(segment
		(start 275.721064 -317.379096)
		(end 275.55825 -317.216282)
		(width 0.14478)
		(layer "In11.Cu")
		(net "M_F_CPU0_SB_DQ<29>")
	)
	(segment
		(start 327.30821 -296.783506)
		(end 310.23941 -313.852306)
		(width 0.14478)
		(layer "In11.Cu")
		(net "M_F_CPU0_SB_DQ<29>")
	)
	(segment
		(start 271.961864 -317.382906)
		(end 271.961864 -317.829946)
		(width 0.14478)
		(layer "In11.Cu")
		(net "M_F_CPU0_SB_DQ<29>")
	)
	(segment
		(start 327.810114 -295.45026)
		(end 327.778364 -295.468548)
		(width 0.0889)
		(layer "In11.Cu")
		(net "M_F_CPU0_SB_DQ<29>")
	)
	(segment
		(start 271.012158 -317.220092)
		(end 270.849344 -317.382906)
		(width 0.14478)
		(layer "In11.Cu")
		(net "M_F_CPU0_SB_DQ<29>")
	)
	(segment
		(start 279.796748 -317.610236)
		(end 279.486614 -317.92037)
		(width 0.14478)
		(layer "In11.Cu")
		(net "M_F_CPU0_SB_DQ<29>")
	)
	(segment
		(start 273.89328 -317.939674)
		(end 273.662648 -317.939674)
		(width 0.14478)
		(layer "In11.Cu")
		(net "M_F_CPU0_SB_DQ<29>")
	)
	(segment
		(start 333.701136 -292.71595)
		(end 333.85506 -292.98138)
		(width 0.0889)
		(layer "In11.Cu")
		(net "M_F_CPU0_SB_DQ<29>")
	)
	(segment
		(start 274.052284 -317.379096)
		(end 274.052284 -317.78067)
		(width 0.14478)
		(layer "In11.Cu")
		(net "M_F_CPU0_SB_DQ<29>")
	)
	(segment
		(start 278.127968 -317.92037)
		(end 277.817834 -317.610236)
		(width 0.14478)
		(layer "In11.Cu")
		(net "M_F_CPU0_SB_DQ<29>")
	)
	(segment
		(start 281.75712 -317.91275)
		(end 281.503374 -317.91275)
		(width 0.14478)
		(layer "In11.Cu")
		(net "M_F_CPU0_SB_DQ<29>")
	)
	(segment
		(start 274.608544 -317.379096)
		(end 274.44573 -317.216282)
		(width 0.14478)
		(layer "In11.Cu")
		(net "M_F_CPU0_SB_DQ<29>")
	)
	(segment
		(start 274.215098 -317.216282)
		(end 274.052284 -317.379096)
		(width 0.14478)
		(layer "In11.Cu")
		(net "M_F_CPU0_SB_DQ<29>")
	)
	(segment
		(start 278.374094 -317.92037)
		(end 278.127968 -317.92037)
		(width 0.14478)
		(layer "In11.Cu")
		(net "M_F_CPU0_SB_DQ<29>")
	)
	(segment
		(start 306.246276 -317.610236)
		(end 306.005992 -317.369952)
		(width 0.14478)
		(layer "In11.Cu")
		(net "M_F_CPU0_SB_DQ<29>")
	)
	(segment
		(start 278.930354 -317.610236)
		(end 278.684228 -317.610236)
		(width 0.14478)
		(layer "In11.Cu")
		(net "M_F_CPU0_SB_DQ<29>")
	)
	(segment
		(start 275.55825 -317.216282)
		(end 275.327618 -317.216282)
		(width 0.14478)
		(layer "In11.Cu")
		(net "M_F_CPU0_SB_DQ<29>")
	)
	(segment
		(start 276.665944 -317.279782)
		(end 276.435312 -317.279782)
		(width 0.14478)
		(layer "In11.Cu")
		(net "M_F_CPU0_SB_DQ<29>")
	)
	(segment
		(start 275.883878 -318.04229)
		(end 275.721064 -317.879476)
		(width 0.14478)
		(layer "In11.Cu")
		(net "M_F_CPU0_SB_DQ<29>")
	)
	(segment
		(start 328.718164 -293.848536)
		(end 328.679048 -293.871396)
		(width 0.0889)
		(layer "In11.Cu")
		(net "M_F_CPU0_SB_DQ<29>")
	)
	(segment
		(start 275.164804 -317.879476)
		(end 275.00199 -318.04229)
		(width 0.14478)
		(layer "In11.Cu")
		(net "M_F_CPU0_SB_DQ<29>")
	)
	(segment
		(start 274.608544 -317.879476)
		(end 274.608544 -317.379096)
		(width 0.14478)
		(layer "In11.Cu")
		(net "M_F_CPU0_SB_DQ<29>")
	)
	(segment
		(start 277.817834 -317.610236)
		(end 276.996398 -317.610236)
		(width 0.14478)
		(layer "In11.Cu")
		(net "M_F_CPU0_SB_DQ<29>")
	)
	(segment
		(start 328.278744 -294.640762)
		(end 328.248264 -294.658542)
		(width 0.0889)
		(layer "In11.Cu")
		(net "M_F_CPU0_SB_DQ<29>")
	)
	(segment
		(start 305.454558 -317.610236)
		(end 282.059634 -317.610236)
		(width 0.14478)
		(layer "In11.Cu")
		(net "M_F_CPU0_SB_DQ<29>")
	)
	(segment
		(start 282.059634 -317.610236)
		(end 281.75712 -317.91275)
		(width 0.14478)
		(layer "In11.Cu")
		(net "M_F_CPU0_SB_DQ<29>")
	)
	(segment
		(start 306.005992 -317.369952)
		(end 305.694842 -317.369952)
		(width 0.14478)
		(layer "In11.Cu")
		(net "M_F_CPU0_SB_DQ<29>")
	)
	(segment
		(start 274.44573 -317.216282)
		(end 274.215098 -317.216282)
		(width 0.14478)
		(layer "In11.Cu")
		(net "M_F_CPU0_SB_DQ<29>")
	)
	(segment
		(start 278.684228 -317.610236)
		(end 278.374094 -317.92037)
		(width 0.14478)
		(layer "In11.Cu")
		(net "M_F_CPU0_SB_DQ<29>")
	)
	(segment
		(start 272.745454 -317.610236)
		(end 272.35531 -317.220092)
		(width 0.14478)
		(layer "In11.Cu")
		(net "M_F_CPU0_SB_DQ<29>")
	)
	(segment
		(start 333.85506 -292.98138)
		(end 333.832708 -293.064692)
		(width 0.0889)
		(layer "In11.Cu")
		(net "M_F_CPU0_SB_DQ<29>")
	)
	(segment
		(start 328.720958 -293.846758)
		(end 328.718164 -293.848536)
		(width 0.0889)
		(layer "In11.Cu")
		(net "M_F_CPU0_SB_DQ<29>")
	)
	(segment
		(start 270.455898 -317.99276)
		(end 269.648178 -317.18504)
		(width 0.14478)
		(layer "In11.Cu")
		(net "M_F_CPU0_SB_DQ<29>")
	)
	(segment
		(start 275.721064 -317.879476)
		(end 275.721064 -317.379096)
		(width 0.14478)
		(layer "In11.Cu")
		(net "M_F_CPU0_SB_DQ<29>")
	)
	(segment
		(start 279.486614 -317.92037)
		(end 279.240488 -317.92037)
		(width 0.14478)
		(layer "In11.Cu")
		(net "M_F_CPU0_SB_DQ<29>")
	)
	(segment
		(start 275.164804 -317.379096)
		(end 275.164804 -317.879476)
		(width 0.14478)
		(layer "In11.Cu")
		(net "M_F_CPU0_SB_DQ<29>")
	)
	(segment
		(start 308.237128 -317.610236)
		(end 306.246276 -317.610236)
		(width 0.14478)
		(layer "In11.Cu")
		(net "M_F_CPU0_SB_DQ<29>")
	)
	(segment
		(start 276.435312 -317.279782)
		(end 276.277324 -317.43777)
		(width 0.14478)
		(layer "In11.Cu")
		(net "M_F_CPU0_SB_DQ<29>")
	)
	(segment
		(start 271.961864 -317.829946)
		(end 271.79905 -317.99276)
		(width 0.14478)
		(layer "In11.Cu")
		(net "M_F_CPU0_SB_DQ<29>")
	)
	(segment
		(start 276.11451 -318.04229)
		(end 275.883878 -318.04229)
		(width 0.14478)
		(layer "In11.Cu")
		(net "M_F_CPU0_SB_DQ<29>")
	)
	(segment
		(start 271.568418 -317.99276)
		(end 271.405604 -317.829946)
		(width 0.14478)
		(layer "In11.Cu")
		(net "M_F_CPU0_SB_DQ<29>")
	)
	(segment
		(start 310.23941 -313.852306)
		(end 310.23941 -315.607954)
		(width 0.14478)
		(layer "In11.Cu")
		(net "M_F_CPU0_SB_DQ<29>")
	)
	(segment
		(start 270.849344 -317.829946)
		(end 270.68653 -317.99276)
		(width 0.14478)
		(layer "In11.Cu")
		(net "M_F_CPU0_SB_DQ<29>")
	)
	(segment
		(start 270.849344 -317.382906)
		(end 270.849344 -317.829946)
		(width 0.14478)
		(layer "In11.Cu")
		(net "M_F_CPU0_SB_DQ<29>")
	)
	(arc
		(start 328.211942 -294.679624)
		(mid 328.03129 -294.882369)
		(end 327.96607 -295.145968)
		(width 0.0889)
		(layer "In11.Cu")
		(net "M_F_CPU0_SB_DQ<29>")
	)
	(arc
		(start 330.127864 -293.03853)
		(mid 329.94092 -293.088854)
		(end 329.753976 -293.03853)
		(width 0.0889)
		(layer "In11.Cu")
		(net "M_F_CPU0_SB_DQ<29>")
	)
	(arc
		(start 331.634084 -293.03853)
		(mid 331.351128 -292.962353)
		(end 331.068172 -293.03853)
		(width 0.0889)
		(layer "In11.Cu")
		(net "M_F_CPU0_SB_DQ<29>")
	)
	(arc
		(start 333.832708 -293.064692)
		(mid 333.670376 -293.08751)
		(end 333.513938 -293.03853)
		(width 0.0889)
		(layer "In11.Cu")
		(net "M_F_CPU0_SB_DQ<29>")
	)
	(arc
		(start 328.679048 -293.871396)
		(mid 328.500235 -294.073746)
		(end 328.435716 -294.335962)
		(width 0.0889)
		(layer "In11.Cu")
		(net "M_F_CPU0_SB_DQ<29>")
	)
	(arc
		(start 327.739248 -295.491408)
		(mid 327.560435 -295.693758)
		(end 327.495916 -295.955974)
		(width 0.0889)
		(layer "In11.Cu")
		(net "M_F_CPU0_SB_DQ<29>")
	)
	(arc
		(start 328.90587 -293.525956)
		(mid 328.856341 -293.711109)
		(end 328.720958 -293.846758)
		(width 0.0889)
		(layer "In11.Cu")
		(net "M_F_CPU0_SB_DQ<29>")
	)
	(arc
		(start 331.068172 -293.03853)
		(mid 330.885921 -293.08888)
		(end 330.702412 -293.043356)
		(width 0.0889)
		(layer "In11.Cu")
		(net "M_F_CPU0_SB_DQ<29>")
	)
	(arc
		(start 327.96607 -295.145968)
		(mid 327.924815 -295.316939)
		(end 327.810114 -295.45026)
		(width 0.0889)
		(layer "In11.Cu")
		(net "M_F_CPU0_SB_DQ<29>")
	)
	(arc
		(start 333.513938 -293.03853)
		(mid 333.230982 -292.962353)
		(end 332.948026 -293.03853)
		(width 0.0889)
		(layer "In11.Cu")
		(net "M_F_CPU0_SB_DQ<29>")
	)
	(arc
		(start 329.753976 -293.03853)
		(mid 329.471164 -292.962481)
		(end 329.188318 -293.03853)
		(width 0.0889)
		(layer "In11.Cu")
		(net "M_F_CPU0_SB_DQ<29>")
	)
	(arc
		(start 332.573884 -293.03853)
		(mid 332.290928 -292.962353)
		(end 332.007972 -293.03853)
		(width 0.0889)
		(layer "In11.Cu")
		(net "M_F_CPU0_SB_DQ<29>")
	)
	(arc
		(start 332.007972 -293.03853)
		(mid 331.821028 -293.088785)
		(end 331.634084 -293.03853)
		(width 0.0889)
		(layer "In11.Cu")
		(net "M_F_CPU0_SB_DQ<29>")
	)
	(arc
		(start 330.69403 -293.03853)
		(mid 330.411074 -292.962353)
		(end 330.128118 -293.03853)
		(width 0.0889)
		(layer "In11.Cu")
		(net "M_F_CPU0_SB_DQ<29>")
	)
	(arc
		(start 329.185778 -293.040054)
		(mid 328.980814 -293.245564)
		(end 328.90587 -293.525956)
		(width 0.0889)
		(layer "In11.Cu")
		(net "M_F_CPU0_SB_DQ<29>")
	)
	(arc
		(start 332.939644 -293.043356)
		(mid 332.756136 -293.08885)
		(end 332.573884 -293.03853)
		(width 0.0889)
		(layer "In11.Cu")
		(net "M_F_CPU0_SB_DQ<29>")
	)
	(arc
		(start 328.435716 -294.335962)
		(mid 328.394167 -294.507384)
		(end 328.278744 -294.640762)
		(width 0.0889)
		(layer "In11.Cu")
		(net "M_F_CPU0_SB_DQ<29>")
	)
	(arc
		(start 327.495916 -295.955974)
		(mid 327.45495 -296.12638)
		(end 327.340976 -296.259504)
		(width 0.0889)
		(layer "In11.Cu")
		(net "M_F_CPU0_SB_DQ<29>")
	)
	(segment
		(start 332.758034 -291.640006)
		(end 332.291182 -291.905944)
		(width 0.10668)
		(layer "F.Cu")
		(net "M_F_CPU0_SB_DQ<28>")
	)
	(segment
		(start 297.20921 -315.910214)
		(end 296.971466 -315.910214)
		(width 0.14478)
		(layer "In11.Cu")
		(net "M_F_CPU0_SB_DQ<28>")
	)
	(segment
		(start 332.291182 -291.905944)
		(end 332.445106 -292.171374)
		(width 0.0889)
		(layer "In11.Cu")
		(net "M_F_CPU0_SB_DQ<28>")
	)
	(segment
		(start 329.292458 -292.23335)
		(end 329.284076 -292.228524)
		(width 0.0889)
		(layer "In11.Cu")
		(net "M_F_CPU0_SB_DQ<28>")
	)
	(segment
		(start 276.867112 -315.910214)
		(end 276.393656 -315.436758)
		(width 0.14478)
		(layer "In11.Cu")
		(net "M_F_CPU0_SB_DQ<28>")
	)
	(segment
		(start 278.168354 -315.910214)
		(end 277.933658 -316.14491)
		(width 0.14478)
		(layer "In11.Cu")
		(net "M_F_CPU0_SB_DQ<28>")
	)
	(segment
		(start 327.33869 -293.02075)
		(end 327.30821 -293.03853)
		(width 0.0889)
		(layer "In11.Cu")
		(net "M_F_CPU0_SB_DQ<28>")
	)
	(segment
		(start 275.03247 -315.566552)
		(end 274.88769 -315.711332)
		(width 0.14478)
		(layer "In11.Cu")
		(net "M_F_CPU0_SB_DQ<28>")
	)
	(segment
		(start 296.415206 -316.22873)
		(end 296.106342 -315.919866)
		(width 0.14478)
		(layer "In11.Cu")
		(net "M_F_CPU0_SB_DQ<28>")
	)
	(segment
		(start 283.191712 -315.910214)
		(end 282.933648 -315.910214)
		(width 0.14478)
		(layer "In11.Cu")
		(net "M_F_CPU0_SB_DQ<28>")
	)
	(segment
		(start 281.264868 -316.20841)
		(end 280.976324 -315.919866)
		(width 0.14478)
		(layer "In11.Cu")
		(net "M_F_CPU0_SB_DQ<28>")
	)
	(segment
		(start 300.542706 -316.19825)
		(end 300.25467 -315.910214)
		(width 0.14478)
		(layer "In11.Cu")
		(net "M_F_CPU0_SB_DQ<28>")
	)
	(segment
		(start 279.211278 -315.97981)
		(end 279.046178 -316.14491)
		(width 0.14478)
		(layer "In11.Cu")
		(net "M_F_CPU0_SB_DQ<28>")
	)
	(segment
		(start 289.644074 -315.910214)
		(end 289.39871 -315.910214)
		(width 0.14478)
		(layer "In11.Cu")
		(net "M_F_CPU0_SB_DQ<28>")
	)
	(segment
		(start 271.810988 -316.304676)
		(end 271.580356 -316.304676)
		(width 0.14478)
		(layer "In11.Cu")
		(net "M_F_CPU0_SB_DQ<28>")
	)
	(segment
		(start 274.88769 -316.134496)
		(end 274.724876 -316.29731)
		(width 0.14478)
		(layer "In11.Cu")
		(net "M_F_CPU0_SB_DQ<28>")
	)
	(segment
		(start 296.65295 -316.22873)
		(end 296.415206 -316.22873)
		(width 0.14478)
		(layer "In11.Cu")
		(net "M_F_CPU0_SB_DQ<28>")
	)
	(segment
		(start 286.301688 -315.910214)
		(end 286.056324 -315.910214)
		(width 0.14478)
		(layer "In11.Cu")
		(net "M_F_CPU0_SB_DQ<28>")
	)
	(segment
		(start 286.056324 -315.910214)
		(end 285.745428 -316.22111)
		(width 0.14478)
		(layer "In11.Cu")
		(net "M_F_CPU0_SB_DQ<28>")
	)
	(segment
		(start 289.95497 -316.22111)
		(end 289.644074 -315.910214)
		(width 0.14478)
		(layer "In11.Cu")
		(net "M_F_CPU0_SB_DQ<28>")
	)
	(segment
		(start 298.32173 -315.910214)
		(end 298.083986 -315.910214)
		(width 0.14478)
		(layer "In11.Cu")
		(net "M_F_CPU0_SB_DQ<28>")
	)
	(segment
		(start 308.814216 -314.210192)
		(end 309.23357 -314.629546)
		(width 0.14478)
		(layer "In11.Cu")
		(net "M_F_CPU0_SB_DQ<28>")
	)
	(segment
		(start 298.640246 -316.22873)
		(end 298.32173 -315.910214)
		(width 0.14478)
		(layer "In11.Cu")
		(net "M_F_CPU0_SB_DQ<28>")
	)
	(segment
		(start 276.00021 -315.599572)
		(end 276.00021 -316.139576)
		(width 0.14478)
		(layer "In11.Cu")
		(net "M_F_CPU0_SB_DQ<28>")
	)
	(segment
		(start 309.048404 -315.019436)
		(end 308.84368 -315.019436)
		(width 0.14478)
		(layer "In11.Cu")
		(net "M_F_CPU0_SB_DQ<28>")
	)
	(segment
		(start 289.39871 -315.910214)
		(end 289.087814 -316.22111)
		(width 0.14478)
		(layer "In11.Cu")
		(net "M_F_CPU0_SB_DQ<28>")
	)
	(segment
		(start 328.718164 -292.228524)
		(end 328.71791 -292.228524)
		(width 0.0889)
		(layer "In11.Cu")
		(net "M_F_CPU0_SB_DQ<28>")
	)
	(segment
		(start 282.933648 -315.910214)
		(end 282.635452 -316.20841)
		(width 0.14478)
		(layer "In11.Cu")
		(net "M_F_CPU0_SB_DQ<28>")
	)
	(segment
		(start 282.635452 -316.20841)
		(end 282.377388 -316.20841)
		(width 0.14478)
		(layer "In11.Cu")
		(net "M_F_CPU0_SB_DQ<28>")
	)
	(segment
		(start 275.44395 -315.711332)
		(end 275.29917 -315.566552)
		(width 0.14478)
		(layer "In11.Cu")
		(net "M_F_CPU0_SB_DQ<28>")
	)
	(segment
		(start 292.72992 -315.910214)
		(end 291.62375 -315.910214)
		(width 0.14478)
		(layer "In11.Cu")
		(net "M_F_CPU0_SB_DQ<28>")
	)
	(segment
		(start 326.185276 -294.885618)
		(end 326.185276 -295.789858)
		(width 0.0889)
		(layer "In11.Cu")
		(net "M_F_CPU0_SB_DQ<28>")
	)
	(segment
		(start 299.196506 -315.910214)
		(end 298.87799 -316.22873)
		(width 0.14478)
		(layer "In11.Cu")
		(net "M_F_CPU0_SB_DQ<28>")
	)
	(segment
		(start 296.971466 -315.910214)
		(end 296.65295 -316.22873)
		(width 0.14478)
		(layer "In11.Cu")
		(net "M_F_CPU0_SB_DQ<28>")
	)
	(segment
		(start 294.130476 -316.19825)
		(end 293.912036 -315.97981)
		(width 0.14478)
		(layer "In11.Cu")
		(net "M_F_CPU0_SB_DQ<28>")
	)
	(segment
		(start 279.837134 -316.14491)
		(end 279.672034 -315.97981)
		(width 0.14478)
		(layer "In11.Cu")
		(net "M_F_CPU0_SB_DQ<28>")
	)
	(segment
		(start 277.933658 -316.14491)
		(end 277.612094 -316.14491)
		(width 0.14478)
		(layer "In11.Cu")
		(net "M_F_CPU0_SB_DQ<28>")
	)
	(segment
		(start 289.087814 -316.22111)
		(end 288.84245 -316.22111)
		(width 0.14478)
		(layer "In11.Cu")
		(net "M_F_CPU0_SB_DQ<28>")
	)
	(segment
		(start 271.417542 -315.75629)
		(end 271.254728 -315.593476)
		(width 0.14478)
		(layer "In11.Cu")
		(net "M_F_CPU0_SB_DQ<28>")
	)
	(segment
		(start 293.28618 -316.19825)
		(end 293.017956 -316.19825)
		(width 0.14478)
		(layer "In11.Cu")
		(net "M_F_CPU0_SB_DQ<28>")
	)
	(segment
		(start 306.449222 -315.910214)
		(end 301.098966 -315.910214)
		(width 0.14478)
		(layer "In11.Cu")
		(net "M_F_CPU0_SB_DQ<28>")
	)
	(segment
		(start 297.527726 -316.22873)
		(end 297.20921 -315.910214)
		(width 0.14478)
		(layer "In11.Cu")
		(net "M_F_CPU0_SB_DQ<28>")
	)
	(segment
		(start 270.467836 -316.304676)
		(end 269.648178 -315.485018)
		(width 0.14478)
		(layer "In11.Cu")
		(net "M_F_CPU0_SB_DQ<28>")
	)
	(segment
		(start 270.861282 -315.75629)
		(end 270.861282 -316.141862)
		(width 0.14478)
		(layer "In11.Cu")
		(net "M_F_CPU0_SB_DQ<28>")
	)
	(segment
		(start 300.25467 -315.910214)
		(end 299.196506 -315.910214)
		(width 0.14478)
		(layer "In11.Cu")
		(net "M_F_CPU0_SB_DQ<28>")
	)
	(segment
		(start 271.024096 -315.593476)
		(end 270.861282 -315.75629)
		(width 0.14478)
		(layer "In11.Cu")
		(net "M_F_CPU0_SB_DQ<28>")
	)
	(segment
		(start 294.677084 -315.919866)
		(end 294.3987 -316.19825)
		(width 0.14478)
		(layer "In11.Cu")
		(net "M_F_CPU0_SB_DQ<28>")
	)
	(segment
		(start 279.046178 -316.14491)
		(end 278.724614 -316.14491)
		(width 0.14478)
		(layer "In11.Cu")
		(net "M_F_CPU0_SB_DQ<28>")
	)
	(segment
		(start 288.541206 -315.919866)
		(end 287.159192 -315.919866)
		(width 0.14478)
		(layer "In11.Cu")
		(net "M_F_CPU0_SB_DQ<28>")
	)
	(segment
		(start 279.672034 -315.97981)
		(end 279.211278 -315.97981)
		(width 0.14478)
		(layer "In11.Cu")
		(net "M_F_CPU0_SB_DQ<28>")
	)
	(segment
		(start 293.017956 -316.19825)
		(end 292.72992 -315.910214)
		(width 0.14478)
		(layer "In11.Cu")
		(net "M_F_CPU0_SB_DQ<28>")
	)
	(segment
		(start 281.522932 -316.20841)
		(end 281.264868 -316.20841)
		(width 0.14478)
		(layer "In11.Cu")
		(net "M_F_CPU0_SB_DQ<28>")
	)
	(segment
		(start 282.079192 -315.910214)
		(end 281.821128 -315.910214)
		(width 0.14478)
		(layer "In11.Cu")
		(net "M_F_CPU0_SB_DQ<28>")
	)
	(segment
		(start 326.838056 -293.848536)
		(end 326.80021 -293.87038)
		(width 0.0889)
		(layer "In11.Cu")
		(net "M_F_CPU0_SB_DQ<28>")
	)
	(segment
		(start 282.377388 -316.20841)
		(end 282.079192 -315.910214)
		(width 0.14478)
		(layer "In11.Cu")
		(net "M_F_CPU0_SB_DQ<28>")
	)
	(segment
		(start 285.745428 -316.22111)
		(end 285.500064 -316.22111)
		(width 0.14478)
		(layer "In11.Cu")
		(net "M_F_CPU0_SB_DQ<28>")
	)
	(segment
		(start 277.612094 -316.14491)
		(end 277.377398 -315.910214)
		(width 0.14478)
		(layer "In11.Cu")
		(net "M_F_CPU0_SB_DQ<28>")
	)
	(segment
		(start 308.219602 -314.600082)
		(end 307.553868 -315.265816)
		(width 0.14478)
		(layer "In11.Cu")
		(net "M_F_CPU0_SB_DQ<28>")
	)
	(segment
		(start 331.538072 -292.228524)
		(end 331.52969 -292.23335)
		(width 0.0889)
		(layer "In11.Cu")
		(net "M_F_CPU0_SB_DQ<28>")
	)
	(segment
		(start 293.50462 -315.97981)
		(end 293.28618 -316.19825)
		(width 0.14478)
		(layer "In11.Cu")
		(net "M_F_CPU0_SB_DQ<28>")
	)
	(segment
		(start 326.398636 -294.640762)
		(end 326.367902 -294.658542)
		(width 0.0889)
		(layer "In11.Cu")
		(net "M_F_CPU0_SB_DQ<28>")
	)
	(segment
		(start 294.3987 -316.19825)
		(end 294.130476 -316.19825)
		(width 0.14478)
		(layer "In11.Cu")
		(net "M_F_CPU0_SB_DQ<28>")
	)
	(segment
		(start 327.77811 -292.228524)
		(end 327.77557 -292.230048)
		(width 0.0889)
		(layer "In11.Cu")
		(net "M_F_CPU0_SB_DQ<28>")
	)
	(segment
		(start 270.698468 -316.304676)
		(end 270.467836 -316.304676)
		(width 0.14478)
		(layer "In11.Cu")
		(net "M_F_CPU0_SB_DQ<28>")
	)
	(segment
		(start 274.1168 -315.919866)
		(end 272.195798 -315.919866)
		(width 0.14478)
		(layer "In11.Cu")
		(net "M_F_CPU0_SB_DQ<28>")
	)
	(segment
		(start 288.84245 -316.22111)
		(end 288.541206 -315.919866)
		(width 0.14478)
		(layer "In11.Cu")
		(net "M_F_CPU0_SB_DQ<28>")
	)
	(segment
		(start 293.912036 -315.97981)
		(end 293.50462 -315.97981)
		(width 0.14478)
		(layer "In11.Cu")
		(net "M_F_CPU0_SB_DQ<28>")
	)
	(segment
		(start 280.976324 -315.919866)
		(end 280.383742 -315.919866)
		(width 0.14478)
		(layer "In11.Cu")
		(net "M_F_CPU0_SB_DQ<28>")
	)
	(segment
		(start 271.417542 -316.141862)
		(end 271.417542 -315.75629)
		(width 0.14478)
		(layer "In11.Cu")
		(net "M_F_CPU0_SB_DQ<28>")
	)
	(segment
		(start 271.254728 -315.593476)
		(end 271.024096 -315.593476)
		(width 0.14478)
		(layer "In11.Cu")
		(net "M_F_CPU0_SB_DQ<28>")
	)
	(segment
		(start 286.612584 -316.22111)
		(end 286.301688 -315.910214)
		(width 0.14478)
		(layer "In11.Cu")
		(net "M_F_CPU0_SB_DQ<28>")
	)
	(segment
		(start 281.821128 -315.910214)
		(end 281.522932 -316.20841)
		(width 0.14478)
		(layer "In11.Cu")
		(net "M_F_CPU0_SB_DQ<28>")
	)
	(segment
		(start 278.489918 -315.910214)
		(end 278.168354 -315.910214)
		(width 0.14478)
		(layer "In11.Cu")
		(net "M_F_CPU0_SB_DQ<28>")
	)
	(segment
		(start 326.869806 -293.830248)
		(end 326.838056 -293.848536)
		(width 0.0889)
		(layer "In11.Cu")
		(net "M_F_CPU0_SB_DQ<28>")
	)
	(segment
		(start 272.195798 -315.919866)
		(end 271.810988 -316.304676)
		(width 0.14478)
		(layer "In11.Cu")
		(net "M_F_CPU0_SB_DQ<28>")
	)
	(segment
		(start 307.553868 -315.265816)
		(end 307.09362 -315.265816)
		(width 0.14478)
		(layer "In11.Cu")
		(net "M_F_CPU0_SB_DQ<28>")
	)
	(segment
		(start 276.393656 -315.436758)
		(end 276.163024 -315.436758)
		(width 0.14478)
		(layer "In11.Cu")
		(net "M_F_CPU0_SB_DQ<28>")
	)
	(segment
		(start 298.87799 -316.22873)
		(end 298.640246 -316.22873)
		(width 0.14478)
		(layer "In11.Cu")
		(net "M_F_CPU0_SB_DQ<28>")
	)
	(segment
		(start 326.367902 -294.658542)
		(end 326.327516 -294.682164)
		(width 0.0889)
		(layer "In11.Cu")
		(net "M_F_CPU0_SB_DQ<28>")
	)
	(segment
		(start 327.30821 -293.03853)
		(end 327.269094 -293.06139)
		(width 0.0889)
		(layer "In11.Cu")
		(net "M_F_CPU0_SB_DQ<28>")
	)
	(segment
		(start 275.44395 -316.139576)
		(end 275.44395 -315.711332)
		(width 0.14478)
		(layer "In11.Cu")
		(net "M_F_CPU0_SB_DQ<28>")
	)
	(segment
		(start 271.580356 -316.304676)
		(end 271.417542 -316.141862)
		(width 0.14478)
		(layer "In11.Cu")
		(net "M_F_CPU0_SB_DQ<28>")
	)
	(segment
		(start 280.383742 -315.919866)
		(end 280.158698 -316.14491)
		(width 0.14478)
		(layer "In11.Cu")
		(net "M_F_CPU0_SB_DQ<28>")
	)
	(segment
		(start 285.500064 -316.22111)
		(end 285.189168 -315.910214)
		(width 0.14478)
		(layer "In11.Cu")
		(net "M_F_CPU0_SB_DQ<28>")
	)
	(segment
		(start 276.00021 -316.139576)
		(end 275.837396 -316.30239)
		(width 0.14478)
		(layer "In11.Cu")
		(net "M_F_CPU0_SB_DQ<28>")
	)
	(segment
		(start 291.06749 -316.22111)
		(end 290.756594 -315.910214)
		(width 0.14478)
		(layer "In11.Cu")
		(net "M_F_CPU0_SB_DQ<28>")
	)
	(segment
		(start 291.312854 -316.22111)
		(end 291.06749 -316.22111)
		(width 0.14478)
		(layer "In11.Cu")
		(net "M_F_CPU0_SB_DQ<28>")
	)
	(segment
		(start 287.159192 -315.919866)
		(end 286.857948 -316.22111)
		(width 0.14478)
		(layer "In11.Cu")
		(net "M_F_CPU0_SB_DQ<28>")
	)
	(segment
		(start 332.445106 -292.171374)
		(end 332.422754 -292.254686)
		(width 0.0889)
		(layer "In11.Cu")
		(net "M_F_CPU0_SB_DQ<28>")
	)
	(segment
		(start 307.09362 -315.265816)
		(end 306.449222 -315.910214)
		(width 0.14478)
		(layer "In11.Cu")
		(net "M_F_CPU0_SB_DQ<28>")
	)
	(segment
		(start 325.588122 -297.231562)
		(end 308.814216 -314.005468)
		(width 0.14478)
		(layer "In11.Cu")
		(net "M_F_CPU0_SB_DQ<28>")
	)
	(segment
		(start 270.861282 -316.141862)
		(end 270.698468 -316.304676)
		(width 0.14478)
		(layer "In11.Cu")
		(net "M_F_CPU0_SB_DQ<28>")
	)
	(segment
		(start 275.837396 -316.30239)
		(end 275.606764 -316.30239)
		(width 0.14478)
		(layer "In11.Cu")
		(net "M_F_CPU0_SB_DQ<28>")
	)
	(segment
		(start 309.23357 -314.83427)
		(end 309.048404 -315.019436)
		(width 0.14478)
		(layer "In11.Cu")
		(net "M_F_CPU0_SB_DQ<28>")
	)
	(segment
		(start 283.747972 -316.20841)
		(end 283.489908 -316.20841)
		(width 0.14478)
		(layer "In11.Cu")
		(net "M_F_CPU0_SB_DQ<28>")
	)
	(segment
		(start 290.51123 -315.910214)
		(end 290.200334 -316.22111)
		(width 0.14478)
		(layer "In11.Cu")
		(net "M_F_CPU0_SB_DQ<28>")
	)
	(segment
		(start 308.84368 -315.019436)
		(end 308.424326 -314.600082)
		(width 0.14478)
		(layer "In11.Cu")
		(net "M_F_CPU0_SB_DQ<28>")
	)
	(segment
		(start 300.81093 -316.19825)
		(end 300.542706 -316.19825)
		(width 0.14478)
		(layer "In11.Cu")
		(net "M_F_CPU0_SB_DQ<28>")
	)
	(segment
		(start 308.424326 -314.600082)
		(end 308.219602 -314.600082)
		(width 0.14478)
		(layer "In11.Cu")
		(net "M_F_CPU0_SB_DQ<28>")
	)
	(segment
		(start 298.083986 -315.910214)
		(end 297.76547 -316.22873)
		(width 0.14478)
		(layer "In11.Cu")
		(net "M_F_CPU0_SB_DQ<28>")
	)
	(segment
		(start 291.62375 -315.910214)
		(end 291.312854 -316.22111)
		(width 0.14478)
		(layer "In11.Cu")
		(net "M_F_CPU0_SB_DQ<28>")
	)
	(segment
		(start 278.724614 -316.14491)
		(end 278.489918 -315.910214)
		(width 0.14478)
		(layer "In11.Cu")
		(net "M_F_CPU0_SB_DQ<28>")
	)
	(segment
		(start 280.158698 -316.14491)
		(end 279.837134 -316.14491)
		(width 0.14478)
		(layer "In11.Cu")
		(net "M_F_CPU0_SB_DQ<28>")
	)
	(segment
		(start 290.200334 -316.22111)
		(end 289.95497 -316.22111)
		(width 0.14478)
		(layer "In11.Cu")
		(net "M_F_CPU0_SB_DQ<28>")
	)
	(segment
		(start 275.606764 -316.30239)
		(end 275.44395 -316.139576)
		(width 0.14478)
		(layer "In11.Cu")
		(net "M_F_CPU0_SB_DQ<28>")
	)
	(segment
		(start 286.857948 -316.22111)
		(end 286.612584 -316.22111)
		(width 0.14478)
		(layer "In11.Cu")
		(net "M_F_CPU0_SB_DQ<28>")
	)
	(segment
		(start 309.23357 -314.629546)
		(end 309.23357 -314.83427)
		(width 0.14478)
		(layer "In11.Cu")
		(net "M_F_CPU0_SB_DQ<28>")
	)
	(segment
		(start 283.489908 -316.20841)
		(end 283.191712 -315.910214)
		(width 0.14478)
		(layer "In11.Cu")
		(net "M_F_CPU0_SB_DQ<28>")
	)
	(segment
		(start 285.189168 -315.910214)
		(end 284.046168 -315.910214)
		(width 0.14478)
		(layer "In11.Cu")
		(net "M_F_CPU0_SB_DQ<28>")
	)
	(segment
		(start 297.76547 -316.22873)
		(end 297.527726 -316.22873)
		(width 0.14478)
		(layer "In11.Cu")
		(net "M_F_CPU0_SB_DQ<28>")
	)
	(segment
		(start 296.106342 -315.919866)
		(end 294.677084 -315.919866)
		(width 0.14478)
		(layer "In11.Cu")
		(net "M_F_CPU0_SB_DQ<28>")
	)
	(segment
		(start 290.756594 -315.910214)
		(end 290.51123 -315.910214)
		(width 0.14478)
		(layer "In11.Cu")
		(net "M_F_CPU0_SB_DQ<28>")
	)
	(segment
		(start 274.494244 -316.29731)
		(end 274.1168 -315.919866)
		(width 0.14478)
		(layer "In11.Cu")
		(net "M_F_CPU0_SB_DQ<28>")
	)
	(segment
		(start 308.814216 -314.005468)
		(end 308.814216 -314.210192)
		(width 0.14478)
		(layer "In11.Cu")
		(net "M_F_CPU0_SB_DQ<28>")
	)
	(segment
		(start 276.163024 -315.436758)
		(end 276.00021 -315.599572)
		(width 0.14478)
		(layer "In11.Cu")
		(net "M_F_CPU0_SB_DQ<28>")
	)
	(segment
		(start 301.098966 -315.910214)
		(end 300.81093 -316.19825)
		(width 0.14478)
		(layer "In11.Cu")
		(net "M_F_CPU0_SB_DQ<28>")
	)
	(segment
		(start 275.29917 -315.566552)
		(end 275.03247 -315.566552)
		(width 0.14478)
		(layer "In11.Cu")
		(net "M_F_CPU0_SB_DQ<28>")
	)
	(segment
		(start 274.88769 -315.711332)
		(end 274.88769 -316.134496)
		(width 0.14478)
		(layer "In11.Cu")
		(net "M_F_CPU0_SB_DQ<28>")
	)
	(segment
		(start 284.046168 -315.910214)
		(end 283.747972 -316.20841)
		(width 0.14478)
		(layer "In11.Cu")
		(net "M_F_CPU0_SB_DQ<28>")
	)
	(segment
		(start 274.724876 -316.29731)
		(end 274.494244 -316.29731)
		(width 0.14478)
		(layer "In11.Cu")
		(net "M_F_CPU0_SB_DQ<28>")
	)
	(segment
		(start 277.377398 -315.910214)
		(end 276.867112 -315.910214)
		(width 0.14478)
		(layer "In11.Cu")
		(net "M_F_CPU0_SB_DQ<28>")
	)
	(arc
		(start 327.495662 -292.71595)
		(mid 327.454113 -292.887372)
		(end 327.33869 -293.02075)
		(width 0.0889)
		(layer "In11.Cu")
		(net "M_F_CPU0_SB_DQ<28>")
	)
	(arc
		(start 329.284076 -292.228524)
		(mid 329.00112 -292.152347)
		(end 328.718164 -292.228524)
		(width 0.0889)
		(layer "In11.Cu")
		(net "M_F_CPU0_SB_DQ<28>")
	)
	(arc
		(start 326.80021 -293.87038)
		(mid 326.620481 -294.073)
		(end 326.555608 -294.335962)
		(width 0.0889)
		(layer "In11.Cu")
		(net "M_F_CPU0_SB_DQ<28>")
	)
	(arc
		(start 332.422754 -292.254686)
		(mid 332.260422 -292.277504)
		(end 332.103984 -292.228524)
		(width 0.0889)
		(layer "In11.Cu")
		(net "M_F_CPU0_SB_DQ<28>")
	)
	(arc
		(start 331.52969 -292.23335)
		(mid 331.346182 -292.278844)
		(end 331.16393 -292.228524)
		(width 0.0889)
		(layer "In11.Cu")
		(net "M_F_CPU0_SB_DQ<28>")
	)
	(arc
		(start 332.103984 -292.228524)
		(mid 331.821028 -292.152347)
		(end 331.538072 -292.228524)
		(width 0.0889)
		(layer "In11.Cu")
		(net "M_F_CPU0_SB_DQ<28>")
	)
	(arc
		(start 329.658218 -292.228524)
		(mid 329.475967 -292.278874)
		(end 329.292458 -292.23335)
		(width 0.0889)
		(layer "In11.Cu")
		(net "M_F_CPU0_SB_DQ<28>")
	)
	(arc
		(start 327.269094 -293.06139)
		(mid 327.090281 -293.26374)
		(end 327.025762 -293.525956)
		(width 0.0889)
		(layer "In11.Cu")
		(net "M_F_CPU0_SB_DQ<28>")
	)
	(arc
		(start 326.185276 -295.789858)
		(mid 326.030077 -296.570095)
		(end 325.588122 -297.231562)
		(width 0.0889)
		(layer "In11.Cu")
		(net "M_F_CPU0_SB_DQ<28>")
	)
	(arc
		(start 326.230488 -294.767508)
		(mid 326.196933 -294.82237)
		(end 326.185276 -294.885618)
		(width 0.0889)
		(layer "In11.Cu")
		(net "M_F_CPU0_SB_DQ<28>")
	)
	(arc
		(start 327.025762 -293.525956)
		(mid 326.984507 -293.696927)
		(end 326.869806 -293.830248)
		(width 0.0889)
		(layer "In11.Cu")
		(net "M_F_CPU0_SB_DQ<28>")
	)
	(arc
		(start 326.555608 -294.335962)
		(mid 326.514059 -294.507384)
		(end 326.398636 -294.640762)
		(width 0.0889)
		(layer "In11.Cu")
		(net "M_F_CPU0_SB_DQ<28>")
	)
	(arc
		(start 327.77557 -292.230048)
		(mid 327.570606 -292.435558)
		(end 327.495662 -292.71595)
		(width 0.0889)
		(layer "In11.Cu")
		(net "M_F_CPU0_SB_DQ<28>")
	)
	(arc
		(start 328.71791 -292.228524)
		(mid 328.530966 -292.278848)
		(end 328.344022 -292.228524)
		(width 0.0889)
		(layer "In11.Cu")
		(net "M_F_CPU0_SB_DQ<28>")
	)
	(arc
		(start 328.344022 -292.228524)
		(mid 328.061066 -292.152347)
		(end 327.77811 -292.228524)
		(width 0.0889)
		(layer "In11.Cu")
		(net "M_F_CPU0_SB_DQ<28>")
	)
	(arc
		(start 330.22413 -292.228524)
		(mid 329.941174 -292.152347)
		(end 329.658218 -292.228524)
		(width 0.0889)
		(layer "In11.Cu")
		(net "M_F_CPU0_SB_DQ<28>")
	)
	(arc
		(start 326.327516 -294.682164)
		(mid 326.276553 -294.722052)
		(end 326.230488 -294.767508)
		(width 0.0889)
		(layer "In11.Cu")
		(net "M_F_CPU0_SB_DQ<28>")
	)
	(arc
		(start 331.16393 -292.228524)
		(mid 330.880974 -292.152347)
		(end 330.598018 -292.228524)
		(width 0.0889)
		(layer "In11.Cu")
		(net "M_F_CPU0_SB_DQ<28>")
	)
	(arc
		(start 330.598018 -292.228524)
		(mid 330.411074 -292.278779)
		(end 330.22413 -292.228524)
		(width 0.0889)
		(layer "In11.Cu")
		(net "M_F_CPU0_SB_DQ<28>")
	)
	(segment
		(start 334.637888 -290.019994)
		(end 334.171036 -290.285932)
		(width 0.10668)
		(layer "F.Cu")
		(net "M_F_CPU0_SB_DQ<27>")
	)
	(segment
		(start 329.292458 -289.958526)
		(end 329.284076 -289.963352)
		(width 0.0889)
		(layer "In11.Cu")
		(net "M_F_CPU0_SB_DQ<27>")
	)
	(segment
		(start 282.308554 -312.500264)
		(end 279.324054 -312.500264)
		(width 0.14478)
		(layer "In11.Cu")
		(net "M_F_CPU0_SB_DQ<27>")
	)
	(segment
		(start 325.546212 -291.789104)
		(end 325.546212 -292.453822)
		(width 0.0889)
		(layer "In11.Cu")
		(net "M_F_CPU0_SB_DQ<27>")
	)
	(segment
		(start 332.478126 -289.963352)
		(end 332.469744 -289.958526)
		(width 0.0889)
		(layer "In11.Cu")
		(net "M_F_CPU0_SB_DQ<27>")
	)
	(segment
		(start 266.637516 -312.058812)
		(end 266.637516 -312.356246)
		(width 0.14478)
		(layer "In11.Cu")
		(net "M_F_CPU0_SB_DQ<27>")
	)
	(segment
		(start 275.599144 -311.65038)
		(end 274.748498 -312.501026)
		(width 0.14478)
		(layer "In11.Cu")
		(net "M_F_CPU0_SB_DQ<27>")
	)
	(segment
		(start 328.718164 -289.963352)
		(end 328.709782 -289.958526)
		(width 0.0889)
		(layer "In11.Cu")
		(net "M_F_CPU0_SB_DQ<27>")
	)
	(segment
		(start 333.05242 -289.958526)
		(end 333.044038 -289.963352)
		(width 0.0889)
		(layer "In11.Cu")
		(net "M_F_CPU0_SB_DQ<27>")
	)
	(segment
		(start 266.492736 -312.501026)
		(end 265.964162 -312.501026)
		(width 0.14478)
		(layer "In11.Cu")
		(net "M_F_CPU0_SB_DQ<27>")
	)
	(segment
		(start 327.475088 -289.96132)
		(end 326.917812 -290.518596)
		(width 0.0889)
		(layer "In11.Cu")
		(net "M_F_CPU0_SB_DQ<27>")
	)
	(segment
		(start 310.469534 -308.811168)
		(end 307.62067 -311.660032)
		(width 0.14478)
		(layer "In11.Cu")
		(net "M_F_CPU0_SB_DQ<27>")
	)
	(segment
		(start 283.158438 -311.65038)
		(end 282.308554 -312.500264)
		(width 0.14478)
		(layer "In11.Cu")
		(net "M_F_CPU0_SB_DQ<27>")
	)
	(segment
		(start 326.461374 -290.793932)
		(end 326.314816 -290.94049)
		(width 0.0889)
		(layer "In11.Cu")
		(net "M_F_CPU0_SB_DQ<27>")
	)
	(segment
		(start 269.475712 -312.221372)
		(end 269.330932 -312.076592)
		(width 0.14478)
		(layer "In11.Cu")
		(net "M_F_CPU0_SB_DQ<27>")
	)
	(segment
		(start 324.726808 -292.99662)
		(end 310.469534 -307.253894)
		(width 0.14478)
		(layer "In11.Cu")
		(net "M_F_CPU0_SB_DQ<27>")
	)
	(segment
		(start 269.475712 -312.356246)
		(end 269.475712 -312.221372)
		(width 0.14478)
		(layer "In11.Cu")
		(net "M_F_CPU0_SB_DQ<27>")
	)
	(segment
		(start 266.637516 -312.356246)
		(end 266.492736 -312.501026)
		(width 0.14478)
		(layer "In11.Cu")
		(net "M_F_CPU0_SB_DQ<27>")
	)
	(segment
		(start 269.620492 -312.501026)
		(end 269.475712 -312.356246)
		(width 0.14478)
		(layer "In11.Cu")
		(net "M_F_CPU0_SB_DQ<27>")
	)
	(segment
		(start 325.17842 -292.821614)
		(end 324.901814 -292.821614)
		(width 0.0889)
		(layer "In11.Cu")
		(net "M_F_CPU0_SB_DQ<27>")
	)
	(segment
		(start 279.324054 -312.500264)
		(end 278.47417 -311.65038)
		(width 0.14478)
		(layer "In11.Cu")
		(net "M_F_CPU0_SB_DQ<27>")
	)
	(segment
		(start 269.330932 -312.076592)
		(end 269.069058 -312.076592)
		(width 0.14478)
		(layer "In11.Cu")
		(net "M_F_CPU0_SB_DQ<27>")
	)
	(segment
		(start 289.84194 -312.500264)
		(end 286.893508 -312.500264)
		(width 0.14478)
		(layer "In11.Cu")
		(net "M_F_CPU0_SB_DQ<27>")
	)
	(segment
		(start 325.546212 -292.453822)
		(end 325.17842 -292.821614)
		(width 0.0889)
		(layer "In11.Cu")
		(net "M_F_CPU0_SB_DQ<27>")
	)
	(segment
		(start 298.18965 -311.65038)
		(end 297.339766 -312.500264)
		(width 0.14478)
		(layer "In11.Cu")
		(net "M_F_CPU0_SB_DQ<27>")
	)
	(segment
		(start 334.017112 -290.020502)
		(end 333.9211 -289.995102)
		(width 0.0889)
		(layer "In11.Cu")
		(net "M_F_CPU0_SB_DQ<27>")
	)
	(segment
		(start 268.924278 -312.221372)
		(end 268.924278 -312.356246)
		(width 0.14478)
		(layer "In11.Cu")
		(net "M_F_CPU0_SB_DQ<27>")
	)
	(segment
		(start 301.549816 -312.114692)
		(end 301.085504 -311.65038)
		(width 0.14478)
		(layer "In11.Cu")
		(net "M_F_CPU0_SB_DQ<27>")
	)
	(segment
		(start 324.901814 -292.821614)
		(end 324.726808 -292.99662)
		(width 0.0889)
		(layer "In11.Cu")
		(net "M_F_CPU0_SB_DQ<27>")
	)
	(segment
		(start 278.47417 -311.65038)
		(end 275.599144 -311.65038)
		(width 0.14478)
		(layer "In11.Cu")
		(net "M_F_CPU0_SB_DQ<27>")
	)
	(segment
		(start 301.085504 -311.65038)
		(end 298.18965 -311.65038)
		(width 0.14478)
		(layer "In11.Cu")
		(net "M_F_CPU0_SB_DQ<27>")
	)
	(segment
		(start 274.748498 -312.501026)
		(end 269.620492 -312.501026)
		(width 0.14478)
		(layer "In11.Cu")
		(net "M_F_CPU0_SB_DQ<27>")
	)
	(segment
		(start 266.782296 -311.914032)
		(end 266.637516 -312.058812)
		(width 0.14478)
		(layer "In11.Cu")
		(net "M_F_CPU0_SB_DQ<27>")
	)
	(segment
		(start 297.339766 -312.500264)
		(end 294.398954 -312.500264)
		(width 0.14478)
		(layer "In11.Cu")
		(net "M_F_CPU0_SB_DQ<27>")
	)
	(segment
		(start 286.043624 -311.65038)
		(end 283.158438 -311.65038)
		(width 0.14478)
		(layer "In11.Cu")
		(net "M_F_CPU0_SB_DQ<27>")
	)
	(segment
		(start 305.329844 -311.660032)
		(end 304.875184 -312.114692)
		(width 0.14478)
		(layer "In11.Cu")
		(net "M_F_CPU0_SB_DQ<27>")
	)
	(segment
		(start 293.54907 -311.65038)
		(end 290.691824 -311.65038)
		(width 0.14478)
		(layer "In11.Cu")
		(net "M_F_CPU0_SB_DQ<27>")
	)
	(segment
		(start 268.779498 -312.501026)
		(end 267.33373 -312.501026)
		(width 0.14478)
		(layer "In11.Cu")
		(net "M_F_CPU0_SB_DQ<27>")
	)
	(segment
		(start 290.691824 -311.65038)
		(end 289.84194 -312.500264)
		(width 0.14478)
		(layer "In11.Cu")
		(net "M_F_CPU0_SB_DQ<27>")
	)
	(segment
		(start 334.171036 -290.285932)
		(end 334.017112 -290.020502)
		(width 0.0889)
		(layer "In11.Cu")
		(net "M_F_CPU0_SB_DQ<27>")
	)
	(segment
		(start 267.04417 -311.914032)
		(end 266.782296 -311.914032)
		(width 0.14478)
		(layer "In11.Cu")
		(net "M_F_CPU0_SB_DQ<27>")
	)
	(segment
		(start 267.33373 -312.501026)
		(end 267.18895 -312.356246)
		(width 0.14478)
		(layer "In11.Cu")
		(net "M_F_CPU0_SB_DQ<27>")
	)
	(segment
		(start 310.469534 -307.253894)
		(end 310.469534 -308.811168)
		(width 0.14478)
		(layer "In11.Cu")
		(net "M_F_CPU0_SB_DQ<27>")
	)
	(segment
		(start 294.398954 -312.500264)
		(end 293.54907 -311.65038)
		(width 0.14478)
		(layer "In11.Cu")
		(net "M_F_CPU0_SB_DQ<27>")
	)
	(segment
		(start 331.538072 -289.963352)
		(end 331.52969 -289.958526)
		(width 0.0889)
		(layer "In11.Cu")
		(net "M_F_CPU0_SB_DQ<27>")
	)
	(segment
		(start 326.25792 -291.077396)
		(end 325.546212 -291.789104)
		(width 0.0889)
		(layer "In11.Cu")
		(net "M_F_CPU0_SB_DQ<27>")
	)
	(segment
		(start 268.924278 -312.356246)
		(end 268.779498 -312.501026)
		(width 0.14478)
		(layer "In11.Cu")
		(net "M_F_CPU0_SB_DQ<27>")
	)
	(segment
		(start 307.62067 -311.660032)
		(end 305.329844 -311.660032)
		(width 0.14478)
		(layer "In11.Cu")
		(net "M_F_CPU0_SB_DQ<27>")
	)
	(segment
		(start 269.069058 -312.076592)
		(end 268.924278 -312.221372)
		(width 0.14478)
		(layer "In11.Cu")
		(net "M_F_CPU0_SB_DQ<27>")
	)
	(segment
		(start 286.893508 -312.500264)
		(end 286.043624 -311.65038)
		(width 0.14478)
		(layer "In11.Cu")
		(net "M_F_CPU0_SB_DQ<27>")
	)
	(segment
		(start 267.18895 -312.356246)
		(end 267.18895 -312.058812)
		(width 0.14478)
		(layer "In11.Cu")
		(net "M_F_CPU0_SB_DQ<27>")
	)
	(segment
		(start 267.18895 -312.058812)
		(end 267.04417 -311.914032)
		(width 0.14478)
		(layer "In11.Cu")
		(net "M_F_CPU0_SB_DQ<27>")
	)
	(segment
		(start 265.964162 -312.501026)
		(end 265.54811 -312.084974)
		(width 0.14478)
		(layer "In11.Cu")
		(net "M_F_CPU0_SB_DQ<27>")
	)
	(segment
		(start 328.344022 -289.963352)
		(end 328.333608 -289.969448)
		(width 0.0889)
		(layer "In11.Cu")
		(net "M_F_CPU0_SB_DQ<27>")
	)
	(segment
		(start 304.875184 -312.114692)
		(end 301.549816 -312.114692)
		(width 0.14478)
		(layer "In11.Cu")
		(net "M_F_CPU0_SB_DQ<27>")
	)
	(arc
		(start 329.658218 -289.963352)
		(mid 329.475967 -289.913002)
		(end 329.292458 -289.958526)
		(width 0.0889)
		(layer "In11.Cu")
		(net "M_F_CPU0_SB_DQ<27>")
	)
	(arc
		(start 330.598018 -289.963352)
		(mid 330.411074 -289.913097)
		(end 330.22413 -289.963352)
		(width 0.0889)
		(layer "In11.Cu")
		(net "M_F_CPU0_SB_DQ<27>")
	)
	(arc
		(start 326.288654 -291.003482)
		(mid 326.280658 -291.0435)
		(end 326.25792 -291.077396)
		(width 0.0889)
		(layer "In11.Cu")
		(net "M_F_CPU0_SB_DQ<27>")
	)
	(arc
		(start 332.469744 -289.958526)
		(mid 332.286236 -289.913032)
		(end 332.103984 -289.963352)
		(width 0.0889)
		(layer "In11.Cu")
		(net "M_F_CPU0_SB_DQ<27>")
	)
	(arc
		(start 333.41818 -289.963352)
		(mid 333.235929 -289.913002)
		(end 333.05242 -289.958526)
		(width 0.0889)
		(layer "In11.Cu")
		(net "M_F_CPU0_SB_DQ<27>")
	)
	(arc
		(start 327.592182 -289.912806)
		(mid 327.52877 -289.925321)
		(end 327.475088 -289.96132)
		(width 0.0889)
		(layer "In11.Cu")
		(net "M_F_CPU0_SB_DQ<27>")
	)
	(arc
		(start 328.709782 -289.958526)
		(mid 328.526274 -289.913032)
		(end 328.344022 -289.963352)
		(width 0.0889)
		(layer "In11.Cu")
		(net "M_F_CPU0_SB_DQ<27>")
	)
	(arc
		(start 331.52969 -289.958526)
		(mid 331.346182 -289.913032)
		(end 331.16393 -289.963352)
		(width 0.0889)
		(layer "In11.Cu")
		(net "M_F_CPU0_SB_DQ<27>")
	)
	(arc
		(start 333.9211 -289.995102)
		(mid 333.665892 -290.038579)
		(end 333.41818 -289.963352)
		(width 0.0889)
		(layer "In11.Cu")
		(net "M_F_CPU0_SB_DQ<27>")
	)
	(arc
		(start 326.818244 -290.59632)
		(mid 326.759109 -290.62712)
		(end 326.696832 -290.65093)
		(width 0.0889)
		(layer "In11.Cu")
		(net "M_F_CPU0_SB_DQ<27>")
	)
	(arc
		(start 331.16393 -289.963352)
		(mid 330.880974 -290.039529)
		(end 330.598018 -289.963352)
		(width 0.0889)
		(layer "In11.Cu")
		(net "M_F_CPU0_SB_DQ<27>")
	)
	(arc
		(start 328.333608 -289.969448)
		(mid 328.054922 -290.039668)
		(end 327.777856 -289.963352)
		(width 0.0889)
		(layer "In11.Cu")
		(net "M_F_CPU0_SB_DQ<27>")
	)
	(arc
		(start 333.044038 -289.963352)
		(mid 332.761082 -290.039529)
		(end 332.478126 -289.963352)
		(width 0.0889)
		(layer "In11.Cu")
		(net "M_F_CPU0_SB_DQ<27>")
	)
	(arc
		(start 330.22413 -289.963352)
		(mid 329.941174 -290.039529)
		(end 329.658218 -289.963352)
		(width 0.0889)
		(layer "In11.Cu")
		(net "M_F_CPU0_SB_DQ<27>")
	)
	(arc
		(start 326.696832 -290.65093)
		(mid 326.57052 -290.708299)
		(end 326.461374 -290.793932)
		(width 0.0889)
		(layer "In11.Cu")
		(net "M_F_CPU0_SB_DQ<27>")
	)
	(arc
		(start 329.284076 -289.963352)
		(mid 329.00112 -290.039529)
		(end 328.718164 -289.963352)
		(width 0.0889)
		(layer "In11.Cu")
		(net "M_F_CPU0_SB_DQ<27>")
	)
	(arc
		(start 326.917812 -290.518596)
		(mid 326.870443 -290.560552)
		(end 326.818244 -290.59632)
		(width 0.0889)
		(layer "In11.Cu")
		(net "M_F_CPU0_SB_DQ<27>")
	)
	(arc
		(start 326.314816 -290.94049)
		(mid 326.295451 -290.969377)
		(end 326.288654 -291.003482)
		(width 0.0889)
		(layer "In11.Cu")
		(net "M_F_CPU0_SB_DQ<27>")
	)
	(arc
		(start 332.103984 -289.963352)
		(mid 331.821028 -290.039529)
		(end 331.538072 -289.963352)
		(width 0.0889)
		(layer "In11.Cu")
		(net "M_F_CPU0_SB_DQ<27>")
	)
	(arc
		(start 327.777856 -289.963352)
		(mid 327.688335 -289.925898)
		(end 327.592182 -289.912806)
		(width 0.0889)
		(layer "In11.Cu")
		(net "M_F_CPU0_SB_DQ<27>")
	)
	(segment
		(start 333.227934 -289.209988)
		(end 332.761082 -289.475926)
		(width 0.10668)
		(layer "F.Cu")
		(net "M_F_CPU0_SB_DQ<26>")
	)
	(segment
		(start 278.2697 -309.96001)
		(end 275.6408 -309.96001)
		(width 0.14478)
		(layer "In11.Cu")
		(net "M_F_CPU0_SB_DQ<26>")
	)
	(segment
		(start 304.893218 -310.810148)
		(end 302.205898 -310.810148)
		(width 0.14478)
		(layer "In11.Cu")
		(net "M_F_CPU0_SB_DQ<26>")
	)
	(segment
		(start 267.297662 -310.331612)
		(end 267.152882 -310.476392)
		(width 0.14478)
		(layer "In11.Cu")
		(net "M_F_CPU0_SB_DQ<26>")
	)
	(segment
		(start 268.25575 -311.143904)
		(end 268.11097 -311.288684)
		(width 0.14478)
		(layer "In11.Cu")
		(net "M_F_CPU0_SB_DQ<26>")
	)
	(segment
		(start 290.12007 -310.810148)
		(end 286.587946 -310.810148)
		(width 0.14478)
		(layer "In11.Cu")
		(net "M_F_CPU0_SB_DQ<26>")
	)
	(segment
		(start 279.119838 -310.810148)
		(end 278.2697 -309.96001)
		(width 0.14478)
		(layer "In11.Cu")
		(net "M_F_CPU0_SB_DQ<26>")
	)
	(segment
		(start 283.375608 -309.96001)
		(end 282.52547 -310.810148)
		(width 0.14478)
		(layer "In11.Cu")
		(net "M_F_CPU0_SB_DQ<26>")
	)
	(segment
		(start 330.702412 -289.14852)
		(end 330.69403 -289.153346)
		(width 0.0889)
		(layer "In11.Cu")
		(net "M_F_CPU0_SB_DQ<26>")
	)
	(segment
		(start 327.309226 -289.153346)
		(end 327.297542 -289.146488)
		(width 0.0889)
		(layer "In11.Cu")
		(net "M_F_CPU0_SB_DQ<26>")
	)
	(segment
		(start 266.746228 -311.288684)
		(end 266.601448 -311.143904)
		(width 0.14478)
		(layer "In11.Cu")
		(net "M_F_CPU0_SB_DQ<26>")
	)
	(segment
		(start 267.008102 -311.288684)
		(end 266.746228 -311.288684)
		(width 0.14478)
		(layer "In11.Cu")
		(net "M_F_CPU0_SB_DQ<26>")
	)
	(segment
		(start 267.152882 -310.476392)
		(end 267.152882 -311.143904)
		(width 0.14478)
		(layer "In11.Cu")
		(net "M_F_CPU0_SB_DQ<26>")
	)
	(segment
		(start 266.456668 -310.810148)
		(end 265.973306 -310.810148)
		(width 0.14478)
		(layer "In11.Cu")
		(net "M_F_CPU0_SB_DQ<26>")
	)
	(segment
		(start 309.340758 -308.363874)
		(end 307.73497 -309.969662)
		(width 0.14478)
		(layer "In11.Cu")
		(net "M_F_CPU0_SB_DQ<26>")
	)
	(segment
		(start 297.374818 -310.810148)
		(end 294.283638 -310.810148)
		(width 0.14478)
		(layer "In11.Cu")
		(net "M_F_CPU0_SB_DQ<26>")
	)
	(segment
		(start 266.601448 -310.954928)
		(end 266.456668 -310.810148)
		(width 0.14478)
		(layer "In11.Cu")
		(net "M_F_CPU0_SB_DQ<26>")
	)
	(segment
		(start 325.427594 -290.69411)
		(end 325.427594 -290.958778)
		(width 0.0889)
		(layer "In11.Cu")
		(net "M_F_CPU0_SB_DQ<26>")
	)
	(segment
		(start 324.202552 -291.94379)
		(end 309.340758 -306.805584)
		(width 0.14478)
		(layer "In11.Cu")
		(net "M_F_CPU0_SB_DQ<26>")
	)
	(segment
		(start 309.340758 -306.805584)
		(end 309.340758 -308.363874)
		(width 0.14478)
		(layer "In11.Cu")
		(net "M_F_CPU0_SB_DQ<26>")
	)
	(segment
		(start 267.849096 -311.288684)
		(end 267.704316 -311.143904)
		(width 0.14478)
		(layer "In11.Cu")
		(net "M_F_CPU0_SB_DQ<26>")
	)
	(segment
		(start 325.427594 -290.958778)
		(end 324.943724 -291.442648)
		(width 0.0889)
		(layer "In11.Cu")
		(net "M_F_CPU0_SB_DQ<26>")
	)
	(segment
		(start 266.601448 -311.143904)
		(end 266.601448 -310.954928)
		(width 0.14478)
		(layer "In11.Cu")
		(net "M_F_CPU0_SB_DQ<26>")
	)
	(segment
		(start 275.6408 -309.96001)
		(end 274.790662 -310.810148)
		(width 0.14478)
		(layer "In11.Cu")
		(net "M_F_CPU0_SB_DQ<26>")
	)
	(segment
		(start 265.973306 -310.810148)
		(end 265.54811 -310.384952)
		(width 0.14478)
		(layer "In11.Cu")
		(net "M_F_CPU0_SB_DQ<26>")
	)
	(segment
		(start 301.35576 -309.96001)
		(end 298.224956 -309.96001)
		(width 0.14478)
		(layer "In11.Cu")
		(net "M_F_CPU0_SB_DQ<26>")
	)
	(segment
		(start 294.283638 -310.810148)
		(end 293.4335 -309.96001)
		(width 0.14478)
		(layer "In11.Cu")
		(net "M_F_CPU0_SB_DQ<26>")
	)
	(segment
		(start 307.73497 -309.969662)
		(end 305.733704 -309.969662)
		(width 0.14478)
		(layer "In11.Cu")
		(net "M_F_CPU0_SB_DQ<26>")
	)
	(segment
		(start 285.737808 -309.96001)
		(end 283.375608 -309.96001)
		(width 0.14478)
		(layer "In11.Cu")
		(net "M_F_CPU0_SB_DQ<26>")
	)
	(segment
		(start 268.951964 -310.810148)
		(end 268.807184 -310.665368)
		(width 0.14478)
		(layer "In11.Cu")
		(net "M_F_CPU0_SB_DQ<26>")
	)
	(segment
		(start 332.607158 -289.210496)
		(end 332.511146 -289.185096)
		(width 0.0889)
		(layer "In11.Cu")
		(net "M_F_CPU0_SB_DQ<26>")
	)
	(segment
		(start 267.704316 -310.476392)
		(end 267.559536 -310.331612)
		(width 0.14478)
		(layer "In11.Cu")
		(net "M_F_CPU0_SB_DQ<26>")
	)
	(segment
		(start 286.587946 -310.810148)
		(end 285.737808 -309.96001)
		(width 0.14478)
		(layer "In11.Cu")
		(net "M_F_CPU0_SB_DQ<26>")
	)
	(segment
		(start 274.790662 -310.810148)
		(end 268.951964 -310.810148)
		(width 0.14478)
		(layer "In11.Cu")
		(net "M_F_CPU0_SB_DQ<26>")
	)
	(segment
		(start 268.40053 -310.331612)
		(end 268.25575 -310.476392)
		(width 0.14478)
		(layer "In11.Cu")
		(net "M_F_CPU0_SB_DQ<26>")
	)
	(segment
		(start 268.807184 -310.476392)
		(end 268.662404 -310.331612)
		(width 0.14478)
		(layer "In11.Cu")
		(net "M_F_CPU0_SB_DQ<26>")
	)
	(segment
		(start 267.152882 -311.143904)
		(end 267.008102 -311.288684)
		(width 0.14478)
		(layer "In11.Cu")
		(net "M_F_CPU0_SB_DQ<26>")
	)
	(segment
		(start 268.662404 -310.331612)
		(end 268.40053 -310.331612)
		(width 0.14478)
		(layer "In11.Cu")
		(net "M_F_CPU0_SB_DQ<26>")
	)
	(segment
		(start 282.52547 -310.810148)
		(end 279.119838 -310.810148)
		(width 0.14478)
		(layer "In11.Cu")
		(net "M_F_CPU0_SB_DQ<26>")
	)
	(segment
		(start 332.761082 -289.475926)
		(end 332.607158 -289.210496)
		(width 0.0889)
		(layer "In11.Cu")
		(net "M_F_CPU0_SB_DQ<26>")
	)
	(segment
		(start 268.807184 -310.665368)
		(end 268.807184 -310.476392)
		(width 0.14478)
		(layer "In11.Cu")
		(net "M_F_CPU0_SB_DQ<26>")
	)
	(segment
		(start 305.733704 -309.969662)
		(end 304.893218 -310.810148)
		(width 0.14478)
		(layer "In11.Cu")
		(net "M_F_CPU0_SB_DQ<26>")
	)
	(segment
		(start 327.890632 -289.144202)
		(end 327.874376 -289.1536)
		(width 0.0889)
		(layer "In11.Cu")
		(net "M_F_CPU0_SB_DQ<26>")
	)
	(segment
		(start 324.943724 -291.442648)
		(end 324.703694 -291.442648)
		(width 0.0889)
		(layer "In11.Cu")
		(net "M_F_CPU0_SB_DQ<26>")
	)
	(segment
		(start 330.128118 -289.153346)
		(end 330.119736 -289.14852)
		(width 0.0889)
		(layer "In11.Cu")
		(net "M_F_CPU0_SB_DQ<26>")
	)
	(segment
		(start 290.970208 -309.96001)
		(end 290.12007 -310.810148)
		(width 0.14478)
		(layer "In11.Cu")
		(net "M_F_CPU0_SB_DQ<26>")
	)
	(segment
		(start 298.224956 -309.96001)
		(end 297.374818 -310.810148)
		(width 0.14478)
		(layer "In11.Cu")
		(net "M_F_CPU0_SB_DQ<26>")
	)
	(segment
		(start 327.874376 -289.1536)
		(end 327.862438 -289.160458)
		(width 0.0889)
		(layer "In11.Cu")
		(net "M_F_CPU0_SB_DQ<26>")
	)
	(segment
		(start 302.205898 -310.810148)
		(end 301.35576 -309.96001)
		(width 0.14478)
		(layer "In11.Cu")
		(net "M_F_CPU0_SB_DQ<26>")
	)
	(segment
		(start 324.703694 -291.442648)
		(end 324.202552 -291.94379)
		(width 0.0889)
		(layer "In11.Cu")
		(net "M_F_CPU0_SB_DQ<26>")
	)
	(segment
		(start 268.11097 -311.288684)
		(end 267.849096 -311.288684)
		(width 0.14478)
		(layer "In11.Cu")
		(net "M_F_CPU0_SB_DQ<26>")
	)
	(segment
		(start 268.25575 -310.476392)
		(end 268.25575 -311.143904)
		(width 0.14478)
		(layer "In11.Cu")
		(net "M_F_CPU0_SB_DQ<26>")
	)
	(segment
		(start 267.704316 -311.143904)
		(end 267.704316 -310.476392)
		(width 0.14478)
		(layer "In11.Cu")
		(net "M_F_CPU0_SB_DQ<26>")
	)
	(segment
		(start 267.559536 -310.331612)
		(end 267.297662 -310.331612)
		(width 0.14478)
		(layer "In11.Cu")
		(net "M_F_CPU0_SB_DQ<26>")
	)
	(segment
		(start 326.54875 -289.35553)
		(end 325.581518 -290.322762)
		(width 0.0889)
		(layer "In11.Cu")
		(net "M_F_CPU0_SB_DQ<26>")
	)
	(segment
		(start 293.4335 -309.96001)
		(end 290.970208 -309.96001)
		(width 0.14478)
		(layer "In11.Cu")
		(net "M_F_CPU0_SB_DQ<26>")
	)
	(segment
		(start 331.642466 -289.14852)
		(end 331.634084 -289.153346)
		(width 0.0889)
		(layer "In11.Cu")
		(net "M_F_CPU0_SB_DQ<26>")
	)
	(arc
		(start 330.119736 -289.14852)
		(mid 329.936228 -289.103026)
		(end 329.753976 -289.153346)
		(width 0.0889)
		(layer "In11.Cu")
		(net "M_F_CPU0_SB_DQ<26>")
	)
	(arc
		(start 326.93483 -289.153346)
		(mid 326.869112 -289.18607)
		(end 326.799702 -289.209988)
		(width 0.0889)
		(layer "In11.Cu")
		(net "M_F_CPU0_SB_DQ<26>")
	)
	(arc
		(start 328.248264 -289.153346)
		(mid 328.070614 -289.103086)
		(end 327.890632 -289.144202)
		(width 0.0889)
		(layer "In11.Cu")
		(net "M_F_CPU0_SB_DQ<26>")
	)
	(arc
		(start 329.753976 -289.153346)
		(mid 329.47102 -289.229523)
		(end 329.188064 -289.153346)
		(width 0.0889)
		(layer "In11.Cu")
		(net "M_F_CPU0_SB_DQ<26>")
	)
	(arc
		(start 330.69403 -289.153346)
		(mid 330.411074 -289.229523)
		(end 330.128118 -289.153346)
		(width 0.0889)
		(layer "In11.Cu")
		(net "M_F_CPU0_SB_DQ<26>")
	)
	(arc
		(start 327.862438 -289.160458)
		(mid 327.584904 -289.229439)
		(end 327.309226 -289.153346)
		(width 0.0889)
		(layer "In11.Cu")
		(net "M_F_CPU0_SB_DQ<26>")
	)
	(arc
		(start 332.008226 -289.153346)
		(mid 331.825975 -289.102996)
		(end 331.642466 -289.14852)
		(width 0.0889)
		(layer "In11.Cu")
		(net "M_F_CPU0_SB_DQ<26>")
	)
	(arc
		(start 328.814176 -289.153346)
		(mid 328.53122 -289.229523)
		(end 328.248264 -289.153346)
		(width 0.0889)
		(layer "In11.Cu")
		(net "M_F_CPU0_SB_DQ<26>")
	)
	(arc
		(start 331.068172 -289.153346)
		(mid 330.885921 -289.102996)
		(end 330.702412 -289.14852)
		(width 0.0889)
		(layer "In11.Cu")
		(net "M_F_CPU0_SB_DQ<26>")
	)
	(arc
		(start 331.634084 -289.153346)
		(mid 331.351128 -289.229523)
		(end 331.068172 -289.153346)
		(width 0.0889)
		(layer "In11.Cu")
		(net "M_F_CPU0_SB_DQ<26>")
	)
	(arc
		(start 326.799702 -289.209988)
		(mid 326.6647 -289.266336)
		(end 326.54875 -289.35553)
		(width 0.0889)
		(layer "In11.Cu")
		(net "M_F_CPU0_SB_DQ<26>")
	)
	(arc
		(start 327.297542 -289.146488)
		(mid 327.115287 -289.102835)
		(end 326.93483 -289.153346)
		(width 0.0889)
		(layer "In11.Cu")
		(net "M_F_CPU0_SB_DQ<26>")
	)
	(arc
		(start 329.188064 -289.153346)
		(mid 329.00112 -289.103091)
		(end 328.814176 -289.153346)
		(width 0.0889)
		(layer "In11.Cu")
		(net "M_F_CPU0_SB_DQ<26>")
	)
	(arc
		(start 325.581518 -290.322762)
		(mid 325.467623 -290.493124)
		(end 325.427594 -290.69411)
		(width 0.0889)
		(layer "In11.Cu")
		(net "M_F_CPU0_SB_DQ<26>")
	)
	(arc
		(start 332.511146 -289.185096)
		(mid 332.255938 -289.228573)
		(end 332.008226 -289.153346)
		(width 0.0889)
		(layer "In11.Cu")
		(net "M_F_CPU0_SB_DQ<26>")
	)
	(segment
		(start 334.167988 -289.209988)
		(end 333.701136 -289.475926)
		(width 0.10668)
		(layer "F.Cu")
		(net "M_F_CPU0_SB_DQ<25>")
	)
	(segment
		(start 298.67987 -310.410352)
		(end 298.53509 -310.555132)
		(width 0.14478)
		(layer "In11.Cu")
		(net "M_F_CPU0_SB_DQ<25>")
	)
	(segment
		(start 273.745198 -311.26684)
		(end 273.354038 -311.658)
		(width 0.14478)
		(layer "In11.Cu")
		(net "M_F_CPU0_SB_DQ<25>")
	)
	(segment
		(start 274.288504 -311.89803)
		(end 274.138644 -311.74817)
		(width 0.14478)
		(layer "In11.Cu")
		(net "M_F_CPU0_SB_DQ<25>")
	)
	(segment
		(start 309.908956 -308.582314)
		(end 307.681376 -310.809894)
		(width 0.14478)
		(layer "In11.Cu")
		(net "M_F_CPU0_SB_DQ<25>")
	)
	(segment
		(start 287.30829 -311.97931)
		(end 287.071308 -311.97931)
		(width 0.14478)
		(layer "In11.Cu")
		(net "M_F_CPU0_SB_DQ<25>")
	)
	(segment
		(start 305.936904 -310.564276)
		(end 305.936904 -311.065672)
		(width 0.14478)
		(layer "In11.Cu")
		(net "M_F_CPU0_SB_DQ<25>")
	)
	(segment
		(start 279.78989 -311.95391)
		(end 279.527508 -311.95391)
		(width 0.14478)
		(layer "In11.Cu")
		(net "M_F_CPU0_SB_DQ<25>")
	)
	(segment
		(start 324.837298 -292.096698)
		(end 324.243446 -292.69055)
		(width 0.0889)
		(layer "In11.Cu")
		(net "M_F_CPU0_SB_DQ<25>")
	)
	(segment
		(start 306.488338 -311.055512)
		(end 306.488338 -310.564276)
		(width 0.14478)
		(layer "In11.Cu")
		(net "M_F_CPU0_SB_DQ<25>")
	)
	(segment
		(start 333.701136 -289.475926)
		(end 333.85506 -289.741356)
		(width 0.0889)
		(layer "In11.Cu")
		(net "M_F_CPU0_SB_DQ<25>")
	)
	(segment
		(start 326.455532 -289.98545)
		(end 325.8947 -290.546282)
		(width 0.0889)
		(layer "In11.Cu")
		(net "M_F_CPU0_SB_DQ<25>")
	)
	(segment
		(start 279.527508 -311.95391)
		(end 278.383492 -310.809894)
		(width 0.14478)
		(layer "In11.Cu")
		(net "M_F_CPU0_SB_DQ<25>")
	)
	(segment
		(start 324.243446 -292.69055)
		(end 309.908956 -307.02504)
		(width 0.14478)
		(layer "In11.Cu")
		(net "M_F_CPU0_SB_DQ<25>")
	)
	(segment
		(start 304.686462 -311.660032)
		(end 302.412654 -311.660032)
		(width 0.14478)
		(layer "In11.Cu")
		(net "M_F_CPU0_SB_DQ<25>")
	)
	(segment
		(start 271.972532 -311.433972)
		(end 271.972532 -311.875424)
		(width 0.14478)
		(layer "In11.Cu")
		(net "M_F_CPU0_SB_DQ<25>")
	)
	(segment
		(start 298.0182 -310.809894)
		(end 297.168062 -311.660032)
		(width 0.14478)
		(layer "In11.Cu")
		(net "M_F_CPU0_SB_DQ<25>")
	)
	(segment
		(start 333.85506 -289.741356)
		(end 333.832708 -289.824668)
		(width 0.0889)
		(layer "In11.Cu")
		(net "M_F_CPU0_SB_DQ<25>")
	)
	(segment
		(start 270.451326 -312.038238)
		(end 269.648178 -311.23509)
		(width 0.14478)
		(layer "In11.Cu")
		(net "M_F_CPU0_SB_DQ<25>")
	)
	(segment
		(start 331.642466 -289.803332)
		(end 331.634084 -289.798506)
		(width 0.0889)
		(layer "In11.Cu")
		(net "M_F_CPU0_SB_DQ<25>")
	)
	(segment
		(start 324.837298 -292.07079)
		(end 324.837298 -292.096698)
		(width 0.0889)
		(layer "In11.Cu")
		(net "M_F_CPU0_SB_DQ<25>")
	)
	(segment
		(start 301.097696 -310.562752)
		(end 300.952916 -310.417972)
		(width 0.14478)
		(layer "In11.Cu")
		(net "M_F_CPU0_SB_DQ<25>")
	)
	(segment
		(start 300.546262 -310.665114)
		(end 300.401482 -310.809894)
		(width 0.14478)
		(layer "In11.Cu")
		(net "M_F_CPU0_SB_DQ<25>")
	)
	(segment
		(start 307.681376 -310.809894)
		(end 307.184552 -310.809894)
		(width 0.14478)
		(layer "In11.Cu")
		(net "M_F_CPU0_SB_DQ<25>")
	)
	(segment
		(start 287.627568 -311.660032)
		(end 287.30829 -311.97931)
		(width 0.14478)
		(layer "In11.Cu")
		(net "M_F_CPU0_SB_DQ<25>")
	)
	(segment
		(start 272.365978 -311.271158)
		(end 272.135346 -311.271158)
		(width 0.14478)
		(layer "In11.Cu")
		(net "M_F_CPU0_SB_DQ<25>")
	)
	(segment
		(start 287.071308 -311.97931)
		(end 285.901892 -310.809894)
		(width 0.14478)
		(layer "In11.Cu")
		(net "M_F_CPU0_SB_DQ<25>")
	)
	(segment
		(start 271.416272 -311.441592)
		(end 271.253458 -311.278778)
		(width 0.14478)
		(layer "In11.Cu")
		(net "M_F_CPU0_SB_DQ<25>")
	)
	(segment
		(start 273.354038 -311.658)
		(end 272.75282 -311.658)
		(width 0.14478)
		(layer "In11.Cu")
		(net "M_F_CPU0_SB_DQ<25>")
	)
	(segment
		(start 285.901892 -310.809894)
		(end 283.338016 -310.809894)
		(width 0.14478)
		(layer "In11.Cu")
		(net "M_F_CPU0_SB_DQ<25>")
	)
	(segment
		(start 297.168062 -311.660032)
		(end 294.39743 -311.660032)
		(width 0.14478)
		(layer "In11.Cu")
		(net "M_F_CPU0_SB_DQ<25>")
	)
	(segment
		(start 302.412654 -311.660032)
		(end 301.562516 -310.809894)
		(width 0.14478)
		(layer "In11.Cu")
		(net "M_F_CPU0_SB_DQ<25>")
	)
	(segment
		(start 301.242476 -310.809894)
		(end 301.097696 -310.665114)
		(width 0.14478)
		(layer "In11.Cu")
		(net "M_F_CPU0_SB_DQ<25>")
	)
	(segment
		(start 281.931618 -311.97169)
		(end 281.61996 -311.660032)
		(width 0.14478)
		(layer "In11.Cu")
		(net "M_F_CPU0_SB_DQ<25>")
	)
	(segment
		(start 300.952916 -310.417972)
		(end 300.691042 -310.417972)
		(width 0.14478)
		(layer "In11.Cu")
		(net "M_F_CPU0_SB_DQ<25>")
	)
	(segment
		(start 274.138644 -311.74817)
		(end 274.138644 -311.429654)
		(width 0.14478)
		(layer "In11.Cu")
		(net "M_F_CPU0_SB_DQ<25>")
	)
	(segment
		(start 278.383492 -310.809894)
		(end 275.588984 -310.809894)
		(width 0.14478)
		(layer "In11.Cu")
		(net "M_F_CPU0_SB_DQ<25>")
	)
	(segment
		(start 305.136042 -311.210452)
		(end 304.686462 -311.660032)
		(width 0.14478)
		(layer "In11.Cu")
		(net "M_F_CPU0_SB_DQ<25>")
	)
	(segment
		(start 299.086524 -310.665114)
		(end 299.086524 -310.555132)
		(width 0.14478)
		(layer "In11.Cu")
		(net "M_F_CPU0_SB_DQ<25>")
	)
	(segment
		(start 289.64382 -311.97169)
		(end 289.399218 -311.97169)
		(width 0.14478)
		(layer "In11.Cu")
		(net "M_F_CPU0_SB_DQ<25>")
	)
	(segment
		(start 289.399218 -311.97169)
		(end 289.08756 -311.660032)
		(width 0.14478)
		(layer "In11.Cu")
		(net "M_F_CPU0_SB_DQ<25>")
	)
	(segment
		(start 294.39743 -311.660032)
		(end 293.547292 -310.809894)
		(width 0.14478)
		(layer "In11.Cu")
		(net "M_F_CPU0_SB_DQ<25>")
	)
	(segment
		(start 293.547292 -310.809894)
		(end 290.805616 -310.809894)
		(width 0.14478)
		(layer "In11.Cu")
		(net "M_F_CPU0_SB_DQ<25>")
	)
	(segment
		(start 300.691042 -310.417972)
		(end 300.546262 -310.562752)
		(width 0.14478)
		(layer "In11.Cu")
		(net "M_F_CPU0_SB_DQ<25>")
	)
	(segment
		(start 306.488338 -310.564276)
		(end 306.343558 -310.419496)
		(width 0.14478)
		(layer "In11.Cu")
		(net "M_F_CPU0_SB_DQ<25>")
	)
	(segment
		(start 275.588984 -310.809894)
		(end 274.500848 -311.89803)
		(width 0.14478)
		(layer "In11.Cu")
		(net "M_F_CPU0_SB_DQ<25>")
	)
	(segment
		(start 305.792124 -311.210452)
		(end 305.136042 -311.210452)
		(width 0.14478)
		(layer "In11.Cu")
		(net "M_F_CPU0_SB_DQ<25>")
	)
	(segment
		(start 282.17622 -311.97169)
		(end 281.931618 -311.97169)
		(width 0.14478)
		(layer "In11.Cu")
		(net "M_F_CPU0_SB_DQ<25>")
	)
	(segment
		(start 283.338016 -310.809894)
		(end 282.17622 -311.97169)
		(width 0.14478)
		(layer "In11.Cu")
		(net "M_F_CPU0_SB_DQ<25>")
	)
	(segment
		(start 306.343558 -310.419496)
		(end 306.081684 -310.419496)
		(width 0.14478)
		(layer "In11.Cu")
		(net "M_F_CPU0_SB_DQ<25>")
	)
	(segment
		(start 306.894992 -311.200292)
		(end 306.633118 -311.200292)
		(width 0.14478)
		(layer "In11.Cu")
		(net "M_F_CPU0_SB_DQ<25>")
	)
	(segment
		(start 307.039772 -310.954674)
		(end 307.039772 -311.055512)
		(width 0.14478)
		(layer "In11.Cu")
		(net "M_F_CPU0_SB_DQ<25>")
	)
	(segment
		(start 280.083768 -311.660032)
		(end 279.78989 -311.95391)
		(width 0.14478)
		(layer "In11.Cu")
		(net "M_F_CPU0_SB_DQ<25>")
	)
	(segment
		(start 298.39031 -310.809894)
		(end 298.0182 -310.809894)
		(width 0.14478)
		(layer "In11.Cu")
		(net "M_F_CPU0_SB_DQ<25>")
	)
	(segment
		(start 299.086524 -310.555132)
		(end 298.941744 -310.410352)
		(width 0.14478)
		(layer "In11.Cu")
		(net "M_F_CPU0_SB_DQ<25>")
	)
	(segment
		(start 330.702412 -289.803332)
		(end 330.69403 -289.798506)
		(width 0.0889)
		(layer "In11.Cu")
		(net "M_F_CPU0_SB_DQ<25>")
	)
	(segment
		(start 306.633118 -311.200292)
		(end 306.488338 -311.055512)
		(width 0.14478)
		(layer "In11.Cu")
		(net "M_F_CPU0_SB_DQ<25>")
	)
	(segment
		(start 300.546262 -310.562752)
		(end 300.546262 -310.665114)
		(width 0.14478)
		(layer "In11.Cu")
		(net "M_F_CPU0_SB_DQ<25>")
	)
	(segment
		(start 271.972532 -311.875424)
		(end 271.809718 -312.038238)
		(width 0.14478)
		(layer "In11.Cu")
		(net "M_F_CPU0_SB_DQ<25>")
	)
	(segment
		(start 274.500848 -311.89803)
		(end 274.288504 -311.89803)
		(width 0.14478)
		(layer "In11.Cu")
		(net "M_F_CPU0_SB_DQ<25>")
	)
	(segment
		(start 325.84771 -291.060378)
		(end 324.837298 -292.07079)
		(width 0.0889)
		(layer "In11.Cu")
		(net "M_F_CPU0_SB_DQ<25>")
	)
	(segment
		(start 305.936904 -311.065672)
		(end 305.792124 -311.210452)
		(width 0.14478)
		(layer "In11.Cu")
		(net "M_F_CPU0_SB_DQ<25>")
	)
	(segment
		(start 272.75282 -311.658)
		(end 272.365978 -311.271158)
		(width 0.14478)
		(layer "In11.Cu")
		(net "M_F_CPU0_SB_DQ<25>")
	)
	(segment
		(start 301.097696 -310.665114)
		(end 301.097696 -310.562752)
		(width 0.14478)
		(layer "In11.Cu")
		(net "M_F_CPU0_SB_DQ<25>")
	)
	(segment
		(start 300.401482 -310.809894)
		(end 299.231304 -310.809894)
		(width 0.14478)
		(layer "In11.Cu")
		(net "M_F_CPU0_SB_DQ<25>")
	)
	(segment
		(start 298.53509 -310.555132)
		(end 298.53509 -310.665114)
		(width 0.14478)
		(layer "In11.Cu")
		(net "M_F_CPU0_SB_DQ<25>")
	)
	(segment
		(start 271.416272 -311.875424)
		(end 271.416272 -311.441592)
		(width 0.14478)
		(layer "In11.Cu")
		(net "M_F_CPU0_SB_DQ<25>")
	)
	(segment
		(start 298.53509 -310.665114)
		(end 298.39031 -310.809894)
		(width 0.14478)
		(layer "In11.Cu")
		(net "M_F_CPU0_SB_DQ<25>")
	)
	(segment
		(start 271.809718 -312.038238)
		(end 271.579086 -312.038238)
		(width 0.14478)
		(layer "In11.Cu")
		(net "M_F_CPU0_SB_DQ<25>")
	)
	(segment
		(start 272.135346 -311.271158)
		(end 271.972532 -311.433972)
		(width 0.14478)
		(layer "In11.Cu")
		(net "M_F_CPU0_SB_DQ<25>")
	)
	(segment
		(start 270.860012 -311.441592)
		(end 270.860012 -311.875424)
		(width 0.14478)
		(layer "In11.Cu")
		(net "M_F_CPU0_SB_DQ<25>")
	)
	(segment
		(start 301.562516 -310.809894)
		(end 301.242476 -310.809894)
		(width 0.14478)
		(layer "In11.Cu")
		(net "M_F_CPU0_SB_DQ<25>")
	)
	(segment
		(start 327.318116 -289.79241)
		(end 327.307702 -289.798506)
		(width 0.0889)
		(layer "In11.Cu")
		(net "M_F_CPU0_SB_DQ<25>")
	)
	(segment
		(start 306.081684 -310.419496)
		(end 305.936904 -310.564276)
		(width 0.14478)
		(layer "In11.Cu")
		(net "M_F_CPU0_SB_DQ<25>")
	)
	(segment
		(start 325.84771 -290.65982)
		(end 325.84771 -291.060378)
		(width 0.0889)
		(layer "In11.Cu")
		(net "M_F_CPU0_SB_DQ<25>")
	)
	(segment
		(start 299.231304 -310.809894)
		(end 299.086524 -310.665114)
		(width 0.14478)
		(layer "In11.Cu")
		(net "M_F_CPU0_SB_DQ<25>")
	)
	(segment
		(start 307.039772 -311.055512)
		(end 306.894992 -311.200292)
		(width 0.14478)
		(layer "In11.Cu")
		(net "M_F_CPU0_SB_DQ<25>")
	)
	(segment
		(start 307.184552 -310.809894)
		(end 307.039772 -310.954674)
		(width 0.14478)
		(layer "In11.Cu")
		(net "M_F_CPU0_SB_DQ<25>")
	)
	(segment
		(start 274.138644 -311.429654)
		(end 273.97583 -311.26684)
		(width 0.14478)
		(layer "In11.Cu")
		(net "M_F_CPU0_SB_DQ<25>")
	)
	(segment
		(start 270.697198 -312.038238)
		(end 270.451326 -312.038238)
		(width 0.14478)
		(layer "In11.Cu")
		(net "M_F_CPU0_SB_DQ<25>")
	)
	(segment
		(start 271.022826 -311.278778)
		(end 270.860012 -311.441592)
		(width 0.14478)
		(layer "In11.Cu")
		(net "M_F_CPU0_SB_DQ<25>")
	)
	(segment
		(start 290.805616 -310.809894)
		(end 289.64382 -311.97169)
		(width 0.14478)
		(layer "In11.Cu")
		(net "M_F_CPU0_SB_DQ<25>")
	)
	(segment
		(start 298.941744 -310.410352)
		(end 298.67987 -310.410352)
		(width 0.14478)
		(layer "In11.Cu")
		(net "M_F_CPU0_SB_DQ<25>")
	)
	(segment
		(start 326.851264 -289.842956)
		(end 326.563482 -289.922458)
		(width 0.0889)
		(layer "In11.Cu")
		(net "M_F_CPU0_SB_DQ<25>")
	)
	(segment
		(start 289.08756 -311.660032)
		(end 287.627568 -311.660032)
		(width 0.14478)
		(layer "In11.Cu")
		(net "M_F_CPU0_SB_DQ<25>")
	)
	(segment
		(start 330.128118 -289.798506)
		(end 330.119736 -289.803332)
		(width 0.0889)
		(layer "In11.Cu")
		(net "M_F_CPU0_SB_DQ<25>")
	)
	(segment
		(start 309.908956 -307.02504)
		(end 309.908956 -308.582314)
		(width 0.14478)
		(layer "In11.Cu")
		(net "M_F_CPU0_SB_DQ<25>")
	)
	(segment
		(start 273.97583 -311.26684)
		(end 273.745198 -311.26684)
		(width 0.14478)
		(layer "In11.Cu")
		(net "M_F_CPU0_SB_DQ<25>")
	)
	(segment
		(start 281.61996 -311.660032)
		(end 280.083768 -311.660032)
		(width 0.14478)
		(layer "In11.Cu")
		(net "M_F_CPU0_SB_DQ<25>")
	)
	(segment
		(start 271.253458 -311.278778)
		(end 271.022826 -311.278778)
		(width 0.14478)
		(layer "In11.Cu")
		(net "M_F_CPU0_SB_DQ<25>")
	)
	(segment
		(start 271.579086 -312.038238)
		(end 271.416272 -311.875424)
		(width 0.14478)
		(layer "In11.Cu")
		(net "M_F_CPU0_SB_DQ<25>")
	)
	(segment
		(start 270.860012 -311.875424)
		(end 270.697198 -312.038238)
		(width 0.14478)
		(layer "In11.Cu")
		(net "M_F_CPU0_SB_DQ<25>")
	)
	(arc
		(start 328.814176 -289.798506)
		(mid 328.53122 -289.722329)
		(end 328.248264 -289.798506)
		(width 0.0889)
		(layer "In11.Cu")
		(net "M_F_CPU0_SB_DQ<25>")
	)
	(arc
		(start 325.8947 -290.546282)
		(mid 325.859947 -290.598388)
		(end 325.84771 -290.65982)
		(width 0.0889)
		(layer "In11.Cu")
		(net "M_F_CPU0_SB_DQ<25>")
	)
	(arc
		(start 329.753976 -289.798506)
		(mid 329.47102 -289.722329)
		(end 329.188064 -289.798506)
		(width 0.0889)
		(layer "In11.Cu")
		(net "M_F_CPU0_SB_DQ<25>")
	)
	(arc
		(start 330.119736 -289.803332)
		(mid 329.936228 -289.848826)
		(end 329.753976 -289.798506)
		(width 0.0889)
		(layer "In11.Cu")
		(net "M_F_CPU0_SB_DQ<25>")
	)
	(arc
		(start 327.307702 -289.798506)
		(mid 327.175571 -289.844833)
		(end 327.035668 -289.839146)
		(width 0.0889)
		(layer "In11.Cu")
		(net "M_F_CPU0_SB_DQ<25>")
	)
	(arc
		(start 332.948026 -289.798506)
		(mid 332.761082 -289.848761)
		(end 332.574138 -289.798506)
		(width 0.0889)
		(layer "In11.Cu")
		(net "M_F_CPU0_SB_DQ<25>")
	)
	(arc
		(start 333.832708 -289.824668)
		(mid 333.670376 -289.847486)
		(end 333.513938 -289.798506)
		(width 0.0889)
		(layer "In11.Cu")
		(net "M_F_CPU0_SB_DQ<25>")
	)
	(arc
		(start 327.873868 -289.798506)
		(mid 327.596801 -289.722235)
		(end 327.318116 -289.79241)
		(width 0.0889)
		(layer "In11.Cu")
		(net "M_F_CPU0_SB_DQ<25>")
	)
	(arc
		(start 329.188064 -289.798506)
		(mid 329.00112 -289.848761)
		(end 328.814176 -289.798506)
		(width 0.0889)
		(layer "In11.Cu")
		(net "M_F_CPU0_SB_DQ<25>")
	)
	(arc
		(start 326.563482 -289.922458)
		(mid 326.505411 -289.946938)
		(end 326.455532 -289.98545)
		(width 0.0889)
		(layer "In11.Cu")
		(net "M_F_CPU0_SB_DQ<25>")
	)
	(arc
		(start 333.513938 -289.798506)
		(mid 333.230982 -289.722329)
		(end 332.948026 -289.798506)
		(width 0.0889)
		(layer "In11.Cu")
		(net "M_F_CPU0_SB_DQ<25>")
	)
	(arc
		(start 327.035668 -289.839146)
		(mid 326.943223 -289.829441)
		(end 326.851264 -289.842956)
		(width 0.0889)
		(layer "In11.Cu")
		(net "M_F_CPU0_SB_DQ<25>")
	)
	(arc
		(start 331.068172 -289.798506)
		(mid 330.885921 -289.848856)
		(end 330.702412 -289.803332)
		(width 0.0889)
		(layer "In11.Cu")
		(net "M_F_CPU0_SB_DQ<25>")
	)
	(arc
		(start 330.69403 -289.798506)
		(mid 330.411074 -289.722329)
		(end 330.128118 -289.798506)
		(width 0.0889)
		(layer "In11.Cu")
		(net "M_F_CPU0_SB_DQ<25>")
	)
	(arc
		(start 328.248264 -289.798506)
		(mid 328.061066 -289.848888)
		(end 327.873868 -289.798506)
		(width 0.0889)
		(layer "In11.Cu")
		(net "M_F_CPU0_SB_DQ<25>")
	)
	(arc
		(start 332.008226 -289.798506)
		(mid 331.825975 -289.848856)
		(end 331.642466 -289.803332)
		(width 0.0889)
		(layer "In11.Cu")
		(net "M_F_CPU0_SB_DQ<25>")
	)
	(arc
		(start 332.574138 -289.798506)
		(mid 332.291182 -289.722329)
		(end 332.008226 -289.798506)
		(width 0.0889)
		(layer "In11.Cu")
		(net "M_F_CPU0_SB_DQ<25>")
	)
	(arc
		(start 331.634084 -289.798506)
		(mid 331.351128 -289.722329)
		(end 331.068172 -289.798506)
		(width 0.0889)
		(layer "In11.Cu")
		(net "M_F_CPU0_SB_DQ<25>")
	)
	(segment
		(start 332.758034 -288.399982)
		(end 332.291182 -288.66592)
		(width 0.10668)
		(layer "F.Cu")
		(net "M_F_CPU0_SB_DQ<24>")
	)
	(segment
		(start 302.149256 -309.96763)
		(end 302.149256 -309.762906)
		(width 0.14478)
		(layer "In11.Cu")
		(net "M_F_CPU0_SB_DQ<24>")
	)
	(segment
		(start 332.445106 -288.93135)
		(end 332.422754 -289.014662)
		(width 0.0889)
		(layer "In11.Cu")
		(net "M_F_CPU0_SB_DQ<24>")
	)
	(segment
		(start 305.540156 -309.520082)
		(end 305.099974 -309.960264)
		(width 0.14478)
		(layer "In11.Cu")
		(net "M_F_CPU0_SB_DQ<24>")
	)
	(segment
		(start 273.316446 -309.960264)
		(end 272.645378 -309.960264)
		(width 0.14478)
		(layer "In11.Cu")
		(net "M_F_CPU0_SB_DQ<24>")
	)
	(segment
		(start 308.13375 -308.32552)
		(end 307.94833 -308.51094)
		(width 0.14478)
		(layer "In11.Cu")
		(net "M_F_CPU0_SB_DQ<24>")
	)
	(segment
		(start 327.778872 -288.988246)
		(end 327.765156 -288.99612)
		(width 0.0889)
		(layer "In11.Cu")
		(net "M_F_CPU0_SB_DQ<24>")
	)
	(segment
		(start 302.69815 -310.26735)
		(end 302.448976 -310.26735)
		(width 0.14478)
		(layer "In11.Cu")
		(net "M_F_CPU0_SB_DQ<24>")
	)
	(segment
		(start 307.94833 -308.715664)
		(end 308.048152 -308.815486)
		(width 0.14478)
		(layer "In11.Cu")
		(net "M_F_CPU0_SB_DQ<24>")
	)
	(segment
		(start 280.010108 -309.960264)
		(end 279.690322 -310.28005)
		(width 0.14478)
		(layer "In11.Cu")
		(net "M_F_CPU0_SB_DQ<24>")
	)
	(segment
		(start 270.85798 -309.841646)
		(end 270.85798 -310.18861)
		(width 0.14478)
		(layer "In11.Cu")
		(net "M_F_CPU0_SB_DQ<24>")
	)
	(segment
		(start 308.891178 -306.619148)
		(end 308.891178 -308.177184)
		(width 0.14478)
		(layer "In11.Cu")
		(net "M_F_CPU0_SB_DQ<24>")
	)
	(segment
		(start 298.773088 -309.110126)
		(end 298.431712 -309.110126)
		(width 0.14478)
		(layer "In11.Cu")
		(net "M_F_CPU0_SB_DQ<24>")
	)
	(segment
		(start 302.250602 -309.456836)
		(end 302.065182 -309.271416)
		(width 0.14478)
		(layer "In11.Cu")
		(net "M_F_CPU0_SB_DQ<24>")
	)
	(segment
		(start 302.250602 -309.66156)
		(end 302.250602 -309.456836)
		(width 0.14478)
		(layer "In11.Cu")
		(net "M_F_CPU0_SB_DQ<24>")
	)
	(segment
		(start 272.363946 -309.678832)
		(end 272.133314 -309.678832)
		(width 0.14478)
		(layer "In11.Cu")
		(net "M_F_CPU0_SB_DQ<24>")
	)
	(segment
		(start 297.025314 -310.28005)
		(end 296.705528 -309.960264)
		(width 0.14478)
		(layer "In11.Cu")
		(net "M_F_CPU0_SB_DQ<24>")
	)
	(segment
		(start 270.695166 -310.351424)
		(end 270.464534 -310.351424)
		(width 0.14478)
		(layer "In11.Cu")
		(net "M_F_CPU0_SB_DQ<24>")
	)
	(segment
		(start 272.133314 -309.678832)
		(end 271.9705 -309.841646)
		(width 0.14478)
		(layer "In11.Cu")
		(net "M_F_CPU0_SB_DQ<24>")
	)
	(segment
		(start 307.612542 -309.45582)
		(end 307.051964 -309.45582)
		(width 0.14478)
		(layer "In11.Cu")
		(net "M_F_CPU0_SB_DQ<24>")
	)
	(segment
		(start 329.292458 -288.993326)
		(end 329.284076 -288.9885)
		(width 0.0889)
		(layer "In11.Cu")
		(net "M_F_CPU0_SB_DQ<24>")
	)
	(segment
		(start 299.329348 -309.42661)
		(end 299.089572 -309.42661)
		(width 0.14478)
		(layer "In11.Cu")
		(net "M_F_CPU0_SB_DQ<24>")
	)
	(segment
		(start 282.056586 -310.25211)
		(end 281.76474 -309.960264)
		(width 0.14478)
		(layer "In11.Cu")
		(net "M_F_CPU0_SB_DQ<24>")
	)
	(segment
		(start 282.321 -310.25211)
		(end 282.056586 -310.25211)
		(width 0.14478)
		(layer "In11.Cu")
		(net "M_F_CPU0_SB_DQ<24>")
	)
	(segment
		(start 308.438296 -308.425342)
		(end 308.338474 -308.32552)
		(width 0.14478)
		(layer "In11.Cu")
		(net "M_F_CPU0_SB_DQ<24>")
	)
	(segment
		(start 302.448976 -310.26735)
		(end 302.149256 -309.96763)
		(width 0.14478)
		(layer "In11.Cu")
		(net "M_F_CPU0_SB_DQ<24>")
	)
	(segment
		(start 273.687032 -310.33085)
		(end 273.316446 -309.960264)
		(width 0.14478)
		(layer "In11.Cu")
		(net "M_F_CPU0_SB_DQ<24>")
	)
	(segment
		(start 306.21097 -309.520082)
		(end 305.540156 -309.520082)
		(width 0.14478)
		(layer "In11.Cu")
		(net "M_F_CPU0_SB_DQ<24>")
	)
	(segment
		(start 327.405238 -288.9885)
		(end 327.387204 -288.977832)
		(width 0.0889)
		(layer "In11.Cu")
		(net "M_F_CPU0_SB_DQ<24>")
	)
	(segment
		(start 296.705528 -309.960264)
		(end 295.100248 -309.960264)
		(width 0.14478)
		(layer "In11.Cu")
		(net "M_F_CPU0_SB_DQ<24>")
	)
	(segment
		(start 299.645832 -309.110126)
		(end 299.329348 -309.42661)
		(width 0.14478)
		(layer "In11.Cu")
		(net "M_F_CPU0_SB_DQ<24>")
	)
	(segment
		(start 289.4711 -309.960264)
		(end 289.196526 -309.960264)
		(width 0.14478)
		(layer "In11.Cu")
		(net "M_F_CPU0_SB_DQ<24>")
	)
	(segment
		(start 271.020794 -309.678832)
		(end 270.85798 -309.841646)
		(width 0.14478)
		(layer "In11.Cu")
		(net "M_F_CPU0_SB_DQ<24>")
	)
	(segment
		(start 271.9705 -310.18099)
		(end 271.807686 -310.343804)
		(width 0.14478)
		(layer "In11.Cu")
		(net "M_F_CPU0_SB_DQ<24>")
	)
	(segment
		(start 274.243292 -309.67045)
		(end 274.080478 -309.833264)
		(width 0.14478)
		(layer "In11.Cu")
		(net "M_F_CPU0_SB_DQ<24>")
	)
	(segment
		(start 279.690322 -310.28005)
		(end 279.453848 -310.28005)
		(width 0.14478)
		(layer "In11.Cu")
		(net "M_F_CPU0_SB_DQ<24>")
	)
	(segment
		(start 288.640266 -310.24195)
		(end 288.35858 -309.960264)
		(width 0.14478)
		(layer "In11.Cu")
		(net "M_F_CPU0_SB_DQ<24>")
	)
	(segment
		(start 287.157922 -310.28005)
		(end 286.921448 -310.28005)
		(width 0.14478)
		(layer "In11.Cu")
		(net "M_F_CPU0_SB_DQ<24>")
	)
	(segment
		(start 297.261788 -310.28005)
		(end 297.025314 -310.28005)
		(width 0.14478)
		(layer "In11.Cu")
		(net "M_F_CPU0_SB_DQ<24>")
	)
	(segment
		(start 271.9705 -309.841646)
		(end 271.9705 -310.18099)
		(width 0.14478)
		(layer "In11.Cu")
		(net "M_F_CPU0_SB_DQ<24>")
	)
	(segment
		(start 271.41424 -309.841646)
		(end 271.251426 -309.678832)
		(width 0.14478)
		(layer "In11.Cu")
		(net "M_F_CPU0_SB_DQ<24>")
	)
	(segment
		(start 271.41424 -310.18099)
		(end 271.41424 -309.841646)
		(width 0.14478)
		(layer "In11.Cu")
		(net "M_F_CPU0_SB_DQ<24>")
	)
	(segment
		(start 306.35575 -309.375302)
		(end 306.21097 -309.520082)
		(width 0.14478)
		(layer "In11.Cu")
		(net "M_F_CPU0_SB_DQ<24>")
	)
	(segment
		(start 331.538072 -288.9885)
		(end 331.52969 -288.993326)
		(width 0.0889)
		(layer "In11.Cu")
		(net "M_F_CPU0_SB_DQ<24>")
	)
	(segment
		(start 274.992846 -309.960264)
		(end 274.763738 -309.960264)
		(width 0.14478)
		(layer "In11.Cu")
		(net "M_F_CPU0_SB_DQ<24>")
	)
	(segment
		(start 326.651112 -289.0393)
		(end 326.348344 -289.0393)
		(width 0.0889)
		(layer "In11.Cu")
		(net "M_F_CPU0_SB_DQ<24>")
	)
	(segment
		(start 295.100248 -309.960264)
		(end 294.777922 -310.28259)
		(width 0.14478)
		(layer "In11.Cu")
		(net "M_F_CPU0_SB_DQ<24>")
	)
	(segment
		(start 278.283924 -309.110126)
		(end 275.842984 -309.110126)
		(width 0.14478)
		(layer "In11.Cu")
		(net "M_F_CPU0_SB_DQ<24>")
	)
	(segment
		(start 273.917664 -310.33085)
		(end 273.687032 -310.33085)
		(width 0.14478)
		(layer "In11.Cu")
		(net "M_F_CPU0_SB_DQ<24>")
	)
	(segment
		(start 274.080478 -310.168036)
		(end 273.917664 -310.33085)
		(width 0.14478)
		(layer "In11.Cu")
		(net "M_F_CPU0_SB_DQ<24>")
	)
	(segment
		(start 302.065182 -309.271416)
		(end 301.860458 -309.271416)
		(width 0.14478)
		(layer "In11.Cu")
		(net "M_F_CPU0_SB_DQ<24>")
	)
	(segment
		(start 275.842984 -309.110126)
		(end 274.992846 -309.960264)
		(width 0.14478)
		(layer "In11.Cu")
		(net "M_F_CPU0_SB_DQ<24>")
	)
	(segment
		(start 327.79081 -288.981388)
		(end 327.778872 -288.988246)
		(width 0.0889)
		(layer "In11.Cu")
		(net "M_F_CPU0_SB_DQ<24>")
	)
	(segment
		(start 304.117756 -309.960264)
		(end 303.81067 -310.26735)
		(width 0.14478)
		(layer "In11.Cu")
		(net "M_F_CPU0_SB_DQ<24>")
	)
	(segment
		(start 274.080478 -309.833264)
		(end 274.080478 -310.168036)
		(width 0.14478)
		(layer "In11.Cu")
		(net "M_F_CPU0_SB_DQ<24>")
	)
	(segment
		(start 305.099974 -309.960264)
		(end 304.117756 -309.960264)
		(width 0.14478)
		(layer "In11.Cu")
		(net "M_F_CPU0_SB_DQ<24>")
	)
	(segment
		(start 286.921448 -310.28005)
		(end 285.751524 -309.110126)
		(width 0.14478)
		(layer "In11.Cu")
		(net "M_F_CPU0_SB_DQ<24>")
	)
	(segment
		(start 301.291752 -309.110126)
		(end 300.995588 -309.110126)
		(width 0.14478)
		(layer "In11.Cu")
		(net "M_F_CPU0_SB_DQ<24>")
	)
	(segment
		(start 301.554388 -309.372762)
		(end 301.291752 -309.110126)
		(width 0.14478)
		(layer "In11.Cu")
		(net "M_F_CPU0_SB_DQ<24>")
	)
	(segment
		(start 285.751524 -309.110126)
		(end 283.462984 -309.110126)
		(width 0.14478)
		(layer "In11.Cu")
		(net "M_F_CPU0_SB_DQ<24>")
	)
	(segment
		(start 324.640194 -290.870132)
		(end 323.895974 -291.614352)
		(width 0.0889)
		(layer "In11.Cu")
		(net "M_F_CPU0_SB_DQ<24>")
	)
	(segment
		(start 288.91484 -310.24195)
		(end 288.640266 -310.24195)
		(width 0.14478)
		(layer "In11.Cu")
		(net "M_F_CPU0_SB_DQ<24>")
	)
	(segment
		(start 307.94833 -308.51094)
		(end 307.94833 -308.715664)
		(width 0.14478)
		(layer "In11.Cu")
		(net "M_F_CPU0_SB_DQ<24>")
	)
	(segment
		(start 308.048152 -308.815486)
		(end 308.048152 -309.02021)
		(width 0.14478)
		(layer "In11.Cu")
		(net "M_F_CPU0_SB_DQ<24>")
	)
	(segment
		(start 300.439328 -309.42407)
		(end 300.125384 -309.110126)
		(width 0.14478)
		(layer "In11.Cu")
		(net "M_F_CPU0_SB_DQ<24>")
	)
	(segment
		(start 303.561496 -310.26735)
		(end 303.25441 -309.960264)
		(width 0.14478)
		(layer "In11.Cu")
		(net "M_F_CPU0_SB_DQ<24>")
	)
	(segment
		(start 302.149256 -309.762906)
		(end 302.250602 -309.66156)
		(width 0.14478)
		(layer "In11.Cu")
		(net "M_F_CPU0_SB_DQ<24>")
	)
	(segment
		(start 301.759112 -309.372762)
		(end 301.554388 -309.372762)
		(width 0.14478)
		(layer "In11.Cu")
		(net "M_F_CPU0_SB_DQ<24>")
	)
	(segment
		(start 298.431712 -309.110126)
		(end 297.261788 -310.28005)
		(width 0.14478)
		(layer "In11.Cu")
		(net "M_F_CPU0_SB_DQ<24>")
	)
	(segment
		(start 283.462984 -309.110126)
		(end 282.321 -310.25211)
		(width 0.14478)
		(layer "In11.Cu")
		(net "M_F_CPU0_SB_DQ<24>")
	)
	(segment
		(start 289.196526 -309.960264)
		(end 288.91484 -310.24195)
		(width 0.14478)
		(layer "In11.Cu")
		(net "M_F_CPU0_SB_DQ<24>")
	)
	(segment
		(start 301.860458 -309.271416)
		(end 301.759112 -309.372762)
		(width 0.14478)
		(layer "In11.Cu")
		(net "M_F_CPU0_SB_DQ<24>")
	)
	(segment
		(start 308.048152 -309.02021)
		(end 307.612542 -309.45582)
		(width 0.14478)
		(layer "In11.Cu")
		(net "M_F_CPU0_SB_DQ<24>")
	)
	(segment
		(start 306.762404 -308.553612)
		(end 306.50053 -308.553612)
		(width 0.14478)
		(layer "In11.Cu")
		(net "M_F_CPU0_SB_DQ<24>")
	)
	(segment
		(start 279.453848 -310.28005)
		(end 278.283924 -309.110126)
		(width 0.14478)
		(layer "In11.Cu")
		(net "M_F_CPU0_SB_DQ<24>")
	)
	(segment
		(start 308.891178 -308.177184)
		(end 308.64302 -308.425342)
		(width 0.14478)
		(layer "In11.Cu")
		(net "M_F_CPU0_SB_DQ<24>")
	)
	(segment
		(start 328.718164 -288.9885)
		(end 328.709782 -288.993326)
		(width 0.0889)
		(layer "In11.Cu")
		(net "M_F_CPU0_SB_DQ<24>")
	)
	(segment
		(start 274.763738 -309.960264)
		(end 274.473924 -309.67045)
		(width 0.14478)
		(layer "In11.Cu")
		(net "M_F_CPU0_SB_DQ<24>")
	)
	(segment
		(start 271.577054 -310.343804)
		(end 271.41424 -310.18099)
		(width 0.14478)
		(layer "In11.Cu")
		(net "M_F_CPU0_SB_DQ<24>")
	)
	(segment
		(start 271.807686 -310.343804)
		(end 271.577054 -310.343804)
		(width 0.14478)
		(layer "In11.Cu")
		(net "M_F_CPU0_SB_DQ<24>")
	)
	(segment
		(start 306.50053 -308.553612)
		(end 306.35575 -308.698392)
		(width 0.14478)
		(layer "In11.Cu")
		(net "M_F_CPU0_SB_DQ<24>")
	)
	(segment
		(start 289.752786 -310.24195)
		(end 289.4711 -309.960264)
		(width 0.14478)
		(layer "In11.Cu")
		(net "M_F_CPU0_SB_DQ<24>")
	)
	(segment
		(start 300.681644 -309.42407)
		(end 300.439328 -309.42407)
		(width 0.14478)
		(layer "In11.Cu")
		(net "M_F_CPU0_SB_DQ<24>")
	)
	(segment
		(start 324.640194 -290.74745)
		(end 324.640194 -290.870132)
		(width 0.0889)
		(layer "In11.Cu")
		(net "M_F_CPU0_SB_DQ<24>")
	)
	(segment
		(start 271.251426 -309.678832)
		(end 271.020794 -309.678832)
		(width 0.14478)
		(layer "In11.Cu")
		(net "M_F_CPU0_SB_DQ<24>")
	)
	(segment
		(start 299.089572 -309.42661)
		(end 298.773088 -309.110126)
		(width 0.14478)
		(layer "In11.Cu")
		(net "M_F_CPU0_SB_DQ<24>")
	)
	(segment
		(start 306.907184 -308.698392)
		(end 306.762404 -308.553612)
		(width 0.14478)
		(layer "In11.Cu")
		(net "M_F_CPU0_SB_DQ<24>")
	)
	(segment
		(start 303.81067 -310.26735)
		(end 303.561496 -310.26735)
		(width 0.14478)
		(layer "In11.Cu")
		(net "M_F_CPU0_SB_DQ<24>")
	)
	(segment
		(start 287.477708 -309.960264)
		(end 287.157922 -310.28005)
		(width 0.14478)
		(layer "In11.Cu")
		(net "M_F_CPU0_SB_DQ<24>")
	)
	(segment
		(start 293.371524 -309.110126)
		(end 291.159184 -309.110126)
		(width 0.14478)
		(layer "In11.Cu")
		(net "M_F_CPU0_SB_DQ<24>")
	)
	(segment
		(start 294.543988 -310.28259)
		(end 293.371524 -309.110126)
		(width 0.14478)
		(layer "In11.Cu")
		(net "M_F_CPU0_SB_DQ<24>")
	)
	(segment
		(start 270.464534 -310.351424)
		(end 269.648178 -309.535068)
		(width 0.14478)
		(layer "In11.Cu")
		(net "M_F_CPU0_SB_DQ<24>")
	)
	(segment
		(start 307.051964 -309.45582)
		(end 306.907184 -309.31104)
		(width 0.14478)
		(layer "In11.Cu")
		(net "M_F_CPU0_SB_DQ<24>")
	)
	(segment
		(start 308.338474 -308.32552)
		(end 308.13375 -308.32552)
		(width 0.14478)
		(layer "In11.Cu")
		(net "M_F_CPU0_SB_DQ<24>")
	)
	(segment
		(start 288.35858 -309.960264)
		(end 287.477708 -309.960264)
		(width 0.14478)
		(layer "In11.Cu")
		(net "M_F_CPU0_SB_DQ<24>")
	)
	(segment
		(start 326.348344 -289.0393)
		(end 324.640194 -290.74745)
		(width 0.0889)
		(layer "In11.Cu")
		(net "M_F_CPU0_SB_DQ<24>")
	)
	(segment
		(start 303.005236 -309.960264)
		(end 302.69815 -310.26735)
		(width 0.14478)
		(layer "In11.Cu")
		(net "M_F_CPU0_SB_DQ<24>")
	)
	(segment
		(start 308.64302 -308.425342)
		(end 308.438296 -308.425342)
		(width 0.14478)
		(layer "In11.Cu")
		(net "M_F_CPU0_SB_DQ<24>")
	)
	(segment
		(start 300.995588 -309.110126)
		(end 300.681644 -309.42407)
		(width 0.14478)
		(layer "In11.Cu")
		(net "M_F_CPU0_SB_DQ<24>")
	)
	(segment
		(start 274.473924 -309.67045)
		(end 274.243292 -309.67045)
		(width 0.14478)
		(layer "In11.Cu")
		(net "M_F_CPU0_SB_DQ<24>")
	)
	(segment
		(start 332.291182 -288.66592)
		(end 332.445106 -288.93135)
		(width 0.0889)
		(layer "In11.Cu")
		(net "M_F_CPU0_SB_DQ<24>")
	)
	(segment
		(start 270.85798 -310.18861)
		(end 270.695166 -310.351424)
		(width 0.14478)
		(layer "In11.Cu")
		(net "M_F_CPU0_SB_DQ<24>")
	)
	(segment
		(start 281.76474 -309.960264)
		(end 280.010108 -309.960264)
		(width 0.14478)
		(layer "In11.Cu")
		(net "M_F_CPU0_SB_DQ<24>")
	)
	(segment
		(start 291.159184 -309.110126)
		(end 290.02736 -310.24195)
		(width 0.14478)
		(layer "In11.Cu")
		(net "M_F_CPU0_SB_DQ<24>")
	)
	(segment
		(start 300.125384 -309.110126)
		(end 299.645832 -309.110126)
		(width 0.14478)
		(layer "In11.Cu")
		(net "M_F_CPU0_SB_DQ<24>")
	)
	(segment
		(start 306.907184 -309.31104)
		(end 306.907184 -308.698392)
		(width 0.14478)
		(layer "In11.Cu")
		(net "M_F_CPU0_SB_DQ<24>")
	)
	(segment
		(start 303.25441 -309.960264)
		(end 303.005236 -309.960264)
		(width 0.14478)
		(layer "In11.Cu")
		(net "M_F_CPU0_SB_DQ<24>")
	)
	(segment
		(start 290.02736 -310.24195)
		(end 289.752786 -310.24195)
		(width 0.14478)
		(layer "In11.Cu")
		(net "M_F_CPU0_SB_DQ<24>")
	)
	(segment
		(start 323.895974 -291.614352)
		(end 308.891178 -306.619148)
		(width 0.14478)
		(layer "In11.Cu")
		(net "M_F_CPU0_SB_DQ<24>")
	)
	(segment
		(start 294.777922 -310.28259)
		(end 294.543988 -310.28259)
		(width 0.14478)
		(layer "In11.Cu")
		(net "M_F_CPU0_SB_DQ<24>")
	)
	(segment
		(start 306.35575 -308.698392)
		(end 306.35575 -309.375302)
		(width 0.14478)
		(layer "In11.Cu")
		(net "M_F_CPU0_SB_DQ<24>")
	)
	(segment
		(start 272.645378 -309.960264)
		(end 272.363946 -309.678832)
		(width 0.14478)
		(layer "In11.Cu")
		(net "M_F_CPU0_SB_DQ<24>")
	)
	(arc
		(start 327.387204 -288.977832)
		(mid 327.111509 -288.911989)
		(end 326.838564 -288.9885)
		(width 0.0889)
		(layer "In11.Cu")
		(net "M_F_CPU0_SB_DQ<24>")
	)
	(arc
		(start 330.22413 -288.9885)
		(mid 329.941174 -288.912323)
		(end 329.658218 -288.9885)
		(width 0.0889)
		(layer "In11.Cu")
		(net "M_F_CPU0_SB_DQ<24>")
	)
	(arc
		(start 326.838564 -288.9885)
		(mid 326.748201 -289.02631)
		(end 326.651112 -289.0393)
		(width 0.0889)
		(layer "In11.Cu")
		(net "M_F_CPU0_SB_DQ<24>")
	)
	(arc
		(start 332.422754 -289.014662)
		(mid 332.260422 -289.03748)
		(end 332.103984 -288.9885)
		(width 0.0889)
		(layer "In11.Cu")
		(net "M_F_CPU0_SB_DQ<24>")
	)
	(arc
		(start 330.598018 -288.9885)
		(mid 330.411074 -289.038755)
		(end 330.22413 -288.9885)
		(width 0.0889)
		(layer "In11.Cu")
		(net "M_F_CPU0_SB_DQ<24>")
	)
	(arc
		(start 327.765156 -288.99612)
		(mid 327.584226 -289.038598)
		(end 327.405238 -288.9885)
		(width 0.0889)
		(layer "In11.Cu")
		(net "M_F_CPU0_SB_DQ<24>")
	)
	(arc
		(start 328.709782 -288.993326)
		(mid 328.526274 -289.03882)
		(end 328.344022 -288.9885)
		(width 0.0889)
		(layer "In11.Cu")
		(net "M_F_CPU0_SB_DQ<24>")
	)
	(arc
		(start 332.103984 -288.9885)
		(mid 331.821028 -288.912323)
		(end 331.538072 -288.9885)
		(width 0.0889)
		(layer "In11.Cu")
		(net "M_F_CPU0_SB_DQ<24>")
	)
	(arc
		(start 331.16393 -288.9885)
		(mid 330.880974 -288.912323)
		(end 330.598018 -288.9885)
		(width 0.0889)
		(layer "In11.Cu")
		(net "M_F_CPU0_SB_DQ<24>")
	)
	(arc
		(start 331.52969 -288.993326)
		(mid 331.346182 -289.03882)
		(end 331.16393 -288.9885)
		(width 0.0889)
		(layer "In11.Cu")
		(net "M_F_CPU0_SB_DQ<24>")
	)
	(arc
		(start 329.284076 -288.9885)
		(mid 329.00112 -288.912323)
		(end 328.718164 -288.9885)
		(width 0.0889)
		(layer "In11.Cu")
		(net "M_F_CPU0_SB_DQ<24>")
	)
	(arc
		(start 329.658218 -288.9885)
		(mid 329.475967 -289.03885)
		(end 329.292458 -288.993326)
		(width 0.0889)
		(layer "In11.Cu")
		(net "M_F_CPU0_SB_DQ<24>")
	)
	(arc
		(start 328.344022 -288.9885)
		(mid 328.068344 -288.91237)
		(end 327.79081 -288.981388)
		(width 0.0889)
		(layer "In11.Cu")
		(net "M_F_CPU0_SB_DQ<24>")
	)
	(segment
		(start 334.637888 -288.399982)
		(end 334.171036 -288.66592)
		(width 0.10668)
		(layer "F.Cu")
		(net "M_F_CPU0_SB_DQ<23>")
	)
	(segment
		(start 267.283692 -308.40807)
		(end 267.428472 -308.55285)
		(width 0.14478)
		(layer "In11.Cu")
		(net "M_F_CPU0_SB_DQ<23>")
	)
	(segment
		(start 328.709782 -288.338768)
		(end 328.718164 -288.343594)
		(width 0.0889)
		(layer "In11.Cu")
		(net "M_F_CPU0_SB_DQ<23>")
	)
	(segment
		(start 328.333608 -288.34969)
		(end 328.344022 -288.343594)
		(width 0.0889)
		(layer "In11.Cu")
		(net "M_F_CPU0_SB_DQ<23>")
	)
	(segment
		(start 279.42032 -309.110126)
		(end 282.404058 -309.110126)
		(width 0.14478)
		(layer "In11.Cu")
		(net "M_F_CPU0_SB_DQ<23>")
	)
	(segment
		(start 301.027338 -308.259988)
		(end 301.708058 -308.714902)
		(width 0.14478)
		(layer "In11.Cu")
		(net "M_F_CPU0_SB_DQ<23>")
	)
	(segment
		(start 282.404058 -309.110126)
		(end 283.67609 -308.259988)
		(width 0.14478)
		(layer "In11.Cu")
		(net "M_F_CPU0_SB_DQ<23>")
	)
	(segment
		(start 332.469744 -288.338768)
		(end 332.478126 -288.343594)
		(width 0.0889)
		(layer "In11.Cu")
		(net "M_F_CPU0_SB_DQ<23>")
	)
	(segment
		(start 305.551078 -308.714902)
		(end 306.406296 -307.859684)
		(width 0.14478)
		(layer "In11.Cu")
		(net "M_F_CPU0_SB_DQ<23>")
	)
	(segment
		(start 291.329618 -308.259988)
		(end 293.262304 -308.259988)
		(width 0.14478)
		(layer "In11.Cu")
		(net "M_F_CPU0_SB_DQ<23>")
	)
	(segment
		(start 331.52969 -288.338768)
		(end 331.538072 -288.343594)
		(width 0.0889)
		(layer "In11.Cu")
		(net "M_F_CPU0_SB_DQ<23>")
	)
	(segment
		(start 333.921354 -288.37509)
		(end 334.017112 -288.40049)
		(width 0.0889)
		(layer "In11.Cu")
		(net "M_F_CPU0_SB_DQ<23>")
	)
	(segment
		(start 290.057332 -309.110126)
		(end 291.329618 -308.259988)
		(width 0.14478)
		(layer "In11.Cu")
		(net "M_F_CPU0_SB_DQ<23>")
	)
	(segment
		(start 274.240244 -309.110126)
		(end 276.292818 -308.259988)
		(width 0.14478)
		(layer "In11.Cu")
		(net "M_F_CPU0_SB_DQ<23>")
	)
	(segment
		(start 308.339998 -307.34508)
		(end 308.339998 -306.390548)
		(width 0.14478)
		(layer "In11.Cu")
		(net "M_F_CPU0_SB_DQ<23>")
	)
	(segment
		(start 266.704572 -309.110126)
		(end 266.849352 -308.965346)
		(width 0.14478)
		(layer "In11.Cu")
		(net "M_F_CPU0_SB_DQ<23>")
	)
	(segment
		(start 276.292818 -308.259988)
		(end 278.148034 -308.259988)
		(width 0.14478)
		(layer "In11.Cu")
		(net "M_F_CPU0_SB_DQ<23>")
	)
	(segment
		(start 266.994132 -308.40807)
		(end 267.283692 -308.40807)
		(width 0.14478)
		(layer "In11.Cu")
		(net "M_F_CPU0_SB_DQ<23>")
	)
	(segment
		(start 307.825394 -307.859684)
		(end 308.339998 -307.34508)
		(width 0.14478)
		(layer "In11.Cu")
		(net "M_F_CPU0_SB_DQ<23>")
	)
	(segment
		(start 324.246494 -290.484052)
		(end 325.033132 -289.697414)
		(width 0.0889)
		(layer "In11.Cu")
		(net "M_F_CPU0_SB_DQ<23>")
	)
	(segment
		(start 267.428472 -308.55285)
		(end 267.428472 -308.965346)
		(width 0.14478)
		(layer "In11.Cu")
		(net "M_F_CPU0_SB_DQ<23>")
	)
	(segment
		(start 283.67609 -308.259988)
		(end 285.658052 -308.259988)
		(width 0.14478)
		(layer "In11.Cu")
		(net "M_F_CPU0_SB_DQ<23>")
	)
	(segment
		(start 267.428472 -308.965346)
		(end 267.573252 -309.110126)
		(width 0.14478)
		(layer "In11.Cu")
		(net "M_F_CPU0_SB_DQ<23>")
	)
	(segment
		(start 325.060818 -289.697414)
		(end 326.413368 -288.344864)
		(width 0.0889)
		(layer "In11.Cu")
		(net "M_F_CPU0_SB_DQ<23>")
	)
	(segment
		(start 333.044038 -288.343594)
		(end 333.05242 -288.338768)
		(width 0.0889)
		(layer "In11.Cu")
		(net "M_F_CPU0_SB_DQ<23>")
	)
	(segment
		(start 278.148034 -308.259988)
		(end 279.42032 -309.110126)
		(width 0.14478)
		(layer "In11.Cu")
		(net "M_F_CPU0_SB_DQ<23>")
	)
	(segment
		(start 334.017112 -288.40049)
		(end 334.171036 -288.66592)
		(width 0.0889)
		(layer "In11.Cu")
		(net "M_F_CPU0_SB_DQ<23>")
	)
	(segment
		(start 326.526906 -288.297874)
		(end 327.55078 -288.297874)
		(width 0.0889)
		(layer "In11.Cu")
		(net "M_F_CPU0_SB_DQ<23>")
	)
	(segment
		(start 265.973052 -309.110126)
		(end 266.704572 -309.110126)
		(width 0.14478)
		(layer "In11.Cu")
		(net "M_F_CPU0_SB_DQ<23>")
	)
	(segment
		(start 285.658052 -308.259988)
		(end 286.930084 -309.110126)
		(width 0.14478)
		(layer "In11.Cu")
		(net "M_F_CPU0_SB_DQ<23>")
	)
	(segment
		(start 293.262304 -308.259988)
		(end 294.534844 -309.110126)
		(width 0.14478)
		(layer "In11.Cu")
		(net "M_F_CPU0_SB_DQ<23>")
	)
	(segment
		(start 297.426634 -309.110126)
		(end 298.698666 -308.259988)
		(width 0.14478)
		(layer "In11.Cu")
		(net "M_F_CPU0_SB_DQ<23>")
	)
	(segment
		(start 267.573252 -309.110126)
		(end 274.240244 -309.110126)
		(width 0.14478)
		(layer "In11.Cu")
		(net "M_F_CPU0_SB_DQ<23>")
	)
	(segment
		(start 266.849352 -308.965346)
		(end 266.849352 -308.55285)
		(width 0.14478)
		(layer "In11.Cu")
		(net "M_F_CPU0_SB_DQ<23>")
	)
	(segment
		(start 294.534844 -309.110126)
		(end 297.426634 -309.110126)
		(width 0.14478)
		(layer "In11.Cu")
		(net "M_F_CPU0_SB_DQ<23>")
	)
	(segment
		(start 286.930084 -309.110126)
		(end 290.057332 -309.110126)
		(width 0.14478)
		(layer "In11.Cu")
		(net "M_F_CPU0_SB_DQ<23>")
	)
	(segment
		(start 308.339998 -306.390548)
		(end 324.246494 -290.484052)
		(width 0.14478)
		(layer "In11.Cu")
		(net "M_F_CPU0_SB_DQ<23>")
	)
	(segment
		(start 325.033132 -289.697414)
		(end 325.060818 -289.697414)
		(width 0.0889)
		(layer "In11.Cu")
		(net "M_F_CPU0_SB_DQ<23>")
	)
	(segment
		(start 306.406296 -307.859684)
		(end 307.825394 -307.859684)
		(width 0.14478)
		(layer "In11.Cu")
		(net "M_F_CPU0_SB_DQ<23>")
	)
	(segment
		(start 266.849352 -308.55285)
		(end 266.994132 -308.40807)
		(width 0.14478)
		(layer "In11.Cu")
		(net "M_F_CPU0_SB_DQ<23>")
	)
	(segment
		(start 298.698666 -308.259988)
		(end 301.027338 -308.259988)
		(width 0.14478)
		(layer "In11.Cu")
		(net "M_F_CPU0_SB_DQ<23>")
	)
	(segment
		(start 265.54811 -308.685184)
		(end 265.973052 -309.110126)
		(width 0.14478)
		(layer "In11.Cu")
		(net "M_F_CPU0_SB_DQ<23>")
	)
	(segment
		(start 301.708058 -308.714902)
		(end 305.551078 -308.714902)
		(width 0.14478)
		(layer "In11.Cu")
		(net "M_F_CPU0_SB_DQ<23>")
	)
	(segment
		(start 329.284076 -288.343594)
		(end 329.292458 -288.338768)
		(width 0.0889)
		(layer "In11.Cu")
		(net "M_F_CPU0_SB_DQ<23>")
	)
	(arc
		(start 327.55078 -288.297874)
		(mid 327.681892 -288.313457)
		(end 327.805796 -288.359088)
		(width 0.0889)
		(layer "In11.Cu")
		(net "M_F_CPU0_SB_DQ<23>")
	)
	(arc
		(start 330.598018 -288.343594)
		(mid 330.880974 -288.419771)
		(end 331.16393 -288.343594)
		(width 0.0889)
		(layer "In11.Cu")
		(net "M_F_CPU0_SB_DQ<23>")
	)
	(arc
		(start 329.658218 -288.343594)
		(mid 329.941174 -288.419771)
		(end 330.22413 -288.343594)
		(width 0.0889)
		(layer "In11.Cu")
		(net "M_F_CPU0_SB_DQ<23>")
	)
	(arc
		(start 329.292458 -288.338768)
		(mid 329.475966 -288.293243)
		(end 329.658218 -288.343594)
		(width 0.0889)
		(layer "In11.Cu")
		(net "M_F_CPU0_SB_DQ<23>")
	)
	(arc
		(start 333.05242 -288.338768)
		(mid 333.235928 -288.293243)
		(end 333.41818 -288.343594)
		(width 0.0889)
		(layer "In11.Cu")
		(net "M_F_CPU0_SB_DQ<23>")
	)
	(arc
		(start 326.413368 -288.344864)
		(mid 326.465474 -288.310111)
		(end 326.526906 -288.297874)
		(width 0.0889)
		(layer "In11.Cu")
		(net "M_F_CPU0_SB_DQ<23>")
	)
	(arc
		(start 330.22413 -288.343594)
		(mid 330.411074 -288.293305)
		(end 330.598018 -288.343594)
		(width 0.0889)
		(layer "In11.Cu")
		(net "M_F_CPU0_SB_DQ<23>")
	)
	(arc
		(start 332.103984 -288.343594)
		(mid 332.286235 -288.29321)
		(end 332.469744 -288.338768)
		(width 0.0889)
		(layer "In11.Cu")
		(net "M_F_CPU0_SB_DQ<23>")
	)
	(arc
		(start 328.344022 -288.343594)
		(mid 328.526273 -288.29321)
		(end 328.709782 -288.338768)
		(width 0.0889)
		(layer "In11.Cu")
		(net "M_F_CPU0_SB_DQ<23>")
	)
	(arc
		(start 331.538072 -288.343594)
		(mid 331.821028 -288.419771)
		(end 332.103984 -288.343594)
		(width 0.0889)
		(layer "In11.Cu")
		(net "M_F_CPU0_SB_DQ<23>")
	)
	(arc
		(start 333.41818 -288.343594)
		(mid 333.66604 -288.418677)
		(end 333.921354 -288.37509)
		(width 0.0889)
		(layer "In11.Cu")
		(net "M_F_CPU0_SB_DQ<23>")
	)
	(arc
		(start 328.718164 -288.343594)
		(mid 329.00112 -288.419771)
		(end 329.284076 -288.343594)
		(width 0.0889)
		(layer "In11.Cu")
		(net "M_F_CPU0_SB_DQ<23>")
	)
	(arc
		(start 331.16393 -288.343594)
		(mid 331.346181 -288.29321)
		(end 331.52969 -288.338768)
		(width 0.0889)
		(layer "In11.Cu")
		(net "M_F_CPU0_SB_DQ<23>")
	)
	(arc
		(start 332.478126 -288.343594)
		(mid 332.761082 -288.419771)
		(end 333.044038 -288.343594)
		(width 0.0889)
		(layer "In11.Cu")
		(net "M_F_CPU0_SB_DQ<23>")
	)
	(arc
		(start 327.805796 -288.359088)
		(mid 328.070867 -288.419987)
		(end 328.333608 -288.34969)
		(width 0.0889)
		(layer "In11.Cu")
		(net "M_F_CPU0_SB_DQ<23>")
	)
	(segment
		(start 333.227934 -287.59023)
		(end 332.761082 -287.856168)
		(width 0.10668)
		(layer "F.Cu")
		(net "M_F_CPU0_SB_DQ<22>")
	)
	(segment
		(start 327.874376 -287.533588)
		(end 327.856342 -287.544002)
		(width 0.0889)
		(layer "In11.Cu")
		(net "M_F_CPU0_SB_DQ<22>")
	)
	(segment
		(start 294.059102 -307.410104)
		(end 293.208964 -306.559966)
		(width 0.14478)
		(layer "In11.Cu")
		(net "M_F_CPU0_SB_DQ<22>")
	)
	(segment
		(start 330.702412 -287.528762)
		(end 330.69403 -287.533588)
		(width 0.0889)
		(layer "In11.Cu")
		(net "M_F_CPU0_SB_DQ<22>")
	)
	(segment
		(start 268.465046 -307.410104)
		(end 268.320266 -307.265324)
		(width 0.14478)
		(layer "In11.Cu")
		(net "M_F_CPU0_SB_DQ<22>")
	)
	(segment
		(start 266.810744 -306.861972)
		(end 266.665964 -307.006752)
		(width 0.14478)
		(layer "In11.Cu")
		(net "M_F_CPU0_SB_DQ<22>")
	)
	(segment
		(start 300.815248 -306.559966)
		(end 298.908216 -306.559966)
		(width 0.14478)
		(layer "In11.Cu")
		(net "M_F_CPU0_SB_DQ<22>")
	)
	(segment
		(start 298.058078 -307.410104)
		(end 294.059102 -307.410104)
		(width 0.14478)
		(layer "In11.Cu")
		(net "M_F_CPU0_SB_DQ<22>")
	)
	(segment
		(start 267.768832 -307.006752)
		(end 267.768832 -307.265324)
		(width 0.14478)
		(layer "In11.Cu")
		(net "M_F_CPU0_SB_DQ<22>")
	)
	(segment
		(start 298.908216 -306.559966)
		(end 298.058078 -307.410104)
		(width 0.14478)
		(layer "In11.Cu")
		(net "M_F_CPU0_SB_DQ<22>")
	)
	(segment
		(start 275.188934 -307.410104)
		(end 268.465046 -307.410104)
		(width 0.14478)
		(layer "In11.Cu")
		(net "M_F_CPU0_SB_DQ<22>")
	)
	(segment
		(start 268.320266 -307.006752)
		(end 268.175486 -306.861972)
		(width 0.14478)
		(layer "In11.Cu")
		(net "M_F_CPU0_SB_DQ<22>")
	)
	(segment
		(start 323.874892 -289.576256)
		(end 306.891182 -306.559966)
		(width 0.14478)
		(layer "In11.Cu")
		(net "M_F_CPU0_SB_DQ<22>")
	)
	(segment
		(start 306.891182 -306.559966)
		(end 306.21986 -306.559966)
		(width 0.14478)
		(layer "In11.Cu")
		(net "M_F_CPU0_SB_DQ<22>")
	)
	(segment
		(start 327.309226 -287.533588)
		(end 327.297542 -287.52673)
		(width 0.0889)
		(layer "In11.Cu")
		(net "M_F_CPU0_SB_DQ<22>")
	)
	(segment
		(start 301.665386 -307.410104)
		(end 300.815248 -306.559966)
		(width 0.14478)
		(layer "In11.Cu")
		(net "M_F_CPU0_SB_DQ<22>")
	)
	(segment
		(start 330.128118 -287.533588)
		(end 330.119736 -287.528762)
		(width 0.0889)
		(layer "In11.Cu")
		(net "M_F_CPU0_SB_DQ<22>")
	)
	(segment
		(start 268.175486 -306.861972)
		(end 267.913612 -306.861972)
		(width 0.14478)
		(layer "In11.Cu")
		(net "M_F_CPU0_SB_DQ<22>")
	)
	(segment
		(start 267.217398 -307.006752)
		(end 267.072618 -306.861972)
		(width 0.14478)
		(layer "In11.Cu")
		(net "M_F_CPU0_SB_DQ<22>")
	)
	(segment
		(start 327.88606 -287.52673)
		(end 327.874376 -287.533588)
		(width 0.0889)
		(layer "In11.Cu")
		(net "M_F_CPU0_SB_DQ<22>")
	)
	(segment
		(start 332.607158 -287.590738)
		(end 332.511146 -287.565338)
		(width 0.0889)
		(layer "In11.Cu")
		(net "M_F_CPU0_SB_DQ<22>")
	)
	(segment
		(start 266.665964 -307.265324)
		(end 266.521184 -307.410104)
		(width 0.14478)
		(layer "In11.Cu")
		(net "M_F_CPU0_SB_DQ<22>")
	)
	(segment
		(start 331.642466 -287.528762)
		(end 331.634084 -287.533588)
		(width 0.0889)
		(layer "In11.Cu")
		(net "M_F_CPU0_SB_DQ<22>")
	)
	(segment
		(start 283.803344 -306.559966)
		(end 282.953206 -307.410104)
		(width 0.14478)
		(layer "In11.Cu")
		(net "M_F_CPU0_SB_DQ<22>")
	)
	(segment
		(start 266.665964 -307.006752)
		(end 266.665964 -307.265324)
		(width 0.14478)
		(layer "In11.Cu")
		(net "M_F_CPU0_SB_DQ<22>")
	)
	(segment
		(start 326.601582 -287.707324)
		(end 325.958708 -287.707324)
		(width 0.0889)
		(layer "In11.Cu")
		(net "M_F_CPU0_SB_DQ<22>")
	)
	(segment
		(start 267.768832 -307.265324)
		(end 267.624052 -307.410104)
		(width 0.14478)
		(layer "In11.Cu")
		(net "M_F_CPU0_SB_DQ<22>")
	)
	(segment
		(start 276.039072 -306.559966)
		(end 275.188934 -307.410104)
		(width 0.14478)
		(layer "In11.Cu")
		(net "M_F_CPU0_SB_DQ<22>")
	)
	(segment
		(start 268.320266 -307.265324)
		(end 268.320266 -307.006752)
		(width 0.14478)
		(layer "In11.Cu")
		(net "M_F_CPU0_SB_DQ<22>")
	)
	(segment
		(start 285.741364 -306.559966)
		(end 283.803344 -306.559966)
		(width 0.14478)
		(layer "In11.Cu")
		(net "M_F_CPU0_SB_DQ<22>")
	)
	(segment
		(start 266.521184 -307.410104)
		(end 265.973052 -307.410104)
		(width 0.14478)
		(layer "In11.Cu")
		(net "M_F_CPU0_SB_DQ<22>")
	)
	(segment
		(start 325.84517 -287.754314)
		(end 325.253604 -288.34588)
		(width 0.0889)
		(layer "In11.Cu")
		(net "M_F_CPU0_SB_DQ<22>")
	)
	(segment
		(start 267.072618 -306.861972)
		(end 266.810744 -306.861972)
		(width 0.14478)
		(layer "In11.Cu")
		(net "M_F_CPU0_SB_DQ<22>")
	)
	(segment
		(start 282.953206 -307.410104)
		(end 278.932894 -307.410104)
		(width 0.14478)
		(layer "In11.Cu")
		(net "M_F_CPU0_SB_DQ<22>")
	)
	(segment
		(start 324.877684 -288.34588)
		(end 324.421754 -288.80181)
		(width 0.0889)
		(layer "In11.Cu")
		(net "M_F_CPU0_SB_DQ<22>")
	)
	(segment
		(start 306.21986 -306.559966)
		(end 305.369722 -307.410104)
		(width 0.14478)
		(layer "In11.Cu")
		(net "M_F_CPU0_SB_DQ<22>")
	)
	(segment
		(start 291.499544 -306.559966)
		(end 290.649406 -307.410104)
		(width 0.14478)
		(layer "In11.Cu")
		(net "M_F_CPU0_SB_DQ<22>")
	)
	(segment
		(start 267.624052 -307.410104)
		(end 267.362178 -307.410104)
		(width 0.14478)
		(layer "In11.Cu")
		(net "M_F_CPU0_SB_DQ<22>")
	)
	(segment
		(start 293.208964 -306.559966)
		(end 291.499544 -306.559966)
		(width 0.14478)
		(layer "In11.Cu")
		(net "M_F_CPU0_SB_DQ<22>")
	)
	(segment
		(start 290.649406 -307.410104)
		(end 286.591502 -307.410104)
		(width 0.14478)
		(layer "In11.Cu")
		(net "M_F_CPU0_SB_DQ<22>")
	)
	(segment
		(start 286.591502 -307.410104)
		(end 285.741364 -306.559966)
		(width 0.14478)
		(layer "In11.Cu")
		(net "M_F_CPU0_SB_DQ<22>")
	)
	(segment
		(start 267.217398 -307.265324)
		(end 267.217398 -307.006752)
		(width 0.14478)
		(layer "In11.Cu")
		(net "M_F_CPU0_SB_DQ<22>")
	)
	(segment
		(start 278.932894 -307.410104)
		(end 278.082756 -306.559966)
		(width 0.14478)
		(layer "In11.Cu")
		(net "M_F_CPU0_SB_DQ<22>")
	)
	(segment
		(start 305.369722 -307.410104)
		(end 301.665386 -307.410104)
		(width 0.14478)
		(layer "In11.Cu")
		(net "M_F_CPU0_SB_DQ<22>")
	)
	(segment
		(start 325.253604 -288.34588)
		(end 324.877684 -288.34588)
		(width 0.0889)
		(layer "In11.Cu")
		(net "M_F_CPU0_SB_DQ<22>")
	)
	(segment
		(start 324.421754 -288.80181)
		(end 324.421754 -289.029394)
		(width 0.0889)
		(layer "In11.Cu")
		(net "M_F_CPU0_SB_DQ<22>")
	)
	(segment
		(start 265.973052 -307.410104)
		(end 265.54811 -306.985162)
		(width 0.14478)
		(layer "In11.Cu")
		(net "M_F_CPU0_SB_DQ<22>")
	)
	(segment
		(start 324.421754 -289.029394)
		(end 323.874892 -289.576256)
		(width 0.0889)
		(layer "In11.Cu")
		(net "M_F_CPU0_SB_DQ<22>")
	)
	(segment
		(start 278.082756 -306.559966)
		(end 276.039072 -306.559966)
		(width 0.14478)
		(layer "In11.Cu")
		(net "M_F_CPU0_SB_DQ<22>")
	)
	(segment
		(start 267.913612 -306.861972)
		(end 267.768832 -307.006752)
		(width 0.14478)
		(layer "In11.Cu")
		(net "M_F_CPU0_SB_DQ<22>")
	)
	(segment
		(start 327.034652 -287.511744)
		(end 326.782176 -287.658556)
		(width 0.0889)
		(layer "In11.Cu")
		(net "M_F_CPU0_SB_DQ<22>")
	)
	(segment
		(start 267.362178 -307.410104)
		(end 267.217398 -307.265324)
		(width 0.14478)
		(layer "In11.Cu")
		(net "M_F_CPU0_SB_DQ<22>")
	)
	(segment
		(start 332.761082 -287.856168)
		(end 332.607158 -287.590738)
		(width 0.0889)
		(layer "In11.Cu")
		(net "M_F_CPU0_SB_DQ<22>")
	)
	(arc
		(start 330.119736 -287.528762)
		(mid 329.936228 -287.483268)
		(end 329.753976 -287.533588)
		(width 0.0889)
		(layer "In11.Cu")
		(net "M_F_CPU0_SB_DQ<22>")
	)
	(arc
		(start 331.634084 -287.533588)
		(mid 331.351128 -287.609731)
		(end 331.068172 -287.533588)
		(width 0.0889)
		(layer "In11.Cu")
		(net "M_F_CPU0_SB_DQ<22>")
	)
	(arc
		(start 329.188064 -287.533588)
		(mid 329.00112 -287.483333)
		(end 328.814176 -287.533588)
		(width 0.0889)
		(layer "In11.Cu")
		(net "M_F_CPU0_SB_DQ<22>")
	)
	(arc
		(start 330.69403 -287.533588)
		(mid 330.411074 -287.609731)
		(end 330.128118 -287.533588)
		(width 0.0889)
		(layer "In11.Cu")
		(net "M_F_CPU0_SB_DQ<22>")
	)
	(arc
		(start 331.068172 -287.533588)
		(mid 330.885921 -287.483238)
		(end 330.702412 -287.528762)
		(width 0.0889)
		(layer "In11.Cu")
		(net "M_F_CPU0_SB_DQ<22>")
	)
	(arc
		(start 328.814176 -287.533588)
		(mid 328.53122 -287.609731)
		(end 328.248264 -287.533588)
		(width 0.0889)
		(layer "In11.Cu")
		(net "M_F_CPU0_SB_DQ<22>")
	)
	(arc
		(start 327.297542 -287.52673)
		(mid 327.229893 -287.498797)
		(end 327.158096 -287.484566)
		(width 0.0889)
		(layer "In11.Cu")
		(net "M_F_CPU0_SB_DQ<22>")
	)
	(arc
		(start 328.248264 -287.533588)
		(mid 328.068059 -287.483271)
		(end 327.88606 -287.52673)
		(width 0.0889)
		(layer "In11.Cu")
		(net "M_F_CPU0_SB_DQ<22>")
	)
	(arc
		(start 329.753976 -287.533588)
		(mid 329.47102 -287.609731)
		(end 329.188064 -287.533588)
		(width 0.0889)
		(layer "In11.Cu")
		(net "M_F_CPU0_SB_DQ<22>")
	)
	(arc
		(start 332.511146 -287.565338)
		(mid 332.255938 -287.608795)
		(end 332.008226 -287.533588)
		(width 0.0889)
		(layer "In11.Cu")
		(net "M_F_CPU0_SB_DQ<22>")
	)
	(arc
		(start 326.782176 -287.658556)
		(mid 326.69511 -287.694915)
		(end 326.601582 -287.707324)
		(width 0.0889)
		(layer "In11.Cu")
		(net "M_F_CPU0_SB_DQ<22>")
	)
	(arc
		(start 332.008226 -287.533588)
		(mid 331.825975 -287.483238)
		(end 331.642466 -287.528762)
		(width 0.0889)
		(layer "In11.Cu")
		(net "M_F_CPU0_SB_DQ<22>")
	)
	(arc
		(start 325.958708 -287.707324)
		(mid 325.897262 -287.719528)
		(end 325.84517 -287.754314)
		(width 0.0889)
		(layer "In11.Cu")
		(net "M_F_CPU0_SB_DQ<22>")
	)
	(arc
		(start 327.856342 -287.544002)
		(mid 327.581438 -287.609612)
		(end 327.309226 -287.533588)
		(width 0.0889)
		(layer "In11.Cu")
		(net "M_F_CPU0_SB_DQ<22>")
	)
	(arc
		(start 327.158096 -287.484566)
		(mid 327.094236 -287.488452)
		(end 327.034652 -287.511744)
		(width 0.0889)
		(layer "In11.Cu")
		(net "M_F_CPU0_SB_DQ<22>")
	)
	(segment
		(start 334.167988 -287.59023)
		(end 333.701136 -287.856168)
		(width 0.10668)
		(layer "F.Cu")
		(net "M_F_CPU0_SB_DQ<21>")
	)
	(segment
		(start 330.128118 -288.178494)
		(end 330.119736 -288.18332)
		(width 0.0889)
		(layer "In11.Cu")
		(net "M_F_CPU0_SB_DQ<21>")
	)
	(segment
		(start 302.79975 -308.015132)
		(end 302.65497 -307.870352)
		(width 0.14478)
		(layer "In11.Cu")
		(net "M_F_CPU0_SB_DQ<21>")
	)
	(segment
		(start 307.890418 -307.15839)
		(end 307.638704 -307.410104)
		(width 0.14478)
		(layer "In11.Cu")
		(net "M_F_CPU0_SB_DQ<21>")
	)
	(segment
		(start 298.70146 -307.410104)
		(end 297.851322 -308.260242)
		(width 0.14478)
		(layer "In11.Cu")
		(net "M_F_CPU0_SB_DQ<21>")
	)
	(segment
		(start 301.872142 -308.260242)
		(end 301.022004 -307.410104)
		(width 0.14478)
		(layer "In11.Cu")
		(net "M_F_CPU0_SB_DQ<21>")
	)
	(segment
		(start 302.79975 -308.115462)
		(end 302.79975 -308.015132)
		(width 0.14478)
		(layer "In11.Cu")
		(net "M_F_CPU0_SB_DQ<21>")
	)
	(segment
		(start 282.789122 -308.260242)
		(end 281.829764 -308.260242)
		(width 0.14478)
		(layer "In11.Cu")
		(net "M_F_CPU0_SB_DQ<21>")
	)
	(segment
		(start 293.398448 -307.410104)
		(end 291.33546 -307.410104)
		(width 0.14478)
		(layer "In11.Cu")
		(net "M_F_CPU0_SB_DQ<21>")
	)
	(segment
		(start 271.795494 -308.63921)
		(end 271.564862 -308.63921)
		(width 0.14478)
		(layer "In11.Cu")
		(net "M_F_CPU0_SB_DQ<21>")
	)
	(segment
		(start 294.248586 -308.260242)
		(end 293.398448 -307.410104)
		(width 0.14478)
		(layer "In11.Cu")
		(net "M_F_CPU0_SB_DQ<21>")
	)
	(segment
		(start 302.103536 -308.260242)
		(end 301.872142 -308.260242)
		(width 0.14478)
		(layer "In11.Cu")
		(net "M_F_CPU0_SB_DQ<21>")
	)
	(segment
		(start 302.65497 -307.870352)
		(end 302.393096 -307.870352)
		(width 0.14478)
		(layer "In11.Cu")
		(net "M_F_CPU0_SB_DQ<21>")
	)
	(segment
		(start 301.022004 -307.410104)
		(end 298.70146 -307.410104)
		(width 0.14478)
		(layer "In11.Cu")
		(net "M_F_CPU0_SB_DQ<21>")
	)
	(segment
		(start 271.958308 -308.033928)
		(end 271.958308 -308.476396)
		(width 0.14478)
		(layer "In11.Cu")
		(net "M_F_CPU0_SB_DQ<21>")
	)
	(segment
		(start 273.919188 -308.58079)
		(end 273.59864 -308.260242)
		(width 0.14478)
		(layer "In11.Cu")
		(net "M_F_CPU0_SB_DQ<21>")
	)
	(segment
		(start 275.86686 -307.410104)
		(end 275.016722 -308.260242)
		(width 0.14478)
		(layer "In11.Cu")
		(net "M_F_CPU0_SB_DQ<21>")
	)
	(segment
		(start 270.845788 -308.033928)
		(end 270.845788 -308.476396)
		(width 0.14478)
		(layer "In11.Cu")
		(net "M_F_CPU0_SB_DQ<21>")
	)
	(segment
		(start 281.273504 -308.58333)
		(end 280.950416 -308.260242)
		(width 0.14478)
		(layer "In11.Cu")
		(net "M_F_CPU0_SB_DQ<21>")
	)
	(segment
		(start 304.73904 -308.115462)
		(end 304.73904 -308.015132)
		(width 0.14478)
		(layer "In11.Cu")
		(net "M_F_CPU0_SB_DQ<21>")
	)
	(segment
		(start 327.36663 -288.002726)
		(end 326.145906 -288.002726)
		(width 0.0889)
		(layer "In11.Cu")
		(net "M_F_CPU0_SB_DQ<21>")
	)
	(segment
		(start 285.702248 -307.410104)
		(end 283.63926 -307.410104)
		(width 0.14478)
		(layer "In11.Cu")
		(net "M_F_CPU0_SB_DQ<21>")
	)
	(segment
		(start 271.239234 -307.871114)
		(end 271.008602 -307.871114)
		(width 0.14478)
		(layer "In11.Cu")
		(net "M_F_CPU0_SB_DQ<21>")
	)
	(segment
		(start 272.740882 -308.260242)
		(end 272.351754 -307.871114)
		(width 0.14478)
		(layer "In11.Cu")
		(net "M_F_CPU0_SB_DQ<21>")
	)
	(segment
		(start 270.845788 -308.476396)
		(end 270.682974 -308.63921)
		(width 0.14478)
		(layer "In11.Cu")
		(net "M_F_CPU0_SB_DQ<21>")
	)
	(segment
		(start 325.292212 -288.723324)
		(end 324.998588 -288.723324)
		(width 0.0889)
		(layer "In11.Cu")
		(net "M_F_CPU0_SB_DQ<21>")
	)
	(segment
		(start 304.332386 -307.870352)
		(end 304.187606 -308.015132)
		(width 0.14478)
		(layer "In11.Cu")
		(net "M_F_CPU0_SB_DQ<21>")
	)
	(segment
		(start 271.402048 -308.033928)
		(end 271.239234 -307.871114)
		(width 0.14478)
		(layer "In11.Cu")
		(net "M_F_CPU0_SB_DQ<21>")
	)
	(segment
		(start 271.564862 -308.63921)
		(end 271.402048 -308.476396)
		(width 0.14478)
		(layer "In11.Cu")
		(net "M_F_CPU0_SB_DQ<21>")
	)
	(segment
		(start 271.402048 -308.476396)
		(end 271.402048 -308.033928)
		(width 0.14478)
		(layer "In11.Cu")
		(net "M_F_CPU0_SB_DQ<21>")
	)
	(segment
		(start 306.21986 -307.410104)
		(end 305.369722 -308.260242)
		(width 0.14478)
		(layer "In11.Cu")
		(net "M_F_CPU0_SB_DQ<21>")
	)
	(segment
		(start 304.187606 -308.015132)
		(end 304.187606 -308.115462)
		(width 0.14478)
		(layer "In11.Cu")
		(net "M_F_CPU0_SB_DQ<21>")
	)
	(segment
		(start 279.059386 -308.260242)
		(end 278.209248 -307.410104)
		(width 0.14478)
		(layer "In11.Cu")
		(net "M_F_CPU0_SB_DQ<21>")
	)
	(segment
		(start 302.248316 -308.115462)
		(end 302.103536 -308.260242)
		(width 0.14478)
		(layer "In11.Cu")
		(net "M_F_CPU0_SB_DQ<21>")
	)
	(segment
		(start 323.897752 -290.189666)
		(end 307.890418 -306.197)
		(width 0.14478)
		(layer "In11.Cu")
		(net "M_F_CPU0_SB_DQ<21>")
	)
	(segment
		(start 326.032368 -288.049716)
		(end 325.40575 -288.676334)
		(width 0.0889)
		(layer "In11.Cu")
		(net "M_F_CPU0_SB_DQ<21>")
	)
	(segment
		(start 281.506676 -308.58333)
		(end 281.273504 -308.58333)
		(width 0.14478)
		(layer "In11.Cu")
		(net "M_F_CPU0_SB_DQ<21>")
	)
	(segment
		(start 274.1549 -308.58079)
		(end 273.919188 -308.58079)
		(width 0.14478)
		(layer "In11.Cu")
		(net "M_F_CPU0_SB_DQ<21>")
	)
	(segment
		(start 297.851322 -308.260242)
		(end 294.248586 -308.260242)
		(width 0.14478)
		(layer "In11.Cu")
		(net "M_F_CPU0_SB_DQ<21>")
	)
	(segment
		(start 270.452342 -308.63921)
		(end 269.648178 -307.835046)
		(width 0.14478)
		(layer "In11.Cu")
		(net "M_F_CPU0_SB_DQ<21>")
	)
	(segment
		(start 304.042826 -308.260242)
		(end 302.94453 -308.260242)
		(width 0.14478)
		(layer "In11.Cu")
		(net "M_F_CPU0_SB_DQ<21>")
	)
	(segment
		(start 302.248316 -308.015132)
		(end 302.248316 -308.115462)
		(width 0.14478)
		(layer "In11.Cu")
		(net "M_F_CPU0_SB_DQ<21>")
	)
	(segment
		(start 333.85506 -288.121598)
		(end 333.832708 -288.204656)
		(width 0.0889)
		(layer "In11.Cu")
		(net "M_F_CPU0_SB_DQ<21>")
	)
	(segment
		(start 271.008602 -307.871114)
		(end 270.845788 -308.033928)
		(width 0.14478)
		(layer "In11.Cu")
		(net "M_F_CPU0_SB_DQ<21>")
	)
	(segment
		(start 271.958308 -308.476396)
		(end 271.795494 -308.63921)
		(width 0.14478)
		(layer "In11.Cu")
		(net "M_F_CPU0_SB_DQ<21>")
	)
	(segment
		(start 291.33546 -307.410104)
		(end 290.485322 -308.260242)
		(width 0.14478)
		(layer "In11.Cu")
		(net "M_F_CPU0_SB_DQ<21>")
	)
	(segment
		(start 333.701136 -287.856168)
		(end 333.85506 -288.121598)
		(width 0.0889)
		(layer "In11.Cu")
		(net "M_F_CPU0_SB_DQ<21>")
	)
	(segment
		(start 272.121122 -307.871114)
		(end 271.958308 -308.033928)
		(width 0.14478)
		(layer "In11.Cu")
		(net "M_F_CPU0_SB_DQ<21>")
	)
	(segment
		(start 274.475448 -308.260242)
		(end 274.1549 -308.58079)
		(width 0.14478)
		(layer "In11.Cu")
		(net "M_F_CPU0_SB_DQ<21>")
	)
	(segment
		(start 304.187606 -308.115462)
		(end 304.042826 -308.260242)
		(width 0.14478)
		(layer "In11.Cu")
		(net "M_F_CPU0_SB_DQ<21>")
	)
	(segment
		(start 278.209248 -307.410104)
		(end 275.86686 -307.410104)
		(width 0.14478)
		(layer "In11.Cu")
		(net "M_F_CPU0_SB_DQ<21>")
	)
	(segment
		(start 307.638704 -307.410104)
		(end 306.21986 -307.410104)
		(width 0.14478)
		(layer "In11.Cu")
		(net "M_F_CPU0_SB_DQ<21>")
	)
	(segment
		(start 302.94453 -308.260242)
		(end 302.79975 -308.115462)
		(width 0.14478)
		(layer "In11.Cu")
		(net "M_F_CPU0_SB_DQ<21>")
	)
	(segment
		(start 324.668134 -289.419284)
		(end 323.897752 -290.189666)
		(width 0.0889)
		(layer "In11.Cu")
		(net "M_F_CPU0_SB_DQ<21>")
	)
	(segment
		(start 281.829764 -308.260242)
		(end 281.506676 -308.58333)
		(width 0.14478)
		(layer "In11.Cu")
		(net "M_F_CPU0_SB_DQ<21>")
	)
	(segment
		(start 286.552386 -308.260242)
		(end 285.702248 -307.410104)
		(width 0.14478)
		(layer "In11.Cu")
		(net "M_F_CPU0_SB_DQ<21>")
	)
	(segment
		(start 275.016722 -308.260242)
		(end 274.475448 -308.260242)
		(width 0.14478)
		(layer "In11.Cu")
		(net "M_F_CPU0_SB_DQ<21>")
	)
	(segment
		(start 307.890418 -306.197)
		(end 307.890418 -307.15839)
		(width 0.14478)
		(layer "In11.Cu")
		(net "M_F_CPU0_SB_DQ<21>")
	)
	(segment
		(start 290.485322 -308.260242)
		(end 286.552386 -308.260242)
		(width 0.14478)
		(layer "In11.Cu")
		(net "M_F_CPU0_SB_DQ<21>")
	)
	(segment
		(start 324.88505 -288.770314)
		(end 324.668134 -288.98723)
		(width 0.0889)
		(layer "In11.Cu")
		(net "M_F_CPU0_SB_DQ<21>")
	)
	(segment
		(start 272.351754 -307.871114)
		(end 272.121122 -307.871114)
		(width 0.14478)
		(layer "In11.Cu")
		(net "M_F_CPU0_SB_DQ<21>")
	)
	(segment
		(start 270.682974 -308.63921)
		(end 270.452342 -308.63921)
		(width 0.14478)
		(layer "In11.Cu")
		(net "M_F_CPU0_SB_DQ<21>")
	)
	(segment
		(start 283.63926 -307.410104)
		(end 282.789122 -308.260242)
		(width 0.14478)
		(layer "In11.Cu")
		(net "M_F_CPU0_SB_DQ<21>")
	)
	(segment
		(start 302.393096 -307.870352)
		(end 302.248316 -308.015132)
		(width 0.14478)
		(layer "In11.Cu")
		(net "M_F_CPU0_SB_DQ<21>")
	)
	(segment
		(start 330.702412 -288.18332)
		(end 330.69403 -288.178494)
		(width 0.0889)
		(layer "In11.Cu")
		(net "M_F_CPU0_SB_DQ<21>")
	)
	(segment
		(start 304.88382 -308.260242)
		(end 304.73904 -308.115462)
		(width 0.14478)
		(layer "In11.Cu")
		(net "M_F_CPU0_SB_DQ<21>")
	)
	(segment
		(start 324.668134 -288.98723)
		(end 324.668134 -289.419284)
		(width 0.0889)
		(layer "In11.Cu")
		(net "M_F_CPU0_SB_DQ<21>")
	)
	(segment
		(start 305.369722 -308.260242)
		(end 304.88382 -308.260242)
		(width 0.14478)
		(layer "In11.Cu")
		(net "M_F_CPU0_SB_DQ<21>")
	)
	(segment
		(start 273.59864 -308.260242)
		(end 272.740882 -308.260242)
		(width 0.14478)
		(layer "In11.Cu")
		(net "M_F_CPU0_SB_DQ<21>")
	)
	(segment
		(start 327.64095 -288.07283)
		(end 327.490836 -288.022792)
		(width 0.0889)
		(layer "In11.Cu")
		(net "M_F_CPU0_SB_DQ<21>")
	)
	(segment
		(start 331.642466 -288.18332)
		(end 331.634084 -288.178494)
		(width 0.0889)
		(layer "In11.Cu")
		(net "M_F_CPU0_SB_DQ<21>")
	)
	(segment
		(start 304.59426 -307.870352)
		(end 304.332386 -307.870352)
		(width 0.14478)
		(layer "In11.Cu")
		(net "M_F_CPU0_SB_DQ<21>")
	)
	(segment
		(start 304.73904 -308.015132)
		(end 304.59426 -307.870352)
		(width 0.14478)
		(layer "In11.Cu")
		(net "M_F_CPU0_SB_DQ<21>")
	)
	(segment
		(start 280.950416 -308.260242)
		(end 279.059386 -308.260242)
		(width 0.14478)
		(layer "In11.Cu")
		(net "M_F_CPU0_SB_DQ<21>")
	)
	(arc
		(start 329.188064 -288.178494)
		(mid 329.00112 -288.228783)
		(end 328.814176 -288.178494)
		(width 0.0889)
		(layer "In11.Cu")
		(net "M_F_CPU0_SB_DQ<21>")
	)
	(arc
		(start 331.634084 -288.178494)
		(mid 331.351128 -288.102317)
		(end 331.068172 -288.178494)
		(width 0.0889)
		(layer "In11.Cu")
		(net "M_F_CPU0_SB_DQ<21>")
	)
	(arc
		(start 328.248264 -288.178494)
		(mid 328.061066 -288.228911)
		(end 327.873868 -288.178494)
		(width 0.0889)
		(layer "In11.Cu")
		(net "M_F_CPU0_SB_DQ<21>")
	)
	(arc
		(start 332.574138 -288.178494)
		(mid 332.291182 -288.102317)
		(end 332.008226 -288.178494)
		(width 0.0889)
		(layer "In11.Cu")
		(net "M_F_CPU0_SB_DQ<21>")
	)
	(arc
		(start 327.873868 -288.178494)
		(mid 327.760139 -288.119643)
		(end 327.64095 -288.07283)
		(width 0.0889)
		(layer "In11.Cu")
		(net "M_F_CPU0_SB_DQ<21>")
	)
	(arc
		(start 332.948026 -288.178494)
		(mid 332.761082 -288.228783)
		(end 332.574138 -288.178494)
		(width 0.0889)
		(layer "In11.Cu")
		(net "M_F_CPU0_SB_DQ<21>")
	)
	(arc
		(start 333.832708 -288.204656)
		(mid 333.670376 -288.22749)
		(end 333.513938 -288.178494)
		(width 0.0889)
		(layer "In11.Cu")
		(net "M_F_CPU0_SB_DQ<21>")
	)
	(arc
		(start 332.008226 -288.178494)
		(mid 331.825975 -288.228878)
		(end 331.642466 -288.18332)
		(width 0.0889)
		(layer "In11.Cu")
		(net "M_F_CPU0_SB_DQ<21>")
	)
	(arc
		(start 331.068172 -288.178494)
		(mid 330.885921 -288.228878)
		(end 330.702412 -288.18332)
		(width 0.0889)
		(layer "In11.Cu")
		(net "M_F_CPU0_SB_DQ<21>")
	)
	(arc
		(start 326.145906 -288.002726)
		(mid 326.08446 -288.01493)
		(end 326.032368 -288.049716)
		(width 0.0889)
		(layer "In11.Cu")
		(net "M_F_CPU0_SB_DQ<21>")
	)
	(arc
		(start 330.69403 -288.178494)
		(mid 330.411074 -288.102317)
		(end 330.128118 -288.178494)
		(width 0.0889)
		(layer "In11.Cu")
		(net "M_F_CPU0_SB_DQ<21>")
	)
	(arc
		(start 330.119736 -288.18332)
		(mid 329.936228 -288.228845)
		(end 329.753976 -288.178494)
		(width 0.0889)
		(layer "In11.Cu")
		(net "M_F_CPU0_SB_DQ<21>")
	)
	(arc
		(start 328.814176 -288.178494)
		(mid 328.53122 -288.102317)
		(end 328.248264 -288.178494)
		(width 0.0889)
		(layer "In11.Cu")
		(net "M_F_CPU0_SB_DQ<21>")
	)
	(arc
		(start 333.513938 -288.178494)
		(mid 333.230982 -288.102317)
		(end 332.948026 -288.178494)
		(width 0.0889)
		(layer "In11.Cu")
		(net "M_F_CPU0_SB_DQ<21>")
	)
	(arc
		(start 324.998588 -288.723324)
		(mid 324.937142 -288.735528)
		(end 324.88505 -288.770314)
		(width 0.0889)
		(layer "In11.Cu")
		(net "M_F_CPU0_SB_DQ<21>")
	)
	(arc
		(start 329.753976 -288.178494)
		(mid 329.47102 -288.102317)
		(end 329.188064 -288.178494)
		(width 0.0889)
		(layer "In11.Cu")
		(net "M_F_CPU0_SB_DQ<21>")
	)
	(arc
		(start 327.490836 -288.022792)
		(mid 327.429541 -288.007757)
		(end 327.36663 -288.002726)
		(width 0.0889)
		(layer "In11.Cu")
		(net "M_F_CPU0_SB_DQ<21>")
	)
	(arc
		(start 325.40575 -288.676334)
		(mid 325.353644 -288.711087)
		(end 325.292212 -288.723324)
		(width 0.0889)
		(layer "In11.Cu")
		(net "M_F_CPU0_SB_DQ<21>")
	)
	(segment
		(start 332.758034 -286.780224)
		(end 332.291182 -287.045908)
		(width 0.10668)
		(layer "F.Cu")
		(net "M_F_CPU0_SB_DQ<20>")
	)
	(segment
		(start 278.420576 -305.719734)
		(end 276.733 -305.719734)
		(width 0.14478)
		(layer "In11.Cu")
		(net "M_F_CPU0_SB_DQ<20>")
	)
	(segment
		(start 270.548862 -305.829716)
		(end 270.385794 -305.992784)
		(width 0.14478)
		(layer "In11.Cu")
		(net "M_F_CPU0_SB_DQ<20>")
	)
	(segment
		(start 276.579584 -305.87315)
		(end 276.579584 -305.940968)
		(width 0.14478)
		(layer "In11.Cu")
		(net "M_F_CPU0_SB_DQ<20>")
	)
	(segment
		(start 279.821894 -306.958492)
		(end 279.56002 -306.958492)
		(width 0.14478)
		(layer "In11.Cu")
		(net "M_F_CPU0_SB_DQ<20>")
	)
	(segment
		(start 296.283126 -306.569618)
		(end 295.208452 -306.569618)
		(width 0.14478)
		(layer "In11.Cu")
		(net "M_F_CPU0_SB_DQ<20>")
	)
	(segment
		(start 301.061628 -305.719734)
		(end 299.392848 -305.719734)
		(width 0.14478)
		(layer "In11.Cu")
		(net "M_F_CPU0_SB_DQ<20>")
	)
	(segment
		(start 332.445106 -287.311338)
		(end 332.422754 -287.39465)
		(width 0.0889)
		(layer "In11.Cu")
		(net "M_F_CPU0_SB_DQ<20>")
	)
	(segment
		(start 286.897064 -306.813712)
		(end 286.897064 -306.714398)
		(width 0.14478)
		(layer "In11.Cu")
		(net "M_F_CPU0_SB_DQ<20>")
	)
	(segment
		(start 274.745196 -306.569618)
		(end 272.511774 -306.569618)
		(width 0.14478)
		(layer "In11.Cu")
		(net "M_F_CPU0_SB_DQ<20>")
	)
	(segment
		(start 325.196454 -287.95091)
		(end 324.86219 -287.95091)
		(width 0.0889)
		(layer "In11.Cu")
		(net "M_F_CPU0_SB_DQ<20>")
	)
	(segment
		(start 270.385794 -306.396898)
		(end 270.222726 -306.559966)
		(width 0.14478)
		(layer "In11.Cu")
		(net "M_F_CPU0_SB_DQ<20>")
	)
	(segment
		(start 270.942308 -305.992784)
		(end 270.77924 -305.829716)
		(width 0.14478)
		(layer "In11.Cu")
		(net "M_F_CPU0_SB_DQ<20>")
	)
	(segment
		(start 304.23993 -306.85867)
		(end 303.98212 -306.85867)
		(width 0.14478)
		(layer "In11.Cu")
		(net "M_F_CPU0_SB_DQ<20>")
	)
	(segment
		(start 296.436542 -306.723034)
		(end 296.283126 -306.569618)
		(width 0.14478)
		(layer "In11.Cu")
		(net "M_F_CPU0_SB_DQ<20>")
	)
	(segment
		(start 324.86219 -287.95091)
		(end 323.910452 -288.902648)
		(width 0.0889)
		(layer "In11.Cu")
		(net "M_F_CPU0_SB_DQ<20>")
	)
	(segment
		(start 290.732972 -305.710082)
		(end 289.883088 -306.559966)
		(width 0.14478)
		(layer "In11.Cu")
		(net "M_F_CPU0_SB_DQ<20>")
	)
	(segment
		(start 283.558488 -305.940968)
		(end 283.558488 -305.87315)
		(width 0.14478)
		(layer "In11.Cu")
		(net "M_F_CPU0_SB_DQ<20>")
	)
	(segment
		(start 294.512238 -306.714398)
		(end 293.517574 -305.719734)
		(width 0.14478)
		(layer "In11.Cu")
		(net "M_F_CPU0_SB_DQ<20>")
	)
	(segment
		(start 281.443684 -306.723034)
		(end 281.290268 -306.569618)
		(width 0.14478)
		(layer "In11.Cu")
		(net "M_F_CPU0_SB_DQ<20>")
	)
	(segment
		(start 282.000198 -306.723034)
		(end 282.000198 -306.789328)
		(width 0.14478)
		(layer "In11.Cu")
		(net "M_F_CPU0_SB_DQ<20>")
	)
	(segment
		(start 270.222726 -306.559966)
		(end 270.07312 -306.559966)
		(width 0.14478)
		(layer "In11.Cu")
		(net "M_F_CPU0_SB_DQ<20>")
	)
	(segment
		(start 296.829988 -306.952396)
		(end 296.59961 -306.952396)
		(width 0.14478)
		(layer "In11.Cu")
		(net "M_F_CPU0_SB_DQ<20>")
	)
	(segment
		(start 288.984944 -306.789328)
		(end 288.984944 -306.723034)
		(width 0.14478)
		(layer "In11.Cu")
		(net "M_F_CPU0_SB_DQ<20>")
	)
	(segment
		(start 294.918892 -306.958492)
		(end 294.657018 -306.958492)
		(width 0.14478)
		(layer "In11.Cu")
		(net "M_F_CPU0_SB_DQ<20>")
	)
	(segment
		(start 303.98212 -306.85867)
		(end 303.68367 -306.56022)
		(width 0.14478)
		(layer "In11.Cu")
		(net "M_F_CPU0_SB_DQ<20>")
	)
	(segment
		(start 271.964912 -306.952396)
		(end 271.801844 -306.789328)
		(width 0.14478)
		(layer "In11.Cu")
		(net "M_F_CPU0_SB_DQ<20>")
	)
	(segment
		(start 282.163266 -306.559966)
		(end 282.000198 -306.723034)
		(width 0.14478)
		(layer "In11.Cu")
		(net "M_F_CPU0_SB_DQ<20>")
	)
	(segment
		(start 289.883088 -306.559966)
		(end 289.704526 -306.559966)
		(width 0.14478)
		(layer "In11.Cu")
		(net "M_F_CPU0_SB_DQ<20>")
	)
	(segment
		(start 283.17317 -305.710082)
		(end 282.323286 -306.559966)
		(width 0.14478)
		(layer "In11.Cu")
		(net "M_F_CPU0_SB_DQ<20>")
	)
	(segment
		(start 279.56002 -306.958492)
		(end 279.41524 -306.813712)
		(width 0.14478)
		(layer "In11.Cu")
		(net "M_F_CPU0_SB_DQ<20>")
	)
	(segment
		(start 289.541458 -306.789328)
		(end 289.37839 -306.952396)
		(width 0.14478)
		(layer "In11.Cu")
		(net "M_F_CPU0_SB_DQ<20>")
	)
	(segment
		(start 301.902114 -306.56022)
		(end 301.061628 -305.719734)
		(width 0.14478)
		(layer "In11.Cu")
		(net "M_F_CPU0_SB_DQ<20>")
	)
	(segment
		(start 283.721556 -306.104036)
		(end 283.558488 -305.940968)
		(width 0.14478)
		(layer "In11.Cu")
		(net "M_F_CPU0_SB_DQ<20>")
	)
	(segment
		(start 302.8696 -306.85867)
		(end 302.57115 -306.56022)
		(width 0.14478)
		(layer "In11.Cu")
		(net "M_F_CPU0_SB_DQ<20>")
	)
	(segment
		(start 283.39542 -305.710082)
		(end 283.17317 -305.710082)
		(width 0.14478)
		(layer "In11.Cu")
		(net "M_F_CPU0_SB_DQ<20>")
	)
	(segment
		(start 297.389042 -306.559966)
		(end 297.156124 -306.559966)
		(width 0.14478)
		(layer "In11.Cu")
		(net "M_F_CPU0_SB_DQ<20>")
	)
	(segment
		(start 279.41524 -306.813712)
		(end 279.41524 -306.714398)
		(width 0.14478)
		(layer "In11.Cu")
		(net "M_F_CPU0_SB_DQ<20>")
	)
	(segment
		(start 291.692076 -305.87315)
		(end 291.692076 -305.933348)
		(width 0.14478)
		(layer "In11.Cu")
		(net "M_F_CPU0_SB_DQ<20>")
	)
	(segment
		(start 295.208452 -306.569618)
		(end 295.063672 -306.714398)
		(width 0.14478)
		(layer "In11.Cu")
		(net "M_F_CPU0_SB_DQ<20>")
	)
	(segment
		(start 295.063672 -306.714398)
		(end 295.063672 -306.813712)
		(width 0.14478)
		(layer "In11.Cu")
		(net "M_F_CPU0_SB_DQ<20>")
	)
	(segment
		(start 271.105376 -306.559966)
		(end 270.942308 -306.396898)
		(width 0.14478)
		(layer "In11.Cu")
		(net "M_F_CPU0_SB_DQ<20>")
	)
	(segment
		(start 298.845986 -306.096416)
		(end 298.682918 -305.933348)
		(width 0.14478)
		(layer "In11.Cu")
		(net "M_F_CPU0_SB_DQ<20>")
	)
	(segment
		(start 291.135562 -305.933348)
		(end 291.135562 -305.87315)
		(width 0.14478)
		(layer "In11.Cu")
		(net "M_F_CPU0_SB_DQ<20>")
	)
	(segment
		(start 280.111454 -306.569618)
		(end 279.966674 -306.714398)
		(width 0.14478)
		(layer "In11.Cu")
		(net "M_F_CPU0_SB_DQ<20>")
	)
	(segment
		(start 279.966674 -306.813712)
		(end 279.821894 -306.958492)
		(width 0.14478)
		(layer "In11.Cu")
		(net "M_F_CPU0_SB_DQ<20>")
	)
	(segment
		(start 287.593278 -306.569618)
		(end 287.448498 -306.714398)
		(width 0.14478)
		(layer "In11.Cu")
		(net "M_F_CPU0_SB_DQ<20>")
	)
	(segment
		(start 331.538072 -287.368488)
		(end 331.52969 -287.373314)
		(width 0.0889)
		(layer "In11.Cu")
		(net "M_F_CPU0_SB_DQ<20>")
	)
	(segment
		(start 284.115002 -305.87315)
		(end 284.115002 -305.940968)
		(width 0.14478)
		(layer "In11.Cu")
		(net "M_F_CPU0_SB_DQ<20>")
	)
	(segment
		(start 289.148012 -306.952396)
		(end 288.984944 -306.789328)
		(width 0.14478)
		(layer "In11.Cu")
		(net "M_F_CPU0_SB_DQ<20>")
	)
	(segment
		(start 276.02307 -305.87315)
		(end 275.860002 -305.710082)
		(width 0.14478)
		(layer "In11.Cu")
		(net "M_F_CPU0_SB_DQ<20>")
	)
	(segment
		(start 270.07312 -306.559966)
		(end 269.648178 -306.135024)
		(width 0.14478)
		(layer "In11.Cu")
		(net "M_F_CPU0_SB_DQ<20>")
	)
	(segment
		(start 281.83713 -306.952396)
		(end 281.606752 -306.952396)
		(width 0.14478)
		(layer "In11.Cu")
		(net "M_F_CPU0_SB_DQ<20>")
	)
	(segment
		(start 303.42586 -306.56022)
		(end 303.12741 -306.85867)
		(width 0.14478)
		(layer "In11.Cu")
		(net "M_F_CPU0_SB_DQ<20>")
	)
	(segment
		(start 283.558488 -305.87315)
		(end 283.39542 -305.710082)
		(width 0.14478)
		(layer "In11.Cu")
		(net "M_F_CPU0_SB_DQ<20>")
	)
	(segment
		(start 288.984944 -306.723034)
		(end 288.831528 -306.569618)
		(width 0.14478)
		(layer "In11.Cu")
		(net "M_F_CPU0_SB_DQ<20>")
	)
	(segment
		(start 294.512238 -306.813712)
		(end 294.512238 -306.714398)
		(width 0.14478)
		(layer "In11.Cu")
		(net "M_F_CPU0_SB_DQ<20>")
	)
	(segment
		(start 291.692076 -305.933348)
		(end 291.529008 -306.096416)
		(width 0.14478)
		(layer "In11.Cu")
		(net "M_F_CPU0_SB_DQ<20>")
	)
	(segment
		(start 327.796906 -287.358074)
		(end 327.778872 -287.368488)
		(width 0.0889)
		(layer "In11.Cu")
		(net "M_F_CPU0_SB_DQ<20>")
	)
	(segment
		(start 306.031392 -306.105306)
		(end 305.576478 -306.56022)
		(width 0.14478)
		(layer "In11.Cu")
		(net "M_F_CPU0_SB_DQ<20>")
	)
	(segment
		(start 291.29863 -306.096416)
		(end 291.135562 -305.933348)
		(width 0.14478)
		(layer "In11.Cu")
		(net "M_F_CPU0_SB_DQ<20>")
	)
	(segment
		(start 299.076364 -306.096416)
		(end 298.845986 -306.096416)
		(width 0.14478)
		(layer "In11.Cu")
		(net "M_F_CPU0_SB_DQ<20>")
	)
	(segment
		(start 305.576478 -306.56022)
		(end 304.53838 -306.56022)
		(width 0.14478)
		(layer "In11.Cu")
		(net "M_F_CPU0_SB_DQ<20>")
	)
	(segment
		(start 284.115002 -305.940968)
		(end 283.951934 -306.104036)
		(width 0.14478)
		(layer "In11.Cu")
		(net "M_F_CPU0_SB_DQ<20>")
	)
	(segment
		(start 271.801844 -306.789328)
		(end 271.801844 -306.723034)
		(width 0.14478)
		(layer "In11.Cu")
		(net "M_F_CPU0_SB_DQ<20>")
	)
	(segment
		(start 276.186138 -306.104036)
		(end 276.02307 -305.940968)
		(width 0.14478)
		(layer "In11.Cu")
		(net "M_F_CPU0_SB_DQ<20>")
	)
	(segment
		(start 283.951934 -306.104036)
		(end 283.721556 -306.104036)
		(width 0.14478)
		(layer "In11.Cu")
		(net "M_F_CPU0_SB_DQ<20>")
	)
	(segment
		(start 285.9024 -305.719734)
		(end 284.268418 -305.719734)
		(width 0.14478)
		(layer "In11.Cu")
		(net "M_F_CPU0_SB_DQ<20>")
	)
	(segment
		(start 272.358358 -306.723034)
		(end 272.358358 -306.789328)
		(width 0.14478)
		(layer "In11.Cu")
		(net "M_F_CPU0_SB_DQ<20>")
	)
	(segment
		(start 287.041844 -306.958492)
		(end 286.897064 -306.813712)
		(width 0.14478)
		(layer "In11.Cu")
		(net "M_F_CPU0_SB_DQ<20>")
	)
	(segment
		(start 287.448498 -306.813712)
		(end 287.303718 -306.958492)
		(width 0.14478)
		(layer "In11.Cu")
		(net "M_F_CPU0_SB_DQ<20>")
	)
	(segment
		(start 289.37839 -306.952396)
		(end 289.148012 -306.952396)
		(width 0.14478)
		(layer "In11.Cu")
		(net "M_F_CPU0_SB_DQ<20>")
	)
	(segment
		(start 275.860002 -305.710082)
		(end 275.604732 -305.710082)
		(width 0.14478)
		(layer "In11.Cu")
		(net "M_F_CPU0_SB_DQ<20>")
	)
	(segment
		(start 272.511774 -306.569618)
		(end 272.358358 -306.723034)
		(width 0.14478)
		(layer "In11.Cu")
		(net "M_F_CPU0_SB_DQ<20>")
	)
	(segment
		(start 286.897064 -306.714398)
		(end 285.9024 -305.719734)
		(width 0.14478)
		(layer "In11.Cu")
		(net "M_F_CPU0_SB_DQ<20>")
	)
	(segment
		(start 329.292458 -287.373314)
		(end 329.284076 -287.368488)
		(width 0.0889)
		(layer "In11.Cu")
		(net "M_F_CPU0_SB_DQ<20>")
	)
	(segment
		(start 332.291182 -287.045908)
		(end 332.445106 -287.311338)
		(width 0.0889)
		(layer "In11.Cu")
		(net "M_F_CPU0_SB_DQ<20>")
	)
	(segment
		(start 271.638776 -306.559966)
		(end 271.105376 -306.559966)
		(width 0.14478)
		(layer "In11.Cu")
		(net "M_F_CPU0_SB_DQ<20>")
	)
	(segment
		(start 284.268418 -305.719734)
		(end 284.115002 -305.87315)
		(width 0.14478)
		(layer "In11.Cu")
		(net "M_F_CPU0_SB_DQ<20>")
	)
	(segment
		(start 276.02307 -305.940968)
		(end 276.02307 -305.87315)
		(width 0.14478)
		(layer "In11.Cu")
		(net "M_F_CPU0_SB_DQ<20>")
	)
	(segment
		(start 325.727822 -287.419542)
		(end 325.196454 -287.95091)
		(width 0.0889)
		(layer "In11.Cu")
		(net "M_F_CPU0_SB_DQ<20>")
	)
	(segment
		(start 289.704526 -306.559966)
		(end 289.541458 -306.723034)
		(width 0.14478)
		(layer "In11.Cu")
		(net "M_F_CPU0_SB_DQ<20>")
	)
	(segment
		(start 302.57115 -306.56022)
		(end 301.902114 -306.56022)
		(width 0.14478)
		(layer "In11.Cu")
		(net "M_F_CPU0_SB_DQ<20>")
	)
	(segment
		(start 296.59961 -306.952396)
		(end 296.436542 -306.789328)
		(width 0.14478)
		(layer "In11.Cu")
		(net "M_F_CPU0_SB_DQ<20>")
	)
	(segment
		(start 290.972494 -305.710082)
		(end 290.732972 -305.710082)
		(width 0.14478)
		(layer "In11.Cu")
		(net "M_F_CPU0_SB_DQ<20>")
	)
	(segment
		(start 288.831528 -306.569618)
		(end 287.593278 -306.569618)
		(width 0.14478)
		(layer "In11.Cu")
		(net "M_F_CPU0_SB_DQ<20>")
	)
	(segment
		(start 299.239432 -305.933348)
		(end 299.076364 -306.096416)
		(width 0.14478)
		(layer "In11.Cu")
		(net "M_F_CPU0_SB_DQ<20>")
	)
	(segment
		(start 289.541458 -306.723034)
		(end 289.541458 -306.789328)
		(width 0.14478)
		(layer "In11.Cu")
		(net "M_F_CPU0_SB_DQ<20>")
	)
	(segment
		(start 295.063672 -306.813712)
		(end 294.918892 -306.958492)
		(width 0.14478)
		(layer "In11.Cu")
		(net "M_F_CPU0_SB_DQ<20>")
	)
	(segment
		(start 275.604732 -305.710082)
		(end 274.745196 -306.569618)
		(width 0.14478)
		(layer "In11.Cu")
		(net "M_F_CPU0_SB_DQ<20>")
	)
	(segment
		(start 327.778872 -287.368488)
		(end 327.77049 -287.373314)
		(width 0.0889)
		(layer "In11.Cu")
		(net "M_F_CPU0_SB_DQ<20>")
	)
	(segment
		(start 271.801844 -306.723034)
		(end 271.638776 -306.559966)
		(width 0.14478)
		(layer "In11.Cu")
		(net "M_F_CPU0_SB_DQ<20>")
	)
	(segment
		(start 272.358358 -306.789328)
		(end 272.19529 -306.952396)
		(width 0.14478)
		(layer "In11.Cu")
		(net "M_F_CPU0_SB_DQ<20>")
	)
	(segment
		(start 296.993056 -306.789328)
		(end 296.829988 -306.952396)
		(width 0.14478)
		(layer "In11.Cu")
		(net "M_F_CPU0_SB_DQ<20>")
	)
	(segment
		(start 281.290268 -306.569618)
		(end 280.111454 -306.569618)
		(width 0.14478)
		(layer "In11.Cu")
		(net "M_F_CPU0_SB_DQ<20>")
	)
	(segment
		(start 297.156124 -306.559966)
		(end 296.993056 -306.723034)
		(width 0.14478)
		(layer "In11.Cu")
		(net "M_F_CPU0_SB_DQ<20>")
	)
	(segment
		(start 298.682918 -305.87315)
		(end 298.51985 -305.710082)
		(width 0.14478)
		(layer "In11.Cu")
		(net "M_F_CPU0_SB_DQ<20>")
	)
	(segment
		(start 282.323286 -306.559966)
		(end 282.163266 -306.559966)
		(width 0.14478)
		(layer "In11.Cu")
		(net "M_F_CPU0_SB_DQ<20>")
	)
	(segment
		(start 293.517574 -305.719734)
		(end 291.845492 -305.719734)
		(width 0.14478)
		(layer "In11.Cu")
		(net "M_F_CPU0_SB_DQ<20>")
	)
	(segment
		(start 306.707794 -306.105306)
		(end 306.031392 -306.105306)
		(width 0.14478)
		(layer "In11.Cu")
		(net "M_F_CPU0_SB_DQ<20>")
	)
	(segment
		(start 279.41524 -306.714398)
		(end 278.420576 -305.719734)
		(width 0.14478)
		(layer "In11.Cu")
		(net "M_F_CPU0_SB_DQ<20>")
	)
	(segment
		(start 327.405238 -287.368488)
		(end 327.387204 -287.35782)
		(width 0.0889)
		(layer "In11.Cu")
		(net "M_F_CPU0_SB_DQ<20>")
	)
	(segment
		(start 294.657018 -306.958492)
		(end 294.512238 -306.813712)
		(width 0.14478)
		(layer "In11.Cu")
		(net "M_F_CPU0_SB_DQ<20>")
	)
	(segment
		(start 291.845492 -305.719734)
		(end 291.692076 -305.87315)
		(width 0.14478)
		(layer "In11.Cu")
		(net "M_F_CPU0_SB_DQ<20>")
	)
	(segment
		(start 282.000198 -306.789328)
		(end 281.83713 -306.952396)
		(width 0.14478)
		(layer "In11.Cu")
		(net "M_F_CPU0_SB_DQ<20>")
	)
	(segment
		(start 298.682918 -305.933348)
		(end 298.682918 -305.87315)
		(width 0.14478)
		(layer "In11.Cu")
		(net "M_F_CPU0_SB_DQ<20>")
	)
	(segment
		(start 296.993056 -306.723034)
		(end 296.993056 -306.789328)
		(width 0.14478)
		(layer "In11.Cu")
		(net "M_F_CPU0_SB_DQ<20>")
	)
	(segment
		(start 270.77924 -305.829716)
		(end 270.548862 -305.829716)
		(width 0.14478)
		(layer "In11.Cu")
		(net "M_F_CPU0_SB_DQ<20>")
	)
	(segment
		(start 298.238926 -305.710082)
		(end 297.389042 -306.559966)
		(width 0.14478)
		(layer "In11.Cu")
		(net "M_F_CPU0_SB_DQ<20>")
	)
	(segment
		(start 276.733 -305.719734)
		(end 276.579584 -305.87315)
		(width 0.14478)
		(layer "In11.Cu")
		(net "M_F_CPU0_SB_DQ<20>")
	)
	(segment
		(start 276.579584 -305.940968)
		(end 276.416516 -306.104036)
		(width 0.14478)
		(layer "In11.Cu")
		(net "M_F_CPU0_SB_DQ<20>")
	)
	(segment
		(start 296.436542 -306.789328)
		(end 296.436542 -306.723034)
		(width 0.14478)
		(layer "In11.Cu")
		(net "M_F_CPU0_SB_DQ<20>")
	)
	(segment
		(start 303.12741 -306.85867)
		(end 302.8696 -306.85867)
		(width 0.14478)
		(layer "In11.Cu")
		(net "M_F_CPU0_SB_DQ<20>")
	)
	(segment
		(start 287.448498 -306.714398)
		(end 287.448498 -306.813712)
		(width 0.14478)
		(layer "In11.Cu")
		(net "M_F_CPU0_SB_DQ<20>")
	)
	(segment
		(start 291.135562 -305.87315)
		(end 290.972494 -305.710082)
		(width 0.14478)
		(layer "In11.Cu")
		(net "M_F_CPU0_SB_DQ<20>")
	)
	(segment
		(start 303.68367 -306.56022)
		(end 303.42586 -306.56022)
		(width 0.14478)
		(layer "In11.Cu")
		(net "M_F_CPU0_SB_DQ<20>")
	)
	(segment
		(start 270.942308 -306.396898)
		(end 270.942308 -305.992784)
		(width 0.14478)
		(layer "In11.Cu")
		(net "M_F_CPU0_SB_DQ<20>")
	)
	(segment
		(start 304.53838 -306.56022)
		(end 304.23993 -306.85867)
		(width 0.14478)
		(layer "In11.Cu")
		(net "M_F_CPU0_SB_DQ<20>")
	)
	(segment
		(start 291.529008 -306.096416)
		(end 291.29863 -306.096416)
		(width 0.14478)
		(layer "In11.Cu")
		(net "M_F_CPU0_SB_DQ<20>")
	)
	(segment
		(start 299.392848 -305.719734)
		(end 299.239432 -305.87315)
		(width 0.14478)
		(layer "In11.Cu")
		(net "M_F_CPU0_SB_DQ<20>")
	)
	(segment
		(start 279.966674 -306.714398)
		(end 279.966674 -306.813712)
		(width 0.14478)
		(layer "In11.Cu")
		(net "M_F_CPU0_SB_DQ<20>")
	)
	(segment
		(start 326.651112 -287.419542)
		(end 325.727822 -287.419542)
		(width 0.0889)
		(layer "In11.Cu")
		(net "M_F_CPU0_SB_DQ<20>")
	)
	(segment
		(start 299.239432 -305.87315)
		(end 299.239432 -305.933348)
		(width 0.14478)
		(layer "In11.Cu")
		(net "M_F_CPU0_SB_DQ<20>")
	)
	(segment
		(start 281.606752 -306.952396)
		(end 281.443684 -306.789328)
		(width 0.14478)
		(layer "In11.Cu")
		(net "M_F_CPU0_SB_DQ<20>")
	)
	(segment
		(start 298.51985 -305.710082)
		(end 298.238926 -305.710082)
		(width 0.14478)
		(layer "In11.Cu")
		(net "M_F_CPU0_SB_DQ<20>")
	)
	(segment
		(start 272.19529 -306.952396)
		(end 271.964912 -306.952396)
		(width 0.14478)
		(layer "In11.Cu")
		(net "M_F_CPU0_SB_DQ<20>")
	)
	(segment
		(start 323.910452 -288.902648)
		(end 306.707794 -306.105306)
		(width 0.14478)
		(layer "In11.Cu")
		(net "M_F_CPU0_SB_DQ<20>")
	)
	(segment
		(start 287.303718 -306.958492)
		(end 287.041844 -306.958492)
		(width 0.14478)
		(layer "In11.Cu")
		(net "M_F_CPU0_SB_DQ<20>")
	)
	(segment
		(start 270.385794 -305.992784)
		(end 270.385794 -306.396898)
		(width 0.14478)
		(layer "In11.Cu")
		(net "M_F_CPU0_SB_DQ<20>")
	)
	(segment
		(start 281.443684 -306.789328)
		(end 281.443684 -306.723034)
		(width 0.14478)
		(layer "In11.Cu")
		(net "M_F_CPU0_SB_DQ<20>")
	)
	(segment
		(start 328.718164 -287.368488)
		(end 328.709782 -287.373314)
		(width 0.0889)
		(layer "In11.Cu")
		(net "M_F_CPU0_SB_DQ<20>")
	)
	(segment
		(start 276.416516 -306.104036)
		(end 276.186138 -306.104036)
		(width 0.14478)
		(layer "In11.Cu")
		(net "M_F_CPU0_SB_DQ<20>")
	)
	(arc
		(start 330.22413 -287.368488)
		(mid 329.941174 -287.292345)
		(end 329.658218 -287.368488)
		(width 0.0889)
		(layer "In11.Cu")
		(net "M_F_CPU0_SB_DQ<20>")
	)
	(arc
		(start 329.284076 -287.368488)
		(mid 329.00112 -287.292345)
		(end 328.718164 -287.368488)
		(width 0.0889)
		(layer "In11.Cu")
		(net "M_F_CPU0_SB_DQ<20>")
	)
	(arc
		(start 329.658218 -287.368488)
		(mid 329.475967 -287.418838)
		(end 329.292458 -287.373314)
		(width 0.0889)
		(layer "In11.Cu")
		(net "M_F_CPU0_SB_DQ<20>")
	)
	(arc
		(start 327.387204 -287.35782)
		(mid 327.111509 -287.292006)
		(end 326.838564 -287.368488)
		(width 0.0889)
		(layer "In11.Cu")
		(net "M_F_CPU0_SB_DQ<20>")
	)
	(arc
		(start 332.422754 -287.39465)
		(mid 332.260422 -287.417468)
		(end 332.103984 -287.368488)
		(width 0.0889)
		(layer "In11.Cu")
		(net "M_F_CPU0_SB_DQ<20>")
	)
	(arc
		(start 332.103984 -287.368488)
		(mid 331.821028 -287.292345)
		(end 331.538072 -287.368488)
		(width 0.0889)
		(layer "In11.Cu")
		(net "M_F_CPU0_SB_DQ<20>")
	)
	(arc
		(start 330.598018 -287.368488)
		(mid 330.411074 -287.418743)
		(end 330.22413 -287.368488)
		(width 0.0889)
		(layer "In11.Cu")
		(net "M_F_CPU0_SB_DQ<20>")
	)
	(arc
		(start 328.709782 -287.373314)
		(mid 328.526274 -287.418808)
		(end 328.344022 -287.368488)
		(width 0.0889)
		(layer "In11.Cu")
		(net "M_F_CPU0_SB_DQ<20>")
	)
	(arc
		(start 331.52969 -287.373314)
		(mid 331.346182 -287.418808)
		(end 331.16393 -287.368488)
		(width 0.0889)
		(layer "In11.Cu")
		(net "M_F_CPU0_SB_DQ<20>")
	)
	(arc
		(start 326.838564 -287.368488)
		(mid 326.748217 -287.406421)
		(end 326.651112 -287.419542)
		(width 0.0889)
		(layer "In11.Cu")
		(net "M_F_CPU0_SB_DQ<20>")
	)
	(arc
		(start 328.344022 -287.368488)
		(mid 328.07181 -287.292448)
		(end 327.796906 -287.358074)
		(width 0.0889)
		(layer "In11.Cu")
		(net "M_F_CPU0_SB_DQ<20>")
	)
	(arc
		(start 327.77049 -287.373314)
		(mid 327.587236 -287.418687)
		(end 327.405238 -287.368488)
		(width 0.0889)
		(layer "In11.Cu")
		(net "M_F_CPU0_SB_DQ<20>")
	)
	(arc
		(start 331.16393 -287.368488)
		(mid 330.880974 -287.292345)
		(end 330.598018 -287.368488)
		(width 0.0889)
		(layer "In11.Cu")
		(net "M_F_CPU0_SB_DQ<20>")
	)
	(segment
		(start 334.167988 -274.630134)
		(end 333.701136 -274.896072)
		(width 0.10668)
		(layer "F.Cu")
		(net "M_F_CPU0_SB_DQ<1>")
	)
	(segment
		(start 311.986422 -278.304498)
		(end 311.986422 -277.909274)
		(width 0.14478)
		(layer "In11.Cu")
		(net "M_F_CPU0_SB_DQ<1>")
	)
	(segment
		(start 269.648178 -283.185108)
		(end 269.648178 -283.298392)
		(width 0.14478)
		(layer "In11.Cu")
		(net "M_F_CPU0_SB_DQ<1>")
	)
	(segment
		(start 301.006256 -282.759912)
		(end 301.856394 -283.61005)
		(width 0.14478)
		(layer "In11.Cu")
		(net "M_F_CPU0_SB_DQ<1>")
	)
	(segment
		(start 315.69533 -274.59559)
		(end 316.16142 -274.1295)
		(width 0.14478)
		(layer "In11.Cu")
		(net "M_F_CPU0_SB_DQ<1>")
	)
	(segment
		(start 310.425846 -279.865074)
		(end 310.425846 -279.46985)
		(width 0.14478)
		(layer "In11.Cu")
		(net "M_F_CPU0_SB_DQ<1>")
	)
	(segment
		(start 316.16142 -274.1295)
		(end 324.174104 -274.1295)
		(width 0.14478)
		(layer "In11.Cu")
		(net "M_F_CPU0_SB_DQ<1>")
	)
	(segment
		(start 330.119736 -275.223478)
		(end 330.128118 -275.218652)
		(width 0.0889)
		(layer "In11.Cu")
		(net "M_F_CPU0_SB_DQ<1>")
	)
	(segment
		(start 308.86527 -281.42565)
		(end 308.86527 -281.030426)
		(width 0.14478)
		(layer "In11.Cu")
		(net "M_F_CPU0_SB_DQ<1>")
	)
	(segment
		(start 276.016974 -282.49499)
		(end 276.308312 -282.49499)
		(width 0.14478)
		(layer "In11.Cu")
		(net "M_F_CPU0_SB_DQ<1>")
	)
	(segment
		(start 274.026884 -283.29255)
		(end 274.344384 -283.61005)
		(width 0.14478)
		(layer "In11.Cu")
		(net "M_F_CPU0_SB_DQ<1>")
	)
	(segment
		(start 307.531008 -282.759912)
		(end 308.084982 -282.205938)
		(width 0.14478)
		(layer "In11.Cu")
		(net "M_F_CPU0_SB_DQ<1>")
	)
	(segment
		(start 272.119344 -283.215334)
		(end 272.349976 -283.215334)
		(width 0.14478)
		(layer "In11.Cu")
		(net "M_F_CPU0_SB_DQ<1>")
	)
	(segment
		(start 271.95653 -283.378148)
		(end 272.119344 -283.215334)
		(width 0.14478)
		(layer "In11.Cu")
		(net "M_F_CPU0_SB_DQ<1>")
	)
	(segment
		(start 314.519818 -275.375878)
		(end 314.915042 -275.375878)
		(width 0.14478)
		(layer "In11.Cu")
		(net "M_F_CPU0_SB_DQ<1>")
	)
	(segment
		(start 308.672738 -281.618182)
		(end 308.86527 -281.42565)
		(width 0.14478)
		(layer "In11.Cu")
		(net "M_F_CPU0_SB_DQ<1>")
	)
	(segment
		(start 313.354466 -276.936454)
		(end 313.546998 -276.743922)
		(width 0.14478)
		(layer "In11.Cu")
		(net "M_F_CPU0_SB_DQ<1>")
	)
	(segment
		(start 309.83809 -280.057606)
		(end 310.233314 -280.057606)
		(width 0.14478)
		(layer "In11.Cu")
		(net "M_F_CPU0_SB_DQ<1>")
	)
	(segment
		(start 271.40027 -283.82468)
		(end 271.563084 -283.987494)
		(width 0.14478)
		(layer "In11.Cu")
		(net "M_F_CPU0_SB_DQ<1>")
	)
	(segment
		(start 326.390254 -275.09851)
		(end 327.428352 -275.09851)
		(width 0.0889)
		(layer "In11.Cu")
		(net "M_F_CPU0_SB_DQ<1>")
	)
	(segment
		(start 273.788124 -283.29255)
		(end 274.026884 -283.29255)
		(width 0.14478)
		(layer "In11.Cu")
		(net "M_F_CPU0_SB_DQ<1>")
	)
	(segment
		(start 311.013602 -279.277318)
		(end 311.206134 -279.084786)
		(width 0.14478)
		(layer "In11.Cu")
		(net "M_F_CPU0_SB_DQ<1>")
	)
	(segment
		(start 310.425846 -279.46985)
		(end 310.618378 -279.277318)
		(width 0.14478)
		(layer "In11.Cu")
		(net "M_F_CPU0_SB_DQ<1>")
	)
	(segment
		(start 293.513256 -282.759912)
		(end 294.363394 -283.61005)
		(width 0.14478)
		(layer "In11.Cu")
		(net "M_F_CPU0_SB_DQ<1>")
	)
	(segment
		(start 271.95653 -283.82468)
		(end 271.95653 -283.378148)
		(width 0.14478)
		(layer "In11.Cu")
		(net "M_F_CPU0_SB_DQ<1>")
	)
	(segment
		(start 270.84401 -283.378148)
		(end 271.006824 -283.215334)
		(width 0.14478)
		(layer "In11.Cu")
		(net "M_F_CPU0_SB_DQ<1>")
	)
	(segment
		(start 289.913314 -283.61005)
		(end 290.763452 -282.759912)
		(width 0.14478)
		(layer "In11.Cu")
		(net "M_F_CPU0_SB_DQ<1>")
	)
	(segment
		(start 269.648178 -283.298392)
		(end 270.33728 -283.987494)
		(width 0.14478)
		(layer "In11.Cu")
		(net "M_F_CPU0_SB_DQ<1>")
	)
	(segment
		(start 315.107574 -274.788122)
		(end 315.300106 -274.59559)
		(width 0.14478)
		(layer "In11.Cu")
		(net "M_F_CPU0_SB_DQ<1>")
	)
	(segment
		(start 290.763452 -282.759912)
		(end 293.513256 -282.759912)
		(width 0.14478)
		(layer "In11.Cu")
		(net "M_F_CPU0_SB_DQ<1>")
	)
	(segment
		(start 324.174104 -274.1295)
		(end 324.271894 -274.03171)
		(width 0.0889)
		(layer "In11.Cu")
		(net "M_F_CPU0_SB_DQ<1>")
	)
	(segment
		(start 309.645558 -280.250138)
		(end 309.83809 -280.057606)
		(width 0.14478)
		(layer "In11.Cu")
		(net "M_F_CPU0_SB_DQ<1>")
	)
	(segment
		(start 276.573234 -282.759912)
		(end 278.400256 -282.759912)
		(width 0.14478)
		(layer "In11.Cu")
		(net "M_F_CPU0_SB_DQ<1>")
	)
	(segment
		(start 274.344384 -283.61005)
		(end 274.901914 -283.61005)
		(width 0.14478)
		(layer "In11.Cu")
		(net "M_F_CPU0_SB_DQ<1>")
	)
	(segment
		(start 308.86527 -281.030426)
		(end 309.057802 -280.837894)
		(width 0.14478)
		(layer "In11.Cu")
		(net "M_F_CPU0_SB_DQ<1>")
	)
	(segment
		(start 271.006824 -283.215334)
		(end 271.237456 -283.215334)
		(width 0.14478)
		(layer "In11.Cu")
		(net "M_F_CPU0_SB_DQ<1>")
	)
	(segment
		(start 330.69403 -275.218652)
		(end 330.702412 -275.223478)
		(width 0.0889)
		(layer "In11.Cu")
		(net "M_F_CPU0_SB_DQ<1>")
	)
	(segment
		(start 271.237456 -283.215334)
		(end 271.40027 -283.378148)
		(width 0.14478)
		(layer "In11.Cu")
		(net "M_F_CPU0_SB_DQ<1>")
	)
	(segment
		(start 331.634084 -275.218652)
		(end 331.642466 -275.223478)
		(width 0.0889)
		(layer "In11.Cu")
		(net "M_F_CPU0_SB_DQ<1>")
	)
	(segment
		(start 312.76671 -277.128986)
		(end 312.959242 -276.936454)
		(width 0.14478)
		(layer "In11.Cu")
		(net "M_F_CPU0_SB_DQ<1>")
	)
	(segment
		(start 313.73953 -276.156166)
		(end 314.134754 -276.156166)
		(width 0.14478)
		(layer "In11.Cu")
		(net "M_F_CPU0_SB_DQ<1>")
	)
	(segment
		(start 333.832708 -275.244814)
		(end 333.85506 -275.161502)
		(width 0.0889)
		(layer "In11.Cu")
		(net "M_F_CPU0_SB_DQ<1>")
	)
	(segment
		(start 308.277514 -281.618182)
		(end 308.672738 -281.618182)
		(width 0.14478)
		(layer "In11.Cu")
		(net "M_F_CPU0_SB_DQ<1>")
	)
	(segment
		(start 273.470624 -283.61005)
		(end 273.788124 -283.29255)
		(width 0.14478)
		(layer "In11.Cu")
		(net "M_F_CPU0_SB_DQ<1>")
	)
	(segment
		(start 314.327286 -275.963634)
		(end 314.327286 -275.56841)
		(width 0.14478)
		(layer "In11.Cu")
		(net "M_F_CPU0_SB_DQ<1>")
	)
	(segment
		(start 279.250394 -283.61005)
		(end 282.166314 -283.61005)
		(width 0.14478)
		(layer "In11.Cu")
		(net "M_F_CPU0_SB_DQ<1>")
	)
	(segment
		(start 309.453026 -280.837894)
		(end 309.645558 -280.645362)
		(width 0.14478)
		(layer "In11.Cu")
		(net "M_F_CPU0_SB_DQ<1>")
	)
	(segment
		(start 271.793716 -283.987494)
		(end 271.95653 -283.82468)
		(width 0.14478)
		(layer "In11.Cu")
		(net "M_F_CPU0_SB_DQ<1>")
	)
	(segment
		(start 297.007026 -283.61005)
		(end 297.857164 -282.759912)
		(width 0.14478)
		(layer "In11.Cu")
		(net "M_F_CPU0_SB_DQ<1>")
	)
	(segment
		(start 312.959242 -276.936454)
		(end 313.354466 -276.936454)
		(width 0.14478)
		(layer "In11.Cu")
		(net "M_F_CPU0_SB_DQ<1>")
	)
	(segment
		(start 305.240436 -282.759912)
		(end 307.531008 -282.759912)
		(width 0.14478)
		(layer "In11.Cu")
		(net "M_F_CPU0_SB_DQ<1>")
	)
	(segment
		(start 309.645558 -280.645362)
		(end 309.645558 -280.250138)
		(width 0.14478)
		(layer "In11.Cu")
		(net "M_F_CPU0_SB_DQ<1>")
	)
	(segment
		(start 304.390298 -283.61005)
		(end 305.240436 -282.759912)
		(width 0.14478)
		(layer "In11.Cu")
		(net "M_F_CPU0_SB_DQ<1>")
	)
	(segment
		(start 285.893256 -282.759912)
		(end 286.743394 -283.61005)
		(width 0.14478)
		(layer "In11.Cu")
		(net "M_F_CPU0_SB_DQ<1>")
	)
	(segment
		(start 309.057802 -280.837894)
		(end 309.453026 -280.837894)
		(width 0.14478)
		(layer "In11.Cu")
		(net "M_F_CPU0_SB_DQ<1>")
	)
	(segment
		(start 274.901914 -283.61005)
		(end 276.016974 -282.49499)
		(width 0.14478)
		(layer "In11.Cu")
		(net "M_F_CPU0_SB_DQ<1>")
	)
	(segment
		(start 315.300106 -274.59559)
		(end 315.69533 -274.59559)
		(width 0.14478)
		(layer "In11.Cu")
		(net "M_F_CPU0_SB_DQ<1>")
	)
	(segment
		(start 270.84401 -283.82468)
		(end 270.84401 -283.378148)
		(width 0.14478)
		(layer "In11.Cu")
		(net "M_F_CPU0_SB_DQ<1>")
	)
	(segment
		(start 312.574178 -277.716742)
		(end 312.76671 -277.52421)
		(width 0.14478)
		(layer "In11.Cu")
		(net "M_F_CPU0_SB_DQ<1>")
	)
	(segment
		(start 278.400256 -282.759912)
		(end 279.250394 -283.61005)
		(width 0.14478)
		(layer "In11.Cu")
		(net "M_F_CPU0_SB_DQ<1>")
	)
	(segment
		(start 276.308312 -282.49499)
		(end 276.573234 -282.759912)
		(width 0.14478)
		(layer "In11.Cu")
		(net "M_F_CPU0_SB_DQ<1>")
	)
	(segment
		(start 270.33728 -283.987494)
		(end 270.681196 -283.987494)
		(width 0.14478)
		(layer "In11.Cu")
		(net "M_F_CPU0_SB_DQ<1>")
	)
	(segment
		(start 308.084982 -282.205938)
		(end 308.084982 -281.810714)
		(width 0.14478)
		(layer "In11.Cu")
		(net "M_F_CPU0_SB_DQ<1>")
	)
	(segment
		(start 333.85506 -275.161502)
		(end 333.701136 -274.896072)
		(width 0.0889)
		(layer "In11.Cu")
		(net "M_F_CPU0_SB_DQ<1>")
	)
	(segment
		(start 283.016452 -282.759912)
		(end 285.893256 -282.759912)
		(width 0.14478)
		(layer "In11.Cu")
		(net "M_F_CPU0_SB_DQ<1>")
	)
	(segment
		(start 308.084982 -281.810714)
		(end 308.277514 -281.618182)
		(width 0.14478)
		(layer "In11.Cu")
		(net "M_F_CPU0_SB_DQ<1>")
	)
	(segment
		(start 311.206134 -278.689562)
		(end 311.398666 -278.49703)
		(width 0.14478)
		(layer "In11.Cu")
		(net "M_F_CPU0_SB_DQ<1>")
	)
	(segment
		(start 312.178954 -277.716742)
		(end 312.574178 -277.716742)
		(width 0.14478)
		(layer "In11.Cu")
		(net "M_F_CPU0_SB_DQ<1>")
	)
	(segment
		(start 325.323454 -274.03171)
		(end 326.390254 -275.09851)
		(width 0.0889)
		(layer "In11.Cu")
		(net "M_F_CPU0_SB_DQ<1>")
	)
	(segment
		(start 314.134754 -276.156166)
		(end 314.327286 -275.963634)
		(width 0.14478)
		(layer "In11.Cu")
		(net "M_F_CPU0_SB_DQ<1>")
	)
	(segment
		(start 312.76671 -277.52421)
		(end 312.76671 -277.128986)
		(width 0.14478)
		(layer "In11.Cu")
		(net "M_F_CPU0_SB_DQ<1>")
	)
	(segment
		(start 310.233314 -280.057606)
		(end 310.425846 -279.865074)
		(width 0.14478)
		(layer "In11.Cu")
		(net "M_F_CPU0_SB_DQ<1>")
	)
	(segment
		(start 311.206134 -279.084786)
		(end 311.206134 -278.689562)
		(width 0.14478)
		(layer "In11.Cu")
		(net "M_F_CPU0_SB_DQ<1>")
	)
	(segment
		(start 311.986422 -277.909274)
		(end 312.178954 -277.716742)
		(width 0.14478)
		(layer "In11.Cu")
		(net "M_F_CPU0_SB_DQ<1>")
	)
	(segment
		(start 314.327286 -275.56841)
		(end 314.519818 -275.375878)
		(width 0.14478)
		(layer "In11.Cu")
		(net "M_F_CPU0_SB_DQ<1>")
	)
	(segment
		(start 272.744692 -283.61005)
		(end 273.470624 -283.61005)
		(width 0.14478)
		(layer "In11.Cu")
		(net "M_F_CPU0_SB_DQ<1>")
	)
	(segment
		(start 313.546998 -276.743922)
		(end 313.546998 -276.348698)
		(width 0.14478)
		(layer "In11.Cu")
		(net "M_F_CPU0_SB_DQ<1>")
	)
	(segment
		(start 286.743394 -283.61005)
		(end 289.913314 -283.61005)
		(width 0.14478)
		(layer "In11.Cu")
		(net "M_F_CPU0_SB_DQ<1>")
	)
	(segment
		(start 271.563084 -283.987494)
		(end 271.793716 -283.987494)
		(width 0.14478)
		(layer "In11.Cu")
		(net "M_F_CPU0_SB_DQ<1>")
	)
	(segment
		(start 271.40027 -283.378148)
		(end 271.40027 -283.82468)
		(width 0.14478)
		(layer "In11.Cu")
		(net "M_F_CPU0_SB_DQ<1>")
	)
	(segment
		(start 315.107574 -275.183346)
		(end 315.107574 -274.788122)
		(width 0.14478)
		(layer "In11.Cu")
		(net "M_F_CPU0_SB_DQ<1>")
	)
	(segment
		(start 270.681196 -283.987494)
		(end 270.84401 -283.82468)
		(width 0.14478)
		(layer "In11.Cu")
		(net "M_F_CPU0_SB_DQ<1>")
	)
	(segment
		(start 311.79389 -278.49703)
		(end 311.986422 -278.304498)
		(width 0.14478)
		(layer "In11.Cu")
		(net "M_F_CPU0_SB_DQ<1>")
	)
	(segment
		(start 311.398666 -278.49703)
		(end 311.79389 -278.49703)
		(width 0.14478)
		(layer "In11.Cu")
		(net "M_F_CPU0_SB_DQ<1>")
	)
	(segment
		(start 301.856394 -283.61005)
		(end 304.390298 -283.61005)
		(width 0.14478)
		(layer "In11.Cu")
		(net "M_F_CPU0_SB_DQ<1>")
	)
	(segment
		(start 272.349976 -283.215334)
		(end 272.744692 -283.61005)
		(width 0.14478)
		(layer "In11.Cu")
		(net "M_F_CPU0_SB_DQ<1>")
	)
	(segment
		(start 324.271894 -274.03171)
		(end 325.323454 -274.03171)
		(width 0.0889)
		(layer "In11.Cu")
		(net "M_F_CPU0_SB_DQ<1>")
	)
	(segment
		(start 282.166314 -283.61005)
		(end 283.016452 -282.759912)
		(width 0.14478)
		(layer "In11.Cu")
		(net "M_F_CPU0_SB_DQ<1>")
	)
	(segment
		(start 314.915042 -275.375878)
		(end 315.107574 -275.183346)
		(width 0.14478)
		(layer "In11.Cu")
		(net "M_F_CPU0_SB_DQ<1>")
	)
	(segment
		(start 310.618378 -279.277318)
		(end 311.013602 -279.277318)
		(width 0.14478)
		(layer "In11.Cu")
		(net "M_F_CPU0_SB_DQ<1>")
	)
	(segment
		(start 297.857164 -282.759912)
		(end 301.006256 -282.759912)
		(width 0.14478)
		(layer "In11.Cu")
		(net "M_F_CPU0_SB_DQ<1>")
	)
	(segment
		(start 313.546998 -276.348698)
		(end 313.73953 -276.156166)
		(width 0.14478)
		(layer "In11.Cu")
		(net "M_F_CPU0_SB_DQ<1>")
	)
	(segment
		(start 294.363394 -283.61005)
		(end 297.007026 -283.61005)
		(width 0.14478)
		(layer "In11.Cu")
		(net "M_F_CPU0_SB_DQ<1>")
	)
	(arc
		(start 328.248264 -275.218652)
		(mid 328.53122 -275.142475)
		(end 328.814176 -275.218652)
		(width 0.0889)
		(layer "In11.Cu")
		(net "M_F_CPU0_SB_DQ<1>")
	)
	(arc
		(start 330.128118 -275.218652)
		(mid 330.411074 -275.142475)
		(end 330.69403 -275.218652)
		(width 0.0889)
		(layer "In11.Cu")
		(net "M_F_CPU0_SB_DQ<1>")
	)
	(arc
		(start 332.574138 -275.218652)
		(mid 332.761082 -275.268907)
		(end 332.948026 -275.218652)
		(width 0.0889)
		(layer "In11.Cu")
		(net "M_F_CPU0_SB_DQ<1>")
	)
	(arc
		(start 332.948026 -275.218652)
		(mid 333.230982 -275.142475)
		(end 333.513938 -275.218652)
		(width 0.0889)
		(layer "In11.Cu")
		(net "M_F_CPU0_SB_DQ<1>")
	)
	(arc
		(start 328.814176 -275.218652)
		(mid 329.00112 -275.268907)
		(end 329.188064 -275.218652)
		(width 0.0889)
		(layer "In11.Cu")
		(net "M_F_CPU0_SB_DQ<1>")
	)
	(arc
		(start 327.873868 -275.218652)
		(mid 328.061066 -275.269034)
		(end 328.248264 -275.218652)
		(width 0.0889)
		(layer "In11.Cu")
		(net "M_F_CPU0_SB_DQ<1>")
	)
	(arc
		(start 327.428352 -275.09851)
		(mid 327.659065 -275.129078)
		(end 327.873868 -275.218652)
		(width 0.0889)
		(layer "In11.Cu")
		(net "M_F_CPU0_SB_DQ<1>")
	)
	(arc
		(start 333.513938 -275.218652)
		(mid 333.670376 -275.267623)
		(end 333.832708 -275.244814)
		(width 0.0889)
		(layer "In11.Cu")
		(net "M_F_CPU0_SB_DQ<1>")
	)
	(arc
		(start 329.188064 -275.218652)
		(mid 329.47102 -275.142475)
		(end 329.753976 -275.218652)
		(width 0.0889)
		(layer "In11.Cu")
		(net "M_F_CPU0_SB_DQ<1>")
	)
	(arc
		(start 330.702412 -275.223478)
		(mid 330.88592 -275.268972)
		(end 331.068172 -275.218652)
		(width 0.0889)
		(layer "In11.Cu")
		(net "M_F_CPU0_SB_DQ<1>")
	)
	(arc
		(start 332.008226 -275.218652)
		(mid 332.291182 -275.142475)
		(end 332.574138 -275.218652)
		(width 0.0889)
		(layer "In11.Cu")
		(net "M_F_CPU0_SB_DQ<1>")
	)
	(arc
		(start 331.642466 -275.223478)
		(mid 331.825974 -275.268972)
		(end 332.008226 -275.218652)
		(width 0.0889)
		(layer "In11.Cu")
		(net "M_F_CPU0_SB_DQ<1>")
	)
	(arc
		(start 329.753976 -275.218652)
		(mid 329.936227 -275.269002)
		(end 330.119736 -275.223478)
		(width 0.0889)
		(layer "In11.Cu")
		(net "M_F_CPU0_SB_DQ<1>")
	)
	(arc
		(start 331.068172 -275.218652)
		(mid 331.351128 -275.142475)
		(end 331.634084 -275.218652)
		(width 0.0889)
		(layer "In11.Cu")
		(net "M_F_CPU0_SB_DQ<1>")
	)
	(segment
		(start 334.637888 -285.160212)
		(end 334.171036 -285.42615)
		(width 0.10668)
		(layer "F.Cu")
		(net "M_F_CPU0_SB_DQ<19>")
	)
	(segment
		(start 324.865238 -285.57982)
		(end 324.613778 -285.83128)
		(width 0.0889)
		(layer "In11.Cu")
		(net "M_F_CPU0_SB_DQ<19>")
	)
	(segment
		(start 306.822856 -302.023018)
		(end 306.561236 -302.023018)
		(width 0.14478)
		(layer "In11.Cu")
		(net "M_F_CPU0_SB_DQ<19>")
	)
	(segment
		(start 289.84194 -303.15027)
		(end 286.893508 -303.15027)
		(width 0.14478)
		(layer "In11.Cu")
		(net "M_F_CPU0_SB_DQ<19>")
	)
	(segment
		(start 267.165328 -302.997108)
		(end 267.165328 -302.629824)
		(width 0.14478)
		(layer "In11.Cu")
		(net "M_F_CPU0_SB_DQ<19>")
	)
	(segment
		(start 293.54907 -302.300386)
		(end 290.691824 -302.300386)
		(width 0.14478)
		(layer "In11.Cu")
		(net "M_F_CPU0_SB_DQ<19>")
	)
	(segment
		(start 304.674524 -302.764698)
		(end 301.549816 -302.764698)
		(width 0.14478)
		(layer "In11.Cu")
		(net "M_F_CPU0_SB_DQ<19>")
	)
	(segment
		(start 282.308554 -303.15027)
		(end 279.324054 -303.15027)
		(width 0.14478)
		(layer "In11.Cu")
		(net "M_F_CPU0_SB_DQ<19>")
	)
	(segment
		(start 326.84847 -285.109666)
		(end 326.838056 -285.10357)
		(width 0.0889)
		(layer "In11.Cu")
		(net "M_F_CPU0_SB_DQ<19>")
	)
	(segment
		(start 326.838056 -285.10357)
		(end 326.829674 -285.098744)
		(width 0.0889)
		(layer "In11.Cu")
		(net "M_F_CPU0_SB_DQ<19>")
	)
	(segment
		(start 328.344022 -285.10357)
		(end 328.333608 -285.109666)
		(width 0.0889)
		(layer "In11.Cu")
		(net "M_F_CPU0_SB_DQ<19>")
	)
	(segment
		(start 305.988974 -301.450248)
		(end 304.674524 -302.764698)
		(width 0.14478)
		(layer "In11.Cu")
		(net "M_F_CPU0_SB_DQ<19>")
	)
	(segment
		(start 326.180958 -285.17977)
		(end 325.867522 -285.17977)
		(width 0.0889)
		(layer "In11.Cu")
		(net "M_F_CPU0_SB_DQ<19>")
	)
	(segment
		(start 306.416456 -301.878238)
		(end 306.416456 -301.595028)
		(width 0.14478)
		(layer "In11.Cu")
		(net "M_F_CPU0_SB_DQ<19>")
	)
	(segment
		(start 267.165328 -302.629824)
		(end 267.00226 -302.466756)
		(width 0.14478)
		(layer "In11.Cu")
		(net "M_F_CPU0_SB_DQ<19>")
	)
	(segment
		(start 333.05242 -285.098744)
		(end 333.044038 -285.10357)
		(width 0.0889)
		(layer "In11.Cu")
		(net "M_F_CPU0_SB_DQ<19>")
	)
	(segment
		(start 323.861684 -285.83128)
		(end 323.737224 -285.83128)
		(width 0.14478)
		(layer "In11.Cu")
		(net "M_F_CPU0_SB_DQ<19>")
	)
	(segment
		(start 266.608814 -302.629824)
		(end 266.608814 -302.997108)
		(width 0.14478)
		(layer "In11.Cu")
		(net "M_F_CPU0_SB_DQ<19>")
	)
	(segment
		(start 286.043624 -302.300386)
		(end 283.158438 -302.300386)
		(width 0.14478)
		(layer "In11.Cu")
		(net "M_F_CPU0_SB_DQ<19>")
	)
	(segment
		(start 325.467472 -285.57982)
		(end 324.865238 -285.57982)
		(width 0.0889)
		(layer "In11.Cu")
		(net "M_F_CPU0_SB_DQ<19>")
	)
	(segment
		(start 306.967636 -301.595028)
		(end 306.967636 -301.878238)
		(width 0.14478)
		(layer "In11.Cu")
		(net "M_F_CPU0_SB_DQ<19>")
	)
	(segment
		(start 294.398954 -303.15027)
		(end 293.54907 -302.300386)
		(width 0.14478)
		(layer "In11.Cu")
		(net "M_F_CPU0_SB_DQ<19>")
	)
	(segment
		(start 274.74926 -303.15027)
		(end 267.31849 -303.15027)
		(width 0.14478)
		(layer "In11.Cu")
		(net "M_F_CPU0_SB_DQ<19>")
	)
	(segment
		(start 306.967636 -301.878238)
		(end 306.822856 -302.023018)
		(width 0.14478)
		(layer "In11.Cu")
		(net "M_F_CPU0_SB_DQ<19>")
	)
	(segment
		(start 328.718164 -285.10357)
		(end 328.709782 -285.098744)
		(width 0.0889)
		(layer "In11.Cu")
		(net "M_F_CPU0_SB_DQ<19>")
	)
	(segment
		(start 323.737224 -285.83128)
		(end 321.06108 -288.507424)
		(width 0.14478)
		(layer "In11.Cu")
		(net "M_F_CPU0_SB_DQ<19>")
	)
	(segment
		(start 290.691824 -302.300386)
		(end 289.84194 -303.15027)
		(width 0.14478)
		(layer "In11.Cu")
		(net "M_F_CPU0_SB_DQ<19>")
	)
	(segment
		(start 286.893508 -303.15027)
		(end 286.043624 -302.300386)
		(width 0.14478)
		(layer "In11.Cu")
		(net "M_F_CPU0_SB_DQ<19>")
	)
	(segment
		(start 320.251836 -288.507424)
		(end 307.783484 -300.975776)
		(width 0.14478)
		(layer "In11.Cu")
		(net "M_F_CPU0_SB_DQ<19>")
	)
	(segment
		(start 332.478126 -285.10357)
		(end 332.469744 -285.098744)
		(width 0.0889)
		(layer "In11.Cu")
		(net "M_F_CPU0_SB_DQ<19>")
	)
	(segment
		(start 306.416456 -301.595028)
		(end 306.271676 -301.450248)
		(width 0.14478)
		(layer "In11.Cu")
		(net "M_F_CPU0_SB_DQ<19>")
	)
	(segment
		(start 265.973306 -303.160176)
		(end 265.54811 -302.73498)
		(width 0.14478)
		(layer "In11.Cu")
		(net "M_F_CPU0_SB_DQ<19>")
	)
	(segment
		(start 334.171036 -285.42615)
		(end 334.017112 -285.16072)
		(width 0.0889)
		(layer "In11.Cu")
		(net "M_F_CPU0_SB_DQ<19>")
	)
	(segment
		(start 307.112416 -301.450248)
		(end 306.967636 -301.595028)
		(width 0.14478)
		(layer "In11.Cu")
		(net "M_F_CPU0_SB_DQ<19>")
	)
	(segment
		(start 325.867522 -285.17977)
		(end 325.467472 -285.57982)
		(width 0.0889)
		(layer "In11.Cu")
		(net "M_F_CPU0_SB_DQ<19>")
	)
	(segment
		(start 267.00226 -302.466756)
		(end 266.771882 -302.466756)
		(width 0.14478)
		(layer "In11.Cu")
		(net "M_F_CPU0_SB_DQ<19>")
	)
	(segment
		(start 334.017112 -285.16072)
		(end 333.9211 -285.13532)
		(width 0.0889)
		(layer "In11.Cu")
		(net "M_F_CPU0_SB_DQ<19>")
	)
	(segment
		(start 307.783484 -300.975776)
		(end 307.783484 -301.239428)
		(width 0.14478)
		(layer "In11.Cu")
		(net "M_F_CPU0_SB_DQ<19>")
	)
	(segment
		(start 306.271676 -301.450248)
		(end 305.988974 -301.450248)
		(width 0.14478)
		(layer "In11.Cu")
		(net "M_F_CPU0_SB_DQ<19>")
	)
	(segment
		(start 306.561236 -302.023018)
		(end 306.416456 -301.878238)
		(width 0.14478)
		(layer "In11.Cu")
		(net "M_F_CPU0_SB_DQ<19>")
	)
	(segment
		(start 283.158438 -302.300386)
		(end 282.308554 -303.15027)
		(width 0.14478)
		(layer "In11.Cu")
		(net "M_F_CPU0_SB_DQ<19>")
	)
	(segment
		(start 266.771882 -302.466756)
		(end 266.608814 -302.629824)
		(width 0.14478)
		(layer "In11.Cu")
		(net "M_F_CPU0_SB_DQ<19>")
	)
	(segment
		(start 298.18965 -302.300386)
		(end 297.339766 -303.15027)
		(width 0.14478)
		(layer "In11.Cu")
		(net "M_F_CPU0_SB_DQ<19>")
	)
	(segment
		(start 327.412096 -285.098744)
		(end 327.403714 -285.10357)
		(width 0.0889)
		(layer "In11.Cu")
		(net "M_F_CPU0_SB_DQ<19>")
	)
	(segment
		(start 275.599144 -302.300386)
		(end 274.74926 -303.15027)
		(width 0.14478)
		(layer "In11.Cu")
		(net "M_F_CPU0_SB_DQ<19>")
	)
	(segment
		(start 307.783484 -301.239428)
		(end 307.572664 -301.450248)
		(width 0.14478)
		(layer "In11.Cu")
		(net "M_F_CPU0_SB_DQ<19>")
	)
	(segment
		(start 321.06108 -288.507424)
		(end 320.251836 -288.507424)
		(width 0.14478)
		(layer "In11.Cu")
		(net "M_F_CPU0_SB_DQ<19>")
	)
	(segment
		(start 331.538072 -285.10357)
		(end 331.52969 -285.098744)
		(width 0.0889)
		(layer "In11.Cu")
		(net "M_F_CPU0_SB_DQ<19>")
	)
	(segment
		(start 266.608814 -302.997108)
		(end 266.445746 -303.160176)
		(width 0.14478)
		(layer "In11.Cu")
		(net "M_F_CPU0_SB_DQ<19>")
	)
	(segment
		(start 301.085504 -302.300386)
		(end 298.18965 -302.300386)
		(width 0.14478)
		(layer "In11.Cu")
		(net "M_F_CPU0_SB_DQ<19>")
	)
	(segment
		(start 266.445746 -303.160176)
		(end 265.973306 -303.160176)
		(width 0.14478)
		(layer "In11.Cu")
		(net "M_F_CPU0_SB_DQ<19>")
	)
	(segment
		(start 324.613778 -285.83128)
		(end 323.861684 -285.83128)
		(width 0.0889)
		(layer "In11.Cu")
		(net "M_F_CPU0_SB_DQ<19>")
	)
	(segment
		(start 329.292458 -285.098744)
		(end 329.284076 -285.10357)
		(width 0.0889)
		(layer "In11.Cu")
		(net "M_F_CPU0_SB_DQ<19>")
	)
	(segment
		(start 307.572664 -301.450248)
		(end 307.112416 -301.450248)
		(width 0.14478)
		(layer "In11.Cu")
		(net "M_F_CPU0_SB_DQ<19>")
	)
	(segment
		(start 278.47417 -302.300386)
		(end 275.599144 -302.300386)
		(width 0.14478)
		(layer "In11.Cu")
		(net "M_F_CPU0_SB_DQ<19>")
	)
	(segment
		(start 297.339766 -303.15027)
		(end 294.398954 -303.15027)
		(width 0.14478)
		(layer "In11.Cu")
		(net "M_F_CPU0_SB_DQ<19>")
	)
	(segment
		(start 301.549816 -302.764698)
		(end 301.085504 -302.300386)
		(width 0.14478)
		(layer "In11.Cu")
		(net "M_F_CPU0_SB_DQ<19>")
	)
	(segment
		(start 267.31849 -303.15027)
		(end 267.165328 -302.997108)
		(width 0.14478)
		(layer "In11.Cu")
		(net "M_F_CPU0_SB_DQ<19>")
	)
	(segment
		(start 279.324054 -303.15027)
		(end 278.47417 -302.300386)
		(width 0.14478)
		(layer "In11.Cu")
		(net "M_F_CPU0_SB_DQ<19>")
	)
	(arc
		(start 326.463914 -285.10357)
		(mid 326.327469 -285.160344)
		(end 326.180958 -285.17977)
		(width 0.0889)
		(layer "In11.Cu")
		(net "M_F_CPU0_SB_DQ<19>")
	)
	(arc
		(start 331.52969 -285.098744)
		(mid 331.346182 -285.05325)
		(end 331.16393 -285.10357)
		(width 0.0889)
		(layer "In11.Cu")
		(net "M_F_CPU0_SB_DQ<19>")
	)
	(arc
		(start 330.598018 -285.10357)
		(mid 330.411074 -285.053315)
		(end 330.22413 -285.10357)
		(width 0.0889)
		(layer "In11.Cu")
		(net "M_F_CPU0_SB_DQ<19>")
	)
	(arc
		(start 331.16393 -285.10357)
		(mid 330.880974 -285.179747)
		(end 330.598018 -285.10357)
		(width 0.0889)
		(layer "In11.Cu")
		(net "M_F_CPU0_SB_DQ<19>")
	)
	(arc
		(start 333.044038 -285.10357)
		(mid 332.761082 -285.179747)
		(end 332.478126 -285.10357)
		(width 0.0889)
		(layer "In11.Cu")
		(net "M_F_CPU0_SB_DQ<19>")
	)
	(arc
		(start 326.829674 -285.098744)
		(mid 326.646166 -285.05325)
		(end 326.463914 -285.10357)
		(width 0.0889)
		(layer "In11.Cu")
		(net "M_F_CPU0_SB_DQ<19>")
	)
	(arc
		(start 329.284076 -285.10357)
		(mid 329.00112 -285.179747)
		(end 328.718164 -285.10357)
		(width 0.0889)
		(layer "In11.Cu")
		(net "M_F_CPU0_SB_DQ<19>")
	)
	(arc
		(start 327.403714 -285.10357)
		(mid 327.126901 -285.179713)
		(end 326.84847 -285.109666)
		(width 0.0889)
		(layer "In11.Cu")
		(net "M_F_CPU0_SB_DQ<19>")
	)
	(arc
		(start 333.41818 -285.10357)
		(mid 333.235929 -285.05322)
		(end 333.05242 -285.098744)
		(width 0.0889)
		(layer "In11.Cu")
		(net "M_F_CPU0_SB_DQ<19>")
	)
	(arc
		(start 327.777856 -285.10357)
		(mid 327.595605 -285.05322)
		(end 327.412096 -285.098744)
		(width 0.0889)
		(layer "In11.Cu")
		(net "M_F_CPU0_SB_DQ<19>")
	)
	(arc
		(start 328.333608 -285.109666)
		(mid 328.054922 -285.179886)
		(end 327.777856 -285.10357)
		(width 0.0889)
		(layer "In11.Cu")
		(net "M_F_CPU0_SB_DQ<19>")
	)
	(arc
		(start 333.9211 -285.13532)
		(mid 333.665892 -285.178797)
		(end 333.41818 -285.10357)
		(width 0.0889)
		(layer "In11.Cu")
		(net "M_F_CPU0_SB_DQ<19>")
	)
	(arc
		(start 330.22413 -285.10357)
		(mid 329.941174 -285.179747)
		(end 329.658218 -285.10357)
		(width 0.0889)
		(layer "In11.Cu")
		(net "M_F_CPU0_SB_DQ<19>")
	)
	(arc
		(start 332.103984 -285.10357)
		(mid 331.821028 -285.179747)
		(end 331.538072 -285.10357)
		(width 0.0889)
		(layer "In11.Cu")
		(net "M_F_CPU0_SB_DQ<19>")
	)
	(arc
		(start 329.658218 -285.10357)
		(mid 329.475967 -285.05322)
		(end 329.292458 -285.098744)
		(width 0.0889)
		(layer "In11.Cu")
		(net "M_F_CPU0_SB_DQ<19>")
	)
	(arc
		(start 328.709782 -285.098744)
		(mid 328.526274 -285.05325)
		(end 328.344022 -285.10357)
		(width 0.0889)
		(layer "In11.Cu")
		(net "M_F_CPU0_SB_DQ<19>")
	)
	(arc
		(start 332.469744 -285.098744)
		(mid 332.286236 -285.05325)
		(end 332.103984 -285.10357)
		(width 0.0889)
		(layer "In11.Cu")
		(net "M_F_CPU0_SB_DQ<19>")
	)
	(segment
		(start 333.227934 -284.350206)
		(end 332.761082 -284.616144)
		(width 0.10668)
		(layer "F.Cu")
		(net "M_F_CPU0_SB_DQ<18>")
	)
	(segment
		(start 267.605764 -300.918372)
		(end 267.34389 -300.918372)
		(width 0.14478)
		(layer "In11.Cu")
		(net "M_F_CPU0_SB_DQ<18>")
	)
	(segment
		(start 267.19911 -301.857156)
		(end 267.05433 -302.001936)
		(width 0.14478)
		(layer "In11.Cu")
		(net "M_F_CPU0_SB_DQ<18>")
	)
	(segment
		(start 268.708632 -300.918372)
		(end 268.446758 -300.918372)
		(width 0.14478)
		(layer "In11.Cu")
		(net "M_F_CPU0_SB_DQ<18>")
	)
	(segment
		(start 290.464748 -300.610016)
		(end 289.61461 -301.460154)
		(width 0.14478)
		(layer "In11.Cu")
		(net "M_F_CPU0_SB_DQ<18>")
	)
	(segment
		(start 266.647676 -301.857156)
		(end 266.647676 -301.604934)
		(width 0.14478)
		(layer "In11.Cu")
		(net "M_F_CPU0_SB_DQ<18>")
	)
	(segment
		(start 267.05433 -302.001936)
		(end 266.792456 -302.001936)
		(width 0.14478)
		(layer "In11.Cu")
		(net "M_F_CPU0_SB_DQ<18>")
	)
	(segment
		(start 278.914098 -301.460154)
		(end 278.06396 -300.610016)
		(width 0.14478)
		(layer "In11.Cu")
		(net "M_F_CPU0_SB_DQ<18>")
	)
	(segment
		(start 267.750544 -301.857156)
		(end 267.750544 -301.063152)
		(width 0.14478)
		(layer "In11.Cu")
		(net "M_F_CPU0_SB_DQ<18>")
	)
	(segment
		(start 268.446758 -300.918372)
		(end 268.301978 -301.063152)
		(width 0.14478)
		(layer "In11.Cu")
		(net "M_F_CPU0_SB_DQ<18>")
	)
	(segment
		(start 294.941498 -301.460154)
		(end 294.09136 -300.610016)
		(width 0.14478)
		(layer "In11.Cu")
		(net "M_F_CPU0_SB_DQ<18>")
	)
	(segment
		(start 330.702412 -284.288738)
		(end 330.69403 -284.293564)
		(width 0.0889)
		(layer "In11.Cu")
		(net "M_F_CPU0_SB_DQ<18>")
	)
	(segment
		(start 268.301978 -301.063152)
		(end 268.301978 -301.857156)
		(width 0.14478)
		(layer "In11.Cu")
		(net "M_F_CPU0_SB_DQ<18>")
	)
	(segment
		(start 323.374512 -284.92196)
		(end 320.688208 -287.608264)
		(width 0.14478)
		(layer "In11.Cu")
		(net "M_F_CPU0_SB_DQ<18>")
	)
	(segment
		(start 283.352748 -300.610016)
		(end 282.50261 -301.460154)
		(width 0.14478)
		(layer "In11.Cu")
		(net "M_F_CPU0_SB_DQ<18>")
	)
	(segment
		(start 267.750544 -301.063152)
		(end 267.605764 -300.918372)
		(width 0.14478)
		(layer "In11.Cu")
		(net "M_F_CPU0_SB_DQ<18>")
	)
	(segment
		(start 289.61461 -301.460154)
		(end 286.737298 -301.460154)
		(width 0.14478)
		(layer "In11.Cu")
		(net "M_F_CPU0_SB_DQ<18>")
	)
	(segment
		(start 327.874376 -284.293818)
		(end 327.862438 -284.300676)
		(width 0.0889)
		(layer "In11.Cu")
		(net "M_F_CPU0_SB_DQ<18>")
	)
	(segment
		(start 331.642466 -284.288738)
		(end 331.634084 -284.293564)
		(width 0.0889)
		(layer "In11.Cu")
		(net "M_F_CPU0_SB_DQ<18>")
	)
	(segment
		(start 286.737298 -301.460154)
		(end 285.88716 -300.610016)
		(width 0.14478)
		(layer "In11.Cu")
		(net "M_F_CPU0_SB_DQ<18>")
	)
	(segment
		(start 266.792456 -302.001936)
		(end 266.647676 -301.857156)
		(width 0.14478)
		(layer "In11.Cu")
		(net "M_F_CPU0_SB_DQ<18>")
	)
	(segment
		(start 267.895324 -302.001936)
		(end 267.750544 -301.857156)
		(width 0.14478)
		(layer "In11.Cu")
		(net "M_F_CPU0_SB_DQ<18>")
	)
	(segment
		(start 306.416456 -299.75048)
		(end 304.706782 -301.460154)
		(width 0.14478)
		(layer "In11.Cu")
		(net "M_F_CPU0_SB_DQ<18>")
	)
	(segment
		(start 294.09136 -300.610016)
		(end 290.464748 -300.610016)
		(width 0.14478)
		(layer "In11.Cu")
		(net "M_F_CPU0_SB_DQ<18>")
	)
	(segment
		(start 325.184008 -284.92196)
		(end 323.821044 -284.92196)
		(width 0.0889)
		(layer "In11.Cu")
		(net "M_F_CPU0_SB_DQ<18>")
	)
	(segment
		(start 282.50261 -301.460154)
		(end 278.914098 -301.460154)
		(width 0.14478)
		(layer "In11.Cu")
		(net "M_F_CPU0_SB_DQ<18>")
	)
	(segment
		(start 266.647676 -301.604934)
		(end 266.502896 -301.460154)
		(width 0.14478)
		(layer "In11.Cu")
		(net "M_F_CPU0_SB_DQ<18>")
	)
	(segment
		(start 332.607158 -284.350714)
		(end 332.511146 -284.325314)
		(width 0.0889)
		(layer "In11.Cu")
		(net "M_F_CPU0_SB_DQ<18>")
	)
	(segment
		(start 320.688208 -287.608264)
		(end 319.87871 -287.608264)
		(width 0.14478)
		(layer "In11.Cu")
		(net "M_F_CPU0_SB_DQ<18>")
	)
	(segment
		(start 275.783548 -300.610016)
		(end 274.93341 -301.460154)
		(width 0.14478)
		(layer "In11.Cu")
		(net "M_F_CPU0_SB_DQ<18>")
	)
	(segment
		(start 266.502896 -301.460154)
		(end 265.973306 -301.460154)
		(width 0.14478)
		(layer "In11.Cu")
		(net "M_F_CPU0_SB_DQ<18>")
	)
	(segment
		(start 274.93341 -301.460154)
		(end 268.998192 -301.460154)
		(width 0.14478)
		(layer "In11.Cu")
		(net "M_F_CPU0_SB_DQ<18>")
	)
	(segment
		(start 327.33107 -284.305756)
		(end 327.304654 -284.29204)
		(width 0.0889)
		(layer "In11.Cu")
		(net "M_F_CPU0_SB_DQ<18>")
	)
	(segment
		(start 327.890632 -284.28442)
		(end 327.874376 -284.293818)
		(width 0.0889)
		(layer "In11.Cu")
		(net "M_F_CPU0_SB_DQ<18>")
	)
	(segment
		(start 298.224956 -300.610016)
		(end 297.374818 -301.460154)
		(width 0.14478)
		(layer "In11.Cu")
		(net "M_F_CPU0_SB_DQ<18>")
	)
	(segment
		(start 268.301978 -301.857156)
		(end 268.157198 -302.001936)
		(width 0.14478)
		(layer "In11.Cu")
		(net "M_F_CPU0_SB_DQ<18>")
	)
	(segment
		(start 325.486014 -284.619954)
		(end 325.184008 -284.92196)
		(width 0.0889)
		(layer "In11.Cu")
		(net "M_F_CPU0_SB_DQ<18>")
	)
	(segment
		(start 307.736494 -299.75048)
		(end 306.416456 -299.75048)
		(width 0.14478)
		(layer "In11.Cu")
		(net "M_F_CPU0_SB_DQ<18>")
	)
	(segment
		(start 323.821044 -284.92196)
		(end 323.374512 -284.92196)
		(width 0.14478)
		(layer "In11.Cu")
		(net "M_F_CPU0_SB_DQ<18>")
	)
	(segment
		(start 327.08469 -284.296866)
		(end 326.775318 -284.476698)
		(width 0.0889)
		(layer "In11.Cu")
		(net "M_F_CPU0_SB_DQ<18>")
	)
	(segment
		(start 301.35576 -300.610016)
		(end 298.224956 -300.610016)
		(width 0.14478)
		(layer "In11.Cu")
		(net "M_F_CPU0_SB_DQ<18>")
	)
	(segment
		(start 265.973306 -301.460154)
		(end 265.54811 -301.034958)
		(width 0.14478)
		(layer "In11.Cu")
		(net "M_F_CPU0_SB_DQ<18>")
	)
	(segment
		(start 268.853412 -301.063152)
		(end 268.708632 -300.918372)
		(width 0.14478)
		(layer "In11.Cu")
		(net "M_F_CPU0_SB_DQ<18>")
	)
	(segment
		(start 332.761082 -284.616144)
		(end 332.607158 -284.350714)
		(width 0.0889)
		(layer "In11.Cu")
		(net "M_F_CPU0_SB_DQ<18>")
	)
	(segment
		(start 302.205898 -301.460154)
		(end 301.35576 -300.610016)
		(width 0.14478)
		(layer "In11.Cu")
		(net "M_F_CPU0_SB_DQ<18>")
	)
	(segment
		(start 330.128118 -284.293564)
		(end 330.119736 -284.288738)
		(width 0.0889)
		(layer "In11.Cu")
		(net "M_F_CPU0_SB_DQ<18>")
	)
	(segment
		(start 304.706782 -301.460154)
		(end 302.205898 -301.460154)
		(width 0.14478)
		(layer "In11.Cu")
		(net "M_F_CPU0_SB_DQ<18>")
	)
	(segment
		(start 267.19911 -301.063152)
		(end 267.19911 -301.857156)
		(width 0.14478)
		(layer "In11.Cu")
		(net "M_F_CPU0_SB_DQ<18>")
	)
	(segment
		(start 278.06396 -300.610016)
		(end 275.783548 -300.610016)
		(width 0.14478)
		(layer "In11.Cu")
		(net "M_F_CPU0_SB_DQ<18>")
	)
	(segment
		(start 268.853412 -301.315374)
		(end 268.853412 -301.063152)
		(width 0.14478)
		(layer "In11.Cu")
		(net "M_F_CPU0_SB_DQ<18>")
	)
	(segment
		(start 267.34389 -300.918372)
		(end 267.19911 -301.063152)
		(width 0.14478)
		(layer "In11.Cu")
		(net "M_F_CPU0_SB_DQ<18>")
	)
	(segment
		(start 297.374818 -301.460154)
		(end 294.941498 -301.460154)
		(width 0.14478)
		(layer "In11.Cu")
		(net "M_F_CPU0_SB_DQ<18>")
	)
	(segment
		(start 326.507856 -284.548834)
		(end 325.657718 -284.548834)
		(width 0.0889)
		(layer "In11.Cu")
		(net "M_F_CPU0_SB_DQ<18>")
	)
	(segment
		(start 268.157198 -302.001936)
		(end 267.895324 -302.001936)
		(width 0.14478)
		(layer "In11.Cu")
		(net "M_F_CPU0_SB_DQ<18>")
	)
	(segment
		(start 319.87871 -287.608264)
		(end 307.736494 -299.75048)
		(width 0.14478)
		(layer "In11.Cu")
		(net "M_F_CPU0_SB_DQ<18>")
	)
	(segment
		(start 268.998192 -301.460154)
		(end 268.853412 -301.315374)
		(width 0.14478)
		(layer "In11.Cu")
		(net "M_F_CPU0_SB_DQ<18>")
	)
	(segment
		(start 285.88716 -300.610016)
		(end 283.352748 -300.610016)
		(width 0.14478)
		(layer "In11.Cu")
		(net "M_F_CPU0_SB_DQ<18>")
	)
	(arc
		(start 329.753976 -284.293564)
		(mid 329.47102 -284.369741)
		(end 329.188064 -284.293564)
		(width 0.0889)
		(layer "In11.Cu")
		(net "M_F_CPU0_SB_DQ<18>")
	)
	(arc
		(start 326.775318 -284.476698)
		(mid 326.646366 -284.530487)
		(end 326.507856 -284.548834)
		(width 0.0889)
		(layer "In11.Cu")
		(net "M_F_CPU0_SB_DQ<18>")
	)
	(arc
		(start 328.814176 -284.293564)
		(mid 328.53122 -284.369741)
		(end 328.248264 -284.293564)
		(width 0.0889)
		(layer "In11.Cu")
		(net "M_F_CPU0_SB_DQ<18>")
	)
	(arc
		(start 327.862438 -284.300676)
		(mid 327.597382 -284.369799)
		(end 327.33107 -284.305756)
		(width 0.0889)
		(layer "In11.Cu")
		(net "M_F_CPU0_SB_DQ<18>")
	)
	(arc
		(start 331.068172 -284.293564)
		(mid 330.885921 -284.243214)
		(end 330.702412 -284.288738)
		(width 0.0889)
		(layer "In11.Cu")
		(net "M_F_CPU0_SB_DQ<18>")
	)
	(arc
		(start 332.511146 -284.325314)
		(mid 332.255938 -284.368791)
		(end 332.008226 -284.293564)
		(width 0.0889)
		(layer "In11.Cu")
		(net "M_F_CPU0_SB_DQ<18>")
	)
	(arc
		(start 328.248264 -284.293564)
		(mid 328.070614 -284.243304)
		(end 327.890632 -284.28442)
		(width 0.0889)
		(layer "In11.Cu")
		(net "M_F_CPU0_SB_DQ<18>")
	)
	(arc
		(start 325.657718 -284.548834)
		(mid 325.564793 -284.567318)
		(end 325.486014 -284.619954)
		(width 0.0889)
		(layer "In11.Cu")
		(net "M_F_CPU0_SB_DQ<18>")
	)
	(arc
		(start 330.69403 -284.293564)
		(mid 330.411074 -284.369741)
		(end 330.128118 -284.293564)
		(width 0.0889)
		(layer "In11.Cu")
		(net "M_F_CPU0_SB_DQ<18>")
	)
	(arc
		(start 331.634084 -284.293564)
		(mid 331.351128 -284.369741)
		(end 331.068172 -284.293564)
		(width 0.0889)
		(layer "In11.Cu")
		(net "M_F_CPU0_SB_DQ<18>")
	)
	(arc
		(start 327.304654 -284.29204)
		(mid 327.194043 -284.266119)
		(end 327.08469 -284.296866)
		(width 0.0889)
		(layer "In11.Cu")
		(net "M_F_CPU0_SB_DQ<18>")
	)
	(arc
		(start 329.188064 -284.293564)
		(mid 329.00112 -284.243309)
		(end 328.814176 -284.293564)
		(width 0.0889)
		(layer "In11.Cu")
		(net "M_F_CPU0_SB_DQ<18>")
	)
	(arc
		(start 330.119736 -284.288738)
		(mid 329.936228 -284.243244)
		(end 329.753976 -284.293564)
		(width 0.0889)
		(layer "In11.Cu")
		(net "M_F_CPU0_SB_DQ<18>")
	)
	(arc
		(start 332.008226 -284.293564)
		(mid 331.825975 -284.243214)
		(end 331.642466 -284.288738)
		(width 0.0889)
		(layer "In11.Cu")
		(net "M_F_CPU0_SB_DQ<18>")
	)
	(segment
		(start 334.167988 -284.350206)
		(end 333.701136 -284.616144)
		(width 0.10668)
		(layer "F.Cu")
		(net "M_F_CPU0_SB_DQ<17>")
	)
	(segment
		(start 293.673784 -301.315374)
		(end 293.673784 -301.205392)
		(width 0.14478)
		(layer "In11.Cu")
		(net "M_F_CPU0_SB_DQ<17>")
	)
	(segment
		(start 270.45412 -302.691038)
		(end 269.648178 -301.885096)
		(width 0.14478)
		(layer "In11.Cu")
		(net "M_F_CPU0_SB_DQ<17>")
	)
	(segment
		(start 300.677072 -301.060612)
		(end 300.532292 -301.205392)
		(width 0.14478)
		(layer "In11.Cu")
		(net "M_F_CPU0_SB_DQ<17>")
	)
	(segment
		(start 293.818564 -301.460154)
		(end 293.673784 -301.315374)
		(width 0.14478)
		(layer "In11.Cu")
		(net "M_F_CPU0_SB_DQ<17>")
	)
	(segment
		(start 298.419774 -301.4599)
		(end 298.0182 -301.4599)
		(width 0.14478)
		(layer "In11.Cu")
		(net "M_F_CPU0_SB_DQ<17>")
	)
	(segment
		(start 300.532292 -301.31512)
		(end 300.387512 -301.4599)
		(width 0.14478)
		(layer "In11.Cu")
		(net "M_F_CPU0_SB_DQ<17>")
	)
	(segment
		(start 299.115988 -301.205392)
		(end 298.971208 -301.060612)
		(width 0.14478)
		(layer "In11.Cu")
		(net "M_F_CPU0_SB_DQ<17>")
	)
	(segment
		(start 274.540472 -302.691292)
		(end 274.285456 -302.691292)
		(width 0.14478)
		(layer "In11.Cu")
		(net "M_F_CPU0_SB_DQ<17>")
	)
	(segment
		(start 294.154098 -301.460154)
		(end 293.818564 -301.460154)
		(width 0.14478)
		(layer "In11.Cu")
		(net "M_F_CPU0_SB_DQ<17>")
	)
	(segment
		(start 292.97757 -301.460154)
		(end 291.631878 -301.460154)
		(width 0.14478)
		(layer "In11.Cu")
		(net "M_F_CPU0_SB_DQ<17>")
	)
	(segment
		(start 293.12235 -301.205392)
		(end 293.12235 -301.315374)
		(width 0.14478)
		(layer "In11.Cu")
		(net "M_F_CPU0_SB_DQ<17>")
	)
	(segment
		(start 285.240984 -301.15891)
		(end 284.939994 -301.4599)
		(width 0.14478)
		(layer "In11.Cu")
		(net "M_F_CPU0_SB_DQ<17>")
	)
	(segment
		(start 284.939994 -301.4599)
		(end 284.030674 -301.4599)
		(width 0.14478)
		(layer "In11.Cu")
		(net "M_F_CPU0_SB_DQ<17>")
	)
	(segment
		(start 295.003982 -302.310038)
		(end 294.154098 -301.460154)
		(width 0.14478)
		(layer "In11.Cu")
		(net "M_F_CPU0_SB_DQ<17>")
	)
	(segment
		(start 289.577526 -302.310038)
		(end 286.71647 -302.310038)
		(width 0.14478)
		(layer "In11.Cu")
		(net "M_F_CPU0_SB_DQ<17>")
	)
	(segment
		(start 325.383144 -285.37662)
		(end 323.942964 -285.37662)
		(width 0.0889)
		(layer "In11.Cu")
		(net "M_F_CPU0_SB_DQ<17>")
	)
	(segment
		(start 297.168062 -302.310038)
		(end 295.003982 -302.310038)
		(width 0.14478)
		(layer "In11.Cu")
		(net "M_F_CPU0_SB_DQ<17>")
	)
	(segment
		(start 285.565342 -301.15891)
		(end 285.240984 -301.15891)
		(width 0.14478)
		(layer "In11.Cu")
		(net "M_F_CPU0_SB_DQ<17>")
	)
	(segment
		(start 274.134834 -302.54067)
		(end 274.134834 -302.105314)
		(width 0.14478)
		(layer "In11.Cu")
		(net "M_F_CPU0_SB_DQ<17>")
	)
	(segment
		(start 290.42741 -301.460154)
		(end 289.577526 -302.310038)
		(width 0.14478)
		(layer "In11.Cu")
		(net "M_F_CPU0_SB_DQ<17>")
	)
	(segment
		(start 283.474414 -301.14875)
		(end 282.001214 -302.62195)
		(width 0.14478)
		(layer "In11.Cu")
		(net "M_F_CPU0_SB_DQ<17>")
	)
	(segment
		(start 273.97202 -301.9425)
		(end 273.741388 -301.9425)
		(width 0.14478)
		(layer "In11.Cu")
		(net "M_F_CPU0_SB_DQ<17>")
	)
	(segment
		(start 298.971208 -301.060612)
		(end 298.709334 -301.060612)
		(width 0.14478)
		(layer "In11.Cu")
		(net "M_F_CPU0_SB_DQ<17>")
	)
	(segment
		(start 290.790884 -301.460154)
		(end 290.42741 -301.460154)
		(width 0.14478)
		(layer "In11.Cu")
		(net "M_F_CPU0_SB_DQ<17>")
	)
	(segment
		(start 281.444954 -302.310038)
		(end 279.854914 -302.310038)
		(width 0.14478)
		(layer "In11.Cu")
		(net "M_F_CPU0_SB_DQ<17>")
	)
	(segment
		(start 293.529004 -301.060612)
		(end 293.26713 -301.060612)
		(width 0.14478)
		(layer "In11.Cu")
		(net "M_F_CPU0_SB_DQ<17>")
	)
	(segment
		(start 299.260768 -301.4599)
		(end 299.115988 -301.31512)
		(width 0.14478)
		(layer "In11.Cu")
		(net "M_F_CPU0_SB_DQ<17>")
	)
	(segment
		(start 325.770494 -284.98927)
		(end 325.383144 -285.37662)
		(width 0.0889)
		(layer "In11.Cu")
		(net "M_F_CPU0_SB_DQ<17>")
	)
	(segment
		(start 276.083014 -301.14875)
		(end 274.540472 -302.691292)
		(width 0.14478)
		(layer "In11.Cu")
		(net "M_F_CPU0_SB_DQ<17>")
	)
	(segment
		(start 271.253712 -301.922434)
		(end 271.02308 -301.922434)
		(width 0.14478)
		(layer "In11.Cu")
		(net "M_F_CPU0_SB_DQ<17>")
	)
	(segment
		(start 327.318116 -284.932628)
		(end 327.307702 -284.938724)
		(width 0.0889)
		(layer "In11.Cu")
		(net "M_F_CPU0_SB_DQ<17>")
	)
	(segment
		(start 320.874644 -288.057844)
		(end 320.0654 -288.057844)
		(width 0.14478)
		(layer "In11.Cu")
		(net "M_F_CPU0_SB_DQ<17>")
	)
	(segment
		(start 301.562516 -301.4599)
		(end 301.228506 -301.4599)
		(width 0.14478)
		(layer "In11.Cu")
		(net "M_F_CPU0_SB_DQ<17>")
	)
	(segment
		(start 284.030674 -301.4599)
		(end 283.719524 -301.14875)
		(width 0.14478)
		(layer "In11.Cu")
		(net "M_F_CPU0_SB_DQ<17>")
	)
	(segment
		(start 272.1356 -301.922434)
		(end 271.972786 -302.085248)
		(width 0.14478)
		(layer "In11.Cu")
		(net "M_F_CPU0_SB_DQ<17>")
	)
	(segment
		(start 300.938946 -301.060612)
		(end 300.677072 -301.060612)
		(width 0.14478)
		(layer "In11.Cu")
		(net "M_F_CPU0_SB_DQ<17>")
	)
	(segment
		(start 271.416526 -302.085248)
		(end 271.253712 -301.922434)
		(width 0.14478)
		(layer "In11.Cu")
		(net "M_F_CPU0_SB_DQ<17>")
	)
	(segment
		(start 330.702412 -284.94355)
		(end 330.69403 -284.938724)
		(width 0.0889)
		(layer "In11.Cu")
		(net "M_F_CPU0_SB_DQ<17>")
	)
	(segment
		(start 271.416526 -302.525684)
		(end 271.416526 -302.085248)
		(width 0.14478)
		(layer "In11.Cu")
		(net "M_F_CPU0_SB_DQ<17>")
	)
	(segment
		(start 331.642466 -284.94355)
		(end 331.634084 -284.938724)
		(width 0.0889)
		(layer "In11.Cu")
		(net "M_F_CPU0_SB_DQ<17>")
	)
	(segment
		(start 291.631878 -301.460154)
		(end 291.487098 -301.315374)
		(width 0.14478)
		(layer "In11.Cu")
		(net "M_F_CPU0_SB_DQ<17>")
	)
	(segment
		(start 272.753836 -302.310038)
		(end 272.366232 -301.922434)
		(width 0.14478)
		(layer "In11.Cu")
		(net "M_F_CPU0_SB_DQ<17>")
	)
	(segment
		(start 293.12235 -301.315374)
		(end 292.97757 -301.460154)
		(width 0.14478)
		(layer "In11.Cu")
		(net "M_F_CPU0_SB_DQ<17>")
	)
	(segment
		(start 290.935664 -301.315374)
		(end 290.790884 -301.460154)
		(width 0.14478)
		(layer "In11.Cu")
		(net "M_F_CPU0_SB_DQ<17>")
	)
	(segment
		(start 306.602892 -300.20006)
		(end 304.492914 -302.310038)
		(width 0.14478)
		(layer "In11.Cu")
		(net "M_F_CPU0_SB_DQ<17>")
	)
	(segment
		(start 323.942964 -285.37662)
		(end 323.555868 -285.37662)
		(width 0.14478)
		(layer "In11.Cu")
		(net "M_F_CPU0_SB_DQ<17>")
	)
	(segment
		(start 276.554184 -301.14875)
		(end 276.083014 -301.14875)
		(width 0.14478)
		(layer "In11.Cu")
		(net "M_F_CPU0_SB_DQ<17>")
	)
	(segment
		(start 301.228506 -301.4599)
		(end 301.083726 -301.31512)
		(width 0.14478)
		(layer "In11.Cu")
		(net "M_F_CPU0_SB_DQ<17>")
	)
	(segment
		(start 301.083726 -301.31512)
		(end 301.083726 -301.205392)
		(width 0.14478)
		(layer "In11.Cu")
		(net "M_F_CPU0_SB_DQ<17>")
	)
	(segment
		(start 291.487098 -301.205392)
		(end 291.342318 -301.060612)
		(width 0.14478)
		(layer "In11.Cu")
		(net "M_F_CPU0_SB_DQ<17>")
	)
	(segment
		(start 282.001214 -302.62195)
		(end 281.756866 -302.62195)
		(width 0.14478)
		(layer "In11.Cu")
		(net "M_F_CPU0_SB_DQ<17>")
	)
	(segment
		(start 279.3873 -302.57242)
		(end 278.27478 -301.4599)
		(width 0.14478)
		(layer "In11.Cu")
		(net "M_F_CPU0_SB_DQ<17>")
	)
	(segment
		(start 271.02308 -301.922434)
		(end 270.860266 -302.085248)
		(width 0.14478)
		(layer "In11.Cu")
		(net "M_F_CPU0_SB_DQ<17>")
	)
	(segment
		(start 298.564554 -301.205392)
		(end 298.564554 -301.31512)
		(width 0.14478)
		(layer "In11.Cu")
		(net "M_F_CPU0_SB_DQ<17>")
	)
	(segment
		(start 271.972786 -302.530764)
		(end 271.812512 -302.691038)
		(width 0.14478)
		(layer "In11.Cu")
		(net "M_F_CPU0_SB_DQ<17>")
	)
	(segment
		(start 276.865334 -301.4599)
		(end 276.554184 -301.14875)
		(width 0.14478)
		(layer "In11.Cu")
		(net "M_F_CPU0_SB_DQ<17>")
	)
	(segment
		(start 291.342318 -301.060612)
		(end 291.080444 -301.060612)
		(width 0.14478)
		(layer "In11.Cu")
		(net "M_F_CPU0_SB_DQ<17>")
	)
	(segment
		(start 290.935664 -301.205392)
		(end 290.935664 -301.315374)
		(width 0.14478)
		(layer "In11.Cu")
		(net "M_F_CPU0_SB_DQ<17>")
	)
	(segment
		(start 270.860266 -302.530764)
		(end 270.699992 -302.691038)
		(width 0.14478)
		(layer "In11.Cu")
		(net "M_F_CPU0_SB_DQ<17>")
	)
	(segment
		(start 330.128118 -284.938724)
		(end 330.119736 -284.94355)
		(width 0.0889)
		(layer "In11.Cu")
		(net "M_F_CPU0_SB_DQ<17>")
	)
	(segment
		(start 271.58188 -302.691038)
		(end 271.416526 -302.525684)
		(width 0.14478)
		(layer "In11.Cu")
		(net "M_F_CPU0_SB_DQ<17>")
	)
	(segment
		(start 279.854914 -302.310038)
		(end 279.592532 -302.57242)
		(width 0.14478)
		(layer "In11.Cu")
		(net "M_F_CPU0_SB_DQ<17>")
	)
	(segment
		(start 283.719524 -301.14875)
		(end 283.474414 -301.14875)
		(width 0.14478)
		(layer "In11.Cu")
		(net "M_F_CPU0_SB_DQ<17>")
	)
	(segment
		(start 326.933814 -284.938724)
		(end 326.919082 -284.930088)
		(width 0.0889)
		(layer "In11.Cu")
		(net "M_F_CPU0_SB_DQ<17>")
	)
	(segment
		(start 271.972786 -302.085248)
		(end 271.972786 -302.530764)
		(width 0.14478)
		(layer "In11.Cu")
		(net "M_F_CPU0_SB_DQ<17>")
	)
	(segment
		(start 272.366232 -301.922434)
		(end 272.1356 -301.922434)
		(width 0.14478)
		(layer "In11.Cu")
		(net "M_F_CPU0_SB_DQ<17>")
	)
	(segment
		(start 307.923184 -300.20006)
		(end 306.602892 -300.20006)
		(width 0.14478)
		(layer "In11.Cu")
		(net "M_F_CPU0_SB_DQ<17>")
	)
	(segment
		(start 323.555868 -285.37662)
		(end 320.874644 -288.057844)
		(width 0.14478)
		(layer "In11.Cu")
		(net "M_F_CPU0_SB_DQ<17>")
	)
	(segment
		(start 279.592532 -302.57242)
		(end 279.3873 -302.57242)
		(width 0.14478)
		(layer "In11.Cu")
		(net "M_F_CPU0_SB_DQ<17>")
	)
	(segment
		(start 298.709334 -301.060612)
		(end 298.564554 -301.205392)
		(width 0.14478)
		(layer "In11.Cu")
		(net "M_F_CPU0_SB_DQ<17>")
	)
	(segment
		(start 300.532292 -301.205392)
		(end 300.532292 -301.31512)
		(width 0.14478)
		(layer "In11.Cu")
		(net "M_F_CPU0_SB_DQ<17>")
	)
	(segment
		(start 298.564554 -301.31512)
		(end 298.419774 -301.4599)
		(width 0.14478)
		(layer "In11.Cu")
		(net "M_F_CPU0_SB_DQ<17>")
	)
	(segment
		(start 300.387512 -301.4599)
		(end 299.260768 -301.4599)
		(width 0.14478)
		(layer "In11.Cu")
		(net "M_F_CPU0_SB_DQ<17>")
	)
	(segment
		(start 320.0654 -288.057844)
		(end 307.923184 -300.20006)
		(width 0.14478)
		(layer "In11.Cu")
		(net "M_F_CPU0_SB_DQ<17>")
	)
	(segment
		(start 271.812512 -302.691038)
		(end 271.58188 -302.691038)
		(width 0.14478)
		(layer "In11.Cu")
		(net "M_F_CPU0_SB_DQ<17>")
	)
	(segment
		(start 304.492914 -302.310038)
		(end 302.412654 -302.310038)
		(width 0.14478)
		(layer "In11.Cu")
		(net "M_F_CPU0_SB_DQ<17>")
	)
	(segment
		(start 273.741388 -301.9425)
		(end 273.37385 -302.310038)
		(width 0.14478)
		(layer "In11.Cu")
		(net "M_F_CPU0_SB_DQ<17>")
	)
	(segment
		(start 298.0182 -301.4599)
		(end 297.168062 -302.310038)
		(width 0.14478)
		(layer "In11.Cu")
		(net "M_F_CPU0_SB_DQ<17>")
	)
	(segment
		(start 333.85506 -284.881574)
		(end 333.832708 -284.964886)
		(width 0.0889)
		(layer "In11.Cu")
		(net "M_F_CPU0_SB_DQ<17>")
	)
	(segment
		(start 301.083726 -301.205392)
		(end 300.938946 -301.060612)
		(width 0.14478)
		(layer "In11.Cu")
		(net "M_F_CPU0_SB_DQ<17>")
	)
	(segment
		(start 302.412654 -302.310038)
		(end 301.562516 -301.4599)
		(width 0.14478)
		(layer "In11.Cu")
		(net "M_F_CPU0_SB_DQ<17>")
	)
	(segment
		(start 274.134834 -302.105314)
		(end 273.97202 -301.9425)
		(width 0.14478)
		(layer "In11.Cu")
		(net "M_F_CPU0_SB_DQ<17>")
	)
	(segment
		(start 274.285456 -302.691292)
		(end 274.134834 -302.54067)
		(width 0.14478)
		(layer "In11.Cu")
		(net "M_F_CPU0_SB_DQ<17>")
	)
	(segment
		(start 299.115988 -301.31512)
		(end 299.115988 -301.205392)
		(width 0.14478)
		(layer "In11.Cu")
		(net "M_F_CPU0_SB_DQ<17>")
	)
	(segment
		(start 293.26713 -301.060612)
		(end 293.12235 -301.205392)
		(width 0.14478)
		(layer "In11.Cu")
		(net "M_F_CPU0_SB_DQ<17>")
	)
	(segment
		(start 270.860266 -302.085248)
		(end 270.860266 -302.530764)
		(width 0.14478)
		(layer "In11.Cu")
		(net "M_F_CPU0_SB_DQ<17>")
	)
	(segment
		(start 293.673784 -301.205392)
		(end 293.529004 -301.060612)
		(width 0.14478)
		(layer "In11.Cu")
		(net "M_F_CPU0_SB_DQ<17>")
	)
	(segment
		(start 291.080444 -301.060612)
		(end 290.935664 -301.205392)
		(width 0.14478)
		(layer "In11.Cu")
		(net "M_F_CPU0_SB_DQ<17>")
	)
	(segment
		(start 333.701136 -284.616144)
		(end 333.85506 -284.881574)
		(width 0.0889)
		(layer "In11.Cu")
		(net "M_F_CPU0_SB_DQ<17>")
	)
	(segment
		(start 281.756866 -302.62195)
		(end 281.444954 -302.310038)
		(width 0.14478)
		(layer "In11.Cu")
		(net "M_F_CPU0_SB_DQ<17>")
	)
	(segment
		(start 291.487098 -301.315374)
		(end 291.487098 -301.205392)
		(width 0.14478)
		(layer "In11.Cu")
		(net "M_F_CPU0_SB_DQ<17>")
	)
	(segment
		(start 278.27478 -301.4599)
		(end 276.865334 -301.4599)
		(width 0.14478)
		(layer "In11.Cu")
		(net "M_F_CPU0_SB_DQ<17>")
	)
	(segment
		(start 286.71647 -302.310038)
		(end 285.565342 -301.15891)
		(width 0.14478)
		(layer "In11.Cu")
		(net "M_F_CPU0_SB_DQ<17>")
	)
	(segment
		(start 273.37385 -302.310038)
		(end 272.753836 -302.310038)
		(width 0.14478)
		(layer "In11.Cu")
		(net "M_F_CPU0_SB_DQ<17>")
	)
	(segment
		(start 326.180704 -284.98927)
		(end 325.770494 -284.98927)
		(width 0.0889)
		(layer "In11.Cu")
		(net "M_F_CPU0_SB_DQ<17>")
	)
	(segment
		(start 270.699992 -302.691038)
		(end 270.45412 -302.691038)
		(width 0.14478)
		(layer "In11.Cu")
		(net "M_F_CPU0_SB_DQ<17>")
	)
	(arc
		(start 329.188064 -284.938724)
		(mid 329.00112 -284.988979)
		(end 328.814176 -284.938724)
		(width 0.0889)
		(layer "In11.Cu")
		(net "M_F_CPU0_SB_DQ<17>")
	)
	(arc
		(start 326.367902 -284.938724)
		(mid 326.277642 -284.976352)
		(end 326.180704 -284.98927)
		(width 0.0889)
		(layer "In11.Cu")
		(net "M_F_CPU0_SB_DQ<17>")
	)
	(arc
		(start 326.919082 -284.930088)
		(mid 326.642353 -284.862405)
		(end 326.367902 -284.938724)
		(width 0.0889)
		(layer "In11.Cu")
		(net "M_F_CPU0_SB_DQ<17>")
	)
	(arc
		(start 331.634084 -284.938724)
		(mid 331.351128 -284.862547)
		(end 331.068172 -284.938724)
		(width 0.0889)
		(layer "In11.Cu")
		(net "M_F_CPU0_SB_DQ<17>")
	)
	(arc
		(start 329.753976 -284.938724)
		(mid 329.47102 -284.862547)
		(end 329.188064 -284.938724)
		(width 0.0889)
		(layer "In11.Cu")
		(net "M_F_CPU0_SB_DQ<17>")
	)
	(arc
		(start 328.248264 -284.938724)
		(mid 328.061066 -284.989106)
		(end 327.873868 -284.938724)
		(width 0.0889)
		(layer "In11.Cu")
		(net "M_F_CPU0_SB_DQ<17>")
	)
	(arc
		(start 333.513938 -284.938724)
		(mid 333.230982 -284.862547)
		(end 332.948026 -284.938724)
		(width 0.0889)
		(layer "In11.Cu")
		(net "M_F_CPU0_SB_DQ<17>")
	)
	(arc
		(start 332.008226 -284.938724)
		(mid 331.825975 -284.989074)
		(end 331.642466 -284.94355)
		(width 0.0889)
		(layer "In11.Cu")
		(net "M_F_CPU0_SB_DQ<17>")
	)
	(arc
		(start 332.574138 -284.938724)
		(mid 332.291182 -284.862547)
		(end 332.008226 -284.938724)
		(width 0.0889)
		(layer "In11.Cu")
		(net "M_F_CPU0_SB_DQ<17>")
	)
	(arc
		(start 330.119736 -284.94355)
		(mid 329.936228 -284.989044)
		(end 329.753976 -284.938724)
		(width 0.0889)
		(layer "In11.Cu")
		(net "M_F_CPU0_SB_DQ<17>")
	)
	(arc
		(start 330.69403 -284.938724)
		(mid 330.411074 -284.862547)
		(end 330.128118 -284.938724)
		(width 0.0889)
		(layer "In11.Cu")
		(net "M_F_CPU0_SB_DQ<17>")
	)
	(arc
		(start 327.307702 -284.938724)
		(mid 327.120758 -284.988979)
		(end 326.933814 -284.938724)
		(width 0.0889)
		(layer "In11.Cu")
		(net "M_F_CPU0_SB_DQ<17>")
	)
	(arc
		(start 328.814176 -284.938724)
		(mid 328.53122 -284.862547)
		(end 328.248264 -284.938724)
		(width 0.0889)
		(layer "In11.Cu")
		(net "M_F_CPU0_SB_DQ<17>")
	)
	(arc
		(start 332.948026 -284.938724)
		(mid 332.761082 -284.988979)
		(end 332.574138 -284.938724)
		(width 0.0889)
		(layer "In11.Cu")
		(net "M_F_CPU0_SB_DQ<17>")
	)
	(arc
		(start 333.832708 -284.964886)
		(mid 333.670376 -284.987704)
		(end 333.513938 -284.938724)
		(width 0.0889)
		(layer "In11.Cu")
		(net "M_F_CPU0_SB_DQ<17>")
	)
	(arc
		(start 331.068172 -284.938724)
		(mid 330.885921 -284.989074)
		(end 330.702412 -284.94355)
		(width 0.0889)
		(layer "In11.Cu")
		(net "M_F_CPU0_SB_DQ<17>")
	)
	(arc
		(start 327.873868 -284.938724)
		(mid 327.596801 -284.862453)
		(end 327.318116 -284.932628)
		(width 0.0889)
		(layer "In11.Cu")
		(net "M_F_CPU0_SB_DQ<17>")
	)
	(segment
		(start 332.758034 -283.5402)
		(end 332.291182 -283.806138)
		(width 0.10668)
		(layer "F.Cu")
		(net "M_F_CPU0_SB_DQ<16>")
	)
	(segment
		(start 322.004182 -284.701234)
		(end 322.004182 -284.905958)
		(width 0.14478)
		(layer "In11.Cu")
		(net "M_F_CPU0_SB_DQ<16>")
	)
	(segment
		(start 292.960806 -300.07687)
		(end 292.644068 -299.760132)
		(width 0.14478)
		(layer "In11.Cu")
		(net "M_F_CPU0_SB_DQ<16>")
	)
	(segment
		(start 324.75805 -283.969714)
		(end 324.255384 -284.47238)
		(width 0.0889)
		(layer "In11.Cu")
		(net "M_F_CPU0_SB_DQ<16>")
	)
	(segment
		(start 270.444468 -300.981364)
		(end 269.648178 -300.185074)
		(width 0.14478)
		(layer "In11.Cu")
		(net "M_F_CPU0_SB_DQ<16>")
	)
	(segment
		(start 326.69099 -284.157166)
		(end 325.886064 -284.157166)
		(width 0.0889)
		(layer "In11.Cu")
		(net "M_F_CPU0_SB_DQ<16>")
	)
	(segment
		(start 322.233036 -284.47238)
		(end 322.004182 -284.701234)
		(width 0.14478)
		(layer "In11.Cu")
		(net "M_F_CPU0_SB_DQ<16>")
	)
	(segment
		(start 320.053462 -286.856678)
		(end 319.848738 -286.856678)
		(width 0.14478)
		(layer "In11.Cu")
		(net "M_F_CPU0_SB_DQ<16>")
	)
	(segment
		(start 287.332674 -300.93031)
		(end 287.096454 -300.93031)
		(width 0.14478)
		(layer "In11.Cu")
		(net "M_F_CPU0_SB_DQ<16>")
	)
	(segment
		(start 271.950434 -300.81855)
		(end 271.78762 -300.981364)
		(width 0.14478)
		(layer "In11.Cu")
		(net "M_F_CPU0_SB_DQ<16>")
	)
	(segment
		(start 296.58437 -300.92523)
		(end 296.34307 -300.92523)
		(width 0.14478)
		(layer "In11.Cu")
		(net "M_F_CPU0_SB_DQ<16>")
	)
	(segment
		(start 271.950434 -300.488858)
		(end 271.950434 -300.81855)
		(width 0.14478)
		(layer "In11.Cu")
		(net "M_F_CPU0_SB_DQ<16>")
	)
	(segment
		(start 303.660048 -300.61027)
		(end 303.416208 -300.61027)
		(width 0.14478)
		(layer "In11.Cu")
		(net "M_F_CPU0_SB_DQ<16>")
	)
	(segment
		(start 293.200328 -300.07687)
		(end 292.960806 -300.07687)
		(width 0.14478)
		(layer "In11.Cu")
		(net "M_F_CPU0_SB_DQ<16>")
	)
	(segment
		(start 320.443606 -286.26181)
		(end 320.443606 -286.466534)
		(width 0.14478)
		(layer "In11.Cu")
		(net "M_F_CPU0_SB_DQ<16>")
	)
	(segment
		(start 325.433182 -283.969714)
		(end 324.75805 -283.969714)
		(width 0.0889)
		(layer "In11.Cu")
		(net "M_F_CPU0_SB_DQ<16>")
	)
	(segment
		(start 271.78762 -300.981364)
		(end 271.556988 -300.981364)
		(width 0.14478)
		(layer "In11.Cu")
		(net "M_F_CPU0_SB_DQ<16>")
	)
	(segment
		(start 298.71543 -299.760132)
		(end 298.431712 -299.760132)
		(width 0.14478)
		(layer "In11.Cu")
		(net "M_F_CPU0_SB_DQ<16>")
	)
	(segment
		(start 270.837914 -300.81855)
		(end 270.6751 -300.981364)
		(width 0.14478)
		(layer "In11.Cu")
		(net "M_F_CPU0_SB_DQ<16>")
	)
	(segment
		(start 291.062918 -299.760132)
		(end 290.628832 -299.760132)
		(width 0.14478)
		(layer "In11.Cu")
		(net "M_F_CPU0_SB_DQ<16>")
	)
	(segment
		(start 278.103076 -299.760132)
		(end 275.820632 -299.760132)
		(width 0.14478)
		(layer "In11.Cu")
		(net "M_F_CPU0_SB_DQ<16>")
	)
	(segment
		(start 327.79081 -284.121606)
		(end 327.778872 -284.128464)
		(width 0.0889)
		(layer "In11.Cu")
		(net "M_F_CPU0_SB_DQ<16>")
	)
	(segment
		(start 296.34307 -300.92523)
		(end 296.02811 -300.61027)
		(width 0.14478)
		(layer "In11.Cu")
		(net "M_F_CPU0_SB_DQ<16>")
	)
	(segment
		(start 281.608022 -300.61027)
		(end 279.816814 -300.61027)
		(width 0.14478)
		(layer "In11.Cu")
		(net "M_F_CPU0_SB_DQ<16>")
	)
	(segment
		(start 308.103778 -298.601638)
		(end 306.929282 -298.601638)
		(width 0.14478)
		(layer "In11.Cu")
		(net "M_F_CPU0_SB_DQ<16>")
	)
	(segment
		(start 299.27169 -300.07687)
		(end 299.032168 -300.07687)
		(width 0.14478)
		(layer "In11.Cu")
		(net "M_F_CPU0_SB_DQ<16>")
	)
	(segment
		(start 327.778872 -284.128464)
		(end 327.765156 -284.136338)
		(width 0.0889)
		(layer "In11.Cu")
		(net "M_F_CPU0_SB_DQ<16>")
	)
	(segment
		(start 294.777414 -300.61027)
		(end 293.927276 -299.760132)
		(width 0.14478)
		(layer "In11.Cu")
		(net "M_F_CPU0_SB_DQ<16>")
	)
	(segment
		(start 304.528728 -300.61027)
		(end 304.216308 -300.92269)
		(width 0.14478)
		(layer "In11.Cu")
		(net "M_F_CPU0_SB_DQ<16>")
	)
	(segment
		(start 273.989038 -300.32071)
		(end 273.758406 -300.32071)
		(width 0.14478)
		(layer "In11.Cu")
		(net "M_F_CPU0_SB_DQ<16>")
	)
	(segment
		(start 320.253868 -287.057084)
		(end 320.053462 -286.856678)
		(width 0.14478)
		(layer "In11.Cu")
		(net "M_F_CPU0_SB_DQ<16>")
	)
	(segment
		(start 291.619178 -300.08195)
		(end 291.384736 -300.08195)
		(width 0.14478)
		(layer "In11.Cu")
		(net "M_F_CPU0_SB_DQ<16>")
	)
	(segment
		(start 271.23136 -300.326044)
		(end 271.000728 -300.326044)
		(width 0.14478)
		(layer "In11.Cu")
		(net "M_F_CPU0_SB_DQ<16>")
	)
	(segment
		(start 322.204588 -285.311088)
		(end 322.019168 -285.496508)
		(width 0.14478)
		(layer "In11.Cu")
		(net "M_F_CPU0_SB_DQ<16>")
	)
	(segment
		(start 279.260554 -300.91761)
		(end 278.103076 -299.760132)
		(width 0.14478)
		(layer "In11.Cu")
		(net "M_F_CPU0_SB_DQ<16>")
	)
	(segment
		(start 304.216308 -300.92269)
		(end 303.972468 -300.92269)
		(width 0.14478)
		(layer "In11.Cu")
		(net "M_F_CPU0_SB_DQ<16>")
	)
	(segment
		(start 271.000728 -300.326044)
		(end 270.837914 -300.488858)
		(width 0.14478)
		(layer "In11.Cu")
		(net "M_F_CPU0_SB_DQ<16>")
	)
	(segment
		(start 322.004182 -284.905958)
		(end 322.204588 -285.106364)
		(width 0.14478)
		(layer "In11.Cu")
		(net "M_F_CPU0_SB_DQ<16>")
	)
	(segment
		(start 303.972468 -300.92269)
		(end 303.660048 -300.61027)
		(width 0.14478)
		(layer "In11.Cu")
		(net "M_F_CPU0_SB_DQ<16>")
	)
	(segment
		(start 271.556988 -300.981364)
		(end 271.394174 -300.81855)
		(width 0.14478)
		(layer "In11.Cu")
		(net "M_F_CPU0_SB_DQ<16>")
	)
	(segment
		(start 320.644012 -286.871664)
		(end 320.458592 -287.057084)
		(width 0.14478)
		(layer "In11.Cu")
		(net "M_F_CPU0_SB_DQ<16>")
	)
	(segment
		(start 290.628832 -299.760132)
		(end 289.471354 -300.91761)
		(width 0.14478)
		(layer "In11.Cu")
		(net "M_F_CPU0_SB_DQ<16>")
	)
	(segment
		(start 321.4243 -286.091376)
		(end 321.23888 -286.276796)
		(width 0.14478)
		(layer "In11.Cu")
		(net "M_F_CPU0_SB_DQ<16>")
	)
	(segment
		(start 271.394174 -300.81855)
		(end 271.394174 -300.488858)
		(width 0.14478)
		(layer "In11.Cu")
		(net "M_F_CPU0_SB_DQ<16>")
	)
	(segment
		(start 320.458592 -287.057084)
		(end 320.253868 -287.057084)
		(width 0.14478)
		(layer "In11.Cu")
		(net "M_F_CPU0_SB_DQ<16>")
	)
	(segment
		(start 293.927276 -299.760132)
		(end 293.517066 -299.760132)
		(width 0.14478)
		(layer "In11.Cu")
		(net "M_F_CPU0_SB_DQ<16>")
	)
	(segment
		(start 274.578826 -301.001938)
		(end 274.348194 -301.001938)
		(width 0.14478)
		(layer "In11.Cu")
		(net "M_F_CPU0_SB_DQ<16>")
	)
	(segment
		(start 274.348194 -301.001938)
		(end 274.18538 -300.839124)
		(width 0.14478)
		(layer "In11.Cu")
		(net "M_F_CPU0_SB_DQ<16>")
	)
	(segment
		(start 273.758406 -300.32071)
		(end 273.468846 -300.61027)
		(width 0.14478)
		(layer "In11.Cu")
		(net "M_F_CPU0_SB_DQ<16>")
	)
	(segment
		(start 279.816814 -300.61027)
		(end 279.509474 -300.91761)
		(width 0.14478)
		(layer "In11.Cu")
		(net "M_F_CPU0_SB_DQ<16>")
	)
	(segment
		(start 272.34388 -300.326044)
		(end 272.113248 -300.326044)
		(width 0.14478)
		(layer "In11.Cu")
		(net "M_F_CPU0_SB_DQ<16>")
	)
	(segment
		(start 274.18538 -300.517052)
		(end 273.989038 -300.32071)
		(width 0.14478)
		(layer "In11.Cu")
		(net "M_F_CPU0_SB_DQ<16>")
	)
	(segment
		(start 291.940996 -299.760132)
		(end 291.619178 -300.08195)
		(width 0.14478)
		(layer "In11.Cu")
		(net "M_F_CPU0_SB_DQ<16>")
	)
	(segment
		(start 271.394174 -300.488858)
		(end 271.23136 -300.326044)
		(width 0.14478)
		(layer "In11.Cu")
		(net "M_F_CPU0_SB_DQ<16>")
	)
	(segment
		(start 321.223894 -285.686246)
		(end 321.4243 -285.886652)
		(width 0.14478)
		(layer "In11.Cu")
		(net "M_F_CPU0_SB_DQ<16>")
	)
	(segment
		(start 287.096454 -300.93031)
		(end 285.926276 -299.760132)
		(width 0.14478)
		(layer "In11.Cu")
		(net "M_F_CPU0_SB_DQ<16>")
	)
	(segment
		(start 272.628106 -300.61027)
		(end 272.34388 -300.326044)
		(width 0.14478)
		(layer "In11.Cu")
		(net "M_F_CPU0_SB_DQ<16>")
	)
	(segment
		(start 324.255384 -284.47238)
		(end 322.233036 -284.47238)
		(width 0.14478)
		(layer "In11.Cu")
		(net "M_F_CPU0_SB_DQ<16>")
	)
	(segment
		(start 272.113248 -300.326044)
		(end 271.950434 -300.488858)
		(width 0.14478)
		(layer "In11.Cu")
		(net "M_F_CPU0_SB_DQ<16>")
	)
	(segment
		(start 281.915362 -300.91761)
		(end 281.608022 -300.61027)
		(width 0.14478)
		(layer "In11.Cu")
		(net "M_F_CPU0_SB_DQ<16>")
	)
	(segment
		(start 302.859948 -300.92269)
		(end 302.547528 -300.61027)
		(width 0.14478)
		(layer "In11.Cu")
		(net "M_F_CPU0_SB_DQ<16>")
	)
	(segment
		(start 320.644012 -286.66694)
		(end 320.644012 -286.871664)
		(width 0.14478)
		(layer "In11.Cu")
		(net "M_F_CPU0_SB_DQ<16>")
	)
	(segment
		(start 321.223894 -285.481522)
		(end 321.223894 -285.686246)
		(width 0.14478)
		(layer "In11.Cu")
		(net "M_F_CPU0_SB_DQ<16>")
	)
	(segment
		(start 301.291752 -299.760132)
		(end 300.994826 -299.760132)
		(width 0.14478)
		(layer "In11.Cu")
		(net "M_F_CPU0_SB_DQ<16>")
	)
	(segment
		(start 302.14189 -300.61027)
		(end 301.291752 -299.760132)
		(width 0.14478)
		(layer "In11.Cu")
		(net "M_F_CPU0_SB_DQ<16>")
	)
	(segment
		(start 292.644068 -299.760132)
		(end 291.940996 -299.760132)
		(width 0.14478)
		(layer "In11.Cu")
		(net "M_F_CPU0_SB_DQ<16>")
	)
	(segment
		(start 300.129448 -299.760132)
		(end 299.588428 -299.760132)
		(width 0.14478)
		(layer "In11.Cu")
		(net "M_F_CPU0_SB_DQ<16>")
	)
	(segment
		(start 282.270454 -300.91761)
		(end 281.915362 -300.91761)
		(width 0.14478)
		(layer "In11.Cu")
		(net "M_F_CPU0_SB_DQ<16>")
	)
	(segment
		(start 298.431712 -299.760132)
		(end 297.581574 -300.61027)
		(width 0.14478)
		(layer "In11.Cu")
		(net "M_F_CPU0_SB_DQ<16>")
	)
	(segment
		(start 285.926276 -299.760132)
		(end 283.427932 -299.760132)
		(width 0.14478)
		(layer "In11.Cu")
		(net "M_F_CPU0_SB_DQ<16>")
	)
	(segment
		(start 293.517066 -299.760132)
		(end 293.200328 -300.07687)
		(width 0.14478)
		(layer "In11.Cu")
		(net "M_F_CPU0_SB_DQ<16>")
	)
	(segment
		(start 304.92065 -300.61027)
		(end 304.528728 -300.61027)
		(width 0.14478)
		(layer "In11.Cu")
		(net "M_F_CPU0_SB_DQ<16>")
	)
	(segment
		(start 300.994826 -299.760132)
		(end 300.685708 -300.06925)
		(width 0.14478)
		(layer "In11.Cu")
		(net "M_F_CPU0_SB_DQ<16>")
	)
	(segment
		(start 300.685708 -300.06925)
		(end 300.438566 -300.06925)
		(width 0.14478)
		(layer "In11.Cu")
		(net "M_F_CPU0_SB_DQ<16>")
	)
	(segment
		(start 321.409314 -285.296102)
		(end 321.223894 -285.481522)
		(width 0.14478)
		(layer "In11.Cu")
		(net "M_F_CPU0_SB_DQ<16>")
	)
	(segment
		(start 270.6751 -300.981364)
		(end 270.444468 -300.981364)
		(width 0.14478)
		(layer "In11.Cu")
		(net "M_F_CPU0_SB_DQ<16>")
	)
	(segment
		(start 297.581574 -300.61027)
		(end 296.89933 -300.61027)
		(width 0.14478)
		(layer "In11.Cu")
		(net "M_F_CPU0_SB_DQ<16>")
	)
	(segment
		(start 289.222434 -300.91761)
		(end 288.915094 -300.61027)
		(width 0.14478)
		(layer "In11.Cu")
		(net "M_F_CPU0_SB_DQ<16>")
	)
	(segment
		(start 319.848738 -286.856678)
		(end 308.103778 -298.601638)
		(width 0.14478)
		(layer "In11.Cu")
		(net "M_F_CPU0_SB_DQ<16>")
	)
	(segment
		(start 279.509474 -300.91761)
		(end 279.260554 -300.91761)
		(width 0.14478)
		(layer "In11.Cu")
		(net "M_F_CPU0_SB_DQ<16>")
	)
	(segment
		(start 321.814444 -285.496508)
		(end 321.614038 -285.296102)
		(width 0.14478)
		(layer "In11.Cu")
		(net "M_F_CPU0_SB_DQ<16>")
	)
	(segment
		(start 329.292458 -284.133544)
		(end 329.284076 -284.128718)
		(width 0.0889)
		(layer "In11.Cu")
		(net "M_F_CPU0_SB_DQ<16>")
	)
	(segment
		(start 273.468846 -300.61027)
		(end 272.628106 -300.61027)
		(width 0.14478)
		(layer "In11.Cu")
		(net "M_F_CPU0_SB_DQ<16>")
	)
	(segment
		(start 322.204588 -285.106364)
		(end 322.204588 -285.311088)
		(width 0.14478)
		(layer "In11.Cu")
		(net "M_F_CPU0_SB_DQ<16>")
	)
	(segment
		(start 274.18538 -300.839124)
		(end 274.18538 -300.517052)
		(width 0.14478)
		(layer "In11.Cu")
		(net "M_F_CPU0_SB_DQ<16>")
	)
	(segment
		(start 302.547528 -300.61027)
		(end 302.14189 -300.61027)
		(width 0.14478)
		(layer "In11.Cu")
		(net "M_F_CPU0_SB_DQ<16>")
	)
	(segment
		(start 303.103788 -300.92269)
		(end 302.859948 -300.92269)
		(width 0.14478)
		(layer "In11.Cu")
		(net "M_F_CPU0_SB_DQ<16>")
	)
	(segment
		(start 289.471354 -300.91761)
		(end 289.222434 -300.91761)
		(width 0.14478)
		(layer "In11.Cu")
		(net "M_F_CPU0_SB_DQ<16>")
	)
	(segment
		(start 327.415398 -284.13456)
		(end 327.337166 -284.092396)
		(width 0.0889)
		(layer "In11.Cu")
		(net "M_F_CPU0_SB_DQ<16>")
	)
	(segment
		(start 288.915094 -300.61027)
		(end 287.652714 -300.61027)
		(width 0.14478)
		(layer "In11.Cu")
		(net "M_F_CPU0_SB_DQ<16>")
	)
	(segment
		(start 296.89933 -300.61027)
		(end 296.58437 -300.92523)
		(width 0.14478)
		(layer "In11.Cu")
		(net "M_F_CPU0_SB_DQ<16>")
	)
	(segment
		(start 291.384736 -300.08195)
		(end 291.062918 -299.760132)
		(width 0.14478)
		(layer "In11.Cu")
		(net "M_F_CPU0_SB_DQ<16>")
	)
	(segment
		(start 320.443606 -286.466534)
		(end 320.644012 -286.66694)
		(width 0.14478)
		(layer "In11.Cu")
		(net "M_F_CPU0_SB_DQ<16>")
	)
	(segment
		(start 321.614038 -285.296102)
		(end 321.409314 -285.296102)
		(width 0.14478)
		(layer "In11.Cu")
		(net "M_F_CPU0_SB_DQ<16>")
	)
	(segment
		(start 321.23888 -286.276796)
		(end 321.034156 -286.276796)
		(width 0.14478)
		(layer "In11.Cu")
		(net "M_F_CPU0_SB_DQ<16>")
	)
	(segment
		(start 306.929282 -298.601638)
		(end 304.92065 -300.61027)
		(width 0.14478)
		(layer "In11.Cu")
		(net "M_F_CPU0_SB_DQ<16>")
	)
	(segment
		(start 320.83375 -286.07639)
		(end 320.629026 -286.07639)
		(width 0.14478)
		(layer "In11.Cu")
		(net "M_F_CPU0_SB_DQ<16>")
	)
	(segment
		(start 332.291182 -283.806138)
		(end 332.445106 -284.071568)
		(width 0.0889)
		(layer "In11.Cu")
		(net "M_F_CPU0_SB_DQ<16>")
	)
	(segment
		(start 327.158096 -284.06598)
		(end 326.736456 -284.152594)
		(width 0.0889)
		(layer "In11.Cu")
		(net "M_F_CPU0_SB_DQ<16>")
	)
	(segment
		(start 296.02811 -300.61027)
		(end 294.777414 -300.61027)
		(width 0.14478)
		(layer "In11.Cu")
		(net "M_F_CPU0_SB_DQ<16>")
	)
	(segment
		(start 320.629026 -286.07639)
		(end 320.443606 -286.26181)
		(width 0.14478)
		(layer "In11.Cu")
		(net "M_F_CPU0_SB_DQ<16>")
	)
	(segment
		(start 322.019168 -285.496508)
		(end 321.814444 -285.496508)
		(width 0.14478)
		(layer "In11.Cu")
		(net "M_F_CPU0_SB_DQ<16>")
	)
	(segment
		(start 300.438566 -300.06925)
		(end 300.129448 -299.760132)
		(width 0.14478)
		(layer "In11.Cu")
		(net "M_F_CPU0_SB_DQ<16>")
	)
	(segment
		(start 299.588428 -299.760132)
		(end 299.27169 -300.07687)
		(width 0.14478)
		(layer "In11.Cu")
		(net "M_F_CPU0_SB_DQ<16>")
	)
	(segment
		(start 299.032168 -300.07687)
		(end 298.71543 -299.760132)
		(width 0.14478)
		(layer "In11.Cu")
		(net "M_F_CPU0_SB_DQ<16>")
	)
	(segment
		(start 270.837914 -300.488858)
		(end 270.837914 -300.81855)
		(width 0.14478)
		(layer "In11.Cu")
		(net "M_F_CPU0_SB_DQ<16>")
	)
	(segment
		(start 287.652714 -300.61027)
		(end 287.332674 -300.93031)
		(width 0.14478)
		(layer "In11.Cu")
		(net "M_F_CPU0_SB_DQ<16>")
	)
	(segment
		(start 328.718164 -284.128718)
		(end 328.709782 -284.133544)
		(width 0.0889)
		(layer "In11.Cu")
		(net "M_F_CPU0_SB_DQ<16>")
	)
	(segment
		(start 283.427932 -299.760132)
		(end 282.270454 -300.91761)
		(width 0.14478)
		(layer "In11.Cu")
		(net "M_F_CPU0_SB_DQ<16>")
	)
	(segment
		(start 321.4243 -285.886652)
		(end 321.4243 -286.091376)
		(width 0.14478)
		(layer "In11.Cu")
		(net "M_F_CPU0_SB_DQ<16>")
	)
	(segment
		(start 321.034156 -286.276796)
		(end 320.83375 -286.07639)
		(width 0.14478)
		(layer "In11.Cu")
		(net "M_F_CPU0_SB_DQ<16>")
	)
	(segment
		(start 303.416208 -300.61027)
		(end 303.103788 -300.92269)
		(width 0.14478)
		(layer "In11.Cu")
		(net "M_F_CPU0_SB_DQ<16>")
	)
	(segment
		(start 275.820632 -299.760132)
		(end 274.578826 -301.001938)
		(width 0.14478)
		(layer "In11.Cu")
		(net "M_F_CPU0_SB_DQ<16>")
	)
	(segment
		(start 332.445106 -284.071568)
		(end 332.422754 -284.15488)
		(width 0.0889)
		(layer "In11.Cu")
		(net "M_F_CPU0_SB_DQ<16>")
	)
	(segment
		(start 331.538072 -284.128718)
		(end 331.52969 -284.133544)
		(width 0.0889)
		(layer "In11.Cu")
		(net "M_F_CPU0_SB_DQ<16>")
	)
	(arc
		(start 329.658218 -284.128718)
		(mid 329.475967 -284.179068)
		(end 329.292458 -284.133544)
		(width 0.0889)
		(layer "In11.Cu")
		(net "M_F_CPU0_SB_DQ<16>")
	)
	(arc
		(start 325.886064 -284.157166)
		(mid 325.721113 -284.124355)
		(end 325.581264 -284.030928)
		(width 0.0889)
		(layer "In11.Cu")
		(net "M_F_CPU0_SB_DQ<16>")
	)
	(arc
		(start 326.736456 -284.152594)
		(mid 326.713836 -284.156001)
		(end 326.69099 -284.157166)
		(width 0.0889)
		(layer "In11.Cu")
		(net "M_F_CPU0_SB_DQ<16>")
	)
	(arc
		(start 332.422754 -284.15488)
		(mid 332.260422 -284.177698)
		(end 332.103984 -284.128718)
		(width 0.0889)
		(layer "In11.Cu")
		(net "M_F_CPU0_SB_DQ<16>")
	)
	(arc
		(start 329.284076 -284.128718)
		(mid 329.00112 -284.052541)
		(end 328.718164 -284.128718)
		(width 0.0889)
		(layer "In11.Cu")
		(net "M_F_CPU0_SB_DQ<16>")
	)
	(arc
		(start 330.22413 -284.128718)
		(mid 329.941174 -284.052541)
		(end 329.658218 -284.128718)
		(width 0.0889)
		(layer "In11.Cu")
		(net "M_F_CPU0_SB_DQ<16>")
	)
	(arc
		(start 331.52969 -284.133544)
		(mid 331.346182 -284.179038)
		(end 331.16393 -284.128718)
		(width 0.0889)
		(layer "In11.Cu")
		(net "M_F_CPU0_SB_DQ<16>")
	)
	(arc
		(start 330.598018 -284.128718)
		(mid 330.411074 -284.178973)
		(end 330.22413 -284.128718)
		(width 0.0889)
		(layer "In11.Cu")
		(net "M_F_CPU0_SB_DQ<16>")
	)
	(arc
		(start 325.581264 -284.030928)
		(mid 325.513308 -283.985615)
		(end 325.433182 -283.969714)
		(width 0.0889)
		(layer "In11.Cu")
		(net "M_F_CPU0_SB_DQ<16>")
	)
	(arc
		(start 327.765156 -284.136338)
		(mid 327.590053 -284.179014)
		(end 327.415398 -284.13456)
		(width 0.0889)
		(layer "In11.Cu")
		(net "M_F_CPU0_SB_DQ<16>")
	)
	(arc
		(start 332.103984 -284.128718)
		(mid 331.821028 -284.052541)
		(end 331.538072 -284.128718)
		(width 0.0889)
		(layer "In11.Cu")
		(net "M_F_CPU0_SB_DQ<16>")
	)
	(arc
		(start 328.344022 -284.128718)
		(mid 328.068344 -284.052588)
		(end 327.79081 -284.121606)
		(width 0.0889)
		(layer "In11.Cu")
		(net "M_F_CPU0_SB_DQ<16>")
	)
	(arc
		(start 327.337166 -284.092396)
		(mid 327.249955 -284.063389)
		(end 327.158096 -284.06598)
		(width 0.0889)
		(layer "In11.Cu")
		(net "M_F_CPU0_SB_DQ<16>")
	)
	(arc
		(start 331.16393 -284.128718)
		(mid 330.880974 -284.052541)
		(end 330.598018 -284.128718)
		(width 0.0889)
		(layer "In11.Cu")
		(net "M_F_CPU0_SB_DQ<16>")
	)
	(arc
		(start 328.709782 -284.133544)
		(mid 328.526274 -284.179038)
		(end 328.344022 -284.128718)
		(width 0.0889)
		(layer "In11.Cu")
		(net "M_F_CPU0_SB_DQ<16>")
	)
	(segment
		(start 334.637888 -283.5402)
		(end 334.171036 -283.806138)
		(width 0.10668)
		(layer "F.Cu")
		(net "M_F_CPU0_SB_DQ<15>")
	)
	(segment
		(start 331.52969 -283.478732)
		(end 331.538072 -283.483558)
		(width 0.0889)
		(layer "In11.Cu")
		(net "M_F_CPU0_SB_DQ<15>")
	)
	(segment
		(start 268.16812 -299.615352)
		(end 268.16812 -299.511212)
		(width 0.14478)
		(layer "In11.Cu")
		(net "M_F_CPU0_SB_DQ<15>")
	)
	(segment
		(start 267.761466 -299.760132)
		(end 268.02334 -299.760132)
		(width 0.14478)
		(layer "In11.Cu")
		(net "M_F_CPU0_SB_DQ<15>")
	)
	(segment
		(start 326.829674 -283.478732)
		(end 326.838056 -283.483558)
		(width 0.0889)
		(layer "In11.Cu")
		(net "M_F_CPU0_SB_DQ<15>")
	)
	(segment
		(start 267.471906 -299.366432)
		(end 267.616686 -299.511212)
		(width 0.14478)
		(layer "In11.Cu")
		(net "M_F_CPU0_SB_DQ<15>")
	)
	(segment
		(start 278.116284 -298.909994)
		(end 279.388824 -299.760132)
		(width 0.14478)
		(layer "In11.Cu")
		(net "M_F_CPU0_SB_DQ<15>")
	)
	(segment
		(start 301.035466 -298.909994)
		(end 302.308006 -299.760132)
		(width 0.14478)
		(layer "In11.Cu")
		(net "M_F_CPU0_SB_DQ<15>")
	)
	(segment
		(start 332.469744 -283.478732)
		(end 332.478126 -283.483558)
		(width 0.0889)
		(layer "In11.Cu")
		(net "M_F_CPU0_SB_DQ<15>")
	)
	(segment
		(start 298.67098 -298.909994)
		(end 301.035466 -298.909994)
		(width 0.14478)
		(layer "In11.Cu")
		(net "M_F_CPU0_SB_DQ<15>")
	)
	(segment
		(start 302.308006 -299.760132)
		(end 304.991262 -299.760132)
		(width 0.14478)
		(layer "In11.Cu")
		(net "M_F_CPU0_SB_DQ<15>")
	)
	(segment
		(start 333.044038 -283.483558)
		(end 333.05242 -283.478732)
		(width 0.0889)
		(layer "In11.Cu")
		(net "M_F_CPU0_SB_DQ<15>")
	)
	(segment
		(start 268.719554 -299.511212)
		(end 268.719554 -299.615352)
		(width 0.14478)
		(layer "In11.Cu")
		(net "M_F_CPU0_SB_DQ<15>")
	)
	(segment
		(start 265.54811 -299.33519)
		(end 265.973052 -299.760132)
		(width 0.14478)
		(layer "In11.Cu")
		(net "M_F_CPU0_SB_DQ<15>")
	)
	(segment
		(start 334.017112 -283.540708)
		(end 334.171036 -283.806138)
		(width 0.0889)
		(layer "In11.Cu")
		(net "M_F_CPU0_SB_DQ<15>")
	)
	(segment
		(start 265.973052 -299.760132)
		(end 266.920472 -299.760132)
		(width 0.14478)
		(layer "In11.Cu")
		(net "M_F_CPU0_SB_DQ<15>")
	)
	(segment
		(start 282.425902 -299.760132)
		(end 283.698188 -298.909994)
		(width 0.14478)
		(layer "In11.Cu")
		(net "M_F_CPU0_SB_DQ<15>")
	)
	(segment
		(start 267.065252 -299.615352)
		(end 267.065252 -299.511212)
		(width 0.14478)
		(layer "In11.Cu")
		(net "M_F_CPU0_SB_DQ<15>")
	)
	(segment
		(start 267.210032 -299.366432)
		(end 267.471906 -299.366432)
		(width 0.14478)
		(layer "In11.Cu")
		(net "M_F_CPU0_SB_DQ<15>")
	)
	(segment
		(start 322.014596 -283.91104)
		(end 323.903594 -283.91104)
		(width 0.14478)
		(layer "In11.Cu")
		(net "M_F_CPU0_SB_DQ<15>")
	)
	(segment
		(start 267.616686 -299.615352)
		(end 267.761466 -299.760132)
		(width 0.14478)
		(layer "In11.Cu")
		(net "M_F_CPU0_SB_DQ<15>")
	)
	(segment
		(start 283.698188 -298.909994)
		(end 285.80969 -298.909994)
		(width 0.14478)
		(layer "In11.Cu")
		(net "M_F_CPU0_SB_DQ<15>")
	)
	(segment
		(start 307.875178 -298.050458)
		(end 322.014596 -283.91104)
		(width 0.14478)
		(layer "In11.Cu")
		(net "M_F_CPU0_SB_DQ<15>")
	)
	(segment
		(start 324.420484 -283.91104)
		(end 324.771766 -283.559758)
		(width 0.0889)
		(layer "In11.Cu")
		(net "M_F_CPU0_SB_DQ<15>")
	)
	(segment
		(start 333.9211 -283.515308)
		(end 334.017112 -283.540708)
		(width 0.0889)
		(layer "In11.Cu")
		(net "M_F_CPU0_SB_DQ<15>")
	)
	(segment
		(start 276.011132 -298.909994)
		(end 278.116284 -298.909994)
		(width 0.14478)
		(layer "In11.Cu")
		(net "M_F_CPU0_SB_DQ<15>")
	)
	(segment
		(start 266.920472 -299.760132)
		(end 267.065252 -299.615352)
		(width 0.14478)
		(layer "In11.Cu")
		(net "M_F_CPU0_SB_DQ<15>")
	)
	(segment
		(start 327.403714 -283.483558)
		(end 327.412096 -283.478732)
		(width 0.0889)
		(layer "In11.Cu")
		(net "M_F_CPU0_SB_DQ<15>")
	)
	(segment
		(start 323.903594 -283.91104)
		(end 324.420484 -283.91104)
		(width 0.0889)
		(layer "In11.Cu")
		(net "M_F_CPU0_SB_DQ<15>")
	)
	(segment
		(start 328.333608 -283.489654)
		(end 328.344022 -283.483558)
		(width 0.0889)
		(layer "In11.Cu")
		(net "M_F_CPU0_SB_DQ<15>")
	)
	(segment
		(start 268.02334 -299.760132)
		(end 268.16812 -299.615352)
		(width 0.14478)
		(layer "In11.Cu")
		(net "M_F_CPU0_SB_DQ<15>")
	)
	(segment
		(start 268.3129 -299.366432)
		(end 268.574774 -299.366432)
		(width 0.14478)
		(layer "In11.Cu")
		(net "M_F_CPU0_SB_DQ<15>")
	)
	(segment
		(start 293.685722 -298.913804)
		(end 294.952166 -299.760132)
		(width 0.14478)
		(layer "In11.Cu")
		(net "M_F_CPU0_SB_DQ<15>")
	)
	(segment
		(start 274.738592 -299.760132)
		(end 276.011132 -298.909994)
		(width 0.14478)
		(layer "In11.Cu")
		(net "M_F_CPU0_SB_DQ<15>")
	)
	(segment
		(start 267.065252 -299.511212)
		(end 267.210032 -299.366432)
		(width 0.14478)
		(layer "In11.Cu")
		(net "M_F_CPU0_SB_DQ<15>")
	)
	(segment
		(start 289.536378 -299.760132)
		(end 290.803076 -298.913804)
		(width 0.14478)
		(layer "In11.Cu")
		(net "M_F_CPU0_SB_DQ<15>")
	)
	(segment
		(start 306.700936 -298.050458)
		(end 307.875178 -298.050458)
		(width 0.14478)
		(layer "In11.Cu")
		(net "M_F_CPU0_SB_DQ<15>")
	)
	(segment
		(start 268.574774 -299.366432)
		(end 268.719554 -299.511212)
		(width 0.14478)
		(layer "In11.Cu")
		(net "M_F_CPU0_SB_DQ<15>")
	)
	(segment
		(start 268.864334 -299.760132)
		(end 274.738592 -299.760132)
		(width 0.14478)
		(layer "In11.Cu")
		(net "M_F_CPU0_SB_DQ<15>")
	)
	(segment
		(start 285.80969 -298.909994)
		(end 287.08223 -299.760132)
		(width 0.14478)
		(layer "In11.Cu")
		(net "M_F_CPU0_SB_DQ<15>")
	)
	(segment
		(start 304.991262 -299.760132)
		(end 306.700936 -298.050458)
		(width 0.14478)
		(layer "In11.Cu")
		(net "M_F_CPU0_SB_DQ<15>")
	)
	(segment
		(start 294.952166 -299.760132)
		(end 297.398694 -299.760132)
		(width 0.14478)
		(layer "In11.Cu")
		(net "M_F_CPU0_SB_DQ<15>")
	)
	(segment
		(start 329.284076 -283.483558)
		(end 329.292458 -283.478732)
		(width 0.0889)
		(layer "In11.Cu")
		(net "M_F_CPU0_SB_DQ<15>")
	)
	(segment
		(start 268.16812 -299.511212)
		(end 268.3129 -299.366432)
		(width 0.14478)
		(layer "In11.Cu")
		(net "M_F_CPU0_SB_DQ<15>")
	)
	(segment
		(start 297.398694 -299.760132)
		(end 298.67098 -298.909994)
		(width 0.14478)
		(layer "In11.Cu")
		(net "M_F_CPU0_SB_DQ<15>")
	)
	(segment
		(start 287.08223 -299.760132)
		(end 289.536378 -299.760132)
		(width 0.14478)
		(layer "In11.Cu")
		(net "M_F_CPU0_SB_DQ<15>")
	)
	(segment
		(start 290.803076 -298.913804)
		(end 293.685722 -298.913804)
		(width 0.14478)
		(layer "In11.Cu")
		(net "M_F_CPU0_SB_DQ<15>")
	)
	(segment
		(start 267.616686 -299.511212)
		(end 267.616686 -299.615352)
		(width 0.14478)
		(layer "In11.Cu")
		(net "M_F_CPU0_SB_DQ<15>")
	)
	(segment
		(start 324.771766 -283.559758)
		(end 326.180958 -283.559758)
		(width 0.0889)
		(layer "In11.Cu")
		(net "M_F_CPU0_SB_DQ<15>")
	)
	(segment
		(start 268.719554 -299.615352)
		(end 268.864334 -299.760132)
		(width 0.14478)
		(layer "In11.Cu")
		(net "M_F_CPU0_SB_DQ<15>")
	)
	(segment
		(start 326.838056 -283.483558)
		(end 326.84847 -283.489654)
		(width 0.0889)
		(layer "In11.Cu")
		(net "M_F_CPU0_SB_DQ<15>")
	)
	(segment
		(start 328.709782 -283.478732)
		(end 328.718164 -283.483558)
		(width 0.0889)
		(layer "In11.Cu")
		(net "M_F_CPU0_SB_DQ<15>")
	)
	(segment
		(start 279.388824 -299.760132)
		(end 282.425902 -299.760132)
		(width 0.14478)
		(layer "In11.Cu")
		(net "M_F_CPU0_SB_DQ<15>")
	)
	(arc
		(start 330.22413 -283.483558)
		(mid 330.411074 -283.433303)
		(end 330.598018 -283.483558)
		(width 0.0889)
		(layer "In11.Cu")
		(net "M_F_CPU0_SB_DQ<15>")
	)
	(arc
		(start 331.16393 -283.483558)
		(mid 331.346181 -283.433208)
		(end 331.52969 -283.478732)
		(width 0.0889)
		(layer "In11.Cu")
		(net "M_F_CPU0_SB_DQ<15>")
	)
	(arc
		(start 326.180958 -283.559758)
		(mid 326.327484 -283.540388)
		(end 326.463914 -283.483558)
		(width 0.0889)
		(layer "In11.Cu")
		(net "M_F_CPU0_SB_DQ<15>")
	)
	(arc
		(start 327.777856 -283.483558)
		(mid 328.054923 -283.559829)
		(end 328.333608 -283.489654)
		(width 0.0889)
		(layer "In11.Cu")
		(net "M_F_CPU0_SB_DQ<15>")
	)
	(arc
		(start 333.05242 -283.478732)
		(mid 333.235928 -283.433238)
		(end 333.41818 -283.483558)
		(width 0.0889)
		(layer "In11.Cu")
		(net "M_F_CPU0_SB_DQ<15>")
	)
	(arc
		(start 332.478126 -283.483558)
		(mid 332.761082 -283.559735)
		(end 333.044038 -283.483558)
		(width 0.0889)
		(layer "In11.Cu")
		(net "M_F_CPU0_SB_DQ<15>")
	)
	(arc
		(start 327.412096 -283.478732)
		(mid 327.595604 -283.433238)
		(end 327.777856 -283.483558)
		(width 0.0889)
		(layer "In11.Cu")
		(net "M_F_CPU0_SB_DQ<15>")
	)
	(arc
		(start 333.41818 -283.483558)
		(mid 333.665893 -283.558778)
		(end 333.9211 -283.515308)
		(width 0.0889)
		(layer "In11.Cu")
		(net "M_F_CPU0_SB_DQ<15>")
	)
	(arc
		(start 328.344022 -283.483558)
		(mid 328.526273 -283.433208)
		(end 328.709782 -283.478732)
		(width 0.0889)
		(layer "In11.Cu")
		(net "M_F_CPU0_SB_DQ<15>")
	)
	(arc
		(start 331.538072 -283.483558)
		(mid 331.821028 -283.559735)
		(end 332.103984 -283.483558)
		(width 0.0889)
		(layer "In11.Cu")
		(net "M_F_CPU0_SB_DQ<15>")
	)
	(arc
		(start 329.658218 -283.483558)
		(mid 329.941174 -283.559735)
		(end 330.22413 -283.483558)
		(width 0.0889)
		(layer "In11.Cu")
		(net "M_F_CPU0_SB_DQ<15>")
	)
	(arc
		(start 332.103984 -283.483558)
		(mid 332.286235 -283.433208)
		(end 332.469744 -283.478732)
		(width 0.0889)
		(layer "In11.Cu")
		(net "M_F_CPU0_SB_DQ<15>")
	)
	(arc
		(start 329.292458 -283.478732)
		(mid 329.475966 -283.433238)
		(end 329.658218 -283.483558)
		(width 0.0889)
		(layer "In11.Cu")
		(net "M_F_CPU0_SB_DQ<15>")
	)
	(arc
		(start 330.598018 -283.483558)
		(mid 330.880974 -283.559735)
		(end 331.16393 -283.483558)
		(width 0.0889)
		(layer "In11.Cu")
		(net "M_F_CPU0_SB_DQ<15>")
	)
	(arc
		(start 326.84847 -283.489654)
		(mid 327.126902 -283.559752)
		(end 327.403714 -283.483558)
		(width 0.0889)
		(layer "In11.Cu")
		(net "M_F_CPU0_SB_DQ<15>")
	)
	(arc
		(start 328.718164 -283.483558)
		(mid 329.00112 -283.559735)
		(end 329.284076 -283.483558)
		(width 0.0889)
		(layer "In11.Cu")
		(net "M_F_CPU0_SB_DQ<15>")
	)
	(arc
		(start 326.463914 -283.483558)
		(mid 326.646165 -283.433208)
		(end 326.829674 -283.478732)
		(width 0.0889)
		(layer "In11.Cu")
		(net "M_F_CPU0_SB_DQ<15>")
	)
	(segment
		(start 333.227934 -282.730194)
		(end 332.761082 -282.996132)
		(width 0.10668)
		(layer "F.Cu")
		(net "M_F_CPU0_SB_DQ<14>")
	)
	(segment
		(start 327.862438 -282.680664)
		(end 327.874376 -282.673806)
		(width 0.0889)
		(layer "In11.Cu")
		(net "M_F_CPU0_SB_DQ<14>")
	)
	(segment
		(start 282.905454 -298.06011)
		(end 283.755592 -297.209972)
		(width 0.14478)
		(layer "In11.Cu")
		(net "M_F_CPU0_SB_DQ<14>")
	)
	(segment
		(start 321.651884 -283.00172)
		(end 323.906134 -283.00172)
		(width 0.14478)
		(layer "In11.Cu")
		(net "M_F_CPU0_SB_DQ<14>")
	)
	(segment
		(start 298.908216 -297.209972)
		(end 300.815248 -297.209972)
		(width 0.14478)
		(layer "In11.Cu")
		(net "M_F_CPU0_SB_DQ<14>")
	)
	(segment
		(start 265.54811 -297.635168)
		(end 265.973052 -298.06011)
		(width 0.14478)
		(layer "In11.Cu")
		(net "M_F_CPU0_SB_DQ<14>")
	)
	(segment
		(start 268.266672 -297.710352)
		(end 268.411452 -297.565572)
		(width 0.14478)
		(layer "In11.Cu")
		(net "M_F_CPU0_SB_DQ<14>")
	)
	(segment
		(start 326.108822 -282.750006)
		(end 326.651112 -282.750006)
		(width 0.0889)
		(layer "In11.Cu")
		(net "M_F_CPU0_SB_DQ<14>")
	)
	(segment
		(start 276.110192 -297.209972)
		(end 277.993856 -297.209972)
		(width 0.14478)
		(layer "In11.Cu")
		(net "M_F_CPU0_SB_DQ<14>")
	)
	(segment
		(start 323.906134 -283.00172)
		(end 324.20433 -283.00172)
		(width 0.0889)
		(layer "In11.Cu")
		(net "M_F_CPU0_SB_DQ<14>")
	)
	(segment
		(start 268.266672 -297.91533)
		(end 268.266672 -297.710352)
		(width 0.14478)
		(layer "In11.Cu")
		(net "M_F_CPU0_SB_DQ<14>")
	)
	(segment
		(start 285.941516 -297.209972)
		(end 286.791654 -298.06011)
		(width 0.14478)
		(layer "In11.Cu")
		(net "M_F_CPU0_SB_DQ<14>")
	)
	(segment
		(start 267.570458 -297.565572)
		(end 267.715238 -297.710352)
		(width 0.14478)
		(layer "In11.Cu")
		(net "M_F_CPU0_SB_DQ<14>")
	)
	(segment
		(start 268.962886 -298.06011)
		(end 275.260054 -298.06011)
		(width 0.14478)
		(layer "In11.Cu")
		(net "M_F_CPU0_SB_DQ<14>")
	)
	(segment
		(start 330.119736 -282.668726)
		(end 330.128118 -282.673552)
		(width 0.0889)
		(layer "In11.Cu")
		(net "M_F_CPU0_SB_DQ<14>")
	)
	(segment
		(start 330.69403 -282.673552)
		(end 330.702412 -282.668726)
		(width 0.0889)
		(layer "In11.Cu")
		(net "M_F_CPU0_SB_DQ<14>")
	)
	(segment
		(start 325.721726 -282.36291)
		(end 326.108822 -282.750006)
		(width 0.0889)
		(layer "In11.Cu")
		(net "M_F_CPU0_SB_DQ<14>")
	)
	(segment
		(start 283.755592 -297.209972)
		(end 285.941516 -297.209972)
		(width 0.14478)
		(layer "In11.Cu")
		(net "M_F_CPU0_SB_DQ<14>")
	)
	(segment
		(start 306.96535 -296.464482)
		(end 308.189122 -296.464482)
		(width 0.14478)
		(layer "In11.Cu")
		(net "M_F_CPU0_SB_DQ<14>")
	)
	(segment
		(start 267.308584 -297.565572)
		(end 267.570458 -297.565572)
		(width 0.14478)
		(layer "In11.Cu")
		(net "M_F_CPU0_SB_DQ<14>")
	)
	(segment
		(start 268.673326 -297.565572)
		(end 268.818106 -297.710352)
		(width 0.14478)
		(layer "In11.Cu")
		(net "M_F_CPU0_SB_DQ<14>")
	)
	(segment
		(start 294.464994 -298.06011)
		(end 298.058078 -298.06011)
		(width 0.14478)
		(layer "In11.Cu")
		(net "M_F_CPU0_SB_DQ<14>")
	)
	(segment
		(start 290.969192 -297.209972)
		(end 293.614856 -297.209972)
		(width 0.14478)
		(layer "In11.Cu")
		(net "M_F_CPU0_SB_DQ<14>")
	)
	(segment
		(start 286.791654 -298.06011)
		(end 290.119054 -298.06011)
		(width 0.14478)
		(layer "In11.Cu")
		(net "M_F_CPU0_SB_DQ<14>")
	)
	(segment
		(start 298.058078 -298.06011)
		(end 298.908216 -297.209972)
		(width 0.14478)
		(layer "In11.Cu")
		(net "M_F_CPU0_SB_DQ<14>")
	)
	(segment
		(start 277.993856 -297.209972)
		(end 278.843994 -298.06011)
		(width 0.14478)
		(layer "In11.Cu")
		(net "M_F_CPU0_SB_DQ<14>")
	)
	(segment
		(start 267.019024 -298.06011)
		(end 267.163804 -297.91533)
		(width 0.14478)
		(layer "In11.Cu")
		(net "M_F_CPU0_SB_DQ<14>")
	)
	(segment
		(start 331.634084 -282.673552)
		(end 331.642466 -282.668726)
		(width 0.0889)
		(layer "In11.Cu")
		(net "M_F_CPU0_SB_DQ<14>")
	)
	(segment
		(start 268.121892 -298.06011)
		(end 268.266672 -297.91533)
		(width 0.14478)
		(layer "In11.Cu")
		(net "M_F_CPU0_SB_DQ<14>")
	)
	(segment
		(start 332.511146 -282.705302)
		(end 332.607158 -282.730702)
		(width 0.0889)
		(layer "In11.Cu")
		(net "M_F_CPU0_SB_DQ<14>")
	)
	(segment
		(start 267.715238 -297.710352)
		(end 267.715238 -297.91533)
		(width 0.14478)
		(layer "In11.Cu")
		(net "M_F_CPU0_SB_DQ<14>")
	)
	(segment
		(start 327.874376 -282.673806)
		(end 327.890632 -282.664408)
		(width 0.0889)
		(layer "In11.Cu")
		(net "M_F_CPU0_SB_DQ<14>")
	)
	(segment
		(start 300.815248 -297.209972)
		(end 301.665386 -298.06011)
		(width 0.14478)
		(layer "In11.Cu")
		(net "M_F_CPU0_SB_DQ<14>")
	)
	(segment
		(start 275.260054 -298.06011)
		(end 276.110192 -297.209972)
		(width 0.14478)
		(layer "In11.Cu")
		(net "M_F_CPU0_SB_DQ<14>")
	)
	(segment
		(start 293.614856 -297.209972)
		(end 294.464994 -298.06011)
		(width 0.14478)
		(layer "In11.Cu")
		(net "M_F_CPU0_SB_DQ<14>")
	)
	(segment
		(start 267.163804 -297.710352)
		(end 267.308584 -297.565572)
		(width 0.14478)
		(layer "In11.Cu")
		(net "M_F_CPU0_SB_DQ<14>")
	)
	(segment
		(start 305.369722 -298.06011)
		(end 306.96535 -296.464482)
		(width 0.14478)
		(layer "In11.Cu")
		(net "M_F_CPU0_SB_DQ<14>")
	)
	(segment
		(start 301.665386 -298.06011)
		(end 305.369722 -298.06011)
		(width 0.14478)
		(layer "In11.Cu")
		(net "M_F_CPU0_SB_DQ<14>")
	)
	(segment
		(start 268.818106 -297.91533)
		(end 268.962886 -298.06011)
		(width 0.14478)
		(layer "In11.Cu")
		(net "M_F_CPU0_SB_DQ<14>")
	)
	(segment
		(start 267.715238 -297.91533)
		(end 267.860018 -298.06011)
		(width 0.14478)
		(layer "In11.Cu")
		(net "M_F_CPU0_SB_DQ<14>")
	)
	(segment
		(start 278.843994 -298.06011)
		(end 282.905454 -298.06011)
		(width 0.14478)
		(layer "In11.Cu")
		(net "M_F_CPU0_SB_DQ<14>")
	)
	(segment
		(start 267.163804 -297.91533)
		(end 267.163804 -297.710352)
		(width 0.14478)
		(layer "In11.Cu")
		(net "M_F_CPU0_SB_DQ<14>")
	)
	(segment
		(start 332.607158 -282.730702)
		(end 332.761082 -282.996132)
		(width 0.0889)
		(layer "In11.Cu")
		(net "M_F_CPU0_SB_DQ<14>")
	)
	(segment
		(start 324.84314 -282.36291)
		(end 325.721726 -282.36291)
		(width 0.0889)
		(layer "In11.Cu")
		(net "M_F_CPU0_SB_DQ<14>")
	)
	(segment
		(start 268.411452 -297.565572)
		(end 268.673326 -297.565572)
		(width 0.14478)
		(layer "In11.Cu")
		(net "M_F_CPU0_SB_DQ<14>")
	)
	(segment
		(start 265.973052 -298.06011)
		(end 267.019024 -298.06011)
		(width 0.14478)
		(layer "In11.Cu")
		(net "M_F_CPU0_SB_DQ<14>")
	)
	(segment
		(start 324.20433 -283.00172)
		(end 324.84314 -282.36291)
		(width 0.0889)
		(layer "In11.Cu")
		(net "M_F_CPU0_SB_DQ<14>")
	)
	(segment
		(start 268.818106 -297.710352)
		(end 268.818106 -297.91533)
		(width 0.14478)
		(layer "In11.Cu")
		(net "M_F_CPU0_SB_DQ<14>")
	)
	(segment
		(start 290.119054 -298.06011)
		(end 290.969192 -297.209972)
		(width 0.14478)
		(layer "In11.Cu")
		(net "M_F_CPU0_SB_DQ<14>")
	)
	(segment
		(start 308.189122 -296.464482)
		(end 321.651884 -283.00172)
		(width 0.14478)
		(layer "In11.Cu")
		(net "M_F_CPU0_SB_DQ<14>")
	)
	(segment
		(start 327.297542 -282.666694)
		(end 327.309226 -282.673552)
		(width 0.0889)
		(layer "In11.Cu")
		(net "M_F_CPU0_SB_DQ<14>")
	)
	(segment
		(start 267.860018 -298.06011)
		(end 268.121892 -298.06011)
		(width 0.14478)
		(layer "In11.Cu")
		(net "M_F_CPU0_SB_DQ<14>")
	)
	(arc
		(start 328.814176 -282.673552)
		(mid 329.00112 -282.623297)
		(end 329.188064 -282.673552)
		(width 0.0889)
		(layer "In11.Cu")
		(net "M_F_CPU0_SB_DQ<14>")
	)
	(arc
		(start 331.068172 -282.673552)
		(mid 331.351128 -282.749729)
		(end 331.634084 -282.673552)
		(width 0.0889)
		(layer "In11.Cu")
		(net "M_F_CPU0_SB_DQ<14>")
	)
	(arc
		(start 330.128118 -282.673552)
		(mid 330.411074 -282.749729)
		(end 330.69403 -282.673552)
		(width 0.0889)
		(layer "In11.Cu")
		(net "M_F_CPU0_SB_DQ<14>")
	)
	(arc
		(start 330.702412 -282.668726)
		(mid 330.88592 -282.623232)
		(end 331.068172 -282.673552)
		(width 0.0889)
		(layer "In11.Cu")
		(net "M_F_CPU0_SB_DQ<14>")
	)
	(arc
		(start 327.890632 -282.664408)
		(mid 328.070614 -282.623308)
		(end 328.248264 -282.673552)
		(width 0.0889)
		(layer "In11.Cu")
		(net "M_F_CPU0_SB_DQ<14>")
	)
	(arc
		(start 327.309226 -282.673552)
		(mid 327.584904 -282.749682)
		(end 327.862438 -282.680664)
		(width 0.0889)
		(layer "In11.Cu")
		(net "M_F_CPU0_SB_DQ<14>")
	)
	(arc
		(start 332.008226 -282.673552)
		(mid 332.255939 -282.748772)
		(end 332.511146 -282.705302)
		(width 0.0889)
		(layer "In11.Cu")
		(net "M_F_CPU0_SB_DQ<14>")
	)
	(arc
		(start 326.651112 -282.750006)
		(mid 326.798043 -282.730595)
		(end 326.93483 -282.673552)
		(width 0.0889)
		(layer "In11.Cu")
		(net "M_F_CPU0_SB_DQ<14>")
	)
	(arc
		(start 329.188064 -282.673552)
		(mid 329.47102 -282.749729)
		(end 329.753976 -282.673552)
		(width 0.0889)
		(layer "In11.Cu")
		(net "M_F_CPU0_SB_DQ<14>")
	)
	(arc
		(start 328.248264 -282.673552)
		(mid 328.53122 -282.749729)
		(end 328.814176 -282.673552)
		(width 0.0889)
		(layer "In11.Cu")
		(net "M_F_CPU0_SB_DQ<14>")
	)
	(arc
		(start 331.642466 -282.668726)
		(mid 331.825974 -282.623232)
		(end 332.008226 -282.673552)
		(width 0.0889)
		(layer "In11.Cu")
		(net "M_F_CPU0_SB_DQ<14>")
	)
	(arc
		(start 326.93483 -282.673552)
		(mid 327.115288 -282.623108)
		(end 327.297542 -282.666694)
		(width 0.0889)
		(layer "In11.Cu")
		(net "M_F_CPU0_SB_DQ<14>")
	)
	(arc
		(start 329.753976 -282.673552)
		(mid 329.936227 -282.623202)
		(end 330.119736 -282.668726)
		(width 0.0889)
		(layer "In11.Cu")
		(net "M_F_CPU0_SB_DQ<14>")
	)
	(segment
		(start 334.167988 -282.730194)
		(end 333.701136 -282.996132)
		(width 0.10668)
		(layer "F.Cu")
		(net "M_F_CPU0_SB_DQ<13>")
	)
	(segment
		(start 324.400926 -283.369258)
		(end 326.180704 -283.369258)
		(width 0.0889)
		(layer "In11.Cu")
		(net "M_F_CPU0_SB_DQ<13>")
	)
	(segment
		(start 281.497532 -299.20311)
		(end 281.76093 -299.20311)
		(width 0.14478)
		(layer "In11.Cu")
		(net "M_F_CPU0_SB_DQ<13>")
	)
	(segment
		(start 271.387062 -298.68368)
		(end 271.387062 -299.111416)
		(width 0.14478)
		(layer "In11.Cu")
		(net "M_F_CPU0_SB_DQ<13>")
	)
	(segment
		(start 304.067972 -298.657772)
		(end 304.212752 -298.512992)
		(width 0.14478)
		(layer "In11.Cu")
		(net "M_F_CPU0_SB_DQ<13>")
	)
	(segment
		(start 282.766262 -298.910248)
		(end 283.6164 -298.06011)
		(width 0.14478)
		(layer "In11.Cu")
		(net "M_F_CPU0_SB_DQ<13>")
	)
	(segment
		(start 272.106136 -298.520866)
		(end 272.336768 -298.520866)
		(width 0.14478)
		(layer "In11.Cu")
		(net "M_F_CPU0_SB_DQ<13>")
	)
	(segment
		(start 304.067972 -298.765468)
		(end 304.067972 -298.657772)
		(width 0.14478)
		(layer "In11.Cu")
		(net "M_F_CPU0_SB_DQ<13>")
	)
	(segment
		(start 270.667988 -299.27423)
		(end 270.830802 -299.111416)
		(width 0.14478)
		(layer "In11.Cu")
		(net "M_F_CPU0_SB_DQ<13>")
	)
	(segment
		(start 281.20467 -298.910248)
		(end 281.497532 -299.20311)
		(width 0.14478)
		(layer "In11.Cu")
		(net "M_F_CPU0_SB_DQ<13>")
	)
	(segment
		(start 271.943322 -298.68368)
		(end 272.106136 -298.520866)
		(width 0.14478)
		(layer "In11.Cu")
		(net "M_F_CPU0_SB_DQ<13>")
	)
	(segment
		(start 321.83324 -283.45638)
		(end 323.913754 -283.45638)
		(width 0.14478)
		(layer "In11.Cu")
		(net "M_F_CPU0_SB_DQ<13>")
	)
	(segment
		(start 273.657568 -298.525946)
		(end 273.8882 -298.525946)
		(width 0.14478)
		(layer "In11.Cu")
		(net "M_F_CPU0_SB_DQ<13>")
	)
	(segment
		(start 296.68597 -298.657772)
		(end 296.83075 -298.512992)
		(width 0.14478)
		(layer "In11.Cu")
		(net "M_F_CPU0_SB_DQ<13>")
	)
	(segment
		(start 308.375558 -296.914062)
		(end 321.83324 -283.45638)
		(width 0.14478)
		(layer "In11.Cu")
		(net "M_F_CPU0_SB_DQ<13>")
	)
	(segment
		(start 286.080708 -298.06011)
		(end 286.930846 -298.910248)
		(width 0.14478)
		(layer "In11.Cu")
		(net "M_F_CPU0_SB_DQ<13>")
	)
	(segment
		(start 271.387062 -299.111416)
		(end 271.549876 -299.27423)
		(width 0.14478)
		(layer "In11.Cu")
		(net "M_F_CPU0_SB_DQ<13>")
	)
	(segment
		(start 274.828762 -298.910248)
		(end 275.146262 -298.910248)
		(width 0.14478)
		(layer "In11.Cu")
		(net "M_F_CPU0_SB_DQ<13>")
	)
	(segment
		(start 297.092624 -298.512992)
		(end 297.237404 -298.657772)
		(width 0.14478)
		(layer "In11.Cu")
		(net "M_F_CPU0_SB_DQ<13>")
	)
	(segment
		(start 270.437356 -299.27423)
		(end 270.667988 -299.27423)
		(width 0.14478)
		(layer "In11.Cu")
		(net "M_F_CPU0_SB_DQ<13>")
	)
	(segment
		(start 302.258222 -298.667932)
		(end 302.403002 -298.523152)
		(width 0.14478)
		(layer "In11.Cu")
		(net "M_F_CPU0_SB_DQ<13>")
	)
	(segment
		(start 270.830802 -299.111416)
		(end 270.830802 -298.68368)
		(width 0.14478)
		(layer "In11.Cu")
		(net "M_F_CPU0_SB_DQ<13>")
	)
	(segment
		(start 330.119736 -283.323538)
		(end 330.128118 -283.318712)
		(width 0.0889)
		(layer "In11.Cu")
		(net "M_F_CPU0_SB_DQ<13>")
	)
	(segment
		(start 274.213828 -299.29455)
		(end 274.44446 -299.29455)
		(width 0.14478)
		(layer "In11.Cu")
		(net "M_F_CPU0_SB_DQ<13>")
	)
	(segment
		(start 304.619406 -298.657772)
		(end 304.619406 -298.765468)
		(width 0.14478)
		(layer "In11.Cu")
		(net "M_F_CPU0_SB_DQ<13>")
	)
	(segment
		(start 304.474626 -298.512992)
		(end 304.619406 -298.657772)
		(width 0.14478)
		(layer "In11.Cu")
		(net "M_F_CPU0_SB_DQ<13>")
	)
	(segment
		(start 275.9964 -298.06011)
		(end 278.105108 -298.06011)
		(width 0.14478)
		(layer "In11.Cu")
		(net "M_F_CPU0_SB_DQ<13>")
	)
	(segment
		(start 290.7792 -298.06011)
		(end 293.776908 -298.06011)
		(width 0.14478)
		(layer "In11.Cu")
		(net "M_F_CPU0_SB_DQ<13>")
	)
	(segment
		(start 296.54119 -298.910248)
		(end 296.68597 -298.765468)
		(width 0.14478)
		(layer "In11.Cu")
		(net "M_F_CPU0_SB_DQ<13>")
	)
	(segment
		(start 282.053792 -298.910248)
		(end 282.766262 -298.910248)
		(width 0.14478)
		(layer "In11.Cu")
		(net "M_F_CPU0_SB_DQ<13>")
	)
	(segment
		(start 301.022004 -298.06011)
		(end 301.872142 -298.910248)
		(width 0.14478)
		(layer "In11.Cu")
		(net "M_F_CPU0_SB_DQ<13>")
	)
	(segment
		(start 270.993616 -298.520866)
		(end 271.224248 -298.520866)
		(width 0.14478)
		(layer "In11.Cu")
		(net "M_F_CPU0_SB_DQ<13>")
	)
	(segment
		(start 305.20513 -298.910248)
		(end 307.201316 -296.914062)
		(width 0.14478)
		(layer "In11.Cu")
		(net "M_F_CPU0_SB_DQ<13>")
	)
	(segment
		(start 302.809656 -298.765468)
		(end 302.954436 -298.910248)
		(width 0.14478)
		(layer "In11.Cu")
		(net "M_F_CPU0_SB_DQ<13>")
	)
	(segment
		(start 302.809656 -298.667932)
		(end 302.809656 -298.765468)
		(width 0.14478)
		(layer "In11.Cu")
		(net "M_F_CPU0_SB_DQ<13>")
	)
	(segment
		(start 324.313804 -283.45638)
		(end 324.400926 -283.369258)
		(width 0.0889)
		(layer "In11.Cu")
		(net "M_F_CPU0_SB_DQ<13>")
	)
	(segment
		(start 281.76093 -299.20311)
		(end 282.053792 -298.910248)
		(width 0.14478)
		(layer "In11.Cu")
		(net "M_F_CPU0_SB_DQ<13>")
	)
	(segment
		(start 302.258222 -298.765468)
		(end 302.258222 -298.667932)
		(width 0.14478)
		(layer "In11.Cu")
		(net "M_F_CPU0_SB_DQ<13>")
	)
	(segment
		(start 302.113442 -298.910248)
		(end 302.258222 -298.765468)
		(width 0.14478)
		(layer "In11.Cu")
		(net "M_F_CPU0_SB_DQ<13>")
	)
	(segment
		(start 278.105108 -298.06011)
		(end 278.955246 -298.910248)
		(width 0.14478)
		(layer "In11.Cu")
		(net "M_F_CPU0_SB_DQ<13>")
	)
	(segment
		(start 302.954436 -298.910248)
		(end 303.923192 -298.910248)
		(width 0.14478)
		(layer "In11.Cu")
		(net "M_F_CPU0_SB_DQ<13>")
	)
	(segment
		(start 294.627046 -298.910248)
		(end 296.54119 -298.910248)
		(width 0.14478)
		(layer "In11.Cu")
		(net "M_F_CPU0_SB_DQ<13>")
	)
	(segment
		(start 297.237404 -298.765468)
		(end 297.382184 -298.910248)
		(width 0.14478)
		(layer "In11.Cu")
		(net "M_F_CPU0_SB_DQ<13>")
	)
	(segment
		(start 272.72615 -298.910248)
		(end 273.273266 -298.910248)
		(width 0.14478)
		(layer "In11.Cu")
		(net "M_F_CPU0_SB_DQ<13>")
	)
	(segment
		(start 333.832708 -283.344874)
		(end 333.85506 -283.261562)
		(width 0.0889)
		(layer "In11.Cu")
		(net "M_F_CPU0_SB_DQ<13>")
	)
	(segment
		(start 272.336768 -298.520866)
		(end 272.72615 -298.910248)
		(width 0.14478)
		(layer "In11.Cu")
		(net "M_F_CPU0_SB_DQ<13>")
	)
	(segment
		(start 271.224248 -298.520866)
		(end 271.387062 -298.68368)
		(width 0.14478)
		(layer "In11.Cu")
		(net "M_F_CPU0_SB_DQ<13>")
	)
	(segment
		(start 296.83075 -298.512992)
		(end 297.092624 -298.512992)
		(width 0.14478)
		(layer "In11.Cu")
		(net "M_F_CPU0_SB_DQ<13>")
	)
	(segment
		(start 293.776908 -298.06011)
		(end 294.627046 -298.910248)
		(width 0.14478)
		(layer "In11.Cu")
		(net "M_F_CPU0_SB_DQ<13>")
	)
	(segment
		(start 270.830802 -298.68368)
		(end 270.993616 -298.520866)
		(width 0.14478)
		(layer "In11.Cu")
		(net "M_F_CPU0_SB_DQ<13>")
	)
	(segment
		(start 307.201316 -296.914062)
		(end 308.375558 -296.914062)
		(width 0.14478)
		(layer "In11.Cu")
		(net "M_F_CPU0_SB_DQ<13>")
	)
	(segment
		(start 274.051014 -298.68876)
		(end 274.051014 -299.131736)
		(width 0.14478)
		(layer "In11.Cu")
		(net "M_F_CPU0_SB_DQ<13>")
	)
	(segment
		(start 273.8882 -298.525946)
		(end 274.051014 -298.68876)
		(width 0.14478)
		(layer "In11.Cu")
		(net "M_F_CPU0_SB_DQ<13>")
	)
	(segment
		(start 274.051014 -299.131736)
		(end 274.213828 -299.29455)
		(width 0.14478)
		(layer "In11.Cu")
		(net "M_F_CPU0_SB_DQ<13>")
	)
	(segment
		(start 297.851322 -298.910248)
		(end 298.70146 -298.06011)
		(width 0.14478)
		(layer "In11.Cu")
		(net "M_F_CPU0_SB_DQ<13>")
	)
	(segment
		(start 304.764186 -298.910248)
		(end 305.20513 -298.910248)
		(width 0.14478)
		(layer "In11.Cu")
		(net "M_F_CPU0_SB_DQ<13>")
	)
	(segment
		(start 286.930846 -298.910248)
		(end 289.929062 -298.910248)
		(width 0.14478)
		(layer "In11.Cu")
		(net "M_F_CPU0_SB_DQ<13>")
	)
	(segment
		(start 304.212752 -298.512992)
		(end 304.474626 -298.512992)
		(width 0.14478)
		(layer "In11.Cu")
		(net "M_F_CPU0_SB_DQ<13>")
	)
	(segment
		(start 301.872142 -298.910248)
		(end 302.113442 -298.910248)
		(width 0.14478)
		(layer "In11.Cu")
		(net "M_F_CPU0_SB_DQ<13>")
	)
	(segment
		(start 269.648178 -298.485052)
		(end 270.437356 -299.27423)
		(width 0.14478)
		(layer "In11.Cu")
		(net "M_F_CPU0_SB_DQ<13>")
	)
	(segment
		(start 298.70146 -298.06011)
		(end 301.022004 -298.06011)
		(width 0.14478)
		(layer "In11.Cu")
		(net "M_F_CPU0_SB_DQ<13>")
	)
	(segment
		(start 273.273266 -298.910248)
		(end 273.657568 -298.525946)
		(width 0.14478)
		(layer "In11.Cu")
		(net "M_F_CPU0_SB_DQ<13>")
	)
	(segment
		(start 271.943322 -299.111416)
		(end 271.943322 -298.68368)
		(width 0.14478)
		(layer "In11.Cu")
		(net "M_F_CPU0_SB_DQ<13>")
	)
	(segment
		(start 275.146262 -298.910248)
		(end 275.9964 -298.06011)
		(width 0.14478)
		(layer "In11.Cu")
		(net "M_F_CPU0_SB_DQ<13>")
	)
	(segment
		(start 302.403002 -298.523152)
		(end 302.664876 -298.523152)
		(width 0.14478)
		(layer "In11.Cu")
		(net "M_F_CPU0_SB_DQ<13>")
	)
	(segment
		(start 296.68597 -298.765468)
		(end 296.68597 -298.657772)
		(width 0.14478)
		(layer "In11.Cu")
		(net "M_F_CPU0_SB_DQ<13>")
	)
	(segment
		(start 302.664876 -298.523152)
		(end 302.809656 -298.667932)
		(width 0.14478)
		(layer "In11.Cu")
		(net "M_F_CPU0_SB_DQ<13>")
	)
	(segment
		(start 333.85506 -283.261562)
		(end 333.701136 -282.996132)
		(width 0.0889)
		(layer "In11.Cu")
		(net "M_F_CPU0_SB_DQ<13>")
	)
	(segment
		(start 303.923192 -298.910248)
		(end 304.067972 -298.765468)
		(width 0.14478)
		(layer "In11.Cu")
		(net "M_F_CPU0_SB_DQ<13>")
	)
	(segment
		(start 271.549876 -299.27423)
		(end 271.780508 -299.27423)
		(width 0.14478)
		(layer "In11.Cu")
		(net "M_F_CPU0_SB_DQ<13>")
	)
	(segment
		(start 274.44446 -299.29455)
		(end 274.828762 -298.910248)
		(width 0.14478)
		(layer "In11.Cu")
		(net "M_F_CPU0_SB_DQ<13>")
	)
	(segment
		(start 327.307702 -283.318712)
		(end 327.318116 -283.312616)
		(width 0.0889)
		(layer "In11.Cu")
		(net "M_F_CPU0_SB_DQ<13>")
	)
	(segment
		(start 289.929062 -298.910248)
		(end 290.7792 -298.06011)
		(width 0.14478)
		(layer "In11.Cu")
		(net "M_F_CPU0_SB_DQ<13>")
	)
	(segment
		(start 278.955246 -298.910248)
		(end 281.20467 -298.910248)
		(width 0.14478)
		(layer "In11.Cu")
		(net "M_F_CPU0_SB_DQ<13>")
	)
	(segment
		(start 330.69403 -283.318712)
		(end 330.702412 -283.323538)
		(width 0.0889)
		(layer "In11.Cu")
		(net "M_F_CPU0_SB_DQ<13>")
	)
	(segment
		(start 297.382184 -298.910248)
		(end 297.851322 -298.910248)
		(width 0.14478)
		(layer "In11.Cu")
		(net "M_F_CPU0_SB_DQ<13>")
	)
	(segment
		(start 271.780508 -299.27423)
		(end 271.943322 -299.111416)
		(width 0.14478)
		(layer "In11.Cu")
		(net "M_F_CPU0_SB_DQ<13>")
	)
	(segment
		(start 326.919082 -283.310076)
		(end 326.933814 -283.318712)
		(width 0.0889)
		(layer "In11.Cu")
		(net "M_F_CPU0_SB_DQ<13>")
	)
	(segment
		(start 297.237404 -298.657772)
		(end 297.237404 -298.765468)
		(width 0.14478)
		(layer "In11.Cu")
		(net "M_F_CPU0_SB_DQ<13>")
	)
	(segment
		(start 283.6164 -298.06011)
		(end 286.080708 -298.06011)
		(width 0.14478)
		(layer "In11.Cu")
		(net "M_F_CPU0_SB_DQ<13>")
	)
	(segment
		(start 304.619406 -298.765468)
		(end 304.764186 -298.910248)
		(width 0.14478)
		(layer "In11.Cu")
		(net "M_F_CPU0_SB_DQ<13>")
	)
	(segment
		(start 323.913754 -283.45638)
		(end 324.313804 -283.45638)
		(width 0.0889)
		(layer "In11.Cu")
		(net "M_F_CPU0_SB_DQ<13>")
	)
	(segment
		(start 331.634084 -283.318712)
		(end 331.642466 -283.323538)
		(width 0.0889)
		(layer "In11.Cu")
		(net "M_F_CPU0_SB_DQ<13>")
	)
	(arc
		(start 332.008226 -283.318712)
		(mid 332.291182 -283.242535)
		(end 332.574138 -283.318712)
		(width 0.0889)
		(layer "In11.Cu")
		(net "M_F_CPU0_SB_DQ<13>")
	)
	(arc
		(start 329.753976 -283.318712)
		(mid 329.936227 -283.369062)
		(end 330.119736 -283.323538)
		(width 0.0889)
		(layer "In11.Cu")
		(net "M_F_CPU0_SB_DQ<13>")
	)
	(arc
		(start 328.248264 -283.318712)
		(mid 328.53122 -283.242535)
		(end 328.814176 -283.318712)
		(width 0.0889)
		(layer "In11.Cu")
		(net "M_F_CPU0_SB_DQ<13>")
	)
	(arc
		(start 331.642466 -283.323538)
		(mid 331.825974 -283.369032)
		(end 332.008226 -283.318712)
		(width 0.0889)
		(layer "In11.Cu")
		(net "M_F_CPU0_SB_DQ<13>")
	)
	(arc
		(start 327.318116 -283.312616)
		(mid 327.596802 -283.242396)
		(end 327.873868 -283.318712)
		(width 0.0889)
		(layer "In11.Cu")
		(net "M_F_CPU0_SB_DQ<13>")
	)
	(arc
		(start 332.948026 -283.318712)
		(mid 333.230982 -283.242535)
		(end 333.513938 -283.318712)
		(width 0.0889)
		(layer "In11.Cu")
		(net "M_F_CPU0_SB_DQ<13>")
	)
	(arc
		(start 330.128118 -283.318712)
		(mid 330.411074 -283.242535)
		(end 330.69403 -283.318712)
		(width 0.0889)
		(layer "In11.Cu")
		(net "M_F_CPU0_SB_DQ<13>")
	)
	(arc
		(start 328.814176 -283.318712)
		(mid 329.00112 -283.368967)
		(end 329.188064 -283.318712)
		(width 0.0889)
		(layer "In11.Cu")
		(net "M_F_CPU0_SB_DQ<13>")
	)
	(arc
		(start 329.188064 -283.318712)
		(mid 329.47102 -283.242535)
		(end 329.753976 -283.318712)
		(width 0.0889)
		(layer "In11.Cu")
		(net "M_F_CPU0_SB_DQ<13>")
	)
	(arc
		(start 327.873868 -283.318712)
		(mid 328.061066 -283.369094)
		(end 328.248264 -283.318712)
		(width 0.0889)
		(layer "In11.Cu")
		(net "M_F_CPU0_SB_DQ<13>")
	)
	(arc
		(start 333.513938 -283.318712)
		(mid 333.670376 -283.367683)
		(end 333.832708 -283.344874)
		(width 0.0889)
		(layer "In11.Cu")
		(net "M_F_CPU0_SB_DQ<13>")
	)
	(arc
		(start 331.068172 -283.318712)
		(mid 331.351128 -283.242535)
		(end 331.634084 -283.318712)
		(width 0.0889)
		(layer "In11.Cu")
		(net "M_F_CPU0_SB_DQ<13>")
	)
	(arc
		(start 332.574138 -283.318712)
		(mid 332.761082 -283.368967)
		(end 332.948026 -283.318712)
		(width 0.0889)
		(layer "In11.Cu")
		(net "M_F_CPU0_SB_DQ<13>")
	)
	(arc
		(start 326.367902 -283.318712)
		(mid 326.642354 -283.242476)
		(end 326.919082 -283.310076)
		(width 0.0889)
		(layer "In11.Cu")
		(net "M_F_CPU0_SB_DQ<13>")
	)
	(arc
		(start 326.180704 -283.369258)
		(mid 326.277651 -283.356375)
		(end 326.367902 -283.318712)
		(width 0.0889)
		(layer "In11.Cu")
		(net "M_F_CPU0_SB_DQ<13>")
	)
	(arc
		(start 330.702412 -283.323538)
		(mid 330.88592 -283.369032)
		(end 331.068172 -283.318712)
		(width 0.0889)
		(layer "In11.Cu")
		(net "M_F_CPU0_SB_DQ<13>")
	)
	(arc
		(start 326.933814 -283.318712)
		(mid 327.120758 -283.368967)
		(end 327.307702 -283.318712)
		(width 0.0889)
		(layer "In11.Cu")
		(net "M_F_CPU0_SB_DQ<13>")
	)
	(segment
		(start 332.758034 -281.920188)
		(end 332.291182 -282.186126)
		(width 0.10668)
		(layer "F.Cu")
		(net "M_F_CPU0_SB_DQ<12>")
	)
	(segment
		(start 302.57115 -297.210226)
		(end 302.872394 -297.51147)
		(width 0.14478)
		(layer "In11.Cu")
		(net "M_F_CPU0_SB_DQ<12>")
	)
	(segment
		(start 296.993056 -297.37304)
		(end 297.156124 -297.209972)
		(width 0.14478)
		(layer "In11.Cu")
		(net "M_F_CPU0_SB_DQ<12>")
	)
	(segment
		(start 298.845986 -296.746422)
		(end 299.076364 -296.746422)
		(width 0.14478)
		(layer "In11.Cu")
		(net "M_F_CPU0_SB_DQ<12>")
	)
	(segment
		(start 287.041844 -297.608752)
		(end 287.303718 -297.608752)
		(width 0.14478)
		(layer "In11.Cu")
		(net "M_F_CPU0_SB_DQ<12>")
	)
	(segment
		(start 276.186138 -296.754042)
		(end 276.416516 -296.754042)
		(width 0.14478)
		(layer "In11.Cu")
		(net "M_F_CPU0_SB_DQ<12>")
	)
	(segment
		(start 301.061628 -296.36974)
		(end 301.902114 -297.210226)
		(width 0.14478)
		(layer "In11.Cu")
		(net "M_F_CPU0_SB_DQ<12>")
	)
	(segment
		(start 293.517574 -296.36974)
		(end 294.367458 -297.219624)
		(width 0.14478)
		(layer "In11.Cu")
		(net "M_F_CPU0_SB_DQ<12>")
	)
	(segment
		(start 291.529008 -296.746422)
		(end 291.692076 -296.583354)
		(width 0.14478)
		(layer "In11.Cu")
		(net "M_F_CPU0_SB_DQ<12>")
	)
	(segment
		(start 299.076364 -296.746422)
		(end 299.239432 -296.583354)
		(width 0.14478)
		(layer "In11.Cu")
		(net "M_F_CPU0_SB_DQ<12>")
	)
	(segment
		(start 327.765156 -282.516326)
		(end 327.778872 -282.508452)
		(width 0.0889)
		(layer "In11.Cu")
		(net "M_F_CPU0_SB_DQ<12>")
	)
	(segment
		(start 275.604732 -296.360088)
		(end 275.860002 -296.360088)
		(width 0.14478)
		(layer "In11.Cu")
		(net "M_F_CPU0_SB_DQ<12>")
	)
	(segment
		(start 286.897064 -297.364404)
		(end 286.897064 -297.463972)
		(width 0.14478)
		(layer "In11.Cu")
		(net "M_F_CPU0_SB_DQ<12>")
	)
	(segment
		(start 271.105376 -297.209972)
		(end 271.638776 -297.209972)
		(width 0.14478)
		(layer "In11.Cu")
		(net "M_F_CPU0_SB_DQ<12>")
	)
	(segment
		(start 332.445106 -282.451556)
		(end 332.291182 -282.186126)
		(width 0.0889)
		(layer "In11.Cu")
		(net "M_F_CPU0_SB_DQ<12>")
	)
	(segment
		(start 328.709782 -282.513532)
		(end 328.718164 -282.508706)
		(width 0.0889)
		(layer "In11.Cu")
		(net "M_F_CPU0_SB_DQ<12>")
	)
	(segment
		(start 281.443684 -297.37304)
		(end 281.443684 -297.439334)
		(width 0.14478)
		(layer "In11.Cu")
		(net "M_F_CPU0_SB_DQ<12>")
	)
	(segment
		(start 304.23993 -297.51147)
		(end 304.541174 -297.210226)
		(width 0.14478)
		(layer "In11.Cu")
		(net "M_F_CPU0_SB_DQ<12>")
	)
	(segment
		(start 290.972494 -296.360088)
		(end 291.135562 -296.523156)
		(width 0.14478)
		(layer "In11.Cu")
		(net "M_F_CPU0_SB_DQ<12>")
	)
	(segment
		(start 289.704526 -297.209972)
		(end 289.883088 -297.209972)
		(width 0.14478)
		(layer "In11.Cu")
		(net "M_F_CPU0_SB_DQ<12>")
	)
	(segment
		(start 279.966674 -297.364404)
		(end 280.111454 -297.219624)
		(width 0.14478)
		(layer "In11.Cu")
		(net "M_F_CPU0_SB_DQ<12>")
	)
	(segment
		(start 279.966674 -297.463972)
		(end 279.966674 -297.364404)
		(width 0.14478)
		(layer "In11.Cu")
		(net "M_F_CPU0_SB_DQ<12>")
	)
	(segment
		(start 305.576478 -297.210226)
		(end 306.771802 -296.014902)
		(width 0.14478)
		(layer "In11.Cu")
		(net "M_F_CPU0_SB_DQ<12>")
	)
	(segment
		(start 327.387204 -282.498038)
		(end 327.405238 -282.508706)
		(width 0.0889)
		(layer "In11.Cu")
		(net "M_F_CPU0_SB_DQ<12>")
	)
	(segment
		(start 302.872394 -297.51147)
		(end 303.12741 -297.51147)
		(width 0.14478)
		(layer "In11.Cu")
		(net "M_F_CPU0_SB_DQ<12>")
	)
	(segment
		(start 297.156124 -297.209972)
		(end 297.389042 -297.209972)
		(width 0.14478)
		(layer "In11.Cu")
		(net "M_F_CPU0_SB_DQ<12>")
	)
	(segment
		(start 284.115002 -296.523156)
		(end 284.268418 -296.36974)
		(width 0.14478)
		(layer "In11.Cu")
		(net "M_F_CPU0_SB_DQ<12>")
	)
	(segment
		(start 283.558488 -296.590974)
		(end 283.721556 -296.754042)
		(width 0.14478)
		(layer "In11.Cu")
		(net "M_F_CPU0_SB_DQ<12>")
	)
	(segment
		(start 329.284076 -282.508706)
		(end 329.292458 -282.513532)
		(width 0.0889)
		(layer "In11.Cu")
		(net "M_F_CPU0_SB_DQ<12>")
	)
	(segment
		(start 283.951934 -296.754042)
		(end 284.115002 -296.590974)
		(width 0.14478)
		(layer "In11.Cu")
		(net "M_F_CPU0_SB_DQ<12>")
	)
	(segment
		(start 297.389042 -297.209972)
		(end 298.238926 -296.360088)
		(width 0.14478)
		(layer "In11.Cu")
		(net "M_F_CPU0_SB_DQ<12>")
	)
	(segment
		(start 270.07312 -297.209972)
		(end 270.222726 -297.209972)
		(width 0.14478)
		(layer "In11.Cu")
		(net "M_F_CPU0_SB_DQ<12>")
	)
	(segment
		(start 303.68367 -297.210226)
		(end 303.984914 -297.51147)
		(width 0.14478)
		(layer "In11.Cu")
		(net "M_F_CPU0_SB_DQ<12>")
	)
	(segment
		(start 271.801844 -297.37304)
		(end 271.801844 -297.439334)
		(width 0.14478)
		(layer "In11.Cu")
		(net "M_F_CPU0_SB_DQ<12>")
	)
	(segment
		(start 270.942308 -297.046904)
		(end 271.105376 -297.209972)
		(width 0.14478)
		(layer "In11.Cu")
		(net "M_F_CPU0_SB_DQ<12>")
	)
	(segment
		(start 286.897064 -297.463972)
		(end 287.041844 -297.608752)
		(width 0.14478)
		(layer "In11.Cu")
		(net "M_F_CPU0_SB_DQ<12>")
	)
	(segment
		(start 304.541174 -297.210226)
		(end 305.576478 -297.210226)
		(width 0.14478)
		(layer "In11.Cu")
		(net "M_F_CPU0_SB_DQ<12>")
	)
	(segment
		(start 303.428654 -297.210226)
		(end 303.68367 -297.210226)
		(width 0.14478)
		(layer "In11.Cu")
		(net "M_F_CPU0_SB_DQ<12>")
	)
	(segment
		(start 301.902114 -297.210226)
		(end 302.57115 -297.210226)
		(width 0.14478)
		(layer "In11.Cu")
		(net "M_F_CPU0_SB_DQ<12>")
	)
	(segment
		(start 281.606752 -297.602402)
		(end 281.83713 -297.602402)
		(width 0.14478)
		(layer "In11.Cu")
		(net "M_F_CPU0_SB_DQ<12>")
	)
	(segment
		(start 283.721556 -296.754042)
		(end 283.951934 -296.754042)
		(width 0.14478)
		(layer "In11.Cu")
		(net "M_F_CPU0_SB_DQ<12>")
	)
	(segment
		(start 299.392848 -296.36974)
		(end 301.061628 -296.36974)
		(width 0.14478)
		(layer "In11.Cu")
		(net "M_F_CPU0_SB_DQ<12>")
	)
	(segment
		(start 289.541458 -297.439334)
		(end 289.541458 -297.37304)
		(width 0.14478)
		(layer "In11.Cu")
		(net "M_F_CPU0_SB_DQ<12>")
	)
	(segment
		(start 271.801844 -297.439334)
		(end 271.964912 -297.602402)
		(width 0.14478)
		(layer "In11.Cu")
		(net "M_F_CPU0_SB_DQ<12>")
	)
	(segment
		(start 271.638776 -297.209972)
		(end 271.801844 -297.37304)
		(width 0.14478)
		(layer "In11.Cu")
		(net "M_F_CPU0_SB_DQ<12>")
	)
	(segment
		(start 282.000198 -297.439334)
		(end 282.000198 -297.37304)
		(width 0.14478)
		(layer "In11.Cu")
		(net "M_F_CPU0_SB_DQ<12>")
	)
	(segment
		(start 274.048982 -297.463972)
		(end 274.193762 -297.608752)
		(width 0.14478)
		(layer "In11.Cu")
		(net "M_F_CPU0_SB_DQ<12>")
	)
	(segment
		(start 291.29863 -296.746422)
		(end 291.529008 -296.746422)
		(width 0.14478)
		(layer "In11.Cu")
		(net "M_F_CPU0_SB_DQ<12>")
	)
	(segment
		(start 270.548862 -296.479722)
		(end 270.77924 -296.479722)
		(width 0.14478)
		(layer "In11.Cu")
		(net "M_F_CPU0_SB_DQ<12>")
	)
	(segment
		(start 332.422754 -282.534868)
		(end 332.445106 -282.451556)
		(width 0.0889)
		(layer "In11.Cu")
		(net "M_F_CPU0_SB_DQ<12>")
	)
	(segment
		(start 291.135562 -296.583354)
		(end 291.29863 -296.746422)
		(width 0.14478)
		(layer "In11.Cu")
		(net "M_F_CPU0_SB_DQ<12>")
	)
	(segment
		(start 296.59961 -297.602402)
		(end 296.829988 -297.602402)
		(width 0.14478)
		(layer "In11.Cu")
		(net "M_F_CPU0_SB_DQ<12>")
	)
	(segment
		(start 282.000198 -297.37304)
		(end 282.163266 -297.209972)
		(width 0.14478)
		(layer "In11.Cu")
		(net "M_F_CPU0_SB_DQ<12>")
	)
	(segment
		(start 287.448498 -297.463972)
		(end 287.448498 -297.364404)
		(width 0.14478)
		(layer "In11.Cu")
		(net "M_F_CPU0_SB_DQ<12>")
	)
	(segment
		(start 299.239432 -296.523156)
		(end 299.392848 -296.36974)
		(width 0.14478)
		(layer "In11.Cu")
		(net "M_F_CPU0_SB_DQ<12>")
	)
	(segment
		(start 308.002686 -296.014902)
		(end 321.470528 -282.54706)
		(width 0.14478)
		(layer "In11.Cu")
		(net "M_F_CPU0_SB_DQ<12>")
	)
	(segment
		(start 281.290268 -297.219624)
		(end 281.443684 -297.37304)
		(width 0.14478)
		(layer "In11.Cu")
		(net "M_F_CPU0_SB_DQ<12>")
	)
	(segment
		(start 298.238926 -296.360088)
		(end 298.51985 -296.360088)
		(width 0.14478)
		(layer "In11.Cu")
		(net "M_F_CPU0_SB_DQ<12>")
	)
	(segment
		(start 270.942308 -296.64279)
		(end 270.942308 -297.046904)
		(width 0.14478)
		(layer "In11.Cu")
		(net "M_F_CPU0_SB_DQ<12>")
	)
	(segment
		(start 272.358358 -297.37304)
		(end 272.511774 -297.219624)
		(width 0.14478)
		(layer "In11.Cu")
		(net "M_F_CPU0_SB_DQ<12>")
	)
	(segment
		(start 275.860002 -296.360088)
		(end 276.02307 -296.523156)
		(width 0.14478)
		(layer "In11.Cu")
		(net "M_F_CPU0_SB_DQ<12>")
	)
	(segment
		(start 306.771802 -296.014902)
		(end 308.002686 -296.014902)
		(width 0.14478)
		(layer "In11.Cu")
		(net "M_F_CPU0_SB_DQ<12>")
	)
	(segment
		(start 270.385794 -297.046904)
		(end 270.385794 -296.64279)
		(width 0.14478)
		(layer "In11.Cu")
		(net "M_F_CPU0_SB_DQ<12>")
	)
	(segment
		(start 288.831528 -297.219624)
		(end 288.984944 -297.37304)
		(width 0.14478)
		(layer "In11.Cu")
		(net "M_F_CPU0_SB_DQ<12>")
	)
	(segment
		(start 279.56002 -297.608752)
		(end 279.821894 -297.608752)
		(width 0.14478)
		(layer "In11.Cu")
		(net "M_F_CPU0_SB_DQ<12>")
	)
	(segment
		(start 276.416516 -296.754042)
		(end 276.579584 -296.590974)
		(width 0.14478)
		(layer "In11.Cu")
		(net "M_F_CPU0_SB_DQ<12>")
	)
	(segment
		(start 291.845492 -296.36974)
		(end 293.517574 -296.36974)
		(width 0.14478)
		(layer "In11.Cu")
		(net "M_F_CPU0_SB_DQ<12>")
	)
	(segment
		(start 287.303718 -297.608752)
		(end 287.448498 -297.463972)
		(width 0.14478)
		(layer "In11.Cu")
		(net "M_F_CPU0_SB_DQ<12>")
	)
	(segment
		(start 298.51985 -296.360088)
		(end 298.682918 -296.523156)
		(width 0.14478)
		(layer "In11.Cu")
		(net "M_F_CPU0_SB_DQ<12>")
	)
	(segment
		(start 274.600416 -297.364404)
		(end 275.604732 -296.360088)
		(width 0.14478)
		(layer "In11.Cu")
		(net "M_F_CPU0_SB_DQ<12>")
	)
	(segment
		(start 289.541458 -297.37304)
		(end 289.704526 -297.209972)
		(width 0.14478)
		(layer "In11.Cu")
		(net "M_F_CPU0_SB_DQ<12>")
	)
	(segment
		(start 276.733 -296.36974)
		(end 278.420576 -296.36974)
		(width 0.14478)
		(layer "In11.Cu")
		(net "M_F_CPU0_SB_DQ<12>")
	)
	(segment
		(start 279.41524 -297.364404)
		(end 279.41524 -297.463972)
		(width 0.14478)
		(layer "In11.Cu")
		(net "M_F_CPU0_SB_DQ<12>")
	)
	(segment
		(start 276.02307 -296.523156)
		(end 276.02307 -296.590974)
		(width 0.14478)
		(layer "In11.Cu")
		(net "M_F_CPU0_SB_DQ<12>")
	)
	(segment
		(start 276.579584 -296.523156)
		(end 276.733 -296.36974)
		(width 0.14478)
		(layer "In11.Cu")
		(net "M_F_CPU0_SB_DQ<12>")
	)
	(segment
		(start 294.367458 -297.219624)
		(end 296.283126 -297.219624)
		(width 0.14478)
		(layer "In11.Cu")
		(net "M_F_CPU0_SB_DQ<12>")
	)
	(segment
		(start 281.443684 -297.439334)
		(end 281.606752 -297.602402)
		(width 0.14478)
		(layer "In11.Cu")
		(net "M_F_CPU0_SB_DQ<12>")
	)
	(segment
		(start 284.115002 -296.590974)
		(end 284.115002 -296.523156)
		(width 0.14478)
		(layer "In11.Cu")
		(net "M_F_CPU0_SB_DQ<12>")
	)
	(segment
		(start 279.41524 -297.463972)
		(end 279.56002 -297.608752)
		(width 0.14478)
		(layer "In11.Cu")
		(net "M_F_CPU0_SB_DQ<12>")
	)
	(segment
		(start 327.778872 -282.508452)
		(end 327.79081 -282.501594)
		(width 0.0889)
		(layer "In11.Cu")
		(net "M_F_CPU0_SB_DQ<12>")
	)
	(segment
		(start 283.39542 -296.360088)
		(end 283.558488 -296.523156)
		(width 0.14478)
		(layer "In11.Cu")
		(net "M_F_CPU0_SB_DQ<12>")
	)
	(segment
		(start 285.9024 -296.36974)
		(end 286.897064 -297.364404)
		(width 0.14478)
		(layer "In11.Cu")
		(net "M_F_CPU0_SB_DQ<12>")
	)
	(segment
		(start 278.420576 -296.36974)
		(end 279.41524 -297.364404)
		(width 0.14478)
		(layer "In11.Cu")
		(net "M_F_CPU0_SB_DQ<12>")
	)
	(segment
		(start 276.02307 -296.590974)
		(end 276.186138 -296.754042)
		(width 0.14478)
		(layer "In11.Cu")
		(net "M_F_CPU0_SB_DQ<12>")
	)
	(segment
		(start 326.20585 -282.559506)
		(end 326.651112 -282.559506)
		(width 0.0889)
		(layer "In11.Cu")
		(net "M_F_CPU0_SB_DQ<12>")
	)
	(segment
		(start 291.135562 -296.523156)
		(end 291.135562 -296.583354)
		(width 0.14478)
		(layer "In11.Cu")
		(net "M_F_CPU0_SB_DQ<12>")
	)
	(segment
		(start 296.436542 -297.439334)
		(end 296.59961 -297.602402)
		(width 0.14478)
		(layer "In11.Cu")
		(net "M_F_CPU0_SB_DQ<12>")
	)
	(segment
		(start 270.77924 -296.479722)
		(end 270.942308 -296.64279)
		(width 0.14478)
		(layer "In11.Cu")
		(net "M_F_CPU0_SB_DQ<12>")
	)
	(segment
		(start 272.19529 -297.602402)
		(end 272.358358 -297.439334)
		(width 0.14478)
		(layer "In11.Cu")
		(net "M_F_CPU0_SB_DQ<12>")
	)
	(segment
		(start 296.436542 -297.37304)
		(end 296.436542 -297.439334)
		(width 0.14478)
		(layer "In11.Cu")
		(net "M_F_CPU0_SB_DQ<12>")
	)
	(segment
		(start 321.470528 -282.54706)
		(end 323.974968 -282.54706)
		(width 0.14478)
		(layer "In11.Cu")
		(net "M_F_CPU0_SB_DQ<12>")
	)
	(segment
		(start 274.455636 -297.608752)
		(end 274.600416 -297.463972)
		(width 0.14478)
		(layer "In11.Cu")
		(net "M_F_CPU0_SB_DQ<12>")
	)
	(segment
		(start 282.323286 -297.209972)
		(end 283.17317 -296.360088)
		(width 0.14478)
		(layer "In11.Cu")
		(net "M_F_CPU0_SB_DQ<12>")
	)
	(segment
		(start 270.385794 -296.64279)
		(end 270.548862 -296.479722)
		(width 0.14478)
		(layer "In11.Cu")
		(net "M_F_CPU0_SB_DQ<12>")
	)
	(segment
		(start 323.974968 -282.54706)
		(end 324.362318 -282.15971)
		(width 0.0889)
		(layer "In11.Cu")
		(net "M_F_CPU0_SB_DQ<12>")
	)
	(segment
		(start 296.829988 -297.602402)
		(end 296.993056 -297.439334)
		(width 0.14478)
		(layer "In11.Cu")
		(net "M_F_CPU0_SB_DQ<12>")
	)
	(segment
		(start 272.358358 -297.439334)
		(end 272.358358 -297.37304)
		(width 0.14478)
		(layer "In11.Cu")
		(net "M_F_CPU0_SB_DQ<12>")
	)
	(segment
		(start 287.593278 -297.219624)
		(end 288.831528 -297.219624)
		(width 0.14478)
		(layer "In11.Cu")
		(net "M_F_CPU0_SB_DQ<12>")
	)
	(segment
		(start 288.984944 -297.439334)
		(end 289.148012 -297.602402)
		(width 0.14478)
		(layer "In11.Cu")
		(net "M_F_CPU0_SB_DQ<12>")
	)
	(segment
		(start 283.558488 -296.523156)
		(end 283.558488 -296.590974)
		(width 0.14478)
		(layer "In11.Cu")
		(net "M_F_CPU0_SB_DQ<12>")
	)
	(segment
		(start 280.111454 -297.219624)
		(end 281.290268 -297.219624)
		(width 0.14478)
		(layer "In11.Cu")
		(net "M_F_CPU0_SB_DQ<12>")
	)
	(segment
		(start 289.37839 -297.602402)
		(end 289.541458 -297.439334)
		(width 0.14478)
		(layer "In11.Cu")
		(net "M_F_CPU0_SB_DQ<12>")
	)
	(segment
		(start 282.163266 -297.209972)
		(end 282.323286 -297.209972)
		(width 0.14478)
		(layer "In11.Cu")
		(net "M_F_CPU0_SB_DQ<12>")
	)
	(segment
		(start 303.12741 -297.51147)
		(end 303.428654 -297.210226)
		(width 0.14478)
		(layer "In11.Cu")
		(net "M_F_CPU0_SB_DQ<12>")
	)
	(segment
		(start 288.984944 -297.37304)
		(end 288.984944 -297.439334)
		(width 0.14478)
		(layer "In11.Cu")
		(net "M_F_CPU0_SB_DQ<12>")
	)
	(segment
		(start 270.222726 -297.209972)
		(end 270.385794 -297.046904)
		(width 0.14478)
		(layer "In11.Cu")
		(net "M_F_CPU0_SB_DQ<12>")
	)
	(segment
		(start 290.732972 -296.360088)
		(end 290.972494 -296.360088)
		(width 0.14478)
		(layer "In11.Cu")
		(net "M_F_CPU0_SB_DQ<12>")
	)
	(segment
		(start 279.821894 -297.608752)
		(end 279.966674 -297.463972)
		(width 0.14478)
		(layer "In11.Cu")
		(net "M_F_CPU0_SB_DQ<12>")
	)
	(segment
		(start 289.883088 -297.209972)
		(end 290.732972 -296.360088)
		(width 0.14478)
		(layer "In11.Cu")
		(net "M_F_CPU0_SB_DQ<12>")
	)
	(segment
		(start 298.682918 -296.523156)
		(end 298.682918 -296.583354)
		(width 0.14478)
		(layer "In11.Cu")
		(net "M_F_CPU0_SB_DQ<12>")
	)
	(segment
		(start 296.283126 -297.219624)
		(end 296.436542 -297.37304)
		(width 0.14478)
		(layer "In11.Cu")
		(net "M_F_CPU0_SB_DQ<12>")
	)
	(segment
		(start 273.904202 -297.219624)
		(end 274.048982 -297.364404)
		(width 0.14478)
		(layer "In11.Cu")
		(net "M_F_CPU0_SB_DQ<12>")
	)
	(segment
		(start 291.692076 -296.583354)
		(end 291.692076 -296.523156)
		(width 0.14478)
		(layer "In11.Cu")
		(net "M_F_CPU0_SB_DQ<12>")
	)
	(segment
		(start 269.648178 -296.78503)
		(end 270.07312 -297.209972)
		(width 0.14478)
		(layer "In11.Cu")
		(net "M_F_CPU0_SB_DQ<12>")
	)
	(segment
		(start 284.268418 -296.36974)
		(end 285.9024 -296.36974)
		(width 0.14478)
		(layer "In11.Cu")
		(net "M_F_CPU0_SB_DQ<12>")
	)
	(segment
		(start 287.448498 -297.364404)
		(end 287.593278 -297.219624)
		(width 0.14478)
		(layer "In11.Cu")
		(net "M_F_CPU0_SB_DQ<12>")
	)
	(segment
		(start 276.579584 -296.590974)
		(end 276.579584 -296.523156)
		(width 0.14478)
		(layer "In11.Cu")
		(net "M_F_CPU0_SB_DQ<12>")
	)
	(segment
		(start 303.984914 -297.51147)
		(end 304.23993 -297.51147)
		(width 0.14478)
		(layer "In11.Cu")
		(net "M_F_CPU0_SB_DQ<12>")
	)
	(segment
		(start 299.239432 -296.583354)
		(end 299.239432 -296.523156)
		(width 0.14478)
		(layer "In11.Cu")
		(net "M_F_CPU0_SB_DQ<12>")
	)
	(segment
		(start 271.964912 -297.602402)
		(end 272.19529 -297.602402)
		(width 0.14478)
		(layer "In11.Cu")
		(net "M_F_CPU0_SB_DQ<12>")
	)
	(segment
		(start 289.148012 -297.602402)
		(end 289.37839 -297.602402)
		(width 0.14478)
		(layer "In11.Cu")
		(net "M_F_CPU0_SB_DQ<12>")
	)
	(segment
		(start 324.362318 -282.15971)
		(end 325.806054 -282.15971)
		(width 0.0889)
		(layer "In11.Cu")
		(net "M_F_CPU0_SB_DQ<12>")
	)
	(segment
		(start 291.692076 -296.523156)
		(end 291.845492 -296.36974)
		(width 0.14478)
		(layer "In11.Cu")
		(net "M_F_CPU0_SB_DQ<12>")
	)
	(segment
		(start 298.682918 -296.583354)
		(end 298.845986 -296.746422)
		(width 0.14478)
		(layer "In11.Cu")
		(net "M_F_CPU0_SB_DQ<12>")
	)
	(segment
		(start 274.600416 -297.463972)
		(end 274.600416 -297.364404)
		(width 0.14478)
		(layer "In11.Cu")
		(net "M_F_CPU0_SB_DQ<12>")
	)
	(segment
		(start 296.993056 -297.439334)
		(end 296.993056 -297.37304)
		(width 0.14478)
		(layer "In11.Cu")
		(net "M_F_CPU0_SB_DQ<12>")
	)
	(segment
		(start 281.83713 -297.602402)
		(end 282.000198 -297.439334)
		(width 0.14478)
		(layer "In11.Cu")
		(net "M_F_CPU0_SB_DQ<12>")
	)
	(segment
		(start 283.17317 -296.360088)
		(end 283.39542 -296.360088)
		(width 0.14478)
		(layer "In11.Cu")
		(net "M_F_CPU0_SB_DQ<12>")
	)
	(segment
		(start 274.193762 -297.608752)
		(end 274.455636 -297.608752)
		(width 0.14478)
		(layer "In11.Cu")
		(net "M_F_CPU0_SB_DQ<12>")
	)
	(segment
		(start 272.511774 -297.219624)
		(end 273.904202 -297.219624)
		(width 0.14478)
		(layer "In11.Cu")
		(net "M_F_CPU0_SB_DQ<12>")
	)
	(segment
		(start 274.048982 -297.364404)
		(end 274.048982 -297.463972)
		(width 0.14478)
		(layer "In11.Cu")
		(net "M_F_CPU0_SB_DQ<12>")
	)
	(segment
		(start 325.806054 -282.15971)
		(end 326.20585 -282.559506)
		(width 0.0889)
		(layer "In11.Cu")
		(net "M_F_CPU0_SB_DQ<12>")
	)
	(segment
		(start 331.52969 -282.513532)
		(end 331.538072 -282.508706)
		(width 0.0889)
		(layer "In11.Cu")
		(net "M_F_CPU0_SB_DQ<12>")
	)
	(arc
		(start 327.405238 -282.508706)
		(mid 327.584225 -282.558876)
		(end 327.765156 -282.516326)
		(width 0.0889)
		(layer "In11.Cu")
		(net "M_F_CPU0_SB_DQ<12>")
	)
	(arc
		(start 326.651112 -282.559506)
		(mid 326.748201 -282.546516)
		(end 326.838564 -282.508706)
		(width 0.0889)
		(layer "In11.Cu")
		(net "M_F_CPU0_SB_DQ<12>")
	)
	(arc
		(start 331.538072 -282.508706)
		(mid 331.821028 -282.432529)
		(end 332.103984 -282.508706)
		(width 0.0889)
		(layer "In11.Cu")
		(net "M_F_CPU0_SB_DQ<12>")
	)
	(arc
		(start 330.22413 -282.508706)
		(mid 330.411074 -282.558961)
		(end 330.598018 -282.508706)
		(width 0.0889)
		(layer "In11.Cu")
		(net "M_F_CPU0_SB_DQ<12>")
	)
	(arc
		(start 329.658218 -282.508706)
		(mid 329.941174 -282.432529)
		(end 330.22413 -282.508706)
		(width 0.0889)
		(layer "In11.Cu")
		(net "M_F_CPU0_SB_DQ<12>")
	)
	(arc
		(start 331.16393 -282.508706)
		(mid 331.346181 -282.559056)
		(end 331.52969 -282.513532)
		(width 0.0889)
		(layer "In11.Cu")
		(net "M_F_CPU0_SB_DQ<12>")
	)
	(arc
		(start 332.103984 -282.508706)
		(mid 332.260422 -282.557677)
		(end 332.422754 -282.534868)
		(width 0.0889)
		(layer "In11.Cu")
		(net "M_F_CPU0_SB_DQ<12>")
	)
	(arc
		(start 329.292458 -282.513532)
		(mid 329.475966 -282.559026)
		(end 329.658218 -282.508706)
		(width 0.0889)
		(layer "In11.Cu")
		(net "M_F_CPU0_SB_DQ<12>")
	)
	(arc
		(start 327.79081 -282.501594)
		(mid 328.068344 -282.432613)
		(end 328.344022 -282.508706)
		(width 0.0889)
		(layer "In11.Cu")
		(net "M_F_CPU0_SB_DQ<12>")
	)
	(arc
		(start 326.838564 -282.508706)
		(mid 327.111508 -282.432126)
		(end 327.387204 -282.498038)
		(width 0.0889)
		(layer "In11.Cu")
		(net "M_F_CPU0_SB_DQ<12>")
	)
	(arc
		(start 330.598018 -282.508706)
		(mid 330.880974 -282.432529)
		(end 331.16393 -282.508706)
		(width 0.0889)
		(layer "In11.Cu")
		(net "M_F_CPU0_SB_DQ<12>")
	)
	(arc
		(start 328.718164 -282.508706)
		(mid 329.00112 -282.432529)
		(end 329.284076 -282.508706)
		(width 0.0889)
		(layer "In11.Cu")
		(net "M_F_CPU0_SB_DQ<12>")
	)
	(arc
		(start 328.344022 -282.508706)
		(mid 328.526273 -282.559056)
		(end 328.709782 -282.513532)
		(width 0.0889)
		(layer "In11.Cu")
		(net "M_F_CPU0_SB_DQ<12>")
	)
	(segment
		(start 334.637888 -280.300176)
		(end 334.171036 -280.566114)
		(width 0.10668)
		(layer "F.Cu")
		(net "M_F_CPU0_SB_DQ<11>")
	)
	(segment
		(start 283.158438 -292.950392)
		(end 286.043624 -292.950392)
		(width 0.14478)
		(layer "In11.Cu")
		(net "M_F_CPU0_SB_DQ<11>")
	)
	(segment
		(start 289.84194 -293.800276)
		(end 290.691824 -292.950392)
		(width 0.14478)
		(layer "In11.Cu")
		(net "M_F_CPU0_SB_DQ<11>")
	)
	(segment
		(start 267.165328 -293.647114)
		(end 267.31849 -293.800276)
		(width 0.14478)
		(layer "In11.Cu")
		(net "M_F_CPU0_SB_DQ<11>")
	)
	(segment
		(start 316.785244 -283.393642)
		(end 319.971166 -280.20772)
		(width 0.14478)
		(layer "In11.Cu")
		(net "M_F_CPU0_SB_DQ<11>")
	)
	(segment
		(start 334.017112 -280.300684)
		(end 334.171036 -280.566114)
		(width 0.0889)
		(layer "In11.Cu")
		(net "M_F_CPU0_SB_DQ<11>")
	)
	(segment
		(start 333.044038 -280.243534)
		(end 333.05242 -280.238708)
		(width 0.0889)
		(layer "In11.Cu")
		(net "M_F_CPU0_SB_DQ<11>")
	)
	(segment
		(start 266.608814 -293.647114)
		(end 266.608814 -293.27983)
		(width 0.14478)
		(layer "In11.Cu")
		(net "M_F_CPU0_SB_DQ<11>")
	)
	(segment
		(start 267.165328 -293.27983)
		(end 267.165328 -293.647114)
		(width 0.14478)
		(layer "In11.Cu")
		(net "M_F_CPU0_SB_DQ<11>")
	)
	(segment
		(start 266.771882 -293.116762)
		(end 267.00226 -293.116762)
		(width 0.14478)
		(layer "In11.Cu")
		(net "M_F_CPU0_SB_DQ<11>")
	)
	(segment
		(start 290.691824 -292.950392)
		(end 293.54907 -292.950392)
		(width 0.14478)
		(layer "In11.Cu")
		(net "M_F_CPU0_SB_DQ<11>")
	)
	(segment
		(start 331.52969 -280.238708)
		(end 331.538072 -280.243534)
		(width 0.0889)
		(layer "In11.Cu")
		(net "M_F_CPU0_SB_DQ<11>")
	)
	(segment
		(start 294.398954 -293.800276)
		(end 297.339766 -293.800276)
		(width 0.14478)
		(layer "In11.Cu")
		(net "M_F_CPU0_SB_DQ<11>")
	)
	(segment
		(start 319.971166 -280.20772)
		(end 323.906134 -280.20772)
		(width 0.14478)
		(layer "In11.Cu")
		(net "M_F_CPU0_SB_DQ<11>")
	)
	(segment
		(start 286.893508 -293.800276)
		(end 289.84194 -293.800276)
		(width 0.14478)
		(layer "In11.Cu")
		(net "M_F_CPU0_SB_DQ<11>")
	)
	(segment
		(start 329.284076 -280.243534)
		(end 329.292458 -280.238708)
		(width 0.0889)
		(layer "In11.Cu")
		(net "M_F_CPU0_SB_DQ<11>")
	)
	(segment
		(start 324.180454 -280.12771)
		(end 327.349358 -280.12771)
		(width 0.0889)
		(layer "In11.Cu")
		(net "M_F_CPU0_SB_DQ<11>")
	)
	(segment
		(start 301.085504 -292.950392)
		(end 301.549816 -293.414704)
		(width 0.14478)
		(layer "In11.Cu")
		(net "M_F_CPU0_SB_DQ<11>")
	)
	(segment
		(start 293.54907 -292.950392)
		(end 294.398954 -293.800276)
		(width 0.14478)
		(layer "In11.Cu")
		(net "M_F_CPU0_SB_DQ<11>")
	)
	(segment
		(start 316.45606 -283.393642)
		(end 316.785244 -283.393642)
		(width 0.14478)
		(layer "In11.Cu")
		(net "M_F_CPU0_SB_DQ<11>")
	)
	(segment
		(start 286.043624 -292.950392)
		(end 286.893508 -293.800276)
		(width 0.14478)
		(layer "In11.Cu")
		(net "M_F_CPU0_SB_DQ<11>")
	)
	(segment
		(start 328.709782 -280.238708)
		(end 328.718164 -280.243534)
		(width 0.0889)
		(layer "In11.Cu")
		(net "M_F_CPU0_SB_DQ<11>")
	)
	(segment
		(start 323.906134 -280.20772)
		(end 324.100444 -280.20772)
		(width 0.0889)
		(layer "In11.Cu")
		(net "M_F_CPU0_SB_DQ<11>")
	)
	(segment
		(start 307.594 -292.68293)
		(end 308.339998 -291.936932)
		(width 0.14478)
		(layer "In11.Cu")
		(net "M_F_CPU0_SB_DQ<11>")
	)
	(segment
		(start 301.549816 -293.414704)
		(end 304.875184 -293.414704)
		(width 0.14478)
		(layer "In11.Cu")
		(net "M_F_CPU0_SB_DQ<11>")
	)
	(segment
		(start 305.606958 -292.68293)
		(end 307.594 -292.68293)
		(width 0.14478)
		(layer "In11.Cu")
		(net "M_F_CPU0_SB_DQ<11>")
	)
	(segment
		(start 278.47417 -292.950392)
		(end 279.324054 -293.800276)
		(width 0.14478)
		(layer "In11.Cu")
		(net "M_F_CPU0_SB_DQ<11>")
	)
	(segment
		(start 275.527516 -292.950392)
		(end 278.47417 -292.950392)
		(width 0.14478)
		(layer "In11.Cu")
		(net "M_F_CPU0_SB_DQ<11>")
	)
	(segment
		(start 304.875184 -293.414704)
		(end 305.606958 -292.68293)
		(width 0.14478)
		(layer "In11.Cu")
		(net "M_F_CPU0_SB_DQ<11>")
	)
	(segment
		(start 266.608814 -293.27983)
		(end 266.771882 -293.116762)
		(width 0.14478)
		(layer "In11.Cu")
		(net "M_F_CPU0_SB_DQ<11>")
	)
	(segment
		(start 333.9211 -280.275284)
		(end 334.017112 -280.300684)
		(width 0.0889)
		(layer "In11.Cu")
		(net "M_F_CPU0_SB_DQ<11>")
	)
	(segment
		(start 267.31849 -293.800276)
		(end 274.677632 -293.800276)
		(width 0.14478)
		(layer "In11.Cu")
		(net "M_F_CPU0_SB_DQ<11>")
	)
	(segment
		(start 298.18965 -292.950392)
		(end 301.085504 -292.950392)
		(width 0.14478)
		(layer "In11.Cu")
		(net "M_F_CPU0_SB_DQ<11>")
	)
	(segment
		(start 328.333608 -280.24963)
		(end 328.344022 -280.243534)
		(width 0.0889)
		(layer "In11.Cu")
		(net "M_F_CPU0_SB_DQ<11>")
	)
	(segment
		(start 266.445746 -293.810182)
		(end 266.608814 -293.647114)
		(width 0.14478)
		(layer "In11.Cu")
		(net "M_F_CPU0_SB_DQ<11>")
	)
	(segment
		(start 265.973306 -293.810182)
		(end 266.445746 -293.810182)
		(width 0.14478)
		(layer "In11.Cu")
		(net "M_F_CPU0_SB_DQ<11>")
	)
	(segment
		(start 308.339998 -291.509704)
		(end 316.45606 -283.393642)
		(width 0.14478)
		(layer "In11.Cu")
		(net "M_F_CPU0_SB_DQ<11>")
	)
	(segment
		(start 267.00226 -293.116762)
		(end 267.165328 -293.27983)
		(width 0.14478)
		(layer "In11.Cu")
		(net "M_F_CPU0_SB_DQ<11>")
	)
	(segment
		(start 265.54811 -293.384986)
		(end 265.973306 -293.810182)
		(width 0.14478)
		(layer "In11.Cu")
		(net "M_F_CPU0_SB_DQ<11>")
	)
	(segment
		(start 282.308554 -293.800276)
		(end 283.158438 -292.950392)
		(width 0.14478)
		(layer "In11.Cu")
		(net "M_F_CPU0_SB_DQ<11>")
	)
	(segment
		(start 279.324054 -293.800276)
		(end 282.308554 -293.800276)
		(width 0.14478)
		(layer "In11.Cu")
		(net "M_F_CPU0_SB_DQ<11>")
	)
	(segment
		(start 274.677632 -293.800276)
		(end 275.527516 -292.950392)
		(width 0.14478)
		(layer "In11.Cu")
		(net "M_F_CPU0_SB_DQ<11>")
	)
	(segment
		(start 324.100444 -280.20772)
		(end 324.180454 -280.12771)
		(width 0.0889)
		(layer "In11.Cu")
		(net "M_F_CPU0_SB_DQ<11>")
	)
	(segment
		(start 297.339766 -293.800276)
		(end 298.18965 -292.950392)
		(width 0.14478)
		(layer "In11.Cu")
		(net "M_F_CPU0_SB_DQ<11>")
	)
	(segment
		(start 308.339998 -291.936932)
		(end 308.339998 -291.509704)
		(width 0.14478)
		(layer "In11.Cu")
		(net "M_F_CPU0_SB_DQ<11>")
	)
	(segment
		(start 332.469744 -280.238708)
		(end 332.478126 -280.243534)
		(width 0.0889)
		(layer "In11.Cu")
		(net "M_F_CPU0_SB_DQ<11>")
	)
	(arc
		(start 327.349358 -280.12771)
		(mid 327.571302 -280.157165)
		(end 327.777856 -280.243534)
		(width 0.0889)
		(layer "In11.Cu")
		(net "M_F_CPU0_SB_DQ<11>")
	)
	(arc
		(start 329.658218 -280.243534)
		(mid 329.941174 -280.319711)
		(end 330.22413 -280.243534)
		(width 0.0889)
		(layer "In11.Cu")
		(net "M_F_CPU0_SB_DQ<11>")
	)
	(arc
		(start 331.538072 -280.243534)
		(mid 331.821028 -280.319711)
		(end 332.103984 -280.243534)
		(width 0.0889)
		(layer "In11.Cu")
		(net "M_F_CPU0_SB_DQ<11>")
	)
	(arc
		(start 328.718164 -280.243534)
		(mid 329.00112 -280.319711)
		(end 329.284076 -280.243534)
		(width 0.0889)
		(layer "In11.Cu")
		(net "M_F_CPU0_SB_DQ<11>")
	)
	(arc
		(start 330.598018 -280.243534)
		(mid 330.880974 -280.319711)
		(end 331.16393 -280.243534)
		(width 0.0889)
		(layer "In11.Cu")
		(net "M_F_CPU0_SB_DQ<11>")
	)
	(arc
		(start 332.103984 -280.243534)
		(mid 332.286235 -280.193184)
		(end 332.469744 -280.238708)
		(width 0.0889)
		(layer "In11.Cu")
		(net "M_F_CPU0_SB_DQ<11>")
	)
	(arc
		(start 329.292458 -280.238708)
		(mid 329.475966 -280.193214)
		(end 329.658218 -280.243534)
		(width 0.0889)
		(layer "In11.Cu")
		(net "M_F_CPU0_SB_DQ<11>")
	)
	(arc
		(start 333.41818 -280.243534)
		(mid 333.665893 -280.318754)
		(end 333.9211 -280.275284)
		(width 0.0889)
		(layer "In11.Cu")
		(net "M_F_CPU0_SB_DQ<11>")
	)
	(arc
		(start 327.777856 -280.243534)
		(mid 328.054923 -280.319805)
		(end 328.333608 -280.24963)
		(width 0.0889)
		(layer "In11.Cu")
		(net "M_F_CPU0_SB_DQ<11>")
	)
	(arc
		(start 328.344022 -280.243534)
		(mid 328.526273 -280.193184)
		(end 328.709782 -280.238708)
		(width 0.0889)
		(layer "In11.Cu")
		(net "M_F_CPU0_SB_DQ<11>")
	)
	(arc
		(start 333.05242 -280.238708)
		(mid 333.235928 -280.193214)
		(end 333.41818 -280.243534)
		(width 0.0889)
		(layer "In11.Cu")
		(net "M_F_CPU0_SB_DQ<11>")
	)
	(arc
		(start 332.478126 -280.243534)
		(mid 332.761082 -280.319711)
		(end 333.044038 -280.243534)
		(width 0.0889)
		(layer "In11.Cu")
		(net "M_F_CPU0_SB_DQ<11>")
	)
	(arc
		(start 331.16393 -280.243534)
		(mid 331.346181 -280.193184)
		(end 331.52969 -280.238708)
		(width 0.0889)
		(layer "In11.Cu")
		(net "M_F_CPU0_SB_DQ<11>")
	)
	(arc
		(start 330.22413 -280.243534)
		(mid 330.411074 -280.193279)
		(end 330.598018 -280.243534)
		(width 0.0889)
		(layer "In11.Cu")
		(net "M_F_CPU0_SB_DQ<11>")
	)
	(segment
		(start 333.227934 -279.49017)
		(end 332.761082 -279.756108)
		(width 0.10668)
		(layer "F.Cu")
		(net "M_F_CPU0_SB_DQ<10>")
	)
	(segment
		(start 293.27602 -291.260022)
		(end 294.126158 -292.11016)
		(width 0.14478)
		(layer "In11.Cu")
		(net "M_F_CPU0_SB_DQ<10>")
	)
	(segment
		(start 330.119736 -279.428702)
		(end 330.128118 -279.433528)
		(width 0.0889)
		(layer "In11.Cu")
		(net "M_F_CPU0_SB_DQ<10>")
	)
	(segment
		(start 266.86764 -291.96538)
		(end 266.86764 -291.494972)
		(width 0.14478)
		(layer "In11.Cu")
		(net "M_F_CPU0_SB_DQ<10>")
	)
	(segment
		(start 325.954898 -279.04694)
		(end 326.252586 -279.344628)
		(width 0.0889)
		(layer "In11.Cu")
		(net "M_F_CPU0_SB_DQ<10>")
	)
	(segment
		(start 301.152052 -291.260022)
		(end 302.00219 -292.11016)
		(width 0.14478)
		(layer "In11.Cu")
		(net "M_F_CPU0_SB_DQ<10>")
	)
	(segment
		(start 266.86764 -291.494972)
		(end 267.01242 -291.350192)
		(width 0.14478)
		(layer "In11.Cu")
		(net "M_F_CPU0_SB_DQ<10>")
	)
	(segment
		(start 282.581858 -292.11016)
		(end 283.431996 -291.260022)
		(width 0.14478)
		(layer "In11.Cu")
		(net "M_F_CPU0_SB_DQ<10>")
	)
	(segment
		(start 285.8389 -291.260022)
		(end 286.689038 -292.11016)
		(width 0.14478)
		(layer "In11.Cu")
		(net "M_F_CPU0_SB_DQ<10>")
	)
	(segment
		(start 279.114758 -292.11016)
		(end 282.581858 -292.11016)
		(width 0.14478)
		(layer "In11.Cu")
		(net "M_F_CPU0_SB_DQ<10>")
	)
	(segment
		(start 298.224956 -291.260022)
		(end 301.152052 -291.260022)
		(width 0.14478)
		(layer "In11.Cu")
		(net "M_F_CPU0_SB_DQ<10>")
	)
	(segment
		(start 290.822888 -291.260022)
		(end 293.27602 -291.260022)
		(width 0.14478)
		(layer "In11.Cu")
		(net "M_F_CPU0_SB_DQ<10>")
	)
	(segment
		(start 278.26462 -291.260022)
		(end 279.114758 -292.11016)
		(width 0.14478)
		(layer "In11.Cu")
		(net "M_F_CPU0_SB_DQ<10>")
	)
	(segment
		(start 275.01215 -292.11016)
		(end 275.862288 -291.260022)
		(width 0.14478)
		(layer "In11.Cu")
		(net "M_F_CPU0_SB_DQ<10>")
	)
	(segment
		(start 330.69403 -279.433528)
		(end 330.702412 -279.428702)
		(width 0.0889)
		(layer "In11.Cu")
		(net "M_F_CPU0_SB_DQ<10>")
	)
	(segment
		(start 326.368918 -279.433782)
		(end 326.390508 -279.446228)
		(width 0.0889)
		(layer "In11.Cu")
		(net "M_F_CPU0_SB_DQ<10>")
	)
	(segment
		(start 327.862438 -279.44064)
		(end 327.874376 -279.433782)
		(width 0.0889)
		(layer "In11.Cu")
		(net "M_F_CPU0_SB_DQ<10>")
	)
	(segment
		(start 268.115288 -291.350192)
		(end 268.377162 -291.350192)
		(width 0.14478)
		(layer "In11.Cu")
		(net "M_F_CPU0_SB_DQ<10>")
	)
	(segment
		(start 267.825728 -292.11016)
		(end 267.970508 -291.96538)
		(width 0.14478)
		(layer "In11.Cu")
		(net "M_F_CPU0_SB_DQ<10>")
	)
	(segment
		(start 327.297542 -279.42667)
		(end 327.309226 -279.433528)
		(width 0.0889)
		(layer "In11.Cu")
		(net "M_F_CPU0_SB_DQ<10>")
	)
	(segment
		(start 283.431996 -291.260022)
		(end 285.8389 -291.260022)
		(width 0.14478)
		(layer "In11.Cu")
		(net "M_F_CPU0_SB_DQ<10>")
	)
	(segment
		(start 324.318884 -279.2984)
		(end 324.570344 -279.04694)
		(width 0.0889)
		(layer "In11.Cu")
		(net "M_F_CPU0_SB_DQ<10>")
	)
	(segment
		(start 319.279016 -279.2984)
		(end 324.318884 -279.2984)
		(width 0.14478)
		(layer "In11.Cu")
		(net "M_F_CPU0_SB_DQ<10>")
	)
	(segment
		(start 267.419074 -291.96538)
		(end 267.563854 -292.11016)
		(width 0.14478)
		(layer "In11.Cu")
		(net "M_F_CPU0_SB_DQ<10>")
	)
	(segment
		(start 265.973306 -292.11016)
		(end 266.72286 -292.11016)
		(width 0.14478)
		(layer "In11.Cu")
		(net "M_F_CPU0_SB_DQ<10>")
	)
	(segment
		(start 267.563854 -292.11016)
		(end 267.825728 -292.11016)
		(width 0.14478)
		(layer "In11.Cu")
		(net "M_F_CPU0_SB_DQ<10>")
	)
	(segment
		(start 307.317394 -291.260022)
		(end 319.279016 -279.2984)
		(width 0.14478)
		(layer "In11.Cu")
		(net "M_F_CPU0_SB_DQ<10>")
	)
	(segment
		(start 332.511146 -279.465278)
		(end 332.607158 -279.490678)
		(width 0.0889)
		(layer "In11.Cu")
		(net "M_F_CPU0_SB_DQ<10>")
	)
	(segment
		(start 286.689038 -292.11016)
		(end 289.97275 -292.11016)
		(width 0.14478)
		(layer "In11.Cu")
		(net "M_F_CPU0_SB_DQ<10>")
	)
	(segment
		(start 289.97275 -292.11016)
		(end 290.822888 -291.260022)
		(width 0.14478)
		(layer "In11.Cu")
		(net "M_F_CPU0_SB_DQ<10>")
	)
	(segment
		(start 265.54811 -291.684964)
		(end 265.973306 -292.11016)
		(width 0.14478)
		(layer "In11.Cu")
		(net "M_F_CPU0_SB_DQ<10>")
	)
	(segment
		(start 268.521942 -291.96538)
		(end 268.666722 -292.11016)
		(width 0.14478)
		(layer "In11.Cu")
		(net "M_F_CPU0_SB_DQ<10>")
	)
	(segment
		(start 268.377162 -291.350192)
		(end 268.521942 -291.494972)
		(width 0.14478)
		(layer "In11.Cu")
		(net "M_F_CPU0_SB_DQ<10>")
	)
	(segment
		(start 304.893218 -292.11016)
		(end 305.743356 -291.260022)
		(width 0.14478)
		(layer "In11.Cu")
		(net "M_F_CPU0_SB_DQ<10>")
	)
	(segment
		(start 297.374818 -292.11016)
		(end 298.224956 -291.260022)
		(width 0.14478)
		(layer "In11.Cu")
		(net "M_F_CPU0_SB_DQ<10>")
	)
	(segment
		(start 267.419074 -291.494972)
		(end 267.419074 -291.96538)
		(width 0.14478)
		(layer "In11.Cu")
		(net "M_F_CPU0_SB_DQ<10>")
	)
	(segment
		(start 267.274294 -291.350192)
		(end 267.419074 -291.494972)
		(width 0.14478)
		(layer "In11.Cu")
		(net "M_F_CPU0_SB_DQ<10>")
	)
	(segment
		(start 332.607158 -279.490678)
		(end 332.761082 -279.756108)
		(width 0.0889)
		(layer "In11.Cu")
		(net "M_F_CPU0_SB_DQ<10>")
	)
	(segment
		(start 267.01242 -291.350192)
		(end 267.274294 -291.350192)
		(width 0.14478)
		(layer "In11.Cu")
		(net "M_F_CPU0_SB_DQ<10>")
	)
	(segment
		(start 331.634084 -279.433528)
		(end 331.642466 -279.428702)
		(width 0.0889)
		(layer "In11.Cu")
		(net "M_F_CPU0_SB_DQ<10>")
	)
	(segment
		(start 294.126158 -292.11016)
		(end 297.374818 -292.11016)
		(width 0.14478)
		(layer "In11.Cu")
		(net "M_F_CPU0_SB_DQ<10>")
	)
	(segment
		(start 327.874376 -279.433782)
		(end 327.890632 -279.424384)
		(width 0.0889)
		(layer "In11.Cu")
		(net "M_F_CPU0_SB_DQ<10>")
	)
	(segment
		(start 275.862288 -291.260022)
		(end 278.26462 -291.260022)
		(width 0.14478)
		(layer "In11.Cu")
		(net "M_F_CPU0_SB_DQ<10>")
	)
	(segment
		(start 302.00219 -292.11016)
		(end 304.893218 -292.11016)
		(width 0.14478)
		(layer "In11.Cu")
		(net "M_F_CPU0_SB_DQ<10>")
	)
	(segment
		(start 267.970508 -291.96538)
		(end 267.970508 -291.494972)
		(width 0.14478)
		(layer "In11.Cu")
		(net "M_F_CPU0_SB_DQ<10>")
	)
	(segment
		(start 267.970508 -291.494972)
		(end 268.115288 -291.350192)
		(width 0.14478)
		(layer "In11.Cu")
		(net "M_F_CPU0_SB_DQ<10>")
	)
	(segment
		(start 324.570344 -279.04694)
		(end 325.954898 -279.04694)
		(width 0.0889)
		(layer "In11.Cu")
		(net "M_F_CPU0_SB_DQ<10>")
	)
	(segment
		(start 266.72286 -292.11016)
		(end 266.86764 -291.96538)
		(width 0.14478)
		(layer "In11.Cu")
		(net "M_F_CPU0_SB_DQ<10>")
	)
	(segment
		(start 305.743356 -291.260022)
		(end 307.317394 -291.260022)
		(width 0.14478)
		(layer "In11.Cu")
		(net "M_F_CPU0_SB_DQ<10>")
	)
	(segment
		(start 268.521942 -291.494972)
		(end 268.521942 -291.96538)
		(width 0.14478)
		(layer "In11.Cu")
		(net "M_F_CPU0_SB_DQ<10>")
	)
	(segment
		(start 268.666722 -292.11016)
		(end 275.01215 -292.11016)
		(width 0.14478)
		(layer "In11.Cu")
		(net "M_F_CPU0_SB_DQ<10>")
	)
	(arc
		(start 328.248264 -279.433528)
		(mid 328.53122 -279.509705)
		(end 328.814176 -279.433528)
		(width 0.0889)
		(layer "In11.Cu")
		(net "M_F_CPU0_SB_DQ<10>")
	)
	(arc
		(start 326.93483 -279.433528)
		(mid 327.115288 -279.383084)
		(end 327.297542 -279.42667)
		(width 0.0889)
		(layer "In11.Cu")
		(net "M_F_CPU0_SB_DQ<10>")
	)
	(arc
		(start 326.390508 -279.446228)
		(mid 326.664298 -279.509899)
		(end 326.93483 -279.433528)
		(width 0.0889)
		(layer "In11.Cu")
		(net "M_F_CPU0_SB_DQ<10>")
	)
	(arc
		(start 327.309226 -279.433528)
		(mid 327.584904 -279.509658)
		(end 327.862438 -279.44064)
		(width 0.0889)
		(layer "In11.Cu")
		(net "M_F_CPU0_SB_DQ<10>")
	)
	(arc
		(start 331.068172 -279.433528)
		(mid 331.351128 -279.509705)
		(end 331.634084 -279.433528)
		(width 0.0889)
		(layer "In11.Cu")
		(net "M_F_CPU0_SB_DQ<10>")
	)
	(arc
		(start 330.128118 -279.433528)
		(mid 330.411074 -279.509705)
		(end 330.69403 -279.433528)
		(width 0.0889)
		(layer "In11.Cu")
		(net "M_F_CPU0_SB_DQ<10>")
	)
	(arc
		(start 330.702412 -279.428702)
		(mid 330.88592 -279.383208)
		(end 331.068172 -279.433528)
		(width 0.0889)
		(layer "In11.Cu")
		(net "M_F_CPU0_SB_DQ<10>")
	)
	(arc
		(start 329.753976 -279.433528)
		(mid 329.936227 -279.383178)
		(end 330.119736 -279.428702)
		(width 0.0889)
		(layer "In11.Cu")
		(net "M_F_CPU0_SB_DQ<10>")
	)
	(arc
		(start 326.252586 -279.344628)
		(mid 326.307836 -279.39301)
		(end 326.368918 -279.433782)
		(width 0.0889)
		(layer "In11.Cu")
		(net "M_F_CPU0_SB_DQ<10>")
	)
	(arc
		(start 328.814176 -279.433528)
		(mid 329.00112 -279.383273)
		(end 329.188064 -279.433528)
		(width 0.0889)
		(layer "In11.Cu")
		(net "M_F_CPU0_SB_DQ<10>")
	)
	(arc
		(start 327.890632 -279.424384)
		(mid 328.070614 -279.383284)
		(end 328.248264 -279.433528)
		(width 0.0889)
		(layer "In11.Cu")
		(net "M_F_CPU0_SB_DQ<10>")
	)
	(arc
		(start 329.188064 -279.433528)
		(mid 329.47102 -279.509705)
		(end 329.753976 -279.433528)
		(width 0.0889)
		(layer "In11.Cu")
		(net "M_F_CPU0_SB_DQ<10>")
	)
	(arc
		(start 331.642466 -279.428702)
		(mid 331.825974 -279.383208)
		(end 332.008226 -279.433528)
		(width 0.0889)
		(layer "In11.Cu")
		(net "M_F_CPU0_SB_DQ<10>")
	)
	(arc
		(start 332.008226 -279.433528)
		(mid 332.255939 -279.508748)
		(end 332.511146 -279.465278)
		(width 0.0889)
		(layer "In11.Cu")
		(net "M_F_CPU0_SB_DQ<10>")
	)
	(segment
		(start 332.758034 -273.820128)
		(end 332.291182 -274.086066)
		(width 0.10668)
		(layer "F.Cu")
		(net "M_F_CPU0_SB_DQ<0>")
	)
	(segment
		(start 327.778872 -274.408392)
		(end 327.79081 -274.401534)
		(width 0.0889)
		(layer "In11.Cu")
		(net "M_F_CPU0_SB_DQ<0>")
	)
	(segment
		(start 271.973548 -282.141676)
		(end 271.973548 -281.78252)
		(width 0.14478)
		(layer "In11.Cu")
		(net "M_F_CPU0_SB_DQ<0>")
	)
	(segment
		(start 304.80381 -281.910028)
		(end 305.653948 -281.05989)
		(width 0.14478)
		(layer "In11.Cu")
		(net "M_F_CPU0_SB_DQ<0>")
	)
	(segment
		(start 274.620228 -282.29179)
		(end 275.852128 -281.05989)
		(width 0.14478)
		(layer "In11.Cu")
		(net "M_F_CPU0_SB_DQ<0>")
	)
	(segment
		(start 273.833336 -281.61869)
		(end 274.063968 -281.61869)
		(width 0.14478)
		(layer "In11.Cu")
		(net "M_F_CPU0_SB_DQ<0>")
	)
	(segment
		(start 312.88355 -275.376132)
		(end 312.946796 -275.439378)
		(width 0.14478)
		(layer "In11.Cu")
		(net "M_F_CPU0_SB_DQ<0>")
	)
	(segment
		(start 312.166508 -276.219666)
		(end 312.371232 -276.219412)
		(width 0.14478)
		(layer "In11.Cu")
		(net "M_F_CPU0_SB_DQ<0>")
	)
	(segment
		(start 311.38622 -276.999954)
		(end 311.590944 -276.9997)
		(width 0.14478)
		(layer "In11.Cu")
		(net "M_F_CPU0_SB_DQ<0>")
	)
	(segment
		(start 270.861028 -282.141676)
		(end 270.861028 -281.78252)
		(width 0.14478)
		(layer "In11.Cu")
		(net "M_F_CPU0_SB_DQ<0>")
	)
	(segment
		(start 309.372 -278.682958)
		(end 309.557674 -278.497284)
		(width 0.14478)
		(layer "In11.Cu")
		(net "M_F_CPU0_SB_DQ<0>")
	)
	(segment
		(start 310.996076 -277.594568)
		(end 310.996076 -277.389844)
		(width 0.14478)
		(layer "In11.Cu")
		(net "M_F_CPU0_SB_DQ<0>")
	)
	(segment
		(start 331.52969 -274.413472)
		(end 331.538072 -274.408646)
		(width 0.0889)
		(layer "In11.Cu")
		(net "M_F_CPU0_SB_DQ<0>")
	)
	(segment
		(start 311.590944 -276.9997)
		(end 311.776364 -276.81428)
		(width 0.14478)
		(layer "In11.Cu")
		(net "M_F_CPU0_SB_DQ<0>")
	)
	(segment
		(start 291.092128 -281.05989)
		(end 293.15918 -281.05989)
		(width 0.14478)
		(layer "In11.Cu")
		(net "M_F_CPU0_SB_DQ<0>")
	)
	(segment
		(start 294.009318 -281.910028)
		(end 297.420538 -281.910028)
		(width 0.14478)
		(layer "In11.Cu")
		(net "M_F_CPU0_SB_DQ<0>")
	)
	(segment
		(start 272.366994 -281.619706)
		(end 272.657316 -281.910028)
		(width 0.14478)
		(layer "In11.Cu")
		(net "M_F_CPU0_SB_DQ<0>")
	)
	(segment
		(start 271.417288 -281.78252)
		(end 271.417288 -282.141676)
		(width 0.14478)
		(layer "In11.Cu")
		(net "M_F_CPU0_SB_DQ<0>")
	)
	(segment
		(start 274.389596 -282.29179)
		(end 274.620228 -282.29179)
		(width 0.14478)
		(layer "In11.Cu")
		(net "M_F_CPU0_SB_DQ<0>")
	)
	(segment
		(start 283.817568 -281.20467)
		(end 283.962348 -281.34945)
		(width 0.14478)
		(layer "In11.Cu")
		(net "M_F_CPU0_SB_DQ<0>")
	)
	(segment
		(start 274.226782 -281.781504)
		(end 274.226782 -282.128976)
		(width 0.14478)
		(layer "In11.Cu")
		(net "M_F_CPU0_SB_DQ<0>")
	)
	(segment
		(start 271.810734 -282.30449)
		(end 271.973548 -282.141676)
		(width 0.14478)
		(layer "In11.Cu")
		(net "M_F_CPU0_SB_DQ<0>")
	)
	(segment
		(start 283.962348 -281.34945)
		(end 284.229048 -281.34945)
		(width 0.14478)
		(layer "In11.Cu")
		(net "M_F_CPU0_SB_DQ<0>")
	)
	(segment
		(start 298.270676 -281.05989)
		(end 300.80458 -281.05989)
		(width 0.14478)
		(layer "In11.Cu")
		(net "M_F_CPU0_SB_DQ<0>")
	)
	(segment
		(start 293.15918 -281.05989)
		(end 294.009318 -281.910028)
		(width 0.14478)
		(layer "In11.Cu")
		(net "M_F_CPU0_SB_DQ<0>")
	)
	(segment
		(start 309.372254 -278.887174)
		(end 309.372 -278.682958)
		(width 0.14478)
		(layer "In11.Cu")
		(net "M_F_CPU0_SB_DQ<0>")
	)
	(segment
		(start 289.855402 -282.296616)
		(end 291.092128 -281.05989)
		(width 0.14478)
		(layer "In11.Cu")
		(net "M_F_CPU0_SB_DQ<0>")
	)
	(segment
		(start 270.861028 -281.78252)
		(end 271.023842 -281.619706)
		(width 0.14478)
		(layer "In11.Cu")
		(net "M_F_CPU0_SB_DQ<0>")
	)
	(segment
		(start 310.542686 -277.716996)
		(end 310.605932 -277.780242)
		(width 0.14478)
		(layer "In11.Cu")
		(net "M_F_CPU0_SB_DQ<0>")
	)
	(segment
		(start 311.322974 -276.936708)
		(end 311.38622 -276.999954)
		(width 0.14478)
		(layer "In11.Cu")
		(net "M_F_CPU0_SB_DQ<0>")
	)
	(segment
		(start 283.672788 -280.77033)
		(end 283.817568 -280.91511)
		(width 0.14478)
		(layer "In11.Cu")
		(net "M_F_CPU0_SB_DQ<0>")
	)
	(segment
		(start 310.93283 -277.326598)
		(end 310.932576 -277.122382)
		(width 0.14478)
		(layer "In11.Cu")
		(net "M_F_CPU0_SB_DQ<0>")
	)
	(segment
		(start 301.654718 -281.910028)
		(end 304.80381 -281.910028)
		(width 0.14478)
		(layer "In11.Cu")
		(net "M_F_CPU0_SB_DQ<0>")
	)
	(segment
		(start 326.464676 -274.408392)
		(end 326.484742 -274.419822)
		(width 0.0889)
		(layer "In11.Cu")
		(net "M_F_CPU0_SB_DQ<0>")
	)
	(segment
		(start 297.420538 -281.910028)
		(end 298.270676 -281.05989)
		(width 0.14478)
		(layer "In11.Cu")
		(net "M_F_CPU0_SB_DQ<0>")
	)
	(segment
		(start 278.52878 -281.05989)
		(end 279.378918 -281.910028)
		(width 0.14478)
		(layer "In11.Cu")
		(net "M_F_CPU0_SB_DQ<0>")
	)
	(segment
		(start 312.103262 -276.15642)
		(end 312.166508 -276.219666)
		(width 0.14478)
		(layer "In11.Cu")
		(net "M_F_CPU0_SB_DQ<0>")
	)
	(segment
		(start 310.337962 -277.716996)
		(end 310.542686 -277.716996)
		(width 0.14478)
		(layer "In11.Cu")
		(net "M_F_CPU0_SB_DQ<0>")
	)
	(segment
		(start 309.557674 -278.497284)
		(end 309.762398 -278.497284)
		(width 0.14478)
		(layer "In11.Cu")
		(net "M_F_CPU0_SB_DQ<0>")
	)
	(segment
		(start 285.58998 -281.05989)
		(end 286.825944 -282.295854)
		(width 0.14478)
		(layer "In11.Cu")
		(net "M_F_CPU0_SB_DQ<0>")
	)
	(segment
		(start 309.4355 -278.95042)
		(end 309.372254 -278.887174)
		(width 0.14478)
		(layer "In11.Cu")
		(net "M_F_CPU0_SB_DQ<0>")
	)
	(segment
		(start 271.254474 -281.619706)
		(end 271.417288 -281.78252)
		(width 0.14478)
		(layer "In11.Cu")
		(net "M_F_CPU0_SB_DQ<0>")
	)
	(segment
		(start 309.825644 -278.56053)
		(end 310.030368 -278.560276)
		(width 0.14478)
		(layer "In11.Cu")
		(net "M_F_CPU0_SB_DQ<0>")
	)
	(segment
		(start 270.698214 -282.30449)
		(end 270.861028 -282.141676)
		(width 0.14478)
		(layer "In11.Cu")
		(net "M_F_CPU0_SB_DQ<0>")
	)
	(segment
		(start 271.023842 -281.619706)
		(end 271.254474 -281.619706)
		(width 0.14478)
		(layer "In11.Cu")
		(net "M_F_CPU0_SB_DQ<0>")
	)
	(segment
		(start 311.712864 -276.342094)
		(end 311.898538 -276.15642)
		(width 0.14478)
		(layer "In11.Cu")
		(net "M_F_CPU0_SB_DQ<0>")
	)
	(segment
		(start 326.387206 -274.349718)
		(end 326.38746 -274.349718)
		(width 0.0889)
		(layer "In11.Cu")
		(net "M_F_CPU0_SB_DQ<0>")
	)
	(segment
		(start 329.284076 -274.408646)
		(end 329.292458 -274.413472)
		(width 0.0889)
		(layer "In11.Cu")
		(net "M_F_CPU0_SB_DQ<0>")
	)
	(segment
		(start 324.917054 -273.47291)
		(end 325.510398 -273.47291)
		(width 0.0889)
		(layer "In11.Cu")
		(net "M_F_CPU0_SB_DQ<0>")
	)
	(segment
		(start 289.461956 -282.133802)
		(end 289.62477 -282.296616)
		(width 0.14478)
		(layer "In11.Cu")
		(net "M_F_CPU0_SB_DQ<0>")
	)
	(segment
		(start 311.898538 -276.15642)
		(end 312.103262 -276.15642)
		(width 0.14478)
		(layer "In11.Cu")
		(net "M_F_CPU0_SB_DQ<0>")
	)
	(segment
		(start 312.556652 -276.033992)
		(end 312.556652 -275.829268)
		(width 0.14478)
		(layer "In11.Cu")
		(net "M_F_CPU0_SB_DQ<0>")
	)
	(segment
		(start 310.605932 -277.780242)
		(end 310.810656 -277.779988)
		(width 0.14478)
		(layer "In11.Cu")
		(net "M_F_CPU0_SB_DQ<0>")
	)
	(segment
		(start 312.678826 -275.376132)
		(end 312.88355 -275.376132)
		(width 0.14478)
		(layer "In11.Cu")
		(net "M_F_CPU0_SB_DQ<0>")
	)
	(segment
		(start 289.297364 -281.618436)
		(end 289.461956 -281.783028)
		(width 0.14478)
		(layer "In11.Cu")
		(net "M_F_CPU0_SB_DQ<0>")
	)
	(segment
		(start 323.927724 -273.22018)
		(end 324.664324 -273.22018)
		(width 0.0889)
		(layer "In11.Cu")
		(net "M_F_CPU0_SB_DQ<0>")
	)
	(segment
		(start 287.21939 -281.780488)
		(end 287.382204 -281.617674)
		(width 0.14478)
		(layer "In11.Cu")
		(net "M_F_CPU0_SB_DQ<0>")
	)
	(segment
		(start 307.530754 -281.05989)
		(end 309.4355 -279.155144)
		(width 0.14478)
		(layer "In11.Cu")
		(net "M_F_CPU0_SB_DQ<0>")
	)
	(segment
		(start 310.810656 -277.779988)
		(end 310.996076 -277.594568)
		(width 0.14478)
		(layer "In11.Cu")
		(net "M_F_CPU0_SB_DQ<0>")
	)
	(segment
		(start 272.657316 -281.910028)
		(end 273.541998 -281.910028)
		(width 0.14478)
		(layer "In11.Cu")
		(net "M_F_CPU0_SB_DQ<0>")
	)
	(segment
		(start 311.713118 -276.54631)
		(end 311.712864 -276.342094)
		(width 0.14478)
		(layer "In11.Cu")
		(net "M_F_CPU0_SB_DQ<0>")
	)
	(segment
		(start 287.21939 -282.13304)
		(end 287.21939 -281.780488)
		(width 0.14478)
		(layer "In11.Cu")
		(net "M_F_CPU0_SB_DQ<0>")
	)
	(segment
		(start 312.371232 -276.219412)
		(end 312.556652 -276.033992)
		(width 0.14478)
		(layer "In11.Cu")
		(net "M_F_CPU0_SB_DQ<0>")
	)
	(segment
		(start 287.90519 -281.910028)
		(end 288.77514 -281.910028)
		(width 0.14478)
		(layer "In11.Cu")
		(net "M_F_CPU0_SB_DQ<0>")
	)
	(segment
		(start 311.776364 -276.609556)
		(end 311.713118 -276.54631)
		(width 0.14478)
		(layer "In11.Cu")
		(net "M_F_CPU0_SB_DQ<0>")
	)
	(segment
		(start 312.493406 -275.766022)
		(end 312.493152 -275.561806)
		(width 0.14478)
		(layer "In11.Cu")
		(net "M_F_CPU0_SB_DQ<0>")
	)
	(segment
		(start 310.152542 -278.106886)
		(end 310.152288 -277.90267)
		(width 0.14478)
		(layer "In11.Cu")
		(net "M_F_CPU0_SB_DQ<0>")
	)
	(segment
		(start 327.387204 -274.397978)
		(end 327.405238 -274.408646)
		(width 0.0889)
		(layer "In11.Cu")
		(net "M_F_CPU0_SB_DQ<0>")
	)
	(segment
		(start 310.996076 -277.389844)
		(end 310.93283 -277.326598)
		(width 0.14478)
		(layer "In11.Cu")
		(net "M_F_CPU0_SB_DQ<0>")
	)
	(segment
		(start 310.152288 -277.90267)
		(end 310.337962 -277.716996)
		(width 0.14478)
		(layer "In11.Cu")
		(net "M_F_CPU0_SB_DQ<0>")
	)
	(segment
		(start 287.612836 -281.617674)
		(end 287.90519 -281.910028)
		(width 0.14478)
		(layer "In11.Cu")
		(net "M_F_CPU0_SB_DQ<0>")
	)
	(segment
		(start 273.541998 -281.910028)
		(end 273.833336 -281.61869)
		(width 0.14478)
		(layer "In11.Cu")
		(net "M_F_CPU0_SB_DQ<0>")
	)
	(segment
		(start 309.762398 -278.497284)
		(end 309.825644 -278.56053)
		(width 0.14478)
		(layer "In11.Cu")
		(net "M_F_CPU0_SB_DQ<0>")
	)
	(segment
		(start 312.556652 -275.829268)
		(end 312.493406 -275.766022)
		(width 0.14478)
		(layer "In11.Cu")
		(net "M_F_CPU0_SB_DQ<0>")
	)
	(segment
		(start 287.056576 -282.295854)
		(end 287.21939 -282.13304)
		(width 0.14478)
		(layer "In11.Cu")
		(net "M_F_CPU0_SB_DQ<0>")
	)
	(segment
		(start 286.825944 -282.295854)
		(end 287.056576 -282.295854)
		(width 0.14478)
		(layer "In11.Cu")
		(net "M_F_CPU0_SB_DQ<0>")
	)
	(segment
		(start 312.946796 -275.439378)
		(end 313.15152 -275.439124)
		(width 0.14478)
		(layer "In11.Cu")
		(net "M_F_CPU0_SB_DQ<0>")
	)
	(segment
		(start 289.62477 -282.296616)
		(end 289.855402 -282.296616)
		(width 0.14478)
		(layer "In11.Cu")
		(net "M_F_CPU0_SB_DQ<0>")
	)
	(segment
		(start 271.580102 -282.30449)
		(end 271.810734 -282.30449)
		(width 0.14478)
		(layer "In11.Cu")
		(net "M_F_CPU0_SB_DQ<0>")
	)
	(segment
		(start 272.136362 -281.619706)
		(end 272.366994 -281.619706)
		(width 0.14478)
		(layer "In11.Cu")
		(net "M_F_CPU0_SB_DQ<0>")
	)
	(segment
		(start 283.406088 -280.77033)
		(end 283.672788 -280.77033)
		(width 0.14478)
		(layer "In11.Cu")
		(net "M_F_CPU0_SB_DQ<0>")
	)
	(segment
		(start 328.709782 -274.413472)
		(end 328.718164 -274.408646)
		(width 0.0889)
		(layer "In11.Cu")
		(net "M_F_CPU0_SB_DQ<0>")
	)
	(segment
		(start 310.215788 -278.170132)
		(end 310.152542 -278.106886)
		(width 0.14478)
		(layer "In11.Cu")
		(net "M_F_CPU0_SB_DQ<0>")
	)
	(segment
		(start 282.26639 -281.910028)
		(end 283.406088 -280.77033)
		(width 0.14478)
		(layer "In11.Cu")
		(net "M_F_CPU0_SB_DQ<0>")
	)
	(segment
		(start 332.445106 -274.351496)
		(end 332.291182 -274.086066)
		(width 0.0889)
		(layer "In11.Cu")
		(net "M_F_CPU0_SB_DQ<0>")
	)
	(segment
		(start 274.226782 -282.128976)
		(end 274.389596 -282.29179)
		(width 0.14478)
		(layer "In11.Cu")
		(net "M_F_CPU0_SB_DQ<0>")
	)
	(segment
		(start 275.852128 -281.05989)
		(end 278.52878 -281.05989)
		(width 0.14478)
		(layer "In11.Cu")
		(net "M_F_CPU0_SB_DQ<0>")
	)
	(segment
		(start 327.765156 -274.416266)
		(end 327.778872 -274.408392)
		(width 0.0889)
		(layer "In11.Cu")
		(net "M_F_CPU0_SB_DQ<0>")
	)
	(segment
		(start 287.382204 -281.617674)
		(end 287.612836 -281.617674)
		(width 0.14478)
		(layer "In11.Cu")
		(net "M_F_CPU0_SB_DQ<0>")
	)
	(segment
		(start 284.518608 -281.05989)
		(end 285.58998 -281.05989)
		(width 0.14478)
		(layer "In11.Cu")
		(net "M_F_CPU0_SB_DQ<0>")
	)
	(segment
		(start 310.932576 -277.122382)
		(end 311.11825 -276.936708)
		(width 0.14478)
		(layer "In11.Cu")
		(net "M_F_CPU0_SB_DQ<0>")
	)
	(segment
		(start 332.422754 -274.434808)
		(end 332.445106 -274.351496)
		(width 0.0889)
		(layer "In11.Cu")
		(net "M_F_CPU0_SB_DQ<0>")
	)
	(segment
		(start 324.664324 -273.22018)
		(end 324.917054 -273.47291)
		(width 0.0889)
		(layer "In11.Cu")
		(net "M_F_CPU0_SB_DQ<0>")
	)
	(segment
		(start 300.80458 -281.05989)
		(end 301.654718 -281.910028)
		(width 0.14478)
		(layer "In11.Cu")
		(net "M_F_CPU0_SB_DQ<0>")
	)
	(segment
		(start 311.776364 -276.81428)
		(end 311.776364 -276.609556)
		(width 0.14478)
		(layer "In11.Cu")
		(net "M_F_CPU0_SB_DQ<0>")
	)
	(segment
		(start 279.378918 -281.910028)
		(end 282.26639 -281.910028)
		(width 0.14478)
		(layer "In11.Cu")
		(net "M_F_CPU0_SB_DQ<0>")
	)
	(segment
		(start 271.973548 -281.78252)
		(end 272.136362 -281.619706)
		(width 0.14478)
		(layer "In11.Cu")
		(net "M_F_CPU0_SB_DQ<0>")
	)
	(segment
		(start 311.11825 -276.936708)
		(end 311.322974 -276.936708)
		(width 0.14478)
		(layer "In11.Cu")
		(net "M_F_CPU0_SB_DQ<0>")
	)
	(segment
		(start 310.030368 -278.560276)
		(end 310.215788 -278.374856)
		(width 0.14478)
		(layer "In11.Cu")
		(net "M_F_CPU0_SB_DQ<0>")
	)
	(segment
		(start 271.417288 -282.141676)
		(end 271.580102 -282.30449)
		(width 0.14478)
		(layer "In11.Cu")
		(net "M_F_CPU0_SB_DQ<0>")
	)
	(segment
		(start 289.461956 -281.783028)
		(end 289.461956 -282.133802)
		(width 0.14478)
		(layer "In11.Cu")
		(net "M_F_CPU0_SB_DQ<0>")
	)
	(segment
		(start 288.77514 -281.910028)
		(end 289.066732 -281.618436)
		(width 0.14478)
		(layer "In11.Cu")
		(net "M_F_CPU0_SB_DQ<0>")
	)
	(segment
		(start 269.648178 -281.485086)
		(end 270.467582 -282.30449)
		(width 0.14478)
		(layer "In11.Cu")
		(net "M_F_CPU0_SB_DQ<0>")
	)
	(segment
		(start 312.493152 -275.561806)
		(end 312.678826 -275.376132)
		(width 0.14478)
		(layer "In11.Cu")
		(net "M_F_CPU0_SB_DQ<0>")
	)
	(segment
		(start 274.063968 -281.61869)
		(end 274.226782 -281.781504)
		(width 0.14478)
		(layer "In11.Cu")
		(net "M_F_CPU0_SB_DQ<0>")
	)
	(segment
		(start 309.4355 -279.155144)
		(end 309.4355 -278.95042)
		(width 0.14478)
		(layer "In11.Cu")
		(net "M_F_CPU0_SB_DQ<0>")
	)
	(segment
		(start 284.229048 -281.34945)
		(end 284.518608 -281.05989)
		(width 0.14478)
		(layer "In11.Cu")
		(net "M_F_CPU0_SB_DQ<0>")
	)
	(segment
		(start 313.15152 -275.439124)
		(end 315.370464 -273.22018)
		(width 0.14478)
		(layer "In11.Cu")
		(net "M_F_CPU0_SB_DQ<0>")
	)
	(segment
		(start 310.215788 -278.374856)
		(end 310.215788 -278.170132)
		(width 0.14478)
		(layer "In11.Cu")
		(net "M_F_CPU0_SB_DQ<0>")
	)
	(segment
		(start 270.467582 -282.30449)
		(end 270.698214 -282.30449)
		(width 0.14478)
		(layer "In11.Cu")
		(net "M_F_CPU0_SB_DQ<0>")
	)
	(segment
		(start 283.817568 -280.91511)
		(end 283.817568 -281.20467)
		(width 0.14478)
		(layer "In11.Cu")
		(net "M_F_CPU0_SB_DQ<0>")
	)
	(segment
		(start 325.510398 -273.47291)
		(end 326.387206 -274.349718)
		(width 0.0889)
		(layer "In11.Cu")
		(net "M_F_CPU0_SB_DQ<0>")
	)
	(segment
		(start 315.370464 -273.22018)
		(end 323.927724 -273.22018)
		(width 0.14478)
		(layer "In11.Cu")
		(net "M_F_CPU0_SB_DQ<0>")
	)
	(segment
		(start 289.066732 -281.618436)
		(end 289.297364 -281.618436)
		(width 0.14478)
		(layer "In11.Cu")
		(net "M_F_CPU0_SB_DQ<0>")
	)
	(segment
		(start 305.653948 -281.05989)
		(end 307.530754 -281.05989)
		(width 0.14478)
		(layer "In11.Cu")
		(net "M_F_CPU0_SB_DQ<0>")
	)
	(arc
		(start 331.538072 -274.408646)
		(mid 331.821028 -274.332469)
		(end 332.103984 -274.408646)
		(width 0.0889)
		(layer "In11.Cu")
		(net "M_F_CPU0_SB_DQ<0>")
	)
	(arc
		(start 326.484742 -274.419822)
		(mid 326.663074 -274.458919)
		(end 326.838564 -274.408646)
		(width 0.0889)
		(layer "In11.Cu")
		(net "M_F_CPU0_SB_DQ<0>")
	)
	(arc
		(start 326.838564 -274.408646)
		(mid 327.111508 -274.332066)
		(end 327.387204 -274.397978)
		(width 0.0889)
		(layer "In11.Cu")
		(net "M_F_CPU0_SB_DQ<0>")
	)
	(arc
		(start 326.38746 -274.349718)
		(mid 326.424156 -274.381571)
		(end 326.464676 -274.408392)
		(width 0.0889)
		(layer "In11.Cu")
		(net "M_F_CPU0_SB_DQ<0>")
	)
	(arc
		(start 328.344022 -274.408646)
		(mid 328.526273 -274.458996)
		(end 328.709782 -274.413472)
		(width 0.0889)
		(layer "In11.Cu")
		(net "M_F_CPU0_SB_DQ<0>")
	)
	(arc
		(start 329.658218 -274.408646)
		(mid 329.941174 -274.332469)
		(end 330.22413 -274.408646)
		(width 0.0889)
		(layer "In11.Cu")
		(net "M_F_CPU0_SB_DQ<0>")
	)
	(arc
		(start 330.598018 -274.408646)
		(mid 330.880974 -274.332469)
		(end 331.16393 -274.408646)
		(width 0.0889)
		(layer "In11.Cu")
		(net "M_F_CPU0_SB_DQ<0>")
	)
	(arc
		(start 329.292458 -274.413472)
		(mid 329.475966 -274.458966)
		(end 329.658218 -274.408646)
		(width 0.0889)
		(layer "In11.Cu")
		(net "M_F_CPU0_SB_DQ<0>")
	)
	(arc
		(start 332.103984 -274.408646)
		(mid 332.260422 -274.457617)
		(end 332.422754 -274.434808)
		(width 0.0889)
		(layer "In11.Cu")
		(net "M_F_CPU0_SB_DQ<0>")
	)
	(arc
		(start 328.718164 -274.408646)
		(mid 329.00112 -274.332469)
		(end 329.284076 -274.408646)
		(width 0.0889)
		(layer "In11.Cu")
		(net "M_F_CPU0_SB_DQ<0>")
	)
	(arc
		(start 331.16393 -274.408646)
		(mid 331.346181 -274.458996)
		(end 331.52969 -274.413472)
		(width 0.0889)
		(layer "In11.Cu")
		(net "M_F_CPU0_SB_DQ<0>")
	)
	(arc
		(start 330.22413 -274.408646)
		(mid 330.411074 -274.458901)
		(end 330.598018 -274.408646)
		(width 0.0889)
		(layer "In11.Cu")
		(net "M_F_CPU0_SB_DQ<0>")
	)
	(arc
		(start 327.79081 -274.401534)
		(mid 328.068344 -274.332553)
		(end 328.344022 -274.408646)
		(width 0.0889)
		(layer "In11.Cu")
		(net "M_F_CPU0_SB_DQ<0>")
	)
	(arc
		(start 327.405238 -274.408646)
		(mid 327.584225 -274.458816)
		(end 327.765156 -274.416266)
		(width 0.0889)
		(layer "In11.Cu")
		(net "M_F_CPU0_SB_DQ<0>")
	)
	(segment
		(start 333.227934 -266.530074)
		(end 332.761082 -266.796012)
		(width 0.10668)
		(layer "F.Cu")
		(net "M_F_CPU0_SB_CS_N<1>")
	)
	(segment
		(start 326.27443 -266.422886)
		(end 328.061066 -266.422886)
		(width 0.0889)
		(layer "In11.Cu")
		(net "M_F_CPU0_SB_CS_N<1>")
	)
	(segment
		(start 265.54811 -268.735048)
		(end 265.973052 -268.310106)
		(width 0.14478)
		(layer "In11.Cu")
		(net "M_F_CPU0_SB_CS_N<1>")
	)
	(segment
		(start 331.634084 -266.473432)
		(end 331.642466 -266.468606)
		(width 0.0889)
		(layer "In11.Cu")
		(net "M_F_CPU0_SB_CS_N<1>")
	)
	(segment
		(start 330.119736 -266.468606)
		(end 330.128118 -266.473432)
		(width 0.0889)
		(layer "In11.Cu")
		(net "M_F_CPU0_SB_CS_N<1>")
	)
	(segment
		(start 325.835264 -265.98372)
		(end 326.27443 -266.422886)
		(width 0.0889)
		(layer "In11.Cu")
		(net "M_F_CPU0_SB_CS_N<1>")
	)
	(segment
		(start 332.511146 -266.505182)
		(end 332.607158 -266.530582)
		(width 0.0889)
		(layer "In11.Cu")
		(net "M_F_CPU0_SB_CS_N<1>")
	)
	(segment
		(start 330.69403 -266.473432)
		(end 330.702412 -266.468606)
		(width 0.0889)
		(layer "In11.Cu")
		(net "M_F_CPU0_SB_CS_N<1>")
	)
	(segment
		(start 308.185058 -268.310106)
		(end 310.511444 -265.98372)
		(width 0.14478)
		(layer "In11.Cu")
		(net "M_F_CPU0_SB_CS_N<1>")
	)
	(segment
		(start 323.897244 -265.98372)
		(end 325.835264 -265.98372)
		(width 0.0889)
		(layer "In11.Cu")
		(net "M_F_CPU0_SB_CS_N<1>")
	)
	(segment
		(start 310.511444 -265.98372)
		(end 323.897244 -265.98372)
		(width 0.14478)
		(layer "In11.Cu")
		(net "M_F_CPU0_SB_CS_N<1>")
	)
	(segment
		(start 265.973052 -268.310106)
		(end 308.185058 -268.310106)
		(width 0.14478)
		(layer "In11.Cu")
		(net "M_F_CPU0_SB_CS_N<1>")
	)
	(segment
		(start 332.607158 -266.530582)
		(end 332.761082 -266.796012)
		(width 0.0889)
		(layer "In11.Cu")
		(net "M_F_CPU0_SB_CS_N<1>")
	)
	(arc
		(start 331.642466 -266.468606)
		(mid 331.825974 -266.423112)
		(end 332.008226 -266.473432)
		(width 0.0889)
		(layer "In11.Cu")
		(net "M_F_CPU0_SB_CS_N<1>")
	)
	(arc
		(start 331.068172 -266.473432)
		(mid 331.351128 -266.549609)
		(end 331.634084 -266.473432)
		(width 0.0889)
		(layer "In11.Cu")
		(net "M_F_CPU0_SB_CS_N<1>")
	)
	(arc
		(start 329.753976 -266.473432)
		(mid 329.936227 -266.423082)
		(end 330.119736 -266.468606)
		(width 0.0889)
		(layer "In11.Cu")
		(net "M_F_CPU0_SB_CS_N<1>")
	)
	(arc
		(start 329.188064 -266.473432)
		(mid 329.47102 -266.549609)
		(end 329.753976 -266.473432)
		(width 0.0889)
		(layer "In11.Cu")
		(net "M_F_CPU0_SB_CS_N<1>")
	)
	(arc
		(start 328.061066 -266.422886)
		(mid 328.158013 -266.435769)
		(end 328.248264 -266.473432)
		(width 0.0889)
		(layer "In11.Cu")
		(net "M_F_CPU0_SB_CS_N<1>")
	)
	(arc
		(start 330.128118 -266.473432)
		(mid 330.411074 -266.549609)
		(end 330.69403 -266.473432)
		(width 0.0889)
		(layer "In11.Cu")
		(net "M_F_CPU0_SB_CS_N<1>")
	)
	(arc
		(start 328.248264 -266.473432)
		(mid 328.53122 -266.549609)
		(end 328.814176 -266.473432)
		(width 0.0889)
		(layer "In11.Cu")
		(net "M_F_CPU0_SB_CS_N<1>")
	)
	(arc
		(start 330.702412 -266.468606)
		(mid 330.88592 -266.423112)
		(end 331.068172 -266.473432)
		(width 0.0889)
		(layer "In11.Cu")
		(net "M_F_CPU0_SB_CS_N<1>")
	)
	(arc
		(start 332.008226 -266.473432)
		(mid 332.255939 -266.548652)
		(end 332.511146 -266.505182)
		(width 0.0889)
		(layer "In11.Cu")
		(net "M_F_CPU0_SB_CS_N<1>")
	)
	(arc
		(start 328.814176 -266.473432)
		(mid 329.00112 -266.423177)
		(end 329.188064 -266.473432)
		(width 0.0889)
		(layer "In11.Cu")
		(net "M_F_CPU0_SB_CS_N<1>")
	)
	(segment
		(start 334.637888 -265.720068)
		(end 334.171036 -265.986006)
		(width 0.10668)
		(layer "F.Cu")
		(net "M_F_CPU0_SB_CS_N<0>")
	)
	(segment
		(start 333.9211 -265.695176)
		(end 334.017112 -265.720576)
		(width 0.0889)
		(layer "In11.Cu")
		(net "M_F_CPU0_SB_CS_N<0>")
	)
	(segment
		(start 270.99768 -267.852906)
		(end 271.228312 -267.852906)
		(width 0.14478)
		(layer "In11.Cu")
		(net "M_F_CPU0_SB_CS_N<0>")
	)
	(segment
		(start 334.017112 -265.720576)
		(end 334.171036 -265.986006)
		(width 0.0889)
		(layer "In11.Cu")
		(net "M_F_CPU0_SB_CS_N<0>")
	)
	(segment
		(start 328.709782 -265.6586)
		(end 328.718164 -265.663426)
		(width 0.0889)
		(layer "In11.Cu")
		(net "M_F_CPU0_SB_CS_N<0>")
	)
	(segment
		(start 324.059804 -265.52906)
		(end 327.280524 -265.52906)
		(width 0.0889)
		(layer "In11.Cu")
		(net "M_F_CPU0_SB_CS_N<0>")
	)
	(segment
		(start 308.145942 -267.460222)
		(end 310.077104 -265.52906)
		(width 0.14478)
		(layer "In11.Cu")
		(net "M_F_CPU0_SB_CS_N<0>")
	)
	(segment
		(start 271.391126 -267.690092)
		(end 271.391126 -267.254736)
		(width 0.14478)
		(layer "In11.Cu")
		(net "M_F_CPU0_SB_CS_N<0>")
	)
	(segment
		(start 271.391126 -267.254736)
		(end 271.55394 -267.091922)
		(width 0.14478)
		(layer "In11.Cu")
		(net "M_F_CPU0_SB_CS_N<0>")
	)
	(segment
		(start 270.672052 -267.091922)
		(end 270.834866 -267.254736)
		(width 0.14478)
		(layer "In11.Cu")
		(net "M_F_CPU0_SB_CS_N<0>")
	)
	(segment
		(start 333.044038 -265.663426)
		(end 333.05242 -265.6586)
		(width 0.0889)
		(layer "In11.Cu")
		(net "M_F_CPU0_SB_CS_N<0>")
	)
	(segment
		(start 269.648178 -267.885164)
		(end 270.44142 -267.091922)
		(width 0.14478)
		(layer "In11.Cu")
		(net "M_F_CPU0_SB_CS_N<0>")
	)
	(segment
		(start 271.228312 -267.852906)
		(end 271.391126 -267.690092)
		(width 0.14478)
		(layer "In11.Cu")
		(net "M_F_CPU0_SB_CS_N<0>")
	)
	(segment
		(start 328.333608 -265.669522)
		(end 328.344022 -265.663426)
		(width 0.0889)
		(layer "In11.Cu")
		(net "M_F_CPU0_SB_CS_N<0>")
	)
	(segment
		(start 270.44142 -267.091922)
		(end 270.672052 -267.091922)
		(width 0.14478)
		(layer "In11.Cu")
		(net "M_F_CPU0_SB_CS_N<0>")
	)
	(segment
		(start 272.733516 -267.460222)
		(end 308.145942 -267.460222)
		(width 0.14478)
		(layer "In11.Cu")
		(net "M_F_CPU0_SB_CS_N<0>")
	)
	(segment
		(start 272.1102 -267.852906)
		(end 272.340832 -267.852906)
		(width 0.14478)
		(layer "In11.Cu")
		(net "M_F_CPU0_SB_CS_N<0>")
	)
	(segment
		(start 271.55394 -267.091922)
		(end 271.784572 -267.091922)
		(width 0.14478)
		(layer "In11.Cu")
		(net "M_F_CPU0_SB_CS_N<0>")
	)
	(segment
		(start 330.22413 -265.663426)
		(end 330.232512 -265.6586)
		(width 0.0889)
		(layer "In11.Cu")
		(net "M_F_CPU0_SB_CS_N<0>")
	)
	(segment
		(start 270.834866 -267.690092)
		(end 270.99768 -267.852906)
		(width 0.14478)
		(layer "In11.Cu")
		(net "M_F_CPU0_SB_CS_N<0>")
	)
	(segment
		(start 271.947386 -267.690092)
		(end 272.1102 -267.852906)
		(width 0.14478)
		(layer "In11.Cu")
		(net "M_F_CPU0_SB_CS_N<0>")
	)
	(segment
		(start 310.077104 -265.52906)
		(end 324.059804 -265.52906)
		(width 0.14478)
		(layer "In11.Cu")
		(net "M_F_CPU0_SB_CS_N<0>")
	)
	(segment
		(start 270.834866 -267.254736)
		(end 270.834866 -267.690092)
		(width 0.14478)
		(layer "In11.Cu")
		(net "M_F_CPU0_SB_CS_N<0>")
	)
	(segment
		(start 332.469744 -265.6586)
		(end 332.478126 -265.663426)
		(width 0.0889)
		(layer "In11.Cu")
		(net "M_F_CPU0_SB_CS_N<0>")
	)
	(segment
		(start 329.284076 -265.663426)
		(end 329.292458 -265.6586)
		(width 0.0889)
		(layer "In11.Cu")
		(net "M_F_CPU0_SB_CS_N<0>")
	)
	(segment
		(start 271.947386 -267.254736)
		(end 271.947386 -267.690092)
		(width 0.14478)
		(layer "In11.Cu")
		(net "M_F_CPU0_SB_CS_N<0>")
	)
	(segment
		(start 271.784572 -267.091922)
		(end 271.947386 -267.254736)
		(width 0.14478)
		(layer "In11.Cu")
		(net "M_F_CPU0_SB_CS_N<0>")
	)
	(segment
		(start 272.340832 -267.852906)
		(end 272.733516 -267.460222)
		(width 0.14478)
		(layer "In11.Cu")
		(net "M_F_CPU0_SB_CS_N<0>")
	)
	(arc
		(start 329.292458 -265.6586)
		(mid 329.475966 -265.613106)
		(end 329.658218 -265.663426)
		(width 0.0889)
		(layer "In11.Cu")
		(net "M_F_CPU0_SB_CS_N<0>")
	)
	(arc
		(start 333.41818 -265.663426)
		(mid 333.665893 -265.738646)
		(end 333.9211 -265.695176)
		(width 0.0889)
		(layer "In11.Cu")
		(net "M_F_CPU0_SB_CS_N<0>")
	)
	(arc
		(start 327.280524 -265.52906)
		(mid 327.538101 -265.563252)
		(end 327.777856 -265.663426)
		(width 0.0889)
		(layer "In11.Cu")
		(net "M_F_CPU0_SB_CS_N<0>")
	)
	(arc
		(start 333.05242 -265.6586)
		(mid 333.235928 -265.613106)
		(end 333.41818 -265.663426)
		(width 0.0889)
		(layer "In11.Cu")
		(net "M_F_CPU0_SB_CS_N<0>")
	)
	(arc
		(start 331.538072 -265.663426)
		(mid 331.821028 -265.739603)
		(end 332.103984 -265.663426)
		(width 0.0889)
		(layer "In11.Cu")
		(net "M_F_CPU0_SB_CS_N<0>")
	)
	(arc
		(start 331.164184 -265.663426)
		(mid 331.351128 -265.613171)
		(end 331.538072 -265.663426)
		(width 0.0889)
		(layer "In11.Cu")
		(net "M_F_CPU0_SB_CS_N<0>")
	)
	(arc
		(start 330.598272 -265.663426)
		(mid 330.881228 -265.739603)
		(end 331.164184 -265.663426)
		(width 0.0889)
		(layer "In11.Cu")
		(net "M_F_CPU0_SB_CS_N<0>")
	)
	(arc
		(start 328.718164 -265.663426)
		(mid 329.00112 -265.739603)
		(end 329.284076 -265.663426)
		(width 0.0889)
		(layer "In11.Cu")
		(net "M_F_CPU0_SB_CS_N<0>")
	)
	(arc
		(start 332.478126 -265.663426)
		(mid 332.761082 -265.739603)
		(end 333.044038 -265.663426)
		(width 0.0889)
		(layer "In11.Cu")
		(net "M_F_CPU0_SB_CS_N<0>")
	)
	(arc
		(start 332.103984 -265.663426)
		(mid 332.286235 -265.613076)
		(end 332.469744 -265.6586)
		(width 0.0889)
		(layer "In11.Cu")
		(net "M_F_CPU0_SB_CS_N<0>")
	)
	(arc
		(start 330.232512 -265.6586)
		(mid 330.41602 -265.613106)
		(end 330.598272 -265.663426)
		(width 0.0889)
		(layer "In11.Cu")
		(net "M_F_CPU0_SB_CS_N<0>")
	)
	(arc
		(start 327.777856 -265.663426)
		(mid 328.054923 -265.739697)
		(end 328.333608 -265.669522)
		(width 0.0889)
		(layer "In11.Cu")
		(net "M_F_CPU0_SB_CS_N<0>")
	)
	(arc
		(start 328.344022 -265.663426)
		(mid 328.526273 -265.613076)
		(end 328.709782 -265.6586)
		(width 0.0889)
		(layer "In11.Cu")
		(net "M_F_CPU0_SB_CS_N<0>")
	)
	(arc
		(start 329.658218 -265.663426)
		(mid 329.941174 -265.739603)
		(end 330.22413 -265.663426)
		(width 0.0889)
		(layer "In11.Cu")
		(net "M_F_CPU0_SB_CS_N<0>")
	)
	(segment
		(start 334.637888 -270.580104)
		(end 334.171036 -270.846042)
		(width 0.10668)
		(layer "F.Cu")
		(net "M_F_CPU0_SB_CB<7>")
	)
	(segment
		(start 324.138544 -268.9606)
		(end 324.282054 -269.10411)
		(width 0.0889)
		(layer "In11.Cu")
		(net "M_F_CPU0_SB_CB<7>")
	)
	(segment
		(start 308.2798 -273.410172)
		(end 312.729372 -268.9606)
		(width 0.14478)
		(layer "In11.Cu")
		(net "M_F_CPU0_SB_CB<7>")
	)
	(segment
		(start 268.52372 -273.36115)
		(end 268.754352 -273.36115)
		(width 0.14478)
		(layer "In11.Cu")
		(net "M_F_CPU0_SB_CB<7>")
	)
	(segment
		(start 266.135866 -273.694144)
		(end 266.29868 -273.53133)
		(width 0.14478)
		(layer "In11.Cu")
		(net "M_F_CPU0_SB_CB<7>")
	)
	(segment
		(start 266.692126 -274.097242)
		(end 266.85494 -274.260056)
		(width 0.14478)
		(layer "In11.Cu")
		(net "M_F_CPU0_SB_CB<7>")
	)
	(segment
		(start 266.529312 -273.53133)
		(end 266.692126 -273.694144)
		(width 0.14478)
		(layer "In11.Cu")
		(net "M_F_CPU0_SB_CB<7>")
	)
	(segment
		(start 266.29868 -273.53133)
		(end 266.529312 -273.53133)
		(width 0.14478)
		(layer "In11.Cu")
		(net "M_F_CPU0_SB_CB<7>")
	)
	(segment
		(start 265.54811 -274.684998)
		(end 266.135866 -274.097242)
		(width 0.14478)
		(layer "In11.Cu")
		(net "M_F_CPU0_SB_CB<7>")
	)
	(segment
		(start 333.044038 -270.523462)
		(end 333.05242 -270.518636)
		(width 0.0889)
		(layer "In11.Cu")
		(net "M_F_CPU0_SB_CB<7>")
	)
	(segment
		(start 328.709782 -270.518636)
		(end 328.718164 -270.523462)
		(width 0.0889)
		(layer "In11.Cu")
		(net "M_F_CPU0_SB_CB<7>")
	)
	(segment
		(start 268.917166 -273.523964)
		(end 268.917166 -274.097242)
		(width 0.14478)
		(layer "In11.Cu")
		(net "M_F_CPU0_SB_CB<7>")
	)
	(segment
		(start 275.017992 -273.410172)
		(end 308.2798 -273.410172)
		(width 0.14478)
		(layer "In11.Cu")
		(net "M_F_CPU0_SB_CB<7>")
	)
	(segment
		(start 333.9211 -270.555212)
		(end 334.017112 -270.580612)
		(width 0.0889)
		(layer "In11.Cu")
		(net "M_F_CPU0_SB_CB<7>")
	)
	(segment
		(start 266.85494 -274.260056)
		(end 267.085572 -274.260056)
		(width 0.14478)
		(layer "In11.Cu")
		(net "M_F_CPU0_SB_CB<7>")
	)
	(segment
		(start 268.360906 -273.523964)
		(end 268.52372 -273.36115)
		(width 0.14478)
		(layer "In11.Cu")
		(net "M_F_CPU0_SB_CB<7>")
	)
	(segment
		(start 328.333608 -270.529558)
		(end 328.344022 -270.523462)
		(width 0.0889)
		(layer "In11.Cu")
		(net "M_F_CPU0_SB_CB<7>")
	)
	(segment
		(start 324.282054 -269.10411)
		(end 325.022718 -269.10411)
		(width 0.0889)
		(layer "In11.Cu")
		(net "M_F_CPU0_SB_CB<7>")
	)
	(segment
		(start 325.022718 -269.10411)
		(end 326.247252 -270.328644)
		(width 0.0889)
		(layer "In11.Cu")
		(net "M_F_CPU0_SB_CB<7>")
	)
	(segment
		(start 268.198092 -274.260056)
		(end 268.360906 -274.097242)
		(width 0.14478)
		(layer "In11.Cu")
		(net "M_F_CPU0_SB_CB<7>")
	)
	(segment
		(start 268.360906 -274.097242)
		(end 268.360906 -273.523964)
		(width 0.14478)
		(layer "In11.Cu")
		(net "M_F_CPU0_SB_CB<7>")
	)
	(segment
		(start 266.135866 -274.097242)
		(end 266.135866 -273.694144)
		(width 0.14478)
		(layer "In11.Cu")
		(net "M_F_CPU0_SB_CB<7>")
	)
	(segment
		(start 267.96746 -274.260056)
		(end 268.198092 -274.260056)
		(width 0.14478)
		(layer "In11.Cu")
		(net "M_F_CPU0_SB_CB<7>")
	)
	(segment
		(start 268.917166 -274.097242)
		(end 269.07998 -274.260056)
		(width 0.14478)
		(layer "In11.Cu")
		(net "M_F_CPU0_SB_CB<7>")
	)
	(segment
		(start 267.248386 -273.523964)
		(end 267.4112 -273.36115)
		(width 0.14478)
		(layer "In11.Cu")
		(net "M_F_CPU0_SB_CB<7>")
	)
	(segment
		(start 267.248386 -274.097242)
		(end 267.248386 -273.523964)
		(width 0.14478)
		(layer "In11.Cu")
		(net "M_F_CPU0_SB_CB<7>")
	)
	(segment
		(start 269.07998 -274.260056)
		(end 274.168108 -274.260056)
		(width 0.14478)
		(layer "In11.Cu")
		(net "M_F_CPU0_SB_CB<7>")
	)
	(segment
		(start 268.754352 -273.36115)
		(end 268.917166 -273.523964)
		(width 0.14478)
		(layer "In11.Cu")
		(net "M_F_CPU0_SB_CB<7>")
	)
	(segment
		(start 267.804646 -274.097242)
		(end 267.96746 -274.260056)
		(width 0.14478)
		(layer "In11.Cu")
		(net "M_F_CPU0_SB_CB<7>")
	)
	(segment
		(start 326.327516 -270.361918)
		(end 327.17994 -270.361918)
		(width 0.0889)
		(layer "In11.Cu")
		(net "M_F_CPU0_SB_CB<7>")
	)
	(segment
		(start 323.874892 -268.9606)
		(end 324.138544 -268.9606)
		(width 0.0889)
		(layer "In11.Cu")
		(net "M_F_CPU0_SB_CB<7>")
	)
	(segment
		(start 267.085572 -274.260056)
		(end 267.248386 -274.097242)
		(width 0.14478)
		(layer "In11.Cu")
		(net "M_F_CPU0_SB_CB<7>")
	)
	(segment
		(start 274.168108 -274.260056)
		(end 275.017992 -273.410172)
		(width 0.14478)
		(layer "In11.Cu")
		(net "M_F_CPU0_SB_CB<7>")
	)
	(segment
		(start 312.729372 -268.9606)
		(end 323.874892 -268.9606)
		(width 0.14478)
		(layer "In11.Cu")
		(net "M_F_CPU0_SB_CB<7>")
	)
	(segment
		(start 334.017112 -270.580612)
		(end 334.171036 -270.846042)
		(width 0.0889)
		(layer "In11.Cu")
		(net "M_F_CPU0_SB_CB<7>")
	)
	(segment
		(start 332.469744 -270.518636)
		(end 332.478126 -270.523462)
		(width 0.0889)
		(layer "In11.Cu")
		(net "M_F_CPU0_SB_CB<7>")
	)
	(segment
		(start 331.52969 -270.518636)
		(end 331.538072 -270.523462)
		(width 0.0889)
		(layer "In11.Cu")
		(net "M_F_CPU0_SB_CB<7>")
	)
	(segment
		(start 267.4112 -273.36115)
		(end 267.641832 -273.36115)
		(width 0.14478)
		(layer "In11.Cu")
		(net "M_F_CPU0_SB_CB<7>")
	)
	(segment
		(start 329.284076 -270.523462)
		(end 329.292458 -270.518636)
		(width 0.0889)
		(layer "In11.Cu")
		(net "M_F_CPU0_SB_CB<7>")
	)
	(segment
		(start 267.804646 -273.523964)
		(end 267.804646 -274.097242)
		(width 0.14478)
		(layer "In11.Cu")
		(net "M_F_CPU0_SB_CB<7>")
	)
	(segment
		(start 267.641832 -273.36115)
		(end 267.804646 -273.523964)
		(width 0.14478)
		(layer "In11.Cu")
		(net "M_F_CPU0_SB_CB<7>")
	)
	(segment
		(start 266.692126 -273.694144)
		(end 266.692126 -274.097242)
		(width 0.14478)
		(layer "In11.Cu")
		(net "M_F_CPU0_SB_CB<7>")
	)
	(arc
		(start 329.658218 -270.523462)
		(mid 329.941174 -270.599639)
		(end 330.22413 -270.523462)
		(width 0.0889)
		(layer "In11.Cu")
		(net "M_F_CPU0_SB_CB<7>")
	)
	(arc
		(start 327.777856 -270.523462)
		(mid 328.054923 -270.599733)
		(end 328.333608 -270.529558)
		(width 0.0889)
		(layer "In11.Cu")
		(net "M_F_CPU0_SB_CB<7>")
	)
	(arc
		(start 329.292458 -270.518636)
		(mid 329.475966 -270.473142)
		(end 329.658218 -270.523462)
		(width 0.0889)
		(layer "In11.Cu")
		(net "M_F_CPU0_SB_CB<7>")
	)
	(arc
		(start 332.478126 -270.523462)
		(mid 332.761082 -270.599639)
		(end 333.044038 -270.523462)
		(width 0.0889)
		(layer "In11.Cu")
		(net "M_F_CPU0_SB_CB<7>")
	)
	(arc
		(start 328.344022 -270.523462)
		(mid 328.526273 -270.473112)
		(end 328.709782 -270.518636)
		(width 0.0889)
		(layer "In11.Cu")
		(net "M_F_CPU0_SB_CB<7>")
	)
	(arc
		(start 332.103984 -270.523462)
		(mid 332.286235 -270.473112)
		(end 332.469744 -270.518636)
		(width 0.0889)
		(layer "In11.Cu")
		(net "M_F_CPU0_SB_CB<7>")
	)
	(arc
		(start 328.718164 -270.523462)
		(mid 329.00112 -270.599639)
		(end 329.284076 -270.523462)
		(width 0.0889)
		(layer "In11.Cu")
		(net "M_F_CPU0_SB_CB<7>")
	)
	(arc
		(start 330.22413 -270.523462)
		(mid 330.411074 -270.473207)
		(end 330.598018 -270.523462)
		(width 0.0889)
		(layer "In11.Cu")
		(net "M_F_CPU0_SB_CB<7>")
	)
	(arc
		(start 331.16393 -270.523462)
		(mid 331.346181 -270.473112)
		(end 331.52969 -270.518636)
		(width 0.0889)
		(layer "In11.Cu")
		(net "M_F_CPU0_SB_CB<7>")
	)
	(arc
		(start 326.247252 -270.328644)
		(mid 326.284063 -270.353304)
		(end 326.327516 -270.361918)
		(width 0.0889)
		(layer "In11.Cu")
		(net "M_F_CPU0_SB_CB<7>")
	)
	(arc
		(start 331.538072 -270.523462)
		(mid 331.821028 -270.599639)
		(end 332.103984 -270.523462)
		(width 0.0889)
		(layer "In11.Cu")
		(net "M_F_CPU0_SB_CB<7>")
	)
	(arc
		(start 333.41818 -270.523462)
		(mid 333.665893 -270.598682)
		(end 333.9211 -270.555212)
		(width 0.0889)
		(layer "In11.Cu")
		(net "M_F_CPU0_SB_CB<7>")
	)
	(arc
		(start 327.17994 -270.361918)
		(mid 327.489611 -270.403026)
		(end 327.777856 -270.523462)
		(width 0.0889)
		(layer "In11.Cu")
		(net "M_F_CPU0_SB_CB<7>")
	)
	(arc
		(start 333.05242 -270.518636)
		(mid 333.235928 -270.473142)
		(end 333.41818 -270.523462)
		(width 0.0889)
		(layer "In11.Cu")
		(net "M_F_CPU0_SB_CB<7>")
	)
	(arc
		(start 330.598018 -270.523462)
		(mid 330.880974 -270.599639)
		(end 331.16393 -270.523462)
		(width 0.0889)
		(layer "In11.Cu")
		(net "M_F_CPU0_SB_CB<7>")
	)
	(segment
		(start 333.227934 -269.770098)
		(end 332.761082 -270.036036)
		(width 0.10668)
		(layer "F.Cu")
		(net "M_F_CPU0_SB_CB<6>")
	)
	(segment
		(start 324.169024 -268.05128)
		(end 324.683882 -268.566138)
		(width 0.0889)
		(layer "In11.Cu")
		(net "M_F_CPU0_SB_CB<6>")
	)
	(segment
		(start 266.692126 -272.39722)
		(end 266.85494 -272.560034)
		(width 0.14478)
		(layer "In11.Cu")
		(net "M_F_CPU0_SB_CB<6>")
	)
	(segment
		(start 268.198092 -272.560034)
		(end 268.360906 -272.39722)
		(width 0.14478)
		(layer "In11.Cu")
		(net "M_F_CPU0_SB_CB<6>")
	)
	(segment
		(start 332.511146 -269.745206)
		(end 332.607158 -269.770606)
		(width 0.0889)
		(layer "In11.Cu")
		(net "M_F_CPU0_SB_CB<6>")
	)
	(segment
		(start 266.529312 -271.43837)
		(end 266.692126 -271.601184)
		(width 0.14478)
		(layer "In11.Cu")
		(net "M_F_CPU0_SB_CB<6>")
	)
	(segment
		(start 327.308972 -269.71371)
		(end 327.32091 -269.720568)
		(width 0.0889)
		(layer "In11.Cu")
		(net "M_F_CPU0_SB_CB<6>")
	)
	(segment
		(start 327.874122 -269.713456)
		(end 327.882504 -269.70863)
		(width 0.0889)
		(layer "In11.Cu")
		(net "M_F_CPU0_SB_CB<6>")
	)
	(segment
		(start 266.692126 -271.601184)
		(end 266.692126 -272.39722)
		(width 0.14478)
		(layer "In11.Cu")
		(net "M_F_CPU0_SB_CB<6>")
	)
	(segment
		(start 267.248386 -272.39722)
		(end 267.248386 -271.601184)
		(width 0.14478)
		(layer "In11.Cu")
		(net "M_F_CPU0_SB_CB<6>")
	)
	(segment
		(start 267.085572 -272.560034)
		(end 267.248386 -272.39722)
		(width 0.14478)
		(layer "In11.Cu")
		(net "M_F_CPU0_SB_CB<6>")
	)
	(segment
		(start 268.917166 -272.39722)
		(end 269.07998 -272.560034)
		(width 0.14478)
		(layer "In11.Cu")
		(net "M_F_CPU0_SB_CB<6>")
	)
	(segment
		(start 267.804646 -271.657064)
		(end 267.804646 -272.39722)
		(width 0.14478)
		(layer "In11.Cu")
		(net "M_F_CPU0_SB_CB<6>")
	)
	(segment
		(start 266.135866 -271.601184)
		(end 266.29868 -271.43837)
		(width 0.14478)
		(layer "In11.Cu")
		(net "M_F_CPU0_SB_CB<6>")
	)
	(segment
		(start 269.07998 -272.560034)
		(end 273.96313 -272.560034)
		(width 0.14478)
		(layer "In11.Cu")
		(net "M_F_CPU0_SB_CB<6>")
	)
	(segment
		(start 268.917166 -271.601184)
		(end 268.917166 -272.39722)
		(width 0.14478)
		(layer "In11.Cu")
		(net "M_F_CPU0_SB_CB<6>")
	)
	(segment
		(start 268.754352 -271.43837)
		(end 268.917166 -271.601184)
		(width 0.14478)
		(layer "In11.Cu")
		(net "M_F_CPU0_SB_CB<6>")
	)
	(segment
		(start 323.915024 -268.05128)
		(end 324.169024 -268.05128)
		(width 0.0889)
		(layer "In11.Cu")
		(net "M_F_CPU0_SB_CB<6>")
	)
	(segment
		(start 268.360906 -271.601184)
		(end 268.52372 -271.43837)
		(width 0.14478)
		(layer "In11.Cu")
		(net "M_F_CPU0_SB_CB<6>")
	)
	(segment
		(start 330.119736 -269.70863)
		(end 330.128118 -269.713456)
		(width 0.0889)
		(layer "In11.Cu")
		(net "M_F_CPU0_SB_CB<6>")
	)
	(segment
		(start 326.368918 -269.71371)
		(end 326.390508 -269.726156)
		(width 0.0889)
		(layer "In11.Cu")
		(net "M_F_CPU0_SB_CB<6>")
	)
	(segment
		(start 332.607158 -269.770606)
		(end 332.761082 -270.036036)
		(width 0.0889)
		(layer "In11.Cu")
		(net "M_F_CPU0_SB_CB<6>")
	)
	(segment
		(start 267.39596 -271.45361)
		(end 267.601192 -271.45361)
		(width 0.14478)
		(layer "In11.Cu")
		(net "M_F_CPU0_SB_CB<6>")
	)
	(segment
		(start 273.96313 -272.560034)
		(end 274.813014 -271.71015)
		(width 0.14478)
		(layer "In11.Cu")
		(net "M_F_CPU0_SB_CB<6>")
	)
	(segment
		(start 268.360906 -272.39722)
		(end 268.360906 -271.601184)
		(width 0.14478)
		(layer "In11.Cu")
		(net "M_F_CPU0_SB_CB<6>")
	)
	(segment
		(start 265.54811 -272.984976)
		(end 266.135866 -272.39722)
		(width 0.14478)
		(layer "In11.Cu")
		(net "M_F_CPU0_SB_CB<6>")
	)
	(segment
		(start 267.601192 -271.45361)
		(end 267.804646 -271.657064)
		(width 0.14478)
		(layer "In11.Cu")
		(net "M_F_CPU0_SB_CB<6>")
	)
	(segment
		(start 267.804646 -272.39722)
		(end 267.96746 -272.560034)
		(width 0.14478)
		(layer "In11.Cu")
		(net "M_F_CPU0_SB_CB<6>")
	)
	(segment
		(start 330.69403 -269.713456)
		(end 330.702412 -269.70863)
		(width 0.0889)
		(layer "In11.Cu")
		(net "M_F_CPU0_SB_CB<6>")
	)
	(segment
		(start 266.135866 -272.39722)
		(end 266.135866 -271.601184)
		(width 0.14478)
		(layer "In11.Cu")
		(net "M_F_CPU0_SB_CB<6>")
	)
	(segment
		(start 268.52372 -271.43837)
		(end 268.754352 -271.43837)
		(width 0.14478)
		(layer "In11.Cu")
		(net "M_F_CPU0_SB_CB<6>")
	)
	(segment
		(start 267.248386 -271.601184)
		(end 267.39596 -271.45361)
		(width 0.14478)
		(layer "In11.Cu")
		(net "M_F_CPU0_SB_CB<6>")
	)
	(segment
		(start 324.683882 -268.566138)
		(end 325.194168 -268.566138)
		(width 0.0889)
		(layer "In11.Cu")
		(net "M_F_CPU0_SB_CB<6>")
	)
	(segment
		(start 327.290684 -269.703296)
		(end 327.308972 -269.71371)
		(width 0.0889)
		(layer "In11.Cu")
		(net "M_F_CPU0_SB_CB<6>")
	)
	(segment
		(start 325.194168 -268.566138)
		(end 326.252586 -269.624556)
		(width 0.0889)
		(layer "In11.Cu")
		(net "M_F_CPU0_SB_CB<6>")
	)
	(segment
		(start 312.36666 -268.05128)
		(end 323.915024 -268.05128)
		(width 0.14478)
		(layer "In11.Cu")
		(net "M_F_CPU0_SB_CB<6>")
	)
	(segment
		(start 267.96746 -272.560034)
		(end 268.198092 -272.560034)
		(width 0.14478)
		(layer "In11.Cu")
		(net "M_F_CPU0_SB_CB<6>")
	)
	(segment
		(start 331.634084 -269.713456)
		(end 331.642466 -269.70863)
		(width 0.0889)
		(layer "In11.Cu")
		(net "M_F_CPU0_SB_CB<6>")
	)
	(segment
		(start 274.813014 -271.71015)
		(end 308.70779 -271.71015)
		(width 0.14478)
		(layer "In11.Cu")
		(net "M_F_CPU0_SB_CB<6>")
	)
	(segment
		(start 266.29868 -271.43837)
		(end 266.529312 -271.43837)
		(width 0.14478)
		(layer "In11.Cu")
		(net "M_F_CPU0_SB_CB<6>")
	)
	(segment
		(start 308.70779 -271.71015)
		(end 312.36666 -268.05128)
		(width 0.14478)
		(layer "In11.Cu")
		(net "M_F_CPU0_SB_CB<6>")
	)
	(segment
		(start 266.85494 -272.560034)
		(end 267.085572 -272.560034)
		(width 0.14478)
		(layer "In11.Cu")
		(net "M_F_CPU0_SB_CB<6>")
	)
	(arc
		(start 331.068172 -269.713456)
		(mid 331.351128 -269.789633)
		(end 331.634084 -269.713456)
		(width 0.0889)
		(layer "In11.Cu")
		(net "M_F_CPU0_SB_CB<6>")
	)
	(arc
		(start 330.128118 -269.713456)
		(mid 330.411074 -269.789633)
		(end 330.69403 -269.713456)
		(width 0.0889)
		(layer "In11.Cu")
		(net "M_F_CPU0_SB_CB<6>")
	)
	(arc
		(start 326.93483 -269.713456)
		(mid 327.111458 -269.663223)
		(end 327.290684 -269.703296)
		(width 0.0889)
		(layer "In11.Cu")
		(net "M_F_CPU0_SB_CB<6>")
	)
	(arc
		(start 326.390508 -269.726156)
		(mid 326.664298 -269.789827)
		(end 326.93483 -269.713456)
		(width 0.0889)
		(layer "In11.Cu")
		(net "M_F_CPU0_SB_CB<6>")
	)
	(arc
		(start 327.882504 -269.70863)
		(mid 328.066012 -269.663136)
		(end 328.248264 -269.713456)
		(width 0.0889)
		(layer "In11.Cu")
		(net "M_F_CPU0_SB_CB<6>")
	)
	(arc
		(start 329.753976 -269.713456)
		(mid 329.936227 -269.663106)
		(end 330.119736 -269.70863)
		(width 0.0889)
		(layer "In11.Cu")
		(net "M_F_CPU0_SB_CB<6>")
	)
	(arc
		(start 328.248264 -269.713456)
		(mid 328.53122 -269.789633)
		(end 328.814176 -269.713456)
		(width 0.0889)
		(layer "In11.Cu")
		(net "M_F_CPU0_SB_CB<6>")
	)
	(arc
		(start 327.32091 -269.720568)
		(mid 327.598444 -269.789549)
		(end 327.874122 -269.713456)
		(width 0.0889)
		(layer "In11.Cu")
		(net "M_F_CPU0_SB_CB<6>")
	)
	(arc
		(start 330.702412 -269.70863)
		(mid 330.88592 -269.663136)
		(end 331.068172 -269.713456)
		(width 0.0889)
		(layer "In11.Cu")
		(net "M_F_CPU0_SB_CB<6>")
	)
	(arc
		(start 331.642466 -269.70863)
		(mid 331.825974 -269.663136)
		(end 332.008226 -269.713456)
		(width 0.0889)
		(layer "In11.Cu")
		(net "M_F_CPU0_SB_CB<6>")
	)
	(arc
		(start 329.188064 -269.713456)
		(mid 329.47102 -269.789633)
		(end 329.753976 -269.713456)
		(width 0.0889)
		(layer "In11.Cu")
		(net "M_F_CPU0_SB_CB<6>")
	)
	(arc
		(start 328.814176 -269.713456)
		(mid 329.00112 -269.663201)
		(end 329.188064 -269.713456)
		(width 0.0889)
		(layer "In11.Cu")
		(net "M_F_CPU0_SB_CB<6>")
	)
	(arc
		(start 332.008226 -269.713456)
		(mid 332.255939 -269.788676)
		(end 332.511146 -269.745206)
		(width 0.0889)
		(layer "In11.Cu")
		(net "M_F_CPU0_SB_CB<6>")
	)
	(arc
		(start 326.252586 -269.624556)
		(mid 326.307836 -269.672938)
		(end 326.368918 -269.71371)
		(width 0.0889)
		(layer "In11.Cu")
		(net "M_F_CPU0_SB_CB<6>")
	)
	(segment
		(start 334.167988 -269.770098)
		(end 333.701136 -270.036036)
		(width 0.10668)
		(layer "F.Cu")
		(net "M_F_CPU0_SB_CB<5>")
	)
	(segment
		(start 298.577762 -272.86839)
		(end 298.825666 -272.86839)
		(width 0.14478)
		(layer "In11.Cu")
		(net "M_F_CPU0_SB_CB<5>")
	)
	(segment
		(start 271.021048 -273.802348)
		(end 271.25168 -273.802348)
		(width 0.14478)
		(layer "In11.Cu")
		(net "M_F_CPU0_SB_CB<5>")
	)
	(segment
		(start 285.60268 -272.88109)
		(end 285.923736 -272.560034)
		(width 0.14478)
		(layer "In11.Cu")
		(net "M_F_CPU0_SB_CB<5>")
	)
	(segment
		(start 270.464788 -273.018504)
		(end 270.69542 -273.018504)
		(width 0.14478)
		(layer "In11.Cu")
		(net "M_F_CPU0_SB_CB<5>")
	)
	(segment
		(start 294.38219 -272.87347)
		(end 294.695626 -272.560034)
		(width 0.14478)
		(layer "In11.Cu")
		(net "M_F_CPU0_SB_CB<5>")
	)
	(segment
		(start 288.981896 -272.87601)
		(end 289.297872 -272.560034)
		(width 0.14478)
		(layer "In11.Cu")
		(net "M_F_CPU0_SB_CB<5>")
	)
	(segment
		(start 286.7152 -272.88109)
		(end 287.036256 -272.560034)
		(width 0.14478)
		(layer "In11.Cu")
		(net "M_F_CPU0_SB_CB<5>")
	)
	(segment
		(start 271.970754 -273.639534)
		(end 272.133568 -273.802348)
		(width 0.14478)
		(layer "In11.Cu")
		(net "M_F_CPU0_SB_CB<5>")
	)
	(segment
		(start 306.17541 -272.429732)
		(end 306.32019 -272.574512)
		(width 0.14478)
		(layer "In11.Cu")
		(net "M_F_CPU0_SB_CB<5>")
	)
	(segment
		(start 278.685752 -272.560034)
		(end 278.986488 -272.86077)
		(width 0.14478)
		(layer "In11.Cu")
		(net "M_F_CPU0_SB_CB<5>")
	)
	(segment
		(start 305.768756 -272.73885)
		(end 305.768756 -272.574512)
		(width 0.14478)
		(layer "In11.Cu")
		(net "M_F_CPU0_SB_CB<5>")
	)
	(segment
		(start 279.542748 -272.560034)
		(end 280.972768 -272.560034)
		(width 0.14478)
		(layer "In11.Cu")
		(net "M_F_CPU0_SB_CB<5>")
	)
	(segment
		(start 285.04642 -272.560034)
		(end 285.367476 -272.88109)
		(width 0.14478)
		(layer "In11.Cu")
		(net "M_F_CPU0_SB_CB<5>")
	)
	(segment
		(start 333.85506 -270.301466)
		(end 333.701136 -270.036036)
		(width 0.0889)
		(layer "In11.Cu")
		(net "M_F_CPU0_SB_CB<5>")
	)
	(segment
		(start 302.743362 -272.88363)
		(end 304.521108 -272.88363)
		(width 0.14478)
		(layer "In11.Cu")
		(net "M_F_CPU0_SB_CB<5>")
	)
	(segment
		(start 281.278584 -272.86585)
		(end 281.529028 -272.86585)
		(width 0.14478)
		(layer "In11.Cu")
		(net "M_F_CPU0_SB_CB<5>")
	)
	(segment
		(start 306.32019 -272.73885)
		(end 306.46497 -272.88363)
		(width 0.14478)
		(layer "In11.Cu")
		(net "M_F_CPU0_SB_CB<5>")
	)
	(segment
		(start 302.187102 -272.560034)
		(end 302.419766 -272.560034)
		(width 0.14478)
		(layer "In11.Cu")
		(net "M_F_CPU0_SB_CB<5>")
	)
	(segment
		(start 272.756376 -273.410172)
		(end 274.103846 -273.410172)
		(width 0.14478)
		(layer "In11.Cu")
		(net "M_F_CPU0_SB_CB<5>")
	)
	(segment
		(start 298.021502 -272.560034)
		(end 298.269406 -272.560034)
		(width 0.14478)
		(layer "In11.Cu")
		(net "M_F_CPU0_SB_CB<5>")
	)
	(segment
		(start 290.650676 -272.560034)
		(end 290.966652 -272.87601)
		(width 0.14478)
		(layer "In11.Cu")
		(net "M_F_CPU0_SB_CB<5>")
	)
	(segment
		(start 300.750986 -272.88363)
		(end 301.074582 -272.560034)
		(width 0.14478)
		(layer "In11.Cu")
		(net "M_F_CPU0_SB_CB<5>")
	)
	(segment
		(start 304.665888 -272.73885)
		(end 304.665888 -272.574512)
		(width 0.14478)
		(layer "In11.Cu")
		(net "M_F_CPU0_SB_CB<5>")
	)
	(segment
		(start 323.887084 -268.50594)
		(end 324.191884 -268.50594)
		(width 0.0889)
		(layer "In11.Cu")
		(net "M_F_CPU0_SB_CB<5>")
	)
	(segment
		(start 306.806346 -272.88363)
		(end 307.129942 -272.560034)
		(width 0.14478)
		(layer "In11.Cu")
		(net "M_F_CPU0_SB_CB<5>")
	)
	(segment
		(start 289.538156 -272.560034)
		(end 289.854132 -272.87601)
		(width 0.14478)
		(layer "In11.Cu")
		(net "M_F_CPU0_SB_CB<5>")
	)
	(segment
		(start 324.191884 -268.50594)
		(end 324.510654 -268.82471)
		(width 0.0889)
		(layer "In11.Cu")
		(net "M_F_CPU0_SB_CB<5>")
	)
	(segment
		(start 274.103846 -273.410172)
		(end 274.953984 -272.560034)
		(width 0.14478)
		(layer "In11.Cu")
		(net "M_F_CPU0_SB_CB<5>")
	)
	(segment
		(start 275.945092 -272.86585)
		(end 276.250908 -272.560034)
		(width 0.14478)
		(layer "In11.Cu")
		(net "M_F_CPU0_SB_CB<5>")
	)
	(segment
		(start 278.129492 -272.86077)
		(end 278.430228 -272.560034)
		(width 0.14478)
		(layer "In11.Cu")
		(net "M_F_CPU0_SB_CB<5>")
	)
	(segment
		(start 296.044366 -272.560034)
		(end 296.352722 -272.86839)
		(width 0.14478)
		(layer "In11.Cu")
		(net "M_F_CPU0_SB_CB<5>")
	)
	(segment
		(start 305.913536 -272.429732)
		(end 306.17541 -272.429732)
		(width 0.14478)
		(layer "In11.Cu")
		(net "M_F_CPU0_SB_CB<5>")
	)
	(segment
		(start 306.46497 -272.88363)
		(end 306.806346 -272.88363)
		(width 0.14478)
		(layer "In11.Cu")
		(net "M_F_CPU0_SB_CB<5>")
	)
	(segment
		(start 282.085288 -272.560034)
		(end 282.391104 -272.86585)
		(width 0.14478)
		(layer "In11.Cu")
		(net "M_F_CPU0_SB_CB<5>")
	)
	(segment
		(start 296.600626 -272.86839)
		(end 296.908982 -272.560034)
		(width 0.14478)
		(layer "In11.Cu")
		(net "M_F_CPU0_SB_CB<5>")
	)
	(segment
		(start 296.908982 -272.560034)
		(end 297.156886 -272.560034)
		(width 0.14478)
		(layer "In11.Cu")
		(net "M_F_CPU0_SB_CB<5>")
	)
	(segment
		(start 271.970754 -273.181318)
		(end 271.970754 -273.639534)
		(width 0.14478)
		(layer "In11.Cu")
		(net "M_F_CPU0_SB_CB<5>")
	)
	(segment
		(start 270.69542 -273.018504)
		(end 270.858234 -273.181318)
		(width 0.14478)
		(layer "In11.Cu")
		(net "M_F_CPU0_SB_CB<5>")
	)
	(segment
		(start 271.80794 -273.018504)
		(end 271.970754 -273.181318)
		(width 0.14478)
		(layer "In11.Cu")
		(net "M_F_CPU0_SB_CB<5>")
	)
	(segment
		(start 286.15894 -272.560034)
		(end 286.479996 -272.88109)
		(width 0.14478)
		(layer "In11.Cu")
		(net "M_F_CPU0_SB_CB<5>")
	)
	(segment
		(start 305.217322 -272.73885)
		(end 305.362102 -272.88363)
		(width 0.14478)
		(layer "In11.Cu")
		(net "M_F_CPU0_SB_CB<5>")
	)
	(segment
		(start 277.573232 -272.560034)
		(end 277.873968 -272.86077)
		(width 0.14478)
		(layer "In11.Cu")
		(net "M_F_CPU0_SB_CB<5>")
	)
	(segment
		(start 300.194726 -272.560034)
		(end 300.518322 -272.88363)
		(width 0.14478)
		(layer "In11.Cu")
		(net "M_F_CPU0_SB_CB<5>")
	)
	(segment
		(start 275.694648 -272.86585)
		(end 275.945092 -272.86585)
		(width 0.14478)
		(layer "In11.Cu")
		(net "M_F_CPU0_SB_CB<5>")
	)
	(segment
		(start 290.094416 -272.87601)
		(end 290.410392 -272.560034)
		(width 0.14478)
		(layer "In11.Cu")
		(net "M_F_CPU0_SB_CB<5>")
	)
	(segment
		(start 301.074582 -272.560034)
		(end 301.307246 -272.560034)
		(width 0.14478)
		(layer "In11.Cu")
		(net "M_F_CPU0_SB_CB<5>")
	)
	(segment
		(start 270.858234 -273.639534)
		(end 271.021048 -273.802348)
		(width 0.14478)
		(layer "In11.Cu")
		(net "M_F_CPU0_SB_CB<5>")
	)
	(segment
		(start 298.825666 -272.86839)
		(end 299.134022 -272.560034)
		(width 0.14478)
		(layer "In11.Cu")
		(net "M_F_CPU0_SB_CB<5>")
	)
	(segment
		(start 297.156886 -272.560034)
		(end 297.465242 -272.86839)
		(width 0.14478)
		(layer "In11.Cu")
		(net "M_F_CPU0_SB_CB<5>")
	)
	(segment
		(start 333.832708 -270.384778)
		(end 333.85506 -270.301466)
		(width 0.0889)
		(layer "In11.Cu")
		(net "M_F_CPU0_SB_CB<5>")
	)
	(segment
		(start 280.972768 -272.560034)
		(end 281.278584 -272.86585)
		(width 0.14478)
		(layer "In11.Cu")
		(net "M_F_CPU0_SB_CB<5>")
	)
	(segment
		(start 312.548016 -268.50594)
		(end 323.887084 -268.50594)
		(width 0.14478)
		(layer "In11.Cu")
		(net "M_F_CPU0_SB_CB<5>")
	)
	(segment
		(start 293.82593 -272.560034)
		(end 294.139366 -272.87347)
		(width 0.14478)
		(layer "In11.Cu")
		(net "M_F_CPU0_SB_CB<5>")
	)
	(segment
		(start 330.69403 -270.358616)
		(end 330.702412 -270.363442)
		(width 0.0889)
		(layer "In11.Cu")
		(net "M_F_CPU0_SB_CB<5>")
	)
	(segment
		(start 278.986488 -272.86077)
		(end 279.242012 -272.86077)
		(width 0.14478)
		(layer "In11.Cu")
		(net "M_F_CPU0_SB_CB<5>")
	)
	(segment
		(start 294.139366 -272.87347)
		(end 294.38219 -272.87347)
		(width 0.14478)
		(layer "In11.Cu")
		(net "M_F_CPU0_SB_CB<5>")
	)
	(segment
		(start 292.71341 -272.560034)
		(end 293.026846 -272.87347)
		(width 0.14478)
		(layer "In11.Cu")
		(net "M_F_CPU0_SB_CB<5>")
	)
	(segment
		(start 306.32019 -272.574512)
		(end 306.32019 -272.73885)
		(width 0.14478)
		(layer "In11.Cu")
		(net "M_F_CPU0_SB_CB<5>")
	)
	(segment
		(start 283.197808 -272.560034)
		(end 283.503624 -272.86585)
		(width 0.14478)
		(layer "In11.Cu")
		(net "M_F_CPU0_SB_CB<5>")
	)
	(segment
		(start 305.768756 -272.574512)
		(end 305.913536 -272.429732)
		(width 0.14478)
		(layer "In11.Cu")
		(net "M_F_CPU0_SB_CB<5>")
	)
	(segment
		(start 293.26967 -272.87347)
		(end 293.583106 -272.560034)
		(width 0.14478)
		(layer "In11.Cu")
		(net "M_F_CPU0_SB_CB<5>")
	)
	(segment
		(start 277.873968 -272.86077)
		(end 278.129492 -272.86077)
		(width 0.14478)
		(layer "In11.Cu")
		(net "M_F_CPU0_SB_CB<5>")
	)
	(segment
		(start 330.119736 -270.363442)
		(end 330.128118 -270.358616)
		(width 0.0889)
		(layer "In11.Cu")
		(net "M_F_CPU0_SB_CB<5>")
	)
	(segment
		(start 271.25168 -273.802348)
		(end 271.414494 -273.639534)
		(width 0.14478)
		(layer "In11.Cu")
		(net "M_F_CPU0_SB_CB<5>")
	)
	(segment
		(start 294.695626 -272.560034)
		(end 296.044366 -272.560034)
		(width 0.14478)
		(layer "In11.Cu")
		(net "M_F_CPU0_SB_CB<5>")
	)
	(segment
		(start 283.754068 -272.86585)
		(end 284.059884 -272.560034)
		(width 0.14478)
		(layer "In11.Cu")
		(net "M_F_CPU0_SB_CB<5>")
	)
	(segment
		(start 301.863506 -272.88363)
		(end 302.187102 -272.560034)
		(width 0.14478)
		(layer "In11.Cu")
		(net "M_F_CPU0_SB_CB<5>")
	)
	(segment
		(start 272.3642 -273.802348)
		(end 272.756376 -273.410172)
		(width 0.14478)
		(layer "In11.Cu")
		(net "M_F_CPU0_SB_CB<5>")
	)
	(segment
		(start 287.036256 -272.560034)
		(end 288.425636 -272.560034)
		(width 0.14478)
		(layer "In11.Cu")
		(net "M_F_CPU0_SB_CB<5>")
	)
	(segment
		(start 279.242012 -272.86077)
		(end 279.542748 -272.560034)
		(width 0.14478)
		(layer "In11.Cu")
		(net "M_F_CPU0_SB_CB<5>")
	)
	(segment
		(start 281.529028 -272.86585)
		(end 281.834844 -272.560034)
		(width 0.14478)
		(layer "In11.Cu")
		(net "M_F_CPU0_SB_CB<5>")
	)
	(segment
		(start 282.391104 -272.86585)
		(end 282.641548 -272.86585)
		(width 0.14478)
		(layer "In11.Cu")
		(net "M_F_CPU0_SB_CB<5>")
	)
	(segment
		(start 331.634084 -270.358616)
		(end 331.642466 -270.363442)
		(width 0.0889)
		(layer "In11.Cu")
		(net "M_F_CPU0_SB_CB<5>")
	)
	(segment
		(start 289.297872 -272.560034)
		(end 289.538156 -272.560034)
		(width 0.14478)
		(layer "In11.Cu")
		(net "M_F_CPU0_SB_CB<5>")
	)
	(segment
		(start 269.648178 -273.835114)
		(end 270.464788 -273.018504)
		(width 0.14478)
		(layer "In11.Cu")
		(net "M_F_CPU0_SB_CB<5>")
	)
	(segment
		(start 271.414494 -273.181318)
		(end 271.577308 -273.018504)
		(width 0.14478)
		(layer "In11.Cu")
		(net "M_F_CPU0_SB_CB<5>")
	)
	(segment
		(start 297.465242 -272.86839)
		(end 297.713146 -272.86839)
		(width 0.14478)
		(layer "In11.Cu")
		(net "M_F_CPU0_SB_CB<5>")
	)
	(segment
		(start 307.129942 -272.560034)
		(end 308.493922 -272.560034)
		(width 0.14478)
		(layer "In11.Cu")
		(net "M_F_CPU0_SB_CB<5>")
	)
	(segment
		(start 271.577308 -273.018504)
		(end 271.80794 -273.018504)
		(width 0.14478)
		(layer "In11.Cu")
		(net "M_F_CPU0_SB_CB<5>")
	)
	(segment
		(start 304.521108 -272.88363)
		(end 304.665888 -272.73885)
		(width 0.14478)
		(layer "In11.Cu")
		(net "M_F_CPU0_SB_CB<5>")
	)
	(segment
		(start 282.947364 -272.560034)
		(end 283.197808 -272.560034)
		(width 0.14478)
		(layer "In11.Cu")
		(net "M_F_CPU0_SB_CB<5>")
	)
	(segment
		(start 274.953984 -272.560034)
		(end 275.388832 -272.560034)
		(width 0.14478)
		(layer "In11.Cu")
		(net "M_F_CPU0_SB_CB<5>")
	)
	(segment
		(start 301.307246 -272.560034)
		(end 301.630842 -272.88363)
		(width 0.14478)
		(layer "In11.Cu")
		(net "M_F_CPU0_SB_CB<5>")
	)
	(segment
		(start 286.479996 -272.88109)
		(end 286.7152 -272.88109)
		(width 0.14478)
		(layer "In11.Cu")
		(net "M_F_CPU0_SB_CB<5>")
	)
	(segment
		(start 308.493922 -272.560034)
		(end 312.548016 -268.50594)
		(width 0.14478)
		(layer "In11.Cu")
		(net "M_F_CPU0_SB_CB<5>")
	)
	(segment
		(start 288.425636 -272.560034)
		(end 288.741612 -272.87601)
		(width 0.14478)
		(layer "In11.Cu")
		(net "M_F_CPU0_SB_CB<5>")
	)
	(segment
		(start 326.411844 -270.158718)
		(end 327.132696 -270.158718)
		(width 0.0889)
		(layer "In11.Cu")
		(net "M_F_CPU0_SB_CB<5>")
	)
	(segment
		(start 285.367476 -272.88109)
		(end 285.60268 -272.88109)
		(width 0.14478)
		(layer "In11.Cu")
		(net "M_F_CPU0_SB_CB<5>")
	)
	(segment
		(start 300.518322 -272.88363)
		(end 300.750986 -272.88363)
		(width 0.14478)
		(layer "In11.Cu")
		(net "M_F_CPU0_SB_CB<5>")
	)
	(segment
		(start 305.072542 -272.429732)
		(end 305.217322 -272.574512)
		(width 0.14478)
		(layer "In11.Cu")
		(net "M_F_CPU0_SB_CB<5>")
	)
	(segment
		(start 325.030846 -268.82471)
		(end 326.33158 -270.125444)
		(width 0.0889)
		(layer "In11.Cu")
		(net "M_F_CPU0_SB_CB<5>")
	)
	(segment
		(start 298.269406 -272.560034)
		(end 298.577762 -272.86839)
		(width 0.14478)
		(layer "In11.Cu")
		(net "M_F_CPU0_SB_CB<5>")
	)
	(segment
		(start 304.810668 -272.429732)
		(end 305.072542 -272.429732)
		(width 0.14478)
		(layer "In11.Cu")
		(net "M_F_CPU0_SB_CB<5>")
	)
	(segment
		(start 293.583106 -272.560034)
		(end 293.82593 -272.560034)
		(width 0.14478)
		(layer "In11.Cu")
		(net "M_F_CPU0_SB_CB<5>")
	)
	(segment
		(start 290.966652 -272.87601)
		(end 291.206936 -272.87601)
		(width 0.14478)
		(layer "In11.Cu")
		(net "M_F_CPU0_SB_CB<5>")
	)
	(segment
		(start 271.414494 -273.639534)
		(end 271.414494 -273.181318)
		(width 0.14478)
		(layer "In11.Cu")
		(net "M_F_CPU0_SB_CB<5>")
	)
	(segment
		(start 276.250908 -272.560034)
		(end 277.573232 -272.560034)
		(width 0.14478)
		(layer "In11.Cu")
		(net "M_F_CPU0_SB_CB<5>")
	)
	(segment
		(start 305.623976 -272.88363)
		(end 305.768756 -272.73885)
		(width 0.14478)
		(layer "In11.Cu")
		(net "M_F_CPU0_SB_CB<5>")
	)
	(segment
		(start 304.665888 -272.574512)
		(end 304.810668 -272.429732)
		(width 0.14478)
		(layer "In11.Cu")
		(net "M_F_CPU0_SB_CB<5>")
	)
	(segment
		(start 290.410392 -272.560034)
		(end 290.650676 -272.560034)
		(width 0.14478)
		(layer "In11.Cu")
		(net "M_F_CPU0_SB_CB<5>")
	)
	(segment
		(start 301.630842 -272.88363)
		(end 301.863506 -272.88363)
		(width 0.14478)
		(layer "In11.Cu")
		(net "M_F_CPU0_SB_CB<5>")
	)
	(segment
		(start 305.362102 -272.88363)
		(end 305.623976 -272.88363)
		(width 0.14478)
		(layer "In11.Cu")
		(net "M_F_CPU0_SB_CB<5>")
	)
	(segment
		(start 305.217322 -272.574512)
		(end 305.217322 -272.73885)
		(width 0.14478)
		(layer "In11.Cu")
		(net "M_F_CPU0_SB_CB<5>")
	)
	(segment
		(start 272.133568 -273.802348)
		(end 272.3642 -273.802348)
		(width 0.14478)
		(layer "In11.Cu")
		(net "M_F_CPU0_SB_CB<5>")
	)
	(segment
		(start 291.206936 -272.87601)
		(end 291.522912 -272.560034)
		(width 0.14478)
		(layer "In11.Cu")
		(net "M_F_CPU0_SB_CB<5>")
	)
	(segment
		(start 296.352722 -272.86839)
		(end 296.600626 -272.86839)
		(width 0.14478)
		(layer "In11.Cu")
		(net "M_F_CPU0_SB_CB<5>")
	)
	(segment
		(start 282.641548 -272.86585)
		(end 282.947364 -272.560034)
		(width 0.14478)
		(layer "In11.Cu")
		(net "M_F_CPU0_SB_CB<5>")
	)
	(segment
		(start 289.854132 -272.87601)
		(end 290.094416 -272.87601)
		(width 0.14478)
		(layer "In11.Cu")
		(net "M_F_CPU0_SB_CB<5>")
	)
	(segment
		(start 281.834844 -272.560034)
		(end 282.085288 -272.560034)
		(width 0.14478)
		(layer "In11.Cu")
		(net "M_F_CPU0_SB_CB<5>")
	)
	(segment
		(start 284.059884 -272.560034)
		(end 285.04642 -272.560034)
		(width 0.14478)
		(layer "In11.Cu")
		(net "M_F_CPU0_SB_CB<5>")
	)
	(segment
		(start 299.134022 -272.560034)
		(end 300.194726 -272.560034)
		(width 0.14478)
		(layer "In11.Cu")
		(net "M_F_CPU0_SB_CB<5>")
	)
	(segment
		(start 288.741612 -272.87601)
		(end 288.981896 -272.87601)
		(width 0.14478)
		(layer "In11.Cu")
		(net "M_F_CPU0_SB_CB<5>")
	)
	(segment
		(start 283.503624 -272.86585)
		(end 283.754068 -272.86585)
		(width 0.14478)
		(layer "In11.Cu")
		(net "M_F_CPU0_SB_CB<5>")
	)
	(segment
		(start 270.858234 -273.181318)
		(end 270.858234 -273.639534)
		(width 0.14478)
		(layer "In11.Cu")
		(net "M_F_CPU0_SB_CB<5>")
	)
	(segment
		(start 275.388832 -272.560034)
		(end 275.694648 -272.86585)
		(width 0.14478)
		(layer "In11.Cu")
		(net "M_F_CPU0_SB_CB<5>")
	)
	(segment
		(start 285.923736 -272.560034)
		(end 286.15894 -272.560034)
		(width 0.14478)
		(layer "In11.Cu")
		(net "M_F_CPU0_SB_CB<5>")
	)
	(segment
		(start 291.522912 -272.560034)
		(end 292.71341 -272.560034)
		(width 0.14478)
		(layer "In11.Cu")
		(net "M_F_CPU0_SB_CB<5>")
	)
	(segment
		(start 278.430228 -272.560034)
		(end 278.685752 -272.560034)
		(width 0.14478)
		(layer "In11.Cu")
		(net "M_F_CPU0_SB_CB<5>")
	)
	(segment
		(start 293.026846 -272.87347)
		(end 293.26967 -272.87347)
		(width 0.14478)
		(layer "In11.Cu")
		(net "M_F_CPU0_SB_CB<5>")
	)
	(segment
		(start 297.713146 -272.86839)
		(end 298.021502 -272.560034)
		(width 0.14478)
		(layer "In11.Cu")
		(net "M_F_CPU0_SB_CB<5>")
	)
	(segment
		(start 302.419766 -272.560034)
		(end 302.743362 -272.88363)
		(width 0.14478)
		(layer "In11.Cu")
		(net "M_F_CPU0_SB_CB<5>")
	)
	(segment
		(start 324.510654 -268.82471)
		(end 325.030846 -268.82471)
		(width 0.0889)
		(layer "In11.Cu")
		(net "M_F_CPU0_SB_CB<5>")
	)
	(arc
		(start 333.513938 -270.358616)
		(mid 333.670376 -270.407587)
		(end 333.832708 -270.384778)
		(width 0.0889)
		(layer "In11.Cu")
		(net "M_F_CPU0_SB_CB<5>")
	)
	(arc
		(start 330.702412 -270.363442)
		(mid 330.88592 -270.408936)
		(end 331.068172 -270.358616)
		(width 0.0889)
		(layer "In11.Cu")
		(net "M_F_CPU0_SB_CB<5>")
	)
	(arc
		(start 330.128118 -270.358616)
		(mid 330.411074 -270.282439)
		(end 330.69403 -270.358616)
		(width 0.0889)
		(layer "In11.Cu")
		(net "M_F_CPU0_SB_CB<5>")
	)
	(arc
		(start 332.008226 -270.358616)
		(mid 332.291182 -270.282439)
		(end 332.574138 -270.358616)
		(width 0.0889)
		(layer "In11.Cu")
		(net "M_F_CPU0_SB_CB<5>")
	)
	(arc
		(start 331.642466 -270.363442)
		(mid 331.825974 -270.408936)
		(end 332.008226 -270.358616)
		(width 0.0889)
		(layer "In11.Cu")
		(net "M_F_CPU0_SB_CB<5>")
	)
	(arc
		(start 327.132696 -270.158718)
		(mid 327.516528 -270.209563)
		(end 327.873868 -270.358616)
		(width 0.0889)
		(layer "In11.Cu")
		(net "M_F_CPU0_SB_CB<5>")
	)
	(arc
		(start 326.33158 -270.125444)
		(mid 326.368391 -270.150104)
		(end 326.411844 -270.158718)
		(width 0.0889)
		(layer "In11.Cu")
		(net "M_F_CPU0_SB_CB<5>")
	)
	(arc
		(start 327.873868 -270.358616)
		(mid 328.061066 -270.408998)
		(end 328.248264 -270.358616)
		(width 0.0889)
		(layer "In11.Cu")
		(net "M_F_CPU0_SB_CB<5>")
	)
	(arc
		(start 331.068172 -270.358616)
		(mid 331.351128 -270.282439)
		(end 331.634084 -270.358616)
		(width 0.0889)
		(layer "In11.Cu")
		(net "M_F_CPU0_SB_CB<5>")
	)
	(arc
		(start 329.753976 -270.358616)
		(mid 329.936227 -270.408966)
		(end 330.119736 -270.363442)
		(width 0.0889)
		(layer "In11.Cu")
		(net "M_F_CPU0_SB_CB<5>")
	)
	(arc
		(start 329.188064 -270.358616)
		(mid 329.47102 -270.282439)
		(end 329.753976 -270.358616)
		(width 0.0889)
		(layer "In11.Cu")
		(net "M_F_CPU0_SB_CB<5>")
	)
	(arc
		(start 328.248264 -270.358616)
		(mid 328.53122 -270.282439)
		(end 328.814176 -270.358616)
		(width 0.0889)
		(layer "In11.Cu")
		(net "M_F_CPU0_SB_CB<5>")
	)
	(arc
		(start 332.574138 -270.358616)
		(mid 332.761082 -270.408871)
		(end 332.948026 -270.358616)
		(width 0.0889)
		(layer "In11.Cu")
		(net "M_F_CPU0_SB_CB<5>")
	)
	(arc
		(start 332.948026 -270.358616)
		(mid 333.230982 -270.282439)
		(end 333.513938 -270.358616)
		(width 0.0889)
		(layer "In11.Cu")
		(net "M_F_CPU0_SB_CB<5>")
	)
	(arc
		(start 328.814176 -270.358616)
		(mid 329.00112 -270.408871)
		(end 329.188064 -270.358616)
		(width 0.0889)
		(layer "In11.Cu")
		(net "M_F_CPU0_SB_CB<5>")
	)
	(segment
		(start 332.758034 -268.960092)
		(end 332.291182 -269.22603)
		(width 0.10668)
		(layer "F.Cu")
		(net "M_F_CPU0_SB_CB<4>")
	)
	(segment
		(start 285.17977 -270.860012)
		(end 285.504128 -271.18437)
		(width 0.14478)
		(layer "In11.Cu")
		(net "M_F_CPU0_SB_CB<4>")
	)
	(segment
		(start 278.445722 -270.860012)
		(end 278.697944 -270.860012)
		(width 0.14478)
		(layer "In11.Cu")
		(net "M_F_CPU0_SB_CB<4>")
	)
	(segment
		(start 309.931816 -269.850108)
		(end 309.931816 -269.645384)
		(width 0.14478)
		(layer "In11.Cu")
		(net "M_F_CPU0_SB_CB<4>")
	)
	(segment
		(start 271.030954 -272.095976)
		(end 271.261586 -272.095976)
		(width 0.14478)
		(layer "In11.Cu")
		(net "M_F_CPU0_SB_CB<4>")
	)
	(segment
		(start 271.4244 -271.933162)
		(end 271.4244 -271.47139)
		(width 0.14478)
		(layer "In11.Cu")
		(net "M_F_CPU0_SB_CB<4>")
	)
	(segment
		(start 277.585424 -270.860012)
		(end 277.889462 -271.16405)
		(width 0.14478)
		(layer "In11.Cu")
		(net "M_F_CPU0_SB_CB<4>")
	)
	(segment
		(start 310.257952 -269.191232)
		(end 310.32196 -269.25524)
		(width 0.14478)
		(layer "In11.Cu")
		(net "M_F_CPU0_SB_CB<4>")
	)
	(segment
		(start 308.761384 -270.815816)
		(end 308.966108 -270.815816)
		(width 0.14478)
		(layer "In11.Cu")
		(net "M_F_CPU0_SB_CB<4>")
	)
	(segment
		(start 309.931816 -269.645384)
		(end 309.867808 -269.581376)
		(width 0.14478)
		(layer "In11.Cu")
		(net "M_F_CPU0_SB_CB<4>")
	)
	(segment
		(start 275.552154 -271.16913)
		(end 275.799296 -271.16913)
		(width 0.14478)
		(layer "In11.Cu")
		(net "M_F_CPU0_SB_CB<4>")
	)
	(segment
		(start 311.64784 -267.59662)
		(end 323.909944 -267.59662)
		(width 0.14478)
		(layer "In11.Cu")
		(net "M_F_CPU0_SB_CB<4>")
	)
	(segment
		(start 271.261586 -272.095976)
		(end 271.4244 -271.933162)
		(width 0.14478)
		(layer "In11.Cu")
		(net "M_F_CPU0_SB_CB<4>")
	)
	(segment
		(start 310.32196 -269.25524)
		(end 310.526684 -269.25524)
		(width 0.14478)
		(layer "In11.Cu")
		(net "M_F_CPU0_SB_CB<4>")
	)
	(segment
		(start 325.421244 -267.9827)
		(end 325.421244 -268.52372)
		(width 0.0889)
		(layer "In11.Cu")
		(net "M_F_CPU0_SB_CB<4>")
	)
	(segment
		(start 301.91202 -271.16405)
		(end 302.216058 -270.860012)
		(width 0.14478)
		(layer "In11.Cu")
		(net "M_F_CPU0_SB_CB<4>")
	)
	(segment
		(start 270.705326 -271.308576)
		(end 270.86814 -271.47139)
		(width 0.14478)
		(layer "In11.Cu")
		(net "M_F_CPU0_SB_CB<4>")
	)
	(segment
		(start 301.659798 -271.16405)
		(end 301.91202 -271.16405)
		(width 0.14478)
		(layer "In11.Cu")
		(net "M_F_CPU0_SB_CB<4>")
	)
	(segment
		(start 289.675316 -270.860012)
		(end 289.999674 -271.18437)
		(width 0.14478)
		(layer "In11.Cu")
		(net "M_F_CPU0_SB_CB<4>")
	)
	(segment
		(start 309.27294 -269.97152)
		(end 309.477664 -269.97152)
		(width 0.14478)
		(layer "In11.Cu")
		(net "M_F_CPU0_SB_CB<4>")
	)
	(segment
		(start 270.86814 -271.933162)
		(end 271.030954 -272.095976)
		(width 0.14478)
		(layer "In11.Cu")
		(net "M_F_CPU0_SB_CB<4>")
	)
	(segment
		(start 293.578026 -270.860012)
		(end 293.809928 -270.860012)
		(width 0.14478)
		(layer "In11.Cu")
		(net "M_F_CPU0_SB_CB<4>")
	)
	(segment
		(start 279.254204 -271.16405)
		(end 279.558242 -270.860012)
		(width 0.14478)
		(layer "In11.Cu")
		(net "M_F_CPU0_SB_CB<4>")
	)
	(segment
		(start 285.504128 -271.18437)
		(end 285.73603 -271.18437)
		(width 0.14478)
		(layer "In11.Cu")
		(net "M_F_CPU0_SB_CB<4>")
	)
	(segment
		(start 274.749006 -270.860012)
		(end 275.243036 -270.860012)
		(width 0.14478)
		(layer "In11.Cu")
		(net "M_F_CPU0_SB_CB<4>")
	)
	(segment
		(start 291.112194 -271.18437)
		(end 291.344096 -271.18437)
		(width 0.14478)
		(layer "In11.Cu")
		(net "M_F_CPU0_SB_CB<4>")
	)
	(segment
		(start 300.7995 -271.16405)
		(end 301.103538 -270.860012)
		(width 0.14478)
		(layer "In11.Cu")
		(net "M_F_CPU0_SB_CB<4>")
	)
	(segment
		(start 296.620946 -271.17675)
		(end 296.937684 -270.860012)
		(width 0.14478)
		(layer "In11.Cu")
		(net "M_F_CPU0_SB_CB<4>")
	)
	(segment
		(start 278.697944 -270.860012)
		(end 279.001982 -271.16405)
		(width 0.14478)
		(layer "In11.Cu")
		(net "M_F_CPU0_SB_CB<4>")
	)
	(segment
		(start 309.151528 -270.425672)
		(end 309.08752 -270.361664)
		(width 0.14478)
		(layer "In11.Cu")
		(net "M_F_CPU0_SB_CB<4>")
	)
	(segment
		(start 289.443414 -270.860012)
		(end 289.675316 -270.860012)
		(width 0.14478)
		(layer "In11.Cu")
		(net "M_F_CPU0_SB_CB<4>")
	)
	(segment
		(start 290.555934 -270.860012)
		(end 290.787836 -270.860012)
		(width 0.14478)
		(layer "In11.Cu")
		(net "M_F_CPU0_SB_CB<4>")
	)
	(segment
		(start 309.541672 -270.035528)
		(end 309.746396 -270.035528)
		(width 0.14478)
		(layer "In11.Cu")
		(net "M_F_CPU0_SB_CB<4>")
	)
	(segment
		(start 305.24958 -271.16405)
		(end 305.553618 -270.860012)
		(width 0.14478)
		(layer "In11.Cu")
		(net "M_F_CPU0_SB_CB<4>")
	)
	(segment
		(start 303.328578 -270.860012)
		(end 303.5808 -270.860012)
		(width 0.14478)
		(layer "In11.Cu")
		(net "M_F_CPU0_SB_CB<4>")
	)
	(segment
		(start 302.46828 -270.860012)
		(end 302.772318 -271.16405)
		(width 0.14478)
		(layer "In11.Cu")
		(net "M_F_CPU0_SB_CB<4>")
	)
	(segment
		(start 305.80584 -270.860012)
		(end 306.109878 -271.16405)
		(width 0.14478)
		(layer "In11.Cu")
		(net "M_F_CPU0_SB_CB<4>")
	)
	(segment
		(start 288.887154 -271.18437)
		(end 289.119056 -271.18437)
		(width 0.14478)
		(layer "In11.Cu")
		(net "M_F_CPU0_SB_CB<4>")
	)
	(segment
		(start 281.87142 -270.860012)
		(end 282.113482 -270.860012)
		(width 0.14478)
		(layer "In11.Cu")
		(net "M_F_CPU0_SB_CB<4>")
	)
	(segment
		(start 310.833516 -268.410944)
		(end 311.03824 -268.410944)
		(width 0.14478)
		(layer "In11.Cu")
		(net "M_F_CPU0_SB_CB<4>")
	)
	(segment
		(start 309.477664 -269.97152)
		(end 309.541672 -270.035528)
		(width 0.14478)
		(layer "In11.Cu")
		(net "M_F_CPU0_SB_CB<4>")
	)
	(segment
		(start 306.3621 -271.16405)
		(end 306.666138 -270.860012)
		(width 0.14478)
		(layer "In11.Cu")
		(net "M_F_CPU0_SB_CB<4>")
	)
	(segment
		(start 300.24324 -270.860012)
		(end 300.547278 -271.16405)
		(width 0.14478)
		(layer "In11.Cu")
		(net "M_F_CPU0_SB_CB<4>")
	)
	(segment
		(start 296.937684 -270.860012)
		(end 297.177206 -270.860012)
		(width 0.14478)
		(layer "In11.Cu")
		(net "M_F_CPU0_SB_CB<4>")
	)
	(segment
		(start 304.13706 -271.16405)
		(end 304.441098 -270.860012)
		(width 0.14478)
		(layer "In11.Cu")
		(net "M_F_CPU0_SB_CB<4>")
	)
	(segment
		(start 272.143474 -272.095976)
		(end 272.374106 -272.095976)
		(width 0.14478)
		(layer "In11.Cu")
		(net "M_F_CPU0_SB_CB<4>")
	)
	(segment
		(start 282.669742 -271.17421)
		(end 282.98394 -270.860012)
		(width 0.14478)
		(layer "In11.Cu")
		(net "M_F_CPU0_SB_CB<4>")
	)
	(segment
		(start 308.384448 -270.860012)
		(end 308.492652 -270.751808)
		(width 0.14478)
		(layer "In11.Cu")
		(net "M_F_CPU0_SB_CB<4>")
	)
	(segment
		(start 288.562796 -270.860012)
		(end 288.887154 -271.18437)
		(width 0.14478)
		(layer "In11.Cu")
		(net "M_F_CPU0_SB_CB<4>")
	)
	(segment
		(start 310.648096 -268.801088)
		(end 310.648096 -268.596364)
		(width 0.14478)
		(layer "In11.Cu")
		(net "M_F_CPU0_SB_CB<4>")
	)
	(segment
		(start 304.997358 -271.16405)
		(end 305.24958 -271.16405)
		(width 0.14478)
		(layer "In11.Cu")
		(net "M_F_CPU0_SB_CB<4>")
	)
	(segment
		(start 298.606464 -271.17675)
		(end 298.845986 -271.17675)
		(width 0.14478)
		(layer "In11.Cu")
		(net "M_F_CPU0_SB_CB<4>")
	)
	(segment
		(start 311.492392 -268.289532)
		(end 311.492392 -268.084808)
		(width 0.14478)
		(layer "In11.Cu")
		(net "M_F_CPU0_SB_CB<4>")
	)
	(segment
		(start 311.306972 -268.474952)
		(end 311.492392 -268.289532)
		(width 0.14478)
		(layer "In11.Cu")
		(net "M_F_CPU0_SB_CB<4>")
	)
	(segment
		(start 309.151528 -270.630396)
		(end 309.151528 -270.425672)
		(width 0.14478)
		(layer "In11.Cu")
		(net "M_F_CPU0_SB_CB<4>")
	)
	(segment
		(start 271.4244 -271.47139)
		(end 271.587214 -271.308576)
		(width 0.14478)
		(layer "In11.Cu")
		(net "M_F_CPU0_SB_CB<4>")
	)
	(segment
		(start 278.141684 -271.16405)
		(end 278.445722 -270.860012)
		(width 0.14478)
		(layer "In11.Cu")
		(net "M_F_CPU0_SB_CB<4>")
	)
	(segment
		(start 286.060388 -270.860012)
		(end 286.29229 -270.860012)
		(width 0.14478)
		(layer "In11.Cu")
		(net "M_F_CPU0_SB_CB<4>")
	)
	(segment
		(start 273.898868 -271.71015)
		(end 274.749006 -270.860012)
		(width 0.14478)
		(layer "In11.Cu")
		(net "M_F_CPU0_SB_CB<4>")
	)
	(segment
		(start 275.243036 -270.860012)
		(end 275.552154 -271.16913)
		(width 0.14478)
		(layer "In11.Cu")
		(net "M_F_CPU0_SB_CB<4>")
	)
	(segment
		(start 305.553618 -270.860012)
		(end 305.80584 -270.860012)
		(width 0.14478)
		(layer "In11.Cu")
		(net "M_F_CPU0_SB_CB<4>")
	)
	(segment
		(start 304.69332 -270.860012)
		(end 304.997358 -271.16405)
		(width 0.14478)
		(layer "In11.Cu")
		(net "M_F_CPU0_SB_CB<4>")
	)
	(segment
		(start 290.787836 -270.860012)
		(end 291.112194 -271.18437)
		(width 0.14478)
		(layer "In11.Cu")
		(net "M_F_CPU0_SB_CB<4>")
	)
	(segment
		(start 303.02454 -271.16405)
		(end 303.328578 -270.860012)
		(width 0.14478)
		(layer "In11.Cu")
		(net "M_F_CPU0_SB_CB<4>")
	)
	(segment
		(start 284.09646 -270.860012)
		(end 285.17977 -270.860012)
		(width 0.14478)
		(layer "In11.Cu")
		(net "M_F_CPU0_SB_CB<4>")
	)
	(segment
		(start 297.733466 -271.17675)
		(end 298.050204 -270.860012)
		(width 0.14478)
		(layer "In11.Cu")
		(net "M_F_CPU0_SB_CB<4>")
	)
	(segment
		(start 306.109878 -271.16405)
		(end 306.3621 -271.16405)
		(width 0.14478)
		(layer "In11.Cu")
		(net "M_F_CPU0_SB_CB<4>")
	)
	(segment
		(start 300.547278 -271.16405)
		(end 300.7995 -271.16405)
		(width 0.14478)
		(layer "In11.Cu")
		(net "M_F_CPU0_SB_CB<4>")
	)
	(segment
		(start 302.216058 -270.860012)
		(end 302.46828 -270.860012)
		(width 0.14478)
		(layer "In11.Cu")
		(net "M_F_CPU0_SB_CB<4>")
	)
	(segment
		(start 279.001982 -271.16405)
		(end 279.254204 -271.16405)
		(width 0.14478)
		(layer "In11.Cu")
		(net "M_F_CPU0_SB_CB<4>")
	)
	(segment
		(start 303.5808 -270.860012)
		(end 303.884838 -271.16405)
		(width 0.14478)
		(layer "In11.Cu")
		(net "M_F_CPU0_SB_CB<4>")
	)
	(segment
		(start 327.404476 -269.548356)
		(end 327.418192 -269.55623)
		(width 0.0889)
		(layer "In11.Cu")
		(net "M_F_CPU0_SB_CB<4>")
	)
	(segment
		(start 308.697376 -270.751808)
		(end 308.761384 -270.815816)
		(width 0.14478)
		(layer "In11.Cu")
		(net "M_F_CPU0_SB_CB<4>")
	)
	(segment
		(start 297.177206 -270.860012)
		(end 297.493944 -271.17675)
		(width 0.14478)
		(layer "In11.Cu")
		(net "M_F_CPU0_SB_CB<4>")
	)
	(segment
		(start 309.867808 -269.581376)
		(end 309.867808 -269.376652)
		(width 0.14478)
		(layer "In11.Cu")
		(net "M_F_CPU0_SB_CB<4>")
	)
	(segment
		(start 271.587214 -271.308576)
		(end 271.817846 -271.308576)
		(width 0.14478)
		(layer "In11.Cu")
		(net "M_F_CPU0_SB_CB<4>")
	)
	(segment
		(start 306.666138 -270.860012)
		(end 308.384448 -270.860012)
		(width 0.14478)
		(layer "In11.Cu")
		(net "M_F_CPU0_SB_CB<4>")
	)
	(segment
		(start 272.759932 -271.71015)
		(end 273.898868 -271.71015)
		(width 0.14478)
		(layer "In11.Cu")
		(net "M_F_CPU0_SB_CB<4>")
	)
	(segment
		(start 281.557222 -271.17421)
		(end 281.87142 -270.860012)
		(width 0.14478)
		(layer "In11.Cu")
		(net "M_F_CPU0_SB_CB<4>")
	)
	(segment
		(start 328.709782 -269.553436)
		(end 328.718164 -269.54861)
		(width 0.0889)
		(layer "In11.Cu")
		(net "M_F_CPU0_SB_CB<4>")
	)
	(segment
		(start 294.366188 -271.18437)
		(end 294.690546 -270.860012)
		(width 0.14478)
		(layer "In11.Cu")
		(net "M_F_CPU0_SB_CB<4>")
	)
	(segment
		(start 291.668454 -270.860012)
		(end 292.697408 -270.860012)
		(width 0.14478)
		(layer "In11.Cu")
		(net "M_F_CPU0_SB_CB<4>")
	)
	(segment
		(start 311.492392 -268.084808)
		(end 311.428384 -268.0208)
		(width 0.14478)
		(layer "In11.Cu")
		(net "M_F_CPU0_SB_CB<4>")
	)
	(segment
		(start 332.445106 -269.49146)
		(end 332.291182 -269.22603)
		(width 0.0889)
		(layer "In11.Cu")
		(net "M_F_CPU0_SB_CB<4>")
	)
	(segment
		(start 289.999674 -271.18437)
		(end 290.231576 -271.18437)
		(width 0.14478)
		(layer "In11.Cu")
		(net "M_F_CPU0_SB_CB<4>")
	)
	(segment
		(start 304.441098 -270.860012)
		(end 304.69332 -270.860012)
		(width 0.14478)
		(layer "In11.Cu")
		(net "M_F_CPU0_SB_CB<4>")
	)
	(segment
		(start 331.52969 -269.553436)
		(end 331.538072 -269.54861)
		(width 0.0889)
		(layer "In11.Cu")
		(net "M_F_CPU0_SB_CB<4>")
	)
	(segment
		(start 310.053228 -269.191232)
		(end 310.257952 -269.191232)
		(width 0.14478)
		(layer "In11.Cu")
		(net "M_F_CPU0_SB_CB<4>")
	)
	(segment
		(start 310.648096 -268.596364)
		(end 310.833516 -268.410944)
		(width 0.14478)
		(layer "In11.Cu")
		(net "M_F_CPU0_SB_CB<4>")
	)
	(segment
		(start 289.119056 -271.18437)
		(end 289.443414 -270.860012)
		(width 0.14478)
		(layer "In11.Cu")
		(net "M_F_CPU0_SB_CB<4>")
	)
	(segment
		(start 302.772318 -271.16405)
		(end 303.02454 -271.16405)
		(width 0.14478)
		(layer "In11.Cu")
		(net "M_F_CPU0_SB_CB<4>")
	)
	(segment
		(start 311.428384 -268.0208)
		(end 311.428384 -267.816076)
		(width 0.14478)
		(layer "In11.Cu")
		(net "M_F_CPU0_SB_CB<4>")
	)
	(segment
		(start 301.103538 -270.860012)
		(end 301.35576 -270.860012)
		(width 0.14478)
		(layer "In11.Cu")
		(net "M_F_CPU0_SB_CB<4>")
	)
	(segment
		(start 282.42768 -271.17421)
		(end 282.669742 -271.17421)
		(width 0.14478)
		(layer "In11.Cu")
		(net "M_F_CPU0_SB_CB<4>")
	)
	(segment
		(start 281.31516 -271.17421)
		(end 281.557222 -271.17421)
		(width 0.14478)
		(layer "In11.Cu")
		(net "M_F_CPU0_SB_CB<4>")
	)
	(segment
		(start 285.73603 -271.18437)
		(end 286.060388 -270.860012)
		(width 0.14478)
		(layer "In11.Cu")
		(net "M_F_CPU0_SB_CB<4>")
	)
	(segment
		(start 329.284076 -269.54861)
		(end 329.292458 -269.553436)
		(width 0.0889)
		(layer "In11.Cu")
		(net "M_F_CPU0_SB_CB<4>")
	)
	(segment
		(start 309.867808 -269.376652)
		(end 310.053228 -269.191232)
		(width 0.14478)
		(layer "In11.Cu")
		(net "M_F_CPU0_SB_CB<4>")
	)
	(segment
		(start 298.289726 -270.860012)
		(end 298.606464 -271.17675)
		(width 0.14478)
		(layer "In11.Cu")
		(net "M_F_CPU0_SB_CB<4>")
	)
	(segment
		(start 283.5402 -271.17421)
		(end 283.782262 -271.17421)
		(width 0.14478)
		(layer "In11.Cu")
		(net "M_F_CPU0_SB_CB<4>")
	)
	(segment
		(start 287.172908 -270.860012)
		(end 288.562796 -270.860012)
		(width 0.14478)
		(layer "In11.Cu")
		(net "M_F_CPU0_SB_CB<4>")
	)
	(segment
		(start 270.86814 -271.47139)
		(end 270.86814 -271.933162)
		(width 0.14478)
		(layer "In11.Cu")
		(net "M_F_CPU0_SB_CB<4>")
	)
	(segment
		(start 283.226002 -270.860012)
		(end 283.5402 -271.17421)
		(width 0.14478)
		(layer "In11.Cu")
		(net "M_F_CPU0_SB_CB<4>")
	)
	(segment
		(start 293.809928 -270.860012)
		(end 294.134286 -271.18437)
		(width 0.14478)
		(layer "In11.Cu")
		(net "M_F_CPU0_SB_CB<4>")
	)
	(segment
		(start 279.558242 -270.860012)
		(end 281.000962 -270.860012)
		(width 0.14478)
		(layer "In11.Cu")
		(net "M_F_CPU0_SB_CB<4>")
	)
	(segment
		(start 309.08752 -270.15694)
		(end 309.27294 -269.97152)
		(width 0.14478)
		(layer "In11.Cu")
		(net "M_F_CPU0_SB_CB<4>")
	)
	(segment
		(start 308.492652 -270.751808)
		(end 308.697376 -270.751808)
		(width 0.14478)
		(layer "In11.Cu")
		(net "M_F_CPU0_SB_CB<4>")
	)
	(segment
		(start 282.113482 -270.860012)
		(end 282.42768 -271.17421)
		(width 0.14478)
		(layer "In11.Cu")
		(net "M_F_CPU0_SB_CB<4>")
	)
	(segment
		(start 294.690546 -270.860012)
		(end 296.064686 -270.860012)
		(width 0.14478)
		(layer "In11.Cu")
		(net "M_F_CPU0_SB_CB<4>")
	)
	(segment
		(start 310.712104 -268.865096)
		(end 310.648096 -268.801088)
		(width 0.14478)
		(layer "In11.Cu")
		(net "M_F_CPU0_SB_CB<4>")
	)
	(segment
		(start 269.648178 -272.135092)
		(end 270.474694 -271.308576)
		(width 0.14478)
		(layer "In11.Cu")
		(net "M_F_CPU0_SB_CB<4>")
	)
	(segment
		(start 303.884838 -271.16405)
		(end 304.13706 -271.16405)
		(width 0.14478)
		(layer "In11.Cu")
		(net "M_F_CPU0_SB_CB<4>")
	)
	(segment
		(start 293.021766 -271.18437)
		(end 293.253668 -271.18437)
		(width 0.14478)
		(layer "In11.Cu")
		(net "M_F_CPU0_SB_CB<4>")
	)
	(segment
		(start 275.799296 -271.16913)
		(end 276.108414 -270.860012)
		(width 0.14478)
		(layer "In11.Cu")
		(net "M_F_CPU0_SB_CB<4>")
	)
	(segment
		(start 296.381424 -271.17675)
		(end 296.620946 -271.17675)
		(width 0.14478)
		(layer "In11.Cu")
		(net "M_F_CPU0_SB_CB<4>")
	)
	(segment
		(start 272.374106 -272.095976)
		(end 272.759932 -271.71015)
		(width 0.14478)
		(layer "In11.Cu")
		(net "M_F_CPU0_SB_CB<4>")
	)
	(segment
		(start 310.712104 -269.06982)
		(end 310.712104 -268.865096)
		(width 0.14478)
		(layer "In11.Cu")
		(net "M_F_CPU0_SB_CB<4>")
	)
	(segment
		(start 311.102248 -268.474952)
		(end 311.306972 -268.474952)
		(width 0.14478)
		(layer "In11.Cu")
		(net "M_F_CPU0_SB_CB<4>")
	)
	(segment
		(start 291.344096 -271.18437)
		(end 291.668454 -270.860012)
		(width 0.14478)
		(layer "In11.Cu")
		(net "M_F_CPU0_SB_CB<4>")
	)
	(segment
		(start 326.464676 -269.548356)
		(end 326.484742 -269.559786)
		(width 0.0889)
		(layer "In11.Cu")
		(net "M_F_CPU0_SB_CB<4>")
	)
	(segment
		(start 298.050204 -270.860012)
		(end 298.289726 -270.860012)
		(width 0.14478)
		(layer "In11.Cu")
		(net "M_F_CPU0_SB_CB<4>")
	)
	(segment
		(start 325.421244 -268.52372)
		(end 326.387206 -269.489682)
		(width 0.0889)
		(layer "In11.Cu")
		(net "M_F_CPU0_SB_CB<4>")
	)
	(segment
		(start 271.98066 -271.933162)
		(end 272.143474 -272.095976)
		(width 0.14478)
		(layer "In11.Cu")
		(net "M_F_CPU0_SB_CB<4>")
	)
	(segment
		(start 281.000962 -270.860012)
		(end 281.31516 -271.17421)
		(width 0.14478)
		(layer "In11.Cu")
		(net "M_F_CPU0_SB_CB<4>")
	)
	(segment
		(start 310.526684 -269.25524)
		(end 310.712104 -269.06982)
		(width 0.14478)
		(layer "In11.Cu")
		(net "M_F_CPU0_SB_CB<4>")
	)
	(segment
		(start 308.966108 -270.815816)
		(end 309.151528 -270.630396)
		(width 0.14478)
		(layer "In11.Cu")
		(net "M_F_CPU0_SB_CB<4>")
	)
	(segment
		(start 286.84855 -271.18437)
		(end 287.172908 -270.860012)
		(width 0.14478)
		(layer "In11.Cu")
		(net "M_F_CPU0_SB_CB<4>")
	)
	(segment
		(start 294.134286 -271.18437)
		(end 294.366188 -271.18437)
		(width 0.14478)
		(layer "In11.Cu")
		(net "M_F_CPU0_SB_CB<4>")
	)
	(segment
		(start 326.387206 -269.489682)
		(end 326.38746 -269.489682)
		(width 0.0889)
		(layer "In11.Cu")
		(net "M_F_CPU0_SB_CB<4>")
	)
	(segment
		(start 282.98394 -270.860012)
		(end 283.226002 -270.860012)
		(width 0.14478)
		(layer "In11.Cu")
		(net "M_F_CPU0_SB_CB<4>")
	)
	(segment
		(start 309.746396 -270.035528)
		(end 309.931816 -269.850108)
		(width 0.14478)
		(layer "In11.Cu")
		(net "M_F_CPU0_SB_CB<4>")
	)
	(segment
		(start 270.474694 -271.308576)
		(end 270.705326 -271.308576)
		(width 0.14478)
		(layer "In11.Cu")
		(net "M_F_CPU0_SB_CB<4>")
	)
	(segment
		(start 309.08752 -270.361664)
		(end 309.08752 -270.15694)
		(width 0.14478)
		(layer "In11.Cu")
		(net "M_F_CPU0_SB_CB<4>")
	)
	(segment
		(start 293.253668 -271.18437)
		(end 293.578026 -270.860012)
		(width 0.14478)
		(layer "In11.Cu")
		(net "M_F_CPU0_SB_CB<4>")
	)
	(segment
		(start 323.909944 -267.59662)
		(end 325.035164 -267.59662)
		(width 0.0889)
		(layer "In11.Cu")
		(net "M_F_CPU0_SB_CB<4>")
	)
	(segment
		(start 298.845986 -271.17675)
		(end 299.162724 -270.860012)
		(width 0.14478)
		(layer "In11.Cu")
		(net "M_F_CPU0_SB_CB<4>")
	)
	(segment
		(start 283.782262 -271.17421)
		(end 284.09646 -270.860012)
		(width 0.14478)
		(layer "In11.Cu")
		(net "M_F_CPU0_SB_CB<4>")
	)
	(segment
		(start 292.697408 -270.860012)
		(end 293.021766 -271.18437)
		(width 0.14478)
		(layer "In11.Cu")
		(net "M_F_CPU0_SB_CB<4>")
	)
	(segment
		(start 271.817846 -271.308576)
		(end 271.98066 -271.47139)
		(width 0.14478)
		(layer "In11.Cu")
		(net "M_F_CPU0_SB_CB<4>")
	)
	(segment
		(start 286.616648 -271.18437)
		(end 286.84855 -271.18437)
		(width 0.14478)
		(layer "In11.Cu")
		(net "M_F_CPU0_SB_CB<4>")
	)
	(segment
		(start 297.493944 -271.17675)
		(end 297.733466 -271.17675)
		(width 0.14478)
		(layer "In11.Cu")
		(net "M_F_CPU0_SB_CB<4>")
	)
	(segment
		(start 290.231576 -271.18437)
		(end 290.555934 -270.860012)
		(width 0.14478)
		(layer "In11.Cu")
		(net "M_F_CPU0_SB_CB<4>")
	)
	(segment
		(start 276.108414 -270.860012)
		(end 277.585424 -270.860012)
		(width 0.14478)
		(layer "In11.Cu")
		(net "M_F_CPU0_SB_CB<4>")
	)
	(segment
		(start 327.382886 -269.53591)
		(end 327.404476 -269.548356)
		(width 0.0889)
		(layer "In11.Cu")
		(net "M_F_CPU0_SB_CB<4>")
	)
	(segment
		(start 271.98066 -271.47139)
		(end 271.98066 -271.933162)
		(width 0.14478)
		(layer "In11.Cu")
		(net "M_F_CPU0_SB_CB<4>")
	)
	(segment
		(start 301.35576 -270.860012)
		(end 301.659798 -271.16405)
		(width 0.14478)
		(layer "In11.Cu")
		(net "M_F_CPU0_SB_CB<4>")
	)
	(segment
		(start 299.162724 -270.860012)
		(end 300.24324 -270.860012)
		(width 0.14478)
		(layer "In11.Cu")
		(net "M_F_CPU0_SB_CB<4>")
	)
	(segment
		(start 296.064686 -270.860012)
		(end 296.381424 -271.17675)
		(width 0.14478)
		(layer "In11.Cu")
		(net "M_F_CPU0_SB_CB<4>")
	)
	(segment
		(start 311.428384 -267.816076)
		(end 311.64784 -267.59662)
		(width 0.14478)
		(layer "In11.Cu")
		(net "M_F_CPU0_SB_CB<4>")
	)
	(segment
		(start 277.889462 -271.16405)
		(end 278.141684 -271.16405)
		(width 0.14478)
		(layer "In11.Cu")
		(net "M_F_CPU0_SB_CB<4>")
	)
	(segment
		(start 332.422754 -269.574772)
		(end 332.445106 -269.49146)
		(width 0.0889)
		(layer "In11.Cu")
		(net "M_F_CPU0_SB_CB<4>")
	)
	(segment
		(start 286.29229 -270.860012)
		(end 286.616648 -271.18437)
		(width 0.14478)
		(layer "In11.Cu")
		(net "M_F_CPU0_SB_CB<4>")
	)
	(segment
		(start 325.035164 -267.59662)
		(end 325.421244 -267.9827)
		(width 0.0889)
		(layer "In11.Cu")
		(net "M_F_CPU0_SB_CB<4>")
	)
	(segment
		(start 311.03824 -268.410944)
		(end 311.102248 -268.474952)
		(width 0.14478)
		(layer "In11.Cu")
		(net "M_F_CPU0_SB_CB<4>")
	)
	(arc
		(start 326.38746 -269.489682)
		(mid 326.424156 -269.521535)
		(end 326.464676 -269.548356)
		(width 0.0889)
		(layer "In11.Cu")
		(net "M_F_CPU0_SB_CB<4>")
	)
	(arc
		(start 332.103984 -269.54861)
		(mid 332.260422 -269.597581)
		(end 332.422754 -269.574772)
		(width 0.0889)
		(layer "In11.Cu")
		(net "M_F_CPU0_SB_CB<4>")
	)
	(arc
		(start 331.16393 -269.54861)
		(mid 331.346181 -269.59896)
		(end 331.52969 -269.553436)
		(width 0.0889)
		(layer "In11.Cu")
		(net "M_F_CPU0_SB_CB<4>")
	)
	(arc
		(start 329.658218 -269.54861)
		(mid 329.941174 -269.472433)
		(end 330.22413 -269.54861)
		(width 0.0889)
		(layer "In11.Cu")
		(net "M_F_CPU0_SB_CB<4>")
	)
	(arc
		(start 330.598018 -269.54861)
		(mid 330.880974 -269.472433)
		(end 331.16393 -269.54861)
		(width 0.0889)
		(layer "In11.Cu")
		(net "M_F_CPU0_SB_CB<4>")
	)
	(arc
		(start 330.22413 -269.54861)
		(mid 330.411074 -269.598865)
		(end 330.598018 -269.54861)
		(width 0.0889)
		(layer "In11.Cu")
		(net "M_F_CPU0_SB_CB<4>")
	)
	(arc
		(start 329.292458 -269.553436)
		(mid 329.475966 -269.59893)
		(end 329.658218 -269.54861)
		(width 0.0889)
		(layer "In11.Cu")
		(net "M_F_CPU0_SB_CB<4>")
	)
	(arc
		(start 328.718164 -269.54861)
		(mid 329.00112 -269.472433)
		(end 329.284076 -269.54861)
		(width 0.0889)
		(layer "In11.Cu")
		(net "M_F_CPU0_SB_CB<4>")
	)
	(arc
		(start 327.77811 -269.54861)
		(mid 328.061066 -269.472433)
		(end 328.344022 -269.54861)
		(width 0.0889)
		(layer "In11.Cu")
		(net "M_F_CPU0_SB_CB<4>")
	)
	(arc
		(start 327.418192 -269.55623)
		(mid 327.599122 -269.598708)
		(end 327.77811 -269.54861)
		(width 0.0889)
		(layer "In11.Cu")
		(net "M_F_CPU0_SB_CB<4>")
	)
	(arc
		(start 326.838564 -269.54861)
		(mid 327.109095 -269.472204)
		(end 327.382886 -269.53591)
		(width 0.0889)
		(layer "In11.Cu")
		(net "M_F_CPU0_SB_CB<4>")
	)
	(arc
		(start 331.538072 -269.54861)
		(mid 331.821028 -269.472433)
		(end 332.103984 -269.54861)
		(width 0.0889)
		(layer "In11.Cu")
		(net "M_F_CPU0_SB_CB<4>")
	)
	(arc
		(start 326.484742 -269.559786)
		(mid 326.663074 -269.598883)
		(end 326.838564 -269.54861)
		(width 0.0889)
		(layer "In11.Cu")
		(net "M_F_CPU0_SB_CB<4>")
	)
	(arc
		(start 328.344022 -269.54861)
		(mid 328.526273 -269.59896)
		(end 328.709782 -269.553436)
		(width 0.0889)
		(layer "In11.Cu")
		(net "M_F_CPU0_SB_CB<4>")
	)
	(segment
		(start 334.637888 -273.820128)
		(end 334.171036 -274.086066)
		(width 0.10668)
		(layer "F.Cu")
		(net "M_F_CPU0_SB_CB<3>")
	)
	(segment
		(start 301.959518 -281.060144)
		(end 304.629058 -281.060144)
		(width 0.14478)
		(layer "In11.Cu")
		(net "M_F_CPU0_SB_CB<3>")
	)
	(segment
		(start 328.709782 -273.75866)
		(end 328.718164 -273.763486)
		(width 0.0889)
		(layer "In11.Cu")
		(net "M_F_CPU0_SB_CB<3>")
	)
	(segment
		(start 325.162926 -272.50771)
		(end 326.367902 -273.712686)
		(width 0.0889)
		(layer "In11.Cu")
		(net "M_F_CPU0_SB_CB<3>")
	)
	(segment
		(start 314.862972 -272.66392)
		(end 324.161404 -272.66392)
		(width 0.14478)
		(layer "In11.Cu")
		(net "M_F_CPU0_SB_CB<3>")
	)
	(segment
		(start 324.161404 -272.66392)
		(end 324.317614 -272.50771)
		(width 0.0889)
		(layer "In11.Cu")
		(net "M_F_CPU0_SB_CB<3>")
	)
	(segment
		(start 267.744702 -280.915364)
		(end 267.744702 -280.788872)
		(width 0.14478)
		(layer "In11.Cu")
		(net "M_F_CPU0_SB_CB<3>")
	)
	(segment
		(start 279.749758 -281.060144)
		(end 281.94127 -281.060144)
		(width 0.14478)
		(layer "In11.Cu")
		(net "M_F_CPU0_SB_CB<3>")
	)
	(segment
		(start 333.9211 -273.795236)
		(end 334.017112 -273.820636)
		(width 0.0889)
		(layer "In11.Cu")
		(net "M_F_CPU0_SB_CB<3>")
	)
	(segment
		(start 333.044038 -273.763486)
		(end 333.05242 -273.75866)
		(width 0.0889)
		(layer "In11.Cu")
		(net "M_F_CPU0_SB_CB<3>")
	)
	(segment
		(start 334.017112 -273.820636)
		(end 334.171036 -274.086066)
		(width 0.0889)
		(layer "In11.Cu")
		(net "M_F_CPU0_SB_CB<3>")
	)
	(segment
		(start 268.296136 -280.915364)
		(end 268.440916 -281.060144)
		(width 0.14478)
		(layer "In11.Cu")
		(net "M_F_CPU0_SB_CB<3>")
	)
	(segment
		(start 298.537376 -280.210006)
		(end 300.687232 -280.210006)
		(width 0.14478)
		(layer "In11.Cu")
		(net "M_F_CPU0_SB_CB<3>")
	)
	(segment
		(start 278.477218 -280.210006)
		(end 279.749758 -281.060144)
		(width 0.14478)
		(layer "In11.Cu")
		(net "M_F_CPU0_SB_CB<3>")
	)
	(segment
		(start 326.367902 -273.712686)
		(end 327.590404 -273.712686)
		(width 0.0889)
		(layer "In11.Cu")
		(net "M_F_CPU0_SB_CB<3>")
	)
	(segment
		(start 286.639254 -281.060144)
		(end 290.04387 -281.060144)
		(width 0.14478)
		(layer "In11.Cu")
		(net "M_F_CPU0_SB_CB<3>")
	)
	(segment
		(start 305.90109 -280.210006)
		(end 307.316886 -280.210006)
		(width 0.14478)
		(layer "In11.Cu")
		(net "M_F_CPU0_SB_CB<3>")
	)
	(segment
		(start 290.04387 -281.060144)
		(end 291.313616 -280.211784)
		(width 0.14478)
		(layer "In11.Cu")
		(net "M_F_CPU0_SB_CB<3>")
	)
	(segment
		(start 285.367222 -280.210006)
		(end 286.639254 -281.060144)
		(width 0.14478)
		(layer "In11.Cu")
		(net "M_F_CPU0_SB_CB<3>")
	)
	(segment
		(start 308.312058 -279.214834)
		(end 308.312058 -278.528272)
		(width 0.14478)
		(layer "In11.Cu")
		(net "M_F_CPU0_SB_CB<3>")
	)
	(segment
		(start 308.312058 -278.528272)
		(end 312.466736 -274.373594)
		(width 0.14478)
		(layer "In11.Cu")
		(net "M_F_CPU0_SB_CB<3>")
	)
	(segment
		(start 268.151356 -280.644092)
		(end 268.296136 -280.788872)
		(width 0.14478)
		(layer "In11.Cu")
		(net "M_F_CPU0_SB_CB<3>")
	)
	(segment
		(start 281.94127 -281.060144)
		(end 283.21381 -280.210006)
		(width 0.14478)
		(layer "In11.Cu")
		(net "M_F_CPU0_SB_CB<3>")
	)
	(segment
		(start 267.889482 -280.644092)
		(end 268.151356 -280.644092)
		(width 0.14478)
		(layer "In11.Cu")
		(net "M_F_CPU0_SB_CB<3>")
	)
	(segment
		(start 267.599922 -281.060144)
		(end 267.744702 -280.915364)
		(width 0.14478)
		(layer "In11.Cu")
		(net "M_F_CPU0_SB_CB<3>")
	)
	(segment
		(start 268.440916 -281.060144)
		(end 274.74418 -281.060144)
		(width 0.14478)
		(layer "In11.Cu")
		(net "M_F_CPU0_SB_CB<3>")
	)
	(segment
		(start 313.153298 -274.373594)
		(end 314.862972 -272.66392)
		(width 0.14478)
		(layer "In11.Cu")
		(net "M_F_CPU0_SB_CB<3>")
	)
	(segment
		(start 297.26509 -281.060144)
		(end 298.537376 -280.210006)
		(width 0.14478)
		(layer "In11.Cu")
		(net "M_F_CPU0_SB_CB<3>")
	)
	(segment
		(start 274.74418 -281.060144)
		(end 276.01672 -280.210006)
		(width 0.14478)
		(layer "In11.Cu")
		(net "M_F_CPU0_SB_CB<3>")
	)
	(segment
		(start 292.992556 -280.211784)
		(end 294.262048 -281.060144)
		(width 0.14478)
		(layer "In11.Cu")
		(net "M_F_CPU0_SB_CB<3>")
	)
	(segment
		(start 331.52969 -273.75866)
		(end 331.538072 -273.763486)
		(width 0.0889)
		(layer "In11.Cu")
		(net "M_F_CPU0_SB_CB<3>")
	)
	(segment
		(start 268.296136 -280.788872)
		(end 268.296136 -280.915364)
		(width 0.14478)
		(layer "In11.Cu")
		(net "M_F_CPU0_SB_CB<3>")
	)
	(segment
		(start 304.629058 -281.060144)
		(end 305.90109 -280.210006)
		(width 0.14478)
		(layer "In11.Cu")
		(net "M_F_CPU0_SB_CB<3>")
	)
	(segment
		(start 328.333608 -273.769582)
		(end 328.344022 -273.763486)
		(width 0.0889)
		(layer "In11.Cu")
		(net "M_F_CPU0_SB_CB<3>")
	)
	(segment
		(start 300.687232 -280.210006)
		(end 301.959518 -281.060144)
		(width 0.14478)
		(layer "In11.Cu")
		(net "M_F_CPU0_SB_CB<3>")
	)
	(segment
		(start 324.317614 -272.50771)
		(end 325.162926 -272.50771)
		(width 0.0889)
		(layer "In11.Cu")
		(net "M_F_CPU0_SB_CB<3>")
	)
	(segment
		(start 265.54811 -280.634948)
		(end 265.973306 -281.060144)
		(width 0.14478)
		(layer "In11.Cu")
		(net "M_F_CPU0_SB_CB<3>")
	)
	(segment
		(start 332.469744 -273.75866)
		(end 332.478126 -273.763486)
		(width 0.0889)
		(layer "In11.Cu")
		(net "M_F_CPU0_SB_CB<3>")
	)
	(segment
		(start 294.262048 -281.060144)
		(end 297.26509 -281.060144)
		(width 0.14478)
		(layer "In11.Cu")
		(net "M_F_CPU0_SB_CB<3>")
	)
	(segment
		(start 283.21381 -280.210006)
		(end 285.367222 -280.210006)
		(width 0.14478)
		(layer "In11.Cu")
		(net "M_F_CPU0_SB_CB<3>")
	)
	(segment
		(start 276.01672 -280.210006)
		(end 278.477218 -280.210006)
		(width 0.14478)
		(layer "In11.Cu")
		(net "M_F_CPU0_SB_CB<3>")
	)
	(segment
		(start 291.313616 -280.211784)
		(end 292.992556 -280.211784)
		(width 0.14478)
		(layer "In11.Cu")
		(net "M_F_CPU0_SB_CB<3>")
	)
	(segment
		(start 329.284076 -273.763486)
		(end 329.292458 -273.75866)
		(width 0.0889)
		(layer "In11.Cu")
		(net "M_F_CPU0_SB_CB<3>")
	)
	(segment
		(start 267.744702 -280.788872)
		(end 267.889482 -280.644092)
		(width 0.14478)
		(layer "In11.Cu")
		(net "M_F_CPU0_SB_CB<3>")
	)
	(segment
		(start 265.973306 -281.060144)
		(end 267.599922 -281.060144)
		(width 0.14478)
		(layer "In11.Cu")
		(net "M_F_CPU0_SB_CB<3>")
	)
	(segment
		(start 312.466736 -274.373594)
		(end 313.153298 -274.373594)
		(width 0.14478)
		(layer "In11.Cu")
		(net "M_F_CPU0_SB_CB<3>")
	)
	(segment
		(start 307.316886 -280.210006)
		(end 308.312058 -279.214834)
		(width 0.14478)
		(layer "In11.Cu")
		(net "M_F_CPU0_SB_CB<3>")
	)
	(arc
		(start 329.658218 -273.763486)
		(mid 329.941174 -273.839663)
		(end 330.22413 -273.763486)
		(width 0.0889)
		(layer "In11.Cu")
		(net "M_F_CPU0_SB_CB<3>")
	)
	(arc
		(start 328.718164 -273.763486)
		(mid 329.00112 -273.839663)
		(end 329.284076 -273.763486)
		(width 0.0889)
		(layer "In11.Cu")
		(net "M_F_CPU0_SB_CB<3>")
	)
	(arc
		(start 330.22413 -273.763486)
		(mid 330.411074 -273.713231)
		(end 330.598018 -273.763486)
		(width 0.0889)
		(layer "In11.Cu")
		(net "M_F_CPU0_SB_CB<3>")
	)
	(arc
		(start 331.16393 -273.763486)
		(mid 331.346181 -273.713136)
		(end 331.52969 -273.75866)
		(width 0.0889)
		(layer "In11.Cu")
		(net "M_F_CPU0_SB_CB<3>")
	)
	(arc
		(start 332.478126 -273.763486)
		(mid 332.761082 -273.839663)
		(end 333.044038 -273.763486)
		(width 0.0889)
		(layer "In11.Cu")
		(net "M_F_CPU0_SB_CB<3>")
	)
	(arc
		(start 327.590404 -273.712686)
		(mid 327.687493 -273.725676)
		(end 327.777856 -273.763486)
		(width 0.0889)
		(layer "In11.Cu")
		(net "M_F_CPU0_SB_CB<3>")
	)
	(arc
		(start 331.538072 -273.763486)
		(mid 331.821028 -273.839663)
		(end 332.103984 -273.763486)
		(width 0.0889)
		(layer "In11.Cu")
		(net "M_F_CPU0_SB_CB<3>")
	)
	(arc
		(start 330.598018 -273.763486)
		(mid 330.880974 -273.839663)
		(end 331.16393 -273.763486)
		(width 0.0889)
		(layer "In11.Cu")
		(net "M_F_CPU0_SB_CB<3>")
	)
	(arc
		(start 333.05242 -273.75866)
		(mid 333.235928 -273.713166)
		(end 333.41818 -273.763486)
		(width 0.0889)
		(layer "In11.Cu")
		(net "M_F_CPU0_SB_CB<3>")
	)
	(arc
		(start 333.41818 -273.763486)
		(mid 333.665893 -273.838706)
		(end 333.9211 -273.795236)
		(width 0.0889)
		(layer "In11.Cu")
		(net "M_F_CPU0_SB_CB<3>")
	)
	(arc
		(start 328.344022 -273.763486)
		(mid 328.526273 -273.713136)
		(end 328.709782 -273.75866)
		(width 0.0889)
		(layer "In11.Cu")
		(net "M_F_CPU0_SB_CB<3>")
	)
	(arc
		(start 327.777856 -273.763486)
		(mid 328.054923 -273.839757)
		(end 328.333608 -273.769582)
		(width 0.0889)
		(layer "In11.Cu")
		(net "M_F_CPU0_SB_CB<3>")
	)
	(arc
		(start 329.292458 -273.75866)
		(mid 329.475966 -273.713166)
		(end 329.658218 -273.763486)
		(width 0.0889)
		(layer "In11.Cu")
		(net "M_F_CPU0_SB_CB<3>")
	)
	(arc
		(start 332.103984 -273.763486)
		(mid 332.286235 -273.713136)
		(end 332.469744 -273.75866)
		(width 0.0889)
		(layer "In11.Cu")
		(net "M_F_CPU0_SB_CB<3>")
	)
	(segment
		(start 333.227934 -273.010122)
		(end 332.761082 -273.27606)
		(width 0.10668)
		(layer "F.Cu")
		(net "M_F_CPU0_SB_CB<2>")
	)
	(segment
		(start 327.862438 -272.960592)
		(end 327.874376 -272.953734)
		(width 0.0889)
		(layer "In11.Cu")
		(net "M_F_CPU0_SB_CB<2>")
	)
	(segment
		(start 275.062442 -279.360122)
		(end 275.91258 -278.509984)
		(width 0.14478)
		(layer "In11.Cu")
		(net "M_F_CPU0_SB_CB<2>")
	)
	(segment
		(start 307.053488 -278.509984)
		(end 313.808872 -271.7546)
		(width 0.14478)
		(layer "In11.Cu")
		(net "M_F_CPU0_SB_CB<2>")
	)
	(segment
		(start 266.811252 -278.911812)
		(end 266.956032 -278.767032)
		(width 0.14478)
		(layer "In11.Cu")
		(net "M_F_CPU0_SB_CB<2>")
	)
	(segment
		(start 293.999666 -279.360122)
		(end 297.897042 -279.360122)
		(width 0.14478)
		(layer "In11.Cu")
		(net "M_F_CPU0_SB_CB<2>")
	)
	(segment
		(start 323.901054 -271.7546)
		(end 324.562216 -271.7546)
		(width 0.0889)
		(layer "In11.Cu")
		(net "M_F_CPU0_SB_CB<2>")
	)
	(segment
		(start 326.368918 -272.953734)
		(end 326.390508 -272.96618)
		(width 0.0889)
		(layer "In11.Cu")
		(net "M_F_CPU0_SB_CB<2>")
	)
	(segment
		(start 290.607242 -279.360122)
		(end 291.45738 -278.509984)
		(width 0.14478)
		(layer "In11.Cu")
		(net "M_F_CPU0_SB_CB<2>")
	)
	(segment
		(start 305.280314 -279.360122)
		(end 306.130452 -278.509984)
		(width 0.14478)
		(layer "In11.Cu")
		(net "M_F_CPU0_SB_CB<2>")
	)
	(segment
		(start 286.410654 -279.360122)
		(end 290.607242 -279.360122)
		(width 0.14478)
		(layer "In11.Cu")
		(net "M_F_CPU0_SB_CB<2>")
	)
	(segment
		(start 297.897042 -279.360122)
		(end 298.74718 -278.509984)
		(width 0.14478)
		(layer "In11.Cu")
		(net "M_F_CPU0_SB_CB<2>")
	)
	(segment
		(start 265.973052 -279.360122)
		(end 266.666472 -279.360122)
		(width 0.14478)
		(layer "In11.Cu")
		(net "M_F_CPU0_SB_CB<2>")
	)
	(segment
		(start 279.191466 -279.360122)
		(end 282.504642 -279.360122)
		(width 0.14478)
		(layer "In11.Cu")
		(net "M_F_CPU0_SB_CB<2>")
	)
	(segment
		(start 324.752208 -271.944592)
		(end 325.332598 -271.944592)
		(width 0.0889)
		(layer "In11.Cu")
		(net "M_F_CPU0_SB_CB<2>")
	)
	(segment
		(start 267.362686 -279.215342)
		(end 267.507466 -279.360122)
		(width 0.14478)
		(layer "In11.Cu")
		(net "M_F_CPU0_SB_CB<2>")
	)
	(segment
		(start 267.362686 -278.911812)
		(end 267.362686 -279.215342)
		(width 0.14478)
		(layer "In11.Cu")
		(net "M_F_CPU0_SB_CB<2>")
	)
	(segment
		(start 275.91258 -278.509984)
		(end 278.341328 -278.509984)
		(width 0.14478)
		(layer "In11.Cu")
		(net "M_F_CPU0_SB_CB<2>")
	)
	(segment
		(start 267.91412 -279.215342)
		(end 267.91412 -278.911812)
		(width 0.14478)
		(layer "In11.Cu")
		(net "M_F_CPU0_SB_CB<2>")
	)
	(segment
		(start 268.465554 -278.911812)
		(end 268.465554 -279.215342)
		(width 0.14478)
		(layer "In11.Cu")
		(net "M_F_CPU0_SB_CB<2>")
	)
	(segment
		(start 268.465554 -279.215342)
		(end 268.610334 -279.360122)
		(width 0.14478)
		(layer "In11.Cu")
		(net "M_F_CPU0_SB_CB<2>")
	)
	(segment
		(start 330.69403 -272.95348)
		(end 330.702412 -272.948654)
		(width 0.0889)
		(layer "In11.Cu")
		(net "M_F_CPU0_SB_CB<2>")
	)
	(segment
		(start 327.874376 -272.953734)
		(end 327.890632 -272.944336)
		(width 0.0889)
		(layer "In11.Cu")
		(net "M_F_CPU0_SB_CB<2>")
	)
	(segment
		(start 324.562216 -271.7546)
		(end 324.752208 -271.944592)
		(width 0.0889)
		(layer "In11.Cu")
		(net "M_F_CPU0_SB_CB<2>")
	)
	(segment
		(start 332.607158 -273.01063)
		(end 332.761082 -273.27606)
		(width 0.0889)
		(layer "In11.Cu")
		(net "M_F_CPU0_SB_CB<2>")
	)
	(segment
		(start 268.0589 -278.767032)
		(end 268.320774 -278.767032)
		(width 0.14478)
		(layer "In11.Cu")
		(net "M_F_CPU0_SB_CB<2>")
	)
	(segment
		(start 291.45738 -278.509984)
		(end 293.149528 -278.509984)
		(width 0.14478)
		(layer "In11.Cu")
		(net "M_F_CPU0_SB_CB<2>")
	)
	(segment
		(start 285.560516 -278.509984)
		(end 286.410654 -279.360122)
		(width 0.14478)
		(layer "In11.Cu")
		(net "M_F_CPU0_SB_CB<2>")
	)
	(segment
		(start 266.956032 -278.767032)
		(end 267.217906 -278.767032)
		(width 0.14478)
		(layer "In11.Cu")
		(net "M_F_CPU0_SB_CB<2>")
	)
	(segment
		(start 278.341328 -278.509984)
		(end 279.191466 -279.360122)
		(width 0.14478)
		(layer "In11.Cu")
		(net "M_F_CPU0_SB_CB<2>")
	)
	(segment
		(start 331.634084 -272.95348)
		(end 331.642466 -272.948654)
		(width 0.0889)
		(layer "In11.Cu")
		(net "M_F_CPU0_SB_CB<2>")
	)
	(segment
		(start 325.332598 -271.944592)
		(end 326.252586 -272.86458)
		(width 0.0889)
		(layer "In11.Cu")
		(net "M_F_CPU0_SB_CB<2>")
	)
	(segment
		(start 300.769528 -278.509984)
		(end 301.619666 -279.360122)
		(width 0.14478)
		(layer "In11.Cu")
		(net "M_F_CPU0_SB_CB<2>")
	)
	(segment
		(start 306.130452 -278.509984)
		(end 307.053488 -278.509984)
		(width 0.14478)
		(layer "In11.Cu")
		(net "M_F_CPU0_SB_CB<2>")
	)
	(segment
		(start 268.610334 -279.360122)
		(end 275.062442 -279.360122)
		(width 0.14478)
		(layer "In11.Cu")
		(net "M_F_CPU0_SB_CB<2>")
	)
	(segment
		(start 267.507466 -279.360122)
		(end 267.76934 -279.360122)
		(width 0.14478)
		(layer "In11.Cu")
		(net "M_F_CPU0_SB_CB<2>")
	)
	(segment
		(start 267.217906 -278.767032)
		(end 267.362686 -278.911812)
		(width 0.14478)
		(layer "In11.Cu")
		(net "M_F_CPU0_SB_CB<2>")
	)
	(segment
		(start 293.149528 -278.509984)
		(end 293.999666 -279.360122)
		(width 0.14478)
		(layer "In11.Cu")
		(net "M_F_CPU0_SB_CB<2>")
	)
	(segment
		(start 268.320774 -278.767032)
		(end 268.465554 -278.911812)
		(width 0.14478)
		(layer "In11.Cu")
		(net "M_F_CPU0_SB_CB<2>")
	)
	(segment
		(start 301.619666 -279.360122)
		(end 305.280314 -279.360122)
		(width 0.14478)
		(layer "In11.Cu")
		(net "M_F_CPU0_SB_CB<2>")
	)
	(segment
		(start 332.511146 -272.98523)
		(end 332.607158 -273.01063)
		(width 0.0889)
		(layer "In11.Cu")
		(net "M_F_CPU0_SB_CB<2>")
	)
	(segment
		(start 267.76934 -279.360122)
		(end 267.91412 -279.215342)
		(width 0.14478)
		(layer "In11.Cu")
		(net "M_F_CPU0_SB_CB<2>")
	)
	(segment
		(start 327.297542 -272.946622)
		(end 327.309226 -272.95348)
		(width 0.0889)
		(layer "In11.Cu")
		(net "M_F_CPU0_SB_CB<2>")
	)
	(segment
		(start 298.74718 -278.509984)
		(end 300.769528 -278.509984)
		(width 0.14478)
		(layer "In11.Cu")
		(net "M_F_CPU0_SB_CB<2>")
	)
	(segment
		(start 313.808872 -271.7546)
		(end 323.901054 -271.7546)
		(width 0.14478)
		(layer "In11.Cu")
		(net "M_F_CPU0_SB_CB<2>")
	)
	(segment
		(start 266.666472 -279.360122)
		(end 266.811252 -279.215342)
		(width 0.14478)
		(layer "In11.Cu")
		(net "M_F_CPU0_SB_CB<2>")
	)
	(segment
		(start 330.119736 -272.948654)
		(end 330.128118 -272.95348)
		(width 0.0889)
		(layer "In11.Cu")
		(net "M_F_CPU0_SB_CB<2>")
	)
	(segment
		(start 265.54811 -278.93518)
		(end 265.973052 -279.360122)
		(width 0.14478)
		(layer "In11.Cu")
		(net "M_F_CPU0_SB_CB<2>")
	)
	(segment
		(start 283.35478 -278.509984)
		(end 285.560516 -278.509984)
		(width 0.14478)
		(layer "In11.Cu")
		(net "M_F_CPU0_SB_CB<2>")
	)
	(segment
		(start 266.811252 -279.215342)
		(end 266.811252 -278.911812)
		(width 0.14478)
		(layer "In11.Cu")
		(net "M_F_CPU0_SB_CB<2>")
	)
	(segment
		(start 282.504642 -279.360122)
		(end 283.35478 -278.509984)
		(width 0.14478)
		(layer "In11.Cu")
		(net "M_F_CPU0_SB_CB<2>")
	)
	(segment
		(start 267.91412 -278.911812)
		(end 268.0589 -278.767032)
		(width 0.14478)
		(layer "In11.Cu")
		(net "M_F_CPU0_SB_CB<2>")
	)
	(arc
		(start 328.814176 -272.95348)
		(mid 329.00112 -272.903225)
		(end 329.188064 -272.95348)
		(width 0.0889)
		(layer "In11.Cu")
		(net "M_F_CPU0_SB_CB<2>")
	)
	(arc
		(start 331.068172 -272.95348)
		(mid 331.351128 -273.029657)
		(end 331.634084 -272.95348)
		(width 0.0889)
		(layer "In11.Cu")
		(net "M_F_CPU0_SB_CB<2>")
	)
	(arc
		(start 326.252586 -272.86458)
		(mid 326.307836 -272.912962)
		(end 326.368918 -272.953734)
		(width 0.0889)
		(layer "In11.Cu")
		(net "M_F_CPU0_SB_CB<2>")
	)
	(arc
		(start 329.753976 -272.95348)
		(mid 329.936227 -272.90313)
		(end 330.119736 -272.948654)
		(width 0.0889)
		(layer "In11.Cu")
		(net "M_F_CPU0_SB_CB<2>")
	)
	(arc
		(start 326.93483 -272.95348)
		(mid 327.115288 -272.903036)
		(end 327.297542 -272.946622)
		(width 0.0889)
		(layer "In11.Cu")
		(net "M_F_CPU0_SB_CB<2>")
	)
	(arc
		(start 331.642466 -272.948654)
		(mid 331.825974 -272.90316)
		(end 332.008226 -272.95348)
		(width 0.0889)
		(layer "In11.Cu")
		(net "M_F_CPU0_SB_CB<2>")
	)
	(arc
		(start 330.128118 -272.95348)
		(mid 330.411074 -273.029657)
		(end 330.69403 -272.95348)
		(width 0.0889)
		(layer "In11.Cu")
		(net "M_F_CPU0_SB_CB<2>")
	)
	(arc
		(start 328.248264 -272.95348)
		(mid 328.53122 -273.029657)
		(end 328.814176 -272.95348)
		(width 0.0889)
		(layer "In11.Cu")
		(net "M_F_CPU0_SB_CB<2>")
	)
	(arc
		(start 330.702412 -272.948654)
		(mid 330.88592 -272.90316)
		(end 331.068172 -272.95348)
		(width 0.0889)
		(layer "In11.Cu")
		(net "M_F_CPU0_SB_CB<2>")
	)
	(arc
		(start 329.188064 -272.95348)
		(mid 329.47102 -273.029657)
		(end 329.753976 -272.95348)
		(width 0.0889)
		(layer "In11.Cu")
		(net "M_F_CPU0_SB_CB<2>")
	)
	(arc
		(start 326.390508 -272.96618)
		(mid 326.664298 -273.029851)
		(end 326.93483 -272.95348)
		(width 0.0889)
		(layer "In11.Cu")
		(net "M_F_CPU0_SB_CB<2>")
	)
	(arc
		(start 327.890632 -272.944336)
		(mid 328.070614 -272.903236)
		(end 328.248264 -272.95348)
		(width 0.0889)
		(layer "In11.Cu")
		(net "M_F_CPU0_SB_CB<2>")
	)
	(arc
		(start 332.008226 -272.95348)
		(mid 332.255939 -273.0287)
		(end 332.511146 -272.98523)
		(width 0.0889)
		(layer "In11.Cu")
		(net "M_F_CPU0_SB_CB<2>")
	)
	(arc
		(start 327.309226 -272.95348)
		(mid 327.584904 -273.02961)
		(end 327.862438 -272.960592)
		(width 0.0889)
		(layer "In11.Cu")
		(net "M_F_CPU0_SB_CB<2>")
	)
	(segment
		(start 334.167988 -273.010122)
		(end 333.701136 -273.27606)
		(width 0.10668)
		(layer "F.Cu")
		(net "M_F_CPU0_SB_CB<1>")
	)
	(segment
		(start 285.408116 -279.359868)
		(end 286.258254 -280.210006)
		(width 0.14478)
		(layer "In11.Cu")
		(net "M_F_CPU0_SB_CB<1>")
	)
	(segment
		(start 313.762644 -272.436844)
		(end 313.990228 -272.20926)
		(width 0.14478)
		(layer "In11.Cu")
		(net "M_F_CPU0_SB_CB<1>")
	)
	(segment
		(start 274.322286 -280.363676)
		(end 274.4851 -280.52649)
		(width 0.14478)
		(layer "In11.Cu")
		(net "M_F_CPU0_SB_CB<1>")
	)
	(segment
		(start 269.648178 -279.785064)
		(end 270.465296 -280.602182)
		(width 0.14478)
		(layer "In11.Cu")
		(net "M_F_CPU0_SB_CB<1>")
	)
	(segment
		(start 270.695928 -280.602182)
		(end 270.858742 -280.439368)
		(width 0.14478)
		(layer "In11.Cu")
		(net "M_F_CPU0_SB_CB<1>")
	)
	(segment
		(start 283.241496 -279.359868)
		(end 285.408116 -279.359868)
		(width 0.14478)
		(layer "In11.Cu")
		(net "M_F_CPU0_SB_CB<1>")
	)
	(segment
		(start 313.688476 -273.143726)
		(end 313.87415 -272.958052)
		(width 0.14478)
		(layer "In11.Cu")
		(net "M_F_CPU0_SB_CB<1>")
	)
	(segment
		(start 270.465296 -280.602182)
		(end 270.695928 -280.602182)
		(width 0.14478)
		(layer "In11.Cu")
		(net "M_F_CPU0_SB_CB<1>")
	)
	(segment
		(start 271.415002 -279.982168)
		(end 271.415002 -280.439368)
		(width 0.14478)
		(layer "In11.Cu")
		(net "M_F_CPU0_SB_CB<1>")
	)
	(segment
		(start 286.258254 -280.210006)
		(end 290.493958 -280.210006)
		(width 0.14478)
		(layer "In11.Cu")
		(net "M_F_CPU0_SB_CB<1>")
	)
	(segment
		(start 274.4851 -280.52649)
		(end 274.715732 -280.52649)
		(width 0.14478)
		(layer "In11.Cu")
		(net "M_F_CPU0_SB_CB<1>")
	)
	(segment
		(start 271.415002 -280.439368)
		(end 271.577816 -280.602182)
		(width 0.14478)
		(layer "In11.Cu")
		(net "M_F_CPU0_SB_CB<1>")
	)
	(segment
		(start 330.119736 -273.603466)
		(end 330.128118 -273.59864)
		(width 0.0889)
		(layer "In11.Cu")
		(net "M_F_CPU0_SB_CB<1>")
	)
	(segment
		(start 297.690286 -280.210006)
		(end 298.540424 -279.359868)
		(width 0.14478)
		(layer "In11.Cu")
		(net "M_F_CPU0_SB_CB<1>")
	)
	(segment
		(start 313.990228 -272.20926)
		(end 323.901054 -272.20926)
		(width 0.14478)
		(layer "In11.Cu")
		(net "M_F_CPU0_SB_CB<1>")
	)
	(segment
		(start 271.971262 -280.439368)
		(end 271.971262 -279.982168)
		(width 0.14478)
		(layer "In11.Cu")
		(net "M_F_CPU0_SB_CB<1>")
	)
	(segment
		(start 313.093862 -273.533616)
		(end 312.982102 -273.421856)
		(width 0.14478)
		(layer "In11.Cu")
		(net "M_F_CPU0_SB_CB<1>")
	)
	(segment
		(start 271.252188 -279.819354)
		(end 271.415002 -279.982168)
		(width 0.14478)
		(layer "In11.Cu")
		(net "M_F_CPU0_SB_CB<1>")
	)
	(segment
		(start 313.167776 -273.031712)
		(end 313.3725 -273.031712)
		(width 0.14478)
		(layer "In11.Cu")
		(net "M_F_CPU0_SB_CB<1>")
	)
	(segment
		(start 312.592212 -273.812)
		(end 312.703972 -273.92376)
		(width 0.14478)
		(layer "In11.Cu")
		(net "M_F_CPU0_SB_CB<1>")
	)
	(segment
		(start 291.342318 -279.361646)
		(end 293.11219 -279.361646)
		(width 0.14478)
		(layer "In11.Cu")
		(net "M_F_CPU0_SB_CB<1>")
	)
	(segment
		(start 307.862478 -278.33701)
		(end 312.387488 -273.812)
		(width 0.14478)
		(layer "In11.Cu")
		(net "M_F_CPU0_SB_CB<1>")
	)
	(segment
		(start 271.971262 -279.982168)
		(end 272.134076 -279.819354)
		(width 0.14478)
		(layer "In11.Cu")
		(net "M_F_CPU0_SB_CB<1>")
	)
	(segment
		(start 307.531008 -279.359868)
		(end 307.862478 -279.028398)
		(width 0.14478)
		(layer "In11.Cu")
		(net "M_F_CPU0_SB_CB<1>")
	)
	(segment
		(start 293.11219 -279.361646)
		(end 293.96055 -280.210006)
		(width 0.14478)
		(layer "In11.Cu")
		(net "M_F_CPU0_SB_CB<1>")
	)
	(segment
		(start 272.75536 -280.210006)
		(end 273.534378 -280.210006)
		(width 0.14478)
		(layer "In11.Cu")
		(net "M_F_CPU0_SB_CB<1>")
	)
	(segment
		(start 273.92884 -279.815544)
		(end 274.159472 -279.815544)
		(width 0.14478)
		(layer "In11.Cu")
		(net "M_F_CPU0_SB_CB<1>")
	)
	(segment
		(start 300.857412 -279.359868)
		(end 301.70755 -280.210006)
		(width 0.14478)
		(layer "In11.Cu")
		(net "M_F_CPU0_SB_CB<1>")
	)
	(segment
		(start 274.322286 -279.978358)
		(end 274.322286 -280.363676)
		(width 0.14478)
		(layer "In11.Cu")
		(net "M_F_CPU0_SB_CB<1>")
	)
	(segment
		(start 312.387488 -273.812)
		(end 312.592212 -273.812)
		(width 0.14478)
		(layer "In11.Cu")
		(net "M_F_CPU0_SB_CB<1>")
	)
	(segment
		(start 312.982102 -273.421856)
		(end 312.982356 -273.217132)
		(width 0.14478)
		(layer "In11.Cu")
		(net "M_F_CPU0_SB_CB<1>")
	)
	(segment
		(start 274.159472 -279.815544)
		(end 274.322286 -279.978358)
		(width 0.14478)
		(layer "In11.Cu")
		(net "M_F_CPU0_SB_CB<1>")
	)
	(segment
		(start 326.46493 -273.522186)
		(end 327.590658 -273.522186)
		(width 0.0889)
		(layer "In11.Cu")
		(net "M_F_CPU0_SB_CB<1>")
	)
	(segment
		(start 271.577816 -280.602182)
		(end 271.808448 -280.602182)
		(width 0.14478)
		(layer "In11.Cu")
		(net "M_F_CPU0_SB_CB<1>")
	)
	(segment
		(start 274.715732 -280.52649)
		(end 275.882354 -279.359868)
		(width 0.14478)
		(layer "In11.Cu")
		(net "M_F_CPU0_SB_CB<1>")
	)
	(segment
		(start 333.832708 -273.624802)
		(end 333.85506 -273.54149)
		(width 0.0889)
		(layer "In11.Cu")
		(net "M_F_CPU0_SB_CB<1>")
	)
	(segment
		(start 313.76239 -272.641568)
		(end 313.762644 -272.436844)
		(width 0.14478)
		(layer "In11.Cu")
		(net "M_F_CPU0_SB_CB<1>")
	)
	(segment
		(start 307.862478 -279.028398)
		(end 307.862478 -278.33701)
		(width 0.14478)
		(layer "In11.Cu")
		(net "M_F_CPU0_SB_CB<1>")
	)
	(segment
		(start 312.982356 -273.217132)
		(end 313.167776 -273.031712)
		(width 0.14478)
		(layer "In11.Cu")
		(net "M_F_CPU0_SB_CB<1>")
	)
	(segment
		(start 272.134076 -279.819354)
		(end 272.364708 -279.819354)
		(width 0.14478)
		(layer "In11.Cu")
		(net "M_F_CPU0_SB_CB<1>")
	)
	(segment
		(start 271.021556 -279.819354)
		(end 271.252188 -279.819354)
		(width 0.14478)
		(layer "In11.Cu")
		(net "M_F_CPU0_SB_CB<1>")
	)
	(segment
		(start 325.152004 -272.20926)
		(end 326.46493 -273.522186)
		(width 0.0889)
		(layer "In11.Cu")
		(net "M_F_CPU0_SB_CB<1>")
	)
	(segment
		(start 331.634084 -273.59864)
		(end 331.642466 -273.603466)
		(width 0.0889)
		(layer "In11.Cu")
		(net "M_F_CPU0_SB_CB<1>")
	)
	(segment
		(start 270.858742 -280.439368)
		(end 270.858742 -279.982168)
		(width 0.14478)
		(layer "In11.Cu")
		(net "M_F_CPU0_SB_CB<1>")
	)
	(segment
		(start 271.808448 -280.602182)
		(end 271.971262 -280.439368)
		(width 0.14478)
		(layer "In11.Cu")
		(net "M_F_CPU0_SB_CB<1>")
	)
	(segment
		(start 333.85506 -273.54149)
		(end 333.701136 -273.27606)
		(width 0.0889)
		(layer "In11.Cu")
		(net "M_F_CPU0_SB_CB<1>")
	)
	(segment
		(start 330.69403 -273.59864)
		(end 330.702412 -273.603466)
		(width 0.0889)
		(layer "In11.Cu")
		(net "M_F_CPU0_SB_CB<1>")
	)
	(segment
		(start 305.923696 -279.359868)
		(end 307.531008 -279.359868)
		(width 0.14478)
		(layer "In11.Cu")
		(net "M_F_CPU0_SB_CB<1>")
	)
	(segment
		(start 270.858742 -279.982168)
		(end 271.021556 -279.819354)
		(width 0.14478)
		(layer "In11.Cu")
		(net "M_F_CPU0_SB_CB<1>")
	)
	(segment
		(start 290.493958 -280.210006)
		(end 291.342318 -279.361646)
		(width 0.14478)
		(layer "In11.Cu")
		(net "M_F_CPU0_SB_CB<1>")
	)
	(segment
		(start 313.48426 -273.143472)
		(end 313.688476 -273.143726)
		(width 0.14478)
		(layer "In11.Cu")
		(net "M_F_CPU0_SB_CB<1>")
	)
	(segment
		(start 282.391358 -280.210006)
		(end 283.241496 -279.359868)
		(width 0.14478)
		(layer "In11.Cu")
		(net "M_F_CPU0_SB_CB<1>")
	)
	(segment
		(start 305.073558 -280.210006)
		(end 305.923696 -279.359868)
		(width 0.14478)
		(layer "In11.Cu")
		(net "M_F_CPU0_SB_CB<1>")
	)
	(segment
		(start 312.703972 -273.92376)
		(end 312.908188 -273.924014)
		(width 0.14478)
		(layer "In11.Cu")
		(net "M_F_CPU0_SB_CB<1>")
	)
	(segment
		(start 298.540424 -279.359868)
		(end 300.857412 -279.359868)
		(width 0.14478)
		(layer "In11.Cu")
		(net "M_F_CPU0_SB_CB<1>")
	)
	(segment
		(start 313.093862 -273.73834)
		(end 313.093862 -273.533616)
		(width 0.14478)
		(layer "In11.Cu")
		(net "M_F_CPU0_SB_CB<1>")
	)
	(segment
		(start 272.364708 -279.819354)
		(end 272.75536 -280.210006)
		(width 0.14478)
		(layer "In11.Cu")
		(net "M_F_CPU0_SB_CB<1>")
	)
	(segment
		(start 313.87415 -272.958052)
		(end 313.87415 -272.753328)
		(width 0.14478)
		(layer "In11.Cu")
		(net "M_F_CPU0_SB_CB<1>")
	)
	(segment
		(start 313.87415 -272.753328)
		(end 313.76239 -272.641568)
		(width 0.14478)
		(layer "In11.Cu")
		(net "M_F_CPU0_SB_CB<1>")
	)
	(segment
		(start 301.70755 -280.210006)
		(end 305.073558 -280.210006)
		(width 0.14478)
		(layer "In11.Cu")
		(net "M_F_CPU0_SB_CB<1>")
	)
	(segment
		(start 275.882354 -279.359868)
		(end 278.505412 -279.359868)
		(width 0.14478)
		(layer "In11.Cu")
		(net "M_F_CPU0_SB_CB<1>")
	)
	(segment
		(start 273.534378 -280.210006)
		(end 273.92884 -279.815544)
		(width 0.14478)
		(layer "In11.Cu")
		(net "M_F_CPU0_SB_CB<1>")
	)
	(segment
		(start 313.3725 -273.031712)
		(end 313.48426 -273.143472)
		(width 0.14478)
		(layer "In11.Cu")
		(net "M_F_CPU0_SB_CB<1>")
	)
	(segment
		(start 323.901054 -272.20926)
		(end 325.152004 -272.20926)
		(width 0.0889)
		(layer "In11.Cu")
		(net "M_F_CPU0_SB_CB<1>")
	)
	(segment
		(start 278.505412 -279.359868)
		(end 279.35555 -280.210006)
		(width 0.14478)
		(layer "In11.Cu")
		(net "M_F_CPU0_SB_CB<1>")
	)
	(segment
		(start 279.35555 -280.210006)
		(end 282.391358 -280.210006)
		(width 0.14478)
		(layer "In11.Cu")
		(net "M_F_CPU0_SB_CB<1>")
	)
	(segment
		(start 293.96055 -280.210006)
		(end 297.690286 -280.210006)
		(width 0.14478)
		(layer "In11.Cu")
		(net "M_F_CPU0_SB_CB<1>")
	)
	(segment
		(start 312.908188 -273.924014)
		(end 313.093862 -273.73834)
		(width 0.14478)
		(layer "In11.Cu")
		(net "M_F_CPU0_SB_CB<1>")
	)
	(arc
		(start 327.590658 -273.522186)
		(mid 327.737326 -273.541663)
		(end 327.873868 -273.59864)
		(width 0.0889)
		(layer "In11.Cu")
		(net "M_F_CPU0_SB_CB<1>")
	)
	(arc
		(start 327.873868 -273.59864)
		(mid 328.061066 -273.649022)
		(end 328.248264 -273.59864)
		(width 0.0889)
		(layer "In11.Cu")
		(net "M_F_CPU0_SB_CB<1>")
	)
	(arc
		(start 328.248264 -273.59864)
		(mid 328.53122 -273.522463)
		(end 328.814176 -273.59864)
		(width 0.0889)
		(layer "In11.Cu")
		(net "M_F_CPU0_SB_CB<1>")
	)
	(arc
		(start 332.574138 -273.59864)
		(mid 332.761082 -273.648895)
		(end 332.948026 -273.59864)
		(width 0.0889)
		(layer "In11.Cu")
		(net "M_F_CPU0_SB_CB<1>")
	)
	(arc
		(start 332.948026 -273.59864)
		(mid 333.230982 -273.522463)
		(end 333.513938 -273.59864)
		(width 0.0889)
		(layer "In11.Cu")
		(net "M_F_CPU0_SB_CB<1>")
	)
	(arc
		(start 330.128118 -273.59864)
		(mid 330.411074 -273.522463)
		(end 330.69403 -273.59864)
		(width 0.0889)
		(layer "In11.Cu")
		(net "M_F_CPU0_SB_CB<1>")
	)
	(arc
		(start 333.513938 -273.59864)
		(mid 333.670376 -273.647611)
		(end 333.832708 -273.624802)
		(width 0.0889)
		(layer "In11.Cu")
		(net "M_F_CPU0_SB_CB<1>")
	)
	(arc
		(start 331.642466 -273.603466)
		(mid 331.825974 -273.64896)
		(end 332.008226 -273.59864)
		(width 0.0889)
		(layer "In11.Cu")
		(net "M_F_CPU0_SB_CB<1>")
	)
	(arc
		(start 330.702412 -273.603466)
		(mid 330.88592 -273.64896)
		(end 331.068172 -273.59864)
		(width 0.0889)
		(layer "In11.Cu")
		(net "M_F_CPU0_SB_CB<1>")
	)
	(arc
		(start 331.068172 -273.59864)
		(mid 331.351128 -273.522463)
		(end 331.634084 -273.59864)
		(width 0.0889)
		(layer "In11.Cu")
		(net "M_F_CPU0_SB_CB<1>")
	)
	(arc
		(start 329.753976 -273.59864)
		(mid 329.936227 -273.64899)
		(end 330.119736 -273.603466)
		(width 0.0889)
		(layer "In11.Cu")
		(net "M_F_CPU0_SB_CB<1>")
	)
	(arc
		(start 332.008226 -273.59864)
		(mid 332.291182 -273.522463)
		(end 332.574138 -273.59864)
		(width 0.0889)
		(layer "In11.Cu")
		(net "M_F_CPU0_SB_CB<1>")
	)
	(arc
		(start 329.188064 -273.59864)
		(mid 329.47102 -273.522463)
		(end 329.753976 -273.59864)
		(width 0.0889)
		(layer "In11.Cu")
		(net "M_F_CPU0_SB_CB<1>")
	)
	(arc
		(start 328.814176 -273.59864)
		(mid 329.00112 -273.648895)
		(end 329.188064 -273.59864)
		(width 0.0889)
		(layer "In11.Cu")
		(net "M_F_CPU0_SB_CB<1>")
	)
	(segment
		(start 332.758034 -272.200116)
		(end 332.291182 -272.466054)
		(width 0.10668)
		(layer "F.Cu")
		(net "M_F_CPU0_SB_CB<0>")
	)
	(segment
		(start 283.17317 -277.6601)
		(end 283.39542 -277.6601)
		(width 0.14478)
		(layer "In11.Cu")
		(net "M_F_CPU0_SB_CB<0>")
	)
	(segment
		(start 302.725582 -278.271732)
		(end 302.870362 -278.416512)
		(width 0.14478)
		(layer "In11.Cu")
		(net "M_F_CPU0_SB_CB<0>")
	)
	(segment
		(start 275.860002 -277.6601)
		(end 276.02307 -277.823168)
		(width 0.14478)
		(layer "In11.Cu")
		(net "M_F_CPU0_SB_CB<0>")
	)
	(segment
		(start 281.83713 -278.902414)
		(end 282.000198 -278.739346)
		(width 0.14478)
		(layer "In11.Cu")
		(net "M_F_CPU0_SB_CB<0>")
	)
	(segment
		(start 298.682918 -277.823168)
		(end 298.682918 -277.883366)
		(width 0.14478)
		(layer "In11.Cu")
		(net "M_F_CPU0_SB_CB<0>")
	)
	(segment
		(start 294.367458 -278.519636)
		(end 296.283126 -278.519636)
		(width 0.14478)
		(layer "In11.Cu")
		(net "M_F_CPU0_SB_CB<0>")
	)
	(segment
		(start 299.076364 -278.046434)
		(end 299.239432 -277.883366)
		(width 0.14478)
		(layer "In11.Cu")
		(net "M_F_CPU0_SB_CB<0>")
	)
	(segment
		(start 296.436542 -278.673052)
		(end 296.436542 -278.739346)
		(width 0.14478)
		(layer "In11.Cu")
		(net "M_F_CPU0_SB_CB<0>")
	)
	(segment
		(start 272.511774 -278.519636)
		(end 274.745196 -278.519636)
		(width 0.14478)
		(layer "In11.Cu")
		(net "M_F_CPU0_SB_CB<0>")
	)
	(segment
		(start 291.692076 -277.883366)
		(end 291.692076 -277.823168)
		(width 0.14478)
		(layer "In11.Cu")
		(net "M_F_CPU0_SB_CB<0>")
	)
	(segment
		(start 302.463708 -278.271732)
		(end 302.725582 -278.271732)
		(width 0.14478)
		(layer "In11.Cu")
		(net "M_F_CPU0_SB_CB<0>")
	)
	(segment
		(start 271.638776 -278.509984)
		(end 271.801844 -278.673052)
		(width 0.14478)
		(layer "In11.Cu")
		(net "M_F_CPU0_SB_CB<0>")
	)
	(segment
		(start 299.239432 -277.823168)
		(end 299.392848 -277.669752)
		(width 0.14478)
		(layer "In11.Cu")
		(net "M_F_CPU0_SB_CB<0>")
	)
	(segment
		(start 282.163266 -278.509984)
		(end 282.323286 -278.509984)
		(width 0.14478)
		(layer "In11.Cu")
		(net "M_F_CPU0_SB_CB<0>")
	)
	(segment
		(start 299.392848 -277.669752)
		(end 300.788324 -277.669752)
		(width 0.14478)
		(layer "In11.Cu")
		(net "M_F_CPU0_SB_CB<0>")
	)
	(segment
		(start 329.284076 -272.788634)
		(end 329.292458 -272.79346)
		(width 0.0889)
		(layer "In11.Cu")
		(net "M_F_CPU0_SB_CB<0>")
	)
	(segment
		(start 288.984944 -278.673052)
		(end 288.984944 -278.739346)
		(width 0.14478)
		(layer "In11.Cu")
		(net "M_F_CPU0_SB_CB<0>")
	)
	(segment
		(start 302.870362 -278.65197)
		(end 303.015142 -278.79675)
		(width 0.14478)
		(layer "In11.Cu")
		(net "M_F_CPU0_SB_CB<0>")
	)
	(segment
		(start 270.385794 -278.346916)
		(end 270.385794 -277.942802)
		(width 0.14478)
		(layer "In11.Cu")
		(net "M_F_CPU0_SB_CB<0>")
	)
	(segment
		(start 291.845492 -277.669752)
		(end 293.517574 -277.669752)
		(width 0.14478)
		(layer "In11.Cu")
		(net "M_F_CPU0_SB_CB<0>")
	)
	(segment
		(start 324.840854 -271.74571)
		(end 325.40321 -271.74571)
		(width 0.0889)
		(layer "In11.Cu")
		(net "M_F_CPU0_SB_CB<0>")
	)
	(segment
		(start 276.02307 -277.890986)
		(end 276.186138 -278.054054)
		(width 0.14478)
		(layer "In11.Cu")
		(net "M_F_CPU0_SB_CB<0>")
	)
	(segment
		(start 289.541458 -278.673052)
		(end 289.704526 -278.509984)
		(width 0.14478)
		(layer "In11.Cu")
		(net "M_F_CPU0_SB_CB<0>")
	)
	(segment
		(start 282.000198 -278.739346)
		(end 282.000198 -278.673052)
		(width 0.14478)
		(layer "In11.Cu")
		(net "M_F_CPU0_SB_CB<0>")
	)
	(segment
		(start 269.648178 -278.085042)
		(end 270.07312 -278.509984)
		(width 0.14478)
		(layer "In11.Cu")
		(net "M_F_CPU0_SB_CB<0>")
	)
	(segment
		(start 276.416516 -278.054054)
		(end 276.579584 -277.890986)
		(width 0.14478)
		(layer "In11.Cu")
		(net "M_F_CPU0_SB_CB<0>")
	)
	(segment
		(start 298.845986 -278.046434)
		(end 299.076364 -278.046434)
		(width 0.14478)
		(layer "In11.Cu")
		(net "M_F_CPU0_SB_CB<0>")
	)
	(segment
		(start 283.721556 -278.054054)
		(end 283.951934 -278.054054)
		(width 0.14478)
		(layer "In11.Cu")
		(net "M_F_CPU0_SB_CB<0>")
	)
	(segment
		(start 296.283126 -278.519636)
		(end 296.436542 -278.673052)
		(width 0.14478)
		(layer "In11.Cu")
		(net "M_F_CPU0_SB_CB<0>")
	)
	(segment
		(start 326.387206 -272.729706)
		(end 326.38746 -272.729706)
		(width 0.0889)
		(layer "In11.Cu")
		(net "M_F_CPU0_SB_CB<0>")
	)
	(segment
		(start 331.52969 -272.79346)
		(end 331.538072 -272.788634)
		(width 0.0889)
		(layer "In11.Cu")
		(net "M_F_CPU0_SB_CB<0>")
	)
	(segment
		(start 297.389042 -278.509984)
		(end 298.238926 -277.6601)
		(width 0.14478)
		(layer "In11.Cu")
		(net "M_F_CPU0_SB_CB<0>")
	)
	(segment
		(start 327.765156 -272.796254)
		(end 327.778872 -272.78838)
		(width 0.0889)
		(layer "In11.Cu")
		(net "M_F_CPU0_SB_CB<0>")
	)
	(segment
		(start 327.778872 -272.78838)
		(end 327.79081 -272.781522)
		(width 0.0889)
		(layer "In11.Cu")
		(net "M_F_CPU0_SB_CB<0>")
	)
	(segment
		(start 291.135562 -277.823168)
		(end 291.135562 -277.883366)
		(width 0.14478)
		(layer "In11.Cu")
		(net "M_F_CPU0_SB_CB<0>")
	)
	(segment
		(start 302.174148 -278.79675)
		(end 302.318928 -278.65197)
		(width 0.14478)
		(layer "In11.Cu")
		(net "M_F_CPU0_SB_CB<0>")
	)
	(segment
		(start 270.385794 -277.942802)
		(end 270.548862 -277.779734)
		(width 0.14478)
		(layer "In11.Cu")
		(net "M_F_CPU0_SB_CB<0>")
	)
	(segment
		(start 298.238926 -277.6601)
		(end 298.51985 -277.6601)
		(width 0.14478)
		(layer "In11.Cu")
		(net "M_F_CPU0_SB_CB<0>")
	)
	(segment
		(start 276.733 -277.669752)
		(end 278.420576 -277.669752)
		(width 0.14478)
		(layer "In11.Cu")
		(net "M_F_CPU0_SB_CB<0>")
	)
	(segment
		(start 302.870362 -278.416512)
		(end 302.870362 -278.65197)
		(width 0.14478)
		(layer "In11.Cu")
		(net "M_F_CPU0_SB_CB<0>")
	)
	(segment
		(start 272.358358 -278.739346)
		(end 272.358358 -278.673052)
		(width 0.14478)
		(layer "In11.Cu")
		(net "M_F_CPU0_SB_CB<0>")
	)
	(segment
		(start 288.984944 -278.739346)
		(end 289.148012 -278.902414)
		(width 0.14478)
		(layer "In11.Cu")
		(net "M_F_CPU0_SB_CB<0>")
	)
	(segment
		(start 281.443684 -278.739346)
		(end 281.606752 -278.902414)
		(width 0.14478)
		(layer "In11.Cu")
		(net "M_F_CPU0_SB_CB<0>")
	)
	(segment
		(start 303.566576 -278.271732)
		(end 303.82845 -278.271732)
		(width 0.14478)
		(layer "In11.Cu")
		(net "M_F_CPU0_SB_CB<0>")
	)
	(segment
		(start 291.692076 -277.823168)
		(end 291.845492 -277.669752)
		(width 0.14478)
		(layer "In11.Cu")
		(net "M_F_CPU0_SB_CB<0>")
	)
	(segment
		(start 272.19529 -278.902414)
		(end 272.358358 -278.739346)
		(width 0.14478)
		(layer "In11.Cu")
		(net "M_F_CPU0_SB_CB<0>")
	)
	(segment
		(start 271.801844 -278.739346)
		(end 271.964912 -278.902414)
		(width 0.14478)
		(layer "In11.Cu")
		(net "M_F_CPU0_SB_CB<0>")
	)
	(segment
		(start 270.222726 -278.509984)
		(end 270.385794 -278.346916)
		(width 0.14478)
		(layer "In11.Cu")
		(net "M_F_CPU0_SB_CB<0>")
	)
	(segment
		(start 328.709782 -272.79346)
		(end 328.718164 -272.788634)
		(width 0.0889)
		(layer "In11.Cu")
		(net "M_F_CPU0_SB_CB<0>")
	)
	(segment
		(start 271.964912 -278.902414)
		(end 272.19529 -278.902414)
		(width 0.14478)
		(layer "In11.Cu")
		(net "M_F_CPU0_SB_CB<0>")
	)
	(segment
		(start 327.387204 -272.777966)
		(end 327.405238 -272.788634)
		(width 0.0889)
		(layer "In11.Cu")
		(net "M_F_CPU0_SB_CB<0>")
	)
	(segment
		(start 281.290268 -278.519636)
		(end 281.443684 -278.673052)
		(width 0.14478)
		(layer "In11.Cu")
		(net "M_F_CPU0_SB_CB<0>")
	)
	(segment
		(start 278.420576 -277.669752)
		(end 279.27046 -278.519636)
		(width 0.14478)
		(layer "In11.Cu")
		(net "M_F_CPU0_SB_CB<0>")
	)
	(segment
		(start 274.745196 -278.519636)
		(end 275.604732 -277.6601)
		(width 0.14478)
		(layer "In11.Cu")
		(net "M_F_CPU0_SB_CB<0>")
	)
	(segment
		(start 272.358358 -278.673052)
		(end 272.511774 -278.519636)
		(width 0.14478)
		(layer "In11.Cu")
		(net "M_F_CPU0_SB_CB<0>")
	)
	(segment
		(start 323.901054 -271.29994)
		(end 324.395084 -271.29994)
		(width 0.0889)
		(layer "In11.Cu")
		(net "M_F_CPU0_SB_CB<0>")
	)
	(segment
		(start 306.872132 -278.055324)
		(end 313.627516 -271.29994)
		(width 0.14478)
		(layer "In11.Cu")
		(net "M_F_CPU0_SB_CB<0>")
	)
	(segment
		(start 296.993056 -278.739346)
		(end 296.993056 -278.673052)
		(width 0.14478)
		(layer "In11.Cu")
		(net "M_F_CPU0_SB_CB<0>")
	)
	(segment
		(start 290.972494 -277.6601)
		(end 291.135562 -277.823168)
		(width 0.14478)
		(layer "In11.Cu")
		(net "M_F_CPU0_SB_CB<0>")
	)
	(segment
		(start 296.59961 -278.902414)
		(end 296.829988 -278.902414)
		(width 0.14478)
		(layer "In11.Cu")
		(net "M_F_CPU0_SB_CB<0>")
	)
	(segment
		(start 283.39542 -277.6601)
		(end 283.558488 -277.823168)
		(width 0.14478)
		(layer "In11.Cu")
		(net "M_F_CPU0_SB_CB<0>")
	)
	(segment
		(start 270.07312 -278.509984)
		(end 270.222726 -278.509984)
		(width 0.14478)
		(layer "In11.Cu")
		(net "M_F_CPU0_SB_CB<0>")
	)
	(segment
		(start 276.02307 -277.823168)
		(end 276.02307 -277.890986)
		(width 0.14478)
		(layer "In11.Cu")
		(net "M_F_CPU0_SB_CB<0>")
	)
	(segment
		(start 296.436542 -278.739346)
		(end 296.59961 -278.902414)
		(width 0.14478)
		(layer "In11.Cu")
		(net "M_F_CPU0_SB_CB<0>")
	)
	(segment
		(start 305.80584 -278.055324)
		(end 306.872132 -278.055324)
		(width 0.14478)
		(layer "In11.Cu")
		(net "M_F_CPU0_SB_CB<0>")
	)
	(segment
		(start 283.558488 -277.823168)
		(end 283.558488 -277.890986)
		(width 0.14478)
		(layer "In11.Cu")
		(net "M_F_CPU0_SB_CB<0>")
	)
	(segment
		(start 300.788324 -277.669752)
		(end 301.915322 -278.79675)
		(width 0.14478)
		(layer "In11.Cu")
		(net "M_F_CPU0_SB_CB<0>")
	)
	(segment
		(start 305.064414 -278.79675)
		(end 305.80584 -278.055324)
		(width 0.14478)
		(layer "In11.Cu")
		(net "M_F_CPU0_SB_CB<0>")
	)
	(segment
		(start 270.77924 -277.779734)
		(end 270.942308 -277.942802)
		(width 0.14478)
		(layer "In11.Cu")
		(net "M_F_CPU0_SB_CB<0>")
	)
	(segment
		(start 291.529008 -278.046434)
		(end 291.692076 -277.883366)
		(width 0.14478)
		(layer "In11.Cu")
		(net "M_F_CPU0_SB_CB<0>")
	)
	(segment
		(start 270.942308 -277.942802)
		(end 270.942308 -278.346916)
		(width 0.14478)
		(layer "In11.Cu")
		(net "M_F_CPU0_SB_CB<0>")
	)
	(segment
		(start 303.421796 -278.65197)
		(end 303.421796 -278.416512)
		(width 0.14478)
		(layer "In11.Cu")
		(net "M_F_CPU0_SB_CB<0>")
	)
	(segment
		(start 284.115002 -277.890986)
		(end 284.115002 -277.823168)
		(width 0.14478)
		(layer "In11.Cu")
		(net "M_F_CPU0_SB_CB<0>")
	)
	(segment
		(start 298.51985 -277.6601)
		(end 298.682918 -277.823168)
		(width 0.14478)
		(layer "In11.Cu")
		(net "M_F_CPU0_SB_CB<0>")
	)
	(segment
		(start 289.883088 -278.509984)
		(end 290.732972 -277.6601)
		(width 0.14478)
		(layer "In11.Cu")
		(net "M_F_CPU0_SB_CB<0>")
	)
	(segment
		(start 332.422754 -272.814796)
		(end 332.445106 -272.731484)
		(width 0.0889)
		(layer "In11.Cu")
		(net "M_F_CPU0_SB_CB<0>")
	)
	(segment
		(start 303.82845 -278.271732)
		(end 303.97323 -278.416512)
		(width 0.14478)
		(layer "In11.Cu")
		(net "M_F_CPU0_SB_CB<0>")
	)
	(segment
		(start 283.951934 -278.054054)
		(end 284.115002 -277.890986)
		(width 0.14478)
		(layer "In11.Cu")
		(net "M_F_CPU0_SB_CB<0>")
	)
	(segment
		(start 284.268418 -277.669752)
		(end 285.9024 -277.669752)
		(width 0.14478)
		(layer "In11.Cu")
		(net "M_F_CPU0_SB_CB<0>")
	)
	(segment
		(start 276.579584 -277.823168)
		(end 276.733 -277.669752)
		(width 0.14478)
		(layer "In11.Cu")
		(net "M_F_CPU0_SB_CB<0>")
	)
	(segment
		(start 270.548862 -277.779734)
		(end 270.77924 -277.779734)
		(width 0.14478)
		(layer "In11.Cu")
		(net "M_F_CPU0_SB_CB<0>")
	)
	(segment
		(start 275.604732 -277.6601)
		(end 275.860002 -277.6601)
		(width 0.14478)
		(layer "In11.Cu")
		(net "M_F_CPU0_SB_CB<0>")
	)
	(segment
		(start 296.829988 -278.902414)
		(end 296.993056 -278.739346)
		(width 0.14478)
		(layer "In11.Cu")
		(net "M_F_CPU0_SB_CB<0>")
	)
	(segment
		(start 281.606752 -278.902414)
		(end 281.83713 -278.902414)
		(width 0.14478)
		(layer "In11.Cu")
		(net "M_F_CPU0_SB_CB<0>")
	)
	(segment
		(start 276.579584 -277.890986)
		(end 276.579584 -277.823168)
		(width 0.14478)
		(layer "In11.Cu")
		(net "M_F_CPU0_SB_CB<0>")
	)
	(segment
		(start 289.541458 -278.739346)
		(end 289.541458 -278.673052)
		(width 0.14478)
		(layer "In11.Cu")
		(net "M_F_CPU0_SB_CB<0>")
	)
	(segment
		(start 326.464676 -272.78838)
		(end 326.484742 -272.79981)
		(width 0.0889)
		(layer "In11.Cu")
		(net "M_F_CPU0_SB_CB<0>")
	)
	(segment
		(start 303.97323 -278.416512)
		(end 303.97323 -278.65197)
		(width 0.14478)
		(layer "In11.Cu")
		(net "M_F_CPU0_SB_CB<0>")
	)
	(segment
		(start 297.156124 -278.509984)
		(end 297.389042 -278.509984)
		(width 0.14478)
		(layer "In11.Cu")
		(net "M_F_CPU0_SB_CB<0>")
	)
	(segment
		(start 288.831528 -278.519636)
		(end 288.984944 -278.673052)
		(width 0.14478)
		(layer "In11.Cu")
		(net "M_F_CPU0_SB_CB<0>")
	)
	(segment
		(start 276.186138 -278.054054)
		(end 276.416516 -278.054054)
		(width 0.14478)
		(layer "In11.Cu")
		(net "M_F_CPU0_SB_CB<0>")
	)
	(segment
		(start 303.277016 -278.79675)
		(end 303.421796 -278.65197)
		(width 0.14478)
		(layer "In11.Cu")
		(net "M_F_CPU0_SB_CB<0>")
	)
	(segment
		(start 325.40321 -271.74571)
		(end 326.387206 -272.729706)
		(width 0.0889)
		(layer "In11.Cu")
		(net "M_F_CPU0_SB_CB<0>")
	)
	(segment
		(start 289.37839 -278.902414)
		(end 289.541458 -278.739346)
		(width 0.14478)
		(layer "In11.Cu")
		(net "M_F_CPU0_SB_CB<0>")
	)
	(segment
		(start 332.445106 -272.731484)
		(end 332.291182 -272.466054)
		(width 0.0889)
		(layer "In11.Cu")
		(net "M_F_CPU0_SB_CB<0>")
	)
	(segment
		(start 290.732972 -277.6601)
		(end 290.972494 -277.6601)
		(width 0.14478)
		(layer "In11.Cu")
		(net "M_F_CPU0_SB_CB<0>")
	)
	(segment
		(start 289.148012 -278.902414)
		(end 289.37839 -278.902414)
		(width 0.14478)
		(layer "In11.Cu")
		(net "M_F_CPU0_SB_CB<0>")
	)
	(segment
		(start 303.97323 -278.65197)
		(end 304.11801 -278.79675)
		(width 0.14478)
		(layer "In11.Cu")
		(net "M_F_CPU0_SB_CB<0>")
	)
	(segment
		(start 302.318928 -278.65197)
		(end 302.318928 -278.416512)
		(width 0.14478)
		(layer "In11.Cu")
		(net "M_F_CPU0_SB_CB<0>")
	)
	(segment
		(start 271.105376 -278.509984)
		(end 271.638776 -278.509984)
		(width 0.14478)
		(layer "In11.Cu")
		(net "M_F_CPU0_SB_CB<0>")
	)
	(segment
		(start 304.11801 -278.79675)
		(end 305.064414 -278.79675)
		(width 0.14478)
		(layer "In11.Cu")
		(net "M_F_CPU0_SB_CB<0>")
	)
	(segment
		(start 282.323286 -278.509984)
		(end 283.17317 -277.6601)
		(width 0.14478)
		(layer "In11.Cu")
		(net "M_F_CPU0_SB_CB<0>")
	)
	(segment
		(start 283.558488 -277.890986)
		(end 283.721556 -278.054054)
		(width 0.14478)
		(layer "In11.Cu")
		(net "M_F_CPU0_SB_CB<0>")
	)
	(segment
		(start 286.752284 -278.519636)
		(end 288.831528 -278.519636)
		(width 0.14478)
		(layer "In11.Cu")
		(net "M_F_CPU0_SB_CB<0>")
	)
	(segment
		(start 281.443684 -278.673052)
		(end 281.443684 -278.739346)
		(width 0.14478)
		(layer "In11.Cu")
		(net "M_F_CPU0_SB_CB<0>")
	)
	(segment
		(start 303.421796 -278.416512)
		(end 303.566576 -278.271732)
		(width 0.14478)
		(layer "In11.Cu")
		(net "M_F_CPU0_SB_CB<0>")
	)
	(segment
		(start 291.135562 -277.883366)
		(end 291.29863 -278.046434)
		(width 0.14478)
		(layer "In11.Cu")
		(net "M_F_CPU0_SB_CB<0>")
	)
	(segment
		(start 293.517574 -277.669752)
		(end 294.367458 -278.519636)
		(width 0.14478)
		(layer "In11.Cu")
		(net "M_F_CPU0_SB_CB<0>")
	)
	(segment
		(start 284.115002 -277.823168)
		(end 284.268418 -277.669752)
		(width 0.14478)
		(layer "In11.Cu")
		(net "M_F_CPU0_SB_CB<0>")
	)
	(segment
		(start 299.239432 -277.883366)
		(end 299.239432 -277.823168)
		(width 0.14478)
		(layer "In11.Cu")
		(net "M_F_CPU0_SB_CB<0>")
	)
	(segment
		(start 302.318928 -278.416512)
		(end 302.463708 -278.271732)
		(width 0.14478)
		(layer "In11.Cu")
		(net "M_F_CPU0_SB_CB<0>")
	)
	(segment
		(start 282.000198 -278.673052)
		(end 282.163266 -278.509984)
		(width 0.14478)
		(layer "In11.Cu")
		(net "M_F_CPU0_SB_CB<0>")
	)
	(segment
		(start 301.915322 -278.79675)
		(end 302.174148 -278.79675)
		(width 0.14478)
		(layer "In11.Cu")
		(net "M_F_CPU0_SB_CB<0>")
	)
	(segment
		(start 296.993056 -278.673052)
		(end 297.156124 -278.509984)
		(width 0.14478)
		(layer "In11.Cu")
		(net "M_F_CPU0_SB_CB<0>")
	)
	(segment
		(start 289.704526 -278.509984)
		(end 289.883088 -278.509984)
		(width 0.14478)
		(layer "In11.Cu")
		(net "M_F_CPU0_SB_CB<0>")
	)
	(segment
		(start 291.29863 -278.046434)
		(end 291.529008 -278.046434)
		(width 0.14478)
		(layer "In11.Cu")
		(net "M_F_CPU0_SB_CB<0>")
	)
	(segment
		(start 303.015142 -278.79675)
		(end 303.277016 -278.79675)
		(width 0.14478)
		(layer "In11.Cu")
		(net "M_F_CPU0_SB_CB<0>")
	)
	(segment
		(start 313.627516 -271.29994)
		(end 323.901054 -271.29994)
		(width 0.14478)
		(layer "In11.Cu")
		(net "M_F_CPU0_SB_CB<0>")
	)
	(segment
		(start 298.682918 -277.883366)
		(end 298.845986 -278.046434)
		(width 0.14478)
		(layer "In11.Cu")
		(net "M_F_CPU0_SB_CB<0>")
	)
	(segment
		(start 285.9024 -277.669752)
		(end 286.752284 -278.519636)
		(width 0.14478)
		(layer "In11.Cu")
		(net "M_F_CPU0_SB_CB<0>")
	)
	(segment
		(start 271.801844 -278.673052)
		(end 271.801844 -278.739346)
		(width 0.14478)
		(layer "In11.Cu")
		(net "M_F_CPU0_SB_CB<0>")
	)
	(segment
		(start 324.395084 -271.29994)
		(end 324.840854 -271.74571)
		(width 0.0889)
		(layer "In11.Cu")
		(net "M_F_CPU0_SB_CB<0>")
	)
	(segment
		(start 279.27046 -278.519636)
		(end 281.290268 -278.519636)
		(width 0.14478)
		(layer "In11.Cu")
		(net "M_F_CPU0_SB_CB<0>")
	)
	(segment
		(start 270.942308 -278.346916)
		(end 271.105376 -278.509984)
		(width 0.14478)
		(layer "In11.Cu")
		(net "M_F_CPU0_SB_CB<0>")
	)
	(arc
		(start 327.79081 -272.781522)
		(mid 328.068344 -272.712541)
		(end 328.344022 -272.788634)
		(width 0.0889)
		(layer "In11.Cu")
		(net "M_F_CPU0_SB_CB<0>")
	)
	(arc
		(start 329.292458 -272.79346)
		(mid 329.475966 -272.838954)
		(end 329.658218 -272.788634)
		(width 0.0889)
		(layer "In11.Cu")
		(net "M_F_CPU0_SB_CB<0>")
	)
	(arc
		(start 331.16393 -272.788634)
		(mid 331.346181 -272.838984)
		(end 331.52969 -272.79346)
		(width 0.0889)
		(layer "In11.Cu")
		(net "M_F_CPU0_SB_CB<0>")
	)
	(arc
		(start 326.484742 -272.79981)
		(mid 326.663074 -272.838907)
		(end 326.838564 -272.788634)
		(width 0.0889)
		(layer "In11.Cu")
		(net "M_F_CPU0_SB_CB<0>")
	)
	(arc
		(start 332.103984 -272.788634)
		(mid 332.260422 -272.837605)
		(end 332.422754 -272.814796)
		(width 0.0889)
		(layer "In11.Cu")
		(net "M_F_CPU0_SB_CB<0>")
	)
	(arc
		(start 331.538072 -272.788634)
		(mid 331.821028 -272.712457)
		(end 332.103984 -272.788634)
		(width 0.0889)
		(layer "In11.Cu")
		(net "M_F_CPU0_SB_CB<0>")
	)
	(arc
		(start 326.38746 -272.729706)
		(mid 326.424156 -272.761559)
		(end 326.464676 -272.78838)
		(width 0.0889)
		(layer "In11.Cu")
		(net "M_F_CPU0_SB_CB<0>")
	)
	(arc
		(start 326.838564 -272.788634)
		(mid 327.111508 -272.712054)
		(end 327.387204 -272.777966)
		(width 0.0889)
		(layer "In11.Cu")
		(net "M_F_CPU0_SB_CB<0>")
	)
	(arc
		(start 328.718164 -272.788634)
		(mid 329.00112 -272.712457)
		(end 329.284076 -272.788634)
		(width 0.0889)
		(layer "In11.Cu")
		(net "M_F_CPU0_SB_CB<0>")
	)
	(arc
		(start 329.658218 -272.788634)
		(mid 329.941174 -272.712457)
		(end 330.22413 -272.788634)
		(width 0.0889)
		(layer "In11.Cu")
		(net "M_F_CPU0_SB_CB<0>")
	)
	(arc
		(start 330.598018 -272.788634)
		(mid 330.880974 -272.712457)
		(end 331.16393 -272.788634)
		(width 0.0889)
		(layer "In11.Cu")
		(net "M_F_CPU0_SB_CB<0>")
	)
	(arc
		(start 327.405238 -272.788634)
		(mid 327.584225 -272.838804)
		(end 327.765156 -272.796254)
		(width 0.0889)
		(layer "In11.Cu")
		(net "M_F_CPU0_SB_CB<0>")
	)
	(arc
		(start 330.22413 -272.788634)
		(mid 330.411074 -272.838889)
		(end 330.598018 -272.788634)
		(width 0.0889)
		(layer "In11.Cu")
		(net "M_F_CPU0_SB_CB<0>")
	)
	(arc
		(start 328.344022 -272.788634)
		(mid 328.526273 -272.838984)
		(end 328.709782 -272.79346)
		(width 0.0889)
		(layer "In11.Cu")
		(net "M_F_CPU0_SB_CB<0>")
	)
	(segment
		(start 332.758034 -264.100056)
		(end 332.291182 -264.365994)
		(width 0.10668)
		(layer "F.Cu")
		(net "M_F_CPU0_SB_CA<6>")
	)
	(segment
		(start 323.936614 -264.61974)
		(end 324.199504 -264.61974)
		(width 0.0889)
		(layer "In11.Cu")
		(net "M_F_CPU0_SB_CA<6>")
	)
	(segment
		(start 271.973548 -265.528552)
		(end 271.973548 -265.982704)
		(width 0.14478)
		(layer "In11.Cu")
		(net "M_F_CPU0_SB_CA<6>")
	)
	(segment
		(start 274.338796 -265.533124)
		(end 274.50161 -265.37031)
		(width 0.14478)
		(layer "In11.Cu")
		(net "M_F_CPU0_SB_CA<6>")
	)
	(segment
		(start 273.94535 -266.15009)
		(end 274.175982 -266.15009)
		(width 0.14478)
		(layer "In11.Cu")
		(net "M_F_CPU0_SB_CA<6>")
	)
	(segment
		(start 274.895056 -265.533124)
		(end 274.895056 -265.987276)
		(width 0.14478)
		(layer "In11.Cu")
		(net "M_F_CPU0_SB_CA<6>")
	)
	(segment
		(start 270.698214 -265.365738)
		(end 270.861028 -265.528552)
		(width 0.14478)
		(layer "In11.Cu")
		(net "M_F_CPU0_SB_CA<6>")
	)
	(segment
		(start 271.417288 -265.528552)
		(end 271.580102 -265.365738)
		(width 0.14478)
		(layer "In11.Cu")
		(net "M_F_CPU0_SB_CA<6>")
	)
	(segment
		(start 270.861028 -265.982704)
		(end 271.023842 -266.145518)
		(width 0.14478)
		(layer "In11.Cu")
		(net "M_F_CPU0_SB_CA<6>")
	)
	(segment
		(start 325.399654 -264.30351)
		(end 325.708518 -264.612374)
		(width 0.0889)
		(layer "In11.Cu")
		(net "M_F_CPU0_SB_CA<6>")
	)
	(segment
		(start 332.422754 -264.714736)
		(end 332.445106 -264.631424)
		(width 0.0889)
		(layer "In11.Cu")
		(net "M_F_CPU0_SB_CA<6>")
	)
	(segment
		(start 275.05787 -266.15009)
		(end 275.288502 -266.15009)
		(width 0.14478)
		(layer "In11.Cu")
		(net "M_F_CPU0_SB_CA<6>")
	)
	(segment
		(start 332.445106 -264.631424)
		(end 332.291182 -264.365994)
		(width 0.0889)
		(layer "In11.Cu")
		(net "M_F_CPU0_SB_CA<6>")
	)
	(segment
		(start 274.895056 -265.987276)
		(end 275.05787 -266.15009)
		(width 0.14478)
		(layer "In11.Cu")
		(net "M_F_CPU0_SB_CA<6>")
	)
	(segment
		(start 327.778872 -264.68832)
		(end 327.79081 -264.681462)
		(width 0.0889)
		(layer "In11.Cu")
		(net "M_F_CPU0_SB_CA<6>")
	)
	(segment
		(start 274.175982 -266.15009)
		(end 274.338796 -265.987276)
		(width 0.14478)
		(layer "In11.Cu")
		(net "M_F_CPU0_SB_CA<6>")
	)
	(segment
		(start 308.16042 -265.7602)
		(end 309.30088 -264.61974)
		(width 0.14478)
		(layer "In11.Cu")
		(net "M_F_CPU0_SB_CA<6>")
	)
	(segment
		(start 324.515734 -264.30351)
		(end 325.399654 -264.30351)
		(width 0.0889)
		(layer "In11.Cu")
		(net "M_F_CPU0_SB_CA<6>")
	)
	(segment
		(start 274.732242 -265.37031)
		(end 274.895056 -265.533124)
		(width 0.14478)
		(layer "In11.Cu")
		(net "M_F_CPU0_SB_CA<6>")
	)
	(segment
		(start 309.30088 -264.61974)
		(end 323.936614 -264.61974)
		(width 0.14478)
		(layer "In11.Cu")
		(net "M_F_CPU0_SB_CA<6>")
	)
	(segment
		(start 271.023842 -266.145518)
		(end 271.254474 -266.145518)
		(width 0.14478)
		(layer "In11.Cu")
		(net "M_F_CPU0_SB_CA<6>")
	)
	(segment
		(start 274.50161 -265.37031)
		(end 274.732242 -265.37031)
		(width 0.14478)
		(layer "In11.Cu")
		(net "M_F_CPU0_SB_CA<6>")
	)
	(segment
		(start 269.648178 -266.185142)
		(end 270.467582 -265.365738)
		(width 0.14478)
		(layer "In11.Cu")
		(net "M_F_CPU0_SB_CA<6>")
	)
	(segment
		(start 273.55546 -265.7602)
		(end 273.94535 -266.15009)
		(width 0.14478)
		(layer "In11.Cu")
		(net "M_F_CPU0_SB_CA<6>")
	)
	(segment
		(start 272.752312 -265.7602)
		(end 273.55546 -265.7602)
		(width 0.14478)
		(layer "In11.Cu")
		(net "M_F_CPU0_SB_CA<6>")
	)
	(segment
		(start 272.136362 -266.145518)
		(end 272.366994 -266.145518)
		(width 0.14478)
		(layer "In11.Cu")
		(net "M_F_CPU0_SB_CA<6>")
	)
	(segment
		(start 328.709782 -264.6934)
		(end 328.718164 -264.688574)
		(width 0.0889)
		(layer "In11.Cu")
		(net "M_F_CPU0_SB_CA<6>")
	)
	(segment
		(start 274.338796 -265.987276)
		(end 274.338796 -265.533124)
		(width 0.14478)
		(layer "In11.Cu")
		(net "M_F_CPU0_SB_CA<6>")
	)
	(segment
		(start 271.580102 -265.365738)
		(end 271.810734 -265.365738)
		(width 0.14478)
		(layer "In11.Cu")
		(net "M_F_CPU0_SB_CA<6>")
	)
	(segment
		(start 326.464676 -264.68832)
		(end 326.484742 -264.69975)
		(width 0.0889)
		(layer "In11.Cu")
		(net "M_F_CPU0_SB_CA<6>")
	)
	(segment
		(start 270.861028 -265.528552)
		(end 270.861028 -265.982704)
		(width 0.14478)
		(layer "In11.Cu")
		(net "M_F_CPU0_SB_CA<6>")
	)
	(segment
		(start 271.254474 -266.145518)
		(end 271.417288 -265.982704)
		(width 0.14478)
		(layer "In11.Cu")
		(net "M_F_CPU0_SB_CA<6>")
	)
	(segment
		(start 275.288502 -266.15009)
		(end 275.678392 -265.7602)
		(width 0.14478)
		(layer "In11.Cu")
		(net "M_F_CPU0_SB_CA<6>")
	)
	(segment
		(start 270.467582 -265.365738)
		(end 270.698214 -265.365738)
		(width 0.14478)
		(layer "In11.Cu")
		(net "M_F_CPU0_SB_CA<6>")
	)
	(segment
		(start 271.973548 -265.982704)
		(end 272.136362 -266.145518)
		(width 0.14478)
		(layer "In11.Cu")
		(net "M_F_CPU0_SB_CA<6>")
	)
	(segment
		(start 330.22413 -264.688574)
		(end 330.232512 -264.6934)
		(width 0.0889)
		(layer "In11.Cu")
		(net "M_F_CPU0_SB_CA<6>")
	)
	(segment
		(start 329.284076 -264.688574)
		(end 329.292458 -264.6934)
		(width 0.0889)
		(layer "In11.Cu")
		(net "M_F_CPU0_SB_CA<6>")
	)
	(segment
		(start 275.678392 -265.7602)
		(end 308.16042 -265.7602)
		(width 0.14478)
		(layer "In11.Cu")
		(net "M_F_CPU0_SB_CA<6>")
	)
	(segment
		(start 271.810734 -265.365738)
		(end 271.973548 -265.528552)
		(width 0.14478)
		(layer "In11.Cu")
		(net "M_F_CPU0_SB_CA<6>")
	)
	(segment
		(start 271.417288 -265.982704)
		(end 271.417288 -265.528552)
		(width 0.14478)
		(layer "In11.Cu")
		(net "M_F_CPU0_SB_CA<6>")
	)
	(segment
		(start 324.199504 -264.61974)
		(end 324.515734 -264.30351)
		(width 0.0889)
		(layer "In11.Cu")
		(net "M_F_CPU0_SB_CA<6>")
	)
	(segment
		(start 272.366994 -266.145518)
		(end 272.752312 -265.7602)
		(width 0.14478)
		(layer "In11.Cu")
		(net "M_F_CPU0_SB_CA<6>")
	)
	(segment
		(start 327.387204 -264.677906)
		(end 327.405238 -264.688574)
		(width 0.0889)
		(layer "In11.Cu")
		(net "M_F_CPU0_SB_CA<6>")
	)
	(segment
		(start 325.708518 -264.612374)
		(end 326.182736 -264.612374)
		(width 0.0889)
		(layer "In11.Cu")
		(net "M_F_CPU0_SB_CA<6>")
	)
	(segment
		(start 327.765156 -264.696194)
		(end 327.778872 -264.68832)
		(width 0.0889)
		(layer "In11.Cu")
		(net "M_F_CPU0_SB_CA<6>")
	)
	(arc
		(start 327.79081 -264.681462)
		(mid 328.068344 -264.612481)
		(end 328.344022 -264.688574)
		(width 0.0889)
		(layer "In11.Cu")
		(net "M_F_CPU0_SB_CA<6>")
	)
	(arc
		(start 329.658218 -264.688574)
		(mid 329.941174 -264.612397)
		(end 330.22413 -264.688574)
		(width 0.0889)
		(layer "In11.Cu")
		(net "M_F_CPU0_SB_CA<6>")
	)
	(arc
		(start 329.292458 -264.6934)
		(mid 329.475966 -264.738894)
		(end 329.658218 -264.688574)
		(width 0.0889)
		(layer "In11.Cu")
		(net "M_F_CPU0_SB_CA<6>")
	)
	(arc
		(start 326.21093 -264.613136)
		(mid 326.342284 -264.63561)
		(end 326.464676 -264.68832)
		(width 0.0889)
		(layer "In11.Cu")
		(net "M_F_CPU0_SB_CA<6>")
	)
	(arc
		(start 328.718164 -264.688574)
		(mid 329.00112 -264.612397)
		(end 329.284076 -264.688574)
		(width 0.0889)
		(layer "In11.Cu")
		(net "M_F_CPU0_SB_CA<6>")
	)
	(arc
		(start 332.103984 -264.688574)
		(mid 332.260422 -264.737545)
		(end 332.422754 -264.714736)
		(width 0.0889)
		(layer "In11.Cu")
		(net "M_F_CPU0_SB_CA<6>")
	)
	(arc
		(start 331.164184 -264.688574)
		(mid 331.351128 -264.738829)
		(end 331.538072 -264.688574)
		(width 0.0889)
		(layer "In11.Cu")
		(net "M_F_CPU0_SB_CA<6>")
	)
	(arc
		(start 326.838564 -264.688574)
		(mid 327.111508 -264.611994)
		(end 327.387204 -264.677906)
		(width 0.0889)
		(layer "In11.Cu")
		(net "M_F_CPU0_SB_CA<6>")
	)
	(arc
		(start 331.538072 -264.688574)
		(mid 331.821028 -264.612397)
		(end 332.103984 -264.688574)
		(width 0.0889)
		(layer "In11.Cu")
		(net "M_F_CPU0_SB_CA<6>")
	)
	(arc
		(start 326.484742 -264.69975)
		(mid 326.663074 -264.738847)
		(end 326.838564 -264.688574)
		(width 0.0889)
		(layer "In11.Cu")
		(net "M_F_CPU0_SB_CA<6>")
	)
	(arc
		(start 330.598272 -264.688574)
		(mid 330.881228 -264.612397)
		(end 331.164184 -264.688574)
		(width 0.0889)
		(layer "In11.Cu")
		(net "M_F_CPU0_SB_CA<6>")
	)
	(arc
		(start 328.344022 -264.688574)
		(mid 328.526273 -264.738924)
		(end 328.709782 -264.6934)
		(width 0.0889)
		(layer "In11.Cu")
		(net "M_F_CPU0_SB_CA<6>")
	)
	(arc
		(start 327.405238 -264.688574)
		(mid 327.584225 -264.738744)
		(end 327.765156 -264.696194)
		(width 0.0889)
		(layer "In11.Cu")
		(net "M_F_CPU0_SB_CA<6>")
	)
	(arc
		(start 330.232512 -264.6934)
		(mid 330.41602 -264.738894)
		(end 330.598272 -264.688574)
		(width 0.0889)
		(layer "In11.Cu")
		(net "M_F_CPU0_SB_CA<6>")
	)
	(arc
		(start 326.182736 -264.612374)
		(mid 326.196838 -264.612576)
		(end 326.21093 -264.613136)
		(width 0.0889)
		(layer "In11.Cu")
		(net "M_F_CPU0_SB_CA<6>")
	)
	(segment
		(start 334.637888 -264.100056)
		(end 334.171036 -264.365994)
		(width 0.10668)
		(layer "F.Cu")
		(net "M_F_CPU0_SB_CA<5>")
	)
	(segment
		(start 333.044038 -264.043414)
		(end 333.05242 -264.038588)
		(width 0.0889)
		(layer "In11.Cu")
		(net "M_F_CPU0_SB_CA<5>")
	)
	(segment
		(start 265.973052 -264.910062)
		(end 308.099968 -264.910062)
		(width 0.14478)
		(layer "In11.Cu")
		(net "M_F_CPU0_SB_CA<5>")
	)
	(segment
		(start 324.32625 -264.00887)
		(end 327.584054 -264.013442)
		(width 0.0889)
		(layer "In11.Cu")
		(net "M_F_CPU0_SB_CA<5>")
	)
	(segment
		(start 328.709782 -264.038588)
		(end 328.718164 -264.043414)
		(width 0.0889)
		(layer "In11.Cu")
		(net "M_F_CPU0_SB_CA<5>")
	)
	(segment
		(start 333.9211 -264.075164)
		(end 334.017112 -264.100564)
		(width 0.0889)
		(layer "In11.Cu")
		(net "M_F_CPU0_SB_CA<5>")
	)
	(segment
		(start 332.469744 -264.038588)
		(end 332.478126 -264.043414)
		(width 0.0889)
		(layer "In11.Cu")
		(net "M_F_CPU0_SB_CA<5>")
	)
	(segment
		(start 265.54811 -265.335004)
		(end 265.973052 -264.910062)
		(width 0.14478)
		(layer "In11.Cu")
		(net "M_F_CPU0_SB_CA<5>")
	)
	(segment
		(start 324.156324 -264.131806)
		(end 324.24624 -264.04189)
		(width 0.0889)
		(layer "In11.Cu")
		(net "M_F_CPU0_SB_CA<5>")
	)
	(segment
		(start 329.284076 -264.043414)
		(end 329.292458 -264.038588)
		(width 0.0889)
		(layer "In11.Cu")
		(net "M_F_CPU0_SB_CA<5>")
	)
	(segment
		(start 308.099968 -264.910062)
		(end 308.84495 -264.16508)
		(width 0.14478)
		(layer "In11.Cu")
		(net "M_F_CPU0_SB_CA<5>")
	)
	(segment
		(start 328.333608 -264.04951)
		(end 328.344022 -264.043414)
		(width 0.0889)
		(layer "In11.Cu")
		(net "M_F_CPU0_SB_CA<5>")
	)
	(segment
		(start 323.944234 -264.16508)
		(end 324.07606 -264.16508)
		(width 0.0889)
		(layer "In11.Cu")
		(net "M_F_CPU0_SB_CA<5>")
	)
	(segment
		(start 334.017112 -264.100564)
		(end 334.171036 -264.365994)
		(width 0.0889)
		(layer "In11.Cu")
		(net "M_F_CPU0_SB_CA<5>")
	)
	(segment
		(start 308.84495 -264.16508)
		(end 323.944234 -264.16508)
		(width 0.14478)
		(layer "In11.Cu")
		(net "M_F_CPU0_SB_CA<5>")
	)
	(segment
		(start 331.52969 -264.038588)
		(end 331.538072 -264.043414)
		(width 0.0889)
		(layer "In11.Cu")
		(net "M_F_CPU0_SB_CA<5>")
	)
	(arc
		(start 328.344022 -264.043414)
		(mid 328.526273 -263.993064)
		(end 328.709782 -264.038588)
		(width 0.0889)
		(layer "In11.Cu")
		(net "M_F_CPU0_SB_CA<5>")
	)
	(arc
		(start 328.718164 -264.043414)
		(mid 329.00112 -264.119591)
		(end 329.284076 -264.043414)
		(width 0.0889)
		(layer "In11.Cu")
		(net "M_F_CPU0_SB_CA<5>")
	)
	(arc
		(start 327.822052 -264.066782)
		(mid 328.079895 -264.119506)
		(end 328.333608 -264.04951)
		(width 0.0889)
		(layer "In11.Cu")
		(net "M_F_CPU0_SB_CA<5>")
	)
	(arc
		(start 329.292458 -264.038588)
		(mid 329.475966 -263.993094)
		(end 329.658218 -264.043414)
		(width 0.0889)
		(layer "In11.Cu")
		(net "M_F_CPU0_SB_CA<5>")
	)
	(arc
		(start 324.07606 -264.16508)
		(mid 324.119495 -264.156422)
		(end 324.156324 -264.131806)
		(width 0.0889)
		(layer "In11.Cu")
		(net "M_F_CPU0_SB_CA<5>")
	)
	(arc
		(start 332.478126 -264.043414)
		(mid 332.761082 -264.119591)
		(end 333.044038 -264.043414)
		(width 0.0889)
		(layer "In11.Cu")
		(net "M_F_CPU0_SB_CA<5>")
	)
	(arc
		(start 330.22413 -264.043414)
		(mid 330.411074 -263.993159)
		(end 330.598018 -264.043414)
		(width 0.0889)
		(layer "In11.Cu")
		(net "M_F_CPU0_SB_CA<5>")
	)
	(arc
		(start 332.103984 -264.043414)
		(mid 332.286235 -263.993064)
		(end 332.469744 -264.038588)
		(width 0.0889)
		(layer "In11.Cu")
		(net "M_F_CPU0_SB_CA<5>")
	)
	(arc
		(start 327.584054 -264.013442)
		(mid 327.705978 -264.027069)
		(end 327.822052 -264.066782)
		(width 0.0889)
		(layer "In11.Cu")
		(net "M_F_CPU0_SB_CA<5>")
	)
	(arc
		(start 333.05242 -264.038588)
		(mid 333.235928 -263.993094)
		(end 333.41818 -264.043414)
		(width 0.0889)
		(layer "In11.Cu")
		(net "M_F_CPU0_SB_CA<5>")
	)
	(arc
		(start 329.658218 -264.043414)
		(mid 329.941174 -264.119591)
		(end 330.22413 -264.043414)
		(width 0.0889)
		(layer "In11.Cu")
		(net "M_F_CPU0_SB_CA<5>")
	)
	(arc
		(start 324.24624 -264.04189)
		(mid 324.282964 -264.017445)
		(end 324.32625 -264.00887)
		(width 0.0889)
		(layer "In11.Cu")
		(net "M_F_CPU0_SB_CA<5>")
	)
	(arc
		(start 331.16393 -264.043414)
		(mid 331.346181 -263.993064)
		(end 331.52969 -264.038588)
		(width 0.0889)
		(layer "In11.Cu")
		(net "M_F_CPU0_SB_CA<5>")
	)
	(arc
		(start 333.41818 -264.043414)
		(mid 333.665893 -264.118634)
		(end 333.9211 -264.075164)
		(width 0.0889)
		(layer "In11.Cu")
		(net "M_F_CPU0_SB_CA<5>")
	)
	(arc
		(start 331.538072 -264.043414)
		(mid 331.821028 -264.119591)
		(end 332.103984 -264.043414)
		(width 0.0889)
		(layer "In11.Cu")
		(net "M_F_CPU0_SB_CA<5>")
	)
	(arc
		(start 330.598018 -264.043414)
		(mid 330.880974 -264.119591)
		(end 331.16393 -264.043414)
		(width 0.0889)
		(layer "In11.Cu")
		(net "M_F_CPU0_SB_CA<5>")
	)
	(segment
		(start 334.167988 -263.29005)
		(end 333.701136 -263.555988)
		(width 0.10668)
		(layer "F.Cu")
		(net "M_F_CPU0_SB_CA<4>")
	)
	(segment
		(start 331.634084 -263.878568)
		(end 331.642466 -263.883394)
		(width 0.0889)
		(layer "In11.Cu")
		(net "M_F_CPU0_SB_CA<4>")
	)
	(segment
		(start 271.017492 -264.454894)
		(end 271.248124 -264.454894)
		(width 0.14478)
		(layer "In11.Cu")
		(net "M_F_CPU0_SB_CA<4>")
	)
	(segment
		(start 270.691864 -263.672066)
		(end 270.854678 -263.83488)
		(width 0.14478)
		(layer "In11.Cu")
		(net "M_F_CPU0_SB_CA<4>")
	)
	(segment
		(start 274.123658 -264.44829)
		(end 274.286472 -264.285476)
		(width 0.14478)
		(layer "In11.Cu")
		(net "M_F_CPU0_SB_CA<4>")
	)
	(segment
		(start 275.068284 -264.059924)
		(end 308.160166 -264.059924)
		(width 0.14478)
		(layer "In11.Cu")
		(net "M_F_CPU0_SB_CA<4>")
	)
	(segment
		(start 323.892164 -263.71042)
		(end 327.250298 -263.71042)
		(width 0.0889)
		(layer "In11.Cu")
		(net "M_F_CPU0_SB_CA<4>")
	)
	(segment
		(start 270.854678 -263.83488)
		(end 270.854678 -264.29208)
		(width 0.14478)
		(layer "In11.Cu")
		(net "M_F_CPU0_SB_CA<4>")
	)
	(segment
		(start 269.648178 -264.48512)
		(end 270.461232 -263.672066)
		(width 0.14478)
		(layer "In11.Cu")
		(net "M_F_CPU0_SB_CA<4>")
	)
	(segment
		(start 333.832708 -263.90473)
		(end 333.85506 -263.821418)
		(width 0.0889)
		(layer "In11.Cu")
		(net "M_F_CPU0_SB_CA<4>")
	)
	(segment
		(start 333.85506 -263.821418)
		(end 333.701136 -263.555988)
		(width 0.0889)
		(layer "In11.Cu")
		(net "M_F_CPU0_SB_CA<4>")
	)
	(segment
		(start 271.967198 -264.29208)
		(end 272.130012 -264.454894)
		(width 0.14478)
		(layer "In11.Cu")
		(net "M_F_CPU0_SB_CA<4>")
	)
	(segment
		(start 271.967198 -263.83488)
		(end 271.967198 -264.29208)
		(width 0.14478)
		(layer "In11.Cu")
		(net "M_F_CPU0_SB_CA<4>")
	)
	(segment
		(start 308.50967 -263.71042)
		(end 323.892164 -263.71042)
		(width 0.14478)
		(layer "In11.Cu")
		(net "M_F_CPU0_SB_CA<4>")
	)
	(segment
		(start 273.893026 -264.44829)
		(end 274.123658 -264.44829)
		(width 0.14478)
		(layer "In11.Cu")
		(net "M_F_CPU0_SB_CA<4>")
	)
	(segment
		(start 274.286472 -263.834372)
		(end 274.449286 -263.671558)
		(width 0.14478)
		(layer "In11.Cu")
		(net "M_F_CPU0_SB_CA<4>")
	)
	(segment
		(start 271.410938 -263.83488)
		(end 271.573752 -263.672066)
		(width 0.14478)
		(layer "In11.Cu")
		(net "M_F_CPU0_SB_CA<4>")
	)
	(segment
		(start 272.360644 -264.454894)
		(end 272.755614 -264.059924)
		(width 0.14478)
		(layer "In11.Cu")
		(net "M_F_CPU0_SB_CA<4>")
	)
	(segment
		(start 330.119736 -263.883394)
		(end 330.128118 -263.878568)
		(width 0.0889)
		(layer "In11.Cu")
		(net "M_F_CPU0_SB_CA<4>")
	)
	(segment
		(start 270.854678 -264.29208)
		(end 271.017492 -264.454894)
		(width 0.14478)
		(layer "In11.Cu")
		(net "M_F_CPU0_SB_CA<4>")
	)
	(segment
		(start 270.461232 -263.672066)
		(end 270.691864 -263.672066)
		(width 0.14478)
		(layer "In11.Cu")
		(net "M_F_CPU0_SB_CA<4>")
	)
	(segment
		(start 272.130012 -264.454894)
		(end 272.360644 -264.454894)
		(width 0.14478)
		(layer "In11.Cu")
		(net "M_F_CPU0_SB_CA<4>")
	)
	(segment
		(start 271.410938 -264.29208)
		(end 271.410938 -263.83488)
		(width 0.14478)
		(layer "In11.Cu")
		(net "M_F_CPU0_SB_CA<4>")
	)
	(segment
		(start 272.755614 -264.059924)
		(end 273.50466 -264.059924)
		(width 0.14478)
		(layer "In11.Cu")
		(net "M_F_CPU0_SB_CA<4>")
	)
	(segment
		(start 330.69403 -263.878568)
		(end 330.702412 -263.883394)
		(width 0.0889)
		(layer "In11.Cu")
		(net "M_F_CPU0_SB_CA<4>")
	)
	(segment
		(start 308.160166 -264.059924)
		(end 308.50967 -263.71042)
		(width 0.14478)
		(layer "In11.Cu")
		(net "M_F_CPU0_SB_CA<4>")
	)
	(segment
		(start 274.449286 -263.671558)
		(end 274.679918 -263.671558)
		(width 0.14478)
		(layer "In11.Cu")
		(net "M_F_CPU0_SB_CA<4>")
	)
	(segment
		(start 274.286472 -264.285476)
		(end 274.286472 -263.834372)
		(width 0.14478)
		(layer "In11.Cu")
		(net "M_F_CPU0_SB_CA<4>")
	)
	(segment
		(start 271.248124 -264.454894)
		(end 271.410938 -264.29208)
		(width 0.14478)
		(layer "In11.Cu")
		(net "M_F_CPU0_SB_CA<4>")
	)
	(segment
		(start 271.573752 -263.672066)
		(end 271.804384 -263.672066)
		(width 0.14478)
		(layer "In11.Cu")
		(net "M_F_CPU0_SB_CA<4>")
	)
	(segment
		(start 273.50466 -264.059924)
		(end 273.893026 -264.44829)
		(width 0.14478)
		(layer "In11.Cu")
		(net "M_F_CPU0_SB_CA<4>")
	)
	(segment
		(start 274.679918 -263.671558)
		(end 275.068284 -264.059924)
		(width 0.14478)
		(layer "In11.Cu")
		(net "M_F_CPU0_SB_CA<4>")
	)
	(segment
		(start 271.804384 -263.672066)
		(end 271.967198 -263.83488)
		(width 0.14478)
		(layer "In11.Cu")
		(net "M_F_CPU0_SB_CA<4>")
	)
	(arc
		(start 327.250298 -263.71042)
		(mid 327.573214 -263.753203)
		(end 327.873868 -263.878568)
		(width 0.0889)
		(layer "In11.Cu")
		(net "M_F_CPU0_SB_CA<4>")
	)
	(arc
		(start 332.574138 -263.878568)
		(mid 332.761082 -263.928823)
		(end 332.948026 -263.878568)
		(width 0.0889)
		(layer "In11.Cu")
		(net "M_F_CPU0_SB_CA<4>")
	)
	(arc
		(start 329.188064 -263.878568)
		(mid 329.47102 -263.802391)
		(end 329.753976 -263.878568)
		(width 0.0889)
		(layer "In11.Cu")
		(net "M_F_CPU0_SB_CA<4>")
	)
	(arc
		(start 332.008226 -263.878568)
		(mid 332.291182 -263.802391)
		(end 332.574138 -263.878568)
		(width 0.0889)
		(layer "In11.Cu")
		(net "M_F_CPU0_SB_CA<4>")
	)
	(arc
		(start 329.753976 -263.878568)
		(mid 329.936227 -263.928918)
		(end 330.119736 -263.883394)
		(width 0.0889)
		(layer "In11.Cu")
		(net "M_F_CPU0_SB_CA<4>")
	)
	(arc
		(start 332.948026 -263.878568)
		(mid 333.230982 -263.802391)
		(end 333.513938 -263.878568)
		(width 0.0889)
		(layer "In11.Cu")
		(net "M_F_CPU0_SB_CA<4>")
	)
	(arc
		(start 328.814176 -263.878568)
		(mid 329.00112 -263.928823)
		(end 329.188064 -263.878568)
		(width 0.0889)
		(layer "In11.Cu")
		(net "M_F_CPU0_SB_CA<4>")
	)
	(arc
		(start 330.128118 -263.878568)
		(mid 330.411074 -263.802391)
		(end 330.69403 -263.878568)
		(width 0.0889)
		(layer "In11.Cu")
		(net "M_F_CPU0_SB_CA<4>")
	)
	(arc
		(start 331.642466 -263.883394)
		(mid 331.825974 -263.928888)
		(end 332.008226 -263.878568)
		(width 0.0889)
		(layer "In11.Cu")
		(net "M_F_CPU0_SB_CA<4>")
	)
	(arc
		(start 327.873868 -263.878568)
		(mid 328.061066 -263.92895)
		(end 328.248264 -263.878568)
		(width 0.0889)
		(layer "In11.Cu")
		(net "M_F_CPU0_SB_CA<4>")
	)
	(arc
		(start 333.513938 -263.878568)
		(mid 333.670376 -263.927539)
		(end 333.832708 -263.90473)
		(width 0.0889)
		(layer "In11.Cu")
		(net "M_F_CPU0_SB_CA<4>")
	)
	(arc
		(start 331.068172 -263.878568)
		(mid 331.351128 -263.802391)
		(end 331.634084 -263.878568)
		(width 0.0889)
		(layer "In11.Cu")
		(net "M_F_CPU0_SB_CA<4>")
	)
	(arc
		(start 330.702412 -263.883394)
		(mid 330.88592 -263.928888)
		(end 331.068172 -263.878568)
		(width 0.0889)
		(layer "In11.Cu")
		(net "M_F_CPU0_SB_CA<4>")
	)
	(arc
		(start 328.248264 -263.878568)
		(mid 328.53122 -263.802391)
		(end 328.814176 -263.878568)
		(width 0.0889)
		(layer "In11.Cu")
		(net "M_F_CPU0_SB_CA<4>")
	)
	(segment
		(start 333.227934 -263.29005)
		(end 332.761082 -263.555988)
		(width 0.10668)
		(layer "F.Cu")
		(net "M_F_CPU0_SB_CA<3>")
	)
	(segment
		(start 325.865744 -262.90143)
		(end 326.273922 -263.309608)
		(width 0.0889)
		(layer "In11.Cu")
		(net "M_F_CPU0_SB_CA<3>")
	)
	(segment
		(start 330.69403 -263.233408)
		(end 330.702412 -263.228582)
		(width 0.0889)
		(layer "In11.Cu")
		(net "M_F_CPU0_SB_CA<3>")
	)
	(segment
		(start 265.54811 -263.634982)
		(end 265.973052 -263.21004)
		(width 0.14478)
		(layer "In11.Cu")
		(net "M_F_CPU0_SB_CA<3>")
	)
	(segment
		(start 327.874376 -263.233662)
		(end 327.890632 -263.224264)
		(width 0.0889)
		(layer "In11.Cu")
		(net "M_F_CPU0_SB_CA<3>")
	)
	(segment
		(start 324.458584 -263.21004)
		(end 324.767194 -262.90143)
		(width 0.0889)
		(layer "In11.Cu")
		(net "M_F_CPU0_SB_CA<3>")
	)
	(segment
		(start 331.634084 -263.233408)
		(end 331.642466 -263.228582)
		(width 0.0889)
		(layer "In11.Cu")
		(net "M_F_CPU0_SB_CA<3>")
	)
	(segment
		(start 332.607158 -263.290558)
		(end 332.761082 -263.555988)
		(width 0.0889)
		(layer "In11.Cu")
		(net "M_F_CPU0_SB_CA<3>")
	)
	(segment
		(start 330.119736 -263.228582)
		(end 330.128118 -263.233408)
		(width 0.0889)
		(layer "In11.Cu")
		(net "M_F_CPU0_SB_CA<3>")
	)
	(segment
		(start 323.918834 -263.21004)
		(end 324.458584 -263.21004)
		(width 0.0889)
		(layer "In11.Cu")
		(net "M_F_CPU0_SB_CA<3>")
	)
	(segment
		(start 265.973052 -263.21004)
		(end 323.918834 -263.21004)
		(width 0.14478)
		(layer "In11.Cu")
		(net "M_F_CPU0_SB_CA<3>")
	)
	(segment
		(start 326.273922 -263.309608)
		(end 327.591928 -263.309608)
		(width 0.0889)
		(layer "In11.Cu")
		(net "M_F_CPU0_SB_CA<3>")
	)
	(segment
		(start 332.511146 -263.265158)
		(end 332.607158 -263.290558)
		(width 0.0889)
		(layer "In11.Cu")
		(net "M_F_CPU0_SB_CA<3>")
	)
	(segment
		(start 324.767194 -262.90143)
		(end 325.865744 -262.90143)
		(width 0.0889)
		(layer "In11.Cu")
		(net "M_F_CPU0_SB_CA<3>")
	)
	(arc
		(start 330.128118 -263.233408)
		(mid 330.411074 -263.309585)
		(end 330.69403 -263.233408)
		(width 0.0889)
		(layer "In11.Cu")
		(net "M_F_CPU0_SB_CA<3>")
	)
	(arc
		(start 331.068172 -263.233408)
		(mid 331.351128 -263.309585)
		(end 331.634084 -263.233408)
		(width 0.0889)
		(layer "In11.Cu")
		(net "M_F_CPU0_SB_CA<3>")
	)
	(arc
		(start 329.188064 -263.233408)
		(mid 329.47102 -263.309585)
		(end 329.753976 -263.233408)
		(width 0.0889)
		(layer "In11.Cu")
		(net "M_F_CPU0_SB_CA<3>")
	)
	(arc
		(start 327.591928 -263.309608)
		(mid 327.738176 -263.290303)
		(end 327.874376 -263.233662)
		(width 0.0889)
		(layer "In11.Cu")
		(net "M_F_CPU0_SB_CA<3>")
	)
	(arc
		(start 329.753976 -263.233408)
		(mid 329.936227 -263.183058)
		(end 330.119736 -263.228582)
		(width 0.0889)
		(layer "In11.Cu")
		(net "M_F_CPU0_SB_CA<3>")
	)
	(arc
		(start 330.702412 -263.228582)
		(mid 330.88592 -263.183088)
		(end 331.068172 -263.233408)
		(width 0.0889)
		(layer "In11.Cu")
		(net "M_F_CPU0_SB_CA<3>")
	)
	(arc
		(start 328.248264 -263.233408)
		(mid 328.53122 -263.309585)
		(end 328.814176 -263.233408)
		(width 0.0889)
		(layer "In11.Cu")
		(net "M_F_CPU0_SB_CA<3>")
	)
	(arc
		(start 332.008226 -263.233408)
		(mid 332.255939 -263.308628)
		(end 332.511146 -263.265158)
		(width 0.0889)
		(layer "In11.Cu")
		(net "M_F_CPU0_SB_CA<3>")
	)
	(arc
		(start 331.642466 -263.228582)
		(mid 331.825974 -263.183088)
		(end 332.008226 -263.233408)
		(width 0.0889)
		(layer "In11.Cu")
		(net "M_F_CPU0_SB_CA<3>")
	)
	(arc
		(start 327.890632 -263.224264)
		(mid 328.070614 -263.183164)
		(end 328.248264 -263.233408)
		(width 0.0889)
		(layer "In11.Cu")
		(net "M_F_CPU0_SB_CA<3>")
	)
	(arc
		(start 328.814176 -263.233408)
		(mid 329.00112 -263.183153)
		(end 329.188064 -263.233408)
		(width 0.0889)
		(layer "In11.Cu")
		(net "M_F_CPU0_SB_CA<3>")
	)
	(segment
		(start 332.758034 -262.480044)
		(end 332.291182 -262.745982)
		(width 0.10668)
		(layer "F.Cu")
		(net "M_F_CPU0_SB_CA<2>")
	)
	(segment
		(start 275.509228 -261.985506)
		(end 275.73986 -261.985506)
		(width 0.14478)
		(layer "In11.Cu")
		(net "M_F_CPU0_SB_CA<2>")
	)
	(segment
		(start 275.902674 -262.586216)
		(end 276.065488 -262.74903)
		(width 0.14478)
		(layer "In11.Cu")
		(net "M_F_CPU0_SB_CA<2>")
	)
	(segment
		(start 323.92112 -262.767572)
		(end 324.291198 -262.767572)
		(width 0.0889)
		(layer "In11.Cu")
		(net "M_F_CPU0_SB_CA<2>")
	)
	(segment
		(start 270.84274 -262.591804)
		(end 271.005554 -262.754618)
		(width 0.14478)
		(layer "In11.Cu")
		(net "M_F_CPU0_SB_CA<2>")
	)
	(segment
		(start 331.52969 -263.073388)
		(end 331.538072 -263.068562)
		(width 0.0889)
		(layer "In11.Cu")
		(net "M_F_CPU0_SB_CA<2>")
	)
	(segment
		(start 274.952968 -262.74903)
		(end 275.1836 -262.74903)
		(width 0.14478)
		(layer "In11.Cu")
		(net "M_F_CPU0_SB_CA<2>")
	)
	(segment
		(start 276.29612 -262.74903)
		(end 276.677882 -262.367268)
		(width 0.14478)
		(layer "In11.Cu")
		(net "M_F_CPU0_SB_CA<2>")
	)
	(segment
		(start 271.95526 -262.146796)
		(end 271.95526 -262.591804)
		(width 0.14478)
		(layer "In11.Cu")
		(net "M_F_CPU0_SB_CA<2>")
	)
	(segment
		(start 274.790154 -262.586216)
		(end 274.952968 -262.74903)
		(width 0.14478)
		(layer "In11.Cu")
		(net "M_F_CPU0_SB_CA<2>")
	)
	(segment
		(start 271.005554 -262.754618)
		(end 271.236186 -262.754618)
		(width 0.14478)
		(layer "In11.Cu")
		(net "M_F_CPU0_SB_CA<2>")
	)
	(segment
		(start 274.790154 -262.14832)
		(end 274.790154 -262.586216)
		(width 0.14478)
		(layer "In11.Cu")
		(net "M_F_CPU0_SB_CA<2>")
	)
	(segment
		(start 275.73986 -261.985506)
		(end 275.902674 -262.14832)
		(width 0.14478)
		(layer "In11.Cu")
		(net "M_F_CPU0_SB_CA<2>")
	)
	(segment
		(start 271.399 -262.146796)
		(end 271.561814 -261.983982)
		(width 0.14478)
		(layer "In11.Cu")
		(net "M_F_CPU0_SB_CA<2>")
	)
	(segment
		(start 271.95526 -262.591804)
		(end 272.118074 -262.754618)
		(width 0.14478)
		(layer "In11.Cu")
		(net "M_F_CPU0_SB_CA<2>")
	)
	(segment
		(start 324.458838 -262.599932)
		(end 325.862442 -262.599932)
		(width 0.0889)
		(layer "In11.Cu")
		(net "M_F_CPU0_SB_CA<2>")
	)
	(segment
		(start 274.233894 -262.14832)
		(end 274.396708 -261.985506)
		(width 0.14478)
		(layer "In11.Cu")
		(net "M_F_CPU0_SB_CA<2>")
	)
	(segment
		(start 308.7624 -262.367268)
		(end 309.150258 -262.755126)
		(width 0.14478)
		(layer "In11.Cu")
		(net "M_F_CPU0_SB_CA<2>")
	)
	(segment
		(start 274.07108 -262.74903)
		(end 274.233894 -262.586216)
		(width 0.14478)
		(layer "In11.Cu")
		(net "M_F_CPU0_SB_CA<2>")
	)
	(segment
		(start 276.065488 -262.74903)
		(end 276.29612 -262.74903)
		(width 0.14478)
		(layer "In11.Cu")
		(net "M_F_CPU0_SB_CA<2>")
	)
	(segment
		(start 325.862442 -262.599932)
		(end 326.334628 -263.072118)
		(width 0.0889)
		(layer "In11.Cu")
		(net "M_F_CPU0_SB_CA<2>")
	)
	(segment
		(start 271.236186 -262.754618)
		(end 271.399 -262.591804)
		(width 0.14478)
		(layer "In11.Cu")
		(net "M_F_CPU0_SB_CA<2>")
	)
	(segment
		(start 270.84274 -262.146796)
		(end 270.84274 -262.591804)
		(width 0.14478)
		(layer "In11.Cu")
		(net "M_F_CPU0_SB_CA<2>")
	)
	(segment
		(start 323.908674 -262.755126)
		(end 323.92112 -262.767572)
		(width 0.0889)
		(layer "In11.Cu")
		(net "M_F_CPU0_SB_CA<2>")
	)
	(segment
		(start 269.648178 -262.785098)
		(end 270.449294 -261.983982)
		(width 0.14478)
		(layer "In11.Cu")
		(net "M_F_CPU0_SB_CA<2>")
	)
	(segment
		(start 270.449294 -261.983982)
		(end 270.679926 -261.983982)
		(width 0.14478)
		(layer "In11.Cu")
		(net "M_F_CPU0_SB_CA<2>")
	)
	(segment
		(start 329.284076 -263.068562)
		(end 329.292458 -263.073388)
		(width 0.0889)
		(layer "In11.Cu")
		(net "M_F_CPU0_SB_CA<2>")
	)
	(segment
		(start 309.150258 -262.755126)
		(end 323.908674 -262.755126)
		(width 0.14478)
		(layer "In11.Cu")
		(net "M_F_CPU0_SB_CA<2>")
	)
	(segment
		(start 275.1836 -262.74903)
		(end 275.346414 -262.586216)
		(width 0.14478)
		(layer "In11.Cu")
		(net "M_F_CPU0_SB_CA<2>")
	)
	(segment
		(start 275.902674 -262.14832)
		(end 275.902674 -262.586216)
		(width 0.14478)
		(layer "In11.Cu")
		(net "M_F_CPU0_SB_CA<2>")
	)
	(segment
		(start 271.792446 -261.983982)
		(end 271.95526 -262.146796)
		(width 0.14478)
		(layer "In11.Cu")
		(net "M_F_CPU0_SB_CA<2>")
	)
	(segment
		(start 271.561814 -261.983982)
		(end 271.792446 -261.983982)
		(width 0.14478)
		(layer "In11.Cu")
		(net "M_F_CPU0_SB_CA<2>")
	)
	(segment
		(start 324.291198 -262.767572)
		(end 324.458838 -262.599932)
		(width 0.0889)
		(layer "In11.Cu")
		(net "M_F_CPU0_SB_CA<2>")
	)
	(segment
		(start 275.346414 -262.586216)
		(end 275.346414 -262.14832)
		(width 0.14478)
		(layer "In11.Cu")
		(net "M_F_CPU0_SB_CA<2>")
	)
	(segment
		(start 270.679926 -261.983982)
		(end 270.84274 -262.146796)
		(width 0.14478)
		(layer "In11.Cu")
		(net "M_F_CPU0_SB_CA<2>")
	)
	(segment
		(start 272.348706 -262.754618)
		(end 272.736056 -262.367268)
		(width 0.14478)
		(layer "In11.Cu")
		(net "M_F_CPU0_SB_CA<2>")
	)
	(segment
		(start 276.677882 -262.367268)
		(end 308.7624 -262.367268)
		(width 0.14478)
		(layer "In11.Cu")
		(net "M_F_CPU0_SB_CA<2>")
	)
	(segment
		(start 271.399 -262.591804)
		(end 271.399 -262.146796)
		(width 0.14478)
		(layer "In11.Cu")
		(net "M_F_CPU0_SB_CA<2>")
	)
	(segment
		(start 328.709782 -263.073388)
		(end 328.718164 -263.068562)
		(width 0.0889)
		(layer "In11.Cu")
		(net "M_F_CPU0_SB_CA<2>")
	)
	(segment
		(start 274.62734 -261.985506)
		(end 274.790154 -262.14832)
		(width 0.14478)
		(layer "In11.Cu")
		(net "M_F_CPU0_SB_CA<2>")
	)
	(segment
		(start 273.458686 -262.367268)
		(end 273.840448 -262.74903)
		(width 0.14478)
		(layer "In11.Cu")
		(net "M_F_CPU0_SB_CA<2>")
	)
	(segment
		(start 272.118074 -262.754618)
		(end 272.348706 -262.754618)
		(width 0.14478)
		(layer "In11.Cu")
		(net "M_F_CPU0_SB_CA<2>")
	)
	(segment
		(start 273.840448 -262.74903)
		(end 274.07108 -262.74903)
		(width 0.14478)
		(layer "In11.Cu")
		(net "M_F_CPU0_SB_CA<2>")
	)
	(segment
		(start 274.233894 -262.586216)
		(end 274.233894 -262.14832)
		(width 0.14478)
		(layer "In11.Cu")
		(net "M_F_CPU0_SB_CA<2>")
	)
	(segment
		(start 326.414892 -263.105392)
		(end 327.569068 -263.105392)
		(width 0.0889)
		(layer "In11.Cu")
		(net "M_F_CPU0_SB_CA<2>")
	)
	(segment
		(start 332.422754 -263.094724)
		(end 332.445106 -263.011412)
		(width 0.0889)
		(layer "In11.Cu")
		(net "M_F_CPU0_SB_CA<2>")
	)
	(segment
		(start 332.445106 -263.011412)
		(end 332.291182 -262.745982)
		(width 0.0889)
		(layer "In11.Cu")
		(net "M_F_CPU0_SB_CA<2>")
	)
	(segment
		(start 274.396708 -261.985506)
		(end 274.62734 -261.985506)
		(width 0.14478)
		(layer "In11.Cu")
		(net "M_F_CPU0_SB_CA<2>")
	)
	(segment
		(start 272.736056 -262.367268)
		(end 273.458686 -262.367268)
		(width 0.14478)
		(layer "In11.Cu")
		(net "M_F_CPU0_SB_CA<2>")
	)
	(segment
		(start 275.346414 -262.14832)
		(end 275.509228 -261.985506)
		(width 0.14478)
		(layer "In11.Cu")
		(net "M_F_CPU0_SB_CA<2>")
	)
	(arc
		(start 326.334628 -263.072118)
		(mid 326.371439 -263.096778)
		(end 326.414892 -263.105392)
		(width 0.0889)
		(layer "In11.Cu")
		(net "M_F_CPU0_SB_CA<2>")
	)
	(arc
		(start 329.292458 -263.073388)
		(mid 329.475966 -263.118882)
		(end 329.658218 -263.068562)
		(width 0.0889)
		(layer "In11.Cu")
		(net "M_F_CPU0_SB_CA<2>")
	)
	(arc
		(start 331.16393 -263.068562)
		(mid 331.346181 -263.118912)
		(end 331.52969 -263.073388)
		(width 0.0889)
		(layer "In11.Cu")
		(net "M_F_CPU0_SB_CA<2>")
	)
	(arc
		(start 327.81494 -263.04875)
		(mid 328.081946 -262.992697)
		(end 328.344022 -263.068562)
		(width 0.0889)
		(layer "In11.Cu")
		(net "M_F_CPU0_SB_CA<2>")
	)
	(arc
		(start 330.598018 -263.068562)
		(mid 330.880974 -262.992385)
		(end 331.16393 -263.068562)
		(width 0.0889)
		(layer "In11.Cu")
		(net "M_F_CPU0_SB_CA<2>")
	)
	(arc
		(start 330.22413 -263.068562)
		(mid 330.411074 -263.118817)
		(end 330.598018 -263.068562)
		(width 0.0889)
		(layer "In11.Cu")
		(net "M_F_CPU0_SB_CA<2>")
	)
	(arc
		(start 329.658218 -263.068562)
		(mid 329.941174 -262.992385)
		(end 330.22413 -263.068562)
		(width 0.0889)
		(layer "In11.Cu")
		(net "M_F_CPU0_SB_CA<2>")
	)
	(arc
		(start 327.569068 -263.105392)
		(mid 327.695221 -263.091028)
		(end 327.81494 -263.04875)
		(width 0.0889)
		(layer "In11.Cu")
		(net "M_F_CPU0_SB_CA<2>")
	)
	(arc
		(start 332.103984 -263.068562)
		(mid 332.260422 -263.117533)
		(end 332.422754 -263.094724)
		(width 0.0889)
		(layer "In11.Cu")
		(net "M_F_CPU0_SB_CA<2>")
	)
	(arc
		(start 328.718164 -263.068562)
		(mid 329.00112 -262.992385)
		(end 329.284076 -263.068562)
		(width 0.0889)
		(layer "In11.Cu")
		(net "M_F_CPU0_SB_CA<2>")
	)
	(arc
		(start 331.538072 -263.068562)
		(mid 331.821028 -262.992385)
		(end 332.103984 -263.068562)
		(width 0.0889)
		(layer "In11.Cu")
		(net "M_F_CPU0_SB_CA<2>")
	)
	(arc
		(start 328.344022 -263.068562)
		(mid 328.526273 -263.118912)
		(end 328.709782 -263.073388)
		(width 0.0889)
		(layer "In11.Cu")
		(net "M_F_CPU0_SB_CA<2>")
	)
	(segment
		(start 334.637888 -262.480044)
		(end 334.171036 -262.745982)
		(width 0.10668)
		(layer "F.Cu")
		(net "M_F_CPU0_SB_CA<1>")
	)
	(segment
		(start 334.017112 -262.480552)
		(end 334.171036 -262.745982)
		(width 0.0889)
		(layer "In11.Cu")
		(net "M_F_CPU0_SB_CA<1>")
	)
	(segment
		(start 328.333608 -262.429498)
		(end 328.344022 -262.423402)
		(width 0.0889)
		(layer "In11.Cu")
		(net "M_F_CPU0_SB_CA<1>")
	)
	(segment
		(start 323.933312 -262.239252)
		(end 327.096374 -262.239252)
		(width 0.0889)
		(layer "In11.Cu")
		(net "M_F_CPU0_SB_CA<1>")
	)
	(segment
		(start 332.469744 -262.418576)
		(end 332.478126 -262.423402)
		(width 0.0889)
		(layer "In11.Cu")
		(net "M_F_CPU0_SB_CA<1>")
	)
	(segment
		(start 265.973052 -261.510018)
		(end 308.624478 -261.510018)
		(width 0.14478)
		(layer "In11.Cu")
		(net "M_F_CPU0_SB_CA<1>")
	)
	(segment
		(start 328.709782 -262.418576)
		(end 328.718164 -262.423402)
		(width 0.0889)
		(layer "In11.Cu")
		(net "M_F_CPU0_SB_CA<1>")
	)
	(segment
		(start 265.54811 -261.93496)
		(end 265.973052 -261.510018)
		(width 0.14478)
		(layer "In11.Cu")
		(net "M_F_CPU0_SB_CA<1>")
	)
	(segment
		(start 308.624478 -261.510018)
		(end 309.36057 -262.24611)
		(width 0.14478)
		(layer "In11.Cu")
		(net "M_F_CPU0_SB_CA<1>")
	)
	(segment
		(start 309.36057 -262.24611)
		(end 323.926454 -262.24611)
		(width 0.14478)
		(layer "In11.Cu")
		(net "M_F_CPU0_SB_CA<1>")
	)
	(segment
		(start 333.044038 -262.423402)
		(end 333.05242 -262.418576)
		(width 0.0889)
		(layer "In11.Cu")
		(net "M_F_CPU0_SB_CA<1>")
	)
	(segment
		(start 331.52969 -262.418576)
		(end 331.538072 -262.423402)
		(width 0.0889)
		(layer "In11.Cu")
		(net "M_F_CPU0_SB_CA<1>")
	)
	(segment
		(start 329.284076 -262.423402)
		(end 329.292458 -262.418576)
		(width 0.0889)
		(layer "In11.Cu")
		(net "M_F_CPU0_SB_CA<1>")
	)
	(segment
		(start 323.926454 -262.24611)
		(end 323.933312 -262.239252)
		(width 0.0889)
		(layer "In11.Cu")
		(net "M_F_CPU0_SB_CA<1>")
	)
	(segment
		(start 333.9211 -262.455152)
		(end 334.017112 -262.480552)
		(width 0.0889)
		(layer "In11.Cu")
		(net "M_F_CPU0_SB_CA<1>")
	)
	(arc
		(start 331.16393 -262.423402)
		(mid 331.346181 -262.373052)
		(end 331.52969 -262.418576)
		(width 0.0889)
		(layer "In11.Cu")
		(net "M_F_CPU0_SB_CA<1>")
	)
	(arc
		(start 328.344022 -262.423402)
		(mid 328.526273 -262.373052)
		(end 328.709782 -262.418576)
		(width 0.0889)
		(layer "In11.Cu")
		(net "M_F_CPU0_SB_CA<1>")
	)
	(arc
		(start 333.41818 -262.423402)
		(mid 333.665893 -262.498622)
		(end 333.9211 -262.455152)
		(width 0.0889)
		(layer "In11.Cu")
		(net "M_F_CPU0_SB_CA<1>")
	)
	(arc
		(start 330.598018 -262.423402)
		(mid 330.880974 -262.499579)
		(end 331.16393 -262.423402)
		(width 0.0889)
		(layer "In11.Cu")
		(net "M_F_CPU0_SB_CA<1>")
	)
	(arc
		(start 328.718164 -262.423402)
		(mid 329.00112 -262.499579)
		(end 329.284076 -262.423402)
		(width 0.0889)
		(layer "In11.Cu")
		(net "M_F_CPU0_SB_CA<1>")
	)
	(arc
		(start 332.478126 -262.423402)
		(mid 332.761082 -262.499579)
		(end 333.044038 -262.423402)
		(width 0.0889)
		(layer "In11.Cu")
		(net "M_F_CPU0_SB_CA<1>")
	)
	(arc
		(start 332.103984 -262.423402)
		(mid 332.286235 -262.373052)
		(end 332.469744 -262.418576)
		(width 0.0889)
		(layer "In11.Cu")
		(net "M_F_CPU0_SB_CA<1>")
	)
	(arc
		(start 327.096374 -262.239252)
		(mid 327.449336 -262.2861)
		(end 327.777856 -262.423402)
		(width 0.0889)
		(layer "In11.Cu")
		(net "M_F_CPU0_SB_CA<1>")
	)
	(arc
		(start 333.05242 -262.418576)
		(mid 333.235928 -262.373082)
		(end 333.41818 -262.423402)
		(width 0.0889)
		(layer "In11.Cu")
		(net "M_F_CPU0_SB_CA<1>")
	)
	(arc
		(start 329.292458 -262.418576)
		(mid 329.475966 -262.373082)
		(end 329.658218 -262.423402)
		(width 0.0889)
		(layer "In11.Cu")
		(net "M_F_CPU0_SB_CA<1>")
	)
	(arc
		(start 327.777856 -262.423402)
		(mid 328.054923 -262.499673)
		(end 328.333608 -262.429498)
		(width 0.0889)
		(layer "In11.Cu")
		(net "M_F_CPU0_SB_CA<1>")
	)
	(arc
		(start 329.658218 -262.423402)
		(mid 329.941174 -262.499579)
		(end 330.22413 -262.423402)
		(width 0.0889)
		(layer "In11.Cu")
		(net "M_F_CPU0_SB_CA<1>")
	)
	(arc
		(start 331.538072 -262.423402)
		(mid 331.821028 -262.499579)
		(end 332.103984 -262.423402)
		(width 0.0889)
		(layer "In11.Cu")
		(net "M_F_CPU0_SB_CA<1>")
	)
	(arc
		(start 330.22413 -262.423402)
		(mid 330.411074 -262.373147)
		(end 330.598018 -262.423402)
		(width 0.0889)
		(layer "In11.Cu")
		(net "M_F_CPU0_SB_CA<1>")
	)
	(segment
		(start 334.167988 -261.670038)
		(end 333.701136 -261.935976)
		(width 0.10668)
		(layer "F.Cu")
		(net "M_F_CPU0_SB_CA<0>")
	)
	(segment
		(start 273.794982 -260.660134)
		(end 308.587394 -260.660134)
		(width 0.14478)
		(layer "In11.Cu")
		(net "M_F_CPU0_SB_CA<0>")
	)
	(segment
		(start 323.889116 -261.776972)
		(end 324.471538 -261.776972)
		(width 0.0889)
		(layer "In11.Cu")
		(net "M_F_CPU0_SB_CA<0>")
	)
	(segment
		(start 270.706088 -260.257798)
		(end 270.868902 -260.420612)
		(width 0.14478)
		(layer "In11.Cu")
		(net "M_F_CPU0_SB_CA<0>")
	)
	(segment
		(start 333.85506 -262.201406)
		(end 333.701136 -261.935976)
		(width 0.0889)
		(layer "In11.Cu")
		(net "M_F_CPU0_SB_CA<0>")
	)
	(segment
		(start 330.69403 -262.258556)
		(end 330.702412 -262.263382)
		(width 0.0889)
		(layer "In11.Cu")
		(net "M_F_CPU0_SB_CA<0>")
	)
	(segment
		(start 331.634084 -262.258556)
		(end 331.642466 -262.263382)
		(width 0.0889)
		(layer "In11.Cu")
		(net "M_F_CPU0_SB_CA<0>")
	)
	(segment
		(start 273.487388 -261.048246)
		(end 273.650202 -260.885432)
		(width 0.14478)
		(layer "In11.Cu")
		(net "M_F_CPU0_SB_CA<0>")
	)
	(segment
		(start 270.475456 -260.257798)
		(end 270.706088 -260.257798)
		(width 0.14478)
		(layer "In11.Cu")
		(net "M_F_CPU0_SB_CA<0>")
	)
	(segment
		(start 271.981422 -260.885432)
		(end 272.144236 -261.048246)
		(width 0.14478)
		(layer "In11.Cu")
		(net "M_F_CPU0_SB_CA<0>")
	)
	(segment
		(start 323.8881 -261.775956)
		(end 323.889116 -261.776972)
		(width 0.0889)
		(layer "In11.Cu")
		(net "M_F_CPU0_SB_CA<0>")
	)
	(segment
		(start 270.868902 -260.420612)
		(end 270.868902 -260.885432)
		(width 0.14478)
		(layer "In11.Cu")
		(net "M_F_CPU0_SB_CA<0>")
	)
	(segment
		(start 273.650202 -260.804914)
		(end 273.794982 -260.660134)
		(width 0.14478)
		(layer "In11.Cu")
		(net "M_F_CPU0_SB_CA<0>")
	)
	(segment
		(start 309.703216 -261.775956)
		(end 323.8881 -261.775956)
		(width 0.14478)
		(layer "In11.Cu")
		(net "M_F_CPU0_SB_CA<0>")
	)
	(segment
		(start 272.537682 -260.885432)
		(end 272.537682 -260.420612)
		(width 0.14478)
		(layer "In11.Cu")
		(net "M_F_CPU0_SB_CA<0>")
	)
	(segment
		(start 271.425162 -260.420612)
		(end 271.587976 -260.257798)
		(width 0.14478)
		(layer "In11.Cu")
		(net "M_F_CPU0_SB_CA<0>")
	)
	(segment
		(start 271.818608 -260.257798)
		(end 271.981422 -260.420612)
		(width 0.14478)
		(layer "In11.Cu")
		(net "M_F_CPU0_SB_CA<0>")
	)
	(segment
		(start 272.537682 -260.420612)
		(end 272.700496 -260.257798)
		(width 0.14478)
		(layer "In11.Cu")
		(net "M_F_CPU0_SB_CA<0>")
	)
	(segment
		(start 271.587976 -260.257798)
		(end 271.818608 -260.257798)
		(width 0.14478)
		(layer "In11.Cu")
		(net "M_F_CPU0_SB_CA<0>")
	)
	(segment
		(start 273.093942 -260.885432)
		(end 273.256756 -261.048246)
		(width 0.14478)
		(layer "In11.Cu")
		(net "M_F_CPU0_SB_CA<0>")
	)
	(segment
		(start 272.374868 -261.048246)
		(end 272.537682 -260.885432)
		(width 0.14478)
		(layer "In11.Cu")
		(net "M_F_CPU0_SB_CA<0>")
	)
	(segment
		(start 308.587394 -260.660134)
		(end 309.703216 -261.775956)
		(width 0.14478)
		(layer "In11.Cu")
		(net "M_F_CPU0_SB_CA<0>")
	)
	(segment
		(start 324.471538 -261.776972)
		(end 324.704964 -262.010398)
		(width 0.0889)
		(layer "In11.Cu")
		(net "M_F_CPU0_SB_CA<0>")
	)
	(segment
		(start 271.981422 -260.420612)
		(end 271.981422 -260.885432)
		(width 0.14478)
		(layer "In11.Cu")
		(net "M_F_CPU0_SB_CA<0>")
	)
	(segment
		(start 273.256756 -261.048246)
		(end 273.487388 -261.048246)
		(width 0.14478)
		(layer "In11.Cu")
		(net "M_F_CPU0_SB_CA<0>")
	)
	(segment
		(start 269.648178 -261.085076)
		(end 270.475456 -260.257798)
		(width 0.14478)
		(layer "In11.Cu")
		(net "M_F_CPU0_SB_CA<0>")
	)
	(segment
		(start 271.262348 -261.048246)
		(end 271.425162 -260.885432)
		(width 0.14478)
		(layer "In11.Cu")
		(net "M_F_CPU0_SB_CA<0>")
	)
	(segment
		(start 324.785228 -262.043672)
		(end 327.07707 -262.043672)
		(width 0.0889)
		(layer "In11.Cu")
		(net "M_F_CPU0_SB_CA<0>")
	)
	(segment
		(start 271.031716 -261.048246)
		(end 271.262348 -261.048246)
		(width 0.14478)
		(layer "In11.Cu")
		(net "M_F_CPU0_SB_CA<0>")
	)
	(segment
		(start 272.931128 -260.257798)
		(end 273.093942 -260.420612)
		(width 0.14478)
		(layer "In11.Cu")
		(net "M_F_CPU0_SB_CA<0>")
	)
	(segment
		(start 271.425162 -260.885432)
		(end 271.425162 -260.420612)
		(width 0.14478)
		(layer "In11.Cu")
		(net "M_F_CPU0_SB_CA<0>")
	)
	(segment
		(start 272.700496 -260.257798)
		(end 272.931128 -260.257798)
		(width 0.14478)
		(layer "In11.Cu")
		(net "M_F_CPU0_SB_CA<0>")
	)
	(segment
		(start 333.832708 -262.284718)
		(end 333.85506 -262.201406)
		(width 0.0889)
		(layer "In11.Cu")
		(net "M_F_CPU0_SB_CA<0>")
	)
	(segment
		(start 272.144236 -261.048246)
		(end 272.374868 -261.048246)
		(width 0.14478)
		(layer "In11.Cu")
		(net "M_F_CPU0_SB_CA<0>")
	)
	(segment
		(start 273.650202 -260.885432)
		(end 273.650202 -260.804914)
		(width 0.14478)
		(layer "In11.Cu")
		(net "M_F_CPU0_SB_CA<0>")
	)
	(segment
		(start 273.093942 -260.420612)
		(end 273.093942 -260.885432)
		(width 0.14478)
		(layer "In11.Cu")
		(net "M_F_CPU0_SB_CA<0>")
	)
	(segment
		(start 330.119736 -262.263382)
		(end 330.128118 -262.258556)
		(width 0.0889)
		(layer "In11.Cu")
		(net "M_F_CPU0_SB_CA<0>")
	)
	(segment
		(start 270.868902 -260.885432)
		(end 271.031716 -261.048246)
		(width 0.14478)
		(layer "In11.Cu")
		(net "M_F_CPU0_SB_CA<0>")
	)
	(arc
		(start 330.702412 -262.263382)
		(mid 330.88592 -262.308876)
		(end 331.068172 -262.258556)
		(width 0.0889)
		(layer "In11.Cu")
		(net "M_F_CPU0_SB_CA<0>")
	)
	(arc
		(start 332.574138 -262.258556)
		(mid 332.761082 -262.308811)
		(end 332.948026 -262.258556)
		(width 0.0889)
		(layer "In11.Cu")
		(net "M_F_CPU0_SB_CA<0>")
	)
	(arc
		(start 332.008226 -262.258556)
		(mid 332.291182 -262.182379)
		(end 332.574138 -262.258556)
		(width 0.0889)
		(layer "In11.Cu")
		(net "M_F_CPU0_SB_CA<0>")
	)
	(arc
		(start 333.513938 -262.258556)
		(mid 333.670376 -262.307527)
		(end 333.832708 -262.284718)
		(width 0.0889)
		(layer "In11.Cu")
		(net "M_F_CPU0_SB_CA<0>")
	)
	(arc
		(start 328.248264 -262.258556)
		(mid 328.53122 -262.182379)
		(end 328.814176 -262.258556)
		(width 0.0889)
		(layer "In11.Cu")
		(net "M_F_CPU0_SB_CA<0>")
	)
	(arc
		(start 330.128118 -262.258556)
		(mid 330.411074 -262.182379)
		(end 330.69403 -262.258556)
		(width 0.0889)
		(layer "In11.Cu")
		(net "M_F_CPU0_SB_CA<0>")
	)
	(arc
		(start 329.753976 -262.258556)
		(mid 329.936227 -262.308906)
		(end 330.119736 -262.263382)
		(width 0.0889)
		(layer "In11.Cu")
		(net "M_F_CPU0_SB_CA<0>")
	)
	(arc
		(start 327.873868 -262.258556)
		(mid 328.061066 -262.308938)
		(end 328.248264 -262.258556)
		(width 0.0889)
		(layer "In11.Cu")
		(net "M_F_CPU0_SB_CA<0>")
	)
	(arc
		(start 331.068172 -262.258556)
		(mid 331.351128 -262.182379)
		(end 331.634084 -262.258556)
		(width 0.0889)
		(layer "In11.Cu")
		(net "M_F_CPU0_SB_CA<0>")
	)
	(arc
		(start 327.07707 -262.043672)
		(mid 327.489702 -262.098336)
		(end 327.873868 -262.258556)
		(width 0.0889)
		(layer "In11.Cu")
		(net "M_F_CPU0_SB_CA<0>")
	)
	(arc
		(start 328.814176 -262.258556)
		(mid 329.00112 -262.308811)
		(end 329.188064 -262.258556)
		(width 0.0889)
		(layer "In11.Cu")
		(net "M_F_CPU0_SB_CA<0>")
	)
	(arc
		(start 324.704964 -262.010398)
		(mid 324.741775 -262.035058)
		(end 324.785228 -262.043672)
		(width 0.0889)
		(layer "In11.Cu")
		(net "M_F_CPU0_SB_CA<0>")
	)
	(arc
		(start 331.642466 -262.263382)
		(mid 331.825974 -262.308876)
		(end 332.008226 -262.258556)
		(width 0.0889)
		(layer "In11.Cu")
		(net "M_F_CPU0_SB_CA<0>")
	)
	(arc
		(start 332.948026 -262.258556)
		(mid 333.230982 -262.182379)
		(end 333.513938 -262.258556)
		(width 0.0889)
		(layer "In11.Cu")
		(net "M_F_CPU0_SB_CA<0>")
	)
	(arc
		(start 329.188064 -262.258556)
		(mid 329.47102 -262.182379)
		(end 329.753976 -262.258556)
		(width 0.0889)
		(layer "In11.Cu")
		(net "M_F_CPU0_SB_CA<0>")
	)
	(segment
		(start 334.167988 -266.530074)
		(end 333.701136 -266.796012)
		(width 0.10668)
		(layer "F.Cu")
		(net "M_F_CPU0_SA_RSP<0>")
	)
	(segment
		(start 270.576802 -269.503144)
		(end 270.731488 -269.65783)
		(width 0.11684)
		(layer "In11.Cu")
		(net "M_F_CPU0_SA_RSP<0>")
	)
	(segment
		(start 271.633442 -269.503144)
		(end 271.788128 -269.65783)
		(width 0.11684)
		(layer "In11.Cu")
		(net "M_F_CPU0_SA_RSP<0>")
	)
	(segment
		(start 272.316448 -269.15999)
		(end 308.198774 -269.15999)
		(width 0.11684)
		(layer "In11.Cu")
		(net "M_F_CPU0_SA_RSP<0>")
	)
	(segment
		(start 310.934354 -266.42441)
		(end 323.989954 -266.42441)
		(width 0.11684)
		(layer "In11.Cu")
		(net "M_F_CPU0_SA_RSP<0>")
	)
	(segment
		(start 270.073374 -269.15999)
		(end 270.422116 -269.15999)
		(width 0.11684)
		(layer "In11.Cu")
		(net "M_F_CPU0_SA_RSP<0>")
	)
	(segment
		(start 271.105122 -269.314676)
		(end 271.259808 -269.15999)
		(width 0.11684)
		(layer "In11.Cu")
		(net "M_F_CPU0_SA_RSP<0>")
	)
	(segment
		(start 270.422116 -269.15999)
		(end 270.576802 -269.314676)
		(width 0.11684)
		(layer "In11.Cu")
		(net "M_F_CPU0_SA_RSP<0>")
	)
	(segment
		(start 272.161762 -269.314676)
		(end 272.316448 -269.15999)
		(width 0.11684)
		(layer "In11.Cu")
		(net "M_F_CPU0_SA_RSP<0>")
	)
	(segment
		(start 331.634084 -267.118592)
		(end 331.642466 -267.123418)
		(width 0.0889)
		(layer "In11.Cu")
		(net "M_F_CPU0_SA_RSP<0>")
	)
	(segment
		(start 271.259808 -269.15999)
		(end 271.478756 -269.15999)
		(width 0.11684)
		(layer "In11.Cu")
		(net "M_F_CPU0_SA_RSP<0>")
	)
	(segment
		(start 324.432676 -266.42441)
		(end 325.136002 -267.127736)
		(width 0.0889)
		(layer "In11.Cu")
		(net "M_F_CPU0_SA_RSP<0>")
	)
	(segment
		(start 271.105122 -269.503144)
		(end 271.105122 -269.314676)
		(width 0.11684)
		(layer "In11.Cu")
		(net "M_F_CPU0_SA_RSP<0>")
	)
	(segment
		(start 270.731488 -269.65783)
		(end 270.950436 -269.65783)
		(width 0.11684)
		(layer "In11.Cu")
		(net "M_F_CPU0_SA_RSP<0>")
	)
	(segment
		(start 271.633442 -269.314676)
		(end 271.633442 -269.503144)
		(width 0.11684)
		(layer "In11.Cu")
		(net "M_F_CPU0_SA_RSP<0>")
	)
	(segment
		(start 308.198774 -269.15999)
		(end 310.934354 -266.42441)
		(width 0.11684)
		(layer "In11.Cu")
		(net "M_F_CPU0_SA_RSP<0>")
	)
	(segment
		(start 323.989954 -266.42441)
		(end 324.432676 -266.42441)
		(width 0.0889)
		(layer "In11.Cu")
		(net "M_F_CPU0_SA_RSP<0>")
	)
	(segment
		(start 330.119736 -267.123418)
		(end 330.128118 -267.118592)
		(width 0.0889)
		(layer "In11.Cu")
		(net "M_F_CPU0_SA_RSP<0>")
	)
	(segment
		(start 272.161762 -269.503144)
		(end 272.161762 -269.314676)
		(width 0.11684)
		(layer "In11.Cu")
		(net "M_F_CPU0_SA_RSP<0>")
	)
	(segment
		(start 271.788128 -269.65783)
		(end 272.007076 -269.65783)
		(width 0.11684)
		(layer "In11.Cu")
		(net "M_F_CPU0_SA_RSP<0>")
	)
	(segment
		(start 333.832708 -267.144754)
		(end 333.85506 -267.061442)
		(width 0.0889)
		(layer "In11.Cu")
		(net "M_F_CPU0_SA_RSP<0>")
	)
	(segment
		(start 333.85506 -267.061442)
		(end 333.701136 -266.796012)
		(width 0.0889)
		(layer "In11.Cu")
		(net "M_F_CPU0_SA_RSP<0>")
	)
	(segment
		(start 271.478756 -269.15999)
		(end 271.633442 -269.314676)
		(width 0.11684)
		(layer "In11.Cu")
		(net "M_F_CPU0_SA_RSP<0>")
	)
	(segment
		(start 270.576802 -269.314676)
		(end 270.576802 -269.503144)
		(width 0.11684)
		(layer "In11.Cu")
		(net "M_F_CPU0_SA_RSP<0>")
	)
	(segment
		(start 269.648178 -269.585186)
		(end 270.073374 -269.15999)
		(width 0.11684)
		(layer "In11.Cu")
		(net "M_F_CPU0_SA_RSP<0>")
	)
	(segment
		(start 272.007076 -269.65783)
		(end 272.161762 -269.503144)
		(width 0.11684)
		(layer "In11.Cu")
		(net "M_F_CPU0_SA_RSP<0>")
	)
	(segment
		(start 270.950436 -269.65783)
		(end 271.105122 -269.503144)
		(width 0.11684)
		(layer "In11.Cu")
		(net "M_F_CPU0_SA_RSP<0>")
	)
	(segment
		(start 330.69403 -267.118592)
		(end 330.702412 -267.123418)
		(width 0.0889)
		(layer "In11.Cu")
		(net "M_F_CPU0_SA_RSP<0>")
	)
	(segment
		(start 325.136002 -267.127736)
		(end 327.890632 -267.127736)
		(width 0.0889)
		(layer "In11.Cu")
		(net "M_F_CPU0_SA_RSP<0>")
	)
	(arc
		(start 330.128118 -267.118592)
		(mid 330.411074 -267.042415)
		(end 330.69403 -267.118592)
		(width 0.0889)
		(layer "In11.Cu")
		(net "M_F_CPU0_SA_RSP<0>")
	)
	(arc
		(start 331.068172 -267.118592)
		(mid 331.351128 -267.042415)
		(end 331.634084 -267.118592)
		(width 0.0889)
		(layer "In11.Cu")
		(net "M_F_CPU0_SA_RSP<0>")
	)
	(arc
		(start 327.890632 -267.127736)
		(mid 328.070614 -267.168836)
		(end 328.248264 -267.118592)
		(width 0.0889)
		(layer "In11.Cu")
		(net "M_F_CPU0_SA_RSP<0>")
	)
	(arc
		(start 332.574138 -267.118592)
		(mid 332.761082 -267.168847)
		(end 332.948026 -267.118592)
		(width 0.0889)
		(layer "In11.Cu")
		(net "M_F_CPU0_SA_RSP<0>")
	)
	(arc
		(start 328.248264 -267.118592)
		(mid 328.53122 -267.042415)
		(end 328.814176 -267.118592)
		(width 0.0889)
		(layer "In11.Cu")
		(net "M_F_CPU0_SA_RSP<0>")
	)
	(arc
		(start 333.513938 -267.118592)
		(mid 333.670376 -267.167563)
		(end 333.832708 -267.144754)
		(width 0.0889)
		(layer "In11.Cu")
		(net "M_F_CPU0_SA_RSP<0>")
	)
	(arc
		(start 328.814176 -267.118592)
		(mid 329.00112 -267.168847)
		(end 329.188064 -267.118592)
		(width 0.0889)
		(layer "In11.Cu")
		(net "M_F_CPU0_SA_RSP<0>")
	)
	(arc
		(start 330.702412 -267.123418)
		(mid 330.88592 -267.168912)
		(end 331.068172 -267.118592)
		(width 0.0889)
		(layer "In11.Cu")
		(net "M_F_CPU0_SA_RSP<0>")
	)
	(arc
		(start 329.753976 -267.118592)
		(mid 329.936227 -267.168942)
		(end 330.119736 -267.123418)
		(width 0.0889)
		(layer "In11.Cu")
		(net "M_F_CPU0_SA_RSP<0>")
	)
	(arc
		(start 329.188064 -267.118592)
		(mid 329.47102 -267.042415)
		(end 329.753976 -267.118592)
		(width 0.0889)
		(layer "In11.Cu")
		(net "M_F_CPU0_SA_RSP<0>")
	)
	(arc
		(start 332.008226 -267.118592)
		(mid 332.291182 -267.042415)
		(end 332.574138 -267.118592)
		(width 0.0889)
		(layer "In11.Cu")
		(net "M_F_CPU0_SA_RSP<0>")
	)
	(arc
		(start 331.642466 -267.123418)
		(mid 331.825974 -267.168912)
		(end 332.008226 -267.118592)
		(width 0.0889)
		(layer "In11.Cu")
		(net "M_F_CPU0_SA_RSP<0>")
	)
	(arc
		(start 332.948026 -267.118592)
		(mid 333.230982 -267.042415)
		(end 333.513938 -267.118592)
		(width 0.0889)
		(layer "In11.Cu")
		(net "M_F_CPU0_SA_RSP<0>")
	)
	(segment
		(start 333.868014 -256.090166)
		(end 333.401162 -255.824228)
		(width 0.10668)
		(layer "F.Cu")
		(net "M_F_CPU0_SA_PAR")
	)
	(segment
		(start 319.474342 -255.15443)
		(end 320.988182 -256.66827)
		(width 0.14478)
		(layer "In11.Cu")
		(net "M_F_CPU0_SA_PAR")
	)
	(segment
		(start 333.555086 -255.558798)
		(end 333.401162 -255.824228)
		(width 0.0889)
		(layer "In11.Cu")
		(net "M_F_CPU0_SA_PAR")
	)
	(segment
		(start 327.007728 -255.501648)
		(end 327.018142 -255.507744)
		(width 0.0889)
		(layer "In11.Cu")
		(net "M_F_CPU0_SA_PAR")
	)
	(segment
		(start 324.736714 -256.66827)
		(end 325.752714 -255.65227)
		(width 0.0889)
		(layer "In11.Cu")
		(net "M_F_CPU0_SA_PAR")
	)
	(segment
		(start 275.854668 -255.580642)
		(end 276.017736 -255.74371)
		(width 0.14478)
		(layer "In11.Cu")
		(net "M_F_CPU0_SA_PAR")
	)
	(segment
		(start 329.819762 -255.496822)
		(end 329.828144 -255.501648)
		(width 0.0889)
		(layer "In11.Cu")
		(net "M_F_CPU0_SA_PAR")
	)
	(segment
		(start 275.298154 -255.368298)
		(end 275.461222 -255.20523)
		(width 0.14478)
		(layer "In11.Cu")
		(net "M_F_CPU0_SA_PAR")
	)
	(segment
		(start 312.925714 -255.74371)
		(end 313.514994 -255.15443)
		(width 0.14478)
		(layer "In11.Cu")
		(net "M_F_CPU0_SA_PAR")
	)
	(segment
		(start 274.348194 -255.20523)
		(end 274.578572 -255.20523)
		(width 0.14478)
		(layer "In11.Cu")
		(net "M_F_CPU0_SA_PAR")
	)
	(segment
		(start 274.185126 -255.580642)
		(end 274.185126 -255.368298)
		(width 0.14478)
		(layer "In11.Cu")
		(net "M_F_CPU0_SA_PAR")
	)
	(segment
		(start 323.995034 -256.66827)
		(end 324.736714 -256.66827)
		(width 0.0889)
		(layer "In11.Cu")
		(net "M_F_CPU0_SA_PAR")
	)
	(segment
		(start 325.752714 -255.65227)
		(end 326.483218 -255.65227)
		(width 0.0889)
		(layer "In11.Cu")
		(net "M_F_CPU0_SA_PAR")
	)
	(segment
		(start 269.648178 -254.284988)
		(end 271.1069 -255.74371)
		(width 0.14478)
		(layer "In11.Cu")
		(net "M_F_CPU0_SA_PAR")
	)
	(segment
		(start 330.394056 -255.501648)
		(end 330.402438 -255.496822)
		(width 0.0889)
		(layer "In11.Cu")
		(net "M_F_CPU0_SA_PAR")
	)
	(segment
		(start 275.298154 -255.580642)
		(end 275.298154 -255.368298)
		(width 0.14478)
		(layer "In11.Cu")
		(net "M_F_CPU0_SA_PAR")
	)
	(segment
		(start 275.6916 -255.20523)
		(end 275.854668 -255.368298)
		(width 0.14478)
		(layer "In11.Cu")
		(net "M_F_CPU0_SA_PAR")
	)
	(segment
		(start 275.135086 -255.74371)
		(end 275.298154 -255.580642)
		(width 0.14478)
		(layer "In11.Cu")
		(net "M_F_CPU0_SA_PAR")
	)
	(segment
		(start 331.33411 -255.501648)
		(end 331.342492 -255.496822)
		(width 0.0889)
		(layer "In11.Cu")
		(net "M_F_CPU0_SA_PAR")
	)
	(segment
		(start 274.578572 -255.20523)
		(end 274.74164 -255.368298)
		(width 0.14478)
		(layer "In11.Cu")
		(net "M_F_CPU0_SA_PAR")
	)
	(segment
		(start 333.532734 -255.475486)
		(end 333.555086 -255.558798)
		(width 0.0889)
		(layer "In11.Cu")
		(net "M_F_CPU0_SA_PAR")
	)
	(segment
		(start 274.74164 -255.368298)
		(end 274.74164 -255.580642)
		(width 0.14478)
		(layer "In11.Cu")
		(net "M_F_CPU0_SA_PAR")
	)
	(segment
		(start 274.022058 -255.74371)
		(end 274.185126 -255.580642)
		(width 0.14478)
		(layer "In11.Cu")
		(net "M_F_CPU0_SA_PAR")
	)
	(segment
		(start 276.017736 -255.74371)
		(end 312.925714 -255.74371)
		(width 0.14478)
		(layer "In11.Cu")
		(net "M_F_CPU0_SA_PAR")
	)
	(segment
		(start 274.185126 -255.368298)
		(end 274.348194 -255.20523)
		(width 0.14478)
		(layer "In11.Cu")
		(net "M_F_CPU0_SA_PAR")
	)
	(segment
		(start 326.63384 -255.501648)
		(end 326.645524 -255.49479)
		(width 0.0889)
		(layer "In11.Cu")
		(net "M_F_CPU0_SA_PAR")
	)
	(segment
		(start 274.74164 -255.580642)
		(end 274.904708 -255.74371)
		(width 0.14478)
		(layer "In11.Cu")
		(net "M_F_CPU0_SA_PAR")
	)
	(segment
		(start 275.461222 -255.20523)
		(end 275.6916 -255.20523)
		(width 0.14478)
		(layer "In11.Cu")
		(net "M_F_CPU0_SA_PAR")
	)
	(segment
		(start 271.1069 -255.74371)
		(end 274.022058 -255.74371)
		(width 0.14478)
		(layer "In11.Cu")
		(net "M_F_CPU0_SA_PAR")
	)
	(segment
		(start 274.904708 -255.74371)
		(end 275.135086 -255.74371)
		(width 0.14478)
		(layer "In11.Cu")
		(net "M_F_CPU0_SA_PAR")
	)
	(segment
		(start 275.854668 -255.368298)
		(end 275.854668 -255.580642)
		(width 0.14478)
		(layer "In11.Cu")
		(net "M_F_CPU0_SA_PAR")
	)
	(segment
		(start 313.514994 -255.15443)
		(end 319.474342 -255.15443)
		(width 0.14478)
		(layer "In11.Cu")
		(net "M_F_CPU0_SA_PAR")
	)
	(segment
		(start 320.988182 -256.66827)
		(end 323.995034 -256.66827)
		(width 0.14478)
		(layer "In11.Cu")
		(net "M_F_CPU0_SA_PAR")
	)
	(segment
		(start 326.483218 -255.65227)
		(end 326.63384 -255.501648)
		(width 0.0889)
		(layer "In11.Cu")
		(net "M_F_CPU0_SA_PAR")
	)
	(arc
		(start 330.768198 -255.501648)
		(mid 331.051154 -255.577825)
		(end 331.33411 -255.501648)
		(width 0.0889)
		(layer "In11.Cu")
		(net "M_F_CPU0_SA_PAR")
	)
	(arc
		(start 328.514202 -255.501648)
		(mid 328.701146 -255.451393)
		(end 328.88809 -255.501648)
		(width 0.0889)
		(layer "In11.Cu")
		(net "M_F_CPU0_SA_PAR")
	)
	(arc
		(start 330.402438 -255.496822)
		(mid 330.585946 -255.451328)
		(end 330.768198 -255.501648)
		(width 0.0889)
		(layer "In11.Cu")
		(net "M_F_CPU0_SA_PAR")
	)
	(arc
		(start 328.88809 -255.501648)
		(mid 329.171046 -255.577825)
		(end 329.454002 -255.501648)
		(width 0.0889)
		(layer "In11.Cu")
		(net "M_F_CPU0_SA_PAR")
	)
	(arc
		(start 326.645524 -255.49479)
		(mid 326.827525 -255.451257)
		(end 327.007728 -255.501648)
		(width 0.0889)
		(layer "In11.Cu")
		(net "M_F_CPU0_SA_PAR")
	)
	(arc
		(start 333.213964 -255.501648)
		(mid 333.370402 -255.452677)
		(end 333.532734 -255.475486)
		(width 0.0889)
		(layer "In11.Cu")
		(net "M_F_CPU0_SA_PAR")
	)
	(arc
		(start 329.828144 -255.501648)
		(mid 330.1111 -255.577825)
		(end 330.394056 -255.501648)
		(width 0.0889)
		(layer "In11.Cu")
		(net "M_F_CPU0_SA_PAR")
	)
	(arc
		(start 327.94829 -255.501648)
		(mid 328.231246 -255.577825)
		(end 328.514202 -255.501648)
		(width 0.0889)
		(layer "In11.Cu")
		(net "M_F_CPU0_SA_PAR")
	)
	(arc
		(start 329.454002 -255.501648)
		(mid 329.636253 -255.451298)
		(end 329.819762 -255.496822)
		(width 0.0889)
		(layer "In11.Cu")
		(net "M_F_CPU0_SA_PAR")
	)
	(arc
		(start 327.573894 -255.501648)
		(mid 327.761092 -255.451266)
		(end 327.94829 -255.501648)
		(width 0.0889)
		(layer "In11.Cu")
		(net "M_F_CPU0_SA_PAR")
	)
	(arc
		(start 332.274164 -255.501648)
		(mid 332.461108 -255.451393)
		(end 332.648052 -255.501648)
		(width 0.0889)
		(layer "In11.Cu")
		(net "M_F_CPU0_SA_PAR")
	)
	(arc
		(start 327.018142 -255.507744)
		(mid 327.296828 -255.577964)
		(end 327.573894 -255.501648)
		(width 0.0889)
		(layer "In11.Cu")
		(net "M_F_CPU0_SA_PAR")
	)
	(arc
		(start 331.342492 -255.496822)
		(mid 331.526 -255.451328)
		(end 331.708252 -255.501648)
		(width 0.0889)
		(layer "In11.Cu")
		(net "M_F_CPU0_SA_PAR")
	)
	(arc
		(start 332.648052 -255.501648)
		(mid 332.931008 -255.577825)
		(end 333.213964 -255.501648)
		(width 0.0889)
		(layer "In11.Cu")
		(net "M_F_CPU0_SA_PAR")
	)
	(arc
		(start 331.708252 -255.501648)
		(mid 331.991208 -255.577825)
		(end 332.274164 -255.501648)
		(width 0.0889)
		(layer "In11.Cu")
		(net "M_F_CPU0_SA_PAR")
	)
	(segment
		(start 333.868014 -247.990106)
		(end 333.401162 -247.724168)
		(width 0.12954)
		(layer "F.Cu")
		(net "M_F_CPU0_SA_DQS_DP<9>")
	)
	(segment
		(start 281.837892 -240.240312)
		(end 282.315412 -240.240312)
		(width 0.16002)
		(layer "In11.Cu")
		(net "M_F_CPU0_SA_DQS_DP<9>")
	)
	(segment
		(start 325.449184 -247.623076)
		(end 325.614284 -247.457976)
		(width 0.09525)
		(layer "In11.Cu")
		(net "M_F_CPU0_SA_DQS_DP<9>")
	)
	(segment
		(start 294.610028 -240.560352)
		(end 296.60596 -240.560352)
		(width 0.16002)
		(layer "In11.Cu")
		(net "M_F_CPU0_SA_DQS_DP<9>")
	)
	(segment
		(start 293.75989 -239.710214)
		(end 294.610028 -240.560352)
		(width 0.16002)
		(layer "In11.Cu")
		(net "M_F_CPU0_SA_DQS_DP<9>")
	)
	(segment
		(start 298.943776 -239.710214)
		(end 301.303944 -239.710214)
		(width 0.16002)
		(layer "In11.Cu")
		(net "M_F_CPU0_SA_DQS_DP<9>")
	)
	(segment
		(start 330.392532 -247.399048)
		(end 330.400914 -247.394222)
		(width 0.09525)
		(layer "In11.Cu")
		(net "M_F_CPU0_SA_DQS_DP<9>")
	)
	(segment
		(start 290.74364 -239.356138)
		(end 291.045646 -239.356138)
		(width 0.16002)
		(layer "In11.Cu")
		(net "M_F_CPU0_SA_DQS_DP<9>")
	)
	(segment
		(start 267.866876 -239.395508)
		(end 268.456156 -239.395508)
		(width 0.16002)
		(layer "In11.Cu")
		(net "M_F_CPU0_SA_DQS_DP<9>")
	)
	(segment
		(start 265.54811 -239.835182)
		(end 265.822176 -239.561116)
		(width 0.16002)
		(layer "In11.Cu")
		(net "M_F_CPU0_SA_DQS_DP<9>")
	)
	(segment
		(start 270.121888 -239.858804)
		(end 270.238728 -239.741964)
		(width 0.16002)
		(layer "In11.Cu")
		(net "M_F_CPU0_SA_DQS_DP<9>")
	)
	(segment
		(start 327.009252 -247.399048)
		(end 327.019666 -247.405144)
		(width 0.09525)
		(layer "In11.Cu")
		(net "M_F_CPU0_SA_DQS_DP<9>")
	)
	(segment
		(start 273.973798 -240.560352)
		(end 274.293838 -240.240312)
		(width 0.16002)
		(layer "In11.Cu")
		(net "M_F_CPU0_SA_DQS_DP<9>")
	)
	(segment
		(start 276.311614 -239.710214)
		(end 278.671782 -239.710214)
		(width 0.16002)
		(layer "In11.Cu")
		(net "M_F_CPU0_SA_DQS_DP<9>")
	)
	(segment
		(start 305.77917 -240.905792)
		(end 307.337206 -240.905792)
		(width 0.16002)
		(layer "In11.Cu")
		(net "M_F_CPU0_SA_DQS_DP<9>")
	)
	(segment
		(start 297.40352 -240.240312)
		(end 298.287694 -239.356138)
		(width 0.16002)
		(layer "In11.Cu")
		(net "M_F_CPU0_SA_DQS_DP<9>")
	)
	(segment
		(start 307.337206 -240.905792)
		(end 313.633866 -247.202452)
		(width 0.16002)
		(layer "In11.Cu")
		(net "M_F_CPU0_SA_DQS_DP<9>")
	)
	(segment
		(start 268.802612 -239.741964)
		(end 269.524988 -239.741964)
		(width 0.16002)
		(layer "In11.Cu")
		(net "M_F_CPU0_SA_DQS_DP<9>")
	)
	(segment
		(start 323.235828 -247.682004)
		(end 323.895974 -247.682004)
		(width 0.16002)
		(layer "In11.Cu")
		(net "M_F_CPU0_SA_DQS_DP<9>")
	)
	(segment
		(start 305.11369 -240.240312)
		(end 305.77917 -240.905792)
		(width 0.16002)
		(layer "In11.Cu")
		(net "M_F_CPU0_SA_DQS_DP<9>")
	)
	(segment
		(start 301.834042 -240.240312)
		(end 305.11369 -240.240312)
		(width 0.16002)
		(layer "In11.Cu")
		(net "M_F_CPU0_SA_DQS_DP<9>")
	)
	(segment
		(start 281.517852 -240.560352)
		(end 281.837892 -240.240312)
		(width 0.16002)
		(layer "In11.Cu")
		(net "M_F_CPU0_SA_DQS_DP<9>")
	)
	(segment
		(start 267.701268 -239.561116)
		(end 267.866876 -239.395508)
		(width 0.16002)
		(layer "In11.Cu")
		(net "M_F_CPU0_SA_DQS_DP<9>")
	)
	(segment
		(start 331.332586 -247.399048)
		(end 331.340968 -247.394222)
		(width 0.09525)
		(layer "In11.Cu")
		(net "M_F_CPU0_SA_DQS_DP<9>")
	)
	(segment
		(start 329.821286 -247.394222)
		(end 329.829668 -247.399048)
		(width 0.09525)
		(layer "In11.Cu")
		(net "M_F_CPU0_SA_DQS_DP<9>")
	)
	(segment
		(start 272.01114 -240.560352)
		(end 273.973798 -240.560352)
		(width 0.16002)
		(layer "In11.Cu")
		(net "M_F_CPU0_SA_DQS_DP<9>")
	)
	(segment
		(start 278.671782 -239.710214)
		(end 279.52192 -240.560352)
		(width 0.16002)
		(layer "In11.Cu")
		(net "M_F_CPU0_SA_DQS_DP<9>")
	)
	(segment
		(start 291.045646 -239.356138)
		(end 291.399722 -239.710214)
		(width 0.16002)
		(layer "In11.Cu")
		(net "M_F_CPU0_SA_DQS_DP<9>")
	)
	(segment
		(start 271.192752 -239.741964)
		(end 272.01114 -240.560352)
		(width 0.16002)
		(layer "In11.Cu")
		(net "M_F_CPU0_SA_DQS_DP<9>")
	)
	(segment
		(start 279.52192 -240.560352)
		(end 281.517852 -240.560352)
		(width 0.16002)
		(layer "In11.Cu")
		(net "M_F_CPU0_SA_DQS_DP<9>")
	)
	(segment
		(start 326.625712 -247.40235)
		(end 326.632062 -247.39854)
		(width 0.09525)
		(layer "In11.Cu")
		(net "M_F_CPU0_SA_DQS_DP<9>")
	)
	(segment
		(start 326.639174 -247.395238)
		(end 326.641206 -247.393968)
		(width 0.09525)
		(layer "In11.Cu")
		(net "M_F_CPU0_SA_DQS_DP<9>")
	)
	(segment
		(start 286.215836 -239.710214)
		(end 287.065974 -240.560352)
		(width 0.16002)
		(layer "In11.Cu")
		(net "M_F_CPU0_SA_DQS_DP<9>")
	)
	(segment
		(start 323.978524 -247.623076)
		(end 325.449184 -247.623076)
		(width 0.09525)
		(layer "In11.Cu")
		(net "M_F_CPU0_SA_DQS_DP<9>")
	)
	(segment
		(start 333.555086 -247.458738)
		(end 333.401162 -247.724168)
		(width 0.09525)
		(layer "In11.Cu")
		(net "M_F_CPU0_SA_DQS_DP<9>")
	)
	(segment
		(start 296.60596 -240.560352)
		(end 296.926 -240.240312)
		(width 0.16002)
		(layer "In11.Cu")
		(net "M_F_CPU0_SA_DQS_DP<9>")
	)
	(segment
		(start 296.926 -240.240312)
		(end 297.40352 -240.240312)
		(width 0.16002)
		(layer "In11.Cu")
		(net "M_F_CPU0_SA_DQS_DP<9>")
	)
	(segment
		(start 274.771358 -240.240312)
		(end 275.655532 -239.356138)
		(width 0.16002)
		(layer "In11.Cu")
		(net "M_F_CPU0_SA_DQS_DP<9>")
	)
	(segment
		(start 323.895974 -247.682004)
		(end 323.919596 -247.682004)
		(width 0.09525)
		(layer "In11.Cu")
		(net "M_F_CPU0_SA_DQS_DP<9>")
	)
	(segment
		(start 322.756276 -247.202452)
		(end 323.235828 -247.682004)
		(width 0.16002)
		(layer "In11.Cu")
		(net "M_F_CPU0_SA_DQS_DP<9>")
	)
	(segment
		(start 301.303944 -239.710214)
		(end 301.834042 -240.240312)
		(width 0.16002)
		(layer "In11.Cu")
		(net "M_F_CPU0_SA_DQS_DP<9>")
	)
	(segment
		(start 274.293838 -240.240312)
		(end 274.771358 -240.240312)
		(width 0.16002)
		(layer "In11.Cu")
		(net "M_F_CPU0_SA_DQS_DP<9>")
	)
	(segment
		(start 333.531718 -247.37187)
		(end 333.555086 -247.458738)
		(width 0.09525)
		(layer "In11.Cu")
		(net "M_F_CPU0_SA_DQS_DP<9>")
	)
	(segment
		(start 282.315412 -240.240312)
		(end 283.199586 -239.356138)
		(width 0.16002)
		(layer "In11.Cu")
		(net "M_F_CPU0_SA_DQS_DP<9>")
	)
	(segment
		(start 268.456156 -239.395508)
		(end 268.802612 -239.741964)
		(width 0.16002)
		(layer "In11.Cu")
		(net "M_F_CPU0_SA_DQS_DP<9>")
	)
	(segment
		(start 265.822176 -239.561116)
		(end 267.701268 -239.561116)
		(width 0.16002)
		(layer "In11.Cu")
		(net "M_F_CPU0_SA_DQS_DP<9>")
	)
	(segment
		(start 270.238728 -239.741964)
		(end 271.192752 -239.741964)
		(width 0.16002)
		(layer "In11.Cu")
		(net "M_F_CPU0_SA_DQS_DP<9>")
	)
	(segment
		(start 275.655532 -239.356138)
		(end 275.957538 -239.356138)
		(width 0.16002)
		(layer "In11.Cu")
		(net "M_F_CPU0_SA_DQS_DP<9>")
	)
	(segment
		(start 326.63257 -247.398794)
		(end 326.638158 -247.395746)
		(width 0.09525)
		(layer "In11.Cu")
		(net "M_F_CPU0_SA_DQS_DP<9>")
	)
	(segment
		(start 283.199586 -239.356138)
		(end 283.501592 -239.356138)
		(width 0.16002)
		(layer "In11.Cu")
		(net "M_F_CPU0_SA_DQS_DP<9>")
	)
	(segment
		(start 283.501592 -239.356138)
		(end 283.855668 -239.710214)
		(width 0.16002)
		(layer "In11.Cu")
		(net "M_F_CPU0_SA_DQS_DP<9>")
	)
	(segment
		(start 323.919596 -247.682004)
		(end 323.978524 -247.623076)
		(width 0.09525)
		(layer "In11.Cu")
		(net "M_F_CPU0_SA_DQS_DP<9>")
	)
	(segment
		(start 287.065974 -240.560352)
		(end 289.061906 -240.560352)
		(width 0.16002)
		(layer "In11.Cu")
		(net "M_F_CPU0_SA_DQS_DP<9>")
	)
	(segment
		(start 326.641206 -247.393968)
		(end 326.644254 -247.39219)
		(width 0.09525)
		(layer "In11.Cu")
		(net "M_F_CPU0_SA_DQS_DP<9>")
	)
	(segment
		(start 326.638158 -247.395746)
		(end 326.639174 -247.395238)
		(width 0.09525)
		(layer "In11.Cu")
		(net "M_F_CPU0_SA_DQS_DP<9>")
	)
	(segment
		(start 326.632062 -247.39854)
		(end 326.63257 -247.398794)
		(width 0.09525)
		(layer "In11.Cu")
		(net "M_F_CPU0_SA_DQS_DP<9>")
	)
	(segment
		(start 326.613774 -247.409208)
		(end 326.625712 -247.40235)
		(width 0.09525)
		(layer "In11.Cu")
		(net "M_F_CPU0_SA_DQS_DP<9>")
	)
	(segment
		(start 298.5897 -239.356138)
		(end 298.943776 -239.710214)
		(width 0.16002)
		(layer "In11.Cu")
		(net "M_F_CPU0_SA_DQS_DP<9>")
	)
	(segment
		(start 269.524988 -239.741964)
		(end 269.641828 -239.858804)
		(width 0.16002)
		(layer "In11.Cu")
		(net "M_F_CPU0_SA_DQS_DP<9>")
	)
	(segment
		(start 269.641828 -239.858804)
		(end 270.121888 -239.858804)
		(width 0.16002)
		(layer "In11.Cu")
		(net "M_F_CPU0_SA_DQS_DP<9>")
	)
	(segment
		(start 313.633866 -247.202452)
		(end 322.756276 -247.202452)
		(width 0.16002)
		(layer "In11.Cu")
		(net "M_F_CPU0_SA_DQS_DP<9>")
	)
	(segment
		(start 283.855668 -239.710214)
		(end 286.215836 -239.710214)
		(width 0.16002)
		(layer "In11.Cu")
		(net "M_F_CPU0_SA_DQS_DP<9>")
	)
	(segment
		(start 275.957538 -239.356138)
		(end 276.311614 -239.710214)
		(width 0.16002)
		(layer "In11.Cu")
		(net "M_F_CPU0_SA_DQS_DP<9>")
	)
	(segment
		(start 289.381946 -240.240312)
		(end 289.859466 -240.240312)
		(width 0.16002)
		(layer "In11.Cu")
		(net "M_F_CPU0_SA_DQS_DP<9>")
	)
	(segment
		(start 289.859466 -240.240312)
		(end 290.74364 -239.356138)
		(width 0.16002)
		(layer "In11.Cu")
		(net "M_F_CPU0_SA_DQS_DP<9>")
	)
	(segment
		(start 289.061906 -240.560352)
		(end 289.381946 -240.240312)
		(width 0.16002)
		(layer "In11.Cu")
		(net "M_F_CPU0_SA_DQS_DP<9>")
	)
	(segment
		(start 298.287694 -239.356138)
		(end 298.5897 -239.356138)
		(width 0.16002)
		(layer "In11.Cu")
		(net "M_F_CPU0_SA_DQS_DP<9>")
	)
	(segment
		(start 291.399722 -239.710214)
		(end 293.75989 -239.710214)
		(width 0.16002)
		(layer "In11.Cu")
		(net "M_F_CPU0_SA_DQS_DP<9>")
	)
	(arc
		(start 327.019666 -247.405144)
		(mid 327.296828 -247.474944)
		(end 327.57237 -247.399048)
		(width 0.09525)
		(layer "In11.Cu")
		(net "M_F_CPU0_SA_DQS_DP<9>")
	)
	(arc
		(start 331.340968 -247.394222)
		(mid 331.526 -247.348308)
		(end 331.709776 -247.399048)
		(width 0.09525)
		(layer "In11.Cu")
		(net "M_F_CPU0_SA_DQS_DP<9>")
	)
	(arc
		(start 327.949814 -247.399048)
		(mid 328.231246 -247.474803)
		(end 328.512678 -247.399048)
		(width 0.09525)
		(layer "In11.Cu")
		(net "M_F_CPU0_SA_DQS_DP<9>")
	)
	(arc
		(start 328.512678 -247.399048)
		(mid 328.701146 -247.348371)
		(end 328.889614 -247.399048)
		(width 0.09525)
		(layer "In11.Cu")
		(net "M_F_CPU0_SA_DQS_DP<9>")
	)
	(arc
		(start 330.400914 -247.394222)
		(mid 330.585946 -247.348308)
		(end 330.769722 -247.399048)
		(width 0.09525)
		(layer "In11.Cu")
		(net "M_F_CPU0_SA_DQS_DP<9>")
	)
	(arc
		(start 326.644254 -247.39219)
		(mid 326.827635 -247.348359)
		(end 327.009252 -247.399048)
		(width 0.09525)
		(layer "In11.Cu")
		(net "M_F_CPU0_SA_DQS_DP<9>")
	)
	(arc
		(start 332.649576 -247.399048)
		(mid 332.931008 -247.474803)
		(end 333.21244 -247.399048)
		(width 0.09525)
		(layer "In11.Cu")
		(net "M_F_CPU0_SA_DQS_DP<9>")
	)
	(arc
		(start 327.57237 -247.399048)
		(mid 327.761092 -247.348244)
		(end 327.949814 -247.399048)
		(width 0.09525)
		(layer "In11.Cu")
		(net "M_F_CPU0_SA_DQS_DP<9>")
	)
	(arc
		(start 331.709776 -247.399048)
		(mid 331.991208 -247.474803)
		(end 332.27264 -247.399048)
		(width 0.09525)
		(layer "In11.Cu")
		(net "M_F_CPU0_SA_DQS_DP<9>")
	)
	(arc
		(start 325.614284 -247.457976)
		(mid 325.83193 -247.350859)
		(end 326.069706 -247.398794)
		(width 0.09525)
		(layer "In11.Cu")
		(net "M_F_CPU0_SA_DQS_DP<9>")
	)
	(arc
		(start 330.769722 -247.399048)
		(mid 331.051154 -247.474803)
		(end 331.332586 -247.399048)
		(width 0.09525)
		(layer "In11.Cu")
		(net "M_F_CPU0_SA_DQS_DP<9>")
	)
	(arc
		(start 328.889614 -247.399048)
		(mid 329.171046 -247.474803)
		(end 329.452478 -247.399048)
		(width 0.09525)
		(layer "In11.Cu")
		(net "M_F_CPU0_SA_DQS_DP<9>")
	)
	(arc
		(start 326.069706 -247.398794)
		(mid 326.340394 -247.47448)
		(end 326.613774 -247.409208)
		(width 0.09525)
		(layer "In11.Cu")
		(net "M_F_CPU0_SA_DQS_DP<9>")
	)
	(arc
		(start 333.21244 -247.399048)
		(mid 333.369038 -247.349759)
		(end 333.531718 -247.37187)
		(width 0.09525)
		(layer "In11.Cu")
		(net "M_F_CPU0_SA_DQS_DP<9>")
	)
	(arc
		(start 329.452478 -247.399048)
		(mid 329.636253 -247.348276)
		(end 329.821286 -247.394222)
		(width 0.09525)
		(layer "In11.Cu")
		(net "M_F_CPU0_SA_DQS_DP<9>")
	)
	(arc
		(start 332.27264 -247.399048)
		(mid 332.461108 -247.348371)
		(end 332.649576 -247.399048)
		(width 0.09525)
		(layer "In11.Cu")
		(net "M_F_CPU0_SA_DQS_DP<9>")
	)
	(arc
		(start 329.829668 -247.399048)
		(mid 330.1111 -247.474803)
		(end 330.392532 -247.399048)
		(width 0.09525)
		(layer "In11.Cu")
		(net "M_F_CPU0_SA_DQS_DP<9>")
	)
	(segment
		(start 333.868014 -243.13007)
		(end 333.401162 -242.864132)
		(width 0.12954)
		(layer "F.Cu")
		(net "M_F_CPU0_SA_DQS_DP<8>")
	)
	(segment
		(start 283.855668 -230.36022)
		(end 286.215836 -230.36022)
		(width 0.16002)
		(layer "In11.Cu")
		(net "M_F_CPU0_SA_DQS_DP<8>")
	)
	(segment
		(start 268.456156 -230.045514)
		(end 268.802612 -230.39197)
		(width 0.16002)
		(layer "In11.Cu")
		(net "M_F_CPU0_SA_DQS_DP<8>")
	)
	(segment
		(start 310.367934 -233.685588)
		(end 310.367934 -235.357924)
		(width 0.16002)
		(layer "In11.Cu")
		(net "M_F_CPU0_SA_DQS_DP<8>")
	)
	(segment
		(start 283.501592 -230.006144)
		(end 283.855668 -230.36022)
		(width 0.16002)
		(layer "In11.Cu")
		(net "M_F_CPU0_SA_DQS_DP<8>")
	)
	(segment
		(start 267.866876 -230.045514)
		(end 268.456156 -230.045514)
		(width 0.16002)
		(layer "In11.Cu")
		(net "M_F_CPU0_SA_DQS_DP<8>")
	)
	(segment
		(start 323.805042 -241.536728)
		(end 323.979794 -241.536728)
		(width 0.09525)
		(layer "In11.Cu")
		(net "M_F_CPU0_SA_DQS_DP<8>")
	)
	(segment
		(start 323.722238 -241.59591)
		(end 323.74586 -241.59591)
		(width 0.09525)
		(layer "In11.Cu")
		(net "M_F_CPU0_SA_DQS_DP<8>")
	)
	(segment
		(start 333.555086 -242.598702)
		(end 333.401162 -242.864132)
		(width 0.09525)
		(layer "In11.Cu")
		(net "M_F_CPU0_SA_DQS_DP<8>")
	)
	(segment
		(start 294.610028 -231.210358)
		(end 296.60596 -231.210358)
		(width 0.16002)
		(layer "In11.Cu")
		(net "M_F_CPU0_SA_DQS_DP<8>")
	)
	(segment
		(start 279.52192 -231.210358)
		(end 281.517852 -231.210358)
		(width 0.16002)
		(layer "In11.Cu")
		(net "M_F_CPU0_SA_DQS_DP<8>")
	)
	(segment
		(start 267.701268 -230.211122)
		(end 267.866876 -230.045514)
		(width 0.16002)
		(layer "In11.Cu")
		(net "M_F_CPU0_SA_DQS_DP<8>")
	)
	(segment
		(start 310.367934 -235.357924)
		(end 316.60592 -241.59591)
		(width 0.16002)
		(layer "In11.Cu")
		(net "M_F_CPU0_SA_DQS_DP<8>")
	)
	(segment
		(start 286.215836 -230.36022)
		(end 287.065974 -231.210358)
		(width 0.16002)
		(layer "In11.Cu")
		(net "M_F_CPU0_SA_DQS_DP<8>")
	)
	(segment
		(start 326.617584 -242.547648)
		(end 326.632316 -242.539012)
		(width 0.09525)
		(layer "In11.Cu")
		(net "M_F_CPU0_SA_DQS_DP<8>")
	)
	(segment
		(start 333.531718 -242.511834)
		(end 333.555086 -242.598702)
		(width 0.09525)
		(layer "In11.Cu")
		(net "M_F_CPU0_SA_DQS_DP<8>")
	)
	(segment
		(start 298.943776 -230.36022)
		(end 301.303944 -230.36022)
		(width 0.16002)
		(layer "In11.Cu")
		(net "M_F_CPU0_SA_DQS_DP<8>")
	)
	(segment
		(start 297.40352 -230.890318)
		(end 298.287694 -230.006144)
		(width 0.16002)
		(layer "In11.Cu")
		(net "M_F_CPU0_SA_DQS_DP<8>")
	)
	(segment
		(start 273.973798 -231.210358)
		(end 274.293838 -230.890318)
		(width 0.16002)
		(layer "In11.Cu")
		(net "M_F_CPU0_SA_DQS_DP<8>")
	)
	(segment
		(start 265.822176 -230.211122)
		(end 266.507468 -230.211122)
		(width 0.16002)
		(layer "In11.Cu")
		(net "M_F_CPU0_SA_DQS_DP<8>")
	)
	(segment
		(start 291.045646 -230.006144)
		(end 291.399722 -230.36022)
		(width 0.16002)
		(layer "In11.Cu")
		(net "M_F_CPU0_SA_DQS_DP<8>")
	)
	(segment
		(start 305.831494 -230.006144)
		(end 306.68849 -230.006144)
		(width 0.16002)
		(layer "In11.Cu")
		(net "M_F_CPU0_SA_DQS_DP<8>")
	)
	(segment
		(start 293.75989 -230.36022)
		(end 294.610028 -231.210358)
		(width 0.16002)
		(layer "In11.Cu")
		(net "M_F_CPU0_SA_DQS_DP<8>")
	)
	(segment
		(start 275.655532 -230.006144)
		(end 275.957538 -230.006144)
		(width 0.16002)
		(layer "In11.Cu")
		(net "M_F_CPU0_SA_DQS_DP<8>")
	)
	(segment
		(start 298.287694 -230.006144)
		(end 298.5897 -230.006144)
		(width 0.16002)
		(layer "In11.Cu")
		(net "M_F_CPU0_SA_DQS_DP<8>")
	)
	(segment
		(start 274.771358 -230.890318)
		(end 275.655532 -230.006144)
		(width 0.16002)
		(layer "In11.Cu")
		(net "M_F_CPU0_SA_DQS_DP<8>")
	)
	(segment
		(start 282.315412 -230.890318)
		(end 283.199586 -230.006144)
		(width 0.16002)
		(layer "In11.Cu")
		(net "M_F_CPU0_SA_DQS_DP<8>")
	)
	(segment
		(start 265.54811 -230.485188)
		(end 265.822176 -230.211122)
		(width 0.16002)
		(layer "In11.Cu")
		(net "M_F_CPU0_SA_DQS_DP<8>")
	)
	(segment
		(start 287.065974 -231.210358)
		(end 289.061906 -231.210358)
		(width 0.16002)
		(layer "In11.Cu")
		(net "M_F_CPU0_SA_DQS_DP<8>")
	)
	(segment
		(start 327.009252 -242.539012)
		(end 327.019666 -242.545108)
		(width 0.09525)
		(layer "In11.Cu")
		(net "M_F_CPU0_SA_DQS_DP<8>")
	)
	(segment
		(start 291.399722 -230.36022)
		(end 293.75989 -230.36022)
		(width 0.16002)
		(layer "In11.Cu")
		(net "M_F_CPU0_SA_DQS_DP<8>")
	)
	(segment
		(start 325.668894 -242.48745)
		(end 325.880476 -242.48745)
		(width 0.09525)
		(layer "In11.Cu")
		(net "M_F_CPU0_SA_DQS_DP<8>")
	)
	(segment
		(start 325.338694 -242.15725)
		(end 325.668894 -242.48745)
		(width 0.09525)
		(layer "In11.Cu")
		(net "M_F_CPU0_SA_DQS_DP<8>")
	)
	(segment
		(start 281.837892 -230.890318)
		(end 282.315412 -230.890318)
		(width 0.16002)
		(layer "In11.Cu")
		(net "M_F_CPU0_SA_DQS_DP<8>")
	)
	(segment
		(start 289.061906 -231.210358)
		(end 289.381946 -230.890318)
		(width 0.16002)
		(layer "In11.Cu")
		(net "M_F_CPU0_SA_DQS_DP<8>")
	)
	(segment
		(start 298.5897 -230.006144)
		(end 298.943776 -230.36022)
		(width 0.16002)
		(layer "In11.Cu")
		(net "M_F_CPU0_SA_DQS_DP<8>")
	)
	(segment
		(start 331.332586 -242.539012)
		(end 331.340968 -242.534186)
		(width 0.09525)
		(layer "In11.Cu")
		(net "M_F_CPU0_SA_DQS_DP<8>")
	)
	(segment
		(start 266.507468 -230.211122)
		(end 266.624308 -230.327962)
		(width 0.16002)
		(layer "In11.Cu")
		(net "M_F_CPU0_SA_DQS_DP<8>")
	)
	(segment
		(start 289.859466 -230.890318)
		(end 290.74364 -230.006144)
		(width 0.16002)
		(layer "In11.Cu")
		(net "M_F_CPU0_SA_DQS_DP<8>")
	)
	(segment
		(start 276.311614 -230.36022)
		(end 278.671782 -230.36022)
		(width 0.16002)
		(layer "In11.Cu")
		(net "M_F_CPU0_SA_DQS_DP<8>")
	)
	(segment
		(start 301.303944 -230.36022)
		(end 301.834042 -230.890318)
		(width 0.16002)
		(layer "In11.Cu")
		(net "M_F_CPU0_SA_DQS_DP<8>")
	)
	(segment
		(start 330.392532 -242.539012)
		(end 330.400914 -242.534186)
		(width 0.09525)
		(layer "In11.Cu")
		(net "M_F_CPU0_SA_DQS_DP<8>")
	)
	(segment
		(start 266.624308 -230.327962)
		(end 267.104368 -230.327962)
		(width 0.16002)
		(layer "In11.Cu")
		(net "M_F_CPU0_SA_DQS_DP<8>")
	)
	(segment
		(start 296.926 -230.890318)
		(end 297.40352 -230.890318)
		(width 0.16002)
		(layer "In11.Cu")
		(net "M_F_CPU0_SA_DQS_DP<8>")
	)
	(segment
		(start 304.94732 -230.890318)
		(end 305.831494 -230.006144)
		(width 0.16002)
		(layer "In11.Cu")
		(net "M_F_CPU0_SA_DQS_DP<8>")
	)
	(segment
		(start 296.60596 -231.210358)
		(end 296.926 -230.890318)
		(width 0.16002)
		(layer "In11.Cu")
		(net "M_F_CPU0_SA_DQS_DP<8>")
	)
	(segment
		(start 267.104368 -230.327962)
		(end 267.221208 -230.211122)
		(width 0.16002)
		(layer "In11.Cu")
		(net "M_F_CPU0_SA_DQS_DP<8>")
	)
	(segment
		(start 326.632316 -242.539012)
		(end 326.644254 -242.532154)
		(width 0.09525)
		(layer "In11.Cu")
		(net "M_F_CPU0_SA_DQS_DP<8>")
	)
	(segment
		(start 275.957538 -230.006144)
		(end 276.311614 -230.36022)
		(width 0.16002)
		(layer "In11.Cu")
		(net "M_F_CPU0_SA_DQS_DP<8>")
	)
	(segment
		(start 272.01114 -231.210358)
		(end 273.973798 -231.210358)
		(width 0.16002)
		(layer "In11.Cu")
		(net "M_F_CPU0_SA_DQS_DP<8>")
	)
	(segment
		(start 301.834042 -230.890318)
		(end 304.94732 -230.890318)
		(width 0.16002)
		(layer "In11.Cu")
		(net "M_F_CPU0_SA_DQS_DP<8>")
	)
	(segment
		(start 274.293838 -230.890318)
		(end 274.771358 -230.890318)
		(width 0.16002)
		(layer "In11.Cu")
		(net "M_F_CPU0_SA_DQS_DP<8>")
	)
	(segment
		(start 271.192752 -230.39197)
		(end 272.01114 -231.210358)
		(width 0.16002)
		(layer "In11.Cu")
		(net "M_F_CPU0_SA_DQS_DP<8>")
	)
	(segment
		(start 267.221208 -230.211122)
		(end 267.701268 -230.211122)
		(width 0.16002)
		(layer "In11.Cu")
		(net "M_F_CPU0_SA_DQS_DP<8>")
	)
	(segment
		(start 268.802612 -230.39197)
		(end 271.192752 -230.39197)
		(width 0.16002)
		(layer "In11.Cu")
		(net "M_F_CPU0_SA_DQS_DP<8>")
	)
	(segment
		(start 329.821286 -242.534186)
		(end 329.829668 -242.539012)
		(width 0.09525)
		(layer "In11.Cu")
		(net "M_F_CPU0_SA_DQS_DP<8>")
	)
	(segment
		(start 323.979794 -241.536728)
		(end 324.600316 -242.15725)
		(width 0.09525)
		(layer "In11.Cu")
		(net "M_F_CPU0_SA_DQS_DP<8>")
	)
	(segment
		(start 316.60592 -241.59591)
		(end 323.722238 -241.59591)
		(width 0.16002)
		(layer "In11.Cu")
		(net "M_F_CPU0_SA_DQS_DP<8>")
	)
	(segment
		(start 290.74364 -230.006144)
		(end 291.045646 -230.006144)
		(width 0.16002)
		(layer "In11.Cu")
		(net "M_F_CPU0_SA_DQS_DP<8>")
	)
	(segment
		(start 283.199586 -230.006144)
		(end 283.501592 -230.006144)
		(width 0.16002)
		(layer "In11.Cu")
		(net "M_F_CPU0_SA_DQS_DP<8>")
	)
	(segment
		(start 281.517852 -231.210358)
		(end 281.837892 -230.890318)
		(width 0.16002)
		(layer "In11.Cu")
		(net "M_F_CPU0_SA_DQS_DP<8>")
	)
	(segment
		(start 306.68849 -230.006144)
		(end 310.367934 -233.685588)
		(width 0.16002)
		(layer "In11.Cu")
		(net "M_F_CPU0_SA_DQS_DP<8>")
	)
	(segment
		(start 278.671782 -230.36022)
		(end 279.52192 -231.210358)
		(width 0.16002)
		(layer "In11.Cu")
		(net "M_F_CPU0_SA_DQS_DP<8>")
	)
	(segment
		(start 324.600316 -242.15725)
		(end 325.338694 -242.15725)
		(width 0.09525)
		(layer "In11.Cu")
		(net "M_F_CPU0_SA_DQS_DP<8>")
	)
	(segment
		(start 323.74586 -241.59591)
		(end 323.805042 -241.536728)
		(width 0.09525)
		(layer "In11.Cu")
		(net "M_F_CPU0_SA_DQS_DP<8>")
	)
	(segment
		(start 289.381946 -230.890318)
		(end 289.859466 -230.890318)
		(width 0.16002)
		(layer "In11.Cu")
		(net "M_F_CPU0_SA_DQS_DP<8>")
	)
	(arc
		(start 332.27264 -242.539012)
		(mid 332.461108 -242.488335)
		(end 332.649576 -242.539012)
		(width 0.09525)
		(layer "In11.Cu")
		(net "M_F_CPU0_SA_DQS_DP<8>")
	)
	(arc
		(start 327.57237 -242.539012)
		(mid 327.761092 -242.488208)
		(end 327.949814 -242.539012)
		(width 0.09525)
		(layer "In11.Cu")
		(net "M_F_CPU0_SA_DQS_DP<8>")
	)
	(arc
		(start 327.019666 -242.545108)
		(mid 327.296828 -242.614908)
		(end 327.57237 -242.539012)
		(width 0.09525)
		(layer "In11.Cu")
		(net "M_F_CPU0_SA_DQS_DP<8>")
	)
	(arc
		(start 331.709776 -242.539012)
		(mid 331.991208 -242.614767)
		(end 332.27264 -242.539012)
		(width 0.09525)
		(layer "In11.Cu")
		(net "M_F_CPU0_SA_DQS_DP<8>")
	)
	(arc
		(start 333.21244 -242.539012)
		(mid 333.369038 -242.489723)
		(end 333.531718 -242.511834)
		(width 0.09525)
		(layer "In11.Cu")
		(net "M_F_CPU0_SA_DQS_DP<8>")
	)
	(arc
		(start 329.452478 -242.539012)
		(mid 329.636253 -242.48824)
		(end 329.821286 -242.534186)
		(width 0.09525)
		(layer "In11.Cu")
		(net "M_F_CPU0_SA_DQS_DP<8>")
	)
	(arc
		(start 331.340968 -242.534186)
		(mid 331.526 -242.488272)
		(end 331.709776 -242.539012)
		(width 0.09525)
		(layer "In11.Cu")
		(net "M_F_CPU0_SA_DQS_DP<8>")
	)
	(arc
		(start 325.880476 -242.48745)
		(mid 325.978373 -242.500736)
		(end 326.069452 -242.539012)
		(width 0.09525)
		(layer "In11.Cu")
		(net "M_F_CPU0_SA_DQS_DP<8>")
	)
	(arc
		(start 326.644254 -242.532154)
		(mid 326.827635 -242.488323)
		(end 327.009252 -242.539012)
		(width 0.09525)
		(layer "In11.Cu")
		(net "M_F_CPU0_SA_DQS_DP<8>")
	)
	(arc
		(start 330.769722 -242.539012)
		(mid 331.051154 -242.614767)
		(end 331.332586 -242.539012)
		(width 0.09525)
		(layer "In11.Cu")
		(net "M_F_CPU0_SA_DQS_DP<8>")
	)
	(arc
		(start 329.829668 -242.539012)
		(mid 330.1111 -242.614767)
		(end 330.392532 -242.539012)
		(width 0.09525)
		(layer "In11.Cu")
		(net "M_F_CPU0_SA_DQS_DP<8>")
	)
	(arc
		(start 330.400914 -242.534186)
		(mid 330.585946 -242.488272)
		(end 330.769722 -242.539012)
		(width 0.09525)
		(layer "In11.Cu")
		(net "M_F_CPU0_SA_DQS_DP<8>")
	)
	(arc
		(start 328.889614 -242.539012)
		(mid 329.171046 -242.614767)
		(end 329.452478 -242.539012)
		(width 0.09525)
		(layer "In11.Cu")
		(net "M_F_CPU0_SA_DQS_DP<8>")
	)
	(arc
		(start 326.069452 -242.539012)
		(mid 326.34238 -242.614826)
		(end 326.617584 -242.547648)
		(width 0.09525)
		(layer "In11.Cu")
		(net "M_F_CPU0_SA_DQS_DP<8>")
	)
	(arc
		(start 328.512678 -242.539012)
		(mid 328.701146 -242.488335)
		(end 328.889614 -242.539012)
		(width 0.09525)
		(layer "In11.Cu")
		(net "M_F_CPU0_SA_DQS_DP<8>")
	)
	(arc
		(start 332.649576 -242.539012)
		(mid 332.931008 -242.614767)
		(end 333.21244 -242.539012)
		(width 0.09525)
		(layer "In11.Cu")
		(net "M_F_CPU0_SA_DQS_DP<8>")
	)
	(arc
		(start 327.949814 -242.539012)
		(mid 328.231246 -242.614767)
		(end 328.512678 -242.539012)
		(width 0.09525)
		(layer "In11.Cu")
		(net "M_F_CPU0_SA_DQS_DP<8>")
	)
	(segment
		(start 333.868014 -238.270034)
		(end 333.401162 -238.004096)
		(width 0.12954)
		(layer "F.Cu")
		(net "M_F_CPU0_SA_DQS_DP<7>")
	)
	(segment
		(start 267.701268 -220.861128)
		(end 267.866876 -220.69552)
		(width 0.16002)
		(layer "In11.Cu")
		(net "M_F_CPU0_SA_DQS_DP<7>")
	)
	(segment
		(start 326.620886 -237.68558)
		(end 326.644254 -237.672118)
		(width 0.09525)
		(layer "In11.Cu")
		(net "M_F_CPU0_SA_DQS_DP<7>")
	)
	(segment
		(start 333.531718 -237.651798)
		(end 333.555086 -237.738666)
		(width 0.09525)
		(layer "In11.Cu")
		(net "M_F_CPU0_SA_DQS_DP<7>")
	)
	(segment
		(start 333.555086 -237.738666)
		(end 333.401162 -238.004096)
		(width 0.09525)
		(layer "In11.Cu")
		(net "M_F_CPU0_SA_DQS_DP<7>")
	)
	(segment
		(start 296.926 -221.540324)
		(end 297.40352 -221.540324)
		(width 0.16002)
		(layer "In11.Cu")
		(net "M_F_CPU0_SA_DQS_DP<7>")
	)
	(segment
		(start 291.399722 -221.010226)
		(end 293.75989 -221.010226)
		(width 0.16002)
		(layer "In11.Cu")
		(net "M_F_CPU0_SA_DQS_DP<7>")
	)
	(segment
		(start 273.973798 -221.860364)
		(end 274.293838 -221.540324)
		(width 0.16002)
		(layer "In11.Cu")
		(net "M_F_CPU0_SA_DQS_DP<7>")
	)
	(segment
		(start 283.199586 -220.65615)
		(end 283.501592 -220.65615)
		(width 0.16002)
		(layer "In11.Cu")
		(net "M_F_CPU0_SA_DQS_DP<7>")
	)
	(segment
		(start 326.61987 -237.686088)
		(end 326.620886 -237.68558)
		(width 0.09525)
		(layer "In11.Cu")
		(net "M_F_CPU0_SA_DQS_DP<7>")
	)
	(segment
		(start 323.895974 -235.95584)
		(end 323.919596 -235.95584)
		(width 0.09525)
		(layer "In11.Cu")
		(net "M_F_CPU0_SA_DQS_DP<7>")
	)
	(segment
		(start 289.381946 -221.540324)
		(end 289.859466 -221.540324)
		(width 0.16002)
		(layer "In11.Cu")
		(net "M_F_CPU0_SA_DQS_DP<7>")
	)
	(segment
		(start 301.303944 -221.010226)
		(end 301.834042 -221.540324)
		(width 0.16002)
		(layer "In11.Cu")
		(net "M_F_CPU0_SA_DQS_DP<7>")
	)
	(segment
		(start 306.26558 -222.076772)
		(end 306.51196 -221.830392)
		(width 0.16002)
		(layer "In11.Cu")
		(net "M_F_CPU0_SA_DQS_DP<7>")
	)
	(segment
		(start 324.139306 -235.896912)
		(end 324.529704 -236.28731)
		(width 0.09525)
		(layer "In11.Cu")
		(net "M_F_CPU0_SA_DQS_DP<7>")
	)
	(segment
		(start 267.086588 -220.977968)
		(end 267.203428 -220.861128)
		(width 0.16002)
		(layer "In11.Cu")
		(net "M_F_CPU0_SA_DQS_DP<7>")
	)
	(segment
		(start 305.585876 -222.076772)
		(end 306.26558 -222.076772)
		(width 0.16002)
		(layer "In11.Cu")
		(net "M_F_CPU0_SA_DQS_DP<7>")
	)
	(segment
		(start 330.392532 -237.678976)
		(end 330.400914 -237.67415)
		(width 0.09525)
		(layer "In11.Cu")
		(net "M_F_CPU0_SA_DQS_DP<7>")
	)
	(segment
		(start 275.957538 -220.65615)
		(end 276.311614 -221.010226)
		(width 0.16002)
		(layer "In11.Cu")
		(net "M_F_CPU0_SA_DQS_DP<7>")
	)
	(segment
		(start 324.917054 -236.28731)
		(end 325.145654 -236.51591)
		(width 0.09525)
		(layer "In11.Cu")
		(net "M_F_CPU0_SA_DQS_DP<7>")
	)
	(segment
		(start 306.51196 -221.830392)
		(end 307.742082 -221.830392)
		(width 0.16002)
		(layer "In11.Cu")
		(net "M_F_CPU0_SA_DQS_DP<7>")
	)
	(segment
		(start 298.287694 -220.65615)
		(end 298.5897 -220.65615)
		(width 0.16002)
		(layer "In11.Cu")
		(net "M_F_CPU0_SA_DQS_DP<7>")
	)
	(segment
		(start 289.859466 -221.540324)
		(end 290.74364 -220.65615)
		(width 0.16002)
		(layer "In11.Cu")
		(net "M_F_CPU0_SA_DQS_DP<7>")
	)
	(segment
		(start 298.943776 -221.010226)
		(end 301.303944 -221.010226)
		(width 0.16002)
		(layer "In11.Cu")
		(net "M_F_CPU0_SA_DQS_DP<7>")
	)
	(segment
		(start 321.337178 -235.95584)
		(end 323.895974 -235.95584)
		(width 0.16002)
		(layer "In11.Cu")
		(net "M_F_CPU0_SA_DQS_DP<7>")
	)
	(segment
		(start 307.742082 -221.830392)
		(end 310.300878 -224.389188)
		(width 0.16002)
		(layer "In11.Cu")
		(net "M_F_CPU0_SA_DQS_DP<7>")
	)
	(segment
		(start 305.049428 -221.540324)
		(end 305.585876 -222.076772)
		(width 0.16002)
		(layer "In11.Cu")
		(net "M_F_CPU0_SA_DQS_DP<7>")
	)
	(segment
		(start 331.332586 -237.678976)
		(end 331.340968 -237.67415)
		(width 0.09525)
		(layer "In11.Cu")
		(net "M_F_CPU0_SA_DQS_DP<7>")
	)
	(segment
		(start 274.293838 -221.540324)
		(end 274.771358 -221.540324)
		(width 0.16002)
		(layer "In11.Cu")
		(net "M_F_CPU0_SA_DQS_DP<7>")
	)
	(segment
		(start 298.5897 -220.65615)
		(end 298.943776 -221.010226)
		(width 0.16002)
		(layer "In11.Cu")
		(net "M_F_CPU0_SA_DQS_DP<7>")
	)
	(segment
		(start 324.529704 -236.28731)
		(end 324.917054 -236.28731)
		(width 0.09525)
		(layer "In11.Cu")
		(net "M_F_CPU0_SA_DQS_DP<7>")
	)
	(segment
		(start 327.009252 -237.678976)
		(end 327.019666 -237.685072)
		(width 0.09525)
		(layer "In11.Cu")
		(net "M_F_CPU0_SA_DQS_DP<7>")
	)
	(segment
		(start 281.517852 -221.860364)
		(end 281.837892 -221.540324)
		(width 0.16002)
		(layer "In11.Cu")
		(net "M_F_CPU0_SA_DQS_DP<7>")
	)
	(segment
		(start 278.671782 -221.010226)
		(end 279.52192 -221.860364)
		(width 0.16002)
		(layer "In11.Cu")
		(net "M_F_CPU0_SA_DQS_DP<7>")
	)
	(segment
		(start 272.01114 -221.860364)
		(end 273.973798 -221.860364)
		(width 0.16002)
		(layer "In11.Cu")
		(net "M_F_CPU0_SA_DQS_DP<7>")
	)
	(segment
		(start 281.837892 -221.540324)
		(end 282.315412 -221.540324)
		(width 0.16002)
		(layer "In11.Cu")
		(net "M_F_CPU0_SA_DQS_DP<7>")
	)
	(segment
		(start 265.54811 -221.13494)
		(end 265.821922 -220.861128)
		(width 0.16002)
		(layer "In11.Cu")
		(net "M_F_CPU0_SA_DQS_DP<7>")
	)
	(segment
		(start 325.145654 -236.51591)
		(end 325.145654 -236.781594)
		(width 0.09525)
		(layer "In11.Cu")
		(net "M_F_CPU0_SA_DQS_DP<7>")
	)
	(segment
		(start 266.489688 -220.861128)
		(end 266.606528 -220.977968)
		(width 0.16002)
		(layer "In11.Cu")
		(net "M_F_CPU0_SA_DQS_DP<7>")
	)
	(segment
		(start 283.855668 -221.010226)
		(end 286.215836 -221.010226)
		(width 0.16002)
		(layer "In11.Cu")
		(net "M_F_CPU0_SA_DQS_DP<7>")
	)
	(segment
		(start 265.821922 -220.861128)
		(end 266.489688 -220.861128)
		(width 0.16002)
		(layer "In11.Cu")
		(net "M_F_CPU0_SA_DQS_DP<7>")
	)
	(segment
		(start 282.315412 -221.540324)
		(end 283.199586 -220.65615)
		(width 0.16002)
		(layer "In11.Cu")
		(net "M_F_CPU0_SA_DQS_DP<7>")
	)
	(segment
		(start 291.045646 -220.65615)
		(end 291.399722 -221.010226)
		(width 0.16002)
		(layer "In11.Cu")
		(net "M_F_CPU0_SA_DQS_DP<7>")
	)
	(segment
		(start 310.300878 -224.91954)
		(end 321.337178 -235.95584)
		(width 0.16002)
		(layer "In11.Cu")
		(net "M_F_CPU0_SA_DQS_DP<7>")
	)
	(segment
		(start 296.60596 -221.860364)
		(end 296.926 -221.540324)
		(width 0.16002)
		(layer "In11.Cu")
		(net "M_F_CPU0_SA_DQS_DP<7>")
	)
	(segment
		(start 271.192752 -221.041976)
		(end 272.01114 -221.860364)
		(width 0.16002)
		(layer "In11.Cu")
		(net "M_F_CPU0_SA_DQS_DP<7>")
	)
	(segment
		(start 275.655532 -220.65615)
		(end 275.957538 -220.65615)
		(width 0.16002)
		(layer "In11.Cu")
		(net "M_F_CPU0_SA_DQS_DP<7>")
	)
	(segment
		(start 329.821286 -237.67415)
		(end 329.829668 -237.678976)
		(width 0.09525)
		(layer "In11.Cu")
		(net "M_F_CPU0_SA_DQS_DP<7>")
	)
	(segment
		(start 301.834042 -221.540324)
		(end 305.049428 -221.540324)
		(width 0.16002)
		(layer "In11.Cu")
		(net "M_F_CPU0_SA_DQS_DP<7>")
	)
	(segment
		(start 297.40352 -221.540324)
		(end 298.287694 -220.65615)
		(width 0.16002)
		(layer "In11.Cu")
		(net "M_F_CPU0_SA_DQS_DP<7>")
	)
	(segment
		(start 267.866876 -220.69552)
		(end 268.456156 -220.69552)
		(width 0.16002)
		(layer "In11.Cu")
		(net "M_F_CPU0_SA_DQS_DP<7>")
	)
	(segment
		(start 276.311614 -221.010226)
		(end 278.671782 -221.010226)
		(width 0.16002)
		(layer "In11.Cu")
		(net "M_F_CPU0_SA_DQS_DP<7>")
	)
	(segment
		(start 325.145654 -236.781594)
		(end 325.954644 -237.590584)
		(width 0.09525)
		(layer "In11.Cu")
		(net "M_F_CPU0_SA_DQS_DP<7>")
	)
	(segment
		(start 268.802612 -221.041976)
		(end 271.192752 -221.041976)
		(width 0.16002)
		(layer "In11.Cu")
		(net "M_F_CPU0_SA_DQS_DP<7>")
	)
	(segment
		(start 283.501592 -220.65615)
		(end 283.855668 -221.010226)
		(width 0.16002)
		(layer "In11.Cu")
		(net "M_F_CPU0_SA_DQS_DP<7>")
	)
	(segment
		(start 279.52192 -221.860364)
		(end 281.517852 -221.860364)
		(width 0.16002)
		(layer "In11.Cu")
		(net "M_F_CPU0_SA_DQS_DP<7>")
	)
	(segment
		(start 323.919596 -235.95584)
		(end 323.978524 -235.896912)
		(width 0.09525)
		(layer "In11.Cu")
		(net "M_F_CPU0_SA_DQS_DP<7>")
	)
	(segment
		(start 323.978524 -235.896912)
		(end 324.139306 -235.896912)
		(width 0.09525)
		(layer "In11.Cu")
		(net "M_F_CPU0_SA_DQS_DP<7>")
	)
	(segment
		(start 286.215836 -221.010226)
		(end 287.065974 -221.860364)
		(width 0.16002)
		(layer "In11.Cu")
		(net "M_F_CPU0_SA_DQS_DP<7>")
	)
	(segment
		(start 294.610028 -221.860364)
		(end 296.60596 -221.860364)
		(width 0.16002)
		(layer "In11.Cu")
		(net "M_F_CPU0_SA_DQS_DP<7>")
	)
	(segment
		(start 310.300878 -224.389188)
		(end 310.300878 -224.91954)
		(width 0.16002)
		(layer "In11.Cu")
		(net "M_F_CPU0_SA_DQS_DP<7>")
	)
	(segment
		(start 293.75989 -221.010226)
		(end 294.610028 -221.860364)
		(width 0.16002)
		(layer "In11.Cu")
		(net "M_F_CPU0_SA_DQS_DP<7>")
	)
	(segment
		(start 267.203428 -220.861128)
		(end 267.701268 -220.861128)
		(width 0.16002)
		(layer "In11.Cu")
		(net "M_F_CPU0_SA_DQS_DP<7>")
	)
	(segment
		(start 289.061906 -221.860364)
		(end 289.381946 -221.540324)
		(width 0.16002)
		(layer "In11.Cu")
		(net "M_F_CPU0_SA_DQS_DP<7>")
	)
	(segment
		(start 290.74364 -220.65615)
		(end 291.045646 -220.65615)
		(width 0.16002)
		(layer "In11.Cu")
		(net "M_F_CPU0_SA_DQS_DP<7>")
	)
	(segment
		(start 287.065974 -221.860364)
		(end 289.061906 -221.860364)
		(width 0.16002)
		(layer "In11.Cu")
		(net "M_F_CPU0_SA_DQS_DP<7>")
	)
	(segment
		(start 266.606528 -220.977968)
		(end 267.086588 -220.977968)
		(width 0.16002)
		(layer "In11.Cu")
		(net "M_F_CPU0_SA_DQS_DP<7>")
	)
	(segment
		(start 274.771358 -221.540324)
		(end 275.655532 -220.65615)
		(width 0.16002)
		(layer "In11.Cu")
		(net "M_F_CPU0_SA_DQS_DP<7>")
	)
	(segment
		(start 268.456156 -220.69552)
		(end 268.802612 -221.041976)
		(width 0.16002)
		(layer "In11.Cu")
		(net "M_F_CPU0_SA_DQS_DP<7>")
	)
	(segment
		(start 326.617584 -237.687612)
		(end 326.61987 -237.686088)
		(width 0.09525)
		(layer "In11.Cu")
		(net "M_F_CPU0_SA_DQS_DP<7>")
	)
	(arc
		(start 327.949814 -237.678976)
		(mid 328.231246 -237.754731)
		(end 328.512678 -237.678976)
		(width 0.09525)
		(layer "In11.Cu")
		(net "M_F_CPU0_SA_DQS_DP<7>")
	)
	(arc
		(start 328.889614 -237.678976)
		(mid 329.171046 -237.754731)
		(end 329.452478 -237.678976)
		(width 0.09525)
		(layer "In11.Cu")
		(net "M_F_CPU0_SA_DQS_DP<7>")
	)
	(arc
		(start 328.512678 -237.678976)
		(mid 328.701146 -237.628299)
		(end 328.889614 -237.678976)
		(width 0.09525)
		(layer "In11.Cu")
		(net "M_F_CPU0_SA_DQS_DP<7>")
	)
	(arc
		(start 326.644254 -237.672118)
		(mid 326.827635 -237.628287)
		(end 327.009252 -237.678976)
		(width 0.09525)
		(layer "In11.Cu")
		(net "M_F_CPU0_SA_DQS_DP<7>")
	)
	(arc
		(start 331.340968 -237.67415)
		(mid 331.526 -237.628236)
		(end 331.709776 -237.678976)
		(width 0.09525)
		(layer "In11.Cu")
		(net "M_F_CPU0_SA_DQS_DP<7>")
	)
	(arc
		(start 329.829668 -237.678976)
		(mid 330.1111 -237.754731)
		(end 330.392532 -237.678976)
		(width 0.09525)
		(layer "In11.Cu")
		(net "M_F_CPU0_SA_DQS_DP<7>")
	)
	(arc
		(start 330.769722 -237.678976)
		(mid 331.051154 -237.754731)
		(end 331.332586 -237.678976)
		(width 0.09525)
		(layer "In11.Cu")
		(net "M_F_CPU0_SA_DQS_DP<7>")
	)
	(arc
		(start 331.709776 -237.678976)
		(mid 331.991208 -237.754731)
		(end 332.27264 -237.678976)
		(width 0.09525)
		(layer "In11.Cu")
		(net "M_F_CPU0_SA_DQS_DP<7>")
	)
	(arc
		(start 325.954644 -237.590584)
		(mid 326.270019 -237.748919)
		(end 326.617584 -237.687612)
		(width 0.09525)
		(layer "In11.Cu")
		(net "M_F_CPU0_SA_DQS_DP<7>")
	)
	(arc
		(start 332.27264 -237.678976)
		(mid 332.461108 -237.628299)
		(end 332.649576 -237.678976)
		(width 0.09525)
		(layer "In11.Cu")
		(net "M_F_CPU0_SA_DQS_DP<7>")
	)
	(arc
		(start 330.400914 -237.67415)
		(mid 330.585946 -237.628236)
		(end 330.769722 -237.678976)
		(width 0.09525)
		(layer "In11.Cu")
		(net "M_F_CPU0_SA_DQS_DP<7>")
	)
	(arc
		(start 329.452478 -237.678976)
		(mid 329.636253 -237.628204)
		(end 329.821286 -237.67415)
		(width 0.09525)
		(layer "In11.Cu")
		(net "M_F_CPU0_SA_DQS_DP<7>")
	)
	(arc
		(start 327.019666 -237.685072)
		(mid 327.296828 -237.754872)
		(end 327.57237 -237.678976)
		(width 0.09525)
		(layer "In11.Cu")
		(net "M_F_CPU0_SA_DQS_DP<7>")
	)
	(arc
		(start 333.21244 -237.678976)
		(mid 333.369038 -237.629687)
		(end 333.531718 -237.651798)
		(width 0.09525)
		(layer "In11.Cu")
		(net "M_F_CPU0_SA_DQS_DP<7>")
	)
	(arc
		(start 327.57237 -237.678976)
		(mid 327.761092 -237.628172)
		(end 327.949814 -237.678976)
		(width 0.09525)
		(layer "In11.Cu")
		(net "M_F_CPU0_SA_DQS_DP<7>")
	)
	(arc
		(start 332.649576 -237.678976)
		(mid 332.931008 -237.754731)
		(end 333.21244 -237.678976)
		(width 0.09525)
		(layer "In11.Cu")
		(net "M_F_CPU0_SA_DQS_DP<7>")
	)
	(segment
		(start 333.868014 -233.409998)
		(end 333.401162 -233.14406)
		(width 0.12954)
		(layer "F.Cu")
		(net "M_F_CPU0_SA_DQS_DP<6>")
	)
	(segment
		(start 325.332344 -232.108248)
		(end 325.954644 -232.730548)
		(width 0.09525)
		(layer "In11.Cu")
		(net "M_F_CPU0_SA_DQS_DP<6>")
	)
	(segment
		(start 307.295042 -211.306156)
		(end 310.780938 -214.792052)
		(width 0.16002)
		(layer "In11.Cu")
		(net "M_F_CPU0_SA_DQS_DP<6>")
	)
	(segment
		(start 324.774306 -231.22509)
		(end 325.040498 -231.22509)
		(width 0.09525)
		(layer "In11.Cu")
		(net "M_F_CPU0_SA_DQS_DP<6>")
	)
	(segment
		(start 272.01114 -212.51037)
		(end 273.973798 -212.51037)
		(width 0.16002)
		(layer "In11.Cu")
		(net "M_F_CPU0_SA_DQS_DP<6>")
	)
	(segment
		(start 275.655532 -211.306156)
		(end 275.957538 -211.306156)
		(width 0.16002)
		(layer "In11.Cu")
		(net "M_F_CPU0_SA_DQS_DP<6>")
	)
	(segment
		(start 310.780938 -216.132156)
		(end 315.995558 -221.346776)
		(width 0.16002)
		(layer "In11.Cu")
		(net "M_F_CPU0_SA_DQS_DP<6>")
	)
	(segment
		(start 283.501592 -211.306156)
		(end 283.855668 -211.660232)
		(width 0.16002)
		(layer "In11.Cu")
		(net "M_F_CPU0_SA_DQS_DP<6>")
	)
	(segment
		(start 331.332586 -232.81894)
		(end 331.340968 -232.814114)
		(width 0.09525)
		(layer "In11.Cu")
		(net "M_F_CPU0_SA_DQS_DP<6>")
	)
	(segment
		(start 298.943776 -211.660232)
		(end 301.303944 -211.660232)
		(width 0.16002)
		(layer "In11.Cu")
		(net "M_F_CPU0_SA_DQS_DP<6>")
	)
	(segment
		(start 310.780938 -214.792052)
		(end 310.780938 -216.132156)
		(width 0.16002)
		(layer "In11.Cu")
		(net "M_F_CPU0_SA_DQS_DP<6>")
	)
	(segment
		(start 282.315412 -212.19033)
		(end 283.199586 -211.306156)
		(width 0.16002)
		(layer "In11.Cu")
		(net "M_F_CPU0_SA_DQS_DP<6>")
	)
	(segment
		(start 298.287694 -211.306156)
		(end 298.5897 -211.306156)
		(width 0.16002)
		(layer "In11.Cu")
		(net "M_F_CPU0_SA_DQS_DP<6>")
	)
	(segment
		(start 293.75989 -211.660232)
		(end 294.610028 -212.51037)
		(width 0.16002)
		(layer "In11.Cu")
		(net "M_F_CPU0_SA_DQS_DP<6>")
	)
	(segment
		(start 267.221208 -211.511134)
		(end 267.701268 -211.511134)
		(width 0.16002)
		(layer "In11.Cu")
		(net "M_F_CPU0_SA_DQS_DP<6>")
	)
	(segment
		(start 301.303944 -211.660232)
		(end 301.834042 -212.19033)
		(width 0.16002)
		(layer "In11.Cu")
		(net "M_F_CPU0_SA_DQS_DP<6>")
	)
	(segment
		(start 274.771358 -212.19033)
		(end 275.655532 -211.306156)
		(width 0.16002)
		(layer "In11.Cu")
		(net "M_F_CPU0_SA_DQS_DP<6>")
	)
	(segment
		(start 268.456156 -211.345526)
		(end 268.802612 -211.691982)
		(width 0.16002)
		(layer "In11.Cu")
		(net "M_F_CPU0_SA_DQS_DP<6>")
	)
	(segment
		(start 266.507468 -211.511134)
		(end 266.624308 -211.627974)
		(width 0.16002)
		(layer "In11.Cu")
		(net "M_F_CPU0_SA_DQS_DP<6>")
	)
	(segment
		(start 265.821922 -211.511134)
		(end 266.507468 -211.511134)
		(width 0.16002)
		(layer "In11.Cu")
		(net "M_F_CPU0_SA_DQS_DP<6>")
	)
	(segment
		(start 325.040498 -231.22509)
		(end 325.332344 -231.516936)
		(width 0.09525)
		(layer "In11.Cu")
		(net "M_F_CPU0_SA_DQS_DP<6>")
	)
	(segment
		(start 324.104508 -230.241602)
		(end 324.199758 -230.336852)
		(width 0.09525)
		(layer "In11.Cu")
		(net "M_F_CPU0_SA_DQS_DP<6>")
	)
	(segment
		(start 276.311614 -211.660232)
		(end 278.671782 -211.660232)
		(width 0.16002)
		(layer "In11.Cu")
		(net "M_F_CPU0_SA_DQS_DP<6>")
	)
	(segment
		(start 294.610028 -212.51037)
		(end 296.60596 -212.51037)
		(width 0.16002)
		(layer "In11.Cu")
		(net "M_F_CPU0_SA_DQS_DP<6>")
	)
	(segment
		(start 283.199586 -211.306156)
		(end 283.501592 -211.306156)
		(width 0.16002)
		(layer "In11.Cu")
		(net "M_F_CPU0_SA_DQS_DP<6>")
	)
	(segment
		(start 267.866876 -211.345526)
		(end 268.456156 -211.345526)
		(width 0.16002)
		(layer "In11.Cu")
		(net "M_F_CPU0_SA_DQS_DP<6>")
	)
	(segment
		(start 275.957538 -211.306156)
		(end 276.311614 -211.660232)
		(width 0.16002)
		(layer "In11.Cu")
		(net "M_F_CPU0_SA_DQS_DP<6>")
	)
	(segment
		(start 333.555086 -232.87863)
		(end 333.401162 -233.14406)
		(width 0.09525)
		(layer "In11.Cu")
		(net "M_F_CPU0_SA_DQS_DP<6>")
	)
	(segment
		(start 265.54811 -211.784946)
		(end 265.821922 -211.511134)
		(width 0.16002)
		(layer "In11.Cu")
		(net "M_F_CPU0_SA_DQS_DP<6>")
	)
	(segment
		(start 273.973798 -212.51037)
		(end 274.293838 -212.19033)
		(width 0.16002)
		(layer "In11.Cu")
		(net "M_F_CPU0_SA_DQS_DP<6>")
	)
	(segment
		(start 290.74364 -211.306156)
		(end 291.045646 -211.306156)
		(width 0.16002)
		(layer "In11.Cu")
		(net "M_F_CPU0_SA_DQS_DP<6>")
	)
	(segment
		(start 301.834042 -212.19033)
		(end 304.94732 -212.19033)
		(width 0.16002)
		(layer "In11.Cu")
		(net "M_F_CPU0_SA_DQS_DP<6>")
	)
	(segment
		(start 289.859466 -212.19033)
		(end 290.74364 -211.306156)
		(width 0.16002)
		(layer "In11.Cu")
		(net "M_F_CPU0_SA_DQS_DP<6>")
	)
	(segment
		(start 298.5897 -211.306156)
		(end 298.943776 -211.660232)
		(width 0.16002)
		(layer "In11.Cu")
		(net "M_F_CPU0_SA_DQS_DP<6>")
	)
	(segment
		(start 286.215836 -211.660232)
		(end 287.065974 -212.51037)
		(width 0.16002)
		(layer "In11.Cu")
		(net "M_F_CPU0_SA_DQS_DP<6>")
	)
	(segment
		(start 267.701268 -211.511134)
		(end 267.866876 -211.345526)
		(width 0.16002)
		(layer "In11.Cu")
		(net "M_F_CPU0_SA_DQS_DP<6>")
	)
	(segment
		(start 281.837892 -212.19033)
		(end 282.315412 -212.19033)
		(width 0.16002)
		(layer "In11.Cu")
		(net "M_F_CPU0_SA_DQS_DP<6>")
	)
	(segment
		(start 323.919596 -230.30053)
		(end 323.978524 -230.241602)
		(width 0.09525)
		(layer "In11.Cu")
		(net "M_F_CPU0_SA_DQS_DP<6>")
	)
	(segment
		(start 279.52192 -212.51037)
		(end 281.517852 -212.51037)
		(width 0.16002)
		(layer "In11.Cu")
		(net "M_F_CPU0_SA_DQS_DP<6>")
	)
	(segment
		(start 323.614542 -230.30053)
		(end 323.895974 -230.30053)
		(width 0.16002)
		(layer "In11.Cu")
		(net "M_F_CPU0_SA_DQS_DP<6>")
	)
	(segment
		(start 287.065974 -212.51037)
		(end 289.061906 -212.51037)
		(width 0.16002)
		(layer "In11.Cu")
		(net "M_F_CPU0_SA_DQS_DP<6>")
	)
	(segment
		(start 267.104368 -211.627974)
		(end 267.221208 -211.511134)
		(width 0.16002)
		(layer "In11.Cu")
		(net "M_F_CPU0_SA_DQS_DP<6>")
	)
	(segment
		(start 291.399722 -211.660232)
		(end 293.75989 -211.660232)
		(width 0.16002)
		(layer "In11.Cu")
		(net "M_F_CPU0_SA_DQS_DP<6>")
	)
	(segment
		(start 329.821286 -232.814114)
		(end 329.829668 -232.81894)
		(width 0.09525)
		(layer "In11.Cu")
		(net "M_F_CPU0_SA_DQS_DP<6>")
	)
	(segment
		(start 296.60596 -212.51037)
		(end 296.926 -212.19033)
		(width 0.16002)
		(layer "In11.Cu")
		(net "M_F_CPU0_SA_DQS_DP<6>")
	)
	(segment
		(start 291.045646 -211.306156)
		(end 291.399722 -211.660232)
		(width 0.16002)
		(layer "In11.Cu")
		(net "M_F_CPU0_SA_DQS_DP<6>")
	)
	(segment
		(start 333.531718 -232.791762)
		(end 333.555086 -232.87863)
		(width 0.09525)
		(layer "In11.Cu")
		(net "M_F_CPU0_SA_DQS_DP<6>")
	)
	(segment
		(start 327.009252 -232.81894)
		(end 327.019666 -232.825036)
		(width 0.09525)
		(layer "In11.Cu")
		(net "M_F_CPU0_SA_DQS_DP<6>")
	)
	(segment
		(start 266.624308 -211.627974)
		(end 267.104368 -211.627974)
		(width 0.16002)
		(layer "In11.Cu")
		(net "M_F_CPU0_SA_DQS_DP<6>")
	)
	(segment
		(start 324.199758 -230.336852)
		(end 324.199758 -230.650542)
		(width 0.09525)
		(layer "In11.Cu")
		(net "M_F_CPU0_SA_DQS_DP<6>")
	)
	(segment
		(start 278.671782 -211.660232)
		(end 279.52192 -212.51037)
		(width 0.16002)
		(layer "In11.Cu")
		(net "M_F_CPU0_SA_DQS_DP<6>")
	)
	(segment
		(start 325.332344 -231.516936)
		(end 325.332344 -232.108248)
		(width 0.09525)
		(layer "In11.Cu")
		(net "M_F_CPU0_SA_DQS_DP<6>")
	)
	(segment
		(start 289.381946 -212.19033)
		(end 289.859466 -212.19033)
		(width 0.16002)
		(layer "In11.Cu")
		(net "M_F_CPU0_SA_DQS_DP<6>")
	)
	(segment
		(start 274.293838 -212.19033)
		(end 274.771358 -212.19033)
		(width 0.16002)
		(layer "In11.Cu")
		(net "M_F_CPU0_SA_DQS_DP<6>")
	)
	(segment
		(start 323.978524 -230.241602)
		(end 324.104508 -230.241602)
		(width 0.09525)
		(layer "In11.Cu")
		(net "M_F_CPU0_SA_DQS_DP<6>")
	)
	(segment
		(start 296.926 -212.19033)
		(end 297.40352 -212.19033)
		(width 0.16002)
		(layer "In11.Cu")
		(net "M_F_CPU0_SA_DQS_DP<6>")
	)
	(segment
		(start 283.855668 -211.660232)
		(end 286.215836 -211.660232)
		(width 0.16002)
		(layer "In11.Cu")
		(net "M_F_CPU0_SA_DQS_DP<6>")
	)
	(segment
		(start 281.517852 -212.51037)
		(end 281.837892 -212.19033)
		(width 0.16002)
		(layer "In11.Cu")
		(net "M_F_CPU0_SA_DQS_DP<6>")
	)
	(segment
		(start 268.802612 -211.691982)
		(end 271.192752 -211.691982)
		(width 0.16002)
		(layer "In11.Cu")
		(net "M_F_CPU0_SA_DQS_DP<6>")
	)
	(segment
		(start 315.995558 -222.681546)
		(end 323.614542 -230.30053)
		(width 0.16002)
		(layer "In11.Cu")
		(net "M_F_CPU0_SA_DQS_DP<6>")
	)
	(segment
		(start 324.199758 -230.650542)
		(end 324.774306 -231.22509)
		(width 0.09525)
		(layer "In11.Cu")
		(net "M_F_CPU0_SA_DQS_DP<6>")
	)
	(segment
		(start 315.995558 -221.346776)
		(end 315.995558 -222.681546)
		(width 0.16002)
		(layer "In11.Cu")
		(net "M_F_CPU0_SA_DQS_DP<6>")
	)
	(segment
		(start 326.617584 -232.827576)
		(end 326.644254 -232.812082)
		(width 0.09525)
		(layer "In11.Cu")
		(net "M_F_CPU0_SA_DQS_DP<6>")
	)
	(segment
		(start 323.895974 -230.30053)
		(end 323.919596 -230.30053)
		(width 0.09525)
		(layer "In11.Cu")
		(net "M_F_CPU0_SA_DQS_DP<6>")
	)
	(segment
		(start 289.061906 -212.51037)
		(end 289.381946 -212.19033)
		(width 0.16002)
		(layer "In11.Cu")
		(net "M_F_CPU0_SA_DQS_DP<6>")
	)
	(segment
		(start 271.192752 -211.691982)
		(end 272.01114 -212.51037)
		(width 0.16002)
		(layer "In11.Cu")
		(net "M_F_CPU0_SA_DQS_DP<6>")
	)
	(segment
		(start 297.40352 -212.19033)
		(end 298.287694 -211.306156)
		(width 0.16002)
		(layer "In11.Cu")
		(net "M_F_CPU0_SA_DQS_DP<6>")
	)
	(segment
		(start 330.392532 -232.81894)
		(end 330.400914 -232.814114)
		(width 0.09525)
		(layer "In11.Cu")
		(net "M_F_CPU0_SA_DQS_DP<6>")
	)
	(segment
		(start 305.831494 -211.306156)
		(end 307.295042 -211.306156)
		(width 0.16002)
		(layer "In11.Cu")
		(net "M_F_CPU0_SA_DQS_DP<6>")
	)
	(segment
		(start 304.94732 -212.19033)
		(end 305.831494 -211.306156)
		(width 0.16002)
		(layer "In11.Cu")
		(net "M_F_CPU0_SA_DQS_DP<6>")
	)
	(arc
		(start 329.829668 -232.81894)
		(mid 330.1111 -232.894695)
		(end 330.392532 -232.81894)
		(width 0.09525)
		(layer "In11.Cu")
		(net "M_F_CPU0_SA_DQS_DP<6>")
	)
	(arc
		(start 331.709776 -232.81894)
		(mid 331.991208 -232.894695)
		(end 332.27264 -232.81894)
		(width 0.09525)
		(layer "In11.Cu")
		(net "M_F_CPU0_SA_DQS_DP<6>")
	)
	(arc
		(start 330.400914 -232.814114)
		(mid 330.585946 -232.7682)
		(end 330.769722 -232.81894)
		(width 0.09525)
		(layer "In11.Cu")
		(net "M_F_CPU0_SA_DQS_DP<6>")
	)
	(arc
		(start 329.452478 -232.81894)
		(mid 329.636253 -232.768168)
		(end 329.821286 -232.814114)
		(width 0.09525)
		(layer "In11.Cu")
		(net "M_F_CPU0_SA_DQS_DP<6>")
	)
	(arc
		(start 328.889614 -232.81894)
		(mid 329.171046 -232.894695)
		(end 329.452478 -232.81894)
		(width 0.09525)
		(layer "In11.Cu")
		(net "M_F_CPU0_SA_DQS_DP<6>")
	)
	(arc
		(start 331.340968 -232.814114)
		(mid 331.526 -232.7682)
		(end 331.709776 -232.81894)
		(width 0.09525)
		(layer "In11.Cu")
		(net "M_F_CPU0_SA_DQS_DP<6>")
	)
	(arc
		(start 328.512678 -232.81894)
		(mid 328.701146 -232.768263)
		(end 328.889614 -232.81894)
		(width 0.09525)
		(layer "In11.Cu")
		(net "M_F_CPU0_SA_DQS_DP<6>")
	)
	(arc
		(start 327.949814 -232.81894)
		(mid 328.231246 -232.894695)
		(end 328.512678 -232.81894)
		(width 0.09525)
		(layer "In11.Cu")
		(net "M_F_CPU0_SA_DQS_DP<6>")
	)
	(arc
		(start 330.769722 -232.81894)
		(mid 331.051154 -232.894695)
		(end 331.332586 -232.81894)
		(width 0.09525)
		(layer "In11.Cu")
		(net "M_F_CPU0_SA_DQS_DP<6>")
	)
	(arc
		(start 326.069198 -232.81894)
		(mid 326.342269 -232.89488)
		(end 326.617584 -232.827576)
		(width 0.09525)
		(layer "In11.Cu")
		(net "M_F_CPU0_SA_DQS_DP<6>")
	)
	(arc
		(start 327.57237 -232.81894)
		(mid 327.761092 -232.768136)
		(end 327.949814 -232.81894)
		(width 0.09525)
		(layer "In11.Cu")
		(net "M_F_CPU0_SA_DQS_DP<6>")
	)
	(arc
		(start 327.019666 -232.825036)
		(mid 327.296828 -232.894836)
		(end 327.57237 -232.81894)
		(width 0.09525)
		(layer "In11.Cu")
		(net "M_F_CPU0_SA_DQS_DP<6>")
	)
	(arc
		(start 332.649576 -232.81894)
		(mid 332.931008 -232.894695)
		(end 333.21244 -232.81894)
		(width 0.09525)
		(layer "In11.Cu")
		(net "M_F_CPU0_SA_DQS_DP<6>")
	)
	(arc
		(start 333.21244 -232.81894)
		(mid 333.369038 -232.769651)
		(end 333.531718 -232.791762)
		(width 0.09525)
		(layer "In11.Cu")
		(net "M_F_CPU0_SA_DQS_DP<6>")
	)
	(arc
		(start 332.27264 -232.81894)
		(mid 332.461108 -232.768263)
		(end 332.649576 -232.81894)
		(width 0.09525)
		(layer "In11.Cu")
		(net "M_F_CPU0_SA_DQS_DP<6>")
	)
	(arc
		(start 325.954644 -232.730548)
		(mid 326.009054 -232.778461)
		(end 326.069198 -232.81894)
		(width 0.09525)
		(layer "In11.Cu")
		(net "M_F_CPU0_SA_DQS_DP<6>")
	)
	(arc
		(start 326.644254 -232.812082)
		(mid 326.827635 -232.768251)
		(end 327.009252 -232.81894)
		(width 0.09525)
		(layer "In11.Cu")
		(net "M_F_CPU0_SA_DQS_DP<6>")
	)
	(segment
		(start 333.868014 -228.550216)
		(end 333.401162 -228.284278)
		(width 0.12954)
		(layer "F.Cu")
		(net "M_F_CPU0_SA_DQS_DP<5>")
	)
	(segment
		(start 311.324498 -206.986632)
		(end 321.814698 -217.476832)
		(width 0.16002)
		(layer "In11.Cu")
		(net "M_F_CPU0_SA_DQS_DP<5>")
	)
	(segment
		(start 326.582278 -227.160836)
		(end 326.671432 -227.191316)
		(width 0.09525)
		(layer "In11.Cu")
		(net "M_F_CPU0_SA_DQS_DP<5>")
	)
	(segment
		(start 291.399722 -202.310238)
		(end 293.75989 -202.310238)
		(width 0.16002)
		(layer "In11.Cu")
		(net "M_F_CPU0_SA_DQS_DP<5>")
	)
	(segment
		(start 266.507468 -202.16114)
		(end 266.624308 -202.27798)
		(width 0.16002)
		(layer "In11.Cu")
		(net "M_F_CPU0_SA_DQS_DP<5>")
	)
	(segment
		(start 333.531718 -227.93198)
		(end 333.555086 -228.018848)
		(width 0.09525)
		(layer "In11.Cu")
		(net "M_F_CPU0_SA_DQS_DP<5>")
	)
	(segment
		(start 286.215836 -202.310238)
		(end 287.065974 -203.160376)
		(width 0.16002)
		(layer "In11.Cu")
		(net "M_F_CPU0_SA_DQS_DP<5>")
	)
	(segment
		(start 325.561706 -223.88703)
		(end 325.631302 -223.927416)
		(width 0.09525)
		(layer "In11.Cu")
		(net "M_F_CPU0_SA_DQS_DP<5>")
	)
	(segment
		(start 307.777388 -201.956162)
		(end 311.324498 -205.503272)
		(width 0.16002)
		(layer "In11.Cu")
		(net "M_F_CPU0_SA_DQS_DP<5>")
	)
	(segment
		(start 276.311614 -202.310238)
		(end 278.671782 -202.310238)
		(width 0.16002)
		(layer "In11.Cu")
		(net "M_F_CPU0_SA_DQS_DP<5>")
	)
	(segment
		(start 281.837892 -202.840336)
		(end 282.315412 -202.840336)
		(width 0.16002)
		(layer "In11.Cu")
		(net "M_F_CPU0_SA_DQS_DP<5>")
	)
	(segment
		(start 293.75989 -202.310238)
		(end 294.610028 -203.160376)
		(width 0.16002)
		(layer "In11.Cu")
		(net "M_F_CPU0_SA_DQS_DP<5>")
	)
	(segment
		(start 301.834042 -202.840336)
		(end 304.94732 -202.840336)
		(width 0.16002)
		(layer "In11.Cu")
		(net "M_F_CPU0_SA_DQS_DP<5>")
	)
	(segment
		(start 268.456156 -201.995532)
		(end 268.802612 -202.341988)
		(width 0.16002)
		(layer "In11.Cu")
		(net "M_F_CPU0_SA_DQS_DP<5>")
	)
	(segment
		(start 296.926 -202.840336)
		(end 297.40352 -202.840336)
		(width 0.16002)
		(layer "In11.Cu")
		(net "M_F_CPU0_SA_DQS_DP<5>")
	)
	(segment
		(start 333.555086 -228.018848)
		(end 333.401162 -228.284278)
		(width 0.09525)
		(layer "In11.Cu")
		(net "M_F_CPU0_SA_DQS_DP<5>")
	)
	(segment
		(start 268.802612 -202.341988)
		(end 269.282672 -202.341988)
		(width 0.16002)
		(layer "In11.Cu")
		(net "M_F_CPU0_SA_DQS_DP<5>")
	)
	(segment
		(start 265.821922 -202.16114)
		(end 266.507468 -202.16114)
		(width 0.16002)
		(layer "In11.Cu")
		(net "M_F_CPU0_SA_DQS_DP<5>")
	)
	(segment
		(start 265.54811 -202.434952)
		(end 265.821922 -202.16114)
		(width 0.16002)
		(layer "In11.Cu")
		(net "M_F_CPU0_SA_DQS_DP<5>")
	)
	(segment
		(start 282.315412 -202.840336)
		(end 283.199586 -201.956162)
		(width 0.16002)
		(layer "In11.Cu")
		(net "M_F_CPU0_SA_DQS_DP<5>")
	)
	(segment
		(start 289.859466 -202.840336)
		(end 290.74364 -201.956162)
		(width 0.16002)
		(layer "In11.Cu")
		(net "M_F_CPU0_SA_DQS_DP<5>")
	)
	(segment
		(start 269.996412 -202.341988)
		(end 271.192752 -202.341988)
		(width 0.16002)
		(layer "In11.Cu")
		(net "M_F_CPU0_SA_DQS_DP<5>")
	)
	(segment
		(start 271.192752 -202.341988)
		(end 272.01114 -203.160376)
		(width 0.16002)
		(layer "In11.Cu")
		(net "M_F_CPU0_SA_DQS_DP<5>")
	)
	(segment
		(start 326.431656 -227.070158)
		(end 326.432418 -227.070666)
		(width 0.09525)
		(layer "In11.Cu")
		(net "M_F_CPU0_SA_DQS_DP<5>")
	)
	(segment
		(start 298.5897 -201.956162)
		(end 298.943776 -202.310238)
		(width 0.16002)
		(layer "In11.Cu")
		(net "M_F_CPU0_SA_DQS_DP<5>")
	)
	(segment
		(start 324.893432 -222.874332)
		(end 324.910196 -222.891096)
		(width 0.09525)
		(layer "In11.Cu")
		(net "M_F_CPU0_SA_DQS_DP<5>")
	)
	(segment
		(start 287.065974 -203.160376)
		(end 289.061906 -203.160376)
		(width 0.16002)
		(layer "In11.Cu")
		(net "M_F_CPU0_SA_DQS_DP<5>")
	)
	(segment
		(start 298.943776 -202.310238)
		(end 301.303944 -202.310238)
		(width 0.16002)
		(layer "In11.Cu")
		(net "M_F_CPU0_SA_DQS_DP<5>")
	)
	(segment
		(start 291.045646 -201.956162)
		(end 291.399722 -202.310238)
		(width 0.16002)
		(layer "In11.Cu")
		(net "M_F_CPU0_SA_DQS_DP<5>")
	)
	(segment
		(start 283.501592 -201.956162)
		(end 283.855668 -202.310238)
		(width 0.16002)
		(layer "In11.Cu")
		(net "M_F_CPU0_SA_DQS_DP<5>")
	)
	(segment
		(start 325.788782 -224.234248)
		(end 325.788782 -225.855022)
		(width 0.09525)
		(layer "In11.Cu")
		(net "M_F_CPU0_SA_DQS_DP<5>")
	)
	(segment
		(start 274.771358 -202.840336)
		(end 275.655532 -201.956162)
		(width 0.16002)
		(layer "In11.Cu")
		(net "M_F_CPU0_SA_DQS_DP<5>")
	)
	(segment
		(start 326.969374 -227.576634)
		(end 327.100438 -227.707952)
		(width 0.09525)
		(layer "In11.Cu")
		(net "M_F_CPU0_SA_DQS_DP<5>")
	)
	(segment
		(start 283.199586 -201.956162)
		(end 283.501592 -201.956162)
		(width 0.16002)
		(layer "In11.Cu")
		(net "M_F_CPU0_SA_DQS_DP<5>")
	)
	(segment
		(start 267.701268 -202.16114)
		(end 267.866876 -201.995532)
		(width 0.16002)
		(layer "In11.Cu")
		(net "M_F_CPU0_SA_DQS_DP<5>")
	)
	(segment
		(start 273.973798 -203.160376)
		(end 274.293838 -202.840336)
		(width 0.16002)
		(layer "In11.Cu")
		(net "M_F_CPU0_SA_DQS_DP<5>")
	)
	(segment
		(start 275.957538 -201.956162)
		(end 276.311614 -202.310238)
		(width 0.16002)
		(layer "In11.Cu")
		(net "M_F_CPU0_SA_DQS_DP<5>")
	)
	(segment
		(start 324.994016 -222.891096)
		(end 325.318882 -223.215962)
		(width 0.09525)
		(layer "In11.Cu")
		(net "M_F_CPU0_SA_DQS_DP<5>")
	)
	(segment
		(start 279.52192 -203.160376)
		(end 281.517852 -203.160376)
		(width 0.16002)
		(layer "In11.Cu")
		(net "M_F_CPU0_SA_DQS_DP<5>")
	)
	(segment
		(start 329.821286 -227.954332)
		(end 329.829668 -227.959158)
		(width 0.09525)
		(layer "In11.Cu")
		(net "M_F_CPU0_SA_DQS_DP<5>")
	)
	(segment
		(start 283.855668 -202.310238)
		(end 286.215836 -202.310238)
		(width 0.16002)
		(layer "In11.Cu")
		(net "M_F_CPU0_SA_DQS_DP<5>")
	)
	(segment
		(start 325.956422 -226.241102)
		(end 326.084692 -226.360736)
		(width 0.09525)
		(layer "In11.Cu")
		(net "M_F_CPU0_SA_DQS_DP<5>")
	)
	(segment
		(start 289.061906 -203.160376)
		(end 289.381946 -202.840336)
		(width 0.16002)
		(layer "In11.Cu")
		(net "M_F_CPU0_SA_DQS_DP<5>")
	)
	(segment
		(start 330.392532 -227.959158)
		(end 330.400914 -227.954332)
		(width 0.09525)
		(layer "In11.Cu")
		(net "M_F_CPU0_SA_DQS_DP<5>")
	)
	(segment
		(start 269.282672 -202.341988)
		(end 269.399512 -202.458828)
		(width 0.16002)
		(layer "In11.Cu")
		(net "M_F_CPU0_SA_DQS_DP<5>")
	)
	(segment
		(start 321.814698 -219.795598)
		(end 324.893432 -222.874332)
		(width 0.16002)
		(layer "In11.Cu")
		(net "M_F_CPU0_SA_DQS_DP<5>")
	)
	(segment
		(start 269.879572 -202.458828)
		(end 269.996412 -202.341988)
		(width 0.16002)
		(layer "In11.Cu")
		(net "M_F_CPU0_SA_DQS_DP<5>")
	)
	(segment
		(start 304.94732 -202.840336)
		(end 305.831494 -201.956162)
		(width 0.16002)
		(layer "In11.Cu")
		(net "M_F_CPU0_SA_DQS_DP<5>")
	)
	(segment
		(start 327.583038 -227.90785)
		(end 327.761092 -227.90785)
		(width 0.09525)
		(layer "In11.Cu")
		(net "M_F_CPU0_SA_DQS_DP<5>")
	)
	(segment
		(start 325.318882 -223.215962)
		(end 325.318882 -223.424242)
		(width 0.09525)
		(layer "In11.Cu")
		(net "M_F_CPU0_SA_DQS_DP<5>")
	)
	(segment
		(start 311.324498 -205.503272)
		(end 311.324498 -206.986632)
		(width 0.16002)
		(layer "In11.Cu")
		(net "M_F_CPU0_SA_DQS_DP<5>")
	)
	(segment
		(start 324.910196 -222.891096)
		(end 324.994016 -222.891096)
		(width 0.09525)
		(layer "In11.Cu")
		(net "M_F_CPU0_SA_DQS_DP<5>")
	)
	(segment
		(start 297.40352 -202.840336)
		(end 298.287694 -201.956162)
		(width 0.16002)
		(layer "In11.Cu")
		(net "M_F_CPU0_SA_DQS_DP<5>")
	)
	(segment
		(start 298.287694 -201.956162)
		(end 298.5897 -201.956162)
		(width 0.16002)
		(layer "In11.Cu")
		(net "M_F_CPU0_SA_DQS_DP<5>")
	)
	(segment
		(start 269.399512 -202.458828)
		(end 269.879572 -202.458828)
		(width 0.16002)
		(layer "In11.Cu")
		(net "M_F_CPU0_SA_DQS_DP<5>")
	)
	(segment
		(start 289.381946 -202.840336)
		(end 289.859466 -202.840336)
		(width 0.16002)
		(layer "In11.Cu")
		(net "M_F_CPU0_SA_DQS_DP<5>")
	)
	(segment
		(start 294.610028 -203.160376)
		(end 296.60596 -203.160376)
		(width 0.16002)
		(layer "In11.Cu")
		(net "M_F_CPU0_SA_DQS_DP<5>")
	)
	(segment
		(start 267.104368 -202.27798)
		(end 267.221208 -202.16114)
		(width 0.16002)
		(layer "In11.Cu")
		(net "M_F_CPU0_SA_DQS_DP<5>")
	)
	(segment
		(start 305.831494 -201.956162)
		(end 307.777388 -201.956162)
		(width 0.16002)
		(layer "In11.Cu")
		(net "M_F_CPU0_SA_DQS_DP<5>")
	)
	(segment
		(start 331.332586 -227.959158)
		(end 331.340968 -227.954332)
		(width 0.09525)
		(layer "In11.Cu")
		(net "M_F_CPU0_SA_DQS_DP<5>")
	)
	(segment
		(start 267.221208 -202.16114)
		(end 267.701268 -202.16114)
		(width 0.16002)
		(layer "In11.Cu")
		(net "M_F_CPU0_SA_DQS_DP<5>")
	)
	(segment
		(start 281.517852 -203.160376)
		(end 281.837892 -202.840336)
		(width 0.16002)
		(layer "In11.Cu")
		(net "M_F_CPU0_SA_DQS_DP<5>")
	)
	(segment
		(start 290.74364 -201.956162)
		(end 291.045646 -201.956162)
		(width 0.16002)
		(layer "In11.Cu")
		(net "M_F_CPU0_SA_DQS_DP<5>")
	)
	(segment
		(start 272.01114 -203.160376)
		(end 273.973798 -203.160376)
		(width 0.16002)
		(layer "In11.Cu")
		(net "M_F_CPU0_SA_DQS_DP<5>")
	)
	(segment
		(start 266.624308 -202.27798)
		(end 267.104368 -202.27798)
		(width 0.16002)
		(layer "In11.Cu")
		(net "M_F_CPU0_SA_DQS_DP<5>")
	)
	(segment
		(start 296.60596 -203.160376)
		(end 296.926 -202.840336)
		(width 0.16002)
		(layer "In11.Cu")
		(net "M_F_CPU0_SA_DQS_DP<5>")
	)
	(segment
		(start 278.671782 -202.310238)
		(end 279.52192 -203.160376)
		(width 0.16002)
		(layer "In11.Cu")
		(net "M_F_CPU0_SA_DQS_DP<5>")
	)
	(segment
		(start 267.866876 -201.995532)
		(end 268.456156 -201.995532)
		(width 0.16002)
		(layer "In11.Cu")
		(net "M_F_CPU0_SA_DQS_DP<5>")
	)
	(segment
		(start 301.303944 -202.310238)
		(end 301.834042 -202.840336)
		(width 0.16002)
		(layer "In11.Cu")
		(net "M_F_CPU0_SA_DQS_DP<5>")
	)
	(segment
		(start 321.814698 -217.476832)
		(end 321.814698 -219.795598)
		(width 0.16002)
		(layer "In11.Cu")
		(net "M_F_CPU0_SA_DQS_DP<5>")
	)
	(segment
		(start 274.293838 -202.840336)
		(end 274.771358 -202.840336)
		(width 0.16002)
		(layer "In11.Cu")
		(net "M_F_CPU0_SA_DQS_DP<5>")
	)
	(segment
		(start 275.655532 -201.956162)
		(end 275.957538 -201.956162)
		(width 0.16002)
		(layer "In11.Cu")
		(net "M_F_CPU0_SA_DQS_DP<5>")
	)
	(arc
		(start 328.889614 -227.959158)
		(mid 329.171046 -228.034913)
		(end 329.452478 -227.959158)
		(width 0.09525)
		(layer "In11.Cu")
		(net "M_F_CPU0_SA_DQS_DP<5>")
	)
	(arc
		(start 331.709776 -227.959158)
		(mid 331.991208 -228.034913)
		(end 332.27264 -227.959158)
		(width 0.09525)
		(layer "In11.Cu")
		(net "M_F_CPU0_SA_DQS_DP<5>")
	)
	(arc
		(start 326.844406 -227.359972)
		(mid 326.860084 -227.399168)
		(end 326.876156 -227.438204)
		(width 0.09525)
		(layer "In11.Cu")
		(net "M_F_CPU0_SA_DQS_DP<5>")
	)
	(arc
		(start 326.671432 -227.191316)
		(mid 326.678535 -227.193756)
		(end 326.685656 -227.196142)
		(width 0.09525)
		(layer "In11.Cu")
		(net "M_F_CPU0_SA_DQS_DP<5>")
	)
	(arc
		(start 333.21244 -227.959158)
		(mid 333.369038 -227.909869)
		(end 333.531718 -227.93198)
		(width 0.09525)
		(layer "In11.Cu")
		(net "M_F_CPU0_SA_DQS_DP<5>")
	)
	(arc
		(start 326.260714 -226.718114)
		(mid 326.314593 -226.909473)
		(end 326.431656 -227.070158)
		(width 0.09525)
		(layer "In11.Cu")
		(net "M_F_CPU0_SA_DQS_DP<5>")
	)
	(arc
		(start 332.27264 -227.959158)
		(mid 332.461108 -227.908481)
		(end 332.649576 -227.959158)
		(width 0.09525)
		(layer "In11.Cu")
		(net "M_F_CPU0_SA_DQS_DP<5>")
	)
	(arc
		(start 325.788782 -225.855022)
		(mid 325.832383 -226.065538)
		(end 325.956422 -226.241102)
		(width 0.09525)
		(layer "In11.Cu")
		(net "M_F_CPU0_SA_DQS_DP<5>")
	)
	(arc
		(start 327.100438 -227.707952)
		(mid 327.321857 -227.855899)
		(end 327.583038 -227.90785)
		(width 0.09525)
		(layer "In11.Cu")
		(net "M_F_CPU0_SA_DQS_DP<5>")
	)
	(arc
		(start 326.820276 -227.31222)
		(mid 326.833571 -227.335475)
		(end 326.844406 -227.359972)
		(width 0.09525)
		(layer "In11.Cu")
		(net "M_F_CPU0_SA_DQS_DP<5>")
	)
	(arc
		(start 326.876156 -227.438204)
		(mid 326.916011 -227.511966)
		(end 326.969374 -227.576634)
		(width 0.09525)
		(layer "In11.Cu")
		(net "M_F_CPU0_SA_DQS_DP<5>")
	)
	(arc
		(start 325.318882 -223.424242)
		(mid 325.383279 -223.685548)
		(end 325.561706 -223.88703)
		(width 0.09525)
		(layer "In11.Cu")
		(net "M_F_CPU0_SA_DQS_DP<5>")
	)
	(arc
		(start 327.949814 -227.959158)
		(mid 328.231246 -228.034913)
		(end 328.512678 -227.959158)
		(width 0.09525)
		(layer "In11.Cu")
		(net "M_F_CPU0_SA_DQS_DP<5>")
	)
	(arc
		(start 326.685656 -227.196142)
		(mid 326.735298 -227.219319)
		(end 326.776588 -227.255324)
		(width 0.09525)
		(layer "In11.Cu")
		(net "M_F_CPU0_SA_DQS_DP<5>")
	)
	(arc
		(start 330.769722 -227.959158)
		(mid 331.051154 -228.034913)
		(end 331.332586 -227.959158)
		(width 0.09525)
		(layer "In11.Cu")
		(net "M_F_CPU0_SA_DQS_DP<5>")
	)
	(arc
		(start 326.084692 -226.360736)
		(mid 326.205379 -226.523324)
		(end 326.260714 -226.718114)
		(width 0.09525)
		(layer "In11.Cu")
		(net "M_F_CPU0_SA_DQS_DP<5>")
	)
	(arc
		(start 326.776588 -227.255324)
		(mid 326.799158 -227.283215)
		(end 326.820276 -227.31222)
		(width 0.09525)
		(layer "In11.Cu")
		(net "M_F_CPU0_SA_DQS_DP<5>")
	)
	(arc
		(start 328.512678 -227.959158)
		(mid 328.701146 -227.908481)
		(end 328.889614 -227.959158)
		(width 0.09525)
		(layer "In11.Cu")
		(net "M_F_CPU0_SA_DQS_DP<5>")
	)
	(arc
		(start 332.649576 -227.959158)
		(mid 332.931008 -228.034913)
		(end 333.21244 -227.959158)
		(width 0.09525)
		(layer "In11.Cu")
		(net "M_F_CPU0_SA_DQS_DP<5>")
	)
	(arc
		(start 329.829668 -227.959158)
		(mid 330.1111 -228.034913)
		(end 330.392532 -227.959158)
		(width 0.09525)
		(layer "In11.Cu")
		(net "M_F_CPU0_SA_DQS_DP<5>")
	)
	(arc
		(start 326.432418 -227.070666)
		(mid 326.502427 -227.123926)
		(end 326.582278 -227.160836)
		(width 0.09525)
		(layer "In11.Cu")
		(net "M_F_CPU0_SA_DQS_DP<5>")
	)
	(arc
		(start 325.631302 -223.927416)
		(mid 325.7471 -224.06181)
		(end 325.788782 -224.234248)
		(width 0.09525)
		(layer "In11.Cu")
		(net "M_F_CPU0_SA_DQS_DP<5>")
	)
	(arc
		(start 327.761092 -227.90785)
		(mid 327.858838 -227.921045)
		(end 327.949814 -227.959158)
		(width 0.09525)
		(layer "In11.Cu")
		(net "M_F_CPU0_SA_DQS_DP<5>")
	)
	(arc
		(start 331.340968 -227.954332)
		(mid 331.526 -227.908418)
		(end 331.709776 -227.959158)
		(width 0.09525)
		(layer "In11.Cu")
		(net "M_F_CPU0_SA_DQS_DP<5>")
	)
	(arc
		(start 329.452478 -227.959158)
		(mid 329.636253 -227.908386)
		(end 329.821286 -227.954332)
		(width 0.09525)
		(layer "In11.Cu")
		(net "M_F_CPU0_SA_DQS_DP<5>")
	)
	(arc
		(start 330.400914 -227.954332)
		(mid 330.585946 -227.908418)
		(end 330.769722 -227.959158)
		(width 0.09525)
		(layer "In11.Cu")
		(net "M_F_CPU0_SA_DQS_DP<5>")
	)
	(segment
		(start 332.92796 -246.370094)
		(end 332.461108 -246.104156)
		(width 0.12954)
		(layer "F.Cu")
		(net "M_F_CPU0_SA_DQS_DP<4>")
	)
	(segment
		(start 300.817534 -237.40999)
		(end 301.460154 -238.05261)
		(width 0.16002)
		(layer "In11.Cu")
		(net "M_F_CPU0_SA_DQS_DP<4>")
	)
	(segment
		(start 291.047678 -237.779052)
		(end 291.41674 -237.40999)
		(width 0.16002)
		(layer "In11.Cu")
		(net "M_F_CPU0_SA_DQS_DP<4>")
	)
	(segment
		(start 310.08066 -241.972592)
		(end 310.360568 -242.2525)
		(width 0.16002)
		(layer "In11.Cu")
		(net "M_F_CPU0_SA_DQS_DP<4>")
	)
	(segment
		(start 269.648178 -238.13516)
		(end 269.92199 -238.408972)
		(width 0.16002)
		(layer "In11.Cu")
		(net "M_F_CPU0_SA_DQS_DP<4>")
	)
	(segment
		(start 272.095468 -238.259874)
		(end 273.94535 -238.259874)
		(width 0.16002)
		(layer "In11.Cu")
		(net "M_F_CPU0_SA_DQS_DP<4>")
	)
	(segment
		(start 302.649128 -238.604552)
		(end 302.809148 -238.444532)
		(width 0.16002)
		(layer "In11.Cu")
		(net "M_F_CPU0_SA_DQS_DP<4>")
	)
	(segment
		(start 298.960794 -237.40999)
		(end 300.817534 -237.40999)
		(width 0.16002)
		(layer "In11.Cu")
		(net "M_F_CPU0_SA_DQS_DP<4>")
	)
	(segment
		(start 304.084228 -238.22533)
		(end 304.084228 -238.909352)
		(width 0.16002)
		(layer "In11.Cu")
		(net "M_F_CPU0_SA_DQS_DP<4>")
	)
	(segment
		(start 276.328632 -237.40999)
		(end 278.185372 -237.40999)
		(width 0.16002)
		(layer "In11.Cu")
		(net "M_F_CPU0_SA_DQS_DP<4>")
	)
	(segment
		(start 304.084228 -238.909352)
		(end 304.244248 -239.069372)
		(width 0.16002)
		(layer "In11.Cu")
		(net "M_F_CPU0_SA_DQS_DP<4>")
	)
	(segment
		(start 296.577512 -238.259874)
		(end 296.92219 -238.604552)
		(width 0.16002)
		(layer "In11.Cu")
		(net "M_F_CPU0_SA_DQS_DP<4>")
	)
	(segment
		(start 306.802536 -239.253268)
		(end 306.802536 -239.479328)
		(width 0.16002)
		(layer "In11.Cu")
		(net "M_F_CPU0_SA_DQS_DP<4>")
	)
	(segment
		(start 290.602924 -237.779052)
		(end 291.047678 -237.779052)
		(width 0.16002)
		(layer "In11.Cu")
		(net "M_F_CPU0_SA_DQS_DP<4>")
	)
	(segment
		(start 275.95957 -237.779052)
		(end 276.328632 -237.40999)
		(width 0.16002)
		(layer "In11.Cu")
		(net "M_F_CPU0_SA_DQS_DP<4>")
	)
	(segment
		(start 323.740526 -246.493792)
		(end 323.895974 -246.493792)
		(width 0.16002)
		(layer "In11.Cu")
		(net "M_F_CPU0_SA_DQS_DP<4>")
	)
	(segment
		(start 326.05853 -246.436134)
		(end 326.070468 -246.429276)
		(width 0.09525)
		(layer "In11.Cu")
		(net "M_F_CPU0_SA_DQS_DP<4>")
	)
	(segment
		(start 330.392532 -246.429276)
		(end 330.400914 -246.434102)
		(width 0.09525)
		(layer "In11.Cu")
		(net "M_F_CPU0_SA_DQS_DP<4>")
	)
	(segment
		(start 307.163724 -238.415576)
		(end 307.163724 -238.89208)
		(width 0.16002)
		(layer "In11.Cu")
		(net "M_F_CPU0_SA_DQS_DP<4>")
	)
	(segment
		(start 304.715418 -239.069372)
		(end 306.005738 -237.779052)
		(width 0.16002)
		(layer "In11.Cu")
		(net "M_F_CPU0_SA_DQS_DP<4>")
	)
	(segment
		(start 289.777424 -238.604552)
		(end 290.602924 -237.779052)
		(width 0.16002)
		(layer "In11.Cu")
		(net "M_F_CPU0_SA_DQS_DP<4>")
	)
	(segment
		(start 326.070468 -246.429276)
		(end 326.095868 -246.414544)
		(width 0.09525)
		(layer "In11.Cu")
		(net "M_F_CPU0_SA_DQS_DP<4>")
	)
	(segment
		(start 274.290028 -238.604552)
		(end 274.689316 -238.604552)
		(width 0.16002)
		(layer "In11.Cu")
		(net "M_F_CPU0_SA_DQS_DP<4>")
	)
	(segment
		(start 325.701914 -246.468646)
		(end 325.928736 -246.47652)
		(width 0.09525)
		(layer "In11.Cu")
		(net "M_F_CPU0_SA_DQS_DP<4>")
	)
	(segment
		(start 313.11342 -245.005352)
		(end 313.7535 -245.005352)
		(width 0.16002)
		(layer "In11.Cu")
		(net "M_F_CPU0_SA_DQS_DP<4>")
	)
	(segment
		(start 308.704234 -239.956086)
		(end 308.704234 -240.596166)
		(width 0.16002)
		(layer "In11.Cu")
		(net "M_F_CPU0_SA_DQS_DP<4>")
	)
	(segment
		(start 274.689316 -238.604552)
		(end 275.514816 -237.779052)
		(width 0.16002)
		(layer "In11.Cu")
		(net "M_F_CPU0_SA_DQS_DP<4>")
	)
	(segment
		(start 306.5272 -237.779052)
		(end 307.163724 -238.415576)
		(width 0.16002)
		(layer "In11.Cu")
		(net "M_F_CPU0_SA_DQS_DP<4>")
	)
	(segment
		(start 311.000648 -242.2525)
		(end 311.457086 -242.708938)
		(width 0.16002)
		(layer "In11.Cu")
		(net "M_F_CPU0_SA_DQS_DP<4>")
	)
	(segment
		(start 308.114954 -239.366806)
		(end 308.704234 -239.956086)
		(width 0.16002)
		(layer "In11.Cu")
		(net "M_F_CPU0_SA_DQS_DP<4>")
	)
	(segment
		(start 312.833512 -244.085364)
		(end 312.833512 -244.725444)
		(width 0.16002)
		(layer "In11.Cu")
		(net "M_F_CPU0_SA_DQS_DP<4>")
	)
	(segment
		(start 327.554844 -246.418862)
		(end 327.572878 -246.429276)
		(width 0.09525)
		(layer "In11.Cu")
		(net "M_F_CPU0_SA_DQS_DP<4>")
	)
	(segment
		(start 310.360568 -242.2525)
		(end 311.000648 -242.2525)
		(width 0.16002)
		(layer "In11.Cu")
		(net "M_F_CPU0_SA_DQS_DP<4>")
	)
	(segment
		(start 307.63845 -239.366806)
		(end 308.114954 -239.366806)
		(width 0.16002)
		(layer "In11.Cu")
		(net "M_F_CPU0_SA_DQS_DP<4>")
	)
	(segment
		(start 307.051202 -239.727994)
		(end 307.277262 -239.727994)
		(width 0.16002)
		(layer "In11.Cu")
		(net "M_F_CPU0_SA_DQS_DP<4>")
	)
	(segment
		(start 324.416166 -246.55272)
		(end 324.601078 -246.737632)
		(width 0.09525)
		(layer "In11.Cu")
		(net "M_F_CPU0_SA_DQS_DP<4>")
	)
	(segment
		(start 294.123364 -238.259874)
		(end 296.577512 -238.259874)
		(width 0.16002)
		(layer "In11.Cu")
		(net "M_F_CPU0_SA_DQS_DP<4>")
	)
	(segment
		(start 283.05887 -237.779052)
		(end 283.503624 -237.779052)
		(width 0.16002)
		(layer "In11.Cu")
		(net "M_F_CPU0_SA_DQS_DP<4>")
	)
	(segment
		(start 324.951598 -246.737632)
		(end 325.220584 -246.468646)
		(width 0.09525)
		(layer "In11.Cu")
		(net "M_F_CPU0_SA_DQS_DP<4>")
	)
	(segment
		(start 289.033458 -238.259874)
		(end 289.378136 -238.604552)
		(width 0.16002)
		(layer "In11.Cu")
		(net "M_F_CPU0_SA_DQS_DP<4>")
	)
	(segment
		(start 323.919596 -246.493792)
		(end 323.978524 -246.55272)
		(width 0.09525)
		(layer "In11.Cu")
		(net "M_F_CPU0_SA_DQS_DP<4>")
	)
	(segment
		(start 327.572878 -246.429276)
		(end 327.584816 -246.436134)
		(width 0.09525)
		(layer "In11.Cu")
		(net "M_F_CPU0_SA_DQS_DP<4>")
	)
	(segment
		(start 285.729426 -237.40999)
		(end 286.57931 -238.259874)
		(width 0.16002)
		(layer "In11.Cu")
		(net "M_F_CPU0_SA_DQS_DP<4>")
	)
	(segment
		(start 283.872686 -237.40999)
		(end 285.729426 -237.40999)
		(width 0.16002)
		(layer "In11.Cu")
		(net "M_F_CPU0_SA_DQS_DP<4>")
	)
	(segment
		(start 308.704234 -240.596166)
		(end 308.984142 -240.876074)
		(width 0.16002)
		(layer "In11.Cu")
		(net "M_F_CPU0_SA_DQS_DP<4>")
	)
	(segment
		(start 313.7535 -245.005352)
		(end 314.75426 -246.006112)
		(width 0.16002)
		(layer "In11.Cu")
		(net "M_F_CPU0_SA_DQS_DP<4>")
	)
	(segment
		(start 311.736994 -243.628926)
		(end 312.377074 -243.628926)
		(width 0.16002)
		(layer "In11.Cu")
		(net "M_F_CPU0_SA_DQS_DP<4>")
	)
	(segment
		(start 326.998838 -246.436134)
		(end 327.010776 -246.429276)
		(width 0.09525)
		(layer "In11.Cu")
		(net "M_F_CPU0_SA_DQS_DP<4>")
	)
	(segment
		(start 291.41674 -237.40999)
		(end 293.27348 -237.40999)
		(width 0.16002)
		(layer "In11.Cu")
		(net "M_F_CPU0_SA_DQS_DP<4>")
	)
	(segment
		(start 332.307184 -246.369586)
		(end 332.461108 -246.104156)
		(width 0.09525)
		(layer "In11.Cu")
		(net "M_F_CPU0_SA_DQS_DP<4>")
	)
	(segment
		(start 298.146978 -237.779052)
		(end 298.591732 -237.779052)
		(width 0.16002)
		(layer "In11.Cu")
		(net "M_F_CPU0_SA_DQS_DP<4>")
	)
	(segment
		(start 275.514816 -237.779052)
		(end 275.95957 -237.779052)
		(width 0.16002)
		(layer "In11.Cu")
		(net "M_F_CPU0_SA_DQS_DP<4>")
	)
	(segment
		(start 293.27348 -237.40999)
		(end 294.123364 -238.259874)
		(width 0.16002)
		(layer "In11.Cu")
		(net "M_F_CPU0_SA_DQS_DP<4>")
	)
	(segment
		(start 279.035256 -238.259874)
		(end 281.489404 -238.259874)
		(width 0.16002)
		(layer "In11.Cu")
		(net "M_F_CPU0_SA_DQS_DP<4>")
	)
	(segment
		(start 301.460154 -238.05261)
		(end 301.817024 -238.05261)
		(width 0.16002)
		(layer "In11.Cu")
		(net "M_F_CPU0_SA_DQS_DP<4>")
	)
	(segment
		(start 303.74717 -237.888272)
		(end 304.084228 -238.22533)
		(width 0.16002)
		(layer "In11.Cu")
		(net "M_F_CPU0_SA_DQS_DP<4>")
	)
	(segment
		(start 325.220584 -246.468646)
		(end 325.701914 -246.468646)
		(width 0.09525)
		(layer "In11.Cu")
		(net "M_F_CPU0_SA_DQS_DP<4>")
	)
	(segment
		(start 304.244248 -239.069372)
		(end 304.715418 -239.069372)
		(width 0.16002)
		(layer "In11.Cu")
		(net "M_F_CPU0_SA_DQS_DP<4>")
	)
	(segment
		(start 296.92219 -238.604552)
		(end 297.321478 -238.604552)
		(width 0.16002)
		(layer "In11.Cu")
		(net "M_F_CPU0_SA_DQS_DP<4>")
	)
	(segment
		(start 271.94637 -238.408972)
		(end 272.095468 -238.259874)
		(width 0.16002)
		(layer "In11.Cu")
		(net "M_F_CPU0_SA_DQS_DP<4>")
	)
	(segment
		(start 331.332586 -246.429276)
		(end 331.340968 -246.434102)
		(width 0.09525)
		(layer "In11.Cu")
		(net "M_F_CPU0_SA_DQS_DP<4>")
	)
	(segment
		(start 323.252846 -246.006112)
		(end 323.740526 -246.493792)
		(width 0.16002)
		(layer "In11.Cu")
		(net "M_F_CPU0_SA_DQS_DP<4>")
	)
	(segment
		(start 302.809148 -238.444532)
		(end 302.809148 -238.22533)
		(width 0.16002)
		(layer "In11.Cu")
		(net "M_F_CPU0_SA_DQS_DP<4>")
	)
	(segment
		(start 323.895974 -246.493792)
		(end 323.919596 -246.493792)
		(width 0.09525)
		(layer "In11.Cu")
		(net "M_F_CPU0_SA_DQS_DP<4>")
	)
	(segment
		(start 308.984142 -240.876074)
		(end 309.624222 -240.876074)
		(width 0.16002)
		(layer "In11.Cu")
		(net "M_F_CPU0_SA_DQS_DP<4>")
	)
	(segment
		(start 307.277262 -239.727994)
		(end 307.63845 -239.366806)
		(width 0.16002)
		(layer "In11.Cu")
		(net "M_F_CPU0_SA_DQS_DP<4>")
	)
	(segment
		(start 310.08066 -241.332512)
		(end 310.08066 -241.972592)
		(width 0.16002)
		(layer "In11.Cu")
		(net "M_F_CPU0_SA_DQS_DP<4>")
	)
	(segment
		(start 329.821286 -246.434102)
		(end 329.829668 -246.429276)
		(width 0.09525)
		(layer "In11.Cu")
		(net "M_F_CPU0_SA_DQS_DP<4>")
	)
	(segment
		(start 269.92199 -238.408972)
		(end 271.94637 -238.408972)
		(width 0.16002)
		(layer "In11.Cu")
		(net "M_F_CPU0_SA_DQS_DP<4>")
	)
	(segment
		(start 273.94535 -238.259874)
		(end 274.290028 -238.604552)
		(width 0.16002)
		(layer "In11.Cu")
		(net "M_F_CPU0_SA_DQS_DP<4>")
	)
	(segment
		(start 298.591732 -237.779052)
		(end 298.960794 -237.40999)
		(width 0.16002)
		(layer "In11.Cu")
		(net "M_F_CPU0_SA_DQS_DP<4>")
	)
	(segment
		(start 311.457086 -243.349018)
		(end 311.736994 -243.628926)
		(width 0.16002)
		(layer "In11.Cu")
		(net "M_F_CPU0_SA_DQS_DP<4>")
	)
	(segment
		(start 332.206346 -246.396256)
		(end 332.307184 -246.369586)
		(width 0.09525)
		(layer "In11.Cu")
		(net "M_F_CPU0_SA_DQS_DP<4>")
	)
	(segment
		(start 297.321478 -238.604552)
		(end 298.146978 -237.779052)
		(width 0.16002)
		(layer "In11.Cu")
		(net "M_F_CPU0_SA_DQS_DP<4>")
	)
	(segment
		(start 325.928736 -246.47652)
		(end 325.932038 -246.47652)
		(width 0.09525)
		(layer "In11.Cu")
		(net "M_F_CPU0_SA_DQS_DP<4>")
	)
	(segment
		(start 302.809148 -238.22533)
		(end 303.146206 -237.888272)
		(width 0.16002)
		(layer "In11.Cu")
		(net "M_F_CPU0_SA_DQS_DP<4>")
	)
	(segment
		(start 324.601078 -246.737632)
		(end 324.951598 -246.737632)
		(width 0.09525)
		(layer "In11.Cu")
		(net "M_F_CPU0_SA_DQS_DP<4>")
	)
	(segment
		(start 307.163724 -238.89208)
		(end 306.802536 -239.253268)
		(width 0.16002)
		(layer "In11.Cu")
		(net "M_F_CPU0_SA_DQS_DP<4>")
	)
	(segment
		(start 286.57931 -238.259874)
		(end 289.033458 -238.259874)
		(width 0.16002)
		(layer "In11.Cu")
		(net "M_F_CPU0_SA_DQS_DP<4>")
	)
	(segment
		(start 312.833512 -244.725444)
		(end 313.11342 -245.005352)
		(width 0.16002)
		(layer "In11.Cu")
		(net "M_F_CPU0_SA_DQS_DP<4>")
	)
	(segment
		(start 301.817024 -238.05261)
		(end 302.368966 -238.604552)
		(width 0.16002)
		(layer "In11.Cu")
		(net "M_F_CPU0_SA_DQS_DP<4>")
	)
	(segment
		(start 289.378136 -238.604552)
		(end 289.777424 -238.604552)
		(width 0.16002)
		(layer "In11.Cu")
		(net "M_F_CPU0_SA_DQS_DP<4>")
	)
	(segment
		(start 303.146206 -237.888272)
		(end 303.74717 -237.888272)
		(width 0.16002)
		(layer "In11.Cu")
		(net "M_F_CPU0_SA_DQS_DP<4>")
	)
	(segment
		(start 283.503624 -237.779052)
		(end 283.872686 -237.40999)
		(width 0.16002)
		(layer "In11.Cu")
		(net "M_F_CPU0_SA_DQS_DP<4>")
	)
	(segment
		(start 281.489404 -238.259874)
		(end 281.834082 -238.604552)
		(width 0.16002)
		(layer "In11.Cu")
		(net "M_F_CPU0_SA_DQS_DP<4>")
	)
	(segment
		(start 323.978524 -246.55272)
		(end 324.416166 -246.55272)
		(width 0.09525)
		(layer "In11.Cu")
		(net "M_F_CPU0_SA_DQS_DP<4>")
	)
	(segment
		(start 278.185372 -237.40999)
		(end 279.035256 -238.259874)
		(width 0.16002)
		(layer "In11.Cu")
		(net "M_F_CPU0_SA_DQS_DP<4>")
	)
	(segment
		(start 282.23337 -238.604552)
		(end 283.05887 -237.779052)
		(width 0.16002)
		(layer "In11.Cu")
		(net "M_F_CPU0_SA_DQS_DP<4>")
	)
	(segment
		(start 306.005738 -237.779052)
		(end 306.5272 -237.779052)
		(width 0.16002)
		(layer "In11.Cu")
		(net "M_F_CPU0_SA_DQS_DP<4>")
	)
	(segment
		(start 302.368966 -238.604552)
		(end 302.649128 -238.604552)
		(width 0.16002)
		(layer "In11.Cu")
		(net "M_F_CPU0_SA_DQS_DP<4>")
	)
	(segment
		(start 281.834082 -238.604552)
		(end 282.23337 -238.604552)
		(width 0.16002)
		(layer "In11.Cu")
		(net "M_F_CPU0_SA_DQS_DP<4>")
	)
	(segment
		(start 312.377074 -243.628926)
		(end 312.833512 -244.085364)
		(width 0.16002)
		(layer "In11.Cu")
		(net "M_F_CPU0_SA_DQS_DP<4>")
	)
	(segment
		(start 311.457086 -242.708938)
		(end 311.457086 -243.349018)
		(width 0.16002)
		(layer "In11.Cu")
		(net "M_F_CPU0_SA_DQS_DP<4>")
	)
	(segment
		(start 306.802536 -239.479328)
		(end 307.051202 -239.727994)
		(width 0.16002)
		(layer "In11.Cu")
		(net "M_F_CPU0_SA_DQS_DP<4>")
	)
	(segment
		(start 314.75426 -246.006112)
		(end 323.252846 -246.006112)
		(width 0.16002)
		(layer "In11.Cu")
		(net "M_F_CPU0_SA_DQS_DP<4>")
	)
	(segment
		(start 309.624222 -240.876074)
		(end 310.08066 -241.332512)
		(width 0.16002)
		(layer "In11.Cu")
		(net "M_F_CPU0_SA_DQS_DP<4>")
	)
	(arc
		(start 326.095868 -246.414544)
		(mid 326.366484 -246.353319)
		(end 326.633332 -246.429276)
		(width 0.09525)
		(layer "In11.Cu")
		(net "M_F_CPU0_SA_DQS_DP<4>")
	)
	(arc
		(start 329.452478 -246.429276)
		(mid 329.636253 -246.480048)
		(end 329.821286 -246.434102)
		(width 0.09525)
		(layer "In11.Cu")
		(net "M_F_CPU0_SA_DQS_DP<4>")
	)
	(arc
		(start 327.949814 -246.429276)
		(mid 328.231246 -246.353521)
		(end 328.512678 -246.429276)
		(width 0.09525)
		(layer "In11.Cu")
		(net "M_F_CPU0_SA_DQS_DP<4>")
	)
	(arc
		(start 327.584816 -246.436134)
		(mid 327.768197 -246.479965)
		(end 327.949814 -246.429276)
		(width 0.09525)
		(layer "In11.Cu")
		(net "M_F_CPU0_SA_DQS_DP<4>")
	)
	(arc
		(start 329.829668 -246.429276)
		(mid 330.1111 -246.353521)
		(end 330.392532 -246.429276)
		(width 0.09525)
		(layer "In11.Cu")
		(net "M_F_CPU0_SA_DQS_DP<4>")
	)
	(arc
		(start 325.932038 -246.47652)
		(mid 325.997082 -246.461957)
		(end 326.05853 -246.436134)
		(width 0.09525)
		(layer "In11.Cu")
		(net "M_F_CPU0_SA_DQS_DP<4>")
	)
	(arc
		(start 327.010776 -246.429276)
		(mid 327.281464 -246.353624)
		(end 327.554844 -246.418862)
		(width 0.09525)
		(layer "In11.Cu")
		(net "M_F_CPU0_SA_DQS_DP<4>")
	)
	(arc
		(start 328.889614 -246.429276)
		(mid 329.171046 -246.353521)
		(end 329.452478 -246.429276)
		(width 0.09525)
		(layer "In11.Cu")
		(net "M_F_CPU0_SA_DQS_DP<4>")
	)
	(arc
		(start 328.512678 -246.429276)
		(mid 328.701146 -246.479953)
		(end 328.889614 -246.429276)
		(width 0.09525)
		(layer "In11.Cu")
		(net "M_F_CPU0_SA_DQS_DP<4>")
	)
	(arc
		(start 332.186026 -246.388382)
		(mid 332.196225 -246.392219)
		(end 332.206346 -246.396256)
		(width 0.09525)
		(layer "In11.Cu")
		(net "M_F_CPU0_SA_DQS_DP<4>")
	)
	(arc
		(start 330.400914 -246.434102)
		(mid 330.585946 -246.480016)
		(end 330.769722 -246.429276)
		(width 0.09525)
		(layer "In11.Cu")
		(net "M_F_CPU0_SA_DQS_DP<4>")
	)
	(arc
		(start 331.709776 -246.429276)
		(mid 331.94332 -246.35557)
		(end 332.186026 -246.388382)
		(width 0.09525)
		(layer "In11.Cu")
		(net "M_F_CPU0_SA_DQS_DP<4>")
	)
	(arc
		(start 330.769722 -246.429276)
		(mid 331.051154 -246.353521)
		(end 331.332586 -246.429276)
		(width 0.09525)
		(layer "In11.Cu")
		(net "M_F_CPU0_SA_DQS_DP<4>")
	)
	(arc
		(start 331.340968 -246.434102)
		(mid 331.526 -246.480016)
		(end 331.709776 -246.429276)
		(width 0.09525)
		(layer "In11.Cu")
		(net "M_F_CPU0_SA_DQS_DP<4>")
	)
	(arc
		(start 326.633332 -246.429276)
		(mid 326.815202 -246.480141)
		(end 326.998838 -246.436134)
		(width 0.09525)
		(layer "In11.Cu")
		(net "M_F_CPU0_SA_DQS_DP<4>")
	)
	(segment
		(start 332.92796 -241.510058)
		(end 332.461108 -241.24412)
		(width 0.12954)
		(layer "F.Cu")
		(net "M_F_CPU0_SA_DQS_DP<3>")
	)
	(segment
		(start 323.919596 -240.39068)
		(end 323.978524 -240.449608)
		(width 0.09525)
		(layer "In11.Cu")
		(net "M_F_CPU0_SA_DQS_DP<3>")
	)
	(segment
		(start 300.817534 -228.059996)
		(end 301.98441 -229.226872)
		(width 0.16002)
		(layer "In11.Cu")
		(net "M_F_CPU0_SA_DQS_DP<3>")
	)
	(segment
		(start 274.689316 -229.254558)
		(end 275.514816 -228.429058)
		(width 0.16002)
		(layer "In11.Cu")
		(net "M_F_CPU0_SA_DQS_DP<3>")
	)
	(segment
		(start 313.557666 -235.392468)
		(end 313.557666 -235.868972)
		(width 0.16002)
		(layer "In11.Cu")
		(net "M_F_CPU0_SA_DQS_DP<3>")
	)
	(segment
		(start 290.602924 -228.429058)
		(end 291.047678 -228.429058)
		(width 0.16002)
		(layer "In11.Cu")
		(net "M_F_CPU0_SA_DQS_DP<3>")
	)
	(segment
		(start 314.533026 -237.866682)
		(end 314.77966 -238.113316)
		(width 0.16002)
		(layer "In11.Cu")
		(net "M_F_CPU0_SA_DQS_DP<3>")
	)
	(segment
		(start 315.880496 -237.715298)
		(end 316.30493 -238.139732)
		(width 0.16002)
		(layer "In11.Cu")
		(net "M_F_CPU0_SA_DQS_DP<3>")
	)
	(segment
		(start 317.057024 -240.39068)
		(end 323.895974 -240.39068)
		(width 0.16002)
		(layer "In11.Cu")
		(net "M_F_CPU0_SA_DQS_DP<3>")
	)
	(segment
		(start 281.834082 -229.254558)
		(end 282.23337 -229.254558)
		(width 0.16002)
		(layer "In11.Cu")
		(net "M_F_CPU0_SA_DQS_DP<3>")
	)
	(segment
		(start 276.328632 -228.059996)
		(end 278.185372 -228.059996)
		(width 0.16002)
		(layer "In11.Cu")
		(net "M_F_CPU0_SA_DQS_DP<3>")
	)
	(segment
		(start 301.98441 -229.226872)
		(end 304.892964 -229.226872)
		(width 0.16002)
		(layer "In11.Cu")
		(net "M_F_CPU0_SA_DQS_DP<3>")
	)
	(segment
		(start 293.27348 -228.059996)
		(end 294.123364 -228.90988)
		(width 0.16002)
		(layer "In11.Cu")
		(net "M_F_CPU0_SA_DQS_DP<3>")
	)
	(segment
		(start 327.572878 -241.56924)
		(end 327.584816 -241.576098)
		(width 0.09525)
		(layer "In11.Cu")
		(net "M_F_CPU0_SA_DQS_DP<3>")
	)
	(segment
		(start 311.538874 -234.87253)
		(end 312.032396 -235.366052)
		(width 0.16002)
		(layer "In11.Cu")
		(net "M_F_CPU0_SA_DQS_DP<3>")
	)
	(segment
		(start 283.503624 -228.429058)
		(end 283.872686 -228.059996)
		(width 0.16002)
		(layer "In11.Cu")
		(net "M_F_CPU0_SA_DQS_DP<3>")
	)
	(segment
		(start 296.577512 -228.90988)
		(end 296.92219 -229.254558)
		(width 0.16002)
		(layer "In11.Cu")
		(net "M_F_CPU0_SA_DQS_DP<3>")
	)
	(segment
		(start 313.159394 -236.26699)
		(end 313.159394 -236.49305)
		(width 0.16002)
		(layer "In11.Cu")
		(net "M_F_CPU0_SA_DQS_DP<3>")
	)
	(segment
		(start 289.033458 -228.90988)
		(end 289.378136 -229.254558)
		(width 0.16002)
		(layer "In11.Cu")
		(net "M_F_CPU0_SA_DQS_DP<3>")
	)
	(segment
		(start 283.05887 -228.429058)
		(end 283.503624 -228.429058)
		(width 0.16002)
		(layer "In11.Cu")
		(net "M_F_CPU0_SA_DQS_DP<3>")
	)
	(segment
		(start 312.656728 -234.968034)
		(end 313.133232 -234.968034)
		(width 0.16002)
		(layer "In11.Cu")
		(net "M_F_CPU0_SA_DQS_DP<3>")
	)
	(segment
		(start 312.258456 -235.366052)
		(end 312.656728 -234.968034)
		(width 0.16002)
		(layer "In11.Cu")
		(net "M_F_CPU0_SA_DQS_DP<3>")
	)
	(segment
		(start 313.406028 -236.739684)
		(end 313.632088 -236.739684)
		(width 0.16002)
		(layer "In11.Cu")
		(net "M_F_CPU0_SA_DQS_DP<3>")
	)
	(segment
		(start 327.554844 -241.558826)
		(end 327.572878 -241.56924)
		(width 0.09525)
		(layer "In11.Cu")
		(net "M_F_CPU0_SA_DQS_DP<3>")
	)
	(segment
		(start 326.998838 -241.576098)
		(end 327.010776 -241.56924)
		(width 0.09525)
		(layer "In11.Cu")
		(net "M_F_CPU0_SA_DQS_DP<3>")
	)
	(segment
		(start 278.185372 -228.059996)
		(end 279.035256 -228.90988)
		(width 0.16002)
		(layer "In11.Cu")
		(net "M_F_CPU0_SA_DQS_DP<3>")
	)
	(segment
		(start 313.632088 -236.739684)
		(end 314.03036 -236.341666)
		(width 0.16002)
		(layer "In11.Cu")
		(net "M_F_CPU0_SA_DQS_DP<3>")
	)
	(segment
		(start 313.159394 -236.49305)
		(end 313.406028 -236.739684)
		(width 0.16002)
		(layer "In11.Cu")
		(net "M_F_CPU0_SA_DQS_DP<3>")
	)
	(segment
		(start 324.95871 -240.920524)
		(end 325.531734 -241.493548)
		(width 0.09525)
		(layer "In11.Cu")
		(net "M_F_CPU0_SA_DQS_DP<3>")
	)
	(segment
		(start 323.978524 -240.449608)
		(end 324.1929 -240.449608)
		(width 0.09525)
		(layer "In11.Cu")
		(net "M_F_CPU0_SA_DQS_DP<3>")
	)
	(segment
		(start 297.321478 -229.254558)
		(end 298.146978 -228.429058)
		(width 0.16002)
		(layer "In11.Cu")
		(net "M_F_CPU0_SA_DQS_DP<3>")
	)
	(segment
		(start 289.378136 -229.254558)
		(end 289.777424 -229.254558)
		(width 0.16002)
		(layer "In11.Cu")
		(net "M_F_CPU0_SA_DQS_DP<3>")
	)
	(segment
		(start 314.931298 -237.242604)
		(end 314.533026 -237.640622)
		(width 0.16002)
		(layer "In11.Cu")
		(net "M_F_CPU0_SA_DQS_DP<3>")
	)
	(segment
		(start 304.892964 -229.226872)
		(end 305.690778 -228.429058)
		(width 0.16002)
		(layer "In11.Cu")
		(net "M_F_CPU0_SA_DQS_DP<3>")
	)
	(segment
		(start 269.92199 -229.058978)
		(end 271.94637 -229.058978)
		(width 0.16002)
		(layer "In11.Cu")
		(net "M_F_CPU0_SA_DQS_DP<3>")
	)
	(segment
		(start 296.92219 -229.254558)
		(end 297.321478 -229.254558)
		(width 0.16002)
		(layer "In11.Cu")
		(net "M_F_CPU0_SA_DQS_DP<3>")
	)
	(segment
		(start 275.514816 -228.429058)
		(end 275.95957 -228.429058)
		(width 0.16002)
		(layer "In11.Cu")
		(net "M_F_CPU0_SA_DQS_DP<3>")
	)
	(segment
		(start 329.821286 -241.574066)
		(end 329.829668 -241.56924)
		(width 0.09525)
		(layer "In11.Cu")
		(net "M_F_CPU0_SA_DQS_DP<3>")
	)
	(segment
		(start 271.94637 -229.058978)
		(end 272.095468 -228.90988)
		(width 0.16002)
		(layer "In11.Cu")
		(net "M_F_CPU0_SA_DQS_DP<3>")
	)
	(segment
		(start 315.403992 -237.715298)
		(end 315.880496 -237.715298)
		(width 0.16002)
		(layer "In11.Cu")
		(net "M_F_CPU0_SA_DQS_DP<3>")
	)
	(segment
		(start 313.133232 -234.968034)
		(end 313.557666 -235.392468)
		(width 0.16002)
		(layer "In11.Cu")
		(net "M_F_CPU0_SA_DQS_DP<3>")
	)
	(segment
		(start 315.906658 -239.014254)
		(end 315.906658 -239.240314)
		(width 0.16002)
		(layer "In11.Cu")
		(net "M_F_CPU0_SA_DQS_DP<3>")
	)
	(segment
		(start 326.25665 -241.49304)
		(end 326.351392 -241.49304)
		(width 0.09525)
		(layer "In11.Cu")
		(net "M_F_CPU0_SA_DQS_DP<3>")
	)
	(segment
		(start 291.047678 -228.429058)
		(end 291.41674 -228.059996)
		(width 0.16002)
		(layer "In11.Cu")
		(net "M_F_CPU0_SA_DQS_DP<3>")
	)
	(segment
		(start 274.290028 -229.254558)
		(end 274.689316 -229.254558)
		(width 0.16002)
		(layer "In11.Cu")
		(net "M_F_CPU0_SA_DQS_DP<3>")
	)
	(segment
		(start 311.538874 -233.174794)
		(end 311.538874 -234.87253)
		(width 0.16002)
		(layer "In11.Cu")
		(net "M_F_CPU0_SA_DQS_DP<3>")
	)
	(segment
		(start 332.307184 -241.50955)
		(end 332.461108 -241.24412)
		(width 0.09525)
		(layer "In11.Cu")
		(net "M_F_CPU0_SA_DQS_DP<3>")
	)
	(segment
		(start 279.035256 -228.90988)
		(end 281.489404 -228.90988)
		(width 0.16002)
		(layer "In11.Cu")
		(net "M_F_CPU0_SA_DQS_DP<3>")
	)
	(segment
		(start 314.03036 -236.341666)
		(end 314.506864 -236.341666)
		(width 0.16002)
		(layer "In11.Cu")
		(net "M_F_CPU0_SA_DQS_DP<3>")
	)
	(segment
		(start 313.557666 -235.868972)
		(end 313.159394 -236.26699)
		(width 0.16002)
		(layer "In11.Cu")
		(net "M_F_CPU0_SA_DQS_DP<3>")
	)
	(segment
		(start 314.931298 -236.7661)
		(end 314.931298 -237.242604)
		(width 0.16002)
		(layer "In11.Cu")
		(net "M_F_CPU0_SA_DQS_DP<3>")
	)
	(segment
		(start 330.392532 -241.56924)
		(end 330.400914 -241.574066)
		(width 0.09525)
		(layer "In11.Cu")
		(net "M_F_CPU0_SA_DQS_DP<3>")
	)
	(segment
		(start 298.146978 -228.429058)
		(end 298.591732 -228.429058)
		(width 0.16002)
		(layer "In11.Cu")
		(net "M_F_CPU0_SA_DQS_DP<3>")
	)
	(segment
		(start 291.41674 -228.059996)
		(end 293.27348 -228.059996)
		(width 0.16002)
		(layer "In11.Cu")
		(net "M_F_CPU0_SA_DQS_DP<3>")
	)
	(segment
		(start 289.777424 -229.254558)
		(end 290.602924 -228.429058)
		(width 0.16002)
		(layer "In11.Cu")
		(net "M_F_CPU0_SA_DQS_DP<3>")
	)
	(segment
		(start 272.095468 -228.90988)
		(end 273.94535 -228.90988)
		(width 0.16002)
		(layer "In11.Cu")
		(net "M_F_CPU0_SA_DQS_DP<3>")
	)
	(segment
		(start 281.489404 -228.90988)
		(end 281.834082 -229.254558)
		(width 0.16002)
		(layer "In11.Cu")
		(net "M_F_CPU0_SA_DQS_DP<3>")
	)
	(segment
		(start 314.506864 -236.341666)
		(end 314.931298 -236.7661)
		(width 0.16002)
		(layer "In11.Cu")
		(net "M_F_CPU0_SA_DQS_DP<3>")
	)
	(segment
		(start 316.30493 -238.616236)
		(end 315.906658 -239.014254)
		(width 0.16002)
		(layer "In11.Cu")
		(net "M_F_CPU0_SA_DQS_DP<3>")
	)
	(segment
		(start 314.77966 -238.113316)
		(end 315.00572 -238.113316)
		(width 0.16002)
		(layer "In11.Cu")
		(net "M_F_CPU0_SA_DQS_DP<3>")
	)
	(segment
		(start 269.648178 -228.785166)
		(end 269.92199 -229.058978)
		(width 0.16002)
		(layer "In11.Cu")
		(net "M_F_CPU0_SA_DQS_DP<3>")
	)
	(segment
		(start 312.032396 -235.366052)
		(end 312.258456 -235.366052)
		(width 0.16002)
		(layer "In11.Cu")
		(net "M_F_CPU0_SA_DQS_DP<3>")
	)
	(segment
		(start 316.30493 -238.139732)
		(end 316.30493 -238.616236)
		(width 0.16002)
		(layer "In11.Cu")
		(net "M_F_CPU0_SA_DQS_DP<3>")
	)
	(segment
		(start 286.57931 -228.90988)
		(end 289.033458 -228.90988)
		(width 0.16002)
		(layer "In11.Cu")
		(net "M_F_CPU0_SA_DQS_DP<3>")
	)
	(segment
		(start 275.95957 -228.429058)
		(end 276.328632 -228.059996)
		(width 0.16002)
		(layer "In11.Cu")
		(net "M_F_CPU0_SA_DQS_DP<3>")
	)
	(segment
		(start 326.256142 -241.493548)
		(end 326.25665 -241.49304)
		(width 0.09525)
		(layer "In11.Cu")
		(net "M_F_CPU0_SA_DQS_DP<3>")
	)
	(segment
		(start 314.533026 -237.640622)
		(end 314.533026 -237.866682)
		(width 0.16002)
		(layer "In11.Cu")
		(net "M_F_CPU0_SA_DQS_DP<3>")
	)
	(segment
		(start 331.332586 -241.56924)
		(end 331.340968 -241.574066)
		(width 0.09525)
		(layer "In11.Cu")
		(net "M_F_CPU0_SA_DQS_DP<3>")
	)
	(segment
		(start 282.23337 -229.254558)
		(end 283.05887 -228.429058)
		(width 0.16002)
		(layer "In11.Cu")
		(net "M_F_CPU0_SA_DQS_DP<3>")
	)
	(segment
		(start 325.531734 -241.493548)
		(end 326.256142 -241.493548)
		(width 0.09525)
		(layer "In11.Cu")
		(net "M_F_CPU0_SA_DQS_DP<3>")
	)
	(segment
		(start 298.591732 -228.429058)
		(end 298.960794 -228.059996)
		(width 0.16002)
		(layer "In11.Cu")
		(net "M_F_CPU0_SA_DQS_DP<3>")
	)
	(segment
		(start 294.123364 -228.90988)
		(end 296.577512 -228.90988)
		(width 0.16002)
		(layer "In11.Cu")
		(net "M_F_CPU0_SA_DQS_DP<3>")
	)
	(segment
		(start 315.00572 -238.113316)
		(end 315.403992 -237.715298)
		(width 0.16002)
		(layer "In11.Cu")
		(net "M_F_CPU0_SA_DQS_DP<3>")
	)
	(segment
		(start 315.906658 -239.240314)
		(end 317.057024 -240.39068)
		(width 0.16002)
		(layer "In11.Cu")
		(net "M_F_CPU0_SA_DQS_DP<3>")
	)
	(segment
		(start 306.793138 -228.429058)
		(end 311.538874 -233.174794)
		(width 0.16002)
		(layer "In11.Cu")
		(net "M_F_CPU0_SA_DQS_DP<3>")
	)
	(segment
		(start 324.663816 -240.920524)
		(end 324.95871 -240.920524)
		(width 0.09525)
		(layer "In11.Cu")
		(net "M_F_CPU0_SA_DQS_DP<3>")
	)
	(segment
		(start 298.960794 -228.059996)
		(end 300.817534 -228.059996)
		(width 0.16002)
		(layer "In11.Cu")
		(net "M_F_CPU0_SA_DQS_DP<3>")
	)
	(segment
		(start 273.94535 -228.90988)
		(end 274.290028 -229.254558)
		(width 0.16002)
		(layer "In11.Cu")
		(net "M_F_CPU0_SA_DQS_DP<3>")
	)
	(segment
		(start 324.1929 -240.449608)
		(end 324.663816 -240.920524)
		(width 0.09525)
		(layer "In11.Cu")
		(net "M_F_CPU0_SA_DQS_DP<3>")
	)
	(segment
		(start 332.206346 -241.53622)
		(end 332.307184 -241.50955)
		(width 0.09525)
		(layer "In11.Cu")
		(net "M_F_CPU0_SA_DQS_DP<3>")
	)
	(segment
		(start 323.895974 -240.39068)
		(end 323.919596 -240.39068)
		(width 0.09525)
		(layer "In11.Cu")
		(net "M_F_CPU0_SA_DQS_DP<3>")
	)
	(segment
		(start 305.690778 -228.429058)
		(end 306.793138 -228.429058)
		(width 0.16002)
		(layer "In11.Cu")
		(net "M_F_CPU0_SA_DQS_DP<3>")
	)
	(segment
		(start 283.872686 -228.059996)
		(end 285.729426 -228.059996)
		(width 0.16002)
		(layer "In11.Cu")
		(net "M_F_CPU0_SA_DQS_DP<3>")
	)
	(segment
		(start 285.729426 -228.059996)
		(end 286.57931 -228.90988)
		(width 0.16002)
		(layer "In11.Cu")
		(net "M_F_CPU0_SA_DQS_DP<3>")
	)
	(arc
		(start 329.452478 -241.56924)
		(mid 329.636253 -241.620012)
		(end 329.821286 -241.574066)
		(width 0.09525)
		(layer "In11.Cu")
		(net "M_F_CPU0_SA_DQS_DP<3>")
	)
	(arc
		(start 331.340968 -241.574066)
		(mid 331.526 -241.61998)
		(end 331.709776 -241.56924)
		(width 0.09525)
		(layer "In11.Cu")
		(net "M_F_CPU0_SA_DQS_DP<3>")
	)
	(arc
		(start 328.512678 -241.56924)
		(mid 328.701146 -241.619917)
		(end 328.889614 -241.56924)
		(width 0.09525)
		(layer "In11.Cu")
		(net "M_F_CPU0_SA_DQS_DP<3>")
	)
	(arc
		(start 330.400914 -241.574066)
		(mid 330.585946 -241.61998)
		(end 330.769722 -241.56924)
		(width 0.09525)
		(layer "In11.Cu")
		(net "M_F_CPU0_SA_DQS_DP<3>")
	)
	(arc
		(start 327.010776 -241.56924)
		(mid 327.281464 -241.493588)
		(end 327.554844 -241.558826)
		(width 0.09525)
		(layer "In11.Cu")
		(net "M_F_CPU0_SA_DQS_DP<3>")
	)
	(arc
		(start 326.633332 -241.56924)
		(mid 326.815202 -241.620105)
		(end 326.998838 -241.576098)
		(width 0.09525)
		(layer "In11.Cu")
		(net "M_F_CPU0_SA_DQS_DP<3>")
	)
	(arc
		(start 329.829668 -241.56924)
		(mid 330.1111 -241.493485)
		(end 330.392532 -241.56924)
		(width 0.09525)
		(layer "In11.Cu")
		(net "M_F_CPU0_SA_DQS_DP<3>")
	)
	(arc
		(start 328.889614 -241.56924)
		(mid 329.171046 -241.493485)
		(end 329.452478 -241.56924)
		(width 0.09525)
		(layer "In11.Cu")
		(net "M_F_CPU0_SA_DQS_DP<3>")
	)
	(arc
		(start 327.949814 -241.56924)
		(mid 328.231246 -241.493485)
		(end 328.512678 -241.56924)
		(width 0.09525)
		(layer "In11.Cu")
		(net "M_F_CPU0_SA_DQS_DP<3>")
	)
	(arc
		(start 327.584816 -241.576098)
		(mid 327.768197 -241.619929)
		(end 327.949814 -241.56924)
		(width 0.09525)
		(layer "In11.Cu")
		(net "M_F_CPU0_SA_DQS_DP<3>")
	)
	(arc
		(start 331.709776 -241.56924)
		(mid 331.94332 -241.495534)
		(end 332.186026 -241.528346)
		(width 0.09525)
		(layer "In11.Cu")
		(net "M_F_CPU0_SA_DQS_DP<3>")
	)
	(arc
		(start 326.351392 -241.49304)
		(mid 326.497419 -241.512444)
		(end 326.633332 -241.56924)
		(width 0.09525)
		(layer "In11.Cu")
		(net "M_F_CPU0_SA_DQS_DP<3>")
	)
	(arc
		(start 330.769722 -241.56924)
		(mid 331.051154 -241.493485)
		(end 331.332586 -241.56924)
		(width 0.09525)
		(layer "In11.Cu")
		(net "M_F_CPU0_SA_DQS_DP<3>")
	)
	(arc
		(start 332.186026 -241.528346)
		(mid 332.196225 -241.532183)
		(end 332.206346 -241.53622)
		(width 0.09525)
		(layer "In11.Cu")
		(net "M_F_CPU0_SA_DQS_DP<3>")
	)
	(segment
		(start 332.92796 -236.650022)
		(end 332.461108 -236.384084)
		(width 0.12954)
		(layer "F.Cu")
		(net "M_F_CPU0_SA_DQS_DP<2>")
	)
	(segment
		(start 326.134476 -236.633004)
		(end 326.351138 -236.633004)
		(width 0.09525)
		(layer "In11.Cu")
		(net "M_F_CPU0_SA_DQS_DP<2>")
	)
	(segment
		(start 303.824386 -220.209364)
		(end 303.984406 -220.369384)
		(width 0.16002)
		(layer "In11.Cu")
		(net "M_F_CPU0_SA_DQS_DP<2>")
	)
	(segment
		(start 283.503624 -219.079064)
		(end 283.872686 -218.710002)
		(width 0.16002)
		(layer "In11.Cu")
		(net "M_F_CPU0_SA_DQS_DP<2>")
	)
	(segment
		(start 294.123364 -219.559886)
		(end 296.577512 -219.559886)
		(width 0.16002)
		(layer "In11.Cu")
		(net "M_F_CPU0_SA_DQS_DP<2>")
	)
	(segment
		(start 281.870658 -220.267276)
		(end 283.05887 -219.079064)
		(width 0.16002)
		(layer "In11.Cu")
		(net "M_F_CPU0_SA_DQS_DP<2>")
	)
	(segment
		(start 307.553106 -219.367354)
		(end 308.019958 -219.834206)
		(width 0.16002)
		(layer "In11.Cu")
		(net "M_F_CPU0_SA_DQS_DP<2>")
	)
	(segment
		(start 285.729426 -218.710002)
		(end 286.57931 -219.559886)
		(width 0.16002)
		(layer "In11.Cu")
		(net "M_F_CPU0_SA_DQS_DP<2>")
	)
	(segment
		(start 272.095468 -219.559886)
		(end 273.392646 -219.559886)
		(width 0.16002)
		(layer "In11.Cu")
		(net "M_F_CPU0_SA_DQS_DP<2>")
	)
	(segment
		(start 305.248818 -220.209364)
		(end 305.248818 -219.416122)
		(width 0.16002)
		(layer "In11.Cu")
		(net "M_F_CPU0_SA_DQS_DP<2>")
	)
	(segment
		(start 301.2313 -219.45219)
		(end 301.62246 -219.84335)
		(width 0.16002)
		(layer "In11.Cu")
		(net "M_F_CPU0_SA_DQS_DP<2>")
	)
	(segment
		(start 298.591732 -219.079064)
		(end 298.960794 -218.710002)
		(width 0.16002)
		(layer "In11.Cu")
		(net "M_F_CPU0_SA_DQS_DP<2>")
	)
	(segment
		(start 286.57931 -219.559886)
		(end 288.480754 -219.559886)
		(width 0.16002)
		(layer "In11.Cu")
		(net "M_F_CPU0_SA_DQS_DP<2>")
	)
	(segment
		(start 274.070572 -220.237812)
		(end 274.356068 -220.237812)
		(width 0.16002)
		(layer "In11.Cu")
		(net "M_F_CPU0_SA_DQS_DP<2>")
	)
	(segment
		(start 309.39359 -221.207838)
		(end 309.39359 -221.825566)
		(width 0.16002)
		(layer "In11.Cu")
		(net "M_F_CPU0_SA_DQS_DP<2>")
	)
	(segment
		(start 332.206346 -236.676184)
		(end 332.307184 -236.649514)
		(width 0.09525)
		(layer "In11.Cu")
		(net "M_F_CPU0_SA_DQS_DP<2>")
	)
	(segment
		(start 308.019958 -219.834206)
		(end 308.019958 -220.451934)
		(width 0.16002)
		(layer "In11.Cu")
		(net "M_F_CPU0_SA_DQS_DP<2>")
	)
	(segment
		(start 283.872686 -218.710002)
		(end 285.729426 -218.710002)
		(width 0.16002)
		(layer "In11.Cu")
		(net "M_F_CPU0_SA_DQS_DP<2>")
	)
	(segment
		(start 281.64409 -220.267276)
		(end 281.870658 -220.267276)
		(width 0.16002)
		(layer "In11.Cu")
		(net "M_F_CPU0_SA_DQS_DP<2>")
	)
	(segment
		(start 293.27348 -218.710002)
		(end 294.123364 -219.559886)
		(width 0.16002)
		(layer "In11.Cu")
		(net "M_F_CPU0_SA_DQS_DP<2>")
	)
	(segment
		(start 309.682642 -222.114618)
		(end 310.30037 -222.114618)
		(width 0.16002)
		(layer "In11.Cu")
		(net "M_F_CPU0_SA_DQS_DP<2>")
	)
	(segment
		(start 308.30901 -220.740986)
		(end 308.926738 -220.740986)
		(width 0.16002)
		(layer "In11.Cu")
		(net "M_F_CPU0_SA_DQS_DP<2>")
	)
	(segment
		(start 296.577512 -219.559886)
		(end 296.92219 -219.904564)
		(width 0.16002)
		(layer "In11.Cu")
		(net "M_F_CPU0_SA_DQS_DP<2>")
	)
	(segment
		(start 301.62246 -219.84335)
		(end 302.391572 -219.84335)
		(width 0.16002)
		(layer "In11.Cu")
		(net "M_F_CPU0_SA_DQS_DP<2>")
	)
	(segment
		(start 305.585876 -219.079064)
		(end 306.647088 -219.079064)
		(width 0.16002)
		(layer "In11.Cu")
		(net "M_F_CPU0_SA_DQS_DP<2>")
	)
	(segment
		(start 330.392532 -236.709204)
		(end 330.400914 -236.71403)
		(width 0.09525)
		(layer "In11.Cu")
		(net "M_F_CPU0_SA_DQS_DP<2>")
	)
	(segment
		(start 288.480754 -219.559886)
		(end 289.188144 -220.267276)
		(width 0.16002)
		(layer "In11.Cu")
		(net "M_F_CPU0_SA_DQS_DP<2>")
	)
	(segment
		(start 310.767222 -222.58147)
		(end 310.767222 -223.199198)
		(width 0.16002)
		(layer "In11.Cu")
		(net "M_F_CPU0_SA_DQS_DP<2>")
	)
	(segment
		(start 303.984406 -220.369384)
		(end 305.088798 -220.369384)
		(width 0.16002)
		(layer "In11.Cu")
		(net "M_F_CPU0_SA_DQS_DP<2>")
	)
	(segment
		(start 332.307184 -236.649514)
		(end 332.461108 -236.384084)
		(width 0.09525)
		(layer "In11.Cu")
		(net "M_F_CPU0_SA_DQS_DP<2>")
	)
	(segment
		(start 310.30037 -222.114618)
		(end 310.767222 -222.58147)
		(width 0.16002)
		(layer "In11.Cu")
		(net "M_F_CPU0_SA_DQS_DP<2>")
	)
	(segment
		(start 297.321478 -219.904564)
		(end 298.146978 -219.079064)
		(width 0.16002)
		(layer "In11.Cu")
		(net "M_F_CPU0_SA_DQS_DP<2>")
	)
	(segment
		(start 311.484518 -224.4471)
		(end 321.776598 -234.73918)
		(width 0.16002)
		(layer "In11.Cu")
		(net "M_F_CPU0_SA_DQS_DP<2>")
	)
	(segment
		(start 327.554844 -236.69879)
		(end 327.572878 -236.709204)
		(width 0.09525)
		(layer "In11.Cu")
		(net "M_F_CPU0_SA_DQS_DP<2>")
	)
	(segment
		(start 331.332586 -236.709204)
		(end 331.340968 -236.71403)
		(width 0.09525)
		(layer "In11.Cu")
		(net "M_F_CPU0_SA_DQS_DP<2>")
	)
	(segment
		(start 303.487328 -219.168472)
		(end 303.824386 -219.50553)
		(width 0.16002)
		(layer "In11.Cu")
		(net "M_F_CPU0_SA_DQS_DP<2>")
	)
	(segment
		(start 306.935378 -219.367354)
		(end 307.553106 -219.367354)
		(width 0.16002)
		(layer "In11.Cu")
		(net "M_F_CPU0_SA_DQS_DP<2>")
	)
	(segment
		(start 302.551592 -219.50553)
		(end 302.88865 -219.168472)
		(width 0.16002)
		(layer "In11.Cu")
		(net "M_F_CPU0_SA_DQS_DP<2>")
	)
	(segment
		(start 275.95957 -219.079064)
		(end 276.328632 -218.710002)
		(width 0.16002)
		(layer "In11.Cu")
		(net "M_F_CPU0_SA_DQS_DP<2>")
	)
	(segment
		(start 308.019958 -220.451934)
		(end 308.30901 -220.740986)
		(width 0.16002)
		(layer "In11.Cu")
		(net "M_F_CPU0_SA_DQS_DP<2>")
	)
	(segment
		(start 300.817534 -218.710002)
		(end 301.2313 -219.123768)
		(width 0.16002)
		(layer "In11.Cu")
		(net "M_F_CPU0_SA_DQS_DP<2>")
	)
	(segment
		(start 306.647088 -219.079064)
		(end 306.935378 -219.367354)
		(width 0.16002)
		(layer "In11.Cu")
		(net "M_F_CPU0_SA_DQS_DP<2>")
	)
	(segment
		(start 301.2313 -219.123768)
		(end 301.2313 -219.45219)
		(width 0.16002)
		(layer "In11.Cu")
		(net "M_F_CPU0_SA_DQS_DP<2>")
	)
	(segment
		(start 269.648178 -219.435172)
		(end 269.92199 -219.708984)
		(width 0.16002)
		(layer "In11.Cu")
		(net "M_F_CPU0_SA_DQS_DP<2>")
	)
	(segment
		(start 275.514816 -219.079064)
		(end 275.95957 -219.079064)
		(width 0.16002)
		(layer "In11.Cu")
		(net "M_F_CPU0_SA_DQS_DP<2>")
	)
	(segment
		(start 296.92219 -219.904564)
		(end 297.321478 -219.904564)
		(width 0.16002)
		(layer "In11.Cu")
		(net "M_F_CPU0_SA_DQS_DP<2>")
	)
	(segment
		(start 269.92199 -219.708984)
		(end 271.94637 -219.708984)
		(width 0.16002)
		(layer "In11.Cu")
		(net "M_F_CPU0_SA_DQS_DP<2>")
	)
	(segment
		(start 273.392646 -219.559886)
		(end 274.070572 -220.237812)
		(width 0.16002)
		(layer "In11.Cu")
		(net "M_F_CPU0_SA_DQS_DP<2>")
	)
	(segment
		(start 324.364604 -235.001308)
		(end 324.364604 -235.244132)
		(width 0.09525)
		(layer "In11.Cu")
		(net "M_F_CPU0_SA_DQS_DP<2>")
	)
	(segment
		(start 302.391572 -219.84335)
		(end 302.551592 -219.68333)
		(width 0.16002)
		(layer "In11.Cu")
		(net "M_F_CPU0_SA_DQS_DP<2>")
	)
	(segment
		(start 278.185372 -218.710002)
		(end 279.035256 -219.559886)
		(width 0.16002)
		(layer "In11.Cu")
		(net "M_F_CPU0_SA_DQS_DP<2>")
	)
	(segment
		(start 289.414712 -220.267276)
		(end 290.602924 -219.079064)
		(width 0.16002)
		(layer "In11.Cu")
		(net "M_F_CPU0_SA_DQS_DP<2>")
	)
	(segment
		(start 326.998838 -236.716062)
		(end 327.010776 -236.709204)
		(width 0.09525)
		(layer "In11.Cu")
		(net "M_F_CPU0_SA_DQS_DP<2>")
	)
	(segment
		(start 274.356068 -220.237812)
		(end 275.514816 -219.079064)
		(width 0.16002)
		(layer "In11.Cu")
		(net "M_F_CPU0_SA_DQS_DP<2>")
	)
	(segment
		(start 289.188144 -220.267276)
		(end 289.414712 -220.267276)
		(width 0.16002)
		(layer "In11.Cu")
		(net "M_F_CPU0_SA_DQS_DP<2>")
	)
	(segment
		(start 305.088798 -220.369384)
		(end 305.248818 -220.209364)
		(width 0.16002)
		(layer "In11.Cu")
		(net "M_F_CPU0_SA_DQS_DP<2>")
	)
	(segment
		(start 325.094854 -235.593382)
		(end 326.134476 -236.633004)
		(width 0.09525)
		(layer "In11.Cu")
		(net "M_F_CPU0_SA_DQS_DP<2>")
	)
	(segment
		(start 298.960794 -218.710002)
		(end 300.817534 -218.710002)
		(width 0.16002)
		(layer "In11.Cu")
		(net "M_F_CPU0_SA_DQS_DP<2>")
	)
	(segment
		(start 302.88865 -219.168472)
		(end 303.487328 -219.168472)
		(width 0.16002)
		(layer "In11.Cu")
		(net "M_F_CPU0_SA_DQS_DP<2>")
	)
	(segment
		(start 291.41674 -218.710002)
		(end 293.27348 -218.710002)
		(width 0.16002)
		(layer "In11.Cu")
		(net "M_F_CPU0_SA_DQS_DP<2>")
	)
	(segment
		(start 327.572878 -236.709204)
		(end 327.584816 -236.716062)
		(width 0.09525)
		(layer "In11.Cu")
		(net "M_F_CPU0_SA_DQS_DP<2>")
	)
	(segment
		(start 323.919596 -234.73918)
		(end 323.978778 -234.798362)
		(width 0.09525)
		(layer "In11.Cu")
		(net "M_F_CPU0_SA_DQS_DP<2>")
	)
	(segment
		(start 324.364604 -235.244132)
		(end 324.713854 -235.593382)
		(width 0.09525)
		(layer "In11.Cu")
		(net "M_F_CPU0_SA_DQS_DP<2>")
	)
	(segment
		(start 309.39359 -221.825566)
		(end 309.682642 -222.114618)
		(width 0.16002)
		(layer "In11.Cu")
		(net "M_F_CPU0_SA_DQS_DP<2>")
	)
	(segment
		(start 323.978778 -234.798362)
		(end 324.161658 -234.798362)
		(width 0.09525)
		(layer "In11.Cu")
		(net "M_F_CPU0_SA_DQS_DP<2>")
	)
	(segment
		(start 323.895974 -234.73918)
		(end 323.919596 -234.73918)
		(width 0.09525)
		(layer "In11.Cu")
		(net "M_F_CPU0_SA_DQS_DP<2>")
	)
	(segment
		(start 311.484518 -223.916494)
		(end 311.484518 -224.4471)
		(width 0.16002)
		(layer "In11.Cu")
		(net "M_F_CPU0_SA_DQS_DP<2>")
	)
	(segment
		(start 280.9367 -219.559886)
		(end 281.64409 -220.267276)
		(width 0.16002)
		(layer "In11.Cu")
		(net "M_F_CPU0_SA_DQS_DP<2>")
	)
	(segment
		(start 303.824386 -219.50553)
		(end 303.824386 -220.209364)
		(width 0.16002)
		(layer "In11.Cu")
		(net "M_F_CPU0_SA_DQS_DP<2>")
	)
	(segment
		(start 329.821286 -236.71403)
		(end 329.829668 -236.709204)
		(width 0.09525)
		(layer "In11.Cu")
		(net "M_F_CPU0_SA_DQS_DP<2>")
	)
	(segment
		(start 321.776598 -234.73918)
		(end 323.895974 -234.73918)
		(width 0.16002)
		(layer "In11.Cu")
		(net "M_F_CPU0_SA_DQS_DP<2>")
	)
	(segment
		(start 279.035256 -219.559886)
		(end 280.9367 -219.559886)
		(width 0.16002)
		(layer "In11.Cu")
		(net "M_F_CPU0_SA_DQS_DP<2>")
	)
	(segment
		(start 291.047678 -219.079064)
		(end 291.41674 -218.710002)
		(width 0.16002)
		(layer "In11.Cu")
		(net "M_F_CPU0_SA_DQS_DP<2>")
	)
	(segment
		(start 298.146978 -219.079064)
		(end 298.591732 -219.079064)
		(width 0.16002)
		(layer "In11.Cu")
		(net "M_F_CPU0_SA_DQS_DP<2>")
	)
	(segment
		(start 302.551592 -219.68333)
		(end 302.551592 -219.50553)
		(width 0.16002)
		(layer "In11.Cu")
		(net "M_F_CPU0_SA_DQS_DP<2>")
	)
	(segment
		(start 324.713854 -235.593382)
		(end 325.094854 -235.593382)
		(width 0.09525)
		(layer "In11.Cu")
		(net "M_F_CPU0_SA_DQS_DP<2>")
	)
	(segment
		(start 271.94637 -219.708984)
		(end 272.095468 -219.559886)
		(width 0.16002)
		(layer "In11.Cu")
		(net "M_F_CPU0_SA_DQS_DP<2>")
	)
	(segment
		(start 276.328632 -218.710002)
		(end 278.185372 -218.710002)
		(width 0.16002)
		(layer "In11.Cu")
		(net "M_F_CPU0_SA_DQS_DP<2>")
	)
	(segment
		(start 310.767222 -223.199198)
		(end 311.484518 -223.916494)
		(width 0.16002)
		(layer "In11.Cu")
		(net "M_F_CPU0_SA_DQS_DP<2>")
	)
	(segment
		(start 324.161658 -234.798362)
		(end 324.364604 -235.001308)
		(width 0.09525)
		(layer "In11.Cu")
		(net "M_F_CPU0_SA_DQS_DP<2>")
	)
	(segment
		(start 308.926738 -220.740986)
		(end 309.39359 -221.207838)
		(width 0.16002)
		(layer "In11.Cu")
		(net "M_F_CPU0_SA_DQS_DP<2>")
	)
	(segment
		(start 283.05887 -219.079064)
		(end 283.503624 -219.079064)
		(width 0.16002)
		(layer "In11.Cu")
		(net "M_F_CPU0_SA_DQS_DP<2>")
	)
	(segment
		(start 305.248818 -219.416122)
		(end 305.585876 -219.079064)
		(width 0.16002)
		(layer "In11.Cu")
		(net "M_F_CPU0_SA_DQS_DP<2>")
	)
	(segment
		(start 290.602924 -219.079064)
		(end 291.047678 -219.079064)
		(width 0.16002)
		(layer "In11.Cu")
		(net "M_F_CPU0_SA_DQS_DP<2>")
	)
	(arc
		(start 329.829668 -236.709204)
		(mid 330.1111 -236.633449)
		(end 330.392532 -236.709204)
		(width 0.09525)
		(layer "In11.Cu")
		(net "M_F_CPU0_SA_DQS_DP<2>")
	)
	(arc
		(start 332.186026 -236.66831)
		(mid 332.196225 -236.672147)
		(end 332.206346 -236.676184)
		(width 0.09525)
		(layer "In11.Cu")
		(net "M_F_CPU0_SA_DQS_DP<2>")
	)
	(arc
		(start 327.010776 -236.709204)
		(mid 327.281464 -236.633552)
		(end 327.554844 -236.69879)
		(width 0.09525)
		(layer "In11.Cu")
		(net "M_F_CPU0_SA_DQS_DP<2>")
	)
	(arc
		(start 330.769722 -236.709204)
		(mid 331.051154 -236.633449)
		(end 331.332586 -236.709204)
		(width 0.09525)
		(layer "In11.Cu")
		(net "M_F_CPU0_SA_DQS_DP<2>")
	)
	(arc
		(start 330.400914 -236.71403)
		(mid 330.585946 -236.759944)
		(end 330.769722 -236.709204)
		(width 0.09525)
		(layer "In11.Cu")
		(net "M_F_CPU0_SA_DQS_DP<2>")
	)
	(arc
		(start 328.512678 -236.709204)
		(mid 328.701146 -236.759881)
		(end 328.889614 -236.709204)
		(width 0.09525)
		(layer "In11.Cu")
		(net "M_F_CPU0_SA_DQS_DP<2>")
	)
	(arc
		(start 328.889614 -236.709204)
		(mid 329.171046 -236.633449)
		(end 329.452478 -236.709204)
		(width 0.09525)
		(layer "In11.Cu")
		(net "M_F_CPU0_SA_DQS_DP<2>")
	)
	(arc
		(start 331.709776 -236.709204)
		(mid 331.94332 -236.635498)
		(end 332.186026 -236.66831)
		(width 0.09525)
		(layer "In11.Cu")
		(net "M_F_CPU0_SA_DQS_DP<2>")
	)
	(arc
		(start 331.340968 -236.71403)
		(mid 331.526 -236.759944)
		(end 331.709776 -236.709204)
		(width 0.09525)
		(layer "In11.Cu")
		(net "M_F_CPU0_SA_DQS_DP<2>")
	)
	(arc
		(start 327.584816 -236.716062)
		(mid 327.768197 -236.759893)
		(end 327.949814 -236.709204)
		(width 0.09525)
		(layer "In11.Cu")
		(net "M_F_CPU0_SA_DQS_DP<2>")
	)
	(arc
		(start 327.949814 -236.709204)
		(mid 328.231246 -236.633449)
		(end 328.512678 -236.709204)
		(width 0.09525)
		(layer "In11.Cu")
		(net "M_F_CPU0_SA_DQS_DP<2>")
	)
	(arc
		(start 326.351138 -236.633004)
		(mid 326.497297 -236.652375)
		(end 326.633332 -236.709204)
		(width 0.09525)
		(layer "In11.Cu")
		(net "M_F_CPU0_SA_DQS_DP<2>")
	)
	(arc
		(start 326.633332 -236.709204)
		(mid 326.815202 -236.760069)
		(end 326.998838 -236.716062)
		(width 0.09525)
		(layer "In11.Cu")
		(net "M_F_CPU0_SA_DQS_DP<2>")
	)
	(arc
		(start 329.452478 -236.709204)
		(mid 329.636253 -236.759976)
		(end 329.821286 -236.71403)
		(width 0.09525)
		(layer "In11.Cu")
		(net "M_F_CPU0_SA_DQS_DP<2>")
	)
	(segment
		(start 332.92796 -231.789986)
		(end 332.461108 -231.524048)
		(width 0.12954)
		(layer "F.Cu")
		(net "M_F_CPU0_SA_DQS_DP<1>")
	)
	(segment
		(start 289.378136 -210.55457)
		(end 289.777424 -210.55457)
		(width 0.16002)
		(layer "In11.Cu")
		(net "M_F_CPU0_SA_DQS_DP<1>")
	)
	(segment
		(start 283.05887 -209.72907)
		(end 283.503624 -209.72907)
		(width 0.16002)
		(layer "In11.Cu")
		(net "M_F_CPU0_SA_DQS_DP<1>")
	)
	(segment
		(start 317.171578 -219.49791)
		(end 317.171578 -222.179388)
		(width 0.16002)
		(layer "In11.Cu")
		(net "M_F_CPU0_SA_DQS_DP<1>")
	)
	(segment
		(start 315.623448 -219.31376)
		(end 315.849508 -219.31376)
		(width 0.16002)
		(layer "In11.Cu")
		(net "M_F_CPU0_SA_DQS_DP<1>")
	)
	(segment
		(start 312.628788 -216.3191)
		(end 312.876184 -216.566496)
		(width 0.16002)
		(layer "In11.Cu")
		(net "M_F_CPU0_SA_DQS_DP<1>")
	)
	(segment
		(start 271.94637 -210.35899)
		(end 272.095468 -210.209892)
		(width 0.16002)
		(layer "In11.Cu")
		(net "M_F_CPU0_SA_DQS_DP<1>")
	)
	(segment
		(start 330.392532 -231.849168)
		(end 330.400914 -231.853994)
		(width 0.09525)
		(layer "In11.Cu")
		(net "M_F_CPU0_SA_DQS_DP<1>")
	)
	(segment
		(start 269.92199 -210.35899)
		(end 271.94637 -210.35899)
		(width 0.16002)
		(layer "In11.Cu")
		(net "M_F_CPU0_SA_DQS_DP<1>")
	)
	(segment
		(start 291.047678 -209.72907)
		(end 291.41674 -209.360008)
		(width 0.16002)
		(layer "In11.Cu")
		(net "M_F_CPU0_SA_DQS_DP<1>")
	)
	(segment
		(start 323.895974 -228.903784)
		(end 323.912738 -228.920548)
		(width 0.09525)
		(layer "In11.Cu")
		(net "M_F_CPU0_SA_DQS_DP<1>")
	)
	(segment
		(start 326.267064 -231.623362)
		(end 326.38873 -231.623362)
		(width 0.09525)
		(layer "In11.Cu")
		(net "M_F_CPU0_SA_DQS_DP<1>")
	)
	(segment
		(start 302.012096 -210.55457)
		(end 302.337978 -210.55457)
		(width 0.16002)
		(layer "In11.Cu")
		(net "M_F_CPU0_SA_DQS_DP<1>")
	)
	(segment
		(start 313.432952 -216.235788)
		(end 313.909456 -216.235788)
		(width 0.16002)
		(layer "In11.Cu")
		(net "M_F_CPU0_SA_DQS_DP<1>")
	)
	(segment
		(start 293.27348 -209.360008)
		(end 294.123364 -210.209892)
		(width 0.16002)
		(layer "In11.Cu")
		(net "M_F_CPU0_SA_DQS_DP<1>")
	)
	(segment
		(start 326.38873 -231.623362)
		(end 326.555862 -231.790494)
		(width 0.09525)
		(layer "In11.Cu")
		(net "M_F_CPU0_SA_DQS_DP<1>")
	)
	(segment
		(start 289.777424 -210.55457)
		(end 290.602924 -209.72907)
		(width 0.16002)
		(layer "In11.Cu")
		(net "M_F_CPU0_SA_DQS_DP<1>")
	)
	(segment
		(start 290.602924 -209.72907)
		(end 291.047678 -209.72907)
		(width 0.16002)
		(layer "In11.Cu")
		(net "M_F_CPU0_SA_DQS_DP<1>")
	)
	(segment
		(start 314.333128 -217.135964)
		(end 314.00242 -217.466672)
		(width 0.16002)
		(layer "In11.Cu")
		(net "M_F_CPU0_SA_DQS_DP<1>")
	)
	(segment
		(start 298.591732 -209.72907)
		(end 298.960794 -209.360008)
		(width 0.16002)
		(layer "In11.Cu")
		(net "M_F_CPU0_SA_DQS_DP<1>")
	)
	(segment
		(start 323.912738 -228.920548)
		(end 323.912738 -229.003352)
		(width 0.09525)
		(layer "In11.Cu")
		(net "M_F_CPU0_SA_DQS_DP<1>")
	)
	(segment
		(start 315.283088 -217.60942)
		(end 315.70676 -218.033092)
		(width 0.16002)
		(layer "In11.Cu")
		(net "M_F_CPU0_SA_DQS_DP<1>")
	)
	(segment
		(start 274.290028 -210.55457)
		(end 274.689316 -210.55457)
		(width 0.16002)
		(layer "In11.Cu")
		(net "M_F_CPU0_SA_DQS_DP<1>")
	)
	(segment
		(start 300.817534 -209.360008)
		(end 302.012096 -210.55457)
		(width 0.16002)
		(layer "In11.Cu")
		(net "M_F_CPU0_SA_DQS_DP<1>")
	)
	(segment
		(start 332.307184 -231.789478)
		(end 332.461108 -231.524048)
		(width 0.09525)
		(layer "In11.Cu")
		(net "M_F_CPU0_SA_DQS_DP<1>")
	)
	(segment
		(start 327.572878 -231.849168)
		(end 327.584816 -231.856026)
		(width 0.09525)
		(layer "In11.Cu")
		(net "M_F_CPU0_SA_DQS_DP<1>")
	)
	(segment
		(start 329.821286 -231.853994)
		(end 329.829668 -231.849168)
		(width 0.09525)
		(layer "In11.Cu")
		(net "M_F_CPU0_SA_DQS_DP<1>")
	)
	(segment
		(start 283.503624 -209.72907)
		(end 283.872686 -209.360008)
		(width 0.16002)
		(layer "In11.Cu")
		(net "M_F_CPU0_SA_DQS_DP<1>")
	)
	(segment
		(start 298.960794 -209.360008)
		(end 300.817534 -209.360008)
		(width 0.16002)
		(layer "In11.Cu")
		(net "M_F_CPU0_SA_DQS_DP<1>")
	)
	(segment
		(start 302.667416 -210.225132)
		(end 303.441354 -210.225132)
		(width 0.16002)
		(layer "In11.Cu")
		(net "M_F_CPU0_SA_DQS_DP<1>")
	)
	(segment
		(start 331.332586 -231.849168)
		(end 331.340968 -231.853994)
		(width 0.09525)
		(layer "In11.Cu")
		(net "M_F_CPU0_SA_DQS_DP<1>")
	)
	(segment
		(start 325.418704 -230.071676)
		(end 325.418704 -230.775002)
		(width 0.09525)
		(layer "In11.Cu")
		(net "M_F_CPU0_SA_DQS_DP<1>")
	)
	(segment
		(start 326.998838 -231.856026)
		(end 327.010776 -231.849168)
		(width 0.09525)
		(layer "In11.Cu")
		(net "M_F_CPU0_SA_DQS_DP<1>")
	)
	(segment
		(start 325.418704 -230.775002)
		(end 326.267064 -231.623362)
		(width 0.09525)
		(layer "In11.Cu")
		(net "M_F_CPU0_SA_DQS_DP<1>")
	)
	(segment
		(start 312.628788 -216.09304)
		(end 312.628788 -216.3191)
		(width 0.16002)
		(layer "In11.Cu")
		(net "M_F_CPU0_SA_DQS_DP<1>")
	)
	(segment
		(start 286.57931 -210.209892)
		(end 289.033458 -210.209892)
		(width 0.16002)
		(layer "In11.Cu")
		(net "M_F_CPU0_SA_DQS_DP<1>")
	)
	(segment
		(start 315.70676 -218.033092)
		(end 315.70676 -218.509596)
		(width 0.16002)
		(layer "In11.Cu")
		(net "M_F_CPU0_SA_DQS_DP<1>")
	)
	(segment
		(start 305.690778 -209.72907)
		(end 307.402738 -209.72907)
		(width 0.16002)
		(layer "In11.Cu")
		(net "M_F_CPU0_SA_DQS_DP<1>")
	)
	(segment
		(start 282.23337 -210.55457)
		(end 283.05887 -209.72907)
		(width 0.16002)
		(layer "In11.Cu")
		(net "M_F_CPU0_SA_DQS_DP<1>")
	)
	(segment
		(start 315.376052 -219.066364)
		(end 315.623448 -219.31376)
		(width 0.16002)
		(layer "In11.Cu")
		(net "M_F_CPU0_SA_DQS_DP<1>")
	)
	(segment
		(start 278.185372 -209.360008)
		(end 279.035256 -210.209892)
		(width 0.16002)
		(layer "In11.Cu")
		(net "M_F_CPU0_SA_DQS_DP<1>")
	)
	(segment
		(start 316.180216 -218.983052)
		(end 316.65672 -218.983052)
		(width 0.16002)
		(layer "In11.Cu")
		(net "M_F_CPU0_SA_DQS_DP<1>")
	)
	(segment
		(start 314.249816 -217.940128)
		(end 314.475876 -217.940128)
		(width 0.16002)
		(layer "In11.Cu")
		(net "M_F_CPU0_SA_DQS_DP<1>")
	)
	(segment
		(start 283.872686 -209.360008)
		(end 285.729426 -209.360008)
		(width 0.16002)
		(layer "In11.Cu")
		(net "M_F_CPU0_SA_DQS_DP<1>")
	)
	(segment
		(start 332.206346 -231.816148)
		(end 332.307184 -231.789478)
		(width 0.09525)
		(layer "In11.Cu")
		(net "M_F_CPU0_SA_DQS_DP<1>")
	)
	(segment
		(start 315.376052 -218.840304)
		(end 315.376052 -219.066364)
		(width 0.16002)
		(layer "In11.Cu")
		(net "M_F_CPU0_SA_DQS_DP<1>")
	)
	(segment
		(start 297.321478 -210.55457)
		(end 298.146978 -209.72907)
		(width 0.16002)
		(layer "In11.Cu")
		(net "M_F_CPU0_SA_DQS_DP<1>")
	)
	(segment
		(start 315.70676 -218.509596)
		(end 315.376052 -218.840304)
		(width 0.16002)
		(layer "In11.Cu")
		(net "M_F_CPU0_SA_DQS_DP<1>")
	)
	(segment
		(start 281.834082 -210.55457)
		(end 282.23337 -210.55457)
		(width 0.16002)
		(layer "In11.Cu")
		(net "M_F_CPU0_SA_DQS_DP<1>")
	)
	(segment
		(start 314.806584 -217.60942)
		(end 315.283088 -217.60942)
		(width 0.16002)
		(layer "In11.Cu")
		(net "M_F_CPU0_SA_DQS_DP<1>")
	)
	(segment
		(start 298.146978 -209.72907)
		(end 298.591732 -209.72907)
		(width 0.16002)
		(layer "In11.Cu")
		(net "M_F_CPU0_SA_DQS_DP<1>")
	)
	(segment
		(start 273.94535 -210.209892)
		(end 274.290028 -210.55457)
		(width 0.16002)
		(layer "In11.Cu")
		(net "M_F_CPU0_SA_DQS_DP<1>")
	)
	(segment
		(start 303.441354 -210.225132)
		(end 304.159158 -210.942936)
		(width 0.16002)
		(layer "In11.Cu")
		(net "M_F_CPU0_SA_DQS_DP<1>")
	)
	(segment
		(start 316.65672 -218.983052)
		(end 317.171578 -219.49791)
		(width 0.16002)
		(layer "In11.Cu")
		(net "M_F_CPU0_SA_DQS_DP<1>")
	)
	(segment
		(start 294.123364 -210.209892)
		(end 296.577512 -210.209892)
		(width 0.16002)
		(layer "In11.Cu")
		(net "M_F_CPU0_SA_DQS_DP<1>")
	)
	(segment
		(start 285.729426 -209.360008)
		(end 286.57931 -210.209892)
		(width 0.16002)
		(layer "In11.Cu")
		(net "M_F_CPU0_SA_DQS_DP<1>")
	)
	(segment
		(start 312.876184 -216.566496)
		(end 313.102244 -216.566496)
		(width 0.16002)
		(layer "In11.Cu")
		(net "M_F_CPU0_SA_DQS_DP<1>")
	)
	(segment
		(start 317.171578 -222.179388)
		(end 323.895974 -228.903784)
		(width 0.16002)
		(layer "In11.Cu")
		(net "M_F_CPU0_SA_DQS_DP<1>")
	)
	(segment
		(start 304.159158 -210.942936)
		(end 304.476912 -210.942936)
		(width 0.16002)
		(layer "In11.Cu")
		(net "M_F_CPU0_SA_DQS_DP<1>")
	)
	(segment
		(start 302.337978 -210.55457)
		(end 302.667416 -210.225132)
		(width 0.16002)
		(layer "In11.Cu")
		(net "M_F_CPU0_SA_DQS_DP<1>")
	)
	(segment
		(start 324.535292 -229.62616)
		(end 324.973188 -229.62616)
		(width 0.09525)
		(layer "In11.Cu")
		(net "M_F_CPU0_SA_DQS_DP<1>")
	)
	(segment
		(start 307.402738 -209.72907)
		(end 312.959496 -215.285828)
		(width 0.16002)
		(layer "In11.Cu")
		(net "M_F_CPU0_SA_DQS_DP<1>")
	)
	(segment
		(start 275.95957 -209.72907)
		(end 276.328632 -209.360008)
		(width 0.16002)
		(layer "In11.Cu")
		(net "M_F_CPU0_SA_DQS_DP<1>")
	)
	(segment
		(start 272.095468 -210.209892)
		(end 273.94535 -210.209892)
		(width 0.16002)
		(layer "In11.Cu")
		(net "M_F_CPU0_SA_DQS_DP<1>")
	)
	(segment
		(start 323.912738 -229.003352)
		(end 324.535292 -229.62616)
		(width 0.09525)
		(layer "In11.Cu")
		(net "M_F_CPU0_SA_DQS_DP<1>")
	)
	(segment
		(start 314.333128 -216.65946)
		(end 314.333128 -217.135964)
		(width 0.16002)
		(layer "In11.Cu")
		(net "M_F_CPU0_SA_DQS_DP<1>")
	)
	(segment
		(start 279.035256 -210.209892)
		(end 281.489404 -210.209892)
		(width 0.16002)
		(layer "In11.Cu")
		(net "M_F_CPU0_SA_DQS_DP<1>")
	)
	(segment
		(start 304.476912 -210.942936)
		(end 305.690778 -209.72907)
		(width 0.16002)
		(layer "In11.Cu")
		(net "M_F_CPU0_SA_DQS_DP<1>")
	)
	(segment
		(start 324.973188 -229.62616)
		(end 325.418704 -230.071676)
		(width 0.09525)
		(layer "In11.Cu")
		(net "M_F_CPU0_SA_DQS_DP<1>")
	)
	(segment
		(start 275.514816 -209.72907)
		(end 275.95957 -209.72907)
		(width 0.16002)
		(layer "In11.Cu")
		(net "M_F_CPU0_SA_DQS_DP<1>")
	)
	(segment
		(start 327.554844 -231.838754)
		(end 327.572878 -231.849168)
		(width 0.09525)
		(layer "In11.Cu")
		(net "M_F_CPU0_SA_DQS_DP<1>")
	)
	(segment
		(start 313.909456 -216.235788)
		(end 314.333128 -216.65946)
		(width 0.16002)
		(layer "In11.Cu")
		(net "M_F_CPU0_SA_DQS_DP<1>")
	)
	(segment
		(start 312.959496 -215.285828)
		(end 312.959496 -215.762332)
		(width 0.16002)
		(layer "In11.Cu")
		(net "M_F_CPU0_SA_DQS_DP<1>")
	)
	(segment
		(start 314.00242 -217.692732)
		(end 314.249816 -217.940128)
		(width 0.16002)
		(layer "In11.Cu")
		(net "M_F_CPU0_SA_DQS_DP<1>")
	)
	(segment
		(start 291.41674 -209.360008)
		(end 293.27348 -209.360008)
		(width 0.16002)
		(layer "In11.Cu")
		(net "M_F_CPU0_SA_DQS_DP<1>")
	)
	(segment
		(start 312.959496 -215.762332)
		(end 312.628788 -216.09304)
		(width 0.16002)
		(layer "In11.Cu")
		(net "M_F_CPU0_SA_DQS_DP<1>")
	)
	(segment
		(start 314.00242 -217.466672)
		(end 314.00242 -217.692732)
		(width 0.16002)
		(layer "In11.Cu")
		(net "M_F_CPU0_SA_DQS_DP<1>")
	)
	(segment
		(start 314.475876 -217.940128)
		(end 314.806584 -217.60942)
		(width 0.16002)
		(layer "In11.Cu")
		(net "M_F_CPU0_SA_DQS_DP<1>")
	)
	(segment
		(start 276.328632 -209.360008)
		(end 278.185372 -209.360008)
		(width 0.16002)
		(layer "In11.Cu")
		(net "M_F_CPU0_SA_DQS_DP<1>")
	)
	(segment
		(start 296.92219 -210.55457)
		(end 297.321478 -210.55457)
		(width 0.16002)
		(layer "In11.Cu")
		(net "M_F_CPU0_SA_DQS_DP<1>")
	)
	(segment
		(start 274.689316 -210.55457)
		(end 275.514816 -209.72907)
		(width 0.16002)
		(layer "In11.Cu")
		(net "M_F_CPU0_SA_DQS_DP<1>")
	)
	(segment
		(start 269.648178 -210.085178)
		(end 269.92199 -210.35899)
		(width 0.16002)
		(layer "In11.Cu")
		(net "M_F_CPU0_SA_DQS_DP<1>")
	)
	(segment
		(start 296.577512 -210.209892)
		(end 296.92219 -210.55457)
		(width 0.16002)
		(layer "In11.Cu")
		(net "M_F_CPU0_SA_DQS_DP<1>")
	)
	(segment
		(start 315.849508 -219.31376)
		(end 316.180216 -218.983052)
		(width 0.16002)
		(layer "In11.Cu")
		(net "M_F_CPU0_SA_DQS_DP<1>")
	)
	(segment
		(start 313.102244 -216.566496)
		(end 313.432952 -216.235788)
		(width 0.16002)
		(layer "In11.Cu")
		(net "M_F_CPU0_SA_DQS_DP<1>")
	)
	(segment
		(start 281.489404 -210.209892)
		(end 281.834082 -210.55457)
		(width 0.16002)
		(layer "In11.Cu")
		(net "M_F_CPU0_SA_DQS_DP<1>")
	)
	(segment
		(start 289.033458 -210.209892)
		(end 289.378136 -210.55457)
		(width 0.16002)
		(layer "In11.Cu")
		(net "M_F_CPU0_SA_DQS_DP<1>")
	)
	(arc
		(start 328.889614 -231.849168)
		(mid 329.171046 -231.773413)
		(end 329.452478 -231.849168)
		(width 0.09525)
		(layer "In11.Cu")
		(net "M_F_CPU0_SA_DQS_DP<1>")
	)
	(arc
		(start 330.769722 -231.849168)
		(mid 331.051154 -231.773413)
		(end 331.332586 -231.849168)
		(width 0.09525)
		(layer "In11.Cu")
		(net "M_F_CPU0_SA_DQS_DP<1>")
	)
	(arc
		(start 331.709776 -231.849168)
		(mid 331.94332 -231.775462)
		(end 332.186026 -231.808274)
		(width 0.09525)
		(layer "In11.Cu")
		(net "M_F_CPU0_SA_DQS_DP<1>")
	)
	(arc
		(start 326.555862 -231.790494)
		(mid 326.592692 -231.822346)
		(end 326.633332 -231.849168)
		(width 0.09525)
		(layer "In11.Cu")
		(net "M_F_CPU0_SA_DQS_DP<1>")
	)
	(arc
		(start 329.829668 -231.849168)
		(mid 330.1111 -231.773413)
		(end 330.392532 -231.849168)
		(width 0.09525)
		(layer "In11.Cu")
		(net "M_F_CPU0_SA_DQS_DP<1>")
	)
	(arc
		(start 326.633332 -231.849168)
		(mid 326.815202 -231.900033)
		(end 326.998838 -231.856026)
		(width 0.09525)
		(layer "In11.Cu")
		(net "M_F_CPU0_SA_DQS_DP<1>")
	)
	(arc
		(start 327.010776 -231.849168)
		(mid 327.281464 -231.773516)
		(end 327.554844 -231.838754)
		(width 0.09525)
		(layer "In11.Cu")
		(net "M_F_CPU0_SA_DQS_DP<1>")
	)
	(arc
		(start 332.186026 -231.808274)
		(mid 332.196225 -231.812111)
		(end 332.206346 -231.816148)
		(width 0.09525)
		(layer "In11.Cu")
		(net "M_F_CPU0_SA_DQS_DP<1>")
	)
	(arc
		(start 328.512678 -231.849168)
		(mid 328.701146 -231.899845)
		(end 328.889614 -231.849168)
		(width 0.09525)
		(layer "In11.Cu")
		(net "M_F_CPU0_SA_DQS_DP<1>")
	)
	(arc
		(start 327.584816 -231.856026)
		(mid 327.768197 -231.899857)
		(end 327.949814 -231.849168)
		(width 0.09525)
		(layer "In11.Cu")
		(net "M_F_CPU0_SA_DQS_DP<1>")
	)
	(arc
		(start 327.949814 -231.849168)
		(mid 328.231246 -231.773413)
		(end 328.512678 -231.849168)
		(width 0.09525)
		(layer "In11.Cu")
		(net "M_F_CPU0_SA_DQS_DP<1>")
	)
	(arc
		(start 330.400914 -231.853994)
		(mid 330.585946 -231.899908)
		(end 330.769722 -231.849168)
		(width 0.09525)
		(layer "In11.Cu")
		(net "M_F_CPU0_SA_DQS_DP<1>")
	)
	(arc
		(start 329.452478 -231.849168)
		(mid 329.636253 -231.89994)
		(end 329.821286 -231.853994)
		(width 0.09525)
		(layer "In11.Cu")
		(net "M_F_CPU0_SA_DQS_DP<1>")
	)
	(arc
		(start 331.340968 -231.853994)
		(mid 331.526 -231.899908)
		(end 331.709776 -231.849168)
		(width 0.09525)
		(layer "In11.Cu")
		(net "M_F_CPU0_SA_DQS_DP<1>")
	)
	(segment
		(start 332.92796 -226.930204)
		(end 332.461108 -226.664266)
		(width 0.12954)
		(layer "F.Cu")
		(net "M_F_CPU0_SA_DQS_DP<0>")
	)
	(segment
		(start 316.653672 -209.212434)
		(end 317.078106 -209.636868)
		(width 0.16002)
		(layer "In11.Cu")
		(net "M_F_CPU0_SA_DQS_DP<0>")
	)
	(segment
		(start 325.76008 -222.12427)
		(end 325.97344 -222.33763)
		(width 0.09525)
		(layer "In11.Cu")
		(net "M_F_CPU0_SA_DQS_DP<0>")
	)
	(segment
		(start 326.178926 -222.948754)
		(end 326.196452 -222.958914)
		(width 0.09525)
		(layer "In11.Cu")
		(net "M_F_CPU0_SA_DQS_DP<0>")
	)
	(segment
		(start 279.035256 -200.859898)
		(end 281.489404 -200.859898)
		(width 0.16002)
		(layer "In11.Cu")
		(net "M_F_CPU0_SA_DQS_DP<0>")
	)
	(segment
		(start 300.817534 -200.010014)
		(end 302.012096 -201.204576)
		(width 0.16002)
		(layer "In11.Cu")
		(net "M_F_CPU0_SA_DQS_DP<0>")
	)
	(segment
		(start 283.872686 -200.010014)
		(end 285.729426 -200.010014)
		(width 0.16002)
		(layer "In11.Cu")
		(net "M_F_CPU0_SA_DQS_DP<0>")
	)
	(segment
		(start 314.235846 -208.180178)
		(end 314.461906 -208.180178)
		(width 0.16002)
		(layer "In11.Cu")
		(net "M_F_CPU0_SA_DQS_DP<0>")
	)
	(segment
		(start 313.429904 -206.46517)
		(end 313.906408 -206.46517)
		(width 0.16002)
		(layer "In11.Cu")
		(net "M_F_CPU0_SA_DQS_DP<0>")
	)
	(segment
		(start 281.834082 -201.204576)
		(end 282.23337 -201.204576)
		(width 0.16002)
		(layer "In11.Cu")
		(net "M_F_CPU0_SA_DQS_DP<0>")
	)
	(segment
		(start 327.540112 -226.97059)
		(end 327.572624 -226.989386)
		(width 0.09525)
		(layer "In11.Cu")
		(net "M_F_CPU0_SA_DQS_DP<0>")
	)
	(segment
		(start 312.581798 -206.52613)
		(end 312.862214 -206.806546)
		(width 0.16002)
		(layer "In11.Cu")
		(net "M_F_CPU0_SA_DQS_DP<0>")
	)
	(segment
		(start 305.690778 -200.379076)
		(end 307.895244 -200.379076)
		(width 0.16002)
		(layer "In11.Cu")
		(net "M_F_CPU0_SA_DQS_DP<0>")
	)
	(segment
		(start 298.960794 -200.010014)
		(end 300.817534 -200.010014)
		(width 0.16002)
		(layer "In11.Cu")
		(net "M_F_CPU0_SA_DQS_DP<0>")
	)
	(segment
		(start 316.736476 -210.454748)
		(end 316.736476 -210.680808)
		(width 0.16002)
		(layer "In11.Cu")
		(net "M_F_CPU0_SA_DQS_DP<0>")
	)
	(segment
		(start 314.803536 -207.838802)
		(end 315.28004 -207.838802)
		(width 0.16002)
		(layer "In11.Cu")
		(net "M_F_CPU0_SA_DQS_DP<0>")
	)
	(segment
		(start 273.94535 -200.859898)
		(end 274.290028 -201.204576)
		(width 0.16002)
		(layer "In11.Cu")
		(net "M_F_CPU0_SA_DQS_DP<0>")
	)
	(segment
		(start 326.139556 -222.92564)
		(end 326.171052 -222.944182)
		(width 0.09525)
		(layer "In11.Cu")
		(net "M_F_CPU0_SA_DQS_DP<0>")
	)
	(segment
		(start 314.461906 -208.180178)
		(end 314.803536 -207.838802)
		(width 0.16002)
		(layer "In11.Cu")
		(net "M_F_CPU0_SA_DQS_DP<0>")
	)
	(segment
		(start 286.57931 -200.859898)
		(end 289.033458 -200.859898)
		(width 0.16002)
		(layer "In11.Cu")
		(net "M_F_CPU0_SA_DQS_DP<0>")
	)
	(segment
		(start 316.177168 -209.212434)
		(end 316.653672 -209.212434)
		(width 0.16002)
		(layer "In11.Cu")
		(net "M_F_CPU0_SA_DQS_DP<0>")
	)
	(segment
		(start 326.554846 -224.778316)
		(end 326.548242 -224.784666)
		(width 0.09525)
		(layer "In11.Cu")
		(net "M_F_CPU0_SA_DQS_DP<0>")
	)
	(segment
		(start 312.862214 -206.806546)
		(end 313.088274 -206.806546)
		(width 0.16002)
		(layer "In11.Cu")
		(net "M_F_CPU0_SA_DQS_DP<0>")
	)
	(segment
		(start 298.146978 -200.379076)
		(end 298.591732 -200.379076)
		(width 0.16002)
		(layer "In11.Cu")
		(net "M_F_CPU0_SA_DQS_DP<0>")
	)
	(segment
		(start 325.97344 -222.33763)
		(end 325.97344 -222.63608)
		(width 0.09525)
		(layer "In11.Cu")
		(net "M_F_CPU0_SA_DQS_DP<0>")
	)
	(segment
		(start 313.989212 -207.933544)
		(end 314.235846 -208.180178)
		(width 0.16002)
		(layer "In11.Cu")
		(net "M_F_CPU0_SA_DQS_DP<0>")
	)
	(segment
		(start 315.362844 -209.081116)
		(end 315.362844 -209.307176)
		(width 0.16002)
		(layer "In11.Cu")
		(net "M_F_CPU0_SA_DQS_DP<0>")
	)
	(segment
		(start 330.392532 -226.989386)
		(end 330.400914 -226.994212)
		(width 0.09525)
		(layer "In11.Cu")
		(net "M_F_CPU0_SA_DQS_DP<0>")
	)
	(segment
		(start 326.649842 -224.70872)
		(end 326.649334 -224.708974)
		(width 0.09525)
		(layer "In11.Cu")
		(net "M_F_CPU0_SA_DQS_DP<0>")
	)
	(segment
		(start 326.442832 -225.038666)
		(end 326.442832 -225.044254)
		(width 0.09525)
		(layer "In11.Cu")
		(net "M_F_CPU0_SA_DQS_DP<0>")
	)
	(segment
		(start 289.378136 -201.204576)
		(end 289.777424 -201.204576)
		(width 0.16002)
		(layer "In11.Cu")
		(net "M_F_CPU0_SA_DQS_DP<0>")
	)
	(segment
		(start 327.572878 -226.989386)
		(end 327.584816 -226.996244)
		(width 0.09525)
		(layer "In11.Cu")
		(net "M_F_CPU0_SA_DQS_DP<0>")
	)
	(segment
		(start 326.600058 -223.730566)
		(end 326.63257 -223.749362)
		(width 0.09525)
		(layer "In11.Cu")
		(net "M_F_CPU0_SA_DQS_DP<0>")
	)
	(segment
		(start 275.514816 -200.379076)
		(end 275.95957 -200.379076)
		(width 0.16002)
		(layer "In11.Cu")
		(net "M_F_CPU0_SA_DQS_DP<0>")
	)
	(segment
		(start 274.689316 -201.204576)
		(end 275.514816 -200.379076)
		(width 0.16002)
		(layer "In11.Cu")
		(net "M_F_CPU0_SA_DQS_DP<0>")
	)
	(segment
		(start 314.330842 -206.889604)
		(end 314.330842 -207.366108)
		(width 0.16002)
		(layer "In11.Cu")
		(net "M_F_CPU0_SA_DQS_DP<0>")
	)
	(segment
		(start 307.895244 -200.379076)
		(end 312.581798 -205.06563)
		(width 0.16002)
		(layer "In11.Cu")
		(net "M_F_CPU0_SA_DQS_DP<0>")
	)
	(segment
		(start 291.41674 -200.010014)
		(end 293.27348 -200.010014)
		(width 0.16002)
		(layer "In11.Cu")
		(net "M_F_CPU0_SA_DQS_DP<0>")
	)
	(segment
		(start 322.985638 -219.266516)
		(end 325.743316 -222.024194)
		(width 0.16002)
		(layer "In11.Cu")
		(net "M_F_CPU0_SA_DQS_DP<0>")
	)
	(segment
		(start 327.572624 -226.989386)
		(end 327.572878 -226.989386)
		(width 0.09525)
		(layer "In11.Cu")
		(net "M_F_CPU0_SA_DQS_DP<0>")
	)
	(segment
		(start 278.185372 -200.010014)
		(end 279.035256 -200.859898)
		(width 0.16002)
		(layer "In11.Cu")
		(net "M_F_CPU0_SA_DQS_DP<0>")
	)
	(segment
		(start 325.76008 -222.040958)
		(end 325.76008 -222.12427)
		(width 0.09525)
		(layer "In11.Cu")
		(net "M_F_CPU0_SA_DQS_DP<0>")
	)
	(segment
		(start 317.078106 -210.113372)
		(end 316.736476 -210.454748)
		(width 0.16002)
		(layer "In11.Cu")
		(net "M_F_CPU0_SA_DQS_DP<0>")
	)
	(segment
		(start 283.05887 -200.379076)
		(end 283.503624 -200.379076)
		(width 0.16002)
		(layer "In11.Cu")
		(net "M_F_CPU0_SA_DQS_DP<0>")
	)
	(segment
		(start 326.61606 -225.360484)
		(end 326.616568 -225.36023)
		(width 0.09525)
		(layer "In11.Cu")
		(net "M_F_CPU0_SA_DQS_DP<0>")
	)
	(segment
		(start 282.23337 -201.204576)
		(end 283.05887 -200.379076)
		(width 0.16002)
		(layer "In11.Cu")
		(net "M_F_CPU0_SA_DQS_DP<0>")
	)
	(segment
		(start 326.178418 -222.949008)
		(end 326.178926 -222.948754)
		(width 0.09525)
		(layer "In11.Cu")
		(net "M_F_CPU0_SA_DQS_DP<0>")
	)
	(segment
		(start 313.989212 -207.707484)
		(end 313.989212 -207.933544)
		(width 0.16002)
		(layer "In11.Cu")
		(net "M_F_CPU0_SA_DQS_DP<0>")
	)
	(segment
		(start 269.92199 -201.008996)
		(end 271.94637 -201.008996)
		(width 0.16002)
		(layer "In11.Cu")
		(net "M_F_CPU0_SA_DQS_DP<0>")
	)
	(segment
		(start 326.616568 -225.36023)
		(end 326.67067 -225.391472)
		(width 0.09525)
		(layer "In11.Cu")
		(net "M_F_CPU0_SA_DQS_DP<0>")
	)
	(segment
		(start 269.648178 -200.735184)
		(end 269.92199 -201.008996)
		(width 0.16002)
		(layer "In11.Cu")
		(net "M_F_CPU0_SA_DQS_DP<0>")
	)
	(segment
		(start 315.704474 -208.263236)
		(end 315.704474 -208.73974)
		(width 0.16002)
		(layer "In11.Cu")
		(net "M_F_CPU0_SA_DQS_DP<0>")
	)
	(segment
		(start 327.068942 -226.159822)
		(end 327.102724 -226.17938)
		(width 0.09525)
		(layer "In11.Cu")
		(net "M_F_CPU0_SA_DQS_DP<0>")
	)
	(segment
		(start 285.729426 -200.010014)
		(end 286.57931 -200.859898)
		(width 0.16002)
		(layer "In11.Cu")
		(net "M_F_CPU0_SA_DQS_DP<0>")
	)
	(segment
		(start 325.743316 -222.024194)
		(end 325.76008 -222.040958)
		(width 0.09525)
		(layer "In11.Cu")
		(net "M_F_CPU0_SA_DQS_DP<0>")
	)
	(segment
		(start 272.095468 -200.859898)
		(end 273.94535 -200.859898)
		(width 0.16002)
		(layer "In11.Cu")
		(net "M_F_CPU0_SA_DQS_DP<0>")
	)
	(segment
		(start 297.321478 -201.204576)
		(end 298.146978 -200.379076)
		(width 0.16002)
		(layer "In11.Cu")
		(net "M_F_CPU0_SA_DQS_DP<0>")
	)
	(segment
		(start 329.821286 -226.994212)
		(end 329.829668 -226.989386)
		(width 0.09525)
		(layer "In11.Cu")
		(net "M_F_CPU0_SA_DQS_DP<0>")
	)
	(segment
		(start 327.102724 -226.17938)
		(end 327.134982 -226.198176)
		(width 0.09525)
		(layer "In11.Cu")
		(net "M_F_CPU0_SA_DQS_DP<0>")
	)
	(segment
		(start 281.489404 -200.859898)
		(end 281.834082 -201.204576)
		(width 0.16002)
		(layer "In11.Cu")
		(net "M_F_CPU0_SA_DQS_DP<0>")
	)
	(segment
		(start 326.601074 -225.351594)
		(end 326.61606 -225.360484)
		(width 0.09525)
		(layer "In11.Cu")
		(net "M_F_CPU0_SA_DQS_DP<0>")
	)
	(segment
		(start 298.591732 -200.379076)
		(end 298.960794 -200.010014)
		(width 0.16002)
		(layer "In11.Cu")
		(net "M_F_CPU0_SA_DQS_DP<0>")
	)
	(segment
		(start 275.95957 -200.379076)
		(end 276.328632 -200.010014)
		(width 0.16002)
		(layer "In11.Cu")
		(net "M_F_CPU0_SA_DQS_DP<0>")
	)
	(segment
		(start 271.94637 -201.008996)
		(end 272.095468 -200.859898)
		(width 0.16002)
		(layer "In11.Cu")
		(net "M_F_CPU0_SA_DQS_DP<0>")
	)
	(segment
		(start 315.835538 -209.55381)
		(end 316.177168 -209.212434)
		(width 0.16002)
		(layer "In11.Cu")
		(net "M_F_CPU0_SA_DQS_DP<0>")
	)
	(segment
		(start 332.307184 -226.929696)
		(end 332.461108 -226.664266)
		(width 0.09525)
		(layer "In11.Cu")
		(net "M_F_CPU0_SA_DQS_DP<0>")
	)
	(segment
		(start 326.63257 -223.749362)
		(end 326.67067 -223.77146)
		(width 0.09525)
		(layer "In11.Cu")
		(net "M_F_CPU0_SA_DQS_DP<0>")
	)
	(segment
		(start 276.328632 -200.010014)
		(end 278.185372 -200.010014)
		(width 0.16002)
		(layer "In11.Cu")
		(net "M_F_CPU0_SA_DQS_DP<0>")
	)
	(segment
		(start 294.123364 -200.859898)
		(end 296.577512 -200.859898)
		(width 0.16002)
		(layer "In11.Cu")
		(net "M_F_CPU0_SA_DQS_DP<0>")
	)
	(segment
		(start 274.290028 -201.204576)
		(end 274.689316 -201.204576)
		(width 0.16002)
		(layer "In11.Cu")
		(net "M_F_CPU0_SA_DQS_DP<0>")
	)
	(segment
		(start 296.577512 -200.859898)
		(end 296.92219 -201.204576)
		(width 0.16002)
		(layer "In11.Cu")
		(net "M_F_CPU0_SA_DQS_DP<0>")
	)
	(segment
		(start 315.704474 -208.73974)
		(end 315.362844 -209.081116)
		(width 0.16002)
		(layer "In11.Cu")
		(net "M_F_CPU0_SA_DQS_DP<0>")
	)
	(segment
		(start 291.047678 -200.379076)
		(end 291.41674 -200.010014)
		(width 0.16002)
		(layer "In11.Cu")
		(net "M_F_CPU0_SA_DQS_DP<0>")
	)
	(segment
		(start 289.033458 -200.859898)
		(end 289.378136 -201.204576)
		(width 0.16002)
		(layer "In11.Cu")
		(net "M_F_CPU0_SA_DQS_DP<0>")
	)
	(segment
		(start 326.171052 -222.944182)
		(end 326.178418 -222.949008)
		(width 0.09525)
		(layer "In11.Cu")
		(net "M_F_CPU0_SA_DQS_DP<0>")
	)
	(segment
		(start 293.27348 -200.010014)
		(end 294.123364 -200.859898)
		(width 0.16002)
		(layer "In11.Cu")
		(net "M_F_CPU0_SA_DQS_DP<0>")
	)
	(segment
		(start 315.609478 -209.55381)
		(end 315.835538 -209.55381)
		(width 0.16002)
		(layer "In11.Cu")
		(net "M_F_CPU0_SA_DQS_DP<0>")
	)
	(segment
		(start 296.92219 -201.204576)
		(end 297.321478 -201.204576)
		(width 0.16002)
		(layer "In11.Cu")
		(net "M_F_CPU0_SA_DQS_DP<0>")
	)
	(segment
		(start 315.28004 -207.838802)
		(end 315.704474 -208.263236)
		(width 0.16002)
		(layer "In11.Cu")
		(net "M_F_CPU0_SA_DQS_DP<0>")
	)
	(segment
		(start 304.865278 -201.204576)
		(end 305.690778 -200.379076)
		(width 0.16002)
		(layer "In11.Cu")
		(net "M_F_CPU0_SA_DQS_DP<0>")
	)
	(segment
		(start 326.67067 -224.697036)
		(end 326.649842 -224.70872)
		(width 0.09525)
		(layer "In11.Cu")
		(net "M_F_CPU0_SA_DQS_DP<0>")
	)
	(segment
		(start 322.985638 -216.92997)
		(end 322.985638 -219.266516)
		(width 0.16002)
		(layer "In11.Cu")
		(net "M_F_CPU0_SA_DQS_DP<0>")
	)
	(segment
		(start 331.332586 -226.989386)
		(end 331.340968 -226.994212)
		(width 0.09525)
		(layer "In11.Cu")
		(net "M_F_CPU0_SA_DQS_DP<0>")
	)
	(segment
		(start 326.649334 -224.708974)
		(end 326.632062 -224.71888)
		(width 0.09525)
		(layer "In11.Cu")
		(net "M_F_CPU0_SA_DQS_DP<0>")
	)
	(segment
		(start 317.078106 -209.636868)
		(end 317.078106 -210.113372)
		(width 0.16002)
		(layer "In11.Cu")
		(net "M_F_CPU0_SA_DQS_DP<0>")
	)
	(segment
		(start 302.012096 -201.204576)
		(end 304.865278 -201.204576)
		(width 0.16002)
		(layer "In11.Cu")
		(net "M_F_CPU0_SA_DQS_DP<0>")
	)
	(segment
		(start 290.602924 -200.379076)
		(end 291.047678 -200.379076)
		(width 0.16002)
		(layer "In11.Cu")
		(net "M_F_CPU0_SA_DQS_DP<0>")
	)
	(segment
		(start 327.134982 -226.198176)
		(end 327.137776 -226.199954)
		(width 0.09525)
		(layer "In11.Cu")
		(net "M_F_CPU0_SA_DQS_DP<0>")
	)
	(segment
		(start 312.581798 -205.06563)
		(end 312.581798 -206.52613)
		(width 0.16002)
		(layer "In11.Cu")
		(net "M_F_CPU0_SA_DQS_DP<0>")
	)
	(segment
		(start 289.777424 -201.204576)
		(end 290.602924 -200.379076)
		(width 0.16002)
		(layer "In11.Cu")
		(net "M_F_CPU0_SA_DQS_DP<0>")
	)
	(segment
		(start 314.330842 -207.366108)
		(end 313.989212 -207.707484)
		(width 0.16002)
		(layer "In11.Cu")
		(net "M_F_CPU0_SA_DQS_DP<0>")
	)
	(segment
		(start 316.736476 -210.680808)
		(end 322.985638 -216.92997)
		(width 0.16002)
		(layer "In11.Cu")
		(net "M_F_CPU0_SA_DQS_DP<0>")
	)
	(segment
		(start 315.362844 -209.307176)
		(end 315.609478 -209.55381)
		(width 0.16002)
		(layer "In11.Cu")
		(net "M_F_CPU0_SA_DQS_DP<0>")
	)
	(segment
		(start 313.906408 -206.46517)
		(end 314.330842 -206.889604)
		(width 0.16002)
		(layer "In11.Cu")
		(net "M_F_CPU0_SA_DQS_DP<0>")
	)
	(segment
		(start 283.503624 -200.379076)
		(end 283.872686 -200.010014)
		(width 0.16002)
		(layer "In11.Cu")
		(net "M_F_CPU0_SA_DQS_DP<0>")
	)
	(segment
		(start 313.088274 -206.806546)
		(end 313.429904 -206.46517)
		(width 0.16002)
		(layer "In11.Cu")
		(net "M_F_CPU0_SA_DQS_DP<0>")
	)
	(segment
		(start 332.206346 -226.956366)
		(end 332.307184 -226.929696)
		(width 0.09525)
		(layer "In11.Cu")
		(net "M_F_CPU0_SA_DQS_DP<0>")
	)
	(arc
		(start 330.400914 -226.994212)
		(mid 330.585946 -227.040126)
		(end 330.769722 -226.989386)
		(width 0.09525)
		(layer "In11.Cu")
		(net "M_F_CPU0_SA_DQS_DP<0>")
	)
	(arc
		(start 326.913494 -225.85426)
		(mid 326.954596 -226.025666)
		(end 327.068942 -226.159822)
		(width 0.09525)
		(layer "In11.Cu")
		(net "M_F_CPU0_SA_DQS_DP<0>")
	)
	(arc
		(start 327.383394 -226.664266)
		(mid 327.424851 -226.836306)
		(end 327.540112 -226.97059)
		(width 0.09525)
		(layer "In11.Cu")
		(net "M_F_CPU0_SA_DQS_DP<0>")
	)
	(arc
		(start 328.512678 -226.989386)
		(mid 328.701146 -227.040063)
		(end 328.889614 -226.989386)
		(width 0.09525)
		(layer "In11.Cu")
		(net "M_F_CPU0_SA_DQS_DP<0>")
	)
	(arc
		(start 325.97344 -222.63608)
		(mid 326.017909 -222.803006)
		(end 326.139556 -222.92564)
		(width 0.09525)
		(layer "In11.Cu")
		(net "M_F_CPU0_SA_DQS_DP<0>")
	)
	(arc
		(start 329.452478 -226.989386)
		(mid 329.636253 -227.040158)
		(end 329.821286 -226.994212)
		(width 0.09525)
		(layer "In11.Cu")
		(net "M_F_CPU0_SA_DQS_DP<0>")
	)
	(arc
		(start 327.137776 -226.199954)
		(mid 327.318231 -226.40162)
		(end 327.383394 -226.664266)
		(width 0.09525)
		(layer "In11.Cu")
		(net "M_F_CPU0_SA_DQS_DP<0>")
	)
	(arc
		(start 326.44334 -223.424242)
		(mid 326.484797 -223.596282)
		(end 326.600058 -223.730566)
		(width 0.09525)
		(layer "In11.Cu")
		(net "M_F_CPU0_SA_DQS_DP<0>")
	)
	(arc
		(start 332.186026 -226.948492)
		(mid 332.196225 -226.952329)
		(end 332.206346 -226.956366)
		(width 0.09525)
		(layer "In11.Cu")
		(net "M_F_CPU0_SA_DQS_DP<0>")
	)
	(arc
		(start 331.340968 -226.994212)
		(mid 331.526 -227.040126)
		(end 331.709776 -226.989386)
		(width 0.09525)
		(layer "In11.Cu")
		(net "M_F_CPU0_SA_DQS_DP<0>")
	)
	(arc
		(start 326.632062 -224.71888)
		(mid 326.591522 -224.746088)
		(end 326.554846 -224.778316)
		(width 0.09525)
		(layer "In11.Cu")
		(net "M_F_CPU0_SA_DQS_DP<0>")
	)
	(arc
		(start 329.829668 -226.989386)
		(mid 330.1111 -226.913631)
		(end 330.392532 -226.989386)
		(width 0.09525)
		(layer "In11.Cu")
		(net "M_F_CPU0_SA_DQS_DP<0>")
	)
	(arc
		(start 326.548242 -224.784666)
		(mid 326.470238 -224.901173)
		(end 326.442832 -225.038666)
		(width 0.09525)
		(layer "In11.Cu")
		(net "M_F_CPU0_SA_DQS_DP<0>")
	)
	(arc
		(start 331.709776 -226.989386)
		(mid 331.94332 -226.91568)
		(end 332.186026 -226.948492)
		(width 0.09525)
		(layer "In11.Cu")
		(net "M_F_CPU0_SA_DQS_DP<0>")
	)
	(arc
		(start 326.67067 -223.77146)
		(mid 326.91352 -224.234248)
		(end 326.67067 -224.697036)
		(width 0.09525)
		(layer "In11.Cu")
		(net "M_F_CPU0_SA_DQS_DP<0>")
	)
	(arc
		(start 327.949814 -226.989386)
		(mid 328.231246 -226.913631)
		(end 328.512678 -226.989386)
		(width 0.09525)
		(layer "In11.Cu")
		(net "M_F_CPU0_SA_DQS_DP<0>")
	)
	(arc
		(start 327.584816 -226.996244)
		(mid 327.768197 -227.040075)
		(end 327.949814 -226.989386)
		(width 0.09525)
		(layer "In11.Cu")
		(net "M_F_CPU0_SA_DQS_DP<0>")
	)
	(arc
		(start 326.196452 -222.958914)
		(mid 326.377831 -223.160846)
		(end 326.44334 -223.424242)
		(width 0.09525)
		(layer "In11.Cu")
		(net "M_F_CPU0_SA_DQS_DP<0>")
	)
	(arc
		(start 328.889614 -226.989386)
		(mid 329.171046 -226.913631)
		(end 329.452478 -226.989386)
		(width 0.09525)
		(layer "In11.Cu")
		(net "M_F_CPU0_SA_DQS_DP<0>")
	)
	(arc
		(start 330.769722 -226.989386)
		(mid 331.051154 -226.913631)
		(end 331.332586 -226.989386)
		(width 0.09525)
		(layer "In11.Cu")
		(net "M_F_CPU0_SA_DQS_DP<0>")
	)
	(arc
		(start 326.442832 -225.044254)
		(mid 326.48476 -225.217081)
		(end 326.601074 -225.351594)
		(width 0.09525)
		(layer "In11.Cu")
		(net "M_F_CPU0_SA_DQS_DP<0>")
	)
	(arc
		(start 326.67067 -225.391472)
		(mid 326.84912 -225.592942)
		(end 326.913494 -225.85426)
		(width 0.09525)
		(layer "In11.Cu")
		(net "M_F_CPU0_SA_DQS_DP<0>")
	)
	(segment
		(start 334.337914 -247.1801)
		(end 333.871062 -246.914162)
		(width 0.12954)
		(layer "F.Cu")
		(net "M_F_CPU0_SA_DQS_DN<9>")
	)
	(segment
		(start 265.54811 -238.985044)
		(end 265.821922 -239.258856)
		(width 0.16002)
		(layer "In11.Cu")
		(net "M_F_CPU0_SA_DQS_DN<9>")
	)
	(segment
		(start 286.341058 -239.407954)
		(end 287.191196 -240.258092)
		(width 0.16002)
		(layer "In11.Cu")
		(net "M_F_CPU0_SA_DQS_DN<9>")
	)
	(segment
		(start 278.797004 -239.407954)
		(end 279.647142 -240.258092)
		(width 0.16002)
		(layer "In11.Cu")
		(net "M_F_CPU0_SA_DQS_DN<9>")
	)
	(segment
		(start 298.714922 -239.053878)
		(end 299.068998 -239.407954)
		(width 0.16002)
		(layer "In11.Cu")
		(net "M_F_CPU0_SA_DQS_DN<9>")
	)
	(segment
		(start 325.37273 -247.438926)
		(end 325.483982 -247.327674)
		(width 0.09525)
		(layer "In11.Cu")
		(net "M_F_CPU0_SA_DQS_DN<9>")
	)
	(segment
		(start 293.885112 -239.407954)
		(end 294.73525 -240.258092)
		(width 0.16002)
		(layer "In11.Cu")
		(net "M_F_CPU0_SA_DQS_DN<9>")
	)
	(segment
		(start 296.800778 -239.938052)
		(end 297.278298 -239.938052)
		(width 0.16002)
		(layer "In11.Cu")
		(net "M_F_CPU0_SA_DQS_DN<9>")
	)
	(segment
		(start 328.03211 -247.233186)
		(end 328.042524 -247.239282)
		(width 0.09525)
		(layer "In11.Cu")
		(net "M_F_CPU0_SA_DQS_DN<9>")
	)
	(segment
		(start 313.759088 -246.900192)
		(end 322.881498 -246.900192)
		(width 0.16002)
		(layer "In11.Cu")
		(net "M_F_CPU0_SA_DQS_DN<9>")
	)
	(segment
		(start 333.717138 -247.179592)
		(end 333.871062 -246.914162)
		(width 0.09525)
		(layer "In11.Cu")
		(net "M_F_CPU0_SA_DQS_DN<9>")
	)
	(segment
		(start 323.919596 -247.379744)
		(end 323.978778 -247.438926)
		(width 0.09525)
		(layer "In11.Cu")
		(net "M_F_CPU0_SA_DQS_DN<9>")
	)
	(segment
		(start 296.480738 -240.258092)
		(end 296.800778 -239.938052)
		(width 0.16002)
		(layer "In11.Cu")
		(net "M_F_CPU0_SA_DQS_DN<9>")
	)
	(segment
		(start 283.074364 -239.053878)
		(end 283.626814 -239.053878)
		(width 0.16002)
		(layer "In11.Cu")
		(net "M_F_CPU0_SA_DQS_DN<9>")
	)
	(segment
		(start 291.170868 -239.053878)
		(end 291.524944 -239.407954)
		(width 0.16002)
		(layer "In11.Cu")
		(net "M_F_CPU0_SA_DQS_DN<9>")
	)
	(segment
		(start 289.256724 -239.938052)
		(end 289.734244 -239.938052)
		(width 0.16002)
		(layer "In11.Cu")
		(net "M_F_CPU0_SA_DQS_DN<9>")
	)
	(segment
		(start 323.895974 -247.379744)
		(end 323.919596 -247.379744)
		(width 0.09525)
		(layer "In11.Cu")
		(net "M_F_CPU0_SA_DQS_DN<9>")
	)
	(segment
		(start 328.411332 -247.244108)
		(end 328.419714 -247.239282)
		(width 0.09525)
		(layer "In11.Cu")
		(net "M_F_CPU0_SA_DQS_DN<9>")
	)
	(segment
		(start 283.98089 -239.407954)
		(end 286.341058 -239.407954)
		(width 0.16002)
		(layer "In11.Cu")
		(net "M_F_CPU0_SA_DQS_DN<9>")
	)
	(segment
		(start 305.238912 -239.938052)
		(end 305.904392 -240.603532)
		(width 0.16002)
		(layer "In11.Cu")
		(net "M_F_CPU0_SA_DQS_DN<9>")
	)
	(segment
		(start 332.74254 -247.239282)
		(end 332.750922 -247.244108)
		(width 0.09525)
		(layer "In11.Cu")
		(net "M_F_CPU0_SA_DQS_DN<9>")
	)
	(segment
		(start 299.068998 -239.407954)
		(end 301.429166 -239.407954)
		(width 0.16002)
		(layer "In11.Cu")
		(net "M_F_CPU0_SA_DQS_DN<9>")
	)
	(segment
		(start 273.848576 -240.258092)
		(end 274.168616 -239.938052)
		(width 0.16002)
		(layer "In11.Cu")
		(net "M_F_CPU0_SA_DQS_DN<9>")
	)
	(segment
		(start 272.136362 -240.258092)
		(end 273.848576 -240.258092)
		(width 0.16002)
		(layer "In11.Cu")
		(net "M_F_CPU0_SA_DQS_DN<9>")
	)
	(segment
		(start 298.162472 -239.053878)
		(end 298.714922 -239.053878)
		(width 0.16002)
		(layer "In11.Cu")
		(net "M_F_CPU0_SA_DQS_DN<9>")
	)
	(segment
		(start 274.646136 -239.938052)
		(end 275.53031 -239.053878)
		(width 0.16002)
		(layer "In11.Cu")
		(net "M_F_CPU0_SA_DQS_DN<9>")
	)
	(segment
		(start 305.904392 -240.603532)
		(end 307.462428 -240.603532)
		(width 0.16002)
		(layer "In11.Cu")
		(net "M_F_CPU0_SA_DQS_DN<9>")
	)
	(segment
		(start 265.821922 -239.258856)
		(end 267.576046 -239.258856)
		(width 0.16002)
		(layer "In11.Cu")
		(net "M_F_CPU0_SA_DQS_DN<9>")
	)
	(segment
		(start 274.168616 -239.938052)
		(end 274.646136 -239.938052)
		(width 0.16002)
		(layer "In11.Cu")
		(net "M_F_CPU0_SA_DQS_DN<9>")
	)
	(segment
		(start 323.978778 -247.438926)
		(end 325.37273 -247.438926)
		(width 0.09525)
		(layer "In11.Cu")
		(net "M_F_CPU0_SA_DQS_DN<9>")
	)
	(segment
		(start 289.734244 -239.938052)
		(end 290.618418 -239.053878)
		(width 0.16002)
		(layer "In11.Cu")
		(net "M_F_CPU0_SA_DQS_DN<9>")
	)
	(segment
		(start 276.436836 -239.407954)
		(end 278.797004 -239.407954)
		(width 0.16002)
		(layer "In11.Cu")
		(net "M_F_CPU0_SA_DQS_DN<9>")
	)
	(segment
		(start 290.618418 -239.053878)
		(end 291.170868 -239.053878)
		(width 0.16002)
		(layer "In11.Cu")
		(net "M_F_CPU0_SA_DQS_DN<9>")
	)
	(segment
		(start 297.278298 -239.938052)
		(end 298.162472 -239.053878)
		(width 0.16002)
		(layer "In11.Cu")
		(net "M_F_CPU0_SA_DQS_DN<9>")
	)
	(segment
		(start 268.927834 -239.439704)
		(end 271.317974 -239.439704)
		(width 0.16002)
		(layer "In11.Cu")
		(net "M_F_CPU0_SA_DQS_DN<9>")
	)
	(segment
		(start 275.53031 -239.053878)
		(end 276.08276 -239.053878)
		(width 0.16002)
		(layer "In11.Cu")
		(net "M_F_CPU0_SA_DQS_DN<9>")
	)
	(segment
		(start 271.317974 -239.439704)
		(end 272.136362 -240.258092)
		(width 0.16002)
		(layer "In11.Cu")
		(net "M_F_CPU0_SA_DQS_DN<9>")
	)
	(segment
		(start 283.626814 -239.053878)
		(end 283.98089 -239.407954)
		(width 0.16002)
		(layer "In11.Cu")
		(net "M_F_CPU0_SA_DQS_DN<9>")
	)
	(segment
		(start 301.429166 -239.407954)
		(end 301.959264 -239.938052)
		(width 0.16002)
		(layer "In11.Cu")
		(net "M_F_CPU0_SA_DQS_DN<9>")
	)
	(segment
		(start 268.581378 -239.093248)
		(end 268.927834 -239.439704)
		(width 0.16002)
		(layer "In11.Cu")
		(net "M_F_CPU0_SA_DQS_DN<9>")
	)
	(segment
		(start 332.171294 -247.244108)
		(end 332.179676 -247.239282)
		(width 0.09525)
		(layer "In11.Cu")
		(net "M_F_CPU0_SA_DQS_DN<9>")
	)
	(segment
		(start 267.576046 -239.258856)
		(end 267.741654 -239.093248)
		(width 0.16002)
		(layer "In11.Cu")
		(net "M_F_CPU0_SA_DQS_DN<9>")
	)
	(segment
		(start 281.39263 -240.258092)
		(end 281.71267 -239.938052)
		(width 0.16002)
		(layer "In11.Cu")
		(net "M_F_CPU0_SA_DQS_DN<9>")
	)
	(segment
		(start 282.19019 -239.938052)
		(end 283.074364 -239.053878)
		(width 0.16002)
		(layer "In11.Cu")
		(net "M_F_CPU0_SA_DQS_DN<9>")
	)
	(segment
		(start 279.647142 -240.258092)
		(end 281.39263 -240.258092)
		(width 0.16002)
		(layer "In11.Cu")
		(net "M_F_CPU0_SA_DQS_DN<9>")
	)
	(segment
		(start 267.741654 -239.093248)
		(end 268.581378 -239.093248)
		(width 0.16002)
		(layer "In11.Cu")
		(net "M_F_CPU0_SA_DQS_DN<9>")
	)
	(segment
		(start 291.524944 -239.407954)
		(end 293.885112 -239.407954)
		(width 0.16002)
		(layer "In11.Cu")
		(net "M_F_CPU0_SA_DQS_DN<9>")
	)
	(segment
		(start 326.524874 -247.247664)
		(end 326.549766 -247.233186)
		(width 0.09525)
		(layer "In11.Cu")
		(net "M_F_CPU0_SA_DQS_DN<9>")
	)
	(segment
		(start 307.462428 -240.603532)
		(end 313.759088 -246.900192)
		(width 0.16002)
		(layer "In11.Cu")
		(net "M_F_CPU0_SA_DQS_DN<9>")
	)
	(segment
		(start 281.71267 -239.938052)
		(end 282.19019 -239.938052)
		(width 0.16002)
		(layer "In11.Cu")
		(net "M_F_CPU0_SA_DQS_DN<9>")
	)
	(segment
		(start 276.08276 -239.053878)
		(end 276.436836 -239.407954)
		(width 0.16002)
		(layer "In11.Cu")
		(net "M_F_CPU0_SA_DQS_DN<9>")
	)
	(segment
		(start 331.23124 -247.244108)
		(end 331.239622 -247.239282)
		(width 0.09525)
		(layer "In11.Cu")
		(net "M_F_CPU0_SA_DQS_DN<9>")
	)
	(segment
		(start 322.881498 -246.900192)
		(end 323.36105 -247.379744)
		(width 0.16002)
		(layer "In11.Cu")
		(net "M_F_CPU0_SA_DQS_DN<9>")
	)
	(segment
		(start 301.959264 -239.938052)
		(end 305.238912 -239.938052)
		(width 0.16002)
		(layer "In11.Cu")
		(net "M_F_CPU0_SA_DQS_DN<9>")
	)
	(segment
		(start 328.982578 -247.239282)
		(end 328.99096 -247.244108)
		(width 0.09525)
		(layer "In11.Cu")
		(net "M_F_CPU0_SA_DQS_DN<9>")
	)
	(segment
		(start 287.191196 -240.258092)
		(end 288.936684 -240.258092)
		(width 0.16002)
		(layer "In11.Cu")
		(net "M_F_CPU0_SA_DQS_DN<9>")
	)
	(segment
		(start 294.73525 -240.258092)
		(end 296.480738 -240.258092)
		(width 0.16002)
		(layer "In11.Cu")
		(net "M_F_CPU0_SA_DQS_DN<9>")
	)
	(segment
		(start 323.36105 -247.379744)
		(end 323.895974 -247.379744)
		(width 0.16002)
		(layer "In11.Cu")
		(net "M_F_CPU0_SA_DQS_DN<9>")
	)
	(segment
		(start 333.6163 -247.206262)
		(end 333.717138 -247.179592)
		(width 0.09525)
		(layer "In11.Cu")
		(net "M_F_CPU0_SA_DQS_DN<9>")
	)
	(segment
		(start 288.936684 -240.258092)
		(end 289.256724 -239.938052)
		(width 0.16002)
		(layer "In11.Cu")
		(net "M_F_CPU0_SA_DQS_DN<9>")
	)
	(arc
		(start 325.483982 -247.327674)
		(mid 325.808032 -247.16814)
		(end 326.162162 -247.239282)
		(width 0.09525)
		(layer "In11.Cu")
		(net "M_F_CPU0_SA_DQS_DN<9>")
	)
	(arc
		(start 329.359768 -247.239282)
		(mid 329.6412 -247.163527)
		(end 329.922632 -247.239282)
		(width 0.09525)
		(layer "In11.Cu")
		(net "M_F_CPU0_SA_DQS_DN<9>")
	)
	(arc
		(start 332.179676 -247.239282)
		(mid 332.461108 -247.163527)
		(end 332.74254 -247.239282)
		(width 0.09525)
		(layer "In11.Cu")
		(net "M_F_CPU0_SA_DQS_DN<9>")
	)
	(arc
		(start 331.802486 -247.239282)
		(mid 331.986261 -247.290054)
		(end 332.171294 -247.244108)
		(width 0.09525)
		(layer "In11.Cu")
		(net "M_F_CPU0_SA_DQS_DN<9>")
	)
	(arc
		(start 326.549766 -247.233186)
		(mid 326.826674 -247.163509)
		(end 327.101962 -247.239282)
		(width 0.09525)
		(layer "In11.Cu")
		(net "M_F_CPU0_SA_DQS_DN<9>")
	)
	(arc
		(start 327.479406 -247.239282)
		(mid 327.754949 -247.163433)
		(end 328.03211 -247.233186)
		(width 0.09525)
		(layer "In11.Cu")
		(net "M_F_CPU0_SA_DQS_DN<9>")
	)
	(arc
		(start 326.162162 -247.239282)
		(mid 326.342441 -247.290113)
		(end 326.524874 -247.247664)
		(width 0.09525)
		(layer "In11.Cu")
		(net "M_F_CPU0_SA_DQS_DN<9>")
	)
	(arc
		(start 327.101962 -247.239282)
		(mid 327.290684 -247.290086)
		(end 327.479406 -247.239282)
		(width 0.09525)
		(layer "In11.Cu")
		(net "M_F_CPU0_SA_DQS_DN<9>")
	)
	(arc
		(start 330.862432 -247.239282)
		(mid 331.046207 -247.290054)
		(end 331.23124 -247.244108)
		(width 0.09525)
		(layer "In11.Cu")
		(net "M_F_CPU0_SA_DQS_DN<9>")
	)
	(arc
		(start 331.239622 -247.239282)
		(mid 331.521054 -247.163527)
		(end 331.802486 -247.239282)
		(width 0.09525)
		(layer "In11.Cu")
		(net "M_F_CPU0_SA_DQS_DN<9>")
	)
	(arc
		(start 330.299568 -247.239282)
		(mid 330.581 -247.163527)
		(end 330.862432 -247.239282)
		(width 0.09525)
		(layer "In11.Cu")
		(net "M_F_CPU0_SA_DQS_DN<9>")
	)
	(arc
		(start 332.750922 -247.244108)
		(mid 332.935954 -247.290022)
		(end 333.11973 -247.239282)
		(width 0.09525)
		(layer "In11.Cu")
		(net "M_F_CPU0_SA_DQS_DN<9>")
	)
	(arc
		(start 328.99096 -247.244108)
		(mid 329.175992 -247.290022)
		(end 329.359768 -247.239282)
		(width 0.09525)
		(layer "In11.Cu")
		(net "M_F_CPU0_SA_DQS_DN<9>")
	)
	(arc
		(start 329.922632 -247.239282)
		(mid 330.1111 -247.289959)
		(end 330.299568 -247.239282)
		(width 0.09525)
		(layer "In11.Cu")
		(net "M_F_CPU0_SA_DQS_DN<9>")
	)
	(arc
		(start 333.11973 -247.239282)
		(mid 333.353274 -247.165576)
		(end 333.59598 -247.198388)
		(width 0.09525)
		(layer "In11.Cu")
		(net "M_F_CPU0_SA_DQS_DN<9>")
	)
	(arc
		(start 328.419714 -247.239282)
		(mid 328.701146 -247.163527)
		(end 328.982578 -247.239282)
		(width 0.09525)
		(layer "In11.Cu")
		(net "M_F_CPU0_SA_DQS_DN<9>")
	)
	(arc
		(start 328.042524 -247.239282)
		(mid 328.226299 -247.290054)
		(end 328.411332 -247.244108)
		(width 0.09525)
		(layer "In11.Cu")
		(net "M_F_CPU0_SA_DQS_DN<9>")
	)
	(arc
		(start 333.59598 -247.198388)
		(mid 333.606179 -247.202225)
		(end 333.6163 -247.206262)
		(width 0.09525)
		(layer "In11.Cu")
		(net "M_F_CPU0_SA_DQS_DN<9>")
	)
	(segment
		(start 334.337914 -242.320064)
		(end 333.871062 -242.054126)
		(width 0.12954)
		(layer "F.Cu")
		(net "M_F_CPU0_SA_DQS_DN<8>")
	)
	(segment
		(start 296.800778 -230.588058)
		(end 297.278298 -230.588058)
		(width 0.16002)
		(layer "In11.Cu")
		(net "M_F_CPU0_SA_DQS_DN<8>")
	)
	(segment
		(start 268.927834 -230.08971)
		(end 271.317974 -230.08971)
		(width 0.16002)
		(layer "In11.Cu")
		(net "M_F_CPU0_SA_DQS_DN<8>")
	)
	(segment
		(start 310.670194 -235.232702)
		(end 316.731142 -241.29365)
		(width 0.16002)
		(layer "In11.Cu")
		(net "M_F_CPU0_SA_DQS_DN<8>")
	)
	(segment
		(start 276.08276 -229.703884)
		(end 276.436836 -230.05796)
		(width 0.16002)
		(layer "In11.Cu")
		(net "M_F_CPU0_SA_DQS_DN<8>")
	)
	(segment
		(start 286.341058 -230.05796)
		(end 287.191196 -230.908098)
		(width 0.16002)
		(layer "In11.Cu")
		(net "M_F_CPU0_SA_DQS_DN<8>")
	)
	(segment
		(start 283.98089 -230.05796)
		(end 286.341058 -230.05796)
		(width 0.16002)
		(layer "In11.Cu")
		(net "M_F_CPU0_SA_DQS_DN<8>")
	)
	(segment
		(start 274.168616 -230.588058)
		(end 274.646136 -230.588058)
		(width 0.16002)
		(layer "In11.Cu")
		(net "M_F_CPU0_SA_DQS_DN<8>")
	)
	(segment
		(start 305.706272 -229.703884)
		(end 306.813712 -229.703884)
		(width 0.16002)
		(layer "In11.Cu")
		(net "M_F_CPU0_SA_DQS_DN<8>")
	)
	(segment
		(start 268.581378 -229.743254)
		(end 268.927834 -230.08971)
		(width 0.16002)
		(layer "In11.Cu")
		(net "M_F_CPU0_SA_DQS_DN<8>")
	)
	(segment
		(start 333.6163 -242.346226)
		(end 333.717138 -242.319556)
		(width 0.09525)
		(layer "In11.Cu")
		(net "M_F_CPU0_SA_DQS_DN<8>")
	)
	(segment
		(start 298.162472 -229.703884)
		(end 298.714922 -229.703884)
		(width 0.16002)
		(layer "In11.Cu")
		(net "M_F_CPU0_SA_DQS_DN<8>")
	)
	(segment
		(start 328.03211 -242.37315)
		(end 328.042524 -242.379246)
		(width 0.09525)
		(layer "In11.Cu")
		(net "M_F_CPU0_SA_DQS_DN<8>")
	)
	(segment
		(start 325.745348 -242.3033)
		(end 325.880476 -242.3033)
		(width 0.09525)
		(layer "In11.Cu")
		(net "M_F_CPU0_SA_DQS_DN<8>")
	)
	(segment
		(start 293.885112 -230.05796)
		(end 294.73525 -230.908098)
		(width 0.16002)
		(layer "In11.Cu")
		(net "M_F_CPU0_SA_DQS_DN<8>")
	)
	(segment
		(start 306.813712 -229.703884)
		(end 310.670194 -233.560366)
		(width 0.16002)
		(layer "In11.Cu")
		(net "M_F_CPU0_SA_DQS_DN<8>")
	)
	(segment
		(start 297.278298 -230.588058)
		(end 298.162472 -229.703884)
		(width 0.16002)
		(layer "In11.Cu")
		(net "M_F_CPU0_SA_DQS_DN<8>")
	)
	(segment
		(start 282.19019 -230.588058)
		(end 283.074364 -229.703884)
		(width 0.16002)
		(layer "In11.Cu")
		(net "M_F_CPU0_SA_DQS_DN<8>")
	)
	(segment
		(start 289.734244 -230.588058)
		(end 290.618418 -229.703884)
		(width 0.16002)
		(layer "In11.Cu")
		(net "M_F_CPU0_SA_DQS_DN<8>")
	)
	(segment
		(start 323.804788 -241.352578)
		(end 324.056248 -241.352578)
		(width 0.09525)
		(layer "In11.Cu")
		(net "M_F_CPU0_SA_DQS_DN<8>")
	)
	(segment
		(start 272.136362 -230.908098)
		(end 273.848576 -230.908098)
		(width 0.16002)
		(layer "In11.Cu")
		(net "M_F_CPU0_SA_DQS_DN<8>")
	)
	(segment
		(start 278.797004 -230.05796)
		(end 279.647142 -230.908098)
		(width 0.16002)
		(layer "In11.Cu")
		(net "M_F_CPU0_SA_DQS_DN<8>")
	)
	(segment
		(start 328.411332 -242.384072)
		(end 328.419714 -242.379246)
		(width 0.09525)
		(layer "In11.Cu")
		(net "M_F_CPU0_SA_DQS_DN<8>")
	)
	(segment
		(start 291.170868 -229.703884)
		(end 291.524944 -230.05796)
		(width 0.16002)
		(layer "In11.Cu")
		(net "M_F_CPU0_SA_DQS_DN<8>")
	)
	(segment
		(start 324.67677 -241.9731)
		(end 325.415148 -241.9731)
		(width 0.09525)
		(layer "In11.Cu")
		(net "M_F_CPU0_SA_DQS_DN<8>")
	)
	(segment
		(start 294.73525 -230.908098)
		(end 296.480738 -230.908098)
		(width 0.16002)
		(layer "In11.Cu")
		(net "M_F_CPU0_SA_DQS_DN<8>")
	)
	(segment
		(start 275.53031 -229.703884)
		(end 276.08276 -229.703884)
		(width 0.16002)
		(layer "In11.Cu")
		(net "M_F_CPU0_SA_DQS_DN<8>")
	)
	(segment
		(start 310.670194 -233.560366)
		(end 310.670194 -235.232702)
		(width 0.16002)
		(layer "In11.Cu")
		(net "M_F_CPU0_SA_DQS_DN<8>")
	)
	(segment
		(start 301.959264 -230.588058)
		(end 304.822098 -230.588058)
		(width 0.16002)
		(layer "In11.Cu")
		(net "M_F_CPU0_SA_DQS_DN<8>")
	)
	(segment
		(start 333.717138 -242.319556)
		(end 333.871062 -242.054126)
		(width 0.09525)
		(layer "In11.Cu")
		(net "M_F_CPU0_SA_DQS_DN<8>")
	)
	(segment
		(start 326.524874 -242.387628)
		(end 326.539352 -242.379246)
		(width 0.09525)
		(layer "In11.Cu")
		(net "M_F_CPU0_SA_DQS_DN<8>")
	)
	(segment
		(start 274.646136 -230.588058)
		(end 275.53031 -229.703884)
		(width 0.16002)
		(layer "In11.Cu")
		(net "M_F_CPU0_SA_DQS_DN<8>")
	)
	(segment
		(start 289.256724 -230.588058)
		(end 289.734244 -230.588058)
		(width 0.16002)
		(layer "In11.Cu")
		(net "M_F_CPU0_SA_DQS_DN<8>")
	)
	(segment
		(start 265.821922 -229.908862)
		(end 267.576046 -229.908862)
		(width 0.16002)
		(layer "In11.Cu")
		(net "M_F_CPU0_SA_DQS_DN<8>")
	)
	(segment
		(start 271.317974 -230.08971)
		(end 272.136362 -230.908098)
		(width 0.16002)
		(layer "In11.Cu")
		(net "M_F_CPU0_SA_DQS_DN<8>")
	)
	(segment
		(start 316.731142 -241.29365)
		(end 323.722238 -241.29365)
		(width 0.16002)
		(layer "In11.Cu")
		(net "M_F_CPU0_SA_DQS_DN<8>")
	)
	(segment
		(start 299.068998 -230.05796)
		(end 301.429166 -230.05796)
		(width 0.16002)
		(layer "In11.Cu")
		(net "M_F_CPU0_SA_DQS_DN<8>")
	)
	(segment
		(start 323.74586 -241.29365)
		(end 323.804788 -241.352578)
		(width 0.09525)
		(layer "In11.Cu")
		(net "M_F_CPU0_SA_DQS_DN<8>")
	)
	(segment
		(start 267.576046 -229.908862)
		(end 267.741654 -229.743254)
		(width 0.16002)
		(layer "In11.Cu")
		(net "M_F_CPU0_SA_DQS_DN<8>")
	)
	(segment
		(start 332.74254 -242.379246)
		(end 332.750922 -242.384072)
		(width 0.09525)
		(layer "In11.Cu")
		(net "M_F_CPU0_SA_DQS_DN<8>")
	)
	(segment
		(start 323.722238 -241.29365)
		(end 323.74586 -241.29365)
		(width 0.09525)
		(layer "In11.Cu")
		(net "M_F_CPU0_SA_DQS_DN<8>")
	)
	(segment
		(start 296.480738 -230.908098)
		(end 296.800778 -230.588058)
		(width 0.16002)
		(layer "In11.Cu")
		(net "M_F_CPU0_SA_DQS_DN<8>")
	)
	(segment
		(start 328.982578 -242.379246)
		(end 328.99096 -242.384072)
		(width 0.09525)
		(layer "In11.Cu")
		(net "M_F_CPU0_SA_DQS_DN<8>")
	)
	(segment
		(start 283.626814 -229.703884)
		(end 283.98089 -230.05796)
		(width 0.16002)
		(layer "In11.Cu")
		(net "M_F_CPU0_SA_DQS_DN<8>")
	)
	(segment
		(start 281.71267 -230.588058)
		(end 282.19019 -230.588058)
		(width 0.16002)
		(layer "In11.Cu")
		(net "M_F_CPU0_SA_DQS_DN<8>")
	)
	(segment
		(start 279.647142 -230.908098)
		(end 281.39263 -230.908098)
		(width 0.16002)
		(layer "In11.Cu")
		(net "M_F_CPU0_SA_DQS_DN<8>")
	)
	(segment
		(start 287.191196 -230.908098)
		(end 288.936684 -230.908098)
		(width 0.16002)
		(layer "In11.Cu")
		(net "M_F_CPU0_SA_DQS_DN<8>")
	)
	(segment
		(start 298.714922 -229.703884)
		(end 299.068998 -230.05796)
		(width 0.16002)
		(layer "In11.Cu")
		(net "M_F_CPU0_SA_DQS_DN<8>")
	)
	(segment
		(start 290.618418 -229.703884)
		(end 291.170868 -229.703884)
		(width 0.16002)
		(layer "In11.Cu")
		(net "M_F_CPU0_SA_DQS_DN<8>")
	)
	(segment
		(start 273.848576 -230.908098)
		(end 274.168616 -230.588058)
		(width 0.16002)
		(layer "In11.Cu")
		(net "M_F_CPU0_SA_DQS_DN<8>")
	)
	(segment
		(start 267.741654 -229.743254)
		(end 268.581378 -229.743254)
		(width 0.16002)
		(layer "In11.Cu")
		(net "M_F_CPU0_SA_DQS_DN<8>")
	)
	(segment
		(start 324.056248 -241.352578)
		(end 324.67677 -241.9731)
		(width 0.09525)
		(layer "In11.Cu")
		(net "M_F_CPU0_SA_DQS_DN<8>")
	)
	(segment
		(start 301.429166 -230.05796)
		(end 301.959264 -230.588058)
		(width 0.16002)
		(layer "In11.Cu")
		(net "M_F_CPU0_SA_DQS_DN<8>")
	)
	(segment
		(start 288.936684 -230.908098)
		(end 289.256724 -230.588058)
		(width 0.16002)
		(layer "In11.Cu")
		(net "M_F_CPU0_SA_DQS_DN<8>")
	)
	(segment
		(start 331.23124 -242.384072)
		(end 331.239622 -242.379246)
		(width 0.09525)
		(layer "In11.Cu")
		(net "M_F_CPU0_SA_DQS_DN<8>")
	)
	(segment
		(start 265.54811 -229.63505)
		(end 265.821922 -229.908862)
		(width 0.16002)
		(layer "In11.Cu")
		(net "M_F_CPU0_SA_DQS_DN<8>")
	)
	(segment
		(start 332.171294 -242.384072)
		(end 332.179676 -242.379246)
		(width 0.09525)
		(layer "In11.Cu")
		(net "M_F_CPU0_SA_DQS_DN<8>")
	)
	(segment
		(start 325.415148 -241.9731)
		(end 325.745348 -242.3033)
		(width 0.09525)
		(layer "In11.Cu")
		(net "M_F_CPU0_SA_DQS_DN<8>")
	)
	(segment
		(start 281.39263 -230.908098)
		(end 281.71267 -230.588058)
		(width 0.16002)
		(layer "In11.Cu")
		(net "M_F_CPU0_SA_DQS_DN<8>")
	)
	(segment
		(start 326.539352 -242.379246)
		(end 326.549766 -242.37315)
		(width 0.09525)
		(layer "In11.Cu")
		(net "M_F_CPU0_SA_DQS_DN<8>")
	)
	(segment
		(start 276.436836 -230.05796)
		(end 278.797004 -230.05796)
		(width 0.16002)
		(layer "In11.Cu")
		(net "M_F_CPU0_SA_DQS_DN<8>")
	)
	(segment
		(start 291.524944 -230.05796)
		(end 293.885112 -230.05796)
		(width 0.16002)
		(layer "In11.Cu")
		(net "M_F_CPU0_SA_DQS_DN<8>")
	)
	(segment
		(start 283.074364 -229.703884)
		(end 283.626814 -229.703884)
		(width 0.16002)
		(layer "In11.Cu")
		(net "M_F_CPU0_SA_DQS_DN<8>")
	)
	(segment
		(start 304.822098 -230.588058)
		(end 305.706272 -229.703884)
		(width 0.16002)
		(layer "In11.Cu")
		(net "M_F_CPU0_SA_DQS_DN<8>")
	)
	(arc
		(start 328.042524 -242.379246)
		(mid 328.226299 -242.430018)
		(end 328.411332 -242.384072)
		(width 0.09525)
		(layer "In11.Cu")
		(net "M_F_CPU0_SA_DQS_DN<8>")
	)
	(arc
		(start 329.922632 -242.379246)
		(mid 330.1111 -242.429923)
		(end 330.299568 -242.379246)
		(width 0.09525)
		(layer "In11.Cu")
		(net "M_F_CPU0_SA_DQS_DN<8>")
	)
	(arc
		(start 328.419714 -242.379246)
		(mid 328.701146 -242.303491)
		(end 328.982578 -242.379246)
		(width 0.09525)
		(layer "In11.Cu")
		(net "M_F_CPU0_SA_DQS_DN<8>")
	)
	(arc
		(start 328.99096 -242.384072)
		(mid 329.175992 -242.429986)
		(end 329.359768 -242.379246)
		(width 0.09525)
		(layer "In11.Cu")
		(net "M_F_CPU0_SA_DQS_DN<8>")
	)
	(arc
		(start 327.479406 -242.379246)
		(mid 327.754949 -242.303397)
		(end 328.03211 -242.37315)
		(width 0.09525)
		(layer "In11.Cu")
		(net "M_F_CPU0_SA_DQS_DN<8>")
	)
	(arc
		(start 330.862432 -242.379246)
		(mid 331.046207 -242.430018)
		(end 331.23124 -242.384072)
		(width 0.09525)
		(layer "In11.Cu")
		(net "M_F_CPU0_SA_DQS_DN<8>")
	)
	(arc
		(start 330.299568 -242.379246)
		(mid 330.581 -242.303491)
		(end 330.862432 -242.379246)
		(width 0.09525)
		(layer "In11.Cu")
		(net "M_F_CPU0_SA_DQS_DN<8>")
	)
	(arc
		(start 331.239622 -242.379246)
		(mid 331.521054 -242.303491)
		(end 331.802486 -242.379246)
		(width 0.09525)
		(layer "In11.Cu")
		(net "M_F_CPU0_SA_DQS_DN<8>")
	)
	(arc
		(start 333.11973 -242.379246)
		(mid 333.353274 -242.30554)
		(end 333.59598 -242.338352)
		(width 0.09525)
		(layer "In11.Cu")
		(net "M_F_CPU0_SA_DQS_DN<8>")
	)
	(arc
		(start 331.802486 -242.379246)
		(mid 331.986261 -242.430018)
		(end 332.171294 -242.384072)
		(width 0.09525)
		(layer "In11.Cu")
		(net "M_F_CPU0_SA_DQS_DN<8>")
	)
	(arc
		(start 326.549766 -242.37315)
		(mid 326.826674 -242.303473)
		(end 327.101962 -242.379246)
		(width 0.09525)
		(layer "In11.Cu")
		(net "M_F_CPU0_SA_DQS_DN<8>")
	)
	(arc
		(start 333.59598 -242.338352)
		(mid 333.606179 -242.342189)
		(end 333.6163 -242.346226)
		(width 0.09525)
		(layer "In11.Cu")
		(net "M_F_CPU0_SA_DQS_DN<8>")
	)
	(arc
		(start 326.162162 -242.379246)
		(mid 326.342441 -242.430077)
		(end 326.524874 -242.387628)
		(width 0.09525)
		(layer "In11.Cu")
		(net "M_F_CPU0_SA_DQS_DN<8>")
	)
	(arc
		(start 325.880476 -242.3033)
		(mid 326.026336 -242.322659)
		(end 326.162162 -242.379246)
		(width 0.09525)
		(layer "In11.Cu")
		(net "M_F_CPU0_SA_DQS_DN<8>")
	)
	(arc
		(start 332.179676 -242.379246)
		(mid 332.461108 -242.303491)
		(end 332.74254 -242.379246)
		(width 0.09525)
		(layer "In11.Cu")
		(net "M_F_CPU0_SA_DQS_DN<8>")
	)
	(arc
		(start 329.359768 -242.379246)
		(mid 329.6412 -242.303491)
		(end 329.922632 -242.379246)
		(width 0.09525)
		(layer "In11.Cu")
		(net "M_F_CPU0_SA_DQS_DN<8>")
	)
	(arc
		(start 332.750922 -242.384072)
		(mid 332.935954 -242.429986)
		(end 333.11973 -242.379246)
		(width 0.09525)
		(layer "In11.Cu")
		(net "M_F_CPU0_SA_DQS_DN<8>")
	)
	(arc
		(start 327.101962 -242.379246)
		(mid 327.290684 -242.43005)
		(end 327.479406 -242.379246)
		(width 0.09525)
		(layer "In11.Cu")
		(net "M_F_CPU0_SA_DQS_DN<8>")
	)
	(segment
		(start 334.337914 -237.460028)
		(end 333.871062 -237.19409)
		(width 0.12954)
		(layer "F.Cu")
		(net "M_F_CPU0_SA_DQS_DN<7>")
	)
	(segment
		(start 326.524874 -237.527592)
		(end 326.526398 -237.526576)
		(width 0.09525)
		(layer "In11.Cu")
		(net "M_F_CPU0_SA_DQS_DN<7>")
	)
	(segment
		(start 283.626814 -220.35389)
		(end 283.98089 -220.707966)
		(width 0.16002)
		(layer "In11.Cu")
		(net "M_F_CPU0_SA_DQS_DN<7>")
	)
	(segment
		(start 281.71267 -221.238064)
		(end 282.19019 -221.238064)
		(width 0.16002)
		(layer "In11.Cu")
		(net "M_F_CPU0_SA_DQS_DN<7>")
	)
	(segment
		(start 290.618418 -220.35389)
		(end 291.170868 -220.35389)
		(width 0.16002)
		(layer "In11.Cu")
		(net "M_F_CPU0_SA_DQS_DN<7>")
	)
	(segment
		(start 310.603138 -224.263966)
		(end 310.603138 -224.794318)
		(width 0.16002)
		(layer "In11.Cu")
		(net "M_F_CPU0_SA_DQS_DN<7>")
	)
	(segment
		(start 332.74254 -237.51921)
		(end 332.750922 -237.524036)
		(width 0.09525)
		(layer "In11.Cu")
		(net "M_F_CPU0_SA_DQS_DN<7>")
	)
	(segment
		(start 306.140358 -221.774512)
		(end 306.386738 -221.528132)
		(width 0.16002)
		(layer "In11.Cu")
		(net "M_F_CPU0_SA_DQS_DN<7>")
	)
	(segment
		(start 273.848576 -221.558104)
		(end 274.168616 -221.238064)
		(width 0.16002)
		(layer "In11.Cu")
		(net "M_F_CPU0_SA_DQS_DN<7>")
	)
	(segment
		(start 301.429166 -220.707966)
		(end 301.959264 -221.238064)
		(width 0.16002)
		(layer "In11.Cu")
		(net "M_F_CPU0_SA_DQS_DN<7>")
	)
	(segment
		(start 305.711098 -221.774512)
		(end 306.140358 -221.774512)
		(width 0.16002)
		(layer "In11.Cu")
		(net "M_F_CPU0_SA_DQS_DN<7>")
	)
	(segment
		(start 325.329804 -236.70514)
		(end 326.084946 -237.460282)
		(width 0.09525)
		(layer "In11.Cu")
		(net "M_F_CPU0_SA_DQS_DN<7>")
	)
	(segment
		(start 324.993508 -236.10316)
		(end 325.329804 -236.439456)
		(width 0.09525)
		(layer "In11.Cu")
		(net "M_F_CPU0_SA_DQS_DN<7>")
	)
	(segment
		(start 328.982578 -237.51921)
		(end 328.99096 -237.524036)
		(width 0.09525)
		(layer "In11.Cu")
		(net "M_F_CPU0_SA_DQS_DN<7>")
	)
	(segment
		(start 296.800778 -221.238064)
		(end 297.278298 -221.238064)
		(width 0.16002)
		(layer "In11.Cu")
		(net "M_F_CPU0_SA_DQS_DN<7>")
	)
	(segment
		(start 305.17465 -221.238064)
		(end 305.711098 -221.774512)
		(width 0.16002)
		(layer "In11.Cu")
		(net "M_F_CPU0_SA_DQS_DN<7>")
	)
	(segment
		(start 307.867304 -221.528132)
		(end 310.603138 -224.263966)
		(width 0.16002)
		(layer "In11.Cu")
		(net "M_F_CPU0_SA_DQS_DN<7>")
	)
	(segment
		(start 268.581378 -220.39326)
		(end 268.927834 -220.739716)
		(width 0.16002)
		(layer "In11.Cu")
		(net "M_F_CPU0_SA_DQS_DN<7>")
	)
	(segment
		(start 265.821922 -220.558868)
		(end 267.576046 -220.558868)
		(width 0.16002)
		(layer "In11.Cu")
		(net "M_F_CPU0_SA_DQS_DN<7>")
	)
	(segment
		(start 287.191196 -221.558104)
		(end 288.936684 -221.558104)
		(width 0.16002)
		(layer "In11.Cu")
		(net "M_F_CPU0_SA_DQS_DN<7>")
	)
	(segment
		(start 293.885112 -220.707966)
		(end 294.73525 -221.558104)
		(width 0.16002)
		(layer "In11.Cu")
		(net "M_F_CPU0_SA_DQS_DN<7>")
	)
	(segment
		(start 325.329804 -236.439456)
		(end 325.329804 -236.70514)
		(width 0.09525)
		(layer "In11.Cu")
		(net "M_F_CPU0_SA_DQS_DN<7>")
	)
	(segment
		(start 326.084946 -237.460282)
		(end 326.085454 -237.460028)
		(width 0.09525)
		(layer "In11.Cu")
		(net "M_F_CPU0_SA_DQS_DN<7>")
	)
	(segment
		(start 268.927834 -220.739716)
		(end 271.317974 -220.739716)
		(width 0.16002)
		(layer "In11.Cu")
		(net "M_F_CPU0_SA_DQS_DN<7>")
	)
	(segment
		(start 333.6163 -237.48619)
		(end 333.717138 -237.45952)
		(width 0.09525)
		(layer "In11.Cu")
		(net "M_F_CPU0_SA_DQS_DN<7>")
	)
	(segment
		(start 278.797004 -220.707966)
		(end 279.647142 -221.558104)
		(width 0.16002)
		(layer "In11.Cu")
		(net "M_F_CPU0_SA_DQS_DN<7>")
	)
	(segment
		(start 324.21576 -235.712762)
		(end 324.606158 -236.10316)
		(width 0.09525)
		(layer "In11.Cu")
		(net "M_F_CPU0_SA_DQS_DN<7>")
	)
	(segment
		(start 291.524944 -220.707966)
		(end 293.885112 -220.707966)
		(width 0.16002)
		(layer "In11.Cu")
		(net "M_F_CPU0_SA_DQS_DN<7>")
	)
	(segment
		(start 281.39263 -221.558104)
		(end 281.71267 -221.238064)
		(width 0.16002)
		(layer "In11.Cu")
		(net "M_F_CPU0_SA_DQS_DN<7>")
	)
	(segment
		(start 297.278298 -221.238064)
		(end 298.162472 -220.35389)
		(width 0.16002)
		(layer "In11.Cu")
		(net "M_F_CPU0_SA_DQS_DN<7>")
	)
	(segment
		(start 301.959264 -221.238064)
		(end 305.17465 -221.238064)
		(width 0.16002)
		(layer "In11.Cu")
		(net "M_F_CPU0_SA_DQS_DN<7>")
	)
	(segment
		(start 324.606158 -236.10316)
		(end 324.993508 -236.10316)
		(width 0.09525)
		(layer "In11.Cu")
		(net "M_F_CPU0_SA_DQS_DN<7>")
	)
	(segment
		(start 332.171294 -237.524036)
		(end 332.179676 -237.51921)
		(width 0.09525)
		(layer "In11.Cu")
		(net "M_F_CPU0_SA_DQS_DN<7>")
	)
	(segment
		(start 267.576046 -220.558868)
		(end 267.741654 -220.39326)
		(width 0.16002)
		(layer "In11.Cu")
		(net "M_F_CPU0_SA_DQS_DN<7>")
	)
	(segment
		(start 328.411332 -237.524036)
		(end 328.419714 -237.51921)
		(width 0.09525)
		(layer "In11.Cu")
		(net "M_F_CPU0_SA_DQS_DN<7>")
	)
	(segment
		(start 279.647142 -221.558104)
		(end 281.39263 -221.558104)
		(width 0.16002)
		(layer "In11.Cu")
		(net "M_F_CPU0_SA_DQS_DN<7>")
	)
	(segment
		(start 274.168616 -221.238064)
		(end 274.646136 -221.238064)
		(width 0.16002)
		(layer "In11.Cu")
		(net "M_F_CPU0_SA_DQS_DN<7>")
	)
	(segment
		(start 286.341058 -220.707966)
		(end 287.191196 -221.558104)
		(width 0.16002)
		(layer "In11.Cu")
		(net "M_F_CPU0_SA_DQS_DN<7>")
	)
	(segment
		(start 288.936684 -221.558104)
		(end 289.256724 -221.238064)
		(width 0.16002)
		(layer "In11.Cu")
		(net "M_F_CPU0_SA_DQS_DN<7>")
	)
	(segment
		(start 296.480738 -221.558104)
		(end 296.800778 -221.238064)
		(width 0.16002)
		(layer "In11.Cu")
		(net "M_F_CPU0_SA_DQS_DN<7>")
	)
	(segment
		(start 323.919596 -235.65358)
		(end 323.978778 -235.712762)
		(width 0.09525)
		(layer "In11.Cu")
		(net "M_F_CPU0_SA_DQS_DN<7>")
	)
	(segment
		(start 274.646136 -221.238064)
		(end 275.53031 -220.35389)
		(width 0.16002)
		(layer "In11.Cu")
		(net "M_F_CPU0_SA_DQS_DN<7>")
	)
	(segment
		(start 289.256724 -221.238064)
		(end 289.734244 -221.238064)
		(width 0.16002)
		(layer "In11.Cu")
		(net "M_F_CPU0_SA_DQS_DN<7>")
	)
	(segment
		(start 275.53031 -220.35389)
		(end 276.08276 -220.35389)
		(width 0.16002)
		(layer "In11.Cu")
		(net "M_F_CPU0_SA_DQS_DN<7>")
	)
	(segment
		(start 283.074364 -220.35389)
		(end 283.626814 -220.35389)
		(width 0.16002)
		(layer "In11.Cu")
		(net "M_F_CPU0_SA_DQS_DN<7>")
	)
	(segment
		(start 299.068998 -220.707966)
		(end 301.429166 -220.707966)
		(width 0.16002)
		(layer "In11.Cu")
		(net "M_F_CPU0_SA_DQS_DN<7>")
	)
	(segment
		(start 298.714922 -220.35389)
		(end 299.068998 -220.707966)
		(width 0.16002)
		(layer "In11.Cu")
		(net "M_F_CPU0_SA_DQS_DN<7>")
	)
	(segment
		(start 323.895974 -235.65358)
		(end 323.919596 -235.65358)
		(width 0.09525)
		(layer "In11.Cu")
		(net "M_F_CPU0_SA_DQS_DN<7>")
	)
	(segment
		(start 323.978778 -235.712762)
		(end 324.21576 -235.712762)
		(width 0.09525)
		(layer "In11.Cu")
		(net "M_F_CPU0_SA_DQS_DN<7>")
	)
	(segment
		(start 326.539352 -237.51921)
		(end 326.549766 -237.513114)
		(width 0.09525)
		(layer "In11.Cu")
		(net "M_F_CPU0_SA_DQS_DN<7>")
	)
	(segment
		(start 294.73525 -221.558104)
		(end 296.480738 -221.558104)
		(width 0.16002)
		(layer "In11.Cu")
		(net "M_F_CPU0_SA_DQS_DN<7>")
	)
	(segment
		(start 306.386738 -221.528132)
		(end 307.867304 -221.528132)
		(width 0.16002)
		(layer "In11.Cu")
		(net "M_F_CPU0_SA_DQS_DN<7>")
	)
	(segment
		(start 276.436836 -220.707966)
		(end 278.797004 -220.707966)
		(width 0.16002)
		(layer "In11.Cu")
		(net "M_F_CPU0_SA_DQS_DN<7>")
	)
	(segment
		(start 289.734244 -221.238064)
		(end 290.618418 -220.35389)
		(width 0.16002)
		(layer "In11.Cu")
		(net "M_F_CPU0_SA_DQS_DN<7>")
	)
	(segment
		(start 271.317974 -220.739716)
		(end 272.136362 -221.558104)
		(width 0.16002)
		(layer "In11.Cu")
		(net "M_F_CPU0_SA_DQS_DN<7>")
	)
	(segment
		(start 328.03211 -237.513114)
		(end 328.042524 -237.51921)
		(width 0.09525)
		(layer "In11.Cu")
		(net "M_F_CPU0_SA_DQS_DN<7>")
	)
	(segment
		(start 298.162472 -220.35389)
		(end 298.714922 -220.35389)
		(width 0.16002)
		(layer "In11.Cu")
		(net "M_F_CPU0_SA_DQS_DN<7>")
	)
	(segment
		(start 282.19019 -221.238064)
		(end 283.074364 -220.35389)
		(width 0.16002)
		(layer "In11.Cu")
		(net "M_F_CPU0_SA_DQS_DN<7>")
	)
	(segment
		(start 333.717138 -237.45952)
		(end 333.871062 -237.19409)
		(width 0.09525)
		(layer "In11.Cu")
		(net "M_F_CPU0_SA_DQS_DN<7>")
	)
	(segment
		(start 276.08276 -220.35389)
		(end 276.436836 -220.707966)
		(width 0.16002)
		(layer "In11.Cu")
		(net "M_F_CPU0_SA_DQS_DN<7>")
	)
	(segment
		(start 326.526398 -237.526576)
		(end 326.539352 -237.51921)
		(width 0.09525)
		(layer "In11.Cu")
		(net "M_F_CPU0_SA_DQS_DN<7>")
	)
	(segment
		(start 283.98089 -220.707966)
		(end 286.341058 -220.707966)
		(width 0.16002)
		(layer "In11.Cu")
		(net "M_F_CPU0_SA_DQS_DN<7>")
	)
	(segment
		(start 321.4624 -235.65358)
		(end 323.895974 -235.65358)
		(width 0.16002)
		(layer "In11.Cu")
		(net "M_F_CPU0_SA_DQS_DN<7>")
	)
	(segment
		(start 272.136362 -221.558104)
		(end 273.848576 -221.558104)
		(width 0.16002)
		(layer "In11.Cu")
		(net "M_F_CPU0_SA_DQS_DN<7>")
	)
	(segment
		(start 291.170868 -220.35389)
		(end 291.524944 -220.707966)
		(width 0.16002)
		(layer "In11.Cu")
		(net "M_F_CPU0_SA_DQS_DN<7>")
	)
	(segment
		(start 267.741654 -220.39326)
		(end 268.581378 -220.39326)
		(width 0.16002)
		(layer "In11.Cu")
		(net "M_F_CPU0_SA_DQS_DN<7>")
	)
	(segment
		(start 265.54811 -220.285056)
		(end 265.821922 -220.558868)
		(width 0.16002)
		(layer "In11.Cu")
		(net "M_F_CPU0_SA_DQS_DN<7>")
	)
	(segment
		(start 331.23124 -237.524036)
		(end 331.239622 -237.51921)
		(width 0.09525)
		(layer "In11.Cu")
		(net "M_F_CPU0_SA_DQS_DN<7>")
	)
	(segment
		(start 310.603138 -224.794318)
		(end 321.4624 -235.65358)
		(width 0.16002)
		(layer "In11.Cu")
		(net "M_F_CPU0_SA_DQS_DN<7>")
	)
	(arc
		(start 327.479406 -237.51921)
		(mid 327.754949 -237.443361)
		(end 328.03211 -237.513114)
		(width 0.09525)
		(layer "In11.Cu")
		(net "M_F_CPU0_SA_DQS_DN<7>")
	)
	(arc
		(start 326.085454 -237.460028)
		(mid 326.121893 -237.492102)
		(end 326.162162 -237.51921)
		(width 0.09525)
		(layer "In11.Cu")
		(net "M_F_CPU0_SA_DQS_DN<7>")
	)
	(arc
		(start 330.862432 -237.51921)
		(mid 331.046207 -237.569982)
		(end 331.23124 -237.524036)
		(width 0.09525)
		(layer "In11.Cu")
		(net "M_F_CPU0_SA_DQS_DN<7>")
	)
	(arc
		(start 331.802486 -237.51921)
		(mid 331.986261 -237.569982)
		(end 332.171294 -237.524036)
		(width 0.09525)
		(layer "In11.Cu")
		(net "M_F_CPU0_SA_DQS_DN<7>")
	)
	(arc
		(start 326.549766 -237.513114)
		(mid 326.826674 -237.443437)
		(end 327.101962 -237.51921)
		(width 0.09525)
		(layer "In11.Cu")
		(net "M_F_CPU0_SA_DQS_DN<7>")
	)
	(arc
		(start 326.162162 -237.51921)
		(mid 326.342441 -237.570041)
		(end 326.524874 -237.527592)
		(width 0.09525)
		(layer "In11.Cu")
		(net "M_F_CPU0_SA_DQS_DN<7>")
	)
	(arc
		(start 330.299568 -237.51921)
		(mid 330.581 -237.443455)
		(end 330.862432 -237.51921)
		(width 0.09525)
		(layer "In11.Cu")
		(net "M_F_CPU0_SA_DQS_DN<7>")
	)
	(arc
		(start 333.11973 -237.51921)
		(mid 333.353274 -237.445504)
		(end 333.59598 -237.478316)
		(width 0.09525)
		(layer "In11.Cu")
		(net "M_F_CPU0_SA_DQS_DN<7>")
	)
	(arc
		(start 328.042524 -237.51921)
		(mid 328.226299 -237.569982)
		(end 328.411332 -237.524036)
		(width 0.09525)
		(layer "In11.Cu")
		(net "M_F_CPU0_SA_DQS_DN<7>")
	)
	(arc
		(start 329.922632 -237.51921)
		(mid 330.1111 -237.569887)
		(end 330.299568 -237.51921)
		(width 0.09525)
		(layer "In11.Cu")
		(net "M_F_CPU0_SA_DQS_DN<7>")
	)
	(arc
		(start 331.239622 -237.51921)
		(mid 331.521054 -237.443455)
		(end 331.802486 -237.51921)
		(width 0.09525)
		(layer "In11.Cu")
		(net "M_F_CPU0_SA_DQS_DN<7>")
	)
	(arc
		(start 327.101962 -237.51921)
		(mid 327.290684 -237.570014)
		(end 327.479406 -237.51921)
		(width 0.09525)
		(layer "In11.Cu")
		(net "M_F_CPU0_SA_DQS_DN<7>")
	)
	(arc
		(start 332.179676 -237.51921)
		(mid 332.461108 -237.443455)
		(end 332.74254 -237.51921)
		(width 0.09525)
		(layer "In11.Cu")
		(net "M_F_CPU0_SA_DQS_DN<7>")
	)
	(arc
		(start 329.359768 -237.51921)
		(mid 329.6412 -237.443455)
		(end 329.922632 -237.51921)
		(width 0.09525)
		(layer "In11.Cu")
		(net "M_F_CPU0_SA_DQS_DN<7>")
	)
	(arc
		(start 332.750922 -237.524036)
		(mid 332.935954 -237.56995)
		(end 333.11973 -237.51921)
		(width 0.09525)
		(layer "In11.Cu")
		(net "M_F_CPU0_SA_DQS_DN<7>")
	)
	(arc
		(start 333.59598 -237.478316)
		(mid 333.606179 -237.482153)
		(end 333.6163 -237.48619)
		(width 0.09525)
		(layer "In11.Cu")
		(net "M_F_CPU0_SA_DQS_DN<7>")
	)
	(arc
		(start 328.419714 -237.51921)
		(mid 328.701146 -237.443455)
		(end 328.982578 -237.51921)
		(width 0.09525)
		(layer "In11.Cu")
		(net "M_F_CPU0_SA_DQS_DN<7>")
	)
	(arc
		(start 328.99096 -237.524036)
		(mid 329.175992 -237.56995)
		(end 329.359768 -237.51921)
		(width 0.09525)
		(layer "In11.Cu")
		(net "M_F_CPU0_SA_DQS_DN<7>")
	)
	(segment
		(start 334.337914 -232.599992)
		(end 333.871062 -232.334054)
		(width 0.12954)
		(layer "F.Cu")
		(net "M_F_CPU0_SA_DQS_DN<6>")
	)
	(segment
		(start 298.162472 -211.003896)
		(end 298.714922 -211.003896)
		(width 0.16002)
		(layer "In11.Cu")
		(net "M_F_CPU0_SA_DQS_DN<6>")
	)
	(segment
		(start 326.084946 -232.600246)
		(end 326.085454 -232.599992)
		(width 0.09525)
		(layer "In11.Cu")
		(net "M_F_CPU0_SA_DQS_DN<6>")
	)
	(segment
		(start 331.23124 -232.664)
		(end 331.239622 -232.659174)
		(width 0.09525)
		(layer "In11.Cu")
		(net "M_F_CPU0_SA_DQS_DN<6>")
	)
	(segment
		(start 328.03211 -232.653078)
		(end 328.042524 -232.659174)
		(width 0.09525)
		(layer "In11.Cu")
		(net "M_F_CPU0_SA_DQS_DN<6>")
	)
	(segment
		(start 326.539352 -232.659174)
		(end 326.549766 -232.653078)
		(width 0.09525)
		(layer "In11.Cu")
		(net "M_F_CPU0_SA_DQS_DN<6>")
	)
	(segment
		(start 290.618418 -211.003896)
		(end 291.170868 -211.003896)
		(width 0.16002)
		(layer "In11.Cu")
		(net "M_F_CPU0_SA_DQS_DN<6>")
	)
	(segment
		(start 323.739764 -229.99827)
		(end 323.895974 -229.99827)
		(width 0.16002)
		(layer "In11.Cu")
		(net "M_F_CPU0_SA_DQS_DN<6>")
	)
	(segment
		(start 316.297818 -222.556324)
		(end 323.739764 -229.99827)
		(width 0.16002)
		(layer "In11.Cu")
		(net "M_F_CPU0_SA_DQS_DN<6>")
	)
	(segment
		(start 305.706272 -211.003896)
		(end 307.420264 -211.003896)
		(width 0.16002)
		(layer "In11.Cu")
		(net "M_F_CPU0_SA_DQS_DN<6>")
	)
	(segment
		(start 265.54811 -210.935062)
		(end 265.821922 -211.208874)
		(width 0.16002)
		(layer "In11.Cu")
		(net "M_F_CPU0_SA_DQS_DN<6>")
	)
	(segment
		(start 275.53031 -211.003896)
		(end 276.08276 -211.003896)
		(width 0.16002)
		(layer "In11.Cu")
		(net "M_F_CPU0_SA_DQS_DN<6>")
	)
	(segment
		(start 268.927834 -211.389722)
		(end 271.317974 -211.389722)
		(width 0.16002)
		(layer "In11.Cu")
		(net "M_F_CPU0_SA_DQS_DN<6>")
	)
	(segment
		(start 301.429166 -211.357972)
		(end 301.959264 -211.88807)
		(width 0.16002)
		(layer "In11.Cu")
		(net "M_F_CPU0_SA_DQS_DN<6>")
	)
	(segment
		(start 324.383908 -230.260398)
		(end 324.383908 -230.574088)
		(width 0.09525)
		(layer "In11.Cu")
		(net "M_F_CPU0_SA_DQS_DN<6>")
	)
	(segment
		(start 297.278298 -211.88807)
		(end 298.162472 -211.003896)
		(width 0.16002)
		(layer "In11.Cu")
		(net "M_F_CPU0_SA_DQS_DN<6>")
	)
	(segment
		(start 294.73525 -212.20811)
		(end 296.480738 -212.20811)
		(width 0.16002)
		(layer "In11.Cu")
		(net "M_F_CPU0_SA_DQS_DN<6>")
	)
	(segment
		(start 325.516494 -232.031794)
		(end 326.084946 -232.600246)
		(width 0.09525)
		(layer "In11.Cu")
		(net "M_F_CPU0_SA_DQS_DN<6>")
	)
	(segment
		(start 296.480738 -212.20811)
		(end 296.800778 -211.88807)
		(width 0.16002)
		(layer "In11.Cu")
		(net "M_F_CPU0_SA_DQS_DN<6>")
	)
	(segment
		(start 298.714922 -211.003896)
		(end 299.068998 -211.357972)
		(width 0.16002)
		(layer "In11.Cu")
		(net "M_F_CPU0_SA_DQS_DN<6>")
	)
	(segment
		(start 311.083198 -214.66683)
		(end 311.083198 -216.006934)
		(width 0.16002)
		(layer "In11.Cu")
		(net "M_F_CPU0_SA_DQS_DN<6>")
	)
	(segment
		(start 323.895974 -229.99827)
		(end 323.919596 -229.99827)
		(width 0.09525)
		(layer "In11.Cu")
		(net "M_F_CPU0_SA_DQS_DN<6>")
	)
	(segment
		(start 272.136362 -212.20811)
		(end 273.848576 -212.20811)
		(width 0.16002)
		(layer "In11.Cu")
		(net "M_F_CPU0_SA_DQS_DN<6>")
	)
	(segment
		(start 281.71267 -211.88807)
		(end 282.19019 -211.88807)
		(width 0.16002)
		(layer "In11.Cu")
		(net "M_F_CPU0_SA_DQS_DN<6>")
	)
	(segment
		(start 271.317974 -211.389722)
		(end 272.136362 -212.20811)
		(width 0.16002)
		(layer "In11.Cu")
		(net "M_F_CPU0_SA_DQS_DN<6>")
	)
	(segment
		(start 268.581378 -211.043266)
		(end 268.927834 -211.389722)
		(width 0.16002)
		(layer "In11.Cu")
		(net "M_F_CPU0_SA_DQS_DN<6>")
	)
	(segment
		(start 328.982578 -232.659174)
		(end 328.99096 -232.664)
		(width 0.09525)
		(layer "In11.Cu")
		(net "M_F_CPU0_SA_DQS_DN<6>")
	)
	(segment
		(start 282.19019 -211.88807)
		(end 283.074364 -211.003896)
		(width 0.16002)
		(layer "In11.Cu")
		(net "M_F_CPU0_SA_DQS_DN<6>")
	)
	(segment
		(start 279.647142 -212.20811)
		(end 281.39263 -212.20811)
		(width 0.16002)
		(layer "In11.Cu")
		(net "M_F_CPU0_SA_DQS_DN<6>")
	)
	(segment
		(start 324.85076 -231.04094)
		(end 325.116952 -231.04094)
		(width 0.09525)
		(layer "In11.Cu")
		(net "M_F_CPU0_SA_DQS_DN<6>")
	)
	(segment
		(start 276.436836 -211.357972)
		(end 278.797004 -211.357972)
		(width 0.16002)
		(layer "In11.Cu")
		(net "M_F_CPU0_SA_DQS_DN<6>")
	)
	(segment
		(start 301.959264 -211.88807)
		(end 304.822098 -211.88807)
		(width 0.16002)
		(layer "In11.Cu")
		(net "M_F_CPU0_SA_DQS_DN<6>")
	)
	(segment
		(start 288.936684 -212.20811)
		(end 289.256724 -211.88807)
		(width 0.16002)
		(layer "In11.Cu")
		(net "M_F_CPU0_SA_DQS_DN<6>")
	)
	(segment
		(start 273.848576 -212.20811)
		(end 274.168616 -211.88807)
		(width 0.16002)
		(layer "In11.Cu")
		(net "M_F_CPU0_SA_DQS_DN<6>")
	)
	(segment
		(start 281.39263 -212.20811)
		(end 281.71267 -211.88807)
		(width 0.16002)
		(layer "In11.Cu")
		(net "M_F_CPU0_SA_DQS_DN<6>")
	)
	(segment
		(start 274.646136 -211.88807)
		(end 275.53031 -211.003896)
		(width 0.16002)
		(layer "In11.Cu")
		(net "M_F_CPU0_SA_DQS_DN<6>")
	)
	(segment
		(start 265.821922 -211.208874)
		(end 267.576046 -211.208874)
		(width 0.16002)
		(layer "In11.Cu")
		(net "M_F_CPU0_SA_DQS_DN<6>")
	)
	(segment
		(start 333.6163 -232.626154)
		(end 333.717138 -232.599484)
		(width 0.09525)
		(layer "In11.Cu")
		(net "M_F_CPU0_SA_DQS_DN<6>")
	)
	(segment
		(start 287.191196 -212.20811)
		(end 288.936684 -212.20811)
		(width 0.16002)
		(layer "In11.Cu")
		(net "M_F_CPU0_SA_DQS_DN<6>")
	)
	(segment
		(start 323.919596 -229.99827)
		(end 323.978778 -230.057452)
		(width 0.09525)
		(layer "In11.Cu")
		(net "M_F_CPU0_SA_DQS_DN<6>")
	)
	(segment
		(start 283.074364 -211.003896)
		(end 283.626814 -211.003896)
		(width 0.16002)
		(layer "In11.Cu")
		(net "M_F_CPU0_SA_DQS_DN<6>")
	)
	(segment
		(start 286.341058 -211.357972)
		(end 287.191196 -212.20811)
		(width 0.16002)
		(layer "In11.Cu")
		(net "M_F_CPU0_SA_DQS_DN<6>")
	)
	(segment
		(start 325.516494 -231.440482)
		(end 325.516494 -232.031794)
		(width 0.09525)
		(layer "In11.Cu")
		(net "M_F_CPU0_SA_DQS_DN<6>")
	)
	(segment
		(start 299.068998 -211.357972)
		(end 301.429166 -211.357972)
		(width 0.16002)
		(layer "In11.Cu")
		(net "M_F_CPU0_SA_DQS_DN<6>")
	)
	(segment
		(start 283.98089 -211.357972)
		(end 286.341058 -211.357972)
		(width 0.16002)
		(layer "In11.Cu")
		(net "M_F_CPU0_SA_DQS_DN<6>")
	)
	(segment
		(start 307.420264 -211.003896)
		(end 311.083198 -214.66683)
		(width 0.16002)
		(layer "In11.Cu")
		(net "M_F_CPU0_SA_DQS_DN<6>")
	)
	(segment
		(start 267.741654 -211.043266)
		(end 268.581378 -211.043266)
		(width 0.16002)
		(layer "In11.Cu")
		(net "M_F_CPU0_SA_DQS_DN<6>")
	)
	(segment
		(start 304.822098 -211.88807)
		(end 305.706272 -211.003896)
		(width 0.16002)
		(layer "In11.Cu")
		(net "M_F_CPU0_SA_DQS_DN<6>")
	)
	(segment
		(start 274.168616 -211.88807)
		(end 274.646136 -211.88807)
		(width 0.16002)
		(layer "In11.Cu")
		(net "M_F_CPU0_SA_DQS_DN<6>")
	)
	(segment
		(start 324.180962 -230.057452)
		(end 324.383908 -230.260398)
		(width 0.09525)
		(layer "In11.Cu")
		(net "M_F_CPU0_SA_DQS_DN<6>")
	)
	(segment
		(start 276.08276 -211.003896)
		(end 276.436836 -211.357972)
		(width 0.16002)
		(layer "In11.Cu")
		(net "M_F_CPU0_SA_DQS_DN<6>")
	)
	(segment
		(start 278.797004 -211.357972)
		(end 279.647142 -212.20811)
		(width 0.16002)
		(layer "In11.Cu")
		(net "M_F_CPU0_SA_DQS_DN<6>")
	)
	(segment
		(start 324.383908 -230.574088)
		(end 324.85076 -231.04094)
		(width 0.09525)
		(layer "In11.Cu")
		(net "M_F_CPU0_SA_DQS_DN<6>")
	)
	(segment
		(start 289.734244 -211.88807)
		(end 290.618418 -211.003896)
		(width 0.16002)
		(layer "In11.Cu")
		(net "M_F_CPU0_SA_DQS_DN<6>")
	)
	(segment
		(start 332.171294 -232.664)
		(end 332.179676 -232.659174)
		(width 0.09525)
		(layer "In11.Cu")
		(net "M_F_CPU0_SA_DQS_DN<6>")
	)
	(segment
		(start 293.885112 -211.357972)
		(end 294.73525 -212.20811)
		(width 0.16002)
		(layer "In11.Cu")
		(net "M_F_CPU0_SA_DQS_DN<6>")
	)
	(segment
		(start 283.626814 -211.003896)
		(end 283.98089 -211.357972)
		(width 0.16002)
		(layer "In11.Cu")
		(net "M_F_CPU0_SA_DQS_DN<6>")
	)
	(segment
		(start 291.170868 -211.003896)
		(end 291.524944 -211.357972)
		(width 0.16002)
		(layer "In11.Cu")
		(net "M_F_CPU0_SA_DQS_DN<6>")
	)
	(segment
		(start 323.978778 -230.057452)
		(end 324.180962 -230.057452)
		(width 0.09525)
		(layer "In11.Cu")
		(net "M_F_CPU0_SA_DQS_DN<6>")
	)
	(segment
		(start 296.800778 -211.88807)
		(end 297.278298 -211.88807)
		(width 0.16002)
		(layer "In11.Cu")
		(net "M_F_CPU0_SA_DQS_DN<6>")
	)
	(segment
		(start 291.524944 -211.357972)
		(end 293.885112 -211.357972)
		(width 0.16002)
		(layer "In11.Cu")
		(net "M_F_CPU0_SA_DQS_DN<6>")
	)
	(segment
		(start 267.576046 -211.208874)
		(end 267.741654 -211.043266)
		(width 0.16002)
		(layer "In11.Cu")
		(net "M_F_CPU0_SA_DQS_DN<6>")
	)
	(segment
		(start 328.411332 -232.664)
		(end 328.419714 -232.659174)
		(width 0.09525)
		(layer "In11.Cu")
		(net "M_F_CPU0_SA_DQS_DN<6>")
	)
	(segment
		(start 326.524874 -232.667556)
		(end 326.539352 -232.659174)
		(width 0.09525)
		(layer "In11.Cu")
		(net "M_F_CPU0_SA_DQS_DN<6>")
	)
	(segment
		(start 289.256724 -211.88807)
		(end 289.734244 -211.88807)
		(width 0.16002)
		(layer "In11.Cu")
		(net "M_F_CPU0_SA_DQS_DN<6>")
	)
	(segment
		(start 333.717138 -232.599484)
		(end 333.871062 -232.334054)
		(width 0.09525)
		(layer "In11.Cu")
		(net "M_F_CPU0_SA_DQS_DN<6>")
	)
	(segment
		(start 316.297818 -221.221554)
		(end 316.297818 -222.556324)
		(width 0.16002)
		(layer "In11.Cu")
		(net "M_F_CPU0_SA_DQS_DN<6>")
	)
	(segment
		(start 311.083198 -216.006934)
		(end 316.297818 -221.221554)
		(width 0.16002)
		(layer "In11.Cu")
		(net "M_F_CPU0_SA_DQS_DN<6>")
	)
	(segment
		(start 332.74254 -232.659174)
		(end 332.750922 -232.664)
		(width 0.09525)
		(layer "In11.Cu")
		(net "M_F_CPU0_SA_DQS_DN<6>")
	)
	(segment
		(start 325.116952 -231.04094)
		(end 325.516494 -231.440482)
		(width 0.09525)
		(layer "In11.Cu")
		(net "M_F_CPU0_SA_DQS_DN<6>")
	)
	(arc
		(start 329.922632 -232.659174)
		(mid 330.1111 -232.709851)
		(end 330.299568 -232.659174)
		(width 0.09525)
		(layer "In11.Cu")
		(net "M_F_CPU0_SA_DQS_DN<6>")
	)
	(arc
		(start 333.59598 -232.61828)
		(mid 333.606179 -232.622117)
		(end 333.6163 -232.626154)
		(width 0.09525)
		(layer "In11.Cu")
		(net "M_F_CPU0_SA_DQS_DN<6>")
	)
	(arc
		(start 326.162162 -232.659174)
		(mid 326.342441 -232.710005)
		(end 326.524874 -232.667556)
		(width 0.09525)
		(layer "In11.Cu")
		(net "M_F_CPU0_SA_DQS_DN<6>")
	)
	(arc
		(start 328.419714 -232.659174)
		(mid 328.701146 -232.583419)
		(end 328.982578 -232.659174)
		(width 0.09525)
		(layer "In11.Cu")
		(net "M_F_CPU0_SA_DQS_DN<6>")
	)
	(arc
		(start 333.11973 -232.659174)
		(mid 333.353274 -232.585468)
		(end 333.59598 -232.61828)
		(width 0.09525)
		(layer "In11.Cu")
		(net "M_F_CPU0_SA_DQS_DN<6>")
	)
	(arc
		(start 327.479406 -232.659174)
		(mid 327.754949 -232.583325)
		(end 328.03211 -232.653078)
		(width 0.09525)
		(layer "In11.Cu")
		(net "M_F_CPU0_SA_DQS_DN<6>")
	)
	(arc
		(start 331.802486 -232.659174)
		(mid 331.986261 -232.709946)
		(end 332.171294 -232.664)
		(width 0.09525)
		(layer "In11.Cu")
		(net "M_F_CPU0_SA_DQS_DN<6>")
	)
	(arc
		(start 328.042524 -232.659174)
		(mid 328.226299 -232.709946)
		(end 328.411332 -232.664)
		(width 0.09525)
		(layer "In11.Cu")
		(net "M_F_CPU0_SA_DQS_DN<6>")
	)
	(arc
		(start 326.085454 -232.599992)
		(mid 326.121893 -232.632066)
		(end 326.162162 -232.659174)
		(width 0.09525)
		(layer "In11.Cu")
		(net "M_F_CPU0_SA_DQS_DN<6>")
	)
	(arc
		(start 331.239622 -232.659174)
		(mid 331.521054 -232.583419)
		(end 331.802486 -232.659174)
		(width 0.09525)
		(layer "In11.Cu")
		(net "M_F_CPU0_SA_DQS_DN<6>")
	)
	(arc
		(start 326.549766 -232.653078)
		(mid 326.826674 -232.583401)
		(end 327.101962 -232.659174)
		(width 0.09525)
		(layer "In11.Cu")
		(net "M_F_CPU0_SA_DQS_DN<6>")
	)
	(arc
		(start 327.101962 -232.659174)
		(mid 327.290684 -232.709978)
		(end 327.479406 -232.659174)
		(width 0.09525)
		(layer "In11.Cu")
		(net "M_F_CPU0_SA_DQS_DN<6>")
	)
	(arc
		(start 328.99096 -232.664)
		(mid 329.175992 -232.709914)
		(end 329.359768 -232.659174)
		(width 0.09525)
		(layer "In11.Cu")
		(net "M_F_CPU0_SA_DQS_DN<6>")
	)
	(arc
		(start 332.750922 -232.664)
		(mid 332.935954 -232.709914)
		(end 333.11973 -232.659174)
		(width 0.09525)
		(layer "In11.Cu")
		(net "M_F_CPU0_SA_DQS_DN<6>")
	)
	(arc
		(start 330.862432 -232.659174)
		(mid 331.046207 -232.709946)
		(end 331.23124 -232.664)
		(width 0.09525)
		(layer "In11.Cu")
		(net "M_F_CPU0_SA_DQS_DN<6>")
	)
	(arc
		(start 332.179676 -232.659174)
		(mid 332.461108 -232.583419)
		(end 332.74254 -232.659174)
		(width 0.09525)
		(layer "In11.Cu")
		(net "M_F_CPU0_SA_DQS_DN<6>")
	)
	(arc
		(start 329.359768 -232.659174)
		(mid 329.6412 -232.583419)
		(end 329.922632 -232.659174)
		(width 0.09525)
		(layer "In11.Cu")
		(net "M_F_CPU0_SA_DQS_DN<6>")
	)
	(arc
		(start 330.299568 -232.659174)
		(mid 330.581 -232.583419)
		(end 330.862432 -232.659174)
		(width 0.09525)
		(layer "In11.Cu")
		(net "M_F_CPU0_SA_DQS_DN<6>")
	)
	(segment
		(start 334.337914 -227.74021)
		(end 333.871062 -227.474272)
		(width 0.12954)
		(layer "F.Cu")
		(net "M_F_CPU0_SA_DQS_DN<5>")
	)
	(segment
		(start 304.822098 -202.538076)
		(end 305.706272 -201.653902)
		(width 0.16002)
		(layer "In11.Cu")
		(net "M_F_CPU0_SA_DQS_DN<5>")
	)
	(segment
		(start 326.082152 -226.106482)
		(end 326.210422 -226.226116)
		(width 0.09525)
		(layer "In11.Cu")
		(net "M_F_CPU0_SA_DQS_DN<5>")
	)
	(segment
		(start 294.73525 -202.858116)
		(end 296.480738 -202.858116)
		(width 0.16002)
		(layer "In11.Cu")
		(net "M_F_CPU0_SA_DQS_DN<5>")
	)
	(segment
		(start 301.959264 -202.538076)
		(end 304.822098 -202.538076)
		(width 0.16002)
		(layer "In11.Cu")
		(net "M_F_CPU0_SA_DQS_DN<5>")
	)
	(segment
		(start 325.97344 -224.234248)
		(end 325.972932 -224.234756)
		(width 0.09525)
		(layer "In11.Cu")
		(net "M_F_CPU0_SA_DQS_DN<5>")
	)
	(segment
		(start 325.972932 -224.234756)
		(end 325.972932 -225.855276)
		(width 0.09525)
		(layer "In11.Cu")
		(net "M_F_CPU0_SA_DQS_DN<5>")
	)
	(segment
		(start 325.503032 -223.139508)
		(end 325.503032 -223.424242)
		(width 0.09525)
		(layer "In11.Cu")
		(net "M_F_CPU0_SA_DQS_DN<5>")
	)
	(segment
		(start 297.278298 -202.538076)
		(end 298.162472 -201.653902)
		(width 0.16002)
		(layer "In11.Cu")
		(net "M_F_CPU0_SA_DQS_DN<5>")
	)
	(segment
		(start 272.136362 -202.858116)
		(end 273.848576 -202.858116)
		(width 0.16002)
		(layer "In11.Cu")
		(net "M_F_CPU0_SA_DQS_DN<5>")
	)
	(segment
		(start 283.626814 -201.653902)
		(end 283.98089 -202.007978)
		(width 0.16002)
		(layer "In11.Cu")
		(net "M_F_CPU0_SA_DQS_DN<5>")
	)
	(segment
		(start 328.982578 -227.799392)
		(end 328.99096 -227.804218)
		(width 0.09525)
		(layer "In11.Cu")
		(net "M_F_CPU0_SA_DQS_DN<5>")
	)
	(segment
		(start 311.626758 -206.86141)
		(end 322.116958 -217.35161)
		(width 0.16002)
		(layer "In11.Cu")
		(net "M_F_CPU0_SA_DQS_DN<5>")
	)
	(segment
		(start 268.581378 -201.693272)
		(end 268.927834 -202.039728)
		(width 0.16002)
		(layer "In11.Cu")
		(net "M_F_CPU0_SA_DQS_DN<5>")
	)
	(segment
		(start 305.706272 -201.653902)
		(end 307.90261 -201.653902)
		(width 0.16002)
		(layer "In11.Cu")
		(net "M_F_CPU0_SA_DQS_DN<5>")
	)
	(segment
		(start 283.98089 -202.007978)
		(end 286.341058 -202.007978)
		(width 0.16002)
		(layer "In11.Cu")
		(net "M_F_CPU0_SA_DQS_DN<5>")
	)
	(segment
		(start 267.741654 -201.693272)
		(end 268.581378 -201.693272)
		(width 0.16002)
		(layer "In11.Cu")
		(net "M_F_CPU0_SA_DQS_DN<5>")
	)
	(segment
		(start 326.640698 -226.986084)
		(end 326.731884 -227.017326)
		(width 0.09525)
		(layer "In11.Cu")
		(net "M_F_CPU0_SA_DQS_DN<5>")
	)
	(segment
		(start 282.19019 -202.538076)
		(end 283.074364 -201.653902)
		(width 0.16002)
		(layer "In11.Cu")
		(net "M_F_CPU0_SA_DQS_DN<5>")
	)
	(segment
		(start 299.068998 -202.007978)
		(end 301.429166 -202.007978)
		(width 0.16002)
		(layer "In11.Cu")
		(net "M_F_CPU0_SA_DQS_DN<5>")
	)
	(segment
		(start 265.54811 -201.585068)
		(end 265.821922 -201.85888)
		(width 0.16002)
		(layer "In11.Cu")
		(net "M_F_CPU0_SA_DQS_DN<5>")
	)
	(segment
		(start 325.1073 -222.660464)
		(end 325.124064 -222.677228)
		(width 0.09525)
		(layer "In11.Cu")
		(net "M_F_CPU0_SA_DQS_DN<5>")
	)
	(segment
		(start 286.341058 -202.007978)
		(end 287.191196 -202.858116)
		(width 0.16002)
		(layer "In11.Cu")
		(net "M_F_CPU0_SA_DQS_DN<5>")
	)
	(segment
		(start 293.885112 -202.007978)
		(end 294.73525 -202.858116)
		(width 0.16002)
		(layer "In11.Cu")
		(net "M_F_CPU0_SA_DQS_DN<5>")
	)
	(segment
		(start 325.661274 -223.731582)
		(end 325.730616 -223.77146)
		(width 0.09525)
		(layer "In11.Cu")
		(net "M_F_CPU0_SA_DQS_DN<5>")
	)
	(segment
		(start 327.099422 -227.446078)
		(end 327.23074 -227.57765)
		(width 0.09525)
		(layer "In11.Cu")
		(net "M_F_CPU0_SA_DQS_DN<5>")
	)
	(segment
		(start 273.848576 -202.858116)
		(end 274.168616 -202.538076)
		(width 0.16002)
		(layer "In11.Cu")
		(net "M_F_CPU0_SA_DQS_DN<5>")
	)
	(segment
		(start 298.162472 -201.653902)
		(end 298.714922 -201.653902)
		(width 0.16002)
		(layer "In11.Cu")
		(net "M_F_CPU0_SA_DQS_DN<5>")
	)
	(segment
		(start 333.717138 -227.739702)
		(end 333.871062 -227.474272)
		(width 0.09525)
		(layer "In11.Cu")
		(net "M_F_CPU0_SA_DQS_DN<5>")
	)
	(segment
		(start 275.53031 -201.653902)
		(end 276.08276 -201.653902)
		(width 0.16002)
		(layer "In11.Cu")
		(net "M_F_CPU0_SA_DQS_DN<5>")
	)
	(segment
		(start 289.256724 -202.538076)
		(end 289.734244 -202.538076)
		(width 0.16002)
		(layer "In11.Cu")
		(net "M_F_CPU0_SA_DQS_DN<5>")
	)
	(segment
		(start 322.116958 -219.670122)
		(end 325.1073 -222.660464)
		(width 0.16002)
		(layer "In11.Cu")
		(net "M_F_CPU0_SA_DQS_DN<5>")
	)
	(segment
		(start 290.618418 -201.653902)
		(end 291.170868 -201.653902)
		(width 0.16002)
		(layer "In11.Cu")
		(net "M_F_CPU0_SA_DQS_DN<5>")
	)
	(segment
		(start 274.168616 -202.538076)
		(end 274.646136 -202.538076)
		(width 0.16002)
		(layer "In11.Cu")
		(net "M_F_CPU0_SA_DQS_DN<5>")
	)
	(segment
		(start 301.429166 -202.007978)
		(end 301.959264 -202.538076)
		(width 0.16002)
		(layer "In11.Cu")
		(net "M_F_CPU0_SA_DQS_DN<5>")
	)
	(segment
		(start 332.171294 -227.804218)
		(end 332.179676 -227.799392)
		(width 0.09525)
		(layer "In11.Cu")
		(net "M_F_CPU0_SA_DQS_DN<5>")
	)
	(segment
		(start 279.647142 -202.858116)
		(end 281.39263 -202.858116)
		(width 0.16002)
		(layer "In11.Cu")
		(net "M_F_CPU0_SA_DQS_DN<5>")
	)
	(segment
		(start 311.626758 -205.37805)
		(end 311.626758 -206.86141)
		(width 0.16002)
		(layer "In11.Cu")
		(net "M_F_CPU0_SA_DQS_DN<5>")
	)
	(segment
		(start 287.191196 -202.858116)
		(end 288.936684 -202.858116)
		(width 0.16002)
		(layer "In11.Cu")
		(net "M_F_CPU0_SA_DQS_DN<5>")
	)
	(segment
		(start 281.39263 -202.858116)
		(end 281.71267 -202.538076)
		(width 0.16002)
		(layer "In11.Cu")
		(net "M_F_CPU0_SA_DQS_DN<5>")
	)
	(segment
		(start 296.480738 -202.858116)
		(end 296.800778 -202.538076)
		(width 0.16002)
		(layer "In11.Cu")
		(net "M_F_CPU0_SA_DQS_DN<5>")
	)
	(segment
		(start 278.797004 -202.007978)
		(end 279.647142 -202.858116)
		(width 0.16002)
		(layer "In11.Cu")
		(net "M_F_CPU0_SA_DQS_DN<5>")
	)
	(segment
		(start 325.124064 -222.76054)
		(end 325.503032 -223.139508)
		(width 0.09525)
		(layer "In11.Cu")
		(net "M_F_CPU0_SA_DQS_DN<5>")
	)
	(segment
		(start 283.074364 -201.653902)
		(end 283.626814 -201.653902)
		(width 0.16002)
		(layer "In11.Cu")
		(net "M_F_CPU0_SA_DQS_DN<5>")
	)
	(segment
		(start 291.524944 -202.007978)
		(end 293.885112 -202.007978)
		(width 0.16002)
		(layer "In11.Cu")
		(net "M_F_CPU0_SA_DQS_DN<5>")
	)
	(segment
		(start 332.74254 -227.799392)
		(end 332.750922 -227.804218)
		(width 0.09525)
		(layer "In11.Cu")
		(net "M_F_CPU0_SA_DQS_DN<5>")
	)
	(segment
		(start 322.116958 -217.35161)
		(end 322.116958 -219.670122)
		(width 0.16002)
		(layer "In11.Cu")
		(net "M_F_CPU0_SA_DQS_DN<5>")
	)
	(segment
		(start 327.583038 -227.7237)
		(end 327.761092 -227.7237)
		(width 0.09525)
		(layer "In11.Cu")
		(net "M_F_CPU0_SA_DQS_DN<5>")
	)
	(segment
		(start 291.170868 -201.653902)
		(end 291.524944 -202.007978)
		(width 0.16002)
		(layer "In11.Cu")
		(net "M_F_CPU0_SA_DQS_DN<5>")
	)
	(segment
		(start 333.6163 -227.766372)
		(end 333.717138 -227.739702)
		(width 0.09525)
		(layer "In11.Cu")
		(net "M_F_CPU0_SA_DQS_DN<5>")
	)
	(segment
		(start 268.927834 -202.039728)
		(end 271.317974 -202.039728)
		(width 0.16002)
		(layer "In11.Cu")
		(net "M_F_CPU0_SA_DQS_DN<5>")
	)
	(segment
		(start 289.734244 -202.538076)
		(end 290.618418 -201.653902)
		(width 0.16002)
		(layer "In11.Cu")
		(net "M_F_CPU0_SA_DQS_DN<5>")
	)
	(segment
		(start 267.576046 -201.85888)
		(end 267.741654 -201.693272)
		(width 0.16002)
		(layer "In11.Cu")
		(net "M_F_CPU0_SA_DQS_DN<5>")
	)
	(segment
		(start 298.714922 -201.653902)
		(end 299.068998 -202.007978)
		(width 0.16002)
		(layer "In11.Cu")
		(net "M_F_CPU0_SA_DQS_DN<5>")
	)
	(segment
		(start 307.90261 -201.653902)
		(end 311.626758 -205.37805)
		(width 0.16002)
		(layer "In11.Cu")
		(net "M_F_CPU0_SA_DQS_DN<5>")
	)
	(segment
		(start 276.436836 -202.007978)
		(end 278.797004 -202.007978)
		(width 0.16002)
		(layer "In11.Cu")
		(net "M_F_CPU0_SA_DQS_DN<5>")
	)
	(segment
		(start 331.23124 -227.804218)
		(end 331.239622 -227.799392)
		(width 0.09525)
		(layer "In11.Cu")
		(net "M_F_CPU0_SA_DQS_DN<5>")
	)
	(segment
		(start 281.71267 -202.538076)
		(end 282.19019 -202.538076)
		(width 0.16002)
		(layer "In11.Cu")
		(net "M_F_CPU0_SA_DQS_DN<5>")
	)
	(segment
		(start 265.821922 -201.85888)
		(end 267.576046 -201.85888)
		(width 0.16002)
		(layer "In11.Cu")
		(net "M_F_CPU0_SA_DQS_DN<5>")
	)
	(segment
		(start 274.646136 -202.538076)
		(end 275.53031 -201.653902)
		(width 0.16002)
		(layer "In11.Cu")
		(net "M_F_CPU0_SA_DQS_DN<5>")
	)
	(segment
		(start 271.317974 -202.039728)
		(end 272.136362 -202.858116)
		(width 0.16002)
		(layer "In11.Cu")
		(net "M_F_CPU0_SA_DQS_DN<5>")
	)
	(segment
		(start 296.800778 -202.538076)
		(end 297.278298 -202.538076)
		(width 0.16002)
		(layer "In11.Cu")
		(net "M_F_CPU0_SA_DQS_DN<5>")
	)
	(segment
		(start 288.936684 -202.858116)
		(end 289.256724 -202.538076)
		(width 0.16002)
		(layer "In11.Cu")
		(net "M_F_CPU0_SA_DQS_DN<5>")
	)
	(segment
		(start 325.124064 -222.677228)
		(end 325.124064 -222.76054)
		(width 0.09525)
		(layer "In11.Cu")
		(net "M_F_CPU0_SA_DQS_DN<5>")
	)
	(segment
		(start 276.08276 -201.653902)
		(end 276.436836 -202.007978)
		(width 0.16002)
		(layer "In11.Cu")
		(net "M_F_CPU0_SA_DQS_DN<5>")
	)
	(segment
		(start 328.411332 -227.804218)
		(end 328.419714 -227.799392)
		(width 0.09525)
		(layer "In11.Cu")
		(net "M_F_CPU0_SA_DQS_DN<5>")
	)
	(arc
		(start 327.23074 -227.57765)
		(mid 327.392361 -227.685734)
		(end 327.583038 -227.7237)
		(width 0.09525)
		(layer "In11.Cu")
		(net "M_F_CPU0_SA_DQS_DN<5>")
	)
	(arc
		(start 333.59598 -227.758498)
		(mid 333.606179 -227.762335)
		(end 333.6163 -227.766372)
		(width 0.09525)
		(layer "In11.Cu")
		(net "M_F_CPU0_SA_DQS_DN<5>")
	)
	(arc
		(start 330.862432 -227.799392)
		(mid 331.046207 -227.850164)
		(end 331.23124 -227.804218)
		(width 0.09525)
		(layer "In11.Cu")
		(net "M_F_CPU0_SA_DQS_DN<5>")
	)
	(arc
		(start 331.802486 -227.799392)
		(mid 331.986261 -227.850164)
		(end 332.171294 -227.804218)
		(width 0.09525)
		(layer "In11.Cu")
		(net "M_F_CPU0_SA_DQS_DN<5>")
	)
	(arc
		(start 328.419714 -227.799392)
		(mid 328.701146 -227.723637)
		(end 328.982578 -227.799392)
		(width 0.09525)
		(layer "In11.Cu")
		(net "M_F_CPU0_SA_DQS_DN<5>")
	)
	(arc
		(start 326.916288 -227.135182)
		(mid 326.940423 -227.164523)
		(end 326.963278 -227.194872)
		(width 0.09525)
		(layer "In11.Cu")
		(net "M_F_CPU0_SA_DQS_DN<5>")
	)
	(arc
		(start 327.046082 -227.367084)
		(mid 327.068886 -227.409195)
		(end 327.099422 -227.446078)
		(width 0.09525)
		(layer "In11.Cu")
		(net "M_F_CPU0_SA_DQS_DN<5>")
	)
	(arc
		(start 325.972932 -225.855276)
		(mid 326.001424 -225.992232)
		(end 326.082152 -226.106482)
		(width 0.09525)
		(layer "In11.Cu")
		(net "M_F_CPU0_SA_DQS_DN<5>")
	)
	(arc
		(start 326.735694 -227.018596)
		(mid 326.738993 -227.019747)
		(end 326.742298 -227.020882)
		(width 0.09525)
		(layer "In11.Cu")
		(net "M_F_CPU0_SA_DQS_DN<5>")
	)
	(arc
		(start 326.210422 -226.226116)
		(mid 326.37059 -226.441863)
		(end 326.444102 -226.700334)
		(width 0.09525)
		(layer "In11.Cu")
		(net "M_F_CPU0_SA_DQS_DN<5>")
	)
	(arc
		(start 327.01611 -227.29317)
		(mid 327.030911 -227.330202)
		(end 327.046082 -227.367084)
		(width 0.09525)
		(layer "In11.Cu")
		(net "M_F_CPU0_SA_DQS_DN<5>")
	)
	(arc
		(start 326.963278 -227.194872)
		(mid 326.992767 -227.242368)
		(end 327.01611 -227.29317)
		(width 0.09525)
		(layer "In11.Cu")
		(net "M_F_CPU0_SA_DQS_DN<5>")
	)
	(arc
		(start 332.179676 -227.799392)
		(mid 332.461108 -227.723637)
		(end 332.74254 -227.799392)
		(width 0.09525)
		(layer "In11.Cu")
		(net "M_F_CPU0_SA_DQS_DN<5>")
	)
	(arc
		(start 328.99096 -227.804218)
		(mid 329.175992 -227.850132)
		(end 329.359768 -227.799392)
		(width 0.09525)
		(layer "In11.Cu")
		(net "M_F_CPU0_SA_DQS_DN<5>")
	)
	(arc
		(start 326.559164 -226.937062)
		(mid 326.597258 -226.96602)
		(end 326.640698 -226.986084)
		(width 0.09525)
		(layer "In11.Cu")
		(net "M_F_CPU0_SA_DQS_DN<5>")
	)
	(arc
		(start 326.731884 -227.017326)
		(mid 326.733788 -227.017964)
		(end 326.735694 -227.018596)
		(width 0.09525)
		(layer "In11.Cu")
		(net "M_F_CPU0_SA_DQS_DN<5>")
	)
	(arc
		(start 332.750922 -227.804218)
		(mid 332.935954 -227.850132)
		(end 333.11973 -227.799392)
		(width 0.09525)
		(layer "In11.Cu")
		(net "M_F_CPU0_SA_DQS_DN<5>")
	)
	(arc
		(start 325.503032 -223.424242)
		(mid 325.54496 -223.597069)
		(end 325.661274 -223.731582)
		(width 0.09525)
		(layer "In11.Cu")
		(net "M_F_CPU0_SA_DQS_DN<5>")
	)
	(arc
		(start 326.742298 -227.020882)
		(mid 326.837282 -227.065877)
		(end 326.916288 -227.135182)
		(width 0.09525)
		(layer "In11.Cu")
		(net "M_F_CPU0_SA_DQS_DN<5>")
	)
	(arc
		(start 333.11973 -227.799392)
		(mid 333.353274 -227.725686)
		(end 333.59598 -227.758498)
		(width 0.09525)
		(layer "In11.Cu")
		(net "M_F_CPU0_SA_DQS_DN<5>")
	)
	(arc
		(start 331.239622 -227.799392)
		(mid 331.521054 -227.723637)
		(end 331.802486 -227.799392)
		(width 0.09525)
		(layer "In11.Cu")
		(net "M_F_CPU0_SA_DQS_DN<5>")
	)
	(arc
		(start 329.359768 -227.799392)
		(mid 329.6412 -227.723637)
		(end 329.922632 -227.799392)
		(width 0.09525)
		(layer "In11.Cu")
		(net "M_F_CPU0_SA_DQS_DN<5>")
	)
	(arc
		(start 328.042524 -227.799392)
		(mid 328.226299 -227.850164)
		(end 328.411332 -227.804218)
		(width 0.09525)
		(layer "In11.Cu")
		(net "M_F_CPU0_SA_DQS_DN<5>")
	)
	(arc
		(start 329.922632 -227.799392)
		(mid 330.1111 -227.850069)
		(end 330.299568 -227.799392)
		(width 0.09525)
		(layer "In11.Cu")
		(net "M_F_CPU0_SA_DQS_DN<5>")
	)
	(arc
		(start 326.444102 -226.700334)
		(mid 326.480358 -226.829042)
		(end 326.559164 -226.937062)
		(width 0.09525)
		(layer "In11.Cu")
		(net "M_F_CPU0_SA_DQS_DN<5>")
	)
	(arc
		(start 330.299568 -227.799392)
		(mid 330.581 -227.723637)
		(end 330.862432 -227.799392)
		(width 0.09525)
		(layer "In11.Cu")
		(net "M_F_CPU0_SA_DQS_DN<5>")
	)
	(arc
		(start 327.761092 -227.7237)
		(mid 327.9068 -227.742968)
		(end 328.042524 -227.799392)
		(width 0.09525)
		(layer "In11.Cu")
		(net "M_F_CPU0_SA_DQS_DN<5>")
	)
	(arc
		(start 325.730616 -223.77146)
		(mid 325.909066 -223.97293)
		(end 325.97344 -224.234248)
		(width 0.09525)
		(layer "In11.Cu")
		(net "M_F_CPU0_SA_DQS_DN<5>")
	)
	(segment
		(start 332.45806 -247.1801)
		(end 331.991208 -246.914162)
		(width 0.12954)
		(layer "F.Cu")
		(net "M_F_CPU0_SA_DQS_DN<4>")
	)
	(segment
		(start 285.604204 -237.71225)
		(end 286.454088 -238.562134)
		(width 0.16002)
		(layer "In11.Cu")
		(net "M_F_CPU0_SA_DQS_DN<4>")
	)
	(segment
		(start 293.998142 -238.562134)
		(end 296.45229 -238.562134)
		(width 0.16002)
		(layer "In11.Cu")
		(net "M_F_CPU0_SA_DQS_DN<4>")
	)
	(segment
		(start 307.763672 -239.669066)
		(end 307.989732 -239.669066)
		(width 0.16002)
		(layer "In11.Cu")
		(net "M_F_CPU0_SA_DQS_DN<4>")
	)
	(segment
		(start 308.401974 -240.081308)
		(end 308.401974 -240.721388)
		(width 0.16002)
		(layer "In11.Cu")
		(net "M_F_CPU0_SA_DQS_DN<4>")
	)
	(segment
		(start 301.691802 -238.35487)
		(end 302.243744 -238.906812)
		(width 0.16002)
		(layer "In11.Cu")
		(net "M_F_CPU0_SA_DQS_DN<4>")
	)
	(segment
		(start 298.716954 -238.081312)
		(end 299.086016 -237.71225)
		(width 0.16002)
		(layer "In11.Cu")
		(net "M_F_CPU0_SA_DQS_DN<4>")
	)
	(segment
		(start 300.692312 -237.71225)
		(end 301.334932 -238.35487)
		(width 0.16002)
		(layer "In11.Cu")
		(net "M_F_CPU0_SA_DQS_DN<4>")
	)
	(segment
		(start 312.988198 -245.307612)
		(end 313.628278 -245.307612)
		(width 0.16002)
		(layer "In11.Cu")
		(net "M_F_CPU0_SA_DQS_DN<4>")
	)
	(segment
		(start 306.500276 -239.128046)
		(end 306.500276 -239.60455)
		(width 0.16002)
		(layer "In11.Cu")
		(net "M_F_CPU0_SA_DQS_DN<4>")
	)
	(segment
		(start 324.339712 -246.73687)
		(end 324.524624 -246.921782)
		(width 0.09525)
		(layer "In11.Cu")
		(net "M_F_CPU0_SA_DQS_DN<4>")
	)
	(segment
		(start 310.235346 -242.55476)
		(end 310.875426 -242.55476)
		(width 0.16002)
		(layer "In11.Cu")
		(net "M_F_CPU0_SA_DQS_DN<4>")
	)
	(segment
		(start 282.358592 -238.906812)
		(end 283.184092 -238.081312)
		(width 0.16002)
		(layer "In11.Cu")
		(net "M_F_CPU0_SA_DQS_DN<4>")
	)
	(segment
		(start 311.154826 -243.47424)
		(end 311.611772 -243.931186)
		(width 0.16002)
		(layer "In11.Cu")
		(net "M_F_CPU0_SA_DQS_DN<4>")
	)
	(segment
		(start 331.23124 -246.584216)
		(end 331.239622 -246.589042)
		(width 0.09525)
		(layer "In11.Cu")
		(net "M_F_CPU0_SA_DQS_DN<4>")
	)
	(segment
		(start 302.243744 -238.906812)
		(end 302.77435 -238.906812)
		(width 0.16002)
		(layer "In11.Cu")
		(net "M_F_CPU0_SA_DQS_DN<4>")
	)
	(segment
		(start 303.621948 -238.190532)
		(end 303.781968 -238.350552)
		(width 0.16002)
		(layer "In11.Cu")
		(net "M_F_CPU0_SA_DQS_DN<4>")
	)
	(segment
		(start 283.184092 -238.081312)
		(end 283.628846 -238.081312)
		(width 0.16002)
		(layer "In11.Cu")
		(net "M_F_CPU0_SA_DQS_DN<4>")
	)
	(segment
		(start 325.698612 -246.652796)
		(end 325.922386 -246.66067)
		(width 0.09525)
		(layer "In11.Cu")
		(net "M_F_CPU0_SA_DQS_DN<4>")
	)
	(segment
		(start 306.13096 -238.081312)
		(end 306.401978 -238.081312)
		(width 0.16002)
		(layer "In11.Cu")
		(net "M_F_CPU0_SA_DQS_DN<4>")
	)
	(segment
		(start 309.499 -241.178334)
		(end 309.7784 -241.457734)
		(width 0.16002)
		(layer "In11.Cu")
		(net "M_F_CPU0_SA_DQS_DN<4>")
	)
	(segment
		(start 314.629038 -246.308372)
		(end 323.127624 -246.308372)
		(width 0.16002)
		(layer "In11.Cu")
		(net "M_F_CPU0_SA_DQS_DN<4>")
	)
	(segment
		(start 272.071592 -238.711232)
		(end 272.22069 -238.562134)
		(width 0.16002)
		(layer "In11.Cu")
		(net "M_F_CPU0_SA_DQS_DN<4>")
	)
	(segment
		(start 303.781968 -238.350552)
		(end 303.781968 -239.034574)
		(width 0.16002)
		(layer "In11.Cu")
		(net "M_F_CPU0_SA_DQS_DN<4>")
	)
	(segment
		(start 296.45229 -238.562134)
		(end 296.796968 -238.906812)
		(width 0.16002)
		(layer "In11.Cu")
		(net "M_F_CPU0_SA_DQS_DN<4>")
	)
	(segment
		(start 323.978778 -246.73687)
		(end 324.339712 -246.73687)
		(width 0.09525)
		(layer "In11.Cu")
		(net "M_F_CPU0_SA_DQS_DN<4>")
	)
	(segment
		(start 309.7784 -242.097814)
		(end 310.235346 -242.55476)
		(width 0.16002)
		(layer "In11.Cu")
		(net "M_F_CPU0_SA_DQS_DN<4>")
	)
	(segment
		(start 275.640038 -238.081312)
		(end 276.084792 -238.081312)
		(width 0.16002)
		(layer "In11.Cu")
		(net "M_F_CPU0_SA_DQS_DN<4>")
	)
	(segment
		(start 323.127624 -246.308372)
		(end 323.615304 -246.796052)
		(width 0.16002)
		(layer "In11.Cu")
		(net "M_F_CPU0_SA_DQS_DN<4>")
	)
	(segment
		(start 311.154826 -242.83416)
		(end 311.154826 -243.47424)
		(width 0.16002)
		(layer "In11.Cu")
		(net "M_F_CPU0_SA_DQS_DN<4>")
	)
	(segment
		(start 325.028052 -246.921782)
		(end 325.297038 -246.652796)
		(width 0.09525)
		(layer "In11.Cu")
		(net "M_F_CPU0_SA_DQS_DN<4>")
	)
	(segment
		(start 271.264888 -238.711232)
		(end 272.071592 -238.711232)
		(width 0.16002)
		(layer "In11.Cu")
		(net "M_F_CPU0_SA_DQS_DN<4>")
	)
	(segment
		(start 276.453854 -237.71225)
		(end 278.06015 -237.71225)
		(width 0.16002)
		(layer "In11.Cu")
		(net "M_F_CPU0_SA_DQS_DN<4>")
	)
	(segment
		(start 291.541962 -237.71225)
		(end 293.148258 -237.71225)
		(width 0.16002)
		(layer "In11.Cu")
		(net "M_F_CPU0_SA_DQS_DN<4>")
	)
	(segment
		(start 273.820128 -238.562134)
		(end 274.164806 -238.906812)
		(width 0.16002)
		(layer "In11.Cu")
		(net "M_F_CPU0_SA_DQS_DN<4>")
	)
	(segment
		(start 312.531252 -244.210586)
		(end 312.531252 -244.850666)
		(width 0.16002)
		(layer "In11.Cu")
		(net "M_F_CPU0_SA_DQS_DN<4>")
	)
	(segment
		(start 308.85892 -241.178334)
		(end 309.499 -241.178334)
		(width 0.16002)
		(layer "In11.Cu")
		(net "M_F_CPU0_SA_DQS_DN<4>")
	)
	(segment
		(start 323.919596 -246.796052)
		(end 323.978778 -246.73687)
		(width 0.09525)
		(layer "In11.Cu")
		(net "M_F_CPU0_SA_DQS_DN<4>")
	)
	(segment
		(start 272.22069 -238.562134)
		(end 273.820128 -238.562134)
		(width 0.16002)
		(layer "In11.Cu")
		(net "M_F_CPU0_SA_DQS_DN<4>")
	)
	(segment
		(start 303.271428 -238.190532)
		(end 303.621948 -238.190532)
		(width 0.16002)
		(layer "In11.Cu")
		(net "M_F_CPU0_SA_DQS_DN<4>")
	)
	(segment
		(start 281.364182 -238.562134)
		(end 281.70886 -238.906812)
		(width 0.16002)
		(layer "In11.Cu")
		(net "M_F_CPU0_SA_DQS_DN<4>")
	)
	(segment
		(start 269.648178 -238.985044)
		(end 269.92199 -238.711232)
		(width 0.16002)
		(layer "In11.Cu")
		(net "M_F_CPU0_SA_DQS_DN<4>")
	)
	(segment
		(start 304.84064 -239.371632)
		(end 306.13096 -238.081312)
		(width 0.16002)
		(layer "In11.Cu")
		(net "M_F_CPU0_SA_DQS_DN<4>")
	)
	(segment
		(start 303.111408 -238.569754)
		(end 303.111408 -238.350552)
		(width 0.16002)
		(layer "In11.Cu")
		(net "M_F_CPU0_SA_DQS_DN<4>")
	)
	(segment
		(start 290.728146 -238.081312)
		(end 291.1729 -238.081312)
		(width 0.16002)
		(layer "In11.Cu")
		(net "M_F_CPU0_SA_DQS_DN<4>")
	)
	(segment
		(start 332.145132 -246.648732)
		(end 331.991208 -246.914162)
		(width 0.09525)
		(layer "In11.Cu")
		(net "M_F_CPU0_SA_DQS_DN<4>")
	)
	(segment
		(start 328.411332 -246.584216)
		(end 328.419714 -246.589042)
		(width 0.09525)
		(layer "In11.Cu")
		(net "M_F_CPU0_SA_DQS_DN<4>")
	)
	(segment
		(start 281.70886 -238.906812)
		(end 282.358592 -238.906812)
		(width 0.16002)
		(layer "In11.Cu")
		(net "M_F_CPU0_SA_DQS_DN<4>")
	)
	(segment
		(start 288.908236 -238.562134)
		(end 289.252914 -238.906812)
		(width 0.16002)
		(layer "In11.Cu")
		(net "M_F_CPU0_SA_DQS_DN<4>")
	)
	(segment
		(start 313.628278 -245.307612)
		(end 314.629038 -246.308372)
		(width 0.16002)
		(layer "In11.Cu")
		(net "M_F_CPU0_SA_DQS_DN<4>")
	)
	(segment
		(start 308.401974 -240.721388)
		(end 308.85892 -241.178334)
		(width 0.16002)
		(layer "In11.Cu")
		(net "M_F_CPU0_SA_DQS_DN<4>")
	)
	(segment
		(start 306.500276 -239.60455)
		(end 306.92598 -240.030254)
		(width 0.16002)
		(layer "In11.Cu")
		(net "M_F_CPU0_SA_DQS_DN<4>")
	)
	(segment
		(start 306.401978 -238.081312)
		(end 306.861464 -238.540798)
		(width 0.16002)
		(layer "In11.Cu")
		(net "M_F_CPU0_SA_DQS_DN<4>")
	)
	(segment
		(start 283.997908 -237.71225)
		(end 285.604204 -237.71225)
		(width 0.16002)
		(layer "In11.Cu")
		(net "M_F_CPU0_SA_DQS_DN<4>")
	)
	(segment
		(start 325.297038 -246.652796)
		(end 325.698612 -246.652796)
		(width 0.09525)
		(layer "In11.Cu")
		(net "M_F_CPU0_SA_DQS_DN<4>")
	)
	(segment
		(start 269.92199 -238.711232)
		(end 270.551148 -238.711232)
		(width 0.16002)
		(layer "In11.Cu")
		(net "M_F_CPU0_SA_DQS_DN<4>")
	)
	(segment
		(start 325.922386 -246.66067)
		(end 325.924672 -246.66321)
		(width 0.09525)
		(layer "In11.Cu")
		(net "M_F_CPU0_SA_DQS_DN<4>")
	)
	(segment
		(start 328.982578 -246.589042)
		(end 328.99096 -246.584216)
		(width 0.09525)
		(layer "In11.Cu")
		(net "M_F_CPU0_SA_DQS_DN<4>")
	)
	(segment
		(start 274.164806 -238.906812)
		(end 274.814538 -238.906812)
		(width 0.16002)
		(layer "In11.Cu")
		(net "M_F_CPU0_SA_DQS_DN<4>")
	)
	(segment
		(start 278.910034 -238.562134)
		(end 281.364182 -238.562134)
		(width 0.16002)
		(layer "In11.Cu")
		(net "M_F_CPU0_SA_DQS_DN<4>")
	)
	(segment
		(start 278.06015 -237.71225)
		(end 278.910034 -238.562134)
		(width 0.16002)
		(layer "In11.Cu")
		(net "M_F_CPU0_SA_DQS_DN<4>")
	)
	(segment
		(start 309.7784 -241.457734)
		(end 309.7784 -242.097814)
		(width 0.16002)
		(layer "In11.Cu")
		(net "M_F_CPU0_SA_DQS_DN<4>")
	)
	(segment
		(start 303.781968 -239.034574)
		(end 304.119026 -239.371632)
		(width 0.16002)
		(layer "In11.Cu")
		(net "M_F_CPU0_SA_DQS_DN<4>")
	)
	(segment
		(start 270.551148 -238.711232)
		(end 270.667988 -238.828072)
		(width 0.16002)
		(layer "In11.Cu")
		(net "M_F_CPU0_SA_DQS_DN<4>")
	)
	(segment
		(start 291.1729 -238.081312)
		(end 291.541962 -237.71225)
		(width 0.16002)
		(layer "In11.Cu")
		(net "M_F_CPU0_SA_DQS_DN<4>")
	)
	(segment
		(start 293.148258 -237.71225)
		(end 293.998142 -238.562134)
		(width 0.16002)
		(layer "In11.Cu")
		(net "M_F_CPU0_SA_DQS_DN<4>")
	)
	(segment
		(start 311.611772 -243.931186)
		(end 312.251852 -243.931186)
		(width 0.16002)
		(layer "In11.Cu")
		(net "M_F_CPU0_SA_DQS_DN<4>")
	)
	(segment
		(start 323.615304 -246.796052)
		(end 323.895974 -246.796052)
		(width 0.16002)
		(layer "In11.Cu")
		(net "M_F_CPU0_SA_DQS_DN<4>")
	)
	(segment
		(start 326.145144 -246.599456)
		(end 326.163178 -246.589042)
		(width 0.09525)
		(layer "In11.Cu")
		(net "M_F_CPU0_SA_DQS_DN<4>")
	)
	(segment
		(start 323.895974 -246.796052)
		(end 323.919596 -246.796052)
		(width 0.09525)
		(layer "In11.Cu")
		(net "M_F_CPU0_SA_DQS_DN<4>")
	)
	(segment
		(start 304.119026 -239.371632)
		(end 304.84064 -239.371632)
		(width 0.16002)
		(layer "In11.Cu")
		(net "M_F_CPU0_SA_DQS_DN<4>")
	)
	(segment
		(start 326.163178 -246.589042)
		(end 326.179942 -246.57939)
		(width 0.09525)
		(layer "In11.Cu")
		(net "M_F_CPU0_SA_DQS_DN<4>")
	)
	(segment
		(start 306.861464 -238.766858)
		(end 306.500276 -239.128046)
		(width 0.16002)
		(layer "In11.Cu")
		(net "M_F_CPU0_SA_DQS_DN<4>")
	)
	(segment
		(start 299.086016 -237.71225)
		(end 300.692312 -237.71225)
		(width 0.16002)
		(layer "In11.Cu")
		(net "M_F_CPU0_SA_DQS_DN<4>")
	)
	(segment
		(start 289.252914 -238.906812)
		(end 289.902646 -238.906812)
		(width 0.16002)
		(layer "In11.Cu")
		(net "M_F_CPU0_SA_DQS_DN<4>")
	)
	(segment
		(start 270.667988 -238.828072)
		(end 271.148048 -238.828072)
		(width 0.16002)
		(layer "In11.Cu")
		(net "M_F_CPU0_SA_DQS_DN<4>")
	)
	(segment
		(start 312.251852 -243.931186)
		(end 312.531252 -244.210586)
		(width 0.16002)
		(layer "In11.Cu")
		(net "M_F_CPU0_SA_DQS_DN<4>")
	)
	(segment
		(start 307.989732 -239.669066)
		(end 308.401974 -240.081308)
		(width 0.16002)
		(layer "In11.Cu")
		(net "M_F_CPU0_SA_DQS_DN<4>")
	)
	(segment
		(start 312.531252 -244.850666)
		(end 312.988198 -245.307612)
		(width 0.16002)
		(layer "In11.Cu")
		(net "M_F_CPU0_SA_DQS_DN<4>")
	)
	(segment
		(start 298.2722 -238.081312)
		(end 298.716954 -238.081312)
		(width 0.16002)
		(layer "In11.Cu")
		(net "M_F_CPU0_SA_DQS_DN<4>")
	)
	(segment
		(start 306.861464 -238.540798)
		(end 306.861464 -238.766858)
		(width 0.16002)
		(layer "In11.Cu")
		(net "M_F_CPU0_SA_DQS_DN<4>")
	)
	(segment
		(start 296.796968 -238.906812)
		(end 297.4467 -238.906812)
		(width 0.16002)
		(layer "In11.Cu")
		(net "M_F_CPU0_SA_DQS_DN<4>")
	)
	(segment
		(start 307.402484 -240.030254)
		(end 307.763672 -239.669066)
		(width 0.16002)
		(layer "In11.Cu")
		(net "M_F_CPU0_SA_DQS_DN<4>")
	)
	(segment
		(start 327.480422 -246.589042)
		(end 327.498456 -246.599456)
		(width 0.09525)
		(layer "In11.Cu")
		(net "M_F_CPU0_SA_DQS_DN<4>")
	)
	(segment
		(start 327.47204 -246.584216)
		(end 327.480422 -246.589042)
		(width 0.09525)
		(layer "In11.Cu")
		(net "M_F_CPU0_SA_DQS_DN<4>")
	)
	(segment
		(start 274.814538 -238.906812)
		(end 275.640038 -238.081312)
		(width 0.16002)
		(layer "In11.Cu")
		(net "M_F_CPU0_SA_DQS_DN<4>")
	)
	(segment
		(start 289.902646 -238.906812)
		(end 290.728146 -238.081312)
		(width 0.16002)
		(layer "In11.Cu")
		(net "M_F_CPU0_SA_DQS_DN<4>")
	)
	(segment
		(start 324.524624 -246.921782)
		(end 325.028052 -246.921782)
		(width 0.09525)
		(layer "In11.Cu")
		(net "M_F_CPU0_SA_DQS_DN<4>")
	)
	(segment
		(start 310.875426 -242.55476)
		(end 311.154826 -242.83416)
		(width 0.16002)
		(layer "In11.Cu")
		(net "M_F_CPU0_SA_DQS_DN<4>")
	)
	(segment
		(start 271.148048 -238.828072)
		(end 271.264888 -238.711232)
		(width 0.16002)
		(layer "In11.Cu")
		(net "M_F_CPU0_SA_DQS_DN<4>")
	)
	(segment
		(start 327.085706 -246.599456)
		(end 327.10374 -246.589042)
		(width 0.09525)
		(layer "In11.Cu")
		(net "M_F_CPU0_SA_DQS_DN<4>")
	)
	(segment
		(start 286.454088 -238.562134)
		(end 288.908236 -238.562134)
		(width 0.16002)
		(layer "In11.Cu")
		(net "M_F_CPU0_SA_DQS_DN<4>")
	)
	(segment
		(start 302.77435 -238.906812)
		(end 303.111408 -238.569754)
		(width 0.16002)
		(layer "In11.Cu")
		(net "M_F_CPU0_SA_DQS_DN<4>")
	)
	(segment
		(start 297.4467 -238.906812)
		(end 298.2722 -238.081312)
		(width 0.16002)
		(layer "In11.Cu")
		(net "M_F_CPU0_SA_DQS_DN<4>")
	)
	(segment
		(start 303.111408 -238.350552)
		(end 303.271428 -238.190532)
		(width 0.16002)
		(layer "In11.Cu")
		(net "M_F_CPU0_SA_DQS_DN<4>")
	)
	(segment
		(start 301.334932 -238.35487)
		(end 301.691802 -238.35487)
		(width 0.16002)
		(layer "In11.Cu")
		(net "M_F_CPU0_SA_DQS_DN<4>")
	)
	(segment
		(start 306.92598 -240.030254)
		(end 307.402484 -240.030254)
		(width 0.16002)
		(layer "In11.Cu")
		(net "M_F_CPU0_SA_DQS_DN<4>")
	)
	(segment
		(start 283.628846 -238.081312)
		(end 283.997908 -237.71225)
		(width 0.16002)
		(layer "In11.Cu")
		(net "M_F_CPU0_SA_DQS_DN<4>")
	)
	(segment
		(start 332.121764 -246.561864)
		(end 332.145132 -246.648732)
		(width 0.09525)
		(layer "In11.Cu")
		(net "M_F_CPU0_SA_DQS_DN<4>")
	)
	(segment
		(start 276.084792 -238.081312)
		(end 276.453854 -237.71225)
		(width 0.16002)
		(layer "In11.Cu")
		(net "M_F_CPU0_SA_DQS_DN<4>")
	)
	(arc
		(start 326.540114 -246.589042)
		(mid 326.811564 -246.665077)
		(end 327.085706 -246.599456)
		(width 0.09525)
		(layer "In11.Cu")
		(net "M_F_CPU0_SA_DQS_DN<4>")
	)
	(arc
		(start 331.802486 -246.589042)
		(mid 331.959084 -246.539753)
		(end 332.121764 -246.561864)
		(width 0.09525)
		(layer "In11.Cu")
		(net "M_F_CPU0_SA_DQS_DN<4>")
	)
	(arc
		(start 330.862432 -246.589042)
		(mid 331.046207 -246.53827)
		(end 331.23124 -246.584216)
		(width 0.09525)
		(layer "In11.Cu")
		(net "M_F_CPU0_SA_DQS_DN<4>")
	)
	(arc
		(start 328.042524 -246.589042)
		(mid 328.226299 -246.53827)
		(end 328.411332 -246.584216)
		(width 0.09525)
		(layer "In11.Cu")
		(net "M_F_CPU0_SA_DQS_DN<4>")
	)
	(arc
		(start 329.922632 -246.589042)
		(mid 330.1111 -246.538365)
		(end 330.299568 -246.589042)
		(width 0.09525)
		(layer "In11.Cu")
		(net "M_F_CPU0_SA_DQS_DN<4>")
	)
	(arc
		(start 328.99096 -246.584216)
		(mid 329.175992 -246.538302)
		(end 329.359768 -246.589042)
		(width 0.09525)
		(layer "In11.Cu")
		(net "M_F_CPU0_SA_DQS_DN<4>")
	)
	(arc
		(start 330.299568 -246.589042)
		(mid 330.581 -246.664797)
		(end 330.862432 -246.589042)
		(width 0.09525)
		(layer "In11.Cu")
		(net "M_F_CPU0_SA_DQS_DN<4>")
	)
	(arc
		(start 331.239622 -246.589042)
		(mid 331.521054 -246.664797)
		(end 331.802486 -246.589042)
		(width 0.09525)
		(layer "In11.Cu")
		(net "M_F_CPU0_SA_DQS_DN<4>")
	)
	(arc
		(start 327.498456 -246.599456)
		(mid 327.771836 -246.664677)
		(end 328.042524 -246.589042)
		(width 0.09525)
		(layer "In11.Cu")
		(net "M_F_CPU0_SA_DQS_DN<4>")
	)
	(arc
		(start 326.179942 -246.57939)
		(mid 326.361253 -246.538292)
		(end 326.540114 -246.589042)
		(width 0.09525)
		(layer "In11.Cu")
		(net "M_F_CPU0_SA_DQS_DN<4>")
	)
	(arc
		(start 328.419714 -246.589042)
		(mid 328.701146 -246.664797)
		(end 328.982578 -246.589042)
		(width 0.09525)
		(layer "In11.Cu")
		(net "M_F_CPU0_SA_DQS_DN<4>")
	)
	(arc
		(start 329.359768 -246.589042)
		(mid 329.6412 -246.664797)
		(end 329.922632 -246.589042)
		(width 0.09525)
		(layer "In11.Cu")
		(net "M_F_CPU0_SA_DQS_DN<4>")
	)
	(arc
		(start 325.924672 -246.66321)
		(mid 326.038209 -246.642744)
		(end 326.145144 -246.599456)
		(width 0.09525)
		(layer "In11.Cu")
		(net "M_F_CPU0_SA_DQS_DN<4>")
	)
	(arc
		(start 327.10374 -246.589042)
		(mid 327.287261 -246.538398)
		(end 327.47204 -246.584216)
		(width 0.09525)
		(layer "In11.Cu")
		(net "M_F_CPU0_SA_DQS_DN<4>")
	)
	(segment
		(start 332.45806 -242.320064)
		(end 331.991208 -242.054126)
		(width 0.12954)
		(layer "F.Cu")
		(net "M_F_CPU0_SA_DQS_DN<3>")
	)
	(segment
		(start 274.164806 -229.556818)
		(end 274.814538 -229.556818)
		(width 0.16002)
		(layer "In11.Cu")
		(net "M_F_CPU0_SA_DQS_DN<3>")
	)
	(segment
		(start 270.678148 -229.361238)
		(end 270.794988 -229.478078)
		(width 0.16002)
		(layer "In11.Cu")
		(net "M_F_CPU0_SA_DQS_DN<3>")
	)
	(segment
		(start 301.859188 -229.529132)
		(end 305.018186 -229.529132)
		(width 0.16002)
		(layer "In11.Cu")
		(net "M_F_CPU0_SA_DQS_DN<3>")
	)
	(segment
		(start 278.06015 -228.362256)
		(end 278.910034 -229.21214)
		(width 0.16002)
		(layer "In11.Cu")
		(net "M_F_CPU0_SA_DQS_DN<3>")
	)
	(segment
		(start 327.085706 -241.73942)
		(end 327.10374 -241.729006)
		(width 0.09525)
		(layer "In11.Cu")
		(net "M_F_CPU0_SA_DQS_DN<3>")
	)
	(segment
		(start 269.92199 -229.361238)
		(end 270.678148 -229.361238)
		(width 0.16002)
		(layer "In11.Cu")
		(net "M_F_CPU0_SA_DQS_DN<3>")
	)
	(segment
		(start 332.121764 -241.701828)
		(end 332.145132 -241.788696)
		(width 0.09525)
		(layer "In11.Cu")
		(net "M_F_CPU0_SA_DQS_DN<3>")
	)
	(segment
		(start 314.230766 -237.991904)
		(end 314.654438 -238.415576)
		(width 0.16002)
		(layer "In11.Cu")
		(net "M_F_CPU0_SA_DQS_DN<3>")
	)
	(segment
		(start 314.629038 -236.891322)
		(end 314.629038 -237.117128)
		(width 0.16002)
		(layer "In11.Cu")
		(net "M_F_CPU0_SA_DQS_DN<3>")
	)
	(segment
		(start 286.454088 -229.21214)
		(end 288.908236 -229.21214)
		(width 0.16002)
		(layer "In11.Cu")
		(net "M_F_CPU0_SA_DQS_DN<3>")
	)
	(segment
		(start 298.2722 -228.731318)
		(end 298.716954 -228.731318)
		(width 0.16002)
		(layer "In11.Cu")
		(net "M_F_CPU0_SA_DQS_DN<3>")
	)
	(segment
		(start 291.1729 -228.731318)
		(end 291.541962 -228.362256)
		(width 0.16002)
		(layer "In11.Cu")
		(net "M_F_CPU0_SA_DQS_DN<3>")
	)
	(segment
		(start 271.391888 -229.361238)
		(end 272.071592 -229.361238)
		(width 0.16002)
		(layer "In11.Cu")
		(net "M_F_CPU0_SA_DQS_DN<3>")
	)
	(segment
		(start 285.604204 -228.362256)
		(end 286.454088 -229.21214)
		(width 0.16002)
		(layer "In11.Cu")
		(net "M_F_CPU0_SA_DQS_DN<3>")
	)
	(segment
		(start 272.22069 -229.21214)
		(end 273.820128 -229.21214)
		(width 0.16002)
		(layer "In11.Cu")
		(net "M_F_CPU0_SA_DQS_DN<3>")
	)
	(segment
		(start 278.910034 -229.21214)
		(end 281.364182 -229.21214)
		(width 0.16002)
		(layer "In11.Cu")
		(net "M_F_CPU0_SA_DQS_DN<3>")
	)
	(segment
		(start 282.358592 -229.556818)
		(end 283.184092 -228.731318)
		(width 0.16002)
		(layer "In11.Cu")
		(net "M_F_CPU0_SA_DQS_DN<3>")
	)
	(segment
		(start 291.541962 -228.362256)
		(end 293.148258 -228.362256)
		(width 0.16002)
		(layer "In11.Cu")
		(net "M_F_CPU0_SA_DQS_DN<3>")
	)
	(segment
		(start 323.919596 -240.69294)
		(end 323.978778 -240.633758)
		(width 0.09525)
		(layer "In11.Cu")
		(net "M_F_CPU0_SA_DQS_DN<3>")
	)
	(segment
		(start 305.018186 -229.529132)
		(end 305.816 -228.731318)
		(width 0.16002)
		(layer "In11.Cu")
		(net "M_F_CPU0_SA_DQS_DN<3>")
	)
	(segment
		(start 315.755274 -238.017558)
		(end 316.00267 -238.264954)
		(width 0.16002)
		(layer "In11.Cu")
		(net "M_F_CPU0_SA_DQS_DN<3>")
	)
	(segment
		(start 311.236614 -234.997752)
		(end 311.907174 -235.668312)
		(width 0.16002)
		(layer "In11.Cu")
		(net "M_F_CPU0_SA_DQS_DN<3>")
	)
	(segment
		(start 275.640038 -228.731318)
		(end 276.084792 -228.731318)
		(width 0.16002)
		(layer "In11.Cu")
		(net "M_F_CPU0_SA_DQS_DN<3>")
	)
	(segment
		(start 297.4467 -229.556818)
		(end 298.2722 -228.731318)
		(width 0.16002)
		(layer "In11.Cu")
		(net "M_F_CPU0_SA_DQS_DN<3>")
	)
	(segment
		(start 273.820128 -229.21214)
		(end 274.164806 -229.556818)
		(width 0.16002)
		(layer "In11.Cu")
		(net "M_F_CPU0_SA_DQS_DN<3>")
	)
	(segment
		(start 314.381642 -236.643926)
		(end 314.629038 -236.891322)
		(width 0.16002)
		(layer "In11.Cu")
		(net "M_F_CPU0_SA_DQS_DN<3>")
	)
	(segment
		(start 281.70886 -229.556818)
		(end 282.358592 -229.556818)
		(width 0.16002)
		(layer "In11.Cu")
		(net "M_F_CPU0_SA_DQS_DN<3>")
	)
	(segment
		(start 281.364182 -229.21214)
		(end 281.70886 -229.556818)
		(width 0.16002)
		(layer "In11.Cu")
		(net "M_F_CPU0_SA_DQS_DN<3>")
	)
	(segment
		(start 323.978778 -240.633758)
		(end 324.116446 -240.633758)
		(width 0.09525)
		(layer "In11.Cu")
		(net "M_F_CPU0_SA_DQS_DN<3>")
	)
	(segment
		(start 269.648178 -229.63505)
		(end 269.92199 -229.361238)
		(width 0.16002)
		(layer "In11.Cu")
		(net "M_F_CPU0_SA_DQS_DN<3>")
	)
	(segment
		(start 313.255406 -235.743496)
		(end 312.857134 -236.141514)
		(width 0.16002)
		(layer "In11.Cu")
		(net "M_F_CPU0_SA_DQS_DN<3>")
	)
	(segment
		(start 326.25665 -241.678206)
		(end 326.351392 -241.678206)
		(width 0.09525)
		(layer "In11.Cu")
		(net "M_F_CPU0_SA_DQS_DN<3>")
	)
	(segment
		(start 326.256142 -241.677698)
		(end 326.25665 -241.678206)
		(width 0.09525)
		(layer "In11.Cu")
		(net "M_F_CPU0_SA_DQS_DN<3>")
	)
	(segment
		(start 332.145132 -241.788696)
		(end 331.991208 -242.054126)
		(width 0.09525)
		(layer "In11.Cu")
		(net "M_F_CPU0_SA_DQS_DN<3>")
	)
	(segment
		(start 289.252914 -229.556818)
		(end 289.902646 -229.556818)
		(width 0.16002)
		(layer "In11.Cu")
		(net "M_F_CPU0_SA_DQS_DN<3>")
	)
	(segment
		(start 293.148258 -228.362256)
		(end 293.998142 -229.21214)
		(width 0.16002)
		(layer "In11.Cu")
		(net "M_F_CPU0_SA_DQS_DN<3>")
	)
	(segment
		(start 276.084792 -228.731318)
		(end 276.453854 -228.362256)
		(width 0.16002)
		(layer "In11.Cu")
		(net "M_F_CPU0_SA_DQS_DN<3>")
	)
	(segment
		(start 313.280806 -237.041944)
		(end 313.75731 -237.041944)
		(width 0.16002)
		(layer "In11.Cu")
		(net "M_F_CPU0_SA_DQS_DN<3>")
	)
	(segment
		(start 293.998142 -229.21214)
		(end 296.45229 -229.21214)
		(width 0.16002)
		(layer "In11.Cu")
		(net "M_F_CPU0_SA_DQS_DN<3>")
	)
	(segment
		(start 313.75731 -237.041944)
		(end 314.155582 -236.643926)
		(width 0.16002)
		(layer "In11.Cu")
		(net "M_F_CPU0_SA_DQS_DN<3>")
	)
	(segment
		(start 306.667916 -228.731318)
		(end 311.236614 -233.300016)
		(width 0.16002)
		(layer "In11.Cu")
		(net "M_F_CPU0_SA_DQS_DN<3>")
	)
	(segment
		(start 324.116446 -240.633758)
		(end 324.587362 -241.104674)
		(width 0.09525)
		(layer "In11.Cu")
		(net "M_F_CPU0_SA_DQS_DN<3>")
	)
	(segment
		(start 324.587362 -241.104674)
		(end 324.882256 -241.104674)
		(width 0.09525)
		(layer "In11.Cu")
		(net "M_F_CPU0_SA_DQS_DN<3>")
	)
	(segment
		(start 298.716954 -228.731318)
		(end 299.086016 -228.362256)
		(width 0.16002)
		(layer "In11.Cu")
		(net "M_F_CPU0_SA_DQS_DN<3>")
	)
	(segment
		(start 283.628846 -228.731318)
		(end 283.997908 -228.362256)
		(width 0.16002)
		(layer "In11.Cu")
		(net "M_F_CPU0_SA_DQS_DN<3>")
	)
	(segment
		(start 314.629038 -237.117128)
		(end 314.230766 -237.515146)
		(width 0.16002)
		(layer "In11.Cu")
		(net "M_F_CPU0_SA_DQS_DN<3>")
	)
	(segment
		(start 328.411332 -241.72418)
		(end 328.419714 -241.729006)
		(width 0.09525)
		(layer "In11.Cu")
		(net "M_F_CPU0_SA_DQS_DN<3>")
	)
	(segment
		(start 314.654438 -238.415576)
		(end 315.130942 -238.415576)
		(width 0.16002)
		(layer "In11.Cu")
		(net "M_F_CPU0_SA_DQS_DN<3>")
	)
	(segment
		(start 316.00267 -238.49076)
		(end 315.604398 -238.888778)
		(width 0.16002)
		(layer "In11.Cu")
		(net "M_F_CPU0_SA_DQS_DN<3>")
	)
	(segment
		(start 314.230766 -237.515146)
		(end 314.230766 -237.991904)
		(width 0.16002)
		(layer "In11.Cu")
		(net "M_F_CPU0_SA_DQS_DN<3>")
	)
	(segment
		(start 305.816 -228.731318)
		(end 306.667916 -228.731318)
		(width 0.16002)
		(layer "In11.Cu")
		(net "M_F_CPU0_SA_DQS_DN<3>")
	)
	(segment
		(start 328.982578 -241.729006)
		(end 328.99096 -241.72418)
		(width 0.09525)
		(layer "In11.Cu")
		(net "M_F_CPU0_SA_DQS_DN<3>")
	)
	(segment
		(start 272.071592 -229.361238)
		(end 272.22069 -229.21214)
		(width 0.16002)
		(layer "In11.Cu")
		(net "M_F_CPU0_SA_DQS_DN<3>")
	)
	(segment
		(start 271.275048 -229.478078)
		(end 271.391888 -229.361238)
		(width 0.16002)
		(layer "In11.Cu")
		(net "M_F_CPU0_SA_DQS_DN<3>")
	)
	(segment
		(start 312.78195 -235.270294)
		(end 313.00801 -235.270294)
		(width 0.16002)
		(layer "In11.Cu")
		(net "M_F_CPU0_SA_DQS_DN<3>")
	)
	(segment
		(start 315.529214 -238.017558)
		(end 315.755274 -238.017558)
		(width 0.16002)
		(layer "In11.Cu")
		(net "M_F_CPU0_SA_DQS_DN<3>")
	)
	(segment
		(start 331.23124 -241.72418)
		(end 331.239622 -241.729006)
		(width 0.09525)
		(layer "In11.Cu")
		(net "M_F_CPU0_SA_DQS_DN<3>")
	)
	(segment
		(start 283.184092 -228.731318)
		(end 283.628846 -228.731318)
		(width 0.16002)
		(layer "In11.Cu")
		(net "M_F_CPU0_SA_DQS_DN<3>")
	)
	(segment
		(start 274.814538 -229.556818)
		(end 275.640038 -228.731318)
		(width 0.16002)
		(layer "In11.Cu")
		(net "M_F_CPU0_SA_DQS_DN<3>")
	)
	(segment
		(start 312.383678 -235.668312)
		(end 312.78195 -235.270294)
		(width 0.16002)
		(layer "In11.Cu")
		(net "M_F_CPU0_SA_DQS_DN<3>")
	)
	(segment
		(start 313.00801 -235.270294)
		(end 313.255406 -235.51769)
		(width 0.16002)
		(layer "In11.Cu")
		(net "M_F_CPU0_SA_DQS_DN<3>")
	)
	(segment
		(start 327.47204 -241.72418)
		(end 327.480422 -241.729006)
		(width 0.09525)
		(layer "In11.Cu")
		(net "M_F_CPU0_SA_DQS_DN<3>")
	)
	(segment
		(start 314.155582 -236.643926)
		(end 314.381642 -236.643926)
		(width 0.16002)
		(layer "In11.Cu")
		(net "M_F_CPU0_SA_DQS_DN<3>")
	)
	(segment
		(start 325.45528 -241.677698)
		(end 326.256142 -241.677698)
		(width 0.09525)
		(layer "In11.Cu")
		(net "M_F_CPU0_SA_DQS_DN<3>")
	)
	(segment
		(start 316.931802 -240.69294)
		(end 323.895974 -240.69294)
		(width 0.16002)
		(layer "In11.Cu")
		(net "M_F_CPU0_SA_DQS_DN<3>")
	)
	(segment
		(start 300.692312 -228.362256)
		(end 301.859188 -229.529132)
		(width 0.16002)
		(layer "In11.Cu")
		(net "M_F_CPU0_SA_DQS_DN<3>")
	)
	(segment
		(start 316.00267 -238.264954)
		(end 316.00267 -238.49076)
		(width 0.16002)
		(layer "In11.Cu")
		(net "M_F_CPU0_SA_DQS_DN<3>")
	)
	(segment
		(start 312.857134 -236.618272)
		(end 313.280806 -237.041944)
		(width 0.16002)
		(layer "In11.Cu")
		(net "M_F_CPU0_SA_DQS_DN<3>")
	)
	(segment
		(start 323.895974 -240.69294)
		(end 323.919596 -240.69294)
		(width 0.09525)
		(layer "In11.Cu")
		(net "M_F_CPU0_SA_DQS_DN<3>")
	)
	(segment
		(start 312.857134 -236.141514)
		(end 312.857134 -236.618272)
		(width 0.16002)
		(layer "In11.Cu")
		(net "M_F_CPU0_SA_DQS_DN<3>")
	)
	(segment
		(start 283.997908 -228.362256)
		(end 285.604204 -228.362256)
		(width 0.16002)
		(layer "In11.Cu")
		(net "M_F_CPU0_SA_DQS_DN<3>")
	)
	(segment
		(start 311.236614 -233.300016)
		(end 311.236614 -234.997752)
		(width 0.16002)
		(layer "In11.Cu")
		(net "M_F_CPU0_SA_DQS_DN<3>")
	)
	(segment
		(start 270.794988 -229.478078)
		(end 271.275048 -229.478078)
		(width 0.16002)
		(layer "In11.Cu")
		(net "M_F_CPU0_SA_DQS_DN<3>")
	)
	(segment
		(start 324.882256 -241.104674)
		(end 325.45528 -241.677698)
		(width 0.09525)
		(layer "In11.Cu")
		(net "M_F_CPU0_SA_DQS_DN<3>")
	)
	(segment
		(start 311.907174 -235.668312)
		(end 312.383678 -235.668312)
		(width 0.16002)
		(layer "In11.Cu")
		(net "M_F_CPU0_SA_DQS_DN<3>")
	)
	(segment
		(start 315.130942 -238.415576)
		(end 315.529214 -238.017558)
		(width 0.16002)
		(layer "In11.Cu")
		(net "M_F_CPU0_SA_DQS_DN<3>")
	)
	(segment
		(start 315.604398 -239.365536)
		(end 316.931802 -240.69294)
		(width 0.16002)
		(layer "In11.Cu")
		(net "M_F_CPU0_SA_DQS_DN<3>")
	)
	(segment
		(start 296.796968 -229.556818)
		(end 297.4467 -229.556818)
		(width 0.16002)
		(layer "In11.Cu")
		(net "M_F_CPU0_SA_DQS_DN<3>")
	)
	(segment
		(start 276.453854 -228.362256)
		(end 278.06015 -228.362256)
		(width 0.16002)
		(layer "In11.Cu")
		(net "M_F_CPU0_SA_DQS_DN<3>")
	)
	(segment
		(start 296.45229 -229.21214)
		(end 296.796968 -229.556818)
		(width 0.16002)
		(layer "In11.Cu")
		(net "M_F_CPU0_SA_DQS_DN<3>")
	)
	(segment
		(start 288.908236 -229.21214)
		(end 289.252914 -229.556818)
		(width 0.16002)
		(layer "In11.Cu")
		(net "M_F_CPU0_SA_DQS_DN<3>")
	)
	(segment
		(start 289.902646 -229.556818)
		(end 290.728146 -228.731318)
		(width 0.16002)
		(layer "In11.Cu")
		(net "M_F_CPU0_SA_DQS_DN<3>")
	)
	(segment
		(start 290.728146 -228.731318)
		(end 291.1729 -228.731318)
		(width 0.16002)
		(layer "In11.Cu")
		(net "M_F_CPU0_SA_DQS_DN<3>")
	)
	(segment
		(start 313.255406 -235.51769)
		(end 313.255406 -235.743496)
		(width 0.16002)
		(layer "In11.Cu")
		(net "M_F_CPU0_SA_DQS_DN<3>")
	)
	(segment
		(start 299.086016 -228.362256)
		(end 300.692312 -228.362256)
		(width 0.16002)
		(layer "In11.Cu")
		(net "M_F_CPU0_SA_DQS_DN<3>")
	)
	(segment
		(start 327.480422 -241.729006)
		(end 327.498456 -241.73942)
		(width 0.09525)
		(layer "In11.Cu")
		(net "M_F_CPU0_SA_DQS_DN<3>")
	)
	(segment
		(start 315.604398 -238.888778)
		(end 315.604398 -239.365536)
		(width 0.16002)
		(layer "In11.Cu")
		(net "M_F_CPU0_SA_DQS_DN<3>")
	)
	(arc
		(start 330.299568 -241.729006)
		(mid 330.581 -241.804761)
		(end 330.862432 -241.729006)
		(width 0.09525)
		(layer "In11.Cu")
		(net "M_F_CPU0_SA_DQS_DN<3>")
	)
	(arc
		(start 326.540114 -241.729006)
		(mid 326.811564 -241.805041)
		(end 327.085706 -241.73942)
		(width 0.09525)
		(layer "In11.Cu")
		(net "M_F_CPU0_SA_DQS_DN<3>")
	)
	(arc
		(start 326.351392 -241.678206)
		(mid 326.449111 -241.691129)
		(end 326.540114 -241.729006)
		(width 0.09525)
		(layer "In11.Cu")
		(net "M_F_CPU0_SA_DQS_DN<3>")
	)
	(arc
		(start 328.419714 -241.729006)
		(mid 328.701146 -241.804761)
		(end 328.982578 -241.729006)
		(width 0.09525)
		(layer "In11.Cu")
		(net "M_F_CPU0_SA_DQS_DN<3>")
	)
	(arc
		(start 327.10374 -241.729006)
		(mid 327.287261 -241.678362)
		(end 327.47204 -241.72418)
		(width 0.09525)
		(layer "In11.Cu")
		(net "M_F_CPU0_SA_DQS_DN<3>")
	)
	(arc
		(start 328.99096 -241.72418)
		(mid 329.175992 -241.678266)
		(end 329.359768 -241.729006)
		(width 0.09525)
		(layer "In11.Cu")
		(net "M_F_CPU0_SA_DQS_DN<3>")
	)
	(arc
		(start 329.922632 -241.729006)
		(mid 330.1111 -241.678329)
		(end 330.299568 -241.729006)
		(width 0.09525)
		(layer "In11.Cu")
		(net "M_F_CPU0_SA_DQS_DN<3>")
	)
	(arc
		(start 330.862432 -241.729006)
		(mid 331.046207 -241.678234)
		(end 331.23124 -241.72418)
		(width 0.09525)
		(layer "In11.Cu")
		(net "M_F_CPU0_SA_DQS_DN<3>")
	)
	(arc
		(start 331.802486 -241.729006)
		(mid 331.959084 -241.679717)
		(end 332.121764 -241.701828)
		(width 0.09525)
		(layer "In11.Cu")
		(net "M_F_CPU0_SA_DQS_DN<3>")
	)
	(arc
		(start 328.042524 -241.729006)
		(mid 328.226299 -241.678234)
		(end 328.411332 -241.72418)
		(width 0.09525)
		(layer "In11.Cu")
		(net "M_F_CPU0_SA_DQS_DN<3>")
	)
	(arc
		(start 329.359768 -241.729006)
		(mid 329.6412 -241.804761)
		(end 329.922632 -241.729006)
		(width 0.09525)
		(layer "In11.Cu")
		(net "M_F_CPU0_SA_DQS_DN<3>")
	)
	(arc
		(start 327.498456 -241.73942)
		(mid 327.771836 -241.804641)
		(end 328.042524 -241.729006)
		(width 0.09525)
		(layer "In11.Cu")
		(net "M_F_CPU0_SA_DQS_DN<3>")
	)
	(arc
		(start 331.239622 -241.729006)
		(mid 331.521054 -241.804761)
		(end 331.802486 -241.729006)
		(width 0.09525)
		(layer "In11.Cu")
		(net "M_F_CPU0_SA_DQS_DN<3>")
	)
	(segment
		(start 332.45806 -237.460028)
		(end 331.991208 -237.19409)
		(width 0.12954)
		(layer "F.Cu")
		(net "M_F_CPU0_SA_DQS_DN<2>")
	)
	(segment
		(start 308.801516 -221.043246)
		(end 309.09133 -221.33306)
		(width 0.16002)
		(layer "In11.Cu")
		(net "M_F_CPU0_SA_DQS_DN<2>")
	)
	(segment
		(start 303.859184 -220.671644)
		(end 305.21402 -220.671644)
		(width 0.16002)
		(layer "In11.Cu")
		(net "M_F_CPU0_SA_DQS_DN<2>")
	)
	(segment
		(start 290.728146 -219.381324)
		(end 291.1729 -219.381324)
		(width 0.16002)
		(layer "In11.Cu")
		(net "M_F_CPU0_SA_DQS_DN<2>")
	)
	(segment
		(start 324.180454 -235.320586)
		(end 324.6374 -235.777532)
		(width 0.09525)
		(layer "In11.Cu")
		(net "M_F_CPU0_SA_DQS_DN<2>")
	)
	(segment
		(start 269.92199 -220.011244)
		(end 270.690848 -220.011244)
		(width 0.16002)
		(layer "In11.Cu")
		(net "M_F_CPU0_SA_DQS_DN<2>")
	)
	(segment
		(start 327.085706 -236.879384)
		(end 327.10374 -236.86897)
		(width 0.09525)
		(layer "In11.Cu")
		(net "M_F_CPU0_SA_DQS_DN<2>")
	)
	(segment
		(start 286.454088 -219.862146)
		(end 288.355532 -219.862146)
		(width 0.16002)
		(layer "In11.Cu")
		(net "M_F_CPU0_SA_DQS_DN<2>")
	)
	(segment
		(start 289.539934 -220.569536)
		(end 290.728146 -219.381324)
		(width 0.16002)
		(layer "In11.Cu")
		(net "M_F_CPU0_SA_DQS_DN<2>")
	)
	(segment
		(start 274.48129 -220.540072)
		(end 275.640038 -219.381324)
		(width 0.16002)
		(layer "In11.Cu")
		(net "M_F_CPU0_SA_DQS_DN<2>")
	)
	(segment
		(start 275.640038 -219.381324)
		(end 276.084792 -219.381324)
		(width 0.16002)
		(layer "In11.Cu")
		(net "M_F_CPU0_SA_DQS_DN<2>")
	)
	(segment
		(start 305.21402 -220.671644)
		(end 305.551078 -220.334586)
		(width 0.16002)
		(layer "In11.Cu")
		(net "M_F_CPU0_SA_DQS_DN<2>")
	)
	(segment
		(start 305.551078 -219.541344)
		(end 305.711098 -219.381324)
		(width 0.16002)
		(layer "In11.Cu")
		(net "M_F_CPU0_SA_DQS_DN<2>")
	)
	(segment
		(start 291.541962 -219.012262)
		(end 293.148258 -219.012262)
		(width 0.16002)
		(layer "In11.Cu")
		(net "M_F_CPU0_SA_DQS_DN<2>")
	)
	(segment
		(start 311.182258 -224.041716)
		(end 311.182258 -224.572322)
		(width 0.16002)
		(layer "In11.Cu")
		(net "M_F_CPU0_SA_DQS_DN<2>")
	)
	(segment
		(start 278.910034 -219.862146)
		(end 280.811478 -219.862146)
		(width 0.16002)
		(layer "In11.Cu")
		(net "M_F_CPU0_SA_DQS_DN<2>")
	)
	(segment
		(start 309.55742 -222.416878)
		(end 310.175148 -222.416878)
		(width 0.16002)
		(layer "In11.Cu")
		(net "M_F_CPU0_SA_DQS_DN<2>")
	)
	(segment
		(start 281.518868 -220.569536)
		(end 281.99588 -220.569536)
		(width 0.16002)
		(layer "In11.Cu")
		(net "M_F_CPU0_SA_DQS_DN<2>")
	)
	(segment
		(start 310.464962 -223.32442)
		(end 311.182258 -224.041716)
		(width 0.16002)
		(layer "In11.Cu")
		(net "M_F_CPU0_SA_DQS_DN<2>")
	)
	(segment
		(start 331.23124 -236.864144)
		(end 331.239622 -236.86897)
		(width 0.09525)
		(layer "In11.Cu")
		(net "M_F_CPU0_SA_DQS_DN<2>")
	)
	(segment
		(start 323.895974 -235.04144)
		(end 323.919596 -235.04144)
		(width 0.09525)
		(layer "In11.Cu")
		(net "M_F_CPU0_SA_DQS_DN<2>")
	)
	(segment
		(start 305.551078 -220.334586)
		(end 305.551078 -219.541344)
		(width 0.16002)
		(layer "In11.Cu")
		(net "M_F_CPU0_SA_DQS_DN<2>")
	)
	(segment
		(start 307.717698 -219.959428)
		(end 307.717698 -220.577156)
		(width 0.16002)
		(layer "In11.Cu")
		(net "M_F_CPU0_SA_DQS_DN<2>")
	)
	(segment
		(start 289.062922 -220.569536)
		(end 289.539934 -220.569536)
		(width 0.16002)
		(layer "In11.Cu")
		(net "M_F_CPU0_SA_DQS_DN<2>")
	)
	(segment
		(start 302.853852 -219.808552)
		(end 302.853852 -219.630752)
		(width 0.16002)
		(layer "In11.Cu")
		(net "M_F_CPU0_SA_DQS_DN<2>")
	)
	(segment
		(start 280.811478 -219.862146)
		(end 281.518868 -220.569536)
		(width 0.16002)
		(layer "In11.Cu")
		(net "M_F_CPU0_SA_DQS_DN<2>")
	)
	(segment
		(start 298.716954 -219.381324)
		(end 299.086016 -219.012262)
		(width 0.16002)
		(layer "In11.Cu")
		(net "M_F_CPU0_SA_DQS_DN<2>")
	)
	(segment
		(start 303.522126 -220.334586)
		(end 303.859184 -220.671644)
		(width 0.16002)
		(layer "In11.Cu")
		(net "M_F_CPU0_SA_DQS_DN<2>")
	)
	(segment
		(start 276.453854 -219.012262)
		(end 278.06015 -219.012262)
		(width 0.16002)
		(layer "In11.Cu")
		(net "M_F_CPU0_SA_DQS_DN<2>")
	)
	(segment
		(start 293.148258 -219.012262)
		(end 293.998142 -219.862146)
		(width 0.16002)
		(layer "In11.Cu")
		(net "M_F_CPU0_SA_DQS_DN<2>")
	)
	(segment
		(start 288.355532 -219.862146)
		(end 289.062922 -220.569536)
		(width 0.16002)
		(layer "In11.Cu")
		(net "M_F_CPU0_SA_DQS_DN<2>")
	)
	(segment
		(start 324.6374 -235.777532)
		(end 325.0184 -235.777532)
		(width 0.09525)
		(layer "In11.Cu")
		(net "M_F_CPU0_SA_DQS_DN<2>")
	)
	(segment
		(start 281.99588 -220.569536)
		(end 283.184092 -219.381324)
		(width 0.16002)
		(layer "In11.Cu")
		(net "M_F_CPU0_SA_DQS_DN<2>")
	)
	(segment
		(start 311.182258 -224.572322)
		(end 321.651376 -235.04144)
		(width 0.16002)
		(layer "In11.Cu")
		(net "M_F_CPU0_SA_DQS_DN<2>")
	)
	(segment
		(start 270.690848 -220.011244)
		(end 270.807688 -220.128084)
		(width 0.16002)
		(layer "In11.Cu")
		(net "M_F_CPU0_SA_DQS_DN<2>")
	)
	(segment
		(start 305.711098 -219.381324)
		(end 306.521866 -219.381324)
		(width 0.16002)
		(layer "In11.Cu")
		(net "M_F_CPU0_SA_DQS_DN<2>")
	)
	(segment
		(start 270.807688 -220.128084)
		(end 271.287748 -220.128084)
		(width 0.16002)
		(layer "In11.Cu")
		(net "M_F_CPU0_SA_DQS_DN<2>")
	)
	(segment
		(start 310.175148 -222.416878)
		(end 310.464962 -222.706692)
		(width 0.16002)
		(layer "In11.Cu")
		(net "M_F_CPU0_SA_DQS_DN<2>")
	)
	(segment
		(start 296.45229 -219.862146)
		(end 296.796968 -220.206824)
		(width 0.16002)
		(layer "In11.Cu")
		(net "M_F_CPU0_SA_DQS_DN<2>")
	)
	(segment
		(start 306.521866 -219.381324)
		(end 306.810156 -219.669614)
		(width 0.16002)
		(layer "In11.Cu")
		(net "M_F_CPU0_SA_DQS_DN<2>")
	)
	(segment
		(start 310.464962 -222.706692)
		(end 310.464962 -223.32442)
		(width 0.16002)
		(layer "In11.Cu")
		(net "M_F_CPU0_SA_DQS_DN<2>")
	)
	(segment
		(start 272.22069 -219.862146)
		(end 273.267424 -219.862146)
		(width 0.16002)
		(layer "In11.Cu")
		(net "M_F_CPU0_SA_DQS_DN<2>")
	)
	(segment
		(start 283.997908 -219.012262)
		(end 285.604204 -219.012262)
		(width 0.16002)
		(layer "In11.Cu")
		(net "M_F_CPU0_SA_DQS_DN<2>")
	)
	(segment
		(start 324.180454 -235.077762)
		(end 324.180454 -235.320586)
		(width 0.09525)
		(layer "In11.Cu")
		(net "M_F_CPU0_SA_DQS_DN<2>")
	)
	(segment
		(start 302.516794 -220.14561)
		(end 302.853852 -219.808552)
		(width 0.16002)
		(layer "In11.Cu")
		(net "M_F_CPU0_SA_DQS_DN<2>")
	)
	(segment
		(start 285.604204 -219.012262)
		(end 286.454088 -219.862146)
		(width 0.16002)
		(layer "In11.Cu")
		(net "M_F_CPU0_SA_DQS_DN<2>")
	)
	(segment
		(start 299.086016 -219.012262)
		(end 300.692312 -219.012262)
		(width 0.16002)
		(layer "In11.Cu")
		(net "M_F_CPU0_SA_DQS_DN<2>")
	)
	(segment
		(start 272.071592 -220.011244)
		(end 272.22069 -219.862146)
		(width 0.16002)
		(layer "In11.Cu")
		(net "M_F_CPU0_SA_DQS_DN<2>")
	)
	(segment
		(start 327.480422 -236.86897)
		(end 327.498456 -236.879384)
		(width 0.09525)
		(layer "In11.Cu")
		(net "M_F_CPU0_SA_DQS_DN<2>")
	)
	(segment
		(start 293.998142 -219.862146)
		(end 296.45229 -219.862146)
		(width 0.16002)
		(layer "In11.Cu")
		(net "M_F_CPU0_SA_DQS_DN<2>")
	)
	(segment
		(start 271.287748 -220.128084)
		(end 271.404588 -220.011244)
		(width 0.16002)
		(layer "In11.Cu")
		(net "M_F_CPU0_SA_DQS_DN<2>")
	)
	(segment
		(start 308.183788 -221.043246)
		(end 308.801516 -221.043246)
		(width 0.16002)
		(layer "In11.Cu")
		(net "M_F_CPU0_SA_DQS_DN<2>")
	)
	(segment
		(start 307.717698 -220.577156)
		(end 308.183788 -221.043246)
		(width 0.16002)
		(layer "In11.Cu")
		(net "M_F_CPU0_SA_DQS_DN<2>")
	)
	(segment
		(start 328.982578 -236.86897)
		(end 328.99096 -236.864144)
		(width 0.09525)
		(layer "In11.Cu")
		(net "M_F_CPU0_SA_DQS_DN<2>")
	)
	(segment
		(start 269.648178 -220.285056)
		(end 269.92199 -220.011244)
		(width 0.16002)
		(layer "In11.Cu")
		(net "M_F_CPU0_SA_DQS_DN<2>")
	)
	(segment
		(start 303.362106 -219.470732)
		(end 303.522126 -219.630752)
		(width 0.16002)
		(layer "In11.Cu")
		(net "M_F_CPU0_SA_DQS_DN<2>")
	)
	(segment
		(start 302.853852 -219.630752)
		(end 303.013872 -219.470732)
		(width 0.16002)
		(layer "In11.Cu")
		(net "M_F_CPU0_SA_DQS_DN<2>")
	)
	(segment
		(start 303.522126 -219.630752)
		(end 303.522126 -220.334586)
		(width 0.16002)
		(layer "In11.Cu")
		(net "M_F_CPU0_SA_DQS_DN<2>")
	)
	(segment
		(start 332.121764 -236.841792)
		(end 332.145132 -236.92866)
		(width 0.09525)
		(layer "In11.Cu")
		(net "M_F_CPU0_SA_DQS_DN<2>")
	)
	(segment
		(start 321.651376 -235.04144)
		(end 323.895974 -235.04144)
		(width 0.16002)
		(layer "In11.Cu")
		(net "M_F_CPU0_SA_DQS_DN<2>")
	)
	(segment
		(start 278.06015 -219.012262)
		(end 278.910034 -219.862146)
		(width 0.16002)
		(layer "In11.Cu")
		(net "M_F_CPU0_SA_DQS_DN<2>")
	)
	(segment
		(start 291.1729 -219.381324)
		(end 291.541962 -219.012262)
		(width 0.16002)
		(layer "In11.Cu")
		(net "M_F_CPU0_SA_DQS_DN<2>")
	)
	(segment
		(start 303.013872 -219.470732)
		(end 303.362106 -219.470732)
		(width 0.16002)
		(layer "In11.Cu")
		(net "M_F_CPU0_SA_DQS_DN<2>")
	)
	(segment
		(start 327.47204 -236.864144)
		(end 327.480422 -236.86897)
		(width 0.09525)
		(layer "In11.Cu")
		(net "M_F_CPU0_SA_DQS_DN<2>")
	)
	(segment
		(start 296.796968 -220.206824)
		(end 297.4467 -220.206824)
		(width 0.16002)
		(layer "In11.Cu")
		(net "M_F_CPU0_SA_DQS_DN<2>")
	)
	(segment
		(start 283.628846 -219.381324)
		(end 283.997908 -219.012262)
		(width 0.16002)
		(layer "In11.Cu")
		(net "M_F_CPU0_SA_DQS_DN<2>")
	)
	(segment
		(start 271.404588 -220.011244)
		(end 272.071592 -220.011244)
		(width 0.16002)
		(layer "In11.Cu")
		(net "M_F_CPU0_SA_DQS_DN<2>")
	)
	(segment
		(start 300.92904 -219.577412)
		(end 301.497238 -220.14561)
		(width 0.16002)
		(layer "In11.Cu")
		(net "M_F_CPU0_SA_DQS_DN<2>")
	)
	(segment
		(start 273.94535 -220.540072)
		(end 274.48129 -220.540072)
		(width 0.16002)
		(layer "In11.Cu")
		(net "M_F_CPU0_SA_DQS_DN<2>")
	)
	(segment
		(start 297.4467 -220.206824)
		(end 298.2722 -219.381324)
		(width 0.16002)
		(layer "In11.Cu")
		(net "M_F_CPU0_SA_DQS_DN<2>")
	)
	(segment
		(start 332.145132 -236.92866)
		(end 331.991208 -237.19409)
		(width 0.09525)
		(layer "In11.Cu")
		(net "M_F_CPU0_SA_DQS_DN<2>")
	)
	(segment
		(start 283.184092 -219.381324)
		(end 283.628846 -219.381324)
		(width 0.16002)
		(layer "In11.Cu")
		(net "M_F_CPU0_SA_DQS_DN<2>")
	)
	(segment
		(start 300.692312 -219.012262)
		(end 300.92904 -219.24899)
		(width 0.16002)
		(layer "In11.Cu")
		(net "M_F_CPU0_SA_DQS_DN<2>")
	)
	(segment
		(start 273.267424 -219.862146)
		(end 273.94535 -220.540072)
		(width 0.16002)
		(layer "In11.Cu")
		(net "M_F_CPU0_SA_DQS_DN<2>")
	)
	(segment
		(start 324.085204 -234.982512)
		(end 324.180454 -235.077762)
		(width 0.09525)
		(layer "In11.Cu")
		(net "M_F_CPU0_SA_DQS_DN<2>")
	)
	(segment
		(start 323.978524 -234.982512)
		(end 324.085204 -234.982512)
		(width 0.09525)
		(layer "In11.Cu")
		(net "M_F_CPU0_SA_DQS_DN<2>")
	)
	(segment
		(start 307.427884 -219.669614)
		(end 307.717698 -219.959428)
		(width 0.16002)
		(layer "In11.Cu")
		(net "M_F_CPU0_SA_DQS_DN<2>")
	)
	(segment
		(start 276.084792 -219.381324)
		(end 276.453854 -219.012262)
		(width 0.16002)
		(layer "In11.Cu")
		(net "M_F_CPU0_SA_DQS_DN<2>")
	)
	(segment
		(start 300.92904 -219.24899)
		(end 300.92904 -219.577412)
		(width 0.16002)
		(layer "In11.Cu")
		(net "M_F_CPU0_SA_DQS_DN<2>")
	)
	(segment
		(start 301.497238 -220.14561)
		(end 302.516794 -220.14561)
		(width 0.16002)
		(layer "In11.Cu")
		(net "M_F_CPU0_SA_DQS_DN<2>")
	)
	(segment
		(start 325.0184 -235.777532)
		(end 326.058022 -236.817154)
		(width 0.09525)
		(layer "In11.Cu")
		(net "M_F_CPU0_SA_DQS_DN<2>")
	)
	(segment
		(start 309.09133 -221.33306)
		(end 309.09133 -221.950788)
		(width 0.16002)
		(layer "In11.Cu")
		(net "M_F_CPU0_SA_DQS_DN<2>")
	)
	(segment
		(start 298.2722 -219.381324)
		(end 298.716954 -219.381324)
		(width 0.16002)
		(layer "In11.Cu")
		(net "M_F_CPU0_SA_DQS_DN<2>")
	)
	(segment
		(start 326.058022 -236.817154)
		(end 326.351138 -236.817154)
		(width 0.09525)
		(layer "In11.Cu")
		(net "M_F_CPU0_SA_DQS_DN<2>")
	)
	(segment
		(start 323.919596 -235.04144)
		(end 323.978524 -234.982512)
		(width 0.09525)
		(layer "In11.Cu")
		(net "M_F_CPU0_SA_DQS_DN<2>")
	)
	(segment
		(start 306.810156 -219.669614)
		(end 307.427884 -219.669614)
		(width 0.16002)
		(layer "In11.Cu")
		(net "M_F_CPU0_SA_DQS_DN<2>")
	)
	(segment
		(start 309.09133 -221.950788)
		(end 309.55742 -222.416878)
		(width 0.16002)
		(layer "In11.Cu")
		(net "M_F_CPU0_SA_DQS_DN<2>")
	)
	(segment
		(start 328.411332 -236.864144)
		(end 328.419714 -236.86897)
		(width 0.09525)
		(layer "In11.Cu")
		(net "M_F_CPU0_SA_DQS_DN<2>")
	)
	(arc
		(start 328.042524 -236.86897)
		(mid 328.226299 -236.818198)
		(end 328.411332 -236.864144)
		(width 0.09525)
		(layer "In11.Cu")
		(net "M_F_CPU0_SA_DQS_DN<2>")
	)
	(arc
		(start 326.540114 -236.86897)
		(mid 326.811564 -236.945005)
		(end 327.085706 -236.879384)
		(width 0.09525)
		(layer "In11.Cu")
		(net "M_F_CPU0_SA_DQS_DN<2>")
	)
	(arc
		(start 330.299568 -236.86897)
		(mid 330.581 -236.944725)
		(end 330.862432 -236.86897)
		(width 0.09525)
		(layer "In11.Cu")
		(net "M_F_CPU0_SA_DQS_DN<2>")
	)
	(arc
		(start 328.99096 -236.864144)
		(mid 329.175992 -236.81823)
		(end 329.359768 -236.86897)
		(width 0.09525)
		(layer "In11.Cu")
		(net "M_F_CPU0_SA_DQS_DN<2>")
	)
	(arc
		(start 331.239622 -236.86897)
		(mid 331.521054 -236.944725)
		(end 331.802486 -236.86897)
		(width 0.09525)
		(layer "In11.Cu")
		(net "M_F_CPU0_SA_DQS_DN<2>")
	)
	(arc
		(start 327.498456 -236.879384)
		(mid 327.771836 -236.944605)
		(end 328.042524 -236.86897)
		(width 0.09525)
		(layer "In11.Cu")
		(net "M_F_CPU0_SA_DQS_DN<2>")
	)
	(arc
		(start 331.802486 -236.86897)
		(mid 331.959084 -236.819681)
		(end 332.121764 -236.841792)
		(width 0.09525)
		(layer "In11.Cu")
		(net "M_F_CPU0_SA_DQS_DN<2>")
	)
	(arc
		(start 327.10374 -236.86897)
		(mid 327.287261 -236.818326)
		(end 327.47204 -236.864144)
		(width 0.09525)
		(layer "In11.Cu")
		(net "M_F_CPU0_SA_DQS_DN<2>")
	)
	(arc
		(start 329.359768 -236.86897)
		(mid 329.6412 -236.944725)
		(end 329.922632 -236.86897)
		(width 0.09525)
		(layer "In11.Cu")
		(net "M_F_CPU0_SA_DQS_DN<2>")
	)
	(arc
		(start 328.419714 -236.86897)
		(mid 328.701146 -236.944725)
		(end 328.982578 -236.86897)
		(width 0.09525)
		(layer "In11.Cu")
		(net "M_F_CPU0_SA_DQS_DN<2>")
	)
	(arc
		(start 330.862432 -236.86897)
		(mid 331.046207 -236.818198)
		(end 331.23124 -236.864144)
		(width 0.09525)
		(layer "In11.Cu")
		(net "M_F_CPU0_SA_DQS_DN<2>")
	)
	(arc
		(start 329.922632 -236.86897)
		(mid 330.1111 -236.818293)
		(end 330.299568 -236.86897)
		(width 0.09525)
		(layer "In11.Cu")
		(net "M_F_CPU0_SA_DQS_DN<2>")
	)
	(arc
		(start 326.351138 -236.817154)
		(mid 326.449067 -236.830526)
		(end 326.540114 -236.86897)
		(width 0.09525)
		(layer "In11.Cu")
		(net "M_F_CPU0_SA_DQS_DN<2>")
	)
	(segment
		(start 332.45806 -232.599992)
		(end 331.991208 -232.334054)
		(width 0.12954)
		(layer "F.Cu")
		(net "M_F_CPU0_SA_DQS_DN<1>")
	)
	(segment
		(start 323.78269 -229.134162)
		(end 324.458838 -229.81031)
		(width 0.09525)
		(layer "In11.Cu")
		(net "M_F_CPU0_SA_DQS_DN<1>")
	)
	(segment
		(start 312.326528 -216.444322)
		(end 312.750962 -216.868756)
		(width 0.16002)
		(layer "In11.Cu")
		(net "M_F_CPU0_SA_DQS_DN<1>")
	)
	(segment
		(start 283.184092 -210.03133)
		(end 283.628846 -210.03133)
		(width 0.16002)
		(layer "In11.Cu")
		(net "M_F_CPU0_SA_DQS_DN<1>")
	)
	(segment
		(start 269.92199 -210.66125)
		(end 270.640048 -210.66125)
		(width 0.16002)
		(layer "In11.Cu")
		(net "M_F_CPU0_SA_DQS_DN<1>")
	)
	(segment
		(start 291.541962 -209.662268)
		(end 293.148258 -209.662268)
		(width 0.16002)
		(layer "In11.Cu")
		(net "M_F_CPU0_SA_DQS_DN<1>")
	)
	(segment
		(start 289.902646 -210.85683)
		(end 290.728146 -210.03133)
		(width 0.16002)
		(layer "In11.Cu")
		(net "M_F_CPU0_SA_DQS_DN<1>")
	)
	(segment
		(start 325.234554 -230.14813)
		(end 325.234554 -230.851456)
		(width 0.09525)
		(layer "In11.Cu")
		(net "M_F_CPU0_SA_DQS_DN<1>")
	)
	(segment
		(start 296.796968 -210.85683)
		(end 297.4467 -210.85683)
		(width 0.16002)
		(layer "In11.Cu")
		(net "M_F_CPU0_SA_DQS_DN<1>")
	)
	(segment
		(start 272.22069 -210.512152)
		(end 273.820128 -210.512152)
		(width 0.16002)
		(layer "In11.Cu")
		(net "M_F_CPU0_SA_DQS_DN<1>")
	)
	(segment
		(start 328.411332 -232.004108)
		(end 328.419714 -232.008934)
		(width 0.09525)
		(layer "In11.Cu")
		(net "M_F_CPU0_SA_DQS_DN<1>")
	)
	(segment
		(start 331.23124 -232.004108)
		(end 331.239622 -232.008934)
		(width 0.09525)
		(layer "In11.Cu")
		(net "M_F_CPU0_SA_DQS_DN<1>")
	)
	(segment
		(start 299.086016 -209.662268)
		(end 300.692312 -209.662268)
		(width 0.16002)
		(layer "In11.Cu")
		(net "M_F_CPU0_SA_DQS_DN<1>")
	)
	(segment
		(start 324.458838 -229.81031)
		(end 324.896734 -229.81031)
		(width 0.09525)
		(layer "In11.Cu")
		(net "M_F_CPU0_SA_DQS_DN<1>")
	)
	(segment
		(start 278.06015 -209.662268)
		(end 278.910034 -210.512152)
		(width 0.16002)
		(layer "In11.Cu")
		(net "M_F_CPU0_SA_DQS_DN<1>")
	)
	(segment
		(start 316.869318 -222.30461)
		(end 323.682106 -229.117398)
		(width 0.16002)
		(layer "In11.Cu")
		(net "M_F_CPU0_SA_DQS_DN<1>")
	)
	(segment
		(start 276.084792 -210.03133)
		(end 276.453854 -209.662268)
		(width 0.16002)
		(layer "In11.Cu")
		(net "M_F_CPU0_SA_DQS_DN<1>")
	)
	(segment
		(start 314.030868 -217.010742)
		(end 313.70016 -217.34145)
		(width 0.16002)
		(layer "In11.Cu")
		(net "M_F_CPU0_SA_DQS_DN<1>")
	)
	(segment
		(start 307.277516 -210.03133)
		(end 312.657236 -215.41105)
		(width 0.16002)
		(layer "In11.Cu")
		(net "M_F_CPU0_SA_DQS_DN<1>")
	)
	(segment
		(start 332.121764 -231.981756)
		(end 332.145132 -232.068624)
		(width 0.09525)
		(layer "In11.Cu")
		(net "M_F_CPU0_SA_DQS_DN<1>")
	)
	(segment
		(start 315.97473 -219.61602)
		(end 316.305438 -219.285312)
		(width 0.16002)
		(layer "In11.Cu")
		(net "M_F_CPU0_SA_DQS_DN<1>")
	)
	(segment
		(start 302.792638 -210.527392)
		(end 303.316132 -210.527392)
		(width 0.16002)
		(layer "In11.Cu")
		(net "M_F_CPU0_SA_DQS_DN<1>")
	)
	(segment
		(start 280.103834 -210.512152)
		(end 281.364182 -210.512152)
		(width 0.16002)
		(layer "In11.Cu")
		(net "M_F_CPU0_SA_DQS_DN<1>")
	)
	(segment
		(start 315.073792 -218.715082)
		(end 315.073792 -219.191586)
		(width 0.16002)
		(layer "In11.Cu")
		(net "M_F_CPU0_SA_DQS_DN<1>")
	)
	(segment
		(start 312.750962 -216.868756)
		(end 313.227466 -216.868756)
		(width 0.16002)
		(layer "In11.Cu")
		(net "M_F_CPU0_SA_DQS_DN<1>")
	)
	(segment
		(start 324.896734 -229.81031)
		(end 325.234554 -230.14813)
		(width 0.09525)
		(layer "In11.Cu")
		(net "M_F_CPU0_SA_DQS_DN<1>")
	)
	(segment
		(start 272.071592 -210.66125)
		(end 272.22069 -210.512152)
		(width 0.16002)
		(layer "In11.Cu")
		(net "M_F_CPU0_SA_DQS_DN<1>")
	)
	(segment
		(start 316.531498 -219.285312)
		(end 316.869318 -219.623132)
		(width 0.16002)
		(layer "In11.Cu")
		(net "M_F_CPU0_SA_DQS_DN<1>")
	)
	(segment
		(start 315.4045 -218.384374)
		(end 315.073792 -218.715082)
		(width 0.16002)
		(layer "In11.Cu")
		(net "M_F_CPU0_SA_DQS_DN<1>")
	)
	(segment
		(start 291.1729 -210.03133)
		(end 291.541962 -209.662268)
		(width 0.16002)
		(layer "In11.Cu")
		(net "M_F_CPU0_SA_DQS_DN<1>")
	)
	(segment
		(start 270.640048 -210.66125)
		(end 270.756888 -210.77809)
		(width 0.16002)
		(layer "In11.Cu")
		(net "M_F_CPU0_SA_DQS_DN<1>")
	)
	(segment
		(start 276.453854 -209.662268)
		(end 278.06015 -209.662268)
		(width 0.16002)
		(layer "In11.Cu")
		(net "M_F_CPU0_SA_DQS_DN<1>")
	)
	(segment
		(start 314.601098 -218.242388)
		(end 314.931806 -217.91168)
		(width 0.16002)
		(layer "In11.Cu")
		(net "M_F_CPU0_SA_DQS_DN<1>")
	)
	(segment
		(start 269.648178 -210.935062)
		(end 269.92199 -210.66125)
		(width 0.16002)
		(layer "In11.Cu")
		(net "M_F_CPU0_SA_DQS_DN<1>")
	)
	(segment
		(start 298.716954 -210.03133)
		(end 299.086016 -209.662268)
		(width 0.16002)
		(layer "In11.Cu")
		(net "M_F_CPU0_SA_DQS_DN<1>")
	)
	(segment
		(start 279.986994 -210.628992)
		(end 280.103834 -210.512152)
		(width 0.16002)
		(layer "In11.Cu")
		(net "M_F_CPU0_SA_DQS_DN<1>")
	)
	(segment
		(start 323.69887 -229.134162)
		(end 323.78269 -229.134162)
		(width 0.09525)
		(layer "In11.Cu")
		(net "M_F_CPU0_SA_DQS_DN<1>")
	)
	(segment
		(start 304.602134 -211.245196)
		(end 305.816 -210.03133)
		(width 0.16002)
		(layer "In11.Cu")
		(net "M_F_CPU0_SA_DQS_DN<1>")
	)
	(segment
		(start 274.164806 -210.85683)
		(end 274.814538 -210.85683)
		(width 0.16002)
		(layer "In11.Cu")
		(net "M_F_CPU0_SA_DQS_DN<1>")
	)
	(segment
		(start 290.728146 -210.03133)
		(end 291.1729 -210.03133)
		(width 0.16002)
		(layer "In11.Cu")
		(net "M_F_CPU0_SA_DQS_DN<1>")
	)
	(segment
		(start 275.640038 -210.03133)
		(end 276.084792 -210.03133)
		(width 0.16002)
		(layer "In11.Cu")
		(net "M_F_CPU0_SA_DQS_DN<1>")
	)
	(segment
		(start 283.997908 -209.662268)
		(end 285.604204 -209.662268)
		(width 0.16002)
		(layer "In11.Cu")
		(net "M_F_CPU0_SA_DQS_DN<1>")
	)
	(segment
		(start 273.820128 -210.512152)
		(end 274.164806 -210.85683)
		(width 0.16002)
		(layer "In11.Cu")
		(net "M_F_CPU0_SA_DQS_DN<1>")
	)
	(segment
		(start 316.869318 -219.623132)
		(end 316.869318 -222.30461)
		(width 0.16002)
		(layer "In11.Cu")
		(net "M_F_CPU0_SA_DQS_DN<1>")
	)
	(segment
		(start 313.227466 -216.868756)
		(end 313.558174 -216.538048)
		(width 0.16002)
		(layer "In11.Cu")
		(net "M_F_CPU0_SA_DQS_DN<1>")
	)
	(segment
		(start 314.931806 -217.91168)
		(end 315.157866 -217.91168)
		(width 0.16002)
		(layer "In11.Cu")
		(net "M_F_CPU0_SA_DQS_DN<1>")
	)
	(segment
		(start 279.390094 -210.512152)
		(end 279.506934 -210.628992)
		(width 0.16002)
		(layer "In11.Cu")
		(net "M_F_CPU0_SA_DQS_DN<1>")
	)
	(segment
		(start 314.030868 -216.784682)
		(end 314.030868 -217.010742)
		(width 0.16002)
		(layer "In11.Cu")
		(net "M_F_CPU0_SA_DQS_DN<1>")
	)
	(segment
		(start 274.814538 -210.85683)
		(end 275.640038 -210.03133)
		(width 0.16002)
		(layer "In11.Cu")
		(net "M_F_CPU0_SA_DQS_DN<1>")
	)
	(segment
		(start 278.910034 -210.512152)
		(end 279.390094 -210.512152)
		(width 0.16002)
		(layer "In11.Cu")
		(net "M_F_CPU0_SA_DQS_DN<1>")
	)
	(segment
		(start 326.19061 -231.807512)
		(end 326.312276 -231.807512)
		(width 0.09525)
		(layer "In11.Cu")
		(net "M_F_CPU0_SA_DQS_DN<1>")
	)
	(segment
		(start 323.682106 -229.117398)
		(end 323.69887 -229.134162)
		(width 0.09525)
		(layer "In11.Cu")
		(net "M_F_CPU0_SA_DQS_DN<1>")
	)
	(segment
		(start 271.236948 -210.77809)
		(end 271.353788 -210.66125)
		(width 0.16002)
		(layer "In11.Cu")
		(net "M_F_CPU0_SA_DQS_DN<1>")
	)
	(segment
		(start 315.073792 -219.191586)
		(end 315.498226 -219.61602)
		(width 0.16002)
		(layer "In11.Cu")
		(net "M_F_CPU0_SA_DQS_DN<1>")
	)
	(segment
		(start 315.498226 -219.61602)
		(end 315.97473 -219.61602)
		(width 0.16002)
		(layer "In11.Cu")
		(net "M_F_CPU0_SA_DQS_DN<1>")
	)
	(segment
		(start 300.692312 -209.662268)
		(end 301.886874 -210.85683)
		(width 0.16002)
		(layer "In11.Cu")
		(net "M_F_CPU0_SA_DQS_DN<1>")
	)
	(segment
		(start 326.312276 -231.807512)
		(end 326.42556 -231.920796)
		(width 0.09525)
		(layer "In11.Cu")
		(net "M_F_CPU0_SA_DQS_DN<1>")
	)
	(segment
		(start 270.756888 -210.77809)
		(end 271.236948 -210.77809)
		(width 0.16002)
		(layer "In11.Cu")
		(net "M_F_CPU0_SA_DQS_DN<1>")
	)
	(segment
		(start 327.480422 -232.008934)
		(end 327.498456 -232.019348)
		(width 0.09525)
		(layer "In11.Cu")
		(net "M_F_CPU0_SA_DQS_DN<1>")
	)
	(segment
		(start 271.353788 -210.66125)
		(end 272.071592 -210.66125)
		(width 0.16002)
		(layer "In11.Cu")
		(net "M_F_CPU0_SA_DQS_DN<1>")
	)
	(segment
		(start 332.145132 -232.068624)
		(end 331.991208 -232.334054)
		(width 0.09525)
		(layer "In11.Cu")
		(net "M_F_CPU0_SA_DQS_DN<1>")
	)
	(segment
		(start 288.908236 -210.512152)
		(end 289.252914 -210.85683)
		(width 0.16002)
		(layer "In11.Cu")
		(net "M_F_CPU0_SA_DQS_DN<1>")
	)
	(segment
		(start 312.326528 -215.967818)
		(end 312.326528 -216.444322)
		(width 0.16002)
		(layer "In11.Cu")
		(net "M_F_CPU0_SA_DQS_DN<1>")
	)
	(segment
		(start 305.816 -210.03133)
		(end 307.277516 -210.03133)
		(width 0.16002)
		(layer "In11.Cu")
		(net "M_F_CPU0_SA_DQS_DN<1>")
	)
	(segment
		(start 313.558174 -216.538048)
		(end 313.784234 -216.538048)
		(width 0.16002)
		(layer "In11.Cu")
		(net "M_F_CPU0_SA_DQS_DN<1>")
	)
	(segment
		(start 314.124594 -218.242388)
		(end 314.601098 -218.242388)
		(width 0.16002)
		(layer "In11.Cu")
		(net "M_F_CPU0_SA_DQS_DN<1>")
	)
	(segment
		(start 313.70016 -217.34145)
		(end 313.70016 -217.817954)
		(width 0.16002)
		(layer "In11.Cu")
		(net "M_F_CPU0_SA_DQS_DN<1>")
	)
	(segment
		(start 327.085706 -232.019348)
		(end 327.10374 -232.008934)
		(width 0.09525)
		(layer "In11.Cu")
		(net "M_F_CPU0_SA_DQS_DN<1>")
	)
	(segment
		(start 303.316132 -210.527392)
		(end 304.033936 -211.245196)
		(width 0.16002)
		(layer "In11.Cu")
		(net "M_F_CPU0_SA_DQS_DN<1>")
	)
	(segment
		(start 289.252914 -210.85683)
		(end 289.902646 -210.85683)
		(width 0.16002)
		(layer "In11.Cu")
		(net "M_F_CPU0_SA_DQS_DN<1>")
	)
	(segment
		(start 296.45229 -210.512152)
		(end 296.796968 -210.85683)
		(width 0.16002)
		(layer "In11.Cu")
		(net "M_F_CPU0_SA_DQS_DN<1>")
	)
	(segment
		(start 286.454088 -210.512152)
		(end 288.908236 -210.512152)
		(width 0.16002)
		(layer "In11.Cu")
		(net "M_F_CPU0_SA_DQS_DN<1>")
	)
	(segment
		(start 313.784234 -216.538048)
		(end 314.030868 -216.784682)
		(width 0.16002)
		(layer "In11.Cu")
		(net "M_F_CPU0_SA_DQS_DN<1>")
	)
	(segment
		(start 312.657236 -215.63711)
		(end 312.326528 -215.967818)
		(width 0.16002)
		(layer "In11.Cu")
		(net "M_F_CPU0_SA_DQS_DN<1>")
	)
	(segment
		(start 293.148258 -209.662268)
		(end 293.998142 -210.512152)
		(width 0.16002)
		(layer "In11.Cu")
		(net "M_F_CPU0_SA_DQS_DN<1>")
	)
	(segment
		(start 327.47204 -232.004108)
		(end 327.480422 -232.008934)
		(width 0.09525)
		(layer "In11.Cu")
		(net "M_F_CPU0_SA_DQS_DN<1>")
	)
	(segment
		(start 282.358592 -210.85683)
		(end 283.184092 -210.03133)
		(width 0.16002)
		(layer "In11.Cu")
		(net "M_F_CPU0_SA_DQS_DN<1>")
	)
	(segment
		(start 312.657236 -215.41105)
		(end 312.657236 -215.63711)
		(width 0.16002)
		(layer "In11.Cu")
		(net "M_F_CPU0_SA_DQS_DN<1>")
	)
	(segment
		(start 301.886874 -210.85683)
		(end 302.4632 -210.85683)
		(width 0.16002)
		(layer "In11.Cu")
		(net "M_F_CPU0_SA_DQS_DN<1>")
	)
	(segment
		(start 315.157866 -217.91168)
		(end 315.4045 -218.158314)
		(width 0.16002)
		(layer "In11.Cu")
		(net "M_F_CPU0_SA_DQS_DN<1>")
	)
	(segment
		(start 313.70016 -217.817954)
		(end 314.124594 -218.242388)
		(width 0.16002)
		(layer "In11.Cu")
		(net "M_F_CPU0_SA_DQS_DN<1>")
	)
	(segment
		(start 304.033936 -211.245196)
		(end 304.602134 -211.245196)
		(width 0.16002)
		(layer "In11.Cu")
		(net "M_F_CPU0_SA_DQS_DN<1>")
	)
	(segment
		(start 279.506934 -210.628992)
		(end 279.986994 -210.628992)
		(width 0.16002)
		(layer "In11.Cu")
		(net "M_F_CPU0_SA_DQS_DN<1>")
	)
	(segment
		(start 283.628846 -210.03133)
		(end 283.997908 -209.662268)
		(width 0.16002)
		(layer "In11.Cu")
		(net "M_F_CPU0_SA_DQS_DN<1>")
	)
	(segment
		(start 281.364182 -210.512152)
		(end 281.70886 -210.85683)
		(width 0.16002)
		(layer "In11.Cu")
		(net "M_F_CPU0_SA_DQS_DN<1>")
	)
	(segment
		(start 293.998142 -210.512152)
		(end 296.45229 -210.512152)
		(width 0.16002)
		(layer "In11.Cu")
		(net "M_F_CPU0_SA_DQS_DN<1>")
	)
	(segment
		(start 281.70886 -210.85683)
		(end 282.358592 -210.85683)
		(width 0.16002)
		(layer "In11.Cu")
		(net "M_F_CPU0_SA_DQS_DN<1>")
	)
	(segment
		(start 315.4045 -218.158314)
		(end 315.4045 -218.384374)
		(width 0.16002)
		(layer "In11.Cu")
		(net "M_F_CPU0_SA_DQS_DN<1>")
	)
	(segment
		(start 328.982578 -232.008934)
		(end 328.99096 -232.004108)
		(width 0.09525)
		(layer "In11.Cu")
		(net "M_F_CPU0_SA_DQS_DN<1>")
	)
	(segment
		(start 297.4467 -210.85683)
		(end 298.2722 -210.03133)
		(width 0.16002)
		(layer "In11.Cu")
		(net "M_F_CPU0_SA_DQS_DN<1>")
	)
	(segment
		(start 316.305438 -219.285312)
		(end 316.531498 -219.285312)
		(width 0.16002)
		(layer "In11.Cu")
		(net "M_F_CPU0_SA_DQS_DN<1>")
	)
	(segment
		(start 302.4632 -210.85683)
		(end 302.792638 -210.527392)
		(width 0.16002)
		(layer "In11.Cu")
		(net "M_F_CPU0_SA_DQS_DN<1>")
	)
	(segment
		(start 325.234554 -230.851456)
		(end 326.19061 -231.807512)
		(width 0.09525)
		(layer "In11.Cu")
		(net "M_F_CPU0_SA_DQS_DN<1>")
	)
	(segment
		(start 298.2722 -210.03133)
		(end 298.716954 -210.03133)
		(width 0.16002)
		(layer "In11.Cu")
		(net "M_F_CPU0_SA_DQS_DN<1>")
	)
	(segment
		(start 285.604204 -209.662268)
		(end 286.454088 -210.512152)
		(width 0.16002)
		(layer "In11.Cu")
		(net "M_F_CPU0_SA_DQS_DN<1>")
	)
	(arc
		(start 329.922632 -232.008934)
		(mid 330.1111 -231.958257)
		(end 330.299568 -232.008934)
		(width 0.09525)
		(layer "In11.Cu")
		(net "M_F_CPU0_SA_DQS_DN<1>")
	)
	(arc
		(start 328.042524 -232.008934)
		(mid 328.226299 -231.958162)
		(end 328.411332 -232.004108)
		(width 0.09525)
		(layer "In11.Cu")
		(net "M_F_CPU0_SA_DQS_DN<1>")
	)
	(arc
		(start 330.299568 -232.008934)
		(mid 330.581 -232.084689)
		(end 330.862432 -232.008934)
		(width 0.09525)
		(layer "In11.Cu")
		(net "M_F_CPU0_SA_DQS_DN<1>")
	)
	(arc
		(start 328.419714 -232.008934)
		(mid 328.701146 -232.084689)
		(end 328.982578 -232.008934)
		(width 0.09525)
		(layer "In11.Cu")
		(net "M_F_CPU0_SA_DQS_DN<1>")
	)
	(arc
		(start 329.359768 -232.008934)
		(mid 329.6412 -232.084689)
		(end 329.922632 -232.008934)
		(width 0.09525)
		(layer "In11.Cu")
		(net "M_F_CPU0_SA_DQS_DN<1>")
	)
	(arc
		(start 331.802486 -232.008934)
		(mid 331.959084 -231.959645)
		(end 332.121764 -231.981756)
		(width 0.09525)
		(layer "In11.Cu")
		(net "M_F_CPU0_SA_DQS_DN<1>")
	)
	(arc
		(start 326.42556 -231.920796)
		(mid 326.739393 -232.078974)
		(end 327.085706 -232.019348)
		(width 0.09525)
		(layer "In11.Cu")
		(net "M_F_CPU0_SA_DQS_DN<1>")
	)
	(arc
		(start 330.862432 -232.008934)
		(mid 331.046207 -231.958162)
		(end 331.23124 -232.004108)
		(width 0.09525)
		(layer "In11.Cu")
		(net "M_F_CPU0_SA_DQS_DN<1>")
	)
	(arc
		(start 328.99096 -232.004108)
		(mid 329.175992 -231.958194)
		(end 329.359768 -232.008934)
		(width 0.09525)
		(layer "In11.Cu")
		(net "M_F_CPU0_SA_DQS_DN<1>")
	)
	(arc
		(start 327.10374 -232.008934)
		(mid 327.287261 -231.95829)
		(end 327.47204 -232.004108)
		(width 0.09525)
		(layer "In11.Cu")
		(net "M_F_CPU0_SA_DQS_DN<1>")
	)
	(arc
		(start 331.239622 -232.008934)
		(mid 331.521054 -232.084689)
		(end 331.802486 -232.008934)
		(width 0.09525)
		(layer "In11.Cu")
		(net "M_F_CPU0_SA_DQS_DN<1>")
	)
	(arc
		(start 327.498456 -232.019348)
		(mid 327.771836 -232.084569)
		(end 328.042524 -232.008934)
		(width 0.09525)
		(layer "In11.Cu")
		(net "M_F_CPU0_SA_DQS_DN<1>")
	)
	(segment
		(start 332.45806 -227.74021)
		(end 331.991208 -227.474272)
		(width 0.12954)
		(layer "F.Cu")
		(net "M_F_CPU0_SA_DQS_DN<0>")
	)
	(segment
		(start 326.501506 -225.507042)
		(end 326.574404 -225.549206)
		(width 0.09525)
		(layer "In11.Cu")
		(net "M_F_CPU0_SA_DQS_DN<0>")
	)
	(segment
		(start 326.046084 -223.084644)
		(end 326.077072 -223.102932)
		(width 0.09525)
		(layer "In11.Cu")
		(net "M_F_CPU0_SA_DQS_DN<0>")
	)
	(segment
		(start 326.258682 -225.038666)
		(end 326.258682 -225.044254)
		(width 0.09525)
		(layer "In11.Cu")
		(net "M_F_CPU0_SA_DQS_DN<0>")
	)
	(segment
		(start 276.453854 -200.312274)
		(end 278.06015 -200.312274)
		(width 0.16002)
		(layer "In11.Cu")
		(net "M_F_CPU0_SA_DQS_DN<0>")
	)
	(segment
		(start 270.99895 -201.428096)
		(end 271.11579 -201.311256)
		(width 0.16002)
		(layer "In11.Cu")
		(net "M_F_CPU0_SA_DQS_DN<0>")
	)
	(segment
		(start 326.07758 -223.10344)
		(end 326.078088 -223.103694)
		(width 0.09525)
		(layer "In11.Cu")
		(net "M_F_CPU0_SA_DQS_DN<0>")
	)
	(segment
		(start 315.484256 -209.85607)
		(end 315.96076 -209.85607)
		(width 0.16002)
		(layer "In11.Cu")
		(net "M_F_CPU0_SA_DQS_DN<0>")
	)
	(segment
		(start 312.736992 -207.108806)
		(end 313.213496 -207.108806)
		(width 0.16002)
		(layer "In11.Cu")
		(net "M_F_CPU0_SA_DQS_DN<0>")
	)
	(segment
		(start 280.103834 -201.162158)
		(end 281.364182 -201.162158)
		(width 0.16002)
		(layer "In11.Cu")
		(net "M_F_CPU0_SA_DQS_DN<0>")
	)
	(segment
		(start 327.480422 -227.149152)
		(end 327.498456 -227.159566)
		(width 0.09525)
		(layer "In11.Cu")
		(net "M_F_CPU0_SA_DQS_DN<0>")
	)
	(segment
		(start 296.45229 -201.162158)
		(end 296.796968 -201.506836)
		(width 0.16002)
		(layer "In11.Cu")
		(net "M_F_CPU0_SA_DQS_DN<0>")
	)
	(segment
		(start 289.252914 -201.506836)
		(end 289.902646 -201.506836)
		(width 0.16002)
		(layer "In11.Cu")
		(net "M_F_CPU0_SA_DQS_DN<0>")
	)
	(segment
		(start 275.640038 -200.681336)
		(end 276.084792 -200.681336)
		(width 0.16002)
		(layer "In11.Cu")
		(net "M_F_CPU0_SA_DQS_DN<0>")
	)
	(segment
		(start 315.402214 -208.614264)
		(end 315.060584 -208.95564)
		(width 0.16002)
		(layer "In11.Cu")
		(net "M_F_CPU0_SA_DQS_DN<0>")
	)
	(segment
		(start 283.997908 -200.312274)
		(end 285.604204 -200.312274)
		(width 0.16002)
		(layer "In11.Cu")
		(net "M_F_CPU0_SA_DQS_DN<0>")
	)
	(segment
		(start 315.402214 -208.388458)
		(end 315.402214 -208.614264)
		(width 0.16002)
		(layer "In11.Cu")
		(net "M_F_CPU0_SA_DQS_DN<0>")
	)
	(segment
		(start 272.22069 -201.162158)
		(end 273.820128 -201.162158)
		(width 0.16002)
		(layer "In11.Cu")
		(net "M_F_CPU0_SA_DQS_DN<0>")
	)
	(segment
		(start 328.982578 -227.149152)
		(end 328.99096 -227.144326)
		(width 0.09525)
		(layer "In11.Cu")
		(net "M_F_CPU0_SA_DQS_DN<0>")
	)
	(segment
		(start 316.775846 -209.76209)
		(end 316.775846 -209.987896)
		(width 0.16002)
		(layer "In11.Cu")
		(net "M_F_CPU0_SA_DQS_DN<0>")
	)
	(segment
		(start 315.060584 -208.95564)
		(end 315.060584 -209.432398)
		(width 0.16002)
		(layer "In11.Cu")
		(net "M_F_CPU0_SA_DQS_DN<0>")
	)
	(segment
		(start 315.060584 -209.432398)
		(end 315.484256 -209.85607)
		(width 0.16002)
		(layer "In11.Cu")
		(net "M_F_CPU0_SA_DQS_DN<0>")
	)
	(segment
		(start 286.454088 -201.162158)
		(end 288.908236 -201.162158)
		(width 0.16002)
		(layer "In11.Cu")
		(net "M_F_CPU0_SA_DQS_DN<0>")
	)
	(segment
		(start 316.52845 -209.514694)
		(end 316.775846 -209.76209)
		(width 0.16002)
		(layer "In11.Cu")
		(net "M_F_CPU0_SA_DQS_DN<0>")
	)
	(segment
		(start 279.506934 -201.278998)
		(end 279.986994 -201.278998)
		(width 0.16002)
		(layer "In11.Cu")
		(net "M_F_CPU0_SA_DQS_DN<0>")
	)
	(segment
		(start 270.51889 -201.428096)
		(end 270.99895 -201.428096)
		(width 0.16002)
		(layer "In11.Cu")
		(net "M_F_CPU0_SA_DQS_DN<0>")
	)
	(segment
		(start 325.546212 -222.254826)
		(end 325.630032 -222.254826)
		(width 0.09525)
		(layer "In11.Cu")
		(net "M_F_CPU0_SA_DQS_DN<0>")
	)
	(segment
		(start 283.628846 -200.681336)
		(end 283.997908 -200.312274)
		(width 0.16002)
		(layer "In11.Cu")
		(net "M_F_CPU0_SA_DQS_DN<0>")
	)
	(segment
		(start 314.587128 -208.482438)
		(end 314.928758 -208.141062)
		(width 0.16002)
		(layer "In11.Cu")
		(net "M_F_CPU0_SA_DQS_DN<0>")
	)
	(segment
		(start 282.358592 -201.506836)
		(end 283.184092 -200.681336)
		(width 0.16002)
		(layer "In11.Cu")
		(net "M_F_CPU0_SA_DQS_DN<0>")
	)
	(segment
		(start 273.820128 -201.162158)
		(end 274.164806 -201.506836)
		(width 0.16002)
		(layer "In11.Cu")
		(net "M_F_CPU0_SA_DQS_DN<0>")
	)
	(segment
		(start 325.78929 -222.414084)
		(end 325.78929 -222.63608)
		(width 0.09525)
		(layer "In11.Cu")
		(net "M_F_CPU0_SA_DQS_DN<0>")
	)
	(segment
		(start 327.479914 -227.149152)
		(end 327.480422 -227.149152)
		(width 0.09525)
		(layer "In11.Cu")
		(net "M_F_CPU0_SA_DQS_DN<0>")
	)
	(segment
		(start 272.071592 -201.311256)
		(end 272.22069 -201.162158)
		(width 0.16002)
		(layer "In11.Cu")
		(net "M_F_CPU0_SA_DQS_DN<0>")
	)
	(segment
		(start 326.504554 -223.888554)
		(end 326.506586 -223.889824)
		(width 0.09525)
		(layer "In11.Cu")
		(net "M_F_CPU0_SA_DQS_DN<0>")
	)
	(segment
		(start 332.121764 -227.121974)
		(end 332.145132 -227.208842)
		(width 0.09525)
		(layer "In11.Cu")
		(net "M_F_CPU0_SA_DQS_DN<0>")
	)
	(segment
		(start 316.434216 -210.80603)
		(end 322.683378 -217.055192)
		(width 0.16002)
		(layer "In11.Cu")
		(net "M_F_CPU0_SA_DQS_DN<0>")
	)
	(segment
		(start 293.998142 -201.162158)
		(end 296.45229 -201.162158)
		(width 0.16002)
		(layer "In11.Cu")
		(net "M_F_CPU0_SA_DQS_DN<0>")
	)
	(segment
		(start 307.770022 -200.681336)
		(end 312.279538 -205.190852)
		(width 0.16002)
		(layer "In11.Cu")
		(net "M_F_CPU0_SA_DQS_DN<0>")
	)
	(segment
		(start 315.96076 -209.85607)
		(end 316.30239 -209.514694)
		(width 0.16002)
		(layer "In11.Cu")
		(net "M_F_CPU0_SA_DQS_DN<0>")
	)
	(segment
		(start 291.541962 -200.312274)
		(end 293.148258 -200.312274)
		(width 0.16002)
		(layer "In11.Cu")
		(net "M_F_CPU0_SA_DQS_DN<0>")
	)
	(segment
		(start 316.434216 -210.329272)
		(end 316.434216 -210.80603)
		(width 0.16002)
		(layer "In11.Cu")
		(net "M_F_CPU0_SA_DQS_DN<0>")
	)
	(segment
		(start 299.086016 -200.312274)
		(end 300.692312 -200.312274)
		(width 0.16002)
		(layer "In11.Cu")
		(net "M_F_CPU0_SA_DQS_DN<0>")
	)
	(segment
		(start 288.908236 -201.162158)
		(end 289.252914 -201.506836)
		(width 0.16002)
		(layer "In11.Cu")
		(net "M_F_CPU0_SA_DQS_DN<0>")
	)
	(segment
		(start 283.184092 -200.681336)
		(end 283.628846 -200.681336)
		(width 0.16002)
		(layer "In11.Cu")
		(net "M_F_CPU0_SA_DQS_DN<0>")
	)
	(segment
		(start 274.164806 -201.506836)
		(end 274.814538 -201.506836)
		(width 0.16002)
		(layer "In11.Cu")
		(net "M_F_CPU0_SA_DQS_DN<0>")
	)
	(segment
		(start 316.30239 -209.514694)
		(end 316.52845 -209.514694)
		(width 0.16002)
		(layer "In11.Cu")
		(net "M_F_CPU0_SA_DQS_DN<0>")
	)
	(segment
		(start 269.648178 -201.585068)
		(end 269.92199 -201.311256)
		(width 0.16002)
		(layer "In11.Cu")
		(net "M_F_CPU0_SA_DQS_DN<0>")
	)
	(segment
		(start 322.683378 -219.391992)
		(end 325.529448 -222.238062)
		(width 0.16002)
		(layer "In11.Cu")
		(net "M_F_CPU0_SA_DQS_DN<0>")
	)
	(segment
		(start 332.145132 -227.208842)
		(end 331.991208 -227.474272)
		(width 0.09525)
		(layer "In11.Cu")
		(net "M_F_CPU0_SA_DQS_DN<0>")
	)
	(segment
		(start 293.148258 -200.312274)
		(end 293.998142 -201.162158)
		(width 0.16002)
		(layer "In11.Cu")
		(net "M_F_CPU0_SA_DQS_DN<0>")
	)
	(segment
		(start 313.213496 -207.108806)
		(end 313.555126 -206.76743)
		(width 0.16002)
		(layer "In11.Cu")
		(net "M_F_CPU0_SA_DQS_DN<0>")
	)
	(segment
		(start 315.154818 -208.141062)
		(end 315.402214 -208.388458)
		(width 0.16002)
		(layer "In11.Cu")
		(net "M_F_CPU0_SA_DQS_DN<0>")
	)
	(segment
		(start 316.775846 -209.987896)
		(end 316.434216 -210.329272)
		(width 0.16002)
		(layer "In11.Cu")
		(net "M_F_CPU0_SA_DQS_DN<0>")
	)
	(segment
		(start 291.1729 -200.681336)
		(end 291.541962 -200.312274)
		(width 0.16002)
		(layer "In11.Cu")
		(net "M_F_CPU0_SA_DQS_DN<0>")
	)
	(segment
		(start 327.443338 -227.127816)
		(end 327.479914 -227.149152)
		(width 0.09525)
		(layer "In11.Cu")
		(net "M_F_CPU0_SA_DQS_DN<0>")
	)
	(segment
		(start 326.093582 -223.112838)
		(end 326.101456 -223.11741)
		(width 0.09525)
		(layer "In11.Cu")
		(net "M_F_CPU0_SA_DQS_DN<0>")
	)
	(segment
		(start 278.06015 -200.312274)
		(end 278.910034 -201.162158)
		(width 0.16002)
		(layer "In11.Cu")
		(net "M_F_CPU0_SA_DQS_DN<0>")
	)
	(segment
		(start 312.279538 -205.190852)
		(end 312.279538 -206.651352)
		(width 0.16002)
		(layer "In11.Cu")
		(net "M_F_CPU0_SA_DQS_DN<0>")
	)
	(segment
		(start 314.110624 -208.482438)
		(end 314.587128 -208.482438)
		(width 0.16002)
		(layer "In11.Cu")
		(net "M_F_CPU0_SA_DQS_DN<0>")
	)
	(segment
		(start 279.390094 -201.162158)
		(end 279.506934 -201.278998)
		(width 0.16002)
		(layer "In11.Cu")
		(net "M_F_CPU0_SA_DQS_DN<0>")
	)
	(segment
		(start 276.084792 -200.681336)
		(end 276.453854 -200.312274)
		(width 0.16002)
		(layer "In11.Cu")
		(net "M_F_CPU0_SA_DQS_DN<0>")
	)
	(segment
		(start 325.630032 -222.254826)
		(end 325.78929 -222.414084)
		(width 0.09525)
		(layer "In11.Cu")
		(net "M_F_CPU0_SA_DQS_DN<0>")
	)
	(segment
		(start 281.364182 -201.162158)
		(end 281.70886 -201.506836)
		(width 0.16002)
		(layer "In11.Cu")
		(net "M_F_CPU0_SA_DQS_DN<0>")
	)
	(segment
		(start 298.2722 -200.681336)
		(end 298.716954 -200.681336)
		(width 0.16002)
		(layer "In11.Cu")
		(net "M_F_CPU0_SA_DQS_DN<0>")
	)
	(segment
		(start 326.539606 -223.909128)
		(end 326.574404 -223.929194)
		(width 0.09525)
		(layer "In11.Cu")
		(net "M_F_CPU0_SA_DQS_DN<0>")
	)
	(segment
		(start 271.11579 -201.311256)
		(end 272.071592 -201.311256)
		(width 0.16002)
		(layer "In11.Cu")
		(net "M_F_CPU0_SA_DQS_DN<0>")
	)
	(segment
		(start 279.986994 -201.278998)
		(end 280.103834 -201.162158)
		(width 0.16002)
		(layer "In11.Cu")
		(net "M_F_CPU0_SA_DQS_DN<0>")
	)
	(segment
		(start 325.529448 -222.238062)
		(end 325.546212 -222.254826)
		(width 0.09525)
		(layer "In11.Cu")
		(net "M_F_CPU0_SA_DQS_DN<0>")
	)
	(segment
		(start 304.9905 -201.506836)
		(end 305.816 -200.681336)
		(width 0.16002)
		(layer "In11.Cu")
		(net "M_F_CPU0_SA_DQS_DN<0>")
	)
	(segment
		(start 313.686952 -207.582008)
		(end 313.686952 -208.058766)
		(width 0.16002)
		(layer "In11.Cu")
		(net "M_F_CPU0_SA_DQS_DN<0>")
	)
	(segment
		(start 298.716954 -200.681336)
		(end 299.086016 -200.312274)
		(width 0.16002)
		(layer "In11.Cu")
		(net "M_F_CPU0_SA_DQS_DN<0>")
	)
	(segment
		(start 314.028582 -207.240632)
		(end 313.686952 -207.582008)
		(width 0.16002)
		(layer "In11.Cu")
		(net "M_F_CPU0_SA_DQS_DN<0>")
	)
	(segment
		(start 328.411332 -227.144326)
		(end 328.419714 -227.149152)
		(width 0.09525)
		(layer "In11.Cu")
		(net "M_F_CPU0_SA_DQS_DN<0>")
	)
	(segment
		(start 274.814538 -201.506836)
		(end 275.640038 -200.681336)
		(width 0.16002)
		(layer "In11.Cu")
		(net "M_F_CPU0_SA_DQS_DN<0>")
	)
	(segment
		(start 313.686952 -208.058766)
		(end 314.110624 -208.482438)
		(width 0.16002)
		(layer "In11.Cu")
		(net "M_F_CPU0_SA_DQS_DN<0>")
	)
	(segment
		(start 301.886874 -201.506836)
		(end 304.9905 -201.506836)
		(width 0.16002)
		(layer "In11.Cu")
		(net "M_F_CPU0_SA_DQS_DN<0>")
	)
	(segment
		(start 313.555126 -206.76743)
		(end 313.781186 -206.76743)
		(width 0.16002)
		(layer "In11.Cu")
		(net "M_F_CPU0_SA_DQS_DN<0>")
	)
	(segment
		(start 327.010776 -226.339654)
		(end 327.04151 -226.357434)
		(width 0.09525)
		(layer "In11.Cu")
		(net "M_F_CPU0_SA_DQS_DN<0>")
	)
	(segment
		(start 289.902646 -201.506836)
		(end 290.728146 -200.681336)
		(width 0.16002)
		(layer "In11.Cu")
		(net "M_F_CPU0_SA_DQS_DN<0>")
	)
	(segment
		(start 312.279538 -206.651352)
		(end 312.736992 -207.108806)
		(width 0.16002)
		(layer "In11.Cu")
		(net "M_F_CPU0_SA_DQS_DN<0>")
	)
	(segment
		(start 296.796968 -201.506836)
		(end 297.4467 -201.506836)
		(width 0.16002)
		(layer "In11.Cu")
		(net "M_F_CPU0_SA_DQS_DN<0>")
	)
	(segment
		(start 269.92199 -201.311256)
		(end 270.40205 -201.311256)
		(width 0.16002)
		(layer "In11.Cu")
		(net "M_F_CPU0_SA_DQS_DN<0>")
	)
	(segment
		(start 300.692312 -200.312274)
		(end 301.886874 -201.506836)
		(width 0.16002)
		(layer "In11.Cu")
		(net "M_F_CPU0_SA_DQS_DN<0>")
	)
	(segment
		(start 331.23124 -227.144326)
		(end 331.239622 -227.149152)
		(width 0.09525)
		(layer "In11.Cu")
		(net "M_F_CPU0_SA_DQS_DN<0>")
	)
	(segment
		(start 290.728146 -200.681336)
		(end 291.1729 -200.681336)
		(width 0.16002)
		(layer "In11.Cu")
		(net "M_F_CPU0_SA_DQS_DN<0>")
	)
	(segment
		(start 326.078088 -223.103694)
		(end 326.093582 -223.112838)
		(width 0.09525)
		(layer "In11.Cu")
		(net "M_F_CPU0_SA_DQS_DN<0>")
	)
	(segment
		(start 326.077072 -223.102932)
		(end 326.07758 -223.103186)
		(width 0.09525)
		(layer "In11.Cu")
		(net "M_F_CPU0_SA_DQS_DN<0>")
	)
	(segment
		(start 285.604204 -200.312274)
		(end 286.454088 -201.162158)
		(width 0.16002)
		(layer "In11.Cu")
		(net "M_F_CPU0_SA_DQS_DN<0>")
	)
	(segment
		(start 313.781186 -206.76743)
		(end 314.028582 -207.014826)
		(width 0.16002)
		(layer "In11.Cu")
		(net "M_F_CPU0_SA_DQS_DN<0>")
	)
	(segment
		(start 326.506586 -223.889824)
		(end 326.539606 -223.909128)
		(width 0.09525)
		(layer "In11.Cu")
		(net "M_F_CPU0_SA_DQS_DN<0>")
	)
	(segment
		(start 314.928758 -208.141062)
		(end 315.154818 -208.141062)
		(width 0.16002)
		(layer "In11.Cu")
		(net "M_F_CPU0_SA_DQS_DN<0>")
	)
	(segment
		(start 278.910034 -201.162158)
		(end 279.390094 -201.162158)
		(width 0.16002)
		(layer "In11.Cu")
		(net "M_F_CPU0_SA_DQS_DN<0>")
	)
	(segment
		(start 327.010014 -226.339146)
		(end 327.010776 -226.339654)
		(width 0.09525)
		(layer "In11.Cu")
		(net "M_F_CPU0_SA_DQS_DN<0>")
	)
	(segment
		(start 281.70886 -201.506836)
		(end 282.358592 -201.506836)
		(width 0.16002)
		(layer "In11.Cu")
		(net "M_F_CPU0_SA_DQS_DN<0>")
	)
	(segment
		(start 326.574404 -224.539302)
		(end 326.539606 -224.559368)
		(width 0.09525)
		(layer "In11.Cu")
		(net "M_F_CPU0_SA_DQS_DN<0>")
	)
	(segment
		(start 297.4467 -201.506836)
		(end 298.2722 -200.681336)
		(width 0.16002)
		(layer "In11.Cu")
		(net "M_F_CPU0_SA_DQS_DN<0>")
	)
	(segment
		(start 305.816 -200.681336)
		(end 307.770022 -200.681336)
		(width 0.16002)
		(layer "In11.Cu")
		(net "M_F_CPU0_SA_DQS_DN<0>")
	)
	(segment
		(start 270.40205 -201.311256)
		(end 270.51889 -201.428096)
		(width 0.16002)
		(layer "In11.Cu")
		(net "M_F_CPU0_SA_DQS_DN<0>")
	)
	(segment
		(start 326.424544 -224.64776)
		(end 326.41794 -224.654364)
		(width 0.09525)
		(layer "In11.Cu")
		(net "M_F_CPU0_SA_DQS_DN<0>")
	)
	(segment
		(start 314.028582 -207.014826)
		(end 314.028582 -207.240632)
		(width 0.16002)
		(layer "In11.Cu")
		(net "M_F_CPU0_SA_DQS_DN<0>")
	)
	(segment
		(start 322.683378 -217.055192)
		(end 322.683378 -219.391992)
		(width 0.16002)
		(layer "In11.Cu")
		(net "M_F_CPU0_SA_DQS_DN<0>")
	)
	(segment
		(start 326.971914 -226.317048)
		(end 327.010014 -226.339146)
		(width 0.09525)
		(layer "In11.Cu")
		(net "M_F_CPU0_SA_DQS_DN<0>")
	)
	(segment
		(start 326.07758 -223.103186)
		(end 326.07758 -223.10344)
		(width 0.09525)
		(layer "In11.Cu")
		(net "M_F_CPU0_SA_DQS_DN<0>")
	)
	(arc
		(start 326.258682 -225.044254)
		(mid 326.323079 -225.30556)
		(end 326.501506 -225.507042)
		(width 0.09525)
		(layer "In11.Cu")
		(net "M_F_CPU0_SA_DQS_DN<0>")
	)
	(arc
		(start 327.04151 -226.357434)
		(mid 327.157308 -226.491828)
		(end 327.19899 -226.664266)
		(width 0.09525)
		(layer "In11.Cu")
		(net "M_F_CPU0_SA_DQS_DN<0>")
	)
	(arc
		(start 326.41794 -224.654364)
		(mid 326.300074 -224.830669)
		(end 326.258682 -225.038666)
		(width 0.09525)
		(layer "In11.Cu")
		(net "M_F_CPU0_SA_DQS_DN<0>")
	)
	(arc
		(start 331.239622 -227.149152)
		(mid 331.521054 -227.224907)
		(end 331.802486 -227.149152)
		(width 0.09525)
		(layer "In11.Cu")
		(net "M_F_CPU0_SA_DQS_DN<0>")
	)
	(arc
		(start 329.922632 -227.149152)
		(mid 330.1111 -227.098475)
		(end 330.299568 -227.149152)
		(width 0.09525)
		(layer "In11.Cu")
		(net "M_F_CPU0_SA_DQS_DN<0>")
	)
	(arc
		(start 326.574404 -225.549206)
		(mid 326.688189 -225.68325)
		(end 326.72909 -225.85426)
		(width 0.09525)
		(layer "In11.Cu")
		(net "M_F_CPU0_SA_DQS_DN<0>")
	)
	(arc
		(start 327.19899 -226.664266)
		(mid 327.263819 -226.926268)
		(end 327.443338 -227.127816)
		(width 0.09525)
		(layer "In11.Cu")
		(net "M_F_CPU0_SA_DQS_DN<0>")
	)
	(arc
		(start 326.72909 -225.85426)
		(mid 326.793487 -226.115566)
		(end 326.971914 -226.317048)
		(width 0.09525)
		(layer "In11.Cu")
		(net "M_F_CPU0_SA_DQS_DN<0>")
	)
	(arc
		(start 326.258936 -223.424242)
		(mid 326.324129 -223.686871)
		(end 326.504554 -223.888554)
		(width 0.09525)
		(layer "In11.Cu")
		(net "M_F_CPU0_SA_DQS_DN<0>")
	)
	(arc
		(start 326.539606 -224.559368)
		(mid 326.479202 -224.599824)
		(end 326.424544 -224.64776)
		(width 0.09525)
		(layer "In11.Cu")
		(net "M_F_CPU0_SA_DQS_DN<0>")
	)
	(arc
		(start 330.299568 -227.149152)
		(mid 330.581 -227.224907)
		(end 330.862432 -227.149152)
		(width 0.09525)
		(layer "In11.Cu")
		(net "M_F_CPU0_SA_DQS_DN<0>")
	)
	(arc
		(start 329.359768 -227.149152)
		(mid 329.6412 -227.224907)
		(end 329.922632 -227.149152)
		(width 0.09525)
		(layer "In11.Cu")
		(net "M_F_CPU0_SA_DQS_DN<0>")
	)
	(arc
		(start 328.99096 -227.144326)
		(mid 329.175992 -227.098412)
		(end 329.359768 -227.149152)
		(width 0.09525)
		(layer "In11.Cu")
		(net "M_F_CPU0_SA_DQS_DN<0>")
	)
	(arc
		(start 326.574404 -223.929194)
		(mid 326.729063 -224.234248)
		(end 326.574404 -224.539302)
		(width 0.09525)
		(layer "In11.Cu")
		(net "M_F_CPU0_SA_DQS_DN<0>")
	)
	(arc
		(start 330.862432 -227.149152)
		(mid 331.046207 -227.09838)
		(end 331.23124 -227.144326)
		(width 0.09525)
		(layer "In11.Cu")
		(net "M_F_CPU0_SA_DQS_DN<0>")
	)
	(arc
		(start 327.498456 -227.159566)
		(mid 327.771836 -227.224787)
		(end 328.042524 -227.149152)
		(width 0.09525)
		(layer "In11.Cu")
		(net "M_F_CPU0_SA_DQS_DN<0>")
	)
	(arc
		(start 325.78929 -222.63608)
		(mid 325.857975 -222.894543)
		(end 326.046084 -223.084644)
		(width 0.09525)
		(layer "In11.Cu")
		(net "M_F_CPU0_SA_DQS_DN<0>")
	)
	(arc
		(start 328.042524 -227.149152)
		(mid 328.226299 -227.09838)
		(end 328.411332 -227.144326)
		(width 0.09525)
		(layer "In11.Cu")
		(net "M_F_CPU0_SA_DQS_DN<0>")
	)
	(arc
		(start 328.419714 -227.149152)
		(mid 328.701146 -227.224907)
		(end 328.982578 -227.149152)
		(width 0.09525)
		(layer "In11.Cu")
		(net "M_F_CPU0_SA_DQS_DN<0>")
	)
	(arc
		(start 326.101456 -223.11741)
		(mid 326.217254 -223.251804)
		(end 326.258936 -223.424242)
		(width 0.09525)
		(layer "In11.Cu")
		(net "M_F_CPU0_SA_DQS_DN<0>")
	)
	(arc
		(start 331.802486 -227.149152)
		(mid 331.959084 -227.099863)
		(end 332.121764 -227.121974)
		(width 0.09525)
		(layer "In11.Cu")
		(net "M_F_CPU0_SA_DQS_DN<0>")
	)
	(segment
		(start 334.337914 -230.97998)
		(end 333.871062 -230.714296)
		(width 0.10668)
		(layer "F.Cu")
		(net "M_F_CPU0_SA_DQ<9>")
	)
	(segment
		(start 303.759362 -208.973166)
		(end 303.759362 -209.037682)
		(width 0.14478)
		(layer "In11.Cu")
		(net "M_F_CPU0_SA_DQ<9>")
	)
	(segment
		(start 281.604466 -209.20075)
		(end 281.767534 -209.037682)
		(width 0.14478)
		(layer "In11.Cu")
		(net "M_F_CPU0_SA_DQ<9>")
	)
	(segment
		(start 318.191134 -218.996006)
		(end 318.191134 -221.745302)
		(width 0.14478)
		(layer "In11.Cu")
		(net "M_F_CPU0_SA_DQ<9>")
	)
	(segment
		(start 332.744064 -231.036622)
		(end 332.752446 -231.041448)
		(width 0.0889)
		(layer "In11.Cu")
		(net "M_F_CPU0_SA_DQ<9>")
	)
	(segment
		(start 323.791834 -227.346002)
		(end 324.382384 -227.936552)
		(width 0.0889)
		(layer "In11.Cu")
		(net "M_F_CPU0_SA_DQ<9>")
	)
	(segment
		(start 276.296374 -208.342992)
		(end 276.545548 -208.342992)
		(width 0.14478)
		(layer "In11.Cu")
		(net "M_F_CPU0_SA_DQ<9>")
	)
	(segment
		(start 291.129466 -208.189322)
		(end 291.278056 -208.337912)
		(width 0.14478)
		(layer "In11.Cu")
		(net "M_F_CPU0_SA_DQ<9>")
	)
	(segment
		(start 289.243008 -208.973166)
		(end 289.406076 -208.810098)
		(width 0.14478)
		(layer "In11.Cu")
		(net "M_F_CPU0_SA_DQ<9>")
	)
	(segment
		(start 276.699218 -208.123282)
		(end 276.862286 -207.960214)
		(width 0.14478)
		(layer "In11.Cu")
		(net "M_F_CPU0_SA_DQ<9>")
	)
	(segment
		(start 291.68598 -208.189322)
		(end 291.68598 -208.123282)
		(width 0.14478)
		(layer "In11.Cu")
		(net "M_F_CPU0_SA_DQ<9>")
	)
	(segment
		(start 304.152808 -209.20075)
		(end 304.315876 -209.037682)
		(width 0.14478)
		(layer "In11.Cu")
		(net "M_F_CPU0_SA_DQ<9>")
	)
	(segment
		(start 297.389042 -208.810098)
		(end 298.238926 -207.960214)
		(width 0.14478)
		(layer "In11.Cu")
		(net "M_F_CPU0_SA_DQ<9>")
	)
	(segment
		(start 281.930602 -208.810098)
		(end 282.323286 -208.810098)
		(width 0.14478)
		(layer "In11.Cu")
		(net "M_F_CPU0_SA_DQ<9>")
	)
	(segment
		(start 303.365916 -208.810098)
		(end 303.596294 -208.810098)
		(width 0.14478)
		(layer "In11.Cu")
		(net "M_F_CPU0_SA_DQ<9>")
	)
	(segment
		(start 282.323286 -208.810098)
		(end 283.17317 -207.960214)
		(width 0.14478)
		(layer "In11.Cu")
		(net "M_F_CPU0_SA_DQ<9>")
	)
	(segment
		(start 289.883088 -208.810098)
		(end 290.732972 -207.960214)
		(width 0.14478)
		(layer "In11.Cu")
		(net "M_F_CPU0_SA_DQ<9>")
	)
	(segment
		(start 304.315876 -209.037682)
		(end 304.315876 -208.973166)
		(width 0.14478)
		(layer "In11.Cu")
		(net "M_F_CPU0_SA_DQ<9>")
	)
	(segment
		(start 304.315876 -208.973166)
		(end 304.478944 -208.810098)
		(width 0.14478)
		(layer "In11.Cu")
		(net "M_F_CPU0_SA_DQ<9>")
	)
	(segment
		(start 299.136054 -208.34477)
		(end 299.299122 -208.181702)
		(width 0.14478)
		(layer "In11.Cu")
		(net "M_F_CPU0_SA_DQ<9>")
	)
	(segment
		(start 272.112994 -209.18805)
		(end 272.276062 -209.024982)
		(width 0.14478)
		(layer "In11.Cu")
		(net "M_F_CPU0_SA_DQ<9>")
	)
	(segment
		(start 332.16977 -231.041448)
		(end 332.178152 -231.036622)
		(width 0.0889)
		(layer "In11.Cu")
		(net "M_F_CPU0_SA_DQ<9>")
	)
	(segment
		(start 284.156912 -208.189322)
		(end 284.156912 -208.123282)
		(width 0.14478)
		(layer "In11.Cu")
		(net "M_F_CPU0_SA_DQ<9>")
	)
	(segment
		(start 275.979636 -207.960214)
		(end 276.142704 -208.123282)
		(width 0.14478)
		(layer "In11.Cu")
		(net "M_F_CPU0_SA_DQ<9>")
	)
	(segment
		(start 289.406076 -208.810098)
		(end 289.883088 -208.810098)
		(width 0.14478)
		(layer "In11.Cu")
		(net "M_F_CPU0_SA_DQ<9>")
	)
	(segment
		(start 296.359072 -209.037682)
		(end 296.52214 -209.20075)
		(width 0.14478)
		(layer "In11.Cu")
		(net "M_F_CPU0_SA_DQ<9>")
	)
	(segment
		(start 276.142704 -208.189322)
		(end 276.296374 -208.342992)
		(width 0.14478)
		(layer "In11.Cu")
		(net "M_F_CPU0_SA_DQ<9>")
	)
	(segment
		(start 281.047952 -208.810098)
		(end 281.21102 -208.973166)
		(width 0.14478)
		(layer "In11.Cu")
		(net "M_F_CPU0_SA_DQ<9>")
	)
	(segment
		(start 297.078654 -208.810098)
		(end 297.389042 -208.810098)
		(width 0.14478)
		(layer "In11.Cu")
		(net "M_F_CPU0_SA_DQ<9>")
	)
	(segment
		(start 302.483266 -208.810098)
		(end 302.646334 -208.973166)
		(width 0.14478)
		(layer "In11.Cu")
		(net "M_F_CPU0_SA_DQ<9>")
	)
	(segment
		(start 291.849048 -207.960214)
		(end 293.507922 -207.960214)
		(width 0.14478)
		(layer "In11.Cu")
		(net "M_F_CPU0_SA_DQ<9>")
	)
	(segment
		(start 273.788886 -208.973166)
		(end 273.788886 -209.037682)
		(width 0.14478)
		(layer "In11.Cu")
		(net "M_F_CPU0_SA_DQ<9>")
	)
	(segment
		(start 276.142704 -208.123282)
		(end 276.142704 -208.189322)
		(width 0.14478)
		(layer "In11.Cu")
		(net "M_F_CPU0_SA_DQ<9>")
	)
	(segment
		(start 279.260808 -208.810098)
		(end 281.047952 -208.810098)
		(width 0.14478)
		(layer "In11.Cu")
		(net "M_F_CPU0_SA_DQ<9>")
	)
	(segment
		(start 324.382384 -228.70922)
		(end 324.848474 -229.17531)
		(width 0.0889)
		(layer "In11.Cu")
		(net "M_F_CPU0_SA_DQ<9>")
	)
	(segment
		(start 296.915586 -208.973166)
		(end 297.078654 -208.810098)
		(width 0.14478)
		(layer "In11.Cu")
		(net "M_F_CPU0_SA_DQ<9>")
	)
	(segment
		(start 298.238926 -207.960214)
		(end 298.57954 -207.960214)
		(width 0.14478)
		(layer "In11.Cu")
		(net "M_F_CPU0_SA_DQ<9>")
	)
	(segment
		(start 288.523426 -208.810098)
		(end 288.686494 -208.973166)
		(width 0.14478)
		(layer "In11.Cu")
		(net "M_F_CPU0_SA_DQ<9>")
	)
	(segment
		(start 333.62138 -231.005126)
		(end 333.717138 -230.979726)
		(width 0.0889)
		(layer "In11.Cu")
		(net "M_F_CPU0_SA_DQ<9>")
	)
	(segment
		(start 272.43913 -208.810098)
		(end 273.625818 -208.810098)
		(width 0.14478)
		(layer "In11.Cu")
		(net "M_F_CPU0_SA_DQ<9>")
	)
	(segment
		(start 283.600398 -208.123282)
		(end 283.600398 -208.189322)
		(width 0.14478)
		(layer "In11.Cu")
		(net "M_F_CPU0_SA_DQ<9>")
	)
	(segment
		(start 272.276062 -208.973166)
		(end 272.43913 -208.810098)
		(width 0.14478)
		(layer "In11.Cu")
		(net "M_F_CPU0_SA_DQ<9>")
	)
	(segment
		(start 285.892748 -207.960214)
		(end 286.742632 -208.810098)
		(width 0.14478)
		(layer "In11.Cu")
		(net "M_F_CPU0_SA_DQ<9>")
	)
	(segment
		(start 301.051976 -207.960214)
		(end 301.90186 -208.810098)
		(width 0.14478)
		(layer "In11.Cu")
		(net "M_F_CPU0_SA_DQ<9>")
	)
	(segment
		(start 304.478944 -208.810098)
		(end 304.894742 -208.810098)
		(width 0.14478)
		(layer "In11.Cu")
		(net "M_F_CPU0_SA_DQ<9>")
	)
	(segment
		(start 274.3454 -208.973166)
		(end 274.508468 -208.810098)
		(width 0.14478)
		(layer "In11.Cu")
		(net "M_F_CPU0_SA_DQ<9>")
	)
	(segment
		(start 281.767534 -209.037682)
		(end 281.767534 -208.973166)
		(width 0.14478)
		(layer "In11.Cu")
		(net "M_F_CPU0_SA_DQ<9>")
	)
	(segment
		(start 318.191134 -221.745302)
		(end 323.791834 -227.346002)
		(width 0.14478)
		(layer "In11.Cu")
		(net "M_F_CPU0_SA_DQ<9>")
	)
	(segment
		(start 304.894742 -208.810098)
		(end 305.744626 -207.960214)
		(width 0.14478)
		(layer "In11.Cu")
		(net "M_F_CPU0_SA_DQ<9>")
	)
	(segment
		(start 303.202848 -209.037682)
		(end 303.202848 -208.973166)
		(width 0.14478)
		(layer "In11.Cu")
		(net "M_F_CPU0_SA_DQ<9>")
	)
	(segment
		(start 296.359072 -208.973166)
		(end 296.359072 -209.037682)
		(width 0.14478)
		(layer "In11.Cu")
		(net "M_F_CPU0_SA_DQ<9>")
	)
	(segment
		(start 271.574768 -208.810098)
		(end 271.719548 -208.954878)
		(width 0.14478)
		(layer "In11.Cu")
		(net "M_F_CPU0_SA_DQ<9>")
	)
	(segment
		(start 291.129466 -208.123282)
		(end 291.129466 -208.189322)
		(width 0.14478)
		(layer "In11.Cu")
		(net "M_F_CPU0_SA_DQ<9>")
	)
	(segment
		(start 283.17317 -207.960214)
		(end 283.43733 -207.960214)
		(width 0.14478)
		(layer "In11.Cu")
		(net "M_F_CPU0_SA_DQ<9>")
	)
	(segment
		(start 303.596294 -208.810098)
		(end 303.759362 -208.973166)
		(width 0.14478)
		(layer "In11.Cu")
		(net "M_F_CPU0_SA_DQ<9>")
	)
	(segment
		(start 290.966398 -207.960214)
		(end 291.129466 -208.123282)
		(width 0.14478)
		(layer "In11.Cu")
		(net "M_F_CPU0_SA_DQ<9>")
	)
	(segment
		(start 274.3454 -209.037682)
		(end 274.3454 -208.973166)
		(width 0.14478)
		(layer "In11.Cu")
		(net "M_F_CPU0_SA_DQ<9>")
	)
	(segment
		(start 273.788886 -209.037682)
		(end 273.951954 -209.20075)
		(width 0.14478)
		(layer "In11.Cu")
		(net "M_F_CPU0_SA_DQ<9>")
	)
	(segment
		(start 276.545548 -208.342992)
		(end 276.699218 -208.189322)
		(width 0.14478)
		(layer "In11.Cu")
		(net "M_F_CPU0_SA_DQ<9>")
	)
	(segment
		(start 302.809402 -209.20075)
		(end 303.03978 -209.20075)
		(width 0.14478)
		(layer "In11.Cu")
		(net "M_F_CPU0_SA_DQ<9>")
	)
	(segment
		(start 283.600398 -208.189322)
		(end 283.754068 -208.342992)
		(width 0.14478)
		(layer "In11.Cu")
		(net "M_F_CPU0_SA_DQ<9>")
	)
	(segment
		(start 290.732972 -207.960214)
		(end 290.966398 -207.960214)
		(width 0.14478)
		(layer "In11.Cu")
		(net "M_F_CPU0_SA_DQ<9>")
	)
	(segment
		(start 284.31998 -207.960214)
		(end 285.892748 -207.960214)
		(width 0.14478)
		(layer "In11.Cu")
		(net "M_F_CPU0_SA_DQ<9>")
	)
	(segment
		(start 274.754848 -208.810098)
		(end 275.604732 -207.960214)
		(width 0.14478)
		(layer "In11.Cu")
		(net "M_F_CPU0_SA_DQ<9>")
	)
	(segment
		(start 275.604732 -207.960214)
		(end 275.979636 -207.960214)
		(width 0.14478)
		(layer "In11.Cu")
		(net "M_F_CPU0_SA_DQ<9>")
	)
	(segment
		(start 294.357806 -208.810098)
		(end 296.196004 -208.810098)
		(width 0.14478)
		(layer "In11.Cu")
		(net "M_F_CPU0_SA_DQ<9>")
	)
	(segment
		(start 333.717138 -230.979726)
		(end 333.871062 -230.714296)
		(width 0.0889)
		(layer "In11.Cu")
		(net "M_F_CPU0_SA_DQ<9>")
	)
	(segment
		(start 331.229716 -231.041448)
		(end 331.238098 -231.036622)
		(width 0.0889)
		(layer "In11.Cu")
		(net "M_F_CPU0_SA_DQ<9>")
	)
	(segment
		(start 328.409808 -231.041448)
		(end 328.41819 -231.036622)
		(width 0.0889)
		(layer "In11.Cu")
		(net "M_F_CPU0_SA_DQ<9>")
	)
	(segment
		(start 301.90186 -208.810098)
		(end 302.483266 -208.810098)
		(width 0.14478)
		(layer "In11.Cu")
		(net "M_F_CPU0_SA_DQ<9>")
	)
	(segment
		(start 328.984102 -231.036622)
		(end 328.992484 -231.041448)
		(width 0.0889)
		(layer "In11.Cu")
		(net "M_F_CPU0_SA_DQ<9>")
	)
	(segment
		(start 326.590152 -230.082852)
		(end 327.304146 -230.796846)
		(width 0.0889)
		(layer "In11.Cu")
		(net "M_F_CPU0_SA_DQ<9>")
	)
	(segment
		(start 302.646334 -209.037682)
		(end 302.809402 -209.20075)
		(width 0.14478)
		(layer "In11.Cu")
		(net "M_F_CPU0_SA_DQ<9>")
	)
	(segment
		(start 299.46219 -207.960214)
		(end 301.051976 -207.960214)
		(width 0.14478)
		(layer "In11.Cu")
		(net "M_F_CPU0_SA_DQ<9>")
	)
	(segment
		(start 271.719548 -209.024982)
		(end 271.882616 -209.18805)
		(width 0.14478)
		(layer "In11.Cu")
		(net "M_F_CPU0_SA_DQ<9>")
	)
	(segment
		(start 293.507922 -207.960214)
		(end 294.357806 -208.810098)
		(width 0.14478)
		(layer "In11.Cu")
		(net "M_F_CPU0_SA_DQ<9>")
	)
	(segment
		(start 281.21102 -208.973166)
		(end 281.21102 -209.037682)
		(width 0.14478)
		(layer "In11.Cu")
		(net "M_F_CPU0_SA_DQ<9>")
	)
	(segment
		(start 325.171308 -229.17531)
		(end 326.079358 -230.082852)
		(width 0.0889)
		(layer "In11.Cu")
		(net "M_F_CPU0_SA_DQ<9>")
	)
	(segment
		(start 291.278056 -208.337912)
		(end 291.53739 -208.337912)
		(width 0.14478)
		(layer "In11.Cu")
		(net "M_F_CPU0_SA_DQ<9>")
	)
	(segment
		(start 298.905676 -208.34477)
		(end 299.136054 -208.34477)
		(width 0.14478)
		(layer "In11.Cu")
		(net "M_F_CPU0_SA_DQ<9>")
	)
	(segment
		(start 284.156912 -208.123282)
		(end 284.31998 -207.960214)
		(width 0.14478)
		(layer "In11.Cu")
		(net "M_F_CPU0_SA_DQ<9>")
	)
	(segment
		(start 305.744626 -207.960214)
		(end 307.155342 -207.960214)
		(width 0.14478)
		(layer "In11.Cu")
		(net "M_F_CPU0_SA_DQ<9>")
	)
	(segment
		(start 276.699218 -208.189322)
		(end 276.699218 -208.123282)
		(width 0.14478)
		(layer "In11.Cu")
		(net "M_F_CPU0_SA_DQ<9>")
	)
	(segment
		(start 303.92243 -209.20075)
		(end 304.152808 -209.20075)
		(width 0.14478)
		(layer "In11.Cu")
		(net "M_F_CPU0_SA_DQ<9>")
	)
	(segment
		(start 324.848474 -229.17531)
		(end 325.171308 -229.17531)
		(width 0.0889)
		(layer "In11.Cu")
		(net "M_F_CPU0_SA_DQ<9>")
	)
	(segment
		(start 298.742608 -208.123282)
		(end 298.742608 -208.181702)
		(width 0.14478)
		(layer "In11.Cu")
		(net "M_F_CPU0_SA_DQ<9>")
	)
	(segment
		(start 273.625818 -208.810098)
		(end 273.788886 -208.973166)
		(width 0.14478)
		(layer "In11.Cu")
		(net "M_F_CPU0_SA_DQ<9>")
	)
	(segment
		(start 307.155342 -207.960214)
		(end 318.191134 -218.996006)
		(width 0.14478)
		(layer "In11.Cu")
		(net "M_F_CPU0_SA_DQ<9>")
	)
	(segment
		(start 299.299122 -208.123282)
		(end 299.46219 -207.960214)
		(width 0.14478)
		(layer "In11.Cu")
		(net "M_F_CPU0_SA_DQ<9>")
	)
	(segment
		(start 270.07312 -208.810098)
		(end 271.574768 -208.810098)
		(width 0.14478)
		(layer "In11.Cu")
		(net "M_F_CPU0_SA_DQ<9>")
	)
	(segment
		(start 296.915586 -209.037682)
		(end 296.915586 -208.973166)
		(width 0.14478)
		(layer "In11.Cu")
		(net "M_F_CPU0_SA_DQ<9>")
	)
	(segment
		(start 289.243008 -209.024982)
		(end 289.243008 -208.973166)
		(width 0.14478)
		(layer "In11.Cu")
		(net "M_F_CPU0_SA_DQ<9>")
	)
	(segment
		(start 273.951954 -209.20075)
		(end 274.182332 -209.20075)
		(width 0.14478)
		(layer "In11.Cu")
		(net "M_F_CPU0_SA_DQ<9>")
	)
	(segment
		(start 324.382384 -227.936552)
		(end 324.382384 -228.70922)
		(width 0.0889)
		(layer "In11.Cu")
		(net "M_F_CPU0_SA_DQ<9>")
	)
	(segment
		(start 286.742632 -208.810098)
		(end 288.523426 -208.810098)
		(width 0.14478)
		(layer "In11.Cu")
		(net "M_F_CPU0_SA_DQ<9>")
	)
	(segment
		(start 281.21102 -209.037682)
		(end 281.374088 -209.20075)
		(width 0.14478)
		(layer "In11.Cu")
		(net "M_F_CPU0_SA_DQ<9>")
	)
	(segment
		(start 276.862286 -207.960214)
		(end 278.410924 -207.960214)
		(width 0.14478)
		(layer "In11.Cu")
		(net "M_F_CPU0_SA_DQ<9>")
	)
	(segment
		(start 302.646334 -208.973166)
		(end 302.646334 -209.037682)
		(width 0.14478)
		(layer "In11.Cu")
		(net "M_F_CPU0_SA_DQ<9>")
	)
	(segment
		(start 303.759362 -209.037682)
		(end 303.92243 -209.20075)
		(width 0.14478)
		(layer "In11.Cu")
		(net "M_F_CPU0_SA_DQ<9>")
	)
	(segment
		(start 296.196004 -208.810098)
		(end 296.359072 -208.973166)
		(width 0.14478)
		(layer "In11.Cu")
		(net "M_F_CPU0_SA_DQ<9>")
	)
	(segment
		(start 283.754068 -208.342992)
		(end 284.003242 -208.342992)
		(width 0.14478)
		(layer "In11.Cu")
		(net "M_F_CPU0_SA_DQ<9>")
	)
	(segment
		(start 291.53739 -208.337912)
		(end 291.68598 -208.189322)
		(width 0.14478)
		(layer "In11.Cu")
		(net "M_F_CPU0_SA_DQ<9>")
	)
	(segment
		(start 278.410924 -207.960214)
		(end 279.260808 -208.810098)
		(width 0.14478)
		(layer "In11.Cu")
		(net "M_F_CPU0_SA_DQ<9>")
	)
	(segment
		(start 288.686494 -209.024982)
		(end 288.849562 -209.18805)
		(width 0.14478)
		(layer "In11.Cu")
		(net "M_F_CPU0_SA_DQ<9>")
	)
	(segment
		(start 299.299122 -208.181702)
		(end 299.299122 -208.123282)
		(width 0.14478)
		(layer "In11.Cu")
		(net "M_F_CPU0_SA_DQ<9>")
	)
	(segment
		(start 288.849562 -209.18805)
		(end 289.07994 -209.18805)
		(width 0.14478)
		(layer "In11.Cu")
		(net "M_F_CPU0_SA_DQ<9>")
	)
	(segment
		(start 274.508468 -208.810098)
		(end 274.754848 -208.810098)
		(width 0.14478)
		(layer "In11.Cu")
		(net "M_F_CPU0_SA_DQ<9>")
	)
	(segment
		(start 281.767534 -208.973166)
		(end 281.930602 -208.810098)
		(width 0.14478)
		(layer "In11.Cu")
		(net "M_F_CPU0_SA_DQ<9>")
	)
	(segment
		(start 288.686494 -208.973166)
		(end 288.686494 -209.024982)
		(width 0.14478)
		(layer "In11.Cu")
		(net "M_F_CPU0_SA_DQ<9>")
	)
	(segment
		(start 291.68598 -208.123282)
		(end 291.849048 -207.960214)
		(width 0.14478)
		(layer "In11.Cu")
		(net "M_F_CPU0_SA_DQ<9>")
	)
	(segment
		(start 281.374088 -209.20075)
		(end 281.604466 -209.20075)
		(width 0.14478)
		(layer "In11.Cu")
		(net "M_F_CPU0_SA_DQ<9>")
	)
	(segment
		(start 298.57954 -207.960214)
		(end 298.742608 -208.123282)
		(width 0.14478)
		(layer "In11.Cu")
		(net "M_F_CPU0_SA_DQ<9>")
	)
	(segment
		(start 296.52214 -209.20075)
		(end 296.752518 -209.20075)
		(width 0.14478)
		(layer "In11.Cu")
		(net "M_F_CPU0_SA_DQ<9>")
	)
	(segment
		(start 271.719548 -208.954878)
		(end 271.719548 -209.024982)
		(width 0.14478)
		(layer "In11.Cu")
		(net "M_F_CPU0_SA_DQ<9>")
	)
	(segment
		(start 274.182332 -209.20075)
		(end 274.3454 -209.037682)
		(width 0.14478)
		(layer "In11.Cu")
		(net "M_F_CPU0_SA_DQ<9>")
	)
	(segment
		(start 296.752518 -209.20075)
		(end 296.915586 -209.037682)
		(width 0.14478)
		(layer "In11.Cu")
		(net "M_F_CPU0_SA_DQ<9>")
	)
	(segment
		(start 283.43733 -207.960214)
		(end 283.600398 -208.123282)
		(width 0.14478)
		(layer "In11.Cu")
		(net "M_F_CPU0_SA_DQ<9>")
	)
	(segment
		(start 269.648178 -208.385156)
		(end 270.07312 -208.810098)
		(width 0.14478)
		(layer "In11.Cu")
		(net "M_F_CPU0_SA_DQ<9>")
	)
	(segment
		(start 326.079358 -230.082852)
		(end 326.590152 -230.082852)
		(width 0.0889)
		(layer "In11.Cu")
		(net "M_F_CPU0_SA_DQ<9>")
	)
	(segment
		(start 303.202848 -208.973166)
		(end 303.365916 -208.810098)
		(width 0.14478)
		(layer "In11.Cu")
		(net "M_F_CPU0_SA_DQ<9>")
	)
	(segment
		(start 298.742608 -208.181702)
		(end 298.905676 -208.34477)
		(width 0.14478)
		(layer "In11.Cu")
		(net "M_F_CPU0_SA_DQ<9>")
	)
	(segment
		(start 284.003242 -208.342992)
		(end 284.156912 -208.189322)
		(width 0.14478)
		(layer "In11.Cu")
		(net "M_F_CPU0_SA_DQ<9>")
	)
	(segment
		(start 303.03978 -209.20075)
		(end 303.202848 -209.037682)
		(width 0.14478)
		(layer "In11.Cu")
		(net "M_F_CPU0_SA_DQ<9>")
	)
	(segment
		(start 272.276062 -209.024982)
		(end 272.276062 -208.973166)
		(width 0.14478)
		(layer "In11.Cu")
		(net "M_F_CPU0_SA_DQ<9>")
	)
	(segment
		(start 271.882616 -209.18805)
		(end 272.112994 -209.18805)
		(width 0.14478)
		(layer "In11.Cu")
		(net "M_F_CPU0_SA_DQ<9>")
	)
	(segment
		(start 289.07994 -209.18805)
		(end 289.243008 -209.024982)
		(width 0.14478)
		(layer "In11.Cu")
		(net "M_F_CPU0_SA_DQ<9>")
	)
	(arc
		(start 331.238098 -231.036622)
		(mid 331.521054 -230.960445)
		(end 331.80401 -231.036622)
		(width 0.0889)
		(layer "In11.Cu")
		(net "M_F_CPU0_SA_DQ<9>")
	)
	(arc
		(start 328.41819 -231.036622)
		(mid 328.701146 -230.960445)
		(end 328.984102 -231.036622)
		(width 0.0889)
		(layer "In11.Cu")
		(net "M_F_CPU0_SA_DQ<9>")
	)
	(arc
		(start 330.863956 -231.036622)
		(mid 331.046207 -231.087006)
		(end 331.229716 -231.041448)
		(width 0.0889)
		(layer "In11.Cu")
		(net "M_F_CPU0_SA_DQ<9>")
	)
	(arc
		(start 329.924156 -231.036622)
		(mid 330.1111 -231.086911)
		(end 330.298044 -231.036622)
		(width 0.0889)
		(layer "In11.Cu")
		(net "M_F_CPU0_SA_DQ<9>")
	)
	(arc
		(start 330.298044 -231.036622)
		(mid 330.581 -230.960445)
		(end 330.863956 -231.036622)
		(width 0.0889)
		(layer "In11.Cu")
		(net "M_F_CPU0_SA_DQ<9>")
	)
	(arc
		(start 328.992484 -231.041448)
		(mid 329.175992 -231.086973)
		(end 329.358244 -231.036622)
		(width 0.0889)
		(layer "In11.Cu")
		(net "M_F_CPU0_SA_DQ<9>")
	)
	(arc
		(start 332.178152 -231.036622)
		(mid 332.461108 -230.960445)
		(end 332.744064 -231.036622)
		(width 0.0889)
		(layer "In11.Cu")
		(net "M_F_CPU0_SA_DQ<9>")
	)
	(arc
		(start 333.118206 -231.036622)
		(mid 333.366066 -230.961539)
		(end 333.62138 -231.005126)
		(width 0.0889)
		(layer "In11.Cu")
		(net "M_F_CPU0_SA_DQ<9>")
	)
	(arc
		(start 328.044048 -231.036622)
		(mid 328.226299 -231.087006)
		(end 328.409808 -231.041448)
		(width 0.0889)
		(layer "In11.Cu")
		(net "M_F_CPU0_SA_DQ<9>")
	)
	(arc
		(start 332.752446 -231.041448)
		(mid 332.935954 -231.086973)
		(end 333.118206 -231.036622)
		(width 0.0889)
		(layer "In11.Cu")
		(net "M_F_CPU0_SA_DQ<9>")
	)
	(arc
		(start 329.358244 -231.036622)
		(mid 329.6412 -230.960445)
		(end 329.924156 -231.036622)
		(width 0.0889)
		(layer "In11.Cu")
		(net "M_F_CPU0_SA_DQ<9>")
	)
	(arc
		(start 327.304146 -230.796846)
		(mid 327.500561 -230.924435)
		(end 327.731882 -230.961184)
		(width 0.0889)
		(layer "In11.Cu")
		(net "M_F_CPU0_SA_DQ<9>")
	)
	(arc
		(start 331.80401 -231.036622)
		(mid 331.986261 -231.087006)
		(end 332.16977 -231.041448)
		(width 0.0889)
		(layer "In11.Cu")
		(net "M_F_CPU0_SA_DQ<9>")
	)
	(arc
		(start 327.731882 -230.961184)
		(mid 327.893455 -230.976189)
		(end 328.044048 -231.036622)
		(width 0.0889)
		(layer "In11.Cu")
		(net "M_F_CPU0_SA_DQ<9>")
	)
	(segment
		(start 332.92796 -230.169974)
		(end 332.461108 -229.904036)
		(width 0.10668)
		(layer "F.Cu")
		(net "M_F_CPU0_SA_DQ<8>")
	)
	(segment
		(start 303.09947 -207.49133)
		(end 303.262538 -207.328262)
		(width 0.14478)
		(layer "In11.Cu")
		(net "M_F_CPU0_SA_DQ<8>")
	)
	(segment
		(start 281.15133 -207.273144)
		(end 281.15133 -207.323182)
		(width 0.14478)
		(layer "In11.Cu")
		(net "M_F_CPU0_SA_DQ<8>")
	)
	(segment
		(start 303.262538 -207.273144)
		(end 303.425606 -207.110076)
		(width 0.14478)
		(layer "In11.Cu")
		(net "M_F_CPU0_SA_DQ<8>")
	)
	(segment
		(start 271.894554 -207.49895)
		(end 272.124932 -207.49895)
		(width 0.14478)
		(layer "In11.Cu")
		(net "M_F_CPU0_SA_DQ<8>")
	)
	(segment
		(start 298.62145 -206.260192)
		(end 298.784518 -206.42326)
		(width 0.14478)
		(layer "In11.Cu")
		(net "M_F_CPU0_SA_DQ<8>")
	)
	(segment
		(start 274.015454 -207.49895)
		(end 274.178522 -207.335882)
		(width 0.14478)
		(layer "In11.Cu")
		(net "M_F_CPU0_SA_DQ<8>")
	)
	(segment
		(start 327.574148 -230.226616)
		(end 327.574402 -230.226616)
		(width 0.0889)
		(layer "In11.Cu")
		(net "M_F_CPU0_SA_DQ<8>")
	)
	(segment
		(start 298.784518 -206.487522)
		(end 298.947586 -206.65059)
		(width 0.14478)
		(layer "In11.Cu")
		(net "M_F_CPU0_SA_DQ<8>")
	)
	(segment
		(start 324.32117 -226.589082)
		(end 324.32117 -227.004626)
		(width 0.0889)
		(layer "In11.Cu")
		(net "M_F_CPU0_SA_DQ<8>")
	)
	(segment
		(start 301.051976 -206.260192)
		(end 301.90186 -207.110076)
		(width 0.14478)
		(layer "In11.Cu")
		(net "M_F_CPU0_SA_DQ<8>")
	)
	(segment
		(start 306.97043 -206.487522)
		(end 306.97043 -206.42326)
		(width 0.14478)
		(layer "In11.Cu")
		(net "M_F_CPU0_SA_DQ<8>")
	)
	(segment
		(start 302.542956 -207.110076)
		(end 302.706024 -207.273144)
		(width 0.14478)
		(layer "In11.Cu")
		(net "M_F_CPU0_SA_DQ<8>")
	)
	(segment
		(start 289.374326 -207.273144)
		(end 289.537394 -207.110076)
		(width 0.14478)
		(layer "In11.Cu")
		(net "M_F_CPU0_SA_DQ<8>")
	)
	(segment
		(start 276.088856 -206.474822)
		(end 276.251924 -206.63789)
		(width 0.14478)
		(layer "In11.Cu")
		(net "M_F_CPU0_SA_DQ<8>")
	)
	(segment
		(start 303.262538 -207.328262)
		(end 303.262538 -207.273144)
		(width 0.14478)
		(layer "In11.Cu")
		(net "M_F_CPU0_SA_DQ<8>")
	)
	(segment
		(start 281.15133 -207.323182)
		(end 281.314398 -207.48625)
		(width 0.14478)
		(layer "In11.Cu")
		(net "M_F_CPU0_SA_DQ<8>")
	)
	(segment
		(start 291.412168 -206.64297)
		(end 291.642546 -206.64297)
		(width 0.14478)
		(layer "In11.Cu")
		(net "M_F_CPU0_SA_DQ<8>")
	)
	(segment
		(start 298.238926 -206.260192)
		(end 298.62145 -206.260192)
		(width 0.14478)
		(layer "In11.Cu")
		(net "M_F_CPU0_SA_DQ<8>")
	)
	(segment
		(start 271.731486 -207.335882)
		(end 271.894554 -207.49895)
		(width 0.14478)
		(layer "In11.Cu")
		(net "M_F_CPU0_SA_DQ<8>")
	)
	(segment
		(start 293.507922 -206.260192)
		(end 294.357806 -207.110076)
		(width 0.14478)
		(layer "In11.Cu")
		(net "M_F_CPU0_SA_DQ<8>")
	)
	(segment
		(start 325.336154 -228.64191)
		(end 326.303894 -229.60965)
		(width 0.0889)
		(layer "In11.Cu")
		(net "M_F_CPU0_SA_DQ<8>")
	)
	(segment
		(start 275.604732 -206.260192)
		(end 275.925788 -206.260192)
		(width 0.14478)
		(layer "In11.Cu")
		(net "M_F_CPU0_SA_DQ<8>")
	)
	(segment
		(start 291.805614 -206.479902)
		(end 291.805614 -206.42326)
		(width 0.14478)
		(layer "In11.Cu")
		(net "M_F_CPU0_SA_DQ<8>")
	)
	(segment
		(start 304.375566 -207.273144)
		(end 304.538634 -207.110076)
		(width 0.14478)
		(layer "In11.Cu")
		(net "M_F_CPU0_SA_DQ<8>")
	)
	(segment
		(start 324.917054 -227.60051)
		(end 324.917054 -227.74275)
		(width 0.0889)
		(layer "In11.Cu")
		(net "M_F_CPU0_SA_DQ<8>")
	)
	(segment
		(start 276.088856 -206.42326)
		(end 276.088856 -206.474822)
		(width 0.14478)
		(layer "In11.Cu")
		(net "M_F_CPU0_SA_DQ<8>")
	)
	(segment
		(start 332.307184 -230.169466)
		(end 332.461108 -229.904036)
		(width 0.0889)
		(layer "In11.Cu")
		(net "M_F_CPU0_SA_DQ<8>")
	)
	(segment
		(start 276.64537 -206.474822)
		(end 276.64537 -206.42326)
		(width 0.14478)
		(layer "In11.Cu")
		(net "M_F_CPU0_SA_DQ<8>")
	)
	(segment
		(start 274.178522 -207.335882)
		(end 274.178522 -207.273144)
		(width 0.14478)
		(layer "In11.Cu")
		(net "M_F_CPU0_SA_DQ<8>")
	)
	(segment
		(start 281.314398 -207.48625)
		(end 281.544776 -207.48625)
		(width 0.14478)
		(layer "In11.Cu")
		(net "M_F_CPU0_SA_DQ<8>")
	)
	(segment
		(start 276.64537 -206.42326)
		(end 276.808438 -206.260192)
		(width 0.14478)
		(layer "In11.Cu")
		(net "M_F_CPU0_SA_DQ<8>")
	)
	(segment
		(start 282.323286 -207.110076)
		(end 283.17317 -206.260192)
		(width 0.14478)
		(layer "In11.Cu")
		(net "M_F_CPU0_SA_DQ<8>")
	)
	(segment
		(start 283.672026 -206.42326)
		(end 283.672026 -206.479902)
		(width 0.14478)
		(layer "In11.Cu")
		(net "M_F_CPU0_SA_DQ<8>")
	)
	(segment
		(start 325.336154 -228.16185)
		(end 325.336154 -228.64191)
		(width 0.0889)
		(layer "In11.Cu")
		(net "M_F_CPU0_SA_DQ<8>")
	)
	(segment
		(start 299.5041 -206.260192)
		(end 301.051976 -206.260192)
		(width 0.14478)
		(layer "In11.Cu")
		(net "M_F_CPU0_SA_DQ<8>")
	)
	(segment
		(start 281.707844 -207.323182)
		(end 281.707844 -207.273144)
		(width 0.14478)
		(layer "In11.Cu")
		(net "M_F_CPU0_SA_DQ<8>")
	)
	(segment
		(start 299.341032 -206.42326)
		(end 299.5041 -206.260192)
		(width 0.14478)
		(layer "In11.Cu")
		(net "M_F_CPU0_SA_DQ<8>")
	)
	(segment
		(start 285.892748 -206.260192)
		(end 286.742632 -207.110076)
		(width 0.14478)
		(layer "In11.Cu")
		(net "M_F_CPU0_SA_DQ<8>")
	)
	(segment
		(start 284.22854 -206.479902)
		(end 284.22854 -206.42326)
		(width 0.14478)
		(layer "In11.Cu")
		(net "M_F_CPU0_SA_DQ<8>")
	)
	(segment
		(start 286.742632 -207.110076)
		(end 288.654744 -207.110076)
		(width 0.14478)
		(layer "In11.Cu")
		(net "M_F_CPU0_SA_DQ<8>")
	)
	(segment
		(start 326.939148 -229.60965)
		(end 327.497186 -230.167688)
		(width 0.0889)
		(layer "In11.Cu")
		(net "M_F_CPU0_SA_DQ<8>")
	)
	(segment
		(start 307.133498 -206.260192)
		(end 307.611018 -206.260192)
		(width 0.14478)
		(layer "In11.Cu")
		(net "M_F_CPU0_SA_DQ<8>")
	)
	(segment
		(start 324.917054 -227.74275)
		(end 325.336154 -228.16185)
		(width 0.0889)
		(layer "In11.Cu")
		(net "M_F_CPU0_SA_DQ<8>")
	)
	(segment
		(start 273.45894 -207.110076)
		(end 273.622008 -207.273144)
		(width 0.14478)
		(layer "In11.Cu")
		(net "M_F_CPU0_SA_DQ<8>")
	)
	(segment
		(start 291.2491 -206.479902)
		(end 291.412168 -206.64297)
		(width 0.14478)
		(layer "In11.Cu")
		(net "M_F_CPU0_SA_DQ<8>")
	)
	(segment
		(start 279.260808 -207.110076)
		(end 280.988262 -207.110076)
		(width 0.14478)
		(layer "In11.Cu")
		(net "M_F_CPU0_SA_DQ<8>")
	)
	(segment
		(start 289.537394 -207.110076)
		(end 289.883088 -207.110076)
		(width 0.14478)
		(layer "In11.Cu")
		(net "M_F_CPU0_SA_DQ<8>")
	)
	(segment
		(start 272.451068 -207.110076)
		(end 273.45894 -207.110076)
		(width 0.14478)
		(layer "In11.Cu")
		(net "M_F_CPU0_SA_DQ<8>")
	)
	(segment
		(start 284.391608 -206.260192)
		(end 285.892748 -206.260192)
		(width 0.14478)
		(layer "In11.Cu")
		(net "M_F_CPU0_SA_DQ<8>")
	)
	(segment
		(start 272.288 -207.273144)
		(end 272.451068 -207.110076)
		(width 0.14478)
		(layer "In11.Cu")
		(net "M_F_CPU0_SA_DQ<8>")
	)
	(segment
		(start 281.870912 -207.110076)
		(end 282.323286 -207.110076)
		(width 0.14478)
		(layer "In11.Cu")
		(net "M_F_CPU0_SA_DQ<8>")
	)
	(segment
		(start 302.706024 -207.328262)
		(end 302.869092 -207.49133)
		(width 0.14478)
		(layer "In11.Cu")
		(net "M_F_CPU0_SA_DQ<8>")
	)
	(segment
		(start 269.648178 -206.685134)
		(end 270.07312 -207.110076)
		(width 0.14478)
		(layer "In11.Cu")
		(net "M_F_CPU0_SA_DQ<8>")
	)
	(segment
		(start 290.732972 -206.260192)
		(end 291.086032 -206.260192)
		(width 0.14478)
		(layer "In11.Cu")
		(net "M_F_CPU0_SA_DQ<8>")
	)
	(segment
		(start 273.622008 -207.335882)
		(end 273.785076 -207.49895)
		(width 0.14478)
		(layer "In11.Cu")
		(net "M_F_CPU0_SA_DQ<8>")
	)
	(segment
		(start 289.374326 -207.335882)
		(end 289.374326 -207.273144)
		(width 0.14478)
		(layer "In11.Cu")
		(net "M_F_CPU0_SA_DQ<8>")
	)
	(segment
		(start 271.586706 -207.110076)
		(end 271.731486 -207.254856)
		(width 0.14478)
		(layer "In11.Cu")
		(net "M_F_CPU0_SA_DQ<8>")
	)
	(segment
		(start 273.622008 -207.273144)
		(end 273.622008 -207.335882)
		(width 0.14478)
		(layer "In11.Cu")
		(net "M_F_CPU0_SA_DQ<8>")
	)
	(segment
		(start 296.185082 -207.110076)
		(end 296.34815 -207.273144)
		(width 0.14478)
		(layer "In11.Cu")
		(net "M_F_CPU0_SA_DQ<8>")
	)
	(segment
		(start 329.819762 -230.231442)
		(end 329.828144 -230.226616)
		(width 0.0889)
		(layer "In11.Cu")
		(net "M_F_CPU0_SA_DQ<8>")
	)
	(segment
		(start 324.32117 -227.004626)
		(end 324.917054 -227.60051)
		(width 0.0889)
		(layer "In11.Cu")
		(net "M_F_CPU0_SA_DQ<8>")
	)
	(segment
		(start 304.894742 -207.110076)
		(end 305.744626 -206.260192)
		(width 0.14478)
		(layer "In11.Cu")
		(net "M_F_CPU0_SA_DQ<8>")
	)
	(segment
		(start 332.211172 -230.194866)
		(end 332.307184 -230.169466)
		(width 0.0889)
		(layer "In11.Cu")
		(net "M_F_CPU0_SA_DQ<8>")
	)
	(segment
		(start 304.212498 -207.49133)
		(end 304.375566 -207.328262)
		(width 0.14478)
		(layer "In11.Cu")
		(net "M_F_CPU0_SA_DQ<8>")
	)
	(segment
		(start 272.124932 -207.49895)
		(end 272.288 -207.335882)
		(width 0.14478)
		(layer "In11.Cu")
		(net "M_F_CPU0_SA_DQ<8>")
	)
	(segment
		(start 297.067732 -207.110076)
		(end 297.389042 -207.110076)
		(width 0.14478)
		(layer "In11.Cu")
		(net "M_F_CPU0_SA_DQ<8>")
	)
	(segment
		(start 283.835094 -206.64297)
		(end 284.065472 -206.64297)
		(width 0.14478)
		(layer "In11.Cu")
		(net "M_F_CPU0_SA_DQ<8>")
	)
	(segment
		(start 278.410924 -206.260192)
		(end 279.260808 -207.110076)
		(width 0.14478)
		(layer "In11.Cu")
		(net "M_F_CPU0_SA_DQ<8>")
	)
	(segment
		(start 274.34159 -207.110076)
		(end 274.754848 -207.110076)
		(width 0.14478)
		(layer "In11.Cu")
		(net "M_F_CPU0_SA_DQ<8>")
	)
	(segment
		(start 288.654744 -207.110076)
		(end 288.817812 -207.273144)
		(width 0.14478)
		(layer "In11.Cu")
		(net "M_F_CPU0_SA_DQ<8>")
	)
	(segment
		(start 327.574402 -230.226616)
		(end 327.586086 -230.233474)
		(width 0.0889)
		(layer "In11.Cu")
		(net "M_F_CPU0_SA_DQ<8>")
	)
	(segment
		(start 304.375566 -207.328262)
		(end 304.375566 -207.273144)
		(width 0.14478)
		(layer "In11.Cu")
		(net "M_F_CPU0_SA_DQ<8>")
	)
	(segment
		(start 302.706024 -207.273144)
		(end 302.706024 -207.328262)
		(width 0.14478)
		(layer "In11.Cu")
		(net "M_F_CPU0_SA_DQ<8>")
	)
	(segment
		(start 273.785076 -207.49895)
		(end 274.015454 -207.49895)
		(width 0.14478)
		(layer "In11.Cu")
		(net "M_F_CPU0_SA_DQ<8>")
	)
	(segment
		(start 303.819052 -207.273144)
		(end 303.819052 -207.328262)
		(width 0.14478)
		(layer "In11.Cu")
		(net "M_F_CPU0_SA_DQ<8>")
	)
	(segment
		(start 288.98088 -207.49895)
		(end 289.211258 -207.49895)
		(width 0.14478)
		(layer "In11.Cu")
		(net "M_F_CPU0_SA_DQ<8>")
	)
	(segment
		(start 276.482302 -206.63789)
		(end 276.64537 -206.474822)
		(width 0.14478)
		(layer "In11.Cu")
		(net "M_F_CPU0_SA_DQ<8>")
	)
	(segment
		(start 306.576984 -206.65059)
		(end 306.807362 -206.65059)
		(width 0.14478)
		(layer "In11.Cu")
		(net "M_F_CPU0_SA_DQ<8>")
	)
	(segment
		(start 303.819052 -207.328262)
		(end 303.98212 -207.49133)
		(width 0.14478)
		(layer "In11.Cu")
		(net "M_F_CPU0_SA_DQ<8>")
	)
	(segment
		(start 305.744626 -206.260192)
		(end 306.250848 -206.260192)
		(width 0.14478)
		(layer "In11.Cu")
		(net "M_F_CPU0_SA_DQ<8>")
	)
	(segment
		(start 281.544776 -207.48625)
		(end 281.707844 -207.323182)
		(width 0.14478)
		(layer "In11.Cu")
		(net "M_F_CPU0_SA_DQ<8>")
	)
	(segment
		(start 298.947586 -206.65059)
		(end 299.177964 -206.65059)
		(width 0.14478)
		(layer "In11.Cu")
		(net "M_F_CPU0_SA_DQ<8>")
	)
	(segment
		(start 291.086032 -206.260192)
		(end 291.2491 -206.42326)
		(width 0.14478)
		(layer "In11.Cu")
		(net "M_F_CPU0_SA_DQ<8>")
	)
	(segment
		(start 270.07312 -207.110076)
		(end 271.586706 -207.110076)
		(width 0.14478)
		(layer "In11.Cu")
		(net "M_F_CPU0_SA_DQ<8>")
	)
	(segment
		(start 276.251924 -206.63789)
		(end 276.482302 -206.63789)
		(width 0.14478)
		(layer "In11.Cu")
		(net "M_F_CPU0_SA_DQ<8>")
	)
	(segment
		(start 330.394056 -230.226616)
		(end 330.402438 -230.231442)
		(width 0.0889)
		(layer "In11.Cu")
		(net "M_F_CPU0_SA_DQ<8>")
	)
	(segment
		(start 324.035166 -226.303078)
		(end 324.32117 -226.589082)
		(width 0.0889)
		(layer "In11.Cu")
		(net "M_F_CPU0_SA_DQ<8>")
	)
	(segment
		(start 294.357806 -207.110076)
		(end 296.185082 -207.110076)
		(width 0.14478)
		(layer "In11.Cu")
		(net "M_F_CPU0_SA_DQ<8>")
	)
	(segment
		(start 276.808438 -206.260192)
		(end 278.410924 -206.260192)
		(width 0.14478)
		(layer "In11.Cu")
		(net "M_F_CPU0_SA_DQ<8>")
	)
	(segment
		(start 301.90186 -207.110076)
		(end 302.542956 -207.110076)
		(width 0.14478)
		(layer "In11.Cu")
		(net "M_F_CPU0_SA_DQ<8>")
	)
	(segment
		(start 296.904664 -207.273144)
		(end 297.067732 -207.110076)
		(width 0.14478)
		(layer "In11.Cu")
		(net "M_F_CPU0_SA_DQ<8>")
	)
	(segment
		(start 319.100454 -218.61907)
		(end 319.100454 -221.368366)
		(width 0.14478)
		(layer "In11.Cu")
		(net "M_F_CPU0_SA_DQ<8>")
	)
	(segment
		(start 284.065472 -206.64297)
		(end 284.22854 -206.479902)
		(width 0.14478)
		(layer "In11.Cu")
		(net "M_F_CPU0_SA_DQ<8>")
	)
	(segment
		(start 272.288 -207.335882)
		(end 272.288 -207.273144)
		(width 0.14478)
		(layer "In11.Cu")
		(net "M_F_CPU0_SA_DQ<8>")
	)
	(segment
		(start 308.383178 -207.032352)
		(end 308.383178 -207.901794)
		(width 0.14478)
		(layer "In11.Cu")
		(net "M_F_CPU0_SA_DQ<8>")
	)
	(segment
		(start 280.988262 -207.110076)
		(end 281.15133 -207.273144)
		(width 0.14478)
		(layer "In11.Cu")
		(net "M_F_CPU0_SA_DQ<8>")
	)
	(segment
		(start 291.968682 -206.260192)
		(end 293.507922 -206.260192)
		(width 0.14478)
		(layer "In11.Cu")
		(net "M_F_CPU0_SA_DQ<8>")
	)
	(segment
		(start 274.754848 -207.110076)
		(end 275.604732 -206.260192)
		(width 0.14478)
		(layer "In11.Cu")
		(net "M_F_CPU0_SA_DQ<8>")
	)
	(segment
		(start 303.655984 -207.110076)
		(end 303.819052 -207.273144)
		(width 0.14478)
		(layer "In11.Cu")
		(net "M_F_CPU0_SA_DQ<8>")
	)
	(segment
		(start 283.17317 -206.260192)
		(end 283.508958 -206.260192)
		(width 0.14478)
		(layer "In11.Cu")
		(net "M_F_CPU0_SA_DQ<8>")
	)
	(segment
		(start 289.211258 -207.49895)
		(end 289.374326 -207.335882)
		(width 0.14478)
		(layer "In11.Cu")
		(net "M_F_CPU0_SA_DQ<8>")
	)
	(segment
		(start 284.22854 -206.42326)
		(end 284.391608 -206.260192)
		(width 0.14478)
		(layer "In11.Cu")
		(net "M_F_CPU0_SA_DQ<8>")
	)
	(segment
		(start 304.538634 -207.110076)
		(end 304.894742 -207.110076)
		(width 0.14478)
		(layer "In11.Cu")
		(net "M_F_CPU0_SA_DQ<8>")
	)
	(segment
		(start 283.508958 -206.260192)
		(end 283.672026 -206.42326)
		(width 0.14478)
		(layer "In11.Cu")
		(net "M_F_CPU0_SA_DQ<8>")
	)
	(segment
		(start 299.177964 -206.65059)
		(end 299.341032 -206.487522)
		(width 0.14478)
		(layer "In11.Cu")
		(net "M_F_CPU0_SA_DQ<8>")
	)
	(segment
		(start 274.178522 -207.273144)
		(end 274.34159 -207.110076)
		(width 0.14478)
		(layer "In11.Cu")
		(net "M_F_CPU0_SA_DQ<8>")
	)
	(segment
		(start 288.817812 -207.273144)
		(end 288.817812 -207.335882)
		(width 0.14478)
		(layer "In11.Cu")
		(net "M_F_CPU0_SA_DQ<8>")
	)
	(segment
		(start 319.100454 -221.368366)
		(end 324.035166 -226.303078)
		(width 0.14478)
		(layer "In11.Cu")
		(net "M_F_CPU0_SA_DQ<8>")
	)
	(segment
		(start 291.805614 -206.42326)
		(end 291.968682 -206.260192)
		(width 0.14478)
		(layer "In11.Cu")
		(net "M_F_CPU0_SA_DQ<8>")
	)
	(segment
		(start 306.413916 -206.42326)
		(end 306.413916 -206.487522)
		(width 0.14478)
		(layer "In11.Cu")
		(net "M_F_CPU0_SA_DQ<8>")
	)
	(segment
		(start 306.250848 -206.260192)
		(end 306.413916 -206.42326)
		(width 0.14478)
		(layer "In11.Cu")
		(net "M_F_CPU0_SA_DQ<8>")
	)
	(segment
		(start 296.34815 -207.340962)
		(end 296.511218 -207.50403)
		(width 0.14478)
		(layer "In11.Cu")
		(net "M_F_CPU0_SA_DQ<8>")
	)
	(segment
		(start 275.925788 -206.260192)
		(end 276.088856 -206.42326)
		(width 0.14478)
		(layer "In11.Cu")
		(net "M_F_CPU0_SA_DQ<8>")
	)
	(segment
		(start 302.869092 -207.49133)
		(end 303.09947 -207.49133)
		(width 0.14478)
		(layer "In11.Cu")
		(net "M_F_CPU0_SA_DQ<8>")
	)
	(segment
		(start 308.383178 -207.901794)
		(end 319.100454 -218.61907)
		(width 0.14478)
		(layer "In11.Cu")
		(net "M_F_CPU0_SA_DQ<8>")
	)
	(segment
		(start 331.33411 -230.226616)
		(end 331.342492 -230.231442)
		(width 0.0889)
		(layer "In11.Cu")
		(net "M_F_CPU0_SA_DQ<8>")
	)
	(segment
		(start 299.341032 -206.487522)
		(end 299.341032 -206.42326)
		(width 0.14478)
		(layer "In11.Cu")
		(net "M_F_CPU0_SA_DQ<8>")
	)
	(segment
		(start 306.413916 -206.487522)
		(end 306.576984 -206.65059)
		(width 0.14478)
		(layer "In11.Cu")
		(net "M_F_CPU0_SA_DQ<8>")
	)
	(segment
		(start 306.97043 -206.42326)
		(end 307.133498 -206.260192)
		(width 0.14478)
		(layer "In11.Cu")
		(net "M_F_CPU0_SA_DQ<8>")
	)
	(segment
		(start 271.731486 -207.254856)
		(end 271.731486 -207.335882)
		(width 0.14478)
		(layer "In11.Cu")
		(net "M_F_CPU0_SA_DQ<8>")
	)
	(segment
		(start 288.817812 -207.335882)
		(end 288.98088 -207.49895)
		(width 0.14478)
		(layer "In11.Cu")
		(net "M_F_CPU0_SA_DQ<8>")
	)
	(segment
		(start 296.34815 -207.273144)
		(end 296.34815 -207.340962)
		(width 0.14478)
		(layer "In11.Cu")
		(net "M_F_CPU0_SA_DQ<8>")
	)
	(segment
		(start 303.425606 -207.110076)
		(end 303.655984 -207.110076)
		(width 0.14478)
		(layer "In11.Cu")
		(net "M_F_CPU0_SA_DQ<8>")
	)
	(segment
		(start 306.807362 -206.65059)
		(end 306.97043 -206.487522)
		(width 0.14478)
		(layer "In11.Cu")
		(net "M_F_CPU0_SA_DQ<8>")
	)
	(segment
		(start 296.741596 -207.50403)
		(end 296.904664 -207.340962)
		(width 0.14478)
		(layer "In11.Cu")
		(net "M_F_CPU0_SA_DQ<8>")
	)
	(segment
		(start 289.883088 -207.110076)
		(end 290.732972 -206.260192)
		(width 0.14478)
		(layer "In11.Cu")
		(net "M_F_CPU0_SA_DQ<8>")
	)
	(segment
		(start 326.303894 -229.60965)
		(end 326.939148 -229.60965)
		(width 0.0889)
		(layer "In11.Cu")
		(net "M_F_CPU0_SA_DQ<8>")
	)
	(segment
		(start 296.904664 -207.340962)
		(end 296.904664 -207.273144)
		(width 0.14478)
		(layer "In11.Cu")
		(net "M_F_CPU0_SA_DQ<8>")
	)
	(segment
		(start 291.2491 -206.42326)
		(end 291.2491 -206.479902)
		(width 0.14478)
		(layer "In11.Cu")
		(net "M_F_CPU0_SA_DQ<8>")
	)
	(segment
		(start 307.611018 -206.260192)
		(end 308.383178 -207.032352)
		(width 0.14478)
		(layer "In11.Cu")
		(net "M_F_CPU0_SA_DQ<8>")
	)
	(segment
		(start 296.511218 -207.50403)
		(end 296.741596 -207.50403)
		(width 0.14478)
		(layer "In11.Cu")
		(net "M_F_CPU0_SA_DQ<8>")
	)
	(segment
		(start 291.642546 -206.64297)
		(end 291.805614 -206.479902)
		(width 0.14478)
		(layer "In11.Cu")
		(net "M_F_CPU0_SA_DQ<8>")
	)
	(segment
		(start 297.389042 -207.110076)
		(end 298.238926 -206.260192)
		(width 0.14478)
		(layer "In11.Cu")
		(net "M_F_CPU0_SA_DQ<8>")
	)
	(segment
		(start 303.98212 -207.49133)
		(end 304.212498 -207.49133)
		(width 0.14478)
		(layer "In11.Cu")
		(net "M_F_CPU0_SA_DQ<8>")
	)
	(segment
		(start 298.784518 -206.42326)
		(end 298.784518 -206.487522)
		(width 0.14478)
		(layer "In11.Cu")
		(net "M_F_CPU0_SA_DQ<8>")
	)
	(segment
		(start 283.672026 -206.479902)
		(end 283.835094 -206.64297)
		(width 0.14478)
		(layer "In11.Cu")
		(net "M_F_CPU0_SA_DQ<8>")
	)
	(segment
		(start 281.707844 -207.273144)
		(end 281.870912 -207.110076)
		(width 0.14478)
		(layer "In11.Cu")
		(net "M_F_CPU0_SA_DQ<8>")
	)
	(arc
		(start 327.497186 -230.167688)
		(mid 327.533739 -230.199671)
		(end 327.574148 -230.226616)
		(width 0.0889)
		(layer "In11.Cu")
		(net "M_F_CPU0_SA_DQ<8>")
	)
	(arc
		(start 328.514202 -230.226616)
		(mid 328.701146 -230.276871)
		(end 328.88809 -230.226616)
		(width 0.0889)
		(layer "In11.Cu")
		(net "M_F_CPU0_SA_DQ<8>")
	)
	(arc
		(start 329.828144 -230.226616)
		(mid 330.1111 -230.150473)
		(end 330.394056 -230.226616)
		(width 0.0889)
		(layer "In11.Cu")
		(net "M_F_CPU0_SA_DQ<8>")
	)
	(arc
		(start 330.768198 -230.226616)
		(mid 331.051154 -230.150473)
		(end 331.33411 -230.226616)
		(width 0.0889)
		(layer "In11.Cu")
		(net "M_F_CPU0_SA_DQ<8>")
	)
	(arc
		(start 328.88809 -230.226616)
		(mid 329.171046 -230.150473)
		(end 329.454002 -230.226616)
		(width 0.0889)
		(layer "In11.Cu")
		(net "M_F_CPU0_SA_DQ<8>")
	)
	(arc
		(start 327.94829 -230.226616)
		(mid 328.231246 -230.150473)
		(end 328.514202 -230.226616)
		(width 0.0889)
		(layer "In11.Cu")
		(net "M_F_CPU0_SA_DQ<8>")
	)
	(arc
		(start 327.586086 -230.233474)
		(mid 327.768087 -230.277007)
		(end 327.94829 -230.226616)
		(width 0.0889)
		(layer "In11.Cu")
		(net "M_F_CPU0_SA_DQ<8>")
	)
	(arc
		(start 329.454002 -230.226616)
		(mid 329.636253 -230.276966)
		(end 329.819762 -230.231442)
		(width 0.0889)
		(layer "In11.Cu")
		(net "M_F_CPU0_SA_DQ<8>")
	)
	(arc
		(start 331.708252 -230.226616)
		(mid 331.955965 -230.15143)
		(end 332.211172 -230.194866)
		(width 0.0889)
		(layer "In11.Cu")
		(net "M_F_CPU0_SA_DQ<8>")
	)
	(arc
		(start 331.342492 -230.231442)
		(mid 331.526 -230.276936)
		(end 331.708252 -230.226616)
		(width 0.0889)
		(layer "In11.Cu")
		(net "M_F_CPU0_SA_DQ<8>")
	)
	(arc
		(start 330.402438 -230.231442)
		(mid 330.585946 -230.276936)
		(end 330.768198 -230.226616)
		(width 0.0889)
		(layer "In11.Cu")
		(net "M_F_CPU0_SA_DQ<8>")
	)
	(segment
		(start 333.868014 -230.169974)
		(end 333.401162 -229.904036)
		(width 0.10668)
		(layer "F.Cu")
		(net "M_F_CPU0_SA_DQ<7>")
	)
	(segment
		(start 265.54811 -205.834996)
		(end 265.973306 -206.260192)
		(width 0.14478)
		(layer "In11.Cu")
		(net "M_F_CPU0_SA_DQ<7>")
	)
	(segment
		(start 274.667726 -206.260192)
		(end 275.517864 -205.410054)
		(width 0.14478)
		(layer "In11.Cu")
		(net "M_F_CPU0_SA_DQ<7>")
	)
	(segment
		(start 266.683744 -205.528418)
		(end 266.846812 -205.36535)
		(width 0.14478)
		(layer "In11.Cu")
		(net "M_F_CPU0_SA_DQ<7>")
	)
	(segment
		(start 309.152798 -206.935578)
		(end 309.152798 -207.869282)
		(width 0.14478)
		(layer "In11.Cu")
		(net "M_F_CPU0_SA_DQ<7>")
	)
	(segment
		(start 286.903414 -206.260192)
		(end 289.832034 -206.260192)
		(width 0.14478)
		(layer "In11.Cu")
		(net "M_F_CPU0_SA_DQ<7>")
	)
	(segment
		(start 267.403326 -206.260192)
		(end 267.633704 -206.260192)
		(width 0.14478)
		(layer "In11.Cu")
		(net "M_F_CPU0_SA_DQ<7>")
	)
	(segment
		(start 301.945294 -206.260192)
		(end 304.8762 -206.260192)
		(width 0.14478)
		(layer "In11.Cu")
		(net "M_F_CPU0_SA_DQ<7>")
	)
	(segment
		(start 319.662302 -221.139258)
		(end 323.798438 -225.275394)
		(width 0.14478)
		(layer "In11.Cu")
		(net "M_F_CPU0_SA_DQ<7>")
	)
	(segment
		(start 304.8762 -206.260192)
		(end 305.726338 -205.410054)
		(width 0.14478)
		(layer "In11.Cu")
		(net "M_F_CPU0_SA_DQ<7>")
	)
	(segment
		(start 307.627274 -205.410054)
		(end 309.152798 -206.935578)
		(width 0.14478)
		(layer "In11.Cu")
		(net "M_F_CPU0_SA_DQ<7>")
	)
	(segment
		(start 324.581774 -226.05873)
		(end 324.581774 -226.94773)
		(width 0.0889)
		(layer "In11.Cu")
		(net "M_F_CPU0_SA_DQ<7>")
	)
	(segment
		(start 282.298648 -206.260192)
		(end 283.148786 -205.410054)
		(width 0.14478)
		(layer "In11.Cu")
		(net "M_F_CPU0_SA_DQ<7>")
	)
	(segment
		(start 266.520676 -206.260192)
		(end 266.683744 -206.097124)
		(width 0.14478)
		(layer "In11.Cu")
		(net "M_F_CPU0_SA_DQ<7>")
	)
	(segment
		(start 266.846812 -205.36535)
		(end 267.07719 -205.36535)
		(width 0.14478)
		(layer "In11.Cu")
		(net "M_F_CPU0_SA_DQ<7>")
	)
	(segment
		(start 323.798438 -225.275394)
		(end 324.581774 -226.05873)
		(width 0.0889)
		(layer "In11.Cu")
		(net "M_F_CPU0_SA_DQ<7>")
	)
	(segment
		(start 267.796772 -206.097124)
		(end 267.796772 -205.528418)
		(width 0.14478)
		(layer "In11.Cu")
		(net "M_F_CPU0_SA_DQ<7>")
	)
	(segment
		(start 331.33411 -229.58171)
		(end 331.342492 -229.576884)
		(width 0.0889)
		(layer "In11.Cu")
		(net "M_F_CPU0_SA_DQ<7>")
	)
	(segment
		(start 267.240258 -206.097124)
		(end 267.403326 -206.260192)
		(width 0.14478)
		(layer "In11.Cu")
		(net "M_F_CPU0_SA_DQ<7>")
	)
	(segment
		(start 278.483822 -205.410054)
		(end 279.33396 -206.260192)
		(width 0.14478)
		(layer "In11.Cu")
		(net "M_F_CPU0_SA_DQ<7>")
	)
	(segment
		(start 267.95984 -205.36535)
		(end 268.190218 -205.36535)
		(width 0.14478)
		(layer "In11.Cu")
		(net "M_F_CPU0_SA_DQ<7>")
	)
	(segment
		(start 267.633704 -206.260192)
		(end 267.796772 -206.097124)
		(width 0.14478)
		(layer "In11.Cu")
		(net "M_F_CPU0_SA_DQ<7>")
	)
	(segment
		(start 294.40886 -206.260192)
		(end 297.32986 -206.260192)
		(width 0.14478)
		(layer "In11.Cu")
		(net "M_F_CPU0_SA_DQ<7>")
	)
	(segment
		(start 325.176134 -227.54209)
		(end 325.176134 -227.67925)
		(width 0.0889)
		(layer "In11.Cu")
		(net "M_F_CPU0_SA_DQ<7>")
	)
	(segment
		(start 329.819762 -229.576884)
		(end 329.828144 -229.58171)
		(width 0.0889)
		(layer "In11.Cu")
		(net "M_F_CPU0_SA_DQ<7>")
	)
	(segment
		(start 301.095156 -205.410054)
		(end 301.945294 -206.260192)
		(width 0.14478)
		(layer "In11.Cu")
		(net "M_F_CPU0_SA_DQ<7>")
	)
	(segment
		(start 268.190218 -205.36535)
		(end 268.353286 -205.528418)
		(width 0.14478)
		(layer "In11.Cu")
		(net "M_F_CPU0_SA_DQ<7>")
	)
	(segment
		(start 330.394056 -229.58171)
		(end 330.402438 -229.576884)
		(width 0.0889)
		(layer "In11.Cu")
		(net "M_F_CPU0_SA_DQ<7>")
	)
	(segment
		(start 265.973306 -206.260192)
		(end 266.520676 -206.260192)
		(width 0.14478)
		(layer "In11.Cu")
		(net "M_F_CPU0_SA_DQ<7>")
	)
	(segment
		(start 275.517864 -205.410054)
		(end 278.483822 -205.410054)
		(width 0.14478)
		(layer "In11.Cu")
		(net "M_F_CPU0_SA_DQ<7>")
	)
	(segment
		(start 268.353286 -206.097124)
		(end 268.516354 -206.260192)
		(width 0.14478)
		(layer "In11.Cu")
		(net "M_F_CPU0_SA_DQ<7>")
	)
	(segment
		(start 290.682172 -205.410054)
		(end 293.558722 -205.410054)
		(width 0.14478)
		(layer "In11.Cu")
		(net "M_F_CPU0_SA_DQ<7>")
	)
	(segment
		(start 305.726338 -205.410054)
		(end 307.627274 -205.410054)
		(width 0.14478)
		(layer "In11.Cu")
		(net "M_F_CPU0_SA_DQ<7>")
	)
	(segment
		(start 297.32986 -206.260192)
		(end 298.179998 -205.410054)
		(width 0.14478)
		(layer "In11.Cu")
		(net "M_F_CPU0_SA_DQ<7>")
	)
	(segment
		(start 326.227694 -228.73081)
		(end 326.509634 -228.73081)
		(width 0.0889)
		(layer "In11.Cu")
		(net "M_F_CPU0_SA_DQ<7>")
	)
	(segment
		(start 267.240258 -205.528418)
		(end 267.240258 -206.097124)
		(width 0.14478)
		(layer "In11.Cu")
		(net "M_F_CPU0_SA_DQ<7>")
	)
	(segment
		(start 333.532734 -229.555548)
		(end 333.555086 -229.638606)
		(width 0.0889)
		(layer "In11.Cu")
		(net "M_F_CPU0_SA_DQ<7>")
	)
	(segment
		(start 283.148786 -205.410054)
		(end 286.053276 -205.410054)
		(width 0.14478)
		(layer "In11.Cu")
		(net "M_F_CPU0_SA_DQ<7>")
	)
	(segment
		(start 267.07719 -205.36535)
		(end 267.240258 -205.528418)
		(width 0.14478)
		(layer "In11.Cu")
		(net "M_F_CPU0_SA_DQ<7>")
	)
	(segment
		(start 319.662302 -218.378786)
		(end 319.662302 -221.139258)
		(width 0.14478)
		(layer "In11.Cu")
		(net "M_F_CPU0_SA_DQ<7>")
	)
	(segment
		(start 327.309734 -229.53091)
		(end 327.761092 -229.53091)
		(width 0.0889)
		(layer "In11.Cu")
		(net "M_F_CPU0_SA_DQ<7>")
	)
	(segment
		(start 279.33396 -206.260192)
		(end 282.298648 -206.260192)
		(width 0.14478)
		(layer "In11.Cu")
		(net "M_F_CPU0_SA_DQ<7>")
	)
	(segment
		(start 267.796772 -205.528418)
		(end 267.95984 -205.36535)
		(width 0.14478)
		(layer "In11.Cu")
		(net "M_F_CPU0_SA_DQ<7>")
	)
	(segment
		(start 293.558722 -205.410054)
		(end 294.40886 -206.260192)
		(width 0.14478)
		(layer "In11.Cu")
		(net "M_F_CPU0_SA_DQ<7>")
	)
	(segment
		(start 326.509634 -228.73081)
		(end 327.309734 -229.53091)
		(width 0.0889)
		(layer "In11.Cu")
		(net "M_F_CPU0_SA_DQ<7>")
	)
	(segment
		(start 324.581774 -226.94773)
		(end 325.176134 -227.54209)
		(width 0.0889)
		(layer "In11.Cu")
		(net "M_F_CPU0_SA_DQ<7>")
	)
	(segment
		(start 325.176134 -227.67925)
		(end 326.227694 -228.73081)
		(width 0.0889)
		(layer "In11.Cu")
		(net "M_F_CPU0_SA_DQ<7>")
	)
	(segment
		(start 333.555086 -229.638606)
		(end 333.401162 -229.904036)
		(width 0.0889)
		(layer "In11.Cu")
		(net "M_F_CPU0_SA_DQ<7>")
	)
	(segment
		(start 268.516354 -206.260192)
		(end 274.667726 -206.260192)
		(width 0.14478)
		(layer "In11.Cu")
		(net "M_F_CPU0_SA_DQ<7>")
	)
	(segment
		(start 286.053276 -205.410054)
		(end 286.903414 -206.260192)
		(width 0.14478)
		(layer "In11.Cu")
		(net "M_F_CPU0_SA_DQ<7>")
	)
	(segment
		(start 268.353286 -205.528418)
		(end 268.353286 -206.097124)
		(width 0.14478)
		(layer "In11.Cu")
		(net "M_F_CPU0_SA_DQ<7>")
	)
	(segment
		(start 266.683744 -206.097124)
		(end 266.683744 -205.528418)
		(width 0.14478)
		(layer "In11.Cu")
		(net "M_F_CPU0_SA_DQ<7>")
	)
	(segment
		(start 298.179998 -205.410054)
		(end 301.095156 -205.410054)
		(width 0.14478)
		(layer "In11.Cu")
		(net "M_F_CPU0_SA_DQ<7>")
	)
	(segment
		(start 289.832034 -206.260192)
		(end 290.682172 -205.410054)
		(width 0.14478)
		(layer "In11.Cu")
		(net "M_F_CPU0_SA_DQ<7>")
	)
	(segment
		(start 309.152798 -207.869282)
		(end 319.662302 -218.378786)
		(width 0.14478)
		(layer "In11.Cu")
		(net "M_F_CPU0_SA_DQ<7>")
	)
	(arc
		(start 333.213964 -229.58171)
		(mid 333.370402 -229.532705)
		(end 333.532734 -229.555548)
		(width 0.0889)
		(layer "In11.Cu")
		(net "M_F_CPU0_SA_DQ<7>")
	)
	(arc
		(start 332.648052 -229.58171)
		(mid 332.931008 -229.657887)
		(end 333.213964 -229.58171)
		(width 0.0889)
		(layer "In11.Cu")
		(net "M_F_CPU0_SA_DQ<7>")
	)
	(arc
		(start 329.828144 -229.58171)
		(mid 330.1111 -229.657887)
		(end 330.394056 -229.58171)
		(width 0.0889)
		(layer "In11.Cu")
		(net "M_F_CPU0_SA_DQ<7>")
	)
	(arc
		(start 327.761092 -229.53091)
		(mid 327.858045 -229.543941)
		(end 327.94829 -229.58171)
		(width 0.0889)
		(layer "In11.Cu")
		(net "M_F_CPU0_SA_DQ<7>")
	)
	(arc
		(start 332.274164 -229.58171)
		(mid 332.461108 -229.531421)
		(end 332.648052 -229.58171)
		(width 0.0889)
		(layer "In11.Cu")
		(net "M_F_CPU0_SA_DQ<7>")
	)
	(arc
		(start 330.402438 -229.576884)
		(mid 330.585946 -229.531359)
		(end 330.768198 -229.58171)
		(width 0.0889)
		(layer "In11.Cu")
		(net "M_F_CPU0_SA_DQ<7>")
	)
	(arc
		(start 327.94829 -229.58171)
		(mid 328.231246 -229.657887)
		(end 328.514202 -229.58171)
		(width 0.0889)
		(layer "In11.Cu")
		(net "M_F_CPU0_SA_DQ<7>")
	)
	(arc
		(start 328.514202 -229.58171)
		(mid 328.701146 -229.531421)
		(end 328.88809 -229.58171)
		(width 0.0889)
		(layer "In11.Cu")
		(net "M_F_CPU0_SA_DQ<7>")
	)
	(arc
		(start 330.768198 -229.58171)
		(mid 331.051154 -229.657887)
		(end 331.33411 -229.58171)
		(width 0.0889)
		(layer "In11.Cu")
		(net "M_F_CPU0_SA_DQ<7>")
	)
	(arc
		(start 328.88809 -229.58171)
		(mid 329.171046 -229.657887)
		(end 329.454002 -229.58171)
		(width 0.0889)
		(layer "In11.Cu")
		(net "M_F_CPU0_SA_DQ<7>")
	)
	(arc
		(start 331.708252 -229.58171)
		(mid 331.991208 -229.657887)
		(end 332.274164 -229.58171)
		(width 0.0889)
		(layer "In11.Cu")
		(net "M_F_CPU0_SA_DQ<7>")
	)
	(arc
		(start 331.342492 -229.576884)
		(mid 331.526 -229.531359)
		(end 331.708252 -229.58171)
		(width 0.0889)
		(layer "In11.Cu")
		(net "M_F_CPU0_SA_DQ<7>")
	)
	(arc
		(start 329.454002 -229.58171)
		(mid 329.636253 -229.531326)
		(end 329.819762 -229.576884)
		(width 0.0889)
		(layer "In11.Cu")
		(net "M_F_CPU0_SA_DQ<7>")
	)
	(segment
		(start 332.45806 -229.360222)
		(end 331.991208 -229.094284)
		(width 0.10668)
		(layer "F.Cu")
		(net "M_F_CPU0_SA_DQ<6>")
	)
	(segment
		(start 325.455534 -226.30257)
		(end 325.734934 -226.977448)
		(width 0.0889)
		(layer "In11.Cu")
		(net "M_F_CPU0_SA_DQ<6>")
	)
	(segment
		(start 332.12278 -228.745542)
		(end 332.145132 -228.828854)
		(width 0.0889)
		(layer "In11.Cu")
		(net "M_F_CPU0_SA_DQ<6>")
	)
	(segment
		(start 275.517864 -203.710032)
		(end 278.483822 -203.710032)
		(width 0.14478)
		(layer "In11.Cu")
		(net "M_F_CPU0_SA_DQ<6>")
	)
	(segment
		(start 267.014706 -204.56017)
		(end 267.177774 -204.397102)
		(width 0.14478)
		(layer "In11.Cu")
		(net "M_F_CPU0_SA_DQ<6>")
	)
	(segment
		(start 326.245474 -228.16693)
		(end 326.712326 -228.16693)
		(width 0.0889)
		(layer "In11.Cu")
		(net "M_F_CPU0_SA_DQ<6>")
	)
	(segment
		(start 328.984102 -228.771704)
		(end 328.992484 -228.766878)
		(width 0.0889)
		(layer "In11.Cu")
		(net "M_F_CPU0_SA_DQ<6>")
	)
	(segment
		(start 326.712326 -228.16693)
		(end 327.3933 -228.847904)
		(width 0.0889)
		(layer "In11.Cu")
		(net "M_F_CPU0_SA_DQ<6>")
	)
	(segment
		(start 301.945294 -204.56017)
		(end 304.8762 -204.56017)
		(width 0.14478)
		(layer "In11.Cu")
		(net "M_F_CPU0_SA_DQ<6>")
	)
	(segment
		(start 304.8762 -204.56017)
		(end 305.726338 -203.710032)
		(width 0.14478)
		(layer "In11.Cu")
		(net "M_F_CPU0_SA_DQ<6>")
	)
	(segment
		(start 310.065674 -206.023972)
		(end 310.065674 -207.367378)
		(width 0.14478)
		(layer "In11.Cu")
		(net "M_F_CPU0_SA_DQ<6>")
	)
	(segment
		(start 298.179998 -203.710032)
		(end 301.095156 -203.710032)
		(width 0.14478)
		(layer "In11.Cu")
		(net "M_F_CPU0_SA_DQ<6>")
	)
	(segment
		(start 267.177774 -203.798678)
		(end 267.340842 -203.63561)
		(width 0.14478)
		(layer "In11.Cu")
		(net "M_F_CPU0_SA_DQ<6>")
	)
	(segment
		(start 331.229716 -228.766878)
		(end 331.238098 -228.771704)
		(width 0.0889)
		(layer "In11.Cu")
		(net "M_F_CPU0_SA_DQ<6>")
	)
	(segment
		(start 310.065674 -207.367378)
		(end 320.662554 -217.964258)
		(width 0.14478)
		(layer "In11.Cu")
		(net "M_F_CPU0_SA_DQ<6>")
	)
	(segment
		(start 265.54811 -204.134974)
		(end 265.973306 -204.56017)
		(width 0.14478)
		(layer "In11.Cu")
		(net "M_F_CPU0_SA_DQ<6>")
	)
	(segment
		(start 286.053276 -203.710032)
		(end 286.903414 -204.56017)
		(width 0.14478)
		(layer "In11.Cu")
		(net "M_F_CPU0_SA_DQ<6>")
	)
	(segment
		(start 324.579234 -224.64141)
		(end 324.579234 -225.42627)
		(width 0.0889)
		(layer "In11.Cu")
		(net "M_F_CPU0_SA_DQ<6>")
	)
	(segment
		(start 267.177774 -204.397102)
		(end 267.177774 -203.798678)
		(width 0.14478)
		(layer "In11.Cu")
		(net "M_F_CPU0_SA_DQ<6>")
	)
	(segment
		(start 327.3933 -228.847904)
		(end 327.761092 -228.847904)
		(width 0.0889)
		(layer "In11.Cu")
		(net "M_F_CPU0_SA_DQ<6>")
	)
	(segment
		(start 325.734934 -227.65639)
		(end 326.245474 -228.16693)
		(width 0.0889)
		(layer "In11.Cu")
		(net "M_F_CPU0_SA_DQ<6>")
	)
	(segment
		(start 282.298648 -204.56017)
		(end 283.148786 -203.710032)
		(width 0.14478)
		(layer "In11.Cu")
		(net "M_F_CPU0_SA_DQ<6>")
	)
	(segment
		(start 324.359016 -224.421192)
		(end 324.579234 -224.64141)
		(width 0.0889)
		(layer "In11.Cu")
		(net "M_F_CPU0_SA_DQ<6>")
	)
	(segment
		(start 307.751734 -203.710032)
		(end 310.065674 -206.023972)
		(width 0.14478)
		(layer "In11.Cu")
		(net "M_F_CPU0_SA_DQ<6>")
	)
	(segment
		(start 267.340842 -203.63561)
		(end 267.57122 -203.63561)
		(width 0.14478)
		(layer "In11.Cu")
		(net "M_F_CPU0_SA_DQ<6>")
	)
	(segment
		(start 267.734288 -203.798678)
		(end 267.734288 -204.397102)
		(width 0.14478)
		(layer "In11.Cu")
		(net "M_F_CPU0_SA_DQ<6>")
	)
	(segment
		(start 265.973306 -204.56017)
		(end 267.014706 -204.56017)
		(width 0.14478)
		(layer "In11.Cu")
		(net "M_F_CPU0_SA_DQ<6>")
	)
	(segment
		(start 268.290802 -203.798678)
		(end 268.45387 -203.63561)
		(width 0.14478)
		(layer "In11.Cu")
		(net "M_F_CPU0_SA_DQ<6>")
	)
	(segment
		(start 301.095156 -203.710032)
		(end 301.945294 -204.56017)
		(width 0.14478)
		(layer "In11.Cu")
		(net "M_F_CPU0_SA_DQ<6>")
	)
	(segment
		(start 332.145132 -228.828854)
		(end 331.991208 -229.094284)
		(width 0.0889)
		(layer "In11.Cu")
		(net "M_F_CPU0_SA_DQ<6>")
	)
	(segment
		(start 268.45387 -203.63561)
		(end 268.684248 -203.63561)
		(width 0.14478)
		(layer "In11.Cu")
		(net "M_F_CPU0_SA_DQ<6>")
	)
	(segment
		(start 268.847316 -203.798678)
		(end 268.847316 -204.397102)
		(width 0.14478)
		(layer "In11.Cu")
		(net "M_F_CPU0_SA_DQ<6>")
	)
	(segment
		(start 268.847316 -204.397102)
		(end 269.010384 -204.56017)
		(width 0.14478)
		(layer "In11.Cu")
		(net "M_F_CPU0_SA_DQ<6>")
	)
	(segment
		(start 268.127734 -204.56017)
		(end 268.290802 -204.397102)
		(width 0.14478)
		(layer "In11.Cu")
		(net "M_F_CPU0_SA_DQ<6>")
	)
	(segment
		(start 279.33396 -204.56017)
		(end 282.298648 -204.56017)
		(width 0.14478)
		(layer "In11.Cu")
		(net "M_F_CPU0_SA_DQ<6>")
	)
	(segment
		(start 274.667726 -204.56017)
		(end 275.517864 -203.710032)
		(width 0.14478)
		(layer "In11.Cu")
		(net "M_F_CPU0_SA_DQ<6>")
	)
	(segment
		(start 267.897356 -204.56017)
		(end 268.127734 -204.56017)
		(width 0.14478)
		(layer "In11.Cu")
		(net "M_F_CPU0_SA_DQ<6>")
	)
	(segment
		(start 294.40886 -204.56017)
		(end 297.32986 -204.56017)
		(width 0.14478)
		(layer "In11.Cu")
		(net "M_F_CPU0_SA_DQ<6>")
	)
	(segment
		(start 305.726338 -203.710032)
		(end 307.751734 -203.710032)
		(width 0.14478)
		(layer "In11.Cu")
		(net "M_F_CPU0_SA_DQ<6>")
	)
	(segment
		(start 290.682172 -203.710032)
		(end 293.558722 -203.710032)
		(width 0.14478)
		(layer "In11.Cu")
		(net "M_F_CPU0_SA_DQ<6>")
	)
	(segment
		(start 297.32986 -204.56017)
		(end 298.179998 -203.710032)
		(width 0.14478)
		(layer "In11.Cu")
		(net "M_F_CPU0_SA_DQ<6>")
	)
	(segment
		(start 289.832034 -204.56017)
		(end 290.682172 -203.710032)
		(width 0.14478)
		(layer "In11.Cu")
		(net "M_F_CPU0_SA_DQ<6>")
	)
	(segment
		(start 320.662554 -220.72473)
		(end 324.359016 -224.421192)
		(width 0.14478)
		(layer "In11.Cu")
		(net "M_F_CPU0_SA_DQ<6>")
	)
	(segment
		(start 328.409808 -228.766878)
		(end 328.41819 -228.771704)
		(width 0.0889)
		(layer "In11.Cu")
		(net "M_F_CPU0_SA_DQ<6>")
	)
	(segment
		(start 278.483822 -203.710032)
		(end 279.33396 -204.56017)
		(width 0.14478)
		(layer "In11.Cu")
		(net "M_F_CPU0_SA_DQ<6>")
	)
	(segment
		(start 267.57122 -203.63561)
		(end 267.734288 -203.798678)
		(width 0.14478)
		(layer "In11.Cu")
		(net "M_F_CPU0_SA_DQ<6>")
	)
	(segment
		(start 325.734934 -226.977448)
		(end 325.734934 -227.65639)
		(width 0.0889)
		(layer "In11.Cu")
		(net "M_F_CPU0_SA_DQ<6>")
	)
	(segment
		(start 286.903414 -204.56017)
		(end 289.832034 -204.56017)
		(width 0.14478)
		(layer "In11.Cu")
		(net "M_F_CPU0_SA_DQ<6>")
	)
	(segment
		(start 283.148786 -203.710032)
		(end 286.053276 -203.710032)
		(width 0.14478)
		(layer "In11.Cu")
		(net "M_F_CPU0_SA_DQ<6>")
	)
	(segment
		(start 324.579234 -225.42627)
		(end 325.455534 -226.30257)
		(width 0.0889)
		(layer "In11.Cu")
		(net "M_F_CPU0_SA_DQ<6>")
	)
	(segment
		(start 269.010384 -204.56017)
		(end 274.667726 -204.56017)
		(width 0.14478)
		(layer "In11.Cu")
		(net "M_F_CPU0_SA_DQ<6>")
	)
	(segment
		(start 268.290802 -204.397102)
		(end 268.290802 -203.798678)
		(width 0.14478)
		(layer "In11.Cu")
		(net "M_F_CPU0_SA_DQ<6>")
	)
	(segment
		(start 268.684248 -203.63561)
		(end 268.847316 -203.798678)
		(width 0.14478)
		(layer "In11.Cu")
		(net "M_F_CPU0_SA_DQ<6>")
	)
	(segment
		(start 267.734288 -204.397102)
		(end 267.897356 -204.56017)
		(width 0.14478)
		(layer "In11.Cu")
		(net "M_F_CPU0_SA_DQ<6>")
	)
	(segment
		(start 320.662554 -217.964258)
		(end 320.662554 -220.72473)
		(width 0.14478)
		(layer "In11.Cu")
		(net "M_F_CPU0_SA_DQ<6>")
	)
	(segment
		(start 293.558722 -203.710032)
		(end 294.40886 -204.56017)
		(width 0.14478)
		(layer "In11.Cu")
		(net "M_F_CPU0_SA_DQ<6>")
	)
	(arc
		(start 328.992484 -228.766878)
		(mid 329.175992 -228.721384)
		(end 329.358244 -228.771704)
		(width 0.0889)
		(layer "In11.Cu")
		(net "M_F_CPU0_SA_DQ<6>")
	)
	(arc
		(start 329.358244 -228.771704)
		(mid 329.6412 -228.847881)
		(end 329.924156 -228.771704)
		(width 0.0889)
		(layer "In11.Cu")
		(net "M_F_CPU0_SA_DQ<6>")
	)
	(arc
		(start 331.238098 -228.771704)
		(mid 331.521054 -228.847881)
		(end 331.80401 -228.771704)
		(width 0.0889)
		(layer "In11.Cu")
		(net "M_F_CPU0_SA_DQ<6>")
	)
	(arc
		(start 328.044048 -228.771704)
		(mid 328.226299 -228.721354)
		(end 328.409808 -228.766878)
		(width 0.0889)
		(layer "In11.Cu")
		(net "M_F_CPU0_SA_DQ<6>")
	)
	(arc
		(start 330.863956 -228.771704)
		(mid 331.046207 -228.721354)
		(end 331.229716 -228.766878)
		(width 0.0889)
		(layer "In11.Cu")
		(net "M_F_CPU0_SA_DQ<6>")
	)
	(arc
		(start 330.298044 -228.771704)
		(mid 330.581 -228.847881)
		(end 330.863956 -228.771704)
		(width 0.0889)
		(layer "In11.Cu")
		(net "M_F_CPU0_SA_DQ<6>")
	)
	(arc
		(start 328.41819 -228.771704)
		(mid 328.701146 -228.847881)
		(end 328.984102 -228.771704)
		(width 0.0889)
		(layer "In11.Cu")
		(net "M_F_CPU0_SA_DQ<6>")
	)
	(arc
		(start 331.80401 -228.771704)
		(mid 331.960448 -228.722733)
		(end 332.12278 -228.745542)
		(width 0.0889)
		(layer "In11.Cu")
		(net "M_F_CPU0_SA_DQ<6>")
	)
	(arc
		(start 329.924156 -228.771704)
		(mid 330.1111 -228.721449)
		(end 330.298044 -228.771704)
		(width 0.0889)
		(layer "In11.Cu")
		(net "M_F_CPU0_SA_DQ<6>")
	)
	(arc
		(start 327.761092 -228.847904)
		(mid 327.907609 -228.828518)
		(end 328.044048 -228.771704)
		(width 0.0889)
		(layer "In11.Cu")
		(net "M_F_CPU0_SA_DQ<6>")
	)
	(segment
		(start 334.337914 -229.360222)
		(end 333.871062 -229.094284)
		(width 0.10668)
		(layer "F.Cu")
		(net "M_F_CPU0_SA_DQ<5>")
	)
	(segment
		(start 304.027078 -205.79969)
		(end 304.257456 -205.79969)
		(width 0.14478)
		(layer "In11.Cu")
		(net "M_F_CPU0_SA_DQ<5>")
	)
	(segment
		(start 281.839162 -205.573122)
		(end 282.00223 -205.410054)
		(width 0.14478)
		(layer "In11.Cu")
		(net "M_F_CPU0_SA_DQ<5>")
	)
	(segment
		(start 285.892748 -204.56017)
		(end 286.742632 -205.410054)
		(width 0.14478)
		(layer "In11.Cu")
		(net "M_F_CPU0_SA_DQ<5>")
	)
	(segment
		(start 284.0355 -204.95387)
		(end 284.198568 -204.790802)
		(width 0.14478)
		(layer "In11.Cu")
		(net "M_F_CPU0_SA_DQ<5>")
	)
	(segment
		(start 283.642054 -204.723238)
		(end 283.642054 -204.790802)
		(width 0.14478)
		(layer "In11.Cu")
		(net "M_F_CPU0_SA_DQ<5>")
	)
	(segment
		(start 291.008308 -204.56017)
		(end 291.171376 -204.723238)
		(width 0.14478)
		(layer "In11.Cu")
		(net "M_F_CPU0_SA_DQ<5>")
	)
	(segment
		(start 273.621754 -205.573122)
		(end 273.621754 -205.639162)
		(width 0.14478)
		(layer "In11.Cu")
		(net "M_F_CPU0_SA_DQ<5>")
	)
	(segment
		(start 306.627276 -204.955394)
		(end 306.857654 -204.955394)
		(width 0.14478)
		(layer "In11.Cu")
		(net "M_F_CPU0_SA_DQ<5>")
	)
	(segment
		(start 326.674734 -228.51999)
		(end 327.488804 -229.33406)
		(width 0.0889)
		(layer "In11.Cu")
		(net "M_F_CPU0_SA_DQ<5>")
	)
	(segment
		(start 296.486326 -205.80223)
		(end 296.716704 -205.80223)
		(width 0.14478)
		(layer "In11.Cu")
		(net "M_F_CPU0_SA_DQ<5>")
	)
	(segment
		(start 327.631298 -229.34041)
		(end 327.761346 -229.34041)
		(width 0.0889)
		(layer "In11.Cu")
		(net "M_F_CPU0_SA_DQ<5>")
	)
	(segment
		(start 303.470564 -205.410054)
		(end 303.700942 -205.410054)
		(width 0.14478)
		(layer "In11.Cu")
		(net "M_F_CPU0_SA_DQ<5>")
	)
	(segment
		(start 302.750982 -205.573122)
		(end 302.750982 -205.636622)
		(width 0.14478)
		(layer "In11.Cu")
		(net "M_F_CPU0_SA_DQ<5>")
	)
	(segment
		(start 304.420524 -205.636622)
		(end 304.420524 -205.573122)
		(width 0.14478)
		(layer "In11.Cu")
		(net "M_F_CPU0_SA_DQ<5>")
	)
	(segment
		(start 273.784822 -205.80223)
		(end 274.0152 -205.80223)
		(width 0.14478)
		(layer "In11.Cu")
		(net "M_F_CPU0_SA_DQ<5>")
	)
	(segment
		(start 286.742632 -205.410054)
		(end 288.66084 -205.410054)
		(width 0.14478)
		(layer "In11.Cu")
		(net "M_F_CPU0_SA_DQ<5>")
	)
	(segment
		(start 306.30114 -204.56017)
		(end 306.464208 -204.723238)
		(width 0.14478)
		(layer "In11.Cu")
		(net "M_F_CPU0_SA_DQ<5>")
	)
	(segment
		(start 302.587914 -205.410054)
		(end 302.750982 -205.573122)
		(width 0.14478)
		(layer "In11.Cu")
		(net "M_F_CPU0_SA_DQ<5>")
	)
	(segment
		(start 328.984102 -229.41661)
		(end 328.992484 -229.421436)
		(width 0.0889)
		(layer "In11.Cu")
		(net "M_F_CPU0_SA_DQ<5>")
	)
	(segment
		(start 271.642078 -205.180946)
		(end 271.642078 -205.639162)
		(width 0.14478)
		(layer "In11.Cu")
		(net "M_F_CPU0_SA_DQ<5>")
	)
	(segment
		(start 307.18379 -204.56017)
		(end 307.751734 -204.56017)
		(width 0.14478)
		(layer "In11.Cu")
		(net "M_F_CPU0_SA_DQ<5>")
	)
	(segment
		(start 272.198592 -205.639162)
		(end 272.198592 -205.573122)
		(width 0.14478)
		(layer "In11.Cu")
		(net "M_F_CPU0_SA_DQ<5>")
	)
	(segment
		(start 324.343014 -225.16211)
		(end 324.343014 -225.509582)
		(width 0.0889)
		(layer "In11.Cu")
		(net "M_F_CPU0_SA_DQ<5>")
	)
	(segment
		(start 284.198568 -204.723238)
		(end 284.361636 -204.56017)
		(width 0.14478)
		(layer "In11.Cu")
		(net "M_F_CPU0_SA_DQ<5>")
	)
	(segment
		(start 270.692118 -205.80223)
		(end 270.922496 -205.80223)
		(width 0.14478)
		(layer "In11.Cu")
		(net "M_F_CPU0_SA_DQ<5>")
	)
	(segment
		(start 276.808438 -204.56017)
		(end 278.410924 -204.56017)
		(width 0.14478)
		(layer "In11.Cu")
		(net "M_F_CPU0_SA_DQ<5>")
	)
	(segment
		(start 320.127376 -218.186)
		(end 320.127376 -220.946472)
		(width 0.14478)
		(layer "In11.Cu")
		(net "M_F_CPU0_SA_DQ<5>")
	)
	(segment
		(start 272.36166 -205.410054)
		(end 273.458686 -205.410054)
		(width 0.14478)
		(layer "In11.Cu")
		(net "M_F_CPU0_SA_DQ<5>")
	)
	(segment
		(start 294.357806 -205.410054)
		(end 296.16019 -205.410054)
		(width 0.14478)
		(layer "In11.Cu")
		(net "M_F_CPU0_SA_DQ<5>")
	)
	(segment
		(start 325.22541 -226.391978)
		(end 325.478394 -227.003356)
		(width 0.0889)
		(layer "In11.Cu")
		(net "M_F_CPU0_SA_DQ<5>")
	)
	(segment
		(start 270.922496 -205.80223)
		(end 271.085564 -205.639162)
		(width 0.14478)
		(layer "In11.Cu")
		(net "M_F_CPU0_SA_DQ<5>")
	)
	(segment
		(start 278.410924 -204.56017)
		(end 279.260808 -205.410054)
		(width 0.14478)
		(layer "In11.Cu")
		(net "M_F_CPU0_SA_DQ<5>")
	)
	(segment
		(start 304.420524 -205.573122)
		(end 304.583592 -205.410054)
		(width 0.14478)
		(layer "In11.Cu")
		(net "M_F_CPU0_SA_DQ<5>")
	)
	(segment
		(start 296.16019 -205.410054)
		(end 296.323258 -205.573122)
		(width 0.14478)
		(layer "In11.Cu")
		(net "M_F_CPU0_SA_DQ<5>")
	)
	(segment
		(start 298.721526 -204.723238)
		(end 298.721526 -204.788262)
		(width 0.14478)
		(layer "In11.Cu")
		(net "M_F_CPU0_SA_DQ<5>")
	)
	(segment
		(start 273.621754 -205.639162)
		(end 273.784822 -205.80223)
		(width 0.14478)
		(layer "In11.Cu")
		(net "M_F_CPU0_SA_DQ<5>")
	)
	(segment
		(start 284.361636 -204.56017)
		(end 285.892748 -204.56017)
		(width 0.14478)
		(layer "In11.Cu")
		(net "M_F_CPU0_SA_DQ<5>")
	)
	(segment
		(start 289.380422 -205.573122)
		(end 289.54349 -205.410054)
		(width 0.14478)
		(layer "In11.Cu")
		(net "M_F_CPU0_SA_DQ<5>")
	)
	(segment
		(start 276.64537 -204.723238)
		(end 276.808438 -204.56017)
		(width 0.14478)
		(layer "In11.Cu")
		(net "M_F_CPU0_SA_DQ<5>")
	)
	(segment
		(start 271.248632 -205.017878)
		(end 271.47901 -205.017878)
		(width 0.14478)
		(layer "In11.Cu")
		(net "M_F_CPU0_SA_DQ<5>")
	)
	(segment
		(start 269.648178 -204.985112)
		(end 270.07312 -205.410054)
		(width 0.14478)
		(layer "In11.Cu")
		(net "M_F_CPU0_SA_DQ<5>")
	)
	(segment
		(start 298.558458 -204.56017)
		(end 298.721526 -204.723238)
		(width 0.14478)
		(layer "In11.Cu")
		(net "M_F_CPU0_SA_DQ<5>")
	)
	(segment
		(start 288.986976 -205.80223)
		(end 289.217354 -205.80223)
		(width 0.14478)
		(layer "In11.Cu")
		(net "M_F_CPU0_SA_DQ<5>")
	)
	(segment
		(start 281.839162 -205.639162)
		(end 281.839162 -205.573122)
		(width 0.14478)
		(layer "In11.Cu")
		(net "M_F_CPU0_SA_DQ<5>")
	)
	(segment
		(start 297.04284 -205.410054)
		(end 297.389042 -205.410054)
		(width 0.14478)
		(layer "In11.Cu")
		(net "M_F_CPU0_SA_DQ<5>")
	)
	(segment
		(start 297.389042 -205.410054)
		(end 298.238926 -204.56017)
		(width 0.14478)
		(layer "In11.Cu")
		(net "M_F_CPU0_SA_DQ<5>")
	)
	(segment
		(start 326.308974 -228.51999)
		(end 326.674734 -228.51999)
		(width 0.0889)
		(layer "In11.Cu")
		(net "M_F_CPU0_SA_DQ<5>")
	)
	(segment
		(start 303.307496 -205.573122)
		(end 303.470564 -205.410054)
		(width 0.14478)
		(layer "In11.Cu")
		(net "M_F_CPU0_SA_DQ<5>")
	)
	(segment
		(start 324.132194 -224.95129)
		(end 324.343014 -225.16211)
		(width 0.0889)
		(layer "In11.Cu")
		(net "M_F_CPU0_SA_DQ<5>")
	)
	(segment
		(start 272.035524 -205.80223)
		(end 272.198592 -205.639162)
		(width 0.14478)
		(layer "In11.Cu")
		(net "M_F_CPU0_SA_DQ<5>")
	)
	(segment
		(start 270.52905 -205.639162)
		(end 270.692118 -205.80223)
		(width 0.14478)
		(layer "In11.Cu")
		(net "M_F_CPU0_SA_DQ<5>")
	)
	(segment
		(start 271.642078 -205.639162)
		(end 271.805146 -205.80223)
		(width 0.14478)
		(layer "In11.Cu")
		(net "M_F_CPU0_SA_DQ<5>")
	)
	(segment
		(start 303.700942 -205.410054)
		(end 303.86401 -205.573122)
		(width 0.14478)
		(layer "In11.Cu")
		(net "M_F_CPU0_SA_DQ<5>")
	)
	(segment
		(start 274.178268 -205.573122)
		(end 274.341336 -205.410054)
		(width 0.14478)
		(layer "In11.Cu")
		(net "M_F_CPU0_SA_DQ<5>")
	)
	(segment
		(start 296.323258 -205.573122)
		(end 296.323258 -205.639162)
		(width 0.14478)
		(layer "In11.Cu")
		(net "M_F_CPU0_SA_DQ<5>")
	)
	(segment
		(start 299.114972 -204.95133)
		(end 299.27804 -204.788262)
		(width 0.14478)
		(layer "In11.Cu")
		(net "M_F_CPU0_SA_DQ<5>")
	)
	(segment
		(start 296.716704 -205.80223)
		(end 296.879772 -205.639162)
		(width 0.14478)
		(layer "In11.Cu")
		(net "M_F_CPU0_SA_DQ<5>")
	)
	(segment
		(start 303.144428 -205.79969)
		(end 303.307496 -205.636622)
		(width 0.14478)
		(layer "In11.Cu")
		(net "M_F_CPU0_SA_DQ<5>")
	)
	(segment
		(start 304.257456 -205.79969)
		(end 304.420524 -205.636622)
		(width 0.14478)
		(layer "In11.Cu")
		(net "M_F_CPU0_SA_DQ<5>")
	)
	(segment
		(start 289.883088 -205.410054)
		(end 290.732972 -204.56017)
		(width 0.14478)
		(layer "In11.Cu")
		(net "M_F_CPU0_SA_DQ<5>")
	)
	(segment
		(start 303.86401 -205.573122)
		(end 303.86401 -205.636622)
		(width 0.14478)
		(layer "In11.Cu")
		(net "M_F_CPU0_SA_DQ<5>")
	)
	(segment
		(start 306.464208 -204.723238)
		(end 306.464208 -204.792326)
		(width 0.14478)
		(layer "In11.Cu")
		(net "M_F_CPU0_SA_DQ<5>")
	)
	(segment
		(start 270.365982 -205.410054)
		(end 270.52905 -205.573122)
		(width 0.14478)
		(layer "In11.Cu")
		(net "M_F_CPU0_SA_DQ<5>")
	)
	(segment
		(start 296.879772 -205.639162)
		(end 296.879772 -205.573122)
		(width 0.14478)
		(layer "In11.Cu")
		(net "M_F_CPU0_SA_DQ<5>")
	)
	(segment
		(start 309.604918 -207.663542)
		(end 320.127376 -218.186)
		(width 0.14478)
		(layer "In11.Cu")
		(net "M_F_CPU0_SA_DQ<5>")
	)
	(segment
		(start 276.088856 -204.785722)
		(end 276.251924 -204.94879)
		(width 0.14478)
		(layer "In11.Cu")
		(net "M_F_CPU0_SA_DQ<5>")
	)
	(segment
		(start 276.64537 -204.785722)
		(end 276.64537 -204.723238)
		(width 0.14478)
		(layer "In11.Cu")
		(net "M_F_CPU0_SA_DQ<5>")
	)
	(segment
		(start 284.198568 -204.790802)
		(end 284.198568 -204.723238)
		(width 0.14478)
		(layer "In11.Cu")
		(net "M_F_CPU0_SA_DQ<5>")
	)
	(segment
		(start 276.482302 -204.94879)
		(end 276.64537 -204.785722)
		(width 0.14478)
		(layer "In11.Cu")
		(net "M_F_CPU0_SA_DQ<5>")
	)
	(segment
		(start 283.642054 -204.790802)
		(end 283.805122 -204.95387)
		(width 0.14478)
		(layer "In11.Cu")
		(net "M_F_CPU0_SA_DQ<5>")
	)
	(segment
		(start 307.020722 -204.723238)
		(end 307.18379 -204.56017)
		(width 0.14478)
		(layer "In11.Cu")
		(net "M_F_CPU0_SA_DQ<5>")
	)
	(segment
		(start 291.72789 -204.790802)
		(end 291.72789 -204.723238)
		(width 0.14478)
		(layer "In11.Cu")
		(net "M_F_CPU0_SA_DQ<5>")
	)
	(segment
		(start 274.754848 -205.410054)
		(end 275.604732 -204.56017)
		(width 0.14478)
		(layer "In11.Cu")
		(net "M_F_CPU0_SA_DQ<5>")
	)
	(segment
		(start 291.171376 -204.723238)
		(end 291.171376 -204.790802)
		(width 0.14478)
		(layer "In11.Cu")
		(net "M_F_CPU0_SA_DQ<5>")
	)
	(segment
		(start 301.051976 -204.56017)
		(end 301.90186 -205.410054)
		(width 0.14478)
		(layer "In11.Cu")
		(net "M_F_CPU0_SA_DQ<5>")
	)
	(segment
		(start 276.251924 -204.94879)
		(end 276.482302 -204.94879)
		(width 0.14478)
		(layer "In11.Cu")
		(net "M_F_CPU0_SA_DQ<5>")
	)
	(segment
		(start 272.198592 -205.573122)
		(end 272.36166 -205.410054)
		(width 0.14478)
		(layer "In11.Cu")
		(net "M_F_CPU0_SA_DQ<5>")
	)
	(segment
		(start 274.341336 -205.410054)
		(end 274.754848 -205.410054)
		(width 0.14478)
		(layer "In11.Cu")
		(net "M_F_CPU0_SA_DQ<5>")
	)
	(segment
		(start 288.823908 -205.639162)
		(end 288.986976 -205.80223)
		(width 0.14478)
		(layer "In11.Cu")
		(net "M_F_CPU0_SA_DQ<5>")
	)
	(segment
		(start 331.229716 -229.421436)
		(end 331.238098 -229.41661)
		(width 0.0889)
		(layer "In11.Cu")
		(net "M_F_CPU0_SA_DQ<5>")
	)
	(segment
		(start 281.282648 -205.639162)
		(end 281.445716 -205.80223)
		(width 0.14478)
		(layer "In11.Cu")
		(net "M_F_CPU0_SA_DQ<5>")
	)
	(segment
		(start 309.604918 -206.413354)
		(end 309.604918 -207.663542)
		(width 0.14478)
		(layer "In11.Cu")
		(net "M_F_CPU0_SA_DQ<5>")
	)
	(segment
		(start 303.307496 -205.636622)
		(end 303.307496 -205.573122)
		(width 0.14478)
		(layer "In11.Cu")
		(net "M_F_CPU0_SA_DQ<5>")
	)
	(segment
		(start 291.564822 -204.95387)
		(end 291.72789 -204.790802)
		(width 0.14478)
		(layer "In11.Cu")
		(net "M_F_CPU0_SA_DQ<5>")
	)
	(segment
		(start 320.127376 -220.946472)
		(end 324.132194 -224.95129)
		(width 0.14478)
		(layer "In11.Cu")
		(net "M_F_CPU0_SA_DQ<5>")
	)
	(segment
		(start 289.380422 -205.639162)
		(end 289.380422 -205.573122)
		(width 0.14478)
		(layer "In11.Cu")
		(net "M_F_CPU0_SA_DQ<5>")
	)
	(segment
		(start 270.07312 -205.410054)
		(end 270.365982 -205.410054)
		(width 0.14478)
		(layer "In11.Cu")
		(net "M_F_CPU0_SA_DQ<5>")
	)
	(segment
		(start 302.750982 -205.636622)
		(end 302.91405 -205.79969)
		(width 0.14478)
		(layer "In11.Cu")
		(net "M_F_CPU0_SA_DQ<5>")
	)
	(segment
		(start 307.751734 -204.56017)
		(end 309.604918 -206.413354)
		(width 0.14478)
		(layer "In11.Cu")
		(net "M_F_CPU0_SA_DQ<5>")
	)
	(segment
		(start 288.66084 -205.410054)
		(end 288.823908 -205.573122)
		(width 0.14478)
		(layer "In11.Cu")
		(net "M_F_CPU0_SA_DQ<5>")
	)
	(segment
		(start 303.86401 -205.636622)
		(end 304.027078 -205.79969)
		(width 0.14478)
		(layer "In11.Cu")
		(net "M_F_CPU0_SA_DQ<5>")
	)
	(segment
		(start 304.894742 -205.410054)
		(end 305.744626 -204.56017)
		(width 0.14478)
		(layer "In11.Cu")
		(net "M_F_CPU0_SA_DQ<5>")
	)
	(segment
		(start 293.507922 -204.56017)
		(end 294.357806 -205.410054)
		(width 0.14478)
		(layer "In11.Cu")
		(net "M_F_CPU0_SA_DQ<5>")
	)
	(segment
		(start 283.478986 -204.56017)
		(end 283.642054 -204.723238)
		(width 0.14478)
		(layer "In11.Cu")
		(net "M_F_CPU0_SA_DQ<5>")
	)
	(segment
		(start 299.27804 -204.723238)
		(end 299.441108 -204.56017)
		(width 0.14478)
		(layer "In11.Cu")
		(net "M_F_CPU0_SA_DQ<5>")
	)
	(segment
		(start 298.884594 -204.95133)
		(end 299.114972 -204.95133)
		(width 0.14478)
		(layer "In11.Cu")
		(net "M_F_CPU0_SA_DQ<5>")
	)
	(segment
		(start 271.085564 -205.180946)
		(end 271.248632 -205.017878)
		(width 0.14478)
		(layer "In11.Cu")
		(net "M_F_CPU0_SA_DQ<5>")
	)
	(segment
		(start 298.238926 -204.56017)
		(end 298.558458 -204.56017)
		(width 0.14478)
		(layer "In11.Cu")
		(net "M_F_CPU0_SA_DQ<5>")
	)
	(segment
		(start 306.857654 -204.955394)
		(end 307.020722 -204.792326)
		(width 0.14478)
		(layer "In11.Cu")
		(net "M_F_CPU0_SA_DQ<5>")
	)
	(segment
		(start 291.334444 -204.95387)
		(end 291.564822 -204.95387)
		(width 0.14478)
		(layer "In11.Cu")
		(net "M_F_CPU0_SA_DQ<5>")
	)
	(segment
		(start 281.445716 -205.80223)
		(end 281.676094 -205.80223)
		(width 0.14478)
		(layer "In11.Cu")
		(net "M_F_CPU0_SA_DQ<5>")
	)
	(segment
		(start 332.16977 -229.421436)
		(end 332.178152 -229.41661)
		(width 0.0889)
		(layer "In11.Cu")
		(net "M_F_CPU0_SA_DQ<5>")
	)
	(segment
		(start 281.11958 -205.410054)
		(end 281.282648 -205.573122)
		(width 0.14478)
		(layer "In11.Cu")
		(net "M_F_CPU0_SA_DQ<5>")
	)
	(segment
		(start 305.744626 -204.56017)
		(end 306.30114 -204.56017)
		(width 0.14478)
		(layer "In11.Cu")
		(net "M_F_CPU0_SA_DQ<5>")
	)
	(segment
		(start 289.217354 -205.80223)
		(end 289.380422 -205.639162)
		(width 0.14478)
		(layer "In11.Cu")
		(net "M_F_CPU0_SA_DQ<5>")
	)
	(segment
		(start 270.52905 -205.573122)
		(end 270.52905 -205.639162)
		(width 0.14478)
		(layer "In11.Cu")
		(net "M_F_CPU0_SA_DQ<5>")
	)
	(segment
		(start 276.088856 -204.723238)
		(end 276.088856 -204.785722)
		(width 0.14478)
		(layer "In11.Cu")
		(net "M_F_CPU0_SA_DQ<5>")
	)
	(segment
		(start 304.583592 -205.410054)
		(end 304.894742 -205.410054)
		(width 0.14478)
		(layer "In11.Cu")
		(net "M_F_CPU0_SA_DQ<5>")
	)
	(segment
		(start 274.0152 -205.80223)
		(end 274.178268 -205.639162)
		(width 0.14478)
		(layer "In11.Cu")
		(net "M_F_CPU0_SA_DQ<5>")
	)
	(segment
		(start 282.323286 -205.410054)
		(end 283.17317 -204.56017)
		(width 0.14478)
		(layer "In11.Cu")
		(net "M_F_CPU0_SA_DQ<5>")
	)
	(segment
		(start 328.409808 -229.421436)
		(end 328.41819 -229.41661)
		(width 0.0889)
		(layer "In11.Cu")
		(net "M_F_CPU0_SA_DQ<5>")
	)
	(segment
		(start 290.732972 -204.56017)
		(end 291.008308 -204.56017)
		(width 0.14478)
		(layer "In11.Cu")
		(net "M_F_CPU0_SA_DQ<5>")
	)
	(segment
		(start 325.478394 -227.68941)
		(end 326.308974 -228.51999)
		(width 0.0889)
		(layer "In11.Cu")
		(net "M_F_CPU0_SA_DQ<5>")
	)
	(segment
		(start 333.62138 -229.385114)
		(end 333.717138 -229.359714)
		(width 0.0889)
		(layer "In11.Cu")
		(net "M_F_CPU0_SA_DQ<5>")
	)
	(segment
		(start 327.488804 -229.33406)
		(end 327.631298 -229.34041)
		(width 0.0889)
		(layer "In11.Cu")
		(net "M_F_CPU0_SA_DQ<5>")
	)
	(segment
		(start 271.085564 -205.639162)
		(end 271.085564 -205.180946)
		(width 0.14478)
		(layer "In11.Cu")
		(net "M_F_CPU0_SA_DQ<5>")
	)
	(segment
		(start 291.171376 -204.790802)
		(end 291.334444 -204.95387)
		(width 0.14478)
		(layer "In11.Cu")
		(net "M_F_CPU0_SA_DQ<5>")
	)
	(segment
		(start 291.72789 -204.723238)
		(end 291.890958 -204.56017)
		(width 0.14478)
		(layer "In11.Cu")
		(net "M_F_CPU0_SA_DQ<5>")
	)
	(segment
		(start 298.721526 -204.788262)
		(end 298.884594 -204.95133)
		(width 0.14478)
		(layer "In11.Cu")
		(net "M_F_CPU0_SA_DQ<5>")
	)
	(segment
		(start 281.282648 -205.573122)
		(end 281.282648 -205.639162)
		(width 0.14478)
		(layer "In11.Cu")
		(net "M_F_CPU0_SA_DQ<5>")
	)
	(segment
		(start 333.717138 -229.359714)
		(end 333.871062 -229.094284)
		(width 0.0889)
		(layer "In11.Cu")
		(net "M_F_CPU0_SA_DQ<5>")
	)
	(segment
		(start 271.47901 -205.017878)
		(end 271.642078 -205.180946)
		(width 0.14478)
		(layer "In11.Cu")
		(net "M_F_CPU0_SA_DQ<5>")
	)
	(segment
		(start 279.260808 -205.410054)
		(end 281.11958 -205.410054)
		(width 0.14478)
		(layer "In11.Cu")
		(net "M_F_CPU0_SA_DQ<5>")
	)
	(segment
		(start 301.90186 -205.410054)
		(end 302.587914 -205.410054)
		(width 0.14478)
		(layer "In11.Cu")
		(net "M_F_CPU0_SA_DQ<5>")
	)
	(segment
		(start 291.890958 -204.56017)
		(end 293.507922 -204.56017)
		(width 0.14478)
		(layer "In11.Cu")
		(net "M_F_CPU0_SA_DQ<5>")
	)
	(segment
		(start 289.54349 -205.410054)
		(end 289.883088 -205.410054)
		(width 0.14478)
		(layer "In11.Cu")
		(net "M_F_CPU0_SA_DQ<5>")
	)
	(segment
		(start 281.676094 -205.80223)
		(end 281.839162 -205.639162)
		(width 0.14478)
		(layer "In11.Cu")
		(net "M_F_CPU0_SA_DQ<5>")
	)
	(segment
		(start 299.441108 -204.56017)
		(end 301.051976 -204.56017)
		(width 0.14478)
		(layer "In11.Cu")
		(net "M_F_CPU0_SA_DQ<5>")
	)
	(segment
		(start 296.323258 -205.639162)
		(end 296.486326 -205.80223)
		(width 0.14478)
		(layer "In11.Cu")
		(net "M_F_CPU0_SA_DQ<5>")
	)
	(segment
		(start 325.478394 -227.003356)
		(end 325.478394 -227.68941)
		(width 0.0889)
		(layer "In11.Cu")
		(net "M_F_CPU0_SA_DQ<5>")
	)
	(segment
		(start 306.464208 -204.792326)
		(end 306.627276 -204.955394)
		(width 0.14478)
		(layer "In11.Cu")
		(net "M_F_CPU0_SA_DQ<5>")
	)
	(segment
		(start 307.020722 -204.792326)
		(end 307.020722 -204.723238)
		(width 0.14478)
		(layer "In11.Cu")
		(net "M_F_CPU0_SA_DQ<5>")
	)
	(segment
		(start 273.458686 -205.410054)
		(end 273.621754 -205.573122)
		(width 0.14478)
		(layer "In11.Cu")
		(net "M_F_CPU0_SA_DQ<5>")
	)
	(segment
		(start 296.879772 -205.573122)
		(end 297.04284 -205.410054)
		(width 0.14478)
		(layer "In11.Cu")
		(net "M_F_CPU0_SA_DQ<5>")
	)
	(segment
		(start 271.805146 -205.80223)
		(end 272.035524 -205.80223)
		(width 0.14478)
		(layer "In11.Cu")
		(net "M_F_CPU0_SA_DQ<5>")
	)
	(segment
		(start 275.925788 -204.56017)
		(end 276.088856 -204.723238)
		(width 0.14478)
		(layer "In11.Cu")
		(net "M_F_CPU0_SA_DQ<5>")
	)
	(segment
		(start 324.343014 -225.509582)
		(end 325.22541 -226.391978)
		(width 0.0889)
		(layer "In11.Cu")
		(net "M_F_CPU0_SA_DQ<5>")
	)
	(segment
		(start 275.604732 -204.56017)
		(end 275.925788 -204.56017)
		(width 0.14478)
		(layer "In11.Cu")
		(net "M_F_CPU0_SA_DQ<5>")
	)
	(segment
		(start 288.823908 -205.573122)
		(end 288.823908 -205.639162)
		(width 0.14478)
		(layer "In11.Cu")
		(net "M_F_CPU0_SA_DQ<5>")
	)
	(segment
		(start 302.91405 -205.79969)
		(end 303.144428 -205.79969)
		(width 0.14478)
		(layer "In11.Cu")
		(net "M_F_CPU0_SA_DQ<5>")
	)
	(segment
		(start 332.744064 -229.41661)
		(end 332.752446 -229.421436)
		(width 0.0889)
		(layer "In11.Cu")
		(net "M_F_CPU0_SA_DQ<5>")
	)
	(segment
		(start 282.00223 -205.410054)
		(end 282.323286 -205.410054)
		(width 0.14478)
		(layer "In11.Cu")
		(net "M_F_CPU0_SA_DQ<5>")
	)
	(segment
		(start 283.805122 -204.95387)
		(end 284.0355 -204.95387)
		(width 0.14478)
		(layer "In11.Cu")
		(net "M_F_CPU0_SA_DQ<5>")
	)
	(segment
		(start 283.17317 -204.56017)
		(end 283.478986 -204.56017)
		(width 0.14478)
		(layer "In11.Cu")
		(net "M_F_CPU0_SA_DQ<5>")
	)
	(segment
		(start 274.178268 -205.639162)
		(end 274.178268 -205.573122)
		(width 0.14478)
		(layer "In11.Cu")
		(net "M_F_CPU0_SA_DQ<5>")
	)
	(segment
		(start 299.27804 -204.788262)
		(end 299.27804 -204.723238)
		(width 0.14478)
		(layer "In11.Cu")
		(net "M_F_CPU0_SA_DQ<5>")
	)
	(arc
		(start 329.924156 -229.41661)
		(mid 330.1111 -229.466899)
		(end 330.298044 -229.41661)
		(width 0.0889)
		(layer "In11.Cu")
		(net "M_F_CPU0_SA_DQ<5>")
	)
	(arc
		(start 329.358244 -229.41661)
		(mid 329.6412 -229.340433)
		(end 329.924156 -229.41661)
		(width 0.0889)
		(layer "In11.Cu")
		(net "M_F_CPU0_SA_DQ<5>")
	)
	(arc
		(start 328.992484 -229.421436)
		(mid 329.175992 -229.466961)
		(end 329.358244 -229.41661)
		(width 0.0889)
		(layer "In11.Cu")
		(net "M_F_CPU0_SA_DQ<5>")
	)
	(arc
		(start 330.863956 -229.41661)
		(mid 331.046207 -229.466994)
		(end 331.229716 -229.421436)
		(width 0.0889)
		(layer "In11.Cu")
		(net "M_F_CPU0_SA_DQ<5>")
	)
	(arc
		(start 332.752446 -229.421436)
		(mid 332.935954 -229.466961)
		(end 333.118206 -229.41661)
		(width 0.0889)
		(layer "In11.Cu")
		(net "M_F_CPU0_SA_DQ<5>")
	)
	(arc
		(start 333.118206 -229.41661)
		(mid 333.366066 -229.341527)
		(end 333.62138 -229.385114)
		(width 0.0889)
		(layer "In11.Cu")
		(net "M_F_CPU0_SA_DQ<5>")
	)
	(arc
		(start 332.178152 -229.41661)
		(mid 332.461108 -229.340433)
		(end 332.744064 -229.41661)
		(width 0.0889)
		(layer "In11.Cu")
		(net "M_F_CPU0_SA_DQ<5>")
	)
	(arc
		(start 328.044048 -229.41661)
		(mid 328.226299 -229.466994)
		(end 328.409808 -229.421436)
		(width 0.0889)
		(layer "In11.Cu")
		(net "M_F_CPU0_SA_DQ<5>")
	)
	(arc
		(start 327.761346 -229.34041)
		(mid 327.907736 -229.359821)
		(end 328.044048 -229.41661)
		(width 0.0889)
		(layer "In11.Cu")
		(net "M_F_CPU0_SA_DQ<5>")
	)
	(arc
		(start 330.298044 -229.41661)
		(mid 330.581 -229.340433)
		(end 330.863956 -229.41661)
		(width 0.0889)
		(layer "In11.Cu")
		(net "M_F_CPU0_SA_DQ<5>")
	)
	(arc
		(start 328.41819 -229.41661)
		(mid 328.701146 -229.340433)
		(end 328.984102 -229.41661)
		(width 0.0889)
		(layer "In11.Cu")
		(net "M_F_CPU0_SA_DQ<5>")
	)
	(arc
		(start 331.80401 -229.41661)
		(mid 331.986261 -229.466994)
		(end 332.16977 -229.421436)
		(width 0.0889)
		(layer "In11.Cu")
		(net "M_F_CPU0_SA_DQ<5>")
	)
	(arc
		(start 331.238098 -229.41661)
		(mid 331.521054 -229.340433)
		(end 331.80401 -229.41661)
		(width 0.0889)
		(layer "In11.Cu")
		(net "M_F_CPU0_SA_DQ<5>")
	)
	(segment
		(start 332.92796 -228.550216)
		(end 332.461108 -228.284278)
		(width 0.10668)
		(layer "F.Cu")
		(net "M_F_CPU0_SA_DQ<4>")
	)
	(segment
		(start 307.530246 -203.09205)
		(end 308.052978 -203.09205)
		(width 0.14478)
		(layer "In11.Cu")
		(net "M_F_CPU0_SA_DQ<4>")
	)
	(segment
		(start 271.59712 -203.710032)
		(end 271.760188 -203.8731)
		(width 0.14478)
		(layer "In11.Cu")
		(net "M_F_CPU0_SA_DQ<4>")
	)
	(segment
		(start 307.298344 -202.860148)
		(end 307.530246 -203.09205)
		(width 0.14478)
		(layer "In11.Cu")
		(net "M_F_CPU0_SA_DQ<4>")
	)
	(segment
		(start 288.883598 -203.942442)
		(end 289.046666 -204.10551)
		(width 0.14478)
		(layer "In11.Cu")
		(net "M_F_CPU0_SA_DQ<4>")
	)
	(segment
		(start 289.440112 -203.942442)
		(end 289.440112 -203.8731)
		(width 0.14478)
		(layer "In11.Cu")
		(net "M_F_CPU0_SA_DQ<4>")
	)
	(segment
		(start 302.544734 -203.8731)
		(end 302.544734 -203.942442)
		(width 0.14478)
		(layer "In11.Cu")
		(net "M_F_CPU0_SA_DQ<4>")
	)
	(segment
		(start 289.046666 -204.10551)
		(end 289.277044 -204.10551)
		(width 0.14478)
		(layer "In11.Cu")
		(net "M_F_CPU0_SA_DQ<4>")
	)
	(segment
		(start 271.055592 -203.546964)
		(end 271.21866 -203.710032)
		(width 0.14478)
		(layer "In11.Cu")
		(net "M_F_CPU0_SA_DQ<4>")
	)
	(segment
		(start 276.762972 -202.8698)
		(end 278.420576 -202.8698)
		(width 0.14478)
		(layer "In11.Cu")
		(net "M_F_CPU0_SA_DQ<4>")
	)
	(segment
		(start 274.508468 -203.710032)
		(end 274.754848 -203.710032)
		(width 0.14478)
		(layer "In11.Cu")
		(net "M_F_CPU0_SA_DQ<4>")
	)
	(segment
		(start 324.866508 -224.283016)
		(end 325.55307 -224.969578)
		(width 0.0889)
		(layer "In11.Cu")
		(net "M_F_CPU0_SA_DQ<4>")
	)
	(segment
		(start 325.55307 -224.969578)
		(end 325.55307 -225.676714)
		(width 0.0889)
		(layer "In11.Cu")
		(net "M_F_CPU0_SA_DQ<4>")
	)
	(segment
		(start 303.264316 -203.499212)
		(end 303.494694 -203.499212)
		(width 0.14478)
		(layer "In11.Cu")
		(net "M_F_CPU0_SA_DQ<4>")
	)
	(segment
		(start 306.511452 -203.24699)
		(end 306.74183 -203.24699)
		(width 0.14478)
		(layer "In11.Cu")
		(net "M_F_CPU0_SA_DQ<4>")
	)
	(segment
		(start 284.023562 -203.24699)
		(end 284.18663 -203.083922)
		(width 0.14478)
		(layer "In11.Cu")
		(net "M_F_CPU0_SA_DQ<4>")
	)
	(segment
		(start 297.138344 -203.710032)
		(end 297.389042 -203.710032)
		(width 0.14478)
		(layer "In11.Cu")
		(net "M_F_CPU0_SA_DQ<4>")
	)
	(segment
		(start 271.760188 -203.8731)
		(end 271.760188 -203.937362)
		(width 0.14478)
		(layer "In11.Cu")
		(net "M_F_CPU0_SA_DQ<4>")
	)
	(segment
		(start 271.923256 -204.10043)
		(end 272.153634 -204.10043)
		(width 0.14478)
		(layer "In11.Cu")
		(net "M_F_CPU0_SA_DQ<4>")
	)
	(segment
		(start 273.788886 -203.932282)
		(end 273.951954 -204.09535)
		(width 0.14478)
		(layer "In11.Cu")
		(net "M_F_CPU0_SA_DQ<4>")
	)
	(segment
		(start 291.171376 -203.078842)
		(end 291.334444 -203.24191)
		(width 0.14478)
		(layer "In11.Cu")
		(net "M_F_CPU0_SA_DQ<4>")
	)
	(segment
		(start 332.307184 -228.549708)
		(end 332.461108 -228.284278)
		(width 0.0889)
		(layer "In11.Cu")
		(net "M_F_CPU0_SA_DQ<4>")
	)
	(segment
		(start 283.630116 -203.083922)
		(end 283.793184 -203.24699)
		(width 0.14478)
		(layer "In11.Cu")
		(net "M_F_CPU0_SA_DQ<4>")
	)
	(segment
		(start 326.796654 -227.96373)
		(end 327.490328 -228.657404)
		(width 0.0889)
		(layer "In11.Cu")
		(net "M_F_CPU0_SA_DQ<4>")
	)
	(segment
		(start 283.630116 -203.023216)
		(end 283.630116 -203.083922)
		(width 0.14478)
		(layer "In11.Cu")
		(net "M_F_CPU0_SA_DQ<4>")
	)
	(segment
		(start 304.051208 -204.10551)
		(end 304.214276 -203.942442)
		(width 0.14478)
		(layer "In11.Cu")
		(net "M_F_CPU0_SA_DQ<4>")
	)
	(segment
		(start 273.788886 -203.8731)
		(end 273.788886 -203.932282)
		(width 0.14478)
		(layer "In11.Cu")
		(net "M_F_CPU0_SA_DQ<4>")
	)
	(segment
		(start 270.892524 -202.99807)
		(end 271.055592 -203.161138)
		(width 0.14478)
		(layer "In11.Cu")
		(net "M_F_CPU0_SA_DQ<4>")
	)
	(segment
		(start 306.74183 -203.24699)
		(end 306.904898 -203.083922)
		(width 0.14478)
		(layer "In11.Cu")
		(net "M_F_CPU0_SA_DQ<4>")
	)
	(segment
		(start 302.381666 -203.710032)
		(end 302.544734 -203.8731)
		(width 0.14478)
		(layer "In11.Cu")
		(net "M_F_CPU0_SA_DQ<4>")
	)
	(segment
		(start 297.389042 -203.710032)
		(end 298.238926 -202.860148)
		(width 0.14478)
		(layer "In11.Cu")
		(net "M_F_CPU0_SA_DQ<4>")
	)
	(segment
		(start 310.642254 -207.12811)
		(end 321.239134 -217.72499)
		(width 0.14478)
		(layer "In11.Cu")
		(net "M_F_CPU0_SA_DQ<4>")
	)
	(segment
		(start 321.239134 -220.467682)
		(end 324.866508 -224.095056)
		(width 0.14478)
		(layer "In11.Cu")
		(net "M_F_CPU0_SA_DQ<4>")
	)
	(segment
		(start 299.434504 -202.8698)
		(end 301.061628 -202.8698)
		(width 0.14478)
		(layer "In11.Cu")
		(net "M_F_CPU0_SA_DQ<4>")
	)
	(segment
		(start 303.494694 -203.499212)
		(end 303.657762 -203.66228)
		(width 0.14478)
		(layer "In11.Cu")
		(net "M_F_CPU0_SA_DQ<4>")
	)
	(segment
		(start 276.21611 -203.24699)
		(end 276.446488 -203.24699)
		(width 0.14478)
		(layer "In11.Cu")
		(net "M_F_CPU0_SA_DQ<4>")
	)
	(segment
		(start 329.819762 -228.611684)
		(end 329.828144 -228.606858)
		(width 0.0889)
		(layer "In11.Cu")
		(net "M_F_CPU0_SA_DQ<4>")
	)
	(segment
		(start 298.724574 -203.023216)
		(end 298.724574 -203.078842)
		(width 0.14478)
		(layer "In11.Cu")
		(net "M_F_CPU0_SA_DQ<4>")
	)
	(segment
		(start 286.752284 -203.719684)
		(end 288.730182 -203.719684)
		(width 0.14478)
		(layer "In11.Cu")
		(net "M_F_CPU0_SA_DQ<4>")
	)
	(segment
		(start 310.642254 -205.681326)
		(end 310.642254 -207.12811)
		(width 0.14478)
		(layer "In11.Cu")
		(net "M_F_CPU0_SA_DQ<4>")
	)
	(segment
		(start 330.394056 -228.606858)
		(end 330.402438 -228.611684)
		(width 0.0889)
		(layer "In11.Cu")
		(net "M_F_CPU0_SA_DQ<4>")
	)
	(segment
		(start 304.377344 -203.710032)
		(end 304.894742 -203.710032)
		(width 0.14478)
		(layer "In11.Cu")
		(net "M_F_CPU0_SA_DQ<4>")
	)
	(segment
		(start 276.609556 -203.083922)
		(end 276.609556 -203.023216)
		(width 0.14478)
		(layer "In11.Cu")
		(net "M_F_CPU0_SA_DQ<4>")
	)
	(segment
		(start 289.440112 -203.8731)
		(end 289.60318 -203.710032)
		(width 0.14478)
		(layer "In11.Cu")
		(net "M_F_CPU0_SA_DQ<4>")
	)
	(segment
		(start 276.053042 -203.083922)
		(end 276.21611 -203.24699)
		(width 0.14478)
		(layer "In11.Cu")
		(net "M_F_CPU0_SA_DQ<4>")
	)
	(segment
		(start 291.72789 -203.023216)
		(end 291.881306 -202.8698)
		(width 0.14478)
		(layer "In11.Cu")
		(net "M_F_CPU0_SA_DQ<4>")
	)
	(segment
		(start 291.881306 -202.8698)
		(end 293.517574 -202.8698)
		(width 0.14478)
		(layer "In11.Cu")
		(net "M_F_CPU0_SA_DQ<4>")
	)
	(segment
		(start 275.604732 -202.860148)
		(end 275.889974 -202.860148)
		(width 0.14478)
		(layer "In11.Cu")
		(net "M_F_CPU0_SA_DQ<4>")
	)
	(segment
		(start 298.561506 -202.860148)
		(end 298.724574 -203.023216)
		(width 0.14478)
		(layer "In11.Cu")
		(net "M_F_CPU0_SA_DQ<4>")
	)
	(segment
		(start 301.061628 -202.8698)
		(end 301.90186 -203.710032)
		(width 0.14478)
		(layer "In11.Cu")
		(net "M_F_CPU0_SA_DQ<4>")
	)
	(segment
		(start 288.883598 -203.8731)
		(end 288.883598 -203.942442)
		(width 0.14478)
		(layer "In11.Cu")
		(net "M_F_CPU0_SA_DQ<4>")
	)
	(segment
		(start 299.281088 -203.023216)
		(end 299.434504 -202.8698)
		(width 0.14478)
		(layer "In11.Cu")
		(net "M_F_CPU0_SA_DQ<4>")
	)
	(segment
		(start 306.904898 -203.023216)
		(end 307.067966 -202.860148)
		(width 0.14478)
		(layer "In11.Cu")
		(net "M_F_CPU0_SA_DQ<4>")
	)
	(segment
		(start 298.238926 -202.860148)
		(end 298.561506 -202.860148)
		(width 0.14478)
		(layer "In11.Cu")
		(net "M_F_CPU0_SA_DQ<4>")
	)
	(segment
		(start 272.316702 -203.937362)
		(end 272.316702 -203.8731)
		(width 0.14478)
		(layer "In11.Cu")
		(net "M_F_CPU0_SA_DQ<4>")
	)
	(segment
		(start 296.975276 -203.8731)
		(end 297.138344 -203.710032)
		(width 0.14478)
		(layer "In11.Cu")
		(net "M_F_CPU0_SA_DQ<4>")
	)
	(segment
		(start 304.894742 -203.710032)
		(end 305.744626 -202.860148)
		(width 0.14478)
		(layer "In11.Cu")
		(net "M_F_CPU0_SA_DQ<4>")
	)
	(segment
		(start 326.331834 -227.96373)
		(end 326.796654 -227.96373)
		(width 0.0889)
		(layer "In11.Cu")
		(net "M_F_CPU0_SA_DQ<4>")
	)
	(segment
		(start 270.662146 -202.99807)
		(end 270.892524 -202.99807)
		(width 0.14478)
		(layer "In11.Cu")
		(net "M_F_CPU0_SA_DQ<4>")
	)
	(segment
		(start 296.418762 -203.937362)
		(end 296.58183 -204.10043)
		(width 0.14478)
		(layer "In11.Cu")
		(net "M_F_CPU0_SA_DQ<4>")
	)
	(segment
		(start 281.212544 -203.719684)
		(end 281.36596 -203.8731)
		(width 0.14478)
		(layer "In11.Cu")
		(net "M_F_CPU0_SA_DQ<4>")
	)
	(segment
		(start 327.490328 -228.657404)
		(end 327.761092 -228.657404)
		(width 0.0889)
		(layer "In11.Cu")
		(net "M_F_CPU0_SA_DQ<4>")
	)
	(segment
		(start 270.499078 -203.546964)
		(end 270.499078 -203.161138)
		(width 0.14478)
		(layer "In11.Cu")
		(net "M_F_CPU0_SA_DQ<4>")
	)
	(segment
		(start 274.3454 -203.8731)
		(end 274.508468 -203.710032)
		(width 0.14478)
		(layer "In11.Cu")
		(net "M_F_CPU0_SA_DQ<4>")
	)
	(segment
		(start 270.499078 -203.161138)
		(end 270.662146 -202.99807)
		(width 0.14478)
		(layer "In11.Cu")
		(net "M_F_CPU0_SA_DQ<4>")
	)
	(segment
		(start 305.744626 -202.860148)
		(end 306.185316 -202.860148)
		(width 0.14478)
		(layer "In11.Cu")
		(net "M_F_CPU0_SA_DQ<4>")
	)
	(segment
		(start 283.467048 -202.860148)
		(end 283.630116 -203.023216)
		(width 0.14478)
		(layer "In11.Cu")
		(net "M_F_CPU0_SA_DQ<4>")
	)
	(segment
		(start 294.367458 -203.719684)
		(end 296.265346 -203.719684)
		(width 0.14478)
		(layer "In11.Cu")
		(net "M_F_CPU0_SA_DQ<4>")
	)
	(segment
		(start 324.866508 -224.095056)
		(end 324.866508 -224.283016)
		(width 0.14478)
		(layer "In11.Cu")
		(net "M_F_CPU0_SA_DQ<4>")
	)
	(segment
		(start 325.973694 -226.968304)
		(end 325.973694 -227.60559)
		(width 0.0889)
		(layer "In11.Cu")
		(net "M_F_CPU0_SA_DQ<4>")
	)
	(segment
		(start 290.732972 -202.860148)
		(end 291.008308 -202.860148)
		(width 0.14478)
		(layer "In11.Cu")
		(net "M_F_CPU0_SA_DQ<4>")
	)
	(segment
		(start 270.33601 -203.710032)
		(end 270.499078 -203.546964)
		(width 0.14478)
		(layer "In11.Cu")
		(net "M_F_CPU0_SA_DQ<4>")
	)
	(segment
		(start 276.053042 -203.023216)
		(end 276.053042 -203.083922)
		(width 0.14478)
		(layer "In11.Cu")
		(net "M_F_CPU0_SA_DQ<4>")
	)
	(segment
		(start 281.922474 -203.8731)
		(end 282.085542 -203.710032)
		(width 0.14478)
		(layer "In11.Cu")
		(net "M_F_CPU0_SA_DQ<4>")
	)
	(segment
		(start 291.008308 -202.860148)
		(end 291.171376 -203.023216)
		(width 0.14478)
		(layer "In11.Cu")
		(net "M_F_CPU0_SA_DQ<4>")
	)
	(segment
		(start 289.883088 -203.710032)
		(end 290.732972 -202.860148)
		(width 0.14478)
		(layer "In11.Cu")
		(net "M_F_CPU0_SA_DQ<4>")
	)
	(segment
		(start 288.730182 -203.719684)
		(end 288.883598 -203.8731)
		(width 0.14478)
		(layer "In11.Cu")
		(net "M_F_CPU0_SA_DQ<4>")
	)
	(segment
		(start 278.420576 -202.8698)
		(end 279.27046 -203.719684)
		(width 0.14478)
		(layer "In11.Cu")
		(net "M_F_CPU0_SA_DQ<4>")
	)
	(segment
		(start 304.214276 -203.8731)
		(end 304.377344 -203.710032)
		(width 0.14478)
		(layer "In11.Cu")
		(net "M_F_CPU0_SA_DQ<4>")
	)
	(segment
		(start 282.085542 -203.710032)
		(end 282.323286 -203.710032)
		(width 0.14478)
		(layer "In11.Cu")
		(net "M_F_CPU0_SA_DQ<4>")
	)
	(segment
		(start 272.470118 -203.719684)
		(end 273.63547 -203.719684)
		(width 0.14478)
		(layer "In11.Cu")
		(net "M_F_CPU0_SA_DQ<4>")
	)
	(segment
		(start 303.657762 -203.942442)
		(end 303.82083 -204.10551)
		(width 0.14478)
		(layer "In11.Cu")
		(net "M_F_CPU0_SA_DQ<4>")
	)
	(segment
		(start 275.889974 -202.860148)
		(end 276.053042 -203.023216)
		(width 0.14478)
		(layer "In11.Cu")
		(net "M_F_CPU0_SA_DQ<4>")
	)
	(segment
		(start 291.171376 -203.023216)
		(end 291.171376 -203.078842)
		(width 0.14478)
		(layer "In11.Cu")
		(net "M_F_CPU0_SA_DQ<4>")
	)
	(segment
		(start 296.812208 -204.10043)
		(end 296.975276 -203.937362)
		(width 0.14478)
		(layer "In11.Cu")
		(net "M_F_CPU0_SA_DQ<4>")
	)
	(segment
		(start 284.340046 -202.8698)
		(end 285.9024 -202.8698)
		(width 0.14478)
		(layer "In11.Cu")
		(net "M_F_CPU0_SA_DQ<4>")
	)
	(segment
		(start 271.760188 -203.937362)
		(end 271.923256 -204.10043)
		(width 0.14478)
		(layer "In11.Cu")
		(net "M_F_CPU0_SA_DQ<4>")
	)
	(segment
		(start 281.759406 -204.10043)
		(end 281.922474 -203.937362)
		(width 0.14478)
		(layer "In11.Cu")
		(net "M_F_CPU0_SA_DQ<4>")
	)
	(segment
		(start 284.18663 -203.023216)
		(end 284.340046 -202.8698)
		(width 0.14478)
		(layer "In11.Cu")
		(net "M_F_CPU0_SA_DQ<4>")
	)
	(segment
		(start 285.9024 -202.8698)
		(end 286.752284 -203.719684)
		(width 0.14478)
		(layer "In11.Cu")
		(net "M_F_CPU0_SA_DQ<4>")
	)
	(segment
		(start 306.348384 -203.023216)
		(end 306.348384 -203.083922)
		(width 0.14478)
		(layer "In11.Cu")
		(net "M_F_CPU0_SA_DQ<4>")
	)
	(segment
		(start 293.517574 -202.8698)
		(end 294.367458 -203.719684)
		(width 0.14478)
		(layer "In11.Cu")
		(net "M_F_CPU0_SA_DQ<4>")
	)
	(segment
		(start 271.21866 -203.710032)
		(end 271.59712 -203.710032)
		(width 0.14478)
		(layer "In11.Cu")
		(net "M_F_CPU0_SA_DQ<4>")
	)
	(segment
		(start 274.3454 -203.932282)
		(end 274.3454 -203.8731)
		(width 0.14478)
		(layer "In11.Cu")
		(net "M_F_CPU0_SA_DQ<4>")
	)
	(segment
		(start 308.052978 -203.09205)
		(end 310.642254 -205.681326)
		(width 0.14478)
		(layer "In11.Cu")
		(net "M_F_CPU0_SA_DQ<4>")
	)
	(segment
		(start 296.975276 -203.937362)
		(end 296.975276 -203.8731)
		(width 0.14478)
		(layer "In11.Cu")
		(net "M_F_CPU0_SA_DQ<4>")
	)
	(segment
		(start 276.446488 -203.24699)
		(end 276.609556 -203.083922)
		(width 0.14478)
		(layer "In11.Cu")
		(net "M_F_CPU0_SA_DQ<4>")
	)
	(segment
		(start 272.316702 -203.8731)
		(end 272.470118 -203.719684)
		(width 0.14478)
		(layer "In11.Cu")
		(net "M_F_CPU0_SA_DQ<4>")
	)
	(segment
		(start 296.418762 -203.8731)
		(end 296.418762 -203.937362)
		(width 0.14478)
		(layer "In11.Cu")
		(net "M_F_CPU0_SA_DQ<4>")
	)
	(segment
		(start 283.17317 -202.860148)
		(end 283.467048 -202.860148)
		(width 0.14478)
		(layer "In11.Cu")
		(net "M_F_CPU0_SA_DQ<4>")
	)
	(segment
		(start 269.648178 -203.28509)
		(end 270.07312 -203.710032)
		(width 0.14478)
		(layer "In11.Cu")
		(net "M_F_CPU0_SA_DQ<4>")
	)
	(segment
		(start 306.185316 -202.860148)
		(end 306.348384 -203.023216)
		(width 0.14478)
		(layer "In11.Cu")
		(net "M_F_CPU0_SA_DQ<4>")
	)
	(segment
		(start 281.922474 -203.937362)
		(end 281.922474 -203.8731)
		(width 0.14478)
		(layer "In11.Cu")
		(net "M_F_CPU0_SA_DQ<4>")
	)
	(segment
		(start 274.182332 -204.09535)
		(end 274.3454 -203.932282)
		(width 0.14478)
		(layer "In11.Cu")
		(net "M_F_CPU0_SA_DQ<4>")
	)
	(segment
		(start 303.101248 -203.942442)
		(end 303.101248 -203.66228)
		(width 0.14478)
		(layer "In11.Cu")
		(net "M_F_CPU0_SA_DQ<4>")
	)
	(segment
		(start 303.82083 -204.10551)
		(end 304.051208 -204.10551)
		(width 0.14478)
		(layer "In11.Cu")
		(net "M_F_CPU0_SA_DQ<4>")
	)
	(segment
		(start 325.973694 -227.60559)
		(end 326.331834 -227.96373)
		(width 0.0889)
		(layer "In11.Cu")
		(net "M_F_CPU0_SA_DQ<4>")
	)
	(segment
		(start 279.27046 -203.719684)
		(end 281.212544 -203.719684)
		(width 0.14478)
		(layer "In11.Cu")
		(net "M_F_CPU0_SA_DQ<4>")
	)
	(segment
		(start 273.951954 -204.09535)
		(end 274.182332 -204.09535)
		(width 0.14478)
		(layer "In11.Cu")
		(net "M_F_CPU0_SA_DQ<4>")
	)
	(segment
		(start 296.265346 -203.719684)
		(end 296.418762 -203.8731)
		(width 0.14478)
		(layer "In11.Cu")
		(net "M_F_CPU0_SA_DQ<4>")
	)
	(segment
		(start 274.754848 -203.710032)
		(end 275.604732 -202.860148)
		(width 0.14478)
		(layer "In11.Cu")
		(net "M_F_CPU0_SA_DQ<4>")
	)
	(segment
		(start 289.277044 -204.10551)
		(end 289.440112 -203.942442)
		(width 0.14478)
		(layer "In11.Cu")
		(net "M_F_CPU0_SA_DQ<4>")
	)
	(segment
		(start 276.609556 -203.023216)
		(end 276.762972 -202.8698)
		(width 0.14478)
		(layer "In11.Cu")
		(net "M_F_CPU0_SA_DQ<4>")
	)
	(segment
		(start 296.58183 -204.10043)
		(end 296.812208 -204.10043)
		(width 0.14478)
		(layer "In11.Cu")
		(net "M_F_CPU0_SA_DQ<4>")
	)
	(segment
		(start 291.334444 -203.24191)
		(end 291.564822 -203.24191)
		(width 0.14478)
		(layer "In11.Cu")
		(net "M_F_CPU0_SA_DQ<4>")
	)
	(segment
		(start 304.214276 -203.942442)
		(end 304.214276 -203.8731)
		(width 0.14478)
		(layer "In11.Cu")
		(net "M_F_CPU0_SA_DQ<4>")
	)
	(segment
		(start 325.662036 -226.215956)
		(end 325.973694 -226.968304)
		(width 0.0889)
		(layer "In11.Cu")
		(net "M_F_CPU0_SA_DQ<4>")
	)
	(segment
		(start 273.63547 -203.719684)
		(end 273.788886 -203.8731)
		(width 0.14478)
		(layer "In11.Cu")
		(net "M_F_CPU0_SA_DQ<4>")
	)
	(segment
		(start 299.11802 -203.24191)
		(end 299.281088 -203.078842)
		(width 0.14478)
		(layer "In11.Cu")
		(net "M_F_CPU0_SA_DQ<4>")
	)
	(segment
		(start 325.480934 -225.74885)
		(end 325.480934 -226.034854)
		(width 0.0889)
		(layer "In11.Cu")
		(net "M_F_CPU0_SA_DQ<4>")
	)
	(segment
		(start 284.18663 -203.083922)
		(end 284.18663 -203.023216)
		(width 0.14478)
		(layer "In11.Cu")
		(net "M_F_CPU0_SA_DQ<4>")
	)
	(segment
		(start 321.239134 -217.72499)
		(end 321.239134 -220.467682)
		(width 0.14478)
		(layer "In11.Cu")
		(net "M_F_CPU0_SA_DQ<4>")
	)
	(segment
		(start 298.887642 -203.24191)
		(end 299.11802 -203.24191)
		(width 0.14478)
		(layer "In11.Cu")
		(net "M_F_CPU0_SA_DQ<4>")
	)
	(segment
		(start 303.101248 -203.66228)
		(end 303.264316 -203.499212)
		(width 0.14478)
		(layer "In11.Cu")
		(net "M_F_CPU0_SA_DQ<4>")
	)
	(segment
		(start 306.904898 -203.083922)
		(end 306.904898 -203.023216)
		(width 0.14478)
		(layer "In11.Cu")
		(net "M_F_CPU0_SA_DQ<4>")
	)
	(segment
		(start 299.281088 -203.078842)
		(end 299.281088 -203.023216)
		(width 0.14478)
		(layer "In11.Cu")
		(net "M_F_CPU0_SA_DQ<4>")
	)
	(segment
		(start 282.323286 -203.710032)
		(end 283.17317 -202.860148)
		(width 0.14478)
		(layer "In11.Cu")
		(net "M_F_CPU0_SA_DQ<4>")
	)
	(segment
		(start 270.07312 -203.710032)
		(end 270.33601 -203.710032)
		(width 0.14478)
		(layer "In11.Cu")
		(net "M_F_CPU0_SA_DQ<4>")
	)
	(segment
		(start 271.055592 -203.161138)
		(end 271.055592 -203.546964)
		(width 0.14478)
		(layer "In11.Cu")
		(net "M_F_CPU0_SA_DQ<4>")
	)
	(segment
		(start 332.211172 -228.575108)
		(end 332.307184 -228.549708)
		(width 0.0889)
		(layer "In11.Cu")
		(net "M_F_CPU0_SA_DQ<4>")
	)
	(segment
		(start 291.564822 -203.24191)
		(end 291.72789 -203.078842)
		(width 0.14478)
		(layer "In11.Cu")
		(net "M_F_CPU0_SA_DQ<4>")
	)
	(segment
		(start 272.153634 -204.10043)
		(end 272.316702 -203.937362)
		(width 0.14478)
		(layer "In11.Cu")
		(net "M_F_CPU0_SA_DQ<4>")
	)
	(segment
		(start 289.60318 -203.710032)
		(end 289.883088 -203.710032)
		(width 0.14478)
		(layer "In11.Cu")
		(net "M_F_CPU0_SA_DQ<4>")
	)
	(segment
		(start 281.36596 -203.937362)
		(end 281.529028 -204.10043)
		(width 0.14478)
		(layer "In11.Cu")
		(net "M_F_CPU0_SA_DQ<4>")
	)
	(segment
		(start 283.793184 -203.24699)
		(end 284.023562 -203.24699)
		(width 0.14478)
		(layer "In11.Cu")
		(net "M_F_CPU0_SA_DQ<4>")
	)
	(segment
		(start 331.33411 -228.606858)
		(end 331.342492 -228.611684)
		(width 0.0889)
		(layer "In11.Cu")
		(net "M_F_CPU0_SA_DQ<4>")
	)
	(segment
		(start 281.36596 -203.8731)
		(end 281.36596 -203.937362)
		(width 0.14478)
		(layer "In11.Cu")
		(net "M_F_CPU0_SA_DQ<4>")
	)
	(segment
		(start 306.348384 -203.083922)
		(end 306.511452 -203.24699)
		(width 0.14478)
		(layer "In11.Cu")
		(net "M_F_CPU0_SA_DQ<4>")
	)
	(segment
		(start 303.657762 -203.66228)
		(end 303.657762 -203.942442)
		(width 0.14478)
		(layer "In11.Cu")
		(net "M_F_CPU0_SA_DQ<4>")
	)
	(segment
		(start 291.72789 -203.078842)
		(end 291.72789 -203.023216)
		(width 0.14478)
		(layer "In11.Cu")
		(net "M_F_CPU0_SA_DQ<4>")
	)
	(segment
		(start 302.544734 -203.942442)
		(end 302.707802 -204.10551)
		(width 0.14478)
		(layer "In11.Cu")
		(net "M_F_CPU0_SA_DQ<4>")
	)
	(segment
		(start 307.067966 -202.860148)
		(end 307.298344 -202.860148)
		(width 0.14478)
		(layer "In11.Cu")
		(net "M_F_CPU0_SA_DQ<4>")
	)
	(segment
		(start 298.724574 -203.078842)
		(end 298.887642 -203.24191)
		(width 0.14478)
		(layer "In11.Cu")
		(net "M_F_CPU0_SA_DQ<4>")
	)
	(segment
		(start 325.480934 -226.034854)
		(end 325.662036 -226.215956)
		(width 0.0889)
		(layer "In11.Cu")
		(net "M_F_CPU0_SA_DQ<4>")
	)
	(segment
		(start 281.529028 -204.10043)
		(end 281.759406 -204.10043)
		(width 0.14478)
		(layer "In11.Cu")
		(net "M_F_CPU0_SA_DQ<4>")
	)
	(segment
		(start 302.707802 -204.10551)
		(end 302.93818 -204.10551)
		(width 0.14478)
		(layer "In11.Cu")
		(net "M_F_CPU0_SA_DQ<4>")
	)
	(segment
		(start 302.93818 -204.10551)
		(end 303.101248 -203.942442)
		(width 0.14478)
		(layer "In11.Cu")
		(net "M_F_CPU0_SA_DQ<4>")
	)
	(segment
		(start 301.90186 -203.710032)
		(end 302.381666 -203.710032)
		(width 0.14478)
		(layer "In11.Cu")
		(net "M_F_CPU0_SA_DQ<4>")
	)
	(segment
		(start 325.55307 -225.676714)
		(end 325.480934 -225.74885)
		(width 0.0889)
		(layer "In11.Cu")
		(net "M_F_CPU0_SA_DQ<4>")
	)
	(arc
		(start 331.342492 -228.611684)
		(mid 331.526 -228.657178)
		(end 331.708252 -228.606858)
		(width 0.0889)
		(layer "In11.Cu")
		(net "M_F_CPU0_SA_DQ<4>")
	)
	(arc
		(start 328.88809 -228.606858)
		(mid 329.171046 -228.530681)
		(end 329.454002 -228.606858)
		(width 0.0889)
		(layer "In11.Cu")
		(net "M_F_CPU0_SA_DQ<4>")
	)
	(arc
		(start 329.828144 -228.606858)
		(mid 330.1111 -228.530681)
		(end 330.394056 -228.606858)
		(width 0.0889)
		(layer "In11.Cu")
		(net "M_F_CPU0_SA_DQ<4>")
	)
	(arc
		(start 327.94829 -228.606858)
		(mid 328.231246 -228.530681)
		(end 328.514202 -228.606858)
		(width 0.0889)
		(layer "In11.Cu")
		(net "M_F_CPU0_SA_DQ<4>")
	)
	(arc
		(start 330.402438 -228.611684)
		(mid 330.585946 -228.657178)
		(end 330.768198 -228.606858)
		(width 0.0889)
		(layer "In11.Cu")
		(net "M_F_CPU0_SA_DQ<4>")
	)
	(arc
		(start 330.768198 -228.606858)
		(mid 331.051154 -228.530681)
		(end 331.33411 -228.606858)
		(width 0.0889)
		(layer "In11.Cu")
		(net "M_F_CPU0_SA_DQ<4>")
	)
	(arc
		(start 327.761092 -228.657404)
		(mid 327.858034 -228.644513)
		(end 327.94829 -228.606858)
		(width 0.0889)
		(layer "In11.Cu")
		(net "M_F_CPU0_SA_DQ<4>")
	)
	(arc
		(start 328.514202 -228.606858)
		(mid 328.701146 -228.657113)
		(end 328.88809 -228.606858)
		(width 0.0889)
		(layer "In11.Cu")
		(net "M_F_CPU0_SA_DQ<4>")
	)
	(arc
		(start 329.454002 -228.606858)
		(mid 329.636253 -228.657208)
		(end 329.819762 -228.611684)
		(width 0.0889)
		(layer "In11.Cu")
		(net "M_F_CPU0_SA_DQ<4>")
	)
	(arc
		(start 331.708252 -228.606858)
		(mid 331.955965 -228.531638)
		(end 332.211172 -228.575108)
		(width 0.0889)
		(layer "In11.Cu")
		(net "M_F_CPU0_SA_DQ<4>")
	)
	(segment
		(start 333.868014 -226.930204)
		(end 333.401162 -226.664266)
		(width 0.10668)
		(layer "F.Cu")
		(net "M_F_CPU0_SA_DQ<3>")
	)
	(segment
		(start 323.555614 -216.656666)
		(end 323.555614 -219.02293)
		(width 0.14478)
		(layer "In11.Cu")
		(net "M_F_CPU0_SA_DQ<3>")
	)
	(segment
		(start 265.973306 -200.310242)
		(end 266.5095 -200.310242)
		(width 0.14478)
		(layer "In11.Cu")
		(net "M_F_CPU0_SA_DQ<3>")
	)
	(segment
		(start 308.073552 -199.460104)
		(end 317.896494 -209.283046)
		(width 0.14478)
		(layer "In11.Cu")
		(net "M_F_CPU0_SA_DQ<3>")
	)
	(segment
		(start 325.998078 -221.465394)
		(end 326.181974 -221.64929)
		(width 0.0889)
		(layer "In11.Cu")
		(net "M_F_CPU0_SA_DQ<3>")
	)
	(segment
		(start 267.382244 -200.300336)
		(end 274.677632 -200.300336)
		(width 0.14478)
		(layer "In11.Cu")
		(net "M_F_CPU0_SA_DQ<3>")
	)
	(segment
		(start 282.308554 -200.300336)
		(end 283.158438 -199.450452)
		(width 0.14478)
		(layer "In11.Cu")
		(net "M_F_CPU0_SA_DQ<3>")
	)
	(segment
		(start 293.54907 -199.450452)
		(end 294.398954 -200.300336)
		(width 0.14478)
		(layer "In11.Cu")
		(net "M_F_CPU0_SA_DQ<3>")
	)
	(segment
		(start 278.47417 -199.450452)
		(end 279.324054 -200.300336)
		(width 0.14478)
		(layer "In11.Cu")
		(net "M_F_CPU0_SA_DQ<3>")
	)
	(segment
		(start 267.066014 -199.93737)
		(end 267.229082 -200.100438)
		(width 0.14478)
		(layer "In11.Cu")
		(net "M_F_CPU0_SA_DQ<3>")
	)
	(segment
		(start 275.527516 -199.450452)
		(end 278.47417 -199.450452)
		(width 0.14478)
		(layer "In11.Cu")
		(net "M_F_CPU0_SA_DQ<3>")
	)
	(segment
		(start 304.8762 -200.310242)
		(end 305.726338 -199.460104)
		(width 0.14478)
		(layer "In11.Cu")
		(net "M_F_CPU0_SA_DQ<3>")
	)
	(segment
		(start 298.18965 -199.450452)
		(end 301.085504 -199.450452)
		(width 0.14478)
		(layer "In11.Cu")
		(net "M_F_CPU0_SA_DQ<3>")
	)
	(segment
		(start 266.5095 -200.310242)
		(end 266.672568 -200.147174)
		(width 0.14478)
		(layer "In11.Cu")
		(net "M_F_CPU0_SA_DQ<3>")
	)
	(segment
		(start 327.008236 -223.101662)
		(end 327.041002 -223.120712)
		(width 0.0889)
		(layer "In11.Cu")
		(net "M_F_CPU0_SA_DQ<3>")
	)
	(segment
		(start 317.896494 -209.283046)
		(end 317.896494 -210.997546)
		(width 0.14478)
		(layer "In11.Cu")
		(net "M_F_CPU0_SA_DQ<3>")
	)
	(segment
		(start 290.691824 -199.450452)
		(end 293.54907 -199.450452)
		(width 0.14478)
		(layer "In11.Cu")
		(net "M_F_CPU0_SA_DQ<3>")
	)
	(segment
		(start 289.84194 -200.300336)
		(end 290.691824 -199.450452)
		(width 0.14478)
		(layer "In11.Cu")
		(net "M_F_CPU0_SA_DQ<3>")
	)
	(segment
		(start 326.181974 -222.07855)
		(end 326.351138 -222.247714)
		(width 0.0889)
		(layer "In11.Cu")
		(net "M_F_CPU0_SA_DQ<3>")
	)
	(segment
		(start 286.893508 -200.300336)
		(end 289.84194 -200.300336)
		(width 0.14478)
		(layer "In11.Cu")
		(net "M_F_CPU0_SA_DQ<3>")
	)
	(segment
		(start 267.229082 -200.100438)
		(end 267.229082 -200.147174)
		(width 0.14478)
		(layer "In11.Cu")
		(net "M_F_CPU0_SA_DQ<3>")
	)
	(segment
		(start 333.555086 -226.398836)
		(end 333.401162 -226.664266)
		(width 0.0889)
		(layer "In11.Cu")
		(net "M_F_CPU0_SA_DQ<3>")
	)
	(segment
		(start 327.911968 -226.320604)
		(end 327.94829 -226.341686)
		(width 0.0889)
		(layer "In11.Cu")
		(net "M_F_CPU0_SA_DQ<3>")
	)
	(segment
		(start 329.819762 -226.33686)
		(end 329.828144 -226.341686)
		(width 0.0889)
		(layer "In11.Cu")
		(net "M_F_CPU0_SA_DQ<3>")
	)
	(segment
		(start 327.51014 -224.53854)
		(end 327.47839 -224.556828)
		(width 0.0889)
		(layer "In11.Cu")
		(net "M_F_CPU0_SA_DQ<3>")
	)
	(segment
		(start 327.47839 -223.911668)
		(end 327.51014 -223.929956)
		(width 0.0889)
		(layer "In11.Cu")
		(net "M_F_CPU0_SA_DQ<3>")
	)
	(segment
		(start 327.47839 -224.556828)
		(end 327.438004 -224.58045)
		(width 0.0889)
		(layer "In11.Cu")
		(net "M_F_CPU0_SA_DQ<3>")
	)
	(segment
		(start 327.438004 -225.508058)
		(end 327.47839 -225.53168)
		(width 0.0889)
		(layer "In11.Cu")
		(net "M_F_CPU0_SA_DQ<3>")
	)
	(segment
		(start 327.439274 -223.888808)
		(end 327.47839 -223.911668)
		(width 0.0889)
		(layer "In11.Cu")
		(net "M_F_CPU0_SA_DQ<3>")
	)
	(segment
		(start 266.672568 -200.100438)
		(end 266.835636 -199.93737)
		(width 0.14478)
		(layer "In11.Cu")
		(net "M_F_CPU0_SA_DQ<3>")
	)
	(segment
		(start 317.896494 -210.997546)
		(end 323.555614 -216.656666)
		(width 0.14478)
		(layer "In11.Cu")
		(net "M_F_CPU0_SA_DQ<3>")
	)
	(segment
		(start 265.54811 -199.885046)
		(end 265.973306 -200.310242)
		(width 0.14478)
		(layer "In11.Cu")
		(net "M_F_CPU0_SA_DQ<3>")
	)
	(segment
		(start 267.229082 -200.147174)
		(end 267.382244 -200.300336)
		(width 0.14478)
		(layer "In11.Cu")
		(net "M_F_CPU0_SA_DQ<3>")
	)
	(segment
		(start 326.351138 -222.247714)
		(end 326.376284 -222.247714)
		(width 0.0889)
		(layer "In11.Cu")
		(net "M_F_CPU0_SA_DQ<3>")
	)
	(segment
		(start 326.181974 -221.64929)
		(end 326.181974 -222.07855)
		(width 0.0889)
		(layer "In11.Cu")
		(net "M_F_CPU0_SA_DQ<3>")
	)
	(segment
		(start 286.043624 -199.450452)
		(end 286.893508 -200.300336)
		(width 0.14478)
		(layer "In11.Cu")
		(net "M_F_CPU0_SA_DQ<3>")
	)
	(segment
		(start 331.33411 -226.341686)
		(end 331.342492 -226.33686)
		(width 0.0889)
		(layer "In11.Cu")
		(net "M_F_CPU0_SA_DQ<3>")
	)
	(segment
		(start 323.555614 -219.02293)
		(end 325.998078 -221.465394)
		(width 0.14478)
		(layer "In11.Cu")
		(net "M_F_CPU0_SA_DQ<3>")
	)
	(segment
		(start 301.945294 -200.310242)
		(end 304.8762 -200.310242)
		(width 0.14478)
		(layer "In11.Cu")
		(net "M_F_CPU0_SA_DQ<3>")
	)
	(segment
		(start 266.835636 -199.93737)
		(end 267.066014 -199.93737)
		(width 0.14478)
		(layer "In11.Cu")
		(net "M_F_CPU0_SA_DQ<3>")
	)
	(segment
		(start 305.726338 -199.460104)
		(end 308.073552 -199.460104)
		(width 0.14478)
		(layer "In11.Cu")
		(net "M_F_CPU0_SA_DQ<3>")
	)
	(segment
		(start 330.394056 -226.341686)
		(end 330.402438 -226.33686)
		(width 0.0889)
		(layer "In11.Cu")
		(net "M_F_CPU0_SA_DQ<3>")
	)
	(segment
		(start 301.085504 -199.450452)
		(end 301.945294 -200.310242)
		(width 0.14478)
		(layer "In11.Cu")
		(net "M_F_CPU0_SA_DQ<3>")
	)
	(segment
		(start 326.973438 -223.081342)
		(end 327.008236 -223.101662)
		(width 0.0889)
		(layer "In11.Cu")
		(net "M_F_CPU0_SA_DQ<3>")
	)
	(segment
		(start 333.532734 -226.315524)
		(end 333.555086 -226.398836)
		(width 0.0889)
		(layer "In11.Cu")
		(net "M_F_CPU0_SA_DQ<3>")
	)
	(segment
		(start 327.47839 -225.53168)
		(end 327.51014 -225.549968)
		(width 0.0889)
		(layer "In11.Cu")
		(net "M_F_CPU0_SA_DQ<3>")
	)
	(segment
		(start 279.324054 -200.300336)
		(end 282.308554 -200.300336)
		(width 0.14478)
		(layer "In11.Cu")
		(net "M_F_CPU0_SA_DQ<3>")
	)
	(segment
		(start 297.339766 -200.300336)
		(end 298.18965 -199.450452)
		(width 0.14478)
		(layer "In11.Cu")
		(net "M_F_CPU0_SA_DQ<3>")
	)
	(segment
		(start 294.398954 -200.300336)
		(end 297.339766 -200.300336)
		(width 0.14478)
		(layer "In11.Cu")
		(net "M_F_CPU0_SA_DQ<3>")
	)
	(segment
		(start 274.677632 -200.300336)
		(end 275.527516 -199.450452)
		(width 0.14478)
		(layer "In11.Cu")
		(net "M_F_CPU0_SA_DQ<3>")
	)
	(segment
		(start 283.158438 -199.450452)
		(end 286.043624 -199.450452)
		(width 0.14478)
		(layer "In11.Cu")
		(net "M_F_CPU0_SA_DQ<3>")
	)
	(segment
		(start 266.672568 -200.147174)
		(end 266.672568 -200.100438)
		(width 0.14478)
		(layer "In11.Cu")
		(net "M_F_CPU0_SA_DQ<3>")
	)
	(arc
		(start 327.666096 -225.85426)
		(mid 327.731332 -226.117851)
		(end 327.911968 -226.320604)
		(width 0.0889)
		(layer "In11.Cu")
		(net "M_F_CPU0_SA_DQ<3>")
	)
	(arc
		(start 331.342492 -226.33686)
		(mid 331.526 -226.291366)
		(end 331.708252 -226.341686)
		(width 0.0889)
		(layer "In11.Cu")
		(net "M_F_CPU0_SA_DQ<3>")
	)
	(arc
		(start 327.94829 -226.341686)
		(mid 328.231246 -226.417863)
		(end 328.514202 -226.341686)
		(width 0.0889)
		(layer "In11.Cu")
		(net "M_F_CPU0_SA_DQ<3>")
	)
	(arc
		(start 328.514202 -226.341686)
		(mid 328.701146 -226.291431)
		(end 328.88809 -226.341686)
		(width 0.0889)
		(layer "In11.Cu")
		(net "M_F_CPU0_SA_DQ<3>")
	)
	(arc
		(start 329.828144 -226.341686)
		(mid 330.1111 -226.417863)
		(end 330.394056 -226.341686)
		(width 0.0889)
		(layer "In11.Cu")
		(net "M_F_CPU0_SA_DQ<3>")
	)
	(arc
		(start 326.376284 -222.247714)
		(mid 326.473642 -222.267181)
		(end 326.564752 -222.306642)
		(width 0.0889)
		(layer "In11.Cu")
		(net "M_F_CPU0_SA_DQ<3>")
	)
	(arc
		(start 331.708252 -226.341686)
		(mid 331.991208 -226.417863)
		(end 332.274164 -226.341686)
		(width 0.0889)
		(layer "In11.Cu")
		(net "M_F_CPU0_SA_DQ<3>")
	)
	(arc
		(start 327.51014 -225.549968)
		(mid 327.624816 -225.683302)
		(end 327.666096 -225.85426)
		(width 0.0889)
		(layer "In11.Cu")
		(net "M_F_CPU0_SA_DQ<3>")
	)
	(arc
		(start 329.454002 -226.341686)
		(mid 329.636253 -226.291336)
		(end 329.819762 -226.33686)
		(width 0.0889)
		(layer "In11.Cu")
		(net "M_F_CPU0_SA_DQ<3>")
	)
	(arc
		(start 327.195688 -225.044254)
		(mid 327.259981 -225.305859)
		(end 327.438004 -225.508058)
		(width 0.0889)
		(layer "In11.Cu")
		(net "M_F_CPU0_SA_DQ<3>")
	)
	(arc
		(start 330.402438 -226.33686)
		(mid 330.585946 -226.291366)
		(end 330.768198 -226.341686)
		(width 0.0889)
		(layer "In11.Cu")
		(net "M_F_CPU0_SA_DQ<3>")
	)
	(arc
		(start 326.564752 -222.306642)
		(mid 326.571965 -222.311138)
		(end 326.578722 -222.316294)
		(width 0.0889)
		(layer "In11.Cu")
		(net "M_F_CPU0_SA_DQ<3>")
	)
	(arc
		(start 332.274164 -226.341686)
		(mid 332.461108 -226.291431)
		(end 332.648052 -226.341686)
		(width 0.0889)
		(layer "In11.Cu")
		(net "M_F_CPU0_SA_DQ<3>")
	)
	(arc
		(start 327.51014 -223.929956)
		(mid 327.666068 -224.234248)
		(end 327.51014 -224.53854)
		(width 0.0889)
		(layer "In11.Cu")
		(net "M_F_CPU0_SA_DQ<3>")
	)
	(arc
		(start 333.213964 -226.341686)
		(mid 333.370402 -226.292715)
		(end 333.532734 -226.315524)
		(width 0.0889)
		(layer "In11.Cu")
		(net "M_F_CPU0_SA_DQ<3>")
	)
	(arc
		(start 326.578722 -222.316294)
		(mid 326.682999 -222.450167)
		(end 326.726296 -222.614236)
		(width 0.0889)
		(layer "In11.Cu")
		(net "M_F_CPU0_SA_DQ<3>")
	)
	(arc
		(start 328.88809 -226.341686)
		(mid 329.171046 -226.417863)
		(end 329.454002 -226.341686)
		(width 0.0889)
		(layer "In11.Cu")
		(net "M_F_CPU0_SA_DQ<3>")
	)
	(arc
		(start 327.041002 -223.120712)
		(mid 327.154931 -223.253859)
		(end 327.195942 -223.424242)
		(width 0.0889)
		(layer "In11.Cu")
		(net "M_F_CPU0_SA_DQ<3>")
	)
	(arc
		(start 330.768198 -226.341686)
		(mid 331.051154 -226.417863)
		(end 331.33411 -226.341686)
		(width 0.0889)
		(layer "In11.Cu")
		(net "M_F_CPU0_SA_DQ<3>")
	)
	(arc
		(start 326.726296 -222.614236)
		(mid 326.791897 -222.878455)
		(end 326.973438 -223.081342)
		(width 0.0889)
		(layer "In11.Cu")
		(net "M_F_CPU0_SA_DQ<3>")
	)
	(arc
		(start 327.195942 -223.424242)
		(mid 327.260457 -223.686461)
		(end 327.439274 -223.888808)
		(width 0.0889)
		(layer "In11.Cu")
		(net "M_F_CPU0_SA_DQ<3>")
	)
	(arc
		(start 327.438004 -224.58045)
		(mid 327.259939 -224.782627)
		(end 327.195688 -225.044254)
		(width 0.0889)
		(layer "In11.Cu")
		(net "M_F_CPU0_SA_DQ<3>")
	)
	(arc
		(start 332.648052 -226.341686)
		(mid 332.931008 -226.417863)
		(end 333.213964 -226.341686)
		(width 0.0889)
		(layer "In11.Cu")
		(net "M_F_CPU0_SA_DQ<3>")
	)
	(segment
		(start 333.868014 -244.750082)
		(end 333.401162 -244.484144)
		(width 0.10668)
		(layer "F.Cu")
		(net "M_F_CPU0_SA_DQ<31>")
	)
	(segment
		(start 266.983972 -233.51363)
		(end 267.21435 -233.51363)
		(width 0.14478)
		(layer "In11.Cu")
		(net "M_F_CPU0_SA_DQ<31>")
	)
	(segment
		(start 331.33411 -244.161564)
		(end 331.342492 -244.156738)
		(width 0.0889)
		(layer "In11.Cu")
		(net "M_F_CPU0_SA_DQ<31>")
	)
	(segment
		(start 282.298648 -234.310174)
		(end 283.148786 -233.460036)
		(width 0.14478)
		(layer "In11.Cu")
		(net "M_F_CPU0_SA_DQ<31>")
	)
	(segment
		(start 289.832034 -234.310174)
		(end 290.682172 -233.460036)
		(width 0.14478)
		(layer "In11.Cu")
		(net "M_F_CPU0_SA_DQ<31>")
	)
	(segment
		(start 268.490446 -234.147106)
		(end 268.653514 -234.310174)
		(width 0.14478)
		(layer "In11.Cu")
		(net "M_F_CPU0_SA_DQ<31>")
	)
	(segment
		(start 293.558722 -233.460036)
		(end 294.40886 -234.310174)
		(width 0.14478)
		(layer "In11.Cu")
		(net "M_F_CPU0_SA_DQ<31>")
	)
	(segment
		(start 268.490446 -233.676698)
		(end 268.490446 -234.147106)
		(width 0.14478)
		(layer "In11.Cu")
		(net "M_F_CPU0_SA_DQ<31>")
	)
	(segment
		(start 325.754746 -244.23751)
		(end 326.351138 -244.23751)
		(width 0.0889)
		(layer "In11.Cu")
		(net "M_F_CPU0_SA_DQ<31>")
	)
	(segment
		(start 266.820904 -234.147106)
		(end 266.820904 -233.676698)
		(width 0.14478)
		(layer "In11.Cu")
		(net "M_F_CPU0_SA_DQ<31>")
	)
	(segment
		(start 286.903414 -234.310174)
		(end 289.832034 -234.310174)
		(width 0.14478)
		(layer "In11.Cu")
		(net "M_F_CPU0_SA_DQ<31>")
	)
	(segment
		(start 266.657836 -234.310174)
		(end 266.820904 -234.147106)
		(width 0.14478)
		(layer "In11.Cu")
		(net "M_F_CPU0_SA_DQ<31>")
	)
	(segment
		(start 329.819762 -244.156738)
		(end 329.828144 -244.161564)
		(width 0.0889)
		(layer "In11.Cu")
		(net "M_F_CPU0_SA_DQ<31>")
	)
	(segment
		(start 327.007728 -244.161564)
		(end 327.018142 -244.16766)
		(width 0.0889)
		(layer "In11.Cu")
		(net "M_F_CPU0_SA_DQ<31>")
	)
	(segment
		(start 333.532734 -244.135402)
		(end 333.555086 -244.218714)
		(width 0.0889)
		(layer "In11.Cu")
		(net "M_F_CPU0_SA_DQ<31>")
	)
	(segment
		(start 323.870574 -243.52123)
		(end 324.147434 -243.52123)
		(width 0.0889)
		(layer "In11.Cu")
		(net "M_F_CPU0_SA_DQ<31>")
	)
	(segment
		(start 333.555086 -244.218714)
		(end 333.401162 -244.484144)
		(width 0.0889)
		(layer "In11.Cu")
		(net "M_F_CPU0_SA_DQ<31>")
	)
	(segment
		(start 267.933932 -233.676698)
		(end 268.097 -233.51363)
		(width 0.14478)
		(layer "In11.Cu")
		(net "M_F_CPU0_SA_DQ<31>")
	)
	(segment
		(start 326.63384 -244.161564)
		(end 326.645524 -244.154706)
		(width 0.0889)
		(layer "In11.Cu")
		(net "M_F_CPU0_SA_DQ<31>")
	)
	(segment
		(start 308.403498 -235.114338)
		(end 308.403498 -236.113574)
		(width 0.14478)
		(layer "In11.Cu")
		(net "M_F_CPU0_SA_DQ<31>")
	)
	(segment
		(start 325.330566 -243.81333)
		(end 325.754746 -244.23751)
		(width 0.0889)
		(layer "In11.Cu")
		(net "M_F_CPU0_SA_DQ<31>")
	)
	(segment
		(start 307.599334 -234.310174)
		(end 308.403498 -235.114338)
		(width 0.14478)
		(layer "In11.Cu")
		(net "M_F_CPU0_SA_DQ<31>")
	)
	(segment
		(start 267.377418 -233.676698)
		(end 267.377418 -234.147106)
		(width 0.14478)
		(layer "In11.Cu")
		(net "M_F_CPU0_SA_DQ<31>")
	)
	(segment
		(start 298.179998 -233.460036)
		(end 301.095156 -233.460036)
		(width 0.14478)
		(layer "In11.Cu")
		(net "M_F_CPU0_SA_DQ<31>")
	)
	(segment
		(start 324.439534 -243.81333)
		(end 325.330566 -243.81333)
		(width 0.0889)
		(layer "In11.Cu")
		(net "M_F_CPU0_SA_DQ<31>")
	)
	(segment
		(start 275.517864 -233.460036)
		(end 278.483822 -233.460036)
		(width 0.14478)
		(layer "In11.Cu")
		(net "M_F_CPU0_SA_DQ<31>")
	)
	(segment
		(start 267.933932 -234.147106)
		(end 267.933932 -233.676698)
		(width 0.14478)
		(layer "In11.Cu")
		(net "M_F_CPU0_SA_DQ<31>")
	)
	(segment
		(start 294.40886 -234.310174)
		(end 297.32986 -234.310174)
		(width 0.14478)
		(layer "In11.Cu")
		(net "M_F_CPU0_SA_DQ<31>")
	)
	(segment
		(start 265.973306 -234.310174)
		(end 266.657836 -234.310174)
		(width 0.14478)
		(layer "In11.Cu")
		(net "M_F_CPU0_SA_DQ<31>")
	)
	(segment
		(start 330.394056 -244.161564)
		(end 330.402438 -244.156738)
		(width 0.0889)
		(layer "In11.Cu")
		(net "M_F_CPU0_SA_DQ<31>")
	)
	(segment
		(start 266.820904 -233.676698)
		(end 266.983972 -233.51363)
		(width 0.14478)
		(layer "In11.Cu")
		(net "M_F_CPU0_SA_DQ<31>")
	)
	(segment
		(start 267.21435 -233.51363)
		(end 267.377418 -233.676698)
		(width 0.14478)
		(layer "In11.Cu")
		(net "M_F_CPU0_SA_DQ<31>")
	)
	(segment
		(start 283.148786 -233.460036)
		(end 286.053276 -233.460036)
		(width 0.14478)
		(layer "In11.Cu")
		(net "M_F_CPU0_SA_DQ<31>")
	)
	(segment
		(start 268.097 -233.51363)
		(end 268.327378 -233.51363)
		(width 0.14478)
		(layer "In11.Cu")
		(net "M_F_CPU0_SA_DQ<31>")
	)
	(segment
		(start 267.770864 -234.310174)
		(end 267.933932 -234.147106)
		(width 0.14478)
		(layer "In11.Cu")
		(net "M_F_CPU0_SA_DQ<31>")
	)
	(segment
		(start 297.32986 -234.310174)
		(end 298.179998 -233.460036)
		(width 0.14478)
		(layer "In11.Cu")
		(net "M_F_CPU0_SA_DQ<31>")
	)
	(segment
		(start 315.811154 -243.52123)
		(end 323.870574 -243.52123)
		(width 0.14478)
		(layer "In11.Cu")
		(net "M_F_CPU0_SA_DQ<31>")
	)
	(segment
		(start 301.095156 -233.460036)
		(end 301.945294 -234.310174)
		(width 0.14478)
		(layer "In11.Cu")
		(net "M_F_CPU0_SA_DQ<31>")
	)
	(segment
		(start 279.33396 -234.310174)
		(end 282.298648 -234.310174)
		(width 0.14478)
		(layer "In11.Cu")
		(net "M_F_CPU0_SA_DQ<31>")
	)
	(segment
		(start 278.483822 -233.460036)
		(end 279.33396 -234.310174)
		(width 0.14478)
		(layer "In11.Cu")
		(net "M_F_CPU0_SA_DQ<31>")
	)
	(segment
		(start 268.653514 -234.310174)
		(end 274.667726 -234.310174)
		(width 0.14478)
		(layer "In11.Cu")
		(net "M_F_CPU0_SA_DQ<31>")
	)
	(segment
		(start 324.147434 -243.52123)
		(end 324.439534 -243.81333)
		(width 0.0889)
		(layer "In11.Cu")
		(net "M_F_CPU0_SA_DQ<31>")
	)
	(segment
		(start 267.540486 -234.310174)
		(end 267.770864 -234.310174)
		(width 0.14478)
		(layer "In11.Cu")
		(net "M_F_CPU0_SA_DQ<31>")
	)
	(segment
		(start 265.54811 -233.884978)
		(end 265.973306 -234.310174)
		(width 0.14478)
		(layer "In11.Cu")
		(net "M_F_CPU0_SA_DQ<31>")
	)
	(segment
		(start 301.945294 -234.310174)
		(end 307.599334 -234.310174)
		(width 0.14478)
		(layer "In11.Cu")
		(net "M_F_CPU0_SA_DQ<31>")
	)
	(segment
		(start 274.667726 -234.310174)
		(end 275.517864 -233.460036)
		(width 0.14478)
		(layer "In11.Cu")
		(net "M_F_CPU0_SA_DQ<31>")
	)
	(segment
		(start 290.682172 -233.460036)
		(end 293.558722 -233.460036)
		(width 0.14478)
		(layer "In11.Cu")
		(net "M_F_CPU0_SA_DQ<31>")
	)
	(segment
		(start 286.053276 -233.460036)
		(end 286.903414 -234.310174)
		(width 0.14478)
		(layer "In11.Cu")
		(net "M_F_CPU0_SA_DQ<31>")
	)
	(segment
		(start 267.377418 -234.147106)
		(end 267.540486 -234.310174)
		(width 0.14478)
		(layer "In11.Cu")
		(net "M_F_CPU0_SA_DQ<31>")
	)
	(segment
		(start 308.403498 -236.113574)
		(end 315.811154 -243.52123)
		(width 0.14478)
		(layer "In11.Cu")
		(net "M_F_CPU0_SA_DQ<31>")
	)
	(segment
		(start 268.327378 -233.51363)
		(end 268.490446 -233.676698)
		(width 0.14478)
		(layer "In11.Cu")
		(net "M_F_CPU0_SA_DQ<31>")
	)
	(arc
		(start 326.351138 -244.23751)
		(mid 326.497513 -244.218231)
		(end 326.63384 -244.161564)
		(width 0.0889)
		(layer "In11.Cu")
		(net "M_F_CPU0_SA_DQ<31>")
	)
	(arc
		(start 328.88809 -244.161564)
		(mid 329.171046 -244.237741)
		(end 329.454002 -244.161564)
		(width 0.0889)
		(layer "In11.Cu")
		(net "M_F_CPU0_SA_DQ<31>")
	)
	(arc
		(start 332.648052 -244.161564)
		(mid 332.931008 -244.237741)
		(end 333.213964 -244.161564)
		(width 0.0889)
		(layer "In11.Cu")
		(net "M_F_CPU0_SA_DQ<31>")
	)
	(arc
		(start 329.454002 -244.161564)
		(mid 329.636253 -244.111214)
		(end 329.819762 -244.156738)
		(width 0.0889)
		(layer "In11.Cu")
		(net "M_F_CPU0_SA_DQ<31>")
	)
	(arc
		(start 331.342492 -244.156738)
		(mid 331.526 -244.111244)
		(end 331.708252 -244.161564)
		(width 0.0889)
		(layer "In11.Cu")
		(net "M_F_CPU0_SA_DQ<31>")
	)
	(arc
		(start 326.645524 -244.154706)
		(mid 326.827525 -244.111173)
		(end 327.007728 -244.161564)
		(width 0.0889)
		(layer "In11.Cu")
		(net "M_F_CPU0_SA_DQ<31>")
	)
	(arc
		(start 328.514202 -244.161564)
		(mid 328.701146 -244.111309)
		(end 328.88809 -244.161564)
		(width 0.0889)
		(layer "In11.Cu")
		(net "M_F_CPU0_SA_DQ<31>")
	)
	(arc
		(start 333.213964 -244.161564)
		(mid 333.370402 -244.112593)
		(end 333.532734 -244.135402)
		(width 0.0889)
		(layer "In11.Cu")
		(net "M_F_CPU0_SA_DQ<31>")
	)
	(arc
		(start 330.768198 -244.161564)
		(mid 331.051154 -244.237741)
		(end 331.33411 -244.161564)
		(width 0.0889)
		(layer "In11.Cu")
		(net "M_F_CPU0_SA_DQ<31>")
	)
	(arc
		(start 332.274164 -244.161564)
		(mid 332.461108 -244.111309)
		(end 332.648052 -244.161564)
		(width 0.0889)
		(layer "In11.Cu")
		(net "M_F_CPU0_SA_DQ<31>")
	)
	(arc
		(start 327.94829 -244.161564)
		(mid 328.231246 -244.237741)
		(end 328.514202 -244.161564)
		(width 0.0889)
		(layer "In11.Cu")
		(net "M_F_CPU0_SA_DQ<31>")
	)
	(arc
		(start 330.402438 -244.156738)
		(mid 330.585946 -244.111244)
		(end 330.768198 -244.161564)
		(width 0.0889)
		(layer "In11.Cu")
		(net "M_F_CPU0_SA_DQ<31>")
	)
	(arc
		(start 331.708252 -244.161564)
		(mid 331.991208 -244.237741)
		(end 332.274164 -244.161564)
		(width 0.0889)
		(layer "In11.Cu")
		(net "M_F_CPU0_SA_DQ<31>")
	)
	(arc
		(start 327.018142 -244.16766)
		(mid 327.296828 -244.23788)
		(end 327.573894 -244.161564)
		(width 0.0889)
		(layer "In11.Cu")
		(net "M_F_CPU0_SA_DQ<31>")
	)
	(arc
		(start 327.573894 -244.161564)
		(mid 327.761092 -244.111182)
		(end 327.94829 -244.161564)
		(width 0.0889)
		(layer "In11.Cu")
		(net "M_F_CPU0_SA_DQ<31>")
	)
	(arc
		(start 329.828144 -244.161564)
		(mid 330.1111 -244.237741)
		(end 330.394056 -244.161564)
		(width 0.0889)
		(layer "In11.Cu")
		(net "M_F_CPU0_SA_DQ<31>")
	)
	(segment
		(start 332.45806 -243.940076)
		(end 331.991208 -243.674138)
		(width 0.10668)
		(layer "F.Cu")
		(net "M_F_CPU0_SA_DQ<30>")
	)
	(segment
		(start 325.038974 -242.76939)
		(end 325.57085 -243.301266)
		(width 0.0889)
		(layer "In11.Cu")
		(net "M_F_CPU0_SA_DQ<30>")
	)
	(segment
		(start 266.575032 -232.610152)
		(end 266.7381 -232.447084)
		(width 0.14478)
		(layer "In11.Cu")
		(net "M_F_CPU0_SA_DQ<30>")
	)
	(segment
		(start 327.08723 -243.362226)
		(end 327.105264 -243.351558)
		(width 0.0889)
		(layer "In11.Cu")
		(net "M_F_CPU0_SA_DQ<30>")
	)
	(segment
		(start 327.465182 -243.343938)
		(end 327.478898 -243.351812)
		(width 0.0889)
		(layer "In11.Cu")
		(net "M_F_CPU0_SA_DQ<30>")
	)
	(segment
		(start 282.298648 -232.610152)
		(end 283.148786 -231.760014)
		(width 0.14478)
		(layer "In11.Cu")
		(net "M_F_CPU0_SA_DQ<30>")
	)
	(segment
		(start 301.945294 -232.610152)
		(end 307.433472 -232.610152)
		(width 0.14478)
		(layer "In11.Cu")
		(net "M_F_CPU0_SA_DQ<30>")
	)
	(segment
		(start 265.54811 -232.184956)
		(end 265.973306 -232.610152)
		(width 0.14478)
		(layer "In11.Cu")
		(net "M_F_CPU0_SA_DQ<30>")
	)
	(segment
		(start 297.32986 -232.610152)
		(end 298.179998 -231.760014)
		(width 0.14478)
		(layer "In11.Cu")
		(net "M_F_CPU0_SA_DQ<30>")
	)
	(segment
		(start 268.715744 -231.66324)
		(end 268.715744 -232.447084)
		(width 0.14478)
		(layer "In11.Cu")
		(net "M_F_CPU0_SA_DQ<30>")
	)
	(segment
		(start 274.667726 -232.610152)
		(end 275.517864 -231.760014)
		(width 0.14478)
		(layer "In11.Cu")
		(net "M_F_CPU0_SA_DQ<30>")
	)
	(segment
		(start 323.918834 -242.61191)
		(end 324.213474 -242.61191)
		(width 0.0889)
		(layer "In11.Cu")
		(net "M_F_CPU0_SA_DQ<30>")
	)
	(segment
		(start 265.973306 -232.610152)
		(end 266.575032 -232.610152)
		(width 0.14478)
		(layer "In11.Cu")
		(net "M_F_CPU0_SA_DQ<30>")
	)
	(segment
		(start 298.179998 -231.760014)
		(end 301.095156 -231.760014)
		(width 0.14478)
		(layer "In11.Cu")
		(net "M_F_CPU0_SA_DQ<30>")
	)
	(segment
		(start 286.903414 -232.610152)
		(end 289.832034 -232.610152)
		(width 0.14478)
		(layer "In11.Cu")
		(net "M_F_CPU0_SA_DQ<30>")
	)
	(segment
		(start 327.478898 -243.351812)
		(end 327.490836 -243.35867)
		(width 0.0889)
		(layer "In11.Cu")
		(net "M_F_CPU0_SA_DQ<30>")
	)
	(segment
		(start 328.409808 -243.346732)
		(end 328.41819 -243.351558)
		(width 0.0889)
		(layer "In11.Cu")
		(net "M_F_CPU0_SA_DQ<30>")
	)
	(segment
		(start 266.7381 -231.957118)
		(end 266.901168 -231.79405)
		(width 0.14478)
		(layer "In11.Cu")
		(net "M_F_CPU0_SA_DQ<30>")
	)
	(segment
		(start 332.145132 -243.408708)
		(end 331.991208 -243.674138)
		(width 0.0889)
		(layer "In11.Cu")
		(net "M_F_CPU0_SA_DQ<30>")
	)
	(segment
		(start 290.682172 -231.760014)
		(end 293.558722 -231.760014)
		(width 0.14478)
		(layer "In11.Cu")
		(net "M_F_CPU0_SA_DQ<30>")
	)
	(segment
		(start 268.878812 -232.610152)
		(end 274.667726 -232.610152)
		(width 0.14478)
		(layer "In11.Cu")
		(net "M_F_CPU0_SA_DQ<30>")
	)
	(segment
		(start 331.229716 -243.346732)
		(end 331.238098 -243.351558)
		(width 0.0889)
		(layer "In11.Cu")
		(net "M_F_CPU0_SA_DQ<30>")
	)
	(segment
		(start 283.148786 -231.760014)
		(end 286.053276 -231.760014)
		(width 0.14478)
		(layer "In11.Cu")
		(net "M_F_CPU0_SA_DQ<30>")
	)
	(segment
		(start 275.517864 -231.760014)
		(end 278.483822 -231.760014)
		(width 0.14478)
		(layer "In11.Cu")
		(net "M_F_CPU0_SA_DQ<30>")
	)
	(segment
		(start 268.15923 -232.634282)
		(end 268.15923 -231.66324)
		(width 0.14478)
		(layer "In11.Cu")
		(net "M_F_CPU0_SA_DQ<30>")
	)
	(segment
		(start 316.18809 -242.61191)
		(end 323.918834 -242.61191)
		(width 0.14478)
		(layer "In11.Cu")
		(net "M_F_CPU0_SA_DQ<30>")
	)
	(segment
		(start 267.457682 -232.79735)
		(end 267.996162 -232.79735)
		(width 0.14478)
		(layer "In11.Cu")
		(net "M_F_CPU0_SA_DQ<30>")
	)
	(segment
		(start 268.322298 -231.500172)
		(end 268.552676 -231.500172)
		(width 0.14478)
		(layer "In11.Cu")
		(net "M_F_CPU0_SA_DQ<30>")
	)
	(segment
		(start 332.12278 -243.325396)
		(end 332.145132 -243.408708)
		(width 0.0889)
		(layer "In11.Cu")
		(net "M_F_CPU0_SA_DQ<30>")
	)
	(segment
		(start 324.213474 -242.61191)
		(end 324.370954 -242.76939)
		(width 0.0889)
		(layer "In11.Cu")
		(net "M_F_CPU0_SA_DQ<30>")
	)
	(segment
		(start 266.7381 -232.447084)
		(end 266.7381 -231.957118)
		(width 0.14478)
		(layer "In11.Cu")
		(net "M_F_CPU0_SA_DQ<30>")
	)
	(segment
		(start 267.996162 -232.79735)
		(end 268.15923 -232.634282)
		(width 0.14478)
		(layer "In11.Cu")
		(net "M_F_CPU0_SA_DQ<30>")
	)
	(segment
		(start 328.984102 -243.351558)
		(end 328.992484 -243.346732)
		(width 0.0889)
		(layer "In11.Cu")
		(net "M_F_CPU0_SA_DQ<30>")
	)
	(segment
		(start 267.294614 -232.634282)
		(end 267.457682 -232.79735)
		(width 0.14478)
		(layer "In11.Cu")
		(net "M_F_CPU0_SA_DQ<30>")
	)
	(segment
		(start 309.354474 -235.778294)
		(end 316.18809 -242.61191)
		(width 0.14478)
		(layer "In11.Cu")
		(net "M_F_CPU0_SA_DQ<30>")
	)
	(segment
		(start 268.15923 -231.66324)
		(end 268.322298 -231.500172)
		(width 0.14478)
		(layer "In11.Cu")
		(net "M_F_CPU0_SA_DQ<30>")
	)
	(segment
		(start 325.57085 -243.301266)
		(end 326.351138 -243.301266)
		(width 0.0889)
		(layer "In11.Cu")
		(net "M_F_CPU0_SA_DQ<30>")
	)
	(segment
		(start 286.053276 -231.760014)
		(end 286.903414 -232.610152)
		(width 0.14478)
		(layer "In11.Cu")
		(net "M_F_CPU0_SA_DQ<30>")
	)
	(segment
		(start 278.483822 -231.760014)
		(end 279.33396 -232.610152)
		(width 0.14478)
		(layer "In11.Cu")
		(net "M_F_CPU0_SA_DQ<30>")
	)
	(segment
		(start 307.433472 -232.610152)
		(end 309.354474 -234.531154)
		(width 0.14478)
		(layer "In11.Cu")
		(net "M_F_CPU0_SA_DQ<30>")
	)
	(segment
		(start 294.40886 -232.610152)
		(end 297.32986 -232.610152)
		(width 0.14478)
		(layer "In11.Cu")
		(net "M_F_CPU0_SA_DQ<30>")
	)
	(segment
		(start 289.832034 -232.610152)
		(end 290.682172 -231.760014)
		(width 0.14478)
		(layer "In11.Cu")
		(net "M_F_CPU0_SA_DQ<30>")
	)
	(segment
		(start 301.095156 -231.760014)
		(end 301.945294 -232.610152)
		(width 0.14478)
		(layer "In11.Cu")
		(net "M_F_CPU0_SA_DQ<30>")
	)
	(segment
		(start 279.33396 -232.610152)
		(end 282.298648 -232.610152)
		(width 0.14478)
		(layer "In11.Cu")
		(net "M_F_CPU0_SA_DQ<30>")
	)
	(segment
		(start 293.558722 -231.760014)
		(end 294.40886 -232.610152)
		(width 0.14478)
		(layer "In11.Cu")
		(net "M_F_CPU0_SA_DQ<30>")
	)
	(segment
		(start 267.294614 -231.957118)
		(end 267.294614 -232.634282)
		(width 0.14478)
		(layer "In11.Cu")
		(net "M_F_CPU0_SA_DQ<30>")
	)
	(segment
		(start 324.370954 -242.76939)
		(end 325.038974 -242.76939)
		(width 0.0889)
		(layer "In11.Cu")
		(net "M_F_CPU0_SA_DQ<30>")
	)
	(segment
		(start 268.715744 -232.447084)
		(end 268.878812 -232.610152)
		(width 0.14478)
		(layer "In11.Cu")
		(net "M_F_CPU0_SA_DQ<30>")
	)
	(segment
		(start 268.552676 -231.500172)
		(end 268.715744 -231.66324)
		(width 0.14478)
		(layer "In11.Cu")
		(net "M_F_CPU0_SA_DQ<30>")
	)
	(segment
		(start 266.901168 -231.79405)
		(end 267.131546 -231.79405)
		(width 0.14478)
		(layer "In11.Cu")
		(net "M_F_CPU0_SA_DQ<30>")
	)
	(segment
		(start 309.354474 -234.531154)
		(end 309.354474 -235.778294)
		(width 0.14478)
		(layer "In11.Cu")
		(net "M_F_CPU0_SA_DQ<30>")
	)
	(segment
		(start 267.131546 -231.79405)
		(end 267.294614 -231.957118)
		(width 0.14478)
		(layer "In11.Cu")
		(net "M_F_CPU0_SA_DQ<30>")
	)
	(arc
		(start 326.53859 -243.351558)
		(mid 326.811534 -243.428138)
		(end 327.08723 -243.362226)
		(width 0.0889)
		(layer "In11.Cu")
		(net "M_F_CPU0_SA_DQ<30>")
	)
	(arc
		(start 331.238098 -243.351558)
		(mid 331.521054 -243.427735)
		(end 331.80401 -243.351558)
		(width 0.0889)
		(layer "In11.Cu")
		(net "M_F_CPU0_SA_DQ<30>")
	)
	(arc
		(start 326.351138 -243.301266)
		(mid 326.448201 -243.313984)
		(end 326.53859 -243.351558)
		(width 0.0889)
		(layer "In11.Cu")
		(net "M_F_CPU0_SA_DQ<30>")
	)
	(arc
		(start 327.105264 -243.351558)
		(mid 327.284251 -243.301388)
		(end 327.465182 -243.343938)
		(width 0.0889)
		(layer "In11.Cu")
		(net "M_F_CPU0_SA_DQ<30>")
	)
	(arc
		(start 328.044048 -243.351558)
		(mid 328.226299 -243.301208)
		(end 328.409808 -243.346732)
		(width 0.0889)
		(layer "In11.Cu")
		(net "M_F_CPU0_SA_DQ<30>")
	)
	(arc
		(start 331.80401 -243.351558)
		(mid 331.960448 -243.302587)
		(end 332.12278 -243.325396)
		(width 0.0889)
		(layer "In11.Cu")
		(net "M_F_CPU0_SA_DQ<30>")
	)
	(arc
		(start 328.992484 -243.346732)
		(mid 329.175992 -243.301238)
		(end 329.358244 -243.351558)
		(width 0.0889)
		(layer "In11.Cu")
		(net "M_F_CPU0_SA_DQ<30>")
	)
	(arc
		(start 329.924156 -243.351558)
		(mid 330.1111 -243.301303)
		(end 330.298044 -243.351558)
		(width 0.0889)
		(layer "In11.Cu")
		(net "M_F_CPU0_SA_DQ<30>")
	)
	(arc
		(start 329.358244 -243.351558)
		(mid 329.6412 -243.427735)
		(end 329.924156 -243.351558)
		(width 0.0889)
		(layer "In11.Cu")
		(net "M_F_CPU0_SA_DQ<30>")
	)
	(arc
		(start 328.41819 -243.351558)
		(mid 328.701146 -243.427735)
		(end 328.984102 -243.351558)
		(width 0.0889)
		(layer "In11.Cu")
		(net "M_F_CPU0_SA_DQ<30>")
	)
	(arc
		(start 330.298044 -243.351558)
		(mid 330.581 -243.427735)
		(end 330.863956 -243.351558)
		(width 0.0889)
		(layer "In11.Cu")
		(net "M_F_CPU0_SA_DQ<30>")
	)
	(arc
		(start 327.490836 -243.35867)
		(mid 327.76837 -243.427651)
		(end 328.044048 -243.351558)
		(width 0.0889)
		(layer "In11.Cu")
		(net "M_F_CPU0_SA_DQ<30>")
	)
	(arc
		(start 330.863956 -243.351558)
		(mid 331.046207 -243.301208)
		(end 331.229716 -243.346732)
		(width 0.0889)
		(layer "In11.Cu")
		(net "M_F_CPU0_SA_DQ<30>")
	)
	(segment
		(start 332.45806 -226.120198)
		(end 331.991208 -225.85426)
		(width 0.10668)
		(layer "F.Cu")
		(net "M_F_CPU0_SA_DQ<2>")
	)
	(segment
		(start 326.989694 -221.25813)
		(end 326.989694 -221.416118)
		(width 0.0889)
		(layer "In11.Cu")
		(net "M_F_CPU0_SA_DQ<2>")
	)
	(segment
		(start 301.095156 -197.760082)
		(end 301.945294 -198.61022)
		(width 0.14478)
		(layer "In11.Cu")
		(net "M_F_CPU0_SA_DQ<2>")
	)
	(segment
		(start 286.053276 -197.760082)
		(end 286.903414 -198.61022)
		(width 0.14478)
		(layer "In11.Cu")
		(net "M_F_CPU0_SA_DQ<2>")
	)
	(segment
		(start 327.47839 -222.291656)
		(end 327.51014 -222.309944)
		(width 0.0889)
		(layer "In11.Cu")
		(net "M_F_CPU0_SA_DQ<2>")
	)
	(segment
		(start 283.148786 -197.760082)
		(end 286.053276 -197.760082)
		(width 0.14478)
		(layer "In11.Cu")
		(net "M_F_CPU0_SA_DQ<2>")
	)
	(segment
		(start 327.94829 -223.101662)
		(end 327.98004 -223.11995)
		(width 0.0889)
		(layer "In11.Cu")
		(net "M_F_CPU0_SA_DQ<2>")
	)
	(segment
		(start 266.57173 -198.61022)
		(end 266.734798 -198.447152)
		(width 0.14478)
		(layer "In11.Cu")
		(net "M_F_CPU0_SA_DQ<2>")
	)
	(segment
		(start 266.897866 -197.77583)
		(end 267.128244 -197.77583)
		(width 0.14478)
		(layer "In11.Cu")
		(net "M_F_CPU0_SA_DQ<2>")
	)
	(segment
		(start 304.8762 -198.61022)
		(end 305.726338 -197.760082)
		(width 0.14478)
		(layer "In11.Cu")
		(net "M_F_CPU0_SA_DQ<2>")
	)
	(segment
		(start 267.45438 -198.61022)
		(end 274.667726 -198.61022)
		(width 0.14478)
		(layer "In11.Cu")
		(net "M_F_CPU0_SA_DQ<2>")
	)
	(segment
		(start 265.54811 -198.185024)
		(end 265.973306 -198.61022)
		(width 0.14478)
		(layer "In11.Cu")
		(net "M_F_CPU0_SA_DQ<2>")
	)
	(segment
		(start 274.667726 -198.61022)
		(end 275.517864 -197.760082)
		(width 0.14478)
		(layer "In11.Cu")
		(net "M_F_CPU0_SA_DQ<2>")
	)
	(segment
		(start 324.525894 -214.54745)
		(end 324.525894 -218.61653)
		(width 0.14478)
		(layer "In11.Cu")
		(net "M_F_CPU0_SA_DQ<2>")
	)
	(segment
		(start 328.41819 -223.911668)
		(end 328.44994 -223.929956)
		(width 0.0889)
		(layer "In11.Cu")
		(net "M_F_CPU0_SA_DQ<2>")
	)
	(segment
		(start 332.145132 -225.58883)
		(end 331.991208 -225.85426)
		(width 0.0889)
		(layer "In11.Cu")
		(net "M_F_CPU0_SA_DQ<2>")
	)
	(segment
		(start 327.195688 -221.622112)
		(end 327.195688 -221.80423)
		(width 0.0889)
		(layer "In11.Cu")
		(net "M_F_CPU0_SA_DQ<2>")
	)
	(segment
		(start 289.832034 -198.61022)
		(end 290.682172 -197.760082)
		(width 0.14478)
		(layer "In11.Cu")
		(net "M_F_CPU0_SA_DQ<2>")
	)
	(segment
		(start 327.438004 -222.268034)
		(end 327.47839 -222.291656)
		(width 0.0889)
		(layer "In11.Cu")
		(net "M_F_CPU0_SA_DQ<2>")
	)
	(segment
		(start 328.984102 -225.53168)
		(end 328.992484 -225.526854)
		(width 0.0889)
		(layer "In11.Cu")
		(net "M_F_CPU0_SA_DQ<2>")
	)
	(segment
		(start 266.734798 -198.447152)
		(end 266.734798 -197.938898)
		(width 0.14478)
		(layer "In11.Cu")
		(net "M_F_CPU0_SA_DQ<2>")
	)
	(segment
		(start 301.945294 -198.61022)
		(end 304.8762 -198.61022)
		(width 0.14478)
		(layer "In11.Cu")
		(net "M_F_CPU0_SA_DQ<2>")
	)
	(segment
		(start 328.41819 -224.556828)
		(end 328.379074 -224.579688)
		(width 0.0889)
		(layer "In11.Cu")
		(net "M_F_CPU0_SA_DQ<2>")
	)
	(segment
		(start 307.738526 -197.760082)
		(end 324.525894 -214.54745)
		(width 0.14478)
		(layer "In11.Cu")
		(net "M_F_CPU0_SA_DQ<2>")
	)
	(segment
		(start 286.903414 -198.61022)
		(end 289.832034 -198.61022)
		(width 0.14478)
		(layer "In11.Cu")
		(net "M_F_CPU0_SA_DQ<2>")
	)
	(segment
		(start 324.525894 -218.61653)
		(end 326.989694 -221.08033)
		(width 0.14478)
		(layer "In11.Cu")
		(net "M_F_CPU0_SA_DQ<2>")
	)
	(segment
		(start 278.483822 -197.760082)
		(end 279.33396 -198.61022)
		(width 0.14478)
		(layer "In11.Cu")
		(net "M_F_CPU0_SA_DQ<2>")
	)
	(segment
		(start 297.32986 -198.61022)
		(end 298.179998 -197.760082)
		(width 0.14478)
		(layer "In11.Cu")
		(net "M_F_CPU0_SA_DQ<2>")
	)
	(segment
		(start 328.379074 -225.50882)
		(end 328.41819 -225.53168)
		(width 0.0889)
		(layer "In11.Cu")
		(net "M_F_CPU0_SA_DQ<2>")
	)
	(segment
		(start 328.44994 -224.53854)
		(end 328.41819 -224.556828)
		(width 0.0889)
		(layer "In11.Cu")
		(net "M_F_CPU0_SA_DQ<2>")
	)
	(segment
		(start 305.726338 -197.760082)
		(end 307.738526 -197.760082)
		(width 0.14478)
		(layer "In11.Cu")
		(net "M_F_CPU0_SA_DQ<2>")
	)
	(segment
		(start 326.989694 -221.416118)
		(end 327.195688 -221.622112)
		(width 0.0889)
		(layer "In11.Cu")
		(net "M_F_CPU0_SA_DQ<2>")
	)
	(segment
		(start 266.734798 -197.938898)
		(end 266.897866 -197.77583)
		(width 0.14478)
		(layer "In11.Cu")
		(net "M_F_CPU0_SA_DQ<2>")
	)
	(segment
		(start 282.298648 -198.61022)
		(end 283.148786 -197.760082)
		(width 0.14478)
		(layer "In11.Cu")
		(net "M_F_CPU0_SA_DQ<2>")
	)
	(segment
		(start 327.911968 -223.08058)
		(end 327.94829 -223.101662)
		(width 0.0889)
		(layer "In11.Cu")
		(net "M_F_CPU0_SA_DQ<2>")
	)
	(segment
		(start 267.291312 -197.938898)
		(end 267.291312 -198.447152)
		(width 0.14478)
		(layer "In11.Cu")
		(net "M_F_CPU0_SA_DQ<2>")
	)
	(segment
		(start 331.229716 -225.526854)
		(end 331.238098 -225.53168)
		(width 0.0889)
		(layer "In11.Cu")
		(net "M_F_CPU0_SA_DQ<2>")
	)
	(segment
		(start 294.40886 -198.61022)
		(end 297.32986 -198.61022)
		(width 0.14478)
		(layer "In11.Cu")
		(net "M_F_CPU0_SA_DQ<2>")
	)
	(segment
		(start 267.291312 -198.447152)
		(end 267.45438 -198.61022)
		(width 0.14478)
		(layer "In11.Cu")
		(net "M_F_CPU0_SA_DQ<2>")
	)
	(segment
		(start 332.12278 -225.505518)
		(end 332.145132 -225.58883)
		(width 0.0889)
		(layer "In11.Cu")
		(net "M_F_CPU0_SA_DQ<2>")
	)
	(segment
		(start 328.381868 -223.890586)
		(end 328.41819 -223.911668)
		(width 0.0889)
		(layer "In11.Cu")
		(net "M_F_CPU0_SA_DQ<2>")
	)
	(segment
		(start 279.33396 -198.61022)
		(end 282.298648 -198.61022)
		(width 0.14478)
		(layer "In11.Cu")
		(net "M_F_CPU0_SA_DQ<2>")
	)
	(segment
		(start 265.973306 -198.61022)
		(end 266.57173 -198.61022)
		(width 0.14478)
		(layer "In11.Cu")
		(net "M_F_CPU0_SA_DQ<2>")
	)
	(segment
		(start 293.558722 -197.760082)
		(end 294.40886 -198.61022)
		(width 0.14478)
		(layer "In11.Cu")
		(net "M_F_CPU0_SA_DQ<2>")
	)
	(segment
		(start 326.989694 -221.08033)
		(end 326.989694 -221.25813)
		(width 0.14478)
		(layer "In11.Cu")
		(net "M_F_CPU0_SA_DQ<2>")
	)
	(segment
		(start 275.517864 -197.760082)
		(end 278.483822 -197.760082)
		(width 0.14478)
		(layer "In11.Cu")
		(net "M_F_CPU0_SA_DQ<2>")
	)
	(segment
		(start 298.179998 -197.760082)
		(end 301.095156 -197.760082)
		(width 0.14478)
		(layer "In11.Cu")
		(net "M_F_CPU0_SA_DQ<2>")
	)
	(segment
		(start 290.682172 -197.760082)
		(end 293.558722 -197.760082)
		(width 0.14478)
		(layer "In11.Cu")
		(net "M_F_CPU0_SA_DQ<2>")
	)
	(segment
		(start 267.128244 -197.77583)
		(end 267.291312 -197.938898)
		(width 0.14478)
		(layer "In11.Cu")
		(net "M_F_CPU0_SA_DQ<2>")
	)
	(arc
		(start 330.298044 -225.53168)
		(mid 330.581 -225.607857)
		(end 330.863956 -225.53168)
		(width 0.0889)
		(layer "In11.Cu")
		(net "M_F_CPU0_SA_DQ<2>")
	)
	(arc
		(start 328.135996 -223.424242)
		(mid 328.201232 -223.687833)
		(end 328.381868 -223.890586)
		(width 0.0889)
		(layer "In11.Cu")
		(net "M_F_CPU0_SA_DQ<2>")
	)
	(arc
		(start 328.379074 -224.579688)
		(mid 328.135747 -225.044254)
		(end 328.379074 -225.50882)
		(width 0.0889)
		(layer "In11.Cu")
		(net "M_F_CPU0_SA_DQ<2>")
	)
	(arc
		(start 331.238098 -225.53168)
		(mid 331.521054 -225.607857)
		(end 331.80401 -225.53168)
		(width 0.0889)
		(layer "In11.Cu")
		(net "M_F_CPU0_SA_DQ<2>")
	)
	(arc
		(start 328.41819 -225.53168)
		(mid 328.701146 -225.607857)
		(end 328.984102 -225.53168)
		(width 0.0889)
		(layer "In11.Cu")
		(net "M_F_CPU0_SA_DQ<2>")
	)
	(arc
		(start 329.924156 -225.53168)
		(mid 330.1111 -225.481425)
		(end 330.298044 -225.53168)
		(width 0.0889)
		(layer "In11.Cu")
		(net "M_F_CPU0_SA_DQ<2>")
	)
	(arc
		(start 330.863956 -225.53168)
		(mid 331.046207 -225.48133)
		(end 331.229716 -225.526854)
		(width 0.0889)
		(layer "In11.Cu")
		(net "M_F_CPU0_SA_DQ<2>")
	)
	(arc
		(start 327.98004 -223.11995)
		(mid 328.094716 -223.253284)
		(end 328.135996 -223.424242)
		(width 0.0889)
		(layer "In11.Cu")
		(net "M_F_CPU0_SA_DQ<2>")
	)
	(arc
		(start 328.992484 -225.526854)
		(mid 329.175992 -225.48136)
		(end 329.358244 -225.53168)
		(width 0.0889)
		(layer "In11.Cu")
		(net "M_F_CPU0_SA_DQ<2>")
	)
	(arc
		(start 328.44994 -223.929956)
		(mid 328.605868 -224.234248)
		(end 328.44994 -224.53854)
		(width 0.0889)
		(layer "In11.Cu")
		(net "M_F_CPU0_SA_DQ<2>")
	)
	(arc
		(start 331.80401 -225.53168)
		(mid 331.960448 -225.482709)
		(end 332.12278 -225.505518)
		(width 0.0889)
		(layer "In11.Cu")
		(net "M_F_CPU0_SA_DQ<2>")
	)
	(arc
		(start 329.358244 -225.53168)
		(mid 329.6412 -225.607857)
		(end 329.924156 -225.53168)
		(width 0.0889)
		(layer "In11.Cu")
		(net "M_F_CPU0_SA_DQ<2>")
	)
	(arc
		(start 327.51014 -222.309944)
		(mid 327.624816 -222.443278)
		(end 327.666096 -222.614236)
		(width 0.0889)
		(layer "In11.Cu")
		(net "M_F_CPU0_SA_DQ<2>")
	)
	(arc
		(start 327.666096 -222.614236)
		(mid 327.731332 -222.877827)
		(end 327.911968 -223.08058)
		(width 0.0889)
		(layer "In11.Cu")
		(net "M_F_CPU0_SA_DQ<2>")
	)
	(arc
		(start 327.195688 -221.80423)
		(mid 327.259981 -222.065835)
		(end 327.438004 -222.268034)
		(width 0.0889)
		(layer "In11.Cu")
		(net "M_F_CPU0_SA_DQ<2>")
	)
	(segment
		(start 334.337914 -243.940076)
		(end 333.871062 -243.674138)
		(width 0.10668)
		(layer "F.Cu")
		(net "M_F_CPU0_SA_DQ<29>")
	)
	(segment
		(start 296.782236 -233.84637)
		(end 296.945304 -233.683302)
		(width 0.14478)
		(layer "In11.Cu")
		(net "M_F_CPU0_SA_DQ<29>")
	)
	(segment
		(start 272.383504 -233.690922)
		(end 272.383504 -233.623104)
		(width 0.14478)
		(layer "In11.Cu")
		(net "M_F_CPU0_SA_DQ<29>")
	)
	(segment
		(start 270.07312 -233.460036)
		(end 270.550894 -233.460036)
		(width 0.14478)
		(layer "In11.Cu")
		(net "M_F_CPU0_SA_DQ<29>")
	)
	(segment
		(start 281.616404 -233.85399)
		(end 281.779472 -233.690922)
		(width 0.14478)
		(layer "In11.Cu")
		(net "M_F_CPU0_SA_DQ<29>")
	)
	(segment
		(start 271.270476 -233.690922)
		(end 271.270476 -233.22915)
		(width 0.14478)
		(layer "In11.Cu")
		(net "M_F_CPU0_SA_DQ<29>")
	)
	(segment
		(start 271.433544 -233.066082)
		(end 271.663922 -233.066082)
		(width 0.14478)
		(layer "In11.Cu")
		(net "M_F_CPU0_SA_DQ<29>")
	)
	(segment
		(start 282.323286 -233.460036)
		(end 283.17317 -232.610152)
		(width 0.14478)
		(layer "In11.Cu")
		(net "M_F_CPU0_SA_DQ<29>")
	)
	(segment
		(start 306.032408 -233.857292)
		(end 306.294282 -233.857292)
		(width 0.14478)
		(layer "In11.Cu")
		(net "M_F_CPU0_SA_DQ<29>")
	)
	(segment
		(start 289.883088 -233.460036)
		(end 290.732972 -232.610152)
		(width 0.14478)
		(layer "In11.Cu")
		(net "M_F_CPU0_SA_DQ<29>")
	)
	(segment
		(start 298.513754 -232.610152)
		(end 298.676822 -232.77322)
		(width 0.14478)
		(layer "In11.Cu")
		(net "M_F_CPU0_SA_DQ<29>")
	)
	(segment
		(start 296.945304 -233.683302)
		(end 296.945304 -233.623104)
		(width 0.14478)
		(layer "In11.Cu")
		(net "M_F_CPU0_SA_DQ<29>")
	)
	(segment
		(start 305.887628 -233.712512)
		(end 306.032408 -233.857292)
		(width 0.14478)
		(layer "In11.Cu")
		(net "M_F_CPU0_SA_DQ<29>")
	)
	(segment
		(start 271.663922 -233.066082)
		(end 271.82699 -233.22915)
		(width 0.14478)
		(layer "In11.Cu")
		(net "M_F_CPU0_SA_DQ<29>")
	)
	(segment
		(start 270.713962 -233.690922)
		(end 270.87703 -233.85399)
		(width 0.14478)
		(layer "In11.Cu")
		(net "M_F_CPU0_SA_DQ<29>")
	)
	(segment
		(start 289.392106 -233.623104)
		(end 289.555174 -233.460036)
		(width 0.14478)
		(layer "In11.Cu")
		(net "M_F_CPU0_SA_DQ<29>")
	)
	(segment
		(start 286.742632 -233.460036)
		(end 288.672524 -233.460036)
		(width 0.14478)
		(layer "In11.Cu")
		(net "M_F_CPU0_SA_DQ<29>")
	)
	(segment
		(start 273.808952 -233.84637)
		(end 274.03933 -233.84637)
		(width 0.14478)
		(layer "In11.Cu")
		(net "M_F_CPU0_SA_DQ<29>")
	)
	(segment
		(start 303.537112 -233.460036)
		(end 303.681892 -233.604816)
		(width 0.14478)
		(layer "In11.Cu")
		(net "M_F_CPU0_SA_DQ<29>")
	)
	(segment
		(start 299.233336 -232.77322)
		(end 299.396404 -232.610152)
		(width 0.14478)
		(layer "In11.Cu")
		(net "M_F_CPU0_SA_DQ<29>")
	)
	(segment
		(start 276.035262 -232.77322)
		(end 276.035262 -232.829862)
		(width 0.14478)
		(layer "In11.Cu")
		(net "M_F_CPU0_SA_DQ<29>")
	)
	(segment
		(start 275.872194 -232.610152)
		(end 276.035262 -232.77322)
		(width 0.14478)
		(layer "In11.Cu")
		(net "M_F_CPU0_SA_DQ<29>")
	)
	(segment
		(start 289.555174 -233.460036)
		(end 289.883088 -233.460036)
		(width 0.14478)
		(layer "In11.Cu")
		(net "M_F_CPU0_SA_DQ<29>")
	)
	(segment
		(start 306.583842 -233.460036)
		(end 307.594762 -233.460036)
		(width 0.14478)
		(layer "In11.Cu")
		(net "M_F_CPU0_SA_DQ<29>")
	)
	(segment
		(start 294.357806 -233.460036)
		(end 296.225722 -233.460036)
		(width 0.14478)
		(layer "In11.Cu")
		(net "M_F_CPU0_SA_DQ<29>")
	)
	(segment
		(start 304.233326 -233.712512)
		(end 304.233326 -233.604816)
		(width 0.14478)
		(layer "In11.Cu")
		(net "M_F_CPU0_SA_DQ<29>")
	)
	(segment
		(start 306.439062 -233.604816)
		(end 306.583842 -233.460036)
		(width 0.14478)
		(layer "In11.Cu")
		(net "M_F_CPU0_SA_DQ<29>")
	)
	(segment
		(start 304.088546 -233.857292)
		(end 304.233326 -233.712512)
		(width 0.14478)
		(layer "In11.Cu")
		(net "M_F_CPU0_SA_DQ<29>")
	)
	(segment
		(start 306.294282 -233.857292)
		(end 306.439062 -233.712512)
		(width 0.14478)
		(layer "In11.Cu")
		(net "M_F_CPU0_SA_DQ<29>")
	)
	(segment
		(start 291.159438 -232.837482)
		(end 291.322506 -233.00055)
		(width 0.14478)
		(layer "In11.Cu")
		(net "M_F_CPU0_SA_DQ<29>")
	)
	(segment
		(start 289.229038 -233.85399)
		(end 289.392106 -233.690922)
		(width 0.14478)
		(layer "In11.Cu")
		(net "M_F_CPU0_SA_DQ<29>")
	)
	(segment
		(start 305.336194 -233.604816)
		(end 305.480974 -233.460036)
		(width 0.14478)
		(layer "In11.Cu")
		(net "M_F_CPU0_SA_DQ<29>")
	)
	(segment
		(start 301.90186 -233.460036)
		(end 303.537112 -233.460036)
		(width 0.14478)
		(layer "In11.Cu")
		(net "M_F_CPU0_SA_DQ<29>")
	)
	(segment
		(start 306.439062 -233.712512)
		(end 306.439062 -233.604816)
		(width 0.14478)
		(layer "In11.Cu")
		(net "M_F_CPU0_SA_DQ<29>")
	)
	(segment
		(start 276.19833 -232.99293)
		(end 276.428708 -232.99293)
		(width 0.14478)
		(layer "In11.Cu")
		(net "M_F_CPU0_SA_DQ<29>")
	)
	(segment
		(start 278.410924 -232.610152)
		(end 279.260808 -233.460036)
		(width 0.14478)
		(layer "In11.Cu")
		(net "M_F_CPU0_SA_DQ<29>")
	)
	(segment
		(start 307.594762 -233.460036)
		(end 308.903878 -234.769152)
		(width 0.14478)
		(layer "In11.Cu")
		(net "M_F_CPU0_SA_DQ<29>")
	)
	(segment
		(start 296.551858 -233.84637)
		(end 296.782236 -233.84637)
		(width 0.14478)
		(layer "In11.Cu")
		(net "M_F_CPU0_SA_DQ<29>")
	)
	(segment
		(start 279.260808 -233.460036)
		(end 281.05989 -233.460036)
		(width 0.14478)
		(layer "In11.Cu")
		(net "M_F_CPU0_SA_DQ<29>")
	)
	(segment
		(start 315.999622 -243.06657)
		(end 323.895974 -243.06657)
		(width 0.14478)
		(layer "In11.Cu")
		(net "M_F_CPU0_SA_DQ<29>")
	)
	(segment
		(start 284.192472 -232.77322)
		(end 284.35554 -232.610152)
		(width 0.14478)
		(layer "In11.Cu")
		(net "M_F_CPU0_SA_DQ<29>")
	)
	(segment
		(start 305.480974 -233.460036)
		(end 305.742848 -233.460036)
		(width 0.14478)
		(layer "In11.Cu")
		(net "M_F_CPU0_SA_DQ<29>")
	)
	(segment
		(start 323.895974 -243.06657)
		(end 324.127114 -243.06657)
		(width 0.0889)
		(layer "In11.Cu")
		(net "M_F_CPU0_SA_DQ<29>")
	)
	(segment
		(start 333.621126 -243.964968)
		(end 333.717138 -243.939568)
		(width 0.0889)
		(layer "In11.Cu")
		(net "M_F_CPU0_SA_DQ<29>")
	)
	(segment
		(start 270.87703 -233.85399)
		(end 271.107408 -233.85399)
		(width 0.14478)
		(layer "In11.Cu")
		(net "M_F_CPU0_SA_DQ<29>")
	)
	(segment
		(start 303.826672 -233.857292)
		(end 304.088546 -233.857292)
		(width 0.14478)
		(layer "In11.Cu")
		(net "M_F_CPU0_SA_DQ<29>")
	)
	(segment
		(start 272.220436 -233.85399)
		(end 272.383504 -233.690922)
		(width 0.14478)
		(layer "In11.Cu")
		(net "M_F_CPU0_SA_DQ<29>")
	)
	(segment
		(start 305.191414 -233.857292)
		(end 305.336194 -233.712512)
		(width 0.14478)
		(layer "In11.Cu")
		(net "M_F_CPU0_SA_DQ<29>")
	)
	(segment
		(start 281.222958 -233.690922)
		(end 281.386026 -233.85399)
		(width 0.14478)
		(layer "In11.Cu")
		(net "M_F_CPU0_SA_DQ<29>")
	)
	(segment
		(start 285.892748 -232.610152)
		(end 286.742632 -233.460036)
		(width 0.14478)
		(layer "In11.Cu")
		(net "M_F_CPU0_SA_DQ<29>")
	)
	(segment
		(start 296.945304 -233.623104)
		(end 297.108372 -233.460036)
		(width 0.14478)
		(layer "In11.Cu")
		(net "M_F_CPU0_SA_DQ<29>")
	)
	(segment
		(start 328.984102 -243.996718)
		(end 328.992484 -244.001544)
		(width 0.0889)
		(layer "In11.Cu")
		(net "M_F_CPU0_SA_DQ<29>")
	)
	(segment
		(start 333.717138 -243.939568)
		(end 333.871062 -243.674138)
		(width 0.0889)
		(layer "In11.Cu")
		(net "M_F_CPU0_SA_DQ<29>")
	)
	(segment
		(start 305.336194 -233.712512)
		(end 305.336194 -233.604816)
		(width 0.14478)
		(layer "In11.Cu")
		(net "M_F_CPU0_SA_DQ<29>")
	)
	(segment
		(start 274.754848 -233.460036)
		(end 275.604732 -232.610152)
		(width 0.14478)
		(layer "In11.Cu")
		(net "M_F_CPU0_SA_DQ<29>")
	)
	(segment
		(start 328.033634 -243.990622)
		(end 328.044048 -243.996718)
		(width 0.0889)
		(layer "In11.Cu")
		(net "M_F_CPU0_SA_DQ<29>")
	)
	(segment
		(start 281.222958 -233.623104)
		(end 281.222958 -233.690922)
		(width 0.14478)
		(layer "In11.Cu")
		(net "M_F_CPU0_SA_DQ<29>")
	)
	(segment
		(start 301.051976 -232.610152)
		(end 301.90186 -233.460036)
		(width 0.14478)
		(layer "In11.Cu")
		(net "M_F_CPU0_SA_DQ<29>")
	)
	(segment
		(start 284.029404 -233.00055)
		(end 284.192472 -232.837482)
		(width 0.14478)
		(layer "In11.Cu")
		(net "M_F_CPU0_SA_DQ<29>")
	)
	(segment
		(start 303.681892 -233.604816)
		(end 303.681892 -233.712512)
		(width 0.14478)
		(layer "In11.Cu")
		(net "M_F_CPU0_SA_DQ<29>")
	)
	(segment
		(start 298.676822 -232.77322)
		(end 298.676822 -232.829862)
		(width 0.14478)
		(layer "In11.Cu")
		(net "M_F_CPU0_SA_DQ<29>")
	)
	(segment
		(start 276.754844 -232.610152)
		(end 278.410924 -232.610152)
		(width 0.14478)
		(layer "In11.Cu")
		(net "M_F_CPU0_SA_DQ<29>")
	)
	(segment
		(start 275.604732 -232.610152)
		(end 275.872194 -232.610152)
		(width 0.14478)
		(layer "In11.Cu")
		(net "M_F_CPU0_SA_DQ<29>")
	)
	(segment
		(start 298.676822 -232.829862)
		(end 298.83989 -232.99293)
		(width 0.14478)
		(layer "In11.Cu")
		(net "M_F_CPU0_SA_DQ<29>")
	)
	(segment
		(start 276.591776 -232.77322)
		(end 276.754844 -232.610152)
		(width 0.14478)
		(layer "In11.Cu")
		(net "M_F_CPU0_SA_DQ<29>")
	)
	(segment
		(start 291.715952 -232.77322)
		(end 291.87902 -232.610152)
		(width 0.14478)
		(layer "In11.Cu")
		(net "M_F_CPU0_SA_DQ<29>")
	)
	(segment
		(start 304.78476 -233.604816)
		(end 304.78476 -233.712512)
		(width 0.14478)
		(layer "In11.Cu")
		(net "M_F_CPU0_SA_DQ<29>")
	)
	(segment
		(start 281.05989 -233.460036)
		(end 281.222958 -233.623104)
		(width 0.14478)
		(layer "In11.Cu")
		(net "M_F_CPU0_SA_DQ<29>")
	)
	(segment
		(start 276.428708 -232.99293)
		(end 276.591776 -232.829862)
		(width 0.14478)
		(layer "In11.Cu")
		(net "M_F_CPU0_SA_DQ<29>")
	)
	(segment
		(start 281.386026 -233.85399)
		(end 281.616404 -233.85399)
		(width 0.14478)
		(layer "In11.Cu")
		(net "M_F_CPU0_SA_DQ<29>")
	)
	(segment
		(start 273.482816 -233.460036)
		(end 273.645884 -233.623104)
		(width 0.14478)
		(layer "In11.Cu")
		(net "M_F_CPU0_SA_DQ<29>")
	)
	(segment
		(start 283.635958 -232.77322)
		(end 283.635958 -232.837482)
		(width 0.14478)
		(layer "In11.Cu")
		(net "M_F_CPU0_SA_DQ<29>")
	)
	(segment
		(start 284.192472 -232.837482)
		(end 284.192472 -232.77322)
		(width 0.14478)
		(layer "In11.Cu")
		(net "M_F_CPU0_SA_DQ<29>")
	)
	(segment
		(start 288.672524 -233.460036)
		(end 288.835592 -233.623104)
		(width 0.14478)
		(layer "In11.Cu")
		(net "M_F_CPU0_SA_DQ<29>")
	)
	(segment
		(start 308.903878 -234.769152)
		(end 308.903878 -235.970826)
		(width 0.14478)
		(layer "In11.Cu")
		(net "M_F_CPU0_SA_DQ<29>")
	)
	(segment
		(start 273.645884 -233.623104)
		(end 273.645884 -233.683302)
		(width 0.14478)
		(layer "In11.Cu")
		(net "M_F_CPU0_SA_DQ<29>")
	)
	(segment
		(start 304.233326 -233.604816)
		(end 304.378106 -233.460036)
		(width 0.14478)
		(layer "In11.Cu")
		(net "M_F_CPU0_SA_DQ<29>")
	)
	(segment
		(start 326.350884 -244.04701)
		(end 326.351138 -244.046756)
		(width 0.0889)
		(layer "In11.Cu")
		(net "M_F_CPU0_SA_DQ<29>")
	)
	(segment
		(start 288.835592 -233.690922)
		(end 288.99866 -233.85399)
		(width 0.14478)
		(layer "In11.Cu")
		(net "M_F_CPU0_SA_DQ<29>")
	)
	(segment
		(start 272.546572 -233.460036)
		(end 273.482816 -233.460036)
		(width 0.14478)
		(layer "In11.Cu")
		(net "M_F_CPU0_SA_DQ<29>")
	)
	(segment
		(start 291.87902 -232.610152)
		(end 293.507922 -232.610152)
		(width 0.14478)
		(layer "In11.Cu")
		(net "M_F_CPU0_SA_DQ<29>")
	)
	(segment
		(start 283.47289 -232.610152)
		(end 283.635958 -232.77322)
		(width 0.14478)
		(layer "In11.Cu")
		(net "M_F_CPU0_SA_DQ<29>")
	)
	(segment
		(start 297.389042 -233.460036)
		(end 298.238926 -232.610152)
		(width 0.14478)
		(layer "In11.Cu")
		(net "M_F_CPU0_SA_DQ<29>")
	)
	(segment
		(start 272.383504 -233.623104)
		(end 272.546572 -233.460036)
		(width 0.14478)
		(layer "In11.Cu")
		(net "M_F_CPU0_SA_DQ<29>")
	)
	(segment
		(start 281.779472 -233.623104)
		(end 281.94254 -233.460036)
		(width 0.14478)
		(layer "In11.Cu")
		(net "M_F_CPU0_SA_DQ<29>")
	)
	(segment
		(start 304.378106 -233.460036)
		(end 304.63998 -233.460036)
		(width 0.14478)
		(layer "In11.Cu")
		(net "M_F_CPU0_SA_DQ<29>")
	)
	(segment
		(start 288.99866 -233.85399)
		(end 289.229038 -233.85399)
		(width 0.14478)
		(layer "In11.Cu")
		(net "M_F_CPU0_SA_DQ<29>")
	)
	(segment
		(start 283.799026 -233.00055)
		(end 284.029404 -233.00055)
		(width 0.14478)
		(layer "In11.Cu")
		(net "M_F_CPU0_SA_DQ<29>")
	)
	(segment
		(start 283.17317 -232.610152)
		(end 283.47289 -232.610152)
		(width 0.14478)
		(layer "In11.Cu")
		(net "M_F_CPU0_SA_DQ<29>")
	)
	(segment
		(start 281.779472 -233.690922)
		(end 281.779472 -233.623104)
		(width 0.14478)
		(layer "In11.Cu")
		(net "M_F_CPU0_SA_DQ<29>")
	)
	(segment
		(start 273.645884 -233.683302)
		(end 273.808952 -233.84637)
		(width 0.14478)
		(layer "In11.Cu")
		(net "M_F_CPU0_SA_DQ<29>")
	)
	(segment
		(start 296.38879 -233.623104)
		(end 296.38879 -233.683302)
		(width 0.14478)
		(layer "In11.Cu")
		(net "M_F_CPU0_SA_DQ<29>")
	)
	(segment
		(start 291.715952 -232.837482)
		(end 291.715952 -232.77322)
		(width 0.14478)
		(layer "In11.Cu")
		(net "M_F_CPU0_SA_DQ<29>")
	)
	(segment
		(start 297.108372 -233.460036)
		(end 297.389042 -233.460036)
		(width 0.14478)
		(layer "In11.Cu")
		(net "M_F_CPU0_SA_DQ<29>")
	)
	(segment
		(start 271.270476 -233.22915)
		(end 271.433544 -233.066082)
		(width 0.14478)
		(layer "In11.Cu")
		(net "M_F_CPU0_SA_DQ<29>")
	)
	(segment
		(start 283.635958 -232.837482)
		(end 283.799026 -233.00055)
		(width 0.14478)
		(layer "In11.Cu")
		(net "M_F_CPU0_SA_DQ<29>")
	)
	(segment
		(start 304.92954 -233.857292)
		(end 305.191414 -233.857292)
		(width 0.14478)
		(layer "In11.Cu")
		(net "M_F_CPU0_SA_DQ<29>")
	)
	(segment
		(start 324.127114 -243.06657)
		(end 324.556374 -243.49583)
		(width 0.0889)
		(layer "In11.Cu")
		(net "M_F_CPU0_SA_DQ<29>")
	)
	(segment
		(start 328.409808 -244.001544)
		(end 328.41819 -243.996718)
		(width 0.0889)
		(layer "In11.Cu")
		(net "M_F_CPU0_SA_DQ<29>")
	)
	(segment
		(start 332.16977 -244.001544)
		(end 332.178152 -243.996718)
		(width 0.0889)
		(layer "In11.Cu")
		(net "M_F_CPU0_SA_DQ<29>")
	)
	(segment
		(start 290.732972 -232.610152)
		(end 290.99637 -232.610152)
		(width 0.14478)
		(layer "In11.Cu")
		(net "M_F_CPU0_SA_DQ<29>")
	)
	(segment
		(start 305.887628 -233.604816)
		(end 305.887628 -233.712512)
		(width 0.14478)
		(layer "In11.Cu")
		(net "M_F_CPU0_SA_DQ<29>")
	)
	(segment
		(start 293.507922 -232.610152)
		(end 294.357806 -233.460036)
		(width 0.14478)
		(layer "In11.Cu")
		(net "M_F_CPU0_SA_DQ<29>")
	)
	(segment
		(start 325.300594 -243.49583)
		(end 325.851774 -244.04701)
		(width 0.0889)
		(layer "In11.Cu")
		(net "M_F_CPU0_SA_DQ<29>")
	)
	(segment
		(start 298.238926 -232.610152)
		(end 298.513754 -232.610152)
		(width 0.14478)
		(layer "In11.Cu")
		(net "M_F_CPU0_SA_DQ<29>")
	)
	(segment
		(start 298.83989 -232.99293)
		(end 299.070268 -232.99293)
		(width 0.14478)
		(layer "In11.Cu")
		(net "M_F_CPU0_SA_DQ<29>")
	)
	(segment
		(start 305.742848 -233.460036)
		(end 305.887628 -233.604816)
		(width 0.14478)
		(layer "In11.Cu")
		(net "M_F_CPU0_SA_DQ<29>")
	)
	(segment
		(start 276.035262 -232.829862)
		(end 276.19833 -232.99293)
		(width 0.14478)
		(layer "In11.Cu")
		(net "M_F_CPU0_SA_DQ<29>")
	)
	(segment
		(start 324.556374 -243.49583)
		(end 325.300594 -243.49583)
		(width 0.0889)
		(layer "In11.Cu")
		(net "M_F_CPU0_SA_DQ<29>")
	)
	(segment
		(start 304.63998 -233.460036)
		(end 304.78476 -233.604816)
		(width 0.14478)
		(layer "In11.Cu")
		(net "M_F_CPU0_SA_DQ<29>")
	)
	(segment
		(start 274.03933 -233.84637)
		(end 274.202398 -233.683302)
		(width 0.14478)
		(layer "In11.Cu")
		(net "M_F_CPU0_SA_DQ<29>")
	)
	(segment
		(start 296.225722 -233.460036)
		(end 296.38879 -233.623104)
		(width 0.14478)
		(layer "In11.Cu")
		(net "M_F_CPU0_SA_DQ<29>")
	)
	(segment
		(start 269.648178 -233.035094)
		(end 270.07312 -233.460036)
		(width 0.14478)
		(layer "In11.Cu")
		(net "M_F_CPU0_SA_DQ<29>")
	)
	(segment
		(start 271.990058 -233.85399)
		(end 272.220436 -233.85399)
		(width 0.14478)
		(layer "In11.Cu")
		(net "M_F_CPU0_SA_DQ<29>")
	)
	(segment
		(start 303.681892 -233.712512)
		(end 303.826672 -233.857292)
		(width 0.14478)
		(layer "In11.Cu")
		(net "M_F_CPU0_SA_DQ<29>")
	)
	(segment
		(start 289.392106 -233.690922)
		(end 289.392106 -233.623104)
		(width 0.14478)
		(layer "In11.Cu")
		(net "M_F_CPU0_SA_DQ<29>")
	)
	(segment
		(start 290.99637 -232.610152)
		(end 291.159438 -232.77322)
		(width 0.14478)
		(layer "In11.Cu")
		(net "M_F_CPU0_SA_DQ<29>")
	)
	(segment
		(start 270.713962 -233.623104)
		(end 270.713962 -233.690922)
		(width 0.14478)
		(layer "In11.Cu")
		(net "M_F_CPU0_SA_DQ<29>")
	)
	(segment
		(start 299.233336 -232.829862)
		(end 299.233336 -232.77322)
		(width 0.14478)
		(layer "In11.Cu")
		(net "M_F_CPU0_SA_DQ<29>")
	)
	(segment
		(start 296.38879 -233.683302)
		(end 296.551858 -233.84637)
		(width 0.14478)
		(layer "In11.Cu")
		(net "M_F_CPU0_SA_DQ<29>")
	)
	(segment
		(start 274.365466 -233.460036)
		(end 274.754848 -233.460036)
		(width 0.14478)
		(layer "In11.Cu")
		(net "M_F_CPU0_SA_DQ<29>")
	)
	(segment
		(start 331.229716 -244.001544)
		(end 331.238098 -243.996718)
		(width 0.0889)
		(layer "In11.Cu")
		(net "M_F_CPU0_SA_DQ<29>")
	)
	(segment
		(start 332.744064 -243.996718)
		(end 332.752446 -244.001544)
		(width 0.0889)
		(layer "In11.Cu")
		(net "M_F_CPU0_SA_DQ<29>")
	)
	(segment
		(start 326.537828 -243.996718)
		(end 326.548242 -243.990622)
		(width 0.0889)
		(layer "In11.Cu")
		(net "M_F_CPU0_SA_DQ<29>")
	)
	(segment
		(start 291.552884 -233.00055)
		(end 291.715952 -232.837482)
		(width 0.14478)
		(layer "In11.Cu")
		(net "M_F_CPU0_SA_DQ<29>")
	)
	(segment
		(start 271.82699 -233.690922)
		(end 271.990058 -233.85399)
		(width 0.14478)
		(layer "In11.Cu")
		(net "M_F_CPU0_SA_DQ<29>")
	)
	(segment
		(start 291.322506 -233.00055)
		(end 291.552884 -233.00055)
		(width 0.14478)
		(layer "In11.Cu")
		(net "M_F_CPU0_SA_DQ<29>")
	)
	(segment
		(start 270.550894 -233.460036)
		(end 270.713962 -233.623104)
		(width 0.14478)
		(layer "In11.Cu")
		(net "M_F_CPU0_SA_DQ<29>")
	)
	(segment
		(start 271.107408 -233.85399)
		(end 271.270476 -233.690922)
		(width 0.14478)
		(layer "In11.Cu")
		(net "M_F_CPU0_SA_DQ<29>")
	)
	(segment
		(start 325.851774 -244.04701)
		(end 326.350884 -244.04701)
		(width 0.0889)
		(layer "In11.Cu")
		(net "M_F_CPU0_SA_DQ<29>")
	)
	(segment
		(start 276.591776 -232.829862)
		(end 276.591776 -232.77322)
		(width 0.14478)
		(layer "In11.Cu")
		(net "M_F_CPU0_SA_DQ<29>")
	)
	(segment
		(start 281.94254 -233.460036)
		(end 282.323286 -233.460036)
		(width 0.14478)
		(layer "In11.Cu")
		(net "M_F_CPU0_SA_DQ<29>")
	)
	(segment
		(start 299.396404 -232.610152)
		(end 301.051976 -232.610152)
		(width 0.14478)
		(layer "In11.Cu")
		(net "M_F_CPU0_SA_DQ<29>")
	)
	(segment
		(start 288.835592 -233.623104)
		(end 288.835592 -233.690922)
		(width 0.14478)
		(layer "In11.Cu")
		(net "M_F_CPU0_SA_DQ<29>")
	)
	(segment
		(start 308.903878 -235.970826)
		(end 315.999622 -243.06657)
		(width 0.14478)
		(layer "In11.Cu")
		(net "M_F_CPU0_SA_DQ<29>")
	)
	(segment
		(start 274.202398 -233.623104)
		(end 274.365466 -233.460036)
		(width 0.14478)
		(layer "In11.Cu")
		(net "M_F_CPU0_SA_DQ<29>")
	)
	(segment
		(start 274.202398 -233.683302)
		(end 274.202398 -233.623104)
		(width 0.14478)
		(layer "In11.Cu")
		(net "M_F_CPU0_SA_DQ<29>")
	)
	(segment
		(start 304.78476 -233.712512)
		(end 304.92954 -233.857292)
		(width 0.14478)
		(layer "In11.Cu")
		(net "M_F_CPU0_SA_DQ<29>")
	)
	(segment
		(start 284.35554 -232.610152)
		(end 285.892748 -232.610152)
		(width 0.14478)
		(layer "In11.Cu")
		(net "M_F_CPU0_SA_DQ<29>")
	)
	(segment
		(start 299.070268 -232.99293)
		(end 299.233336 -232.829862)
		(width 0.14478)
		(layer "In11.Cu")
		(net "M_F_CPU0_SA_DQ<29>")
	)
	(segment
		(start 271.82699 -233.22915)
		(end 271.82699 -233.690922)
		(width 0.14478)
		(layer "In11.Cu")
		(net "M_F_CPU0_SA_DQ<29>")
	)
	(segment
		(start 291.159438 -232.77322)
		(end 291.159438 -232.837482)
		(width 0.14478)
		(layer "In11.Cu")
		(net "M_F_CPU0_SA_DQ<29>")
	)
	(arc
		(start 333.118206 -243.996718)
		(mid 333.365919 -243.921498)
		(end 333.621126 -243.964968)
		(width 0.0889)
		(layer "In11.Cu")
		(net "M_F_CPU0_SA_DQ<29>")
	)
	(arc
		(start 328.044048 -243.996718)
		(mid 328.226299 -244.047068)
		(end 328.409808 -244.001544)
		(width 0.0889)
		(layer "In11.Cu")
		(net "M_F_CPU0_SA_DQ<29>")
	)
	(arc
		(start 326.351138 -244.046756)
		(mid 326.447791 -244.034071)
		(end 326.537828 -243.996718)
		(width 0.0889)
		(layer "In11.Cu")
		(net "M_F_CPU0_SA_DQ<29>")
	)
	(arc
		(start 326.548242 -243.990622)
		(mid 326.826674 -243.920524)
		(end 327.103486 -243.996718)
		(width 0.0889)
		(layer "In11.Cu")
		(net "M_F_CPU0_SA_DQ<29>")
	)
	(arc
		(start 328.992484 -244.001544)
		(mid 329.175992 -244.047038)
		(end 329.358244 -243.996718)
		(width 0.0889)
		(layer "In11.Cu")
		(net "M_F_CPU0_SA_DQ<29>")
	)
	(arc
		(start 328.41819 -243.996718)
		(mid 328.701146 -243.920541)
		(end 328.984102 -243.996718)
		(width 0.0889)
		(layer "In11.Cu")
		(net "M_F_CPU0_SA_DQ<29>")
	)
	(arc
		(start 329.924156 -243.996718)
		(mid 330.1111 -244.046973)
		(end 330.298044 -243.996718)
		(width 0.0889)
		(layer "In11.Cu")
		(net "M_F_CPU0_SA_DQ<29>")
	)
	(arc
		(start 331.238098 -243.996718)
		(mid 331.521054 -243.920541)
		(end 331.80401 -243.996718)
		(width 0.0889)
		(layer "In11.Cu")
		(net "M_F_CPU0_SA_DQ<29>")
	)
	(arc
		(start 329.358244 -243.996718)
		(mid 329.6412 -243.920541)
		(end 329.924156 -243.996718)
		(width 0.0889)
		(layer "In11.Cu")
		(net "M_F_CPU0_SA_DQ<29>")
	)
	(arc
		(start 332.178152 -243.996718)
		(mid 332.461108 -243.920541)
		(end 332.744064 -243.996718)
		(width 0.0889)
		(layer "In11.Cu")
		(net "M_F_CPU0_SA_DQ<29>")
	)
	(arc
		(start 327.477882 -243.996718)
		(mid 327.754949 -243.920447)
		(end 328.033634 -243.990622)
		(width 0.0889)
		(layer "In11.Cu")
		(net "M_F_CPU0_SA_DQ<29>")
	)
	(arc
		(start 330.298044 -243.996718)
		(mid 330.581 -243.920541)
		(end 330.863956 -243.996718)
		(width 0.0889)
		(layer "In11.Cu")
		(net "M_F_CPU0_SA_DQ<29>")
	)
	(arc
		(start 327.103486 -243.996718)
		(mid 327.290684 -244.0471)
		(end 327.477882 -243.996718)
		(width 0.0889)
		(layer "In11.Cu")
		(net "M_F_CPU0_SA_DQ<29>")
	)
	(arc
		(start 332.752446 -244.001544)
		(mid 332.935954 -244.047038)
		(end 333.118206 -243.996718)
		(width 0.0889)
		(layer "In11.Cu")
		(net "M_F_CPU0_SA_DQ<29>")
	)
	(arc
		(start 330.863956 -243.996718)
		(mid 331.046207 -244.047068)
		(end 331.229716 -244.001544)
		(width 0.0889)
		(layer "In11.Cu")
		(net "M_F_CPU0_SA_DQ<29>")
	)
	(arc
		(start 331.80401 -243.996718)
		(mid 331.986261 -244.047068)
		(end 332.16977 -244.001544)
		(width 0.0889)
		(layer "In11.Cu")
		(net "M_F_CPU0_SA_DQ<29>")
	)
	(segment
		(start 332.92796 -243.13007)
		(end 332.461108 -242.864132)
		(width 0.10668)
		(layer "F.Cu")
		(net "M_F_CPU0_SA_DQ<28>")
	)
	(segment
		(start 269.648178 -231.335072)
		(end 270.07312 -231.760014)
		(width 0.14478)
		(layer "In11.Cu")
		(net "M_F_CPU0_SA_DQ<28>")
	)
	(segment
		(start 271.105376 -231.760014)
		(end 271.638776 -231.760014)
		(width 0.14478)
		(layer "In11.Cu")
		(net "M_F_CPU0_SA_DQ<28>")
	)
	(segment
		(start 283.17317 -230.91013)
		(end 283.39542 -230.91013)
		(width 0.14478)
		(layer "In11.Cu")
		(net "M_F_CPU0_SA_DQ<28>")
	)
	(segment
		(start 276.733 -230.919782)
		(end 278.420576 -230.919782)
		(width 0.14478)
		(layer "In11.Cu")
		(net "M_F_CPU0_SA_DQ<28>")
	)
	(segment
		(start 281.443684 -231.923082)
		(end 281.443684 -231.989376)
		(width 0.14478)
		(layer "In11.Cu")
		(net "M_F_CPU0_SA_DQ<28>")
	)
	(segment
		(start 304.449226 -231.760014)
		(end 304.894742 -231.760014)
		(width 0.14478)
		(layer "In11.Cu")
		(net "M_F_CPU0_SA_DQ<28>")
	)
	(segment
		(start 303.336198 -231.48417)
		(end 303.566576 -231.48417)
		(width 0.14478)
		(layer "In11.Cu")
		(net "M_F_CPU0_SA_DQ<28>")
	)
	(segment
		(start 283.951934 -231.304084)
		(end 284.115002 -231.141016)
		(width 0.14478)
		(layer "In11.Cu")
		(net "M_F_CPU0_SA_DQ<28>")
	)
	(segment
		(start 279.27046 -231.769666)
		(end 281.290268 -231.769666)
		(width 0.14478)
		(layer "In11.Cu")
		(net "M_F_CPU0_SA_DQ<28>")
	)
	(segment
		(start 298.238926 -230.91013)
		(end 298.51985 -230.91013)
		(width 0.14478)
		(layer "In11.Cu")
		(net "M_F_CPU0_SA_DQ<28>")
	)
	(segment
		(start 303.729644 -231.981502)
		(end 303.892712 -232.14457)
		(width 0.14478)
		(layer "In11.Cu")
		(net "M_F_CPU0_SA_DQ<28>")
	)
	(segment
		(start 306.54498 -231.916732)
		(end 306.54498 -231.510332)
		(width 0.14478)
		(layer "In11.Cu")
		(net "M_F_CPU0_SA_DQ<28>")
	)
	(segment
		(start 326.997568 -243.19357)
		(end 327.009252 -243.186712)
		(width 0.0889)
		(layer "In11.Cu")
		(net "M_F_CPU0_SA_DQ<28>")
	)
	(segment
		(start 270.548862 -231.029764)
		(end 270.77924 -231.029764)
		(width 0.14478)
		(layer "In11.Cu")
		(net "M_F_CPU0_SA_DQ<28>")
	)
	(segment
		(start 309.809134 -235.589826)
		(end 316.376558 -242.15725)
		(width 0.14478)
		(layer "In11.Cu")
		(net "M_F_CPU0_SA_DQ<28>")
	)
	(segment
		(start 297.389042 -231.760014)
		(end 298.238926 -230.91013)
		(width 0.14478)
		(layer "In11.Cu")
		(net "M_F_CPU0_SA_DQ<28>")
	)
	(segment
		(start 291.692076 -231.133396)
		(end 291.692076 -231.073198)
		(width 0.14478)
		(layer "In11.Cu")
		(net "M_F_CPU0_SA_DQ<28>")
	)
	(segment
		(start 281.606752 -232.152444)
		(end 281.83713 -232.152444)
		(width 0.14478)
		(layer "In11.Cu")
		(net "M_F_CPU0_SA_DQ<28>")
	)
	(segment
		(start 274.745196 -231.769666)
		(end 275.604732 -230.91013)
		(width 0.14478)
		(layer "In11.Cu")
		(net "M_F_CPU0_SA_DQ<28>")
	)
	(segment
		(start 331.33411 -243.186712)
		(end 331.342492 -243.191538)
		(width 0.0889)
		(layer "In11.Cu")
		(net "M_F_CPU0_SA_DQ<28>")
	)
	(segment
		(start 330.394056 -243.186712)
		(end 330.402438 -243.191538)
		(width 0.0889)
		(layer "In11.Cu")
		(net "M_F_CPU0_SA_DQ<28>")
	)
	(segment
		(start 284.268418 -230.919782)
		(end 285.9024 -230.919782)
		(width 0.14478)
		(layer "In11.Cu")
		(net "M_F_CPU0_SA_DQ<28>")
	)
	(segment
		(start 332.307184 -243.129562)
		(end 332.461108 -242.864132)
		(width 0.0889)
		(layer "In11.Cu")
		(net "M_F_CPU0_SA_DQ<28>")
	)
	(segment
		(start 272.511774 -231.769666)
		(end 274.745196 -231.769666)
		(width 0.14478)
		(layer "In11.Cu")
		(net "M_F_CPU0_SA_DQ<28>")
	)
	(segment
		(start 289.37839 -232.152444)
		(end 289.541458 -231.989376)
		(width 0.14478)
		(layer "In11.Cu")
		(net "M_F_CPU0_SA_DQ<28>")
	)
	(segment
		(start 283.558488 -231.141016)
		(end 283.721556 -231.304084)
		(width 0.14478)
		(layer "In11.Cu")
		(net "M_F_CPU0_SA_DQ<28>")
	)
	(segment
		(start 290.732972 -230.91013)
		(end 290.972494 -230.91013)
		(width 0.14478)
		(layer "In11.Cu")
		(net "M_F_CPU0_SA_DQ<28>")
	)
	(segment
		(start 302.453548 -231.760014)
		(end 302.616616 -231.923082)
		(width 0.14478)
		(layer "In11.Cu")
		(net "M_F_CPU0_SA_DQ<28>")
	)
	(segment
		(start 283.39542 -230.91013)
		(end 283.558488 -231.073198)
		(width 0.14478)
		(layer "In11.Cu")
		(net "M_F_CPU0_SA_DQ<28>")
	)
	(segment
		(start 306.68976 -231.365552)
		(end 307.257196 -231.365552)
		(width 0.14478)
		(layer "In11.Cu")
		(net "M_F_CPU0_SA_DQ<28>")
	)
	(segment
		(start 282.163266 -231.760014)
		(end 282.323286 -231.760014)
		(width 0.14478)
		(layer "In11.Cu")
		(net "M_F_CPU0_SA_DQ<28>")
	)
	(segment
		(start 304.286158 -231.981502)
		(end 304.286158 -231.923082)
		(width 0.14478)
		(layer "In11.Cu")
		(net "M_F_CPU0_SA_DQ<28>")
	)
	(segment
		(start 291.529008 -231.296464)
		(end 291.692076 -231.133396)
		(width 0.14478)
		(layer "In11.Cu")
		(net "M_F_CPU0_SA_DQ<28>")
	)
	(segment
		(start 294.367458 -231.769666)
		(end 296.283126 -231.769666)
		(width 0.14478)
		(layer "In11.Cu")
		(net "M_F_CPU0_SA_DQ<28>")
	)
	(segment
		(start 303.566576 -231.48417)
		(end 303.729644 -231.647238)
		(width 0.14478)
		(layer "In11.Cu")
		(net "M_F_CPU0_SA_DQ<28>")
	)
	(segment
		(start 281.83713 -232.152444)
		(end 282.000198 -231.989376)
		(width 0.14478)
		(layer "In11.Cu")
		(net "M_F_CPU0_SA_DQ<28>")
	)
	(segment
		(start 296.436542 -231.923082)
		(end 296.436542 -231.989376)
		(width 0.14478)
		(layer "In11.Cu")
		(net "M_F_CPU0_SA_DQ<28>")
	)
	(segment
		(start 289.541458 -231.989376)
		(end 289.541458 -231.923082)
		(width 0.14478)
		(layer "In11.Cu")
		(net "M_F_CPU0_SA_DQ<28>")
	)
	(segment
		(start 276.579584 -231.141016)
		(end 276.579584 -231.073198)
		(width 0.14478)
		(layer "In11.Cu")
		(net "M_F_CPU0_SA_DQ<28>")
	)
	(segment
		(start 327.574402 -243.186458)
		(end 327.590658 -243.195856)
		(width 0.0889)
		(layer "In11.Cu")
		(net "M_F_CPU0_SA_DQ<28>")
	)
	(segment
		(start 297.156124 -231.760014)
		(end 297.389042 -231.760014)
		(width 0.14478)
		(layer "In11.Cu")
		(net "M_F_CPU0_SA_DQ<28>")
	)
	(segment
		(start 272.19529 -232.152444)
		(end 272.358358 -231.989376)
		(width 0.14478)
		(layer "In11.Cu")
		(net "M_F_CPU0_SA_DQ<28>")
	)
	(segment
		(start 304.894742 -231.760014)
		(end 305.289204 -231.365552)
		(width 0.14478)
		(layer "In11.Cu")
		(net "M_F_CPU0_SA_DQ<28>")
	)
	(segment
		(start 299.076364 -231.296464)
		(end 299.239432 -231.133396)
		(width 0.14478)
		(layer "In11.Cu")
		(net "M_F_CPU0_SA_DQ<28>")
	)
	(segment
		(start 270.942308 -231.596946)
		(end 271.105376 -231.760014)
		(width 0.14478)
		(layer "In11.Cu")
		(net "M_F_CPU0_SA_DQ<28>")
	)
	(segment
		(start 296.993056 -231.989376)
		(end 296.993056 -231.923082)
		(width 0.14478)
		(layer "In11.Cu")
		(net "M_F_CPU0_SA_DQ<28>")
	)
	(segment
		(start 278.420576 -230.919782)
		(end 279.27046 -231.769666)
		(width 0.14478)
		(layer "In11.Cu")
		(net "M_F_CPU0_SA_DQ<28>")
	)
	(segment
		(start 299.239432 -231.073198)
		(end 299.392848 -230.919782)
		(width 0.14478)
		(layer "In11.Cu")
		(net "M_F_CPU0_SA_DQ<28>")
	)
	(segment
		(start 303.010062 -232.14457)
		(end 303.17313 -231.981502)
		(width 0.14478)
		(layer "In11.Cu")
		(net "M_F_CPU0_SA_DQ<28>")
	)
	(segment
		(start 301.90186 -231.760014)
		(end 302.453548 -231.760014)
		(width 0.14478)
		(layer "In11.Cu")
		(net "M_F_CPU0_SA_DQ<28>")
	)
	(segment
		(start 276.416516 -231.304084)
		(end 276.579584 -231.141016)
		(width 0.14478)
		(layer "In11.Cu")
		(net "M_F_CPU0_SA_DQ<28>")
	)
	(segment
		(start 282.323286 -231.760014)
		(end 283.17317 -230.91013)
		(width 0.14478)
		(layer "In11.Cu")
		(net "M_F_CPU0_SA_DQ<28>")
	)
	(segment
		(start 271.801844 -231.989376)
		(end 271.964912 -232.152444)
		(width 0.14478)
		(layer "In11.Cu")
		(net "M_F_CPU0_SA_DQ<28>")
	)
	(segment
		(start 285.9024 -230.919782)
		(end 286.752284 -231.769666)
		(width 0.14478)
		(layer "In11.Cu")
		(net "M_F_CPU0_SA_DQ<28>")
	)
	(segment
		(start 291.692076 -231.073198)
		(end 291.845492 -230.919782)
		(width 0.14478)
		(layer "In11.Cu")
		(net "M_F_CPU0_SA_DQ<28>")
	)
	(segment
		(start 276.02307 -231.073198)
		(end 276.02307 -231.141016)
		(width 0.14478)
		(layer "In11.Cu")
		(net "M_F_CPU0_SA_DQ<28>")
	)
	(segment
		(start 306.138326 -232.061512)
		(end 306.4002 -232.061512)
		(width 0.14478)
		(layer "In11.Cu")
		(net "M_F_CPU0_SA_DQ<28>")
	)
	(segment
		(start 291.135562 -231.133396)
		(end 291.29863 -231.296464)
		(width 0.14478)
		(layer "In11.Cu")
		(net "M_F_CPU0_SA_DQ<28>")
	)
	(segment
		(start 270.07312 -231.760014)
		(end 270.222726 -231.760014)
		(width 0.14478)
		(layer "In11.Cu")
		(net "M_F_CPU0_SA_DQ<28>")
	)
	(segment
		(start 325.661782 -243.110512)
		(end 326.351138 -243.110258)
		(width 0.0889)
		(layer "In11.Cu")
		(net "M_F_CPU0_SA_DQ<28>")
	)
	(segment
		(start 286.752284 -231.769666)
		(end 288.831528 -231.769666)
		(width 0.14478)
		(layer "In11.Cu")
		(net "M_F_CPU0_SA_DQ<28>")
	)
	(segment
		(start 270.385794 -231.596946)
		(end 270.385794 -231.192832)
		(width 0.14478)
		(layer "In11.Cu")
		(net "M_F_CPU0_SA_DQ<28>")
	)
	(segment
		(start 324.48754 -242.504976)
		(end 325.056246 -242.504976)
		(width 0.0889)
		(layer "In11.Cu")
		(net "M_F_CPU0_SA_DQ<28>")
	)
	(segment
		(start 305.993546 -231.510332)
		(end 305.993546 -231.916732)
		(width 0.14478)
		(layer "In11.Cu")
		(net "M_F_CPU0_SA_DQ<28>")
	)
	(segment
		(start 284.115002 -231.073198)
		(end 284.268418 -230.919782)
		(width 0.14478)
		(layer "In11.Cu")
		(net "M_F_CPU0_SA_DQ<28>")
	)
	(segment
		(start 275.860002 -230.91013)
		(end 276.02307 -231.073198)
		(width 0.14478)
		(layer "In11.Cu")
		(net "M_F_CPU0_SA_DQ<28>")
	)
	(segment
		(start 298.682918 -231.073198)
		(end 298.682918 -231.133396)
		(width 0.14478)
		(layer "In11.Cu")
		(net "M_F_CPU0_SA_DQ<28>")
	)
	(segment
		(start 296.993056 -231.923082)
		(end 297.156124 -231.760014)
		(width 0.14478)
		(layer "In11.Cu")
		(net "M_F_CPU0_SA_DQ<28>")
	)
	(segment
		(start 276.186138 -231.304084)
		(end 276.416516 -231.304084)
		(width 0.14478)
		(layer "In11.Cu")
		(net "M_F_CPU0_SA_DQ<28>")
	)
	(segment
		(start 272.358358 -231.989376)
		(end 272.358358 -231.923082)
		(width 0.14478)
		(layer "In11.Cu")
		(net "M_F_CPU0_SA_DQ<28>")
	)
	(segment
		(start 296.436542 -231.989376)
		(end 296.59961 -232.152444)
		(width 0.14478)
		(layer "In11.Cu")
		(net "M_F_CPU0_SA_DQ<28>")
	)
	(segment
		(start 296.59961 -232.152444)
		(end 296.829988 -232.152444)
		(width 0.14478)
		(layer "In11.Cu")
		(net "M_F_CPU0_SA_DQ<28>")
	)
	(segment
		(start 271.801844 -231.923082)
		(end 271.801844 -231.989376)
		(width 0.14478)
		(layer "In11.Cu")
		(net "M_F_CPU0_SA_DQ<28>")
	)
	(segment
		(start 327.562464 -243.1796)
		(end 327.574402 -243.186458)
		(width 0.0889)
		(layer "In11.Cu")
		(net "M_F_CPU0_SA_DQ<28>")
	)
	(segment
		(start 270.77924 -231.029764)
		(end 270.942308 -231.192832)
		(width 0.14478)
		(layer "In11.Cu")
		(net "M_F_CPU0_SA_DQ<28>")
	)
	(segment
		(start 276.02307 -231.141016)
		(end 276.186138 -231.304084)
		(width 0.14478)
		(layer "In11.Cu")
		(net "M_F_CPU0_SA_DQ<28>")
	)
	(segment
		(start 298.682918 -231.133396)
		(end 298.845986 -231.296464)
		(width 0.14478)
		(layer "In11.Cu")
		(net "M_F_CPU0_SA_DQ<28>")
	)
	(segment
		(start 283.558488 -231.073198)
		(end 283.558488 -231.141016)
		(width 0.14478)
		(layer "In11.Cu")
		(net "M_F_CPU0_SA_DQ<28>")
	)
	(segment
		(start 281.443684 -231.989376)
		(end 281.606752 -232.152444)
		(width 0.14478)
		(layer "In11.Cu")
		(net "M_F_CPU0_SA_DQ<28>")
	)
	(segment
		(start 284.115002 -231.141016)
		(end 284.115002 -231.073198)
		(width 0.14478)
		(layer "In11.Cu")
		(net "M_F_CPU0_SA_DQ<28>")
	)
	(segment
		(start 291.135562 -231.073198)
		(end 291.135562 -231.133396)
		(width 0.14478)
		(layer "In11.Cu")
		(net "M_F_CPU0_SA_DQ<28>")
	)
	(segment
		(start 332.211172 -243.154962)
		(end 332.307184 -243.129562)
		(width 0.0889)
		(layer "In11.Cu")
		(net "M_F_CPU0_SA_DQ<28>")
	)
	(segment
		(start 305.848766 -231.365552)
		(end 305.993546 -231.510332)
		(width 0.14478)
		(layer "In11.Cu")
		(net "M_F_CPU0_SA_DQ<28>")
	)
	(segment
		(start 289.704526 -231.760014)
		(end 289.883088 -231.760014)
		(width 0.14478)
		(layer "In11.Cu")
		(net "M_F_CPU0_SA_DQ<28>")
	)
	(segment
		(start 271.638776 -231.760014)
		(end 271.801844 -231.923082)
		(width 0.14478)
		(layer "In11.Cu")
		(net "M_F_CPU0_SA_DQ<28>")
	)
	(segment
		(start 270.385794 -231.192832)
		(end 270.548862 -231.029764)
		(width 0.14478)
		(layer "In11.Cu")
		(net "M_F_CPU0_SA_DQ<28>")
	)
	(segment
		(start 282.000198 -231.923082)
		(end 282.163266 -231.760014)
		(width 0.14478)
		(layer "In11.Cu")
		(net "M_F_CPU0_SA_DQ<28>")
	)
	(segment
		(start 303.729644 -231.647238)
		(end 303.729644 -231.981502)
		(width 0.14478)
		(layer "In11.Cu")
		(net "M_F_CPU0_SA_DQ<28>")
	)
	(segment
		(start 306.54498 -231.510332)
		(end 306.68976 -231.365552)
		(width 0.14478)
		(layer "In11.Cu")
		(net "M_F_CPU0_SA_DQ<28>")
	)
	(segment
		(start 303.892712 -232.14457)
		(end 304.12309 -232.14457)
		(width 0.14478)
		(layer "In11.Cu")
		(net "M_F_CPU0_SA_DQ<28>")
	)
	(segment
		(start 302.616616 -231.981502)
		(end 302.779684 -232.14457)
		(width 0.14478)
		(layer "In11.Cu")
		(net "M_F_CPU0_SA_DQ<28>")
	)
	(segment
		(start 288.831528 -231.769666)
		(end 288.984944 -231.923082)
		(width 0.14478)
		(layer "In11.Cu")
		(net "M_F_CPU0_SA_DQ<28>")
	)
	(segment
		(start 271.964912 -232.152444)
		(end 272.19529 -232.152444)
		(width 0.14478)
		(layer "In11.Cu")
		(net "M_F_CPU0_SA_DQ<28>")
	)
	(segment
		(start 304.286158 -231.923082)
		(end 304.449226 -231.760014)
		(width 0.14478)
		(layer "In11.Cu")
		(net "M_F_CPU0_SA_DQ<28>")
	)
	(segment
		(start 304.12309 -232.14457)
		(end 304.286158 -231.981502)
		(width 0.14478)
		(layer "In11.Cu")
		(net "M_F_CPU0_SA_DQ<28>")
	)
	(segment
		(start 299.239432 -231.133396)
		(end 299.239432 -231.073198)
		(width 0.14478)
		(layer "In11.Cu")
		(net "M_F_CPU0_SA_DQ<28>")
	)
	(segment
		(start 270.942308 -231.192832)
		(end 270.942308 -231.596946)
		(width 0.14478)
		(layer "In11.Cu")
		(net "M_F_CPU0_SA_DQ<28>")
	)
	(segment
		(start 272.358358 -231.923082)
		(end 272.511774 -231.769666)
		(width 0.14478)
		(layer "In11.Cu")
		(net "M_F_CPU0_SA_DQ<28>")
	)
	(segment
		(start 324.139814 -242.15725)
		(end 324.48754 -242.504976)
		(width 0.0889)
		(layer "In11.Cu")
		(net "M_F_CPU0_SA_DQ<28>")
	)
	(segment
		(start 270.222726 -231.760014)
		(end 270.385794 -231.596946)
		(width 0.14478)
		(layer "In11.Cu")
		(net "M_F_CPU0_SA_DQ<28>")
	)
	(segment
		(start 283.721556 -231.304084)
		(end 283.951934 -231.304084)
		(width 0.14478)
		(layer "In11.Cu")
		(net "M_F_CPU0_SA_DQ<28>")
	)
	(segment
		(start 303.17313 -231.981502)
		(end 303.17313 -231.647238)
		(width 0.14478)
		(layer "In11.Cu")
		(net "M_F_CPU0_SA_DQ<28>")
	)
	(segment
		(start 325.056246 -242.504976)
		(end 325.661782 -243.110512)
		(width 0.0889)
		(layer "In11.Cu")
		(net "M_F_CPU0_SA_DQ<28>")
	)
	(segment
		(start 282.000198 -231.989376)
		(end 282.000198 -231.923082)
		(width 0.14478)
		(layer "In11.Cu")
		(net "M_F_CPU0_SA_DQ<28>")
	)
	(segment
		(start 323.906134 -242.15725)
		(end 324.139814 -242.15725)
		(width 0.0889)
		(layer "In11.Cu")
		(net "M_F_CPU0_SA_DQ<28>")
	)
	(segment
		(start 293.517574 -230.919782)
		(end 294.367458 -231.769666)
		(width 0.14478)
		(layer "In11.Cu")
		(net "M_F_CPU0_SA_DQ<28>")
	)
	(segment
		(start 281.290268 -231.769666)
		(end 281.443684 -231.923082)
		(width 0.14478)
		(layer "In11.Cu")
		(net "M_F_CPU0_SA_DQ<28>")
	)
	(segment
		(start 290.972494 -230.91013)
		(end 291.135562 -231.073198)
		(width 0.14478)
		(layer "In11.Cu")
		(net "M_F_CPU0_SA_DQ<28>")
	)
	(segment
		(start 296.829988 -232.152444)
		(end 296.993056 -231.989376)
		(width 0.14478)
		(layer "In11.Cu")
		(net "M_F_CPU0_SA_DQ<28>")
	)
	(segment
		(start 306.4002 -232.061512)
		(end 306.54498 -231.916732)
		(width 0.14478)
		(layer "In11.Cu")
		(net "M_F_CPU0_SA_DQ<28>")
	)
	(segment
		(start 289.148012 -232.152444)
		(end 289.37839 -232.152444)
		(width 0.14478)
		(layer "In11.Cu")
		(net "M_F_CPU0_SA_DQ<28>")
	)
	(segment
		(start 305.993546 -231.916732)
		(end 306.138326 -232.061512)
		(width 0.14478)
		(layer "In11.Cu")
		(net "M_F_CPU0_SA_DQ<28>")
	)
	(segment
		(start 298.51985 -230.91013)
		(end 298.682918 -231.073198)
		(width 0.14478)
		(layer "In11.Cu")
		(net "M_F_CPU0_SA_DQ<28>")
	)
	(segment
		(start 305.289204 -231.365552)
		(end 305.848766 -231.365552)
		(width 0.14478)
		(layer "In11.Cu")
		(net "M_F_CPU0_SA_DQ<28>")
	)
	(segment
		(start 289.883088 -231.760014)
		(end 290.732972 -230.91013)
		(width 0.14478)
		(layer "In11.Cu")
		(net "M_F_CPU0_SA_DQ<28>")
	)
	(segment
		(start 275.604732 -230.91013)
		(end 275.860002 -230.91013)
		(width 0.14478)
		(layer "In11.Cu")
		(net "M_F_CPU0_SA_DQ<28>")
	)
	(segment
		(start 298.845986 -231.296464)
		(end 299.076364 -231.296464)
		(width 0.14478)
		(layer "In11.Cu")
		(net "M_F_CPU0_SA_DQ<28>")
	)
	(segment
		(start 291.845492 -230.919782)
		(end 293.517574 -230.919782)
		(width 0.14478)
		(layer "In11.Cu")
		(net "M_F_CPU0_SA_DQ<28>")
	)
	(segment
		(start 309.809134 -233.91749)
		(end 309.809134 -235.589826)
		(width 0.14478)
		(layer "In11.Cu")
		(net "M_F_CPU0_SA_DQ<28>")
	)
	(segment
		(start 302.616616 -231.923082)
		(end 302.616616 -231.981502)
		(width 0.14478)
		(layer "In11.Cu")
		(net "M_F_CPU0_SA_DQ<28>")
	)
	(segment
		(start 299.392848 -230.919782)
		(end 301.061628 -230.919782)
		(width 0.14478)
		(layer "In11.Cu")
		(net "M_F_CPU0_SA_DQ<28>")
	)
	(segment
		(start 288.984944 -231.923082)
		(end 288.984944 -231.989376)
		(width 0.14478)
		(layer "In11.Cu")
		(net "M_F_CPU0_SA_DQ<28>")
	)
	(segment
		(start 291.29863 -231.296464)
		(end 291.529008 -231.296464)
		(width 0.14478)
		(layer "In11.Cu")
		(net "M_F_CPU0_SA_DQ<28>")
	)
	(segment
		(start 307.257196 -231.365552)
		(end 309.809134 -233.91749)
		(width 0.14478)
		(layer "In11.Cu")
		(net "M_F_CPU0_SA_DQ<28>")
	)
	(segment
		(start 303.17313 -231.647238)
		(end 303.336198 -231.48417)
		(width 0.14478)
		(layer "In11.Cu")
		(net "M_F_CPU0_SA_DQ<28>")
	)
	(segment
		(start 289.541458 -231.923082)
		(end 289.704526 -231.760014)
		(width 0.14478)
		(layer "In11.Cu")
		(net "M_F_CPU0_SA_DQ<28>")
	)
	(segment
		(start 301.061628 -230.919782)
		(end 301.90186 -231.760014)
		(width 0.14478)
		(layer "In11.Cu")
		(net "M_F_CPU0_SA_DQ<28>")
	)
	(segment
		(start 296.283126 -231.769666)
		(end 296.436542 -231.923082)
		(width 0.14478)
		(layer "In11.Cu")
		(net "M_F_CPU0_SA_DQ<28>")
	)
	(segment
		(start 329.819762 -243.191538)
		(end 329.828144 -243.186712)
		(width 0.0889)
		(layer "In11.Cu")
		(net "M_F_CPU0_SA_DQ<28>")
	)
	(segment
		(start 288.984944 -231.989376)
		(end 289.148012 -232.152444)
		(width 0.14478)
		(layer "In11.Cu")
		(net "M_F_CPU0_SA_DQ<28>")
	)
	(segment
		(start 316.376558 -242.15725)
		(end 323.906134 -242.15725)
		(width 0.14478)
		(layer "In11.Cu")
		(net "M_F_CPU0_SA_DQ<28>")
	)
	(segment
		(start 302.779684 -232.14457)
		(end 303.010062 -232.14457)
		(width 0.14478)
		(layer "In11.Cu")
		(net "M_F_CPU0_SA_DQ<28>")
	)
	(segment
		(start 276.579584 -231.073198)
		(end 276.733 -230.919782)
		(width 0.14478)
		(layer "In11.Cu")
		(net "M_F_CPU0_SA_DQ<28>")
	)
	(arc
		(start 326.634856 -243.186712)
		(mid 326.815314 -243.237156)
		(end 326.997568 -243.19357)
		(width 0.0889)
		(layer "In11.Cu")
		(net "M_F_CPU0_SA_DQ<28>")
	)
	(arc
		(start 327.590658 -243.195856)
		(mid 327.77064 -243.236956)
		(end 327.94829 -243.186712)
		(width 0.0889)
		(layer "In11.Cu")
		(net "M_F_CPU0_SA_DQ<28>")
	)
	(arc
		(start 326.351138 -243.110258)
		(mid 326.498069 -243.129669)
		(end 326.634856 -243.186712)
		(width 0.0889)
		(layer "In11.Cu")
		(net "M_F_CPU0_SA_DQ<28>")
	)
	(arc
		(start 327.009252 -243.186712)
		(mid 327.28493 -243.110582)
		(end 327.562464 -243.1796)
		(width 0.0889)
		(layer "In11.Cu")
		(net "M_F_CPU0_SA_DQ<28>")
	)
	(arc
		(start 331.708252 -243.186712)
		(mid 331.955965 -243.111492)
		(end 332.211172 -243.154962)
		(width 0.0889)
		(layer "In11.Cu")
		(net "M_F_CPU0_SA_DQ<28>")
	)
	(arc
		(start 329.454002 -243.186712)
		(mid 329.636253 -243.237062)
		(end 329.819762 -243.191538)
		(width 0.0889)
		(layer "In11.Cu")
		(net "M_F_CPU0_SA_DQ<28>")
	)
	(arc
		(start 331.342492 -243.191538)
		(mid 331.526 -243.237032)
		(end 331.708252 -243.186712)
		(width 0.0889)
		(layer "In11.Cu")
		(net "M_F_CPU0_SA_DQ<28>")
	)
	(arc
		(start 329.828144 -243.186712)
		(mid 330.1111 -243.110535)
		(end 330.394056 -243.186712)
		(width 0.0889)
		(layer "In11.Cu")
		(net "M_F_CPU0_SA_DQ<28>")
	)
	(arc
		(start 330.768198 -243.186712)
		(mid 331.051154 -243.110535)
		(end 331.33411 -243.186712)
		(width 0.0889)
		(layer "In11.Cu")
		(net "M_F_CPU0_SA_DQ<28>")
	)
	(arc
		(start 330.402438 -243.191538)
		(mid 330.585946 -243.237032)
		(end 330.768198 -243.186712)
		(width 0.0889)
		(layer "In11.Cu")
		(net "M_F_CPU0_SA_DQ<28>")
	)
	(arc
		(start 328.88809 -243.186712)
		(mid 329.171046 -243.110535)
		(end 329.454002 -243.186712)
		(width 0.0889)
		(layer "In11.Cu")
		(net "M_F_CPU0_SA_DQ<28>")
	)
	(arc
		(start 327.94829 -243.186712)
		(mid 328.231246 -243.110535)
		(end 328.514202 -243.186712)
		(width 0.0889)
		(layer "In11.Cu")
		(net "M_F_CPU0_SA_DQ<28>")
	)
	(arc
		(start 328.514202 -243.186712)
		(mid 328.701146 -243.236967)
		(end 328.88809 -243.186712)
		(width 0.0889)
		(layer "In11.Cu")
		(net "M_F_CPU0_SA_DQ<28>")
	)
	(segment
		(start 333.868014 -241.510058)
		(end 333.401162 -241.24412)
		(width 0.10668)
		(layer "F.Cu")
		(net "M_F_CPU0_SA_DQ<27>")
	)
	(segment
		(start 305.270154 -227.96627)
		(end 305.726338 -227.510086)
		(width 0.14478)
		(layer "In11.Cu")
		(net "M_F_CPU0_SA_DQ<27>")
	)
	(segment
		(start 305.726338 -227.510086)
		(end 306.783486 -227.510086)
		(width 0.14478)
		(layer "In11.Cu")
		(net "M_F_CPU0_SA_DQ<27>")
	)
	(segment
		(start 319.09131 -239.81791)
		(end 323.931534 -239.81791)
		(width 0.14478)
		(layer "In11.Cu")
		(net "M_F_CPU0_SA_DQ<27>")
	)
	(segment
		(start 266.445746 -228.360224)
		(end 266.608814 -228.197156)
		(width 0.14478)
		(layer "In11.Cu")
		(net "M_F_CPU0_SA_DQ<27>")
	)
	(segment
		(start 297.339766 -228.350318)
		(end 298.18965 -227.500434)
		(width 0.14478)
		(layer "In11.Cu")
		(net "M_F_CPU0_SA_DQ<27>")
	)
	(segment
		(start 333.555086 -240.97869)
		(end 333.401162 -241.24412)
		(width 0.0889)
		(layer "In11.Cu")
		(net "M_F_CPU0_SA_DQ<27>")
	)
	(segment
		(start 326.63257 -240.921794)
		(end 326.652636 -240.910364)
		(width 0.0889)
		(layer "In11.Cu")
		(net "M_F_CPU0_SA_DQ<27>")
	)
	(segment
		(start 274.677632 -228.350318)
		(end 275.527516 -227.500434)
		(width 0.14478)
		(layer "In11.Cu")
		(net "M_F_CPU0_SA_DQ<27>")
	)
	(segment
		(start 290.691824 -227.500434)
		(end 293.54907 -227.500434)
		(width 0.14478)
		(layer "In11.Cu")
		(net "M_F_CPU0_SA_DQ<27>")
	)
	(segment
		(start 279.324054 -228.350318)
		(end 282.308554 -228.350318)
		(width 0.14478)
		(layer "In11.Cu")
		(net "M_F_CPU0_SA_DQ<27>")
	)
	(segment
		(start 283.158438 -227.500434)
		(end 286.043624 -227.500434)
		(width 0.14478)
		(layer "In11.Cu")
		(net "M_F_CPU0_SA_DQ<27>")
	)
	(segment
		(start 267.165328 -228.197156)
		(end 267.31849 -228.350318)
		(width 0.14478)
		(layer "In11.Cu")
		(net "M_F_CPU0_SA_DQ<27>")
	)
	(segment
		(start 333.532734 -240.895378)
		(end 333.555086 -240.97869)
		(width 0.0889)
		(layer "In11.Cu")
		(net "M_F_CPU0_SA_DQ<27>")
	)
	(segment
		(start 267.00226 -227.405692)
		(end 267.165328 -227.56876)
		(width 0.14478)
		(layer "In11.Cu")
		(net "M_F_CPU0_SA_DQ<27>")
	)
	(segment
		(start 327.933812 -240.913158)
		(end 327.94829 -240.92154)
		(width 0.0889)
		(layer "In11.Cu")
		(net "M_F_CPU0_SA_DQ<27>")
	)
	(segment
		(start 266.608814 -228.197156)
		(end 266.608814 -227.56876)
		(width 0.14478)
		(layer "In11.Cu")
		(net "M_F_CPU0_SA_DQ<27>")
	)
	(segment
		(start 294.398954 -228.350318)
		(end 297.339766 -228.350318)
		(width 0.14478)
		(layer "In11.Cu")
		(net "M_F_CPU0_SA_DQ<27>")
	)
	(segment
		(start 324.122034 -239.81791)
		(end 324.591934 -240.28781)
		(width 0.0889)
		(layer "In11.Cu")
		(net "M_F_CPU0_SA_DQ<27>")
	)
	(segment
		(start 267.31849 -228.350318)
		(end 274.677632 -228.350318)
		(width 0.14478)
		(layer "In11.Cu")
		(net "M_F_CPU0_SA_DQ<27>")
	)
	(segment
		(start 330.394056 -240.92154)
		(end 330.402438 -240.916714)
		(width 0.0889)
		(layer "In11.Cu")
		(net "M_F_CPU0_SA_DQ<27>")
	)
	(segment
		(start 278.47417 -227.500434)
		(end 279.324054 -228.350318)
		(width 0.14478)
		(layer "In11.Cu")
		(net "M_F_CPU0_SA_DQ<27>")
	)
	(segment
		(start 293.54907 -227.500434)
		(end 294.398954 -228.350318)
		(width 0.14478)
		(layer "In11.Cu")
		(net "M_F_CPU0_SA_DQ<27>")
	)
	(segment
		(start 286.893508 -228.350318)
		(end 289.84194 -228.350318)
		(width 0.14478)
		(layer "In11.Cu")
		(net "M_F_CPU0_SA_DQ<27>")
	)
	(segment
		(start 301.55134 -227.96627)
		(end 305.270154 -227.96627)
		(width 0.14478)
		(layer "In11.Cu")
		(net "M_F_CPU0_SA_DQ<27>")
	)
	(segment
		(start 298.18965 -227.500434)
		(end 301.085504 -227.500434)
		(width 0.14478)
		(layer "In11.Cu")
		(net "M_F_CPU0_SA_DQ<27>")
	)
	(segment
		(start 323.931534 -239.81791)
		(end 324.122034 -239.81791)
		(width 0.0889)
		(layer "In11.Cu")
		(net "M_F_CPU0_SA_DQ<27>")
	)
	(segment
		(start 306.783486 -227.510086)
		(end 319.09131 -239.81791)
		(width 0.14478)
		(layer "In11.Cu")
		(net "M_F_CPU0_SA_DQ<27>")
	)
	(segment
		(start 275.527516 -227.500434)
		(end 278.47417 -227.500434)
		(width 0.14478)
		(layer "In11.Cu")
		(net "M_F_CPU0_SA_DQ<27>")
	)
	(segment
		(start 286.043624 -227.500434)
		(end 286.893508 -228.350318)
		(width 0.14478)
		(layer "In11.Cu")
		(net "M_F_CPU0_SA_DQ<27>")
	)
	(segment
		(start 266.608814 -227.56876)
		(end 266.771882 -227.405692)
		(width 0.14478)
		(layer "In11.Cu")
		(net "M_F_CPU0_SA_DQ<27>")
	)
	(segment
		(start 265.54811 -227.935028)
		(end 265.973306 -228.360224)
		(width 0.14478)
		(layer "In11.Cu")
		(net "M_F_CPU0_SA_DQ<27>")
	)
	(segment
		(start 265.973306 -228.360224)
		(end 266.445746 -228.360224)
		(width 0.14478)
		(layer "In11.Cu")
		(net "M_F_CPU0_SA_DQ<27>")
	)
	(segment
		(start 267.165328 -227.56876)
		(end 267.165328 -228.197156)
		(width 0.14478)
		(layer "In11.Cu")
		(net "M_F_CPU0_SA_DQ<27>")
	)
	(segment
		(start 331.33411 -240.92154)
		(end 331.342492 -240.916714)
		(width 0.0889)
		(layer "In11.Cu")
		(net "M_F_CPU0_SA_DQ<27>")
	)
	(segment
		(start 326.599042 -240.941098)
		(end 326.63257 -240.921794)
		(width 0.0889)
		(layer "In11.Cu")
		(net "M_F_CPU0_SA_DQ<27>")
	)
	(segment
		(start 329.819762 -240.916714)
		(end 329.828144 -240.92154)
		(width 0.0889)
		(layer "In11.Cu")
		(net "M_F_CPU0_SA_DQ<27>")
	)
	(segment
		(start 282.308554 -228.350318)
		(end 283.158438 -227.500434)
		(width 0.14478)
		(layer "In11.Cu")
		(net "M_F_CPU0_SA_DQ<27>")
	)
	(segment
		(start 325.706994 -241.03965)
		(end 326.17283 -241.03965)
		(width 0.0889)
		(layer "In11.Cu")
		(net "M_F_CPU0_SA_DQ<27>")
	)
	(segment
		(start 266.771882 -227.405692)
		(end 267.00226 -227.405692)
		(width 0.14478)
		(layer "In11.Cu")
		(net "M_F_CPU0_SA_DQ<27>")
	)
	(segment
		(start 324.955154 -240.28781)
		(end 325.706994 -241.03965)
		(width 0.0889)
		(layer "In11.Cu")
		(net "M_F_CPU0_SA_DQ<27>")
	)
	(segment
		(start 289.84194 -228.350318)
		(end 290.691824 -227.500434)
		(width 0.14478)
		(layer "In11.Cu")
		(net "M_F_CPU0_SA_DQ<27>")
	)
	(segment
		(start 301.085504 -227.500434)
		(end 301.55134 -227.96627)
		(width 0.14478)
		(layer "In11.Cu")
		(net "M_F_CPU0_SA_DQ<27>")
	)
	(segment
		(start 327.00595 -240.92154)
		(end 327.029318 -240.935256)
		(width 0.0889)
		(layer "In11.Cu")
		(net "M_F_CPU0_SA_DQ<27>")
	)
	(segment
		(start 324.591934 -240.28781)
		(end 324.955154 -240.28781)
		(width 0.0889)
		(layer "In11.Cu")
		(net "M_F_CPU0_SA_DQ<27>")
	)
	(arc
		(start 333.213964 -240.92154)
		(mid 333.370402 -240.872569)
		(end 333.532734 -240.895378)
		(width 0.0889)
		(layer "In11.Cu")
		(net "M_F_CPU0_SA_DQ<27>")
	)
	(arc
		(start 331.708252 -240.92154)
		(mid 331.991208 -240.997717)
		(end 332.274164 -240.92154)
		(width 0.0889)
		(layer "In11.Cu")
		(net "M_F_CPU0_SA_DQ<27>")
	)
	(arc
		(start 330.402438 -240.916714)
		(mid 330.585946 -240.87122)
		(end 330.768198 -240.92154)
		(width 0.0889)
		(layer "In11.Cu")
		(net "M_F_CPU0_SA_DQ<27>")
	)
	(arc
		(start 331.342492 -240.916714)
		(mid 331.526 -240.87122)
		(end 331.708252 -240.92154)
		(width 0.0889)
		(layer "In11.Cu")
		(net "M_F_CPU0_SA_DQ<27>")
	)
	(arc
		(start 328.88809 -240.92154)
		(mid 329.171046 -240.997717)
		(end 329.454002 -240.92154)
		(width 0.0889)
		(layer "In11.Cu")
		(net "M_F_CPU0_SA_DQ<27>")
	)
	(arc
		(start 327.029318 -240.935256)
		(mid 327.302972 -240.998199)
		(end 327.573132 -240.92154)
		(width 0.0889)
		(layer "In11.Cu")
		(net "M_F_CPU0_SA_DQ<27>")
	)
	(arc
		(start 329.454002 -240.92154)
		(mid 329.636253 -240.87119)
		(end 329.819762 -240.916714)
		(width 0.0889)
		(layer "In11.Cu")
		(net "M_F_CPU0_SA_DQ<27>")
	)
	(arc
		(start 327.573132 -240.92154)
		(mid 327.752395 -240.870876)
		(end 327.933812 -240.913158)
		(width 0.0889)
		(layer "In11.Cu")
		(net "M_F_CPU0_SA_DQ<27>")
	)
	(arc
		(start 332.274164 -240.92154)
		(mid 332.461108 -240.871285)
		(end 332.648052 -240.92154)
		(width 0.0889)
		(layer "In11.Cu")
		(net "M_F_CPU0_SA_DQ<27>")
	)
	(arc
		(start 328.514202 -240.92154)
		(mid 328.701146 -240.871285)
		(end 328.88809 -240.92154)
		(width 0.0889)
		(layer "In11.Cu")
		(net "M_F_CPU0_SA_DQ<27>")
	)
	(arc
		(start 326.17283 -241.03965)
		(mid 326.391557 -241.014688)
		(end 326.599042 -240.941098)
		(width 0.0889)
		(layer "In11.Cu")
		(net "M_F_CPU0_SA_DQ<27>")
	)
	(arc
		(start 326.652636 -240.910364)
		(mid 326.830714 -240.87138)
		(end 327.00595 -240.92154)
		(width 0.0889)
		(layer "In11.Cu")
		(net "M_F_CPU0_SA_DQ<27>")
	)
	(arc
		(start 330.768198 -240.92154)
		(mid 331.051154 -240.997717)
		(end 331.33411 -240.92154)
		(width 0.0889)
		(layer "In11.Cu")
		(net "M_F_CPU0_SA_DQ<27>")
	)
	(arc
		(start 327.94829 -240.92154)
		(mid 328.231246 -240.997717)
		(end 328.514202 -240.92154)
		(width 0.0889)
		(layer "In11.Cu")
		(net "M_F_CPU0_SA_DQ<27>")
	)
	(arc
		(start 329.828144 -240.92154)
		(mid 330.1111 -240.997717)
		(end 330.394056 -240.92154)
		(width 0.0889)
		(layer "In11.Cu")
		(net "M_F_CPU0_SA_DQ<27>")
	)
	(arc
		(start 332.648052 -240.92154)
		(mid 332.931008 -240.997717)
		(end 333.213964 -240.92154)
		(width 0.0889)
		(layer "In11.Cu")
		(net "M_F_CPU0_SA_DQ<27>")
	)
	(segment
		(start 332.45806 -240.700052)
		(end 331.991208 -240.434114)
		(width 0.10668)
		(layer "F.Cu")
		(net "M_F_CPU0_SA_DQ<26>")
	)
	(segment
		(start 266.614656 -226.497134)
		(end 266.614656 -225.904298)
		(width 0.14478)
		(layer "In11.Cu")
		(net "M_F_CPU0_SA_DQ<26>")
	)
	(segment
		(start 293.558722 -225.810064)
		(end 294.40886 -226.660202)
		(width 0.14478)
		(layer "In11.Cu")
		(net "M_F_CPU0_SA_DQ<26>")
	)
	(segment
		(start 294.40886 -226.660202)
		(end 297.32986 -226.660202)
		(width 0.14478)
		(layer "In11.Cu")
		(net "M_F_CPU0_SA_DQ<26>")
	)
	(segment
		(start 268.284198 -226.497134)
		(end 268.447266 -226.660202)
		(width 0.14478)
		(layer "In11.Cu")
		(net "M_F_CPU0_SA_DQ<26>")
	)
	(segment
		(start 267.727684 -225.904298)
		(end 267.890752 -225.74123)
		(width 0.14478)
		(layer "In11.Cu")
		(net "M_F_CPU0_SA_DQ<26>")
	)
	(segment
		(start 301.095156 -225.810064)
		(end 301.945294 -226.660202)
		(width 0.14478)
		(layer "In11.Cu")
		(net "M_F_CPU0_SA_DQ<26>")
	)
	(segment
		(start 289.832034 -226.660202)
		(end 290.682172 -225.810064)
		(width 0.14478)
		(layer "In11.Cu")
		(net "M_F_CPU0_SA_DQ<26>")
	)
	(segment
		(start 290.682172 -225.810064)
		(end 293.558722 -225.810064)
		(width 0.14478)
		(layer "In11.Cu")
		(net "M_F_CPU0_SA_DQ<26>")
	)
	(segment
		(start 267.890752 -225.74123)
		(end 268.12113 -225.74123)
		(width 0.14478)
		(layer "In11.Cu")
		(net "M_F_CPU0_SA_DQ<26>")
	)
	(segment
		(start 324.309994 -238.90351)
		(end 324.447154 -239.04067)
		(width 0.0889)
		(layer "In11.Cu")
		(net "M_F_CPU0_SA_DQ<26>")
	)
	(segment
		(start 266.451588 -226.660202)
		(end 266.614656 -226.497134)
		(width 0.14478)
		(layer "In11.Cu")
		(net "M_F_CPU0_SA_DQ<26>")
	)
	(segment
		(start 305.06289 -226.473512)
		(end 307.018944 -226.473512)
		(width 0.14478)
		(layer "In11.Cu")
		(net "M_F_CPU0_SA_DQ<26>")
	)
	(segment
		(start 323.918834 -238.90351)
		(end 324.309994 -238.90351)
		(width 0.0889)
		(layer "In11.Cu")
		(net "M_F_CPU0_SA_DQ<26>")
	)
	(segment
		(start 283.148786 -225.810064)
		(end 286.053276 -225.810064)
		(width 0.14478)
		(layer "In11.Cu")
		(net "M_F_CPU0_SA_DQ<26>")
	)
	(segment
		(start 282.298648 -226.660202)
		(end 283.148786 -225.810064)
		(width 0.14478)
		(layer "In11.Cu")
		(net "M_F_CPU0_SA_DQ<26>")
	)
	(segment
		(start 307.018944 -226.473512)
		(end 319.448942 -238.90351)
		(width 0.14478)
		(layer "In11.Cu")
		(net "M_F_CPU0_SA_DQ<26>")
	)
	(segment
		(start 286.053276 -225.810064)
		(end 286.903414 -226.660202)
		(width 0.14478)
		(layer "In11.Cu")
		(net "M_F_CPU0_SA_DQ<26>")
	)
	(segment
		(start 327.08723 -240.122202)
		(end 327.105264 -240.111534)
		(width 0.0889)
		(layer "In11.Cu")
		(net "M_F_CPU0_SA_DQ<26>")
	)
	(segment
		(start 332.12278 -240.085372)
		(end 332.145132 -240.168684)
		(width 0.0889)
		(layer "In11.Cu")
		(net "M_F_CPU0_SA_DQ<26>")
	)
	(segment
		(start 328.984102 -240.111534)
		(end 328.992484 -240.106708)
		(width 0.0889)
		(layer "In11.Cu")
		(net "M_F_CPU0_SA_DQ<26>")
	)
	(segment
		(start 267.334238 -226.660202)
		(end 267.564616 -226.660202)
		(width 0.14478)
		(layer "In11.Cu")
		(net "M_F_CPU0_SA_DQ<26>")
	)
	(segment
		(start 286.903414 -226.660202)
		(end 289.832034 -226.660202)
		(width 0.14478)
		(layer "In11.Cu")
		(net "M_F_CPU0_SA_DQ<26>")
	)
	(segment
		(start 267.564616 -226.660202)
		(end 267.727684 -226.497134)
		(width 0.14478)
		(layer "In11.Cu")
		(net "M_F_CPU0_SA_DQ<26>")
	)
	(segment
		(start 319.448942 -238.90351)
		(end 323.918834 -238.90351)
		(width 0.14478)
		(layer "In11.Cu")
		(net "M_F_CPU0_SA_DQ<26>")
	)
	(segment
		(start 275.517864 -225.810064)
		(end 278.483822 -225.810064)
		(width 0.14478)
		(layer "In11.Cu")
		(net "M_F_CPU0_SA_DQ<26>")
	)
	(segment
		(start 267.17117 -226.497134)
		(end 267.334238 -226.660202)
		(width 0.14478)
		(layer "In11.Cu")
		(net "M_F_CPU0_SA_DQ<26>")
	)
	(segment
		(start 324.447154 -239.04067)
		(end 324.904354 -239.04067)
		(width 0.0889)
		(layer "In11.Cu")
		(net "M_F_CPU0_SA_DQ<26>")
	)
	(segment
		(start 278.483822 -225.810064)
		(end 279.33396 -226.660202)
		(width 0.14478)
		(layer "In11.Cu")
		(net "M_F_CPU0_SA_DQ<26>")
	)
	(segment
		(start 331.229716 -240.106708)
		(end 331.238098 -240.111534)
		(width 0.0889)
		(layer "In11.Cu")
		(net "M_F_CPU0_SA_DQ<26>")
	)
	(segment
		(start 266.614656 -225.904298)
		(end 266.777724 -225.74123)
		(width 0.14478)
		(layer "In11.Cu")
		(net "M_F_CPU0_SA_DQ<26>")
	)
	(segment
		(start 267.727684 -226.497134)
		(end 267.727684 -225.904298)
		(width 0.14478)
		(layer "In11.Cu")
		(net "M_F_CPU0_SA_DQ<26>")
	)
	(segment
		(start 274.667726 -226.660202)
		(end 275.517864 -225.810064)
		(width 0.14478)
		(layer "In11.Cu")
		(net "M_F_CPU0_SA_DQ<26>")
	)
	(segment
		(start 324.904354 -239.04067)
		(end 325.925434 -240.06175)
		(width 0.0889)
		(layer "In11.Cu")
		(net "M_F_CPU0_SA_DQ<26>")
	)
	(segment
		(start 297.32986 -226.660202)
		(end 298.179998 -225.810064)
		(width 0.14478)
		(layer "In11.Cu")
		(net "M_F_CPU0_SA_DQ<26>")
	)
	(segment
		(start 325.925434 -240.06175)
		(end 325.931276 -240.06175)
		(width 0.0889)
		(layer "In11.Cu")
		(net "M_F_CPU0_SA_DQ<26>")
	)
	(segment
		(start 328.409808 -240.106708)
		(end 328.41819 -240.111534)
		(width 0.0889)
		(layer "In11.Cu")
		(net "M_F_CPU0_SA_DQ<26>")
	)
	(segment
		(start 267.17117 -225.904298)
		(end 267.17117 -226.497134)
		(width 0.14478)
		(layer "In11.Cu")
		(net "M_F_CPU0_SA_DQ<26>")
	)
	(segment
		(start 327.465182 -240.103914)
		(end 327.478898 -240.111788)
		(width 0.0889)
		(layer "In11.Cu")
		(net "M_F_CPU0_SA_DQ<26>")
	)
	(segment
		(start 301.945294 -226.660202)
		(end 304.8762 -226.660202)
		(width 0.14478)
		(layer "In11.Cu")
		(net "M_F_CPU0_SA_DQ<26>")
	)
	(segment
		(start 268.12113 -225.74123)
		(end 268.284198 -225.904298)
		(width 0.14478)
		(layer "In11.Cu")
		(net "M_F_CPU0_SA_DQ<26>")
	)
	(segment
		(start 332.145132 -240.168684)
		(end 331.991208 -240.434114)
		(width 0.0889)
		(layer "In11.Cu")
		(net "M_F_CPU0_SA_DQ<26>")
	)
	(segment
		(start 265.54811 -226.235006)
		(end 265.973306 -226.660202)
		(width 0.14478)
		(layer "In11.Cu")
		(net "M_F_CPU0_SA_DQ<26>")
	)
	(segment
		(start 304.8762 -226.660202)
		(end 305.06289 -226.473512)
		(width 0.14478)
		(layer "In11.Cu")
		(net "M_F_CPU0_SA_DQ<26>")
	)
	(segment
		(start 327.478898 -240.111788)
		(end 327.490836 -240.118646)
		(width 0.0889)
		(layer "In11.Cu")
		(net "M_F_CPU0_SA_DQ<26>")
	)
	(segment
		(start 267.008102 -225.74123)
		(end 267.17117 -225.904298)
		(width 0.14478)
		(layer "In11.Cu")
		(net "M_F_CPU0_SA_DQ<26>")
	)
	(segment
		(start 266.777724 -225.74123)
		(end 267.008102 -225.74123)
		(width 0.14478)
		(layer "In11.Cu")
		(net "M_F_CPU0_SA_DQ<26>")
	)
	(segment
		(start 265.973306 -226.660202)
		(end 266.451588 -226.660202)
		(width 0.14478)
		(layer "In11.Cu")
		(net "M_F_CPU0_SA_DQ<26>")
	)
	(segment
		(start 279.33396 -226.660202)
		(end 282.298648 -226.660202)
		(width 0.14478)
		(layer "In11.Cu")
		(net "M_F_CPU0_SA_DQ<26>")
	)
	(segment
		(start 268.284198 -225.904298)
		(end 268.284198 -226.497134)
		(width 0.14478)
		(layer "In11.Cu")
		(net "M_F_CPU0_SA_DQ<26>")
	)
	(segment
		(start 298.179998 -225.810064)
		(end 301.095156 -225.810064)
		(width 0.14478)
		(layer "In11.Cu")
		(net "M_F_CPU0_SA_DQ<26>")
	)
	(segment
		(start 325.931276 -240.06175)
		(end 326.351138 -240.061242)
		(width 0.0889)
		(layer "In11.Cu")
		(net "M_F_CPU0_SA_DQ<26>")
	)
	(segment
		(start 268.447266 -226.660202)
		(end 274.667726 -226.660202)
		(width 0.14478)
		(layer "In11.Cu")
		(net "M_F_CPU0_SA_DQ<26>")
	)
	(arc
		(start 328.992484 -240.106708)
		(mid 329.175992 -240.061214)
		(end 329.358244 -240.111534)
		(width 0.0889)
		(layer "In11.Cu")
		(net "M_F_CPU0_SA_DQ<26>")
	)
	(arc
		(start 326.351138 -240.061242)
		(mid 326.448201 -240.07396)
		(end 326.53859 -240.111534)
		(width 0.0889)
		(layer "In11.Cu")
		(net "M_F_CPU0_SA_DQ<26>")
	)
	(arc
		(start 331.238098 -240.111534)
		(mid 331.521054 -240.187711)
		(end 331.80401 -240.111534)
		(width 0.0889)
		(layer "In11.Cu")
		(net "M_F_CPU0_SA_DQ<26>")
	)
	(arc
		(start 330.298044 -240.111534)
		(mid 330.581 -240.187711)
		(end 330.863956 -240.111534)
		(width 0.0889)
		(layer "In11.Cu")
		(net "M_F_CPU0_SA_DQ<26>")
	)
	(arc
		(start 327.105264 -240.111534)
		(mid 327.284251 -240.061364)
		(end 327.465182 -240.103914)
		(width 0.0889)
		(layer "In11.Cu")
		(net "M_F_CPU0_SA_DQ<26>")
	)
	(arc
		(start 329.358244 -240.111534)
		(mid 329.6412 -240.187711)
		(end 329.924156 -240.111534)
		(width 0.0889)
		(layer "In11.Cu")
		(net "M_F_CPU0_SA_DQ<26>")
	)
	(arc
		(start 327.490836 -240.118646)
		(mid 327.76837 -240.187627)
		(end 328.044048 -240.111534)
		(width 0.0889)
		(layer "In11.Cu")
		(net "M_F_CPU0_SA_DQ<26>")
	)
	(arc
		(start 330.863956 -240.111534)
		(mid 331.046207 -240.061184)
		(end 331.229716 -240.106708)
		(width 0.0889)
		(layer "In11.Cu")
		(net "M_F_CPU0_SA_DQ<26>")
	)
	(arc
		(start 331.80401 -240.111534)
		(mid 331.960448 -240.062563)
		(end 332.12278 -240.085372)
		(width 0.0889)
		(layer "In11.Cu")
		(net "M_F_CPU0_SA_DQ<26>")
	)
	(arc
		(start 326.53859 -240.111534)
		(mid 326.811534 -240.188114)
		(end 327.08723 -240.122202)
		(width 0.0889)
		(layer "In11.Cu")
		(net "M_F_CPU0_SA_DQ<26>")
	)
	(arc
		(start 328.41819 -240.111534)
		(mid 328.701146 -240.187711)
		(end 328.984102 -240.111534)
		(width 0.0889)
		(layer "In11.Cu")
		(net "M_F_CPU0_SA_DQ<26>")
	)
	(arc
		(start 329.924156 -240.111534)
		(mid 330.1111 -240.061279)
		(end 330.298044 -240.111534)
		(width 0.0889)
		(layer "In11.Cu")
		(net "M_F_CPU0_SA_DQ<26>")
	)
	(arc
		(start 328.044048 -240.111534)
		(mid 328.226299 -240.061184)
		(end 328.409808 -240.106708)
		(width 0.0889)
		(layer "In11.Cu")
		(net "M_F_CPU0_SA_DQ<26>")
	)
	(segment
		(start 334.337914 -240.700052)
		(end 333.871062 -240.434114)
		(width 0.10668)
		(layer "F.Cu")
		(net "M_F_CPU0_SA_DQ<25>")
	)
	(segment
		(start 296.83964 -227.895912)
		(end 296.99331 -227.742242)
		(width 0.14478)
		(layer "In11.Cu")
		(net "M_F_CPU0_SA_DQ<25>")
	)
	(segment
		(start 291.16528 -226.888802)
		(end 291.32403 -227.047552)
		(width 0.14478)
		(layer "In11.Cu")
		(net "M_F_CPU0_SA_DQ<25>")
	)
	(segment
		(start 290.732972 -226.660202)
		(end 291.002212 -226.660202)
		(width 0.14478)
		(layer "In11.Cu")
		(net "M_F_CPU0_SA_DQ<25>")
	)
	(segment
		(start 296.590466 -227.895912)
		(end 296.83964 -227.895912)
		(width 0.14478)
		(layer "In11.Cu")
		(net "M_F_CPU0_SA_DQ<25>")
	)
	(segment
		(start 271.722088 -227.375212)
		(end 271.866868 -227.519992)
		(width 0.14478)
		(layer "In11.Cu")
		(net "M_F_CPU0_SA_DQ<25>")
	)
	(segment
		(start 301.051976 -226.660202)
		(end 301.90186 -227.510086)
		(width 0.14478)
		(layer "In11.Cu")
		(net "M_F_CPU0_SA_DQ<25>")
	)
	(segment
		(start 279.260808 -227.510086)
		(end 281.089608 -227.510086)
		(width 0.14478)
		(layer "In11.Cu")
		(net "M_F_CPU0_SA_DQ<25>")
	)
	(segment
		(start 270.764 -227.519992)
		(end 270.764 -227.74783)
		(width 0.14478)
		(layer "In11.Cu")
		(net "M_F_CPU0_SA_DQ<25>")
	)
	(segment
		(start 285.892748 -226.660202)
		(end 286.742632 -227.510086)
		(width 0.14478)
		(layer "In11.Cu")
		(net "M_F_CPU0_SA_DQ<25>")
	)
	(segment
		(start 273.856704 -227.89769)
		(end 274.087082 -227.89769)
		(width 0.14478)
		(layer "In11.Cu")
		(net "M_F_CPU0_SA_DQ<25>")
	)
	(segment
		(start 291.563044 -227.047552)
		(end 291.721794 -226.888802)
		(width 0.14478)
		(layer "In11.Cu")
		(net "M_F_CPU0_SA_DQ<25>")
	)
	(segment
		(start 291.884862 -226.660202)
		(end 293.507922 -226.660202)
		(width 0.14478)
		(layer "In11.Cu")
		(net "M_F_CPU0_SA_DQ<25>")
	)
	(segment
		(start 296.99331 -227.742242)
		(end 296.99331 -227.673154)
		(width 0.14478)
		(layer "In11.Cu")
		(net "M_F_CPU0_SA_DQ<25>")
	)
	(segment
		(start 281.972258 -227.510086)
		(end 282.323286 -227.510086)
		(width 0.14478)
		(layer "In11.Cu")
		(net "M_F_CPU0_SA_DQ<25>")
	)
	(segment
		(start 296.99331 -227.673154)
		(end 297.156378 -227.510086)
		(width 0.14478)
		(layer "In11.Cu")
		(net "M_F_CPU0_SA_DQ<25>")
	)
	(segment
		(start 293.507922 -226.660202)
		(end 294.357806 -227.510086)
		(width 0.14478)
		(layer "In11.Cu")
		(net "M_F_CPU0_SA_DQ<25>")
	)
	(segment
		(start 289.883088 -227.510086)
		(end 290.732972 -226.660202)
		(width 0.14478)
		(layer "In11.Cu")
		(net "M_F_CPU0_SA_DQ<25>")
	)
	(segment
		(start 273.693636 -227.673154)
		(end 273.693636 -227.734622)
		(width 0.14478)
		(layer "In11.Cu")
		(net "M_F_CPU0_SA_DQ<25>")
	)
	(segment
		(start 291.16528 -226.82327)
		(end 291.16528 -226.888802)
		(width 0.14478)
		(layer "In11.Cu")
		(net "M_F_CPU0_SA_DQ<25>")
	)
	(segment
		(start 289.585146 -227.510086)
		(end 289.883088 -227.510086)
		(width 0.14478)
		(layer "In11.Cu")
		(net "M_F_CPU0_SA_DQ<25>")
	)
	(segment
		(start 296.273728 -227.510086)
		(end 296.436796 -227.673154)
		(width 0.14478)
		(layer "In11.Cu")
		(net "M_F_CPU0_SA_DQ<25>")
	)
	(segment
		(start 288.702496 -227.510086)
		(end 288.865564 -227.673154)
		(width 0.14478)
		(layer "In11.Cu")
		(net "M_F_CPU0_SA_DQ<25>")
	)
	(segment
		(start 289.422078 -227.742242)
		(end 289.422078 -227.673154)
		(width 0.14478)
		(layer "In11.Cu")
		(net "M_F_CPU0_SA_DQ<25>")
	)
	(segment
		(start 281.403806 -227.893372)
		(end 281.65806 -227.893372)
		(width 0.14478)
		(layer "In11.Cu")
		(net "M_F_CPU0_SA_DQ<25>")
	)
	(segment
		(start 271.866868 -227.519992)
		(end 271.866868 -227.74783)
		(width 0.14478)
		(layer "In11.Cu")
		(net "M_F_CPU0_SA_DQ<25>")
	)
	(segment
		(start 328.984102 -240.756694)
		(end 328.992484 -240.76152)
		(width 0.0889)
		(layer "In11.Cu")
		(net "M_F_CPU0_SA_DQ<25>")
	)
	(segment
		(start 331.229716 -240.76152)
		(end 331.238098 -240.756694)
		(width 0.0889)
		(layer "In11.Cu")
		(net "M_F_CPU0_SA_DQ<25>")
	)
	(segment
		(start 328.02068 -240.742978)
		(end 328.044048 -240.756694)
		(width 0.0889)
		(layer "In11.Cu")
		(net "M_F_CPU0_SA_DQ<25>")
	)
	(segment
		(start 328.409808 -240.76152)
		(end 328.41819 -240.756694)
		(width 0.0889)
		(layer "In11.Cu")
		(net "M_F_CPU0_SA_DQ<25>")
	)
	(segment
		(start 296.436796 -227.742242)
		(end 296.590466 -227.895912)
		(width 0.14478)
		(layer "In11.Cu")
		(net "M_F_CPU0_SA_DQ<25>")
	)
	(segment
		(start 284.20441 -226.82327)
		(end 284.367478 -226.660202)
		(width 0.14478)
		(layer "In11.Cu")
		(net "M_F_CPU0_SA_DQ<25>")
	)
	(segment
		(start 274.413218 -227.510086)
		(end 274.754848 -227.510086)
		(width 0.14478)
		(layer "In11.Cu")
		(net "M_F_CPU0_SA_DQ<25>")
	)
	(segment
		(start 326.511158 -240.771426)
		(end 326.53732 -240.75644)
		(width 0.0889)
		(layer "In11.Cu")
		(net "M_F_CPU0_SA_DQ<25>")
	)
	(segment
		(start 269.648178 -227.085144)
		(end 269.648178 -227.74783)
		(width 0.14478)
		(layer "In11.Cu")
		(net "M_F_CPU0_SA_DQ<25>")
	)
	(segment
		(start 284.20441 -226.888802)
		(end 284.20441 -226.82327)
		(width 0.14478)
		(layer "In11.Cu")
		(net "M_F_CPU0_SA_DQ<25>")
	)
	(segment
		(start 276.453346 -227.045012)
		(end 276.609556 -226.888802)
		(width 0.14478)
		(layer "In11.Cu")
		(net "M_F_CPU0_SA_DQ<25>")
	)
	(segment
		(start 276.053042 -226.888802)
		(end 276.209252 -227.045012)
		(width 0.14478)
		(layer "In11.Cu")
		(net "M_F_CPU0_SA_DQ<25>")
	)
	(segment
		(start 299.24502 -226.882452)
		(end 299.24502 -226.82327)
		(width 0.14478)
		(layer "In11.Cu")
		(net "M_F_CPU0_SA_DQ<25>")
	)
	(segment
		(start 274.087082 -227.89769)
		(end 274.25015 -227.734622)
		(width 0.14478)
		(layer "In11.Cu")
		(net "M_F_CPU0_SA_DQ<25>")
	)
	(segment
		(start 281.80919 -227.742242)
		(end 281.80919 -227.673154)
		(width 0.14478)
		(layer "In11.Cu")
		(net "M_F_CPU0_SA_DQ<25>")
	)
	(segment
		(start 276.772624 -226.660202)
		(end 278.410924 -226.660202)
		(width 0.14478)
		(layer "In11.Cu")
		(net "M_F_CPU0_SA_DQ<25>")
	)
	(segment
		(start 332.744064 -240.756694)
		(end 332.752446 -240.76152)
		(width 0.0889)
		(layer "In11.Cu")
		(net "M_F_CPU0_SA_DQ<25>")
	)
	(segment
		(start 286.742632 -227.510086)
		(end 288.702496 -227.510086)
		(width 0.14478)
		(layer "In11.Cu")
		(net "M_F_CPU0_SA_DQ<25>")
	)
	(segment
		(start 298.688506 -226.82327)
		(end 298.688506 -226.882452)
		(width 0.14478)
		(layer "In11.Cu")
		(net "M_F_CPU0_SA_DQ<25>")
	)
	(segment
		(start 324.866 -239.45977)
		(end 326.162924 -240.756694)
		(width 0.0889)
		(layer "In11.Cu")
		(net "M_F_CPU0_SA_DQ<25>")
	)
	(segment
		(start 305.369976 -227.034852)
		(end 306.944268 -227.034852)
		(width 0.14478)
		(layer "In11.Cu")
		(net "M_F_CPU0_SA_DQ<25>")
	)
	(segment
		(start 269.792958 -227.89261)
		(end 270.067786 -227.89261)
		(width 0.14478)
		(layer "In11.Cu")
		(net "M_F_CPU0_SA_DQ<25>")
	)
	(segment
		(start 298.525438 -226.660202)
		(end 298.688506 -226.82327)
		(width 0.14478)
		(layer "In11.Cu")
		(net "M_F_CPU0_SA_DQ<25>")
	)
	(segment
		(start 274.25015 -227.673154)
		(end 274.413218 -227.510086)
		(width 0.14478)
		(layer "In11.Cu")
		(net "M_F_CPU0_SA_DQ<25>")
	)
	(segment
		(start 299.24502 -226.82327)
		(end 299.408088 -226.660202)
		(width 0.14478)
		(layer "In11.Cu")
		(net "M_F_CPU0_SA_DQ<25>")
	)
	(segment
		(start 281.252676 -227.673154)
		(end 281.252676 -227.742242)
		(width 0.14478)
		(layer "In11.Cu")
		(net "M_F_CPU0_SA_DQ<25>")
	)
	(segment
		(start 288.865564 -227.742242)
		(end 289.014154 -227.890832)
		(width 0.14478)
		(layer "In11.Cu")
		(net "M_F_CPU0_SA_DQ<25>")
	)
	(segment
		(start 283.801566 -227.042472)
		(end 284.05074 -227.042472)
		(width 0.14478)
		(layer "In11.Cu")
		(net "M_F_CPU0_SA_DQ<25>")
	)
	(segment
		(start 291.721794 -226.82327)
		(end 291.884862 -226.660202)
		(width 0.14478)
		(layer "In11.Cu")
		(net "M_F_CPU0_SA_DQ<25>")
	)
	(segment
		(start 284.367478 -226.660202)
		(end 285.892748 -226.660202)
		(width 0.14478)
		(layer "In11.Cu")
		(net "M_F_CPU0_SA_DQ<25>")
	)
	(segment
		(start 271.460214 -227.375212)
		(end 271.722088 -227.375212)
		(width 0.14478)
		(layer "In11.Cu")
		(net "M_F_CPU0_SA_DQ<25>")
	)
	(segment
		(start 327.101708 -240.756694)
		(end 327.116186 -240.765076)
		(width 0.0889)
		(layer "In11.Cu")
		(net "M_F_CPU0_SA_DQ<25>")
	)
	(segment
		(start 289.273488 -227.890832)
		(end 289.422078 -227.742242)
		(width 0.14478)
		(layer "In11.Cu")
		(net "M_F_CPU0_SA_DQ<25>")
	)
	(segment
		(start 271.315434 -227.519992)
		(end 271.460214 -227.375212)
		(width 0.14478)
		(layer "In11.Cu")
		(net "M_F_CPU0_SA_DQ<25>")
	)
	(segment
		(start 333.717138 -240.699544)
		(end 333.871062 -240.434114)
		(width 0.0889)
		(layer "In11.Cu")
		(net "M_F_CPU0_SA_DQ<25>")
	)
	(segment
		(start 289.422078 -227.673154)
		(end 289.585146 -227.510086)
		(width 0.14478)
		(layer "In11.Cu")
		(net "M_F_CPU0_SA_DQ<25>")
	)
	(segment
		(start 270.61922 -227.375212)
		(end 270.764 -227.519992)
		(width 0.14478)
		(layer "In11.Cu")
		(net "M_F_CPU0_SA_DQ<25>")
	)
	(segment
		(start 294.357806 -227.510086)
		(end 296.273728 -227.510086)
		(width 0.14478)
		(layer "In11.Cu")
		(net "M_F_CPU0_SA_DQ<25>")
	)
	(segment
		(start 269.648178 -227.74783)
		(end 269.792958 -227.89261)
		(width 0.14478)
		(layer "In11.Cu")
		(net "M_F_CPU0_SA_DQ<25>")
	)
	(segment
		(start 270.067786 -227.89261)
		(end 270.212566 -227.74783)
		(width 0.14478)
		(layer "In11.Cu")
		(net "M_F_CPU0_SA_DQ<25>")
	)
	(segment
		(start 298.238926 -226.660202)
		(end 298.525438 -226.660202)
		(width 0.14478)
		(layer "In11.Cu")
		(net "M_F_CPU0_SA_DQ<25>")
	)
	(segment
		(start 298.833286 -227.027232)
		(end 299.10024 -227.027232)
		(width 0.14478)
		(layer "In11.Cu")
		(net "M_F_CPU0_SA_DQ<25>")
	)
	(segment
		(start 324.327774 -239.36325)
		(end 324.424294 -239.45977)
		(width 0.0889)
		(layer "In11.Cu")
		(net "M_F_CPU0_SA_DQ<25>")
	)
	(segment
		(start 283.17317 -226.660202)
		(end 283.484828 -226.660202)
		(width 0.14478)
		(layer "In11.Cu")
		(net "M_F_CPU0_SA_DQ<25>")
	)
	(segment
		(start 284.05074 -227.042472)
		(end 284.20441 -226.888802)
		(width 0.14478)
		(layer "In11.Cu")
		(net "M_F_CPU0_SA_DQ<25>")
	)
	(segment
		(start 297.389042 -227.510086)
		(end 298.238926 -226.660202)
		(width 0.14478)
		(layer "In11.Cu")
		(net "M_F_CPU0_SA_DQ<25>")
	)
	(segment
		(start 291.721794 -226.888802)
		(end 291.721794 -226.82327)
		(width 0.14478)
		(layer "In11.Cu")
		(net "M_F_CPU0_SA_DQ<25>")
	)
	(segment
		(start 301.90186 -227.510086)
		(end 304.894742 -227.510086)
		(width 0.14478)
		(layer "In11.Cu")
		(net "M_F_CPU0_SA_DQ<25>")
	)
	(segment
		(start 270.212566 -227.519992)
		(end 270.357346 -227.375212)
		(width 0.14478)
		(layer "In11.Cu")
		(net "M_F_CPU0_SA_DQ<25>")
	)
	(segment
		(start 276.209252 -227.045012)
		(end 276.453346 -227.045012)
		(width 0.14478)
		(layer "In11.Cu")
		(net "M_F_CPU0_SA_DQ<25>")
	)
	(segment
		(start 275.604732 -226.660202)
		(end 275.889974 -226.660202)
		(width 0.14478)
		(layer "In11.Cu")
		(net "M_F_CPU0_SA_DQ<25>")
	)
	(segment
		(start 274.25015 -227.734622)
		(end 274.25015 -227.673154)
		(width 0.14478)
		(layer "In11.Cu")
		(net "M_F_CPU0_SA_DQ<25>")
	)
	(segment
		(start 273.693636 -227.734622)
		(end 273.856704 -227.89769)
		(width 0.14478)
		(layer "In11.Cu")
		(net "M_F_CPU0_SA_DQ<25>")
	)
	(segment
		(start 296.436796 -227.673154)
		(end 296.436796 -227.742242)
		(width 0.14478)
		(layer "In11.Cu")
		(net "M_F_CPU0_SA_DQ<25>")
	)
	(segment
		(start 289.014154 -227.890832)
		(end 289.273488 -227.890832)
		(width 0.14478)
		(layer "In11.Cu")
		(net "M_F_CPU0_SA_DQ<25>")
	)
	(segment
		(start 333.621126 -240.724944)
		(end 333.717138 -240.699544)
		(width 0.0889)
		(layer "In11.Cu")
		(net "M_F_CPU0_SA_DQ<25>")
	)
	(segment
		(start 283.647896 -226.82327)
		(end 283.647896 -226.888802)
		(width 0.14478)
		(layer "In11.Cu")
		(net "M_F_CPU0_SA_DQ<25>")
	)
	(segment
		(start 272.668746 -227.510086)
		(end 273.530568 -227.510086)
		(width 0.14478)
		(layer "In11.Cu")
		(net "M_F_CPU0_SA_DQ<25>")
	)
	(segment
		(start 274.754848 -227.510086)
		(end 275.604732 -226.660202)
		(width 0.14478)
		(layer "In11.Cu")
		(net "M_F_CPU0_SA_DQ<25>")
	)
	(segment
		(start 324.424294 -239.45977)
		(end 324.866 -239.45977)
		(width 0.0889)
		(layer "In11.Cu")
		(net "M_F_CPU0_SA_DQ<25>")
	)
	(segment
		(start 298.688506 -226.882452)
		(end 298.833286 -227.027232)
		(width 0.14478)
		(layer "In11.Cu")
		(net "M_F_CPU0_SA_DQ<25>")
	)
	(segment
		(start 291.32403 -227.047552)
		(end 291.563044 -227.047552)
		(width 0.14478)
		(layer "In11.Cu")
		(net "M_F_CPU0_SA_DQ<25>")
	)
	(segment
		(start 270.212566 -227.74783)
		(end 270.212566 -227.519992)
		(width 0.14478)
		(layer "In11.Cu")
		(net "M_F_CPU0_SA_DQ<25>")
	)
	(segment
		(start 273.530568 -227.510086)
		(end 273.693636 -227.673154)
		(width 0.14478)
		(layer "In11.Cu")
		(net "M_F_CPU0_SA_DQ<25>")
	)
	(segment
		(start 282.323286 -227.510086)
		(end 283.17317 -226.660202)
		(width 0.14478)
		(layer "In11.Cu")
		(net "M_F_CPU0_SA_DQ<25>")
	)
	(segment
		(start 299.408088 -226.660202)
		(end 301.051976 -226.660202)
		(width 0.14478)
		(layer "In11.Cu")
		(net "M_F_CPU0_SA_DQ<25>")
	)
	(segment
		(start 272.286222 -227.89261)
		(end 272.668746 -227.510086)
		(width 0.14478)
		(layer "In11.Cu")
		(net "M_F_CPU0_SA_DQ<25>")
	)
	(segment
		(start 270.764 -227.74783)
		(end 270.90878 -227.89261)
		(width 0.14478)
		(layer "In11.Cu")
		(net "M_F_CPU0_SA_DQ<25>")
	)
	(segment
		(start 319.272666 -239.36325)
		(end 323.928994 -239.36325)
		(width 0.14478)
		(layer "In11.Cu")
		(net "M_F_CPU0_SA_DQ<25>")
	)
	(segment
		(start 299.10024 -227.027232)
		(end 299.24502 -226.882452)
		(width 0.14478)
		(layer "In11.Cu")
		(net "M_F_CPU0_SA_DQ<25>")
	)
	(segment
		(start 306.944268 -227.034852)
		(end 319.272666 -239.36325)
		(width 0.14478)
		(layer "In11.Cu")
		(net "M_F_CPU0_SA_DQ<25>")
	)
	(segment
		(start 270.90878 -227.89261)
		(end 271.170654 -227.89261)
		(width 0.14478)
		(layer "In11.Cu")
		(net "M_F_CPU0_SA_DQ<25>")
	)
	(segment
		(start 281.65806 -227.893372)
		(end 281.80919 -227.742242)
		(width 0.14478)
		(layer "In11.Cu")
		(net "M_F_CPU0_SA_DQ<25>")
	)
	(segment
		(start 271.866868 -227.74783)
		(end 272.011648 -227.89261)
		(width 0.14478)
		(layer "In11.Cu")
		(net "M_F_CPU0_SA_DQ<25>")
	)
	(segment
		(start 326.53732 -240.75644)
		(end 326.55891 -240.743994)
		(width 0.0889)
		(layer "In11.Cu")
		(net "M_F_CPU0_SA_DQ<25>")
	)
	(segment
		(start 283.647896 -226.888802)
		(end 283.801566 -227.042472)
		(width 0.14478)
		(layer "In11.Cu")
		(net "M_F_CPU0_SA_DQ<25>")
	)
	(segment
		(start 288.865564 -227.673154)
		(end 288.865564 -227.742242)
		(width 0.14478)
		(layer "In11.Cu")
		(net "M_F_CPU0_SA_DQ<25>")
	)
	(segment
		(start 276.609556 -226.888802)
		(end 276.609556 -226.82327)
		(width 0.14478)
		(layer "In11.Cu")
		(net "M_F_CPU0_SA_DQ<25>")
	)
	(segment
		(start 283.484828 -226.660202)
		(end 283.647896 -226.82327)
		(width 0.14478)
		(layer "In11.Cu")
		(net "M_F_CPU0_SA_DQ<25>")
	)
	(segment
		(start 332.16977 -240.76152)
		(end 332.178152 -240.756694)
		(width 0.0889)
		(layer "In11.Cu")
		(net "M_F_CPU0_SA_DQ<25>")
	)
	(segment
		(start 276.609556 -226.82327)
		(end 276.772624 -226.660202)
		(width 0.14478)
		(layer "In11.Cu")
		(net "M_F_CPU0_SA_DQ<25>")
	)
	(segment
		(start 291.002212 -226.660202)
		(end 291.16528 -226.82327)
		(width 0.14478)
		(layer "In11.Cu")
		(net "M_F_CPU0_SA_DQ<25>")
	)
	(segment
		(start 271.315434 -227.74783)
		(end 271.315434 -227.519992)
		(width 0.14478)
		(layer "In11.Cu")
		(net "M_F_CPU0_SA_DQ<25>")
	)
	(segment
		(start 271.170654 -227.89261)
		(end 271.315434 -227.74783)
		(width 0.14478)
		(layer "In11.Cu")
		(net "M_F_CPU0_SA_DQ<25>")
	)
	(segment
		(start 275.889974 -226.660202)
		(end 276.053042 -226.82327)
		(width 0.14478)
		(layer "In11.Cu")
		(net "M_F_CPU0_SA_DQ<25>")
	)
	(segment
		(start 323.928994 -239.36325)
		(end 324.327774 -239.36325)
		(width 0.0889)
		(layer "In11.Cu")
		(net "M_F_CPU0_SA_DQ<25>")
	)
	(segment
		(start 297.156378 -227.510086)
		(end 297.389042 -227.510086)
		(width 0.14478)
		(layer "In11.Cu")
		(net "M_F_CPU0_SA_DQ<25>")
	)
	(segment
		(start 281.80919 -227.673154)
		(end 281.972258 -227.510086)
		(width 0.14478)
		(layer "In11.Cu")
		(net "M_F_CPU0_SA_DQ<25>")
	)
	(segment
		(start 281.252676 -227.742242)
		(end 281.403806 -227.893372)
		(width 0.14478)
		(layer "In11.Cu")
		(net "M_F_CPU0_SA_DQ<25>")
	)
	(segment
		(start 272.011648 -227.89261)
		(end 272.286222 -227.89261)
		(width 0.14478)
		(layer "In11.Cu")
		(net "M_F_CPU0_SA_DQ<25>")
	)
	(segment
		(start 276.053042 -226.82327)
		(end 276.053042 -226.888802)
		(width 0.14478)
		(layer "In11.Cu")
		(net "M_F_CPU0_SA_DQ<25>")
	)
	(segment
		(start 304.894742 -227.510086)
		(end 305.369976 -227.034852)
		(width 0.14478)
		(layer "In11.Cu")
		(net "M_F_CPU0_SA_DQ<25>")
	)
	(segment
		(start 278.410924 -226.660202)
		(end 279.260808 -227.510086)
		(width 0.14478)
		(layer "In11.Cu")
		(net "M_F_CPU0_SA_DQ<25>")
	)
	(segment
		(start 270.357346 -227.375212)
		(end 270.61922 -227.375212)
		(width 0.14478)
		(layer "In11.Cu")
		(net "M_F_CPU0_SA_DQ<25>")
	)
	(segment
		(start 281.089608 -227.510086)
		(end 281.252676 -227.673154)
		(width 0.14478)
		(layer "In11.Cu")
		(net "M_F_CPU0_SA_DQ<25>")
	)
	(arc
		(start 328.044048 -240.756694)
		(mid 328.226299 -240.807044)
		(end 328.409808 -240.76152)
		(width 0.0889)
		(layer "In11.Cu")
		(net "M_F_CPU0_SA_DQ<25>")
	)
	(arc
		(start 328.992484 -240.76152)
		(mid 329.175992 -240.807014)
		(end 329.358244 -240.756694)
		(width 0.0889)
		(layer "In11.Cu")
		(net "M_F_CPU0_SA_DQ<25>")
	)
	(arc
		(start 333.118206 -240.756694)
		(mid 333.365919 -240.681474)
		(end 333.621126 -240.724944)
		(width 0.0889)
		(layer "In11.Cu")
		(net "M_F_CPU0_SA_DQ<25>")
	)
	(arc
		(start 329.924156 -240.756694)
		(mid 330.1111 -240.806949)
		(end 330.298044 -240.756694)
		(width 0.0889)
		(layer "In11.Cu")
		(net "M_F_CPU0_SA_DQ<25>")
	)
	(arc
		(start 330.863956 -240.756694)
		(mid 331.046207 -240.807044)
		(end 331.229716 -240.76152)
		(width 0.0889)
		(layer "In11.Cu")
		(net "M_F_CPU0_SA_DQ<25>")
	)
	(arc
		(start 326.55891 -240.743994)
		(mid 326.831939 -240.680675)
		(end 327.101708 -240.756694)
		(width 0.0889)
		(layer "In11.Cu")
		(net "M_F_CPU0_SA_DQ<25>")
	)
	(arc
		(start 329.358244 -240.756694)
		(mid 329.6412 -240.680517)
		(end 329.924156 -240.756694)
		(width 0.0889)
		(layer "In11.Cu")
		(net "M_F_CPU0_SA_DQ<25>")
	)
	(arc
		(start 331.238098 -240.756694)
		(mid 331.521054 -240.680517)
		(end 331.80401 -240.756694)
		(width 0.0889)
		(layer "In11.Cu")
		(net "M_F_CPU0_SA_DQ<25>")
	)
	(arc
		(start 332.178152 -240.756694)
		(mid 332.461108 -240.680517)
		(end 332.744064 -240.756694)
		(width 0.0889)
		(layer "In11.Cu")
		(net "M_F_CPU0_SA_DQ<25>")
	)
	(arc
		(start 328.41819 -240.756694)
		(mid 328.701146 -240.680517)
		(end 328.984102 -240.756694)
		(width 0.0889)
		(layer "In11.Cu")
		(net "M_F_CPU0_SA_DQ<25>")
	)
	(arc
		(start 327.116186 -240.765076)
		(mid 327.297602 -240.807333)
		(end 327.476866 -240.756694)
		(width 0.0889)
		(layer "In11.Cu")
		(net "M_F_CPU0_SA_DQ<25>")
	)
	(arc
		(start 330.298044 -240.756694)
		(mid 330.581 -240.680517)
		(end 330.863956 -240.756694)
		(width 0.0889)
		(layer "In11.Cu")
		(net "M_F_CPU0_SA_DQ<25>")
	)
	(arc
		(start 331.80401 -240.756694)
		(mid 331.986261 -240.807044)
		(end 332.16977 -240.76152)
		(width 0.0889)
		(layer "In11.Cu")
		(net "M_F_CPU0_SA_DQ<25>")
	)
	(arc
		(start 327.476866 -240.756694)
		(mid 327.747023 -240.679932)
		(end 328.02068 -240.742978)
		(width 0.0889)
		(layer "In11.Cu")
		(net "M_F_CPU0_SA_DQ<25>")
	)
	(arc
		(start 326.162924 -240.756694)
		(mid 326.335206 -240.80713)
		(end 326.511158 -240.771426)
		(width 0.0889)
		(layer "In11.Cu")
		(net "M_F_CPU0_SA_DQ<25>")
	)
	(arc
		(start 332.752446 -240.76152)
		(mid 332.935954 -240.807014)
		(end 333.118206 -240.756694)
		(width 0.0889)
		(layer "In11.Cu")
		(net "M_F_CPU0_SA_DQ<25>")
	)
	(segment
		(start 332.92796 -239.890046)
		(end 332.461108 -239.624108)
		(width 0.10668)
		(layer "F.Cu")
		(net "M_F_CPU0_SA_DQ<24>")
	)
	(segment
		(start 297.389042 -225.810064)
		(end 298.238926 -224.96018)
		(width 0.14478)
		(layer "In11.Cu")
		(net "M_F_CPU0_SA_DQ<24>")
	)
	(segment
		(start 281.06878 -225.810064)
		(end 281.231848 -225.973132)
		(width 0.14478)
		(layer "In11.Cu")
		(net "M_F_CPU0_SA_DQ<24>")
	)
	(segment
		(start 271.307052 -225.978212)
		(end 271.626076 -225.978212)
		(width 0.14478)
		(layer "In11.Cu")
		(net "M_F_CPU0_SA_DQ<24>")
	)
	(segment
		(start 276.482302 -225.35515)
		(end 276.64537 -225.192082)
		(width 0.14478)
		(layer "In11.Cu")
		(net "M_F_CPU0_SA_DQ<24>")
	)
	(segment
		(start 271.074642 -226.210622)
		(end 271.307052 -225.978212)
		(width 0.14478)
		(layer "In11.Cu")
		(net "M_F_CPU0_SA_DQ<24>")
	)
	(segment
		(start 303.178972 -226.035362)
		(end 303.178972 -225.973132)
		(width 0.14478)
		(layer "In11.Cu")
		(net "M_F_CPU0_SA_DQ<24>")
	)
	(segment
		(start 305.942492 -225.51136)
		(end 306.204366 -225.51136)
		(width 0.14478)
		(layer "In11.Cu")
		(net "M_F_CPU0_SA_DQ<24>")
	)
	(segment
		(start 332.211172 -239.914938)
		(end 332.307184 -239.889538)
		(width 0.0889)
		(layer "In11.Cu")
		(net "M_F_CPU0_SA_DQ<24>")
	)
	(segment
		(start 269.648178 -225.385122)
		(end 269.648178 -225.64725)
		(width 0.14478)
		(layer "In11.Cu")
		(net "M_F_CPU0_SA_DQ<24>")
	)
	(segment
		(start 291.78758 -225.123248)
		(end 291.950648 -224.96018)
		(width 0.14478)
		(layer "In11.Cu")
		(net "M_F_CPU0_SA_DQ<24>")
	)
	(segment
		(start 307.809138 -226.535742)
		(end 319.722246 -238.44885)
		(width 0.14478)
		(layer "In11.Cu")
		(net "M_F_CPU0_SA_DQ<24>")
	)
	(segment
		(start 276.088856 -225.192082)
		(end 276.251924 -225.35515)
		(width 0.14478)
		(layer "In11.Cu")
		(net "M_F_CPU0_SA_DQ<24>")
	)
	(segment
		(start 327.562464 -239.939576)
		(end 327.574402 -239.946434)
		(width 0.0889)
		(layer "In11.Cu")
		(net "M_F_CPU0_SA_DQ<24>")
	)
	(segment
		(start 291.950648 -224.96018)
		(end 293.507922 -224.96018)
		(width 0.14478)
		(layer "In11.Cu")
		(net "M_F_CPU0_SA_DQ<24>")
	)
	(segment
		(start 326.106536 -239.870234)
		(end 326.351138 -239.870234)
		(width 0.0889)
		(layer "In11.Cu")
		(net "M_F_CPU0_SA_DQ<24>")
	)
	(segment
		(start 323.873114 -238.44885)
		(end 324.368414 -238.44885)
		(width 0.0889)
		(layer "In11.Cu")
		(net "M_F_CPU0_SA_DQ<24>")
	)
	(segment
		(start 298.664884 -225.123248)
		(end 298.664884 -225.181922)
		(width 0.14478)
		(layer "In11.Cu")
		(net "M_F_CPU0_SA_DQ<24>")
	)
	(segment
		(start 302.622458 -226.035362)
		(end 302.785526 -226.19843)
		(width 0.14478)
		(layer "In11.Cu")
		(net "M_F_CPU0_SA_DQ<24>")
	)
	(segment
		(start 303.898554 -226.19843)
		(end 304.128932 -226.19843)
		(width 0.14478)
		(layer "In11.Cu")
		(net "M_F_CPU0_SA_DQ<24>")
	)
	(segment
		(start 281.231848 -225.973132)
		(end 281.231848 -226.035362)
		(width 0.14478)
		(layer "In11.Cu")
		(net "M_F_CPU0_SA_DQ<24>")
	)
	(segment
		(start 293.507922 -224.96018)
		(end 294.357806 -225.810064)
		(width 0.14478)
		(layer "In11.Cu")
		(net "M_F_CPU0_SA_DQ<24>")
	)
	(segment
		(start 306.204366 -225.51136)
		(end 306.349146 -225.65614)
		(width 0.14478)
		(layer "In11.Cu")
		(net "M_F_CPU0_SA_DQ<24>")
	)
	(segment
		(start 288.883344 -226.030282)
		(end 289.046412 -226.19335)
		(width 0.14478)
		(layer "In11.Cu")
		(net "M_F_CPU0_SA_DQ<24>")
	)
	(segment
		(start 276.64537 -225.192082)
		(end 276.64537 -225.123248)
		(width 0.14478)
		(layer "In11.Cu")
		(net "M_F_CPU0_SA_DQ<24>")
	)
	(segment
		(start 330.394056 -239.946688)
		(end 330.402438 -239.951514)
		(width 0.0889)
		(layer "In11.Cu")
		(net "M_F_CPU0_SA_DQ<24>")
	)
	(segment
		(start 281.95143 -225.810064)
		(end 282.323286 -225.810064)
		(width 0.14478)
		(layer "In11.Cu")
		(net "M_F_CPU0_SA_DQ<24>")
	)
	(segment
		(start 303.015904 -226.19843)
		(end 303.178972 -226.035362)
		(width 0.14478)
		(layer "In11.Cu")
		(net "M_F_CPU0_SA_DQ<24>")
	)
	(segment
		(start 305.652932 -226.018852)
		(end 305.797712 -225.874072)
		(width 0.14478)
		(layer "In11.Cu")
		(net "M_F_CPU0_SA_DQ<24>")
	)
	(segment
		(start 305.101498 -225.51136)
		(end 305.246278 -225.65614)
		(width 0.14478)
		(layer "In11.Cu")
		(net "M_F_CPU0_SA_DQ<24>")
	)
	(segment
		(start 284.222444 -225.123248)
		(end 284.385512 -224.96018)
		(width 0.14478)
		(layer "In11.Cu")
		(net "M_F_CPU0_SA_DQ<24>")
	)
	(segment
		(start 283.17317 -224.96018)
		(end 283.502862 -224.96018)
		(width 0.14478)
		(layer "In11.Cu")
		(net "M_F_CPU0_SA_DQ<24>")
	)
	(segment
		(start 305.246278 -225.65614)
		(end 305.246278 -225.874072)
		(width 0.14478)
		(layer "In11.Cu")
		(net "M_F_CPU0_SA_DQ<24>")
	)
	(segment
		(start 297.186096 -225.810064)
		(end 297.389042 -225.810064)
		(width 0.14478)
		(layer "In11.Cu")
		(net "M_F_CPU0_SA_DQ<24>")
	)
	(segment
		(start 273.838924 -226.20097)
		(end 274.069302 -226.20097)
		(width 0.14478)
		(layer "In11.Cu")
		(net "M_F_CPU0_SA_DQ<24>")
	)
	(segment
		(start 290.732972 -224.96018)
		(end 291.067998 -224.96018)
		(width 0.14478)
		(layer "In11.Cu")
		(net "M_F_CPU0_SA_DQ<24>")
	)
	(segment
		(start 307.809138 -225.856038)
		(end 307.809138 -226.535742)
		(width 0.14478)
		(layer "In11.Cu")
		(net "M_F_CPU0_SA_DQ<24>")
	)
	(segment
		(start 304.43678 -225.51136)
		(end 305.101498 -225.51136)
		(width 0.14478)
		(layer "In11.Cu")
		(net "M_F_CPU0_SA_DQ<24>")
	)
	(segment
		(start 302.45939 -225.810064)
		(end 302.622458 -225.973132)
		(width 0.14478)
		(layer "In11.Cu")
		(net "M_F_CPU0_SA_DQ<24>")
	)
	(segment
		(start 273.675856 -225.973132)
		(end 273.675856 -226.037902)
		(width 0.14478)
		(layer "In11.Cu")
		(net "M_F_CPU0_SA_DQ<24>")
	)
	(segment
		(start 278.410924 -224.96018)
		(end 279.260808 -225.810064)
		(width 0.14478)
		(layer "In11.Cu")
		(net "M_F_CPU0_SA_DQ<24>")
	)
	(segment
		(start 303.34204 -225.810064)
		(end 303.572418 -225.810064)
		(width 0.14478)
		(layer "In11.Cu")
		(net "M_F_CPU0_SA_DQ<24>")
	)
	(segment
		(start 298.664884 -225.181922)
		(end 298.827952 -225.34499)
		(width 0.14478)
		(layer "In11.Cu")
		(net "M_F_CPU0_SA_DQ<24>")
	)
	(segment
		(start 324.368414 -238.44885)
		(end 324.569074 -238.64951)
		(width 0.0889)
		(layer "In11.Cu")
		(net "M_F_CPU0_SA_DQ<24>")
	)
	(segment
		(start 291.231066 -225.181922)
		(end 291.394134 -225.34499)
		(width 0.14478)
		(layer "In11.Cu")
		(net "M_F_CPU0_SA_DQ<24>")
	)
	(segment
		(start 285.892748 -224.96018)
		(end 286.742632 -225.810064)
		(width 0.14478)
		(layer "In11.Cu")
		(net "M_F_CPU0_SA_DQ<24>")
	)
	(segment
		(start 306.493926 -226.018852)
		(end 306.7558 -226.018852)
		(width 0.14478)
		(layer "In11.Cu")
		(net "M_F_CPU0_SA_DQ<24>")
	)
	(segment
		(start 269.648178 -225.64725)
		(end 270.21155 -226.210622)
		(width 0.14478)
		(layer "In11.Cu")
		(net "M_F_CPU0_SA_DQ<24>")
	)
	(segment
		(start 331.33411 -239.946688)
		(end 331.342492 -239.951514)
		(width 0.0889)
		(layer "In11.Cu")
		(net "M_F_CPU0_SA_DQ<24>")
	)
	(segment
		(start 291.78758 -225.181922)
		(end 291.78758 -225.123248)
		(width 0.14478)
		(layer "In11.Cu")
		(net "M_F_CPU0_SA_DQ<24>")
	)
	(segment
		(start 289.439858 -226.030282)
		(end 289.439858 -225.973132)
		(width 0.14478)
		(layer "In11.Cu")
		(net "M_F_CPU0_SA_DQ<24>")
	)
	(segment
		(start 297.023028 -226.035362)
		(end 297.023028 -225.973132)
		(width 0.14478)
		(layer "In11.Cu")
		(net "M_F_CPU0_SA_DQ<24>")
	)
	(segment
		(start 296.85996 -226.19843)
		(end 297.023028 -226.035362)
		(width 0.14478)
		(layer "In11.Cu")
		(net "M_F_CPU0_SA_DQ<24>")
	)
	(segment
		(start 305.391058 -226.018852)
		(end 305.652932 -226.018852)
		(width 0.14478)
		(layer "In11.Cu")
		(net "M_F_CPU0_SA_DQ<24>")
	)
	(segment
		(start 303.735486 -226.035362)
		(end 303.898554 -226.19843)
		(width 0.14478)
		(layer "In11.Cu")
		(net "M_F_CPU0_SA_DQ<24>")
	)
	(segment
		(start 289.27679 -226.19335)
		(end 289.439858 -226.030282)
		(width 0.14478)
		(layer "In11.Cu")
		(net "M_F_CPU0_SA_DQ<24>")
	)
	(segment
		(start 301.051976 -224.96018)
		(end 301.90186 -225.810064)
		(width 0.14478)
		(layer "In11.Cu")
		(net "M_F_CPU0_SA_DQ<24>")
	)
	(segment
		(start 276.088856 -225.123248)
		(end 276.088856 -225.192082)
		(width 0.14478)
		(layer "In11.Cu")
		(net "M_F_CPU0_SA_DQ<24>")
	)
	(segment
		(start 296.466514 -226.035362)
		(end 296.629582 -226.19843)
		(width 0.14478)
		(layer "In11.Cu")
		(net "M_F_CPU0_SA_DQ<24>")
	)
	(segment
		(start 283.66593 -225.123248)
		(end 283.66593 -225.187002)
		(width 0.14478)
		(layer "In11.Cu")
		(net "M_F_CPU0_SA_DQ<24>")
	)
	(segment
		(start 274.395438 -225.810064)
		(end 274.754848 -225.810064)
		(width 0.14478)
		(layer "In11.Cu")
		(net "M_F_CPU0_SA_DQ<24>")
	)
	(segment
		(start 307.04536 -225.51136)
		(end 307.46446 -225.51136)
		(width 0.14478)
		(layer "In11.Cu")
		(net "M_F_CPU0_SA_DQ<24>")
	)
	(segment
		(start 296.303446 -225.810064)
		(end 296.466514 -225.973132)
		(width 0.14478)
		(layer "In11.Cu")
		(net "M_F_CPU0_SA_DQ<24>")
	)
	(segment
		(start 306.349146 -225.874072)
		(end 306.493926 -226.018852)
		(width 0.14478)
		(layer "In11.Cu")
		(net "M_F_CPU0_SA_DQ<24>")
	)
	(segment
		(start 286.742632 -225.810064)
		(end 288.720276 -225.810064)
		(width 0.14478)
		(layer "In11.Cu")
		(net "M_F_CPU0_SA_DQ<24>")
	)
	(segment
		(start 296.629582 -226.19843)
		(end 296.85996 -226.19843)
		(width 0.14478)
		(layer "In11.Cu")
		(net "M_F_CPU0_SA_DQ<24>")
	)
	(segment
		(start 305.797712 -225.65614)
		(end 305.942492 -225.51136)
		(width 0.14478)
		(layer "In11.Cu")
		(net "M_F_CPU0_SA_DQ<24>")
	)
	(segment
		(start 305.246278 -225.874072)
		(end 305.391058 -226.018852)
		(width 0.14478)
		(layer "In11.Cu")
		(net "M_F_CPU0_SA_DQ<24>")
	)
	(segment
		(start 291.067998 -224.96018)
		(end 291.231066 -225.123248)
		(width 0.14478)
		(layer "In11.Cu")
		(net "M_F_CPU0_SA_DQ<24>")
	)
	(segment
		(start 283.502862 -224.96018)
		(end 283.66593 -225.123248)
		(width 0.14478)
		(layer "In11.Cu")
		(net "M_F_CPU0_SA_DQ<24>")
	)
	(segment
		(start 289.883088 -225.810064)
		(end 290.732972 -224.96018)
		(width 0.14478)
		(layer "In11.Cu")
		(net "M_F_CPU0_SA_DQ<24>")
	)
	(segment
		(start 271.626076 -225.978212)
		(end 271.858486 -226.210622)
		(width 0.14478)
		(layer "In11.Cu")
		(net "M_F_CPU0_SA_DQ<24>")
	)
	(segment
		(start 298.827952 -225.34499)
		(end 299.05833 -225.34499)
		(width 0.14478)
		(layer "In11.Cu")
		(net "M_F_CPU0_SA_DQ<24>")
	)
	(segment
		(start 273.512788 -225.810064)
		(end 273.675856 -225.973132)
		(width 0.14478)
		(layer "In11.Cu")
		(net "M_F_CPU0_SA_DQ<24>")
	)
	(segment
		(start 272.494248 -226.210622)
		(end 272.894806 -225.810064)
		(width 0.14478)
		(layer "In11.Cu")
		(net "M_F_CPU0_SA_DQ<24>")
	)
	(segment
		(start 283.828998 -225.35007)
		(end 284.059376 -225.35007)
		(width 0.14478)
		(layer "In11.Cu")
		(net "M_F_CPU0_SA_DQ<24>")
	)
	(segment
		(start 326.997568 -239.953546)
		(end 327.009252 -239.946688)
		(width 0.0889)
		(layer "In11.Cu")
		(net "M_F_CPU0_SA_DQ<24>")
	)
	(segment
		(start 302.785526 -226.19843)
		(end 303.015904 -226.19843)
		(width 0.14478)
		(layer "In11.Cu")
		(net "M_F_CPU0_SA_DQ<24>")
	)
	(segment
		(start 274.754848 -225.810064)
		(end 275.604732 -224.96018)
		(width 0.14478)
		(layer "In11.Cu")
		(net "M_F_CPU0_SA_DQ<24>")
	)
	(segment
		(start 327.574402 -239.946434)
		(end 327.590658 -239.955832)
		(width 0.0889)
		(layer "In11.Cu")
		(net "M_F_CPU0_SA_DQ<24>")
	)
	(segment
		(start 303.178972 -225.973132)
		(end 303.34204 -225.810064)
		(width 0.14478)
		(layer "In11.Cu")
		(net "M_F_CPU0_SA_DQ<24>")
	)
	(segment
		(start 291.394134 -225.34499)
		(end 291.624512 -225.34499)
		(width 0.14478)
		(layer "In11.Cu")
		(net "M_F_CPU0_SA_DQ<24>")
	)
	(segment
		(start 275.925788 -224.96018)
		(end 276.088856 -225.123248)
		(width 0.14478)
		(layer "In11.Cu")
		(net "M_F_CPU0_SA_DQ<24>")
	)
	(segment
		(start 281.788362 -226.035362)
		(end 281.788362 -225.973132)
		(width 0.14478)
		(layer "In11.Cu")
		(net "M_F_CPU0_SA_DQ<24>")
	)
	(segment
		(start 301.90186 -225.810064)
		(end 302.45939 -225.810064)
		(width 0.14478)
		(layer "In11.Cu")
		(net "M_F_CPU0_SA_DQ<24>")
	)
	(segment
		(start 306.7558 -226.018852)
		(end 306.90058 -225.874072)
		(width 0.14478)
		(layer "In11.Cu")
		(net "M_F_CPU0_SA_DQ<24>")
	)
	(segment
		(start 302.622458 -225.973132)
		(end 302.622458 -226.035362)
		(width 0.14478)
		(layer "In11.Cu")
		(net "M_F_CPU0_SA_DQ<24>")
	)
	(segment
		(start 305.797712 -225.874072)
		(end 305.797712 -225.65614)
		(width 0.14478)
		(layer "In11.Cu")
		(net "M_F_CPU0_SA_DQ<24>")
	)
	(segment
		(start 284.059376 -225.35007)
		(end 284.222444 -225.187002)
		(width 0.14478)
		(layer "In11.Cu")
		(net "M_F_CPU0_SA_DQ<24>")
	)
	(segment
		(start 306.90058 -225.65614)
		(end 307.04536 -225.51136)
		(width 0.14478)
		(layer "In11.Cu")
		(net "M_F_CPU0_SA_DQ<24>")
	)
	(segment
		(start 284.385512 -224.96018)
		(end 285.892748 -224.96018)
		(width 0.14478)
		(layer "In11.Cu")
		(net "M_F_CPU0_SA_DQ<24>")
	)
	(segment
		(start 289.602926 -225.810064)
		(end 289.883088 -225.810064)
		(width 0.14478)
		(layer "In11.Cu")
		(net "M_F_CPU0_SA_DQ<24>")
	)
	(segment
		(start 284.222444 -225.187002)
		(end 284.222444 -225.123248)
		(width 0.14478)
		(layer "In11.Cu")
		(net "M_F_CPU0_SA_DQ<24>")
	)
	(segment
		(start 276.808438 -224.96018)
		(end 278.410924 -224.96018)
		(width 0.14478)
		(layer "In11.Cu")
		(net "M_F_CPU0_SA_DQ<24>")
	)
	(segment
		(start 289.046412 -226.19335)
		(end 289.27679 -226.19335)
		(width 0.14478)
		(layer "In11.Cu")
		(net "M_F_CPU0_SA_DQ<24>")
	)
	(segment
		(start 291.231066 -225.123248)
		(end 291.231066 -225.181922)
		(width 0.14478)
		(layer "In11.Cu")
		(net "M_F_CPU0_SA_DQ<24>")
	)
	(segment
		(start 298.238926 -224.96018)
		(end 298.501816 -224.96018)
		(width 0.14478)
		(layer "In11.Cu")
		(net "M_F_CPU0_SA_DQ<24>")
	)
	(segment
		(start 282.323286 -225.810064)
		(end 283.17317 -224.96018)
		(width 0.14478)
		(layer "In11.Cu")
		(net "M_F_CPU0_SA_DQ<24>")
	)
	(segment
		(start 306.90058 -225.874072)
		(end 306.90058 -225.65614)
		(width 0.14478)
		(layer "In11.Cu")
		(net "M_F_CPU0_SA_DQ<24>")
	)
	(segment
		(start 288.883344 -225.973132)
		(end 288.883344 -226.030282)
		(width 0.14478)
		(layer "In11.Cu")
		(net "M_F_CPU0_SA_DQ<24>")
	)
	(segment
		(start 332.307184 -239.889538)
		(end 332.461108 -239.624108)
		(width 0.0889)
		(layer "In11.Cu")
		(net "M_F_CPU0_SA_DQ<24>")
	)
	(segment
		(start 274.23237 -225.973132)
		(end 274.395438 -225.810064)
		(width 0.14478)
		(layer "In11.Cu")
		(net "M_F_CPU0_SA_DQ<24>")
	)
	(segment
		(start 275.604732 -224.96018)
		(end 275.925788 -224.96018)
		(width 0.14478)
		(layer "In11.Cu")
		(net "M_F_CPU0_SA_DQ<24>")
	)
	(segment
		(start 324.885812 -238.64951)
		(end 326.106536 -239.870234)
		(width 0.0889)
		(layer "In11.Cu")
		(net "M_F_CPU0_SA_DQ<24>")
	)
	(segment
		(start 306.349146 -225.65614)
		(end 306.349146 -225.874072)
		(width 0.14478)
		(layer "In11.Cu")
		(net "M_F_CPU0_SA_DQ<24>")
	)
	(segment
		(start 283.66593 -225.187002)
		(end 283.828998 -225.35007)
		(width 0.14478)
		(layer "In11.Cu")
		(net "M_F_CPU0_SA_DQ<24>")
	)
	(segment
		(start 294.357806 -225.810064)
		(end 296.303446 -225.810064)
		(width 0.14478)
		(layer "In11.Cu")
		(net "M_F_CPU0_SA_DQ<24>")
	)
	(segment
		(start 329.819762 -239.951514)
		(end 329.828144 -239.946688)
		(width 0.0889)
		(layer "In11.Cu")
		(net "M_F_CPU0_SA_DQ<24>")
	)
	(segment
		(start 324.569074 -238.64951)
		(end 324.885812 -238.64951)
		(width 0.0889)
		(layer "In11.Cu")
		(net "M_F_CPU0_SA_DQ<24>")
	)
	(segment
		(start 291.624512 -225.34499)
		(end 291.78758 -225.181922)
		(width 0.14478)
		(layer "In11.Cu")
		(net "M_F_CPU0_SA_DQ<24>")
	)
	(segment
		(start 289.439858 -225.973132)
		(end 289.602926 -225.810064)
		(width 0.14478)
		(layer "In11.Cu")
		(net "M_F_CPU0_SA_DQ<24>")
	)
	(segment
		(start 274.069302 -226.20097)
		(end 274.23237 -226.037902)
		(width 0.14478)
		(layer "In11.Cu")
		(net "M_F_CPU0_SA_DQ<24>")
	)
	(segment
		(start 319.722246 -238.44885)
		(end 323.873114 -238.44885)
		(width 0.14478)
		(layer "In11.Cu")
		(net "M_F_CPU0_SA_DQ<24>")
	)
	(segment
		(start 276.64537 -225.123248)
		(end 276.808438 -224.96018)
		(width 0.14478)
		(layer "In11.Cu")
		(net "M_F_CPU0_SA_DQ<24>")
	)
	(segment
		(start 288.720276 -225.810064)
		(end 288.883344 -225.973132)
		(width 0.14478)
		(layer "In11.Cu")
		(net "M_F_CPU0_SA_DQ<24>")
	)
	(segment
		(start 299.221398 -225.123248)
		(end 299.384466 -224.96018)
		(width 0.14478)
		(layer "In11.Cu")
		(net "M_F_CPU0_SA_DQ<24>")
	)
	(segment
		(start 298.501816 -224.96018)
		(end 298.664884 -225.123248)
		(width 0.14478)
		(layer "In11.Cu")
		(net "M_F_CPU0_SA_DQ<24>")
	)
	(segment
		(start 296.466514 -225.973132)
		(end 296.466514 -226.035362)
		(width 0.14478)
		(layer "In11.Cu")
		(net "M_F_CPU0_SA_DQ<24>")
	)
	(segment
		(start 281.788362 -225.973132)
		(end 281.95143 -225.810064)
		(width 0.14478)
		(layer "In11.Cu")
		(net "M_F_CPU0_SA_DQ<24>")
	)
	(segment
		(start 304.292 -225.65614)
		(end 304.43678 -225.51136)
		(width 0.14478)
		(layer "In11.Cu")
		(net "M_F_CPU0_SA_DQ<24>")
	)
	(segment
		(start 272.894806 -225.810064)
		(end 273.512788 -225.810064)
		(width 0.14478)
		(layer "In11.Cu")
		(net "M_F_CPU0_SA_DQ<24>")
	)
	(segment
		(start 299.221398 -225.181922)
		(end 299.221398 -225.123248)
		(width 0.14478)
		(layer "In11.Cu")
		(net "M_F_CPU0_SA_DQ<24>")
	)
	(segment
		(start 274.23237 -226.037902)
		(end 274.23237 -225.973132)
		(width 0.14478)
		(layer "In11.Cu")
		(net "M_F_CPU0_SA_DQ<24>")
	)
	(segment
		(start 303.572418 -225.810064)
		(end 303.735486 -225.973132)
		(width 0.14478)
		(layer "In11.Cu")
		(net "M_F_CPU0_SA_DQ<24>")
	)
	(segment
		(start 273.675856 -226.037902)
		(end 273.838924 -226.20097)
		(width 0.14478)
		(layer "In11.Cu")
		(net "M_F_CPU0_SA_DQ<24>")
	)
	(segment
		(start 281.231848 -226.035362)
		(end 281.394916 -226.19843)
		(width 0.14478)
		(layer "In11.Cu")
		(net "M_F_CPU0_SA_DQ<24>")
	)
	(segment
		(start 270.21155 -226.210622)
		(end 271.074642 -226.210622)
		(width 0.14478)
		(layer "In11.Cu")
		(net "M_F_CPU0_SA_DQ<24>")
	)
	(segment
		(start 304.292 -226.035362)
		(end 304.292 -225.65614)
		(width 0.14478)
		(layer "In11.Cu")
		(net "M_F_CPU0_SA_DQ<24>")
	)
	(segment
		(start 299.384466 -224.96018)
		(end 301.051976 -224.96018)
		(width 0.14478)
		(layer "In11.Cu")
		(net "M_F_CPU0_SA_DQ<24>")
	)
	(segment
		(start 276.251924 -225.35515)
		(end 276.482302 -225.35515)
		(width 0.14478)
		(layer "In11.Cu")
		(net "M_F_CPU0_SA_DQ<24>")
	)
	(segment
		(start 279.260808 -225.810064)
		(end 281.06878 -225.810064)
		(width 0.14478)
		(layer "In11.Cu")
		(net "M_F_CPU0_SA_DQ<24>")
	)
	(segment
		(start 281.394916 -226.19843)
		(end 281.625294 -226.19843)
		(width 0.14478)
		(layer "In11.Cu")
		(net "M_F_CPU0_SA_DQ<24>")
	)
	(segment
		(start 307.46446 -225.51136)
		(end 307.809138 -225.856038)
		(width 0.14478)
		(layer "In11.Cu")
		(net "M_F_CPU0_SA_DQ<24>")
	)
	(segment
		(start 271.858486 -226.210622)
		(end 272.494248 -226.210622)
		(width 0.14478)
		(layer "In11.Cu")
		(net "M_F_CPU0_SA_DQ<24>")
	)
	(segment
		(start 304.128932 -226.19843)
		(end 304.292 -226.035362)
		(width 0.14478)
		(layer "In11.Cu")
		(net "M_F_CPU0_SA_DQ<24>")
	)
	(segment
		(start 303.735486 -225.973132)
		(end 303.735486 -226.035362)
		(width 0.14478)
		(layer "In11.Cu")
		(net "M_F_CPU0_SA_DQ<24>")
	)
	(segment
		(start 281.625294 -226.19843)
		(end 281.788362 -226.035362)
		(width 0.14478)
		(layer "In11.Cu")
		(net "M_F_CPU0_SA_DQ<24>")
	)
	(segment
		(start 299.05833 -225.34499)
		(end 299.221398 -225.181922)
		(width 0.14478)
		(layer "In11.Cu")
		(net "M_F_CPU0_SA_DQ<24>")
	)
	(segment
		(start 297.023028 -225.973132)
		(end 297.186096 -225.810064)
		(width 0.14478)
		(layer "In11.Cu")
		(net "M_F_CPU0_SA_DQ<24>")
	)
	(arc
		(start 328.88809 -239.946688)
		(mid 329.171046 -239.870511)
		(end 329.454002 -239.946688)
		(width 0.0889)
		(layer "In11.Cu")
		(net "M_F_CPU0_SA_DQ<24>")
	)
	(arc
		(start 330.402438 -239.951514)
		(mid 330.585946 -239.997008)
		(end 330.768198 -239.946688)
		(width 0.0889)
		(layer "In11.Cu")
		(net "M_F_CPU0_SA_DQ<24>")
	)
	(arc
		(start 330.768198 -239.946688)
		(mid 331.051154 -239.870511)
		(end 331.33411 -239.946688)
		(width 0.0889)
		(layer "In11.Cu")
		(net "M_F_CPU0_SA_DQ<24>")
	)
	(arc
		(start 326.351138 -239.870234)
		(mid 326.498069 -239.889645)
		(end 326.634856 -239.946688)
		(width 0.0889)
		(layer "In11.Cu")
		(net "M_F_CPU0_SA_DQ<24>")
	)
	(arc
		(start 327.009252 -239.946688)
		(mid 327.28493 -239.870558)
		(end 327.562464 -239.939576)
		(width 0.0889)
		(layer "In11.Cu")
		(net "M_F_CPU0_SA_DQ<24>")
	)
	(arc
		(start 326.634856 -239.946688)
		(mid 326.815314 -239.997132)
		(end 326.997568 -239.953546)
		(width 0.0889)
		(layer "In11.Cu")
		(net "M_F_CPU0_SA_DQ<24>")
	)
	(arc
		(start 328.514202 -239.946688)
		(mid 328.701146 -239.996943)
		(end 328.88809 -239.946688)
		(width 0.0889)
		(layer "In11.Cu")
		(net "M_F_CPU0_SA_DQ<24>")
	)
	(arc
		(start 327.590658 -239.955832)
		(mid 327.77064 -239.996932)
		(end 327.94829 -239.946688)
		(width 0.0889)
		(layer "In11.Cu")
		(net "M_F_CPU0_SA_DQ<24>")
	)
	(arc
		(start 329.454002 -239.946688)
		(mid 329.636253 -239.997038)
		(end 329.819762 -239.951514)
		(width 0.0889)
		(layer "In11.Cu")
		(net "M_F_CPU0_SA_DQ<24>")
	)
	(arc
		(start 327.94829 -239.946688)
		(mid 328.231246 -239.870511)
		(end 328.514202 -239.946688)
		(width 0.0889)
		(layer "In11.Cu")
		(net "M_F_CPU0_SA_DQ<24>")
	)
	(arc
		(start 329.828144 -239.946688)
		(mid 330.1111 -239.870511)
		(end 330.394056 -239.946688)
		(width 0.0889)
		(layer "In11.Cu")
		(net "M_F_CPU0_SA_DQ<24>")
	)
	(arc
		(start 331.708252 -239.946688)
		(mid 331.955965 -239.871468)
		(end 332.211172 -239.914938)
		(width 0.0889)
		(layer "In11.Cu")
		(net "M_F_CPU0_SA_DQ<24>")
	)
	(arc
		(start 331.342492 -239.951514)
		(mid 331.526 -239.997008)
		(end 331.708252 -239.946688)
		(width 0.0889)
		(layer "In11.Cu")
		(net "M_F_CPU0_SA_DQ<24>")
	)
	(segment
		(start 333.868014 -239.890046)
		(end 333.401162 -239.624108)
		(width 0.10668)
		(layer "F.Cu")
		(net "M_F_CPU0_SA_DQ<23>")
	)
	(segment
		(start 290.682172 -224.110042)
		(end 293.558722 -224.110042)
		(width 0.14478)
		(layer "In11.Cu")
		(net "M_F_CPU0_SA_DQ<23>")
	)
	(segment
		(start 301.945294 -224.96018)
		(end 307.715666 -224.96018)
		(width 0.14478)
		(layer "In11.Cu")
		(net "M_F_CPU0_SA_DQ<23>")
	)
	(segment
		(start 278.483822 -224.110042)
		(end 279.33396 -224.96018)
		(width 0.14478)
		(layer "In11.Cu")
		(net "M_F_CPU0_SA_DQ<23>")
	)
	(segment
		(start 326.63384 -239.301528)
		(end 326.645524 -239.29467)
		(width 0.0889)
		(layer "In11.Cu")
		(net "M_F_CPU0_SA_DQ<23>")
	)
	(segment
		(start 286.053276 -224.110042)
		(end 286.903414 -224.96018)
		(width 0.14478)
		(layer "In11.Cu")
		(net "M_F_CPU0_SA_DQ<23>")
	)
	(segment
		(start 325.404734 -238.35233)
		(end 325.404734 -238.780574)
		(width 0.0889)
		(layer "In11.Cu")
		(net "M_F_CPU0_SA_DQ<23>")
	)
	(segment
		(start 301.095156 -224.110042)
		(end 301.945294 -224.96018)
		(width 0.14478)
		(layer "In11.Cu")
		(net "M_F_CPU0_SA_DQ<23>")
	)
	(segment
		(start 289.832034 -224.96018)
		(end 290.682172 -224.110042)
		(width 0.14478)
		(layer "In11.Cu")
		(net "M_F_CPU0_SA_DQ<23>")
	)
	(segment
		(start 267.450062 -224.96018)
		(end 267.711936 -224.96018)
		(width 0.14478)
		(layer "In11.Cu")
		(net "M_F_CPU0_SA_DQ<23>")
	)
	(segment
		(start 267.160502 -224.438972)
		(end 267.305282 -224.583752)
		(width 0.14478)
		(layer "In11.Cu")
		(net "M_F_CPU0_SA_DQ<23>")
	)
	(segment
		(start 268.40815 -224.8154)
		(end 268.55293 -224.96018)
		(width 0.14478)
		(layer "In11.Cu")
		(net "M_F_CPU0_SA_DQ<23>")
	)
	(segment
		(start 268.55293 -224.96018)
		(end 274.667726 -224.96018)
		(width 0.14478)
		(layer "In11.Cu")
		(net "M_F_CPU0_SA_DQ<23>")
	)
	(segment
		(start 283.148786 -224.110042)
		(end 286.053276 -224.110042)
		(width 0.14478)
		(layer "In11.Cu")
		(net "M_F_CPU0_SA_DQ<23>")
	)
	(segment
		(start 266.753848 -224.8154)
		(end 266.753848 -224.583752)
		(width 0.14478)
		(layer "In11.Cu")
		(net "M_F_CPU0_SA_DQ<23>")
	)
	(segment
		(start 268.001496 -224.438972)
		(end 268.26337 -224.438972)
		(width 0.14478)
		(layer "In11.Cu")
		(net "M_F_CPU0_SA_DQ<23>")
	)
	(segment
		(start 333.555086 -239.358678)
		(end 333.401162 -239.624108)
		(width 0.0889)
		(layer "In11.Cu")
		(net "M_F_CPU0_SA_DQ<23>")
	)
	(segment
		(start 274.667726 -224.96018)
		(end 275.517864 -224.110042)
		(width 0.14478)
		(layer "In11.Cu")
		(net "M_F_CPU0_SA_DQ<23>")
	)
	(segment
		(start 267.305282 -224.8154)
		(end 267.450062 -224.96018)
		(width 0.14478)
		(layer "In11.Cu")
		(net "M_F_CPU0_SA_DQ<23>")
	)
	(segment
		(start 268.40815 -224.583752)
		(end 268.40815 -224.8154)
		(width 0.14478)
		(layer "In11.Cu")
		(net "M_F_CPU0_SA_DQ<23>")
	)
	(segment
		(start 279.33396 -224.96018)
		(end 282.298648 -224.96018)
		(width 0.14478)
		(layer "In11.Cu")
		(net "M_F_CPU0_SA_DQ<23>")
	)
	(segment
		(start 267.856716 -224.583752)
		(end 268.001496 -224.438972)
		(width 0.14478)
		(layer "In11.Cu")
		(net "M_F_CPU0_SA_DQ<23>")
	)
	(segment
		(start 266.753848 -224.583752)
		(end 266.898628 -224.438972)
		(width 0.14478)
		(layer "In11.Cu")
		(net "M_F_CPU0_SA_DQ<23>")
	)
	(segment
		(start 267.856716 -224.8154)
		(end 267.856716 -224.583752)
		(width 0.14478)
		(layer "In11.Cu")
		(net "M_F_CPU0_SA_DQ<23>")
	)
	(segment
		(start 330.394056 -239.301528)
		(end 330.402438 -239.296702)
		(width 0.0889)
		(layer "In11.Cu")
		(net "M_F_CPU0_SA_DQ<23>")
	)
	(segment
		(start 266.609068 -224.96018)
		(end 266.753848 -224.8154)
		(width 0.14478)
		(layer "In11.Cu")
		(net "M_F_CPU0_SA_DQ<23>")
	)
	(segment
		(start 327.007728 -239.301528)
		(end 327.018142 -239.307624)
		(width 0.0889)
		(layer "In11.Cu")
		(net "M_F_CPU0_SA_DQ<23>")
	)
	(segment
		(start 293.558722 -224.110042)
		(end 294.40886 -224.96018)
		(width 0.14478)
		(layer "In11.Cu")
		(net "M_F_CPU0_SA_DQ<23>")
	)
	(segment
		(start 324.944994 -237.89259)
		(end 325.404734 -238.35233)
		(width 0.0889)
		(layer "In11.Cu")
		(net "M_F_CPU0_SA_DQ<23>")
	)
	(segment
		(start 307.715666 -224.96018)
		(end 308.365398 -225.609912)
		(width 0.14478)
		(layer "In11.Cu")
		(net "M_F_CPU0_SA_DQ<23>")
	)
	(segment
		(start 286.903414 -224.96018)
		(end 289.832034 -224.96018)
		(width 0.14478)
		(layer "In11.Cu")
		(net "M_F_CPU0_SA_DQ<23>")
	)
	(segment
		(start 323.908674 -237.89259)
		(end 324.944994 -237.89259)
		(width 0.0889)
		(layer "In11.Cu")
		(net "M_F_CPU0_SA_DQ<23>")
	)
	(segment
		(start 294.40886 -224.96018)
		(end 297.32986 -224.96018)
		(width 0.14478)
		(layer "In11.Cu")
		(net "M_F_CPU0_SA_DQ<23>")
	)
	(segment
		(start 331.33411 -239.301528)
		(end 331.342492 -239.296702)
		(width 0.0889)
		(layer "In11.Cu")
		(net "M_F_CPU0_SA_DQ<23>")
	)
	(segment
		(start 275.517864 -224.110042)
		(end 278.483822 -224.110042)
		(width 0.14478)
		(layer "In11.Cu")
		(net "M_F_CPU0_SA_DQ<23>")
	)
	(segment
		(start 326.619108 -239.310164)
		(end 326.63384 -239.301528)
		(width 0.0889)
		(layer "In11.Cu")
		(net "M_F_CPU0_SA_DQ<23>")
	)
	(segment
		(start 282.298648 -224.96018)
		(end 283.148786 -224.110042)
		(width 0.14478)
		(layer "In11.Cu")
		(net "M_F_CPU0_SA_DQ<23>")
	)
	(segment
		(start 265.54811 -224.534984)
		(end 265.973306 -224.96018)
		(width 0.14478)
		(layer "In11.Cu")
		(net "M_F_CPU0_SA_DQ<23>")
	)
	(segment
		(start 267.305282 -224.583752)
		(end 267.305282 -224.8154)
		(width 0.14478)
		(layer "In11.Cu")
		(net "M_F_CPU0_SA_DQ<23>")
	)
	(segment
		(start 266.898628 -224.438972)
		(end 267.160502 -224.438972)
		(width 0.14478)
		(layer "In11.Cu")
		(net "M_F_CPU0_SA_DQ<23>")
	)
	(segment
		(start 325.881492 -239.257332)
		(end 325.94423 -239.257332)
		(width 0.0889)
		(layer "In11.Cu")
		(net "M_F_CPU0_SA_DQ<23>")
	)
	(segment
		(start 329.819762 -239.296702)
		(end 329.828144 -239.301528)
		(width 0.0889)
		(layer "In11.Cu")
		(net "M_F_CPU0_SA_DQ<23>")
	)
	(segment
		(start 297.32986 -224.96018)
		(end 298.179998 -224.110042)
		(width 0.14478)
		(layer "In11.Cu")
		(net "M_F_CPU0_SA_DQ<23>")
	)
	(segment
		(start 265.973306 -224.96018)
		(end 266.609068 -224.96018)
		(width 0.14478)
		(layer "In11.Cu")
		(net "M_F_CPU0_SA_DQ<23>")
	)
	(segment
		(start 308.365398 -225.609912)
		(end 308.365398 -226.312222)
		(width 0.14478)
		(layer "In11.Cu")
		(net "M_F_CPU0_SA_DQ<23>")
	)
	(segment
		(start 268.26337 -224.438972)
		(end 268.40815 -224.583752)
		(width 0.14478)
		(layer "In11.Cu")
		(net "M_F_CPU0_SA_DQ<23>")
	)
	(segment
		(start 308.365398 -226.312222)
		(end 319.945766 -237.89259)
		(width 0.14478)
		(layer "In11.Cu")
		(net "M_F_CPU0_SA_DQ<23>")
	)
	(segment
		(start 298.179998 -224.110042)
		(end 301.095156 -224.110042)
		(width 0.14478)
		(layer "In11.Cu")
		(net "M_F_CPU0_SA_DQ<23>")
	)
	(segment
		(start 267.711936 -224.96018)
		(end 267.856716 -224.8154)
		(width 0.14478)
		(layer "In11.Cu")
		(net "M_F_CPU0_SA_DQ<23>")
	)
	(segment
		(start 325.404734 -238.780574)
		(end 325.881492 -239.257332)
		(width 0.0889)
		(layer "In11.Cu")
		(net "M_F_CPU0_SA_DQ<23>")
	)
	(segment
		(start 319.945766 -237.89259)
		(end 323.908674 -237.89259)
		(width 0.14478)
		(layer "In11.Cu")
		(net "M_F_CPU0_SA_DQ<23>")
	)
	(segment
		(start 333.532734 -239.275366)
		(end 333.555086 -239.358678)
		(width 0.0889)
		(layer "In11.Cu")
		(net "M_F_CPU0_SA_DQ<23>")
	)
	(segment
		(start 325.956422 -239.259618)
		(end 326.105774 -239.321594)
		(width 0.0889)
		(layer "In11.Cu")
		(net "M_F_CPU0_SA_DQ<23>")
	)
	(arc
		(start 325.94423 -239.257332)
		(mid 325.950433 -239.257893)
		(end 325.956422 -239.259618)
		(width 0.0889)
		(layer "In11.Cu")
		(net "M_F_CPU0_SA_DQ<23>")
	)
	(arc
		(start 328.514202 -239.301528)
		(mid 328.701146 -239.251273)
		(end 328.88809 -239.301528)
		(width 0.0889)
		(layer "In11.Cu")
		(net "M_F_CPU0_SA_DQ<23>")
	)
	(arc
		(start 327.94829 -239.301528)
		(mid 328.231246 -239.377705)
		(end 328.514202 -239.301528)
		(width 0.0889)
		(layer "In11.Cu")
		(net "M_F_CPU0_SA_DQ<23>")
	)
	(arc
		(start 328.88809 -239.301528)
		(mid 329.171046 -239.377705)
		(end 329.454002 -239.301528)
		(width 0.0889)
		(layer "In11.Cu")
		(net "M_F_CPU0_SA_DQ<23>")
	)
	(arc
		(start 327.018142 -239.307624)
		(mid 327.296828 -239.377844)
		(end 327.573894 -239.301528)
		(width 0.0889)
		(layer "In11.Cu")
		(net "M_F_CPU0_SA_DQ<23>")
	)
	(arc
		(start 330.768198 -239.301528)
		(mid 331.051154 -239.377705)
		(end 331.33411 -239.301528)
		(width 0.0889)
		(layer "In11.Cu")
		(net "M_F_CPU0_SA_DQ<23>")
	)
	(arc
		(start 329.454002 -239.301528)
		(mid 329.636253 -239.251178)
		(end 329.819762 -239.296702)
		(width 0.0889)
		(layer "In11.Cu")
		(net "M_F_CPU0_SA_DQ<23>")
	)
	(arc
		(start 331.708252 -239.301528)
		(mid 331.991208 -239.377705)
		(end 332.274164 -239.301528)
		(width 0.0889)
		(layer "In11.Cu")
		(net "M_F_CPU0_SA_DQ<23>")
	)
	(arc
		(start 330.402438 -239.296702)
		(mid 330.585946 -239.251208)
		(end 330.768198 -239.301528)
		(width 0.0889)
		(layer "In11.Cu")
		(net "M_F_CPU0_SA_DQ<23>")
	)
	(arc
		(start 326.105774 -239.321594)
		(mid 326.363833 -239.37777)
		(end 326.619108 -239.310164)
		(width 0.0889)
		(layer "In11.Cu")
		(net "M_F_CPU0_SA_DQ<23>")
	)
	(arc
		(start 329.828144 -239.301528)
		(mid 330.1111 -239.377705)
		(end 330.394056 -239.301528)
		(width 0.0889)
		(layer "In11.Cu")
		(net "M_F_CPU0_SA_DQ<23>")
	)
	(arc
		(start 332.274164 -239.301528)
		(mid 332.461108 -239.251273)
		(end 332.648052 -239.301528)
		(width 0.0889)
		(layer "In11.Cu")
		(net "M_F_CPU0_SA_DQ<23>")
	)
	(arc
		(start 333.213964 -239.301528)
		(mid 333.370402 -239.252557)
		(end 333.532734 -239.275366)
		(width 0.0889)
		(layer "In11.Cu")
		(net "M_F_CPU0_SA_DQ<23>")
	)
	(arc
		(start 331.342492 -239.296702)
		(mid 331.526 -239.251208)
		(end 331.708252 -239.301528)
		(width 0.0889)
		(layer "In11.Cu")
		(net "M_F_CPU0_SA_DQ<23>")
	)
	(arc
		(start 332.648052 -239.301528)
		(mid 332.931008 -239.377705)
		(end 333.213964 -239.301528)
		(width 0.0889)
		(layer "In11.Cu")
		(net "M_F_CPU0_SA_DQ<23>")
	)
	(arc
		(start 327.573894 -239.301528)
		(mid 327.761092 -239.251146)
		(end 327.94829 -239.301528)
		(width 0.0889)
		(layer "In11.Cu")
		(net "M_F_CPU0_SA_DQ<23>")
	)
	(arc
		(start 326.645524 -239.29467)
		(mid 326.827525 -239.251137)
		(end 327.007728 -239.301528)
		(width 0.0889)
		(layer "In11.Cu")
		(net "M_F_CPU0_SA_DQ<23>")
	)
	(segment
		(start 332.45806 -239.08004)
		(end 331.991208 -238.814102)
		(width 0.10668)
		(layer "F.Cu")
		(net "M_F_CPU0_SA_DQ<22>")
	)
	(segment
		(start 289.832034 -223.260158)
		(end 290.682172 -222.41002)
		(width 0.14478)
		(layer "In11.Cu")
		(net "M_F_CPU0_SA_DQ<22>")
	)
	(segment
		(start 297.32986 -223.260158)
		(end 298.179998 -222.41002)
		(width 0.14478)
		(layer "In11.Cu")
		(net "M_F_CPU0_SA_DQ<22>")
	)
	(segment
		(start 328.409808 -238.486696)
		(end 328.41819 -238.491522)
		(width 0.0889)
		(layer "In11.Cu")
		(net "M_F_CPU0_SA_DQ<22>")
	)
	(segment
		(start 286.053276 -222.41002)
		(end 286.903414 -223.260158)
		(width 0.14478)
		(layer "In11.Cu")
		(net "M_F_CPU0_SA_DQ<22>")
	)
	(segment
		(start 298.179998 -222.41002)
		(end 301.095156 -222.41002)
		(width 0.14478)
		(layer "In11.Cu")
		(net "M_F_CPU0_SA_DQ<22>")
	)
	(segment
		(start 320.308478 -236.98327)
		(end 323.964554 -236.98327)
		(width 0.14478)
		(layer "In11.Cu")
		(net "M_F_CPU0_SA_DQ<22>")
	)
	(segment
		(start 265.54811 -222.834962)
		(end 265.973306 -223.260158)
		(width 0.14478)
		(layer "In11.Cu")
		(net "M_F_CPU0_SA_DQ<22>")
	)
	(segment
		(start 324.986142 -237.28045)
		(end 326.146414 -238.440722)
		(width 0.0889)
		(layer "In11.Cu")
		(net "M_F_CPU0_SA_DQ<22>")
	)
	(segment
		(start 282.298648 -223.260158)
		(end 283.148786 -222.41002)
		(width 0.14478)
		(layer "In11.Cu")
		(net "M_F_CPU0_SA_DQ<22>")
	)
	(segment
		(start 327.465182 -238.483902)
		(end 327.478898 -238.491776)
		(width 0.0889)
		(layer "In11.Cu")
		(net "M_F_CPU0_SA_DQ<22>")
	)
	(segment
		(start 268.028166 -222.470472)
		(end 268.29004 -222.470472)
		(width 0.14478)
		(layer "In11.Cu")
		(net "M_F_CPU0_SA_DQ<22>")
	)
	(segment
		(start 267.331952 -222.615252)
		(end 267.331952 -223.235012)
		(width 0.14478)
		(layer "In11.Cu")
		(net "M_F_CPU0_SA_DQ<22>")
	)
	(segment
		(start 327.478898 -238.491776)
		(end 327.490836 -238.498634)
		(width 0.0889)
		(layer "In11.Cu")
		(net "M_F_CPU0_SA_DQ<22>")
	)
	(segment
		(start 267.476732 -223.379792)
		(end 267.738606 -223.379792)
		(width 0.14478)
		(layer "In11.Cu")
		(net "M_F_CPU0_SA_DQ<22>")
	)
	(segment
		(start 301.095156 -222.41002)
		(end 301.945294 -223.260158)
		(width 0.14478)
		(layer "In11.Cu")
		(net "M_F_CPU0_SA_DQ<22>")
	)
	(segment
		(start 266.780518 -222.615252)
		(end 266.925298 -222.470472)
		(width 0.14478)
		(layer "In11.Cu")
		(net "M_F_CPU0_SA_DQ<22>")
	)
	(segment
		(start 279.33396 -223.260158)
		(end 282.298648 -223.260158)
		(width 0.14478)
		(layer "In11.Cu")
		(net "M_F_CPU0_SA_DQ<22>")
	)
	(segment
		(start 286.903414 -223.260158)
		(end 289.832034 -223.260158)
		(width 0.14478)
		(layer "In11.Cu")
		(net "M_F_CPU0_SA_DQ<22>")
	)
	(segment
		(start 267.883386 -222.615252)
		(end 268.028166 -222.470472)
		(width 0.14478)
		(layer "In11.Cu")
		(net "M_F_CPU0_SA_DQ<22>")
	)
	(segment
		(start 267.187172 -222.470472)
		(end 267.331952 -222.615252)
		(width 0.14478)
		(layer "In11.Cu")
		(net "M_F_CPU0_SA_DQ<22>")
	)
	(segment
		(start 332.145132 -238.548672)
		(end 331.991208 -238.814102)
		(width 0.0889)
		(layer "In11.Cu")
		(net "M_F_CPU0_SA_DQ<22>")
	)
	(segment
		(start 268.29004 -222.470472)
		(end 268.43482 -222.615252)
		(width 0.14478)
		(layer "In11.Cu")
		(net "M_F_CPU0_SA_DQ<22>")
	)
	(segment
		(start 309.274718 -225.180652)
		(end 309.274718 -225.94951)
		(width 0.14478)
		(layer "In11.Cu")
		(net "M_F_CPU0_SA_DQ<22>")
	)
	(segment
		(start 266.925298 -222.470472)
		(end 267.187172 -222.470472)
		(width 0.14478)
		(layer "In11.Cu")
		(net "M_F_CPU0_SA_DQ<22>")
	)
	(segment
		(start 307.354224 -223.260158)
		(end 309.274718 -225.180652)
		(width 0.14478)
		(layer "In11.Cu")
		(net "M_F_CPU0_SA_DQ<22>")
	)
	(segment
		(start 278.483822 -222.41002)
		(end 279.33396 -223.260158)
		(width 0.14478)
		(layer "In11.Cu")
		(net "M_F_CPU0_SA_DQ<22>")
	)
	(segment
		(start 268.5796 -223.260158)
		(end 274.667726 -223.260158)
		(width 0.14478)
		(layer "In11.Cu")
		(net "M_F_CPU0_SA_DQ<22>")
	)
	(segment
		(start 268.43482 -222.615252)
		(end 268.43482 -223.115378)
		(width 0.14478)
		(layer "In11.Cu")
		(net "M_F_CPU0_SA_DQ<22>")
	)
	(segment
		(start 293.558722 -222.41002)
		(end 294.40886 -223.260158)
		(width 0.14478)
		(layer "In11.Cu")
		(net "M_F_CPU0_SA_DQ<22>")
	)
	(segment
		(start 268.43482 -223.115378)
		(end 268.5796 -223.260158)
		(width 0.14478)
		(layer "In11.Cu")
		(net "M_F_CPU0_SA_DQ<22>")
	)
	(segment
		(start 274.667726 -223.260158)
		(end 275.517864 -222.41002)
		(width 0.14478)
		(layer "In11.Cu")
		(net "M_F_CPU0_SA_DQ<22>")
	)
	(segment
		(start 323.964554 -236.98327)
		(end 324.129654 -236.98327)
		(width 0.0889)
		(layer "In11.Cu")
		(net "M_F_CPU0_SA_DQ<22>")
	)
	(segment
		(start 294.40886 -223.260158)
		(end 297.32986 -223.260158)
		(width 0.14478)
		(layer "In11.Cu")
		(net "M_F_CPU0_SA_DQ<22>")
	)
	(segment
		(start 327.08723 -238.50219)
		(end 327.105264 -238.491522)
		(width 0.0889)
		(layer "In11.Cu")
		(net "M_F_CPU0_SA_DQ<22>")
	)
	(segment
		(start 267.738606 -223.379792)
		(end 267.883386 -223.235012)
		(width 0.14478)
		(layer "In11.Cu")
		(net "M_F_CPU0_SA_DQ<22>")
	)
	(segment
		(start 326.146414 -238.440722)
		(end 326.351138 -238.440722)
		(width 0.0889)
		(layer "In11.Cu")
		(net "M_F_CPU0_SA_DQ<22>")
	)
	(segment
		(start 265.973306 -223.260158)
		(end 266.635738 -223.260158)
		(width 0.14478)
		(layer "In11.Cu")
		(net "M_F_CPU0_SA_DQ<22>")
	)
	(segment
		(start 283.148786 -222.41002)
		(end 286.053276 -222.41002)
		(width 0.14478)
		(layer "In11.Cu")
		(net "M_F_CPU0_SA_DQ<22>")
	)
	(segment
		(start 266.635738 -223.260158)
		(end 266.780518 -223.115378)
		(width 0.14478)
		(layer "In11.Cu")
		(net "M_F_CPU0_SA_DQ<22>")
	)
	(segment
		(start 266.780518 -223.115378)
		(end 266.780518 -222.615252)
		(width 0.14478)
		(layer "In11.Cu")
		(net "M_F_CPU0_SA_DQ<22>")
	)
	(segment
		(start 328.984102 -238.491522)
		(end 328.992484 -238.486696)
		(width 0.0889)
		(layer "In11.Cu")
		(net "M_F_CPU0_SA_DQ<22>")
	)
	(segment
		(start 331.229716 -238.486696)
		(end 331.238098 -238.491522)
		(width 0.0889)
		(layer "In11.Cu")
		(net "M_F_CPU0_SA_DQ<22>")
	)
	(segment
		(start 324.426834 -237.28045)
		(end 324.986142 -237.28045)
		(width 0.0889)
		(layer "In11.Cu")
		(net "M_F_CPU0_SA_DQ<22>")
	)
	(segment
		(start 267.331952 -223.235012)
		(end 267.476732 -223.379792)
		(width 0.14478)
		(layer "In11.Cu")
		(net "M_F_CPU0_SA_DQ<22>")
	)
	(segment
		(start 290.682172 -222.41002)
		(end 293.558722 -222.41002)
		(width 0.14478)
		(layer "In11.Cu")
		(net "M_F_CPU0_SA_DQ<22>")
	)
	(segment
		(start 309.274718 -225.94951)
		(end 320.308478 -236.98327)
		(width 0.14478)
		(layer "In11.Cu")
		(net "M_F_CPU0_SA_DQ<22>")
	)
	(segment
		(start 267.883386 -223.235012)
		(end 267.883386 -222.615252)
		(width 0.14478)
		(layer "In11.Cu")
		(net "M_F_CPU0_SA_DQ<22>")
	)
	(segment
		(start 275.517864 -222.41002)
		(end 278.483822 -222.41002)
		(width 0.14478)
		(layer "In11.Cu")
		(net "M_F_CPU0_SA_DQ<22>")
	)
	(segment
		(start 324.129654 -236.98327)
		(end 324.426834 -237.28045)
		(width 0.0889)
		(layer "In11.Cu")
		(net "M_F_CPU0_SA_DQ<22>")
	)
	(segment
		(start 332.12278 -238.46536)
		(end 332.145132 -238.548672)
		(width 0.0889)
		(layer "In11.Cu")
		(net "M_F_CPU0_SA_DQ<22>")
	)
	(segment
		(start 301.945294 -223.260158)
		(end 307.354224 -223.260158)
		(width 0.14478)
		(layer "In11.Cu")
		(net "M_F_CPU0_SA_DQ<22>")
	)
	(arc
		(start 327.105264 -238.491522)
		(mid 327.284251 -238.441352)
		(end 327.465182 -238.483902)
		(width 0.0889)
		(layer "In11.Cu")
		(net "M_F_CPU0_SA_DQ<22>")
	)
	(arc
		(start 328.044048 -238.491522)
		(mid 328.226299 -238.441172)
		(end 328.409808 -238.486696)
		(width 0.0889)
		(layer "In11.Cu")
		(net "M_F_CPU0_SA_DQ<22>")
	)
	(arc
		(start 327.490836 -238.498634)
		(mid 327.76837 -238.567615)
		(end 328.044048 -238.491522)
		(width 0.0889)
		(layer "In11.Cu")
		(net "M_F_CPU0_SA_DQ<22>")
	)
	(arc
		(start 328.992484 -238.486696)
		(mid 329.175992 -238.441202)
		(end 329.358244 -238.491522)
		(width 0.0889)
		(layer "In11.Cu")
		(net "M_F_CPU0_SA_DQ<22>")
	)
	(arc
		(start 331.80401 -238.491522)
		(mid 331.960448 -238.442551)
		(end 332.12278 -238.46536)
		(width 0.0889)
		(layer "In11.Cu")
		(net "M_F_CPU0_SA_DQ<22>")
	)
	(arc
		(start 326.53859 -238.491522)
		(mid 326.811534 -238.568102)
		(end 327.08723 -238.50219)
		(width 0.0889)
		(layer "In11.Cu")
		(net "M_F_CPU0_SA_DQ<22>")
	)
	(arc
		(start 329.924156 -238.491522)
		(mid 330.1111 -238.441267)
		(end 330.298044 -238.491522)
		(width 0.0889)
		(layer "In11.Cu")
		(net "M_F_CPU0_SA_DQ<22>")
	)
	(arc
		(start 326.351138 -238.440722)
		(mid 326.448227 -238.453712)
		(end 326.53859 -238.491522)
		(width 0.0889)
		(layer "In11.Cu")
		(net "M_F_CPU0_SA_DQ<22>")
	)
	(arc
		(start 328.41819 -238.491522)
		(mid 328.701146 -238.567699)
		(end 328.984102 -238.491522)
		(width 0.0889)
		(layer "In11.Cu")
		(net "M_F_CPU0_SA_DQ<22>")
	)
	(arc
		(start 329.358244 -238.491522)
		(mid 329.6412 -238.567699)
		(end 329.924156 -238.491522)
		(width 0.0889)
		(layer "In11.Cu")
		(net "M_F_CPU0_SA_DQ<22>")
	)
	(arc
		(start 331.238098 -238.491522)
		(mid 331.521054 -238.567699)
		(end 331.80401 -238.491522)
		(width 0.0889)
		(layer "In11.Cu")
		(net "M_F_CPU0_SA_DQ<22>")
	)
	(arc
		(start 330.298044 -238.491522)
		(mid 330.581 -238.567699)
		(end 330.863956 -238.491522)
		(width 0.0889)
		(layer "In11.Cu")
		(net "M_F_CPU0_SA_DQ<22>")
	)
	(arc
		(start 330.863956 -238.491522)
		(mid 331.046207 -238.441172)
		(end 331.229716 -238.486696)
		(width 0.0889)
		(layer "In11.Cu")
		(net "M_F_CPU0_SA_DQ<22>")
	)
	(segment
		(start 334.337914 -239.08004)
		(end 333.871062 -238.814102)
		(width 0.10668)
		(layer "F.Cu")
		(net "M_F_CPU0_SA_DQ<21>")
	)
	(segment
		(start 276.100794 -223.423226)
		(end 276.100794 -223.485202)
		(width 0.14478)
		(layer "In11.Cu")
		(net "M_F_CPU0_SA_DQ<21>")
	)
	(segment
		(start 291.177218 -223.423226)
		(end 291.177218 -223.485202)
		(width 0.14478)
		(layer "In11.Cu")
		(net "M_F_CPU0_SA_DQ<21>")
	)
	(segment
		(start 271.599152 -224.192592)
		(end 271.743932 -224.047812)
		(width 0.14478)
		(layer "In11.Cu")
		(net "M_F_CPU0_SA_DQ<21>")
	)
	(segment
		(start 331.229716 -239.141508)
		(end 331.238098 -239.136682)
		(width 0.0889)
		(layer "In11.Cu")
		(net "M_F_CPU0_SA_DQ<21>")
	)
	(segment
		(start 281.344116 -224.50425)
		(end 281.574494 -224.50425)
		(width 0.14478)
		(layer "In11.Cu")
		(net "M_F_CPU0_SA_DQ<21>")
	)
	(segment
		(start 285.892748 -223.260158)
		(end 286.742632 -224.110042)
		(width 0.14478)
		(layer "In11.Cu")
		(net "M_F_CPU0_SA_DQ<21>")
	)
	(segment
		(start 288.775902 -224.27311)
		(end 288.775902 -224.333562)
		(width 0.14478)
		(layer "In11.Cu")
		(net "M_F_CPU0_SA_DQ<21>")
	)
	(segment
		(start 305.056032 -223.948752)
		(end 307.392578 -223.948752)
		(width 0.14478)
		(layer "In11.Cu")
		(net "M_F_CPU0_SA_DQ<21>")
	)
	(segment
		(start 308.814978 -225.371152)
		(end 308.814978 -226.125786)
		(width 0.14478)
		(layer "In11.Cu")
		(net "M_F_CPU0_SA_DQ<21>")
	)
	(segment
		(start 271.192498 -224.047812)
		(end 271.337278 -224.192592)
		(width 0.14478)
		(layer "In11.Cu")
		(net "M_F_CPU0_SA_DQ<21>")
	)
	(segment
		(start 291.177218 -223.485202)
		(end 291.340286 -223.64827)
		(width 0.14478)
		(layer "In11.Cu")
		(net "M_F_CPU0_SA_DQ<21>")
	)
	(segment
		(start 284.290008 -223.260158)
		(end 285.892748 -223.260158)
		(width 0.14478)
		(layer "In11.Cu")
		(net "M_F_CPU0_SA_DQ<21>")
	)
	(segment
		(start 281.737562 -224.341182)
		(end 281.737562 -224.27311)
		(width 0.14478)
		(layer "In11.Cu")
		(net "M_F_CPU0_SA_DQ<21>")
	)
	(segment
		(start 303.169066 -224.110042)
		(end 303.399444 -224.110042)
		(width 0.14478)
		(layer "In11.Cu")
		(net "M_F_CPU0_SA_DQ<21>")
	)
	(segment
		(start 301.051976 -223.260158)
		(end 301.90186 -224.110042)
		(width 0.14478)
		(layer "In11.Cu")
		(net "M_F_CPU0_SA_DQ<21>")
	)
	(segment
		(start 273.89836 -224.50425)
		(end 274.128738 -224.50425)
		(width 0.14478)
		(layer "In11.Cu")
		(net "M_F_CPU0_SA_DQ<21>")
	)
	(segment
		(start 271.743932 -223.880172)
		(end 271.888712 -223.735392)
		(width 0.14478)
		(layer "In11.Cu")
		(net "M_F_CPU0_SA_DQ<21>")
	)
	(segment
		(start 298.585382 -223.260158)
		(end 298.74845 -223.423226)
		(width 0.14478)
		(layer "In11.Cu")
		(net "M_F_CPU0_SA_DQ<21>")
	)
	(segment
		(start 308.814978 -226.125786)
		(end 320.127122 -237.43793)
		(width 0.14478)
		(layer "In11.Cu")
		(net "M_F_CPU0_SA_DQ<21>")
	)
	(segment
		(start 284.12694 -223.485202)
		(end 284.12694 -223.423226)
		(width 0.14478)
		(layer "In11.Cu")
		(net "M_F_CPU0_SA_DQ<21>")
	)
	(segment
		(start 281.737562 -224.27311)
		(end 281.90063 -224.110042)
		(width 0.14478)
		(layer "In11.Cu")
		(net "M_F_CPU0_SA_DQ<21>")
	)
	(segment
		(start 325.684134 -238.65713)
		(end 326.163686 -239.136682)
		(width 0.0889)
		(layer "In11.Cu")
		(net "M_F_CPU0_SA_DQ<21>")
	)
	(segment
		(start 302.449484 -224.27311)
		(end 302.449484 -224.341182)
		(width 0.14478)
		(layer "In11.Cu")
		(net "M_F_CPU0_SA_DQ<21>")
	)
	(segment
		(start 291.8968 -223.260158)
		(end 293.507922 -223.260158)
		(width 0.14478)
		(layer "In11.Cu")
		(net "M_F_CPU0_SA_DQ<21>")
	)
	(segment
		(start 279.260808 -224.110042)
		(end 281.01798 -224.110042)
		(width 0.14478)
		(layer "In11.Cu")
		(net "M_F_CPU0_SA_DQ<21>")
	)
	(segment
		(start 297.054778 -224.110042)
		(end 297.389042 -224.110042)
		(width 0.14478)
		(layer "In11.Cu")
		(net "M_F_CPU0_SA_DQ<21>")
	)
	(segment
		(start 296.89171 -224.27311)
		(end 297.054778 -224.110042)
		(width 0.14478)
		(layer "In11.Cu")
		(net "M_F_CPU0_SA_DQ<21>")
	)
	(segment
		(start 323.885814 -237.43793)
		(end 324.094094 -237.43793)
		(width 0.0889)
		(layer "In11.Cu")
		(net "M_F_CPU0_SA_DQ<21>")
	)
	(segment
		(start 276.49424 -223.64827)
		(end 276.657308 -223.485202)
		(width 0.14478)
		(layer "In11.Cu")
		(net "M_F_CPU0_SA_DQ<21>")
	)
	(segment
		(start 288.612834 -224.110042)
		(end 288.775902 -224.27311)
		(width 0.14478)
		(layer "In11.Cu")
		(net "M_F_CPU0_SA_DQ<21>")
	)
	(segment
		(start 296.89171 -224.341182)
		(end 296.89171 -224.27311)
		(width 0.14478)
		(layer "In11.Cu")
		(net "M_F_CPU0_SA_DQ<21>")
	)
	(segment
		(start 269.648178 -223.6851)
		(end 270.07312 -224.110042)
		(width 0.14478)
		(layer "In11.Cu")
		(net "M_F_CPU0_SA_DQ<21>")
	)
	(segment
		(start 271.192498 -223.880172)
		(end 271.192498 -224.047812)
		(width 0.14478)
		(layer "In11.Cu")
		(net "M_F_CPU0_SA_DQ<21>")
	)
	(segment
		(start 270.641064 -223.965262)
		(end 270.641064 -223.880172)
		(width 0.14478)
		(layer "In11.Cu")
		(net "M_F_CPU0_SA_DQ<21>")
	)
	(segment
		(start 294.357806 -224.110042)
		(end 296.172128 -224.110042)
		(width 0.14478)
		(layer "In11.Cu")
		(net "M_F_CPU0_SA_DQ<21>")
	)
	(segment
		(start 283.17317 -223.260158)
		(end 283.407358 -223.260158)
		(width 0.14478)
		(layer "In11.Cu")
		(net "M_F_CPU0_SA_DQ<21>")
	)
	(segment
		(start 275.604732 -223.260158)
		(end 275.937726 -223.260158)
		(width 0.14478)
		(layer "In11.Cu")
		(net "M_F_CPU0_SA_DQ<21>")
	)
	(segment
		(start 304.119026 -224.27311)
		(end 304.282094 -224.110042)
		(width 0.14478)
		(layer "In11.Cu")
		(net "M_F_CPU0_SA_DQ<21>")
	)
	(segment
		(start 293.507922 -223.260158)
		(end 294.357806 -224.110042)
		(width 0.14478)
		(layer "In11.Cu")
		(net "M_F_CPU0_SA_DQ<21>")
	)
	(segment
		(start 303.399444 -224.110042)
		(end 303.562512 -224.27311)
		(width 0.14478)
		(layer "In11.Cu")
		(net "M_F_CPU0_SA_DQ<21>")
	)
	(segment
		(start 326.537828 -239.136682)
		(end 326.548242 -239.130586)
		(width 0.0889)
		(layer "In11.Cu")
		(net "M_F_CPU0_SA_DQ<21>")
	)
	(segment
		(start 303.72558 -224.50425)
		(end 303.955958 -224.50425)
		(width 0.14478)
		(layer "In11.Cu")
		(net "M_F_CPU0_SA_DQ<21>")
	)
	(segment
		(start 274.454874 -224.110042)
		(end 274.754848 -224.110042)
		(width 0.14478)
		(layer "In11.Cu")
		(net "M_F_CPU0_SA_DQ<21>")
	)
	(segment
		(start 302.84293 -224.50425)
		(end 303.005998 -224.341182)
		(width 0.14478)
		(layer "In11.Cu")
		(net "M_F_CPU0_SA_DQ<21>")
	)
	(segment
		(start 270.785844 -223.735392)
		(end 271.047718 -223.735392)
		(width 0.14478)
		(layer "In11.Cu")
		(net "M_F_CPU0_SA_DQ<21>")
	)
	(segment
		(start 303.562512 -224.27311)
		(end 303.562512 -224.341182)
		(width 0.14478)
		(layer "In11.Cu")
		(net "M_F_CPU0_SA_DQ<21>")
	)
	(segment
		(start 296.335196 -224.341182)
		(end 296.498264 -224.50425)
		(width 0.14478)
		(layer "In11.Cu")
		(net "M_F_CPU0_SA_DQ<21>")
	)
	(segment
		(start 282.323286 -224.110042)
		(end 283.17317 -223.260158)
		(width 0.14478)
		(layer "In11.Cu")
		(net "M_F_CPU0_SA_DQ<21>")
	)
	(segment
		(start 291.733732 -223.485202)
		(end 291.733732 -223.423226)
		(width 0.14478)
		(layer "In11.Cu")
		(net "M_F_CPU0_SA_DQ<21>")
	)
	(segment
		(start 289.332416 -224.333562)
		(end 289.332416 -224.27311)
		(width 0.14478)
		(layer "In11.Cu")
		(net "M_F_CPU0_SA_DQ<21>")
	)
	(segment
		(start 274.291806 -224.27311)
		(end 274.454874 -224.110042)
		(width 0.14478)
		(layer "In11.Cu")
		(net "M_F_CPU0_SA_DQ<21>")
	)
	(segment
		(start 275.937726 -223.260158)
		(end 276.100794 -223.423226)
		(width 0.14478)
		(layer "In11.Cu")
		(net "M_F_CPU0_SA_DQ<21>")
	)
	(segment
		(start 284.12694 -223.423226)
		(end 284.290008 -223.260158)
		(width 0.14478)
		(layer "In11.Cu")
		(net "M_F_CPU0_SA_DQ<21>")
	)
	(segment
		(start 328.033634 -239.130586)
		(end 328.044048 -239.136682)
		(width 0.0889)
		(layer "In11.Cu")
		(net "M_F_CPU0_SA_DQ<21>")
	)
	(segment
		(start 283.407358 -223.260158)
		(end 283.570426 -223.423226)
		(width 0.14478)
		(layer "In11.Cu")
		(net "M_F_CPU0_SA_DQ<21>")
	)
	(segment
		(start 273.735292 -224.341182)
		(end 273.89836 -224.50425)
		(width 0.14478)
		(layer "In11.Cu")
		(net "M_F_CPU0_SA_DQ<21>")
	)
	(segment
		(start 299.304964 -223.480122)
		(end 299.304964 -223.423226)
		(width 0.14478)
		(layer "In11.Cu")
		(net "M_F_CPU0_SA_DQ<21>")
	)
	(segment
		(start 290.732972 -223.260158)
		(end 291.01415 -223.260158)
		(width 0.14478)
		(layer "In11.Cu")
		(net "M_F_CPU0_SA_DQ<21>")
	)
	(segment
		(start 333.717138 -239.079532)
		(end 333.871062 -238.814102)
		(width 0.0889)
		(layer "In11.Cu")
		(net "M_F_CPU0_SA_DQ<21>")
	)
	(segment
		(start 291.01415 -223.260158)
		(end 291.177218 -223.423226)
		(width 0.14478)
		(layer "In11.Cu")
		(net "M_F_CPU0_SA_DQ<21>")
	)
	(segment
		(start 274.754848 -224.110042)
		(end 275.604732 -223.260158)
		(width 0.14478)
		(layer "In11.Cu")
		(net "M_F_CPU0_SA_DQ<21>")
	)
	(segment
		(start 299.468032 -223.260158)
		(end 301.051976 -223.260158)
		(width 0.14478)
		(layer "In11.Cu")
		(net "M_F_CPU0_SA_DQ<21>")
	)
	(segment
		(start 276.100794 -223.485202)
		(end 276.263862 -223.64827)
		(width 0.14478)
		(layer "In11.Cu")
		(net "M_F_CPU0_SA_DQ<21>")
	)
	(segment
		(start 273.572224 -224.110042)
		(end 273.735292 -224.27311)
		(width 0.14478)
		(layer "In11.Cu")
		(net "M_F_CPU0_SA_DQ<21>")
	)
	(segment
		(start 291.733732 -223.423226)
		(end 291.8968 -223.260158)
		(width 0.14478)
		(layer "In11.Cu")
		(net "M_F_CPU0_SA_DQ<21>")
	)
	(segment
		(start 296.335196 -224.27311)
		(end 296.335196 -224.341182)
		(width 0.14478)
		(layer "In11.Cu")
		(net "M_F_CPU0_SA_DQ<21>")
	)
	(segment
		(start 283.733494 -223.64827)
		(end 283.963872 -223.64827)
		(width 0.14478)
		(layer "In11.Cu")
		(net "M_F_CPU0_SA_DQ<21>")
	)
	(segment
		(start 326.52335 -239.145064)
		(end 326.537828 -239.136682)
		(width 0.0889)
		(layer "In11.Cu")
		(net "M_F_CPU0_SA_DQ<21>")
	)
	(segment
		(start 289.169348 -224.49663)
		(end 289.332416 -224.333562)
		(width 0.14478)
		(layer "In11.Cu")
		(net "M_F_CPU0_SA_DQ<21>")
	)
	(segment
		(start 286.742632 -224.110042)
		(end 288.612834 -224.110042)
		(width 0.14478)
		(layer "In11.Cu")
		(net "M_F_CPU0_SA_DQ<21>")
	)
	(segment
		(start 283.963872 -223.64827)
		(end 284.12694 -223.485202)
		(width 0.14478)
		(layer "In11.Cu")
		(net "M_F_CPU0_SA_DQ<21>")
	)
	(segment
		(start 271.743932 -224.047812)
		(end 271.743932 -223.880172)
		(width 0.14478)
		(layer "In11.Cu")
		(net "M_F_CPU0_SA_DQ<21>")
	)
	(segment
		(start 271.337278 -224.192592)
		(end 271.599152 -224.192592)
		(width 0.14478)
		(layer "In11.Cu")
		(net "M_F_CPU0_SA_DQ<21>")
	)
	(segment
		(start 304.282094 -224.110042)
		(end 304.894742 -224.110042)
		(width 0.14478)
		(layer "In11.Cu")
		(net "M_F_CPU0_SA_DQ<21>")
	)
	(segment
		(start 291.340286 -223.64827)
		(end 291.570664 -223.64827)
		(width 0.14478)
		(layer "In11.Cu")
		(net "M_F_CPU0_SA_DQ<21>")
	)
	(segment
		(start 272.295366 -223.880172)
		(end 272.295366 -223.965262)
		(width 0.14478)
		(layer "In11.Cu")
		(net "M_F_CPU0_SA_DQ<21>")
	)
	(segment
		(start 302.449484 -224.341182)
		(end 302.612552 -224.50425)
		(width 0.14478)
		(layer "In11.Cu")
		(net "M_F_CPU0_SA_DQ<21>")
	)
	(segment
		(start 302.286416 -224.110042)
		(end 302.449484 -224.27311)
		(width 0.14478)
		(layer "In11.Cu")
		(net "M_F_CPU0_SA_DQ<21>")
	)
	(segment
		(start 296.498264 -224.50425)
		(end 296.728642 -224.50425)
		(width 0.14478)
		(layer "In11.Cu")
		(net "M_F_CPU0_SA_DQ<21>")
	)
	(segment
		(start 307.392578 -223.948752)
		(end 308.814978 -225.371152)
		(width 0.14478)
		(layer "In11.Cu")
		(net "M_F_CPU0_SA_DQ<21>")
	)
	(segment
		(start 288.93897 -224.49663)
		(end 289.169348 -224.49663)
		(width 0.14478)
		(layer "In11.Cu")
		(net "M_F_CPU0_SA_DQ<21>")
	)
	(segment
		(start 324.259194 -237.60303)
		(end 324.978014 -237.60303)
		(width 0.0889)
		(layer "In11.Cu")
		(net "M_F_CPU0_SA_DQ<21>")
	)
	(segment
		(start 304.119026 -224.341182)
		(end 304.119026 -224.27311)
		(width 0.14478)
		(layer "In11.Cu")
		(net "M_F_CPU0_SA_DQ<21>")
	)
	(segment
		(start 288.775902 -224.333562)
		(end 288.93897 -224.49663)
		(width 0.14478)
		(layer "In11.Cu")
		(net "M_F_CPU0_SA_DQ<21>")
	)
	(segment
		(start 328.409808 -239.141508)
		(end 328.41819 -239.136682)
		(width 0.0889)
		(layer "In11.Cu")
		(net "M_F_CPU0_SA_DQ<21>")
	)
	(segment
		(start 281.181048 -224.341182)
		(end 281.344116 -224.50425)
		(width 0.14478)
		(layer "In11.Cu")
		(net "M_F_CPU0_SA_DQ<21>")
	)
	(segment
		(start 298.74845 -223.423226)
		(end 298.74845 -223.480122)
		(width 0.14478)
		(layer "In11.Cu")
		(net "M_F_CPU0_SA_DQ<21>")
	)
	(segment
		(start 298.74845 -223.480122)
		(end 298.911518 -223.64319)
		(width 0.14478)
		(layer "In11.Cu")
		(net "M_F_CPU0_SA_DQ<21>")
	)
	(segment
		(start 296.172128 -224.110042)
		(end 296.335196 -224.27311)
		(width 0.14478)
		(layer "In11.Cu")
		(net "M_F_CPU0_SA_DQ<21>")
	)
	(segment
		(start 303.005998 -224.27311)
		(end 303.169066 -224.110042)
		(width 0.14478)
		(layer "In11.Cu")
		(net "M_F_CPU0_SA_DQ<21>")
	)
	(segment
		(start 291.570664 -223.64827)
		(end 291.733732 -223.485202)
		(width 0.14478)
		(layer "In11.Cu")
		(net "M_F_CPU0_SA_DQ<21>")
	)
	(segment
		(start 283.570426 -223.485202)
		(end 283.733494 -223.64827)
		(width 0.14478)
		(layer "In11.Cu")
		(net "M_F_CPU0_SA_DQ<21>")
	)
	(segment
		(start 272.295366 -223.965262)
		(end 272.440146 -224.110042)
		(width 0.14478)
		(layer "In11.Cu")
		(net "M_F_CPU0_SA_DQ<21>")
	)
	(segment
		(start 332.16977 -239.141508)
		(end 332.178152 -239.136682)
		(width 0.0889)
		(layer "In11.Cu")
		(net "M_F_CPU0_SA_DQ<21>")
	)
	(segment
		(start 281.01798 -224.110042)
		(end 281.181048 -224.27311)
		(width 0.14478)
		(layer "In11.Cu")
		(net "M_F_CPU0_SA_DQ<21>")
	)
	(segment
		(start 274.128738 -224.50425)
		(end 274.291806 -224.341182)
		(width 0.14478)
		(layer "In11.Cu")
		(net "M_F_CPU0_SA_DQ<21>")
	)
	(segment
		(start 328.984102 -239.136682)
		(end 328.992484 -239.141508)
		(width 0.0889)
		(layer "In11.Cu")
		(net "M_F_CPU0_SA_DQ<21>")
	)
	(segment
		(start 289.332416 -224.27311)
		(end 289.495484 -224.110042)
		(width 0.14478)
		(layer "In11.Cu")
		(net "M_F_CPU0_SA_DQ<21>")
	)
	(segment
		(start 324.094094 -237.43793)
		(end 324.259194 -237.60303)
		(width 0.0889)
		(layer "In11.Cu")
		(net "M_F_CPU0_SA_DQ<21>")
	)
	(segment
		(start 270.641064 -223.880172)
		(end 270.785844 -223.735392)
		(width 0.14478)
		(layer "In11.Cu")
		(net "M_F_CPU0_SA_DQ<21>")
	)
	(segment
		(start 270.496284 -224.110042)
		(end 270.641064 -223.965262)
		(width 0.14478)
		(layer "In11.Cu")
		(net "M_F_CPU0_SA_DQ<21>")
	)
	(segment
		(start 278.410924 -223.260158)
		(end 279.260808 -224.110042)
		(width 0.14478)
		(layer "In11.Cu")
		(net "M_F_CPU0_SA_DQ<21>")
	)
	(segment
		(start 271.888712 -223.735392)
		(end 272.150586 -223.735392)
		(width 0.14478)
		(layer "In11.Cu")
		(net "M_F_CPU0_SA_DQ<21>")
	)
	(segment
		(start 301.90186 -224.110042)
		(end 302.286416 -224.110042)
		(width 0.14478)
		(layer "In11.Cu")
		(net "M_F_CPU0_SA_DQ<21>")
	)
	(segment
		(start 304.894742 -224.110042)
		(end 305.056032 -223.948752)
		(width 0.14478)
		(layer "In11.Cu")
		(net "M_F_CPU0_SA_DQ<21>")
	)
	(segment
		(start 276.657308 -223.485202)
		(end 276.657308 -223.423226)
		(width 0.14478)
		(layer "In11.Cu")
		(net "M_F_CPU0_SA_DQ<21>")
	)
	(segment
		(start 289.883088 -224.110042)
		(end 290.732972 -223.260158)
		(width 0.14478)
		(layer "In11.Cu")
		(net "M_F_CPU0_SA_DQ<21>")
	)
	(segment
		(start 276.820376 -223.260158)
		(end 278.410924 -223.260158)
		(width 0.14478)
		(layer "In11.Cu")
		(net "M_F_CPU0_SA_DQ<21>")
	)
	(segment
		(start 303.005998 -224.341182)
		(end 303.005998 -224.27311)
		(width 0.14478)
		(layer "In11.Cu")
		(net "M_F_CPU0_SA_DQ<21>")
	)
	(segment
		(start 281.181048 -224.27311)
		(end 281.181048 -224.341182)
		(width 0.14478)
		(layer "In11.Cu")
		(net "M_F_CPU0_SA_DQ<21>")
	)
	(segment
		(start 302.612552 -224.50425)
		(end 302.84293 -224.50425)
		(width 0.14478)
		(layer "In11.Cu")
		(net "M_F_CPU0_SA_DQ<21>")
	)
	(segment
		(start 289.495484 -224.110042)
		(end 289.883088 -224.110042)
		(width 0.14478)
		(layer "In11.Cu")
		(net "M_F_CPU0_SA_DQ<21>")
	)
	(segment
		(start 270.07312 -224.110042)
		(end 270.496284 -224.110042)
		(width 0.14478)
		(layer "In11.Cu")
		(net "M_F_CPU0_SA_DQ<21>")
	)
	(segment
		(start 320.127122 -237.43793)
		(end 323.885814 -237.43793)
		(width 0.14478)
		(layer "In11.Cu")
		(net "M_F_CPU0_SA_DQ<21>")
	)
	(segment
		(start 272.150586 -223.735392)
		(end 272.295366 -223.880172)
		(width 0.14478)
		(layer "In11.Cu")
		(net "M_F_CPU0_SA_DQ<21>")
	)
	(segment
		(start 281.90063 -224.110042)
		(end 282.323286 -224.110042)
		(width 0.14478)
		(layer "In11.Cu")
		(net "M_F_CPU0_SA_DQ<21>")
	)
	(segment
		(start 298.911518 -223.64319)
		(end 299.141896 -223.64319)
		(width 0.14478)
		(layer "In11.Cu")
		(net "M_F_CPU0_SA_DQ<21>")
	)
	(segment
		(start 283.570426 -223.423226)
		(end 283.570426 -223.485202)
		(width 0.14478)
		(layer "In11.Cu")
		(net "M_F_CPU0_SA_DQ<21>")
	)
	(segment
		(start 296.728642 -224.50425)
		(end 296.89171 -224.341182)
		(width 0.14478)
		(layer "In11.Cu")
		(net "M_F_CPU0_SA_DQ<21>")
	)
	(segment
		(start 273.735292 -224.27311)
		(end 273.735292 -224.341182)
		(width 0.14478)
		(layer "In11.Cu")
		(net "M_F_CPU0_SA_DQ<21>")
	)
	(segment
		(start 333.621126 -239.104932)
		(end 333.717138 -239.079532)
		(width 0.0889)
		(layer "In11.Cu")
		(net "M_F_CPU0_SA_DQ<21>")
	)
	(segment
		(start 303.955958 -224.50425)
		(end 304.119026 -224.341182)
		(width 0.14478)
		(layer "In11.Cu")
		(net "M_F_CPU0_SA_DQ<21>")
	)
	(segment
		(start 276.263862 -223.64827)
		(end 276.49424 -223.64827)
		(width 0.14478)
		(layer "In11.Cu")
		(net "M_F_CPU0_SA_DQ<21>")
	)
	(segment
		(start 332.744064 -239.136682)
		(end 332.752446 -239.141508)
		(width 0.0889)
		(layer "In11.Cu")
		(net "M_F_CPU0_SA_DQ<21>")
	)
	(segment
		(start 325.684134 -238.30915)
		(end 325.684134 -238.65713)
		(width 0.0889)
		(layer "In11.Cu")
		(net "M_F_CPU0_SA_DQ<21>")
	)
	(segment
		(start 297.389042 -224.110042)
		(end 298.238926 -223.260158)
		(width 0.14478)
		(layer "In11.Cu")
		(net "M_F_CPU0_SA_DQ<21>")
	)
	(segment
		(start 271.047718 -223.735392)
		(end 271.192498 -223.880172)
		(width 0.14478)
		(layer "In11.Cu")
		(net "M_F_CPU0_SA_DQ<21>")
	)
	(segment
		(start 281.574494 -224.50425)
		(end 281.737562 -224.341182)
		(width 0.14478)
		(layer "In11.Cu")
		(net "M_F_CPU0_SA_DQ<21>")
	)
	(segment
		(start 272.440146 -224.110042)
		(end 273.572224 -224.110042)
		(width 0.14478)
		(layer "In11.Cu")
		(net "M_F_CPU0_SA_DQ<21>")
	)
	(segment
		(start 303.562512 -224.341182)
		(end 303.72558 -224.50425)
		(width 0.14478)
		(layer "In11.Cu")
		(net "M_F_CPU0_SA_DQ<21>")
	)
	(segment
		(start 299.304964 -223.423226)
		(end 299.468032 -223.260158)
		(width 0.14478)
		(layer "In11.Cu")
		(net "M_F_CPU0_SA_DQ<21>")
	)
	(segment
		(start 298.238926 -223.260158)
		(end 298.585382 -223.260158)
		(width 0.14478)
		(layer "In11.Cu")
		(net "M_F_CPU0_SA_DQ<21>")
	)
	(segment
		(start 324.978014 -237.60303)
		(end 325.684134 -238.30915)
		(width 0.0889)
		(layer "In11.Cu")
		(net "M_F_CPU0_SA_DQ<21>")
	)
	(segment
		(start 299.141896 -223.64319)
		(end 299.304964 -223.480122)
		(width 0.14478)
		(layer "In11.Cu")
		(net "M_F_CPU0_SA_DQ<21>")
	)
	(segment
		(start 276.657308 -223.423226)
		(end 276.820376 -223.260158)
		(width 0.14478)
		(layer "In11.Cu")
		(net "M_F_CPU0_SA_DQ<21>")
	)
	(segment
		(start 274.291806 -224.341182)
		(end 274.291806 -224.27311)
		(width 0.14478)
		(layer "In11.Cu")
		(net "M_F_CPU0_SA_DQ<21>")
	)
	(arc
		(start 331.80401 -239.136682)
		(mid 331.986261 -239.187032)
		(end 332.16977 -239.141508)
		(width 0.0889)
		(layer "In11.Cu")
		(net "M_F_CPU0_SA_DQ<21>")
	)
	(arc
		(start 330.298044 -239.136682)
		(mid 330.581 -239.060505)
		(end 330.863956 -239.136682)
		(width 0.0889)
		(layer "In11.Cu")
		(net "M_F_CPU0_SA_DQ<21>")
	)
	(arc
		(start 333.118206 -239.136682)
		(mid 333.365919 -239.061462)
		(end 333.621126 -239.104932)
		(width 0.0889)
		(layer "In11.Cu")
		(net "M_F_CPU0_SA_DQ<21>")
	)
	(arc
		(start 330.863956 -239.136682)
		(mid 331.046207 -239.187032)
		(end 331.229716 -239.141508)
		(width 0.0889)
		(layer "In11.Cu")
		(net "M_F_CPU0_SA_DQ<21>")
	)
	(arc
		(start 329.358244 -239.136682)
		(mid 329.6412 -239.060505)
		(end 329.924156 -239.136682)
		(width 0.0889)
		(layer "In11.Cu")
		(net "M_F_CPU0_SA_DQ<21>")
	)
	(arc
		(start 331.238098 -239.136682)
		(mid 331.521054 -239.060505)
		(end 331.80401 -239.136682)
		(width 0.0889)
		(layer "In11.Cu")
		(net "M_F_CPU0_SA_DQ<21>")
	)
	(arc
		(start 332.752446 -239.141508)
		(mid 332.935954 -239.187002)
		(end 333.118206 -239.136682)
		(width 0.0889)
		(layer "In11.Cu")
		(net "M_F_CPU0_SA_DQ<21>")
	)
	(arc
		(start 327.477882 -239.136682)
		(mid 327.754949 -239.060411)
		(end 328.033634 -239.130586)
		(width 0.0889)
		(layer "In11.Cu")
		(net "M_F_CPU0_SA_DQ<21>")
	)
	(arc
		(start 329.924156 -239.136682)
		(mid 330.1111 -239.186937)
		(end 330.298044 -239.136682)
		(width 0.0889)
		(layer "In11.Cu")
		(net "M_F_CPU0_SA_DQ<21>")
	)
	(arc
		(start 328.992484 -239.141508)
		(mid 329.175992 -239.187002)
		(end 329.358244 -239.136682)
		(width 0.0889)
		(layer "In11.Cu")
		(net "M_F_CPU0_SA_DQ<21>")
	)
	(arc
		(start 332.178152 -239.136682)
		(mid 332.461108 -239.060505)
		(end 332.744064 -239.136682)
		(width 0.0889)
		(layer "In11.Cu")
		(net "M_F_CPU0_SA_DQ<21>")
	)
	(arc
		(start 328.41819 -239.136682)
		(mid 328.701146 -239.060505)
		(end 328.984102 -239.136682)
		(width 0.0889)
		(layer "In11.Cu")
		(net "M_F_CPU0_SA_DQ<21>")
	)
	(arc
		(start 326.548242 -239.130586)
		(mid 326.826674 -239.060488)
		(end 327.103486 -239.136682)
		(width 0.0889)
		(layer "In11.Cu")
		(net "M_F_CPU0_SA_DQ<21>")
	)
	(arc
		(start 326.163686 -239.136682)
		(mid 326.342441 -239.187091)
		(end 326.52335 -239.145064)
		(width 0.0889)
		(layer "In11.Cu")
		(net "M_F_CPU0_SA_DQ<21>")
	)
	(arc
		(start 327.103486 -239.136682)
		(mid 327.290684 -239.187064)
		(end 327.477882 -239.136682)
		(width 0.0889)
		(layer "In11.Cu")
		(net "M_F_CPU0_SA_DQ<21>")
	)
	(arc
		(start 328.044048 -239.136682)
		(mid 328.226299 -239.187032)
		(end 328.409808 -239.141508)
		(width 0.0889)
		(layer "In11.Cu")
		(net "M_F_CPU0_SA_DQ<21>")
	)
	(segment
		(start 332.92796 -238.270034)
		(end 332.461108 -238.004096)
		(width 0.10668)
		(layer "F.Cu")
		(net "M_F_CPU0_SA_DQ<20>")
	)
	(segment
		(start 296.829988 -222.80245)
		(end 296.993056 -222.639382)
		(width 0.14478)
		(layer "In11.Cu")
		(net "M_F_CPU0_SA_DQ<20>")
	)
	(segment
		(start 281.290268 -222.419672)
		(end 281.443684 -222.573088)
		(width 0.14478)
		(layer "In11.Cu")
		(net "M_F_CPU0_SA_DQ<20>")
	)
	(segment
		(start 285.9024 -221.569788)
		(end 286.752284 -222.419672)
		(width 0.14478)
		(layer "In11.Cu")
		(net "M_F_CPU0_SA_DQ<20>")
	)
	(segment
		(start 291.692076 -221.723204)
		(end 291.845492 -221.569788)
		(width 0.14478)
		(layer "In11.Cu")
		(net "M_F_CPU0_SA_DQ<20>")
	)
	(segment
		(start 276.02307 -221.791022)
		(end 276.186138 -221.95409)
		(width 0.14478)
		(layer "In11.Cu")
		(net "M_F_CPU0_SA_DQ<20>")
	)
	(segment
		(start 270.925544 -221.642432)
		(end 271.070324 -221.787212)
		(width 0.14478)
		(layer "In11.Cu")
		(net "M_F_CPU0_SA_DQ<20>")
	)
	(segment
		(start 288.831528 -222.419672)
		(end 288.984944 -222.573088)
		(width 0.14478)
		(layer "In11.Cu")
		(net "M_F_CPU0_SA_DQ<20>")
	)
	(segment
		(start 270.11249 -222.682054)
		(end 270.37411 -222.682054)
		(width 0.14478)
		(layer "In11.Cu")
		(net "M_F_CPU0_SA_DQ<20>")
	)
	(segment
		(start 324.988936 -237.01375)
		(end 326.225408 -238.250222)
		(width 0.0889)
		(layer "In11.Cu")
		(net "M_F_CPU0_SA_DQ<20>")
	)
	(segment
		(start 284.115002 -221.791022)
		(end 284.115002 -221.723204)
		(width 0.14478)
		(layer "In11.Cu")
		(net "M_F_CPU0_SA_DQ<20>")
	)
	(segment
		(start 303.405286 -222.14459)
		(end 303.568354 -222.307658)
		(width 0.14478)
		(layer "In11.Cu")
		(net "M_F_CPU0_SA_DQ<20>")
	)
	(segment
		(start 306.374546 -222.80245)
		(end 306.766976 -222.41002)
		(width 0.14478)
		(layer "In11.Cu")
		(net "M_F_CPU0_SA_DQ<20>")
	)
	(segment
		(start 271.911318 -222.564452)
		(end 272.056098 -222.419672)
		(width 0.14478)
		(layer "In11.Cu")
		(net "M_F_CPU0_SA_DQ<20>")
	)
	(segment
		(start 327.562464 -238.319564)
		(end 327.574402 -238.326422)
		(width 0.0889)
		(layer "In11.Cu")
		(net "M_F_CPU0_SA_DQ<20>")
	)
	(segment
		(start 301.90186 -222.41002)
		(end 302.292258 -222.41002)
		(width 0.14478)
		(layer "In11.Cu")
		(net "M_F_CPU0_SA_DQ<20>")
	)
	(segment
		(start 307.531008 -222.41002)
		(end 309.726838 -224.60585)
		(width 0.14478)
		(layer "In11.Cu")
		(net "M_F_CPU0_SA_DQ<20>")
	)
	(segment
		(start 289.541458 -222.639382)
		(end 289.541458 -222.573088)
		(width 0.14478)
		(layer "In11.Cu")
		(net "M_F_CPU0_SA_DQ<20>")
	)
	(segment
		(start 291.845492 -221.569788)
		(end 293.517574 -221.569788)
		(width 0.14478)
		(layer "In11.Cu")
		(net "M_F_CPU0_SA_DQ<20>")
	)
	(segment
		(start 309.726838 -224.60585)
		(end 309.726838 -225.765614)
		(width 0.14478)
		(layer "In11.Cu")
		(net "M_F_CPU0_SA_DQ<20>")
	)
	(segment
		(start 332.307184 -238.269526)
		(end 332.461108 -238.004096)
		(width 0.0889)
		(layer "In11.Cu")
		(net "M_F_CPU0_SA_DQ<20>")
	)
	(segment
		(start 303.568354 -222.307658)
		(end 303.568354 -222.639382)
		(width 0.14478)
		(layer "In11.Cu")
		(net "M_F_CPU0_SA_DQ<20>")
	)
	(segment
		(start 282.323286 -222.41002)
		(end 283.17317 -221.560136)
		(width 0.14478)
		(layer "In11.Cu")
		(net "M_F_CPU0_SA_DQ<20>")
	)
	(segment
		(start 281.443684 -222.639382)
		(end 281.606752 -222.80245)
		(width 0.14478)
		(layer "In11.Cu")
		(net "M_F_CPU0_SA_DQ<20>")
	)
	(segment
		(start 299.392848 -221.569788)
		(end 301.061628 -221.569788)
		(width 0.14478)
		(layer "In11.Cu")
		(net "M_F_CPU0_SA_DQ<20>")
	)
	(segment
		(start 303.174908 -222.14459)
		(end 303.405286 -222.14459)
		(width 0.14478)
		(layer "In11.Cu")
		(net "M_F_CPU0_SA_DQ<20>")
	)
	(segment
		(start 284.115002 -221.723204)
		(end 284.268418 -221.569788)
		(width 0.14478)
		(layer "In11.Cu")
		(net "M_F_CPU0_SA_DQ<20>")
	)
	(segment
		(start 297.389042 -222.41002)
		(end 298.238926 -221.560136)
		(width 0.14478)
		(layer "In11.Cu")
		(net "M_F_CPU0_SA_DQ<20>")
	)
	(segment
		(start 269.96771 -222.537274)
		(end 270.11249 -222.682054)
		(width 0.14478)
		(layer "In11.Cu")
		(net "M_F_CPU0_SA_DQ<20>")
	)
	(segment
		(start 306.766976 -222.41002)
		(end 307.531008 -222.41002)
		(width 0.14478)
		(layer "In11.Cu")
		(net "M_F_CPU0_SA_DQ<20>")
	)
	(segment
		(start 286.752284 -222.419672)
		(end 288.831528 -222.419672)
		(width 0.14478)
		(layer "In11.Cu")
		(net "M_F_CPU0_SA_DQ<20>")
	)
	(segment
		(start 332.211172 -238.294926)
		(end 332.307184 -238.269526)
		(width 0.0889)
		(layer "In11.Cu")
		(net "M_F_CPU0_SA_DQ<20>")
	)
	(segment
		(start 290.972494 -221.560136)
		(end 291.135562 -221.723204)
		(width 0.14478)
		(layer "In11.Cu")
		(net "M_F_CPU0_SA_DQ<20>")
	)
	(segment
		(start 297.156124 -222.41002)
		(end 297.389042 -222.41002)
		(width 0.14478)
		(layer "In11.Cu")
		(net "M_F_CPU0_SA_DQ<20>")
	)
	(segment
		(start 281.443684 -222.573088)
		(end 281.443684 -222.639382)
		(width 0.14478)
		(layer "In11.Cu")
		(net "M_F_CPU0_SA_DQ<20>")
	)
	(segment
		(start 326.997568 -238.333534)
		(end 327.009252 -238.326676)
		(width 0.0889)
		(layer "In11.Cu")
		(net "M_F_CPU0_SA_DQ<20>")
	)
	(segment
		(start 299.239432 -221.783402)
		(end 299.239432 -221.723204)
		(width 0.14478)
		(layer "In11.Cu")
		(net "M_F_CPU0_SA_DQ<20>")
	)
	(segment
		(start 282.000198 -222.573088)
		(end 282.163266 -222.41002)
		(width 0.14478)
		(layer "In11.Cu")
		(net "M_F_CPU0_SA_DQ<20>")
	)
	(segment
		(start 302.618394 -222.80245)
		(end 302.848772 -222.80245)
		(width 0.14478)
		(layer "In11.Cu")
		(net "M_F_CPU0_SA_DQ<20>")
	)
	(segment
		(start 330.394056 -238.326676)
		(end 330.402438 -238.331502)
		(width 0.0889)
		(layer "In11.Cu")
		(net "M_F_CPU0_SA_DQ<20>")
	)
	(segment
		(start 271.070324 -221.787212)
		(end 271.070324 -222.653352)
		(width 0.14478)
		(layer "In11.Cu")
		(net "M_F_CPU0_SA_DQ<20>")
	)
	(segment
		(start 302.455326 -222.639382)
		(end 302.618394 -222.80245)
		(width 0.14478)
		(layer "In11.Cu")
		(net "M_F_CPU0_SA_DQ<20>")
	)
	(segment
		(start 276.416516 -221.95409)
		(end 276.579584 -221.791022)
		(width 0.14478)
		(layer "In11.Cu")
		(net "M_F_CPU0_SA_DQ<20>")
	)
	(segment
		(start 279.27046 -222.419672)
		(end 281.290268 -222.419672)
		(width 0.14478)
		(layer "In11.Cu")
		(net "M_F_CPU0_SA_DQ<20>")
	)
	(segment
		(start 303.01184 -222.307658)
		(end 303.174908 -222.14459)
		(width 0.14478)
		(layer "In11.Cu")
		(net "M_F_CPU0_SA_DQ<20>")
	)
	(segment
		(start 296.993056 -222.639382)
		(end 296.993056 -222.573088)
		(width 0.14478)
		(layer "In11.Cu")
		(net "M_F_CPU0_SA_DQ<20>")
	)
	(segment
		(start 270.37411 -222.682054)
		(end 270.51889 -222.537274)
		(width 0.14478)
		(layer "In11.Cu")
		(net "M_F_CPU0_SA_DQ<20>")
	)
	(segment
		(start 289.704526 -222.41002)
		(end 289.883088 -222.41002)
		(width 0.14478)
		(layer "In11.Cu")
		(net "M_F_CPU0_SA_DQ<20>")
	)
	(segment
		(start 298.238926 -221.560136)
		(end 298.51985 -221.560136)
		(width 0.14478)
		(layer "In11.Cu")
		(net "M_F_CPU0_SA_DQ<20>")
	)
	(segment
		(start 270.66367 -221.642432)
		(end 270.925544 -221.642432)
		(width 0.14478)
		(layer "In11.Cu")
		(net "M_F_CPU0_SA_DQ<20>")
	)
	(segment
		(start 296.993056 -222.573088)
		(end 297.156124 -222.41002)
		(width 0.14478)
		(layer "In11.Cu")
		(net "M_F_CPU0_SA_DQ<20>")
	)
	(segment
		(start 302.292258 -222.41002)
		(end 302.455326 -222.573088)
		(width 0.14478)
		(layer "In11.Cu")
		(net "M_F_CPU0_SA_DQ<20>")
	)
	(segment
		(start 283.39542 -221.560136)
		(end 283.558488 -221.723204)
		(width 0.14478)
		(layer "In11.Cu")
		(net "M_F_CPU0_SA_DQ<20>")
	)
	(segment
		(start 271.911318 -222.653352)
		(end 271.911318 -222.564452)
		(width 0.14478)
		(layer "In11.Cu")
		(net "M_F_CPU0_SA_DQ<20>")
	)
	(segment
		(start 281.606752 -222.80245)
		(end 281.83713 -222.80245)
		(width 0.14478)
		(layer "In11.Cu")
		(net "M_F_CPU0_SA_DQ<20>")
	)
	(segment
		(start 283.951934 -221.95409)
		(end 284.115002 -221.791022)
		(width 0.14478)
		(layer "In11.Cu")
		(net "M_F_CPU0_SA_DQ<20>")
	)
	(segment
		(start 283.17317 -221.560136)
		(end 283.39542 -221.560136)
		(width 0.14478)
		(layer "In11.Cu")
		(net "M_F_CPU0_SA_DQ<20>")
	)
	(segment
		(start 299.076364 -221.94647)
		(end 299.239432 -221.783402)
		(width 0.14478)
		(layer "In11.Cu")
		(net "M_F_CPU0_SA_DQ<20>")
	)
	(segment
		(start 296.436542 -222.639382)
		(end 296.59961 -222.80245)
		(width 0.14478)
		(layer "In11.Cu")
		(net "M_F_CPU0_SA_DQ<20>")
	)
	(segment
		(start 272.056098 -222.419672)
		(end 274.745196 -222.419672)
		(width 0.14478)
		(layer "In11.Cu")
		(net "M_F_CPU0_SA_DQ<20>")
	)
	(segment
		(start 291.135562 -221.783402)
		(end 291.29863 -221.94647)
		(width 0.14478)
		(layer "In11.Cu")
		(net "M_F_CPU0_SA_DQ<20>")
	)
	(segment
		(start 301.061628 -221.569788)
		(end 301.90186 -222.41002)
		(width 0.14478)
		(layer "In11.Cu")
		(net "M_F_CPU0_SA_DQ<20>")
	)
	(segment
		(start 283.558488 -221.791022)
		(end 283.721556 -221.95409)
		(width 0.14478)
		(layer "In11.Cu")
		(net "M_F_CPU0_SA_DQ<20>")
	)
	(segment
		(start 326.225408 -238.250222)
		(end 326.351138 -238.250222)
		(width 0.0889)
		(layer "In11.Cu")
		(net "M_F_CPU0_SA_DQ<20>")
	)
	(segment
		(start 303.01184 -222.639382)
		(end 303.01184 -222.307658)
		(width 0.14478)
		(layer "In11.Cu")
		(net "M_F_CPU0_SA_DQ<20>")
	)
	(segment
		(start 296.436542 -222.573088)
		(end 296.436542 -222.639382)
		(width 0.14478)
		(layer "In11.Cu")
		(net "M_F_CPU0_SA_DQ<20>")
	)
	(segment
		(start 271.215104 -222.798132)
		(end 271.766538 -222.798132)
		(width 0.14478)
		(layer "In11.Cu")
		(net "M_F_CPU0_SA_DQ<20>")
	)
	(segment
		(start 298.51985 -221.560136)
		(end 298.682918 -221.723204)
		(width 0.14478)
		(layer "In11.Cu")
		(net "M_F_CPU0_SA_DQ<20>")
	)
	(segment
		(start 276.579584 -221.791022)
		(end 276.579584 -221.723204)
		(width 0.14478)
		(layer "In11.Cu")
		(net "M_F_CPU0_SA_DQ<20>")
	)
	(segment
		(start 271.070324 -222.653352)
		(end 271.215104 -222.798132)
		(width 0.14478)
		(layer "In11.Cu")
		(net "M_F_CPU0_SA_DQ<20>")
	)
	(segment
		(start 276.579584 -221.723204)
		(end 276.733 -221.569788)
		(width 0.14478)
		(layer "In11.Cu")
		(net "M_F_CPU0_SA_DQ<20>")
	)
	(segment
		(start 329.819762 -238.331502)
		(end 329.828144 -238.326676)
		(width 0.0889)
		(layer "In11.Cu")
		(net "M_F_CPU0_SA_DQ<20>")
	)
	(segment
		(start 298.682918 -221.723204)
		(end 298.682918 -221.783402)
		(width 0.14478)
		(layer "In11.Cu")
		(net "M_F_CPU0_SA_DQ<20>")
	)
	(segment
		(start 331.33411 -238.326676)
		(end 331.342492 -238.331502)
		(width 0.0889)
		(layer "In11.Cu")
		(net "M_F_CPU0_SA_DQ<20>")
	)
	(segment
		(start 324.124574 -236.52861)
		(end 324.609714 -237.01375)
		(width 0.0889)
		(layer "In11.Cu")
		(net "M_F_CPU0_SA_DQ<20>")
	)
	(segment
		(start 296.283126 -222.419672)
		(end 296.436542 -222.573088)
		(width 0.14478)
		(layer "In11.Cu")
		(net "M_F_CPU0_SA_DQ<20>")
	)
	(segment
		(start 299.239432 -221.723204)
		(end 299.392848 -221.569788)
		(width 0.14478)
		(layer "In11.Cu")
		(net "M_F_CPU0_SA_DQ<20>")
	)
	(segment
		(start 270.51889 -222.537274)
		(end 270.51889 -221.787212)
		(width 0.14478)
		(layer "In11.Cu")
		(net "M_F_CPU0_SA_DQ<20>")
	)
	(segment
		(start 283.558488 -221.723204)
		(end 283.558488 -221.791022)
		(width 0.14478)
		(layer "In11.Cu")
		(net "M_F_CPU0_SA_DQ<20>")
	)
	(segment
		(start 291.529008 -221.94647)
		(end 291.692076 -221.783402)
		(width 0.14478)
		(layer "In11.Cu")
		(net "M_F_CPU0_SA_DQ<20>")
	)
	(segment
		(start 289.541458 -222.573088)
		(end 289.704526 -222.41002)
		(width 0.14478)
		(layer "In11.Cu")
		(net "M_F_CPU0_SA_DQ<20>")
	)
	(segment
		(start 291.29863 -221.94647)
		(end 291.529008 -221.94647)
		(width 0.14478)
		(layer "In11.Cu")
		(net "M_F_CPU0_SA_DQ<20>")
	)
	(segment
		(start 276.733 -221.569788)
		(end 278.420576 -221.569788)
		(width 0.14478)
		(layer "In11.Cu")
		(net "M_F_CPU0_SA_DQ<20>")
	)
	(segment
		(start 291.692076 -221.783402)
		(end 291.692076 -221.723204)
		(width 0.14478)
		(layer "In11.Cu")
		(net "M_F_CPU0_SA_DQ<20>")
	)
	(segment
		(start 282.163266 -222.41002)
		(end 282.323286 -222.41002)
		(width 0.14478)
		(layer "In11.Cu")
		(net "M_F_CPU0_SA_DQ<20>")
	)
	(segment
		(start 302.455326 -222.573088)
		(end 302.455326 -222.639382)
		(width 0.14478)
		(layer "In11.Cu")
		(net "M_F_CPU0_SA_DQ<20>")
	)
	(segment
		(start 269.82293 -221.985078)
		(end 269.96771 -222.129858)
		(width 0.14478)
		(layer "In11.Cu")
		(net "M_F_CPU0_SA_DQ<20>")
	)
	(segment
		(start 271.766538 -222.798132)
		(end 271.911318 -222.653352)
		(width 0.14478)
		(layer "In11.Cu")
		(net "M_F_CPU0_SA_DQ<20>")
	)
	(segment
		(start 296.59961 -222.80245)
		(end 296.829988 -222.80245)
		(width 0.14478)
		(layer "In11.Cu")
		(net "M_F_CPU0_SA_DQ<20>")
	)
	(segment
		(start 289.37839 -222.80245)
		(end 289.541458 -222.639382)
		(width 0.14478)
		(layer "In11.Cu")
		(net "M_F_CPU0_SA_DQ<20>")
	)
	(segment
		(start 276.02307 -221.723204)
		(end 276.02307 -221.791022)
		(width 0.14478)
		(layer "In11.Cu")
		(net "M_F_CPU0_SA_DQ<20>")
	)
	(segment
		(start 309.726838 -225.765614)
		(end 320.489834 -236.52861)
		(width 0.14478)
		(layer "In11.Cu")
		(net "M_F_CPU0_SA_DQ<20>")
	)
	(segment
		(start 303.568354 -222.639382)
		(end 303.731422 -222.80245)
		(width 0.14478)
		(layer "In11.Cu")
		(net "M_F_CPU0_SA_DQ<20>")
	)
	(segment
		(start 294.367458 -222.419672)
		(end 296.283126 -222.419672)
		(width 0.14478)
		(layer "In11.Cu")
		(net "M_F_CPU0_SA_DQ<20>")
	)
	(segment
		(start 324.609714 -237.01375)
		(end 324.988936 -237.01375)
		(width 0.0889)
		(layer "In11.Cu")
		(net "M_F_CPU0_SA_DQ<20>")
	)
	(segment
		(start 278.420576 -221.569788)
		(end 279.27046 -222.419672)
		(width 0.14478)
		(layer "In11.Cu")
		(net "M_F_CPU0_SA_DQ<20>")
	)
	(segment
		(start 291.135562 -221.723204)
		(end 291.135562 -221.783402)
		(width 0.14478)
		(layer "In11.Cu")
		(net "M_F_CPU0_SA_DQ<20>")
	)
	(segment
		(start 275.604732 -221.560136)
		(end 275.860002 -221.560136)
		(width 0.14478)
		(layer "In11.Cu")
		(net "M_F_CPU0_SA_DQ<20>")
	)
	(segment
		(start 284.268418 -221.569788)
		(end 285.9024 -221.569788)
		(width 0.14478)
		(layer "In11.Cu")
		(net "M_F_CPU0_SA_DQ<20>")
	)
	(segment
		(start 270.51889 -221.787212)
		(end 270.66367 -221.642432)
		(width 0.14478)
		(layer "In11.Cu")
		(net "M_F_CPU0_SA_DQ<20>")
	)
	(segment
		(start 289.148012 -222.80245)
		(end 289.37839 -222.80245)
		(width 0.14478)
		(layer "In11.Cu")
		(net "M_F_CPU0_SA_DQ<20>")
	)
	(segment
		(start 298.682918 -221.783402)
		(end 298.845986 -221.94647)
		(width 0.14478)
		(layer "In11.Cu")
		(net "M_F_CPU0_SA_DQ<20>")
	)
	(segment
		(start 323.934074 -236.52861)
		(end 324.124574 -236.52861)
		(width 0.0889)
		(layer "In11.Cu")
		(net "M_F_CPU0_SA_DQ<20>")
	)
	(segment
		(start 288.984944 -222.573088)
		(end 288.984944 -222.639382)
		(width 0.14478)
		(layer "In11.Cu")
		(net "M_F_CPU0_SA_DQ<20>")
	)
	(segment
		(start 303.731422 -222.80245)
		(end 306.374546 -222.80245)
		(width 0.14478)
		(layer "In11.Cu")
		(net "M_F_CPU0_SA_DQ<20>")
	)
	(segment
		(start 282.000198 -222.639382)
		(end 282.000198 -222.573088)
		(width 0.14478)
		(layer "In11.Cu")
		(net "M_F_CPU0_SA_DQ<20>")
	)
	(segment
		(start 276.186138 -221.95409)
		(end 276.416516 -221.95409)
		(width 0.14478)
		(layer "In11.Cu")
		(net "M_F_CPU0_SA_DQ<20>")
	)
	(segment
		(start 269.96771 -222.129858)
		(end 269.96771 -222.537274)
		(width 0.14478)
		(layer "In11.Cu")
		(net "M_F_CPU0_SA_DQ<20>")
	)
	(segment
		(start 269.648178 -221.985078)
		(end 269.82293 -221.985078)
		(width 0.14478)
		(layer "In11.Cu")
		(net "M_F_CPU0_SA_DQ<20>")
	)
	(segment
		(start 290.732972 -221.560136)
		(end 290.972494 -221.560136)
		(width 0.14478)
		(layer "In11.Cu")
		(net "M_F_CPU0_SA_DQ<20>")
	)
	(segment
		(start 320.489834 -236.52861)
		(end 323.934074 -236.52861)
		(width 0.14478)
		(layer "In11.Cu")
		(net "M_F_CPU0_SA_DQ<20>")
	)
	(segment
		(start 327.574402 -238.326422)
		(end 327.590658 -238.33582)
		(width 0.0889)
		(layer "In11.Cu")
		(net "M_F_CPU0_SA_DQ<20>")
	)
	(segment
		(start 302.848772 -222.80245)
		(end 303.01184 -222.639382)
		(width 0.14478)
		(layer "In11.Cu")
		(net "M_F_CPU0_SA_DQ<20>")
	)
	(segment
		(start 274.745196 -222.419672)
		(end 275.604732 -221.560136)
		(width 0.14478)
		(layer "In11.Cu")
		(net "M_F_CPU0_SA_DQ<20>")
	)
	(segment
		(start 289.883088 -222.41002)
		(end 290.732972 -221.560136)
		(width 0.14478)
		(layer "In11.Cu")
		(net "M_F_CPU0_SA_DQ<20>")
	)
	(segment
		(start 298.845986 -221.94647)
		(end 299.076364 -221.94647)
		(width 0.14478)
		(layer "In11.Cu")
		(net "M_F_CPU0_SA_DQ<20>")
	)
	(segment
		(start 293.517574 -221.569788)
		(end 294.367458 -222.419672)
		(width 0.14478)
		(layer "In11.Cu")
		(net "M_F_CPU0_SA_DQ<20>")
	)
	(segment
		(start 281.83713 -222.80245)
		(end 282.000198 -222.639382)
		(width 0.14478)
		(layer "In11.Cu")
		(net "M_F_CPU0_SA_DQ<20>")
	)
	(segment
		(start 283.721556 -221.95409)
		(end 283.951934 -221.95409)
		(width 0.14478)
		(layer "In11.Cu")
		(net "M_F_CPU0_SA_DQ<20>")
	)
	(segment
		(start 288.984944 -222.639382)
		(end 289.148012 -222.80245)
		(width 0.14478)
		(layer "In11.Cu")
		(net "M_F_CPU0_SA_DQ<20>")
	)
	(segment
		(start 275.860002 -221.560136)
		(end 276.02307 -221.723204)
		(width 0.14478)
		(layer "In11.Cu")
		(net "M_F_CPU0_SA_DQ<20>")
	)
	(arc
		(start 331.342492 -238.331502)
		(mid 331.526 -238.376996)
		(end 331.708252 -238.326676)
		(width 0.0889)
		(layer "In11.Cu")
		(net "M_F_CPU0_SA_DQ<20>")
	)
	(arc
		(start 328.88809 -238.326676)
		(mid 329.171046 -238.250499)
		(end 329.454002 -238.326676)
		(width 0.0889)
		(layer "In11.Cu")
		(net "M_F_CPU0_SA_DQ<20>")
	)
	(arc
		(start 326.634856 -238.326676)
		(mid 326.815314 -238.37712)
		(end 326.997568 -238.333534)
		(width 0.0889)
		(layer "In11.Cu")
		(net "M_F_CPU0_SA_DQ<20>")
	)
	(arc
		(start 329.454002 -238.326676)
		(mid 329.636253 -238.377026)
		(end 329.819762 -238.331502)
		(width 0.0889)
		(layer "In11.Cu")
		(net "M_F_CPU0_SA_DQ<20>")
	)
	(arc
		(start 327.590658 -238.33582)
		(mid 327.77064 -238.37692)
		(end 327.94829 -238.326676)
		(width 0.0889)
		(layer "In11.Cu")
		(net "M_F_CPU0_SA_DQ<20>")
	)
	(arc
		(start 329.828144 -238.326676)
		(mid 330.1111 -238.250499)
		(end 330.394056 -238.326676)
		(width 0.0889)
		(layer "In11.Cu")
		(net "M_F_CPU0_SA_DQ<20>")
	)
	(arc
		(start 327.009252 -238.326676)
		(mid 327.28493 -238.250546)
		(end 327.562464 -238.319564)
		(width 0.0889)
		(layer "In11.Cu")
		(net "M_F_CPU0_SA_DQ<20>")
	)
	(arc
		(start 330.768198 -238.326676)
		(mid 331.051154 -238.250499)
		(end 331.33411 -238.326676)
		(width 0.0889)
		(layer "In11.Cu")
		(net "M_F_CPU0_SA_DQ<20>")
	)
	(arc
		(start 326.351138 -238.250222)
		(mid 326.498069 -238.269633)
		(end 326.634856 -238.326676)
		(width 0.0889)
		(layer "In11.Cu")
		(net "M_F_CPU0_SA_DQ<20>")
	)
	(arc
		(start 327.94829 -238.326676)
		(mid 328.231246 -238.250499)
		(end 328.514202 -238.326676)
		(width 0.0889)
		(layer "In11.Cu")
		(net "M_F_CPU0_SA_DQ<20>")
	)
	(arc
		(start 328.514202 -238.326676)
		(mid 328.701146 -238.376931)
		(end 328.88809 -238.326676)
		(width 0.0889)
		(layer "In11.Cu")
		(net "M_F_CPU0_SA_DQ<20>")
	)
	(arc
		(start 331.708252 -238.326676)
		(mid 331.955965 -238.251456)
		(end 332.211172 -238.294926)
		(width 0.0889)
		(layer "In11.Cu")
		(net "M_F_CPU0_SA_DQ<20>")
	)
	(arc
		(start 330.402438 -238.331502)
		(mid 330.585946 -238.376996)
		(end 330.768198 -238.326676)
		(width 0.0889)
		(layer "In11.Cu")
		(net "M_F_CPU0_SA_DQ<20>")
	)
	(segment
		(start 334.337914 -226.120198)
		(end 333.871062 -225.85426)
		(width 0.10668)
		(layer "F.Cu")
		(net "M_F_CPU0_SA_DQ<1>")
	)
	(segment
		(start 286.742632 -199.460104)
		(end 289.883088 -199.460104)
		(width 0.14478)
		(layer "In11.Cu")
		(net "M_F_CPU0_SA_DQ<1>")
	)
	(segment
		(start 327.574402 -223.746822)
		(end 327.610724 -223.767904)
		(width 0.0889)
		(layer "In11.Cu")
		(net "M_F_CPU0_SA_DQ<1>")
	)
	(segment
		(start 301.90186 -199.460104)
		(end 304.894742 -199.460104)
		(width 0.14478)
		(layer "In11.Cu")
		(net "M_F_CPU0_SA_DQ<1>")
	)
	(segment
		(start 328.409808 -226.181666)
		(end 328.41819 -226.17684)
		(width 0.0889)
		(layer "In11.Cu")
		(net "M_F_CPU0_SA_DQ<1>")
	)
	(segment
		(start 320.0273 -212.474556)
		(end 320.190368 -212.637624)
		(width 0.14478)
		(layer "In11.Cu")
		(net "M_F_CPU0_SA_DQ<1>")
	)
	(segment
		(start 280.128218 -199.460104)
		(end 282.323286 -199.460104)
		(width 0.14478)
		(layer "In11.Cu")
		(net "M_F_CPU0_SA_DQ<1>")
	)
	(segment
		(start 327.104248 -222.936816)
		(end 327.14184 -222.95866)
		(width 0.0889)
		(layer "In11.Cu")
		(net "M_F_CPU0_SA_DQ<1>")
	)
	(segment
		(start 319.34912 -210.790536)
		(end 319.512188 -210.953604)
		(width 0.14478)
		(layer "In11.Cu")
		(net "M_F_CPU0_SA_DQ<1>")
	)
	(segment
		(start 326.634348 -222.12681)
		(end 326.672194 -222.148654)
		(width 0.0889)
		(layer "In11.Cu")
		(net "M_F_CPU0_SA_DQ<1>")
	)
	(segment
		(start 298.238926 -198.61022)
		(end 301.051976 -198.61022)
		(width 0.14478)
		(layer "In11.Cu")
		(net "M_F_CPU0_SA_DQ<1>")
	)
	(segment
		(start 333.621126 -226.14509)
		(end 333.717138 -226.11969)
		(width 0.0889)
		(layer "In11.Cu")
		(net "M_F_CPU0_SA_DQ<1>")
	)
	(segment
		(start 321.086988 -212.759036)
		(end 320.8147 -213.031324)
		(width 0.14478)
		(layer "In11.Cu")
		(net "M_F_CPU0_SA_DQ<1>")
	)
	(segment
		(start 326.463914 -222.007938)
		(end 326.495156 -222.06839)
		(width 0.0889)
		(layer "In11.Cu")
		(net "M_F_CPU0_SA_DQ<1>")
	)
	(segment
		(start 289.883088 -199.460104)
		(end 290.732972 -198.61022)
		(width 0.14478)
		(layer "In11.Cu")
		(net "M_F_CPU0_SA_DQ<1>")
	)
	(segment
		(start 324.017894 -216.46515)
		(end 324.017894 -218.81465)
		(width 0.14478)
		(layer "In11.Cu")
		(net "M_F_CPU0_SA_DQ<1>")
	)
	(segment
		(start 321.6021 -213.818724)
		(end 321.6021 -214.049356)
		(width 0.14478)
		(layer "In11.Cu")
		(net "M_F_CPU0_SA_DQ<1>")
	)
	(segment
		(start 319.905888 -211.577936)
		(end 320.13652 -211.577936)
		(width 0.14478)
		(layer "In11.Cu")
		(net "M_F_CPU0_SA_DQ<1>")
	)
	(segment
		(start 328.013568 -226.15906)
		(end 328.044048 -226.17684)
		(width 0.0889)
		(layer "In11.Cu")
		(net "M_F_CPU0_SA_DQ<1>")
	)
	(segment
		(start 285.892748 -198.61022)
		(end 286.742632 -199.460104)
		(width 0.14478)
		(layer "In11.Cu")
		(net "M_F_CPU0_SA_DQ<1>")
	)
	(segment
		(start 293.507922 -198.61022)
		(end 294.357806 -199.460104)
		(width 0.14478)
		(layer "In11.Cu")
		(net "M_F_CPU0_SA_DQ<1>")
	)
	(segment
		(start 318.8462 -211.062824)
		(end 319.118488 -210.790536)
		(width 0.14478)
		(layer "In11.Cu")
		(net "M_F_CPU0_SA_DQ<1>")
	)
	(segment
		(start 327.542398 -225.348546)
		(end 327.574148 -225.366834)
		(width 0.0889)
		(layer "In11.Cu")
		(net "M_F_CPU0_SA_DQ<1>")
	)
	(segment
		(start 333.717138 -226.11969)
		(end 333.871062 -225.85426)
		(width 0.0889)
		(layer "In11.Cu")
		(net "M_F_CPU0_SA_DQ<1>")
	)
	(segment
		(start 327.54062 -223.727264)
		(end 327.574402 -223.746822)
		(width 0.0889)
		(layer "In11.Cu")
		(net "M_F_CPU0_SA_DQ<1>")
	)
	(segment
		(start 321.71132 -213.152736)
		(end 321.874388 -213.315804)
		(width 0.14478)
		(layer "In11.Cu")
		(net "M_F_CPU0_SA_DQ<1>")
	)
	(segment
		(start 321.480688 -213.152736)
		(end 321.71132 -213.152736)
		(width 0.14478)
		(layer "In11.Cu")
		(net "M_F_CPU0_SA_DQ<1>")
	)
	(segment
		(start 320.92392 -212.365336)
		(end 321.086988 -212.528404)
		(width 0.14478)
		(layer "In11.Cu")
		(net "M_F_CPU0_SA_DQ<1>")
	)
	(segment
		(start 320.13652 -211.577936)
		(end 320.299588 -211.741004)
		(width 0.14478)
		(layer "In11.Cu")
		(net "M_F_CPU0_SA_DQ<1>")
	)
	(segment
		(start 320.190368 -212.637624)
		(end 320.421 -212.637624)
		(width 0.14478)
		(layer "In11.Cu")
		(net "M_F_CPU0_SA_DQ<1>")
	)
	(segment
		(start 320.421 -212.637624)
		(end 320.693288 -212.365336)
		(width 0.14478)
		(layer "In11.Cu")
		(net "M_F_CPU0_SA_DQ<1>")
	)
	(segment
		(start 294.357806 -199.460104)
		(end 297.389042 -199.460104)
		(width 0.14478)
		(layer "In11.Cu")
		(net "M_F_CPU0_SA_DQ<1>")
	)
	(segment
		(start 275.933154 -198.61022)
		(end 278.076406 -198.61022)
		(width 0.14478)
		(layer "In11.Cu")
		(net "M_F_CPU0_SA_DQ<1>")
	)
	(segment
		(start 319.118488 -210.790536)
		(end 319.34912 -210.790536)
		(width 0.14478)
		(layer "In11.Cu")
		(net "M_F_CPU0_SA_DQ<1>")
	)
	(segment
		(start 326.463914 -221.26067)
		(end 326.463914 -222.007938)
		(width 0.0889)
		(layer "In11.Cu")
		(net "M_F_CPU0_SA_DQ<1>")
	)
	(segment
		(start 290.732972 -198.61022)
		(end 293.507922 -198.61022)
		(width 0.14478)
		(layer "In11.Cu")
		(net "M_F_CPU0_SA_DQ<1>")
	)
	(segment
		(start 320.8147 -213.261956)
		(end 320.977768 -213.425024)
		(width 0.14478)
		(layer "In11.Cu")
		(net "M_F_CPU0_SA_DQ<1>")
	)
	(segment
		(start 318.351154 -209.08391)
		(end 318.351154 -210.79841)
		(width 0.14478)
		(layer "In11.Cu")
		(net "M_F_CPU0_SA_DQ<1>")
	)
	(segment
		(start 305.744626 -198.61022)
		(end 307.877464 -198.61022)
		(width 0.14478)
		(layer "In11.Cu")
		(net "M_F_CPU0_SA_DQ<1>")
	)
	(segment
		(start 307.877464 -198.61022)
		(end 318.351154 -209.08391)
		(width 0.14478)
		(layer "In11.Cu")
		(net "M_F_CPU0_SA_DQ<1>")
	)
	(segment
		(start 269.648178 -199.035162)
		(end 270.07312 -199.460104)
		(width 0.14478)
		(layer "In11.Cu")
		(net "M_F_CPU0_SA_DQ<1>")
	)
	(segment
		(start 320.8147 -213.031324)
		(end 320.8147 -213.261956)
		(width 0.14478)
		(layer "In11.Cu")
		(net "M_F_CPU0_SA_DQ<1>")
	)
	(segment
		(start 327.611994 -224.69983)
		(end 327.574148 -224.721674)
		(width 0.0889)
		(layer "In11.Cu")
		(net "M_F_CPU0_SA_DQ<1>")
	)
	(segment
		(start 273.881342 -199.460104)
		(end 275.933154 -198.61022)
		(width 0.14478)
		(layer "In11.Cu")
		(net "M_F_CPU0_SA_DQ<1>")
	)
	(segment
		(start 321.2084 -213.425024)
		(end 321.480688 -213.152736)
		(width 0.14478)
		(layer "In11.Cu")
		(net "M_F_CPU0_SA_DQ<1>")
	)
	(segment
		(start 304.894742 -199.460104)
		(end 305.744626 -198.61022)
		(width 0.14478)
		(layer "In11.Cu")
		(net "M_F_CPU0_SA_DQ<1>")
	)
	(segment
		(start 278.076406 -198.61022)
		(end 278.647398 -198.846694)
		(width 0.14478)
		(layer "In11.Cu")
		(net "M_F_CPU0_SA_DQ<1>")
	)
	(segment
		(start 320.299588 -211.971636)
		(end 320.0273 -212.243924)
		(width 0.14478)
		(layer "In11.Cu")
		(net "M_F_CPU0_SA_DQ<1>")
	)
	(segment
		(start 319.402968 -211.850224)
		(end 319.6336 -211.850224)
		(width 0.14478)
		(layer "In11.Cu")
		(net "M_F_CPU0_SA_DQ<1>")
	)
	(segment
		(start 318.615568 -211.062824)
		(end 318.8462 -211.062824)
		(width 0.14478)
		(layer "In11.Cu")
		(net "M_F_CPU0_SA_DQ<1>")
	)
	(segment
		(start 319.2399 -211.687156)
		(end 319.402968 -211.850224)
		(width 0.14478)
		(layer "In11.Cu")
		(net "M_F_CPU0_SA_DQ<1>")
	)
	(segment
		(start 270.07312 -199.460104)
		(end 273.881342 -199.460104)
		(width 0.14478)
		(layer "In11.Cu")
		(net "M_F_CPU0_SA_DQ<1>")
	)
	(segment
		(start 320.299588 -211.741004)
		(end 320.299588 -211.971636)
		(width 0.14478)
		(layer "In11.Cu")
		(net "M_F_CPU0_SA_DQ<1>")
	)
	(segment
		(start 332.744064 -226.17684)
		(end 332.752446 -226.181666)
		(width 0.0889)
		(layer "In11.Cu")
		(net "M_F_CPU0_SA_DQ<1>")
	)
	(segment
		(start 301.051976 -198.61022)
		(end 301.90186 -199.460104)
		(width 0.14478)
		(layer "In11.Cu")
		(net "M_F_CPU0_SA_DQ<1>")
	)
	(segment
		(start 321.6021 -214.049356)
		(end 324.017894 -216.46515)
		(width 0.14478)
		(layer "In11.Cu")
		(net "M_F_CPU0_SA_DQ<1>")
	)
	(segment
		(start 321.086988 -212.528404)
		(end 321.086988 -212.759036)
		(width 0.14478)
		(layer "In11.Cu")
		(net "M_F_CPU0_SA_DQ<1>")
	)
	(segment
		(start 327.574148 -224.721674)
		(end 327.542398 -224.739962)
		(width 0.0889)
		(layer "In11.Cu")
		(net "M_F_CPU0_SA_DQ<1>")
	)
	(segment
		(start 297.389042 -199.460104)
		(end 298.238926 -198.61022)
		(width 0.14478)
		(layer "In11.Cu")
		(net "M_F_CPU0_SA_DQ<1>")
	)
	(segment
		(start 327.073768 -222.919036)
		(end 327.104248 -222.936816)
		(width 0.0889)
		(layer "In11.Cu")
		(net "M_F_CPU0_SA_DQ<1>")
	)
	(segment
		(start 282.323286 -199.460104)
		(end 283.17317 -198.61022)
		(width 0.14478)
		(layer "In11.Cu")
		(net "M_F_CPU0_SA_DQ<1>")
	)
	(segment
		(start 318.351154 -210.79841)
		(end 318.615568 -211.062824)
		(width 0.14478)
		(layer "In11.Cu")
		(net "M_F_CPU0_SA_DQ<1>")
	)
	(segment
		(start 324.017894 -218.81465)
		(end 326.463914 -221.26067)
		(width 0.14478)
		(layer "In11.Cu")
		(net "M_F_CPU0_SA_DQ<1>")
	)
	(segment
		(start 319.2399 -211.456524)
		(end 319.2399 -211.687156)
		(width 0.14478)
		(layer "In11.Cu")
		(net "M_F_CPU0_SA_DQ<1>")
	)
	(segment
		(start 278.647398 -198.846694)
		(end 280.128218 -199.460104)
		(width 0.14478)
		(layer "In11.Cu")
		(net "M_F_CPU0_SA_DQ<1>")
	)
	(segment
		(start 331.229716 -226.181666)
		(end 331.238098 -226.17684)
		(width 0.0889)
		(layer "In11.Cu")
		(net "M_F_CPU0_SA_DQ<1>")
	)
	(segment
		(start 328.984102 -226.17684)
		(end 328.992484 -226.181666)
		(width 0.0889)
		(layer "In11.Cu")
		(net "M_F_CPU0_SA_DQ<1>")
	)
	(segment
		(start 321.874388 -213.315804)
		(end 321.874388 -213.546436)
		(width 0.14478)
		(layer "In11.Cu")
		(net "M_F_CPU0_SA_DQ<1>")
	)
	(segment
		(start 319.512188 -211.184236)
		(end 319.2399 -211.456524)
		(width 0.14478)
		(layer "In11.Cu")
		(net "M_F_CPU0_SA_DQ<1>")
	)
	(segment
		(start 327.574148 -225.366834)
		(end 327.611994 -225.388678)
		(width 0.0889)
		(layer "In11.Cu")
		(net "M_F_CPU0_SA_DQ<1>")
	)
	(segment
		(start 332.16977 -226.181666)
		(end 332.178152 -226.17684)
		(width 0.0889)
		(layer "In11.Cu")
		(net "M_F_CPU0_SA_DQ<1>")
	)
	(segment
		(start 320.693288 -212.365336)
		(end 320.92392 -212.365336)
		(width 0.14478)
		(layer "In11.Cu")
		(net "M_F_CPU0_SA_DQ<1>")
	)
	(segment
		(start 319.6336 -211.850224)
		(end 319.905888 -211.577936)
		(width 0.14478)
		(layer "In11.Cu")
		(net "M_F_CPU0_SA_DQ<1>")
	)
	(segment
		(start 326.495156 -222.06839)
		(end 326.52335 -222.077534)
		(width 0.0889)
		(layer "In11.Cu")
		(net "M_F_CPU0_SA_DQ<1>")
	)
	(segment
		(start 320.0273 -212.243924)
		(end 320.0273 -212.474556)
		(width 0.14478)
		(layer "In11.Cu")
		(net "M_F_CPU0_SA_DQ<1>")
	)
	(segment
		(start 283.17317 -198.61022)
		(end 285.892748 -198.61022)
		(width 0.14478)
		(layer "In11.Cu")
		(net "M_F_CPU0_SA_DQ<1>")
	)
	(segment
		(start 320.977768 -213.425024)
		(end 321.2084 -213.425024)
		(width 0.14478)
		(layer "In11.Cu")
		(net "M_F_CPU0_SA_DQ<1>")
	)
	(segment
		(start 319.512188 -210.953604)
		(end 319.512188 -211.184236)
		(width 0.14478)
		(layer "In11.Cu")
		(net "M_F_CPU0_SA_DQ<1>")
	)
	(segment
		(start 321.874388 -213.546436)
		(end 321.6021 -213.818724)
		(width 0.14478)
		(layer "In11.Cu")
		(net "M_F_CPU0_SA_DQ<1>")
	)
	(arc
		(start 328.044048 -226.17684)
		(mid 328.226299 -226.22719)
		(end 328.409808 -226.181666)
		(width 0.0889)
		(layer "In11.Cu")
		(net "M_F_CPU0_SA_DQ<1>")
	)
	(arc
		(start 332.752446 -226.181666)
		(mid 332.935954 -226.22716)
		(end 333.118206 -226.17684)
		(width 0.0889)
		(layer "In11.Cu")
		(net "M_F_CPU0_SA_DQ<1>")
	)
	(arc
		(start 327.14184 -222.95866)
		(mid 327.321569 -223.16128)
		(end 327.386442 -223.424242)
		(width 0.0889)
		(layer "In11.Cu")
		(net "M_F_CPU0_SA_DQ<1>")
	)
	(arc
		(start 327.856596 -224.234248)
		(mid 327.791724 -224.497211)
		(end 327.611994 -224.69983)
		(width 0.0889)
		(layer "In11.Cu")
		(net "M_F_CPU0_SA_DQ<1>")
	)
	(arc
		(start 326.916796 -222.614236)
		(mid 326.958345 -222.785658)
		(end 327.073768 -222.919036)
		(width 0.0889)
		(layer "In11.Cu")
		(net "M_F_CPU0_SA_DQ<1>")
	)
	(arc
		(start 327.610724 -223.767904)
		(mid 327.791376 -223.970649)
		(end 327.856596 -224.234248)
		(width 0.0889)
		(layer "In11.Cu")
		(net "M_F_CPU0_SA_DQ<1>")
	)
	(arc
		(start 327.856596 -225.85426)
		(mid 327.898145 -226.025682)
		(end 328.013568 -226.15906)
		(width 0.0889)
		(layer "In11.Cu")
		(net "M_F_CPU0_SA_DQ<1>")
	)
	(arc
		(start 327.386442 -223.424242)
		(mid 327.4272 -223.59424)
		(end 327.54062 -223.727264)
		(width 0.0889)
		(layer "In11.Cu")
		(net "M_F_CPU0_SA_DQ<1>")
	)
	(arc
		(start 326.672194 -222.148654)
		(mid 326.851923 -222.351274)
		(end 326.916796 -222.614236)
		(width 0.0889)
		(layer "In11.Cu")
		(net "M_F_CPU0_SA_DQ<1>")
	)
	(arc
		(start 328.41819 -226.17684)
		(mid 328.701146 -226.100663)
		(end 328.984102 -226.17684)
		(width 0.0889)
		(layer "In11.Cu")
		(net "M_F_CPU0_SA_DQ<1>")
	)
	(arc
		(start 329.924156 -226.17684)
		(mid 330.1111 -226.227095)
		(end 330.298044 -226.17684)
		(width 0.0889)
		(layer "In11.Cu")
		(net "M_F_CPU0_SA_DQ<1>")
	)
	(arc
		(start 331.238098 -226.17684)
		(mid 331.521054 -226.100663)
		(end 331.80401 -226.17684)
		(width 0.0889)
		(layer "In11.Cu")
		(net "M_F_CPU0_SA_DQ<1>")
	)
	(arc
		(start 333.118206 -226.17684)
		(mid 333.365919 -226.10162)
		(end 333.621126 -226.14509)
		(width 0.0889)
		(layer "In11.Cu")
		(net "M_F_CPU0_SA_DQ<1>")
	)
	(arc
		(start 328.992484 -226.181666)
		(mid 329.175992 -226.22716)
		(end 329.358244 -226.17684)
		(width 0.0889)
		(layer "In11.Cu")
		(net "M_F_CPU0_SA_DQ<1>")
	)
	(arc
		(start 331.80401 -226.17684)
		(mid 331.986261 -226.22719)
		(end 332.16977 -226.181666)
		(width 0.0889)
		(layer "In11.Cu")
		(net "M_F_CPU0_SA_DQ<1>")
	)
	(arc
		(start 327.611994 -225.388678)
		(mid 327.791723 -225.591298)
		(end 327.856596 -225.85426)
		(width 0.0889)
		(layer "In11.Cu")
		(net "M_F_CPU0_SA_DQ<1>")
	)
	(arc
		(start 327.542398 -224.739962)
		(mid 327.38647 -225.044254)
		(end 327.542398 -225.348546)
		(width 0.0889)
		(layer "In11.Cu")
		(net "M_F_CPU0_SA_DQ<1>")
	)
	(arc
		(start 326.52335 -222.077534)
		(mid 326.580186 -222.099162)
		(end 326.634348 -222.12681)
		(width 0.0889)
		(layer "In11.Cu")
		(net "M_F_CPU0_SA_DQ<1>")
	)
	(arc
		(start 332.178152 -226.17684)
		(mid 332.461108 -226.100663)
		(end 332.744064 -226.17684)
		(width 0.0889)
		(layer "In11.Cu")
		(net "M_F_CPU0_SA_DQ<1>")
	)
	(arc
		(start 330.863956 -226.17684)
		(mid 331.046207 -226.22719)
		(end 331.229716 -226.181666)
		(width 0.0889)
		(layer "In11.Cu")
		(net "M_F_CPU0_SA_DQ<1>")
	)
	(arc
		(start 330.298044 -226.17684)
		(mid 330.581 -226.100663)
		(end 330.863956 -226.17684)
		(width 0.0889)
		(layer "In11.Cu")
		(net "M_F_CPU0_SA_DQ<1>")
	)
	(arc
		(start 329.358244 -226.17684)
		(mid 329.6412 -226.100663)
		(end 329.924156 -226.17684)
		(width 0.0889)
		(layer "In11.Cu")
		(net "M_F_CPU0_SA_DQ<1>")
	)
	(segment
		(start 333.868014 -236.650022)
		(end 333.401162 -236.384084)
		(width 0.10668)
		(layer "F.Cu")
		(net "M_F_CPU0_SA_DQ<19>")
	)
	(segment
		(start 290.691824 -218.15044)
		(end 293.54907 -218.15044)
		(width 0.14478)
		(layer "In11.Cu")
		(net "M_F_CPU0_SA_DQ<19>")
	)
	(segment
		(start 327.007728 -236.061504)
		(end 327.018142 -236.0676)
		(width 0.0889)
		(layer "In11.Cu")
		(net "M_F_CPU0_SA_DQ<19>")
	)
	(segment
		(start 312.072274 -224.244154)
		(end 321.99453 -234.16641)
		(width 0.14478)
		(layer "In11.Cu")
		(net "M_F_CPU0_SA_DQ<19>")
	)
	(segment
		(start 326.619108 -236.07014)
		(end 326.63384 -236.061504)
		(width 0.0889)
		(layer "In11.Cu")
		(net "M_F_CPU0_SA_DQ<19>")
	)
	(segment
		(start 274.677632 -219.000324)
		(end 275.527516 -218.15044)
		(width 0.14478)
		(layer "In11.Cu")
		(net "M_F_CPU0_SA_DQ<19>")
	)
	(segment
		(start 286.043624 -218.15044)
		(end 286.893508 -219.000324)
		(width 0.14478)
		(layer "In11.Cu")
		(net "M_F_CPU0_SA_DQ<19>")
	)
	(segment
		(start 293.54907 -218.15044)
		(end 294.398954 -219.000324)
		(width 0.14478)
		(layer "In11.Cu")
		(net "M_F_CPU0_SA_DQ<19>")
	)
	(segment
		(start 326.63384 -236.061504)
		(end 326.645524 -236.054646)
		(width 0.0889)
		(layer "In11.Cu")
		(net "M_F_CPU0_SA_DQ<19>")
	)
	(segment
		(start 298.18965 -218.15044)
		(end 301.085504 -218.15044)
		(width 0.14478)
		(layer "In11.Cu")
		(net "M_F_CPU0_SA_DQ<19>")
	)
	(segment
		(start 294.398954 -219.000324)
		(end 297.339766 -219.000324)
		(width 0.14478)
		(layer "In11.Cu")
		(net "M_F_CPU0_SA_DQ<19>")
	)
	(segment
		(start 265.9634 -219.000324)
		(end 274.677632 -219.000324)
		(width 0.14478)
		(layer "In11.Cu")
		(net "M_F_CPU0_SA_DQ<19>")
	)
	(segment
		(start 282.308554 -219.000324)
		(end 283.158438 -218.15044)
		(width 0.14478)
		(layer "In11.Cu")
		(net "M_F_CPU0_SA_DQ<19>")
	)
	(segment
		(start 265.54811 -218.585034)
		(end 265.9634 -219.000324)
		(width 0.14478)
		(layer "In11.Cu")
		(net "M_F_CPU0_SA_DQ<19>")
	)
	(segment
		(start 297.339766 -219.000324)
		(end 298.18965 -218.15044)
		(width 0.14478)
		(layer "In11.Cu")
		(net "M_F_CPU0_SA_DQ<19>")
	)
	(segment
		(start 333.532734 -236.035342)
		(end 333.555086 -236.118654)
		(width 0.0889)
		(layer "In11.Cu")
		(net "M_F_CPU0_SA_DQ<19>")
	)
	(segment
		(start 305.726338 -218.160092)
		(end 307.136292 -218.160092)
		(width 0.14478)
		(layer "In11.Cu")
		(net "M_F_CPU0_SA_DQ<19>")
	)
	(segment
		(start 283.158438 -218.15044)
		(end 286.043624 -218.15044)
		(width 0.14478)
		(layer "In11.Cu")
		(net "M_F_CPU0_SA_DQ<19>")
	)
	(segment
		(start 307.136292 -218.160092)
		(end 312.072274 -223.096074)
		(width 0.14478)
		(layer "In11.Cu")
		(net "M_F_CPU0_SA_DQ<19>")
	)
	(segment
		(start 312.072274 -223.096074)
		(end 312.072274 -224.244154)
		(width 0.14478)
		(layer "In11.Cu")
		(net "M_F_CPU0_SA_DQ<19>")
	)
	(segment
		(start 323.568314 -234.16641)
		(end 323.977254 -234.16641)
		(width 0.0889)
		(layer "In11.Cu")
		(net "M_F_CPU0_SA_DQ<19>")
	)
	(segment
		(start 330.394056 -236.061504)
		(end 330.402438 -236.056678)
		(width 0.0889)
		(layer "In11.Cu")
		(net "M_F_CPU0_SA_DQ<19>")
	)
	(segment
		(start 305.276758 -218.609672)
		(end 305.726338 -218.160092)
		(width 0.14478)
		(layer "In11.Cu")
		(net "M_F_CPU0_SA_DQ<19>")
	)
	(segment
		(start 279.324054 -219.000324)
		(end 282.308554 -219.000324)
		(width 0.14478)
		(layer "In11.Cu")
		(net "M_F_CPU0_SA_DQ<19>")
	)
	(segment
		(start 289.84194 -219.000324)
		(end 290.691824 -218.15044)
		(width 0.14478)
		(layer "In11.Cu")
		(net "M_F_CPU0_SA_DQ<19>")
	)
	(segment
		(start 301.085504 -218.15044)
		(end 301.544736 -218.609672)
		(width 0.14478)
		(layer "In11.Cu")
		(net "M_F_CPU0_SA_DQ<19>")
	)
	(segment
		(start 329.819762 -236.056678)
		(end 329.828144 -236.061504)
		(width 0.0889)
		(layer "In11.Cu")
		(net "M_F_CPU0_SA_DQ<19>")
	)
	(segment
		(start 325.120254 -234.89031)
		(end 325.120254 -235.140246)
		(width 0.0889)
		(layer "In11.Cu")
		(net "M_F_CPU0_SA_DQ<19>")
	)
	(segment
		(start 323.977254 -234.16641)
		(end 324.485254 -234.67441)
		(width 0.0889)
		(layer "In11.Cu")
		(net "M_F_CPU0_SA_DQ<19>")
	)
	(segment
		(start 301.544736 -218.609672)
		(end 305.276758 -218.609672)
		(width 0.14478)
		(layer "In11.Cu")
		(net "M_F_CPU0_SA_DQ<19>")
	)
	(segment
		(start 286.893508 -219.000324)
		(end 289.84194 -219.000324)
		(width 0.14478)
		(layer "In11.Cu")
		(net "M_F_CPU0_SA_DQ<19>")
	)
	(segment
		(start 333.555086 -236.118654)
		(end 333.401162 -236.384084)
		(width 0.0889)
		(layer "In11.Cu")
		(net "M_F_CPU0_SA_DQ<19>")
	)
	(segment
		(start 275.527516 -218.15044)
		(end 278.47417 -218.15044)
		(width 0.14478)
		(layer "In11.Cu")
		(net "M_F_CPU0_SA_DQ<19>")
	)
	(segment
		(start 321.99453 -234.16641)
		(end 323.568314 -234.16641)
		(width 0.14478)
		(layer "In11.Cu")
		(net "M_F_CPU0_SA_DQ<19>")
	)
	(segment
		(start 278.47417 -218.15044)
		(end 279.324054 -219.000324)
		(width 0.14478)
		(layer "In11.Cu")
		(net "M_F_CPU0_SA_DQ<19>")
	)
	(segment
		(start 325.120254 -235.140246)
		(end 325.952612 -235.972604)
		(width 0.0889)
		(layer "In11.Cu")
		(net "M_F_CPU0_SA_DQ<19>")
	)
	(segment
		(start 324.485254 -234.67441)
		(end 324.904354 -234.67441)
		(width 0.0889)
		(layer "In11.Cu")
		(net "M_F_CPU0_SA_DQ<19>")
	)
	(segment
		(start 331.33411 -236.061504)
		(end 331.342492 -236.056678)
		(width 0.0889)
		(layer "In11.Cu")
		(net "M_F_CPU0_SA_DQ<19>")
	)
	(segment
		(start 324.904354 -234.67441)
		(end 325.120254 -234.89031)
		(width 0.0889)
		(layer "In11.Cu")
		(net "M_F_CPU0_SA_DQ<19>")
	)
	(arc
		(start 329.828144 -236.061504)
		(mid 330.1111 -236.137681)
		(end 330.394056 -236.061504)
		(width 0.0889)
		(layer "In11.Cu")
		(net "M_F_CPU0_SA_DQ<19>")
	)
	(arc
		(start 327.94829 -236.061504)
		(mid 328.231246 -236.137681)
		(end 328.514202 -236.061504)
		(width 0.0889)
		(layer "In11.Cu")
		(net "M_F_CPU0_SA_DQ<19>")
	)
	(arc
		(start 327.018142 -236.0676)
		(mid 327.296828 -236.13782)
		(end 327.573894 -236.061504)
		(width 0.0889)
		(layer "In11.Cu")
		(net "M_F_CPU0_SA_DQ<19>")
	)
	(arc
		(start 331.342492 -236.056678)
		(mid 331.526 -236.011184)
		(end 331.708252 -236.061504)
		(width 0.0889)
		(layer "In11.Cu")
		(net "M_F_CPU0_SA_DQ<19>")
	)
	(arc
		(start 333.213964 -236.061504)
		(mid 333.370402 -236.012533)
		(end 333.532734 -236.035342)
		(width 0.0889)
		(layer "In11.Cu")
		(net "M_F_CPU0_SA_DQ<19>")
	)
	(arc
		(start 332.274164 -236.061504)
		(mid 332.461108 -236.011249)
		(end 332.648052 -236.061504)
		(width 0.0889)
		(layer "In11.Cu")
		(net "M_F_CPU0_SA_DQ<19>")
	)
	(arc
		(start 329.454002 -236.061504)
		(mid 329.636253 -236.011154)
		(end 329.819762 -236.056678)
		(width 0.0889)
		(layer "In11.Cu")
		(net "M_F_CPU0_SA_DQ<19>")
	)
	(arc
		(start 330.768198 -236.061504)
		(mid 331.051154 -236.137681)
		(end 331.33411 -236.061504)
		(width 0.0889)
		(layer "In11.Cu")
		(net "M_F_CPU0_SA_DQ<19>")
	)
	(arc
		(start 325.952612 -235.972604)
		(mid 326.007384 -236.020798)
		(end 326.067928 -236.061504)
		(width 0.0889)
		(layer "In11.Cu")
		(net "M_F_CPU0_SA_DQ<19>")
	)
	(arc
		(start 331.708252 -236.061504)
		(mid 331.991208 -236.137681)
		(end 332.274164 -236.061504)
		(width 0.0889)
		(layer "In11.Cu")
		(net "M_F_CPU0_SA_DQ<19>")
	)
	(arc
		(start 328.88809 -236.061504)
		(mid 329.171046 -236.137681)
		(end 329.454002 -236.061504)
		(width 0.0889)
		(layer "In11.Cu")
		(net "M_F_CPU0_SA_DQ<19>")
	)
	(arc
		(start 326.067928 -236.061504)
		(mid 326.34238 -236.13774)
		(end 326.619108 -236.07014)
		(width 0.0889)
		(layer "In11.Cu")
		(net "M_F_CPU0_SA_DQ<19>")
	)
	(arc
		(start 332.648052 -236.061504)
		(mid 332.931008 -236.137681)
		(end 333.213964 -236.061504)
		(width 0.0889)
		(layer "In11.Cu")
		(net "M_F_CPU0_SA_DQ<19>")
	)
	(arc
		(start 327.573894 -236.061504)
		(mid 327.761092 -236.011122)
		(end 327.94829 -236.061504)
		(width 0.0889)
		(layer "In11.Cu")
		(net "M_F_CPU0_SA_DQ<19>")
	)
	(arc
		(start 326.645524 -236.054646)
		(mid 326.827525 -236.011113)
		(end 327.007728 -236.061504)
		(width 0.0889)
		(layer "In11.Cu")
		(net "M_F_CPU0_SA_DQ<19>")
	)
	(arc
		(start 328.514202 -236.061504)
		(mid 328.701146 -236.011249)
		(end 328.88809 -236.061504)
		(width 0.0889)
		(layer "In11.Cu")
		(net "M_F_CPU0_SA_DQ<19>")
	)
	(arc
		(start 330.402438 -236.056678)
		(mid 330.585946 -236.011184)
		(end 330.768198 -236.061504)
		(width 0.0889)
		(layer "In11.Cu")
		(net "M_F_CPU0_SA_DQ<19>")
	)
	(segment
		(start 332.45806 -235.840016)
		(end 331.991208 -235.574078)
		(width 0.10668)
		(layer "F.Cu")
		(net "M_F_CPU0_SA_DQ<18>")
	)
	(segment
		(start 327.08723 -235.262166)
		(end 327.105264 -235.251498)
		(width 0.0889)
		(layer "In11.Cu")
		(net "M_F_CPU0_SA_DQ<18>")
	)
	(segment
		(start 313.001914 -222.666814)
		(end 313.001914 -223.887538)
		(width 0.14478)
		(layer "In11.Cu")
		(net "M_F_CPU0_SA_DQ<18>")
	)
	(segment
		(start 301.945294 -217.310208)
		(end 304.8762 -217.310208)
		(width 0.14478)
		(layer "In11.Cu")
		(net "M_F_CPU0_SA_DQ<18>")
	)
	(segment
		(start 283.148786 -216.46007)
		(end 286.053276 -216.46007)
		(width 0.14478)
		(layer "In11.Cu")
		(net "M_F_CPU0_SA_DQ<18>")
	)
	(segment
		(start 324.629526 -234.10291)
		(end 324.985126 -234.10291)
		(width 0.0889)
		(layer "In11.Cu")
		(net "M_F_CPU0_SA_DQ<18>")
	)
	(segment
		(start 265.973306 -217.310208)
		(end 267.457936 -217.310208)
		(width 0.14478)
		(layer "In11.Cu")
		(net "M_F_CPU0_SA_DQ<18>")
	)
	(segment
		(start 323.568314 -233.25709)
		(end 323.893434 -233.25709)
		(width 0.0889)
		(layer "In11.Cu")
		(net "M_F_CPU0_SA_DQ<18>")
	)
	(segment
		(start 323.893434 -233.25709)
		(end 324.180454 -233.54411)
		(width 0.0889)
		(layer "In11.Cu")
		(net "M_F_CPU0_SA_DQ<18>")
	)
	(segment
		(start 328.409808 -235.246672)
		(end 328.41819 -235.251498)
		(width 0.0889)
		(layer "In11.Cu")
		(net "M_F_CPU0_SA_DQ<18>")
	)
	(segment
		(start 326.089518 -235.20146)
		(end 326.351392 -235.201206)
		(width 0.0889)
		(layer "In11.Cu")
		(net "M_F_CPU0_SA_DQ<18>")
	)
	(segment
		(start 332.12278 -235.225336)
		(end 332.145132 -235.308648)
		(width 0.0889)
		(layer "In11.Cu")
		(net "M_F_CPU0_SA_DQ<18>")
	)
	(segment
		(start 267.457936 -217.310208)
		(end 267.624052 -217.144092)
		(width 0.14478)
		(layer "In11.Cu")
		(net "M_F_CPU0_SA_DQ<18>")
	)
	(segment
		(start 307.821838 -217.486738)
		(end 313.001914 -222.666814)
		(width 0.14478)
		(layer "In11.Cu")
		(net "M_F_CPU0_SA_DQ<18>")
	)
	(segment
		(start 327.465182 -235.243878)
		(end 327.478898 -235.251752)
		(width 0.0889)
		(layer "In11.Cu")
		(net "M_F_CPU0_SA_DQ<18>")
	)
	(segment
		(start 328.984102 -235.251498)
		(end 328.992484 -235.246672)
		(width 0.0889)
		(layer "In11.Cu")
		(net "M_F_CPU0_SA_DQ<18>")
	)
	(segment
		(start 286.053276 -216.46007)
		(end 286.903414 -217.310208)
		(width 0.14478)
		(layer "In11.Cu")
		(net "M_F_CPU0_SA_DQ<18>")
	)
	(segment
		(start 289.832034 -217.310208)
		(end 290.682172 -216.46007)
		(width 0.14478)
		(layer "In11.Cu")
		(net "M_F_CPU0_SA_DQ<18>")
	)
	(segment
		(start 268.175486 -217.310208)
		(end 274.667726 -217.310208)
		(width 0.14478)
		(layer "In11.Cu")
		(net "M_F_CPU0_SA_DQ<18>")
	)
	(segment
		(start 279.33396 -217.310208)
		(end 282.298648 -217.310208)
		(width 0.14478)
		(layer "In11.Cu")
		(net "M_F_CPU0_SA_DQ<18>")
	)
	(segment
		(start 331.229716 -235.246672)
		(end 331.238098 -235.251498)
		(width 0.0889)
		(layer "In11.Cu")
		(net "M_F_CPU0_SA_DQ<18>")
	)
	(segment
		(start 286.903414 -217.310208)
		(end 289.832034 -217.310208)
		(width 0.14478)
		(layer "In11.Cu")
		(net "M_F_CPU0_SA_DQ<18>")
	)
	(segment
		(start 301.095156 -216.46007)
		(end 301.945294 -217.310208)
		(width 0.14478)
		(layer "In11.Cu")
		(net "M_F_CPU0_SA_DQ<18>")
	)
	(segment
		(start 282.298648 -217.310208)
		(end 283.148786 -216.46007)
		(width 0.14478)
		(layer "In11.Cu")
		(net "M_F_CPU0_SA_DQ<18>")
	)
	(segment
		(start 327.478898 -235.251752)
		(end 327.490836 -235.25861)
		(width 0.0889)
		(layer "In11.Cu")
		(net "M_F_CPU0_SA_DQ<18>")
	)
	(segment
		(start 274.667726 -217.310208)
		(end 275.517864 -216.46007)
		(width 0.14478)
		(layer "In11.Cu")
		(net "M_F_CPU0_SA_DQ<18>")
	)
	(segment
		(start 322.371466 -233.25709)
		(end 323.568314 -233.25709)
		(width 0.14478)
		(layer "In11.Cu")
		(net "M_F_CPU0_SA_DQ<18>")
	)
	(segment
		(start 297.32986 -217.310208)
		(end 298.179998 -216.46007)
		(width 0.14478)
		(layer "In11.Cu")
		(net "M_F_CPU0_SA_DQ<18>")
	)
	(segment
		(start 307.57241 -216.46007)
		(end 307.821838 -216.709498)
		(width 0.14478)
		(layer "In11.Cu")
		(net "M_F_CPU0_SA_DQ<18>")
	)
	(segment
		(start 265.54811 -216.885012)
		(end 265.973306 -217.310208)
		(width 0.14478)
		(layer "In11.Cu")
		(net "M_F_CPU0_SA_DQ<18>")
	)
	(segment
		(start 324.180454 -233.653838)
		(end 324.629526 -234.10291)
		(width 0.0889)
		(layer "In11.Cu")
		(net "M_F_CPU0_SA_DQ<18>")
	)
	(segment
		(start 332.145132 -235.308648)
		(end 331.991208 -235.574078)
		(width 0.0889)
		(layer "In11.Cu")
		(net "M_F_CPU0_SA_DQ<18>")
	)
	(segment
		(start 294.40886 -217.310208)
		(end 297.32986 -217.310208)
		(width 0.14478)
		(layer "In11.Cu")
		(net "M_F_CPU0_SA_DQ<18>")
	)
	(segment
		(start 275.517864 -216.46007)
		(end 278.483822 -216.46007)
		(width 0.14478)
		(layer "In11.Cu")
		(net "M_F_CPU0_SA_DQ<18>")
	)
	(segment
		(start 304.8762 -217.310208)
		(end 305.726338 -216.46007)
		(width 0.14478)
		(layer "In11.Cu")
		(net "M_F_CPU0_SA_DQ<18>")
	)
	(segment
		(start 326.083676 -235.20146)
		(end 326.089518 -235.20146)
		(width 0.0889)
		(layer "In11.Cu")
		(net "M_F_CPU0_SA_DQ<18>")
	)
	(segment
		(start 324.985126 -234.10291)
		(end 326.083676 -235.20146)
		(width 0.0889)
		(layer "In11.Cu")
		(net "M_F_CPU0_SA_DQ<18>")
	)
	(segment
		(start 305.726338 -216.46007)
		(end 307.57241 -216.46007)
		(width 0.14478)
		(layer "In11.Cu")
		(net "M_F_CPU0_SA_DQ<18>")
	)
	(segment
		(start 313.001914 -223.887538)
		(end 322.371466 -233.25709)
		(width 0.14478)
		(layer "In11.Cu")
		(net "M_F_CPU0_SA_DQ<18>")
	)
	(segment
		(start 324.180454 -233.54411)
		(end 324.180454 -233.653838)
		(width 0.0889)
		(layer "In11.Cu")
		(net "M_F_CPU0_SA_DQ<18>")
	)
	(segment
		(start 290.682172 -216.46007)
		(end 293.558722 -216.46007)
		(width 0.14478)
		(layer "In11.Cu")
		(net "M_F_CPU0_SA_DQ<18>")
	)
	(segment
		(start 268.00937 -217.144092)
		(end 268.175486 -217.310208)
		(width 0.14478)
		(layer "In11.Cu")
		(net "M_F_CPU0_SA_DQ<18>")
	)
	(segment
		(start 307.821838 -216.709498)
		(end 307.821838 -217.486738)
		(width 0.14478)
		(layer "In11.Cu")
		(net "M_F_CPU0_SA_DQ<18>")
	)
	(segment
		(start 278.483822 -216.46007)
		(end 279.33396 -217.310208)
		(width 0.14478)
		(layer "In11.Cu")
		(net "M_F_CPU0_SA_DQ<18>")
	)
	(segment
		(start 298.179998 -216.46007)
		(end 301.095156 -216.46007)
		(width 0.14478)
		(layer "In11.Cu")
		(net "M_F_CPU0_SA_DQ<18>")
	)
	(segment
		(start 267.624052 -217.144092)
		(end 268.00937 -217.144092)
		(width 0.14478)
		(layer "In11.Cu")
		(net "M_F_CPU0_SA_DQ<18>")
	)
	(segment
		(start 293.558722 -216.46007)
		(end 294.40886 -217.310208)
		(width 0.14478)
		(layer "In11.Cu")
		(net "M_F_CPU0_SA_DQ<18>")
	)
	(arc
		(start 327.490836 -235.25861)
		(mid 327.76837 -235.327591)
		(end 328.044048 -235.251498)
		(width 0.0889)
		(layer "In11.Cu")
		(net "M_F_CPU0_SA_DQ<18>")
	)
	(arc
		(start 326.53859 -235.251498)
		(mid 326.811534 -235.328078)
		(end 327.08723 -235.262166)
		(width 0.0889)
		(layer "In11.Cu")
		(net "M_F_CPU0_SA_DQ<18>")
	)
	(arc
		(start 327.105264 -235.251498)
		(mid 327.284251 -235.201328)
		(end 327.465182 -235.243878)
		(width 0.0889)
		(layer "In11.Cu")
		(net "M_F_CPU0_SA_DQ<18>")
	)
	(arc
		(start 331.238098 -235.251498)
		(mid 331.521054 -235.327675)
		(end 331.80401 -235.251498)
		(width 0.0889)
		(layer "In11.Cu")
		(net "M_F_CPU0_SA_DQ<18>")
	)
	(arc
		(start 328.992484 -235.246672)
		(mid 329.175992 -235.201178)
		(end 329.358244 -235.251498)
		(width 0.0889)
		(layer "In11.Cu")
		(net "M_F_CPU0_SA_DQ<18>")
	)
	(arc
		(start 329.358244 -235.251498)
		(mid 329.6412 -235.327675)
		(end 329.924156 -235.251498)
		(width 0.0889)
		(layer "In11.Cu")
		(net "M_F_CPU0_SA_DQ<18>")
	)
	(arc
		(start 329.924156 -235.251498)
		(mid 330.1111 -235.201243)
		(end 330.298044 -235.251498)
		(width 0.0889)
		(layer "In11.Cu")
		(net "M_F_CPU0_SA_DQ<18>")
	)
	(arc
		(start 330.298044 -235.251498)
		(mid 330.581 -235.327675)
		(end 330.863956 -235.251498)
		(width 0.0889)
		(layer "In11.Cu")
		(net "M_F_CPU0_SA_DQ<18>")
	)
	(arc
		(start 331.80401 -235.251498)
		(mid 331.960448 -235.202527)
		(end 332.12278 -235.225336)
		(width 0.0889)
		(layer "In11.Cu")
		(net "M_F_CPU0_SA_DQ<18>")
	)
	(arc
		(start 328.41819 -235.251498)
		(mid 328.701146 -235.327675)
		(end 328.984102 -235.251498)
		(width 0.0889)
		(layer "In11.Cu")
		(net "M_F_CPU0_SA_DQ<18>")
	)
	(arc
		(start 328.044048 -235.251498)
		(mid 328.226299 -235.201148)
		(end 328.409808 -235.246672)
		(width 0.0889)
		(layer "In11.Cu")
		(net "M_F_CPU0_SA_DQ<18>")
	)
	(arc
		(start 330.863956 -235.251498)
		(mid 331.046207 -235.201148)
		(end 331.229716 -235.246672)
		(width 0.0889)
		(layer "In11.Cu")
		(net "M_F_CPU0_SA_DQ<18>")
	)
	(arc
		(start 326.351392 -235.201206)
		(mid 326.448324 -235.213957)
		(end 326.53859 -235.251498)
		(width 0.0889)
		(layer "In11.Cu")
		(net "M_F_CPU0_SA_DQ<18>")
	)
	(segment
		(start 334.337914 -235.840016)
		(end 333.871062 -235.574078)
		(width 0.10668)
		(layer "F.Cu")
		(net "M_F_CPU0_SA_DQ<17>")
	)
	(segment
		(start 323.568314 -233.71175)
		(end 323.888354 -233.71175)
		(width 0.0889)
		(layer "In11.Cu")
		(net "M_F_CPU0_SA_DQ<17>")
	)
	(segment
		(start 288.733484 -218.160092)
		(end 288.896552 -218.32316)
		(width 0.14478)
		(layer "In11.Cu")
		(net "M_F_CPU0_SA_DQ<17>")
	)
	(segment
		(start 274.315682 -218.32316)
		(end 274.47875 -218.160092)
		(width 0.14478)
		(layer "In11.Cu")
		(net "M_F_CPU0_SA_DQ<17>")
	)
	(segment
		(start 289.304476 -218.541092)
		(end 289.453066 -218.392502)
		(width 0.14478)
		(layer "In11.Cu")
		(net "M_F_CPU0_SA_DQ<17>")
	)
	(segment
		(start 278.410924 -217.310208)
		(end 279.260808 -218.160092)
		(width 0.14478)
		(layer "In11.Cu")
		(net "M_F_CPU0_SA_DQ<17>")
	)
	(segment
		(start 324.635114 -234.45851)
		(end 325.018654 -234.45851)
		(width 0.0889)
		(layer "In11.Cu")
		(net "M_F_CPU0_SA_DQ<17>")
	)
	(segment
		(start 272.174208 -218.160092)
		(end 273.5961 -218.160092)
		(width 0.14478)
		(layer "In11.Cu")
		(net "M_F_CPU0_SA_DQ<17>")
	)
	(segment
		(start 332.744064 -235.896658)
		(end 332.752446 -235.901484)
		(width 0.0889)
		(layer "In11.Cu")
		(net "M_F_CPU0_SA_DQ<17>")
	)
	(segment
		(start 328.409808 -235.901484)
		(end 328.41819 -235.896658)
		(width 0.0889)
		(layer "In11.Cu")
		(net "M_F_CPU0_SA_DQ<17>")
	)
	(segment
		(start 284.198568 -217.539062)
		(end 284.198568 -217.473276)
		(width 0.14478)
		(layer "In11.Cu")
		(net "M_F_CPU0_SA_DQ<17>")
	)
	(segment
		(start 298.742608 -217.539062)
		(end 298.888658 -217.685112)
		(width 0.14478)
		(layer "In11.Cu")
		(net "M_F_CPU0_SA_DQ<17>")
	)
	(segment
		(start 274.754848 -218.160092)
		(end 275.604732 -217.310208)
		(width 0.14478)
		(layer "In11.Cu")
		(net "M_F_CPU0_SA_DQ<17>")
	)
	(segment
		(start 276.621748 -217.539062)
		(end 276.621748 -217.473276)
		(width 0.14478)
		(layer "In11.Cu")
		(net "M_F_CPU0_SA_DQ<17>")
	)
	(segment
		(start 289.883088 -218.160092)
		(end 290.732972 -217.310208)
		(width 0.14478)
		(layer "In11.Cu")
		(net "M_F_CPU0_SA_DQ<17>")
	)
	(segment
		(start 325.323454 -235.073952)
		(end 326.087486 -235.837984)
		(width 0.0889)
		(layer "In11.Cu")
		(net "M_F_CPU0_SA_DQ<17>")
	)
	(segment
		(start 291.1475 -217.539062)
		(end 291.30625 -217.697812)
		(width 0.14478)
		(layer "In11.Cu")
		(net "M_F_CPU0_SA_DQ<17>")
	)
	(segment
		(start 290.732972 -217.310208)
		(end 290.984432 -217.310208)
		(width 0.14478)
		(layer "In11.Cu")
		(net "M_F_CPU0_SA_DQ<17>")
	)
	(segment
		(start 288.896552 -218.32316)
		(end 288.896552 -218.392502)
		(width 0.14478)
		(layer "In11.Cu")
		(net "M_F_CPU0_SA_DQ<17>")
	)
	(segment
		(start 296.97045 -218.32316)
		(end 297.133518 -218.160092)
		(width 0.14478)
		(layer "In11.Cu")
		(net "M_F_CPU0_SA_DQ<17>")
	)
	(segment
		(start 289.616134 -218.160092)
		(end 289.883088 -218.160092)
		(width 0.14478)
		(layer "In11.Cu")
		(net "M_F_CPU0_SA_DQ<17>")
	)
	(segment
		(start 296.250868 -218.160092)
		(end 296.413936 -218.32316)
		(width 0.14478)
		(layer "In11.Cu")
		(net "M_F_CPU0_SA_DQ<17>")
	)
	(segment
		(start 270.07312 -218.160092)
		(end 271.439894 -218.160092)
		(width 0.14478)
		(layer "In11.Cu")
		(net "M_F_CPU0_SA_DQ<17>")
	)
	(segment
		(start 271.439894 -218.160092)
		(end 271.622774 -218.342972)
		(width 0.14478)
		(layer "In11.Cu")
		(net "M_F_CPU0_SA_DQ<17>")
	)
	(segment
		(start 299.299122 -217.539062)
		(end 299.299122 -217.473276)
		(width 0.14478)
		(layer "In11.Cu")
		(net "M_F_CPU0_SA_DQ<17>")
	)
	(segment
		(start 274.164552 -218.543632)
		(end 274.315682 -218.392502)
		(width 0.14478)
		(layer "In11.Cu")
		(net "M_F_CPU0_SA_DQ<17>")
	)
	(segment
		(start 297.389042 -218.160092)
		(end 298.238926 -217.310208)
		(width 0.14478)
		(layer "In11.Cu")
		(net "M_F_CPU0_SA_DQ<17>")
	)
	(segment
		(start 283.478986 -217.310208)
		(end 283.642054 -217.473276)
		(width 0.14478)
		(layer "In11.Cu")
		(net "M_F_CPU0_SA_DQ<17>")
	)
	(segment
		(start 325.018654 -234.45851)
		(end 325.323454 -234.76331)
		(width 0.0889)
		(layer "In11.Cu")
		(net "M_F_CPU0_SA_DQ<17>")
	)
	(segment
		(start 298.57954 -217.310208)
		(end 298.742608 -217.473276)
		(width 0.14478)
		(layer "In11.Cu")
		(net "M_F_CPU0_SA_DQ<17>")
	)
	(segment
		(start 296.413936 -218.391232)
		(end 296.558716 -218.536012)
		(width 0.14478)
		(layer "In11.Cu")
		(net "M_F_CPU0_SA_DQ<17>")
	)
	(segment
		(start 289.045142 -218.541092)
		(end 289.304476 -218.541092)
		(width 0.14478)
		(layer "In11.Cu")
		(net "M_F_CPU0_SA_DQ<17>")
	)
	(segment
		(start 291.30625 -217.697812)
		(end 291.545264 -217.697812)
		(width 0.14478)
		(layer "In11.Cu")
		(net "M_F_CPU0_SA_DQ<17>")
	)
	(segment
		(start 281.247596 -218.32316)
		(end 281.247596 -218.387422)
		(width 0.14478)
		(layer "In11.Cu")
		(net "M_F_CPU0_SA_DQ<17>")
	)
	(segment
		(start 323.888354 -233.71175)
		(end 324.635114 -234.45851)
		(width 0.0889)
		(layer "In11.Cu")
		(net "M_F_CPU0_SA_DQ<17>")
	)
	(segment
		(start 296.413936 -218.32316)
		(end 296.413936 -218.391232)
		(width 0.14478)
		(layer "In11.Cu")
		(net "M_F_CPU0_SA_DQ<17>")
	)
	(segment
		(start 274.315682 -218.392502)
		(end 274.315682 -218.32316)
		(width 0.14478)
		(layer "In11.Cu")
		(net "M_F_CPU0_SA_DQ<17>")
	)
	(segment
		(start 279.260808 -218.160092)
		(end 281.084528 -218.160092)
		(width 0.14478)
		(layer "In11.Cu")
		(net "M_F_CPU0_SA_DQ<17>")
	)
	(segment
		(start 281.247596 -218.387422)
		(end 281.410664 -218.55049)
		(width 0.14478)
		(layer "In11.Cu")
		(net "M_F_CPU0_SA_DQ<17>")
	)
	(segment
		(start 276.621748 -217.473276)
		(end 276.784816 -217.310208)
		(width 0.14478)
		(layer "In11.Cu")
		(net "M_F_CPU0_SA_DQ<17>")
	)
	(segment
		(start 301.90186 -218.160092)
		(end 304.894742 -218.160092)
		(width 0.14478)
		(layer "In11.Cu")
		(net "M_F_CPU0_SA_DQ<17>")
	)
	(segment
		(start 283.17317 -217.310208)
		(end 283.478986 -217.310208)
		(width 0.14478)
		(layer "In11.Cu")
		(net "M_F_CPU0_SA_DQ<17>")
	)
	(segment
		(start 269.648178 -217.73515)
		(end 270.07312 -218.160092)
		(width 0.14478)
		(layer "In11.Cu")
		(net "M_F_CPU0_SA_DQ<17>")
	)
	(segment
		(start 312.526934 -224.055686)
		(end 322.182998 -233.71175)
		(width 0.14478)
		(layer "In11.Cu")
		(net "M_F_CPU0_SA_DQ<17>")
	)
	(segment
		(start 276.065234 -217.473276)
		(end 276.065234 -217.539062)
		(width 0.14478)
		(layer "In11.Cu")
		(net "M_F_CPU0_SA_DQ<17>")
	)
	(segment
		(start 284.037278 -217.700352)
		(end 284.198568 -217.539062)
		(width 0.14478)
		(layer "In11.Cu")
		(net "M_F_CPU0_SA_DQ<17>")
	)
	(segment
		(start 298.742608 -217.473276)
		(end 298.742608 -217.539062)
		(width 0.14478)
		(layer "In11.Cu")
		(net "M_F_CPU0_SA_DQ<17>")
	)
	(segment
		(start 293.507922 -217.310208)
		(end 294.357806 -218.160092)
		(width 0.14478)
		(layer "In11.Cu")
		(net "M_F_CPU0_SA_DQ<17>")
	)
	(segment
		(start 276.784816 -217.310208)
		(end 278.410924 -217.310208)
		(width 0.14478)
		(layer "In11.Cu")
		(net "M_F_CPU0_SA_DQ<17>")
	)
	(segment
		(start 306.977288 -217.310208)
		(end 312.526934 -222.859854)
		(width 0.14478)
		(layer "In11.Cu")
		(net "M_F_CPU0_SA_DQ<17>")
	)
	(segment
		(start 273.759168 -218.32316)
		(end 273.759168 -218.392502)
		(width 0.14478)
		(layer "In11.Cu")
		(net "M_F_CPU0_SA_DQ<17>")
	)
	(segment
		(start 285.892748 -217.310208)
		(end 286.742632 -218.160092)
		(width 0.14478)
		(layer "In11.Cu")
		(net "M_F_CPU0_SA_DQ<17>")
	)
	(segment
		(start 281.967178 -218.160092)
		(end 282.323286 -218.160092)
		(width 0.14478)
		(layer "In11.Cu")
		(net "M_F_CPU0_SA_DQ<17>")
	)
	(segment
		(start 281.80411 -218.387422)
		(end 281.80411 -218.32316)
		(width 0.14478)
		(layer "In11.Cu")
		(net "M_F_CPU0_SA_DQ<17>")
	)
	(segment
		(start 281.410664 -218.55049)
		(end 281.641042 -218.55049)
		(width 0.14478)
		(layer "In11.Cu")
		(net "M_F_CPU0_SA_DQ<17>")
	)
	(segment
		(start 291.545264 -217.697812)
		(end 291.704014 -217.539062)
		(width 0.14478)
		(layer "In11.Cu")
		(net "M_F_CPU0_SA_DQ<17>")
	)
	(segment
		(start 299.299122 -217.473276)
		(end 299.46219 -217.310208)
		(width 0.14478)
		(layer "In11.Cu")
		(net "M_F_CPU0_SA_DQ<17>")
	)
	(segment
		(start 274.47875 -218.160092)
		(end 274.754848 -218.160092)
		(width 0.14478)
		(layer "In11.Cu")
		(net "M_F_CPU0_SA_DQ<17>")
	)
	(segment
		(start 294.357806 -218.160092)
		(end 296.250868 -218.160092)
		(width 0.14478)
		(layer "In11.Cu")
		(net "M_F_CPU0_SA_DQ<17>")
	)
	(segment
		(start 291.704014 -217.539062)
		(end 291.704014 -217.473276)
		(width 0.14478)
		(layer "In11.Cu")
		(net "M_F_CPU0_SA_DQ<17>")
	)
	(segment
		(start 298.888658 -217.685112)
		(end 299.153072 -217.685112)
		(width 0.14478)
		(layer "In11.Cu")
		(net "M_F_CPU0_SA_DQ<17>")
	)
	(segment
		(start 276.065234 -217.539062)
		(end 276.213824 -217.687652)
		(width 0.14478)
		(layer "In11.Cu")
		(net "M_F_CPU0_SA_DQ<17>")
	)
	(segment
		(start 276.473158 -217.687652)
		(end 276.621748 -217.539062)
		(width 0.14478)
		(layer "In11.Cu")
		(net "M_F_CPU0_SA_DQ<17>")
	)
	(segment
		(start 332.16977 -235.901484)
		(end 332.178152 -235.896658)
		(width 0.0889)
		(layer "In11.Cu")
		(net "M_F_CPU0_SA_DQ<17>")
	)
	(segment
		(start 296.82567 -218.536012)
		(end 296.97045 -218.391232)
		(width 0.14478)
		(layer "In11.Cu")
		(net "M_F_CPU0_SA_DQ<17>")
	)
	(segment
		(start 291.1475 -217.473276)
		(end 291.1475 -217.539062)
		(width 0.14478)
		(layer "In11.Cu")
		(net "M_F_CPU0_SA_DQ<17>")
	)
	(segment
		(start 283.642054 -217.473276)
		(end 283.642054 -217.539062)
		(width 0.14478)
		(layer "In11.Cu")
		(net "M_F_CPU0_SA_DQ<17>")
	)
	(segment
		(start 273.910298 -218.543632)
		(end 274.164552 -218.543632)
		(width 0.14478)
		(layer "In11.Cu")
		(net "M_F_CPU0_SA_DQ<17>")
	)
	(segment
		(start 291.704014 -217.473276)
		(end 291.867082 -217.310208)
		(width 0.14478)
		(layer "In11.Cu")
		(net "M_F_CPU0_SA_DQ<17>")
	)
	(segment
		(start 289.453066 -218.32316)
		(end 289.616134 -218.160092)
		(width 0.14478)
		(layer "In11.Cu")
		(net "M_F_CPU0_SA_DQ<17>")
	)
	(segment
		(start 283.803344 -217.700352)
		(end 284.037278 -217.700352)
		(width 0.14478)
		(layer "In11.Cu")
		(net "M_F_CPU0_SA_DQ<17>")
	)
	(segment
		(start 281.641042 -218.55049)
		(end 281.80411 -218.387422)
		(width 0.14478)
		(layer "In11.Cu")
		(net "M_F_CPU0_SA_DQ<17>")
	)
	(segment
		(start 325.323454 -234.76331)
		(end 325.323454 -235.073952)
		(width 0.0889)
		(layer "In11.Cu")
		(net "M_F_CPU0_SA_DQ<17>")
	)
	(segment
		(start 275.604732 -217.310208)
		(end 275.902166 -217.310208)
		(width 0.14478)
		(layer "In11.Cu")
		(net "M_F_CPU0_SA_DQ<17>")
	)
	(segment
		(start 273.5961 -218.160092)
		(end 273.759168 -218.32316)
		(width 0.14478)
		(layer "In11.Cu")
		(net "M_F_CPU0_SA_DQ<17>")
	)
	(segment
		(start 296.558716 -218.536012)
		(end 296.82567 -218.536012)
		(width 0.14478)
		(layer "In11.Cu")
		(net "M_F_CPU0_SA_DQ<17>")
	)
	(segment
		(start 289.453066 -218.392502)
		(end 289.453066 -218.32316)
		(width 0.14478)
		(layer "In11.Cu")
		(net "M_F_CPU0_SA_DQ<17>")
	)
	(segment
		(start 273.759168 -218.392502)
		(end 273.910298 -218.543632)
		(width 0.14478)
		(layer "In11.Cu")
		(net "M_F_CPU0_SA_DQ<17>")
	)
	(segment
		(start 328.033634 -235.890562)
		(end 328.044048 -235.896658)
		(width 0.0889)
		(layer "In11.Cu")
		(net "M_F_CPU0_SA_DQ<17>")
	)
	(segment
		(start 298.238926 -217.310208)
		(end 298.57954 -217.310208)
		(width 0.14478)
		(layer "In11.Cu")
		(net "M_F_CPU0_SA_DQ<17>")
	)
	(segment
		(start 301.051976 -217.310208)
		(end 301.90186 -218.160092)
		(width 0.14478)
		(layer "In11.Cu")
		(net "M_F_CPU0_SA_DQ<17>")
	)
	(segment
		(start 286.742632 -218.160092)
		(end 288.733484 -218.160092)
		(width 0.14478)
		(layer "In11.Cu")
		(net "M_F_CPU0_SA_DQ<17>")
	)
	(segment
		(start 296.97045 -218.391232)
		(end 296.97045 -218.32316)
		(width 0.14478)
		(layer "In11.Cu")
		(net "M_F_CPU0_SA_DQ<17>")
	)
	(segment
		(start 333.621126 -235.864908)
		(end 333.717138 -235.839508)
		(width 0.0889)
		(layer "In11.Cu")
		(net "M_F_CPU0_SA_DQ<17>")
	)
	(segment
		(start 288.896552 -218.392502)
		(end 289.045142 -218.541092)
		(width 0.14478)
		(layer "In11.Cu")
		(net "M_F_CPU0_SA_DQ<17>")
	)
	(segment
		(start 326.52335 -235.90504)
		(end 326.548242 -235.890562)
		(width 0.0889)
		(layer "In11.Cu")
		(net "M_F_CPU0_SA_DQ<17>")
	)
	(segment
		(start 291.867082 -217.310208)
		(end 293.507922 -217.310208)
		(width 0.14478)
		(layer "In11.Cu")
		(net "M_F_CPU0_SA_DQ<17>")
	)
	(segment
		(start 281.084528 -218.160092)
		(end 281.247596 -218.32316)
		(width 0.14478)
		(layer "In11.Cu")
		(net "M_F_CPU0_SA_DQ<17>")
	)
	(segment
		(start 322.182998 -233.71175)
		(end 323.568314 -233.71175)
		(width 0.14478)
		(layer "In11.Cu")
		(net "M_F_CPU0_SA_DQ<17>")
	)
	(segment
		(start 284.198568 -217.473276)
		(end 284.361636 -217.310208)
		(width 0.14478)
		(layer "In11.Cu")
		(net "M_F_CPU0_SA_DQ<17>")
	)
	(segment
		(start 271.991328 -218.342972)
		(end 272.174208 -218.160092)
		(width 0.14478)
		(layer "In11.Cu")
		(net "M_F_CPU0_SA_DQ<17>")
	)
	(segment
		(start 333.717138 -235.839508)
		(end 333.871062 -235.574078)
		(width 0.0889)
		(layer "In11.Cu")
		(net "M_F_CPU0_SA_DQ<17>")
	)
	(segment
		(start 284.361636 -217.310208)
		(end 285.892748 -217.310208)
		(width 0.14478)
		(layer "In11.Cu")
		(net "M_F_CPU0_SA_DQ<17>")
	)
	(segment
		(start 304.894742 -218.160092)
		(end 305.744626 -217.310208)
		(width 0.14478)
		(layer "In11.Cu")
		(net "M_F_CPU0_SA_DQ<17>")
	)
	(segment
		(start 282.323286 -218.160092)
		(end 283.17317 -217.310208)
		(width 0.14478)
		(layer "In11.Cu")
		(net "M_F_CPU0_SA_DQ<17>")
	)
	(segment
		(start 299.153072 -217.685112)
		(end 299.299122 -217.539062)
		(width 0.14478)
		(layer "In11.Cu")
		(net "M_F_CPU0_SA_DQ<17>")
	)
	(segment
		(start 283.642054 -217.539062)
		(end 283.803344 -217.700352)
		(width 0.14478)
		(layer "In11.Cu")
		(net "M_F_CPU0_SA_DQ<17>")
	)
	(segment
		(start 281.80411 -218.32316)
		(end 281.967178 -218.160092)
		(width 0.14478)
		(layer "In11.Cu")
		(net "M_F_CPU0_SA_DQ<17>")
	)
	(segment
		(start 312.526934 -222.859854)
		(end 312.526934 -224.055686)
		(width 0.14478)
		(layer "In11.Cu")
		(net "M_F_CPU0_SA_DQ<17>")
	)
	(segment
		(start 331.229716 -235.901484)
		(end 331.238098 -235.896658)
		(width 0.0889)
		(layer "In11.Cu")
		(net "M_F_CPU0_SA_DQ<17>")
	)
	(segment
		(start 276.213824 -217.687652)
		(end 276.473158 -217.687652)
		(width 0.14478)
		(layer "In11.Cu")
		(net "M_F_CPU0_SA_DQ<17>")
	)
	(segment
		(start 305.744626 -217.310208)
		(end 306.977288 -217.310208)
		(width 0.14478)
		(layer "In11.Cu")
		(net "M_F_CPU0_SA_DQ<17>")
	)
	(segment
		(start 271.622774 -218.342972)
		(end 271.991328 -218.342972)
		(width 0.14478)
		(layer "In11.Cu")
		(net "M_F_CPU0_SA_DQ<17>")
	)
	(segment
		(start 275.902166 -217.310208)
		(end 276.065234 -217.473276)
		(width 0.14478)
		(layer "In11.Cu")
		(net "M_F_CPU0_SA_DQ<17>")
	)
	(segment
		(start 290.984432 -217.310208)
		(end 291.1475 -217.473276)
		(width 0.14478)
		(layer "In11.Cu")
		(net "M_F_CPU0_SA_DQ<17>")
	)
	(segment
		(start 299.46219 -217.310208)
		(end 301.051976 -217.310208)
		(width 0.14478)
		(layer "In11.Cu")
		(net "M_F_CPU0_SA_DQ<17>")
	)
	(segment
		(start 328.984102 -235.896658)
		(end 328.992484 -235.901484)
		(width 0.0889)
		(layer "In11.Cu")
		(net "M_F_CPU0_SA_DQ<17>")
	)
	(segment
		(start 297.133518 -218.160092)
		(end 297.389042 -218.160092)
		(width 0.14478)
		(layer "In11.Cu")
		(net "M_F_CPU0_SA_DQ<17>")
	)
	(arc
		(start 332.752446 -235.901484)
		(mid 332.935954 -235.946978)
		(end 333.118206 -235.896658)
		(width 0.0889)
		(layer "In11.Cu")
		(net "M_F_CPU0_SA_DQ<17>")
	)
	(arc
		(start 330.863956 -235.896658)
		(mid 331.046207 -235.947008)
		(end 331.229716 -235.901484)
		(width 0.0889)
		(layer "In11.Cu")
		(net "M_F_CPU0_SA_DQ<17>")
	)
	(arc
		(start 327.477882 -235.896658)
		(mid 327.754949 -235.820387)
		(end 328.033634 -235.890562)
		(width 0.0889)
		(layer "In11.Cu")
		(net "M_F_CPU0_SA_DQ<17>")
	)
	(arc
		(start 327.103486 -235.896658)
		(mid 327.290684 -235.94704)
		(end 327.477882 -235.896658)
		(width 0.0889)
		(layer "In11.Cu")
		(net "M_F_CPU0_SA_DQ<17>")
	)
	(arc
		(start 326.087486 -235.837984)
		(mid 326.294445 -235.942785)
		(end 326.52335 -235.90504)
		(width 0.0889)
		(layer "In11.Cu")
		(net "M_F_CPU0_SA_DQ<17>")
	)
	(arc
		(start 328.044048 -235.896658)
		(mid 328.226299 -235.947008)
		(end 328.409808 -235.901484)
		(width 0.0889)
		(layer "In11.Cu")
		(net "M_F_CPU0_SA_DQ<17>")
	)
	(arc
		(start 332.178152 -235.896658)
		(mid 332.461108 -235.820481)
		(end 332.744064 -235.896658)
		(width 0.0889)
		(layer "In11.Cu")
		(net "M_F_CPU0_SA_DQ<17>")
	)
	(arc
		(start 329.924156 -235.896658)
		(mid 330.1111 -235.946913)
		(end 330.298044 -235.896658)
		(width 0.0889)
		(layer "In11.Cu")
		(net "M_F_CPU0_SA_DQ<17>")
	)
	(arc
		(start 328.992484 -235.901484)
		(mid 329.175992 -235.946978)
		(end 329.358244 -235.896658)
		(width 0.0889)
		(layer "In11.Cu")
		(net "M_F_CPU0_SA_DQ<17>")
	)
	(arc
		(start 328.41819 -235.896658)
		(mid 328.701146 -235.820481)
		(end 328.984102 -235.896658)
		(width 0.0889)
		(layer "In11.Cu")
		(net "M_F_CPU0_SA_DQ<17>")
	)
	(arc
		(start 330.298044 -235.896658)
		(mid 330.581 -235.820481)
		(end 330.863956 -235.896658)
		(width 0.0889)
		(layer "In11.Cu")
		(net "M_F_CPU0_SA_DQ<17>")
	)
	(arc
		(start 331.80401 -235.896658)
		(mid 331.986261 -235.947008)
		(end 332.16977 -235.901484)
		(width 0.0889)
		(layer "In11.Cu")
		(net "M_F_CPU0_SA_DQ<17>")
	)
	(arc
		(start 326.548242 -235.890562)
		(mid 326.826674 -235.820464)
		(end 327.103486 -235.896658)
		(width 0.0889)
		(layer "In11.Cu")
		(net "M_F_CPU0_SA_DQ<17>")
	)
	(arc
		(start 329.358244 -235.896658)
		(mid 329.6412 -235.820481)
		(end 329.924156 -235.896658)
		(width 0.0889)
		(layer "In11.Cu")
		(net "M_F_CPU0_SA_DQ<17>")
	)
	(arc
		(start 333.118206 -235.896658)
		(mid 333.365919 -235.821438)
		(end 333.621126 -235.864908)
		(width 0.0889)
		(layer "In11.Cu")
		(net "M_F_CPU0_SA_DQ<17>")
	)
	(arc
		(start 331.238098 -235.896658)
		(mid 331.521054 -235.820481)
		(end 331.80401 -235.896658)
		(width 0.0889)
		(layer "In11.Cu")
		(net "M_F_CPU0_SA_DQ<17>")
	)
	(segment
		(start 332.92796 -235.03001)
		(end 332.461108 -234.764072)
		(width 0.10668)
		(layer "F.Cu")
		(net "M_F_CPU0_SA_DQ<16>")
	)
	(segment
		(start 281.779472 -216.623138)
		(end 281.94254 -216.46007)
		(width 0.14478)
		(layer "In11.Cu")
		(net "M_F_CPU0_SA_DQ<16>")
	)
	(segment
		(start 296.765472 -216.85377)
		(end 296.92854 -216.690702)
		(width 0.14478)
		(layer "In11.Cu")
		(net "M_F_CPU0_SA_DQ<16>")
	)
	(segment
		(start 276.541992 -215.99525)
		(end 276.70506 -215.832182)
		(width 0.14478)
		(layer "In11.Cu")
		(net "M_F_CPU0_SA_DQ<16>")
	)
	(segment
		(start 289.883088 -216.46007)
		(end 290.732972 -215.610186)
		(width 0.14478)
		(layer "In11.Cu")
		(net "M_F_CPU0_SA_DQ<16>")
	)
	(segment
		(start 272.03019 -216.618312)
		(end 272.188432 -216.46007)
		(width 0.14478)
		(layer "In11.Cu")
		(net "M_F_CPU0_SA_DQ<16>")
	)
	(segment
		(start 313.471814 -223.71431)
		(end 322.559934 -232.80243)
		(width 0.14478)
		(layer "In11.Cu")
		(net "M_F_CPU0_SA_DQ<16>")
	)
	(segment
		(start 324.388734 -233.26979)
		(end 324.388734 -233.57459)
		(width 0.0889)
		(layer "In11.Cu")
		(net "M_F_CPU0_SA_DQ<16>")
	)
	(segment
		(start 285.892748 -215.610186)
		(end 286.742632 -216.46007)
		(width 0.14478)
		(layer "In11.Cu")
		(net "M_F_CPU0_SA_DQ<16>")
	)
	(segment
		(start 274.25015 -216.623138)
		(end 274.413218 -216.46007)
		(width 0.14478)
		(layer "In11.Cu")
		(net "M_F_CPU0_SA_DQ<16>")
	)
	(segment
		(start 323.568314 -232.80243)
		(end 323.921374 -232.80243)
		(width 0.0889)
		(layer "In11.Cu")
		(net "M_F_CPU0_SA_DQ<16>")
	)
	(segment
		(start 276.70506 -215.773254)
		(end 276.868128 -215.610186)
		(width 0.14478)
		(layer "In11.Cu")
		(net "M_F_CPU0_SA_DQ<16>")
	)
	(segment
		(start 290.732972 -215.610186)
		(end 291.074094 -215.610186)
		(width 0.14478)
		(layer "In11.Cu")
		(net "M_F_CPU0_SA_DQ<16>")
	)
	(segment
		(start 273.693636 -216.623138)
		(end 273.693636 -216.683082)
		(width 0.14478)
		(layer "In11.Cu")
		(net "M_F_CPU0_SA_DQ<16>")
	)
	(segment
		(start 302.737774 -216.85377)
		(end 302.968152 -216.85377)
		(width 0.14478)
		(layer "In11.Cu")
		(net "M_F_CPU0_SA_DQ<16>")
	)
	(segment
		(start 296.92854 -216.623138)
		(end 297.091608 -216.46007)
		(width 0.14478)
		(layer "In11.Cu")
		(net "M_F_CPU0_SA_DQ<16>")
	)
	(segment
		(start 289.506914 -216.685622)
		(end 289.506914 -216.623138)
		(width 0.14478)
		(layer "In11.Cu")
		(net "M_F_CPU0_SA_DQ<16>")
	)
	(segment
		(start 308.296818 -216.219786)
		(end 308.296818 -217.255598)
		(width 0.14478)
		(layer "In11.Cu")
		(net "M_F_CPU0_SA_DQ<16>")
	)
	(segment
		(start 271.478756 -216.46007)
		(end 271.636998 -216.618312)
		(width 0.14478)
		(layer "In11.Cu")
		(net "M_F_CPU0_SA_DQ<16>")
	)
	(segment
		(start 323.921374 -232.80243)
		(end 324.388734 -233.26979)
		(width 0.0889)
		(layer "In11.Cu")
		(net "M_F_CPU0_SA_DQ<16>")
	)
	(segment
		(start 291.630608 -216.00033)
		(end 291.793676 -215.837262)
		(width 0.14478)
		(layer "In11.Cu")
		(net "M_F_CPU0_SA_DQ<16>")
	)
	(segment
		(start 291.237162 -215.773254)
		(end 291.237162 -215.837262)
		(width 0.14478)
		(layer "In11.Cu")
		(net "M_F_CPU0_SA_DQ<16>")
	)
	(segment
		(start 305.744626 -215.610186)
		(end 307.687218 -215.610186)
		(width 0.14478)
		(layer "In11.Cu")
		(net "M_F_CPU0_SA_DQ<16>")
	)
	(segment
		(start 271.636998 -216.618312)
		(end 272.03019 -216.618312)
		(width 0.14478)
		(layer "In11.Cu")
		(net "M_F_CPU0_SA_DQ<16>")
	)
	(segment
		(start 283.5148 -215.610186)
		(end 283.677868 -215.773254)
		(width 0.14478)
		(layer "In11.Cu")
		(net "M_F_CPU0_SA_DQ<16>")
	)
	(segment
		(start 303.13122 -216.690702)
		(end 303.13122 -216.623138)
		(width 0.14478)
		(layer "In11.Cu")
		(net "M_F_CPU0_SA_DQ<16>")
	)
	(segment
		(start 273.530568 -216.46007)
		(end 273.693636 -216.623138)
		(width 0.14478)
		(layer "In11.Cu")
		(net "M_F_CPU0_SA_DQ<16>")
	)
	(segment
		(start 283.677868 -215.773254)
		(end 283.677868 -215.842342)
		(width 0.14478)
		(layer "In11.Cu")
		(net "M_F_CPU0_SA_DQ<16>")
	)
	(segment
		(start 276.868128 -215.610186)
		(end 278.410924 -215.610186)
		(width 0.14478)
		(layer "In11.Cu")
		(net "M_F_CPU0_SA_DQ<16>")
	)
	(segment
		(start 283.17317 -215.610186)
		(end 283.5148 -215.610186)
		(width 0.14478)
		(layer "In11.Cu")
		(net "M_F_CPU0_SA_DQ<16>")
	)
	(segment
		(start 275.985478 -215.610186)
		(end 276.148546 -215.773254)
		(width 0.14478)
		(layer "In11.Cu")
		(net "M_F_CPU0_SA_DQ<16>")
	)
	(segment
		(start 296.372026 -216.690702)
		(end 296.535094 -216.85377)
		(width 0.14478)
		(layer "In11.Cu")
		(net "M_F_CPU0_SA_DQ<16>")
	)
	(segment
		(start 269.648178 -216.035128)
		(end 270.07312 -216.46007)
		(width 0.14478)
		(layer "In11.Cu")
		(net "M_F_CPU0_SA_DQ<16>")
	)
	(segment
		(start 298.706794 -215.773254)
		(end 298.706794 -215.837262)
		(width 0.14478)
		(layer "In11.Cu")
		(net "M_F_CPU0_SA_DQ<16>")
	)
	(segment
		(start 272.188432 -216.46007)
		(end 273.530568 -216.46007)
		(width 0.14478)
		(layer "In11.Cu")
		(net "M_F_CPU0_SA_DQ<16>")
	)
	(segment
		(start 302.411638 -216.46007)
		(end 302.574706 -216.623138)
		(width 0.14478)
		(layer "In11.Cu")
		(net "M_F_CPU0_SA_DQ<16>")
	)
	(segment
		(start 298.238926 -215.610186)
		(end 298.543726 -215.610186)
		(width 0.14478)
		(layer "In11.Cu")
		(net "M_F_CPU0_SA_DQ<16>")
	)
	(segment
		(start 276.148546 -215.832182)
		(end 276.311614 -215.99525)
		(width 0.14478)
		(layer "In11.Cu")
		(net "M_F_CPU0_SA_DQ<16>")
	)
	(segment
		(start 288.9504 -216.623138)
		(end 288.9504 -216.685622)
		(width 0.14478)
		(layer "In11.Cu")
		(net "M_F_CPU0_SA_DQ<16>")
	)
	(segment
		(start 330.394056 -235.086652)
		(end 330.402438 -235.091478)
		(width 0.0889)
		(layer "In11.Cu")
		(net "M_F_CPU0_SA_DQ<16>")
	)
	(segment
		(start 325.063612 -233.89971)
		(end 326.1741 -235.010198)
		(width 0.0889)
		(layer "In11.Cu")
		(net "M_F_CPU0_SA_DQ<16>")
	)
	(segment
		(start 313.471814 -222.430594)
		(end 313.471814 -223.71431)
		(width 0.14478)
		(layer "In11.Cu")
		(net "M_F_CPU0_SA_DQ<16>")
	)
	(segment
		(start 298.869862 -216.00033)
		(end 299.10024 -216.00033)
		(width 0.14478)
		(layer "In11.Cu")
		(net "M_F_CPU0_SA_DQ<16>")
	)
	(segment
		(start 289.669982 -216.46007)
		(end 289.883088 -216.46007)
		(width 0.14478)
		(layer "In11.Cu")
		(net "M_F_CPU0_SA_DQ<16>")
	)
	(segment
		(start 326.1741 -235.010198)
		(end 326.351138 -235.010198)
		(width 0.0889)
		(layer "In11.Cu")
		(net "M_F_CPU0_SA_DQ<16>")
	)
	(segment
		(start 299.10024 -216.00033)
		(end 299.263308 -215.837262)
		(width 0.14478)
		(layer "In11.Cu")
		(net "M_F_CPU0_SA_DQ<16>")
	)
	(segment
		(start 288.787332 -216.46007)
		(end 288.9504 -216.623138)
		(width 0.14478)
		(layer "In11.Cu")
		(net "M_F_CPU0_SA_DQ<16>")
	)
	(segment
		(start 293.507922 -215.610186)
		(end 294.357806 -216.46007)
		(width 0.14478)
		(layer "In11.Cu")
		(net "M_F_CPU0_SA_DQ<16>")
	)
	(segment
		(start 307.687218 -215.610186)
		(end 308.296818 -216.219786)
		(width 0.14478)
		(layer "In11.Cu")
		(net "M_F_CPU0_SA_DQ<16>")
	)
	(segment
		(start 291.074094 -215.610186)
		(end 291.237162 -215.773254)
		(width 0.14478)
		(layer "In11.Cu")
		(net "M_F_CPU0_SA_DQ<16>")
	)
	(segment
		(start 304.894742 -216.46007)
		(end 305.744626 -215.610186)
		(width 0.14478)
		(layer "In11.Cu")
		(net "M_F_CPU0_SA_DQ<16>")
	)
	(segment
		(start 329.819762 -235.091478)
		(end 329.828144 -235.086652)
		(width 0.0889)
		(layer "In11.Cu")
		(net "M_F_CPU0_SA_DQ<16>")
	)
	(segment
		(start 291.793676 -215.837262)
		(end 291.793676 -215.773254)
		(width 0.14478)
		(layer "In11.Cu")
		(net "M_F_CPU0_SA_DQ<16>")
	)
	(segment
		(start 291.40023 -216.00033)
		(end 291.630608 -216.00033)
		(width 0.14478)
		(layer "In11.Cu")
		(net "M_F_CPU0_SA_DQ<16>")
	)
	(segment
		(start 324.713854 -233.89971)
		(end 325.063612 -233.89971)
		(width 0.0889)
		(layer "In11.Cu")
		(net "M_F_CPU0_SA_DQ<16>")
	)
	(segment
		(start 282.323286 -216.46007)
		(end 283.17317 -215.610186)
		(width 0.14478)
		(layer "In11.Cu")
		(net "M_F_CPU0_SA_DQ<16>")
	)
	(segment
		(start 298.706794 -215.837262)
		(end 298.869862 -216.00033)
		(width 0.14478)
		(layer "In11.Cu")
		(net "M_F_CPU0_SA_DQ<16>")
	)
	(segment
		(start 286.742632 -216.46007)
		(end 288.787332 -216.46007)
		(width 0.14478)
		(layer "In11.Cu")
		(net "M_F_CPU0_SA_DQ<16>")
	)
	(segment
		(start 288.9504 -216.685622)
		(end 289.113468 -216.84869)
		(width 0.14478)
		(layer "In11.Cu")
		(net "M_F_CPU0_SA_DQ<16>")
	)
	(segment
		(start 283.677868 -215.842342)
		(end 283.840936 -216.00541)
		(width 0.14478)
		(layer "In11.Cu")
		(net "M_F_CPU0_SA_DQ<16>")
	)
	(segment
		(start 332.307184 -235.029502)
		(end 332.461108 -234.764072)
		(width 0.0889)
		(layer "In11.Cu")
		(net "M_F_CPU0_SA_DQ<16>")
	)
	(segment
		(start 291.237162 -215.837262)
		(end 291.40023 -216.00033)
		(width 0.14478)
		(layer "In11.Cu")
		(net "M_F_CPU0_SA_DQ<16>")
	)
	(segment
		(start 308.296818 -217.255598)
		(end 313.471814 -222.430594)
		(width 0.14478)
		(layer "In11.Cu")
		(net "M_F_CPU0_SA_DQ<16>")
	)
	(segment
		(start 291.956744 -215.610186)
		(end 293.507922 -215.610186)
		(width 0.14478)
		(layer "In11.Cu")
		(net "M_F_CPU0_SA_DQ<16>")
	)
	(segment
		(start 302.574706 -216.623138)
		(end 302.574706 -216.690702)
		(width 0.14478)
		(layer "In11.Cu")
		(net "M_F_CPU0_SA_DQ<16>")
	)
	(segment
		(start 281.386026 -216.85377)
		(end 281.616404 -216.85377)
		(width 0.14478)
		(layer "In11.Cu")
		(net "M_F_CPU0_SA_DQ<16>")
	)
	(segment
		(start 284.39745 -215.610186)
		(end 285.892748 -215.610186)
		(width 0.14478)
		(layer "In11.Cu")
		(net "M_F_CPU0_SA_DQ<16>")
	)
	(segment
		(start 294.357806 -216.46007)
		(end 296.208958 -216.46007)
		(width 0.14478)
		(layer "In11.Cu")
		(net "M_F_CPU0_SA_DQ<16>")
	)
	(segment
		(start 278.410924 -215.610186)
		(end 279.260808 -216.46007)
		(width 0.14478)
		(layer "In11.Cu")
		(net "M_F_CPU0_SA_DQ<16>")
	)
	(segment
		(start 289.506914 -216.623138)
		(end 289.669982 -216.46007)
		(width 0.14478)
		(layer "In11.Cu")
		(net "M_F_CPU0_SA_DQ<16>")
	)
	(segment
		(start 302.574706 -216.690702)
		(end 302.737774 -216.85377)
		(width 0.14478)
		(layer "In11.Cu")
		(net "M_F_CPU0_SA_DQ<16>")
	)
	(segment
		(start 299.263308 -215.773254)
		(end 299.426376 -215.610186)
		(width 0.14478)
		(layer "In11.Cu")
		(net "M_F_CPU0_SA_DQ<16>")
	)
	(segment
		(start 270.07312 -216.46007)
		(end 271.478756 -216.46007)
		(width 0.14478)
		(layer "In11.Cu")
		(net "M_F_CPU0_SA_DQ<16>")
	)
	(segment
		(start 331.33411 -235.086652)
		(end 331.342492 -235.091478)
		(width 0.0889)
		(layer "In11.Cu")
		(net "M_F_CPU0_SA_DQ<16>")
	)
	(segment
		(start 297.389042 -216.46007)
		(end 298.238926 -215.610186)
		(width 0.14478)
		(layer "In11.Cu")
		(net "M_F_CPU0_SA_DQ<16>")
	)
	(segment
		(start 301.90186 -216.46007)
		(end 302.411638 -216.46007)
		(width 0.14478)
		(layer "In11.Cu")
		(net "M_F_CPU0_SA_DQ<16>")
	)
	(segment
		(start 297.091608 -216.46007)
		(end 297.389042 -216.46007)
		(width 0.14478)
		(layer "In11.Cu")
		(net "M_F_CPU0_SA_DQ<16>")
	)
	(segment
		(start 296.92854 -216.690702)
		(end 296.92854 -216.623138)
		(width 0.14478)
		(layer "In11.Cu")
		(net "M_F_CPU0_SA_DQ<16>")
	)
	(segment
		(start 301.051976 -215.610186)
		(end 301.90186 -216.46007)
		(width 0.14478)
		(layer "In11.Cu")
		(net "M_F_CPU0_SA_DQ<16>")
	)
	(segment
		(start 332.211172 -235.054902)
		(end 332.307184 -235.029502)
		(width 0.0889)
		(layer "In11.Cu")
		(net "M_F_CPU0_SA_DQ<16>")
	)
	(segment
		(start 279.260808 -216.46007)
		(end 281.05989 -216.46007)
		(width 0.14478)
		(layer "In11.Cu")
		(net "M_F_CPU0_SA_DQ<16>")
	)
	(segment
		(start 296.372026 -216.623138)
		(end 296.372026 -216.690702)
		(width 0.14478)
		(layer "In11.Cu")
		(net "M_F_CPU0_SA_DQ<16>")
	)
	(segment
		(start 284.234382 -215.842342)
		(end 284.234382 -215.773254)
		(width 0.14478)
		(layer "In11.Cu")
		(net "M_F_CPU0_SA_DQ<16>")
	)
	(segment
		(start 327.562464 -235.07954)
		(end 327.574402 -235.086398)
		(width 0.0889)
		(layer "In11.Cu")
		(net "M_F_CPU0_SA_DQ<16>")
	)
	(segment
		(start 284.234382 -215.773254)
		(end 284.39745 -215.610186)
		(width 0.14478)
		(layer "In11.Cu")
		(net "M_F_CPU0_SA_DQ<16>")
	)
	(segment
		(start 274.413218 -216.46007)
		(end 274.754848 -216.46007)
		(width 0.14478)
		(layer "In11.Cu")
		(net "M_F_CPU0_SA_DQ<16>")
	)
	(segment
		(start 274.754848 -216.46007)
		(end 275.604732 -215.610186)
		(width 0.14478)
		(layer "In11.Cu")
		(net "M_F_CPU0_SA_DQ<16>")
	)
	(segment
		(start 302.968152 -216.85377)
		(end 303.13122 -216.690702)
		(width 0.14478)
		(layer "In11.Cu")
		(net "M_F_CPU0_SA_DQ<16>")
	)
	(segment
		(start 296.208958 -216.46007)
		(end 296.372026 -216.623138)
		(width 0.14478)
		(layer "In11.Cu")
		(net "M_F_CPU0_SA_DQ<16>")
	)
	(segment
		(start 327.574402 -235.086398)
		(end 327.590658 -235.095796)
		(width 0.0889)
		(layer "In11.Cu")
		(net "M_F_CPU0_SA_DQ<16>")
	)
	(segment
		(start 281.05989 -216.46007)
		(end 281.222958 -216.623138)
		(width 0.14478)
		(layer "In11.Cu")
		(net "M_F_CPU0_SA_DQ<16>")
	)
	(segment
		(start 276.148546 -215.773254)
		(end 276.148546 -215.832182)
		(width 0.14478)
		(layer "In11.Cu")
		(net "M_F_CPU0_SA_DQ<16>")
	)
	(segment
		(start 303.13122 -216.623138)
		(end 303.294288 -216.46007)
		(width 0.14478)
		(layer "In11.Cu")
		(net "M_F_CPU0_SA_DQ<16>")
	)
	(segment
		(start 281.222958 -216.690702)
		(end 281.386026 -216.85377)
		(width 0.14478)
		(layer "In11.Cu")
		(net "M_F_CPU0_SA_DQ<16>")
	)
	(segment
		(start 275.604732 -215.610186)
		(end 275.985478 -215.610186)
		(width 0.14478)
		(layer "In11.Cu")
		(net "M_F_CPU0_SA_DQ<16>")
	)
	(segment
		(start 326.997568 -235.09351)
		(end 327.009252 -235.086652)
		(width 0.0889)
		(layer "In11.Cu")
		(net "M_F_CPU0_SA_DQ<16>")
	)
	(segment
		(start 289.113468 -216.84869)
		(end 289.343846 -216.84869)
		(width 0.14478)
		(layer "In11.Cu")
		(net "M_F_CPU0_SA_DQ<16>")
	)
	(segment
		(start 324.388734 -233.57459)
		(end 324.713854 -233.89971)
		(width 0.0889)
		(layer "In11.Cu")
		(net "M_F_CPU0_SA_DQ<16>")
	)
	(segment
		(start 296.535094 -216.85377)
		(end 296.765472 -216.85377)
		(width 0.14478)
		(layer "In11.Cu")
		(net "M_F_CPU0_SA_DQ<16>")
	)
	(segment
		(start 289.343846 -216.84869)
		(end 289.506914 -216.685622)
		(width 0.14478)
		(layer "In11.Cu")
		(net "M_F_CPU0_SA_DQ<16>")
	)
	(segment
		(start 281.222958 -216.623138)
		(end 281.222958 -216.690702)
		(width 0.14478)
		(layer "In11.Cu")
		(net "M_F_CPU0_SA_DQ<16>")
	)
	(segment
		(start 276.311614 -215.99525)
		(end 276.541992 -215.99525)
		(width 0.14478)
		(layer "In11.Cu")
		(net "M_F_CPU0_SA_DQ<16>")
	)
	(segment
		(start 281.94254 -216.46007)
		(end 282.323286 -216.46007)
		(width 0.14478)
		(layer "In11.Cu")
		(net "M_F_CPU0_SA_DQ<16>")
	)
	(segment
		(start 274.25015 -216.683082)
		(end 274.25015 -216.623138)
		(width 0.14478)
		(layer "In11.Cu")
		(net "M_F_CPU0_SA_DQ<16>")
	)
	(segment
		(start 291.793676 -215.773254)
		(end 291.956744 -215.610186)
		(width 0.14478)
		(layer "In11.Cu")
		(net "M_F_CPU0_SA_DQ<16>")
	)
	(segment
		(start 276.70506 -215.832182)
		(end 276.70506 -215.773254)
		(width 0.14478)
		(layer "In11.Cu")
		(net "M_F_CPU0_SA_DQ<16>")
	)
	(segment
		(start 299.263308 -215.837262)
		(end 299.263308 -215.773254)
		(width 0.14478)
		(layer "In11.Cu")
		(net "M_F_CPU0_SA_DQ<16>")
	)
	(segment
		(start 274.087082 -216.84615)
		(end 274.25015 -216.683082)
		(width 0.14478)
		(layer "In11.Cu")
		(net "M_F_CPU0_SA_DQ<16>")
	)
	(segment
		(start 281.616404 -216.85377)
		(end 281.779472 -216.690702)
		(width 0.14478)
		(layer "In11.Cu")
		(net "M_F_CPU0_SA_DQ<16>")
	)
	(segment
		(start 273.856704 -216.84615)
		(end 274.087082 -216.84615)
		(width 0.14478)
		(layer "In11.Cu")
		(net "M_F_CPU0_SA_DQ<16>")
	)
	(segment
		(start 322.559934 -232.80243)
		(end 323.568314 -232.80243)
		(width 0.14478)
		(layer "In11.Cu")
		(net "M_F_CPU0_SA_DQ<16>")
	)
	(segment
		(start 298.543726 -215.610186)
		(end 298.706794 -215.773254)
		(width 0.14478)
		(layer "In11.Cu")
		(net "M_F_CPU0_SA_DQ<16>")
	)
	(segment
		(start 281.779472 -216.690702)
		(end 281.779472 -216.623138)
		(width 0.14478)
		(layer "In11.Cu")
		(net "M_F_CPU0_SA_DQ<16>")
	)
	(segment
		(start 284.071314 -216.00541)
		(end 284.234382 -215.842342)
		(width 0.14478)
		(layer "In11.Cu")
		(net "M_F_CPU0_SA_DQ<16>")
	)
	(segment
		(start 303.294288 -216.46007)
		(end 304.894742 -216.46007)
		(width 0.14478)
		(layer "In11.Cu")
		(net "M_F_CPU0_SA_DQ<16>")
	)
	(segment
		(start 299.426376 -215.610186)
		(end 301.051976 -215.610186)
		(width 0.14478)
		(layer "In11.Cu")
		(net "M_F_CPU0_SA_DQ<16>")
	)
	(segment
		(start 283.840936 -216.00541)
		(end 284.071314 -216.00541)
		(width 0.14478)
		(layer "In11.Cu")
		(net "M_F_CPU0_SA_DQ<16>")
	)
	(segment
		(start 273.693636 -216.683082)
		(end 273.856704 -216.84615)
		(width 0.14478)
		(layer "In11.Cu")
		(net "M_F_CPU0_SA_DQ<16>")
	)
	(arc
		(start 327.94829 -235.086652)
		(mid 328.231246 -235.010475)
		(end 328.514202 -235.086652)
		(width 0.0889)
		(layer "In11.Cu")
		(net "M_F_CPU0_SA_DQ<16>")
	)
	(arc
		(start 331.342492 -235.091478)
		(mid 331.526 -235.136972)
		(end 331.708252 -235.086652)
		(width 0.0889)
		(layer "In11.Cu")
		(net "M_F_CPU0_SA_DQ<16>")
	)
	(arc
		(start 330.402438 -235.091478)
		(mid 330.585946 -235.136972)
		(end 330.768198 -235.086652)
		(width 0.0889)
		(layer "In11.Cu")
		(net "M_F_CPU0_SA_DQ<16>")
	)
	(arc
		(start 326.634856 -235.086652)
		(mid 326.815314 -235.137096)
		(end 326.997568 -235.09351)
		(width 0.0889)
		(layer "In11.Cu")
		(net "M_F_CPU0_SA_DQ<16>")
	)
	(arc
		(start 328.514202 -235.086652)
		(mid 328.701146 -235.136907)
		(end 328.88809 -235.086652)
		(width 0.0889)
		(layer "In11.Cu")
		(net "M_F_CPU0_SA_DQ<16>")
	)
	(arc
		(start 330.768198 -235.086652)
		(mid 331.051154 -235.010475)
		(end 331.33411 -235.086652)
		(width 0.0889)
		(layer "In11.Cu")
		(net "M_F_CPU0_SA_DQ<16>")
	)
	(arc
		(start 327.590658 -235.095796)
		(mid 327.77064 -235.136896)
		(end 327.94829 -235.086652)
		(width 0.0889)
		(layer "In11.Cu")
		(net "M_F_CPU0_SA_DQ<16>")
	)
	(arc
		(start 329.828144 -235.086652)
		(mid 330.1111 -235.010475)
		(end 330.394056 -235.086652)
		(width 0.0889)
		(layer "In11.Cu")
		(net "M_F_CPU0_SA_DQ<16>")
	)
	(arc
		(start 326.351138 -235.010198)
		(mid 326.498069 -235.029609)
		(end 326.634856 -235.086652)
		(width 0.0889)
		(layer "In11.Cu")
		(net "M_F_CPU0_SA_DQ<16>")
	)
	(arc
		(start 328.88809 -235.086652)
		(mid 329.171046 -235.010475)
		(end 329.454002 -235.086652)
		(width 0.0889)
		(layer "In11.Cu")
		(net "M_F_CPU0_SA_DQ<16>")
	)
	(arc
		(start 331.708252 -235.086652)
		(mid 331.955965 -235.011432)
		(end 332.211172 -235.054902)
		(width 0.0889)
		(layer "In11.Cu")
		(net "M_F_CPU0_SA_DQ<16>")
	)
	(arc
		(start 327.009252 -235.086652)
		(mid 327.28493 -235.010522)
		(end 327.562464 -235.07954)
		(width 0.0889)
		(layer "In11.Cu")
		(net "M_F_CPU0_SA_DQ<16>")
	)
	(arc
		(start 329.454002 -235.086652)
		(mid 329.636253 -235.137002)
		(end 329.819762 -235.091478)
		(width 0.0889)
		(layer "In11.Cu")
		(net "M_F_CPU0_SA_DQ<16>")
	)
	(segment
		(start 333.868014 -235.03001)
		(end 333.401162 -234.764072)
		(width 0.10668)
		(layer "F.Cu")
		(net "M_F_CPU0_SA_DQ<15>")
	)
	(segment
		(start 327.007728 -234.441492)
		(end 327.018142 -234.447588)
		(width 0.0889)
		(layer "In11.Cu")
		(net "M_F_CPU0_SA_DQ<15>")
	)
	(segment
		(start 268.260322 -214.842598)
		(end 268.260322 -215.447118)
		(width 0.14478)
		(layer "In11.Cu")
		(net "M_F_CPU0_SA_DQ<15>")
	)
	(segment
		(start 325.116698 -233.223562)
		(end 325.116698 -233.516678)
		(width 0.0889)
		(layer "In11.Cu")
		(net "M_F_CPU0_SA_DQ<15>")
	)
	(segment
		(start 267.310362 -215.610186)
		(end 267.54074 -215.610186)
		(width 0.14478)
		(layer "In11.Cu")
		(net "M_F_CPU0_SA_DQ<15>")
	)
	(segment
		(start 290.682172 -214.760048)
		(end 293.558722 -214.760048)
		(width 0.14478)
		(layer "In11.Cu")
		(net "M_F_CPU0_SA_DQ<15>")
	)
	(segment
		(start 322.79717 -232.24617)
		(end 323.568314 -232.24617)
		(width 0.14478)
		(layer "In11.Cu")
		(net "M_F_CPU0_SA_DQ<15>")
	)
	(segment
		(start 330.394056 -234.441492)
		(end 330.402438 -234.436666)
		(width 0.0889)
		(layer "In11.Cu")
		(net "M_F_CPU0_SA_DQ<15>")
	)
	(segment
		(start 266.753848 -214.67953)
		(end 266.984226 -214.67953)
		(width 0.14478)
		(layer "In11.Cu")
		(net "M_F_CPU0_SA_DQ<15>")
	)
	(segment
		(start 331.33411 -234.441492)
		(end 331.342492 -234.436666)
		(width 0.0889)
		(layer "In11.Cu")
		(net "M_F_CPU0_SA_DQ<15>")
	)
	(segment
		(start 324.668642 -233.039666)
		(end 324.932802 -233.039666)
		(width 0.0889)
		(layer "In11.Cu")
		(net "M_F_CPU0_SA_DQ<15>")
	)
	(segment
		(start 326.63384 -234.441492)
		(end 326.645524 -234.434634)
		(width 0.0889)
		(layer "In11.Cu")
		(net "M_F_CPU0_SA_DQ<15>")
	)
	(segment
		(start 266.59078 -214.842598)
		(end 266.753848 -214.67953)
		(width 0.14478)
		(layer "In11.Cu")
		(net "M_F_CPU0_SA_DQ<15>")
	)
	(segment
		(start 282.298648 -215.610186)
		(end 283.148786 -214.760048)
		(width 0.14478)
		(layer "In11.Cu")
		(net "M_F_CPU0_SA_DQ<15>")
	)
	(segment
		(start 268.097254 -214.67953)
		(end 268.260322 -214.842598)
		(width 0.14478)
		(layer "In11.Cu")
		(net "M_F_CPU0_SA_DQ<15>")
	)
	(segment
		(start 314.030614 -223.479614)
		(end 322.79717 -232.24617)
		(width 0.14478)
		(layer "In11.Cu")
		(net "M_F_CPU0_SA_DQ<15>")
	)
	(segment
		(start 278.483822 -214.760048)
		(end 279.33396 -215.610186)
		(width 0.14478)
		(layer "In11.Cu")
		(net "M_F_CPU0_SA_DQ<15>")
	)
	(segment
		(start 304.8762 -215.610186)
		(end 305.726338 -214.760048)
		(width 0.14478)
		(layer "In11.Cu")
		(net "M_F_CPU0_SA_DQ<15>")
	)
	(segment
		(start 267.866876 -214.67953)
		(end 268.097254 -214.67953)
		(width 0.14478)
		(layer "In11.Cu")
		(net "M_F_CPU0_SA_DQ<15>")
	)
	(segment
		(start 286.903414 -215.610186)
		(end 289.832034 -215.610186)
		(width 0.14478)
		(layer "In11.Cu")
		(net "M_F_CPU0_SA_DQ<15>")
	)
	(segment
		(start 275.517864 -214.760048)
		(end 278.483822 -214.760048)
		(width 0.14478)
		(layer "In11.Cu")
		(net "M_F_CPU0_SA_DQ<15>")
	)
	(segment
		(start 266.59078 -215.447118)
		(end 266.59078 -214.842598)
		(width 0.14478)
		(layer "In11.Cu")
		(net "M_F_CPU0_SA_DQ<15>")
	)
	(segment
		(start 274.667726 -215.610186)
		(end 275.517864 -214.760048)
		(width 0.14478)
		(layer "In11.Cu")
		(net "M_F_CPU0_SA_DQ<15>")
	)
	(segment
		(start 329.819762 -234.436666)
		(end 329.828144 -234.441492)
		(width 0.0889)
		(layer "In11.Cu")
		(net "M_F_CPU0_SA_DQ<15>")
	)
	(segment
		(start 301.945294 -215.610186)
		(end 304.8762 -215.610186)
		(width 0.14478)
		(layer "In11.Cu")
		(net "M_F_CPU0_SA_DQ<15>")
	)
	(segment
		(start 267.147294 -215.447118)
		(end 267.310362 -215.610186)
		(width 0.14478)
		(layer "In11.Cu")
		(net "M_F_CPU0_SA_DQ<15>")
	)
	(segment
		(start 265.54811 -215.18499)
		(end 265.973306 -215.610186)
		(width 0.14478)
		(layer "In11.Cu")
		(net "M_F_CPU0_SA_DQ<15>")
	)
	(segment
		(start 289.832034 -215.610186)
		(end 290.682172 -214.760048)
		(width 0.14478)
		(layer "In11.Cu")
		(net "M_F_CPU0_SA_DQ<15>")
	)
	(segment
		(start 266.984226 -214.67953)
		(end 267.147294 -214.842598)
		(width 0.14478)
		(layer "In11.Cu")
		(net "M_F_CPU0_SA_DQ<15>")
	)
	(segment
		(start 333.532734 -234.41533)
		(end 333.555086 -234.498642)
		(width 0.0889)
		(layer "In11.Cu")
		(net "M_F_CPU0_SA_DQ<15>")
	)
	(segment
		(start 286.053276 -214.760048)
		(end 286.903414 -215.610186)
		(width 0.14478)
		(layer "In11.Cu")
		(net "M_F_CPU0_SA_DQ<15>")
	)
	(segment
		(start 267.703808 -215.447118)
		(end 267.703808 -214.842598)
		(width 0.14478)
		(layer "In11.Cu")
		(net "M_F_CPU0_SA_DQ<15>")
	)
	(segment
		(start 293.558722 -214.760048)
		(end 294.40886 -215.610186)
		(width 0.14478)
		(layer "In11.Cu")
		(net "M_F_CPU0_SA_DQ<15>")
	)
	(segment
		(start 323.568314 -232.24617)
		(end 323.875146 -232.24617)
		(width 0.0889)
		(layer "In11.Cu")
		(net "M_F_CPU0_SA_DQ<15>")
	)
	(segment
		(start 268.42339 -215.610186)
		(end 274.667726 -215.610186)
		(width 0.14478)
		(layer "In11.Cu")
		(net "M_F_CPU0_SA_DQ<15>")
	)
	(segment
		(start 307.654198 -214.760048)
		(end 308.853078 -215.958928)
		(width 0.14478)
		(layer "In11.Cu")
		(net "M_F_CPU0_SA_DQ<15>")
	)
	(segment
		(start 267.54074 -215.610186)
		(end 267.703808 -215.447118)
		(width 0.14478)
		(layer "In11.Cu")
		(net "M_F_CPU0_SA_DQ<15>")
	)
	(segment
		(start 301.095156 -214.760048)
		(end 301.945294 -215.610186)
		(width 0.14478)
		(layer "In11.Cu")
		(net "M_F_CPU0_SA_DQ<15>")
	)
	(segment
		(start 298.179998 -214.760048)
		(end 301.095156 -214.760048)
		(width 0.14478)
		(layer "In11.Cu")
		(net "M_F_CPU0_SA_DQ<15>")
	)
	(segment
		(start 294.40886 -215.610186)
		(end 297.32986 -215.610186)
		(width 0.14478)
		(layer "In11.Cu")
		(net "M_F_CPU0_SA_DQ<15>")
	)
	(segment
		(start 314.030614 -222.141034)
		(end 314.030614 -223.479614)
		(width 0.14478)
		(layer "In11.Cu")
		(net "M_F_CPU0_SA_DQ<15>")
	)
	(segment
		(start 297.32986 -215.610186)
		(end 298.179998 -214.760048)
		(width 0.14478)
		(layer "In11.Cu")
		(net "M_F_CPU0_SA_DQ<15>")
	)
	(segment
		(start 324.932802 -233.039666)
		(end 325.116698 -233.223562)
		(width 0.0889)
		(layer "In11.Cu")
		(net "M_F_CPU0_SA_DQ<15>")
	)
	(segment
		(start 279.33396 -215.610186)
		(end 282.298648 -215.610186)
		(width 0.14478)
		(layer "In11.Cu")
		(net "M_F_CPU0_SA_DQ<15>")
	)
	(segment
		(start 268.260322 -215.447118)
		(end 268.42339 -215.610186)
		(width 0.14478)
		(layer "In11.Cu")
		(net "M_F_CPU0_SA_DQ<15>")
	)
	(segment
		(start 267.703808 -214.842598)
		(end 267.866876 -214.67953)
		(width 0.14478)
		(layer "In11.Cu")
		(net "M_F_CPU0_SA_DQ<15>")
	)
	(segment
		(start 305.726338 -214.760048)
		(end 307.654198 -214.760048)
		(width 0.14478)
		(layer "In11.Cu")
		(net "M_F_CPU0_SA_DQ<15>")
	)
	(segment
		(start 323.875146 -232.24617)
		(end 324.668642 -233.039666)
		(width 0.0889)
		(layer "In11.Cu")
		(net "M_F_CPU0_SA_DQ<15>")
	)
	(segment
		(start 326.619108 -234.450128)
		(end 326.63384 -234.441492)
		(width 0.0889)
		(layer "In11.Cu")
		(net "M_F_CPU0_SA_DQ<15>")
	)
	(segment
		(start 308.853078 -216.963498)
		(end 314.030614 -222.141034)
		(width 0.14478)
		(layer "In11.Cu")
		(net "M_F_CPU0_SA_DQ<15>")
	)
	(segment
		(start 283.148786 -214.760048)
		(end 286.053276 -214.760048)
		(width 0.14478)
		(layer "In11.Cu")
		(net "M_F_CPU0_SA_DQ<15>")
	)
	(segment
		(start 308.853078 -215.958928)
		(end 308.853078 -216.963498)
		(width 0.14478)
		(layer "In11.Cu")
		(net "M_F_CPU0_SA_DQ<15>")
	)
	(segment
		(start 333.555086 -234.498642)
		(end 333.401162 -234.764072)
		(width 0.0889)
		(layer "In11.Cu")
		(net "M_F_CPU0_SA_DQ<15>")
	)
	(segment
		(start 267.147294 -214.842598)
		(end 267.147294 -215.447118)
		(width 0.14478)
		(layer "In11.Cu")
		(net "M_F_CPU0_SA_DQ<15>")
	)
	(segment
		(start 325.116698 -233.516678)
		(end 325.952612 -234.352592)
		(width 0.0889)
		(layer "In11.Cu")
		(net "M_F_CPU0_SA_DQ<15>")
	)
	(segment
		(start 266.427712 -215.610186)
		(end 266.59078 -215.447118)
		(width 0.14478)
		(layer "In11.Cu")
		(net "M_F_CPU0_SA_DQ<15>")
	)
	(segment
		(start 265.973306 -215.610186)
		(end 266.427712 -215.610186)
		(width 0.14478)
		(layer "In11.Cu")
		(net "M_F_CPU0_SA_DQ<15>")
	)
	(arc
		(start 325.952612 -234.352592)
		(mid 326.007384 -234.400786)
		(end 326.067928 -234.441492)
		(width 0.0889)
		(layer "In11.Cu")
		(net "M_F_CPU0_SA_DQ<15>")
	)
	(arc
		(start 328.88809 -234.441492)
		(mid 329.171046 -234.517669)
		(end 329.454002 -234.441492)
		(width 0.0889)
		(layer "In11.Cu")
		(net "M_F_CPU0_SA_DQ<15>")
	)
	(arc
		(start 329.828144 -234.441492)
		(mid 330.1111 -234.517669)
		(end 330.394056 -234.441492)
		(width 0.0889)
		(layer "In11.Cu")
		(net "M_F_CPU0_SA_DQ<15>")
	)
	(arc
		(start 332.274164 -234.441492)
		(mid 332.461108 -234.391237)
		(end 332.648052 -234.441492)
		(width 0.0889)
		(layer "In11.Cu")
		(net "M_F_CPU0_SA_DQ<15>")
	)
	(arc
		(start 327.018142 -234.447588)
		(mid 327.296828 -234.517808)
		(end 327.573894 -234.441492)
		(width 0.0889)
		(layer "In11.Cu")
		(net "M_F_CPU0_SA_DQ<15>")
	)
	(arc
		(start 332.648052 -234.441492)
		(mid 332.931008 -234.517669)
		(end 333.213964 -234.441492)
		(width 0.0889)
		(layer "In11.Cu")
		(net "M_F_CPU0_SA_DQ<15>")
	)
	(arc
		(start 330.402438 -234.436666)
		(mid 330.585946 -234.391172)
		(end 330.768198 -234.441492)
		(width 0.0889)
		(layer "In11.Cu")
		(net "M_F_CPU0_SA_DQ<15>")
	)
	(arc
		(start 327.94829 -234.441492)
		(mid 328.231246 -234.517669)
		(end 328.514202 -234.441492)
		(width 0.0889)
		(layer "In11.Cu")
		(net "M_F_CPU0_SA_DQ<15>")
	)
	(arc
		(start 326.645524 -234.434634)
		(mid 326.827525 -234.391101)
		(end 327.007728 -234.441492)
		(width 0.0889)
		(layer "In11.Cu")
		(net "M_F_CPU0_SA_DQ<15>")
	)
	(arc
		(start 326.067928 -234.441492)
		(mid 326.34238 -234.517728)
		(end 326.619108 -234.450128)
		(width 0.0889)
		(layer "In11.Cu")
		(net "M_F_CPU0_SA_DQ<15>")
	)
	(arc
		(start 331.708252 -234.441492)
		(mid 331.991208 -234.517669)
		(end 332.274164 -234.441492)
		(width 0.0889)
		(layer "In11.Cu")
		(net "M_F_CPU0_SA_DQ<15>")
	)
	(arc
		(start 328.514202 -234.441492)
		(mid 328.701146 -234.391237)
		(end 328.88809 -234.441492)
		(width 0.0889)
		(layer "In11.Cu")
		(net "M_F_CPU0_SA_DQ<15>")
	)
	(arc
		(start 327.573894 -234.441492)
		(mid 327.761092 -234.39111)
		(end 327.94829 -234.441492)
		(width 0.0889)
		(layer "In11.Cu")
		(net "M_F_CPU0_SA_DQ<15>")
	)
	(arc
		(start 329.454002 -234.441492)
		(mid 329.636253 -234.391142)
		(end 329.819762 -234.436666)
		(width 0.0889)
		(layer "In11.Cu")
		(net "M_F_CPU0_SA_DQ<15>")
	)
	(arc
		(start 331.342492 -234.436666)
		(mid 331.526 -234.391172)
		(end 331.708252 -234.441492)
		(width 0.0889)
		(layer "In11.Cu")
		(net "M_F_CPU0_SA_DQ<15>")
	)
	(arc
		(start 330.768198 -234.441492)
		(mid 331.051154 -234.517669)
		(end 331.33411 -234.441492)
		(width 0.0889)
		(layer "In11.Cu")
		(net "M_F_CPU0_SA_DQ<15>")
	)
	(arc
		(start 333.213964 -234.441492)
		(mid 333.370402 -234.392521)
		(end 333.532734 -234.41533)
		(width 0.0889)
		(layer "In11.Cu")
		(net "M_F_CPU0_SA_DQ<15>")
	)
	(segment
		(start 332.45806 -234.220004)
		(end 331.991208 -233.954066)
		(width 0.10668)
		(layer "F.Cu")
		(net "M_F_CPU0_SA_DQ<14>")
	)
	(segment
		(start 267.369036 -212.907118)
		(end 267.532104 -212.74405)
		(width 0.14478)
		(layer "In11.Cu")
		(net "M_F_CPU0_SA_DQ<14>")
	)
	(segment
		(start 286.053276 -213.060026)
		(end 286.903414 -213.910164)
		(width 0.14478)
		(layer "In11.Cu")
		(net "M_F_CPU0_SA_DQ<14>")
	)
	(segment
		(start 304.8762 -213.910164)
		(end 305.726338 -213.060026)
		(width 0.14478)
		(layer "In11.Cu")
		(net "M_F_CPU0_SA_DQ<14>")
	)
	(segment
		(start 278.483822 -213.060026)
		(end 279.33396 -213.910164)
		(width 0.14478)
		(layer "In11.Cu")
		(net "M_F_CPU0_SA_DQ<14>")
	)
	(segment
		(start 268.088618 -213.910164)
		(end 268.318996 -213.910164)
		(width 0.14478)
		(layer "In11.Cu")
		(net "M_F_CPU0_SA_DQ<14>")
	)
	(segment
		(start 289.832034 -213.910164)
		(end 290.682172 -213.060026)
		(width 0.14478)
		(layer "In11.Cu")
		(net "M_F_CPU0_SA_DQ<14>")
	)
	(segment
		(start 332.145132 -233.688636)
		(end 331.991208 -233.954066)
		(width 0.0889)
		(layer "In11.Cu")
		(net "M_F_CPU0_SA_DQ<14>")
	)
	(segment
		(start 327.465182 -233.623866)
		(end 327.478898 -233.63174)
		(width 0.0889)
		(layer "In11.Cu")
		(net "M_F_CPU0_SA_DQ<14>")
	)
	(segment
		(start 293.558722 -213.060026)
		(end 294.40886 -213.910164)
		(width 0.14478)
		(layer "In11.Cu")
		(net "M_F_CPU0_SA_DQ<14>")
	)
	(segment
		(start 297.32986 -213.910164)
		(end 298.179998 -213.060026)
		(width 0.14478)
		(layer "In11.Cu")
		(net "M_F_CPU0_SA_DQ<14>")
	)
	(segment
		(start 283.148786 -213.060026)
		(end 286.053276 -213.060026)
		(width 0.14478)
		(layer "In11.Cu")
		(net "M_F_CPU0_SA_DQ<14>")
	)
	(segment
		(start 275.517864 -213.060026)
		(end 278.483822 -213.060026)
		(width 0.14478)
		(layer "In11.Cu")
		(net "M_F_CPU0_SA_DQ<14>")
	)
	(segment
		(start 267.205968 -213.910164)
		(end 267.369036 -213.747096)
		(width 0.14478)
		(layer "In11.Cu")
		(net "M_F_CPU0_SA_DQ<14>")
	)
	(segment
		(start 314.942474 -221.727522)
		(end 314.942474 -223.105218)
		(width 0.14478)
		(layer "In11.Cu")
		(net "M_F_CPU0_SA_DQ<14>")
	)
	(segment
		(start 268.87551 -212.74405)
		(end 269.038578 -212.907118)
		(width 0.14478)
		(layer "In11.Cu")
		(net "M_F_CPU0_SA_DQ<14>")
	)
	(segment
		(start 290.682172 -213.060026)
		(end 293.558722 -213.060026)
		(width 0.14478)
		(layer "In11.Cu")
		(net "M_F_CPU0_SA_DQ<14>")
	)
	(segment
		(start 268.645132 -212.74405)
		(end 268.87551 -212.74405)
		(width 0.14478)
		(layer "In11.Cu")
		(net "M_F_CPU0_SA_DQ<14>")
	)
	(segment
		(start 325.112126 -232.57891)
		(end 326.113902 -233.580686)
		(width 0.0889)
		(layer "In11.Cu")
		(net "M_F_CPU0_SA_DQ<14>")
	)
	(segment
		(start 294.40886 -213.910164)
		(end 297.32986 -213.910164)
		(width 0.14478)
		(layer "In11.Cu")
		(net "M_F_CPU0_SA_DQ<14>")
	)
	(segment
		(start 274.667726 -213.910164)
		(end 275.517864 -213.060026)
		(width 0.14478)
		(layer "In11.Cu")
		(net "M_F_CPU0_SA_DQ<14>")
	)
	(segment
		(start 267.92555 -212.907118)
		(end 267.92555 -213.747096)
		(width 0.14478)
		(layer "In11.Cu")
		(net "M_F_CPU0_SA_DQ<14>")
	)
	(segment
		(start 314.942474 -223.105218)
		(end 323.174106 -231.33685)
		(width 0.14478)
		(layer "In11.Cu")
		(net "M_F_CPU0_SA_DQ<14>")
	)
	(segment
		(start 332.12278 -233.605324)
		(end 332.145132 -233.688636)
		(width 0.0889)
		(layer "In11.Cu")
		(net "M_F_CPU0_SA_DQ<14>")
	)
	(segment
		(start 269.201646 -213.910164)
		(end 274.667726 -213.910164)
		(width 0.14478)
		(layer "In11.Cu")
		(net "M_F_CPU0_SA_DQ<14>")
	)
	(segment
		(start 323.568314 -231.33685)
		(end 323.903594 -231.33685)
		(width 0.0889)
		(layer "In11.Cu")
		(net "M_F_CPU0_SA_DQ<14>")
	)
	(segment
		(start 279.33396 -213.910164)
		(end 282.298648 -213.910164)
		(width 0.14478)
		(layer "In11.Cu")
		(net "M_F_CPU0_SA_DQ<14>")
	)
	(segment
		(start 282.298648 -213.910164)
		(end 283.148786 -213.060026)
		(width 0.14478)
		(layer "In11.Cu")
		(net "M_F_CPU0_SA_DQ<14>")
	)
	(segment
		(start 324.878446 -232.57891)
		(end 325.112126 -232.57891)
		(width 0.0889)
		(layer "In11.Cu")
		(net "M_F_CPU0_SA_DQ<14>")
	)
	(segment
		(start 265.973306 -213.910164)
		(end 267.205968 -213.910164)
		(width 0.14478)
		(layer "In11.Cu")
		(net "M_F_CPU0_SA_DQ<14>")
	)
	(segment
		(start 268.482064 -213.747096)
		(end 268.482064 -212.907118)
		(width 0.14478)
		(layer "In11.Cu")
		(net "M_F_CPU0_SA_DQ<14>")
	)
	(segment
		(start 326.113902 -233.580686)
		(end 326.351138 -233.580686)
		(width 0.0889)
		(layer "In11.Cu")
		(net "M_F_CPU0_SA_DQ<14>")
	)
	(segment
		(start 331.229716 -233.62666)
		(end 331.238098 -233.631486)
		(width 0.0889)
		(layer "In11.Cu")
		(net "M_F_CPU0_SA_DQ<14>")
	)
	(segment
		(start 307.566314 -213.060026)
		(end 309.764938 -215.25865)
		(width 0.14478)
		(layer "In11.Cu")
		(net "M_F_CPU0_SA_DQ<14>")
	)
	(segment
		(start 305.726338 -213.060026)
		(end 307.566314 -213.060026)
		(width 0.14478)
		(layer "In11.Cu")
		(net "M_F_CPU0_SA_DQ<14>")
	)
	(segment
		(start 328.409808 -233.62666)
		(end 328.41819 -233.631486)
		(width 0.0889)
		(layer "In11.Cu")
		(net "M_F_CPU0_SA_DQ<14>")
	)
	(segment
		(start 269.038578 -212.907118)
		(end 269.038578 -213.747096)
		(width 0.14478)
		(layer "In11.Cu")
		(net "M_F_CPU0_SA_DQ<14>")
	)
	(segment
		(start 323.903594 -231.33685)
		(end 324.383654 -231.81691)
		(width 0.0889)
		(layer "In11.Cu")
		(net "M_F_CPU0_SA_DQ<14>")
	)
	(segment
		(start 324.383654 -232.084118)
		(end 324.878446 -232.57891)
		(width 0.0889)
		(layer "In11.Cu")
		(net "M_F_CPU0_SA_DQ<14>")
	)
	(segment
		(start 267.369036 -213.747096)
		(end 267.369036 -212.907118)
		(width 0.14478)
		(layer "In11.Cu")
		(net "M_F_CPU0_SA_DQ<14>")
	)
	(segment
		(start 298.179998 -213.060026)
		(end 301.095156 -213.060026)
		(width 0.14478)
		(layer "In11.Cu")
		(net "M_F_CPU0_SA_DQ<14>")
	)
	(segment
		(start 323.174106 -231.33685)
		(end 323.568314 -231.33685)
		(width 0.14478)
		(layer "In11.Cu")
		(net "M_F_CPU0_SA_DQ<14>")
	)
	(segment
		(start 269.038578 -213.747096)
		(end 269.201646 -213.910164)
		(width 0.14478)
		(layer "In11.Cu")
		(net "M_F_CPU0_SA_DQ<14>")
	)
	(segment
		(start 268.482064 -212.907118)
		(end 268.645132 -212.74405)
		(width 0.14478)
		(layer "In11.Cu")
		(net "M_F_CPU0_SA_DQ<14>")
	)
	(segment
		(start 327.08723 -233.642154)
		(end 327.105264 -233.631486)
		(width 0.0889)
		(layer "In11.Cu")
		(net "M_F_CPU0_SA_DQ<14>")
	)
	(segment
		(start 301.945294 -213.910164)
		(end 304.8762 -213.910164)
		(width 0.14478)
		(layer "In11.Cu")
		(net "M_F_CPU0_SA_DQ<14>")
	)
	(segment
		(start 265.54811 -213.484968)
		(end 265.973306 -213.910164)
		(width 0.14478)
		(layer "In11.Cu")
		(net "M_F_CPU0_SA_DQ<14>")
	)
	(segment
		(start 267.532104 -212.74405)
		(end 267.762482 -212.74405)
		(width 0.14478)
		(layer "In11.Cu")
		(net "M_F_CPU0_SA_DQ<14>")
	)
	(segment
		(start 309.764938 -216.549986)
		(end 314.942474 -221.727522)
		(width 0.14478)
		(layer "In11.Cu")
		(net "M_F_CPU0_SA_DQ<14>")
	)
	(segment
		(start 301.095156 -213.060026)
		(end 301.945294 -213.910164)
		(width 0.14478)
		(layer "In11.Cu")
		(net "M_F_CPU0_SA_DQ<14>")
	)
	(segment
		(start 267.762482 -212.74405)
		(end 267.92555 -212.907118)
		(width 0.14478)
		(layer "In11.Cu")
		(net "M_F_CPU0_SA_DQ<14>")
	)
	(segment
		(start 327.478898 -233.63174)
		(end 327.490836 -233.638598)
		(width 0.0889)
		(layer "In11.Cu")
		(net "M_F_CPU0_SA_DQ<14>")
	)
	(segment
		(start 309.764938 -215.25865)
		(end 309.764938 -216.549986)
		(width 0.14478)
		(layer "In11.Cu")
		(net "M_F_CPU0_SA_DQ<14>")
	)
	(segment
		(start 324.383654 -231.81691)
		(end 324.383654 -232.084118)
		(width 0.0889)
		(layer "In11.Cu")
		(net "M_F_CPU0_SA_DQ<14>")
	)
	(segment
		(start 286.903414 -213.910164)
		(end 289.832034 -213.910164)
		(width 0.14478)
		(layer "In11.Cu")
		(net "M_F_CPU0_SA_DQ<14>")
	)
	(segment
		(start 267.92555 -213.747096)
		(end 268.088618 -213.910164)
		(width 0.14478)
		(layer "In11.Cu")
		(net "M_F_CPU0_SA_DQ<14>")
	)
	(segment
		(start 328.984102 -233.631486)
		(end 328.992484 -233.62666)
		(width 0.0889)
		(layer "In11.Cu")
		(net "M_F_CPU0_SA_DQ<14>")
	)
	(segment
		(start 268.318996 -213.910164)
		(end 268.482064 -213.747096)
		(width 0.14478)
		(layer "In11.Cu")
		(net "M_F_CPU0_SA_DQ<14>")
	)
	(arc
		(start 328.41819 -233.631486)
		(mid 328.701146 -233.707663)
		(end 328.984102 -233.631486)
		(width 0.0889)
		(layer "In11.Cu")
		(net "M_F_CPU0_SA_DQ<14>")
	)
	(arc
		(start 327.105264 -233.631486)
		(mid 327.284251 -233.581316)
		(end 327.465182 -233.623866)
		(width 0.0889)
		(layer "In11.Cu")
		(net "M_F_CPU0_SA_DQ<14>")
	)
	(arc
		(start 326.351138 -233.580686)
		(mid 326.448227 -233.593676)
		(end 326.53859 -233.631486)
		(width 0.0889)
		(layer "In11.Cu")
		(net "M_F_CPU0_SA_DQ<14>")
	)
	(arc
		(start 327.490836 -233.638598)
		(mid 327.76837 -233.707579)
		(end 328.044048 -233.631486)
		(width 0.0889)
		(layer "In11.Cu")
		(net "M_F_CPU0_SA_DQ<14>")
	)
	(arc
		(start 326.53859 -233.631486)
		(mid 326.811534 -233.708066)
		(end 327.08723 -233.642154)
		(width 0.0889)
		(layer "In11.Cu")
		(net "M_F_CPU0_SA_DQ<14>")
	)
	(arc
		(start 329.358244 -233.631486)
		(mid 329.6412 -233.707663)
		(end 329.924156 -233.631486)
		(width 0.0889)
		(layer "In11.Cu")
		(net "M_F_CPU0_SA_DQ<14>")
	)
	(arc
		(start 328.044048 -233.631486)
		(mid 328.226299 -233.581136)
		(end 328.409808 -233.62666)
		(width 0.0889)
		(layer "In11.Cu")
		(net "M_F_CPU0_SA_DQ<14>")
	)
	(arc
		(start 331.80401 -233.631486)
		(mid 331.960448 -233.582515)
		(end 332.12278 -233.605324)
		(width 0.0889)
		(layer "In11.Cu")
		(net "M_F_CPU0_SA_DQ<14>")
	)
	(arc
		(start 328.992484 -233.62666)
		(mid 329.175992 -233.581166)
		(end 329.358244 -233.631486)
		(width 0.0889)
		(layer "In11.Cu")
		(net "M_F_CPU0_SA_DQ<14>")
	)
	(arc
		(start 330.863956 -233.631486)
		(mid 331.046207 -233.581136)
		(end 331.229716 -233.62666)
		(width 0.0889)
		(layer "In11.Cu")
		(net "M_F_CPU0_SA_DQ<14>")
	)
	(arc
		(start 330.298044 -233.631486)
		(mid 330.581 -233.707663)
		(end 330.863956 -233.631486)
		(width 0.0889)
		(layer "In11.Cu")
		(net "M_F_CPU0_SA_DQ<14>")
	)
	(arc
		(start 329.924156 -233.631486)
		(mid 330.1111 -233.581231)
		(end 330.298044 -233.631486)
		(width 0.0889)
		(layer "In11.Cu")
		(net "M_F_CPU0_SA_DQ<14>")
	)
	(arc
		(start 331.238098 -233.631486)
		(mid 331.521054 -233.707663)
		(end 331.80401 -233.631486)
		(width 0.0889)
		(layer "In11.Cu")
		(net "M_F_CPU0_SA_DQ<14>")
	)
	(segment
		(start 334.337914 -234.220004)
		(end 333.871062 -233.954066)
		(width 0.10668)
		(layer "F.Cu")
		(net "M_F_CPU0_SA_DQ<13>")
	)
	(segment
		(start 290.732972 -213.910164)
		(end 290.990274 -213.910164)
		(width 0.14478)
		(layer "In11.Cu")
		(net "M_F_CPU0_SA_DQ<13>")
	)
	(segment
		(start 306.396136 -214.135462)
		(end 306.559204 -214.29853)
		(width 0.14478)
		(layer "In11.Cu")
		(net "M_F_CPU0_SA_DQ<13>")
	)
	(segment
		(start 294.357806 -214.760048)
		(end 296.196004 -214.760048)
		(width 0.14478)
		(layer "In11.Cu")
		(net "M_F_CPU0_SA_DQ<13>")
	)
	(segment
		(start 306.396136 -214.073232)
		(end 306.396136 -214.135462)
		(width 0.14478)
		(layer "In11.Cu")
		(net "M_F_CPU0_SA_DQ<13>")
	)
	(segment
		(start 269.648178 -214.335106)
		(end 270.07312 -214.760048)
		(width 0.14478)
		(layer "In11.Cu")
		(net "M_F_CPU0_SA_DQ<13>")
	)
	(segment
		(start 279.260808 -214.760048)
		(end 281.149298 -214.760048)
		(width 0.14478)
		(layer "In11.Cu")
		(net "M_F_CPU0_SA_DQ<13>")
	)
	(segment
		(start 299.358558 -214.073232)
		(end 299.521626 -213.910164)
		(width 0.14478)
		(layer "In11.Cu")
		(net "M_F_CPU0_SA_DQ<13>")
	)
	(segment
		(start 303.336198 -214.760048)
		(end 303.566576 -214.760048)
		(width 0.14478)
		(layer "In11.Cu")
		(net "M_F_CPU0_SA_DQ<13>")
	)
	(segment
		(start 288.776156 -214.923116)
		(end 288.776156 -214.988902)
		(width 0.14478)
		(layer "In11.Cu")
		(net "M_F_CPU0_SA_DQ<13>")
	)
	(segment
		(start 332.744064 -234.276646)
		(end 332.752446 -234.281472)
		(width 0.0889)
		(layer "In11.Cu")
		(net "M_F_CPU0_SA_DQ<13>")
	)
	(segment
		(start 296.359072 -214.923116)
		(end 296.359072 -214.978742)
		(width 0.14478)
		(layer "In11.Cu")
		(net "M_F_CPU0_SA_DQ<13>")
	)
	(segment
		(start 272.294096 -214.923116)
		(end 272.457164 -214.760048)
		(width 0.14478)
		(layer "In11.Cu")
		(net "M_F_CPU0_SA_DQ<13>")
	)
	(segment
		(start 302.779684 -215.14689)
		(end 303.010062 -215.14689)
		(width 0.14478)
		(layer "In11.Cu")
		(net "M_F_CPU0_SA_DQ<13>")
	)
	(segment
		(start 306.95265 -214.073232)
		(end 307.115718 -213.910164)
		(width 0.14478)
		(layer "In11.Cu")
		(net "M_F_CPU0_SA_DQ<13>")
	)
	(segment
		(start 325.323454 -233.45394)
		(end 326.087486 -234.217972)
		(width 0.0889)
		(layer "In11.Cu")
		(net "M_F_CPU0_SA_DQ<13>")
	)
	(segment
		(start 297.078654 -214.760048)
		(end 297.389042 -214.760048)
		(width 0.14478)
		(layer "In11.Cu")
		(net "M_F_CPU0_SA_DQ<13>")
	)
	(segment
		(start 304.12309 -215.14689)
		(end 304.286158 -214.983822)
		(width 0.14478)
		(layer "In11.Cu")
		(net "M_F_CPU0_SA_DQ<13>")
	)
	(segment
		(start 298.238926 -213.910164)
		(end 298.638976 -213.910164)
		(width 0.14478)
		(layer "In11.Cu")
		(net "M_F_CPU0_SA_DQ<13>")
	)
	(segment
		(start 281.475434 -215.15197)
		(end 281.705812 -215.15197)
		(width 0.14478)
		(layer "In11.Cu")
		(net "M_F_CPU0_SA_DQ<13>")
	)
	(segment
		(start 271.737582 -214.983822)
		(end 271.90065 -215.14689)
		(width 0.14478)
		(layer "In11.Cu")
		(net "M_F_CPU0_SA_DQ<13>")
	)
	(segment
		(start 304.894742 -214.760048)
		(end 305.744626 -213.910164)
		(width 0.14478)
		(layer "In11.Cu")
		(net "M_F_CPU0_SA_DQ<13>")
	)
	(segment
		(start 306.233068 -213.910164)
		(end 306.396136 -214.073232)
		(width 0.14478)
		(layer "In11.Cu")
		(net "M_F_CPU0_SA_DQ<13>")
	)
	(segment
		(start 301.051976 -213.910164)
		(end 301.90186 -214.760048)
		(width 0.14478)
		(layer "In11.Cu")
		(net "M_F_CPU0_SA_DQ<13>")
	)
	(segment
		(start 271.181068 -214.536274)
		(end 271.344136 -214.373206)
		(width 0.14478)
		(layer "In11.Cu")
		(net "M_F_CPU0_SA_DQ<13>")
	)
	(segment
		(start 304.449226 -214.760048)
		(end 304.894742 -214.760048)
		(width 0.14478)
		(layer "In11.Cu")
		(net "M_F_CPU0_SA_DQ<13>")
	)
	(segment
		(start 296.196004 -214.760048)
		(end 296.359072 -214.923116)
		(width 0.14478)
		(layer "In11.Cu")
		(net "M_F_CPU0_SA_DQ<13>")
	)
	(segment
		(start 325.323454 -233.13771)
		(end 325.323454 -233.45394)
		(width 0.0889)
		(layer "In11.Cu")
		(net "M_F_CPU0_SA_DQ<13>")
	)
	(segment
		(start 307.960522 -214.29853)
		(end 309.310278 -215.648286)
		(width 0.14478)
		(layer "In11.Cu")
		(net "M_F_CPU0_SA_DQ<13>")
	)
	(segment
		(start 270.624554 -214.983822)
		(end 270.787622 -215.14689)
		(width 0.14478)
		(layer "In11.Cu")
		(net "M_F_CPU0_SA_DQ<13>")
	)
	(segment
		(start 270.787622 -215.14689)
		(end 271.018 -215.14689)
		(width 0.14478)
		(layer "In11.Cu")
		(net "M_F_CPU0_SA_DQ<13>")
	)
	(segment
		(start 281.312366 -214.988902)
		(end 281.475434 -215.15197)
		(width 0.14478)
		(layer "In11.Cu")
		(net "M_F_CPU0_SA_DQ<13>")
	)
	(segment
		(start 291.709856 -214.073232)
		(end 291.872924 -213.910164)
		(width 0.14478)
		(layer "In11.Cu")
		(net "M_F_CPU0_SA_DQ<13>")
	)
	(segment
		(start 328.033634 -234.27055)
		(end 328.044048 -234.276646)
		(width 0.0889)
		(layer "In11.Cu")
		(net "M_F_CPU0_SA_DQ<13>")
	)
	(segment
		(start 297.389042 -214.760048)
		(end 298.238926 -213.910164)
		(width 0.14478)
		(layer "In11.Cu")
		(net "M_F_CPU0_SA_DQ<13>")
	)
	(segment
		(start 328.984102 -234.276646)
		(end 328.992484 -234.281472)
		(width 0.0889)
		(layer "In11.Cu")
		(net "M_F_CPU0_SA_DQ<13>")
	)
	(segment
		(start 296.915586 -214.978742)
		(end 296.915586 -214.923116)
		(width 0.14478)
		(layer "In11.Cu")
		(net "M_F_CPU0_SA_DQ<13>")
	)
	(segment
		(start 275.604732 -213.910164)
		(end 275.931884 -213.910164)
		(width 0.14478)
		(layer "In11.Cu")
		(net "M_F_CPU0_SA_DQ<13>")
	)
	(segment
		(start 304.286158 -214.923116)
		(end 304.449226 -214.760048)
		(width 0.14478)
		(layer "In11.Cu")
		(net "M_F_CPU0_SA_DQ<13>")
	)
	(segment
		(start 309.310278 -215.648286)
		(end 309.310278 -216.738454)
		(width 0.14478)
		(layer "In11.Cu")
		(net "M_F_CPU0_SA_DQ<13>")
	)
	(segment
		(start 291.153342 -214.073232)
		(end 291.153342 -214.135462)
		(width 0.14478)
		(layer "In11.Cu")
		(net "M_F_CPU0_SA_DQ<13>")
	)
	(segment
		(start 299.358558 -214.135462)
		(end 299.358558 -214.073232)
		(width 0.14478)
		(layer "In11.Cu")
		(net "M_F_CPU0_SA_DQ<13>")
	)
	(segment
		(start 273.94027 -215.15197)
		(end 274.170648 -215.15197)
		(width 0.14478)
		(layer "In11.Cu")
		(net "M_F_CPU0_SA_DQ<13>")
	)
	(segment
		(start 274.496784 -214.760048)
		(end 274.754848 -214.760048)
		(width 0.14478)
		(layer "In11.Cu")
		(net "M_F_CPU0_SA_DQ<13>")
	)
	(segment
		(start 298.802044 -214.073232)
		(end 298.802044 -214.135462)
		(width 0.14478)
		(layer "In11.Cu")
		(net "M_F_CPU0_SA_DQ<13>")
	)
	(segment
		(start 271.018 -215.14689)
		(end 271.181068 -214.983822)
		(width 0.14478)
		(layer "In11.Cu")
		(net "M_F_CPU0_SA_DQ<13>")
	)
	(segment
		(start 303.729644 -214.923116)
		(end 303.729644 -214.983822)
		(width 0.14478)
		(layer "In11.Cu")
		(net "M_F_CPU0_SA_DQ<13>")
	)
	(segment
		(start 303.566576 -214.760048)
		(end 303.729644 -214.923116)
		(width 0.14478)
		(layer "In11.Cu")
		(net "M_F_CPU0_SA_DQ<13>")
	)
	(segment
		(start 288.776156 -214.988902)
		(end 288.939224 -215.15197)
		(width 0.14478)
		(layer "In11.Cu")
		(net "M_F_CPU0_SA_DQ<13>")
	)
	(segment
		(start 306.95265 -214.135462)
		(end 306.95265 -214.073232)
		(width 0.14478)
		(layer "In11.Cu")
		(net "M_F_CPU0_SA_DQ<13>")
	)
	(segment
		(start 305.744626 -213.910164)
		(end 306.233068 -213.910164)
		(width 0.14478)
		(layer "In11.Cu")
		(net "M_F_CPU0_SA_DQ<13>")
	)
	(segment
		(start 323.568314 -231.79151)
		(end 323.908674 -231.79151)
		(width 0.0889)
		(layer "In11.Cu")
		(net "M_F_CPU0_SA_DQ<13>")
	)
	(segment
		(start 276.25802 -214.29853)
		(end 276.488398 -214.29853)
		(width 0.14478)
		(layer "In11.Cu")
		(net "M_F_CPU0_SA_DQ<13>")
	)
	(segment
		(start 324.137782 -232.127298)
		(end 324.843394 -232.83291)
		(width 0.0889)
		(layer "In11.Cu")
		(net "M_F_CPU0_SA_DQ<13>")
	)
	(segment
		(start 272.131028 -215.14689)
		(end 272.294096 -214.983822)
		(width 0.14478)
		(layer "In11.Cu")
		(net "M_F_CPU0_SA_DQ<13>")
	)
	(segment
		(start 298.965112 -214.29853)
		(end 299.19549 -214.29853)
		(width 0.14478)
		(layer "In11.Cu")
		(net "M_F_CPU0_SA_DQ<13>")
	)
	(segment
		(start 302.616616 -214.983822)
		(end 302.779684 -215.14689)
		(width 0.14478)
		(layer "In11.Cu")
		(net "M_F_CPU0_SA_DQ<13>")
	)
	(segment
		(start 282.031948 -214.760048)
		(end 282.323286 -214.760048)
		(width 0.14478)
		(layer "In11.Cu")
		(net "M_F_CPU0_SA_DQ<13>")
	)
	(segment
		(start 276.094952 -214.135462)
		(end 276.25802 -214.29853)
		(width 0.14478)
		(layer "In11.Cu")
		(net "M_F_CPU0_SA_DQ<13>")
	)
	(segment
		(start 296.52214 -215.14181)
		(end 296.752518 -215.14181)
		(width 0.14478)
		(layer "In11.Cu")
		(net "M_F_CPU0_SA_DQ<13>")
	)
	(segment
		(start 283.636212 -214.130382)
		(end 283.79928 -214.29345)
		(width 0.14478)
		(layer "In11.Cu")
		(net "M_F_CPU0_SA_DQ<13>")
	)
	(segment
		(start 291.153342 -214.135462)
		(end 291.31641 -214.29853)
		(width 0.14478)
		(layer "In11.Cu")
		(net "M_F_CPU0_SA_DQ<13>")
	)
	(segment
		(start 306.559204 -214.29853)
		(end 306.789582 -214.29853)
		(width 0.14478)
		(layer "In11.Cu")
		(net "M_F_CPU0_SA_DQ<13>")
	)
	(segment
		(start 281.86888 -214.923116)
		(end 282.031948 -214.760048)
		(width 0.14478)
		(layer "In11.Cu")
		(net "M_F_CPU0_SA_DQ<13>")
	)
	(segment
		(start 291.709856 -214.135462)
		(end 291.709856 -214.073232)
		(width 0.14478)
		(layer "In11.Cu")
		(net "M_F_CPU0_SA_DQ<13>")
	)
	(segment
		(start 282.323286 -214.760048)
		(end 283.17317 -213.910164)
		(width 0.14478)
		(layer "In11.Cu")
		(net "M_F_CPU0_SA_DQ<13>")
	)
	(segment
		(start 314.487814 -223.293686)
		(end 322.985638 -231.79151)
		(width 0.14478)
		(layer "In11.Cu")
		(net "M_F_CPU0_SA_DQ<13>")
	)
	(segment
		(start 299.19549 -214.29853)
		(end 299.358558 -214.135462)
		(width 0.14478)
		(layer "In11.Cu")
		(net "M_F_CPU0_SA_DQ<13>")
	)
	(segment
		(start 288.613088 -214.760048)
		(end 288.776156 -214.923116)
		(width 0.14478)
		(layer "In11.Cu")
		(net "M_F_CPU0_SA_DQ<13>")
	)
	(segment
		(start 331.229716 -234.281472)
		(end 331.238098 -234.276646)
		(width 0.0889)
		(layer "In11.Cu")
		(net "M_F_CPU0_SA_DQ<13>")
	)
	(segment
		(start 303.010062 -215.14689)
		(end 303.17313 -214.983822)
		(width 0.14478)
		(layer "In11.Cu")
		(net "M_F_CPU0_SA_DQ<13>")
	)
	(segment
		(start 271.90065 -215.14689)
		(end 272.131028 -215.14689)
		(width 0.14478)
		(layer "In11.Cu")
		(net "M_F_CPU0_SA_DQ<13>")
	)
	(segment
		(start 333.621126 -234.244896)
		(end 333.717138 -234.219496)
		(width 0.0889)
		(layer "In11.Cu")
		(net "M_F_CPU0_SA_DQ<13>")
	)
	(segment
		(start 276.651466 -214.073232)
		(end 276.814534 -213.910164)
		(width 0.14478)
		(layer "In11.Cu")
		(net "M_F_CPU0_SA_DQ<13>")
	)
	(segment
		(start 289.33267 -214.988902)
		(end 289.33267 -214.923116)
		(width 0.14478)
		(layer "In11.Cu")
		(net "M_F_CPU0_SA_DQ<13>")
	)
	(segment
		(start 276.651466 -214.135462)
		(end 276.651466 -214.073232)
		(width 0.14478)
		(layer "In11.Cu")
		(net "M_F_CPU0_SA_DQ<13>")
	)
	(segment
		(start 274.333716 -214.923116)
		(end 274.496784 -214.760048)
		(width 0.14478)
		(layer "In11.Cu")
		(net "M_F_CPU0_SA_DQ<13>")
	)
	(segment
		(start 281.86888 -214.988902)
		(end 281.86888 -214.923116)
		(width 0.14478)
		(layer "In11.Cu")
		(net "M_F_CPU0_SA_DQ<13>")
	)
	(segment
		(start 284.355794 -213.910164)
		(end 285.892748 -213.910164)
		(width 0.14478)
		(layer "In11.Cu")
		(net "M_F_CPU0_SA_DQ<13>")
	)
	(segment
		(start 314.487814 -221.91599)
		(end 314.487814 -223.293686)
		(width 0.14478)
		(layer "In11.Cu")
		(net "M_F_CPU0_SA_DQ<13>")
	)
	(segment
		(start 286.742632 -214.760048)
		(end 288.613088 -214.760048)
		(width 0.14478)
		(layer "In11.Cu")
		(net "M_F_CPU0_SA_DQ<13>")
	)
	(segment
		(start 275.931884 -213.910164)
		(end 276.094952 -214.073232)
		(width 0.14478)
		(layer "In11.Cu")
		(net "M_F_CPU0_SA_DQ<13>")
	)
	(segment
		(start 322.985638 -231.79151)
		(end 323.568314 -231.79151)
		(width 0.14478)
		(layer "In11.Cu")
		(net "M_F_CPU0_SA_DQ<13>")
	)
	(segment
		(start 296.752518 -215.14181)
		(end 296.915586 -214.978742)
		(width 0.14478)
		(layer "In11.Cu")
		(net "M_F_CPU0_SA_DQ<13>")
	)
	(segment
		(start 326.52335 -234.285028)
		(end 326.548242 -234.27055)
		(width 0.0889)
		(layer "In11.Cu")
		(net "M_F_CPU0_SA_DQ<13>")
	)
	(segment
		(start 303.892712 -215.14689)
		(end 304.12309 -215.14689)
		(width 0.14478)
		(layer "In11.Cu")
		(net "M_F_CPU0_SA_DQ<13>")
	)
	(segment
		(start 270.624554 -214.923116)
		(end 270.624554 -214.983822)
		(width 0.14478)
		(layer "In11.Cu")
		(net "M_F_CPU0_SA_DQ<13>")
	)
	(segment
		(start 281.705812 -215.15197)
		(end 281.86888 -214.988902)
		(width 0.14478)
		(layer "In11.Cu")
		(net "M_F_CPU0_SA_DQ<13>")
	)
	(segment
		(start 274.170648 -215.15197)
		(end 274.333716 -214.988902)
		(width 0.14478)
		(layer "In11.Cu")
		(net "M_F_CPU0_SA_DQ<13>")
	)
	(segment
		(start 276.488398 -214.29853)
		(end 276.651466 -214.135462)
		(width 0.14478)
		(layer "In11.Cu")
		(net "M_F_CPU0_SA_DQ<13>")
	)
	(segment
		(start 283.17317 -213.910164)
		(end 283.473144 -213.910164)
		(width 0.14478)
		(layer "In11.Cu")
		(net "M_F_CPU0_SA_DQ<13>")
	)
	(segment
		(start 290.990274 -213.910164)
		(end 291.153342 -214.073232)
		(width 0.14478)
		(layer "In11.Cu")
		(net "M_F_CPU0_SA_DQ<13>")
	)
	(segment
		(start 296.915586 -214.923116)
		(end 297.078654 -214.760048)
		(width 0.14478)
		(layer "In11.Cu")
		(net "M_F_CPU0_SA_DQ<13>")
	)
	(segment
		(start 273.614134 -214.760048)
		(end 273.777202 -214.923116)
		(width 0.14478)
		(layer "In11.Cu")
		(net "M_F_CPU0_SA_DQ<13>")
	)
	(segment
		(start 298.638976 -213.910164)
		(end 298.802044 -214.073232)
		(width 0.14478)
		(layer "In11.Cu")
		(net "M_F_CPU0_SA_DQ<13>")
	)
	(segment
		(start 323.908674 -231.79151)
		(end 324.137782 -232.020618)
		(width 0.0889)
		(layer "In11.Cu")
		(net "M_F_CPU0_SA_DQ<13>")
	)
	(segment
		(start 271.344136 -214.373206)
		(end 271.574514 -214.373206)
		(width 0.14478)
		(layer "In11.Cu")
		(net "M_F_CPU0_SA_DQ<13>")
	)
	(segment
		(start 281.312366 -214.923116)
		(end 281.312366 -214.988902)
		(width 0.14478)
		(layer "In11.Cu")
		(net "M_F_CPU0_SA_DQ<13>")
	)
	(segment
		(start 278.410924 -213.910164)
		(end 279.260808 -214.760048)
		(width 0.14478)
		(layer "In11.Cu")
		(net "M_F_CPU0_SA_DQ<13>")
	)
	(segment
		(start 296.359072 -214.978742)
		(end 296.52214 -215.14181)
		(width 0.14478)
		(layer "In11.Cu")
		(net "M_F_CPU0_SA_DQ<13>")
	)
	(segment
		(start 304.286158 -214.983822)
		(end 304.286158 -214.923116)
		(width 0.14478)
		(layer "In11.Cu")
		(net "M_F_CPU0_SA_DQ<13>")
	)
	(segment
		(start 303.17313 -214.983822)
		(end 303.17313 -214.923116)
		(width 0.14478)
		(layer "In11.Cu")
		(net "M_F_CPU0_SA_DQ<13>")
	)
	(segment
		(start 272.294096 -214.983822)
		(end 272.294096 -214.923116)
		(width 0.14478)
		(layer "In11.Cu")
		(net "M_F_CPU0_SA_DQ<13>")
	)
	(segment
		(start 328.409808 -234.281472)
		(end 328.41819 -234.276646)
		(width 0.0889)
		(layer "In11.Cu")
		(net "M_F_CPU0_SA_DQ<13>")
	)
	(segment
		(start 274.333716 -214.988902)
		(end 274.333716 -214.923116)
		(width 0.14478)
		(layer "In11.Cu")
		(net "M_F_CPU0_SA_DQ<13>")
	)
	(segment
		(start 288.939224 -215.15197)
		(end 289.169602 -215.15197)
		(width 0.14478)
		(layer "In11.Cu")
		(net "M_F_CPU0_SA_DQ<13>")
	)
	(segment
		(start 299.521626 -213.910164)
		(end 301.051976 -213.910164)
		(width 0.14478)
		(layer "In11.Cu")
		(net "M_F_CPU0_SA_DQ<13>")
	)
	(segment
		(start 271.737582 -214.536274)
		(end 271.737582 -214.983822)
		(width 0.14478)
		(layer "In11.Cu")
		(net "M_F_CPU0_SA_DQ<13>")
	)
	(segment
		(start 289.33267 -214.923116)
		(end 289.495738 -214.760048)
		(width 0.14478)
		(layer "In11.Cu")
		(net "M_F_CPU0_SA_DQ<13>")
	)
	(segment
		(start 274.754848 -214.760048)
		(end 275.604732 -213.910164)
		(width 0.14478)
		(layer "In11.Cu")
		(net "M_F_CPU0_SA_DQ<13>")
	)
	(segment
		(start 289.883088 -214.760048)
		(end 290.732972 -213.910164)
		(width 0.14478)
		(layer "In11.Cu")
		(net "M_F_CPU0_SA_DQ<13>")
	)
	(segment
		(start 333.717138 -234.219496)
		(end 333.871062 -233.954066)
		(width 0.0889)
		(layer "In11.Cu")
		(net "M_F_CPU0_SA_DQ<13>")
	)
	(segment
		(start 309.310278 -216.738454)
		(end 314.487814 -221.91599)
		(width 0.14478)
		(layer "In11.Cu")
		(net "M_F_CPU0_SA_DQ<13>")
	)
	(segment
		(start 289.495738 -214.760048)
		(end 289.883088 -214.760048)
		(width 0.14478)
		(layer "In11.Cu")
		(net "M_F_CPU0_SA_DQ<13>")
	)
	(segment
		(start 284.192726 -214.130382)
		(end 284.192726 -214.073232)
		(width 0.14478)
		(layer "In11.Cu")
		(net "M_F_CPU0_SA_DQ<13>")
	)
	(segment
		(start 303.17313 -214.923116)
		(end 303.336198 -214.760048)
		(width 0.14478)
		(layer "In11.Cu")
		(net "M_F_CPU0_SA_DQ<13>")
	)
	(segment
		(start 302.453548 -214.760048)
		(end 302.616616 -214.923116)
		(width 0.14478)
		(layer "In11.Cu")
		(net "M_F_CPU0_SA_DQ<13>")
	)
	(segment
		(start 291.31641 -214.29853)
		(end 291.546788 -214.29853)
		(width 0.14478)
		(layer "In11.Cu")
		(net "M_F_CPU0_SA_DQ<13>")
	)
	(segment
		(start 324.137782 -232.020618)
		(end 324.137782 -232.127298)
		(width 0.0889)
		(layer "In11.Cu")
		(net "M_F_CPU0_SA_DQ<13>")
	)
	(segment
		(start 324.843394 -232.83291)
		(end 325.018654 -232.83291)
		(width 0.0889)
		(layer "In11.Cu")
		(net "M_F_CPU0_SA_DQ<13>")
	)
	(segment
		(start 291.872924 -213.910164)
		(end 293.507922 -213.910164)
		(width 0.14478)
		(layer "In11.Cu")
		(net "M_F_CPU0_SA_DQ<13>")
	)
	(segment
		(start 307.509164 -214.135462)
		(end 307.672232 -214.29853)
		(width 0.14478)
		(layer "In11.Cu")
		(net "M_F_CPU0_SA_DQ<13>")
	)
	(segment
		(start 271.574514 -214.373206)
		(end 271.737582 -214.536274)
		(width 0.14478)
		(layer "In11.Cu")
		(net "M_F_CPU0_SA_DQ<13>")
	)
	(segment
		(start 271.181068 -214.983822)
		(end 271.181068 -214.536274)
		(width 0.14478)
		(layer "In11.Cu")
		(net "M_F_CPU0_SA_DQ<13>")
	)
	(segment
		(start 284.192726 -214.073232)
		(end 284.355794 -213.910164)
		(width 0.14478)
		(layer "In11.Cu")
		(net "M_F_CPU0_SA_DQ<13>")
	)
	(segment
		(start 307.115718 -213.910164)
		(end 307.346096 -213.910164)
		(width 0.14478)
		(layer "In11.Cu")
		(net "M_F_CPU0_SA_DQ<13>")
	)
	(segment
		(start 285.892748 -213.910164)
		(end 286.742632 -214.760048)
		(width 0.14478)
		(layer "In11.Cu")
		(net "M_F_CPU0_SA_DQ<13>")
	)
	(segment
		(start 284.029658 -214.29345)
		(end 284.192726 -214.130382)
		(width 0.14478)
		(layer "In11.Cu")
		(net "M_F_CPU0_SA_DQ<13>")
	)
	(segment
		(start 307.509164 -214.073232)
		(end 307.509164 -214.135462)
		(width 0.14478)
		(layer "In11.Cu")
		(net "M_F_CPU0_SA_DQ<13>")
	)
	(segment
		(start 307.346096 -213.910164)
		(end 307.509164 -214.073232)
		(width 0.14478)
		(layer "In11.Cu")
		(net "M_F_CPU0_SA_DQ<13>")
	)
	(segment
		(start 332.16977 -234.281472)
		(end 332.178152 -234.276646)
		(width 0.0889)
		(layer "In11.Cu")
		(net "M_F_CPU0_SA_DQ<13>")
	)
	(segment
		(start 276.094952 -214.073232)
		(end 276.094952 -214.135462)
		(width 0.14478)
		(layer "In11.Cu")
		(net "M_F_CPU0_SA_DQ<13>")
	)
	(segment
		(start 289.169602 -215.15197)
		(end 289.33267 -214.988902)
		(width 0.14478)
		(layer "In11.Cu")
		(net "M_F_CPU0_SA_DQ<13>")
	)
	(segment
		(start 270.07312 -214.760048)
		(end 270.461486 -214.760048)
		(width 0.14478)
		(layer "In11.Cu")
		(net "M_F_CPU0_SA_DQ<13>")
	)
	(segment
		(start 307.672232 -214.29853)
		(end 307.960522 -214.29853)
		(width 0.14478)
		(layer "In11.Cu")
		(net "M_F_CPU0_SA_DQ<13>")
	)
	(segment
		(start 281.149298 -214.760048)
		(end 281.312366 -214.923116)
		(width 0.14478)
		(layer "In11.Cu")
		(net "M_F_CPU0_SA_DQ<13>")
	)
	(segment
		(start 301.90186 -214.760048)
		(end 302.453548 -214.760048)
		(width 0.14478)
		(layer "In11.Cu")
		(net "M_F_CPU0_SA_DQ<13>")
	)
	(segment
		(start 298.802044 -214.135462)
		(end 298.965112 -214.29853)
		(width 0.14478)
		(layer "In11.Cu")
		(net "M_F_CPU0_SA_DQ<13>")
	)
	(segment
		(start 273.777202 -214.923116)
		(end 273.777202 -214.988902)
		(width 0.14478)
		(layer "In11.Cu")
		(net "M_F_CPU0_SA_DQ<13>")
	)
	(segment
		(start 291.546788 -214.29853)
		(end 291.709856 -214.135462)
		(width 0.14478)
		(layer "In11.Cu")
		(net "M_F_CPU0_SA_DQ<13>")
	)
	(segment
		(start 293.507922 -213.910164)
		(end 294.357806 -214.760048)
		(width 0.14478)
		(layer "In11.Cu")
		(net "M_F_CPU0_SA_DQ<13>")
	)
	(segment
		(start 283.473144 -213.910164)
		(end 283.636212 -214.073232)
		(width 0.14478)
		(layer "In11.Cu")
		(net "M_F_CPU0_SA_DQ<13>")
	)
	(segment
		(start 270.461486 -214.760048)
		(end 270.624554 -214.923116)
		(width 0.14478)
		(layer "In11.Cu")
		(net "M_F_CPU0_SA_DQ<13>")
	)
	(segment
		(start 303.729644 -214.983822)
		(end 303.892712 -215.14689)
		(width 0.14478)
		(layer "In11.Cu")
		(net "M_F_CPU0_SA_DQ<13>")
	)
	(segment
		(start 283.79928 -214.29345)
		(end 284.029658 -214.29345)
		(width 0.14478)
		(layer "In11.Cu")
		(net "M_F_CPU0_SA_DQ<13>")
	)
	(segment
		(start 276.814534 -213.910164)
		(end 278.410924 -213.910164)
		(width 0.14478)
		(layer "In11.Cu")
		(net "M_F_CPU0_SA_DQ<13>")
	)
	(segment
		(start 272.457164 -214.760048)
		(end 273.614134 -214.760048)
		(width 0.14478)
		(layer "In11.Cu")
		(net "M_F_CPU0_SA_DQ<13>")
	)
	(segment
		(start 283.636212 -214.073232)
		(end 283.636212 -214.130382)
		(width 0.14478)
		(layer "In11.Cu")
		(net "M_F_CPU0_SA_DQ<13>")
	)
	(segment
		(start 306.789582 -214.29853)
		(end 306.95265 -214.135462)
		(width 0.14478)
		(layer "In11.Cu")
		(net "M_F_CPU0_SA_DQ<13>")
	)
	(segment
		(start 273.777202 -214.988902)
		(end 273.94027 -215.15197)
		(width 0.14478)
		(layer "In11.Cu")
		(net "M_F_CPU0_SA_DQ<13>")
	)
	(segment
		(start 325.018654 -232.83291)
		(end 325.323454 -233.13771)
		(width 0.0889)
		(layer "In11.Cu")
		(net "M_F_CPU0_SA_DQ<13>")
	)
	(segment
		(start 302.616616 -214.923116)
		(end 302.616616 -214.983822)
		(width 0.14478)
		(layer "In11.Cu")
		(net "M_F_CPU0_SA_DQ<13>")
	)
	(arc
		(start 328.992484 -234.281472)
		(mid 329.175992 -234.326966)
		(end 329.358244 -234.276646)
		(width 0.0889)
		(layer "In11.Cu")
		(net "M_F_CPU0_SA_DQ<13>")
	)
	(arc
		(start 331.238098 -234.276646)
		(mid 331.521054 -234.200469)
		(end 331.80401 -234.276646)
		(width 0.0889)
		(layer "In11.Cu")
		(net "M_F_CPU0_SA_DQ<13>")
	)
	(arc
		(start 331.80401 -234.276646)
		(mid 331.986261 -234.326996)
		(end 332.16977 -234.281472)
		(width 0.0889)
		(layer "In11.Cu")
		(net "M_F_CPU0_SA_DQ<13>")
	)
	(arc
		(start 330.863956 -234.276646)
		(mid 331.046207 -234.326996)
		(end 331.229716 -234.281472)
		(width 0.0889)
		(layer "In11.Cu")
		(net "M_F_CPU0_SA_DQ<13>")
	)
	(arc
		(start 329.924156 -234.276646)
		(mid 330.1111 -234.326901)
		(end 330.298044 -234.276646)
		(width 0.0889)
		(layer "In11.Cu")
		(net "M_F_CPU0_SA_DQ<13>")
	)
	(arc
		(start 326.548242 -234.27055)
		(mid 326.826674 -234.200452)
		(end 327.103486 -234.276646)
		(width 0.0889)
		(layer "In11.Cu")
		(net "M_F_CPU0_SA_DQ<13>")
	)
	(arc
		(start 328.41819 -234.276646)
		(mid 328.701146 -234.200469)
		(end 328.984102 -234.276646)
		(width 0.0889)
		(layer "In11.Cu")
		(net "M_F_CPU0_SA_DQ<13>")
	)
	(arc
		(start 332.752446 -234.281472)
		(mid 332.935954 -234.326966)
		(end 333.118206 -234.276646)
		(width 0.0889)
		(layer "In11.Cu")
		(net "M_F_CPU0_SA_DQ<13>")
	)
	(arc
		(start 328.044048 -234.276646)
		(mid 328.226299 -234.326996)
		(end 328.409808 -234.281472)
		(width 0.0889)
		(layer "In11.Cu")
		(net "M_F_CPU0_SA_DQ<13>")
	)
	(arc
		(start 333.118206 -234.276646)
		(mid 333.365919 -234.201426)
		(end 333.621126 -234.244896)
		(width 0.0889)
		(layer "In11.Cu")
		(net "M_F_CPU0_SA_DQ<13>")
	)
	(arc
		(start 327.103486 -234.276646)
		(mid 327.290684 -234.327028)
		(end 327.477882 -234.276646)
		(width 0.0889)
		(layer "In11.Cu")
		(net "M_F_CPU0_SA_DQ<13>")
	)
	(arc
		(start 332.178152 -234.276646)
		(mid 332.461108 -234.200469)
		(end 332.744064 -234.276646)
		(width 0.0889)
		(layer "In11.Cu")
		(net "M_F_CPU0_SA_DQ<13>")
	)
	(arc
		(start 326.087486 -234.217972)
		(mid 326.294445 -234.322773)
		(end 326.52335 -234.285028)
		(width 0.0889)
		(layer "In11.Cu")
		(net "M_F_CPU0_SA_DQ<13>")
	)
	(arc
		(start 330.298044 -234.276646)
		(mid 330.581 -234.200469)
		(end 330.863956 -234.276646)
		(width 0.0889)
		(layer "In11.Cu")
		(net "M_F_CPU0_SA_DQ<13>")
	)
	(arc
		(start 329.358244 -234.276646)
		(mid 329.6412 -234.200469)
		(end 329.924156 -234.276646)
		(width 0.0889)
		(layer "In11.Cu")
		(net "M_F_CPU0_SA_DQ<13>")
	)
	(arc
		(start 327.477882 -234.276646)
		(mid 327.754949 -234.200375)
		(end 328.033634 -234.27055)
		(width 0.0889)
		(layer "In11.Cu")
		(net "M_F_CPU0_SA_DQ<13>")
	)
	(segment
		(start 332.92796 -233.409998)
		(end 332.461108 -233.14406)
		(width 0.10668)
		(layer "F.Cu")
		(net "M_F_CPU0_SA_DQ<12>")
	)
	(segment
		(start 294.367458 -213.069678)
		(end 296.242486 -213.069678)
		(width 0.14478)
		(layer "In11.Cu")
		(net "M_F_CPU0_SA_DQ<12>")
	)
	(segment
		(start 281.248358 -213.069678)
		(end 281.401774 -213.223094)
		(width 0.14478)
		(layer "In11.Cu")
		(net "M_F_CPU0_SA_DQ<12>")
	)
	(segment
		(start 291.16528 -212.37321)
		(end 291.16528 -212.441282)
		(width 0.14478)
		(layer "In11.Cu")
		(net "M_F_CPU0_SA_DQ<12>")
	)
	(segment
		(start 303.90211 -213.45017)
		(end 304.065178 -213.287102)
		(width 0.14478)
		(layer "In11.Cu")
		(net "M_F_CPU0_SA_DQ<12>")
	)
	(segment
		(start 272.5166 -213.069678)
		(end 273.731228 -213.069678)
		(width 0.14478)
		(layer "In11.Cu")
		(net "M_F_CPU0_SA_DQ<12>")
	)
	(segment
		(start 288.53892 -213.069678)
		(end 288.692336 -213.223094)
		(width 0.14478)
		(layer "In11.Cu")
		(net "M_F_CPU0_SA_DQ<12>")
	)
	(segment
		(start 291.721794 -212.37321)
		(end 291.87521 -212.219794)
		(width 0.14478)
		(layer "In11.Cu")
		(net "M_F_CPU0_SA_DQ<12>")
	)
	(segment
		(start 275.969476 -212.37321)
		(end 275.969476 -212.428582)
		(width 0.14478)
		(layer "In11.Cu")
		(net "M_F_CPU0_SA_DQ<12>")
	)
	(segment
		(start 291.721794 -212.441282)
		(end 291.721794 -212.37321)
		(width 0.14478)
		(layer "In11.Cu")
		(net "M_F_CPU0_SA_DQ<12>")
	)
	(segment
		(start 272.363184 -213.287102)
		(end 272.363184 -213.223094)
		(width 0.14478)
		(layer "In11.Cu")
		(net "M_F_CPU0_SA_DQ<12>")
	)
	(segment
		(start 306.767484 -212.37321)
		(end 306.930552 -212.210142)
		(width 0.14478)
		(layer "In11.Cu")
		(net "M_F_CPU0_SA_DQ<12>")
	)
	(segment
		(start 323.895974 -230.88219)
		(end 324.44817 -231.434386)
		(width 0.0889)
		(layer "In11.Cu")
		(net "M_F_CPU0_SA_DQ<12>")
	)
	(segment
		(start 274.441158 -213.282022)
		(end 274.441158 -213.223094)
		(width 0.14478)
		(layer "In11.Cu")
		(net "M_F_CPU0_SA_DQ<12>")
	)
	(segment
		(start 304.228246 -213.060026)
		(end 304.894742 -213.060026)
		(width 0.14478)
		(layer "In11.Cu")
		(net "M_F_CPU0_SA_DQ<12>")
	)
	(segment
		(start 275.806408 -212.210142)
		(end 275.969476 -212.37321)
		(width 0.14478)
		(layer "In11.Cu")
		(net "M_F_CPU0_SA_DQ<12>")
	)
	(segment
		(start 274.441158 -213.223094)
		(end 274.604226 -213.060026)
		(width 0.14478)
		(layer "In11.Cu")
		(net "M_F_CPU0_SA_DQ<12>")
	)
	(segment
		(start 296.395902 -213.223094)
		(end 296.395902 -213.287102)
		(width 0.14478)
		(layer "In11.Cu")
		(net "M_F_CPU0_SA_DQ<12>")
	)
	(segment
		(start 281.564842 -213.44509)
		(end 281.79522 -213.44509)
		(width 0.14478)
		(layer "In11.Cu")
		(net "M_F_CPU0_SA_DQ<12>")
	)
	(segment
		(start 332.307184 -233.40949)
		(end 332.461108 -233.14406)
		(width 0.0889)
		(layer "In11.Cu")
		(net "M_F_CPU0_SA_DQ<12>")
	)
	(segment
		(start 291.16528 -212.441282)
		(end 291.328348 -212.60435)
		(width 0.14478)
		(layer "In11.Cu")
		(net "M_F_CPU0_SA_DQ<12>")
	)
	(segment
		(start 302.95215 -213.287102)
		(end 302.95215 -212.927438)
		(width 0.14478)
		(layer "In11.Cu")
		(net "M_F_CPU0_SA_DQ<12>")
	)
	(segment
		(start 285.9024 -212.219794)
		(end 286.752284 -213.069678)
		(width 0.14478)
		(layer "In11.Cu")
		(net "M_F_CPU0_SA_DQ<12>")
	)
	(segment
		(start 302.395636 -213.287102)
		(end 302.558704 -213.45017)
		(width 0.14478)
		(layer "In11.Cu")
		(net "M_F_CPU0_SA_DQ<12>")
	)
	(segment
		(start 276.362922 -212.59165)
		(end 276.52599 -212.428582)
		(width 0.14478)
		(layer "In11.Cu")
		(net "M_F_CPU0_SA_DQ<12>")
	)
	(segment
		(start 306.047902 -212.210142)
		(end 306.21097 -212.37321)
		(width 0.14478)
		(layer "In11.Cu")
		(net "M_F_CPU0_SA_DQ<12>")
	)
	(segment
		(start 272.363184 -213.223094)
		(end 272.5166 -213.069678)
		(width 0.14478)
		(layer "In11.Cu")
		(net "M_F_CPU0_SA_DQ<12>")
	)
	(segment
		(start 301.061628 -212.219794)
		(end 301.90186 -213.060026)
		(width 0.14478)
		(layer "In11.Cu")
		(net "M_F_CPU0_SA_DQ<12>")
	)
	(segment
		(start 272.200116 -213.45017)
		(end 272.363184 -213.287102)
		(width 0.14478)
		(layer "In11.Cu")
		(net "M_F_CPU0_SA_DQ<12>")
	)
	(segment
		(start 269.648178 -212.635084)
		(end 270.07312 -213.060026)
		(width 0.14478)
		(layer "In11.Cu")
		(net "M_F_CPU0_SA_DQ<12>")
	)
	(segment
		(start 293.517574 -212.219794)
		(end 294.367458 -213.069678)
		(width 0.14478)
		(layer "In11.Cu")
		(net "M_F_CPU0_SA_DQ<12>")
	)
	(segment
		(start 274.604226 -213.060026)
		(end 274.754848 -213.060026)
		(width 0.14478)
		(layer "In11.Cu")
		(net "M_F_CPU0_SA_DQ<12>")
	)
	(segment
		(start 275.969476 -212.428582)
		(end 276.132544 -212.59165)
		(width 0.14478)
		(layer "In11.Cu")
		(net "M_F_CPU0_SA_DQ<12>")
	)
	(segment
		(start 324.44817 -231.434386)
		(end 324.91299 -231.434386)
		(width 0.0889)
		(layer "In11.Cu")
		(net "M_F_CPU0_SA_DQ<12>")
	)
	(segment
		(start 302.558704 -213.45017)
		(end 302.789082 -213.45017)
		(width 0.14478)
		(layer "In11.Cu")
		(net "M_F_CPU0_SA_DQ<12>")
	)
	(segment
		(start 307.16093 -212.210142)
		(end 307.323998 -212.37321)
		(width 0.14478)
		(layer "In11.Cu")
		(net "M_F_CPU0_SA_DQ<12>")
	)
	(segment
		(start 302.395636 -213.223094)
		(end 302.395636 -213.287102)
		(width 0.14478)
		(layer "In11.Cu")
		(net "M_F_CPU0_SA_DQ<12>")
	)
	(segment
		(start 307.323998 -212.441282)
		(end 307.487066 -212.60435)
		(width 0.14478)
		(layer "In11.Cu")
		(net "M_F_CPU0_SA_DQ<12>")
	)
	(segment
		(start 298.501816 -212.210142)
		(end 298.664884 -212.37321)
		(width 0.14478)
		(layer "In11.Cu")
		(net "M_F_CPU0_SA_DQ<12>")
	)
	(segment
		(start 296.55897 -213.45017)
		(end 296.789348 -213.45017)
		(width 0.14478)
		(layer "In11.Cu")
		(net "M_F_CPU0_SA_DQ<12>")
	)
	(segment
		(start 270.709898 -212.26653)
		(end 270.940276 -212.26653)
		(width 0.14478)
		(layer "In11.Cu")
		(net "M_F_CPU0_SA_DQ<12>")
	)
	(segment
		(start 299.221398 -212.438742)
		(end 299.221398 -212.37321)
		(width 0.14478)
		(layer "In11.Cu")
		(net "M_F_CPU0_SA_DQ<12>")
	)
	(segment
		(start 296.242486 -213.069678)
		(end 296.395902 -213.223094)
		(width 0.14478)
		(layer "In11.Cu")
		(net "M_F_CPU0_SA_DQ<12>")
	)
	(segment
		(start 301.90186 -213.060026)
		(end 302.232568 -213.060026)
		(width 0.14478)
		(layer "In11.Cu")
		(net "M_F_CPU0_SA_DQ<12>")
	)
	(segment
		(start 306.21097 -212.441282)
		(end 306.374038 -212.60435)
		(width 0.14478)
		(layer "In11.Cu")
		(net "M_F_CPU0_SA_DQ<12>")
	)
	(segment
		(start 291.87521 -212.219794)
		(end 293.517574 -212.219794)
		(width 0.14478)
		(layer "In11.Cu")
		(net "M_F_CPU0_SA_DQ<12>")
	)
	(segment
		(start 291.328348 -212.60435)
		(end 291.558726 -212.60435)
		(width 0.14478)
		(layer "In11.Cu")
		(net "M_F_CPU0_SA_DQ<12>")
	)
	(segment
		(start 278.420576 -212.219794)
		(end 279.27046 -213.069678)
		(width 0.14478)
		(layer "In11.Cu")
		(net "M_F_CPU0_SA_DQ<12>")
	)
	(segment
		(start 307.323998 -212.37321)
		(end 307.323998 -212.441282)
		(width 0.14478)
		(layer "In11.Cu")
		(net "M_F_CPU0_SA_DQ<12>")
	)
	(segment
		(start 271.643602 -213.060026)
		(end 271.80667 -213.223094)
		(width 0.14478)
		(layer "In11.Cu")
		(net "M_F_CPU0_SA_DQ<12>")
	)
	(segment
		(start 327.562464 -233.459528)
		(end 327.574402 -233.466386)
		(width 0.0889)
		(layer "In11.Cu")
		(net "M_F_CPU0_SA_DQ<12>")
	)
	(segment
		(start 283.683964 -212.433662)
		(end 283.847032 -212.59673)
		(width 0.14478)
		(layer "In11.Cu")
		(net "M_F_CPU0_SA_DQ<12>")
	)
	(segment
		(start 304.894742 -213.060026)
		(end 305.744626 -212.210142)
		(width 0.14478)
		(layer "In11.Cu")
		(net "M_F_CPU0_SA_DQ<12>")
	)
	(segment
		(start 276.52599 -212.37321)
		(end 276.679406 -212.219794)
		(width 0.14478)
		(layer "In11.Cu")
		(net "M_F_CPU0_SA_DQ<12>")
	)
	(segment
		(start 297.389042 -213.060026)
		(end 298.238926 -212.210142)
		(width 0.14478)
		(layer "In11.Cu")
		(net "M_F_CPU0_SA_DQ<12>")
	)
	(segment
		(start 296.395902 -213.287102)
		(end 296.55897 -213.45017)
		(width 0.14478)
		(layer "In11.Cu")
		(net "M_F_CPU0_SA_DQ<12>")
	)
	(segment
		(start 284.240478 -212.433662)
		(end 284.240478 -212.37321)
		(width 0.14478)
		(layer "In11.Cu")
		(net "M_F_CPU0_SA_DQ<12>")
	)
	(segment
		(start 289.883088 -213.060026)
		(end 290.732972 -212.210142)
		(width 0.14478)
		(layer "In11.Cu")
		(net "M_F_CPU0_SA_DQ<12>")
	)
	(segment
		(start 325.10857 -231.629966)
		(end 325.10857 -232.287826)
		(width 0.0889)
		(layer "In11.Cu")
		(net "M_F_CPU0_SA_DQ<12>")
	)
	(segment
		(start 296.952416 -213.223094)
		(end 297.115484 -213.060026)
		(width 0.14478)
		(layer "In11.Cu")
		(net "M_F_CPU0_SA_DQ<12>")
	)
	(segment
		(start 286.752284 -213.069678)
		(end 288.53892 -213.069678)
		(width 0.14478)
		(layer "In11.Cu")
		(net "M_F_CPU0_SA_DQ<12>")
	)
	(segment
		(start 281.401774 -213.223094)
		(end 281.401774 -213.282022)
		(width 0.14478)
		(layer "In11.Cu")
		(net "M_F_CPU0_SA_DQ<12>")
	)
	(segment
		(start 303.115218 -212.76437)
		(end 303.345596 -212.76437)
		(width 0.14478)
		(layer "In11.Cu")
		(net "M_F_CPU0_SA_DQ<12>")
	)
	(segment
		(start 270.383762 -213.060026)
		(end 270.54683 -212.896958)
		(width 0.14478)
		(layer "In11.Cu")
		(net "M_F_CPU0_SA_DQ<12>")
	)
	(segment
		(start 283.847032 -212.59673)
		(end 284.07741 -212.59673)
		(width 0.14478)
		(layer "In11.Cu")
		(net "M_F_CPU0_SA_DQ<12>")
	)
	(segment
		(start 304.065178 -213.287102)
		(end 304.065178 -213.223094)
		(width 0.14478)
		(layer "In11.Cu")
		(net "M_F_CPU0_SA_DQ<12>")
	)
	(segment
		(start 307.487066 -212.60435)
		(end 307.761894 -212.60435)
		(width 0.14478)
		(layer "In11.Cu")
		(net "M_F_CPU0_SA_DQ<12>")
	)
	(segment
		(start 326.997568 -233.473498)
		(end 327.009252 -233.46664)
		(width 0.0889)
		(layer "In11.Cu")
		(net "M_F_CPU0_SA_DQ<12>")
	)
	(segment
		(start 271.80667 -213.287102)
		(end 271.969738 -213.45017)
		(width 0.14478)
		(layer "In11.Cu")
		(net "M_F_CPU0_SA_DQ<12>")
	)
	(segment
		(start 306.930552 -212.210142)
		(end 307.16093 -212.210142)
		(width 0.14478)
		(layer "In11.Cu")
		(net "M_F_CPU0_SA_DQ<12>")
	)
	(segment
		(start 323.362574 -230.88219)
		(end 323.568314 -230.88219)
		(width 0.14478)
		(layer "In11.Cu")
		(net "M_F_CPU0_SA_DQ<12>")
	)
	(segment
		(start 274.754848 -213.060026)
		(end 275.604732 -212.210142)
		(width 0.14478)
		(layer "In11.Cu")
		(net "M_F_CPU0_SA_DQ<12>")
	)
	(segment
		(start 270.07312 -213.060026)
		(end 270.383762 -213.060026)
		(width 0.14478)
		(layer "In11.Cu")
		(net "M_F_CPU0_SA_DQ<12>")
	)
	(segment
		(start 288.692336 -213.223094)
		(end 288.692336 -213.287102)
		(width 0.14478)
		(layer "In11.Cu")
		(net "M_F_CPU0_SA_DQ<12>")
	)
	(segment
		(start 290.732972 -212.210142)
		(end 291.002212 -212.210142)
		(width 0.14478)
		(layer "In11.Cu")
		(net "M_F_CPU0_SA_DQ<12>")
	)
	(segment
		(start 303.508664 -212.927438)
		(end 303.508664 -213.287102)
		(width 0.14478)
		(layer "In11.Cu")
		(net "M_F_CPU0_SA_DQ<12>")
	)
	(segment
		(start 323.568314 -230.88219)
		(end 323.895974 -230.88219)
		(width 0.0889)
		(layer "In11.Cu")
		(net "M_F_CPU0_SA_DQ<12>")
	)
	(segment
		(start 271.80667 -213.223094)
		(end 271.80667 -213.287102)
		(width 0.14478)
		(layer "In11.Cu")
		(net "M_F_CPU0_SA_DQ<12>")
	)
	(segment
		(start 296.952416 -213.287102)
		(end 296.952416 -213.223094)
		(width 0.14478)
		(layer "In11.Cu")
		(net "M_F_CPU0_SA_DQ<12>")
	)
	(segment
		(start 291.002212 -212.210142)
		(end 291.16528 -212.37321)
		(width 0.14478)
		(layer "In11.Cu")
		(net "M_F_CPU0_SA_DQ<12>")
	)
	(segment
		(start 282.323286 -213.060026)
		(end 283.17317 -212.210142)
		(width 0.14478)
		(layer "In11.Cu")
		(net "M_F_CPU0_SA_DQ<12>")
	)
	(segment
		(start 281.958288 -213.223094)
		(end 282.121356 -213.060026)
		(width 0.14478)
		(layer "In11.Cu")
		(net "M_F_CPU0_SA_DQ<12>")
	)
	(segment
		(start 281.79522 -213.44509)
		(end 281.958288 -213.282022)
		(width 0.14478)
		(layer "In11.Cu")
		(net "M_F_CPU0_SA_DQ<12>")
	)
	(segment
		(start 298.827952 -212.60181)
		(end 299.05833 -212.60181)
		(width 0.14478)
		(layer "In11.Cu")
		(net "M_F_CPU0_SA_DQ<12>")
	)
	(segment
		(start 298.664884 -212.438742)
		(end 298.827952 -212.60181)
		(width 0.14478)
		(layer "In11.Cu")
		(net "M_F_CPU0_SA_DQ<12>")
	)
	(segment
		(start 289.085782 -213.45017)
		(end 289.24885 -213.287102)
		(width 0.14478)
		(layer "In11.Cu")
		(net "M_F_CPU0_SA_DQ<12>")
	)
	(segment
		(start 274.27809 -213.44509)
		(end 274.441158 -213.282022)
		(width 0.14478)
		(layer "In11.Cu")
		(net "M_F_CPU0_SA_DQ<12>")
	)
	(segment
		(start 306.21097 -212.37321)
		(end 306.21097 -212.441282)
		(width 0.14478)
		(layer "In11.Cu")
		(net "M_F_CPU0_SA_DQ<12>")
	)
	(segment
		(start 302.232568 -213.060026)
		(end 302.395636 -213.223094)
		(width 0.14478)
		(layer "In11.Cu")
		(net "M_F_CPU0_SA_DQ<12>")
	)
	(segment
		(start 303.508664 -213.287102)
		(end 303.671732 -213.45017)
		(width 0.14478)
		(layer "In11.Cu")
		(net "M_F_CPU0_SA_DQ<12>")
	)
	(segment
		(start 326.21093 -233.390186)
		(end 326.351138 -233.390186)
		(width 0.0889)
		(layer "In11.Cu")
		(net "M_F_CPU0_SA_DQ<12>")
	)
	(segment
		(start 273.884644 -213.282022)
		(end 274.047712 -213.44509)
		(width 0.14478)
		(layer "In11.Cu")
		(net "M_F_CPU0_SA_DQ<12>")
	)
	(segment
		(start 274.047712 -213.44509)
		(end 274.27809 -213.44509)
		(width 0.14478)
		(layer "In11.Cu")
		(net "M_F_CPU0_SA_DQ<12>")
	)
	(segment
		(start 281.958288 -213.282022)
		(end 281.958288 -213.223094)
		(width 0.14478)
		(layer "In11.Cu")
		(net "M_F_CPU0_SA_DQ<12>")
	)
	(segment
		(start 282.121356 -213.060026)
		(end 282.323286 -213.060026)
		(width 0.14478)
		(layer "In11.Cu")
		(net "M_F_CPU0_SA_DQ<12>")
	)
	(segment
		(start 305.744626 -212.210142)
		(end 306.047902 -212.210142)
		(width 0.14478)
		(layer "In11.Cu")
		(net "M_F_CPU0_SA_DQ<12>")
	)
	(segment
		(start 306.604416 -212.60435)
		(end 306.767484 -212.441282)
		(width 0.14478)
		(layer "In11.Cu")
		(net "M_F_CPU0_SA_DQ<12>")
	)
	(segment
		(start 298.238926 -212.210142)
		(end 298.501816 -212.210142)
		(width 0.14478)
		(layer "In11.Cu")
		(net "M_F_CPU0_SA_DQ<12>")
	)
	(segment
		(start 279.27046 -213.069678)
		(end 281.248358 -213.069678)
		(width 0.14478)
		(layer "In11.Cu")
		(net "M_F_CPU0_SA_DQ<12>")
	)
	(segment
		(start 327.574402 -233.466386)
		(end 327.590658 -233.475784)
		(width 0.0889)
		(layer "In11.Cu")
		(net "M_F_CPU0_SA_DQ<12>")
	)
	(segment
		(start 281.401774 -213.282022)
		(end 281.564842 -213.44509)
		(width 0.14478)
		(layer "In11.Cu")
		(net "M_F_CPU0_SA_DQ<12>")
	)
	(segment
		(start 271.103344 -212.429598)
		(end 271.103344 -212.896958)
		(width 0.14478)
		(layer "In11.Cu")
		(net "M_F_CPU0_SA_DQ<12>")
	)
	(segment
		(start 291.558726 -212.60435)
		(end 291.721794 -212.441282)
		(width 0.14478)
		(layer "In11.Cu")
		(net "M_F_CPU0_SA_DQ<12>")
	)
	(segment
		(start 299.05833 -212.60181)
		(end 299.221398 -212.438742)
		(width 0.14478)
		(layer "In11.Cu")
		(net "M_F_CPU0_SA_DQ<12>")
	)
	(segment
		(start 302.789082 -213.45017)
		(end 302.95215 -213.287102)
		(width 0.14478)
		(layer "In11.Cu")
		(net "M_F_CPU0_SA_DQ<12>")
	)
	(segment
		(start 273.731228 -213.069678)
		(end 273.884644 -213.223094)
		(width 0.14478)
		(layer "In11.Cu")
		(net "M_F_CPU0_SA_DQ<12>")
	)
	(segment
		(start 288.855404 -213.45017)
		(end 289.085782 -213.45017)
		(width 0.14478)
		(layer "In11.Cu")
		(net "M_F_CPU0_SA_DQ<12>")
	)
	(segment
		(start 307.761894 -212.60435)
		(end 310.222138 -215.064594)
		(width 0.14478)
		(layer "In11.Cu")
		(net "M_F_CPU0_SA_DQ<12>")
	)
	(segment
		(start 271.969738 -213.45017)
		(end 272.200116 -213.45017)
		(width 0.14478)
		(layer "In11.Cu")
		(net "M_F_CPU0_SA_DQ<12>")
	)
	(segment
		(start 302.95215 -212.927438)
		(end 303.115218 -212.76437)
		(width 0.14478)
		(layer "In11.Cu")
		(net "M_F_CPU0_SA_DQ<12>")
	)
	(segment
		(start 306.374038 -212.60435)
		(end 306.604416 -212.60435)
		(width 0.14478)
		(layer "In11.Cu")
		(net "M_F_CPU0_SA_DQ<12>")
	)
	(segment
		(start 332.211172 -233.43489)
		(end 332.307184 -233.40949)
		(width 0.0889)
		(layer "In11.Cu")
		(net "M_F_CPU0_SA_DQ<12>")
	)
	(segment
		(start 284.240478 -212.37321)
		(end 284.393894 -212.219794)
		(width 0.14478)
		(layer "In11.Cu")
		(net "M_F_CPU0_SA_DQ<12>")
	)
	(segment
		(start 271.103344 -212.896958)
		(end 271.266412 -213.060026)
		(width 0.14478)
		(layer "In11.Cu")
		(net "M_F_CPU0_SA_DQ<12>")
	)
	(segment
		(start 271.266412 -213.060026)
		(end 271.643602 -213.060026)
		(width 0.14478)
		(layer "In11.Cu")
		(net "M_F_CPU0_SA_DQ<12>")
	)
	(segment
		(start 299.221398 -212.37321)
		(end 299.374814 -212.219794)
		(width 0.14478)
		(layer "In11.Cu")
		(net "M_F_CPU0_SA_DQ<12>")
	)
	(segment
		(start 283.683964 -212.37321)
		(end 283.683964 -212.433662)
		(width 0.14478)
		(layer "In11.Cu")
		(net "M_F_CPU0_SA_DQ<12>")
	)
	(segment
		(start 270.54683 -212.896958)
		(end 270.54683 -212.429598)
		(width 0.14478)
		(layer "In11.Cu")
		(net "M_F_CPU0_SA_DQ<12>")
	)
	(segment
		(start 325.10857 -232.287826)
		(end 326.21093 -233.390186)
		(width 0.0889)
		(layer "In11.Cu")
		(net "M_F_CPU0_SA_DQ<12>")
	)
	(segment
		(start 276.132544 -212.59165)
		(end 276.362922 -212.59165)
		(width 0.14478)
		(layer "In11.Cu")
		(net "M_F_CPU0_SA_DQ<12>")
	)
	(segment
		(start 315.397134 -221.539054)
		(end 315.397134 -222.91675)
		(width 0.14478)
		(layer "In11.Cu")
		(net "M_F_CPU0_SA_DQ<12>")
	)
	(segment
		(start 288.692336 -213.287102)
		(end 288.855404 -213.45017)
		(width 0.14478)
		(layer "In11.Cu")
		(net "M_F_CPU0_SA_DQ<12>")
	)
	(segment
		(start 303.345596 -212.76437)
		(end 303.508664 -212.927438)
		(width 0.14478)
		(layer "In11.Cu")
		(net "M_F_CPU0_SA_DQ<12>")
	)
	(segment
		(start 297.115484 -213.060026)
		(end 297.389042 -213.060026)
		(width 0.14478)
		(layer "In11.Cu")
		(net "M_F_CPU0_SA_DQ<12>")
	)
	(segment
		(start 315.397134 -222.91675)
		(end 323.362574 -230.88219)
		(width 0.14478)
		(layer "In11.Cu")
		(net "M_F_CPU0_SA_DQ<12>")
	)
	(segment
		(start 289.411918 -213.060026)
		(end 289.883088 -213.060026)
		(width 0.14478)
		(layer "In11.Cu")
		(net "M_F_CPU0_SA_DQ<12>")
	)
	(segment
		(start 273.884644 -213.223094)
		(end 273.884644 -213.282022)
		(width 0.14478)
		(layer "In11.Cu")
		(net "M_F_CPU0_SA_DQ<12>")
	)
	(segment
		(start 298.664884 -212.37321)
		(end 298.664884 -212.438742)
		(width 0.14478)
		(layer "In11.Cu")
		(net "M_F_CPU0_SA_DQ<12>")
	)
	(segment
		(start 270.54683 -212.429598)
		(end 270.709898 -212.26653)
		(width 0.14478)
		(layer "In11.Cu")
		(net "M_F_CPU0_SA_DQ<12>")
	)
	(segment
		(start 296.789348 -213.45017)
		(end 296.952416 -213.287102)
		(width 0.14478)
		(layer "In11.Cu")
		(net "M_F_CPU0_SA_DQ<12>")
	)
	(segment
		(start 324.91299 -231.434386)
		(end 325.10857 -231.629966)
		(width 0.0889)
		(layer "In11.Cu")
		(net "M_F_CPU0_SA_DQ<12>")
	)
	(segment
		(start 270.940276 -212.26653)
		(end 271.103344 -212.429598)
		(width 0.14478)
		(layer "In11.Cu")
		(net "M_F_CPU0_SA_DQ<12>")
	)
	(segment
		(start 330.394056 -233.46664)
		(end 330.402438 -233.471466)
		(width 0.0889)
		(layer "In11.Cu")
		(net "M_F_CPU0_SA_DQ<12>")
	)
	(segment
		(start 284.07741 -212.59673)
		(end 284.240478 -212.433662)
		(width 0.14478)
		(layer "In11.Cu")
		(net "M_F_CPU0_SA_DQ<12>")
	)
	(segment
		(start 310.222138 -215.064594)
		(end 310.222138 -216.364058)
		(width 0.14478)
		(layer "In11.Cu")
		(net "M_F_CPU0_SA_DQ<12>")
	)
	(segment
		(start 303.671732 -213.45017)
		(end 303.90211 -213.45017)
		(width 0.14478)
		(layer "In11.Cu")
		(net "M_F_CPU0_SA_DQ<12>")
	)
	(segment
		(start 283.520896 -212.210142)
		(end 283.683964 -212.37321)
		(width 0.14478)
		(layer "In11.Cu")
		(net "M_F_CPU0_SA_DQ<12>")
	)
	(segment
		(start 310.222138 -216.364058)
		(end 315.397134 -221.539054)
		(width 0.14478)
		(layer "In11.Cu")
		(net "M_F_CPU0_SA_DQ<12>")
	)
	(segment
		(start 299.374814 -212.219794)
		(end 301.061628 -212.219794)
		(width 0.14478)
		(layer "In11.Cu")
		(net "M_F_CPU0_SA_DQ<12>")
	)
	(segment
		(start 331.33411 -233.46664)
		(end 331.342492 -233.471466)
		(width 0.0889)
		(layer "In11.Cu")
		(net "M_F_CPU0_SA_DQ<12>")
	)
	(segment
		(start 304.065178 -213.223094)
		(end 304.228246 -213.060026)
		(width 0.14478)
		(layer "In11.Cu")
		(net "M_F_CPU0_SA_DQ<12>")
	)
	(segment
		(start 289.24885 -213.287102)
		(end 289.24885 -213.223094)
		(width 0.14478)
		(layer "In11.Cu")
		(net "M_F_CPU0_SA_DQ<12>")
	)
	(segment
		(start 284.393894 -212.219794)
		(end 285.9024 -212.219794)
		(width 0.14478)
		(layer "In11.Cu")
		(net "M_F_CPU0_SA_DQ<12>")
	)
	(segment
		(start 283.17317 -212.210142)
		(end 283.520896 -212.210142)
		(width 0.14478)
		(layer "In11.Cu")
		(net "M_F_CPU0_SA_DQ<12>")
	)
	(segment
		(start 276.52599 -212.428582)
		(end 276.52599 -212.37321)
		(width 0.14478)
		(layer "In11.Cu")
		(net "M_F_CPU0_SA_DQ<12>")
	)
	(segment
		(start 329.819762 -233.471466)
		(end 329.828144 -233.46664)
		(width 0.0889)
		(layer "In11.Cu")
		(net "M_F_CPU0_SA_DQ<12>")
	)
	(segment
		(start 289.24885 -213.223094)
		(end 289.411918 -213.060026)
		(width 0.14478)
		(layer "In11.Cu")
		(net "M_F_CPU0_SA_DQ<12>")
	)
	(segment
		(start 306.767484 -212.441282)
		(end 306.767484 -212.37321)
		(width 0.14478)
		(layer "In11.Cu")
		(net "M_F_CPU0_SA_DQ<12>")
	)
	(segment
		(start 276.679406 -212.219794)
		(end 278.420576 -212.219794)
		(width 0.14478)
		(layer "In11.Cu")
		(net "M_F_CPU0_SA_DQ<12>")
	)
	(segment
		(start 275.604732 -212.210142)
		(end 275.806408 -212.210142)
		(width 0.14478)
		(layer "In11.Cu")
		(net "M_F_CPU0_SA_DQ<12>")
	)
	(arc
		(start 329.828144 -233.46664)
		(mid 330.1111 -233.390463)
		(end 330.394056 -233.46664)
		(width 0.0889)
		(layer "In11.Cu")
		(net "M_F_CPU0_SA_DQ<12>")
	)
	(arc
		(start 331.342492 -233.471466)
		(mid 331.526 -233.51696)
		(end 331.708252 -233.46664)
		(width 0.0889)
		(layer "In11.Cu")
		(net "M_F_CPU0_SA_DQ<12>")
	)
	(arc
		(start 330.768198 -233.46664)
		(mid 331.051154 -233.390463)
		(end 331.33411 -233.46664)
		(width 0.0889)
		(layer "In11.Cu")
		(net "M_F_CPU0_SA_DQ<12>")
	)
	(arc
		(start 330.402438 -233.471466)
		(mid 330.585946 -233.51696)
		(end 330.768198 -233.46664)
		(width 0.0889)
		(layer "In11.Cu")
		(net "M_F_CPU0_SA_DQ<12>")
	)
	(arc
		(start 328.88809 -233.46664)
		(mid 329.171046 -233.390463)
		(end 329.454002 -233.46664)
		(width 0.0889)
		(layer "In11.Cu")
		(net "M_F_CPU0_SA_DQ<12>")
	)
	(arc
		(start 327.009252 -233.46664)
		(mid 327.28493 -233.39051)
		(end 327.562464 -233.459528)
		(width 0.0889)
		(layer "In11.Cu")
		(net "M_F_CPU0_SA_DQ<12>")
	)
	(arc
		(start 327.94829 -233.46664)
		(mid 328.231246 -233.390463)
		(end 328.514202 -233.46664)
		(width 0.0889)
		(layer "In11.Cu")
		(net "M_F_CPU0_SA_DQ<12>")
	)
	(arc
		(start 328.514202 -233.46664)
		(mid 328.701146 -233.516895)
		(end 328.88809 -233.46664)
		(width 0.0889)
		(layer "In11.Cu")
		(net "M_F_CPU0_SA_DQ<12>")
	)
	(arc
		(start 326.634856 -233.46664)
		(mid 326.815314 -233.517084)
		(end 326.997568 -233.473498)
		(width 0.0889)
		(layer "In11.Cu")
		(net "M_F_CPU0_SA_DQ<12>")
	)
	(arc
		(start 327.590658 -233.475784)
		(mid 327.77064 -233.516884)
		(end 327.94829 -233.46664)
		(width 0.0889)
		(layer "In11.Cu")
		(net "M_F_CPU0_SA_DQ<12>")
	)
	(arc
		(start 326.351138 -233.390186)
		(mid 326.498069 -233.409597)
		(end 326.634856 -233.46664)
		(width 0.0889)
		(layer "In11.Cu")
		(net "M_F_CPU0_SA_DQ<12>")
	)
	(arc
		(start 329.454002 -233.46664)
		(mid 329.636253 -233.51699)
		(end 329.819762 -233.471466)
		(width 0.0889)
		(layer "In11.Cu")
		(net "M_F_CPU0_SA_DQ<12>")
	)
	(arc
		(start 331.708252 -233.46664)
		(mid 331.955965 -233.39142)
		(end 332.211172 -233.43489)
		(width 0.0889)
		(layer "In11.Cu")
		(net "M_F_CPU0_SA_DQ<12>")
	)
	(segment
		(start 333.868014 -231.789986)
		(end 333.401162 -231.524048)
		(width 0.10668)
		(layer "F.Cu")
		(net "M_F_CPU0_SA_DQ<11>")
	)
	(segment
		(start 326.511158 -230.273352)
		(end 327.241408 -231.003602)
		(width 0.0889)
		(layer "In11.Cu")
		(net "M_F_CPU0_SA_DQ<11>")
	)
	(segment
		(start 266.873736 -209.660236)
		(end 267.036804 -209.497168)
		(width 0.14478)
		(layer "In11.Cu")
		(net "M_F_CPU0_SA_DQ<11>")
	)
	(segment
		(start 293.54907 -208.800446)
		(end 294.398954 -209.65033)
		(width 0.14478)
		(layer "In11.Cu")
		(net "M_F_CPU0_SA_DQ<11>")
	)
	(segment
		(start 265.54811 -209.23504)
		(end 265.973306 -209.660236)
		(width 0.14478)
		(layer "In11.Cu")
		(net "M_F_CPU0_SA_DQ<11>")
	)
	(segment
		(start 275.527516 -208.800446)
		(end 278.47417 -208.800446)
		(width 0.14478)
		(layer "In11.Cu")
		(net "M_F_CPU0_SA_DQ<11>")
	)
	(segment
		(start 278.47417 -208.800446)
		(end 279.324054 -209.65033)
		(width 0.14478)
		(layer "In11.Cu")
		(net "M_F_CPU0_SA_DQ<11>")
	)
	(segment
		(start 301.085504 -208.800446)
		(end 301.945294 -209.660236)
		(width 0.14478)
		(layer "In11.Cu")
		(net "M_F_CPU0_SA_DQ<11>")
	)
	(segment
		(start 301.945294 -209.660236)
		(end 304.8762 -209.660236)
		(width 0.14478)
		(layer "In11.Cu")
		(net "M_F_CPU0_SA_DQ<11>")
	)
	(segment
		(start 333.555086 -231.258618)
		(end 333.401162 -231.524048)
		(width 0.0889)
		(layer "In11.Cu")
		(net "M_F_CPU0_SA_DQ<11>")
	)
	(segment
		(start 327.527158 -231.14635)
		(end 327.594976 -231.156002)
		(width 0.0889)
		(layer "In11.Cu")
		(net "M_F_CPU0_SA_DQ<11>")
	)
	(segment
		(start 267.43025 -208.88071)
		(end 267.593318 -209.043778)
		(width 0.14478)
		(layer "In11.Cu")
		(net "M_F_CPU0_SA_DQ<11>")
	)
	(segment
		(start 329.819762 -231.196896)
		(end 329.828144 -231.201722)
		(width 0.0889)
		(layer "In11.Cu")
		(net "M_F_CPU0_SA_DQ<11>")
	)
	(segment
		(start 331.33411 -231.201722)
		(end 331.342492 -231.196896)
		(width 0.0889)
		(layer "In11.Cu")
		(net "M_F_CPU0_SA_DQ<11>")
	)
	(segment
		(start 267.74648 -209.65033)
		(end 274.677632 -209.65033)
		(width 0.14478)
		(layer "In11.Cu")
		(net "M_F_CPU0_SA_DQ<11>")
	)
	(segment
		(start 274.677632 -209.65033)
		(end 275.527516 -208.800446)
		(width 0.14478)
		(layer "In11.Cu")
		(net "M_F_CPU0_SA_DQ<11>")
	)
	(segment
		(start 317.736474 -219.184474)
		(end 317.736474 -221.93377)
		(width 0.14478)
		(layer "In11.Cu")
		(net "M_F_CPU0_SA_DQ<11>")
	)
	(segment
		(start 323.946774 -228.14407)
		(end 324.179184 -228.37648)
		(width 0.0889)
		(layer "In11.Cu")
		(net "M_F_CPU0_SA_DQ<11>")
	)
	(segment
		(start 325.112634 -229.38867)
		(end 325.997316 -230.273352)
		(width 0.0889)
		(layer "In11.Cu")
		(net "M_F_CPU0_SA_DQ<11>")
	)
	(segment
		(start 283.158438 -208.800446)
		(end 286.043624 -208.800446)
		(width 0.14478)
		(layer "In11.Cu")
		(net "M_F_CPU0_SA_DQ<11>")
	)
	(segment
		(start 265.973306 -209.660236)
		(end 266.873736 -209.660236)
		(width 0.14478)
		(layer "In11.Cu")
		(net "M_F_CPU0_SA_DQ<11>")
	)
	(segment
		(start 297.339766 -209.65033)
		(end 298.18965 -208.800446)
		(width 0.14478)
		(layer "In11.Cu")
		(net "M_F_CPU0_SA_DQ<11>")
	)
	(segment
		(start 304.8762 -209.660236)
		(end 305.726338 -208.810098)
		(width 0.14478)
		(layer "In11.Cu")
		(net "M_F_CPU0_SA_DQ<11>")
	)
	(segment
		(start 289.84194 -209.65033)
		(end 290.691824 -208.800446)
		(width 0.14478)
		(layer "In11.Cu")
		(net "M_F_CPU0_SA_DQ<11>")
	)
	(segment
		(start 333.532734 -231.17556)
		(end 333.555086 -231.258618)
		(width 0.0889)
		(layer "In11.Cu")
		(net "M_F_CPU0_SA_DQ<11>")
	)
	(segment
		(start 267.593318 -209.497168)
		(end 267.74648 -209.65033)
		(width 0.14478)
		(layer "In11.Cu")
		(net "M_F_CPU0_SA_DQ<11>")
	)
	(segment
		(start 305.726338 -208.810098)
		(end 307.362098 -208.810098)
		(width 0.14478)
		(layer "In11.Cu")
		(net "M_F_CPU0_SA_DQ<11>")
	)
	(segment
		(start 286.043624 -208.800446)
		(end 286.893508 -209.65033)
		(width 0.14478)
		(layer "In11.Cu")
		(net "M_F_CPU0_SA_DQ<11>")
	)
	(segment
		(start 267.199872 -208.88071)
		(end 267.43025 -208.88071)
		(width 0.14478)
		(layer "In11.Cu")
		(net "M_F_CPU0_SA_DQ<11>")
	)
	(segment
		(start 324.179184 -228.37648)
		(end 324.179184 -228.82606)
		(width 0.0889)
		(layer "In11.Cu")
		(net "M_F_CPU0_SA_DQ<11>")
	)
	(segment
		(start 279.324054 -209.65033)
		(end 282.308554 -209.65033)
		(width 0.14478)
		(layer "In11.Cu")
		(net "M_F_CPU0_SA_DQ<11>")
	)
	(segment
		(start 290.691824 -208.800446)
		(end 293.54907 -208.800446)
		(width 0.14478)
		(layer "In11.Cu")
		(net "M_F_CPU0_SA_DQ<11>")
	)
	(segment
		(start 325.997316 -230.273352)
		(end 326.511158 -230.273352)
		(width 0.0889)
		(layer "In11.Cu")
		(net "M_F_CPU0_SA_DQ<11>")
	)
	(segment
		(start 317.736474 -221.93377)
		(end 323.946774 -228.14407)
		(width 0.14478)
		(layer "In11.Cu")
		(net "M_F_CPU0_SA_DQ<11>")
	)
	(segment
		(start 330.394056 -231.201722)
		(end 330.402438 -231.196896)
		(width 0.0889)
		(layer "In11.Cu")
		(net "M_F_CPU0_SA_DQ<11>")
	)
	(segment
		(start 267.036804 -209.497168)
		(end 267.036804 -209.043778)
		(width 0.14478)
		(layer "In11.Cu")
		(net "M_F_CPU0_SA_DQ<11>")
	)
	(segment
		(start 286.893508 -209.65033)
		(end 289.84194 -209.65033)
		(width 0.14478)
		(layer "In11.Cu")
		(net "M_F_CPU0_SA_DQ<11>")
	)
	(segment
		(start 267.593318 -209.043778)
		(end 267.593318 -209.497168)
		(width 0.14478)
		(layer "In11.Cu")
		(net "M_F_CPU0_SA_DQ<11>")
	)
	(segment
		(start 324.179184 -228.82606)
		(end 324.741794 -229.38867)
		(width 0.0889)
		(layer "In11.Cu")
		(net "M_F_CPU0_SA_DQ<11>")
	)
	(segment
		(start 298.18965 -208.800446)
		(end 301.085504 -208.800446)
		(width 0.14478)
		(layer "In11.Cu")
		(net "M_F_CPU0_SA_DQ<11>")
	)
	(segment
		(start 307.362098 -208.810098)
		(end 317.736474 -219.184474)
		(width 0.14478)
		(layer "In11.Cu")
		(net "M_F_CPU0_SA_DQ<11>")
	)
	(segment
		(start 294.398954 -209.65033)
		(end 297.339766 -209.65033)
		(width 0.14478)
		(layer "In11.Cu")
		(net "M_F_CPU0_SA_DQ<11>")
	)
	(segment
		(start 282.308554 -209.65033)
		(end 283.158438 -208.800446)
		(width 0.14478)
		(layer "In11.Cu")
		(net "M_F_CPU0_SA_DQ<11>")
	)
	(segment
		(start 267.036804 -209.043778)
		(end 267.199872 -208.88071)
		(width 0.14478)
		(layer "In11.Cu")
		(net "M_F_CPU0_SA_DQ<11>")
	)
	(segment
		(start 324.741794 -229.38867)
		(end 325.112634 -229.38867)
		(width 0.0889)
		(layer "In11.Cu")
		(net "M_F_CPU0_SA_DQ<11>")
	)
	(arc
		(start 331.342492 -231.196896)
		(mid 331.526 -231.151371)
		(end 331.708252 -231.201722)
		(width 0.0889)
		(layer "In11.Cu")
		(net "M_F_CPU0_SA_DQ<11>")
	)
	(arc
		(start 327.594976 -231.156002)
		(mid 327.649732 -231.159799)
		(end 327.70445 -231.155494)
		(width 0.0889)
		(layer "In11.Cu")
		(net "M_F_CPU0_SA_DQ<11>")
	)
	(arc
		(start 330.402438 -231.196896)
		(mid 330.585946 -231.151371)
		(end 330.768198 -231.201722)
		(width 0.0889)
		(layer "In11.Cu")
		(net "M_F_CPU0_SA_DQ<11>")
	)
	(arc
		(start 327.70445 -231.155494)
		(mid 327.830324 -231.157738)
		(end 327.94829 -231.201722)
		(width 0.0889)
		(layer "In11.Cu")
		(net "M_F_CPU0_SA_DQ<11>")
	)
	(arc
		(start 328.514202 -231.201722)
		(mid 328.701146 -231.151433)
		(end 328.88809 -231.201722)
		(width 0.0889)
		(layer "In11.Cu")
		(net "M_F_CPU0_SA_DQ<11>")
	)
	(arc
		(start 329.454002 -231.201722)
		(mid 329.636253 -231.151338)
		(end 329.819762 -231.196896)
		(width 0.0889)
		(layer "In11.Cu")
		(net "M_F_CPU0_SA_DQ<11>")
	)
	(arc
		(start 332.648052 -231.201722)
		(mid 332.931008 -231.277899)
		(end 333.213964 -231.201722)
		(width 0.0889)
		(layer "In11.Cu")
		(net "M_F_CPU0_SA_DQ<11>")
	)
	(arc
		(start 330.768198 -231.201722)
		(mid 331.051154 -231.277899)
		(end 331.33411 -231.201722)
		(width 0.0889)
		(layer "In11.Cu")
		(net "M_F_CPU0_SA_DQ<11>")
	)
	(arc
		(start 329.828144 -231.201722)
		(mid 330.1111 -231.277899)
		(end 330.394056 -231.201722)
		(width 0.0889)
		(layer "In11.Cu")
		(net "M_F_CPU0_SA_DQ<11>")
	)
	(arc
		(start 331.708252 -231.201722)
		(mid 331.991208 -231.277899)
		(end 332.274164 -231.201722)
		(width 0.0889)
		(layer "In11.Cu")
		(net "M_F_CPU0_SA_DQ<11>")
	)
	(arc
		(start 328.88809 -231.201722)
		(mid 329.171046 -231.277899)
		(end 329.454002 -231.201722)
		(width 0.0889)
		(layer "In11.Cu")
		(net "M_F_CPU0_SA_DQ<11>")
	)
	(arc
		(start 327.241408 -231.003602)
		(mid 327.372686 -231.098197)
		(end 327.527158 -231.14635)
		(width 0.0889)
		(layer "In11.Cu")
		(net "M_F_CPU0_SA_DQ<11>")
	)
	(arc
		(start 333.213964 -231.201722)
		(mid 333.370402 -231.152717)
		(end 333.532734 -231.17556)
		(width 0.0889)
		(layer "In11.Cu")
		(net "M_F_CPU0_SA_DQ<11>")
	)
	(arc
		(start 327.94829 -231.201722)
		(mid 328.231246 -231.277899)
		(end 328.514202 -231.201722)
		(width 0.0889)
		(layer "In11.Cu")
		(net "M_F_CPU0_SA_DQ<11>")
	)
	(arc
		(start 332.274164 -231.201722)
		(mid 332.461108 -231.151433)
		(end 332.648052 -231.201722)
		(width 0.0889)
		(layer "In11.Cu")
		(net "M_F_CPU0_SA_DQ<11>")
	)
	(segment
		(start 332.45806 -230.97998)
		(end 331.991208 -230.714296)
		(width 0.10668)
		(layer "F.Cu")
		(net "M_F_CPU0_SA_DQ<10>")
	)
	(segment
		(start 298.179998 -207.110076)
		(end 301.095156 -207.110076)
		(width 0.14478)
		(layer "In11.Cu")
		(net "M_F_CPU0_SA_DQ<10>")
	)
	(segment
		(start 307.933598 -207.402176)
		(end 307.933598 -208.095342)
		(width 0.14478)
		(layer "In11.Cu")
		(net "M_F_CPU0_SA_DQ<10>")
	)
	(segment
		(start 327.478898 -230.391716)
		(end 327.496932 -230.40213)
		(width 0.0889)
		(layer "In11.Cu")
		(net "M_F_CPU0_SA_DQ<10>")
	)
	(segment
		(start 324.585584 -228.58984)
		(end 324.930008 -228.934264)
		(width 0.0889)
		(layer "In11.Cu")
		(net "M_F_CPU0_SA_DQ<10>")
	)
	(segment
		(start 304.8762 -207.960214)
		(end 305.726338 -207.110076)
		(width 0.14478)
		(layer "In11.Cu")
		(net "M_F_CPU0_SA_DQ<10>")
	)
	(segment
		(start 286.053276 -207.110076)
		(end 286.903414 -207.960214)
		(width 0.14478)
		(layer "In11.Cu")
		(net "M_F_CPU0_SA_DQ<10>")
	)
	(segment
		(start 275.517864 -207.110076)
		(end 278.483822 -207.110076)
		(width 0.14478)
		(layer "In11.Cu")
		(net "M_F_CPU0_SA_DQ<10>")
	)
	(segment
		(start 331.229716 -230.38689)
		(end 331.238098 -230.391716)
		(width 0.0889)
		(layer "In11.Cu")
		(net "M_F_CPU0_SA_DQ<10>")
	)
	(segment
		(start 267.843254 -207.23225)
		(end 268.073632 -207.23225)
		(width 0.14478)
		(layer "In11.Cu")
		(net "M_F_CPU0_SA_DQ<10>")
	)
	(segment
		(start 279.33396 -207.960214)
		(end 282.298648 -207.960214)
		(width 0.14478)
		(layer "In11.Cu")
		(net "M_F_CPU0_SA_DQ<10>")
	)
	(segment
		(start 282.298648 -207.960214)
		(end 283.148786 -207.110076)
		(width 0.14478)
		(layer "In11.Cu")
		(net "M_F_CPU0_SA_DQ<10>")
	)
	(segment
		(start 278.483822 -207.110076)
		(end 279.33396 -207.960214)
		(width 0.14478)
		(layer "In11.Cu")
		(net "M_F_CPU0_SA_DQ<10>")
	)
	(segment
		(start 283.148786 -207.110076)
		(end 286.053276 -207.110076)
		(width 0.14478)
		(layer "In11.Cu")
		(net "M_F_CPU0_SA_DQ<10>")
	)
	(segment
		(start 301.095156 -207.110076)
		(end 301.945294 -207.960214)
		(width 0.14478)
		(layer "In11.Cu")
		(net "M_F_CPU0_SA_DQ<10>")
	)
	(segment
		(start 267.680186 -207.395318)
		(end 267.843254 -207.23225)
		(width 0.14478)
		(layer "In11.Cu")
		(net "M_F_CPU0_SA_DQ<10>")
	)
	(segment
		(start 301.945294 -207.960214)
		(end 304.8762 -207.960214)
		(width 0.14478)
		(layer "In11.Cu")
		(net "M_F_CPU0_SA_DQ<10>")
	)
	(segment
		(start 324.930008 -228.934264)
		(end 325.34098 -228.934264)
		(width 0.0889)
		(layer "In11.Cu")
		(net "M_F_CPU0_SA_DQ<10>")
	)
	(segment
		(start 324.119494 -227.10521)
		(end 324.585584 -227.5713)
		(width 0.0889)
		(layer "In11.Cu")
		(net "M_F_CPU0_SA_DQ<10>")
	)
	(segment
		(start 286.903414 -207.960214)
		(end 289.832034 -207.960214)
		(width 0.14478)
		(layer "In11.Cu")
		(net "M_F_CPU0_SA_DQ<10>")
	)
	(segment
		(start 307.933598 -208.095342)
		(end 318.645794 -218.807538)
		(width 0.14478)
		(layer "In11.Cu")
		(net "M_F_CPU0_SA_DQ<10>")
	)
	(segment
		(start 328.984102 -230.391716)
		(end 328.992484 -230.38689)
		(width 0.0889)
		(layer "In11.Cu")
		(net "M_F_CPU0_SA_DQ<10>")
	)
	(segment
		(start 268.2367 -207.395318)
		(end 268.2367 -207.797146)
		(width 0.14478)
		(layer "In11.Cu")
		(net "M_F_CPU0_SA_DQ<10>")
	)
	(segment
		(start 328.409808 -230.38689)
		(end 328.41819 -230.391716)
		(width 0.0889)
		(layer "In11.Cu")
		(net "M_F_CPU0_SA_DQ<10>")
	)
	(segment
		(start 265.54811 -207.535018)
		(end 265.973306 -207.960214)
		(width 0.14478)
		(layer "In11.Cu")
		(net "M_F_CPU0_SA_DQ<10>")
	)
	(segment
		(start 294.40886 -207.960214)
		(end 297.32986 -207.960214)
		(width 0.14478)
		(layer "In11.Cu")
		(net "M_F_CPU0_SA_DQ<10>")
	)
	(segment
		(start 297.32986 -207.960214)
		(end 298.179998 -207.110076)
		(width 0.14478)
		(layer "In11.Cu")
		(net "M_F_CPU0_SA_DQ<10>")
	)
	(segment
		(start 268.2367 -207.797146)
		(end 268.399768 -207.960214)
		(width 0.14478)
		(layer "In11.Cu")
		(net "M_F_CPU0_SA_DQ<10>")
	)
	(segment
		(start 323.886068 -226.797108)
		(end 323.900292 -226.797108)
		(width 0.0889)
		(layer "In11.Cu")
		(net "M_F_CPU0_SA_DQ<10>")
	)
	(segment
		(start 293.558722 -207.110076)
		(end 294.40886 -207.960214)
		(width 0.14478)
		(layer "In11.Cu")
		(net "M_F_CPU0_SA_DQ<10>")
	)
	(segment
		(start 265.973306 -207.960214)
		(end 267.517118 -207.960214)
		(width 0.14478)
		(layer "In11.Cu")
		(net "M_F_CPU0_SA_DQ<10>")
	)
	(segment
		(start 324.119494 -227.01631)
		(end 324.119494 -227.10521)
		(width 0.0889)
		(layer "In11.Cu")
		(net "M_F_CPU0_SA_DQ<10>")
	)
	(segment
		(start 324.585584 -227.5713)
		(end 324.585584 -228.58984)
		(width 0.0889)
		(layer "In11.Cu")
		(net "M_F_CPU0_SA_DQ<10>")
	)
	(segment
		(start 332.145132 -230.448866)
		(end 331.991208 -230.714296)
		(width 0.0889)
		(layer "In11.Cu")
		(net "M_F_CPU0_SA_DQ<10>")
	)
	(segment
		(start 332.12278 -230.365554)
		(end 332.145132 -230.448866)
		(width 0.0889)
		(layer "In11.Cu")
		(net "M_F_CPU0_SA_DQ<10>")
	)
	(segment
		(start 323.900292 -226.797108)
		(end 324.119494 -227.01631)
		(width 0.0889)
		(layer "In11.Cu")
		(net "M_F_CPU0_SA_DQ<10>")
	)
	(segment
		(start 307.641498 -207.110076)
		(end 307.933598 -207.402176)
		(width 0.14478)
		(layer "In11.Cu")
		(net "M_F_CPU0_SA_DQ<10>")
	)
	(segment
		(start 305.726338 -207.110076)
		(end 307.641498 -207.110076)
		(width 0.14478)
		(layer "In11.Cu")
		(net "M_F_CPU0_SA_DQ<10>")
	)
	(segment
		(start 326.868282 -229.808278)
		(end 327.362566 -230.302562)
		(width 0.0889)
		(layer "In11.Cu")
		(net "M_F_CPU0_SA_DQ<10>")
	)
	(segment
		(start 267.517118 -207.960214)
		(end 267.680186 -207.797146)
		(width 0.14478)
		(layer "In11.Cu")
		(net "M_F_CPU0_SA_DQ<10>")
	)
	(segment
		(start 268.399768 -207.960214)
		(end 274.667726 -207.960214)
		(width 0.14478)
		(layer "In11.Cu")
		(net "M_F_CPU0_SA_DQ<10>")
	)
	(segment
		(start 289.832034 -207.960214)
		(end 290.682172 -207.110076)
		(width 0.14478)
		(layer "In11.Cu")
		(net "M_F_CPU0_SA_DQ<10>")
	)
	(segment
		(start 318.645794 -221.556834)
		(end 323.886068 -226.797108)
		(width 0.14478)
		(layer "In11.Cu")
		(net "M_F_CPU0_SA_DQ<10>")
	)
	(segment
		(start 326.214994 -229.808278)
		(end 326.868282 -229.808278)
		(width 0.0889)
		(layer "In11.Cu")
		(net "M_F_CPU0_SA_DQ<10>")
	)
	(segment
		(start 268.073632 -207.23225)
		(end 268.2367 -207.395318)
		(width 0.14478)
		(layer "In11.Cu")
		(net "M_F_CPU0_SA_DQ<10>")
	)
	(segment
		(start 274.667726 -207.960214)
		(end 275.517864 -207.110076)
		(width 0.14478)
		(layer "In11.Cu")
		(net "M_F_CPU0_SA_DQ<10>")
	)
	(segment
		(start 325.34098 -228.934264)
		(end 326.214994 -229.808278)
		(width 0.0889)
		(layer "In11.Cu")
		(net "M_F_CPU0_SA_DQ<10>")
	)
	(segment
		(start 290.682172 -207.110076)
		(end 293.558722 -207.110076)
		(width 0.14478)
		(layer "In11.Cu")
		(net "M_F_CPU0_SA_DQ<10>")
	)
	(segment
		(start 318.645794 -218.807538)
		(end 318.645794 -221.556834)
		(width 0.14478)
		(layer "In11.Cu")
		(net "M_F_CPU0_SA_DQ<10>")
	)
	(segment
		(start 267.680186 -207.797146)
		(end 267.680186 -207.395318)
		(width 0.14478)
		(layer "In11.Cu")
		(net "M_F_CPU0_SA_DQ<10>")
	)
	(arc
		(start 327.362566 -230.302562)
		(mid 327.417816 -230.350944)
		(end 327.478898 -230.391716)
		(width 0.0889)
		(layer "In11.Cu")
		(net "M_F_CPU0_SA_DQ<10>")
	)
	(arc
		(start 328.992484 -230.38689)
		(mid 329.175992 -230.341396)
		(end 329.358244 -230.391716)
		(width 0.0889)
		(layer "In11.Cu")
		(net "M_F_CPU0_SA_DQ<10>")
	)
	(arc
		(start 330.298044 -230.391716)
		(mid 330.581 -230.467859)
		(end 330.863956 -230.391716)
		(width 0.0889)
		(layer "In11.Cu")
		(net "M_F_CPU0_SA_DQ<10>")
	)
	(arc
		(start 331.80401 -230.391716)
		(mid 331.960448 -230.342745)
		(end 332.12278 -230.365554)
		(width 0.0889)
		(layer "In11.Cu")
		(net "M_F_CPU0_SA_DQ<10>")
	)
	(arc
		(start 328.41819 -230.391716)
		(mid 328.701146 -230.467859)
		(end 328.984102 -230.391716)
		(width 0.0889)
		(layer "In11.Cu")
		(net "M_F_CPU0_SA_DQ<10>")
	)
	(arc
		(start 330.863956 -230.391716)
		(mid 331.046207 -230.341366)
		(end 331.229716 -230.38689)
		(width 0.0889)
		(layer "In11.Cu")
		(net "M_F_CPU0_SA_DQ<10>")
	)
	(arc
		(start 328.044048 -230.391716)
		(mid 328.226299 -230.341366)
		(end 328.409808 -230.38689)
		(width 0.0889)
		(layer "In11.Cu")
		(net "M_F_CPU0_SA_DQ<10>")
	)
	(arc
		(start 329.924156 -230.391716)
		(mid 330.1111 -230.341461)
		(end 330.298044 -230.391716)
		(width 0.0889)
		(layer "In11.Cu")
		(net "M_F_CPU0_SA_DQ<10>")
	)
	(arc
		(start 327.496932 -230.40213)
		(mid 327.771836 -230.46774)
		(end 328.044048 -230.391716)
		(width 0.0889)
		(layer "In11.Cu")
		(net "M_F_CPU0_SA_DQ<10>")
	)
	(arc
		(start 329.358244 -230.391716)
		(mid 329.6412 -230.467859)
		(end 329.924156 -230.391716)
		(width 0.0889)
		(layer "In11.Cu")
		(net "M_F_CPU0_SA_DQ<10>")
	)
	(arc
		(start 331.238098 -230.391716)
		(mid 331.521054 -230.467859)
		(end 331.80401 -230.391716)
		(width 0.0889)
		(layer "In11.Cu")
		(net "M_F_CPU0_SA_DQ<10>")
	)
	(segment
		(start 332.92796 -225.310192)
		(end 332.461108 -225.044254)
		(width 0.10668)
		(layer "F.Cu")
		(net "M_F_CPU0_SA_DQ<0>")
	)
	(segment
		(start 286.742632 -197.760082)
		(end 289.883088 -197.760082)
		(width 0.14478)
		(layer "In11.Cu")
		(net "M_F_CPU0_SA_DQ<0>")
	)
	(segment
		(start 272.692368 -197.760082)
		(end 273.54022 -197.760082)
		(width 0.14478)
		(layer "In11.Cu")
		(net "M_F_CPU0_SA_DQ<0>")
	)
	(segment
		(start 328.482452 -225.348546)
		(end 328.514202 -225.366834)
		(width 0.0889)
		(layer "In11.Cu")
		(net "M_F_CPU0_SA_DQ<0>")
	)
	(segment
		(start 304.894742 -197.760082)
		(end 305.744626 -196.910198)
		(width 0.14478)
		(layer "In11.Cu")
		(net "M_F_CPU0_SA_DQ<0>")
	)
	(segment
		(start 270.859758 -197.597014)
		(end 270.859758 -196.897498)
		(width 0.14478)
		(layer "In11.Cu")
		(net "M_F_CPU0_SA_DQ<0>")
	)
	(segment
		(start 272.5293 -196.897498)
		(end 272.5293 -197.597014)
		(width 0.14478)
		(layer "In11.Cu")
		(net "M_F_CPU0_SA_DQ<0>")
	)
	(segment
		(start 279.260808 -197.760082)
		(end 282.323286 -197.760082)
		(width 0.14478)
		(layer "In11.Cu")
		(net "M_F_CPU0_SA_DQ<0>")
	)
	(segment
		(start 270.859758 -196.897498)
		(end 271.022826 -196.73443)
		(width 0.14478)
		(layer "In11.Cu")
		(net "M_F_CPU0_SA_DQ<0>")
	)
	(segment
		(start 328.482452 -223.728534)
		(end 328.514202 -223.746822)
		(width 0.0889)
		(layer "In11.Cu")
		(net "M_F_CPU0_SA_DQ<0>")
	)
	(segment
		(start 301.051976 -196.910198)
		(end 301.90186 -197.760082)
		(width 0.14478)
		(layer "In11.Cu")
		(net "M_F_CPU0_SA_DQ<0>")
	)
	(segment
		(start 271.809718 -197.760082)
		(end 271.972786 -197.597014)
		(width 0.14478)
		(layer "In11.Cu")
		(net "M_F_CPU0_SA_DQ<0>")
	)
	(segment
		(start 271.022826 -196.73443)
		(end 271.253204 -196.73443)
		(width 0.14478)
		(layer "In11.Cu")
		(net "M_F_CPU0_SA_DQ<0>")
	)
	(segment
		(start 324.985634 -214.10549)
		(end 324.985634 -218.42603)
		(width 0.14478)
		(layer "In11.Cu")
		(net "M_F_CPU0_SA_DQ<0>")
	)
	(segment
		(start 274.259802 -197.113398)
		(end 274.259802 -197.597014)
		(width 0.14478)
		(layer "In11.Cu")
		(net "M_F_CPU0_SA_DQ<0>")
	)
	(segment
		(start 324.985634 -218.42603)
		(end 327.502774 -220.94317)
		(width 0.14478)
		(layer "In11.Cu")
		(net "M_F_CPU0_SA_DQ<0>")
	)
	(segment
		(start 272.135854 -196.73443)
		(end 272.366232 -196.73443)
		(width 0.14478)
		(layer "In11.Cu")
		(net "M_F_CPU0_SA_DQ<0>")
	)
	(segment
		(start 307.790342 -196.910198)
		(end 324.985634 -214.10549)
		(width 0.14478)
		(layer "In11.Cu")
		(net "M_F_CPU0_SA_DQ<0>")
	)
	(segment
		(start 282.323286 -197.760082)
		(end 283.17317 -196.910198)
		(width 0.14478)
		(layer "In11.Cu")
		(net "M_F_CPU0_SA_DQ<0>")
	)
	(segment
		(start 271.972786 -197.597014)
		(end 271.972786 -196.897498)
		(width 0.14478)
		(layer "In11.Cu")
		(net "M_F_CPU0_SA_DQ<0>")
	)
	(segment
		(start 274.096734 -196.95033)
		(end 274.259802 -197.113398)
		(width 0.14478)
		(layer "In11.Cu")
		(net "M_F_CPU0_SA_DQ<0>")
	)
	(segment
		(start 327.542398 -222.108522)
		(end 327.611994 -222.148654)
		(width 0.0889)
		(layer "In11.Cu")
		(net "M_F_CPU0_SA_DQ<0>")
	)
	(segment
		(start 328.550524 -224.700592)
		(end 328.514202 -224.721674)
		(width 0.0889)
		(layer "In11.Cu")
		(net "M_F_CPU0_SA_DQ<0>")
	)
	(segment
		(start 329.819762 -225.37166)
		(end 329.828144 -225.366834)
		(width 0.0889)
		(layer "In11.Cu")
		(net "M_F_CPU0_SA_DQ<0>")
	)
	(segment
		(start 273.866356 -196.95033)
		(end 274.096734 -196.95033)
		(width 0.14478)
		(layer "In11.Cu")
		(net "M_F_CPU0_SA_DQ<0>")
	)
	(segment
		(start 290.732972 -196.910198)
		(end 293.507922 -196.910198)
		(width 0.14478)
		(layer "In11.Cu")
		(net "M_F_CPU0_SA_DQ<0>")
	)
	(segment
		(start 293.507922 -196.910198)
		(end 294.357806 -197.760082)
		(width 0.14478)
		(layer "In11.Cu")
		(net "M_F_CPU0_SA_DQ<0>")
	)
	(segment
		(start 273.54022 -197.760082)
		(end 273.703288 -197.597014)
		(width 0.14478)
		(layer "In11.Cu")
		(net "M_F_CPU0_SA_DQ<0>")
	)
	(segment
		(start 328.044302 -222.936816)
		(end 328.080624 -222.957898)
		(width 0.0889)
		(layer "In11.Cu")
		(net "M_F_CPU0_SA_DQ<0>")
	)
	(segment
		(start 272.366232 -196.73443)
		(end 272.5293 -196.897498)
		(width 0.14478)
		(layer "In11.Cu")
		(net "M_F_CPU0_SA_DQ<0>")
	)
	(segment
		(start 271.57934 -197.760082)
		(end 271.809718 -197.760082)
		(width 0.14478)
		(layer "In11.Cu")
		(net "M_F_CPU0_SA_DQ<0>")
	)
	(segment
		(start 283.17317 -196.910198)
		(end 285.892748 -196.910198)
		(width 0.14478)
		(layer "In11.Cu")
		(net "M_F_CPU0_SA_DQ<0>")
	)
	(segment
		(start 327.502774 -220.94317)
		(end 327.502774 -221.23273)
		(width 0.14478)
		(layer "In11.Cu")
		(net "M_F_CPU0_SA_DQ<0>")
	)
	(segment
		(start 331.33411 -225.366834)
		(end 331.342492 -225.37166)
		(width 0.0889)
		(layer "In11.Cu")
		(net "M_F_CPU0_SA_DQ<0>")
	)
	(segment
		(start 330.394056 -225.366834)
		(end 330.402438 -225.37166)
		(width 0.0889)
		(layer "In11.Cu")
		(net "M_F_CPU0_SA_DQ<0>")
	)
	(segment
		(start 327.386188 -221.562676)
		(end 327.386188 -221.803976)
		(width 0.0889)
		(layer "In11.Cu")
		(net "M_F_CPU0_SA_DQ<0>")
	)
	(segment
		(start 271.253204 -196.73443)
		(end 271.416272 -196.897498)
		(width 0.14478)
		(layer "In11.Cu")
		(net "M_F_CPU0_SA_DQ<0>")
	)
	(segment
		(start 285.892748 -196.910198)
		(end 286.742632 -197.760082)
		(width 0.14478)
		(layer "In11.Cu")
		(net "M_F_CPU0_SA_DQ<0>")
	)
	(segment
		(start 269.648178 -197.33514)
		(end 270.07312 -197.760082)
		(width 0.14478)
		(layer "In11.Cu")
		(net "M_F_CPU0_SA_DQ<0>")
	)
	(segment
		(start 327.502774 -221.44609)
		(end 327.386188 -221.562676)
		(width 0.0889)
		(layer "In11.Cu")
		(net "M_F_CPU0_SA_DQ<0>")
	)
	(segment
		(start 332.307184 -225.309684)
		(end 332.461108 -225.044254)
		(width 0.0889)
		(layer "In11.Cu")
		(net "M_F_CPU0_SA_DQ<0>")
	)
	(segment
		(start 270.69669 -197.760082)
		(end 270.859758 -197.597014)
		(width 0.14478)
		(layer "In11.Cu")
		(net "M_F_CPU0_SA_DQ<0>")
	)
	(segment
		(start 328.012552 -222.918528)
		(end 328.044302 -222.936816)
		(width 0.0889)
		(layer "In11.Cu")
		(net "M_F_CPU0_SA_DQ<0>")
	)
	(segment
		(start 278.410924 -196.910198)
		(end 279.260808 -197.760082)
		(width 0.14478)
		(layer "In11.Cu")
		(net "M_F_CPU0_SA_DQ<0>")
	)
	(segment
		(start 274.259802 -197.597014)
		(end 274.42287 -197.760082)
		(width 0.14478)
		(layer "In11.Cu")
		(net "M_F_CPU0_SA_DQ<0>")
	)
	(segment
		(start 294.357806 -197.760082)
		(end 297.389042 -197.760082)
		(width 0.14478)
		(layer "In11.Cu")
		(net "M_F_CPU0_SA_DQ<0>")
	)
	(segment
		(start 305.744626 -196.910198)
		(end 307.790342 -196.910198)
		(width 0.14478)
		(layer "In11.Cu")
		(net "M_F_CPU0_SA_DQ<0>")
	)
	(segment
		(start 327.502774 -221.23273)
		(end 327.502774 -221.44609)
		(width 0.0889)
		(layer "In11.Cu")
		(net "M_F_CPU0_SA_DQ<0>")
	)
	(segment
		(start 273.703288 -197.113398)
		(end 273.866356 -196.95033)
		(width 0.14478)
		(layer "In11.Cu")
		(net "M_F_CPU0_SA_DQ<0>")
	)
	(segment
		(start 289.883088 -197.760082)
		(end 290.732972 -196.910198)
		(width 0.14478)
		(layer "In11.Cu")
		(net "M_F_CPU0_SA_DQ<0>")
	)
	(segment
		(start 271.416272 -196.897498)
		(end 271.416272 -197.597014)
		(width 0.14478)
		(layer "In11.Cu")
		(net "M_F_CPU0_SA_DQ<0>")
	)
	(segment
		(start 328.514202 -223.746822)
		(end 328.550524 -223.767904)
		(width 0.0889)
		(layer "In11.Cu")
		(net "M_F_CPU0_SA_DQ<0>")
	)
	(segment
		(start 274.754848 -197.760082)
		(end 275.604732 -196.910198)
		(width 0.14478)
		(layer "In11.Cu")
		(net "M_F_CPU0_SA_DQ<0>")
	)
	(segment
		(start 274.42287 -197.760082)
		(end 274.754848 -197.760082)
		(width 0.14478)
		(layer "In11.Cu")
		(net "M_F_CPU0_SA_DQ<0>")
	)
	(segment
		(start 273.703288 -197.597014)
		(end 273.703288 -197.113398)
		(width 0.14478)
		(layer "In11.Cu")
		(net "M_F_CPU0_SA_DQ<0>")
	)
	(segment
		(start 272.5293 -197.597014)
		(end 272.692368 -197.760082)
		(width 0.14478)
		(layer "In11.Cu")
		(net "M_F_CPU0_SA_DQ<0>")
	)
	(segment
		(start 298.238926 -196.910198)
		(end 301.051976 -196.910198)
		(width 0.14478)
		(layer "In11.Cu")
		(net "M_F_CPU0_SA_DQ<0>")
	)
	(segment
		(start 271.416272 -197.597014)
		(end 271.57934 -197.760082)
		(width 0.14478)
		(layer "In11.Cu")
		(net "M_F_CPU0_SA_DQ<0>")
	)
	(segment
		(start 275.604732 -196.910198)
		(end 278.410924 -196.910198)
		(width 0.14478)
		(layer "In11.Cu")
		(net "M_F_CPU0_SA_DQ<0>")
	)
	(segment
		(start 271.972786 -196.897498)
		(end 272.135854 -196.73443)
		(width 0.14478)
		(layer "In11.Cu")
		(net "M_F_CPU0_SA_DQ<0>")
	)
	(segment
		(start 301.90186 -197.760082)
		(end 304.894742 -197.760082)
		(width 0.14478)
		(layer "In11.Cu")
		(net "M_F_CPU0_SA_DQ<0>")
	)
	(segment
		(start 328.514202 -224.721674)
		(end 328.482452 -224.739962)
		(width 0.0889)
		(layer "In11.Cu")
		(net "M_F_CPU0_SA_DQ<0>")
	)
	(segment
		(start 270.07312 -197.760082)
		(end 270.69669 -197.760082)
		(width 0.14478)
		(layer "In11.Cu")
		(net "M_F_CPU0_SA_DQ<0>")
	)
	(segment
		(start 332.211172 -225.335084)
		(end 332.307184 -225.309684)
		(width 0.0889)
		(layer "In11.Cu")
		(net "M_F_CPU0_SA_DQ<0>")
	)
	(segment
		(start 297.389042 -197.760082)
		(end 298.238926 -196.910198)
		(width 0.14478)
		(layer "In11.Cu")
		(net "M_F_CPU0_SA_DQ<0>")
	)
	(arc
		(start 328.88809 -225.366834)
		(mid 329.171046 -225.290657)
		(end 329.454002 -225.366834)
		(width 0.0889)
		(layer "In11.Cu")
		(net "M_F_CPU0_SA_DQ<0>")
	)
	(arc
		(start 330.402438 -225.37166)
		(mid 330.585946 -225.417154)
		(end 330.768198 -225.366834)
		(width 0.0889)
		(layer "In11.Cu")
		(net "M_F_CPU0_SA_DQ<0>")
	)
	(arc
		(start 327.611994 -222.148654)
		(mid 327.791723 -222.351274)
		(end 327.856596 -222.614236)
		(width 0.0889)
		(layer "In11.Cu")
		(net "M_F_CPU0_SA_DQ<0>")
	)
	(arc
		(start 329.828144 -225.366834)
		(mid 330.1111 -225.290657)
		(end 330.394056 -225.366834)
		(width 0.0889)
		(layer "In11.Cu")
		(net "M_F_CPU0_SA_DQ<0>")
	)
	(arc
		(start 328.550524 -223.767904)
		(mid 328.796414 -224.234248)
		(end 328.550524 -224.700592)
		(width 0.0889)
		(layer "In11.Cu")
		(net "M_F_CPU0_SA_DQ<0>")
	)
	(arc
		(start 328.080624 -222.957898)
		(mid 328.261276 -223.160643)
		(end 328.326496 -223.424242)
		(width 0.0889)
		(layer "In11.Cu")
		(net "M_F_CPU0_SA_DQ<0>")
	)
	(arc
		(start 327.386188 -221.803976)
		(mid 327.421718 -221.963224)
		(end 327.52157 -222.092266)
		(width 0.0889)
		(layer "In11.Cu")
		(net "M_F_CPU0_SA_DQ<0>")
	)
	(arc
		(start 329.454002 -225.366834)
		(mid 329.636253 -225.417184)
		(end 329.819762 -225.37166)
		(width 0.0889)
		(layer "In11.Cu")
		(net "M_F_CPU0_SA_DQ<0>")
	)
	(arc
		(start 328.326496 -223.424242)
		(mid 328.367751 -223.595213)
		(end 328.482452 -223.728534)
		(width 0.0889)
		(layer "In11.Cu")
		(net "M_F_CPU0_SA_DQ<0>")
	)
	(arc
		(start 328.514202 -225.366834)
		(mid 328.701146 -225.417089)
		(end 328.88809 -225.366834)
		(width 0.0889)
		(layer "In11.Cu")
		(net "M_F_CPU0_SA_DQ<0>")
	)
	(arc
		(start 327.52157 -222.092266)
		(mid 327.53184 -222.100578)
		(end 327.542398 -222.108522)
		(width 0.0889)
		(layer "In11.Cu")
		(net "M_F_CPU0_SA_DQ<0>")
	)
	(arc
		(start 331.708252 -225.366834)
		(mid 331.955965 -225.291614)
		(end 332.211172 -225.335084)
		(width 0.0889)
		(layer "In11.Cu")
		(net "M_F_CPU0_SA_DQ<0>")
	)
	(arc
		(start 331.342492 -225.37166)
		(mid 331.526 -225.417154)
		(end 331.708252 -225.366834)
		(width 0.0889)
		(layer "In11.Cu")
		(net "M_F_CPU0_SA_DQ<0>")
	)
	(arc
		(start 328.482452 -224.739962)
		(mid 328.326524 -225.044254)
		(end 328.482452 -225.348546)
		(width 0.0889)
		(layer "In11.Cu")
		(net "M_F_CPU0_SA_DQ<0>")
	)
	(arc
		(start 327.856596 -222.614236)
		(mid 327.897851 -222.785207)
		(end 328.012552 -222.918528)
		(width 0.0889)
		(layer "In11.Cu")
		(net "M_F_CPU0_SA_DQ<0>")
	)
	(arc
		(start 330.768198 -225.366834)
		(mid 331.051154 -225.290657)
		(end 331.33411 -225.366834)
		(width 0.0889)
		(layer "In11.Cu")
		(net "M_F_CPU0_SA_DQ<0>")
	)
	(segment
		(start 333.868014 -252.850142)
		(end 333.401162 -252.584204)
		(width 0.10668)
		(layer "F.Cu")
		(net "M_F_CPU0_SA_CS_N<1>")
	)
	(segment
		(start 324.589394 -252.46203)
		(end 325.097394 -252.46203)
		(width 0.0889)
		(layer "In11.Cu")
		(net "M_F_CPU0_SA_CS_N<1>")
	)
	(segment
		(start 325.292212 -252.267212)
		(end 325.687944 -252.267212)
		(width 0.0889)
		(layer "In11.Cu")
		(net "M_F_CPU0_SA_CS_N<1>")
	)
	(segment
		(start 265.54811 -246.635016)
		(end 265.973052 -247.059958)
		(width 0.14478)
		(layer "In11.Cu")
		(net "M_F_CPU0_SA_CS_N<1>")
	)
	(segment
		(start 326.619108 -252.27026)
		(end 326.63384 -252.261624)
		(width 0.0889)
		(layer "In11.Cu")
		(net "M_F_CPU0_SA_CS_N<1>")
	)
	(segment
		(start 331.33411 -252.261624)
		(end 331.342492 -252.256798)
		(width 0.0889)
		(layer "In11.Cu")
		(net "M_F_CPU0_SA_CS_N<1>")
	)
	(segment
		(start 322.297806 -252.83287)
		(end 323.916294 -252.83287)
		(width 0.14478)
		(layer "In11.Cu")
		(net "M_F_CPU0_SA_CS_N<1>")
	)
	(segment
		(start 333.532734 -252.235462)
		(end 333.555086 -252.318774)
		(width 0.0889)
		(layer "In11.Cu")
		(net "M_F_CPU0_SA_CS_N<1>")
	)
	(segment
		(start 333.555086 -252.318774)
		(end 333.401162 -252.584204)
		(width 0.0889)
		(layer "In11.Cu")
		(net "M_F_CPU0_SA_CS_N<1>")
	)
	(segment
		(start 323.916294 -252.83287)
		(end 324.218554 -252.83287)
		(width 0.0889)
		(layer "In11.Cu")
		(net "M_F_CPU0_SA_CS_N<1>")
	)
	(segment
		(start 330.394056 -252.261624)
		(end 330.402438 -252.256798)
		(width 0.0889)
		(layer "In11.Cu")
		(net "M_F_CPU0_SA_CS_N<1>")
	)
	(segment
		(start 325.693532 -252.261624)
		(end 325.705216 -252.254766)
		(width 0.0889)
		(layer "In11.Cu")
		(net "M_F_CPU0_SA_CS_N<1>")
	)
	(segment
		(start 307.327554 -248.75998)
		(end 310.084724 -251.51715)
		(width 0.14478)
		(layer "In11.Cu")
		(net "M_F_CPU0_SA_CS_N<1>")
	)
	(segment
		(start 326.63384 -252.261624)
		(end 326.645524 -252.254766)
		(width 0.0889)
		(layer "In11.Cu")
		(net "M_F_CPU0_SA_CS_N<1>")
	)
	(segment
		(start 270.009112 -247.059958)
		(end 271.709134 -248.75998)
		(width 0.14478)
		(layer "In11.Cu")
		(net "M_F_CPU0_SA_CS_N<1>")
	)
	(segment
		(start 320.982086 -251.51715)
		(end 322.297806 -252.83287)
		(width 0.14478)
		(layer "In11.Cu")
		(net "M_F_CPU0_SA_CS_N<1>")
	)
	(segment
		(start 324.218554 -252.83287)
		(end 324.589394 -252.46203)
		(width 0.0889)
		(layer "In11.Cu")
		(net "M_F_CPU0_SA_CS_N<1>")
	)
	(segment
		(start 327.007728 -252.261624)
		(end 327.018142 -252.26772)
		(width 0.0889)
		(layer "In11.Cu")
		(net "M_F_CPU0_SA_CS_N<1>")
	)
	(segment
		(start 271.709134 -248.75998)
		(end 307.327554 -248.75998)
		(width 0.14478)
		(layer "In11.Cu")
		(net "M_F_CPU0_SA_CS_N<1>")
	)
	(segment
		(start 325.097394 -252.46203)
		(end 325.292212 -252.267212)
		(width 0.0889)
		(layer "In11.Cu")
		(net "M_F_CPU0_SA_CS_N<1>")
	)
	(segment
		(start 329.819762 -252.256798)
		(end 329.828144 -252.261624)
		(width 0.0889)
		(layer "In11.Cu")
		(net "M_F_CPU0_SA_CS_N<1>")
	)
	(segment
		(start 265.973052 -247.059958)
		(end 270.009112 -247.059958)
		(width 0.14478)
		(layer "In11.Cu")
		(net "M_F_CPU0_SA_CS_N<1>")
	)
	(segment
		(start 310.084724 -251.51715)
		(end 320.982086 -251.51715)
		(width 0.14478)
		(layer "In11.Cu")
		(net "M_F_CPU0_SA_CS_N<1>")
	)
	(segment
		(start 325.687944 -252.267212)
		(end 325.693532 -252.261624)
		(width 0.0889)
		(layer "In11.Cu")
		(net "M_F_CPU0_SA_CS_N<1>")
	)
	(arc
		(start 330.768198 -252.261624)
		(mid 331.051154 -252.337801)
		(end 331.33411 -252.261624)
		(width 0.0889)
		(layer "In11.Cu")
		(net "M_F_CPU0_SA_CS_N<1>")
	)
	(arc
		(start 332.648052 -252.261624)
		(mid 332.931008 -252.337801)
		(end 333.213964 -252.261624)
		(width 0.0889)
		(layer "In11.Cu")
		(net "M_F_CPU0_SA_CS_N<1>")
	)
	(arc
		(start 331.342492 -252.256798)
		(mid 331.526 -252.211304)
		(end 331.708252 -252.261624)
		(width 0.0889)
		(layer "In11.Cu")
		(net "M_F_CPU0_SA_CS_N<1>")
	)
	(arc
		(start 331.708252 -252.261624)
		(mid 331.991208 -252.337801)
		(end 332.274164 -252.261624)
		(width 0.0889)
		(layer "In11.Cu")
		(net "M_F_CPU0_SA_CS_N<1>")
	)
	(arc
		(start 330.402438 -252.256798)
		(mid 330.585946 -252.211304)
		(end 330.768198 -252.261624)
		(width 0.0889)
		(layer "In11.Cu")
		(net "M_F_CPU0_SA_CS_N<1>")
	)
	(arc
		(start 328.88809 -252.261624)
		(mid 329.171046 -252.337801)
		(end 329.454002 -252.261624)
		(width 0.0889)
		(layer "In11.Cu")
		(net "M_F_CPU0_SA_CS_N<1>")
	)
	(arc
		(start 328.514202 -252.261624)
		(mid 328.701146 -252.211369)
		(end 328.88809 -252.261624)
		(width 0.0889)
		(layer "In11.Cu")
		(net "M_F_CPU0_SA_CS_N<1>")
	)
	(arc
		(start 333.213964 -252.261624)
		(mid 333.370402 -252.212653)
		(end 333.532734 -252.235462)
		(width 0.0889)
		(layer "In11.Cu")
		(net "M_F_CPU0_SA_CS_N<1>")
	)
	(arc
		(start 327.018142 -252.26772)
		(mid 327.296828 -252.33794)
		(end 327.573894 -252.261624)
		(width 0.0889)
		(layer "In11.Cu")
		(net "M_F_CPU0_SA_CS_N<1>")
	)
	(arc
		(start 325.705216 -252.254766)
		(mid 325.887471 -252.211113)
		(end 326.067928 -252.261624)
		(width 0.0889)
		(layer "In11.Cu")
		(net "M_F_CPU0_SA_CS_N<1>")
	)
	(arc
		(start 326.645524 -252.254766)
		(mid 326.827525 -252.211233)
		(end 327.007728 -252.261624)
		(width 0.0889)
		(layer "In11.Cu")
		(net "M_F_CPU0_SA_CS_N<1>")
	)
	(arc
		(start 329.454002 -252.261624)
		(mid 329.636253 -252.211274)
		(end 329.819762 -252.256798)
		(width 0.0889)
		(layer "In11.Cu")
		(net "M_F_CPU0_SA_CS_N<1>")
	)
	(arc
		(start 327.94829 -252.261624)
		(mid 328.231246 -252.337801)
		(end 328.514202 -252.261624)
		(width 0.0889)
		(layer "In11.Cu")
		(net "M_F_CPU0_SA_CS_N<1>")
	)
	(arc
		(start 329.828144 -252.261624)
		(mid 330.1111 -252.337801)
		(end 330.394056 -252.261624)
		(width 0.0889)
		(layer "In11.Cu")
		(net "M_F_CPU0_SA_CS_N<1>")
	)
	(arc
		(start 327.573894 -252.261624)
		(mid 327.761092 -252.211242)
		(end 327.94829 -252.261624)
		(width 0.0889)
		(layer "In11.Cu")
		(net "M_F_CPU0_SA_CS_N<1>")
	)
	(arc
		(start 332.274164 -252.261624)
		(mid 332.461108 -252.211369)
		(end 332.648052 -252.261624)
		(width 0.0889)
		(layer "In11.Cu")
		(net "M_F_CPU0_SA_CS_N<1>")
	)
	(arc
		(start 326.067928 -252.261624)
		(mid 326.34238 -252.33786)
		(end 326.619108 -252.27026)
		(width 0.0889)
		(layer "In11.Cu")
		(net "M_F_CPU0_SA_CS_N<1>")
	)
	(segment
		(start 332.45806 -252.040136)
		(end 331.991208 -251.774198)
		(width 0.10668)
		(layer "F.Cu")
		(net "M_F_CPU0_SA_CS_N<0>")
	)
	(segment
		(start 271.773142 -247.910096)
		(end 274.072604 -247.910096)
		(width 0.14478)
		(layer "In11.Cu")
		(net "M_F_CPU0_SA_CS_N<0>")
	)
	(segment
		(start 327.46061 -251.441458)
		(end 327.478898 -251.451872)
		(width 0.0889)
		(layer "In11.Cu")
		(net "M_F_CPU0_SA_CS_N<0>")
	)
	(segment
		(start 326.538082 -251.451618)
		(end 326.556116 -251.462286)
		(width 0.0889)
		(layer "In11.Cu")
		(net "M_F_CPU0_SA_CS_N<0>")
	)
	(segment
		(start 286.461708 -248.140982)
		(end 286.461708 -248.073164)
		(width 0.14478)
		(layer "In11.Cu")
		(net "M_F_CPU0_SA_CS_N<0>")
	)
	(segment
		(start 274.792186 -248.073164)
		(end 274.955254 -247.910096)
		(width 0.14478)
		(layer "In11.Cu")
		(net "M_F_CPU0_SA_CS_N<0>")
	)
	(segment
		(start 286.29864 -248.30405)
		(end 286.461708 -248.140982)
		(width 0.14478)
		(layer "In11.Cu")
		(net "M_F_CPU0_SA_CS_N<0>")
	)
	(segment
		(start 283.644848 -247.910096)
		(end 285.742126 -247.910096)
		(width 0.14478)
		(layer "In11.Cu")
		(net "M_F_CPU0_SA_CS_N<0>")
	)
	(segment
		(start 332.145132 -251.508768)
		(end 331.991208 -251.774198)
		(width 0.0889)
		(layer "In11.Cu")
		(net "M_F_CPU0_SA_CS_N<0>")
	)
	(segment
		(start 269.648178 -245.785132)
		(end 271.773142 -247.910096)
		(width 0.14478)
		(layer "In11.Cu")
		(net "M_F_CPU0_SA_CS_N<0>")
	)
	(segment
		(start 281.812238 -248.073164)
		(end 281.812238 -248.133362)
		(width 0.14478)
		(layer "In11.Cu")
		(net "M_F_CPU0_SA_CS_N<0>")
	)
	(segment
		(start 325.030338 -252.074172)
		(end 325.645018 -251.459492)
		(width 0.0889)
		(layer "In11.Cu")
		(net "M_F_CPU0_SA_CS_N<0>")
	)
	(segment
		(start 278.73706 -248.140982)
		(end 278.900128 -248.30405)
		(width 0.14478)
		(layer "In11.Cu")
		(net "M_F_CPU0_SA_CS_N<0>")
	)
	(segment
		(start 281.812238 -248.133362)
		(end 281.975306 -248.29643)
		(width 0.14478)
		(layer "In11.Cu")
		(net "M_F_CPU0_SA_CS_N<0>")
	)
	(segment
		(start 327.478898 -251.451872)
		(end 327.490836 -251.45873)
		(width 0.0889)
		(layer "In11.Cu")
		(net "M_F_CPU0_SA_CS_N<0>")
	)
	(segment
		(start 279.130506 -248.30405)
		(end 279.293574 -248.140982)
		(width 0.14478)
		(layer "In11.Cu")
		(net "M_F_CPU0_SA_CS_N<0>")
	)
	(segment
		(start 275.742146 -248.30405)
		(end 275.905214 -248.140982)
		(width 0.14478)
		(layer "In11.Cu")
		(net "M_F_CPU0_SA_CS_N<0>")
	)
	(segment
		(start 328.984102 -251.451618)
		(end 328.992484 -251.446792)
		(width 0.0889)
		(layer "In11.Cu")
		(net "M_F_CPU0_SA_CS_N<0>")
	)
	(segment
		(start 274.235672 -248.140982)
		(end 274.39874 -248.30405)
		(width 0.14478)
		(layer "In11.Cu")
		(net "M_F_CPU0_SA_CS_N<0>")
	)
	(segment
		(start 274.792186 -248.140982)
		(end 274.792186 -248.073164)
		(width 0.14478)
		(layer "In11.Cu")
		(net "M_F_CPU0_SA_CS_N<0>")
	)
	(segment
		(start 282.205684 -248.29643)
		(end 282.368752 -248.133362)
		(width 0.14478)
		(layer "In11.Cu")
		(net "M_F_CPU0_SA_CS_N<0>")
	)
	(segment
		(start 279.456642 -247.910096)
		(end 281.64917 -247.910096)
		(width 0.14478)
		(layer "In11.Cu")
		(net "M_F_CPU0_SA_CS_N<0>")
	)
	(segment
		(start 282.925266 -248.073164)
		(end 282.925266 -248.133362)
		(width 0.14478)
		(layer "In11.Cu")
		(net "M_F_CPU0_SA_CS_N<0>")
	)
	(segment
		(start 286.461708 -248.073164)
		(end 286.624776 -247.910096)
		(width 0.14478)
		(layer "In11.Cu")
		(net "M_F_CPU0_SA_CS_N<0>")
	)
	(segment
		(start 323.9262 -252.37821)
		(end 324.230238 -252.074172)
		(width 0.0889)
		(layer "In11.Cu")
		(net "M_F_CPU0_SA_CS_N<0>")
	)
	(segment
		(start 328.409808 -251.446792)
		(end 328.41819 -251.451618)
		(width 0.0889)
		(layer "In11.Cu")
		(net "M_F_CPU0_SA_CS_N<0>")
	)
	(segment
		(start 285.742126 -247.910096)
		(end 285.905194 -248.073164)
		(width 0.14478)
		(layer "In11.Cu")
		(net "M_F_CPU0_SA_CS_N<0>")
	)
	(segment
		(start 325.645018 -251.459492)
		(end 326.157082 -251.459492)
		(width 0.0889)
		(layer "In11.Cu")
		(net "M_F_CPU0_SA_CS_N<0>")
	)
	(segment
		(start 326.164702 -251.451872)
		(end 326.180958 -251.442474)
		(width 0.0889)
		(layer "In11.Cu")
		(net "M_F_CPU0_SA_CS_N<0>")
	)
	(segment
		(start 282.368752 -248.133362)
		(end 282.368752 -248.073164)
		(width 0.14478)
		(layer "In11.Cu")
		(net "M_F_CPU0_SA_CS_N<0>")
	)
	(segment
		(start 283.48178 -248.073164)
		(end 283.644848 -247.910096)
		(width 0.14478)
		(layer "In11.Cu")
		(net "M_F_CPU0_SA_CS_N<0>")
	)
	(segment
		(start 281.64917 -247.910096)
		(end 281.812238 -248.073164)
		(width 0.14478)
		(layer "In11.Cu")
		(net "M_F_CPU0_SA_CS_N<0>")
	)
	(segment
		(start 275.3487 -248.140982)
		(end 275.511768 -248.30405)
		(width 0.14478)
		(layer "In11.Cu")
		(net "M_F_CPU0_SA_CS_N<0>")
	)
	(segment
		(start 274.39874 -248.30405)
		(end 274.629118 -248.30405)
		(width 0.14478)
		(layer "In11.Cu")
		(net "M_F_CPU0_SA_CS_N<0>")
	)
	(segment
		(start 274.235672 -248.073164)
		(end 274.235672 -248.140982)
		(width 0.14478)
		(layer "In11.Cu")
		(net "M_F_CPU0_SA_CS_N<0>")
	)
	(segment
		(start 274.955254 -247.910096)
		(end 275.185632 -247.910096)
		(width 0.14478)
		(layer "In11.Cu")
		(net "M_F_CPU0_SA_CS_N<0>")
	)
	(segment
		(start 286.624776 -247.910096)
		(end 307.53431 -247.910096)
		(width 0.14478)
		(layer "In11.Cu")
		(net "M_F_CPU0_SA_CS_N<0>")
	)
	(segment
		(start 276.068282 -247.910096)
		(end 278.573992 -247.910096)
		(width 0.14478)
		(layer "In11.Cu")
		(net "M_F_CPU0_SA_CS_N<0>")
	)
	(segment
		(start 322.486274 -252.37821)
		(end 323.9262 -252.37821)
		(width 0.14478)
		(layer "In11.Cu")
		(net "M_F_CPU0_SA_CS_N<0>")
	)
	(segment
		(start 282.368752 -248.073164)
		(end 282.53182 -247.910096)
		(width 0.14478)
		(layer "In11.Cu")
		(net "M_F_CPU0_SA_CS_N<0>")
	)
	(segment
		(start 283.318712 -248.29643)
		(end 283.48178 -248.133362)
		(width 0.14478)
		(layer "In11.Cu")
		(net "M_F_CPU0_SA_CS_N<0>")
	)
	(segment
		(start 278.73706 -248.073164)
		(end 278.73706 -248.140982)
		(width 0.14478)
		(layer "In11.Cu")
		(net "M_F_CPU0_SA_CS_N<0>")
	)
	(segment
		(start 324.230238 -252.074172)
		(end 325.030338 -252.074172)
		(width 0.0889)
		(layer "In11.Cu")
		(net "M_F_CPU0_SA_CS_N<0>")
	)
	(segment
		(start 274.629118 -248.30405)
		(end 274.792186 -248.140982)
		(width 0.14478)
		(layer "In11.Cu")
		(net "M_F_CPU0_SA_CS_N<0>")
	)
	(segment
		(start 282.762198 -247.910096)
		(end 282.925266 -248.073164)
		(width 0.14478)
		(layer "In11.Cu")
		(net "M_F_CPU0_SA_CS_N<0>")
	)
	(segment
		(start 279.293574 -248.073164)
		(end 279.456642 -247.910096)
		(width 0.14478)
		(layer "In11.Cu")
		(net "M_F_CPU0_SA_CS_N<0>")
	)
	(segment
		(start 275.3487 -248.073164)
		(end 275.3487 -248.140982)
		(width 0.14478)
		(layer "In11.Cu")
		(net "M_F_CPU0_SA_CS_N<0>")
	)
	(segment
		(start 310.686704 -251.06249)
		(end 321.170554 -251.06249)
		(width 0.14478)
		(layer "In11.Cu")
		(net "M_F_CPU0_SA_CS_N<0>")
	)
	(segment
		(start 331.229716 -251.446792)
		(end 331.238098 -251.451618)
		(width 0.0889)
		(layer "In11.Cu")
		(net "M_F_CPU0_SA_CS_N<0>")
	)
	(segment
		(start 275.905214 -248.140982)
		(end 275.905214 -248.073164)
		(width 0.14478)
		(layer "In11.Cu")
		(net "M_F_CPU0_SA_CS_N<0>")
	)
	(segment
		(start 275.905214 -248.073164)
		(end 276.068282 -247.910096)
		(width 0.14478)
		(layer "In11.Cu")
		(net "M_F_CPU0_SA_CS_N<0>")
	)
	(segment
		(start 285.905194 -248.073164)
		(end 285.905194 -248.140982)
		(width 0.14478)
		(layer "In11.Cu")
		(net "M_F_CPU0_SA_CS_N<0>")
	)
	(segment
		(start 332.12278 -251.425456)
		(end 332.145132 -251.508768)
		(width 0.0889)
		(layer "In11.Cu")
		(net "M_F_CPU0_SA_CS_N<0>")
	)
	(segment
		(start 282.925266 -248.133362)
		(end 283.088334 -248.29643)
		(width 0.14478)
		(layer "In11.Cu")
		(net "M_F_CPU0_SA_CS_N<0>")
	)
	(segment
		(start 282.53182 -247.910096)
		(end 282.762198 -247.910096)
		(width 0.14478)
		(layer "In11.Cu")
		(net "M_F_CPU0_SA_CS_N<0>")
	)
	(segment
		(start 275.185632 -247.910096)
		(end 275.3487 -248.073164)
		(width 0.14478)
		(layer "In11.Cu")
		(net "M_F_CPU0_SA_CS_N<0>")
	)
	(segment
		(start 278.900128 -248.30405)
		(end 279.130506 -248.30405)
		(width 0.14478)
		(layer "In11.Cu")
		(net "M_F_CPU0_SA_CS_N<0>")
	)
	(segment
		(start 321.170554 -251.06249)
		(end 322.486274 -252.37821)
		(width 0.14478)
		(layer "In11.Cu")
		(net "M_F_CPU0_SA_CS_N<0>")
	)
	(segment
		(start 274.072604 -247.910096)
		(end 274.235672 -248.073164)
		(width 0.14478)
		(layer "In11.Cu")
		(net "M_F_CPU0_SA_CS_N<0>")
	)
	(segment
		(start 283.088334 -248.29643)
		(end 283.318712 -248.29643)
		(width 0.14478)
		(layer "In11.Cu")
		(net "M_F_CPU0_SA_CS_N<0>")
	)
	(segment
		(start 278.573992 -247.910096)
		(end 278.73706 -248.073164)
		(width 0.14478)
		(layer "In11.Cu")
		(net "M_F_CPU0_SA_CS_N<0>")
	)
	(segment
		(start 281.975306 -248.29643)
		(end 282.205684 -248.29643)
		(width 0.14478)
		(layer "In11.Cu")
		(net "M_F_CPU0_SA_CS_N<0>")
	)
	(segment
		(start 275.511768 -248.30405)
		(end 275.742146 -248.30405)
		(width 0.14478)
		(layer "In11.Cu")
		(net "M_F_CPU0_SA_CS_N<0>")
	)
	(segment
		(start 283.48178 -248.133362)
		(end 283.48178 -248.073164)
		(width 0.14478)
		(layer "In11.Cu")
		(net "M_F_CPU0_SA_CS_N<0>")
	)
	(segment
		(start 286.068262 -248.30405)
		(end 286.29864 -248.30405)
		(width 0.14478)
		(layer "In11.Cu")
		(net "M_F_CPU0_SA_CS_N<0>")
	)
	(segment
		(start 307.53431 -247.910096)
		(end 310.686704 -251.06249)
		(width 0.14478)
		(layer "In11.Cu")
		(net "M_F_CPU0_SA_CS_N<0>")
	)
	(segment
		(start 285.905194 -248.140982)
		(end 286.068262 -248.30405)
		(width 0.14478)
		(layer "In11.Cu")
		(net "M_F_CPU0_SA_CS_N<0>")
	)
	(segment
		(start 326.157082 -251.459492)
		(end 326.164702 -251.451872)
		(width 0.0889)
		(layer "In11.Cu")
		(net "M_F_CPU0_SA_CS_N<0>")
	)
	(segment
		(start 279.293574 -248.140982)
		(end 279.293574 -248.073164)
		(width 0.14478)
		(layer "In11.Cu")
		(net "M_F_CPU0_SA_CS_N<0>")
	)
	(arc
		(start 327.104756 -251.451618)
		(mid 327.281384 -251.401385)
		(end 327.46061 -251.441458)
		(width 0.0889)
		(layer "In11.Cu")
		(net "M_F_CPU0_SA_CS_N<0>")
	)
	(arc
		(start 327.490836 -251.45873)
		(mid 327.76837 -251.527711)
		(end 328.044048 -251.451618)
		(width 0.0889)
		(layer "In11.Cu")
		(net "M_F_CPU0_SA_CS_N<0>")
	)
	(arc
		(start 330.863956 -251.451618)
		(mid 331.046207 -251.401268)
		(end 331.229716 -251.446792)
		(width 0.0889)
		(layer "In11.Cu")
		(net "M_F_CPU0_SA_CS_N<0>")
	)
	(arc
		(start 328.41819 -251.451618)
		(mid 328.701146 -251.527795)
		(end 328.984102 -251.451618)
		(width 0.0889)
		(layer "In11.Cu")
		(net "M_F_CPU0_SA_CS_N<0>")
	)
	(arc
		(start 329.924156 -251.451618)
		(mid 330.1111 -251.401363)
		(end 330.298044 -251.451618)
		(width 0.0889)
		(layer "In11.Cu")
		(net "M_F_CPU0_SA_CS_N<0>")
	)
	(arc
		(start 328.992484 -251.446792)
		(mid 329.175992 -251.401298)
		(end 329.358244 -251.451618)
		(width 0.0889)
		(layer "In11.Cu")
		(net "M_F_CPU0_SA_CS_N<0>")
	)
	(arc
		(start 326.180958 -251.442474)
		(mid 326.360686 -251.40149)
		(end 326.538082 -251.451618)
		(width 0.0889)
		(layer "In11.Cu")
		(net "M_F_CPU0_SA_CS_N<0>")
	)
	(arc
		(start 329.358244 -251.451618)
		(mid 329.6412 -251.527795)
		(end 329.924156 -251.451618)
		(width 0.0889)
		(layer "In11.Cu")
		(net "M_F_CPU0_SA_CS_N<0>")
	)
	(arc
		(start 330.298044 -251.451618)
		(mid 330.581 -251.527795)
		(end 330.863956 -251.451618)
		(width 0.0889)
		(layer "In11.Cu")
		(net "M_F_CPU0_SA_CS_N<0>")
	)
	(arc
		(start 326.556116 -251.462286)
		(mid 326.831811 -251.528129)
		(end 327.104756 -251.451618)
		(width 0.0889)
		(layer "In11.Cu")
		(net "M_F_CPU0_SA_CS_N<0>")
	)
	(arc
		(start 328.044048 -251.451618)
		(mid 328.226299 -251.401268)
		(end 328.409808 -251.446792)
		(width 0.0889)
		(layer "In11.Cu")
		(net "M_F_CPU0_SA_CS_N<0>")
	)
	(arc
		(start 331.80401 -251.451618)
		(mid 331.960448 -251.402647)
		(end 332.12278 -251.425456)
		(width 0.0889)
		(layer "In11.Cu")
		(net "M_F_CPU0_SA_CS_N<0>")
	)
	(arc
		(start 331.238098 -251.451618)
		(mid 331.521054 -251.527795)
		(end 331.80401 -251.451618)
		(width 0.0889)
		(layer "In11.Cu")
		(net "M_F_CPU0_SA_CS_N<0>")
	)
	(segment
		(start 333.868014 -249.610118)
		(end 333.401162 -249.34418)
		(width 0.10668)
		(layer "F.Cu")
		(net "M_F_CPU0_SA_CB<7>")
	)
	(segment
		(start 326.63384 -249.0216)
		(end 326.645524 -249.014742)
		(width 0.0889)
		(layer "In11.Cu")
		(net "M_F_CPU0_SA_CB<7>")
	)
	(segment
		(start 308.508654 -245.36019)
		(end 312.293254 -249.14479)
		(width 0.14478)
		(layer "In11.Cu")
		(net "M_F_CPU0_SA_CB<7>")
	)
	(segment
		(start 279.38476 -244.245638)
		(end 279.547828 -244.08257)
		(width 0.14478)
		(layer "In11.Cu")
		(net "M_F_CPU0_SA_CB<7>")
	)
	(segment
		(start 279.778206 -244.08257)
		(end 279.941274 -244.245638)
		(width 0.14478)
		(layer "In11.Cu")
		(net "M_F_CPU0_SA_CB<7>")
	)
	(segment
		(start 275.09978 -245.36019)
		(end 275.773388 -245.36019)
		(width 0.14478)
		(layer "In11.Cu")
		(net "M_F_CPU0_SA_CB<7>")
	)
	(segment
		(start 276.099524 -243.61521)
		(end 276.329902 -243.61521)
		(width 0.14478)
		(layer "In11.Cu")
		(net "M_F_CPU0_SA_CB<7>")
	)
	(segment
		(start 333.555086 -249.07875)
		(end 333.401162 -249.34418)
		(width 0.0889)
		(layer "In11.Cu")
		(net "M_F_CPU0_SA_CB<7>")
	)
	(segment
		(start 279.941274 -245.197122)
		(end 280.104342 -245.36019)
		(width 0.14478)
		(layer "In11.Cu")
		(net "M_F_CPU0_SA_CB<7>")
	)
	(segment
		(start 329.819762 -249.016774)
		(end 329.828144 -249.0216)
		(width 0.0889)
		(layer "In11.Cu")
		(net "M_F_CPU0_SA_CB<7>")
	)
	(segment
		(start 325.68769 -249.96775)
		(end 326.63384 -249.0216)
		(width 0.0889)
		(layer "In11.Cu")
		(net "M_F_CPU0_SA_CB<7>")
	)
	(segment
		(start 279.941274 -244.245638)
		(end 279.941274 -245.197122)
		(width 0.14478)
		(layer "In11.Cu")
		(net "M_F_CPU0_SA_CB<7>")
	)
	(segment
		(start 276.656038 -245.36019)
		(end 279.221692 -245.36019)
		(width 0.14478)
		(layer "In11.Cu")
		(net "M_F_CPU0_SA_CB<7>")
	)
	(segment
		(start 279.221692 -245.36019)
		(end 279.38476 -245.197122)
		(width 0.14478)
		(layer "In11.Cu")
		(net "M_F_CPU0_SA_CB<7>")
	)
	(segment
		(start 280.104342 -245.36019)
		(end 308.508654 -245.36019)
		(width 0.14478)
		(layer "In11.Cu")
		(net "M_F_CPU0_SA_CB<7>")
	)
	(segment
		(start 327.007728 -249.0216)
		(end 327.018142 -249.027696)
		(width 0.0889)
		(layer "In11.Cu")
		(net "M_F_CPU0_SA_CB<7>")
	)
	(segment
		(start 279.547828 -244.08257)
		(end 279.778206 -244.08257)
		(width 0.14478)
		(layer "In11.Cu")
		(net "M_F_CPU0_SA_CB<7>")
	)
	(segment
		(start 322.788534 -249.96775)
		(end 324.188074 -249.96775)
		(width 0.14478)
		(layer "In11.Cu")
		(net "M_F_CPU0_SA_CB<7>")
	)
	(segment
		(start 275.936456 -243.778278)
		(end 276.099524 -243.61521)
		(width 0.14478)
		(layer "In11.Cu")
		(net "M_F_CPU0_SA_CB<7>")
	)
	(segment
		(start 276.329902 -243.61521)
		(end 276.49297 -243.778278)
		(width 0.14478)
		(layer "In11.Cu")
		(net "M_F_CPU0_SA_CB<7>")
	)
	(segment
		(start 279.38476 -245.197122)
		(end 279.38476 -244.245638)
		(width 0.14478)
		(layer "In11.Cu")
		(net "M_F_CPU0_SA_CB<7>")
	)
	(segment
		(start 275.773388 -245.36019)
		(end 275.936456 -245.197122)
		(width 0.14478)
		(layer "In11.Cu")
		(net "M_F_CPU0_SA_CB<7>")
	)
	(segment
		(start 276.49297 -245.197122)
		(end 276.656038 -245.36019)
		(width 0.14478)
		(layer "In11.Cu")
		(net "M_F_CPU0_SA_CB<7>")
	)
	(segment
		(start 275.936456 -245.197122)
		(end 275.936456 -243.778278)
		(width 0.14478)
		(layer "In11.Cu")
		(net "M_F_CPU0_SA_CB<7>")
	)
	(segment
		(start 331.33411 -249.0216)
		(end 331.342492 -249.016774)
		(width 0.0889)
		(layer "In11.Cu")
		(net "M_F_CPU0_SA_CB<7>")
	)
	(segment
		(start 312.293254 -249.14479)
		(end 321.965574 -249.14479)
		(width 0.14478)
		(layer "In11.Cu")
		(net "M_F_CPU0_SA_CB<7>")
	)
	(segment
		(start 265.973306 -243.660168)
		(end 273.399758 -243.660168)
		(width 0.14478)
		(layer "In11.Cu")
		(net "M_F_CPU0_SA_CB<7>")
	)
	(segment
		(start 330.394056 -249.0216)
		(end 330.402438 -249.016774)
		(width 0.0889)
		(layer "In11.Cu")
		(net "M_F_CPU0_SA_CB<7>")
	)
	(segment
		(start 276.49297 -243.778278)
		(end 276.49297 -245.197122)
		(width 0.14478)
		(layer "In11.Cu")
		(net "M_F_CPU0_SA_CB<7>")
	)
	(segment
		(start 333.532734 -248.995438)
		(end 333.555086 -249.07875)
		(width 0.0889)
		(layer "In11.Cu")
		(net "M_F_CPU0_SA_CB<7>")
	)
	(segment
		(start 321.965574 -249.14479)
		(end 322.788534 -249.96775)
		(width 0.14478)
		(layer "In11.Cu")
		(net "M_F_CPU0_SA_CB<7>")
	)
	(segment
		(start 265.54811 -243.234972)
		(end 265.973306 -243.660168)
		(width 0.14478)
		(layer "In11.Cu")
		(net "M_F_CPU0_SA_CB<7>")
	)
	(segment
		(start 324.188074 -249.96775)
		(end 325.68769 -249.96775)
		(width 0.0889)
		(layer "In11.Cu")
		(net "M_F_CPU0_SA_CB<7>")
	)
	(segment
		(start 273.399758 -243.660168)
		(end 275.09978 -245.36019)
		(width 0.14478)
		(layer "In11.Cu")
		(net "M_F_CPU0_SA_CB<7>")
	)
	(arc
		(start 332.648052 -249.0216)
		(mid 332.931008 -249.097777)
		(end 333.213964 -249.0216)
		(width 0.0889)
		(layer "In11.Cu")
		(net "M_F_CPU0_SA_CB<7>")
	)
	(arc
		(start 330.768198 -249.0216)
		(mid 331.051154 -249.097777)
		(end 331.33411 -249.0216)
		(width 0.0889)
		(layer "In11.Cu")
		(net "M_F_CPU0_SA_CB<7>")
	)
	(arc
		(start 327.94829 -249.0216)
		(mid 328.231246 -249.097777)
		(end 328.514202 -249.0216)
		(width 0.0889)
		(layer "In11.Cu")
		(net "M_F_CPU0_SA_CB<7>")
	)
	(arc
		(start 328.88809 -249.0216)
		(mid 329.171046 -249.097777)
		(end 329.454002 -249.0216)
		(width 0.0889)
		(layer "In11.Cu")
		(net "M_F_CPU0_SA_CB<7>")
	)
	(arc
		(start 326.645524 -249.014742)
		(mid 326.827525 -248.971209)
		(end 327.007728 -249.0216)
		(width 0.0889)
		(layer "In11.Cu")
		(net "M_F_CPU0_SA_CB<7>")
	)
	(arc
		(start 331.342492 -249.016774)
		(mid 331.526 -248.97128)
		(end 331.708252 -249.0216)
		(width 0.0889)
		(layer "In11.Cu")
		(net "M_F_CPU0_SA_CB<7>")
	)
	(arc
		(start 330.402438 -249.016774)
		(mid 330.585946 -248.97128)
		(end 330.768198 -249.0216)
		(width 0.0889)
		(layer "In11.Cu")
		(net "M_F_CPU0_SA_CB<7>")
	)
	(arc
		(start 327.018142 -249.027696)
		(mid 327.296828 -249.097916)
		(end 327.573894 -249.0216)
		(width 0.0889)
		(layer "In11.Cu")
		(net "M_F_CPU0_SA_CB<7>")
	)
	(arc
		(start 331.708252 -249.0216)
		(mid 331.991208 -249.097777)
		(end 332.274164 -249.0216)
		(width 0.0889)
		(layer "In11.Cu")
		(net "M_F_CPU0_SA_CB<7>")
	)
	(arc
		(start 332.274164 -249.0216)
		(mid 332.461108 -248.971345)
		(end 332.648052 -249.0216)
		(width 0.0889)
		(layer "In11.Cu")
		(net "M_F_CPU0_SA_CB<7>")
	)
	(arc
		(start 327.573894 -249.0216)
		(mid 327.761092 -248.971218)
		(end 327.94829 -249.0216)
		(width 0.0889)
		(layer "In11.Cu")
		(net "M_F_CPU0_SA_CB<7>")
	)
	(arc
		(start 333.213964 -249.0216)
		(mid 333.370402 -248.972629)
		(end 333.532734 -248.995438)
		(width 0.0889)
		(layer "In11.Cu")
		(net "M_F_CPU0_SA_CB<7>")
	)
	(arc
		(start 329.828144 -249.0216)
		(mid 330.1111 -249.097777)
		(end 330.394056 -249.0216)
		(width 0.0889)
		(layer "In11.Cu")
		(net "M_F_CPU0_SA_CB<7>")
	)
	(arc
		(start 328.514202 -249.0216)
		(mid 328.701146 -248.971345)
		(end 328.88809 -249.0216)
		(width 0.0889)
		(layer "In11.Cu")
		(net "M_F_CPU0_SA_CB<7>")
	)
	(arc
		(start 329.454002 -249.0216)
		(mid 329.636253 -248.97125)
		(end 329.819762 -249.016774)
		(width 0.0889)
		(layer "In11.Cu")
		(net "M_F_CPU0_SA_CB<7>")
	)
	(segment
		(start 332.45806 -248.800112)
		(end 331.991208 -248.534174)
		(width 0.10668)
		(layer "F.Cu")
		(net "M_F_CPU0_SA_CB<6>")
	)
	(segment
		(start 313.197494 -248.23547)
		(end 322.34251 -248.23547)
		(width 0.14478)
		(layer "In11.Cu")
		(net "M_F_CPU0_SA_CB<6>")
	)
	(segment
		(start 326.164702 -248.211848)
		(end 326.184768 -248.200418)
		(width 0.0889)
		(layer "In11.Cu")
		(net "M_F_CPU0_SA_CB<6>")
	)
	(segment
		(start 294.31488 -242.594892)
		(end 294.45966 -242.739672)
		(width 0.14478)
		(layer "In11.Cu")
		(net "M_F_CPU0_SA_CB<6>")
	)
	(segment
		(start 327.08723 -248.222262)
		(end 327.105264 -248.211594)
		(width 0.0889)
		(layer "In11.Cu")
		(net "M_F_CPU0_SA_CB<6>")
	)
	(segment
		(start 293.763446 -243.659914)
		(end 293.908226 -243.515134)
		(width 0.14478)
		(layer "In11.Cu")
		(net "M_F_CPU0_SA_CB<6>")
	)
	(segment
		(start 298.842938 -242.856512)
		(end 298.842938 -243.515134)
		(width 0.14478)
		(layer "In11.Cu")
		(net "M_F_CPU0_SA_CB<6>")
	)
	(segment
		(start 297.043856 -243.659914)
		(end 297.188636 -243.515134)
		(width 0.14478)
		(layer "In11.Cu")
		(net "M_F_CPU0_SA_CB<6>")
	)
	(segment
		(start 305.951636 -243.659914)
		(end 306.920138 -242.691412)
		(width 0.14478)
		(layer "In11.Cu")
		(net "M_F_CPU0_SA_CB<6>")
	)
	(segment
		(start 325.576184 -248.800366)
		(end 326.164702 -248.211848)
		(width 0.0889)
		(layer "In11.Cu")
		(net "M_F_CPU0_SA_CB<6>")
	)
	(segment
		(start 327.478898 -248.211848)
		(end 327.490836 -248.218706)
		(width 0.0889)
		(layer "In11.Cu")
		(net "M_F_CPU0_SA_CB<6>")
	)
	(segment
		(start 328.409808 -248.206768)
		(end 328.41819 -248.211594)
		(width 0.0889)
		(layer "In11.Cu")
		(net "M_F_CPU0_SA_CB<6>")
	)
	(segment
		(start 294.45966 -243.515134)
		(end 294.60444 -243.659914)
		(width 0.14478)
		(layer "In11.Cu")
		(net "M_F_CPU0_SA_CB<6>")
	)
	(segment
		(start 298.436284 -242.711732)
		(end 298.698158 -242.711732)
		(width 0.14478)
		(layer "In11.Cu")
		(net "M_F_CPU0_SA_CB<6>")
	)
	(segment
		(start 298.698158 -242.711732)
		(end 298.842938 -242.856512)
		(width 0.14478)
		(layer "In11.Cu")
		(net "M_F_CPU0_SA_CB<6>")
	)
	(segment
		(start 265.973306 -241.960146)
		(end 289.319716 -241.960146)
		(width 0.14478)
		(layer "In11.Cu")
		(net "M_F_CPU0_SA_CB<6>")
	)
	(segment
		(start 298.987718 -243.659914)
		(end 305.951636 -243.659914)
		(width 0.14478)
		(layer "In11.Cu")
		(net "M_F_CPU0_SA_CB<6>")
	)
	(segment
		(start 322.34251 -248.23547)
		(end 322.907406 -248.800366)
		(width 0.14478)
		(layer "In11.Cu")
		(net "M_F_CPU0_SA_CB<6>")
	)
	(segment
		(start 323.951854 -248.800366)
		(end 325.576184 -248.800366)
		(width 0.0889)
		(layer "In11.Cu")
		(net "M_F_CPU0_SA_CB<6>")
	)
	(segment
		(start 298.146724 -243.659914)
		(end 298.291504 -243.515134)
		(width 0.14478)
		(layer "In11.Cu")
		(net "M_F_CPU0_SA_CB<6>")
	)
	(segment
		(start 332.145132 -248.268744)
		(end 331.991208 -248.534174)
		(width 0.0889)
		(layer "In11.Cu")
		(net "M_F_CPU0_SA_CB<6>")
	)
	(segment
		(start 327.465182 -248.203974)
		(end 327.478898 -248.211848)
		(width 0.0889)
		(layer "In11.Cu")
		(net "M_F_CPU0_SA_CB<6>")
	)
	(segment
		(start 307.653436 -242.691412)
		(end 313.197494 -248.23547)
		(width 0.14478)
		(layer "In11.Cu")
		(net "M_F_CPU0_SA_CB<6>")
	)
	(segment
		(start 306.920138 -242.691412)
		(end 307.653436 -242.691412)
		(width 0.14478)
		(layer "In11.Cu")
		(net "M_F_CPU0_SA_CB<6>")
	)
	(segment
		(start 298.291504 -243.515134)
		(end 298.291504 -242.856512)
		(width 0.14478)
		(layer "In11.Cu")
		(net "M_F_CPU0_SA_CB<6>")
	)
	(segment
		(start 294.60444 -243.659914)
		(end 297.043856 -243.659914)
		(width 0.14478)
		(layer "In11.Cu")
		(net "M_F_CPU0_SA_CB<6>")
	)
	(segment
		(start 297.188636 -243.515134)
		(end 297.188636 -242.856512)
		(width 0.14478)
		(layer "In11.Cu")
		(net "M_F_CPU0_SA_CB<6>")
	)
	(segment
		(start 294.45966 -242.739672)
		(end 294.45966 -243.515134)
		(width 0.14478)
		(layer "In11.Cu")
		(net "M_F_CPU0_SA_CB<6>")
	)
	(segment
		(start 294.053006 -242.594892)
		(end 294.31488 -242.594892)
		(width 0.14478)
		(layer "In11.Cu")
		(net "M_F_CPU0_SA_CB<6>")
	)
	(segment
		(start 297.88485 -243.659914)
		(end 298.146724 -243.659914)
		(width 0.14478)
		(layer "In11.Cu")
		(net "M_F_CPU0_SA_CB<6>")
	)
	(segment
		(start 328.984102 -248.211594)
		(end 328.992484 -248.206768)
		(width 0.0889)
		(layer "In11.Cu")
		(net "M_F_CPU0_SA_CB<6>")
	)
	(segment
		(start 322.907406 -248.800366)
		(end 323.951854 -248.800366)
		(width 0.14478)
		(layer "In11.Cu")
		(net "M_F_CPU0_SA_CB<6>")
	)
	(segment
		(start 298.291504 -242.856512)
		(end 298.436284 -242.711732)
		(width 0.14478)
		(layer "In11.Cu")
		(net "M_F_CPU0_SA_CB<6>")
	)
	(segment
		(start 332.12278 -248.185432)
		(end 332.145132 -248.268744)
		(width 0.0889)
		(layer "In11.Cu")
		(net "M_F_CPU0_SA_CB<6>")
	)
	(segment
		(start 293.908226 -242.739672)
		(end 294.053006 -242.594892)
		(width 0.14478)
		(layer "In11.Cu")
		(net "M_F_CPU0_SA_CB<6>")
	)
	(segment
		(start 297.59529 -242.711732)
		(end 297.74007 -242.856512)
		(width 0.14478)
		(layer "In11.Cu")
		(net "M_F_CPU0_SA_CB<6>")
	)
	(segment
		(start 331.229716 -248.206768)
		(end 331.238098 -248.211594)
		(width 0.0889)
		(layer "In11.Cu")
		(net "M_F_CPU0_SA_CB<6>")
	)
	(segment
		(start 297.188636 -242.856512)
		(end 297.333416 -242.711732)
		(width 0.14478)
		(layer "In11.Cu")
		(net "M_F_CPU0_SA_CB<6>")
	)
	(segment
		(start 291.019484 -243.659914)
		(end 293.763446 -243.659914)
		(width 0.14478)
		(layer "In11.Cu")
		(net "M_F_CPU0_SA_CB<6>")
	)
	(segment
		(start 293.908226 -243.515134)
		(end 293.908226 -242.739672)
		(width 0.14478)
		(layer "In11.Cu")
		(net "M_F_CPU0_SA_CB<6>")
	)
	(segment
		(start 297.74007 -243.515134)
		(end 297.88485 -243.659914)
		(width 0.14478)
		(layer "In11.Cu")
		(net "M_F_CPU0_SA_CB<6>")
	)
	(segment
		(start 297.74007 -242.856512)
		(end 297.74007 -243.515134)
		(width 0.14478)
		(layer "In11.Cu")
		(net "M_F_CPU0_SA_CB<6>")
	)
	(segment
		(start 265.54811 -241.53495)
		(end 265.973306 -241.960146)
		(width 0.14478)
		(layer "In11.Cu")
		(net "M_F_CPU0_SA_CB<6>")
	)
	(segment
		(start 297.333416 -242.711732)
		(end 297.59529 -242.711732)
		(width 0.14478)
		(layer "In11.Cu")
		(net "M_F_CPU0_SA_CB<6>")
	)
	(segment
		(start 298.842938 -243.515134)
		(end 298.987718 -243.659914)
		(width 0.14478)
		(layer "In11.Cu")
		(net "M_F_CPU0_SA_CB<6>")
	)
	(segment
		(start 289.319716 -241.960146)
		(end 291.019484 -243.659914)
		(width 0.14478)
		(layer "In11.Cu")
		(net "M_F_CPU0_SA_CB<6>")
	)
	(arc
		(start 329.358244 -248.211594)
		(mid 329.6412 -248.287771)
		(end 329.924156 -248.211594)
		(width 0.0889)
		(layer "In11.Cu")
		(net "M_F_CPU0_SA_CB<6>")
	)
	(arc
		(start 327.105264 -248.211594)
		(mid 327.284251 -248.161424)
		(end 327.465182 -248.203974)
		(width 0.0889)
		(layer "In11.Cu")
		(net "M_F_CPU0_SA_CB<6>")
	)
	(arc
		(start 327.490836 -248.218706)
		(mid 327.76837 -248.287687)
		(end 328.044048 -248.211594)
		(width 0.0889)
		(layer "In11.Cu")
		(net "M_F_CPU0_SA_CB<6>")
	)
	(arc
		(start 328.41819 -248.211594)
		(mid 328.701146 -248.287771)
		(end 328.984102 -248.211594)
		(width 0.0889)
		(layer "In11.Cu")
		(net "M_F_CPU0_SA_CB<6>")
	)
	(arc
		(start 331.80401 -248.211594)
		(mid 331.960448 -248.162623)
		(end 332.12278 -248.185432)
		(width 0.0889)
		(layer "In11.Cu")
		(net "M_F_CPU0_SA_CB<6>")
	)
	(arc
		(start 330.298044 -248.211594)
		(mid 330.581 -248.287771)
		(end 330.863956 -248.211594)
		(width 0.0889)
		(layer "In11.Cu")
		(net "M_F_CPU0_SA_CB<6>")
	)
	(arc
		(start 326.53859 -248.211594)
		(mid 326.811534 -248.288174)
		(end 327.08723 -248.222262)
		(width 0.0889)
		(layer "In11.Cu")
		(net "M_F_CPU0_SA_CB<6>")
	)
	(arc
		(start 329.924156 -248.211594)
		(mid 330.1111 -248.161339)
		(end 330.298044 -248.211594)
		(width 0.0889)
		(layer "In11.Cu")
		(net "M_F_CPU0_SA_CB<6>")
	)
	(arc
		(start 326.184768 -248.200418)
		(mid 326.3631 -248.161321)
		(end 326.53859 -248.211594)
		(width 0.0889)
		(layer "In11.Cu")
		(net "M_F_CPU0_SA_CB<6>")
	)
	(arc
		(start 331.238098 -248.211594)
		(mid 331.521054 -248.287771)
		(end 331.80401 -248.211594)
		(width 0.0889)
		(layer "In11.Cu")
		(net "M_F_CPU0_SA_CB<6>")
	)
	(arc
		(start 328.992484 -248.206768)
		(mid 329.175992 -248.161274)
		(end 329.358244 -248.211594)
		(width 0.0889)
		(layer "In11.Cu")
		(net "M_F_CPU0_SA_CB<6>")
	)
	(arc
		(start 328.044048 -248.211594)
		(mid 328.226299 -248.161244)
		(end 328.409808 -248.206768)
		(width 0.0889)
		(layer "In11.Cu")
		(net "M_F_CPU0_SA_CB<6>")
	)
	(arc
		(start 330.863956 -248.211594)
		(mid 331.046207 -248.161244)
		(end 331.229716 -248.206768)
		(width 0.0889)
		(layer "In11.Cu")
		(net "M_F_CPU0_SA_CB<6>")
	)
	(segment
		(start 334.337914 -248.800112)
		(end 333.871062 -248.534174)
		(width 0.10668)
		(layer "F.Cu")
		(net "M_F_CPU0_SA_CB<5>")
	)
	(segment
		(start 287.542224 -242.716558)
		(end 287.542224 -244.346984)
		(width 0.14478)
		(layer "In11.Cu")
		(net "M_F_CPU0_SA_CB<5>")
	)
	(segment
		(start 289.138868 -243.17325)
		(end 289.369246 -243.17325)
		(width 0.14478)
		(layer "In11.Cu")
		(net "M_F_CPU0_SA_CB<5>")
	)
	(segment
		(start 322.778882 -249.31497)
		(end 323.880734 -249.31497)
		(width 0.14478)
		(layer "In11.Cu")
		(net "M_F_CPU0_SA_CB<5>")
	)
	(segment
		(start 332.744064 -248.856754)
		(end 332.752446 -248.86158)
		(width 0.0889)
		(layer "In11.Cu")
		(net "M_F_CPU0_SA_CB<5>")
	)
	(segment
		(start 286.822642 -244.510052)
		(end 286.98571 -244.346984)
		(width 0.14478)
		(layer "In11.Cu")
		(net "M_F_CPU0_SA_CB<5>")
	)
	(segment
		(start 325.882 -249.242072)
		(end 325.885302 -249.23877)
		(width 0.0889)
		(layer "In11.Cu")
		(net "M_F_CPU0_SA_CB<5>")
	)
	(segment
		(start 324.430898 -249.315732)
		(end 324.504558 -249.242072)
		(width 0.0889)
		(layer "In11.Cu")
		(net "M_F_CPU0_SA_CB<5>")
	)
	(segment
		(start 288.9758 -243.336318)
		(end 289.138868 -243.17325)
		(width 0.14478)
		(layer "In11.Cu")
		(net "M_F_CPU0_SA_CB<5>")
	)
	(segment
		(start 289.695382 -244.510052)
		(end 308.537356 -244.510052)
		(width 0.14478)
		(layer "In11.Cu")
		(net "M_F_CPU0_SA_CB<5>")
	)
	(segment
		(start 331.229716 -248.86158)
		(end 331.238098 -248.856754)
		(width 0.0889)
		(layer "In11.Cu")
		(net "M_F_CPU0_SA_CB<5>")
	)
	(segment
		(start 269.648178 -242.385088)
		(end 270.07312 -242.81003)
		(width 0.14478)
		(layer "In11.Cu")
		(net "M_F_CPU0_SA_CB<5>")
	)
	(segment
		(start 328.984102 -248.856754)
		(end 328.992484 -248.86158)
		(width 0.0889)
		(layer "In11.Cu")
		(net "M_F_CPU0_SA_CB<5>")
	)
	(segment
		(start 325.885302 -249.23877)
		(end 326.548242 -248.850658)
		(width 0.0889)
		(layer "In11.Cu")
		(net "M_F_CPU0_SA_CB<5>")
	)
	(segment
		(start 287.705292 -244.510052)
		(end 288.812732 -244.510052)
		(width 0.14478)
		(layer "In11.Cu")
		(net "M_F_CPU0_SA_CB<5>")
	)
	(segment
		(start 322.154042 -248.69013)
		(end 322.778882 -249.31497)
		(width 0.14478)
		(layer "In11.Cu")
		(net "M_F_CPU0_SA_CB<5>")
	)
	(segment
		(start 333.717138 -248.799604)
		(end 333.871062 -248.534174)
		(width 0.0889)
		(layer "In11.Cu")
		(net "M_F_CPU0_SA_CB<5>")
	)
	(segment
		(start 283.652722 -242.50523)
		(end 283.8831 -242.50523)
		(width 0.14478)
		(layer "In11.Cu")
		(net "M_F_CPU0_SA_CB<5>")
	)
	(segment
		(start 284.046168 -242.668298)
		(end 284.046168 -244.346984)
		(width 0.14478)
		(layer "In11.Cu")
		(net "M_F_CPU0_SA_CB<5>")
	)
	(segment
		(start 333.621126 -248.825004)
		(end 333.717138 -248.799604)
		(width 0.0889)
		(layer "In11.Cu")
		(net "M_F_CPU0_SA_CB<5>")
	)
	(segment
		(start 270.07312 -242.81003)
		(end 280.9748 -242.81003)
		(width 0.14478)
		(layer "In11.Cu")
		(net "M_F_CPU0_SA_CB<5>")
	)
	(segment
		(start 284.046168 -244.346984)
		(end 284.209236 -244.510052)
		(width 0.14478)
		(layer "In11.Cu")
		(net "M_F_CPU0_SA_CB<5>")
	)
	(segment
		(start 312.717434 -248.69013)
		(end 322.154042 -248.69013)
		(width 0.14478)
		(layer "In11.Cu")
		(net "M_F_CPU0_SA_CB<5>")
	)
	(segment
		(start 282.674822 -244.510052)
		(end 283.326586 -244.510052)
		(width 0.14478)
		(layer "In11.Cu")
		(net "M_F_CPU0_SA_CB<5>")
	)
	(segment
		(start 289.532314 -244.346984)
		(end 289.695382 -244.510052)
		(width 0.14478)
		(layer "In11.Cu")
		(net "M_F_CPU0_SA_CB<5>")
	)
	(segment
		(start 286.98571 -244.346984)
		(end 286.98571 -242.716558)
		(width 0.14478)
		(layer "In11.Cu")
		(net "M_F_CPU0_SA_CB<5>")
	)
	(segment
		(start 328.033634 -248.850658)
		(end 328.044048 -248.856754)
		(width 0.0889)
		(layer "In11.Cu")
		(net "M_F_CPU0_SA_CB<5>")
	)
	(segment
		(start 332.16977 -248.86158)
		(end 332.178152 -248.856754)
		(width 0.0889)
		(layer "In11.Cu")
		(net "M_F_CPU0_SA_CB<5>")
	)
	(segment
		(start 280.9748 -242.81003)
		(end 282.674822 -244.510052)
		(width 0.14478)
		(layer "In11.Cu")
		(net "M_F_CPU0_SA_CB<5>")
	)
	(segment
		(start 289.369246 -243.17325)
		(end 289.532314 -243.336318)
		(width 0.14478)
		(layer "In11.Cu")
		(net "M_F_CPU0_SA_CB<5>")
	)
	(segment
		(start 283.489654 -242.668298)
		(end 283.652722 -242.50523)
		(width 0.14478)
		(layer "In11.Cu")
		(net "M_F_CPU0_SA_CB<5>")
	)
	(segment
		(start 308.537356 -244.510052)
		(end 312.717434 -248.69013)
		(width 0.14478)
		(layer "In11.Cu")
		(net "M_F_CPU0_SA_CB<5>")
	)
	(segment
		(start 287.379156 -242.55349)
		(end 287.542224 -242.716558)
		(width 0.14478)
		(layer "In11.Cu")
		(net "M_F_CPU0_SA_CB<5>")
	)
	(segment
		(start 283.489654 -244.346984)
		(end 283.489654 -242.668298)
		(width 0.14478)
		(layer "In11.Cu")
		(net "M_F_CPU0_SA_CB<5>")
	)
	(segment
		(start 328.409808 -248.86158)
		(end 328.41819 -248.856754)
		(width 0.0889)
		(layer "In11.Cu")
		(net "M_F_CPU0_SA_CB<5>")
	)
	(segment
		(start 324.504558 -249.242072)
		(end 325.882 -249.242072)
		(width 0.0889)
		(layer "In11.Cu")
		(net "M_F_CPU0_SA_CB<5>")
	)
	(segment
		(start 288.9758 -244.346984)
		(end 288.9758 -243.336318)
		(width 0.14478)
		(layer "In11.Cu")
		(net "M_F_CPU0_SA_CB<5>")
	)
	(segment
		(start 283.8831 -242.50523)
		(end 284.046168 -242.668298)
		(width 0.14478)
		(layer "In11.Cu")
		(net "M_F_CPU0_SA_CB<5>")
	)
	(segment
		(start 323.881496 -249.315732)
		(end 324.430898 -249.315732)
		(width 0.0889)
		(layer "In11.Cu")
		(net "M_F_CPU0_SA_CB<5>")
	)
	(segment
		(start 289.532314 -243.336318)
		(end 289.532314 -244.346984)
		(width 0.14478)
		(layer "In11.Cu")
		(net "M_F_CPU0_SA_CB<5>")
	)
	(segment
		(start 287.148778 -242.55349)
		(end 287.379156 -242.55349)
		(width 0.14478)
		(layer "In11.Cu")
		(net "M_F_CPU0_SA_CB<5>")
	)
	(segment
		(start 283.326586 -244.510052)
		(end 283.489654 -244.346984)
		(width 0.14478)
		(layer "In11.Cu")
		(net "M_F_CPU0_SA_CB<5>")
	)
	(segment
		(start 284.209236 -244.510052)
		(end 286.822642 -244.510052)
		(width 0.14478)
		(layer "In11.Cu")
		(net "M_F_CPU0_SA_CB<5>")
	)
	(segment
		(start 323.880734 -249.31497)
		(end 323.881496 -249.315732)
		(width 0.0889)
		(layer "In11.Cu")
		(net "M_F_CPU0_SA_CB<5>")
	)
	(segment
		(start 286.98571 -242.716558)
		(end 287.148778 -242.55349)
		(width 0.14478)
		(layer "In11.Cu")
		(net "M_F_CPU0_SA_CB<5>")
	)
	(segment
		(start 287.542224 -244.346984)
		(end 287.705292 -244.510052)
		(width 0.14478)
		(layer "In11.Cu")
		(net "M_F_CPU0_SA_CB<5>")
	)
	(segment
		(start 288.812732 -244.510052)
		(end 288.9758 -244.346984)
		(width 0.14478)
		(layer "In11.Cu")
		(net "M_F_CPU0_SA_CB<5>")
	)
	(arc
		(start 329.358244 -248.856754)
		(mid 329.6412 -248.780577)
		(end 329.924156 -248.856754)
		(width 0.0889)
		(layer "In11.Cu")
		(net "M_F_CPU0_SA_CB<5>")
	)
	(arc
		(start 332.178152 -248.856754)
		(mid 332.461108 -248.780577)
		(end 332.744064 -248.856754)
		(width 0.0889)
		(layer "In11.Cu")
		(net "M_F_CPU0_SA_CB<5>")
	)
	(arc
		(start 330.863956 -248.856754)
		(mid 331.046207 -248.907104)
		(end 331.229716 -248.86158)
		(width 0.0889)
		(layer "In11.Cu")
		(net "M_F_CPU0_SA_CB<5>")
	)
	(arc
		(start 326.548242 -248.850658)
		(mid 326.826674 -248.78056)
		(end 327.103486 -248.856754)
		(width 0.0889)
		(layer "In11.Cu")
		(net "M_F_CPU0_SA_CB<5>")
	)
	(arc
		(start 328.41819 -248.856754)
		(mid 328.701146 -248.780577)
		(end 328.984102 -248.856754)
		(width 0.0889)
		(layer "In11.Cu")
		(net "M_F_CPU0_SA_CB<5>")
	)
	(arc
		(start 332.752446 -248.86158)
		(mid 332.935954 -248.907074)
		(end 333.118206 -248.856754)
		(width 0.0889)
		(layer "In11.Cu")
		(net "M_F_CPU0_SA_CB<5>")
	)
	(arc
		(start 329.924156 -248.856754)
		(mid 330.1111 -248.907009)
		(end 330.298044 -248.856754)
		(width 0.0889)
		(layer "In11.Cu")
		(net "M_F_CPU0_SA_CB<5>")
	)
	(arc
		(start 328.044048 -248.856754)
		(mid 328.226299 -248.907104)
		(end 328.409808 -248.86158)
		(width 0.0889)
		(layer "In11.Cu")
		(net "M_F_CPU0_SA_CB<5>")
	)
	(arc
		(start 333.118206 -248.856754)
		(mid 333.365919 -248.781534)
		(end 333.621126 -248.825004)
		(width 0.0889)
		(layer "In11.Cu")
		(net "M_F_CPU0_SA_CB<5>")
	)
	(arc
		(start 327.103486 -248.856754)
		(mid 327.290684 -248.907136)
		(end 327.477882 -248.856754)
		(width 0.0889)
		(layer "In11.Cu")
		(net "M_F_CPU0_SA_CB<5>")
	)
	(arc
		(start 331.238098 -248.856754)
		(mid 331.521054 -248.780577)
		(end 331.80401 -248.856754)
		(width 0.0889)
		(layer "In11.Cu")
		(net "M_F_CPU0_SA_CB<5>")
	)
	(arc
		(start 331.80401 -248.856754)
		(mid 331.986261 -248.907104)
		(end 332.16977 -248.86158)
		(width 0.0889)
		(layer "In11.Cu")
		(net "M_F_CPU0_SA_CB<5>")
	)
	(arc
		(start 328.992484 -248.86158)
		(mid 329.175992 -248.907074)
		(end 329.358244 -248.856754)
		(width 0.0889)
		(layer "In11.Cu")
		(net "M_F_CPU0_SA_CB<5>")
	)
	(arc
		(start 327.477882 -248.856754)
		(mid 327.754949 -248.780483)
		(end 328.033634 -248.850658)
		(width 0.0889)
		(layer "In11.Cu")
		(net "M_F_CPU0_SA_CB<5>")
	)
	(arc
		(start 330.298044 -248.856754)
		(mid 330.581 -248.780577)
		(end 330.863956 -248.856754)
		(width 0.0889)
		(layer "In11.Cu")
		(net "M_F_CPU0_SA_CB<5>")
	)
	(segment
		(start 332.92796 -247.990106)
		(end 332.461108 -247.724168)
		(width 0.10668)
		(layer "F.Cu")
		(net "M_F_CPU0_SA_CB<4>")
	)
	(segment
		(start 301.024798 -242.85067)
		(end 301.187866 -242.687602)
		(width 0.14478)
		(layer "In11.Cu")
		(net "M_F_CPU0_SA_CB<4>")
	)
	(segment
		(start 304.511964 -242.815872)
		(end 304.675032 -242.652804)
		(width 0.14478)
		(layer "In11.Cu")
		(net "M_F_CPU0_SA_CB<4>")
	)
	(segment
		(start 302.300894 -241.273076)
		(end 302.463962 -241.110008)
		(width 0.14478)
		(layer "In11.Cu")
		(net "M_F_CPU0_SA_CB<4>")
	)
	(segment
		(start 302.463962 -241.110008)
		(end 303.95545 -241.110008)
		(width 0.14478)
		(layer "In11.Cu")
		(net "M_F_CPU0_SA_CB<4>")
	)
	(segment
		(start 300.477936 -241.11966)
		(end 300.631352 -241.273076)
		(width 0.14478)
		(layer "In11.Cu")
		(net "M_F_CPU0_SA_CB<4>")
	)
	(segment
		(start 304.281586 -242.815872)
		(end 304.511964 -242.815872)
		(width 0.14478)
		(layer "In11.Cu")
		(net "M_F_CPU0_SA_CB<4>")
	)
	(segment
		(start 301.187866 -242.687602)
		(end 301.187866 -241.273076)
		(width 0.14478)
		(layer "In11.Cu")
		(net "M_F_CPU0_SA_CB<4>")
	)
	(segment
		(start 307.732684 -242.127532)
		(end 313.385962 -247.78081)
		(width 0.14478)
		(layer "In11.Cu")
		(net "M_F_CPU0_SA_CB<4>")
	)
	(segment
		(start 304.675032 -242.652804)
		(end 304.675032 -241.273076)
		(width 0.14478)
		(layer "In11.Cu")
		(net "M_F_CPU0_SA_CB<4>")
	)
	(segment
		(start 304.118518 -242.652804)
		(end 304.281586 -242.815872)
		(width 0.14478)
		(layer "In11.Cu")
		(net "M_F_CPU0_SA_CB<4>")
	)
	(segment
		(start 302.300894 -242.687602)
		(end 302.300894 -241.273076)
		(width 0.14478)
		(layer "In11.Cu")
		(net "M_F_CPU0_SA_CB<4>")
	)
	(segment
		(start 330.394056 -248.046748)
		(end 330.402438 -248.051574)
		(width 0.0889)
		(layer "In11.Cu")
		(net "M_F_CPU0_SA_CB<4>")
	)
	(segment
		(start 313.385962 -247.78081)
		(end 322.530978 -247.78081)
		(width 0.14478)
		(layer "In11.Cu")
		(net "M_F_CPU0_SA_CB<4>")
	)
	(segment
		(start 301.581312 -241.110008)
		(end 301.74438 -241.273076)
		(width 0.14478)
		(layer "In11.Cu")
		(net "M_F_CPU0_SA_CB<4>")
	)
	(segment
		(start 301.187866 -241.273076)
		(end 301.350934 -241.110008)
		(width 0.14478)
		(layer "In11.Cu")
		(net "M_F_CPU0_SA_CB<4>")
	)
	(segment
		(start 301.350934 -241.110008)
		(end 301.581312 -241.110008)
		(width 0.14478)
		(layer "In11.Cu")
		(net "M_F_CPU0_SA_CB<4>")
	)
	(segment
		(start 270.082772 -241.11966)
		(end 300.477936 -241.11966)
		(width 0.14478)
		(layer "In11.Cu")
		(net "M_F_CPU0_SA_CB<4>")
	)
	(segment
		(start 269.648178 -240.685066)
		(end 270.082772 -241.11966)
		(width 0.14478)
		(layer "In11.Cu")
		(net "M_F_CPU0_SA_CB<4>")
	)
	(segment
		(start 332.307184 -247.989598)
		(end 332.461108 -247.724168)
		(width 0.0889)
		(layer "In11.Cu")
		(net "M_F_CPU0_SA_CB<4>")
	)
	(segment
		(start 301.907448 -242.85067)
		(end 302.137826 -242.85067)
		(width 0.14478)
		(layer "In11.Cu")
		(net "M_F_CPU0_SA_CB<4>")
	)
	(segment
		(start 331.33411 -248.046748)
		(end 331.342492 -248.051574)
		(width 0.0889)
		(layer "In11.Cu")
		(net "M_F_CPU0_SA_CB<4>")
	)
	(segment
		(start 305.068478 -241.110008)
		(end 305.231546 -241.273076)
		(width 0.14478)
		(layer "In11.Cu")
		(net "M_F_CPU0_SA_CB<4>")
	)
	(segment
		(start 304.8381 -241.110008)
		(end 305.068478 -241.110008)
		(width 0.14478)
		(layer "In11.Cu")
		(net "M_F_CPU0_SA_CB<4>")
	)
	(segment
		(start 302.137826 -242.85067)
		(end 302.300894 -242.687602)
		(width 0.14478)
		(layer "In11.Cu")
		(net "M_F_CPU0_SA_CB<4>")
	)
	(segment
		(start 300.631352 -241.273076)
		(end 300.631352 -242.687602)
		(width 0.14478)
		(layer "In11.Cu")
		(net "M_F_CPU0_SA_CB<4>")
	)
	(segment
		(start 332.211172 -248.014998)
		(end 332.307184 -247.989598)
		(width 0.0889)
		(layer "In11.Cu")
		(net "M_F_CPU0_SA_CB<4>")
	)
	(segment
		(start 301.74438 -241.273076)
		(end 301.74438 -242.687602)
		(width 0.14478)
		(layer "In11.Cu")
		(net "M_F_CPU0_SA_CB<4>")
	)
	(segment
		(start 300.79442 -242.85067)
		(end 301.024798 -242.85067)
		(width 0.14478)
		(layer "In11.Cu")
		(net "M_F_CPU0_SA_CB<4>")
	)
	(segment
		(start 305.376326 -242.127532)
		(end 307.732684 -242.127532)
		(width 0.14478)
		(layer "In11.Cu")
		(net "M_F_CPU0_SA_CB<4>")
	)
	(segment
		(start 323.969634 -248.345706)
		(end 323.97446 -248.350532)
		(width 0.0889)
		(layer "In11.Cu")
		(net "M_F_CPU0_SA_CB<4>")
	)
	(segment
		(start 304.675032 -241.273076)
		(end 304.8381 -241.110008)
		(width 0.14478)
		(layer "In11.Cu")
		(net "M_F_CPU0_SA_CB<4>")
	)
	(segment
		(start 305.231546 -241.982752)
		(end 305.376326 -242.127532)
		(width 0.14478)
		(layer "In11.Cu")
		(net "M_F_CPU0_SA_CB<4>")
	)
	(segment
		(start 300.631352 -242.687602)
		(end 300.79442 -242.85067)
		(width 0.14478)
		(layer "In11.Cu")
		(net "M_F_CPU0_SA_CB<4>")
	)
	(segment
		(start 329.819762 -248.051574)
		(end 329.828144 -248.046748)
		(width 0.0889)
		(layer "In11.Cu")
		(net "M_F_CPU0_SA_CB<4>")
	)
	(segment
		(start 304.118518 -241.273076)
		(end 304.118518 -242.652804)
		(width 0.14478)
		(layer "In11.Cu")
		(net "M_F_CPU0_SA_CB<4>")
	)
	(segment
		(start 301.74438 -242.687602)
		(end 301.907448 -242.85067)
		(width 0.14478)
		(layer "In11.Cu")
		(net "M_F_CPU0_SA_CB<4>")
	)
	(segment
		(start 322.530978 -247.78081)
		(end 323.095874 -248.345706)
		(width 0.14478)
		(layer "In11.Cu")
		(net "M_F_CPU0_SA_CB<4>")
	)
	(segment
		(start 326.997568 -248.053606)
		(end 327.009252 -248.046748)
		(width 0.0889)
		(layer "In11.Cu")
		(net "M_F_CPU0_SA_CB<4>")
	)
	(segment
		(start 327.562464 -248.039636)
		(end 327.574402 -248.046494)
		(width 0.0889)
		(layer "In11.Cu")
		(net "M_F_CPU0_SA_CB<4>")
	)
	(segment
		(start 323.095874 -248.345706)
		(end 323.969634 -248.345706)
		(width 0.14478)
		(layer "In11.Cu")
		(net "M_F_CPU0_SA_CB<4>")
	)
	(segment
		(start 325.583296 -248.350532)
		(end 326.026526 -248.061988)
		(width 0.0889)
		(layer "In11.Cu")
		(net "M_F_CPU0_SA_CB<4>")
	)
	(segment
		(start 303.95545 -241.110008)
		(end 304.118518 -241.273076)
		(width 0.14478)
		(layer "In11.Cu")
		(net "M_F_CPU0_SA_CB<4>")
	)
	(segment
		(start 327.574402 -248.046494)
		(end 327.590658 -248.055892)
		(width 0.0889)
		(layer "In11.Cu")
		(net "M_F_CPU0_SA_CB<4>")
	)
	(segment
		(start 305.231546 -241.273076)
		(end 305.231546 -241.982752)
		(width 0.14478)
		(layer "In11.Cu")
		(net "M_F_CPU0_SA_CB<4>")
	)
	(segment
		(start 323.97446 -248.350532)
		(end 325.583296 -248.350532)
		(width 0.0889)
		(layer "In11.Cu")
		(net "M_F_CPU0_SA_CB<4>")
	)
	(arc
		(start 327.009252 -248.046748)
		(mid 327.28493 -247.970618)
		(end 327.562464 -248.039636)
		(width 0.0889)
		(layer "In11.Cu")
		(net "M_F_CPU0_SA_CB<4>")
	)
	(arc
		(start 326.026526 -248.061988)
		(mid 326.328525 -247.96823)
		(end 326.634856 -248.046748)
		(width 0.0889)
		(layer "In11.Cu")
		(net "M_F_CPU0_SA_CB<4>")
	)
	(arc
		(start 328.514202 -248.046748)
		(mid 328.701146 -248.097003)
		(end 328.88809 -248.046748)
		(width 0.0889)
		(layer "In11.Cu")
		(net "M_F_CPU0_SA_CB<4>")
	)
	(arc
		(start 331.342492 -248.051574)
		(mid 331.526 -248.097068)
		(end 331.708252 -248.046748)
		(width 0.0889)
		(layer "In11.Cu")
		(net "M_F_CPU0_SA_CB<4>")
	)
	(arc
		(start 326.634856 -248.046748)
		(mid 326.815314 -248.097192)
		(end 326.997568 -248.053606)
		(width 0.0889)
		(layer "In11.Cu")
		(net "M_F_CPU0_SA_CB<4>")
	)
	(arc
		(start 330.768198 -248.046748)
		(mid 331.051154 -247.970571)
		(end 331.33411 -248.046748)
		(width 0.0889)
		(layer "In11.Cu")
		(net "M_F_CPU0_SA_CB<4>")
	)
	(arc
		(start 327.94829 -248.046748)
		(mid 328.231246 -247.970571)
		(end 328.514202 -248.046748)
		(width 0.0889)
		(layer "In11.Cu")
		(net "M_F_CPU0_SA_CB<4>")
	)
	(arc
		(start 331.708252 -248.046748)
		(mid 331.955965 -247.971528)
		(end 332.211172 -248.014998)
		(width 0.0889)
		(layer "In11.Cu")
		(net "M_F_CPU0_SA_CB<4>")
	)
	(arc
		(start 330.402438 -248.051574)
		(mid 330.585946 -248.097068)
		(end 330.768198 -248.046748)
		(width 0.0889)
		(layer "In11.Cu")
		(net "M_F_CPU0_SA_CB<4>")
	)
	(arc
		(start 328.88809 -248.046748)
		(mid 329.171046 -247.970571)
		(end 329.454002 -248.046748)
		(width 0.0889)
		(layer "In11.Cu")
		(net "M_F_CPU0_SA_CB<4>")
	)
	(arc
		(start 329.454002 -248.046748)
		(mid 329.636253 -248.097098)
		(end 329.819762 -248.051574)
		(width 0.0889)
		(layer "In11.Cu")
		(net "M_F_CPU0_SA_CB<4>")
	)
	(arc
		(start 329.828144 -248.046748)
		(mid 330.1111 -247.970571)
		(end 330.394056 -248.046748)
		(width 0.0889)
		(layer "In11.Cu")
		(net "M_F_CPU0_SA_CB<4>")
	)
	(arc
		(start 327.590658 -248.055892)
		(mid 327.77064 -248.096992)
		(end 327.94829 -248.046748)
		(width 0.0889)
		(layer "In11.Cu")
		(net "M_F_CPU0_SA_CB<4>")
	)
	(segment
		(start 333.868014 -246.370094)
		(end 333.401162 -246.104156)
		(width 0.10668)
		(layer "F.Cu")
		(net "M_F_CPU0_SA_CB<3>")
	)
	(segment
		(start 329.819762 -245.77675)
		(end 329.828144 -245.781576)
		(width 0.0889)
		(layer "In11.Cu")
		(net "M_F_CPU0_SA_CB<3>")
	)
	(segment
		(start 274.677632 -237.700312)
		(end 275.527516 -236.850428)
		(width 0.14478)
		(layer "In11.Cu")
		(net "M_F_CPU0_SA_CB<3>")
	)
	(segment
		(start 323.939154 -245.80723)
		(end 324.005956 -245.874032)
		(width 0.0889)
		(layer "In11.Cu")
		(net "M_F_CPU0_SA_CB<3>")
	)
	(segment
		(start 301.556166 -237.32109)
		(end 305.265328 -237.32109)
		(width 0.14478)
		(layer "In11.Cu")
		(net "M_F_CPU0_SA_CB<3>")
	)
	(segment
		(start 324.005956 -245.874032)
		(end 326.541384 -245.874032)
		(width 0.0889)
		(layer "In11.Cu")
		(net "M_F_CPU0_SA_CB<3>")
	)
	(segment
		(start 289.84194 -237.700312)
		(end 290.691824 -236.850428)
		(width 0.14478)
		(layer "In11.Cu")
		(net "M_F_CPU0_SA_CB<3>")
	)
	(segment
		(start 266.980162 -236.838998)
		(end 267.14323 -236.67593)
		(width 0.14478)
		(layer "In11.Cu")
		(net "M_F_CPU0_SA_CB<3>")
	)
	(segment
		(start 283.158438 -236.850428)
		(end 286.043624 -236.850428)
		(width 0.14478)
		(layer "In11.Cu")
		(net "M_F_CPU0_SA_CB<3>")
	)
	(segment
		(start 315.02223 -245.44147)
		(end 323.573394 -245.44147)
		(width 0.14478)
		(layer "In11.Cu")
		(net "M_F_CPU0_SA_CB<3>")
	)
	(segment
		(start 278.47417 -236.850428)
		(end 279.324054 -237.700312)
		(width 0.14478)
		(layer "In11.Cu")
		(net "M_F_CPU0_SA_CB<3>")
	)
	(segment
		(start 266.817094 -237.710218)
		(end 266.980162 -237.54715)
		(width 0.14478)
		(layer "In11.Cu")
		(net "M_F_CPU0_SA_CB<3>")
	)
	(segment
		(start 326.541384 -245.874032)
		(end 326.63384 -245.781576)
		(width 0.0889)
		(layer "In11.Cu")
		(net "M_F_CPU0_SA_CB<3>")
	)
	(segment
		(start 326.63384 -245.781576)
		(end 326.645524 -245.774718)
		(width 0.0889)
		(layer "In11.Cu")
		(net "M_F_CPU0_SA_CB<3>")
	)
	(segment
		(start 286.043624 -236.850428)
		(end 286.893508 -237.700312)
		(width 0.14478)
		(layer "In11.Cu")
		(net "M_F_CPU0_SA_CB<3>")
	)
	(segment
		(start 265.973306 -237.710218)
		(end 266.817094 -237.710218)
		(width 0.14478)
		(layer "In11.Cu")
		(net "M_F_CPU0_SA_CB<3>")
	)
	(segment
		(start 333.555086 -245.838726)
		(end 333.401162 -246.104156)
		(width 0.0889)
		(layer "In11.Cu")
		(net "M_F_CPU0_SA_CB<3>")
	)
	(segment
		(start 306.44084 -236.86008)
		(end 315.02223 -245.44147)
		(width 0.14478)
		(layer "In11.Cu")
		(net "M_F_CPU0_SA_CB<3>")
	)
	(segment
		(start 290.691824 -236.850428)
		(end 293.54907 -236.850428)
		(width 0.14478)
		(layer "In11.Cu")
		(net "M_F_CPU0_SA_CB<3>")
	)
	(segment
		(start 323.573394 -245.44147)
		(end 323.939154 -245.80723)
		(width 0.14478)
		(layer "In11.Cu")
		(net "M_F_CPU0_SA_CB<3>")
	)
	(segment
		(start 297.339766 -237.700312)
		(end 298.18965 -236.850428)
		(width 0.14478)
		(layer "In11.Cu")
		(net "M_F_CPU0_SA_CB<3>")
	)
	(segment
		(start 282.308554 -237.700312)
		(end 283.158438 -236.850428)
		(width 0.14478)
		(layer "In11.Cu")
		(net "M_F_CPU0_SA_CB<3>")
	)
	(segment
		(start 305.726338 -236.86008)
		(end 306.44084 -236.86008)
		(width 0.14478)
		(layer "In11.Cu")
		(net "M_F_CPU0_SA_CB<3>")
	)
	(segment
		(start 267.536676 -237.54715)
		(end 267.689838 -237.700312)
		(width 0.14478)
		(layer "In11.Cu")
		(net "M_F_CPU0_SA_CB<3>")
	)
	(segment
		(start 330.394056 -245.781576)
		(end 330.402438 -245.77675)
		(width 0.0889)
		(layer "In11.Cu")
		(net "M_F_CPU0_SA_CB<3>")
	)
	(segment
		(start 279.324054 -237.700312)
		(end 282.308554 -237.700312)
		(width 0.14478)
		(layer "In11.Cu")
		(net "M_F_CPU0_SA_CB<3>")
	)
	(segment
		(start 266.980162 -237.54715)
		(end 266.980162 -236.838998)
		(width 0.14478)
		(layer "In11.Cu")
		(net "M_F_CPU0_SA_CB<3>")
	)
	(segment
		(start 301.085504 -236.850428)
		(end 301.556166 -237.32109)
		(width 0.14478)
		(layer "In11.Cu")
		(net "M_F_CPU0_SA_CB<3>")
	)
	(segment
		(start 267.14323 -236.67593)
		(end 267.373608 -236.67593)
		(width 0.14478)
		(layer "In11.Cu")
		(net "M_F_CPU0_SA_CB<3>")
	)
	(segment
		(start 265.54811 -237.285022)
		(end 265.973306 -237.710218)
		(width 0.14478)
		(layer "In11.Cu")
		(net "M_F_CPU0_SA_CB<3>")
	)
	(segment
		(start 293.54907 -236.850428)
		(end 294.398954 -237.700312)
		(width 0.14478)
		(layer "In11.Cu")
		(net "M_F_CPU0_SA_CB<3>")
	)
	(segment
		(start 294.398954 -237.700312)
		(end 297.339766 -237.700312)
		(width 0.14478)
		(layer "In11.Cu")
		(net "M_F_CPU0_SA_CB<3>")
	)
	(segment
		(start 333.532734 -245.755414)
		(end 333.555086 -245.838726)
		(width 0.0889)
		(layer "In11.Cu")
		(net "M_F_CPU0_SA_CB<3>")
	)
	(segment
		(start 327.007728 -245.781576)
		(end 327.018142 -245.787672)
		(width 0.0889)
		(layer "In11.Cu")
		(net "M_F_CPU0_SA_CB<3>")
	)
	(segment
		(start 331.33411 -245.781576)
		(end 331.342492 -245.77675)
		(width 0.0889)
		(layer "In11.Cu")
		(net "M_F_CPU0_SA_CB<3>")
	)
	(segment
		(start 267.689838 -237.700312)
		(end 274.677632 -237.700312)
		(width 0.14478)
		(layer "In11.Cu")
		(net "M_F_CPU0_SA_CB<3>")
	)
	(segment
		(start 286.893508 -237.700312)
		(end 289.84194 -237.700312)
		(width 0.14478)
		(layer "In11.Cu")
		(net "M_F_CPU0_SA_CB<3>")
	)
	(segment
		(start 298.18965 -236.850428)
		(end 301.085504 -236.850428)
		(width 0.14478)
		(layer "In11.Cu")
		(net "M_F_CPU0_SA_CB<3>")
	)
	(segment
		(start 267.536676 -236.838998)
		(end 267.536676 -237.54715)
		(width 0.14478)
		(layer "In11.Cu")
		(net "M_F_CPU0_SA_CB<3>")
	)
	(segment
		(start 267.373608 -236.67593)
		(end 267.536676 -236.838998)
		(width 0.14478)
		(layer "In11.Cu")
		(net "M_F_CPU0_SA_CB<3>")
	)
	(segment
		(start 275.527516 -236.850428)
		(end 278.47417 -236.850428)
		(width 0.14478)
		(layer "In11.Cu")
		(net "M_F_CPU0_SA_CB<3>")
	)
	(segment
		(start 305.265328 -237.32109)
		(end 305.726338 -236.86008)
		(width 0.14478)
		(layer "In11.Cu")
		(net "M_F_CPU0_SA_CB<3>")
	)
	(arc
		(start 332.648052 -245.781576)
		(mid 332.931008 -245.857753)
		(end 333.213964 -245.781576)
		(width 0.0889)
		(layer "In11.Cu")
		(net "M_F_CPU0_SA_CB<3>")
	)
	(arc
		(start 332.274164 -245.781576)
		(mid 332.461108 -245.731321)
		(end 332.648052 -245.781576)
		(width 0.0889)
		(layer "In11.Cu")
		(net "M_F_CPU0_SA_CB<3>")
	)
	(arc
		(start 327.94829 -245.781576)
		(mid 328.231246 -245.857753)
		(end 328.514202 -245.781576)
		(width 0.0889)
		(layer "In11.Cu")
		(net "M_F_CPU0_SA_CB<3>")
	)
	(arc
		(start 328.88809 -245.781576)
		(mid 329.171046 -245.857753)
		(end 329.454002 -245.781576)
		(width 0.0889)
		(layer "In11.Cu")
		(net "M_F_CPU0_SA_CB<3>")
	)
	(arc
		(start 331.708252 -245.781576)
		(mid 331.991208 -245.857753)
		(end 332.274164 -245.781576)
		(width 0.0889)
		(layer "In11.Cu")
		(net "M_F_CPU0_SA_CB<3>")
	)
	(arc
		(start 333.213964 -245.781576)
		(mid 333.370402 -245.732605)
		(end 333.532734 -245.755414)
		(width 0.0889)
		(layer "In11.Cu")
		(net "M_F_CPU0_SA_CB<3>")
	)
	(arc
		(start 331.342492 -245.77675)
		(mid 331.526 -245.731256)
		(end 331.708252 -245.781576)
		(width 0.0889)
		(layer "In11.Cu")
		(net "M_F_CPU0_SA_CB<3>")
	)
	(arc
		(start 330.402438 -245.77675)
		(mid 330.585946 -245.731256)
		(end 330.768198 -245.781576)
		(width 0.0889)
		(layer "In11.Cu")
		(net "M_F_CPU0_SA_CB<3>")
	)
	(arc
		(start 329.454002 -245.781576)
		(mid 329.636253 -245.731226)
		(end 329.819762 -245.77675)
		(width 0.0889)
		(layer "In11.Cu")
		(net "M_F_CPU0_SA_CB<3>")
	)
	(arc
		(start 329.828144 -245.781576)
		(mid 330.1111 -245.857753)
		(end 330.394056 -245.781576)
		(width 0.0889)
		(layer "In11.Cu")
		(net "M_F_CPU0_SA_CB<3>")
	)
	(arc
		(start 327.573894 -245.781576)
		(mid 327.761092 -245.731194)
		(end 327.94829 -245.781576)
		(width 0.0889)
		(layer "In11.Cu")
		(net "M_F_CPU0_SA_CB<3>")
	)
	(arc
		(start 328.514202 -245.781576)
		(mid 328.701146 -245.731321)
		(end 328.88809 -245.781576)
		(width 0.0889)
		(layer "In11.Cu")
		(net "M_F_CPU0_SA_CB<3>")
	)
	(arc
		(start 330.768198 -245.781576)
		(mid 331.051154 -245.857753)
		(end 331.33411 -245.781576)
		(width 0.0889)
		(layer "In11.Cu")
		(net "M_F_CPU0_SA_CB<3>")
	)
	(arc
		(start 327.018142 -245.787672)
		(mid 327.296828 -245.857892)
		(end 327.573894 -245.781576)
		(width 0.0889)
		(layer "In11.Cu")
		(net "M_F_CPU0_SA_CB<3>")
	)
	(arc
		(start 326.645524 -245.774718)
		(mid 326.827525 -245.731185)
		(end 327.007728 -245.781576)
		(width 0.0889)
		(layer "In11.Cu")
		(net "M_F_CPU0_SA_CB<3>")
	)
	(segment
		(start 332.45806 -245.560088)
		(end 331.991208 -245.29415)
		(width 0.10668)
		(layer "F.Cu")
		(net "M_F_CPU0_SA_CB<2>")
	)
	(segment
		(start 290.682172 -235.160058)
		(end 293.558722 -235.160058)
		(width 0.14478)
		(layer "In11.Cu")
		(net "M_F_CPU0_SA_CB<2>")
	)
	(segment
		(start 286.903414 -236.010196)
		(end 289.832034 -236.010196)
		(width 0.14478)
		(layer "In11.Cu")
		(net "M_F_CPU0_SA_CB<2>")
	)
	(segment
		(start 266.628118 -236.010196)
		(end 266.791186 -235.847128)
		(width 0.14478)
		(layer "In11.Cu")
		(net "M_F_CPU0_SA_CB<2>")
	)
	(segment
		(start 283.148786 -235.160058)
		(end 286.053276 -235.160058)
		(width 0.14478)
		(layer "In11.Cu")
		(net "M_F_CPU0_SA_CB<2>")
	)
	(segment
		(start 267.184632 -235.23321)
		(end 267.3477 -235.396278)
		(width 0.14478)
		(layer "In11.Cu")
		(net "M_F_CPU0_SA_CB<2>")
	)
	(segment
		(start 282.298648 -236.010196)
		(end 283.148786 -235.160058)
		(width 0.14478)
		(layer "In11.Cu")
		(net "M_F_CPU0_SA_CB<2>")
	)
	(segment
		(start 266.791186 -235.847128)
		(end 266.791186 -235.396278)
		(width 0.14478)
		(layer "In11.Cu")
		(net "M_F_CPU0_SA_CB<2>")
	)
	(segment
		(start 315.399166 -244.53215)
		(end 323.873114 -244.53215)
		(width 0.14478)
		(layer "In11.Cu")
		(net "M_F_CPU0_SA_CB<2>")
	)
	(segment
		(start 328.984102 -244.97157)
		(end 328.992484 -244.966744)
		(width 0.0889)
		(layer "In11.Cu")
		(net "M_F_CPU0_SA_CB<2>")
	)
	(segment
		(start 279.33396 -236.010196)
		(end 282.298648 -236.010196)
		(width 0.14478)
		(layer "In11.Cu")
		(net "M_F_CPU0_SA_CB<2>")
	)
	(segment
		(start 274.667726 -236.010196)
		(end 275.517864 -235.160058)
		(width 0.14478)
		(layer "In11.Cu")
		(net "M_F_CPU0_SA_CB<2>")
	)
	(segment
		(start 268.460728 -235.847128)
		(end 268.623796 -236.010196)
		(width 0.14478)
		(layer "In11.Cu")
		(net "M_F_CPU0_SA_CB<2>")
	)
	(segment
		(start 278.483822 -235.160058)
		(end 279.33396 -236.010196)
		(width 0.14478)
		(layer "In11.Cu")
		(net "M_F_CPU0_SA_CB<2>")
	)
	(segment
		(start 331.229716 -244.966744)
		(end 331.238098 -244.97157)
		(width 0.0889)
		(layer "In11.Cu")
		(net "M_F_CPU0_SA_CB<2>")
	)
	(segment
		(start 275.517864 -235.160058)
		(end 278.483822 -235.160058)
		(width 0.14478)
		(layer "In11.Cu")
		(net "M_F_CPU0_SA_CB<2>")
	)
	(segment
		(start 326.152764 -244.978682)
		(end 326.164702 -244.971824)
		(width 0.0889)
		(layer "In11.Cu")
		(net "M_F_CPU0_SA_CB<2>")
	)
	(segment
		(start 267.904214 -235.847128)
		(end 267.904214 -235.396278)
		(width 0.14478)
		(layer "In11.Cu")
		(net "M_F_CPU0_SA_CB<2>")
	)
	(segment
		(start 305.136804 -235.749592)
		(end 306.616608 -235.749592)
		(width 0.14478)
		(layer "In11.Cu")
		(net "M_F_CPU0_SA_CB<2>")
	)
	(segment
		(start 266.791186 -235.396278)
		(end 266.954254 -235.23321)
		(width 0.14478)
		(layer "In11.Cu")
		(net "M_F_CPU0_SA_CB<2>")
	)
	(segment
		(start 301.095156 -235.160058)
		(end 301.945294 -236.010196)
		(width 0.14478)
		(layer "In11.Cu")
		(net "M_F_CPU0_SA_CB<2>")
	)
	(segment
		(start 332.145132 -245.02872)
		(end 331.991208 -245.29415)
		(width 0.0889)
		(layer "In11.Cu")
		(net "M_F_CPU0_SA_CB<2>")
	)
	(segment
		(start 323.873114 -244.53215)
		(end 324.015354 -244.53215)
		(width 0.0889)
		(layer "In11.Cu")
		(net "M_F_CPU0_SA_CB<2>")
	)
	(segment
		(start 327.08723 -244.982238)
		(end 327.105264 -244.97157)
		(width 0.0889)
		(layer "In11.Cu")
		(net "M_F_CPU0_SA_CB<2>")
	)
	(segment
		(start 266.954254 -235.23321)
		(end 267.184632 -235.23321)
		(width 0.14478)
		(layer "In11.Cu")
		(net "M_F_CPU0_SA_CB<2>")
	)
	(segment
		(start 326.164702 -244.971824)
		(end 326.184768 -244.960394)
		(width 0.0889)
		(layer "In11.Cu")
		(net "M_F_CPU0_SA_CB<2>")
	)
	(segment
		(start 267.741146 -236.010196)
		(end 267.904214 -235.847128)
		(width 0.14478)
		(layer "In11.Cu")
		(net "M_F_CPU0_SA_CB<2>")
	)
	(segment
		(start 265.54811 -235.585)
		(end 265.973306 -236.010196)
		(width 0.14478)
		(layer "In11.Cu")
		(net "M_F_CPU0_SA_CB<2>")
	)
	(segment
		(start 324.716394 -245.23319)
		(end 325.107554 -245.23319)
		(width 0.0889)
		(layer "In11.Cu")
		(net "M_F_CPU0_SA_CB<2>")
	)
	(segment
		(start 268.623796 -236.010196)
		(end 274.667726 -236.010196)
		(width 0.14478)
		(layer "In11.Cu")
		(net "M_F_CPU0_SA_CB<2>")
	)
	(segment
		(start 293.558722 -235.160058)
		(end 294.40886 -236.010196)
		(width 0.14478)
		(layer "In11.Cu")
		(net "M_F_CPU0_SA_CB<2>")
	)
	(segment
		(start 286.053276 -235.160058)
		(end 286.903414 -236.010196)
		(width 0.14478)
		(layer "In11.Cu")
		(net "M_F_CPU0_SA_CB<2>")
	)
	(segment
		(start 268.460728 -235.396278)
		(end 268.460728 -235.847128)
		(width 0.14478)
		(layer "In11.Cu")
		(net "M_F_CPU0_SA_CB<2>")
	)
	(segment
		(start 267.3477 -235.847128)
		(end 267.510768 -236.010196)
		(width 0.14478)
		(layer "In11.Cu")
		(net "M_F_CPU0_SA_CB<2>")
	)
	(segment
		(start 267.904214 -235.396278)
		(end 268.067282 -235.23321)
		(width 0.14478)
		(layer "In11.Cu")
		(net "M_F_CPU0_SA_CB<2>")
	)
	(segment
		(start 306.616608 -235.749592)
		(end 315.399166 -244.53215)
		(width 0.14478)
		(layer "In11.Cu")
		(net "M_F_CPU0_SA_CB<2>")
	)
	(segment
		(start 267.510768 -236.010196)
		(end 267.741146 -236.010196)
		(width 0.14478)
		(layer "In11.Cu")
		(net "M_F_CPU0_SA_CB<2>")
	)
	(segment
		(start 328.409808 -244.966744)
		(end 328.41819 -244.97157)
		(width 0.0889)
		(layer "In11.Cu")
		(net "M_F_CPU0_SA_CB<2>")
	)
	(segment
		(start 327.478898 -244.971824)
		(end 327.490836 -244.978682)
		(width 0.0889)
		(layer "In11.Cu")
		(net "M_F_CPU0_SA_CB<2>")
	)
	(segment
		(start 301.945294 -236.010196)
		(end 304.8762 -236.010196)
		(width 0.14478)
		(layer "In11.Cu")
		(net "M_F_CPU0_SA_CB<2>")
	)
	(segment
		(start 325.107554 -245.23319)
		(end 325.292974 -245.04777)
		(width 0.0889)
		(layer "In11.Cu")
		(net "M_F_CPU0_SA_CB<2>")
	)
	(segment
		(start 289.832034 -236.010196)
		(end 290.682172 -235.160058)
		(width 0.14478)
		(layer "In11.Cu")
		(net "M_F_CPU0_SA_CB<2>")
	)
	(segment
		(start 267.3477 -235.396278)
		(end 267.3477 -235.847128)
		(width 0.14478)
		(layer "In11.Cu")
		(net "M_F_CPU0_SA_CB<2>")
	)
	(segment
		(start 265.973306 -236.010196)
		(end 266.628118 -236.010196)
		(width 0.14478)
		(layer "In11.Cu")
		(net "M_F_CPU0_SA_CB<2>")
	)
	(segment
		(start 268.29766 -235.23321)
		(end 268.460728 -235.396278)
		(width 0.14478)
		(layer "In11.Cu")
		(net "M_F_CPU0_SA_CB<2>")
	)
	(segment
		(start 304.8762 -236.010196)
		(end 305.136804 -235.749592)
		(width 0.14478)
		(layer "In11.Cu")
		(net "M_F_CPU0_SA_CB<2>")
	)
	(segment
		(start 325.292974 -245.04777)
		(end 325.879968 -245.04777)
		(width 0.0889)
		(layer "In11.Cu")
		(net "M_F_CPU0_SA_CB<2>")
	)
	(segment
		(start 332.12278 -244.945408)
		(end 332.145132 -245.02872)
		(width 0.0889)
		(layer "In11.Cu")
		(net "M_F_CPU0_SA_CB<2>")
	)
	(segment
		(start 324.015354 -244.53215)
		(end 324.716394 -245.23319)
		(width 0.0889)
		(layer "In11.Cu")
		(net "M_F_CPU0_SA_CB<2>")
	)
	(segment
		(start 268.067282 -235.23321)
		(end 268.29766 -235.23321)
		(width 0.14478)
		(layer "In11.Cu")
		(net "M_F_CPU0_SA_CB<2>")
	)
	(segment
		(start 294.40886 -236.010196)
		(end 297.32986 -236.010196)
		(width 0.14478)
		(layer "In11.Cu")
		(net "M_F_CPU0_SA_CB<2>")
	)
	(segment
		(start 298.179998 -235.160058)
		(end 301.095156 -235.160058)
		(width 0.14478)
		(layer "In11.Cu")
		(net "M_F_CPU0_SA_CB<2>")
	)
	(segment
		(start 327.465182 -244.96395)
		(end 327.478898 -244.971824)
		(width 0.0889)
		(layer "In11.Cu")
		(net "M_F_CPU0_SA_CB<2>")
	)
	(segment
		(start 297.32986 -236.010196)
		(end 298.179998 -235.160058)
		(width 0.14478)
		(layer "In11.Cu")
		(net "M_F_CPU0_SA_CB<2>")
	)
	(arc
		(start 326.184768 -244.960394)
		(mid 326.3631 -244.921297)
		(end 326.53859 -244.97157)
		(width 0.0889)
		(layer "In11.Cu")
		(net "M_F_CPU0_SA_CB<2>")
	)
	(arc
		(start 328.044048 -244.97157)
		(mid 328.226299 -244.92122)
		(end 328.409808 -244.966744)
		(width 0.0889)
		(layer "In11.Cu")
		(net "M_F_CPU0_SA_CB<2>")
	)
	(arc
		(start 326.53859 -244.97157)
		(mid 326.811534 -245.04815)
		(end 327.08723 -244.982238)
		(width 0.0889)
		(layer "In11.Cu")
		(net "M_F_CPU0_SA_CB<2>")
	)
	(arc
		(start 329.358244 -244.97157)
		(mid 329.6412 -245.047747)
		(end 329.924156 -244.97157)
		(width 0.0889)
		(layer "In11.Cu")
		(net "M_F_CPU0_SA_CB<2>")
	)
	(arc
		(start 327.490836 -244.978682)
		(mid 327.76837 -245.047663)
		(end 328.044048 -244.97157)
		(width 0.0889)
		(layer "In11.Cu")
		(net "M_F_CPU0_SA_CB<2>")
	)
	(arc
		(start 328.992484 -244.966744)
		(mid 329.175992 -244.92125)
		(end 329.358244 -244.97157)
		(width 0.0889)
		(layer "In11.Cu")
		(net "M_F_CPU0_SA_CB<2>")
	)
	(arc
		(start 331.80401 -244.97157)
		(mid 331.960448 -244.922599)
		(end 332.12278 -244.945408)
		(width 0.0889)
		(layer "In11.Cu")
		(net "M_F_CPU0_SA_CB<2>")
	)
	(arc
		(start 328.41819 -244.97157)
		(mid 328.701146 -245.047747)
		(end 328.984102 -244.97157)
		(width 0.0889)
		(layer "In11.Cu")
		(net "M_F_CPU0_SA_CB<2>")
	)
	(arc
		(start 330.863956 -244.97157)
		(mid 331.046207 -244.92122)
		(end 331.229716 -244.966744)
		(width 0.0889)
		(layer "In11.Cu")
		(net "M_F_CPU0_SA_CB<2>")
	)
	(arc
		(start 331.238098 -244.97157)
		(mid 331.521054 -245.047747)
		(end 331.80401 -244.97157)
		(width 0.0889)
		(layer "In11.Cu")
		(net "M_F_CPU0_SA_CB<2>")
	)
	(arc
		(start 329.924156 -244.97157)
		(mid 330.1111 -244.921315)
		(end 330.298044 -244.97157)
		(width 0.0889)
		(layer "In11.Cu")
		(net "M_F_CPU0_SA_CB<2>")
	)
	(arc
		(start 325.879968 -245.04777)
		(mid 326.020736 -245.030497)
		(end 326.152764 -244.978682)
		(width 0.0889)
		(layer "In11.Cu")
		(net "M_F_CPU0_SA_CB<2>")
	)
	(arc
		(start 330.298044 -244.97157)
		(mid 330.581 -245.047747)
		(end 330.863956 -244.97157)
		(width 0.0889)
		(layer "In11.Cu")
		(net "M_F_CPU0_SA_CB<2>")
	)
	(arc
		(start 327.105264 -244.97157)
		(mid 327.284251 -244.9214)
		(end 327.465182 -244.96395)
		(width 0.0889)
		(layer "In11.Cu")
		(net "M_F_CPU0_SA_CB<2>")
	)
	(segment
		(start 334.337914 -245.560088)
		(end 333.871062 -245.29415)
		(width 0.10668)
		(layer "F.Cu")
		(net "M_F_CPU0_SA_CB<1>")
	)
	(segment
		(start 296.644822 -237.24997)
		(end 296.80789 -237.086902)
		(width 0.14478)
		(layer "In11.Cu")
		(net "M_F_CPU0_SA_CB<1>")
	)
	(segment
		(start 272.029174 -237.240572)
		(end 272.173954 -237.095792)
		(width 0.14478)
		(layer "In11.Cu")
		(net "M_F_CPU0_SA_CB<1>")
	)
	(segment
		(start 293.507922 -236.010196)
		(end 294.357806 -236.86008)
		(width 0.14478)
		(layer "In11.Cu")
		(net "M_F_CPU0_SA_CB<1>")
	)
	(segment
		(start 289.362388 -237.086902)
		(end 289.362388 -237.023148)
		(width 0.14478)
		(layer "In11.Cu")
		(net "M_F_CPU0_SA_CB<1>")
	)
	(segment
		(start 288.805874 -237.023148)
		(end 288.805874 -237.086902)
		(width 0.14478)
		(layer "In11.Cu")
		(net "M_F_CPU0_SA_CB<1>")
	)
	(segment
		(start 281.276552 -237.086902)
		(end 281.43962 -237.24997)
		(width 0.14478)
		(layer "In11.Cu")
		(net "M_F_CPU0_SA_CB<1>")
	)
	(segment
		(start 331.229716 -245.621556)
		(end 331.238098 -245.61673)
		(width 0.0889)
		(layer "In11.Cu")
		(net "M_F_CPU0_SA_CB<1>")
	)
	(segment
		(start 281.276552 -237.023148)
		(end 281.276552 -237.086902)
		(width 0.14478)
		(layer "In11.Cu")
		(net "M_F_CPU0_SA_CB<1>")
	)
	(segment
		(start 298.55287 -236.010196)
		(end 298.715938 -236.173264)
		(width 0.14478)
		(layer "In11.Cu")
		(net "M_F_CPU0_SA_CB<1>")
	)
	(segment
		(start 333.621126 -245.58498)
		(end 333.717138 -245.55958)
		(width 0.0889)
		(layer "In11.Cu")
		(net "M_F_CPU0_SA_CB<1>")
	)
	(segment
		(start 326.467216 -245.658132)
		(end 326.548242 -245.610634)
		(width 0.0889)
		(layer "In11.Cu")
		(net "M_F_CPU0_SA_CB<1>")
	)
	(segment
		(start 291.144452 -236.238542)
		(end 291.303202 -236.397292)
		(width 0.14478)
		(layer "In11.Cu")
		(net "M_F_CPU0_SA_CB<1>")
	)
	(segment
		(start 301.90186 -236.86008)
		(end 303.699926 -236.86008)
		(width 0.14478)
		(layer "In11.Cu")
		(net "M_F_CPU0_SA_CB<1>")
	)
	(segment
		(start 304.419508 -236.697012)
		(end 304.582576 -236.86008)
		(width 0.14478)
		(layer "In11.Cu")
		(net "M_F_CPU0_SA_CB<1>")
	)
	(segment
		(start 269.648178 -236.435138)
		(end 270.07312 -236.86008)
		(width 0.14478)
		(layer "In11.Cu")
		(net "M_F_CPU0_SA_CB<1>")
	)
	(segment
		(start 285.892748 -236.010196)
		(end 286.742632 -236.86008)
		(width 0.14478)
		(layer "In11.Cu")
		(net "M_F_CPU0_SA_CB<1>")
	)
	(segment
		(start 273.916902 -236.86008)
		(end 274.203414 -237.146592)
		(width 0.14478)
		(layer "In11.Cu")
		(net "M_F_CPU0_SA_CB<1>")
	)
	(segment
		(start 272.318734 -236.86008)
		(end 273.916902 -236.86008)
		(width 0.14478)
		(layer "In11.Cu")
		(net "M_F_CPU0_SA_CB<1>")
	)
	(segment
		(start 271.47774 -236.86008)
		(end 271.62252 -237.00486)
		(width 0.14478)
		(layer "In11.Cu")
		(net "M_F_CPU0_SA_CB<1>")
	)
	(segment
		(start 296.80789 -237.023148)
		(end 296.970958 -236.86008)
		(width 0.14478)
		(layer "In11.Cu")
		(net "M_F_CPU0_SA_CB<1>")
	)
	(segment
		(start 283.594302 -236.173264)
		(end 283.594302 -236.233462)
		(width 0.14478)
		(layer "In11.Cu")
		(net "M_F_CPU0_SA_CB<1>")
	)
	(segment
		(start 272.173954 -237.095792)
		(end 272.173954 -237.00486)
		(width 0.14478)
		(layer "In11.Cu")
		(net "M_F_CPU0_SA_CB<1>")
	)
	(segment
		(start 291.303202 -236.397292)
		(end 291.542216 -236.397292)
		(width 0.14478)
		(layer "In11.Cu")
		(net "M_F_CPU0_SA_CB<1>")
	)
	(segment
		(start 291.864034 -236.010196)
		(end 293.507922 -236.010196)
		(width 0.14478)
		(layer "In11.Cu")
		(net "M_F_CPU0_SA_CB<1>")
	)
	(segment
		(start 304.25644 -236.46765)
		(end 304.419508 -236.630718)
		(width 0.14478)
		(layer "In11.Cu")
		(net "M_F_CPU0_SA_CB<1>")
	)
	(segment
		(start 289.362388 -237.023148)
		(end 289.525456 -236.86008)
		(width 0.14478)
		(layer "In11.Cu")
		(net "M_F_CPU0_SA_CB<1>")
	)
	(segment
		(start 281.996134 -236.86008)
		(end 282.323286 -236.86008)
		(width 0.14478)
		(layer "In11.Cu")
		(net "M_F_CPU0_SA_CB<1>")
	)
	(segment
		(start 284.150816 -236.233462)
		(end 284.150816 -236.173264)
		(width 0.14478)
		(layer "In11.Cu")
		(net "M_F_CPU0_SA_CB<1>")
	)
	(segment
		(start 276.08276 -236.233462)
		(end 276.245828 -236.39653)
		(width 0.14478)
		(layer "In11.Cu")
		(net "M_F_CPU0_SA_CB<1>")
	)
	(segment
		(start 304.894742 -236.86008)
		(end 305.43119 -236.323632)
		(width 0.14478)
		(layer "In11.Cu")
		(net "M_F_CPU0_SA_CB<1>")
	)
	(segment
		(start 291.700966 -236.238542)
		(end 291.700966 -236.173264)
		(width 0.14478)
		(layer "In11.Cu")
		(net "M_F_CPU0_SA_CB<1>")
	)
	(segment
		(start 284.150816 -236.173264)
		(end 284.313884 -236.010196)
		(width 0.14478)
		(layer "In11.Cu")
		(net "M_F_CPU0_SA_CB<1>")
	)
	(segment
		(start 283.75737 -236.39653)
		(end 283.987748 -236.39653)
		(width 0.14478)
		(layer "In11.Cu")
		(net "M_F_CPU0_SA_CB<1>")
	)
	(segment
		(start 296.970958 -236.86008)
		(end 297.389042 -236.86008)
		(width 0.14478)
		(layer "In11.Cu")
		(net "M_F_CPU0_SA_CB<1>")
	)
	(segment
		(start 276.639274 -236.173264)
		(end 276.802342 -236.010196)
		(width 0.14478)
		(layer "In11.Cu")
		(net "M_F_CPU0_SA_CB<1>")
	)
	(segment
		(start 276.245828 -236.39653)
		(end 276.476206 -236.39653)
		(width 0.14478)
		(layer "In11.Cu")
		(net "M_F_CPU0_SA_CB<1>")
	)
	(segment
		(start 288.968942 -237.24997)
		(end 289.19932 -237.24997)
		(width 0.14478)
		(layer "In11.Cu")
		(net "M_F_CPU0_SA_CB<1>")
	)
	(segment
		(start 315.210698 -244.98681)
		(end 323.779134 -244.98681)
		(width 0.14478)
		(layer "In11.Cu")
		(net "M_F_CPU0_SA_CB<1>")
	)
	(segment
		(start 301.051976 -236.010196)
		(end 301.90186 -236.86008)
		(width 0.14478)
		(layer "In11.Cu")
		(net "M_F_CPU0_SA_CB<1>")
	)
	(segment
		(start 299.43552 -236.010196)
		(end 301.051976 -236.010196)
		(width 0.14478)
		(layer "In11.Cu")
		(net "M_F_CPU0_SA_CB<1>")
	)
	(segment
		(start 281.43962 -237.24997)
		(end 281.669998 -237.24997)
		(width 0.14478)
		(layer "In11.Cu")
		(net "M_F_CPU0_SA_CB<1>")
	)
	(segment
		(start 290.981384 -236.010196)
		(end 291.144452 -236.173264)
		(width 0.14478)
		(layer "In11.Cu")
		(net "M_F_CPU0_SA_CB<1>")
	)
	(segment
		(start 271.215866 -236.86008)
		(end 271.47774 -236.86008)
		(width 0.14478)
		(layer "In11.Cu")
		(net "M_F_CPU0_SA_CB<1>")
	)
	(segment
		(start 281.669998 -237.24997)
		(end 281.833066 -237.086902)
		(width 0.14478)
		(layer "In11.Cu")
		(net "M_F_CPU0_SA_CB<1>")
	)
	(segment
		(start 332.744064 -245.61673)
		(end 332.752446 -245.621556)
		(width 0.0889)
		(layer "In11.Cu")
		(net "M_F_CPU0_SA_CB<1>")
	)
	(segment
		(start 270.664432 -237.240572)
		(end 270.926306 -237.240572)
		(width 0.14478)
		(layer "In11.Cu")
		(net "M_F_CPU0_SA_CB<1>")
	)
	(segment
		(start 296.088308 -236.86008)
		(end 296.251376 -237.023148)
		(width 0.14478)
		(layer "In11.Cu")
		(net "M_F_CPU0_SA_CB<1>")
	)
	(segment
		(start 270.926306 -237.240572)
		(end 271.071086 -237.095792)
		(width 0.14478)
		(layer "In11.Cu")
		(net "M_F_CPU0_SA_CB<1>")
	)
	(segment
		(start 298.879006 -236.39653)
		(end 299.109384 -236.39653)
		(width 0.14478)
		(layer "In11.Cu")
		(net "M_F_CPU0_SA_CB<1>")
	)
	(segment
		(start 291.542216 -236.397292)
		(end 291.700966 -236.238542)
		(width 0.14478)
		(layer "In11.Cu")
		(net "M_F_CPU0_SA_CB<1>")
	)
	(segment
		(start 281.833066 -237.023148)
		(end 281.996134 -236.86008)
		(width 0.14478)
		(layer "In11.Cu")
		(net "M_F_CPU0_SA_CB<1>")
	)
	(segment
		(start 326.24014 -245.658132)
		(end 326.467216 -245.658132)
		(width 0.0889)
		(layer "In11.Cu")
		(net "M_F_CPU0_SA_CB<1>")
	)
	(segment
		(start 296.251376 -237.023148)
		(end 296.251376 -237.086902)
		(width 0.14478)
		(layer "In11.Cu")
		(net "M_F_CPU0_SA_CB<1>")
	)
	(segment
		(start 272.173954 -237.00486)
		(end 272.318734 -236.86008)
		(width 0.14478)
		(layer "In11.Cu")
		(net "M_F_CPU0_SA_CB<1>")
	)
	(segment
		(start 276.639274 -236.233462)
		(end 276.639274 -236.173264)
		(width 0.14478)
		(layer "In11.Cu")
		(net "M_F_CPU0_SA_CB<1>")
	)
	(segment
		(start 333.717138 -245.55958)
		(end 333.871062 -245.29415)
		(width 0.0889)
		(layer "In11.Cu")
		(net "M_F_CPU0_SA_CB<1>")
	)
	(segment
		(start 270.07312 -236.86008)
		(end 270.374872 -236.86008)
		(width 0.14478)
		(layer "In11.Cu")
		(net "M_F_CPU0_SA_CB<1>")
	)
	(segment
		(start 271.7673 -237.240572)
		(end 272.029174 -237.240572)
		(width 0.14478)
		(layer "In11.Cu")
		(net "M_F_CPU0_SA_CB<1>")
	)
	(segment
		(start 270.519652 -237.095792)
		(end 270.664432 -237.240572)
		(width 0.14478)
		(layer "In11.Cu")
		(net "M_F_CPU0_SA_CB<1>")
	)
	(segment
		(start 275.604732 -236.010196)
		(end 275.919692 -236.010196)
		(width 0.14478)
		(layer "In11.Cu")
		(net "M_F_CPU0_SA_CB<1>")
	)
	(segment
		(start 281.113484 -236.86008)
		(end 281.276552 -237.023148)
		(width 0.14478)
		(layer "In11.Cu")
		(net "M_F_CPU0_SA_CB<1>")
	)
	(segment
		(start 298.715938 -236.233462)
		(end 298.879006 -236.39653)
		(width 0.14478)
		(layer "In11.Cu")
		(net "M_F_CPU0_SA_CB<1>")
	)
	(segment
		(start 299.272452 -236.233462)
		(end 299.272452 -236.173264)
		(width 0.14478)
		(layer "In11.Cu")
		(net "M_F_CPU0_SA_CB<1>")
	)
	(segment
		(start 271.62252 -237.095792)
		(end 271.7673 -237.240572)
		(width 0.14478)
		(layer "In11.Cu")
		(net "M_F_CPU0_SA_CB<1>")
	)
	(segment
		(start 323.979794 -245.193058)
		(end 324.403466 -245.61673)
		(width 0.0889)
		(layer "In11.Cu")
		(net "M_F_CPU0_SA_CB<1>")
	)
	(segment
		(start 332.16977 -245.621556)
		(end 332.178152 -245.61673)
		(width 0.0889)
		(layer "In11.Cu")
		(net "M_F_CPU0_SA_CB<1>")
	)
	(segment
		(start 323.779134 -244.98681)
		(end 323.979794 -245.18747)
		(width 0.14478)
		(layer "In11.Cu")
		(net "M_F_CPU0_SA_CB<1>")
	)
	(segment
		(start 283.17317 -236.010196)
		(end 283.431234 -236.010196)
		(width 0.14478)
		(layer "In11.Cu")
		(net "M_F_CPU0_SA_CB<1>")
	)
	(segment
		(start 279.260808 -236.86008)
		(end 281.113484 -236.86008)
		(width 0.14478)
		(layer "In11.Cu")
		(net "M_F_CPU0_SA_CB<1>")
	)
	(segment
		(start 276.08276 -236.173264)
		(end 276.08276 -236.233462)
		(width 0.14478)
		(layer "In11.Cu")
		(net "M_F_CPU0_SA_CB<1>")
	)
	(segment
		(start 298.238926 -236.010196)
		(end 298.55287 -236.010196)
		(width 0.14478)
		(layer "In11.Cu")
		(net "M_F_CPU0_SA_CB<1>")
	)
	(segment
		(start 323.979794 -245.18747)
		(end 323.979794 -245.193058)
		(width 0.0889)
		(layer "In11.Cu")
		(net "M_F_CPU0_SA_CB<1>")
	)
	(segment
		(start 289.19932 -237.24997)
		(end 289.362388 -237.086902)
		(width 0.14478)
		(layer "In11.Cu")
		(net "M_F_CPU0_SA_CB<1>")
	)
	(segment
		(start 289.883088 -236.86008)
		(end 290.732972 -236.010196)
		(width 0.14478)
		(layer "In11.Cu")
		(net "M_F_CPU0_SA_CB<1>")
	)
	(segment
		(start 299.109384 -236.39653)
		(end 299.272452 -236.233462)
		(width 0.14478)
		(layer "In11.Cu")
		(net "M_F_CPU0_SA_CB<1>")
	)
	(segment
		(start 274.203414 -237.146592)
		(end 274.468336 -237.146592)
		(width 0.14478)
		(layer "In11.Cu")
		(net "M_F_CPU0_SA_CB<1>")
	)
	(segment
		(start 328.984102 -245.61673)
		(end 328.992484 -245.621556)
		(width 0.0889)
		(layer "In11.Cu")
		(net "M_F_CPU0_SA_CB<1>")
	)
	(segment
		(start 294.357806 -236.86008)
		(end 296.088308 -236.86008)
		(width 0.14478)
		(layer "In11.Cu")
		(net "M_F_CPU0_SA_CB<1>")
	)
	(segment
		(start 275.919692 -236.010196)
		(end 276.08276 -236.173264)
		(width 0.14478)
		(layer "In11.Cu")
		(net "M_F_CPU0_SA_CB<1>")
	)
	(segment
		(start 296.80789 -237.086902)
		(end 296.80789 -237.023148)
		(width 0.14478)
		(layer "In11.Cu")
		(net "M_F_CPU0_SA_CB<1>")
	)
	(segment
		(start 289.525456 -236.86008)
		(end 289.883088 -236.86008)
		(width 0.14478)
		(layer "In11.Cu")
		(net "M_F_CPU0_SA_CB<1>")
	)
	(segment
		(start 304.582576 -236.86008)
		(end 304.894742 -236.86008)
		(width 0.14478)
		(layer "In11.Cu")
		(net "M_F_CPU0_SA_CB<1>")
	)
	(segment
		(start 286.742632 -236.86008)
		(end 288.642806 -236.86008)
		(width 0.14478)
		(layer "In11.Cu")
		(net "M_F_CPU0_SA_CB<1>")
	)
	(segment
		(start 328.033634 -245.610634)
		(end 328.044048 -245.61673)
		(width 0.0889)
		(layer "In11.Cu")
		(net "M_F_CPU0_SA_CB<1>")
	)
	(segment
		(start 271.071086 -237.095792)
		(end 271.071086 -237.00486)
		(width 0.14478)
		(layer "In11.Cu")
		(net "M_F_CPU0_SA_CB<1>")
	)
	(segment
		(start 291.144452 -236.173264)
		(end 291.144452 -236.238542)
		(width 0.14478)
		(layer "In11.Cu")
		(net "M_F_CPU0_SA_CB<1>")
	)
	(segment
		(start 296.414444 -237.24997)
		(end 296.644822 -237.24997)
		(width 0.14478)
		(layer "In11.Cu")
		(net "M_F_CPU0_SA_CB<1>")
	)
	(segment
		(start 326.198738 -245.61673)
		(end 326.24014 -245.658132)
		(width 0.0889)
		(layer "In11.Cu")
		(net "M_F_CPU0_SA_CB<1>")
	)
	(segment
		(start 296.251376 -237.086902)
		(end 296.414444 -237.24997)
		(width 0.14478)
		(layer "In11.Cu")
		(net "M_F_CPU0_SA_CB<1>")
	)
	(segment
		(start 278.410924 -236.010196)
		(end 279.260808 -236.86008)
		(width 0.14478)
		(layer "In11.Cu")
		(net "M_F_CPU0_SA_CB<1>")
	)
	(segment
		(start 298.715938 -236.173264)
		(end 298.715938 -236.233462)
		(width 0.14478)
		(layer "In11.Cu")
		(net "M_F_CPU0_SA_CB<1>")
	)
	(segment
		(start 303.862994 -236.630718)
		(end 304.026062 -236.46765)
		(width 0.14478)
		(layer "In11.Cu")
		(net "M_F_CPU0_SA_CB<1>")
	)
	(segment
		(start 297.389042 -236.86008)
		(end 298.238926 -236.010196)
		(width 0.14478)
		(layer "In11.Cu")
		(net "M_F_CPU0_SA_CB<1>")
	)
	(segment
		(start 271.071086 -237.00486)
		(end 271.215866 -236.86008)
		(width 0.14478)
		(layer "In11.Cu")
		(net "M_F_CPU0_SA_CB<1>")
	)
	(segment
		(start 274.468336 -237.146592)
		(end 275.604732 -236.010196)
		(width 0.14478)
		(layer "In11.Cu")
		(net "M_F_CPU0_SA_CB<1>")
	)
	(segment
		(start 291.700966 -236.173264)
		(end 291.864034 -236.010196)
		(width 0.14478)
		(layer "In11.Cu")
		(net "M_F_CPU0_SA_CB<1>")
	)
	(segment
		(start 288.642806 -236.86008)
		(end 288.805874 -237.023148)
		(width 0.14478)
		(layer "In11.Cu")
		(net "M_F_CPU0_SA_CB<1>")
	)
	(segment
		(start 328.409808 -245.621556)
		(end 328.41819 -245.61673)
		(width 0.0889)
		(layer "In11.Cu")
		(net "M_F_CPU0_SA_CB<1>")
	)
	(segment
		(start 276.476206 -236.39653)
		(end 276.639274 -236.233462)
		(width 0.14478)
		(layer "In11.Cu")
		(net "M_F_CPU0_SA_CB<1>")
	)
	(segment
		(start 303.862994 -236.697012)
		(end 303.862994 -236.630718)
		(width 0.14478)
		(layer "In11.Cu")
		(net "M_F_CPU0_SA_CB<1>")
	)
	(segment
		(start 304.419508 -236.630718)
		(end 304.419508 -236.697012)
		(width 0.14478)
		(layer "In11.Cu")
		(net "M_F_CPU0_SA_CB<1>")
	)
	(segment
		(start 303.699926 -236.86008)
		(end 303.862994 -236.697012)
		(width 0.14478)
		(layer "In11.Cu")
		(net "M_F_CPU0_SA_CB<1>")
	)
	(segment
		(start 271.62252 -237.00486)
		(end 271.62252 -237.095792)
		(width 0.14478)
		(layer "In11.Cu")
		(net "M_F_CPU0_SA_CB<1>")
	)
	(segment
		(start 270.374872 -236.86008)
		(end 270.519652 -237.00486)
		(width 0.14478)
		(layer "In11.Cu")
		(net "M_F_CPU0_SA_CB<1>")
	)
	(segment
		(start 283.594302 -236.233462)
		(end 283.75737 -236.39653)
		(width 0.14478)
		(layer "In11.Cu")
		(net "M_F_CPU0_SA_CB<1>")
	)
	(segment
		(start 281.833066 -237.086902)
		(end 281.833066 -237.023148)
		(width 0.14478)
		(layer "In11.Cu")
		(net "M_F_CPU0_SA_CB<1>")
	)
	(segment
		(start 282.323286 -236.86008)
		(end 283.17317 -236.010196)
		(width 0.14478)
		(layer "In11.Cu")
		(net "M_F_CPU0_SA_CB<1>")
	)
	(segment
		(start 299.272452 -236.173264)
		(end 299.43552 -236.010196)
		(width 0.14478)
		(layer "In11.Cu")
		(net "M_F_CPU0_SA_CB<1>")
	)
	(segment
		(start 288.805874 -237.086902)
		(end 288.968942 -237.24997)
		(width 0.14478)
		(layer "In11.Cu")
		(net "M_F_CPU0_SA_CB<1>")
	)
	(segment
		(start 324.403466 -245.61673)
		(end 326.198738 -245.61673)
		(width 0.0889)
		(layer "In11.Cu")
		(net "M_F_CPU0_SA_CB<1>")
	)
	(segment
		(start 283.431234 -236.010196)
		(end 283.594302 -236.173264)
		(width 0.14478)
		(layer "In11.Cu")
		(net "M_F_CPU0_SA_CB<1>")
	)
	(segment
		(start 283.987748 -236.39653)
		(end 284.150816 -236.233462)
		(width 0.14478)
		(layer "In11.Cu")
		(net "M_F_CPU0_SA_CB<1>")
	)
	(segment
		(start 304.026062 -236.46765)
		(end 304.25644 -236.46765)
		(width 0.14478)
		(layer "In11.Cu")
		(net "M_F_CPU0_SA_CB<1>")
	)
	(segment
		(start 270.519652 -237.00486)
		(end 270.519652 -237.095792)
		(width 0.14478)
		(layer "In11.Cu")
		(net "M_F_CPU0_SA_CB<1>")
	)
	(segment
		(start 276.802342 -236.010196)
		(end 278.410924 -236.010196)
		(width 0.14478)
		(layer "In11.Cu")
		(net "M_F_CPU0_SA_CB<1>")
	)
	(segment
		(start 290.732972 -236.010196)
		(end 290.981384 -236.010196)
		(width 0.14478)
		(layer "In11.Cu")
		(net "M_F_CPU0_SA_CB<1>")
	)
	(segment
		(start 284.313884 -236.010196)
		(end 285.892748 -236.010196)
		(width 0.14478)
		(layer "In11.Cu")
		(net "M_F_CPU0_SA_CB<1>")
	)
	(segment
		(start 306.54752 -236.323632)
		(end 315.210698 -244.98681)
		(width 0.14478)
		(layer "In11.Cu")
		(net "M_F_CPU0_SA_CB<1>")
	)
	(segment
		(start 305.43119 -236.323632)
		(end 306.54752 -236.323632)
		(width 0.14478)
		(layer "In11.Cu")
		(net "M_F_CPU0_SA_CB<1>")
	)
	(arc
		(start 333.118206 -245.61673)
		(mid 333.365919 -245.54151)
		(end 333.621126 -245.58498)
		(width 0.0889)
		(layer "In11.Cu")
		(net "M_F_CPU0_SA_CB<1>")
	)
	(arc
		(start 328.044048 -245.61673)
		(mid 328.226299 -245.66708)
		(end 328.409808 -245.621556)
		(width 0.0889)
		(layer "In11.Cu")
		(net "M_F_CPU0_SA_CB<1>")
	)
	(arc
		(start 327.103486 -245.61673)
		(mid 327.290684 -245.667112)
		(end 327.477882 -245.61673)
		(width 0.0889)
		(layer "In11.Cu")
		(net "M_F_CPU0_SA_CB<1>")
	)
	(arc
		(start 329.358244 -245.61673)
		(mid 329.6412 -245.540553)
		(end 329.924156 -245.61673)
		(width 0.0889)
		(layer "In11.Cu")
		(net "M_F_CPU0_SA_CB<1>")
	)
	(arc
		(start 328.992484 -245.621556)
		(mid 329.175992 -245.66705)
		(end 329.358244 -245.61673)
		(width 0.0889)
		(layer "In11.Cu")
		(net "M_F_CPU0_SA_CB<1>")
	)
	(arc
		(start 330.298044 -245.61673)
		(mid 330.581 -245.540553)
		(end 330.863956 -245.61673)
		(width 0.0889)
		(layer "In11.Cu")
		(net "M_F_CPU0_SA_CB<1>")
	)
	(arc
		(start 331.238098 -245.61673)
		(mid 331.521054 -245.540553)
		(end 331.80401 -245.61673)
		(width 0.0889)
		(layer "In11.Cu")
		(net "M_F_CPU0_SA_CB<1>")
	)
	(arc
		(start 332.752446 -245.621556)
		(mid 332.935954 -245.66705)
		(end 333.118206 -245.61673)
		(width 0.0889)
		(layer "In11.Cu")
		(net "M_F_CPU0_SA_CB<1>")
	)
	(arc
		(start 327.477882 -245.61673)
		(mid 327.754949 -245.540459)
		(end 328.033634 -245.610634)
		(width 0.0889)
		(layer "In11.Cu")
		(net "M_F_CPU0_SA_CB<1>")
	)
	(arc
		(start 332.178152 -245.61673)
		(mid 332.461108 -245.540553)
		(end 332.744064 -245.61673)
		(width 0.0889)
		(layer "In11.Cu")
		(net "M_F_CPU0_SA_CB<1>")
	)
	(arc
		(start 329.924156 -245.61673)
		(mid 330.1111 -245.666985)
		(end 330.298044 -245.61673)
		(width 0.0889)
		(layer "In11.Cu")
		(net "M_F_CPU0_SA_CB<1>")
	)
	(arc
		(start 326.548242 -245.610634)
		(mid 326.826674 -245.540536)
		(end 327.103486 -245.61673)
		(width 0.0889)
		(layer "In11.Cu")
		(net "M_F_CPU0_SA_CB<1>")
	)
	(arc
		(start 328.41819 -245.61673)
		(mid 328.701146 -245.540553)
		(end 328.984102 -245.61673)
		(width 0.0889)
		(layer "In11.Cu")
		(net "M_F_CPU0_SA_CB<1>")
	)
	(arc
		(start 331.80401 -245.61673)
		(mid 331.986261 -245.66708)
		(end 332.16977 -245.621556)
		(width 0.0889)
		(layer "In11.Cu")
		(net "M_F_CPU0_SA_CB<1>")
	)
	(arc
		(start 330.863956 -245.61673)
		(mid 331.046207 -245.66708)
		(end 331.229716 -245.621556)
		(width 0.0889)
		(layer "In11.Cu")
		(net "M_F_CPU0_SA_CB<1>")
	)
	(segment
		(start 332.92796 -244.750082)
		(end 332.461108 -244.484144)
		(width 0.10668)
		(layer "F.Cu")
		(net "M_F_CPU0_SA_CB<0>")
	)
	(segment
		(start 302.771048 -235.53801)
		(end 302.934116 -235.374942)
		(width 0.14478)
		(layer "In11.Cu")
		(net "M_F_CPU0_SA_CB<0>")
	)
	(segment
		(start 274.754848 -235.160058)
		(end 275.604732 -234.310174)
		(width 0.14478)
		(layer "In11.Cu")
		(net "M_F_CPU0_SA_CB<0>")
	)
	(segment
		(start 283.490924 -234.310174)
		(end 283.653992 -234.473242)
		(width 0.14478)
		(layer "In11.Cu")
		(net "M_F_CPU0_SA_CB<0>")
	)
	(segment
		(start 276.204172 -234.70235)
		(end 276.43455 -234.70235)
		(width 0.14478)
		(layer "In11.Cu")
		(net "M_F_CPU0_SA_CB<0>")
	)
	(segment
		(start 284.373574 -234.310174)
		(end 285.892748 -234.310174)
		(width 0.14478)
		(layer "In11.Cu")
		(net "M_F_CPU0_SA_CB<0>")
	)
	(segment
		(start 301.051976 -234.310174)
		(end 301.90186 -235.160058)
		(width 0.14478)
		(layer "In11.Cu")
		(net "M_F_CPU0_SA_CB<0>")
	)
	(segment
		(start 291.278818 -234.539282)
		(end 291.441886 -234.70235)
		(width 0.14478)
		(layer "In11.Cu")
		(net "M_F_CPU0_SA_CB<0>")
	)
	(segment
		(start 324.970394 -244.29593)
		(end 325.53148 -244.857016)
		(width 0.0889)
		(layer "In11.Cu")
		(net "M_F_CPU0_SA_CB<0>")
	)
	(segment
		(start 283.653992 -234.531662)
		(end 283.81706 -234.69473)
		(width 0.14478)
		(layer "In11.Cu")
		(net "M_F_CPU0_SA_CB<0>")
	)
	(segment
		(start 296.861738 -235.385102)
		(end 296.861738 -235.323126)
		(width 0.14478)
		(layer "In11.Cu")
		(net "M_F_CPU0_SA_CB<0>")
	)
	(segment
		(start 276.43455 -234.70235)
		(end 276.597618 -234.539282)
		(width 0.14478)
		(layer "In11.Cu")
		(net "M_F_CPU0_SA_CB<0>")
	)
	(segment
		(start 272.22831 -235.323126)
		(end 272.391378 -235.160058)
		(width 0.14478)
		(layer "In11.Cu")
		(net "M_F_CPU0_SA_CB<0>")
	)
	(segment
		(start 315.587634 -244.07749)
		(end 323.890894 -244.07749)
		(width 0.14478)
		(layer "In11.Cu")
		(net "M_F_CPU0_SA_CB<0>")
	)
	(segment
		(start 281.258518 -235.323126)
		(end 281.258518 -235.380022)
		(width 0.14478)
		(layer "In11.Cu")
		(net "M_F_CPU0_SA_CB<0>")
	)
	(segment
		(start 323.890894 -244.07749)
		(end 324.198234 -244.07749)
		(width 0.0889)
		(layer "In11.Cu")
		(net "M_F_CPU0_SA_CB<0>")
	)
	(segment
		(start 324.416674 -244.29593)
		(end 324.970394 -244.29593)
		(width 0.0889)
		(layer "In11.Cu")
		(net "M_F_CPU0_SA_CB<0>")
	)
	(segment
		(start 272.22831 -235.385102)
		(end 272.22831 -235.323126)
		(width 0.14478)
		(layer "In11.Cu")
		(net "M_F_CPU0_SA_CB<0>")
	)
	(segment
		(start 332.211172 -244.774974)
		(end 332.307184 -244.749574)
		(width 0.0889)
		(layer "In11.Cu")
		(net "M_F_CPU0_SA_CB<0>")
	)
	(segment
		(start 289.609022 -235.160058)
		(end 289.883088 -235.160058)
		(width 0.14478)
		(layer "In11.Cu")
		(net "M_F_CPU0_SA_CB<0>")
	)
	(segment
		(start 289.445954 -235.323126)
		(end 289.609022 -235.160058)
		(width 0.14478)
		(layer "In11.Cu")
		(net "M_F_CPU0_SA_CB<0>")
	)
	(segment
		(start 298.615354 -234.310174)
		(end 298.778422 -234.473242)
		(width 0.14478)
		(layer "In11.Cu")
		(net "M_F_CPU0_SA_CB<0>")
	)
	(segment
		(start 276.597618 -234.539282)
		(end 276.597618 -234.473242)
		(width 0.14478)
		(layer "In11.Cu")
		(net "M_F_CPU0_SA_CB<0>")
	)
	(segment
		(start 285.892748 -234.310174)
		(end 286.742632 -235.160058)
		(width 0.14478)
		(layer "In11.Cu")
		(net "M_F_CPU0_SA_CB<0>")
	)
	(segment
		(start 275.604732 -234.310174)
		(end 275.878036 -234.310174)
		(width 0.14478)
		(layer "In11.Cu")
		(net "M_F_CPU0_SA_CB<0>")
	)
	(segment
		(start 296.142156 -235.160058)
		(end 296.305224 -235.323126)
		(width 0.14478)
		(layer "In11.Cu")
		(net "M_F_CPU0_SA_CB<0>")
	)
	(segment
		(start 298.778422 -234.531662)
		(end 298.94149 -234.69473)
		(width 0.14478)
		(layer "In11.Cu")
		(net "M_F_CPU0_SA_CB<0>")
	)
	(segment
		(start 326.052688 -244.815868)
		(end 326.068944 -244.80647)
		(width 0.0889)
		(layer "In11.Cu")
		(net "M_F_CPU0_SA_CB<0>")
	)
	(segment
		(start 284.210506 -234.473242)
		(end 284.373574 -234.310174)
		(width 0.14478)
		(layer "In11.Cu")
		(net "M_F_CPU0_SA_CB<0>")
	)
	(segment
		(start 271.115282 -235.024422)
		(end 271.27835 -234.861354)
		(width 0.14478)
		(layer "In11.Cu")
		(net "M_F_CPU0_SA_CB<0>")
	)
	(segment
		(start 270.721836 -235.54817)
		(end 270.952214 -235.54817)
		(width 0.14478)
		(layer "In11.Cu")
		(net "M_F_CPU0_SA_CB<0>")
	)
	(segment
		(start 275.878036 -234.310174)
		(end 276.041104 -234.473242)
		(width 0.14478)
		(layer "In11.Cu")
		(net "M_F_CPU0_SA_CB<0>")
	)
	(segment
		(start 299.334936 -234.531662)
		(end 299.334936 -234.473242)
		(width 0.14478)
		(layer "In11.Cu")
		(net "M_F_CPU0_SA_CB<0>")
	)
	(segment
		(start 324.198234 -244.07749)
		(end 324.416674 -244.29593)
		(width 0.0889)
		(layer "In11.Cu")
		(net "M_F_CPU0_SA_CB<0>")
	)
	(segment
		(start 299.334936 -234.473242)
		(end 299.498004 -234.310174)
		(width 0.14478)
		(layer "In11.Cu")
		(net "M_F_CPU0_SA_CB<0>")
	)
	(segment
		(start 274.353274 -235.160058)
		(end 274.754848 -235.160058)
		(width 0.14478)
		(layer "In11.Cu")
		(net "M_F_CPU0_SA_CB<0>")
	)
	(segment
		(start 297.389042 -235.160058)
		(end 298.238926 -234.310174)
		(width 0.14478)
		(layer "In11.Cu")
		(net "M_F_CPU0_SA_CB<0>")
	)
	(segment
		(start 270.558768 -235.323126)
		(end 270.558768 -235.385102)
		(width 0.14478)
		(layer "In11.Cu")
		(net "M_F_CPU0_SA_CB<0>")
	)
	(segment
		(start 271.115282 -235.385102)
		(end 271.115282 -235.024422)
		(width 0.14478)
		(layer "In11.Cu")
		(net "M_F_CPU0_SA_CB<0>")
	)
	(segment
		(start 291.672264 -234.70235)
		(end 291.835332 -234.539282)
		(width 0.14478)
		(layer "In11.Cu")
		(net "M_F_CPU0_SA_CB<0>")
	)
	(segment
		(start 281.9781 -235.160058)
		(end 282.323286 -235.160058)
		(width 0.14478)
		(layer "In11.Cu")
		(net "M_F_CPU0_SA_CB<0>")
	)
	(segment
		(start 298.94149 -234.69473)
		(end 299.171868 -234.69473)
		(width 0.14478)
		(layer "In11.Cu")
		(net "M_F_CPU0_SA_CB<0>")
	)
	(segment
		(start 270.952214 -235.54817)
		(end 271.115282 -235.385102)
		(width 0.14478)
		(layer "In11.Cu")
		(net "M_F_CPU0_SA_CB<0>")
	)
	(segment
		(start 296.468292 -235.54817)
		(end 296.69867 -235.54817)
		(width 0.14478)
		(layer "In11.Cu")
		(net "M_F_CPU0_SA_CB<0>")
	)
	(segment
		(start 305.036728 -235.018072)
		(end 307.471572 -235.018072)
		(width 0.14478)
		(layer "In11.Cu")
		(net "M_F_CPU0_SA_CB<0>")
	)
	(segment
		(start 303.327562 -235.160058)
		(end 303.49063 -235.323126)
		(width 0.14478)
		(layer "In11.Cu")
		(net "M_F_CPU0_SA_CB<0>")
	)
	(segment
		(start 332.307184 -244.749574)
		(end 332.461108 -244.484144)
		(width 0.0889)
		(layer "In11.Cu")
		(net "M_F_CPU0_SA_CB<0>")
	)
	(segment
		(start 276.041104 -234.539282)
		(end 276.204172 -234.70235)
		(width 0.14478)
		(layer "In11.Cu")
		(net "M_F_CPU0_SA_CB<0>")
	)
	(segment
		(start 281.651964 -235.54309)
		(end 281.815032 -235.380022)
		(width 0.14478)
		(layer "In11.Cu")
		(net "M_F_CPU0_SA_CB<0>")
	)
	(segment
		(start 271.27835 -234.861354)
		(end 271.508728 -234.861354)
		(width 0.14478)
		(layer "In11.Cu")
		(net "M_F_CPU0_SA_CB<0>")
	)
	(segment
		(start 303.653698 -235.53801)
		(end 303.884076 -235.53801)
		(width 0.14478)
		(layer "In11.Cu")
		(net "M_F_CPU0_SA_CB<0>")
	)
	(segment
		(start 276.041104 -234.473242)
		(end 276.041104 -234.539282)
		(width 0.14478)
		(layer "In11.Cu")
		(net "M_F_CPU0_SA_CB<0>")
	)
	(segment
		(start 304.047144 -235.374942)
		(end 304.047144 -235.323126)
		(width 0.14478)
		(layer "In11.Cu")
		(net "M_F_CPU0_SA_CB<0>")
	)
	(segment
		(start 291.835332 -234.539282)
		(end 291.835332 -234.473242)
		(width 0.14478)
		(layer "In11.Cu")
		(net "M_F_CPU0_SA_CB<0>")
	)
	(segment
		(start 291.835332 -234.473242)
		(end 291.9984 -234.310174)
		(width 0.14478)
		(layer "In11.Cu")
		(net "M_F_CPU0_SA_CB<0>")
	)
	(segment
		(start 290.732972 -234.310174)
		(end 291.11575 -234.310174)
		(width 0.14478)
		(layer "In11.Cu")
		(net "M_F_CPU0_SA_CB<0>")
	)
	(segment
		(start 291.441886 -234.70235)
		(end 291.672264 -234.70235)
		(width 0.14478)
		(layer "In11.Cu")
		(net "M_F_CPU0_SA_CB<0>")
	)
	(segment
		(start 289.052508 -235.54817)
		(end 289.282886 -235.54817)
		(width 0.14478)
		(layer "In11.Cu")
		(net "M_F_CPU0_SA_CB<0>")
	)
	(segment
		(start 270.07312 -235.160058)
		(end 270.3957 -235.160058)
		(width 0.14478)
		(layer "In11.Cu")
		(net "M_F_CPU0_SA_CB<0>")
	)
	(segment
		(start 270.558768 -235.385102)
		(end 270.721836 -235.54817)
		(width 0.14478)
		(layer "In11.Cu")
		(net "M_F_CPU0_SA_CB<0>")
	)
	(segment
		(start 283.81706 -234.69473)
		(end 284.047438 -234.69473)
		(width 0.14478)
		(layer "In11.Cu")
		(net "M_F_CPU0_SA_CB<0>")
	)
	(segment
		(start 326.997568 -244.813582)
		(end 327.009252 -244.806724)
		(width 0.0889)
		(layer "In11.Cu")
		(net "M_F_CPU0_SA_CB<0>")
	)
	(segment
		(start 303.49063 -235.374942)
		(end 303.653698 -235.53801)
		(width 0.14478)
		(layer "In11.Cu")
		(net "M_F_CPU0_SA_CB<0>")
	)
	(segment
		(start 273.79676 -235.54817)
		(end 274.027138 -235.54817)
		(width 0.14478)
		(layer "In11.Cu")
		(net "M_F_CPU0_SA_CB<0>")
	)
	(segment
		(start 302.377602 -235.323126)
		(end 302.377602 -235.374942)
		(width 0.14478)
		(layer "In11.Cu")
		(net "M_F_CPU0_SA_CB<0>")
	)
	(segment
		(start 273.633692 -235.323126)
		(end 273.633692 -235.385102)
		(width 0.14478)
		(layer "In11.Cu")
		(net "M_F_CPU0_SA_CB<0>")
	)
	(segment
		(start 307.837078 -235.383578)
		(end 307.837078 -236.326934)
		(width 0.14478)
		(layer "In11.Cu")
		(net "M_F_CPU0_SA_CB<0>")
	)
	(segment
		(start 284.210506 -234.531662)
		(end 284.210506 -234.473242)
		(width 0.14478)
		(layer "In11.Cu")
		(net "M_F_CPU0_SA_CB<0>")
	)
	(segment
		(start 281.09545 -235.160058)
		(end 281.258518 -235.323126)
		(width 0.14478)
		(layer "In11.Cu")
		(net "M_F_CPU0_SA_CB<0>")
	)
	(segment
		(start 284.047438 -234.69473)
		(end 284.210506 -234.531662)
		(width 0.14478)
		(layer "In11.Cu")
		(net "M_F_CPU0_SA_CB<0>")
	)
	(segment
		(start 281.258518 -235.380022)
		(end 281.421586 -235.54309)
		(width 0.14478)
		(layer "In11.Cu")
		(net "M_F_CPU0_SA_CB<0>")
	)
	(segment
		(start 298.238926 -234.310174)
		(end 298.615354 -234.310174)
		(width 0.14478)
		(layer "In11.Cu")
		(net "M_F_CPU0_SA_CB<0>")
	)
	(segment
		(start 271.671796 -235.385102)
		(end 271.834864 -235.54817)
		(width 0.14478)
		(layer "In11.Cu")
		(net "M_F_CPU0_SA_CB<0>")
	)
	(segment
		(start 302.934116 -235.323126)
		(end 303.097184 -235.160058)
		(width 0.14478)
		(layer "In11.Cu")
		(net "M_F_CPU0_SA_CB<0>")
	)
	(segment
		(start 288.88944 -235.323126)
		(end 288.88944 -235.385102)
		(width 0.14478)
		(layer "In11.Cu")
		(net "M_F_CPU0_SA_CB<0>")
	)
	(segment
		(start 288.726372 -235.160058)
		(end 288.88944 -235.323126)
		(width 0.14478)
		(layer "In11.Cu")
		(net "M_F_CPU0_SA_CB<0>")
	)
	(segment
		(start 276.760686 -234.310174)
		(end 278.410924 -234.310174)
		(width 0.14478)
		(layer "In11.Cu")
		(net "M_F_CPU0_SA_CB<0>")
	)
	(segment
		(start 271.671796 -235.024422)
		(end 271.671796 -235.385102)
		(width 0.14478)
		(layer "In11.Cu")
		(net "M_F_CPU0_SA_CB<0>")
	)
	(segment
		(start 283.17317 -234.310174)
		(end 283.490924 -234.310174)
		(width 0.14478)
		(layer "In11.Cu")
		(net "M_F_CPU0_SA_CB<0>")
	)
	(segment
		(start 296.861738 -235.323126)
		(end 297.024806 -235.160058)
		(width 0.14478)
		(layer "In11.Cu")
		(net "M_F_CPU0_SA_CB<0>")
	)
	(segment
		(start 330.394056 -244.806724)
		(end 330.402438 -244.81155)
		(width 0.0889)
		(layer "In11.Cu")
		(net "M_F_CPU0_SA_CB<0>")
	)
	(segment
		(start 281.815032 -235.380022)
		(end 281.815032 -235.323126)
		(width 0.14478)
		(layer "In11.Cu")
		(net "M_F_CPU0_SA_CB<0>")
	)
	(segment
		(start 289.282886 -235.54817)
		(end 289.445954 -235.385102)
		(width 0.14478)
		(layer "In11.Cu")
		(net "M_F_CPU0_SA_CB<0>")
	)
	(segment
		(start 271.508728 -234.861354)
		(end 271.671796 -235.024422)
		(width 0.14478)
		(layer "In11.Cu")
		(net "M_F_CPU0_SA_CB<0>")
	)
	(segment
		(start 282.323286 -235.160058)
		(end 283.17317 -234.310174)
		(width 0.14478)
		(layer "In11.Cu")
		(net "M_F_CPU0_SA_CB<0>")
	)
	(segment
		(start 304.894742 -235.160058)
		(end 305.036728 -235.018072)
		(width 0.14478)
		(layer "In11.Cu")
		(net "M_F_CPU0_SA_CB<0>")
	)
	(segment
		(start 296.305224 -235.323126)
		(end 296.305224 -235.385102)
		(width 0.14478)
		(layer "In11.Cu")
		(net "M_F_CPU0_SA_CB<0>")
	)
	(segment
		(start 278.410924 -234.310174)
		(end 279.260808 -235.160058)
		(width 0.14478)
		(layer "In11.Cu")
		(net "M_F_CPU0_SA_CB<0>")
	)
	(segment
		(start 293.507922 -234.310174)
		(end 294.357806 -235.160058)
		(width 0.14478)
		(layer "In11.Cu")
		(net "M_F_CPU0_SA_CB<0>")
	)
	(segment
		(start 296.305224 -235.385102)
		(end 296.468292 -235.54817)
		(width 0.14478)
		(layer "In11.Cu")
		(net "M_F_CPU0_SA_CB<0>")
	)
	(segment
		(start 294.357806 -235.160058)
		(end 296.142156 -235.160058)
		(width 0.14478)
		(layer "In11.Cu")
		(net "M_F_CPU0_SA_CB<0>")
	)
	(segment
		(start 291.11575 -234.310174)
		(end 291.278818 -234.473242)
		(width 0.14478)
		(layer "In11.Cu")
		(net "M_F_CPU0_SA_CB<0>")
	)
	(segment
		(start 286.742632 -235.160058)
		(end 288.726372 -235.160058)
		(width 0.14478)
		(layer "In11.Cu")
		(net "M_F_CPU0_SA_CB<0>")
	)
	(segment
		(start 288.88944 -235.385102)
		(end 289.052508 -235.54817)
		(width 0.14478)
		(layer "In11.Cu")
		(net "M_F_CPU0_SA_CB<0>")
	)
	(segment
		(start 307.471572 -235.018072)
		(end 307.837078 -235.383578)
		(width 0.14478)
		(layer "In11.Cu")
		(net "M_F_CPU0_SA_CB<0>")
	)
	(segment
		(start 331.33411 -244.806724)
		(end 331.342492 -244.81155)
		(width 0.0889)
		(layer "In11.Cu")
		(net "M_F_CPU0_SA_CB<0>")
	)
	(segment
		(start 283.653992 -234.473242)
		(end 283.653992 -234.531662)
		(width 0.14478)
		(layer "In11.Cu")
		(net "M_F_CPU0_SA_CB<0>")
	)
	(segment
		(start 271.834864 -235.54817)
		(end 272.065242 -235.54817)
		(width 0.14478)
		(layer "In11.Cu")
		(net "M_F_CPU0_SA_CB<0>")
	)
	(segment
		(start 289.883088 -235.160058)
		(end 290.732972 -234.310174)
		(width 0.14478)
		(layer "In11.Cu")
		(net "M_F_CPU0_SA_CB<0>")
	)
	(segment
		(start 303.884076 -235.53801)
		(end 304.047144 -235.374942)
		(width 0.14478)
		(layer "In11.Cu")
		(net "M_F_CPU0_SA_CB<0>")
	)
	(segment
		(start 303.49063 -235.323126)
		(end 303.49063 -235.374942)
		(width 0.14478)
		(layer "In11.Cu")
		(net "M_F_CPU0_SA_CB<0>")
	)
	(segment
		(start 326.068944 -244.80647)
		(end 326.090534 -244.794024)
		(width 0.0889)
		(layer "In11.Cu")
		(net "M_F_CPU0_SA_CB<0>")
	)
	(segment
		(start 302.934116 -235.374942)
		(end 302.934116 -235.323126)
		(width 0.14478)
		(layer "In11.Cu")
		(net "M_F_CPU0_SA_CB<0>")
	)
	(segment
		(start 327.574402 -244.80647)
		(end 327.590658 -244.815868)
		(width 0.0889)
		(layer "In11.Cu")
		(net "M_F_CPU0_SA_CB<0>")
	)
	(segment
		(start 329.819762 -244.81155)
		(end 329.828144 -244.806724)
		(width 0.0889)
		(layer "In11.Cu")
		(net "M_F_CPU0_SA_CB<0>")
	)
	(segment
		(start 298.778422 -234.473242)
		(end 298.778422 -234.531662)
		(width 0.14478)
		(layer "In11.Cu")
		(net "M_F_CPU0_SA_CB<0>")
	)
	(segment
		(start 281.815032 -235.323126)
		(end 281.9781 -235.160058)
		(width 0.14478)
		(layer "In11.Cu")
		(net "M_F_CPU0_SA_CB<0>")
	)
	(segment
		(start 325.53148 -244.857016)
		(end 325.879714 -244.857016)
		(width 0.0889)
		(layer "In11.Cu")
		(net "M_F_CPU0_SA_CB<0>")
	)
	(segment
		(start 269.648178 -234.735116)
		(end 270.07312 -235.160058)
		(width 0.14478)
		(layer "In11.Cu")
		(net "M_F_CPU0_SA_CB<0>")
	)
	(segment
		(start 272.391378 -235.160058)
		(end 273.470624 -235.160058)
		(width 0.14478)
		(layer "In11.Cu")
		(net "M_F_CPU0_SA_CB<0>")
	)
	(segment
		(start 304.210212 -235.160058)
		(end 304.894742 -235.160058)
		(width 0.14478)
		(layer "In11.Cu")
		(net "M_F_CPU0_SA_CB<0>")
	)
	(segment
		(start 291.278818 -234.473242)
		(end 291.278818 -234.539282)
		(width 0.14478)
		(layer "In11.Cu")
		(net "M_F_CPU0_SA_CB<0>")
	)
	(segment
		(start 289.445954 -235.385102)
		(end 289.445954 -235.323126)
		(width 0.14478)
		(layer "In11.Cu")
		(net "M_F_CPU0_SA_CB<0>")
	)
	(segment
		(start 301.90186 -235.160058)
		(end 302.214534 -235.160058)
		(width 0.14478)
		(layer "In11.Cu")
		(net "M_F_CPU0_SA_CB<0>")
	)
	(segment
		(start 307.837078 -236.326934)
		(end 315.587634 -244.07749)
		(width 0.14478)
		(layer "In11.Cu")
		(net "M_F_CPU0_SA_CB<0>")
	)
	(segment
		(start 281.421586 -235.54309)
		(end 281.651964 -235.54309)
		(width 0.14478)
		(layer "In11.Cu")
		(net "M_F_CPU0_SA_CB<0>")
	)
	(segment
		(start 270.3957 -235.160058)
		(end 270.558768 -235.323126)
		(width 0.14478)
		(layer "In11.Cu")
		(net "M_F_CPU0_SA_CB<0>")
	)
	(segment
		(start 274.027138 -235.54817)
		(end 274.190206 -235.385102)
		(width 0.14478)
		(layer "In11.Cu")
		(net "M_F_CPU0_SA_CB<0>")
	)
	(segment
		(start 296.69867 -235.54817)
		(end 296.861738 -235.385102)
		(width 0.14478)
		(layer "In11.Cu")
		(net "M_F_CPU0_SA_CB<0>")
	)
	(segment
		(start 291.9984 -234.310174)
		(end 293.507922 -234.310174)
		(width 0.14478)
		(layer "In11.Cu")
		(net "M_F_CPU0_SA_CB<0>")
	)
	(segment
		(start 302.54067 -235.53801)
		(end 302.771048 -235.53801)
		(width 0.14478)
		(layer "In11.Cu")
		(net "M_F_CPU0_SA_CB<0>")
	)
	(segment
		(start 303.097184 -235.160058)
		(end 303.327562 -235.160058)
		(width 0.14478)
		(layer "In11.Cu")
		(net "M_F_CPU0_SA_CB<0>")
	)
	(segment
		(start 302.377602 -235.374942)
		(end 302.54067 -235.53801)
		(width 0.14478)
		(layer "In11.Cu")
		(net "M_F_CPU0_SA_CB<0>")
	)
	(segment
		(start 297.024806 -235.160058)
		(end 297.389042 -235.160058)
		(width 0.14478)
		(layer "In11.Cu")
		(net "M_F_CPU0_SA_CB<0>")
	)
	(segment
		(start 302.214534 -235.160058)
		(end 302.377602 -235.323126)
		(width 0.14478)
		(layer "In11.Cu")
		(net "M_F_CPU0_SA_CB<0>")
	)
	(segment
		(start 273.633692 -235.385102)
		(end 273.79676 -235.54817)
		(width 0.14478)
		(layer "In11.Cu")
		(net "M_F_CPU0_SA_CB<0>")
	)
	(segment
		(start 273.470624 -235.160058)
		(end 273.633692 -235.323126)
		(width 0.14478)
		(layer "In11.Cu")
		(net "M_F_CPU0_SA_CB<0>")
	)
	(segment
		(start 272.065242 -235.54817)
		(end 272.22831 -235.385102)
		(width 0.14478)
		(layer "In11.Cu")
		(net "M_F_CPU0_SA_CB<0>")
	)
	(segment
		(start 276.597618 -234.473242)
		(end 276.760686 -234.310174)
		(width 0.14478)
		(layer "In11.Cu")
		(net "M_F_CPU0_SA_CB<0>")
	)
	(segment
		(start 279.260808 -235.160058)
		(end 281.09545 -235.160058)
		(width 0.14478)
		(layer "In11.Cu")
		(net "M_F_CPU0_SA_CB<0>")
	)
	(segment
		(start 299.171868 -234.69473)
		(end 299.334936 -234.531662)
		(width 0.14478)
		(layer "In11.Cu")
		(net "M_F_CPU0_SA_CB<0>")
	)
	(segment
		(start 274.190206 -235.323126)
		(end 274.353274 -235.160058)
		(width 0.14478)
		(layer "In11.Cu")
		(net "M_F_CPU0_SA_CB<0>")
	)
	(segment
		(start 299.498004 -234.310174)
		(end 301.051976 -234.310174)
		(width 0.14478)
		(layer "In11.Cu")
		(net "M_F_CPU0_SA_CB<0>")
	)
	(segment
		(start 304.047144 -235.323126)
		(end 304.210212 -235.160058)
		(width 0.14478)
		(layer "In11.Cu")
		(net "M_F_CPU0_SA_CB<0>")
	)
	(segment
		(start 327.562464 -244.799612)
		(end 327.574402 -244.80647)
		(width 0.0889)
		(layer "In11.Cu")
		(net "M_F_CPU0_SA_CB<0>")
	)
	(segment
		(start 274.190206 -235.385102)
		(end 274.190206 -235.323126)
		(width 0.14478)
		(layer "In11.Cu")
		(net "M_F_CPU0_SA_CB<0>")
	)
	(arc
		(start 327.94829 -244.806724)
		(mid 328.231246 -244.730547)
		(end 328.514202 -244.806724)
		(width 0.0889)
		(layer "In11.Cu")
		(net "M_F_CPU0_SA_CB<0>")
	)
	(arc
		(start 325.879714 -244.857016)
		(mid 325.968699 -244.846928)
		(end 326.052688 -244.815868)
		(width 0.0889)
		(layer "In11.Cu")
		(net "M_F_CPU0_SA_CB<0>")
	)
	(arc
		(start 328.514202 -244.806724)
		(mid 328.701146 -244.856979)
		(end 328.88809 -244.806724)
		(width 0.0889)
		(layer "In11.Cu")
		(net "M_F_CPU0_SA_CB<0>")
	)
	(arc
		(start 329.828144 -244.806724)
		(mid 330.1111 -244.730547)
		(end 330.394056 -244.806724)
		(width 0.0889)
		(layer "In11.Cu")
		(net "M_F_CPU0_SA_CB<0>")
	)
	(arc
		(start 328.88809 -244.806724)
		(mid 329.171046 -244.730547)
		(end 329.454002 -244.806724)
		(width 0.0889)
		(layer "In11.Cu")
		(net "M_F_CPU0_SA_CB<0>")
	)
	(arc
		(start 329.454002 -244.806724)
		(mid 329.636253 -244.857074)
		(end 329.819762 -244.81155)
		(width 0.0889)
		(layer "In11.Cu")
		(net "M_F_CPU0_SA_CB<0>")
	)
	(arc
		(start 330.402438 -244.81155)
		(mid 330.585946 -244.857044)
		(end 330.768198 -244.806724)
		(width 0.0889)
		(layer "In11.Cu")
		(net "M_F_CPU0_SA_CB<0>")
	)
	(arc
		(start 326.634856 -244.806724)
		(mid 326.815314 -244.857168)
		(end 326.997568 -244.813582)
		(width 0.0889)
		(layer "In11.Cu")
		(net "M_F_CPU0_SA_CB<0>")
	)
	(arc
		(start 330.768198 -244.806724)
		(mid 331.051154 -244.730547)
		(end 331.33411 -244.806724)
		(width 0.0889)
		(layer "In11.Cu")
		(net "M_F_CPU0_SA_CB<0>")
	)
	(arc
		(start 326.090534 -244.794024)
		(mid 326.364324 -244.730353)
		(end 326.634856 -244.806724)
		(width 0.0889)
		(layer "In11.Cu")
		(net "M_F_CPU0_SA_CB<0>")
	)
	(arc
		(start 327.009252 -244.806724)
		(mid 327.28493 -244.730594)
		(end 327.562464 -244.799612)
		(width 0.0889)
		(layer "In11.Cu")
		(net "M_F_CPU0_SA_CB<0>")
	)
	(arc
		(start 327.590658 -244.815868)
		(mid 327.77064 -244.856968)
		(end 327.94829 -244.806724)
		(width 0.0889)
		(layer "In11.Cu")
		(net "M_F_CPU0_SA_CB<0>")
	)
	(arc
		(start 331.342492 -244.81155)
		(mid 331.526 -244.857044)
		(end 331.708252 -244.806724)
		(width 0.0889)
		(layer "In11.Cu")
		(net "M_F_CPU0_SA_CB<0>")
	)
	(arc
		(start 331.708252 -244.806724)
		(mid 331.955965 -244.731504)
		(end 332.211172 -244.774974)
		(width 0.0889)
		(layer "In11.Cu")
		(net "M_F_CPU0_SA_CB<0>")
	)
	(segment
		(start 334.337914 -255.28016)
		(end 333.871062 -255.014222)
		(width 0.10668)
		(layer "F.Cu")
		(net "M_F_CPU0_SA_CA<6>")
	)
	(segment
		(start 308.587394 -254.710184)
		(end 308.597808 -254.69977)
		(width 0.14478)
		(layer "In11.Cu")
		(net "M_F_CPU0_SA_CA<6>")
	)
	(segment
		(start 328.984102 -255.336802)
		(end 328.992484 -255.341628)
		(width 0.0889)
		(layer "In11.Cu")
		(net "M_F_CPU0_SA_CA<6>")
	)
	(segment
		(start 271.147286 -254.084074)
		(end 271.147032 -254.314198)
		(width 0.14478)
		(layer "In11.Cu")
		(net "M_F_CPU0_SA_CA<6>")
	)
	(segment
		(start 324.622414 -255.58877)
		(end 325.102474 -255.58877)
		(width 0.0889)
		(layer "In11.Cu")
		(net "M_F_CPU0_SA_CA<6>")
	)
	(segment
		(start 323.941694 -256.04597)
		(end 324.165214 -256.04597)
		(width 0.0889)
		(layer "In11.Cu")
		(net "M_F_CPU0_SA_CA<6>")
	)
	(segment
		(start 325.403718 -255.287526)
		(end 326.128888 -255.287526)
		(width 0.0889)
		(layer "In11.Cu")
		(net "M_F_CPU0_SA_CA<6>")
	)
	(segment
		(start 271.147032 -254.314198)
		(end 270.89481 -254.56642)
		(width 0.14478)
		(layer "In11.Cu")
		(net "M_F_CPU0_SA_CA<6>")
	)
	(segment
		(start 325.102474 -255.58877)
		(end 325.403718 -255.287526)
		(width 0.0889)
		(layer "In11.Cu")
		(net "M_F_CPU0_SA_CA<6>")
	)
	(segment
		(start 332.16977 -255.341628)
		(end 332.178152 -255.336802)
		(width 0.0889)
		(layer "In11.Cu")
		(net "M_F_CPU0_SA_CA<6>")
	)
	(segment
		(start 333.621126 -255.305052)
		(end 333.717138 -255.279652)
		(width 0.0889)
		(layer "In11.Cu")
		(net "M_F_CPU0_SA_CA<6>")
	)
	(segment
		(start 328.409808 -255.341628)
		(end 328.41819 -255.336802)
		(width 0.0889)
		(layer "In11.Cu")
		(net "M_F_CPU0_SA_CA<6>")
	)
	(segment
		(start 332.744064 -255.336802)
		(end 332.752446 -255.341628)
		(width 0.0889)
		(layer "In11.Cu")
		(net "M_F_CPU0_SA_CA<6>")
	)
	(segment
		(start 326.471788 -255.37541)
		(end 326.548242 -255.330706)
		(width 0.0889)
		(layer "In11.Cu")
		(net "M_F_CPU0_SA_CA<6>")
	)
	(segment
		(start 269.648178 -252.584966)
		(end 270.359886 -253.296674)
		(width 0.14478)
		(layer "In11.Cu")
		(net "M_F_CPU0_SA_CA<6>")
	)
	(segment
		(start 324.165214 -256.04597)
		(end 324.622414 -255.58877)
		(width 0.0889)
		(layer "In11.Cu")
		(net "M_F_CPU0_SA_CA<6>")
	)
	(segment
		(start 271.28851 -254.960374)
		(end 271.5387 -254.710184)
		(width 0.14478)
		(layer "In11.Cu")
		(net "M_F_CPU0_SA_CA<6>")
	)
	(segment
		(start 333.717138 -255.279652)
		(end 333.871062 -255.014222)
		(width 0.0889)
		(layer "In11.Cu")
		(net "M_F_CPU0_SA_CA<6>")
	)
	(segment
		(start 270.753332 -253.920752)
		(end 270.983964 -253.920752)
		(width 0.14478)
		(layer "In11.Cu")
		(net "M_F_CPU0_SA_CA<6>")
	)
	(segment
		(start 270.270478 -254.17272)
		(end 270.50111 -254.172974)
		(width 0.14478)
		(layer "In11.Cu")
		(net "M_F_CPU0_SA_CA<6>")
	)
	(segment
		(start 270.10741 -254.009652)
		(end 270.270478 -254.17272)
		(width 0.14478)
		(layer "In11.Cu")
		(net "M_F_CPU0_SA_CA<6>")
	)
	(segment
		(start 270.89481 -254.56642)
		(end 270.89481 -254.797052)
		(width 0.14478)
		(layer "In11.Cu")
		(net "M_F_CPU0_SA_CA<6>")
	)
	(segment
		(start 271.5387 -254.710184)
		(end 308.587394 -254.710184)
		(width 0.14478)
		(layer "In11.Cu")
		(net "M_F_CPU0_SA_CA<6>")
	)
	(segment
		(start 270.50111 -254.172974)
		(end 270.753332 -253.920752)
		(width 0.14478)
		(layer "In11.Cu")
		(net "M_F_CPU0_SA_CA<6>")
	)
	(segment
		(start 270.983964 -253.920752)
		(end 271.147286 -254.084074)
		(width 0.14478)
		(layer "In11.Cu")
		(net "M_F_CPU0_SA_CA<6>")
	)
	(segment
		(start 328.033634 -255.330706)
		(end 328.044048 -255.336802)
		(width 0.0889)
		(layer "In11.Cu")
		(net "M_F_CPU0_SA_CA<6>")
	)
	(segment
		(start 270.10741 -253.77902)
		(end 270.10741 -254.009652)
		(width 0.14478)
		(layer "In11.Cu")
		(net "M_F_CPU0_SA_CA<6>")
	)
	(segment
		(start 326.128888 -255.287526)
		(end 326.17918 -255.337818)
		(width 0.0889)
		(layer "In11.Cu")
		(net "M_F_CPU0_SA_CA<6>")
	)
	(segment
		(start 270.359632 -253.526798)
		(end 270.10741 -253.77902)
		(width 0.14478)
		(layer "In11.Cu")
		(net "M_F_CPU0_SA_CA<6>")
	)
	(segment
		(start 270.359886 -253.296674)
		(end 270.359632 -253.526798)
		(width 0.14478)
		(layer "In11.Cu")
		(net "M_F_CPU0_SA_CA<6>")
	)
	(segment
		(start 271.057878 -254.96012)
		(end 271.28851 -254.960374)
		(width 0.14478)
		(layer "In11.Cu")
		(net "M_F_CPU0_SA_CA<6>")
	)
	(segment
		(start 321.00901 -256.04597)
		(end 323.941694 -256.04597)
		(width 0.14478)
		(layer "In11.Cu")
		(net "M_F_CPU0_SA_CA<6>")
	)
	(segment
		(start 308.597808 -254.69977)
		(end 319.66281 -254.69977)
		(width 0.14478)
		(layer "In11.Cu")
		(net "M_F_CPU0_SA_CA<6>")
	)
	(segment
		(start 331.229716 -255.341628)
		(end 331.238098 -255.336802)
		(width 0.0889)
		(layer "In11.Cu")
		(net "M_F_CPU0_SA_CA<6>")
	)
	(segment
		(start 319.66281 -254.69977)
		(end 321.00901 -256.04597)
		(width 0.14478)
		(layer "In11.Cu")
		(net "M_F_CPU0_SA_CA<6>")
	)
	(segment
		(start 270.89481 -254.797052)
		(end 271.057878 -254.96012)
		(width 0.14478)
		(layer "In11.Cu")
		(net "M_F_CPU0_SA_CA<6>")
	)
	(arc
		(start 328.41819 -255.336802)
		(mid 328.701146 -255.260625)
		(end 328.984102 -255.336802)
		(width 0.0889)
		(layer "In11.Cu")
		(net "M_F_CPU0_SA_CA<6>")
	)
	(arc
		(start 333.118206 -255.336802)
		(mid 333.365919 -255.261582)
		(end 333.621126 -255.305052)
		(width 0.0889)
		(layer "In11.Cu")
		(net "M_F_CPU0_SA_CA<6>")
	)
	(arc
		(start 332.178152 -255.336802)
		(mid 332.461108 -255.260625)
		(end 332.744064 -255.336802)
		(width 0.0889)
		(layer "In11.Cu")
		(net "M_F_CPU0_SA_CA<6>")
	)
	(arc
		(start 329.358244 -255.336802)
		(mid 329.6412 -255.260625)
		(end 329.924156 -255.336802)
		(width 0.0889)
		(layer "In11.Cu")
		(net "M_F_CPU0_SA_CA<6>")
	)
	(arc
		(start 331.80401 -255.336802)
		(mid 331.986261 -255.387152)
		(end 332.16977 -255.341628)
		(width 0.0889)
		(layer "In11.Cu")
		(net "M_F_CPU0_SA_CA<6>")
	)
	(arc
		(start 330.298044 -255.336802)
		(mid 330.581 -255.260625)
		(end 330.863956 -255.336802)
		(width 0.0889)
		(layer "In11.Cu")
		(net "M_F_CPU0_SA_CA<6>")
	)
	(arc
		(start 331.238098 -255.336802)
		(mid 331.521054 -255.260625)
		(end 331.80401 -255.336802)
		(width 0.0889)
		(layer "In11.Cu")
		(net "M_F_CPU0_SA_CA<6>")
	)
	(arc
		(start 332.752446 -255.341628)
		(mid 332.935954 -255.387122)
		(end 333.118206 -255.336802)
		(width 0.0889)
		(layer "In11.Cu")
		(net "M_F_CPU0_SA_CA<6>")
	)
	(arc
		(start 329.924156 -255.336802)
		(mid 330.1111 -255.387057)
		(end 330.298044 -255.336802)
		(width 0.0889)
		(layer "In11.Cu")
		(net "M_F_CPU0_SA_CA<6>")
	)
	(arc
		(start 328.044048 -255.336802)
		(mid 328.226299 -255.387152)
		(end 328.409808 -255.341628)
		(width 0.0889)
		(layer "In11.Cu")
		(net "M_F_CPU0_SA_CA<6>")
	)
	(arc
		(start 328.992484 -255.341628)
		(mid 329.175992 -255.387122)
		(end 329.358244 -255.336802)
		(width 0.0889)
		(layer "In11.Cu")
		(net "M_F_CPU0_SA_CA<6>")
	)
	(arc
		(start 326.548242 -255.330706)
		(mid 326.826674 -255.260608)
		(end 327.103486 -255.336802)
		(width 0.0889)
		(layer "In11.Cu")
		(net "M_F_CPU0_SA_CA<6>")
	)
	(arc
		(start 327.477882 -255.336802)
		(mid 327.754949 -255.260531)
		(end 328.033634 -255.330706)
		(width 0.0889)
		(layer "In11.Cu")
		(net "M_F_CPU0_SA_CA<6>")
	)
	(arc
		(start 330.863956 -255.336802)
		(mid 331.046207 -255.387152)
		(end 331.229716 -255.341628)
		(width 0.0889)
		(layer "In11.Cu")
		(net "M_F_CPU0_SA_CA<6>")
	)
	(arc
		(start 327.103486 -255.336802)
		(mid 327.290684 -255.387184)
		(end 327.477882 -255.336802)
		(width 0.0889)
		(layer "In11.Cu")
		(net "M_F_CPU0_SA_CA<6>")
	)
	(arc
		(start 326.17918 -255.337818)
		(mid 326.319077 -255.406547)
		(end 326.471788 -255.37541)
		(width 0.0889)
		(layer "In11.Cu")
		(net "M_F_CPU0_SA_CA<6>")
	)
	(segment
		(start 332.45806 -255.28016)
		(end 331.991208 -255.014222)
		(width 0.10668)
		(layer "F.Cu")
		(net "M_F_CPU0_SA_CA<5>")
	)
	(segment
		(start 327.465182 -254.684022)
		(end 327.478898 -254.691896)
		(width 0.0889)
		(layer "In11.Cu")
		(net "M_F_CPU0_SA_CA<5>")
	)
	(segment
		(start 325.397622 -254.767842)
		(end 325.882254 -254.767842)
		(width 0.0889)
		(layer "In11.Cu")
		(net "M_F_CPU0_SA_CA<5>")
	)
	(segment
		(start 324.124574 -255.56083)
		(end 324.586854 -255.09855)
		(width 0.0889)
		(layer "In11.Cu")
		(net "M_F_CPU0_SA_CA<5>")
	)
	(segment
		(start 325.066914 -255.09855)
		(end 325.397622 -254.767842)
		(width 0.0889)
		(layer "In11.Cu")
		(net "M_F_CPU0_SA_CA<5>")
	)
	(segment
		(start 332.12278 -254.66548)
		(end 332.145132 -254.748792)
		(width 0.0889)
		(layer "In11.Cu")
		(net "M_F_CPU0_SA_CA<5>")
	)
	(segment
		(start 328.984102 -254.691642)
		(end 328.992484 -254.686816)
		(width 0.0889)
		(layer "In11.Cu")
		(net "M_F_CPU0_SA_CA<5>")
	)
	(segment
		(start 326.164702 -254.691896)
		(end 326.184768 -254.680466)
		(width 0.0889)
		(layer "In11.Cu")
		(net "M_F_CPU0_SA_CA<5>")
	)
	(segment
		(start 271.709134 -253.860046)
		(end 307.873146 -253.860046)
		(width 0.14478)
		(layer "In11.Cu")
		(net "M_F_CPU0_SA_CA<5>")
	)
	(segment
		(start 324.586854 -255.09855)
		(end 325.066914 -255.09855)
		(width 0.0889)
		(layer "In11.Cu")
		(net "M_F_CPU0_SA_CA<5>")
	)
	(segment
		(start 319.851278 -254.24511)
		(end 321.166998 -255.56083)
		(width 0.14478)
		(layer "In11.Cu")
		(net "M_F_CPU0_SA_CA<5>")
	)
	(segment
		(start 331.229716 -254.686816)
		(end 331.238098 -254.691642)
		(width 0.0889)
		(layer "In11.Cu")
		(net "M_F_CPU0_SA_CA<5>")
	)
	(segment
		(start 328.409808 -254.686816)
		(end 328.41819 -254.691642)
		(width 0.0889)
		(layer "In11.Cu")
		(net "M_F_CPU0_SA_CA<5>")
	)
	(segment
		(start 327.478898 -254.691896)
		(end 327.490836 -254.698754)
		(width 0.0889)
		(layer "In11.Cu")
		(net "M_F_CPU0_SA_CA<5>")
	)
	(segment
		(start 308.25821 -254.24511)
		(end 319.851278 -254.24511)
		(width 0.14478)
		(layer "In11.Cu")
		(net "M_F_CPU0_SA_CA<5>")
	)
	(segment
		(start 332.145132 -254.748792)
		(end 331.991208 -255.014222)
		(width 0.0889)
		(layer "In11.Cu")
		(net "M_F_CPU0_SA_CA<5>")
	)
	(segment
		(start 321.166998 -255.56083)
		(end 323.931534 -255.56083)
		(width 0.14478)
		(layer "In11.Cu")
		(net "M_F_CPU0_SA_CA<5>")
	)
	(segment
		(start 327.08723 -254.70231)
		(end 327.105264 -254.691642)
		(width 0.0889)
		(layer "In11.Cu")
		(net "M_F_CPU0_SA_CA<5>")
	)
	(segment
		(start 265.54811 -251.735082)
		(end 265.973052 -252.160024)
		(width 0.14478)
		(layer "In11.Cu")
		(net "M_F_CPU0_SA_CA<5>")
	)
	(segment
		(start 270.009112 -252.160024)
		(end 271.709134 -253.860046)
		(width 0.14478)
		(layer "In11.Cu")
		(net "M_F_CPU0_SA_CA<5>")
	)
	(segment
		(start 323.931534 -255.56083)
		(end 324.124574 -255.56083)
		(width 0.0889)
		(layer "In11.Cu")
		(net "M_F_CPU0_SA_CA<5>")
	)
	(segment
		(start 265.973052 -252.160024)
		(end 270.009112 -252.160024)
		(width 0.14478)
		(layer "In11.Cu")
		(net "M_F_CPU0_SA_CA<5>")
	)
	(segment
		(start 307.873146 -253.860046)
		(end 308.25821 -254.24511)
		(width 0.14478)
		(layer "In11.Cu")
		(net "M_F_CPU0_SA_CA<5>")
	)
	(arc
		(start 327.490836 -254.698754)
		(mid 327.76837 -254.767735)
		(end 328.044048 -254.691642)
		(width 0.0889)
		(layer "In11.Cu")
		(net "M_F_CPU0_SA_CA<5>")
	)
	(arc
		(start 327.105264 -254.691642)
		(mid 327.284251 -254.641472)
		(end 327.465182 -254.684022)
		(width 0.0889)
		(layer "In11.Cu")
		(net "M_F_CPU0_SA_CA<5>")
	)
	(arc
		(start 329.924156 -254.691642)
		(mid 330.1111 -254.641387)
		(end 330.298044 -254.691642)
		(width 0.0889)
		(layer "In11.Cu")
		(net "M_F_CPU0_SA_CA<5>")
	)
	(arc
		(start 328.41819 -254.691642)
		(mid 328.701146 -254.767819)
		(end 328.984102 -254.691642)
		(width 0.0889)
		(layer "In11.Cu")
		(net "M_F_CPU0_SA_CA<5>")
	)
	(arc
		(start 325.882254 -254.767842)
		(mid 326.028502 -254.748537)
		(end 326.164702 -254.691896)
		(width 0.0889)
		(layer "In11.Cu")
		(net "M_F_CPU0_SA_CA<5>")
	)
	(arc
		(start 328.044048 -254.691642)
		(mid 328.226299 -254.641292)
		(end 328.409808 -254.686816)
		(width 0.0889)
		(layer "In11.Cu")
		(net "M_F_CPU0_SA_CA<5>")
	)
	(arc
		(start 331.238098 -254.691642)
		(mid 331.521054 -254.767819)
		(end 331.80401 -254.691642)
		(width 0.0889)
		(layer "In11.Cu")
		(net "M_F_CPU0_SA_CA<5>")
	)
	(arc
		(start 329.358244 -254.691642)
		(mid 329.6412 -254.767819)
		(end 329.924156 -254.691642)
		(width 0.0889)
		(layer "In11.Cu")
		(net "M_F_CPU0_SA_CA<5>")
	)
	(arc
		(start 328.992484 -254.686816)
		(mid 329.175992 -254.641322)
		(end 329.358244 -254.691642)
		(width 0.0889)
		(layer "In11.Cu")
		(net "M_F_CPU0_SA_CA<5>")
	)
	(arc
		(start 330.863956 -254.691642)
		(mid 331.046207 -254.641292)
		(end 331.229716 -254.686816)
		(width 0.0889)
		(layer "In11.Cu")
		(net "M_F_CPU0_SA_CA<5>")
	)
	(arc
		(start 331.80401 -254.691642)
		(mid 331.960448 -254.642671)
		(end 332.12278 -254.66548)
		(width 0.0889)
		(layer "In11.Cu")
		(net "M_F_CPU0_SA_CA<5>")
	)
	(arc
		(start 326.53859 -254.691642)
		(mid 326.811534 -254.768222)
		(end 327.08723 -254.70231)
		(width 0.0889)
		(layer "In11.Cu")
		(net "M_F_CPU0_SA_CA<5>")
	)
	(arc
		(start 330.298044 -254.691642)
		(mid 330.581 -254.767819)
		(end 330.863956 -254.691642)
		(width 0.0889)
		(layer "In11.Cu")
		(net "M_F_CPU0_SA_CA<5>")
	)
	(arc
		(start 326.184768 -254.680466)
		(mid 326.3631 -254.641369)
		(end 326.53859 -254.691642)
		(width 0.0889)
		(layer "In11.Cu")
		(net "M_F_CPU0_SA_CA<5>")
	)
	(segment
		(start 332.92796 -254.470154)
		(end 332.461108 -254.204216)
		(width 0.10668)
		(layer "F.Cu")
		(net "M_F_CPU0_SA_CA<4>")
	)
	(segment
		(start 286.336994 -253.39929)
		(end 286.500062 -253.236222)
		(width 0.14478)
		(layer "In11.Cu")
		(net "M_F_CPU0_SA_CA<4>")
	)
	(segment
		(start 275.040598 -253.238762)
		(end 275.203666 -253.40183)
		(width 0.14478)
		(layer "In11.Cu")
		(net "M_F_CPU0_SA_CA<4>")
	)
	(segment
		(start 274.87753 -253.009908)
		(end 275.040598 -253.172976)
		(width 0.14478)
		(layer "In11.Cu")
		(net "M_F_CPU0_SA_CA<4>")
	)
	(segment
		(start 275.203666 -253.40183)
		(end 275.434044 -253.40183)
		(width 0.14478)
		(layer "In11.Cu")
		(net "M_F_CPU0_SA_CA<4>")
	)
	(segment
		(start 274.321016 -253.40183)
		(end 274.484084 -253.238762)
		(width 0.14478)
		(layer "In11.Cu")
		(net "M_F_CPU0_SA_CA<4>")
	)
	(segment
		(start 273.92757 -253.238762)
		(end 274.090638 -253.40183)
		(width 0.14478)
		(layer "In11.Cu")
		(net "M_F_CPU0_SA_CA<4>")
	)
	(segment
		(start 278.049736 -253.009908)
		(end 278.212804 -253.172976)
		(width 0.14478)
		(layer "In11.Cu")
		(net "M_F_CPU0_SA_CA<4>")
	)
	(segment
		(start 274.647152 -253.009908)
		(end 274.87753 -253.009908)
		(width 0.14478)
		(layer "In11.Cu")
		(net "M_F_CPU0_SA_CA<4>")
	)
	(segment
		(start 326.997568 -254.533654)
		(end 327.009252 -254.526796)
		(width 0.0889)
		(layer "In11.Cu")
		(net "M_F_CPU0_SA_CA<4>")
	)
	(segment
		(start 278.932386 -253.009908)
		(end 279.162764 -253.009908)
		(width 0.14478)
		(layer "In11.Cu")
		(net "M_F_CPU0_SA_CA<4>")
	)
	(segment
		(start 279.162764 -253.009908)
		(end 279.325832 -253.172976)
		(width 0.14478)
		(layer "In11.Cu")
		(net "M_F_CPU0_SA_CA<4>")
	)
	(segment
		(start 329.819762 -254.531622)
		(end 329.828144 -254.526796)
		(width 0.0889)
		(layer "In11.Cu")
		(net "M_F_CPU0_SA_CA<4>")
	)
	(segment
		(start 274.090638 -253.40183)
		(end 274.321016 -253.40183)
		(width 0.14478)
		(layer "In11.Cu")
		(net "M_F_CPU0_SA_CA<4>")
	)
	(segment
		(start 285.78048 -253.009908)
		(end 285.943548 -253.172976)
		(width 0.14478)
		(layer "In11.Cu")
		(net "M_F_CPU0_SA_CA<4>")
	)
	(segment
		(start 327.562464 -254.519684)
		(end 327.574402 -254.526542)
		(width 0.0889)
		(layer "In11.Cu")
		(net "M_F_CPU0_SA_CA<4>")
	)
	(segment
		(start 321.355466 -255.10617)
		(end 323.918834 -255.10617)
		(width 0.14478)
		(layer "In11.Cu")
		(net "M_F_CPU0_SA_CA<4>")
	)
	(segment
		(start 275.597112 -253.172976)
		(end 275.76018 -253.009908)
		(width 0.14478)
		(layer "In11.Cu")
		(net "M_F_CPU0_SA_CA<4>")
	)
	(segment
		(start 286.500062 -253.172976)
		(end 286.66313 -253.009908)
		(width 0.14478)
		(layer "In11.Cu")
		(net "M_F_CPU0_SA_CA<4>")
	)
	(segment
		(start 279.4889 -253.40183)
		(end 279.719278 -253.40183)
		(width 0.14478)
		(layer "In11.Cu")
		(net "M_F_CPU0_SA_CA<4>")
	)
	(segment
		(start 283.451046 -253.172976)
		(end 283.614114 -253.009908)
		(width 0.14478)
		(layer "In11.Cu")
		(net "M_F_CPU0_SA_CA<4>")
	)
	(segment
		(start 279.325832 -253.238762)
		(end 279.4889 -253.40183)
		(width 0.14478)
		(layer "In11.Cu")
		(net "M_F_CPU0_SA_CA<4>")
	)
	(segment
		(start 283.287978 -253.40183)
		(end 283.451046 -253.238762)
		(width 0.14478)
		(layer "In11.Cu")
		(net "M_F_CPU0_SA_CA<4>")
	)
	(segment
		(start 331.33411 -254.526796)
		(end 331.342492 -254.531622)
		(width 0.0889)
		(layer "In11.Cu")
		(net "M_F_CPU0_SA_CA<4>")
	)
	(segment
		(start 271.773142 -253.009908)
		(end 273.764502 -253.009908)
		(width 0.14478)
		(layer "In11.Cu")
		(net "M_F_CPU0_SA_CA<4>")
	)
	(segment
		(start 278.212804 -253.172976)
		(end 278.212804 -253.238762)
		(width 0.14478)
		(layer "In11.Cu")
		(net "M_F_CPU0_SA_CA<4>")
	)
	(segment
		(start 283.614114 -253.009908)
		(end 285.78048 -253.009908)
		(width 0.14478)
		(layer "In11.Cu")
		(net "M_F_CPU0_SA_CA<4>")
	)
	(segment
		(start 274.484084 -253.172976)
		(end 274.647152 -253.009908)
		(width 0.14478)
		(layer "In11.Cu")
		(net "M_F_CPU0_SA_CA<4>")
	)
	(segment
		(start 274.484084 -253.238762)
		(end 274.484084 -253.172976)
		(width 0.14478)
		(layer "In11.Cu")
		(net "M_F_CPU0_SA_CA<4>")
	)
	(segment
		(start 275.76018 -253.009908)
		(end 278.049736 -253.009908)
		(width 0.14478)
		(layer "In11.Cu")
		(net "M_F_CPU0_SA_CA<4>")
	)
	(segment
		(start 282.894532 -253.172976)
		(end 282.894532 -253.238762)
		(width 0.14478)
		(layer "In11.Cu")
		(net "M_F_CPU0_SA_CA<4>")
	)
	(segment
		(start 281.781504 -253.172976)
		(end 281.781504 -253.238762)
		(width 0.14478)
		(layer "In11.Cu")
		(net "M_F_CPU0_SA_CA<4>")
	)
	(segment
		(start 324.129654 -255.10617)
		(end 324.381114 -254.85471)
		(width 0.0889)
		(layer "In11.Cu")
		(net "M_F_CPU0_SA_CA<4>")
	)
	(segment
		(start 278.212804 -253.238762)
		(end 278.375872 -253.40183)
		(width 0.14478)
		(layer "In11.Cu")
		(net "M_F_CPU0_SA_CA<4>")
	)
	(segment
		(start 278.769318 -253.172976)
		(end 278.932386 -253.009908)
		(width 0.14478)
		(layer "In11.Cu")
		(net "M_F_CPU0_SA_CA<4>")
	)
	(segment
		(start 325.237602 -254.577342)
		(end 325.882 -254.577342)
		(width 0.0889)
		(layer "In11.Cu")
		(net "M_F_CPU0_SA_CA<4>")
	)
	(segment
		(start 281.618436 -253.009908)
		(end 281.781504 -253.172976)
		(width 0.14478)
		(layer "In11.Cu")
		(net "M_F_CPU0_SA_CA<4>")
	)
	(segment
		(start 308.46649 -253.79045)
		(end 320.039746 -253.79045)
		(width 0.14478)
		(layer "In11.Cu")
		(net "M_F_CPU0_SA_CA<4>")
	)
	(segment
		(start 275.434044 -253.40183)
		(end 275.597112 -253.238762)
		(width 0.14478)
		(layer "In11.Cu")
		(net "M_F_CPU0_SA_CA<4>")
	)
	(segment
		(start 279.882346 -253.238762)
		(end 279.882346 -253.172976)
		(width 0.14478)
		(layer "In11.Cu")
		(net "M_F_CPU0_SA_CA<4>")
	)
	(segment
		(start 278.769318 -253.238762)
		(end 278.769318 -253.172976)
		(width 0.14478)
		(layer "In11.Cu")
		(net "M_F_CPU0_SA_CA<4>")
	)
	(segment
		(start 282.17495 -253.40183)
		(end 282.338018 -253.238762)
		(width 0.14478)
		(layer "In11.Cu")
		(net "M_F_CPU0_SA_CA<4>")
	)
	(segment
		(start 281.781504 -253.238762)
		(end 281.944572 -253.40183)
		(width 0.14478)
		(layer "In11.Cu")
		(net "M_F_CPU0_SA_CA<4>")
	)
	(segment
		(start 282.501086 -253.009908)
		(end 282.731464 -253.009908)
		(width 0.14478)
		(layer "In11.Cu")
		(net "M_F_CPU0_SA_CA<4>")
	)
	(segment
		(start 273.92757 -253.172976)
		(end 273.92757 -253.238762)
		(width 0.14478)
		(layer "In11.Cu")
		(net "M_F_CPU0_SA_CA<4>")
	)
	(segment
		(start 275.040598 -253.172976)
		(end 275.040598 -253.238762)
		(width 0.14478)
		(layer "In11.Cu")
		(net "M_F_CPU0_SA_CA<4>")
	)
	(segment
		(start 278.375872 -253.40183)
		(end 278.60625 -253.40183)
		(width 0.14478)
		(layer "In11.Cu")
		(net "M_F_CPU0_SA_CA<4>")
	)
	(segment
		(start 282.338018 -253.238762)
		(end 282.338018 -253.172976)
		(width 0.14478)
		(layer "In11.Cu")
		(net "M_F_CPU0_SA_CA<4>")
	)
	(segment
		(start 330.394056 -254.526796)
		(end 330.402438 -254.531622)
		(width 0.0889)
		(layer "In11.Cu")
		(net "M_F_CPU0_SA_CA<4>")
	)
	(segment
		(start 275.597112 -253.238762)
		(end 275.597112 -253.172976)
		(width 0.14478)
		(layer "In11.Cu")
		(net "M_F_CPU0_SA_CA<4>")
	)
	(segment
		(start 273.764502 -253.009908)
		(end 273.92757 -253.172976)
		(width 0.14478)
		(layer "In11.Cu")
		(net "M_F_CPU0_SA_CA<4>")
	)
	(segment
		(start 286.500062 -253.236222)
		(end 286.500062 -253.172976)
		(width 0.14478)
		(layer "In11.Cu")
		(net "M_F_CPU0_SA_CA<4>")
	)
	(segment
		(start 323.918834 -255.10617)
		(end 324.129654 -255.10617)
		(width 0.0889)
		(layer "In11.Cu")
		(net "M_F_CPU0_SA_CA<4>")
	)
	(segment
		(start 286.106616 -253.39929)
		(end 286.336994 -253.39929)
		(width 0.14478)
		(layer "In11.Cu")
		(net "M_F_CPU0_SA_CA<4>")
	)
	(segment
		(start 285.943548 -253.172976)
		(end 285.943548 -253.236222)
		(width 0.14478)
		(layer "In11.Cu")
		(net "M_F_CPU0_SA_CA<4>")
	)
	(segment
		(start 283.0576 -253.40183)
		(end 283.287978 -253.40183)
		(width 0.14478)
		(layer "In11.Cu")
		(net "M_F_CPU0_SA_CA<4>")
	)
	(segment
		(start 283.451046 -253.238762)
		(end 283.451046 -253.172976)
		(width 0.14478)
		(layer "In11.Cu")
		(net "M_F_CPU0_SA_CA<4>")
	)
	(segment
		(start 285.943548 -253.236222)
		(end 286.106616 -253.39929)
		(width 0.14478)
		(layer "In11.Cu")
		(net "M_F_CPU0_SA_CA<4>")
	)
	(segment
		(start 332.307184 -254.469646)
		(end 332.461108 -254.204216)
		(width 0.0889)
		(layer "In11.Cu")
		(net "M_F_CPU0_SA_CA<4>")
	)
	(segment
		(start 279.882346 -253.172976)
		(end 280.045414 -253.009908)
		(width 0.14478)
		(layer "In11.Cu")
		(net "M_F_CPU0_SA_CA<4>")
	)
	(segment
		(start 332.211172 -254.495046)
		(end 332.307184 -254.469646)
		(width 0.0889)
		(layer "In11.Cu")
		(net "M_F_CPU0_SA_CA<4>")
	)
	(segment
		(start 282.894532 -253.238762)
		(end 283.0576 -253.40183)
		(width 0.14478)
		(layer "In11.Cu")
		(net "M_F_CPU0_SA_CA<4>")
	)
	(segment
		(start 282.731464 -253.009908)
		(end 282.894532 -253.172976)
		(width 0.14478)
		(layer "In11.Cu")
		(net "M_F_CPU0_SA_CA<4>")
	)
	(segment
		(start 280.045414 -253.009908)
		(end 281.618436 -253.009908)
		(width 0.14478)
		(layer "In11.Cu")
		(net "M_F_CPU0_SA_CA<4>")
	)
	(segment
		(start 279.719278 -253.40183)
		(end 279.882346 -253.238762)
		(width 0.14478)
		(layer "In11.Cu")
		(net "M_F_CPU0_SA_CA<4>")
	)
	(segment
		(start 269.648178 -250.884944)
		(end 271.773142 -253.009908)
		(width 0.14478)
		(layer "In11.Cu")
		(net "M_F_CPU0_SA_CA<4>")
	)
	(segment
		(start 281.944572 -253.40183)
		(end 282.17495 -253.40183)
		(width 0.14478)
		(layer "In11.Cu")
		(net "M_F_CPU0_SA_CA<4>")
	)
	(segment
		(start 324.960234 -254.85471)
		(end 325.237602 -254.577342)
		(width 0.0889)
		(layer "In11.Cu")
		(net "M_F_CPU0_SA_CA<4>")
	)
	(segment
		(start 286.66313 -253.009908)
		(end 307.685948 -253.009908)
		(width 0.14478)
		(layer "In11.Cu")
		(net "M_F_CPU0_SA_CA<4>")
	)
	(segment
		(start 326.068944 -254.526542)
		(end 326.090534 -254.514096)
		(width 0.0889)
		(layer "In11.Cu")
		(net "M_F_CPU0_SA_CA<4>")
	)
	(segment
		(start 279.325832 -253.172976)
		(end 279.325832 -253.238762)
		(width 0.14478)
		(layer "In11.Cu")
		(net "M_F_CPU0_SA_CA<4>")
	)
	(segment
		(start 320.039746 -253.79045)
		(end 321.355466 -255.10617)
		(width 0.14478)
		(layer "In11.Cu")
		(net "M_F_CPU0_SA_CA<4>")
	)
	(segment
		(start 307.685948 -253.009908)
		(end 308.46649 -253.79045)
		(width 0.14478)
		(layer "In11.Cu")
		(net "M_F_CPU0_SA_CA<4>")
	)
	(segment
		(start 324.381114 -254.85471)
		(end 324.960234 -254.85471)
		(width 0.0889)
		(layer "In11.Cu")
		(net "M_F_CPU0_SA_CA<4>")
	)
	(segment
		(start 278.60625 -253.40183)
		(end 278.769318 -253.238762)
		(width 0.14478)
		(layer "In11.Cu")
		(net "M_F_CPU0_SA_CA<4>")
	)
	(segment
		(start 327.574402 -254.526542)
		(end 327.590658 -254.53594)
		(width 0.0889)
		(layer "In11.Cu")
		(net "M_F_CPU0_SA_CA<4>")
	)
	(segment
		(start 282.338018 -253.172976)
		(end 282.501086 -253.009908)
		(width 0.14478)
		(layer "In11.Cu")
		(net "M_F_CPU0_SA_CA<4>")
	)
	(arc
		(start 326.634856 -254.526796)
		(mid 326.815314 -254.57724)
		(end 326.997568 -254.533654)
		(width 0.0889)
		(layer "In11.Cu")
		(net "M_F_CPU0_SA_CA<4>")
	)
	(arc
		(start 327.009252 -254.526796)
		(mid 327.28493 -254.450666)
		(end 327.562464 -254.519684)
		(width 0.0889)
		(layer "In11.Cu")
		(net "M_F_CPU0_SA_CA<4>")
	)
	(arc
		(start 328.514202 -254.526796)
		(mid 328.701146 -254.577051)
		(end 328.88809 -254.526796)
		(width 0.0889)
		(layer "In11.Cu")
		(net "M_F_CPU0_SA_CA<4>")
	)
	(arc
		(start 330.768198 -254.526796)
		(mid 331.051154 -254.450619)
		(end 331.33411 -254.526796)
		(width 0.0889)
		(layer "In11.Cu")
		(net "M_F_CPU0_SA_CA<4>")
	)
	(arc
		(start 331.342492 -254.531622)
		(mid 331.526 -254.577116)
		(end 331.708252 -254.526796)
		(width 0.0889)
		(layer "In11.Cu")
		(net "M_F_CPU0_SA_CA<4>")
	)
	(arc
		(start 330.402438 -254.531622)
		(mid 330.585946 -254.577116)
		(end 330.768198 -254.526796)
		(width 0.0889)
		(layer "In11.Cu")
		(net "M_F_CPU0_SA_CA<4>")
	)
	(arc
		(start 331.708252 -254.526796)
		(mid 331.955965 -254.451576)
		(end 332.211172 -254.495046)
		(width 0.0889)
		(layer "In11.Cu")
		(net "M_F_CPU0_SA_CA<4>")
	)
	(arc
		(start 329.454002 -254.526796)
		(mid 329.636253 -254.577146)
		(end 329.819762 -254.531622)
		(width 0.0889)
		(layer "In11.Cu")
		(net "M_F_CPU0_SA_CA<4>")
	)
	(arc
		(start 327.590658 -254.53594)
		(mid 327.77064 -254.57704)
		(end 327.94829 -254.526796)
		(width 0.0889)
		(layer "In11.Cu")
		(net "M_F_CPU0_SA_CA<4>")
	)
	(arc
		(start 327.94829 -254.526796)
		(mid 328.231246 -254.450619)
		(end 328.514202 -254.526796)
		(width 0.0889)
		(layer "In11.Cu")
		(net "M_F_CPU0_SA_CA<4>")
	)
	(arc
		(start 326.090534 -254.514096)
		(mid 326.364324 -254.450425)
		(end 326.634856 -254.526796)
		(width 0.0889)
		(layer "In11.Cu")
		(net "M_F_CPU0_SA_CA<4>")
	)
	(arc
		(start 325.882 -254.577342)
		(mid 325.978818 -254.564271)
		(end 326.068944 -254.526542)
		(width 0.0889)
		(layer "In11.Cu")
		(net "M_F_CPU0_SA_CA<4>")
	)
	(arc
		(start 329.828144 -254.526796)
		(mid 330.1111 -254.450619)
		(end 330.394056 -254.526796)
		(width 0.0889)
		(layer "In11.Cu")
		(net "M_F_CPU0_SA_CA<4>")
	)
	(arc
		(start 328.88809 -254.526796)
		(mid 329.171046 -254.450619)
		(end 329.454002 -254.526796)
		(width 0.0889)
		(layer "In11.Cu")
		(net "M_F_CPU0_SA_CA<4>")
	)
	(segment
		(start 333.868014 -254.470154)
		(end 333.401162 -254.204216)
		(width 0.10668)
		(layer "F.Cu")
		(net "M_F_CPU0_SA_CA<3>")
	)
	(segment
		(start 329.819762 -253.87681)
		(end 329.828144 -253.881636)
		(width 0.0889)
		(layer "In11.Cu")
		(net "M_F_CPU0_SA_CA<3>")
	)
	(segment
		(start 324.284594 -254.47879)
		(end 324.284594 -254.38735)
		(width 0.0889)
		(layer "In11.Cu")
		(net "M_F_CPU0_SA_CA<3>")
	)
	(segment
		(start 323.921374 -254.65151)
		(end 324.111874 -254.65151)
		(width 0.0889)
		(layer "In11.Cu")
		(net "M_F_CPU0_SA_CA<3>")
	)
	(segment
		(start 333.555086 -253.938786)
		(end 333.401162 -254.204216)
		(width 0.0889)
		(layer "In11.Cu")
		(net "M_F_CPU0_SA_CA<3>")
	)
	(segment
		(start 270.009112 -250.460002)
		(end 271.709134 -252.160024)
		(width 0.14478)
		(layer "In11.Cu")
		(net "M_F_CPU0_SA_CA<3>")
	)
	(segment
		(start 324.607174 -254.06477)
		(end 325.510398 -254.06477)
		(width 0.0889)
		(layer "In11.Cu")
		(net "M_F_CPU0_SA_CA<3>")
	)
	(segment
		(start 330.394056 -253.881636)
		(end 330.402438 -253.87681)
		(width 0.0889)
		(layer "In11.Cu")
		(net "M_F_CPU0_SA_CA<3>")
	)
	(segment
		(start 327.007728 -253.881636)
		(end 327.018142 -253.887732)
		(width 0.0889)
		(layer "In11.Cu")
		(net "M_F_CPU0_SA_CA<3>")
	)
	(segment
		(start 333.532734 -253.855474)
		(end 333.555086 -253.938786)
		(width 0.0889)
		(layer "In11.Cu")
		(net "M_F_CPU0_SA_CA<3>")
	)
	(segment
		(start 326.619108 -253.890272)
		(end 326.63384 -253.881636)
		(width 0.0889)
		(layer "In11.Cu")
		(net "M_F_CPU0_SA_CA<3>")
	)
	(segment
		(start 265.973052 -250.460002)
		(end 270.009112 -250.460002)
		(width 0.14478)
		(layer "In11.Cu")
		(net "M_F_CPU0_SA_CA<3>")
	)
	(segment
		(start 325.510398 -254.06477)
		(end 325.693532 -253.881636)
		(width 0.0889)
		(layer "In11.Cu")
		(net "M_F_CPU0_SA_CA<3>")
	)
	(segment
		(start 326.63384 -253.881636)
		(end 326.645524 -253.874778)
		(width 0.0889)
		(layer "In11.Cu")
		(net "M_F_CPU0_SA_CA<3>")
	)
	(segment
		(start 320.228214 -253.33579)
		(end 321.543934 -254.65151)
		(width 0.14478)
		(layer "In11.Cu")
		(net "M_F_CPU0_SA_CA<3>")
	)
	(segment
		(start 324.284594 -254.38735)
		(end 324.607174 -254.06477)
		(width 0.0889)
		(layer "In11.Cu")
		(net "M_F_CPU0_SA_CA<3>")
	)
	(segment
		(start 265.54811 -250.03506)
		(end 265.973052 -250.460002)
		(width 0.14478)
		(layer "In11.Cu")
		(net "M_F_CPU0_SA_CA<3>")
	)
	(segment
		(start 308.676802 -253.33579)
		(end 320.228214 -253.33579)
		(width 0.14478)
		(layer "In11.Cu")
		(net "M_F_CPU0_SA_CA<3>")
	)
	(segment
		(start 331.33411 -253.881636)
		(end 331.342492 -253.87681)
		(width 0.0889)
		(layer "In11.Cu")
		(net "M_F_CPU0_SA_CA<3>")
	)
	(segment
		(start 325.693532 -253.881636)
		(end 325.705216 -253.874778)
		(width 0.0889)
		(layer "In11.Cu")
		(net "M_F_CPU0_SA_CA<3>")
	)
	(segment
		(start 321.543934 -254.65151)
		(end 323.921374 -254.65151)
		(width 0.14478)
		(layer "In11.Cu")
		(net "M_F_CPU0_SA_CA<3>")
	)
	(segment
		(start 271.709134 -252.160024)
		(end 307.501036 -252.160024)
		(width 0.14478)
		(layer "In11.Cu")
		(net "M_F_CPU0_SA_CA<3>")
	)
	(segment
		(start 324.111874 -254.65151)
		(end 324.284594 -254.47879)
		(width 0.0889)
		(layer "In11.Cu")
		(net "M_F_CPU0_SA_CA<3>")
	)
	(segment
		(start 307.501036 -252.160024)
		(end 308.676802 -253.33579)
		(width 0.14478)
		(layer "In11.Cu")
		(net "M_F_CPU0_SA_CA<3>")
	)
	(arc
		(start 329.828144 -253.881636)
		(mid 330.1111 -253.957813)
		(end 330.394056 -253.881636)
		(width 0.0889)
		(layer "In11.Cu")
		(net "M_F_CPU0_SA_CA<3>")
	)
	(arc
		(start 332.274164 -253.881636)
		(mid 332.461108 -253.831381)
		(end 332.648052 -253.881636)
		(width 0.0889)
		(layer "In11.Cu")
		(net "M_F_CPU0_SA_CA<3>")
	)
	(arc
		(start 330.402438 -253.87681)
		(mid 330.585946 -253.831316)
		(end 330.768198 -253.881636)
		(width 0.0889)
		(layer "In11.Cu")
		(net "M_F_CPU0_SA_CA<3>")
	)
	(arc
		(start 331.708252 -253.881636)
		(mid 331.991208 -253.957813)
		(end 332.274164 -253.881636)
		(width 0.0889)
		(layer "In11.Cu")
		(net "M_F_CPU0_SA_CA<3>")
	)
	(arc
		(start 327.94829 -253.881636)
		(mid 328.231246 -253.957813)
		(end 328.514202 -253.881636)
		(width 0.0889)
		(layer "In11.Cu")
		(net "M_F_CPU0_SA_CA<3>")
	)
	(arc
		(start 328.514202 -253.881636)
		(mid 328.701146 -253.831381)
		(end 328.88809 -253.881636)
		(width 0.0889)
		(layer "In11.Cu")
		(net "M_F_CPU0_SA_CA<3>")
	)
	(arc
		(start 327.018142 -253.887732)
		(mid 327.296828 -253.957952)
		(end 327.573894 -253.881636)
		(width 0.0889)
		(layer "In11.Cu")
		(net "M_F_CPU0_SA_CA<3>")
	)
	(arc
		(start 326.067928 -253.881636)
		(mid 326.34238 -253.957872)
		(end 326.619108 -253.890272)
		(width 0.0889)
		(layer "In11.Cu")
		(net "M_F_CPU0_SA_CA<3>")
	)
	(arc
		(start 326.645524 -253.874778)
		(mid 326.827525 -253.831245)
		(end 327.007728 -253.881636)
		(width 0.0889)
		(layer "In11.Cu")
		(net "M_F_CPU0_SA_CA<3>")
	)
	(arc
		(start 325.705216 -253.874778)
		(mid 325.887471 -253.831125)
		(end 326.067928 -253.881636)
		(width 0.0889)
		(layer "In11.Cu")
		(net "M_F_CPU0_SA_CA<3>")
	)
	(arc
		(start 329.454002 -253.881636)
		(mid 329.636253 -253.831286)
		(end 329.819762 -253.87681)
		(width 0.0889)
		(layer "In11.Cu")
		(net "M_F_CPU0_SA_CA<3>")
	)
	(arc
		(start 333.213964 -253.881636)
		(mid 333.370402 -253.832665)
		(end 333.532734 -253.855474)
		(width 0.0889)
		(layer "In11.Cu")
		(net "M_F_CPU0_SA_CA<3>")
	)
	(arc
		(start 327.573894 -253.881636)
		(mid 327.761092 -253.831254)
		(end 327.94829 -253.881636)
		(width 0.0889)
		(layer "In11.Cu")
		(net "M_F_CPU0_SA_CA<3>")
	)
	(arc
		(start 332.648052 -253.881636)
		(mid 332.931008 -253.957813)
		(end 333.213964 -253.881636)
		(width 0.0889)
		(layer "In11.Cu")
		(net "M_F_CPU0_SA_CA<3>")
	)
	(arc
		(start 330.768198 -253.881636)
		(mid 331.051154 -253.957813)
		(end 331.33411 -253.881636)
		(width 0.0889)
		(layer "In11.Cu")
		(net "M_F_CPU0_SA_CA<3>")
	)
	(arc
		(start 331.342492 -253.87681)
		(mid 331.526 -253.831316)
		(end 331.708252 -253.881636)
		(width 0.0889)
		(layer "In11.Cu")
		(net "M_F_CPU0_SA_CA<3>")
	)
	(arc
		(start 328.88809 -253.881636)
		(mid 329.171046 -253.957813)
		(end 329.454002 -253.881636)
		(width 0.0889)
		(layer "In11.Cu")
		(net "M_F_CPU0_SA_CA<3>")
	)
	(segment
		(start 334.337914 -253.660148)
		(end 333.871062 -253.39421)
		(width 0.10668)
		(layer "F.Cu")
		(net "M_F_CPU0_SA_CA<2>")
	)
	(segment
		(start 325.171054 -253.71679)
		(end 325.59752 -253.71679)
		(width 0.0889)
		(layer "In11.Cu")
		(net "M_F_CPU0_SA_CA<2>")
	)
	(segment
		(start 325.59752 -253.71679)
		(end 325.607934 -253.710694)
		(width 0.0889)
		(layer "In11.Cu")
		(net "M_F_CPU0_SA_CA<2>")
	)
	(segment
		(start 333.717138 -253.65964)
		(end 333.871062 -253.39421)
		(width 0.0889)
		(layer "In11.Cu")
		(net "M_F_CPU0_SA_CA<2>")
	)
	(segment
		(start 328.409808 -253.721616)
		(end 328.41819 -253.71679)
		(width 0.0889)
		(layer "In11.Cu")
		(net "M_F_CPU0_SA_CA<2>")
	)
	(segment
		(start 275.704808 -251.472954)
		(end 275.867876 -251.309886)
		(width 0.14478)
		(layer "In11.Cu")
		(net "M_F_CPU0_SA_CA<2>")
	)
	(segment
		(start 274.59178 -251.539502)
		(end 274.59178 -251.472954)
		(width 0.14478)
		(layer "In11.Cu")
		(net "M_F_CPU0_SA_CA<2>")
	)
	(segment
		(start 326.537828 -253.71679)
		(end 326.548242 -253.710694)
		(width 0.0889)
		(layer "In11.Cu")
		(net "M_F_CPU0_SA_CA<2>")
	)
	(segment
		(start 274.198334 -251.70257)
		(end 274.428712 -251.70257)
		(width 0.14478)
		(layer "In11.Cu")
		(net "M_F_CPU0_SA_CA<2>")
	)
	(segment
		(start 269.648178 -249.185176)
		(end 271.772888 -251.309886)
		(width 0.14478)
		(layer "In11.Cu")
		(net "M_F_CPU0_SA_CA<2>")
	)
	(segment
		(start 331.229716 -253.721616)
		(end 331.238098 -253.71679)
		(width 0.0889)
		(layer "In11.Cu")
		(net "M_F_CPU0_SA_CA<2>")
	)
	(segment
		(start 274.985226 -251.309886)
		(end 275.148294 -251.472954)
		(width 0.14478)
		(layer "In11.Cu")
		(net "M_F_CPU0_SA_CA<2>")
	)
	(segment
		(start 324.500494 -253.82093)
		(end 325.066914 -253.82093)
		(width 0.0889)
		(layer "In11.Cu")
		(net "M_F_CPU0_SA_CA<2>")
	)
	(segment
		(start 324.124574 -254.19685)
		(end 324.500494 -253.82093)
		(width 0.0889)
		(layer "In11.Cu")
		(net "M_F_CPU0_SA_CA<2>")
	)
	(segment
		(start 278.772874 -251.70257)
		(end 279.003252 -251.70257)
		(width 0.14478)
		(layer "In11.Cu")
		(net "M_F_CPU0_SA_CA<2>")
	)
	(segment
		(start 274.428712 -251.70257)
		(end 274.59178 -251.539502)
		(width 0.14478)
		(layer "In11.Cu")
		(net "M_F_CPU0_SA_CA<2>")
	)
	(segment
		(start 275.148294 -251.539502)
		(end 275.311362 -251.70257)
		(width 0.14478)
		(layer "In11.Cu")
		(net "M_F_CPU0_SA_CA<2>")
	)
	(segment
		(start 275.54174 -251.70257)
		(end 275.704808 -251.539502)
		(width 0.14478)
		(layer "In11.Cu")
		(net "M_F_CPU0_SA_CA<2>")
	)
	(segment
		(start 278.446738 -251.309886)
		(end 278.609806 -251.472954)
		(width 0.14478)
		(layer "In11.Cu")
		(net "M_F_CPU0_SA_CA<2>")
	)
	(segment
		(start 275.867876 -251.309886)
		(end 278.446738 -251.309886)
		(width 0.14478)
		(layer "In11.Cu")
		(net "M_F_CPU0_SA_CA<2>")
	)
	(segment
		(start 275.148294 -251.472954)
		(end 275.148294 -251.539502)
		(width 0.14478)
		(layer "In11.Cu")
		(net "M_F_CPU0_SA_CA<2>")
	)
	(segment
		(start 274.59178 -251.472954)
		(end 274.754848 -251.309886)
		(width 0.14478)
		(layer "In11.Cu")
		(net "M_F_CPU0_SA_CA<2>")
	)
	(segment
		(start 325.066914 -253.82093)
		(end 325.171054 -253.71679)
		(width 0.0889)
		(layer "In11.Cu")
		(net "M_F_CPU0_SA_CA<2>")
	)
	(segment
		(start 328.033634 -253.710694)
		(end 328.044048 -253.71679)
		(width 0.0889)
		(layer "In11.Cu")
		(net "M_F_CPU0_SA_CA<2>")
	)
	(segment
		(start 278.609806 -251.472954)
		(end 278.609806 -251.539502)
		(width 0.14478)
		(layer "In11.Cu")
		(net "M_F_CPU0_SA_CA<2>")
	)
	(segment
		(start 307.579014 -251.309886)
		(end 309.150258 -252.88113)
		(width 0.14478)
		(layer "In11.Cu")
		(net "M_F_CPU0_SA_CA<2>")
	)
	(segment
		(start 328.984102 -253.71679)
		(end 328.992484 -253.721616)
		(width 0.0889)
		(layer "In11.Cu")
		(net "M_F_CPU0_SA_CA<2>")
	)
	(segment
		(start 333.621126 -253.68504)
		(end 333.717138 -253.65964)
		(width 0.0889)
		(layer "In11.Cu")
		(net "M_F_CPU0_SA_CA<2>")
	)
	(segment
		(start 275.311362 -251.70257)
		(end 275.54174 -251.70257)
		(width 0.14478)
		(layer "In11.Cu")
		(net "M_F_CPU0_SA_CA<2>")
	)
	(segment
		(start 275.704808 -251.539502)
		(end 275.704808 -251.472954)
		(width 0.14478)
		(layer "In11.Cu")
		(net "M_F_CPU0_SA_CA<2>")
	)
	(segment
		(start 279.16632 -251.472954)
		(end 279.329388 -251.309886)
		(width 0.14478)
		(layer "In11.Cu")
		(net "M_F_CPU0_SA_CA<2>")
	)
	(segment
		(start 274.035266 -251.472954)
		(end 274.035266 -251.539502)
		(width 0.14478)
		(layer "In11.Cu")
		(net "M_F_CPU0_SA_CA<2>")
	)
	(segment
		(start 332.744064 -253.71679)
		(end 332.752446 -253.721616)
		(width 0.0889)
		(layer "In11.Cu")
		(net "M_F_CPU0_SA_CA<2>")
	)
	(segment
		(start 273.872198 -251.309886)
		(end 274.035266 -251.472954)
		(width 0.14478)
		(layer "In11.Cu")
		(net "M_F_CPU0_SA_CA<2>")
	)
	(segment
		(start 321.732402 -254.19685)
		(end 323.918834 -254.19685)
		(width 0.14478)
		(layer "In11.Cu")
		(net "M_F_CPU0_SA_CA<2>")
	)
	(segment
		(start 323.918834 -254.19685)
		(end 324.124574 -254.19685)
		(width 0.0889)
		(layer "In11.Cu")
		(net "M_F_CPU0_SA_CA<2>")
	)
	(segment
		(start 326.52335 -253.725172)
		(end 326.537828 -253.71679)
		(width 0.0889)
		(layer "In11.Cu")
		(net "M_F_CPU0_SA_CA<2>")
	)
	(segment
		(start 274.754848 -251.309886)
		(end 274.985226 -251.309886)
		(width 0.14478)
		(layer "In11.Cu")
		(net "M_F_CPU0_SA_CA<2>")
	)
	(segment
		(start 279.16632 -251.539502)
		(end 279.16632 -251.472954)
		(width 0.14478)
		(layer "In11.Cu")
		(net "M_F_CPU0_SA_CA<2>")
	)
	(segment
		(start 332.16977 -253.721616)
		(end 332.178152 -253.71679)
		(width 0.0889)
		(layer "In11.Cu")
		(net "M_F_CPU0_SA_CA<2>")
	)
	(segment
		(start 320.416682 -252.88113)
		(end 321.732402 -254.19685)
		(width 0.14478)
		(layer "In11.Cu")
		(net "M_F_CPU0_SA_CA<2>")
	)
	(segment
		(start 309.150258 -252.88113)
		(end 320.416682 -252.88113)
		(width 0.14478)
		(layer "In11.Cu")
		(net "M_F_CPU0_SA_CA<2>")
	)
	(segment
		(start 271.772888 -251.309886)
		(end 273.872198 -251.309886)
		(width 0.14478)
		(layer "In11.Cu")
		(net "M_F_CPU0_SA_CA<2>")
	)
	(segment
		(start 279.329388 -251.309886)
		(end 307.579014 -251.309886)
		(width 0.14478)
		(layer "In11.Cu")
		(net "M_F_CPU0_SA_CA<2>")
	)
	(segment
		(start 278.609806 -251.539502)
		(end 278.772874 -251.70257)
		(width 0.14478)
		(layer "In11.Cu")
		(net "M_F_CPU0_SA_CA<2>")
	)
	(segment
		(start 274.035266 -251.539502)
		(end 274.198334 -251.70257)
		(width 0.14478)
		(layer "In11.Cu")
		(net "M_F_CPU0_SA_CA<2>")
	)
	(segment
		(start 279.003252 -251.70257)
		(end 279.16632 -251.539502)
		(width 0.14478)
		(layer "In11.Cu")
		(net "M_F_CPU0_SA_CA<2>")
	)
	(arc
		(start 328.41819 -253.71679)
		(mid 328.701146 -253.640613)
		(end 328.984102 -253.71679)
		(width 0.0889)
		(layer "In11.Cu")
		(net "M_F_CPU0_SA_CA<2>")
	)
	(arc
		(start 328.992484 -253.721616)
		(mid 329.175992 -253.76711)
		(end 329.358244 -253.71679)
		(width 0.0889)
		(layer "In11.Cu")
		(net "M_F_CPU0_SA_CA<2>")
	)
	(arc
		(start 327.477882 -253.71679)
		(mid 327.754949 -253.640519)
		(end 328.033634 -253.710694)
		(width 0.0889)
		(layer "In11.Cu")
		(net "M_F_CPU0_SA_CA<2>")
	)
	(arc
		(start 325.607934 -253.710694)
		(mid 325.88662 -253.640474)
		(end 326.163686 -253.71679)
		(width 0.0889)
		(layer "In11.Cu")
		(net "M_F_CPU0_SA_CA<2>")
	)
	(arc
		(start 330.863956 -253.71679)
		(mid 331.046207 -253.76714)
		(end 331.229716 -253.721616)
		(width 0.0889)
		(layer "In11.Cu")
		(net "M_F_CPU0_SA_CA<2>")
	)
	(arc
		(start 330.298044 -253.71679)
		(mid 330.581 -253.640613)
		(end 330.863956 -253.71679)
		(width 0.0889)
		(layer "In11.Cu")
		(net "M_F_CPU0_SA_CA<2>")
	)
	(arc
		(start 328.044048 -253.71679)
		(mid 328.226299 -253.76714)
		(end 328.409808 -253.721616)
		(width 0.0889)
		(layer "In11.Cu")
		(net "M_F_CPU0_SA_CA<2>")
	)
	(arc
		(start 327.103486 -253.71679)
		(mid 327.290684 -253.767172)
		(end 327.477882 -253.71679)
		(width 0.0889)
		(layer "In11.Cu")
		(net "M_F_CPU0_SA_CA<2>")
	)
	(arc
		(start 329.358244 -253.71679)
		(mid 329.6412 -253.640613)
		(end 329.924156 -253.71679)
		(width 0.0889)
		(layer "In11.Cu")
		(net "M_F_CPU0_SA_CA<2>")
	)
	(arc
		(start 332.752446 -253.721616)
		(mid 332.935954 -253.76711)
		(end 333.118206 -253.71679)
		(width 0.0889)
		(layer "In11.Cu")
		(net "M_F_CPU0_SA_CA<2>")
	)
	(arc
		(start 329.924156 -253.71679)
		(mid 330.1111 -253.767045)
		(end 330.298044 -253.71679)
		(width 0.0889)
		(layer "In11.Cu")
		(net "M_F_CPU0_SA_CA<2>")
	)
	(arc
		(start 332.178152 -253.71679)
		(mid 332.461108 -253.640613)
		(end 332.744064 -253.71679)
		(width 0.0889)
		(layer "In11.Cu")
		(net "M_F_CPU0_SA_CA<2>")
	)
	(arc
		(start 326.548242 -253.710694)
		(mid 326.826674 -253.640596)
		(end 327.103486 -253.71679)
		(width 0.0889)
		(layer "In11.Cu")
		(net "M_F_CPU0_SA_CA<2>")
	)
	(arc
		(start 331.80401 -253.71679)
		(mid 331.986261 -253.76714)
		(end 332.16977 -253.721616)
		(width 0.0889)
		(layer "In11.Cu")
		(net "M_F_CPU0_SA_CA<2>")
	)
	(arc
		(start 331.238098 -253.71679)
		(mid 331.521054 -253.640613)
		(end 331.80401 -253.71679)
		(width 0.0889)
		(layer "In11.Cu")
		(net "M_F_CPU0_SA_CA<2>")
	)
	(arc
		(start 333.118206 -253.71679)
		(mid 333.365919 -253.64157)
		(end 333.621126 -253.68504)
		(width 0.0889)
		(layer "In11.Cu")
		(net "M_F_CPU0_SA_CA<2>")
	)
	(arc
		(start 326.163686 -253.71679)
		(mid 326.342441 -253.767199)
		(end 326.52335 -253.725172)
		(width 0.0889)
		(layer "In11.Cu")
		(net "M_F_CPU0_SA_CA<2>")
	)
	(segment
		(start 332.45806 -253.660148)
		(end 331.991208 -253.39421)
		(width 0.10668)
		(layer "F.Cu")
		(net "M_F_CPU0_SA_CA<1>")
	)
	(segment
		(start 265.973052 -248.75998)
		(end 270.009112 -248.75998)
		(width 0.14478)
		(layer "In11.Cu")
		(net "M_F_CPU0_SA_CA<1>")
	)
	(segment
		(start 331.229716 -253.066804)
		(end 331.238098 -253.07163)
		(width 0.0889)
		(layer "In11.Cu")
		(net "M_F_CPU0_SA_CA<1>")
	)
	(segment
		(start 307.471318 -250.460002)
		(end 309.437786 -252.42647)
		(width 0.14478)
		(layer "In11.Cu")
		(net "M_F_CPU0_SA_CA<1>")
	)
	(segment
		(start 332.12278 -253.045468)
		(end 332.145132 -253.12878)
		(width 0.0889)
		(layer "In11.Cu")
		(net "M_F_CPU0_SA_CA<1>")
	)
	(segment
		(start 323.926454 -253.74219)
		(end 324.111874 -253.74219)
		(width 0.0889)
		(layer "In11.Cu")
		(net "M_F_CPU0_SA_CA<1>")
	)
	(segment
		(start 271.709134 -250.460002)
		(end 307.471318 -250.460002)
		(width 0.14478)
		(layer "In11.Cu")
		(net "M_F_CPU0_SA_CA<1>")
	)
	(segment
		(start 309.437786 -252.42647)
		(end 320.60515 -252.42647)
		(width 0.14478)
		(layer "In11.Cu")
		(net "M_F_CPU0_SA_CA<1>")
	)
	(segment
		(start 325.435214 -253.14783)
		(end 325.882254 -253.14783)
		(width 0.0889)
		(layer "In11.Cu")
		(net "M_F_CPU0_SA_CA<1>")
	)
	(segment
		(start 325.054214 -253.52883)
		(end 325.435214 -253.14783)
		(width 0.0889)
		(layer "In11.Cu")
		(net "M_F_CPU0_SA_CA<1>")
	)
	(segment
		(start 324.325234 -253.52883)
		(end 325.054214 -253.52883)
		(width 0.0889)
		(layer "In11.Cu")
		(net "M_F_CPU0_SA_CA<1>")
	)
	(segment
		(start 332.145132 -253.12878)
		(end 331.991208 -253.39421)
		(width 0.0889)
		(layer "In11.Cu")
		(net "M_F_CPU0_SA_CA<1>")
	)
	(segment
		(start 265.54811 -248.335038)
		(end 265.973052 -248.75998)
		(width 0.14478)
		(layer "In11.Cu")
		(net "M_F_CPU0_SA_CA<1>")
	)
	(segment
		(start 320.60515 -252.42647)
		(end 321.92087 -253.74219)
		(width 0.14478)
		(layer "In11.Cu")
		(net "M_F_CPU0_SA_CA<1>")
	)
	(segment
		(start 327.08723 -253.082298)
		(end 327.105264 -253.07163)
		(width 0.0889)
		(layer "In11.Cu")
		(net "M_F_CPU0_SA_CA<1>")
	)
	(segment
		(start 327.465182 -253.06401)
		(end 327.478898 -253.071884)
		(width 0.0889)
		(layer "In11.Cu")
		(net "M_F_CPU0_SA_CA<1>")
	)
	(segment
		(start 326.164702 -253.071884)
		(end 326.184768 -253.060454)
		(width 0.0889)
		(layer "In11.Cu")
		(net "M_F_CPU0_SA_CA<1>")
	)
	(segment
		(start 328.984102 -253.07163)
		(end 328.992484 -253.066804)
		(width 0.0889)
		(layer "In11.Cu")
		(net "M_F_CPU0_SA_CA<1>")
	)
	(segment
		(start 321.92087 -253.74219)
		(end 323.926454 -253.74219)
		(width 0.14478)
		(layer "In11.Cu")
		(net "M_F_CPU0_SA_CA<1>")
	)
	(segment
		(start 327.478898 -253.071884)
		(end 327.490836 -253.078742)
		(width 0.0889)
		(layer "In11.Cu")
		(net "M_F_CPU0_SA_CA<1>")
	)
	(segment
		(start 324.111874 -253.74219)
		(end 324.325234 -253.52883)
		(width 0.0889)
		(layer "In11.Cu")
		(net "M_F_CPU0_SA_CA<1>")
	)
	(segment
		(start 270.009112 -248.75998)
		(end 271.709134 -250.460002)
		(width 0.14478)
		(layer "In11.Cu")
		(net "M_F_CPU0_SA_CA<1>")
	)
	(segment
		(start 328.409808 -253.066804)
		(end 328.41819 -253.07163)
		(width 0.0889)
		(layer "In11.Cu")
		(net "M_F_CPU0_SA_CA<1>")
	)
	(arc
		(start 329.924156 -253.07163)
		(mid 330.1111 -253.021375)
		(end 330.298044 -253.07163)
		(width 0.0889)
		(layer "In11.Cu")
		(net "M_F_CPU0_SA_CA<1>")
	)
	(arc
		(start 328.992484 -253.066804)
		(mid 329.175992 -253.02131)
		(end 329.358244 -253.07163)
		(width 0.0889)
		(layer "In11.Cu")
		(net "M_F_CPU0_SA_CA<1>")
	)
	(arc
		(start 326.184768 -253.060454)
		(mid 326.3631 -253.021357)
		(end 326.53859 -253.07163)
		(width 0.0889)
		(layer "In11.Cu")
		(net "M_F_CPU0_SA_CA<1>")
	)
	(arc
		(start 331.80401 -253.07163)
		(mid 331.960448 -253.022659)
		(end 332.12278 -253.045468)
		(width 0.0889)
		(layer "In11.Cu")
		(net "M_F_CPU0_SA_CA<1>")
	)
	(arc
		(start 325.882254 -253.14783)
		(mid 326.028502 -253.128525)
		(end 326.164702 -253.071884)
		(width 0.0889)
		(layer "In11.Cu")
		(net "M_F_CPU0_SA_CA<1>")
	)
	(arc
		(start 330.298044 -253.07163)
		(mid 330.581 -253.147807)
		(end 330.863956 -253.07163)
		(width 0.0889)
		(layer "In11.Cu")
		(net "M_F_CPU0_SA_CA<1>")
	)
	(arc
		(start 330.863956 -253.07163)
		(mid 331.046207 -253.02128)
		(end 331.229716 -253.066804)
		(width 0.0889)
		(layer "In11.Cu")
		(net "M_F_CPU0_SA_CA<1>")
	)
	(arc
		(start 327.105264 -253.07163)
		(mid 327.284251 -253.02146)
		(end 327.465182 -253.06401)
		(width 0.0889)
		(layer "In11.Cu")
		(net "M_F_CPU0_SA_CA<1>")
	)
	(arc
		(start 328.41819 -253.07163)
		(mid 328.701146 -253.147807)
		(end 328.984102 -253.07163)
		(width 0.0889)
		(layer "In11.Cu")
		(net "M_F_CPU0_SA_CA<1>")
	)
	(arc
		(start 329.358244 -253.07163)
		(mid 329.6412 -253.147807)
		(end 329.924156 -253.07163)
		(width 0.0889)
		(layer "In11.Cu")
		(net "M_F_CPU0_SA_CA<1>")
	)
	(arc
		(start 328.044048 -253.07163)
		(mid 328.226299 -253.02128)
		(end 328.409808 -253.066804)
		(width 0.0889)
		(layer "In11.Cu")
		(net "M_F_CPU0_SA_CA<1>")
	)
	(arc
		(start 331.238098 -253.07163)
		(mid 331.521054 -253.147807)
		(end 331.80401 -253.07163)
		(width 0.0889)
		(layer "In11.Cu")
		(net "M_F_CPU0_SA_CA<1>")
	)
	(arc
		(start 327.490836 -253.078742)
		(mid 327.76837 -253.147723)
		(end 328.044048 -253.07163)
		(width 0.0889)
		(layer "In11.Cu")
		(net "M_F_CPU0_SA_CA<1>")
	)
	(arc
		(start 326.53859 -253.07163)
		(mid 326.811534 -253.14821)
		(end 327.08723 -253.082298)
		(width 0.0889)
		(layer "In11.Cu")
		(net "M_F_CPU0_SA_CA<1>")
	)
	(segment
		(start 332.92796 -252.850142)
		(end 332.461108 -252.584204)
		(width 0.10668)
		(layer "F.Cu")
		(net "M_F_CPU0_SA_CA<0>")
	)
	(segment
		(start 327.574402 -252.90653)
		(end 327.590658 -252.915928)
		(width 0.0889)
		(layer "In11.Cu")
		(net "M_F_CPU0_SA_CA<0>")
	)
	(segment
		(start 329.819762 -252.91161)
		(end 329.828144 -252.906784)
		(width 0.0889)
		(layer "In11.Cu")
		(net "M_F_CPU0_SA_CA<0>")
	)
	(segment
		(start 274.073874 -249.773186)
		(end 274.073874 -249.837702)
		(width 0.14478)
		(layer "In11.Cu")
		(net "M_F_CPU0_SA_CA<0>")
	)
	(segment
		(start 281.904694 -249.840242)
		(end 282.067762 -250.00331)
		(width 0.14478)
		(layer "In11.Cu")
		(net "M_F_CPU0_SA_CA<0>")
	)
	(segment
		(start 285.768796 -249.610118)
		(end 285.931864 -249.773186)
		(width 0.14478)
		(layer "In11.Cu")
		(net "M_F_CPU0_SA_CA<0>")
	)
	(segment
		(start 278.946356 -250.00077)
		(end 279.176734 -250.00077)
		(width 0.14478)
		(layer "In11.Cu")
		(net "M_F_CPU0_SA_CA<0>")
	)
	(segment
		(start 281.741626 -249.610118)
		(end 281.904694 -249.773186)
		(width 0.14478)
		(layer "In11.Cu")
		(net "M_F_CPU0_SA_CA<0>")
	)
	(segment
		(start 283.574236 -249.773186)
		(end 283.737304 -249.610118)
		(width 0.14478)
		(layer "In11.Cu")
		(net "M_F_CPU0_SA_CA<0>")
	)
	(segment
		(start 278.783288 -249.773186)
		(end 278.783288 -249.837702)
		(width 0.14478)
		(layer "In11.Cu")
		(net "M_F_CPU0_SA_CA<0>")
	)
	(segment
		(start 279.50287 -249.610118)
		(end 281.741626 -249.610118)
		(width 0.14478)
		(layer "In11.Cu")
		(net "M_F_CPU0_SA_CA<0>")
	)
	(segment
		(start 282.624276 -249.610118)
		(end 282.854654 -249.610118)
		(width 0.14478)
		(layer "In11.Cu")
		(net "M_F_CPU0_SA_CA<0>")
	)
	(segment
		(start 274.630388 -249.773186)
		(end 274.793456 -249.610118)
		(width 0.14478)
		(layer "In11.Cu")
		(net "M_F_CPU0_SA_CA<0>")
	)
	(segment
		(start 275.743416 -249.773186)
		(end 275.906484 -249.610118)
		(width 0.14478)
		(layer "In11.Cu")
		(net "M_F_CPU0_SA_CA<0>")
	)
	(segment
		(start 282.461208 -249.773186)
		(end 282.624276 -249.610118)
		(width 0.14478)
		(layer "In11.Cu")
		(net "M_F_CPU0_SA_CA<0>")
	)
	(segment
		(start 274.630388 -249.837702)
		(end 274.630388 -249.773186)
		(width 0.14478)
		(layer "In11.Cu")
		(net "M_F_CPU0_SA_CA<0>")
	)
	(segment
		(start 332.307184 -252.849634)
		(end 332.461108 -252.584204)
		(width 0.0889)
		(layer "In11.Cu")
		(net "M_F_CPU0_SA_CA<0>")
	)
	(segment
		(start 331.33411 -252.906784)
		(end 331.342492 -252.91161)
		(width 0.0889)
		(layer "In11.Cu")
		(net "M_F_CPU0_SA_CA<0>")
	)
	(segment
		(start 275.186902 -249.773186)
		(end 275.186902 -249.837702)
		(width 0.14478)
		(layer "In11.Cu")
		(net "M_F_CPU0_SA_CA<0>")
	)
	(segment
		(start 307.53431 -249.610118)
		(end 309.896002 -251.97181)
		(width 0.14478)
		(layer "In11.Cu")
		(net "M_F_CPU0_SA_CA<0>")
	)
	(segment
		(start 282.854654 -249.610118)
		(end 283.017722 -249.773186)
		(width 0.14478)
		(layer "In11.Cu")
		(net "M_F_CPU0_SA_CA<0>")
	)
	(segment
		(start 282.29814 -250.00331)
		(end 282.461208 -249.840242)
		(width 0.14478)
		(layer "In11.Cu")
		(net "M_F_CPU0_SA_CA<0>")
	)
	(segment
		(start 327.562464 -252.899672)
		(end 327.574402 -252.90653)
		(width 0.0889)
		(layer "In11.Cu")
		(net "M_F_CPU0_SA_CA<0>")
	)
	(segment
		(start 283.411168 -250.00331)
		(end 283.574236 -249.840242)
		(width 0.14478)
		(layer "In11.Cu")
		(net "M_F_CPU0_SA_CA<0>")
	)
	(segment
		(start 275.34997 -250.00077)
		(end 275.580348 -250.00077)
		(width 0.14478)
		(layer "In11.Cu")
		(net "M_F_CPU0_SA_CA<0>")
	)
	(segment
		(start 285.931864 -249.773186)
		(end 285.931864 -249.840242)
		(width 0.14478)
		(layer "In11.Cu")
		(net "M_F_CPU0_SA_CA<0>")
	)
	(segment
		(start 274.46732 -250.00077)
		(end 274.630388 -249.837702)
		(width 0.14478)
		(layer "In11.Cu")
		(net "M_F_CPU0_SA_CA<0>")
	)
	(segment
		(start 275.743416 -249.837702)
		(end 275.743416 -249.773186)
		(width 0.14478)
		(layer "In11.Cu")
		(net "M_F_CPU0_SA_CA<0>")
	)
	(segment
		(start 286.094932 -250.00331)
		(end 286.32531 -250.00331)
		(width 0.14478)
		(layer "In11.Cu")
		(net "M_F_CPU0_SA_CA<0>")
	)
	(segment
		(start 324.142354 -253.25451)
		(end 324.886574 -253.25451)
		(width 0.0889)
		(layer "In11.Cu")
		(net "M_F_CPU0_SA_CA<0>")
	)
	(segment
		(start 323.898514 -253.28753)
		(end 324.109334 -253.28753)
		(width 0.0889)
		(layer "In11.Cu")
		(net "M_F_CPU0_SA_CA<0>")
	)
	(segment
		(start 286.488378 -249.840242)
		(end 286.488378 -249.773186)
		(width 0.14478)
		(layer "In11.Cu")
		(net "M_F_CPU0_SA_CA<0>")
	)
	(segment
		(start 283.017722 -249.840242)
		(end 283.18079 -250.00331)
		(width 0.14478)
		(layer "In11.Cu")
		(net "M_F_CPU0_SA_CA<0>")
	)
	(segment
		(start 275.186902 -249.837702)
		(end 275.34997 -250.00077)
		(width 0.14478)
		(layer "In11.Cu")
		(net "M_F_CPU0_SA_CA<0>")
	)
	(segment
		(start 326.997568 -252.913642)
		(end 327.009252 -252.906784)
		(width 0.0889)
		(layer "In11.Cu")
		(net "M_F_CPU0_SA_CA<0>")
	)
	(segment
		(start 282.067762 -250.00331)
		(end 282.29814 -250.00331)
		(width 0.14478)
		(layer "In11.Cu")
		(net "M_F_CPU0_SA_CA<0>")
	)
	(segment
		(start 283.18079 -250.00331)
		(end 283.411168 -250.00331)
		(width 0.14478)
		(layer "In11.Cu")
		(net "M_F_CPU0_SA_CA<0>")
	)
	(segment
		(start 320.793618 -251.97181)
		(end 322.109338 -253.28753)
		(width 0.14478)
		(layer "In11.Cu")
		(net "M_F_CPU0_SA_CA<0>")
	)
	(segment
		(start 275.580348 -250.00077)
		(end 275.743416 -249.837702)
		(width 0.14478)
		(layer "In11.Cu")
		(net "M_F_CPU0_SA_CA<0>")
	)
	(segment
		(start 274.793456 -249.610118)
		(end 275.023834 -249.610118)
		(width 0.14478)
		(layer "In11.Cu")
		(net "M_F_CPU0_SA_CA<0>")
	)
	(segment
		(start 279.339802 -249.837702)
		(end 279.339802 -249.773186)
		(width 0.14478)
		(layer "In11.Cu")
		(net "M_F_CPU0_SA_CA<0>")
	)
	(segment
		(start 273.910806 -249.610118)
		(end 274.073874 -249.773186)
		(width 0.14478)
		(layer "In11.Cu")
		(net "M_F_CPU0_SA_CA<0>")
	)
	(segment
		(start 274.073874 -249.837702)
		(end 274.236942 -250.00077)
		(width 0.14478)
		(layer "In11.Cu")
		(net "M_F_CPU0_SA_CA<0>")
	)
	(segment
		(start 283.574236 -249.840242)
		(end 283.574236 -249.773186)
		(width 0.14478)
		(layer "In11.Cu")
		(net "M_F_CPU0_SA_CA<0>")
	)
	(segment
		(start 278.783288 -249.837702)
		(end 278.946356 -250.00077)
		(width 0.14478)
		(layer "In11.Cu")
		(net "M_F_CPU0_SA_CA<0>")
	)
	(segment
		(start 286.32531 -250.00331)
		(end 286.488378 -249.840242)
		(width 0.14478)
		(layer "In11.Cu")
		(net "M_F_CPU0_SA_CA<0>")
	)
	(segment
		(start 283.737304 -249.610118)
		(end 285.768796 -249.610118)
		(width 0.14478)
		(layer "In11.Cu")
		(net "M_F_CPU0_SA_CA<0>")
	)
	(segment
		(start 324.109334 -253.28753)
		(end 324.142354 -253.25451)
		(width 0.0889)
		(layer "In11.Cu")
		(net "M_F_CPU0_SA_CA<0>")
	)
	(segment
		(start 285.931864 -249.840242)
		(end 286.094932 -250.00331)
		(width 0.14478)
		(layer "In11.Cu")
		(net "M_F_CPU0_SA_CA<0>")
	)
	(segment
		(start 279.176734 -250.00077)
		(end 279.339802 -249.837702)
		(width 0.14478)
		(layer "In11.Cu")
		(net "M_F_CPU0_SA_CA<0>")
	)
	(segment
		(start 332.211172 -252.875034)
		(end 332.307184 -252.849634)
		(width 0.0889)
		(layer "In11.Cu")
		(net "M_F_CPU0_SA_CA<0>")
	)
	(segment
		(start 275.906484 -249.610118)
		(end 278.62022 -249.610118)
		(width 0.14478)
		(layer "In11.Cu")
		(net "M_F_CPU0_SA_CA<0>")
	)
	(segment
		(start 275.023834 -249.610118)
		(end 275.186902 -249.773186)
		(width 0.14478)
		(layer "In11.Cu")
		(net "M_F_CPU0_SA_CA<0>")
	)
	(segment
		(start 309.896002 -251.97181)
		(end 320.793618 -251.97181)
		(width 0.14478)
		(layer "In11.Cu")
		(net "M_F_CPU0_SA_CA<0>")
	)
	(segment
		(start 326.068944 -252.90653)
		(end 326.090534 -252.894084)
		(width 0.0889)
		(layer "In11.Cu")
		(net "M_F_CPU0_SA_CA<0>")
	)
	(segment
		(start 283.017722 -249.773186)
		(end 283.017722 -249.840242)
		(width 0.14478)
		(layer "In11.Cu")
		(net "M_F_CPU0_SA_CA<0>")
	)
	(segment
		(start 269.648178 -247.485154)
		(end 271.773142 -249.610118)
		(width 0.14478)
		(layer "In11.Cu")
		(net "M_F_CPU0_SA_CA<0>")
	)
	(segment
		(start 325.183754 -252.95733)
		(end 325.882 -252.95733)
		(width 0.0889)
		(layer "In11.Cu")
		(net "M_F_CPU0_SA_CA<0>")
	)
	(segment
		(start 286.651446 -249.610118)
		(end 307.53431 -249.610118)
		(width 0.14478)
		(layer "In11.Cu")
		(net "M_F_CPU0_SA_CA<0>")
	)
	(segment
		(start 322.109338 -253.28753)
		(end 323.898514 -253.28753)
		(width 0.14478)
		(layer "In11.Cu")
		(net "M_F_CPU0_SA_CA<0>")
	)
	(segment
		(start 274.236942 -250.00077)
		(end 274.46732 -250.00077)
		(width 0.14478)
		(layer "In11.Cu")
		(net "M_F_CPU0_SA_CA<0>")
	)
	(segment
		(start 324.886574 -253.25451)
		(end 325.183754 -252.95733)
		(width 0.0889)
		(layer "In11.Cu")
		(net "M_F_CPU0_SA_CA<0>")
	)
	(segment
		(start 281.904694 -249.773186)
		(end 281.904694 -249.840242)
		(width 0.14478)
		(layer "In11.Cu")
		(net "M_F_CPU0_SA_CA<0>")
	)
	(segment
		(start 330.394056 -252.906784)
		(end 330.402438 -252.91161)
		(width 0.0889)
		(layer "In11.Cu")
		(net "M_F_CPU0_SA_CA<0>")
	)
	(segment
		(start 278.62022 -249.610118)
		(end 278.783288 -249.773186)
		(width 0.14478)
		(layer "In11.Cu")
		(net "M_F_CPU0_SA_CA<0>")
	)
	(segment
		(start 279.339802 -249.773186)
		(end 279.50287 -249.610118)
		(width 0.14478)
		(layer "In11.Cu")
		(net "M_F_CPU0_SA_CA<0>")
	)
	(segment
		(start 286.488378 -249.773186)
		(end 286.651446 -249.610118)
		(width 0.14478)
		(layer "In11.Cu")
		(net "M_F_CPU0_SA_CA<0>")
	)
	(segment
		(start 271.773142 -249.610118)
		(end 273.910806 -249.610118)
		(width 0.14478)
		(layer "In11.Cu")
		(net "M_F_CPU0_SA_CA<0>")
	)
	(segment
		(start 282.461208 -249.840242)
		(end 282.461208 -249.773186)
		(width 0.14478)
		(layer "In11.Cu")
		(net "M_F_CPU0_SA_CA<0>")
	)
	(arc
		(start 326.634856 -252.906784)
		(mid 326.815314 -252.957228)
		(end 326.997568 -252.913642)
		(width 0.0889)
		(layer "In11.Cu")
		(net "M_F_CPU0_SA_CA<0>")
	)
	(arc
		(start 325.882 -252.95733)
		(mid 325.978818 -252.944259)
		(end 326.068944 -252.90653)
		(width 0.0889)
		(layer "In11.Cu")
		(net "M_F_CPU0_SA_CA<0>")
	)
	(arc
		(start 328.514202 -252.906784)
		(mid 328.701146 -252.957039)
		(end 328.88809 -252.906784)
		(width 0.0889)
		(layer "In11.Cu")
		(net "M_F_CPU0_SA_CA<0>")
	)
	(arc
		(start 330.768198 -252.906784)
		(mid 331.051154 -252.830607)
		(end 331.33411 -252.906784)
		(width 0.0889)
		(layer "In11.Cu")
		(net "M_F_CPU0_SA_CA<0>")
	)
	(arc
		(start 327.590658 -252.915928)
		(mid 327.77064 -252.957028)
		(end 327.94829 -252.906784)
		(width 0.0889)
		(layer "In11.Cu")
		(net "M_F_CPU0_SA_CA<0>")
	)
	(arc
		(start 326.090534 -252.894084)
		(mid 326.364324 -252.830413)
		(end 326.634856 -252.906784)
		(width 0.0889)
		(layer "In11.Cu")
		(net "M_F_CPU0_SA_CA<0>")
	)
	(arc
		(start 329.828144 -252.906784)
		(mid 330.1111 -252.830607)
		(end 330.394056 -252.906784)
		(width 0.0889)
		(layer "In11.Cu")
		(net "M_F_CPU0_SA_CA<0>")
	)
	(arc
		(start 328.88809 -252.906784)
		(mid 329.171046 -252.830607)
		(end 329.454002 -252.906784)
		(width 0.0889)
		(layer "In11.Cu")
		(net "M_F_CPU0_SA_CA<0>")
	)
	(arc
		(start 331.708252 -252.906784)
		(mid 331.955965 -252.831564)
		(end 332.211172 -252.875034)
		(width 0.0889)
		(layer "In11.Cu")
		(net "M_F_CPU0_SA_CA<0>")
	)
	(arc
		(start 331.342492 -252.91161)
		(mid 331.526 -252.957104)
		(end 331.708252 -252.906784)
		(width 0.0889)
		(layer "In11.Cu")
		(net "M_F_CPU0_SA_CA<0>")
	)
	(arc
		(start 329.454002 -252.906784)
		(mid 329.636253 -252.957134)
		(end 329.819762 -252.91161)
		(width 0.0889)
		(layer "In11.Cu")
		(net "M_F_CPU0_SA_CA<0>")
	)
	(arc
		(start 327.009252 -252.906784)
		(mid 327.28493 -252.830654)
		(end 327.562464 -252.899672)
		(width 0.0889)
		(layer "In11.Cu")
		(net "M_F_CPU0_SA_CA<0>")
	)
	(arc
		(start 327.94829 -252.906784)
		(mid 328.231246 -252.830607)
		(end 328.514202 -252.906784)
		(width 0.0889)
		(layer "In11.Cu")
		(net "M_F_CPU0_SA_CA<0>")
	)
	(arc
		(start 330.402438 -252.91161)
		(mid 330.585946 -252.957104)
		(end 330.768198 -252.906784)
		(width 0.0889)
		(layer "In11.Cu")
		(net "M_F_CPU0_SA_CA<0>")
	)
	(segment
		(start 333.868014 -251.23013)
		(end 333.401162 -250.964192)
		(width 0.10668)
		(layer "F.Cu")
		(net "M_F_CPU0_RESET_N")
	)
	(segment
		(start 324.086982 -251.611892)
		(end 324.903338 -251.611892)
		(width 0.0889)
		(layer "In11.Cu")
		(net "M_F_CPU0_RESET_N")
	)
	(segment
		(start 307.758338 -247.059958)
		(end 311.01538 -250.317)
		(width 0.11684)
		(layer "In11.Cu")
		(net "M_F_CPU0_RESET_N")
	)
	(segment
		(start 326.634094 -250.641612)
		(end 326.642476 -250.636786)
		(width 0.0889)
		(layer "In11.Cu")
		(net "M_F_CPU0_RESET_N")
	)
	(segment
		(start 322.781422 -251.61875)
		(end 324.080124 -251.61875)
		(width 0.11684)
		(layer "In11.Cu")
		(net "M_F_CPU0_RESET_N")
	)
	(segment
		(start 330.394056 -250.641612)
		(end 330.402438 -250.636786)
		(width 0.0889)
		(layer "In11.Cu")
		(net "M_F_CPU0_RESET_N")
	)
	(segment
		(start 311.01538 -250.317)
		(end 321.479672 -250.317)
		(width 0.11684)
		(layer "In11.Cu")
		(net "M_F_CPU0_RESET_N")
	)
	(segment
		(start 326.62368 -250.647708)
		(end 326.634094 -250.641612)
		(width 0.0889)
		(layer "In11.Cu")
		(net "M_F_CPU0_RESET_N")
	)
	(segment
		(start 333.532734 -250.61545)
		(end 333.555086 -250.698762)
		(width 0.0889)
		(layer "In11.Cu")
		(net "M_F_CPU0_RESET_N")
	)
	(segment
		(start 272.232374 -247.059958)
		(end 307.758338 -247.059958)
		(width 0.11684)
		(layer "In11.Cu")
		(net "M_F_CPU0_RESET_N")
	)
	(segment
		(start 324.080124 -251.61875)
		(end 324.086982 -251.611892)
		(width 0.0889)
		(layer "In11.Cu")
		(net "M_F_CPU0_RESET_N")
	)
	(segment
		(start 326.156066 -250.717304)
		(end 326.325738 -250.717304)
		(width 0.0889)
		(layer "In11.Cu")
		(net "M_F_CPU0_RESET_N")
	)
	(segment
		(start 331.33411 -250.641612)
		(end 331.342492 -250.636786)
		(width 0.0889)
		(layer "In11.Cu")
		(net "M_F_CPU0_RESET_N")
	)
	(segment
		(start 329.819762 -250.636786)
		(end 329.828144 -250.641612)
		(width 0.0889)
		(layer "In11.Cu")
		(net "M_F_CPU0_RESET_N")
	)
	(segment
		(start 325.464678 -251.050552)
		(end 325.822818 -251.050552)
		(width 0.0889)
		(layer "In11.Cu")
		(net "M_F_CPU0_RESET_N")
	)
	(segment
		(start 265.54811 -244.934994)
		(end 265.973052 -245.359936)
		(width 0.11684)
		(layer "In11.Cu")
		(net "M_F_CPU0_RESET_N")
	)
	(segment
		(start 265.973052 -245.359936)
		(end 270.532352 -245.359936)
		(width 0.11684)
		(layer "In11.Cu")
		(net "M_F_CPU0_RESET_N")
	)
	(segment
		(start 324.903338 -251.611892)
		(end 325.464678 -251.050552)
		(width 0.0889)
		(layer "In11.Cu")
		(net "M_F_CPU0_RESET_N")
	)
	(segment
		(start 321.479672 -250.317)
		(end 322.781422 -251.61875)
		(width 0.11684)
		(layer "In11.Cu")
		(net "M_F_CPU0_RESET_N")
	)
	(segment
		(start 325.822818 -251.050552)
		(end 326.156066 -250.717304)
		(width 0.0889)
		(layer "In11.Cu")
		(net "M_F_CPU0_RESET_N")
	)
	(segment
		(start 270.532352 -245.359936)
		(end 272.232374 -247.059958)
		(width 0.11684)
		(layer "In11.Cu")
		(net "M_F_CPU0_RESET_N")
	)
	(segment
		(start 327.574148 -250.641612)
		(end 327.58253 -250.636786)
		(width 0.0889)
		(layer "In11.Cu")
		(net "M_F_CPU0_RESET_N")
	)
	(segment
		(start 333.555086 -250.698762)
		(end 333.401162 -250.964192)
		(width 0.0889)
		(layer "In11.Cu")
		(net "M_F_CPU0_RESET_N")
	)
	(arc
		(start 327.58253 -250.636786)
		(mid 327.766038 -250.591292)
		(end 327.94829 -250.641612)
		(width 0.0889)
		(layer "In11.Cu")
		(net "M_F_CPU0_RESET_N")
	)
	(arc
		(start 326.325738 -250.717304)
		(mid 326.47953 -250.703131)
		(end 326.62368 -250.647708)
		(width 0.0889)
		(layer "In11.Cu")
		(net "M_F_CPU0_RESET_N")
	)
	(arc
		(start 331.708252 -250.641612)
		(mid 331.991208 -250.717789)
		(end 332.274164 -250.641612)
		(width 0.0889)
		(layer "In11.Cu")
		(net "M_F_CPU0_RESET_N")
	)
	(arc
		(start 332.274164 -250.641612)
		(mid 332.461108 -250.591357)
		(end 332.648052 -250.641612)
		(width 0.0889)
		(layer "In11.Cu")
		(net "M_F_CPU0_RESET_N")
	)
	(arc
		(start 327.008236 -250.641612)
		(mid 327.291192 -250.717789)
		(end 327.574148 -250.641612)
		(width 0.0889)
		(layer "In11.Cu")
		(net "M_F_CPU0_RESET_N")
	)
	(arc
		(start 330.768198 -250.641612)
		(mid 331.051154 -250.717789)
		(end 331.33411 -250.641612)
		(width 0.0889)
		(layer "In11.Cu")
		(net "M_F_CPU0_RESET_N")
	)
	(arc
		(start 331.342492 -250.636786)
		(mid 331.526 -250.591292)
		(end 331.708252 -250.641612)
		(width 0.0889)
		(layer "In11.Cu")
		(net "M_F_CPU0_RESET_N")
	)
	(arc
		(start 329.828144 -250.641612)
		(mid 330.1111 -250.717789)
		(end 330.394056 -250.641612)
		(width 0.0889)
		(layer "In11.Cu")
		(net "M_F_CPU0_RESET_N")
	)
	(arc
		(start 328.88809 -250.641612)
		(mid 329.171046 -250.717789)
		(end 329.454002 -250.641612)
		(width 0.0889)
		(layer "In11.Cu")
		(net "M_F_CPU0_RESET_N")
	)
	(arc
		(start 330.402438 -250.636786)
		(mid 330.585946 -250.591292)
		(end 330.768198 -250.641612)
		(width 0.0889)
		(layer "In11.Cu")
		(net "M_F_CPU0_RESET_N")
	)
	(arc
		(start 327.94829 -250.641612)
		(mid 328.231246 -250.717789)
		(end 328.514202 -250.641612)
		(width 0.0889)
		(layer "In11.Cu")
		(net "M_F_CPU0_RESET_N")
	)
	(arc
		(start 332.648052 -250.641612)
		(mid 332.931008 -250.717789)
		(end 333.213964 -250.641612)
		(width 0.0889)
		(layer "In11.Cu")
		(net "M_F_CPU0_RESET_N")
	)
	(arc
		(start 333.213964 -250.641612)
		(mid 333.370402 -250.592641)
		(end 333.532734 -250.61545)
		(width 0.0889)
		(layer "In11.Cu")
		(net "M_F_CPU0_RESET_N")
	)
	(arc
		(start 329.454002 -250.641612)
		(mid 329.636253 -250.591262)
		(end 329.819762 -250.636786)
		(width 0.0889)
		(layer "In11.Cu")
		(net "M_F_CPU0_RESET_N")
	)
	(arc
		(start 328.514202 -250.641612)
		(mid 328.701146 -250.591357)
		(end 328.88809 -250.641612)
		(width 0.0889)
		(layer "In11.Cu")
		(net "M_F_CPU0_RESET_N")
	)
	(arc
		(start 326.642476 -250.636786)
		(mid 326.825984 -250.591292)
		(end 327.008236 -250.641612)
		(width 0.0889)
		(layer "In11.Cu")
		(net "M_F_CPU0_RESET_N")
	)
	(segment
		(start 332.92796 -256.090166)
		(end 332.461108 -255.824228)
		(width 0.14732)
		(layer "F.Cu")
		(net "M_F_CPU0_CLK_DP<0>")
	)
	(segment
		(start 269.415006 -256.41681)
		(end 313.367674 -256.41681)
		(width 0.16002)
		(layer "In11.Cu")
		(net "M_F_CPU0_CLK_DP<0>")
	)
	(segment
		(start 320.635376 -257.34264)
		(end 323.895974 -257.34264)
		(width 0.16002)
		(layer "In11.Cu")
		(net "M_F_CPU0_CLK_DP<0>")
	)
	(segment
		(start 326.070468 -256.149348)
		(end 326.095868 -256.134616)
		(width 0.09525)
		(layer "In11.Cu")
		(net "M_F_CPU0_CLK_DP<0>")
	)
	(segment
		(start 327.010522 -256.149348)
		(end 327.028556 -256.138934)
		(width 0.09525)
		(layer "In11.Cu")
		(net "M_F_CPU0_CLK_DP<0>")
	)
	(segment
		(start 330.392532 -256.149348)
		(end 330.400914 -256.154174)
		(width 0.09525)
		(layer "In11.Cu")
		(net "M_F_CPU0_CLK_DP<0>")
	)
	(segment
		(start 323.919596 -257.34264)
		(end 323.978778 -257.401822)
		(width 0.09525)
		(layer "In11.Cu")
		(net "M_F_CPU0_CLK_DP<0>")
	)
	(segment
		(start 329.821286 -256.154174)
		(end 329.829668 -256.149348)
		(width 0.09525)
		(layer "In11.Cu")
		(net "M_F_CPU0_CLK_DP<0>")
	)
	(segment
		(start 331.332586 -256.149348)
		(end 331.340968 -256.154174)
		(width 0.09525)
		(layer "In11.Cu")
		(net "M_F_CPU0_CLK_DP<0>")
	)
	(segment
		(start 313.962034 -255.82245)
		(end 319.115186 -255.82245)
		(width 0.16002)
		(layer "In11.Cu")
		(net "M_F_CPU0_CLK_DP<0>")
	)
	(segment
		(start 266.707112 -253.708916)
		(end 269.415006 -256.41681)
		(width 0.16002)
		(layer "In11.Cu")
		(net "M_F_CPU0_CLK_DP<0>")
	)
	(segment
		(start 323.978778 -257.401822)
		(end 324.79107 -257.401822)
		(width 0.09525)
		(layer "In11.Cu")
		(net "M_F_CPU0_CLK_DP<0>")
	)
	(segment
		(start 327.572624 -256.149348)
		(end 327.581006 -256.154174)
		(width 0.09525)
		(layer "In11.Cu")
		(net "M_F_CPU0_CLK_DP<0>")
	)
	(segment
		(start 265.54811 -253.435104)
		(end 265.821922 -253.708916)
		(width 0.16002)
		(layer "In11.Cu")
		(net "M_F_CPU0_CLK_DP<0>")
	)
	(segment
		(start 332.206346 -256.116328)
		(end 332.307184 -256.089658)
		(width 0.09525)
		(layer "In11.Cu")
		(net "M_F_CPU0_CLK_DP<0>")
	)
	(segment
		(start 326.996044 -256.15773)
		(end 327.010522 -256.149348)
		(width 0.09525)
		(layer "In11.Cu")
		(net "M_F_CPU0_CLK_DP<0>")
	)
	(segment
		(start 323.895974 -257.34264)
		(end 323.919596 -257.34264)
		(width 0.09525)
		(layer "In11.Cu")
		(net "M_F_CPU0_CLK_DP<0>")
	)
	(segment
		(start 319.115186 -255.82245)
		(end 320.635376 -257.34264)
		(width 0.16002)
		(layer "In11.Cu")
		(net "M_F_CPU0_CLK_DP<0>")
	)
	(segment
		(start 313.367674 -256.41681)
		(end 313.962034 -255.82245)
		(width 0.16002)
		(layer "In11.Cu")
		(net "M_F_CPU0_CLK_DP<0>")
	)
	(segment
		(start 324.79107 -257.401822)
		(end 325.954898 -256.237994)
		(width 0.09525)
		(layer "In11.Cu")
		(net "M_F_CPU0_CLK_DP<0>")
	)
	(segment
		(start 265.821922 -253.708916)
		(end 266.707112 -253.708916)
		(width 0.16002)
		(layer "In11.Cu")
		(net "M_F_CPU0_CLK_DP<0>")
	)
	(segment
		(start 332.307184 -256.089658)
		(end 332.461108 -255.824228)
		(width 0.09525)
		(layer "In11.Cu")
		(net "M_F_CPU0_CLK_DP<0>")
	)
	(arc
		(start 327.949814 -256.149348)
		(mid 328.231246 -256.073593)
		(end 328.512678 -256.149348)
		(width 0.09525)
		(layer "In11.Cu")
		(net "M_F_CPU0_CLK_DP<0>")
	)
	(arc
		(start 331.340968 -256.154174)
		(mid 331.526 -256.200088)
		(end 331.709776 -256.149348)
		(width 0.09525)
		(layer "In11.Cu")
		(net "M_F_CPU0_CLK_DP<0>")
	)
	(arc
		(start 327.028556 -256.138934)
		(mid 327.301936 -256.073713)
		(end 327.572624 -256.149348)
		(width 0.09525)
		(layer "In11.Cu")
		(net "M_F_CPU0_CLK_DP<0>")
	)
	(arc
		(start 326.095868 -256.134616)
		(mid 326.366484 -256.073391)
		(end 326.633332 -256.149348)
		(width 0.09525)
		(layer "In11.Cu")
		(net "M_F_CPU0_CLK_DP<0>")
	)
	(arc
		(start 330.400914 -256.154174)
		(mid 330.585946 -256.200088)
		(end 330.769722 -256.149348)
		(width 0.09525)
		(layer "In11.Cu")
		(net "M_F_CPU0_CLK_DP<0>")
	)
	(arc
		(start 329.452478 -256.149348)
		(mid 329.636253 -256.20012)
		(end 329.821286 -256.154174)
		(width 0.09525)
		(layer "In11.Cu")
		(net "M_F_CPU0_CLK_DP<0>")
	)
	(arc
		(start 331.709776 -256.149348)
		(mid 331.954202 -256.074705)
		(end 332.206346 -256.116328)
		(width 0.09525)
		(layer "In11.Cu")
		(net "M_F_CPU0_CLK_DP<0>")
	)
	(arc
		(start 326.633332 -256.149348)
		(mid 326.813611 -256.200179)
		(end 326.996044 -256.15773)
		(width 0.09525)
		(layer "In11.Cu")
		(net "M_F_CPU0_CLK_DP<0>")
	)
	(arc
		(start 327.581006 -256.154174)
		(mid 327.766038 -256.200088)
		(end 327.949814 -256.149348)
		(width 0.09525)
		(layer "In11.Cu")
		(net "M_F_CPU0_CLK_DP<0>")
	)
	(arc
		(start 330.769722 -256.149348)
		(mid 331.051154 -256.073593)
		(end 331.332586 -256.149348)
		(width 0.09525)
		(layer "In11.Cu")
		(net "M_F_CPU0_CLK_DP<0>")
	)
	(arc
		(start 329.829668 -256.149348)
		(mid 330.1111 -256.073593)
		(end 330.392532 -256.149348)
		(width 0.09525)
		(layer "In11.Cu")
		(net "M_F_CPU0_CLK_DP<0>")
	)
	(arc
		(start 328.512678 -256.149348)
		(mid 328.701146 -256.200025)
		(end 328.889614 -256.149348)
		(width 0.09525)
		(layer "In11.Cu")
		(net "M_F_CPU0_CLK_DP<0>")
	)
	(arc
		(start 328.889614 -256.149348)
		(mid 329.171046 -256.073593)
		(end 329.452478 -256.149348)
		(width 0.09525)
		(layer "In11.Cu")
		(net "M_F_CPU0_CLK_DP<0>")
	)
	(arc
		(start 325.954898 -256.237994)
		(mid 326.009786 -256.189893)
		(end 326.070468 -256.149348)
		(width 0.09525)
		(layer "In11.Cu")
		(net "M_F_CPU0_CLK_DP<0>")
	)
	(segment
		(start 332.45806 -256.900172)
		(end 331.991208 -256.634234)
		(width 0.14732)
		(layer "F.Cu")
		(net "M_F_CPU0_CLK_DN<0>")
	)
	(segment
		(start 311.528968 -256.83591)
		(end 311.645808 -256.71907)
		(width 0.16002)
		(layer "In11.Cu")
		(net "M_F_CPU0_CLK_DN<0>")
	)
	(segment
		(start 323.978524 -257.585972)
		(end 324.867524 -257.585972)
		(width 0.09525)
		(layer "In11.Cu")
		(net "M_F_CPU0_CLK_DN<0>")
	)
	(segment
		(start 265.54811 -254.284988)
		(end 265.821922 -254.011176)
		(width 0.16002)
		(layer "In11.Cu")
		(net "M_F_CPU0_CLK_DN<0>")
	)
	(segment
		(start 326.163178 -256.309114)
		(end 326.179942 -256.299462)
		(width 0.09525)
		(layer "In11.Cu")
		(net "M_F_CPU0_CLK_DN<0>")
	)
	(segment
		(start 327.077578 -256.323846)
		(end 327.102978 -256.309114)
		(width 0.09525)
		(layer "In11.Cu")
		(net "M_F_CPU0_CLK_DN<0>")
	)
	(segment
		(start 265.821922 -254.011176)
		(end 266.58189 -254.011176)
		(width 0.16002)
		(layer "In11.Cu")
		(net "M_F_CPU0_CLK_DN<0>")
	)
	(segment
		(start 332.121764 -256.281936)
		(end 332.145132 -256.368804)
		(width 0.09525)
		(layer "In11.Cu")
		(net "M_F_CPU0_CLK_DN<0>")
	)
	(segment
		(start 311.645808 -256.71907)
		(end 313.492896 -256.71907)
		(width 0.16002)
		(layer "In11.Cu")
		(net "M_F_CPU0_CLK_DN<0>")
	)
	(segment
		(start 269.289784 -256.71907)
		(end 310.932068 -256.71907)
		(width 0.16002)
		(layer "In11.Cu")
		(net "M_F_CPU0_CLK_DN<0>")
	)
	(segment
		(start 328.411332 -256.304288)
		(end 328.419714 -256.309114)
		(width 0.09525)
		(layer "In11.Cu")
		(net "M_F_CPU0_CLK_DN<0>")
	)
	(segment
		(start 327.102978 -256.309114)
		(end 327.11136 -256.304288)
		(width 0.09525)
		(layer "In11.Cu")
		(net "M_F_CPU0_CLK_DN<0>")
	)
	(segment
		(start 323.895974 -257.6449)
		(end 323.919596 -257.6449)
		(width 0.09525)
		(layer "In11.Cu")
		(net "M_F_CPU0_CLK_DN<0>")
	)
	(segment
		(start 311.048908 -256.83591)
		(end 311.528968 -256.83591)
		(width 0.16002)
		(layer "In11.Cu")
		(net "M_F_CPU0_CLK_DN<0>")
	)
	(segment
		(start 320.510154 -257.6449)
		(end 323.895974 -257.6449)
		(width 0.16002)
		(layer "In11.Cu")
		(net "M_F_CPU0_CLK_DN<0>")
	)
	(segment
		(start 328.982578 -256.309114)
		(end 328.99096 -256.304288)
		(width 0.09525)
		(layer "In11.Cu")
		(net "M_F_CPU0_CLK_DN<0>")
	)
	(segment
		(start 313.492896 -256.71907)
		(end 314.087256 -256.12471)
		(width 0.16002)
		(layer "In11.Cu")
		(net "M_F_CPU0_CLK_DN<0>")
	)
	(segment
		(start 324.867524 -257.585972)
		(end 326.0852 -256.368296)
		(width 0.09525)
		(layer "In11.Cu")
		(net "M_F_CPU0_CLK_DN<0>")
	)
	(segment
		(start 310.932068 -256.71907)
		(end 311.048908 -256.83591)
		(width 0.16002)
		(layer "In11.Cu")
		(net "M_F_CPU0_CLK_DN<0>")
	)
	(segment
		(start 318.989964 -256.12471)
		(end 320.510154 -257.6449)
		(width 0.16002)
		(layer "In11.Cu")
		(net "M_F_CPU0_CLK_DN<0>")
	)
	(segment
		(start 332.145132 -256.368804)
		(end 331.991208 -256.634234)
		(width 0.09525)
		(layer "In11.Cu")
		(net "M_F_CPU0_CLK_DN<0>")
	)
	(segment
		(start 323.919596 -257.6449)
		(end 323.978524 -257.585972)
		(width 0.09525)
		(layer "In11.Cu")
		(net "M_F_CPU0_CLK_DN<0>")
	)
	(segment
		(start 314.087256 -256.12471)
		(end 318.989964 -256.12471)
		(width 0.16002)
		(layer "In11.Cu")
		(net "M_F_CPU0_CLK_DN<0>")
	)
	(segment
		(start 331.23124 -256.304288)
		(end 331.239622 -256.309114)
		(width 0.09525)
		(layer "In11.Cu")
		(net "M_F_CPU0_CLK_DN<0>")
	)
	(segment
		(start 266.58189 -254.011176)
		(end 269.289784 -256.71907)
		(width 0.16002)
		(layer "In11.Cu")
		(net "M_F_CPU0_CLK_DN<0>")
	)
	(arc
		(start 330.299568 -256.309114)
		(mid 330.581 -256.384869)
		(end 330.862432 -256.309114)
		(width 0.09525)
		(layer "In11.Cu")
		(net "M_F_CPU0_CLK_DN<0>")
	)
	(arc
		(start 327.47966 -256.309114)
		(mid 327.761092 -256.384869)
		(end 328.042524 -256.309114)
		(width 0.09525)
		(layer "In11.Cu")
		(net "M_F_CPU0_CLK_DN<0>")
	)
	(arc
		(start 328.99096 -256.304288)
		(mid 329.175992 -256.258374)
		(end 329.359768 -256.309114)
		(width 0.09525)
		(layer "In11.Cu")
		(net "M_F_CPU0_CLK_DN<0>")
	)
	(arc
		(start 331.802486 -256.309114)
		(mid 331.959084 -256.259825)
		(end 332.121764 -256.281936)
		(width 0.09525)
		(layer "In11.Cu")
		(net "M_F_CPU0_CLK_DN<0>")
	)
	(arc
		(start 329.359768 -256.309114)
		(mid 329.6412 -256.384869)
		(end 329.922632 -256.309114)
		(width 0.09525)
		(layer "In11.Cu")
		(net "M_F_CPU0_CLK_DN<0>")
	)
	(arc
		(start 330.862432 -256.309114)
		(mid 331.046207 -256.258342)
		(end 331.23124 -256.304288)
		(width 0.09525)
		(layer "In11.Cu")
		(net "M_F_CPU0_CLK_DN<0>")
	)
	(arc
		(start 328.419714 -256.309114)
		(mid 328.701146 -256.384869)
		(end 328.982578 -256.309114)
		(width 0.09525)
		(layer "In11.Cu")
		(net "M_F_CPU0_CLK_DN<0>")
	)
	(arc
		(start 329.922632 -256.309114)
		(mid 330.1111 -256.258437)
		(end 330.299568 -256.309114)
		(width 0.09525)
		(layer "In11.Cu")
		(net "M_F_CPU0_CLK_DN<0>")
	)
	(arc
		(start 327.11136 -256.304288)
		(mid 327.296138 -256.258495)
		(end 327.47966 -256.309114)
		(width 0.09525)
		(layer "In11.Cu")
		(net "M_F_CPU0_CLK_DN<0>")
	)
	(arc
		(start 331.239622 -256.309114)
		(mid 331.521054 -256.384869)
		(end 331.802486 -256.309114)
		(width 0.09525)
		(layer "In11.Cu")
		(net "M_F_CPU0_CLK_DN<0>")
	)
	(arc
		(start 326.0852 -256.368296)
		(mid 326.122258 -256.336162)
		(end 326.163178 -256.309114)
		(width 0.09525)
		(layer "In11.Cu")
		(net "M_F_CPU0_CLK_DN<0>")
	)
	(arc
		(start 326.540114 -256.309114)
		(mid 326.806963 -256.385042)
		(end 327.077578 -256.323846)
		(width 0.09525)
		(layer "In11.Cu")
		(net "M_F_CPU0_CLK_DN<0>")
	)
	(arc
		(start 326.179942 -256.299462)
		(mid 326.361253 -256.258364)
		(end 326.540114 -256.309114)
		(width 0.09525)
		(layer "In11.Cu")
		(net "M_F_CPU0_CLK_DN<0>")
	)
	(arc
		(start 328.042524 -256.309114)
		(mid 328.226299 -256.258342)
		(end 328.411332 -256.304288)
		(width 0.09525)
		(layer "In11.Cu")
		(net "M_F_CPU0_CLK_DN<0>")
	)
	(segment
		(start 334.337914 -250.420124)
		(end 333.871062 -250.154186)
		(width 0.10668)
		(layer "F.Cu")
		(net "M_F_CPU0_ALERT_R_N")
	)
	(segment
		(start 324.629272 -250.710192)
		(end 325.779638 -250.710192)
		(width 0.0889)
		(layer "In11.Cu")
		(net "M_F_CPU0_ALERT_R_N")
	)
	(segment
		(start 333.717138 -250.419616)
		(end 333.871062 -250.154186)
		(width 0.0889)
		(layer "In11.Cu")
		(net "M_F_CPU0_ALERT_R_N")
	)
	(segment
		(start 327.469754 -250.481592)
		(end 327.478136 -250.476766)
		(width 0.0889)
		(layer "In11.Cu")
		(net "M_F_CPU0_ALERT_R_N")
	)
	(segment
		(start 325.964296 -250.525534)
		(end 326.315832 -250.525534)
		(width 0.0889)
		(layer "In11.Cu")
		(net "M_F_CPU0_ALERT_R_N")
	)
	(segment
		(start 308.060598 -246.210074)
		(end 311.740804 -249.89028)
		(width 0.11684)
		(layer "In11.Cu")
		(net "M_F_CPU0_ALERT_R_N")
	)
	(segment
		(start 271.045178 -244.820948)
		(end 272.434304 -246.210074)
		(width 0.11684)
		(layer "In11.Cu")
		(net "M_F_CPU0_ALERT_R_N")
	)
	(segment
		(start 271.045178 -244.08511)
		(end 271.045178 -244.820948)
		(width 0.11684)
		(layer "In11.Cu")
		(net "M_F_CPU0_ALERT_R_N")
	)
	(segment
		(start 324.627494 -250.71197)
		(end 324.629272 -250.710192)
		(width 0.0889)
		(layer "In11.Cu")
		(net "M_F_CPU0_ALERT_R_N")
	)
	(segment
		(start 325.779638 -250.710192)
		(end 325.964296 -250.525534)
		(width 0.0889)
		(layer "In11.Cu")
		(net "M_F_CPU0_ALERT_R_N")
	)
	(segment
		(start 332.16977 -250.481592)
		(end 332.178152 -250.476766)
		(width 0.0889)
		(layer "In11.Cu")
		(net "M_F_CPU0_ALERT_R_N")
	)
	(segment
		(start 333.621126 -250.445016)
		(end 333.717138 -250.419616)
		(width 0.0889)
		(layer "In11.Cu")
		(net "M_F_CPU0_ALERT_R_N")
	)
	(segment
		(start 326.526398 -250.483624)
		(end 326.538082 -250.476766)
		(width 0.0889)
		(layer "In11.Cu")
		(net "M_F_CPU0_ALERT_R_N")
	)
	(segment
		(start 311.740804 -249.89028)
		(end 321.656456 -249.89028)
		(width 0.11684)
		(layer "In11.Cu")
		(net "M_F_CPU0_ALERT_R_N")
	)
	(segment
		(start 328.409808 -250.481592)
		(end 328.41819 -250.476766)
		(width 0.0889)
		(layer "In11.Cu")
		(net "M_F_CPU0_ALERT_R_N")
	)
	(segment
		(start 331.229716 -250.481592)
		(end 331.238098 -250.476766)
		(width 0.0889)
		(layer "In11.Cu")
		(net "M_F_CPU0_ALERT_R_N")
	)
	(segment
		(start 324.457314 -250.88215)
		(end 324.627494 -250.71197)
		(width 0.11684)
		(layer "In11.Cu")
		(net "M_F_CPU0_ALERT_R_N")
	)
	(segment
		(start 332.744064 -250.476766)
		(end 332.752446 -250.481592)
		(width 0.0889)
		(layer "In11.Cu")
		(net "M_F_CPU0_ALERT_R_N")
	)
	(segment
		(start 328.984102 -250.476766)
		(end 328.992484 -250.481592)
		(width 0.0889)
		(layer "In11.Cu")
		(net "M_F_CPU0_ALERT_R_N")
	)
	(segment
		(start 322.648326 -250.88215)
		(end 324.457314 -250.88215)
		(width 0.11684)
		(layer "In11.Cu")
		(net "M_F_CPU0_ALERT_R_N")
	)
	(segment
		(start 321.656456 -249.89028)
		(end 322.648326 -250.88215)
		(width 0.11684)
		(layer "In11.Cu")
		(net "M_F_CPU0_ALERT_R_N")
	)
	(segment
		(start 272.434304 -246.210074)
		(end 308.060598 -246.210074)
		(width 0.11684)
		(layer "In11.Cu")
		(net "M_F_CPU0_ALERT_R_N")
	)
	(arc
		(start 332.752446 -250.481592)
		(mid 332.935954 -250.527086)
		(end 333.118206 -250.476766)
		(width 0.0889)
		(layer "In11.Cu")
		(net "M_F_CPU0_ALERT_R_N")
	)
	(arc
		(start 328.044048 -250.476766)
		(mid 328.226299 -250.527116)
		(end 328.409808 -250.481592)
		(width 0.0889)
		(layer "In11.Cu")
		(net "M_F_CPU0_ALERT_R_N")
	)
	(arc
		(start 327.103994 -250.476766)
		(mid 327.286245 -250.527116)
		(end 327.469754 -250.481592)
		(width 0.0889)
		(layer "In11.Cu")
		(net "M_F_CPU0_ALERT_R_N")
	)
	(arc
		(start 332.178152 -250.476766)
		(mid 332.461108 -250.400589)
		(end 332.744064 -250.476766)
		(width 0.0889)
		(layer "In11.Cu")
		(net "M_F_CPU0_ALERT_R_N")
	)
	(arc
		(start 327.478136 -250.476766)
		(mid 327.761092 -250.400589)
		(end 328.044048 -250.476766)
		(width 0.0889)
		(layer "In11.Cu")
		(net "M_F_CPU0_ALERT_R_N")
	)
	(arc
		(start 326.538082 -250.476766)
		(mid 326.821038 -250.400589)
		(end 327.103994 -250.476766)
		(width 0.0889)
		(layer "In11.Cu")
		(net "M_F_CPU0_ALERT_R_N")
	)
	(arc
		(start 330.863956 -250.476766)
		(mid 331.046207 -250.527116)
		(end 331.229716 -250.481592)
		(width 0.0889)
		(layer "In11.Cu")
		(net "M_F_CPU0_ALERT_R_N")
	)
	(arc
		(start 330.298044 -250.476766)
		(mid 330.581 -250.400589)
		(end 330.863956 -250.476766)
		(width 0.0889)
		(layer "In11.Cu")
		(net "M_F_CPU0_ALERT_R_N")
	)
	(arc
		(start 328.41819 -250.476766)
		(mid 328.701146 -250.400589)
		(end 328.984102 -250.476766)
		(width 0.0889)
		(layer "In11.Cu")
		(net "M_F_CPU0_ALERT_R_N")
	)
	(arc
		(start 329.924156 -250.476766)
		(mid 330.1111 -250.527021)
		(end 330.298044 -250.476766)
		(width 0.0889)
		(layer "In11.Cu")
		(net "M_F_CPU0_ALERT_R_N")
	)
	(arc
		(start 329.358244 -250.476766)
		(mid 329.6412 -250.400589)
		(end 329.924156 -250.476766)
		(width 0.0889)
		(layer "In11.Cu")
		(net "M_F_CPU0_ALERT_R_N")
	)
	(arc
		(start 328.992484 -250.481592)
		(mid 329.175992 -250.527086)
		(end 329.358244 -250.476766)
		(width 0.0889)
		(layer "In11.Cu")
		(net "M_F_CPU0_ALERT_R_N")
	)
	(arc
		(start 326.315832 -250.525534)
		(mid 326.424197 -250.520059)
		(end 326.526398 -250.483624)
		(width 0.0889)
		(layer "In11.Cu")
		(net "M_F_CPU0_ALERT_R_N")
	)
	(arc
		(start 331.80401 -250.476766)
		(mid 331.986261 -250.527116)
		(end 332.16977 -250.481592)
		(width 0.0889)
		(layer "In11.Cu")
		(net "M_F_CPU0_ALERT_R_N")
	)
	(arc
		(start 333.118206 -250.476766)
		(mid 333.365919 -250.401546)
		(end 333.621126 -250.445016)
		(width 0.0889)
		(layer "In11.Cu")
		(net "M_F_CPU0_ALERT_R_N")
	)
	(arc
		(start 331.238098 -250.476766)
		(mid 331.521054 -250.400589)
		(end 331.80401 -250.476766)
		(width 0.0889)
		(layer "In11.Cu")
		(net "M_F_CPU0_ALERT_R_N")
	)
	(via
		(at 269.648178 -244.08511)
		(size 0.4826)
		(drill 0.254)
		(layers "F.Cu" "B.Cu")
		(net "M_F_CPU0_ALERT_N")
	)
	(segment
		(start 270.245078 -244.08511)
		(end 269.648178 -244.08511)
		(width 0.10668)
		(layer "B.Cu")
		(net "M_F_CPU0_ALERT_N")
	)
	(segment
		(start 81.997804 -267.340334)
		(end 81.530952 -267.606272)
		(width 0.10668)
		(layer "F.Cu")
		(net "M_E_CPU1_SB_RSP<0>")
	)
	(segment
		(start 43.064938 -269.739364)
		(end 43.32224 -269.739364)
		(width 0.11684)
		(layer "In6.Cu")
		(net "M_E_CPU1_SB_RSP<0>")
	)
	(segment
		(start 40.951658 -269.739364)
		(end 41.20896 -269.739364)
		(width 0.11684)
		(layer "In6.Cu")
		(net "M_E_CPU1_SB_RSP<0>")
	)
	(segment
		(start 46.545754 -270.010382)
		(end 46.803056 -270.010382)
		(width 0.11684)
		(layer "In6.Cu")
		(net "M_E_CPU1_SB_RSP<0>")
	)
	(segment
		(start 42.79392 -270.010382)
		(end 43.064938 -269.739364)
		(width 0.11684)
		(layer "In6.Cu")
		(net "M_E_CPU1_SB_RSP<0>")
	)
	(segment
		(start 79.82331 -267.929868)
		(end 79.834994 -267.923264)
		(width 0.1016)
		(layer "In6.Cu")
		(net "M_E_CPU1_SB_RSP<0>")
	)
	(segment
		(start 42.536618 -270.010382)
		(end 42.79392 -270.010382)
		(width 0.11684)
		(layer "In6.Cu")
		(net "M_E_CPU1_SB_RSP<0>")
	)
	(segment
		(start 43.32224 -269.739364)
		(end 43.593258 -270.010382)
		(width 0.11684)
		(layer "In6.Cu")
		(net "M_E_CPU1_SB_RSP<0>")
	)
	(segment
		(start 42.2656 -269.739364)
		(end 42.536618 -270.010382)
		(width 0.11684)
		(layer "In6.Cu")
		(net "M_E_CPU1_SB_RSP<0>")
	)
	(segment
		(start 46.803056 -270.010382)
		(end 47.074074 -269.739364)
		(width 0.11684)
		(layer "In6.Cu")
		(net "M_E_CPU1_SB_RSP<0>")
	)
	(segment
		(start 34.999422 -270.010382)
		(end 35.231324 -270.010382)
		(width 0.11684)
		(layer "In6.Cu")
		(net "M_E_CPU1_SB_RSP<0>")
	)
	(segment
		(start 40.68064 -270.010382)
		(end 40.951658 -269.739364)
		(width 0.11684)
		(layer "In6.Cu")
		(net "M_E_CPU1_SB_RSP<0>")
	)
	(segment
		(start 47.331376 -269.739364)
		(end 47.602394 -270.010382)
		(width 0.11684)
		(layer "In6.Cu")
		(net "M_E_CPU1_SB_RSP<0>")
	)
	(segment
		(start 35.759644 -269.713964)
		(end 36.056062 -270.010382)
		(width 0.11684)
		(layer "In6.Cu")
		(net "M_E_CPU1_SB_RSP<0>")
	)
	(segment
		(start 43.593258 -270.010382)
		(end 44.689776 -270.010382)
		(width 0.11684)
		(layer "In6.Cu")
		(net "M_E_CPU1_SB_RSP<0>")
	)
	(segment
		(start 79.834994 -267.923264)
		(end 79.845662 -267.917168)
		(width 0.1016)
		(layer "In6.Cu")
		(net "M_E_CPU1_SB_RSP<0>")
	)
	(segment
		(start 62.900306 -266.851384)
		(end 75.968606 -266.851384)
		(width 0.11684)
		(layer "In6.Cu")
		(net "M_E_CPU1_SB_RSP<0>")
	)
	(segment
		(start 39.104824 -270.010382)
		(end 40.68064 -270.010382)
		(width 0.11684)
		(layer "In6.Cu")
		(net "M_E_CPU1_SB_RSP<0>")
	)
	(segment
		(start 33.646364 -269.713964)
		(end 33.942782 -270.010382)
		(width 0.11684)
		(layer "In6.Cu")
		(net "M_E_CPU1_SB_RSP<0>")
	)
	(segment
		(start 45.218096 -269.739364)
		(end 45.489114 -270.010382)
		(width 0.11684)
		(layer "In6.Cu")
		(net "M_E_CPU1_SB_RSP<0>")
	)
	(segment
		(start 38.048184 -270.010382)
		(end 38.280086 -270.010382)
		(width 0.11684)
		(layer "In6.Cu")
		(net "M_E_CPU1_SB_RSP<0>")
	)
	(segment
		(start 46.017434 -269.739364)
		(end 46.274736 -269.739364)
		(width 0.11684)
		(layer "In6.Cu")
		(net "M_E_CPU1_SB_RSP<0>")
	)
	(segment
		(start 45.489114 -270.010382)
		(end 45.746416 -270.010382)
		(width 0.11684)
		(layer "In6.Cu")
		(net "M_E_CPU1_SB_RSP<0>")
	)
	(segment
		(start 34.174684 -270.010382)
		(end 34.471102 -269.713964)
		(width 0.11684)
		(layer "In6.Cu")
		(net "M_E_CPU1_SB_RSP<0>")
	)
	(segment
		(start 41.479978 -270.010382)
		(end 41.73728 -270.010382)
		(width 0.11684)
		(layer "In6.Cu")
		(net "M_E_CPU1_SB_RSP<0>")
	)
	(segment
		(start 37.519864 -269.713964)
		(end 37.751766 -269.713964)
		(width 0.11684)
		(layer "In6.Cu")
		(net "M_E_CPU1_SB_RSP<0>")
	)
	(segment
		(start 76.748386 -267.275564)
		(end 77.684884 -267.275564)
		(width 0.1016)
		(layer "In6.Cu")
		(net "M_E_CPU1_SB_RSP<0>")
	)
	(segment
		(start 37.751766 -269.713964)
		(end 38.048184 -270.010382)
		(width 0.11684)
		(layer "In6.Cu")
		(net "M_E_CPU1_SB_RSP<0>")
	)
	(segment
		(start 47.602394 -270.010382)
		(end 59.741308 -270.010382)
		(width 0.11684)
		(layer "In6.Cu")
		(net "M_E_CPU1_SB_RSP<0>")
	)
	(segment
		(start 47.074074 -269.739364)
		(end 47.331376 -269.739364)
		(width 0.11684)
		(layer "In6.Cu")
		(net "M_E_CPU1_SB_RSP<0>")
	)
	(segment
		(start 81.279492 -267.889736)
		(end 81.382108 -267.862558)
		(width 0.1016)
		(layer "In6.Cu")
		(net "M_E_CPU1_SB_RSP<0>")
	)
	(segment
		(start 33.118044 -270.010382)
		(end 33.414462 -269.713964)
		(width 0.11684)
		(layer "In6.Cu")
		(net "M_E_CPU1_SB_RSP<0>")
	)
	(segment
		(start 36.056062 -270.010382)
		(end 37.223446 -270.010382)
		(width 0.11684)
		(layer "In6.Cu")
		(net "M_E_CPU1_SB_RSP<0>")
	)
	(segment
		(start 29.677106 -270.010382)
		(end 33.118044 -270.010382)
		(width 0.11684)
		(layer "In6.Cu")
		(net "M_E_CPU1_SB_RSP<0>")
	)
	(segment
		(start 44.960794 -269.739364)
		(end 45.218096 -269.739364)
		(width 0.11684)
		(layer "In6.Cu")
		(net "M_E_CPU1_SB_RSP<0>")
	)
	(segment
		(start 33.414462 -269.713964)
		(end 33.646364 -269.713964)
		(width 0.11684)
		(layer "In6.Cu")
		(net "M_E_CPU1_SB_RSP<0>")
	)
	(segment
		(start 37.223446 -270.010382)
		(end 37.519864 -269.713964)
		(width 0.11684)
		(layer "In6.Cu")
		(net "M_E_CPU1_SB_RSP<0>")
	)
	(segment
		(start 35.231324 -270.010382)
		(end 35.527742 -269.713964)
		(width 0.11684)
		(layer "In6.Cu")
		(net "M_E_CPU1_SB_RSP<0>")
	)
	(segment
		(start 78.89494 -267.923264)
		(end 78.905608 -267.917168)
		(width 0.1016)
		(layer "In6.Cu")
		(net "M_E_CPU1_SB_RSP<0>")
	)
	(segment
		(start 77.684884 -267.275564)
		(end 78.527402 -267.923264)
		(width 0.1016)
		(layer "In6.Cu")
		(net "M_E_CPU1_SB_RSP<0>")
	)
	(segment
		(start 59.741308 -270.010382)
		(end 62.900306 -266.851384)
		(width 0.11684)
		(layer "In6.Cu")
		(net "M_E_CPU1_SB_RSP<0>")
	)
	(segment
		(start 34.471102 -269.713964)
		(end 34.703004 -269.713964)
		(width 0.11684)
		(layer "In6.Cu")
		(net "M_E_CPU1_SB_RSP<0>")
	)
	(segment
		(start 76.324206 -266.851384)
		(end 76.748386 -267.275564)
		(width 0.1016)
		(layer "In6.Cu")
		(net "M_E_CPU1_SB_RSP<0>")
	)
	(segment
		(start 38.576504 -269.713964)
		(end 38.808406 -269.713964)
		(width 0.11684)
		(layer "In6.Cu")
		(net "M_E_CPU1_SB_RSP<0>")
	)
	(segment
		(start 81.382108 -267.862558)
		(end 81.530952 -267.606272)
		(width 0.1016)
		(layer "In6.Cu")
		(net "M_E_CPU1_SB_RSP<0>")
	)
	(segment
		(start 45.746416 -270.010382)
		(end 46.017434 -269.739364)
		(width 0.11684)
		(layer "In6.Cu")
		(net "M_E_CPU1_SB_RSP<0>")
	)
	(segment
		(start 75.968606 -266.851384)
		(end 76.324206 -266.851384)
		(width 0.1016)
		(layer "In6.Cu")
		(net "M_E_CPU1_SB_RSP<0>")
	)
	(segment
		(start 41.73728 -270.010382)
		(end 42.008298 -269.739364)
		(width 0.11684)
		(layer "In6.Cu")
		(net "M_E_CPU1_SB_RSP<0>")
	)
	(segment
		(start 35.527742 -269.713964)
		(end 35.759644 -269.713964)
		(width 0.11684)
		(layer "In6.Cu")
		(net "M_E_CPU1_SB_RSP<0>")
	)
	(segment
		(start 41.20896 -269.739364)
		(end 41.479978 -270.010382)
		(width 0.11684)
		(layer "In6.Cu")
		(net "M_E_CPU1_SB_RSP<0>")
	)
	(segment
		(start 33.942782 -270.010382)
		(end 34.174684 -270.010382)
		(width 0.11684)
		(layer "In6.Cu")
		(net "M_E_CPU1_SB_RSP<0>")
	)
	(segment
		(start 34.703004 -269.713964)
		(end 34.999422 -270.010382)
		(width 0.11684)
		(layer "In6.Cu")
		(net "M_E_CPU1_SB_RSP<0>")
	)
	(segment
		(start 42.008298 -269.739364)
		(end 42.2656 -269.739364)
		(width 0.11684)
		(layer "In6.Cu")
		(net "M_E_CPU1_SB_RSP<0>")
	)
	(segment
		(start 44.689776 -270.010382)
		(end 44.960794 -269.739364)
		(width 0.11684)
		(layer "In6.Cu")
		(net "M_E_CPU1_SB_RSP<0>")
	)
	(segment
		(start 46.274736 -269.739364)
		(end 46.545754 -270.010382)
		(width 0.11684)
		(layer "In6.Cu")
		(net "M_E_CPU1_SB_RSP<0>")
	)
	(segment
		(start 29.252164 -270.435324)
		(end 29.677106 -270.010382)
		(width 0.11684)
		(layer "In6.Cu")
		(net "M_E_CPU1_SB_RSP<0>")
	)
	(segment
		(start 38.280086 -270.010382)
		(end 38.576504 -269.713964)
		(width 0.11684)
		(layer "In6.Cu")
		(net "M_E_CPU1_SB_RSP<0>")
	)
	(segment
		(start 78.527402 -267.923264)
		(end 78.53553 -267.92809)
		(width 0.1016)
		(layer "In6.Cu")
		(net "M_E_CPU1_SB_RSP<0>")
	)
	(segment
		(start 38.808406 -269.713964)
		(end 39.104824 -270.010382)
		(width 0.11684)
		(layer "In6.Cu")
		(net "M_E_CPU1_SB_RSP<0>")
	)
	(arc
		(start 80.407256 -267.923264)
		(mid 80.591152 -267.972744)
		(end 80.775048 -267.923264)
		(width 0.1016)
		(layer "In6.Cu")
		(net "M_E_CPU1_SB_RSP<0>")
	)
	(arc
		(start 78.905608 -267.917168)
		(mid 79.187197 -267.846294)
		(end 79.467202 -267.923264)
		(width 0.1016)
		(layer "In6.Cu")
		(net "M_E_CPU1_SB_RSP<0>")
	)
	(arc
		(start 79.467202 -267.923264)
		(mid 79.644388 -267.972682)
		(end 79.82331 -267.929868)
		(width 0.1016)
		(layer "In6.Cu")
		(net "M_E_CPU1_SB_RSP<0>")
	)
	(arc
		(start 78.53553 -267.92809)
		(mid 78.71588 -267.972808)
		(end 78.89494 -267.923264)
		(width 0.1016)
		(layer "In6.Cu")
		(net "M_E_CPU1_SB_RSP<0>")
	)
	(arc
		(start 80.775048 -267.923264)
		(mid 81.023342 -267.847561)
		(end 81.279492 -267.889736)
		(width 0.1016)
		(layer "In6.Cu")
		(net "M_E_CPU1_SB_RSP<0>")
	)
	(arc
		(start 79.845662 -267.917168)
		(mid 80.127251 -267.846294)
		(end 80.407256 -267.923264)
		(width 0.1016)
		(layer "In6.Cu")
		(net "M_E_CPU1_SB_RSP<0>")
	)
	(segment
		(start 81.527904 -264.910316)
		(end 81.061052 -265.176254)
		(width 0.10668)
		(layer "F.Cu")
		(net "M_E_CPU1_SB_PAR")
	)
	(segment
		(start 76.312776 -265.074654)
		(end 76.880466 -264.506964)
		(width 0.0889)
		(layer "In6.Cu")
		(net "M_E_CPU1_SB_PAR")
	)
	(segment
		(start 79.360014 -264.848848)
		(end 79.368396 -264.853674)
		(width 0.0889)
		(layer "In6.Cu")
		(net "M_E_CPU1_SB_PAR")
	)
	(segment
		(start 81.214976 -264.910824)
		(end 81.061052 -265.176254)
		(width 0.0889)
		(layer "In6.Cu")
		(net "M_E_CPU1_SB_PAR")
	)
	(segment
		(start 77.67193 -264.803636)
		(end 78.24216 -264.803636)
		(width 0.0889)
		(layer "In6.Cu")
		(net "M_E_CPU1_SB_PAR")
	)
	(segment
		(start 59.699652 -266.610338)
		(end 61.235336 -265.074654)
		(width 0.14478)
		(layer "In6.Cu")
		(net "M_E_CPU1_SB_PAR")
	)
	(segment
		(start 77.375258 -264.506964)
		(end 77.67193 -264.803636)
		(width 0.0889)
		(layer "In6.Cu")
		(net "M_E_CPU1_SB_PAR")
	)
	(segment
		(start 79.92364 -264.85977)
		(end 79.934054 -264.853674)
		(width 0.0889)
		(layer "In6.Cu")
		(net "M_E_CPU1_SB_PAR")
	)
	(segment
		(start 81.192624 -264.827512)
		(end 81.214976 -264.910824)
		(width 0.0889)
		(layer "In6.Cu")
		(net "M_E_CPU1_SB_PAR")
	)
	(segment
		(start 25.577038 -266.610338)
		(end 59.699652 -266.610338)
		(width 0.14478)
		(layer "In6.Cu")
		(net "M_E_CPU1_SB_PAR")
	)
	(segment
		(start 76.880466 -264.506964)
		(end 77.375258 -264.506964)
		(width 0.0889)
		(layer "In6.Cu")
		(net "M_E_CPU1_SB_PAR")
	)
	(segment
		(start 78.428342 -264.853674)
		(end 78.443074 -264.86231)
		(width 0.0889)
		(layer "In6.Cu")
		(net "M_E_CPU1_SB_PAR")
	)
	(segment
		(start 61.235336 -265.074654)
		(end 75.966066 -265.074654)
		(width 0.14478)
		(layer "In6.Cu")
		(net "M_E_CPU1_SB_PAR")
	)
	(segment
		(start 75.966066 -265.074654)
		(end 76.312776 -265.074654)
		(width 0.0889)
		(layer "In6.Cu")
		(net "M_E_CPU1_SB_PAR")
	)
	(segment
		(start 79.934054 -264.853674)
		(end 79.942436 -264.848848)
		(width 0.0889)
		(layer "In6.Cu")
		(net "M_E_CPU1_SB_PAR")
	)
	(segment
		(start 25.152096 -267.03528)
		(end 25.577038 -266.610338)
		(width 0.14478)
		(layer "In6.Cu")
		(net "M_E_CPU1_SB_PAR")
	)
	(arc
		(start 78.443074 -264.86231)
		(mid 78.719803 -264.929993)
		(end 78.994254 -264.853674)
		(width 0.0889)
		(layer "In6.Cu")
		(net "M_E_CPU1_SB_PAR")
	)
	(arc
		(start 79.368396 -264.853674)
		(mid 79.645209 -264.929817)
		(end 79.92364 -264.85977)
		(width 0.0889)
		(layer "In6.Cu")
		(net "M_E_CPU1_SB_PAR")
	)
	(arc
		(start 80.308196 -264.853674)
		(mid 80.591152 -264.929851)
		(end 80.874108 -264.853674)
		(width 0.0889)
		(layer "In6.Cu")
		(net "M_E_CPU1_SB_PAR")
	)
	(arc
		(start 78.24216 -264.803636)
		(mid 78.338534 -264.816433)
		(end 78.428342 -264.853674)
		(width 0.0889)
		(layer "In6.Cu")
		(net "M_E_CPU1_SB_PAR")
	)
	(arc
		(start 79.942436 -264.848848)
		(mid 80.125944 -264.803354)
		(end 80.308196 -264.853674)
		(width 0.0889)
		(layer "In6.Cu")
		(net "M_E_CPU1_SB_PAR")
	)
	(arc
		(start 80.874108 -264.853674)
		(mid 81.030427 -264.804679)
		(end 81.192624 -264.827512)
		(width 0.0889)
		(layer "In6.Cu")
		(net "M_E_CPU1_SB_PAR")
	)
	(arc
		(start 78.994254 -264.853674)
		(mid 79.176505 -264.803324)
		(end 79.360014 -264.848848)
		(width 0.0889)
		(layer "In6.Cu")
		(net "M_E_CPU1_SB_PAR")
	)
	(segment
		(start 81.997804 -270.580358)
		(end 81.530952 -270.846296)
		(width 0.12954)
		(layer "F.Cu")
		(net "M_E_CPU1_SB_DQS_DP<9>")
	)
	(segment
		(start 58.828178 -274.958048)
		(end 58.828178 -274.396708)
		(width 0.16002)
		(layer "In6.Cu")
		(net "M_E_CPU1_SB_DQS_DP<9>")
	)
	(segment
		(start 60.01766 -274.021804)
		(end 60.63615 -273.403314)
		(width 0.16002)
		(layer "In6.Cu")
		(net "M_E_CPU1_SB_DQS_DP<9>")
	)
	(segment
		(start 76.308712 -269.592552)
		(end 76.861924 -270.145764)
		(width 0.09525)
		(layer "In6.Cu")
		(net "M_E_CPU1_SB_DQS_DP<9>")
	)
	(segment
		(start 34.210498 -276.078696)
		(end 35.14979 -275.139404)
		(width 0.16002)
		(layer "In6.Cu")
		(net "M_E_CPU1_SB_DQS_DP<9>")
	)
	(segment
		(start 63.963804 -269.533624)
		(end 75.955906 -269.533624)
		(width 0.16002)
		(layer "In6.Cu")
		(net "M_E_CPU1_SB_DQS_DP<9>")
	)
	(segment
		(start 32.230568 -275.643594)
		(end 33.525206 -275.643594)
		(width 0.16002)
		(layer "In6.Cu")
		(net "M_E_CPU1_SB_DQS_DP<9>")
	)
	(segment
		(start 57.78119 -275.164804)
		(end 58.621422 -275.164804)
		(width 0.16002)
		(layer "In6.Cu")
		(net "M_E_CPU1_SB_DQS_DP<9>")
	)
	(segment
		(start 45.513752 -275.643594)
		(end 48.62068 -275.643594)
		(width 0.16002)
		(layer "In6.Cu")
		(net "M_E_CPU1_SB_DQS_DP<9>")
	)
	(segment
		(start 59.203082 -274.021804)
		(end 60.01766 -274.021804)
		(width 0.16002)
		(layer "In6.Cu")
		(net "M_E_CPU1_SB_DQS_DP<9>")
	)
	(segment
		(start 54.754526 -275.796248)
		(end 54.754526 -274.904708)
		(width 0.16002)
		(layer "In6.Cu")
		(net "M_E_CPU1_SB_DQS_DP<9>")
	)
	(segment
		(start 31.122366 -274.820126)
		(end 31.73349 -274.820126)
		(width 0.16002)
		(layer "In6.Cu")
		(net "M_E_CPU1_SB_DQS_DP<9>")
	)
	(segment
		(start 60.63615 -273.403314)
		(end 60.63615 -272.861278)
		(width 0.16002)
		(layer "In6.Cu")
		(net "M_E_CPU1_SB_DQS_DP<9>")
	)
	(segment
		(start 41.10228 -275.643594)
		(end 41.44899 -275.990304)
		(width 0.16002)
		(layer "In6.Cu")
		(net "M_E_CPU1_SB_DQS_DP<9>")
	)
	(segment
		(start 42.64279 -275.164804)
		(end 43.12539 -275.164804)
		(width 0.16002)
		(layer "In6.Cu")
		(net "M_E_CPU1_SB_DQS_DP<9>")
	)
	(segment
		(start 29.525976 -275.809202)
		(end 30.45968 -275.809202)
		(width 0.16002)
		(layer "In6.Cu")
		(net "M_E_CPU1_SB_DQS_DP<9>")
	)
	(segment
		(start 58.828178 -274.396708)
		(end 59.203082 -274.021804)
		(width 0.16002)
		(layer "In6.Cu")
		(net "M_E_CPU1_SB_DQS_DP<9>")
	)
	(segment
		(start 75.981306 -269.533624)
		(end 76.004928 -269.533624)
		(width 0.09525)
		(layer "In6.Cu")
		(net "M_E_CPU1_SB_DQS_DP<9>")
	)
	(segment
		(start 60.63615 -272.861278)
		(end 63.963804 -269.533624)
		(width 0.16002)
		(layer "In6.Cu")
		(net "M_E_CPU1_SB_DQS_DP<9>")
	)
	(segment
		(start 43.12539 -275.164804)
		(end 43.496484 -274.79371)
		(width 0.16002)
		(layer "In6.Cu")
		(net "M_E_CPU1_SB_DQS_DP<9>")
	)
	(segment
		(start 76.004928 -269.533624)
		(end 76.063856 -269.592552)
		(width 0.09525)
		(layer "In6.Cu")
		(net "M_E_CPU1_SB_DQS_DP<9>")
	)
	(segment
		(start 50.64379 -275.190204)
		(end 51.040284 -274.79371)
		(width 0.16002)
		(layer "In6.Cu")
		(net "M_E_CPU1_SB_DQS_DP<9>")
	)
	(segment
		(start 53.95595 -276.003004)
		(end 54.54777 -276.003004)
		(width 0.16002)
		(layer "In6.Cu")
		(net "M_E_CPU1_SB_DQS_DP<9>")
	)
	(segment
		(start 29.252164 -275.53539)
		(end 29.525976 -275.809202)
		(width 0.16002)
		(layer "In6.Cu")
		(net "M_E_CPU1_SB_DQS_DP<9>")
	)
	(segment
		(start 80.771238 -271.176242)
		(end 80.77962 -271.171416)
		(width 0.09525)
		(layer "In6.Cu")
		(net "M_E_CPU1_SB_DQS_DP<9>")
	)
	(segment
		(start 55.659782 -274.529804)
		(end 56.034686 -274.904708)
		(width 0.16002)
		(layer "In6.Cu")
		(net "M_E_CPU1_SB_DQS_DP<9>")
	)
	(segment
		(start 30.785308 -275.483574)
		(end 30.785308 -275.157184)
		(width 0.16002)
		(layer "In6.Cu")
		(net "M_E_CPU1_SB_DQS_DP<9>")
	)
	(segment
		(start 38.374574 -275.648166)
		(end 38.374574 -275.130768)
		(width 0.16002)
		(layer "In6.Cu")
		(net "M_E_CPU1_SB_DQS_DP<9>")
	)
	(segment
		(start 56.94299 -276.003004)
		(end 57.78119 -275.164804)
		(width 0.16002)
		(layer "In6.Cu")
		(net "M_E_CPU1_SB_DQS_DP<9>")
	)
	(segment
		(start 41.44899 -275.990304)
		(end 41.81729 -275.990304)
		(width 0.16002)
		(layer "In6.Cu")
		(net "M_E_CPU1_SB_DQS_DP<9>")
	)
	(segment
		(start 56.034686 -275.796248)
		(end 56.241442 -276.003004)
		(width 0.16002)
		(layer "In6.Cu")
		(net "M_E_CPU1_SB_DQS_DP<9>")
	)
	(segment
		(start 40.397684 -275.643594)
		(end 41.10228 -275.643594)
		(width 0.16002)
		(layer "In6.Cu")
		(net "M_E_CPU1_SB_DQS_DP<9>")
	)
	(segment
		(start 41.81729 -275.990304)
		(end 42.64279 -275.164804)
		(width 0.16002)
		(layer "In6.Cu")
		(net "M_E_CPU1_SB_DQS_DP<9>")
	)
	(segment
		(start 44.663868 -274.79371)
		(end 45.513752 -275.643594)
		(width 0.16002)
		(layer "In6.Cu")
		(net "M_E_CPU1_SB_DQS_DP<9>")
	)
	(segment
		(start 33.960308 -276.078696)
		(end 34.210498 -276.078696)
		(width 0.16002)
		(layer "In6.Cu")
		(net "M_E_CPU1_SB_DQS_DP<9>")
	)
	(segment
		(start 56.034686 -274.904708)
		(end 56.034686 -275.796248)
		(width 0.16002)
		(layer "In6.Cu")
		(net "M_E_CPU1_SB_DQS_DP<9>")
	)
	(segment
		(start 32.070548 -275.483574)
		(end 32.230568 -275.643594)
		(width 0.16002)
		(layer "In6.Cu")
		(net "M_E_CPU1_SB_DQS_DP<9>")
	)
	(segment
		(start 49.38649 -275.990304)
		(end 50.18659 -275.190204)
		(width 0.16002)
		(layer "In6.Cu")
		(net "M_E_CPU1_SB_DQS_DP<9>")
	)
	(segment
		(start 37.693854 -275.130768)
		(end 37.693854 -275.648166)
		(width 0.16002)
		(layer "In6.Cu")
		(net "M_E_CPU1_SB_DQS_DP<9>")
	)
	(segment
		(start 55.12943 -274.529804)
		(end 55.659782 -274.529804)
		(width 0.16002)
		(layer "In6.Cu")
		(net "M_E_CPU1_SB_DQS_DP<9>")
	)
	(segment
		(start 43.496484 -274.79371)
		(end 44.663868 -274.79371)
		(width 0.16002)
		(layer "In6.Cu")
		(net "M_E_CPU1_SB_DQS_DP<9>")
	)
	(segment
		(start 38.214554 -275.808186)
		(end 38.374574 -275.648166)
		(width 0.16002)
		(layer "In6.Cu")
		(net "M_E_CPU1_SB_DQS_DP<9>")
	)
	(segment
		(start 35.14979 -275.139404)
		(end 35.60699 -275.139404)
		(width 0.16002)
		(layer "In6.Cu")
		(net "M_E_CPU1_SB_DQS_DP<9>")
	)
	(segment
		(start 35.60699 -275.139404)
		(end 35.952684 -274.79371)
		(width 0.16002)
		(layer "In6.Cu")
		(net "M_E_CPU1_SB_DQS_DP<9>")
	)
	(segment
		(start 52.746656 -274.79371)
		(end 53.95595 -276.003004)
		(width 0.16002)
		(layer "In6.Cu")
		(net "M_E_CPU1_SB_DQS_DP<9>")
	)
	(segment
		(start 33.525206 -275.643594)
		(end 33.960308 -276.078696)
		(width 0.16002)
		(layer "In6.Cu")
		(net "M_E_CPU1_SB_DQS_DP<9>")
	)
	(segment
		(start 78.55077 -271.203928)
		(end 78.551024 -271.203928)
		(width 0.09525)
		(layer "In6.Cu")
		(net "M_E_CPU1_SB_DQS_DP<9>")
	)
	(segment
		(start 32.070548 -275.157184)
		(end 32.070548 -275.483574)
		(width 0.16002)
		(layer "In6.Cu")
		(net "M_E_CPU1_SB_DQS_DP<9>")
	)
	(segment
		(start 56.241442 -276.003004)
		(end 56.94299 -276.003004)
		(width 0.16002)
		(layer "In6.Cu")
		(net "M_E_CPU1_SB_DQS_DP<9>")
	)
	(segment
		(start 81.27619 -271.138396)
		(end 81.377028 -271.111726)
		(width 0.09525)
		(layer "In6.Cu")
		(net "M_E_CPU1_SB_DQS_DP<9>")
	)
	(segment
		(start 30.45968 -275.809202)
		(end 30.785308 -275.483574)
		(width 0.16002)
		(layer "In6.Cu")
		(net "M_E_CPU1_SB_DQS_DP<9>")
	)
	(segment
		(start 37.853874 -275.808186)
		(end 38.214554 -275.808186)
		(width 0.16002)
		(layer "In6.Cu")
		(net "M_E_CPU1_SB_DQS_DP<9>")
	)
	(segment
		(start 58.621422 -275.164804)
		(end 58.828178 -274.958048)
		(width 0.16002)
		(layer "In6.Cu")
		(net "M_E_CPU1_SB_DQS_DP<9>")
	)
	(segment
		(start 37.356796 -274.79371)
		(end 37.693854 -275.130768)
		(width 0.16002)
		(layer "In6.Cu")
		(net "M_E_CPU1_SB_DQS_DP<9>")
	)
	(segment
		(start 30.785308 -275.157184)
		(end 31.122366 -274.820126)
		(width 0.16002)
		(layer "In6.Cu")
		(net "M_E_CPU1_SB_DQS_DP<9>")
	)
	(segment
		(start 38.374574 -275.130768)
		(end 38.711632 -274.79371)
		(width 0.16002)
		(layer "In6.Cu")
		(net "M_E_CPU1_SB_DQS_DP<9>")
	)
	(segment
		(start 54.54777 -276.003004)
		(end 54.754526 -275.796248)
		(width 0.16002)
		(layer "In6.Cu")
		(net "M_E_CPU1_SB_DQS_DP<9>")
	)
	(segment
		(start 31.73349 -274.820126)
		(end 32.070548 -275.157184)
		(width 0.16002)
		(layer "In6.Cu")
		(net "M_E_CPU1_SB_DQS_DP<9>")
	)
	(segment
		(start 38.711632 -274.79371)
		(end 39.5478 -274.79371)
		(width 0.16002)
		(layer "In6.Cu")
		(net "M_E_CPU1_SB_DQS_DP<9>")
	)
	(segment
		(start 39.5478 -274.79371)
		(end 40.397684 -275.643594)
		(width 0.16002)
		(layer "In6.Cu")
		(net "M_E_CPU1_SB_DQS_DP<9>")
	)
	(segment
		(start 50.18659 -275.190204)
		(end 50.64379 -275.190204)
		(width 0.16002)
		(layer "In6.Cu")
		(net "M_E_CPU1_SB_DQS_DP<9>")
	)
	(segment
		(start 48.62068 -275.643594)
		(end 48.96739 -275.990304)
		(width 0.16002)
		(layer "In6.Cu")
		(net "M_E_CPU1_SB_DQS_DP<9>")
	)
	(segment
		(start 48.96739 -275.990304)
		(end 49.38649 -275.990304)
		(width 0.16002)
		(layer "In6.Cu")
		(net "M_E_CPU1_SB_DQS_DP<9>")
	)
	(segment
		(start 51.040284 -274.79371)
		(end 52.746656 -274.79371)
		(width 0.16002)
		(layer "In6.Cu")
		(net "M_E_CPU1_SB_DQS_DP<9>")
	)
	(segment
		(start 37.693854 -275.648166)
		(end 37.853874 -275.808186)
		(width 0.16002)
		(layer "In6.Cu")
		(net "M_E_CPU1_SB_DQS_DP<9>")
	)
	(segment
		(start 76.861924 -270.145764)
		(end 77.493114 -270.145764)
		(width 0.09525)
		(layer "In6.Cu")
		(net "M_E_CPU1_SB_DQS_DP<9>")
	)
	(segment
		(start 77.493114 -270.145764)
		(end 78.55077 -271.203928)
		(width 0.09525)
		(layer "In6.Cu")
		(net "M_E_CPU1_SB_DQS_DP<9>")
	)
	(segment
		(start 35.952684 -274.79371)
		(end 37.356796 -274.79371)
		(width 0.16002)
		(layer "In6.Cu")
		(net "M_E_CPU1_SB_DQS_DP<9>")
	)
	(segment
		(start 81.377028 -271.111726)
		(end 81.530952 -270.846296)
		(width 0.09525)
		(layer "In6.Cu")
		(net "M_E_CPU1_SB_DQS_DP<9>")
	)
	(segment
		(start 54.754526 -274.904708)
		(end 55.12943 -274.529804)
		(width 0.16002)
		(layer "In6.Cu")
		(net "M_E_CPU1_SB_DQS_DP<9>")
	)
	(segment
		(start 75.955906 -269.533624)
		(end 75.981306 -269.533624)
		(width 0.1016)
		(layer "In6.Cu")
		(net "M_E_CPU1_SB_DQS_DP<9>")
	)
	(segment
		(start 76.063856 -269.592552)
		(end 76.308712 -269.592552)
		(width 0.09525)
		(layer "In6.Cu")
		(net "M_E_CPU1_SB_DQS_DP<9>")
	)
	(arc
		(start 78.636114 -271.246346)
		(mid 79.214432 -271.268137)
		(end 79.786988 -271.183862)
		(width 0.09525)
		(layer "In6.Cu")
		(net "M_E_CPU1_SB_DQS_DP<9>")
	)
	(arc
		(start 80.77962 -271.171416)
		(mid 81.013415 -271.097549)
		(end 81.256378 -271.130522)
		(width 0.09525)
		(layer "In6.Cu")
		(net "M_E_CPU1_SB_DQS_DP<9>")
	)
	(arc
		(start 78.551024 -271.203928)
		(mid 78.589147 -271.231713)
		(end 78.634082 -271.246092)
		(width 0.09525)
		(layer "In6.Cu")
		(net "M_E_CPU1_SB_DQS_DP<9>")
	)
	(arc
		(start 81.256378 -271.130522)
		(mid 81.266321 -271.134365)
		(end 81.27619 -271.138396)
		(width 0.09525)
		(layer "In6.Cu")
		(net "M_E_CPU1_SB_DQS_DP<9>")
	)
	(arc
		(start 78.634082 -271.246092)
		(mid 78.635098 -271.246222)
		(end 78.636114 -271.246346)
		(width 0.09525)
		(layer "In6.Cu")
		(net "M_E_CPU1_SB_DQS_DP<9>")
	)
	(arc
		(start 79.876396 -271.151604)
		(mid 80.141878 -271.095963)
		(end 80.40243 -271.171416)
		(width 0.09525)
		(layer "In6.Cu")
		(net "M_E_CPU1_SB_DQS_DP<9>")
	)
	(arc
		(start 80.40243 -271.171416)
		(mid 80.586205 -271.222188)
		(end 80.771238 -271.176242)
		(width 0.09525)
		(layer "In6.Cu")
		(net "M_E_CPU1_SB_DQS_DP<9>")
	)
	(arc
		(start 79.786988 -271.183862)
		(mid 79.832554 -271.170122)
		(end 79.876396 -271.151604)
		(width 0.09525)
		(layer "In6.Cu")
		(net "M_E_CPU1_SB_DQS_DP<9>")
	)
	(segment
		(start 82.937858 -291.64026)
		(end 82.471006 -291.906198)
		(width 0.12954)
		(layer "F.Cu")
		(net "M_E_CPU1_SB_DQS_DP<8>")
	)
	(segment
		(start 25.425908 -314.361576)
		(end 25.919938 -314.361576)
		(width 0.16002)
		(layer "In6.Cu")
		(net "M_E_CPU1_SB_DQS_DP<8>")
	)
	(segment
		(start 38.480492 -315.129926)
		(end 39.641526 -315.360558)
		(width 0.16002)
		(layer "In6.Cu")
		(net "M_E_CPU1_SB_DQS_DP<8>")
	)
	(segment
		(start 39.641526 -315.360558)
		(end 40.655748 -315.360558)
		(width 0.16002)
		(layer "In6.Cu")
		(net "M_E_CPU1_SB_DQS_DP<8>")
	)
	(segment
		(start 77.872336 -293.556944)
		(end 79.77251 -291.65677)
		(width 0.09525)
		(layer "In6.Cu")
		(net "M_E_CPU1_SB_DQS_DP<8>")
	)
	(segment
		(start 42.921174 -314.161424)
		(end 43.094402 -314.161424)
		(width 0.16002)
		(layer "In6.Cu")
		(net "M_E_CPU1_SB_DQS_DP<8>")
	)
	(segment
		(start 50.308764 -314.195206)
		(end 50.327814 -314.182506)
		(width 0.16002)
		(layer "In6.Cu")
		(net "M_E_CPU1_SB_DQS_DP<8>")
	)
	(segment
		(start 27.844496 -314.164218)
		(end 28.32354 -314.235084)
		(width 0.16002)
		(layer "In6.Cu")
		(net "M_E_CPU1_SB_DQS_DP<8>")
	)
	(segment
		(start 28.32354 -314.235084)
		(end 28.943046 -314.526168)
		(width 0.16002)
		(layer "In6.Cu")
		(net "M_E_CPU1_SB_DQS_DP<8>")
	)
	(segment
		(start 79.77251 -291.65677)
		(end 80.120998 -291.65677)
		(width 0.09525)
		(layer "In6.Cu")
		(net "M_E_CPU1_SB_DQS_DP<8>")
	)
	(segment
		(start 82.62493 -291.640768)
		(end 82.471006 -291.906198)
		(width 0.09525)
		(layer "In6.Cu")
		(net "M_E_CPU1_SB_DQS_DP<8>")
	)
	(segment
		(start 35.348926 -314.186824)
		(end 35.50412 -314.186824)
		(width 0.16002)
		(layer "In6.Cu")
		(net "M_E_CPU1_SB_DQS_DP<8>")
	)
	(segment
		(start 32.46628 -315.360558)
		(end 32.962342 -315.360558)
		(width 0.16002)
		(layer "In6.Cu")
		(net "M_E_CPU1_SB_DQS_DP<8>")
	)
	(segment
		(start 77.872336 -294.087804)
		(end 77.872336 -293.556944)
		(width 0.09525)
		(layer "In6.Cu")
		(net "M_E_CPU1_SB_DQS_DP<8>")
	)
	(segment
		(start 66.95313 -305.09083)
		(end 77.216508 -294.827452)
		(width 0.16002)
		(layer "In6.Cu")
		(net "M_E_CPU1_SB_DQS_DP<8>")
	)
	(segment
		(start 66.95313 -305.491388)
		(end 66.95313 -305.09083)
		(width 0.16002)
		(layer "In6.Cu")
		(net "M_E_CPU1_SB_DQS_DP<8>")
	)
	(segment
		(start 40.655748 -315.360558)
		(end 42.921174 -314.161424)
		(width 0.16002)
		(layer "In6.Cu")
		(net "M_E_CPU1_SB_DQS_DP<8>")
	)
	(segment
		(start 77.233272 -294.726868)
		(end 77.872336 -294.087804)
		(width 0.09525)
		(layer "In6.Cu")
		(net "M_E_CPU1_SB_DQS_DP<8>")
	)
	(segment
		(start 25.919938 -314.361576)
		(end 27.844496 -314.164218)
		(width 0.16002)
		(layer "In6.Cu")
		(net "M_E_CPU1_SB_DQS_DP<8>")
	)
	(segment
		(start 51.160172 -314.182506)
		(end 51.92649 -314.948824)
		(width 0.16002)
		(layer "In6.Cu")
		(net "M_E_CPU1_SB_DQS_DP<8>")
	)
	(segment
		(start 50.327814 -314.182506)
		(end 51.160172 -314.182506)
		(width 0.16002)
		(layer "In6.Cu")
		(net "M_E_CPU1_SB_DQS_DP<8>")
	)
	(segment
		(start 43.094402 -314.161424)
		(end 45.616876 -314.96762)
		(width 0.16002)
		(layer "In6.Cu")
		(net "M_E_CPU1_SB_DQS_DP<8>")
	)
	(segment
		(start 81.342484 -291.581078)
		(end 81.350866 -291.576252)
		(width 0.09525)
		(layer "In6.Cu")
		(net "M_E_CPU1_SB_DQS_DP<8>")
	)
	(segment
		(start 35.50412 -314.186824)
		(end 38.480492 -315.129926)
		(width 0.16002)
		(layer "In6.Cu")
		(net "M_E_CPU1_SB_DQS_DP<8>")
	)
	(segment
		(start 77.233272 -294.810688)
		(end 77.233272 -294.726868)
		(width 0.09525)
		(layer "In6.Cu")
		(net "M_E_CPU1_SB_DQS_DP<8>")
	)
	(segment
		(start 82.601816 -291.554154)
		(end 82.62493 -291.640768)
		(width 0.09525)
		(layer "In6.Cu")
		(net "M_E_CPU1_SB_DQS_DP<8>")
	)
	(segment
		(start 59.631834 -314.174124)
		(end 64.35725 -309.448708)
		(width 0.16002)
		(layer "In6.Cu")
		(net "M_E_CPU1_SB_DQS_DP<8>")
	)
	(segment
		(start 51.92649 -314.948824)
		(end 57.011062 -314.948824)
		(width 0.16002)
		(layer "In6.Cu")
		(net "M_E_CPU1_SB_DQS_DP<8>")
	)
	(segment
		(start 48.033432 -315.360558)
		(end 49.435004 -314.779152)
		(width 0.16002)
		(layer "In6.Cu")
		(net "M_E_CPU1_SB_DQS_DP<8>")
	)
	(segment
		(start 25.152096 -314.635388)
		(end 25.425908 -314.361576)
		(width 0.16002)
		(layer "In6.Cu")
		(net "M_E_CPU1_SB_DQS_DP<8>")
	)
	(segment
		(start 57.785762 -314.174124)
		(end 59.631834 -314.174124)
		(width 0.16002)
		(layer "In6.Cu")
		(net "M_E_CPU1_SB_DQS_DP<8>")
	)
	(segment
		(start 45.616876 -314.96762)
		(end 47.593758 -315.360558)
		(width 0.16002)
		(layer "In6.Cu")
		(net "M_E_CPU1_SB_DQS_DP<8>")
	)
	(segment
		(start 64.35725 -309.448708)
		(end 64.35725 -308.087268)
		(width 0.16002)
		(layer "In6.Cu")
		(net "M_E_CPU1_SB_DQS_DP<8>")
	)
	(segment
		(start 31.185358 -314.971938)
		(end 32.46628 -315.360558)
		(width 0.16002)
		(layer "In6.Cu")
		(net "M_E_CPU1_SB_DQS_DP<8>")
	)
	(segment
		(start 34.330386 -314.793884)
		(end 35.149028 -314.24753)
		(width 0.16002)
		(layer "In6.Cu")
		(net "M_E_CPU1_SB_DQS_DP<8>")
	)
	(segment
		(start 32.962342 -315.360558)
		(end 34.330386 -314.793884)
		(width 0.16002)
		(layer "In6.Cu")
		(net "M_E_CPU1_SB_DQS_DP<8>")
	)
	(segment
		(start 35.149028 -314.24753)
		(end 35.348926 -314.186824)
		(width 0.16002)
		(layer "In6.Cu")
		(net "M_E_CPU1_SB_DQS_DP<8>")
	)
	(segment
		(start 28.943046 -314.526168)
		(end 31.185358 -314.971938)
		(width 0.16002)
		(layer "In6.Cu")
		(net "M_E_CPU1_SB_DQS_DP<8>")
	)
	(segment
		(start 57.011062 -314.948824)
		(end 57.785762 -314.174124)
		(width 0.16002)
		(layer "In6.Cu")
		(net "M_E_CPU1_SB_DQS_DP<8>")
	)
	(segment
		(start 77.216508 -294.827452)
		(end 77.233272 -294.810688)
		(width 0.09525)
		(layer "In6.Cu")
		(net "M_E_CPU1_SB_DQS_DP<8>")
	)
	(segment
		(start 47.593758 -315.360558)
		(end 48.033432 -315.360558)
		(width 0.16002)
		(layer "In6.Cu")
		(net "M_E_CPU1_SB_DQS_DP<8>")
	)
	(segment
		(start 64.35725 -308.087268)
		(end 66.95313 -305.491388)
		(width 0.16002)
		(layer "In6.Cu")
		(net "M_E_CPU1_SB_DQS_DP<8>")
	)
	(segment
		(start 80.771238 -291.576252)
		(end 80.77962 -291.581078)
		(width 0.09525)
		(layer "In6.Cu")
		(net "M_E_CPU1_SB_DQS_DP<8>")
	)
	(segment
		(start 49.435004 -314.779152)
		(end 50.308764 -314.195206)
		(width 0.16002)
		(layer "In6.Cu")
		(net "M_E_CPU1_SB_DQS_DP<8>")
	)
	(arc
		(start 80.120998 -291.65677)
		(mid 80.266706 -291.637502)
		(end 80.40243 -291.581078)
		(width 0.09525)
		(layer "In6.Cu")
		(net "M_E_CPU1_SB_DQS_DP<8>")
	)
	(arc
		(start 81.719674 -291.581078)
		(mid 82.001106 -291.656833)
		(end 82.282538 -291.581078)
		(width 0.09525)
		(layer "In6.Cu")
		(net "M_E_CPU1_SB_DQS_DP<8>")
	)
	(arc
		(start 82.282538 -291.581078)
		(mid 82.439165 -291.531892)
		(end 82.601816 -291.554154)
		(width 0.09525)
		(layer "In6.Cu")
		(net "M_E_CPU1_SB_DQS_DP<8>")
	)
	(arc
		(start 80.40243 -291.581078)
		(mid 80.586205 -291.530306)
		(end 80.771238 -291.576252)
		(width 0.09525)
		(layer "In6.Cu")
		(net "M_E_CPU1_SB_DQS_DP<8>")
	)
	(arc
		(start 80.77962 -291.581078)
		(mid 81.061052 -291.656833)
		(end 81.342484 -291.581078)
		(width 0.09525)
		(layer "In6.Cu")
		(net "M_E_CPU1_SB_DQS_DP<8>")
	)
	(arc
		(start 81.350866 -291.576252)
		(mid 81.535898 -291.530338)
		(end 81.719674 -291.581078)
		(width 0.09525)
		(layer "In6.Cu")
		(net "M_E_CPU1_SB_DQS_DP<8>")
	)
	(segment
		(start 82.937858 -286.780478)
		(end 82.471006 -287.046162)
		(width 0.12954)
		(layer "F.Cu")
		(net "M_E_CPU1_SB_DQS_DP<7>")
	)
	(segment
		(start 79.831184 -286.716216)
		(end 79.839566 -286.721042)
		(width 0.09525)
		(layer "In6.Cu")
		(net "M_E_CPU1_SB_DQS_DP<7>")
	)
	(segment
		(start 36.477194 -305.160426)
		(end 37.859716 -305.160426)
		(width 0.16002)
		(layer "In6.Cu")
		(net "M_E_CPU1_SB_DQS_DP<7>")
	)
	(segment
		(start 26.030936 -305.011582)
		(end 27.087322 -304.801524)
		(width 0.16002)
		(layer "In6.Cu")
		(net "M_E_CPU1_SB_DQS_DP<7>")
	)
	(segment
		(start 75.950572 -287.809686)
		(end 76.24191 -287.809686)
		(width 0.16002)
		(layer "In6.Cu")
		(net "M_E_CPU1_SB_DQS_DP<7>")
	)
	(segment
		(start 55.369968 -305.601624)
		(end 57.354216 -305.207162)
		(width 0.16002)
		(layer "In6.Cu")
		(net "M_E_CPU1_SB_DQS_DP<7>")
	)
	(segment
		(start 78.90002 -286.721042)
		(end 78.899766 -286.721296)
		(width 0.09525)
		(layer "In6.Cu")
		(net "M_E_CPU1_SB_DQS_DP<7>")
	)
	(segment
		(start 42.269156 -305.19624)
		(end 42.848022 -304.809652)
		(width 0.16002)
		(layer "In6.Cu")
		(net "M_E_CPU1_SB_DQS_DP<7>")
	)
	(segment
		(start 72.526652 -290.595812)
		(end 73.61555 -290.144708)
		(width 0.16002)
		(layer "In6.Cu")
		(net "M_E_CPU1_SB_DQS_DP<7>")
	)
	(segment
		(start 82.62493 -286.780732)
		(end 82.471006 -287.046162)
		(width 0.09525)
		(layer "In6.Cu")
		(net "M_E_CPU1_SB_DQS_DP<7>")
	)
	(segment
		(start 25.425908 -305.011582)
		(end 26.030936 -305.011582)
		(width 0.16002)
		(layer "In6.Cu")
		(net "M_E_CPU1_SB_DQS_DP<7>")
	)
	(segment
		(start 60.04687 -304.228754)
		(end 61.734192 -302.541432)
		(width 0.16002)
		(layer "In6.Cu")
		(net "M_E_CPU1_SB_DQS_DP<7>")
	)
	(segment
		(start 78.688692 -286.669988)
		(end 78.711044 -286.669988)
		(width 0.09525)
		(layer "In6.Cu")
		(net "M_E_CPU1_SB_DQS_DP<7>")
	)
	(segment
		(start 78.117954 -287.090866)
		(end 78.43266 -286.77616)
		(width 0.09525)
		(layer "In6.Cu")
		(net "M_E_CPU1_SB_DQS_DP<7>")
	)
	(segment
		(start 61.734192 -302.541432)
		(end 62.549786 -300.572678)
		(width 0.16002)
		(layer "In6.Cu")
		(net "M_E_CPU1_SB_DQS_DP<7>")
	)
	(segment
		(start 53.96103 -305.601624)
		(end 55.369968 -305.601624)
		(width 0.16002)
		(layer "In6.Cu")
		(net "M_E_CPU1_SB_DQS_DP<7>")
	)
	(segment
		(start 32.472884 -306.010564)
		(end 32.937704 -306.010564)
		(width 0.16002)
		(layer "In6.Cu")
		(net "M_E_CPU1_SB_DQS_DP<7>")
	)
	(segment
		(start 42.848022 -304.809652)
		(end 42.851578 -304.807112)
		(width 0.16002)
		(layer "In6.Cu")
		(net "M_E_CPU1_SB_DQS_DP<7>")
	)
	(segment
		(start 48.24095 -306.010564)
		(end 50.105818 -305.013868)
		(width 0.16002)
		(layer "In6.Cu")
		(net "M_E_CPU1_SB_DQS_DP<7>")
	)
	(segment
		(start 28.103068 -304.801524)
		(end 28.801822 -305.091084)
		(width 0.16002)
		(layer "In6.Cu")
		(net "M_E_CPU1_SB_DQS_DP<7>")
	)
	(segment
		(start 81.342484 -286.721042)
		(end 81.350866 -286.716216)
		(width 0.09525)
		(layer "In6.Cu")
		(net "M_E_CPU1_SB_DQS_DP<7>")
	)
	(segment
		(start 76.574142 -287.394142)
		(end 76.877418 -287.090866)
		(width 0.09525)
		(layer "In6.Cu")
		(net "M_E_CPU1_SB_DQS_DP<7>")
	)
	(segment
		(start 39.912544 -306.010564)
		(end 40.57904 -306.010564)
		(width 0.16002)
		(layer "In6.Cu")
		(net "M_E_CPU1_SB_DQS_DP<7>")
	)
	(segment
		(start 58.589418 -304.832512)
		(end 60.04687 -304.228754)
		(width 0.16002)
		(layer "In6.Cu")
		(net "M_E_CPU1_SB_DQS_DP<7>")
	)
	(segment
		(start 57.914794 -304.832512)
		(end 58.589418 -304.832512)
		(width 0.16002)
		(layer "In6.Cu")
		(net "M_E_CPU1_SB_DQS_DP<7>")
	)
	(segment
		(start 42.851578 -304.807112)
		(end 43.07459 -304.807112)
		(width 0.16002)
		(layer "In6.Cu")
		(net "M_E_CPU1_SB_DQS_DP<7>")
	)
	(segment
		(start 47.376334 -306.010564)
		(end 48.24095 -306.010564)
		(width 0.16002)
		(layer "In6.Cu")
		(net "M_E_CPU1_SB_DQS_DP<7>")
	)
	(segment
		(start 80.771238 -286.716216)
		(end 80.77962 -286.721042)
		(width 0.09525)
		(layer "In6.Cu")
		(net "M_E_CPU1_SB_DQS_DP<7>")
	)
	(segment
		(start 43.07459 -304.807112)
		(end 43.927776 -305.160426)
		(width 0.16002)
		(layer "In6.Cu")
		(net "M_E_CPU1_SB_DQS_DP<7>")
	)
	(segment
		(start 50.350166 -304.832512)
		(end 50.852832 -304.832512)
		(width 0.16002)
		(layer "In6.Cu")
		(net "M_E_CPU1_SB_DQS_DP<7>")
	)
	(segment
		(start 35.278568 -304.826924)
		(end 35.67176 -304.826924)
		(width 0.16002)
		(layer "In6.Cu")
		(net "M_E_CPU1_SB_DQS_DP<7>")
	)
	(segment
		(start 76.557378 -287.494218)
		(end 76.574142 -287.477454)
		(width 0.09525)
		(layer "In6.Cu")
		(net "M_E_CPU1_SB_DQS_DP<7>")
	)
	(segment
		(start 50.852832 -304.832512)
		(end 51.64455 -305.160426)
		(width 0.16002)
		(layer "In6.Cu")
		(net "M_E_CPU1_SB_DQS_DP<7>")
	)
	(segment
		(start 27.087322 -304.801524)
		(end 28.103068 -304.801524)
		(width 0.16002)
		(layer "In6.Cu")
		(net "M_E_CPU1_SB_DQS_DP<7>")
	)
	(segment
		(start 73.61555 -290.144708)
		(end 75.950572 -287.809686)
		(width 0.16002)
		(layer "In6.Cu")
		(net "M_E_CPU1_SB_DQS_DP<7>")
	)
	(segment
		(start 76.574142 -287.477454)
		(end 76.574142 -287.394142)
		(width 0.09525)
		(layer "In6.Cu")
		(net "M_E_CPU1_SB_DQS_DP<7>")
	)
	(segment
		(start 57.354216 -305.207162)
		(end 57.914794 -304.832512)
		(width 0.16002)
		(layer "In6.Cu")
		(net "M_E_CPU1_SB_DQS_DP<7>")
	)
	(segment
		(start 40.57904 -306.010564)
		(end 42.269156 -305.19624)
		(width 0.16002)
		(layer "In6.Cu")
		(net "M_E_CPU1_SB_DQS_DP<7>")
	)
	(segment
		(start 32.937704 -306.010564)
		(end 34.435288 -305.390296)
		(width 0.16002)
		(layer "In6.Cu")
		(net "M_E_CPU1_SB_DQS_DP<7>")
	)
	(segment
		(start 52.896008 -305.160426)
		(end 53.96103 -305.601624)
		(width 0.16002)
		(layer "In6.Cu")
		(net "M_E_CPU1_SB_DQS_DP<7>")
	)
	(segment
		(start 34.435288 -305.390296)
		(end 35.278568 -304.826924)
		(width 0.16002)
		(layer "In6.Cu")
		(net "M_E_CPU1_SB_DQS_DP<7>")
	)
	(segment
		(start 35.67176 -304.826924)
		(end 36.477194 -305.160426)
		(width 0.16002)
		(layer "In6.Cu")
		(net "M_E_CPU1_SB_DQS_DP<7>")
	)
	(segment
		(start 25.152096 -305.285394)
		(end 25.425908 -305.011582)
		(width 0.16002)
		(layer "In6.Cu")
		(net "M_E_CPU1_SB_DQS_DP<7>")
	)
	(segment
		(start 82.601816 -286.694118)
		(end 82.62493 -286.780732)
		(width 0.09525)
		(layer "In6.Cu")
		(net "M_E_CPU1_SB_DQS_DP<7>")
	)
	(segment
		(start 28.801822 -305.091084)
		(end 32.472884 -306.010564)
		(width 0.16002)
		(layer "In6.Cu")
		(net "M_E_CPU1_SB_DQS_DP<7>")
	)
	(segment
		(start 76.24191 -287.809686)
		(end 76.557378 -287.494218)
		(width 0.16002)
		(layer "In6.Cu")
		(net "M_E_CPU1_SB_DQS_DP<7>")
	)
	(segment
		(start 45.323506 -305.160426)
		(end 47.376334 -306.010564)
		(width 0.16002)
		(layer "In6.Cu")
		(net "M_E_CPU1_SB_DQS_DP<7>")
	)
	(segment
		(start 50.105818 -305.013868)
		(end 50.350166 -304.832512)
		(width 0.16002)
		(layer "In6.Cu")
		(net "M_E_CPU1_SB_DQS_DP<7>")
	)
	(segment
		(start 76.877418 -287.090866)
		(end 78.117954 -287.090866)
		(width 0.09525)
		(layer "In6.Cu")
		(net "M_E_CPU1_SB_DQS_DP<7>")
	)
	(segment
		(start 43.927776 -305.160426)
		(end 45.323506 -305.160426)
		(width 0.16002)
		(layer "In6.Cu")
		(net "M_E_CPU1_SB_DQS_DP<7>")
	)
	(segment
		(start 62.549786 -300.572678)
		(end 72.526652 -290.595812)
		(width 0.16002)
		(layer "In6.Cu")
		(net "M_E_CPU1_SB_DQS_DP<7>")
	)
	(segment
		(start 37.859716 -305.160426)
		(end 39.912544 -306.010564)
		(width 0.16002)
		(layer "In6.Cu")
		(net "M_E_CPU1_SB_DQS_DP<7>")
	)
	(segment
		(start 51.64455 -305.160426)
		(end 52.896008 -305.160426)
		(width 0.16002)
		(layer "In6.Cu")
		(net "M_E_CPU1_SB_DQS_DP<7>")
	)
	(arc
		(start 81.719674 -286.721042)
		(mid 82.001106 -286.796831)
		(end 82.282538 -286.721042)
		(width 0.09525)
		(layer "In6.Cu")
		(net "M_E_CPU1_SB_DQS_DP<7>")
	)
	(arc
		(start 81.350866 -286.716216)
		(mid 81.535898 -286.670302)
		(end 81.719674 -286.721042)
		(width 0.09525)
		(layer "In6.Cu")
		(net "M_E_CPU1_SB_DQS_DP<7>")
	)
	(arc
		(start 78.43266 -286.77616)
		(mid 78.550113 -286.697587)
		(end 78.688692 -286.669988)
		(width 0.09525)
		(layer "In6.Cu")
		(net "M_E_CPU1_SB_DQS_DP<7>")
	)
	(arc
		(start 79.462376 -286.721042)
		(mid 79.646151 -286.67027)
		(end 79.831184 -286.716216)
		(width 0.09525)
		(layer "In6.Cu")
		(net "M_E_CPU1_SB_DQS_DP<7>")
	)
	(arc
		(start 80.77962 -286.721042)
		(mid 81.061052 -286.796831)
		(end 81.342484 -286.721042)
		(width 0.09525)
		(layer "In6.Cu")
		(net "M_E_CPU1_SB_DQS_DP<7>")
	)
	(arc
		(start 82.282538 -286.721042)
		(mid 82.439165 -286.671856)
		(end 82.601816 -286.694118)
		(width 0.09525)
		(layer "In6.Cu")
		(net "M_E_CPU1_SB_DQS_DP<7>")
	)
	(arc
		(start 78.899766 -286.721296)
		(mid 79.181118 -286.796924)
		(end 79.462376 -286.721042)
		(width 0.09525)
		(layer "In6.Cu")
		(net "M_E_CPU1_SB_DQS_DP<7>")
	)
	(arc
		(start 79.839566 -286.721042)
		(mid 80.120998 -286.796831)
		(end 80.40243 -286.721042)
		(width 0.09525)
		(layer "In6.Cu")
		(net "M_E_CPU1_SB_DQS_DP<7>")
	)
	(arc
		(start 78.711044 -286.669988)
		(mid 78.80891 -286.68301)
		(end 78.90002 -286.721042)
		(width 0.09525)
		(layer "In6.Cu")
		(net "M_E_CPU1_SB_DQS_DP<7>")
	)
	(arc
		(start 80.40243 -286.721042)
		(mid 80.586205 -286.67027)
		(end 80.771238 -286.716216)
		(width 0.09525)
		(layer "In6.Cu")
		(net "M_E_CPU1_SB_DQS_DP<7>")
	)
	(segment
		(start 82.937858 -281.920442)
		(end 82.471006 -282.18638)
		(width 0.12954)
		(layer "F.Cu")
		(net "M_E_CPU1_SB_DQS_DP<6>")
	)
	(segment
		(start 40.541194 -296.66057)
		(end 42.221658 -295.964356)
		(width 0.16002)
		(layer "In6.Cu")
		(net "M_E_CPU1_SB_DQS_DP<6>")
	)
	(segment
		(start 63.366142 -291.281358)
		(end 72.672956 -281.974544)
		(width 0.16002)
		(layer "In6.Cu")
		(net "M_E_CPU1_SB_DQS_DP<6>")
	)
	(segment
		(start 47.35957 -296.66057)
		(end 48.083978 -296.66057)
		(width 0.16002)
		(layer "In6.Cu")
		(net "M_E_CPU1_SB_DQS_DP<6>")
	)
	(segment
		(start 26.507694 -295.661588)
		(end 27.038808 -295.441624)
		(width 0.16002)
		(layer "In6.Cu")
		(net "M_E_CPU1_SB_DQS_DP<6>")
	)
	(segment
		(start 44.043346 -295.810432)
		(end 45.84573 -295.810432)
		(width 0.16002)
		(layer "In6.Cu")
		(net "M_E_CPU1_SB_DQS_DP<6>")
	)
	(segment
		(start 76.038456 -281.915616)
		(end 77.40396 -281.915616)
		(width 0.09525)
		(layer "In6.Cu")
		(net "M_E_CPU1_SB_DQS_DP<6>")
	)
	(segment
		(start 82.62493 -281.92095)
		(end 82.471006 -282.18638)
		(width 0.09525)
		(layer "In6.Cu")
		(net "M_E_CPU1_SB_DQS_DP<6>")
	)
	(segment
		(start 49.007522 -296.278046)
		(end 49.32426 -296.278046)
		(width 0.16002)
		(layer "In6.Cu")
		(net "M_E_CPU1_SB_DQS_DP<6>")
	)
	(segment
		(start 39.83609 -296.66057)
		(end 40.541194 -296.66057)
		(width 0.16002)
		(layer "In6.Cu")
		(net "M_E_CPU1_SB_DQS_DP<6>")
	)
	(segment
		(start 50.853594 -295.497758)
		(end 51.608482 -295.810432)
		(width 0.16002)
		(layer "In6.Cu")
		(net "M_E_CPU1_SB_DQS_DP<6>")
	)
	(segment
		(start 42.728896 -295.457118)
		(end 43.190414 -295.457118)
		(width 0.16002)
		(layer "In6.Cu")
		(net "M_E_CPU1_SB_DQS_DP<6>")
	)
	(segment
		(start 63.018416 -292.120828)
		(end 63.366142 -291.281358)
		(width 0.16002)
		(layer "In6.Cu")
		(net "M_E_CPU1_SB_DQS_DP<6>")
	)
	(segment
		(start 77.597 -281.722576)
		(end 79.325724 -281.722576)
		(width 0.09525)
		(layer "In6.Cu")
		(net "M_E_CPU1_SB_DQS_DP<6>")
	)
	(segment
		(start 55.137812 -296.320464)
		(end 55.254652 -296.437304)
		(width 0.16002)
		(layer "In6.Cu")
		(net "M_E_CPU1_SB_DQS_DP<6>")
	)
	(segment
		(start 72.672956 -281.974544)
		(end 75.955906 -281.974544)
		(width 0.16002)
		(layer "In6.Cu")
		(net "M_E_CPU1_SB_DQS_DP<6>")
	)
	(segment
		(start 36.470336 -295.810432)
		(end 38.11778 -295.810432)
		(width 0.16002)
		(layer "In6.Cu")
		(net "M_E_CPU1_SB_DQS_DP<6>")
	)
	(segment
		(start 38.405562 -295.929558)
		(end 38.642036 -296.166032)
		(width 0.16002)
		(layer "In6.Cu")
		(net "M_E_CPU1_SB_DQS_DP<6>")
	)
	(segment
		(start 81.342484 -281.86126)
		(end 81.350866 -281.856434)
		(width 0.09525)
		(layer "In6.Cu")
		(net "M_E_CPU1_SB_DQS_DP<6>")
	)
	(segment
		(start 75.979528 -281.974544)
		(end 76.038456 -281.915616)
		(width 0.09525)
		(layer "In6.Cu")
		(net "M_E_CPU1_SB_DQS_DP<6>")
	)
	(segment
		(start 27.038808 -295.441624)
		(end 28.064714 -295.441624)
		(width 0.16002)
		(layer "In6.Cu")
		(net "M_E_CPU1_SB_DQS_DP<6>")
	)
	(segment
		(start 42.221658 -295.964356)
		(end 42.728896 -295.457118)
		(width 0.16002)
		(layer "In6.Cu")
		(net "M_E_CPU1_SB_DQS_DP<6>")
	)
	(segment
		(start 56.331612 -296.320464)
		(end 57.496202 -295.838118)
		(width 0.16002)
		(layer "In6.Cu")
		(net "M_E_CPU1_SB_DQS_DP<6>")
	)
	(segment
		(start 49.699926 -296.122344)
		(end 50.324512 -295.497758)
		(width 0.16002)
		(layer "In6.Cu")
		(net "M_E_CPU1_SB_DQS_DP<6>")
	)
	(segment
		(start 53.932074 -296.320464)
		(end 55.137812 -296.320464)
		(width 0.16002)
		(layer "In6.Cu")
		(net "M_E_CPU1_SB_DQS_DP<6>")
	)
	(segment
		(start 55.851552 -296.320464)
		(end 56.331612 -296.320464)
		(width 0.16002)
		(layer "In6.Cu")
		(net "M_E_CPU1_SB_DQS_DP<6>")
	)
	(segment
		(start 53.422042 -295.810432)
		(end 53.932074 -296.320464)
		(width 0.16002)
		(layer "In6.Cu")
		(net "M_E_CPU1_SB_DQS_DP<6>")
	)
	(segment
		(start 55.734712 -296.437304)
		(end 55.851552 -296.320464)
		(width 0.16002)
		(layer "In6.Cu")
		(net "M_E_CPU1_SB_DQS_DP<6>")
	)
	(segment
		(start 60.279026 -294.860218)
		(end 63.018416 -292.120828)
		(width 0.16002)
		(layer "In6.Cu")
		(net "M_E_CPU1_SB_DQS_DP<6>")
	)
	(segment
		(start 79.8449 -281.864308)
		(end 79.850234 -281.867356)
		(width 0.09525)
		(layer "In6.Cu")
		(net "M_E_CPU1_SB_DQS_DP<6>")
	)
	(segment
		(start 45.84573 -295.810432)
		(end 46.22673 -296.191432)
		(width 0.16002)
		(layer "In6.Cu")
		(net "M_E_CPU1_SB_DQS_DP<6>")
	)
	(segment
		(start 79.838804 -281.85999)
		(end 79.838296 -281.860498)
		(width 0.09525)
		(layer "In6.Cu")
		(net "M_E_CPU1_SB_DQS_DP<6>")
	)
	(segment
		(start 51.608482 -295.810432)
		(end 53.422042 -295.810432)
		(width 0.16002)
		(layer "In6.Cu")
		(net "M_E_CPU1_SB_DQS_DP<6>")
	)
	(segment
		(start 31.007558 -296.66057)
		(end 32.87903 -296.66057)
		(width 0.16002)
		(layer "In6.Cu")
		(net "M_E_CPU1_SB_DQS_DP<6>")
	)
	(segment
		(start 34.891218 -295.827196)
		(end 35.23869 -295.479724)
		(width 0.16002)
		(layer "In6.Cu")
		(net "M_E_CPU1_SB_DQS_DP<6>")
	)
	(segment
		(start 50.324512 -295.497758)
		(end 50.853594 -295.497758)
		(width 0.16002)
		(layer "In6.Cu")
		(net "M_E_CPU1_SB_DQS_DP<6>")
	)
	(segment
		(start 80.771238 -281.856434)
		(end 80.77962 -281.86126)
		(width 0.09525)
		(layer "In6.Cu")
		(net "M_E_CPU1_SB_DQS_DP<6>")
	)
	(segment
		(start 75.955906 -281.974544)
		(end 75.979528 -281.974544)
		(width 0.09525)
		(layer "In6.Cu")
		(net "M_E_CPU1_SB_DQS_DP<6>")
	)
	(segment
		(start 57.851802 -295.482518)
		(end 58.77687 -295.482518)
		(width 0.16002)
		(layer "In6.Cu")
		(net "M_E_CPU1_SB_DQS_DP<6>")
	)
	(segment
		(start 32.87903 -296.66057)
		(end 34.891218 -295.827196)
		(width 0.16002)
		(layer "In6.Cu")
		(net "M_E_CPU1_SB_DQS_DP<6>")
	)
	(segment
		(start 25.152096 -295.9354)
		(end 25.425908 -295.661588)
		(width 0.16002)
		(layer "In6.Cu")
		(net "M_E_CPU1_SB_DQS_DP<6>")
	)
	(segment
		(start 28.064714 -295.441624)
		(end 31.007558 -296.66057)
		(width 0.16002)
		(layer "In6.Cu")
		(net "M_E_CPU1_SB_DQS_DP<6>")
	)
	(segment
		(start 48.083978 -296.66057)
		(end 49.007522 -296.278046)
		(width 0.16002)
		(layer "In6.Cu")
		(net "M_E_CPU1_SB_DQS_DP<6>")
	)
	(segment
		(start 49.32426 -296.278046)
		(end 49.699926 -296.122344)
		(width 0.16002)
		(layer "In6.Cu")
		(net "M_E_CPU1_SB_DQS_DP<6>")
	)
	(segment
		(start 35.23869 -295.479724)
		(end 35.672014 -295.479724)
		(width 0.16002)
		(layer "In6.Cu")
		(net "M_E_CPU1_SB_DQS_DP<6>")
	)
	(segment
		(start 58.77687 -295.482518)
		(end 60.279026 -294.860218)
		(width 0.16002)
		(layer "In6.Cu")
		(net "M_E_CPU1_SB_DQS_DP<6>")
	)
	(segment
		(start 57.496202 -295.838118)
		(end 57.851802 -295.482518)
		(width 0.16002)
		(layer "In6.Cu")
		(net "M_E_CPU1_SB_DQS_DP<6>")
	)
	(segment
		(start 55.254652 -296.437304)
		(end 55.734712 -296.437304)
		(width 0.16002)
		(layer "In6.Cu")
		(net "M_E_CPU1_SB_DQS_DP<6>")
	)
	(segment
		(start 38.642036 -296.166032)
		(end 39.83609 -296.66057)
		(width 0.16002)
		(layer "In6.Cu")
		(net "M_E_CPU1_SB_DQS_DP<6>")
	)
	(segment
		(start 43.190414 -295.457118)
		(end 44.043346 -295.810432)
		(width 0.16002)
		(layer "In6.Cu")
		(net "M_E_CPU1_SB_DQS_DP<6>")
	)
	(segment
		(start 79.83982 -281.86126)
		(end 79.8449 -281.864308)
		(width 0.09525)
		(layer "In6.Cu")
		(net "M_E_CPU1_SB_DQS_DP<6>")
	)
	(segment
		(start 25.425908 -295.661588)
		(end 26.507694 -295.661588)
		(width 0.16002)
		(layer "In6.Cu")
		(net "M_E_CPU1_SB_DQS_DP<6>")
	)
	(segment
		(start 38.11778 -295.810432)
		(end 38.405562 -295.929558)
		(width 0.16002)
		(layer "In6.Cu")
		(net "M_E_CPU1_SB_DQS_DP<6>")
	)
	(segment
		(start 35.672014 -295.479724)
		(end 36.470336 -295.810432)
		(width 0.16002)
		(layer "In6.Cu")
		(net "M_E_CPU1_SB_DQS_DP<6>")
	)
	(segment
		(start 46.22673 -296.191432)
		(end 47.35957 -296.66057)
		(width 0.16002)
		(layer "In6.Cu")
		(net "M_E_CPU1_SB_DQS_DP<6>")
	)
	(segment
		(start 77.40396 -281.915616)
		(end 77.597 -281.722576)
		(width 0.09525)
		(layer "In6.Cu")
		(net "M_E_CPU1_SB_DQS_DP<6>")
	)
	(segment
		(start 82.601816 -281.834336)
		(end 82.62493 -281.92095)
		(width 0.09525)
		(layer "In6.Cu")
		(net "M_E_CPU1_SB_DQS_DP<6>")
	)
	(arc
		(start 79.838296 -281.860498)
		(mid 79.839058 -281.860878)
		(end 79.83982 -281.86126)
		(width 0.09525)
		(layer "In6.Cu")
		(net "M_E_CPU1_SB_DQS_DP<6>")
	)
	(arc
		(start 79.325724 -281.722576)
		(mid 79.591279 -281.757605)
		(end 79.838804 -281.85999)
		(width 0.09525)
		(layer "In6.Cu")
		(net "M_E_CPU1_SB_DQS_DP<6>")
	)
	(arc
		(start 79.850234 -281.867356)
		(mid 80.127142 -281.937033)
		(end 80.40243 -281.86126)
		(width 0.09525)
		(layer "In6.Cu")
		(net "M_E_CPU1_SB_DQS_DP<6>")
	)
	(arc
		(start 80.40243 -281.86126)
		(mid 80.586205 -281.810488)
		(end 80.771238 -281.856434)
		(width 0.09525)
		(layer "In6.Cu")
		(net "M_E_CPU1_SB_DQS_DP<6>")
	)
	(arc
		(start 81.350866 -281.856434)
		(mid 81.535898 -281.81052)
		(end 81.719674 -281.86126)
		(width 0.09525)
		(layer "In6.Cu")
		(net "M_E_CPU1_SB_DQS_DP<6>")
	)
	(arc
		(start 81.719674 -281.86126)
		(mid 82.001106 -281.937015)
		(end 82.282538 -281.86126)
		(width 0.09525)
		(layer "In6.Cu")
		(net "M_E_CPU1_SB_DQS_DP<6>")
	)
	(arc
		(start 82.282538 -281.86126)
		(mid 82.439165 -281.812074)
		(end 82.601816 -281.834336)
		(width 0.09525)
		(layer "In6.Cu")
		(net "M_E_CPU1_SB_DQS_DP<6>")
	)
	(arc
		(start 80.77962 -281.86126)
		(mid 81.061052 -281.937015)
		(end 81.342484 -281.86126)
		(width 0.09525)
		(layer "In6.Cu")
		(net "M_E_CPU1_SB_DQS_DP<6>")
	)
	(segment
		(start 82.937858 -277.060406)
		(end 82.471006 -277.326344)
		(width 0.12954)
		(layer "F.Cu")
		(net "M_E_CPU1_SB_DQS_DP<5>")
	)
	(segment
		(start 34.724848 -286.595566)
		(end 35.23869 -286.081724)
		(width 0.16002)
		(layer "In6.Cu")
		(net "M_E_CPU1_SB_DQS_DP<5>")
	)
	(segment
		(start 28.415742 -286.476948)
		(end 30.396942 -286.476948)
		(width 0.16002)
		(layer "In6.Cu")
		(net "M_E_CPU1_SB_DQS_DP<5>")
	)
	(segment
		(start 46.61027 -287.015174)
		(end 47.323502 -287.310576)
		(width 0.16002)
		(layer "In6.Cu")
		(net "M_E_CPU1_SB_DQS_DP<5>")
	)
	(segment
		(start 76.87056 -276.800056)
		(end 79.500984 -276.800056)
		(width 0.09525)
		(layer "In6.Cu")
		(net "M_E_CPU1_SB_DQS_DP<5>")
	)
	(segment
		(start 43.478704 -286.460438)
		(end 45.270928 -286.460438)
		(width 0.16002)
		(layer "In6.Cu")
		(net "M_E_CPU1_SB_DQS_DP<5>")
	)
	(segment
		(start 39.12997 -287.310576)
		(end 41.121838 -287.310576)
		(width 0.16002)
		(layer "In6.Cu")
		(net "M_E_CPU1_SB_DQS_DP<5>")
	)
	(segment
		(start 57.836562 -286.132524)
		(end 58.272934 -286.132524)
		(width 0.16002)
		(layer "In6.Cu")
		(net "M_E_CPU1_SB_DQS_DP<5>")
	)
	(segment
		(start 57.036462 -286.932624)
		(end 57.836562 -286.132524)
		(width 0.16002)
		(layer "In6.Cu")
		(net "M_E_CPU1_SB_DQS_DP<5>")
	)
	(segment
		(start 47.323502 -287.310576)
		(end 48.665638 -287.310576)
		(width 0.16002)
		(layer "In6.Cu")
		(net "M_E_CPU1_SB_DQS_DP<5>")
	)
	(segment
		(start 43.12539 -286.107124)
		(end 43.478704 -286.460438)
		(width 0.16002)
		(layer "In6.Cu")
		(net "M_E_CPU1_SB_DQS_DP<5>")
	)
	(segment
		(start 76.07935 -276.350984)
		(end 76.102972 -276.350984)
		(width 0.09525)
		(layer "In6.Cu")
		(net "M_E_CPU1_SB_DQS_DP<5>")
	)
	(segment
		(start 58.272934 -286.132524)
		(end 61.31941 -284.870652)
		(width 0.16002)
		(layer "In6.Cu")
		(net "M_E_CPU1_SB_DQS_DP<5>")
	)
	(segment
		(start 51.060604 -286.460438)
		(end 53.443632 -286.460438)
		(width 0.16002)
		(layer "In6.Cu")
		(net "M_E_CPU1_SB_DQS_DP<5>")
	)
	(segment
		(start 81.342484 -277.001224)
		(end 81.350866 -276.996398)
		(width 0.09525)
		(layer "In6.Cu")
		(net "M_E_CPU1_SB_DQS_DP<5>")
	)
	(segment
		(start 50.318162 -286.132524)
		(end 50.73269 -286.132524)
		(width 0.16002)
		(layer "In6.Cu")
		(net "M_E_CPU1_SB_DQS_DP<5>")
	)
	(segment
		(start 25.425908 -286.311594)
		(end 26.633424 -286.311594)
		(width 0.16002)
		(layer "In6.Cu")
		(net "M_E_CPU1_SB_DQS_DP<5>")
	)
	(segment
		(start 49.505362 -286.945324)
		(end 50.318162 -286.132524)
		(width 0.16002)
		(layer "In6.Cu")
		(net "M_E_CPU1_SB_DQS_DP<5>")
	)
	(segment
		(start 45.950632 -286.74187)
		(end 46.013878 -286.894778)
		(width 0.16002)
		(layer "In6.Cu")
		(net "M_E_CPU1_SB_DQS_DP<5>")
	)
	(segment
		(start 79.500984 -276.800056)
		(end 79.836772 -276.998684)
		(width 0.09525)
		(layer "In6.Cu")
		(net "M_E_CPU1_SB_DQS_DP<5>")
	)
	(segment
		(start 33.54451 -287.310576)
		(end 33.930336 -286.92475)
		(width 0.16002)
		(layer "In6.Cu")
		(net "M_E_CPU1_SB_DQS_DP<5>")
	)
	(segment
		(start 26.633424 -286.311594)
		(end 27.157934 -286.094424)
		(width 0.16002)
		(layer "In6.Cu")
		(net "M_E_CPU1_SB_DQS_DP<5>")
	)
	(segment
		(start 33.930336 -286.92475)
		(end 34.724848 -286.595566)
		(width 0.16002)
		(layer "In6.Cu")
		(net "M_E_CPU1_SB_DQS_DP<5>")
	)
	(segment
		(start 46.457616 -287.07842)
		(end 46.61027 -287.015174)
		(width 0.16002)
		(layer "In6.Cu")
		(net "M_E_CPU1_SB_DQS_DP<5>")
	)
	(segment
		(start 61.31941 -284.870652)
		(end 69.839078 -276.350984)
		(width 0.16002)
		(layer "In6.Cu")
		(net "M_E_CPU1_SB_DQS_DP<5>")
	)
	(segment
		(start 41.72839 -286.704024)
		(end 42.177462 -286.704024)
		(width 0.16002)
		(layer "In6.Cu")
		(net "M_E_CPU1_SB_DQS_DP<5>")
	)
	(segment
		(start 27.157934 -286.094424)
		(end 28.033218 -286.094424)
		(width 0.16002)
		(layer "In6.Cu")
		(net "M_E_CPU1_SB_DQS_DP<5>")
	)
	(segment
		(start 35.23869 -286.081724)
		(end 35.55619 -286.081724)
		(width 0.16002)
		(layer "In6.Cu")
		(net "M_E_CPU1_SB_DQS_DP<5>")
	)
	(segment
		(start 80.771238 -276.996398)
		(end 80.77962 -277.001224)
		(width 0.09525)
		(layer "In6.Cu")
		(net "M_E_CPU1_SB_DQS_DP<5>")
	)
	(segment
		(start 30.396942 -286.476948)
		(end 31.23057 -287.310576)
		(width 0.16002)
		(layer "In6.Cu")
		(net "M_E_CPU1_SB_DQS_DP<5>")
	)
	(segment
		(start 76.102972 -276.350984)
		(end 76.1619 -276.292056)
		(width 0.09525)
		(layer "In6.Cu")
		(net "M_E_CPU1_SB_DQS_DP<5>")
	)
	(segment
		(start 53.915818 -286.932624)
		(end 57.036462 -286.932624)
		(width 0.16002)
		(layer "In6.Cu")
		(net "M_E_CPU1_SB_DQS_DP<5>")
	)
	(segment
		(start 49.03089 -286.945324)
		(end 49.505362 -286.945324)
		(width 0.16002)
		(layer "In6.Cu")
		(net "M_E_CPU1_SB_DQS_DP<5>")
	)
	(segment
		(start 82.62493 -277.060914)
		(end 82.471006 -277.326344)
		(width 0.09525)
		(layer "In6.Cu")
		(net "M_E_CPU1_SB_DQS_DP<5>")
	)
	(segment
		(start 42.177462 -286.704024)
		(end 42.774362 -286.107124)
		(width 0.16002)
		(layer "In6.Cu")
		(net "M_E_CPU1_SB_DQS_DP<5>")
	)
	(segment
		(start 28.033218 -286.094424)
		(end 28.415742 -286.476948)
		(width 0.16002)
		(layer "In6.Cu")
		(net "M_E_CPU1_SB_DQS_DP<5>")
	)
	(segment
		(start 35.55619 -286.081724)
		(end 35.934904 -286.460438)
		(width 0.16002)
		(layer "In6.Cu")
		(net "M_E_CPU1_SB_DQS_DP<5>")
	)
	(segment
		(start 69.839078 -276.350984)
		(end 76.07935 -276.350984)
		(width 0.16002)
		(layer "In6.Cu")
		(net "M_E_CPU1_SB_DQS_DP<5>")
	)
	(segment
		(start 80.401922 -277.00097)
		(end 80.402176 -277.00097)
		(width 0.09525)
		(layer "In6.Cu")
		(net "M_E_CPU1_SB_DQS_DP<5>")
	)
	(segment
		(start 45.270928 -286.460438)
		(end 45.950632 -286.742124)
		(width 0.16002)
		(layer "In6.Cu")
		(net "M_E_CPU1_SB_DQS_DP<5>")
	)
	(segment
		(start 80.771492 -276.996144)
		(end 80.771238 -276.996398)
		(width 0.09525)
		(layer "In6.Cu")
		(net "M_E_CPU1_SB_DQS_DP<5>")
	)
	(segment
		(start 38.279832 -286.460438)
		(end 39.12997 -287.310576)
		(width 0.16002)
		(layer "In6.Cu")
		(net "M_E_CPU1_SB_DQS_DP<5>")
	)
	(segment
		(start 31.23057 -287.310576)
		(end 33.54451 -287.310576)
		(width 0.16002)
		(layer "In6.Cu")
		(net "M_E_CPU1_SB_DQS_DP<5>")
	)
	(segment
		(start 76.1619 -276.292056)
		(end 76.36256 -276.292056)
		(width 0.09525)
		(layer "In6.Cu")
		(net "M_E_CPU1_SB_DQS_DP<5>")
	)
	(segment
		(start 41.121838 -287.310576)
		(end 41.72839 -286.704024)
		(width 0.16002)
		(layer "In6.Cu")
		(net "M_E_CPU1_SB_DQS_DP<5>")
	)
	(segment
		(start 46.013878 -286.894778)
		(end 46.457616 -287.07842)
		(width 0.16002)
		(layer "In6.Cu")
		(net "M_E_CPU1_SB_DQS_DP<5>")
	)
	(segment
		(start 50.73269 -286.132524)
		(end 51.060604 -286.460438)
		(width 0.16002)
		(layer "In6.Cu")
		(net "M_E_CPU1_SB_DQS_DP<5>")
	)
	(segment
		(start 45.950632 -286.742124)
		(end 45.950632 -286.74187)
		(width 0.16002)
		(layer "In6.Cu")
		(net "M_E_CPU1_SB_DQS_DP<5>")
	)
	(segment
		(start 25.152096 -286.585406)
		(end 25.425908 -286.311594)
		(width 0.16002)
		(layer "In6.Cu")
		(net "M_E_CPU1_SB_DQS_DP<5>")
	)
	(segment
		(start 35.934904 -286.460438)
		(end 38.279832 -286.460438)
		(width 0.16002)
		(layer "In6.Cu")
		(net "M_E_CPU1_SB_DQS_DP<5>")
	)
	(segment
		(start 53.443632 -286.460438)
		(end 53.915818 -286.932624)
		(width 0.16002)
		(layer "In6.Cu")
		(net "M_E_CPU1_SB_DQS_DP<5>")
	)
	(segment
		(start 42.774362 -286.107124)
		(end 43.12539 -286.107124)
		(width 0.16002)
		(layer "In6.Cu")
		(net "M_E_CPU1_SB_DQS_DP<5>")
	)
	(segment
		(start 76.36256 -276.292056)
		(end 76.87056 -276.800056)
		(width 0.09525)
		(layer "In6.Cu")
		(net "M_E_CPU1_SB_DQS_DP<5>")
	)
	(segment
		(start 48.665638 -287.310576)
		(end 49.03089 -286.945324)
		(width 0.16002)
		(layer "In6.Cu")
		(net "M_E_CPU1_SB_DQS_DP<5>")
	)
	(segment
		(start 82.601816 -276.9743)
		(end 82.62493 -277.060914)
		(width 0.09525)
		(layer "In6.Cu")
		(net "M_E_CPU1_SB_DQS_DP<5>")
	)
	(arc
		(start 81.350866 -276.996398)
		(mid 81.535898 -276.950484)
		(end 81.719674 -277.001224)
		(width 0.09525)
		(layer "In6.Cu")
		(net "M_E_CPU1_SB_DQS_DP<5>")
	)
	(arc
		(start 80.402176 -277.00097)
		(mid 80.586205 -276.950105)
		(end 80.771492 -276.996144)
		(width 0.09525)
		(layer "In6.Cu")
		(net "M_E_CPU1_SB_DQS_DP<5>")
	)
	(arc
		(start 82.282538 -277.001224)
		(mid 82.439165 -276.952038)
		(end 82.601816 -276.9743)
		(width 0.09525)
		(layer "In6.Cu")
		(net "M_E_CPU1_SB_DQS_DP<5>")
	)
	(arc
		(start 81.719674 -277.001224)
		(mid 82.001106 -277.076979)
		(end 82.282538 -277.001224)
		(width 0.09525)
		(layer "In6.Cu")
		(net "M_E_CPU1_SB_DQS_DP<5>")
	)
	(arc
		(start 80.77962 -277.001224)
		(mid 81.061052 -277.076979)
		(end 81.342484 -277.001224)
		(width 0.09525)
		(layer "In6.Cu")
		(net "M_E_CPU1_SB_DQS_DP<5>")
	)
	(arc
		(start 79.836772 -276.998684)
		(mid 80.119031 -277.076427)
		(end 80.401922 -277.00097)
		(width 0.09525)
		(layer "In6.Cu")
		(net "M_E_CPU1_SB_DQS_DP<5>")
	)
	(segment
		(start 82.937858 -272.20037)
		(end 82.471006 -272.466308)
		(width 0.12954)
		(layer "F.Cu")
		(net "M_E_CPU1_SB_DQS_DP<4>")
	)
	(segment
		(start 35.93211 -277.110444)
		(end 38.226238 -277.110444)
		(width 0.16002)
		(layer "In6.Cu")
		(net "M_E_CPU1_SB_DQS_DP<4>")
	)
	(segment
		(start 42.294048 -277.248366)
		(end 42.75709 -276.785324)
		(width 0.16002)
		(layer "In6.Cu")
		(net "M_E_CPU1_SB_DQS_DP<4>")
	)
	(segment
		(start 62.058296 -273.095212)
		(end 64.426084 -270.727424)
		(width 0.16002)
		(layer "In6.Cu")
		(net "M_E_CPU1_SB_DQS_DP<4>")
	)
	(segment
		(start 57.85739 -276.772624)
		(end 58.92292 -276.772624)
		(width 0.16002)
		(layer "In6.Cu")
		(net "M_E_CPU1_SB_DQS_DP<4>")
	)
	(segment
		(start 27.399488 -276.721824)
		(end 27.999944 -276.721824)
		(width 0.16002)
		(layer "In6.Cu")
		(net "M_E_CPU1_SB_DQS_DP<4>")
	)
	(segment
		(start 46.442376 -277.960582)
		(end 48.643032 -277.960582)
		(width 0.16002)
		(layer "In6.Cu")
		(net "M_E_CPU1_SB_DQS_DP<4>")
	)
	(segment
		(start 76.063856 -270.668496)
		(end 76.283312 -270.668496)
		(width 0.09525)
		(layer "In6.Cu")
		(net "M_E_CPU1_SB_DQS_DP<4>")
	)
	(segment
		(start 77.427582 -270.958564)
		(end 78.500732 -272.031714)
		(width 0.09525)
		(layer "In6.Cu")
		(net "M_E_CPU1_SB_DQS_DP<4>")
	)
	(segment
		(start 25.965912 -276.9616)
		(end 26.082752 -277.07844)
		(width 0.16002)
		(layer "In6.Cu")
		(net "M_E_CPU1_SB_DQS_DP<4>")
	)
	(segment
		(start 35.21329 -276.785324)
		(end 35.60699 -276.785324)
		(width 0.16002)
		(layer "In6.Cu")
		(net "M_E_CPU1_SB_DQS_DP<4>")
	)
	(segment
		(start 78.500732 -272.031714)
		(end 79.434182 -272.031714)
		(width 0.09525)
		(layer "In6.Cu")
		(net "M_E_CPU1_SB_DQS_DP<4>")
	)
	(segment
		(start 45.592238 -277.110444)
		(end 46.442376 -277.960582)
		(width 0.16002)
		(layer "In6.Cu")
		(net "M_E_CPU1_SB_DQS_DP<4>")
	)
	(segment
		(start 30.171644 -277.126954)
		(end 32.18434 -277.960582)
		(width 0.16002)
		(layer "In6.Cu")
		(net "M_E_CPU1_SB_DQS_DP<4>")
	)
	(segment
		(start 53.339238 -277.110444)
		(end 53.814218 -277.585424)
		(width 0.16002)
		(layer "In6.Cu")
		(net "M_E_CPU1_SB_DQS_DP<4>")
	)
	(segment
		(start 43.47591 -277.110444)
		(end 45.592238 -277.110444)
		(width 0.16002)
		(layer "In6.Cu")
		(net "M_E_CPU1_SB_DQS_DP<4>")
	)
	(segment
		(start 49.178972 -277.424642)
		(end 49.959514 -277.1013)
		(width 0.16002)
		(layer "In6.Cu")
		(net "M_E_CPU1_SB_DQS_DP<4>")
	)
	(segment
		(start 32.18434 -277.960582)
		(end 33.530032 -277.960582)
		(width 0.16002)
		(layer "In6.Cu")
		(net "M_E_CPU1_SB_DQS_DP<4>")
	)
	(segment
		(start 53.814218 -277.585424)
		(end 57.04459 -277.585424)
		(width 0.16002)
		(layer "In6.Cu")
		(net "M_E_CPU1_SB_DQS_DP<4>")
	)
	(segment
		(start 39.076376 -277.960582)
		(end 41.116504 -277.960582)
		(width 0.16002)
		(layer "In6.Cu")
		(net "M_E_CPU1_SB_DQS_DP<4>")
	)
	(segment
		(start 50.33899 -276.721824)
		(end 50.613818 -276.721824)
		(width 0.16002)
		(layer "In6.Cu")
		(net "M_E_CPU1_SB_DQS_DP<4>")
	)
	(segment
		(start 33.530032 -277.960582)
		(end 34.04489 -277.445724)
		(width 0.16002)
		(layer "In6.Cu")
		(net "M_E_CPU1_SB_DQS_DP<4>")
	)
	(segment
		(start 57.04459 -277.585424)
		(end 57.85739 -276.772624)
		(width 0.16002)
		(layer "In6.Cu")
		(net "M_E_CPU1_SB_DQS_DP<4>")
	)
	(segment
		(start 26.679652 -276.9616)
		(end 27.159712 -276.9616)
		(width 0.16002)
		(layer "In6.Cu")
		(net "M_E_CPU1_SB_DQS_DP<4>")
	)
	(segment
		(start 76.283312 -270.668496)
		(end 76.57338 -270.958564)
		(width 0.09525)
		(layer "In6.Cu")
		(net "M_E_CPU1_SB_DQS_DP<4>")
	)
	(segment
		(start 81.342484 -272.141188)
		(end 81.350866 -272.136362)
		(width 0.09525)
		(layer "In6.Cu")
		(net "M_E_CPU1_SB_DQS_DP<4>")
	)
	(segment
		(start 76.57338 -270.958564)
		(end 77.427582 -270.958564)
		(width 0.09525)
		(layer "In6.Cu")
		(net "M_E_CPU1_SB_DQS_DP<4>")
	)
	(segment
		(start 50.613818 -276.721824)
		(end 51.002438 -277.110444)
		(width 0.16002)
		(layer "In6.Cu")
		(net "M_E_CPU1_SB_DQS_DP<4>")
	)
	(segment
		(start 80.771238 -272.136362)
		(end 80.77962 -272.141188)
		(width 0.09525)
		(layer "In6.Cu")
		(net "M_E_CPU1_SB_DQS_DP<4>")
	)
	(segment
		(start 61.67501 -274.020534)
		(end 62.058296 -273.095212)
		(width 0.16002)
		(layer "In6.Cu")
		(net "M_E_CPU1_SB_DQS_DP<4>")
	)
	(segment
		(start 51.002438 -277.110444)
		(end 53.339238 -277.110444)
		(width 0.16002)
		(layer "In6.Cu")
		(net "M_E_CPU1_SB_DQS_DP<4>")
	)
	(segment
		(start 26.082752 -277.07844)
		(end 26.562812 -277.07844)
		(width 0.16002)
		(layer "In6.Cu")
		(net "M_E_CPU1_SB_DQS_DP<4>")
	)
	(segment
		(start 42.75709 -276.785324)
		(end 43.15079 -276.785324)
		(width 0.16002)
		(layer "In6.Cu")
		(net "M_E_CPU1_SB_DQS_DP<4>")
	)
	(segment
		(start 26.562812 -277.07844)
		(end 26.679652 -276.9616)
		(width 0.16002)
		(layer "In6.Cu")
		(net "M_E_CPU1_SB_DQS_DP<4>")
	)
	(segment
		(start 27.159712 -276.9616)
		(end 27.399488 -276.721824)
		(width 0.16002)
		(layer "In6.Cu")
		(net "M_E_CPU1_SB_DQS_DP<4>")
	)
	(segment
		(start 41.116504 -277.960582)
		(end 41.499536 -277.57755)
		(width 0.16002)
		(layer "In6.Cu")
		(net "M_E_CPU1_SB_DQS_DP<4>")
	)
	(segment
		(start 79.840582 -272.141188)
		(end 79.853028 -272.148046)
		(width 0.09525)
		(layer "In6.Cu")
		(net "M_E_CPU1_SB_DQS_DP<4>")
	)
	(segment
		(start 41.499536 -277.57755)
		(end 42.294048 -277.248366)
		(width 0.16002)
		(layer "In6.Cu")
		(net "M_E_CPU1_SB_DQS_DP<4>")
	)
	(segment
		(start 75.955906 -270.727424)
		(end 75.981306 -270.727424)
		(width 0.1016)
		(layer "In6.Cu")
		(net "M_E_CPU1_SB_DQS_DP<4>")
	)
	(segment
		(start 35.60699 -276.785324)
		(end 35.93211 -277.110444)
		(width 0.16002)
		(layer "In6.Cu")
		(net "M_E_CPU1_SB_DQS_DP<4>")
	)
	(segment
		(start 25.152096 -277.235412)
		(end 25.425908 -276.9616)
		(width 0.16002)
		(layer "In6.Cu")
		(net "M_E_CPU1_SB_DQS_DP<4>")
	)
	(segment
		(start 43.15079 -276.785324)
		(end 43.47591 -277.110444)
		(width 0.16002)
		(layer "In6.Cu")
		(net "M_E_CPU1_SB_DQS_DP<4>")
	)
	(segment
		(start 49.959514 -277.1013)
		(end 50.33899 -276.721824)
		(width 0.16002)
		(layer "In6.Cu")
		(net "M_E_CPU1_SB_DQS_DP<4>")
	)
	(segment
		(start 28.405074 -277.126954)
		(end 30.171644 -277.126954)
		(width 0.16002)
		(layer "In6.Cu")
		(net "M_E_CPU1_SB_DQS_DP<4>")
	)
	(segment
		(start 48.643032 -277.960582)
		(end 49.178972 -277.424642)
		(width 0.16002)
		(layer "In6.Cu")
		(net "M_E_CPU1_SB_DQS_DP<4>")
	)
	(segment
		(start 76.004928 -270.727424)
		(end 76.063856 -270.668496)
		(width 0.09525)
		(layer "In6.Cu")
		(net "M_E_CPU1_SB_DQS_DP<4>")
	)
	(segment
		(start 75.981306 -270.727424)
		(end 76.004928 -270.727424)
		(width 0.09525)
		(layer "In6.Cu")
		(net "M_E_CPU1_SB_DQS_DP<4>")
	)
	(segment
		(start 34.55289 -277.445724)
		(end 35.21329 -276.785324)
		(width 0.16002)
		(layer "In6.Cu")
		(net "M_E_CPU1_SB_DQS_DP<4>")
	)
	(segment
		(start 25.425908 -276.9616)
		(end 25.965912 -276.9616)
		(width 0.16002)
		(layer "In6.Cu")
		(net "M_E_CPU1_SB_DQS_DP<4>")
	)
	(segment
		(start 82.601816 -272.114264)
		(end 82.62493 -272.200878)
		(width 0.09525)
		(layer "In6.Cu")
		(net "M_E_CPU1_SB_DQS_DP<4>")
	)
	(segment
		(start 38.226238 -277.110444)
		(end 39.076376 -277.960582)
		(width 0.16002)
		(layer "In6.Cu")
		(net "M_E_CPU1_SB_DQS_DP<4>")
	)
	(segment
		(start 58.92292 -276.772624)
		(end 61.67501 -274.020534)
		(width 0.16002)
		(layer "In6.Cu")
		(net "M_E_CPU1_SB_DQS_DP<4>")
	)
	(segment
		(start 79.840328 -272.140934)
		(end 79.840582 -272.141188)
		(width 0.09525)
		(layer "In6.Cu")
		(net "M_E_CPU1_SB_DQS_DP<4>")
	)
	(segment
		(start 27.999944 -276.721824)
		(end 28.405074 -277.126954)
		(width 0.16002)
		(layer "In6.Cu")
		(net "M_E_CPU1_SB_DQS_DP<4>")
	)
	(segment
		(start 82.62493 -272.200878)
		(end 82.471006 -272.466308)
		(width 0.09525)
		(layer "In6.Cu")
		(net "M_E_CPU1_SB_DQS_DP<4>")
	)
	(segment
		(start 64.426084 -270.727424)
		(end 75.955906 -270.727424)
		(width 0.16002)
		(layer "In6.Cu")
		(net "M_E_CPU1_SB_DQS_DP<4>")
	)
	(segment
		(start 34.04489 -277.445724)
		(end 34.55289 -277.445724)
		(width 0.16002)
		(layer "In6.Cu")
		(net "M_E_CPU1_SB_DQS_DP<4>")
	)
	(arc
		(start 80.40243 -272.141188)
		(mid 80.586205 -272.090416)
		(end 80.771238 -272.136362)
		(width 0.09525)
		(layer "In6.Cu")
		(net "M_E_CPU1_SB_DQS_DP<4>")
	)
	(arc
		(start 79.853028 -272.148046)
		(mid 79.8529 -272.148427)
		(end 79.852774 -272.148808)
		(width 0.09525)
		(layer "In6.Cu")
		(net "M_E_CPU1_SB_DQS_DP<4>")
	)
	(arc
		(start 80.77962 -272.141188)
		(mid 81.061052 -272.216943)
		(end 81.342484 -272.141188)
		(width 0.09525)
		(layer "In6.Cu")
		(net "M_E_CPU1_SB_DQS_DP<4>")
	)
	(arc
		(start 79.434182 -272.031714)
		(mid 79.644462 -272.059526)
		(end 79.840328 -272.140934)
		(width 0.09525)
		(layer "In6.Cu")
		(net "M_E_CPU1_SB_DQS_DP<4>")
	)
	(arc
		(start 81.719674 -272.141188)
		(mid 82.001106 -272.216943)
		(end 82.282538 -272.141188)
		(width 0.09525)
		(layer "In6.Cu")
		(net "M_E_CPU1_SB_DQS_DP<4>")
	)
	(arc
		(start 81.350866 -272.136362)
		(mid 81.535898 -272.090448)
		(end 81.719674 -272.141188)
		(width 0.09525)
		(layer "In6.Cu")
		(net "M_E_CPU1_SB_DQS_DP<4>")
	)
	(arc
		(start 82.282538 -272.141188)
		(mid 82.439165 -272.092002)
		(end 82.601816 -272.114264)
		(width 0.09525)
		(layer "In6.Cu")
		(net "M_E_CPU1_SB_DQS_DP<4>")
	)
	(arc
		(start 79.852774 -272.148808)
		(mid 80.128589 -272.216934)
		(end 80.40243 -272.141188)
		(width 0.09525)
		(layer "In6.Cu")
		(net "M_E_CPU1_SB_DQS_DP<4>")
	)
	(segment
		(start 81.997804 -290.020248)
		(end 81.530952 -290.286186)
		(width 0.12954)
		(layer "F.Cu")
		(net "M_E_CPU1_SB_DQS_DP<3>")
	)
	(segment
		(start 69.360796 -300.415452)
		(end 69.360796 -299.938948)
		(width 0.16002)
		(layer "In6.Cu")
		(net "M_E_CPU1_SB_DQS_DP<3>")
	)
	(segment
		(start 76.394564 -294.011096)
		(end 77.891386 -292.514274)
		(width 0.09525)
		(layer "In6.Cu")
		(net "M_E_CPU1_SB_DQS_DP<3>")
	)
	(segment
		(start 43.11904 -312.538364)
		(end 43.447208 -312.210196)
		(width 0.16002)
		(layer "In6.Cu")
		(net "M_E_CPU1_SB_DQS_DP<3>")
	)
	(segment
		(start 81.377028 -290.551616)
		(end 81.530952 -290.286186)
		(width 0.09525)
		(layer "In6.Cu")
		(net "M_E_CPU1_SB_DQS_DP<3>")
	)
	(segment
		(start 35.07994 -312.551064)
		(end 35.570668 -312.551064)
		(width 0.16002)
		(layer "In6.Cu")
		(net "M_E_CPU1_SB_DQS_DP<3>")
	)
	(segment
		(start 67.874134 -302.448468)
		(end 68.129658 -302.192944)
		(width 0.16002)
		(layer "In6.Cu")
		(net "M_E_CPU1_SB_DQS_DP<3>")
	)
	(segment
		(start 80.392016 -290.60521)
		(end 80.40243 -290.611306)
		(width 0.09525)
		(layer "In6.Cu")
		(net "M_E_CPU1_SB_DQS_DP<3>")
	)
	(segment
		(start 69.265292 -301.05731)
		(end 69.520816 -300.801786)
		(width 0.16002)
		(layer "In6.Cu")
		(net "M_E_CPU1_SB_DQS_DP<3>")
	)
	(segment
		(start 77.891386 -292.514274)
		(end 77.891386 -291.592508)
		(width 0.09525)
		(layer "In6.Cu")
		(net "M_E_CPU1_SB_DQS_DP<3>")
	)
	(segment
		(start 32.01416 -313.209178)
		(end 32.163258 -313.06008)
		(width 0.16002)
		(layer "In6.Cu")
		(net "M_E_CPU1_SB_DQS_DP<3>")
	)
	(segment
		(start 71.821548 -298.274994)
		(end 72.047608 -298.274994)
		(width 0.16002)
		(layer "In6.Cu")
		(net "M_E_CPU1_SB_DQS_DP<3>")
	)
	(segment
		(start 71.185024 -298.11472)
		(end 71.661274 -298.11472)
		(width 0.16002)
		(layer "In6.Cu")
		(net "M_E_CPU1_SB_DQS_DP<3>")
	)
	(segment
		(start 70.751954 -298.54779)
		(end 71.185024 -298.11472)
		(width 0.16002)
		(layer "In6.Cu")
		(net "M_E_CPU1_SB_DQS_DP<3>")
	)
	(segment
		(start 41.23944 -313.376564)
		(end 41.79824 -313.376564)
		(width 0.16002)
		(layer "In6.Cu")
		(net "M_E_CPU1_SB_DQS_DP<3>")
	)
	(segment
		(start 32.163258 -313.06008)
		(end 33.23717 -313.06008)
		(width 0.16002)
		(layer "In6.Cu")
		(net "M_E_CPU1_SB_DQS_DP<3>")
	)
	(segment
		(start 43.447208 -312.210196)
		(end 45.356272 -312.210196)
		(width 0.16002)
		(layer "In6.Cu")
		(net "M_E_CPU1_SB_DQS_DP<3>")
	)
	(segment
		(start 71.661274 -298.11472)
		(end 71.821548 -298.274994)
		(width 0.16002)
		(layer "In6.Cu")
		(net "M_E_CPU1_SB_DQS_DP<3>")
	)
	(segment
		(start 48.9966 -313.372246)
		(end 49.35474 -313.372246)
		(width 0.16002)
		(layer "In6.Cu")
		(net "M_E_CPU1_SB_DQS_DP<3>")
	)
	(segment
		(start 80.771238 -290.616132)
		(end 80.77962 -290.611306)
		(width 0.09525)
		(layer "In6.Cu")
		(net "M_E_CPU1_SB_DQS_DP<3>")
	)
	(segment
		(start 65.74155 -304.581052)
		(end 66.7385 -303.584102)
		(width 0.16002)
		(layer "In6.Cu")
		(net "M_E_CPU1_SB_DQS_DP<3>")
	)
	(segment
		(start 37.413946 -312.210196)
		(end 39.466012 -313.06008)
		(width 0.16002)
		(layer "In6.Cu")
		(net "M_E_CPU1_SB_DQS_DP<3>")
	)
	(segment
		(start 67.4878 -302.288194)
		(end 67.648074 -302.448468)
		(width 0.16002)
		(layer "In6.Cu")
		(net "M_E_CPU1_SB_DQS_DP<3>")
	)
	(segment
		(start 63.14821 -307.606446)
		(end 65.74155 -305.013106)
		(width 0.16002)
		(layer "In6.Cu")
		(net "M_E_CPU1_SB_DQS_DP<3>")
	)
	(segment
		(start 70.751954 -299.024294)
		(end 70.751954 -298.54779)
		(width 0.16002)
		(layer "In6.Cu")
		(net "M_E_CPU1_SB_DQS_DP<3>")
	)
	(segment
		(start 63.14821 -308.917086)
		(end 63.14821 -307.606446)
		(width 0.16002)
		(layer "In6.Cu")
		(net "M_E_CPU1_SB_DQS_DP<3>")
	)
	(segment
		(start 35.911536 -312.210196)
		(end 37.413946 -312.210196)
		(width 0.16002)
		(layer "In6.Cu")
		(net "M_E_CPU1_SB_DQS_DP<3>")
	)
	(segment
		(start 68.129658 -302.192944)
		(end 68.129658 -301.966884)
		(width 0.16002)
		(layer "In6.Cu")
		(net "M_E_CPU1_SB_DQS_DP<3>")
	)
	(segment
		(start 35.570668 -312.551064)
		(end 35.911536 -312.210196)
		(width 0.16002)
		(layer "In6.Cu")
		(net "M_E_CPU1_SB_DQS_DP<3>")
	)
	(segment
		(start 34.24047 -313.390534)
		(end 35.07994 -312.551064)
		(width 0.16002)
		(layer "In6.Cu")
		(net "M_E_CPU1_SB_DQS_DP<3>")
	)
	(segment
		(start 79.461614 -290.611306)
		(end 79.469996 -290.616132)
		(width 0.09525)
		(layer "In6.Cu")
		(net "M_E_CPU1_SB_DQS_DP<3>")
	)
	(segment
		(start 49.35474 -313.372246)
		(end 50.11674 -312.610246)
		(width 0.16002)
		(layer "In6.Cu")
		(net "M_E_CPU1_SB_DQS_DP<3>")
	)
	(segment
		(start 67.01155 -302.288194)
		(end 67.4878 -302.288194)
		(width 0.16002)
		(layer "In6.Cu")
		(net "M_E_CPU1_SB_DQS_DP<3>")
	)
	(segment
		(start 66.7385 -303.358042)
		(end 66.57848 -303.197768)
		(width 0.16002)
		(layer "In6.Cu")
		(net "M_E_CPU1_SB_DQS_DP<3>")
	)
	(segment
		(start 40.922956 -313.06008)
		(end 41.23944 -313.376564)
		(width 0.16002)
		(layer "In6.Cu")
		(net "M_E_CPU1_SB_DQS_DP<3>")
	)
	(segment
		(start 66.7385 -303.584102)
		(end 66.7385 -303.358042)
		(width 0.16002)
		(layer "In6.Cu")
		(net "M_E_CPU1_SB_DQS_DP<3>")
	)
	(segment
		(start 56.88584 -313.384946)
		(end 57.74944 -312.521346)
		(width 0.16002)
		(layer "In6.Cu")
		(net "M_E_CPU1_SB_DQS_DP<3>")
	)
	(segment
		(start 70.270116 -299.505878)
		(end 70.43039 -299.666152)
		(width 0.16002)
		(layer "In6.Cu")
		(net "M_E_CPU1_SB_DQS_DP<3>")
	)
	(segment
		(start 76.294996 -294.027606)
		(end 76.31176 -294.010842)
		(width 0.09525)
		(layer "In6.Cu")
		(net "M_E_CPU1_SB_DQS_DP<3>")
	)
	(segment
		(start 67.969638 -301.330106)
		(end 68.402708 -300.897036)
		(width 0.16002)
		(layer "In6.Cu")
		(net "M_E_CPU1_SB_DQS_DP<3>")
	)
	(segment
		(start 65.74155 -305.013106)
		(end 65.74155 -304.581052)
		(width 0.16002)
		(layer "In6.Cu")
		(net "M_E_CPU1_SB_DQS_DP<3>")
	)
	(segment
		(start 69.793866 -299.505878)
		(end 70.270116 -299.505878)
		(width 0.16002)
		(layer "In6.Cu")
		(net "M_E_CPU1_SB_DQS_DP<3>")
	)
	(segment
		(start 68.402708 -300.897036)
		(end 68.878958 -300.897036)
		(width 0.16002)
		(layer "In6.Cu")
		(net "M_E_CPU1_SB_DQS_DP<3>")
	)
	(segment
		(start 72.047608 -298.274994)
		(end 76.294996 -294.027606)
		(width 0.16002)
		(layer "In6.Cu")
		(net "M_E_CPU1_SB_DQS_DP<3>")
	)
	(segment
		(start 39.466012 -313.06008)
		(end 40.922956 -313.06008)
		(width 0.16002)
		(layer "In6.Cu")
		(net "M_E_CPU1_SB_DQS_DP<3>")
	)
	(segment
		(start 66.57848 -303.197768)
		(end 66.57848 -302.721264)
		(width 0.16002)
		(layer "In6.Cu")
		(net "M_E_CPU1_SB_DQS_DP<3>")
	)
	(segment
		(start 69.360796 -299.938948)
		(end 69.793866 -299.505878)
		(width 0.16002)
		(layer "In6.Cu")
		(net "M_E_CPU1_SB_DQS_DP<3>")
	)
	(segment
		(start 69.520816 -300.801786)
		(end 69.520816 -300.575726)
		(width 0.16002)
		(layer "In6.Cu")
		(net "M_E_CPU1_SB_DQS_DP<3>")
	)
	(segment
		(start 45.356272 -312.210196)
		(end 46.206156 -313.06008)
		(width 0.16002)
		(layer "In6.Cu")
		(net "M_E_CPU1_SB_DQS_DP<3>")
	)
	(segment
		(start 67.969638 -301.80661)
		(end 67.969638 -301.330106)
		(width 0.16002)
		(layer "In6.Cu")
		(net "M_E_CPU1_SB_DQS_DP<3>")
	)
	(segment
		(start 33.567624 -313.390534)
		(end 34.24047 -313.390534)
		(width 0.16002)
		(layer "In6.Cu")
		(net "M_E_CPU1_SB_DQS_DP<3>")
	)
	(segment
		(start 70.65645 -299.666152)
		(end 70.911974 -299.410628)
		(width 0.16002)
		(layer "In6.Cu")
		(net "M_E_CPU1_SB_DQS_DP<3>")
	)
	(segment
		(start 46.206156 -313.06008)
		(end 48.684434 -313.06008)
		(width 0.16002)
		(layer "In6.Cu")
		(net "M_E_CPU1_SB_DQS_DP<3>")
	)
	(segment
		(start 50.59934 -312.610246)
		(end 50.99939 -312.210196)
		(width 0.16002)
		(layer "In6.Cu")
		(net "M_E_CPU1_SB_DQS_DP<3>")
	)
	(segment
		(start 53.035962 -312.210196)
		(end 54.210712 -313.384946)
		(width 0.16002)
		(layer "In6.Cu")
		(net "M_E_CPU1_SB_DQS_DP<3>")
	)
	(segment
		(start 59.54395 -312.521346)
		(end 63.14821 -308.917086)
		(width 0.16002)
		(layer "In6.Cu")
		(net "M_E_CPU1_SB_DQS_DP<3>")
	)
	(segment
		(start 69.520816 -300.575726)
		(end 69.360796 -300.415452)
		(width 0.16002)
		(layer "In6.Cu")
		(net "M_E_CPU1_SB_DQS_DP<3>")
	)
	(segment
		(start 54.210712 -313.384946)
		(end 56.88584 -313.384946)
		(width 0.16002)
		(layer "In6.Cu")
		(net "M_E_CPU1_SB_DQS_DP<3>")
	)
	(segment
		(start 76.31176 -294.010842)
		(end 76.394564 -294.011096)
		(width 0.09525)
		(layer "In6.Cu")
		(net "M_E_CPU1_SB_DQS_DP<3>")
	)
	(segment
		(start 29.525976 -313.209178)
		(end 32.01416 -313.209178)
		(width 0.16002)
		(layer "In6.Cu")
		(net "M_E_CPU1_SB_DQS_DP<3>")
	)
	(segment
		(start 42.63644 -312.538364)
		(end 43.11904 -312.538364)
		(width 0.16002)
		(layer "In6.Cu")
		(net "M_E_CPU1_SB_DQS_DP<3>")
	)
	(segment
		(start 68.878958 -300.897036)
		(end 69.039232 -301.05731)
		(width 0.16002)
		(layer "In6.Cu")
		(net "M_E_CPU1_SB_DQS_DP<3>")
	)
	(segment
		(start 48.684434 -313.06008)
		(end 48.9966 -313.372246)
		(width 0.16002)
		(layer "In6.Cu")
		(net "M_E_CPU1_SB_DQS_DP<3>")
	)
	(segment
		(start 67.648074 -302.448468)
		(end 67.874134 -302.448468)
		(width 0.16002)
		(layer "In6.Cu")
		(net "M_E_CPU1_SB_DQS_DP<3>")
	)
	(segment
		(start 29.252164 -312.935366)
		(end 29.525976 -313.209178)
		(width 0.16002)
		(layer "In6.Cu")
		(net "M_E_CPU1_SB_DQS_DP<3>")
	)
	(segment
		(start 77.891386 -291.592508)
		(end 78.783942 -290.699952)
		(width 0.09525)
		(layer "In6.Cu")
		(net "M_E_CPU1_SB_DQS_DP<3>")
	)
	(segment
		(start 69.039232 -301.05731)
		(end 69.265292 -301.05731)
		(width 0.16002)
		(layer "In6.Cu")
		(net "M_E_CPU1_SB_DQS_DP<3>")
	)
	(segment
		(start 50.11674 -312.610246)
		(end 50.59934 -312.610246)
		(width 0.16002)
		(layer "In6.Cu")
		(net "M_E_CPU1_SB_DQS_DP<3>")
	)
	(segment
		(start 70.43039 -299.666152)
		(end 70.65645 -299.666152)
		(width 0.16002)
		(layer "In6.Cu")
		(net "M_E_CPU1_SB_DQS_DP<3>")
	)
	(segment
		(start 70.911974 -299.184568)
		(end 70.751954 -299.024294)
		(width 0.16002)
		(layer "In6.Cu")
		(net "M_E_CPU1_SB_DQS_DP<3>")
	)
	(segment
		(start 57.74944 -312.521346)
		(end 59.54395 -312.521346)
		(width 0.16002)
		(layer "In6.Cu")
		(net "M_E_CPU1_SB_DQS_DP<3>")
	)
	(segment
		(start 70.911974 -299.410628)
		(end 70.911974 -299.184568)
		(width 0.16002)
		(layer "In6.Cu")
		(net "M_E_CPU1_SB_DQS_DP<3>")
	)
	(segment
		(start 66.57848 -302.721264)
		(end 67.01155 -302.288194)
		(width 0.16002)
		(layer "In6.Cu")
		(net "M_E_CPU1_SB_DQS_DP<3>")
	)
	(segment
		(start 50.99939 -312.210196)
		(end 53.035962 -312.210196)
		(width 0.16002)
		(layer "In6.Cu")
		(net "M_E_CPU1_SB_DQS_DP<3>")
	)
	(segment
		(start 41.79824 -313.376564)
		(end 42.63644 -312.538364)
		(width 0.16002)
		(layer "In6.Cu")
		(net "M_E_CPU1_SB_DQS_DP<3>")
	)
	(segment
		(start 81.27619 -290.578286)
		(end 81.377028 -290.551616)
		(width 0.09525)
		(layer "In6.Cu")
		(net "M_E_CPU1_SB_DQS_DP<3>")
	)
	(segment
		(start 33.23717 -313.06008)
		(end 33.567624 -313.390534)
		(width 0.16002)
		(layer "In6.Cu")
		(net "M_E_CPU1_SB_DQS_DP<3>")
	)
	(segment
		(start 68.129658 -301.966884)
		(end 67.969638 -301.80661)
		(width 0.16002)
		(layer "In6.Cu")
		(net "M_E_CPU1_SB_DQS_DP<3>")
	)
	(arc
		(start 80.40243 -290.611306)
		(mid 80.586205 -290.662078)
		(end 80.771238 -290.616132)
		(width 0.09525)
		(layer "In6.Cu")
		(net "M_E_CPU1_SB_DQS_DP<3>")
	)
	(arc
		(start 80.77962 -290.611306)
		(mid 81.013415 -290.537439)
		(end 81.256378 -290.570412)
		(width 0.09525)
		(layer "In6.Cu")
		(net "M_E_CPU1_SB_DQS_DP<3>")
	)
	(arc
		(start 78.917292 -290.601146)
		(mid 79.190752 -290.535773)
		(end 79.461614 -290.611306)
		(width 0.09525)
		(layer "In6.Cu")
		(net "M_E_CPU1_SB_DQS_DP<3>")
	)
	(arc
		(start 79.469996 -290.616132)
		(mid 79.655282 -290.662168)
		(end 79.839312 -290.611306)
		(width 0.09525)
		(layer "In6.Cu")
		(net "M_E_CPU1_SB_DQS_DP<3>")
	)
	(arc
		(start 79.839312 -290.611306)
		(mid 80.114855 -290.535457)
		(end 80.392016 -290.60521)
		(width 0.09525)
		(layer "In6.Cu")
		(net "M_E_CPU1_SB_DQS_DP<3>")
	)
	(arc
		(start 78.783942 -290.699952)
		(mid 78.846936 -290.64558)
		(end 78.917292 -290.601146)
		(width 0.09525)
		(layer "In6.Cu")
		(net "M_E_CPU1_SB_DQS_DP<3>")
	)
	(arc
		(start 81.256378 -290.570412)
		(mid 81.266321 -290.574255)
		(end 81.27619 -290.578286)
		(width 0.09525)
		(layer "In6.Cu")
		(net "M_E_CPU1_SB_DQS_DP<3>")
	)
	(segment
		(start 81.997804 -285.160466)
		(end 81.530952 -285.426404)
		(width 0.12954)
		(layer "F.Cu")
		(net "M_E_CPU1_SB_DQS_DP<2>")
	)
	(segment
		(start 55.103776 -304.276506)
		(end 55.899304 -304.276506)
		(width 0.16002)
		(layer "In6.Cu")
		(net "M_E_CPU1_SB_DQS_DP<2>")
	)
	(segment
		(start 40.958262 -304.108104)
		(end 41.74109 -304.108104)
		(width 0.16002)
		(layer "In6.Cu")
		(net "M_E_CPU1_SB_DQS_DP<2>")
	)
	(segment
		(start 43.15079 -303.231804)
		(end 43.522392 -302.860202)
		(width 0.16002)
		(layer "In6.Cu")
		(net "M_E_CPU1_SB_DQS_DP<2>")
	)
	(segment
		(start 35.069018 -303.269904)
		(end 35.51809 -303.269904)
		(width 0.16002)
		(layer "In6.Cu")
		(net "M_E_CPU1_SB_DQS_DP<2>")
	)
	(segment
		(start 40.560244 -303.710086)
		(end 40.958262 -304.108104)
		(width 0.16002)
		(layer "In6.Cu")
		(net "M_E_CPU1_SB_DQS_DP<2>")
	)
	(segment
		(start 56.89219 -304.050192)
		(end 57.75579 -303.186592)
		(width 0.16002)
		(layer "In6.Cu")
		(net "M_E_CPU1_SB_DQS_DP<2>")
	)
	(segment
		(start 57.75579 -303.186592)
		(end 59.399424 -303.186592)
		(width 0.16002)
		(layer "In6.Cu")
		(net "M_E_CPU1_SB_DQS_DP<2>")
	)
	(segment
		(start 39.827708 -303.710086)
		(end 40.560244 -303.710086)
		(width 0.16002)
		(layer "In6.Cu")
		(net "M_E_CPU1_SB_DQS_DP<2>")
	)
	(segment
		(start 33.549844 -303.710086)
		(end 33.871662 -304.031904)
		(width 0.16002)
		(layer "In6.Cu")
		(net "M_E_CPU1_SB_DQS_DP<2>")
	)
	(segment
		(start 61.662564 -299.654468)
		(end 66.723006 -294.594026)
		(width 0.16002)
		(layer "In6.Cu")
		(net "M_E_CPU1_SB_DQS_DP<2>")
	)
	(segment
		(start 59.399424 -303.186592)
		(end 60.765182 -301.820834)
		(width 0.16002)
		(layer "In6.Cu")
		(net "M_E_CPU1_SB_DQS_DP<2>")
	)
	(segment
		(start 48.662844 -303.710086)
		(end 48.99025 -304.037492)
		(width 0.16002)
		(layer "In6.Cu")
		(net "M_E_CPU1_SB_DQS_DP<2>")
	)
	(segment
		(start 67.531742 -293.311834)
		(end 68.134992 -293.311834)
		(width 0.16002)
		(layer "In6.Cu")
		(net "M_E_CPU1_SB_DQS_DP<2>")
	)
	(segment
		(start 52.380642 -302.860202)
		(end 52.7177 -303.19726)
		(width 0.16002)
		(layer "In6.Cu")
		(net "M_E_CPU1_SB_DQS_DP<2>")
	)
	(segment
		(start 45.550836 -303.747678)
		(end 45.835062 -304.031904)
		(width 0.16002)
		(layer "In6.Cu")
		(net "M_E_CPU1_SB_DQS_DP<2>")
	)
	(segment
		(start 77.85227 -285.803086)
		(end 78.711044 -285.803086)
		(width 0.09525)
		(layer "In6.Cu")
		(net "M_E_CPU1_SB_DQS_DP<2>")
	)
	(segment
		(start 41.74109 -304.108104)
		(end 42.61739 -303.231804)
		(width 0.16002)
		(layer "In6.Cu")
		(net "M_E_CPU1_SB_DQS_DP<2>")
	)
	(segment
		(start 68.440554 -293.006272)
		(end 68.440554 -292.403022)
		(width 0.16002)
		(layer "In6.Cu")
		(net "M_E_CPU1_SB_DQS_DP<2>")
	)
	(segment
		(start 31.14421 -304.108104)
		(end 31.70809 -304.108104)
		(width 0.16002)
		(layer "In6.Cu")
		(net "M_E_CPU1_SB_DQS_DP<2>")
	)
	(segment
		(start 52.894484 -303.869598)
		(end 54.696868 -303.869598)
		(width 0.16002)
		(layer "In6.Cu")
		(net "M_E_CPU1_SB_DQS_DP<2>")
	)
	(segment
		(start 38.977062 -304.108104)
		(end 39.42969 -304.108104)
		(width 0.16002)
		(layer "In6.Cu")
		(net "M_E_CPU1_SB_DQS_DP<2>")
	)
	(segment
		(start 43.522392 -302.860202)
		(end 45.102272 -302.860202)
		(width 0.16002)
		(layer "In6.Cu")
		(net "M_E_CPU1_SB_DQS_DP<2>")
	)
	(segment
		(start 42.61739 -303.231804)
		(end 43.15079 -303.231804)
		(width 0.16002)
		(layer "In6.Cu")
		(net "M_E_CPU1_SB_DQS_DP<2>")
	)
	(segment
		(start 68.440554 -292.403022)
		(end 68.9229 -291.920676)
		(width 0.16002)
		(layer "In6.Cu")
		(net "M_E_CPU1_SB_DQS_DP<2>")
	)
	(segment
		(start 31.70809 -304.108104)
		(end 32.106108 -303.710086)
		(width 0.16002)
		(layer "In6.Cu")
		(net "M_E_CPU1_SB_DQS_DP<2>")
	)
	(segment
		(start 45.835062 -304.031904)
		(end 47.083218 -304.031904)
		(width 0.16002)
		(layer "In6.Cu")
		(net "M_E_CPU1_SB_DQS_DP<2>")
	)
	(segment
		(start 52.7177 -303.692814)
		(end 52.894484 -303.869598)
		(width 0.16002)
		(layer "In6.Cu")
		(net "M_E_CPU1_SB_DQS_DP<2>")
	)
	(segment
		(start 37.85743 -303.981104)
		(end 38.850062 -303.981104)
		(width 0.16002)
		(layer "In6.Cu")
		(net "M_E_CPU1_SB_DQS_DP<2>")
	)
	(segment
		(start 54.696868 -303.869598)
		(end 55.103776 -304.276506)
		(width 0.16002)
		(layer "In6.Cu")
		(net "M_E_CPU1_SB_DQS_DP<2>")
	)
	(segment
		(start 60.765182 -301.820834)
		(end 61.662564 -299.654468)
		(width 0.16002)
		(layer "In6.Cu")
		(net "M_E_CPU1_SB_DQS_DP<2>")
	)
	(segment
		(start 79.83982 -285.751778)
		(end 79.857092 -285.741872)
		(width 0.09525)
		(layer "In6.Cu")
		(net "M_E_CPU1_SB_DQS_DP<2>")
	)
	(segment
		(start 69.52615 -291.920676)
		(end 69.831712 -291.615114)
		(width 0.16002)
		(layer "In6.Cu")
		(net "M_E_CPU1_SB_DQS_DP<2>")
	)
	(segment
		(start 68.134992 -293.311834)
		(end 68.440554 -293.006272)
		(width 0.16002)
		(layer "In6.Cu")
		(net "M_E_CPU1_SB_DQS_DP<2>")
	)
	(segment
		(start 71.22287 -290.223956)
		(end 71.22287 -289.620706)
		(width 0.16002)
		(layer "In6.Cu")
		(net "M_E_CPU1_SB_DQS_DP<2>")
	)
	(segment
		(start 77.20584 -286.449516)
		(end 77.85227 -285.803086)
		(width 0.09525)
		(layer "In6.Cu")
		(net "M_E_CPU1_SB_DQS_DP<2>")
	)
	(segment
		(start 73.056496 -289.04184)
		(end 75.708002 -286.390334)
		(width 0.16002)
		(layer "In6.Cu")
		(net "M_E_CPU1_SB_DQS_DP<2>")
	)
	(segment
		(start 66.723006 -294.594026)
		(end 67.058286 -293.78529)
		(width 0.16002)
		(layer "In6.Cu")
		(net "M_E_CPU1_SB_DQS_DP<2>")
	)
	(segment
		(start 49.36109 -304.037492)
		(end 50.12309 -303.275492)
		(width 0.16002)
		(layer "In6.Cu")
		(net "M_E_CPU1_SB_DQS_DP<2>")
	)
	(segment
		(start 30.89529 -303.859184)
		(end 31.14421 -304.108104)
		(width 0.16002)
		(layer "In6.Cu")
		(net "M_E_CPU1_SB_DQS_DP<2>")
	)
	(segment
		(start 47.405036 -303.710086)
		(end 48.662844 -303.710086)
		(width 0.16002)
		(layer "In6.Cu")
		(net "M_E_CPU1_SB_DQS_DP<2>")
	)
	(segment
		(start 69.831712 -291.011864)
		(end 70.314058 -290.529518)
		(width 0.16002)
		(layer "In6.Cu")
		(net "M_E_CPU1_SB_DQS_DP<2>")
	)
	(segment
		(start 34.307018 -304.031904)
		(end 35.069018 -303.269904)
		(width 0.16002)
		(layer "In6.Cu")
		(net "M_E_CPU1_SB_DQS_DP<2>")
	)
	(segment
		(start 70.917308 -290.529518)
		(end 71.22287 -290.223956)
		(width 0.16002)
		(layer "In6.Cu")
		(net "M_E_CPU1_SB_DQS_DP<2>")
	)
	(segment
		(start 56.125618 -304.050192)
		(end 56.89219 -304.050192)
		(width 0.16002)
		(layer "In6.Cu")
		(net "M_E_CPU1_SB_DQS_DP<2>")
	)
	(segment
		(start 38.850062 -303.981104)
		(end 38.977062 -304.108104)
		(width 0.16002)
		(layer "In6.Cu")
		(net "M_E_CPU1_SB_DQS_DP<2>")
	)
	(segment
		(start 71.22287 -289.620706)
		(end 71.801736 -289.04184)
		(width 0.16002)
		(layer "In6.Cu")
		(net "M_E_CPU1_SB_DQS_DP<2>")
	)
	(segment
		(start 37.216842 -302.860202)
		(end 37.5539 -303.19726)
		(width 0.16002)
		(layer "In6.Cu")
		(net "M_E_CPU1_SB_DQS_DP<2>")
	)
	(segment
		(start 35.927792 -302.860202)
		(end 37.216842 -302.860202)
		(width 0.16002)
		(layer "In6.Cu")
		(net "M_E_CPU1_SB_DQS_DP<2>")
	)
	(segment
		(start 80.771238 -285.75635)
		(end 80.77962 -285.751524)
		(width 0.09525)
		(layer "In6.Cu")
		(net "M_E_CPU1_SB_DQS_DP<2>")
	)
	(segment
		(start 76.17587 -286.390334)
		(end 76.199492 -286.390334)
		(width 0.09525)
		(layer "In6.Cu")
		(net "M_E_CPU1_SB_DQS_DP<2>")
	)
	(segment
		(start 39.42969 -304.108104)
		(end 39.827708 -303.710086)
		(width 0.16002)
		(layer "In6.Cu")
		(net "M_E_CPU1_SB_DQS_DP<2>")
	)
	(segment
		(start 71.801736 -289.04184)
		(end 73.056496 -289.04184)
		(width 0.16002)
		(layer "In6.Cu")
		(net "M_E_CPU1_SB_DQS_DP<2>")
	)
	(segment
		(start 76.199492 -286.390334)
		(end 76.258674 -286.449516)
		(width 0.09525)
		(layer "In6.Cu")
		(net "M_E_CPU1_SB_DQS_DP<2>")
	)
	(segment
		(start 37.5539 -303.677574)
		(end 37.85743 -303.981104)
		(width 0.16002)
		(layer "In6.Cu")
		(net "M_E_CPU1_SB_DQS_DP<2>")
	)
	(segment
		(start 67.058286 -293.78529)
		(end 67.531742 -293.311834)
		(width 0.16002)
		(layer "In6.Cu")
		(net "M_E_CPU1_SB_DQS_DP<2>")
	)
	(segment
		(start 79.448914 -285.743904)
		(end 79.46263 -285.752032)
		(width 0.09525)
		(layer "In6.Cu")
		(net "M_E_CPU1_SB_DQS_DP<2>")
	)
	(segment
		(start 45.102272 -302.860202)
		(end 45.550836 -303.308766)
		(width 0.16002)
		(layer "In6.Cu")
		(net "M_E_CPU1_SB_DQS_DP<2>")
	)
	(segment
		(start 37.5539 -303.19726)
		(end 37.5539 -303.677574)
		(width 0.16002)
		(layer "In6.Cu")
		(net "M_E_CPU1_SB_DQS_DP<2>")
	)
	(segment
		(start 70.314058 -290.529518)
		(end 70.917308 -290.529518)
		(width 0.16002)
		(layer "In6.Cu")
		(net "M_E_CPU1_SB_DQS_DP<2>")
	)
	(segment
		(start 68.9229 -291.920676)
		(end 69.52615 -291.920676)
		(width 0.16002)
		(layer "In6.Cu")
		(net "M_E_CPU1_SB_DQS_DP<2>")
	)
	(segment
		(start 75.708002 -286.390334)
		(end 76.17587 -286.390334)
		(width 0.16002)
		(layer "In6.Cu")
		(net "M_E_CPU1_SB_DQS_DP<2>")
	)
	(segment
		(start 45.550836 -303.308766)
		(end 45.550836 -303.747678)
		(width 0.16002)
		(layer "In6.Cu")
		(net "M_E_CPU1_SB_DQS_DP<2>")
	)
	(segment
		(start 81.27619 -285.718504)
		(end 81.377028 -285.691834)
		(width 0.09525)
		(layer "In6.Cu")
		(net "M_E_CPU1_SB_DQS_DP<2>")
	)
	(segment
		(start 29.525976 -303.859184)
		(end 30.89529 -303.859184)
		(width 0.16002)
		(layer "In6.Cu")
		(net "M_E_CPU1_SB_DQS_DP<2>")
	)
	(segment
		(start 79.82585 -285.759652)
		(end 79.83982 -285.751778)
		(width 0.09525)
		(layer "In6.Cu")
		(net "M_E_CPU1_SB_DQS_DP<2>")
	)
	(segment
		(start 69.831712 -291.615114)
		(end 69.831712 -291.011864)
		(width 0.16002)
		(layer "In6.Cu")
		(net "M_E_CPU1_SB_DQS_DP<2>")
	)
	(segment
		(start 35.51809 -303.269904)
		(end 35.927792 -302.860202)
		(width 0.16002)
		(layer "In6.Cu")
		(net "M_E_CPU1_SB_DQS_DP<2>")
	)
	(segment
		(start 29.252164 -303.585372)
		(end 29.525976 -303.859184)
		(width 0.16002)
		(layer "In6.Cu")
		(net "M_E_CPU1_SB_DQS_DP<2>")
	)
	(segment
		(start 52.7177 -303.19726)
		(end 52.7177 -303.692814)
		(width 0.16002)
		(layer "In6.Cu")
		(net "M_E_CPU1_SB_DQS_DP<2>")
	)
	(segment
		(start 50.12309 -303.275492)
		(end 50.60569 -303.275492)
		(width 0.16002)
		(layer "In6.Cu")
		(net "M_E_CPU1_SB_DQS_DP<2>")
	)
	(segment
		(start 33.871662 -304.031904)
		(end 34.307018 -304.031904)
		(width 0.16002)
		(layer "In6.Cu")
		(net "M_E_CPU1_SB_DQS_DP<2>")
	)
	(segment
		(start 55.899304 -304.276506)
		(end 56.125618 -304.050192)
		(width 0.16002)
		(layer "In6.Cu")
		(net "M_E_CPU1_SB_DQS_DP<2>")
	)
	(segment
		(start 32.106108 -303.710086)
		(end 33.549844 -303.710086)
		(width 0.16002)
		(layer "In6.Cu")
		(net "M_E_CPU1_SB_DQS_DP<2>")
	)
	(segment
		(start 47.083218 -304.031904)
		(end 47.405036 -303.710086)
		(width 0.16002)
		(layer "In6.Cu")
		(net "M_E_CPU1_SB_DQS_DP<2>")
	)
	(segment
		(start 50.60569 -303.275492)
		(end 51.02098 -302.860202)
		(width 0.16002)
		(layer "In6.Cu")
		(net "M_E_CPU1_SB_DQS_DP<2>")
	)
	(segment
		(start 48.99025 -304.037492)
		(end 49.36109 -304.037492)
		(width 0.16002)
		(layer "In6.Cu")
		(net "M_E_CPU1_SB_DQS_DP<2>")
	)
	(segment
		(start 81.377028 -285.691834)
		(end 81.530952 -285.426404)
		(width 0.09525)
		(layer "In6.Cu")
		(net "M_E_CPU1_SB_DQS_DP<2>")
	)
	(segment
		(start 76.258674 -286.449516)
		(end 77.20584 -286.449516)
		(width 0.09525)
		(layer "In6.Cu")
		(net "M_E_CPU1_SB_DQS_DP<2>")
	)
	(segment
		(start 51.02098 -302.860202)
		(end 52.380642 -302.860202)
		(width 0.16002)
		(layer "In6.Cu")
		(net "M_E_CPU1_SB_DQS_DP<2>")
	)
	(arc
		(start 80.77962 -285.751524)
		(mid 81.013415 -285.677657)
		(end 81.256378 -285.71063)
		(width 0.09525)
		(layer "In6.Cu")
		(net "M_E_CPU1_SB_DQS_DP<2>")
	)
	(arc
		(start 79.857092 -285.741872)
		(mid 80.131001 -285.675951)
		(end 80.40243 -285.751524)
		(width 0.09525)
		(layer "In6.Cu")
		(net "M_E_CPU1_SB_DQS_DP<2>")
	)
	(arc
		(start 78.711044 -285.803086)
		(mid 78.808794 -285.789899)
		(end 78.899766 -285.751778)
		(width 0.09525)
		(layer "In6.Cu")
		(net "M_E_CPU1_SB_DQS_DP<2>")
	)
	(arc
		(start 81.256378 -285.71063)
		(mid 81.266321 -285.714473)
		(end 81.27619 -285.718504)
		(width 0.09525)
		(layer "In6.Cu")
		(net "M_E_CPU1_SB_DQS_DP<2>")
	)
	(arc
		(start 80.40243 -285.751524)
		(mid 80.586205 -285.802296)
		(end 80.771238 -285.75635)
		(width 0.09525)
		(layer "In6.Cu")
		(net "M_E_CPU1_SB_DQS_DP<2>")
	)
	(arc
		(start 79.46263 -285.752032)
		(mid 79.643253 -285.802627)
		(end 79.82585 -285.759652)
		(width 0.09525)
		(layer "In6.Cu")
		(net "M_E_CPU1_SB_DQS_DP<2>")
	)
	(arc
		(start 78.899766 -285.751778)
		(mid 79.173322 -285.675989)
		(end 79.448914 -285.743904)
		(width 0.09525)
		(layer "In6.Cu")
		(net "M_E_CPU1_SB_DQS_DP<2>")
	)
	(segment
		(start 81.997804 -280.30043)
		(end 81.530952 -280.566368)
		(width 0.12954)
		(layer "F.Cu")
		(net "M_E_CPU1_SB_DQS_DP<1>")
	)
	(segment
		(start 31.182818 -294.50919)
		(end 31.419292 -294.745664)
		(width 0.16002)
		(layer "In6.Cu")
		(net "M_E_CPU1_SB_DQS_DP<1>")
	)
	(segment
		(start 29.252164 -294.235378)
		(end 29.525976 -294.50919)
		(width 0.16002)
		(layer "In6.Cu")
		(net "M_E_CPU1_SB_DQS_DP<1>")
	)
	(segment
		(start 34.263076 -294.669464)
		(end 35.063176 -293.869364)
		(width 0.16002)
		(layer "In6.Cu")
		(net "M_E_CPU1_SB_DQS_DP<1>")
	)
	(segment
		(start 65.64884 -287.34258)
		(end 65.64884 -286.766508)
		(width 0.16002)
		(layer "In6.Cu")
		(net "M_E_CPU1_SB_DQS_DP<1>")
	)
	(segment
		(start 48.776382 -295.01338)
		(end 49.094898 -295.01338)
		(width 0.16002)
		(layer "In6.Cu")
		(net "M_E_CPU1_SB_DQS_DP<1>")
	)
	(segment
		(start 29.525976 -294.50919)
		(end 31.182818 -294.50919)
		(width 0.16002)
		(layer "In6.Cu")
		(net "M_E_CPU1_SB_DQS_DP<1>")
	)
	(segment
		(start 66.144648 -286.2707)
		(end 66.72072 -286.2707)
		(width 0.16002)
		(layer "In6.Cu")
		(net "M_E_CPU1_SB_DQS_DP<1>")
	)
	(segment
		(start 53.906928 -294.639492)
		(end 54.434994 -294.111426)
		(width 0.16002)
		(layer "In6.Cu")
		(net "M_E_CPU1_SB_DQS_DP<1>")
	)
	(segment
		(start 70.894194 -282.097226)
		(end 71.213472 -281.777948)
		(width 0.16002)
		(layer "In6.Cu")
		(net "M_E_CPU1_SB_DQS_DP<1>")
	)
	(segment
		(start 42.61104 -293.869364)
		(end 43.19524 -293.869364)
		(width 0.16002)
		(layer "In6.Cu")
		(net "M_E_CPU1_SB_DQS_DP<1>")
	)
	(segment
		(start 49.094898 -295.01338)
		(end 50.19802 -293.910258)
		(width 0.16002)
		(layer "In6.Cu")
		(net "M_E_CPU1_SB_DQS_DP<1>")
	)
	(segment
		(start 68.111878 -284.879542)
		(end 68.431156 -284.560264)
		(width 0.16002)
		(layer "In6.Cu")
		(net "M_E_CPU1_SB_DQS_DP<1>")
	)
	(segment
		(start 59.661806 -293.821358)
		(end 61.89345 -291.589714)
		(width 0.16002)
		(layer "In6.Cu")
		(net "M_E_CPU1_SB_DQS_DP<1>")
	)
	(segment
		(start 68.431156 -284.560264)
		(end 68.431156 -283.984192)
		(width 0.16002)
		(layer "In6.Cu")
		(net "M_E_CPU1_SB_DQS_DP<1>")
	)
	(segment
		(start 44.707302 -293.510208)
		(end 45.815758 -294.618664)
		(width 0.16002)
		(layer "In6.Cu")
		(net "M_E_CPU1_SB_DQS_DP<1>")
	)
	(segment
		(start 76.27239 -280.839926)
		(end 76.57211 -280.540206)
		(width 0.09525)
		(layer "In6.Cu")
		(net "M_E_CPU1_SB_DQS_DP<1>")
	)
	(segment
		(start 48.123094 -294.360092)
		(end 48.776382 -295.01338)
		(width 0.16002)
		(layer "In6.Cu")
		(net "M_E_CPU1_SB_DQS_DP<1>")
	)
	(segment
		(start 41.091358 -294.72001)
		(end 41.760394 -294.72001)
		(width 0.16002)
		(layer "In6.Cu")
		(net "M_E_CPU1_SB_DQS_DP<1>")
	)
	(segment
		(start 69.822314 -283.169106)
		(end 69.822314 -282.593034)
		(width 0.16002)
		(layer "In6.Cu")
		(net "M_E_CPU1_SB_DQS_DP<1>")
	)
	(segment
		(start 79.45247 -280.885392)
		(end 79.462884 -280.891488)
		(width 0.09525)
		(layer "In6.Cu")
		(net "M_E_CPU1_SB_DQS_DP<1>")
	)
	(segment
		(start 43.19524 -293.869364)
		(end 43.554396 -293.510208)
		(width 0.16002)
		(layer "In6.Cu")
		(net "M_E_CPU1_SB_DQS_DP<1>")
	)
	(segment
		(start 57.74944 -293.821358)
		(end 59.661806 -293.821358)
		(width 0.16002)
		(layer "In6.Cu")
		(net "M_E_CPU1_SB_DQS_DP<1>")
	)
	(segment
		(start 66.72072 -286.2707)
		(end 67.039998 -285.951422)
		(width 0.16002)
		(layer "In6.Cu")
		(net "M_E_CPU1_SB_DQS_DP<1>")
	)
	(segment
		(start 46.826932 -294.618664)
		(end 47.085504 -294.360092)
		(width 0.16002)
		(layer "In6.Cu")
		(net "M_E_CPU1_SB_DQS_DP<1>")
	)
	(segment
		(start 61.89345 -291.589714)
		(end 61.89345 -290.521898)
		(width 0.16002)
		(layer "In6.Cu")
		(net "M_E_CPU1_SB_DQS_DP<1>")
	)
	(segment
		(start 55.330852 -294.111426)
		(end 56.09463 -294.875204)
		(width 0.16002)
		(layer "In6.Cu")
		(net "M_E_CPU1_SB_DQS_DP<1>")
	)
	(segment
		(start 69.503036 -283.488384)
		(end 69.822314 -283.169106)
		(width 0.16002)
		(layer "In6.Cu")
		(net "M_E_CPU1_SB_DQS_DP<1>")
	)
	(segment
		(start 76.03871 -280.839926)
		(end 76.27239 -280.839926)
		(width 0.09525)
		(layer "In6.Cu")
		(net "M_E_CPU1_SB_DQS_DP<1>")
	)
	(segment
		(start 31.863538 -294.745664)
		(end 32.24911 -294.360092)
		(width 0.16002)
		(layer "In6.Cu")
		(net "M_E_CPU1_SB_DQS_DP<1>")
	)
	(segment
		(start 71.213472 -281.201876)
		(end 71.634604 -280.780744)
		(width 0.16002)
		(layer "In6.Cu")
		(net "M_E_CPU1_SB_DQS_DP<1>")
	)
	(segment
		(start 78.44536 -280.83256)
		(end 78.44536 -280.832306)
		(width 0.09525)
		(layer "In6.Cu")
		(net "M_E_CPU1_SB_DQS_DP<1>")
	)
	(segment
		(start 47.085504 -294.360092)
		(end 48.123094 -294.360092)
		(width 0.16002)
		(layer "In6.Cu")
		(net "M_E_CPU1_SB_DQS_DP<1>")
	)
	(segment
		(start 67.535806 -284.879542)
		(end 68.111878 -284.879542)
		(width 0.16002)
		(layer "In6.Cu")
		(net "M_E_CPU1_SB_DQS_DP<1>")
	)
	(segment
		(start 39.679118 -294.360092)
		(end 40.73144 -294.360092)
		(width 0.16002)
		(layer "In6.Cu")
		(net "M_E_CPU1_SB_DQS_DP<1>")
	)
	(segment
		(start 68.926964 -283.488384)
		(end 69.503036 -283.488384)
		(width 0.16002)
		(layer "In6.Cu")
		(net "M_E_CPU1_SB_DQS_DP<1>")
	)
	(segment
		(start 35.908996 -293.510208)
		(end 37.705792 -293.510208)
		(width 0.16002)
		(layer "In6.Cu")
		(net "M_E_CPU1_SB_DQS_DP<1>")
	)
	(segment
		(start 33.576514 -294.360092)
		(end 33.885886 -294.669464)
		(width 0.16002)
		(layer "In6.Cu")
		(net "M_E_CPU1_SB_DQS_DP<1>")
	)
	(segment
		(start 56.695594 -294.875204)
		(end 57.74944 -293.821358)
		(width 0.16002)
		(layer "In6.Cu")
		(net "M_E_CPU1_SB_DQS_DP<1>")
	)
	(segment
		(start 33.885886 -294.669464)
		(end 34.263076 -294.669464)
		(width 0.16002)
		(layer "In6.Cu")
		(net "M_E_CPU1_SB_DQS_DP<1>")
	)
	(segment
		(start 35.063176 -293.869364)
		(end 35.54984 -293.869364)
		(width 0.16002)
		(layer "In6.Cu")
		(net "M_E_CPU1_SB_DQS_DP<1>")
	)
	(segment
		(start 81.27619 -280.858468)
		(end 81.377028 -280.831798)
		(width 0.09525)
		(layer "In6.Cu")
		(net "M_E_CPU1_SB_DQS_DP<1>")
	)
	(segment
		(start 71.213472 -281.777948)
		(end 71.213472 -281.201876)
		(width 0.16002)
		(layer "In6.Cu")
		(net "M_E_CPU1_SB_DQS_DP<1>")
	)
	(segment
		(start 40.73144 -294.360092)
		(end 41.091358 -294.72001)
		(width 0.16002)
		(layer "In6.Cu")
		(net "M_E_CPU1_SB_DQS_DP<1>")
	)
	(segment
		(start 38.08603 -293.890446)
		(end 38.08603 -294.38219)
		(width 0.16002)
		(layer "In6.Cu")
		(net "M_E_CPU1_SB_DQS_DP<1>")
	)
	(segment
		(start 52.386738 -293.510208)
		(end 53.516022 -294.639492)
		(width 0.16002)
		(layer "In6.Cu")
		(net "M_E_CPU1_SB_DQS_DP<1>")
	)
	(segment
		(start 78.153006 -280.540206)
		(end 78.44536 -280.83256)
		(width 0.09525)
		(layer "In6.Cu")
		(net "M_E_CPU1_SB_DQS_DP<1>")
	)
	(segment
		(start 35.54984 -293.869364)
		(end 35.908996 -293.510208)
		(width 0.16002)
		(layer "In6.Cu")
		(net "M_E_CPU1_SB_DQS_DP<1>")
	)
	(segment
		(start 65.64884 -286.766508)
		(end 66.144648 -286.2707)
		(width 0.16002)
		(layer "In6.Cu")
		(net "M_E_CPU1_SB_DQS_DP<1>")
	)
	(segment
		(start 67.039998 -285.37535)
		(end 67.535806 -284.879542)
		(width 0.16002)
		(layer "In6.Cu")
		(net "M_E_CPU1_SB_DQS_DP<1>")
	)
	(segment
		(start 75.979528 -280.780744)
		(end 76.03871 -280.839926)
		(width 0.09525)
		(layer "In6.Cu")
		(net "M_E_CPU1_SB_DQS_DP<1>")
	)
	(segment
		(start 79.83982 -280.891488)
		(end 79.850234 -280.885392)
		(width 0.09525)
		(layer "In6.Cu")
		(net "M_E_CPU1_SB_DQS_DP<1>")
	)
	(segment
		(start 80.771238 -280.896314)
		(end 80.77962 -280.891488)
		(width 0.09525)
		(layer "In6.Cu")
		(net "M_E_CPU1_SB_DQS_DP<1>")
	)
	(segment
		(start 78.52283 -280.891488)
		(end 78.534768 -280.898346)
		(width 0.09525)
		(layer "In6.Cu")
		(net "M_E_CPU1_SB_DQS_DP<1>")
	)
	(segment
		(start 50.19802 -293.910258)
		(end 50.59934 -293.910258)
		(width 0.16002)
		(layer "In6.Cu")
		(net "M_E_CPU1_SB_DQS_DP<1>")
	)
	(segment
		(start 32.24911 -294.360092)
		(end 33.576514 -294.360092)
		(width 0.16002)
		(layer "In6.Cu")
		(net "M_E_CPU1_SB_DQS_DP<1>")
	)
	(segment
		(start 75.955906 -280.780744)
		(end 75.979528 -280.780744)
		(width 0.09525)
		(layer "In6.Cu")
		(net "M_E_CPU1_SB_DQS_DP<1>")
	)
	(segment
		(start 50.99939 -293.510208)
		(end 52.386738 -293.510208)
		(width 0.16002)
		(layer "In6.Cu")
		(net "M_E_CPU1_SB_DQS_DP<1>")
	)
	(segment
		(start 37.705792 -293.510208)
		(end 38.08603 -293.890446)
		(width 0.16002)
		(layer "In6.Cu")
		(net "M_E_CPU1_SB_DQS_DP<1>")
	)
	(segment
		(start 50.59934 -293.910258)
		(end 50.99939 -293.510208)
		(width 0.16002)
		(layer "In6.Cu")
		(net "M_E_CPU1_SB_DQS_DP<1>")
	)
	(segment
		(start 39.420546 -294.618664)
		(end 39.679118 -294.360092)
		(width 0.16002)
		(layer "In6.Cu")
		(net "M_E_CPU1_SB_DQS_DP<1>")
	)
	(segment
		(start 81.377028 -280.831798)
		(end 81.530952 -280.566368)
		(width 0.09525)
		(layer "In6.Cu")
		(net "M_E_CPU1_SB_DQS_DP<1>")
	)
	(segment
		(start 31.419292 -294.745664)
		(end 31.863538 -294.745664)
		(width 0.16002)
		(layer "In6.Cu")
		(net "M_E_CPU1_SB_DQS_DP<1>")
	)
	(segment
		(start 67.039998 -285.951422)
		(end 67.039998 -285.37535)
		(width 0.16002)
		(layer "In6.Cu")
		(net "M_E_CPU1_SB_DQS_DP<1>")
	)
	(segment
		(start 38.08603 -294.38219)
		(end 38.322504 -294.618664)
		(width 0.16002)
		(layer "In6.Cu")
		(net "M_E_CPU1_SB_DQS_DP<1>")
	)
	(segment
		(start 43.554396 -293.510208)
		(end 44.707302 -293.510208)
		(width 0.16002)
		(layer "In6.Cu")
		(net "M_E_CPU1_SB_DQS_DP<1>")
	)
	(segment
		(start 56.09463 -294.875204)
		(end 56.695594 -294.875204)
		(width 0.16002)
		(layer "In6.Cu")
		(net "M_E_CPU1_SB_DQS_DP<1>")
	)
	(segment
		(start 38.322504 -294.618664)
		(end 39.420546 -294.618664)
		(width 0.16002)
		(layer "In6.Cu")
		(net "M_E_CPU1_SB_DQS_DP<1>")
	)
	(segment
		(start 70.318122 -282.097226)
		(end 70.894194 -282.097226)
		(width 0.16002)
		(layer "In6.Cu")
		(net "M_E_CPU1_SB_DQS_DP<1>")
	)
	(segment
		(start 78.44536 -280.832306)
		(end 78.445614 -280.832052)
		(width 0.09525)
		(layer "In6.Cu")
		(net "M_E_CPU1_SB_DQS_DP<1>")
	)
	(segment
		(start 61.89345 -290.521898)
		(end 64.75349 -287.661858)
		(width 0.16002)
		(layer "In6.Cu")
		(net "M_E_CPU1_SB_DQS_DP<1>")
	)
	(segment
		(start 41.760394 -294.72001)
		(end 42.61104 -293.869364)
		(width 0.16002)
		(layer "In6.Cu")
		(net "M_E_CPU1_SB_DQS_DP<1>")
	)
	(segment
		(start 68.431156 -283.984192)
		(end 68.926964 -283.488384)
		(width 0.16002)
		(layer "In6.Cu")
		(net "M_E_CPU1_SB_DQS_DP<1>")
	)
	(segment
		(start 64.75349 -287.661858)
		(end 65.329562 -287.661858)
		(width 0.16002)
		(layer "In6.Cu")
		(net "M_E_CPU1_SB_DQS_DP<1>")
	)
	(segment
		(start 69.822314 -282.593034)
		(end 70.318122 -282.097226)
		(width 0.16002)
		(layer "In6.Cu")
		(net "M_E_CPU1_SB_DQS_DP<1>")
	)
	(segment
		(start 76.57211 -280.540206)
		(end 78.153006 -280.540206)
		(width 0.09525)
		(layer "In6.Cu")
		(net "M_E_CPU1_SB_DQS_DP<1>")
	)
	(segment
		(start 54.434994 -294.111426)
		(end 55.330852 -294.111426)
		(width 0.16002)
		(layer "In6.Cu")
		(net "M_E_CPU1_SB_DQS_DP<1>")
	)
	(segment
		(start 53.516022 -294.639492)
		(end 53.906928 -294.639492)
		(width 0.16002)
		(layer "In6.Cu")
		(net "M_E_CPU1_SB_DQS_DP<1>")
	)
	(segment
		(start 71.634604 -280.780744)
		(end 75.955906 -280.780744)
		(width 0.16002)
		(layer "In6.Cu")
		(net "M_E_CPU1_SB_DQS_DP<1>")
	)
	(segment
		(start 65.329562 -287.661858)
		(end 65.64884 -287.34258)
		(width 0.16002)
		(layer "In6.Cu")
		(net "M_E_CPU1_SB_DQS_DP<1>")
	)
	(segment
		(start 45.815758 -294.618664)
		(end 46.826932 -294.618664)
		(width 0.16002)
		(layer "In6.Cu")
		(net "M_E_CPU1_SB_DQS_DP<1>")
	)
	(arc
		(start 79.850234 -280.885392)
		(mid 80.127142 -280.815715)
		(end 80.40243 -280.891488)
		(width 0.09525)
		(layer "In6.Cu")
		(net "M_E_CPU1_SB_DQS_DP<1>")
	)
	(arc
		(start 78.899766 -280.891488)
		(mid 79.175309 -280.815639)
		(end 79.45247 -280.885392)
		(width 0.09525)
		(layer "In6.Cu")
		(net "M_E_CPU1_SB_DQS_DP<1>")
	)
	(arc
		(start 80.77962 -280.891488)
		(mid 81.024046 -280.816845)
		(end 81.27619 -280.858468)
		(width 0.09525)
		(layer "In6.Cu")
		(net "M_E_CPU1_SB_DQS_DP<1>")
	)
	(arc
		(start 78.445614 -280.832052)
		(mid 78.482293 -280.864275)
		(end 78.52283 -280.891488)
		(width 0.09525)
		(layer "In6.Cu")
		(net "M_E_CPU1_SB_DQS_DP<1>")
	)
	(arc
		(start 80.40243 -280.891488)
		(mid 80.586205 -280.94226)
		(end 80.771238 -280.896314)
		(width 0.09525)
		(layer "In6.Cu")
		(net "M_E_CPU1_SB_DQS_DP<1>")
	)
	(arc
		(start 78.534768 -280.898346)
		(mid 78.718149 -280.942177)
		(end 78.899766 -280.891488)
		(width 0.09525)
		(layer "In6.Cu")
		(net "M_E_CPU1_SB_DQS_DP<1>")
	)
	(arc
		(start 79.462884 -280.891488)
		(mid 79.651352 -280.942165)
		(end 79.83982 -280.891488)
		(width 0.09525)
		(layer "In6.Cu")
		(net "M_E_CPU1_SB_DQS_DP<1>")
	)
	(segment
		(start 81.997804 -275.440394)
		(end 81.530952 -275.706332)
		(width 0.12954)
		(layer "F.Cu")
		(net "M_E_CPU1_SB_DQS_DP<0>")
	)
	(segment
		(start 76.187554 -275.216366)
		(end 77.229716 -275.216366)
		(width 0.09525)
		(layer "In6.Cu")
		(net "M_E_CPU1_SB_DQS_DP<0>")
	)
	(segment
		(start 68.288154 -276.245066)
		(end 68.448174 -276.085046)
		(width 0.16002)
		(layer "In6.Cu")
		(net "M_E_CPU1_SB_DQS_DP<0>")
	)
	(segment
		(start 64.957706 -278.867108)
		(end 64.70523 -278.614632)
		(width 0.16002)
		(layer "In6.Cu")
		(net "M_E_CPU1_SB_DQS_DP<0>")
	)
	(segment
		(start 66.348864 -277.47595)
		(end 66.096388 -277.223474)
		(width 0.16002)
		(layer "In6.Cu")
		(net "M_E_CPU1_SB_DQS_DP<0>")
	)
	(segment
		(start 49.35474 -285.322264)
		(end 50.11674 -284.560264)
		(width 0.16002)
		(layer "In6.Cu")
		(net "M_E_CPU1_SB_DQS_DP<0>")
	)
	(segment
		(start 29.252164 -284.885384)
		(end 29.525976 -285.159196)
		(width 0.16002)
		(layer "In6.Cu")
		(net "M_E_CPU1_SB_DQS_DP<0>")
	)
	(segment
		(start 43.489118 -284.160214)
		(end 44.831762 -284.160214)
		(width 0.16002)
		(layer "In6.Cu")
		(net "M_E_CPU1_SB_DQS_DP<0>")
	)
	(segment
		(start 33.877758 -285.322264)
		(end 34.29254 -285.322264)
		(width 0.16002)
		(layer "In6.Cu")
		(net "M_E_CPU1_SB_DQS_DP<0>")
	)
	(segment
		(start 50.11674 -284.560264)
		(end 50.59934 -284.560264)
		(width 0.16002)
		(layer "In6.Cu")
		(net "M_E_CPU1_SB_DQS_DP<0>")
	)
	(segment
		(start 30.563058 -285.010098)
		(end 33.565592 -285.010098)
		(width 0.16002)
		(layer "In6.Cu")
		(net "M_E_CPU1_SB_DQS_DP<0>")
	)
	(segment
		(start 33.565592 -285.010098)
		(end 33.877758 -285.322264)
		(width 0.16002)
		(layer "In6.Cu")
		(net "M_E_CPU1_SB_DQS_DP<0>")
	)
	(segment
		(start 55.41264 -285.715964)
		(end 56.50484 -285.715964)
		(width 0.16002)
		(layer "In6.Cu")
		(net "M_E_CPU1_SB_DQS_DP<0>")
	)
	(segment
		(start 52.360322 -284.160214)
		(end 53.306472 -285.106364)
		(width 0.16002)
		(layer "In6.Cu")
		(net "M_E_CPU1_SB_DQS_DP<0>")
	)
	(segment
		(start 62.2046 -280.991564)
		(end 63.257938 -279.938226)
		(width 0.16002)
		(layer "In6.Cu")
		(net "M_E_CPU1_SB_DQS_DP<0>")
	)
	(segment
		(start 48.653446 -285.010098)
		(end 48.965612 -285.322264)
		(width 0.16002)
		(layer "In6.Cu")
		(net "M_E_CPU1_SB_DQS_DP<0>")
	)
	(segment
		(start 77.229716 -275.216366)
		(end 78.09611 -276.08276)
		(width 0.09525)
		(layer "In6.Cu")
		(net "M_E_CPU1_SB_DQS_DP<0>")
	)
	(segment
		(start 63.746634 -279.096724)
		(end 64.223138 -279.096724)
		(width 0.16002)
		(layer "In6.Cu")
		(net "M_E_CPU1_SB_DQS_DP<0>")
	)
	(segment
		(start 44.831762 -284.160214)
		(end 45.681646 -285.010098)
		(width 0.16002)
		(layer "In6.Cu")
		(net "M_E_CPU1_SB_DQS_DP<0>")
	)
	(segment
		(start 81.27619 -275.998432)
		(end 81.377028 -275.971762)
		(width 0.09525)
		(layer "In6.Cu")
		(net "M_E_CPU1_SB_DQS_DP<0>")
	)
	(segment
		(start 67.767454 -276.085046)
		(end 67.927474 -276.245066)
		(width 0.16002)
		(layer "In6.Cu")
		(net "M_E_CPU1_SB_DQS_DP<0>")
	)
	(segment
		(start 66.44259 -275.659088)
		(end 66.944494 -275.157184)
		(width 0.16002)
		(layer "In6.Cu")
		(net "M_E_CPU1_SB_DQS_DP<0>")
	)
	(segment
		(start 45.681646 -285.010098)
		(end 48.653446 -285.010098)
		(width 0.16002)
		(layer "In6.Cu")
		(net "M_E_CPU1_SB_DQS_DP<0>")
	)
	(segment
		(start 38.087046 -285.010098)
		(end 41.109646 -285.010098)
		(width 0.16002)
		(layer "In6.Cu")
		(net "M_E_CPU1_SB_DQS_DP<0>")
	)
	(segment
		(start 29.525976 -285.159196)
		(end 30.41396 -285.159196)
		(width 0.16002)
		(layer "In6.Cu")
		(net "M_E_CPU1_SB_DQS_DP<0>")
	)
	(segment
		(start 50.59934 -284.560264)
		(end 50.99939 -284.160214)
		(width 0.16002)
		(layer "In6.Cu")
		(net "M_E_CPU1_SB_DQS_DP<0>")
	)
	(segment
		(start 43.089068 -284.560264)
		(end 43.489118 -284.160214)
		(width 0.16002)
		(layer "In6.Cu")
		(net "M_E_CPU1_SB_DQS_DP<0>")
	)
	(segment
		(start 64.475614 -279.3492)
		(end 64.701674 -279.3492)
		(width 0.16002)
		(layer "In6.Cu")
		(net "M_E_CPU1_SB_DQS_DP<0>")
	)
	(segment
		(start 66.092832 -277.958042)
		(end 66.348864 -277.70201)
		(width 0.16002)
		(layer "In6.Cu")
		(net "M_E_CPU1_SB_DQS_DP<0>")
	)
	(segment
		(start 50.99939 -284.160214)
		(end 52.360322 -284.160214)
		(width 0.16002)
		(layer "In6.Cu")
		(net "M_E_CPU1_SB_DQS_DP<0>")
	)
	(segment
		(start 64.223138 -279.096724)
		(end 64.475614 -279.3492)
		(width 0.16002)
		(layer "In6.Cu")
		(net "M_E_CPU1_SB_DQS_DP<0>")
	)
	(segment
		(start 42.581068 -284.560264)
		(end 43.089068 -284.560264)
		(width 0.16002)
		(layer "In6.Cu")
		(net "M_E_CPU1_SB_DQS_DP<0>")
	)
	(segment
		(start 35.152076 -284.462728)
		(end 35.592004 -284.462728)
		(width 0.16002)
		(layer "In6.Cu")
		(net "M_E_CPU1_SB_DQS_DP<0>")
	)
	(segment
		(start 64.957706 -279.093168)
		(end 64.957706 -278.867108)
		(width 0.16002)
		(layer "In6.Cu")
		(net "M_E_CPU1_SB_DQS_DP<0>")
	)
	(segment
		(start 67.430396 -275.157184)
		(end 67.767454 -275.494242)
		(width 0.16002)
		(layer "In6.Cu")
		(net "M_E_CPU1_SB_DQS_DP<0>")
	)
	(segment
		(start 56.50484 -285.715964)
		(end 57.74944 -284.471364)
		(width 0.16002)
		(layer "In6.Cu")
		(net "M_E_CPU1_SB_DQS_DP<0>")
	)
	(segment
		(start 62.2046 -282.195016)
		(end 62.2046 -280.991564)
		(width 0.16002)
		(layer "In6.Cu")
		(net "M_E_CPU1_SB_DQS_DP<0>")
	)
	(segment
		(start 68.448174 -275.494242)
		(end 68.785232 -275.157184)
		(width 0.16002)
		(layer "In6.Cu")
		(net "M_E_CPU1_SB_DQS_DP<0>")
	)
	(segment
		(start 68.785232 -275.157184)
		(end 76.10475 -275.157184)
		(width 0.16002)
		(layer "In6.Cu")
		(net "M_E_CPU1_SB_DQS_DP<0>")
	)
	(segment
		(start 66.096388 -277.223474)
		(end 66.096388 -276.74697)
		(width 0.16002)
		(layer "In6.Cu")
		(net "M_E_CPU1_SB_DQS_DP<0>")
	)
	(segment
		(start 66.944494 -275.157184)
		(end 67.430396 -275.157184)
		(width 0.16002)
		(layer "In6.Cu")
		(net "M_E_CPU1_SB_DQS_DP<0>")
	)
	(segment
		(start 80.771238 -276.036278)
		(end 80.77962 -276.031452)
		(width 0.09525)
		(layer "In6.Cu")
		(net "M_E_CPU1_SB_DQS_DP<0>")
	)
	(segment
		(start 67.767454 -275.494242)
		(end 67.767454 -276.085046)
		(width 0.16002)
		(layer "In6.Cu")
		(net "M_E_CPU1_SB_DQS_DP<0>")
	)
	(segment
		(start 65.866772 -277.958042)
		(end 66.092832 -277.958042)
		(width 0.16002)
		(layer "In6.Cu")
		(net "M_E_CPU1_SB_DQS_DP<0>")
	)
	(segment
		(start 76.128372 -275.157184)
		(end 76.187554 -275.216366)
		(width 0.09525)
		(layer "In6.Cu")
		(net "M_E_CPU1_SB_DQS_DP<0>")
	)
	(segment
		(start 54.80304 -285.106364)
		(end 55.41264 -285.715964)
		(width 0.16002)
		(layer "In6.Cu")
		(net "M_E_CPU1_SB_DQS_DP<0>")
	)
	(segment
		(start 64.70523 -278.614632)
		(end 64.70523 -278.138128)
		(width 0.16002)
		(layer "In6.Cu")
		(net "M_E_CPU1_SB_DQS_DP<0>")
	)
	(segment
		(start 63.257938 -279.938226)
		(end 63.257938 -279.58542)
		(width 0.16002)
		(layer "In6.Cu")
		(net "M_E_CPU1_SB_DQS_DP<0>")
	)
	(segment
		(start 65.614296 -277.705566)
		(end 65.866772 -277.958042)
		(width 0.16002)
		(layer "In6.Cu")
		(net "M_E_CPU1_SB_DQS_DP<0>")
	)
	(segment
		(start 30.41396 -285.159196)
		(end 30.563058 -285.010098)
		(width 0.16002)
		(layer "In6.Cu")
		(net "M_E_CPU1_SB_DQS_DP<0>")
	)
	(segment
		(start 35.894518 -284.160214)
		(end 37.237162 -284.160214)
		(width 0.16002)
		(layer "In6.Cu")
		(net "M_E_CPU1_SB_DQS_DP<0>")
	)
	(segment
		(start 63.257938 -279.58542)
		(end 63.746634 -279.096724)
		(width 0.16002)
		(layer "In6.Cu")
		(net "M_E_CPU1_SB_DQS_DP<0>")
	)
	(segment
		(start 41.109646 -285.010098)
		(end 41.447212 -285.347664)
		(width 0.16002)
		(layer "In6.Cu")
		(net "M_E_CPU1_SB_DQS_DP<0>")
	)
	(segment
		(start 67.927474 -276.245066)
		(end 68.288154 -276.245066)
		(width 0.16002)
		(layer "In6.Cu")
		(net "M_E_CPU1_SB_DQS_DP<0>")
	)
	(segment
		(start 79.83982 -276.031452)
		(end 79.850234 -276.025356)
		(width 0.09525)
		(layer "In6.Cu")
		(net "M_E_CPU1_SB_DQS_DP<0>")
	)
	(segment
		(start 66.348864 -277.70201)
		(end 66.348864 -277.47595)
		(width 0.16002)
		(layer "In6.Cu")
		(net "M_E_CPU1_SB_DQS_DP<0>")
	)
	(segment
		(start 81.377028 -275.971762)
		(end 81.530952 -275.706332)
		(width 0.09525)
		(layer "In6.Cu")
		(net "M_E_CPU1_SB_DQS_DP<0>")
	)
	(segment
		(start 65.137792 -277.705566)
		(end 65.614296 -277.705566)
		(width 0.16002)
		(layer "In6.Cu")
		(net "M_E_CPU1_SB_DQS_DP<0>")
	)
	(segment
		(start 57.74944 -284.471364)
		(end 59.028838 -284.471364)
		(width 0.16002)
		(layer "In6.Cu")
		(net "M_E_CPU1_SB_DQS_DP<0>")
	)
	(segment
		(start 53.306472 -285.106364)
		(end 54.80304 -285.106364)
		(width 0.16002)
		(layer "In6.Cu")
		(net "M_E_CPU1_SB_DQS_DP<0>")
	)
	(segment
		(start 34.29254 -285.322264)
		(end 35.152076 -284.462728)
		(width 0.16002)
		(layer "In6.Cu")
		(net "M_E_CPU1_SB_DQS_DP<0>")
	)
	(segment
		(start 37.237162 -284.160214)
		(end 38.087046 -285.010098)
		(width 0.16002)
		(layer "In6.Cu")
		(net "M_E_CPU1_SB_DQS_DP<0>")
	)
	(segment
		(start 41.447212 -285.347664)
		(end 41.793668 -285.347664)
		(width 0.16002)
		(layer "In6.Cu")
		(net "M_E_CPU1_SB_DQS_DP<0>")
	)
	(segment
		(start 78.09611 -276.08276)
		(end 79.651098 -276.08276)
		(width 0.09525)
		(layer "In6.Cu")
		(net "M_E_CPU1_SB_DQS_DP<0>")
	)
	(segment
		(start 35.592004 -284.462728)
		(end 35.894518 -284.160214)
		(width 0.16002)
		(layer "In6.Cu")
		(net "M_E_CPU1_SB_DQS_DP<0>")
	)
	(segment
		(start 64.701674 -279.3492)
		(end 64.957706 -279.093168)
		(width 0.16002)
		(layer "In6.Cu")
		(net "M_E_CPU1_SB_DQS_DP<0>")
	)
	(segment
		(start 66.44259 -276.400768)
		(end 66.44259 -275.659088)
		(width 0.16002)
		(layer "In6.Cu")
		(net "M_E_CPU1_SB_DQS_DP<0>")
	)
	(segment
		(start 76.10475 -275.157184)
		(end 76.128372 -275.157184)
		(width 0.09525)
		(layer "In6.Cu")
		(net "M_E_CPU1_SB_DQS_DP<0>")
	)
	(segment
		(start 66.096388 -276.74697)
		(end 66.44259 -276.400768)
		(width 0.16002)
		(layer "In6.Cu")
		(net "M_E_CPU1_SB_DQS_DP<0>")
	)
	(segment
		(start 59.028838 -284.471364)
		(end 60.564268 -283.835348)
		(width 0.16002)
		(layer "In6.Cu")
		(net "M_E_CPU1_SB_DQS_DP<0>")
	)
	(segment
		(start 64.70523 -278.138128)
		(end 65.137792 -277.705566)
		(width 0.16002)
		(layer "In6.Cu")
		(net "M_E_CPU1_SB_DQS_DP<0>")
	)
	(segment
		(start 41.793668 -285.347664)
		(end 42.581068 -284.560264)
		(width 0.16002)
		(layer "In6.Cu")
		(net "M_E_CPU1_SB_DQS_DP<0>")
	)
	(segment
		(start 48.965612 -285.322264)
		(end 49.35474 -285.322264)
		(width 0.16002)
		(layer "In6.Cu")
		(net "M_E_CPU1_SB_DQS_DP<0>")
	)
	(segment
		(start 68.448174 -276.085046)
		(end 68.448174 -275.494242)
		(width 0.16002)
		(layer "In6.Cu")
		(net "M_E_CPU1_SB_DQS_DP<0>")
	)
	(segment
		(start 60.564268 -283.835348)
		(end 62.2046 -282.195016)
		(width 0.16002)
		(layer "In6.Cu")
		(net "M_E_CPU1_SB_DQS_DP<0>")
	)
	(arc
		(start 80.40243 -276.031452)
		(mid 80.586205 -276.082224)
		(end 80.771238 -276.036278)
		(width 0.09525)
		(layer "In6.Cu")
		(net "M_E_CPU1_SB_DQS_DP<0>")
	)
	(arc
		(start 80.77962 -276.031452)
		(mid 81.013415 -275.957585)
		(end 81.256378 -275.990558)
		(width 0.09525)
		(layer "In6.Cu")
		(net "M_E_CPU1_SB_DQS_DP<0>")
	)
	(arc
		(start 79.850234 -276.025356)
		(mid 80.127142 -275.955679)
		(end 80.40243 -276.031452)
		(width 0.09525)
		(layer "In6.Cu")
		(net "M_E_CPU1_SB_DQS_DP<0>")
	)
	(arc
		(start 81.256378 -275.990558)
		(mid 81.266321 -275.994401)
		(end 81.27619 -275.998432)
		(width 0.09525)
		(layer "In6.Cu")
		(net "M_E_CPU1_SB_DQS_DP<0>")
	)
	(arc
		(start 79.651098 -276.08276)
		(mid 79.748844 -276.069565)
		(end 79.83982 -276.031452)
		(width 0.09525)
		(layer "In6.Cu")
		(net "M_E_CPU1_SB_DQS_DP<0>")
	)
	(segment
		(start 81.527904 -271.390364)
		(end 81.061052 -271.656302)
		(width 0.12954)
		(layer "F.Cu")
		(net "M_E_CPU1_SB_DQS_DN<9>")
	)
	(segment
		(start 31.087568 -275.608796)
		(end 31.087568 -275.282406)
		(width 0.16002)
		(layer "In6.Cu")
		(net "M_E_CPU1_SB_DQS_DN<9>")
	)
	(segment
		(start 45.38853 -275.945854)
		(end 46.09338 -275.945854)
		(width 0.16002)
		(layer "In6.Cu")
		(net "M_E_CPU1_SB_DQS_DN<9>")
	)
	(segment
		(start 64.089026 -269.835884)
		(end 75.955906 -269.835884)
		(width 0.16002)
		(layer "In6.Cu")
		(net "M_E_CPU1_SB_DQS_DN<9>")
	)
	(segment
		(start 39.422578 -275.09597)
		(end 40.272462 -275.945854)
		(width 0.16002)
		(layer "In6.Cu")
		(net "M_E_CPU1_SB_DQS_DN<9>")
	)
	(segment
		(start 57.068212 -276.305264)
		(end 57.906412 -275.467064)
		(width 0.16002)
		(layer "In6.Cu")
		(net "M_E_CPU1_SB_DQS_DN<9>")
	)
	(segment
		(start 76.06411 -269.776702)
		(end 76.232258 -269.776702)
		(width 0.09525)
		(layer "In6.Cu")
		(net "M_E_CPU1_SB_DQS_DN<9>")
	)
	(segment
		(start 55.056786 -275.02993)
		(end 55.254652 -274.832064)
		(width 0.16002)
		(layer "In6.Cu")
		(net "M_E_CPU1_SB_DQS_DN<9>")
	)
	(segment
		(start 50.769012 -275.492464)
		(end 51.165506 -275.09597)
		(width 0.16002)
		(layer "In6.Cu")
		(net "M_E_CPU1_SB_DQS_DN<9>")
	)
	(segment
		(start 29.252164 -276.385274)
		(end 29.525976 -276.111462)
		(width 0.16002)
		(layer "In6.Cu")
		(net "M_E_CPU1_SB_DQS_DN<9>")
	)
	(segment
		(start 54.672992 -276.305264)
		(end 55.056786 -275.92147)
		(width 0.16002)
		(layer "In6.Cu")
		(net "M_E_CPU1_SB_DQS_DN<9>")
	)
	(segment
		(start 75.981306 -269.835884)
		(end 76.004928 -269.835884)
		(width 0.09525)
		(layer "In6.Cu")
		(net "M_E_CPU1_SB_DQS_DN<9>")
	)
	(segment
		(start 60.93841 -272.9865)
		(end 64.089026 -269.835884)
		(width 0.16002)
		(layer "In6.Cu")
		(net "M_E_CPU1_SB_DQS_DN<9>")
	)
	(segment
		(start 60.142882 -274.324064)
		(end 60.93841 -273.528536)
		(width 0.16002)
		(layer "In6.Cu")
		(net "M_E_CPU1_SB_DQS_DN<9>")
	)
	(segment
		(start 46.09338 -275.945854)
		(end 46.21022 -276.062694)
		(width 0.16002)
		(layer "In6.Cu")
		(net "M_E_CPU1_SB_DQS_DN<9>")
	)
	(segment
		(start 58.746644 -275.467064)
		(end 59.130438 -275.08327)
		(width 0.16002)
		(layer "In6.Cu")
		(net "M_E_CPU1_SB_DQS_DN<9>")
	)
	(segment
		(start 59.130438 -275.08327)
		(end 59.130438 -274.52193)
		(width 0.16002)
		(layer "In6.Cu")
		(net "M_E_CPU1_SB_DQS_DN<9>")
	)
	(segment
		(start 81.214976 -271.390872)
		(end 81.061052 -271.656302)
		(width 0.09525)
		(layer "In6.Cu")
		(net "M_E_CPU1_SB_DQS_DN<9>")
	)
	(segment
		(start 38.676834 -275.773388)
		(end 38.676834 -275.25599)
		(width 0.16002)
		(layer "In6.Cu")
		(net "M_E_CPU1_SB_DQS_DN<9>")
	)
	(segment
		(start 33.399984 -275.945854)
		(end 33.835086 -276.380956)
		(width 0.16002)
		(layer "In6.Cu")
		(net "M_E_CPU1_SB_DQS_DN<9>")
	)
	(segment
		(start 76.004928 -269.835884)
		(end 76.06411 -269.776702)
		(width 0.09525)
		(layer "In6.Cu")
		(net "M_E_CPU1_SB_DQS_DN<9>")
	)
	(segment
		(start 37.728652 -276.110446)
		(end 38.339776 -276.110446)
		(width 0.16002)
		(layer "In6.Cu")
		(net "M_E_CPU1_SB_DQS_DN<9>")
	)
	(segment
		(start 46.21022 -276.062694)
		(end 46.69028 -276.062694)
		(width 0.16002)
		(layer "In6.Cu")
		(net "M_E_CPU1_SB_DQS_DN<9>")
	)
	(segment
		(start 38.836854 -275.09597)
		(end 39.422578 -275.09597)
		(width 0.16002)
		(layer "In6.Cu")
		(net "M_E_CPU1_SB_DQS_DN<9>")
	)
	(segment
		(start 31.247588 -275.122386)
		(end 31.608268 -275.122386)
		(width 0.16002)
		(layer "In6.Cu")
		(net "M_E_CPU1_SB_DQS_DN<9>")
	)
	(segment
		(start 44.538646 -275.09597)
		(end 45.38853 -275.945854)
		(width 0.16002)
		(layer "In6.Cu")
		(net "M_E_CPU1_SB_DQS_DN<9>")
	)
	(segment
		(start 41.323768 -276.292564)
		(end 41.942512 -276.292564)
		(width 0.16002)
		(layer "In6.Cu")
		(net "M_E_CPU1_SB_DQS_DN<9>")
	)
	(segment
		(start 76.232258 -269.776702)
		(end 76.78547 -270.329914)
		(width 0.09525)
		(layer "In6.Cu")
		(net "M_E_CPU1_SB_DQS_DN<9>")
	)
	(segment
		(start 38.339776 -276.110446)
		(end 38.676834 -275.773388)
		(width 0.16002)
		(layer "In6.Cu")
		(net "M_E_CPU1_SB_DQS_DN<9>")
	)
	(segment
		(start 38.676834 -275.25599)
		(end 38.836854 -275.09597)
		(width 0.16002)
		(layer "In6.Cu")
		(net "M_E_CPU1_SB_DQS_DN<9>")
	)
	(segment
		(start 42.768012 -275.467064)
		(end 43.250612 -275.467064)
		(width 0.16002)
		(layer "In6.Cu")
		(net "M_E_CPU1_SB_DQS_DN<9>")
	)
	(segment
		(start 55.056786 -275.92147)
		(end 55.056786 -275.02993)
		(width 0.16002)
		(layer "In6.Cu")
		(net "M_E_CPU1_SB_DQS_DN<9>")
	)
	(segment
		(start 30.584902 -276.111462)
		(end 31.087568 -275.608796)
		(width 0.16002)
		(layer "In6.Cu")
		(net "M_E_CPU1_SB_DQS_DN<9>")
	)
	(segment
		(start 55.254652 -274.832064)
		(end 55.53456 -274.832064)
		(width 0.16002)
		(layer "In6.Cu")
		(net "M_E_CPU1_SB_DQS_DN<9>")
	)
	(segment
		(start 79.956406 -271.31772)
		(end 79.95666 -271.318228)
		(width 0.09525)
		(layer "In6.Cu")
		(net "M_E_CPU1_SB_DQS_DN<9>")
	)
	(segment
		(start 52.621434 -275.09597)
		(end 53.830728 -276.305264)
		(width 0.16002)
		(layer "In6.Cu")
		(net "M_E_CPU1_SB_DQS_DN<9>")
	)
	(segment
		(start 37.391594 -275.25599)
		(end 37.391594 -275.773388)
		(width 0.16002)
		(layer "In6.Cu")
		(net "M_E_CPU1_SB_DQS_DN<9>")
	)
	(segment
		(start 77.41666 -270.329914)
		(end 78.420214 -271.333976)
		(width 0.09525)
		(layer "In6.Cu")
		(net "M_E_CPU1_SB_DQS_DN<9>")
	)
	(segment
		(start 81.191862 -271.304258)
		(end 81.214976 -271.390872)
		(width 0.09525)
		(layer "In6.Cu")
		(net "M_E_CPU1_SB_DQS_DN<9>")
	)
	(segment
		(start 60.93841 -273.528536)
		(end 60.93841 -272.9865)
		(width 0.16002)
		(layer "In6.Cu")
		(net "M_E_CPU1_SB_DQS_DN<9>")
	)
	(segment
		(start 55.732426 -275.02993)
		(end 55.732426 -275.92147)
		(width 0.16002)
		(layer "In6.Cu")
		(net "M_E_CPU1_SB_DQS_DN<9>")
	)
	(segment
		(start 57.906412 -275.467064)
		(end 58.746644 -275.467064)
		(width 0.16002)
		(layer "In6.Cu")
		(net "M_E_CPU1_SB_DQS_DN<9>")
	)
	(segment
		(start 59.328304 -274.324064)
		(end 60.142882 -274.324064)
		(width 0.16002)
		(layer "In6.Cu")
		(net "M_E_CPU1_SB_DQS_DN<9>")
	)
	(segment
		(start 51.165506 -275.09597)
		(end 52.621434 -275.09597)
		(width 0.16002)
		(layer "In6.Cu")
		(net "M_E_CPU1_SB_DQS_DN<9>")
	)
	(segment
		(start 35.275012 -275.441664)
		(end 35.732212 -275.441664)
		(width 0.16002)
		(layer "In6.Cu")
		(net "M_E_CPU1_SB_DQS_DN<9>")
	)
	(segment
		(start 35.732212 -275.441664)
		(end 36.077906 -275.09597)
		(width 0.16002)
		(layer "In6.Cu")
		(net "M_E_CPU1_SB_DQS_DN<9>")
	)
	(segment
		(start 32.105346 -275.945854)
		(end 33.399984 -275.945854)
		(width 0.16002)
		(layer "In6.Cu")
		(net "M_E_CPU1_SB_DQS_DN<9>")
	)
	(segment
		(start 31.768288 -275.282406)
		(end 31.768288 -275.608796)
		(width 0.16002)
		(layer "In6.Cu")
		(net "M_E_CPU1_SB_DQS_DN<9>")
	)
	(segment
		(start 43.621706 -275.09597)
		(end 44.538646 -275.09597)
		(width 0.16002)
		(layer "In6.Cu")
		(net "M_E_CPU1_SB_DQS_DN<9>")
	)
	(segment
		(start 46.80712 -275.945854)
		(end 48.495458 -275.945854)
		(width 0.16002)
		(layer "In6.Cu")
		(net "M_E_CPU1_SB_DQS_DN<9>")
	)
	(segment
		(start 34.33572 -276.380956)
		(end 35.275012 -275.441664)
		(width 0.16002)
		(layer "In6.Cu")
		(net "M_E_CPU1_SB_DQS_DN<9>")
	)
	(segment
		(start 40.977058 -275.945854)
		(end 41.323768 -276.292564)
		(width 0.16002)
		(layer "In6.Cu")
		(net "M_E_CPU1_SB_DQS_DN<9>")
	)
	(segment
		(start 48.495458 -275.945854)
		(end 48.842168 -276.292564)
		(width 0.16002)
		(layer "In6.Cu")
		(net "M_E_CPU1_SB_DQS_DN<9>")
	)
	(segment
		(start 31.608268 -275.122386)
		(end 31.768288 -275.282406)
		(width 0.16002)
		(layer "In6.Cu")
		(net "M_E_CPU1_SB_DQS_DN<9>")
	)
	(segment
		(start 76.78547 -270.329914)
		(end 77.41666 -270.329914)
		(width 0.09525)
		(layer "In6.Cu")
		(net "M_E_CPU1_SB_DQS_DN<9>")
	)
	(segment
		(start 50.311812 -275.492464)
		(end 50.769012 -275.492464)
		(width 0.16002)
		(layer "In6.Cu")
		(net "M_E_CPU1_SB_DQS_DN<9>")
	)
	(segment
		(start 37.391594 -275.773388)
		(end 37.728652 -276.110446)
		(width 0.16002)
		(layer "In6.Cu")
		(net "M_E_CPU1_SB_DQS_DN<9>")
	)
	(segment
		(start 46.69028 -276.062694)
		(end 46.80712 -275.945854)
		(width 0.16002)
		(layer "In6.Cu")
		(net "M_E_CPU1_SB_DQS_DN<9>")
	)
	(segment
		(start 31.087568 -275.282406)
		(end 31.247588 -275.122386)
		(width 0.16002)
		(layer "In6.Cu")
		(net "M_E_CPU1_SB_DQS_DN<9>")
	)
	(segment
		(start 40.272462 -275.945854)
		(end 40.977058 -275.945854)
		(width 0.16002)
		(layer "In6.Cu")
		(net "M_E_CPU1_SB_DQS_DN<9>")
	)
	(segment
		(start 37.231574 -275.09597)
		(end 37.391594 -275.25599)
		(width 0.16002)
		(layer "In6.Cu")
		(net "M_E_CPU1_SB_DQS_DN<9>")
	)
	(segment
		(start 75.955906 -269.835884)
		(end 75.981306 -269.835884)
		(width 0.1016)
		(layer "In6.Cu")
		(net "M_E_CPU1_SB_DQS_DN<9>")
	)
	(segment
		(start 36.077906 -275.09597)
		(end 37.231574 -275.09597)
		(width 0.16002)
		(layer "In6.Cu")
		(net "M_E_CPU1_SB_DQS_DN<9>")
	)
	(segment
		(start 53.830728 -276.305264)
		(end 54.672992 -276.305264)
		(width 0.16002)
		(layer "In6.Cu")
		(net "M_E_CPU1_SB_DQS_DN<9>")
	)
	(segment
		(start 31.768288 -275.608796)
		(end 32.105346 -275.945854)
		(width 0.16002)
		(layer "In6.Cu")
		(net "M_E_CPU1_SB_DQS_DN<9>")
	)
	(segment
		(start 55.732426 -275.92147)
		(end 56.11622 -276.305264)
		(width 0.16002)
		(layer "In6.Cu")
		(net "M_E_CPU1_SB_DQS_DN<9>")
	)
	(segment
		(start 55.53456 -274.832064)
		(end 55.732426 -275.02993)
		(width 0.16002)
		(layer "In6.Cu")
		(net "M_E_CPU1_SB_DQS_DN<9>")
	)
	(segment
		(start 59.130438 -274.52193)
		(end 59.328304 -274.324064)
		(width 0.16002)
		(layer "In6.Cu")
		(net "M_E_CPU1_SB_DQS_DN<9>")
	)
	(segment
		(start 43.250612 -275.467064)
		(end 43.621706 -275.09597)
		(width 0.16002)
		(layer "In6.Cu")
		(net "M_E_CPU1_SB_DQS_DN<9>")
	)
	(segment
		(start 33.835086 -276.380956)
		(end 34.33572 -276.380956)
		(width 0.16002)
		(layer "In6.Cu")
		(net "M_E_CPU1_SB_DQS_DN<9>")
	)
	(segment
		(start 56.11622 -276.305264)
		(end 57.068212 -276.305264)
		(width 0.16002)
		(layer "In6.Cu")
		(net "M_E_CPU1_SB_DQS_DN<9>")
	)
	(segment
		(start 49.511712 -276.292564)
		(end 50.311812 -275.492464)
		(width 0.16002)
		(layer "In6.Cu")
		(net "M_E_CPU1_SB_DQS_DN<9>")
	)
	(segment
		(start 41.942512 -276.292564)
		(end 42.768012 -275.467064)
		(width 0.16002)
		(layer "In6.Cu")
		(net "M_E_CPU1_SB_DQS_DN<9>")
	)
	(segment
		(start 29.525976 -276.111462)
		(end 30.584902 -276.111462)
		(width 0.16002)
		(layer "In6.Cu")
		(net "M_E_CPU1_SB_DQS_DN<9>")
	)
	(segment
		(start 48.842168 -276.292564)
		(end 49.511712 -276.292564)
		(width 0.16002)
		(layer "In6.Cu")
		(net "M_E_CPU1_SB_DQS_DN<9>")
	)
	(arc
		(start 78.607158 -271.428464)
		(mid 79.221953 -271.452336)
		(end 79.830676 -271.362932)
		(width 0.09525)
		(layer "In6.Cu")
		(net "M_E_CPU1_SB_DQS_DN<9>")
	)
	(arc
		(start 79.95666 -271.318228)
		(mid 80.134803 -271.280655)
		(end 80.30972 -271.331182)
		(width 0.09525)
		(layer "In6.Cu")
		(net "M_E_CPU1_SB_DQS_DN<9>")
	)
	(arc
		(start 79.830676 -271.362932)
		(mid 79.894742 -271.343664)
		(end 79.956406 -271.31772)
		(width 0.09525)
		(layer "In6.Cu")
		(net "M_E_CPU1_SB_DQS_DN<9>")
	)
	(arc
		(start 78.420214 -271.333976)
		(mid 78.50603 -271.39638)
		(end 78.607158 -271.428464)
		(width 0.09525)
		(layer "In6.Cu")
		(net "M_E_CPU1_SB_DQS_DN<9>")
	)
	(arc
		(start 80.30972 -271.331182)
		(mid 80.591152 -271.406937)
		(end 80.872584 -271.331182)
		(width 0.09525)
		(layer "In6.Cu")
		(net "M_E_CPU1_SB_DQS_DN<9>")
	)
	(arc
		(start 80.872584 -271.331182)
		(mid 81.029211 -271.281996)
		(end 81.191862 -271.304258)
		(width 0.09525)
		(layer "In6.Cu")
		(net "M_E_CPU1_SB_DQS_DN<9>")
	)
	(segment
		(start 83.408012 -290.830254)
		(end 82.940906 -291.096192)
		(width 0.12954)
		(layer "F.Cu")
		(net "M_E_CPU1_SB_DQS_DN<8>")
	)
	(segment
		(start 82.686144 -291.388292)
		(end 82.786982 -291.361622)
		(width 0.09525)
		(layer "In6.Cu")
		(net "M_E_CPU1_SB_DQS_DN<8>")
	)
	(segment
		(start 64.05499 -309.323486)
		(end 64.05499 -307.962046)
		(width 0.16002)
		(layer "In6.Cu")
		(net "M_E_CPU1_SB_DQS_DN<8>")
	)
	(segment
		(start 66.65087 -305.366166)
		(end 66.65087 -304.965608)
		(width 0.16002)
		(layer "In6.Cu")
		(net "M_E_CPU1_SB_DQS_DN<8>")
	)
	(segment
		(start 77.688186 -293.48049)
		(end 79.696056 -291.47262)
		(width 0.09525)
		(layer "In6.Cu")
		(net "M_E_CPU1_SB_DQS_DN<8>")
	)
	(segment
		(start 51.285394 -313.880246)
		(end 52.051712 -314.646564)
		(width 0.16002)
		(layer "In6.Cu")
		(net "M_E_CPU1_SB_DQS_DN<8>")
	)
	(segment
		(start 32.902144 -315.058298)
		(end 34.187384 -314.525914)
		(width 0.16002)
		(layer "In6.Cu")
		(net "M_E_CPU1_SB_DQS_DN<8>")
	)
	(segment
		(start 64.05499 -307.962046)
		(end 66.65087 -305.366166)
		(width 0.16002)
		(layer "In6.Cu")
		(net "M_E_CPU1_SB_DQS_DN<8>")
	)
	(segment
		(start 82.181192 -291.426138)
		(end 82.189574 -291.421312)
		(width 0.09525)
		(layer "In6.Cu")
		(net "M_E_CPU1_SB_DQS_DN<8>")
	)
	(segment
		(start 29.038296 -314.236862)
		(end 31.258764 -314.678314)
		(width 0.16002)
		(layer "In6.Cu")
		(net "M_E_CPU1_SB_DQS_DN<8>")
	)
	(segment
		(start 47.62373 -315.058298)
		(end 47.97298 -315.058298)
		(width 0.16002)
		(layer "In6.Cu")
		(net "M_E_CPU1_SB_DQS_DN<8>")
	)
	(segment
		(start 56.88584 -314.646564)
		(end 57.66054 -313.871864)
		(width 0.16002)
		(layer "In6.Cu")
		(net "M_E_CPU1_SB_DQS_DN<8>")
	)
	(segment
		(start 35.018218 -313.971178)
		(end 35.303968 -313.884564)
		(width 0.16002)
		(layer "In6.Cu")
		(net "M_E_CPU1_SB_DQS_DN<8>")
	)
	(segment
		(start 49.291748 -314.511182)
		(end 50.23612 -313.880246)
		(width 0.16002)
		(layer "In6.Cu")
		(net "M_E_CPU1_SB_DQS_DN<8>")
	)
	(segment
		(start 27.851354 -313.859418)
		(end 28.411932 -313.942476)
		(width 0.16002)
		(layer "In6.Cu")
		(net "M_E_CPU1_SB_DQS_DN<8>")
	)
	(segment
		(start 45.692568 -314.67425)
		(end 47.62373 -315.058298)
		(width 0.16002)
		(layer "In6.Cu")
		(net "M_E_CPU1_SB_DQS_DN<8>")
	)
	(segment
		(start 25.904444 -314.059316)
		(end 27.851354 -313.859418)
		(width 0.16002)
		(layer "In6.Cu")
		(net "M_E_CPU1_SB_DQS_DN<8>")
	)
	(segment
		(start 38.55593 -314.836556)
		(end 39.671498 -315.058298)
		(width 0.16002)
		(layer "In6.Cu")
		(net "M_E_CPU1_SB_DQS_DN<8>")
	)
	(segment
		(start 77.019658 -294.59682)
		(end 77.102716 -294.59682)
		(width 0.09525)
		(layer "In6.Cu")
		(net "M_E_CPU1_SB_DQS_DN<8>")
	)
	(segment
		(start 25.426162 -314.059316)
		(end 25.904444 -314.059316)
		(width 0.16002)
		(layer "In6.Cu")
		(net "M_E_CPU1_SB_DQS_DN<8>")
	)
	(segment
		(start 40.580564 -315.058298)
		(end 42.84599 -313.859164)
		(width 0.16002)
		(layer "In6.Cu")
		(net "M_E_CPU1_SB_DQS_DN<8>")
	)
	(segment
		(start 77.102716 -294.59682)
		(end 77.688186 -294.01135)
		(width 0.09525)
		(layer "In6.Cu")
		(net "M_E_CPU1_SB_DQS_DN<8>")
	)
	(segment
		(start 79.696056 -291.47262)
		(end 80.120998 -291.47262)
		(width 0.09525)
		(layer "In6.Cu")
		(net "M_E_CPU1_SB_DQS_DN<8>")
	)
	(segment
		(start 57.66054 -313.871864)
		(end 59.506612 -313.871864)
		(width 0.16002)
		(layer "In6.Cu")
		(net "M_E_CPU1_SB_DQS_DN<8>")
	)
	(segment
		(start 42.84599 -313.859164)
		(end 43.141646 -313.859164)
		(width 0.16002)
		(layer "In6.Cu")
		(net "M_E_CPU1_SB_DQS_DN<8>")
	)
	(segment
		(start 50.23612 -313.880246)
		(end 51.285394 -313.880246)
		(width 0.16002)
		(layer "In6.Cu")
		(net "M_E_CPU1_SB_DQS_DN<8>")
	)
	(segment
		(start 82.786982 -291.361622)
		(end 82.940906 -291.096192)
		(width 0.09525)
		(layer "In6.Cu")
		(net "M_E_CPU1_SB_DQS_DN<8>")
	)
	(segment
		(start 59.506612 -313.871864)
		(end 64.05499 -309.323486)
		(width 0.16002)
		(layer "In6.Cu")
		(net "M_E_CPU1_SB_DQS_DN<8>")
	)
	(segment
		(start 66.65087 -304.965608)
		(end 77.002894 -294.613584)
		(width 0.16002)
		(layer "In6.Cu")
		(net "M_E_CPU1_SB_DQS_DN<8>")
	)
	(segment
		(start 28.411932 -313.942476)
		(end 29.038296 -314.236862)
		(width 0.16002)
		(layer "In6.Cu")
		(net "M_E_CPU1_SB_DQS_DN<8>")
	)
	(segment
		(start 52.051712 -314.646564)
		(end 56.88584 -314.646564)
		(width 0.16002)
		(layer "In6.Cu")
		(net "M_E_CPU1_SB_DQS_DN<8>")
	)
	(segment
		(start 39.671498 -315.058298)
		(end 40.580564 -315.058298)
		(width 0.16002)
		(layer "In6.Cu")
		(net "M_E_CPU1_SB_DQS_DN<8>")
	)
	(segment
		(start 77.002894 -294.613584)
		(end 77.019658 -294.59682)
		(width 0.09525)
		(layer "In6.Cu")
		(net "M_E_CPU1_SB_DQS_DN<8>")
	)
	(segment
		(start 43.141646 -313.859164)
		(end 45.692568 -314.67425)
		(width 0.16002)
		(layer "In6.Cu")
		(net "M_E_CPU1_SB_DQS_DN<8>")
	)
	(segment
		(start 25.152096 -313.78525)
		(end 25.426162 -314.059316)
		(width 0.16002)
		(layer "In6.Cu")
		(net "M_E_CPU1_SB_DQS_DN<8>")
	)
	(segment
		(start 77.688186 -294.01135)
		(end 77.688186 -293.48049)
		(width 0.09525)
		(layer "In6.Cu")
		(net "M_E_CPU1_SB_DQS_DN<8>")
	)
	(segment
		(start 35.303968 -313.884564)
		(end 35.55111 -313.884564)
		(width 0.16002)
		(layer "In6.Cu")
		(net "M_E_CPU1_SB_DQS_DN<8>")
	)
	(segment
		(start 31.258764 -314.678314)
		(end 32.511238 -315.058298)
		(width 0.16002)
		(layer "In6.Cu")
		(net "M_E_CPU1_SB_DQS_DN<8>")
	)
	(segment
		(start 35.55111 -313.884564)
		(end 38.55593 -314.836556)
		(width 0.16002)
		(layer "In6.Cu")
		(net "M_E_CPU1_SB_DQS_DN<8>")
	)
	(segment
		(start 47.97298 -315.058298)
		(end 49.291748 -314.511182)
		(width 0.16002)
		(layer "In6.Cu")
		(net "M_E_CPU1_SB_DQS_DN<8>")
	)
	(segment
		(start 32.511238 -315.058298)
		(end 32.902144 -315.058298)
		(width 0.16002)
		(layer "In6.Cu")
		(net "M_E_CPU1_SB_DQS_DN<8>")
	)
	(segment
		(start 34.187384 -314.525914)
		(end 35.018218 -313.971178)
		(width 0.16002)
		(layer "In6.Cu")
		(net "M_E_CPU1_SB_DQS_DN<8>")
	)
	(arc
		(start 81.24952 -291.421312)
		(mid 81.530952 -291.345557)
		(end 81.812384 -291.421312)
		(width 0.09525)
		(layer "In6.Cu")
		(net "M_E_CPU1_SB_DQS_DN<8>")
	)
	(arc
		(start 81.812384 -291.421312)
		(mid 81.996159 -291.472084)
		(end 82.181192 -291.426138)
		(width 0.09525)
		(layer "In6.Cu")
		(net "M_E_CPU1_SB_DQS_DN<8>")
	)
	(arc
		(start 80.30972 -291.421312)
		(mid 80.591152 -291.345557)
		(end 80.872584 -291.421312)
		(width 0.09525)
		(layer "In6.Cu")
		(net "M_E_CPU1_SB_DQS_DN<8>")
	)
	(arc
		(start 80.872584 -291.421312)
		(mid 81.061052 -291.471989)
		(end 81.24952 -291.421312)
		(width 0.09525)
		(layer "In6.Cu")
		(net "M_E_CPU1_SB_DQS_DN<8>")
	)
	(arc
		(start 80.120998 -291.47262)
		(mid 80.218744 -291.459425)
		(end 80.30972 -291.421312)
		(width 0.09525)
		(layer "In6.Cu")
		(net "M_E_CPU1_SB_DQS_DN<8>")
	)
	(arc
		(start 82.189574 -291.421312)
		(mid 82.434 -291.346669)
		(end 82.686144 -291.388292)
		(width 0.09525)
		(layer "In6.Cu")
		(net "M_E_CPU1_SB_DQS_DN<8>")
	)
	(segment
		(start 83.408012 -285.970472)
		(end 82.940906 -286.23641)
		(width 0.12954)
		(layer "F.Cu")
		(net "M_E_CPU1_SB_DQS_DN<7>")
	)
	(segment
		(start 76.34351 -287.280604)
		(end 76.360274 -287.26384)
		(width 0.09525)
		(layer "In6.Cu")
		(net "M_E_CPU1_SB_DQS_DN<7>")
	)
	(segment
		(start 72.355456 -290.339526)
		(end 72.95515 -290.091114)
		(width 0.16002)
		(layer "In6.Cu")
		(net "M_E_CPU1_SB_DQS_DN<7>")
	)
	(segment
		(start 78.688692 -286.485838)
		(end 78.711044 -286.485838)
		(width 0.09525)
		(layer "In6.Cu")
		(net "M_E_CPU1_SB_DQS_DN<7>")
	)
	(segment
		(start 32.510222 -305.708304)
		(end 32.877506 -305.708304)
		(width 0.16002)
		(layer "In6.Cu")
		(net "M_E_CPU1_SB_DQS_DN<7>")
	)
	(segment
		(start 54.021228 -305.299364)
		(end 55.339996 -305.299364)
		(width 0.16002)
		(layer "In6.Cu")
		(net "M_E_CPU1_SB_DQS_DN<7>")
	)
	(segment
		(start 50.25009 -304.530252)
		(end 50.91303 -304.530252)
		(width 0.16002)
		(layer "In6.Cu")
		(net "M_E_CPU1_SB_DQS_DN<7>")
	)
	(segment
		(start 49.943512 -304.757836)
		(end 50.25009 -304.530252)
		(width 0.16002)
		(layer "In6.Cu")
		(net "M_E_CPU1_SB_DQS_DN<7>")
	)
	(segment
		(start 27.05735 -304.499264)
		(end 28.163266 -304.499264)
		(width 0.16002)
		(layer "In6.Cu")
		(net "M_E_CPU1_SB_DQS_DN<7>")
	)
	(segment
		(start 35.731958 -304.524664)
		(end 36.537392 -304.858166)
		(width 0.16002)
		(layer "In6.Cu")
		(net "M_E_CPU1_SB_DQS_DN<7>")
	)
	(segment
		(start 35.186874 -304.524664)
		(end 35.731958 -304.524664)
		(width 0.16002)
		(layer "In6.Cu")
		(net "M_E_CPU1_SB_DQS_DN<7>")
	)
	(segment
		(start 78.0415 -286.906716)
		(end 78.302358 -286.645858)
		(width 0.09525)
		(layer "In6.Cu")
		(net "M_E_CPU1_SB_DQS_DN<7>")
	)
	(segment
		(start 48.165004 -305.708304)
		(end 49.943512 -304.757836)
		(width 0.16002)
		(layer "In6.Cu")
		(net "M_E_CPU1_SB_DQS_DN<7>")
	)
	(segment
		(start 45.383704 -304.858166)
		(end 47.436532 -305.708304)
		(width 0.16002)
		(layer "In6.Cu")
		(net "M_E_CPU1_SB_DQS_DN<7>")
	)
	(segment
		(start 57.23636 -304.922174)
		(end 57.8231 -304.530252)
		(width 0.16002)
		(layer "In6.Cu")
		(net "M_E_CPU1_SB_DQS_DN<7>")
	)
	(segment
		(start 34.292032 -305.122326)
		(end 35.186874 -304.524664)
		(width 0.16002)
		(layer "In6.Cu")
		(net "M_E_CPU1_SB_DQS_DN<7>")
	)
	(segment
		(start 72.95515 -290.091114)
		(end 72.955404 -290.09086)
		(width 0.16002)
		(layer "In6.Cu")
		(net "M_E_CPU1_SB_DQS_DN<7>")
	)
	(segment
		(start 28.897072 -304.803048)
		(end 32.510222 -305.708304)
		(width 0.16002)
		(layer "In6.Cu")
		(net "M_E_CPU1_SB_DQS_DN<7>")
	)
	(segment
		(start 59.875674 -303.972468)
		(end 61.477906 -302.370236)
		(width 0.16002)
		(layer "In6.Cu")
		(net "M_E_CPU1_SB_DQS_DN<7>")
	)
	(segment
		(start 79.93253 -286.56153)
		(end 79.940912 -286.566356)
		(width 0.09525)
		(layer "In6.Cu")
		(net "M_E_CPU1_SB_DQS_DN<7>")
	)
	(segment
		(start 61.477906 -302.370236)
		(end 62.2935 -300.401482)
		(width 0.16002)
		(layer "In6.Cu")
		(net "M_E_CPU1_SB_DQS_DN<7>")
	)
	(segment
		(start 43.987974 -304.858166)
		(end 45.383704 -304.858166)
		(width 0.16002)
		(layer "In6.Cu")
		(net "M_E_CPU1_SB_DQS_DN<7>")
	)
	(segment
		(start 25.152096 -304.435256)
		(end 25.426162 -304.709322)
		(width 0.16002)
		(layer "In6.Cu")
		(net "M_E_CPU1_SB_DQS_DN<7>")
	)
	(segment
		(start 32.877506 -305.708304)
		(end 34.292032 -305.122326)
		(width 0.16002)
		(layer "In6.Cu")
		(net "M_E_CPU1_SB_DQS_DN<7>")
	)
	(segment
		(start 55.339996 -305.299364)
		(end 57.23636 -304.922174)
		(width 0.16002)
		(layer "In6.Cu")
		(net "M_E_CPU1_SB_DQS_DN<7>")
	)
	(segment
		(start 76.800964 -286.906716)
		(end 78.0415 -286.906716)
		(width 0.09525)
		(layer "In6.Cu")
		(net "M_E_CPU1_SB_DQS_DN<7>")
	)
	(segment
		(start 62.2935 -300.401482)
		(end 72.355456 -290.339526)
		(width 0.16002)
		(layer "In6.Cu")
		(net "M_E_CPU1_SB_DQS_DN<7>")
	)
	(segment
		(start 76.44384 -287.26384)
		(end 76.800964 -286.906716)
		(width 0.09525)
		(layer "In6.Cu")
		(net "M_E_CPU1_SB_DQS_DN<7>")
	)
	(segment
		(start 43.134788 -304.504852)
		(end 43.987974 -304.858166)
		(width 0.16002)
		(layer "In6.Cu")
		(net "M_E_CPU1_SB_DQS_DN<7>")
	)
	(segment
		(start 57.8231 -304.530252)
		(end 58.52922 -304.530252)
		(width 0.16002)
		(layer "In6.Cu")
		(net "M_E_CPU1_SB_DQS_DN<7>")
	)
	(segment
		(start 76.116688 -287.507426)
		(end 76.34351 -287.280604)
		(width 0.16002)
		(layer "In6.Cu")
		(net "M_E_CPU1_SB_DQS_DN<7>")
	)
	(segment
		(start 36.537392 -304.858166)
		(end 37.919914 -304.858166)
		(width 0.16002)
		(layer "In6.Cu")
		(net "M_E_CPU1_SB_DQS_DN<7>")
	)
	(segment
		(start 47.436532 -305.708304)
		(end 48.165004 -305.708304)
		(width 0.16002)
		(layer "In6.Cu")
		(net "M_E_CPU1_SB_DQS_DN<7>")
	)
	(segment
		(start 58.52922 -304.530252)
		(end 59.875674 -303.972468)
		(width 0.16002)
		(layer "In6.Cu")
		(net "M_E_CPU1_SB_DQS_DN<7>")
	)
	(segment
		(start 75.82535 -287.507426)
		(end 76.116688 -287.507426)
		(width 0.16002)
		(layer "In6.Cu")
		(net "M_E_CPU1_SB_DQS_DN<7>")
	)
	(segment
		(start 51.704748 -304.858166)
		(end 52.956206 -304.858166)
		(width 0.16002)
		(layer "In6.Cu")
		(net "M_E_CPU1_SB_DQS_DN<7>")
	)
	(segment
		(start 42.118788 -304.933096)
		(end 42.759884 -304.504852)
		(width 0.16002)
		(layer "In6.Cu")
		(net "M_E_CPU1_SB_DQS_DN<7>")
	)
	(segment
		(start 37.919914 -304.858166)
		(end 39.972742 -305.708304)
		(width 0.16002)
		(layer "In6.Cu")
		(net "M_E_CPU1_SB_DQS_DN<7>")
	)
	(segment
		(start 82.181192 -286.566356)
		(end 82.189574 -286.56153)
		(width 0.09525)
		(layer "In6.Cu")
		(net "M_E_CPU1_SB_DQS_DN<7>")
	)
	(segment
		(start 28.163266 -304.499264)
		(end 28.897072 -304.803048)
		(width 0.16002)
		(layer "In6.Cu")
		(net "M_E_CPU1_SB_DQS_DN<7>")
	)
	(segment
		(start 82.686144 -286.52851)
		(end 82.786982 -286.50184)
		(width 0.09525)
		(layer "In6.Cu")
		(net "M_E_CPU1_SB_DQS_DN<7>")
	)
	(segment
		(start 50.91303 -304.530252)
		(end 51.704748 -304.858166)
		(width 0.16002)
		(layer "In6.Cu")
		(net "M_E_CPU1_SB_DQS_DN<7>")
	)
	(segment
		(start 76.360274 -287.26384)
		(end 76.44384 -287.26384)
		(width 0.09525)
		(layer "In6.Cu")
		(net "M_E_CPU1_SB_DQS_DN<7>")
	)
	(segment
		(start 26.000964 -304.709322)
		(end 27.05735 -304.499264)
		(width 0.16002)
		(layer "In6.Cu")
		(net "M_E_CPU1_SB_DQS_DN<7>")
	)
	(segment
		(start 73.444354 -289.888422)
		(end 75.82535 -287.507426)
		(width 0.16002)
		(layer "In6.Cu")
		(net "M_E_CPU1_SB_DQS_DN<7>")
	)
	(segment
		(start 39.972742 -305.708304)
		(end 40.509952 -305.708304)
		(width 0.16002)
		(layer "In6.Cu")
		(net "M_E_CPU1_SB_DQS_DN<7>")
	)
	(segment
		(start 78.992476 -286.56153)
		(end 79.000858 -286.566356)
		(width 0.09525)
		(layer "In6.Cu")
		(net "M_E_CPU1_SB_DQS_DN<7>")
	)
	(segment
		(start 72.955404 -290.09086)
		(end 73.444354 -289.888422)
		(width 0.16002)
		(layer "In6.Cu")
		(net "M_E_CPU1_SB_DQS_DN<7>")
	)
	(segment
		(start 82.786982 -286.50184)
		(end 82.940906 -286.23641)
		(width 0.09525)
		(layer "In6.Cu")
		(net "M_E_CPU1_SB_DQS_DN<7>")
	)
	(segment
		(start 52.956206 -304.858166)
		(end 54.021228 -305.299364)
		(width 0.16002)
		(layer "In6.Cu")
		(net "M_E_CPU1_SB_DQS_DN<7>")
	)
	(segment
		(start 40.509952 -305.708304)
		(end 42.118788 -304.933096)
		(width 0.16002)
		(layer "In6.Cu")
		(net "M_E_CPU1_SB_DQS_DN<7>")
	)
	(segment
		(start 25.426162 -304.709322)
		(end 26.000964 -304.709322)
		(width 0.16002)
		(layer "In6.Cu")
		(net "M_E_CPU1_SB_DQS_DN<7>")
	)
	(segment
		(start 42.759884 -304.504852)
		(end 43.134788 -304.504852)
		(width 0.16002)
		(layer "In6.Cu")
		(net "M_E_CPU1_SB_DQS_DN<7>")
	)
	(arc
		(start 81.24952 -286.56153)
		(mid 81.530952 -286.485741)
		(end 81.812384 -286.56153)
		(width 0.09525)
		(layer "In6.Cu")
		(net "M_E_CPU1_SB_DQS_DN<7>")
	)
	(arc
		(start 82.189574 -286.56153)
		(mid 82.433999 -286.486853)
		(end 82.686144 -286.52851)
		(width 0.09525)
		(layer "In6.Cu")
		(net "M_E_CPU1_SB_DQS_DN<7>")
	)
	(arc
		(start 79.369666 -286.56153)
		(mid 79.651098 -286.485741)
		(end 79.93253 -286.56153)
		(width 0.09525)
		(layer "In6.Cu")
		(net "M_E_CPU1_SB_DQS_DN<7>")
	)
	(arc
		(start 78.711044 -286.485838)
		(mid 78.856773 -286.505052)
		(end 78.992476 -286.56153)
		(width 0.09525)
		(layer "In6.Cu")
		(net "M_E_CPU1_SB_DQS_DN<7>")
	)
	(arc
		(start 79.940912 -286.566356)
		(mid 80.125944 -286.61227)
		(end 80.30972 -286.56153)
		(width 0.09525)
		(layer "In6.Cu")
		(net "M_E_CPU1_SB_DQS_DN<7>")
	)
	(arc
		(start 78.302358 -286.645858)
		(mid 78.47961 -286.527422)
		(end 78.688692 -286.485838)
		(width 0.09525)
		(layer "In6.Cu")
		(net "M_E_CPU1_SB_DQS_DN<7>")
	)
	(arc
		(start 79.000858 -286.566356)
		(mid 79.18589 -286.61227)
		(end 79.369666 -286.56153)
		(width 0.09525)
		(layer "In6.Cu")
		(net "M_E_CPU1_SB_DQS_DN<7>")
	)
	(arc
		(start 80.872584 -286.56153)
		(mid 81.061052 -286.612207)
		(end 81.24952 -286.56153)
		(width 0.09525)
		(layer "In6.Cu")
		(net "M_E_CPU1_SB_DQS_DN<7>")
	)
	(arc
		(start 80.30972 -286.56153)
		(mid 80.591152 -286.485741)
		(end 80.872584 -286.56153)
		(width 0.09525)
		(layer "In6.Cu")
		(net "M_E_CPU1_SB_DQS_DN<7>")
	)
	(arc
		(start 81.812384 -286.56153)
		(mid 81.996159 -286.612302)
		(end 82.181192 -286.566356)
		(width 0.09525)
		(layer "In6.Cu")
		(net "M_E_CPU1_SB_DQS_DN<7>")
	)
	(segment
		(start 83.408012 -281.110436)
		(end 82.940906 -281.376374)
		(width 0.12954)
		(layer "F.Cu")
		(net "M_E_CPU1_SB_DQS_DN<6>")
	)
	(segment
		(start 60.10783 -294.603932)
		(end 62.76213 -291.949632)
		(width 0.16002)
		(layer "In6.Cu")
		(net "M_E_CPU1_SB_DQS_DN<6>")
	)
	(segment
		(start 25.152096 -295.085262)
		(end 25.426162 -295.359328)
		(width 0.16002)
		(layer "In6.Cu")
		(net "M_E_CPU1_SB_DQS_DN<6>")
	)
	(segment
		(start 57.72658 -295.180258)
		(end 58.716672 -295.180258)
		(width 0.16002)
		(layer "In6.Cu")
		(net "M_E_CPU1_SB_DQS_DN<6>")
	)
	(segment
		(start 47.419768 -296.35831)
		(end 48.02378 -296.35831)
		(width 0.16002)
		(layer "In6.Cu")
		(net "M_E_CPU1_SB_DQS_DN<6>")
	)
	(segment
		(start 75.979528 -281.672284)
		(end 76.03871 -281.731466)
		(width 0.09525)
		(layer "In6.Cu")
		(net "M_E_CPU1_SB_DQS_DN<6>")
	)
	(segment
		(start 54.057296 -296.018204)
		(end 56.271414 -296.018204)
		(width 0.16002)
		(layer "In6.Cu")
		(net "M_E_CPU1_SB_DQS_DN<6>")
	)
	(segment
		(start 38.813232 -295.909746)
		(end 39.896288 -296.35831)
		(width 0.16002)
		(layer "In6.Cu")
		(net "M_E_CPU1_SB_DQS_DN<6>")
	)
	(segment
		(start 49.52873 -295.866058)
		(end 50.19929 -295.195498)
		(width 0.16002)
		(layer "In6.Cu")
		(net "M_E_CPU1_SB_DQS_DN<6>")
	)
	(segment
		(start 25.426162 -295.359328)
		(end 26.447496 -295.359328)
		(width 0.16002)
		(layer "In6.Cu")
		(net "M_E_CPU1_SB_DQS_DN<6>")
	)
	(segment
		(start 82.686144 -281.668474)
		(end 82.786982 -281.641804)
		(width 0.09525)
		(layer "In6.Cu")
		(net "M_E_CPU1_SB_DQS_DN<6>")
	)
	(segment
		(start 38.576758 -295.673272)
		(end 38.813232 -295.909746)
		(width 0.16002)
		(layer "In6.Cu")
		(net "M_E_CPU1_SB_DQS_DN<6>")
	)
	(segment
		(start 57.325006 -295.581832)
		(end 57.72658 -295.180258)
		(width 0.16002)
		(layer "In6.Cu")
		(net "M_E_CPU1_SB_DQS_DN<6>")
	)
	(segment
		(start 26.97861 -295.139364)
		(end 28.124912 -295.139364)
		(width 0.16002)
		(layer "In6.Cu")
		(net "M_E_CPU1_SB_DQS_DN<6>")
	)
	(segment
		(start 63.109856 -291.110162)
		(end 72.547734 -281.672284)
		(width 0.16002)
		(layer "In6.Cu")
		(net "M_E_CPU1_SB_DQS_DN<6>")
	)
	(segment
		(start 79.932784 -281.701494)
		(end 79.933546 -281.702002)
		(width 0.09525)
		(layer "In6.Cu")
		(net "M_E_CPU1_SB_DQS_DN<6>")
	)
	(segment
		(start 39.896288 -296.35831)
		(end 40.480996 -296.35831)
		(width 0.16002)
		(layer "In6.Cu")
		(net "M_E_CPU1_SB_DQS_DN<6>")
	)
	(segment
		(start 35.732212 -295.177464)
		(end 36.530534 -295.508172)
		(width 0.16002)
		(layer "In6.Cu")
		(net "M_E_CPU1_SB_DQS_DN<6>")
	)
	(segment
		(start 53.547264 -295.508172)
		(end 54.057296 -296.018204)
		(width 0.16002)
		(layer "In6.Cu")
		(net "M_E_CPU1_SB_DQS_DN<6>")
	)
	(segment
		(start 62.76213 -291.949632)
		(end 63.109856 -291.110162)
		(width 0.16002)
		(layer "In6.Cu")
		(net "M_E_CPU1_SB_DQS_DN<6>")
	)
	(segment
		(start 42.050462 -295.70807)
		(end 42.603674 -295.154858)
		(width 0.16002)
		(layer "In6.Cu")
		(net "M_E_CPU1_SB_DQS_DN<6>")
	)
	(segment
		(start 82.181192 -281.70632)
		(end 82.189574 -281.701494)
		(width 0.09525)
		(layer "In6.Cu")
		(net "M_E_CPU1_SB_DQS_DN<6>")
	)
	(segment
		(start 48.947324 -295.975786)
		(end 49.264062 -295.975786)
		(width 0.16002)
		(layer "In6.Cu")
		(net "M_E_CPU1_SB_DQS_DN<6>")
	)
	(segment
		(start 38.177978 -295.508172)
		(end 38.576758 -295.673272)
		(width 0.16002)
		(layer "In6.Cu")
		(net "M_E_CPU1_SB_DQS_DN<6>")
	)
	(segment
		(start 72.547734 -281.672284)
		(end 75.955906 -281.672284)
		(width 0.16002)
		(layer "In6.Cu")
		(net "M_E_CPU1_SB_DQS_DN<6>")
	)
	(segment
		(start 48.02378 -296.35831)
		(end 48.947324 -295.975786)
		(width 0.16002)
		(layer "In6.Cu")
		(net "M_E_CPU1_SB_DQS_DN<6>")
	)
	(segment
		(start 45.970952 -295.508172)
		(end 46.397926 -295.935146)
		(width 0.16002)
		(layer "In6.Cu")
		(net "M_E_CPU1_SB_DQS_DN<6>")
	)
	(segment
		(start 58.716672 -295.180258)
		(end 60.10783 -294.603932)
		(width 0.16002)
		(layer "In6.Cu")
		(net "M_E_CPU1_SB_DQS_DN<6>")
	)
	(segment
		(start 36.530534 -295.508172)
		(end 38.177978 -295.508172)
		(width 0.16002)
		(layer "In6.Cu")
		(net "M_E_CPU1_SB_DQS_DN<6>")
	)
	(segment
		(start 46.397926 -295.935146)
		(end 47.419768 -296.35831)
		(width 0.16002)
		(layer "In6.Cu")
		(net "M_E_CPU1_SB_DQS_DN<6>")
	)
	(segment
		(start 82.786982 -281.641804)
		(end 82.940906 -281.376374)
		(width 0.09525)
		(layer "In6.Cu")
		(net "M_E_CPU1_SB_DQS_DN<6>")
	)
	(segment
		(start 77.327506 -281.731466)
		(end 77.520546 -281.538426)
		(width 0.09525)
		(layer "In6.Cu")
		(net "M_E_CPU1_SB_DQS_DN<6>")
	)
	(segment
		(start 76.03871 -281.731466)
		(end 77.327506 -281.731466)
		(width 0.09525)
		(layer "In6.Cu")
		(net "M_E_CPU1_SB_DQS_DN<6>")
	)
	(segment
		(start 56.271414 -296.018204)
		(end 57.325006 -295.581832)
		(width 0.16002)
		(layer "In6.Cu")
		(net "M_E_CPU1_SB_DQS_DN<6>")
	)
	(segment
		(start 43.250612 -295.154858)
		(end 44.103544 -295.508172)
		(width 0.16002)
		(layer "In6.Cu")
		(net "M_E_CPU1_SB_DQS_DN<6>")
	)
	(segment
		(start 50.913792 -295.195498)
		(end 51.66868 -295.508172)
		(width 0.16002)
		(layer "In6.Cu")
		(net "M_E_CPU1_SB_DQS_DN<6>")
	)
	(segment
		(start 77.520546 -281.538426)
		(end 79.325978 -281.538426)
		(width 0.09525)
		(layer "In6.Cu")
		(net "M_E_CPU1_SB_DQS_DN<6>")
	)
	(segment
		(start 79.933546 -281.702002)
		(end 79.93634 -281.703526)
		(width 0.09525)
		(layer "In6.Cu")
		(net "M_E_CPU1_SB_DQS_DN<6>")
	)
	(segment
		(start 32.818832 -296.35831)
		(end 34.720022 -295.57091)
		(width 0.16002)
		(layer "In6.Cu")
		(net "M_E_CPU1_SB_DQS_DN<6>")
	)
	(segment
		(start 79.937102 -281.704034)
		(end 79.944722 -281.708352)
		(width 0.09525)
		(layer "In6.Cu")
		(net "M_E_CPU1_SB_DQS_DN<6>")
	)
	(segment
		(start 26.447496 -295.359328)
		(end 26.97861 -295.139364)
		(width 0.16002)
		(layer "In6.Cu")
		(net "M_E_CPU1_SB_DQS_DN<6>")
	)
	(segment
		(start 35.113468 -295.177464)
		(end 35.732212 -295.177464)
		(width 0.16002)
		(layer "In6.Cu")
		(net "M_E_CPU1_SB_DQS_DN<6>")
	)
	(segment
		(start 42.603674 -295.154858)
		(end 43.250612 -295.154858)
		(width 0.16002)
		(layer "In6.Cu")
		(net "M_E_CPU1_SB_DQS_DN<6>")
	)
	(segment
		(start 49.264062 -295.975786)
		(end 49.52873 -295.866058)
		(width 0.16002)
		(layer "In6.Cu")
		(net "M_E_CPU1_SB_DQS_DN<6>")
	)
	(segment
		(start 44.103544 -295.508172)
		(end 45.970952 -295.508172)
		(width 0.16002)
		(layer "In6.Cu")
		(net "M_E_CPU1_SB_DQS_DN<6>")
	)
	(segment
		(start 75.955906 -281.672284)
		(end 75.979528 -281.672284)
		(width 0.09525)
		(layer "In6.Cu")
		(net "M_E_CPU1_SB_DQS_DN<6>")
	)
	(segment
		(start 34.720022 -295.57091)
		(end 35.113468 -295.177464)
		(width 0.16002)
		(layer "In6.Cu")
		(net "M_E_CPU1_SB_DQS_DN<6>")
	)
	(segment
		(start 79.93634 -281.703526)
		(end 79.937102 -281.704034)
		(width 0.09525)
		(layer "In6.Cu")
		(net "M_E_CPU1_SB_DQS_DN<6>")
	)
	(segment
		(start 50.19929 -295.195498)
		(end 50.913792 -295.195498)
		(width 0.16002)
		(layer "In6.Cu")
		(net "M_E_CPU1_SB_DQS_DN<6>")
	)
	(segment
		(start 40.480996 -296.35831)
		(end 42.050462 -295.70807)
		(width 0.16002)
		(layer "In6.Cu")
		(net "M_E_CPU1_SB_DQS_DN<6>")
	)
	(segment
		(start 51.66868 -295.508172)
		(end 53.547264 -295.508172)
		(width 0.16002)
		(layer "In6.Cu")
		(net "M_E_CPU1_SB_DQS_DN<6>")
	)
	(segment
		(start 28.124912 -295.139364)
		(end 31.067756 -296.35831)
		(width 0.16002)
		(layer "In6.Cu")
		(net "M_E_CPU1_SB_DQS_DN<6>")
	)
	(segment
		(start 31.067756 -296.35831)
		(end 32.818832 -296.35831)
		(width 0.16002)
		(layer "In6.Cu")
		(net "M_E_CPU1_SB_DQS_DN<6>")
	)
	(arc
		(start 81.24952 -281.701494)
		(mid 81.530952 -281.625739)
		(end 81.812384 -281.701494)
		(width 0.09525)
		(layer "In6.Cu")
		(net "M_E_CPU1_SB_DQS_DN<6>")
	)
	(arc
		(start 80.872584 -281.701494)
		(mid 81.061052 -281.752171)
		(end 81.24952 -281.701494)
		(width 0.09525)
		(layer "In6.Cu")
		(net "M_E_CPU1_SB_DQS_DN<6>")
	)
	(arc
		(start 82.189574 -281.701494)
		(mid 82.423369 -281.627627)
		(end 82.666332 -281.6606)
		(width 0.09525)
		(layer "In6.Cu")
		(net "M_E_CPU1_SB_DQS_DN<6>")
	)
	(arc
		(start 80.30972 -281.701494)
		(mid 80.591152 -281.625739)
		(end 80.872584 -281.701494)
		(width 0.09525)
		(layer "In6.Cu")
		(net "M_E_CPU1_SB_DQS_DN<6>")
	)
	(arc
		(start 79.331058 -281.538426)
		(mid 79.642577 -281.580629)
		(end 79.932784 -281.701494)
		(width 0.09525)
		(layer "In6.Cu")
		(net "M_E_CPU1_SB_DQS_DN<6>")
	)
	(arc
		(start 82.666332 -281.6606)
		(mid 82.676275 -281.664443)
		(end 82.686144 -281.668474)
		(width 0.09525)
		(layer "In6.Cu")
		(net "M_E_CPU1_SB_DQS_DN<6>")
	)
	(arc
		(start 79.944722 -281.708352)
		(mid 80.128103 -281.752183)
		(end 80.30972 -281.701494)
		(width 0.09525)
		(layer "In6.Cu")
		(net "M_E_CPU1_SB_DQS_DN<6>")
	)
	(arc
		(start 79.325978 -281.538426)
		(mid 79.328518 -281.538423)
		(end 79.331058 -281.538426)
		(width 0.09525)
		(layer "In6.Cu")
		(net "M_E_CPU1_SB_DQS_DN<6>")
	)
	(arc
		(start 81.812384 -281.701494)
		(mid 81.996159 -281.752266)
		(end 82.181192 -281.70632)
		(width 0.09525)
		(layer "In6.Cu")
		(net "M_E_CPU1_SB_DQS_DN<6>")
	)
	(segment
		(start 83.408012 -276.2504)
		(end 82.940906 -276.516338)
		(width 0.12954)
		(layer "F.Cu")
		(net "M_E_CPU1_SB_DQS_DN<5>")
	)
	(segment
		(start 28.15844 -285.792164)
		(end 28.540964 -286.174688)
		(width 0.16002)
		(layer "In6.Cu")
		(net "M_E_CPU1_SB_DQS_DN<5>")
	)
	(segment
		(start 82.686144 -276.808438)
		(end 82.786982 -276.781768)
		(width 0.09525)
		(layer "In6.Cu")
		(net "M_E_CPU1_SB_DQS_DN<5>")
	)
	(segment
		(start 36.060126 -286.158178)
		(end 38.405054 -286.158178)
		(width 0.16002)
		(layer "In6.Cu")
		(net "M_E_CPU1_SB_DQS_DN<5>")
	)
	(segment
		(start 53.568854 -286.158178)
		(end 54.04104 -286.630364)
		(width 0.16002)
		(layer "In6.Cu")
		(net "M_E_CPU1_SB_DQS_DN<5>")
	)
	(segment
		(start 54.04104 -286.630364)
		(end 56.91124 -286.630364)
		(width 0.16002)
		(layer "In6.Cu")
		(net "M_E_CPU1_SB_DQS_DN<5>")
	)
	(segment
		(start 31.355792 -287.008316)
		(end 33.419288 -287.008316)
		(width 0.16002)
		(layer "In6.Cu")
		(net "M_E_CPU1_SB_DQS_DN<5>")
	)
	(segment
		(start 34.553652 -286.33928)
		(end 35.113468 -285.779464)
		(width 0.16002)
		(layer "In6.Cu")
		(net "M_E_CPU1_SB_DQS_DN<5>")
	)
	(segment
		(start 42.64914 -285.804864)
		(end 43.250612 -285.804864)
		(width 0.16002)
		(layer "In6.Cu")
		(net "M_E_CPU1_SB_DQS_DN<5>")
	)
	(segment
		(start 82.181192 -276.846284)
		(end 82.189574 -276.841458)
		(width 0.09525)
		(layer "In6.Cu")
		(net "M_E_CPU1_SB_DQS_DN<5>")
	)
	(segment
		(start 30.522164 -286.174688)
		(end 31.355792 -287.008316)
		(width 0.16002)
		(layer "In6.Cu")
		(net "M_E_CPU1_SB_DQS_DN<5>")
	)
	(segment
		(start 61.148214 -284.614366)
		(end 69.713856 -276.048724)
		(width 0.16002)
		(layer "In6.Cu")
		(net "M_E_CPU1_SB_DQS_DN<5>")
	)
	(segment
		(start 76.439014 -276.107906)
		(end 76.947014 -276.615906)
		(width 0.09525)
		(layer "In6.Cu")
		(net "M_E_CPU1_SB_DQS_DN<5>")
	)
	(segment
		(start 38.405054 -286.158178)
		(end 39.255192 -287.008316)
		(width 0.16002)
		(layer "In6.Cu")
		(net "M_E_CPU1_SB_DQS_DN<5>")
	)
	(segment
		(start 76.102972 -276.048724)
		(end 76.162154 -276.107906)
		(width 0.09525)
		(layer "In6.Cu")
		(net "M_E_CPU1_SB_DQS_DN<5>")
	)
	(segment
		(start 76.162154 -276.107906)
		(end 76.439014 -276.107906)
		(width 0.09525)
		(layer "In6.Cu")
		(net "M_E_CPU1_SB_DQS_DN<5>")
	)
	(segment
		(start 79.55153 -276.615906)
		(end 79.930498 -276.839934)
		(width 0.09525)
		(layer "In6.Cu")
		(net "M_E_CPU1_SB_DQS_DN<5>")
	)
	(segment
		(start 25.152096 -285.735268)
		(end 25.426162 -286.009334)
		(width 0.16002)
		(layer "In6.Cu")
		(net "M_E_CPU1_SB_DQS_DN<5>")
	)
	(segment
		(start 43.250612 -285.804864)
		(end 43.603926 -286.158178)
		(width 0.16002)
		(layer "In6.Cu")
		(net "M_E_CPU1_SB_DQS_DN<5>")
	)
	(segment
		(start 26.573226 -286.009334)
		(end 27.097736 -285.792164)
		(width 0.16002)
		(layer "In6.Cu")
		(net "M_E_CPU1_SB_DQS_DN<5>")
	)
	(segment
		(start 33.419288 -287.008316)
		(end 33.75914 -286.668464)
		(width 0.16002)
		(layer "In6.Cu")
		(net "M_E_CPU1_SB_DQS_DN<5>")
	)
	(segment
		(start 47.3837 -287.008316)
		(end 48.540416 -287.008316)
		(width 0.16002)
		(layer "In6.Cu")
		(net "M_E_CPU1_SB_DQS_DN<5>")
	)
	(segment
		(start 50.857912 -285.830264)
		(end 51.185826 -286.158178)
		(width 0.16002)
		(layer "In6.Cu")
		(net "M_E_CPU1_SB_DQS_DN<5>")
	)
	(segment
		(start 40.996616 -287.008316)
		(end 41.603168 -286.401764)
		(width 0.16002)
		(layer "In6.Cu")
		(net "M_E_CPU1_SB_DQS_DN<5>")
	)
	(segment
		(start 33.75914 -286.668464)
		(end 34.553652 -286.33928)
		(width 0.16002)
		(layer "In6.Cu")
		(net "M_E_CPU1_SB_DQS_DN<5>")
	)
	(segment
		(start 41.603168 -286.401764)
		(end 42.05224 -286.401764)
		(width 0.16002)
		(layer "In6.Cu")
		(net "M_E_CPU1_SB_DQS_DN<5>")
	)
	(segment
		(start 27.097736 -285.792164)
		(end 28.15844 -285.792164)
		(width 0.16002)
		(layer "In6.Cu")
		(net "M_E_CPU1_SB_DQS_DN<5>")
	)
	(segment
		(start 56.91124 -286.630364)
		(end 57.71134 -285.830264)
		(width 0.16002)
		(layer "In6.Cu")
		(net "M_E_CPU1_SB_DQS_DN<5>")
	)
	(segment
		(start 39.255192 -287.008316)
		(end 40.996616 -287.008316)
		(width 0.16002)
		(layer "In6.Cu")
		(net "M_E_CPU1_SB_DQS_DN<5>")
	)
	(segment
		(start 49.38014 -286.643064)
		(end 50.19294 -285.830264)
		(width 0.16002)
		(layer "In6.Cu")
		(net "M_E_CPU1_SB_DQS_DN<5>")
	)
	(segment
		(start 25.426162 -286.009334)
		(end 26.573226 -286.009334)
		(width 0.16002)
		(layer "In6.Cu")
		(net "M_E_CPU1_SB_DQS_DN<5>")
	)
	(segment
		(start 76.947014 -276.615906)
		(end 79.55153 -276.615906)
		(width 0.09525)
		(layer "In6.Cu")
		(net "M_E_CPU1_SB_DQS_DN<5>")
	)
	(segment
		(start 48.905668 -286.643064)
		(end 49.38014 -286.643064)
		(width 0.16002)
		(layer "In6.Cu")
		(net "M_E_CPU1_SB_DQS_DN<5>")
	)
	(segment
		(start 48.540416 -287.008316)
		(end 48.905668 -286.643064)
		(width 0.16002)
		(layer "In6.Cu")
		(net "M_E_CPU1_SB_DQS_DN<5>")
	)
	(segment
		(start 57.71134 -285.830264)
		(end 58.212736 -285.830264)
		(width 0.16002)
		(layer "In6.Cu")
		(net "M_E_CPU1_SB_DQS_DN<5>")
	)
	(segment
		(start 35.113468 -285.779464)
		(end 35.681412 -285.779464)
		(width 0.16002)
		(layer "In6.Cu")
		(net "M_E_CPU1_SB_DQS_DN<5>")
	)
	(segment
		(start 42.05224 -286.401764)
		(end 42.64914 -285.804864)
		(width 0.16002)
		(layer "In6.Cu")
		(net "M_E_CPU1_SB_DQS_DN<5>")
	)
	(segment
		(start 35.681412 -285.779464)
		(end 36.060126 -286.158178)
		(width 0.16002)
		(layer "In6.Cu")
		(net "M_E_CPU1_SB_DQS_DN<5>")
	)
	(segment
		(start 50.19294 -285.830264)
		(end 50.857912 -285.830264)
		(width 0.16002)
		(layer "In6.Cu")
		(net "M_E_CPU1_SB_DQS_DN<5>")
	)
	(segment
		(start 45.331126 -286.158178)
		(end 47.3837 -287.008316)
		(width 0.16002)
		(layer "In6.Cu")
		(net "M_E_CPU1_SB_DQS_DN<5>")
	)
	(segment
		(start 76.07935 -276.048724)
		(end 76.102972 -276.048724)
		(width 0.09525)
		(layer "In6.Cu")
		(net "M_E_CPU1_SB_DQS_DN<5>")
	)
	(segment
		(start 82.786982 -276.781768)
		(end 82.940906 -276.516338)
		(width 0.09525)
		(layer "In6.Cu")
		(net "M_E_CPU1_SB_DQS_DN<5>")
	)
	(segment
		(start 69.713856 -276.048724)
		(end 76.07935 -276.048724)
		(width 0.16002)
		(layer "In6.Cu")
		(net "M_E_CPU1_SB_DQS_DN<5>")
	)
	(segment
		(start 51.185826 -286.158178)
		(end 53.568854 -286.158178)
		(width 0.16002)
		(layer "In6.Cu")
		(net "M_E_CPU1_SB_DQS_DN<5>")
	)
	(segment
		(start 58.212736 -285.830264)
		(end 61.148214 -284.614366)
		(width 0.16002)
		(layer "In6.Cu")
		(net "M_E_CPU1_SB_DQS_DN<5>")
	)
	(segment
		(start 43.603926 -286.158178)
		(end 45.331126 -286.158178)
		(width 0.16002)
		(layer "In6.Cu")
		(net "M_E_CPU1_SB_DQS_DN<5>")
	)
	(segment
		(start 28.540964 -286.174688)
		(end 30.522164 -286.174688)
		(width 0.16002)
		(layer "In6.Cu")
		(net "M_E_CPU1_SB_DQS_DN<5>")
	)
	(arc
		(start 81.812384 -276.841458)
		(mid 81.996159 -276.89223)
		(end 82.181192 -276.846284)
		(width 0.09525)
		(layer "In6.Cu")
		(net "M_E_CPU1_SB_DQS_DN<5>")
	)
	(arc
		(start 80.30972 -276.841458)
		(mid 80.591152 -276.765703)
		(end 80.872584 -276.841458)
		(width 0.09525)
		(layer "In6.Cu")
		(net "M_E_CPU1_SB_DQS_DN<5>")
	)
	(arc
		(start 80.872584 -276.841458)
		(mid 81.061052 -276.892135)
		(end 81.24952 -276.841458)
		(width 0.09525)
		(layer "In6.Cu")
		(net "M_E_CPU1_SB_DQS_DN<5>")
	)
	(arc
		(start 79.930498 -276.839934)
		(mid 80.119915 -276.892204)
		(end 80.30972 -276.841458)
		(width 0.09525)
		(layer "In6.Cu")
		(net "M_E_CPU1_SB_DQS_DN<5>")
	)
	(arc
		(start 82.189574 -276.841458)
		(mid 82.434 -276.766815)
		(end 82.686144 -276.808438)
		(width 0.09525)
		(layer "In6.Cu")
		(net "M_E_CPU1_SB_DQS_DN<5>")
	)
	(arc
		(start 81.24952 -276.841458)
		(mid 81.530952 -276.765703)
		(end 81.812384 -276.841458)
		(width 0.09525)
		(layer "In6.Cu")
		(net "M_E_CPU1_SB_DQS_DN<5>")
	)
	(segment
		(start 83.408012 -271.390364)
		(end 82.940906 -271.656302)
		(width 0.12954)
		(layer "F.Cu")
		(net "M_E_CPU1_SB_DQS_DN<4>")
	)
	(segment
		(start 36.057332 -276.808184)
		(end 38.35146 -276.808184)
		(width 0.16002)
		(layer "In6.Cu")
		(net "M_E_CPU1_SB_DQS_DN<4>")
	)
	(segment
		(start 82.786982 -271.921732)
		(end 82.940906 -271.656302)
		(width 0.09525)
		(layer "In6.Cu")
		(net "M_E_CPU1_SB_DQS_DN<4>")
	)
	(segment
		(start 49.788318 -276.845014)
		(end 50.213768 -276.419564)
		(width 0.16002)
		(layer "In6.Cu")
		(net "M_E_CPU1_SB_DQS_DN<4>")
	)
	(segment
		(start 61.418724 -273.849338)
		(end 61.80201 -272.924016)
		(width 0.16002)
		(layer "In6.Cu")
		(net "M_E_CPU1_SB_DQS_DN<4>")
	)
	(segment
		(start 49.007776 -277.168356)
		(end 49.788318 -276.845014)
		(width 0.16002)
		(layer "In6.Cu")
		(net "M_E_CPU1_SB_DQS_DN<4>")
	)
	(segment
		(start 64.300862 -270.425164)
		(end 75.955906 -270.425164)
		(width 0.16002)
		(layer "In6.Cu")
		(net "M_E_CPU1_SB_DQS_DN<4>")
	)
	(segment
		(start 34.427668 -277.143464)
		(end 35.088068 -276.483064)
		(width 0.16002)
		(layer "In6.Cu")
		(net "M_E_CPU1_SB_DQS_DN<4>")
	)
	(segment
		(start 28.530296 -276.824694)
		(end 30.231842 -276.824694)
		(width 0.16002)
		(layer "In6.Cu")
		(net "M_E_CPU1_SB_DQS_DN<4>")
	)
	(segment
		(start 35.732212 -276.483064)
		(end 36.057332 -276.808184)
		(width 0.16002)
		(layer "In6.Cu")
		(net "M_E_CPU1_SB_DQS_DN<4>")
	)
	(segment
		(start 38.35146 -276.808184)
		(end 39.201598 -277.658322)
		(width 0.16002)
		(layer "In6.Cu")
		(net "M_E_CPU1_SB_DQS_DN<4>")
	)
	(segment
		(start 57.732168 -276.470364)
		(end 58.797698 -276.470364)
		(width 0.16002)
		(layer "In6.Cu")
		(net "M_E_CPU1_SB_DQS_DN<4>")
	)
	(segment
		(start 50.73904 -276.419564)
		(end 51.12766 -276.808184)
		(width 0.16002)
		(layer "In6.Cu")
		(net "M_E_CPU1_SB_DQS_DN<4>")
	)
	(segment
		(start 28.125166 -276.419564)
		(end 28.530296 -276.824694)
		(width 0.16002)
		(layer "In6.Cu")
		(net "M_E_CPU1_SB_DQS_DN<4>")
	)
	(segment
		(start 82.181192 -271.986248)
		(end 82.189574 -271.981422)
		(width 0.09525)
		(layer "In6.Cu")
		(net "M_E_CPU1_SB_DQS_DN<4>")
	)
	(segment
		(start 27.03449 -276.65934)
		(end 27.274266 -276.419564)
		(width 0.16002)
		(layer "In6.Cu")
		(net "M_E_CPU1_SB_DQS_DN<4>")
	)
	(segment
		(start 25.152096 -276.385274)
		(end 25.426162 -276.65934)
		(width 0.16002)
		(layer "In6.Cu")
		(net "M_E_CPU1_SB_DQS_DN<4>")
	)
	(segment
		(start 41.32834 -277.321264)
		(end 42.122852 -276.99208)
		(width 0.16002)
		(layer "In6.Cu")
		(net "M_E_CPU1_SB_DQS_DN<4>")
	)
	(segment
		(start 43.601132 -276.808184)
		(end 45.71746 -276.808184)
		(width 0.16002)
		(layer "In6.Cu")
		(net "M_E_CPU1_SB_DQS_DN<4>")
	)
	(segment
		(start 50.213768 -276.419564)
		(end 50.73904 -276.419564)
		(width 0.16002)
		(layer "In6.Cu")
		(net "M_E_CPU1_SB_DQS_DN<4>")
	)
	(segment
		(start 53.46446 -276.808184)
		(end 53.93944 -277.283164)
		(width 0.16002)
		(layer "In6.Cu")
		(net "M_E_CPU1_SB_DQS_DN<4>")
	)
	(segment
		(start 30.231842 -276.824694)
		(end 32.244538 -277.658322)
		(width 0.16002)
		(layer "In6.Cu")
		(net "M_E_CPU1_SB_DQS_DN<4>")
	)
	(segment
		(start 77.504036 -270.774414)
		(end 78.577186 -271.847564)
		(width 0.09525)
		(layer "In6.Cu")
		(net "M_E_CPU1_SB_DQS_DN<4>")
	)
	(segment
		(start 33.40481 -277.658322)
		(end 33.919668 -277.143464)
		(width 0.16002)
		(layer "In6.Cu")
		(net "M_E_CPU1_SB_DQS_DN<4>")
	)
	(segment
		(start 40.991282 -277.658322)
		(end 41.32834 -277.321264)
		(width 0.16002)
		(layer "In6.Cu")
		(net "M_E_CPU1_SB_DQS_DN<4>")
	)
	(segment
		(start 25.426162 -276.65934)
		(end 27.03449 -276.65934)
		(width 0.16002)
		(layer "In6.Cu")
		(net "M_E_CPU1_SB_DQS_DN<4>")
	)
	(segment
		(start 56.919368 -277.283164)
		(end 57.732168 -276.470364)
		(width 0.16002)
		(layer "In6.Cu")
		(net "M_E_CPU1_SB_DQS_DN<4>")
	)
	(segment
		(start 42.122852 -276.99208)
		(end 42.631868 -276.483064)
		(width 0.16002)
		(layer "In6.Cu")
		(net "M_E_CPU1_SB_DQS_DN<4>")
	)
	(segment
		(start 45.71746 -276.808184)
		(end 46.567598 -277.658322)
		(width 0.16002)
		(layer "In6.Cu")
		(net "M_E_CPU1_SB_DQS_DN<4>")
	)
	(segment
		(start 35.088068 -276.483064)
		(end 35.732212 -276.483064)
		(width 0.16002)
		(layer "In6.Cu")
		(net "M_E_CPU1_SB_DQS_DN<4>")
	)
	(segment
		(start 76.06411 -270.484346)
		(end 76.359766 -270.484346)
		(width 0.09525)
		(layer "In6.Cu")
		(net "M_E_CPU1_SB_DQS_DN<4>")
	)
	(segment
		(start 32.244538 -277.658322)
		(end 33.40481 -277.658322)
		(width 0.16002)
		(layer "In6.Cu")
		(net "M_E_CPU1_SB_DQS_DN<4>")
	)
	(segment
		(start 33.919668 -277.143464)
		(end 34.427668 -277.143464)
		(width 0.16002)
		(layer "In6.Cu")
		(net "M_E_CPU1_SB_DQS_DN<4>")
	)
	(segment
		(start 76.359766 -270.484346)
		(end 76.649834 -270.774414)
		(width 0.09525)
		(layer "In6.Cu")
		(net "M_E_CPU1_SB_DQS_DN<4>")
	)
	(segment
		(start 82.686144 -271.948402)
		(end 82.786982 -271.921732)
		(width 0.09525)
		(layer "In6.Cu")
		(net "M_E_CPU1_SB_DQS_DN<4>")
	)
	(segment
		(start 76.649834 -270.774414)
		(end 77.504036 -270.774414)
		(width 0.09525)
		(layer "In6.Cu")
		(net "M_E_CPU1_SB_DQS_DN<4>")
	)
	(segment
		(start 42.631868 -276.483064)
		(end 43.276012 -276.483064)
		(width 0.16002)
		(layer "In6.Cu")
		(net "M_E_CPU1_SB_DQS_DN<4>")
	)
	(segment
		(start 76.004928 -270.425164)
		(end 76.06411 -270.484346)
		(width 0.09525)
		(layer "In6.Cu")
		(net "M_E_CPU1_SB_DQS_DN<4>")
	)
	(segment
		(start 39.201598 -277.658322)
		(end 40.991282 -277.658322)
		(width 0.16002)
		(layer "In6.Cu")
		(net "M_E_CPU1_SB_DQS_DN<4>")
	)
	(segment
		(start 75.955906 -270.425164)
		(end 75.981306 -270.425164)
		(width 0.1016)
		(layer "In6.Cu")
		(net "M_E_CPU1_SB_DQS_DN<4>")
	)
	(segment
		(start 58.797698 -276.470364)
		(end 61.418724 -273.849338)
		(width 0.16002)
		(layer "In6.Cu")
		(net "M_E_CPU1_SB_DQS_DN<4>")
	)
	(segment
		(start 48.51781 -277.658322)
		(end 49.007776 -277.168356)
		(width 0.16002)
		(layer "In6.Cu")
		(net "M_E_CPU1_SB_DQS_DN<4>")
	)
	(segment
		(start 78.577186 -271.847564)
		(end 79.434436 -271.847564)
		(width 0.09525)
		(layer "In6.Cu")
		(net "M_E_CPU1_SB_DQS_DN<4>")
	)
	(segment
		(start 61.80201 -272.924016)
		(end 64.300862 -270.425164)
		(width 0.16002)
		(layer "In6.Cu")
		(net "M_E_CPU1_SB_DQS_DN<4>")
	)
	(segment
		(start 27.274266 -276.419564)
		(end 28.125166 -276.419564)
		(width 0.16002)
		(layer "In6.Cu")
		(net "M_E_CPU1_SB_DQS_DN<4>")
	)
	(segment
		(start 46.567598 -277.658322)
		(end 48.51781 -277.658322)
		(width 0.16002)
		(layer "In6.Cu")
		(net "M_E_CPU1_SB_DQS_DN<4>")
	)
	(segment
		(start 79.932784 -271.981422)
		(end 79.944722 -271.98828)
		(width 0.09525)
		(layer "In6.Cu")
		(net "M_E_CPU1_SB_DQS_DN<4>")
	)
	(segment
		(start 53.93944 -277.283164)
		(end 56.919368 -277.283164)
		(width 0.16002)
		(layer "In6.Cu")
		(net "M_E_CPU1_SB_DQS_DN<4>")
	)
	(segment
		(start 43.276012 -276.483064)
		(end 43.601132 -276.808184)
		(width 0.16002)
		(layer "In6.Cu")
		(net "M_E_CPU1_SB_DQS_DN<4>")
	)
	(segment
		(start 51.12766 -276.808184)
		(end 53.46446 -276.808184)
		(width 0.16002)
		(layer "In6.Cu")
		(net "M_E_CPU1_SB_DQS_DN<4>")
	)
	(segment
		(start 75.981306 -270.425164)
		(end 76.004928 -270.425164)
		(width 0.09525)
		(layer "In6.Cu")
		(net "M_E_CPU1_SB_DQS_DN<4>")
	)
	(arc
		(start 81.812384 -271.981422)
		(mid 81.996159 -272.032194)
		(end 82.181192 -271.986248)
		(width 0.09525)
		(layer "In6.Cu")
		(net "M_E_CPU1_SB_DQS_DN<4>")
	)
	(arc
		(start 79.944722 -271.98828)
		(mid 80.128103 -272.032111)
		(end 80.30972 -271.981422)
		(width 0.09525)
		(layer "In6.Cu")
		(net "M_E_CPU1_SB_DQS_DN<4>")
	)
	(arc
		(start 82.189574 -271.981422)
		(mid 82.434 -271.906779)
		(end 82.686144 -271.948402)
		(width 0.09525)
		(layer "In6.Cu")
		(net "M_E_CPU1_SB_DQS_DN<4>")
	)
	(arc
		(start 80.872584 -271.981422)
		(mid 81.061052 -272.032099)
		(end 81.24952 -271.981422)
		(width 0.09525)
		(layer "In6.Cu")
		(net "M_E_CPU1_SB_DQS_DN<4>")
	)
	(arc
		(start 80.30972 -271.981422)
		(mid 80.591152 -271.905667)
		(end 80.872584 -271.981422)
		(width 0.09525)
		(layer "In6.Cu")
		(net "M_E_CPU1_SB_DQS_DN<4>")
	)
	(arc
		(start 81.24952 -271.981422)
		(mid 81.530952 -271.905667)
		(end 81.812384 -271.981422)
		(width 0.09525)
		(layer "In6.Cu")
		(net "M_E_CPU1_SB_DQS_DN<4>")
	)
	(arc
		(start 79.434436 -271.847564)
		(mid 79.692452 -271.881593)
		(end 79.932784 -271.981422)
		(width 0.09525)
		(layer "In6.Cu")
		(net "M_E_CPU1_SB_DQS_DN<4>")
	)
	(segment
		(start 81.527904 -290.830254)
		(end 81.061052 -291.096192)
		(width 0.12954)
		(layer "F.Cu")
		(net "M_E_CPU1_SB_DQS_DN<3>")
	)
	(segment
		(start 51.124612 -312.512456)
		(end 52.91074 -312.512456)
		(width 0.16002)
		(layer "In6.Cu")
		(net "M_E_CPU1_SB_DQS_DN<3>")
	)
	(segment
		(start 68.91401 -301.35957)
		(end 69.390514 -301.35957)
		(width 0.16002)
		(layer "In6.Cu")
		(net "M_E_CPU1_SB_DQS_DN<3>")
	)
	(segment
		(start 70.144894 -299.808138)
		(end 70.305168 -299.968412)
		(width 0.16002)
		(layer "In6.Cu")
		(net "M_E_CPU1_SB_DQS_DN<3>")
	)
	(segment
		(start 50.241962 -312.912506)
		(end 50.724562 -312.912506)
		(width 0.16002)
		(layer "In6.Cu")
		(net "M_E_CPU1_SB_DQS_DN<3>")
	)
	(segment
		(start 66.88074 -303.072546)
		(end 66.88074 -302.846486)
		(width 0.16002)
		(layer "In6.Cu")
		(net "M_E_CPU1_SB_DQS_DN<3>")
	)
	(segment
		(start 46.080934 -313.36234)
		(end 48.559212 -313.36234)
		(width 0.16002)
		(layer "In6.Cu")
		(net "M_E_CPU1_SB_DQS_DN<3>")
	)
	(segment
		(start 57.011062 -313.687206)
		(end 57.874662 -312.823606)
		(width 0.16002)
		(layer "In6.Cu")
		(net "M_E_CPU1_SB_DQS_DN<3>")
	)
	(segment
		(start 33.111948 -313.36234)
		(end 33.442402 -313.692794)
		(width 0.16002)
		(layer "In6.Cu")
		(net "M_E_CPU1_SB_DQS_DN<3>")
	)
	(segment
		(start 35.69589 -312.853324)
		(end 36.036758 -312.512456)
		(width 0.16002)
		(layer "In6.Cu")
		(net "M_E_CPU1_SB_DQS_DN<3>")
	)
	(segment
		(start 81.191862 -290.744148)
		(end 81.214976 -290.830762)
		(width 0.09525)
		(layer "In6.Cu")
		(net "M_E_CPU1_SB_DQS_DN<3>")
	)
	(segment
		(start 66.04381 -305.138328)
		(end 66.04381 -304.706274)
		(width 0.16002)
		(layer "In6.Cu")
		(net "M_E_CPU1_SB_DQS_DN<3>")
	)
	(segment
		(start 71.310246 -298.41698)
		(end 71.536052 -298.41698)
		(width 0.16002)
		(layer "In6.Cu")
		(net "M_E_CPU1_SB_DQS_DN<3>")
	)
	(segment
		(start 78.075536 -292.590728)
		(end 78.075536 -291.668962)
		(width 0.09525)
		(layer "In6.Cu")
		(net "M_E_CPU1_SB_DQS_DN<3>")
	)
	(segment
		(start 50.724562 -312.912506)
		(end 51.124612 -312.512456)
		(width 0.16002)
		(layer "In6.Cu")
		(net "M_E_CPU1_SB_DQS_DN<3>")
	)
	(segment
		(start 71.054214 -298.899072)
		(end 71.054214 -298.673012)
		(width 0.16002)
		(layer "In6.Cu")
		(net "M_E_CPU1_SB_DQS_DN<3>")
	)
	(segment
		(start 66.04381 -304.706274)
		(end 67.04076 -303.709324)
		(width 0.16002)
		(layer "In6.Cu")
		(net "M_E_CPU1_SB_DQS_DN<3>")
	)
	(segment
		(start 69.823076 -300.927008)
		(end 69.823076 -300.450504)
		(width 0.16002)
		(layer "In6.Cu")
		(net "M_E_CPU1_SB_DQS_DN<3>")
	)
	(segment
		(start 52.91074 -312.512456)
		(end 54.08549 -313.687206)
		(width 0.16002)
		(layer "In6.Cu")
		(net "M_E_CPU1_SB_DQS_DN<3>")
	)
	(segment
		(start 59.669172 -312.823606)
		(end 63.45047 -309.042308)
		(width 0.16002)
		(layer "In6.Cu")
		(net "M_E_CPU1_SB_DQS_DN<3>")
	)
	(segment
		(start 66.88074 -302.846486)
		(end 67.136772 -302.590454)
		(width 0.16002)
		(layer "In6.Cu")
		(net "M_E_CPU1_SB_DQS_DN<3>")
	)
	(segment
		(start 42.761662 -312.840624)
		(end 43.244262 -312.840624)
		(width 0.16002)
		(layer "In6.Cu")
		(net "M_E_CPU1_SB_DQS_DN<3>")
	)
	(segment
		(start 68.52793 -301.199296)
		(end 68.753736 -301.199296)
		(width 0.16002)
		(layer "In6.Cu")
		(net "M_E_CPU1_SB_DQS_DN<3>")
	)
	(segment
		(start 35.205162 -312.853324)
		(end 35.69589 -312.853324)
		(width 0.16002)
		(layer "In6.Cu")
		(net "M_E_CPU1_SB_DQS_DN<3>")
	)
	(segment
		(start 68.753736 -301.199296)
		(end 68.91401 -301.35957)
		(width 0.16002)
		(layer "In6.Cu")
		(net "M_E_CPU1_SB_DQS_DN<3>")
	)
	(segment
		(start 43.244262 -312.840624)
		(end 43.57243 -312.512456)
		(width 0.16002)
		(layer "In6.Cu")
		(net "M_E_CPU1_SB_DQS_DN<3>")
	)
	(segment
		(start 68.431918 -302.318166)
		(end 68.431918 -301.841662)
		(width 0.16002)
		(layer "In6.Cu")
		(net "M_E_CPU1_SB_DQS_DN<3>")
	)
	(segment
		(start 78.075536 -291.668962)
		(end 78.914244 -290.830254)
		(width 0.09525)
		(layer "In6.Cu")
		(net "M_E_CPU1_SB_DQS_DN<3>")
	)
	(segment
		(start 67.362578 -302.590454)
		(end 67.522852 -302.750728)
		(width 0.16002)
		(layer "In6.Cu")
		(net "M_E_CPU1_SB_DQS_DN<3>")
	)
	(segment
		(start 69.390514 -301.35957)
		(end 69.823076 -300.927008)
		(width 0.16002)
		(layer "In6.Cu")
		(net "M_E_CPU1_SB_DQS_DN<3>")
	)
	(segment
		(start 71.536052 -298.41698)
		(end 71.696326 -298.577254)
		(width 0.16002)
		(layer "In6.Cu")
		(net "M_E_CPU1_SB_DQS_DN<3>")
	)
	(segment
		(start 69.919088 -299.808138)
		(end 70.144894 -299.808138)
		(width 0.16002)
		(layer "In6.Cu")
		(net "M_E_CPU1_SB_DQS_DN<3>")
	)
	(segment
		(start 41.923462 -313.678824)
		(end 42.761662 -312.840624)
		(width 0.16002)
		(layer "In6.Cu")
		(net "M_E_CPU1_SB_DQS_DN<3>")
	)
	(segment
		(start 29.525976 -313.511438)
		(end 32.139382 -313.511438)
		(width 0.16002)
		(layer "In6.Cu")
		(net "M_E_CPU1_SB_DQS_DN<3>")
	)
	(segment
		(start 39.405814 -313.36234)
		(end 40.797734 -313.36234)
		(width 0.16002)
		(layer "In6.Cu")
		(net "M_E_CPU1_SB_DQS_DN<3>")
	)
	(segment
		(start 68.431918 -301.841662)
		(end 68.271898 -301.681388)
		(width 0.16002)
		(layer "In6.Cu")
		(net "M_E_CPU1_SB_DQS_DN<3>")
	)
	(segment
		(start 32.139382 -313.511438)
		(end 32.28848 -313.36234)
		(width 0.16002)
		(layer "In6.Cu")
		(net "M_E_CPU1_SB_DQS_DN<3>")
	)
	(segment
		(start 45.23105 -312.512456)
		(end 46.080934 -313.36234)
		(width 0.16002)
		(layer "In6.Cu")
		(net "M_E_CPU1_SB_DQS_DN<3>")
	)
	(segment
		(start 72.17283 -298.577254)
		(end 76.508864 -294.24122)
		(width 0.16002)
		(layer "In6.Cu")
		(net "M_E_CPU1_SB_DQS_DN<3>")
	)
	(segment
		(start 70.305168 -299.968412)
		(end 70.781672 -299.968412)
		(width 0.16002)
		(layer "In6.Cu")
		(net "M_E_CPU1_SB_DQS_DN<3>")
	)
	(segment
		(start 69.823076 -300.450504)
		(end 69.663056 -300.29023)
		(width 0.16002)
		(layer "In6.Cu")
		(net "M_E_CPU1_SB_DQS_DN<3>")
	)
	(segment
		(start 81.214976 -290.830762)
		(end 81.061052 -291.096192)
		(width 0.09525)
		(layer "In6.Cu")
		(net "M_E_CPU1_SB_DQS_DN<3>")
	)
	(segment
		(start 67.136772 -302.590454)
		(end 67.362578 -302.590454)
		(width 0.16002)
		(layer "In6.Cu")
		(net "M_E_CPU1_SB_DQS_DN<3>")
	)
	(segment
		(start 67.04076 -303.23282)
		(end 66.88074 -303.072546)
		(width 0.16002)
		(layer "In6.Cu")
		(net "M_E_CPU1_SB_DQS_DN<3>")
	)
	(segment
		(start 41.114218 -313.678824)
		(end 41.923462 -313.678824)
		(width 0.16002)
		(layer "In6.Cu")
		(net "M_E_CPU1_SB_DQS_DN<3>")
	)
	(segment
		(start 54.08549 -313.687206)
		(end 57.011062 -313.687206)
		(width 0.16002)
		(layer "In6.Cu")
		(net "M_E_CPU1_SB_DQS_DN<3>")
	)
	(segment
		(start 67.999356 -302.750728)
		(end 68.431918 -302.318166)
		(width 0.16002)
		(layer "In6.Cu")
		(net "M_E_CPU1_SB_DQS_DN<3>")
	)
	(segment
		(start 71.214234 -299.059346)
		(end 71.054214 -298.899072)
		(width 0.16002)
		(layer "In6.Cu")
		(net "M_E_CPU1_SB_DQS_DN<3>")
	)
	(segment
		(start 67.04076 -303.709324)
		(end 67.04076 -303.23282)
		(width 0.16002)
		(layer "In6.Cu")
		(net "M_E_CPU1_SB_DQS_DN<3>")
	)
	(segment
		(start 49.479962 -313.674506)
		(end 50.241962 -312.912506)
		(width 0.16002)
		(layer "In6.Cu")
		(net "M_E_CPU1_SB_DQS_DN<3>")
	)
	(segment
		(start 71.696326 -298.577254)
		(end 72.17283 -298.577254)
		(width 0.16002)
		(layer "In6.Cu")
		(net "M_E_CPU1_SB_DQS_DN<3>")
	)
	(segment
		(start 71.214234 -299.53585)
		(end 71.214234 -299.059346)
		(width 0.16002)
		(layer "In6.Cu")
		(net "M_E_CPU1_SB_DQS_DN<3>")
	)
	(segment
		(start 63.45047 -307.731668)
		(end 66.04381 -305.138328)
		(width 0.16002)
		(layer "In6.Cu")
		(net "M_E_CPU1_SB_DQS_DN<3>")
	)
	(segment
		(start 80.301338 -290.766246)
		(end 80.30972 -290.771072)
		(width 0.09525)
		(layer "In6.Cu")
		(net "M_E_CPU1_SB_DQS_DN<3>")
	)
	(segment
		(start 48.559212 -313.36234)
		(end 48.871378 -313.674506)
		(width 0.16002)
		(layer "In6.Cu")
		(net "M_E_CPU1_SB_DQS_DN<3>")
	)
	(segment
		(start 76.508864 -294.24122)
		(end 76.525628 -294.224456)
		(width 0.09525)
		(layer "In6.Cu")
		(net "M_E_CPU1_SB_DQS_DN<3>")
	)
	(segment
		(start 63.45047 -309.042308)
		(end 63.45047 -307.731668)
		(width 0.16002)
		(layer "In6.Cu")
		(net "M_E_CPU1_SB_DQS_DN<3>")
	)
	(segment
		(start 57.874662 -312.823606)
		(end 59.669172 -312.823606)
		(width 0.16002)
		(layer "In6.Cu")
		(net "M_E_CPU1_SB_DQS_DN<3>")
	)
	(segment
		(start 33.442402 -313.692794)
		(end 34.365692 -313.692794)
		(width 0.16002)
		(layer "In6.Cu")
		(net "M_E_CPU1_SB_DQS_DN<3>")
	)
	(segment
		(start 70.781672 -299.968412)
		(end 71.214234 -299.53585)
		(width 0.16002)
		(layer "In6.Cu")
		(net "M_E_CPU1_SB_DQS_DN<3>")
	)
	(segment
		(start 43.57243 -312.512456)
		(end 45.23105 -312.512456)
		(width 0.16002)
		(layer "In6.Cu")
		(net "M_E_CPU1_SB_DQS_DN<3>")
	)
	(segment
		(start 79.368904 -290.771072)
		(end 79.379318 -290.777168)
		(width 0.09525)
		(layer "In6.Cu")
		(net "M_E_CPU1_SB_DQS_DN<3>")
	)
	(segment
		(start 34.365692 -313.692794)
		(end 35.205162 -312.853324)
		(width 0.16002)
		(layer "In6.Cu")
		(net "M_E_CPU1_SB_DQS_DN<3>")
	)
	(segment
		(start 78.991968 -290.771072)
		(end 79.003906 -290.764214)
		(width 0.09525)
		(layer "In6.Cu")
		(net "M_E_CPU1_SB_DQS_DN<3>")
	)
	(segment
		(start 71.054214 -298.673012)
		(end 71.310246 -298.41698)
		(width 0.16002)
		(layer "In6.Cu")
		(net "M_E_CPU1_SB_DQS_DN<3>")
	)
	(segment
		(start 68.271898 -301.681388)
		(end 68.271898 -301.455328)
		(width 0.16002)
		(layer "In6.Cu")
		(net "M_E_CPU1_SB_DQS_DN<3>")
	)
	(segment
		(start 32.28848 -313.36234)
		(end 33.111948 -313.36234)
		(width 0.16002)
		(layer "In6.Cu")
		(net "M_E_CPU1_SB_DQS_DN<3>")
	)
	(segment
		(start 29.252164 -313.78525)
		(end 29.525976 -313.511438)
		(width 0.16002)
		(layer "In6.Cu")
		(net "M_E_CPU1_SB_DQS_DN<3>")
	)
	(segment
		(start 76.525628 -294.224456)
		(end 76.525628 -294.140636)
		(width 0.09525)
		(layer "In6.Cu")
		(net "M_E_CPU1_SB_DQS_DN<3>")
	)
	(segment
		(start 67.522852 -302.750728)
		(end 67.999356 -302.750728)
		(width 0.16002)
		(layer "In6.Cu")
		(net "M_E_CPU1_SB_DQS_DN<3>")
	)
	(segment
		(start 68.271898 -301.455328)
		(end 68.52793 -301.199296)
		(width 0.16002)
		(layer "In6.Cu")
		(net "M_E_CPU1_SB_DQS_DN<3>")
	)
	(segment
		(start 76.525628 -294.140636)
		(end 78.075536 -292.590728)
		(width 0.09525)
		(layer "In6.Cu")
		(net "M_E_CPU1_SB_DQS_DN<3>")
	)
	(segment
		(start 69.663056 -300.29023)
		(end 69.663056 -300.06417)
		(width 0.16002)
		(layer "In6.Cu")
		(net "M_E_CPU1_SB_DQS_DN<3>")
	)
	(segment
		(start 69.663056 -300.06417)
		(end 69.919088 -299.808138)
		(width 0.16002)
		(layer "In6.Cu")
		(net "M_E_CPU1_SB_DQS_DN<3>")
	)
	(segment
		(start 36.036758 -312.512456)
		(end 37.353748 -312.512456)
		(width 0.16002)
		(layer "In6.Cu")
		(net "M_E_CPU1_SB_DQS_DN<3>")
	)
	(segment
		(start 48.871378 -313.674506)
		(end 49.479962 -313.674506)
		(width 0.16002)
		(layer "In6.Cu")
		(net "M_E_CPU1_SB_DQS_DN<3>")
	)
	(segment
		(start 37.353748 -312.512456)
		(end 39.405814 -313.36234)
		(width 0.16002)
		(layer "In6.Cu")
		(net "M_E_CPU1_SB_DQS_DN<3>")
	)
	(segment
		(start 40.797734 -313.36234)
		(end 41.114218 -313.678824)
		(width 0.16002)
		(layer "In6.Cu")
		(net "M_E_CPU1_SB_DQS_DN<3>")
	)
	(arc
		(start 79.003906 -290.764214)
		(mid 79.187287 -290.720383)
		(end 79.368904 -290.771072)
		(width 0.09525)
		(layer "In6.Cu")
		(net "M_E_CPU1_SB_DQS_DN<3>")
	)
	(arc
		(start 80.872584 -290.771072)
		(mid 81.029211 -290.721886)
		(end 81.191862 -290.744148)
		(width 0.09525)
		(layer "In6.Cu")
		(net "M_E_CPU1_SB_DQS_DN<3>")
	)
	(arc
		(start 78.914244 -290.830254)
		(mid 78.951175 -290.798127)
		(end 78.991968 -290.771072)
		(width 0.09525)
		(layer "In6.Cu")
		(net "M_E_CPU1_SB_DQS_DN<3>")
	)
	(arc
		(start 79.379318 -290.777168)
		(mid 79.65648 -290.846968)
		(end 79.932022 -290.771072)
		(width 0.09525)
		(layer "In6.Cu")
		(net "M_E_CPU1_SB_DQS_DN<3>")
	)
	(arc
		(start 80.30972 -290.771072)
		(mid 80.591152 -290.846827)
		(end 80.872584 -290.771072)
		(width 0.09525)
		(layer "In6.Cu")
		(net "M_E_CPU1_SB_DQS_DN<3>")
	)
	(arc
		(start 79.932022 -290.771072)
		(mid 80.116051 -290.720173)
		(end 80.301338 -290.766246)
		(width 0.09525)
		(layer "In6.Cu")
		(net "M_E_CPU1_SB_DQS_DN<3>")
	)
	(segment
		(start 81.527904 -285.970472)
		(end 81.061052 -286.23641)
		(width 0.12954)
		(layer "F.Cu")
		(net "M_E_CPU1_SB_DQS_DN<2>")
	)
	(segment
		(start 35.19424 -303.572164)
		(end 35.643312 -303.572164)
		(width 0.16002)
		(layer "In6.Cu")
		(net "M_E_CPU1_SB_DQS_DN<2>")
	)
	(segment
		(start 52.769262 -304.171858)
		(end 53.249322 -304.171858)
		(width 0.16002)
		(layer "In6.Cu")
		(net "M_E_CPU1_SB_DQS_DN<2>")
	)
	(segment
		(start 56.25084 -304.352452)
		(end 57.017412 -304.352452)
		(width 0.16002)
		(layer "In6.Cu")
		(net "M_E_CPU1_SB_DQS_DN<2>")
	)
	(segment
		(start 47.530258 -304.012346)
		(end 48.537622 -304.012346)
		(width 0.16002)
		(layer "In6.Cu")
		(net "M_E_CPU1_SB_DQS_DN<2>")
	)
	(segment
		(start 76.17587 -286.692594)
		(end 76.199492 -286.692594)
		(width 0.09525)
		(layer "In6.Cu")
		(net "M_E_CPU1_SB_DQS_DN<2>")
	)
	(segment
		(start 34.43224 -304.334164)
		(end 35.19424 -303.572164)
		(width 0.16002)
		(layer "In6.Cu")
		(net "M_E_CPU1_SB_DQS_DN<2>")
	)
	(segment
		(start 61.021468 -301.99203)
		(end 61.91885 -299.825664)
		(width 0.16002)
		(layer "In6.Cu")
		(net "M_E_CPU1_SB_DQS_DN<2>")
	)
	(segment
		(start 41.866312 -304.410364)
		(end 42.742612 -303.534064)
		(width 0.16002)
		(layer "In6.Cu")
		(net "M_E_CPU1_SB_DQS_DN<2>")
	)
	(segment
		(start 49.486312 -304.339752)
		(end 50.248312 -303.577752)
		(width 0.16002)
		(layer "In6.Cu")
		(net "M_E_CPU1_SB_DQS_DN<2>")
	)
	(segment
		(start 56.024526 -304.578766)
		(end 56.25084 -304.352452)
		(width 0.16002)
		(layer "In6.Cu")
		(net "M_E_CPU1_SB_DQS_DN<2>")
	)
	(segment
		(start 44.97705 -303.162462)
		(end 45.248576 -303.433988)
		(width 0.16002)
		(layer "In6.Cu")
		(net "M_E_CPU1_SB_DQS_DN<2>")
	)
	(segment
		(start 37.732208 -304.283364)
		(end 38.72484 -304.283364)
		(width 0.16002)
		(layer "In6.Cu")
		(net "M_E_CPU1_SB_DQS_DN<2>")
	)
	(segment
		(start 43.647614 -303.162462)
		(end 44.97705 -303.162462)
		(width 0.16002)
		(layer "In6.Cu")
		(net "M_E_CPU1_SB_DQS_DN<2>")
	)
	(segment
		(start 51.146202 -303.162462)
		(end 52.25542 -303.162462)
		(width 0.16002)
		(layer "In6.Cu")
		(net "M_E_CPU1_SB_DQS_DN<2>")
	)
	(segment
		(start 47.20844 -304.334164)
		(end 47.530258 -304.012346)
		(width 0.16002)
		(layer "In6.Cu")
		(net "M_E_CPU1_SB_DQS_DN<2>")
	)
	(segment
		(start 67.656964 -293.614094)
		(end 68.260214 -293.614094)
		(width 0.16002)
		(layer "In6.Cu")
		(net "M_E_CPU1_SB_DQS_DN<2>")
	)
	(segment
		(start 39.554912 -304.410364)
		(end 39.95293 -304.012346)
		(width 0.16002)
		(layer "In6.Cu")
		(net "M_E_CPU1_SB_DQS_DN<2>")
	)
	(segment
		(start 29.525976 -304.161444)
		(end 30.770068 -304.161444)
		(width 0.16002)
		(layer "In6.Cu")
		(net "M_E_CPU1_SB_DQS_DN<2>")
	)
	(segment
		(start 54.571646 -304.171858)
		(end 54.978554 -304.578766)
		(width 0.16002)
		(layer "In6.Cu")
		(net "M_E_CPU1_SB_DQS_DN<2>")
	)
	(segment
		(start 33.74644 -304.334164)
		(end 34.43224 -304.334164)
		(width 0.16002)
		(layer "In6.Cu")
		(net "M_E_CPU1_SB_DQS_DN<2>")
	)
	(segment
		(start 70.133972 -291.363146)
		(end 70.133972 -291.137086)
		(width 0.16002)
		(layer "In6.Cu")
		(net "M_E_CPU1_SB_DQS_DN<2>")
	)
	(segment
		(start 54.978554 -304.578766)
		(end 56.024526 -304.578766)
		(width 0.16002)
		(layer "In6.Cu")
		(net "M_E_CPU1_SB_DQS_DN<2>")
	)
	(segment
		(start 38.72484 -304.283364)
		(end 38.85184 -304.410364)
		(width 0.16002)
		(layer "In6.Cu")
		(net "M_E_CPU1_SB_DQS_DN<2>")
	)
	(segment
		(start 81.214976 -285.97098)
		(end 81.061052 -286.23641)
		(width 0.09525)
		(layer "In6.Cu")
		(net "M_E_CPU1_SB_DQS_DN<2>")
	)
	(segment
		(start 67.314572 -293.956486)
		(end 67.656964 -293.614094)
		(width 0.16002)
		(layer "In6.Cu")
		(net "M_E_CPU1_SB_DQS_DN<2>")
	)
	(segment
		(start 77.282294 -286.633666)
		(end 77.928724 -285.987236)
		(width 0.09525)
		(layer "In6.Cu")
		(net "M_E_CPU1_SB_DQS_DN<2>")
	)
	(segment
		(start 43.276012 -303.534064)
		(end 43.647614 -303.162462)
		(width 0.16002)
		(layer "In6.Cu")
		(net "M_E_CPU1_SB_DQS_DN<2>")
	)
	(segment
		(start 69.048122 -292.222936)
		(end 69.651372 -292.222936)
		(width 0.16002)
		(layer "In6.Cu")
		(net "M_E_CPU1_SB_DQS_DN<2>")
	)
	(segment
		(start 53.249322 -304.171858)
		(end 53.366162 -304.288698)
		(width 0.16002)
		(layer "In6.Cu")
		(net "M_E_CPU1_SB_DQS_DN<2>")
	)
	(segment
		(start 71.52513 -289.745928)
		(end 71.926958 -289.3441)
		(width 0.16002)
		(layer "In6.Cu")
		(net "M_E_CPU1_SB_DQS_DN<2>")
	)
	(segment
		(start 53.846222 -304.288698)
		(end 53.963062 -304.171858)
		(width 0.16002)
		(layer "In6.Cu")
		(net "M_E_CPU1_SB_DQS_DN<2>")
	)
	(segment
		(start 79.915258 -285.92145)
		(end 79.93253 -285.911544)
		(width 0.09525)
		(layer "In6.Cu")
		(net "M_E_CPU1_SB_DQS_DN<2>")
	)
	(segment
		(start 52.41544 -303.322482)
		(end 52.41544 -303.818036)
		(width 0.16002)
		(layer "In6.Cu")
		(net "M_E_CPU1_SB_DQS_DN<2>")
	)
	(segment
		(start 71.52513 -289.971988)
		(end 71.52513 -289.745928)
		(width 0.16002)
		(layer "In6.Cu")
		(net "M_E_CPU1_SB_DQS_DN<2>")
	)
	(segment
		(start 77.928724 -285.987236)
		(end 78.711044 -285.987236)
		(width 0.09525)
		(layer "In6.Cu")
		(net "M_E_CPU1_SB_DQS_DN<2>")
	)
	(segment
		(start 68.743068 -293.13124)
		(end 68.742814 -292.754304)
		(width 0.16002)
		(layer "In6.Cu")
		(net "M_E_CPU1_SB_DQS_DN<2>")
	)
	(segment
		(start 45.248576 -303.8729)
		(end 45.70984 -304.334164)
		(width 0.16002)
		(layer "In6.Cu")
		(net "M_E_CPU1_SB_DQS_DN<2>")
	)
	(segment
		(start 71.04253 -290.831778)
		(end 71.525384 -290.348924)
		(width 0.16002)
		(layer "In6.Cu")
		(net "M_E_CPU1_SB_DQS_DN<2>")
	)
	(segment
		(start 37.25164 -303.322482)
		(end 37.25164 -303.802796)
		(width 0.16002)
		(layer "In6.Cu")
		(net "M_E_CPU1_SB_DQS_DN<2>")
	)
	(segment
		(start 59.524646 -303.488852)
		(end 61.021468 -301.99203)
		(width 0.16002)
		(layer "In6.Cu")
		(net "M_E_CPU1_SB_DQS_DN<2>")
	)
	(segment
		(start 50.730912 -303.577752)
		(end 51.146202 -303.162462)
		(width 0.16002)
		(layer "In6.Cu")
		(net "M_E_CPU1_SB_DQS_DN<2>")
	)
	(segment
		(start 70.134226 -291.740082)
		(end 70.133972 -291.363146)
		(width 0.16002)
		(layer "In6.Cu")
		(net "M_E_CPU1_SB_DQS_DN<2>")
	)
	(segment
		(start 33.424622 -304.012346)
		(end 33.74644 -304.334164)
		(width 0.16002)
		(layer "In6.Cu")
		(net "M_E_CPU1_SB_DQS_DN<2>")
	)
	(segment
		(start 32.23133 -304.012346)
		(end 33.424622 -304.012346)
		(width 0.16002)
		(layer "In6.Cu")
		(net "M_E_CPU1_SB_DQS_DN<2>")
	)
	(segment
		(start 66.979292 -294.765222)
		(end 67.314572 -293.956486)
		(width 0.16002)
		(layer "In6.Cu")
		(net "M_E_CPU1_SB_DQS_DN<2>")
	)
	(segment
		(start 45.70984 -304.334164)
		(end 47.20844 -304.334164)
		(width 0.16002)
		(layer "In6.Cu")
		(net "M_E_CPU1_SB_DQS_DN<2>")
	)
	(segment
		(start 57.017412 -304.352452)
		(end 57.881012 -303.488852)
		(width 0.16002)
		(layer "In6.Cu")
		(net "M_E_CPU1_SB_DQS_DN<2>")
	)
	(segment
		(start 48.537622 -304.012346)
		(end 48.865028 -304.339752)
		(width 0.16002)
		(layer "In6.Cu")
		(net "M_E_CPU1_SB_DQS_DN<2>")
	)
	(segment
		(start 39.95293 -304.012346)
		(end 40.435022 -304.012346)
		(width 0.16002)
		(layer "In6.Cu")
		(net "M_E_CPU1_SB_DQS_DN<2>")
	)
	(segment
		(start 70.133972 -291.137086)
		(end 70.43928 -290.831778)
		(width 0.16002)
		(layer "In6.Cu")
		(net "M_E_CPU1_SB_DQS_DN<2>")
	)
	(segment
		(start 76.199492 -286.692594)
		(end 76.25842 -286.633666)
		(width 0.09525)
		(layer "In6.Cu")
		(net "M_E_CPU1_SB_DQS_DN<2>")
	)
	(segment
		(start 37.09162 -303.162462)
		(end 37.25164 -303.322482)
		(width 0.16002)
		(layer "In6.Cu")
		(net "M_E_CPU1_SB_DQS_DN<2>")
	)
	(segment
		(start 29.252164 -304.435256)
		(end 29.525976 -304.161444)
		(width 0.16002)
		(layer "In6.Cu")
		(net "M_E_CPU1_SB_DQS_DN<2>")
	)
	(segment
		(start 68.260214 -293.614094)
		(end 68.743068 -293.13124)
		(width 0.16002)
		(layer "In6.Cu")
		(net "M_E_CPU1_SB_DQS_DN<2>")
	)
	(segment
		(start 40.83304 -304.410364)
		(end 41.866312 -304.410364)
		(width 0.16002)
		(layer "In6.Cu")
		(net "M_E_CPU1_SB_DQS_DN<2>")
	)
	(segment
		(start 30.770068 -304.161444)
		(end 31.018988 -304.410364)
		(width 0.16002)
		(layer "In6.Cu")
		(net "M_E_CPU1_SB_DQS_DN<2>")
	)
	(segment
		(start 35.643312 -303.572164)
		(end 36.053014 -303.162462)
		(width 0.16002)
		(layer "In6.Cu")
		(net "M_E_CPU1_SB_DQS_DN<2>")
	)
	(segment
		(start 68.742814 -292.754304)
		(end 68.742814 -292.528244)
		(width 0.16002)
		(layer "In6.Cu")
		(net "M_E_CPU1_SB_DQS_DN<2>")
	)
	(segment
		(start 53.963062 -304.171858)
		(end 54.571646 -304.171858)
		(width 0.16002)
		(layer "In6.Cu")
		(net "M_E_CPU1_SB_DQS_DN<2>")
	)
	(segment
		(start 79.358998 -285.905448)
		(end 79.36992 -285.911798)
		(width 0.09525)
		(layer "In6.Cu")
		(net "M_E_CPU1_SB_DQS_DN<2>")
	)
	(segment
		(start 73.181718 -289.3441)
		(end 75.833224 -286.692594)
		(width 0.16002)
		(layer "In6.Cu")
		(net "M_E_CPU1_SB_DQS_DN<2>")
	)
	(segment
		(start 69.651372 -292.222936)
		(end 70.134226 -291.740082)
		(width 0.16002)
		(layer "In6.Cu")
		(net "M_E_CPU1_SB_DQS_DN<2>")
	)
	(segment
		(start 71.926958 -289.3441)
		(end 73.181718 -289.3441)
		(width 0.16002)
		(layer "In6.Cu")
		(net "M_E_CPU1_SB_DQS_DN<2>")
	)
	(segment
		(start 42.742612 -303.534064)
		(end 43.276012 -303.534064)
		(width 0.16002)
		(layer "In6.Cu")
		(net "M_E_CPU1_SB_DQS_DN<2>")
	)
	(segment
		(start 52.41544 -303.818036)
		(end 52.769262 -304.171858)
		(width 0.16002)
		(layer "In6.Cu")
		(net "M_E_CPU1_SB_DQS_DN<2>")
	)
	(segment
		(start 36.053014 -303.162462)
		(end 37.09162 -303.162462)
		(width 0.16002)
		(layer "In6.Cu")
		(net "M_E_CPU1_SB_DQS_DN<2>")
	)
	(segment
		(start 52.25542 -303.162462)
		(end 52.41544 -303.322482)
		(width 0.16002)
		(layer "In6.Cu")
		(net "M_E_CPU1_SB_DQS_DN<2>")
	)
	(segment
		(start 48.865028 -304.339752)
		(end 49.486312 -304.339752)
		(width 0.16002)
		(layer "In6.Cu")
		(net "M_E_CPU1_SB_DQS_DN<2>")
	)
	(segment
		(start 79.93253 -285.911544)
		(end 79.9465 -285.90367)
		(width 0.09525)
		(layer "In6.Cu")
		(net "M_E_CPU1_SB_DQS_DN<2>")
	)
	(segment
		(start 38.85184 -304.410364)
		(end 39.554912 -304.410364)
		(width 0.16002)
		(layer "In6.Cu")
		(net "M_E_CPU1_SB_DQS_DN<2>")
	)
	(segment
		(start 53.366162 -304.288698)
		(end 53.846222 -304.288698)
		(width 0.16002)
		(layer "In6.Cu")
		(net "M_E_CPU1_SB_DQS_DN<2>")
	)
	(segment
		(start 31.833312 -304.410364)
		(end 32.23133 -304.012346)
		(width 0.16002)
		(layer "In6.Cu")
		(net "M_E_CPU1_SB_DQS_DN<2>")
	)
	(segment
		(start 50.248312 -303.577752)
		(end 50.730912 -303.577752)
		(width 0.16002)
		(layer "In6.Cu")
		(net "M_E_CPU1_SB_DQS_DN<2>")
	)
	(segment
		(start 57.881012 -303.488852)
		(end 59.524646 -303.488852)
		(width 0.16002)
		(layer "In6.Cu")
		(net "M_E_CPU1_SB_DQS_DN<2>")
	)
	(segment
		(start 76.25842 -286.633666)
		(end 77.282294 -286.633666)
		(width 0.09525)
		(layer "In6.Cu")
		(net "M_E_CPU1_SB_DQS_DN<2>")
	)
	(segment
		(start 71.525384 -290.348924)
		(end 71.52513 -289.971988)
		(width 0.16002)
		(layer "In6.Cu")
		(net "M_E_CPU1_SB_DQS_DN<2>")
	)
	(segment
		(start 37.25164 -303.802796)
		(end 37.732208 -304.283364)
		(width 0.16002)
		(layer "In6.Cu")
		(net "M_E_CPU1_SB_DQS_DN<2>")
	)
	(segment
		(start 45.248576 -303.433988)
		(end 45.248576 -303.8729)
		(width 0.16002)
		(layer "In6.Cu")
		(net "M_E_CPU1_SB_DQS_DN<2>")
	)
	(segment
		(start 75.833224 -286.692594)
		(end 76.17587 -286.692594)
		(width 0.16002)
		(layer "In6.Cu")
		(net "M_E_CPU1_SB_DQS_DN<2>")
	)
	(segment
		(start 81.191862 -285.884366)
		(end 81.214976 -285.97098)
		(width 0.09525)
		(layer "In6.Cu")
		(net "M_E_CPU1_SB_DQS_DN<2>")
	)
	(segment
		(start 68.742814 -292.528244)
		(end 69.048122 -292.222936)
		(width 0.16002)
		(layer "In6.Cu")
		(net "M_E_CPU1_SB_DQS_DN<2>")
	)
	(segment
		(start 70.43928 -290.831778)
		(end 71.04253 -290.831778)
		(width 0.16002)
		(layer "In6.Cu")
		(net "M_E_CPU1_SB_DQS_DN<2>")
	)
	(segment
		(start 31.018988 -304.410364)
		(end 31.833312 -304.410364)
		(width 0.16002)
		(layer "In6.Cu")
		(net "M_E_CPU1_SB_DQS_DN<2>")
	)
	(segment
		(start 40.435022 -304.012346)
		(end 40.83304 -304.410364)
		(width 0.16002)
		(layer "In6.Cu")
		(net "M_E_CPU1_SB_DQS_DN<2>")
	)
	(segment
		(start 61.91885 -299.825664)
		(end 66.979292 -294.765222)
		(width 0.16002)
		(layer "In6.Cu")
		(net "M_E_CPU1_SB_DQS_DN<2>")
	)
	(arc
		(start 78.992476 -285.911544)
		(mid 79.174944 -285.860826)
		(end 79.358998 -285.905448)
		(width 0.09525)
		(layer "In6.Cu")
		(net "M_E_CPU1_SB_DQS_DN<2>")
	)
	(arc
		(start 78.711044 -285.987236)
		(mid 78.856761 -285.967984)
		(end 78.992476 -285.911544)
		(width 0.09525)
		(layer "In6.Cu")
		(net "M_E_CPU1_SB_DQS_DN<2>")
	)
	(arc
		(start 80.30972 -285.91129)
		(mid 80.591152 -285.987045)
		(end 80.872584 -285.91129)
		(width 0.09525)
		(layer "In6.Cu")
		(net "M_E_CPU1_SB_DQS_DN<2>")
	)
	(arc
		(start 80.872584 -285.91129)
		(mid 81.029211 -285.862104)
		(end 81.191862 -285.884366)
		(width 0.09525)
		(layer "In6.Cu")
		(net "M_E_CPU1_SB_DQS_DN<2>")
	)
	(arc
		(start 79.36992 -285.911798)
		(mid 79.641347 -285.987464)
		(end 79.915258 -285.92145)
		(width 0.09525)
		(layer "In6.Cu")
		(net "M_E_CPU1_SB_DQS_DN<2>")
	)
	(arc
		(start 79.9465 -285.90367)
		(mid 80.129098 -285.860654)
		(end 80.30972 -285.91129)
		(width 0.09525)
		(layer "In6.Cu")
		(net "M_E_CPU1_SB_DQS_DN<2>")
	)
	(segment
		(start 81.527904 -281.110436)
		(end 81.061052 -281.376374)
		(width 0.12954)
		(layer "F.Cu")
		(net "M_E_CPU1_SB_DQS_DN<1>")
	)
	(segment
		(start 67.342258 -286.076644)
		(end 67.342258 -285.500572)
		(width 0.16002)
		(layer "In6.Cu")
		(net "M_E_CPU1_SB_DQS_DN<1>")
	)
	(segment
		(start 65.454784 -287.964118)
		(end 65.9511 -287.467802)
		(width 0.16002)
		(layer "In6.Cu")
		(net "M_E_CPU1_SB_DQS_DN<1>")
	)
	(segment
		(start 70.443344 -282.399486)
		(end 71.019416 -282.399486)
		(width 0.16002)
		(layer "In6.Cu")
		(net "M_E_CPU1_SB_DQS_DN<1>")
	)
	(segment
		(start 58.593228 -294.123618)
		(end 58.710068 -294.240458)
		(width 0.16002)
		(layer "In6.Cu")
		(net "M_E_CPU1_SB_DQS_DN<1>")
	)
	(segment
		(start 36.034218 -293.812468)
		(end 37.58057 -293.812468)
		(width 0.16002)
		(layer "In6.Cu")
		(net "M_E_CPU1_SB_DQS_DN<1>")
	)
	(segment
		(start 62.19571 -290.64712)
		(end 64.878712 -287.964118)
		(width 0.16002)
		(layer "In6.Cu")
		(net "M_E_CPU1_SB_DQS_DN<1>")
	)
	(segment
		(start 75.979528 -281.083004)
		(end 76.038456 -281.024076)
		(width 0.09525)
		(layer "In6.Cu")
		(net "M_E_CPU1_SB_DQS_DN<1>")
	)
	(segment
		(start 76.348844 -281.024076)
		(end 76.648564 -280.724356)
		(width 0.09525)
		(layer "In6.Cu")
		(net "M_E_CPU1_SB_DQS_DN<1>")
	)
	(segment
		(start 54.03215 -294.941752)
		(end 54.560216 -294.413686)
		(width 0.16002)
		(layer "In6.Cu")
		(net "M_E_CPU1_SB_DQS_DN<1>")
	)
	(segment
		(start 39.545768 -294.920924)
		(end 39.80434 -294.662352)
		(width 0.16002)
		(layer "In6.Cu")
		(net "M_E_CPU1_SB_DQS_DN<1>")
	)
	(segment
		(start 68.733416 -284.685486)
		(end 68.733416 -284.109414)
		(width 0.16002)
		(layer "In6.Cu")
		(net "M_E_CPU1_SB_DQS_DN<1>")
	)
	(segment
		(start 71.019416 -282.399486)
		(end 71.515732 -281.90317)
		(width 0.16002)
		(layer "In6.Cu")
		(net "M_E_CPU1_SB_DQS_DN<1>")
	)
	(segment
		(start 35.675062 -294.171624)
		(end 36.034218 -293.812468)
		(width 0.16002)
		(layer "In6.Cu")
		(net "M_E_CPU1_SB_DQS_DN<1>")
	)
	(segment
		(start 58.710068 -294.240458)
		(end 59.190128 -294.240458)
		(width 0.16002)
		(layer "In6.Cu")
		(net "M_E_CPU1_SB_DQS_DN<1>")
	)
	(segment
		(start 34.388298 -294.971724)
		(end 35.188398 -294.171624)
		(width 0.16002)
		(layer "In6.Cu")
		(net "M_E_CPU1_SB_DQS_DN<1>")
	)
	(segment
		(start 42.736262 -294.171624)
		(end 43.320462 -294.171624)
		(width 0.16002)
		(layer "In6.Cu")
		(net "M_E_CPU1_SB_DQS_DN<1>")
	)
	(segment
		(start 81.214976 -281.110944)
		(end 81.061052 -281.376374)
		(width 0.09525)
		(layer "In6.Cu")
		(net "M_E_CPU1_SB_DQS_DN<1>")
	)
	(segment
		(start 43.679618 -293.812468)
		(end 44.58208 -293.812468)
		(width 0.16002)
		(layer "In6.Cu")
		(net "M_E_CPU1_SB_DQS_DN<1>")
	)
	(segment
		(start 54.560216 -294.413686)
		(end 55.20563 -294.413686)
		(width 0.16002)
		(layer "In6.Cu")
		(net "M_E_CPU1_SB_DQS_DN<1>")
	)
	(segment
		(start 48.65116 -295.31564)
		(end 49.22012 -295.31564)
		(width 0.16002)
		(layer "In6.Cu")
		(net "M_E_CPU1_SB_DQS_DN<1>")
	)
	(segment
		(start 76.648564 -280.724356)
		(end 78.076552 -280.724356)
		(width 0.09525)
		(layer "In6.Cu")
		(net "M_E_CPU1_SB_DQS_DN<1>")
	)
	(segment
		(start 71.759826 -281.083004)
		(end 75.955906 -281.083004)
		(width 0.16002)
		(layer "In6.Cu")
		(net "M_E_CPU1_SB_DQS_DN<1>")
	)
	(segment
		(start 64.878712 -287.964118)
		(end 65.454784 -287.964118)
		(width 0.16002)
		(layer "In6.Cu")
		(net "M_E_CPU1_SB_DQS_DN<1>")
	)
	(segment
		(start 56.820816 -295.177464)
		(end 57.874662 -294.123618)
		(width 0.16002)
		(layer "In6.Cu")
		(net "M_E_CPU1_SB_DQS_DN<1>")
	)
	(segment
		(start 69.052186 -283.790644)
		(end 69.628258 -283.790644)
		(width 0.16002)
		(layer "In6.Cu")
		(net "M_E_CPU1_SB_DQS_DN<1>")
	)
	(segment
		(start 65.9511 -287.467802)
		(end 65.9511 -286.89173)
		(width 0.16002)
		(layer "In6.Cu")
		(net "M_E_CPU1_SB_DQS_DN<1>")
	)
	(segment
		(start 40.606218 -294.662352)
		(end 40.966136 -295.02227)
		(width 0.16002)
		(layer "In6.Cu")
		(net "M_E_CPU1_SB_DQS_DN<1>")
	)
	(segment
		(start 45.690536 -294.920924)
		(end 46.952154 -294.920924)
		(width 0.16002)
		(layer "In6.Cu")
		(net "M_E_CPU1_SB_DQS_DN<1>")
	)
	(segment
		(start 29.525976 -294.81145)
		(end 31.057596 -294.81145)
		(width 0.16002)
		(layer "In6.Cu")
		(net "M_E_CPU1_SB_DQS_DN<1>")
	)
	(segment
		(start 65.9511 -286.89173)
		(end 66.26987 -286.57296)
		(width 0.16002)
		(layer "In6.Cu")
		(net "M_E_CPU1_SB_DQS_DN<1>")
	)
	(segment
		(start 43.320462 -294.171624)
		(end 43.679618 -293.812468)
		(width 0.16002)
		(layer "In6.Cu")
		(net "M_E_CPU1_SB_DQS_DN<1>")
	)
	(segment
		(start 37.78377 -294.507412)
		(end 38.197282 -294.920924)
		(width 0.16002)
		(layer "In6.Cu")
		(net "M_E_CPU1_SB_DQS_DN<1>")
	)
	(segment
		(start 39.80434 -294.662352)
		(end 40.606218 -294.662352)
		(width 0.16002)
		(layer "In6.Cu")
		(net "M_E_CPU1_SB_DQS_DN<1>")
	)
	(segment
		(start 59.787028 -294.123618)
		(end 62.19571 -291.714936)
		(width 0.16002)
		(layer "In6.Cu")
		(net "M_E_CPU1_SB_DQS_DN<1>")
	)
	(segment
		(start 37.78377 -294.015668)
		(end 37.78377 -294.507412)
		(width 0.16002)
		(layer "In6.Cu")
		(net "M_E_CPU1_SB_DQS_DN<1>")
	)
	(segment
		(start 70.124574 -283.294328)
		(end 70.124574 -282.718256)
		(width 0.16002)
		(layer "In6.Cu")
		(net "M_E_CPU1_SB_DQS_DN<1>")
	)
	(segment
		(start 47.997872 -294.662352)
		(end 48.65116 -295.31564)
		(width 0.16002)
		(layer "In6.Cu")
		(net "M_E_CPU1_SB_DQS_DN<1>")
	)
	(segment
		(start 46.952154 -294.920924)
		(end 47.210726 -294.662352)
		(width 0.16002)
		(layer "In6.Cu")
		(net "M_E_CPU1_SB_DQS_DN<1>")
	)
	(segment
		(start 55.20563 -294.413686)
		(end 55.969408 -295.177464)
		(width 0.16002)
		(layer "In6.Cu")
		(net "M_E_CPU1_SB_DQS_DN<1>")
	)
	(segment
		(start 59.306968 -294.123618)
		(end 59.787028 -294.123618)
		(width 0.16002)
		(layer "In6.Cu")
		(net "M_E_CPU1_SB_DQS_DN<1>")
	)
	(segment
		(start 81.191862 -281.02433)
		(end 81.214976 -281.110944)
		(width 0.09525)
		(layer "In6.Cu")
		(net "M_E_CPU1_SB_DQS_DN<1>")
	)
	(segment
		(start 38.197282 -294.920924)
		(end 39.545768 -294.920924)
		(width 0.16002)
		(layer "In6.Cu")
		(net "M_E_CPU1_SB_DQS_DN<1>")
	)
	(segment
		(start 67.342258 -285.500572)
		(end 67.661028 -285.181802)
		(width 0.16002)
		(layer "In6.Cu")
		(net "M_E_CPU1_SB_DQS_DN<1>")
	)
	(segment
		(start 59.190128 -294.240458)
		(end 59.306968 -294.123618)
		(width 0.16002)
		(layer "In6.Cu")
		(net "M_E_CPU1_SB_DQS_DN<1>")
	)
	(segment
		(start 31.29407 -295.047924)
		(end 31.98876 -295.047924)
		(width 0.16002)
		(layer "In6.Cu")
		(net "M_E_CPU1_SB_DQS_DN<1>")
	)
	(segment
		(start 66.26987 -286.57296)
		(end 66.845942 -286.57296)
		(width 0.16002)
		(layer "In6.Cu")
		(net "M_E_CPU1_SB_DQS_DN<1>")
	)
	(segment
		(start 70.124574 -282.718256)
		(end 70.443344 -282.399486)
		(width 0.16002)
		(layer "In6.Cu")
		(net "M_E_CPU1_SB_DQS_DN<1>")
	)
	(segment
		(start 53.3908 -294.941752)
		(end 54.03215 -294.941752)
		(width 0.16002)
		(layer "In6.Cu")
		(net "M_E_CPU1_SB_DQS_DN<1>")
	)
	(segment
		(start 47.210726 -294.662352)
		(end 47.997872 -294.662352)
		(width 0.16002)
		(layer "In6.Cu")
		(net "M_E_CPU1_SB_DQS_DN<1>")
	)
	(segment
		(start 37.58057 -293.812468)
		(end 37.78377 -294.015668)
		(width 0.16002)
		(layer "In6.Cu")
		(net "M_E_CPU1_SB_DQS_DN<1>")
	)
	(segment
		(start 78.076552 -280.724356)
		(end 78.314804 -280.962608)
		(width 0.09525)
		(layer "In6.Cu")
		(net "M_E_CPU1_SB_DQS_DN<1>")
	)
	(segment
		(start 50.323242 -294.212518)
		(end 50.724562 -294.212518)
		(width 0.16002)
		(layer "In6.Cu")
		(net "M_E_CPU1_SB_DQS_DN<1>")
	)
	(segment
		(start 71.515732 -281.90317)
		(end 71.515732 -281.327098)
		(width 0.16002)
		(layer "In6.Cu")
		(net "M_E_CPU1_SB_DQS_DN<1>")
	)
	(segment
		(start 35.188398 -294.171624)
		(end 35.675062 -294.171624)
		(width 0.16002)
		(layer "In6.Cu")
		(net "M_E_CPU1_SB_DQS_DN<1>")
	)
	(segment
		(start 62.19571 -291.714936)
		(end 62.19571 -290.64712)
		(width 0.16002)
		(layer "In6.Cu")
		(net "M_E_CPU1_SB_DQS_DN<1>")
	)
	(segment
		(start 31.98876 -295.047924)
		(end 32.374332 -294.662352)
		(width 0.16002)
		(layer "In6.Cu")
		(net "M_E_CPU1_SB_DQS_DN<1>")
	)
	(segment
		(start 33.451292 -294.662352)
		(end 33.760664 -294.971724)
		(width 0.16002)
		(layer "In6.Cu")
		(net "M_E_CPU1_SB_DQS_DN<1>")
	)
	(segment
		(start 76.038456 -281.024076)
		(end 76.348844 -281.024076)
		(width 0.09525)
		(layer "In6.Cu")
		(net "M_E_CPU1_SB_DQS_DN<1>")
	)
	(segment
		(start 69.628258 -283.790644)
		(end 70.124574 -283.294328)
		(width 0.16002)
		(layer "In6.Cu")
		(net "M_E_CPU1_SB_DQS_DN<1>")
	)
	(segment
		(start 31.057596 -294.81145)
		(end 31.29407 -295.047924)
		(width 0.16002)
		(layer "In6.Cu")
		(net "M_E_CPU1_SB_DQS_DN<1>")
	)
	(segment
		(start 66.845942 -286.57296)
		(end 67.342258 -286.076644)
		(width 0.16002)
		(layer "In6.Cu")
		(net "M_E_CPU1_SB_DQS_DN<1>")
	)
	(segment
		(start 49.22012 -295.31564)
		(end 50.323242 -294.212518)
		(width 0.16002)
		(layer "In6.Cu")
		(net "M_E_CPU1_SB_DQS_DN<1>")
	)
	(segment
		(start 50.724562 -294.212518)
		(end 51.124612 -293.812468)
		(width 0.16002)
		(layer "In6.Cu")
		(net "M_E_CPU1_SB_DQS_DN<1>")
	)
	(segment
		(start 40.966136 -295.02227)
		(end 41.885616 -295.02227)
		(width 0.16002)
		(layer "In6.Cu")
		(net "M_E_CPU1_SB_DQS_DN<1>")
	)
	(segment
		(start 55.969408 -295.177464)
		(end 56.820816 -295.177464)
		(width 0.16002)
		(layer "In6.Cu")
		(net "M_E_CPU1_SB_DQS_DN<1>")
	)
	(segment
		(start 51.124612 -293.812468)
		(end 52.261516 -293.812468)
		(width 0.16002)
		(layer "In6.Cu")
		(net "M_E_CPU1_SB_DQS_DN<1>")
	)
	(segment
		(start 67.661028 -285.181802)
		(end 68.2371 -285.181802)
		(width 0.16002)
		(layer "In6.Cu")
		(net "M_E_CPU1_SB_DQS_DN<1>")
	)
	(segment
		(start 78.429866 -281.051254)
		(end 78.444598 -281.05989)
		(width 0.09525)
		(layer "In6.Cu")
		(net "M_E_CPU1_SB_DQS_DN<1>")
	)
	(segment
		(start 33.760664 -294.971724)
		(end 34.388298 -294.971724)
		(width 0.16002)
		(layer "In6.Cu")
		(net "M_E_CPU1_SB_DQS_DN<1>")
	)
	(segment
		(start 68.2371 -285.181802)
		(end 68.733416 -284.685486)
		(width 0.16002)
		(layer "In6.Cu")
		(net "M_E_CPU1_SB_DQS_DN<1>")
	)
	(segment
		(start 57.874662 -294.123618)
		(end 58.593228 -294.123618)
		(width 0.16002)
		(layer "In6.Cu")
		(net "M_E_CPU1_SB_DQS_DN<1>")
	)
	(segment
		(start 68.733416 -284.109414)
		(end 69.052186 -283.790644)
		(width 0.16002)
		(layer "In6.Cu")
		(net "M_E_CPU1_SB_DQS_DN<1>")
	)
	(segment
		(start 75.955906 -281.083004)
		(end 75.979528 -281.083004)
		(width 0.09525)
		(layer "In6.Cu")
		(net "M_E_CPU1_SB_DQS_DN<1>")
	)
	(segment
		(start 32.374332 -294.662352)
		(end 33.451292 -294.662352)
		(width 0.16002)
		(layer "In6.Cu")
		(net "M_E_CPU1_SB_DQS_DN<1>")
	)
	(segment
		(start 41.885616 -295.02227)
		(end 42.736262 -294.171624)
		(width 0.16002)
		(layer "In6.Cu")
		(net "M_E_CPU1_SB_DQS_DN<1>")
	)
	(segment
		(start 44.58208 -293.812468)
		(end 45.690536 -294.920924)
		(width 0.16002)
		(layer "In6.Cu")
		(net "M_E_CPU1_SB_DQS_DN<1>")
	)
	(segment
		(start 71.515732 -281.327098)
		(end 71.759826 -281.083004)
		(width 0.16002)
		(layer "In6.Cu")
		(net "M_E_CPU1_SB_DQS_DN<1>")
	)
	(segment
		(start 79.361538 -281.046428)
		(end 79.36992 -281.051254)
		(width 0.09525)
		(layer "In6.Cu")
		(net "M_E_CPU1_SB_DQS_DN<1>")
	)
	(segment
		(start 52.261516 -293.812468)
		(end 53.3908 -294.941752)
		(width 0.16002)
		(layer "In6.Cu")
		(net "M_E_CPU1_SB_DQS_DN<1>")
	)
	(segment
		(start 29.252164 -295.085262)
		(end 29.525976 -294.81145)
		(width 0.16002)
		(layer "In6.Cu")
		(net "M_E_CPU1_SB_DQS_DN<1>")
	)
	(segment
		(start 79.93253 -281.051254)
		(end 79.940912 -281.046428)
		(width 0.09525)
		(layer "In6.Cu")
		(net "M_E_CPU1_SB_DQS_DN<1>")
	)
	(segment
		(start 79.922116 -281.05735)
		(end 79.93253 -281.051254)
		(width 0.09525)
		(layer "In6.Cu")
		(net "M_E_CPU1_SB_DQS_DN<1>")
	)
	(arc
		(start 80.872584 -281.051254)
		(mid 81.029211 -281.002068)
		(end 81.191862 -281.02433)
		(width 0.09525)
		(layer "In6.Cu")
		(net "M_E_CPU1_SB_DQS_DN<1>")
	)
	(arc
		(start 79.940912 -281.046428)
		(mid 80.125944 -281.000514)
		(end 80.30972 -281.051254)
		(width 0.09525)
		(layer "In6.Cu")
		(net "M_E_CPU1_SB_DQS_DN<1>")
	)
	(arc
		(start 78.444598 -281.05989)
		(mid 78.719803 -281.127154)
		(end 78.99273 -281.051254)
		(width 0.09525)
		(layer "In6.Cu")
		(net "M_E_CPU1_SB_DQS_DN<1>")
	)
	(arc
		(start 80.30972 -281.051254)
		(mid 80.591152 -281.127009)
		(end 80.872584 -281.051254)
		(width 0.09525)
		(layer "In6.Cu")
		(net "M_E_CPU1_SB_DQS_DN<1>")
	)
	(arc
		(start 78.99273 -281.051254)
		(mid 79.176505 -281.000482)
		(end 79.361538 -281.046428)
		(width 0.09525)
		(layer "In6.Cu")
		(net "M_E_CPU1_SB_DQS_DN<1>")
	)
	(arc
		(start 79.36992 -281.051254)
		(mid 79.645209 -281.126975)
		(end 79.922116 -281.05735)
		(width 0.09525)
		(layer "In6.Cu")
		(net "M_E_CPU1_SB_DQS_DN<1>")
	)
	(arc
		(start 78.314804 -280.962608)
		(mid 78.369452 -281.010673)
		(end 78.429866 -281.051254)
		(width 0.09525)
		(layer "In6.Cu")
		(net "M_E_CPU1_SB_DQS_DN<1>")
	)
	(segment
		(start 81.527904 -276.2504)
		(end 81.061052 -276.516338)
		(width 0.12954)
		(layer "F.Cu")
		(net "M_E_CPU1_SB_DQS_DN<0>")
	)
	(segment
		(start 67.465194 -276.210268)
		(end 67.802252 -276.547326)
		(width 0.16002)
		(layer "In6.Cu")
		(net "M_E_CPU1_SB_DQS_DN<0>")
	)
	(segment
		(start 56.630062 -286.018224)
		(end 57.874662 -284.773624)
		(width 0.16002)
		(layer "In6.Cu")
		(net "M_E_CPU1_SB_DQS_DN<0>")
	)
	(segment
		(start 50.724562 -284.862524)
		(end 51.124612 -284.462474)
		(width 0.16002)
		(layer "In6.Cu")
		(net "M_E_CPU1_SB_DQS_DN<0>")
	)
	(segment
		(start 67.802252 -276.547326)
		(end 68.413376 -276.547326)
		(width 0.16002)
		(layer "In6.Cu")
		(net "M_E_CPU1_SB_DQS_DN<0>")
	)
	(segment
		(start 59.089036 -284.773624)
		(end 60.735464 -284.091634)
		(width 0.16002)
		(layer "In6.Cu")
		(net "M_E_CPU1_SB_DQS_DN<0>")
	)
	(segment
		(start 30.539182 -285.461456)
		(end 30.68828 -285.312358)
		(width 0.16002)
		(layer "In6.Cu")
		(net "M_E_CPU1_SB_DQS_DN<0>")
	)
	(segment
		(start 66.651124 -277.827232)
		(end 66.651124 -277.350728)
		(width 0.16002)
		(layer "In6.Cu")
		(net "M_E_CPU1_SB_DQS_DN<0>")
	)
	(segment
		(start 54.677818 -285.408624)
		(end 55.287418 -286.018224)
		(width 0.16002)
		(layer "In6.Cu")
		(net "M_E_CPU1_SB_DQS_DN<0>")
	)
	(segment
		(start 78.019656 -276.26691)
		(end 79.651352 -276.26691)
		(width 0.09525)
		(layer "In6.Cu")
		(net "M_E_CPU1_SB_DQS_DN<0>")
	)
	(segment
		(start 33.752536 -285.624524)
		(end 34.417762 -285.624524)
		(width 0.16002)
		(layer "In6.Cu")
		(net "M_E_CPU1_SB_DQS_DN<0>")
	)
	(segment
		(start 31.37408 -285.312358)
		(end 31.49092 -285.429198)
		(width 0.16002)
		(layer "In6.Cu")
		(net "M_E_CPU1_SB_DQS_DN<0>")
	)
	(segment
		(start 41.91889 -285.649924)
		(end 42.70629 -284.862524)
		(width 0.16002)
		(layer "In6.Cu")
		(net "M_E_CPU1_SB_DQS_DN<0>")
	)
	(segment
		(start 30.68828 -285.312358)
		(end 31.37408 -285.312358)
		(width 0.16002)
		(layer "In6.Cu")
		(net "M_E_CPU1_SB_DQS_DN<0>")
	)
	(segment
		(start 63.560198 -280.063448)
		(end 63.560198 -279.710642)
		(width 0.16002)
		(layer "In6.Cu")
		(net "M_E_CPU1_SB_DQS_DN<0>")
	)
	(segment
		(start 65.259966 -279.21839)
		(end 65.259966 -278.741886)
		(width 0.16002)
		(layer "In6.Cu")
		(net "M_E_CPU1_SB_DQS_DN<0>")
	)
	(segment
		(start 35.717226 -284.764988)
		(end 36.01974 -284.462474)
		(width 0.16002)
		(layer "In6.Cu")
		(net "M_E_CPU1_SB_DQS_DN<0>")
	)
	(segment
		(start 60.735464 -284.091634)
		(end 62.50686 -282.320238)
		(width 0.16002)
		(layer "In6.Cu")
		(net "M_E_CPU1_SB_DQS_DN<0>")
	)
	(segment
		(start 52.2351 -284.462474)
		(end 53.18125 -285.408624)
		(width 0.16002)
		(layer "In6.Cu")
		(net "M_E_CPU1_SB_DQS_DN<0>")
	)
	(segment
		(start 48.84039 -285.624524)
		(end 49.479962 -285.624524)
		(width 0.16002)
		(layer "In6.Cu")
		(net "M_E_CPU1_SB_DQS_DN<0>")
	)
	(segment
		(start 66.74485 -275.78431)
		(end 67.069716 -275.459444)
		(width 0.16002)
		(layer "In6.Cu")
		(net "M_E_CPU1_SB_DQS_DN<0>")
	)
	(segment
		(start 64.350392 -279.65146)
		(end 64.826896 -279.65146)
		(width 0.16002)
		(layer "In6.Cu")
		(net "M_E_CPU1_SB_DQS_DN<0>")
	)
	(segment
		(start 36.01974 -284.462474)
		(end 37.11194 -284.462474)
		(width 0.16002)
		(layer "In6.Cu")
		(net "M_E_CPU1_SB_DQS_DN<0>")
	)
	(segment
		(start 62.50686 -281.116786)
		(end 63.560198 -280.063448)
		(width 0.16002)
		(layer "In6.Cu")
		(net "M_E_CPU1_SB_DQS_DN<0>")
	)
	(segment
		(start 65.489074 -278.007826)
		(end 65.74155 -278.260302)
		(width 0.16002)
		(layer "In6.Cu")
		(net "M_E_CPU1_SB_DQS_DN<0>")
	)
	(segment
		(start 57.874662 -284.773624)
		(end 59.089036 -284.773624)
		(width 0.16002)
		(layer "In6.Cu")
		(net "M_E_CPU1_SB_DQS_DN<0>")
	)
	(segment
		(start 29.525976 -285.461456)
		(end 30.539182 -285.461456)
		(width 0.16002)
		(layer "In6.Cu")
		(net "M_E_CPU1_SB_DQS_DN<0>")
	)
	(segment
		(start 79.93253 -276.191218)
		(end 79.940912 -276.186392)
		(width 0.09525)
		(layer "In6.Cu")
		(net "M_E_CPU1_SB_DQS_DN<0>")
	)
	(segment
		(start 68.750434 -276.210268)
		(end 68.750434 -275.619464)
		(width 0.16002)
		(layer "In6.Cu")
		(net "M_E_CPU1_SB_DQS_DN<0>")
	)
	(segment
		(start 63.871856 -279.398984)
		(end 64.097916 -279.398984)
		(width 0.16002)
		(layer "In6.Cu")
		(net "M_E_CPU1_SB_DQS_DN<0>")
	)
	(segment
		(start 64.826896 -279.65146)
		(end 65.259966 -279.21839)
		(width 0.16002)
		(layer "In6.Cu")
		(net "M_E_CPU1_SB_DQS_DN<0>")
	)
	(segment
		(start 42.70629 -284.862524)
		(end 43.21429 -284.862524)
		(width 0.16002)
		(layer "In6.Cu")
		(net "M_E_CPU1_SB_DQS_DN<0>")
	)
	(segment
		(start 35.277298 -284.764988)
		(end 35.717226 -284.764988)
		(width 0.16002)
		(layer "In6.Cu")
		(net "M_E_CPU1_SB_DQS_DN<0>")
	)
	(segment
		(start 65.74155 -278.260302)
		(end 66.218054 -278.260302)
		(width 0.16002)
		(layer "In6.Cu")
		(net "M_E_CPU1_SB_DQS_DN<0>")
	)
	(segment
		(start 48.528224 -285.312358)
		(end 48.84039 -285.624524)
		(width 0.16002)
		(layer "In6.Cu")
		(net "M_E_CPU1_SB_DQS_DN<0>")
	)
	(segment
		(start 66.398648 -277.098252)
		(end 66.398648 -276.872192)
		(width 0.16002)
		(layer "In6.Cu")
		(net "M_E_CPU1_SB_DQS_DN<0>")
	)
	(segment
		(start 53.18125 -285.408624)
		(end 54.677818 -285.408624)
		(width 0.16002)
		(layer "In6.Cu")
		(net "M_E_CPU1_SB_DQS_DN<0>")
	)
	(segment
		(start 65.00749 -278.48941)
		(end 65.00749 -278.26335)
		(width 0.16002)
		(layer "In6.Cu")
		(net "M_E_CPU1_SB_DQS_DN<0>")
	)
	(segment
		(start 32.08782 -285.312358)
		(end 33.44037 -285.312358)
		(width 0.16002)
		(layer "In6.Cu")
		(net "M_E_CPU1_SB_DQS_DN<0>")
	)
	(segment
		(start 76.1873 -275.400516)
		(end 77.153262 -275.400516)
		(width 0.09525)
		(layer "In6.Cu")
		(net "M_E_CPU1_SB_DQS_DN<0>")
	)
	(segment
		(start 29.252164 -285.735268)
		(end 29.525976 -285.461456)
		(width 0.16002)
		(layer "In6.Cu")
		(net "M_E_CPU1_SB_DQS_DN<0>")
	)
	(segment
		(start 65.259966 -278.741886)
		(end 65.00749 -278.48941)
		(width 0.16002)
		(layer "In6.Cu")
		(net "M_E_CPU1_SB_DQS_DN<0>")
	)
	(segment
		(start 34.417762 -285.624524)
		(end 35.277298 -284.764988)
		(width 0.16002)
		(layer "In6.Cu")
		(net "M_E_CPU1_SB_DQS_DN<0>")
	)
	(segment
		(start 65.263014 -278.007826)
		(end 65.489074 -278.007826)
		(width 0.16002)
		(layer "In6.Cu")
		(net "M_E_CPU1_SB_DQS_DN<0>")
	)
	(segment
		(start 44.70654 -284.462474)
		(end 45.556424 -285.312358)
		(width 0.16002)
		(layer "In6.Cu")
		(net "M_E_CPU1_SB_DQS_DN<0>")
	)
	(segment
		(start 43.21429 -284.862524)
		(end 43.61434 -284.462474)
		(width 0.16002)
		(layer "In6.Cu")
		(net "M_E_CPU1_SB_DQS_DN<0>")
	)
	(segment
		(start 66.398648 -276.872192)
		(end 66.74485 -276.52599)
		(width 0.16002)
		(layer "In6.Cu")
		(net "M_E_CPU1_SB_DQS_DN<0>")
	)
	(segment
		(start 76.128372 -275.459444)
		(end 76.1873 -275.400516)
		(width 0.09525)
		(layer "In6.Cu")
		(net "M_E_CPU1_SB_DQS_DN<0>")
	)
	(segment
		(start 37.11194 -284.462474)
		(end 37.961824 -285.312358)
		(width 0.16002)
		(layer "In6.Cu")
		(net "M_E_CPU1_SB_DQS_DN<0>")
	)
	(segment
		(start 66.651124 -277.350728)
		(end 66.398648 -277.098252)
		(width 0.16002)
		(layer "In6.Cu")
		(net "M_E_CPU1_SB_DQS_DN<0>")
	)
	(segment
		(start 68.910454 -275.459444)
		(end 76.10475 -275.459444)
		(width 0.16002)
		(layer "In6.Cu")
		(net "M_E_CPU1_SB_DQS_DN<0>")
	)
	(segment
		(start 41.32199 -285.649924)
		(end 41.91889 -285.649924)
		(width 0.16002)
		(layer "In6.Cu")
		(net "M_E_CPU1_SB_DQS_DN<0>")
	)
	(segment
		(start 55.287418 -286.018224)
		(end 56.630062 -286.018224)
		(width 0.16002)
		(layer "In6.Cu")
		(net "M_E_CPU1_SB_DQS_DN<0>")
	)
	(segment
		(start 81.214976 -276.250908)
		(end 81.061052 -276.516338)
		(width 0.09525)
		(layer "In6.Cu")
		(net "M_E_CPU1_SB_DQS_DN<0>")
	)
	(segment
		(start 66.218054 -278.260302)
		(end 66.651124 -277.827232)
		(width 0.16002)
		(layer "In6.Cu")
		(net "M_E_CPU1_SB_DQS_DN<0>")
	)
	(segment
		(start 67.069716 -275.459444)
		(end 67.305174 -275.459444)
		(width 0.16002)
		(layer "In6.Cu")
		(net "M_E_CPU1_SB_DQS_DN<0>")
	)
	(segment
		(start 33.44037 -285.312358)
		(end 33.752536 -285.624524)
		(width 0.16002)
		(layer "In6.Cu")
		(net "M_E_CPU1_SB_DQS_DN<0>")
	)
	(segment
		(start 68.750434 -275.619464)
		(end 68.910454 -275.459444)
		(width 0.16002)
		(layer "In6.Cu")
		(net "M_E_CPU1_SB_DQS_DN<0>")
	)
	(segment
		(start 76.10475 -275.459444)
		(end 76.128372 -275.459444)
		(width 0.09525)
		(layer "In6.Cu")
		(net "M_E_CPU1_SB_DQS_DN<0>")
	)
	(segment
		(start 66.74485 -276.52599)
		(end 66.74485 -275.78431)
		(width 0.16002)
		(layer "In6.Cu")
		(net "M_E_CPU1_SB_DQS_DN<0>")
	)
	(segment
		(start 45.556424 -285.312358)
		(end 48.528224 -285.312358)
		(width 0.16002)
		(layer "In6.Cu")
		(net "M_E_CPU1_SB_DQS_DN<0>")
	)
	(segment
		(start 37.961824 -285.312358)
		(end 40.984424 -285.312358)
		(width 0.16002)
		(layer "In6.Cu")
		(net "M_E_CPU1_SB_DQS_DN<0>")
	)
	(segment
		(start 64.097916 -279.398984)
		(end 64.350392 -279.65146)
		(width 0.16002)
		(layer "In6.Cu")
		(net "M_E_CPU1_SB_DQS_DN<0>")
	)
	(segment
		(start 51.124612 -284.462474)
		(end 52.2351 -284.462474)
		(width 0.16002)
		(layer "In6.Cu")
		(net "M_E_CPU1_SB_DQS_DN<0>")
	)
	(segment
		(start 43.61434 -284.462474)
		(end 44.70654 -284.462474)
		(width 0.16002)
		(layer "In6.Cu")
		(net "M_E_CPU1_SB_DQS_DN<0>")
	)
	(segment
		(start 62.50686 -282.320238)
		(end 62.50686 -281.116786)
		(width 0.16002)
		(layer "In6.Cu")
		(net "M_E_CPU1_SB_DQS_DN<0>")
	)
	(segment
		(start 31.97098 -285.429198)
		(end 32.08782 -285.312358)
		(width 0.16002)
		(layer "In6.Cu")
		(net "M_E_CPU1_SB_DQS_DN<0>")
	)
	(segment
		(start 49.479962 -285.624524)
		(end 50.241962 -284.862524)
		(width 0.16002)
		(layer "In6.Cu")
		(net "M_E_CPU1_SB_DQS_DN<0>")
	)
	(segment
		(start 31.49092 -285.429198)
		(end 31.97098 -285.429198)
		(width 0.16002)
		(layer "In6.Cu")
		(net "M_E_CPU1_SB_DQS_DN<0>")
	)
	(segment
		(start 50.241962 -284.862524)
		(end 50.724562 -284.862524)
		(width 0.16002)
		(layer "In6.Cu")
		(net "M_E_CPU1_SB_DQS_DN<0>")
	)
	(segment
		(start 77.153262 -275.400516)
		(end 78.019656 -276.26691)
		(width 0.09525)
		(layer "In6.Cu")
		(net "M_E_CPU1_SB_DQS_DN<0>")
	)
	(segment
		(start 68.413376 -276.547326)
		(end 68.750434 -276.210268)
		(width 0.16002)
		(layer "In6.Cu")
		(net "M_E_CPU1_SB_DQS_DN<0>")
	)
	(segment
		(start 63.560198 -279.710642)
		(end 63.871856 -279.398984)
		(width 0.16002)
		(layer "In6.Cu")
		(net "M_E_CPU1_SB_DQS_DN<0>")
	)
	(segment
		(start 67.465194 -275.619464)
		(end 67.465194 -276.210268)
		(width 0.16002)
		(layer "In6.Cu")
		(net "M_E_CPU1_SB_DQS_DN<0>")
	)
	(segment
		(start 67.305174 -275.459444)
		(end 67.465194 -275.619464)
		(width 0.16002)
		(layer "In6.Cu")
		(net "M_E_CPU1_SB_DQS_DN<0>")
	)
	(segment
		(start 40.984424 -285.312358)
		(end 41.32199 -285.649924)
		(width 0.16002)
		(layer "In6.Cu")
		(net "M_E_CPU1_SB_DQS_DN<0>")
	)
	(segment
		(start 65.00749 -278.26335)
		(end 65.263014 -278.007826)
		(width 0.16002)
		(layer "In6.Cu")
		(net "M_E_CPU1_SB_DQS_DN<0>")
	)
	(segment
		(start 81.191862 -276.164294)
		(end 81.214976 -276.250908)
		(width 0.09525)
		(layer "In6.Cu")
		(net "M_E_CPU1_SB_DQS_DN<0>")
	)
	(arc
		(start 80.872584 -276.191218)
		(mid 81.029211 -276.142032)
		(end 81.191862 -276.164294)
		(width 0.09525)
		(layer "In6.Cu")
		(net "M_E_CPU1_SB_DQS_DN<0>")
	)
	(arc
		(start 79.940912 -276.186392)
		(mid 80.125944 -276.140478)
		(end 80.30972 -276.191218)
		(width 0.09525)
		(layer "In6.Cu")
		(net "M_E_CPU1_SB_DQS_DN<0>")
	)
	(arc
		(start 80.30972 -276.191218)
		(mid 80.591152 -276.266973)
		(end 80.872584 -276.191218)
		(width 0.09525)
		(layer "In6.Cu")
		(net "M_E_CPU1_SB_DQS_DN<0>")
	)
	(arc
		(start 79.651352 -276.26691)
		(mid 79.796929 -276.247609)
		(end 79.93253 -276.191218)
		(width 0.09525)
		(layer "In6.Cu")
		(net "M_E_CPU1_SB_DQS_DN<0>")
	)
	(segment
		(start 83.408012 -279.490424)
		(end 82.940906 -279.756362)
		(width 0.10668)
		(layer "F.Cu")
		(net "M_E_CPU1_SB_DQ<9>")
	)
	(segment
		(start 32.27705 -292.960298)
		(end 32.990536 -292.960298)
		(width 0.14478)
		(layer "In6.Cu")
		(net "M_E_CPU1_SB_DQ<9>")
	)
	(segment
		(start 56.746648 -292.960298)
		(end 57.596786 -292.11016)
		(width 0.14478)
		(layer "In6.Cu")
		(net "M_E_CPU1_SB_DQ<9>")
	)
	(segment
		(start 34.121852 -293.316406)
		(end 35.328098 -292.11016)
		(width 0.14478)
		(layer "In6.Cu")
		(net "M_E_CPU1_SB_DQ<9>")
	)
	(segment
		(start 82.786982 -280.021792)
		(end 82.940906 -279.756362)
		(width 0.0889)
		(layer "In6.Cu")
		(net "M_E_CPU1_SB_DQ<9>")
	)
	(segment
		(start 60.88507 -291.171376)
		(end 60.88507 -290.10356)
		(width 0.14478)
		(layer "In6.Cu")
		(net "M_E_CPU1_SB_DQ<9>")
	)
	(segment
		(start 30.801818 -292.597586)
		(end 30.964632 -292.7604)
		(width 0.14478)
		(layer "In6.Cu")
		(net "M_E_CPU1_SB_DQ<9>")
	)
	(segment
		(start 30.245558 -293.298118)
		(end 30.408372 -293.135304)
		(width 0.14478)
		(layer "In6.Cu")
		(net "M_E_CPU1_SB_DQ<9>")
	)
	(segment
		(start 38.85692 -292.960298)
		(end 41.893998 -292.960298)
		(width 0.14478)
		(layer "In6.Cu")
		(net "M_E_CPU1_SB_DQ<9>")
	)
	(segment
		(start 52.640738 -292.11016)
		(end 53.490876 -292.960298)
		(width 0.14478)
		(layer "In6.Cu")
		(net "M_E_CPU1_SB_DQ<9>")
	)
	(segment
		(start 32.990536 -292.960298)
		(end 33.33496 -292.615874)
		(width 0.14478)
		(layer "In6.Cu")
		(net "M_E_CPU1_SB_DQ<9>")
	)
	(segment
		(start 30.408372 -293.135304)
		(end 30.408372 -292.7604)
		(width 0.14478)
		(layer "In6.Cu")
		(net "M_E_CPU1_SB_DQ<9>")
	)
	(segment
		(start 31.914338 -292.597586)
		(end 32.27705 -292.960298)
		(width 0.14478)
		(layer "In6.Cu")
		(net "M_E_CPU1_SB_DQ<9>")
	)
	(segment
		(start 46.77918 -293.259764)
		(end 47.078646 -292.960298)
		(width 0.14478)
		(layer "In6.Cu")
		(net "M_E_CPU1_SB_DQ<9>")
	)
	(segment
		(start 29.252164 -292.535356)
		(end 30.014926 -293.298118)
		(width 0.14478)
		(layer "In6.Cu")
		(net "M_E_CPU1_SB_DQ<9>")
	)
	(segment
		(start 30.571186 -292.597586)
		(end 30.801818 -292.597586)
		(width 0.14478)
		(layer "In6.Cu")
		(net "M_E_CPU1_SB_DQ<9>")
	)
	(segment
		(start 48.372522 -292.960298)
		(end 48.671988 -293.259764)
		(width 0.14478)
		(layer "In6.Cu")
		(net "M_E_CPU1_SB_DQ<9>")
	)
	(segment
		(start 50.078386 -292.11016)
		(end 52.640738 -292.11016)
		(width 0.14478)
		(layer "In6.Cu")
		(net "M_E_CPU1_SB_DQ<9>")
	)
	(segment
		(start 58.242962 -292.396164)
		(end 58.513218 -292.396164)
		(width 0.14478)
		(layer "In6.Cu")
		(net "M_E_CPU1_SB_DQ<9>")
	)
	(segment
		(start 30.408372 -292.7604)
		(end 30.571186 -292.597586)
		(width 0.14478)
		(layer "In6.Cu")
		(net "M_E_CPU1_SB_DQ<9>")
	)
	(segment
		(start 58.513218 -292.396164)
		(end 58.799222 -292.11016)
		(width 0.14478)
		(layer "In6.Cu")
		(net "M_E_CPU1_SB_DQ<9>")
	)
	(segment
		(start 31.683706 -292.597586)
		(end 31.914338 -292.597586)
		(width 0.14478)
		(layer "In6.Cu")
		(net "M_E_CPU1_SB_DQ<9>")
	)
	(segment
		(start 82.179668 -280.083768)
		(end 82.18805 -280.078942)
		(width 0.0889)
		(layer "In6.Cu")
		(net "M_E_CPU1_SB_DQ<9>")
	)
	(segment
		(start 48.928782 -293.259764)
		(end 50.078386 -292.11016)
		(width 0.14478)
		(layer "In6.Cu")
		(net "M_E_CPU1_SB_DQ<9>")
	)
	(segment
		(start 33.33496 -292.615874)
		(end 33.565592 -292.615874)
		(width 0.14478)
		(layer "In6.Cu")
		(net "M_E_CPU1_SB_DQ<9>")
	)
	(segment
		(start 57.956958 -292.11016)
		(end 58.242962 -292.396164)
		(width 0.14478)
		(layer "In6.Cu")
		(net "M_E_CPU1_SB_DQ<9>")
	)
	(segment
		(start 82.69097 -280.047192)
		(end 82.786982 -280.021792)
		(width 0.0889)
		(layer "In6.Cu")
		(net "M_E_CPU1_SB_DQ<9>")
	)
	(segment
		(start 58.799222 -292.11016)
		(end 59.946286 -292.11016)
		(width 0.14478)
		(layer "In6.Cu")
		(net "M_E_CPU1_SB_DQ<9>")
	)
	(segment
		(start 31.520892 -293.135304)
		(end 31.520892 -292.7604)
		(width 0.14478)
		(layer "In6.Cu")
		(net "M_E_CPU1_SB_DQ<9>")
	)
	(segment
		(start 71.235316 -279.753314)
		(end 75.958446 -279.753314)
		(width 0.14478)
		(layer "In6.Cu")
		(net "M_E_CPU1_SB_DQ<9>")
	)
	(segment
		(start 59.946286 -292.11016)
		(end 60.88507 -291.171376)
		(width 0.14478)
		(layer "In6.Cu")
		(net "M_E_CPU1_SB_DQ<9>")
	)
	(segment
		(start 33.89122 -293.316406)
		(end 34.121852 -293.316406)
		(width 0.14478)
		(layer "In6.Cu")
		(net "M_E_CPU1_SB_DQ<9>")
	)
	(segment
		(start 33.565592 -292.615874)
		(end 33.728406 -292.778688)
		(width 0.14478)
		(layer "In6.Cu")
		(net "M_E_CPU1_SB_DQ<9>")
	)
	(segment
		(start 41.893998 -292.960298)
		(end 42.744136 -292.11016)
		(width 0.14478)
		(layer "In6.Cu")
		(net "M_E_CPU1_SB_DQ<9>")
	)
	(segment
		(start 46.522386 -293.259764)
		(end 46.77918 -293.259764)
		(width 0.14478)
		(layer "In6.Cu")
		(net "M_E_CPU1_SB_DQ<9>")
	)
	(segment
		(start 31.520892 -292.7604)
		(end 31.683706 -292.597586)
		(width 0.14478)
		(layer "In6.Cu")
		(net "M_E_CPU1_SB_DQ<9>")
	)
	(segment
		(start 45.372782 -292.11016)
		(end 46.522386 -293.259764)
		(width 0.14478)
		(layer "In6.Cu")
		(net "M_E_CPU1_SB_DQ<9>")
	)
	(segment
		(start 76.37653 -279.753314)
		(end 76.54798 -279.924764)
		(width 0.0889)
		(layer "In6.Cu")
		(net "M_E_CPU1_SB_DQ<9>")
	)
	(segment
		(start 30.964632 -292.7604)
		(end 30.964632 -293.135304)
		(width 0.14478)
		(layer "In6.Cu")
		(net "M_E_CPU1_SB_DQ<9>")
	)
	(segment
		(start 31.127446 -293.298118)
		(end 31.358078 -293.298118)
		(width 0.14478)
		(layer "In6.Cu")
		(net "M_E_CPU1_SB_DQ<9>")
	)
	(segment
		(start 35.328098 -292.11016)
		(end 38.006782 -292.11016)
		(width 0.14478)
		(layer "In6.Cu")
		(net "M_E_CPU1_SB_DQ<9>")
	)
	(segment
		(start 33.728406 -293.153592)
		(end 33.89122 -293.316406)
		(width 0.14478)
		(layer "In6.Cu")
		(net "M_E_CPU1_SB_DQ<9>")
	)
	(segment
		(start 42.744136 -292.11016)
		(end 45.372782 -292.11016)
		(width 0.14478)
		(layer "In6.Cu")
		(net "M_E_CPU1_SB_DQ<9>")
	)
	(segment
		(start 79.869792 -280.041604)
		(end 79.9338 -280.078942)
		(width 0.0889)
		(layer "In6.Cu")
		(net "M_E_CPU1_SB_DQ<9>")
	)
	(segment
		(start 30.014926 -293.298118)
		(end 30.245558 -293.298118)
		(width 0.14478)
		(layer "In6.Cu")
		(net "M_E_CPU1_SB_DQ<9>")
	)
	(segment
		(start 33.728406 -292.778688)
		(end 33.728406 -293.153592)
		(width 0.14478)
		(layer "In6.Cu")
		(net "M_E_CPU1_SB_DQ<9>")
	)
	(segment
		(start 47.078646 -292.960298)
		(end 48.372522 -292.960298)
		(width 0.14478)
		(layer "In6.Cu")
		(net "M_E_CPU1_SB_DQ<9>")
	)
	(segment
		(start 76.54798 -279.924764)
		(end 79.554578 -279.924764)
		(width 0.0889)
		(layer "In6.Cu")
		(net "M_E_CPU1_SB_DQ<9>")
	)
	(segment
		(start 57.596786 -292.11016)
		(end 57.956958 -292.11016)
		(width 0.14478)
		(layer "In6.Cu")
		(net "M_E_CPU1_SB_DQ<9>")
	)
	(segment
		(start 30.964632 -293.135304)
		(end 31.127446 -293.298118)
		(width 0.14478)
		(layer "In6.Cu")
		(net "M_E_CPU1_SB_DQ<9>")
	)
	(segment
		(start 53.490876 -292.960298)
		(end 56.746648 -292.960298)
		(width 0.14478)
		(layer "In6.Cu")
		(net "M_E_CPU1_SB_DQ<9>")
	)
	(segment
		(start 31.358078 -293.298118)
		(end 31.520892 -293.135304)
		(width 0.14478)
		(layer "In6.Cu")
		(net "M_E_CPU1_SB_DQ<9>")
	)
	(segment
		(start 60.88507 -290.10356)
		(end 71.235316 -279.753314)
		(width 0.14478)
		(layer "In6.Cu")
		(net "M_E_CPU1_SB_DQ<9>")
	)
	(segment
		(start 48.671988 -293.259764)
		(end 48.928782 -293.259764)
		(width 0.14478)
		(layer "In6.Cu")
		(net "M_E_CPU1_SB_DQ<9>")
	)
	(segment
		(start 75.958446 -279.753314)
		(end 76.37653 -279.753314)
		(width 0.0889)
		(layer "In6.Cu")
		(net "M_E_CPU1_SB_DQ<9>")
	)
	(segment
		(start 38.006782 -292.11016)
		(end 38.85692 -292.960298)
		(width 0.14478)
		(layer "In6.Cu")
		(net "M_E_CPU1_SB_DQ<9>")
	)
	(arc
		(start 79.554578 -279.924764)
		(mid 79.599096 -279.928319)
		(end 79.642462 -279.938988)
		(width 0.0889)
		(layer "In6.Cu")
		(net "M_E_CPU1_SB_DQ<9>")
	)
	(arc
		(start 81.247996 -280.078942)
		(mid 81.530952 -280.002765)
		(end 81.813908 -280.078942)
		(width 0.0889)
		(layer "In6.Cu")
		(net "M_E_CPU1_SB_DQ<9>")
	)
	(arc
		(start 80.308196 -280.078942)
		(mid 80.591152 -280.002765)
		(end 80.874108 -280.078942)
		(width 0.0889)
		(layer "In6.Cu")
		(net "M_E_CPU1_SB_DQ<9>")
	)
	(arc
		(start 80.874108 -280.078942)
		(mid 81.061052 -280.129197)
		(end 81.247996 -280.078942)
		(width 0.0889)
		(layer "In6.Cu")
		(net "M_E_CPU1_SB_DQ<9>")
	)
	(arc
		(start 81.813908 -280.078942)
		(mid 81.996159 -280.129292)
		(end 82.179668 -280.083768)
		(width 0.0889)
		(layer "In6.Cu")
		(net "M_E_CPU1_SB_DQ<9>")
	)
	(arc
		(start 82.18805 -280.078942)
		(mid 82.435763 -280.003722)
		(end 82.69097 -280.047192)
		(width 0.0889)
		(layer "In6.Cu")
		(net "M_E_CPU1_SB_DQ<9>")
	)
	(arc
		(start 79.9338 -280.078942)
		(mid 80.120998 -280.129324)
		(end 80.308196 -280.078942)
		(width 0.0889)
		(layer "In6.Cu")
		(net "M_E_CPU1_SB_DQ<9>")
	)
	(arc
		(start 79.642462 -279.938988)
		(mid 79.758748 -279.984491)
		(end 79.869792 -280.041604)
		(width 0.0889)
		(layer "In6.Cu")
		(net "M_E_CPU1_SB_DQ<9>")
	)
	(segment
		(start 81.997804 -278.680418)
		(end 81.530952 -278.946356)
		(width 0.10668)
		(layer "F.Cu")
		(net "M_E_CPU1_SB_DQ<8>")
	)
	(segment
		(start 34.78022 -291.260784)
		(end 35.630866 -290.410392)
		(width 0.14478)
		(layer "In6.Cu")
		(net "M_E_CPU1_SB_DQ<8>")
	)
	(segment
		(start 52.645056 -290.719764)
		(end 52.954428 -290.410392)
		(width 0.14478)
		(layer "In6.Cu")
		(net "M_E_CPU1_SB_DQ<8>")
	)
	(segment
		(start 76.042266 -278.843994)
		(end 78.081124 -278.843994)
		(width 0.0889)
		(layer "In6.Cu")
		(net "M_E_CPU1_SB_DQ<8>")
	)
	(segment
		(start 40.983408 -290.988496)
		(end 41.267888 -290.988496)
		(width 0.14478)
		(layer "In6.Cu")
		(net "M_E_CPU1_SB_DQ<8>")
	)
	(segment
		(start 31.072582 -291.26053)
		(end 31.360618 -291.548566)
		(width 0.14478)
		(layer "In6.Cu")
		(net "M_E_CPU1_SB_DQ<8>")
	)
	(segment
		(start 57.6834 -290.441126)
		(end 57.517538 -290.275264)
		(width 0.14478)
		(layer "In6.Cu")
		(net "M_E_CPU1_SB_DQ<8>")
	)
	(segment
		(start 53.56225 -291.304726)
		(end 53.840888 -291.583364)
		(width 0.14478)
		(layer "In6.Cu")
		(net "M_E_CPU1_SB_DQ<8>")
	)
	(segment
		(start 57.517538 -290.275264)
		(end 57.517538 -290.07054)
		(width 0.14478)
		(layer "In6.Cu")
		(net "M_E_CPU1_SB_DQ<8>")
	)
	(segment
		(start 48.128174 -291.26053)
		(end 48.50003 -291.632386)
		(width 0.14478)
		(layer "In6.Cu")
		(net "M_E_CPU1_SB_DQ<8>")
	)
	(segment
		(start 52.398168 -290.719764)
		(end 52.645056 -290.719764)
		(width 0.14478)
		(layer "In6.Cu")
		(net "M_E_CPU1_SB_DQ<8>")
	)
	(segment
		(start 57.28462 -290.839906)
		(end 57.489344 -290.839906)
		(width 0.14478)
		(layer "In6.Cu")
		(net "M_E_CPU1_SB_DQ<8>")
	)
	(segment
		(start 58.850276 -290.642802)
		(end 59.01309 -290.805616)
		(width 0.14478)
		(layer "In6.Cu")
		(net "M_E_CPU1_SB_DQ<8>")
	)
	(segment
		(start 59.98591 -290.660836)
		(end 59.98591 -289.730688)
		(width 0.14478)
		(layer "In6.Cu")
		(net "M_E_CPU1_SB_DQ<8>")
	)
	(segment
		(start 70.872604 -278.843994)
		(end 76.042266 -278.843994)
		(width 0.14478)
		(layer "In6.Cu")
		(net "M_E_CPU1_SB_DQ<8>")
	)
	(segment
		(start 53.56225 -290.620704)
		(end 53.56225 -291.304726)
		(width 0.14478)
		(layer "In6.Cu")
		(net "M_E_CPU1_SB_DQ<8>")
	)
	(segment
		(start 57.118758 -290.674044)
		(end 57.28462 -290.839906)
		(width 0.14478)
		(layer "In6.Cu")
		(net "M_E_CPU1_SB_DQ<8>")
	)
	(segment
		(start 57.517538 -290.07054)
		(end 57.876948 -289.71113)
		(width 0.14478)
		(layer "In6.Cu")
		(net "M_E_CPU1_SB_DQ<8>")
	)
	(segment
		(start 53.840888 -291.583364)
		(end 54.758336 -291.583364)
		(width 0.14478)
		(layer "In6.Cu")
		(net "M_E_CPU1_SB_DQ<8>")
	)
	(segment
		(start 57.876948 -289.71113)
		(end 58.641234 -289.71113)
		(width 0.14478)
		(layer "In6.Cu")
		(net "M_E_CPU1_SB_DQ<8>")
	)
	(segment
		(start 81.281016 -279.237186)
		(end 81.377028 -279.211786)
		(width 0.0889)
		(layer "In6.Cu")
		(net "M_E_CPU1_SB_DQ<8>")
	)
	(segment
		(start 56.88584 -291.44341)
		(end 56.88584 -291.238686)
		(width 0.14478)
		(layer "In6.Cu")
		(net "M_E_CPU1_SB_DQ<8>")
	)
	(segment
		(start 59.84113 -290.805616)
		(end 59.98591 -290.660836)
		(width 0.14478)
		(layer "In6.Cu")
		(net "M_E_CPU1_SB_DQ<8>")
	)
	(segment
		(start 52.954428 -290.410392)
		(end 53.351938 -290.410392)
		(width 0.14478)
		(layer "In6.Cu")
		(net "M_E_CPU1_SB_DQ<8>")
	)
	(segment
		(start 31.360618 -291.548566)
		(end 31.636462 -291.548566)
		(width 0.14478)
		(layer "In6.Cu")
		(net "M_E_CPU1_SB_DQ<8>")
	)
	(segment
		(start 56.48706 -291.637466)
		(end 56.691784 -291.637466)
		(width 0.14478)
		(layer "In6.Cu")
		(net "M_E_CPU1_SB_DQ<8>")
	)
	(segment
		(start 31.924498 -291.26053)
		(end 34.779966 -291.26053)
		(width 0.14478)
		(layer "In6.Cu")
		(net "M_E_CPU1_SB_DQ<8>")
	)
	(segment
		(start 40.711374 -291.26053)
		(end 40.983408 -290.988496)
		(width 0.14478)
		(layer "In6.Cu")
		(net "M_E_CPU1_SB_DQ<8>")
	)
	(segment
		(start 56.719978 -291.072824)
		(end 56.719978 -290.8681)
		(width 0.14478)
		(layer "In6.Cu")
		(net "M_E_CPU1_SB_DQ<8>")
	)
	(segment
		(start 55.08117 -291.26053)
		(end 55.314596 -291.26053)
		(width 0.14478)
		(layer "In6.Cu")
		(net "M_E_CPU1_SB_DQ<8>")
	)
	(segment
		(start 56.004714 -291.583364)
		(end 56.116474 -291.471604)
		(width 0.14478)
		(layer "In6.Cu")
		(net "M_E_CPU1_SB_DQ<8>")
	)
	(segment
		(start 29.252164 -290.835334)
		(end 29.67736 -291.26053)
		(width 0.14478)
		(layer "In6.Cu")
		(net "M_E_CPU1_SB_DQ<8>")
	)
	(segment
		(start 78.081124 -278.843994)
		(end 78.447138 -279.210008)
		(width 0.0889)
		(layer "In6.Cu")
		(net "M_E_CPU1_SB_DQ<8>")
	)
	(segment
		(start 59.98591 -289.730688)
		(end 70.872604 -278.843994)
		(width 0.14478)
		(layer "In6.Cu")
		(net "M_E_CPU1_SB_DQ<8>")
	)
	(segment
		(start 58.84037 -289.910266)
		(end 58.84037 -290.49726)
		(width 0.14478)
		(layer "In6.Cu")
		(net "M_E_CPU1_SB_DQ<8>")
	)
	(segment
		(start 78.524354 -279.268936)
		(end 78.536038 -279.275794)
		(width 0.0889)
		(layer "In6.Cu")
		(net "M_E_CPU1_SB_DQ<8>")
	)
	(segment
		(start 56.691784 -291.637466)
		(end 56.88584 -291.44341)
		(width 0.14478)
		(layer "In6.Cu")
		(net "M_E_CPU1_SB_DQ<8>")
	)
	(segment
		(start 79.453994 -279.26284)
		(end 79.464408 -279.268936)
		(width 0.0889)
		(layer "In6.Cu")
		(net "M_E_CPU1_SB_DQ<8>")
	)
	(segment
		(start 41.823894 -291.532564)
		(end 42.946066 -290.410392)
		(width 0.14478)
		(layer "In6.Cu")
		(net "M_E_CPU1_SB_DQ<8>")
	)
	(segment
		(start 58.84037 -290.49726)
		(end 58.850276 -290.507166)
		(width 0.14478)
		(layer "In6.Cu")
		(net "M_E_CPU1_SB_DQ<8>")
	)
	(segment
		(start 35.630866 -290.410392)
		(end 38.161722 -290.410392)
		(width 0.14478)
		(layer "In6.Cu")
		(net "M_E_CPU1_SB_DQ<8>")
	)
	(segment
		(start 46.496986 -291.583364)
		(end 46.730412 -291.583364)
		(width 0.14478)
		(layer "In6.Cu")
		(net "M_E_CPU1_SB_DQ<8>")
	)
	(segment
		(start 41.539668 -291.532564)
		(end 41.823894 -291.532564)
		(width 0.14478)
		(layer "In6.Cu")
		(net "M_E_CPU1_SB_DQ<8>")
	)
	(segment
		(start 57.489344 -290.839906)
		(end 57.6834 -290.64585)
		(width 0.14478)
		(layer "In6.Cu")
		(net "M_E_CPU1_SB_DQ<8>")
	)
	(segment
		(start 80.769714 -279.273762)
		(end 80.778096 -279.268936)
		(width 0.0889)
		(layer "In6.Cu")
		(net "M_E_CPU1_SB_DQ<8>")
	)
	(segment
		(start 34.779966 -291.26053)
		(end 34.78022 -291.260784)
		(width 0.14478)
		(layer "In6.Cu")
		(net "M_E_CPU1_SB_DQ<8>")
	)
	(segment
		(start 55.314596 -291.26053)
		(end 55.63743 -291.583364)
		(width 0.14478)
		(layer "In6.Cu")
		(net "M_E_CPU1_SB_DQ<8>")
	)
	(segment
		(start 78.447138 -279.210008)
		(end 78.447392 -279.210008)
		(width 0.0889)
		(layer "In6.Cu")
		(net "M_E_CPU1_SB_DQ<8>")
	)
	(segment
		(start 41.403778 -291.124386)
		(end 41.403778 -291.396674)
		(width 0.14478)
		(layer "In6.Cu")
		(net "M_E_CPU1_SB_DQ<8>")
	)
	(segment
		(start 56.914034 -290.674044)
		(end 57.118758 -290.674044)
		(width 0.14478)
		(layer "In6.Cu")
		(net "M_E_CPU1_SB_DQ<8>")
	)
	(segment
		(start 79.838296 -279.268936)
		(end 79.84871 -279.26284)
		(width 0.0889)
		(layer "In6.Cu")
		(net "M_E_CPU1_SB_DQ<8>")
	)
	(segment
		(start 58.641234 -289.71113)
		(end 58.84037 -289.910266)
		(width 0.14478)
		(layer "In6.Cu")
		(net "M_E_CPU1_SB_DQ<8>")
	)
	(segment
		(start 49.269904 -291.632386)
		(end 50.491898 -290.410392)
		(width 0.14478)
		(layer "In6.Cu")
		(net "M_E_CPU1_SB_DQ<8>")
	)
	(segment
		(start 50.771044 -290.410392)
		(end 51.080416 -290.719764)
		(width 0.14478)
		(layer "In6.Cu")
		(net "M_E_CPU1_SB_DQ<8>")
	)
	(segment
		(start 42.946066 -290.410392)
		(end 45.324014 -290.410392)
		(width 0.14478)
		(layer "In6.Cu")
		(net "M_E_CPU1_SB_DQ<8>")
	)
	(segment
		(start 48.50003 -291.632386)
		(end 49.269904 -291.632386)
		(width 0.14478)
		(layer "In6.Cu")
		(net "M_E_CPU1_SB_DQ<8>")
	)
	(segment
		(start 38.161722 -290.410392)
		(end 39.01186 -291.26053)
		(width 0.14478)
		(layer "In6.Cu")
		(net "M_E_CPU1_SB_DQ<8>")
	)
	(segment
		(start 41.403778 -291.396674)
		(end 41.539668 -291.532564)
		(width 0.14478)
		(layer "In6.Cu")
		(net "M_E_CPU1_SB_DQ<8>")
	)
	(segment
		(start 56.116474 -291.471604)
		(end 56.321198 -291.471604)
		(width 0.14478)
		(layer "In6.Cu")
		(net "M_E_CPU1_SB_DQ<8>")
	)
	(segment
		(start 51.080416 -290.719764)
		(end 51.327304 -290.719764)
		(width 0.14478)
		(layer "In6.Cu")
		(net "M_E_CPU1_SB_DQ<8>")
	)
	(segment
		(start 59.01309 -290.805616)
		(end 59.84113 -290.805616)
		(width 0.14478)
		(layer "In6.Cu")
		(net "M_E_CPU1_SB_DQ<8>")
	)
	(segment
		(start 54.758336 -291.583364)
		(end 55.08117 -291.26053)
		(width 0.14478)
		(layer "In6.Cu")
		(net "M_E_CPU1_SB_DQ<8>")
	)
	(segment
		(start 46.730412 -291.583364)
		(end 47.053246 -291.26053)
		(width 0.14478)
		(layer "In6.Cu")
		(net "M_E_CPU1_SB_DQ<8>")
	)
	(segment
		(start 45.324014 -290.410392)
		(end 46.496986 -291.583364)
		(width 0.14478)
		(layer "In6.Cu")
		(net "M_E_CPU1_SB_DQ<8>")
	)
	(segment
		(start 50.491898 -290.410392)
		(end 50.771044 -290.410392)
		(width 0.14478)
		(layer "In6.Cu")
		(net "M_E_CPU1_SB_DQ<8>")
	)
	(segment
		(start 29.67736 -291.26053)
		(end 31.072582 -291.26053)
		(width 0.14478)
		(layer "In6.Cu")
		(net "M_E_CPU1_SB_DQ<8>")
	)
	(segment
		(start 57.6834 -290.64585)
		(end 57.6834 -290.441126)
		(width 0.14478)
		(layer "In6.Cu")
		(net "M_E_CPU1_SB_DQ<8>")
	)
	(segment
		(start 31.636462 -291.548566)
		(end 31.924498 -291.26053)
		(width 0.14478)
		(layer "In6.Cu")
		(net "M_E_CPU1_SB_DQ<8>")
	)
	(segment
		(start 56.321198 -291.471604)
		(end 56.48706 -291.637466)
		(width 0.14478)
		(layer "In6.Cu")
		(net "M_E_CPU1_SB_DQ<8>")
	)
	(segment
		(start 81.377028 -279.211786)
		(end 81.530952 -278.946356)
		(width 0.0889)
		(layer "In6.Cu")
		(net "M_E_CPU1_SB_DQ<8>")
	)
	(segment
		(start 52.088796 -290.410392)
		(end 52.398168 -290.719764)
		(width 0.14478)
		(layer "In6.Cu")
		(net "M_E_CPU1_SB_DQ<8>")
	)
	(segment
		(start 58.850276 -290.507166)
		(end 58.850276 -290.642802)
		(width 0.14478)
		(layer "In6.Cu")
		(net "M_E_CPU1_SB_DQ<8>")
	)
	(segment
		(start 47.053246 -291.26053)
		(end 48.128174 -291.26053)
		(width 0.14478)
		(layer "In6.Cu")
		(net "M_E_CPU1_SB_DQ<8>")
	)
	(segment
		(start 55.63743 -291.583364)
		(end 56.004714 -291.583364)
		(width 0.14478)
		(layer "In6.Cu")
		(net "M_E_CPU1_SB_DQ<8>")
	)
	(segment
		(start 51.636676 -290.410392)
		(end 52.088796 -290.410392)
		(width 0.14478)
		(layer "In6.Cu")
		(net "M_E_CPU1_SB_DQ<8>")
	)
	(segment
		(start 51.327304 -290.719764)
		(end 51.636676 -290.410392)
		(width 0.14478)
		(layer "In6.Cu")
		(net "M_E_CPU1_SB_DQ<8>")
	)
	(segment
		(start 56.719978 -290.8681)
		(end 56.914034 -290.674044)
		(width 0.14478)
		(layer "In6.Cu")
		(net "M_E_CPU1_SB_DQ<8>")
	)
	(segment
		(start 39.01186 -291.26053)
		(end 40.711374 -291.26053)
		(width 0.14478)
		(layer "In6.Cu")
		(net "M_E_CPU1_SB_DQ<8>")
	)
	(segment
		(start 53.351938 -290.410392)
		(end 53.56225 -290.620704)
		(width 0.14478)
		(layer "In6.Cu")
		(net "M_E_CPU1_SB_DQ<8>")
	)
	(segment
		(start 56.88584 -291.238686)
		(end 56.719978 -291.072824)
		(width 0.14478)
		(layer "In6.Cu")
		(net "M_E_CPU1_SB_DQ<8>")
	)
	(segment
		(start 41.267888 -290.988496)
		(end 41.403778 -291.124386)
		(width 0.14478)
		(layer "In6.Cu")
		(net "M_E_CPU1_SB_DQ<8>")
	)
	(arc
		(start 78.898242 -279.268936)
		(mid 79.175309 -279.192665)
		(end 79.453994 -279.26284)
		(width 0.0889)
		(layer "In6.Cu")
		(net "M_E_CPU1_SB_DQ<8>")
	)
	(arc
		(start 79.84871 -279.26284)
		(mid 80.127142 -279.192742)
		(end 80.403954 -279.268936)
		(width 0.0889)
		(layer "In6.Cu")
		(net "M_E_CPU1_SB_DQ<8>")
	)
	(arc
		(start 80.778096 -279.268936)
		(mid 81.025809 -279.193716)
		(end 81.281016 -279.237186)
		(width 0.0889)
		(layer "In6.Cu")
		(net "M_E_CPU1_SB_DQ<8>")
	)
	(arc
		(start 79.464408 -279.268936)
		(mid 79.651352 -279.319191)
		(end 79.838296 -279.268936)
		(width 0.0889)
		(layer "In6.Cu")
		(net "M_E_CPU1_SB_DQ<8>")
	)
	(arc
		(start 78.536038 -279.275794)
		(mid 78.718039 -279.319327)
		(end 78.898242 -279.268936)
		(width 0.0889)
		(layer "In6.Cu")
		(net "M_E_CPU1_SB_DQ<8>")
	)
	(arc
		(start 80.403954 -279.268936)
		(mid 80.586205 -279.319286)
		(end 80.769714 -279.273762)
		(width 0.0889)
		(layer "In6.Cu")
		(net "M_E_CPU1_SB_DQ<8>")
	)
	(arc
		(start 78.447392 -279.210008)
		(mid 78.483947 -279.241988)
		(end 78.524354 -279.268936)
		(width 0.0889)
		(layer "In6.Cu")
		(net "M_E_CPU1_SB_DQ<8>")
	)
	(segment
		(start 82.937858 -278.680418)
		(end 82.471006 -278.946356)
		(width 0.10668)
		(layer "F.Cu")
		(net "M_E_CPU1_SB_DQ<7>")
	)
	(segment
		(start 82.602578 -278.597614)
		(end 82.62493 -278.680926)
		(width 0.0889)
		(layer "In6.Cu")
		(net "M_E_CPU1_SB_DQ<7>")
	)
	(segment
		(start 76.034392 -278.287734)
		(end 76.703428 -278.287734)
		(width 0.0889)
		(layer "In6.Cu")
		(net "M_E_CPU1_SB_DQ<7>")
	)
	(segment
		(start 82.62493 -278.680926)
		(end 82.471006 -278.946356)
		(width 0.0889)
		(layer "In6.Cu")
		(net "M_E_CPU1_SB_DQ<7>")
	)
	(segment
		(start 76.862178 -278.446484)
		(end 79.180182 -278.446484)
		(width 0.0889)
		(layer "In6.Cu")
		(net "M_E_CPU1_SB_DQ<7>")
	)
	(segment
		(start 59.918346 -289.018726)
		(end 70.649338 -278.287734)
		(width 0.14478)
		(layer "In6.Cu")
		(net "M_E_CPU1_SB_DQ<7>")
	)
	(segment
		(start 70.649338 -278.287734)
		(end 76.034392 -278.287734)
		(width 0.14478)
		(layer "In6.Cu")
		(net "M_E_CPU1_SB_DQ<7>")
	)
	(segment
		(start 35.69335 -289.560254)
		(end 38.09873 -289.560254)
		(width 0.14478)
		(layer "In6.Cu")
		(net "M_E_CPU1_SB_DQ<7>")
	)
	(segment
		(start 50.55489 -289.560254)
		(end 53.288946 -289.560254)
		(width 0.14478)
		(layer "In6.Cu")
		(net "M_E_CPU1_SB_DQ<7>")
	)
	(segment
		(start 34.843212 -290.410392)
		(end 35.69335 -289.560254)
		(width 0.14478)
		(layer "In6.Cu")
		(net "M_E_CPU1_SB_DQ<7>")
	)
	(segment
		(start 38.09873 -289.560254)
		(end 38.948868 -290.410392)
		(width 0.14478)
		(layer "In6.Cu")
		(net "M_E_CPU1_SB_DQ<7>")
	)
	(segment
		(start 59.577478 -289.15995)
		(end 59.918346 -289.018726)
		(width 0.14478)
		(layer "In6.Cu")
		(net "M_E_CPU1_SB_DQ<7>")
	)
	(segment
		(start 57.648602 -289.15995)
		(end 59.577478 -289.15995)
		(width 0.14478)
		(layer "In6.Cu")
		(net "M_E_CPU1_SB_DQ<7>")
	)
	(segment
		(start 80.769714 -278.61895)
		(end 80.778096 -278.623776)
		(width 0.0889)
		(layer "In6.Cu")
		(net "M_E_CPU1_SB_DQ<7>")
	)
	(segment
		(start 42.98315 -289.560254)
		(end 45.28693 -289.560254)
		(width 0.14478)
		(layer "In6.Cu")
		(net "M_E_CPU1_SB_DQ<7>")
	)
	(segment
		(start 81.344008 -278.623776)
		(end 81.35239 -278.61895)
		(width 0.0889)
		(layer "In6.Cu")
		(net "M_E_CPU1_SB_DQ<7>")
	)
	(segment
		(start 49.704752 -290.410392)
		(end 50.55489 -289.560254)
		(width 0.14478)
		(layer "In6.Cu")
		(net "M_E_CPU1_SB_DQ<7>")
	)
	(segment
		(start 54.139084 -290.410392)
		(end 56.39816 -290.410392)
		(width 0.14478)
		(layer "In6.Cu")
		(net "M_E_CPU1_SB_DQ<7>")
	)
	(segment
		(start 76.703428 -278.287734)
		(end 76.862178 -278.446484)
		(width 0.0889)
		(layer "In6.Cu")
		(net "M_E_CPU1_SB_DQ<7>")
	)
	(segment
		(start 38.948868 -290.410392)
		(end 42.133012 -290.410392)
		(width 0.14478)
		(layer "In6.Cu")
		(net "M_E_CPU1_SB_DQ<7>")
	)
	(segment
		(start 46.137068 -290.410392)
		(end 49.704752 -290.410392)
		(width 0.14478)
		(layer "In6.Cu")
		(net "M_E_CPU1_SB_DQ<7>")
	)
	(segment
		(start 25.577038 -290.410392)
		(end 34.843212 -290.410392)
		(width 0.14478)
		(layer "In6.Cu")
		(net "M_E_CPU1_SB_DQ<7>")
	)
	(segment
		(start 45.28693 -289.560254)
		(end 46.137068 -290.410392)
		(width 0.14478)
		(layer "In6.Cu")
		(net "M_E_CPU1_SB_DQ<7>")
	)
	(segment
		(start 42.133012 -290.410392)
		(end 42.98315 -289.560254)
		(width 0.14478)
		(layer "In6.Cu")
		(net "M_E_CPU1_SB_DQ<7>")
	)
	(segment
		(start 25.152096 -289.98545)
		(end 25.577038 -290.410392)
		(width 0.14478)
		(layer "In6.Cu")
		(net "M_E_CPU1_SB_DQ<7>")
	)
	(segment
		(start 53.288946 -289.560254)
		(end 54.139084 -290.410392)
		(width 0.14478)
		(layer "In6.Cu")
		(net "M_E_CPU1_SB_DQ<7>")
	)
	(segment
		(start 56.39816 -290.410392)
		(end 57.648602 -289.15995)
		(width 0.14478)
		(layer "In6.Cu")
		(net "M_E_CPU1_SB_DQ<7>")
	)
	(arc
		(start 80.403954 -278.623776)
		(mid 80.586205 -278.573426)
		(end 80.769714 -278.61895)
		(width 0.0889)
		(layer "In6.Cu")
		(net "M_E_CPU1_SB_DQ<7>")
	)
	(arc
		(start 80.778096 -278.623776)
		(mid 81.061052 -278.699953)
		(end 81.344008 -278.623776)
		(width 0.0889)
		(layer "In6.Cu")
		(net "M_E_CPU1_SB_DQ<7>")
	)
	(arc
		(start 79.838042 -278.623776)
		(mid 80.120998 -278.699953)
		(end 80.403954 -278.623776)
		(width 0.0889)
		(layer "In6.Cu")
		(net "M_E_CPU1_SB_DQ<7>")
	)
	(arc
		(start 82.284062 -278.623776)
		(mid 82.440381 -278.574781)
		(end 82.602578 -278.597614)
		(width 0.0889)
		(layer "In6.Cu")
		(net "M_E_CPU1_SB_DQ<7>")
	)
	(arc
		(start 81.35239 -278.61895)
		(mid 81.535898 -278.573456)
		(end 81.71815 -278.623776)
		(width 0.0889)
		(layer "In6.Cu")
		(net "M_E_CPU1_SB_DQ<7>")
	)
	(arc
		(start 81.71815 -278.623776)
		(mid 82.001106 -278.699953)
		(end 82.284062 -278.623776)
		(width 0.0889)
		(layer "In6.Cu")
		(net "M_E_CPU1_SB_DQ<7>")
	)
	(arc
		(start 79.180182 -278.446484)
		(mid 79.520851 -278.491578)
		(end 79.838042 -278.623776)
		(width 0.0889)
		(layer "In6.Cu")
		(net "M_E_CPU1_SB_DQ<7>")
	)
	(segment
		(start 81.527904 -277.870412)
		(end 81.061052 -278.13635)
		(width 0.10668)
		(layer "F.Cu")
		(net "M_E_CPU1_SB_DQ<6>")
	)
	(segment
		(start 52.875434 -287.860232)
		(end 53.725572 -288.71037)
		(width 0.14478)
		(layer "In6.Cu")
		(net "M_E_CPU1_SB_DQ<6>")
	)
	(segment
		(start 75.959208 -277.373842)
		(end 77.96149 -277.373842)
		(width 0.0889)
		(layer "In6.Cu")
		(net "M_E_CPU1_SB_DQ<6>")
	)
	(segment
		(start 78.428342 -277.81377)
		(end 78.443074 -277.822406)
		(width 0.0889)
		(layer "In6.Cu")
		(net "M_E_CPU1_SB_DQ<6>")
	)
	(segment
		(start 75.954636 -277.378414)
		(end 75.959208 -277.373842)
		(width 0.0889)
		(layer "In6.Cu")
		(net "M_E_CPU1_SB_DQ<6>")
	)
	(segment
		(start 25.152096 -288.285428)
		(end 26.009092 -288.285428)
		(width 0.14478)
		(layer "In6.Cu")
		(net "M_E_CPU1_SB_DQ<6>")
	)
	(segment
		(start 57.967372 -287.504886)
		(end 59.274964 -287.504886)
		(width 0.14478)
		(layer "In6.Cu")
		(net "M_E_CPU1_SB_DQ<6>")
	)
	(segment
		(start 42.309288 -288.71037)
		(end 43.159426 -287.860232)
		(width 0.14478)
		(layer "In6.Cu")
		(net "M_E_CPU1_SB_DQ<6>")
	)
	(segment
		(start 70.272148 -277.378414)
		(end 75.954636 -277.378414)
		(width 0.14478)
		(layer "In6.Cu")
		(net "M_E_CPU1_SB_DQ<6>")
	)
	(segment
		(start 27.267662 -288.139378)
		(end 27.430476 -287.976564)
		(width 0.14478)
		(layer "In6.Cu")
		(net "M_E_CPU1_SB_DQ<6>")
	)
	(segment
		(start 27.986736 -288.71037)
		(end 35.11804 -288.71037)
		(width 0.14478)
		(layer "In6.Cu")
		(net "M_E_CPU1_SB_DQ<6>")
	)
	(segment
		(start 56.761888 -288.71037)
		(end 57.967372 -287.504886)
		(width 0.14478)
		(layer "In6.Cu")
		(net "M_E_CPU1_SB_DQ<6>")
	)
	(segment
		(start 27.823922 -288.139378)
		(end 27.823922 -288.547556)
		(width 0.14478)
		(layer "In6.Cu")
		(net "M_E_CPU1_SB_DQ<6>")
	)
	(segment
		(start 45.085254 -287.860232)
		(end 45.935392 -288.71037)
		(width 0.14478)
		(layer "In6.Cu")
		(net "M_E_CPU1_SB_DQ<6>")
	)
	(segment
		(start 26.317956 -287.976564)
		(end 26.548588 -287.976564)
		(width 0.14478)
		(layer "In6.Cu")
		(net "M_E_CPU1_SB_DQ<6>")
	)
	(segment
		(start 27.104848 -288.71037)
		(end 27.267662 -288.547556)
		(width 0.14478)
		(layer "In6.Cu")
		(net "M_E_CPU1_SB_DQ<6>")
	)
	(segment
		(start 77.96149 -277.373842)
		(end 78.312518 -277.72487)
		(width 0.0889)
		(layer "In6.Cu")
		(net "M_E_CPU1_SB_DQ<6>")
	)
	(segment
		(start 27.823922 -288.547556)
		(end 27.986736 -288.71037)
		(width 0.14478)
		(layer "In6.Cu")
		(net "M_E_CPU1_SB_DQ<6>")
	)
	(segment
		(start 27.661108 -287.976564)
		(end 27.823922 -288.139378)
		(width 0.14478)
		(layer "In6.Cu")
		(net "M_E_CPU1_SB_DQ<6>")
	)
	(segment
		(start 50.118264 -288.71037)
		(end 50.968402 -287.860232)
		(width 0.14478)
		(layer "In6.Cu")
		(net "M_E_CPU1_SB_DQ<6>")
	)
	(segment
		(start 45.935392 -288.71037)
		(end 50.118264 -288.71037)
		(width 0.14478)
		(layer "In6.Cu")
		(net "M_E_CPU1_SB_DQ<6>")
	)
	(segment
		(start 50.968402 -287.860232)
		(end 52.875434 -287.860232)
		(width 0.14478)
		(layer "In6.Cu")
		(net "M_E_CPU1_SB_DQ<6>")
	)
	(segment
		(start 79.92364 -277.819866)
		(end 79.934054 -277.81377)
		(width 0.0889)
		(layer "In6.Cu")
		(net "M_E_CPU1_SB_DQ<6>")
	)
	(segment
		(start 35.968178 -287.860232)
		(end 38.100254 -287.860232)
		(width 0.14478)
		(layer "In6.Cu")
		(net "M_E_CPU1_SB_DQ<6>")
	)
	(segment
		(start 81.214976 -277.87092)
		(end 81.061052 -278.13635)
		(width 0.0889)
		(layer "In6.Cu")
		(net "M_E_CPU1_SB_DQ<6>")
	)
	(segment
		(start 38.950392 -288.71037)
		(end 42.309288 -288.71037)
		(width 0.14478)
		(layer "In6.Cu")
		(net "M_E_CPU1_SB_DQ<6>")
	)
	(segment
		(start 79.360014 -277.808944)
		(end 79.368396 -277.81377)
		(width 0.0889)
		(layer "In6.Cu")
		(net "M_E_CPU1_SB_DQ<6>")
	)
	(segment
		(start 38.100254 -287.860232)
		(end 38.950392 -288.71037)
		(width 0.14478)
		(layer "In6.Cu")
		(net "M_E_CPU1_SB_DQ<6>")
	)
	(segment
		(start 26.711402 -288.547556)
		(end 26.874216 -288.71037)
		(width 0.14478)
		(layer "In6.Cu")
		(net "M_E_CPU1_SB_DQ<6>")
	)
	(segment
		(start 43.159426 -287.860232)
		(end 45.085254 -287.860232)
		(width 0.14478)
		(layer "In6.Cu")
		(net "M_E_CPU1_SB_DQ<6>")
	)
	(segment
		(start 59.274964 -287.504886)
		(end 60.761372 -286.88919)
		(width 0.14478)
		(layer "In6.Cu")
		(net "M_E_CPU1_SB_DQ<6>")
	)
	(segment
		(start 35.11804 -288.71037)
		(end 35.968178 -287.860232)
		(width 0.14478)
		(layer "In6.Cu")
		(net "M_E_CPU1_SB_DQ<6>")
	)
	(segment
		(start 79.934054 -277.81377)
		(end 79.942436 -277.808944)
		(width 0.0889)
		(layer "In6.Cu")
		(net "M_E_CPU1_SB_DQ<6>")
	)
	(segment
		(start 27.430476 -287.976564)
		(end 27.661108 -287.976564)
		(width 0.14478)
		(layer "In6.Cu")
		(net "M_E_CPU1_SB_DQ<6>")
	)
	(segment
		(start 81.192624 -277.787608)
		(end 81.214976 -277.87092)
		(width 0.0889)
		(layer "In6.Cu")
		(net "M_E_CPU1_SB_DQ<6>")
	)
	(segment
		(start 26.548588 -287.976564)
		(end 26.711402 -288.139378)
		(width 0.14478)
		(layer "In6.Cu")
		(net "M_E_CPU1_SB_DQ<6>")
	)
	(segment
		(start 53.725572 -288.71037)
		(end 56.761888 -288.71037)
		(width 0.14478)
		(layer "In6.Cu")
		(net "M_E_CPU1_SB_DQ<6>")
	)
	(segment
		(start 27.267662 -288.547556)
		(end 27.267662 -288.139378)
		(width 0.14478)
		(layer "In6.Cu")
		(net "M_E_CPU1_SB_DQ<6>")
	)
	(segment
		(start 26.009092 -288.285428)
		(end 26.317956 -287.976564)
		(width 0.14478)
		(layer "In6.Cu")
		(net "M_E_CPU1_SB_DQ<6>")
	)
	(segment
		(start 26.874216 -288.71037)
		(end 27.104848 -288.71037)
		(width 0.14478)
		(layer "In6.Cu")
		(net "M_E_CPU1_SB_DQ<6>")
	)
	(segment
		(start 60.761372 -286.88919)
		(end 70.272148 -277.378414)
		(width 0.14478)
		(layer "In6.Cu")
		(net "M_E_CPU1_SB_DQ<6>")
	)
	(segment
		(start 26.711402 -288.139378)
		(end 26.711402 -288.547556)
		(width 0.14478)
		(layer "In6.Cu")
		(net "M_E_CPU1_SB_DQ<6>")
	)
	(arc
		(start 78.443074 -277.822406)
		(mid 78.719803 -277.890089)
		(end 78.994254 -277.81377)
		(width 0.0889)
		(layer "In6.Cu")
		(net "M_E_CPU1_SB_DQ<6>")
	)
	(arc
		(start 78.312518 -277.72487)
		(mid 78.367543 -277.77308)
		(end 78.428342 -277.81377)
		(width 0.0889)
		(layer "In6.Cu")
		(net "M_E_CPU1_SB_DQ<6>")
	)
	(arc
		(start 79.942436 -277.808944)
		(mid 80.125944 -277.76345)
		(end 80.308196 -277.81377)
		(width 0.0889)
		(layer "In6.Cu")
		(net "M_E_CPU1_SB_DQ<6>")
	)
	(arc
		(start 78.994254 -277.81377)
		(mid 79.176505 -277.76342)
		(end 79.360014 -277.808944)
		(width 0.0889)
		(layer "In6.Cu")
		(net "M_E_CPU1_SB_DQ<6>")
	)
	(arc
		(start 79.368396 -277.81377)
		(mid 79.645209 -277.889913)
		(end 79.92364 -277.819866)
		(width 0.0889)
		(layer "In6.Cu")
		(net "M_E_CPU1_SB_DQ<6>")
	)
	(arc
		(start 80.308196 -277.81377)
		(mid 80.591152 -277.889947)
		(end 80.874108 -277.81377)
		(width 0.0889)
		(layer "In6.Cu")
		(net "M_E_CPU1_SB_DQ<6>")
	)
	(arc
		(start 80.874108 -277.81377)
		(mid 81.030427 -277.764775)
		(end 81.192624 -277.787608)
		(width 0.0889)
		(layer "In6.Cu")
		(net "M_E_CPU1_SB_DQ<6>")
	)
	(segment
		(start 83.408012 -277.870412)
		(end 82.940906 -278.13635)
		(width 0.10668)
		(layer "F.Cu")
		(net "M_E_CPU1_SB_DQ<5>")
	)
	(segment
		(start 41.84904 -289.856164)
		(end 42.994834 -288.71037)
		(width 0.14478)
		(layer "In6.Cu")
		(net "M_E_CPU1_SB_DQ<5>")
	)
	(segment
		(start 56.05907 -289.881564)
		(end 56.380126 -289.560508)
		(width 0.14478)
		(layer "In6.Cu")
		(net "M_E_CPU1_SB_DQ<5>")
	)
	(segment
		(start 39.25824 -289.881564)
		(end 39.602918 -289.881564)
		(width 0.14478)
		(layer "In6.Cu")
		(net "M_E_CPU1_SB_DQ<5>")
	)
	(segment
		(start 54.711346 -289.881564)
		(end 54.94655 -289.881564)
		(width 0.14478)
		(layer "In6.Cu")
		(net "M_E_CPU1_SB_DQ<5>")
	)
	(segment
		(start 41.484042 -289.856164)
		(end 41.84904 -289.856164)
		(width 0.14478)
		(layer "In6.Cu")
		(net "M_E_CPU1_SB_DQ<5>")
	)
	(segment
		(start 46.65599 -289.881564)
		(end 46.977046 -289.560508)
		(width 0.14478)
		(layer "In6.Cu")
		(net "M_E_CPU1_SB_DQ<5>")
	)
	(segment
		(start 33.312608 -289.856164)
		(end 33.573212 -289.856164)
		(width 0.14478)
		(layer "In6.Cu")
		(net "M_E_CPU1_SB_DQ<5>")
	)
	(segment
		(start 30.545532 -289.76955)
		(end 30.545532 -289.351466)
		(width 0.14478)
		(layer "In6.Cu")
		(net "M_E_CPU1_SB_DQ<5>")
	)
	(segment
		(start 46.26864 -289.881564)
		(end 46.65599 -289.881564)
		(width 0.14478)
		(layer "In6.Cu")
		(net "M_E_CPU1_SB_DQ<5>")
	)
	(segment
		(start 39.602918 -289.881564)
		(end 39.923974 -289.560508)
		(width 0.14478)
		(layer "In6.Cu")
		(net "M_E_CPU1_SB_DQ<5>")
	)
	(segment
		(start 30.545532 -289.351466)
		(end 30.708346 -289.188652)
		(width 0.14478)
		(layer "In6.Cu")
		(net "M_E_CPU1_SB_DQ<5>")
	)
	(segment
		(start 33.573212 -289.856164)
		(end 33.72104 -289.708336)
		(width 0.14478)
		(layer "In6.Cu")
		(net "M_E_CPU1_SB_DQ<5>")
	)
	(segment
		(start 31.658052 -289.76955)
		(end 31.658052 -289.351466)
		(width 0.14478)
		(layer "In6.Cu")
		(net "M_E_CPU1_SB_DQ<5>")
	)
	(segment
		(start 49.355248 -289.830764)
		(end 49.641252 -289.830764)
		(width 0.14478)
		(layer "In6.Cu")
		(net "M_E_CPU1_SB_DQ<5>")
	)
	(segment
		(start 79.869792 -278.421592)
		(end 79.9338 -278.45893)
		(width 0.0889)
		(layer "In6.Cu")
		(net "M_E_CPU1_SB_DQ<5>")
	)
	(segment
		(start 49.641252 -289.830764)
		(end 50.761646 -288.71037)
		(width 0.14478)
		(layer "In6.Cu")
		(net "M_E_CPU1_SB_DQ<5>")
	)
	(segment
		(start 34.129472 -289.264852)
		(end 34.425128 -289.560508)
		(width 0.14478)
		(layer "In6.Cu")
		(net "M_E_CPU1_SB_DQ<5>")
	)
	(segment
		(start 48.242728 -289.830764)
		(end 48.528732 -289.830764)
		(width 0.14478)
		(layer "In6.Cu")
		(net "M_E_CPU1_SB_DQ<5>")
	)
	(segment
		(start 34.956496 -289.560508)
		(end 35.806634 -288.71037)
		(width 0.14478)
		(layer "In6.Cu")
		(net "M_E_CPU1_SB_DQ<5>")
	)
	(segment
		(start 47.972472 -289.560508)
		(end 48.242728 -289.830764)
		(width 0.14478)
		(layer "In6.Cu")
		(net "M_E_CPU1_SB_DQ<5>")
	)
	(segment
		(start 39.923974 -289.560508)
		(end 41.188386 -289.560508)
		(width 0.14478)
		(layer "In6.Cu")
		(net "M_E_CPU1_SB_DQ<5>")
	)
	(segment
		(start 32.051498 -289.188652)
		(end 32.423354 -289.560508)
		(width 0.14478)
		(layer "In6.Cu")
		(net "M_E_CPU1_SB_DQ<5>")
	)
	(segment
		(start 54.39029 -289.560508)
		(end 54.711346 -289.881564)
		(width 0.14478)
		(layer "In6.Cu")
		(net "M_E_CPU1_SB_DQ<5>")
	)
	(segment
		(start 31.101792 -289.351466)
		(end 31.101792 -289.76955)
		(width 0.14478)
		(layer "In6.Cu")
		(net "M_E_CPU1_SB_DQ<5>")
	)
	(segment
		(start 31.658052 -289.351466)
		(end 31.820866 -289.188652)
		(width 0.14478)
		(layer "In6.Cu")
		(net "M_E_CPU1_SB_DQ<5>")
	)
	(segment
		(start 33.72104 -289.708336)
		(end 33.72104 -289.41268)
		(width 0.14478)
		(layer "In6.Cu")
		(net "M_E_CPU1_SB_DQ<5>")
	)
	(segment
		(start 33.016952 -289.560508)
		(end 33.312608 -289.856164)
		(width 0.14478)
		(layer "In6.Cu")
		(net "M_E_CPU1_SB_DQ<5>")
	)
	(segment
		(start 48.528732 -289.830764)
		(end 48.798988 -289.560508)
		(width 0.14478)
		(layer "In6.Cu")
		(net "M_E_CPU1_SB_DQ<5>")
	)
	(segment
		(start 82.179668 -278.463756)
		(end 82.18805 -278.45893)
		(width 0.0889)
		(layer "In6.Cu")
		(net "M_E_CPU1_SB_DQ<5>")
	)
	(segment
		(start 33.868868 -289.264852)
		(end 34.129472 -289.264852)
		(width 0.14478)
		(layer "In6.Cu")
		(net "M_E_CPU1_SB_DQ<5>")
	)
	(segment
		(start 48.798988 -289.560508)
		(end 49.084992 -289.560508)
		(width 0.14478)
		(layer "In6.Cu")
		(net "M_E_CPU1_SB_DQ<5>")
	)
	(segment
		(start 30.049216 -289.932364)
		(end 30.382718 -289.932364)
		(width 0.14478)
		(layer "In6.Cu")
		(net "M_E_CPU1_SB_DQ<5>")
	)
	(segment
		(start 59.51093 -288.700718)
		(end 59.663584 -288.637472)
		(width 0.14478)
		(layer "In6.Cu")
		(net "M_E_CPU1_SB_DQ<5>")
	)
	(segment
		(start 30.382718 -289.932364)
		(end 30.545532 -289.76955)
		(width 0.14478)
		(layer "In6.Cu")
		(net "M_E_CPU1_SB_DQ<5>")
	)
	(segment
		(start 56.612028 -289.560508)
		(end 57.471818 -288.700718)
		(width 0.14478)
		(layer "In6.Cu")
		(net "M_E_CPU1_SB_DQ<5>")
	)
	(segment
		(start 55.823866 -289.881564)
		(end 56.05907 -289.881564)
		(width 0.14478)
		(layer "In6.Cu")
		(net "M_E_CPU1_SB_DQ<5>")
	)
	(segment
		(start 45.097446 -288.71037)
		(end 46.26864 -289.881564)
		(width 0.14478)
		(layer "In6.Cu")
		(net "M_E_CPU1_SB_DQ<5>")
	)
	(segment
		(start 31.820866 -289.188652)
		(end 32.051498 -289.188652)
		(width 0.14478)
		(layer "In6.Cu")
		(net "M_E_CPU1_SB_DQ<5>")
	)
	(segment
		(start 41.188386 -289.560508)
		(end 41.484042 -289.856164)
		(width 0.14478)
		(layer "In6.Cu")
		(net "M_E_CPU1_SB_DQ<5>")
	)
	(segment
		(start 53.932328 -289.560508)
		(end 54.39029 -289.560508)
		(width 0.14478)
		(layer "In6.Cu")
		(net "M_E_CPU1_SB_DQ<5>")
	)
	(segment
		(start 53.08219 -288.71037)
		(end 53.932328 -289.560508)
		(width 0.14478)
		(layer "In6.Cu")
		(net "M_E_CPU1_SB_DQ<5>")
	)
	(segment
		(start 76.951586 -278.255984)
		(end 79.253842 -278.255984)
		(width 0.0889)
		(layer "In6.Cu")
		(net "M_E_CPU1_SB_DQ<5>")
	)
	(segment
		(start 34.425128 -289.560508)
		(end 34.956496 -289.560508)
		(width 0.14478)
		(layer "In6.Cu")
		(net "M_E_CPU1_SB_DQ<5>")
	)
	(segment
		(start 31.495238 -289.932364)
		(end 31.658052 -289.76955)
		(width 0.14478)
		(layer "In6.Cu")
		(net "M_E_CPU1_SB_DQ<5>")
	)
	(segment
		(start 42.994834 -288.71037)
		(end 45.097446 -288.71037)
		(width 0.14478)
		(layer "In6.Cu")
		(net "M_E_CPU1_SB_DQ<5>")
	)
	(segment
		(start 31.101792 -289.76955)
		(end 31.264606 -289.932364)
		(width 0.14478)
		(layer "In6.Cu")
		(net "M_E_CPU1_SB_DQ<5>")
	)
	(segment
		(start 55.50281 -289.560508)
		(end 55.823866 -289.881564)
		(width 0.14478)
		(layer "In6.Cu")
		(net "M_E_CPU1_SB_DQ<5>")
	)
	(segment
		(start 55.267606 -289.560508)
		(end 55.50281 -289.560508)
		(width 0.14478)
		(layer "In6.Cu")
		(net "M_E_CPU1_SB_DQ<5>")
	)
	(segment
		(start 46.977046 -289.560508)
		(end 47.972472 -289.560508)
		(width 0.14478)
		(layer "In6.Cu")
		(net "M_E_CPU1_SB_DQ<5>")
	)
	(segment
		(start 82.786982 -278.40178)
		(end 82.940906 -278.13635)
		(width 0.0889)
		(layer "In6.Cu")
		(net "M_E_CPU1_SB_DQ<5>")
	)
	(segment
		(start 76.034392 -277.833074)
		(end 76.528676 -277.833074)
		(width 0.0889)
		(layer "In6.Cu")
		(net "M_E_CPU1_SB_DQ<5>")
	)
	(segment
		(start 49.084992 -289.560508)
		(end 49.355248 -289.830764)
		(width 0.14478)
		(layer "In6.Cu")
		(net "M_E_CPU1_SB_DQ<5>")
	)
	(segment
		(start 35.806634 -288.71037)
		(end 38.087046 -288.71037)
		(width 0.14478)
		(layer "In6.Cu")
		(net "M_E_CPU1_SB_DQ<5>")
	)
	(segment
		(start 70.467982 -277.833074)
		(end 76.034392 -277.833074)
		(width 0.14478)
		(layer "In6.Cu")
		(net "M_E_CPU1_SB_DQ<5>")
	)
	(segment
		(start 30.708346 -289.188652)
		(end 30.938978 -289.188652)
		(width 0.14478)
		(layer "In6.Cu")
		(net "M_E_CPU1_SB_DQ<5>")
	)
	(segment
		(start 30.938978 -289.188652)
		(end 31.101792 -289.351466)
		(width 0.14478)
		(layer "In6.Cu")
		(net "M_E_CPU1_SB_DQ<5>")
	)
	(segment
		(start 29.252164 -289.135312)
		(end 30.049216 -289.932364)
		(width 0.14478)
		(layer "In6.Cu")
		(net "M_E_CPU1_SB_DQ<5>")
	)
	(segment
		(start 33.72104 -289.41268)
		(end 33.868868 -289.264852)
		(width 0.14478)
		(layer "In6.Cu")
		(net "M_E_CPU1_SB_DQ<5>")
	)
	(segment
		(start 76.528676 -277.833074)
		(end 76.951586 -278.255984)
		(width 0.0889)
		(layer "In6.Cu")
		(net "M_E_CPU1_SB_DQ<5>")
	)
	(segment
		(start 31.264606 -289.932364)
		(end 31.495238 -289.932364)
		(width 0.14478)
		(layer "In6.Cu")
		(net "M_E_CPU1_SB_DQ<5>")
	)
	(segment
		(start 59.663584 -288.637472)
		(end 70.467982 -277.833074)
		(width 0.14478)
		(layer "In6.Cu")
		(net "M_E_CPU1_SB_DQ<5>")
	)
	(segment
		(start 38.087046 -288.71037)
		(end 39.25824 -289.881564)
		(width 0.14478)
		(layer "In6.Cu")
		(net "M_E_CPU1_SB_DQ<5>")
	)
	(segment
		(start 82.69097 -278.42718)
		(end 82.786982 -278.40178)
		(width 0.0889)
		(layer "In6.Cu")
		(net "M_E_CPU1_SB_DQ<5>")
	)
	(segment
		(start 54.94655 -289.881564)
		(end 55.267606 -289.560508)
		(width 0.14478)
		(layer "In6.Cu")
		(net "M_E_CPU1_SB_DQ<5>")
	)
	(segment
		(start 50.761646 -288.71037)
		(end 53.08219 -288.71037)
		(width 0.14478)
		(layer "In6.Cu")
		(net "M_E_CPU1_SB_DQ<5>")
	)
	(segment
		(start 32.423354 -289.560508)
		(end 33.016952 -289.560508)
		(width 0.14478)
		(layer "In6.Cu")
		(net "M_E_CPU1_SB_DQ<5>")
	)
	(segment
		(start 57.471818 -288.700718)
		(end 59.51093 -288.700718)
		(width 0.14478)
		(layer "In6.Cu")
		(net "M_E_CPU1_SB_DQ<5>")
	)
	(segment
		(start 56.380126 -289.560508)
		(end 56.612028 -289.560508)
		(width 0.14478)
		(layer "In6.Cu")
		(net "M_E_CPU1_SB_DQ<5>")
	)
	(arc
		(start 82.18805 -278.45893)
		(mid 82.435763 -278.38371)
		(end 82.69097 -278.42718)
		(width 0.0889)
		(layer "In6.Cu")
		(net "M_E_CPU1_SB_DQ<5>")
	)
	(arc
		(start 80.874108 -278.45893)
		(mid 81.061052 -278.509185)
		(end 81.247996 -278.45893)
		(width 0.0889)
		(layer "In6.Cu")
		(net "M_E_CPU1_SB_DQ<5>")
	)
	(arc
		(start 81.813908 -278.45893)
		(mid 81.996159 -278.50928)
		(end 82.179668 -278.463756)
		(width 0.0889)
		(layer "In6.Cu")
		(net "M_E_CPU1_SB_DQ<5>")
	)
	(arc
		(start 79.9338 -278.45893)
		(mid 80.120998 -278.509312)
		(end 80.308196 -278.45893)
		(width 0.0889)
		(layer "In6.Cu")
		(net "M_E_CPU1_SB_DQ<5>")
	)
	(arc
		(start 80.308196 -278.45893)
		(mid 80.591152 -278.382753)
		(end 80.874108 -278.45893)
		(width 0.0889)
		(layer "In6.Cu")
		(net "M_E_CPU1_SB_DQ<5>")
	)
	(arc
		(start 79.253842 -278.255984)
		(mid 79.57278 -278.29803)
		(end 79.869792 -278.421592)
		(width 0.0889)
		(layer "In6.Cu")
		(net "M_E_CPU1_SB_DQ<5>")
	)
	(arc
		(start 81.247996 -278.45893)
		(mid 81.530952 -278.382753)
		(end 81.813908 -278.45893)
		(width 0.0889)
		(layer "In6.Cu")
		(net "M_E_CPU1_SB_DQ<5>")
	)
	(segment
		(start 81.997804 -277.060406)
		(end 81.530952 -277.326344)
		(width 0.10668)
		(layer "F.Cu")
		(net "M_E_CPU1_SB_DQ<4>")
	)
	(segment
		(start 54.568598 -287.678622)
		(end 54.731412 -287.515808)
		(width 0.14478)
		(layer "In6.Cu")
		(net "M_E_CPU1_SB_DQ<4>")
	)
	(segment
		(start 59.39282 -286.273748)
		(end 59.73953 -286.130238)
		(width 0.14478)
		(layer "In6.Cu")
		(net "M_E_CPU1_SB_DQ<4>")
	)
	(segment
		(start 31.726886 -287.870138)
		(end 33.927796 -287.870138)
		(width 0.14478)
		(layer "In6.Cu")
		(net "M_E_CPU1_SB_DQ<4>")
	)
	(segment
		(start 52.67833 -287.02)
		(end 53.518816 -287.860486)
		(width 0.14478)
		(layer "In6.Cu")
		(net "M_E_CPU1_SB_DQ<4>")
	)
	(segment
		(start 49.005744 -287.860486)
		(end 49.268126 -287.860486)
		(width 0.14478)
		(layer "In6.Cu")
		(net "M_E_CPU1_SB_DQ<4>")
	)
	(segment
		(start 77.937106 -277.079964)
		(end 78.447138 -277.589996)
		(width 0.0889)
		(layer "In6.Cu")
		(net "M_E_CPU1_SB_DQ<4>")
	)
	(segment
		(start 38.009322 -287.02)
		(end 39.143686 -288.154364)
		(width 0.14478)
		(layer "In6.Cu")
		(net "M_E_CPU1_SB_DQ<4>")
	)
	(segment
		(start 34.217356 -288.251646)
		(end 34.491676 -288.251646)
		(width 0.14478)
		(layer "In6.Cu")
		(net "M_E_CPU1_SB_DQ<4>")
	)
	(segment
		(start 55.287672 -288.205164)
		(end 55.518304 -288.205164)
		(width 0.14478)
		(layer "In6.Cu")
		(net "M_E_CPU1_SB_DQ<4>")
	)
	(segment
		(start 36.02355 -287.02)
		(end 38.009322 -287.02)
		(width 0.14478)
		(layer "In6.Cu")
		(net "M_E_CPU1_SB_DQ<4>")
	)
	(segment
		(start 75.957176 -276.923754)
		(end 76.41844 -276.923754)
		(width 0.0889)
		(layer "In6.Cu")
		(net "M_E_CPU1_SB_DQ<4>")
	)
	(segment
		(start 46.455076 -288.179764)
		(end 46.764702 -287.870138)
		(width 0.14478)
		(layer "In6.Cu")
		(net "M_E_CPU1_SB_DQ<4>")
	)
	(segment
		(start 30.883098 -287.870138)
		(end 31.163006 -288.150046)
		(width 0.14478)
		(layer "In6.Cu")
		(net "M_E_CPU1_SB_DQ<4>")
	)
	(segment
		(start 55.124858 -288.04235)
		(end 55.287672 -288.205164)
		(width 0.14478)
		(layer "In6.Cu")
		(net "M_E_CPU1_SB_DQ<4>")
	)
	(segment
		(start 55.681118 -287.678622)
		(end 55.843932 -287.515808)
		(width 0.14478)
		(layer "In6.Cu")
		(net "M_E_CPU1_SB_DQ<4>")
	)
	(segment
		(start 59.73953 -286.130238)
		(end 59.928506 -286.208724)
		(width 0.14478)
		(layer "In6.Cu")
		(net "M_E_CPU1_SB_DQ<4>")
	)
	(segment
		(start 55.681118 -288.04235)
		(end 55.681118 -287.678622)
		(width 0.14478)
		(layer "In6.Cu")
		(net "M_E_CPU1_SB_DQ<4>")
	)
	(segment
		(start 41.624504 -287.913064)
		(end 41.840404 -288.128964)
		(width 0.14478)
		(layer "In6.Cu")
		(net "M_E_CPU1_SB_DQ<4>")
	)
	(segment
		(start 31.163006 -288.150046)
		(end 31.446978 -288.150046)
		(width 0.14478)
		(layer "In6.Cu")
		(net "M_E_CPU1_SB_DQ<4>")
	)
	(segment
		(start 53.830474 -287.860486)
		(end 54.175152 -288.205164)
		(width 0.14478)
		(layer "In6.Cu")
		(net "M_E_CPU1_SB_DQ<4>")
	)
	(segment
		(start 48.449484 -288.154364)
		(end 48.711866 -288.154364)
		(width 0.14478)
		(layer "In6.Cu")
		(net "M_E_CPU1_SB_DQ<4>")
	)
	(segment
		(start 48.711866 -288.154364)
		(end 49.005744 -287.860486)
		(width 0.14478)
		(layer "In6.Cu")
		(net "M_E_CPU1_SB_DQ<4>")
	)
	(segment
		(start 55.518304 -288.205164)
		(end 55.681118 -288.04235)
		(width 0.14478)
		(layer "In6.Cu")
		(net "M_E_CPU1_SB_DQ<4>")
	)
	(segment
		(start 60.527946 -285.803848)
		(end 61.635894 -285.344616)
		(width 0.14478)
		(layer "In6.Cu")
		(net "M_E_CPU1_SB_DQ<4>")
	)
	(segment
		(start 54.731412 -287.515808)
		(end 54.962044 -287.515808)
		(width 0.14478)
		(layer "In6.Cu")
		(net "M_E_CPU1_SB_DQ<4>")
	)
	(segment
		(start 49.562004 -288.154364)
		(end 49.842674 -288.154364)
		(width 0.14478)
		(layer "In6.Cu")
		(net "M_E_CPU1_SB_DQ<4>")
	)
	(segment
		(start 35.173412 -287.870138)
		(end 36.02355 -287.02)
		(width 0.14478)
		(layer "In6.Cu")
		(net "M_E_CPU1_SB_DQ<4>")
	)
	(segment
		(start 49.842674 -288.154364)
		(end 50.977038 -287.02)
		(width 0.14478)
		(layer "In6.Cu")
		(net "M_E_CPU1_SB_DQ<4>")
	)
	(segment
		(start 80.769714 -277.65375)
		(end 80.778096 -277.648924)
		(width 0.0889)
		(layer "In6.Cu")
		(net "M_E_CPU1_SB_DQ<4>")
	)
	(segment
		(start 60.25261 -286.613092)
		(end 60.50661 -286.507936)
		(width 0.14478)
		(layer "In6.Cu")
		(net "M_E_CPU1_SB_DQ<4>")
	)
	(segment
		(start 54.962044 -287.515808)
		(end 55.124858 -287.678622)
		(width 0.14478)
		(layer "In6.Cu")
		(net "M_E_CPU1_SB_DQ<4>")
	)
	(segment
		(start 54.175152 -288.205164)
		(end 54.405784 -288.205164)
		(width 0.14478)
		(layer "In6.Cu")
		(net "M_E_CPU1_SB_DQ<4>")
	)
	(segment
		(start 76.41844 -276.923754)
		(end 76.57465 -277.079964)
		(width 0.0889)
		(layer "In6.Cu")
		(net "M_E_CPU1_SB_DQ<4>")
	)
	(segment
		(start 57.780682 -287.055306)
		(end 58.91657 -287.055306)
		(width 0.14478)
		(layer "In6.Cu")
		(net "M_E_CPU1_SB_DQ<4>")
	)
	(segment
		(start 56.400192 -288.205164)
		(end 56.630824 -288.205164)
		(width 0.14478)
		(layer "In6.Cu")
		(net "M_E_CPU1_SB_DQ<4>")
	)
	(segment
		(start 60.063634 -286.53486)
		(end 60.25261 -286.613092)
		(width 0.14478)
		(layer "In6.Cu")
		(net "M_E_CPU1_SB_DQ<4>")
	)
	(segment
		(start 44.94149 -287.02)
		(end 46.101254 -288.179764)
		(width 0.14478)
		(layer "In6.Cu")
		(net "M_E_CPU1_SB_DQ<4>")
	)
	(segment
		(start 56.074564 -287.515808)
		(end 56.237378 -287.678622)
		(width 0.14478)
		(layer "In6.Cu")
		(net "M_E_CPU1_SB_DQ<4>")
	)
	(segment
		(start 78.524354 -277.648924)
		(end 78.536038 -277.655782)
		(width 0.0889)
		(layer "In6.Cu")
		(net "M_E_CPU1_SB_DQ<4>")
	)
	(segment
		(start 49.268126 -287.860486)
		(end 49.562004 -288.154364)
		(width 0.14478)
		(layer "In6.Cu")
		(net "M_E_CPU1_SB_DQ<4>")
	)
	(segment
		(start 34.636456 -288.106866)
		(end 34.636456 -288.014918)
		(width 0.14478)
		(layer "In6.Cu")
		(net "M_E_CPU1_SB_DQ<4>")
	)
	(segment
		(start 78.447138 -277.589996)
		(end 78.447392 -277.589996)
		(width 0.0889)
		(layer "In6.Cu")
		(net "M_E_CPU1_SB_DQ<4>")
	)
	(segment
		(start 55.124858 -287.678622)
		(end 55.124858 -288.04235)
		(width 0.14478)
		(layer "In6.Cu")
		(net "M_E_CPU1_SB_DQ<4>")
	)
	(segment
		(start 29.827474 -287.43529)
		(end 30.262322 -287.870138)
		(width 0.14478)
		(layer "In6.Cu")
		(net "M_E_CPU1_SB_DQ<4>")
	)
	(segment
		(start 56.630824 -288.205164)
		(end 57.780682 -287.055306)
		(width 0.14478)
		(layer "In6.Cu")
		(net "M_E_CPU1_SB_DQ<4>")
	)
	(segment
		(start 56.237378 -287.678622)
		(end 56.237378 -288.04235)
		(width 0.14478)
		(layer "In6.Cu")
		(net "M_E_CPU1_SB_DQ<4>")
	)
	(segment
		(start 40.727884 -288.128964)
		(end 41.015666 -288.128964)
		(width 0.14478)
		(layer "In6.Cu")
		(net "M_E_CPU1_SB_DQ<4>")
	)
	(segment
		(start 79.838296 -277.648924)
		(end 79.84871 -277.642828)
		(width 0.0889)
		(layer "In6.Cu")
		(net "M_E_CPU1_SB_DQ<4>")
	)
	(segment
		(start 34.072576 -288.014918)
		(end 34.072576 -288.106866)
		(width 0.14478)
		(layer "In6.Cu")
		(net "M_E_CPU1_SB_DQ<4>")
	)
	(segment
		(start 59.06135 -286.605218)
		(end 59.39282 -286.273748)
		(width 0.14478)
		(layer "In6.Cu")
		(net "M_E_CPU1_SB_DQ<4>")
	)
	(segment
		(start 46.764702 -287.870138)
		(end 48.165258 -287.870138)
		(width 0.14478)
		(layer "In6.Cu")
		(net "M_E_CPU1_SB_DQ<4>")
	)
	(segment
		(start 39.495476 -288.154364)
		(end 39.779702 -287.870138)
		(width 0.14478)
		(layer "In6.Cu")
		(net "M_E_CPU1_SB_DQ<4>")
	)
	(segment
		(start 40.469058 -287.870138)
		(end 40.727884 -288.128964)
		(width 0.14478)
		(layer "In6.Cu")
		(net "M_E_CPU1_SB_DQ<4>")
	)
	(segment
		(start 50.977038 -287.02)
		(end 52.67833 -287.02)
		(width 0.14478)
		(layer "In6.Cu")
		(net "M_E_CPU1_SB_DQ<4>")
	)
	(segment
		(start 41.231566 -287.913064)
		(end 41.624504 -287.913064)
		(width 0.14478)
		(layer "In6.Cu")
		(net "M_E_CPU1_SB_DQ<4>")
	)
	(segment
		(start 31.446978 -288.150046)
		(end 31.726886 -287.870138)
		(width 0.14478)
		(layer "In6.Cu")
		(net "M_E_CPU1_SB_DQ<4>")
	)
	(segment
		(start 41.840404 -288.128964)
		(end 42.128186 -288.128964)
		(width 0.14478)
		(layer "In6.Cu")
		(net "M_E_CPU1_SB_DQ<4>")
	)
	(segment
		(start 42.128186 -288.128964)
		(end 43.23715 -287.02)
		(width 0.14478)
		(layer "In6.Cu")
		(net "M_E_CPU1_SB_DQ<4>")
	)
	(segment
		(start 41.015666 -288.128964)
		(end 41.231566 -287.913064)
		(width 0.14478)
		(layer "In6.Cu")
		(net "M_E_CPU1_SB_DQ<4>")
	)
	(segment
		(start 60.584842 -286.31896)
		(end 60.449714 -285.992824)
		(width 0.14478)
		(layer "In6.Cu")
		(net "M_E_CPU1_SB_DQ<4>")
	)
	(segment
		(start 60.50661 -286.507936)
		(end 60.584842 -286.31896)
		(width 0.14478)
		(layer "In6.Cu")
		(net "M_E_CPU1_SB_DQ<4>")
	)
	(segment
		(start 55.843932 -287.515808)
		(end 56.074564 -287.515808)
		(width 0.14478)
		(layer "In6.Cu")
		(net "M_E_CPU1_SB_DQ<4>")
	)
	(segment
		(start 39.143686 -288.154364)
		(end 39.495476 -288.154364)
		(width 0.14478)
		(layer "In6.Cu")
		(net "M_E_CPU1_SB_DQ<4>")
	)
	(segment
		(start 53.518816 -287.860486)
		(end 53.830474 -287.860486)
		(width 0.14478)
		(layer "In6.Cu")
		(net "M_E_CPU1_SB_DQ<4>")
	)
	(segment
		(start 29.252164 -287.43529)
		(end 29.827474 -287.43529)
		(width 0.14478)
		(layer "In6.Cu")
		(net "M_E_CPU1_SB_DQ<4>")
	)
	(segment
		(start 76.57465 -277.079964)
		(end 77.937106 -277.079964)
		(width 0.0889)
		(layer "In6.Cu")
		(net "M_E_CPU1_SB_DQ<4>")
	)
	(segment
		(start 33.927796 -287.870138)
		(end 34.072576 -288.014918)
		(width 0.14478)
		(layer "In6.Cu")
		(net "M_E_CPU1_SB_DQ<4>")
	)
	(segment
		(start 54.568598 -288.04235)
		(end 54.568598 -287.678622)
		(width 0.14478)
		(layer "In6.Cu")
		(net "M_E_CPU1_SB_DQ<4>")
	)
	(segment
		(start 34.491676 -288.251646)
		(end 34.636456 -288.106866)
		(width 0.14478)
		(layer "In6.Cu")
		(net "M_E_CPU1_SB_DQ<4>")
	)
	(segment
		(start 59.06135 -286.910526)
		(end 59.06135 -286.605218)
		(width 0.14478)
		(layer "In6.Cu")
		(net "M_E_CPU1_SB_DQ<4>")
	)
	(segment
		(start 30.262322 -287.870138)
		(end 30.883098 -287.870138)
		(width 0.14478)
		(layer "In6.Cu")
		(net "M_E_CPU1_SB_DQ<4>")
	)
	(segment
		(start 34.072576 -288.106866)
		(end 34.217356 -288.251646)
		(width 0.14478)
		(layer "In6.Cu")
		(net "M_E_CPU1_SB_DQ<4>")
	)
	(segment
		(start 56.237378 -288.04235)
		(end 56.400192 -288.205164)
		(width 0.14478)
		(layer "In6.Cu")
		(net "M_E_CPU1_SB_DQ<4>")
	)
	(segment
		(start 39.779702 -287.870138)
		(end 40.469058 -287.870138)
		(width 0.14478)
		(layer "In6.Cu")
		(net "M_E_CPU1_SB_DQ<4>")
	)
	(segment
		(start 54.405784 -288.205164)
		(end 54.568598 -288.04235)
		(width 0.14478)
		(layer "In6.Cu")
		(net "M_E_CPU1_SB_DQ<4>")
	)
	(segment
		(start 34.636456 -288.014918)
		(end 34.781236 -287.870138)
		(width 0.14478)
		(layer "In6.Cu")
		(net "M_E_CPU1_SB_DQ<4>")
	)
	(segment
		(start 34.781236 -287.870138)
		(end 35.173412 -287.870138)
		(width 0.14478)
		(layer "In6.Cu")
		(net "M_E_CPU1_SB_DQ<4>")
	)
	(segment
		(start 48.165258 -287.870138)
		(end 48.449484 -288.154364)
		(width 0.14478)
		(layer "In6.Cu")
		(net "M_E_CPU1_SB_DQ<4>")
	)
	(segment
		(start 60.449714 -285.992824)
		(end 60.527946 -285.803848)
		(width 0.14478)
		(layer "In6.Cu")
		(net "M_E_CPU1_SB_DQ<4>")
	)
	(segment
		(start 46.101254 -288.179764)
		(end 46.455076 -288.179764)
		(width 0.14478)
		(layer "In6.Cu")
		(net "M_E_CPU1_SB_DQ<4>")
	)
	(segment
		(start 61.635894 -285.344616)
		(end 70.056756 -276.923754)
		(width 0.14478)
		(layer "In6.Cu")
		(net "M_E_CPU1_SB_DQ<4>")
	)
	(segment
		(start 79.453994 -277.642828)
		(end 79.464408 -277.648924)
		(width 0.0889)
		(layer "In6.Cu")
		(net "M_E_CPU1_SB_DQ<4>")
	)
	(segment
		(start 81.281016 -277.617174)
		(end 81.377028 -277.591774)
		(width 0.0889)
		(layer "In6.Cu")
		(net "M_E_CPU1_SB_DQ<4>")
	)
	(segment
		(start 59.928506 -286.208724)
		(end 60.063634 -286.53486)
		(width 0.14478)
		(layer "In6.Cu")
		(net "M_E_CPU1_SB_DQ<4>")
	)
	(segment
		(start 70.056756 -276.923754)
		(end 75.957176 -276.923754)
		(width 0.14478)
		(layer "In6.Cu")
		(net "M_E_CPU1_SB_DQ<4>")
	)
	(segment
		(start 81.377028 -277.591774)
		(end 81.530952 -277.326344)
		(width 0.0889)
		(layer "In6.Cu")
		(net "M_E_CPU1_SB_DQ<4>")
	)
	(segment
		(start 43.23715 -287.02)
		(end 44.94149 -287.02)
		(width 0.14478)
		(layer "In6.Cu")
		(net "M_E_CPU1_SB_DQ<4>")
	)
	(segment
		(start 58.91657 -287.055306)
		(end 59.06135 -286.910526)
		(width 0.14478)
		(layer "In6.Cu")
		(net "M_E_CPU1_SB_DQ<4>")
	)
	(arc
		(start 78.536038 -277.655782)
		(mid 78.718039 -277.699315)
		(end 78.898242 -277.648924)
		(width 0.0889)
		(layer "In6.Cu")
		(net "M_E_CPU1_SB_DQ<4>")
	)
	(arc
		(start 78.898242 -277.648924)
		(mid 79.175309 -277.572653)
		(end 79.453994 -277.642828)
		(width 0.0889)
		(layer "In6.Cu")
		(net "M_E_CPU1_SB_DQ<4>")
	)
	(arc
		(start 79.464408 -277.648924)
		(mid 79.651352 -277.699179)
		(end 79.838296 -277.648924)
		(width 0.0889)
		(layer "In6.Cu")
		(net "M_E_CPU1_SB_DQ<4>")
	)
	(arc
		(start 79.84871 -277.642828)
		(mid 80.127142 -277.57273)
		(end 80.403954 -277.648924)
		(width 0.0889)
		(layer "In6.Cu")
		(net "M_E_CPU1_SB_DQ<4>")
	)
	(arc
		(start 78.447392 -277.589996)
		(mid 78.483947 -277.621976)
		(end 78.524354 -277.648924)
		(width 0.0889)
		(layer "In6.Cu")
		(net "M_E_CPU1_SB_DQ<4>")
	)
	(arc
		(start 80.403954 -277.648924)
		(mid 80.586205 -277.699274)
		(end 80.769714 -277.65375)
		(width 0.0889)
		(layer "In6.Cu")
		(net "M_E_CPU1_SB_DQ<4>")
	)
	(arc
		(start 80.778096 -277.648924)
		(mid 81.025809 -277.573704)
		(end 81.281016 -277.617174)
		(width 0.0889)
		(layer "In6.Cu")
		(net "M_E_CPU1_SB_DQ<4>")
	)
	(segment
		(start 82.937858 -275.440394)
		(end 82.471006 -275.706332)
		(width 0.10668)
		(layer "F.Cu")
		(net "M_E_CPU1_SB_DQ<3>")
	)
	(segment
		(start 77.299058 -274.235164)
		(end 78.35265 -275.288756)
		(width 0.0889)
		(layer "In6.Cu")
		(net "M_E_CPU1_SB_DQ<3>")
	)
	(segment
		(start 48.870362 -284.450536)
		(end 49.720246 -283.600652)
		(width 0.14478)
		(layer "In6.Cu")
		(net "M_E_CPU1_SB_DQ<3>")
	)
	(segment
		(start 76.822046 -274.235164)
		(end 77.299058 -274.235164)
		(width 0.0889)
		(layer "In6.Cu")
		(net "M_E_CPU1_SB_DQ<3>")
	)
	(segment
		(start 27.116786 -284.450536)
		(end 34.224722 -284.450536)
		(width 0.14478)
		(layer "In6.Cu")
		(net "M_E_CPU1_SB_DQ<3>")
	)
	(segment
		(start 35.074606 -283.600652)
		(end 37.346636 -283.600652)
		(width 0.14478)
		(layer "In6.Cu")
		(net "M_E_CPU1_SB_DQ<3>")
	)
	(segment
		(start 52.553616 -283.600652)
		(end 53.41239 -283.956252)
		(width 0.14478)
		(layer "In6.Cu")
		(net "M_E_CPU1_SB_DQ<3>")
	)
	(segment
		(start 25.152096 -284.035246)
		(end 26.113994 -284.035246)
		(width 0.14478)
		(layer "In6.Cu")
		(net "M_E_CPU1_SB_DQ<3>")
	)
	(segment
		(start 38.60292 -284.121098)
		(end 38.932358 -284.450536)
		(width 0.14478)
		(layer "In6.Cu")
		(net "M_E_CPU1_SB_DQ<3>")
	)
	(segment
		(start 59.952128 -283.305504)
		(end 61.6458 -281.611832)
		(width 0.14478)
		(layer "In6.Cu")
		(net "M_E_CPU1_SB_DQ<3>")
	)
	(segment
		(start 41.793922 -284.450536)
		(end 42.643806 -283.600652)
		(width 0.14478)
		(layer "In6.Cu")
		(net "M_E_CPU1_SB_DQ<3>")
	)
	(segment
		(start 53.41239 -283.956252)
		(end 53.91658 -284.460442)
		(width 0.14478)
		(layer "In6.Cu")
		(net "M_E_CPU1_SB_DQ<3>")
	)
	(segment
		(start 76.472796 -274.584414)
		(end 76.822046 -274.235164)
		(width 0.0889)
		(layer "In6.Cu")
		(net "M_E_CPU1_SB_DQ<3>")
	)
	(segment
		(start 37.346636 -283.600652)
		(end 38.60292 -284.121098)
		(width 0.14478)
		(layer "In6.Cu")
		(net "M_E_CPU1_SB_DQ<3>")
	)
	(segment
		(start 45.005244 -283.600652)
		(end 46.108874 -284.057852)
		(width 0.14478)
		(layer "In6.Cu")
		(net "M_E_CPU1_SB_DQ<3>")
	)
	(segment
		(start 82.602578 -275.35759)
		(end 82.62493 -275.440902)
		(width 0.0889)
		(layer "In6.Cu")
		(net "M_E_CPU1_SB_DQ<3>")
	)
	(segment
		(start 62.699138 -279.706324)
		(end 62.699138 -279.353772)
		(width 0.14478)
		(layer "In6.Cu")
		(net "M_E_CPU1_SB_DQ<3>")
	)
	(segment
		(start 49.720246 -283.600652)
		(end 52.553616 -283.600652)
		(width 0.14478)
		(layer "In6.Cu")
		(net "M_E_CPU1_SB_DQ<3>")
	)
	(segment
		(start 78.35265 -275.288756)
		(end 79.593694 -275.288756)
		(width 0.0889)
		(layer "In6.Cu")
		(net "M_E_CPU1_SB_DQ<3>")
	)
	(segment
		(start 26.113994 -284.035246)
		(end 27.116786 -284.450536)
		(width 0.14478)
		(layer "In6.Cu")
		(net "M_E_CPU1_SB_DQ<3>")
	)
	(segment
		(start 46.501558 -284.450536)
		(end 48.870362 -284.450536)
		(width 0.14478)
		(layer "In6.Cu")
		(net "M_E_CPU1_SB_DQ<3>")
	)
	(segment
		(start 34.224722 -284.450536)
		(end 35.074606 -283.600652)
		(width 0.14478)
		(layer "In6.Cu")
		(net "M_E_CPU1_SB_DQ<3>")
	)
	(segment
		(start 61.6458 -280.759662)
		(end 62.699138 -279.706324)
		(width 0.14478)
		(layer "In6.Cu")
		(net "M_E_CPU1_SB_DQ<3>")
	)
	(segment
		(start 53.91658 -284.460442)
		(end 56.243728 -284.460442)
		(width 0.14478)
		(layer "In6.Cu")
		(net "M_E_CPU1_SB_DQ<3>")
	)
	(segment
		(start 59.216036 -283.610304)
		(end 59.952128 -283.305504)
		(width 0.14478)
		(layer "In6.Cu")
		(net "M_E_CPU1_SB_DQ<3>")
	)
	(segment
		(start 57.762648 -283.610304)
		(end 59.216036 -283.610304)
		(width 0.14478)
		(layer "In6.Cu")
		(net "M_E_CPU1_SB_DQ<3>")
	)
	(segment
		(start 46.108874 -284.057852)
		(end 46.501558 -284.450536)
		(width 0.14478)
		(layer "In6.Cu")
		(net "M_E_CPU1_SB_DQ<3>")
	)
	(segment
		(start 82.62493 -275.440902)
		(end 82.471006 -275.706332)
		(width 0.0889)
		(layer "In6.Cu")
		(net "M_E_CPU1_SB_DQ<3>")
	)
	(segment
		(start 56.243728 -284.460442)
		(end 56.621172 -284.082998)
		(width 0.14478)
		(layer "In6.Cu")
		(net "M_E_CPU1_SB_DQ<3>")
	)
	(segment
		(start 66.726816 -274.584414)
		(end 76.472796 -274.584414)
		(width 0.14478)
		(layer "In6.Cu")
		(net "M_E_CPU1_SB_DQ<3>")
	)
	(segment
		(start 65.96888 -275.34235)
		(end 66.726816 -274.584414)
		(width 0.14478)
		(layer "In6.Cu")
		(net "M_E_CPU1_SB_DQ<3>")
	)
	(segment
		(start 80.769714 -275.378926)
		(end 80.778096 -275.383752)
		(width 0.0889)
		(layer "In6.Cu")
		(net "M_E_CPU1_SB_DQ<3>")
	)
	(segment
		(start 62.699138 -279.353772)
		(end 65.44437 -276.60854)
		(width 0.14478)
		(layer "In6.Cu")
		(net "M_E_CPU1_SB_DQ<3>")
	)
	(segment
		(start 42.643806 -283.600652)
		(end 45.005244 -283.600652)
		(width 0.14478)
		(layer "In6.Cu")
		(net "M_E_CPU1_SB_DQ<3>")
	)
	(segment
		(start 38.932358 -284.450536)
		(end 41.793922 -284.450536)
		(width 0.14478)
		(layer "In6.Cu")
		(net "M_E_CPU1_SB_DQ<3>")
	)
	(segment
		(start 81.344008 -275.383752)
		(end 81.35239 -275.378926)
		(width 0.0889)
		(layer "In6.Cu")
		(net "M_E_CPU1_SB_DQ<3>")
	)
	(segment
		(start 61.6458 -281.611832)
		(end 61.6458 -280.759662)
		(width 0.14478)
		(layer "In6.Cu")
		(net "M_E_CPU1_SB_DQ<3>")
	)
	(segment
		(start 65.44437 -276.60854)
		(end 65.96888 -275.34235)
		(width 0.14478)
		(layer "In6.Cu")
		(net "M_E_CPU1_SB_DQ<3>")
	)
	(segment
		(start 56.621172 -284.082998)
		(end 57.762648 -283.610304)
		(width 0.14478)
		(layer "In6.Cu")
		(net "M_E_CPU1_SB_DQ<3>")
	)
	(arc
		(start 80.403954 -275.383752)
		(mid 80.586205 -275.333402)
		(end 80.769714 -275.378926)
		(width 0.0889)
		(layer "In6.Cu")
		(net "M_E_CPU1_SB_DQ<3>")
	)
	(arc
		(start 81.35239 -275.378926)
		(mid 81.535898 -275.333432)
		(end 81.71815 -275.383752)
		(width 0.0889)
		(layer "In6.Cu")
		(net "M_E_CPU1_SB_DQ<3>")
	)
	(arc
		(start 80.778096 -275.383752)
		(mid 81.061052 -275.459929)
		(end 81.344008 -275.383752)
		(width 0.0889)
		(layer "In6.Cu")
		(net "M_E_CPU1_SB_DQ<3>")
	)
	(arc
		(start 81.71815 -275.383752)
		(mid 82.001106 -275.459929)
		(end 82.284062 -275.383752)
		(width 0.0889)
		(layer "In6.Cu")
		(net "M_E_CPU1_SB_DQ<3>")
	)
	(arc
		(start 79.681324 -275.306028)
		(mid 79.760981 -275.342272)
		(end 79.838042 -275.383752)
		(width 0.0889)
		(layer "In6.Cu")
		(net "M_E_CPU1_SB_DQ<3>")
	)
	(arc
		(start 82.284062 -275.383752)
		(mid 82.440381 -275.334757)
		(end 82.602578 -275.35759)
		(width 0.0889)
		(layer "In6.Cu")
		(net "M_E_CPU1_SB_DQ<3>")
	)
	(arc
		(start 79.593694 -275.288756)
		(mid 79.63836 -275.293071)
		(end 79.681324 -275.306028)
		(width 0.0889)
		(layer "In6.Cu")
		(net "M_E_CPU1_SB_DQ<3>")
	)
	(arc
		(start 79.838042 -275.383752)
		(mid 80.120998 -275.459929)
		(end 80.403954 -275.383752)
		(width 0.0889)
		(layer "In6.Cu")
		(net "M_E_CPU1_SB_DQ<3>")
	)
	(segment
		(start 82.937858 -293.260272)
		(end 82.471006 -293.52621)
		(width 0.10668)
		(layer "F.Cu")
		(net "M_E_CPU1_SB_DQ<31>")
	)
	(segment
		(start 26.471626 -317.643764)
		(end 26.702258 -317.643764)
		(width 0.14478)
		(layer "In6.Cu")
		(net "M_E_CPU1_SB_DQ<31>")
	)
	(segment
		(start 66.67627 -310.601868)
		(end 66.67627 -310.179974)
		(width 0.14478)
		(layer "In6.Cu")
		(net "M_E_CPU1_SB_DQ<31>")
	)
	(segment
		(start 26.865072 -317.806578)
		(end 26.865072 -318.29756)
		(width 0.14478)
		(layer "In6.Cu")
		(net "M_E_CPU1_SB_DQ<31>")
	)
	(segment
		(start 59.18835 -317.586106)
		(end 59.692032 -317.586106)
		(width 0.14478)
		(layer "In6.Cu")
		(net "M_E_CPU1_SB_DQ<31>")
	)
	(segment
		(start 82.281268 -293.205408)
		(end 82.284062 -293.20363)
		(width 0.0889)
		(layer "In6.Cu")
		(net "M_E_CPU1_SB_DQ<31>")
	)
	(segment
		(start 80.719422 -295.929304)
		(end 80.719422 -295.8338)
		(width 0.0889)
		(layer "In6.Cu")
		(net "M_E_CPU1_SB_DQ<31>")
	)
	(segment
		(start 26.702258 -317.643764)
		(end 26.865072 -317.806578)
		(width 0.14478)
		(layer "In6.Cu")
		(net "M_E_CPU1_SB_DQ<31>")
	)
	(segment
		(start 80.745584 -295.770808)
		(end 81.00822 -295.508172)
		(width 0.0889)
		(layer "In6.Cu")
		(net "M_E_CPU1_SB_DQ<31>")
	)
	(segment
		(start 81.344008 -294.823642)
		(end 81.383124 -294.800782)
		(width 0.0889)
		(layer "In6.Cu")
		(net "M_E_CPU1_SB_DQ<31>")
	)
	(segment
		(start 82.62493 -293.26078)
		(end 82.471006 -293.52621)
		(width 0.0889)
		(layer "In6.Cu")
		(net "M_E_CPU1_SB_DQ<31>")
	)
	(segment
		(start 66.67627 -310.179974)
		(end 80.407002 -296.449242)
		(width 0.14478)
		(layer "In6.Cu")
		(net "M_E_CPU1_SB_DQ<31>")
	)
	(segment
		(start 82.602578 -293.177468)
		(end 82.62493 -293.26078)
		(width 0.0889)
		(layer "In6.Cu")
		(net "M_E_CPU1_SB_DQ<31>")
	)
	(segment
		(start 26.865072 -318.29756)
		(end 27.027886 -318.460374)
		(width 0.14478)
		(layer "In6.Cu")
		(net "M_E_CPU1_SB_DQ<31>")
	)
	(segment
		(start 25.152096 -318.035432)
		(end 26.079958 -318.035432)
		(width 0.14478)
		(layer "In6.Cu")
		(net "M_E_CPU1_SB_DQ<31>")
	)
	(segment
		(start 81.813908 -294.013636)
		(end 81.853024 -293.990776)
		(width 0.0889)
		(layer "In6.Cu")
		(net "M_E_CPU1_SB_DQ<31>")
	)
	(segment
		(start 26.079958 -318.035432)
		(end 26.471626 -317.643764)
		(width 0.14478)
		(layer "In6.Cu")
		(net "M_E_CPU1_SB_DQ<31>")
	)
	(segment
		(start 27.027886 -318.460374)
		(end 58.314082 -318.460374)
		(width 0.14478)
		(layer "In6.Cu")
		(net "M_E_CPU1_SB_DQ<31>")
	)
	(segment
		(start 59.692032 -317.586106)
		(end 66.67627 -310.601868)
		(width 0.14478)
		(layer "In6.Cu")
		(net "M_E_CPU1_SB_DQ<31>")
	)
	(segment
		(start 58.314082 -318.460374)
		(end 59.18835 -317.586106)
		(width 0.14478)
		(layer "In6.Cu")
		(net "M_E_CPU1_SB_DQ<31>")
	)
	(segment
		(start 81.783428 -294.031416)
		(end 81.813908 -294.013636)
		(width 0.0889)
		(layer "In6.Cu")
		(net "M_E_CPU1_SB_DQ<31>")
	)
	(segment
		(start 80.407002 -296.449242)
		(end 80.572864 -296.28338)
		(width 0.0889)
		(layer "In6.Cu")
		(net "M_E_CPU1_SB_DQ<31>")
	)
	(arc
		(start 80.719422 -295.8338)
		(mid 80.726208 -295.799682)
		(end 80.745584 -295.770808)
		(width 0.0889)
		(layer "In6.Cu")
		(net "M_E_CPU1_SB_DQ<31>")
	)
	(arc
		(start 80.572864 -296.28338)
		(mid 80.681357 -296.120914)
		(end 80.719422 -295.929304)
		(width 0.0889)
		(layer "In6.Cu")
		(net "M_E_CPU1_SB_DQ<31>")
	)
	(arc
		(start 82.284062 -293.20363)
		(mid 82.440381 -293.154635)
		(end 82.602578 -293.177468)
		(width 0.0889)
		(layer "In6.Cu")
		(net "M_E_CPU1_SB_DQ<31>")
	)
	(arc
		(start 81.162652 -295.1353)
		(mid 81.189856 -294.998537)
		(end 81.2673 -294.88257)
		(width 0.0889)
		(layer "In6.Cu")
		(net "M_E_CPU1_SB_DQ<31>")
	)
	(arc
		(start 81.2673 -294.88257)
		(mid 81.303728 -294.850597)
		(end 81.344008 -294.823642)
		(width 0.0889)
		(layer "In6.Cu")
		(net "M_E_CPU1_SB_DQ<31>")
	)
	(arc
		(start 81.00822 -295.508172)
		(mid 81.122529 -295.337097)
		(end 81.162652 -295.1353)
		(width 0.0889)
		(layer "In6.Cu")
		(net "M_E_CPU1_SB_DQ<31>")
	)
	(arc
		(start 82.096356 -293.52621)
		(mid 82.145885 -293.341057)
		(end 82.281268 -293.205408)
		(width 0.0889)
		(layer "In6.Cu")
		(net "M_E_CPU1_SB_DQ<31>")
	)
	(arc
		(start 81.383124 -294.800782)
		(mid 81.561937 -294.598432)
		(end 81.626456 -294.336216)
		(width 0.0889)
		(layer "In6.Cu")
		(net "M_E_CPU1_SB_DQ<31>")
	)
	(arc
		(start 81.853024 -293.990776)
		(mid 82.031837 -293.788426)
		(end 82.096356 -293.52621)
		(width 0.0889)
		(layer "In6.Cu")
		(net "M_E_CPU1_SB_DQ<31>")
	)
	(arc
		(start 81.626456 -294.336216)
		(mid 81.668005 -294.164794)
		(end 81.783428 -294.031416)
		(width 0.0889)
		(layer "In6.Cu")
		(net "M_E_CPU1_SB_DQ<31>")
	)
	(segment
		(start 81.527904 -292.450266)
		(end 81.061052 -292.716204)
		(width 0.10668)
		(layer "F.Cu")
		(net "M_E_CPU1_SB_DQ<30>")
	)
	(segment
		(start 81.214976 -292.450774)
		(end 81.061052 -292.716204)
		(width 0.0889)
		(layer "In6.Cu")
		(net "M_E_CPU1_SB_DQ<30>")
	)
	(segment
		(start 80.401414 -293.205154)
		(end 80.403954 -293.20363)
		(width 0.0889)
		(layer "In6.Cu")
		(net "M_E_CPU1_SB_DQ<30>")
	)
	(segment
		(start 59.05881 -315.640466)
		(end 60.351416 -315.640466)
		(width 0.14478)
		(layer "In6.Cu")
		(net "M_E_CPU1_SB_DQ<30>")
	)
	(segment
		(start 81.192624 -292.367462)
		(end 81.214976 -292.450774)
		(width 0.0889)
		(layer "In6.Cu")
		(net "M_E_CPU1_SB_DQ<30>")
	)
	(segment
		(start 79.934054 -294.013636)
		(end 79.97317 -293.990776)
		(width 0.0889)
		(layer "In6.Cu")
		(net "M_E_CPU1_SB_DQ<30>")
	)
	(segment
		(start 65.51803 -309.100474)
		(end 78.608936 -296.009568)
		(width 0.14478)
		(layer "In6.Cu")
		(net "M_E_CPU1_SB_DQ<30>")
	)
	(segment
		(start 27.00147 -315.495178)
		(end 27.164284 -315.332364)
		(width 0.14478)
		(layer "In6.Cu")
		(net "M_E_CPU1_SB_DQ<30>")
	)
	(segment
		(start 27.394916 -315.332364)
		(end 27.55773 -315.495178)
		(width 0.14478)
		(layer "In6.Cu")
		(net "M_E_CPU1_SB_DQ<30>")
	)
	(segment
		(start 79.463646 -294.823642)
		(end 79.502762 -294.800782)
		(width 0.0889)
		(layer "In6.Cu")
		(net "M_E_CPU1_SB_DQ<30>")
	)
	(segment
		(start 79.900272 -294.033194)
		(end 79.934054 -294.013636)
		(width 0.0889)
		(layer "In6.Cu")
		(net "M_E_CPU1_SB_DQ<30>")
	)
	(segment
		(start 60.351416 -315.640466)
		(end 65.51803 -310.473852)
		(width 0.14478)
		(layer "In6.Cu")
		(net "M_E_CPU1_SB_DQ<30>")
	)
	(segment
		(start 65.51803 -310.473852)
		(end 65.51803 -309.100474)
		(width 0.14478)
		(layer "In6.Cu")
		(net "M_E_CPU1_SB_DQ<30>")
	)
	(segment
		(start 80.871314 -292.395402)
		(end 80.874108 -292.393624)
		(width 0.0889)
		(layer "In6.Cu")
		(net "M_E_CPU1_SB_DQ<30>")
	)
	(segment
		(start 26.85669 -316.33541)
		(end 27.00147 -316.19063)
		(width 0.14478)
		(layer "In6.Cu")
		(net "M_E_CPU1_SB_DQ<30>")
	)
	(segment
		(start 79.036164 -295.616376)
		(end 79.113126 -295.539668)
		(width 0.0889)
		(layer "In6.Cu")
		(net "M_E_CPU1_SB_DQ<30>")
	)
	(segment
		(start 27.164284 -315.332364)
		(end 27.394916 -315.332364)
		(width 0.14478)
		(layer "In6.Cu")
		(net "M_E_CPU1_SB_DQ<30>")
	)
	(segment
		(start 57.938924 -316.760352)
		(end 59.05881 -315.640466)
		(width 0.14478)
		(layer "In6.Cu")
		(net "M_E_CPU1_SB_DQ<30>")
	)
	(segment
		(start 27.55773 -315.495178)
		(end 27.55773 -316.597538)
		(width 0.14478)
		(layer "In6.Cu")
		(net "M_E_CPU1_SB_DQ<30>")
	)
	(segment
		(start 79.431896 -294.84193)
		(end 79.463646 -294.823642)
		(width 0.0889)
		(layer "In6.Cu")
		(net "M_E_CPU1_SB_DQ<30>")
	)
	(segment
		(start 80.403954 -293.20363)
		(end 80.406494 -293.201852)
		(width 0.0889)
		(layer "In6.Cu")
		(net "M_E_CPU1_SB_DQ<30>")
	)
	(segment
		(start 27.00147 -316.19063)
		(end 27.00147 -315.495178)
		(width 0.14478)
		(layer "In6.Cu")
		(net "M_E_CPU1_SB_DQ<30>")
	)
	(segment
		(start 27.720544 -316.760352)
		(end 57.938924 -316.760352)
		(width 0.14478)
		(layer "In6.Cu")
		(net "M_E_CPU1_SB_DQ<30>")
	)
	(segment
		(start 25.152096 -316.33541)
		(end 26.85669 -316.33541)
		(width 0.14478)
		(layer "In6.Cu")
		(net "M_E_CPU1_SB_DQ<30>")
	)
	(segment
		(start 27.55773 -316.597538)
		(end 27.720544 -316.760352)
		(width 0.14478)
		(layer "In6.Cu")
		(net "M_E_CPU1_SB_DQ<30>")
	)
	(segment
		(start 78.608936 -296.009568)
		(end 78.919832 -295.695116)
		(width 0.0889)
		(layer "In6.Cu")
		(net "M_E_CPU1_SB_DQ<30>")
	)
	(arc
		(start 79.27594 -295.146222)
		(mid 79.317195 -294.975251)
		(end 79.431896 -294.84193)
		(width 0.0889)
		(layer "In6.Cu")
		(net "M_E_CPU1_SB_DQ<30>")
	)
	(arc
		(start 79.746094 -294.336216)
		(mid 79.786852 -294.166218)
		(end 79.900272 -294.033194)
		(width 0.0889)
		(layer "In6.Cu")
		(net "M_E_CPU1_SB_DQ<30>")
	)
	(arc
		(start 78.977998 -295.655746)
		(mid 79.008956 -295.638833)
		(end 79.036164 -295.616376)
		(width 0.0889)
		(layer "In6.Cu")
		(net "M_E_CPU1_SB_DQ<30>")
	)
	(arc
		(start 79.97317 -293.990776)
		(mid 80.151983 -293.788426)
		(end 80.216502 -293.52621)
		(width 0.0889)
		(layer "In6.Cu")
		(net "M_E_CPU1_SB_DQ<30>")
	)
	(arc
		(start 78.919832 -295.695116)
		(mid 78.947035 -295.672652)
		(end 78.977998 -295.655746)
		(width 0.0889)
		(layer "In6.Cu")
		(net "M_E_CPU1_SB_DQ<30>")
	)
	(arc
		(start 80.686402 -292.716204)
		(mid 80.735931 -292.531051)
		(end 80.871314 -292.395402)
		(width 0.0889)
		(layer "In6.Cu")
		(net "M_E_CPU1_SB_DQ<30>")
	)
	(arc
		(start 80.406494 -293.201852)
		(mid 80.611394 -292.996452)
		(end 80.686402 -292.716204)
		(width 0.0889)
		(layer "In6.Cu")
		(net "M_E_CPU1_SB_DQ<30>")
	)
	(arc
		(start 79.113126 -295.539668)
		(mid 79.233659 -295.359138)
		(end 79.27594 -295.146222)
		(width 0.0889)
		(layer "In6.Cu")
		(net "M_E_CPU1_SB_DQ<30>")
	)
	(arc
		(start 80.216502 -293.52621)
		(mid 80.266042 -293.340971)
		(end 80.401414 -293.205154)
		(width 0.0889)
		(layer "In6.Cu")
		(net "M_E_CPU1_SB_DQ<30>")
	)
	(arc
		(start 79.502762 -294.800782)
		(mid 79.681575 -294.598432)
		(end 79.746094 -294.336216)
		(width 0.0889)
		(layer "In6.Cu")
		(net "M_E_CPU1_SB_DQ<30>")
	)
	(arc
		(start 80.874108 -292.393624)
		(mid 81.030427 -292.344629)
		(end 81.192624 -292.367462)
		(width 0.0889)
		(layer "In6.Cu")
		(net "M_E_CPU1_SB_DQ<30>")
	)
	(segment
		(start 81.527904 -274.630388)
		(end 81.061052 -274.896326)
		(width 0.10668)
		(layer "F.Cu")
		(net "M_E_CPU1_SB_DQ<2>")
	)
	(segment
		(start 38.614096 -282.76042)
		(end 42.162984 -282.76042)
		(width 0.14478)
		(layer "In6.Cu")
		(net "M_E_CPU1_SB_DQ<2>")
	)
	(segment
		(start 53.828696 -282.76042)
		(end 56.65724 -282.76042)
		(width 0.14478)
		(layer "In6.Cu")
		(net "M_E_CPU1_SB_DQ<2>")
	)
	(segment
		(start 61.799978 -279.333452)
		(end 61.799978 -278.9809)
		(width 0.14478)
		(layer "In6.Cu")
		(net "M_E_CPU1_SB_DQ<2>")
	)
	(segment
		(start 81.214976 -274.630896)
		(end 81.061052 -274.896326)
		(width 0.0889)
		(layer "In6.Cu")
		(net "M_E_CPU1_SB_DQ<2>")
	)
	(segment
		(start 50.124106 -281.910282)
		(end 52.978558 -281.910282)
		(width 0.14478)
		(layer "In6.Cu")
		(net "M_E_CPU1_SB_DQ<2>")
	)
	(segment
		(start 37.763958 -281.910282)
		(end 38.614096 -282.76042)
		(width 0.14478)
		(layer "In6.Cu")
		(net "M_E_CPU1_SB_DQ<2>")
	)
	(segment
		(start 75.989688 -273.670522)
		(end 77.498194 -273.670522)
		(width 0.0889)
		(layer "In6.Cu")
		(net "M_E_CPU1_SB_DQ<2>")
	)
	(segment
		(start 42.162984 -282.76042)
		(end 43.013122 -281.910282)
		(width 0.14478)
		(layer "In6.Cu")
		(net "M_E_CPU1_SB_DQ<2>")
	)
	(segment
		(start 58.933334 -281.910282)
		(end 59.886596 -281.910282)
		(width 0.14478)
		(layer "In6.Cu")
		(net "M_E_CPU1_SB_DQ<2>")
	)
	(segment
		(start 77.498194 -273.670522)
		(end 78.312518 -274.484846)
		(width 0.0889)
		(layer "In6.Cu")
		(net "M_E_CPU1_SB_DQ<2>")
	)
	(segment
		(start 60.74664 -281.050238)
		(end 60.74664 -280.38679)
		(width 0.14478)
		(layer "In6.Cu")
		(net "M_E_CPU1_SB_DQ<2>")
	)
	(segment
		(start 26.688542 -282.335224)
		(end 27.113738 -282.76042)
		(width 0.14478)
		(layer "In6.Cu")
		(net "M_E_CPU1_SB_DQ<2>")
	)
	(segment
		(start 60.74664 -280.38679)
		(end 61.799978 -279.333452)
		(width 0.14478)
		(layer "In6.Cu")
		(net "M_E_CPU1_SB_DQ<2>")
	)
	(segment
		(start 27.507184 -282.094178)
		(end 27.669998 -281.931364)
		(width 0.14478)
		(layer "In6.Cu")
		(net "M_E_CPU1_SB_DQ<2>")
	)
	(segment
		(start 65.206372 -274.832826)
		(end 66.364104 -273.675094)
		(width 0.14478)
		(layer "In6.Cu")
		(net "M_E_CPU1_SB_DQ<2>")
	)
	(segment
		(start 28.226258 -282.76042)
		(end 34.238184 -282.76042)
		(width 0.14478)
		(layer "In6.Cu")
		(net "M_E_CPU1_SB_DQ<2>")
	)
	(segment
		(start 27.90063 -281.931364)
		(end 28.063444 -282.094178)
		(width 0.14478)
		(layer "In6.Cu")
		(net "M_E_CPU1_SB_DQ<2>")
	)
	(segment
		(start 45.409358 -281.910282)
		(end 46.259496 -282.76042)
		(width 0.14478)
		(layer "In6.Cu")
		(net "M_E_CPU1_SB_DQ<2>")
	)
	(segment
		(start 52.978558 -281.910282)
		(end 53.828696 -282.76042)
		(width 0.14478)
		(layer "In6.Cu")
		(net "M_E_CPU1_SB_DQ<2>")
	)
	(segment
		(start 64.681862 -276.099016)
		(end 65.206372 -274.832826)
		(width 0.14478)
		(layer "In6.Cu")
		(net "M_E_CPU1_SB_DQ<2>")
	)
	(segment
		(start 34.238184 -282.76042)
		(end 35.088322 -281.910282)
		(width 0.14478)
		(layer "In6.Cu")
		(net "M_E_CPU1_SB_DQ<2>")
	)
	(segment
		(start 28.063444 -282.597606)
		(end 28.226258 -282.76042)
		(width 0.14478)
		(layer "In6.Cu")
		(net "M_E_CPU1_SB_DQ<2>")
	)
	(segment
		(start 28.063444 -282.094178)
		(end 28.063444 -282.597606)
		(width 0.14478)
		(layer "In6.Cu")
		(net "M_E_CPU1_SB_DQ<2>")
	)
	(segment
		(start 81.192624 -274.547584)
		(end 81.214976 -274.630896)
		(width 0.0889)
		(layer "In6.Cu")
		(net "M_E_CPU1_SB_DQ<2>")
	)
	(segment
		(start 78.428342 -274.573746)
		(end 78.443074 -274.582382)
		(width 0.0889)
		(layer "In6.Cu")
		(net "M_E_CPU1_SB_DQ<2>")
	)
	(segment
		(start 49.273968 -282.76042)
		(end 50.124106 -281.910282)
		(width 0.14478)
		(layer "In6.Cu")
		(net "M_E_CPU1_SB_DQ<2>")
	)
	(segment
		(start 27.34437 -282.76042)
		(end 27.507184 -282.597606)
		(width 0.14478)
		(layer "In6.Cu")
		(net "M_E_CPU1_SB_DQ<2>")
	)
	(segment
		(start 75.985116 -273.675094)
		(end 75.989688 -273.670522)
		(width 0.0889)
		(layer "In6.Cu")
		(net "M_E_CPU1_SB_DQ<2>")
	)
	(segment
		(start 27.669998 -281.931364)
		(end 27.90063 -281.931364)
		(width 0.14478)
		(layer "In6.Cu")
		(net "M_E_CPU1_SB_DQ<2>")
	)
	(segment
		(start 27.507184 -282.597606)
		(end 27.507184 -282.094178)
		(width 0.14478)
		(layer "In6.Cu")
		(net "M_E_CPU1_SB_DQ<2>")
	)
	(segment
		(start 43.013122 -281.910282)
		(end 45.409358 -281.910282)
		(width 0.14478)
		(layer "In6.Cu")
		(net "M_E_CPU1_SB_DQ<2>")
	)
	(segment
		(start 58.53303 -282.310586)
		(end 58.933334 -281.910282)
		(width 0.14478)
		(layer "In6.Cu")
		(net "M_E_CPU1_SB_DQ<2>")
	)
	(segment
		(start 27.113738 -282.76042)
		(end 27.34437 -282.76042)
		(width 0.14478)
		(layer "In6.Cu")
		(net "M_E_CPU1_SB_DQ<2>")
	)
	(segment
		(start 59.886596 -281.910282)
		(end 60.74664 -281.050238)
		(width 0.14478)
		(layer "In6.Cu")
		(net "M_E_CPU1_SB_DQ<2>")
	)
	(segment
		(start 57.107074 -282.310586)
		(end 58.53303 -282.310586)
		(width 0.14478)
		(layer "In6.Cu")
		(net "M_E_CPU1_SB_DQ<2>")
	)
	(segment
		(start 25.152096 -282.335224)
		(end 26.688542 -282.335224)
		(width 0.14478)
		(layer "In6.Cu")
		(net "M_E_CPU1_SB_DQ<2>")
	)
	(segment
		(start 66.364104 -273.675094)
		(end 75.985116 -273.675094)
		(width 0.14478)
		(layer "In6.Cu")
		(net "M_E_CPU1_SB_DQ<2>")
	)
	(segment
		(start 35.088322 -281.910282)
		(end 37.763958 -281.910282)
		(width 0.14478)
		(layer "In6.Cu")
		(net "M_E_CPU1_SB_DQ<2>")
	)
	(segment
		(start 79.92364 -274.579842)
		(end 79.934054 -274.573746)
		(width 0.0889)
		(layer "In6.Cu")
		(net "M_E_CPU1_SB_DQ<2>")
	)
	(segment
		(start 79.934054 -274.573746)
		(end 79.942436 -274.56892)
		(width 0.0889)
		(layer "In6.Cu")
		(net "M_E_CPU1_SB_DQ<2>")
	)
	(segment
		(start 61.799978 -278.9809)
		(end 64.681862 -276.099016)
		(width 0.14478)
		(layer "In6.Cu")
		(net "M_E_CPU1_SB_DQ<2>")
	)
	(segment
		(start 56.65724 -282.76042)
		(end 57.107074 -282.310586)
		(width 0.14478)
		(layer "In6.Cu")
		(net "M_E_CPU1_SB_DQ<2>")
	)
	(segment
		(start 46.259496 -282.76042)
		(end 49.273968 -282.76042)
		(width 0.14478)
		(layer "In6.Cu")
		(net "M_E_CPU1_SB_DQ<2>")
	)
	(segment
		(start 79.360014 -274.56892)
		(end 79.368396 -274.573746)
		(width 0.0889)
		(layer "In6.Cu")
		(net "M_E_CPU1_SB_DQ<2>")
	)
	(arc
		(start 79.368396 -274.573746)
		(mid 79.645209 -274.649889)
		(end 79.92364 -274.579842)
		(width 0.0889)
		(layer "In6.Cu")
		(net "M_E_CPU1_SB_DQ<2>")
	)
	(arc
		(start 79.942436 -274.56892)
		(mid 80.125944 -274.523426)
		(end 80.308196 -274.573746)
		(width 0.0889)
		(layer "In6.Cu")
		(net "M_E_CPU1_SB_DQ<2>")
	)
	(arc
		(start 80.874108 -274.573746)
		(mid 81.030427 -274.524751)
		(end 81.192624 -274.547584)
		(width 0.0889)
		(layer "In6.Cu")
		(net "M_E_CPU1_SB_DQ<2>")
	)
	(arc
		(start 78.443074 -274.582382)
		(mid 78.719803 -274.650065)
		(end 78.994254 -274.573746)
		(width 0.0889)
		(layer "In6.Cu")
		(net "M_E_CPU1_SB_DQ<2>")
	)
	(arc
		(start 78.312518 -274.484846)
		(mid 78.367543 -274.533056)
		(end 78.428342 -274.573746)
		(width 0.0889)
		(layer "In6.Cu")
		(net "M_E_CPU1_SB_DQ<2>")
	)
	(arc
		(start 80.308196 -274.573746)
		(mid 80.591152 -274.649923)
		(end 80.874108 -274.573746)
		(width 0.0889)
		(layer "In6.Cu")
		(net "M_E_CPU1_SB_DQ<2>")
	)
	(arc
		(start 78.994254 -274.573746)
		(mid 79.176505 -274.523396)
		(end 79.360014 -274.56892)
		(width 0.0889)
		(layer "In6.Cu")
		(net "M_E_CPU1_SB_DQ<2>")
	)
	(segment
		(start 83.408012 -292.450266)
		(end 82.940906 -292.716204)
		(width 0.10668)
		(layer "F.Cu")
		(net "M_E_CPU1_SB_DQ<29>")
	)
	(segment
		(start 57.932066 -317.61049)
		(end 58.62447 -316.918086)
		(width 0.14478)
		(layer "In6.Cu")
		(net "M_E_CPU1_SB_DQ<29>")
	)
	(segment
		(start 38.892226 -317.999364)
		(end 39.2811 -317.61049)
		(width 0.14478)
		(layer "In6.Cu")
		(net "M_E_CPU1_SB_DQ<29>")
	)
	(segment
		(start 66.15557 -309.48249)
		(end 79.127096 -296.510964)
		(width 0.14478)
		(layer "In6.Cu")
		(net "M_E_CPU1_SB_DQ<29>")
	)
	(segment
		(start 59.716924 -316.918086)
		(end 66.15557 -310.47944)
		(width 0.14478)
		(layer "In6.Cu")
		(net "M_E_CPU1_SB_DQ<29>")
	)
	(segment
		(start 31.172404 -317.993014)
		(end 31.403036 -317.993014)
		(width 0.14478)
		(layer "In6.Cu")
		(net "M_E_CPU1_SB_DQ<29>")
	)
	(segment
		(start 80.778096 -293.84879)
		(end 80.78089 -293.847012)
		(width 0.0889)
		(layer "In6.Cu")
		(net "M_E_CPU1_SB_DQ<29>")
	)
	(segment
		(start 79.838296 -295.468802)
		(end 79.870046 -295.450514)
		(width 0.0889)
		(layer "In6.Cu")
		(net "M_E_CPU1_SB_DQ<29>")
	)
	(segment
		(start 80.271874 -294.679878)
		(end 80.308196 -294.658796)
		(width 0.0889)
		(layer "In6.Cu")
		(net "M_E_CPU1_SB_DQ<29>")
	)
	(segment
		(start 31.00959 -317.37808)
		(end 31.00959 -317.8302)
		(width 0.14478)
		(layer "In6.Cu")
		(net "M_E_CPU1_SB_DQ<29>")
	)
	(segment
		(start 66.15557 -310.47944)
		(end 66.15557 -309.48249)
		(width 0.14478)
		(layer "In6.Cu")
		(net "M_E_CPU1_SB_DQ<29>")
	)
	(segment
		(start 35.899852 -317.999364)
		(end 36.288726 -317.61049)
		(width 0.14478)
		(layer "In6.Cu")
		(net "M_E_CPU1_SB_DQ<29>")
	)
	(segment
		(start 38.335966 -317.221616)
		(end 38.49878 -317.38443)
		(width 0.14478)
		(layer "In6.Cu")
		(net "M_E_CPU1_SB_DQ<29>")
	)
	(segment
		(start 80.73898 -293.87165)
		(end 80.778096 -293.84879)
		(width 0.0889)
		(layer "In6.Cu")
		(net "M_E_CPU1_SB_DQ<29>")
	)
	(segment
		(start 58.62447 -316.918086)
		(end 59.716924 -316.918086)
		(width 0.14478)
		(layer "In6.Cu")
		(net "M_E_CPU1_SB_DQ<29>")
	)
	(segment
		(start 31.78556 -317.61049)
		(end 33.611566 -317.61049)
		(width 0.14478)
		(layer "In6.Cu")
		(net "M_E_CPU1_SB_DQ<29>")
	)
	(segment
		(start 35.343592 -317.221616)
		(end 35.506406 -317.38443)
		(width 0.14478)
		(layer "In6.Cu")
		(net "M_E_CPU1_SB_DQ<29>")
	)
	(segment
		(start 30.846776 -317.215266)
		(end 31.00959 -317.37808)
		(width 0.14478)
		(layer "In6.Cu")
		(net "M_E_CPU1_SB_DQ<29>")
	)
	(segment
		(start 35.506406 -317.83655)
		(end 35.66922 -317.999364)
		(width 0.14478)
		(layer "In6.Cu")
		(net "M_E_CPU1_SB_DQ<29>")
	)
	(segment
		(start 31.403036 -317.993014)
		(end 31.78556 -317.61049)
		(width 0.14478)
		(layer "In6.Cu")
		(net "M_E_CPU1_SB_DQ<29>")
	)
	(segment
		(start 82.786982 -292.981634)
		(end 82.940906 -292.716204)
		(width 0.0889)
		(layer "In6.Cu")
		(net "M_E_CPU1_SB_DQ<29>")
	)
	(segment
		(start 34.950146 -317.83655)
		(end 34.950146 -317.38443)
		(width 0.14478)
		(layer "In6.Cu")
		(net "M_E_CPU1_SB_DQ<29>")
	)
	(segment
		(start 31.00959 -317.8302)
		(end 31.172404 -317.993014)
		(width 0.14478)
		(layer "In6.Cu")
		(net "M_E_CPU1_SB_DQ<29>")
	)
	(segment
		(start 82.187796 -293.038784)
		(end 82.18805 -293.038784)
		(width 0.0889)
		(layer "In6.Cu")
		(net "M_E_CPU1_SB_DQ<29>")
	)
	(segment
		(start 34.5567 -317.999364)
		(end 34.787332 -317.999364)
		(width 0.14478)
		(layer "In6.Cu")
		(net "M_E_CPU1_SB_DQ<29>")
	)
	(segment
		(start 29.252164 -317.185294)
		(end 30.059884 -317.993014)
		(width 0.14478)
		(layer "In6.Cu")
		(net "M_E_CPU1_SB_DQ<29>")
	)
	(segment
		(start 34.950146 -317.38443)
		(end 35.11296 -317.221616)
		(width 0.14478)
		(layer "In6.Cu")
		(net "M_E_CPU1_SB_DQ<29>")
	)
	(segment
		(start 81.245964 -293.040054)
		(end 81.247996 -293.038784)
		(width 0.0889)
		(layer "In6.Cu")
		(net "M_E_CPU1_SB_DQ<29>")
	)
	(segment
		(start 34.231072 -317.221616)
		(end 34.393886 -317.38443)
		(width 0.14478)
		(layer "In6.Cu")
		(net "M_E_CPU1_SB_DQ<29>")
	)
	(segment
		(start 38.105334 -317.221616)
		(end 38.335966 -317.221616)
		(width 0.14478)
		(layer "In6.Cu")
		(net "M_E_CPU1_SB_DQ<29>")
	)
	(segment
		(start 39.2811 -317.61049)
		(end 57.932066 -317.61049)
		(width 0.14478)
		(layer "In6.Cu")
		(net "M_E_CPU1_SB_DQ<29>")
	)
	(segment
		(start 79.79918 -295.491662)
		(end 79.838296 -295.468802)
		(width 0.0889)
		(layer "In6.Cu")
		(net "M_E_CPU1_SB_DQ<29>")
	)
	(segment
		(start 38.661594 -317.999364)
		(end 38.892226 -317.999364)
		(width 0.14478)
		(layer "In6.Cu")
		(net "M_E_CPU1_SB_DQ<29>")
	)
	(segment
		(start 82.69097 -293.007034)
		(end 82.786982 -292.981634)
		(width 0.0889)
		(layer "In6.Cu")
		(net "M_E_CPU1_SB_DQ<29>")
	)
	(segment
		(start 34.00044 -317.221616)
		(end 34.231072 -317.221616)
		(width 0.14478)
		(layer "In6.Cu")
		(net "M_E_CPU1_SB_DQ<29>")
	)
	(segment
		(start 30.059884 -317.993014)
		(end 30.290516 -317.993014)
		(width 0.14478)
		(layer "In6.Cu")
		(net "M_E_CPU1_SB_DQ<29>")
	)
	(segment
		(start 37.94252 -317.83655)
		(end 37.94252 -317.38443)
		(width 0.14478)
		(layer "In6.Cu")
		(net "M_E_CPU1_SB_DQ<29>")
	)
	(segment
		(start 80.308196 -294.658796)
		(end 80.338676 -294.641016)
		(width 0.0889)
		(layer "In6.Cu")
		(net "M_E_CPU1_SB_DQ<29>")
	)
	(segment
		(start 79.127604 -296.510964)
		(end 79.466694 -296.171874)
		(width 0.0889)
		(layer "In6.Cu")
		(net "M_E_CPU1_SB_DQ<29>")
	)
	(segment
		(start 30.290516 -317.993014)
		(end 30.45333 -317.8302)
		(width 0.14478)
		(layer "In6.Cu")
		(net "M_E_CPU1_SB_DQ<29>")
	)
	(segment
		(start 37.549074 -317.999364)
		(end 37.779706 -317.999364)
		(width 0.14478)
		(layer "In6.Cu")
		(net "M_E_CPU1_SB_DQ<29>")
	)
	(segment
		(start 33.611566 -317.61049)
		(end 34.00044 -317.221616)
		(width 0.14478)
		(layer "In6.Cu")
		(net "M_E_CPU1_SB_DQ<29>")
	)
	(segment
		(start 38.49878 -317.38443)
		(end 38.49878 -317.83655)
		(width 0.14478)
		(layer "In6.Cu")
		(net "M_E_CPU1_SB_DQ<29>")
	)
	(segment
		(start 34.393886 -317.38443)
		(end 34.393886 -317.83655)
		(width 0.14478)
		(layer "In6.Cu")
		(net "M_E_CPU1_SB_DQ<29>")
	)
	(segment
		(start 35.11296 -317.221616)
		(end 35.343592 -317.221616)
		(width 0.14478)
		(layer "In6.Cu")
		(net "M_E_CPU1_SB_DQ<29>")
	)
	(segment
		(start 37.1602 -317.61049)
		(end 37.549074 -317.999364)
		(width 0.14478)
		(layer "In6.Cu")
		(net "M_E_CPU1_SB_DQ<29>")
	)
	(segment
		(start 35.506406 -317.38443)
		(end 35.506406 -317.83655)
		(width 0.14478)
		(layer "In6.Cu")
		(net "M_E_CPU1_SB_DQ<29>")
	)
	(segment
		(start 37.779706 -317.999364)
		(end 37.94252 -317.83655)
		(width 0.14478)
		(layer "In6.Cu")
		(net "M_E_CPU1_SB_DQ<29>")
	)
	(segment
		(start 37.94252 -317.38443)
		(end 38.105334 -317.221616)
		(width 0.14478)
		(layer "In6.Cu")
		(net "M_E_CPU1_SB_DQ<29>")
	)
	(segment
		(start 35.66922 -317.999364)
		(end 35.899852 -317.999364)
		(width 0.14478)
		(layer "In6.Cu")
		(net "M_E_CPU1_SB_DQ<29>")
	)
	(segment
		(start 30.45333 -317.8302)
		(end 30.45333 -317.37808)
		(width 0.14478)
		(layer "In6.Cu")
		(net "M_E_CPU1_SB_DQ<29>")
	)
	(segment
		(start 36.288726 -317.61049)
		(end 37.1602 -317.61049)
		(width 0.14478)
		(layer "In6.Cu")
		(net "M_E_CPU1_SB_DQ<29>")
	)
	(segment
		(start 34.393886 -317.83655)
		(end 34.5567 -317.999364)
		(width 0.14478)
		(layer "In6.Cu")
		(net "M_E_CPU1_SB_DQ<29>")
	)
	(segment
		(start 34.787332 -317.999364)
		(end 34.950146 -317.83655)
		(width 0.14478)
		(layer "In6.Cu")
		(net "M_E_CPU1_SB_DQ<29>")
	)
	(segment
		(start 30.45333 -317.37808)
		(end 30.616144 -317.215266)
		(width 0.14478)
		(layer "In6.Cu")
		(net "M_E_CPU1_SB_DQ<29>")
	)
	(segment
		(start 38.49878 -317.83655)
		(end 38.661594 -317.999364)
		(width 0.14478)
		(layer "In6.Cu")
		(net "M_E_CPU1_SB_DQ<29>")
	)
	(segment
		(start 30.616144 -317.215266)
		(end 30.846776 -317.215266)
		(width 0.14478)
		(layer "In6.Cu")
		(net "M_E_CPU1_SB_DQ<29>")
	)
	(arc
		(start 79.127096 -296.510964)
		(mid 79.12735 -296.511024)
		(end 79.127604 -296.510964)
		(width 0.0889)
		(layer "In6.Cu")
		(net "M_E_CPU1_SB_DQ<29>")
	)
	(arc
		(start 80.338676 -294.641016)
		(mid 80.454103 -294.50764)
		(end 80.495648 -294.336216)
		(width 0.0889)
		(layer "In6.Cu")
		(net "M_E_CPU1_SB_DQ<29>")
	)
	(arc
		(start 79.555848 -295.956228)
		(mid 79.620363 -295.694009)
		(end 79.79918 -295.491662)
		(width 0.0889)
		(layer "In6.Cu")
		(net "M_E_CPU1_SB_DQ<29>")
	)
	(arc
		(start 80.78089 -293.847012)
		(mid 80.916227 -293.711336)
		(end 80.965802 -293.52621)
		(width 0.0889)
		(layer "In6.Cu")
		(net "M_E_CPU1_SB_DQ<29>")
	)
	(arc
		(start 81.247996 -293.038784)
		(mid 81.530952 -292.962607)
		(end 81.813908 -293.038784)
		(width 0.0889)
		(layer "In6.Cu")
		(net "M_E_CPU1_SB_DQ<29>")
	)
	(arc
		(start 80.495648 -294.336216)
		(mid 80.560163 -294.073997)
		(end 80.73898 -293.87165)
		(width 0.0889)
		(layer "In6.Cu")
		(net "M_E_CPU1_SB_DQ<29>")
	)
	(arc
		(start 79.466694 -296.171874)
		(mid 79.53272 -296.07292)
		(end 79.555848 -295.956228)
		(width 0.0889)
		(layer "In6.Cu")
		(net "M_E_CPU1_SB_DQ<29>")
	)
	(arc
		(start 81.813908 -293.038784)
		(mid 82.000852 -293.089108)
		(end 82.187796 -293.038784)
		(width 0.0889)
		(layer "In6.Cu")
		(net "M_E_CPU1_SB_DQ<29>")
	)
	(arc
		(start 82.18805 -293.038784)
		(mid 82.435763 -292.963564)
		(end 82.69097 -293.007034)
		(width 0.0889)
		(layer "In6.Cu")
		(net "M_E_CPU1_SB_DQ<29>")
	)
	(arc
		(start 80.026002 -295.146222)
		(mid 80.091238 -294.882631)
		(end 80.271874 -294.679878)
		(width 0.0889)
		(layer "In6.Cu")
		(net "M_E_CPU1_SB_DQ<29>")
	)
	(arc
		(start 79.870046 -295.450514)
		(mid 79.984722 -295.31718)
		(end 80.026002 -295.146222)
		(width 0.0889)
		(layer "In6.Cu")
		(net "M_E_CPU1_SB_DQ<29>")
	)
	(arc
		(start 80.965802 -293.52621)
		(mid 81.040858 -293.245662)
		(end 81.245964 -293.040054)
		(width 0.0889)
		(layer "In6.Cu")
		(net "M_E_CPU1_SB_DQ<29>")
	)
	(segment
		(start 81.997804 -291.64026)
		(end 81.530952 -291.906198)
		(width 0.10668)
		(layer "F.Cu")
		(net "M_E_CPU1_SB_DQ<28>")
	)
	(segment
		(start 58.902346 -314.870846)
		(end 59.72556 -314.870846)
		(width 0.14478)
		(layer "In6.Cu")
		(net "M_E_CPU1_SB_DQ<28>")
	)
	(segment
		(start 74.03592 -299.558964)
		(end 73.758044 -299.281088)
		(width 0.14478)
		(layer "In6.Cu")
		(net "M_E_CPU1_SB_DQ<28>")
	)
	(segment
		(start 38.32225 -316.145164)
		(end 38.643814 -316.145164)
		(width 0.14478)
		(layer "In6.Cu")
		(net "M_E_CPU1_SB_DQ<28>")
	)
	(segment
		(start 67.51193 -305.723036)
		(end 67.51193 -305.322478)
		(width 0.14478)
		(layer "In6.Cu")
		(net "M_E_CPU1_SB_DQ<28>")
	)
	(segment
		(start 44.600114 -315.910468)
		(end 44.91101 -316.221364)
		(width 0.14478)
		(layer "In6.Cu")
		(net "M_E_CPU1_SB_DQ<28>")
	)
	(segment
		(start 77.95768 -295.468802)
		(end 77.98943 -295.450514)
		(width 0.0889)
		(layer "In6.Cu")
		(net "M_E_CPU1_SB_DQ<28>")
	)
	(segment
		(start 39.43477 -316.145164)
		(end 39.756334 -316.145164)
		(width 0.14478)
		(layer "In6.Cu")
		(net "M_E_CPU1_SB_DQ<28>")
	)
	(segment
		(start 50.132996 -315.910468)
		(end 50.37836 -315.910468)
		(width 0.14478)
		(layer "In6.Cu")
		(net "M_E_CPU1_SB_DQ<28>")
	)
	(segment
		(start 43.660822 -315.910468)
		(end 44.600114 -315.910468)
		(width 0.14478)
		(layer "In6.Cu")
		(net "M_E_CPU1_SB_DQ<28>")
	)
	(segment
		(start 73.9521 -298.882308)
		(end 74.156824 -298.882308)
		(width 0.14478)
		(layer "In6.Cu")
		(net "M_E_CPU1_SB_DQ<28>")
	)
	(segment
		(start 46.02353 -316.221364)
		(end 46.268894 -316.221364)
		(width 0.14478)
		(layer "In6.Cu")
		(net "M_E_CPU1_SB_DQ<28>")
	)
	(segment
		(start 29.252164 -315.485272)
		(end 30.071822 -316.30493)
		(width 0.14478)
		(layer "In6.Cu")
		(net "M_E_CPU1_SB_DQ<28>")
	)
	(segment
		(start 56.193944 -316.221364)
		(end 56.50484 -315.910468)
		(width 0.14478)
		(layer "In6.Cu")
		(net "M_E_CPU1_SB_DQ<28>")
	)
	(segment
		(start 52.61102 -316.221364)
		(end 52.856384 -316.221364)
		(width 0.14478)
		(layer "In6.Cu")
		(net "M_E_CPU1_SB_DQ<28>")
	)
	(segment
		(start 30.302454 -316.30493)
		(end 30.465268 -316.142116)
		(width 0.14478)
		(layer "In6.Cu")
		(net "M_E_CPU1_SB_DQ<28>")
	)
	(segment
		(start 53.16728 -315.910468)
		(end 53.412644 -315.910468)
		(width 0.14478)
		(layer "In6.Cu")
		(net "M_E_CPU1_SB_DQ<28>")
	)
	(segment
		(start 74.555604 -298.278804)
		(end 74.943462 -297.890946)
		(width 0.14478)
		(layer "In6.Cu")
		(net "M_E_CPU1_SB_DQ<28>")
	)
	(segment
		(start 44.91101 -316.221364)
		(end 45.156374 -316.221364)
		(width 0.14478)
		(layer "In6.Cu")
		(net "M_E_CPU1_SB_DQ<28>")
	)
	(segment
		(start 81.377028 -292.171628)
		(end 81.530952 -291.906198)
		(width 0.0889)
		(layer "In6.Cu")
		(net "M_E_CPU1_SB_DQ<28>")
	)
	(segment
		(start 50.37836 -315.910468)
		(end 50.689256 -316.221364)
		(width 0.14478)
		(layer "In6.Cu")
		(net "M_E_CPU1_SB_DQ<28>")
	)
	(segment
		(start 41.681146 -315.910468)
		(end 41.992042 -316.221364)
		(width 0.14478)
		(layer "In6.Cu")
		(net "M_E_CPU1_SB_DQ<28>")
	)
	(segment
		(start 53.968904 -316.221364)
		(end 54.2798 -315.910468)
		(width 0.14478)
		(layer "In6.Cu")
		(net "M_E_CPU1_SB_DQ<28>")
	)
	(segment
		(start 73.359264 -299.679868)
		(end 73.63714 -299.957744)
		(width 0.14478)
		(layer "In6.Cu")
		(net "M_E_CPU1_SB_DQ<28>")
	)
	(segment
		(start 41.435782 -315.910468)
		(end 41.681146 -315.910468)
		(width 0.14478)
		(layer "In6.Cu")
		(net "M_E_CPU1_SB_DQ<28>")
	)
	(segment
		(start 46.268894 -316.221364)
		(end 46.570138 -315.92012)
		(width 0.14478)
		(layer "In6.Cu")
		(net "M_E_CPU1_SB_DQ<28>")
	)
	(segment
		(start 46.570138 -315.92012)
		(end 48.162972 -315.92012)
		(width 0.14478)
		(layer "In6.Cu")
		(net "M_E_CPU1_SB_DQ<28>")
	)
	(segment
		(start 55.081424 -316.221364)
		(end 55.39232 -315.910468)
		(width 0.14478)
		(layer "In6.Cu")
		(net "M_E_CPU1_SB_DQ<28>")
	)
	(segment
		(start 74.83348 -298.966128)
		(end 74.83348 -298.761404)
		(width 0.14478)
		(layer "In6.Cu")
		(net "M_E_CPU1_SB_DQ<28>")
	)
	(segment
		(start 79.838042 -292.228778)
		(end 79.838296 -292.228778)
		(width 0.0889)
		(layer "In6.Cu")
		(net "M_E_CPU1_SB_DQ<28>")
	)
	(segment
		(start 45.712634 -315.910468)
		(end 46.02353 -316.221364)
		(width 0.14478)
		(layer "In6.Cu")
		(net "M_E_CPU1_SB_DQ<28>")
	)
	(segment
		(start 57.0611 -316.221364)
		(end 57.306464 -316.221364)
		(width 0.14478)
		(layer "In6.Cu")
		(net "M_E_CPU1_SB_DQ<28>")
	)
	(segment
		(start 55.94858 -316.221364)
		(end 56.193944 -316.221364)
		(width 0.14478)
		(layer "In6.Cu")
		(net "M_E_CPU1_SB_DQ<28>")
	)
	(segment
		(start 73.758044 -299.281088)
		(end 73.758044 -299.076364)
		(width 0.14478)
		(layer "In6.Cu")
		(net "M_E_CPU1_SB_DQ<28>")
	)
	(segment
		(start 78.428088 -294.658796)
		(end 78.459838 -294.640508)
		(width 0.0889)
		(layer "In6.Cu")
		(net "M_E_CPU1_SB_DQ<28>")
	)
	(segment
		(start 43.349926 -316.221364)
		(end 43.660822 -315.910468)
		(width 0.14478)
		(layer "In6.Cu")
		(net "M_E_CPU1_SB_DQ<28>")
	)
	(segment
		(start 79.365602 -293.040562)
		(end 79.368142 -293.038784)
		(width 0.0889)
		(layer "In6.Cu")
		(net "M_E_CPU1_SB_DQ<28>")
	)
	(segment
		(start 45.156374 -316.221364)
		(end 45.46727 -315.910468)
		(width 0.14478)
		(layer "In6.Cu")
		(net "M_E_CPU1_SB_DQ<28>")
	)
	(segment
		(start 78.897988 -293.84879)
		(end 78.929738 -293.830502)
		(width 0.0889)
		(layer "In6.Cu")
		(net "M_E_CPU1_SB_DQ<28>")
	)
	(segment
		(start 38.097206 -315.92012)
		(end 38.32225 -316.145164)
		(width 0.14478)
		(layer "In6.Cu")
		(net "M_E_CPU1_SB_DQ<28>")
	)
	(segment
		(start 56.50484 -315.910468)
		(end 56.750204 -315.910468)
		(width 0.14478)
		(layer "In6.Cu")
		(net "M_E_CPU1_SB_DQ<28>")
	)
	(segment
		(start 38.87851 -315.910468)
		(end 39.200074 -315.910468)
		(width 0.14478)
		(layer "In6.Cu")
		(net "M_E_CPU1_SB_DQ<28>")
	)
	(segment
		(start 55.39232 -315.910468)
		(end 55.637684 -315.910468)
		(width 0.14478)
		(layer "In6.Cu")
		(net "M_E_CPU1_SB_DQ<28>")
	)
	(segment
		(start 49.8221 -316.221364)
		(end 50.132996 -315.910468)
		(width 0.14478)
		(layer "In6.Cu")
		(net "M_E_CPU1_SB_DQ<28>")
	)
	(segment
		(start 54.525164 -315.910468)
		(end 54.83606 -316.221364)
		(width 0.14478)
		(layer "In6.Cu")
		(net "M_E_CPU1_SB_DQ<28>")
	)
	(segment
		(start 40.879522 -316.221364)
		(end 41.124886 -316.221364)
		(width 0.14478)
		(layer "In6.Cu")
		(net "M_E_CPU1_SB_DQ<28>")
	)
	(segment
		(start 45.46727 -315.910468)
		(end 45.712634 -315.910468)
		(width 0.14478)
		(layer "In6.Cu")
		(net "M_E_CPU1_SB_DQ<28>")
	)
	(segment
		(start 50.93462 -316.221364)
		(end 51.245516 -315.910468)
		(width 0.14478)
		(layer "In6.Cu")
		(net "M_E_CPU1_SB_DQ<28>")
	)
	(segment
		(start 42.548302 -315.910468)
		(end 42.793666 -315.910468)
		(width 0.14478)
		(layer "In6.Cu")
		(net "M_E_CPU1_SB_DQ<28>")
	)
	(segment
		(start 39.756334 -316.145164)
		(end 39.981378 -315.92012)
		(width 0.14478)
		(layer "In6.Cu")
		(net "M_E_CPU1_SB_DQ<28>")
	)
	(segment
		(start 75.419204 -297.890946)
		(end 77.510386 -295.799764)
		(width 0.14478)
		(layer "In6.Cu")
		(net "M_E_CPU1_SB_DQ<28>")
	)
	(segment
		(start 67.51193 -305.322478)
		(end 73.15454 -299.679868)
		(width 0.14478)
		(layer "In6.Cu")
		(net "M_E_CPU1_SB_DQ<28>")
	)
	(segment
		(start 30.465268 -315.693552)
		(end 30.628082 -315.530738)
		(width 0.14478)
		(layer "In6.Cu")
		(net "M_E_CPU1_SB_DQ<28>")
	)
	(segment
		(start 57.306464 -316.221364)
		(end 57.61736 -315.910468)
		(width 0.14478)
		(layer "In6.Cu")
		(net "M_E_CPU1_SB_DQ<28>")
	)
	(segment
		(start 74.156824 -298.882308)
		(end 74.4347 -299.160184)
		(width 0.14478)
		(layer "In6.Cu")
		(net "M_E_CPU1_SB_DQ<28>")
	)
	(segment
		(start 43.104562 -316.221364)
		(end 43.349926 -316.221364)
		(width 0.14478)
		(layer "In6.Cu")
		(net "M_E_CPU1_SB_DQ<28>")
	)
	(segment
		(start 64.91605 -308.318916)
		(end 67.51193 -305.723036)
		(width 0.14478)
		(layer "In6.Cu")
		(net "M_E_CPU1_SB_DQ<28>")
	)
	(segment
		(start 80.777842 -292.228778)
		(end 80.778096 -292.228778)
		(width 0.0889)
		(layer "In6.Cu")
		(net "M_E_CPU1_SB_DQ<28>")
	)
	(segment
		(start 78.387702 -294.682418)
		(end 78.428088 -294.658796)
		(width 0.0889)
		(layer "In6.Cu")
		(net "M_E_CPU1_SB_DQ<28>")
	)
	(segment
		(start 74.03592 -299.763688)
		(end 74.03592 -299.558964)
		(width 0.14478)
		(layer "In6.Cu")
		(net "M_E_CPU1_SB_DQ<28>")
	)
	(segment
		(start 74.943462 -297.890946)
		(end 75.419204 -297.890946)
		(width 0.14478)
		(layer "In6.Cu")
		(net "M_E_CPU1_SB_DQ<28>")
	)
	(segment
		(start 81.281016 -292.197028)
		(end 81.377028 -292.171628)
		(width 0.0889)
		(layer "In6.Cu")
		(net "M_E_CPU1_SB_DQ<28>")
	)
	(segment
		(start 53.412644 -315.910468)
		(end 53.72354 -316.221364)
		(width 0.14478)
		(layer "In6.Cu")
		(net "M_E_CPU1_SB_DQ<28>")
	)
	(segment
		(start 52.856384 -316.221364)
		(end 53.16728 -315.910468)
		(width 0.14478)
		(layer "In6.Cu")
		(net "M_E_CPU1_SB_DQ<28>")
	)
	(segment
		(start 41.992042 -316.221364)
		(end 42.237406 -316.221364)
		(width 0.14478)
		(layer "In6.Cu")
		(net "M_E_CPU1_SB_DQ<28>")
	)
	(segment
		(start 42.237406 -316.221364)
		(end 42.548302 -315.910468)
		(width 0.14478)
		(layer "In6.Cu")
		(net "M_E_CPU1_SB_DQ<28>")
	)
	(segment
		(start 42.793666 -315.910468)
		(end 43.104562 -316.221364)
		(width 0.14478)
		(layer "In6.Cu")
		(net "M_E_CPU1_SB_DQ<28>")
	)
	(segment
		(start 39.200074 -315.910468)
		(end 39.43477 -316.145164)
		(width 0.14478)
		(layer "In6.Cu")
		(net "M_E_CPU1_SB_DQ<28>")
	)
	(segment
		(start 56.750204 -315.910468)
		(end 57.0611 -316.221364)
		(width 0.14478)
		(layer "In6.Cu")
		(net "M_E_CPU1_SB_DQ<28>")
	)
	(segment
		(start 40.578278 -315.92012)
		(end 40.879522 -316.221364)
		(width 0.14478)
		(layer "In6.Cu")
		(net "M_E_CPU1_SB_DQ<28>")
	)
	(segment
		(start 39.981378 -315.92012)
		(end 40.578278 -315.92012)
		(width 0.14478)
		(layer "In6.Cu")
		(net "M_E_CPU1_SB_DQ<28>")
	)
	(segment
		(start 51.245516 -315.910468)
		(end 52.300124 -315.910468)
		(width 0.14478)
		(layer "In6.Cu")
		(net "M_E_CPU1_SB_DQ<28>")
	)
	(segment
		(start 73.841864 -299.957744)
		(end 74.03592 -299.763688)
		(width 0.14478)
		(layer "In6.Cu")
		(net "M_E_CPU1_SB_DQ<28>")
	)
	(segment
		(start 30.628082 -315.530738)
		(end 30.858714 -315.530738)
		(width 0.14478)
		(layer "In6.Cu")
		(net "M_E_CPU1_SB_DQ<28>")
	)
	(segment
		(start 74.639424 -299.160184)
		(end 74.83348 -298.966128)
		(width 0.14478)
		(layer "In6.Cu")
		(net "M_E_CPU1_SB_DQ<28>")
	)
	(segment
		(start 73.63714 -299.957744)
		(end 73.841864 -299.957744)
		(width 0.14478)
		(layer "In6.Cu")
		(net "M_E_CPU1_SB_DQ<28>")
	)
	(segment
		(start 31.248096 -315.92012)
		(end 38.097206 -315.92012)
		(width 0.14478)
		(layer "In6.Cu")
		(net "M_E_CPU1_SB_DQ<28>")
	)
	(segment
		(start 57.862724 -315.910468)
		(end 58.902346 -314.870846)
		(width 0.14478)
		(layer "In6.Cu")
		(net "M_E_CPU1_SB_DQ<28>")
	)
	(segment
		(start 59.72556 -314.870846)
		(end 64.91605 -309.680356)
		(width 0.14478)
		(layer "In6.Cu")
		(net "M_E_CPU1_SB_DQ<28>")
	)
	(segment
		(start 79.835502 -292.230302)
		(end 79.838042 -292.228778)
		(width 0.0889)
		(layer "In6.Cu")
		(net "M_E_CPU1_SB_DQ<28>")
	)
	(segment
		(start 57.61736 -315.910468)
		(end 57.862724 -315.910468)
		(width 0.14478)
		(layer "In6.Cu")
		(net "M_E_CPU1_SB_DQ<28>")
	)
	(segment
		(start 49.26584 -315.910468)
		(end 49.576736 -316.221364)
		(width 0.14478)
		(layer "In6.Cu")
		(net "M_E_CPU1_SB_DQ<28>")
	)
	(segment
		(start 73.15454 -299.679868)
		(end 73.359264 -299.679868)
		(width 0.14478)
		(layer "In6.Cu")
		(net "M_E_CPU1_SB_DQ<28>")
	)
	(segment
		(start 78.895956 -293.85006)
		(end 78.897988 -293.84879)
		(width 0.0889)
		(layer "In6.Cu")
		(net "M_E_CPU1_SB_DQ<28>")
	)
	(segment
		(start 77.510386 -295.799764)
		(end 77.95768 -295.468802)
		(width 0.0889)
		(layer "In6.Cu")
		(net "M_E_CPU1_SB_DQ<28>")
	)
	(segment
		(start 30.465268 -316.142116)
		(end 30.465268 -315.693552)
		(width 0.14478)
		(layer "In6.Cu")
		(net "M_E_CPU1_SB_DQ<28>")
	)
	(segment
		(start 50.689256 -316.221364)
		(end 50.93462 -316.221364)
		(width 0.14478)
		(layer "In6.Cu")
		(net "M_E_CPU1_SB_DQ<28>")
	)
	(segment
		(start 49.576736 -316.221364)
		(end 49.8221 -316.221364)
		(width 0.14478)
		(layer "In6.Cu")
		(net "M_E_CPU1_SB_DQ<28>")
	)
	(segment
		(start 74.4347 -299.160184)
		(end 74.639424 -299.160184)
		(width 0.14478)
		(layer "In6.Cu")
		(net "M_E_CPU1_SB_DQ<28>")
	)
	(segment
		(start 74.83348 -298.761404)
		(end 74.555604 -298.483528)
		(width 0.14478)
		(layer "In6.Cu")
		(net "M_E_CPU1_SB_DQ<28>")
	)
	(segment
		(start 38.643814 -316.145164)
		(end 38.87851 -315.910468)
		(width 0.14478)
		(layer "In6.Cu")
		(net "M_E_CPU1_SB_DQ<28>")
	)
	(segment
		(start 55.637684 -315.910468)
		(end 55.94858 -316.221364)
		(width 0.14478)
		(layer "In6.Cu")
		(net "M_E_CPU1_SB_DQ<28>")
	)
	(segment
		(start 48.464216 -316.221364)
		(end 48.70958 -316.221364)
		(width 0.14478)
		(layer "In6.Cu")
		(net "M_E_CPU1_SB_DQ<28>")
	)
	(segment
		(start 73.758044 -299.076364)
		(end 73.9521 -298.882308)
		(width 0.14478)
		(layer "In6.Cu")
		(net "M_E_CPU1_SB_DQ<28>")
	)
	(segment
		(start 79.368142 -293.038784)
		(end 79.398622 -293.021004)
		(width 0.0889)
		(layer "In6.Cu")
		(net "M_E_CPU1_SB_DQ<28>")
	)
	(segment
		(start 30.858714 -315.530738)
		(end 31.248096 -315.92012)
		(width 0.14478)
		(layer "In6.Cu")
		(net "M_E_CPU1_SB_DQ<28>")
	)
	(segment
		(start 52.300124 -315.910468)
		(end 52.61102 -316.221364)
		(width 0.14478)
		(layer "In6.Cu")
		(net "M_E_CPU1_SB_DQ<28>")
	)
	(segment
		(start 48.162972 -315.92012)
		(end 48.464216 -316.221364)
		(width 0.14478)
		(layer "In6.Cu")
		(net "M_E_CPU1_SB_DQ<28>")
	)
	(segment
		(start 41.124886 -316.221364)
		(end 41.435782 -315.910468)
		(width 0.14478)
		(layer "In6.Cu")
		(net "M_E_CPU1_SB_DQ<28>")
	)
	(segment
		(start 30.071822 -316.30493)
		(end 30.302454 -316.30493)
		(width 0.14478)
		(layer "In6.Cu")
		(net "M_E_CPU1_SB_DQ<28>")
	)
	(segment
		(start 64.91605 -309.680356)
		(end 64.91605 -308.318916)
		(width 0.14478)
		(layer "In6.Cu")
		(net "M_E_CPU1_SB_DQ<28>")
	)
	(segment
		(start 54.2798 -315.910468)
		(end 54.525164 -315.910468)
		(width 0.14478)
		(layer "In6.Cu")
		(net "M_E_CPU1_SB_DQ<28>")
	)
	(segment
		(start 54.83606 -316.221364)
		(end 55.081424 -316.221364)
		(width 0.14478)
		(layer "In6.Cu")
		(net "M_E_CPU1_SB_DQ<28>")
	)
	(segment
		(start 53.72354 -316.221364)
		(end 53.968904 -316.221364)
		(width 0.14478)
		(layer "In6.Cu")
		(net "M_E_CPU1_SB_DQ<28>")
	)
	(segment
		(start 49.020476 -315.910468)
		(end 49.26584 -315.910468)
		(width 0.14478)
		(layer "In6.Cu")
		(net "M_E_CPU1_SB_DQ<28>")
	)
	(segment
		(start 48.70958 -316.221364)
		(end 49.020476 -315.910468)
		(width 0.14478)
		(layer "In6.Cu")
		(net "M_E_CPU1_SB_DQ<28>")
	)
	(segment
		(start 74.555604 -298.483528)
		(end 74.555604 -298.278804)
		(width 0.14478)
		(layer "In6.Cu")
		(net "M_E_CPU1_SB_DQ<28>")
	)
	(arc
		(start 79.555594 -292.716204)
		(mid 79.630584 -292.435838)
		(end 79.835502 -292.230302)
		(width 0.0889)
		(layer "In6.Cu")
		(net "M_E_CPU1_SB_DQ<28>")
	)
	(arc
		(start 78.145386 -295.146222)
		(mid 78.209679 -294.884617)
		(end 78.387702 -294.682418)
		(width 0.0889)
		(layer "In6.Cu")
		(net "M_E_CPU1_SB_DQ<28>")
	)
	(arc
		(start 79.398622 -293.021004)
		(mid 79.514049 -292.887628)
		(end 79.555594 -292.716204)
		(width 0.0889)
		(layer "In6.Cu")
		(net "M_E_CPU1_SB_DQ<28>")
	)
	(arc
		(start 78.615794 -294.336216)
		(mid 78.69085 -294.055668)
		(end 78.895956 -293.85006)
		(width 0.0889)
		(layer "In6.Cu")
		(net "M_E_CPU1_SB_DQ<28>")
	)
	(arc
		(start 80.403954 -292.228778)
		(mid 80.590898 -292.279102)
		(end 80.777842 -292.228778)
		(width 0.0889)
		(layer "In6.Cu")
		(net "M_E_CPU1_SB_DQ<28>")
	)
	(arc
		(start 78.459838 -294.640508)
		(mid 78.574514 -294.507174)
		(end 78.615794 -294.336216)
		(width 0.0889)
		(layer "In6.Cu")
		(net "M_E_CPU1_SB_DQ<28>")
	)
	(arc
		(start 80.778096 -292.228778)
		(mid 81.025809 -292.153558)
		(end 81.281016 -292.197028)
		(width 0.0889)
		(layer "In6.Cu")
		(net "M_E_CPU1_SB_DQ<28>")
	)
	(arc
		(start 77.98943 -295.450514)
		(mid 78.104106 -295.31718)
		(end 78.145386 -295.146222)
		(width 0.0889)
		(layer "In6.Cu")
		(net "M_E_CPU1_SB_DQ<28>")
	)
	(arc
		(start 79.838296 -292.228778)
		(mid 80.121142 -292.152601)
		(end 80.403954 -292.228778)
		(width 0.0889)
		(layer "In6.Cu")
		(net "M_E_CPU1_SB_DQ<28>")
	)
	(arc
		(start 79.085694 -293.52621)
		(mid 79.160748 -293.245988)
		(end 79.365602 -293.040562)
		(width 0.0889)
		(layer "In6.Cu")
		(net "M_E_CPU1_SB_DQ<28>")
	)
	(arc
		(start 78.929738 -293.830502)
		(mid 79.044414 -293.697168)
		(end 79.085694 -293.52621)
		(width 0.0889)
		(layer "In6.Cu")
		(net "M_E_CPU1_SB_DQ<28>")
	)
	(segment
		(start 82.937858 -290.020248)
		(end 82.471006 -290.286186)
		(width 0.10668)
		(layer "F.Cu")
		(net "M_E_CPU1_SB_DQ<27>")
	)
	(segment
		(start 59.925966 -311.271666)
		(end 62.44717 -308.750462)
		(width 0.14478)
		(layer "In6.Cu")
		(net "M_E_CPU1_SB_DQ<27>")
	)
	(segment
		(start 72.272144 -297.235118)
		(end 76.184506 -293.322756)
		(width 0.14478)
		(layer "In6.Cu")
		(net "M_E_CPU1_SB_DQ<27>")
	)
	(segment
		(start 76.748386 -292.758876)
		(end 76.748386 -292.124892)
		(width 0.0889)
		(layer "In6.Cu")
		(net "M_E_CPU1_SB_DQ<27>")
	)
	(segment
		(start 77.942186 -290.53663)
		(end 78.461108 -290.017708)
		(width 0.0889)
		(layer "In6.Cu")
		(net "M_E_CPU1_SB_DQ<27>")
	)
	(segment
		(start 50.449734 -311.650634)
		(end 53.65877 -311.650634)
		(width 0.14478)
		(layer "In6.Cu")
		(net "M_E_CPU1_SB_DQ<27>")
	)
	(segment
		(start 38.386766 -311.99709)
		(end 39.60241 -312.500518)
		(width 0.14478)
		(layer "In6.Cu")
		(net "M_E_CPU1_SB_DQ<27>")
	)
	(segment
		(start 82.62493 -290.020756)
		(end 82.471006 -290.286186)
		(width 0.0889)
		(layer "In6.Cu")
		(net "M_E_CPU1_SB_DQ<27>")
	)
	(segment
		(start 78.89748 -289.96386)
		(end 78.909418 -289.970718)
		(width 0.0889)
		(layer "In6.Cu")
		(net "M_E_CPU1_SB_DQ<27>")
	)
	(segment
		(start 79.46263 -289.963606)
		(end 79.471012 -289.95878)
		(width 0.0889)
		(layer "In6.Cu")
		(net "M_E_CPU1_SB_DQ<27>")
	)
	(segment
		(start 64.953388 -304.982372)
		(end 65.958974 -302.550068)
		(width 0.14478)
		(layer "In6.Cu")
		(net "M_E_CPU1_SB_DQ<27>")
	)
	(segment
		(start 25.152096 -312.085228)
		(end 25.567386 -312.500518)
		(width 0.14478)
		(layer "In6.Cu")
		(net "M_E_CPU1_SB_DQ<27>")
	)
	(segment
		(start 82.602578 -289.937444)
		(end 82.62493 -290.020756)
		(width 0.0889)
		(layer "In6.Cu")
		(net "M_E_CPU1_SB_DQ<27>")
	)
	(segment
		(start 45.99178 -312.032904)
		(end 47.12081 -312.500518)
		(width 0.14478)
		(layer "In6.Cu")
		(net "M_E_CPU1_SB_DQ<27>")
	)
	(segment
		(start 45.60951 -311.650634)
		(end 45.99178 -312.032904)
		(width 0.14478)
		(layer "In6.Cu")
		(net "M_E_CPU1_SB_DQ<27>")
	)
	(segment
		(start 54.1401 -312.131964)
		(end 56.918352 -312.131964)
		(width 0.14478)
		(layer "In6.Cu")
		(net "M_E_CPU1_SB_DQ<27>")
	)
	(segment
		(start 35.11423 -311.650634)
		(end 38.04031 -311.650634)
		(width 0.14478)
		(layer "In6.Cu")
		(net "M_E_CPU1_SB_DQ<27>")
	)
	(segment
		(start 81.344008 -289.963606)
		(end 81.35239 -289.95878)
		(width 0.0889)
		(layer "In6.Cu")
		(net "M_E_CPU1_SB_DQ<27>")
	)
	(segment
		(start 42.71137 -311.650634)
		(end 45.60951 -311.650634)
		(width 0.14478)
		(layer "In6.Cu")
		(net "M_E_CPU1_SB_DQ<27>")
	)
	(segment
		(start 53.65877 -311.650634)
		(end 54.1401 -312.131964)
		(width 0.14478)
		(layer "In6.Cu")
		(net "M_E_CPU1_SB_DQ<27>")
	)
	(segment
		(start 47.12081 -312.500518)
		(end 48.397922 -312.500518)
		(width 0.14478)
		(layer "In6.Cu")
		(net "M_E_CPU1_SB_DQ<27>")
	)
	(segment
		(start 77.942186 -290.931092)
		(end 77.942186 -290.53663)
		(width 0.0889)
		(layer "In6.Cu")
		(net "M_E_CPU1_SB_DQ<27>")
	)
	(segment
		(start 41.204388 -312.500518)
		(end 42.326052 -312.035952)
		(width 0.14478)
		(layer "In6.Cu")
		(net "M_E_CPU1_SB_DQ<27>")
	)
	(segment
		(start 62.44717 -308.750462)
		(end 62.44717 -307.48859)
		(width 0.14478)
		(layer "In6.Cu")
		(net "M_E_CPU1_SB_DQ<27>")
	)
	(segment
		(start 80.38592 -289.974274)
		(end 80.403954 -289.963606)
		(width 0.0889)
		(layer "In6.Cu")
		(net "M_E_CPU1_SB_DQ<27>")
	)
	(segment
		(start 56.918352 -312.131964)
		(end 57.77865 -311.271666)
		(width 0.14478)
		(layer "In6.Cu")
		(net "M_E_CPU1_SB_DQ<27>")
	)
	(segment
		(start 62.44717 -307.48859)
		(end 64.953388 -304.982372)
		(width 0.14478)
		(layer "In6.Cu")
		(net "M_E_CPU1_SB_DQ<27>")
	)
	(segment
		(start 33.802828 -312.500518)
		(end 34.590482 -312.174382)
		(width 0.14478)
		(layer "In6.Cu")
		(net "M_E_CPU1_SB_DQ<27>")
	)
	(segment
		(start 71.273924 -297.235118)
		(end 72.272144 -297.235118)
		(width 0.14478)
		(layer "In6.Cu")
		(net "M_E_CPU1_SB_DQ<27>")
	)
	(segment
		(start 80.769714 -289.95878)
		(end 80.778096 -289.963606)
		(width 0.0889)
		(layer "In6.Cu")
		(net "M_E_CPU1_SB_DQ<27>")
	)
	(segment
		(start 76.748386 -292.124892)
		(end 77.942186 -290.931092)
		(width 0.0889)
		(layer "In6.Cu")
		(net "M_E_CPU1_SB_DQ<27>")
	)
	(segment
		(start 25.567386 -312.500518)
		(end 33.802828 -312.500518)
		(width 0.14478)
		(layer "In6.Cu")
		(net "M_E_CPU1_SB_DQ<27>")
	)
	(segment
		(start 38.04031 -311.650634)
		(end 38.386766 -311.99709)
		(width 0.14478)
		(layer "In6.Cu")
		(net "M_E_CPU1_SB_DQ<27>")
	)
	(segment
		(start 65.958974 -302.550068)
		(end 71.273924 -297.235118)
		(width 0.14478)
		(layer "In6.Cu")
		(net "M_E_CPU1_SB_DQ<27>")
	)
	(segment
		(start 76.184506 -293.322756)
		(end 76.748386 -292.758876)
		(width 0.0889)
		(layer "In6.Cu")
		(net "M_E_CPU1_SB_DQ<27>")
	)
	(segment
		(start 39.60241 -312.500518)
		(end 41.204388 -312.500518)
		(width 0.14478)
		(layer "In6.Cu")
		(net "M_E_CPU1_SB_DQ<27>")
	)
	(segment
		(start 42.326052 -312.035952)
		(end 42.71137 -311.650634)
		(width 0.14478)
		(layer "In6.Cu")
		(net "M_E_CPU1_SB_DQ<27>")
	)
	(segment
		(start 34.590482 -312.174382)
		(end 35.11423 -311.650634)
		(width 0.14478)
		(layer "In6.Cu")
		(net "M_E_CPU1_SB_DQ<27>")
	)
	(segment
		(start 57.77865 -311.271666)
		(end 59.925966 -311.271666)
		(width 0.14478)
		(layer "In6.Cu")
		(net "M_E_CPU1_SB_DQ<27>")
	)
	(segment
		(start 48.397922 -312.500518)
		(end 50.449734 -311.650634)
		(width 0.14478)
		(layer "In6.Cu")
		(net "M_E_CPU1_SB_DQ<27>")
	)
	(arc
		(start 81.71815 -289.963606)
		(mid 82.001106 -290.039783)
		(end 82.284062 -289.963606)
		(width 0.0889)
		(layer "In6.Cu")
		(net "M_E_CPU1_SB_DQ<27>")
	)
	(arc
		(start 82.284062 -289.963606)
		(mid 82.440381 -289.914611)
		(end 82.602578 -289.937444)
		(width 0.0889)
		(layer "In6.Cu")
		(net "M_E_CPU1_SB_DQ<27>")
	)
	(arc
		(start 78.711044 -289.913314)
		(mid 78.807588 -289.926311)
		(end 78.89748 -289.96386)
		(width 0.0889)
		(layer "In6.Cu")
		(net "M_E_CPU1_SB_DQ<27>")
	)
	(arc
		(start 80.403954 -289.963606)
		(mid 80.586205 -289.913256)
		(end 80.769714 -289.95878)
		(width 0.0889)
		(layer "In6.Cu")
		(net "M_E_CPU1_SB_DQ<27>")
	)
	(arc
		(start 78.909418 -289.970718)
		(mid 79.186952 -290.039699)
		(end 79.46263 -289.963606)
		(width 0.0889)
		(layer "In6.Cu")
		(net "M_E_CPU1_SB_DQ<27>")
	)
	(arc
		(start 79.83728 -289.963606)
		(mid 80.110224 -290.040186)
		(end 80.38592 -289.974274)
		(width 0.0889)
		(layer "In6.Cu")
		(net "M_E_CPU1_SB_DQ<27>")
	)
	(arc
		(start 78.461108 -290.017708)
		(mid 78.576845 -289.943425)
		(end 78.711044 -289.913314)
		(width 0.0889)
		(layer "In6.Cu")
		(net "M_E_CPU1_SB_DQ<27>")
	)
	(arc
		(start 79.471012 -289.95878)
		(mid 79.654774 -289.913164)
		(end 79.83728 -289.963606)
		(width 0.0889)
		(layer "In6.Cu")
		(net "M_E_CPU1_SB_DQ<27>")
	)
	(arc
		(start 81.35239 -289.95878)
		(mid 81.535898 -289.913286)
		(end 81.71815 -289.963606)
		(width 0.0889)
		(layer "In6.Cu")
		(net "M_E_CPU1_SB_DQ<27>")
	)
	(arc
		(start 80.778096 -289.963606)
		(mid 81.061052 -290.039783)
		(end 81.344008 -289.963606)
		(width 0.0889)
		(layer "In6.Cu")
		(net "M_E_CPU1_SB_DQ<27>")
	)
	(segment
		(start 81.527904 -289.210242)
		(end 81.061052 -289.47618)
		(width 0.10668)
		(layer "F.Cu")
		(net "M_E_CPU1_SB_DQ<26>")
	)
	(segment
		(start 26.793952 -310.647588)
		(end 26.956766 -310.810402)
		(width 0.14478)
		(layer "In6.Cu")
		(net "M_E_CPU1_SB_DQ<26>")
	)
	(segment
		(start 49.435004 -310.810402)
		(end 50.285142 -309.960264)
		(width 0.14478)
		(layer "In6.Cu")
		(net "M_E_CPU1_SB_DQ<26>")
	)
	(segment
		(start 81.192624 -289.127438)
		(end 81.214976 -289.21075)
		(width 0.0889)
		(layer "In6.Cu")
		(net "M_E_CPU1_SB_DQ<26>")
	)
	(segment
		(start 26.237692 -310.647588)
		(end 26.237692 -310.389778)
		(width 0.14478)
		(layer "In6.Cu")
		(net "M_E_CPU1_SB_DQ<26>")
	)
	(segment
		(start 76.996544 -290.420806)
		(end 77.322934 -290.420806)
		(width 0.0889)
		(layer "In6.Cu")
		(net "M_E_CPU1_SB_DQ<26>")
	)
	(segment
		(start 65.196212 -302.040544)
		(end 72.09663 -295.140126)
		(width 0.14478)
		(layer "In6.Cu")
		(net "M_E_CPU1_SB_DQ<26>")
	)
	(segment
		(start 25.152096 -310.385206)
		(end 25.577292 -310.810402)
		(width 0.14478)
		(layer "In6.Cu")
		(net "M_E_CPU1_SB_DQ<26>")
	)
	(segment
		(start 45.493686 -309.960264)
		(end 46.343824 -310.810402)
		(width 0.14478)
		(layer "In6.Cu")
		(net "M_E_CPU1_SB_DQ<26>")
	)
	(segment
		(start 76.740766 -290.676584)
		(end 76.996544 -290.420806)
		(width 0.0889)
		(layer "In6.Cu")
		(net "M_E_CPU1_SB_DQ<26>")
	)
	(segment
		(start 60.816236 -308.793896)
		(end 60.816236 -308.352698)
		(width 0.14478)
		(layer "In6.Cu")
		(net "M_E_CPU1_SB_DQ<26>")
	)
	(segment
		(start 34.555176 -310.810402)
		(end 35.405314 -309.960264)
		(width 0.14478)
		(layer "In6.Cu")
		(net "M_E_CPU1_SB_DQ<26>")
	)
	(segment
		(start 73.080626 -295.140126)
		(end 75.976988 -292.243764)
		(width 0.14478)
		(layer "In6.Cu")
		(net "M_E_CPU1_SB_DQ<26>")
	)
	(segment
		(start 26.956766 -310.810402)
		(end 34.555176 -310.810402)
		(width 0.14478)
		(layer "In6.Cu")
		(net "M_E_CPU1_SB_DQ<26>")
	)
	(segment
		(start 26.793952 -310.389778)
		(end 26.793952 -310.647588)
		(width 0.14478)
		(layer "In6.Cu")
		(net "M_E_CPU1_SB_DQ<26>")
	)
	(segment
		(start 79.360014 -289.148774)
		(end 79.368396 -289.1536)
		(width 0.0889)
		(layer "In6.Cu")
		(net "M_E_CPU1_SB_DQ<26>")
	)
	(segment
		(start 57.803542 -309.960264)
		(end 59.649868 -309.960264)
		(width 0.14478)
		(layer "In6.Cu")
		(net "M_E_CPU1_SB_DQ<26>")
	)
	(segment
		(start 26.074878 -310.810402)
		(end 26.237692 -310.647588)
		(width 0.14478)
		(layer "In6.Cu")
		(net "M_E_CPU1_SB_DQ<26>")
	)
	(segment
		(start 61.54039 -307.111908)
		(end 64.195198 -304.4571)
		(width 0.14478)
		(layer "In6.Cu")
		(net "M_E_CPU1_SB_DQ<26>")
	)
	(segment
		(start 77.322934 -290.420806)
		(end 78.51394 -289.2298)
		(width 0.0889)
		(layer "In6.Cu")
		(net "M_E_CPU1_SB_DQ<26>")
	)
	(segment
		(start 54.266084 -310.810402)
		(end 56.953404 -310.810402)
		(width 0.14478)
		(layer "In6.Cu")
		(net "M_E_CPU1_SB_DQ<26>")
	)
	(segment
		(start 76.740766 -291.479986)
		(end 76.740766 -290.676584)
		(width 0.0889)
		(layer "In6.Cu")
		(net "M_E_CPU1_SB_DQ<26>")
	)
	(segment
		(start 79.934054 -289.1536)
		(end 79.942436 -289.148774)
		(width 0.0889)
		(layer "In6.Cu")
		(net "M_E_CPU1_SB_DQ<26>")
	)
	(segment
		(start 26.237692 -310.389778)
		(end 26.400506 -310.226964)
		(width 0.14478)
		(layer "In6.Cu")
		(net "M_E_CPU1_SB_DQ<26>")
	)
	(segment
		(start 37.797994 -309.960264)
		(end 38.648132 -310.810402)
		(width 0.14478)
		(layer "In6.Cu")
		(net "M_E_CPU1_SB_DQ<26>")
	)
	(segment
		(start 60.816236 -308.352698)
		(end 61.54039 -307.628544)
		(width 0.14478)
		(layer "In6.Cu")
		(net "M_E_CPU1_SB_DQ<26>")
	)
	(segment
		(start 38.648132 -310.810402)
		(end 42.180256 -310.810402)
		(width 0.14478)
		(layer "In6.Cu")
		(net "M_E_CPU1_SB_DQ<26>")
	)
	(segment
		(start 56.953404 -310.810402)
		(end 57.803542 -309.960264)
		(width 0.14478)
		(layer "In6.Cu")
		(net "M_E_CPU1_SB_DQ<26>")
	)
	(segment
		(start 72.09663 -295.140126)
		(end 73.080626 -295.140126)
		(width 0.14478)
		(layer "In6.Cu")
		(net "M_E_CPU1_SB_DQ<26>")
	)
	(segment
		(start 81.214976 -289.21075)
		(end 81.061052 -289.47618)
		(width 0.0889)
		(layer "In6.Cu")
		(net "M_E_CPU1_SB_DQ<26>")
	)
	(segment
		(start 26.400506 -310.226964)
		(end 26.631138 -310.226964)
		(width 0.14478)
		(layer "In6.Cu")
		(net "M_E_CPU1_SB_DQ<26>")
	)
	(segment
		(start 64.195198 -304.4571)
		(end 65.196212 -302.040544)
		(width 0.14478)
		(layer "In6.Cu")
		(net "M_E_CPU1_SB_DQ<26>")
	)
	(segment
		(start 25.577292 -310.810402)
		(end 26.074878 -310.810402)
		(width 0.14478)
		(layer "In6.Cu")
		(net "M_E_CPU1_SB_DQ<26>")
	)
	(segment
		(start 46.343824 -310.810402)
		(end 49.435004 -310.810402)
		(width 0.14478)
		(layer "In6.Cu")
		(net "M_E_CPU1_SB_DQ<26>")
	)
	(segment
		(start 35.405314 -309.960264)
		(end 37.797994 -309.960264)
		(width 0.14478)
		(layer "In6.Cu")
		(net "M_E_CPU1_SB_DQ<26>")
	)
	(segment
		(start 75.976988 -292.243764)
		(end 76.740766 -291.479986)
		(width 0.0889)
		(layer "In6.Cu")
		(net "M_E_CPU1_SB_DQ<26>")
	)
	(segment
		(start 78.51394 -289.2298)
		(end 78.711044 -289.2298)
		(width 0.0889)
		(layer "In6.Cu")
		(net "M_E_CPU1_SB_DQ<26>")
	)
	(segment
		(start 50.285142 -309.960264)
		(end 53.415946 -309.960264)
		(width 0.14478)
		(layer "In6.Cu")
		(net "M_E_CPU1_SB_DQ<26>")
	)
	(segment
		(start 61.54039 -307.628544)
		(end 61.54039 -307.111908)
		(width 0.14478)
		(layer "In6.Cu")
		(net "M_E_CPU1_SB_DQ<26>")
	)
	(segment
		(start 59.649868 -309.960264)
		(end 60.816236 -308.793896)
		(width 0.14478)
		(layer "In6.Cu")
		(net "M_E_CPU1_SB_DQ<26>")
	)
	(segment
		(start 79.92364 -289.159696)
		(end 79.934054 -289.1536)
		(width 0.0889)
		(layer "In6.Cu")
		(net "M_E_CPU1_SB_DQ<26>")
	)
	(segment
		(start 43.030394 -309.960264)
		(end 45.493686 -309.960264)
		(width 0.14478)
		(layer "In6.Cu")
		(net "M_E_CPU1_SB_DQ<26>")
	)
	(segment
		(start 26.631138 -310.226964)
		(end 26.793952 -310.389778)
		(width 0.14478)
		(layer "In6.Cu")
		(net "M_E_CPU1_SB_DQ<26>")
	)
	(segment
		(start 53.415946 -309.960264)
		(end 54.266084 -310.810402)
		(width 0.14478)
		(layer "In6.Cu")
		(net "M_E_CPU1_SB_DQ<26>")
	)
	(segment
		(start 42.180256 -310.810402)
		(end 43.030394 -309.960264)
		(width 0.14478)
		(layer "In6.Cu")
		(net "M_E_CPU1_SB_DQ<26>")
	)
	(arc
		(start 79.942436 -289.148774)
		(mid 80.125944 -289.10328)
		(end 80.308196 -289.1536)
		(width 0.0889)
		(layer "In6.Cu")
		(net "M_E_CPU1_SB_DQ<26>")
	)
	(arc
		(start 80.308196 -289.1536)
		(mid 80.591152 -289.229777)
		(end 80.874108 -289.1536)
		(width 0.0889)
		(layer "In6.Cu")
		(net "M_E_CPU1_SB_DQ<26>")
	)
	(arc
		(start 78.994254 -289.1536)
		(mid 79.176505 -289.10325)
		(end 79.360014 -289.148774)
		(width 0.0889)
		(layer "In6.Cu")
		(net "M_E_CPU1_SB_DQ<26>")
	)
	(arc
		(start 78.711044 -289.2298)
		(mid 78.857697 -289.210455)
		(end 78.994254 -289.1536)
		(width 0.0889)
		(layer "In6.Cu")
		(net "M_E_CPU1_SB_DQ<26>")
	)
	(arc
		(start 79.368396 -289.1536)
		(mid 79.645209 -289.229743)
		(end 79.92364 -289.159696)
		(width 0.0889)
		(layer "In6.Cu")
		(net "M_E_CPU1_SB_DQ<26>")
	)
	(arc
		(start 80.874108 -289.1536)
		(mid 81.030427 -289.104605)
		(end 81.192624 -289.127438)
		(width 0.0889)
		(layer "In6.Cu")
		(net "M_E_CPU1_SB_DQ<26>")
	)
	(segment
		(start 83.408012 -289.210242)
		(end 82.940906 -289.47618)
		(width 0.10668)
		(layer "F.Cu")
		(net "M_E_CPU1_SB_DQ<25>")
	)
	(segment
		(start 78.993238 -289.798506)
		(end 79.011526 -289.80892)
		(width 0.0889)
		(layer "In6.Cu")
		(net "M_E_CPU1_SB_DQ<25>")
	)
	(segment
		(start 31.568898 -311.431178)
		(end 31.731712 -311.268364)
		(width 0.14478)
		(layer "In6.Cu")
		(net "M_E_CPU1_SB_DQ<25>")
	)
	(segment
		(start 31.175452 -312.046112)
		(end 31.406084 -312.046112)
		(width 0.14478)
		(layer "In6.Cu")
		(net "M_E_CPU1_SB_DQ<25>")
	)
	(segment
		(start 57.596786 -310.810148)
		(end 59.751468 -310.810148)
		(width 0.14478)
		(layer "In6.Cu")
		(net "M_E_CPU1_SB_DQ<25>")
	)
	(segment
		(start 37.962078 -310.810148)
		(end 38.812216 -311.660286)
		(width 0.14478)
		(layer "In6.Cu")
		(net "M_E_CPU1_SB_DQ<25>")
	)
	(segment
		(start 78.649322 -289.722814)
		(end 78.711044 -289.722814)
		(width 0.0889)
		(layer "In6.Cu")
		(net "M_E_CPU1_SB_DQ<25>")
	)
	(segment
		(start 78.05547 -290.064952)
		(end 78.063598 -290.064952)
		(width 0.0889)
		(layer "In6.Cu")
		(net "M_E_CPU1_SB_DQ<25>")
	)
	(segment
		(start 31.731712 -311.268364)
		(end 31.962344 -311.268364)
		(width 0.14478)
		(layer "In6.Cu")
		(net "M_E_CPU1_SB_DQ<25>")
	)
	(segment
		(start 77.738986 -290.381436)
		(end 78.05547 -290.064952)
		(width 0.0889)
		(layer "In6.Cu")
		(net "M_E_CPU1_SB_DQ<25>")
	)
	(segment
		(start 29.510736 -312.046112)
		(end 30.293564 -312.046112)
		(width 0.14478)
		(layer "In6.Cu")
		(net "M_E_CPU1_SB_DQ<25>")
	)
	(segment
		(start 56.746648 -311.660286)
		(end 57.596786 -310.810148)
		(width 0.14478)
		(layer "In6.Cu")
		(net "M_E_CPU1_SB_DQ<25>")
	)
	(segment
		(start 30.849824 -311.268364)
		(end 31.012638 -311.431178)
		(width 0.14478)
		(layer "In6.Cu")
		(net "M_E_CPU1_SB_DQ<25>")
	)
	(segment
		(start 71.317612 -296.55516)
		(end 71.522336 -296.55516)
		(width 0.14478)
		(layer "In6.Cu")
		(net "M_E_CPU1_SB_DQ<25>")
	)
	(segment
		(start 29.252164 -311.235344)
		(end 29.252164 -311.78754)
		(width 0.14478)
		(layer "In6.Cu")
		(net "M_E_CPU1_SB_DQ<25>")
	)
	(segment
		(start 30.456378 -311.431178)
		(end 30.619192 -311.268364)
		(width 0.14478)
		(layer "In6.Cu")
		(net "M_E_CPU1_SB_DQ<25>")
	)
	(segment
		(start 76.537566 -292.326568)
		(end 76.537566 -292.048184)
		(width 0.0889)
		(layer "In6.Cu")
		(net "M_E_CPU1_SB_DQ<25>")
	)
	(segment
		(start 79.366872 -289.79876)
		(end 79.384906 -289.788092)
		(width 0.0889)
		(layer "In6.Cu")
		(net "M_E_CPU1_SB_DQ<25>")
	)
	(segment
		(start 32.354266 -311.660286)
		(end 33.88995 -311.660286)
		(width 0.14478)
		(layer "In6.Cu")
		(net "M_E_CPU1_SB_DQ<25>")
	)
	(segment
		(start 34.961322 -311.216548)
		(end 35.367722 -310.810148)
		(width 0.14478)
		(layer "In6.Cu")
		(net "M_E_CPU1_SB_DQ<25>")
	)
	(segment
		(start 71.957438 -296.785538)
		(end 72.151494 -296.591482)
		(width 0.14478)
		(layer "In6.Cu")
		(net "M_E_CPU1_SB_DQ<25>")
	)
	(segment
		(start 31.962344 -311.268364)
		(end 32.354266 -311.660286)
		(width 0.14478)
		(layer "In6.Cu")
		(net "M_E_CPU1_SB_DQ<25>")
	)
	(segment
		(start 50.078386 -310.810148)
		(end 53.622702 -310.810148)
		(width 0.14478)
		(layer "In6.Cu")
		(net "M_E_CPU1_SB_DQ<25>")
	)
	(segment
		(start 65.577466 -302.295306)
		(end 71.317612 -296.55516)
		(width 0.14478)
		(layer "In6.Cu")
		(net "M_E_CPU1_SB_DQ<25>")
	)
	(segment
		(start 35.367722 -310.810148)
		(end 37.962078 -310.810148)
		(width 0.14478)
		(layer "In6.Cu")
		(net "M_E_CPU1_SB_DQ<25>")
	)
	(segment
		(start 76.537566 -292.048184)
		(end 77.738986 -290.846764)
		(width 0.0889)
		(layer "In6.Cu")
		(net "M_E_CPU1_SB_DQ<25>")
	)
	(segment
		(start 82.786982 -289.74161)
		(end 82.940906 -289.47618)
		(width 0.0889)
		(layer "In6.Cu")
		(net "M_E_CPU1_SB_DQ<25>")
	)
	(segment
		(start 54.47284 -311.660286)
		(end 56.746648 -311.660286)
		(width 0.14478)
		(layer "In6.Cu")
		(net "M_E_CPU1_SB_DQ<25>")
	)
	(segment
		(start 31.568898 -311.883298)
		(end 31.568898 -311.431178)
		(width 0.14478)
		(layer "In6.Cu")
		(net "M_E_CPU1_SB_DQ<25>")
	)
	(segment
		(start 71.752714 -296.785538)
		(end 71.957438 -296.785538)
		(width 0.14478)
		(layer "In6.Cu")
		(net "M_E_CPU1_SB_DQ<25>")
	)
	(segment
		(start 73.274428 -295.589706)
		(end 75.981306 -292.882828)
		(width 0.14478)
		(layer "In6.Cu")
		(net "M_E_CPU1_SB_DQ<25>")
	)
	(segment
		(start 29.252164 -311.78754)
		(end 29.510736 -312.046112)
		(width 0.14478)
		(layer "In6.Cu")
		(net "M_E_CPU1_SB_DQ<25>")
	)
	(segment
		(start 33.88995 -311.660286)
		(end 34.961322 -311.216548)
		(width 0.14478)
		(layer "In6.Cu")
		(net "M_E_CPU1_SB_DQ<25>")
	)
	(segment
		(start 31.012638 -311.431178)
		(end 31.012638 -311.883298)
		(width 0.14478)
		(layer "In6.Cu")
		(net "M_E_CPU1_SB_DQ<25>")
	)
	(segment
		(start 30.293564 -312.046112)
		(end 30.456378 -311.883298)
		(width 0.14478)
		(layer "In6.Cu")
		(net "M_E_CPU1_SB_DQ<25>")
	)
	(segment
		(start 42.840402 -310.810148)
		(end 45.607478 -310.810148)
		(width 0.14478)
		(layer "In6.Cu")
		(net "M_E_CPU1_SB_DQ<25>")
	)
	(segment
		(start 59.751468 -310.810148)
		(end 61.99759 -308.564026)
		(width 0.14478)
		(layer "In6.Cu")
		(net "M_E_CPU1_SB_DQ<25>")
	)
	(segment
		(start 78.063598 -290.064952)
		(end 78.233524 -289.895026)
		(width 0.0889)
		(layer "In6.Cu")
		(net "M_E_CPU1_SB_DQ<25>")
	)
	(segment
		(start 53.622702 -310.810148)
		(end 54.47284 -311.660286)
		(width 0.14478)
		(layer "In6.Cu")
		(net "M_E_CPU1_SB_DQ<25>")
	)
	(segment
		(start 82.179668 -289.803586)
		(end 82.18805 -289.79876)
		(width 0.0889)
		(layer "In6.Cu")
		(net "M_E_CPU1_SB_DQ<25>")
	)
	(segment
		(start 31.012638 -311.883298)
		(end 31.175452 -312.046112)
		(width 0.14478)
		(layer "In6.Cu")
		(net "M_E_CPU1_SB_DQ<25>")
	)
	(segment
		(start 64.570864 -304.728626)
		(end 65.577466 -302.295306)
		(width 0.14478)
		(layer "In6.Cu")
		(net "M_E_CPU1_SB_DQ<25>")
	)
	(segment
		(start 61.99759 -307.3019)
		(end 64.570864 -304.728626)
		(width 0.14478)
		(layer "In6.Cu")
		(net "M_E_CPU1_SB_DQ<25>")
	)
	(segment
		(start 45.607478 -310.810148)
		(end 46.457616 -311.660286)
		(width 0.14478)
		(layer "In6.Cu")
		(net "M_E_CPU1_SB_DQ<25>")
	)
	(segment
		(start 30.619192 -311.268364)
		(end 30.849824 -311.268364)
		(width 0.14478)
		(layer "In6.Cu")
		(net "M_E_CPU1_SB_DQ<25>")
	)
	(segment
		(start 72.283066 -295.589706)
		(end 73.274428 -295.589706)
		(width 0.14478)
		(layer "In6.Cu")
		(net "M_E_CPU1_SB_DQ<25>")
	)
	(segment
		(start 72.151494 -296.386758)
		(end 71.921116 -296.15638)
		(width 0.14478)
		(layer "In6.Cu")
		(net "M_E_CPU1_SB_DQ<25>")
	)
	(segment
		(start 31.406084 -312.046112)
		(end 31.568898 -311.883298)
		(width 0.14478)
		(layer "In6.Cu")
		(net "M_E_CPU1_SB_DQ<25>")
	)
	(segment
		(start 30.456378 -311.883298)
		(end 30.456378 -311.431178)
		(width 0.14478)
		(layer "In6.Cu")
		(net "M_E_CPU1_SB_DQ<25>")
	)
	(segment
		(start 72.151494 -296.591482)
		(end 72.151494 -296.386758)
		(width 0.14478)
		(layer "In6.Cu")
		(net "M_E_CPU1_SB_DQ<25>")
	)
	(segment
		(start 46.457616 -311.660286)
		(end 49.228248 -311.660286)
		(width 0.14478)
		(layer "In6.Cu")
		(net "M_E_CPU1_SB_DQ<25>")
	)
	(segment
		(start 80.299814 -289.803586)
		(end 80.308196 -289.79876)
		(width 0.0889)
		(layer "In6.Cu")
		(net "M_E_CPU1_SB_DQ<25>")
	)
	(segment
		(start 38.812216 -311.660286)
		(end 41.990264 -311.660286)
		(width 0.14478)
		(layer "In6.Cu")
		(net "M_E_CPU1_SB_DQ<25>")
	)
	(segment
		(start 41.990264 -311.660286)
		(end 42.840402 -310.810148)
		(width 0.14478)
		(layer "In6.Cu")
		(net "M_E_CPU1_SB_DQ<25>")
	)
	(segment
		(start 49.228248 -311.660286)
		(end 50.078386 -310.810148)
		(width 0.14478)
		(layer "In6.Cu")
		(net "M_E_CPU1_SB_DQ<25>")
	)
	(segment
		(start 77.738986 -290.846764)
		(end 77.738986 -290.381436)
		(width 0.0889)
		(layer "In6.Cu")
		(net "M_E_CPU1_SB_DQ<25>")
	)
	(segment
		(start 71.522336 -296.55516)
		(end 71.752714 -296.785538)
		(width 0.14478)
		(layer "In6.Cu")
		(net "M_E_CPU1_SB_DQ<25>")
	)
	(segment
		(start 82.69097 -289.76701)
		(end 82.786982 -289.74161)
		(width 0.0889)
		(layer "In6.Cu")
		(net "M_E_CPU1_SB_DQ<25>")
	)
	(segment
		(start 71.921116 -296.15638)
		(end 71.921116 -295.951656)
		(width 0.14478)
		(layer "In6.Cu")
		(net "M_E_CPU1_SB_DQ<25>")
	)
	(segment
		(start 71.921116 -295.951656)
		(end 72.283066 -295.589706)
		(width 0.14478)
		(layer "In6.Cu")
		(net "M_E_CPU1_SB_DQ<25>")
	)
	(segment
		(start 75.981306 -292.882828)
		(end 76.537566 -292.326568)
		(width 0.0889)
		(layer "In6.Cu")
		(net "M_E_CPU1_SB_DQ<25>")
	)
	(segment
		(start 61.99759 -308.564026)
		(end 61.99759 -307.3019)
		(width 0.14478)
		(layer "In6.Cu")
		(net "M_E_CPU1_SB_DQ<25>")
	)
	(arc
		(start 79.933546 -289.79876)
		(mid 80.116051 -289.849237)
		(end 80.299814 -289.803586)
		(width 0.0889)
		(layer "In6.Cu")
		(net "M_E_CPU1_SB_DQ<25>")
	)
	(arc
		(start 81.247996 -289.79876)
		(mid 81.530952 -289.722583)
		(end 81.813908 -289.79876)
		(width 0.0889)
		(layer "In6.Cu")
		(net "M_E_CPU1_SB_DQ<25>")
	)
	(arc
		(start 80.308196 -289.79876)
		(mid 80.591152 -289.722583)
		(end 80.874108 -289.79876)
		(width 0.0889)
		(layer "In6.Cu")
		(net "M_E_CPU1_SB_DQ<25>")
	)
	(arc
		(start 78.711044 -289.722814)
		(mid 78.857145 -289.74202)
		(end 78.993238 -289.798506)
		(width 0.0889)
		(layer "In6.Cu")
		(net "M_E_CPU1_SB_DQ<25>")
	)
	(arc
		(start 81.813908 -289.79876)
		(mid 81.996159 -289.84911)
		(end 82.179668 -289.803586)
		(width 0.0889)
		(layer "In6.Cu")
		(net "M_E_CPU1_SB_DQ<25>")
	)
	(arc
		(start 80.874108 -289.79876)
		(mid 81.061052 -289.849015)
		(end 81.247996 -289.79876)
		(width 0.0889)
		(layer "In6.Cu")
		(net "M_E_CPU1_SB_DQ<25>")
	)
	(arc
		(start 78.233524 -289.895026)
		(mid 78.424294 -289.767558)
		(end 78.649322 -289.722814)
		(width 0.0889)
		(layer "In6.Cu")
		(net "M_E_CPU1_SB_DQ<25>")
	)
	(arc
		(start 79.011526 -289.80892)
		(mid 79.190501 -289.848958)
		(end 79.366872 -289.79876)
		(width 0.0889)
		(layer "In6.Cu")
		(net "M_E_CPU1_SB_DQ<25>")
	)
	(arc
		(start 79.384906 -289.788092)
		(mid 79.660601 -289.722249)
		(end 79.933546 -289.79876)
		(width 0.0889)
		(layer "In6.Cu")
		(net "M_E_CPU1_SB_DQ<25>")
	)
	(arc
		(start 82.18805 -289.79876)
		(mid 82.435763 -289.72354)
		(end 82.69097 -289.76701)
		(width 0.0889)
		(layer "In6.Cu")
		(net "M_E_CPU1_SB_DQ<25>")
	)
	(segment
		(start 81.997804 -288.400236)
		(end 81.530952 -288.666174)
		(width 0.10668)
		(layer "F.Cu")
		(net "M_E_CPU1_SB_DQ<24>")
	)
	(segment
		(start 55.82539 -310.182768)
		(end 55.82539 -309.830978)
		(width 0.14478)
		(layer "In6.Cu")
		(net "M_E_CPU1_SB_DQ<24>")
	)
	(segment
		(start 30.292802 -310.35244)
		(end 30.455616 -310.189626)
		(width 0.14478)
		(layer "In6.Cu")
		(net "M_E_CPU1_SB_DQ<24>")
	)
	(segment
		(start 51.33975 -309.414164)
		(end 51.643534 -309.11038)
		(width 0.14478)
		(layer "In6.Cu")
		(net "M_E_CPU1_SB_DQ<24>")
	)
	(segment
		(start 79.453994 -288.982658)
		(end 79.464408 -288.988754)
		(width 0.0889)
		(layer "In6.Cu")
		(net "M_E_CPU1_SB_DQ<24>")
	)
	(segment
		(start 56.775096 -310.345582)
		(end 57.999376 -309.121302)
		(width 0.14478)
		(layer "In6.Cu")
		(net "M_E_CPU1_SB_DQ<24>")
	)
	(segment
		(start 56.38165 -309.830978)
		(end 56.38165 -310.182768)
		(width 0.14478)
		(layer "In6.Cu")
		(net "M_E_CPU1_SB_DQ<24>")
	)
	(segment
		(start 75.466194 -292.11143)
		(end 76.011532 -291.566092)
		(width 0.14478)
		(layer "In6.Cu")
		(net "M_E_CPU1_SB_DQ<24>")
	)
	(segment
		(start 32.25546 -309.960518)
		(end 34.718752 -309.960518)
		(width 0.14478)
		(layer "In6.Cu")
		(net "M_E_CPU1_SB_DQ<24>")
	)
	(segment
		(start 60.15101 -308.823106)
		(end 60.15101 -308.381908)
		(width 0.14478)
		(layer "In6.Cu")
		(net "M_E_CPU1_SB_DQ<24>")
	)
	(segment
		(start 72.990964 -293.609776)
		(end 73.195688 -293.609776)
		(width 0.14478)
		(layer "In6.Cu")
		(net "M_E_CPU1_SB_DQ<24>")
	)
	(segment
		(start 55.662576 -310.345582)
		(end 55.82539 -310.182768)
		(width 0.14478)
		(layer "In6.Cu")
		(net "M_E_CPU1_SB_DQ<24>")
	)
	(segment
		(start 73.617836 -293.8272)
		(end 73.811892 -293.633144)
		(width 0.14478)
		(layer "In6.Cu")
		(net "M_E_CPU1_SB_DQ<24>")
	)
	(segment
		(start 53.13172 -309.11038)
		(end 53.351938 -309.11038)
		(width 0.14478)
		(layer "In6.Cu")
		(net "M_E_CPU1_SB_DQ<24>")
	)
	(segment
		(start 73.79843 -292.80231)
		(end 75.466194 -292.11143)
		(width 0.14478)
		(layer "In6.Cu")
		(net "M_E_CPU1_SB_DQ<24>")
	)
	(segment
		(start 78.71079 -289.0393)
		(end 78.711044 -289.039046)
		(width 0.0889)
		(layer "In6.Cu")
		(net "M_E_CPU1_SB_DQ<24>")
	)
	(segment
		(start 76.524866 -291.052758)
		(end 76.524866 -290.587684)
		(width 0.0889)
		(layer "In6.Cu")
		(net "M_E_CPU1_SB_DQ<24>")
	)
	(segment
		(start 30.61843 -309.66664)
		(end 30.849062 -309.66664)
		(width 0.14478)
		(layer "In6.Cu")
		(net "M_E_CPU1_SB_DQ<24>")
	)
	(segment
		(start 30.455616 -310.189626)
		(end 30.455616 -309.829454)
		(width 0.14478)
		(layer "In6.Cu")
		(net "M_E_CPU1_SB_DQ<24>")
	)
	(segment
		(start 61.09081 -306.925472)
		(end 63.813944 -304.202338)
		(width 0.14478)
		(layer "In6.Cu")
		(net "M_E_CPU1_SB_DQ<24>")
	)
	(segment
		(start 38.661848 -309.960518)
		(end 42.369232 -309.960518)
		(width 0.14478)
		(layer "In6.Cu")
		(net "M_E_CPU1_SB_DQ<24>")
	)
	(segment
		(start 81.377028 -288.931604)
		(end 81.530952 -288.666174)
		(width 0.0889)
		(layer "In6.Cu")
		(net "M_E_CPU1_SB_DQ<24>")
	)
	(segment
		(start 35.56889 -309.11038)
		(end 37.81171 -309.11038)
		(width 0.14478)
		(layer "In6.Cu")
		(net "M_E_CPU1_SB_DQ<24>")
	)
	(segment
		(start 72.615552 -294.62476)
		(end 72.820276 -294.62476)
		(width 0.14478)
		(layer "In6.Cu")
		(net "M_E_CPU1_SB_DQ<24>")
	)
	(segment
		(start 60.15101 -308.381908)
		(end 61.09081 -307.442108)
		(width 0.14478)
		(layer "In6.Cu")
		(net "M_E_CPU1_SB_DQ<24>")
	)
	(segment
		(start 72.796908 -294.008556)
		(end 72.796908 -293.803832)
		(width 0.14478)
		(layer "In6.Cu")
		(net "M_E_CPU1_SB_DQ<24>")
	)
	(segment
		(start 30.455616 -309.829454)
		(end 30.61843 -309.66664)
		(width 0.14478)
		(layer "In6.Cu")
		(net "M_E_CPU1_SB_DQ<24>")
	)
	(segment
		(start 34.718752 -309.960518)
		(end 35.56889 -309.11038)
		(width 0.14478)
		(layer "In6.Cu")
		(net "M_E_CPU1_SB_DQ<24>")
	)
	(segment
		(start 76.524866 -290.587684)
		(end 77.058266 -290.054284)
		(width 0.0889)
		(layer "In6.Cu")
		(net "M_E_CPU1_SB_DQ<24>")
	)
	(segment
		(start 49.64176 -309.960518)
		(end 50.491898 -309.11038)
		(width 0.14478)
		(layer "In6.Cu")
		(net "M_E_CPU1_SB_DQ<24>")
	)
	(segment
		(start 73.413112 -293.8272)
		(end 73.617836 -293.8272)
		(width 0.14478)
		(layer "In6.Cu")
		(net "M_E_CPU1_SB_DQ<24>")
	)
	(segment
		(start 63.813944 -304.202338)
		(end 64.814958 -301.785782)
		(width 0.14478)
		(layer "In6.Cu")
		(net "M_E_CPU1_SB_DQ<24>")
	)
	(segment
		(start 31.011876 -310.189626)
		(end 31.17469 -310.35244)
		(width 0.14478)
		(layer "In6.Cu")
		(net "M_E_CPU1_SB_DQ<24>")
	)
	(segment
		(start 55.988204 -309.668164)
		(end 56.218836 -309.668164)
		(width 0.14478)
		(layer "In6.Cu")
		(net "M_E_CPU1_SB_DQ<24>")
	)
	(segment
		(start 52.271676 -309.11038)
		(end 52.57546 -309.414164)
		(width 0.14478)
		(layer "In6.Cu")
		(net "M_E_CPU1_SB_DQ<24>")
	)
	(segment
		(start 37.81171 -309.11038)
		(end 38.661848 -309.960518)
		(width 0.14478)
		(layer "In6.Cu")
		(net "M_E_CPU1_SB_DQ<24>")
	)
	(segment
		(start 52.57546 -309.414164)
		(end 52.827936 -309.414164)
		(width 0.14478)
		(layer "In6.Cu")
		(net "M_E_CPU1_SB_DQ<24>")
	)
	(segment
		(start 77.335126 -290.054284)
		(end 78.35011 -289.0393)
		(width 0.0889)
		(layer "In6.Cu")
		(net "M_E_CPU1_SB_DQ<24>")
	)
	(segment
		(start 31.011876 -309.829454)
		(end 31.011876 -310.189626)
		(width 0.14478)
		(layer "In6.Cu")
		(net "M_E_CPU1_SB_DQ<24>")
	)
	(segment
		(start 73.594468 -293.210996)
		(end 73.594468 -293.006272)
		(width 0.14478)
		(layer "In6.Cu")
		(net "M_E_CPU1_SB_DQ<24>")
	)
	(segment
		(start 31.17469 -310.35244)
		(end 31.405322 -310.35244)
		(width 0.14478)
		(layer "In6.Cu")
		(net "M_E_CPU1_SB_DQ<24>")
	)
	(segment
		(start 54.202076 -309.960518)
		(end 55.04688 -309.960518)
		(width 0.14478)
		(layer "In6.Cu")
		(net "M_E_CPU1_SB_DQ<24>")
	)
	(segment
		(start 57.999376 -309.121302)
		(end 58.399426 -309.121302)
		(width 0.14478)
		(layer "In6.Cu")
		(net "M_E_CPU1_SB_DQ<24>")
	)
	(segment
		(start 29.252164 -309.535322)
		(end 30.069282 -310.35244)
		(width 0.14478)
		(layer "In6.Cu")
		(net "M_E_CPU1_SB_DQ<24>")
	)
	(segment
		(start 59.350148 -309.11038)
		(end 59.863736 -309.11038)
		(width 0.14478)
		(layer "In6.Cu")
		(net "M_E_CPU1_SB_DQ<24>")
	)
	(segment
		(start 81.281016 -288.957004)
		(end 81.377028 -288.931604)
		(width 0.0889)
		(layer "In6.Cu")
		(net "M_E_CPU1_SB_DQ<24>")
	)
	(segment
		(start 55.04688 -309.960518)
		(end 55.431944 -310.345582)
		(width 0.14478)
		(layer "In6.Cu")
		(net "M_E_CPU1_SB_DQ<24>")
	)
	(segment
		(start 72.193404 -294.407336)
		(end 72.398128 -294.407336)
		(width 0.14478)
		(layer "In6.Cu")
		(net "M_E_CPU1_SB_DQ<24>")
	)
	(segment
		(start 73.594468 -293.006272)
		(end 73.79843 -292.80231)
		(width 0.14478)
		(layer "In6.Cu")
		(net "M_E_CPU1_SB_DQ<24>")
	)
	(segment
		(start 79.838296 -288.988754)
		(end 79.84871 -288.982658)
		(width 0.0889)
		(layer "In6.Cu")
		(net "M_E_CPU1_SB_DQ<24>")
	)
	(segment
		(start 73.811892 -293.42842)
		(end 73.594468 -293.210996)
		(width 0.14478)
		(layer "In6.Cu")
		(net "M_E_CPU1_SB_DQ<24>")
	)
	(segment
		(start 58.984642 -309.475886)
		(end 59.350148 -309.11038)
		(width 0.14478)
		(layer "In6.Cu")
		(net "M_E_CPU1_SB_DQ<24>")
	)
	(segment
		(start 59.863736 -309.11038)
		(end 60.15101 -308.823106)
		(width 0.14478)
		(layer "In6.Cu")
		(net "M_E_CPU1_SB_DQ<24>")
	)
	(segment
		(start 73.014332 -294.22598)
		(end 72.796908 -294.008556)
		(width 0.14478)
		(layer "In6.Cu")
		(net "M_E_CPU1_SB_DQ<24>")
	)
	(segment
		(start 31.405322 -310.35244)
		(end 31.568136 -310.189626)
		(width 0.14478)
		(layer "In6.Cu")
		(net "M_E_CPU1_SB_DQ<24>")
	)
	(segment
		(start 76.011532 -291.566092)
		(end 76.524866 -291.052758)
		(width 0.0889)
		(layer "In6.Cu")
		(net "M_E_CPU1_SB_DQ<24>")
	)
	(segment
		(start 73.195688 -293.609776)
		(end 73.413112 -293.8272)
		(width 0.14478)
		(layer "In6.Cu")
		(net "M_E_CPU1_SB_DQ<24>")
	)
	(segment
		(start 72.398128 -294.407336)
		(end 72.615552 -294.62476)
		(width 0.14478)
		(layer "In6.Cu")
		(net "M_E_CPU1_SB_DQ<24>")
	)
	(segment
		(start 56.38165 -310.182768)
		(end 56.544464 -310.345582)
		(width 0.14478)
		(layer "In6.Cu")
		(net "M_E_CPU1_SB_DQ<24>")
	)
	(segment
		(start 72.796908 -293.803832)
		(end 72.990964 -293.609776)
		(width 0.14478)
		(layer "In6.Cu")
		(net "M_E_CPU1_SB_DQ<24>")
	)
	(segment
		(start 50.78349 -309.11038)
		(end 51.087274 -309.414164)
		(width 0.14478)
		(layer "In6.Cu")
		(net "M_E_CPU1_SB_DQ<24>")
	)
	(segment
		(start 31.73095 -309.66664)
		(end 31.961582 -309.66664)
		(width 0.14478)
		(layer "In6.Cu")
		(net "M_E_CPU1_SB_DQ<24>")
	)
	(segment
		(start 31.568136 -310.189626)
		(end 31.568136 -309.829454)
		(width 0.14478)
		(layer "In6.Cu")
		(net "M_E_CPU1_SB_DQ<24>")
	)
	(segment
		(start 31.961582 -309.66664)
		(end 32.25546 -309.960518)
		(width 0.14478)
		(layer "In6.Cu")
		(net "M_E_CPU1_SB_DQ<24>")
	)
	(segment
		(start 73.014332 -294.430704)
		(end 73.014332 -294.22598)
		(width 0.14478)
		(layer "In6.Cu")
		(net "M_E_CPU1_SB_DQ<24>")
	)
	(segment
		(start 55.431944 -310.345582)
		(end 55.662576 -310.345582)
		(width 0.14478)
		(layer "In6.Cu")
		(net "M_E_CPU1_SB_DQ<24>")
	)
	(segment
		(start 53.351938 -309.11038)
		(end 54.202076 -309.960518)
		(width 0.14478)
		(layer "In6.Cu")
		(net "M_E_CPU1_SB_DQ<24>")
	)
	(segment
		(start 72.820276 -294.62476)
		(end 73.014332 -294.430704)
		(width 0.14478)
		(layer "In6.Cu")
		(net "M_E_CPU1_SB_DQ<24>")
	)
	(segment
		(start 51.643534 -309.11038)
		(end 52.271676 -309.11038)
		(width 0.14478)
		(layer "In6.Cu")
		(net "M_E_CPU1_SB_DQ<24>")
	)
	(segment
		(start 51.087274 -309.414164)
		(end 51.33975 -309.414164)
		(width 0.14478)
		(layer "In6.Cu")
		(net "M_E_CPU1_SB_DQ<24>")
	)
	(segment
		(start 43.21937 -309.11038)
		(end 45.43171 -309.11038)
		(width 0.14478)
		(layer "In6.Cu")
		(net "M_E_CPU1_SB_DQ<24>")
	)
	(segment
		(start 52.827936 -309.414164)
		(end 53.13172 -309.11038)
		(width 0.14478)
		(layer "In6.Cu")
		(net "M_E_CPU1_SB_DQ<24>")
	)
	(segment
		(start 46.281848 -309.960518)
		(end 49.64176 -309.960518)
		(width 0.14478)
		(layer "In6.Cu")
		(net "M_E_CPU1_SB_DQ<24>")
	)
	(segment
		(start 58.75401 -309.475886)
		(end 58.984642 -309.475886)
		(width 0.14478)
		(layer "In6.Cu")
		(net "M_E_CPU1_SB_DQ<24>")
	)
	(segment
		(start 80.769714 -288.99358)
		(end 80.778096 -288.988754)
		(width 0.0889)
		(layer "In6.Cu")
		(net "M_E_CPU1_SB_DQ<24>")
	)
	(segment
		(start 61.09081 -307.442108)
		(end 61.09081 -306.925472)
		(width 0.14478)
		(layer "In6.Cu")
		(net "M_E_CPU1_SB_DQ<24>")
	)
	(segment
		(start 56.544464 -310.345582)
		(end 56.775096 -310.345582)
		(width 0.14478)
		(layer "In6.Cu")
		(net "M_E_CPU1_SB_DQ<24>")
	)
	(segment
		(start 55.82539 -309.830978)
		(end 55.988204 -309.668164)
		(width 0.14478)
		(layer "In6.Cu")
		(net "M_E_CPU1_SB_DQ<24>")
	)
	(segment
		(start 78.35011 -289.0393)
		(end 78.71079 -289.0393)
		(width 0.0889)
		(layer "In6.Cu")
		(net "M_E_CPU1_SB_DQ<24>")
	)
	(segment
		(start 50.491898 -309.11038)
		(end 50.78349 -309.11038)
		(width 0.14478)
		(layer "In6.Cu")
		(net "M_E_CPU1_SB_DQ<24>")
	)
	(segment
		(start 45.43171 -309.11038)
		(end 46.281848 -309.960518)
		(width 0.14478)
		(layer "In6.Cu")
		(net "M_E_CPU1_SB_DQ<24>")
	)
	(segment
		(start 56.218836 -309.668164)
		(end 56.38165 -309.830978)
		(width 0.14478)
		(layer "In6.Cu")
		(net "M_E_CPU1_SB_DQ<24>")
	)
	(segment
		(start 42.369232 -309.960518)
		(end 43.21937 -309.11038)
		(width 0.14478)
		(layer "In6.Cu")
		(net "M_E_CPU1_SB_DQ<24>")
	)
	(segment
		(start 58.399426 -309.121302)
		(end 58.75401 -309.475886)
		(width 0.14478)
		(layer "In6.Cu")
		(net "M_E_CPU1_SB_DQ<24>")
	)
	(segment
		(start 30.849062 -309.66664)
		(end 31.011876 -309.829454)
		(width 0.14478)
		(layer "In6.Cu")
		(net "M_E_CPU1_SB_DQ<24>")
	)
	(segment
		(start 31.568136 -309.829454)
		(end 31.73095 -309.66664)
		(width 0.14478)
		(layer "In6.Cu")
		(net "M_E_CPU1_SB_DQ<24>")
	)
	(segment
		(start 77.058266 -290.054284)
		(end 77.335126 -290.054284)
		(width 0.0889)
		(layer "In6.Cu")
		(net "M_E_CPU1_SB_DQ<24>")
	)
	(segment
		(start 64.814958 -301.785782)
		(end 72.193404 -294.407336)
		(width 0.14478)
		(layer "In6.Cu")
		(net "M_E_CPU1_SB_DQ<24>")
	)
	(segment
		(start 30.069282 -310.35244)
		(end 30.292802 -310.35244)
		(width 0.14478)
		(layer "In6.Cu")
		(net "M_E_CPU1_SB_DQ<24>")
	)
	(segment
		(start 73.811892 -293.633144)
		(end 73.811892 -293.42842)
		(width 0.14478)
		(layer "In6.Cu")
		(net "M_E_CPU1_SB_DQ<24>")
	)
	(arc
		(start 80.778096 -288.988754)
		(mid 81.025809 -288.913534)
		(end 81.281016 -288.957004)
		(width 0.0889)
		(layer "In6.Cu")
		(net "M_E_CPU1_SB_DQ<24>")
	)
	(arc
		(start 79.84871 -288.982658)
		(mid 80.127142 -288.91256)
		(end 80.403954 -288.988754)
		(width 0.0889)
		(layer "In6.Cu")
		(net "M_E_CPU1_SB_DQ<24>")
	)
	(arc
		(start 79.464408 -288.988754)
		(mid 79.651352 -289.039009)
		(end 79.838296 -288.988754)
		(width 0.0889)
		(layer "In6.Cu")
		(net "M_E_CPU1_SB_DQ<24>")
	)
	(arc
		(start 80.403954 -288.988754)
		(mid 80.586205 -289.039104)
		(end 80.769714 -288.99358)
		(width 0.0889)
		(layer "In6.Cu")
		(net "M_E_CPU1_SB_DQ<24>")
	)
	(arc
		(start 78.711044 -289.039046)
		(mid 78.807976 -289.026295)
		(end 78.898242 -288.988754)
		(width 0.0889)
		(layer "In6.Cu")
		(net "M_E_CPU1_SB_DQ<24>")
	)
	(arc
		(start 78.898242 -288.988754)
		(mid 79.175309 -288.912483)
		(end 79.453994 -288.982658)
		(width 0.0889)
		(layer "In6.Cu")
		(net "M_E_CPU1_SB_DQ<24>")
	)
	(segment
		(start 82.937858 -288.400236)
		(end 82.471006 -288.666174)
		(width 0.10668)
		(layer "F.Cu")
		(net "M_E_CPU1_SB_DQ<23>")
	)
	(segment
		(start 52.358544 -308.260242)
		(end 53.32349 -308.452266)
		(width 0.14478)
		(layer "In6.Cu")
		(net "M_E_CPU1_SB_DQ<23>")
	)
	(segment
		(start 82.62493 -288.400744)
		(end 82.471006 -288.666174)
		(width 0.0889)
		(layer "In6.Cu")
		(net "M_E_CPU1_SB_DQ<23>")
	)
	(segment
		(start 82.602832 -288.317686)
		(end 82.62493 -288.400744)
		(width 0.0889)
		(layer "In6.Cu")
		(net "M_E_CPU1_SB_DQ<23>")
	)
	(segment
		(start 50.461418 -308.488588)
		(end 51.609752 -308.260242)
		(width 0.14478)
		(layer "In6.Cu")
		(net "M_E_CPU1_SB_DQ<23>")
	)
	(segment
		(start 77.747114 -289.228276)
		(end 77.747114 -288.630614)
		(width 0.0889)
		(layer "In6.Cu")
		(net "M_E_CPU1_SB_DQ<23>")
	)
	(segment
		(start 49.789842 -308.766718)
		(end 50.461418 -308.488588)
		(width 0.14478)
		(layer "In6.Cu")
		(net "M_E_CPU1_SB_DQ<23>")
	)
	(segment
		(start 38.810692 -308.827678)
		(end 40.232838 -309.11038)
		(width 0.14478)
		(layer "In6.Cu")
		(net "M_E_CPU1_SB_DQ<23>")
	)
	(segment
		(start 78.524354 -288.343848)
		(end 78.538832 -288.335466)
		(width 0.0889)
		(layer "In6.Cu")
		(net "M_E_CPU1_SB_DQ<23>")
	)
	(segment
		(start 36.63188 -308.260242)
		(end 36.940744 -308.260242)
		(width 0.14478)
		(layer "In6.Cu")
		(net "M_E_CPU1_SB_DQ<23>")
	)
	(segment
		(start 64.347598 -301.473616)
		(end 73.503536 -292.317678)
		(width 0.14478)
		(layer "In6.Cu")
		(net "M_E_CPU1_SB_DQ<23>")
	)
	(segment
		(start 56.906668 -308.880764)
		(end 57.321704 -308.798214)
		(width 0.14478)
		(layer "In6.Cu")
		(net "M_E_CPU1_SB_DQ<23>")
	)
	(segment
		(start 33.076134 -309.11038)
		(end 33.875726 -308.951376)
		(width 0.14478)
		(layer "In6.Cu")
		(net "M_E_CPU1_SB_DQ<23>")
	)
	(segment
		(start 81.344008 -288.343848)
		(end 81.35239 -288.339022)
		(width 0.0889)
		(layer "In6.Cu")
		(net "M_E_CPU1_SB_DQ<23>")
	)
	(segment
		(start 77.028548 -289.762184)
		(end 77.213206 -289.762184)
		(width 0.0889)
		(layer "In6.Cu")
		(net "M_E_CPU1_SB_DQ<23>")
	)
	(segment
		(start 54.136798 -308.78907)
		(end 54.597808 -308.880764)
		(width 0.14478)
		(layer "In6.Cu")
		(net "M_E_CPU1_SB_DQ<23>")
	)
	(segment
		(start 79.838296 -288.343848)
		(end 79.84871 -288.349944)
		(width 0.0889)
		(layer "In6.Cu")
		(net "M_E_CPU1_SB_DQ<23>")
	)
	(segment
		(start 33.875726 -308.951376)
		(end 36.63188 -308.260242)
		(width 0.14478)
		(layer "In6.Cu")
		(net "M_E_CPU1_SB_DQ<23>")
	)
	(segment
		(start 36.940744 -308.260242)
		(end 38.810692 -308.827678)
		(width 0.14478)
		(layer "In6.Cu")
		(net "M_E_CPU1_SB_DQ<23>")
	)
	(segment
		(start 40.908732 -309.11038)
		(end 44.300648 -308.260242)
		(width 0.14478)
		(layer "In6.Cu")
		(net "M_E_CPU1_SB_DQ<23>")
	)
	(segment
		(start 63.346584 -303.890172)
		(end 64.347598 -301.473616)
		(width 0.14478)
		(layer "In6.Cu")
		(net "M_E_CPU1_SB_DQ<23>")
	)
	(segment
		(start 28.01493 -309.11038)
		(end 33.076134 -309.11038)
		(width 0.14478)
		(layer "In6.Cu")
		(net "M_E_CPU1_SB_DQ<23>")
	)
	(segment
		(start 60.53963 -306.697126)
		(end 63.346584 -303.890172)
		(width 0.14478)
		(layer "In6.Cu")
		(net "M_E_CPU1_SB_DQ<23>")
	)
	(segment
		(start 48.06188 -309.11038)
		(end 49.789842 -308.766718)
		(width 0.14478)
		(layer "In6.Cu")
		(net "M_E_CPU1_SB_DQ<23>")
	)
	(segment
		(start 75.96505 -290.825682)
		(end 77.028548 -289.762184)
		(width 0.0889)
		(layer "In6.Cu")
		(net "M_E_CPU1_SB_DQ<23>")
	)
	(segment
		(start 77.747114 -288.630614)
		(end 77.957934 -288.419794)
		(width 0.0889)
		(layer "In6.Cu")
		(net "M_E_CPU1_SB_DQ<23>")
	)
	(segment
		(start 77.213206 -289.762184)
		(end 77.747114 -289.228276)
		(width 0.0889)
		(layer "In6.Cu")
		(net "M_E_CPU1_SB_DQ<23>")
	)
	(segment
		(start 47.724822 -309.11038)
		(end 48.06188 -309.11038)
		(width 0.14478)
		(layer "In6.Cu")
		(net "M_E_CPU1_SB_DQ<23>")
	)
	(segment
		(start 60.53963 -307.213762)
		(end 60.53963 -306.697126)
		(width 0.14478)
		(layer "In6.Cu")
		(net "M_E_CPU1_SB_DQ<23>")
	)
	(segment
		(start 51.609752 -308.260242)
		(end 52.358544 -308.260242)
		(width 0.14478)
		(layer "In6.Cu")
		(net "M_E_CPU1_SB_DQ<23>")
	)
	(segment
		(start 73.503536 -292.317678)
		(end 75.1586 -291.632132)
		(width 0.14478)
		(layer "In6.Cu")
		(net "M_E_CPU1_SB_DQ<23>")
	)
	(segment
		(start 44.593002 -308.260242)
		(end 46.766226 -308.919626)
		(width 0.14478)
		(layer "In6.Cu")
		(net "M_E_CPU1_SB_DQ<23>")
	)
	(segment
		(start 40.232838 -309.11038)
		(end 40.908732 -309.11038)
		(width 0.14478)
		(layer "In6.Cu")
		(net "M_E_CPU1_SB_DQ<23>")
	)
	(segment
		(start 77.957934 -288.419794)
		(end 78.241652 -288.419794)
		(width 0.0889)
		(layer "In6.Cu")
		(net "M_E_CPU1_SB_DQ<23>")
	)
	(segment
		(start 80.769714 -288.339022)
		(end 80.778096 -288.343848)
		(width 0.0889)
		(layer "In6.Cu")
		(net "M_E_CPU1_SB_DQ<23>")
	)
	(segment
		(start 57.321704 -308.798214)
		(end 57.873138 -308.569614)
		(width 0.14478)
		(layer "In6.Cu")
		(net "M_E_CPU1_SB_DQ<23>")
	)
	(segment
		(start 57.873138 -308.569614)
		(end 58.365898 -308.471824)
		(width 0.14478)
		(layer "In6.Cu")
		(net "M_E_CPU1_SB_DQ<23>")
	)
	(segment
		(start 58.365898 -308.471824)
		(end 59.929268 -307.824124)
		(width 0.14478)
		(layer "In6.Cu")
		(net "M_E_CPU1_SB_DQ<23>")
	)
	(segment
		(start 46.766226 -308.919626)
		(end 47.724822 -309.11038)
		(width 0.14478)
		(layer "In6.Cu")
		(net "M_E_CPU1_SB_DQ<23>")
	)
	(segment
		(start 44.300648 -308.260242)
		(end 44.593002 -308.260242)
		(width 0.14478)
		(layer "In6.Cu")
		(net "M_E_CPU1_SB_DQ<23>")
	)
	(segment
		(start 75.1586 -291.632132)
		(end 75.96505 -290.825682)
		(width 0.14478)
		(layer "In6.Cu")
		(net "M_E_CPU1_SB_DQ<23>")
	)
	(segment
		(start 53.32349 -308.452266)
		(end 54.136798 -308.78907)
		(width 0.14478)
		(layer "In6.Cu")
		(net "M_E_CPU1_SB_DQ<23>")
	)
	(segment
		(start 59.929268 -307.824124)
		(end 60.53963 -307.213762)
		(width 0.14478)
		(layer "In6.Cu")
		(net "M_E_CPU1_SB_DQ<23>")
	)
	(segment
		(start 54.597808 -308.880764)
		(end 56.906668 -308.880764)
		(width 0.14478)
		(layer "In6.Cu")
		(net "M_E_CPU1_SB_DQ<23>")
	)
	(segment
		(start 25.152096 -308.685438)
		(end 28.01493 -309.11038)
		(width 0.14478)
		(layer "In6.Cu")
		(net "M_E_CPU1_SB_DQ<23>")
	)
	(segment
		(start 79.454248 -288.349944)
		(end 79.464662 -288.343848)
		(width 0.0889)
		(layer "In6.Cu")
		(net "M_E_CPU1_SB_DQ<23>")
	)
	(segment
		(start 79.829914 -288.339022)
		(end 79.838296 -288.343848)
		(width 0.0889)
		(layer "In6.Cu")
		(net "M_E_CPU1_SB_DQ<23>")
	)
	(arc
		(start 78.898496 -288.343848)
		(mid 79.175563 -288.420119)
		(end 79.454248 -288.349944)
		(width 0.0889)
		(layer "In6.Cu")
		(net "M_E_CPU1_SB_DQ<23>")
	)
	(arc
		(start 81.35239 -288.339022)
		(mid 81.535898 -288.293497)
		(end 81.71815 -288.343848)
		(width 0.0889)
		(layer "In6.Cu")
		(net "M_E_CPU1_SB_DQ<23>")
	)
	(arc
		(start 79.84871 -288.349944)
		(mid 80.127142 -288.420042)
		(end 80.403954 -288.343848)
		(width 0.0889)
		(layer "In6.Cu")
		(net "M_E_CPU1_SB_DQ<23>")
	)
	(arc
		(start 82.284062 -288.343848)
		(mid 82.440499 -288.29481)
		(end 82.602832 -288.317686)
		(width 0.0889)
		(layer "In6.Cu")
		(net "M_E_CPU1_SB_DQ<23>")
	)
	(arc
		(start 78.538832 -288.335466)
		(mid 78.71974 -288.293415)
		(end 78.898496 -288.343848)
		(width 0.0889)
		(layer "In6.Cu")
		(net "M_E_CPU1_SB_DQ<23>")
	)
	(arc
		(start 80.778096 -288.343848)
		(mid 81.061052 -288.420025)
		(end 81.344008 -288.343848)
		(width 0.0889)
		(layer "In6.Cu")
		(net "M_E_CPU1_SB_DQ<23>")
	)
	(arc
		(start 79.464662 -288.343848)
		(mid 79.646659 -288.293592)
		(end 79.829914 -288.339022)
		(width 0.0889)
		(layer "In6.Cu")
		(net "M_E_CPU1_SB_DQ<23>")
	)
	(arc
		(start 80.403954 -288.343848)
		(mid 80.586205 -288.293464)
		(end 80.769714 -288.339022)
		(width 0.0889)
		(layer "In6.Cu")
		(net "M_E_CPU1_SB_DQ<23>")
	)
	(arc
		(start 78.241652 -288.419794)
		(mid 78.388027 -288.400515)
		(end 78.524354 -288.343848)
		(width 0.0889)
		(layer "In6.Cu")
		(net "M_E_CPU1_SB_DQ<23>")
	)
	(arc
		(start 81.71815 -288.343848)
		(mid 82.001106 -288.420025)
		(end 82.284062 -288.343848)
		(width 0.0889)
		(layer "In6.Cu")
		(net "M_E_CPU1_SB_DQ<23>")
	)
	(segment
		(start 81.527904 -287.590484)
		(end 81.061052 -287.856422)
		(width 0.10668)
		(layer "F.Cu")
		(net "M_E_CPU1_SB_DQ<22>")
	)
	(segment
		(start 77.878686 -287.616392)
		(end 78.711298 -287.610042)
		(width 0.0889)
		(layer "In6.Cu")
		(net "M_E_CPU1_SB_DQ<22>")
	)
	(segment
		(start 46.119288 -307.410358)
		(end 49.948592 -307.410358)
		(width 0.14478)
		(layer "In6.Cu")
		(net "M_E_CPU1_SB_DQ<22>")
	)
	(segment
		(start 59.134756 -305.698398)
		(end 60.61837 -305.083972)
		(width 0.14478)
		(layer "In6.Cu")
		(net "M_E_CPU1_SB_DQ<22>")
	)
	(segment
		(start 53.041042 -306.56022)
		(end 53.89118 -307.410358)
		(width 0.14478)
		(layer "In6.Cu")
		(net "M_E_CPU1_SB_DQ<22>")
	)
	(segment
		(start 63.49238 -301.056802)
		(end 73.095104 -291.454078)
		(width 0.14478)
		(layer "In6.Cu")
		(net "M_E_CPU1_SB_DQ<22>")
	)
	(segment
		(start 79.360014 -287.529016)
		(end 79.368396 -287.533842)
		(width 0.0889)
		(layer "In6.Cu")
		(net "M_E_CPU1_SB_DQ<22>")
	)
	(segment
		(start 34.683192 -307.410358)
		(end 35.53333 -306.56022)
		(width 0.14478)
		(layer "In6.Cu")
		(net "M_E_CPU1_SB_DQ<22>")
	)
	(segment
		(start 45.26915 -306.56022)
		(end 46.119288 -307.410358)
		(width 0.14478)
		(layer "In6.Cu")
		(net "M_E_CPU1_SB_DQ<22>")
	)
	(segment
		(start 75.956922 -289.547554)
		(end 76.481686 -289.02279)
		(width 0.0889)
		(layer "In6.Cu")
		(net "M_E_CPU1_SB_DQ<22>")
	)
	(segment
		(start 81.192624 -287.50768)
		(end 81.214976 -287.590992)
		(width 0.0889)
		(layer "In6.Cu")
		(net "M_E_CPU1_SB_DQ<22>")
	)
	(segment
		(start 42.557192 -307.410358)
		(end 43.40733 -306.56022)
		(width 0.14478)
		(layer "In6.Cu")
		(net "M_E_CPU1_SB_DQ<22>")
	)
	(segment
		(start 79.934054 -287.533842)
		(end 79.942436 -287.529016)
		(width 0.0889)
		(layer "In6.Cu")
		(net "M_E_CPU1_SB_DQ<22>")
	)
	(segment
		(start 37.80155 -306.56022)
		(end 38.651688 -307.410358)
		(width 0.14478)
		(layer "In6.Cu")
		(net "M_E_CPU1_SB_DQ<22>")
	)
	(segment
		(start 76.481686 -289.02279)
		(end 76.481686 -288.726118)
		(width 0.0889)
		(layer "In6.Cu")
		(net "M_E_CPU1_SB_DQ<22>")
	)
	(segment
		(start 60.61837 -305.083972)
		(end 62.676786 -303.025556)
		(width 0.14478)
		(layer "In6.Cu")
		(net "M_E_CPU1_SB_DQ<22>")
	)
	(segment
		(start 38.651688 -307.410358)
		(end 42.557192 -307.410358)
		(width 0.14478)
		(layer "In6.Cu")
		(net "M_E_CPU1_SB_DQ<22>")
	)
	(segment
		(start 57.422796 -307.410358)
		(end 59.134756 -305.698398)
		(width 0.14478)
		(layer "In6.Cu")
		(net "M_E_CPU1_SB_DQ<22>")
	)
	(segment
		(start 50.79873 -306.56022)
		(end 53.041042 -306.56022)
		(width 0.14478)
		(layer "In6.Cu")
		(net "M_E_CPU1_SB_DQ<22>")
	)
	(segment
		(start 25.152096 -306.985416)
		(end 25.577038 -307.410358)
		(width 0.14478)
		(layer "In6.Cu")
		(net "M_E_CPU1_SB_DQ<22>")
	)
	(segment
		(start 53.89118 -307.410358)
		(end 57.422796 -307.410358)
		(width 0.14478)
		(layer "In6.Cu")
		(net "M_E_CPU1_SB_DQ<22>")
	)
	(segment
		(start 79.92364 -287.539938)
		(end 79.934054 -287.533842)
		(width 0.0889)
		(layer "In6.Cu")
		(net "M_E_CPU1_SB_DQ<22>")
	)
	(segment
		(start 73.095104 -291.454078)
		(end 74.725784 -290.778692)
		(width 0.14478)
		(layer "In6.Cu")
		(net "M_E_CPU1_SB_DQ<22>")
	)
	(segment
		(start 49.948592 -307.410358)
		(end 50.79873 -306.56022)
		(width 0.14478)
		(layer "In6.Cu")
		(net "M_E_CPU1_SB_DQ<22>")
	)
	(segment
		(start 35.53333 -306.56022)
		(end 37.80155 -306.56022)
		(width 0.14478)
		(layer "In6.Cu")
		(net "M_E_CPU1_SB_DQ<22>")
	)
	(segment
		(start 25.577038 -307.410358)
		(end 34.683192 -307.410358)
		(width 0.14478)
		(layer "In6.Cu")
		(net "M_E_CPU1_SB_DQ<22>")
	)
	(segment
		(start 77.05344 -288.154364)
		(end 77.340714 -288.154364)
		(width 0.0889)
		(layer "In6.Cu")
		(net "M_E_CPU1_SB_DQ<22>")
	)
	(segment
		(start 76.481686 -288.726118)
		(end 77.05344 -288.154364)
		(width 0.0889)
		(layer "In6.Cu")
		(net "M_E_CPU1_SB_DQ<22>")
	)
	(segment
		(start 74.725784 -290.778692)
		(end 75.956922 -289.547554)
		(width 0.14478)
		(layer "In6.Cu")
		(net "M_E_CPU1_SB_DQ<22>")
	)
	(segment
		(start 77.340714 -288.154364)
		(end 77.878686 -287.616392)
		(width 0.0889)
		(layer "In6.Cu")
		(net "M_E_CPU1_SB_DQ<22>")
	)
	(segment
		(start 43.40733 -306.56022)
		(end 45.26915 -306.56022)
		(width 0.14478)
		(layer "In6.Cu")
		(net "M_E_CPU1_SB_DQ<22>")
	)
	(segment
		(start 81.214976 -287.590992)
		(end 81.061052 -287.856422)
		(width 0.0889)
		(layer "In6.Cu")
		(net "M_E_CPU1_SB_DQ<22>")
	)
	(segment
		(start 62.676786 -303.025556)
		(end 63.49238 -301.056802)
		(width 0.14478)
		(layer "In6.Cu")
		(net "M_E_CPU1_SB_DQ<22>")
	)
	(arc
		(start 79.368396 -287.533842)
		(mid 79.645209 -287.609951)
		(end 79.92364 -287.539938)
		(width 0.0889)
		(layer "In6.Cu")
		(net "M_E_CPU1_SB_DQ<22>")
	)
	(arc
		(start 78.994254 -287.533842)
		(mid 79.176505 -287.483492)
		(end 79.360014 -287.529016)
		(width 0.0889)
		(layer "In6.Cu")
		(net "M_E_CPU1_SB_DQ<22>")
	)
	(arc
		(start 79.942436 -287.529016)
		(mid 80.125944 -287.483522)
		(end 80.308196 -287.533842)
		(width 0.0889)
		(layer "In6.Cu")
		(net "M_E_CPU1_SB_DQ<22>")
	)
	(arc
		(start 80.308196 -287.533842)
		(mid 80.591152 -287.609985)
		(end 80.874108 -287.533842)
		(width 0.0889)
		(layer "In6.Cu")
		(net "M_E_CPU1_SB_DQ<22>")
	)
	(arc
		(start 80.874108 -287.533842)
		(mid 81.030427 -287.484847)
		(end 81.192624 -287.50768)
		(width 0.0889)
		(layer "In6.Cu")
		(net "M_E_CPU1_SB_DQ<22>")
	)
	(arc
		(start 78.711298 -287.610042)
		(mid 78.857824 -287.590672)
		(end 78.994254 -287.533842)
		(width 0.0889)
		(layer "In6.Cu")
		(net "M_E_CPU1_SB_DQ<22>")
	)
	(segment
		(start 83.408012 -287.590484)
		(end 82.940906 -287.856422)
		(width 0.10668)
		(layer "F.Cu")
		(net "M_E_CPU1_SB_DQ<21>")
	)
	(segment
		(start 31.792418 -308.260496)
		(end 34.544508 -308.260496)
		(width 0.14478)
		(layer "In6.Cu")
		(net "M_E_CPU1_SB_DQ<21>")
	)
	(segment
		(start 35.394646 -307.410358)
		(end 37.762434 -307.410358)
		(width 0.14478)
		(layer "In6.Cu")
		(net "M_E_CPU1_SB_DQ<21>")
	)
	(segment
		(start 30.8483 -307.865018)
		(end 31.011114 -308.027832)
		(width 0.14478)
		(layer "In6.Cu")
		(net "M_E_CPU1_SB_DQ<21>")
	)
	(segment
		(start 60.09005 -306.350416)
		(end 63.021464 -303.419002)
		(width 0.14478)
		(layer "In6.Cu")
		(net "M_E_CPU1_SB_DQ<21>")
	)
	(segment
		(start 74.943208 -291.204396)
		(end 75.957684 -290.18992)
		(width 0.14478)
		(layer "In6.Cu")
		(net "M_E_CPU1_SB_DQ<21>")
	)
	(segment
		(start 58.280046 -307.410358)
		(end 59.707018 -307.410358)
		(width 0.14478)
		(layer "In6.Cu")
		(net "M_E_CPU1_SB_DQ<21>")
	)
	(segment
		(start 30.454854 -308.027832)
		(end 30.617668 -307.865018)
		(width 0.14478)
		(layer "In6.Cu")
		(net "M_E_CPU1_SB_DQ<21>")
	)
	(segment
		(start 77.688186 -288.408364)
		(end 77.840332 -288.256218)
		(width 0.0889)
		(layer "In6.Cu")
		(net "M_E_CPU1_SB_DQ<21>")
	)
	(segment
		(start 54.081172 -308.260496)
		(end 57.429908 -308.260496)
		(width 0.14478)
		(layer "In6.Cu")
		(net "M_E_CPU1_SB_DQ<21>")
	)
	(segment
		(start 29.252164 -307.8353)
		(end 30.065218 -308.648354)
		(width 0.14478)
		(layer "In6.Cu")
		(net "M_E_CPU1_SB_DQ<21>")
	)
	(segment
		(start 45.458634 -307.410358)
		(end 46.308772 -308.260496)
		(width 0.14478)
		(layer "In6.Cu")
		(net "M_E_CPU1_SB_DQ<21>")
	)
	(segment
		(start 37.762434 -307.410358)
		(end 38.612572 -308.260496)
		(width 0.14478)
		(layer "In6.Cu")
		(net "M_E_CPU1_SB_DQ<21>")
	)
	(segment
		(start 53.231034 -307.410358)
		(end 54.081172 -308.260496)
		(width 0.14478)
		(layer "In6.Cu")
		(net "M_E_CPU1_SB_DQ<21>")
	)
	(segment
		(start 31.173928 -308.648354)
		(end 31.40456 -308.648354)
		(width 0.14478)
		(layer "In6.Cu")
		(net "M_E_CPU1_SB_DQ<21>")
	)
	(segment
		(start 30.065218 -308.648354)
		(end 30.29204 -308.648354)
		(width 0.14478)
		(layer "In6.Cu")
		(net "M_E_CPU1_SB_DQ<21>")
	)
	(segment
		(start 49.784508 -308.260496)
		(end 50.634646 -307.410358)
		(width 0.14478)
		(layer "In6.Cu")
		(net "M_E_CPU1_SB_DQ<21>")
	)
	(segment
		(start 77.920596 -288.222944)
		(end 78.203806 -288.222944)
		(width 0.0889)
		(layer "In6.Cu")
		(net "M_E_CPU1_SB_DQ<21>")
	)
	(segment
		(start 79.934308 -288.178748)
		(end 79.945992 -288.185606)
		(width 0.0889)
		(layer "In6.Cu")
		(net "M_E_CPU1_SB_DQ<21>")
	)
	(segment
		(start 59.707018 -307.410358)
		(end 60.09005 -307.027326)
		(width 0.14478)
		(layer "In6.Cu")
		(net "M_E_CPU1_SB_DQ<21>")
	)
	(segment
		(start 82.691224 -288.147252)
		(end 82.786982 -288.121852)
		(width 0.0889)
		(layer "In6.Cu")
		(net "M_E_CPU1_SB_DQ<21>")
	)
	(segment
		(start 82.786982 -288.121852)
		(end 82.940906 -287.856422)
		(width 0.0889)
		(layer "In6.Cu")
		(net "M_E_CPU1_SB_DQ<21>")
	)
	(segment
		(start 60.09005 -307.027326)
		(end 60.09005 -306.350416)
		(width 0.14478)
		(layer "In6.Cu")
		(net "M_E_CPU1_SB_DQ<21>")
	)
	(segment
		(start 42.367708 -308.260496)
		(end 43.217846 -307.410358)
		(width 0.14478)
		(layer "In6.Cu")
		(net "M_E_CPU1_SB_DQ<21>")
	)
	(segment
		(start 73.300082 -291.885116)
		(end 74.943208 -291.204396)
		(width 0.14478)
		(layer "In6.Cu")
		(net "M_E_CPU1_SB_DQ<21>")
	)
	(segment
		(start 79.923894 -288.172652)
		(end 79.934308 -288.178748)
		(width 0.0889)
		(layer "In6.Cu")
		(net "M_E_CPU1_SB_DQ<21>")
	)
	(segment
		(start 50.634646 -307.410358)
		(end 53.231034 -307.410358)
		(width 0.14478)
		(layer "In6.Cu")
		(net "M_E_CPU1_SB_DQ<21>")
	)
	(segment
		(start 34.544508 -308.260496)
		(end 35.394646 -307.410358)
		(width 0.14478)
		(layer "In6.Cu")
		(net "M_E_CPU1_SB_DQ<21>")
	)
	(segment
		(start 75.957684 -290.18992)
		(end 76.728066 -289.419538)
		(width 0.0889)
		(layer "In6.Cu")
		(net "M_E_CPU1_SB_DQ<21>")
	)
	(segment
		(start 31.40456 -308.648354)
		(end 31.792418 -308.260496)
		(width 0.14478)
		(layer "In6.Cu")
		(net "M_E_CPU1_SB_DQ<21>")
	)
	(segment
		(start 76.728066 -288.987484)
		(end 77.307186 -288.408364)
		(width 0.0889)
		(layer "In6.Cu")
		(net "M_E_CPU1_SB_DQ<21>")
	)
	(segment
		(start 30.454854 -308.48554)
		(end 30.454854 -308.027832)
		(width 0.14478)
		(layer "In6.Cu")
		(net "M_E_CPU1_SB_DQ<21>")
	)
	(segment
		(start 46.308772 -308.260496)
		(end 49.784508 -308.260496)
		(width 0.14478)
		(layer "In6.Cu")
		(net "M_E_CPU1_SB_DQ<21>")
	)
	(segment
		(start 30.617668 -307.865018)
		(end 30.8483 -307.865018)
		(width 0.14478)
		(layer "In6.Cu")
		(net "M_E_CPU1_SB_DQ<21>")
	)
	(segment
		(start 31.011114 -308.027832)
		(end 31.011114 -308.48554)
		(width 0.14478)
		(layer "In6.Cu")
		(net "M_E_CPU1_SB_DQ<21>")
	)
	(segment
		(start 38.612572 -308.260496)
		(end 42.367708 -308.260496)
		(width 0.14478)
		(layer "In6.Cu")
		(net "M_E_CPU1_SB_DQ<21>")
	)
	(segment
		(start 31.011114 -308.48554)
		(end 31.173928 -308.648354)
		(width 0.14478)
		(layer "In6.Cu")
		(net "M_E_CPU1_SB_DQ<21>")
	)
	(segment
		(start 79.356966 -288.185606)
		(end 79.36865 -288.178748)
		(width 0.0889)
		(layer "In6.Cu")
		(net "M_E_CPU1_SB_DQ<21>")
	)
	(segment
		(start 30.29204 -308.648354)
		(end 30.454854 -308.48554)
		(width 0.14478)
		(layer "In6.Cu")
		(net "M_E_CPU1_SB_DQ<21>")
	)
	(segment
		(start 82.179668 -288.183574)
		(end 82.18805 -288.178748)
		(width 0.0889)
		(layer "In6.Cu")
		(net "M_E_CPU1_SB_DQ<21>")
	)
	(segment
		(start 76.728066 -289.419538)
		(end 76.728066 -288.987484)
		(width 0.0889)
		(layer "In6.Cu")
		(net "M_E_CPU1_SB_DQ<21>")
	)
	(segment
		(start 43.217846 -307.410358)
		(end 45.458634 -307.410358)
		(width 0.14478)
		(layer "In6.Cu")
		(net "M_E_CPU1_SB_DQ<21>")
	)
	(segment
		(start 63.909194 -301.276004)
		(end 73.300082 -291.885116)
		(width 0.14478)
		(layer "In6.Cu")
		(net "M_E_CPU1_SB_DQ<21>")
	)
	(segment
		(start 57.429908 -308.260496)
		(end 58.280046 -307.410358)
		(width 0.14478)
		(layer "In6.Cu")
		(net "M_E_CPU1_SB_DQ<21>")
	)
	(segment
		(start 63.021464 -303.419002)
		(end 63.909194 -301.276004)
		(width 0.14478)
		(layer "In6.Cu")
		(net "M_E_CPU1_SB_DQ<21>")
	)
	(segment
		(start 77.307186 -288.408364)
		(end 77.688186 -288.408364)
		(width 0.0889)
		(layer "In6.Cu")
		(net "M_E_CPU1_SB_DQ<21>")
	)
	(arc
		(start 80.874108 -288.178748)
		(mid 81.061052 -288.229037)
		(end 81.247996 -288.178748)
		(width 0.0889)
		(layer "In6.Cu")
		(net "M_E_CPU1_SB_DQ<21>")
	)
	(arc
		(start 79.945992 -288.185606)
		(mid 80.127993 -288.229169)
		(end 80.308196 -288.178748)
		(width 0.0889)
		(layer "In6.Cu")
		(net "M_E_CPU1_SB_DQ<21>")
	)
	(arc
		(start 78.994254 -288.178748)
		(mid 79.174712 -288.229227)
		(end 79.356966 -288.185606)
		(width 0.0889)
		(layer "In6.Cu")
		(net "M_E_CPU1_SB_DQ<21>")
	)
	(arc
		(start 82.18805 -288.178748)
		(mid 82.43591 -288.103665)
		(end 82.691224 -288.147252)
		(width 0.0889)
		(layer "In6.Cu")
		(net "M_E_CPU1_SB_DQ<21>")
	)
	(arc
		(start 81.247996 -288.178748)
		(mid 81.530952 -288.102571)
		(end 81.813908 -288.178748)
		(width 0.0889)
		(layer "In6.Cu")
		(net "M_E_CPU1_SB_DQ<21>")
	)
	(arc
		(start 81.813908 -288.178748)
		(mid 81.996159 -288.229132)
		(end 82.179668 -288.183574)
		(width 0.0889)
		(layer "In6.Cu")
		(net "M_E_CPU1_SB_DQ<21>")
	)
	(arc
		(start 80.308196 -288.178748)
		(mid 80.591152 -288.102571)
		(end 80.874108 -288.178748)
		(width 0.0889)
		(layer "In6.Cu")
		(net "M_E_CPU1_SB_DQ<21>")
	)
	(arc
		(start 78.457298 -288.162492)
		(mid 78.727838 -288.102531)
		(end 78.994254 -288.178748)
		(width 0.0889)
		(layer "In6.Cu")
		(net "M_E_CPU1_SB_DQ<21>")
	)
	(arc
		(start 77.840332 -288.256218)
		(mid 77.877143 -288.231558)
		(end 77.920596 -288.222944)
		(width 0.0889)
		(layer "In6.Cu")
		(net "M_E_CPU1_SB_DQ<21>")
	)
	(arc
		(start 79.36865 -288.178748)
		(mid 79.645463 -288.102605)
		(end 79.923894 -288.172652)
		(width 0.0889)
		(layer "In6.Cu")
		(net "M_E_CPU1_SB_DQ<21>")
	)
	(arc
		(start 78.203806 -288.222944)
		(mid 78.33409 -288.207559)
		(end 78.457298 -288.162492)
		(width 0.0889)
		(layer "In6.Cu")
		(net "M_E_CPU1_SB_DQ<21>")
	)
	(segment
		(start 81.997804 -286.780478)
		(end 81.530952 -287.046162)
		(width 0.10668)
		(layer "F.Cu")
		(net "M_E_CPU1_SB_DQ<20>")
	)
	(segment
		(start 33.204404 -306.874164)
		(end 32.900366 -306.570126)
		(width 0.14478)
		(layer "In6.Cu")
		(net "M_E_CPU1_SB_DQ<20>")
	)
	(segment
		(start 49.248314 -306.560474)
		(end 49.005744 -306.560474)
		(width 0.14478)
		(layer "In6.Cu")
		(net "M_E_CPU1_SB_DQ<20>")
	)
	(segment
		(start 76.910184 -287.951164)
		(end 75.986386 -288.874962)
		(width 0.0889)
		(layer "In6.Cu")
		(net "M_E_CPU1_SB_DQ<20>")
	)
	(segment
		(start 48.145446 -306.570126)
		(end 46.773338 -306.570126)
		(width 0.14478)
		(layer "In6.Cu")
		(net "M_E_CPU1_SB_DQ<20>")
	)
	(segment
		(start 31.359602 -306.899564)
		(end 31.12897 -306.899564)
		(width 0.14478)
		(layer "In6.Cu")
		(net "M_E_CPU1_SB_DQ<20>")
	)
	(segment
		(start 30.409896 -306.73675)
		(end 30.247082 -306.899564)
		(width 0.14478)
		(layer "In6.Cu")
		(net "M_E_CPU1_SB_DQ<20>")
	)
	(segment
		(start 41.320974 -306.874164)
		(end 41.078404 -306.874164)
		(width 0.14478)
		(layer "In6.Cu")
		(net "M_E_CPU1_SB_DQ<20>")
	)
	(segment
		(start 30.409896 -306.384198)
		(end 30.409896 -306.73675)
		(width 0.14478)
		(layer "In6.Cu")
		(net "M_E_CPU1_SB_DQ<20>")
	)
	(segment
		(start 48.692054 -306.874164)
		(end 48.449484 -306.874164)
		(width 0.14478)
		(layer "In6.Cu")
		(net "M_E_CPU1_SB_DQ<20>")
	)
	(segment
		(start 37.451538 -305.719988)
		(end 35.71367 -305.719988)
		(width 0.14478)
		(layer "In6.Cu")
		(net "M_E_CPU1_SB_DQ<20>")
	)
	(segment
		(start 38.86073 -306.823364)
		(end 37.973508 -305.936142)
		(width 0.14478)
		(layer "In6.Cu")
		(net "M_E_CPU1_SB_DQ<20>")
	)
	(segment
		(start 50.95875 -305.719988)
		(end 49.804574 -306.874164)
		(width 0.14478)
		(layer "In6.Cu")
		(net "M_E_CPU1_SB_DQ<20>")
	)
	(segment
		(start 34.003234 -306.560474)
		(end 33.760664 -306.560474)
		(width 0.14478)
		(layer "In6.Cu")
		(net "M_E_CPU1_SB_DQ<20>")
	)
	(segment
		(start 77.794358 -287.413192)
		(end 77.256386 -287.951164)
		(width 0.0889)
		(layer "In6.Cu")
		(net "M_E_CPU1_SB_DQ<20>")
	)
	(segment
		(start 53.009038 -305.867816)
		(end 52.652168 -305.719988)
		(width 0.14478)
		(layer "In6.Cu")
		(net "M_E_CPU1_SB_DQ<20>")
	)
	(segment
		(start 31.68904 -306.570126)
		(end 31.359602 -306.899564)
		(width 0.14478)
		(layer "In6.Cu")
		(net "M_E_CPU1_SB_DQ<20>")
	)
	(segment
		(start 52.652168 -305.719988)
		(end 50.95875 -305.719988)
		(width 0.14478)
		(layer "In6.Cu")
		(net "M_E_CPU1_SB_DQ<20>")
	)
	(segment
		(start 46.4947 -306.848764)
		(end 46.22673 -306.848764)
		(width 0.14478)
		(layer "In6.Cu")
		(net "M_E_CPU1_SB_DQ<20>")
	)
	(segment
		(start 79.464408 -287.368742)
		(end 79.453994 -287.362646)
		(width 0.0889)
		(layer "In6.Cu")
		(net "M_E_CPU1_SB_DQ<20>")
	)
	(segment
		(start 31.12897 -306.899564)
		(end 30.966156 -306.73675)
		(width 0.14478)
		(layer "In6.Cu")
		(net "M_E_CPU1_SB_DQ<20>")
	)
	(segment
		(start 46.22673 -306.848764)
		(end 45.097954 -305.719988)
		(width 0.14478)
		(layer "In6.Cu")
		(net "M_E_CPU1_SB_DQ<20>")
	)
	(segment
		(start 56.768746 -306.560474)
		(end 56.480456 -306.848764)
		(width 0.14478)
		(layer "In6.Cu")
		(net "M_E_CPU1_SB_DQ<20>")
	)
	(segment
		(start 81.377028 -287.311592)
		(end 81.281016 -287.336992)
		(width 0.0889)
		(layer "In6.Cu")
		(net "M_E_CPU1_SB_DQ<20>")
	)
	(segment
		(start 40.774366 -306.570126)
		(end 39.407338 -306.570126)
		(width 0.14478)
		(layer "In6.Cu")
		(net "M_E_CPU1_SB_DQ<20>")
	)
	(segment
		(start 30.803342 -306.221384)
		(end 30.57271 -306.221384)
		(width 0.14478)
		(layer "In6.Cu")
		(net "M_E_CPU1_SB_DQ<20>")
	)
	(segment
		(start 60.363608 -304.702718)
		(end 58.879994 -305.317144)
		(width 0.14478)
		(layer "In6.Cu")
		(net "M_E_CPU1_SB_DQ<20>")
	)
	(segment
		(start 55.616602 -306.311046)
		(end 55.471822 -306.166266)
		(width 0.14478)
		(layer "In6.Cu")
		(net "M_E_CPU1_SB_DQ<20>")
	)
	(segment
		(start 49.804574 -306.874164)
		(end 49.562004 -306.874164)
		(width 0.14478)
		(layer "In6.Cu")
		(net "M_E_CPU1_SB_DQ<20>")
	)
	(segment
		(start 62.246764 -302.819562)
		(end 60.363608 -304.702718)
		(width 0.14478)
		(layer "In6.Cu")
		(net "M_E_CPU1_SB_DQ<20>")
	)
	(segment
		(start 54.806342 -306.848764)
		(end 53.989986 -306.848764)
		(width 0.14478)
		(layer "In6.Cu")
		(net "M_E_CPU1_SB_DQ<20>")
	)
	(segment
		(start 45.097954 -305.719988)
		(end 43.58767 -305.719988)
		(width 0.14478)
		(layer "In6.Cu")
		(net "M_E_CPU1_SB_DQ<20>")
	)
	(segment
		(start 34.559494 -306.874164)
		(end 34.316924 -306.874164)
		(width 0.14478)
		(layer "In6.Cu")
		(net "M_E_CPU1_SB_DQ<20>")
	)
	(segment
		(start 42.433494 -306.874164)
		(end 42.190924 -306.874164)
		(width 0.14478)
		(layer "In6.Cu")
		(net "M_E_CPU1_SB_DQ<20>")
	)
	(segment
		(start 49.562004 -306.874164)
		(end 49.248314 -306.560474)
		(width 0.14478)
		(layer "In6.Cu")
		(net "M_E_CPU1_SB_DQ<20>")
	)
	(segment
		(start 46.773338 -306.570126)
		(end 46.4947 -306.848764)
		(width 0.14478)
		(layer "In6.Cu")
		(net "M_E_CPU1_SB_DQ<20>")
	)
	(segment
		(start 74.459084 -290.402264)
		(end 72.840342 -291.072824)
		(width 0.14478)
		(layer "In6.Cu")
		(net "M_E_CPU1_SB_DQ<20>")
	)
	(segment
		(start 53.989986 -306.848764)
		(end 53.009038 -305.867816)
		(width 0.14478)
		(layer "In6.Cu")
		(net "M_E_CPU1_SB_DQ<20>")
	)
	(segment
		(start 81.530952 -287.046162)
		(end 81.377028 -287.311592)
		(width 0.0889)
		(layer "In6.Cu")
		(net "M_E_CPU1_SB_DQ<20>")
	)
	(segment
		(start 30.247082 -306.899564)
		(end 30.01645 -306.899564)
		(width 0.14478)
		(layer "In6.Cu")
		(net "M_E_CPU1_SB_DQ<20>")
	)
	(segment
		(start 55.761382 -306.848764)
		(end 55.616602 -306.703984)
		(width 0.14478)
		(layer "In6.Cu")
		(net "M_E_CPU1_SB_DQ<20>")
	)
	(segment
		(start 79.84871 -287.362646)
		(end 79.838296 -287.368742)
		(width 0.0889)
		(layer "In6.Cu")
		(net "M_E_CPU1_SB_DQ<20>")
	)
	(segment
		(start 43.58767 -305.719988)
		(end 42.433494 -306.874164)
		(width 0.14478)
		(layer "In6.Cu")
		(net "M_E_CPU1_SB_DQ<20>")
	)
	(segment
		(start 54.951122 -306.703984)
		(end 54.806342 -306.848764)
		(width 0.14478)
		(layer "In6.Cu")
		(net "M_E_CPU1_SB_DQ<20>")
	)
	(segment
		(start 77.256386 -287.951164)
		(end 76.910184 -287.951164)
		(width 0.0889)
		(layer "In6.Cu")
		(net "M_E_CPU1_SB_DQ<20>")
	)
	(segment
		(start 55.616602 -306.703984)
		(end 55.616602 -306.311046)
		(width 0.14478)
		(layer "In6.Cu")
		(net "M_E_CPU1_SB_DQ<20>")
	)
	(segment
		(start 41.078404 -306.874164)
		(end 40.774366 -306.570126)
		(width 0.14478)
		(layer "In6.Cu")
		(net "M_E_CPU1_SB_DQ<20>")
	)
	(segment
		(start 41.634664 -306.560474)
		(end 41.320974 -306.874164)
		(width 0.14478)
		(layer "In6.Cu")
		(net "M_E_CPU1_SB_DQ<20>")
	)
	(segment
		(start 39.407338 -306.570126)
		(end 39.1541 -306.823364)
		(width 0.14478)
		(layer "In6.Cu")
		(net "M_E_CPU1_SB_DQ<20>")
	)
	(segment
		(start 72.840342 -291.072824)
		(end 63.062358 -300.850808)
		(width 0.14478)
		(layer "In6.Cu")
		(net "M_E_CPU1_SB_DQ<20>")
	)
	(segment
		(start 34.316924 -306.874164)
		(end 34.003234 -306.560474)
		(width 0.14478)
		(layer "In6.Cu")
		(net "M_E_CPU1_SB_DQ<20>")
	)
	(segment
		(start 56.480456 -306.848764)
		(end 55.761382 -306.848764)
		(width 0.14478)
		(layer "In6.Cu")
		(net "M_E_CPU1_SB_DQ<20>")
	)
	(segment
		(start 48.449484 -306.874164)
		(end 48.145446 -306.570126)
		(width 0.14478)
		(layer "In6.Cu")
		(net "M_E_CPU1_SB_DQ<20>")
	)
	(segment
		(start 33.446974 -306.874164)
		(end 33.204404 -306.874164)
		(width 0.14478)
		(layer "In6.Cu")
		(net "M_E_CPU1_SB_DQ<20>")
	)
	(segment
		(start 54.951122 -306.311046)
		(end 54.951122 -306.703984)
		(width 0.14478)
		(layer "In6.Cu")
		(net "M_E_CPU1_SB_DQ<20>")
	)
	(segment
		(start 42.190924 -306.874164)
		(end 41.877234 -306.560474)
		(width 0.14478)
		(layer "In6.Cu")
		(net "M_E_CPU1_SB_DQ<20>")
	)
	(segment
		(start 39.1541 -306.823364)
		(end 38.86073 -306.823364)
		(width 0.14478)
		(layer "In6.Cu")
		(net "M_E_CPU1_SB_DQ<20>")
	)
	(segment
		(start 80.778096 -287.368742)
		(end 80.769714 -287.373568)
		(width 0.0889)
		(layer "In6.Cu")
		(net "M_E_CPU1_SB_DQ<20>")
	)
	(segment
		(start 78.711044 -287.419034)
		(end 77.794358 -287.413192)
		(width 0.0889)
		(layer "In6.Cu")
		(net "M_E_CPU1_SB_DQ<20>")
	)
	(segment
		(start 35.71367 -305.719988)
		(end 34.559494 -306.874164)
		(width 0.14478)
		(layer "In6.Cu")
		(net "M_E_CPU1_SB_DQ<20>")
	)
	(segment
		(start 57.636664 -306.560474)
		(end 56.768746 -306.560474)
		(width 0.14478)
		(layer "In6.Cu")
		(net "M_E_CPU1_SB_DQ<20>")
	)
	(segment
		(start 63.062358 -300.850808)
		(end 62.246764 -302.819562)
		(width 0.14478)
		(layer "In6.Cu")
		(net "M_E_CPU1_SB_DQ<20>")
	)
	(segment
		(start 55.471822 -306.166266)
		(end 55.095902 -306.166266)
		(width 0.14478)
		(layer "In6.Cu")
		(net "M_E_CPU1_SB_DQ<20>")
	)
	(segment
		(start 75.986386 -288.874962)
		(end 74.459084 -290.402264)
		(width 0.14478)
		(layer "In6.Cu")
		(net "M_E_CPU1_SB_DQ<20>")
	)
	(segment
		(start 58.879994 -305.317144)
		(end 57.636664 -306.560474)
		(width 0.14478)
		(layer "In6.Cu")
		(net "M_E_CPU1_SB_DQ<20>")
	)
	(segment
		(start 30.57271 -306.221384)
		(end 30.409896 -306.384198)
		(width 0.14478)
		(layer "In6.Cu")
		(net "M_E_CPU1_SB_DQ<20>")
	)
	(segment
		(start 55.095902 -306.166266)
		(end 54.951122 -306.311046)
		(width 0.14478)
		(layer "In6.Cu")
		(net "M_E_CPU1_SB_DQ<20>")
	)
	(segment
		(start 49.005744 -306.560474)
		(end 48.692054 -306.874164)
		(width 0.14478)
		(layer "In6.Cu")
		(net "M_E_CPU1_SB_DQ<20>")
	)
	(segment
		(start 41.877234 -306.560474)
		(end 41.634664 -306.560474)
		(width 0.14478)
		(layer "In6.Cu")
		(net "M_E_CPU1_SB_DQ<20>")
	)
	(segment
		(start 33.760664 -306.560474)
		(end 33.446974 -306.874164)
		(width 0.14478)
		(layer "In6.Cu")
		(net "M_E_CPU1_SB_DQ<20>")
	)
	(segment
		(start 37.973508 -305.936142)
		(end 37.451538 -305.719988)
		(width 0.14478)
		(layer "In6.Cu")
		(net "M_E_CPU1_SB_DQ<20>")
	)
	(segment
		(start 32.900366 -306.570126)
		(end 31.68904 -306.570126)
		(width 0.14478)
		(layer "In6.Cu")
		(net "M_E_CPU1_SB_DQ<20>")
	)
	(segment
		(start 30.01645 -306.899564)
		(end 29.252164 -306.135278)
		(width 0.14478)
		(layer "In6.Cu")
		(net "M_E_CPU1_SB_DQ<20>")
	)
	(segment
		(start 30.966156 -306.73675)
		(end 30.966156 -306.384198)
		(width 0.14478)
		(layer "In6.Cu")
		(net "M_E_CPU1_SB_DQ<20>")
	)
	(segment
		(start 30.966156 -306.384198)
		(end 30.803342 -306.221384)
		(width 0.14478)
		(layer "In6.Cu")
		(net "M_E_CPU1_SB_DQ<20>")
	)
	(arc
		(start 80.769714 -287.373568)
		(mid 80.586206 -287.419062)
		(end 80.403954 -287.368742)
		(width 0.0889)
		(layer "In6.Cu")
		(net "M_E_CPU1_SB_DQ<20>")
	)
	(arc
		(start 80.403954 -287.368742)
		(mid 80.127141 -287.292633)
		(end 79.84871 -287.362646)
		(width 0.0889)
		(layer "In6.Cu")
		(net "M_E_CPU1_SB_DQ<20>")
	)
	(arc
		(start 81.281016 -287.336992)
		(mid 81.025808 -287.293535)
		(end 80.778096 -287.368742)
		(width 0.0889)
		(layer "In6.Cu")
		(net "M_E_CPU1_SB_DQ<20>")
	)
	(arc
		(start 79.453994 -287.362646)
		(mid 79.175308 -287.292457)
		(end 78.898242 -287.368742)
		(width 0.0889)
		(layer "In6.Cu")
		(net "M_E_CPU1_SB_DQ<20>")
	)
	(arc
		(start 79.838296 -287.368742)
		(mid 79.651352 -287.418997)
		(end 79.464408 -287.368742)
		(width 0.0889)
		(layer "In6.Cu")
		(net "M_E_CPU1_SB_DQ<20>")
	)
	(arc
		(start 78.898242 -287.368742)
		(mid 78.807966 -287.406247)
		(end 78.711044 -287.419034)
		(width 0.0889)
		(layer "In6.Cu")
		(net "M_E_CPU1_SB_DQ<20>")
	)
	(segment
		(start 83.408012 -274.630388)
		(end 82.940906 -274.896326)
		(width 0.10668)
		(layer "F.Cu")
		(net "M_E_CPU1_SB_DQ<1>")
	)
	(segment
		(start 43.701716 -283.074364)
		(end 44.015914 -282.760166)
		(width 0.14478)
		(layer "In6.Cu")
		(net "M_E_CPU1_SB_DQ<1>")
	)
	(segment
		(start 29.252164 -283.185362)
		(end 30.055566 -283.988764)
		(width 0.14478)
		(layer "In6.Cu")
		(net "M_E_CPU1_SB_DQ<1>")
	)
	(segment
		(start 57.666128 -282.760166)
		(end 57.980326 -283.074364)
		(width 0.14478)
		(layer "In6.Cu")
		(net "M_E_CPU1_SB_DQ<1>")
	)
	(segment
		(start 76.331826 -274.031964)
		(end 77.383386 -274.031964)
		(width 0.0889)
		(layer "In6.Cu")
		(net "M_E_CPU1_SB_DQ<1>")
	)
	(segment
		(start 43.145456 -282.760166)
		(end 43.459654 -283.074364)
		(width 0.14478)
		(layer "In6.Cu")
		(net "M_E_CPU1_SB_DQ<1>")
	)
	(segment
		(start 62.249558 -279.519888)
		(end 62.249558 -279.167336)
		(width 0.14478)
		(layer "In6.Cu")
		(net "M_E_CPU1_SB_DQ<1>")
	)
	(segment
		(start 43.459654 -283.074364)
		(end 43.701716 -283.074364)
		(width 0.14478)
		(layer "In6.Cu")
		(net "M_E_CPU1_SB_DQ<1>")
	)
	(segment
		(start 61.19622 -281.425396)
		(end 61.19622 -280.573226)
		(width 0.14478)
		(layer "In6.Cu")
		(net "M_E_CPU1_SB_DQ<1>")
	)
	(segment
		(start 53.066442 -282.760166)
		(end 54.21884 -283.912564)
		(width 0.14478)
		(layer "In6.Cu")
		(net "M_E_CPU1_SB_DQ<1>")
	)
	(segment
		(start 79.869792 -275.181568)
		(end 79.9338 -275.218906)
		(width 0.0889)
		(layer "In6.Cu")
		(net "M_E_CPU1_SB_DQ<1>")
	)
	(segment
		(start 31.0769 -283.82595)
		(end 31.239714 -283.988764)
		(width 0.14478)
		(layer "In6.Cu")
		(net "M_E_CPU1_SB_DQ<1>")
	)
	(segment
		(start 31.63316 -283.82595)
		(end 31.63316 -283.394658)
		(width 0.14478)
		(layer "In6.Cu")
		(net "M_E_CPU1_SB_DQ<1>")
	)
	(segment
		(start 49.067212 -283.610304)
		(end 49.91735 -282.760166)
		(width 0.14478)
		(layer "In6.Cu")
		(net "M_E_CPU1_SB_DQ<1>")
	)
	(segment
		(start 31.470346 -283.988764)
		(end 31.63316 -283.82595)
		(width 0.14478)
		(layer "In6.Cu")
		(net "M_E_CPU1_SB_DQ<1>")
	)
	(segment
		(start 58.222388 -283.074364)
		(end 58.536586 -282.760166)
		(width 0.14478)
		(layer "In6.Cu")
		(net "M_E_CPU1_SB_DQ<1>")
	)
	(segment
		(start 65.06337 -276.353524)
		(end 65.58788 -275.087334)
		(width 0.14478)
		(layer "In6.Cu")
		(net "M_E_CPU1_SB_DQ<1>")
	)
	(segment
		(start 76.234036 -274.129754)
		(end 76.331826 -274.031964)
		(width 0.0889)
		(layer "In6.Cu")
		(net "M_E_CPU1_SB_DQ<1>")
	)
	(segment
		(start 57.980326 -283.074364)
		(end 58.222388 -283.074364)
		(width 0.14478)
		(layer "In6.Cu")
		(net "M_E_CPU1_SB_DQ<1>")
	)
	(segment
		(start 37.953442 -282.760166)
		(end 39.10584 -283.912564)
		(width 0.14478)
		(layer "In6.Cu")
		(net "M_E_CPU1_SB_DQ<1>")
	)
	(segment
		(start 31.63316 -283.394658)
		(end 31.795974 -283.231844)
		(width 0.14478)
		(layer "In6.Cu")
		(net "M_E_CPU1_SB_DQ<1>")
	)
	(segment
		(start 57.300622 -282.760166)
		(end 57.666128 -282.760166)
		(width 0.14478)
		(layer "In6.Cu")
		(net "M_E_CPU1_SB_DQ<1>")
	)
	(segment
		(start 59.86145 -282.760166)
		(end 61.19622 -281.425396)
		(width 0.14478)
		(layer "In6.Cu")
		(net "M_E_CPU1_SB_DQ<1>")
	)
	(segment
		(start 58.778648 -282.760166)
		(end 59.092846 -283.074364)
		(width 0.14478)
		(layer "In6.Cu")
		(net "M_E_CPU1_SB_DQ<1>")
	)
	(segment
		(start 47.422816 -283.610304)
		(end 49.067212 -283.610304)
		(width 0.14478)
		(layer "In6.Cu")
		(net "M_E_CPU1_SB_DQ<1>")
	)
	(segment
		(start 46.72584 -283.912564)
		(end 47.120556 -283.912564)
		(width 0.14478)
		(layer "In6.Cu")
		(net "M_E_CPU1_SB_DQ<1>")
	)
	(segment
		(start 59.334908 -283.074364)
		(end 59.649106 -282.760166)
		(width 0.14478)
		(layer "In6.Cu")
		(net "M_E_CPU1_SB_DQ<1>")
	)
	(segment
		(start 30.055566 -283.988764)
		(end 30.357826 -283.988764)
		(width 0.14478)
		(layer "In6.Cu")
		(net "M_E_CPU1_SB_DQ<1>")
	)
	(segment
		(start 30.683454 -283.231844)
		(end 30.914086 -283.231844)
		(width 0.14478)
		(layer "In6.Cu")
		(net "M_E_CPU1_SB_DQ<1>")
	)
	(segment
		(start 51.136042 -283.074364)
		(end 51.45024 -282.760166)
		(width 0.14478)
		(layer "In6.Cu")
		(net "M_E_CPU1_SB_DQ<1>")
	)
	(segment
		(start 47.120556 -283.912564)
		(end 47.422816 -283.610304)
		(width 0.14478)
		(layer "In6.Cu")
		(net "M_E_CPU1_SB_DQ<1>")
	)
	(segment
		(start 50.89398 -283.074364)
		(end 51.136042 -283.074364)
		(width 0.14478)
		(layer "In6.Cu")
		(net "M_E_CPU1_SB_DQ<1>")
	)
	(segment
		(start 30.52064 -283.394658)
		(end 30.683454 -283.231844)
		(width 0.14478)
		(layer "In6.Cu")
		(net "M_E_CPU1_SB_DQ<1>")
	)
	(segment
		(start 30.357826 -283.988764)
		(end 30.52064 -283.82595)
		(width 0.14478)
		(layer "In6.Cu")
		(net "M_E_CPU1_SB_DQ<1>")
	)
	(segment
		(start 77.383386 -274.031964)
		(end 78.436978 -275.085556)
		(width 0.0889)
		(layer "In6.Cu")
		(net "M_E_CPU1_SB_DQ<1>")
	)
	(segment
		(start 54.681882 -283.912564)
		(end 54.984142 -283.610304)
		(width 0.14478)
		(layer "In6.Cu")
		(net "M_E_CPU1_SB_DQ<1>")
	)
	(segment
		(start 51.45024 -282.760166)
		(end 53.066442 -282.760166)
		(width 0.14478)
		(layer "In6.Cu")
		(net "M_E_CPU1_SB_DQ<1>")
	)
	(segment
		(start 66.54546 -274.129754)
		(end 76.234036 -274.129754)
		(width 0.14478)
		(layer "In6.Cu")
		(net "M_E_CPU1_SB_DQ<1>")
	)
	(segment
		(start 32.026606 -283.231844)
		(end 32.405066 -283.610304)
		(width 0.14478)
		(layer "In6.Cu")
		(net "M_E_CPU1_SB_DQ<1>")
	)
	(segment
		(start 61.19622 -280.573226)
		(end 62.249558 -279.519888)
		(width 0.14478)
		(layer "In6.Cu")
		(net "M_E_CPU1_SB_DQ<1>")
	)
	(segment
		(start 42.823638 -282.760166)
		(end 43.145456 -282.760166)
		(width 0.14478)
		(layer "In6.Cu")
		(net "M_E_CPU1_SB_DQ<1>")
	)
	(segment
		(start 39.862506 -283.610304)
		(end 41.9735 -283.610304)
		(width 0.14478)
		(layer "In6.Cu")
		(net "M_E_CPU1_SB_DQ<1>")
	)
	(segment
		(start 82.786982 -275.161756)
		(end 82.940906 -274.896326)
		(width 0.0889)
		(layer "In6.Cu")
		(net "M_E_CPU1_SB_DQ<1>")
	)
	(segment
		(start 82.69097 -275.187156)
		(end 82.786982 -275.161756)
		(width 0.0889)
		(layer "In6.Cu")
		(net "M_E_CPU1_SB_DQ<1>")
	)
	(segment
		(start 56.148224 -283.912564)
		(end 57.300622 -282.760166)
		(width 0.14478)
		(layer "In6.Cu")
		(net "M_E_CPU1_SB_DQ<1>")
	)
	(segment
		(start 50.579782 -282.760166)
		(end 50.89398 -283.074364)
		(width 0.14478)
		(layer "In6.Cu")
		(net "M_E_CPU1_SB_DQ<1>")
	)
	(segment
		(start 45.573442 -282.760166)
		(end 46.72584 -283.912564)
		(width 0.14478)
		(layer "In6.Cu")
		(net "M_E_CPU1_SB_DQ<1>")
	)
	(segment
		(start 30.52064 -283.82595)
		(end 30.52064 -283.394658)
		(width 0.14478)
		(layer "In6.Cu")
		(net "M_E_CPU1_SB_DQ<1>")
	)
	(segment
		(start 32.405066 -283.610304)
		(end 34.2265 -283.610304)
		(width 0.14478)
		(layer "In6.Cu")
		(net "M_E_CPU1_SB_DQ<1>")
	)
	(segment
		(start 31.239714 -283.988764)
		(end 31.470346 -283.988764)
		(width 0.14478)
		(layer "In6.Cu")
		(net "M_E_CPU1_SB_DQ<1>")
	)
	(segment
		(start 41.9735 -283.610304)
		(end 42.823638 -282.760166)
		(width 0.14478)
		(layer "In6.Cu")
		(net "M_E_CPU1_SB_DQ<1>")
	)
	(segment
		(start 34.2265 -283.610304)
		(end 35.076638 -282.760166)
		(width 0.14478)
		(layer "In6.Cu")
		(net "M_E_CPU1_SB_DQ<1>")
	)
	(segment
		(start 54.21884 -283.912564)
		(end 54.681882 -283.912564)
		(width 0.14478)
		(layer "In6.Cu")
		(net "M_E_CPU1_SB_DQ<1>")
	)
	(segment
		(start 31.795974 -283.231844)
		(end 32.026606 -283.231844)
		(width 0.14478)
		(layer "In6.Cu")
		(net "M_E_CPU1_SB_DQ<1>")
	)
	(segment
		(start 39.560246 -283.912564)
		(end 39.862506 -283.610304)
		(width 0.14478)
		(layer "In6.Cu")
		(net "M_E_CPU1_SB_DQ<1>")
	)
	(segment
		(start 55.238142 -283.610304)
		(end 55.540402 -283.912564)
		(width 0.14478)
		(layer "In6.Cu")
		(net "M_E_CPU1_SB_DQ<1>")
	)
	(segment
		(start 39.10584 -283.912564)
		(end 39.560246 -283.912564)
		(width 0.14478)
		(layer "In6.Cu")
		(net "M_E_CPU1_SB_DQ<1>")
	)
	(segment
		(start 58.536586 -282.760166)
		(end 58.778648 -282.760166)
		(width 0.14478)
		(layer "In6.Cu")
		(net "M_E_CPU1_SB_DQ<1>")
	)
	(segment
		(start 82.179668 -275.223732)
		(end 82.18805 -275.218906)
		(width 0.0889)
		(layer "In6.Cu")
		(net "M_E_CPU1_SB_DQ<1>")
	)
	(segment
		(start 55.540402 -283.912564)
		(end 56.148224 -283.912564)
		(width 0.14478)
		(layer "In6.Cu")
		(net "M_E_CPU1_SB_DQ<1>")
	)
	(segment
		(start 65.58788 -275.087334)
		(end 66.54546 -274.129754)
		(width 0.14478)
		(layer "In6.Cu")
		(net "M_E_CPU1_SB_DQ<1>")
	)
	(segment
		(start 59.649106 -282.760166)
		(end 59.86145 -282.760166)
		(width 0.14478)
		(layer "In6.Cu")
		(net "M_E_CPU1_SB_DQ<1>")
	)
	(segment
		(start 44.015914 -282.760166)
		(end 45.573442 -282.760166)
		(width 0.14478)
		(layer "In6.Cu")
		(net "M_E_CPU1_SB_DQ<1>")
	)
	(segment
		(start 31.0769 -283.394658)
		(end 31.0769 -283.82595)
		(width 0.14478)
		(layer "In6.Cu")
		(net "M_E_CPU1_SB_DQ<1>")
	)
	(segment
		(start 78.436978 -275.085556)
		(end 79.618586 -275.085556)
		(width 0.0889)
		(layer "In6.Cu")
		(net "M_E_CPU1_SB_DQ<1>")
	)
	(segment
		(start 49.91735 -282.760166)
		(end 50.579782 -282.760166)
		(width 0.14478)
		(layer "In6.Cu")
		(net "M_E_CPU1_SB_DQ<1>")
	)
	(segment
		(start 35.076638 -282.760166)
		(end 37.953442 -282.760166)
		(width 0.14478)
		(layer "In6.Cu")
		(net "M_E_CPU1_SB_DQ<1>")
	)
	(segment
		(start 54.984142 -283.610304)
		(end 55.238142 -283.610304)
		(width 0.14478)
		(layer "In6.Cu")
		(net "M_E_CPU1_SB_DQ<1>")
	)
	(segment
		(start 62.249558 -279.167336)
		(end 65.06337 -276.353524)
		(width 0.14478)
		(layer "In6.Cu")
		(net "M_E_CPU1_SB_DQ<1>")
	)
	(segment
		(start 30.914086 -283.231844)
		(end 31.0769 -283.394658)
		(width 0.14478)
		(layer "In6.Cu")
		(net "M_E_CPU1_SB_DQ<1>")
	)
	(segment
		(start 59.092846 -283.074364)
		(end 59.334908 -283.074364)
		(width 0.14478)
		(layer "In6.Cu")
		(net "M_E_CPU1_SB_DQ<1>")
	)
	(arc
		(start 81.813908 -275.218906)
		(mid 81.996159 -275.269256)
		(end 82.179668 -275.223732)
		(width 0.0889)
		(layer "In6.Cu")
		(net "M_E_CPU1_SB_DQ<1>")
	)
	(arc
		(start 79.9338 -275.218906)
		(mid 80.120998 -275.269288)
		(end 80.308196 -275.218906)
		(width 0.0889)
		(layer "In6.Cu")
		(net "M_E_CPU1_SB_DQ<1>")
	)
	(arc
		(start 79.618586 -275.085556)
		(mid 79.663188 -275.089641)
		(end 79.706216 -275.102066)
		(width 0.0889)
		(layer "In6.Cu")
		(net "M_E_CPU1_SB_DQ<1>")
	)
	(arc
		(start 80.874108 -275.218906)
		(mid 81.061052 -275.269161)
		(end 81.247996 -275.218906)
		(width 0.0889)
		(layer "In6.Cu")
		(net "M_E_CPU1_SB_DQ<1>")
	)
	(arc
		(start 80.308196 -275.218906)
		(mid 80.591152 -275.142729)
		(end 80.874108 -275.218906)
		(width 0.0889)
		(layer "In6.Cu")
		(net "M_E_CPU1_SB_DQ<1>")
	)
	(arc
		(start 79.706216 -275.102066)
		(mid 79.789477 -275.138786)
		(end 79.869792 -275.181568)
		(width 0.0889)
		(layer "In6.Cu")
		(net "M_E_CPU1_SB_DQ<1>")
	)
	(arc
		(start 81.247996 -275.218906)
		(mid 81.530952 -275.142729)
		(end 81.813908 -275.218906)
		(width 0.0889)
		(layer "In6.Cu")
		(net "M_E_CPU1_SB_DQ<1>")
	)
	(arc
		(start 82.18805 -275.218906)
		(mid 82.435763 -275.143686)
		(end 82.69097 -275.187156)
		(width 0.0889)
		(layer "In6.Cu")
		(net "M_E_CPU1_SB_DQ<1>")
	)
	(segment
		(start 82.937858 -285.160466)
		(end 82.471006 -285.426404)
		(width 0.10668)
		(layer "F.Cu")
		(net "M_E_CPU1_SB_DQ<19>")
	)
	(segment
		(start 25.152096 -302.735234)
		(end 25.567386 -303.150524)
		(width 0.14478)
		(layer "In6.Cu")
		(net "M_E_CPU1_SB_DQ<19>")
	)
	(segment
		(start 66.249042 -294.277542)
		(end 66.593974 -293.44239)
		(width 0.14478)
		(layer "In6.Cu")
		(net "M_E_CPU1_SB_DQ<19>")
	)
	(segment
		(start 71.550784 -288.48304)
		(end 72.820022 -288.48304)
		(width 0.14478)
		(layer "In6.Cu")
		(net "M_E_CPU1_SB_DQ<19>")
	)
	(segment
		(start 61.188854 -299.33773)
		(end 66.249042 -294.277542)
		(width 0.14478)
		(layer "In6.Cu")
		(net "M_E_CPU1_SB_DQ<19>")
	)
	(segment
		(start 60.321444 -301.431706)
		(end 61.188854 -299.33773)
		(width 0.14478)
		(layer "In6.Cu")
		(net "M_E_CPU1_SB_DQ<19>")
	)
	(segment
		(start 72.820022 -288.48304)
		(end 75.471528 -285.831534)
		(width 0.14478)
		(layer "In6.Cu")
		(net "M_E_CPU1_SB_DQ<19>")
	)
	(segment
		(start 76.284836 -285.831534)
		(end 76.408026 -285.708344)
		(width 0.0889)
		(layer "In6.Cu")
		(net "M_E_CPU1_SB_DQ<19>")
	)
	(segment
		(start 35.19551 -302.30064)
		(end 37.80917 -302.30064)
		(width 0.14478)
		(layer "In6.Cu")
		(net "M_E_CPU1_SB_DQ<19>")
	)
	(segment
		(start 66.593974 -293.44239)
		(end 71.550784 -288.48304)
		(width 0.14478)
		(layer "In6.Cu")
		(net "M_E_CPU1_SB_DQ<19>")
	)
	(segment
		(start 77.525372 -285.588964)
		(end 77.934312 -285.180024)
		(width 0.0889)
		(layer "In6.Cu")
		(net "M_E_CPU1_SB_DQ<19>")
	)
	(segment
		(start 37.80917 -302.30064)
		(end 38.659054 -303.150524)
		(width 0.14478)
		(layer "In6.Cu")
		(net "M_E_CPU1_SB_DQ<19>")
	)
	(segment
		(start 48.395636 -303.150524)
		(end 50.447702 -302.30064)
		(width 0.14478)
		(layer "In6.Cu")
		(net "M_E_CPU1_SB_DQ<19>")
	)
	(segment
		(start 77.934312 -285.180024)
		(end 78.241652 -285.180024)
		(width 0.0889)
		(layer "In6.Cu")
		(net "M_E_CPU1_SB_DQ<19>")
	)
	(segment
		(start 34.345626 -303.150524)
		(end 35.19551 -302.30064)
		(width 0.14478)
		(layer "In6.Cu")
		(net "M_E_CPU1_SB_DQ<19>")
	)
	(segment
		(start 41.610026 -303.150524)
		(end 42.45991 -302.30064)
		(width 0.14478)
		(layer "In6.Cu")
		(net "M_E_CPU1_SB_DQ<19>")
	)
	(segment
		(start 76.814426 -285.708344)
		(end 76.933806 -285.588964)
		(width 0.0889)
		(layer "In6.Cu")
		(net "M_E_CPU1_SB_DQ<19>")
	)
	(segment
		(start 25.567386 -303.150524)
		(end 34.345626 -303.150524)
		(width 0.14478)
		(layer "In6.Cu")
		(net "M_E_CPU1_SB_DQ<19>")
	)
	(segment
		(start 42.45991 -302.30064)
		(end 46.11497 -302.30064)
		(width 0.14478)
		(layer "In6.Cu")
		(net "M_E_CPU1_SB_DQ<19>")
	)
	(segment
		(start 75.471528 -285.831534)
		(end 76.06665 -285.831534)
		(width 0.14478)
		(layer "In6.Cu")
		(net "M_E_CPU1_SB_DQ<19>")
	)
	(segment
		(start 58.951368 -301.909734)
		(end 59.843416 -301.909734)
		(width 0.14478)
		(layer "In6.Cu")
		(net "M_E_CPU1_SB_DQ<19>")
	)
	(segment
		(start 79.454248 -285.10992)
		(end 79.464662 -285.103824)
		(width 0.0889)
		(layer "In6.Cu")
		(net "M_E_CPU1_SB_DQ<19>")
	)
	(segment
		(start 38.659054 -303.150524)
		(end 41.610026 -303.150524)
		(width 0.14478)
		(layer "In6.Cu")
		(net "M_E_CPU1_SB_DQ<19>")
	)
	(segment
		(start 50.447702 -302.30064)
		(end 52.636928 -302.30064)
		(width 0.14478)
		(layer "In6.Cu")
		(net "M_E_CPU1_SB_DQ<19>")
	)
	(segment
		(start 79.838296 -285.103824)
		(end 79.84871 -285.10992)
		(width 0.0889)
		(layer "In6.Cu")
		(net "M_E_CPU1_SB_DQ<19>")
	)
	(segment
		(start 81.344008 -285.103824)
		(end 81.35239 -285.098998)
		(width 0.0889)
		(layer "In6.Cu")
		(net "M_E_CPU1_SB_DQ<19>")
	)
	(segment
		(start 46.11497 -302.30064)
		(end 46.964854 -303.150524)
		(width 0.14478)
		(layer "In6.Cu")
		(net "M_E_CPU1_SB_DQ<19>")
	)
	(segment
		(start 76.933806 -285.588964)
		(end 77.525372 -285.588964)
		(width 0.0889)
		(layer "In6.Cu")
		(net "M_E_CPU1_SB_DQ<19>")
	)
	(segment
		(start 46.964854 -303.150524)
		(end 48.395636 -303.150524)
		(width 0.14478)
		(layer "In6.Cu")
		(net "M_E_CPU1_SB_DQ<19>")
	)
	(segment
		(start 82.602578 -285.077662)
		(end 82.62493 -285.160974)
		(width 0.0889)
		(layer "In6.Cu")
		(net "M_E_CPU1_SB_DQ<19>")
	)
	(segment
		(start 56.899048 -302.759872)
		(end 58.951368 -301.909734)
		(width 0.14478)
		(layer "In6.Cu")
		(net "M_E_CPU1_SB_DQ<19>")
	)
	(segment
		(start 52.636928 -302.30064)
		(end 54.15026 -302.759872)
		(width 0.14478)
		(layer "In6.Cu")
		(net "M_E_CPU1_SB_DQ<19>")
	)
	(segment
		(start 76.06665 -285.831534)
		(end 76.284836 -285.831534)
		(width 0.0889)
		(layer "In6.Cu")
		(net "M_E_CPU1_SB_DQ<19>")
	)
	(segment
		(start 54.15026 -302.759872)
		(end 56.899048 -302.759872)
		(width 0.14478)
		(layer "In6.Cu")
		(net "M_E_CPU1_SB_DQ<19>")
	)
	(segment
		(start 76.408026 -285.708344)
		(end 76.814426 -285.708344)
		(width 0.0889)
		(layer "In6.Cu")
		(net "M_E_CPU1_SB_DQ<19>")
	)
	(segment
		(start 82.62493 -285.160974)
		(end 82.471006 -285.426404)
		(width 0.0889)
		(layer "In6.Cu")
		(net "M_E_CPU1_SB_DQ<19>")
	)
	(segment
		(start 59.843416 -301.909734)
		(end 60.321444 -301.431706)
		(width 0.14478)
		(layer "In6.Cu")
		(net "M_E_CPU1_SB_DQ<19>")
	)
	(segment
		(start 78.524354 -285.104078)
		(end 78.542642 -285.093664)
		(width 0.0889)
		(layer "In6.Cu")
		(net "M_E_CPU1_SB_DQ<19>")
	)
	(segment
		(start 80.769714 -285.098998)
		(end 80.778096 -285.103824)
		(width 0.0889)
		(layer "In6.Cu")
		(net "M_E_CPU1_SB_DQ<19>")
	)
	(segment
		(start 79.829914 -285.098998)
		(end 79.838296 -285.103824)
		(width 0.0889)
		(layer "In6.Cu")
		(net "M_E_CPU1_SB_DQ<19>")
	)
	(arc
		(start 81.71815 -285.103824)
		(mid 82.001106 -285.180001)
		(end 82.284062 -285.103824)
		(width 0.0889)
		(layer "In6.Cu")
		(net "M_E_CPU1_SB_DQ<19>")
	)
	(arc
		(start 82.284062 -285.103824)
		(mid 82.440381 -285.054829)
		(end 82.602578 -285.077662)
		(width 0.0889)
		(layer "In6.Cu")
		(net "M_E_CPU1_SB_DQ<19>")
	)
	(arc
		(start 78.542642 -285.093664)
		(mid 78.721871 -285.053511)
		(end 78.898496 -285.103824)
		(width 0.0889)
		(layer "In6.Cu")
		(net "M_E_CPU1_SB_DQ<19>")
	)
	(arc
		(start 79.84871 -285.10992)
		(mid 80.127142 -285.180018)
		(end 80.403954 -285.103824)
		(width 0.0889)
		(layer "In6.Cu")
		(net "M_E_CPU1_SB_DQ<19>")
	)
	(arc
		(start 78.898496 -285.103824)
		(mid 79.175563 -285.180095)
		(end 79.454248 -285.10992)
		(width 0.0889)
		(layer "In6.Cu")
		(net "M_E_CPU1_SB_DQ<19>")
	)
	(arc
		(start 81.35239 -285.098998)
		(mid 81.535898 -285.053504)
		(end 81.71815 -285.103824)
		(width 0.0889)
		(layer "In6.Cu")
		(net "M_E_CPU1_SB_DQ<19>")
	)
	(arc
		(start 78.241652 -285.180024)
		(mid 78.388015 -285.160707)
		(end 78.524354 -285.104078)
		(width 0.0889)
		(layer "In6.Cu")
		(net "M_E_CPU1_SB_DQ<19>")
	)
	(arc
		(start 80.778096 -285.103824)
		(mid 81.061052 -285.180001)
		(end 81.344008 -285.103824)
		(width 0.0889)
		(layer "In6.Cu")
		(net "M_E_CPU1_SB_DQ<19>")
	)
	(arc
		(start 79.464662 -285.103824)
		(mid 79.646659 -285.053602)
		(end 79.829914 -285.098998)
		(width 0.0889)
		(layer "In6.Cu")
		(net "M_E_CPU1_SB_DQ<19>")
	)
	(arc
		(start 80.403954 -285.103824)
		(mid 80.586205 -285.053474)
		(end 80.769714 -285.098998)
		(width 0.0889)
		(layer "In6.Cu")
		(net "M_E_CPU1_SB_DQ<19>")
	)
	(segment
		(start 81.527904 -284.35046)
		(end 81.061052 -284.616398)
		(width 0.10668)
		(layer "F.Cu")
		(net "M_E_CPU1_SB_DQ<18>")
	)
	(segment
		(start 46.151546 -300.61027)
		(end 47.001684 -301.460408)
		(width 0.14478)
		(layer "In6.Cu")
		(net "M_E_CPU1_SB_DQ<18>")
	)
	(segment
		(start 26.52014 -301.297594)
		(end 26.52014 -301.027846)
		(width 0.14478)
		(layer "In6.Cu")
		(net "M_E_CPU1_SB_DQ<18>")
	)
	(segment
		(start 81.214976 -284.350968)
		(end 81.061052 -284.616398)
		(width 0.0889)
		(layer "In6.Cu")
		(net "M_E_CPU1_SB_DQ<18>")
	)
	(segment
		(start 71.177912 -287.58388)
		(end 72.407526 -287.58388)
		(width 0.14478)
		(layer "In6.Cu")
		(net "M_E_CPU1_SB_DQ<18>")
	)
	(segment
		(start 38.241224 -301.460408)
		(end 41.674796 -301.460408)
		(width 0.14478)
		(layer "In6.Cu")
		(net "M_E_CPU1_SB_DQ<18>")
	)
	(segment
		(start 37.391086 -300.61027)
		(end 38.241224 -301.460408)
		(width 0.14478)
		(layer "In6.Cu")
		(net "M_E_CPU1_SB_DQ<18>")
	)
	(segment
		(start 56.71185 -301.460408)
		(end 57.00141 -301.170848)
		(width 0.14478)
		(layer "In6.Cu")
		(net "M_E_CPU1_SB_DQ<18>")
	)
	(segment
		(start 26.52014 -301.027846)
		(end 26.66492 -300.883066)
		(width 0.14478)
		(layer "In6.Cu")
		(net "M_E_CPU1_SB_DQ<18>")
	)
	(segment
		(start 25.152096 -301.035212)
		(end 25.577292 -301.460408)
		(width 0.14478)
		(layer "In6.Cu")
		(net "M_E_CPU1_SB_DQ<18>")
	)
	(segment
		(start 27.0764 -301.297594)
		(end 27.239214 -301.460408)
		(width 0.14478)
		(layer "In6.Cu")
		(net "M_E_CPU1_SB_DQ<18>")
	)
	(segment
		(start 54.266084 -301.460408)
		(end 56.71185 -301.460408)
		(width 0.14478)
		(layer "In6.Cu")
		(net "M_E_CPU1_SB_DQ<18>")
	)
	(segment
		(start 25.577292 -301.460408)
		(end 26.357326 -301.460408)
		(width 0.14478)
		(layer "In6.Cu")
		(net "M_E_CPU1_SB_DQ<18>")
	)
	(segment
		(start 57.00141 -300.697646)
		(end 57.28843 -300.410626)
		(width 0.14478)
		(layer "In6.Cu")
		(net "M_E_CPU1_SB_DQ<18>")
	)
	(segment
		(start 81.192624 -284.267656)
		(end 81.214976 -284.350968)
		(width 0.0889)
		(layer "In6.Cu")
		(net "M_E_CPU1_SB_DQ<18>")
	)
	(segment
		(start 27.0764 -301.027846)
		(end 27.0764 -301.297594)
		(width 0.14478)
		(layer "In6.Cu")
		(net "M_E_CPU1_SB_DQ<18>")
	)
	(segment
		(start 80.299814 -284.288992)
		(end 80.308196 -284.293818)
		(width 0.0889)
		(layer "In6.Cu")
		(net "M_E_CPU1_SB_DQ<18>")
	)
	(segment
		(start 75.994006 -284.922214)
		(end 77.256386 -284.922214)
		(width 0.0889)
		(layer "In6.Cu")
		(net "M_E_CPU1_SB_DQ<18>")
	)
	(segment
		(start 35.412934 -300.61027)
		(end 37.391086 -300.61027)
		(width 0.14478)
		(layer "In6.Cu")
		(net "M_E_CPU1_SB_DQ<18>")
	)
	(segment
		(start 79.36738 -284.293818)
		(end 79.377794 -284.299914)
		(width 0.0889)
		(layer "In6.Cu")
		(net "M_E_CPU1_SB_DQ<18>")
	)
	(segment
		(start 72.407526 -287.58388)
		(end 75.069192 -284.922214)
		(width 0.14478)
		(layer "In6.Cu")
		(net "M_E_CPU1_SB_DQ<18>")
	)
	(segment
		(start 75.069192 -284.922214)
		(end 75.994006 -284.922214)
		(width 0.14478)
		(layer "In6.Cu")
		(net "M_E_CPU1_SB_DQ<18>")
	)
	(segment
		(start 26.93162 -300.883066)
		(end 27.0764 -301.027846)
		(width 0.14478)
		(layer "In6.Cu")
		(net "M_E_CPU1_SB_DQ<18>")
	)
	(segment
		(start 77.256386 -284.922214)
		(end 77.808582 -284.370018)
		(width 0.0889)
		(layer "In6.Cu")
		(net "M_E_CPU1_SB_DQ<18>")
	)
	(segment
		(start 65.831974 -292.930072)
		(end 71.177912 -287.58388)
		(width 0.14478)
		(layer "In6.Cu")
		(net "M_E_CPU1_SB_DQ<18>")
	)
	(segment
		(start 50.285142 -300.61027)
		(end 53.415946 -300.61027)
		(width 0.14478)
		(layer "In6.Cu")
		(net "M_E_CPU1_SB_DQ<18>")
	)
	(segment
		(start 77.808582 -284.370018)
		(end 78.711044 -284.370018)
		(width 0.0889)
		(layer "In6.Cu")
		(net "M_E_CPU1_SB_DQ<18>")
	)
	(segment
		(start 58.940954 -300.410626)
		(end 60.029598 -299.321982)
		(width 0.14478)
		(layer "In6.Cu")
		(net "M_E_CPU1_SB_DQ<18>")
	)
	(segment
		(start 60.098686 -299.155104)
		(end 65.485264 -293.76878)
		(width 0.14478)
		(layer "In6.Cu")
		(net "M_E_CPU1_SB_DQ<18>")
	)
	(segment
		(start 57.28843 -300.410626)
		(end 58.940954 -300.410626)
		(width 0.14478)
		(layer "In6.Cu")
		(net "M_E_CPU1_SB_DQ<18>")
	)
	(segment
		(start 26.357326 -301.460408)
		(end 26.52014 -301.297594)
		(width 0.14478)
		(layer "In6.Cu")
		(net "M_E_CPU1_SB_DQ<18>")
	)
	(segment
		(start 65.485264 -293.76878)
		(end 65.831974 -292.930072)
		(width 0.14478)
		(layer "In6.Cu")
		(net "M_E_CPU1_SB_DQ<18>")
	)
	(segment
		(start 49.435004 -301.460408)
		(end 50.285142 -300.61027)
		(width 0.14478)
		(layer "In6.Cu")
		(net "M_E_CPU1_SB_DQ<18>")
	)
	(segment
		(start 57.00141 -301.170848)
		(end 57.00141 -300.697646)
		(width 0.14478)
		(layer "In6.Cu")
		(net "M_E_CPU1_SB_DQ<18>")
	)
	(segment
		(start 42.524934 -300.61027)
		(end 46.151546 -300.61027)
		(width 0.14478)
		(layer "In6.Cu")
		(net "M_E_CPU1_SB_DQ<18>")
	)
	(segment
		(start 27.239214 -301.460408)
		(end 34.562796 -301.460408)
		(width 0.14478)
		(layer "In6.Cu")
		(net "M_E_CPU1_SB_DQ<18>")
	)
	(segment
		(start 26.66492 -300.883066)
		(end 26.93162 -300.883066)
		(width 0.14478)
		(layer "In6.Cu")
		(net "M_E_CPU1_SB_DQ<18>")
	)
	(segment
		(start 78.993492 -284.294072)
		(end 79.009748 -284.284674)
		(width 0.0889)
		(layer "In6.Cu")
		(net "M_E_CPU1_SB_DQ<18>")
	)
	(segment
		(start 60.029598 -299.321982)
		(end 60.098686 -299.155104)
		(width 0.14478)
		(layer "In6.Cu")
		(net "M_E_CPU1_SB_DQ<18>")
	)
	(segment
		(start 53.415946 -300.61027)
		(end 54.266084 -301.460408)
		(width 0.14478)
		(layer "In6.Cu")
		(net "M_E_CPU1_SB_DQ<18>")
	)
	(segment
		(start 41.674796 -301.460408)
		(end 42.524934 -300.61027)
		(width 0.14478)
		(layer "In6.Cu")
		(net "M_E_CPU1_SB_DQ<18>")
	)
	(segment
		(start 34.562796 -301.460408)
		(end 35.412934 -300.61027)
		(width 0.14478)
		(layer "In6.Cu")
		(net "M_E_CPU1_SB_DQ<18>")
	)
	(segment
		(start 47.001684 -301.460408)
		(end 49.435004 -301.460408)
		(width 0.14478)
		(layer "In6.Cu")
		(net "M_E_CPU1_SB_DQ<18>")
	)
	(arc
		(start 80.874108 -284.293818)
		(mid 81.030427 -284.244823)
		(end 81.192624 -284.267656)
		(width 0.0889)
		(layer "In6.Cu")
		(net "M_E_CPU1_SB_DQ<18>")
	)
	(arc
		(start 79.009748 -284.284674)
		(mid 79.18973 -284.243574)
		(end 79.36738 -284.293818)
		(width 0.0889)
		(layer "In6.Cu")
		(net "M_E_CPU1_SB_DQ<18>")
	)
	(arc
		(start 79.377794 -284.299914)
		(mid 79.65648 -284.370134)
		(end 79.933546 -284.293818)
		(width 0.0889)
		(layer "In6.Cu")
		(net "M_E_CPU1_SB_DQ<18>")
	)
	(arc
		(start 80.308196 -284.293818)
		(mid 80.591152 -284.369995)
		(end 80.874108 -284.293818)
		(width 0.0889)
		(layer "In6.Cu")
		(net "M_E_CPU1_SB_DQ<18>")
	)
	(arc
		(start 78.711044 -284.370018)
		(mid 78.857292 -284.350713)
		(end 78.993492 -284.294072)
		(width 0.0889)
		(layer "In6.Cu")
		(net "M_E_CPU1_SB_DQ<18>")
	)
	(arc
		(start 79.933546 -284.293818)
		(mid 80.116051 -284.243341)
		(end 80.299814 -284.288992)
		(width 0.0889)
		(layer "In6.Cu")
		(net "M_E_CPU1_SB_DQ<18>")
	)
	(segment
		(start 83.408012 -284.35046)
		(end 82.940906 -284.616398)
		(width 0.10668)
		(layer "F.Cu")
		(net "M_E_CPU1_SB_DQ<17>")
	)
	(segment
		(start 82.69097 -284.907228)
		(end 82.786982 -284.881828)
		(width 0.0889)
		(layer "In6.Cu")
		(net "M_E_CPU1_SB_DQ<17>")
	)
	(segment
		(start 31.720536 -301.939198)
		(end 31.951168 -301.939198)
		(width 0.14478)
		(layer "In6.Cu")
		(net "M_E_CPU1_SB_DQ<17>")
	)
	(segment
		(start 51.28641 -301.460154)
		(end 53.622702 -301.460154)
		(width 0.14478)
		(layer "In6.Cu")
		(net "M_E_CPU1_SB_DQ<17>")
	)
	(segment
		(start 59.644788 -301.460154)
		(end 59.94908 -301.155862)
		(width 0.14478)
		(layer "In6.Cu")
		(net "M_E_CPU1_SB_DQ<17>")
	)
	(segment
		(start 65.866772 -294.023542)
		(end 66.212466 -293.187628)
		(width 0.14478)
		(layer "In6.Cu")
		(net "M_E_CPU1_SB_DQ<17>")
	)
	(segment
		(start 42.809668 -301.460408)
		(end 43.118024 -301.768764)
		(width 0.14478)
		(layer "In6.Cu")
		(net "M_E_CPU1_SB_DQ<17>")
	)
	(segment
		(start 45.413168 -301.460408)
		(end 46.214284 -301.460408)
		(width 0.14478)
		(layer "In6.Cu")
		(net "M_E_CPU1_SB_DQ<17>")
	)
	(segment
		(start 37.604954 -301.460154)
		(end 38.751764 -302.606964)
		(width 0.14478)
		(layer "In6.Cu")
		(net "M_E_CPU1_SB_DQ<17>")
	)
	(segment
		(start 35.80003 -301.768764)
		(end 36.04768 -301.768764)
		(width 0.14478)
		(layer "In6.Cu")
		(net "M_E_CPU1_SB_DQ<17>")
	)
	(segment
		(start 79.934308 -284.938978)
		(end 79.945992 -284.945836)
		(width 0.0889)
		(layer "In6.Cu")
		(net "M_E_CPU1_SB_DQ<17>")
	)
	(segment
		(start 41.081452 -302.632364)
		(end 41.31564 -302.632364)
		(width 0.14478)
		(layer "In6.Cu")
		(net "M_E_CPU1_SB_DQ<17>")
	)
	(segment
		(start 43.674284 -301.460408)
		(end 44.548552 -301.460408)
		(width 0.14478)
		(layer "In6.Cu")
		(net "M_E_CPU1_SB_DQ<17>")
	)
	(segment
		(start 31.164276 -302.684942)
		(end 31.394908 -302.684942)
		(width 0.14478)
		(layer "In6.Cu")
		(net "M_E_CPU1_SB_DQ<17>")
	)
	(segment
		(start 49.228248 -302.310292)
		(end 50.078386 -301.460154)
		(width 0.14478)
		(layer "In6.Cu")
		(net "M_E_CPU1_SB_DQ<17>")
	)
	(segment
		(start 38.751764 -302.606964)
		(end 39.263828 -302.606964)
		(width 0.14478)
		(layer "In6.Cu")
		(net "M_E_CPU1_SB_DQ<17>")
	)
	(segment
		(start 36.35629 -301.460154)
		(end 37.604954 -301.460154)
		(width 0.14478)
		(layer "In6.Cu")
		(net "M_E_CPU1_SB_DQ<17>")
	)
	(segment
		(start 34.373312 -302.310292)
		(end 35.22345 -301.460154)
		(width 0.14478)
		(layer "In6.Cu")
		(net "M_E_CPU1_SB_DQ<17>")
	)
	(segment
		(start 31.001462 -302.522128)
		(end 31.164276 -302.684942)
		(width 0.14478)
		(layer "In6.Cu")
		(net "M_E_CPU1_SB_DQ<17>")
	)
	(segment
		(start 50.078386 -301.460154)
		(end 50.42154 -301.460154)
		(width 0.14478)
		(layer "In6.Cu")
		(net "M_E_CPU1_SB_DQ<17>")
	)
	(segment
		(start 31.951168 -301.939198)
		(end 32.322262 -302.310292)
		(width 0.14478)
		(layer "In6.Cu")
		(net "M_E_CPU1_SB_DQ<17>")
	)
	(segment
		(start 60.8076 -299.082714)
		(end 65.866772 -294.023542)
		(width 0.14478)
		(layer "In6.Cu")
		(net "M_E_CPU1_SB_DQ<17>")
	)
	(segment
		(start 59.94908 -301.155862)
		(end 60.8076 -299.082714)
		(width 0.14478)
		(layer "In6.Cu")
		(net "M_E_CPU1_SB_DQ<17>")
	)
	(segment
		(start 79.356966 -284.945836)
		(end 79.36865 -284.938978)
		(width 0.0889)
		(layer "In6.Cu")
		(net "M_E_CPU1_SB_DQ<17>")
	)
	(segment
		(start 58.442352 -301.460154)
		(end 59.644788 -301.460154)
		(width 0.14478)
		(layer "In6.Cu")
		(net "M_E_CPU1_SB_DQ<17>")
	)
	(segment
		(start 30.838648 -301.939198)
		(end 31.001462 -302.102012)
		(width 0.14478)
		(layer "In6.Cu")
		(net "M_E_CPU1_SB_DQ<17>")
	)
	(segment
		(start 31.557722 -302.522128)
		(end 31.557722 -302.102012)
		(width 0.14478)
		(layer "In6.Cu")
		(net "M_E_CPU1_SB_DQ<17>")
	)
	(segment
		(start 66.212466 -293.187628)
		(end 71.364348 -288.03346)
		(width 0.14478)
		(layer "In6.Cu")
		(net "M_E_CPU1_SB_DQ<17>")
	)
	(segment
		(start 53.622702 -301.460154)
		(end 54.47284 -302.310292)
		(width 0.14478)
		(layer "In6.Cu")
		(net "M_E_CPU1_SB_DQ<17>")
	)
	(segment
		(start 42.487596 -301.460408)
		(end 42.809668 -301.460408)
		(width 0.14478)
		(layer "In6.Cu")
		(net "M_E_CPU1_SB_DQ<17>")
	)
	(segment
		(start 56.39054 -302.310292)
		(end 58.442352 -301.460154)
		(width 0.14478)
		(layer "In6.Cu")
		(net "M_E_CPU1_SB_DQ<17>")
	)
	(segment
		(start 39.5605 -302.310292)
		(end 40.75938 -302.310292)
		(width 0.14478)
		(layer "In6.Cu")
		(net "M_E_CPU1_SB_DQ<17>")
	)
	(segment
		(start 35.22345 -301.460154)
		(end 35.49142 -301.460154)
		(width 0.14478)
		(layer "In6.Cu")
		(net "M_E_CPU1_SB_DQ<17>")
	)
	(segment
		(start 41.31564 -302.632364)
		(end 42.487596 -301.460408)
		(width 0.14478)
		(layer "In6.Cu")
		(net "M_E_CPU1_SB_DQ<17>")
	)
	(segment
		(start 30.445202 -302.102012)
		(end 30.608016 -301.939198)
		(width 0.14478)
		(layer "In6.Cu")
		(net "M_E_CPU1_SB_DQ<17>")
	)
	(segment
		(start 31.001462 -302.102012)
		(end 31.001462 -302.522128)
		(width 0.14478)
		(layer "In6.Cu")
		(net "M_E_CPU1_SB_DQ<17>")
	)
	(segment
		(start 54.47284 -302.310292)
		(end 56.39054 -302.310292)
		(width 0.14478)
		(layer "In6.Cu")
		(net "M_E_CPU1_SB_DQ<17>")
	)
	(segment
		(start 32.322262 -302.310292)
		(end 34.373312 -302.310292)
		(width 0.14478)
		(layer "In6.Cu")
		(net "M_E_CPU1_SB_DQ<17>")
	)
	(segment
		(start 77.904848 -284.96895)
		(end 78.23327 -284.96895)
		(width 0.0889)
		(layer "In6.Cu")
		(net "M_E_CPU1_SB_DQ<17>")
	)
	(segment
		(start 43.365928 -301.768764)
		(end 43.674284 -301.460408)
		(width 0.14478)
		(layer "In6.Cu")
		(net "M_E_CPU1_SB_DQ<17>")
	)
	(segment
		(start 30.608016 -301.939198)
		(end 30.838648 -301.939198)
		(width 0.14478)
		(layer "In6.Cu")
		(net "M_E_CPU1_SB_DQ<17>")
	)
	(segment
		(start 82.179668 -284.943804)
		(end 82.18805 -284.938978)
		(width 0.0889)
		(layer "In6.Cu")
		(net "M_E_CPU1_SB_DQ<17>")
	)
	(segment
		(start 44.856908 -301.768764)
		(end 45.104812 -301.768764)
		(width 0.14478)
		(layer "In6.Cu")
		(net "M_E_CPU1_SB_DQ<17>")
	)
	(segment
		(start 77.449934 -285.376874)
		(end 77.824584 -285.002224)
		(width 0.0889)
		(layer "In6.Cu")
		(net "M_E_CPU1_SB_DQ<17>")
	)
	(segment
		(start 50.9778 -301.768764)
		(end 51.28641 -301.460154)
		(width 0.14478)
		(layer "In6.Cu")
		(net "M_E_CPU1_SB_DQ<17>")
	)
	(segment
		(start 44.548552 -301.460408)
		(end 44.856908 -301.768764)
		(width 0.14478)
		(layer "In6.Cu")
		(net "M_E_CPU1_SB_DQ<17>")
	)
	(segment
		(start 40.75938 -302.310292)
		(end 41.081452 -302.632364)
		(width 0.14478)
		(layer "In6.Cu")
		(net "M_E_CPU1_SB_DQ<17>")
	)
	(segment
		(start 30.282388 -302.684942)
		(end 30.445202 -302.522128)
		(width 0.14478)
		(layer "In6.Cu")
		(net "M_E_CPU1_SB_DQ<17>")
	)
	(segment
		(start 47.064168 -302.310292)
		(end 49.228248 -302.310292)
		(width 0.14478)
		(layer "In6.Cu")
		(net "M_E_CPU1_SB_DQ<17>")
	)
	(segment
		(start 36.04768 -301.768764)
		(end 36.35629 -301.460154)
		(width 0.14478)
		(layer "In6.Cu")
		(net "M_E_CPU1_SB_DQ<17>")
	)
	(segment
		(start 75.263756 -285.376874)
		(end 76.002896 -285.376874)
		(width 0.14478)
		(layer "In6.Cu")
		(net "M_E_CPU1_SB_DQ<17>")
	)
	(segment
		(start 31.394908 -302.684942)
		(end 31.557722 -302.522128)
		(width 0.14478)
		(layer "In6.Cu")
		(net "M_E_CPU1_SB_DQ<17>")
	)
	(segment
		(start 43.118024 -301.768764)
		(end 43.365928 -301.768764)
		(width 0.14478)
		(layer "In6.Cu")
		(net "M_E_CPU1_SB_DQ<17>")
	)
	(segment
		(start 50.42154 -301.460154)
		(end 50.73015 -301.768764)
		(width 0.14478)
		(layer "In6.Cu")
		(net "M_E_CPU1_SB_DQ<17>")
	)
	(segment
		(start 72.60717 -288.03346)
		(end 75.263756 -285.376874)
		(width 0.14478)
		(layer "In6.Cu")
		(net "M_E_CPU1_SB_DQ<17>")
	)
	(segment
		(start 45.104812 -301.768764)
		(end 45.413168 -301.460408)
		(width 0.14478)
		(layer "In6.Cu")
		(net "M_E_CPU1_SB_DQ<17>")
	)
	(segment
		(start 29.252164 -301.88535)
		(end 30.051756 -302.684942)
		(width 0.14478)
		(layer "In6.Cu")
		(net "M_E_CPU1_SB_DQ<17>")
	)
	(segment
		(start 76.002896 -285.376874)
		(end 77.449934 -285.376874)
		(width 0.0889)
		(layer "In6.Cu")
		(net "M_E_CPU1_SB_DQ<17>")
	)
	(segment
		(start 31.557722 -302.102012)
		(end 31.720536 -301.939198)
		(width 0.14478)
		(layer "In6.Cu")
		(net "M_E_CPU1_SB_DQ<17>")
	)
	(segment
		(start 50.73015 -301.768764)
		(end 50.9778 -301.768764)
		(width 0.14478)
		(layer "In6.Cu")
		(net "M_E_CPU1_SB_DQ<17>")
	)
	(segment
		(start 39.263828 -302.606964)
		(end 39.5605 -302.310292)
		(width 0.14478)
		(layer "In6.Cu")
		(net "M_E_CPU1_SB_DQ<17>")
	)
	(segment
		(start 82.786982 -284.881828)
		(end 82.940906 -284.616398)
		(width 0.0889)
		(layer "In6.Cu")
		(net "M_E_CPU1_SB_DQ<17>")
	)
	(segment
		(start 46.214284 -301.460408)
		(end 47.064168 -302.310292)
		(width 0.14478)
		(layer "In6.Cu")
		(net "M_E_CPU1_SB_DQ<17>")
	)
	(segment
		(start 35.49142 -301.460154)
		(end 35.80003 -301.768764)
		(width 0.14478)
		(layer "In6.Cu")
		(net "M_E_CPU1_SB_DQ<17>")
	)
	(segment
		(start 71.364348 -288.03346)
		(end 72.60717 -288.03346)
		(width 0.14478)
		(layer "In6.Cu")
		(net "M_E_CPU1_SB_DQ<17>")
	)
	(segment
		(start 30.445202 -302.522128)
		(end 30.445202 -302.102012)
		(width 0.14478)
		(layer "In6.Cu")
		(net "M_E_CPU1_SB_DQ<17>")
	)
	(segment
		(start 30.051756 -302.684942)
		(end 30.282388 -302.684942)
		(width 0.14478)
		(layer "In6.Cu")
		(net "M_E_CPU1_SB_DQ<17>")
	)
	(segment
		(start 79.923894 -284.932882)
		(end 79.934308 -284.938978)
		(width 0.0889)
		(layer "In6.Cu")
		(net "M_E_CPU1_SB_DQ<17>")
	)
	(arc
		(start 79.36865 -284.938978)
		(mid 79.645463 -284.862835)
		(end 79.923894 -284.932882)
		(width 0.0889)
		(layer "In6.Cu")
		(net "M_E_CPU1_SB_DQ<17>")
	)
	(arc
		(start 81.813908 -284.938978)
		(mid 81.996159 -284.989328)
		(end 82.179668 -284.943804)
		(width 0.0889)
		(layer "In6.Cu")
		(net "M_E_CPU1_SB_DQ<17>")
	)
	(arc
		(start 79.945992 -284.945836)
		(mid 80.127993 -284.989369)
		(end 80.308196 -284.938978)
		(width 0.0889)
		(layer "In6.Cu")
		(net "M_E_CPU1_SB_DQ<17>")
	)
	(arc
		(start 80.308196 -284.938978)
		(mid 80.591152 -284.862801)
		(end 80.874108 -284.938978)
		(width 0.0889)
		(layer "In6.Cu")
		(net "M_E_CPU1_SB_DQ<17>")
	)
	(arc
		(start 77.824584 -285.002224)
		(mid 77.861395 -284.977564)
		(end 77.904848 -284.96895)
		(width 0.0889)
		(layer "In6.Cu")
		(net "M_E_CPU1_SB_DQ<17>")
	)
	(arc
		(start 78.23327 -284.96895)
		(mid 78.355584 -284.955405)
		(end 78.47203 -284.91561)
		(width 0.0889)
		(layer "In6.Cu")
		(net "M_E_CPU1_SB_DQ<17>")
	)
	(arc
		(start 81.247996 -284.938978)
		(mid 81.530952 -284.862801)
		(end 81.813908 -284.938978)
		(width 0.0889)
		(layer "In6.Cu")
		(net "M_E_CPU1_SB_DQ<17>")
	)
	(arc
		(start 78.994254 -284.938978)
		(mid 79.174712 -284.989422)
		(end 79.356966 -284.945836)
		(width 0.0889)
		(layer "In6.Cu")
		(net "M_E_CPU1_SB_DQ<17>")
	)
	(arc
		(start 82.18805 -284.938978)
		(mid 82.435763 -284.863758)
		(end 82.69097 -284.907228)
		(width 0.0889)
		(layer "In6.Cu")
		(net "M_E_CPU1_SB_DQ<17>")
	)
	(arc
		(start 80.874108 -284.938978)
		(mid 81.061052 -284.989233)
		(end 81.247996 -284.938978)
		(width 0.0889)
		(layer "In6.Cu")
		(net "M_E_CPU1_SB_DQ<17>")
	)
	(arc
		(start 78.47203 -284.91561)
		(mid 78.736011 -284.863104)
		(end 78.994254 -284.938978)
		(width 0.0889)
		(layer "In6.Cu")
		(net "M_E_CPU1_SB_DQ<17>")
	)
	(segment
		(start 81.997804 -283.540454)
		(end 81.530952 -283.806392)
		(width 0.10668)
		(layer "F.Cu")
		(net "M_E_CPU1_SB_DQ<16>")
	)
	(segment
		(start 50.491898 -299.760386)
		(end 50.751232 -299.760386)
		(width 0.14478)
		(layer "In6.Cu")
		(net "M_E_CPU1_SB_DQ<16>")
	)
	(segment
		(start 31.394146 -300.984158)
		(end 31.55696 -300.821344)
		(width 0.14478)
		(layer "In6.Cu")
		(net "M_E_CPU1_SB_DQ<16>")
	)
	(segment
		(start 56.15305 -300.888146)
		(end 56.37657 -300.664626)
		(width 0.14478)
		(layer "In6.Cu")
		(net "M_E_CPU1_SB_DQ<16>")
	)
	(segment
		(start 78.897734 -284.128718)
		(end 78.903322 -284.125416)
		(width 0.0889)
		(layer "In6.Cu")
		(net "M_E_CPU1_SB_DQ<16>")
	)
	(segment
		(start 71.932292 -287.1343)
		(end 72.628252 -286.43834)
		(width 0.14478)
		(layer "In6.Cu")
		(net "M_E_CPU1_SB_DQ<16>")
	)
	(segment
		(start 50.751232 -299.760386)
		(end 51.05781 -300.066964)
		(width 0.14478)
		(layer "In6.Cu")
		(net "M_E_CPU1_SB_DQ<16>")
	)
	(segment
		(start 30.050994 -300.984158)
		(end 30.281626 -300.984158)
		(width 0.14478)
		(layer "In6.Cu")
		(net "M_E_CPU1_SB_DQ<16>")
	)
	(segment
		(start 74.599292 -284.467554)
		(end 75.991466 -284.467554)
		(width 0.14478)
		(layer "In6.Cu")
		(net "M_E_CPU1_SB_DQ<16>")
	)
	(segment
		(start 48.60798 -300.930564)
		(end 48.8442 -300.930564)
		(width 0.14478)
		(layer "In6.Cu")
		(net "M_E_CPU1_SB_DQ<16>")
	)
	(segment
		(start 51.61407 -299.760386)
		(end 52.239418 -299.760386)
		(width 0.14478)
		(layer "In6.Cu")
		(net "M_E_CPU1_SB_DQ<16>")
	)
	(segment
		(start 81.377028 -284.071822)
		(end 81.530952 -283.806392)
		(width 0.0889)
		(layer "In6.Cu")
		(net "M_E_CPU1_SB_DQ<16>")
	)
	(segment
		(start 75.991466 -284.467554)
		(end 76.320396 -284.467554)
		(width 0.0889)
		(layer "In6.Cu")
		(net "M_E_CPU1_SB_DQ<16>")
	)
	(segment
		(start 51.05781 -300.066964)
		(end 51.307492 -300.066964)
		(width 0.14478)
		(layer "In6.Cu")
		(net "M_E_CPU1_SB_DQ<16>")
	)
	(segment
		(start 80.39354 -284.122876)
		(end 80.403954 -284.128972)
		(width 0.0889)
		(layer "In6.Cu")
		(net "M_E_CPU1_SB_DQ<16>")
	)
	(segment
		(start 30.837886 -300.323758)
		(end 31.0007 -300.486572)
		(width 0.14478)
		(layer "In6.Cu")
		(net "M_E_CPU1_SB_DQ<16>")
	)
	(segment
		(start 31.55696 -300.486572)
		(end 31.719774 -300.323758)
		(width 0.14478)
		(layer "In6.Cu")
		(net "M_E_CPU1_SB_DQ<16>")
	)
	(segment
		(start 54.40045 -300.611286)
		(end 54.67731 -300.888146)
		(width 0.14478)
		(layer "In6.Cu")
		(net "M_E_CPU1_SB_DQ<16>")
	)
	(segment
		(start 58.316114 -299.911262)
		(end 58.48985 -299.737526)
		(width 0.14478)
		(layer "In6.Cu")
		(net "M_E_CPU1_SB_DQ<16>")
	)
	(segment
		(start 31.0007 -300.821344)
		(end 31.163514 -300.984158)
		(width 0.14478)
		(layer "In6.Cu")
		(net "M_E_CPU1_SB_DQ<16>")
	)
	(segment
		(start 65.450466 -292.67531)
		(end 70.991476 -287.1343)
		(width 0.14478)
		(layer "In6.Cu")
		(net "M_E_CPU1_SB_DQ<16>")
	)
	(segment
		(start 72.628252 -286.43834)
		(end 72.628252 -286.438594)
		(width 0.14478)
		(layer "In6.Cu")
		(net "M_E_CPU1_SB_DQ<16>")
	)
	(segment
		(start 34.036 -300.770544)
		(end 34.19602 -300.930564)
		(width 0.14478)
		(layer "In6.Cu")
		(net "M_E_CPU1_SB_DQ<16>")
	)
	(segment
		(start 31.0007 -300.486572)
		(end 31.0007 -300.821344)
		(width 0.14478)
		(layer "In6.Cu")
		(net "M_E_CPU1_SB_DQ<16>")
	)
	(segment
		(start 46.8376 -300.610524)
		(end 48.28794 -300.610524)
		(width 0.14478)
		(layer "In6.Cu")
		(net "M_E_CPU1_SB_DQ<16>")
	)
	(segment
		(start 34.036 -300.480984)
		(end 34.036 -300.770544)
		(width 0.14478)
		(layer "In6.Cu")
		(net "M_E_CPU1_SB_DQ<16>")
	)
	(segment
		(start 48.28794 -300.610524)
		(end 48.60798 -300.930564)
		(width 0.14478)
		(layer "In6.Cu")
		(net "M_E_CPU1_SB_DQ<16>")
	)
	(segment
		(start 33.87598 -300.320964)
		(end 34.036 -300.480984)
		(width 0.14478)
		(layer "In6.Cu")
		(net "M_E_CPU1_SB_DQ<16>")
	)
	(segment
		(start 33.3502 -300.610524)
		(end 33.63976 -300.320964)
		(width 0.14478)
		(layer "In6.Cu")
		(net "M_E_CPU1_SB_DQ<16>")
	)
	(segment
		(start 52.239418 -299.760386)
		(end 52.545996 -300.066964)
		(width 0.14478)
		(layer "In6.Cu")
		(net "M_E_CPU1_SB_DQ<16>")
	)
	(segment
		(start 41.51884 -300.930564)
		(end 42.689272 -299.760132)
		(width 0.14478)
		(layer "In6.Cu")
		(net "M_E_CPU1_SB_DQ<16>")
	)
	(segment
		(start 76.910184 -283.877766)
		(end 77.494384 -283.877766)
		(width 0.0889)
		(layer "In6.Cu")
		(net "M_E_CPU1_SB_DQ<16>")
	)
	(segment
		(start 52.545996 -300.066964)
		(end 52.795678 -300.066964)
		(width 0.14478)
		(layer "In6.Cu")
		(net "M_E_CPU1_SB_DQ<16>")
	)
	(segment
		(start 38.09111 -300.499526)
		(end 38.522148 -300.930564)
		(width 0.14478)
		(layer "In6.Cu")
		(net "M_E_CPU1_SB_DQ<16>")
	)
	(segment
		(start 80.769714 -284.133798)
		(end 80.778096 -284.128972)
		(width 0.0889)
		(layer "In6.Cu")
		(net "M_E_CPU1_SB_DQ<16>")
	)
	(segment
		(start 30.607254 -300.323758)
		(end 30.837886 -300.323758)
		(width 0.14478)
		(layer "In6.Cu")
		(net "M_E_CPU1_SB_DQ<16>")
	)
	(segment
		(start 49.64176 -300.610524)
		(end 50.491898 -299.760386)
		(width 0.14478)
		(layer "In6.Cu")
		(net "M_E_CPU1_SB_DQ<16>")
	)
	(segment
		(start 34.43224 -300.930564)
		(end 35.602418 -299.760386)
		(width 0.14478)
		(layer "In6.Cu")
		(net "M_E_CPU1_SB_DQ<16>")
	)
	(segment
		(start 52.795678 -300.066964)
		(end 53.102256 -299.760386)
		(width 0.14478)
		(layer "In6.Cu")
		(net "M_E_CPU1_SB_DQ<16>")
	)
	(segment
		(start 42.689526 -299.760386)
		(end 45.987462 -299.760386)
		(width 0.14478)
		(layer "In6.Cu")
		(net "M_E_CPU1_SB_DQ<16>")
	)
	(segment
		(start 58.48985 -299.28312)
		(end 58.85307 -298.9199)
		(width 0.14478)
		(layer "In6.Cu")
		(net "M_E_CPU1_SB_DQ<16>")
	)
	(segment
		(start 56.37657 -300.664626)
		(end 56.37657 -300.113446)
		(width 0.14478)
		(layer "In6.Cu")
		(net "M_E_CPU1_SB_DQ<16>")
	)
	(segment
		(start 76.320396 -284.467554)
		(end 76.910184 -283.877766)
		(width 0.0889)
		(layer "In6.Cu")
		(net "M_E_CPU1_SB_DQ<16>")
	)
	(segment
		(start 58.85307 -298.9199)
		(end 60.294774 -298.322746)
		(width 0.14478)
		(layer "In6.Cu")
		(net "M_E_CPU1_SB_DQ<16>")
	)
	(segment
		(start 34.19602 -300.930564)
		(end 34.43224 -300.930564)
		(width 0.14478)
		(layer "In6.Cu")
		(net "M_E_CPU1_SB_DQ<16>")
	)
	(segment
		(start 37.84727 -299.760386)
		(end 38.09111 -300.004226)
		(width 0.14478)
		(layer "In6.Cu")
		(net "M_E_CPU1_SB_DQ<16>")
	)
	(segment
		(start 29.252164 -300.185328)
		(end 30.050994 -300.984158)
		(width 0.14478)
		(layer "In6.Cu")
		(net "M_E_CPU1_SB_DQ<16>")
	)
	(segment
		(start 35.602418 -299.760386)
		(end 37.84727 -299.760386)
		(width 0.14478)
		(layer "In6.Cu")
		(net "M_E_CPU1_SB_DQ<16>")
	)
	(segment
		(start 77.494384 -283.877766)
		(end 77.796136 -284.179518)
		(width 0.0889)
		(layer "In6.Cu")
		(net "M_E_CPU1_SB_DQ<16>")
	)
	(segment
		(start 72.628252 -286.438594)
		(end 74.599292 -284.467554)
		(width 0.14478)
		(layer "In6.Cu")
		(net "M_E_CPU1_SB_DQ<16>")
	)
	(segment
		(start 30.281626 -300.984158)
		(end 30.44444 -300.821344)
		(width 0.14478)
		(layer "In6.Cu")
		(net "M_E_CPU1_SB_DQ<16>")
	)
	(segment
		(start 60.294774 -298.322746)
		(end 60.886086 -297.731688)
		(width 0.14478)
		(layer "In6.Cu")
		(net "M_E_CPU1_SB_DQ<16>")
	)
	(segment
		(start 39.7129 -300.610524)
		(end 40.96258 -300.610524)
		(width 0.14478)
		(layer "In6.Cu")
		(net "M_E_CPU1_SB_DQ<16>")
	)
	(segment
		(start 30.44444 -300.821344)
		(end 30.44444 -300.486572)
		(width 0.14478)
		(layer "In6.Cu")
		(net "M_E_CPU1_SB_DQ<16>")
	)
	(segment
		(start 54.40045 -300.209966)
		(end 54.40045 -300.611286)
		(width 0.14478)
		(layer "In6.Cu")
		(net "M_E_CPU1_SB_DQ<16>")
	)
	(segment
		(start 31.719774 -300.323758)
		(end 31.950406 -300.323758)
		(width 0.14478)
		(layer "In6.Cu")
		(net "M_E_CPU1_SB_DQ<16>")
	)
	(segment
		(start 54.67731 -300.888146)
		(end 56.15305 -300.888146)
		(width 0.14478)
		(layer "In6.Cu")
		(net "M_E_CPU1_SB_DQ<16>")
	)
	(segment
		(start 38.09111 -300.004226)
		(end 38.09111 -300.499526)
		(width 0.14478)
		(layer "In6.Cu")
		(net "M_E_CPU1_SB_DQ<16>")
	)
	(segment
		(start 49.16424 -300.610524)
		(end 49.64176 -300.610524)
		(width 0.14478)
		(layer "In6.Cu")
		(net "M_E_CPU1_SB_DQ<16>")
	)
	(segment
		(start 77.796136 -284.179518)
		(end 78.711044 -284.179518)
		(width 0.0889)
		(layer "In6.Cu")
		(net "M_E_CPU1_SB_DQ<16>")
	)
	(segment
		(start 51.307492 -300.066964)
		(end 51.61407 -299.760386)
		(width 0.14478)
		(layer "In6.Cu")
		(net "M_E_CPU1_SB_DQ<16>")
	)
	(segment
		(start 56.37657 -300.113446)
		(end 56.578754 -299.911262)
		(width 0.14478)
		(layer "In6.Cu")
		(net "M_E_CPU1_SB_DQ<16>")
	)
	(segment
		(start 81.281016 -284.097222)
		(end 81.377028 -284.071822)
		(width 0.0889)
		(layer "In6.Cu")
		(net "M_E_CPU1_SB_DQ<16>")
	)
	(segment
		(start 31.55696 -300.821344)
		(end 31.55696 -300.486572)
		(width 0.14478)
		(layer "In6.Cu")
		(net "M_E_CPU1_SB_DQ<16>")
	)
	(segment
		(start 70.991476 -287.1343)
		(end 71.932292 -287.1343)
		(width 0.14478)
		(layer "In6.Cu")
		(net "M_E_CPU1_SB_DQ<16>")
	)
	(segment
		(start 31.950406 -300.323758)
		(end 32.237172 -300.610524)
		(width 0.14478)
		(layer "In6.Cu")
		(net "M_E_CPU1_SB_DQ<16>")
	)
	(segment
		(start 42.689272 -299.760132)
		(end 42.689526 -299.760386)
		(width 0.14478)
		(layer "In6.Cu")
		(net "M_E_CPU1_SB_DQ<16>")
	)
	(segment
		(start 56.578754 -299.911262)
		(end 58.316114 -299.911262)
		(width 0.14478)
		(layer "In6.Cu")
		(net "M_E_CPU1_SB_DQ<16>")
	)
	(segment
		(start 45.987462 -299.760386)
		(end 46.8376 -300.610524)
		(width 0.14478)
		(layer "In6.Cu")
		(net "M_E_CPU1_SB_DQ<16>")
	)
	(segment
		(start 40.96258 -300.610524)
		(end 41.28262 -300.930564)
		(width 0.14478)
		(layer "In6.Cu")
		(net "M_E_CPU1_SB_DQ<16>")
	)
	(segment
		(start 30.44444 -300.486572)
		(end 30.607254 -300.323758)
		(width 0.14478)
		(layer "In6.Cu")
		(net "M_E_CPU1_SB_DQ<16>")
	)
	(segment
		(start 79.463138 -284.128972)
		(end 79.47152 -284.133798)
		(width 0.0889)
		(layer "In6.Cu")
		(net "M_E_CPU1_SB_DQ<16>")
	)
	(segment
		(start 41.28262 -300.930564)
		(end 41.51884 -300.930564)
		(width 0.14478)
		(layer "In6.Cu")
		(net "M_E_CPU1_SB_DQ<16>")
	)
	(segment
		(start 32.237172 -300.610524)
		(end 33.3502 -300.610524)
		(width 0.14478)
		(layer "In6.Cu")
		(net "M_E_CPU1_SB_DQ<16>")
	)
	(segment
		(start 54.191916 -300.001432)
		(end 54.40045 -300.209966)
		(width 0.14478)
		(layer "In6.Cu")
		(net "M_E_CPU1_SB_DQ<16>")
	)
	(segment
		(start 48.8442 -300.930564)
		(end 49.16424 -300.610524)
		(width 0.14478)
		(layer "In6.Cu")
		(net "M_E_CPU1_SB_DQ<16>")
	)
	(segment
		(start 53.102256 -299.760386)
		(end 53.351938 -299.760386)
		(width 0.14478)
		(layer "In6.Cu")
		(net "M_E_CPU1_SB_DQ<16>")
	)
	(segment
		(start 53.592984 -300.001432)
		(end 54.191916 -300.001432)
		(width 0.14478)
		(layer "In6.Cu")
		(net "M_E_CPU1_SB_DQ<16>")
	)
	(segment
		(start 31.163514 -300.984158)
		(end 31.394146 -300.984158)
		(width 0.14478)
		(layer "In6.Cu")
		(net "M_E_CPU1_SB_DQ<16>")
	)
	(segment
		(start 58.48985 -299.737526)
		(end 58.48985 -299.28312)
		(width 0.14478)
		(layer "In6.Cu")
		(net "M_E_CPU1_SB_DQ<16>")
	)
	(segment
		(start 60.886086 -297.731688)
		(end 65.103756 -293.514018)
		(width 0.14478)
		(layer "In6.Cu")
		(net "M_E_CPU1_SB_DQ<16>")
	)
	(segment
		(start 39.39286 -300.930564)
		(end 39.7129 -300.610524)
		(width 0.14478)
		(layer "In6.Cu")
		(net "M_E_CPU1_SB_DQ<16>")
	)
	(segment
		(start 33.63976 -300.320964)
		(end 33.87598 -300.320964)
		(width 0.14478)
		(layer "In6.Cu")
		(net "M_E_CPU1_SB_DQ<16>")
	)
	(segment
		(start 65.103756 -293.514018)
		(end 65.450466 -292.67531)
		(width 0.14478)
		(layer "In6.Cu")
		(net "M_E_CPU1_SB_DQ<16>")
	)
	(segment
		(start 38.522148 -300.930564)
		(end 39.39286 -300.930564)
		(width 0.14478)
		(layer "In6.Cu")
		(net "M_E_CPU1_SB_DQ<16>")
	)
	(segment
		(start 53.351938 -299.760386)
		(end 53.592984 -300.001432)
		(width 0.14478)
		(layer "In6.Cu")
		(net "M_E_CPU1_SB_DQ<16>")
	)
	(arc
		(start 80.778096 -284.128972)
		(mid 81.025809 -284.053752)
		(end 81.281016 -284.097222)
		(width 0.0889)
		(layer "In6.Cu")
		(net "M_E_CPU1_SB_DQ<16>")
	)
	(arc
		(start 79.837788 -284.128972)
		(mid 80.114855 -284.052701)
		(end 80.39354 -284.122876)
		(width 0.0889)
		(layer "In6.Cu")
		(net "M_E_CPU1_SB_DQ<16>")
	)
	(arc
		(start 80.403954 -284.128972)
		(mid 80.586205 -284.179322)
		(end 80.769714 -284.133798)
		(width 0.0889)
		(layer "In6.Cu")
		(net "M_E_CPU1_SB_DQ<16>")
	)
	(arc
		(start 79.47152 -284.133798)
		(mid 79.655282 -284.179414)
		(end 79.837788 -284.128972)
		(width 0.0889)
		(layer "In6.Cu")
		(net "M_E_CPU1_SB_DQ<16>")
	)
	(arc
		(start 78.903322 -284.125416)
		(mid 79.183711 -284.052747)
		(end 79.463138 -284.128972)
		(width 0.0889)
		(layer "In6.Cu")
		(net "M_E_CPU1_SB_DQ<16>")
	)
	(arc
		(start 78.711044 -284.179518)
		(mid 78.807735 -284.166422)
		(end 78.897734 -284.128718)
		(width 0.0889)
		(layer "In6.Cu")
		(net "M_E_CPU1_SB_DQ<16>")
	)
	(segment
		(start 82.937858 -283.540454)
		(end 82.471006 -283.806392)
		(width 0.10668)
		(layer "F.Cu")
		(net "M_E_CPU1_SB_DQ<15>")
	)
	(segment
		(start 35.934142 -298.910248)
		(end 37.561774 -298.910248)
		(width 0.14478)
		(layer "In6.Cu")
		(net "M_E_CPU1_SB_DQ<15>")
	)
	(segment
		(start 47.455582 -299.760386)
		(end 49.18583 -299.760386)
		(width 0.14478)
		(layer "In6.Cu")
		(net "M_E_CPU1_SB_DQ<15>")
	)
	(segment
		(start 74.375772 -283.911294)
		(end 75.944476 -283.911294)
		(width 0.14478)
		(layer "In6.Cu")
		(net "M_E_CPU1_SB_DQ<15>")
	)
	(segment
		(start 76.839064 -283.552646)
		(end 78.36789 -283.552646)
		(width 0.0889)
		(layer "In6.Cu")
		(net "M_E_CPU1_SB_DQ<15>")
	)
	(segment
		(start 71.703946 -286.58312)
		(end 74.375772 -283.911294)
		(width 0.14478)
		(layer "In6.Cu")
		(net "M_E_CPU1_SB_DQ<15>")
	)
	(segment
		(start 39.614348 -299.760386)
		(end 41.163748 -299.760386)
		(width 0.14478)
		(layer "In6.Cu")
		(net "M_E_CPU1_SB_DQ<15>")
	)
	(segment
		(start 79.838296 -283.483812)
		(end 79.84871 -283.489908)
		(width 0.0889)
		(layer "In6.Cu")
		(net "M_E_CPU1_SB_DQ<15>")
	)
	(segment
		(start 42.423588 -299.23867)
		(end 42.7482 -298.914058)
		(width 0.14478)
		(layer "In6.Cu")
		(net "M_E_CPU1_SB_DQ<15>")
	)
	(segment
		(start 25.152096 -299.335444)
		(end 25.577038 -299.760386)
		(width 0.14478)
		(layer "In6.Cu")
		(net "M_E_CPU1_SB_DQ<15>")
	)
	(segment
		(start 79.454248 -283.489908)
		(end 79.464662 -283.483812)
		(width 0.0889)
		(layer "In6.Cu")
		(net "M_E_CPU1_SB_DQ<15>")
	)
	(segment
		(start 78.36789 -283.552646)
		(end 78.534006 -283.483812)
		(width 0.0889)
		(layer "In6.Cu")
		(net "M_E_CPU1_SB_DQ<15>")
	)
	(segment
		(start 79.829914 -283.478986)
		(end 79.838296 -283.483812)
		(width 0.0889)
		(layer "In6.Cu")
		(net "M_E_CPU1_SB_DQ<15>")
	)
	(segment
		(start 50.55489 -298.910248)
		(end 53.288946 -298.910248)
		(width 0.14478)
		(layer "In6.Cu")
		(net "M_E_CPU1_SB_DQ<15>")
	)
	(segment
		(start 35.431984 -299.118274)
		(end 35.934142 -298.910248)
		(width 0.14478)
		(layer "In6.Cu")
		(net "M_E_CPU1_SB_DQ<15>")
	)
	(segment
		(start 53.699918 -299.32122)
		(end 53.793644 -299.360082)
		(width 0.14478)
		(layer "In6.Cu")
		(net "M_E_CPU1_SB_DQ<15>")
	)
	(segment
		(start 80.769714 -283.478986)
		(end 80.778096 -283.483812)
		(width 0.0889)
		(layer "In6.Cu")
		(net "M_E_CPU1_SB_DQ<15>")
	)
	(segment
		(start 57.225184 -299.360082)
		(end 57.843928 -298.741338)
		(width 0.14478)
		(layer "In6.Cu")
		(net "M_E_CPU1_SB_DQ<15>")
	)
	(segment
		(start 64.78397 -292.84422)
		(end 64.983106 -292.363144)
		(width 0.14478)
		(layer "In6.Cu")
		(net "M_E_CPU1_SB_DQ<15>")
	)
	(segment
		(start 41.163748 -299.760386)
		(end 42.423588 -299.23867)
		(width 0.14478)
		(layer "In6.Cu")
		(net "M_E_CPU1_SB_DQ<15>")
	)
	(segment
		(start 50.071528 -299.39361)
		(end 50.55489 -298.910248)
		(width 0.14478)
		(layer "In6.Cu")
		(net "M_E_CPU1_SB_DQ<15>")
	)
	(segment
		(start 25.577038 -299.760386)
		(end 34.413698 -299.760386)
		(width 0.14478)
		(layer "In6.Cu")
		(net "M_E_CPU1_SB_DQ<15>")
	)
	(segment
		(start 75.944476 -283.911294)
		(end 76.480416 -283.911294)
		(width 0.0889)
		(layer "In6.Cu")
		(net "M_E_CPU1_SB_DQ<15>")
	)
	(segment
		(start 53.793644 -299.360082)
		(end 57.225184 -299.360082)
		(width 0.14478)
		(layer "In6.Cu")
		(net "M_E_CPU1_SB_DQ<15>")
	)
	(segment
		(start 64.63538 -293.202614)
		(end 64.78397 -292.84422)
		(width 0.14478)
		(layer "In6.Cu")
		(net "M_E_CPU1_SB_DQ<15>")
	)
	(segment
		(start 81.344008 -283.483812)
		(end 81.35239 -283.478986)
		(width 0.0889)
		(layer "In6.Cu")
		(net "M_E_CPU1_SB_DQ<15>")
	)
	(segment
		(start 70.76313 -286.58312)
		(end 71.703946 -286.58312)
		(width 0.14478)
		(layer "In6.Cu")
		(net "M_E_CPU1_SB_DQ<15>")
	)
	(segment
		(start 82.62493 -283.540962)
		(end 82.471006 -283.806392)
		(width 0.0889)
		(layer "In6.Cu")
		(net "M_E_CPU1_SB_DQ<15>")
	)
	(segment
		(start 64.983106 -292.363144)
		(end 70.76313 -286.58312)
		(width 0.14478)
		(layer "In6.Cu")
		(net "M_E_CPU1_SB_DQ<15>")
	)
	(segment
		(start 76.480416 -283.911294)
		(end 76.839064 -283.552646)
		(width 0.0889)
		(layer "In6.Cu")
		(net "M_E_CPU1_SB_DQ<15>")
	)
	(segment
		(start 34.413698 -299.760386)
		(end 35.05581 -299.494448)
		(width 0.14478)
		(layer "In6.Cu")
		(net "M_E_CPU1_SB_DQ<15>")
	)
	(segment
		(start 46.336458 -299.296836)
		(end 47.455582 -299.760386)
		(width 0.14478)
		(layer "In6.Cu")
		(net "M_E_CPU1_SB_DQ<15>")
	)
	(segment
		(start 78.534006 -283.483812)
		(end 78.53553 -283.484574)
		(width 0.0889)
		(layer "In6.Cu")
		(net "M_E_CPU1_SB_DQ<15>")
	)
	(segment
		(start 37.561774 -298.910248)
		(end 39.614348 -299.760386)
		(width 0.14478)
		(layer "In6.Cu")
		(net "M_E_CPU1_SB_DQ<15>")
	)
	(segment
		(start 59.982608 -297.855386)
		(end 64.63538 -293.202614)
		(width 0.14478)
		(layer "In6.Cu")
		(net "M_E_CPU1_SB_DQ<15>")
	)
	(segment
		(start 35.05581 -299.494448)
		(end 35.431984 -299.118274)
		(width 0.14478)
		(layer "In6.Cu")
		(net "M_E_CPU1_SB_DQ<15>")
	)
	(segment
		(start 53.288946 -298.910248)
		(end 53.699918 -299.32122)
		(width 0.14478)
		(layer "In6.Cu")
		(net "M_E_CPU1_SB_DQ<15>")
	)
	(segment
		(start 49.18583 -299.760386)
		(end 50.071528 -299.39361)
		(width 0.14478)
		(layer "In6.Cu")
		(net "M_E_CPU1_SB_DQ<15>")
	)
	(segment
		(start 42.7482 -298.914058)
		(end 45.95368 -298.914058)
		(width 0.14478)
		(layer "In6.Cu")
		(net "M_E_CPU1_SB_DQ<15>")
	)
	(segment
		(start 45.95368 -298.914058)
		(end 46.336458 -299.296836)
		(width 0.14478)
		(layer "In6.Cu")
		(net "M_E_CPU1_SB_DQ<15>")
	)
	(segment
		(start 57.843928 -298.741338)
		(end 59.982608 -297.855386)
		(width 0.14478)
		(layer "In6.Cu")
		(net "M_E_CPU1_SB_DQ<15>")
	)
	(segment
		(start 82.602578 -283.45765)
		(end 82.62493 -283.540962)
		(width 0.0889)
		(layer "In6.Cu")
		(net "M_E_CPU1_SB_DQ<15>")
	)
	(segment
		(start 78.659482 -283.433266)
		(end 78.711044 -283.433266)
		(width 0.0889)
		(layer "In6.Cu")
		(net "M_E_CPU1_SB_DQ<15>")
	)
	(arc
		(start 82.284062 -283.483812)
		(mid 82.440381 -283.434817)
		(end 82.602578 -283.45765)
		(width 0.0889)
		(layer "In6.Cu")
		(net "M_E_CPU1_SB_DQ<15>")
	)
	(arc
		(start 79.84871 -283.489908)
		(mid 80.127142 -283.560006)
		(end 80.403954 -283.483812)
		(width 0.0889)
		(layer "In6.Cu")
		(net "M_E_CPU1_SB_DQ<15>")
	)
	(arc
		(start 78.711044 -283.433266)
		(mid 78.808118 -283.446124)
		(end 78.898496 -283.483812)
		(width 0.0889)
		(layer "In6.Cu")
		(net "M_E_CPU1_SB_DQ<15>")
	)
	(arc
		(start 81.71815 -283.483812)
		(mid 82.001106 -283.559989)
		(end 82.284062 -283.483812)
		(width 0.0889)
		(layer "In6.Cu")
		(net "M_E_CPU1_SB_DQ<15>")
	)
	(arc
		(start 80.403954 -283.483812)
		(mid 80.586205 -283.433462)
		(end 80.769714 -283.478986)
		(width 0.0889)
		(layer "In6.Cu")
		(net "M_E_CPU1_SB_DQ<15>")
	)
	(arc
		(start 80.778096 -283.483812)
		(mid 81.061052 -283.559989)
		(end 81.344008 -283.483812)
		(width 0.0889)
		(layer "In6.Cu")
		(net "M_E_CPU1_SB_DQ<15>")
	)
	(arc
		(start 81.35239 -283.478986)
		(mid 81.535898 -283.433492)
		(end 81.71815 -283.483812)
		(width 0.0889)
		(layer "In6.Cu")
		(net "M_E_CPU1_SB_DQ<15>")
	)
	(arc
		(start 78.898496 -283.483812)
		(mid 79.175563 -283.560083)
		(end 79.454248 -283.489908)
		(width 0.0889)
		(layer "In6.Cu")
		(net "M_E_CPU1_SB_DQ<15>")
	)
	(arc
		(start 78.53553 -283.484574)
		(mid 78.5924 -283.446575)
		(end 78.659482 -283.433266)
		(width 0.0889)
		(layer "In6.Cu")
		(net "M_E_CPU1_SB_DQ<15>")
	)
	(arc
		(start 79.464662 -283.483812)
		(mid 79.646659 -283.43359)
		(end 79.829914 -283.478986)
		(width 0.0889)
		(layer "In6.Cu")
		(net "M_E_CPU1_SB_DQ<15>")
	)
	(segment
		(start 81.527904 -282.730448)
		(end 81.061052 -282.996386)
		(width 0.10668)
		(layer "F.Cu")
		(net "M_E_CPU1_SB_DQ<14>")
	)
	(segment
		(start 77.756258 -282.363164)
		(end 78.1431 -282.750006)
		(width 0.0889)
		(layer "In6.Cu")
		(net "M_E_CPU1_SB_DQ<14>")
	)
	(segment
		(start 42.17924 -298.060364)
		(end 43.029378 -297.210226)
		(width 0.14478)
		(layer "In6.Cu")
		(net "M_E_CPU1_SB_DQ<14>")
	)
	(segment
		(start 78.1431 -282.750006)
		(end 78.711044 -282.750006)
		(width 0.0889)
		(layer "In6.Cu")
		(net "M_E_CPU1_SB_DQ<14>")
	)
	(segment
		(start 43.029378 -297.210226)
		(end 45.647102 -297.210226)
		(width 0.14478)
		(layer "In6.Cu")
		(net "M_E_CPU1_SB_DQ<14>")
	)
	(segment
		(start 50.118264 -298.060364)
		(end 50.968402 -297.210226)
		(width 0.14478)
		(layer "In6.Cu")
		(net "M_E_CPU1_SB_DQ<14>")
	)
	(segment
		(start 76.264262 -283.001974)
		(end 76.903072 -282.363164)
		(width 0.0889)
		(layer "In6.Cu")
		(net "M_E_CPU1_SB_DQ<14>")
	)
	(segment
		(start 63.873126 -292.692836)
		(end 64.220852 -291.853366)
		(width 0.14478)
		(layer "In6.Cu")
		(net "M_E_CPU1_SB_DQ<14>")
	)
	(segment
		(start 75.931776 -283.001974)
		(end 76.264262 -283.001974)
		(width 0.0889)
		(layer "In6.Cu")
		(net "M_E_CPU1_SB_DQ<14>")
	)
	(segment
		(start 38.001702 -297.210226)
		(end 38.85184 -298.060364)
		(width 0.14478)
		(layer "In6.Cu")
		(net "M_E_CPU1_SB_DQ<14>")
	)
	(segment
		(start 50.968402 -297.210226)
		(end 52.875434 -297.210226)
		(width 0.14478)
		(layer "In6.Cu")
		(net "M_E_CPU1_SB_DQ<14>")
	)
	(segment
		(start 25.577038 -298.060364)
		(end 34.96564 -298.060364)
		(width 0.14478)
		(layer "In6.Cu")
		(net "M_E_CPU1_SB_DQ<14>")
	)
	(segment
		(start 58.711846 -296.601134)
		(end 60.851034 -295.714928)
		(width 0.14478)
		(layer "In6.Cu")
		(net "M_E_CPU1_SB_DQ<14>")
	)
	(segment
		(start 25.152096 -297.635422)
		(end 25.577038 -298.060364)
		(width 0.14478)
		(layer "In6.Cu")
		(net "M_E_CPU1_SB_DQ<14>")
	)
	(segment
		(start 70.390258 -285.68396)
		(end 71.31685 -285.68396)
		(width 0.14478)
		(layer "In6.Cu")
		(net "M_E_CPU1_SB_DQ<14>")
	)
	(segment
		(start 52.875434 -297.210226)
		(end 53.725572 -298.060364)
		(width 0.14478)
		(layer "In6.Cu")
		(net "M_E_CPU1_SB_DQ<14>")
	)
	(segment
		(start 35.815778 -297.210226)
		(end 38.001702 -297.210226)
		(width 0.14478)
		(layer "In6.Cu")
		(net "M_E_CPU1_SB_DQ<14>")
	)
	(segment
		(start 81.192624 -282.647644)
		(end 81.214976 -282.730956)
		(width 0.0889)
		(layer "In6.Cu")
		(net "M_E_CPU1_SB_DQ<14>")
	)
	(segment
		(start 45.647102 -297.210226)
		(end 46.49724 -298.060364)
		(width 0.14478)
		(layer "In6.Cu")
		(net "M_E_CPU1_SB_DQ<14>")
	)
	(segment
		(start 64.220852 -291.853366)
		(end 70.390258 -285.68396)
		(width 0.14478)
		(layer "In6.Cu")
		(net "M_E_CPU1_SB_DQ<14>")
	)
	(segment
		(start 34.96564 -298.060364)
		(end 35.815778 -297.210226)
		(width 0.14478)
		(layer "In6.Cu")
		(net "M_E_CPU1_SB_DQ<14>")
	)
	(segment
		(start 80.299814 -282.66898)
		(end 80.308196 -282.673806)
		(width 0.0889)
		(layer "In6.Cu")
		(net "M_E_CPU1_SB_DQ<14>")
	)
	(segment
		(start 81.214976 -282.730956)
		(end 81.061052 -282.996386)
		(width 0.0889)
		(layer "In6.Cu")
		(net "M_E_CPU1_SB_DQ<14>")
	)
	(segment
		(start 78.993492 -282.67406)
		(end 79.009748 -282.664662)
		(width 0.0889)
		(layer "In6.Cu")
		(net "M_E_CPU1_SB_DQ<14>")
	)
	(segment
		(start 46.49724 -298.060364)
		(end 50.118264 -298.060364)
		(width 0.14478)
		(layer "In6.Cu")
		(net "M_E_CPU1_SB_DQ<14>")
	)
	(segment
		(start 76.903072 -282.363164)
		(end 77.756258 -282.363164)
		(width 0.0889)
		(layer "In6.Cu")
		(net "M_E_CPU1_SB_DQ<14>")
	)
	(segment
		(start 73.998836 -283.001974)
		(end 75.931776 -283.001974)
		(width 0.14478)
		(layer "In6.Cu")
		(net "M_E_CPU1_SB_DQ<14>")
	)
	(segment
		(start 71.31685 -285.68396)
		(end 73.998836 -283.001974)
		(width 0.14478)
		(layer "In6.Cu")
		(net "M_E_CPU1_SB_DQ<14>")
	)
	(segment
		(start 38.85184 -298.060364)
		(end 42.17924 -298.060364)
		(width 0.14478)
		(layer "In6.Cu")
		(net "M_E_CPU1_SB_DQ<14>")
	)
	(segment
		(start 60.851034 -295.714928)
		(end 63.873126 -292.692836)
		(width 0.14478)
		(layer "In6.Cu")
		(net "M_E_CPU1_SB_DQ<14>")
	)
	(segment
		(start 53.725572 -298.060364)
		(end 57.252616 -298.060364)
		(width 0.14478)
		(layer "In6.Cu")
		(net "M_E_CPU1_SB_DQ<14>")
	)
	(segment
		(start 79.36738 -282.673806)
		(end 79.377794 -282.679902)
		(width 0.0889)
		(layer "In6.Cu")
		(net "M_E_CPU1_SB_DQ<14>")
	)
	(segment
		(start 57.252616 -298.060364)
		(end 58.711846 -296.601134)
		(width 0.14478)
		(layer "In6.Cu")
		(net "M_E_CPU1_SB_DQ<14>")
	)
	(arc
		(start 79.377794 -282.679902)
		(mid 79.65648 -282.750122)
		(end 79.933546 -282.673806)
		(width 0.0889)
		(layer "In6.Cu")
		(net "M_E_CPU1_SB_DQ<14>")
	)
	(arc
		(start 80.874108 -282.673806)
		(mid 81.030427 -282.624811)
		(end 81.192624 -282.647644)
		(width 0.0889)
		(layer "In6.Cu")
		(net "M_E_CPU1_SB_DQ<14>")
	)
	(arc
		(start 80.308196 -282.673806)
		(mid 80.591152 -282.749983)
		(end 80.874108 -282.673806)
		(width 0.0889)
		(layer "In6.Cu")
		(net "M_E_CPU1_SB_DQ<14>")
	)
	(arc
		(start 78.711044 -282.750006)
		(mid 78.857292 -282.730701)
		(end 78.993492 -282.67406)
		(width 0.0889)
		(layer "In6.Cu")
		(net "M_E_CPU1_SB_DQ<14>")
	)
	(arc
		(start 79.009748 -282.664662)
		(mid 79.18973 -282.623562)
		(end 79.36738 -282.673806)
		(width 0.0889)
		(layer "In6.Cu")
		(net "M_E_CPU1_SB_DQ<14>")
	)
	(arc
		(start 79.933546 -282.673806)
		(mid 80.116051 -282.623329)
		(end 80.299814 -282.66898)
		(width 0.0889)
		(layer "In6.Cu")
		(net "M_E_CPU1_SB_DQ<14>")
	)
	(segment
		(start 83.408012 -282.730448)
		(end 82.940906 -282.996386)
		(width 0.10668)
		(layer "F.Cu")
		(net "M_E_CPU1_SB_DQ<13>")
	)
	(segment
		(start 31.149798 -299.27042)
		(end 31.38043 -299.27042)
		(width 0.14478)
		(layer "In6.Cu")
		(net "M_E_CPU1_SB_DQ<13>")
	)
	(segment
		(start 57.038494 -298.910502)
		(end 58.966608 -296.982388)
		(width 0.14478)
		(layer "In6.Cu")
		(net "M_E_CPU1_SB_DQ<13>")
	)
	(segment
		(start 33.157668 -299.203364)
		(end 33.42132 -299.203364)
		(width 0.14478)
		(layer "In6.Cu")
		(net "M_E_CPU1_SB_DQ<13>")
	)
	(segment
		(start 64.254126 -292.947852)
		(end 64.601852 -292.108382)
		(width 0.14478)
		(layer "In6.Cu")
		(net "M_E_CPU1_SB_DQ<13>")
	)
	(segment
		(start 30.26791 -299.27042)
		(end 30.430724 -299.107606)
		(width 0.14478)
		(layer "In6.Cu")
		(net "M_E_CPU1_SB_DQ<13>")
	)
	(segment
		(start 33.567624 -298.763944)
		(end 33.713928 -298.61764)
		(width 0.14478)
		(layer "In6.Cu")
		(net "M_E_CPU1_SB_DQ<13>")
	)
	(segment
		(start 76.373736 -283.456634)
		(end 76.48067 -283.3497)
		(width 0.0889)
		(layer "In6.Cu")
		(net "M_E_CPU1_SB_DQ<13>")
	)
	(segment
		(start 78.312264 -283.3497)
		(end 78.488794 -283.276548)
		(width 0.0889)
		(layer "In6.Cu")
		(net "M_E_CPU1_SB_DQ<13>")
	)
	(segment
		(start 58.966608 -296.982388)
		(end 61.105796 -296.096182)
		(width 0.14478)
		(layer "In6.Cu")
		(net "M_E_CPU1_SB_DQ<13>")
	)
	(segment
		(start 30.430724 -299.107606)
		(end 30.430724 -298.69511)
		(width 0.14478)
		(layer "In6.Cu")
		(net "M_E_CPU1_SB_DQ<13>")
	)
	(segment
		(start 30.430724 -298.69511)
		(end 30.593538 -298.532296)
		(width 0.14478)
		(layer "In6.Cu")
		(net "M_E_CPU1_SB_DQ<13>")
	)
	(segment
		(start 32.314896 -298.910502)
		(end 32.864806 -298.910502)
		(width 0.14478)
		(layer "In6.Cu")
		(net "M_E_CPU1_SB_DQ<13>")
	)
	(segment
		(start 75.941936 -283.456634)
		(end 76.373736 -283.456634)
		(width 0.0889)
		(layer "In6.Cu")
		(net "M_E_CPU1_SB_DQ<13>")
	)
	(segment
		(start 34.123884 -298.763944)
		(end 34.123884 -299.05706)
		(width 0.14478)
		(layer "In6.Cu")
		(net "M_E_CPU1_SB_DQ<13>")
	)
	(segment
		(start 30.986984 -298.69511)
		(end 30.986984 -299.107606)
		(width 0.14478)
		(layer "In6.Cu")
		(net "M_E_CPU1_SB_DQ<13>")
	)
	(segment
		(start 31.706058 -298.532296)
		(end 31.93669 -298.532296)
		(width 0.14478)
		(layer "In6.Cu")
		(net "M_E_CPU1_SB_DQ<13>")
	)
	(segment
		(start 49.911508 -298.910502)
		(end 50.761646 -298.060364)
		(width 0.14478)
		(layer "In6.Cu")
		(net "M_E_CPU1_SB_DQ<13>")
	)
	(segment
		(start 31.93669 -298.532296)
		(end 32.314896 -298.910502)
		(width 0.14478)
		(layer "In6.Cu")
		(net "M_E_CPU1_SB_DQ<13>")
	)
	(segment
		(start 31.38043 -299.27042)
		(end 31.543244 -299.107606)
		(width 0.14478)
		(layer "In6.Cu")
		(net "M_E_CPU1_SB_DQ<13>")
	)
	(segment
		(start 30.037278 -299.27042)
		(end 30.26791 -299.27042)
		(width 0.14478)
		(layer "In6.Cu")
		(net "M_E_CPU1_SB_DQ<13>")
	)
	(segment
		(start 30.986984 -299.107606)
		(end 31.149798 -299.27042)
		(width 0.14478)
		(layer "In6.Cu")
		(net "M_E_CPU1_SB_DQ<13>")
	)
	(segment
		(start 42.839386 -298.060364)
		(end 45.837094 -298.060364)
		(width 0.14478)
		(layer "In6.Cu")
		(net "M_E_CPU1_SB_DQ<13>")
	)
	(segment
		(start 35.676586 -298.060364)
		(end 38.140894 -298.060364)
		(width 0.14478)
		(layer "In6.Cu")
		(net "M_E_CPU1_SB_DQ<13>")
	)
	(segment
		(start 32.864806 -298.910502)
		(end 33.157668 -299.203364)
		(width 0.14478)
		(layer "In6.Cu")
		(net "M_E_CPU1_SB_DQ<13>")
	)
	(segment
		(start 76.48067 -283.3497)
		(end 78.312264 -283.3497)
		(width 0.0889)
		(layer "In6.Cu")
		(net "M_E_CPU1_SB_DQ<13>")
	)
	(segment
		(start 74.187304 -283.456634)
		(end 75.941936 -283.456634)
		(width 0.14478)
		(layer "In6.Cu")
		(net "M_E_CPU1_SB_DQ<13>")
	)
	(segment
		(start 31.543244 -298.69511)
		(end 31.706058 -298.532296)
		(width 0.14478)
		(layer "In6.Cu")
		(net "M_E_CPU1_SB_DQ<13>")
	)
	(segment
		(start 78.659482 -283.242766)
		(end 78.711044 -283.242766)
		(width 0.0889)
		(layer "In6.Cu")
		(net "M_E_CPU1_SB_DQ<13>")
	)
	(segment
		(start 50.761646 -298.060364)
		(end 53.08219 -298.060364)
		(width 0.14478)
		(layer "In6.Cu")
		(net "M_E_CPU1_SB_DQ<13>")
	)
	(segment
		(start 53.08219 -298.060364)
		(end 53.932328 -298.910502)
		(width 0.14478)
		(layer "In6.Cu")
		(net "M_E_CPU1_SB_DQ<13>")
	)
	(segment
		(start 38.991032 -298.910502)
		(end 41.989248 -298.910502)
		(width 0.14478)
		(layer "In6.Cu")
		(net "M_E_CPU1_SB_DQ<13>")
	)
	(segment
		(start 46.687232 -298.910502)
		(end 49.911508 -298.910502)
		(width 0.14478)
		(layer "In6.Cu")
		(net "M_E_CPU1_SB_DQ<13>")
	)
	(segment
		(start 34.533586 -299.203364)
		(end 35.676586 -298.060364)
		(width 0.14478)
		(layer "In6.Cu")
		(net "M_E_CPU1_SB_DQ<13>")
	)
	(segment
		(start 64.601852 -292.108382)
		(end 70.576694 -286.13354)
		(width 0.14478)
		(layer "In6.Cu")
		(net "M_E_CPU1_SB_DQ<13>")
	)
	(segment
		(start 34.123884 -299.05706)
		(end 34.270188 -299.203364)
		(width 0.14478)
		(layer "In6.Cu")
		(net "M_E_CPU1_SB_DQ<13>")
	)
	(segment
		(start 70.576694 -286.13354)
		(end 71.510398 -286.13354)
		(width 0.14478)
		(layer "In6.Cu")
		(net "M_E_CPU1_SB_DQ<13>")
	)
	(segment
		(start 30.82417 -298.532296)
		(end 30.986984 -298.69511)
		(width 0.14478)
		(layer "In6.Cu")
		(net "M_E_CPU1_SB_DQ<13>")
	)
	(segment
		(start 29.252164 -298.485306)
		(end 30.037278 -299.27042)
		(width 0.14478)
		(layer "In6.Cu")
		(net "M_E_CPU1_SB_DQ<13>")
	)
	(segment
		(start 71.510398 -286.13354)
		(end 74.187304 -283.456634)
		(width 0.14478)
		(layer "In6.Cu")
		(net "M_E_CPU1_SB_DQ<13>")
	)
	(segment
		(start 30.593538 -298.532296)
		(end 30.82417 -298.532296)
		(width 0.14478)
		(layer "In6.Cu")
		(net "M_E_CPU1_SB_DQ<13>")
	)
	(segment
		(start 33.97758 -298.61764)
		(end 34.123884 -298.763944)
		(width 0.14478)
		(layer "In6.Cu")
		(net "M_E_CPU1_SB_DQ<13>")
	)
	(segment
		(start 34.270188 -299.203364)
		(end 34.533586 -299.203364)
		(width 0.14478)
		(layer "In6.Cu")
		(net "M_E_CPU1_SB_DQ<13>")
	)
	(segment
		(start 79.934308 -283.318966)
		(end 79.945992 -283.325824)
		(width 0.0889)
		(layer "In6.Cu")
		(net "M_E_CPU1_SB_DQ<13>")
	)
	(segment
		(start 79.356966 -283.325824)
		(end 79.36865 -283.318966)
		(width 0.0889)
		(layer "In6.Cu")
		(net "M_E_CPU1_SB_DQ<13>")
	)
	(segment
		(start 41.989248 -298.910502)
		(end 42.839386 -298.060364)
		(width 0.14478)
		(layer "In6.Cu")
		(net "M_E_CPU1_SB_DQ<13>")
	)
	(segment
		(start 38.140894 -298.060364)
		(end 38.991032 -298.910502)
		(width 0.14478)
		(layer "In6.Cu")
		(net "M_E_CPU1_SB_DQ<13>")
	)
	(segment
		(start 53.932328 -298.910502)
		(end 57.038494 -298.910502)
		(width 0.14478)
		(layer "In6.Cu")
		(net "M_E_CPU1_SB_DQ<13>")
	)
	(segment
		(start 31.543244 -299.107606)
		(end 31.543244 -298.69511)
		(width 0.14478)
		(layer "In6.Cu")
		(net "M_E_CPU1_SB_DQ<13>")
	)
	(segment
		(start 45.837094 -298.060364)
		(end 46.687232 -298.910502)
		(width 0.14478)
		(layer "In6.Cu")
		(net "M_E_CPU1_SB_DQ<13>")
	)
	(segment
		(start 33.567624 -299.05706)
		(end 33.567624 -298.763944)
		(width 0.14478)
		(layer "In6.Cu")
		(net "M_E_CPU1_SB_DQ<13>")
	)
	(segment
		(start 33.42132 -299.203364)
		(end 33.567624 -299.05706)
		(width 0.14478)
		(layer "In6.Cu")
		(net "M_E_CPU1_SB_DQ<13>")
	)
	(segment
		(start 82.786982 -283.261816)
		(end 82.940906 -282.996386)
		(width 0.0889)
		(layer "In6.Cu")
		(net "M_E_CPU1_SB_DQ<13>")
	)
	(segment
		(start 79.923894 -283.31287)
		(end 79.934308 -283.318966)
		(width 0.0889)
		(layer "In6.Cu")
		(net "M_E_CPU1_SB_DQ<13>")
	)
	(segment
		(start 82.69097 -283.287216)
		(end 82.786982 -283.261816)
		(width 0.0889)
		(layer "In6.Cu")
		(net "M_E_CPU1_SB_DQ<13>")
	)
	(segment
		(start 82.179668 -283.323792)
		(end 82.18805 -283.318966)
		(width 0.0889)
		(layer "In6.Cu")
		(net "M_E_CPU1_SB_DQ<13>")
	)
	(segment
		(start 33.713928 -298.61764)
		(end 33.97758 -298.61764)
		(width 0.14478)
		(layer "In6.Cu")
		(net "M_E_CPU1_SB_DQ<13>")
	)
	(segment
		(start 61.105796 -296.096182)
		(end 64.254126 -292.947852)
		(width 0.14478)
		(layer "In6.Cu")
		(net "M_E_CPU1_SB_DQ<13>")
	)
	(arc
		(start 78.711044 -283.242766)
		(mid 78.857692 -283.262119)
		(end 78.994254 -283.318966)
		(width 0.0889)
		(layer "In6.Cu")
		(net "M_E_CPU1_SB_DQ<13>")
	)
	(arc
		(start 80.308196 -283.318966)
		(mid 80.591152 -283.242789)
		(end 80.874108 -283.318966)
		(width 0.0889)
		(layer "In6.Cu")
		(net "M_E_CPU1_SB_DQ<13>")
	)
	(arc
		(start 81.247996 -283.318966)
		(mid 81.530952 -283.242789)
		(end 81.813908 -283.318966)
		(width 0.0889)
		(layer "In6.Cu")
		(net "M_E_CPU1_SB_DQ<13>")
	)
	(arc
		(start 79.945992 -283.325824)
		(mid 80.127993 -283.369357)
		(end 80.308196 -283.318966)
		(width 0.0889)
		(layer "In6.Cu")
		(net "M_E_CPU1_SB_DQ<13>")
	)
	(arc
		(start 82.18805 -283.318966)
		(mid 82.435763 -283.243746)
		(end 82.69097 -283.287216)
		(width 0.0889)
		(layer "In6.Cu")
		(net "M_E_CPU1_SB_DQ<13>")
	)
	(arc
		(start 79.36865 -283.318966)
		(mid 79.645463 -283.242823)
		(end 79.923894 -283.31287)
		(width 0.0889)
		(layer "In6.Cu")
		(net "M_E_CPU1_SB_DQ<13>")
	)
	(arc
		(start 78.994254 -283.318966)
		(mid 79.174712 -283.36941)
		(end 79.356966 -283.325824)
		(width 0.0889)
		(layer "In6.Cu")
		(net "M_E_CPU1_SB_DQ<13>")
	)
	(arc
		(start 80.874108 -283.318966)
		(mid 81.061052 -283.369221)
		(end 81.247996 -283.318966)
		(width 0.0889)
		(layer "In6.Cu")
		(net "M_E_CPU1_SB_DQ<13>")
	)
	(arc
		(start 78.488794 -283.276548)
		(mid 78.572471 -283.251228)
		(end 78.659482 -283.242766)
		(width 0.0889)
		(layer "In6.Cu")
		(net "M_E_CPU1_SB_DQ<13>")
	)
	(arc
		(start 81.813908 -283.318966)
		(mid 81.996159 -283.369316)
		(end 82.179668 -283.323792)
		(width 0.0889)
		(layer "In6.Cu")
		(net "M_E_CPU1_SB_DQ<13>")
	)
	(segment
		(start 81.997804 -281.920442)
		(end 81.530952 -282.18638)
		(width 0.10668)
		(layer "F.Cu")
		(net "M_E_CPU1_SB_DQ<12>")
	)
	(segment
		(start 38.748208 -297.220132)
		(end 42.359072 -297.220132)
		(width 0.14478)
		(layer "In6.Cu")
		(net "M_E_CPU1_SB_DQ<12>")
	)
	(segment
		(start 71.918322 -284.43682)
		(end 72.112378 -284.242764)
		(width 0.14478)
		(layer "In6.Cu")
		(net "M_E_CPU1_SB_DQ<12>")
	)
	(segment
		(start 71.858632 -283.784294)
		(end 71.858632 -283.57957)
		(width 0.14478)
		(layer "In6.Cu")
		(net "M_E_CPU1_SB_DQ<12>")
	)
	(segment
		(start 33.44926 -297.501564)
		(end 33.714436 -297.501564)
		(width 0.14478)
		(layer "In6.Cu")
		(net "M_E_CPU1_SB_DQ<12>")
	)
	(segment
		(start 33.167828 -297.220132)
		(end 33.44926 -297.501564)
		(width 0.14478)
		(layer "In6.Cu")
		(net "M_E_CPU1_SB_DQ<12>")
	)
	(segment
		(start 50.95875 -296.369994)
		(end 52.90947 -296.369994)
		(width 0.14478)
		(layer "In6.Cu")
		(net "M_E_CPU1_SB_DQ<12>")
	)
	(segment
		(start 37.89807 -296.369994)
		(end 38.748208 -297.220132)
		(width 0.14478)
		(layer "In6.Cu")
		(net "M_E_CPU1_SB_DQ<12>")
	)
	(segment
		(start 72.052688 -283.385514)
		(end 72.257412 -283.385514)
		(width 0.14478)
		(layer "In6.Cu")
		(net "M_E_CPU1_SB_DQ<12>")
	)
	(segment
		(start 71.314818 -285.040324)
		(end 71.314818 -284.8356)
		(width 0.14478)
		(layer "In6.Cu")
		(net "M_E_CPU1_SB_DQ<12>")
	)
	(segment
		(start 29.993844 -297.526964)
		(end 30.23362 -297.526964)
		(width 0.14478)
		(layer "In6.Cu")
		(net "M_E_CPU1_SB_DQ<12>")
	)
	(segment
		(start 72.112378 -284.242764)
		(end 72.112378 -284.03804)
		(width 0.14478)
		(layer "In6.Cu")
		(net "M_E_CPU1_SB_DQ<12>")
	)
	(segment
		(start 78.240128 -282.559506)
		(end 78.711044 -282.559506)
		(width 0.0889)
		(layer "In6.Cu")
		(net "M_E_CPU1_SB_DQ<12>")
	)
	(segment
		(start 71.120762 -285.23438)
		(end 71.314818 -285.040324)
		(width 0.14478)
		(layer "In6.Cu")
		(net "M_E_CPU1_SB_DQ<12>")
	)
	(segment
		(start 54.464458 -297.052238)
		(end 54.6227 -296.893996)
		(width 0.14478)
		(layer "In6.Cu")
		(net "M_E_CPU1_SB_DQ<12>")
	)
	(segment
		(start 46.335188 -297.220132)
		(end 50.108612 -297.220132)
		(width 0.14478)
		(layer "In6.Cu")
		(net "M_E_CPU1_SB_DQ<12>")
	)
	(segment
		(start 72.112378 -284.03804)
		(end 71.858632 -283.784294)
		(width 0.14478)
		(layer "In6.Cu")
		(net "M_E_CPU1_SB_DQ<12>")
	)
	(segment
		(start 54.6227 -296.893996)
		(end 54.862476 -296.893996)
		(width 0.14478)
		(layer "In6.Cu")
		(net "M_E_CPU1_SB_DQ<12>")
	)
	(segment
		(start 71.858632 -283.57957)
		(end 72.052688 -283.385514)
		(width 0.14478)
		(layer "In6.Cu")
		(net "M_E_CPU1_SB_DQ<12>")
	)
	(segment
		(start 72.890888 -282.547314)
		(end 76.0349 -282.547314)
		(width 0.14478)
		(layer "In6.Cu")
		(net "M_E_CPU1_SB_DQ<12>")
	)
	(segment
		(start 71.061072 -284.37713)
		(end 71.255128 -284.183074)
		(width 0.14478)
		(layer "In6.Cu")
		(net "M_E_CPU1_SB_DQ<12>")
	)
	(segment
		(start 79.463138 -282.50896)
		(end 79.47152 -282.513786)
		(width 0.0889)
		(layer "In6.Cu")
		(net "M_E_CPU1_SB_DQ<12>")
	)
	(segment
		(start 76.42225 -282.159964)
		(end 77.840586 -282.159964)
		(width 0.0889)
		(layer "In6.Cu")
		(net "M_E_CPU1_SB_DQ<12>")
	)
	(segment
		(start 72.257412 -283.385514)
		(end 72.511158 -283.63926)
		(width 0.14478)
		(layer "In6.Cu")
		(net "M_E_CPU1_SB_DQ<12>")
	)
	(segment
		(start 63.839598 -291.598604)
		(end 70.457568 -284.980634)
		(width 0.14478)
		(layer "In6.Cu")
		(net "M_E_CPU1_SB_DQ<12>")
	)
	(segment
		(start 34.56178 -297.501564)
		(end 34.826956 -297.501564)
		(width 0.14478)
		(layer "In6.Cu")
		(net "M_E_CPU1_SB_DQ<12>")
	)
	(segment
		(start 81.377028 -282.45181)
		(end 81.530952 -282.18638)
		(width 0.0889)
		(layer "In6.Cu")
		(net "M_E_CPU1_SB_DQ<12>")
	)
	(segment
		(start 55.73522 -297.21048)
		(end 57.466484 -297.21048)
		(width 0.14478)
		(layer "In6.Cu")
		(net "M_E_CPU1_SB_DQ<12>")
	)
	(segment
		(start 52.90947 -296.369994)
		(end 54.06644 -297.526964)
		(width 0.14478)
		(layer "In6.Cu")
		(net "M_E_CPU1_SB_DQ<12>")
	)
	(segment
		(start 29.252164 -296.785284)
		(end 29.993844 -297.526964)
		(width 0.14478)
		(layer "In6.Cu")
		(net "M_E_CPU1_SB_DQ<12>")
	)
	(segment
		(start 30.23362 -297.526964)
		(end 30.550104 -297.21048)
		(width 0.14478)
		(layer "In6.Cu")
		(net "M_E_CPU1_SB_DQ<12>")
	)
	(segment
		(start 30.78988 -297.21048)
		(end 31.106364 -297.526964)
		(width 0.14478)
		(layer "In6.Cu")
		(net "M_E_CPU1_SB_DQ<12>")
	)
	(segment
		(start 72.909938 -283.445204)
		(end 72.909938 -283.24048)
		(width 0.14478)
		(layer "In6.Cu")
		(net "M_E_CPU1_SB_DQ<12>")
	)
	(segment
		(start 72.656192 -282.986734)
		(end 72.656192 -282.78201)
		(width 0.14478)
		(layer "In6.Cu")
		(net "M_E_CPU1_SB_DQ<12>")
	)
	(segment
		(start 31.106364 -297.526964)
		(end 31.34614 -297.526964)
		(width 0.14478)
		(layer "In6.Cu")
		(net "M_E_CPU1_SB_DQ<12>")
	)
	(segment
		(start 71.459852 -284.183074)
		(end 71.713598 -284.43682)
		(width 0.14478)
		(layer "In6.Cu")
		(net "M_E_CPU1_SB_DQ<12>")
	)
	(segment
		(start 54.464458 -297.368722)
		(end 54.464458 -297.052238)
		(width 0.14478)
		(layer "In6.Cu")
		(net "M_E_CPU1_SB_DQ<12>")
	)
	(segment
		(start 54.306216 -297.526964)
		(end 54.464458 -297.368722)
		(width 0.14478)
		(layer "In6.Cu")
		(net "M_E_CPU1_SB_DQ<12>")
	)
	(segment
		(start 58.457084 -296.21988)
		(end 60.596272 -295.333674)
		(width 0.14478)
		(layer "In6.Cu")
		(net "M_E_CPU1_SB_DQ<12>")
	)
	(segment
		(start 34.00552 -297.21048)
		(end 34.270696 -297.21048)
		(width 0.14478)
		(layer "In6.Cu")
		(net "M_E_CPU1_SB_DQ<12>")
	)
	(segment
		(start 81.281016 -282.47721)
		(end 81.377028 -282.45181)
		(width 0.0889)
		(layer "In6.Cu")
		(net "M_E_CPU1_SB_DQ<12>")
	)
	(segment
		(start 57.466484 -297.21048)
		(end 58.457084 -296.21988)
		(width 0.14478)
		(layer "In6.Cu")
		(net "M_E_CPU1_SB_DQ<12>")
	)
	(segment
		(start 72.511158 -283.63926)
		(end 72.715882 -283.63926)
		(width 0.14478)
		(layer "In6.Cu")
		(net "M_E_CPU1_SB_DQ<12>")
	)
	(segment
		(start 50.108612 -297.220132)
		(end 50.95875 -296.369994)
		(width 0.14478)
		(layer "In6.Cu")
		(net "M_E_CPU1_SB_DQ<12>")
	)
	(segment
		(start 71.255128 -284.183074)
		(end 71.459852 -284.183074)
		(width 0.14478)
		(layer "In6.Cu")
		(net "M_E_CPU1_SB_DQ<12>")
	)
	(segment
		(start 43.20921 -296.369994)
		(end 45.48505 -296.369994)
		(width 0.14478)
		(layer "In6.Cu")
		(net "M_E_CPU1_SB_DQ<12>")
	)
	(segment
		(start 70.662292 -284.980634)
		(end 70.916038 -285.23438)
		(width 0.14478)
		(layer "In6.Cu")
		(net "M_E_CPU1_SB_DQ<12>")
	)
	(segment
		(start 54.862476 -296.893996)
		(end 55.020718 -297.052238)
		(width 0.14478)
		(layer "In6.Cu")
		(net "M_E_CPU1_SB_DQ<12>")
	)
	(segment
		(start 45.48505 -296.369994)
		(end 46.335188 -297.220132)
		(width 0.14478)
		(layer "In6.Cu")
		(net "M_E_CPU1_SB_DQ<12>")
	)
	(segment
		(start 34.270696 -297.21048)
		(end 34.56178 -297.501564)
		(width 0.14478)
		(layer "In6.Cu")
		(net "M_E_CPU1_SB_DQ<12>")
	)
	(segment
		(start 31.652972 -297.220132)
		(end 33.167828 -297.220132)
		(width 0.14478)
		(layer "In6.Cu")
		(net "M_E_CPU1_SB_DQ<12>")
	)
	(segment
		(start 63.491872 -292.438074)
		(end 63.839598 -291.598604)
		(width 0.14478)
		(layer "In6.Cu")
		(net "M_E_CPU1_SB_DQ<12>")
	)
	(segment
		(start 71.713598 -284.43682)
		(end 71.918322 -284.43682)
		(width 0.14478)
		(layer "In6.Cu")
		(net "M_E_CPU1_SB_DQ<12>")
	)
	(segment
		(start 55.020718 -297.368722)
		(end 55.17896 -297.526964)
		(width 0.14478)
		(layer "In6.Cu")
		(net "M_E_CPU1_SB_DQ<12>")
	)
	(segment
		(start 71.061072 -284.581854)
		(end 71.061072 -284.37713)
		(width 0.14478)
		(layer "In6.Cu")
		(net "M_E_CPU1_SB_DQ<12>")
	)
	(segment
		(start 31.34614 -297.526964)
		(end 31.652972 -297.220132)
		(width 0.14478)
		(layer "In6.Cu")
		(net "M_E_CPU1_SB_DQ<12>")
	)
	(segment
		(start 78.897734 -282.508706)
		(end 78.903322 -282.505404)
		(width 0.0889)
		(layer "In6.Cu")
		(net "M_E_CPU1_SB_DQ<12>")
	)
	(segment
		(start 55.020718 -297.052238)
		(end 55.020718 -297.368722)
		(width 0.14478)
		(layer "In6.Cu")
		(net "M_E_CPU1_SB_DQ<12>")
	)
	(segment
		(start 70.916038 -285.23438)
		(end 71.120762 -285.23438)
		(width 0.14478)
		(layer "In6.Cu")
		(net "M_E_CPU1_SB_DQ<12>")
	)
	(segment
		(start 33.714436 -297.501564)
		(end 34.00552 -297.21048)
		(width 0.14478)
		(layer "In6.Cu")
		(net "M_E_CPU1_SB_DQ<12>")
	)
	(segment
		(start 35.958526 -296.369994)
		(end 37.89807 -296.369994)
		(width 0.14478)
		(layer "In6.Cu")
		(net "M_E_CPU1_SB_DQ<12>")
	)
	(segment
		(start 72.909938 -283.24048)
		(end 72.656192 -282.986734)
		(width 0.14478)
		(layer "In6.Cu")
		(net "M_E_CPU1_SB_DQ<12>")
	)
	(segment
		(start 55.17896 -297.526964)
		(end 55.418736 -297.526964)
		(width 0.14478)
		(layer "In6.Cu")
		(net "M_E_CPU1_SB_DQ<12>")
	)
	(segment
		(start 30.550104 -297.21048)
		(end 30.78988 -297.21048)
		(width 0.14478)
		(layer "In6.Cu")
		(net "M_E_CPU1_SB_DQ<12>")
	)
	(segment
		(start 71.314818 -284.8356)
		(end 71.061072 -284.581854)
		(width 0.14478)
		(layer "In6.Cu")
		(net "M_E_CPU1_SB_DQ<12>")
	)
	(segment
		(start 54.06644 -297.526964)
		(end 54.306216 -297.526964)
		(width 0.14478)
		(layer "In6.Cu")
		(net "M_E_CPU1_SB_DQ<12>")
	)
	(segment
		(start 60.596272 -295.333674)
		(end 63.491872 -292.438074)
		(width 0.14478)
		(layer "In6.Cu")
		(net "M_E_CPU1_SB_DQ<12>")
	)
	(segment
		(start 70.457568 -284.980634)
		(end 70.662292 -284.980634)
		(width 0.14478)
		(layer "In6.Cu")
		(net "M_E_CPU1_SB_DQ<12>")
	)
	(segment
		(start 80.769714 -282.513786)
		(end 80.778096 -282.50896)
		(width 0.0889)
		(layer "In6.Cu")
		(net "M_E_CPU1_SB_DQ<12>")
	)
	(segment
		(start 76.0349 -282.547314)
		(end 76.42225 -282.159964)
		(width 0.0889)
		(layer "In6.Cu")
		(net "M_E_CPU1_SB_DQ<12>")
	)
	(segment
		(start 72.656192 -282.78201)
		(end 72.890888 -282.547314)
		(width 0.14478)
		(layer "In6.Cu")
		(net "M_E_CPU1_SB_DQ<12>")
	)
	(segment
		(start 34.826956 -297.501564)
		(end 35.958526 -296.369994)
		(width 0.14478)
		(layer "In6.Cu")
		(net "M_E_CPU1_SB_DQ<12>")
	)
	(segment
		(start 55.418736 -297.526964)
		(end 55.73522 -297.21048)
		(width 0.14478)
		(layer "In6.Cu")
		(net "M_E_CPU1_SB_DQ<12>")
	)
	(segment
		(start 77.840586 -282.159964)
		(end 78.240128 -282.559506)
		(width 0.0889)
		(layer "In6.Cu")
		(net "M_E_CPU1_SB_DQ<12>")
	)
	(segment
		(start 42.359072 -297.220132)
		(end 43.20921 -296.369994)
		(width 0.14478)
		(layer "In6.Cu")
		(net "M_E_CPU1_SB_DQ<12>")
	)
	(segment
		(start 80.39354 -282.502864)
		(end 80.403954 -282.50896)
		(width 0.0889)
		(layer "In6.Cu")
		(net "M_E_CPU1_SB_DQ<12>")
	)
	(segment
		(start 72.715882 -283.63926)
		(end 72.909938 -283.445204)
		(width 0.14478)
		(layer "In6.Cu")
		(net "M_E_CPU1_SB_DQ<12>")
	)
	(arc
		(start 80.403954 -282.50896)
		(mid 80.586205 -282.55931)
		(end 80.769714 -282.513786)
		(width 0.0889)
		(layer "In6.Cu")
		(net "M_E_CPU1_SB_DQ<12>")
	)
	(arc
		(start 79.837788 -282.50896)
		(mid 80.114855 -282.432689)
		(end 80.39354 -282.502864)
		(width 0.0889)
		(layer "In6.Cu")
		(net "M_E_CPU1_SB_DQ<12>")
	)
	(arc
		(start 79.47152 -282.513786)
		(mid 79.655282 -282.559402)
		(end 79.837788 -282.50896)
		(width 0.0889)
		(layer "In6.Cu")
		(net "M_E_CPU1_SB_DQ<12>")
	)
	(arc
		(start 80.778096 -282.50896)
		(mid 81.025809 -282.43374)
		(end 81.281016 -282.47721)
		(width 0.0889)
		(layer "In6.Cu")
		(net "M_E_CPU1_SB_DQ<12>")
	)
	(arc
		(start 78.903322 -282.505404)
		(mid 79.183711 -282.432735)
		(end 79.463138 -282.50896)
		(width 0.0889)
		(layer "In6.Cu")
		(net "M_E_CPU1_SB_DQ<12>")
	)
	(arc
		(start 78.711044 -282.559506)
		(mid 78.807735 -282.54641)
		(end 78.897734 -282.508706)
		(width 0.0889)
		(layer "In6.Cu")
		(net "M_E_CPU1_SB_DQ<12>")
	)
	(segment
		(start 82.937858 -280.30043)
		(end 82.471006 -280.566368)
		(width 0.10668)
		(layer "F.Cu")
		(net "M_E_CPU1_SB_DQ<11>")
	)
	(segment
		(start 80.769714 -280.238962)
		(end 80.778096 -280.243788)
		(width 0.0889)
		(layer "In6.Cu")
		(net "M_E_CPU1_SB_DQ<11>")
	)
	(segment
		(start 38.960806 -293.80053)
		(end 41.765474 -293.80053)
		(width 0.14478)
		(layer "In6.Cu")
		(net "M_E_CPU1_SB_DQ<11>")
	)
	(segment
		(start 76.160376 -280.207974)
		(end 76.240386 -280.127964)
		(width 0.0889)
		(layer "In6.Cu")
		(net "M_E_CPU1_SB_DQ<11>")
	)
	(segment
		(start 82.62493 -280.300938)
		(end 82.471006 -280.566368)
		(width 0.0889)
		(layer "In6.Cu")
		(net "M_E_CPU1_SB_DQ<11>")
	)
	(segment
		(start 82.602578 -280.217626)
		(end 82.62493 -280.300938)
		(width 0.0889)
		(layer "In6.Cu")
		(net "M_E_CPU1_SB_DQ<11>")
	)
	(segment
		(start 53.07711 -293.409878)
		(end 56.94045 -293.409878)
		(width 0.14478)
		(layer "In6.Cu")
		(net "M_E_CPU1_SB_DQ<11>")
	)
	(segment
		(start 81.344008 -280.243788)
		(end 81.35239 -280.238962)
		(width 0.0889)
		(layer "In6.Cu")
		(net "M_E_CPU1_SB_DQ<11>")
	)
	(segment
		(start 35.147758 -292.950646)
		(end 38.110922 -292.950646)
		(width 0.14478)
		(layer "In6.Cu")
		(net "M_E_CPU1_SB_DQ<11>")
	)
	(segment
		(start 76.240386 -280.127964)
		(end 79.534004 -280.127964)
		(width 0.0889)
		(layer "In6.Cu")
		(net "M_E_CPU1_SB_DQ<11>")
	)
	(segment
		(start 52.617878 -292.950646)
		(end 53.07711 -293.409878)
		(width 0.14478)
		(layer "In6.Cu")
		(net "M_E_CPU1_SB_DQ<11>")
	)
	(segment
		(start 49.031398 -293.80053)
		(end 49.881282 -292.950646)
		(width 0.14478)
		(layer "In6.Cu")
		(net "M_E_CPU1_SB_DQ<11>")
	)
	(segment
		(start 75.968606 -280.207974)
		(end 76.160376 -280.207974)
		(width 0.0889)
		(layer "In6.Cu")
		(net "M_E_CPU1_SB_DQ<11>")
	)
	(segment
		(start 45.476922 -292.950646)
		(end 46.326806 -293.80053)
		(width 0.14478)
		(layer "In6.Cu")
		(net "M_E_CPU1_SB_DQ<11>")
	)
	(segment
		(start 59.846718 -292.845744)
		(end 61.33465 -291.357812)
		(width 0.14478)
		(layer "In6.Cu")
		(net "M_E_CPU1_SB_DQ<11>")
	)
	(segment
		(start 71.416672 -280.207974)
		(end 75.968606 -280.207974)
		(width 0.14478)
		(layer "In6.Cu")
		(net "M_E_CPU1_SB_DQ<11>")
	)
	(segment
		(start 41.765474 -293.80053)
		(end 42.615358 -292.950646)
		(width 0.14478)
		(layer "In6.Cu")
		(net "M_E_CPU1_SB_DQ<11>")
	)
	(segment
		(start 56.94045 -293.409878)
		(end 57.504584 -292.845744)
		(width 0.14478)
		(layer "In6.Cu")
		(net "M_E_CPU1_SB_DQ<11>")
	)
	(segment
		(start 42.615358 -292.950646)
		(end 45.476922 -292.950646)
		(width 0.14478)
		(layer "In6.Cu")
		(net "M_E_CPU1_SB_DQ<11>")
	)
	(segment
		(start 57.504584 -292.845744)
		(end 59.846718 -292.845744)
		(width 0.14478)
		(layer "In6.Cu")
		(net "M_E_CPU1_SB_DQ<11>")
	)
	(segment
		(start 38.110922 -292.950646)
		(end 38.960806 -293.80053)
		(width 0.14478)
		(layer "In6.Cu")
		(net "M_E_CPU1_SB_DQ<11>")
	)
	(segment
		(start 25.152096 -293.38524)
		(end 25.567386 -293.80053)
		(width 0.14478)
		(layer "In6.Cu")
		(net "M_E_CPU1_SB_DQ<11>")
	)
	(segment
		(start 25.567386 -293.80053)
		(end 34.297874 -293.80053)
		(width 0.14478)
		(layer "In6.Cu")
		(net "M_E_CPU1_SB_DQ<11>")
	)
	(segment
		(start 34.297874 -293.80053)
		(end 35.147758 -292.950646)
		(width 0.14478)
		(layer "In6.Cu")
		(net "M_E_CPU1_SB_DQ<11>")
	)
	(segment
		(start 61.33465 -291.357812)
		(end 61.33465 -290.289996)
		(width 0.14478)
		(layer "In6.Cu")
		(net "M_E_CPU1_SB_DQ<11>")
	)
	(segment
		(start 61.33465 -290.289996)
		(end 71.416672 -280.207974)
		(width 0.14478)
		(layer "In6.Cu")
		(net "M_E_CPU1_SB_DQ<11>")
	)
	(segment
		(start 49.881282 -292.950646)
		(end 52.617878 -292.950646)
		(width 0.14478)
		(layer "In6.Cu")
		(net "M_E_CPU1_SB_DQ<11>")
	)
	(segment
		(start 46.326806 -293.80053)
		(end 49.031398 -293.80053)
		(width 0.14478)
		(layer "In6.Cu")
		(net "M_E_CPU1_SB_DQ<11>")
	)
	(arc
		(start 80.403954 -280.243788)
		(mid 80.586205 -280.193438)
		(end 80.769714 -280.238962)
		(width 0.0889)
		(layer "In6.Cu")
		(net "M_E_CPU1_SB_DQ<11>")
	)
	(arc
		(start 80.778096 -280.243788)
		(mid 81.061052 -280.319965)
		(end 81.344008 -280.243788)
		(width 0.0889)
		(layer "In6.Cu")
		(net "M_E_CPU1_SB_DQ<11>")
	)
	(arc
		(start 81.35239 -280.238962)
		(mid 81.535898 -280.193468)
		(end 81.71815 -280.243788)
		(width 0.0889)
		(layer "In6.Cu")
		(net "M_E_CPU1_SB_DQ<11>")
	)
	(arc
		(start 79.621888 -280.14295)
		(mid 79.732261 -280.188446)
		(end 79.838042 -280.243788)
		(width 0.0889)
		(layer "In6.Cu")
		(net "M_E_CPU1_SB_DQ<11>")
	)
	(arc
		(start 79.534004 -280.127964)
		(mid 79.578598 -280.131642)
		(end 79.621888 -280.14295)
		(width 0.0889)
		(layer "In6.Cu")
		(net "M_E_CPU1_SB_DQ<11>")
	)
	(arc
		(start 82.284062 -280.243788)
		(mid 82.440381 -280.194793)
		(end 82.602578 -280.217626)
		(width 0.0889)
		(layer "In6.Cu")
		(net "M_E_CPU1_SB_DQ<11>")
	)
	(arc
		(start 81.71815 -280.243788)
		(mid 82.001106 -280.319965)
		(end 82.284062 -280.243788)
		(width 0.0889)
		(layer "In6.Cu")
		(net "M_E_CPU1_SB_DQ<11>")
	)
	(arc
		(start 79.838042 -280.243788)
		(mid 80.120998 -280.319965)
		(end 80.403954 -280.243788)
		(width 0.0889)
		(layer "In6.Cu")
		(net "M_E_CPU1_SB_DQ<11>")
	)
	(segment
		(start 81.527904 -279.490424)
		(end 81.061052 -279.756362)
		(width 0.10668)
		(layer "F.Cu")
		(net "M_E_CPU1_SB_DQ<10>")
	)
	(segment
		(start 60.16498 -291.255196)
		(end 60.43549 -290.984686)
		(width 0.14478)
		(layer "In6.Cu")
		(net "M_E_CPU1_SB_DQ<10>")
	)
	(segment
		(start 38.947344 -292.110414)
		(end 42.032936 -292.110414)
		(width 0.14478)
		(layer "In6.Cu")
		(net "M_E_CPU1_SB_DQ<10>")
	)
	(segment
		(start 56.953404 -292.110414)
		(end 57.808622 -291.255196)
		(width 0.14478)
		(layer "In6.Cu")
		(net "M_E_CPU1_SB_DQ<10>")
	)
	(segment
		(start 26.67889 -291.454586)
		(end 26.67889 -291.9476)
		(width 0.14478)
		(layer "In6.Cu")
		(net "M_E_CPU1_SB_DQ<10>")
	)
	(segment
		(start 52.64785 -291.260276)
		(end 53.497988 -292.110414)
		(width 0.14478)
		(layer "In6.Cu")
		(net "M_E_CPU1_SB_DQ<10>")
	)
	(segment
		(start 26.67889 -291.9476)
		(end 26.841704 -292.110414)
		(width 0.14478)
		(layer "In6.Cu")
		(net "M_E_CPU1_SB_DQ<10>")
	)
	(segment
		(start 81.192624 -279.40762)
		(end 81.214976 -279.490932)
		(width 0.0889)
		(layer "In6.Cu")
		(net "M_E_CPU1_SB_DQ<10>")
	)
	(segment
		(start 42.032936 -292.110414)
		(end 42.883074 -291.260276)
		(width 0.14478)
		(layer "In6.Cu")
		(net "M_E_CPU1_SB_DQ<10>")
	)
	(segment
		(start 79.92364 -279.439878)
		(end 79.934054 -279.433782)
		(width 0.0889)
		(layer "In6.Cu")
		(net "M_E_CPU1_SB_DQ<10>")
	)
	(segment
		(start 79.360014 -279.428956)
		(end 79.368396 -279.433782)
		(width 0.0889)
		(layer "In6.Cu")
		(net "M_E_CPU1_SB_DQ<10>")
	)
	(segment
		(start 38.097206 -291.260276)
		(end 38.947344 -292.110414)
		(width 0.14478)
		(layer "In6.Cu")
		(net "M_E_CPU1_SB_DQ<10>")
	)
	(segment
		(start 42.883074 -291.260276)
		(end 45.336206 -291.260276)
		(width 0.14478)
		(layer "In6.Cu")
		(net "M_E_CPU1_SB_DQ<10>")
	)
	(segment
		(start 71.05396 -279.298654)
		(end 76.378816 -279.298654)
		(width 0.14478)
		(layer "In6.Cu")
		(net "M_E_CPU1_SB_DQ<10>")
	)
	(segment
		(start 53.497988 -292.110414)
		(end 56.953404 -292.110414)
		(width 0.14478)
		(layer "In6.Cu")
		(net "M_E_CPU1_SB_DQ<10>")
	)
	(segment
		(start 25.577292 -292.110414)
		(end 25.959816 -292.110414)
		(width 0.14478)
		(layer "In6.Cu")
		(net "M_E_CPU1_SB_DQ<10>")
	)
	(segment
		(start 60.43549 -289.917124)
		(end 71.05396 -279.298654)
		(width 0.14478)
		(layer "In6.Cu")
		(net "M_E_CPU1_SB_DQ<10>")
	)
	(segment
		(start 45.336206 -291.260276)
		(end 46.186344 -292.110414)
		(width 0.14478)
		(layer "In6.Cu")
		(net "M_E_CPU1_SB_DQ<10>")
	)
	(segment
		(start 76.630276 -279.047194)
		(end 78.01483 -279.047194)
		(width 0.0889)
		(layer "In6.Cu")
		(net "M_E_CPU1_SB_DQ<10>")
	)
	(segment
		(start 60.43549 -290.984686)
		(end 60.43549 -289.917124)
		(width 0.14478)
		(layer "In6.Cu")
		(net "M_E_CPU1_SB_DQ<10>")
	)
	(segment
		(start 78.428342 -279.433782)
		(end 78.443074 -279.442418)
		(width 0.0889)
		(layer "In6.Cu")
		(net "M_E_CPU1_SB_DQ<10>")
	)
	(segment
		(start 35.492182 -291.260276)
		(end 38.097206 -291.260276)
		(width 0.14478)
		(layer "In6.Cu")
		(net "M_E_CPU1_SB_DQ<10>")
	)
	(segment
		(start 26.12263 -291.454586)
		(end 26.26741 -291.309806)
		(width 0.14478)
		(layer "In6.Cu")
		(net "M_E_CPU1_SB_DQ<10>")
	)
	(segment
		(start 34.642044 -292.110414)
		(end 35.492182 -291.260276)
		(width 0.14478)
		(layer "In6.Cu")
		(net "M_E_CPU1_SB_DQ<10>")
	)
	(segment
		(start 25.152096 -291.685218)
		(end 25.577292 -292.110414)
		(width 0.14478)
		(layer "In6.Cu")
		(net "M_E_CPU1_SB_DQ<10>")
	)
	(segment
		(start 79.934054 -279.433782)
		(end 79.942436 -279.428956)
		(width 0.0889)
		(layer "In6.Cu")
		(net "M_E_CPU1_SB_DQ<10>")
	)
	(segment
		(start 26.53411 -291.309806)
		(end 26.67889 -291.454586)
		(width 0.14478)
		(layer "In6.Cu")
		(net "M_E_CPU1_SB_DQ<10>")
	)
	(segment
		(start 26.841704 -292.110414)
		(end 34.642044 -292.110414)
		(width 0.14478)
		(layer "In6.Cu")
		(net "M_E_CPU1_SB_DQ<10>")
	)
	(segment
		(start 78.01483 -279.047194)
		(end 78.312518 -279.344882)
		(width 0.0889)
		(layer "In6.Cu")
		(net "M_E_CPU1_SB_DQ<10>")
	)
	(segment
		(start 25.959816 -292.110414)
		(end 26.12263 -291.9476)
		(width 0.14478)
		(layer "In6.Cu")
		(net "M_E_CPU1_SB_DQ<10>")
	)
	(segment
		(start 49.435004 -292.110414)
		(end 50.285142 -291.260276)
		(width 0.14478)
		(layer "In6.Cu")
		(net "M_E_CPU1_SB_DQ<10>")
	)
	(segment
		(start 26.12263 -291.9476)
		(end 26.12263 -291.454586)
		(width 0.14478)
		(layer "In6.Cu")
		(net "M_E_CPU1_SB_DQ<10>")
	)
	(segment
		(start 57.808622 -291.255196)
		(end 60.16498 -291.255196)
		(width 0.14478)
		(layer "In6.Cu")
		(net "M_E_CPU1_SB_DQ<10>")
	)
	(segment
		(start 46.186344 -292.110414)
		(end 49.435004 -292.110414)
		(width 0.14478)
		(layer "In6.Cu")
		(net "M_E_CPU1_SB_DQ<10>")
	)
	(segment
		(start 50.285142 -291.260276)
		(end 52.64785 -291.260276)
		(width 0.14478)
		(layer "In6.Cu")
		(net "M_E_CPU1_SB_DQ<10>")
	)
	(segment
		(start 26.26741 -291.309806)
		(end 26.53411 -291.309806)
		(width 0.14478)
		(layer "In6.Cu")
		(net "M_E_CPU1_SB_DQ<10>")
	)
	(segment
		(start 81.214976 -279.490932)
		(end 81.061052 -279.756362)
		(width 0.0889)
		(layer "In6.Cu")
		(net "M_E_CPU1_SB_DQ<10>")
	)
	(segment
		(start 76.378816 -279.298654)
		(end 76.630276 -279.047194)
		(width 0.0889)
		(layer "In6.Cu")
		(net "M_E_CPU1_SB_DQ<10>")
	)
	(arc
		(start 78.994254 -279.433782)
		(mid 79.176505 -279.383432)
		(end 79.360014 -279.428956)
		(width 0.0889)
		(layer "In6.Cu")
		(net "M_E_CPU1_SB_DQ<10>")
	)
	(arc
		(start 78.312518 -279.344882)
		(mid 78.367543 -279.393092)
		(end 78.428342 -279.433782)
		(width 0.0889)
		(layer "In6.Cu")
		(net "M_E_CPU1_SB_DQ<10>")
	)
	(arc
		(start 79.368396 -279.433782)
		(mid 79.645209 -279.509925)
		(end 79.92364 -279.439878)
		(width 0.0889)
		(layer "In6.Cu")
		(net "M_E_CPU1_SB_DQ<10>")
	)
	(arc
		(start 78.443074 -279.442418)
		(mid 78.719803 -279.510101)
		(end 78.994254 -279.433782)
		(width 0.0889)
		(layer "In6.Cu")
		(net "M_E_CPU1_SB_DQ<10>")
	)
	(arc
		(start 79.942436 -279.428956)
		(mid 80.125944 -279.383462)
		(end 80.308196 -279.433782)
		(width 0.0889)
		(layer "In6.Cu")
		(net "M_E_CPU1_SB_DQ<10>")
	)
	(arc
		(start 80.874108 -279.433782)
		(mid 81.030427 -279.384787)
		(end 81.192624 -279.40762)
		(width 0.0889)
		(layer "In6.Cu")
		(net "M_E_CPU1_SB_DQ<10>")
	)
	(arc
		(start 80.308196 -279.433782)
		(mid 80.591152 -279.509959)
		(end 80.874108 -279.433782)
		(width 0.0889)
		(layer "In6.Cu")
		(net "M_E_CPU1_SB_DQ<10>")
	)
	(segment
		(start 81.997804 -273.820382)
		(end 81.530952 -274.08632)
		(width 0.10668)
		(layer "F.Cu")
		(net "M_E_CPU1_SB_DQ<0>")
	)
	(segment
		(start 61.28131 -279.216104)
		(end 61.28131 -278.121872)
		(width 0.14478)
		(layer "In6.Cu")
		(net "M_E_CPU1_SB_DQ<0>")
	)
	(segment
		(start 50.99177 -281.347164)
		(end 51.26101 -281.347164)
		(width 0.14478)
		(layer "In6.Cu")
		(net "M_E_CPU1_SB_DQ<0>")
	)
	(segment
		(start 29.977588 -282.210764)
		(end 30.570424 -282.210764)
		(width 0.14478)
		(layer "In6.Cu")
		(net "M_E_CPU1_SB_DQ<0>")
	)
	(segment
		(start 60.29706 -280.863802)
		(end 60.29706 -280.200354)
		(width 0.14478)
		(layer "In6.Cu")
		(net "M_E_CPU1_SB_DQ<0>")
	)
	(segment
		(start 79.838296 -274.4089)
		(end 79.84871 -274.402804)
		(width 0.0889)
		(layer "In6.Cu")
		(net "M_E_CPU1_SB_DQ<0>")
	)
	(segment
		(start 31.522162 -282.210764)
		(end 32.044132 -282.210764)
		(width 0.14478)
		(layer "In6.Cu")
		(net "M_E_CPU1_SB_DQ<0>")
	)
	(segment
		(start 61.967618 -277.972266)
		(end 62.172342 -277.972266)
		(width 0.14478)
		(layer "In6.Cu")
		(net "M_E_CPU1_SB_DQ<0>")
	)
	(segment
		(start 59.438794 -281.372564)
		(end 59.788298 -281.372564)
		(width 0.14478)
		(layer "In6.Cu")
		(net "M_E_CPU1_SB_DQ<0>")
	)
	(segment
		(start 58.201306 -280.565606)
		(end 58.631836 -280.565606)
		(width 0.14478)
		(layer "In6.Cu")
		(net "M_E_CPU1_SB_DQ<0>")
	)
	(segment
		(start 55.748174 -282.210764)
		(end 56.003952 -282.210764)
		(width 0.14478)
		(layer "In6.Cu")
		(net "M_E_CPU1_SB_DQ<0>")
	)
	(segment
		(start 32.044132 -282.210764)
		(end 32.344614 -281.910282)
		(width 0.14478)
		(layer "In6.Cu")
		(net "M_E_CPU1_SB_DQ<0>")
	)
	(segment
		(start 55.191914 -281.910282)
		(end 55.447692 -281.910282)
		(width 0.14478)
		(layer "In6.Cu")
		(net "M_E_CPU1_SB_DQ<0>")
	)
	(segment
		(start 46.84395 -282.210764)
		(end 47.144432 -281.910282)
		(width 0.14478)
		(layer "In6.Cu")
		(net "M_E_CPU1_SB_DQ<0>")
	)
	(segment
		(start 35.462718 -281.060144)
		(end 35.775138 -281.372564)
		(width 0.14478)
		(layer "In6.Cu")
		(net "M_E_CPU1_SB_DQ<0>")
	)
	(segment
		(start 34.326576 -281.910282)
		(end 35.176714 -281.060144)
		(width 0.14478)
		(layer "In6.Cu")
		(net "M_E_CPU1_SB_DQ<0>")
	)
	(segment
		(start 32.94507 -281.910282)
		(end 33.245552 -282.210764)
		(width 0.14478)
		(layer "In6.Cu")
		(net "M_E_CPU1_SB_DQ<0>")
	)
	(segment
		(start 41.125902 -282.210764)
		(end 41.426384 -281.910282)
		(width 0.14478)
		(layer "In6.Cu")
		(net "M_E_CPU1_SB_DQ<0>")
	)
	(segment
		(start 48.504856 -282.210764)
		(end 48.760634 -282.210764)
		(width 0.14478)
		(layer "In6.Cu")
		(net "M_E_CPU1_SB_DQ<0>")
	)
	(segment
		(start 61.596778 -277.806404)
		(end 61.801502 -277.80615)
		(width 0.14478)
		(layer "In6.Cu")
		(net "M_E_CPU1_SB_DQ<0>")
	)
	(segment
		(start 40.569642 -281.910282)
		(end 40.870124 -282.210764)
		(width 0.14478)
		(layer "In6.Cu")
		(net "M_E_CPU1_SB_DQ<0>")
	)
	(segment
		(start 62.969902 -277.174706)
		(end 64.22771 -275.916898)
		(width 0.14478)
		(layer "In6.Cu")
		(net "M_E_CPU1_SB_DQ<0>")
	)
	(segment
		(start 52.864766 -281.060144)
		(end 53.714904 -281.910282)
		(width 0.14478)
		(layer "In6.Cu")
		(net "M_E_CPU1_SB_DQ<0>")
	)
	(segment
		(start 75.987656 -273.220434)
		(end 76.722986 -273.220434)
		(width 0.0889)
		(layer "In6.Cu")
		(net "M_E_CPU1_SB_DQ<0>")
	)
	(segment
		(start 33.50133 -282.210764)
		(end 33.801812 -281.910282)
		(width 0.14478)
		(layer "In6.Cu")
		(net "M_E_CPU1_SB_DQ<0>")
	)
	(segment
		(start 35.775138 -281.372564)
		(end 36.018978 -281.372564)
		(width 0.14478)
		(layer "In6.Cu")
		(net "M_E_CPU1_SB_DQ<0>")
	)
	(segment
		(start 50.330862 -281.060144)
		(end 50.70475 -281.060144)
		(width 0.14478)
		(layer "In6.Cu")
		(net "M_E_CPU1_SB_DQ<0>")
	)
	(segment
		(start 66.182748 -273.220434)
		(end 75.987656 -273.220434)
		(width 0.14478)
		(layer "In6.Cu")
		(net "M_E_CPU1_SB_DQ<0>")
	)
	(segment
		(start 57.30494 -281.467306)
		(end 57.50941 -281.466798)
		(width 0.14478)
		(layer "In6.Cu")
		(net "M_E_CPU1_SB_DQ<0>")
	)
	(segment
		(start 33.245552 -282.210764)
		(end 33.50133 -282.210764)
		(width 0.14478)
		(layer "In6.Cu")
		(net "M_E_CPU1_SB_DQ<0>")
	)
	(segment
		(start 51.26101 -281.347164)
		(end 51.54803 -281.060144)
		(width 0.14478)
		(layer "In6.Cu")
		(net "M_E_CPU1_SB_DQ<0>")
	)
	(segment
		(start 32.344614 -281.910282)
		(end 32.94507 -281.910282)
		(width 0.14478)
		(layer "In6.Cu")
		(net "M_E_CPU1_SB_DQ<0>")
	)
	(segment
		(start 38.500304 -281.910282)
		(end 39.047928 -281.910282)
		(width 0.14478)
		(layer "In6.Cu")
		(net "M_E_CPU1_SB_DQ<0>")
	)
	(segment
		(start 58.2676 -281.629104)
		(end 58.266838 -281.42438)
		(width 0.14478)
		(layer "In6.Cu")
		(net "M_E_CPU1_SB_DQ<0>")
	)
	(segment
		(start 31.235904 -281.924506)
		(end 31.522162 -282.210764)
		(width 0.14478)
		(layer "In6.Cu")
		(net "M_E_CPU1_SB_DQ<0>")
	)
	(segment
		(start 40.870124 -282.210764)
		(end 41.125902 -282.210764)
		(width 0.14478)
		(layer "In6.Cu")
		(net "M_E_CPU1_SB_DQ<0>")
	)
	(segment
		(start 53.714904 -281.910282)
		(end 54.335172 -281.910282)
		(width 0.14478)
		(layer "In6.Cu")
		(net "M_E_CPU1_SB_DQ<0>")
	)
	(segment
		(start 61.28131 -278.121872)
		(end 61.596778 -277.806404)
		(width 0.14478)
		(layer "In6.Cu")
		(net "M_E_CPU1_SB_DQ<0>")
	)
	(segment
		(start 62.172342 -277.972266)
		(end 62.366652 -277.777956)
		(width 0.14478)
		(layer "In6.Cu")
		(net "M_E_CPU1_SB_DQ<0>")
	)
	(segment
		(start 62.200282 -277.407624)
		(end 62.200282 -277.2029)
		(width 0.14478)
		(layer "In6.Cu")
		(net "M_E_CPU1_SB_DQ<0>")
	)
	(segment
		(start 45.219366 -281.060144)
		(end 46.369986 -282.210764)
		(width 0.14478)
		(layer "In6.Cu")
		(net "M_E_CPU1_SB_DQ<0>")
	)
	(segment
		(start 77.54493 -273.447764)
		(end 78.447138 -274.349972)
		(width 0.0889)
		(layer "In6.Cu")
		(net "M_E_CPU1_SB_DQ<0>")
	)
	(segment
		(start 78.447138 -274.349972)
		(end 78.447392 -274.349972)
		(width 0.0889)
		(layer "In6.Cu")
		(net "M_E_CPU1_SB_DQ<0>")
	)
	(segment
		(start 46.369986 -282.210764)
		(end 46.84395 -282.210764)
		(width 0.14478)
		(layer "In6.Cu")
		(net "M_E_CPU1_SB_DQ<0>")
	)
	(segment
		(start 57.907174 -281.066494)
		(end 57.906412 -280.862024)
		(width 0.14478)
		(layer "In6.Cu")
		(net "M_E_CPU1_SB_DQ<0>")
	)
	(segment
		(start 78.524354 -274.4089)
		(end 78.536038 -274.415758)
		(width 0.0889)
		(layer "In6.Cu")
		(net "M_E_CPU1_SB_DQ<0>")
	)
	(segment
		(start 62.599062 -277.00859)
		(end 62.765178 -277.174706)
		(width 0.14478)
		(layer "In6.Cu")
		(net "M_E_CPU1_SB_DQ<0>")
	)
	(segment
		(start 48.760634 -282.210764)
		(end 49.061116 -281.910282)
		(width 0.14478)
		(layer "In6.Cu")
		(net "M_E_CPU1_SB_DQ<0>")
	)
	(segment
		(start 39.32301 -282.185364)
		(end 39.604188 -282.185364)
		(width 0.14478)
		(layer "In6.Cu")
		(net "M_E_CPU1_SB_DQ<0>")
	)
	(segment
		(start 56.003952 -282.210764)
		(end 56.304434 -281.910282)
		(width 0.14478)
		(layer "In6.Cu")
		(net "M_E_CPU1_SB_DQ<0>")
	)
	(segment
		(start 62.765178 -277.174706)
		(end 62.969902 -277.174706)
		(width 0.14478)
		(layer "In6.Cu")
		(net "M_E_CPU1_SB_DQ<0>")
	)
	(segment
		(start 60.29706 -280.200354)
		(end 61.28131 -279.216104)
		(width 0.14478)
		(layer "In6.Cu")
		(net "M_E_CPU1_SB_DQ<0>")
	)
	(segment
		(start 62.394338 -277.008844)
		(end 62.599062 -277.00859)
		(width 0.14478)
		(layer "In6.Cu")
		(net "M_E_CPU1_SB_DQ<0>")
	)
	(segment
		(start 54.635654 -282.210764)
		(end 54.891432 -282.210764)
		(width 0.14478)
		(layer "In6.Cu")
		(net "M_E_CPU1_SB_DQ<0>")
	)
	(segment
		(start 64.75222 -274.650962)
		(end 66.182748 -273.220434)
		(width 0.14478)
		(layer "In6.Cu")
		(net "M_E_CPU1_SB_DQ<0>")
	)
	(segment
		(start 59.788298 -281.372564)
		(end 60.29706 -280.863802)
		(width 0.14478)
		(layer "In6.Cu")
		(net "M_E_CPU1_SB_DQ<0>")
	)
	(segment
		(start 57.869074 -281.824684)
		(end 58.073798 -281.823922)
		(width 0.14478)
		(layer "In6.Cu")
		(net "M_E_CPU1_SB_DQ<0>")
	)
	(segment
		(start 57.906412 -280.862024)
		(end 58.201306 -280.565606)
		(width 0.14478)
		(layer "In6.Cu")
		(net "M_E_CPU1_SB_DQ<0>")
	)
	(segment
		(start 58.266838 -281.42438)
		(end 57.907174 -281.066494)
		(width 0.14478)
		(layer "In6.Cu")
		(net "M_E_CPU1_SB_DQ<0>")
	)
	(segment
		(start 30.570424 -282.210764)
		(end 30.856682 -281.924506)
		(width 0.14478)
		(layer "In6.Cu")
		(net "M_E_CPU1_SB_DQ<0>")
	)
	(segment
		(start 54.891432 -282.210764)
		(end 55.191914 -281.910282)
		(width 0.14478)
		(layer "In6.Cu")
		(net "M_E_CPU1_SB_DQ<0>")
	)
	(segment
		(start 41.426384 -281.910282)
		(end 42.302176 -281.910282)
		(width 0.14478)
		(layer "In6.Cu")
		(net "M_E_CPU1_SB_DQ<0>")
	)
	(segment
		(start 80.769714 -274.413726)
		(end 80.778096 -274.4089)
		(width 0.0889)
		(layer "In6.Cu")
		(net "M_E_CPU1_SB_DQ<0>")
	)
	(segment
		(start 33.801812 -281.910282)
		(end 34.326576 -281.910282)
		(width 0.14478)
		(layer "In6.Cu")
		(net "M_E_CPU1_SB_DQ<0>")
	)
	(segment
		(start 36.018978 -281.372564)
		(end 36.331398 -281.060144)
		(width 0.14478)
		(layer "In6.Cu")
		(net "M_E_CPU1_SB_DQ<0>")
	)
	(segment
		(start 47.144432 -281.910282)
		(end 48.204374 -281.910282)
		(width 0.14478)
		(layer "In6.Cu")
		(net "M_E_CPU1_SB_DQ<0>")
	)
	(segment
		(start 39.604188 -282.185364)
		(end 39.87927 -281.910282)
		(width 0.14478)
		(layer "In6.Cu")
		(net "M_E_CPU1_SB_DQ<0>")
	)
	(segment
		(start 62.200282 -277.2029)
		(end 62.394338 -277.008844)
		(width 0.14478)
		(layer "In6.Cu")
		(net "M_E_CPU1_SB_DQ<0>")
	)
	(segment
		(start 76.722986 -273.220434)
		(end 76.950316 -273.447764)
		(width 0.0889)
		(layer "In6.Cu")
		(net "M_E_CPU1_SB_DQ<0>")
	)
	(segment
		(start 56.304434 -281.910282)
		(end 56.863996 -281.910282)
		(width 0.14478)
		(layer "In6.Cu")
		(net "M_E_CPU1_SB_DQ<0>")
	)
	(segment
		(start 49.061116 -281.910282)
		(end 49.480724 -281.910282)
		(width 0.14478)
		(layer "In6.Cu")
		(net "M_E_CPU1_SB_DQ<0>")
	)
	(segment
		(start 58.631836 -280.565606)
		(end 59.438794 -281.372564)
		(width 0.14478)
		(layer "In6.Cu")
		(net "M_E_CPU1_SB_DQ<0>")
	)
	(segment
		(start 55.447692 -281.910282)
		(end 55.748174 -282.210764)
		(width 0.14478)
		(layer "In6.Cu")
		(net "M_E_CPU1_SB_DQ<0>")
	)
	(segment
		(start 51.54803 -281.060144)
		(end 52.864766 -281.060144)
		(width 0.14478)
		(layer "In6.Cu")
		(net "M_E_CPU1_SB_DQ<0>")
	)
	(segment
		(start 54.335172 -281.910282)
		(end 54.635654 -282.210764)
		(width 0.14478)
		(layer "In6.Cu")
		(net "M_E_CPU1_SB_DQ<0>")
	)
	(segment
		(start 37.650166 -281.060144)
		(end 38.500304 -281.910282)
		(width 0.14478)
		(layer "In6.Cu")
		(net "M_E_CPU1_SB_DQ<0>")
	)
	(segment
		(start 56.863996 -281.910282)
		(end 57.30494 -281.467306)
		(width 0.14478)
		(layer "In6.Cu")
		(net "M_E_CPU1_SB_DQ<0>")
	)
	(segment
		(start 64.22771 -275.916898)
		(end 64.75222 -274.650962)
		(width 0.14478)
		(layer "In6.Cu")
		(net "M_E_CPU1_SB_DQ<0>")
	)
	(segment
		(start 58.073798 -281.823922)
		(end 58.2676 -281.629104)
		(width 0.14478)
		(layer "In6.Cu")
		(net "M_E_CPU1_SB_DQ<0>")
	)
	(segment
		(start 62.366398 -277.57374)
		(end 62.200282 -277.407624)
		(width 0.14478)
		(layer "In6.Cu")
		(net "M_E_CPU1_SB_DQ<0>")
	)
	(segment
		(start 48.204374 -281.910282)
		(end 48.504856 -282.210764)
		(width 0.14478)
		(layer "In6.Cu")
		(net "M_E_CPU1_SB_DQ<0>")
	)
	(segment
		(start 50.70475 -281.060144)
		(end 50.99177 -281.347164)
		(width 0.14478)
		(layer "In6.Cu")
		(net "M_E_CPU1_SB_DQ<0>")
	)
	(segment
		(start 79.453994 -274.402804)
		(end 79.464408 -274.4089)
		(width 0.0889)
		(layer "In6.Cu")
		(net "M_E_CPU1_SB_DQ<0>")
	)
	(segment
		(start 81.281016 -274.37715)
		(end 81.377028 -274.35175)
		(width 0.0889)
		(layer "In6.Cu")
		(net "M_E_CPU1_SB_DQ<0>")
	)
	(segment
		(start 35.176714 -281.060144)
		(end 35.462718 -281.060144)
		(width 0.14478)
		(layer "In6.Cu")
		(net "M_E_CPU1_SB_DQ<0>")
	)
	(segment
		(start 36.331398 -281.060144)
		(end 37.650166 -281.060144)
		(width 0.14478)
		(layer "In6.Cu")
		(net "M_E_CPU1_SB_DQ<0>")
	)
	(segment
		(start 39.047928 -281.910282)
		(end 39.32301 -282.185364)
		(width 0.14478)
		(layer "In6.Cu")
		(net "M_E_CPU1_SB_DQ<0>")
	)
	(segment
		(start 76.950316 -273.447764)
		(end 77.54493 -273.447764)
		(width 0.0889)
		(layer "In6.Cu")
		(net "M_E_CPU1_SB_DQ<0>")
	)
	(segment
		(start 29.252164 -281.48534)
		(end 29.977588 -282.210764)
		(width 0.14478)
		(layer "In6.Cu")
		(net "M_E_CPU1_SB_DQ<0>")
	)
	(segment
		(start 81.377028 -274.35175)
		(end 81.530952 -274.08632)
		(width 0.0889)
		(layer "In6.Cu")
		(net "M_E_CPU1_SB_DQ<0>")
	)
	(segment
		(start 39.87927 -281.910282)
		(end 40.569642 -281.910282)
		(width 0.14478)
		(layer "In6.Cu")
		(net "M_E_CPU1_SB_DQ<0>")
	)
	(segment
		(start 49.480724 -281.910282)
		(end 50.330862 -281.060144)
		(width 0.14478)
		(layer "In6.Cu")
		(net "M_E_CPU1_SB_DQ<0>")
	)
	(segment
		(start 62.366652 -277.777956)
		(end 62.366398 -277.57374)
		(width 0.14478)
		(layer "In6.Cu")
		(net "M_E_CPU1_SB_DQ<0>")
	)
	(segment
		(start 42.302176 -281.910282)
		(end 43.152314 -281.060144)
		(width 0.14478)
		(layer "In6.Cu")
		(net "M_E_CPU1_SB_DQ<0>")
	)
	(segment
		(start 30.856682 -281.924506)
		(end 31.235904 -281.924506)
		(width 0.14478)
		(layer "In6.Cu")
		(net "M_E_CPU1_SB_DQ<0>")
	)
	(segment
		(start 61.801502 -277.80615)
		(end 61.967618 -277.972266)
		(width 0.14478)
		(layer "In6.Cu")
		(net "M_E_CPU1_SB_DQ<0>")
	)
	(segment
		(start 57.50941 -281.466798)
		(end 57.869074 -281.824684)
		(width 0.14478)
		(layer "In6.Cu")
		(net "M_E_CPU1_SB_DQ<0>")
	)
	(segment
		(start 43.152314 -281.060144)
		(end 45.219366 -281.060144)
		(width 0.14478)
		(layer "In6.Cu")
		(net "M_E_CPU1_SB_DQ<0>")
	)
	(arc
		(start 78.447392 -274.349972)
		(mid 78.483947 -274.381952)
		(end 78.524354 -274.4089)
		(width 0.0889)
		(layer "In6.Cu")
		(net "M_E_CPU1_SB_DQ<0>")
	)
	(arc
		(start 80.403954 -274.4089)
		(mid 80.586205 -274.45925)
		(end 80.769714 -274.413726)
		(width 0.0889)
		(layer "In6.Cu")
		(net "M_E_CPU1_SB_DQ<0>")
	)
	(arc
		(start 78.898242 -274.4089)
		(mid 79.175309 -274.332629)
		(end 79.453994 -274.402804)
		(width 0.0889)
		(layer "In6.Cu")
		(net "M_E_CPU1_SB_DQ<0>")
	)
	(arc
		(start 78.536038 -274.415758)
		(mid 78.718039 -274.459291)
		(end 78.898242 -274.4089)
		(width 0.0889)
		(layer "In6.Cu")
		(net "M_E_CPU1_SB_DQ<0>")
	)
	(arc
		(start 79.84871 -274.402804)
		(mid 80.127142 -274.332706)
		(end 80.403954 -274.4089)
		(width 0.0889)
		(layer "In6.Cu")
		(net "M_E_CPU1_SB_DQ<0>")
	)
	(arc
		(start 80.778096 -274.4089)
		(mid 81.025809 -274.33368)
		(end 81.281016 -274.37715)
		(width 0.0889)
		(layer "In6.Cu")
		(net "M_E_CPU1_SB_DQ<0>")
	)
	(arc
		(start 79.464408 -274.4089)
		(mid 79.651352 -274.459155)
		(end 79.838296 -274.4089)
		(width 0.0889)
		(layer "In6.Cu")
		(net "M_E_CPU1_SB_DQ<0>")
	)
	(segment
		(start 81.527904 -266.530328)
		(end 81.061052 -266.796266)
		(width 0.10668)
		(layer "F.Cu")
		(net "M_E_CPU1_SB_CS_N<1>")
	)
	(segment
		(start 81.192624 -266.447524)
		(end 81.214976 -266.530836)
		(width 0.0889)
		(layer "In6.Cu")
		(net "M_E_CPU1_SB_CS_N<1>")
	)
	(segment
		(start 75.957176 -265.983974)
		(end 77.894942 -265.983974)
		(width 0.0889)
		(layer "In6.Cu")
		(net "M_E_CPU1_SB_CS_N<1>")
	)
	(segment
		(start 59.652662 -268.31036)
		(end 61.979048 -265.983974)
		(width 0.14478)
		(layer "In6.Cu")
		(net "M_E_CPU1_SB_CS_N<1>")
	)
	(segment
		(start 77.894942 -265.983974)
		(end 78.34503 -266.434062)
		(width 0.0889)
		(layer "In6.Cu")
		(net "M_E_CPU1_SB_CS_N<1>")
	)
	(segment
		(start 61.979048 -265.983974)
		(end 75.957176 -265.983974)
		(width 0.14478)
		(layer "In6.Cu")
		(net "M_E_CPU1_SB_CS_N<1>")
	)
	(segment
		(start 81.214976 -266.530836)
		(end 81.061052 -266.796266)
		(width 0.0889)
		(layer "In6.Cu")
		(net "M_E_CPU1_SB_CS_N<1>")
	)
	(segment
		(start 78.34503 -266.434062)
		(end 80.031844 -266.434062)
		(width 0.0889)
		(layer "In6.Cu")
		(net "M_E_CPU1_SB_CS_N<1>")
	)
	(segment
		(start 25.152096 -268.735302)
		(end 25.577038 -268.31036)
		(width 0.14478)
		(layer "In6.Cu")
		(net "M_E_CPU1_SB_CS_N<1>")
	)
	(segment
		(start 25.577038 -268.31036)
		(end 59.652662 -268.31036)
		(width 0.14478)
		(layer "In6.Cu")
		(net "M_E_CPU1_SB_CS_N<1>")
	)
	(arc
		(start 80.874108 -266.473686)
		(mid 81.030427 -266.424691)
		(end 81.192624 -266.447524)
		(width 0.0889)
		(layer "In6.Cu")
		(net "M_E_CPU1_SB_CS_N<1>")
	)
	(arc
		(start 80.308196 -266.473686)
		(mid 80.591152 -266.549863)
		(end 80.874108 -266.473686)
		(width 0.0889)
		(layer "In6.Cu")
		(net "M_E_CPU1_SB_CS_N<1>")
	)
	(arc
		(start 80.031844 -266.434062)
		(mid 80.173876 -266.427018)
		(end 80.308196 -266.473686)
		(width 0.0889)
		(layer "In6.Cu")
		(net "M_E_CPU1_SB_CS_N<1>")
	)
	(segment
		(start 82.937858 -265.720322)
		(end 82.471006 -265.98626)
		(width 0.10668)
		(layer "F.Cu")
		(net "M_E_CPU1_SB_CS_N<0>")
	)
	(segment
		(start 30.945582 -267.692632)
		(end 30.945582 -267.30452)
		(width 0.14478)
		(layer "In6.Cu")
		(net "M_E_CPU1_SB_CS_N<0>")
	)
	(segment
		(start 30.945582 -267.30452)
		(end 31.101538 -267.148564)
		(width 0.14478)
		(layer "In6.Cu")
		(net "M_E_CPU1_SB_CS_N<0>")
	)
	(segment
		(start 31.501842 -267.30452)
		(end 31.501842 -267.692632)
		(width 0.14478)
		(layer "In6.Cu")
		(net "M_E_CPU1_SB_CS_N<0>")
	)
	(segment
		(start 81.344008 -265.66368)
		(end 81.35239 -265.658854)
		(width 0.0889)
		(layer "In6.Cu")
		(net "M_E_CPU1_SB_CS_N<0>")
	)
	(segment
		(start 31.902146 -267.848588)
		(end 32.290258 -267.460476)
		(width 0.14478)
		(layer "In6.Cu")
		(net "M_E_CPU1_SB_CS_N<0>")
	)
	(segment
		(start 76.119736 -265.529314)
		(end 79.470504 -265.529314)
		(width 0.0889)
		(layer "In6.Cu")
		(net "M_E_CPU1_SB_CS_N<0>")
	)
	(segment
		(start 30.389322 -267.30452)
		(end 30.389322 -267.692632)
		(width 0.14478)
		(layer "In6.Cu")
		(net "M_E_CPU1_SB_CS_N<0>")
	)
	(segment
		(start 31.101538 -267.148564)
		(end 31.345886 -267.148564)
		(width 0.14478)
		(layer "In6.Cu")
		(net "M_E_CPU1_SB_CS_N<0>")
	)
	(segment
		(start 30.545278 -267.848588)
		(end 30.789626 -267.848588)
		(width 0.14478)
		(layer "In6.Cu")
		(net "M_E_CPU1_SB_CS_N<0>")
	)
	(segment
		(start 30.389322 -267.692632)
		(end 30.545278 -267.848588)
		(width 0.14478)
		(layer "In6.Cu")
		(net "M_E_CPU1_SB_CS_N<0>")
	)
	(segment
		(start 30.789626 -267.848588)
		(end 30.945582 -267.692632)
		(width 0.14478)
		(layer "In6.Cu")
		(net "M_E_CPU1_SB_CS_N<0>")
	)
	(segment
		(start 31.657798 -267.848588)
		(end 31.902146 -267.848588)
		(width 0.14478)
		(layer "In6.Cu")
		(net "M_E_CPU1_SB_CS_N<0>")
	)
	(segment
		(start 29.989018 -267.148564)
		(end 30.233366 -267.148564)
		(width 0.14478)
		(layer "In6.Cu")
		(net "M_E_CPU1_SB_CS_N<0>")
	)
	(segment
		(start 31.501842 -267.692632)
		(end 31.657798 -267.848588)
		(width 0.14478)
		(layer "In6.Cu")
		(net "M_E_CPU1_SB_CS_N<0>")
	)
	(segment
		(start 82.602578 -265.637518)
		(end 82.62493 -265.72083)
		(width 0.0889)
		(layer "In6.Cu")
		(net "M_E_CPU1_SB_CS_N<0>")
	)
	(segment
		(start 59.704986 -267.460476)
		(end 61.636148 -265.529314)
		(width 0.14478)
		(layer "In6.Cu")
		(net "M_E_CPU1_SB_CS_N<0>")
	)
	(segment
		(start 31.345886 -267.148564)
		(end 31.501842 -267.30452)
		(width 0.14478)
		(layer "In6.Cu")
		(net "M_E_CPU1_SB_CS_N<0>")
	)
	(segment
		(start 29.252164 -267.885418)
		(end 29.989018 -267.148564)
		(width 0.14478)
		(layer "In6.Cu")
		(net "M_E_CPU1_SB_CS_N<0>")
	)
	(segment
		(start 32.290258 -267.460476)
		(end 59.704986 -267.460476)
		(width 0.14478)
		(layer "In6.Cu")
		(net "M_E_CPU1_SB_CS_N<0>")
	)
	(segment
		(start 30.233366 -267.148564)
		(end 30.389322 -267.30452)
		(width 0.14478)
		(layer "In6.Cu")
		(net "M_E_CPU1_SB_CS_N<0>")
	)
	(segment
		(start 80.769714 -265.658854)
		(end 80.778096 -265.66368)
		(width 0.0889)
		(layer "In6.Cu")
		(net "M_E_CPU1_SB_CS_N<0>")
	)
	(segment
		(start 82.62493 -265.72083)
		(end 82.471006 -265.98626)
		(width 0.0889)
		(layer "In6.Cu")
		(net "M_E_CPU1_SB_CS_N<0>")
	)
	(segment
		(start 61.636148 -265.529314)
		(end 76.119736 -265.529314)
		(width 0.14478)
		(layer "In6.Cu")
		(net "M_E_CPU1_SB_CS_N<0>")
	)
	(arc
		(start 82.284062 -265.66368)
		(mid 82.440381 -265.614685)
		(end 82.602578 -265.637518)
		(width 0.0889)
		(layer "In6.Cu")
		(net "M_E_CPU1_SB_CS_N<0>")
	)
	(arc
		(start 79.558896 -265.542268)
		(mid 79.702004 -265.594845)
		(end 79.838042 -265.66368)
		(width 0.0889)
		(layer "In6.Cu")
		(net "M_E_CPU1_SB_CS_N<0>")
	)
	(arc
		(start 79.470504 -265.529314)
		(mid 79.515177 -265.532536)
		(end 79.558896 -265.542268)
		(width 0.0889)
		(layer "In6.Cu")
		(net "M_E_CPU1_SB_CS_N<0>")
	)
	(arc
		(start 79.838042 -265.66368)
		(mid 80.120998 -265.739857)
		(end 80.403954 -265.66368)
		(width 0.0889)
		(layer "In6.Cu")
		(net "M_E_CPU1_SB_CS_N<0>")
	)
	(arc
		(start 81.71815 -265.66368)
		(mid 82.001106 -265.739857)
		(end 82.284062 -265.66368)
		(width 0.0889)
		(layer "In6.Cu")
		(net "M_E_CPU1_SB_CS_N<0>")
	)
	(arc
		(start 80.403954 -265.66368)
		(mid 80.586205 -265.61333)
		(end 80.769714 -265.658854)
		(width 0.0889)
		(layer "In6.Cu")
		(net "M_E_CPU1_SB_CS_N<0>")
	)
	(arc
		(start 81.35239 -265.658854)
		(mid 81.535898 -265.61336)
		(end 81.71815 -265.66368)
		(width 0.0889)
		(layer "In6.Cu")
		(net "M_E_CPU1_SB_CS_N<0>")
	)
	(arc
		(start 80.778096 -265.66368)
		(mid 81.061052 -265.739857)
		(end 81.344008 -265.66368)
		(width 0.0889)
		(layer "In6.Cu")
		(net "M_E_CPU1_SB_CS_N<0>")
	)
	(segment
		(start 82.937858 -270.580358)
		(end 82.471006 -270.846296)
		(width 0.10668)
		(layer "F.Cu")
		(net "M_E_CPU1_SB_CB<7>")
	)
	(segment
		(start 60.07735 -273.171666)
		(end 60.07735 -272.62963)
		(width 0.14478)
		(layer "In6.Cu")
		(net "M_E_CPU1_SB_CB<7>")
	)
	(segment
		(start 27.583892 -274.097496)
		(end 27.583892 -273.6596)
		(width 0.14478)
		(layer "In6.Cu")
		(net "M_E_CPU1_SB_CB<7>")
	)
	(segment
		(start 27.027632 -273.254978)
		(end 27.027632 -274.097496)
		(width 0.14478)
		(layer "In6.Cu")
		(net "M_E_CPU1_SB_CB<7>")
	)
	(segment
		(start 81.344008 -270.523716)
		(end 81.35239 -270.51889)
		(width 0.0889)
		(layer "In6.Cu")
		(net "M_E_CPU1_SB_CB<7>")
	)
	(segment
		(start 82.62493 -270.580866)
		(end 82.471006 -270.846296)
		(width 0.0889)
		(layer "In6.Cu")
		(net "M_E_CPU1_SB_CB<7>")
	)
	(segment
		(start 27.027632 -274.097496)
		(end 27.190446 -274.26031)
		(width 0.14478)
		(layer "In6.Cu")
		(net "M_E_CPU1_SB_CB<7>")
	)
	(segment
		(start 76.994258 -269.104364)
		(end 78.29423 -270.404336)
		(width 0.0889)
		(layer "In6.Cu")
		(net "M_E_CPU1_SB_CB<7>")
	)
	(segment
		(start 27.746706 -273.496786)
		(end 27.977338 -273.496786)
		(width 0.14478)
		(layer "In6.Cu")
		(net "M_E_CPU1_SB_CB<7>")
	)
	(segment
		(start 26.864818 -273.092164)
		(end 27.027632 -273.254978)
		(width 0.14478)
		(layer "In6.Cu")
		(net "M_E_CPU1_SB_CB<7>")
	)
	(segment
		(start 59.83859 -273.410426)
		(end 60.07735 -273.171666)
		(width 0.14478)
		(layer "In6.Cu")
		(net "M_E_CPU1_SB_CB<7>")
	)
	(segment
		(start 27.190446 -274.26031)
		(end 27.421078 -274.26031)
		(width 0.14478)
		(layer "In6.Cu")
		(net "M_E_CPU1_SB_CB<7>")
	)
	(segment
		(start 78.29423 -270.404336)
		(end 79.522574 -270.404336)
		(width 0.0889)
		(layer "In6.Cu")
		(net "M_E_CPU1_SB_CB<7>")
	)
	(segment
		(start 28.302966 -274.26031)
		(end 34.051494 -274.26031)
		(width 0.14478)
		(layer "In6.Cu")
		(net "M_E_CPU1_SB_CB<7>")
	)
	(segment
		(start 27.583892 -273.6596)
		(end 27.746706 -273.496786)
		(width 0.14478)
		(layer "In6.Cu")
		(net "M_E_CPU1_SB_CB<7>")
	)
	(segment
		(start 26.471372 -273.254978)
		(end 26.634186 -273.092164)
		(width 0.14478)
		(layer "In6.Cu")
		(net "M_E_CPU1_SB_CB<7>")
	)
	(segment
		(start 80.769714 -270.51889)
		(end 80.778096 -270.523716)
		(width 0.0889)
		(layer "In6.Cu")
		(net "M_E_CPU1_SB_CB<7>")
	)
	(segment
		(start 60.07735 -272.62963)
		(end 63.746126 -268.960854)
		(width 0.14478)
		(layer "In6.Cu")
		(net "M_E_CPU1_SB_CB<7>")
	)
	(segment
		(start 75.934824 -268.960854)
		(end 76.198476 -268.960854)
		(width 0.0889)
		(layer "In6.Cu")
		(net "M_E_CPU1_SB_CB<7>")
	)
	(segment
		(start 27.977338 -273.496786)
		(end 28.140152 -273.6596)
		(width 0.14478)
		(layer "In6.Cu")
		(net "M_E_CPU1_SB_CB<7>")
	)
	(segment
		(start 25.577038 -274.26031)
		(end 26.308558 -274.26031)
		(width 0.14478)
		(layer "In6.Cu")
		(net "M_E_CPU1_SB_CB<7>")
	)
	(segment
		(start 63.746126 -268.960854)
		(end 75.934824 -268.960854)
		(width 0.14478)
		(layer "In6.Cu")
		(net "M_E_CPU1_SB_CB<7>")
	)
	(segment
		(start 26.308558 -274.26031)
		(end 26.471372 -274.097496)
		(width 0.14478)
		(layer "In6.Cu")
		(net "M_E_CPU1_SB_CB<7>")
	)
	(segment
		(start 28.140152 -273.6596)
		(end 28.140152 -274.097496)
		(width 0.14478)
		(layer "In6.Cu")
		(net "M_E_CPU1_SB_CB<7>")
	)
	(segment
		(start 26.634186 -273.092164)
		(end 26.864818 -273.092164)
		(width 0.14478)
		(layer "In6.Cu")
		(net "M_E_CPU1_SB_CB<7>")
	)
	(segment
		(start 82.602578 -270.497554)
		(end 82.62493 -270.580866)
		(width 0.0889)
		(layer "In6.Cu")
		(net "M_E_CPU1_SB_CB<7>")
	)
	(segment
		(start 76.198476 -268.960854)
		(end 76.341986 -269.104364)
		(width 0.0889)
		(layer "In6.Cu")
		(net "M_E_CPU1_SB_CB<7>")
	)
	(segment
		(start 27.421078 -274.26031)
		(end 27.583892 -274.097496)
		(width 0.14478)
		(layer "In6.Cu")
		(net "M_E_CPU1_SB_CB<7>")
	)
	(segment
		(start 25.152096 -274.685252)
		(end 25.577038 -274.26031)
		(width 0.14478)
		(layer "In6.Cu")
		(net "M_E_CPU1_SB_CB<7>")
	)
	(segment
		(start 28.140152 -274.097496)
		(end 28.302966 -274.26031)
		(width 0.14478)
		(layer "In6.Cu")
		(net "M_E_CPU1_SB_CB<7>")
	)
	(segment
		(start 76.341986 -269.104364)
		(end 76.994258 -269.104364)
		(width 0.0889)
		(layer "In6.Cu")
		(net "M_E_CPU1_SB_CB<7>")
	)
	(segment
		(start 34.051494 -274.26031)
		(end 34.901378 -273.410426)
		(width 0.14478)
		(layer "In6.Cu")
		(net "M_E_CPU1_SB_CB<7>")
	)
	(segment
		(start 26.471372 -274.097496)
		(end 26.471372 -273.254978)
		(width 0.14478)
		(layer "In6.Cu")
		(net "M_E_CPU1_SB_CB<7>")
	)
	(segment
		(start 34.901378 -273.410426)
		(end 59.83859 -273.410426)
		(width 0.14478)
		(layer "In6.Cu")
		(net "M_E_CPU1_SB_CB<7>")
	)
	(arc
		(start 79.522574 -270.404336)
		(mid 79.567137 -270.407999)
		(end 79.610458 -270.419068)
		(width 0.0889)
		(layer "In6.Cu")
		(net "M_E_CPU1_SB_CB<7>")
	)
	(arc
		(start 81.71815 -270.523716)
		(mid 82.001106 -270.599893)
		(end 82.284062 -270.523716)
		(width 0.0889)
		(layer "In6.Cu")
		(net "M_E_CPU1_SB_CB<7>")
	)
	(arc
		(start 80.778096 -270.523716)
		(mid 81.061052 -270.599893)
		(end 81.344008 -270.523716)
		(width 0.0889)
		(layer "In6.Cu")
		(net "M_E_CPU1_SB_CB<7>")
	)
	(arc
		(start 81.35239 -270.51889)
		(mid 81.535898 -270.473396)
		(end 81.71815 -270.523716)
		(width 0.0889)
		(layer "In6.Cu")
		(net "M_E_CPU1_SB_CB<7>")
	)
	(arc
		(start 80.403954 -270.523716)
		(mid 80.586205 -270.473366)
		(end 80.769714 -270.51889)
		(width 0.0889)
		(layer "In6.Cu")
		(net "M_E_CPU1_SB_CB<7>")
	)
	(arc
		(start 79.838042 -270.523716)
		(mid 80.120998 -270.599893)
		(end 80.403954 -270.523716)
		(width 0.0889)
		(layer "In6.Cu")
		(net "M_E_CPU1_SB_CB<7>")
	)
	(arc
		(start 82.284062 -270.523716)
		(mid 82.440381 -270.474721)
		(end 82.602578 -270.497554)
		(width 0.0889)
		(layer "In6.Cu")
		(net "M_E_CPU1_SB_CB<7>")
	)
	(arc
		(start 79.610458 -270.419068)
		(mid 79.726755 -270.465943)
		(end 79.838042 -270.523716)
		(width 0.0889)
		(layer "In6.Cu")
		(net "M_E_CPU1_SB_CB<7>")
	)
	(segment
		(start 81.527904 -269.770352)
		(end 81.061052 -270.03629)
		(width 0.10668)
		(layer "F.Cu")
		(net "M_E_CPU1_SB_CB<6>")
	)
	(segment
		(start 27.802078 -272.560288)
		(end 27.964892 -272.397474)
		(width 0.14478)
		(layer "In6.Cu")
		(net "M_E_CPU1_SB_CB<6>")
	)
	(segment
		(start 81.192624 -269.687548)
		(end 81.214976 -269.77086)
		(width 0.0889)
		(layer "In6.Cu")
		(net "M_E_CPU1_SB_CB<6>")
	)
	(segment
		(start 27.245818 -271.415764)
		(end 27.408632 -271.578578)
		(width 0.14478)
		(layer "In6.Cu")
		(net "M_E_CPU1_SB_CB<6>")
	)
	(segment
		(start 78.428342 -269.71371)
		(end 78.443074 -269.722346)
		(width 0.0889)
		(layer "In6.Cu")
		(net "M_E_CPU1_SB_CB<6>")
	)
	(segment
		(start 25.902666 -271.415764)
		(end 26.133298 -271.415764)
		(width 0.14478)
		(layer "In6.Cu")
		(net "M_E_CPU1_SB_CB<6>")
	)
	(segment
		(start 27.408632 -271.578578)
		(end 27.408632 -272.397474)
		(width 0.14478)
		(layer "In6.Cu")
		(net "M_E_CPU1_SB_CB<6>")
	)
	(segment
		(start 77.231494 -268.570964)
		(end 78.286102 -269.62608)
		(width 0.0889)
		(layer "In6.Cu")
		(net "M_E_CPU1_SB_CB<6>")
	)
	(segment
		(start 26.458926 -272.560288)
		(end 26.689558 -272.560288)
		(width 0.14478)
		(layer "In6.Cu")
		(net "M_E_CPU1_SB_CB<6>")
	)
	(segment
		(start 26.296112 -271.578578)
		(end 26.296112 -272.397474)
		(width 0.14478)
		(layer "In6.Cu")
		(net "M_E_CPU1_SB_CB<6>")
	)
	(segment
		(start 27.964892 -272.397474)
		(end 27.964892 -271.9959)
		(width 0.14478)
		(layer "In6.Cu")
		(net "M_E_CPU1_SB_CB<6>")
	)
	(segment
		(start 25.739852 -271.578578)
		(end 25.902666 -271.415764)
		(width 0.14478)
		(layer "In6.Cu")
		(net "M_E_CPU1_SB_CB<6>")
	)
	(segment
		(start 27.964892 -271.9959)
		(end 28.127706 -271.833086)
		(width 0.14478)
		(layer "In6.Cu")
		(net "M_E_CPU1_SB_CB<6>")
	)
	(segment
		(start 26.296112 -272.397474)
		(end 26.458926 -272.560288)
		(width 0.14478)
		(layer "In6.Cu")
		(net "M_E_CPU1_SB_CB<6>")
	)
	(segment
		(start 78.286102 -269.62608)
		(end 78.428342 -269.71371)
		(width 0.0889)
		(layer "In6.Cu")
		(net "M_E_CPU1_SB_CB<6>")
	)
	(segment
		(start 33.719516 -272.560288)
		(end 34.5694 -271.710404)
		(width 0.14478)
		(layer "In6.Cu")
		(net "M_E_CPU1_SB_CB<6>")
	)
	(segment
		(start 26.133298 -271.415764)
		(end 26.296112 -271.578578)
		(width 0.14478)
		(layer "In6.Cu")
		(net "M_E_CPU1_SB_CB<6>")
	)
	(segment
		(start 28.127706 -271.833086)
		(end 28.358338 -271.833086)
		(width 0.14478)
		(layer "In6.Cu")
		(net "M_E_CPU1_SB_CB<6>")
	)
	(segment
		(start 81.214976 -269.77086)
		(end 81.061052 -270.03629)
		(width 0.0889)
		(layer "In6.Cu")
		(net "M_E_CPU1_SB_CB<6>")
	)
	(segment
		(start 76.748386 -268.570964)
		(end 77.231494 -268.570964)
		(width 0.0889)
		(layer "In6.Cu")
		(net "M_E_CPU1_SB_CB<6>")
	)
	(segment
		(start 26.852372 -271.578578)
		(end 27.015186 -271.415764)
		(width 0.14478)
		(layer "In6.Cu")
		(net "M_E_CPU1_SB_CB<6>")
	)
	(segment
		(start 27.015186 -271.415764)
		(end 27.245818 -271.415764)
		(width 0.14478)
		(layer "In6.Cu")
		(net "M_E_CPU1_SB_CB<6>")
	)
	(segment
		(start 28.358338 -271.833086)
		(end 28.521152 -271.9959)
		(width 0.14478)
		(layer "In6.Cu")
		(net "M_E_CPU1_SB_CB<6>")
	)
	(segment
		(start 34.5694 -271.710404)
		(end 59.724544 -271.710404)
		(width 0.14478)
		(layer "In6.Cu")
		(net "M_E_CPU1_SB_CB<6>")
	)
	(segment
		(start 27.408632 -272.397474)
		(end 27.571446 -272.560288)
		(width 0.14478)
		(layer "In6.Cu")
		(net "M_E_CPU1_SB_CB<6>")
	)
	(segment
		(start 26.689558 -272.560288)
		(end 26.852372 -272.397474)
		(width 0.14478)
		(layer "In6.Cu")
		(net "M_E_CPU1_SB_CB<6>")
	)
	(segment
		(start 79.368396 -269.71371)
		(end 79.37881 -269.719806)
		(width 0.0889)
		(layer "In6.Cu")
		(net "M_E_CPU1_SB_CB<6>")
	)
	(segment
		(start 28.521152 -272.397474)
		(end 28.683966 -272.560288)
		(width 0.14478)
		(layer "In6.Cu")
		(net "M_E_CPU1_SB_CB<6>")
	)
	(segment
		(start 75.974956 -268.051534)
		(end 76.228956 -268.051534)
		(width 0.0889)
		(layer "In6.Cu")
		(net "M_E_CPU1_SB_CB<6>")
	)
	(segment
		(start 27.571446 -272.560288)
		(end 27.802078 -272.560288)
		(width 0.14478)
		(layer "In6.Cu")
		(net "M_E_CPU1_SB_CB<6>")
	)
	(segment
		(start 79.934054 -269.71371)
		(end 79.942436 -269.708884)
		(width 0.0889)
		(layer "In6.Cu")
		(net "M_E_CPU1_SB_CB<6>")
	)
	(segment
		(start 25.152096 -272.98523)
		(end 25.739852 -272.397474)
		(width 0.14478)
		(layer "In6.Cu")
		(net "M_E_CPU1_SB_CB<6>")
	)
	(segment
		(start 28.683966 -272.560288)
		(end 33.719516 -272.560288)
		(width 0.14478)
		(layer "In6.Cu")
		(net "M_E_CPU1_SB_CB<6>")
	)
	(segment
		(start 79.360014 -269.708884)
		(end 79.368396 -269.71371)
		(width 0.0889)
		(layer "In6.Cu")
		(net "M_E_CPU1_SB_CB<6>")
	)
	(segment
		(start 76.228956 -268.051534)
		(end 76.748386 -268.570964)
		(width 0.0889)
		(layer "In6.Cu")
		(net "M_E_CPU1_SB_CB<6>")
	)
	(segment
		(start 28.521152 -271.9959)
		(end 28.521152 -272.397474)
		(width 0.14478)
		(layer "In6.Cu")
		(net "M_E_CPU1_SB_CB<6>")
	)
	(segment
		(start 59.724544 -271.710404)
		(end 63.383414 -268.051534)
		(width 0.14478)
		(layer "In6.Cu")
		(net "M_E_CPU1_SB_CB<6>")
	)
	(segment
		(start 25.739852 -272.397474)
		(end 25.739852 -271.578578)
		(width 0.14478)
		(layer "In6.Cu")
		(net "M_E_CPU1_SB_CB<6>")
	)
	(segment
		(start 63.383414 -268.051534)
		(end 75.974956 -268.051534)
		(width 0.14478)
		(layer "In6.Cu")
		(net "M_E_CPU1_SB_CB<6>")
	)
	(segment
		(start 26.852372 -272.397474)
		(end 26.852372 -271.578578)
		(width 0.14478)
		(layer "In6.Cu")
		(net "M_E_CPU1_SB_CB<6>")
	)
	(arc
		(start 78.994254 -269.71371)
		(mid 79.176505 -269.66336)
		(end 79.360014 -269.708884)
		(width 0.0889)
		(layer "In6.Cu")
		(net "M_E_CPU1_SB_CB<6>")
	)
	(arc
		(start 79.37881 -269.719806)
		(mid 79.657242 -269.789904)
		(end 79.934054 -269.71371)
		(width 0.0889)
		(layer "In6.Cu")
		(net "M_E_CPU1_SB_CB<6>")
	)
	(arc
		(start 78.443074 -269.722346)
		(mid 78.719803 -269.790029)
		(end 78.994254 -269.71371)
		(width 0.0889)
		(layer "In6.Cu")
		(net "M_E_CPU1_SB_CB<6>")
	)
	(arc
		(start 80.874108 -269.71371)
		(mid 81.030427 -269.664715)
		(end 81.192624 -269.687548)
		(width 0.0889)
		(layer "In6.Cu")
		(net "M_E_CPU1_SB_CB<6>")
	)
	(arc
		(start 79.942436 -269.708884)
		(mid 80.125944 -269.66339)
		(end 80.308196 -269.71371)
		(width 0.0889)
		(layer "In6.Cu")
		(net "M_E_CPU1_SB_CB<6>")
	)
	(arc
		(start 80.308196 -269.71371)
		(mid 80.591152 -269.789887)
		(end 80.874108 -269.71371)
		(width 0.0889)
		(layer "In6.Cu")
		(net "M_E_CPU1_SB_CB<6>")
	)
	(segment
		(start 83.408012 -269.770352)
		(end 82.940906 -270.03629)
		(width 0.10668)
		(layer "F.Cu")
		(net "M_E_CPU1_SB_CB<5>")
	)
	(segment
		(start 31.187644 -273.014948)
		(end 31.418276 -273.014948)
		(width 0.14478)
		(layer "In6.Cu")
		(net "M_E_CPU1_SB_CB<5>")
	)
	(segment
		(start 37.478208 -272.177764)
		(end 37.728144 -272.177764)
		(width 0.14478)
		(layer "In6.Cu")
		(net "M_E_CPU1_SB_CB<5>")
	)
	(segment
		(start 79.869792 -270.321532)
		(end 79.9338 -270.35887)
		(width 0.0889)
		(layer "In6.Cu")
		(net "M_E_CPU1_SB_CB<5>")
	)
	(segment
		(start 82.786982 -270.30172)
		(end 82.940906 -270.03629)
		(width 0.0889)
		(layer "In6.Cu")
		(net "M_E_CPU1_SB_CB<5>")
	)
	(segment
		(start 31.58109 -273.177762)
		(end 31.58109 -273.641058)
		(width 0.14478)
		(layer "In6.Cu")
		(net "M_E_CPU1_SB_CB<5>")
	)
	(segment
		(start 76.570586 -268.824964)
		(end 77.002386 -268.824964)
		(width 0.0889)
		(layer "In6.Cu")
		(net "M_E_CPU1_SB_CB<5>")
	)
	(segment
		(start 78.378558 -270.201136)
		(end 79.542132 -270.201136)
		(width 0.0889)
		(layer "In6.Cu")
		(net "M_E_CPU1_SB_CB<5>")
	)
	(segment
		(start 40.607996 -272.560288)
		(end 40.987472 -272.939764)
		(width 0.14478)
		(layer "In6.Cu")
		(net "M_E_CPU1_SB_CB<5>")
	)
	(segment
		(start 35.598354 -272.939764)
		(end 35.84829 -272.939764)
		(width 0.14478)
		(layer "In6.Cu")
		(net "M_E_CPU1_SB_CB<5>")
	)
	(segment
		(start 38.462966 -272.786602)
		(end 38.462966 -272.330926)
		(width 0.14478)
		(layer "In6.Cu")
		(net "M_E_CPU1_SB_CB<5>")
	)
	(segment
		(start 30.862016 -273.803872)
		(end 31.02483 -273.641058)
		(width 0.14478)
		(layer "In6.Cu")
		(net "M_E_CPU1_SB_CB<5>")
	)
	(segment
		(start 38.616128 -272.177764)
		(end 38.866064 -272.177764)
		(width 0.14478)
		(layer "In6.Cu")
		(net "M_E_CPU1_SB_CB<5>")
	)
	(segment
		(start 41.218104 -272.939764)
		(end 41.380918 -272.77695)
		(width 0.14478)
		(layer "In6.Cu")
		(net "M_E_CPU1_SB_CB<5>")
	)
	(segment
		(start 30.305756 -273.014948)
		(end 30.46857 -273.177762)
		(width 0.14478)
		(layer "In6.Cu")
		(net "M_E_CPU1_SB_CB<5>")
	)
	(segment
		(start 35.295332 -272.177764)
		(end 35.445192 -272.327624)
		(width 0.14478)
		(layer "In6.Cu")
		(net "M_E_CPU1_SB_CB<5>")
	)
	(segment
		(start 40.987472 -272.939764)
		(end 41.218104 -272.939764)
		(width 0.14478)
		(layer "In6.Cu")
		(net "M_E_CPU1_SB_CB<5>")
	)
	(segment
		(start 38.462966 -272.330926)
		(end 38.616128 -272.177764)
		(width 0.14478)
		(layer "In6.Cu")
		(net "M_E_CPU1_SB_CB<5>")
	)
	(segment
		(start 30.631384 -273.803872)
		(end 30.862016 -273.803872)
		(width 0.14478)
		(layer "In6.Cu")
		(net "M_E_CPU1_SB_CB<5>")
	)
	(segment
		(start 31.58109 -273.641058)
		(end 31.743904 -273.803872)
		(width 0.14478)
		(layer "In6.Cu")
		(net "M_E_CPU1_SB_CB<5>")
	)
	(segment
		(start 39.422324 -272.942812)
		(end 39.804848 -272.560288)
		(width 0.14478)
		(layer "In6.Cu")
		(net "M_E_CPU1_SB_CB<5>")
	)
	(segment
		(start 76.251816 -268.506194)
		(end 76.570586 -268.824964)
		(width 0.0889)
		(layer "In6.Cu")
		(net "M_E_CPU1_SB_CB<5>")
	)
	(segment
		(start 29.252164 -273.835368)
		(end 30.072584 -273.014948)
		(width 0.14478)
		(layer "In6.Cu")
		(net "M_E_CPU1_SB_CB<5>")
	)
	(segment
		(start 42.886884 -272.180812)
		(end 43.049698 -272.343626)
		(width 0.14478)
		(layer "In6.Cu")
		(net "M_E_CPU1_SB_CB<5>")
	)
	(segment
		(start 38.309804 -272.939764)
		(end 38.462966 -272.786602)
		(width 0.14478)
		(layer "In6.Cu")
		(net "M_E_CPU1_SB_CB<5>")
	)
	(segment
		(start 59.510676 -272.560288)
		(end 63.56477 -268.506194)
		(width 0.14478)
		(layer "In6.Cu")
		(net "M_E_CPU1_SB_CB<5>")
	)
	(segment
		(start 39.804848 -272.560288)
		(end 40.607996 -272.560288)
		(width 0.14478)
		(layer "In6.Cu")
		(net "M_E_CPU1_SB_CB<5>")
	)
	(segment
		(start 36.227766 -272.560288)
		(end 37.095684 -272.560288)
		(width 0.14478)
		(layer "In6.Cu")
		(net "M_E_CPU1_SB_CB<5>")
	)
	(segment
		(start 37.095684 -272.560288)
		(end 37.478208 -272.177764)
		(width 0.14478)
		(layer "In6.Cu")
		(net "M_E_CPU1_SB_CB<5>")
	)
	(segment
		(start 35.84829 -272.939764)
		(end 36.227766 -272.560288)
		(width 0.14478)
		(layer "In6.Cu")
		(net "M_E_CPU1_SB_CB<5>")
	)
	(segment
		(start 32.367982 -273.410426)
		(end 33.834832 -273.410426)
		(width 0.14478)
		(layer "In6.Cu")
		(net "M_E_CPU1_SB_CB<5>")
	)
	(segment
		(start 31.02483 -273.177762)
		(end 31.187644 -273.014948)
		(width 0.14478)
		(layer "In6.Cu")
		(net "M_E_CPU1_SB_CB<5>")
	)
	(segment
		(start 38.866064 -272.177764)
		(end 39.019226 -272.330926)
		(width 0.14478)
		(layer "In6.Cu")
		(net "M_E_CPU1_SB_CB<5>")
	)
	(segment
		(start 37.906706 -272.356326)
		(end 37.906706 -272.786602)
		(width 0.14478)
		(layer "In6.Cu")
		(net "M_E_CPU1_SB_CB<5>")
	)
	(segment
		(start 35.445192 -272.327624)
		(end 35.445192 -272.786602)
		(width 0.14478)
		(layer "In6.Cu")
		(net "M_E_CPU1_SB_CB<5>")
	)
	(segment
		(start 41.380918 -272.77695)
		(end 41.380918 -272.343626)
		(width 0.14478)
		(layer "In6.Cu")
		(net "M_E_CPU1_SB_CB<5>")
	)
	(segment
		(start 30.46857 -273.641058)
		(end 30.631384 -273.803872)
		(width 0.14478)
		(layer "In6.Cu")
		(net "M_E_CPU1_SB_CB<5>")
	)
	(segment
		(start 41.937178 -272.343626)
		(end 41.937178 -272.77695)
		(width 0.14478)
		(layer "In6.Cu")
		(net "M_E_CPU1_SB_CB<5>")
	)
	(segment
		(start 42.493438 -272.77695)
		(end 42.493438 -272.343626)
		(width 0.14478)
		(layer "In6.Cu")
		(net "M_E_CPU1_SB_CB<5>")
	)
	(segment
		(start 39.019226 -272.330926)
		(end 39.019226 -272.78965)
		(width 0.14478)
		(layer "In6.Cu")
		(net "M_E_CPU1_SB_CB<5>")
	)
	(segment
		(start 41.543732 -272.180812)
		(end 41.774364 -272.180812)
		(width 0.14478)
		(layer "In6.Cu")
		(net "M_E_CPU1_SB_CB<5>")
	)
	(segment
		(start 31.974536 -273.803872)
		(end 32.367982 -273.410426)
		(width 0.14478)
		(layer "In6.Cu")
		(net "M_E_CPU1_SB_CB<5>")
	)
	(segment
		(start 77.002386 -268.824964)
		(end 78.378558 -270.201136)
		(width 0.0889)
		(layer "In6.Cu")
		(net "M_E_CPU1_SB_CB<5>")
	)
	(segment
		(start 39.172388 -272.942812)
		(end 39.422324 -272.942812)
		(width 0.14478)
		(layer "In6.Cu")
		(net "M_E_CPU1_SB_CB<5>")
	)
	(segment
		(start 42.656252 -272.180812)
		(end 42.886884 -272.180812)
		(width 0.14478)
		(layer "In6.Cu")
		(net "M_E_CPU1_SB_CB<5>")
	)
	(segment
		(start 43.049698 -272.343626)
		(end 43.049698 -272.77695)
		(width 0.14478)
		(layer "In6.Cu")
		(net "M_E_CPU1_SB_CB<5>")
	)
	(segment
		(start 35.067494 -272.177764)
		(end 35.295332 -272.177764)
		(width 0.14478)
		(layer "In6.Cu")
		(net "M_E_CPU1_SB_CB<5>")
	)
	(segment
		(start 42.493438 -272.343626)
		(end 42.656252 -272.180812)
		(width 0.14478)
		(layer "In6.Cu")
		(net "M_E_CPU1_SB_CB<5>")
	)
	(segment
		(start 82.179668 -270.363696)
		(end 82.18805 -270.35887)
		(width 0.0889)
		(layer "In6.Cu")
		(net "M_E_CPU1_SB_CB<5>")
	)
	(segment
		(start 39.019226 -272.78965)
		(end 39.172388 -272.942812)
		(width 0.14478)
		(layer "In6.Cu")
		(net "M_E_CPU1_SB_CB<5>")
	)
	(segment
		(start 37.728144 -272.177764)
		(end 37.906706 -272.356326)
		(width 0.14478)
		(layer "In6.Cu")
		(net "M_E_CPU1_SB_CB<5>")
	)
	(segment
		(start 41.937178 -272.77695)
		(end 42.099992 -272.939764)
		(width 0.14478)
		(layer "In6.Cu")
		(net "M_E_CPU1_SB_CB<5>")
	)
	(segment
		(start 43.049698 -272.77695)
		(end 43.212512 -272.939764)
		(width 0.14478)
		(layer "In6.Cu")
		(net "M_E_CPU1_SB_CB<5>")
	)
	(segment
		(start 42.099992 -272.939764)
		(end 42.330624 -272.939764)
		(width 0.14478)
		(layer "In6.Cu")
		(net "M_E_CPU1_SB_CB<5>")
	)
	(segment
		(start 75.947016 -268.506194)
		(end 76.251816 -268.506194)
		(width 0.0889)
		(layer "In6.Cu")
		(net "M_E_CPU1_SB_CB<5>")
	)
	(segment
		(start 43.212512 -272.939764)
		(end 43.443144 -272.939764)
		(width 0.14478)
		(layer "In6.Cu")
		(net "M_E_CPU1_SB_CB<5>")
	)
	(segment
		(start 41.774364 -272.180812)
		(end 41.937178 -272.343626)
		(width 0.14478)
		(layer "In6.Cu")
		(net "M_E_CPU1_SB_CB<5>")
	)
	(segment
		(start 38.059868 -272.939764)
		(end 38.309804 -272.939764)
		(width 0.14478)
		(layer "In6.Cu")
		(net "M_E_CPU1_SB_CB<5>")
	)
	(segment
		(start 37.906706 -272.786602)
		(end 38.059868 -272.939764)
		(width 0.14478)
		(layer "In6.Cu")
		(net "M_E_CPU1_SB_CB<5>")
	)
	(segment
		(start 82.69097 -270.32712)
		(end 82.786982 -270.30172)
		(width 0.0889)
		(layer "In6.Cu")
		(net "M_E_CPU1_SB_CB<5>")
	)
	(segment
		(start 31.02483 -273.641058)
		(end 31.02483 -273.177762)
		(width 0.14478)
		(layer "In6.Cu")
		(net "M_E_CPU1_SB_CB<5>")
	)
	(segment
		(start 31.743904 -273.803872)
		(end 31.974536 -273.803872)
		(width 0.14478)
		(layer "In6.Cu")
		(net "M_E_CPU1_SB_CB<5>")
	)
	(segment
		(start 41.380918 -272.343626)
		(end 41.543732 -272.180812)
		(width 0.14478)
		(layer "In6.Cu")
		(net "M_E_CPU1_SB_CB<5>")
	)
	(segment
		(start 35.445192 -272.786602)
		(end 35.598354 -272.939764)
		(width 0.14478)
		(layer "In6.Cu")
		(net "M_E_CPU1_SB_CB<5>")
	)
	(segment
		(start 42.330624 -272.939764)
		(end 42.493438 -272.77695)
		(width 0.14478)
		(layer "In6.Cu")
		(net "M_E_CPU1_SB_CB<5>")
	)
	(segment
		(start 33.834832 -273.410426)
		(end 35.067494 -272.177764)
		(width 0.14478)
		(layer "In6.Cu")
		(net "M_E_CPU1_SB_CB<5>")
	)
	(segment
		(start 63.56477 -268.506194)
		(end 75.947016 -268.506194)
		(width 0.14478)
		(layer "In6.Cu")
		(net "M_E_CPU1_SB_CB<5>")
	)
	(segment
		(start 31.418276 -273.014948)
		(end 31.58109 -273.177762)
		(width 0.14478)
		(layer "In6.Cu")
		(net "M_E_CPU1_SB_CB<5>")
	)
	(segment
		(start 30.46857 -273.177762)
		(end 30.46857 -273.641058)
		(width 0.14478)
		(layer "In6.Cu")
		(net "M_E_CPU1_SB_CB<5>")
	)
	(segment
		(start 43.443144 -272.939764)
		(end 43.82262 -272.560288)
		(width 0.14478)
		(layer "In6.Cu")
		(net "M_E_CPU1_SB_CB<5>")
	)
	(segment
		(start 43.82262 -272.560288)
		(end 59.510676 -272.560288)
		(width 0.14478)
		(layer "In6.Cu")
		(net "M_E_CPU1_SB_CB<5>")
	)
	(segment
		(start 30.072584 -273.014948)
		(end 30.305756 -273.014948)
		(width 0.14478)
		(layer "In6.Cu")
		(net "M_E_CPU1_SB_CB<5>")
	)
	(arc
		(start 82.18805 -270.35887)
		(mid 82.435763 -270.28365)
		(end 82.69097 -270.32712)
		(width 0.0889)
		(layer "In6.Cu")
		(net "M_E_CPU1_SB_CB<5>")
	)
	(arc
		(start 79.63027 -270.214852)
		(mid 79.752894 -270.261765)
		(end 79.869792 -270.321532)
		(width 0.0889)
		(layer "In6.Cu")
		(net "M_E_CPU1_SB_CB<5>")
	)
	(arc
		(start 81.813908 -270.35887)
		(mid 81.996159 -270.40922)
		(end 82.179668 -270.363696)
		(width 0.0889)
		(layer "In6.Cu")
		(net "M_E_CPU1_SB_CB<5>")
	)
	(arc
		(start 79.9338 -270.35887)
		(mid 80.120998 -270.409252)
		(end 80.308196 -270.35887)
		(width 0.0889)
		(layer "In6.Cu")
		(net "M_E_CPU1_SB_CB<5>")
	)
	(arc
		(start 80.308196 -270.35887)
		(mid 80.591152 -270.282693)
		(end 80.874108 -270.35887)
		(width 0.0889)
		(layer "In6.Cu")
		(net "M_E_CPU1_SB_CB<5>")
	)
	(arc
		(start 79.542132 -270.201136)
		(mid 79.586737 -270.204546)
		(end 79.63027 -270.214852)
		(width 0.0889)
		(layer "In6.Cu")
		(net "M_E_CPU1_SB_CB<5>")
	)
	(arc
		(start 80.874108 -270.35887)
		(mid 81.061052 -270.409125)
		(end 81.247996 -270.35887)
		(width 0.0889)
		(layer "In6.Cu")
		(net "M_E_CPU1_SB_CB<5>")
	)
	(arc
		(start 81.247996 -270.35887)
		(mid 81.530952 -270.282693)
		(end 81.813908 -270.35887)
		(width 0.0889)
		(layer "In6.Cu")
		(net "M_E_CPU1_SB_CB<5>")
	)
	(segment
		(start 81.997804 -268.960346)
		(end 81.530952 -269.226284)
		(width 0.10668)
		(layer "F.Cu")
		(net "M_E_CPU1_SB_CB<4>")
	)
	(segment
		(start 50.588926 -271.161764)
		(end 50.843688 -271.161764)
		(width 0.14478)
		(layer "In6.Cu")
		(net "M_E_CPU1_SB_CB<4>")
	)
	(segment
		(start 40.053514 -270.860266)
		(end 40.592502 -270.860266)
		(width 0.14478)
		(layer "In6.Cu")
		(net "M_E_CPU1_SB_CB<4>")
	)
	(segment
		(start 31.902146 -272.101564)
		(end 32.293306 -271.710404)
		(width 0.14478)
		(layer "In6.Cu")
		(net "M_E_CPU1_SB_CB<4>")
	)
	(segment
		(start 78.524354 -269.548864)
		(end 78.536038 -269.555722)
		(width 0.0889)
		(layer "In6.Cu")
		(net "M_E_CPU1_SB_CB<4>")
	)
	(segment
		(start 56.698896 -270.860266)
		(end 57.000394 -271.161764)
		(width 0.14478)
		(layer "In6.Cu")
		(net "M_E_CPU1_SB_CB<4>")
	)
	(segment
		(start 42.817542 -270.860266)
		(end 43.11904 -271.161764)
		(width 0.14478)
		(layer "In6.Cu")
		(net "M_E_CPU1_SB_CB<4>")
	)
	(segment
		(start 38.384734 -271.136364)
		(end 38.664896 -271.136364)
		(width 0.14478)
		(layer "In6.Cu")
		(net "M_E_CPU1_SB_CB<4>")
	)
	(segment
		(start 30.789626 -272.101564)
		(end 30.95244 -271.93875)
		(width 0.14478)
		(layer "In6.Cu")
		(net "M_E_CPU1_SB_CB<4>")
	)
	(segment
		(start 35.388296 -271.161764)
		(end 35.643058 -271.161764)
		(width 0.14478)
		(layer "In6.Cu")
		(net "M_E_CPU1_SB_CB<4>")
	)
	(segment
		(start 30.39618 -271.93875)
		(end 30.558994 -272.101564)
		(width 0.14478)
		(layer "In6.Cu")
		(net "M_E_CPU1_SB_CB<4>")
	)
	(segment
		(start 42.261282 -271.161764)
		(end 42.56278 -270.860266)
		(width 0.14478)
		(layer "In6.Cu")
		(net "M_E_CPU1_SB_CB<4>")
	)
	(segment
		(start 79.449422 -269.540228)
		(end 79.464154 -269.548864)
		(width 0.0889)
		(layer "In6.Cu")
		(net "M_E_CPU1_SB_CB<4>")
	)
	(segment
		(start 52.248816 -270.860266)
		(end 52.550314 -271.161764)
		(width 0.14478)
		(layer "In6.Cu")
		(net "M_E_CPU1_SB_CB<4>")
	)
	(segment
		(start 29.252164 -272.135346)
		(end 29.83992 -271.54759)
		(width 0.14478)
		(layer "In6.Cu")
		(net "M_E_CPU1_SB_CB<4>")
	)
	(segment
		(start 31.115254 -270.806164)
		(end 31.345886 -270.806164)
		(width 0.14478)
		(layer "In6.Cu")
		(net "M_E_CPU1_SB_CB<4>")
	)
	(segment
		(start 38.664896 -271.136364)
		(end 38.940994 -270.860266)
		(width 0.14478)
		(layer "In6.Cu")
		(net "M_E_CPU1_SB_CB<4>")
	)
	(segment
		(start 33.756854 -271.710404)
		(end 34.606992 -270.860266)
		(width 0.14478)
		(layer "In6.Cu")
		(net "M_E_CPU1_SB_CB<4>")
	)
	(segment
		(start 41.705022 -270.860266)
		(end 42.00652 -271.161764)
		(width 0.14478)
		(layer "In6.Cu")
		(net "M_E_CPU1_SB_CB<4>")
	)
	(segment
		(start 57.556654 -270.860266)
		(end 57.811416 -270.860266)
		(width 0.14478)
		(layer "In6.Cu")
		(net "M_E_CPU1_SB_CB<4>")
	)
	(segment
		(start 41.45026 -270.860266)
		(end 41.705022 -270.860266)
		(width 0.14478)
		(layer "In6.Cu")
		(net "M_E_CPU1_SB_CB<4>")
	)
	(segment
		(start 52.550314 -271.161764)
		(end 52.805076 -271.161764)
		(width 0.14478)
		(layer "In6.Cu")
		(net "M_E_CPU1_SB_CB<4>")
	)
	(segment
		(start 32.293306 -271.710404)
		(end 33.756854 -271.710404)
		(width 0.14478)
		(layer "In6.Cu")
		(net "M_E_CPU1_SB_CB<4>")
	)
	(segment
		(start 56.444134 -270.860266)
		(end 56.698896 -270.860266)
		(width 0.14478)
		(layer "In6.Cu")
		(net "M_E_CPU1_SB_CB<4>")
	)
	(segment
		(start 40.894 -271.161764)
		(end 41.148762 -271.161764)
		(width 0.14478)
		(layer "In6.Cu")
		(net "M_E_CPU1_SB_CB<4>")
	)
	(segment
		(start 37.552376 -271.136364)
		(end 37.828474 -270.860266)
		(width 0.14478)
		(layer "In6.Cu")
		(net "M_E_CPU1_SB_CB<4>")
	)
	(segment
		(start 47.057564 -271.136364)
		(end 47.337726 -271.136364)
		(width 0.14478)
		(layer "In6.Cu")
		(net "M_E_CPU1_SB_CB<4>")
	)
	(segment
		(start 39.777416 -271.136364)
		(end 40.053514 -270.860266)
		(width 0.14478)
		(layer "In6.Cu")
		(net "M_E_CPU1_SB_CB<4>")
	)
	(segment
		(start 36.996116 -270.860266)
		(end 37.272214 -271.136364)
		(width 0.14478)
		(layer "In6.Cu")
		(net "M_E_CPU1_SB_CB<4>")
	)
	(segment
		(start 39.221156 -270.860266)
		(end 39.497254 -271.136364)
		(width 0.14478)
		(layer "In6.Cu")
		(net "M_E_CPU1_SB_CB<4>")
	)
	(segment
		(start 30.002734 -270.806164)
		(end 30.233366 -270.806164)
		(width 0.14478)
		(layer "In6.Cu")
		(net "M_E_CPU1_SB_CB<4>")
	)
	(segment
		(start 55.887874 -271.161764)
		(end 56.142636 -271.161764)
		(width 0.14478)
		(layer "In6.Cu")
		(net "M_E_CPU1_SB_CB<4>")
	)
	(segment
		(start 34.606992 -270.860266)
		(end 35.086798 -270.860266)
		(width 0.14478)
		(layer "In6.Cu")
		(net "M_E_CPU1_SB_CB<4>")
	)
	(segment
		(start 46.781466 -270.860266)
		(end 47.057564 -271.136364)
		(width 0.14478)
		(layer "In6.Cu")
		(net "M_E_CPU1_SB_CB<4>")
	)
	(segment
		(start 44.556426 -270.860266)
		(end 44.832524 -271.136364)
		(width 0.14478)
		(layer "In6.Cu")
		(net "M_E_CPU1_SB_CB<4>")
	)
	(segment
		(start 38.940994 -270.860266)
		(end 39.221156 -270.860266)
		(width 0.14478)
		(layer "In6.Cu")
		(net "M_E_CPU1_SB_CB<4>")
	)
	(segment
		(start 45.945044 -271.136364)
		(end 46.225206 -271.136364)
		(width 0.14478)
		(layer "In6.Cu")
		(net "M_E_CPU1_SB_CB<4>")
	)
	(segment
		(start 46.225206 -271.136364)
		(end 46.501304 -270.860266)
		(width 0.14478)
		(layer "In6.Cu")
		(net "M_E_CPU1_SB_CB<4>")
	)
	(segment
		(start 37.828474 -270.860266)
		(end 38.108636 -270.860266)
		(width 0.14478)
		(layer "In6.Cu")
		(net "M_E_CPU1_SB_CB<4>")
	)
	(segment
		(start 53.917596 -271.161764)
		(end 54.219094 -270.860266)
		(width 0.14478)
		(layer "In6.Cu")
		(net "M_E_CPU1_SB_CB<4>")
	)
	(segment
		(start 30.558994 -272.101564)
		(end 30.789626 -272.101564)
		(width 0.14478)
		(layer "In6.Cu")
		(net "M_E_CPU1_SB_CB<4>")
	)
	(segment
		(start 56.142636 -271.161764)
		(end 56.444134 -270.860266)
		(width 0.14478)
		(layer "In6.Cu")
		(net "M_E_CPU1_SB_CB<4>")
	)
	(segment
		(start 31.5087 -270.968978)
		(end 31.5087 -271.93875)
		(width 0.14478)
		(layer "In6.Cu")
		(net "M_E_CPU1_SB_CB<4>")
	)
	(segment
		(start 53.106574 -270.860266)
		(end 53.361336 -270.860266)
		(width 0.14478)
		(layer "In6.Cu")
		(net "M_E_CPU1_SB_CB<4>")
	)
	(segment
		(start 50.843688 -271.161764)
		(end 51.145186 -270.860266)
		(width 0.14478)
		(layer "In6.Cu")
		(net "M_E_CPU1_SB_CB<4>")
	)
	(segment
		(start 30.233366 -270.806164)
		(end 30.39618 -270.968978)
		(width 0.14478)
		(layer "In6.Cu")
		(net "M_E_CPU1_SB_CB<4>")
	)
	(segment
		(start 49.476406 -271.161764)
		(end 49.731168 -271.161764)
		(width 0.14478)
		(layer "In6.Cu")
		(net "M_E_CPU1_SB_CB<4>")
	)
	(segment
		(start 48.062388 -270.860266)
		(end 48.363886 -271.161764)
		(width 0.14478)
		(layer "In6.Cu")
		(net "M_E_CPU1_SB_CB<4>")
	)
	(segment
		(start 46.501304 -270.860266)
		(end 46.781466 -270.860266)
		(width 0.14478)
		(layer "In6.Cu")
		(net "M_E_CPU1_SB_CB<4>")
	)
	(segment
		(start 59.938666 -270.860266)
		(end 63.202058 -267.596874)
		(width 0.14478)
		(layer "In6.Cu")
		(net "M_E_CPU1_SB_CB<4>")
	)
	(segment
		(start 29.83992 -270.968978)
		(end 30.002734 -270.806164)
		(width 0.14478)
		(layer "In6.Cu")
		(net "M_E_CPU1_SB_CB<4>")
	)
	(segment
		(start 49.731168 -271.161764)
		(end 50.032666 -270.860266)
		(width 0.14478)
		(layer "In6.Cu")
		(net "M_E_CPU1_SB_CB<4>")
	)
	(segment
		(start 48.920146 -270.860266)
		(end 49.174908 -270.860266)
		(width 0.14478)
		(layer "In6.Cu")
		(net "M_E_CPU1_SB_CB<4>")
	)
	(segment
		(start 58.112914 -271.161764)
		(end 58.367676 -271.161764)
		(width 0.14478)
		(layer "In6.Cu")
		(net "M_E_CPU1_SB_CB<4>")
	)
	(segment
		(start 35.643058 -271.161764)
		(end 35.944556 -270.860266)
		(width 0.14478)
		(layer "In6.Cu")
		(net "M_E_CPU1_SB_CB<4>")
	)
	(segment
		(start 75.969876 -267.596874)
		(end 77.094842 -267.596874)
		(width 0.0889)
		(layer "In6.Cu")
		(net "M_E_CPU1_SB_CB<4>")
	)
	(segment
		(start 81.377028 -269.491714)
		(end 81.530952 -269.226284)
		(width 0.0889)
		(layer "In6.Cu")
		(net "M_E_CPU1_SB_CB<4>")
	)
	(segment
		(start 54.473856 -270.860266)
		(end 54.775354 -271.161764)
		(width 0.14478)
		(layer "In6.Cu")
		(net "M_E_CPU1_SB_CB<4>")
	)
	(segment
		(start 43.373802 -271.161764)
		(end 43.6753 -270.860266)
		(width 0.14478)
		(layer "In6.Cu")
		(net "M_E_CPU1_SB_CB<4>")
	)
	(segment
		(start 48.363886 -271.161764)
		(end 48.618648 -271.161764)
		(width 0.14478)
		(layer "In6.Cu")
		(net "M_E_CPU1_SB_CB<4>")
	)
	(segment
		(start 31.5087 -271.93875)
		(end 31.671514 -272.101564)
		(width 0.14478)
		(layer "In6.Cu")
		(net "M_E_CPU1_SB_CB<4>")
	)
	(segment
		(start 50.032666 -270.860266)
		(end 50.287428 -270.860266)
		(width 0.14478)
		(layer "In6.Cu")
		(net "M_E_CPU1_SB_CB<4>")
	)
	(segment
		(start 45.668946 -270.860266)
		(end 45.945044 -271.136364)
		(width 0.14478)
		(layer "In6.Cu")
		(net "M_E_CPU1_SB_CB<4>")
	)
	(segment
		(start 54.219094 -270.860266)
		(end 54.473856 -270.860266)
		(width 0.14478)
		(layer "In6.Cu")
		(net "M_E_CPU1_SB_CB<4>")
	)
	(segment
		(start 81.281016 -269.517114)
		(end 81.377028 -269.491714)
		(width 0.0889)
		(layer "In6.Cu")
		(net "M_E_CPU1_SB_CB<4>")
	)
	(segment
		(start 80.769714 -269.55369)
		(end 80.778096 -269.548864)
		(width 0.0889)
		(layer "In6.Cu")
		(net "M_E_CPU1_SB_CB<4>")
	)
	(segment
		(start 48.618648 -271.161764)
		(end 48.920146 -270.860266)
		(width 0.14478)
		(layer "In6.Cu")
		(net "M_E_CPU1_SB_CB<4>")
	)
	(segment
		(start 42.00652 -271.161764)
		(end 42.261282 -271.161764)
		(width 0.14478)
		(layer "In6.Cu")
		(net "M_E_CPU1_SB_CB<4>")
	)
	(segment
		(start 49.174908 -270.860266)
		(end 49.476406 -271.161764)
		(width 0.14478)
		(layer "In6.Cu")
		(net "M_E_CPU1_SB_CB<4>")
	)
	(segment
		(start 41.148762 -271.161764)
		(end 41.45026 -270.860266)
		(width 0.14478)
		(layer "In6.Cu")
		(net "M_E_CPU1_SB_CB<4>")
	)
	(segment
		(start 44.832524 -271.136364)
		(end 45.112686 -271.136364)
		(width 0.14478)
		(layer "In6.Cu")
		(net "M_E_CPU1_SB_CB<4>")
	)
	(segment
		(start 55.586376 -270.860266)
		(end 55.887874 -271.161764)
		(width 0.14478)
		(layer "In6.Cu")
		(net "M_E_CPU1_SB_CB<4>")
	)
	(segment
		(start 45.112686 -271.136364)
		(end 45.388784 -270.860266)
		(width 0.14478)
		(layer "In6.Cu")
		(net "M_E_CPU1_SB_CB<4>")
	)
	(segment
		(start 52.805076 -271.161764)
		(end 53.106574 -270.860266)
		(width 0.14478)
		(layer "In6.Cu")
		(net "M_E_CPU1_SB_CB<4>")
	)
	(segment
		(start 30.95244 -270.968978)
		(end 31.115254 -270.806164)
		(width 0.14478)
		(layer "In6.Cu")
		(net "M_E_CPU1_SB_CB<4>")
	)
	(segment
		(start 53.361336 -270.860266)
		(end 53.662834 -271.161764)
		(width 0.14478)
		(layer "In6.Cu")
		(net "M_E_CPU1_SB_CB<4>")
	)
	(segment
		(start 58.367676 -271.161764)
		(end 58.669174 -270.860266)
		(width 0.14478)
		(layer "In6.Cu")
		(net "M_E_CPU1_SB_CB<4>")
	)
	(segment
		(start 51.145186 -270.860266)
		(end 52.248816 -270.860266)
		(width 0.14478)
		(layer "In6.Cu")
		(net "M_E_CPU1_SB_CB<4>")
	)
	(segment
		(start 39.497254 -271.136364)
		(end 39.777416 -271.136364)
		(width 0.14478)
		(layer "In6.Cu")
		(net "M_E_CPU1_SB_CB<4>")
	)
	(segment
		(start 30.39618 -270.968978)
		(end 30.39618 -271.93875)
		(width 0.14478)
		(layer "In6.Cu")
		(net "M_E_CPU1_SB_CB<4>")
	)
	(segment
		(start 35.944556 -270.860266)
		(end 36.996116 -270.860266)
		(width 0.14478)
		(layer "In6.Cu")
		(net "M_E_CPU1_SB_CB<4>")
	)
	(segment
		(start 43.11904 -271.161764)
		(end 43.373802 -271.161764)
		(width 0.14478)
		(layer "In6.Cu")
		(net "M_E_CPU1_SB_CB<4>")
	)
	(segment
		(start 55.331614 -270.860266)
		(end 55.586376 -270.860266)
		(width 0.14478)
		(layer "In6.Cu")
		(net "M_E_CPU1_SB_CB<4>")
	)
	(segment
		(start 30.95244 -271.93875)
		(end 30.95244 -270.968978)
		(width 0.14478)
		(layer "In6.Cu")
		(net "M_E_CPU1_SB_CB<4>")
	)
	(segment
		(start 29.83992 -271.54759)
		(end 29.83992 -270.968978)
		(width 0.14478)
		(layer "In6.Cu")
		(net "M_E_CPU1_SB_CB<4>")
	)
	(segment
		(start 57.255156 -271.161764)
		(end 57.556654 -270.860266)
		(width 0.14478)
		(layer "In6.Cu")
		(net "M_E_CPU1_SB_CB<4>")
	)
	(segment
		(start 53.662834 -271.161764)
		(end 53.917596 -271.161764)
		(width 0.14478)
		(layer "In6.Cu")
		(net "M_E_CPU1_SB_CB<4>")
	)
	(segment
		(start 77.484986 -267.987018)
		(end 77.484986 -268.51991)
		(width 0.0889)
		(layer "In6.Cu")
		(net "M_E_CPU1_SB_CB<4>")
	)
	(segment
		(start 40.592502 -270.860266)
		(end 40.894 -271.161764)
		(width 0.14478)
		(layer "In6.Cu")
		(net "M_E_CPU1_SB_CB<4>")
	)
	(segment
		(start 77.484986 -268.51991)
		(end 78.524354 -269.548864)
		(width 0.0889)
		(layer "In6.Cu")
		(net "M_E_CPU1_SB_CB<4>")
	)
	(segment
		(start 31.345886 -270.806164)
		(end 31.5087 -270.968978)
		(width 0.14478)
		(layer "In6.Cu")
		(net "M_E_CPU1_SB_CB<4>")
	)
	(segment
		(start 35.086798 -270.860266)
		(end 35.388296 -271.161764)
		(width 0.14478)
		(layer "In6.Cu")
		(net "M_E_CPU1_SB_CB<4>")
	)
	(segment
		(start 31.671514 -272.101564)
		(end 31.902146 -272.101564)
		(width 0.14478)
		(layer "In6.Cu")
		(net "M_E_CPU1_SB_CB<4>")
	)
	(segment
		(start 47.337726 -271.136364)
		(end 47.613824 -270.860266)
		(width 0.14478)
		(layer "In6.Cu")
		(net "M_E_CPU1_SB_CB<4>")
	)
	(segment
		(start 63.202058 -267.596874)
		(end 75.969876 -267.596874)
		(width 0.14478)
		(layer "In6.Cu")
		(net "M_E_CPU1_SB_CB<4>")
	)
	(segment
		(start 57.811416 -270.860266)
		(end 58.112914 -271.161764)
		(width 0.14478)
		(layer "In6.Cu")
		(net "M_E_CPU1_SB_CB<4>")
	)
	(segment
		(start 54.775354 -271.161764)
		(end 55.030116 -271.161764)
		(width 0.14478)
		(layer "In6.Cu")
		(net "M_E_CPU1_SB_CB<4>")
	)
	(segment
		(start 37.272214 -271.136364)
		(end 37.552376 -271.136364)
		(width 0.14478)
		(layer "In6.Cu")
		(net "M_E_CPU1_SB_CB<4>")
	)
	(segment
		(start 55.030116 -271.161764)
		(end 55.331614 -270.860266)
		(width 0.14478)
		(layer "In6.Cu")
		(net "M_E_CPU1_SB_CB<4>")
	)
	(segment
		(start 47.613824 -270.860266)
		(end 48.062388 -270.860266)
		(width 0.14478)
		(layer "In6.Cu")
		(net "M_E_CPU1_SB_CB<4>")
	)
	(segment
		(start 43.6753 -270.860266)
		(end 44.556426 -270.860266)
		(width 0.14478)
		(layer "In6.Cu")
		(net "M_E_CPU1_SB_CB<4>")
	)
	(segment
		(start 45.388784 -270.860266)
		(end 45.668946 -270.860266)
		(width 0.14478)
		(layer "In6.Cu")
		(net "M_E_CPU1_SB_CB<4>")
	)
	(segment
		(start 42.56278 -270.860266)
		(end 42.817542 -270.860266)
		(width 0.14478)
		(layer "In6.Cu")
		(net "M_E_CPU1_SB_CB<4>")
	)
	(segment
		(start 38.108636 -270.860266)
		(end 38.384734 -271.136364)
		(width 0.14478)
		(layer "In6.Cu")
		(net "M_E_CPU1_SB_CB<4>")
	)
	(segment
		(start 58.669174 -270.860266)
		(end 59.938666 -270.860266)
		(width 0.14478)
		(layer "In6.Cu")
		(net "M_E_CPU1_SB_CB<4>")
	)
	(segment
		(start 77.094842 -267.596874)
		(end 77.484986 -267.987018)
		(width 0.0889)
		(layer "In6.Cu")
		(net "M_E_CPU1_SB_CB<4>")
	)
	(segment
		(start 50.287428 -270.860266)
		(end 50.588926 -271.161764)
		(width 0.14478)
		(layer "In6.Cu")
		(net "M_E_CPU1_SB_CB<4>")
	)
	(segment
		(start 57.000394 -271.161764)
		(end 57.255156 -271.161764)
		(width 0.14478)
		(layer "In6.Cu")
		(net "M_E_CPU1_SB_CB<4>")
	)
	(arc
		(start 78.898242 -269.548864)
		(mid 79.172694 -269.472628)
		(end 79.449422 -269.540228)
		(width 0.0889)
		(layer "In6.Cu")
		(net "M_E_CPU1_SB_CB<4>")
	)
	(arc
		(start 78.536038 -269.555722)
		(mid 78.718039 -269.599255)
		(end 78.898242 -269.548864)
		(width 0.0889)
		(layer "In6.Cu")
		(net "M_E_CPU1_SB_CB<4>")
	)
	(arc
		(start 79.464154 -269.548864)
		(mid 79.651098 -269.599119)
		(end 79.838042 -269.548864)
		(width 0.0889)
		(layer "In6.Cu")
		(net "M_E_CPU1_SB_CB<4>")
	)
	(arc
		(start 80.778096 -269.548864)
		(mid 81.025809 -269.473644)
		(end 81.281016 -269.517114)
		(width 0.0889)
		(layer "In6.Cu")
		(net "M_E_CPU1_SB_CB<4>")
	)
	(arc
		(start 80.403954 -269.548864)
		(mid 80.586205 -269.599214)
		(end 80.769714 -269.55369)
		(width 0.0889)
		(layer "In6.Cu")
		(net "M_E_CPU1_SB_CB<4>")
	)
	(arc
		(start 79.838042 -269.548864)
		(mid 80.120998 -269.472687)
		(end 80.403954 -269.548864)
		(width 0.0889)
		(layer "In6.Cu")
		(net "M_E_CPU1_SB_CB<4>")
	)
	(segment
		(start 82.937858 -273.820382)
		(end 82.471006 -274.08632)
		(width 0.10668)
		(layer "F.Cu")
		(net "M_E_CPU1_SB_CB<3>")
	)
	(segment
		(start 76.221336 -272.664174)
		(end 76.377546 -272.507964)
		(width 0.0889)
		(layer "In6.Cu")
		(net "M_E_CPU1_SB_CB<3>")
	)
	(segment
		(start 60.64123 -277.982172)
		(end 65.959228 -272.664174)
		(width 0.14478)
		(layer "In6.Cu")
		(net "M_E_CPU1_SB_CB<3>")
	)
	(segment
		(start 53.678328 -281.060398)
		(end 56.926988 -281.060398)
		(width 0.14478)
		(layer "In6.Cu")
		(net "M_E_CPU1_SB_CB<3>")
	)
	(segment
		(start 82.62493 -273.82089)
		(end 82.471006 -274.08632)
		(width 0.0889)
		(layer "In6.Cu")
		(net "M_E_CPU1_SB_CB<3>")
	)
	(segment
		(start 34.337752 -281.060398)
		(end 35.18789 -280.21026)
		(width 0.14478)
		(layer "In6.Cu")
		(net "M_E_CPU1_SB_CB<3>")
	)
	(segment
		(start 46.007528 -281.060398)
		(end 49.543716 -281.060398)
		(width 0.14478)
		(layer "In6.Cu")
		(net "M_E_CPU1_SB_CB<3>")
	)
	(segment
		(start 50.393854 -280.21026)
		(end 52.82819 -280.21026)
		(width 0.14478)
		(layer "In6.Cu")
		(net "M_E_CPU1_SB_CB<3>")
	)
	(segment
		(start 45.159168 -280.212038)
		(end 46.007528 -281.060398)
		(width 0.14478)
		(layer "In6.Cu")
		(net "M_E_CPU1_SB_CB<3>")
	)
	(segment
		(start 59.908186 -279.809702)
		(end 60.64123 -279.076658)
		(width 0.14478)
		(layer "In6.Cu")
		(net "M_E_CPU1_SB_CB<3>")
	)
	(segment
		(start 60.64123 -279.076658)
		(end 60.64123 -277.982172)
		(width 0.14478)
		(layer "In6.Cu")
		(net "M_E_CPU1_SB_CB<3>")
	)
	(segment
		(start 52.82819 -280.21026)
		(end 53.678328 -281.060398)
		(width 0.14478)
		(layer "In6.Cu")
		(net "M_E_CPU1_SB_CB<3>")
	)
	(segment
		(start 25.152096 -280.635202)
		(end 25.577292 -281.060398)
		(width 0.14478)
		(layer "In6.Cu")
		(net "M_E_CPU1_SB_CB<3>")
	)
	(segment
		(start 35.18789 -280.21026)
		(end 37.646102 -280.21026)
		(width 0.14478)
		(layer "In6.Cu")
		(net "M_E_CPU1_SB_CB<3>")
	)
	(segment
		(start 65.959228 -272.664174)
		(end 76.221336 -272.664174)
		(width 0.14478)
		(layer "In6.Cu")
		(net "M_E_CPU1_SB_CB<3>")
	)
	(segment
		(start 80.769714 -273.758914)
		(end 80.778096 -273.76374)
		(width 0.0889)
		(layer "In6.Cu")
		(net "M_E_CPU1_SB_CB<3>")
	)
	(segment
		(start 76.377546 -272.507964)
		(end 77.222858 -272.507964)
		(width 0.0889)
		(layer "In6.Cu")
		(net "M_E_CPU1_SB_CB<3>")
	)
	(segment
		(start 42.364152 -281.060398)
		(end 43.212512 -280.212038)
		(width 0.14478)
		(layer "In6.Cu")
		(net "M_E_CPU1_SB_CB<3>")
	)
	(segment
		(start 77.222858 -272.507964)
		(end 78.435454 -273.72056)
		(width 0.0889)
		(layer "In6.Cu")
		(net "M_E_CPU1_SB_CB<3>")
	)
	(segment
		(start 25.577292 -281.060398)
		(end 34.337752 -281.060398)
		(width 0.14478)
		(layer "In6.Cu")
		(net "M_E_CPU1_SB_CB<3>")
	)
	(segment
		(start 37.646102 -280.21026)
		(end 38.49624 -281.060398)
		(width 0.14478)
		(layer "In6.Cu")
		(net "M_E_CPU1_SB_CB<3>")
	)
	(segment
		(start 38.49624 -281.060398)
		(end 42.364152 -281.060398)
		(width 0.14478)
		(layer "In6.Cu")
		(net "M_E_CPU1_SB_CB<3>")
	)
	(segment
		(start 43.212512 -280.212038)
		(end 45.159168 -280.212038)
		(width 0.14478)
		(layer "In6.Cu")
		(net "M_E_CPU1_SB_CB<3>")
	)
	(segment
		(start 82.602578 -273.737578)
		(end 82.62493 -273.82089)
		(width 0.0889)
		(layer "In6.Cu")
		(net "M_E_CPU1_SB_CB<3>")
	)
	(segment
		(start 58.177684 -279.809702)
		(end 59.908186 -279.809702)
		(width 0.14478)
		(layer "In6.Cu")
		(net "M_E_CPU1_SB_CB<3>")
	)
	(segment
		(start 78.435454 -273.72056)
		(end 79.616046 -273.72056)
		(width 0.0889)
		(layer "In6.Cu")
		(net "M_E_CPU1_SB_CB<3>")
	)
	(segment
		(start 81.344008 -273.76374)
		(end 81.35239 -273.758914)
		(width 0.0889)
		(layer "In6.Cu")
		(net "M_E_CPU1_SB_CB<3>")
	)
	(segment
		(start 49.543716 -281.060398)
		(end 50.393854 -280.21026)
		(width 0.14478)
		(layer "In6.Cu")
		(net "M_E_CPU1_SB_CB<3>")
	)
	(segment
		(start 56.926988 -281.060398)
		(end 58.177684 -279.809702)
		(width 0.14478)
		(layer "In6.Cu")
		(net "M_E_CPU1_SB_CB<3>")
	)
	(arc
		(start 81.35239 -273.758914)
		(mid 81.535898 -273.71342)
		(end 81.71815 -273.76374)
		(width 0.0889)
		(layer "In6.Cu")
		(net "M_E_CPU1_SB_CB<3>")
	)
	(arc
		(start 79.616046 -273.72056)
		(mid 79.745762 -273.73569)
		(end 79.868522 -273.78025)
		(width 0.0889)
		(layer "In6.Cu")
		(net "M_E_CPU1_SB_CB<3>")
	)
	(arc
		(start 81.71815 -273.76374)
		(mid 82.001106 -273.839917)
		(end 82.284062 -273.76374)
		(width 0.0889)
		(layer "In6.Cu")
		(net "M_E_CPU1_SB_CB<3>")
	)
	(arc
		(start 80.403954 -273.76374)
		(mid 80.586205 -273.71339)
		(end 80.769714 -273.758914)
		(width 0.0889)
		(layer "In6.Cu")
		(net "M_E_CPU1_SB_CB<3>")
	)
	(arc
		(start 80.778096 -273.76374)
		(mid 81.061052 -273.839917)
		(end 81.344008 -273.76374)
		(width 0.0889)
		(layer "In6.Cu")
		(net "M_E_CPU1_SB_CB<3>")
	)
	(arc
		(start 82.284062 -273.76374)
		(mid 82.440381 -273.714745)
		(end 82.602578 -273.737578)
		(width 0.0889)
		(layer "In6.Cu")
		(net "M_E_CPU1_SB_CB<3>")
	)
	(arc
		(start 79.868522 -273.78025)
		(mid 80.138331 -273.839692)
		(end 80.403954 -273.76374)
		(width 0.0889)
		(layer "In6.Cu")
		(net "M_E_CPU1_SB_CB<3>")
	)
	(segment
		(start 81.527904 -273.010376)
		(end 81.061052 -273.276314)
		(width 0.10668)
		(layer "F.Cu")
		(net "M_E_CPU1_SB_CB<2>")
	)
	(segment
		(start 42.667428 -279.360376)
		(end 43.517566 -278.510238)
		(width 0.14478)
		(layer "In6.Cu")
		(net "M_E_CPU1_SB_CB<2>")
	)
	(segment
		(start 27.752548 -279.360376)
		(end 27.98318 -279.360376)
		(width 0.14478)
		(layer "In6.Cu")
		(net "M_E_CPU1_SB_CB<2>")
	)
	(segment
		(start 76.81214 -271.944846)
		(end 77.392022 -271.944846)
		(width 0.0889)
		(layer "In6.Cu")
		(net "M_E_CPU1_SB_CB<2>")
	)
	(segment
		(start 80.299814 -272.948908)
		(end 80.308196 -272.953734)
		(width 0.0889)
		(layer "In6.Cu")
		(net "M_E_CPU1_SB_CB<2>")
	)
	(segment
		(start 43.517566 -278.510238)
		(end 45.209714 -278.510238)
		(width 0.14478)
		(layer "In6.Cu")
		(net "M_E_CPU1_SB_CB<2>")
	)
	(segment
		(start 81.214976 -273.010884)
		(end 81.061052 -273.276314)
		(width 0.0889)
		(layer "In6.Cu")
		(net "M_E_CPU1_SB_CB<2>")
	)
	(segment
		(start 76.622148 -271.754854)
		(end 76.81214 -271.944846)
		(width 0.0889)
		(layer "In6.Cu")
		(net "M_E_CPU1_SB_CB<2>")
	)
	(segment
		(start 27.589734 -279.197562)
		(end 27.752548 -279.360376)
		(width 0.14478)
		(layer "In6.Cu")
		(net "M_E_CPU1_SB_CB<2>")
	)
	(segment
		(start 26.87066 -279.360376)
		(end 27.033474 -279.197562)
		(width 0.14478)
		(layer "In6.Cu")
		(net "M_E_CPU1_SB_CB<2>")
	)
	(segment
		(start 35.414966 -278.510238)
		(end 37.620702 -278.510238)
		(width 0.14478)
		(layer "In6.Cu")
		(net "M_E_CPU1_SB_CB<2>")
	)
	(segment
		(start 59.241436 -278.109934)
		(end 65.596516 -271.754854)
		(width 0.14478)
		(layer "In6.Cu")
		(net "M_E_CPU1_SB_CB<2>")
	)
	(segment
		(start 28.145994 -279.197562)
		(end 28.145994 -278.919178)
		(width 0.14478)
		(layer "In6.Cu")
		(net "M_E_CPU1_SB_CB<2>")
	)
	(segment
		(start 52.829714 -278.510238)
		(end 53.679852 -279.360376)
		(width 0.14478)
		(layer "In6.Cu")
		(net "M_E_CPU1_SB_CB<2>")
	)
	(segment
		(start 28.702254 -278.919178)
		(end 28.702254 -279.197562)
		(width 0.14478)
		(layer "In6.Cu")
		(net "M_E_CPU1_SB_CB<2>")
	)
	(segment
		(start 57.3405 -279.360376)
		(end 58.590942 -278.109934)
		(width 0.14478)
		(layer "In6.Cu")
		(net "M_E_CPU1_SB_CB<2>")
	)
	(segment
		(start 28.702254 -279.197562)
		(end 28.865068 -279.360376)
		(width 0.14478)
		(layer "In6.Cu")
		(net "M_E_CPU1_SB_CB<2>")
	)
	(segment
		(start 75.960986 -271.754854)
		(end 76.622148 -271.754854)
		(width 0.0889)
		(layer "In6.Cu")
		(net "M_E_CPU1_SB_CB<2>")
	)
	(segment
		(start 27.033474 -279.197562)
		(end 27.033474 -278.919178)
		(width 0.14478)
		(layer "In6.Cu")
		(net "M_E_CPU1_SB_CB<2>")
	)
	(segment
		(start 28.308808 -278.756364)
		(end 28.53944 -278.756364)
		(width 0.14478)
		(layer "In6.Cu")
		(net "M_E_CPU1_SB_CB<2>")
	)
	(segment
		(start 79.36738 -272.953734)
		(end 79.377794 -272.95983)
		(width 0.0889)
		(layer "In6.Cu")
		(net "M_E_CPU1_SB_CB<2>")
	)
	(segment
		(start 34.564828 -279.360376)
		(end 35.414966 -278.510238)
		(width 0.14478)
		(layer "In6.Cu")
		(net "M_E_CPU1_SB_CB<2>")
	)
	(segment
		(start 25.152096 -278.935434)
		(end 25.577038 -279.360376)
		(width 0.14478)
		(layer "In6.Cu")
		(net "M_E_CPU1_SB_CB<2>")
	)
	(segment
		(start 28.53944 -278.756364)
		(end 28.702254 -278.919178)
		(width 0.14478)
		(layer "In6.Cu")
		(net "M_E_CPU1_SB_CB<2>")
	)
	(segment
		(start 38.47084 -279.360376)
		(end 42.667428 -279.360376)
		(width 0.14478)
		(layer "In6.Cu")
		(net "M_E_CPU1_SB_CB<2>")
	)
	(segment
		(start 27.589734 -278.919178)
		(end 27.589734 -279.197562)
		(width 0.14478)
		(layer "In6.Cu")
		(net "M_E_CPU1_SB_CB<2>")
	)
	(segment
		(start 45.209714 -278.510238)
		(end 46.059852 -279.360376)
		(width 0.14478)
		(layer "In6.Cu")
		(net "M_E_CPU1_SB_CB<2>")
	)
	(segment
		(start 27.196288 -278.756364)
		(end 27.42692 -278.756364)
		(width 0.14478)
		(layer "In6.Cu")
		(net "M_E_CPU1_SB_CB<2>")
	)
	(segment
		(start 77.392022 -271.944846)
		(end 78.312264 -272.865088)
		(width 0.0889)
		(layer "In6.Cu")
		(net "M_E_CPU1_SB_CB<2>")
	)
	(segment
		(start 46.059852 -279.360376)
		(end 49.957228 -279.360376)
		(width 0.14478)
		(layer "In6.Cu")
		(net "M_E_CPU1_SB_CB<2>")
	)
	(segment
		(start 25.577038 -279.360376)
		(end 26.87066 -279.360376)
		(width 0.14478)
		(layer "In6.Cu")
		(net "M_E_CPU1_SB_CB<2>")
	)
	(segment
		(start 53.679852 -279.360376)
		(end 57.3405 -279.360376)
		(width 0.14478)
		(layer "In6.Cu")
		(net "M_E_CPU1_SB_CB<2>")
	)
	(segment
		(start 27.42692 -278.756364)
		(end 27.589734 -278.919178)
		(width 0.14478)
		(layer "In6.Cu")
		(net "M_E_CPU1_SB_CB<2>")
	)
	(segment
		(start 78.974696 -272.96491)
		(end 78.993492 -272.953988)
		(width 0.0889)
		(layer "In6.Cu")
		(net "M_E_CPU1_SB_CB<2>")
	)
	(segment
		(start 49.957228 -279.360376)
		(end 50.807366 -278.510238)
		(width 0.14478)
		(layer "In6.Cu")
		(net "M_E_CPU1_SB_CB<2>")
	)
	(segment
		(start 37.620702 -278.510238)
		(end 38.47084 -279.360376)
		(width 0.14478)
		(layer "In6.Cu")
		(net "M_E_CPU1_SB_CB<2>")
	)
	(segment
		(start 28.145994 -278.919178)
		(end 28.308808 -278.756364)
		(width 0.14478)
		(layer "In6.Cu")
		(net "M_E_CPU1_SB_CB<2>")
	)
	(segment
		(start 27.033474 -278.919178)
		(end 27.196288 -278.756364)
		(width 0.14478)
		(layer "In6.Cu")
		(net "M_E_CPU1_SB_CB<2>")
	)
	(segment
		(start 27.98318 -279.360376)
		(end 28.145994 -279.197562)
		(width 0.14478)
		(layer "In6.Cu")
		(net "M_E_CPU1_SB_CB<2>")
	)
	(segment
		(start 50.807366 -278.510238)
		(end 52.829714 -278.510238)
		(width 0.14478)
		(layer "In6.Cu")
		(net "M_E_CPU1_SB_CB<2>")
	)
	(segment
		(start 65.596516 -271.754854)
		(end 75.960986 -271.754854)
		(width 0.14478)
		(layer "In6.Cu")
		(net "M_E_CPU1_SB_CB<2>")
	)
	(segment
		(start 81.192624 -272.927572)
		(end 81.214976 -273.010884)
		(width 0.0889)
		(layer "In6.Cu")
		(net "M_E_CPU1_SB_CB<2>")
	)
	(segment
		(start 58.590942 -278.109934)
		(end 59.241436 -278.109934)
		(width 0.14478)
		(layer "In6.Cu")
		(net "M_E_CPU1_SB_CB<2>")
	)
	(segment
		(start 28.865068 -279.360376)
		(end 34.564828 -279.360376)
		(width 0.14478)
		(layer "In6.Cu")
		(net "M_E_CPU1_SB_CB<2>")
	)
	(segment
		(start 78.993492 -272.953988)
		(end 79.009748 -272.94459)
		(width 0.0889)
		(layer "In6.Cu")
		(net "M_E_CPU1_SB_CB<2>")
	)
	(arc
		(start 80.308196 -272.953734)
		(mid 80.591152 -273.029911)
		(end 80.874108 -272.953734)
		(width 0.0889)
		(layer "In6.Cu")
		(net "M_E_CPU1_SB_CB<2>")
	)
	(arc
		(start 79.009748 -272.94459)
		(mid 79.18973 -272.90349)
		(end 79.36738 -272.953734)
		(width 0.0889)
		(layer "In6.Cu")
		(net "M_E_CPU1_SB_CB<2>")
	)
	(arc
		(start 79.377794 -272.95983)
		(mid 79.65648 -273.03005)
		(end 79.933546 -272.953734)
		(width 0.0889)
		(layer "In6.Cu")
		(net "M_E_CPU1_SB_CB<2>")
	)
	(arc
		(start 79.933546 -272.953734)
		(mid 80.116051 -272.903257)
		(end 80.299814 -272.948908)
		(width 0.0889)
		(layer "In6.Cu")
		(net "M_E_CPU1_SB_CB<2>")
	)
	(arc
		(start 78.427326 -272.953734)
		(mid 78.69956 -273.030177)
		(end 78.974696 -272.96491)
		(width 0.0889)
		(layer "In6.Cu")
		(net "M_E_CPU1_SB_CB<2>")
	)
	(arc
		(start 78.312264 -272.865088)
		(mid 78.366936 -272.91312)
		(end 78.427326 -272.953734)
		(width 0.0889)
		(layer "In6.Cu")
		(net "M_E_CPU1_SB_CB<2>")
	)
	(arc
		(start 80.874108 -272.953734)
		(mid 81.030427 -272.904739)
		(end 81.192624 -272.927572)
		(width 0.0889)
		(layer "In6.Cu")
		(net "M_E_CPU1_SB_CB<2>")
	)
	(segment
		(start 83.408012 -273.010376)
		(end 82.940906 -273.276314)
		(width 0.10668)
		(layer "F.Cu")
		(net "M_E_CPU1_SB_CB<1>")
	)
	(segment
		(start 43.402504 -279.3619)
		(end 45.172376 -279.3619)
		(width 0.14478)
		(layer "In6.Cu")
		(net "M_E_CPU1_SB_CB<1>")
	)
	(segment
		(start 41.226994 -280.42489)
		(end 41.226994 -280.062178)
		(width 0.14478)
		(layer "In6.Cu")
		(net "M_E_CPU1_SB_CB<1>")
	)
	(segment
		(start 78.519782 -273.51736)
		(end 79.742284 -273.51736)
		(width 0.0889)
		(layer "In6.Cu")
		(net "M_E_CPU1_SB_CB<1>")
	)
	(segment
		(start 37.468302 -279.360122)
		(end 38.31844 -280.21026)
		(width 0.14478)
		(layer "In6.Cu")
		(net "M_E_CPU1_SB_CB<1>")
	)
	(segment
		(start 65.777872 -272.209514)
		(end 75.960986 -272.209514)
		(width 0.14478)
		(layer "In6.Cu")
		(net "M_E_CPU1_SB_CB<1>")
	)
	(segment
		(start 57.983882 -279.360122)
		(end 59.721496 -279.360122)
		(width 0.14478)
		(layer "In6.Cu")
		(net "M_E_CPU1_SB_CB<1>")
	)
	(segment
		(start 41.389808 -279.899364)
		(end 41.62044 -279.899364)
		(width 0.14478)
		(layer "In6.Cu")
		(net "M_E_CPU1_SB_CB<1>")
	)
	(segment
		(start 45.172376 -279.3619)
		(end 46.020736 -280.21026)
		(width 0.14478)
		(layer "In6.Cu")
		(net "M_E_CPU1_SB_CB<1>")
	)
	(segment
		(start 29.252164 -279.785318)
		(end 30.040072 -280.573226)
		(width 0.14478)
		(layer "In6.Cu")
		(net "M_E_CPU1_SB_CB<1>")
	)
	(segment
		(start 41.06418 -280.587704)
		(end 41.226994 -280.42489)
		(width 0.14478)
		(layer "In6.Cu")
		(net "M_E_CPU1_SB_CB<1>")
	)
	(segment
		(start 31.546038 -279.986232)
		(end 31.708852 -279.823418)
		(width 0.14478)
		(layer "In6.Cu")
		(net "M_E_CPU1_SB_CB<1>")
	)
	(segment
		(start 30.270704 -280.573226)
		(end 30.433518 -280.410412)
		(width 0.14478)
		(layer "In6.Cu")
		(net "M_E_CPU1_SB_CB<1>")
	)
	(segment
		(start 57.133744 -280.21026)
		(end 57.983882 -279.360122)
		(width 0.14478)
		(layer "In6.Cu")
		(net "M_E_CPU1_SB_CB<1>")
	)
	(segment
		(start 34.021014 -280.597102)
		(end 35.257994 -279.360122)
		(width 0.14478)
		(layer "In6.Cu")
		(net "M_E_CPU1_SB_CB<1>")
	)
	(segment
		(start 30.596332 -279.823418)
		(end 30.826964 -279.823418)
		(width 0.14478)
		(layer "In6.Cu")
		(net "M_E_CPU1_SB_CB<1>")
	)
	(segment
		(start 33.464754 -279.847294)
		(end 33.627568 -280.010108)
		(width 0.14478)
		(layer "In6.Cu")
		(net "M_E_CPU1_SB_CB<1>")
	)
	(segment
		(start 49.750472 -280.21026)
		(end 50.60061 -279.360122)
		(width 0.14478)
		(layer "In6.Cu")
		(net "M_E_CPU1_SB_CB<1>")
	)
	(segment
		(start 38.31844 -280.21026)
		(end 40.456104 -280.21026)
		(width 0.14478)
		(layer "In6.Cu")
		(net "M_E_CPU1_SB_CB<1>")
	)
	(segment
		(start 50.60061 -279.360122)
		(end 52.917598 -279.360122)
		(width 0.14478)
		(layer "In6.Cu")
		(net "M_E_CPU1_SB_CB<1>")
	)
	(segment
		(start 42.1767 -280.587704)
		(end 43.402504 -279.3619)
		(width 0.14478)
		(layer "In6.Cu")
		(net "M_E_CPU1_SB_CB<1>")
	)
	(segment
		(start 82.69097 -273.567144)
		(end 82.786982 -273.541744)
		(width 0.0889)
		(layer "In6.Cu")
		(net "M_E_CPU1_SB_CB<1>")
	)
	(segment
		(start 75.960986 -272.209514)
		(end 77.211936 -272.209514)
		(width 0.0889)
		(layer "In6.Cu")
		(net "M_E_CPU1_SB_CB<1>")
	)
	(segment
		(start 30.433518 -279.986232)
		(end 30.596332 -279.823418)
		(width 0.14478)
		(layer "In6.Cu")
		(net "M_E_CPU1_SB_CB<1>")
	)
	(segment
		(start 59.721496 -279.360122)
		(end 60.16371 -278.917908)
		(width 0.14478)
		(layer "In6.Cu")
		(net "M_E_CPU1_SB_CB<1>")
	)
	(segment
		(start 32.326326 -280.21026)
		(end 32.871156 -280.21026)
		(width 0.14478)
		(layer "In6.Cu")
		(net "M_E_CPU1_SB_CB<1>")
	)
	(segment
		(start 60.16371 -278.917908)
		(end 60.16371 -277.823676)
		(width 0.14478)
		(layer "In6.Cu")
		(net "M_E_CPU1_SB_CB<1>")
	)
	(segment
		(start 33.627568 -280.010108)
		(end 33.627568 -280.434288)
		(width 0.14478)
		(layer "In6.Cu")
		(net "M_E_CPU1_SB_CB<1>")
	)
	(segment
		(start 82.179668 -273.60372)
		(end 82.18805 -273.598894)
		(width 0.0889)
		(layer "In6.Cu")
		(net "M_E_CPU1_SB_CB<1>")
	)
	(segment
		(start 41.62044 -279.899364)
		(end 41.783254 -280.062178)
		(width 0.14478)
		(layer "In6.Cu")
		(net "M_E_CPU1_SB_CB<1>")
	)
	(segment
		(start 30.040072 -280.573226)
		(end 30.270704 -280.573226)
		(width 0.14478)
		(layer "In6.Cu")
		(net "M_E_CPU1_SB_CB<1>")
	)
	(segment
		(start 35.257994 -279.360122)
		(end 37.468302 -279.360122)
		(width 0.14478)
		(layer "In6.Cu")
		(net "M_E_CPU1_SB_CB<1>")
	)
	(segment
		(start 79.869792 -273.561556)
		(end 79.9338 -273.598894)
		(width 0.0889)
		(layer "In6.Cu")
		(net "M_E_CPU1_SB_CB<1>")
	)
	(segment
		(start 82.786982 -273.541744)
		(end 82.940906 -273.276314)
		(width 0.0889)
		(layer "In6.Cu")
		(net "M_E_CPU1_SB_CB<1>")
	)
	(segment
		(start 41.783254 -280.062178)
		(end 41.783254 -280.42489)
		(width 0.14478)
		(layer "In6.Cu")
		(net "M_E_CPU1_SB_CB<1>")
	)
	(segment
		(start 77.211936 -272.209514)
		(end 78.519782 -273.51736)
		(width 0.0889)
		(layer "In6.Cu")
		(net "M_E_CPU1_SB_CB<1>")
	)
	(segment
		(start 30.826964 -279.823418)
		(end 30.989778 -279.986232)
		(width 0.14478)
		(layer "In6.Cu")
		(net "M_E_CPU1_SB_CB<1>")
	)
	(segment
		(start 40.456104 -280.21026)
		(end 40.833548 -280.587704)
		(width 0.14478)
		(layer "In6.Cu")
		(net "M_E_CPU1_SB_CB<1>")
	)
	(segment
		(start 33.234122 -279.847294)
		(end 33.464754 -279.847294)
		(width 0.14478)
		(layer "In6.Cu")
		(net "M_E_CPU1_SB_CB<1>")
	)
	(segment
		(start 31.152592 -280.573226)
		(end 31.383224 -280.573226)
		(width 0.14478)
		(layer "In6.Cu")
		(net "M_E_CPU1_SB_CB<1>")
	)
	(segment
		(start 33.790382 -280.597102)
		(end 34.021014 -280.597102)
		(width 0.14478)
		(layer "In6.Cu")
		(net "M_E_CPU1_SB_CB<1>")
	)
	(segment
		(start 41.946068 -280.587704)
		(end 42.1767 -280.587704)
		(width 0.14478)
		(layer "In6.Cu")
		(net "M_E_CPU1_SB_CB<1>")
	)
	(segment
		(start 33.627568 -280.434288)
		(end 33.790382 -280.597102)
		(width 0.14478)
		(layer "In6.Cu")
		(net "M_E_CPU1_SB_CB<1>")
	)
	(segment
		(start 41.783254 -280.42489)
		(end 41.946068 -280.587704)
		(width 0.14478)
		(layer "In6.Cu")
		(net "M_E_CPU1_SB_CB<1>")
	)
	(segment
		(start 31.383224 -280.573226)
		(end 31.546038 -280.410412)
		(width 0.14478)
		(layer "In6.Cu")
		(net "M_E_CPU1_SB_CB<1>")
	)
	(segment
		(start 53.767736 -280.21026)
		(end 57.133744 -280.21026)
		(width 0.14478)
		(layer "In6.Cu")
		(net "M_E_CPU1_SB_CB<1>")
	)
	(segment
		(start 31.939484 -279.823418)
		(end 32.326326 -280.21026)
		(width 0.14478)
		(layer "In6.Cu")
		(net "M_E_CPU1_SB_CB<1>")
	)
	(segment
		(start 31.708852 -279.823418)
		(end 31.939484 -279.823418)
		(width 0.14478)
		(layer "In6.Cu")
		(net "M_E_CPU1_SB_CB<1>")
	)
	(segment
		(start 30.433518 -280.410412)
		(end 30.433518 -279.986232)
		(width 0.14478)
		(layer "In6.Cu")
		(net "M_E_CPU1_SB_CB<1>")
	)
	(segment
		(start 32.871156 -280.21026)
		(end 33.234122 -279.847294)
		(width 0.14478)
		(layer "In6.Cu")
		(net "M_E_CPU1_SB_CB<1>")
	)
	(segment
		(start 40.833548 -280.587704)
		(end 41.06418 -280.587704)
		(width 0.14478)
		(layer "In6.Cu")
		(net "M_E_CPU1_SB_CB<1>")
	)
	(segment
		(start 41.226994 -280.062178)
		(end 41.389808 -279.899364)
		(width 0.14478)
		(layer "In6.Cu")
		(net "M_E_CPU1_SB_CB<1>")
	)
	(segment
		(start 30.989778 -280.410412)
		(end 31.152592 -280.573226)
		(width 0.14478)
		(layer "In6.Cu")
		(net "M_E_CPU1_SB_CB<1>")
	)
	(segment
		(start 30.989778 -279.986232)
		(end 30.989778 -280.410412)
		(width 0.14478)
		(layer "In6.Cu")
		(net "M_E_CPU1_SB_CB<1>")
	)
	(segment
		(start 31.546038 -280.410412)
		(end 31.546038 -279.986232)
		(width 0.14478)
		(layer "In6.Cu")
		(net "M_E_CPU1_SB_CB<1>")
	)
	(segment
		(start 46.020736 -280.21026)
		(end 49.750472 -280.21026)
		(width 0.14478)
		(layer "In6.Cu")
		(net "M_E_CPU1_SB_CB<1>")
	)
	(segment
		(start 60.16371 -277.823676)
		(end 65.777872 -272.209514)
		(width 0.14478)
		(layer "In6.Cu")
		(net "M_E_CPU1_SB_CB<1>")
	)
	(segment
		(start 52.917598 -279.360122)
		(end 53.767736 -280.21026)
		(width 0.14478)
		(layer "In6.Cu")
		(net "M_E_CPU1_SB_CB<1>")
	)
	(arc
		(start 80.308196 -273.598894)
		(mid 80.591152 -273.522717)
		(end 80.874108 -273.598894)
		(width 0.0889)
		(layer "In6.Cu")
		(net "M_E_CPU1_SB_CB<1>")
	)
	(arc
		(start 82.18805 -273.598894)
		(mid 82.435763 -273.523674)
		(end 82.69097 -273.567144)
		(width 0.0889)
		(layer "In6.Cu")
		(net "M_E_CPU1_SB_CB<1>")
	)
	(arc
		(start 81.813908 -273.598894)
		(mid 81.996159 -273.649244)
		(end 82.179668 -273.60372)
		(width 0.0889)
		(layer "In6.Cu")
		(net "M_E_CPU1_SB_CB<1>")
	)
	(arc
		(start 79.742284 -273.51736)
		(mid 79.7869 -273.522712)
		(end 79.828898 -273.538696)
		(width 0.0889)
		(layer "In6.Cu")
		(net "M_E_CPU1_SB_CB<1>")
	)
	(arc
		(start 79.9338 -273.598894)
		(mid 80.120998 -273.649276)
		(end 80.308196 -273.598894)
		(width 0.0889)
		(layer "In6.Cu")
		(net "M_E_CPU1_SB_CB<1>")
	)
	(arc
		(start 80.874108 -273.598894)
		(mid 81.061052 -273.649149)
		(end 81.247996 -273.598894)
		(width 0.0889)
		(layer "In6.Cu")
		(net "M_E_CPU1_SB_CB<1>")
	)
	(arc
		(start 79.828898 -273.538696)
		(mid 79.849454 -273.549932)
		(end 79.869792 -273.561556)
		(width 0.0889)
		(layer "In6.Cu")
		(net "M_E_CPU1_SB_CB<1>")
	)
	(arc
		(start 81.247996 -273.598894)
		(mid 81.530952 -273.522717)
		(end 81.813908 -273.598894)
		(width 0.0889)
		(layer "In6.Cu")
		(net "M_E_CPU1_SB_CB<1>")
	)
	(segment
		(start 81.997804 -272.20037)
		(end 81.530952 -272.466308)
		(width 0.10668)
		(layer "F.Cu")
		(net "M_E_CPU1_SB_CB<0>")
	)
	(segment
		(start 49.535588 -278.794972)
		(end 49.747932 -278.794972)
		(width 0.14478)
		(layer "In6.Cu")
		(net "M_E_CPU1_SB_CB<0>")
	)
	(segment
		(start 57.411112 -278.510492)
		(end 58.26125 -277.660354)
		(width 0.14478)
		(layer "In6.Cu")
		(net "M_E_CPU1_SB_CB<0>")
	)
	(segment
		(start 34.068258 -278.832564)
		(end 34.39033 -278.510492)
		(width 0.14478)
		(layer "In6.Cu")
		(net "M_E_CPU1_SB_CB<0>")
	)
	(segment
		(start 29.252164 -278.085296)
		(end 29.687012 -278.520144)
		(width 0.14478)
		(layer "In6.Cu")
		(net "M_E_CPU1_SB_CB<0>")
	)
	(segment
		(start 39.51986 -278.520144)
		(end 41.759632 -278.520144)
		(width 0.14478)
		(layer "In6.Cu")
		(net "M_E_CPU1_SB_CB<0>")
	)
	(segment
		(start 33.465262 -278.832564)
		(end 34.068258 -278.832564)
		(width 0.14478)
		(layer "In6.Cu")
		(net "M_E_CPU1_SB_CB<0>")
	)
	(segment
		(start 48.694848 -278.807164)
		(end 48.99152 -278.510492)
		(width 0.14478)
		(layer "In6.Cu")
		(net "M_E_CPU1_SB_CB<0>")
	)
	(segment
		(start 76.900786 -271.745964)
		(end 77.42555 -271.745964)
		(width 0.0889)
		(layer "In6.Cu")
		(net "M_E_CPU1_SB_CB<0>")
	)
	(segment
		(start 63.98895 -272.159984)
		(end 64.159892 -272.330926)
		(width 0.14478)
		(layer "In6.Cu")
		(net "M_E_CPU1_SB_CB<0>")
	)
	(segment
		(start 33.152842 -278.520144)
		(end 33.465262 -278.832564)
		(width 0.14478)
		(layer "In6.Cu")
		(net "M_E_CPU1_SB_CB<0>")
	)
	(segment
		(start 37.528754 -277.670006)
		(end 38.640512 -278.781764)
		(width 0.14478)
		(layer "In6.Cu")
		(net "M_E_CPU1_SB_CB<0>")
	)
	(segment
		(start 54.979824 -278.684228)
		(end 55.142638 -278.847042)
		(width 0.14478)
		(layer "In6.Cu")
		(net "M_E_CPU1_SB_CB<0>")
	)
	(segment
		(start 80.769714 -272.793714)
		(end 80.778096 -272.788888)
		(width 0.0889)
		(layer "In6.Cu")
		(net "M_E_CPU1_SB_CB<0>")
	)
	(segment
		(start 55.37327 -278.847042)
		(end 55.536084 -278.684228)
		(width 0.14478)
		(layer "In6.Cu")
		(net "M_E_CPU1_SB_CB<0>")
	)
	(segment
		(start 35.594798 -277.670006)
		(end 37.528754 -277.670006)
		(width 0.14478)
		(layer "In6.Cu")
		(net "M_E_CPU1_SB_CB<0>")
	)
	(segment
		(start 63.784226 -272.159984)
		(end 63.98895 -272.159984)
		(width 0.14478)
		(layer "In6.Cu")
		(net "M_E_CPU1_SB_CB<0>")
	)
	(segment
		(start 30.76321 -278.899366)
		(end 31.03753 -278.899366)
		(width 0.14478)
		(layer "In6.Cu")
		(net "M_E_CPU1_SB_CB<0>")
	)
	(segment
		(start 62.53226 -273.41195)
		(end 62.986666 -272.957544)
		(width 0.14478)
		(layer "In6.Cu")
		(net "M_E_CPU1_SB_CB<0>")
	)
	(segment
		(start 54.423564 -278.334978)
		(end 54.586378 -278.172164)
		(width 0.14478)
		(layer "In6.Cu")
		(net "M_E_CPU1_SB_CB<0>")
	)
	(segment
		(start 76.455016 -271.300194)
		(end 76.900786 -271.745964)
		(width 0.0889)
		(layer "In6.Cu")
		(net "M_E_CPU1_SB_CB<0>")
	)
	(segment
		(start 63.589916 -272.558764)
		(end 63.59017 -272.35404)
		(width 0.14478)
		(layer "In6.Cu")
		(net "M_E_CPU1_SB_CB<0>")
	)
	(segment
		(start 75.960986 -271.300194)
		(end 76.455016 -271.300194)
		(width 0.0889)
		(layer "In6.Cu")
		(net "M_E_CPU1_SB_CB<0>")
	)
	(segment
		(start 54.030118 -278.847042)
		(end 54.26075 -278.847042)
		(width 0.14478)
		(layer "In6.Cu")
		(net "M_E_CPU1_SB_CB<0>")
	)
	(segment
		(start 48.14824 -278.520144)
		(end 48.43526 -278.807164)
		(width 0.14478)
		(layer "In6.Cu")
		(net "M_E_CPU1_SB_CB<0>")
	)
	(segment
		(start 63.19139 -272.957544)
		(end 63.362332 -273.128486)
		(width 0.14478)
		(layer "In6.Cu")
		(net "M_E_CPU1_SB_CB<0>")
	)
	(segment
		(start 62.149482 -274.336764)
		(end 62.53226 -273.41195)
		(width 0.14478)
		(layer "In6.Cu")
		(net "M_E_CPU1_SB_CB<0>")
	)
	(segment
		(start 64.159892 -272.330926)
		(end 64.364108 -272.33118)
		(width 0.14478)
		(layer "In6.Cu")
		(net "M_E_CPU1_SB_CB<0>")
	)
	(segment
		(start 64.364108 -272.33118)
		(end 64.558418 -272.13687)
		(width 0.14478)
		(layer "In6.Cu")
		(net "M_E_CPU1_SB_CB<0>")
	)
	(segment
		(start 30.05455 -278.375364)
		(end 30.05455 -278.012906)
		(width 0.14478)
		(layer "In6.Cu")
		(net "M_E_CPU1_SB_CB<0>")
	)
	(segment
		(start 41.759632 -278.520144)
		(end 42.046652 -278.807164)
		(width 0.14478)
		(layer "In6.Cu")
		(net "M_E_CPU1_SB_CB<0>")
	)
	(segment
		(start 30.47365 -277.868126)
		(end 30.61843 -278.012906)
		(width 0.14478)
		(layer "In6.Cu")
		(net "M_E_CPU1_SB_CB<0>")
	)
	(segment
		(start 64.38773 -271.55648)
		(end 64.644016 -271.300194)
		(width 0.14478)
		(layer "In6.Cu")
		(net "M_E_CPU1_SB_CB<0>")
	)
	(segment
		(start 45.123354 -277.670006)
		(end 46.285912 -278.832564)
		(width 0.14478)
		(layer "In6.Cu")
		(net "M_E_CPU1_SB_CB<0>")
	)
	(segment
		(start 55.698898 -278.172164)
		(end 55.92953 -278.172164)
		(width 0.14478)
		(layer "In6.Cu")
		(net "M_E_CPU1_SB_CB<0>")
	)
	(segment
		(start 63.566548 -273.12874)
		(end 63.760858 -272.93443)
		(width 0.14478)
		(layer "In6.Cu")
		(net "M_E_CPU1_SB_CB<0>")
	)
	(segment
		(start 58.26125 -277.660354)
		(end 58.825892 -277.660354)
		(width 0.14478)
		(layer "In6.Cu")
		(net "M_E_CPU1_SB_CB<0>")
	)
	(segment
		(start 79.463138 -272.788888)
		(end 79.47152 -272.793714)
		(width 0.0889)
		(layer "In6.Cu")
		(net "M_E_CPU1_SB_CB<0>")
	)
	(segment
		(start 63.59017 -272.35404)
		(end 63.784226 -272.159984)
		(width 0.14478)
		(layer "In6.Cu")
		(net "M_E_CPU1_SB_CB<0>")
	)
	(segment
		(start 55.536084 -278.334978)
		(end 55.698898 -278.172164)
		(width 0.14478)
		(layer "In6.Cu")
		(net "M_E_CPU1_SB_CB<0>")
	)
	(segment
		(start 64.387476 -271.761204)
		(end 64.38773 -271.55648)
		(width 0.14478)
		(layer "In6.Cu")
		(net "M_E_CPU1_SB_CB<0>")
	)
	(segment
		(start 64.558418 -271.932146)
		(end 64.387476 -271.761204)
		(width 0.14478)
		(layer "In6.Cu")
		(net "M_E_CPU1_SB_CB<0>")
	)
	(segment
		(start 56.267858 -278.510492)
		(end 57.411112 -278.510492)
		(width 0.14478)
		(layer "In6.Cu")
		(net "M_E_CPU1_SB_CB<0>")
	)
	(segment
		(start 81.377028 -272.731738)
		(end 81.530952 -272.466308)
		(width 0.0889)
		(layer "In6.Cu")
		(net "M_E_CPU1_SB_CB<0>")
	)
	(segment
		(start 49.747932 -278.794972)
		(end 50.872898 -277.670006)
		(width 0.14478)
		(layer "In6.Cu")
		(net "M_E_CPU1_SB_CB<0>")
	)
	(segment
		(start 48.99152 -278.510492)
		(end 49.251108 -278.510492)
		(width 0.14478)
		(layer "In6.Cu")
		(net "M_E_CPU1_SB_CB<0>")
	)
	(segment
		(start 54.979824 -278.334978)
		(end 54.979824 -278.684228)
		(width 0.14478)
		(layer "In6.Cu")
		(net "M_E_CPU1_SB_CB<0>")
	)
	(segment
		(start 30.61843 -278.754586)
		(end 30.76321 -278.899366)
		(width 0.14478)
		(layer "In6.Cu")
		(net "M_E_CPU1_SB_CB<0>")
	)
	(segment
		(start 31.03753 -278.899366)
		(end 31.416752 -278.520144)
		(width 0.14478)
		(layer "In6.Cu")
		(net "M_E_CPU1_SB_CB<0>")
	)
	(segment
		(start 34.39033 -278.510492)
		(end 34.754312 -278.510492)
		(width 0.14478)
		(layer "In6.Cu")
		(net "M_E_CPU1_SB_CB<0>")
	)
	(segment
		(start 42.046652 -278.807164)
		(end 42.30624 -278.807164)
		(width 0.14478)
		(layer "In6.Cu")
		(net "M_E_CPU1_SB_CB<0>")
	)
	(segment
		(start 54.586378 -278.172164)
		(end 54.81701 -278.172164)
		(width 0.14478)
		(layer "In6.Cu")
		(net "M_E_CPU1_SB_CB<0>")
	)
	(segment
		(start 38.640512 -278.781764)
		(end 39.25824 -278.781764)
		(width 0.14478)
		(layer "In6.Cu")
		(net "M_E_CPU1_SB_CB<0>")
	)
	(segment
		(start 49.251108 -278.510492)
		(end 49.535588 -278.794972)
		(width 0.14478)
		(layer "In6.Cu")
		(net "M_E_CPU1_SB_CB<0>")
	)
	(segment
		(start 63.362332 -273.128486)
		(end 63.566548 -273.12874)
		(width 0.14478)
		(layer "In6.Cu")
		(net "M_E_CPU1_SB_CB<0>")
	)
	(segment
		(start 54.81701 -278.172164)
		(end 54.979824 -278.334978)
		(width 0.14478)
		(layer "In6.Cu")
		(net "M_E_CPU1_SB_CB<0>")
	)
	(segment
		(start 62.986666 -272.957544)
		(end 63.19139 -272.957544)
		(width 0.14478)
		(layer "In6.Cu")
		(net "M_E_CPU1_SB_CB<0>")
	)
	(segment
		(start 29.90977 -278.520144)
		(end 30.05455 -278.375364)
		(width 0.14478)
		(layer "In6.Cu")
		(net "M_E_CPU1_SB_CB<0>")
	)
	(segment
		(start 34.754312 -278.510492)
		(end 35.594798 -277.670006)
		(width 0.14478)
		(layer "In6.Cu")
		(net "M_E_CPU1_SB_CB<0>")
	)
	(segment
		(start 81.281016 -272.757138)
		(end 81.377028 -272.731738)
		(width 0.0889)
		(layer "In6.Cu")
		(net "M_E_CPU1_SB_CB<0>")
	)
	(segment
		(start 29.687012 -278.520144)
		(end 29.90977 -278.520144)
		(width 0.14478)
		(layer "In6.Cu")
		(net "M_E_CPU1_SB_CB<0>")
	)
	(segment
		(start 46.5201 -278.832564)
		(end 46.83252 -278.520144)
		(width 0.14478)
		(layer "In6.Cu")
		(net "M_E_CPU1_SB_CB<0>")
	)
	(segment
		(start 54.423564 -278.684228)
		(end 54.423564 -278.334978)
		(width 0.14478)
		(layer "In6.Cu")
		(net "M_E_CPU1_SB_CB<0>")
	)
	(segment
		(start 64.558418 -272.13687)
		(end 64.558418 -271.932146)
		(width 0.14478)
		(layer "In6.Cu")
		(net "M_E_CPU1_SB_CB<0>")
	)
	(segment
		(start 42.30624 -278.807164)
		(end 43.443398 -277.670006)
		(width 0.14478)
		(layer "In6.Cu")
		(net "M_E_CPU1_SB_CB<0>")
	)
	(segment
		(start 30.05455 -278.012906)
		(end 30.19933 -277.868126)
		(width 0.14478)
		(layer "In6.Cu")
		(net "M_E_CPU1_SB_CB<0>")
	)
	(segment
		(start 46.285912 -278.832564)
		(end 46.5201 -278.832564)
		(width 0.14478)
		(layer "In6.Cu")
		(net "M_E_CPU1_SB_CB<0>")
	)
	(segment
		(start 78.879446 -272.799048)
		(end 78.903322 -272.785332)
		(width 0.0889)
		(layer "In6.Cu")
		(net "M_E_CPU1_SB_CB<0>")
	)
	(segment
		(start 55.142638 -278.847042)
		(end 55.37327 -278.847042)
		(width 0.14478)
		(layer "In6.Cu")
		(net "M_E_CPU1_SB_CB<0>")
	)
	(segment
		(start 63.760858 -272.729706)
		(end 63.589916 -272.558764)
		(width 0.14478)
		(layer "In6.Cu")
		(net "M_E_CPU1_SB_CB<0>")
	)
	(segment
		(start 63.760858 -272.93443)
		(end 63.760858 -272.729706)
		(width 0.14478)
		(layer "In6.Cu")
		(net "M_E_CPU1_SB_CB<0>")
	)
	(segment
		(start 31.416752 -278.520144)
		(end 33.152842 -278.520144)
		(width 0.14478)
		(layer "In6.Cu")
		(net "M_E_CPU1_SB_CB<0>")
	)
	(segment
		(start 55.536084 -278.684228)
		(end 55.536084 -278.334978)
		(width 0.14478)
		(layer "In6.Cu")
		(net "M_E_CPU1_SB_CB<0>")
	)
	(segment
		(start 54.26075 -278.847042)
		(end 54.423564 -278.684228)
		(width 0.14478)
		(layer "In6.Cu")
		(net "M_E_CPU1_SB_CB<0>")
	)
	(segment
		(start 64.644016 -271.300194)
		(end 75.960986 -271.300194)
		(width 0.14478)
		(layer "In6.Cu")
		(net "M_E_CPU1_SB_CB<0>")
	)
	(segment
		(start 30.61843 -278.012906)
		(end 30.61843 -278.754586)
		(width 0.14478)
		(layer "In6.Cu")
		(net "M_E_CPU1_SB_CB<0>")
	)
	(segment
		(start 80.39354 -272.782792)
		(end 80.403954 -272.788888)
		(width 0.0889)
		(layer "In6.Cu")
		(net "M_E_CPU1_SB_CB<0>")
	)
	(segment
		(start 43.443398 -277.670006)
		(end 45.123354 -277.670006)
		(width 0.14478)
		(layer "In6.Cu")
		(net "M_E_CPU1_SB_CB<0>")
	)
	(segment
		(start 50.872898 -277.670006)
		(end 52.853082 -277.670006)
		(width 0.14478)
		(layer "In6.Cu")
		(net "M_E_CPU1_SB_CB<0>")
	)
	(segment
		(start 48.43526 -278.807164)
		(end 48.694848 -278.807164)
		(width 0.14478)
		(layer "In6.Cu")
		(net "M_E_CPU1_SB_CB<0>")
	)
	(segment
		(start 46.83252 -278.520144)
		(end 48.14824 -278.520144)
		(width 0.14478)
		(layer "In6.Cu")
		(net "M_E_CPU1_SB_CB<0>")
	)
	(segment
		(start 58.825892 -277.660354)
		(end 62.149482 -274.336764)
		(width 0.14478)
		(layer "In6.Cu")
		(net "M_E_CPU1_SB_CB<0>")
	)
	(segment
		(start 77.505814 -271.778984)
		(end 78.485746 -272.756884)
		(width 0.0889)
		(layer "In6.Cu")
		(net "M_E_CPU1_SB_CB<0>")
	)
	(segment
		(start 30.19933 -277.868126)
		(end 30.47365 -277.868126)
		(width 0.14478)
		(layer "In6.Cu")
		(net "M_E_CPU1_SB_CB<0>")
	)
	(segment
		(start 39.25824 -278.781764)
		(end 39.51986 -278.520144)
		(width 0.14478)
		(layer "In6.Cu")
		(net "M_E_CPU1_SB_CB<0>")
	)
	(segment
		(start 55.92953 -278.172164)
		(end 56.267858 -278.510492)
		(width 0.14478)
		(layer "In6.Cu")
		(net "M_E_CPU1_SB_CB<0>")
	)
	(segment
		(start 52.853082 -277.670006)
		(end 54.030118 -278.847042)
		(width 0.14478)
		(layer "In6.Cu")
		(net "M_E_CPU1_SB_CB<0>")
	)
	(arc
		(start 80.778096 -272.788888)
		(mid 81.025809 -272.713668)
		(end 81.281016 -272.757138)
		(width 0.0889)
		(layer "In6.Cu")
		(net "M_E_CPU1_SB_CB<0>")
	)
	(arc
		(start 78.559152 -272.80743)
		(mid 78.72025 -272.839407)
		(end 78.879446 -272.799048)
		(width 0.0889)
		(layer "In6.Cu")
		(net "M_E_CPU1_SB_CB<0>")
	)
	(arc
		(start 77.42555 -271.745964)
		(mid 77.46897 -271.754489)
		(end 77.505814 -271.778984)
		(width 0.0889)
		(layer "In6.Cu")
		(net "M_E_CPU1_SB_CB<0>")
	)
	(arc
		(start 80.403954 -272.788888)
		(mid 80.586205 -272.839238)
		(end 80.769714 -272.793714)
		(width 0.0889)
		(layer "In6.Cu")
		(net "M_E_CPU1_SB_CB<0>")
	)
	(arc
		(start 79.47152 -272.793714)
		(mid 79.655282 -272.83933)
		(end 79.837788 -272.788888)
		(width 0.0889)
		(layer "In6.Cu")
		(net "M_E_CPU1_SB_CB<0>")
	)
	(arc
		(start 78.903322 -272.785332)
		(mid 79.183711 -272.712663)
		(end 79.463138 -272.788888)
		(width 0.0889)
		(layer "In6.Cu")
		(net "M_E_CPU1_SB_CB<0>")
	)
	(arc
		(start 78.485746 -272.756884)
		(mid 78.520131 -272.785522)
		(end 78.559152 -272.80743)
		(width 0.0889)
		(layer "In6.Cu")
		(net "M_E_CPU1_SB_CB<0>")
	)
	(arc
		(start 79.837788 -272.788888)
		(mid 80.114855 -272.712617)
		(end 80.39354 -272.782792)
		(width 0.0889)
		(layer "In6.Cu")
		(net "M_E_CPU1_SB_CB<0>")
	)
	(segment
		(start 81.997804 -264.10031)
		(end 81.530952 -264.366248)
		(width 0.10668)
		(layer "F.Cu")
		(net "M_E_CPU1_SB_CA<6>")
	)
	(segment
		(start 31.566104 -265.968988)
		(end 31.728918 -266.131802)
		(width 0.14478)
		(layer "In6.Cu")
		(net "M_E_CPU1_SB_CA<6>")
	)
	(segment
		(start 29.252164 -266.185396)
		(end 30.060138 -265.377422)
		(width 0.14478)
		(layer "In6.Cu")
		(net "M_E_CPU1_SB_CA<6>")
	)
	(segment
		(start 31.566104 -265.540236)
		(end 31.566104 -265.968988)
		(width 0.14478)
		(layer "In6.Cu")
		(net "M_E_CPU1_SB_CA<6>")
	)
	(segment
		(start 34.53384 -266.132564)
		(end 34.764472 -266.132564)
		(width 0.14478)
		(layer "In6.Cu")
		(net "M_E_CPU1_SB_CA<6>")
	)
	(segment
		(start 33.04921 -265.760454)
		(end 33.42132 -266.132564)
		(width 0.14478)
		(layer "In6.Cu")
		(net "M_E_CPU1_SB_CA<6>")
	)
	(segment
		(start 80.769714 -264.693654)
		(end 80.778096 -264.688828)
		(width 0.0889)
		(layer "In6.Cu")
		(net "M_E_CPU1_SB_CA<6>")
	)
	(segment
		(start 79.838296 -264.688828)
		(end 79.84871 -264.682732)
		(width 0.0889)
		(layer "In6.Cu")
		(net "M_E_CPU1_SB_CA<6>")
	)
	(segment
		(start 30.29077 -265.377422)
		(end 30.453584 -265.540236)
		(width 0.14478)
		(layer "In6.Cu")
		(net "M_E_CPU1_SB_CA<6>")
	)
	(segment
		(start 34.764472 -266.132564)
		(end 35.136582 -265.760454)
		(width 0.14478)
		(layer "In6.Cu")
		(net "M_E_CPU1_SB_CA<6>")
	)
	(segment
		(start 81.281016 -264.657078)
		(end 81.377028 -264.631678)
		(width 0.0889)
		(layer "In6.Cu")
		(net "M_E_CPU1_SB_CA<6>")
	)
	(segment
		(start 31.728918 -266.131802)
		(end 31.95955 -266.131802)
		(width 0.14478)
		(layer "In6.Cu")
		(net "M_E_CPU1_SB_CA<6>")
	)
	(segment
		(start 75.968606 -264.619994)
		(end 76.259436 -264.619994)
		(width 0.0889)
		(layer "In6.Cu")
		(net "M_E_CPU1_SB_CA<6>")
	)
	(segment
		(start 33.42132 -266.132564)
		(end 33.651952 -266.132564)
		(width 0.14478)
		(layer "In6.Cu")
		(net "M_E_CPU1_SB_CA<6>")
	)
	(segment
		(start 76.575666 -264.303764)
		(end 77.459586 -264.303764)
		(width 0.0889)
		(layer "In6.Cu")
		(net "M_E_CPU1_SB_CA<6>")
	)
	(segment
		(start 33.814766 -265.551158)
		(end 33.97758 -265.388344)
		(width 0.14478)
		(layer "In6.Cu")
		(net "M_E_CPU1_SB_CA<6>")
	)
	(segment
		(start 33.814766 -265.96975)
		(end 33.814766 -265.551158)
		(width 0.14478)
		(layer "In6.Cu")
		(net "M_E_CPU1_SB_CA<6>")
	)
	(segment
		(start 34.371026 -265.96975)
		(end 34.53384 -266.132564)
		(width 0.14478)
		(layer "In6.Cu")
		(net "M_E_CPU1_SB_CA<6>")
	)
	(segment
		(start 59.865768 -265.760454)
		(end 61.006228 -264.619994)
		(width 0.14478)
		(layer "In6.Cu")
		(net "M_E_CPU1_SB_CA<6>")
	)
	(segment
		(start 76.259436 -264.619994)
		(end 76.575666 -264.303764)
		(width 0.0889)
		(layer "In6.Cu")
		(net "M_E_CPU1_SB_CA<6>")
	)
	(segment
		(start 77.768958 -264.613136)
		(end 78.242414 -264.613136)
		(width 0.0889)
		(layer "In6.Cu")
		(net "M_E_CPU1_SB_CA<6>")
	)
	(segment
		(start 31.40329 -265.377422)
		(end 31.566104 -265.540236)
		(width 0.14478)
		(layer "In6.Cu")
		(net "M_E_CPU1_SB_CA<6>")
	)
	(segment
		(start 34.371026 -265.551158)
		(end 34.371026 -265.96975)
		(width 0.14478)
		(layer "In6.Cu")
		(net "M_E_CPU1_SB_CA<6>")
	)
	(segment
		(start 33.651952 -266.132564)
		(end 33.814766 -265.96975)
		(width 0.14478)
		(layer "In6.Cu")
		(net "M_E_CPU1_SB_CA<6>")
	)
	(segment
		(start 33.97758 -265.388344)
		(end 34.208212 -265.388344)
		(width 0.14478)
		(layer "In6.Cu")
		(net "M_E_CPU1_SB_CA<6>")
	)
	(segment
		(start 78.524354 -264.688828)
		(end 78.536038 -264.695686)
		(width 0.0889)
		(layer "In6.Cu")
		(net "M_E_CPU1_SB_CA<6>")
	)
	(segment
		(start 79.453994 -264.682732)
		(end 79.464408 -264.688828)
		(width 0.0889)
		(layer "In6.Cu")
		(net "M_E_CPU1_SB_CA<6>")
	)
	(segment
		(start 30.453584 -265.968988)
		(end 30.616398 -266.131802)
		(width 0.14478)
		(layer "In6.Cu")
		(net "M_E_CPU1_SB_CA<6>")
	)
	(segment
		(start 77.459586 -264.303764)
		(end 77.768958 -264.613136)
		(width 0.0889)
		(layer "In6.Cu")
		(net "M_E_CPU1_SB_CA<6>")
	)
	(segment
		(start 30.060138 -265.377422)
		(end 30.29077 -265.377422)
		(width 0.14478)
		(layer "In6.Cu")
		(net "M_E_CPU1_SB_CA<6>")
	)
	(segment
		(start 81.377028 -264.631678)
		(end 81.530952 -264.366248)
		(width 0.0889)
		(layer "In6.Cu")
		(net "M_E_CPU1_SB_CA<6>")
	)
	(segment
		(start 30.616398 -266.131802)
		(end 30.84703 -266.131802)
		(width 0.14478)
		(layer "In6.Cu")
		(net "M_E_CPU1_SB_CA<6>")
	)
	(segment
		(start 34.208212 -265.388344)
		(end 34.371026 -265.551158)
		(width 0.14478)
		(layer "In6.Cu")
		(net "M_E_CPU1_SB_CA<6>")
	)
	(segment
		(start 31.95955 -266.131802)
		(end 32.330898 -265.760454)
		(width 0.14478)
		(layer "In6.Cu")
		(net "M_E_CPU1_SB_CA<6>")
	)
	(segment
		(start 31.172658 -265.377422)
		(end 31.40329 -265.377422)
		(width 0.14478)
		(layer "In6.Cu")
		(net "M_E_CPU1_SB_CA<6>")
	)
	(segment
		(start 31.009844 -265.540236)
		(end 31.172658 -265.377422)
		(width 0.14478)
		(layer "In6.Cu")
		(net "M_E_CPU1_SB_CA<6>")
	)
	(segment
		(start 30.453584 -265.540236)
		(end 30.453584 -265.968988)
		(width 0.14478)
		(layer "In6.Cu")
		(net "M_E_CPU1_SB_CA<6>")
	)
	(segment
		(start 35.136582 -265.760454)
		(end 59.865768 -265.760454)
		(width 0.14478)
		(layer "In6.Cu")
		(net "M_E_CPU1_SB_CA<6>")
	)
	(segment
		(start 30.84703 -266.131802)
		(end 31.009844 -265.968988)
		(width 0.14478)
		(layer "In6.Cu")
		(net "M_E_CPU1_SB_CA<6>")
	)
	(segment
		(start 61.006228 -264.619994)
		(end 75.968606 -264.619994)
		(width 0.14478)
		(layer "In6.Cu")
		(net "M_E_CPU1_SB_CA<6>")
	)
	(segment
		(start 31.009844 -265.968988)
		(end 31.009844 -265.540236)
		(width 0.14478)
		(layer "In6.Cu")
		(net "M_E_CPU1_SB_CA<6>")
	)
	(segment
		(start 32.330898 -265.760454)
		(end 33.04921 -265.760454)
		(width 0.14478)
		(layer "In6.Cu")
		(net "M_E_CPU1_SB_CA<6>")
	)
	(arc
		(start 79.464408 -264.688828)
		(mid 79.651352 -264.739083)
		(end 79.838296 -264.688828)
		(width 0.0889)
		(layer "In6.Cu")
		(net "M_E_CPU1_SB_CA<6>")
	)
	(arc
		(start 80.778096 -264.688828)
		(mid 81.025809 -264.613608)
		(end 81.281016 -264.657078)
		(width 0.0889)
		(layer "In6.Cu")
		(net "M_E_CPU1_SB_CA<6>")
	)
	(arc
		(start 78.536038 -264.695686)
		(mid 78.718039 -264.739219)
		(end 78.898242 -264.688828)
		(width 0.0889)
		(layer "In6.Cu")
		(net "M_E_CPU1_SB_CA<6>")
	)
	(arc
		(start 78.898242 -264.688828)
		(mid 79.175309 -264.612557)
		(end 79.453994 -264.682732)
		(width 0.0889)
		(layer "In6.Cu")
		(net "M_E_CPU1_SB_CA<6>")
	)
	(arc
		(start 79.84871 -264.682732)
		(mid 80.127142 -264.612634)
		(end 80.403954 -264.688828)
		(width 0.0889)
		(layer "In6.Cu")
		(net "M_E_CPU1_SB_CA<6>")
	)
	(arc
		(start 78.242414 -264.613136)
		(mid 78.388363 -264.632428)
		(end 78.524354 -264.688828)
		(width 0.0889)
		(layer "In6.Cu")
		(net "M_E_CPU1_SB_CA<6>")
	)
	(arc
		(start 80.403954 -264.688828)
		(mid 80.586205 -264.739178)
		(end 80.769714 -264.693654)
		(width 0.0889)
		(layer "In6.Cu")
		(net "M_E_CPU1_SB_CA<6>")
	)
	(segment
		(start 82.937858 -264.10031)
		(end 82.471006 -264.366248)
		(width 0.10668)
		(layer "F.Cu")
		(net "M_E_CPU1_SB_CA<5>")
	)
	(segment
		(start 76.183236 -264.165334)
		(end 76.339446 -264.009124)
		(width 0.0889)
		(layer "In6.Cu")
		(net "M_E_CPU1_SB_CA<5>")
	)
	(segment
		(start 81.344008 -264.043668)
		(end 81.35239 -264.038842)
		(width 0.0889)
		(layer "In6.Cu")
		(net "M_E_CPU1_SB_CA<5>")
	)
	(segment
		(start 25.577038 -264.910316)
		(end 59.85764 -264.910316)
		(width 0.14478)
		(layer "In6.Cu")
		(net "M_E_CPU1_SB_CA<5>")
	)
	(segment
		(start 75.968606 -264.165334)
		(end 76.183236 -264.165334)
		(width 0.0889)
		(layer "In6.Cu")
		(net "M_E_CPU1_SB_CA<5>")
	)
	(segment
		(start 82.602578 -264.017506)
		(end 82.62493 -264.100818)
		(width 0.0889)
		(layer "In6.Cu")
		(net "M_E_CPU1_SB_CA<5>")
	)
	(segment
		(start 80.769714 -264.038842)
		(end 80.778096 -264.043668)
		(width 0.0889)
		(layer "In6.Cu")
		(net "M_E_CPU1_SB_CA<5>")
	)
	(segment
		(start 76.339446 -264.009124)
		(end 79.633572 -264.009124)
		(width 0.0889)
		(layer "In6.Cu")
		(net "M_E_CPU1_SB_CA<5>")
	)
	(segment
		(start 25.152096 -265.335258)
		(end 25.577038 -264.910316)
		(width 0.14478)
		(layer "In6.Cu")
		(net "M_E_CPU1_SB_CA<5>")
	)
	(segment
		(start 60.602622 -264.165334)
		(end 75.968606 -264.165334)
		(width 0.14478)
		(layer "In6.Cu")
		(net "M_E_CPU1_SB_CA<5>")
	)
	(segment
		(start 59.85764 -264.910316)
		(end 60.602622 -264.165334)
		(width 0.14478)
		(layer "In6.Cu")
		(net "M_E_CPU1_SB_CA<5>")
	)
	(segment
		(start 82.62493 -264.100818)
		(end 82.471006 -264.366248)
		(width 0.0889)
		(layer "In6.Cu")
		(net "M_E_CPU1_SB_CA<5>")
	)
	(arc
		(start 81.35239 -264.038842)
		(mid 81.535898 -263.993348)
		(end 81.71815 -264.043668)
		(width 0.0889)
		(layer "In6.Cu")
		(net "M_E_CPU1_SB_CA<5>")
	)
	(arc
		(start 82.284062 -264.043668)
		(mid 82.440381 -263.994673)
		(end 82.602578 -264.017506)
		(width 0.0889)
		(layer "In6.Cu")
		(net "M_E_CPU1_SB_CA<5>")
	)
	(arc
		(start 80.778096 -264.043668)
		(mid 81.061052 -264.119845)
		(end 81.344008 -264.043668)
		(width 0.0889)
		(layer "In6.Cu")
		(net "M_E_CPU1_SB_CA<5>")
	)
	(arc
		(start 79.877158 -264.064496)
		(mid 80.143158 -264.119526)
		(end 80.403954 -264.043668)
		(width 0.0889)
		(layer "In6.Cu")
		(net "M_E_CPU1_SB_CA<5>")
	)
	(arc
		(start 80.403954 -264.043668)
		(mid 80.586205 -263.993318)
		(end 80.769714 -264.038842)
		(width 0.0889)
		(layer "In6.Cu")
		(net "M_E_CPU1_SB_CA<5>")
	)
	(arc
		(start 81.71815 -264.043668)
		(mid 82.001106 -264.119845)
		(end 82.284062 -264.043668)
		(width 0.0889)
		(layer "In6.Cu")
		(net "M_E_CPU1_SB_CA<5>")
	)
	(arc
		(start 79.633572 -264.009124)
		(mid 79.758474 -264.023138)
		(end 79.877158 -264.064496)
		(width 0.0889)
		(layer "In6.Cu")
		(net "M_E_CPU1_SB_CA<5>")
	)
	(segment
		(start 83.408012 -263.290304)
		(end 82.940906 -263.556242)
		(width 0.10668)
		(layer "F.Cu")
		(net "M_E_CPU1_SB_CA<4>")
	)
	(segment
		(start 82.786982 -263.821672)
		(end 82.940906 -263.556242)
		(width 0.0889)
		(layer "In6.Cu")
		(net "M_E_CPU1_SB_CA<4>")
	)
	(segment
		(start 30.617414 -264.433812)
		(end 30.848046 -264.433812)
		(width 0.14478)
		(layer "In6.Cu")
		(net "M_E_CPU1_SB_CA<4>")
	)
	(segment
		(start 75.947016 -263.710674)
		(end 79.502762 -263.710674)
		(width 0.0889)
		(layer "In6.Cu")
		(net "M_E_CPU1_SB_CA<4>")
	)
	(segment
		(start 34.453576 -264.060178)
		(end 34.773362 -264.379964)
		(width 0.14478)
		(layer "In6.Cu")
		(net "M_E_CPU1_SB_CA<4>")
	)
	(segment
		(start 33.341056 -264.060178)
		(end 33.660842 -264.379964)
		(width 0.14478)
		(layer "In6.Cu")
		(net "M_E_CPU1_SB_CA<4>")
	)
	(segment
		(start 32.3342 -264.060178)
		(end 33.341056 -264.060178)
		(width 0.14478)
		(layer "In6.Cu")
		(net "M_E_CPU1_SB_CA<4>")
	)
	(segment
		(start 30.061154 -263.676384)
		(end 30.291786 -263.676384)
		(width 0.14478)
		(layer "In6.Cu")
		(net "M_E_CPU1_SB_CA<4>")
	)
	(segment
		(start 34.773362 -264.379964)
		(end 35.009836 -264.379964)
		(width 0.14478)
		(layer "In6.Cu")
		(net "M_E_CPU1_SB_CA<4>")
	)
	(segment
		(start 30.4546 -264.270998)
		(end 30.617414 -264.433812)
		(width 0.14478)
		(layer "In6.Cu")
		(net "M_E_CPU1_SB_CA<4>")
	)
	(segment
		(start 30.4546 -263.839198)
		(end 30.4546 -264.270998)
		(width 0.14478)
		(layer "In6.Cu")
		(net "M_E_CPU1_SB_CA<4>")
	)
	(segment
		(start 36.442142 -264.060178)
		(end 59.979052 -264.060178)
		(width 0.14478)
		(layer "In6.Cu")
		(net "M_E_CPU1_SB_CA<4>")
	)
	(segment
		(start 82.179668 -263.883648)
		(end 82.18805 -263.878822)
		(width 0.0889)
		(layer "In6.Cu")
		(net "M_E_CPU1_SB_CA<4>")
	)
	(segment
		(start 79.869792 -263.841484)
		(end 79.9338 -263.878822)
		(width 0.0889)
		(layer "In6.Cu")
		(net "M_E_CPU1_SB_CA<4>")
	)
	(segment
		(start 31.01086 -264.270998)
		(end 31.01086 -263.839198)
		(width 0.14478)
		(layer "In6.Cu")
		(net "M_E_CPU1_SB_CA<4>")
	)
	(segment
		(start 34.217102 -264.060178)
		(end 34.453576 -264.060178)
		(width 0.14478)
		(layer "In6.Cu")
		(net "M_E_CPU1_SB_CA<4>")
	)
	(segment
		(start 33.897316 -264.379964)
		(end 34.217102 -264.060178)
		(width 0.14478)
		(layer "In6.Cu")
		(net "M_E_CPU1_SB_CA<4>")
	)
	(segment
		(start 31.404306 -263.676384)
		(end 31.56712 -263.839198)
		(width 0.14478)
		(layer "In6.Cu")
		(net "M_E_CPU1_SB_CA<4>")
	)
	(segment
		(start 31.56712 -263.839198)
		(end 31.56712 -264.270998)
		(width 0.14478)
		(layer "In6.Cu")
		(net "M_E_CPU1_SB_CA<4>")
	)
	(segment
		(start 31.173674 -263.676384)
		(end 31.404306 -263.676384)
		(width 0.14478)
		(layer "In6.Cu")
		(net "M_E_CPU1_SB_CA<4>")
	)
	(segment
		(start 30.848046 -264.433812)
		(end 31.01086 -264.270998)
		(width 0.14478)
		(layer "In6.Cu")
		(net "M_E_CPU1_SB_CA<4>")
	)
	(segment
		(start 31.960566 -264.433812)
		(end 32.3342 -264.060178)
		(width 0.14478)
		(layer "In6.Cu")
		(net "M_E_CPU1_SB_CA<4>")
	)
	(segment
		(start 35.009836 -264.379964)
		(end 35.329622 -264.060178)
		(width 0.14478)
		(layer "In6.Cu")
		(net "M_E_CPU1_SB_CA<4>")
	)
	(segment
		(start 31.01086 -263.839198)
		(end 31.173674 -263.676384)
		(width 0.14478)
		(layer "In6.Cu")
		(net "M_E_CPU1_SB_CA<4>")
	)
	(segment
		(start 82.69097 -263.847072)
		(end 82.786982 -263.821672)
		(width 0.0889)
		(layer "In6.Cu")
		(net "M_E_CPU1_SB_CA<4>")
	)
	(segment
		(start 35.566096 -264.060178)
		(end 35.885882 -264.379964)
		(width 0.14478)
		(layer "In6.Cu")
		(net "M_E_CPU1_SB_CA<4>")
	)
	(segment
		(start 35.885882 -264.379964)
		(end 36.122356 -264.379964)
		(width 0.14478)
		(layer "In6.Cu")
		(net "M_E_CPU1_SB_CA<4>")
	)
	(segment
		(start 35.329622 -264.060178)
		(end 35.566096 -264.060178)
		(width 0.14478)
		(layer "In6.Cu")
		(net "M_E_CPU1_SB_CA<4>")
	)
	(segment
		(start 59.979052 -264.060178)
		(end 60.328556 -263.710674)
		(width 0.14478)
		(layer "In6.Cu")
		(net "M_E_CPU1_SB_CA<4>")
	)
	(segment
		(start 30.291786 -263.676384)
		(end 30.4546 -263.839198)
		(width 0.14478)
		(layer "In6.Cu")
		(net "M_E_CPU1_SB_CA<4>")
	)
	(segment
		(start 31.56712 -264.270998)
		(end 31.729934 -264.433812)
		(width 0.14478)
		(layer "In6.Cu")
		(net "M_E_CPU1_SB_CA<4>")
	)
	(segment
		(start 31.729934 -264.433812)
		(end 31.960566 -264.433812)
		(width 0.14478)
		(layer "In6.Cu")
		(net "M_E_CPU1_SB_CA<4>")
	)
	(segment
		(start 33.660842 -264.379964)
		(end 33.897316 -264.379964)
		(width 0.14478)
		(layer "In6.Cu")
		(net "M_E_CPU1_SB_CA<4>")
	)
	(segment
		(start 36.122356 -264.379964)
		(end 36.442142 -264.060178)
		(width 0.14478)
		(layer "In6.Cu")
		(net "M_E_CPU1_SB_CA<4>")
	)
	(segment
		(start 29.252164 -264.485374)
		(end 30.061154 -263.676384)
		(width 0.14478)
		(layer "In6.Cu")
		(net "M_E_CPU1_SB_CA<4>")
	)
	(segment
		(start 60.328556 -263.710674)
		(end 75.947016 -263.710674)
		(width 0.14478)
		(layer "In6.Cu")
		(net "M_E_CPU1_SB_CA<4>")
	)
	(arc
		(start 81.813908 -263.878822)
		(mid 81.996159 -263.929172)
		(end 82.179668 -263.883648)
		(width 0.0889)
		(layer "In6.Cu")
		(net "M_E_CPU1_SB_CA<4>")
	)
	(arc
		(start 79.9338 -263.878822)
		(mid 80.120998 -263.929204)
		(end 80.308196 -263.878822)
		(width 0.0889)
		(layer "In6.Cu")
		(net "M_E_CPU1_SB_CA<4>")
	)
	(arc
		(start 80.308196 -263.878822)
		(mid 80.591152 -263.802645)
		(end 80.874108 -263.878822)
		(width 0.0889)
		(layer "In6.Cu")
		(net "M_E_CPU1_SB_CA<4>")
	)
	(arc
		(start 82.18805 -263.878822)
		(mid 82.435763 -263.803602)
		(end 82.69097 -263.847072)
		(width 0.0889)
		(layer "In6.Cu")
		(net "M_E_CPU1_SB_CA<4>")
	)
	(arc
		(start 81.247996 -263.878822)
		(mid 81.530952 -263.802645)
		(end 81.813908 -263.878822)
		(width 0.0889)
		(layer "In6.Cu")
		(net "M_E_CPU1_SB_CA<4>")
	)
	(arc
		(start 80.874108 -263.878822)
		(mid 81.061052 -263.929077)
		(end 81.247996 -263.878822)
		(width 0.0889)
		(layer "In6.Cu")
		(net "M_E_CPU1_SB_CA<4>")
	)
	(arc
		(start 79.502762 -263.710674)
		(mid 79.547383 -263.713685)
		(end 79.591154 -263.722866)
		(width 0.0889)
		(layer "In6.Cu")
		(net "M_E_CPU1_SB_CA<4>")
	)
	(arc
		(start 79.591154 -263.722866)
		(mid 79.734148 -263.773543)
		(end 79.869792 -263.841484)
		(width 0.0889)
		(layer "In6.Cu")
		(net "M_E_CPU1_SB_CA<4>")
	)
	(segment
		(start 81.527904 -263.290304)
		(end 81.061052 -263.556242)
		(width 0.10668)
		(layer "F.Cu")
		(net "M_E_CPU1_SB_CA<3>")
	)
	(segment
		(start 77.925676 -262.901684)
		(end 78.333854 -263.309862)
		(width 0.0889)
		(layer "In6.Cu")
		(net "M_E_CPU1_SB_CA<3>")
	)
	(segment
		(start 25.152096 -263.635236)
		(end 25.577038 -263.210294)
		(width 0.14478)
		(layer "In6.Cu")
		(net "M_E_CPU1_SB_CA<3>")
	)
	(segment
		(start 25.577038 -263.210294)
		(end 75.968606 -263.210294)
		(width 0.14478)
		(layer "In6.Cu")
		(net "M_E_CPU1_SB_CA<3>")
	)
	(segment
		(start 81.214976 -263.290812)
		(end 81.061052 -263.556242)
		(width 0.0889)
		(layer "In6.Cu")
		(net "M_E_CPU1_SB_CA<3>")
	)
	(segment
		(start 79.934054 -263.233662)
		(end 79.942436 -263.228836)
		(width 0.0889)
		(layer "In6.Cu")
		(net "M_E_CPU1_SB_CA<3>")
	)
	(segment
		(start 76.518516 -263.210294)
		(end 76.827126 -262.901684)
		(width 0.0889)
		(layer "In6.Cu")
		(net "M_E_CPU1_SB_CA<3>")
	)
	(segment
		(start 81.192624 -263.2075)
		(end 81.214976 -263.290812)
		(width 0.0889)
		(layer "In6.Cu")
		(net "M_E_CPU1_SB_CA<3>")
	)
	(segment
		(start 78.333854 -263.309862)
		(end 79.650844 -263.309862)
		(width 0.0889)
		(layer "In6.Cu")
		(net "M_E_CPU1_SB_CA<3>")
	)
	(segment
		(start 75.968606 -263.210294)
		(end 76.518516 -263.210294)
		(width 0.0889)
		(layer "In6.Cu")
		(net "M_E_CPU1_SB_CA<3>")
	)
	(segment
		(start 76.827126 -262.901684)
		(end 77.925676 -262.901684)
		(width 0.0889)
		(layer "In6.Cu")
		(net "M_E_CPU1_SB_CA<3>")
	)
	(arc
		(start 79.650844 -263.309862)
		(mid 79.797497 -263.290517)
		(end 79.934054 -263.233662)
		(width 0.0889)
		(layer "In6.Cu")
		(net "M_E_CPU1_SB_CA<3>")
	)
	(arc
		(start 80.308196 -263.233662)
		(mid 80.591152 -263.309839)
		(end 80.874108 -263.233662)
		(width 0.0889)
		(layer "In6.Cu")
		(net "M_E_CPU1_SB_CA<3>")
	)
	(arc
		(start 80.874108 -263.233662)
		(mid 81.030427 -263.184667)
		(end 81.192624 -263.2075)
		(width 0.0889)
		(layer "In6.Cu")
		(net "M_E_CPU1_SB_CA<3>")
	)
	(arc
		(start 79.942436 -263.228836)
		(mid 80.125944 -263.183342)
		(end 80.308196 -263.233662)
		(width 0.0889)
		(layer "In6.Cu")
		(net "M_E_CPU1_SB_CA<3>")
	)
	(segment
		(start 81.997804 -262.480298)
		(end 81.530952 -262.746236)
		(width 0.10668)
		(layer "F.Cu")
		(net "M_E_CPU1_SB_CA<2>")
	)
	(segment
		(start 31.957772 -262.754872)
		(end 32.345122 -262.367522)
		(width 0.14478)
		(layer "In6.Cu")
		(net "M_E_CPU1_SB_CA<2>")
	)
	(segment
		(start 66.986912 -262.75538)
		(end 75.93457 -262.75538)
		(width 0.14478)
		(layer "In6.Cu")
		(net "M_E_CPU1_SB_CA<2>")
	)
	(segment
		(start 34.454338 -262.143494)
		(end 34.454338 -262.59155)
		(width 0.14478)
		(layer "In6.Cu")
		(net "M_E_CPU1_SB_CA<2>")
	)
	(segment
		(start 34.060892 -261.98068)
		(end 34.291524 -261.98068)
		(width 0.14478)
		(layer "In6.Cu")
		(net "M_E_CPU1_SB_CA<2>")
	)
	(segment
		(start 30.61462 -262.754872)
		(end 30.845252 -262.754872)
		(width 0.14478)
		(layer "In6.Cu")
		(net "M_E_CPU1_SB_CA<2>")
	)
	(segment
		(start 35.234626 -262.367522)
		(end 66.599054 -262.367522)
		(width 0.14478)
		(layer "In6.Cu")
		(net "M_E_CPU1_SB_CA<2>")
	)
	(segment
		(start 31.564326 -262.14197)
		(end 31.564326 -262.592058)
		(width 0.14478)
		(layer "In6.Cu")
		(net "M_E_CPU1_SB_CA<2>")
	)
	(segment
		(start 31.72714 -262.754872)
		(end 31.957772 -262.754872)
		(width 0.14478)
		(layer "In6.Cu")
		(net "M_E_CPU1_SB_CA<2>")
	)
	(segment
		(start 34.847784 -262.754364)
		(end 35.234626 -262.367522)
		(width 0.14478)
		(layer "In6.Cu")
		(net "M_E_CPU1_SB_CA<2>")
	)
	(segment
		(start 66.599054 -262.367522)
		(end 66.986912 -262.75538)
		(width 0.14478)
		(layer "In6.Cu")
		(net "M_E_CPU1_SB_CA<2>")
	)
	(segment
		(start 79.838296 -263.068816)
		(end 79.838042 -263.068816)
		(width 0.0889)
		(layer "In6.Cu")
		(net "M_E_CPU1_SB_CA<2>")
	)
	(segment
		(start 34.617152 -262.754364)
		(end 34.847784 -262.754364)
		(width 0.14478)
		(layer "In6.Cu")
		(net "M_E_CPU1_SB_CA<2>")
	)
	(segment
		(start 30.451806 -262.592058)
		(end 30.61462 -262.754872)
		(width 0.14478)
		(layer "In6.Cu")
		(net "M_E_CPU1_SB_CA<2>")
	)
	(segment
		(start 34.291524 -261.98068)
		(end 34.454338 -262.143494)
		(width 0.14478)
		(layer "In6.Cu")
		(net "M_E_CPU1_SB_CA<2>")
	)
	(segment
		(start 33.11779 -262.367522)
		(end 33.504632 -262.754364)
		(width 0.14478)
		(layer "In6.Cu")
		(net "M_E_CPU1_SB_CA<2>")
	)
	(segment
		(start 32.345122 -262.367522)
		(end 33.11779 -262.367522)
		(width 0.14478)
		(layer "In6.Cu")
		(net "M_E_CPU1_SB_CA<2>")
	)
	(segment
		(start 76.502006 -262.601964)
		(end 77.900784 -262.601964)
		(width 0.0889)
		(layer "In6.Cu")
		(net "M_E_CPU1_SB_CA<2>")
	)
	(segment
		(start 33.898078 -262.59155)
		(end 33.898078 -262.143494)
		(width 0.14478)
		(layer "In6.Cu")
		(net "M_E_CPU1_SB_CA<2>")
	)
	(segment
		(start 76.34859 -262.75538)
		(end 76.502006 -262.601964)
		(width 0.0889)
		(layer "In6.Cu")
		(net "M_E_CPU1_SB_CA<2>")
	)
	(segment
		(start 29.252164 -262.785352)
		(end 30.05836 -261.979156)
		(width 0.14478)
		(layer "In6.Cu")
		(net "M_E_CPU1_SB_CA<2>")
	)
	(segment
		(start 31.17088 -261.979156)
		(end 31.401512 -261.979156)
		(width 0.14478)
		(layer "In6.Cu")
		(net "M_E_CPU1_SB_CA<2>")
	)
	(segment
		(start 30.05836 -261.979156)
		(end 30.288992 -261.979156)
		(width 0.14478)
		(layer "In6.Cu")
		(net "M_E_CPU1_SB_CA<2>")
	)
	(segment
		(start 81.377028 -263.011666)
		(end 81.530952 -262.746236)
		(width 0.0889)
		(layer "In6.Cu")
		(net "M_E_CPU1_SB_CA<2>")
	)
	(segment
		(start 80.769714 -263.073642)
		(end 80.778096 -263.068816)
		(width 0.0889)
		(layer "In6.Cu")
		(net "M_E_CPU1_SB_CA<2>")
	)
	(segment
		(start 30.288992 -261.979156)
		(end 30.451806 -262.14197)
		(width 0.14478)
		(layer "In6.Cu")
		(net "M_E_CPU1_SB_CA<2>")
	)
	(segment
		(start 77.900784 -262.601964)
		(end 78.418182 -263.119362)
		(width 0.0889)
		(layer "In6.Cu")
		(net "M_E_CPU1_SB_CA<2>")
	)
	(segment
		(start 81.281016 -263.037066)
		(end 81.377028 -263.011666)
		(width 0.0889)
		(layer "In6.Cu")
		(net "M_E_CPU1_SB_CA<2>")
	)
	(segment
		(start 33.898078 -262.143494)
		(end 34.060892 -261.98068)
		(width 0.14478)
		(layer "In6.Cu")
		(net "M_E_CPU1_SB_CA<2>")
	)
	(segment
		(start 33.504632 -262.754364)
		(end 33.735264 -262.754364)
		(width 0.14478)
		(layer "In6.Cu")
		(net "M_E_CPU1_SB_CA<2>")
	)
	(segment
		(start 33.735264 -262.754364)
		(end 33.898078 -262.59155)
		(width 0.14478)
		(layer "In6.Cu")
		(net "M_E_CPU1_SB_CA<2>")
	)
	(segment
		(start 31.008066 -262.14197)
		(end 31.17088 -261.979156)
		(width 0.14478)
		(layer "In6.Cu")
		(net "M_E_CPU1_SB_CA<2>")
	)
	(segment
		(start 31.008066 -262.592058)
		(end 31.008066 -262.14197)
		(width 0.14478)
		(layer "In6.Cu")
		(net "M_E_CPU1_SB_CA<2>")
	)
	(segment
		(start 78.418182 -263.119362)
		(end 79.651098 -263.119362)
		(width 0.0889)
		(layer "In6.Cu")
		(net "M_E_CPU1_SB_CA<2>")
	)
	(segment
		(start 30.845252 -262.754872)
		(end 31.008066 -262.592058)
		(width 0.14478)
		(layer "In6.Cu")
		(net "M_E_CPU1_SB_CA<2>")
	)
	(segment
		(start 31.564326 -262.592058)
		(end 31.72714 -262.754872)
		(width 0.14478)
		(layer "In6.Cu")
		(net "M_E_CPU1_SB_CA<2>")
	)
	(segment
		(start 30.451806 -262.14197)
		(end 30.451806 -262.592058)
		(width 0.14478)
		(layer "In6.Cu")
		(net "M_E_CPU1_SB_CA<2>")
	)
	(segment
		(start 31.401512 -261.979156)
		(end 31.564326 -262.14197)
		(width 0.14478)
		(layer "In6.Cu")
		(net "M_E_CPU1_SB_CA<2>")
	)
	(segment
		(start 75.93457 -262.75538)
		(end 76.34859 -262.75538)
		(width 0.0889)
		(layer "In6.Cu")
		(net "M_E_CPU1_SB_CA<2>")
	)
	(segment
		(start 34.454338 -262.59155)
		(end 34.617152 -262.754364)
		(width 0.14478)
		(layer "In6.Cu")
		(net "M_E_CPU1_SB_CA<2>")
	)
	(arc
		(start 79.838042 -263.068816)
		(mid 80.120998 -262.992639)
		(end 80.403954 -263.068816)
		(width 0.0889)
		(layer "In6.Cu")
		(net "M_E_CPU1_SB_CA<2>")
	)
	(arc
		(start 80.778096 -263.068816)
		(mid 81.025809 -262.993596)
		(end 81.281016 -263.037066)
		(width 0.0889)
		(layer "In6.Cu")
		(net "M_E_CPU1_SB_CA<2>")
	)
	(arc
		(start 79.651098 -263.119362)
		(mid 79.748045 -263.106479)
		(end 79.838296 -263.068816)
		(width 0.0889)
		(layer "In6.Cu")
		(net "M_E_CPU1_SB_CA<2>")
	)
	(arc
		(start 80.403954 -263.068816)
		(mid 80.586205 -263.119166)
		(end 80.769714 -263.073642)
		(width 0.0889)
		(layer "In6.Cu")
		(net "M_E_CPU1_SB_CA<2>")
	)
	(segment
		(start 82.937858 -262.480298)
		(end 82.471006 -262.746236)
		(width 0.10668)
		(layer "F.Cu")
		(net "M_E_CPU1_SB_CA<1>")
	)
	(segment
		(start 82.62493 -262.480806)
		(end 82.471006 -262.746236)
		(width 0.0889)
		(layer "In6.Cu")
		(net "M_E_CPU1_SB_CA<1>")
	)
	(segment
		(start 75.986386 -262.246364)
		(end 79.180182 -262.246364)
		(width 0.0889)
		(layer "In6.Cu")
		(net "M_E_CPU1_SB_CA<1>")
	)
	(segment
		(start 67.113912 -262.246364)
		(end 75.986386 -262.246364)
		(width 0.14478)
		(layer "In6.Cu")
		(net "M_E_CPU1_SB_CA<1>")
	)
	(segment
		(start 82.602578 -262.397494)
		(end 82.62493 -262.480806)
		(width 0.0889)
		(layer "In6.Cu")
		(net "M_E_CPU1_SB_CA<1>")
	)
	(segment
		(start 25.577038 -261.510272)
		(end 66.37782 -261.510272)
		(width 0.14478)
		(layer "In6.Cu")
		(net "M_E_CPU1_SB_CA<1>")
	)
	(segment
		(start 25.152096 -261.935214)
		(end 25.577038 -261.510272)
		(width 0.14478)
		(layer "In6.Cu")
		(net "M_E_CPU1_SB_CA<1>")
	)
	(segment
		(start 80.769714 -262.41883)
		(end 80.778096 -262.423656)
		(width 0.0889)
		(layer "In6.Cu")
		(net "M_E_CPU1_SB_CA<1>")
	)
	(segment
		(start 66.37782 -261.510272)
		(end 67.113912 -262.246364)
		(width 0.14478)
		(layer "In6.Cu")
		(net "M_E_CPU1_SB_CA<1>")
	)
	(segment
		(start 81.344008 -262.423656)
		(end 81.35239 -262.41883)
		(width 0.0889)
		(layer "In6.Cu")
		(net "M_E_CPU1_SB_CA<1>")
	)
	(arc
		(start 79.180182 -262.246364)
		(mid 79.520851 -262.291458)
		(end 79.838042 -262.423656)
		(width 0.0889)
		(layer "In6.Cu")
		(net "M_E_CPU1_SB_CA<1>")
	)
	(arc
		(start 80.778096 -262.423656)
		(mid 81.061052 -262.499833)
		(end 81.344008 -262.423656)
		(width 0.0889)
		(layer "In6.Cu")
		(net "M_E_CPU1_SB_CA<1>")
	)
	(arc
		(start 81.71815 -262.423656)
		(mid 82.001106 -262.499833)
		(end 82.284062 -262.423656)
		(width 0.0889)
		(layer "In6.Cu")
		(net "M_E_CPU1_SB_CA<1>")
	)
	(arc
		(start 79.838042 -262.423656)
		(mid 80.120998 -262.499833)
		(end 80.403954 -262.423656)
		(width 0.0889)
		(layer "In6.Cu")
		(net "M_E_CPU1_SB_CA<1>")
	)
	(arc
		(start 81.35239 -262.41883)
		(mid 81.535898 -262.373336)
		(end 81.71815 -262.423656)
		(width 0.0889)
		(layer "In6.Cu")
		(net "M_E_CPU1_SB_CA<1>")
	)
	(arc
		(start 82.284062 -262.423656)
		(mid 82.440381 -262.374661)
		(end 82.602578 -262.397494)
		(width 0.0889)
		(layer "In6.Cu")
		(net "M_E_CPU1_SB_CA<1>")
	)
	(arc
		(start 80.403954 -262.423656)
		(mid 80.586205 -262.373306)
		(end 80.769714 -262.41883)
		(width 0.0889)
		(layer "In6.Cu")
		(net "M_E_CPU1_SB_CA<1>")
	)
	(segment
		(start 83.408012 -261.670292)
		(end 82.940906 -261.93623)
		(width 0.10668)
		(layer "F.Cu")
		(net "M_E_CPU1_SB_CA<0>")
	)
	(segment
		(start 82.179668 -262.263636)
		(end 82.18805 -262.25881)
		(width 0.0889)
		(layer "In6.Cu")
		(net "M_E_CPU1_SB_CA<0>")
	)
	(segment
		(start 76.519532 -261.77621)
		(end 76.799186 -262.055864)
		(width 0.0889)
		(layer "In6.Cu")
		(net "M_E_CPU1_SB_CA<0>")
	)
	(segment
		(start 31.581598 -260.424676)
		(end 31.581598 -260.889496)
		(width 0.14478)
		(layer "In6.Cu")
		(net "M_E_CPU1_SB_CA<0>")
	)
	(segment
		(start 31.418784 -260.261862)
		(end 31.581598 -260.424676)
		(width 0.14478)
		(layer "In6.Cu")
		(net "M_E_CPU1_SB_CA<0>")
	)
	(segment
		(start 29.252164 -261.08533)
		(end 30.075632 -260.261862)
		(width 0.14478)
		(layer "In6.Cu")
		(net "M_E_CPU1_SB_CA<0>")
	)
	(segment
		(start 31.025338 -260.889496)
		(end 31.025338 -260.424676)
		(width 0.14478)
		(layer "In6.Cu")
		(net "M_E_CPU1_SB_CA<0>")
	)
	(segment
		(start 31.188152 -260.261862)
		(end 31.418784 -260.261862)
		(width 0.14478)
		(layer "In6.Cu")
		(net "M_E_CPU1_SB_CA<0>")
	)
	(segment
		(start 30.075632 -260.261862)
		(end 30.306264 -260.261862)
		(width 0.14478)
		(layer "In6.Cu")
		(net "M_E_CPU1_SB_CA<0>")
	)
	(segment
		(start 82.69097 -262.22706)
		(end 82.786982 -262.20166)
		(width 0.0889)
		(layer "In6.Cu")
		(net "M_E_CPU1_SB_CA<0>")
	)
	(segment
		(start 32.366966 -260.660388)
		(end 66.163952 -260.660388)
		(width 0.14478)
		(layer "In6.Cu")
		(net "M_E_CPU1_SB_CA<0>")
	)
	(segment
		(start 66.163952 -260.660388)
		(end 67.279774 -261.77621)
		(width 0.14478)
		(layer "In6.Cu")
		(net "M_E_CPU1_SB_CA<0>")
	)
	(segment
		(start 79.869792 -262.221472)
		(end 79.9338 -262.25881)
		(width 0.0889)
		(layer "In6.Cu")
		(net "M_E_CPU1_SB_CA<0>")
	)
	(segment
		(start 30.469078 -260.889496)
		(end 30.631892 -261.05231)
		(width 0.14478)
		(layer "In6.Cu")
		(net "M_E_CPU1_SB_CA<0>")
	)
	(segment
		(start 30.306264 -260.261862)
		(end 30.469078 -260.424676)
		(width 0.14478)
		(layer "In6.Cu")
		(net "M_E_CPU1_SB_CA<0>")
	)
	(segment
		(start 31.581598 -260.889496)
		(end 31.744412 -261.05231)
		(width 0.14478)
		(layer "In6.Cu")
		(net "M_E_CPU1_SB_CA<0>")
	)
	(segment
		(start 76.016866 -261.77621)
		(end 76.519532 -261.77621)
		(width 0.0889)
		(layer "In6.Cu")
		(net "M_E_CPU1_SB_CA<0>")
	)
	(segment
		(start 31.975044 -261.05231)
		(end 32.366966 -260.660388)
		(width 0.14478)
		(layer "In6.Cu")
		(net "M_E_CPU1_SB_CA<0>")
	)
	(segment
		(start 30.631892 -261.05231)
		(end 30.862524 -261.05231)
		(width 0.14478)
		(layer "In6.Cu")
		(net "M_E_CPU1_SB_CA<0>")
	)
	(segment
		(start 67.279774 -261.77621)
		(end 76.016866 -261.77621)
		(width 0.14478)
		(layer "In6.Cu")
		(net "M_E_CPU1_SB_CA<0>")
	)
	(segment
		(start 30.469078 -260.424676)
		(end 30.469078 -260.889496)
		(width 0.14478)
		(layer "In6.Cu")
		(net "M_E_CPU1_SB_CA<0>")
	)
	(segment
		(start 31.025338 -260.424676)
		(end 31.188152 -260.261862)
		(width 0.14478)
		(layer "In6.Cu")
		(net "M_E_CPU1_SB_CA<0>")
	)
	(segment
		(start 30.862524 -261.05231)
		(end 31.025338 -260.889496)
		(width 0.14478)
		(layer "In6.Cu")
		(net "M_E_CPU1_SB_CA<0>")
	)
	(segment
		(start 31.744412 -261.05231)
		(end 31.975044 -261.05231)
		(width 0.14478)
		(layer "In6.Cu")
		(net "M_E_CPU1_SB_CA<0>")
	)
	(segment
		(start 82.786982 -262.20166)
		(end 82.940906 -261.93623)
		(width 0.0889)
		(layer "In6.Cu")
		(net "M_E_CPU1_SB_CA<0>")
	)
	(segment
		(start 76.799186 -262.055864)
		(end 79.253842 -262.055864)
		(width 0.0889)
		(layer "In6.Cu")
		(net "M_E_CPU1_SB_CA<0>")
	)
	(arc
		(start 79.9338 -262.25881)
		(mid 80.120998 -262.309192)
		(end 80.308196 -262.25881)
		(width 0.0889)
		(layer "In6.Cu")
		(net "M_E_CPU1_SB_CA<0>")
	)
	(arc
		(start 79.253842 -262.055864)
		(mid 79.57278 -262.09791)
		(end 79.869792 -262.221472)
		(width 0.0889)
		(layer "In6.Cu")
		(net "M_E_CPU1_SB_CA<0>")
	)
	(arc
		(start 81.813908 -262.25881)
		(mid 81.996159 -262.30916)
		(end 82.179668 -262.263636)
		(width 0.0889)
		(layer "In6.Cu")
		(net "M_E_CPU1_SB_CA<0>")
	)
	(arc
		(start 81.247996 -262.25881)
		(mid 81.530952 -262.182633)
		(end 81.813908 -262.25881)
		(width 0.0889)
		(layer "In6.Cu")
		(net "M_E_CPU1_SB_CA<0>")
	)
	(arc
		(start 80.874108 -262.25881)
		(mid 81.061052 -262.309065)
		(end 81.247996 -262.25881)
		(width 0.0889)
		(layer "In6.Cu")
		(net "M_E_CPU1_SB_CA<0>")
	)
	(arc
		(start 80.308196 -262.25881)
		(mid 80.591152 -262.182633)
		(end 80.874108 -262.25881)
		(width 0.0889)
		(layer "In6.Cu")
		(net "M_E_CPU1_SB_CA<0>")
	)
	(arc
		(start 82.18805 -262.25881)
		(mid 82.435763 -262.18359)
		(end 82.69097 -262.22706)
		(width 0.0889)
		(layer "In6.Cu")
		(net "M_E_CPU1_SB_CA<0>")
	)
	(segment
		(start 83.408012 -266.530328)
		(end 82.940906 -266.796266)
		(width 0.10668)
		(layer "F.Cu")
		(net "M_E_CPU1_SA_RSP<0>")
	)
	(segment
		(start 76.049886 -266.424664)
		(end 76.456286 -266.424664)
		(width 0.0889)
		(layer "In6.Cu")
		(net "M_E_CPU1_SA_RSP<0>")
	)
	(segment
		(start 30.808168 -269.546324)
		(end 31.027116 -269.546324)
		(width 0.11684)
		(layer "In6.Cu")
		(net "M_E_CPU1_SA_RSP<0>")
	)
	(segment
		(start 31.941516 -269.160244)
		(end 59.753246 -269.160244)
		(width 0.11684)
		(layer "In6.Cu")
		(net "M_E_CPU1_SA_RSP<0>")
	)
	(segment
		(start 62.488826 -266.424664)
		(end 76.049886 -266.424664)
		(width 0.11684)
		(layer "In6.Cu")
		(net "M_E_CPU1_SA_RSP<0>")
	)
	(segment
		(start 76.456286 -266.424664)
		(end 77.069442 -267.03782)
		(width 0.0889)
		(layer "In6.Cu")
		(net "M_E_CPU1_SA_RSP<0>")
	)
	(segment
		(start 30.06344 -268.774164)
		(end 30.498796 -268.774164)
		(width 0.11684)
		(layer "In6.Cu")
		(net "M_E_CPU1_SA_RSP<0>")
	)
	(segment
		(start 29.252164 -269.58544)
		(end 30.06344 -268.774164)
		(width 0.11684)
		(layer "In6.Cu")
		(net "M_E_CPU1_SA_RSP<0>")
	)
	(segment
		(start 31.336488 -268.774164)
		(end 31.555436 -268.774164)
		(width 0.11684)
		(layer "In6.Cu")
		(net "M_E_CPU1_SA_RSP<0>")
	)
	(segment
		(start 77.069442 -267.03782)
		(end 79.743554 -267.03782)
		(width 0.0889)
		(layer "In6.Cu")
		(net "M_E_CPU1_SA_RSP<0>")
	)
	(segment
		(start 30.498796 -268.774164)
		(end 30.653482 -268.92885)
		(width 0.11684)
		(layer "In6.Cu")
		(net "M_E_CPU1_SA_RSP<0>")
	)
	(segment
		(start 59.753246 -269.160244)
		(end 62.488826 -266.424664)
		(width 0.11684)
		(layer "In6.Cu")
		(net "M_E_CPU1_SA_RSP<0>")
	)
	(segment
		(start 79.869792 -267.081508)
		(end 79.9338 -267.118846)
		(width 0.0889)
		(layer "In6.Cu")
		(net "M_E_CPU1_SA_RSP<0>")
	)
	(segment
		(start 31.555436 -268.774164)
		(end 31.941516 -269.160244)
		(width 0.11684)
		(layer "In6.Cu")
		(net "M_E_CPU1_SA_RSP<0>")
	)
	(segment
		(start 30.653482 -268.92885)
		(end 30.653482 -269.391638)
		(width 0.11684)
		(layer "In6.Cu")
		(net "M_E_CPU1_SA_RSP<0>")
	)
	(segment
		(start 31.181802 -268.92885)
		(end 31.336488 -268.774164)
		(width 0.11684)
		(layer "In6.Cu")
		(net "M_E_CPU1_SA_RSP<0>")
	)
	(segment
		(start 82.786982 -267.061696)
		(end 82.940906 -266.796266)
		(width 0.0889)
		(layer "In6.Cu")
		(net "M_E_CPU1_SA_RSP<0>")
	)
	(segment
		(start 31.027116 -269.546324)
		(end 31.181802 -269.391638)
		(width 0.11684)
		(layer "In6.Cu")
		(net "M_E_CPU1_SA_RSP<0>")
	)
	(segment
		(start 30.653482 -269.391638)
		(end 30.808168 -269.546324)
		(width 0.11684)
		(layer "In6.Cu")
		(net "M_E_CPU1_SA_RSP<0>")
	)
	(segment
		(start 31.181802 -269.391638)
		(end 31.181802 -268.92885)
		(width 0.11684)
		(layer "In6.Cu")
		(net "M_E_CPU1_SA_RSP<0>")
	)
	(segment
		(start 82.179668 -267.123672)
		(end 82.18805 -267.118846)
		(width 0.0889)
		(layer "In6.Cu")
		(net "M_E_CPU1_SA_RSP<0>")
	)
	(segment
		(start 82.69097 -267.087096)
		(end 82.786982 -267.061696)
		(width 0.0889)
		(layer "In6.Cu")
		(net "M_E_CPU1_SA_RSP<0>")
	)
	(arc
		(start 81.813908 -267.118846)
		(mid 81.996159 -267.169196)
		(end 82.179668 -267.123672)
		(width 0.0889)
		(layer "In6.Cu")
		(net "M_E_CPU1_SA_RSP<0>")
	)
	(arc
		(start 82.18805 -267.118846)
		(mid 82.435763 -267.043626)
		(end 82.69097 -267.087096)
		(width 0.0889)
		(layer "In6.Cu")
		(net "M_E_CPU1_SA_RSP<0>")
	)
	(arc
		(start 81.247996 -267.118846)
		(mid 81.530952 -267.042669)
		(end 81.813908 -267.118846)
		(width 0.0889)
		(layer "In6.Cu")
		(net "M_E_CPU1_SA_RSP<0>")
	)
	(arc
		(start 80.308196 -267.118846)
		(mid 80.591152 -267.042669)
		(end 80.874108 -267.118846)
		(width 0.0889)
		(layer "In6.Cu")
		(net "M_E_CPU1_SA_RSP<0>")
	)
	(arc
		(start 79.9338 -267.118846)
		(mid 80.120998 -267.169228)
		(end 80.308196 -267.118846)
		(width 0.0889)
		(layer "In6.Cu")
		(net "M_E_CPU1_SA_RSP<0>")
	)
	(arc
		(start 80.874108 -267.118846)
		(mid 81.061052 -267.169101)
		(end 81.247996 -267.118846)
		(width 0.0889)
		(layer "In6.Cu")
		(net "M_E_CPU1_SA_RSP<0>")
	)
	(arc
		(start 79.829914 -267.059156)
		(mid 79.849957 -267.070147)
		(end 79.869792 -267.081508)
		(width 0.0889)
		(layer "In6.Cu")
		(net "M_E_CPU1_SA_RSP<0>")
	)
	(arc
		(start 79.743554 -267.03782)
		(mid 79.788032 -267.043217)
		(end 79.829914 -267.059156)
		(width 0.0889)
		(layer "In6.Cu")
		(net "M_E_CPU1_SA_RSP<0>")
	)
	(segment
		(start 83.107784 -256.09042)
		(end 82.640932 -255.824482)
		(width 0.10668)
		(layer "F.Cu")
		(net "M_E_CPU1_SA_PAR")
	)
	(segment
		(start 73.048114 -256.668524)
		(end 76.054966 -256.668524)
		(width 0.14478)
		(layer "In6.Cu")
		(net "M_E_CPU1_SA_PAR")
	)
	(segment
		(start 29.252164 -254.285242)
		(end 30.710886 -255.743964)
		(width 0.14478)
		(layer "In6.Cu")
		(net "M_E_CPU1_SA_PAR")
	)
	(segment
		(start 33.626044 -255.743964)
		(end 33.789112 -255.580896)
		(width 0.14478)
		(layer "In6.Cu")
		(net "M_E_CPU1_SA_PAR")
	)
	(segment
		(start 35.621722 -255.743964)
		(end 63.737998 -255.743964)
		(width 0.14478)
		(layer "In6.Cu")
		(net "M_E_CPU1_SA_PAR")
	)
	(segment
		(start 79.056992 -255.495044)
		(end 79.068676 -255.501902)
		(width 0.0889)
		(layer "In6.Cu")
		(net "M_E_CPU1_SA_PAR")
	)
	(segment
		(start 79.634334 -255.501902)
		(end 79.646018 -255.495044)
		(width 0.0889)
		(layer "In6.Cu")
		(net "M_E_CPU1_SA_PAR")
	)
	(segment
		(start 82.390996 -255.533652)
		(end 82.487008 -255.559052)
		(width 0.0889)
		(layer "In6.Cu")
		(net "M_E_CPU1_SA_PAR")
	)
	(segment
		(start 33.95218 -255.205484)
		(end 34.182558 -255.205484)
		(width 0.14478)
		(layer "In6.Cu")
		(net "M_E_CPU1_SA_PAR")
	)
	(segment
		(start 35.458654 -255.580896)
		(end 35.621722 -255.743964)
		(width 0.14478)
		(layer "In6.Cu")
		(net "M_E_CPU1_SA_PAR")
	)
	(segment
		(start 33.789112 -255.368552)
		(end 33.95218 -255.205484)
		(width 0.14478)
		(layer "In6.Cu")
		(net "M_E_CPU1_SA_PAR")
	)
	(segment
		(start 79.62392 -255.507998)
		(end 79.634334 -255.501902)
		(width 0.0889)
		(layer "In6.Cu")
		(net "M_E_CPU1_SA_PAR")
	)
	(segment
		(start 82.487008 -255.559052)
		(end 82.640932 -255.824482)
		(width 0.0889)
		(layer "In6.Cu")
		(net "M_E_CPU1_SA_PAR")
	)
	(segment
		(start 34.90214 -255.580896)
		(end 34.90214 -255.368552)
		(width 0.14478)
		(layer "In6.Cu")
		(net "M_E_CPU1_SA_PAR")
	)
	(segment
		(start 34.90214 -255.368552)
		(end 35.065208 -255.205484)
		(width 0.14478)
		(layer "In6.Cu")
		(net "M_E_CPU1_SA_PAR")
	)
	(segment
		(start 34.739072 -255.743964)
		(end 34.90214 -255.580896)
		(width 0.14478)
		(layer "In6.Cu")
		(net "M_E_CPU1_SA_PAR")
	)
	(segment
		(start 34.345626 -255.580896)
		(end 34.508694 -255.743964)
		(width 0.14478)
		(layer "In6.Cu")
		(net "M_E_CPU1_SA_PAR")
	)
	(segment
		(start 34.345626 -255.368552)
		(end 34.345626 -255.580896)
		(width 0.14478)
		(layer "In6.Cu")
		(net "M_E_CPU1_SA_PAR")
	)
	(segment
		(start 76.054966 -256.668524)
		(end 76.796646 -256.668524)
		(width 0.0889)
		(layer "In6.Cu")
		(net "M_E_CPU1_SA_PAR")
	)
	(segment
		(start 33.789112 -255.580896)
		(end 33.789112 -255.368552)
		(width 0.14478)
		(layer "In6.Cu")
		(net "M_E_CPU1_SA_PAR")
	)
	(segment
		(start 30.710886 -255.743964)
		(end 33.626044 -255.743964)
		(width 0.14478)
		(layer "In6.Cu")
		(net "M_E_CPU1_SA_PAR")
	)
	(segment
		(start 64.327278 -255.154684)
		(end 71.534274 -255.154684)
		(width 0.14478)
		(layer "In6.Cu")
		(net "M_E_CPU1_SA_PAR")
	)
	(segment
		(start 35.458654 -255.368552)
		(end 35.458654 -255.580896)
		(width 0.14478)
		(layer "In6.Cu")
		(net "M_E_CPU1_SA_PAR")
	)
	(segment
		(start 35.065208 -255.205484)
		(end 35.295586 -255.205484)
		(width 0.14478)
		(layer "In6.Cu")
		(net "M_E_CPU1_SA_PAR")
	)
	(segment
		(start 76.796646 -256.668524)
		(end 77.812646 -255.652524)
		(width 0.0889)
		(layer "In6.Cu")
		(net "M_E_CPU1_SA_PAR")
	)
	(segment
		(start 71.534274 -255.154684)
		(end 73.048114 -256.668524)
		(width 0.14478)
		(layer "In6.Cu")
		(net "M_E_CPU1_SA_PAR")
	)
	(segment
		(start 35.295586 -255.205484)
		(end 35.458654 -255.368552)
		(width 0.14478)
		(layer "In6.Cu")
		(net "M_E_CPU1_SA_PAR")
	)
	(segment
		(start 63.737998 -255.743964)
		(end 64.327278 -255.154684)
		(width 0.14478)
		(layer "In6.Cu")
		(net "M_E_CPU1_SA_PAR")
	)
	(segment
		(start 81.879694 -255.497076)
		(end 81.888076 -255.501902)
		(width 0.0889)
		(layer "In6.Cu")
		(net "M_E_CPU1_SA_PAR")
	)
	(segment
		(start 34.182558 -255.205484)
		(end 34.345626 -255.368552)
		(width 0.14478)
		(layer "In6.Cu")
		(net "M_E_CPU1_SA_PAR")
	)
	(segment
		(start 34.508694 -255.743964)
		(end 34.739072 -255.743964)
		(width 0.14478)
		(layer "In6.Cu")
		(net "M_E_CPU1_SA_PAR")
	)
	(arc
		(start 79.646018 -255.495044)
		(mid 79.828019 -255.451511)
		(end 80.008222 -255.501902)
		(width 0.0889)
		(layer "In6.Cu")
		(net "M_E_CPU1_SA_PAR")
	)
	(arc
		(start 80.574134 -255.501902)
		(mid 80.761078 -255.451647)
		(end 80.948022 -255.501902)
		(width 0.0889)
		(layer "In6.Cu")
		(net "M_E_CPU1_SA_PAR")
	)
	(arc
		(start 78.69428 -255.501902)
		(mid 78.874738 -255.451458)
		(end 79.056992 -255.495044)
		(width 0.0889)
		(layer "In6.Cu")
		(net "M_E_CPU1_SA_PAR")
	)
	(arc
		(start 80.008222 -255.501902)
		(mid 80.291178 -255.578079)
		(end 80.574134 -255.501902)
		(width 0.0889)
		(layer "In6.Cu")
		(net "M_E_CPU1_SA_PAR")
	)
	(arc
		(start 81.513934 -255.501902)
		(mid 81.696185 -255.451552)
		(end 81.879694 -255.497076)
		(width 0.0889)
		(layer "In6.Cu")
		(net "M_E_CPU1_SA_PAR")
	)
	(arc
		(start 77.812646 -255.652524)
		(mid 78.174943 -255.62618)
		(end 78.53299 -255.564894)
		(width 0.0889)
		(layer "In6.Cu")
		(net "M_E_CPU1_SA_PAR")
	)
	(arc
		(start 81.888076 -255.501902)
		(mid 82.135789 -255.577122)
		(end 82.390996 -255.533652)
		(width 0.0889)
		(layer "In6.Cu")
		(net "M_E_CPU1_SA_PAR")
	)
	(arc
		(start 80.948022 -255.501902)
		(mid 81.230978 -255.578079)
		(end 81.513934 -255.501902)
		(width 0.0889)
		(layer "In6.Cu")
		(net "M_E_CPU1_SA_PAR")
	)
	(arc
		(start 79.068676 -255.501902)
		(mid 79.345489 -255.578045)
		(end 79.62392 -255.507998)
		(width 0.0889)
		(layer "In6.Cu")
		(net "M_E_CPU1_SA_PAR")
	)
	(arc
		(start 78.53299 -255.564894)
		(mid 78.616074 -255.53964)
		(end 78.69428 -255.501902)
		(width 0.0889)
		(layer "In6.Cu")
		(net "M_E_CPU1_SA_PAR")
	)
	(segment
		(start 83.107784 -247.99036)
		(end 82.640932 -247.724422)
		(width 0.12954)
		(layer "F.Cu")
		(net "M_E_CPU1_SA_DQS_DP<9>")
	)
	(segment
		(start 75.30846 -247.682258)
		(end 75.955906 -247.682258)
		(width 0.16002)
		(layer "In6.Cu")
		(net "M_E_CPU1_SA_DQS_DP<9>")
	)
	(segment
		(start 29.624274 -239.727232)
		(end 31.636462 -240.560606)
		(width 0.16002)
		(layer "In6.Cu")
		(net "M_E_CPU1_SA_DQS_DP<9>")
	)
	(segment
		(start 33.891474 -240.22558)
		(end 34.368994 -240.22558)
		(width 0.16002)
		(layer "In6.Cu")
		(net "M_E_CPU1_SA_DQS_DP<9>")
	)
	(segment
		(start 42.796968 -239.341406)
		(end 43.111674 -239.341406)
		(width 0.16002)
		(layer "In6.Cu")
		(net "M_E_CPU1_SA_DQS_DP<9>")
	)
	(segment
		(start 65.137792 -247.174766)
		(end 74.800968 -247.174766)
		(width 0.16002)
		(layer "In6.Cu")
		(net "M_E_CPU1_SA_DQS_DP<9>")
	)
	(segment
		(start 77.83957 -247.36298)
		(end 77.840078 -247.362726)
		(width 0.09525)
		(layer "In6.Cu")
		(net "M_E_CPU1_SA_DQS_DP<9>")
	)
	(segment
		(start 35.253168 -239.341406)
		(end 35.567874 -239.341406)
		(width 0.16002)
		(layer "In6.Cu")
		(net "M_E_CPU1_SA_DQS_DP<9>")
	)
	(segment
		(start 79.622396 -247.405398)
		(end 79.63281 -247.399302)
		(width 0.09525)
		(layer "In6.Cu")
		(net "M_E_CPU1_SA_DQS_DP<9>")
	)
	(segment
		(start 77.839316 -247.362472)
		(end 77.83957 -247.36298)
		(width 0.09525)
		(layer "In6.Cu")
		(net "M_E_CPU1_SA_DQS_DP<9>")
	)
	(segment
		(start 44.77131 -239.727232)
		(end 46.783498 -240.560606)
		(width 0.16002)
		(layer "In6.Cu")
		(net "M_E_CPU1_SA_DQS_DP<9>")
	)
	(segment
		(start 57.692798 -240.691924)
		(end 59.544458 -240.691924)
		(width 0.16002)
		(layer "In6.Cu")
		(net "M_E_CPU1_SA_DQS_DP<9>")
	)
	(segment
		(start 39.147242 -240.560606)
		(end 41.100248 -240.560606)
		(width 0.16002)
		(layer "In6.Cu")
		(net "M_E_CPU1_SA_DQS_DP<9>")
	)
	(segment
		(start 78.121764 -247.394476)
		(end 78.130146 -247.399302)
		(width 0.09525)
		(layer "In6.Cu")
		(net "M_E_CPU1_SA_DQS_DP<9>")
	)
	(segment
		(start 25.425908 -239.561624)
		(end 27.402536 -239.561624)
		(width 0.16002)
		(layer "In6.Cu")
		(net "M_E_CPU1_SA_DQS_DP<9>")
	)
	(segment
		(start 46.783498 -240.560606)
		(end 48.314102 -240.560606)
		(width 0.16002)
		(layer "In6.Cu")
		(net "M_E_CPU1_SA_DQS_DP<9>")
	)
	(segment
		(start 43.111674 -239.341406)
		(end 43.4975 -239.727232)
		(width 0.16002)
		(layer "In6.Cu")
		(net "M_E_CPU1_SA_DQS_DP<9>")
	)
	(segment
		(start 35.9537 -239.727232)
		(end 37.135054 -239.727232)
		(width 0.16002)
		(layer "In6.Cu")
		(net "M_E_CPU1_SA_DQS_DP<9>")
	)
	(segment
		(start 76.90358 -247.62333)
		(end 76.904596 -247.624346)
		(width 0.09525)
		(layer "In6.Cu")
		(net "M_E_CPU1_SA_DQS_DP<9>")
	)
	(segment
		(start 49.456848 -240.22558)
		(end 50.341022 -239.341406)
		(width 0.16002)
		(layer "In6.Cu")
		(net "M_E_CPU1_SA_DQS_DP<9>")
	)
	(segment
		(start 53.992526 -240.22558)
		(end 57.226454 -240.22558)
		(width 0.16002)
		(layer "In6.Cu")
		(net "M_E_CPU1_SA_DQS_DP<9>")
	)
	(segment
		(start 82.487008 -247.458992)
		(end 82.640932 -247.724422)
		(width 0.09525)
		(layer "In6.Cu")
		(net "M_E_CPU1_SA_DQS_DP<9>")
	)
	(segment
		(start 41.435274 -240.22558)
		(end 41.912794 -240.22558)
		(width 0.16002)
		(layer "In6.Cu")
		(net "M_E_CPU1_SA_DQS_DP<9>")
	)
	(segment
		(start 37.135054 -239.727232)
		(end 39.147242 -240.560606)
		(width 0.16002)
		(layer "In6.Cu")
		(net "M_E_CPU1_SA_DQS_DP<9>")
	)
	(segment
		(start 57.226454 -240.22558)
		(end 57.692798 -240.691924)
		(width 0.16002)
		(layer "In6.Cu")
		(net "M_E_CPU1_SA_DQS_DP<9>")
	)
	(segment
		(start 75.979528 -247.682258)
		(end 76.038456 -247.62333)
		(width 0.09525)
		(layer "In6.Cu")
		(net "M_E_CPU1_SA_DQS_DP<9>")
	)
	(segment
		(start 77.671168 -247.453912)
		(end 77.718158 -247.406414)
		(width 0.09525)
		(layer "In6.Cu")
		(net "M_E_CPU1_SA_DQS_DP<9>")
	)
	(segment
		(start 43.4975 -239.727232)
		(end 44.77131 -239.727232)
		(width 0.16002)
		(layer "In6.Cu")
		(net "M_E_CPU1_SA_DQS_DP<9>")
	)
	(segment
		(start 33.556448 -240.560606)
		(end 33.891474 -240.22558)
		(width 0.16002)
		(layer "In6.Cu")
		(net "M_E_CPU1_SA_DQS_DP<9>")
	)
	(segment
		(start 41.100248 -240.560606)
		(end 41.435274 -240.22558)
		(width 0.16002)
		(layer "In6.Cu")
		(net "M_E_CPU1_SA_DQS_DP<9>")
	)
	(segment
		(start 27.583384 -239.380776)
		(end 28.066492 -239.380776)
		(width 0.16002)
		(layer "In6.Cu")
		(net "M_E_CPU1_SA_DQS_DP<9>")
	)
	(segment
		(start 79.058262 -247.392444)
		(end 79.0702 -247.399302)
		(width 0.09525)
		(layer "In6.Cu")
		(net "M_E_CPU1_SA_DQS_DP<9>")
	)
	(segment
		(start 50.655728 -239.341406)
		(end 51.041554 -239.727232)
		(width 0.16002)
		(layer "In6.Cu")
		(net "M_E_CPU1_SA_DQS_DP<9>")
	)
	(segment
		(start 41.912794 -240.22558)
		(end 42.796968 -239.341406)
		(width 0.16002)
		(layer "In6.Cu")
		(net "M_E_CPU1_SA_DQS_DP<9>")
	)
	(segment
		(start 48.314102 -240.560606)
		(end 48.649128 -240.22558)
		(width 0.16002)
		(layer "In6.Cu")
		(net "M_E_CPU1_SA_DQS_DP<9>")
	)
	(segment
		(start 76.904596 -247.624346)
		(end 77.260196 -247.624346)
		(width 0.09525)
		(layer "In6.Cu")
		(net "M_E_CPU1_SA_DQS_DP<9>")
	)
	(segment
		(start 51.041554 -239.727232)
		(end 52.789328 -239.727232)
		(width 0.16002)
		(layer "In6.Cu")
		(net "M_E_CPU1_SA_DQS_DP<9>")
	)
	(segment
		(start 52.789328 -239.727232)
		(end 53.992526 -240.22558)
		(width 0.16002)
		(layer "In6.Cu")
		(net "M_E_CPU1_SA_DQS_DP<9>")
	)
	(segment
		(start 59.86145 -241.008916)
		(end 59.86145 -241.898424)
		(width 0.16002)
		(layer "In6.Cu")
		(net "M_E_CPU1_SA_DQS_DP<9>")
	)
	(segment
		(start 59.544458 -240.691924)
		(end 59.86145 -241.008916)
		(width 0.16002)
		(layer "In6.Cu")
		(net "M_E_CPU1_SA_DQS_DP<9>")
	)
	(segment
		(start 59.86145 -241.898424)
		(end 65.137792 -247.174766)
		(width 0.16002)
		(layer "In6.Cu")
		(net "M_E_CPU1_SA_DQS_DP<9>")
	)
	(segment
		(start 28.066492 -239.380776)
		(end 28.412948 -239.727232)
		(width 0.16002)
		(layer "In6.Cu")
		(net "M_E_CPU1_SA_DQS_DP<9>")
	)
	(segment
		(start 35.567874 -239.341406)
		(end 35.9537 -239.727232)
		(width 0.16002)
		(layer "In6.Cu")
		(net "M_E_CPU1_SA_DQS_DP<9>")
	)
	(segment
		(start 74.800968 -247.174766)
		(end 75.30846 -247.682258)
		(width 0.16002)
		(layer "In6.Cu")
		(net "M_E_CPU1_SA_DQS_DP<9>")
	)
	(segment
		(start 27.402536 -239.561624)
		(end 27.583384 -239.380776)
		(width 0.16002)
		(layer "In6.Cu")
		(net "M_E_CPU1_SA_DQS_DP<9>")
	)
	(segment
		(start 76.038456 -247.62333)
		(end 76.90358 -247.62333)
		(width 0.09525)
		(layer "In6.Cu")
		(net "M_E_CPU1_SA_DQS_DP<9>")
	)
	(segment
		(start 81.881218 -247.394476)
		(end 81.8896 -247.399302)
		(width 0.09525)
		(layer "In6.Cu")
		(net "M_E_CPU1_SA_DQS_DP<9>")
	)
	(segment
		(start 78.130146 -247.399302)
		(end 78.14818 -247.409716)
		(width 0.09525)
		(layer "In6.Cu")
		(net "M_E_CPU1_SA_DQS_DP<9>")
	)
	(segment
		(start 48.649128 -240.22558)
		(end 49.456848 -240.22558)
		(width 0.16002)
		(layer "In6.Cu")
		(net "M_E_CPU1_SA_DQS_DP<9>")
	)
	(segment
		(start 79.63281 -247.399302)
		(end 79.644748 -247.392444)
		(width 0.09525)
		(layer "In6.Cu")
		(net "M_E_CPU1_SA_DQS_DP<9>")
	)
	(segment
		(start 50.341022 -239.341406)
		(end 50.655728 -239.341406)
		(width 0.16002)
		(layer "In6.Cu")
		(net "M_E_CPU1_SA_DQS_DP<9>")
	)
	(segment
		(start 34.368994 -240.22558)
		(end 35.253168 -239.341406)
		(width 0.16002)
		(layer "In6.Cu")
		(net "M_E_CPU1_SA_DQS_DP<9>")
	)
	(segment
		(start 31.636462 -240.560606)
		(end 33.556448 -240.560606)
		(width 0.16002)
		(layer "In6.Cu")
		(net "M_E_CPU1_SA_DQS_DP<9>")
	)
	(segment
		(start 28.412948 -239.727232)
		(end 29.624274 -239.727232)
		(width 0.16002)
		(layer "In6.Cu")
		(net "M_E_CPU1_SA_DQS_DP<9>")
	)
	(segment
		(start 25.152096 -239.835436)
		(end 25.425908 -239.561624)
		(width 0.16002)
		(layer "In6.Cu")
		(net "M_E_CPU1_SA_DQS_DP<9>")
	)
	(segment
		(start 75.955906 -247.682258)
		(end 75.979528 -247.682258)
		(width 0.09525)
		(layer "In6.Cu")
		(net "M_E_CPU1_SA_DQS_DP<9>")
	)
	(segment
		(start 82.38617 -247.432322)
		(end 82.487008 -247.458992)
		(width 0.09525)
		(layer "In6.Cu")
		(net "M_E_CPU1_SA_DQS_DP<9>")
	)
	(arc
		(start 80.009746 -247.399302)
		(mid 80.291178 -247.475057)
		(end 80.57261 -247.399302)
		(width 0.09525)
		(layer "In6.Cu")
		(net "M_E_CPU1_SA_DQS_DP<9>")
	)
	(arc
		(start 77.718158 -247.406414)
		(mid 77.740583 -247.389593)
		(end 77.766926 -247.379998)
		(width 0.09525)
		(layer "In6.Cu")
		(net "M_E_CPU1_SA_DQS_DP<9>")
	)
	(arc
		(start 78.14818 -247.409716)
		(mid 78.421814 -247.475057)
		(end 78.692756 -247.399302)
		(width 0.09525)
		(layer "In6.Cu")
		(net "M_E_CPU1_SA_DQS_DP<9>")
	)
	(arc
		(start 79.0702 -247.399302)
		(mid 79.345489 -247.475023)
		(end 79.622396 -247.405398)
		(width 0.09525)
		(layer "In6.Cu")
		(net "M_E_CPU1_SA_DQS_DP<9>")
	)
	(arc
		(start 77.766926 -247.379998)
		(mid 77.803266 -247.371832)
		(end 77.839316 -247.362472)
		(width 0.09525)
		(layer "In6.Cu")
		(net "M_E_CPU1_SA_DQS_DP<9>")
	)
	(arc
		(start 80.949546 -247.399302)
		(mid 81.230978 -247.475057)
		(end 81.51241 -247.399302)
		(width 0.09525)
		(layer "In6.Cu")
		(net "M_E_CPU1_SA_DQS_DP<9>")
	)
	(arc
		(start 79.644748 -247.392444)
		(mid 79.828129 -247.348613)
		(end 80.009746 -247.399302)
		(width 0.09525)
		(layer "In6.Cu")
		(net "M_E_CPU1_SA_DQS_DP<9>")
	)
	(arc
		(start 81.8896 -247.399302)
		(mid 82.123395 -247.473169)
		(end 82.366358 -247.440196)
		(width 0.09525)
		(layer "In6.Cu")
		(net "M_E_CPU1_SA_DQS_DP<9>")
	)
	(arc
		(start 77.260196 -247.624346)
		(mid 77.482659 -247.580082)
		(end 77.671168 -247.453912)
		(width 0.09525)
		(layer "In6.Cu")
		(net "M_E_CPU1_SA_DQS_DP<9>")
	)
	(arc
		(start 82.366358 -247.440196)
		(mid 82.376301 -247.436353)
		(end 82.38617 -247.432322)
		(width 0.09525)
		(layer "In6.Cu")
		(net "M_E_CPU1_SA_DQS_DP<9>")
	)
	(arc
		(start 81.51241 -247.399302)
		(mid 81.696185 -247.34853)
		(end 81.881218 -247.394476)
		(width 0.09525)
		(layer "In6.Cu")
		(net "M_E_CPU1_SA_DQS_DP<9>")
	)
	(arc
		(start 77.840078 -247.362726)
		(mid 77.984029 -247.351024)
		(end 78.121764 -247.394476)
		(width 0.09525)
		(layer "In6.Cu")
		(net "M_E_CPU1_SA_DQS_DP<9>")
	)
	(arc
		(start 78.692756 -247.399302)
		(mid 78.874626 -247.348437)
		(end 79.058262 -247.392444)
		(width 0.09525)
		(layer "In6.Cu")
		(net "M_E_CPU1_SA_DQS_DP<9>")
	)
	(arc
		(start 80.57261 -247.399302)
		(mid 80.761078 -247.348625)
		(end 80.949546 -247.399302)
		(width 0.09525)
		(layer "In6.Cu")
		(net "M_E_CPU1_SA_DQS_DP<9>")
	)
	(segment
		(start 83.107784 -243.130324)
		(end 82.640932 -242.864386)
		(width 0.12954)
		(layer "F.Cu")
		(net "M_E_CPU1_SA_DQS_DP<8>")
	)
	(segment
		(start 27.56408 -230.030782)
		(end 27.9146 -230.030782)
		(width 0.16002)
		(layer "In6.Cu")
		(net "M_E_CPU1_SA_DQS_DP<8>")
	)
	(segment
		(start 27.127454 -230.21163)
		(end 27.56408 -230.030782)
		(width 0.16002)
		(layer "In6.Cu")
		(net "M_E_CPU1_SA_DQS_DP<8>")
	)
	(segment
		(start 41.912794 -230.875586)
		(end 42.796968 -229.991412)
		(width 0.16002)
		(layer "In6.Cu")
		(net "M_E_CPU1_SA_DQS_DP<8>")
	)
	(segment
		(start 76.151486 -241.525806)
		(end 76.246736 -241.621056)
		(width 0.09525)
		(layer "In6.Cu")
		(net "M_E_CPU1_SA_DQS_DP<8>")
	)
	(segment
		(start 42.796968 -229.991412)
		(end 43.111674 -229.991412)
		(width 0.16002)
		(layer "In6.Cu")
		(net "M_E_CPU1_SA_DQS_DP<8>")
	)
	(segment
		(start 81.881218 -242.53444)
		(end 81.8896 -242.539266)
		(width 0.09525)
		(layer "In6.Cu")
		(net "M_E_CPU1_SA_DQS_DP<8>")
	)
	(segment
		(start 77.4065 -242.138454)
		(end 77.756004 -242.487958)
		(width 0.09525)
		(layer "In6.Cu")
		(net "M_E_CPU1_SA_DQS_DP<8>")
	)
	(segment
		(start 34.368994 -230.875586)
		(end 35.253168 -229.991412)
		(width 0.16002)
		(layer "In6.Cu")
		(net "M_E_CPU1_SA_DQS_DP<8>")
	)
	(segment
		(start 58.199782 -229.991412)
		(end 58.860436 -230.652066)
		(width 0.16002)
		(layer "In6.Cu")
		(net "M_E_CPU1_SA_DQS_DP<8>")
	)
	(segment
		(start 50.655728 -229.991412)
		(end 51.02479 -230.360474)
		(width 0.16002)
		(layer "In6.Cu")
		(net "M_E_CPU1_SA_DQS_DP<8>")
	)
	(segment
		(start 53.992526 -230.875586)
		(end 57.000902 -230.875586)
		(width 0.16002)
		(layer "In6.Cu")
		(net "M_E_CPU1_SA_DQS_DP<8>")
	)
	(segment
		(start 59.931808 -230.652066)
		(end 62.422278 -233.142536)
		(width 0.16002)
		(layer "In6.Cu")
		(net "M_E_CPU1_SA_DQS_DP<8>")
	)
	(segment
		(start 76.66863 -242.138454)
		(end 77.4065 -242.138454)
		(width 0.09525)
		(layer "In6.Cu")
		(net "M_E_CPU1_SA_DQS_DP<8>")
	)
	(segment
		(start 82.487008 -242.598956)
		(end 82.640932 -242.864386)
		(width 0.09525)
		(layer "In6.Cu")
		(net "M_E_CPU1_SA_DQS_DP<8>")
	)
	(segment
		(start 27.9146 -230.030782)
		(end 28.751022 -230.377238)
		(width 0.16002)
		(layer "In6.Cu")
		(net "M_E_CPU1_SA_DQS_DP<8>")
	)
	(segment
		(start 41.435274 -230.875586)
		(end 41.912794 -230.875586)
		(width 0.16002)
		(layer "In6.Cu")
		(net "M_E_CPU1_SA_DQS_DP<8>")
	)
	(segment
		(start 79.622396 -242.545362)
		(end 79.63281 -242.539266)
		(width 0.09525)
		(layer "In6.Cu")
		(net "M_E_CPU1_SA_DQS_DP<8>")
	)
	(segment
		(start 57.000902 -230.875586)
		(end 57.885076 -229.991412)
		(width 0.16002)
		(layer "In6.Cu")
		(net "M_E_CPU1_SA_DQS_DP<8>")
	)
	(segment
		(start 50.341022 -229.991412)
		(end 50.655728 -229.991412)
		(width 0.16002)
		(layer "In6.Cu")
		(net "M_E_CPU1_SA_DQS_DP<8>")
	)
	(segment
		(start 45.93336 -230.360474)
		(end 46.783498 -231.210612)
		(width 0.16002)
		(layer "In6.Cu")
		(net "M_E_CPU1_SA_DQS_DP<8>")
	)
	(segment
		(start 33.01746 -231.210612)
		(end 33.82645 -230.875586)
		(width 0.16002)
		(layer "In6.Cu")
		(net "M_E_CPU1_SA_DQS_DP<8>")
	)
	(segment
		(start 48.644302 -231.210612)
		(end 48.979328 -230.875586)
		(width 0.16002)
		(layer "In6.Cu")
		(net "M_E_CPU1_SA_DQS_DP<8>")
	)
	(segment
		(start 79.058262 -242.532408)
		(end 79.0702 -242.539266)
		(width 0.09525)
		(layer "In6.Cu")
		(net "M_E_CPU1_SA_DQS_DP<8>")
	)
	(segment
		(start 31.033466 -230.60787)
		(end 31.262066 -230.83647)
		(width 0.16002)
		(layer "In6.Cu")
		(net "M_E_CPU1_SA_DQS_DP<8>")
	)
	(segment
		(start 32.16529 -231.210612)
		(end 33.01746 -231.210612)
		(width 0.16002)
		(layer "In6.Cu")
		(net "M_E_CPU1_SA_DQS_DP<8>")
	)
	(segment
		(start 78.130146 -242.539266)
		(end 78.14818 -242.54968)
		(width 0.09525)
		(layer "In6.Cu")
		(net "M_E_CPU1_SA_DQS_DP<8>")
	)
	(segment
		(start 63.44793 -235.61802)
		(end 69.414644 -241.584734)
		(width 0.16002)
		(layer "In6.Cu")
		(net "M_E_CPU1_SA_DQS_DP<8>")
	)
	(segment
		(start 69.414644 -241.584734)
		(end 75.955906 -241.584734)
		(width 0.16002)
		(layer "In6.Cu")
		(net "M_E_CPU1_SA_DQS_DP<8>")
	)
	(segment
		(start 53.477414 -230.360474)
		(end 53.992526 -230.875586)
		(width 0.16002)
		(layer "In6.Cu")
		(net "M_E_CPU1_SA_DQS_DP<8>")
	)
	(segment
		(start 33.82645 -230.875586)
		(end 34.368994 -230.875586)
		(width 0.16002)
		(layer "In6.Cu")
		(net "M_E_CPU1_SA_DQS_DP<8>")
	)
	(segment
		(start 76.038456 -241.525806)
		(end 76.151486 -241.525806)
		(width 0.09525)
		(layer "In6.Cu")
		(net "M_E_CPU1_SA_DQS_DP<8>")
	)
	(segment
		(start 35.253168 -229.991412)
		(end 35.567874 -229.991412)
		(width 0.16002)
		(layer "In6.Cu")
		(net "M_E_CPU1_SA_DQS_DP<8>")
	)
	(segment
		(start 46.783498 -231.210612)
		(end 48.644302 -231.210612)
		(width 0.16002)
		(layer "In6.Cu")
		(net "M_E_CPU1_SA_DQS_DP<8>")
	)
	(segment
		(start 38.297104 -230.360474)
		(end 39.147242 -231.210612)
		(width 0.16002)
		(layer "In6.Cu")
		(net "M_E_CPU1_SA_DQS_DP<8>")
	)
	(segment
		(start 49.456848 -230.875586)
		(end 50.341022 -229.991412)
		(width 0.16002)
		(layer "In6.Cu")
		(net "M_E_CPU1_SA_DQS_DP<8>")
	)
	(segment
		(start 76.246736 -241.621056)
		(end 76.246736 -241.71656)
		(width 0.09525)
		(layer "In6.Cu")
		(net "M_E_CPU1_SA_DQS_DP<8>")
	)
	(segment
		(start 25.425908 -230.21163)
		(end 27.127454 -230.21163)
		(width 0.16002)
		(layer "In6.Cu")
		(net "M_E_CPU1_SA_DQS_DP<8>")
	)
	(segment
		(start 58.860436 -230.652066)
		(end 59.931808 -230.652066)
		(width 0.16002)
		(layer "In6.Cu")
		(net "M_E_CPU1_SA_DQS_DP<8>")
	)
	(segment
		(start 35.936936 -230.360474)
		(end 38.297104 -230.360474)
		(width 0.16002)
		(layer "In6.Cu")
		(net "M_E_CPU1_SA_DQS_DP<8>")
	)
	(segment
		(start 57.885076 -229.991412)
		(end 58.199782 -229.991412)
		(width 0.16002)
		(layer "In6.Cu")
		(net "M_E_CPU1_SA_DQS_DP<8>")
	)
	(segment
		(start 51.02479 -230.360474)
		(end 53.477414 -230.360474)
		(width 0.16002)
		(layer "In6.Cu")
		(net "M_E_CPU1_SA_DQS_DP<8>")
	)
	(segment
		(start 41.100248 -231.210612)
		(end 41.435274 -230.875586)
		(width 0.16002)
		(layer "In6.Cu")
		(net "M_E_CPU1_SA_DQS_DP<8>")
	)
	(segment
		(start 39.147242 -231.210612)
		(end 41.100248 -231.210612)
		(width 0.16002)
		(layer "In6.Cu")
		(net "M_E_CPU1_SA_DQS_DP<8>")
	)
	(segment
		(start 76.246736 -241.71656)
		(end 76.66863 -242.138454)
		(width 0.09525)
		(layer "In6.Cu")
		(net "M_E_CPU1_SA_DQS_DP<8>")
	)
	(segment
		(start 43.480736 -230.360474)
		(end 45.93336 -230.360474)
		(width 0.16002)
		(layer "In6.Cu")
		(net "M_E_CPU1_SA_DQS_DP<8>")
	)
	(segment
		(start 75.979528 -241.584734)
		(end 76.038456 -241.525806)
		(width 0.09525)
		(layer "In6.Cu")
		(net "M_E_CPU1_SA_DQS_DP<8>")
	)
	(segment
		(start 35.567874 -229.991412)
		(end 35.936936 -230.360474)
		(width 0.16002)
		(layer "In6.Cu")
		(net "M_E_CPU1_SA_DQS_DP<8>")
	)
	(segment
		(start 79.63281 -242.539266)
		(end 79.644748 -242.532408)
		(width 0.09525)
		(layer "In6.Cu")
		(net "M_E_CPU1_SA_DQS_DP<8>")
	)
	(segment
		(start 43.111674 -229.991412)
		(end 43.480736 -230.360474)
		(width 0.16002)
		(layer "In6.Cu")
		(net "M_E_CPU1_SA_DQS_DP<8>")
	)
	(segment
		(start 30.477206 -230.377238)
		(end 31.033466 -230.60787)
		(width 0.16002)
		(layer "In6.Cu")
		(net "M_E_CPU1_SA_DQS_DP<8>")
	)
	(segment
		(start 75.955906 -241.584734)
		(end 75.979528 -241.584734)
		(width 0.09525)
		(layer "In6.Cu")
		(net "M_E_CPU1_SA_DQS_DP<8>")
	)
	(segment
		(start 31.262066 -230.83647)
		(end 32.16529 -231.210612)
		(width 0.16002)
		(layer "In6.Cu")
		(net "M_E_CPU1_SA_DQS_DP<8>")
	)
	(segment
		(start 62.422278 -233.142536)
		(end 63.44793 -235.61802)
		(width 0.16002)
		(layer "In6.Cu")
		(net "M_E_CPU1_SA_DQS_DP<8>")
	)
	(segment
		(start 82.38617 -242.572286)
		(end 82.487008 -242.598956)
		(width 0.09525)
		(layer "In6.Cu")
		(net "M_E_CPU1_SA_DQS_DP<8>")
	)
	(segment
		(start 25.152096 -230.485442)
		(end 25.425908 -230.21163)
		(width 0.16002)
		(layer "In6.Cu")
		(net "M_E_CPU1_SA_DQS_DP<8>")
	)
	(segment
		(start 48.979328 -230.875586)
		(end 49.456848 -230.875586)
		(width 0.16002)
		(layer "In6.Cu")
		(net "M_E_CPU1_SA_DQS_DP<8>")
	)
	(segment
		(start 77.756004 -242.487958)
		(end 77.941678 -242.487958)
		(width 0.09525)
		(layer "In6.Cu")
		(net "M_E_CPU1_SA_DQS_DP<8>")
	)
	(segment
		(start 28.751022 -230.377238)
		(end 30.477206 -230.377238)
		(width 0.16002)
		(layer "In6.Cu")
		(net "M_E_CPU1_SA_DQS_DP<8>")
	)
	(arc
		(start 81.8896 -242.539266)
		(mid 82.123395 -242.613133)
		(end 82.366358 -242.58016)
		(width 0.09525)
		(layer "In6.Cu")
		(net "M_E_CPU1_SA_DQS_DP<8>")
	)
	(arc
		(start 81.51241 -242.539266)
		(mid 81.696185 -242.488494)
		(end 81.881218 -242.53444)
		(width 0.09525)
		(layer "In6.Cu")
		(net "M_E_CPU1_SA_DQS_DP<8>")
	)
	(arc
		(start 80.57261 -242.539266)
		(mid 80.761078 -242.488589)
		(end 80.949546 -242.539266)
		(width 0.09525)
		(layer "In6.Cu")
		(net "M_E_CPU1_SA_DQS_DP<8>")
	)
	(arc
		(start 80.949546 -242.539266)
		(mid 81.230978 -242.615021)
		(end 81.51241 -242.539266)
		(width 0.09525)
		(layer "In6.Cu")
		(net "M_E_CPU1_SA_DQS_DP<8>")
	)
	(arc
		(start 79.644748 -242.532408)
		(mid 79.828129 -242.488577)
		(end 80.009746 -242.539266)
		(width 0.09525)
		(layer "In6.Cu")
		(net "M_E_CPU1_SA_DQS_DP<8>")
	)
	(arc
		(start 80.009746 -242.539266)
		(mid 80.291178 -242.615021)
		(end 80.57261 -242.539266)
		(width 0.09525)
		(layer "In6.Cu")
		(net "M_E_CPU1_SA_DQS_DP<8>")
	)
	(arc
		(start 82.366358 -242.58016)
		(mid 82.376301 -242.576317)
		(end 82.38617 -242.572286)
		(width 0.09525)
		(layer "In6.Cu")
		(net "M_E_CPU1_SA_DQS_DP<8>")
	)
	(arc
		(start 79.0702 -242.539266)
		(mid 79.345489 -242.614987)
		(end 79.622396 -242.545362)
		(width 0.09525)
		(layer "In6.Cu")
		(net "M_E_CPU1_SA_DQS_DP<8>")
	)
	(arc
		(start 78.692756 -242.539266)
		(mid 78.874626 -242.488401)
		(end 79.058262 -242.532408)
		(width 0.09525)
		(layer "In6.Cu")
		(net "M_E_CPU1_SA_DQS_DP<8>")
	)
	(arc
		(start 78.14818 -242.54968)
		(mid 78.421814 -242.615021)
		(end 78.692756 -242.539266)
		(width 0.09525)
		(layer "In6.Cu")
		(net "M_E_CPU1_SA_DQS_DP<8>")
	)
	(arc
		(start 77.941678 -242.487958)
		(mid 78.039292 -242.501185)
		(end 78.130146 -242.539266)
		(width 0.09525)
		(layer "In6.Cu")
		(net "M_E_CPU1_SA_DQS_DP<8>")
	)
	(segment
		(start 83.107784 -238.270288)
		(end 82.640932 -238.00435)
		(width 0.12954)
		(layer "F.Cu")
		(net "M_E_CPU1_SA_DQS_DP<7>")
	)
	(segment
		(start 25.425908 -220.861382)
		(end 27.334464 -220.861382)
		(width 0.16002)
		(layer "In6.Cu")
		(net "M_E_CPU1_SA_DQS_DP<7>")
	)
	(segment
		(start 32.307784 -221.860364)
		(end 33.06064 -221.860364)
		(width 0.16002)
		(layer "In6.Cu")
		(net "M_E_CPU1_SA_DQS_DP<7>")
	)
	(segment
		(start 76.038456 -235.857288)
		(end 76.159106 -235.857288)
		(width 0.09525)
		(layer "In6.Cu")
		(net "M_E_CPU1_SA_DQS_DP<7>")
	)
	(segment
		(start 79.058262 -237.672372)
		(end 79.0702 -237.67923)
		(width 0.09525)
		(layer "In6.Cu")
		(net "M_E_CPU1_SA_DQS_DP<7>")
	)
	(segment
		(start 73.258426 -235.916216)
		(end 75.955906 -235.916216)
		(width 0.16002)
		(layer "In6.Cu")
		(net "M_E_CPU1_SA_DQS_DP<7>")
	)
	(segment
		(start 75.979528 -235.916216)
		(end 76.038456 -235.857288)
		(width 0.09525)
		(layer "In6.Cu")
		(net "M_E_CPU1_SA_DQS_DP<7>")
	)
	(segment
		(start 76.98486 -236.268514)
		(end 77.224636 -236.50829)
		(width 0.09525)
		(layer "In6.Cu")
		(net "M_E_CPU1_SA_DQS_DP<7>")
	)
	(segment
		(start 42.803318 -220.656404)
		(end 43.170348 -220.656404)
		(width 0.16002)
		(layer "In6.Cu")
		(net "M_E_CPU1_SA_DQS_DP<7>")
	)
	(segment
		(start 62.35827 -222.405448)
		(end 62.35827 -223.986852)
		(width 0.16002)
		(layer "In6.Cu")
		(net "M_E_CPU1_SA_DQS_DP<7>")
	)
	(segment
		(start 79.622396 -237.685326)
		(end 79.63281 -237.67923)
		(width 0.09525)
		(layer "In6.Cu")
		(net "M_E_CPU1_SA_DQS_DP<7>")
	)
	(segment
		(start 40.531288 -221.860364)
		(end 41.303448 -221.540578)
		(width 0.16002)
		(layer "In6.Cu")
		(net "M_E_CPU1_SA_DQS_DP<7>")
	)
	(segment
		(start 51.003454 -221.01048)
		(end 53.455824 -221.01048)
		(width 0.16002)
		(layer "In6.Cu")
		(net "M_E_CPU1_SA_DQS_DP<7>")
	)
	(segment
		(start 28.060142 -220.695774)
		(end 28.406598 -221.04223)
		(width 0.16002)
		(layer "In6.Cu")
		(net "M_E_CPU1_SA_DQS_DP<7>")
	)
	(segment
		(start 75.955906 -235.916216)
		(end 75.979528 -235.916216)
		(width 0.09525)
		(layer "In6.Cu")
		(net "M_E_CPU1_SA_DQS_DP<7>")
	)
	(segment
		(start 27.334464 -220.861382)
		(end 27.500072 -220.695774)
		(width 0.16002)
		(layer "In6.Cu")
		(net "M_E_CPU1_SA_DQS_DP<7>")
	)
	(segment
		(start 82.38617 -237.71225)
		(end 82.487008 -237.73892)
		(width 0.09525)
		(layer "In6.Cu")
		(net "M_E_CPU1_SA_DQS_DP<7>")
	)
	(segment
		(start 62.35827 -223.986852)
		(end 64.71285 -226.341432)
		(width 0.16002)
		(layer "In6.Cu")
		(net "M_E_CPU1_SA_DQS_DP<7>")
	)
	(segment
		(start 58.193432 -220.656658)
		(end 58.894218 -221.357444)
		(width 0.16002)
		(layer "In6.Cu")
		(net "M_E_CPU1_SA_DQS_DP<7>")
	)
	(segment
		(start 79.63281 -237.67923)
		(end 79.644748 -237.672372)
		(width 0.09525)
		(layer "In6.Cu")
		(net "M_E_CPU1_SA_DQS_DP<7>")
	)
	(segment
		(start 77.224636 -236.50829)
		(end 77.224636 -236.657896)
		(width 0.09525)
		(layer "In6.Cu")
		(net "M_E_CPU1_SA_DQS_DP<7>")
	)
	(segment
		(start 43.170348 -220.656404)
		(end 44.025312 -221.01048)
		(width 0.16002)
		(layer "In6.Cu")
		(net "M_E_CPU1_SA_DQS_DP<7>")
	)
	(segment
		(start 25.152096 -221.135194)
		(end 25.425908 -220.861382)
		(width 0.16002)
		(layer "In6.Cu")
		(net "M_E_CPU1_SA_DQS_DP<7>")
	)
	(segment
		(start 57.007252 -221.540832)
		(end 57.891426 -220.656658)
		(width 0.16002)
		(layer "In6.Cu")
		(net "M_E_CPU1_SA_DQS_DP<7>")
	)
	(segment
		(start 61.310266 -221.357444)
		(end 62.35827 -222.405448)
		(width 0.16002)
		(layer "In6.Cu")
		(net "M_E_CPU1_SA_DQS_DP<7>")
	)
	(segment
		(start 50.347372 -220.656404)
		(end 50.649378 -220.656404)
		(width 0.16002)
		(layer "In6.Cu")
		(net "M_E_CPU1_SA_DQS_DP<7>")
	)
	(segment
		(start 30.33268 -221.04223)
		(end 32.307784 -221.860364)
		(width 0.16002)
		(layer "In6.Cu")
		(net "M_E_CPU1_SA_DQS_DP<7>")
	)
	(segment
		(start 33.8328 -221.540578)
		(end 34.375344 -221.540578)
		(width 0.16002)
		(layer "In6.Cu")
		(net "M_E_CPU1_SA_DQS_DP<7>")
	)
	(segment
		(start 39.125652 -221.860364)
		(end 40.531288 -221.860364)
		(width 0.16002)
		(layer "In6.Cu")
		(net "M_E_CPU1_SA_DQS_DP<7>")
	)
	(segment
		(start 49.463198 -221.540578)
		(end 50.347372 -220.656404)
		(width 0.16002)
		(layer "In6.Cu")
		(net "M_E_CPU1_SA_DQS_DP<7>")
	)
	(segment
		(start 48.920654 -221.540578)
		(end 49.463198 -221.540578)
		(width 0.16002)
		(layer "In6.Cu")
		(net "M_E_CPU1_SA_DQS_DP<7>")
	)
	(segment
		(start 38.275768 -221.01048)
		(end 39.125652 -221.860364)
		(width 0.16002)
		(layer "In6.Cu")
		(net "M_E_CPU1_SA_DQS_DP<7>")
	)
	(segment
		(start 58.894218 -221.357444)
		(end 61.310266 -221.357444)
		(width 0.16002)
		(layer "In6.Cu")
		(net "M_E_CPU1_SA_DQS_DP<7>")
	)
	(segment
		(start 41.919144 -221.540578)
		(end 42.803318 -220.656404)
		(width 0.16002)
		(layer "In6.Cu")
		(net "M_E_CPU1_SA_DQS_DP<7>")
	)
	(segment
		(start 64.71285 -227.37064)
		(end 73.258426 -235.916216)
		(width 0.16002)
		(layer "In6.Cu")
		(net "M_E_CPU1_SA_DQS_DP<7>")
	)
	(segment
		(start 57.891426 -220.656658)
		(end 58.193432 -220.656658)
		(width 0.16002)
		(layer "In6.Cu")
		(net "M_E_CPU1_SA_DQS_DP<7>")
	)
	(segment
		(start 53.986176 -221.540832)
		(end 57.007252 -221.540832)
		(width 0.16002)
		(layer "In6.Cu")
		(net "M_E_CPU1_SA_DQS_DP<7>")
	)
	(segment
		(start 82.487008 -237.73892)
		(end 82.640932 -238.00435)
		(width 0.09525)
		(layer "In6.Cu")
		(net "M_E_CPU1_SA_DQS_DP<7>")
	)
	(segment
		(start 46.761908 -221.860364)
		(end 48.148494 -221.860364)
		(width 0.16002)
		(layer "In6.Cu")
		(net "M_E_CPU1_SA_DQS_DP<7>")
	)
	(segment
		(start 44.025312 -221.01048)
		(end 45.912024 -221.01048)
		(width 0.16002)
		(layer "In6.Cu")
		(net "M_E_CPU1_SA_DQS_DP<7>")
	)
	(segment
		(start 36.416488 -221.01048)
		(end 38.275768 -221.01048)
		(width 0.16002)
		(layer "In6.Cu")
		(net "M_E_CPU1_SA_DQS_DP<7>")
	)
	(segment
		(start 28.406598 -221.04223)
		(end 30.33268 -221.04223)
		(width 0.16002)
		(layer "In6.Cu")
		(net "M_E_CPU1_SA_DQS_DP<7>")
	)
	(segment
		(start 35.259518 -220.656404)
		(end 35.561524 -220.656404)
		(width 0.16002)
		(layer "In6.Cu")
		(net "M_E_CPU1_SA_DQS_DP<7>")
	)
	(segment
		(start 76.570332 -236.268514)
		(end 76.98486 -236.268514)
		(width 0.09525)
		(layer "In6.Cu")
		(net "M_E_CPU1_SA_DQS_DP<7>")
	)
	(segment
		(start 45.912024 -221.01048)
		(end 46.761908 -221.860364)
		(width 0.16002)
		(layer "In6.Cu")
		(net "M_E_CPU1_SA_DQS_DP<7>")
	)
	(segment
		(start 64.71285 -226.341432)
		(end 64.71285 -227.37064)
		(width 0.16002)
		(layer "In6.Cu")
		(net "M_E_CPU1_SA_DQS_DP<7>")
	)
	(segment
		(start 76.159106 -235.857288)
		(end 76.570332 -236.268514)
		(width 0.09525)
		(layer "In6.Cu")
		(net "M_E_CPU1_SA_DQS_DP<7>")
	)
	(segment
		(start 34.375344 -221.540578)
		(end 35.259518 -220.656404)
		(width 0.16002)
		(layer "In6.Cu")
		(net "M_E_CPU1_SA_DQS_DP<7>")
	)
	(segment
		(start 50.649378 -220.656404)
		(end 51.003454 -221.01048)
		(width 0.16002)
		(layer "In6.Cu")
		(net "M_E_CPU1_SA_DQS_DP<7>")
	)
	(segment
		(start 35.561524 -220.656404)
		(end 36.416488 -221.01048)
		(width 0.16002)
		(layer "In6.Cu")
		(net "M_E_CPU1_SA_DQS_DP<7>")
	)
	(segment
		(start 81.881218 -237.674404)
		(end 81.8896 -237.67923)
		(width 0.09525)
		(layer "In6.Cu")
		(net "M_E_CPU1_SA_DQS_DP<7>")
	)
	(segment
		(start 41.303448 -221.540578)
		(end 41.919144 -221.540578)
		(width 0.16002)
		(layer "In6.Cu")
		(net "M_E_CPU1_SA_DQS_DP<7>")
	)
	(segment
		(start 53.455824 -221.01048)
		(end 53.986176 -221.540832)
		(width 0.16002)
		(layer "In6.Cu")
		(net "M_E_CPU1_SA_DQS_DP<7>")
	)
	(segment
		(start 48.148494 -221.860364)
		(end 48.920654 -221.540578)
		(width 0.16002)
		(layer "In6.Cu")
		(net "M_E_CPU1_SA_DQS_DP<7>")
	)
	(segment
		(start 33.06064 -221.860364)
		(end 33.8328 -221.540578)
		(width 0.16002)
		(layer "In6.Cu")
		(net "M_E_CPU1_SA_DQS_DP<7>")
	)
	(segment
		(start 77.314044 -236.874304)
		(end 78.07198 -237.632494)
		(width 0.09525)
		(layer "In6.Cu")
		(net "M_E_CPU1_SA_DQS_DP<7>")
	)
	(segment
		(start 27.500072 -220.695774)
		(end 28.060142 -220.695774)
		(width 0.16002)
		(layer "In6.Cu")
		(net "M_E_CPU1_SA_DQS_DP<7>")
	)
	(arc
		(start 77.224636 -236.657896)
		(mid 77.247764 -236.77502)
		(end 77.314044 -236.874304)
		(width 0.09525)
		(layer "In6.Cu")
		(net "M_E_CPU1_SA_DQS_DP<7>")
	)
	(arc
		(start 79.0702 -237.67923)
		(mid 79.345489 -237.754951)
		(end 79.622396 -237.685326)
		(width 0.09525)
		(layer "In6.Cu")
		(net "M_E_CPU1_SA_DQS_DP<7>")
	)
	(arc
		(start 78.692756 -237.67923)
		(mid 78.874626 -237.628365)
		(end 79.058262 -237.672372)
		(width 0.09525)
		(layer "In6.Cu")
		(net "M_E_CPU1_SA_DQS_DP<7>")
	)
	(arc
		(start 80.949546 -237.67923)
		(mid 81.230978 -237.754985)
		(end 81.51241 -237.67923)
		(width 0.09525)
		(layer "In6.Cu")
		(net "M_E_CPU1_SA_DQS_DP<7>")
	)
	(arc
		(start 81.8896 -237.67923)
		(mid 82.123395 -237.753097)
		(end 82.366358 -237.720124)
		(width 0.09525)
		(layer "In6.Cu")
		(net "M_E_CPU1_SA_DQS_DP<7>")
	)
	(arc
		(start 82.366358 -237.720124)
		(mid 82.376301 -237.716281)
		(end 82.38617 -237.71225)
		(width 0.09525)
		(layer "In6.Cu")
		(net "M_E_CPU1_SA_DQS_DP<7>")
	)
	(arc
		(start 80.57261 -237.67923)
		(mid 80.761078 -237.628553)
		(end 80.949546 -237.67923)
		(width 0.09525)
		(layer "In6.Cu")
		(net "M_E_CPU1_SA_DQS_DP<7>")
	)
	(arc
		(start 78.225142 -237.72749)
		(mid 78.464141 -237.753683)
		(end 78.692756 -237.67923)
		(width 0.09525)
		(layer "In6.Cu")
		(net "M_E_CPU1_SA_DQS_DP<7>")
	)
	(arc
		(start 80.009746 -237.67923)
		(mid 80.291178 -237.754985)
		(end 80.57261 -237.67923)
		(width 0.09525)
		(layer "In6.Cu")
		(net "M_E_CPU1_SA_DQS_DP<7>")
	)
	(arc
		(start 81.51241 -237.67923)
		(mid 81.696185 -237.628458)
		(end 81.881218 -237.674404)
		(width 0.09525)
		(layer "In6.Cu")
		(net "M_E_CPU1_SA_DQS_DP<7>")
	)
	(arc
		(start 79.644748 -237.672372)
		(mid 79.828129 -237.628541)
		(end 80.009746 -237.67923)
		(width 0.09525)
		(layer "In6.Cu")
		(net "M_E_CPU1_SA_DQS_DP<7>")
	)
	(arc
		(start 78.07198 -237.632494)
		(mid 78.143027 -237.688911)
		(end 78.225142 -237.72749)
		(width 0.09525)
		(layer "In6.Cu")
		(net "M_E_CPU1_SA_DQS_DP<7>")
	)
	(segment
		(start 83.107784 -233.410252)
		(end 82.640932 -233.144314)
		(width 0.12954)
		(layer "F.Cu")
		(net "M_E_CPU1_SA_DQS_DP<6>")
	)
	(segment
		(start 50.655728 -211.29117)
		(end 51.025044 -211.660486)
		(width 0.16002)
		(layer "In6.Cu")
		(net "M_E_CPU1_SA_DQS_DP<6>")
	)
	(segment
		(start 42.796968 -211.29117)
		(end 43.111674 -211.29117)
		(width 0.16002)
		(layer "In6.Cu")
		(net "M_E_CPU1_SA_DQS_DP<6>")
	)
	(segment
		(start 79.0702 -232.818432)
		(end 79.0702 -232.819194)
		(width 0.09525)
		(layer "In6.Cu")
		(net "M_E_CPU1_SA_DQS_DP<6>")
	)
	(segment
		(start 28.066492 -211.33054)
		(end 28.412948 -211.676996)
		(width 0.16002)
		(layer "In6.Cu")
		(net "M_E_CPU1_SA_DQS_DP<6>")
	)
	(segment
		(start 40.56126 -212.51037)
		(end 41.37025 -212.175344)
		(width 0.16002)
		(layer "In6.Cu")
		(net "M_E_CPU1_SA_DQS_DP<6>")
	)
	(segment
		(start 53.477414 -211.660486)
		(end 53.992526 -212.175598)
		(width 0.16002)
		(layer "In6.Cu")
		(net "M_E_CPU1_SA_DQS_DP<6>")
	)
	(segment
		(start 27.00655 -211.511388)
		(end 27.443176 -211.33054)
		(width 0.16002)
		(layer "In6.Cu")
		(net "M_E_CPU1_SA_DQS_DP<6>")
	)
	(segment
		(start 43.48099 -211.660486)
		(end 45.933614 -211.660486)
		(width 0.16002)
		(layer "In6.Cu")
		(net "M_E_CPU1_SA_DQS_DP<6>")
	)
	(segment
		(start 51.025044 -211.660486)
		(end 53.477414 -211.660486)
		(width 0.16002)
		(layer "In6.Cu")
		(net "M_E_CPU1_SA_DQS_DP<6>")
	)
	(segment
		(start 59.902344 -212.452966)
		(end 62.150244 -214.700866)
		(width 0.16002)
		(layer "In6.Cu")
		(net "M_E_CPU1_SA_DQS_DP<6>")
	)
	(segment
		(start 75.686666 -230.184198)
		(end 75.862434 -230.359966)
		(width 0.09525)
		(layer "In6.Cu")
		(net "M_E_CPU1_SA_DQS_DP<6>")
	)
	(segment
		(start 41.912794 -212.175344)
		(end 42.796968 -211.29117)
		(width 0.16002)
		(layer "In6.Cu")
		(net "M_E_CPU1_SA_DQS_DP<6>")
	)
	(segment
		(start 31.636462 -212.51037)
		(end 33.017714 -212.51037)
		(width 0.16002)
		(layer "In6.Cu")
		(net "M_E_CPU1_SA_DQS_DP<6>")
	)
	(segment
		(start 48.105314 -212.51037)
		(end 48.914304 -212.175344)
		(width 0.16002)
		(layer "In6.Cu")
		(net "M_E_CPU1_SA_DQS_DP<6>")
	)
	(segment
		(start 77.056996 -231.209596)
		(end 77.37856 -231.53116)
		(width 0.09525)
		(layer "In6.Cu")
		(net "M_E_CPU1_SA_DQS_DP<6>")
	)
	(segment
		(start 58.856372 -212.452966)
		(end 59.902344 -212.452966)
		(width 0.16002)
		(layer "In6.Cu")
		(net "M_E_CPU1_SA_DQS_DP<6>")
	)
	(segment
		(start 35.93719 -211.660486)
		(end 38.297358 -211.660486)
		(width 0.16002)
		(layer "In6.Cu")
		(net "M_E_CPU1_SA_DQS_DP<6>")
	)
	(segment
		(start 34.752788 -211.79155)
		(end 35.253168 -211.29117)
		(width 0.16002)
		(layer "In6.Cu")
		(net "M_E_CPU1_SA_DQS_DP<6>")
	)
	(segment
		(start 28.412948 -211.676996)
		(end 30.803088 -211.676996)
		(width 0.16002)
		(layer "In6.Cu")
		(net "M_E_CPU1_SA_DQS_DP<6>")
	)
	(segment
		(start 62.150244 -214.700866)
		(end 64.520826 -214.700866)
		(width 0.16002)
		(layer "In6.Cu")
		(net "M_E_CPU1_SA_DQS_DP<6>")
	)
	(segment
		(start 77.37856 -232.08488)
		(end 78.025498 -232.731818)
		(width 0.09525)
		(layer "In6.Cu")
		(net "M_E_CPU1_SA_DQS_DP<6>")
	)
	(segment
		(start 49.456848 -212.175344)
		(end 50.341022 -211.29117)
		(width 0.16002)
		(layer "In6.Cu")
		(net "M_E_CPU1_SA_DQS_DP<6>")
	)
	(segment
		(start 57.730644 -212.750146)
		(end 58.559192 -212.750146)
		(width 0.16002)
		(layer "In6.Cu")
		(net "M_E_CPU1_SA_DQS_DP<6>")
	)
	(segment
		(start 25.152096 -211.7852)
		(end 25.425908 -211.511388)
		(width 0.16002)
		(layer "In6.Cu")
		(net "M_E_CPU1_SA_DQS_DP<6>")
	)
	(segment
		(start 50.341022 -211.29117)
		(end 50.655728 -211.29117)
		(width 0.16002)
		(layer "In6.Cu")
		(net "M_E_CPU1_SA_DQS_DP<6>")
	)
	(segment
		(start 68.04279 -221.81566)
		(end 70.25005 -224.02292)
		(width 0.16002)
		(layer "In6.Cu")
		(net "M_E_CPU1_SA_DQS_DP<6>")
	)
	(segment
		(start 75.548236 -230.167434)
		(end 75.565 -230.184198)
		(width 0.09525)
		(layer "In6.Cu")
		(net "M_E_CPU1_SA_DQS_DP<6>")
	)
	(segment
		(start 79.061818 -232.813606)
		(end 79.0702 -232.818432)
		(width 0.09525)
		(layer "In6.Cu")
		(net "M_E_CPU1_SA_DQS_DP<6>")
	)
	(segment
		(start 75.862434 -230.359966)
		(end 76.006706 -230.359966)
		(width 0.09525)
		(layer "In6.Cu")
		(net "M_E_CPU1_SA_DQS_DP<6>")
	)
	(segment
		(start 25.425908 -211.511388)
		(end 27.00655 -211.511388)
		(width 0.16002)
		(layer "In6.Cu")
		(net "M_E_CPU1_SA_DQS_DP<6>")
	)
	(segment
		(start 39.147242 -212.51037)
		(end 40.56126 -212.51037)
		(width 0.16002)
		(layer "In6.Cu")
		(net "M_E_CPU1_SA_DQS_DP<6>")
	)
	(segment
		(start 45.933614 -211.660486)
		(end 46.783498 -212.51037)
		(width 0.16002)
		(layer "In6.Cu")
		(net "M_E_CPU1_SA_DQS_DP<6>")
	)
	(segment
		(start 48.914304 -212.175344)
		(end 49.456848 -212.175344)
		(width 0.16002)
		(layer "In6.Cu")
		(net "M_E_CPU1_SA_DQS_DP<6>")
	)
	(segment
		(start 75.565 -230.184198)
		(end 75.686666 -230.184198)
		(width 0.09525)
		(layer "In6.Cu")
		(net "M_E_CPU1_SA_DQS_DP<6>")
	)
	(segment
		(start 76.006706 -230.359966)
		(end 76.856336 -231.209596)
		(width 0.09525)
		(layer "In6.Cu")
		(net "M_E_CPU1_SA_DQS_DP<6>")
	)
	(segment
		(start 77.37856 -231.53116)
		(end 77.37856 -232.08488)
		(width 0.09525)
		(layer "In6.Cu")
		(net "M_E_CPU1_SA_DQS_DP<6>")
	)
	(segment
		(start 70.25005 -224.869248)
		(end 75.548236 -230.167434)
		(width 0.16002)
		(layer "In6.Cu")
		(net "M_E_CPU1_SA_DQS_DP<6>")
	)
	(segment
		(start 68.04279 -218.22283)
		(end 68.04279 -221.81566)
		(width 0.16002)
		(layer "In6.Cu")
		(net "M_E_CPU1_SA_DQS_DP<6>")
	)
	(segment
		(start 76.856336 -231.209596)
		(end 77.056996 -231.209596)
		(width 0.09525)
		(layer "In6.Cu")
		(net "M_E_CPU1_SA_DQS_DP<6>")
	)
	(segment
		(start 64.520826 -214.700866)
		(end 68.04279 -218.22283)
		(width 0.16002)
		(layer "In6.Cu")
		(net "M_E_CPU1_SA_DQS_DP<6>")
	)
	(segment
		(start 70.25005 -224.02292)
		(end 70.25005 -224.869248)
		(width 0.16002)
		(layer "In6.Cu")
		(net "M_E_CPU1_SA_DQS_DP<6>")
	)
	(segment
		(start 38.297358 -211.660486)
		(end 39.147242 -212.51037)
		(width 0.16002)
		(layer "In6.Cu")
		(net "M_E_CPU1_SA_DQS_DP<6>")
	)
	(segment
		(start 79.622396 -232.82529)
		(end 79.63281 -232.819194)
		(width 0.09525)
		(layer "In6.Cu")
		(net "M_E_CPU1_SA_DQS_DP<6>")
	)
	(segment
		(start 43.111674 -211.29117)
		(end 43.48099 -211.660486)
		(width 0.16002)
		(layer "In6.Cu")
		(net "M_E_CPU1_SA_DQS_DP<6>")
	)
	(segment
		(start 58.559192 -212.750146)
		(end 58.856372 -212.452966)
		(width 0.16002)
		(layer "In6.Cu")
		(net "M_E_CPU1_SA_DQS_DP<6>")
	)
	(segment
		(start 79.63281 -232.819194)
		(end 79.644748 -232.812336)
		(width 0.09525)
		(layer "In6.Cu")
		(net "M_E_CPU1_SA_DQS_DP<6>")
	)
	(segment
		(start 82.487008 -232.878884)
		(end 82.640932 -233.144314)
		(width 0.09525)
		(layer "In6.Cu")
		(net "M_E_CPU1_SA_DQS_DP<6>")
	)
	(segment
		(start 81.881218 -232.814368)
		(end 81.8896 -232.819194)
		(width 0.09525)
		(layer "In6.Cu")
		(net "M_E_CPU1_SA_DQS_DP<6>")
	)
	(segment
		(start 82.38617 -232.852214)
		(end 82.487008 -232.878884)
		(width 0.09525)
		(layer "In6.Cu")
		(net "M_E_CPU1_SA_DQS_DP<6>")
	)
	(segment
		(start 35.253168 -211.29117)
		(end 35.567874 -211.29117)
		(width 0.16002)
		(layer "In6.Cu")
		(net "M_E_CPU1_SA_DQS_DP<6>")
	)
	(segment
		(start 33.017714 -212.51037)
		(end 34.752788 -211.79155)
		(width 0.16002)
		(layer "In6.Cu")
		(net "M_E_CPU1_SA_DQS_DP<6>")
	)
	(segment
		(start 35.567874 -211.29117)
		(end 35.93719 -211.660486)
		(width 0.16002)
		(layer "In6.Cu")
		(net "M_E_CPU1_SA_DQS_DP<6>")
	)
	(segment
		(start 41.37025 -212.175344)
		(end 41.912794 -212.175344)
		(width 0.16002)
		(layer "In6.Cu")
		(net "M_E_CPU1_SA_DQS_DP<6>")
	)
	(segment
		(start 53.992526 -212.175598)
		(end 57.156096 -212.175598)
		(width 0.16002)
		(layer "In6.Cu")
		(net "M_E_CPU1_SA_DQS_DP<6>")
	)
	(segment
		(start 30.803088 -211.676996)
		(end 31.636462 -212.51037)
		(width 0.16002)
		(layer "In6.Cu")
		(net "M_E_CPU1_SA_DQS_DP<6>")
	)
	(segment
		(start 46.783498 -212.51037)
		(end 48.105314 -212.51037)
		(width 0.16002)
		(layer "In6.Cu")
		(net "M_E_CPU1_SA_DQS_DP<6>")
	)
	(segment
		(start 57.156096 -212.175598)
		(end 57.730644 -212.750146)
		(width 0.16002)
		(layer "In6.Cu")
		(net "M_E_CPU1_SA_DQS_DP<6>")
	)
	(segment
		(start 27.443176 -211.33054)
		(end 28.066492 -211.33054)
		(width 0.16002)
		(layer "In6.Cu")
		(net "M_E_CPU1_SA_DQS_DP<6>")
	)
	(arc
		(start 79.644748 -232.812336)
		(mid 79.828129 -232.768505)
		(end 80.009746 -232.819194)
		(width 0.09525)
		(layer "In6.Cu")
		(net "M_E_CPU1_SA_DQS_DP<6>")
	)
	(arc
		(start 80.009746 -232.819194)
		(mid 80.291178 -232.894949)
		(end 80.57261 -232.819194)
		(width 0.09525)
		(layer "In6.Cu")
		(net "M_E_CPU1_SA_DQS_DP<6>")
	)
	(arc
		(start 80.57261 -232.819194)
		(mid 80.761078 -232.768517)
		(end 80.949546 -232.819194)
		(width 0.09525)
		(layer "In6.Cu")
		(net "M_E_CPU1_SA_DQS_DP<6>")
	)
	(arc
		(start 80.949546 -232.819194)
		(mid 81.230978 -232.894949)
		(end 81.51241 -232.819194)
		(width 0.09525)
		(layer "In6.Cu")
		(net "M_E_CPU1_SA_DQS_DP<6>")
	)
	(arc
		(start 78.692502 -232.81894)
		(mid 78.876472 -232.767828)
		(end 79.061818 -232.813606)
		(width 0.09525)
		(layer "In6.Cu")
		(net "M_E_CPU1_SA_DQS_DP<6>")
	)
	(arc
		(start 78.025498 -232.731818)
		(mid 78.344185 -232.888847)
		(end 78.692502 -232.81894)
		(width 0.09525)
		(layer "In6.Cu")
		(net "M_E_CPU1_SA_DQS_DP<6>")
	)
	(arc
		(start 79.0702 -232.819194)
		(mid 79.345489 -232.894915)
		(end 79.622396 -232.82529)
		(width 0.09525)
		(layer "In6.Cu")
		(net "M_E_CPU1_SA_DQS_DP<6>")
	)
	(arc
		(start 81.8896 -232.819194)
		(mid 82.123395 -232.893061)
		(end 82.366358 -232.860088)
		(width 0.09525)
		(layer "In6.Cu")
		(net "M_E_CPU1_SA_DQS_DP<6>")
	)
	(arc
		(start 81.51241 -232.819194)
		(mid 81.696185 -232.768422)
		(end 81.881218 -232.814368)
		(width 0.09525)
		(layer "In6.Cu")
		(net "M_E_CPU1_SA_DQS_DP<6>")
	)
	(arc
		(start 82.366358 -232.860088)
		(mid 82.376301 -232.856245)
		(end 82.38617 -232.852214)
		(width 0.09525)
		(layer "In6.Cu")
		(net "M_E_CPU1_SA_DQS_DP<6>")
	)
	(segment
		(start 83.107784 -228.55047)
		(end 82.640932 -228.284532)
		(width 0.12954)
		(layer "F.Cu")
		(net "M_E_CPU1_SA_DQS_DP<5>")
	)
	(segment
		(start 58.199782 -201.94143)
		(end 58.919618 -202.661266)
		(width 0.16002)
		(layer "In6.Cu")
		(net "M_E_CPU1_SA_DQS_DP<5>")
	)
	(segment
		(start 73.87209 -215.574626)
		(end 73.87209 -219.793312)
		(width 0.16002)
		(layer "In6.Cu")
		(net "M_E_CPU1_SA_DQS_DP<5>")
	)
	(segment
		(start 33.891474 -202.82535)
		(end 34.368994 -202.82535)
		(width 0.16002)
		(layer "In6.Cu")
		(net "M_E_CPU1_SA_DQS_DP<5>")
	)
	(segment
		(start 41.100248 -203.160376)
		(end 41.481248 -202.779376)
		(width 0.16002)
		(layer "In6.Cu")
		(net "M_E_CPU1_SA_DQS_DP<5>")
	)
	(segment
		(start 49.840642 -202.441556)
		(end 50.341022 -201.941176)
		(width 0.16002)
		(layer "In6.Cu")
		(net "M_E_CPU1_SA_DQS_DP<5>")
	)
	(segment
		(start 66.14541 -207.847946)
		(end 73.87209 -215.574626)
		(width 0.16002)
		(layer "In6.Cu")
		(net "M_E_CPU1_SA_DQS_DP<5>")
	)
	(segment
		(start 33.556448 -203.160376)
		(end 33.891474 -202.82535)
		(width 0.16002)
		(layer "In6.Cu")
		(net "M_E_CPU1_SA_DQS_DP<5>")
	)
	(segment
		(start 77.378814 -223.216216)
		(end 77.378814 -223.424496)
		(width 0.09525)
		(layer "In6.Cu")
		(net "M_E_CPU1_SA_DQS_DP<5>")
	)
	(segment
		(start 35.567874 -201.941176)
		(end 35.93719 -202.310492)
		(width 0.16002)
		(layer "In6.Cu")
		(net "M_E_CPU1_SA_DQS_DP<5>")
	)
	(segment
		(start 56.569356 -202.77963)
		(end 57.384696 -202.44181)
		(width 0.16002)
		(layer "In6.Cu")
		(net "M_E_CPU1_SA_DQS_DP<5>")
	)
	(segment
		(start 41.481248 -202.779376)
		(end 42.296588 -202.441556)
		(width 0.16002)
		(layer "In6.Cu")
		(net "M_E_CPU1_SA_DQS_DP<5>")
	)
	(segment
		(start 38.297358 -202.310492)
		(end 39.147242 -203.160376)
		(width 0.16002)
		(layer "In6.Cu")
		(net "M_E_CPU1_SA_DQS_DP<5>")
	)
	(segment
		(start 35.93719 -202.310492)
		(end 38.297358 -202.310492)
		(width 0.16002)
		(layer "In6.Cu")
		(net "M_E_CPU1_SA_DQS_DP<5>")
	)
	(segment
		(start 34.368994 -202.82535)
		(end 35.253168 -201.941176)
		(width 0.16002)
		(layer "In6.Cu")
		(net "M_E_CPU1_SA_DQS_DP<5>")
	)
	(segment
		(start 43.48099 -202.310492)
		(end 45.933614 -202.310492)
		(width 0.16002)
		(layer "In6.Cu")
		(net "M_E_CPU1_SA_DQS_DP<5>")
	)
	(segment
		(start 39.147242 -203.160376)
		(end 41.100248 -203.160376)
		(width 0.16002)
		(layer "In6.Cu")
		(net "M_E_CPU1_SA_DQS_DP<5>")
	)
	(segment
		(start 27.077416 -201.980546)
		(end 28.066492 -201.980546)
		(width 0.16002)
		(layer "In6.Cu")
		(net "M_E_CPU1_SA_DQS_DP<5>")
	)
	(segment
		(start 49.025302 -202.779376)
		(end 49.840642 -202.441556)
		(width 0.16002)
		(layer "In6.Cu")
		(net "M_E_CPU1_SA_DQS_DP<5>")
	)
	(segment
		(start 25.425908 -202.161394)
		(end 26.64079 -202.161394)
		(width 0.16002)
		(layer "In6.Cu")
		(net "M_E_CPU1_SA_DQS_DP<5>")
	)
	(segment
		(start 46.783498 -203.160376)
		(end 48.644302 -203.160376)
		(width 0.16002)
		(layer "In6.Cu")
		(net "M_E_CPU1_SA_DQS_DP<5>")
	)
	(segment
		(start 42.796968 -201.941176)
		(end 43.111674 -201.941176)
		(width 0.16002)
		(layer "In6.Cu")
		(net "M_E_CPU1_SA_DQS_DP<5>")
	)
	(segment
		(start 51.025044 -202.310492)
		(end 53.477414 -202.310492)
		(width 0.16002)
		(layer "In6.Cu")
		(net "M_E_CPU1_SA_DQS_DP<5>")
	)
	(segment
		(start 76.969874 -222.891096)
		(end 77.053694 -222.891096)
		(width 0.09525)
		(layer "In6.Cu")
		(net "M_E_CPU1_SA_DQS_DP<5>")
	)
	(segment
		(start 50.341022 -201.941176)
		(end 50.655728 -201.941176)
		(width 0.16002)
		(layer "In6.Cu")
		(net "M_E_CPU1_SA_DQS_DP<5>")
	)
	(segment
		(start 43.111674 -201.941176)
		(end 43.48099 -202.310492)
		(width 0.16002)
		(layer "In6.Cu")
		(net "M_E_CPU1_SA_DQS_DP<5>")
	)
	(segment
		(start 26.64079 -202.161394)
		(end 27.077416 -201.980546)
		(width 0.16002)
		(layer "In6.Cu")
		(net "M_E_CPU1_SA_DQS_DP<5>")
	)
	(segment
		(start 77.848714 -224.234502)
		(end 77.848714 -225.775012)
		(width 0.09525)
		(layer "In6.Cu")
		(net "M_E_CPU1_SA_DQS_DP<5>")
	)
	(segment
		(start 50.655728 -201.941176)
		(end 51.025044 -202.310492)
		(width 0.16002)
		(layer "In6.Cu")
		(net "M_E_CPU1_SA_DQS_DP<5>")
	)
	(segment
		(start 60.314078 -202.661266)
		(end 65.500758 -207.847946)
		(width 0.16002)
		(layer "In6.Cu")
		(net "M_E_CPU1_SA_DQS_DP<5>")
	)
	(segment
		(start 28.412948 -202.327002)
		(end 30.803088 -202.327002)
		(width 0.16002)
		(layer "In6.Cu")
		(net "M_E_CPU1_SA_DQS_DP<5>")
	)
	(segment
		(start 76.95311 -222.874332)
		(end 76.969874 -222.891096)
		(width 0.09525)
		(layer "In6.Cu")
		(net "M_E_CPU1_SA_DQS_DP<5>")
	)
	(segment
		(start 79.627476 -227.908104)
		(end 79.821024 -227.908104)
		(width 0.09525)
		(layer "In6.Cu")
		(net "M_E_CPU1_SA_DQS_DP<5>")
	)
	(segment
		(start 57.885076 -201.94143)
		(end 58.199782 -201.94143)
		(width 0.16002)
		(layer "In6.Cu")
		(net "M_E_CPU1_SA_DQS_DP<5>")
	)
	(segment
		(start 42.296588 -202.441556)
		(end 42.796968 -201.941176)
		(width 0.16002)
		(layer "In6.Cu")
		(net "M_E_CPU1_SA_DQS_DP<5>")
	)
	(segment
		(start 77.659738 -223.909382)
		(end 77.691234 -223.92767)
		(width 0.09525)
		(layer "In6.Cu")
		(net "M_E_CPU1_SA_DQS_DP<5>")
	)
	(segment
		(start 65.500758 -207.847946)
		(end 66.14541 -207.847946)
		(width 0.16002)
		(layer "In6.Cu")
		(net "M_E_CPU1_SA_DQS_DP<5>")
	)
	(segment
		(start 77.621638 -223.887284)
		(end 77.659738 -223.909382)
		(width 0.09525)
		(layer "In6.Cu")
		(net "M_E_CPU1_SA_DQS_DP<5>")
	)
	(segment
		(start 73.87209 -219.793312)
		(end 76.95311 -222.874332)
		(width 0.16002)
		(layer "In6.Cu")
		(net "M_E_CPU1_SA_DQS_DP<5>")
	)
	(segment
		(start 58.919618 -202.661266)
		(end 60.314078 -202.661266)
		(width 0.16002)
		(layer "In6.Cu")
		(net "M_E_CPU1_SA_DQS_DP<5>")
	)
	(segment
		(start 48.644302 -203.160376)
		(end 49.025302 -202.779376)
		(width 0.16002)
		(layer "In6.Cu")
		(net "M_E_CPU1_SA_DQS_DP<5>")
	)
	(segment
		(start 28.066492 -201.980546)
		(end 28.412948 -202.327002)
		(width 0.16002)
		(layer "In6.Cu")
		(net "M_E_CPU1_SA_DQS_DP<5>")
	)
	(segment
		(start 57.384696 -202.44181)
		(end 57.885076 -201.94143)
		(width 0.16002)
		(layer "In6.Cu")
		(net "M_E_CPU1_SA_DQS_DP<5>")
	)
	(segment
		(start 78.81112 -227.358956)
		(end 79.171292 -227.719128)
		(width 0.09525)
		(layer "In6.Cu")
		(net "M_E_CPU1_SA_DQS_DP<5>")
	)
	(segment
		(start 77.053694 -222.891096)
		(end 77.378814 -223.216216)
		(width 0.09525)
		(layer "In6.Cu")
		(net "M_E_CPU1_SA_DQS_DP<5>")
	)
	(segment
		(start 56.21909 -203.129896)
		(end 56.569356 -202.77963)
		(width 0.16002)
		(layer "In6.Cu")
		(net "M_E_CPU1_SA_DQS_DP<5>")
	)
	(segment
		(start 53.477414 -202.310492)
		(end 54.296818 -203.129896)
		(width 0.16002)
		(layer "In6.Cu")
		(net "M_E_CPU1_SA_DQS_DP<5>")
	)
	(segment
		(start 78.81112 -227.358702)
		(end 78.81112 -227.358956)
		(width 0.09525)
		(layer "In6.Cu")
		(net "M_E_CPU1_SA_DQS_DP<5>")
	)
	(segment
		(start 35.253168 -201.941176)
		(end 35.567874 -201.941176)
		(width 0.16002)
		(layer "In6.Cu")
		(net "M_E_CPU1_SA_DQS_DP<5>")
	)
	(segment
		(start 54.296818 -203.129896)
		(end 56.21909 -203.129896)
		(width 0.16002)
		(layer "In6.Cu")
		(net "M_E_CPU1_SA_DQS_DP<5>")
	)
	(segment
		(start 82.38617 -227.992432)
		(end 82.487008 -228.019102)
		(width 0.09525)
		(layer "In6.Cu")
		(net "M_E_CPU1_SA_DQS_DP<5>")
	)
	(segment
		(start 45.933614 -202.310492)
		(end 46.783498 -203.160376)
		(width 0.16002)
		(layer "In6.Cu")
		(net "M_E_CPU1_SA_DQS_DP<5>")
	)
	(segment
		(start 31.636462 -203.160376)
		(end 33.556448 -203.160376)
		(width 0.16002)
		(layer "In6.Cu")
		(net "M_E_CPU1_SA_DQS_DP<5>")
	)
	(segment
		(start 82.487008 -228.019102)
		(end 82.640932 -228.284532)
		(width 0.09525)
		(layer "In6.Cu")
		(net "M_E_CPU1_SA_DQS_DP<5>")
	)
	(segment
		(start 81.881218 -227.954586)
		(end 81.8896 -227.959412)
		(width 0.09525)
		(layer "In6.Cu")
		(net "M_E_CPU1_SA_DQS_DP<5>")
	)
	(segment
		(start 25.152096 -202.435206)
		(end 25.425908 -202.161394)
		(width 0.16002)
		(layer "In6.Cu")
		(net "M_E_CPU1_SA_DQS_DP<5>")
	)
	(segment
		(start 30.803088 -202.327002)
		(end 31.636462 -203.160376)
		(width 0.16002)
		(layer "In6.Cu")
		(net "M_E_CPU1_SA_DQS_DP<5>")
	)
	(arc
		(start 78.11135 -226.321112)
		(mid 78.222731 -226.439952)
		(end 78.295246 -226.58578)
		(width 0.09525)
		(layer "In6.Cu")
		(net "M_E_CPU1_SA_DQS_DP<5>")
	)
	(arc
		(start 80.949546 -227.959412)
		(mid 81.230978 -228.035167)
		(end 81.51241 -227.959412)
		(width 0.09525)
		(layer "In6.Cu")
		(net "M_E_CPU1_SA_DQS_DP<5>")
	)
	(arc
		(start 79.821024 -227.908104)
		(mid 79.91877 -227.921299)
		(end 80.009746 -227.959412)
		(width 0.09525)
		(layer "In6.Cu")
		(net "M_E_CPU1_SA_DQS_DP<5>")
	)
	(arc
		(start 78.295246 -226.58578)
		(mid 78.375488 -226.722628)
		(end 78.50505 -226.814126)
		(width 0.09525)
		(layer "In6.Cu")
		(net "M_E_CPU1_SA_DQS_DP<5>")
	)
	(arc
		(start 81.8896 -227.959412)
		(mid 82.123395 -228.033279)
		(end 82.366358 -228.000306)
		(width 0.09525)
		(layer "In6.Cu")
		(net "M_E_CPU1_SA_DQS_DP<5>")
	)
	(arc
		(start 79.171292 -227.719128)
		(mid 79.380591 -227.858977)
		(end 79.627476 -227.908104)
		(width 0.09525)
		(layer "In6.Cu")
		(net "M_E_CPU1_SA_DQS_DP<5>")
	)
	(arc
		(start 77.378814 -223.424496)
		(mid 77.443211 -223.685802)
		(end 77.621638 -223.887284)
		(width 0.09525)
		(layer "In6.Cu")
		(net "M_E_CPU1_SA_DQS_DP<5>")
	)
	(arc
		(start 81.51241 -227.959412)
		(mid 81.696185 -227.90864)
		(end 81.881218 -227.954586)
		(width 0.09525)
		(layer "In6.Cu")
		(net "M_E_CPU1_SA_DQS_DP<5>")
	)
	(arc
		(start 78.50505 -226.814126)
		(mid 78.591277 -226.88198)
		(end 78.631542 -226.984052)
		(width 0.09525)
		(layer "In6.Cu")
		(net "M_E_CPU1_SA_DQS_DP<5>")
	)
	(arc
		(start 77.691234 -223.92767)
		(mid 77.807032 -224.062064)
		(end 77.848714 -224.234502)
		(width 0.09525)
		(layer "In6.Cu")
		(net "M_E_CPU1_SA_DQS_DP<5>")
	)
	(arc
		(start 77.848714 -225.775012)
		(mid 77.917665 -226.078067)
		(end 78.11135 -226.321112)
		(width 0.09525)
		(layer "In6.Cu")
		(net "M_E_CPU1_SA_DQS_DP<5>")
	)
	(arc
		(start 80.009746 -227.959412)
		(mid 80.291178 -228.035167)
		(end 80.57261 -227.959412)
		(width 0.09525)
		(layer "In6.Cu")
		(net "M_E_CPU1_SA_DQS_DP<5>")
	)
	(arc
		(start 78.631542 -226.984052)
		(mid 78.689398 -227.186681)
		(end 78.81112 -227.358702)
		(width 0.09525)
		(layer "In6.Cu")
		(net "M_E_CPU1_SA_DQS_DP<5>")
	)
	(arc
		(start 82.366358 -228.000306)
		(mid 82.376301 -227.996463)
		(end 82.38617 -227.992432)
		(width 0.09525)
		(layer "In6.Cu")
		(net "M_E_CPU1_SA_DQS_DP<5>")
	)
	(arc
		(start 80.57261 -227.959412)
		(mid 80.761078 -227.908735)
		(end 80.949546 -227.959412)
		(width 0.09525)
		(layer "In6.Cu")
		(net "M_E_CPU1_SA_DQS_DP<5>")
	)
	(segment
		(start 81.22793 -246.370348)
		(end 80.761078 -246.10441)
		(width 0.12954)
		(layer "F.Cu")
		(net "M_E_CPU1_SA_DQS_DP<4>")
	)
	(segment
		(start 33.900364 -238.589566)
		(end 34.286952 -238.589566)
		(width 0.16002)
		(layer "In6.Cu")
		(net "M_E_CPU1_SA_DQS_DP<4>")
	)
	(segment
		(start 63.561722 -243.714016)
		(end 63.561722 -243.940076)
		(width 0.16002)
		(layer "In6.Cu")
		(net "M_E_CPU1_SA_DQS_DP<4>")
	)
	(segment
		(start 41.114726 -238.260128)
		(end 41.444164 -238.589566)
		(width 0.16002)
		(layer "In6.Cu")
		(net "M_E_CPU1_SA_DQS_DP<4>")
	)
	(segment
		(start 62.433454 -242.059968)
		(end 62.170564 -242.322858)
		(width 0.16002)
		(layer "In6.Cu")
		(net "M_E_CPU1_SA_DQS_DP<4>")
	)
	(segment
		(start 50.233834 -237.758986)
		(end 50.65014 -237.758986)
		(width 0.16002)
		(layer "In6.Cu")
		(net "M_E_CPU1_SA_DQS_DP<4>")
	)
	(segment
		(start 42.68978 -237.758986)
		(end 43.106086 -237.758986)
		(width 0.16002)
		(layer "In6.Cu")
		(net "M_E_CPU1_SA_DQS_DP<4>")
	)
	(segment
		(start 62.915546 -242.54206)
		(end 63.39205 -242.54206)
		(width 0.16002)
		(layer "In6.Cu")
		(net "M_E_CPU1_SA_DQS_DP<4>")
	)
	(segment
		(start 50.998882 -237.410244)
		(end 52.781962 -237.410244)
		(width 0.16002)
		(layer "In6.Cu")
		(net "M_E_CPU1_SA_DQS_DP<4>")
	)
	(segment
		(start 63.824612 -243.451126)
		(end 63.561722 -243.714016)
		(width 0.16002)
		(layer "In6.Cu")
		(net "M_E_CPU1_SA_DQS_DP<4>")
	)
	(segment
		(start 76.474828 -246.567706)
		(end 76.649326 -246.742204)
		(width 0.09525)
		(layer "In6.Cu")
		(net "M_E_CPU1_SA_DQS_DP<4>")
	)
	(segment
		(start 56.947308 -238.589566)
		(end 57.777888 -237.758986)
		(width 0.16002)
		(layer "In6.Cu")
		(net "M_E_CPU1_SA_DQS_DP<4>")
	)
	(segment
		(start 62.170564 -242.322858)
		(end 62.170564 -242.548918)
		(width 0.16002)
		(layer "In6.Cu")
		(net "M_E_CPU1_SA_DQS_DP<4>")
	)
	(segment
		(start 35.562286 -237.758986)
		(end 35.911028 -237.410244)
		(width 0.16002)
		(layer "In6.Cu")
		(net "M_E_CPU1_SA_DQS_DP<4>")
	)
	(segment
		(start 65.21577 -244.36578)
		(end 65.21577 -244.842284)
		(width 0.16002)
		(layer "In6.Cu")
		(net "M_E_CPU1_SA_DQS_DP<4>")
	)
	(segment
		(start 30.85338 -238.409226)
		(end 31.528766 -238.409226)
		(width 0.16002)
		(layer "In6.Cu")
		(net "M_E_CPU1_SA_DQS_DP<4>")
	)
	(segment
		(start 30.25648 -238.292386)
		(end 30.73654 -238.292386)
		(width 0.16002)
		(layer "In6.Cu")
		(net "M_E_CPU1_SA_DQS_DP<4>")
	)
	(segment
		(start 76.649326 -246.742204)
		(end 76.979526 -246.742204)
		(width 0.09525)
		(layer "In6.Cu")
		(net "M_E_CPU1_SA_DQS_DP<4>")
	)
	(segment
		(start 66.174366 -245.324376)
		(end 66.853816 -246.003826)
		(width 0.16002)
		(layer "In6.Cu")
		(net "M_E_CPU1_SA_DQS_DP<4>")
	)
	(segment
		(start 31.677864 -238.260128)
		(end 33.570926 -238.260128)
		(width 0.16002)
		(layer "In6.Cu")
		(net "M_E_CPU1_SA_DQS_DP<4>")
	)
	(segment
		(start 64.306704 -243.933218)
		(end 64.783208 -243.933218)
		(width 0.16002)
		(layer "In6.Cu")
		(net "M_E_CPU1_SA_DQS_DP<4>")
	)
	(segment
		(start 65.21577 -244.842284)
		(end 64.95288 -245.105174)
		(width 0.16002)
		(layer "In6.Cu")
		(net "M_E_CPU1_SA_DQS_DP<4>")
	)
	(segment
		(start 50.65014 -237.758986)
		(end 50.998882 -237.410244)
		(width 0.16002)
		(layer "In6.Cu")
		(net "M_E_CPU1_SA_DQS_DP<4>")
	)
	(segment
		(start 62.652656 -242.80495)
		(end 62.915546 -242.54206)
		(width 0.16002)
		(layer "In6.Cu")
		(net "M_E_CPU1_SA_DQS_DP<4>")
	)
	(segment
		(start 62.433454 -241.583464)
		(end 62.433454 -242.059968)
		(width 0.16002)
		(layer "In6.Cu")
		(net "M_E_CPU1_SA_DQS_DP<4>")
	)
	(segment
		(start 61.042296 -240.192306)
		(end 61.042296 -240.87201)
		(width 0.16002)
		(layer "In6.Cu")
		(net "M_E_CPU1_SA_DQS_DP<4>")
	)
	(segment
		(start 48.988218 -238.589566)
		(end 49.403254 -238.589566)
		(width 0.16002)
		(layer "In6.Cu")
		(net "M_E_CPU1_SA_DQS_DP<4>")
	)
	(segment
		(start 80.915002 -246.36984)
		(end 80.761078 -246.10441)
		(width 0.09525)
		(layer "In6.Cu")
		(net "M_E_CPU1_SA_DQS_DP<4>")
	)
	(segment
		(start 49.403254 -238.589566)
		(end 50.233834 -237.758986)
		(width 0.16002)
		(layer "In6.Cu")
		(net "M_E_CPU1_SA_DQS_DP<4>")
	)
	(segment
		(start 66.853816 -246.003826)
		(end 75.298046 -246.003826)
		(width 0.16002)
		(layer "In6.Cu")
		(net "M_E_CPU1_SA_DQS_DP<4>")
	)
	(segment
		(start 64.783208 -243.933218)
		(end 65.21577 -244.36578)
		(width 0.16002)
		(layer "In6.Cu")
		(net "M_E_CPU1_SA_DQS_DP<4>")
	)
	(segment
		(start 43.106086 -237.758986)
		(end 43.454828 -237.410244)
		(width 0.16002)
		(layer "In6.Cu")
		(net "M_E_CPU1_SA_DQS_DP<4>")
	)
	(segment
		(start 30.73654 -238.292386)
		(end 30.85338 -238.409226)
		(width 0.16002)
		(layer "In6.Cu")
		(net "M_E_CPU1_SA_DQS_DP<4>")
	)
	(segment
		(start 30.13964 -238.409226)
		(end 30.25648 -238.292386)
		(width 0.16002)
		(layer "In6.Cu")
		(net "M_E_CPU1_SA_DQS_DP<4>")
	)
	(segment
		(start 61.042296 -240.87201)
		(end 61.321188 -241.150902)
		(width 0.16002)
		(layer "In6.Cu")
		(net "M_E_CPU1_SA_DQS_DP<4>")
	)
	(segment
		(start 58.916062 -237.758986)
		(end 59.86907 -238.711994)
		(width 0.16002)
		(layer "In6.Cu")
		(net "M_E_CPU1_SA_DQS_DP<4>")
	)
	(segment
		(start 52.781962 -237.410244)
		(end 53.64734 -238.275622)
		(width 0.16002)
		(layer "In6.Cu")
		(net "M_E_CPU1_SA_DQS_DP<4>")
	)
	(segment
		(start 45.237908 -237.410244)
		(end 46.087792 -238.260128)
		(width 0.16002)
		(layer "In6.Cu")
		(net "M_E_CPU1_SA_DQS_DP<4>")
	)
	(segment
		(start 61.321188 -241.150902)
		(end 62.000892 -241.150902)
		(width 0.16002)
		(layer "In6.Cu")
		(net "M_E_CPU1_SA_DQS_DP<4>")
	)
	(segment
		(start 79.632556 -246.42953)
		(end 79.640938 -246.434356)
		(width 0.09525)
		(layer "In6.Cu")
		(net "M_E_CPU1_SA_DQS_DP<4>")
	)
	(segment
		(start 65.208912 -245.587266)
		(end 65.434972 -245.587266)
		(width 0.16002)
		(layer "In6.Cu")
		(net "M_E_CPU1_SA_DQS_DP<4>")
	)
	(segment
		(start 53.64734 -238.275622)
		(end 56.160416 -238.275622)
		(width 0.16002)
		(layer "In6.Cu")
		(net "M_E_CPU1_SA_DQS_DP<4>")
	)
	(segment
		(start 80.891888 -246.456454)
		(end 80.915002 -246.36984)
		(width 0.09525)
		(layer "In6.Cu")
		(net "M_E_CPU1_SA_DQS_DP<4>")
	)
	(segment
		(start 62.170564 -242.548918)
		(end 62.426596 -242.80495)
		(width 0.16002)
		(layer "In6.Cu")
		(net "M_E_CPU1_SA_DQS_DP<4>")
	)
	(segment
		(start 77.250798 -246.470932)
		(end 77.96911 -246.470932)
		(width 0.09525)
		(layer "In6.Cu")
		(net "M_E_CPU1_SA_DQS_DP<4>")
	)
	(segment
		(start 35.911028 -237.410244)
		(end 37.65296 -237.410244)
		(width 0.16002)
		(layer "In6.Cu")
		(net "M_E_CPU1_SA_DQS_DP<4>")
	)
	(segment
		(start 34.286952 -238.589566)
		(end 35.117532 -237.758986)
		(width 0.16002)
		(layer "In6.Cu")
		(net "M_E_CPU1_SA_DQS_DP<4>")
	)
	(segment
		(start 37.65296 -237.410244)
		(end 38.502844 -238.260128)
		(width 0.16002)
		(layer "In6.Cu")
		(net "M_E_CPU1_SA_DQS_DP<4>")
	)
	(segment
		(start 62.000892 -241.150902)
		(end 62.433454 -241.583464)
		(width 0.16002)
		(layer "In6.Cu")
		(net "M_E_CPU1_SA_DQS_DP<4>")
	)
	(segment
		(start 59.86907 -238.711994)
		(end 59.86907 -239.01908)
		(width 0.16002)
		(layer "In6.Cu")
		(net "M_E_CPU1_SA_DQS_DP<4>")
	)
	(segment
		(start 76.03871 -246.567706)
		(end 76.474828 -246.567706)
		(width 0.09525)
		(layer "In6.Cu")
		(net "M_E_CPU1_SA_DQS_DP<4>")
	)
	(segment
		(start 63.39205 -242.54206)
		(end 63.824612 -242.974622)
		(width 0.16002)
		(layer "In6.Cu")
		(net "M_E_CPU1_SA_DQS_DP<4>")
	)
	(segment
		(start 38.502844 -238.260128)
		(end 41.114726 -238.260128)
		(width 0.16002)
		(layer "In6.Cu")
		(net "M_E_CPU1_SA_DQS_DP<4>")
	)
	(segment
		(start 79.061564 -246.434356)
		(end 79.069946 -246.42953)
		(width 0.09525)
		(layer "In6.Cu")
		(net "M_E_CPU1_SA_DQS_DP<4>")
	)
	(segment
		(start 62.426596 -242.80495)
		(end 62.652656 -242.80495)
		(width 0.16002)
		(layer "In6.Cu")
		(net "M_E_CPU1_SA_DQS_DP<4>")
	)
	(segment
		(start 75.298046 -246.003826)
		(end 75.802744 -246.508524)
		(width 0.16002)
		(layer "In6.Cu")
		(net "M_E_CPU1_SA_DQS_DP<4>")
	)
	(segment
		(start 75.802744 -246.508524)
		(end 75.955906 -246.508524)
		(width 0.16002)
		(layer "In6.Cu")
		(net "M_E_CPU1_SA_DQS_DP<4>")
	)
	(segment
		(start 31.528766 -238.409226)
		(end 31.677864 -238.260128)
		(width 0.16002)
		(layer "In6.Cu")
		(net "M_E_CPU1_SA_DQS_DP<4>")
	)
	(segment
		(start 29.252164 -238.135414)
		(end 29.525976 -238.409226)
		(width 0.16002)
		(layer "In6.Cu")
		(net "M_E_CPU1_SA_DQS_DP<4>")
	)
	(segment
		(start 63.561722 -243.940076)
		(end 63.817754 -244.196108)
		(width 0.16002)
		(layer "In6.Cu")
		(net "M_E_CPU1_SA_DQS_DP<4>")
	)
	(segment
		(start 65.697862 -245.324376)
		(end 66.174366 -245.324376)
		(width 0.16002)
		(layer "In6.Cu")
		(net "M_E_CPU1_SA_DQS_DP<4>")
	)
	(segment
		(start 59.86907 -239.01908)
		(end 61.042296 -240.192306)
		(width 0.16002)
		(layer "In6.Cu")
		(net "M_E_CPU1_SA_DQS_DP<4>")
	)
	(segment
		(start 46.087792 -238.260128)
		(end 48.65878 -238.260128)
		(width 0.16002)
		(layer "In6.Cu")
		(net "M_E_CPU1_SA_DQS_DP<4>")
	)
	(segment
		(start 65.434972 -245.587266)
		(end 65.697862 -245.324376)
		(width 0.16002)
		(layer "In6.Cu")
		(net "M_E_CPU1_SA_DQS_DP<4>")
	)
	(segment
		(start 43.454828 -237.410244)
		(end 45.237908 -237.410244)
		(width 0.16002)
		(layer "In6.Cu")
		(net "M_E_CPU1_SA_DQS_DP<4>")
	)
	(segment
		(start 64.043814 -244.196108)
		(end 64.306704 -243.933218)
		(width 0.16002)
		(layer "In6.Cu")
		(net "M_E_CPU1_SA_DQS_DP<4>")
	)
	(segment
		(start 64.95288 -245.105174)
		(end 64.95288 -245.331234)
		(width 0.16002)
		(layer "In6.Cu")
		(net "M_E_CPU1_SA_DQS_DP<4>")
	)
	(segment
		(start 41.8592 -238.589566)
		(end 42.68978 -237.758986)
		(width 0.16002)
		(layer "In6.Cu")
		(net "M_E_CPU1_SA_DQS_DP<4>")
	)
	(segment
		(start 77.96911 -246.470932)
		(end 78.151736 -246.395494)
		(width 0.09525)
		(layer "In6.Cu")
		(net "M_E_CPU1_SA_DQS_DP<4>")
	)
	(segment
		(start 33.570926 -238.260128)
		(end 33.900364 -238.589566)
		(width 0.16002)
		(layer "In6.Cu")
		(net "M_E_CPU1_SA_DQS_DP<4>")
	)
	(segment
		(start 63.824612 -242.974622)
		(end 63.824612 -243.451126)
		(width 0.16002)
		(layer "In6.Cu")
		(net "M_E_CPU1_SA_DQS_DP<4>")
	)
	(segment
		(start 57.777888 -237.758986)
		(end 58.916062 -237.758986)
		(width 0.16002)
		(layer "In6.Cu")
		(net "M_E_CPU1_SA_DQS_DP<4>")
	)
	(segment
		(start 41.444164 -238.589566)
		(end 41.8592 -238.589566)
		(width 0.16002)
		(layer "In6.Cu")
		(net "M_E_CPU1_SA_DQS_DP<4>")
	)
	(segment
		(start 75.955906 -246.508524)
		(end 75.979528 -246.508524)
		(width 0.09525)
		(layer "In6.Cu")
		(net "M_E_CPU1_SA_DQS_DP<4>")
	)
	(segment
		(start 76.979526 -246.742204)
		(end 77.250798 -246.470932)
		(width 0.09525)
		(layer "In6.Cu")
		(net "M_E_CPU1_SA_DQS_DP<4>")
	)
	(segment
		(start 29.525976 -238.409226)
		(end 30.13964 -238.409226)
		(width 0.16002)
		(layer "In6.Cu")
		(net "M_E_CPU1_SA_DQS_DP<4>")
	)
	(segment
		(start 63.817754 -244.196108)
		(end 64.043814 -244.196108)
		(width 0.16002)
		(layer "In6.Cu")
		(net "M_E_CPU1_SA_DQS_DP<4>")
	)
	(segment
		(start 79.622142 -246.423434)
		(end 79.632556 -246.42953)
		(width 0.09525)
		(layer "In6.Cu")
		(net "M_E_CPU1_SA_DQS_DP<4>")
	)
	(segment
		(start 48.65878 -238.260128)
		(end 48.988218 -238.589566)
		(width 0.16002)
		(layer "In6.Cu")
		(net "M_E_CPU1_SA_DQS_DP<4>")
	)
	(segment
		(start 75.979528 -246.508524)
		(end 76.03871 -246.567706)
		(width 0.09525)
		(layer "In6.Cu")
		(net "M_E_CPU1_SA_DQS_DP<4>")
	)
	(segment
		(start 35.117532 -237.758986)
		(end 35.562286 -237.758986)
		(width 0.16002)
		(layer "In6.Cu")
		(net "M_E_CPU1_SA_DQS_DP<4>")
	)
	(segment
		(start 56.160416 -238.275622)
		(end 56.47436 -238.589566)
		(width 0.16002)
		(layer "In6.Cu")
		(net "M_E_CPU1_SA_DQS_DP<4>")
	)
	(segment
		(start 56.47436 -238.589566)
		(end 56.947308 -238.589566)
		(width 0.16002)
		(layer "In6.Cu")
		(net "M_E_CPU1_SA_DQS_DP<4>")
	)
	(segment
		(start 78.363064 -246.353584)
		(end 78.411832 -246.353584)
		(width 0.09525)
		(layer "In6.Cu")
		(net "M_E_CPU1_SA_DQS_DP<4>")
	)
	(segment
		(start 64.95288 -245.331234)
		(end 65.208912 -245.587266)
		(width 0.16002)
		(layer "In6.Cu")
		(net "M_E_CPU1_SA_DQS_DP<4>")
	)
	(arc
		(start 79.069946 -246.42953)
		(mid 79.345235 -246.353809)
		(end 79.622142 -246.423434)
		(width 0.09525)
		(layer "In6.Cu")
		(net "M_E_CPU1_SA_DQS_DP<4>")
	)
	(arc
		(start 78.692756 -246.42953)
		(mid 78.876531 -246.480302)
		(end 79.061564 -246.434356)
		(width 0.09525)
		(layer "In6.Cu")
		(net "M_E_CPU1_SA_DQS_DP<4>")
	)
	(arc
		(start 80.57261 -246.42953)
		(mid 80.729237 -246.478716)
		(end 80.891888 -246.456454)
		(width 0.09525)
		(layer "In6.Cu")
		(net "M_E_CPU1_SA_DQS_DP<4>")
	)
	(arc
		(start 78.411832 -246.353584)
		(mid 78.557318 -246.372988)
		(end 78.692756 -246.42953)
		(width 0.09525)
		(layer "In6.Cu")
		(net "M_E_CPU1_SA_DQS_DP<4>")
	)
	(arc
		(start 80.009746 -246.42953)
		(mid 80.291178 -246.353775)
		(end 80.57261 -246.42953)
		(width 0.09525)
		(layer "In6.Cu")
		(net "M_E_CPU1_SA_DQS_DP<4>")
	)
	(arc
		(start 79.640938 -246.434356)
		(mid 79.82597 -246.48027)
		(end 80.009746 -246.42953)
		(width 0.09525)
		(layer "In6.Cu")
		(net "M_E_CPU1_SA_DQS_DP<4>")
	)
	(arc
		(start 78.151736 -246.395494)
		(mid 78.255342 -246.36416)
		(end 78.363064 -246.353584)
		(width 0.09525)
		(layer "In6.Cu")
		(net "M_E_CPU1_SA_DQS_DP<4>")
	)
	(segment
		(start 81.22793 -241.510312)
		(end 80.761078 -241.244374)
		(width 0.12954)
		(layer "F.Cu")
		(net "M_E_CPU1_SA_DQS_DP<3>")
	)
	(segment
		(start 57.777888 -228.408992)
		(end 58.865262 -228.408992)
		(width 0.16002)
		(layer "In6.Cu")
		(net "M_E_CPU1_SA_DQS_DP<3>")
	)
	(segment
		(start 69.890386 -240.390934)
		(end 75.955906 -240.390934)
		(width 0.16002)
		(layer "In6.Cu")
		(net "M_E_CPU1_SA_DQS_DP<3>")
	)
	(segment
		(start 63.444882 -232.507282)
		(end 64.461898 -234.962446)
		(width 0.16002)
		(layer "In6.Cu")
		(net "M_E_CPU1_SA_DQS_DP<3>")
	)
	(segment
		(start 60.400946 -229.463346)
		(end 63.444882 -232.507282)
		(width 0.16002)
		(layer "In6.Cu")
		(net "M_E_CPU1_SA_DQS_DP<3>")
	)
	(segment
		(start 54.43982 -228.992684)
		(end 55.128922 -229.681786)
		(width 0.16002)
		(layer "In6.Cu")
		(net "M_E_CPU1_SA_DQS_DP<3>")
	)
	(segment
		(start 77.573886 -241.493548)
		(end 78.41107 -241.493548)
		(width 0.09525)
		(layer "In6.Cu")
		(net "M_E_CPU1_SA_DQS_DP<3>")
	)
	(segment
		(start 50.233834 -228.408992)
		(end 50.65014 -228.408992)
		(width 0.16002)
		(layer "In6.Cu")
		(net "M_E_CPU1_SA_DQS_DP<3>")
	)
	(segment
		(start 56.505094 -229.681786)
		(end 57.777888 -228.408992)
		(width 0.16002)
		(layer "In6.Cu")
		(net "M_E_CPU1_SA_DQS_DP<3>")
	)
	(segment
		(start 59.31281 -228.85654)
		(end 59.31281 -229.303326)
		(width 0.16002)
		(layer "In6.Cu")
		(net "M_E_CPU1_SA_DQS_DP<3>")
	)
	(segment
		(start 37.20338 -228.06025)
		(end 38.313614 -229.170484)
		(width 0.16002)
		(layer "In6.Cu")
		(net "M_E_CPU1_SA_DQS_DP<3>")
	)
	(segment
		(start 65.581784 -236.082332)
		(end 65.807844 -236.082332)
		(width 0.16002)
		(layer "In6.Cu")
		(net "M_E_CPU1_SA_DQS_DP<3>")
	)
	(segment
		(start 59.31281 -229.303326)
		(end 59.47283 -229.463346)
		(width 0.16002)
		(layer "In6.Cu")
		(net "M_E_CPU1_SA_DQS_DP<3>")
	)
	(segment
		(start 68.59016 -238.864648)
		(end 68.817744 -238.637064)
		(width 0.16002)
		(layer "In6.Cu")
		(net "M_E_CPU1_SA_DQS_DP<3>")
	)
	(segment
		(start 76.715112 -240.929414)
		(end 77.009752 -240.929414)
		(width 0.09525)
		(layer "In6.Cu")
		(net "M_E_CPU1_SA_DQS_DP<3>")
	)
	(segment
		(start 49.190402 -229.452424)
		(end 50.233834 -228.408992)
		(width 0.16002)
		(layer "In6.Cu")
		(net "M_E_CPU1_SA_DQS_DP<3>")
	)
	(segment
		(start 29.525976 -229.059232)
		(end 30.21076 -229.059232)
		(width 0.16002)
		(layer "In6.Cu")
		(net "M_E_CPU1_SA_DQS_DP<3>")
	)
	(segment
		(start 66.945002 -236.764322)
		(end 66.717418 -236.991906)
		(width 0.16002)
		(layer "In6.Cu")
		(net "M_E_CPU1_SA_DQS_DP<3>")
	)
	(segment
		(start 67.199002 -237.47349)
		(end 67.426586 -237.245906)
		(width 0.16002)
		(layer "In6.Cu")
		(net "M_E_CPU1_SA_DQS_DP<3>")
	)
	(segment
		(start 42.68978 -228.408992)
		(end 43.106086 -228.408992)
		(width 0.16002)
		(layer "In6.Cu")
		(net "M_E_CPU1_SA_DQS_DP<3>")
	)
	(segment
		(start 68.3641 -238.864648)
		(end 68.59016 -238.864648)
		(width 0.16002)
		(layer "In6.Cu")
		(net "M_E_CPU1_SA_DQS_DP<3>")
	)
	(segment
		(start 79.061564 -241.57432)
		(end 79.069946 -241.569494)
		(width 0.09525)
		(layer "In6.Cu")
		(net "M_E_CPU1_SA_DQS_DP<3>")
	)
	(segment
		(start 39.426388 -229.170484)
		(end 39.686738 -228.910134)
		(width 0.16002)
		(layer "In6.Cu")
		(net "M_E_CPU1_SA_DQS_DP<3>")
	)
	(segment
		(start 68.817744 -238.637064)
		(end 69.294248 -238.637064)
		(width 0.16002)
		(layer "In6.Cu")
		(net "M_E_CPU1_SA_DQS_DP<3>")
	)
	(segment
		(start 40.69715 -228.910134)
		(end 41.20896 -229.421944)
		(width 0.16002)
		(layer "In6.Cu")
		(net "M_E_CPU1_SA_DQS_DP<3>")
	)
	(segment
		(start 35.117532 -228.408992)
		(end 35.562286 -228.408992)
		(width 0.16002)
		(layer "In6.Cu")
		(net "M_E_CPU1_SA_DQS_DP<3>")
	)
	(segment
		(start 67.90309 -237.245906)
		(end 68.33616 -237.678976)
		(width 0.16002)
		(layer "In6.Cu")
		(net "M_E_CPU1_SA_DQS_DP<3>")
	)
	(segment
		(start 66.717418 -237.217966)
		(end 66.972942 -237.47349)
		(width 0.16002)
		(layer "In6.Cu")
		(net "M_E_CPU1_SA_DQS_DP<3>")
	)
	(segment
		(start 50.998882 -228.06025)
		(end 52.781962 -228.06025)
		(width 0.16002)
		(layer "In6.Cu")
		(net "M_E_CPU1_SA_DQS_DP<3>")
	)
	(segment
		(start 67.426586 -237.245906)
		(end 67.90309 -237.245906)
		(width 0.16002)
		(layer "In6.Cu")
		(net "M_E_CPU1_SA_DQS_DP<3>")
	)
	(segment
		(start 48.225964 -228.910134)
		(end 48.768254 -229.452424)
		(width 0.16002)
		(layer "In6.Cu")
		(net "M_E_CPU1_SA_DQS_DP<3>")
	)
	(segment
		(start 41.676828 -229.421944)
		(end 42.68978 -228.408992)
		(width 0.16002)
		(layer "In6.Cu")
		(net "M_E_CPU1_SA_DQS_DP<3>")
	)
	(segment
		(start 66.035428 -235.854748)
		(end 66.511932 -235.854748)
		(width 0.16002)
		(layer "In6.Cu")
		(net "M_E_CPU1_SA_DQS_DP<3>")
	)
	(segment
		(start 80.891888 -241.596418)
		(end 80.915002 -241.509804)
		(width 0.09525)
		(layer "In6.Cu")
		(net "M_E_CPU1_SA_DQS_DP<3>")
	)
	(segment
		(start 68.108576 -238.383064)
		(end 68.108576 -238.609124)
		(width 0.16002)
		(layer "In6.Cu")
		(net "M_E_CPU1_SA_DQS_DP<3>")
	)
	(segment
		(start 41.20896 -229.421944)
		(end 41.676828 -229.421944)
		(width 0.16002)
		(layer "In6.Cu")
		(net "M_E_CPU1_SA_DQS_DP<3>")
	)
	(segment
		(start 79.622142 -241.563398)
		(end 79.632556 -241.569494)
		(width 0.09525)
		(layer "In6.Cu")
		(net "M_E_CPU1_SA_DQS_DP<3>")
	)
	(segment
		(start 43.454828 -228.06025)
		(end 45.237908 -228.06025)
		(width 0.16002)
		(layer "In6.Cu")
		(net "M_E_CPU1_SA_DQS_DP<3>")
	)
	(segment
		(start 34.01568 -229.510844)
		(end 35.117532 -228.408992)
		(width 0.16002)
		(layer "In6.Cu")
		(net "M_E_CPU1_SA_DQS_DP<3>")
	)
	(segment
		(start 48.768254 -229.452424)
		(end 49.190402 -229.452424)
		(width 0.16002)
		(layer "In6.Cu")
		(net "M_E_CPU1_SA_DQS_DP<3>")
	)
	(segment
		(start 31.677864 -228.910134)
		(end 33.10001 -228.910134)
		(width 0.16002)
		(layer "In6.Cu")
		(net "M_E_CPU1_SA_DQS_DP<3>")
	)
	(segment
		(start 75.979528 -240.390934)
		(end 76.045822 -240.457228)
		(width 0.09525)
		(layer "In6.Cu")
		(net "M_E_CPU1_SA_DQS_DP<3>")
	)
	(segment
		(start 64.461898 -234.962446)
		(end 65.581784 -236.082332)
		(width 0.16002)
		(layer "In6.Cu")
		(net "M_E_CPU1_SA_DQS_DP<3>")
	)
	(segment
		(start 43.106086 -228.408992)
		(end 43.454828 -228.06025)
		(width 0.16002)
		(layer "In6.Cu")
		(net "M_E_CPU1_SA_DQS_DP<3>")
	)
	(segment
		(start 35.562286 -228.408992)
		(end 35.911028 -228.06025)
		(width 0.16002)
		(layer "In6.Cu")
		(net "M_E_CPU1_SA_DQS_DP<3>")
	)
	(segment
		(start 75.955906 -240.390934)
		(end 75.979528 -240.390934)
		(width 0.09525)
		(layer "In6.Cu")
		(net "M_E_CPU1_SA_DQS_DP<3>")
	)
	(segment
		(start 35.911028 -228.06025)
		(end 37.20338 -228.06025)
		(width 0.16002)
		(layer "In6.Cu")
		(net "M_E_CPU1_SA_DQS_DP<3>")
	)
	(segment
		(start 46.087792 -228.910134)
		(end 48.225964 -228.910134)
		(width 0.16002)
		(layer "In6.Cu")
		(net "M_E_CPU1_SA_DQS_DP<3>")
	)
	(segment
		(start 58.865262 -228.408992)
		(end 59.31281 -228.85654)
		(width 0.16002)
		(layer "In6.Cu")
		(net "M_E_CPU1_SA_DQS_DP<3>")
	)
	(segment
		(start 30.3276 -228.942392)
		(end 30.80766 -228.942392)
		(width 0.16002)
		(layer "In6.Cu")
		(net "M_E_CPU1_SA_DQS_DP<3>")
	)
	(segment
		(start 66.972942 -237.47349)
		(end 67.199002 -237.47349)
		(width 0.16002)
		(layer "In6.Cu")
		(net "M_E_CPU1_SA_DQS_DP<3>")
	)
	(segment
		(start 59.47283 -229.463346)
		(end 60.400946 -229.463346)
		(width 0.16002)
		(layer "In6.Cu")
		(net "M_E_CPU1_SA_DQS_DP<3>")
	)
	(segment
		(start 68.33616 -238.15548)
		(end 68.108576 -238.383064)
		(width 0.16002)
		(layer "In6.Cu")
		(net "M_E_CPU1_SA_DQS_DP<3>")
	)
	(segment
		(start 69.727318 -239.546638)
		(end 69.499734 -239.774222)
		(width 0.16002)
		(layer "In6.Cu")
		(net "M_E_CPU1_SA_DQS_DP<3>")
	)
	(segment
		(start 45.237908 -228.06025)
		(end 46.087792 -228.910134)
		(width 0.16002)
		(layer "In6.Cu")
		(net "M_E_CPU1_SA_DQS_DP<3>")
	)
	(segment
		(start 68.33616 -237.678976)
		(end 68.33616 -238.15548)
		(width 0.16002)
		(layer "In6.Cu")
		(net "M_E_CPU1_SA_DQS_DP<3>")
	)
	(segment
		(start 77.009752 -240.929414)
		(end 77.573886 -241.493548)
		(width 0.09525)
		(layer "In6.Cu")
		(net "M_E_CPU1_SA_DQS_DP<3>")
	)
	(segment
		(start 80.915002 -241.509804)
		(end 80.761078 -241.244374)
		(width 0.09525)
		(layer "In6.Cu")
		(net "M_E_CPU1_SA_DQS_DP<3>")
	)
	(segment
		(start 31.528766 -229.059232)
		(end 31.677864 -228.910134)
		(width 0.16002)
		(layer "In6.Cu")
		(net "M_E_CPU1_SA_DQS_DP<3>")
	)
	(segment
		(start 69.727318 -239.070134)
		(end 69.727318 -239.546638)
		(width 0.16002)
		(layer "In6.Cu")
		(net "M_E_CPU1_SA_DQS_DP<3>")
	)
	(segment
		(start 69.499734 -239.774222)
		(end 69.499734 -240.000282)
		(width 0.16002)
		(layer "In6.Cu")
		(net "M_E_CPU1_SA_DQS_DP<3>")
	)
	(segment
		(start 53.714396 -228.992684)
		(end 54.43982 -228.992684)
		(width 0.16002)
		(layer "In6.Cu")
		(net "M_E_CPU1_SA_DQS_DP<3>")
	)
	(segment
		(start 65.807844 -236.082332)
		(end 66.035428 -235.854748)
		(width 0.16002)
		(layer "In6.Cu")
		(net "M_E_CPU1_SA_DQS_DP<3>")
	)
	(segment
		(start 30.9245 -229.059232)
		(end 31.528766 -229.059232)
		(width 0.16002)
		(layer "In6.Cu")
		(net "M_E_CPU1_SA_DQS_DP<3>")
	)
	(segment
		(start 52.781962 -228.06025)
		(end 53.714396 -228.992684)
		(width 0.16002)
		(layer "In6.Cu")
		(net "M_E_CPU1_SA_DQS_DP<3>")
	)
	(segment
		(start 38.313614 -229.170484)
		(end 39.426388 -229.170484)
		(width 0.16002)
		(layer "In6.Cu")
		(net "M_E_CPU1_SA_DQS_DP<3>")
	)
	(segment
		(start 33.70072 -229.510844)
		(end 34.01568 -229.510844)
		(width 0.16002)
		(layer "In6.Cu")
		(net "M_E_CPU1_SA_DQS_DP<3>")
	)
	(segment
		(start 76.242926 -240.457228)
		(end 76.715112 -240.929414)
		(width 0.09525)
		(layer "In6.Cu")
		(net "M_E_CPU1_SA_DQS_DP<3>")
	)
	(segment
		(start 79.632556 -241.569494)
		(end 79.640938 -241.57432)
		(width 0.09525)
		(layer "In6.Cu")
		(net "M_E_CPU1_SA_DQS_DP<3>")
	)
	(segment
		(start 69.294248 -238.637064)
		(end 69.727318 -239.070134)
		(width 0.16002)
		(layer "In6.Cu")
		(net "M_E_CPU1_SA_DQS_DP<3>")
	)
	(segment
		(start 76.045822 -240.457228)
		(end 76.242926 -240.457228)
		(width 0.09525)
		(layer "In6.Cu")
		(net "M_E_CPU1_SA_DQS_DP<3>")
	)
	(segment
		(start 66.717418 -236.991906)
		(end 66.717418 -237.217966)
		(width 0.16002)
		(layer "In6.Cu")
		(net "M_E_CPU1_SA_DQS_DP<3>")
	)
	(segment
		(start 66.945002 -236.287818)
		(end 66.945002 -236.764322)
		(width 0.16002)
		(layer "In6.Cu")
		(net "M_E_CPU1_SA_DQS_DP<3>")
	)
	(segment
		(start 55.128922 -229.681786)
		(end 56.505094 -229.681786)
		(width 0.16002)
		(layer "In6.Cu")
		(net "M_E_CPU1_SA_DQS_DP<3>")
	)
	(segment
		(start 66.511932 -235.854748)
		(end 66.945002 -236.287818)
		(width 0.16002)
		(layer "In6.Cu")
		(net "M_E_CPU1_SA_DQS_DP<3>")
	)
	(segment
		(start 33.10001 -228.910134)
		(end 33.70072 -229.510844)
		(width 0.16002)
		(layer "In6.Cu")
		(net "M_E_CPU1_SA_DQS_DP<3>")
	)
	(segment
		(start 68.108576 -238.609124)
		(end 68.3641 -238.864648)
		(width 0.16002)
		(layer "In6.Cu")
		(net "M_E_CPU1_SA_DQS_DP<3>")
	)
	(segment
		(start 50.65014 -228.408992)
		(end 50.998882 -228.06025)
		(width 0.16002)
		(layer "In6.Cu")
		(net "M_E_CPU1_SA_DQS_DP<3>")
	)
	(segment
		(start 30.21076 -229.059232)
		(end 30.3276 -228.942392)
		(width 0.16002)
		(layer "In6.Cu")
		(net "M_E_CPU1_SA_DQS_DP<3>")
	)
	(segment
		(start 69.499734 -240.000282)
		(end 69.890386 -240.390934)
		(width 0.16002)
		(layer "In6.Cu")
		(net "M_E_CPU1_SA_DQS_DP<3>")
	)
	(segment
		(start 30.80766 -228.942392)
		(end 30.9245 -229.059232)
		(width 0.16002)
		(layer "In6.Cu")
		(net "M_E_CPU1_SA_DQS_DP<3>")
	)
	(segment
		(start 39.686738 -228.910134)
		(end 40.69715 -228.910134)
		(width 0.16002)
		(layer "In6.Cu")
		(net "M_E_CPU1_SA_DQS_DP<3>")
	)
	(segment
		(start 29.252164 -228.78542)
		(end 29.525976 -229.059232)
		(width 0.16002)
		(layer "In6.Cu")
		(net "M_E_CPU1_SA_DQS_DP<3>")
	)
	(arc
		(start 78.41107 -241.493548)
		(mid 78.55695 -241.512853)
		(end 78.692756 -241.569494)
		(width 0.09525)
		(layer "In6.Cu")
		(net "M_E_CPU1_SA_DQS_DP<3>")
	)
	(arc
		(start 79.069946 -241.569494)
		(mid 79.345235 -241.493773)
		(end 79.622142 -241.563398)
		(width 0.09525)
		(layer "In6.Cu")
		(net "M_E_CPU1_SA_DQS_DP<3>")
	)
	(arc
		(start 80.57261 -241.569494)
		(mid 80.729237 -241.61868)
		(end 80.891888 -241.596418)
		(width 0.09525)
		(layer "In6.Cu")
		(net "M_E_CPU1_SA_DQS_DP<3>")
	)
	(arc
		(start 80.009746 -241.569494)
		(mid 80.291178 -241.493739)
		(end 80.57261 -241.569494)
		(width 0.09525)
		(layer "In6.Cu")
		(net "M_E_CPU1_SA_DQS_DP<3>")
	)
	(arc
		(start 79.640938 -241.57432)
		(mid 79.82597 -241.620234)
		(end 80.009746 -241.569494)
		(width 0.09525)
		(layer "In6.Cu")
		(net "M_E_CPU1_SA_DQS_DP<3>")
	)
	(arc
		(start 78.692756 -241.569494)
		(mid 78.876531 -241.620266)
		(end 79.061564 -241.57432)
		(width 0.09525)
		(layer "In6.Cu")
		(net "M_E_CPU1_SA_DQS_DP<3>")
	)
	(segment
		(start 81.22793 -236.650276)
		(end 80.761078 -236.384338)
		(width 0.12954)
		(layer "F.Cu")
		(net "M_E_CPU1_SA_DQS_DP<2>")
	)
	(segment
		(start 59.318398 -220.024706)
		(end 59.478418 -220.184726)
		(width 0.16002)
		(layer "In6.Cu")
		(net "M_E_CPU1_SA_DQS_DP<2>")
	)
	(segment
		(start 30.334966 -219.709238)
		(end 30.451806 -219.592398)
		(width 0.16002)
		(layer "In6.Cu")
		(net "M_E_CPU1_SA_DQS_DP<2>")
	)
	(segment
		(start 61.965078 -220.024706)
		(end 61.965078 -219.673424)
		(width 0.16002)
		(layer "In6.Cu")
		(net "M_E_CPU1_SA_DQS_DP<2>")
	)
	(segment
		(start 31.677864 -219.56014)
		(end 33.065974 -219.56014)
		(width 0.16002)
		(layer "In6.Cu")
		(net "M_E_CPU1_SA_DQS_DP<2>")
	)
	(segment
		(start 59.839098 -220.184726)
		(end 59.999118 -220.024706)
		(width 0.16002)
		(layer "In6.Cu")
		(net "M_E_CPU1_SA_DQS_DP<2>")
	)
	(segment
		(start 54.666896 -219.575634)
		(end 55.389526 -220.298264)
		(width 0.16002)
		(layer "In6.Cu")
		(net "M_E_CPU1_SA_DQS_DP<2>")
	)
	(segment
		(start 80.891888 -236.736382)
		(end 80.915002 -236.649768)
		(width 0.09525)
		(layer "In6.Cu")
		(net "M_E_CPU1_SA_DQS_DP<2>")
	)
	(segment
		(start 65.88379 -225.841306)
		(end 65.88379 -226.879658)
		(width 0.16002)
		(layer "In6.Cu")
		(net "M_E_CPU1_SA_DQS_DP<2>")
	)
	(segment
		(start 65.88379 -226.879658)
		(end 73.743312 -234.73918)
		(width 0.16002)
		(layer "In6.Cu")
		(net "M_E_CPU1_SA_DQS_DP<2>")
	)
	(segment
		(start 80.915002 -236.649768)
		(end 80.761078 -236.384338)
		(width 0.09525)
		(layer "In6.Cu")
		(net "M_E_CPU1_SA_DQS_DP<2>")
	)
	(segment
		(start 46.087792 -219.56014)
		(end 48.161448 -219.56014)
		(width 0.16002)
		(layer "In6.Cu")
		(net "M_E_CPU1_SA_DQS_DP<2>")
	)
	(segment
		(start 33.661858 -220.156024)
		(end 34.020506 -220.156024)
		(width 0.16002)
		(layer "In6.Cu")
		(net "M_E_CPU1_SA_DQS_DP<2>")
	)
	(segment
		(start 55.389526 -220.298264)
		(end 56.538622 -220.298264)
		(width 0.16002)
		(layer "In6.Cu")
		(net "M_E_CPU1_SA_DQS_DP<2>")
	)
	(segment
		(start 43.106086 -219.058998)
		(end 43.454828 -218.710256)
		(width 0.16002)
		(layer "In6.Cu")
		(net "M_E_CPU1_SA_DQS_DP<2>")
	)
	(segment
		(start 29.252164 -219.435426)
		(end 29.525976 -219.709238)
		(width 0.16002)
		(layer "In6.Cu")
		(net "M_E_CPU1_SA_DQS_DP<2>")
	)
	(segment
		(start 61.444378 -220.184726)
		(end 61.805058 -220.184726)
		(width 0.16002)
		(layer "In6.Cu")
		(net "M_E_CPU1_SA_DQS_DP<2>")
	)
	(segment
		(start 33.065974 -219.56014)
		(end 33.661858 -220.156024)
		(width 0.16002)
		(layer "In6.Cu")
		(net "M_E_CPU1_SA_DQS_DP<2>")
	)
	(segment
		(start 57.777888 -219.058998)
		(end 58.98134 -219.058998)
		(width 0.16002)
		(layer "In6.Cu")
		(net "M_E_CPU1_SA_DQS_DP<2>")
	)
	(segment
		(start 59.318398 -219.396056)
		(end 59.318398 -220.024706)
		(width 0.16002)
		(layer "In6.Cu")
		(net "M_E_CPU1_SA_DQS_DP<2>")
	)
	(segment
		(start 40.589454 -219.56014)
		(end 41.195498 -220.166184)
		(width 0.16002)
		(layer "In6.Cu")
		(net "M_E_CPU1_SA_DQS_DP<2>")
	)
	(segment
		(start 50.233834 -219.058998)
		(end 50.65014 -219.058998)
		(width 0.16002)
		(layer "In6.Cu")
		(net "M_E_CPU1_SA_DQS_DP<2>")
	)
	(segment
		(start 41.195498 -220.166184)
		(end 41.582594 -220.166184)
		(width 0.16002)
		(layer "In6.Cu")
		(net "M_E_CPU1_SA_DQS_DP<2>")
	)
	(segment
		(start 61.284358 -219.404184)
		(end 61.284358 -220.024706)
		(width 0.16002)
		(layer "In6.Cu")
		(net "M_E_CPU1_SA_DQS_DP<2>")
	)
	(segment
		(start 61.284358 -220.024706)
		(end 61.444378 -220.184726)
		(width 0.16002)
		(layer "In6.Cu")
		(net "M_E_CPU1_SA_DQS_DP<2>")
	)
	(segment
		(start 73.743312 -234.73918)
		(end 75.955906 -234.73918)
		(width 0.16002)
		(layer "In6.Cu")
		(net "M_E_CPU1_SA_DQS_DP<2>")
	)
	(segment
		(start 59.999118 -220.024706)
		(end 59.999118 -219.404184)
		(width 0.16002)
		(layer "In6.Cu")
		(net "M_E_CPU1_SA_DQS_DP<2>")
	)
	(segment
		(start 76.773786 -235.593636)
		(end 77.203554 -235.593636)
		(width 0.09525)
		(layer "In6.Cu")
		(net "M_E_CPU1_SA_DQS_DP<2>")
	)
	(segment
		(start 35.911028 -218.710256)
		(end 37.693092 -218.710256)
		(width 0.16002)
		(layer "In6.Cu")
		(net "M_E_CPU1_SA_DQS_DP<2>")
	)
	(segment
		(start 56.538622 -220.298264)
		(end 57.777888 -219.058998)
		(width 0.16002)
		(layer "In6.Cu")
		(net "M_E_CPU1_SA_DQS_DP<2>")
	)
	(segment
		(start 30.931866 -219.592398)
		(end 31.048706 -219.709238)
		(width 0.16002)
		(layer "In6.Cu")
		(net "M_E_CPU1_SA_DQS_DP<2>")
	)
	(segment
		(start 79.061564 -236.714284)
		(end 79.069946 -236.709458)
		(width 0.09525)
		(layer "In6.Cu")
		(net "M_E_CPU1_SA_DQS_DP<2>")
	)
	(segment
		(start 50.998882 -218.710256)
		(end 52.781962 -218.710256)
		(width 0.16002)
		(layer "In6.Cu")
		(net "M_E_CPU1_SA_DQS_DP<2>")
	)
	(segment
		(start 76.24064 -234.798108)
		(end 76.443586 -235.001054)
		(width 0.09525)
		(layer "In6.Cu")
		(net "M_E_CPU1_SA_DQS_DP<2>")
	)
	(segment
		(start 58.98134 -219.058998)
		(end 59.318398 -219.396056)
		(width 0.16002)
		(layer "In6.Cu")
		(net "M_E_CPU1_SA_DQS_DP<2>")
	)
	(segment
		(start 77.203554 -235.593636)
		(end 78.24343 -236.633512)
		(width 0.09525)
		(layer "In6.Cu")
		(net "M_E_CPU1_SA_DQS_DP<2>")
	)
	(segment
		(start 76.443586 -235.001054)
		(end 76.443586 -235.263436)
		(width 0.09525)
		(layer "In6.Cu")
		(net "M_E_CPU1_SA_DQS_DP<2>")
	)
	(segment
		(start 63.53175 -219.888816)
		(end 63.53175 -223.489266)
		(width 0.16002)
		(layer "In6.Cu")
		(net "M_E_CPU1_SA_DQS_DP<2>")
	)
	(segment
		(start 35.562286 -219.058998)
		(end 35.911028 -218.710256)
		(width 0.16002)
		(layer "In6.Cu")
		(net "M_E_CPU1_SA_DQS_DP<2>")
	)
	(segment
		(start 59.478418 -220.184726)
		(end 59.839098 -220.184726)
		(width 0.16002)
		(layer "In6.Cu")
		(net "M_E_CPU1_SA_DQS_DP<2>")
	)
	(segment
		(start 75.979528 -234.73918)
		(end 76.038456 -234.798108)
		(width 0.09525)
		(layer "In6.Cu")
		(net "M_E_CPU1_SA_DQS_DP<2>")
	)
	(segment
		(start 60.336176 -219.067126)
		(end 60.9473 -219.067126)
		(width 0.16002)
		(layer "In6.Cu")
		(net "M_E_CPU1_SA_DQS_DP<2>")
	)
	(segment
		(start 62.9793 -219.336366)
		(end 63.53175 -219.888816)
		(width 0.16002)
		(layer "In6.Cu")
		(net "M_E_CPU1_SA_DQS_DP<2>")
	)
	(segment
		(start 45.237908 -218.710256)
		(end 46.087792 -219.56014)
		(width 0.16002)
		(layer "In6.Cu")
		(net "M_E_CPU1_SA_DQS_DP<2>")
	)
	(segment
		(start 76.443586 -235.263436)
		(end 76.773786 -235.593636)
		(width 0.09525)
		(layer "In6.Cu")
		(net "M_E_CPU1_SA_DQS_DP<2>")
	)
	(segment
		(start 29.525976 -219.709238)
		(end 30.334966 -219.709238)
		(width 0.16002)
		(layer "In6.Cu")
		(net "M_E_CPU1_SA_DQS_DP<2>")
	)
	(segment
		(start 61.965078 -219.673424)
		(end 62.302136 -219.336366)
		(width 0.16002)
		(layer "In6.Cu")
		(net "M_E_CPU1_SA_DQS_DP<2>")
	)
	(segment
		(start 60.9473 -219.067126)
		(end 61.284358 -219.404184)
		(width 0.16002)
		(layer "In6.Cu")
		(net "M_E_CPU1_SA_DQS_DP<2>")
	)
	(segment
		(start 30.451806 -219.592398)
		(end 30.931866 -219.592398)
		(width 0.16002)
		(layer "In6.Cu")
		(net "M_E_CPU1_SA_DQS_DP<2>")
	)
	(segment
		(start 52.781962 -218.710256)
		(end 53.64734 -219.575634)
		(width 0.16002)
		(layer "In6.Cu")
		(net "M_E_CPU1_SA_DQS_DP<2>")
	)
	(segment
		(start 35.117532 -219.058998)
		(end 35.562286 -219.058998)
		(width 0.16002)
		(layer "In6.Cu")
		(net "M_E_CPU1_SA_DQS_DP<2>")
	)
	(segment
		(start 41.582594 -220.166184)
		(end 42.68978 -219.058998)
		(width 0.16002)
		(layer "In6.Cu")
		(net "M_E_CPU1_SA_DQS_DP<2>")
	)
	(segment
		(start 38.542976 -219.56014)
		(end 40.589454 -219.56014)
		(width 0.16002)
		(layer "In6.Cu")
		(net "M_E_CPU1_SA_DQS_DP<2>")
	)
	(segment
		(start 48.767492 -220.166184)
		(end 49.126648 -220.166184)
		(width 0.16002)
		(layer "In6.Cu")
		(net "M_E_CPU1_SA_DQS_DP<2>")
	)
	(segment
		(start 75.955906 -234.73918)
		(end 75.979528 -234.73918)
		(width 0.09525)
		(layer "In6.Cu")
		(net "M_E_CPU1_SA_DQS_DP<2>")
	)
	(segment
		(start 48.161448 -219.56014)
		(end 48.767492 -220.166184)
		(width 0.16002)
		(layer "In6.Cu")
		(net "M_E_CPU1_SA_DQS_DP<2>")
	)
	(segment
		(start 43.454828 -218.710256)
		(end 45.237908 -218.710256)
		(width 0.16002)
		(layer "In6.Cu")
		(net "M_E_CPU1_SA_DQS_DP<2>")
	)
	(segment
		(start 37.693092 -218.710256)
		(end 38.542976 -219.56014)
		(width 0.16002)
		(layer "In6.Cu")
		(net "M_E_CPU1_SA_DQS_DP<2>")
	)
	(segment
		(start 59.999118 -219.404184)
		(end 60.336176 -219.067126)
		(width 0.16002)
		(layer "In6.Cu")
		(net "M_E_CPU1_SA_DQS_DP<2>")
	)
	(segment
		(start 61.805058 -220.184726)
		(end 61.965078 -220.024706)
		(width 0.16002)
		(layer "In6.Cu")
		(net "M_E_CPU1_SA_DQS_DP<2>")
	)
	(segment
		(start 76.038456 -234.798108)
		(end 76.24064 -234.798108)
		(width 0.09525)
		(layer "In6.Cu")
		(net "M_E_CPU1_SA_DQS_DP<2>")
	)
	(segment
		(start 79.632556 -236.709458)
		(end 79.640938 -236.714284)
		(width 0.09525)
		(layer "In6.Cu")
		(net "M_E_CPU1_SA_DQS_DP<2>")
	)
	(segment
		(start 78.24343 -236.633512)
		(end 78.41107 -236.633512)
		(width 0.09525)
		(layer "In6.Cu")
		(net "M_E_CPU1_SA_DQS_DP<2>")
	)
	(segment
		(start 63.53175 -223.489266)
		(end 65.88379 -225.841306)
		(width 0.16002)
		(layer "In6.Cu")
		(net "M_E_CPU1_SA_DQS_DP<2>")
	)
	(segment
		(start 42.68978 -219.058998)
		(end 43.106086 -219.058998)
		(width 0.16002)
		(layer "In6.Cu")
		(net "M_E_CPU1_SA_DQS_DP<2>")
	)
	(segment
		(start 62.302136 -219.336366)
		(end 62.9793 -219.336366)
		(width 0.16002)
		(layer "In6.Cu")
		(net "M_E_CPU1_SA_DQS_DP<2>")
	)
	(segment
		(start 49.126648 -220.166184)
		(end 50.233834 -219.058998)
		(width 0.16002)
		(layer "In6.Cu")
		(net "M_E_CPU1_SA_DQS_DP<2>")
	)
	(segment
		(start 31.528766 -219.709238)
		(end 31.677864 -219.56014)
		(width 0.16002)
		(layer "In6.Cu")
		(net "M_E_CPU1_SA_DQS_DP<2>")
	)
	(segment
		(start 34.020506 -220.156024)
		(end 35.117532 -219.058998)
		(width 0.16002)
		(layer "In6.Cu")
		(net "M_E_CPU1_SA_DQS_DP<2>")
	)
	(segment
		(start 31.048706 -219.709238)
		(end 31.528766 -219.709238)
		(width 0.16002)
		(layer "In6.Cu")
		(net "M_E_CPU1_SA_DQS_DP<2>")
	)
	(segment
		(start 50.65014 -219.058998)
		(end 50.998882 -218.710256)
		(width 0.16002)
		(layer "In6.Cu")
		(net "M_E_CPU1_SA_DQS_DP<2>")
	)
	(segment
		(start 79.622142 -236.703362)
		(end 79.632556 -236.709458)
		(width 0.09525)
		(layer "In6.Cu")
		(net "M_E_CPU1_SA_DQS_DP<2>")
	)
	(segment
		(start 53.64734 -219.575634)
		(end 54.666896 -219.575634)
		(width 0.16002)
		(layer "In6.Cu")
		(net "M_E_CPU1_SA_DQS_DP<2>")
	)
	(arc
		(start 79.069946 -236.709458)
		(mid 79.345235 -236.633737)
		(end 79.622142 -236.703362)
		(width 0.09525)
		(layer "In6.Cu")
		(net "M_E_CPU1_SA_DQS_DP<2>")
	)
	(arc
		(start 78.692756 -236.709458)
		(mid 78.876531 -236.76023)
		(end 79.061564 -236.714284)
		(width 0.09525)
		(layer "In6.Cu")
		(net "M_E_CPU1_SA_DQS_DP<2>")
	)
	(arc
		(start 79.640938 -236.714284)
		(mid 79.82597 -236.760198)
		(end 80.009746 -236.709458)
		(width 0.09525)
		(layer "In6.Cu")
		(net "M_E_CPU1_SA_DQS_DP<2>")
	)
	(arc
		(start 78.41107 -236.633512)
		(mid 78.55695 -236.652817)
		(end 78.692756 -236.709458)
		(width 0.09525)
		(layer "In6.Cu")
		(net "M_E_CPU1_SA_DQS_DP<2>")
	)
	(arc
		(start 80.009746 -236.709458)
		(mid 80.291178 -236.633703)
		(end 80.57261 -236.709458)
		(width 0.09525)
		(layer "In6.Cu")
		(net "M_E_CPU1_SA_DQS_DP<2>")
	)
	(arc
		(start 80.57261 -236.709458)
		(mid 80.729237 -236.758644)
		(end 80.891888 -236.736382)
		(width 0.09525)
		(layer "In6.Cu")
		(net "M_E_CPU1_SA_DQS_DP<2>")
	)
	(segment
		(start 81.22793 -231.79024)
		(end 80.761078 -231.524302)
		(width 0.12954)
		(layer "F.Cu")
		(net "M_E_CPU1_SA_DQS_DP<1>")
	)
	(segment
		(start 38.405816 -210.210146)
		(end 40.757094 -210.210146)
		(width 0.16002)
		(layer "In6.Cu")
		(net "M_E_CPU1_SA_DQS_DP<1>")
	)
	(segment
		(start 69.233288 -217.756994)
		(end 69.233288 -221.344236)
		(width 0.16002)
		(layer "In6.Cu")
		(net "M_E_CPU1_SA_DQS_DP<1>")
	)
	(segment
		(start 48.779938 -210.803744)
		(end 49.139094 -210.803744)
		(width 0.16002)
		(layer "In6.Cu")
		(net "M_E_CPU1_SA_DQS_DP<1>")
	)
	(segment
		(start 50.65014 -209.709004)
		(end 50.998882 -209.360262)
		(width 0.16002)
		(layer "In6.Cu")
		(net "M_E_CPU1_SA_DQS_DP<1>")
	)
	(segment
		(start 77.478636 -230.653844)
		(end 78.615286 -231.790494)
		(width 0.09525)
		(layer "In6.Cu")
		(net "M_E_CPU1_SA_DQS_DP<1>")
	)
	(segment
		(start 62.47003 -211.57692)
		(end 62.9031 -212.00999)
		(width 0.16002)
		(layer "In6.Cu")
		(net "M_E_CPU1_SA_DQS_DP<1>")
	)
	(segment
		(start 61.078872 -210.185762)
		(end 61.511942 -210.618832)
		(width 0.16002)
		(layer "In6.Cu")
		(net "M_E_CPU1_SA_DQS_DP<1>")
	)
	(segment
		(start 35.117532 -209.709004)
		(end 35.562286 -209.709004)
		(width 0.16002)
		(layer "In6.Cu")
		(net "M_E_CPU1_SA_DQS_DP<1>")
	)
	(segment
		(start 75.7936 -228.811836)
		(end 76.608178 -229.626414)
		(width 0.09525)
		(layer "In6.Cu")
		(net "M_E_CPU1_SA_DQS_DP<1>")
	)
	(segment
		(start 77.478636 -230.055674)
		(end 77.478636 -230.653844)
		(width 0.09525)
		(layer "In6.Cu")
		(net "M_E_CPU1_SA_DQS_DP<1>")
	)
	(segment
		(start 76.608178 -229.626414)
		(end 77.049376 -229.626414)
		(width 0.09525)
		(layer "In6.Cu")
		(net "M_E_CPU1_SA_DQS_DP<1>")
	)
	(segment
		(start 50.998882 -209.360262)
		(end 52.781962 -209.360262)
		(width 0.16002)
		(layer "In6.Cu")
		(net "M_E_CPU1_SA_DQS_DP<1>")
	)
	(segment
		(start 80.915002 -231.789732)
		(end 80.761078 -231.524302)
		(width 0.09525)
		(layer "In6.Cu")
		(net "M_E_CPU1_SA_DQS_DP<1>")
	)
	(segment
		(start 62.9031 -212.486494)
		(end 62.360556 -213.029038)
		(width 0.16002)
		(layer "In6.Cu")
		(net "M_E_CPU1_SA_DQS_DP<1>")
	)
	(segment
		(start 55.241952 -210.971384)
		(end 56.515508 -210.971384)
		(width 0.16002)
		(layer "In6.Cu")
		(net "M_E_CPU1_SA_DQS_DP<1>")
	)
	(segment
		(start 31.528766 -210.359244)
		(end 31.677864 -210.210146)
		(width 0.16002)
		(layer "In6.Cu")
		(net "M_E_CPU1_SA_DQS_DP<1>")
	)
	(segment
		(start 60.059824 -210.728306)
		(end 60.602368 -210.185762)
		(width 0.16002)
		(layer "In6.Cu")
		(net "M_E_CPU1_SA_DQS_DP<1>")
	)
	(segment
		(start 60.969398 -211.63788)
		(end 60.969398 -211.86394)
		(width 0.16002)
		(layer "In6.Cu")
		(net "M_E_CPU1_SA_DQS_DP<1>")
	)
	(segment
		(start 62.360556 -213.029038)
		(end 62.360556 -213.255098)
		(width 0.16002)
		(layer "In6.Cu")
		(net "M_E_CPU1_SA_DQS_DP<1>")
	)
	(segment
		(start 41.67886 -210.719924)
		(end 42.68978 -209.709004)
		(width 0.16002)
		(layer "In6.Cu")
		(net "M_E_CPU1_SA_DQS_DP<1>")
	)
	(segment
		(start 33.570926 -210.210146)
		(end 33.900364 -210.539584)
		(width 0.16002)
		(layer "In6.Cu")
		(net "M_E_CPU1_SA_DQS_DP<1>")
	)
	(segment
		(start 61.511942 -211.095336)
		(end 60.969398 -211.63788)
		(width 0.16002)
		(layer "In6.Cu")
		(net "M_E_CPU1_SA_DQS_DP<1>")
	)
	(segment
		(start 43.454828 -209.360262)
		(end 45.237908 -209.360262)
		(width 0.16002)
		(layer "In6.Cu")
		(net "M_E_CPU1_SA_DQS_DP<1>")
	)
	(segment
		(start 61.450982 -212.119464)
		(end 61.993526 -211.57692)
		(width 0.16002)
		(layer "In6.Cu")
		(net "M_E_CPU1_SA_DQS_DP<1>")
	)
	(segment
		(start 56.515508 -210.971384)
		(end 57.777888 -209.709004)
		(width 0.16002)
		(layer "In6.Cu")
		(net "M_E_CPU1_SA_DQS_DP<1>")
	)
	(segment
		(start 79.632556 -231.849422)
		(end 79.640938 -231.854248)
		(width 0.09525)
		(layer "In6.Cu")
		(net "M_E_CPU1_SA_DQS_DP<1>")
	)
	(segment
		(start 75.7936 -228.728778)
		(end 75.7936 -228.811836)
		(width 0.09525)
		(layer "In6.Cu")
		(net "M_E_CPU1_SA_DQS_DP<1>")
	)
	(segment
		(start 42.68978 -209.709004)
		(end 43.106086 -209.709004)
		(width 0.16002)
		(layer "In6.Cu")
		(net "M_E_CPU1_SA_DQS_DP<1>")
	)
	(segment
		(start 65.00622 -213.529926)
		(end 69.233288 -217.756994)
		(width 0.16002)
		(layer "In6.Cu")
		(net "M_E_CPU1_SA_DQS_DP<1>")
	)
	(segment
		(start 77.049376 -229.626414)
		(end 77.478636 -230.055674)
		(width 0.09525)
		(layer "In6.Cu")
		(net "M_E_CPU1_SA_DQS_DP<1>")
	)
	(segment
		(start 37.555932 -209.360262)
		(end 38.405816 -210.210146)
		(width 0.16002)
		(layer "In6.Cu")
		(net "M_E_CPU1_SA_DQS_DP<1>")
	)
	(segment
		(start 35.911028 -209.360262)
		(end 37.555932 -209.360262)
		(width 0.16002)
		(layer "In6.Cu")
		(net "M_E_CPU1_SA_DQS_DP<1>")
	)
	(segment
		(start 41.266872 -210.719924)
		(end 41.67886 -210.719924)
		(width 0.16002)
		(layer "In6.Cu")
		(net "M_E_CPU1_SA_DQS_DP<1>")
	)
	(segment
		(start 50.233834 -209.709004)
		(end 50.65014 -209.709004)
		(width 0.16002)
		(layer "In6.Cu")
		(net "M_E_CPU1_SA_DQS_DP<1>")
	)
	(segment
		(start 33.900364 -210.539584)
		(end 34.286952 -210.539584)
		(width 0.16002)
		(layer "In6.Cu")
		(net "M_E_CPU1_SA_DQS_DP<1>")
	)
	(segment
		(start 52.781962 -209.360262)
		(end 53.742844 -210.321144)
		(width 0.16002)
		(layer "In6.Cu")
		(net "M_E_CPU1_SA_DQS_DP<1>")
	)
	(segment
		(start 75.776836 -228.712014)
		(end 75.7936 -228.728778)
		(width 0.09525)
		(layer "In6.Cu")
		(net "M_E_CPU1_SA_DQS_DP<1>")
	)
	(segment
		(start 49.139094 -210.803744)
		(end 50.233834 -209.709004)
		(width 0.16002)
		(layer "In6.Cu")
		(net "M_E_CPU1_SA_DQS_DP<1>")
	)
	(segment
		(start 61.511942 -210.618832)
		(end 61.511942 -211.095336)
		(width 0.16002)
		(layer "In6.Cu")
		(net "M_E_CPU1_SA_DQS_DP<1>")
	)
	(segment
		(start 60.602368 -210.185762)
		(end 61.078872 -210.185762)
		(width 0.16002)
		(layer "In6.Cu")
		(net "M_E_CPU1_SA_DQS_DP<1>")
	)
	(segment
		(start 45.237908 -209.360262)
		(end 46.087792 -210.210146)
		(width 0.16002)
		(layer "In6.Cu")
		(net "M_E_CPU1_SA_DQS_DP<1>")
	)
	(segment
		(start 69.233288 -221.344236)
		(end 71.42353 -223.534478)
		(width 0.16002)
		(layer "In6.Cu")
		(net "M_E_CPU1_SA_DQS_DP<1>")
	)
	(segment
		(start 71.42353 -223.534478)
		(end 71.42353 -224.358708)
		(width 0.16002)
		(layer "In6.Cu")
		(net "M_E_CPU1_SA_DQS_DP<1>")
	)
	(segment
		(start 35.562286 -209.709004)
		(end 35.911028 -209.360262)
		(width 0.16002)
		(layer "In6.Cu")
		(net "M_E_CPU1_SA_DQS_DP<1>")
	)
	(segment
		(start 80.891888 -231.876346)
		(end 80.915002 -231.789732)
		(width 0.09525)
		(layer "In6.Cu")
		(net "M_E_CPU1_SA_DQS_DP<1>")
	)
	(segment
		(start 59.833764 -210.728306)
		(end 60.059824 -210.728306)
		(width 0.16002)
		(layer "In6.Cu")
		(net "M_E_CPU1_SA_DQS_DP<1>")
	)
	(segment
		(start 60.969398 -211.86394)
		(end 61.224922 -212.119464)
		(width 0.16002)
		(layer "In6.Cu")
		(net "M_E_CPU1_SA_DQS_DP<1>")
	)
	(segment
		(start 48.18634 -210.210146)
		(end 48.779938 -210.803744)
		(width 0.16002)
		(layer "In6.Cu")
		(net "M_E_CPU1_SA_DQS_DP<1>")
	)
	(segment
		(start 34.286952 -210.539584)
		(end 35.117532 -209.709004)
		(width 0.16002)
		(layer "In6.Cu")
		(net "M_E_CPU1_SA_DQS_DP<1>")
	)
	(segment
		(start 61.224922 -212.119464)
		(end 61.450982 -212.119464)
		(width 0.16002)
		(layer "In6.Cu")
		(net "M_E_CPU1_SA_DQS_DP<1>")
	)
	(segment
		(start 29.525976 -210.359244)
		(end 31.528766 -210.359244)
		(width 0.16002)
		(layer "In6.Cu")
		(net "M_E_CPU1_SA_DQS_DP<1>")
	)
	(segment
		(start 57.777888 -209.709004)
		(end 58.814462 -209.709004)
		(width 0.16002)
		(layer "In6.Cu")
		(net "M_E_CPU1_SA_DQS_DP<1>")
	)
	(segment
		(start 71.42353 -224.358708)
		(end 75.776836 -228.712014)
		(width 0.16002)
		(layer "In6.Cu")
		(net "M_E_CPU1_SA_DQS_DP<1>")
	)
	(segment
		(start 29.252164 -210.085432)
		(end 29.525976 -210.359244)
		(width 0.16002)
		(layer "In6.Cu")
		(net "M_E_CPU1_SA_DQS_DP<1>")
	)
	(segment
		(start 43.106086 -209.709004)
		(end 43.454828 -209.360262)
		(width 0.16002)
		(layer "In6.Cu")
		(net "M_E_CPU1_SA_DQS_DP<1>")
	)
	(segment
		(start 62.360556 -213.255098)
		(end 62.635384 -213.529926)
		(width 0.16002)
		(layer "In6.Cu")
		(net "M_E_CPU1_SA_DQS_DP<1>")
	)
	(segment
		(start 58.814462 -209.709004)
		(end 59.833764 -210.728306)
		(width 0.16002)
		(layer "In6.Cu")
		(net "M_E_CPU1_SA_DQS_DP<1>")
	)
	(segment
		(start 46.087792 -210.210146)
		(end 48.18634 -210.210146)
		(width 0.16002)
		(layer "In6.Cu")
		(net "M_E_CPU1_SA_DQS_DP<1>")
	)
	(segment
		(start 31.677864 -210.210146)
		(end 33.570926 -210.210146)
		(width 0.16002)
		(layer "In6.Cu")
		(net "M_E_CPU1_SA_DQS_DP<1>")
	)
	(segment
		(start 61.993526 -211.57692)
		(end 62.47003 -211.57692)
		(width 0.16002)
		(layer "In6.Cu")
		(net "M_E_CPU1_SA_DQS_DP<1>")
	)
	(segment
		(start 40.757094 -210.210146)
		(end 41.266872 -210.719924)
		(width 0.16002)
		(layer "In6.Cu")
		(net "M_E_CPU1_SA_DQS_DP<1>")
	)
	(segment
		(start 53.742844 -210.321144)
		(end 54.591712 -210.321144)
		(width 0.16002)
		(layer "In6.Cu")
		(net "M_E_CPU1_SA_DQS_DP<1>")
	)
	(segment
		(start 54.591712 -210.321144)
		(end 55.241952 -210.971384)
		(width 0.16002)
		(layer "In6.Cu")
		(net "M_E_CPU1_SA_DQS_DP<1>")
	)
	(segment
		(start 79.061564 -231.854248)
		(end 79.069946 -231.849422)
		(width 0.09525)
		(layer "In6.Cu")
		(net "M_E_CPU1_SA_DQS_DP<1>")
	)
	(segment
		(start 62.635384 -213.529926)
		(end 65.00622 -213.529926)
		(width 0.16002)
		(layer "In6.Cu")
		(net "M_E_CPU1_SA_DQS_DP<1>")
	)
	(segment
		(start 79.622142 -231.843326)
		(end 79.632556 -231.849422)
		(width 0.09525)
		(layer "In6.Cu")
		(net "M_E_CPU1_SA_DQS_DP<1>")
	)
	(segment
		(start 62.9031 -212.00999)
		(end 62.9031 -212.486494)
		(width 0.16002)
		(layer "In6.Cu")
		(net "M_E_CPU1_SA_DQS_DP<1>")
	)
	(arc
		(start 79.640938 -231.854248)
		(mid 79.82597 -231.900162)
		(end 80.009746 -231.849422)
		(width 0.09525)
		(layer "In6.Cu")
		(net "M_E_CPU1_SA_DQS_DP<1>")
	)
	(arc
		(start 78.615286 -231.790494)
		(mid 78.652103 -231.82248)
		(end 78.692756 -231.849422)
		(width 0.09525)
		(layer "In6.Cu")
		(net "M_E_CPU1_SA_DQS_DP<1>")
	)
	(arc
		(start 80.009746 -231.849422)
		(mid 80.291178 -231.773667)
		(end 80.57261 -231.849422)
		(width 0.09525)
		(layer "In6.Cu")
		(net "M_E_CPU1_SA_DQS_DP<1>")
	)
	(arc
		(start 78.692756 -231.849422)
		(mid 78.876531 -231.900194)
		(end 79.061564 -231.854248)
		(width 0.09525)
		(layer "In6.Cu")
		(net "M_E_CPU1_SA_DQS_DP<1>")
	)
	(arc
		(start 80.57261 -231.849422)
		(mid 80.729237 -231.898608)
		(end 80.891888 -231.876346)
		(width 0.09525)
		(layer "In6.Cu")
		(net "M_E_CPU1_SA_DQS_DP<1>")
	)
	(arc
		(start 79.069946 -231.849422)
		(mid 79.345235 -231.773701)
		(end 79.622142 -231.843326)
		(width 0.09525)
		(layer "In6.Cu")
		(net "M_E_CPU1_SA_DQS_DP<1>")
	)
	(segment
		(start 81.22793 -226.930458)
		(end 80.761078 -226.66452)
		(width 0.12954)
		(layer "F.Cu")
		(net "M_E_CPU1_SA_DQS_DP<0>")
	)
	(segment
		(start 57.777888 -200.35901)
		(end 58.705496 -200.35901)
		(width 0.16002)
		(layer "In6.Cu")
		(net "M_E_CPU1_SA_DQS_DP<0>")
	)
	(segment
		(start 62.331092 -201.495914)
		(end 62.764162 -201.928984)
		(width 0.16002)
		(layer "In6.Cu")
		(net "M_E_CPU1_SA_DQS_DP<0>")
	)
	(segment
		(start 63.245746 -202.887072)
		(end 63.72225 -202.887072)
		(width 0.16002)
		(layer "In6.Cu")
		(net "M_E_CPU1_SA_DQS_DP<0>")
	)
	(segment
		(start 41.114726 -200.860152)
		(end 41.444164 -201.18959)
		(width 0.16002)
		(layer "In6.Cu")
		(net "M_E_CPU1_SA_DQS_DP<0>")
	)
	(segment
		(start 55.843424 -201.535792)
		(end 56.196992 -201.182224)
		(width 0.16002)
		(layer "In6.Cu")
		(net "M_E_CPU1_SA_DQS_DP<0>")
	)
	(segment
		(start 55.16753 -201.710798)
		(end 55.365396 -201.908664)
		(width 0.16002)
		(layer "In6.Cu")
		(net "M_E_CPU1_SA_DQS_DP<0>")
	)
	(segment
		(start 42.68978 -200.35901)
		(end 43.106086 -200.35901)
		(width 0.16002)
		(layer "In6.Cu")
		(net "M_E_CPU1_SA_DQS_DP<0>")
	)
	(segment
		(start 78.692502 -224.719388)
		(end 78.65999 -224.738184)
		(width 0.09525)
		(layer "In6.Cu")
		(net "M_E_CPU1_SA_DQS_DP<0>")
	)
	(segment
		(start 55.16753 -201.25944)
		(end 55.16753 -201.710798)
		(width 0.16002)
		(layer "In6.Cu")
		(net "M_E_CPU1_SA_DQS_DP<0>")
	)
	(segment
		(start 63.743586 -204.43444)
		(end 63.99911 -204.689964)
		(width 0.16002)
		(layer "In6.Cu")
		(net "M_E_CPU1_SA_DQS_DP<0>")
	)
	(segment
		(start 79.632302 -226.98964)
		(end 79.632556 -226.98964)
		(width 0.09525)
		(layer "In6.Cu")
		(net "M_E_CPU1_SA_DQS_DP<0>")
	)
	(segment
		(start 63.99911 -204.689964)
		(end 64.22517 -204.689964)
		(width 0.16002)
		(layer "In6.Cu")
		(net "M_E_CPU1_SA_DQS_DP<0>")
	)
	(segment
		(start 60.799472 -201.490326)
		(end 61.216794 -201.907648)
		(width 0.16002)
		(layer "In6.Cu")
		(net "M_E_CPU1_SA_DQS_DP<0>")
	)
	(segment
		(start 77.803248 -222.024448)
		(end 77.820012 -222.041212)
		(width 0.09525)
		(layer "In6.Cu")
		(net "M_E_CPU1_SA_DQS_DP<0>")
	)
	(segment
		(start 78.02245 -222.326454)
		(end 78.02245 -222.594678)
		(width 0.09525)
		(layer "In6.Cu")
		(net "M_E_CPU1_SA_DQS_DP<0>")
	)
	(segment
		(start 55.843424 -201.710798)
		(end 55.843424 -201.535792)
		(width 0.16002)
		(layer "In6.Cu")
		(net "M_E_CPU1_SA_DQS_DP<0>")
	)
	(segment
		(start 53.64734 -200.875646)
		(end 54.783736 -200.875646)
		(width 0.16002)
		(layer "In6.Cu")
		(net "M_E_CPU1_SA_DQS_DP<0>")
	)
	(segment
		(start 58.705496 -200.35901)
		(end 59.836812 -201.490326)
		(width 0.16002)
		(layer "In6.Cu")
		(net "M_E_CPU1_SA_DQS_DP<0>")
	)
	(segment
		(start 75.06081 -215.08212)
		(end 75.06081 -219.28201)
		(width 0.16002)
		(layer "In6.Cu")
		(net "M_E_CPU1_SA_DQS_DP<0>")
	)
	(segment
		(start 45.237908 -200.010268)
		(end 46.087792 -200.860152)
		(width 0.16002)
		(layer "In6.Cu")
		(net "M_E_CPU1_SA_DQS_DP<0>")
	)
	(segment
		(start 31.685484 -200.860152)
		(end 33.570926 -200.860152)
		(width 0.16002)
		(layer "In6.Cu")
		(net "M_E_CPU1_SA_DQS_DP<0>")
	)
	(segment
		(start 34.286952 -201.18959)
		(end 35.117532 -200.35901)
		(width 0.16002)
		(layer "In6.Cu")
		(net "M_E_CPU1_SA_DQS_DP<0>")
	)
	(segment
		(start 48.988218 -201.18959)
		(end 49.403254 -201.18959)
		(width 0.16002)
		(layer "In6.Cu")
		(net "M_E_CPU1_SA_DQS_DP<0>")
	)
	(segment
		(start 64.15532 -203.320142)
		(end 64.15532 -203.796646)
		(width 0.16002)
		(layer "In6.Cu")
		(net "M_E_CPU1_SA_DQS_DP<0>")
	)
	(segment
		(start 80.915002 -226.92995)
		(end 80.761078 -226.66452)
		(width 0.09525)
		(layer "In6.Cu")
		(net "M_E_CPU1_SA_DQS_DP<0>")
	)
	(segment
		(start 77.820012 -222.124016)
		(end 78.02245 -222.326454)
		(width 0.09525)
		(layer "In6.Cu")
		(net "M_E_CPU1_SA_DQS_DP<0>")
	)
	(segment
		(start 31.536386 -201.00925)
		(end 31.685484 -200.860152)
		(width 0.16002)
		(layer "In6.Cu")
		(net "M_E_CPU1_SA_DQS_DP<0>")
	)
	(segment
		(start 35.911028 -200.010268)
		(end 37.567108 -200.010268)
		(width 0.16002)
		(layer "In6.Cu")
		(net "M_E_CPU1_SA_DQS_DP<0>")
	)
	(segment
		(start 50.233834 -200.35901)
		(end 50.65014 -200.35901)
		(width 0.16002)
		(layer "In6.Cu")
		(net "M_E_CPU1_SA_DQS_DP<0>")
	)
	(segment
		(start 65.113408 -204.27823)
		(end 65.546478 -204.7113)
		(width 0.16002)
		(layer "In6.Cu")
		(net "M_E_CPU1_SA_DQS_DP<0>")
	)
	(segment
		(start 35.562286 -200.35901)
		(end 35.911028 -200.010268)
		(width 0.16002)
		(layer "In6.Cu")
		(net "M_E_CPU1_SA_DQS_DP<0>")
	)
	(segment
		(start 33.900364 -201.18959)
		(end 34.286952 -201.18959)
		(width 0.16002)
		(layer "In6.Cu")
		(net "M_E_CPU1_SA_DQS_DP<0>")
	)
	(segment
		(start 56.196992 -201.182224)
		(end 56.954674 -201.182224)
		(width 0.16002)
		(layer "In6.Cu")
		(net "M_E_CPU1_SA_DQS_DP<0>")
	)
	(segment
		(start 59.836812 -201.490326)
		(end 60.799472 -201.490326)
		(width 0.16002)
		(layer "In6.Cu")
		(net "M_E_CPU1_SA_DQS_DP<0>")
	)
	(segment
		(start 41.444164 -201.18959)
		(end 41.8592 -201.18959)
		(width 0.16002)
		(layer "In6.Cu")
		(net "M_E_CPU1_SA_DQS_DP<0>")
	)
	(segment
		(start 29.252164 -200.735438)
		(end 29.525976 -201.00925)
		(width 0.16002)
		(layer "In6.Cu")
		(net "M_E_CPU1_SA_DQS_DP<0>")
	)
	(segment
		(start 48.65878 -200.860152)
		(end 48.988218 -201.18959)
		(width 0.16002)
		(layer "In6.Cu")
		(net "M_E_CPU1_SA_DQS_DP<0>")
	)
	(segment
		(start 50.65014 -200.35901)
		(end 50.998882 -200.010268)
		(width 0.16002)
		(layer "In6.Cu")
		(net "M_E_CPU1_SA_DQS_DP<0>")
	)
	(segment
		(start 62.764162 -202.405488)
		(end 62.352428 -202.817222)
		(width 0.16002)
		(layer "In6.Cu")
		(net "M_E_CPU1_SA_DQS_DP<0>")
	)
	(segment
		(start 41.8592 -201.18959)
		(end 42.68978 -200.35901)
		(width 0.16002)
		(layer "In6.Cu")
		(net "M_E_CPU1_SA_DQS_DP<0>")
	)
	(segment
		(start 54.783736 -200.875646)
		(end 55.16753 -201.25944)
		(width 0.16002)
		(layer "In6.Cu")
		(net "M_E_CPU1_SA_DQS_DP<0>")
	)
	(segment
		(start 65.134744 -205.825598)
		(end 65.986152 -206.677006)
		(width 0.16002)
		(layer "In6.Cu")
		(net "M_E_CPU1_SA_DQS_DP<0>")
	)
	(segment
		(start 80.891888 -227.016564)
		(end 80.915002 -226.92995)
		(width 0.09525)
		(layer "In6.Cu")
		(net "M_E_CPU1_SA_DQS_DP<0>")
	)
	(segment
		(start 78.237842 -222.949262)
		(end 78.258924 -222.960946)
		(width 0.09525)
		(layer "In6.Cu")
		(net "M_E_CPU1_SA_DQS_DP<0>")
	)
	(segment
		(start 61.442854 -201.907648)
		(end 61.854588 -201.495914)
		(width 0.16002)
		(layer "In6.Cu")
		(net "M_E_CPU1_SA_DQS_DP<0>")
	)
	(segment
		(start 66.655696 -206.677006)
		(end 75.06081 -215.08212)
		(width 0.16002)
		(layer "In6.Cu")
		(net "M_E_CPU1_SA_DQS_DP<0>")
	)
	(segment
		(start 64.15532 -203.796646)
		(end 63.743586 -204.20838)
		(width 0.16002)
		(layer "In6.Cu")
		(net "M_E_CPU1_SA_DQS_DP<0>")
	)
	(segment
		(start 64.22517 -204.689964)
		(end 64.636904 -204.27823)
		(width 0.16002)
		(layer "In6.Cu")
		(net "M_E_CPU1_SA_DQS_DP<0>")
	)
	(segment
		(start 65.546478 -205.187804)
		(end 65.134744 -205.599538)
		(width 0.16002)
		(layer "In6.Cu")
		(net "M_E_CPU1_SA_DQS_DP<0>")
	)
	(segment
		(start 55.645558 -201.908664)
		(end 55.843424 -201.710798)
		(width 0.16002)
		(layer "In6.Cu")
		(net "M_E_CPU1_SA_DQS_DP<0>")
	)
	(segment
		(start 43.454828 -200.010268)
		(end 45.237908 -200.010268)
		(width 0.16002)
		(layer "In6.Cu")
		(net "M_E_CPU1_SA_DQS_DP<0>")
	)
	(segment
		(start 62.352428 -202.817222)
		(end 62.352428 -203.043282)
		(width 0.16002)
		(layer "In6.Cu")
		(net "M_E_CPU1_SA_DQS_DP<0>")
	)
	(segment
		(start 29.525976 -201.00925)
		(end 31.536386 -201.00925)
		(width 0.16002)
		(layer "In6.Cu")
		(net "M_E_CPU1_SA_DQS_DP<0>")
	)
	(segment
		(start 78.692502 -225.369628)
		(end 78.730602 -225.391726)
		(width 0.09525)
		(layer "In6.Cu")
		(net "M_E_CPU1_SA_DQS_DP<0>")
	)
	(segment
		(start 33.570926 -200.860152)
		(end 33.900364 -201.18959)
		(width 0.16002)
		(layer "In6.Cu")
		(net "M_E_CPU1_SA_DQS_DP<0>")
	)
	(segment
		(start 55.365396 -201.908664)
		(end 55.645558 -201.908664)
		(width 0.16002)
		(layer "In6.Cu")
		(net "M_E_CPU1_SA_DQS_DP<0>")
	)
	(segment
		(start 46.087792 -200.860152)
		(end 48.65878 -200.860152)
		(width 0.16002)
		(layer "In6.Cu")
		(net "M_E_CPU1_SA_DQS_DP<0>")
	)
	(segment
		(start 61.854588 -201.495914)
		(end 62.331092 -201.495914)
		(width 0.16002)
		(layer "In6.Cu")
		(net "M_E_CPU1_SA_DQS_DP<0>")
	)
	(segment
		(start 78.189582 -222.921322)
		(end 78.237842 -222.949262)
		(width 0.09525)
		(layer "In6.Cu")
		(net "M_E_CPU1_SA_DQS_DP<0>")
	)
	(segment
		(start 75.06081 -219.28201)
		(end 77.803248 -222.024448)
		(width 0.16002)
		(layer "In6.Cu")
		(net "M_E_CPU1_SA_DQS_DP<0>")
	)
	(segment
		(start 63.72225 -202.887072)
		(end 64.15532 -203.320142)
		(width 0.16002)
		(layer "In6.Cu")
		(net "M_E_CPU1_SA_DQS_DP<0>")
	)
	(segment
		(start 61.216794 -201.907648)
		(end 61.442854 -201.907648)
		(width 0.16002)
		(layer "In6.Cu")
		(net "M_E_CPU1_SA_DQS_DP<0>")
	)
	(segment
		(start 56.954674 -201.182224)
		(end 57.777888 -200.35901)
		(width 0.16002)
		(layer "In6.Cu")
		(net "M_E_CPU1_SA_DQS_DP<0>")
	)
	(segment
		(start 79.162402 -226.179634)
		(end 79.200502 -226.201732)
		(width 0.09525)
		(layer "In6.Cu")
		(net "M_E_CPU1_SA_DQS_DP<0>")
	)
	(segment
		(start 49.403254 -201.18959)
		(end 50.233834 -200.35901)
		(width 0.16002)
		(layer "In6.Cu")
		(net "M_E_CPU1_SA_DQS_DP<0>")
	)
	(segment
		(start 78.730602 -224.69729)
		(end 78.692502 -224.719388)
		(width 0.09525)
		(layer "In6.Cu")
		(net "M_E_CPU1_SA_DQS_DP<0>")
	)
	(segment
		(start 65.134744 -205.599538)
		(end 65.134744 -205.825598)
		(width 0.16002)
		(layer "In6.Cu")
		(net "M_E_CPU1_SA_DQS_DP<0>")
	)
	(segment
		(start 65.546478 -204.7113)
		(end 65.546478 -205.187804)
		(width 0.16002)
		(layer "In6.Cu")
		(net "M_E_CPU1_SA_DQS_DP<0>")
	)
	(segment
		(start 62.607952 -203.298806)
		(end 62.834012 -203.298806)
		(width 0.16002)
		(layer "In6.Cu")
		(net "M_E_CPU1_SA_DQS_DP<0>")
	)
	(segment
		(start 65.986152 -206.677006)
		(end 66.655696 -206.677006)
		(width 0.16002)
		(layer "In6.Cu")
		(net "M_E_CPU1_SA_DQS_DP<0>")
	)
	(segment
		(start 78.692502 -223.749616)
		(end 78.730602 -223.771714)
		(width 0.09525)
		(layer "In6.Cu")
		(net "M_E_CPU1_SA_DQS_DP<0>")
	)
	(segment
		(start 50.998882 -200.010268)
		(end 52.781962 -200.010268)
		(width 0.16002)
		(layer "In6.Cu")
		(net "M_E_CPU1_SA_DQS_DP<0>")
	)
	(segment
		(start 43.106086 -200.35901)
		(end 43.454828 -200.010268)
		(width 0.16002)
		(layer "In6.Cu")
		(net "M_E_CPU1_SA_DQS_DP<0>")
	)
	(segment
		(start 63.743586 -204.20838)
		(end 63.743586 -204.43444)
		(width 0.16002)
		(layer "In6.Cu")
		(net "M_E_CPU1_SA_DQS_DP<0>")
	)
	(segment
		(start 78.657704 -223.72955)
		(end 78.692502 -223.749616)
		(width 0.09525)
		(layer "In6.Cu")
		(net "M_E_CPU1_SA_DQS_DP<0>")
	)
	(segment
		(start 38.416992 -200.860152)
		(end 41.114726 -200.860152)
		(width 0.16002)
		(layer "In6.Cu")
		(net "M_E_CPU1_SA_DQS_DP<0>")
	)
	(segment
		(start 37.567108 -200.010268)
		(end 38.416992 -200.860152)
		(width 0.16002)
		(layer "In6.Cu")
		(net "M_E_CPU1_SA_DQS_DP<0>")
	)
	(segment
		(start 52.781962 -200.010268)
		(end 53.64734 -200.875646)
		(width 0.16002)
		(layer "In6.Cu")
		(net "M_E_CPU1_SA_DQS_DP<0>")
	)
	(segment
		(start 62.352428 -203.043282)
		(end 62.607952 -203.298806)
		(width 0.16002)
		(layer "In6.Cu")
		(net "M_E_CPU1_SA_DQS_DP<0>")
	)
	(segment
		(start 79.600806 -226.971352)
		(end 79.632302 -226.98964)
		(width 0.09525)
		(layer "In6.Cu")
		(net "M_E_CPU1_SA_DQS_DP<0>")
	)
	(segment
		(start 62.834012 -203.298806)
		(end 63.245746 -202.887072)
		(width 0.16002)
		(layer "In6.Cu")
		(net "M_E_CPU1_SA_DQS_DP<0>")
	)
	(segment
		(start 79.632556 -226.98964)
		(end 79.640938 -226.994466)
		(width 0.09525)
		(layer "In6.Cu")
		(net "M_E_CPU1_SA_DQS_DP<0>")
	)
	(segment
		(start 77.820012 -222.041212)
		(end 77.820012 -222.124016)
		(width 0.09525)
		(layer "In6.Cu")
		(net "M_E_CPU1_SA_DQS_DP<0>")
	)
	(segment
		(start 64.636904 -204.27823)
		(end 65.113408 -204.27823)
		(width 0.16002)
		(layer "In6.Cu")
		(net "M_E_CPU1_SA_DQS_DP<0>")
	)
	(segment
		(start 35.117532 -200.35901)
		(end 35.562286 -200.35901)
		(width 0.16002)
		(layer "In6.Cu")
		(net "M_E_CPU1_SA_DQS_DP<0>")
	)
	(segment
		(start 78.65999 -225.350832)
		(end 78.692502 -225.369628)
		(width 0.09525)
		(layer "In6.Cu")
		(net "M_E_CPU1_SA_DQS_DP<0>")
	)
	(segment
		(start 62.764162 -201.928984)
		(end 62.764162 -202.405488)
		(width 0.16002)
		(layer "In6.Cu")
		(net "M_E_CPU1_SA_DQS_DP<0>")
	)
	(segment
		(start 79.130906 -226.161346)
		(end 79.162402 -226.179634)
		(width 0.09525)
		(layer "In6.Cu")
		(net "M_E_CPU1_SA_DQS_DP<0>")
	)
	(arc
		(start 78.730602 -225.391726)
		(mid 78.909052 -225.593196)
		(end 78.973426 -225.854514)
		(width 0.09525)
		(layer "In6.Cu")
		(net "M_E_CPU1_SA_DQS_DP<0>")
	)
	(arc
		(start 80.009746 -226.98964)
		(mid 80.291178 -226.913885)
		(end 80.57261 -226.98964)
		(width 0.09525)
		(layer "In6.Cu")
		(net "M_E_CPU1_SA_DQS_DP<0>")
	)
	(arc
		(start 78.65999 -224.738184)
		(mid 78.503258 -225.044508)
		(end 78.65999 -225.350832)
		(width 0.09525)
		(layer "In6.Cu")
		(net "M_E_CPU1_SA_DQS_DP<0>")
	)
	(arc
		(start 79.200502 -226.201732)
		(mid 79.378952 -226.403202)
		(end 79.443326 -226.66452)
		(width 0.09525)
		(layer "In6.Cu")
		(net "M_E_CPU1_SA_DQS_DP<0>")
	)
	(arc
		(start 78.02245 -222.594678)
		(mid 78.066653 -222.778145)
		(end 78.189582 -222.921322)
		(width 0.09525)
		(layer "In6.Cu")
		(net "M_E_CPU1_SA_DQS_DP<0>")
	)
	(arc
		(start 78.503018 -223.424496)
		(mid 78.543894 -223.595518)
		(end 78.657704 -223.72955)
		(width 0.09525)
		(layer "In6.Cu")
		(net "M_E_CPU1_SA_DQS_DP<0>")
	)
	(arc
		(start 79.443326 -226.66452)
		(mid 79.484991 -226.836967)
		(end 79.600806 -226.971352)
		(width 0.09525)
		(layer "In6.Cu")
		(net "M_E_CPU1_SA_DQS_DP<0>")
	)
	(arc
		(start 80.57261 -226.98964)
		(mid 80.729237 -227.038826)
		(end 80.891888 -227.016564)
		(width 0.09525)
		(layer "In6.Cu")
		(net "M_E_CPU1_SA_DQS_DP<0>")
	)
	(arc
		(start 78.258924 -222.960946)
		(mid 78.438296 -223.162541)
		(end 78.503018 -223.424496)
		(width 0.09525)
		(layer "In6.Cu")
		(net "M_E_CPU1_SA_DQS_DP<0>")
	)
	(arc
		(start 78.730602 -223.771714)
		(mid 78.973452 -224.234502)
		(end 78.730602 -224.69729)
		(width 0.09525)
		(layer "In6.Cu")
		(net "M_E_CPU1_SA_DQS_DP<0>")
	)
	(arc
		(start 79.640938 -226.994466)
		(mid 79.82597 -227.04038)
		(end 80.009746 -226.98964)
		(width 0.09525)
		(layer "In6.Cu")
		(net "M_E_CPU1_SA_DQS_DP<0>")
	)
	(arc
		(start 78.973426 -225.854514)
		(mid 79.015091 -226.026961)
		(end 79.130906 -226.161346)
		(width 0.09525)
		(layer "In6.Cu")
		(net "M_E_CPU1_SA_DQS_DP<0>")
	)
	(segment
		(start 82.637884 -247.180354)
		(end 82.171032 -246.914416)
		(width 0.12954)
		(layer "F.Cu")
		(net "M_E_CPU1_SA_DQS_DN<9>")
	)
	(segment
		(start 75.955906 -247.379998)
		(end 75.979528 -247.379998)
		(width 0.09525)
		(layer "In6.Cu")
		(net "M_E_CPU1_SA_DQS_DN<9>")
	)
	(segment
		(start 80.471264 -247.244362)
		(end 80.479646 -247.239536)
		(width 0.09525)
		(layer "In6.Cu")
		(net "M_E_CPU1_SA_DQS_DN<9>")
	)
	(segment
		(start 57.351676 -239.92332)
		(end 57.81802 -240.389664)
		(width 0.16002)
		(layer "In6.Cu")
		(net "M_E_CPU1_SA_DQS_DN<9>")
	)
	(segment
		(start 55.71744 -239.80648)
		(end 55.83428 -239.92332)
		(width 0.16002)
		(layer "In6.Cu")
		(net "M_E_CPU1_SA_DQS_DN<9>")
	)
	(segment
		(start 60.16371 -241.773202)
		(end 65.263014 -246.872506)
		(width 0.16002)
		(layer "In6.Cu")
		(net "M_E_CPU1_SA_DQS_DN<9>")
	)
	(segment
		(start 75.979528 -247.379998)
		(end 76.03871 -247.43918)
		(width 0.09525)
		(layer "In6.Cu")
		(net "M_E_CPU1_SA_DQS_DN<9>")
	)
	(segment
		(start 54.052724 -239.92332)
		(end 55.12054 -239.92332)
		(width 0.16002)
		(layer "In6.Cu")
		(net "M_E_CPU1_SA_DQS_DN<9>")
	)
	(segment
		(start 78.21041 -247.23217)
		(end 78.214982 -247.234964)
		(width 0.09525)
		(layer "In6.Cu")
		(net "M_E_CPU1_SA_DQS_DN<9>")
	)
	(segment
		(start 60.16371 -240.883694)
		(end 60.16371 -241.773202)
		(width 0.16002)
		(layer "In6.Cu")
		(net "M_E_CPU1_SA_DQS_DN<9>")
	)
	(segment
		(start 49.331626 -239.92332)
		(end 50.2158 -239.039146)
		(width 0.16002)
		(layer "In6.Cu")
		(net "M_E_CPU1_SA_DQS_DN<9>")
	)
	(segment
		(start 51.166776 -239.424972)
		(end 52.849526 -239.424972)
		(width 0.16002)
		(layer "In6.Cu")
		(net "M_E_CPU1_SA_DQS_DN<9>")
	)
	(segment
		(start 76.98105 -247.440196)
		(end 77.260196 -247.440196)
		(width 0.09525)
		(layer "In6.Cu")
		(net "M_E_CPU1_SA_DQS_DN<9>")
	)
	(segment
		(start 25.426162 -239.259364)
		(end 27.277314 -239.259364)
		(width 0.16002)
		(layer "In6.Cu")
		(net "M_E_CPU1_SA_DQS_DN<9>")
	)
	(segment
		(start 50.2158 -239.039146)
		(end 50.78095 -239.039146)
		(width 0.16002)
		(layer "In6.Cu")
		(net "M_E_CPU1_SA_DQS_DN<9>")
	)
	(segment
		(start 82.324956 -247.179846)
		(end 82.171032 -246.914416)
		(width 0.09525)
		(layer "In6.Cu")
		(net "M_E_CPU1_SA_DQS_DN<9>")
	)
	(segment
		(start 50.78095 -239.039146)
		(end 51.166776 -239.424972)
		(width 0.16002)
		(layer "In6.Cu")
		(net "M_E_CPU1_SA_DQS_DN<9>")
	)
	(segment
		(start 75.433682 -247.379998)
		(end 75.955906 -247.379998)
		(width 0.16002)
		(layer "In6.Cu")
		(net "M_E_CPU1_SA_DQS_DN<9>")
	)
	(segment
		(start 82.301842 -247.26646)
		(end 82.324956 -247.179846)
		(width 0.09525)
		(layer "In6.Cu")
		(net "M_E_CPU1_SA_DQS_DN<9>")
	)
	(segment
		(start 40.975026 -240.258346)
		(end 41.310052 -239.92332)
		(width 0.16002)
		(layer "In6.Cu")
		(net "M_E_CPU1_SA_DQS_DN<9>")
	)
	(segment
		(start 41.310052 -239.92332)
		(end 41.787572 -239.92332)
		(width 0.16002)
		(layer "In6.Cu")
		(net "M_E_CPU1_SA_DQS_DN<9>")
	)
	(segment
		(start 48.18888 -240.258346)
		(end 48.523906 -239.92332)
		(width 0.16002)
		(layer "In6.Cu")
		(net "M_E_CPU1_SA_DQS_DN<9>")
	)
	(segment
		(start 43.236896 -239.039146)
		(end 43.622722 -239.424972)
		(width 0.16002)
		(layer "In6.Cu")
		(net "M_E_CPU1_SA_DQS_DN<9>")
	)
	(segment
		(start 79.15275 -247.23344)
		(end 79.163164 -247.239536)
		(width 0.09525)
		(layer "In6.Cu")
		(net "M_E_CPU1_SA_DQS_DN<9>")
	)
	(segment
		(start 77.540358 -247.323864)
		(end 77.587856 -247.276112)
		(width 0.09525)
		(layer "In6.Cu")
		(net "M_E_CPU1_SA_DQS_DN<9>")
	)
	(segment
		(start 35.693096 -239.039146)
		(end 36.078922 -239.424972)
		(width 0.16002)
		(layer "In6.Cu")
		(net "M_E_CPU1_SA_DQS_DN<9>")
	)
	(segment
		(start 27.458162 -239.078516)
		(end 28.191714 -239.078516)
		(width 0.16002)
		(layer "In6.Cu")
		(net "M_E_CPU1_SA_DQS_DN<9>")
	)
	(segment
		(start 55.23738 -239.80648)
		(end 55.71744 -239.80648)
		(width 0.16002)
		(layer "In6.Cu")
		(net "M_E_CPU1_SA_DQS_DN<9>")
	)
	(segment
		(start 76.03871 -247.43918)
		(end 76.980034 -247.43918)
		(width 0.09525)
		(layer "In6.Cu")
		(net "M_E_CPU1_SA_DQS_DN<9>")
	)
	(segment
		(start 79.531464 -247.244362)
		(end 79.539846 -247.239536)
		(width 0.09525)
		(layer "In6.Cu")
		(net "M_E_CPU1_SA_DQS_DN<9>")
	)
	(segment
		(start 29.684472 -239.424972)
		(end 31.69666 -240.258346)
		(width 0.16002)
		(layer "In6.Cu")
		(net "M_E_CPU1_SA_DQS_DN<9>")
	)
	(segment
		(start 79.539846 -247.239536)
		(end 79.55026 -247.23344)
		(width 0.09525)
		(layer "In6.Cu")
		(net "M_E_CPU1_SA_DQS_DN<9>")
	)
	(segment
		(start 28.53817 -239.424972)
		(end 29.684472 -239.424972)
		(width 0.16002)
		(layer "In6.Cu")
		(net "M_E_CPU1_SA_DQS_DN<9>")
	)
	(segment
		(start 57.81802 -240.389664)
		(end 59.66968 -240.389664)
		(width 0.16002)
		(layer "In6.Cu")
		(net "M_E_CPU1_SA_DQS_DN<9>")
	)
	(segment
		(start 27.277314 -239.259364)
		(end 27.458162 -239.078516)
		(width 0.16002)
		(layer "In6.Cu")
		(net "M_E_CPU1_SA_DQS_DN<9>")
	)
	(segment
		(start 34.243772 -239.92332)
		(end 35.127946 -239.039146)
		(width 0.16002)
		(layer "In6.Cu")
		(net "M_E_CPU1_SA_DQS_DN<9>")
	)
	(segment
		(start 81.04251 -247.239536)
		(end 81.050892 -247.244362)
		(width 0.09525)
		(layer "In6.Cu")
		(net "M_E_CPU1_SA_DQS_DN<9>")
	)
	(segment
		(start 33.766252 -239.92332)
		(end 34.243772 -239.92332)
		(width 0.16002)
		(layer "In6.Cu")
		(net "M_E_CPU1_SA_DQS_DN<9>")
	)
	(segment
		(start 78.214982 -247.234964)
		(end 78.237334 -247.247918)
		(width 0.09525)
		(layer "In6.Cu")
		(net "M_E_CPU1_SA_DQS_DN<9>")
	)
	(segment
		(start 55.12054 -239.92332)
		(end 55.23738 -239.80648)
		(width 0.16002)
		(layer "In6.Cu")
		(net "M_E_CPU1_SA_DQS_DN<9>")
	)
	(segment
		(start 37.195252 -239.424972)
		(end 39.20744 -240.258346)
		(width 0.16002)
		(layer "In6.Cu")
		(net "M_E_CPU1_SA_DQS_DN<9>")
	)
	(segment
		(start 36.078922 -239.424972)
		(end 37.195252 -239.424972)
		(width 0.16002)
		(layer "In6.Cu")
		(net "M_E_CPU1_SA_DQS_DN<9>")
	)
	(segment
		(start 46.843696 -240.258346)
		(end 48.18888 -240.258346)
		(width 0.16002)
		(layer "In6.Cu")
		(net "M_E_CPU1_SA_DQS_DN<9>")
	)
	(segment
		(start 33.431226 -240.258346)
		(end 33.766252 -239.92332)
		(width 0.16002)
		(layer "In6.Cu")
		(net "M_E_CPU1_SA_DQS_DN<9>")
	)
	(segment
		(start 43.622722 -239.424972)
		(end 44.831508 -239.424972)
		(width 0.16002)
		(layer "In6.Cu")
		(net "M_E_CPU1_SA_DQS_DN<9>")
	)
	(segment
		(start 59.66968 -240.389664)
		(end 60.16371 -240.883694)
		(width 0.16002)
		(layer "In6.Cu")
		(net "M_E_CPU1_SA_DQS_DN<9>")
	)
	(segment
		(start 35.127946 -239.039146)
		(end 35.693096 -239.039146)
		(width 0.16002)
		(layer "In6.Cu")
		(net "M_E_CPU1_SA_DQS_DN<9>")
	)
	(segment
		(start 65.263014 -246.872506)
		(end 74.92619 -246.872506)
		(width 0.16002)
		(layer "In6.Cu")
		(net "M_E_CPU1_SA_DQS_DN<9>")
	)
	(segment
		(start 42.671746 -239.039146)
		(end 43.236896 -239.039146)
		(width 0.16002)
		(layer "In6.Cu")
		(net "M_E_CPU1_SA_DQS_DN<9>")
	)
	(segment
		(start 76.980034 -247.43918)
		(end 76.98105 -247.440196)
		(width 0.09525)
		(layer "In6.Cu")
		(net "M_E_CPU1_SA_DQS_DN<9>")
	)
	(segment
		(start 28.191714 -239.078516)
		(end 28.53817 -239.424972)
		(width 0.16002)
		(layer "In6.Cu")
		(net "M_E_CPU1_SA_DQS_DN<9>")
	)
	(segment
		(start 44.831508 -239.424972)
		(end 46.843696 -240.258346)
		(width 0.16002)
		(layer "In6.Cu")
		(net "M_E_CPU1_SA_DQS_DN<9>")
	)
	(segment
		(start 25.152096 -238.985298)
		(end 25.426162 -239.259364)
		(width 0.16002)
		(layer "In6.Cu")
		(net "M_E_CPU1_SA_DQS_DN<9>")
	)
	(segment
		(start 48.523906 -239.92332)
		(end 49.331626 -239.92332)
		(width 0.16002)
		(layer "In6.Cu")
		(net "M_E_CPU1_SA_DQS_DN<9>")
	)
	(segment
		(start 55.83428 -239.92332)
		(end 57.351676 -239.92332)
		(width 0.16002)
		(layer "In6.Cu")
		(net "M_E_CPU1_SA_DQS_DN<9>")
	)
	(segment
		(start 41.787572 -239.92332)
		(end 42.671746 -239.039146)
		(width 0.16002)
		(layer "In6.Cu")
		(net "M_E_CPU1_SA_DQS_DN<9>")
	)
	(segment
		(start 52.849526 -239.424972)
		(end 54.052724 -239.92332)
		(width 0.16002)
		(layer "In6.Cu")
		(net "M_E_CPU1_SA_DQS_DN<9>")
	)
	(segment
		(start 74.92619 -246.872506)
		(end 75.433682 -247.379998)
		(width 0.16002)
		(layer "In6.Cu")
		(net "M_E_CPU1_SA_DQS_DN<9>")
	)
	(segment
		(start 78.209902 -247.232678)
		(end 78.21041 -247.23217)
		(width 0.09525)
		(layer "In6.Cu")
		(net "M_E_CPU1_SA_DQS_DN<9>")
	)
	(segment
		(start 39.20744 -240.258346)
		(end 40.975026 -240.258346)
		(width 0.16002)
		(layer "In6.Cu")
		(net "M_E_CPU1_SA_DQS_DN<9>")
	)
	(segment
		(start 31.69666 -240.258346)
		(end 33.431226 -240.258346)
		(width 0.16002)
		(layer "In6.Cu")
		(net "M_E_CPU1_SA_DQS_DN<9>")
	)
	(arc
		(start 80.479646 -247.239536)
		(mid 80.761078 -247.163781)
		(end 81.04251 -247.239536)
		(width 0.09525)
		(layer "In6.Cu")
		(net "M_E_CPU1_SA_DQS_DN<9>")
	)
	(arc
		(start 79.55026 -247.23344)
		(mid 79.827168 -247.163763)
		(end 80.102456 -247.239536)
		(width 0.09525)
		(layer "In6.Cu")
		(net "M_E_CPU1_SA_DQS_DN<9>")
	)
	(arc
		(start 78.237334 -247.247918)
		(mid 78.419766 -247.290358)
		(end 78.600046 -247.239536)
		(width 0.09525)
		(layer "In6.Cu")
		(net "M_E_CPU1_SA_DQS_DN<9>")
	)
	(arc
		(start 77.260196 -247.440196)
		(mid 77.411871 -247.409954)
		(end 77.540358 -247.323864)
		(width 0.09525)
		(layer "In6.Cu")
		(net "M_E_CPU1_SA_DQS_DN<9>")
	)
	(arc
		(start 81.982564 -247.239536)
		(mid 82.139191 -247.288722)
		(end 82.301842 -247.26646)
		(width 0.09525)
		(layer "In6.Cu")
		(net "M_E_CPU1_SA_DQS_DN<9>")
	)
	(arc
		(start 77.729588 -247.199658)
		(mid 77.760958 -247.192563)
		(end 77.792072 -247.184418)
		(width 0.09525)
		(layer "In6.Cu")
		(net "M_E_CPU1_SA_DQS_DN<9>")
	)
	(arc
		(start 81.050892 -247.244362)
		(mid 81.235924 -247.290276)
		(end 81.4197 -247.239536)
		(width 0.09525)
		(layer "In6.Cu")
		(net "M_E_CPU1_SA_DQS_DN<9>")
	)
	(arc
		(start 81.4197 -247.239536)
		(mid 81.701132 -247.163781)
		(end 81.982564 -247.239536)
		(width 0.09525)
		(layer "In6.Cu")
		(net "M_E_CPU1_SA_DQS_DN<9>")
	)
	(arc
		(start 79.163164 -247.239536)
		(mid 79.346685 -247.29018)
		(end 79.531464 -247.244362)
		(width 0.09525)
		(layer "In6.Cu")
		(net "M_E_CPU1_SA_DQS_DN<9>")
	)
	(arc
		(start 77.792072 -247.184418)
		(mid 78.005689 -247.167835)
		(end 78.209902 -247.232678)
		(width 0.09525)
		(layer "In6.Cu")
		(net "M_E_CPU1_SA_DQS_DN<9>")
	)
	(arc
		(start 78.600046 -247.239536)
		(mid 78.875589 -247.163687)
		(end 79.15275 -247.23344)
		(width 0.09525)
		(layer "In6.Cu")
		(net "M_E_CPU1_SA_DQS_DN<9>")
	)
	(arc
		(start 80.102456 -247.239536)
		(mid 80.286231 -247.290308)
		(end 80.471264 -247.244362)
		(width 0.09525)
		(layer "In6.Cu")
		(net "M_E_CPU1_SA_DQS_DN<9>")
	)
	(arc
		(start 77.587856 -247.276112)
		(mid 77.653103 -247.227475)
		(end 77.729588 -247.199658)
		(width 0.09525)
		(layer "In6.Cu")
		(net "M_E_CPU1_SA_DQS_DN<9>")
	)
	(segment
		(start 82.637884 -242.320318)
		(end 82.171032 -242.05438)
		(width 0.12954)
		(layer "F.Cu")
		(net "M_E_CPU1_SA_DQS_DN<8>")
	)
	(segment
		(start 53.005736 -229.941374)
		(end 53.122576 -230.058214)
		(width 0.16002)
		(layer "In6.Cu")
		(net "M_E_CPU1_SA_DQS_DN<8>")
	)
	(segment
		(start 75.955906 -241.282474)
		(end 75.979528 -241.282474)
		(width 0.09525)
		(layer "In6.Cu")
		(net "M_E_CPU1_SA_DQS_DN<8>")
	)
	(segment
		(start 25.152096 -229.635304)
		(end 25.426162 -229.90937)
		(width 0.16002)
		(layer "In6.Cu")
		(net "M_E_CPU1_SA_DQS_DN<8>")
	)
	(segment
		(start 46.90872 -230.908352)
		(end 48.51908 -230.908352)
		(width 0.16002)
		(layer "In6.Cu")
		(net "M_E_CPU1_SA_DQS_DN<8>")
	)
	(segment
		(start 63.704216 -235.446824)
		(end 69.539866 -241.282474)
		(width 0.16002)
		(layer "In6.Cu")
		(net "M_E_CPU1_SA_DQS_DN<8>")
	)
	(segment
		(start 79.539846 -242.3795)
		(end 79.55026 -242.373404)
		(width 0.09525)
		(layer "In6.Cu")
		(net "M_E_CPU1_SA_DQS_DN<8>")
	)
	(segment
		(start 30.537404 -230.074978)
		(end 31.204662 -230.351584)
		(width 0.16002)
		(layer "In6.Cu")
		(net "M_E_CPU1_SA_DQS_DN<8>")
	)
	(segment
		(start 52.408836 -230.058214)
		(end 52.525676 -229.941374)
		(width 0.16002)
		(layer "In6.Cu")
		(net "M_E_CPU1_SA_DQS_DN<8>")
	)
	(segment
		(start 28.81122 -230.074978)
		(end 30.537404 -230.074978)
		(width 0.16002)
		(layer "In6.Cu")
		(net "M_E_CPU1_SA_DQS_DN<8>")
	)
	(segment
		(start 31.433262 -230.580184)
		(end 32.225488 -230.908352)
		(width 0.16002)
		(layer "In6.Cu")
		(net "M_E_CPU1_SA_DQS_DN<8>")
	)
	(segment
		(start 48.51908 -230.908352)
		(end 48.854106 -230.573326)
		(width 0.16002)
		(layer "In6.Cu")
		(net "M_E_CPU1_SA_DQS_DN<8>")
	)
	(segment
		(start 34.243772 -230.573326)
		(end 35.127946 -229.689152)
		(width 0.16002)
		(layer "In6.Cu")
		(net "M_E_CPU1_SA_DQS_DN<8>")
	)
	(segment
		(start 27.503882 -229.728522)
		(end 27.974798 -229.728522)
		(width 0.16002)
		(layer "In6.Cu")
		(net "M_E_CPU1_SA_DQS_DN<8>")
	)
	(segment
		(start 50.78095 -229.689152)
		(end 51.150012 -230.058214)
		(width 0.16002)
		(layer "In6.Cu")
		(net "M_E_CPU1_SA_DQS_DN<8>")
	)
	(segment
		(start 51.150012 -230.058214)
		(end 52.408836 -230.058214)
		(width 0.16002)
		(layer "In6.Cu")
		(net "M_E_CPU1_SA_DQS_DN<8>")
	)
	(segment
		(start 82.301842 -242.406424)
		(end 82.324956 -242.31981)
		(width 0.09525)
		(layer "In6.Cu")
		(net "M_E_CPU1_SA_DQS_DN<8>")
	)
	(segment
		(start 27.974798 -229.728522)
		(end 28.81122 -230.074978)
		(width 0.16002)
		(layer "In6.Cu")
		(net "M_E_CPU1_SA_DQS_DN<8>")
	)
	(segment
		(start 76.22794 -241.341656)
		(end 76.430886 -241.544602)
		(width 0.09525)
		(layer "In6.Cu")
		(net "M_E_CPU1_SA_DQS_DN<8>")
	)
	(segment
		(start 77.832458 -242.303808)
		(end 77.941678 -242.303808)
		(width 0.09525)
		(layer "In6.Cu")
		(net "M_E_CPU1_SA_DQS_DN<8>")
	)
	(segment
		(start 81.04251 -242.3795)
		(end 81.050892 -242.384326)
		(width 0.09525)
		(layer "In6.Cu")
		(net "M_E_CPU1_SA_DQS_DN<8>")
	)
	(segment
		(start 56.87568 -230.573326)
		(end 57.759854 -229.689152)
		(width 0.16002)
		(layer "In6.Cu")
		(net "M_E_CPU1_SA_DQS_DN<8>")
	)
	(segment
		(start 32.225488 -230.908352)
		(end 32.957262 -230.908352)
		(width 0.16002)
		(layer "In6.Cu")
		(net "M_E_CPU1_SA_DQS_DN<8>")
	)
	(segment
		(start 80.471264 -242.384326)
		(end 80.479646 -242.3795)
		(width 0.09525)
		(layer "In6.Cu")
		(net "M_E_CPU1_SA_DQS_DN<8>")
	)
	(segment
		(start 53.602636 -230.058214)
		(end 54.117748 -230.573326)
		(width 0.16002)
		(layer "In6.Cu")
		(net "M_E_CPU1_SA_DQS_DN<8>")
	)
	(segment
		(start 52.525676 -229.941374)
		(end 53.005736 -229.941374)
		(width 0.16002)
		(layer "In6.Cu")
		(net "M_E_CPU1_SA_DQS_DN<8>")
	)
	(segment
		(start 41.787572 -230.573326)
		(end 42.671746 -229.689152)
		(width 0.16002)
		(layer "In6.Cu")
		(net "M_E_CPU1_SA_DQS_DN<8>")
	)
	(segment
		(start 40.975026 -230.908352)
		(end 41.310052 -230.573326)
		(width 0.16002)
		(layer "In6.Cu")
		(net "M_E_CPU1_SA_DQS_DN<8>")
	)
	(segment
		(start 60.05703 -230.349806)
		(end 62.678564 -232.97134)
		(width 0.16002)
		(layer "In6.Cu")
		(net "M_E_CPU1_SA_DQS_DN<8>")
	)
	(segment
		(start 35.693096 -229.689152)
		(end 36.062158 -230.058214)
		(width 0.16002)
		(layer "In6.Cu")
		(net "M_E_CPU1_SA_DQS_DN<8>")
	)
	(segment
		(start 35.127946 -229.689152)
		(end 35.693096 -229.689152)
		(width 0.16002)
		(layer "In6.Cu")
		(net "M_E_CPU1_SA_DQS_DN<8>")
	)
	(segment
		(start 82.324956 -242.31981)
		(end 82.171032 -242.05438)
		(width 0.09525)
		(layer "In6.Cu")
		(net "M_E_CPU1_SA_DQS_DN<8>")
	)
	(segment
		(start 69.539866 -241.282474)
		(end 75.955906 -241.282474)
		(width 0.16002)
		(layer "In6.Cu")
		(net "M_E_CPU1_SA_DQS_DN<8>")
	)
	(segment
		(start 36.062158 -230.058214)
		(end 38.422326 -230.058214)
		(width 0.16002)
		(layer "In6.Cu")
		(net "M_E_CPU1_SA_DQS_DN<8>")
	)
	(segment
		(start 46.058582 -230.058214)
		(end 46.90872 -230.908352)
		(width 0.16002)
		(layer "In6.Cu")
		(net "M_E_CPU1_SA_DQS_DN<8>")
	)
	(segment
		(start 77.482954 -241.954304)
		(end 77.832458 -242.303808)
		(width 0.09525)
		(layer "In6.Cu")
		(net "M_E_CPU1_SA_DQS_DN<8>")
	)
	(segment
		(start 49.331626 -230.573326)
		(end 50.2158 -229.689152)
		(width 0.16002)
		(layer "In6.Cu")
		(net "M_E_CPU1_SA_DQS_DN<8>")
	)
	(segment
		(start 25.426162 -229.90937)
		(end 27.067256 -229.90937)
		(width 0.16002)
		(layer "In6.Cu")
		(net "M_E_CPU1_SA_DQS_DN<8>")
	)
	(segment
		(start 54.117748 -230.573326)
		(end 56.87568 -230.573326)
		(width 0.16002)
		(layer "In6.Cu")
		(net "M_E_CPU1_SA_DQS_DN<8>")
	)
	(segment
		(start 57.759854 -229.689152)
		(end 58.325004 -229.689152)
		(width 0.16002)
		(layer "In6.Cu")
		(net "M_E_CPU1_SA_DQS_DN<8>")
	)
	(segment
		(start 43.605958 -230.058214)
		(end 46.058582 -230.058214)
		(width 0.16002)
		(layer "In6.Cu")
		(net "M_E_CPU1_SA_DQS_DN<8>")
	)
	(segment
		(start 76.430886 -241.544602)
		(end 76.430886 -241.640106)
		(width 0.09525)
		(layer "In6.Cu")
		(net "M_E_CPU1_SA_DQS_DN<8>")
	)
	(segment
		(start 39.272464 -230.908352)
		(end 40.975026 -230.908352)
		(width 0.16002)
		(layer "In6.Cu")
		(net "M_E_CPU1_SA_DQS_DN<8>")
	)
	(segment
		(start 32.957262 -230.908352)
		(end 33.766252 -230.573326)
		(width 0.16002)
		(layer "In6.Cu")
		(net "M_E_CPU1_SA_DQS_DN<8>")
	)
	(segment
		(start 76.03871 -241.341656)
		(end 76.22794 -241.341656)
		(width 0.09525)
		(layer "In6.Cu")
		(net "M_E_CPU1_SA_DQS_DN<8>")
	)
	(segment
		(start 75.979528 -241.282474)
		(end 76.03871 -241.341656)
		(width 0.09525)
		(layer "In6.Cu")
		(net "M_E_CPU1_SA_DQS_DN<8>")
	)
	(segment
		(start 41.310052 -230.573326)
		(end 41.787572 -230.573326)
		(width 0.16002)
		(layer "In6.Cu")
		(net "M_E_CPU1_SA_DQS_DN<8>")
	)
	(segment
		(start 62.678564 -232.97134)
		(end 63.704216 -235.446824)
		(width 0.16002)
		(layer "In6.Cu")
		(net "M_E_CPU1_SA_DQS_DN<8>")
	)
	(segment
		(start 48.854106 -230.573326)
		(end 49.331626 -230.573326)
		(width 0.16002)
		(layer "In6.Cu")
		(net "M_E_CPU1_SA_DQS_DN<8>")
	)
	(segment
		(start 58.985658 -230.349806)
		(end 60.05703 -230.349806)
		(width 0.16002)
		(layer "In6.Cu")
		(net "M_E_CPU1_SA_DQS_DN<8>")
	)
	(segment
		(start 79.15275 -242.373404)
		(end 79.163164 -242.3795)
		(width 0.09525)
		(layer "In6.Cu")
		(net "M_E_CPU1_SA_DQS_DN<8>")
	)
	(segment
		(start 76.430886 -241.640106)
		(end 76.745084 -241.954304)
		(width 0.09525)
		(layer "In6.Cu")
		(net "M_E_CPU1_SA_DQS_DN<8>")
	)
	(segment
		(start 53.122576 -230.058214)
		(end 53.602636 -230.058214)
		(width 0.16002)
		(layer "In6.Cu")
		(net "M_E_CPU1_SA_DQS_DN<8>")
	)
	(segment
		(start 79.531464 -242.384326)
		(end 79.539846 -242.3795)
		(width 0.09525)
		(layer "In6.Cu")
		(net "M_E_CPU1_SA_DQS_DN<8>")
	)
	(segment
		(start 42.671746 -229.689152)
		(end 43.236896 -229.689152)
		(width 0.16002)
		(layer "In6.Cu")
		(net "M_E_CPU1_SA_DQS_DN<8>")
	)
	(segment
		(start 27.067256 -229.90937)
		(end 27.503882 -229.728522)
		(width 0.16002)
		(layer "In6.Cu")
		(net "M_E_CPU1_SA_DQS_DN<8>")
	)
	(segment
		(start 33.766252 -230.573326)
		(end 34.243772 -230.573326)
		(width 0.16002)
		(layer "In6.Cu")
		(net "M_E_CPU1_SA_DQS_DN<8>")
	)
	(segment
		(start 31.204662 -230.351584)
		(end 31.433262 -230.580184)
		(width 0.16002)
		(layer "In6.Cu")
		(net "M_E_CPU1_SA_DQS_DN<8>")
	)
	(segment
		(start 43.236896 -229.689152)
		(end 43.605958 -230.058214)
		(width 0.16002)
		(layer "In6.Cu")
		(net "M_E_CPU1_SA_DQS_DN<8>")
	)
	(segment
		(start 76.745084 -241.954304)
		(end 77.482954 -241.954304)
		(width 0.09525)
		(layer "In6.Cu")
		(net "M_E_CPU1_SA_DQS_DN<8>")
	)
	(segment
		(start 50.2158 -229.689152)
		(end 50.78095 -229.689152)
		(width 0.16002)
		(layer "In6.Cu")
		(net "M_E_CPU1_SA_DQS_DN<8>")
	)
	(segment
		(start 38.422326 -230.058214)
		(end 39.272464 -230.908352)
		(width 0.16002)
		(layer "In6.Cu")
		(net "M_E_CPU1_SA_DQS_DN<8>")
	)
	(segment
		(start 78.222856 -242.3795)
		(end 78.237334 -242.387882)
		(width 0.09525)
		(layer "In6.Cu")
		(net "M_E_CPU1_SA_DQS_DN<8>")
	)
	(segment
		(start 58.325004 -229.689152)
		(end 58.985658 -230.349806)
		(width 0.16002)
		(layer "In6.Cu")
		(net "M_E_CPU1_SA_DQS_DN<8>")
	)
	(arc
		(start 81.982564 -242.3795)
		(mid 82.139191 -242.428686)
		(end 82.301842 -242.406424)
		(width 0.09525)
		(layer "In6.Cu")
		(net "M_E_CPU1_SA_DQS_DN<8>")
	)
	(arc
		(start 79.55026 -242.373404)
		(mid 79.827168 -242.303727)
		(end 80.102456 -242.3795)
		(width 0.09525)
		(layer "In6.Cu")
		(net "M_E_CPU1_SA_DQS_DN<8>")
	)
	(arc
		(start 78.600046 -242.3795)
		(mid 78.875589 -242.303651)
		(end 79.15275 -242.373404)
		(width 0.09525)
		(layer "In6.Cu")
		(net "M_E_CPU1_SA_DQS_DN<8>")
	)
	(arc
		(start 81.050892 -242.384326)
		(mid 81.235924 -242.43024)
		(end 81.4197 -242.3795)
		(width 0.09525)
		(layer "In6.Cu")
		(net "M_E_CPU1_SA_DQS_DN<8>")
	)
	(arc
		(start 80.102456 -242.3795)
		(mid 80.286231 -242.430272)
		(end 80.471264 -242.384326)
		(width 0.09525)
		(layer "In6.Cu")
		(net "M_E_CPU1_SA_DQS_DN<8>")
	)
	(arc
		(start 77.941678 -242.303808)
		(mid 78.08728 -242.323047)
		(end 78.222856 -242.3795)
		(width 0.09525)
		(layer "In6.Cu")
		(net "M_E_CPU1_SA_DQS_DN<8>")
	)
	(arc
		(start 80.479646 -242.3795)
		(mid 80.761078 -242.303745)
		(end 81.04251 -242.3795)
		(width 0.09525)
		(layer "In6.Cu")
		(net "M_E_CPU1_SA_DQS_DN<8>")
	)
	(arc
		(start 78.237334 -242.387882)
		(mid 78.419766 -242.430322)
		(end 78.600046 -242.3795)
		(width 0.09525)
		(layer "In6.Cu")
		(net "M_E_CPU1_SA_DQS_DN<8>")
	)
	(arc
		(start 79.163164 -242.3795)
		(mid 79.346685 -242.430144)
		(end 79.531464 -242.384326)
		(width 0.09525)
		(layer "In6.Cu")
		(net "M_E_CPU1_SA_DQS_DN<8>")
	)
	(arc
		(start 81.4197 -242.3795)
		(mid 81.701132 -242.303745)
		(end 81.982564 -242.3795)
		(width 0.09525)
		(layer "In6.Cu")
		(net "M_E_CPU1_SA_DQS_DN<8>")
	)
	(segment
		(start 82.637884 -237.460282)
		(end 82.171032 -237.194344)
		(width 0.12954)
		(layer "F.Cu")
		(net "M_E_CPU1_SA_DQS_DN<7>")
	)
	(segment
		(start 46.88713 -221.558104)
		(end 48.088296 -221.558104)
		(width 0.16002)
		(layer "In6.Cu")
		(net "M_E_CPU1_SA_DQS_DN<7>")
	)
	(segment
		(start 65.01511 -226.21621)
		(end 65.01511 -227.245418)
		(width 0.16002)
		(layer "In6.Cu")
		(net "M_E_CPU1_SA_DQS_DN<7>")
	)
	(segment
		(start 82.324956 -237.459774)
		(end 82.171032 -237.194344)
		(width 0.09525)
		(layer "In6.Cu")
		(net "M_E_CPU1_SA_DQS_DN<7>")
	)
	(segment
		(start 28.53182 -220.73997)
		(end 30.392878 -220.73997)
		(width 0.16002)
		(layer "In6.Cu")
		(net "M_E_CPU1_SA_DQS_DN<7>")
	)
	(segment
		(start 34.250122 -221.238318)
		(end 35.134296 -220.354144)
		(width 0.16002)
		(layer "In6.Cu")
		(net "M_E_CPU1_SA_DQS_DN<7>")
	)
	(segment
		(start 77.444346 -236.744002)
		(end 78.202536 -237.502192)
		(width 0.09525)
		(layer "In6.Cu")
		(net "M_E_CPU1_SA_DQS_DN<7>")
	)
	(segment
		(start 36.476686 -220.70822)
		(end 38.40099 -220.70822)
		(width 0.16002)
		(layer "In6.Cu")
		(net "M_E_CPU1_SA_DQS_DN<7>")
	)
	(segment
		(start 81.04251 -237.519464)
		(end 81.050892 -237.52429)
		(width 0.09525)
		(layer "In6.Cu")
		(net "M_E_CPU1_SA_DQS_DN<7>")
	)
	(segment
		(start 57.766204 -220.354398)
		(end 58.318654 -220.354398)
		(width 0.16002)
		(layer "In6.Cu")
		(net "M_E_CPU1_SA_DQS_DN<7>")
	)
	(segment
		(start 82.301842 -237.546388)
		(end 82.324956 -237.459774)
		(width 0.09525)
		(layer "In6.Cu")
		(net "M_E_CPU1_SA_DQS_DN<7>")
	)
	(segment
		(start 39.250874 -221.558104)
		(end 40.47109 -221.558104)
		(width 0.16002)
		(layer "In6.Cu")
		(net "M_E_CPU1_SA_DQS_DN<7>")
	)
	(segment
		(start 61.435488 -221.055184)
		(end 62.66053 -222.280226)
		(width 0.16002)
		(layer "In6.Cu")
		(net "M_E_CPU1_SA_DQS_DN<7>")
	)
	(segment
		(start 79.162656 -237.519464)
		(end 79.163164 -237.519464)
		(width 0.09525)
		(layer "In6.Cu")
		(net "M_E_CPU1_SA_DQS_DN<7>")
	)
	(segment
		(start 49.337976 -221.238318)
		(end 50.22215 -220.354144)
		(width 0.16002)
		(layer "In6.Cu")
		(net "M_E_CPU1_SA_DQS_DN<7>")
	)
	(segment
		(start 33.772602 -221.238318)
		(end 34.250122 -221.238318)
		(width 0.16002)
		(layer "In6.Cu")
		(net "M_E_CPU1_SA_DQS_DN<7>")
	)
	(segment
		(start 58.318654 -220.354398)
		(end 59.01944 -221.055184)
		(width 0.16002)
		(layer "In6.Cu")
		(net "M_E_CPU1_SA_DQS_DN<7>")
	)
	(segment
		(start 75.979528 -235.613956)
		(end 76.03871 -235.673138)
		(width 0.09525)
		(layer "In6.Cu")
		(net "M_E_CPU1_SA_DQS_DN<7>")
	)
	(segment
		(start 35.134296 -220.354144)
		(end 35.621722 -220.354144)
		(width 0.16002)
		(layer "In6.Cu")
		(net "M_E_CPU1_SA_DQS_DN<7>")
	)
	(segment
		(start 76.23556 -235.673138)
		(end 76.646786 -236.084364)
		(width 0.09525)
		(layer "In6.Cu")
		(net "M_E_CPU1_SA_DQS_DN<7>")
	)
	(segment
		(start 79.539846 -237.519464)
		(end 79.55026 -237.513368)
		(width 0.09525)
		(layer "In6.Cu")
		(net "M_E_CPU1_SA_DQS_DN<7>")
	)
	(segment
		(start 42.678096 -220.354144)
		(end 43.230546 -220.354144)
		(width 0.16002)
		(layer "In6.Cu")
		(net "M_E_CPU1_SA_DQS_DN<7>")
	)
	(segment
		(start 26.0985 -220.442282)
		(end 26.57856 -220.442282)
		(width 0.16002)
		(layer "In6.Cu")
		(net "M_E_CPU1_SA_DQS_DN<7>")
	)
	(segment
		(start 30.392878 -220.73997)
		(end 32.367982 -221.558104)
		(width 0.16002)
		(layer "In6.Cu")
		(net "M_E_CPU1_SA_DQS_DN<7>")
	)
	(segment
		(start 59.01944 -221.055184)
		(end 61.435488 -221.055184)
		(width 0.16002)
		(layer "In6.Cu")
		(net "M_E_CPU1_SA_DQS_DN<7>")
	)
	(segment
		(start 46.037246 -220.70822)
		(end 46.88713 -221.558104)
		(width 0.16002)
		(layer "In6.Cu")
		(net "M_E_CPU1_SA_DQS_DN<7>")
	)
	(segment
		(start 75.955906 -235.613956)
		(end 75.979528 -235.613956)
		(width 0.09525)
		(layer "In6.Cu")
		(net "M_E_CPU1_SA_DQS_DN<7>")
	)
	(segment
		(start 76.646786 -236.084364)
		(end 77.061314 -236.084364)
		(width 0.09525)
		(layer "In6.Cu")
		(net "M_E_CPU1_SA_DQS_DN<7>")
	)
	(segment
		(start 77.061314 -236.084364)
		(end 77.408786 -236.431836)
		(width 0.09525)
		(layer "In6.Cu")
		(net "M_E_CPU1_SA_DQS_DN<7>")
	)
	(segment
		(start 25.98166 -220.559122)
		(end 26.0985 -220.442282)
		(width 0.16002)
		(layer "In6.Cu")
		(net "M_E_CPU1_SA_DQS_DN<7>")
	)
	(segment
		(start 44.08551 -220.70822)
		(end 46.037246 -220.70822)
		(width 0.16002)
		(layer "In6.Cu")
		(net "M_E_CPU1_SA_DQS_DN<7>")
	)
	(segment
		(start 41.793922 -221.238318)
		(end 42.678096 -220.354144)
		(width 0.16002)
		(layer "In6.Cu")
		(net "M_E_CPU1_SA_DQS_DN<7>")
	)
	(segment
		(start 33.000442 -221.558104)
		(end 33.772602 -221.238318)
		(width 0.16002)
		(layer "In6.Cu")
		(net "M_E_CPU1_SA_DQS_DN<7>")
	)
	(segment
		(start 62.66053 -223.86163)
		(end 65.01511 -226.21621)
		(width 0.16002)
		(layer "In6.Cu")
		(net "M_E_CPU1_SA_DQS_DN<7>")
	)
	(segment
		(start 62.66053 -222.280226)
		(end 62.66053 -223.86163)
		(width 0.16002)
		(layer "In6.Cu")
		(net "M_E_CPU1_SA_DQS_DN<7>")
	)
	(segment
		(start 76.03871 -235.673138)
		(end 76.23556 -235.673138)
		(width 0.09525)
		(layer "In6.Cu")
		(net "M_E_CPU1_SA_DQS_DN<7>")
	)
	(segment
		(start 43.230546 -220.354144)
		(end 44.08551 -220.70822)
		(width 0.16002)
		(layer "In6.Cu")
		(net "M_E_CPU1_SA_DQS_DN<7>")
	)
	(segment
		(start 48.088296 -221.558104)
		(end 48.860456 -221.238318)
		(width 0.16002)
		(layer "In6.Cu")
		(net "M_E_CPU1_SA_DQS_DN<7>")
	)
	(segment
		(start 26.57856 -220.442282)
		(end 26.6954 -220.559122)
		(width 0.16002)
		(layer "In6.Cu")
		(net "M_E_CPU1_SA_DQS_DN<7>")
	)
	(segment
		(start 25.152096 -220.28531)
		(end 25.425908 -220.559122)
		(width 0.16002)
		(layer "In6.Cu")
		(net "M_E_CPU1_SA_DQS_DN<7>")
	)
	(segment
		(start 50.7746 -220.354144)
		(end 51.128676 -220.70822)
		(width 0.16002)
		(layer "In6.Cu")
		(net "M_E_CPU1_SA_DQS_DN<7>")
	)
	(segment
		(start 51.128676 -220.70822)
		(end 53.581046 -220.70822)
		(width 0.16002)
		(layer "In6.Cu")
		(net "M_E_CPU1_SA_DQS_DN<7>")
	)
	(segment
		(start 77.408786 -236.431836)
		(end 77.408786 -236.65815)
		(width 0.09525)
		(layer "In6.Cu")
		(net "M_E_CPU1_SA_DQS_DN<7>")
	)
	(segment
		(start 54.111398 -221.238572)
		(end 56.88203 -221.238572)
		(width 0.16002)
		(layer "In6.Cu")
		(net "M_E_CPU1_SA_DQS_DN<7>")
	)
	(segment
		(start 41.24325 -221.238318)
		(end 41.793922 -221.238318)
		(width 0.16002)
		(layer "In6.Cu")
		(net "M_E_CPU1_SA_DQS_DN<7>")
	)
	(segment
		(start 32.367982 -221.558104)
		(end 33.000442 -221.558104)
		(width 0.16002)
		(layer "In6.Cu")
		(net "M_E_CPU1_SA_DQS_DN<7>")
	)
	(segment
		(start 50.22215 -220.354144)
		(end 50.7746 -220.354144)
		(width 0.16002)
		(layer "In6.Cu")
		(net "M_E_CPU1_SA_DQS_DN<7>")
	)
	(segment
		(start 40.47109 -221.558104)
		(end 41.24325 -221.238318)
		(width 0.16002)
		(layer "In6.Cu")
		(net "M_E_CPU1_SA_DQS_DN<7>")
	)
	(segment
		(start 27.209242 -220.559122)
		(end 27.37485 -220.393514)
		(width 0.16002)
		(layer "In6.Cu")
		(net "M_E_CPU1_SA_DQS_DN<7>")
	)
	(segment
		(start 48.860456 -221.238318)
		(end 49.337976 -221.238318)
		(width 0.16002)
		(layer "In6.Cu")
		(net "M_E_CPU1_SA_DQS_DN<7>")
	)
	(segment
		(start 28.185364 -220.393514)
		(end 28.53182 -220.73997)
		(width 0.16002)
		(layer "In6.Cu")
		(net "M_E_CPU1_SA_DQS_DN<7>")
	)
	(segment
		(start 35.621722 -220.354144)
		(end 36.476686 -220.70822)
		(width 0.16002)
		(layer "In6.Cu")
		(net "M_E_CPU1_SA_DQS_DN<7>")
	)
	(segment
		(start 65.01511 -227.245418)
		(end 73.383648 -235.613956)
		(width 0.16002)
		(layer "In6.Cu")
		(net "M_E_CPU1_SA_DQS_DN<7>")
	)
	(segment
		(start 79.14767 -237.511336)
		(end 79.162656 -237.519464)
		(width 0.09525)
		(layer "In6.Cu")
		(net "M_E_CPU1_SA_DQS_DN<7>")
	)
	(segment
		(start 38.40099 -220.70822)
		(end 39.250874 -221.558104)
		(width 0.16002)
		(layer "In6.Cu")
		(net "M_E_CPU1_SA_DQS_DN<7>")
	)
	(segment
		(start 53.581046 -220.70822)
		(end 54.111398 -221.238572)
		(width 0.16002)
		(layer "In6.Cu")
		(net "M_E_CPU1_SA_DQS_DN<7>")
	)
	(segment
		(start 73.383648 -235.613956)
		(end 75.955906 -235.613956)
		(width 0.16002)
		(layer "In6.Cu")
		(net "M_E_CPU1_SA_DQS_DN<7>")
	)
	(segment
		(start 26.6954 -220.559122)
		(end 27.209242 -220.559122)
		(width 0.16002)
		(layer "In6.Cu")
		(net "M_E_CPU1_SA_DQS_DN<7>")
	)
	(segment
		(start 80.471264 -237.52429)
		(end 80.479646 -237.519464)
		(width 0.09525)
		(layer "In6.Cu")
		(net "M_E_CPU1_SA_DQS_DN<7>")
	)
	(segment
		(start 27.37485 -220.393514)
		(end 28.185364 -220.393514)
		(width 0.16002)
		(layer "In6.Cu")
		(net "M_E_CPU1_SA_DQS_DN<7>")
	)
	(segment
		(start 25.425908 -220.559122)
		(end 25.98166 -220.559122)
		(width 0.16002)
		(layer "In6.Cu")
		(net "M_E_CPU1_SA_DQS_DN<7>")
	)
	(segment
		(start 79.531464 -237.52429)
		(end 79.539846 -237.519464)
		(width 0.09525)
		(layer "In6.Cu")
		(net "M_E_CPU1_SA_DQS_DN<7>")
	)
	(segment
		(start 56.88203 -221.238572)
		(end 57.766204 -220.354398)
		(width 0.16002)
		(layer "In6.Cu")
		(net "M_E_CPU1_SA_DQS_DN<7>")
	)
	(arc
		(start 78.202536 -237.502192)
		(mid 78.240111 -237.532073)
		(end 78.283562 -237.552484)
		(width 0.09525)
		(layer "In6.Cu")
		(net "M_E_CPU1_SA_DQS_DN<7>")
	)
	(arc
		(start 79.55026 -237.513368)
		(mid 79.827168 -237.443691)
		(end 80.102456 -237.519464)
		(width 0.09525)
		(layer "In6.Cu")
		(net "M_E_CPU1_SA_DQS_DN<7>")
	)
	(arc
		(start 81.982564 -237.519464)
		(mid 82.139191 -237.56865)
		(end 82.301842 -237.546388)
		(width 0.09525)
		(layer "In6.Cu")
		(net "M_E_CPU1_SA_DQS_DN<7>")
	)
	(arc
		(start 79.163164 -237.519464)
		(mid 79.346685 -237.570108)
		(end 79.531464 -237.52429)
		(width 0.09525)
		(layer "In6.Cu")
		(net "M_E_CPU1_SA_DQS_DN<7>")
	)
	(arc
		(start 80.479646 -237.519464)
		(mid 80.761078 -237.443709)
		(end 81.04251 -237.519464)
		(width 0.09525)
		(layer "In6.Cu")
		(net "M_E_CPU1_SA_DQS_DN<7>")
	)
	(arc
		(start 80.102456 -237.519464)
		(mid 80.286231 -237.570236)
		(end 80.471264 -237.52429)
		(width 0.09525)
		(layer "In6.Cu")
		(net "M_E_CPU1_SA_DQS_DN<7>")
	)
	(arc
		(start 78.283562 -237.552484)
		(mid 78.445469 -237.570238)
		(end 78.6003 -237.519718)
		(width 0.09525)
		(layer "In6.Cu")
		(net "M_E_CPU1_SA_DQS_DN<7>")
	)
	(arc
		(start 81.050892 -237.52429)
		(mid 81.235924 -237.570204)
		(end 81.4197 -237.519464)
		(width 0.09525)
		(layer "In6.Cu")
		(net "M_E_CPU1_SA_DQS_DN<7>")
	)
	(arc
		(start 77.408786 -236.65815)
		(mid 77.418043 -236.704598)
		(end 77.444346 -236.744002)
		(width 0.09525)
		(layer "In6.Cu")
		(net "M_E_CPU1_SA_DQS_DN<7>")
	)
	(arc
		(start 78.6003 -237.519718)
		(mid 78.872893 -237.444122)
		(end 79.14767 -237.511336)
		(width 0.09525)
		(layer "In6.Cu")
		(net "M_E_CPU1_SA_DQS_DN<7>")
	)
	(arc
		(start 81.4197 -237.519464)
		(mid 81.701132 -237.443709)
		(end 81.982564 -237.519464)
		(width 0.09525)
		(layer "In6.Cu")
		(net "M_E_CPU1_SA_DQS_DN<7>")
	)
	(segment
		(start 82.637884 -232.600246)
		(end 82.171032 -232.334308)
		(width 0.12954)
		(layer "F.Cu")
		(net "M_E_CPU1_SA_DQS_DN<6>")
	)
	(segment
		(start 81.04251 -232.659428)
		(end 81.050892 -232.664254)
		(width 0.09525)
		(layer "In6.Cu")
		(net "M_E_CPU1_SA_DQS_DN<6>")
	)
	(segment
		(start 51.150266 -211.358226)
		(end 53.602636 -211.358226)
		(width 0.16002)
		(layer "In6.Cu")
		(net "M_E_CPU1_SA_DQS_DN<6>")
	)
	(segment
		(start 48.045116 -212.20811)
		(end 48.854106 -211.873084)
		(width 0.16002)
		(layer "In6.Cu")
		(net "M_E_CPU1_SA_DQS_DN<6>")
	)
	(segment
		(start 48.854106 -211.873084)
		(end 49.331626 -211.873084)
		(width 0.16002)
		(layer "In6.Cu")
		(net "M_E_CPU1_SA_DQS_DN<6>")
	)
	(segment
		(start 25.425908 -211.209128)
		(end 26.946352 -211.209128)
		(width 0.16002)
		(layer "In6.Cu")
		(net "M_E_CPU1_SA_DQS_DN<6>")
	)
	(segment
		(start 77.13345 -231.025446)
		(end 77.56271 -231.454706)
		(width 0.09525)
		(layer "In6.Cu")
		(net "M_E_CPU1_SA_DQS_DN<6>")
	)
	(segment
		(start 80.471264 -232.664254)
		(end 80.479646 -232.659428)
		(width 0.09525)
		(layer "In6.Cu")
		(net "M_E_CPU1_SA_DQS_DN<6>")
	)
	(segment
		(start 79.15275 -232.653332)
		(end 79.163164 -232.659428)
		(width 0.09525)
		(layer "In6.Cu")
		(net "M_E_CPU1_SA_DQS_DN<6>")
	)
	(segment
		(start 30.92831 -211.374736)
		(end 31.761684 -212.20811)
		(width 0.16002)
		(layer "In6.Cu")
		(net "M_E_CPU1_SA_DQS_DN<6>")
	)
	(segment
		(start 38.42258 -211.358226)
		(end 39.272464 -212.20811)
		(width 0.16002)
		(layer "In6.Cu")
		(net "M_E_CPU1_SA_DQS_DN<6>")
	)
	(segment
		(start 28.191714 -211.02828)
		(end 28.53817 -211.374736)
		(width 0.16002)
		(layer "In6.Cu")
		(net "M_E_CPU1_SA_DQS_DN<6>")
	)
	(segment
		(start 76.08316 -230.175816)
		(end 76.93279 -231.025446)
		(width 0.09525)
		(layer "In6.Cu")
		(net "M_E_CPU1_SA_DQS_DN<6>")
	)
	(segment
		(start 75.762104 -229.95382)
		(end 75.778868 -229.970584)
		(width 0.09525)
		(layer "In6.Cu")
		(net "M_E_CPU1_SA_DQS_DN<6>")
	)
	(segment
		(start 28.53817 -211.374736)
		(end 30.92831 -211.374736)
		(width 0.16002)
		(layer "In6.Cu")
		(net "M_E_CPU1_SA_DQS_DN<6>")
	)
	(segment
		(start 50.2158 -210.98891)
		(end 50.78095 -210.98891)
		(width 0.16002)
		(layer "In6.Cu")
		(net "M_E_CPU1_SA_DQS_DN<6>")
	)
	(segment
		(start 57.855866 -212.447886)
		(end 58.43397 -212.447886)
		(width 0.16002)
		(layer "In6.Cu")
		(net "M_E_CPU1_SA_DQS_DN<6>")
	)
	(segment
		(start 36.062412 -211.358226)
		(end 38.42258 -211.358226)
		(width 0.16002)
		(layer "In6.Cu")
		(net "M_E_CPU1_SA_DQS_DN<6>")
	)
	(segment
		(start 64.646048 -214.398606)
		(end 68.34505 -218.097608)
		(width 0.16002)
		(layer "In6.Cu")
		(net "M_E_CPU1_SA_DQS_DN<6>")
	)
	(segment
		(start 40.501062 -212.20811)
		(end 41.310052 -211.873084)
		(width 0.16002)
		(layer "In6.Cu")
		(net "M_E_CPU1_SA_DQS_DN<6>")
	)
	(segment
		(start 25.152096 -210.935316)
		(end 25.425908 -211.209128)
		(width 0.16002)
		(layer "In6.Cu")
		(net "M_E_CPU1_SA_DQS_DN<6>")
	)
	(segment
		(start 35.693096 -210.98891)
		(end 36.062412 -211.358226)
		(width 0.16002)
		(layer "In6.Cu")
		(net "M_E_CPU1_SA_DQS_DN<6>")
	)
	(segment
		(start 46.058836 -211.358226)
		(end 46.90872 -212.20811)
		(width 0.16002)
		(layer "In6.Cu")
		(net "M_E_CPU1_SA_DQS_DN<6>")
	)
	(segment
		(start 49.331626 -211.873084)
		(end 50.2158 -210.98891)
		(width 0.16002)
		(layer "In6.Cu")
		(net "M_E_CPU1_SA_DQS_DN<6>")
	)
	(segment
		(start 79.539846 -232.659428)
		(end 79.55026 -232.653332)
		(width 0.09525)
		(layer "In6.Cu")
		(net "M_E_CPU1_SA_DQS_DN<6>")
	)
	(segment
		(start 39.272464 -212.20811)
		(end 40.501062 -212.20811)
		(width 0.16002)
		(layer "In6.Cu")
		(net "M_E_CPU1_SA_DQS_DN<6>")
	)
	(segment
		(start 82.301842 -232.686352)
		(end 82.324956 -232.599738)
		(width 0.09525)
		(layer "In6.Cu")
		(net "M_E_CPU1_SA_DQS_DN<6>")
	)
	(segment
		(start 68.34505 -218.097608)
		(end 68.34505 -221.690438)
		(width 0.16002)
		(layer "In6.Cu")
		(net "M_E_CPU1_SA_DQS_DN<6>")
	)
	(segment
		(start 54.117748 -211.873338)
		(end 57.281318 -211.873338)
		(width 0.16002)
		(layer "In6.Cu")
		(net "M_E_CPU1_SA_DQS_DN<6>")
	)
	(segment
		(start 53.602636 -211.358226)
		(end 54.117748 -211.873338)
		(width 0.16002)
		(layer "In6.Cu")
		(net "M_E_CPU1_SA_DQS_DN<6>")
	)
	(segment
		(start 79.531464 -232.664254)
		(end 79.539846 -232.659428)
		(width 0.09525)
		(layer "In6.Cu")
		(net "M_E_CPU1_SA_DQS_DN<6>")
	)
	(segment
		(start 43.236896 -210.98891)
		(end 43.606212 -211.358226)
		(width 0.16002)
		(layer "In6.Cu")
		(net "M_E_CPU1_SA_DQS_DN<6>")
	)
	(segment
		(start 43.606212 -211.358226)
		(end 46.058836 -211.358226)
		(width 0.16002)
		(layer "In6.Cu")
		(net "M_E_CPU1_SA_DQS_DN<6>")
	)
	(segment
		(start 68.34505 -221.690438)
		(end 70.55231 -223.897698)
		(width 0.16002)
		(layer "In6.Cu")
		(net "M_E_CPU1_SA_DQS_DN<6>")
	)
	(segment
		(start 77.56271 -231.454706)
		(end 77.56271 -232.008426)
		(width 0.09525)
		(layer "In6.Cu")
		(net "M_E_CPU1_SA_DQS_DN<6>")
	)
	(segment
		(start 75.778868 -229.970584)
		(end 75.778868 -230.015796)
		(width 0.09525)
		(layer "In6.Cu")
		(net "M_E_CPU1_SA_DQS_DN<6>")
	)
	(segment
		(start 34.581592 -211.535264)
		(end 35.127946 -210.98891)
		(width 0.16002)
		(layer "In6.Cu")
		(net "M_E_CPU1_SA_DQS_DN<6>")
	)
	(segment
		(start 31.761684 -212.20811)
		(end 32.957516 -212.20811)
		(width 0.16002)
		(layer "In6.Cu")
		(net "M_E_CPU1_SA_DQS_DN<6>")
	)
	(segment
		(start 42.671746 -210.98891)
		(end 43.236896 -210.98891)
		(width 0.16002)
		(layer "In6.Cu")
		(net "M_E_CPU1_SA_DQS_DN<6>")
	)
	(segment
		(start 58.43397 -212.447886)
		(end 58.73115 -212.150706)
		(width 0.16002)
		(layer "In6.Cu")
		(net "M_E_CPU1_SA_DQS_DN<6>")
	)
	(segment
		(start 76.93279 -231.025446)
		(end 77.13345 -231.025446)
		(width 0.09525)
		(layer "In6.Cu")
		(net "M_E_CPU1_SA_DQS_DN<6>")
	)
	(segment
		(start 35.127946 -210.98891)
		(end 35.693096 -210.98891)
		(width 0.16002)
		(layer "In6.Cu")
		(net "M_E_CPU1_SA_DQS_DN<6>")
	)
	(segment
		(start 60.027566 -212.150706)
		(end 62.275466 -214.398606)
		(width 0.16002)
		(layer "In6.Cu")
		(net "M_E_CPU1_SA_DQS_DN<6>")
	)
	(segment
		(start 70.55231 -224.744026)
		(end 75.762104 -229.95382)
		(width 0.16002)
		(layer "In6.Cu")
		(net "M_E_CPU1_SA_DQS_DN<6>")
	)
	(segment
		(start 26.946352 -211.209128)
		(end 27.382978 -211.02828)
		(width 0.16002)
		(layer "In6.Cu")
		(net "M_E_CPU1_SA_DQS_DN<6>")
	)
	(segment
		(start 41.787572 -211.873084)
		(end 42.671746 -210.98891)
		(width 0.16002)
		(layer "In6.Cu")
		(net "M_E_CPU1_SA_DQS_DN<6>")
	)
	(segment
		(start 75.938888 -230.175816)
		(end 76.08316 -230.175816)
		(width 0.09525)
		(layer "In6.Cu")
		(net "M_E_CPU1_SA_DQS_DN<6>")
	)
	(segment
		(start 27.382978 -211.02828)
		(end 28.191714 -211.02828)
		(width 0.16002)
		(layer "In6.Cu")
		(net "M_E_CPU1_SA_DQS_DN<6>")
	)
	(segment
		(start 77.56271 -232.008426)
		(end 78.1558 -232.601516)
		(width 0.09525)
		(layer "In6.Cu")
		(net "M_E_CPU1_SA_DQS_DN<6>")
	)
	(segment
		(start 46.90872 -212.20811)
		(end 48.045116 -212.20811)
		(width 0.16002)
		(layer "In6.Cu")
		(net "M_E_CPU1_SA_DQS_DN<6>")
	)
	(segment
		(start 50.78095 -210.98891)
		(end 51.150266 -211.358226)
		(width 0.16002)
		(layer "In6.Cu")
		(net "M_E_CPU1_SA_DQS_DN<6>")
	)
	(segment
		(start 75.778868 -230.015796)
		(end 75.938888 -230.175816)
		(width 0.09525)
		(layer "In6.Cu")
		(net "M_E_CPU1_SA_DQS_DN<6>")
	)
	(segment
		(start 62.275466 -214.398606)
		(end 64.646048 -214.398606)
		(width 0.16002)
		(layer "In6.Cu")
		(net "M_E_CPU1_SA_DQS_DN<6>")
	)
	(segment
		(start 57.281318 -211.873338)
		(end 57.855866 -212.447886)
		(width 0.16002)
		(layer "In6.Cu")
		(net "M_E_CPU1_SA_DQS_DN<6>")
	)
	(segment
		(start 32.957516 -212.20811)
		(end 34.581592 -211.535264)
		(width 0.16002)
		(layer "In6.Cu")
		(net "M_E_CPU1_SA_DQS_DN<6>")
	)
	(segment
		(start 58.73115 -212.150706)
		(end 60.027566 -212.150706)
		(width 0.16002)
		(layer "In6.Cu")
		(net "M_E_CPU1_SA_DQS_DN<6>")
	)
	(segment
		(start 41.310052 -211.873084)
		(end 41.787572 -211.873084)
		(width 0.16002)
		(layer "In6.Cu")
		(net "M_E_CPU1_SA_DQS_DN<6>")
	)
	(segment
		(start 82.324956 -232.599738)
		(end 82.171032 -232.334308)
		(width 0.09525)
		(layer "In6.Cu")
		(net "M_E_CPU1_SA_DQS_DN<6>")
	)
	(segment
		(start 70.55231 -223.897698)
		(end 70.55231 -224.744026)
		(width 0.16002)
		(layer "In6.Cu")
		(net "M_E_CPU1_SA_DQS_DN<6>")
	)
	(arc
		(start 78.1558 -232.601516)
		(mid 78.368082 -232.706128)
		(end 78.600046 -232.659428)
		(width 0.09525)
		(layer "In6.Cu")
		(net "M_E_CPU1_SA_DQS_DN<6>")
	)
	(arc
		(start 80.102456 -232.659428)
		(mid 80.286231 -232.7102)
		(end 80.471264 -232.664254)
		(width 0.09525)
		(layer "In6.Cu")
		(net "M_E_CPU1_SA_DQS_DN<6>")
	)
	(arc
		(start 80.479646 -232.659428)
		(mid 80.761078 -232.583673)
		(end 81.04251 -232.659428)
		(width 0.09525)
		(layer "In6.Cu")
		(net "M_E_CPU1_SA_DQS_DN<6>")
	)
	(arc
		(start 78.600046 -232.659428)
		(mid 78.875589 -232.583579)
		(end 79.15275 -232.653332)
		(width 0.09525)
		(layer "In6.Cu")
		(net "M_E_CPU1_SA_DQS_DN<6>")
	)
	(arc
		(start 81.050892 -232.664254)
		(mid 81.235924 -232.710168)
		(end 81.4197 -232.659428)
		(width 0.09525)
		(layer "In6.Cu")
		(net "M_E_CPU1_SA_DQS_DN<6>")
	)
	(arc
		(start 81.982564 -232.659428)
		(mid 82.139191 -232.708614)
		(end 82.301842 -232.686352)
		(width 0.09525)
		(layer "In6.Cu")
		(net "M_E_CPU1_SA_DQS_DN<6>")
	)
	(arc
		(start 79.163164 -232.659428)
		(mid 79.346685 -232.710072)
		(end 79.531464 -232.664254)
		(width 0.09525)
		(layer "In6.Cu")
		(net "M_E_CPU1_SA_DQS_DN<6>")
	)
	(arc
		(start 79.55026 -232.653332)
		(mid 79.827168 -232.583655)
		(end 80.102456 -232.659428)
		(width 0.09525)
		(layer "In6.Cu")
		(net "M_E_CPU1_SA_DQS_DN<6>")
	)
	(arc
		(start 81.4197 -232.659428)
		(mid 81.701132 -232.583673)
		(end 81.982564 -232.659428)
		(width 0.09525)
		(layer "In6.Cu")
		(net "M_E_CPU1_SA_DQS_DN<6>")
	)
	(segment
		(start 82.637884 -227.740464)
		(end 82.171032 -227.474526)
		(width 0.12954)
		(layer "F.Cu")
		(net "M_E_CPU1_SA_DQS_DN<5>")
	)
	(segment
		(start 36.062412 -202.008232)
		(end 38.42258 -202.008232)
		(width 0.16002)
		(layer "In6.Cu")
		(net "M_E_CPU1_SA_DQS_DN<5>")
	)
	(segment
		(start 77.720952 -223.731328)
		(end 77.790548 -223.771714)
		(width 0.09525)
		(layer "In6.Cu")
		(net "M_E_CPU1_SA_DQS_DN<5>")
	)
	(segment
		(start 40.975026 -202.858116)
		(end 41.310052 -202.52309)
		(width 0.16002)
		(layer "In6.Cu")
		(net "M_E_CPU1_SA_DQS_DN<5>")
	)
	(segment
		(start 33.431226 -202.858116)
		(end 33.766252 -202.52309)
		(width 0.16002)
		(layer "In6.Cu")
		(net "M_E_CPU1_SA_DQS_DN<5>")
	)
	(segment
		(start 78.941422 -227.2284)
		(end 79.301594 -227.588826)
		(width 0.09525)
		(layer "In6.Cu")
		(net "M_E_CPU1_SA_DQS_DN<5>")
	)
	(segment
		(start 80.471264 -227.804472)
		(end 80.479646 -227.799646)
		(width 0.09525)
		(layer "In6.Cu")
		(net "M_E_CPU1_SA_DQS_DN<5>")
	)
	(segment
		(start 60.4393 -202.359006)
		(end 65.62598 -207.545686)
		(width 0.16002)
		(layer "In6.Cu")
		(net "M_E_CPU1_SA_DQS_DN<5>")
	)
	(segment
		(start 28.191714 -201.678286)
		(end 28.53817 -202.024742)
		(width 0.16002)
		(layer "In6.Cu")
		(net "M_E_CPU1_SA_DQS_DN<5>")
	)
	(segment
		(start 78.032864 -225.775266)
		(end 78.033118 -225.775012)
		(width 0.09525)
		(layer "In6.Cu")
		(net "M_E_CPU1_SA_DQS_DN<5>")
	)
	(segment
		(start 46.058836 -202.008232)
		(end 46.90872 -202.858116)
		(width 0.16002)
		(layer "In6.Cu")
		(net "M_E_CPU1_SA_DQS_DN<5>")
	)
	(segment
		(start 46.90872 -202.858116)
		(end 48.51908 -202.858116)
		(width 0.16002)
		(layer "In6.Cu")
		(net "M_E_CPU1_SA_DQS_DN<5>")
	)
	(segment
		(start 77.183742 -222.760286)
		(end 77.440536 -223.017334)
		(width 0.09525)
		(layer "In6.Cu")
		(net "M_E_CPU1_SA_DQS_DN<5>")
	)
	(segment
		(start 26.580592 -201.859134)
		(end 27.017218 -201.678286)
		(width 0.16002)
		(layer "In6.Cu")
		(net "M_E_CPU1_SA_DQS_DN<5>")
	)
	(segment
		(start 56.39816 -202.523344)
		(end 57.2135 -202.185524)
		(width 0.16002)
		(layer "In6.Cu")
		(net "M_E_CPU1_SA_DQS_DN<5>")
	)
	(segment
		(start 77.720698 -223.731582)
		(end 77.720952 -223.731328)
		(width 0.09525)
		(layer "In6.Cu")
		(net "M_E_CPU1_SA_DQS_DN<5>")
	)
	(segment
		(start 42.671746 -201.638916)
		(end 43.236896 -201.638916)
		(width 0.16002)
		(layer "In6.Cu")
		(net "M_E_CPU1_SA_DQS_DN<5>")
	)
	(segment
		(start 35.127946 -201.638916)
		(end 35.693096 -201.638916)
		(width 0.16002)
		(layer "In6.Cu")
		(net "M_E_CPU1_SA_DQS_DN<5>")
	)
	(segment
		(start 28.53817 -202.024742)
		(end 30.92831 -202.024742)
		(width 0.16002)
		(layer "In6.Cu")
		(net "M_E_CPU1_SA_DQS_DN<5>")
	)
	(segment
		(start 50.78095 -201.638916)
		(end 51.150266 -202.008232)
		(width 0.16002)
		(layer "In6.Cu")
		(net "M_E_CPU1_SA_DQS_DN<5>")
	)
	(segment
		(start 27.017218 -201.678286)
		(end 28.191714 -201.678286)
		(width 0.16002)
		(layer "In6.Cu")
		(net "M_E_CPU1_SA_DQS_DN<5>")
	)
	(segment
		(start 78.033372 -224.383346)
		(end 78.032864 -224.383346)
		(width 0.09525)
		(layer "In6.Cu")
		(net "M_E_CPU1_SA_DQS_DN<5>")
	)
	(segment
		(start 66.270632 -207.545686)
		(end 74.17435 -215.449404)
		(width 0.16002)
		(layer "In6.Cu")
		(net "M_E_CPU1_SA_DQS_DN<5>")
	)
	(segment
		(start 82.301842 -227.82657)
		(end 82.324956 -227.739956)
		(width 0.09525)
		(layer "In6.Cu")
		(net "M_E_CPU1_SA_DQS_DN<5>")
	)
	(segment
		(start 74.17435 -215.449404)
		(end 74.17435 -219.66809)
		(width 0.16002)
		(layer "In6.Cu")
		(net "M_E_CPU1_SA_DQS_DN<5>")
	)
	(segment
		(start 82.324956 -227.739956)
		(end 82.171032 -227.474526)
		(width 0.09525)
		(layer "In6.Cu")
		(net "M_E_CPU1_SA_DQS_DN<5>")
	)
	(segment
		(start 78.814676 -226.963986)
		(end 78.814676 -226.96424)
		(width 0.09525)
		(layer "In6.Cu")
		(net "M_E_CPU1_SA_DQS_DN<5>")
	)
	(segment
		(start 77.440536 -223.017334)
		(end 77.562964 -223.139762)
		(width 0.09525)
		(layer "In6.Cu")
		(net "M_E_CPU1_SA_DQS_DN<5>")
	)
	(segment
		(start 51.150266 -202.008232)
		(end 53.602636 -202.008232)
		(width 0.16002)
		(layer "In6.Cu")
		(net "M_E_CPU1_SA_DQS_DN<5>")
	)
	(segment
		(start 48.854106 -202.52309)
		(end 49.669446 -202.18527)
		(width 0.16002)
		(layer "In6.Cu")
		(net "M_E_CPU1_SA_DQS_DN<5>")
	)
	(segment
		(start 77.183742 -222.677482)
		(end 77.183742 -222.760286)
		(width 0.09525)
		(layer "In6.Cu")
		(net "M_E_CPU1_SA_DQS_DN<5>")
	)
	(segment
		(start 79.627476 -227.723954)
		(end 79.821278 -227.723954)
		(width 0.09525)
		(layer "In6.Cu")
		(net "M_E_CPU1_SA_DQS_DN<5>")
	)
	(segment
		(start 30.92831 -202.024742)
		(end 31.761684 -202.858116)
		(width 0.16002)
		(layer "In6.Cu")
		(net "M_E_CPU1_SA_DQS_DN<5>")
	)
	(segment
		(start 53.602636 -202.008232)
		(end 54.42204 -202.827636)
		(width 0.16002)
		(layer "In6.Cu")
		(net "M_E_CPU1_SA_DQS_DN<5>")
	)
	(segment
		(start 41.310052 -202.52309)
		(end 42.125392 -202.18527)
		(width 0.16002)
		(layer "In6.Cu")
		(net "M_E_CPU1_SA_DQS_DN<5>")
	)
	(segment
		(start 56.093868 -202.827636)
		(end 56.39816 -202.523344)
		(width 0.16002)
		(layer "In6.Cu")
		(net "M_E_CPU1_SA_DQS_DN<5>")
	)
	(segment
		(start 77.562964 -223.139762)
		(end 77.562964 -223.424496)
		(width 0.09525)
		(layer "In6.Cu")
		(net "M_E_CPU1_SA_DQS_DN<5>")
	)
	(segment
		(start 78.033372 -224.234502)
		(end 78.033372 -224.383346)
		(width 0.09525)
		(layer "In6.Cu")
		(net "M_E_CPU1_SA_DQS_DN<5>")
	)
	(segment
		(start 65.62598 -207.545686)
		(end 66.270632 -207.545686)
		(width 0.16002)
		(layer "In6.Cu")
		(net "M_E_CPU1_SA_DQS_DN<5>")
	)
	(segment
		(start 25.152096 -201.585322)
		(end 25.425908 -201.859134)
		(width 0.16002)
		(layer "In6.Cu")
		(net "M_E_CPU1_SA_DQS_DN<5>")
	)
	(segment
		(start 25.425908 -201.859134)
		(end 26.580592 -201.859134)
		(width 0.16002)
		(layer "In6.Cu")
		(net "M_E_CPU1_SA_DQS_DN<5>")
	)
	(segment
		(start 35.693096 -201.638916)
		(end 36.062412 -202.008232)
		(width 0.16002)
		(layer "In6.Cu")
		(net "M_E_CPU1_SA_DQS_DN<5>")
	)
	(segment
		(start 57.2135 -202.185524)
		(end 57.759854 -201.63917)
		(width 0.16002)
		(layer "In6.Cu")
		(net "M_E_CPU1_SA_DQS_DN<5>")
	)
	(segment
		(start 43.236896 -201.638916)
		(end 43.606212 -202.008232)
		(width 0.16002)
		(layer "In6.Cu")
		(net "M_E_CPU1_SA_DQS_DN<5>")
	)
	(segment
		(start 54.42204 -202.827636)
		(end 56.093868 -202.827636)
		(width 0.16002)
		(layer "In6.Cu")
		(net "M_E_CPU1_SA_DQS_DN<5>")
	)
	(segment
		(start 81.04251 -227.799646)
		(end 81.050892 -227.804472)
		(width 0.09525)
		(layer "In6.Cu")
		(net "M_E_CPU1_SA_DQS_DN<5>")
	)
	(segment
		(start 49.669446 -202.18527)
		(end 50.2158 -201.638916)
		(width 0.16002)
		(layer "In6.Cu")
		(net "M_E_CPU1_SA_DQS_DN<5>")
	)
	(segment
		(start 48.51908 -202.858116)
		(end 48.854106 -202.52309)
		(width 0.16002)
		(layer "In6.Cu")
		(net "M_E_CPU1_SA_DQS_DN<5>")
	)
	(segment
		(start 74.17435 -219.66809)
		(end 77.166978 -222.660718)
		(width 0.16002)
		(layer "In6.Cu")
		(net "M_E_CPU1_SA_DQS_DN<5>")
	)
	(segment
		(start 42.125392 -202.18527)
		(end 42.671746 -201.638916)
		(width 0.16002)
		(layer "In6.Cu")
		(net "M_E_CPU1_SA_DQS_DN<5>")
	)
	(segment
		(start 34.243772 -202.52309)
		(end 35.127946 -201.638916)
		(width 0.16002)
		(layer "In6.Cu")
		(net "M_E_CPU1_SA_DQS_DN<5>")
	)
	(segment
		(start 78.032864 -224.383346)
		(end 78.032864 -225.775266)
		(width 0.09525)
		(layer "In6.Cu")
		(net "M_E_CPU1_SA_DQS_DN<5>")
	)
	(segment
		(start 33.766252 -202.52309)
		(end 34.243772 -202.52309)
		(width 0.16002)
		(layer "In6.Cu")
		(net "M_E_CPU1_SA_DQS_DN<5>")
	)
	(segment
		(start 39.272464 -202.858116)
		(end 40.975026 -202.858116)
		(width 0.16002)
		(layer "In6.Cu")
		(net "M_E_CPU1_SA_DQS_DN<5>")
	)
	(segment
		(start 31.761684 -202.858116)
		(end 33.431226 -202.858116)
		(width 0.16002)
		(layer "In6.Cu")
		(net "M_E_CPU1_SA_DQS_DN<5>")
	)
	(segment
		(start 77.166978 -222.660718)
		(end 77.183742 -222.677482)
		(width 0.09525)
		(layer "In6.Cu")
		(net "M_E_CPU1_SA_DQS_DN<5>")
	)
	(segment
		(start 50.2158 -201.638916)
		(end 50.78095 -201.638916)
		(width 0.16002)
		(layer "In6.Cu")
		(net "M_E_CPU1_SA_DQS_DN<5>")
	)
	(segment
		(start 58.325004 -201.63917)
		(end 59.04484 -202.359006)
		(width 0.16002)
		(layer "In6.Cu")
		(net "M_E_CPU1_SA_DQS_DN<5>")
	)
	(segment
		(start 43.606212 -202.008232)
		(end 46.058836 -202.008232)
		(width 0.16002)
		(layer "In6.Cu")
		(net "M_E_CPU1_SA_DQS_DN<5>")
	)
	(segment
		(start 59.04484 -202.359006)
		(end 60.4393 -202.359006)
		(width 0.16002)
		(layer "In6.Cu")
		(net "M_E_CPU1_SA_DQS_DN<5>")
	)
	(segment
		(start 38.42258 -202.008232)
		(end 39.272464 -202.858116)
		(width 0.16002)
		(layer "In6.Cu")
		(net "M_E_CPU1_SA_DQS_DN<5>")
	)
	(segment
		(start 57.759854 -201.63917)
		(end 58.325004 -201.63917)
		(width 0.16002)
		(layer "In6.Cu")
		(net "M_E_CPU1_SA_DQS_DN<5>")
	)
	(arc
		(start 81.4197 -227.799646)
		(mid 81.701132 -227.723891)
		(end 81.982564 -227.799646)
		(width 0.09525)
		(layer "In6.Cu")
		(net "M_E_CPU1_SA_DQS_DN<5>")
	)
	(arc
		(start 77.562964 -223.424496)
		(mid 77.60471 -223.5971)
		(end 77.720698 -223.731582)
		(width 0.09525)
		(layer "In6.Cu")
		(net "M_E_CPU1_SA_DQS_DN<5>")
	)
	(arc
		(start 78.814676 -226.96424)
		(mid 78.855535 -227.107127)
		(end 78.941422 -227.2284)
		(width 0.09525)
		(layer "In6.Cu")
		(net "M_E_CPU1_SA_DQS_DN<5>")
	)
	(arc
		(start 78.470506 -226.528122)
		(mid 78.511459 -226.597782)
		(end 78.57744 -226.644454)
		(width 0.09525)
		(layer "In6.Cu")
		(net "M_E_CPU1_SA_DQS_DN<5>")
	)
	(arc
		(start 79.821278 -227.723954)
		(mid 79.966855 -227.743255)
		(end 80.102456 -227.799646)
		(width 0.09525)
		(layer "In6.Cu")
		(net "M_E_CPU1_SA_DQS_DN<5>")
	)
	(arc
		(start 81.982564 -227.799646)
		(mid 82.139191 -227.848832)
		(end 82.301842 -227.82657)
		(width 0.09525)
		(layer "In6.Cu")
		(net "M_E_CPU1_SA_DQS_DN<5>")
	)
	(arc
		(start 81.050892 -227.804472)
		(mid 81.235924 -227.850386)
		(end 81.4197 -227.799646)
		(width 0.09525)
		(layer "In6.Cu")
		(net "M_E_CPU1_SA_DQS_DN<5>")
	)
	(arc
		(start 78.57744 -226.644454)
		(mid 78.739244 -226.772135)
		(end 78.814676 -226.963986)
		(width 0.09525)
		(layer "In6.Cu")
		(net "M_E_CPU1_SA_DQS_DN<5>")
	)
	(arc
		(start 80.102456 -227.799646)
		(mid 80.286231 -227.850418)
		(end 80.471264 -227.804472)
		(width 0.09525)
		(layer "In6.Cu")
		(net "M_E_CPU1_SA_DQS_DN<5>")
	)
	(arc
		(start 78.226158 -226.177094)
		(mid 78.374018 -226.334725)
		(end 78.470506 -226.528122)
		(width 0.09525)
		(layer "In6.Cu")
		(net "M_E_CPU1_SA_DQS_DN<5>")
	)
	(arc
		(start 79.301594 -227.588826)
		(mid 79.451095 -227.688812)
		(end 79.627476 -227.723954)
		(width 0.09525)
		(layer "In6.Cu")
		(net "M_E_CPU1_SA_DQS_DN<5>")
	)
	(arc
		(start 78.033118 -225.775012)
		(mid 78.083782 -225.998063)
		(end 78.226158 -226.177094)
		(width 0.09525)
		(layer "In6.Cu")
		(net "M_E_CPU1_SA_DQS_DN<5>")
	)
	(arc
		(start 80.479646 -227.799646)
		(mid 80.761078 -227.723891)
		(end 81.04251 -227.799646)
		(width 0.09525)
		(layer "In6.Cu")
		(net "M_E_CPU1_SA_DQS_DN<5>")
	)
	(arc
		(start 77.790548 -223.771714)
		(mid 77.968998 -223.973184)
		(end 78.033372 -224.234502)
		(width 0.09525)
		(layer "In6.Cu")
		(net "M_E_CPU1_SA_DQS_DN<5>")
	)
	(segment
		(start 81.69783 -247.180354)
		(end 81.230978 -246.914416)
		(width 0.12954)
		(layer "F.Cu")
		(net "M_E_CPU1_SA_DQS_DN<4>")
	)
	(segment
		(start 80.471264 -246.58447)
		(end 80.479646 -246.589296)
		(width 0.09525)
		(layer "In6.Cu")
		(net "M_E_CPU1_SA_DQS_DN<4>")
	)
	(segment
		(start 64.65062 -244.979952)
		(end 64.65062 -245.456456)
		(width 0.16002)
		(layer "In6.Cu")
		(net "M_E_CPU1_SA_DQS_DN<4>")
	)
	(segment
		(start 65.560194 -245.889526)
		(end 65.823084 -245.626636)
		(width 0.16002)
		(layer "In6.Cu")
		(net "M_E_CPU1_SA_DQS_DN<4>")
	)
	(segment
		(start 63.692532 -244.498368)
		(end 64.169036 -244.498368)
		(width 0.16002)
		(layer "In6.Cu")
		(net "M_E_CPU1_SA_DQS_DN<4>")
	)
	(segment
		(start 42.815002 -238.061246)
		(end 43.231308 -238.061246)
		(width 0.16002)
		(layer "In6.Cu")
		(net "M_E_CPU1_SA_DQS_DN<4>")
	)
	(segment
		(start 40.989504 -238.562388)
		(end 41.318942 -238.891826)
		(width 0.16002)
		(layer "In6.Cu")
		(net "M_E_CPU1_SA_DQS_DN<4>")
	)
	(segment
		(start 36.03625 -237.712504)
		(end 37.527738 -237.712504)
		(width 0.16002)
		(layer "In6.Cu")
		(net "M_E_CPU1_SA_DQS_DN<4>")
	)
	(segment
		(start 65.823084 -245.626636)
		(end 66.049144 -245.626636)
		(width 0.16002)
		(layer "In6.Cu")
		(net "M_E_CPU1_SA_DQS_DN<4>")
	)
	(segment
		(start 57.90311 -238.061246)
		(end 58.79084 -238.061246)
		(width 0.16002)
		(layer "In6.Cu")
		(net "M_E_CPU1_SA_DQS_DN<4>")
	)
	(segment
		(start 64.169036 -244.498368)
		(end 64.431926 -244.235478)
		(width 0.16002)
		(layer "In6.Cu")
		(net "M_E_CPU1_SA_DQS_DN<4>")
	)
	(segment
		(start 60.740036 -240.317528)
		(end 60.740036 -240.997232)
		(width 0.16002)
		(layer "In6.Cu")
		(net "M_E_CPU1_SA_DQS_DN<4>")
	)
	(segment
		(start 41.984422 -238.891826)
		(end 42.815002 -238.061246)
		(width 0.16002)
		(layer "In6.Cu")
		(net "M_E_CPU1_SA_DQS_DN<4>")
	)
	(segment
		(start 59.56681 -239.144302)
		(end 60.740036 -240.317528)
		(width 0.16002)
		(layer "In6.Cu")
		(net "M_E_CPU1_SA_DQS_DN<4>")
	)
	(segment
		(start 64.91351 -244.491002)
		(end 64.91351 -244.717062)
		(width 0.16002)
		(layer "In6.Cu")
		(net "M_E_CPU1_SA_DQS_DN<4>")
	)
	(segment
		(start 63.040768 -242.84432)
		(end 63.266828 -242.84432)
		(width 0.16002)
		(layer "In6.Cu")
		(net "M_E_CPU1_SA_DQS_DN<4>")
	)
	(segment
		(start 78.005686 -246.655082)
		(end 78.222094 -246.565674)
		(width 0.09525)
		(layer "In6.Cu")
		(net "M_E_CPU1_SA_DQS_DN<4>")
	)
	(segment
		(start 77.05598 -246.926354)
		(end 77.327252 -246.655082)
		(width 0.09525)
		(layer "In6.Cu")
		(net "M_E_CPU1_SA_DQS_DN<4>")
	)
	(segment
		(start 43.58005 -237.712504)
		(end 45.112686 -237.712504)
		(width 0.16002)
		(layer "In6.Cu")
		(net "M_E_CPU1_SA_DQS_DN<4>")
	)
	(segment
		(start 50.775362 -238.061246)
		(end 51.124104 -237.712504)
		(width 0.16002)
		(layer "In6.Cu")
		(net "M_E_CPU1_SA_DQS_DN<4>")
	)
	(segment
		(start 57.07253 -238.891826)
		(end 57.90311 -238.061246)
		(width 0.16002)
		(layer "In6.Cu")
		(net "M_E_CPU1_SA_DQS_DN<4>")
	)
	(segment
		(start 64.65062 -245.456456)
		(end 65.08369 -245.889526)
		(width 0.16002)
		(layer "In6.Cu")
		(net "M_E_CPU1_SA_DQS_DN<4>")
	)
	(segment
		(start 41.318942 -238.891826)
		(end 41.984422 -238.891826)
		(width 0.16002)
		(layer "In6.Cu")
		(net "M_E_CPU1_SA_DQS_DN<4>")
	)
	(segment
		(start 62.131194 -241.934746)
		(end 61.868304 -242.197636)
		(width 0.16002)
		(layer "In6.Cu")
		(net "M_E_CPU1_SA_DQS_DN<4>")
	)
	(segment
		(start 31.653988 -238.711486)
		(end 31.803086 -238.562388)
		(width 0.16002)
		(layer "In6.Cu")
		(net "M_E_CPU1_SA_DQS_DN<4>")
	)
	(segment
		(start 45.96257 -238.562388)
		(end 48.533558 -238.562388)
		(width 0.16002)
		(layer "In6.Cu")
		(net "M_E_CPU1_SA_DQS_DN<4>")
	)
	(segment
		(start 50.359056 -238.061246)
		(end 50.775362 -238.061246)
		(width 0.16002)
		(layer "In6.Cu")
		(net "M_E_CPU1_SA_DQS_DN<4>")
	)
	(segment
		(start 77.327252 -246.655082)
		(end 78.005686 -246.655082)
		(width 0.09525)
		(layer "In6.Cu")
		(net "M_E_CPU1_SA_DQS_DN<4>")
	)
	(segment
		(start 76.398374 -246.751856)
		(end 76.572872 -246.926354)
		(width 0.09525)
		(layer "In6.Cu")
		(net "M_E_CPU1_SA_DQS_DN<4>")
	)
	(segment
		(start 63.522352 -243.099844)
		(end 63.522352 -243.325904)
		(width 0.16002)
		(layer "In6.Cu")
		(net "M_E_CPU1_SA_DQS_DN<4>")
	)
	(segment
		(start 65.08369 -245.889526)
		(end 65.560194 -245.889526)
		(width 0.16002)
		(layer "In6.Cu")
		(net "M_E_CPU1_SA_DQS_DN<4>")
	)
	(segment
		(start 75.172824 -246.306086)
		(end 75.677522 -246.810784)
		(width 0.16002)
		(layer "In6.Cu")
		(net "M_E_CPU1_SA_DQS_DN<4>")
	)
	(segment
		(start 48.862996 -238.891826)
		(end 49.528476 -238.891826)
		(width 0.16002)
		(layer "In6.Cu")
		(net "M_E_CPU1_SA_DQS_DN<4>")
	)
	(segment
		(start 38.377622 -238.562388)
		(end 40.989504 -238.562388)
		(width 0.16002)
		(layer "In6.Cu")
		(net "M_E_CPU1_SA_DQS_DN<4>")
	)
	(segment
		(start 29.252164 -238.985298)
		(end 29.525976 -238.711486)
		(width 0.16002)
		(layer "In6.Cu")
		(net "M_E_CPU1_SA_DQS_DN<4>")
	)
	(segment
		(start 59.56681 -238.837216)
		(end 59.56681 -239.144302)
		(width 0.16002)
		(layer "In6.Cu")
		(net "M_E_CPU1_SA_DQS_DN<4>")
	)
	(segment
		(start 62.301374 -243.10721)
		(end 62.777878 -243.10721)
		(width 0.16002)
		(layer "In6.Cu")
		(net "M_E_CPU1_SA_DQS_DN<4>")
	)
	(segment
		(start 53.522118 -238.577882)
		(end 56.035194 -238.577882)
		(width 0.16002)
		(layer "In6.Cu")
		(net "M_E_CPU1_SA_DQS_DN<4>")
	)
	(segment
		(start 61.195966 -241.453162)
		(end 61.87567 -241.453162)
		(width 0.16002)
		(layer "In6.Cu")
		(net "M_E_CPU1_SA_DQS_DN<4>")
	)
	(segment
		(start 61.87567 -241.453162)
		(end 62.131194 -241.708686)
		(width 0.16002)
		(layer "In6.Cu")
		(net "M_E_CPU1_SA_DQS_DN<4>")
	)
	(segment
		(start 75.677522 -246.810784)
		(end 75.955906 -246.810784)
		(width 0.16002)
		(layer "In6.Cu")
		(net "M_E_CPU1_SA_DQS_DN<4>")
	)
	(segment
		(start 52.65674 -237.712504)
		(end 53.522118 -238.577882)
		(width 0.16002)
		(layer "In6.Cu")
		(net "M_E_CPU1_SA_DQS_DN<4>")
	)
	(segment
		(start 34.412174 -238.891826)
		(end 35.242754 -238.061246)
		(width 0.16002)
		(layer "In6.Cu")
		(net "M_E_CPU1_SA_DQS_DN<4>")
	)
	(segment
		(start 81.077054 -246.648986)
		(end 81.230978 -246.914416)
		(width 0.09525)
		(layer "In6.Cu")
		(net "M_E_CPU1_SA_DQS_DN<4>")
	)
	(segment
		(start 56.035194 -238.577882)
		(end 56.349138 -238.891826)
		(width 0.16002)
		(layer "In6.Cu")
		(net "M_E_CPU1_SA_DQS_DN<4>")
	)
	(segment
		(start 63.259462 -244.065298)
		(end 63.692532 -244.498368)
		(width 0.16002)
		(layer "In6.Cu")
		(net "M_E_CPU1_SA_DQS_DN<4>")
	)
	(segment
		(start 64.91351 -244.717062)
		(end 64.65062 -244.979952)
		(width 0.16002)
		(layer "In6.Cu")
		(net "M_E_CPU1_SA_DQS_DN<4>")
	)
	(segment
		(start 62.777878 -243.10721)
		(end 63.040768 -242.84432)
		(width 0.16002)
		(layer "In6.Cu")
		(net "M_E_CPU1_SA_DQS_DN<4>")
	)
	(segment
		(start 66.049144 -245.626636)
		(end 66.728594 -246.306086)
		(width 0.16002)
		(layer "In6.Cu")
		(net "M_E_CPU1_SA_DQS_DN<4>")
	)
	(segment
		(start 64.431926 -244.235478)
		(end 64.657986 -244.235478)
		(width 0.16002)
		(layer "In6.Cu")
		(net "M_E_CPU1_SA_DQS_DN<4>")
	)
	(segment
		(start 35.687508 -238.061246)
		(end 36.03625 -237.712504)
		(width 0.16002)
		(layer "In6.Cu")
		(net "M_E_CPU1_SA_DQS_DN<4>")
	)
	(segment
		(start 31.803086 -238.562388)
		(end 33.445704 -238.562388)
		(width 0.16002)
		(layer "In6.Cu")
		(net "M_E_CPU1_SA_DQS_DN<4>")
	)
	(segment
		(start 76.038456 -246.751856)
		(end 76.398374 -246.751856)
		(width 0.09525)
		(layer "In6.Cu")
		(net "M_E_CPU1_SA_DQS_DN<4>")
	)
	(segment
		(start 48.533558 -238.562388)
		(end 48.862996 -238.891826)
		(width 0.16002)
		(layer "In6.Cu")
		(net "M_E_CPU1_SA_DQS_DN<4>")
	)
	(segment
		(start 43.231308 -238.061246)
		(end 43.58005 -237.712504)
		(width 0.16002)
		(layer "In6.Cu")
		(net "M_E_CPU1_SA_DQS_DN<4>")
	)
	(segment
		(start 35.242754 -238.061246)
		(end 35.687508 -238.061246)
		(width 0.16002)
		(layer "In6.Cu")
		(net "M_E_CPU1_SA_DQS_DN<4>")
	)
	(segment
		(start 62.131194 -241.708686)
		(end 62.131194 -241.934746)
		(width 0.16002)
		(layer "In6.Cu")
		(net "M_E_CPU1_SA_DQS_DN<4>")
	)
	(segment
		(start 37.527738 -237.712504)
		(end 38.377622 -238.562388)
		(width 0.16002)
		(layer "In6.Cu")
		(net "M_E_CPU1_SA_DQS_DN<4>")
	)
	(segment
		(start 60.740036 -240.997232)
		(end 61.195966 -241.453162)
		(width 0.16002)
		(layer "In6.Cu")
		(net "M_E_CPU1_SA_DQS_DN<4>")
	)
	(segment
		(start 63.259462 -243.588794)
		(end 63.259462 -244.065298)
		(width 0.16002)
		(layer "In6.Cu")
		(net "M_E_CPU1_SA_DQS_DN<4>")
	)
	(segment
		(start 63.522352 -243.325904)
		(end 63.259462 -243.588794)
		(width 0.16002)
		(layer "In6.Cu")
		(net "M_E_CPU1_SA_DQS_DN<4>")
	)
	(segment
		(start 33.445704 -238.562388)
		(end 33.775142 -238.891826)
		(width 0.16002)
		(layer "In6.Cu")
		(net "M_E_CPU1_SA_DQS_DN<4>")
	)
	(segment
		(start 29.525976 -238.711486)
		(end 31.653988 -238.711486)
		(width 0.16002)
		(layer "In6.Cu")
		(net "M_E_CPU1_SA_DQS_DN<4>")
	)
	(segment
		(start 66.728594 -246.306086)
		(end 75.172824 -246.306086)
		(width 0.16002)
		(layer "In6.Cu")
		(net "M_E_CPU1_SA_DQS_DN<4>")
	)
	(segment
		(start 78.363064 -246.537734)
		(end 78.41107 -246.537734)
		(width 0.09525)
		(layer "In6.Cu")
		(net "M_E_CPU1_SA_DQS_DN<4>")
	)
	(segment
		(start 45.112686 -237.712504)
		(end 45.96257 -238.562388)
		(width 0.16002)
		(layer "In6.Cu")
		(net "M_E_CPU1_SA_DQS_DN<4>")
	)
	(segment
		(start 61.868304 -242.197636)
		(end 61.868304 -242.67414)
		(width 0.16002)
		(layer "In6.Cu")
		(net "M_E_CPU1_SA_DQS_DN<4>")
	)
	(segment
		(start 58.79084 -238.061246)
		(end 59.56681 -238.837216)
		(width 0.16002)
		(layer "In6.Cu")
		(net "M_E_CPU1_SA_DQS_DN<4>")
	)
	(segment
		(start 33.775142 -238.891826)
		(end 34.412174 -238.891826)
		(width 0.16002)
		(layer "In6.Cu")
		(net "M_E_CPU1_SA_DQS_DN<4>")
	)
	(segment
		(start 79.152496 -246.595392)
		(end 79.16291 -246.589296)
		(width 0.09525)
		(layer "In6.Cu")
		(net "M_E_CPU1_SA_DQS_DN<4>")
	)
	(segment
		(start 75.979528 -246.810784)
		(end 76.038456 -246.751856)
		(width 0.09525)
		(layer "In6.Cu")
		(net "M_E_CPU1_SA_DQS_DN<4>")
	)
	(segment
		(start 61.868304 -242.67414)
		(end 62.301374 -243.10721)
		(width 0.16002)
		(layer "In6.Cu")
		(net "M_E_CPU1_SA_DQS_DN<4>")
	)
	(segment
		(start 49.528476 -238.891826)
		(end 50.359056 -238.061246)
		(width 0.16002)
		(layer "In6.Cu")
		(net "M_E_CPU1_SA_DQS_DN<4>")
	)
	(segment
		(start 56.349138 -238.891826)
		(end 57.07253 -238.891826)
		(width 0.16002)
		(layer "In6.Cu")
		(net "M_E_CPU1_SA_DQS_DN<4>")
	)
	(segment
		(start 63.266828 -242.84432)
		(end 63.522352 -243.099844)
		(width 0.16002)
		(layer "In6.Cu")
		(net "M_E_CPU1_SA_DQS_DN<4>")
	)
	(segment
		(start 75.955906 -246.810784)
		(end 75.979528 -246.810784)
		(width 0.09525)
		(layer "In6.Cu")
		(net "M_E_CPU1_SA_DQS_DN<4>")
	)
	(segment
		(start 64.657986 -244.235478)
		(end 64.91351 -244.491002)
		(width 0.16002)
		(layer "In6.Cu")
		(net "M_E_CPU1_SA_DQS_DN<4>")
	)
	(segment
		(start 51.124104 -237.712504)
		(end 52.65674 -237.712504)
		(width 0.16002)
		(layer "In6.Cu")
		(net "M_E_CPU1_SA_DQS_DN<4>")
	)
	(segment
		(start 80.976216 -246.622316)
		(end 81.077054 -246.648986)
		(width 0.09525)
		(layer "In6.Cu")
		(net "M_E_CPU1_SA_DQS_DN<4>")
	)
	(segment
		(start 79.539846 -246.589296)
		(end 79.55026 -246.595392)
		(width 0.09525)
		(layer "In6.Cu")
		(net "M_E_CPU1_SA_DQS_DN<4>")
	)
	(segment
		(start 76.572872 -246.926354)
		(end 77.05598 -246.926354)
		(width 0.09525)
		(layer "In6.Cu")
		(net "M_E_CPU1_SA_DQS_DN<4>")
	)
	(arc
		(start 78.222094 -246.565674)
		(mid 78.291208 -246.544785)
		(end 78.363064 -246.537734)
		(width 0.09525)
		(layer "In6.Cu")
		(net "M_E_CPU1_SA_DQS_DN<4>")
	)
	(arc
		(start 79.55026 -246.595392)
		(mid 79.827168 -246.665069)
		(end 80.102456 -246.589296)
		(width 0.09525)
		(layer "In6.Cu")
		(net "M_E_CPU1_SA_DQS_DN<4>")
	)
	(arc
		(start 80.102456 -246.589296)
		(mid 80.286231 -246.538524)
		(end 80.471264 -246.58447)
		(width 0.09525)
		(layer "In6.Cu")
		(net "M_E_CPU1_SA_DQS_DN<4>")
	)
	(arc
		(start 80.956404 -246.63019)
		(mid 80.966347 -246.626347)
		(end 80.976216 -246.622316)
		(width 0.09525)
		(layer "In6.Cu")
		(net "M_E_CPU1_SA_DQS_DN<4>")
	)
	(arc
		(start 79.16291 -246.589296)
		(mid 79.351378 -246.538619)
		(end 79.539846 -246.589296)
		(width 0.09525)
		(layer "In6.Cu")
		(net "M_E_CPU1_SA_DQS_DN<4>")
	)
	(arc
		(start 78.599792 -246.589296)
		(mid 78.875335 -246.665145)
		(end 79.152496 -246.595392)
		(width 0.09525)
		(layer "In6.Cu")
		(net "M_E_CPU1_SA_DQS_DN<4>")
	)
	(arc
		(start 78.41107 -246.537734)
		(mid 78.508826 -246.551068)
		(end 78.599792 -246.589296)
		(width 0.09525)
		(layer "In6.Cu")
		(net "M_E_CPU1_SA_DQS_DN<4>")
	)
	(arc
		(start 80.479646 -246.589296)
		(mid 80.713441 -246.663163)
		(end 80.956404 -246.63019)
		(width 0.09525)
		(layer "In6.Cu")
		(net "M_E_CPU1_SA_DQS_DN<4>")
	)
	(segment
		(start 81.69783 -242.320318)
		(end 81.230978 -242.05438)
		(width 0.12954)
		(layer "F.Cu")
		(net "M_E_CPU1_SA_DQS_DN<3>")
	)
	(segment
		(start 35.242754 -228.711252)
		(end 35.687508 -228.711252)
		(width 0.16002)
		(layer "In6.Cu")
		(net "M_E_CPU1_SA_DQS_DN<3>")
	)
	(segment
		(start 67.806316 -238.734346)
		(end 68.238878 -239.166908)
		(width 0.16002)
		(layer "In6.Cu")
		(net "M_E_CPU1_SA_DQS_DN<3>")
	)
	(segment
		(start 76.933298 -241.113564)
		(end 77.497432 -241.677698)
		(width 0.09525)
		(layer "In6.Cu")
		(net "M_E_CPU1_SA_DQS_DN<3>")
	)
	(segment
		(start 29.525976 -229.361492)
		(end 31.653988 -229.361492)
		(width 0.16002)
		(layer "In6.Cu")
		(net "M_E_CPU1_SA_DQS_DN<3>")
	)
	(segment
		(start 66.642742 -236.6391)
		(end 66.415158 -236.866684)
		(width 0.16002)
		(layer "In6.Cu")
		(net "M_E_CPU1_SA_DQS_DN<3>")
	)
	(segment
		(start 68.715382 -239.166908)
		(end 68.942966 -238.939324)
		(width 0.16002)
		(layer "In6.Cu")
		(net "M_E_CPU1_SA_DQS_DN<3>")
	)
	(segment
		(start 35.687508 -228.711252)
		(end 36.03625 -228.36251)
		(width 0.16002)
		(layer "In6.Cu")
		(net "M_E_CPU1_SA_DQS_DN<3>")
	)
	(segment
		(start 59.01055 -229.428548)
		(end 59.347608 -229.765606)
		(width 0.16002)
		(layer "In6.Cu")
		(net "M_E_CPU1_SA_DQS_DN<3>")
	)
	(segment
		(start 57.90311 -228.711252)
		(end 58.74004 -228.711252)
		(width 0.16002)
		(layer "In6.Cu")
		(net "M_E_CPU1_SA_DQS_DN<3>")
	)
	(segment
		(start 32.974788 -229.212394)
		(end 33.575498 -229.813104)
		(width 0.16002)
		(layer "In6.Cu")
		(net "M_E_CPU1_SA_DQS_DN<3>")
	)
	(segment
		(start 41.80205 -229.724204)
		(end 42.815002 -228.711252)
		(width 0.16002)
		(layer "In6.Cu")
		(net "M_E_CPU1_SA_DQS_DN<3>")
	)
	(segment
		(start 63.188596 -232.678478)
		(end 64.205612 -235.133642)
		(width 0.16002)
		(layer "In6.Cu")
		(net "M_E_CPU1_SA_DQS_DN<3>")
	)
	(segment
		(start 29.252164 -229.635304)
		(end 29.525976 -229.361492)
		(width 0.16002)
		(layer "In6.Cu")
		(net "M_E_CPU1_SA_DQS_DN<3>")
	)
	(segment
		(start 79.152496 -241.735356)
		(end 79.16291 -241.72926)
		(width 0.09525)
		(layer "In6.Cu")
		(net "M_E_CPU1_SA_DQS_DN<3>")
	)
	(segment
		(start 80.976216 -241.76228)
		(end 81.077054 -241.78895)
		(width 0.09525)
		(layer "In6.Cu")
		(net "M_E_CPU1_SA_DQS_DN<3>")
	)
	(segment
		(start 59.01055 -228.981762)
		(end 59.01055 -229.428548)
		(width 0.16002)
		(layer "In6.Cu")
		(net "M_E_CPU1_SA_DQS_DN<3>")
	)
	(segment
		(start 37.078158 -228.36251)
		(end 38.188392 -229.472744)
		(width 0.16002)
		(layer "In6.Cu")
		(net "M_E_CPU1_SA_DQS_DN<3>")
	)
	(segment
		(start 58.74004 -228.711252)
		(end 59.01055 -228.981762)
		(width 0.16002)
		(layer "In6.Cu")
		(net "M_E_CPU1_SA_DQS_DN<3>")
	)
	(segment
		(start 48.643032 -229.754684)
		(end 49.315624 -229.754684)
		(width 0.16002)
		(layer "In6.Cu")
		(net "M_E_CPU1_SA_DQS_DN<3>")
	)
	(segment
		(start 69.425058 -239.421416)
		(end 69.197474 -239.649)
		(width 0.16002)
		(layer "In6.Cu")
		(net "M_E_CPU1_SA_DQS_DN<3>")
	)
	(segment
		(start 43.58005 -228.36251)
		(end 45.112686 -228.36251)
		(width 0.16002)
		(layer "In6.Cu")
		(net "M_E_CPU1_SA_DQS_DN<3>")
	)
	(segment
		(start 52.65674 -228.36251)
		(end 53.589174 -229.294944)
		(width 0.16002)
		(layer "In6.Cu")
		(net "M_E_CPU1_SA_DQS_DN<3>")
	)
	(segment
		(start 56.630316 -229.984046)
		(end 57.90311 -228.711252)
		(width 0.16002)
		(layer "In6.Cu")
		(net "M_E_CPU1_SA_DQS_DN<3>")
	)
	(segment
		(start 69.197474 -239.649)
		(end 69.197474 -240.125504)
		(width 0.16002)
		(layer "In6.Cu")
		(net "M_E_CPU1_SA_DQS_DN<3>")
	)
	(segment
		(start 66.38671 -236.157008)
		(end 66.642742 -236.41304)
		(width 0.16002)
		(layer "In6.Cu")
		(net "M_E_CPU1_SA_DQS_DN<3>")
	)
	(segment
		(start 67.551808 -237.548166)
		(end 67.777868 -237.548166)
		(width 0.16002)
		(layer "In6.Cu")
		(net "M_E_CPU1_SA_DQS_DN<3>")
	)
	(segment
		(start 69.425058 -239.195356)
		(end 69.425058 -239.421416)
		(width 0.16002)
		(layer "In6.Cu")
		(net "M_E_CPU1_SA_DQS_DN<3>")
	)
	(segment
		(start 34.140902 -229.813104)
		(end 35.242754 -228.711252)
		(width 0.16002)
		(layer "In6.Cu")
		(net "M_E_CPU1_SA_DQS_DN<3>")
	)
	(segment
		(start 69.169026 -238.939324)
		(end 69.425058 -239.195356)
		(width 0.16002)
		(layer "In6.Cu")
		(net "M_E_CPU1_SA_DQS_DN<3>")
	)
	(segment
		(start 69.765164 -240.693194)
		(end 75.955906 -240.693194)
		(width 0.16002)
		(layer "In6.Cu")
		(net "M_E_CPU1_SA_DQS_DN<3>")
	)
	(segment
		(start 80.471264 -241.724434)
		(end 80.479646 -241.72926)
		(width 0.09525)
		(layer "In6.Cu")
		(net "M_E_CPU1_SA_DQS_DN<3>")
	)
	(segment
		(start 54.314598 -229.294944)
		(end 55.0037 -229.984046)
		(width 0.16002)
		(layer "In6.Cu")
		(net "M_E_CPU1_SA_DQS_DN<3>")
	)
	(segment
		(start 33.575498 -229.813104)
		(end 34.140902 -229.813104)
		(width 0.16002)
		(layer "In6.Cu")
		(net "M_E_CPU1_SA_DQS_DN<3>")
	)
	(segment
		(start 59.347608 -229.765606)
		(end 60.275724 -229.765606)
		(width 0.16002)
		(layer "In6.Cu")
		(net "M_E_CPU1_SA_DQS_DN<3>")
	)
	(segment
		(start 48.100742 -229.212394)
		(end 48.643032 -229.754684)
		(width 0.16002)
		(layer "In6.Cu")
		(net "M_E_CPU1_SA_DQS_DN<3>")
	)
	(segment
		(start 36.03625 -228.36251)
		(end 37.078158 -228.36251)
		(width 0.16002)
		(layer "In6.Cu")
		(net "M_E_CPU1_SA_DQS_DN<3>")
	)
	(segment
		(start 51.124104 -228.36251)
		(end 52.65674 -228.36251)
		(width 0.16002)
		(layer "In6.Cu")
		(net "M_E_CPU1_SA_DQS_DN<3>")
	)
	(segment
		(start 66.642742 -236.41304)
		(end 66.642742 -236.6391)
		(width 0.16002)
		(layer "In6.Cu")
		(net "M_E_CPU1_SA_DQS_DN<3>")
	)
	(segment
		(start 68.0339 -238.030258)
		(end 67.806316 -238.257842)
		(width 0.16002)
		(layer "In6.Cu")
		(net "M_E_CPU1_SA_DQS_DN<3>")
	)
	(segment
		(start 45.96257 -229.212394)
		(end 48.100742 -229.212394)
		(width 0.16002)
		(layer "In6.Cu")
		(net "M_E_CPU1_SA_DQS_DN<3>")
	)
	(segment
		(start 45.112686 -228.36251)
		(end 45.96257 -229.212394)
		(width 0.16002)
		(layer "In6.Cu")
		(net "M_E_CPU1_SA_DQS_DN<3>")
	)
	(segment
		(start 31.803086 -229.212394)
		(end 32.974788 -229.212394)
		(width 0.16002)
		(layer "In6.Cu")
		(net "M_E_CPU1_SA_DQS_DN<3>")
	)
	(segment
		(start 75.979528 -240.693194)
		(end 76.031344 -240.641378)
		(width 0.09525)
		(layer "In6.Cu")
		(net "M_E_CPU1_SA_DQS_DN<3>")
	)
	(segment
		(start 75.955906 -240.693194)
		(end 75.979528 -240.693194)
		(width 0.09525)
		(layer "In6.Cu")
		(net "M_E_CPU1_SA_DQS_DN<3>")
	)
	(segment
		(start 38.188392 -229.472744)
		(end 39.55161 -229.472744)
		(width 0.16002)
		(layer "In6.Cu")
		(net "M_E_CPU1_SA_DQS_DN<3>")
	)
	(segment
		(start 66.84772 -237.77575)
		(end 67.324224 -237.77575)
		(width 0.16002)
		(layer "In6.Cu")
		(net "M_E_CPU1_SA_DQS_DN<3>")
	)
	(segment
		(start 49.315624 -229.754684)
		(end 50.359056 -228.711252)
		(width 0.16002)
		(layer "In6.Cu")
		(net "M_E_CPU1_SA_DQS_DN<3>")
	)
	(segment
		(start 67.777868 -237.548166)
		(end 68.0339 -237.804198)
		(width 0.16002)
		(layer "In6.Cu")
		(net "M_E_CPU1_SA_DQS_DN<3>")
	)
	(segment
		(start 76.638658 -241.113564)
		(end 76.933298 -241.113564)
		(width 0.09525)
		(layer "In6.Cu")
		(net "M_E_CPU1_SA_DQS_DN<3>")
	)
	(segment
		(start 31.653988 -229.361492)
		(end 31.803086 -229.212394)
		(width 0.16002)
		(layer "In6.Cu")
		(net "M_E_CPU1_SA_DQS_DN<3>")
	)
	(segment
		(start 41.083738 -229.724204)
		(end 41.80205 -229.724204)
		(width 0.16002)
		(layer "In6.Cu")
		(net "M_E_CPU1_SA_DQS_DN<3>")
	)
	(segment
		(start 40.571928 -229.212394)
		(end 41.083738 -229.724204)
		(width 0.16002)
		(layer "In6.Cu")
		(net "M_E_CPU1_SA_DQS_DN<3>")
	)
	(segment
		(start 68.0339 -237.804198)
		(end 68.0339 -238.030258)
		(width 0.16002)
		(layer "In6.Cu")
		(net "M_E_CPU1_SA_DQS_DN<3>")
	)
	(segment
		(start 50.359056 -228.711252)
		(end 50.775362 -228.711252)
		(width 0.16002)
		(layer "In6.Cu")
		(net "M_E_CPU1_SA_DQS_DN<3>")
	)
	(segment
		(start 76.166472 -240.641378)
		(end 76.638658 -241.113564)
		(width 0.09525)
		(layer "In6.Cu")
		(net "M_E_CPU1_SA_DQS_DN<3>")
	)
	(segment
		(start 65.456562 -236.384592)
		(end 65.933066 -236.384592)
		(width 0.16002)
		(layer "In6.Cu")
		(net "M_E_CPU1_SA_DQS_DN<3>")
	)
	(segment
		(start 65.933066 -236.384592)
		(end 66.16065 -236.157008)
		(width 0.16002)
		(layer "In6.Cu")
		(net "M_E_CPU1_SA_DQS_DN<3>")
	)
	(segment
		(start 66.415158 -236.866684)
		(end 66.415158 -237.343188)
		(width 0.16002)
		(layer "In6.Cu")
		(net "M_E_CPU1_SA_DQS_DN<3>")
	)
	(segment
		(start 53.589174 -229.294944)
		(end 54.314598 -229.294944)
		(width 0.16002)
		(layer "In6.Cu")
		(net "M_E_CPU1_SA_DQS_DN<3>")
	)
	(segment
		(start 60.275724 -229.765606)
		(end 63.188596 -232.678478)
		(width 0.16002)
		(layer "In6.Cu")
		(net "M_E_CPU1_SA_DQS_DN<3>")
	)
	(segment
		(start 77.497432 -241.677698)
		(end 78.41107 -241.677698)
		(width 0.09525)
		(layer "In6.Cu")
		(net "M_E_CPU1_SA_DQS_DN<3>")
	)
	(segment
		(start 55.0037 -229.984046)
		(end 56.630316 -229.984046)
		(width 0.16002)
		(layer "In6.Cu")
		(net "M_E_CPU1_SA_DQS_DN<3>")
	)
	(segment
		(start 64.205612 -235.133642)
		(end 65.456562 -236.384592)
		(width 0.16002)
		(layer "In6.Cu")
		(net "M_E_CPU1_SA_DQS_DN<3>")
	)
	(segment
		(start 68.238878 -239.166908)
		(end 68.715382 -239.166908)
		(width 0.16002)
		(layer "In6.Cu")
		(net "M_E_CPU1_SA_DQS_DN<3>")
	)
	(segment
		(start 68.942966 -238.939324)
		(end 69.169026 -238.939324)
		(width 0.16002)
		(layer "In6.Cu")
		(net "M_E_CPU1_SA_DQS_DN<3>")
	)
	(segment
		(start 81.077054 -241.78895)
		(end 81.230978 -242.05438)
		(width 0.09525)
		(layer "In6.Cu")
		(net "M_E_CPU1_SA_DQS_DN<3>")
	)
	(segment
		(start 76.031344 -240.641378)
		(end 76.166472 -240.641378)
		(width 0.09525)
		(layer "In6.Cu")
		(net "M_E_CPU1_SA_DQS_DN<3>")
	)
	(segment
		(start 66.16065 -236.157008)
		(end 66.38671 -236.157008)
		(width 0.16002)
		(layer "In6.Cu")
		(net "M_E_CPU1_SA_DQS_DN<3>")
	)
	(segment
		(start 69.197474 -240.125504)
		(end 69.765164 -240.693194)
		(width 0.16002)
		(layer "In6.Cu")
		(net "M_E_CPU1_SA_DQS_DN<3>")
	)
	(segment
		(start 42.815002 -228.711252)
		(end 43.231308 -228.711252)
		(width 0.16002)
		(layer "In6.Cu")
		(net "M_E_CPU1_SA_DQS_DN<3>")
	)
	(segment
		(start 39.81196 -229.212394)
		(end 40.571928 -229.212394)
		(width 0.16002)
		(layer "In6.Cu")
		(net "M_E_CPU1_SA_DQS_DN<3>")
	)
	(segment
		(start 67.324224 -237.77575)
		(end 67.551808 -237.548166)
		(width 0.16002)
		(layer "In6.Cu")
		(net "M_E_CPU1_SA_DQS_DN<3>")
	)
	(segment
		(start 66.415158 -237.343188)
		(end 66.84772 -237.77575)
		(width 0.16002)
		(layer "In6.Cu")
		(net "M_E_CPU1_SA_DQS_DN<3>")
	)
	(segment
		(start 67.806316 -238.257842)
		(end 67.806316 -238.734346)
		(width 0.16002)
		(layer "In6.Cu")
		(net "M_E_CPU1_SA_DQS_DN<3>")
	)
	(segment
		(start 39.55161 -229.472744)
		(end 39.81196 -229.212394)
		(width 0.16002)
		(layer "In6.Cu")
		(net "M_E_CPU1_SA_DQS_DN<3>")
	)
	(segment
		(start 79.539846 -241.72926)
		(end 79.55026 -241.735356)
		(width 0.09525)
		(layer "In6.Cu")
		(net "M_E_CPU1_SA_DQS_DN<3>")
	)
	(segment
		(start 43.231308 -228.711252)
		(end 43.58005 -228.36251)
		(width 0.16002)
		(layer "In6.Cu")
		(net "M_E_CPU1_SA_DQS_DN<3>")
	)
	(segment
		(start 50.775362 -228.711252)
		(end 51.124104 -228.36251)
		(width 0.16002)
		(layer "In6.Cu")
		(net "M_E_CPU1_SA_DQS_DN<3>")
	)
	(arc
		(start 78.599792 -241.72926)
		(mid 78.875335 -241.805109)
		(end 79.152496 -241.735356)
		(width 0.09525)
		(layer "In6.Cu")
		(net "M_E_CPU1_SA_DQS_DN<3>")
	)
	(arc
		(start 78.41107 -241.677698)
		(mid 78.508826 -241.691032)
		(end 78.599792 -241.72926)
		(width 0.09525)
		(layer "In6.Cu")
		(net "M_E_CPU1_SA_DQS_DN<3>")
	)
	(arc
		(start 79.16291 -241.72926)
		(mid 79.351378 -241.678583)
		(end 79.539846 -241.72926)
		(width 0.09525)
		(layer "In6.Cu")
		(net "M_E_CPU1_SA_DQS_DN<3>")
	)
	(arc
		(start 80.102456 -241.72926)
		(mid 80.286231 -241.678488)
		(end 80.471264 -241.724434)
		(width 0.09525)
		(layer "In6.Cu")
		(net "M_E_CPU1_SA_DQS_DN<3>")
	)
	(arc
		(start 80.479646 -241.72926)
		(mid 80.713441 -241.803127)
		(end 80.956404 -241.770154)
		(width 0.09525)
		(layer "In6.Cu")
		(net "M_E_CPU1_SA_DQS_DN<3>")
	)
	(arc
		(start 79.55026 -241.735356)
		(mid 79.827168 -241.805033)
		(end 80.102456 -241.72926)
		(width 0.09525)
		(layer "In6.Cu")
		(net "M_E_CPU1_SA_DQS_DN<3>")
	)
	(arc
		(start 80.956404 -241.770154)
		(mid 80.966347 -241.766311)
		(end 80.976216 -241.76228)
		(width 0.09525)
		(layer "In6.Cu")
		(net "M_E_CPU1_SA_DQS_DN<3>")
	)
	(segment
		(start 81.69783 -237.460282)
		(end 81.230978 -237.194344)
		(width 0.12954)
		(layer "F.Cu")
		(net "M_E_CPU1_SA_DQS_DN<2>")
	)
	(segment
		(start 60.301378 -219.529406)
		(end 60.461398 -219.369386)
		(width 0.16002)
		(layer "In6.Cu")
		(net "M_E_CPU1_SA_DQS_DN<2>")
	)
	(segment
		(start 48.64227 -220.468444)
		(end 49.25187 -220.468444)
		(width 0.16002)
		(layer "In6.Cu")
		(net "M_E_CPU1_SA_DQS_DN<2>")
	)
	(segment
		(start 45.112686 -219.012516)
		(end 45.96257 -219.8624)
		(width 0.16002)
		(layer "In6.Cu")
		(net "M_E_CPU1_SA_DQS_DN<2>")
	)
	(segment
		(start 61.93028 -220.486986)
		(end 62.267338 -220.149928)
		(width 0.16002)
		(layer "In6.Cu")
		(net "M_E_CPU1_SA_DQS_DN<2>")
	)
	(segment
		(start 33.536636 -220.458284)
		(end 34.145728 -220.458284)
		(width 0.16002)
		(layer "In6.Cu")
		(net "M_E_CPU1_SA_DQS_DN<2>")
	)
	(segment
		(start 62.427358 -219.638626)
		(end 62.854078 -219.638626)
		(width 0.16002)
		(layer "In6.Cu")
		(net "M_E_CPU1_SA_DQS_DN<2>")
	)
	(segment
		(start 51.124104 -219.012516)
		(end 52.65674 -219.012516)
		(width 0.16002)
		(layer "In6.Cu")
		(net "M_E_CPU1_SA_DQS_DN<2>")
	)
	(segment
		(start 79.539846 -236.869224)
		(end 79.55026 -236.87532)
		(width 0.09525)
		(layer "In6.Cu")
		(net "M_E_CPU1_SA_DQS_DN<2>")
	)
	(segment
		(start 45.96257 -219.8624)
		(end 48.036226 -219.8624)
		(width 0.16002)
		(layer "In6.Cu")
		(net "M_E_CPU1_SA_DQS_DN<2>")
	)
	(segment
		(start 78.166976 -236.817662)
		(end 78.41107 -236.817662)
		(width 0.09525)
		(layer "In6.Cu")
		(net "M_E_CPU1_SA_DQS_DN<2>")
	)
	(segment
		(start 60.982098 -220.149928)
		(end 61.319156 -220.486986)
		(width 0.16002)
		(layer "In6.Cu")
		(net "M_E_CPU1_SA_DQS_DN<2>")
	)
	(segment
		(start 63.22949 -223.614488)
		(end 65.58153 -225.966528)
		(width 0.16002)
		(layer "In6.Cu")
		(net "M_E_CPU1_SA_DQS_DN<2>")
	)
	(segment
		(start 50.359056 -219.361258)
		(end 50.775362 -219.361258)
		(width 0.16002)
		(layer "In6.Cu")
		(net "M_E_CPU1_SA_DQS_DN<2>")
	)
	(segment
		(start 48.036226 -219.8624)
		(end 48.64227 -220.468444)
		(width 0.16002)
		(layer "In6.Cu")
		(net "M_E_CPU1_SA_DQS_DN<2>")
	)
	(segment
		(start 63.22949 -220.014038)
		(end 63.22949 -223.614488)
		(width 0.16002)
		(layer "In6.Cu")
		(net "M_E_CPU1_SA_DQS_DN<2>")
	)
	(segment
		(start 41.070276 -220.468444)
		(end 41.707816 -220.468444)
		(width 0.16002)
		(layer "In6.Cu")
		(net "M_E_CPU1_SA_DQS_DN<2>")
	)
	(segment
		(start 29.525976 -220.011498)
		(end 31.653988 -220.011498)
		(width 0.16002)
		(layer "In6.Cu")
		(net "M_E_CPU1_SA_DQS_DN<2>")
	)
	(segment
		(start 55.264304 -220.600524)
		(end 56.663844 -220.600524)
		(width 0.16002)
		(layer "In6.Cu")
		(net "M_E_CPU1_SA_DQS_DN<2>")
	)
	(segment
		(start 65.58153 -227.00488)
		(end 73.61809 -235.04144)
		(width 0.16002)
		(layer "In6.Cu")
		(net "M_E_CPU1_SA_DQS_DN<2>")
	)
	(segment
		(start 43.231308 -219.361258)
		(end 43.58005 -219.012516)
		(width 0.16002)
		(layer "In6.Cu")
		(net "M_E_CPU1_SA_DQS_DN<2>")
	)
	(segment
		(start 80.471264 -236.864398)
		(end 80.479646 -236.869224)
		(width 0.09525)
		(layer "In6.Cu")
		(net "M_E_CPU1_SA_DQS_DN<2>")
	)
	(segment
		(start 31.803086 -219.8624)
		(end 32.940752 -219.8624)
		(width 0.16002)
		(layer "In6.Cu")
		(net "M_E_CPU1_SA_DQS_DN<2>")
	)
	(segment
		(start 59.016138 -220.149928)
		(end 59.353196 -220.486986)
		(width 0.16002)
		(layer "In6.Cu")
		(net "M_E_CPU1_SA_DQS_DN<2>")
	)
	(segment
		(start 36.03625 -219.012516)
		(end 37.56787 -219.012516)
		(width 0.16002)
		(layer "In6.Cu")
		(net "M_E_CPU1_SA_DQS_DN<2>")
	)
	(segment
		(start 32.940752 -219.8624)
		(end 33.536636 -220.458284)
		(width 0.16002)
		(layer "In6.Cu")
		(net "M_E_CPU1_SA_DQS_DN<2>")
	)
	(segment
		(start 75.955906 -235.04144)
		(end 75.979528 -235.04144)
		(width 0.09525)
		(layer "In6.Cu")
		(net "M_E_CPU1_SA_DQS_DN<2>")
	)
	(segment
		(start 42.815002 -219.361258)
		(end 43.231308 -219.361258)
		(width 0.16002)
		(layer "In6.Cu")
		(net "M_E_CPU1_SA_DQS_DN<2>")
	)
	(segment
		(start 59.353196 -220.486986)
		(end 59.96432 -220.486986)
		(width 0.16002)
		(layer "In6.Cu")
		(net "M_E_CPU1_SA_DQS_DN<2>")
	)
	(segment
		(start 76.259436 -235.33989)
		(end 76.697332 -235.777786)
		(width 0.09525)
		(layer "In6.Cu")
		(net "M_E_CPU1_SA_DQS_DN<2>")
	)
	(segment
		(start 76.03871 -234.982258)
		(end 76.164186 -234.982258)
		(width 0.09525)
		(layer "In6.Cu")
		(net "M_E_CPU1_SA_DQS_DN<2>")
	)
	(segment
		(start 41.707816 -220.468444)
		(end 42.815002 -219.361258)
		(width 0.16002)
		(layer "In6.Cu")
		(net "M_E_CPU1_SA_DQS_DN<2>")
	)
	(segment
		(start 57.90311 -219.361258)
		(end 58.856118 -219.361258)
		(width 0.16002)
		(layer "In6.Cu")
		(net "M_E_CPU1_SA_DQS_DN<2>")
	)
	(segment
		(start 35.687508 -219.361258)
		(end 36.03625 -219.012516)
		(width 0.16002)
		(layer "In6.Cu")
		(net "M_E_CPU1_SA_DQS_DN<2>")
	)
	(segment
		(start 60.301378 -220.149928)
		(end 60.301378 -219.529406)
		(width 0.16002)
		(layer "In6.Cu")
		(net "M_E_CPU1_SA_DQS_DN<2>")
	)
	(segment
		(start 56.663844 -220.600524)
		(end 57.90311 -219.361258)
		(width 0.16002)
		(layer "In6.Cu")
		(net "M_E_CPU1_SA_DQS_DN<2>")
	)
	(segment
		(start 75.979528 -235.04144)
		(end 76.03871 -234.982258)
		(width 0.09525)
		(layer "In6.Cu")
		(net "M_E_CPU1_SA_DQS_DN<2>")
	)
	(segment
		(start 79.152496 -236.87532)
		(end 79.16291 -236.869224)
		(width 0.09525)
		(layer "In6.Cu")
		(net "M_E_CPU1_SA_DQS_DN<2>")
	)
	(segment
		(start 76.164186 -234.982258)
		(end 76.259436 -235.077508)
		(width 0.09525)
		(layer "In6.Cu")
		(net "M_E_CPU1_SA_DQS_DN<2>")
	)
	(segment
		(start 61.319156 -220.486986)
		(end 61.93028 -220.486986)
		(width 0.16002)
		(layer "In6.Cu")
		(net "M_E_CPU1_SA_DQS_DN<2>")
	)
	(segment
		(start 81.077054 -236.928914)
		(end 81.230978 -237.194344)
		(width 0.09525)
		(layer "In6.Cu")
		(net "M_E_CPU1_SA_DQS_DN<2>")
	)
	(segment
		(start 62.267338 -220.149928)
		(end 62.267338 -219.798646)
		(width 0.16002)
		(layer "In6.Cu")
		(net "M_E_CPU1_SA_DQS_DN<2>")
	)
	(segment
		(start 34.145728 -220.458284)
		(end 35.242754 -219.361258)
		(width 0.16002)
		(layer "In6.Cu")
		(net "M_E_CPU1_SA_DQS_DN<2>")
	)
	(segment
		(start 62.267338 -219.798646)
		(end 62.427358 -219.638626)
		(width 0.16002)
		(layer "In6.Cu")
		(net "M_E_CPU1_SA_DQS_DN<2>")
	)
	(segment
		(start 62.854078 -219.638626)
		(end 63.22949 -220.014038)
		(width 0.16002)
		(layer "In6.Cu")
		(net "M_E_CPU1_SA_DQS_DN<2>")
	)
	(segment
		(start 59.016138 -219.521278)
		(end 59.016138 -220.149928)
		(width 0.16002)
		(layer "In6.Cu")
		(net "M_E_CPU1_SA_DQS_DN<2>")
	)
	(segment
		(start 73.61809 -235.04144)
		(end 75.955906 -235.04144)
		(width 0.16002)
		(layer "In6.Cu")
		(net "M_E_CPU1_SA_DQS_DN<2>")
	)
	(segment
		(start 76.259436 -235.077508)
		(end 76.259436 -235.33989)
		(width 0.09525)
		(layer "In6.Cu")
		(net "M_E_CPU1_SA_DQS_DN<2>")
	)
	(segment
		(start 37.56787 -219.012516)
		(end 38.417754 -219.8624)
		(width 0.16002)
		(layer "In6.Cu")
		(net "M_E_CPU1_SA_DQS_DN<2>")
	)
	(segment
		(start 59.96432 -220.486986)
		(end 60.301378 -220.149928)
		(width 0.16002)
		(layer "In6.Cu")
		(net "M_E_CPU1_SA_DQS_DN<2>")
	)
	(segment
		(start 40.464232 -219.8624)
		(end 41.070276 -220.468444)
		(width 0.16002)
		(layer "In6.Cu")
		(net "M_E_CPU1_SA_DQS_DN<2>")
	)
	(segment
		(start 52.65674 -219.012516)
		(end 53.522118 -219.877894)
		(width 0.16002)
		(layer "In6.Cu")
		(net "M_E_CPU1_SA_DQS_DN<2>")
	)
	(segment
		(start 35.242754 -219.361258)
		(end 35.687508 -219.361258)
		(width 0.16002)
		(layer "In6.Cu")
		(net "M_E_CPU1_SA_DQS_DN<2>")
	)
	(segment
		(start 77.1271 -235.777786)
		(end 78.166976 -236.817662)
		(width 0.09525)
		(layer "In6.Cu")
		(net "M_E_CPU1_SA_DQS_DN<2>")
	)
	(segment
		(start 50.775362 -219.361258)
		(end 51.124104 -219.012516)
		(width 0.16002)
		(layer "In6.Cu")
		(net "M_E_CPU1_SA_DQS_DN<2>")
	)
	(segment
		(start 60.461398 -219.369386)
		(end 60.822078 -219.369386)
		(width 0.16002)
		(layer "In6.Cu")
		(net "M_E_CPU1_SA_DQS_DN<2>")
	)
	(segment
		(start 43.58005 -219.012516)
		(end 45.112686 -219.012516)
		(width 0.16002)
		(layer "In6.Cu")
		(net "M_E_CPU1_SA_DQS_DN<2>")
	)
	(segment
		(start 65.58153 -225.966528)
		(end 65.58153 -227.00488)
		(width 0.16002)
		(layer "In6.Cu")
		(net "M_E_CPU1_SA_DQS_DN<2>")
	)
	(segment
		(start 80.976216 -236.902244)
		(end 81.077054 -236.928914)
		(width 0.09525)
		(layer "In6.Cu")
		(net "M_E_CPU1_SA_DQS_DN<2>")
	)
	(segment
		(start 54.541674 -219.877894)
		(end 55.264304 -220.600524)
		(width 0.16002)
		(layer "In6.Cu")
		(net "M_E_CPU1_SA_DQS_DN<2>")
	)
	(segment
		(start 60.982098 -219.529406)
		(end 60.982098 -220.149928)
		(width 0.16002)
		(layer "In6.Cu")
		(net "M_E_CPU1_SA_DQS_DN<2>")
	)
	(segment
		(start 76.697332 -235.777786)
		(end 77.1271 -235.777786)
		(width 0.09525)
		(layer "In6.Cu")
		(net "M_E_CPU1_SA_DQS_DN<2>")
	)
	(segment
		(start 53.522118 -219.877894)
		(end 54.541674 -219.877894)
		(width 0.16002)
		(layer "In6.Cu")
		(net "M_E_CPU1_SA_DQS_DN<2>")
	)
	(segment
		(start 29.252164 -220.28531)
		(end 29.525976 -220.011498)
		(width 0.16002)
		(layer "In6.Cu")
		(net "M_E_CPU1_SA_DQS_DN<2>")
	)
	(segment
		(start 49.25187 -220.468444)
		(end 50.359056 -219.361258)
		(width 0.16002)
		(layer "In6.Cu")
		(net "M_E_CPU1_SA_DQS_DN<2>")
	)
	(segment
		(start 58.856118 -219.361258)
		(end 59.016138 -219.521278)
		(width 0.16002)
		(layer "In6.Cu")
		(net "M_E_CPU1_SA_DQS_DN<2>")
	)
	(segment
		(start 38.417754 -219.8624)
		(end 40.464232 -219.8624)
		(width 0.16002)
		(layer "In6.Cu")
		(net "M_E_CPU1_SA_DQS_DN<2>")
	)
	(segment
		(start 60.822078 -219.369386)
		(end 60.982098 -219.529406)
		(width 0.16002)
		(layer "In6.Cu")
		(net "M_E_CPU1_SA_DQS_DN<2>")
	)
	(segment
		(start 31.653988 -220.011498)
		(end 31.803086 -219.8624)
		(width 0.16002)
		(layer "In6.Cu")
		(net "M_E_CPU1_SA_DQS_DN<2>")
	)
	(arc
		(start 78.599792 -236.869224)
		(mid 78.875335 -236.945073)
		(end 79.152496 -236.87532)
		(width 0.09525)
		(layer "In6.Cu")
		(net "M_E_CPU1_SA_DQS_DN<2>")
	)
	(arc
		(start 79.55026 -236.87532)
		(mid 79.827168 -236.944997)
		(end 80.102456 -236.869224)
		(width 0.09525)
		(layer "In6.Cu")
		(net "M_E_CPU1_SA_DQS_DN<2>")
	)
	(arc
		(start 80.956404 -236.910118)
		(mid 80.966347 -236.906275)
		(end 80.976216 -236.902244)
		(width 0.09525)
		(layer "In6.Cu")
		(net "M_E_CPU1_SA_DQS_DN<2>")
	)
	(arc
		(start 78.41107 -236.817662)
		(mid 78.508826 -236.830996)
		(end 78.599792 -236.869224)
		(width 0.09525)
		(layer "In6.Cu")
		(net "M_E_CPU1_SA_DQS_DN<2>")
	)
	(arc
		(start 80.102456 -236.869224)
		(mid 80.286231 -236.818452)
		(end 80.471264 -236.864398)
		(width 0.09525)
		(layer "In6.Cu")
		(net "M_E_CPU1_SA_DQS_DN<2>")
	)
	(arc
		(start 80.479646 -236.869224)
		(mid 80.713441 -236.943091)
		(end 80.956404 -236.910118)
		(width 0.09525)
		(layer "In6.Cu")
		(net "M_E_CPU1_SA_DQS_DN<2>")
	)
	(arc
		(start 79.16291 -236.869224)
		(mid 79.351378 -236.818547)
		(end 79.539846 -236.869224)
		(width 0.09525)
		(layer "In6.Cu")
		(net "M_E_CPU1_SA_DQS_DN<2>")
	)
	(segment
		(start 81.69783 -232.600246)
		(end 81.230978 -232.334308)
		(width 0.12954)
		(layer "F.Cu")
		(net "M_E_CPU1_SA_DQS_DN<1>")
	)
	(segment
		(start 45.96257 -210.512406)
		(end 48.061118 -210.512406)
		(width 0.16002)
		(layer "In6.Cu")
		(net "M_E_CPU1_SA_DQS_DN<1>")
	)
	(segment
		(start 76.531724 -229.810564)
		(end 76.972922 -229.810564)
		(width 0.09525)
		(layer "In6.Cu")
		(net "M_E_CPU1_SA_DQS_DN<1>")
	)
	(segment
		(start 37.43071 -209.662522)
		(end 38.280594 -210.512406)
		(width 0.16002)
		(layer "In6.Cu")
		(net "M_E_CPU1_SA_DQS_DN<1>")
	)
	(segment
		(start 79.539846 -232.009188)
		(end 79.55026 -232.015284)
		(width 0.09525)
		(layer "In6.Cu")
		(net "M_E_CPU1_SA_DQS_DN<1>")
	)
	(segment
		(start 60.72759 -210.488022)
		(end 60.95365 -210.488022)
		(width 0.16002)
		(layer "In6.Cu")
		(net "M_E_CPU1_SA_DQS_DN<1>")
	)
	(segment
		(start 62.118748 -211.87918)
		(end 62.344808 -211.87918)
		(width 0.16002)
		(layer "In6.Cu")
		(net "M_E_CPU1_SA_DQS_DN<1>")
	)
	(segment
		(start 71.12127 -223.6597)
		(end 71.12127 -224.48393)
		(width 0.16002)
		(layer "In6.Cu")
		(net "M_E_CPU1_SA_DQS_DN<1>")
	)
	(segment
		(start 61.209682 -210.744054)
		(end 61.209682 -210.970114)
		(width 0.16002)
		(layer "In6.Cu")
		(net "M_E_CPU1_SA_DQS_DN<1>")
	)
	(segment
		(start 43.231308 -210.011264)
		(end 43.58005 -209.662522)
		(width 0.16002)
		(layer "In6.Cu")
		(net "M_E_CPU1_SA_DQS_DN<1>")
	)
	(segment
		(start 49.264316 -211.106004)
		(end 50.359056 -210.011264)
		(width 0.16002)
		(layer "In6.Cu")
		(net "M_E_CPU1_SA_DQS_DN<1>")
	)
	(segment
		(start 62.344808 -211.87918)
		(end 62.60084 -212.135212)
		(width 0.16002)
		(layer "In6.Cu")
		(net "M_E_CPU1_SA_DQS_DN<1>")
	)
	(segment
		(start 41.804082 -211.022184)
		(end 42.815002 -210.011264)
		(width 0.16002)
		(layer "In6.Cu")
		(net "M_E_CPU1_SA_DQS_DN<1>")
	)
	(segment
		(start 62.510162 -213.832186)
		(end 64.880998 -213.832186)
		(width 0.16002)
		(layer "In6.Cu")
		(net "M_E_CPU1_SA_DQS_DN<1>")
	)
	(segment
		(start 35.242754 -210.011264)
		(end 35.687508 -210.011264)
		(width 0.16002)
		(layer "In6.Cu")
		(net "M_E_CPU1_SA_DQS_DN<1>")
	)
	(segment
		(start 50.359056 -210.011264)
		(end 50.775362 -210.011264)
		(width 0.16002)
		(layer "In6.Cu")
		(net "M_E_CPU1_SA_DQS_DN<1>")
	)
	(segment
		(start 77.294486 -230.730298)
		(end 78.484984 -231.920796)
		(width 0.09525)
		(layer "In6.Cu")
		(net "M_E_CPU1_SA_DQS_DN<1>")
	)
	(segment
		(start 41.14165 -211.022184)
		(end 41.804082 -211.022184)
		(width 0.16002)
		(layer "In6.Cu")
		(net "M_E_CPU1_SA_DQS_DN<1>")
	)
	(segment
		(start 45.112686 -209.662522)
		(end 45.96257 -210.512406)
		(width 0.16002)
		(layer "In6.Cu")
		(net "M_E_CPU1_SA_DQS_DN<1>")
	)
	(segment
		(start 31.653988 -210.661504)
		(end 31.803086 -210.512406)
		(width 0.16002)
		(layer "In6.Cu")
		(net "M_E_CPU1_SA_DQS_DN<1>")
	)
	(segment
		(start 31.803086 -210.512406)
		(end 33.445704 -210.512406)
		(width 0.16002)
		(layer "In6.Cu")
		(net "M_E_CPU1_SA_DQS_DN<1>")
	)
	(segment
		(start 60.185046 -211.030566)
		(end 60.72759 -210.488022)
		(width 0.16002)
		(layer "In6.Cu")
		(net "M_E_CPU1_SA_DQS_DN<1>")
	)
	(segment
		(start 52.65674 -209.662522)
		(end 53.617622 -210.623404)
		(width 0.16002)
		(layer "In6.Cu")
		(net "M_E_CPU1_SA_DQS_DN<1>")
	)
	(segment
		(start 61.0997 -212.421724)
		(end 61.576204 -212.421724)
		(width 0.16002)
		(layer "In6.Cu")
		(net "M_E_CPU1_SA_DQS_DN<1>")
	)
	(segment
		(start 36.03625 -209.662522)
		(end 37.43071 -209.662522)
		(width 0.16002)
		(layer "In6.Cu")
		(net "M_E_CPU1_SA_DQS_DN<1>")
	)
	(segment
		(start 81.077054 -232.068878)
		(end 81.230978 -232.334308)
		(width 0.09525)
		(layer "In6.Cu")
		(net "M_E_CPU1_SA_DQS_DN<1>")
	)
	(segment
		(start 55.11673 -211.273644)
		(end 56.64073 -211.273644)
		(width 0.16002)
		(layer "In6.Cu")
		(net "M_E_CPU1_SA_DQS_DN<1>")
	)
	(segment
		(start 75.663552 -228.942392)
		(end 76.531724 -229.810564)
		(width 0.09525)
		(layer "In6.Cu")
		(net "M_E_CPU1_SA_DQS_DN<1>")
	)
	(segment
		(start 43.58005 -209.662522)
		(end 45.112686 -209.662522)
		(width 0.16002)
		(layer "In6.Cu")
		(net "M_E_CPU1_SA_DQS_DN<1>")
	)
	(segment
		(start 60.95365 -210.488022)
		(end 61.209682 -210.744054)
		(width 0.16002)
		(layer "In6.Cu")
		(net "M_E_CPU1_SA_DQS_DN<1>")
	)
	(segment
		(start 35.687508 -210.011264)
		(end 36.03625 -209.662522)
		(width 0.16002)
		(layer "In6.Cu")
		(net "M_E_CPU1_SA_DQS_DN<1>")
	)
	(segment
		(start 60.667138 -211.512658)
		(end 60.667138 -211.989162)
		(width 0.16002)
		(layer "In6.Cu")
		(net "M_E_CPU1_SA_DQS_DN<1>")
	)
	(segment
		(start 59.708542 -211.030566)
		(end 60.185046 -211.030566)
		(width 0.16002)
		(layer "In6.Cu")
		(net "M_E_CPU1_SA_DQS_DN<1>")
	)
	(segment
		(start 62.058296 -212.903816)
		(end 62.058296 -213.38032)
		(width 0.16002)
		(layer "In6.Cu")
		(net "M_E_CPU1_SA_DQS_DN<1>")
	)
	(segment
		(start 64.880998 -213.832186)
		(end 68.931028 -217.882216)
		(width 0.16002)
		(layer "In6.Cu")
		(net "M_E_CPU1_SA_DQS_DN<1>")
	)
	(segment
		(start 51.124104 -209.662522)
		(end 52.65674 -209.662522)
		(width 0.16002)
		(layer "In6.Cu")
		(net "M_E_CPU1_SA_DQS_DN<1>")
	)
	(segment
		(start 29.525976 -210.661504)
		(end 31.653988 -210.661504)
		(width 0.16002)
		(layer "In6.Cu")
		(net "M_E_CPU1_SA_DQS_DN<1>")
	)
	(segment
		(start 33.775142 -210.841844)
		(end 34.412174 -210.841844)
		(width 0.16002)
		(layer "In6.Cu")
		(net "M_E_CPU1_SA_DQS_DN<1>")
	)
	(segment
		(start 56.64073 -211.273644)
		(end 57.90311 -210.011264)
		(width 0.16002)
		(layer "In6.Cu")
		(net "M_E_CPU1_SA_DQS_DN<1>")
	)
	(segment
		(start 50.775362 -210.011264)
		(end 51.124104 -209.662522)
		(width 0.16002)
		(layer "In6.Cu")
		(net "M_E_CPU1_SA_DQS_DN<1>")
	)
	(segment
		(start 62.058296 -213.38032)
		(end 62.510162 -213.832186)
		(width 0.16002)
		(layer "In6.Cu")
		(net "M_E_CPU1_SA_DQS_DN<1>")
	)
	(segment
		(start 48.061118 -210.512406)
		(end 48.654716 -211.106004)
		(width 0.16002)
		(layer "In6.Cu")
		(net "M_E_CPU1_SA_DQS_DN<1>")
	)
	(segment
		(start 42.815002 -210.011264)
		(end 43.231308 -210.011264)
		(width 0.16002)
		(layer "In6.Cu")
		(net "M_E_CPU1_SA_DQS_DN<1>")
	)
	(segment
		(start 68.931028 -217.882216)
		(end 68.931028 -221.469458)
		(width 0.16002)
		(layer "In6.Cu")
		(net "M_E_CPU1_SA_DQS_DN<1>")
	)
	(segment
		(start 71.12127 -224.48393)
		(end 75.562968 -228.925628)
		(width 0.16002)
		(layer "In6.Cu")
		(net "M_E_CPU1_SA_DQS_DN<1>")
	)
	(segment
		(start 54.46649 -210.623404)
		(end 55.11673 -211.273644)
		(width 0.16002)
		(layer "In6.Cu")
		(net "M_E_CPU1_SA_DQS_DN<1>")
	)
	(segment
		(start 68.931028 -221.469458)
		(end 71.12127 -223.6597)
		(width 0.16002)
		(layer "In6.Cu")
		(net "M_E_CPU1_SA_DQS_DN<1>")
	)
	(segment
		(start 75.562968 -228.925628)
		(end 75.579732 -228.942392)
		(width 0.09525)
		(layer "In6.Cu")
		(net "M_E_CPU1_SA_DQS_DN<1>")
	)
	(segment
		(start 79.152496 -232.015284)
		(end 79.16291 -232.009188)
		(width 0.09525)
		(layer "In6.Cu")
		(net "M_E_CPU1_SA_DQS_DN<1>")
	)
	(segment
		(start 38.280594 -210.512406)
		(end 40.631872 -210.512406)
		(width 0.16002)
		(layer "In6.Cu")
		(net "M_E_CPU1_SA_DQS_DN<1>")
	)
	(segment
		(start 61.576204 -212.421724)
		(end 62.118748 -211.87918)
		(width 0.16002)
		(layer "In6.Cu")
		(net "M_E_CPU1_SA_DQS_DN<1>")
	)
	(segment
		(start 76.972922 -229.810564)
		(end 77.294486 -230.132128)
		(width 0.09525)
		(layer "In6.Cu")
		(net "M_E_CPU1_SA_DQS_DN<1>")
	)
	(segment
		(start 61.209682 -210.970114)
		(end 60.667138 -211.512658)
		(width 0.16002)
		(layer "In6.Cu")
		(net "M_E_CPU1_SA_DQS_DN<1>")
	)
	(segment
		(start 80.471264 -232.004362)
		(end 80.479646 -232.009188)
		(width 0.09525)
		(layer "In6.Cu")
		(net "M_E_CPU1_SA_DQS_DN<1>")
	)
	(segment
		(start 62.60084 -212.135212)
		(end 62.60084 -212.361272)
		(width 0.16002)
		(layer "In6.Cu")
		(net "M_E_CPU1_SA_DQS_DN<1>")
	)
	(segment
		(start 58.68924 -210.011264)
		(end 59.708542 -211.030566)
		(width 0.16002)
		(layer "In6.Cu")
		(net "M_E_CPU1_SA_DQS_DN<1>")
	)
	(segment
		(start 75.579732 -228.942392)
		(end 75.663552 -228.942392)
		(width 0.09525)
		(layer "In6.Cu")
		(net "M_E_CPU1_SA_DQS_DN<1>")
	)
	(segment
		(start 53.617622 -210.623404)
		(end 54.46649 -210.623404)
		(width 0.16002)
		(layer "In6.Cu")
		(net "M_E_CPU1_SA_DQS_DN<1>")
	)
	(segment
		(start 80.976216 -232.042208)
		(end 81.077054 -232.068878)
		(width 0.09525)
		(layer "In6.Cu")
		(net "M_E_CPU1_SA_DQS_DN<1>")
	)
	(segment
		(start 40.631872 -210.512406)
		(end 41.14165 -211.022184)
		(width 0.16002)
		(layer "In6.Cu")
		(net "M_E_CPU1_SA_DQS_DN<1>")
	)
	(segment
		(start 34.412174 -210.841844)
		(end 35.242754 -210.011264)
		(width 0.16002)
		(layer "In6.Cu")
		(net "M_E_CPU1_SA_DQS_DN<1>")
	)
	(segment
		(start 33.445704 -210.512406)
		(end 33.775142 -210.841844)
		(width 0.16002)
		(layer "In6.Cu")
		(net "M_E_CPU1_SA_DQS_DN<1>")
	)
	(segment
		(start 77.294486 -230.132128)
		(end 77.294486 -230.730298)
		(width 0.09525)
		(layer "In6.Cu")
		(net "M_E_CPU1_SA_DQS_DN<1>")
	)
	(segment
		(start 60.667138 -211.989162)
		(end 61.0997 -212.421724)
		(width 0.16002)
		(layer "In6.Cu")
		(net "M_E_CPU1_SA_DQS_DN<1>")
	)
	(segment
		(start 57.90311 -210.011264)
		(end 58.68924 -210.011264)
		(width 0.16002)
		(layer "In6.Cu")
		(net "M_E_CPU1_SA_DQS_DN<1>")
	)
	(segment
		(start 29.252164 -210.935316)
		(end 29.525976 -210.661504)
		(width 0.16002)
		(layer "In6.Cu")
		(net "M_E_CPU1_SA_DQS_DN<1>")
	)
	(segment
		(start 48.654716 -211.106004)
		(end 49.264316 -211.106004)
		(width 0.16002)
		(layer "In6.Cu")
		(net "M_E_CPU1_SA_DQS_DN<1>")
	)
	(segment
		(start 62.60084 -212.361272)
		(end 62.058296 -212.903816)
		(width 0.16002)
		(layer "In6.Cu")
		(net "M_E_CPU1_SA_DQS_DN<1>")
	)
	(arc
		(start 80.956404 -232.050082)
		(mid 80.966347 -232.046239)
		(end 80.976216 -232.042208)
		(width 0.09525)
		(layer "In6.Cu")
		(net "M_E_CPU1_SA_DQS_DN<1>")
	)
	(arc
		(start 79.16291 -232.009188)
		(mid 79.351378 -231.958511)
		(end 79.539846 -232.009188)
		(width 0.09525)
		(layer "In6.Cu")
		(net "M_E_CPU1_SA_DQS_DN<1>")
	)
	(arc
		(start 78.484984 -231.920796)
		(mid 78.539646 -231.968727)
		(end 78.600046 -232.009188)
		(width 0.09525)
		(layer "In6.Cu")
		(net "M_E_CPU1_SA_DQS_DN<1>")
	)
	(arc
		(start 79.55026 -232.015284)
		(mid 79.827168 -232.084961)
		(end 80.102456 -232.009188)
		(width 0.09525)
		(layer "In6.Cu")
		(net "M_E_CPU1_SA_DQS_DN<1>")
	)
	(arc
		(start 78.600046 -232.009188)
		(mid 78.875478 -232.085036)
		(end 79.152496 -232.015284)
		(width 0.09525)
		(layer "In6.Cu")
		(net "M_E_CPU1_SA_DQS_DN<1>")
	)
	(arc
		(start 80.479646 -232.009188)
		(mid 80.713441 -232.083055)
		(end 80.956404 -232.050082)
		(width 0.09525)
		(layer "In6.Cu")
		(net "M_E_CPU1_SA_DQS_DN<1>")
	)
	(arc
		(start 80.102456 -232.009188)
		(mid 80.286231 -231.958416)
		(end 80.471264 -232.004362)
		(width 0.09525)
		(layer "In6.Cu")
		(net "M_E_CPU1_SA_DQS_DN<1>")
	)
	(segment
		(start 81.69783 -227.740464)
		(end 81.230978 -227.474526)
		(width 0.12954)
		(layer "F.Cu")
		(net "M_E_CPU1_SA_DQS_DN<0>")
	)
	(segment
		(start 31.810706 -201.162412)
		(end 33.445704 -201.162412)
		(width 0.16002)
		(layer "In6.Cu")
		(net "M_E_CPU1_SA_DQS_DN<0>")
	)
	(segment
		(start 62.48273 -203.601066)
		(end 62.959234 -203.601066)
		(width 0.16002)
		(layer "In6.Cu")
		(net "M_E_CPU1_SA_DQS_DN<0>")
	)
	(segment
		(start 63.441326 -204.083158)
		(end 63.441326 -204.559662)
		(width 0.16002)
		(layer "In6.Cu")
		(net "M_E_CPU1_SA_DQS_DN<0>")
	)
	(segment
		(start 45.96257 -201.162412)
		(end 48.533558 -201.162412)
		(width 0.16002)
		(layer "In6.Cu")
		(net "M_E_CPU1_SA_DQS_DN<0>")
	)
	(segment
		(start 64.350392 -204.992224)
		(end 64.762126 -204.58049)
		(width 0.16002)
		(layer "In6.Cu")
		(net "M_E_CPU1_SA_DQS_DN<0>")
	)
	(segment
		(start 78.599538 -225.529394)
		(end 78.63205 -225.54819)
		(width 0.09525)
		(layer "In6.Cu")
		(net "M_E_CPU1_SA_DQS_DN<0>")
	)
	(segment
		(start 33.775142 -201.49185)
		(end 34.412174 -201.49185)
		(width 0.16002)
		(layer "In6.Cu")
		(net "M_E_CPU1_SA_DQS_DN<0>")
	)
	(segment
		(start 62.050168 -202.692)
		(end 62.050168 -203.168504)
		(width 0.16002)
		(layer "In6.Cu")
		(net "M_E_CPU1_SA_DQS_DN<0>")
	)
	(segment
		(start 77.606398 -222.25508)
		(end 77.690472 -222.25508)
		(width 0.09525)
		(layer "In6.Cu")
		(net "M_E_CPU1_SA_DQS_DN<0>")
	)
	(segment
		(start 51.124104 -200.312528)
		(end 52.65674 -200.312528)
		(width 0.16002)
		(layer "In6.Cu")
		(net "M_E_CPU1_SA_DQS_DN<0>")
	)
	(segment
		(start 79.069692 -226.3394)
		(end 79.101188 -226.357688)
		(width 0.09525)
		(layer "In6.Cu")
		(net "M_E_CPU1_SA_DQS_DN<0>")
	)
	(segment
		(start 61.091572 -202.209908)
		(end 61.568076 -202.209908)
		(width 0.16002)
		(layer "In6.Cu")
		(net "M_E_CPU1_SA_DQS_DN<0>")
	)
	(segment
		(start 56.322214 -201.484484)
		(end 57.079896 -201.484484)
		(width 0.16002)
		(layer "In6.Cu")
		(net "M_E_CPU1_SA_DQS_DN<0>")
	)
	(segment
		(start 35.242754 -200.66127)
		(end 35.687508 -200.66127)
		(width 0.16002)
		(layer "In6.Cu")
		(net "M_E_CPU1_SA_DQS_DN<0>")
	)
	(segment
		(start 35.687508 -200.66127)
		(end 36.03625 -200.312528)
		(width 0.16002)
		(layer "In6.Cu")
		(net "M_E_CPU1_SA_DQS_DN<0>")
	)
	(segment
		(start 40.989504 -201.162412)
		(end 41.318942 -201.49185)
		(width 0.16002)
		(layer "In6.Cu")
		(net "M_E_CPU1_SA_DQS_DN<0>")
	)
	(segment
		(start 64.762126 -204.58049)
		(end 64.988186 -204.58049)
		(width 0.16002)
		(layer "In6.Cu")
		(net "M_E_CPU1_SA_DQS_DN<0>")
	)
	(segment
		(start 62.461902 -202.280266)
		(end 62.050168 -202.692)
		(width 0.16002)
		(layer "In6.Cu")
		(net "M_E_CPU1_SA_DQS_DN<0>")
	)
	(segment
		(start 60.67425 -201.792586)
		(end 61.091572 -202.209908)
		(width 0.16002)
		(layer "In6.Cu")
		(net "M_E_CPU1_SA_DQS_DN<0>")
	)
	(segment
		(start 33.445704 -201.162412)
		(end 33.775142 -201.49185)
		(width 0.16002)
		(layer "In6.Cu")
		(net "M_E_CPU1_SA_DQS_DN<0>")
	)
	(segment
		(start 61.568076 -202.209908)
		(end 61.97981 -201.798174)
		(width 0.16002)
		(layer "In6.Cu")
		(net "M_E_CPU1_SA_DQS_DN<0>")
	)
	(segment
		(start 78.634336 -224.539556)
		(end 78.599538 -224.559622)
		(width 0.09525)
		(layer "In6.Cu")
		(net "M_E_CPU1_SA_DQS_DN<0>")
	)
	(segment
		(start 78.090014 -223.076516)
		(end 78.163166 -223.118934)
		(width 0.09525)
		(layer "In6.Cu")
		(net "M_E_CPU1_SA_DQS_DN<0>")
	)
	(segment
		(start 41.318942 -201.49185)
		(end 41.984422 -201.49185)
		(width 0.16002)
		(layer "In6.Cu")
		(net "M_E_CPU1_SA_DQS_DN<0>")
	)
	(segment
		(start 63.85306 -203.671424)
		(end 63.441326 -204.083158)
		(width 0.16002)
		(layer "In6.Cu")
		(net "M_E_CPU1_SA_DQS_DN<0>")
	)
	(segment
		(start 43.58005 -200.312528)
		(end 45.112686 -200.312528)
		(width 0.16002)
		(layer "In6.Cu")
		(net "M_E_CPU1_SA_DQS_DN<0>")
	)
	(segment
		(start 50.775362 -200.66127)
		(end 51.124104 -200.312528)
		(width 0.16002)
		(layer "In6.Cu")
		(net "M_E_CPU1_SA_DQS_DN<0>")
	)
	(segment
		(start 42.815002 -200.66127)
		(end 43.231308 -200.66127)
		(width 0.16002)
		(layer "In6.Cu")
		(net "M_E_CPU1_SA_DQS_DN<0>")
	)
	(segment
		(start 63.873888 -204.992224)
		(end 64.350392 -204.992224)
		(width 0.16002)
		(layer "In6.Cu")
		(net "M_E_CPU1_SA_DQS_DN<0>")
	)
	(segment
		(start 61.97981 -201.798174)
		(end 62.20587 -201.798174)
		(width 0.16002)
		(layer "In6.Cu")
		(net "M_E_CPU1_SA_DQS_DN<0>")
	)
	(segment
		(start 80.471264 -227.14458)
		(end 80.479646 -227.149406)
		(width 0.09525)
		(layer "In6.Cu")
		(net "M_E_CPU1_SA_DQS_DN<0>")
	)
	(segment
		(start 54.86527 -201.384662)
		(end 54.86527 -201.83602)
		(width 0.16002)
		(layer "In6.Cu")
		(net "M_E_CPU1_SA_DQS_DN<0>")
	)
	(segment
		(start 55.77078 -202.210924)
		(end 56.145684 -201.83602)
		(width 0.16002)
		(layer "In6.Cu")
		(net "M_E_CPU1_SA_DQS_DN<0>")
	)
	(segment
		(start 36.03625 -200.312528)
		(end 37.441886 -200.312528)
		(width 0.16002)
		(layer "In6.Cu")
		(net "M_E_CPU1_SA_DQS_DN<0>")
	)
	(segment
		(start 66.530474 -206.979266)
		(end 74.75855 -215.207342)
		(width 0.16002)
		(layer "In6.Cu")
		(net "M_E_CPU1_SA_DQS_DN<0>")
	)
	(segment
		(start 62.959234 -203.601066)
		(end 63.370968 -203.189332)
		(width 0.16002)
		(layer "In6.Cu")
		(net "M_E_CPU1_SA_DQS_DN<0>")
	)
	(segment
		(start 64.832484 -205.95082)
		(end 65.86093 -206.979266)
		(width 0.16002)
		(layer "In6.Cu")
		(net "M_E_CPU1_SA_DQS_DN<0>")
	)
	(segment
		(start 55.240174 -202.210924)
		(end 55.77078 -202.210924)
		(width 0.16002)
		(layer "In6.Cu")
		(net "M_E_CPU1_SA_DQS_DN<0>")
	)
	(segment
		(start 77.8383 -222.402908)
		(end 77.8383 -222.594932)
		(width 0.09525)
		(layer "In6.Cu")
		(net "M_E_CPU1_SA_DQS_DN<0>")
	)
	(segment
		(start 81.077054 -227.209096)
		(end 81.230978 -227.474526)
		(width 0.09525)
		(layer "In6.Cu")
		(net "M_E_CPU1_SA_DQS_DN<0>")
	)
	(segment
		(start 56.145684 -201.661014)
		(end 56.322214 -201.484484)
		(width 0.16002)
		(layer "In6.Cu")
		(net "M_E_CPU1_SA_DQS_DN<0>")
	)
	(segment
		(start 62.050168 -203.168504)
		(end 62.48273 -203.601066)
		(width 0.16002)
		(layer "In6.Cu")
		(net "M_E_CPU1_SA_DQS_DN<0>")
	)
	(segment
		(start 57.90311 -200.66127)
		(end 58.580274 -200.66127)
		(width 0.16002)
		(layer "In6.Cu")
		(net "M_E_CPU1_SA_DQS_DN<0>")
	)
	(segment
		(start 52.65674 -200.312528)
		(end 53.522118 -201.177906)
		(width 0.16002)
		(layer "In6.Cu")
		(net "M_E_CPU1_SA_DQS_DN<0>")
	)
	(segment
		(start 77.589634 -222.238316)
		(end 77.606398 -222.25508)
		(width 0.09525)
		(layer "In6.Cu")
		(net "M_E_CPU1_SA_DQS_DN<0>")
	)
	(segment
		(start 78.599538 -224.559622)
		(end 78.564486 -224.580196)
		(width 0.09525)
		(layer "In6.Cu")
		(net "M_E_CPU1_SA_DQS_DN<0>")
	)
	(segment
		(start 29.525976 -201.31151)
		(end 31.661608 -201.31151)
		(width 0.16002)
		(layer "In6.Cu")
		(net "M_E_CPU1_SA_DQS_DN<0>")
	)
	(segment
		(start 62.20587 -201.798174)
		(end 62.461902 -202.054206)
		(width 0.16002)
		(layer "In6.Cu")
		(net "M_E_CPU1_SA_DQS_DN<0>")
	)
	(segment
		(start 38.29177 -201.162412)
		(end 40.989504 -201.162412)
		(width 0.16002)
		(layer "In6.Cu")
		(net "M_E_CPU1_SA_DQS_DN<0>")
	)
	(segment
		(start 29.252164 -201.585322)
		(end 29.525976 -201.31151)
		(width 0.16002)
		(layer "In6.Cu")
		(net "M_E_CPU1_SA_DQS_DN<0>")
	)
	(segment
		(start 79.031592 -226.317302)
		(end 79.069692 -226.3394)
		(width 0.09525)
		(layer "In6.Cu")
		(net "M_E_CPU1_SA_DQS_DN<0>")
	)
	(segment
		(start 58.580274 -200.66127)
		(end 59.71159 -201.792586)
		(width 0.16002)
		(layer "In6.Cu")
		(net "M_E_CPU1_SA_DQS_DN<0>")
	)
	(segment
		(start 54.86527 -201.83602)
		(end 55.240174 -202.210924)
		(width 0.16002)
		(layer "In6.Cu")
		(net "M_E_CPU1_SA_DQS_DN<0>")
	)
	(segment
		(start 49.528476 -201.49185)
		(end 50.359056 -200.66127)
		(width 0.16002)
		(layer "In6.Cu")
		(net "M_E_CPU1_SA_DQS_DN<0>")
	)
	(segment
		(start 74.75855 -215.207342)
		(end 74.75855 -219.407232)
		(width 0.16002)
		(layer "In6.Cu")
		(net "M_E_CPU1_SA_DQS_DN<0>")
	)
	(segment
		(start 50.359056 -200.66127)
		(end 50.775362 -200.66127)
		(width 0.16002)
		(layer "In6.Cu")
		(net "M_E_CPU1_SA_DQS_DN<0>")
	)
	(segment
		(start 63.441326 -204.559662)
		(end 63.873888 -204.992224)
		(width 0.16002)
		(layer "In6.Cu")
		(net "M_E_CPU1_SA_DQS_DN<0>")
	)
	(segment
		(start 59.71159 -201.792586)
		(end 60.67425 -201.792586)
		(width 0.16002)
		(layer "In6.Cu")
		(net "M_E_CPU1_SA_DQS_DN<0>")
	)
	(segment
		(start 62.461902 -202.054206)
		(end 62.461902 -202.280266)
		(width 0.16002)
		(layer "In6.Cu")
		(net "M_E_CPU1_SA_DQS_DN<0>")
	)
	(segment
		(start 57.079896 -201.484484)
		(end 57.90311 -200.66127)
		(width 0.16002)
		(layer "In6.Cu")
		(net "M_E_CPU1_SA_DQS_DN<0>")
	)
	(segment
		(start 79.539846 -227.149406)
		(end 79.55026 -227.155502)
		(width 0.09525)
		(layer "In6.Cu")
		(net "M_E_CPU1_SA_DQS_DN<0>")
	)
	(segment
		(start 65.86093 -206.979266)
		(end 66.530474 -206.979266)
		(width 0.16002)
		(layer "In6.Cu")
		(net "M_E_CPU1_SA_DQS_DN<0>")
	)
	(segment
		(start 78.599538 -223.909382)
		(end 78.634336 -223.929448)
		(width 0.09525)
		(layer "In6.Cu")
		(net "M_E_CPU1_SA_DQS_DN<0>")
	)
	(segment
		(start 64.832484 -205.474316)
		(end 64.832484 -205.95082)
		(width 0.16002)
		(layer "In6.Cu")
		(net "M_E_CPU1_SA_DQS_DN<0>")
	)
	(segment
		(start 37.441886 -200.312528)
		(end 38.29177 -201.162412)
		(width 0.16002)
		(layer "In6.Cu")
		(net "M_E_CPU1_SA_DQS_DN<0>")
	)
	(segment
		(start 56.145684 -201.83602)
		(end 56.145684 -201.661014)
		(width 0.16002)
		(layer "In6.Cu")
		(net "M_E_CPU1_SA_DQS_DN<0>")
	)
	(segment
		(start 48.533558 -201.162412)
		(end 48.862996 -201.49185)
		(width 0.16002)
		(layer "In6.Cu")
		(net "M_E_CPU1_SA_DQS_DN<0>")
	)
	(segment
		(start 63.370968 -203.189332)
		(end 63.597028 -203.189332)
		(width 0.16002)
		(layer "In6.Cu")
		(net "M_E_CPU1_SA_DQS_DN<0>")
	)
	(segment
		(start 43.231308 -200.66127)
		(end 43.58005 -200.312528)
		(width 0.16002)
		(layer "In6.Cu")
		(net "M_E_CPU1_SA_DQS_DN<0>")
	)
	(segment
		(start 79.501492 -227.127308)
		(end 79.539592 -227.149406)
		(width 0.09525)
		(layer "In6.Cu")
		(net "M_E_CPU1_SA_DQS_DN<0>")
	)
	(segment
		(start 77.690472 -222.25508)
		(end 77.8383 -222.402908)
		(width 0.09525)
		(layer "In6.Cu")
		(net "M_E_CPU1_SA_DQS_DN<0>")
	)
	(segment
		(start 78.564486 -225.50882)
		(end 78.599538 -225.529394)
		(width 0.09525)
		(layer "In6.Cu")
		(net "M_E_CPU1_SA_DQS_DN<0>")
	)
	(segment
		(start 80.976216 -227.182426)
		(end 81.077054 -227.209096)
		(width 0.09525)
		(layer "In6.Cu")
		(net "M_E_CPU1_SA_DQS_DN<0>")
	)
	(segment
		(start 78.561438 -223.887284)
		(end 78.599538 -223.909382)
		(width 0.09525)
		(layer "In6.Cu")
		(net "M_E_CPU1_SA_DQS_DN<0>")
	)
	(segment
		(start 79.539592 -227.149406)
		(end 79.539846 -227.149406)
		(width 0.09525)
		(layer "In6.Cu")
		(net "M_E_CPU1_SA_DQS_DN<0>")
	)
	(segment
		(start 34.412174 -201.49185)
		(end 35.242754 -200.66127)
		(width 0.16002)
		(layer "In6.Cu")
		(net "M_E_CPU1_SA_DQS_DN<0>")
	)
	(segment
		(start 65.244218 -205.062582)
		(end 64.832484 -205.474316)
		(width 0.16002)
		(layer "In6.Cu")
		(net "M_E_CPU1_SA_DQS_DN<0>")
	)
	(segment
		(start 64.988186 -204.58049)
		(end 65.244218 -204.836522)
		(width 0.16002)
		(layer "In6.Cu")
		(net "M_E_CPU1_SA_DQS_DN<0>")
	)
	(segment
		(start 74.75855 -219.407232)
		(end 77.589634 -222.238316)
		(width 0.16002)
		(layer "In6.Cu")
		(net "M_E_CPU1_SA_DQS_DN<0>")
	)
	(segment
		(start 63.597028 -203.189332)
		(end 63.85306 -203.445364)
		(width 0.16002)
		(layer "In6.Cu")
		(net "M_E_CPU1_SA_DQS_DN<0>")
	)
	(segment
		(start 54.658514 -201.177906)
		(end 54.86527 -201.384662)
		(width 0.16002)
		(layer "In6.Cu")
		(net "M_E_CPU1_SA_DQS_DN<0>")
	)
	(segment
		(start 45.112686 -200.312528)
		(end 45.96257 -201.162412)
		(width 0.16002)
		(layer "In6.Cu")
		(net "M_E_CPU1_SA_DQS_DN<0>")
	)
	(segment
		(start 31.661608 -201.31151)
		(end 31.810706 -201.162412)
		(width 0.16002)
		(layer "In6.Cu")
		(net "M_E_CPU1_SA_DQS_DN<0>")
	)
	(segment
		(start 65.244218 -204.836522)
		(end 65.244218 -205.062582)
		(width 0.16002)
		(layer "In6.Cu")
		(net "M_E_CPU1_SA_DQS_DN<0>")
	)
	(segment
		(start 41.984422 -201.49185)
		(end 42.815002 -200.66127)
		(width 0.16002)
		(layer "In6.Cu")
		(net "M_E_CPU1_SA_DQS_DN<0>")
	)
	(segment
		(start 53.522118 -201.177906)
		(end 54.658514 -201.177906)
		(width 0.16002)
		(layer "In6.Cu")
		(net "M_E_CPU1_SA_DQS_DN<0>")
	)
	(segment
		(start 63.85306 -203.445364)
		(end 63.85306 -203.671424)
		(width 0.16002)
		(layer "In6.Cu")
		(net "M_E_CPU1_SA_DQS_DN<0>")
	)
	(segment
		(start 48.862996 -201.49185)
		(end 49.528476 -201.49185)
		(width 0.16002)
		(layer "In6.Cu")
		(net "M_E_CPU1_SA_DQS_DN<0>")
	)
	(arc
		(start 77.8383 -222.594932)
		(mid 77.905082 -222.866599)
		(end 78.090014 -223.076516)
		(width 0.09525)
		(layer "In6.Cu")
		(net "M_E_CPU1_SA_DQS_DN<0>")
	)
	(arc
		(start 78.788768 -225.854514)
		(mid 78.853165 -226.11582)
		(end 79.031592 -226.317302)
		(width 0.09525)
		(layer "In6.Cu")
		(net "M_E_CPU1_SA_DQS_DN<0>")
	)
	(arc
		(start 78.634336 -223.929448)
		(mid 78.788995 -224.234502)
		(end 78.634336 -224.539556)
		(width 0.09525)
		(layer "In6.Cu")
		(net "M_E_CPU1_SA_DQS_DN<0>")
	)
	(arc
		(start 78.163166 -223.118934)
		(mid 78.277545 -223.253073)
		(end 78.318614 -223.424496)
		(width 0.09525)
		(layer "In6.Cu")
		(net "M_E_CPU1_SA_DQS_DN<0>")
	)
	(arc
		(start 78.63205 -225.54819)
		(mid 78.747324 -225.682468)
		(end 78.788768 -225.854514)
		(width 0.09525)
		(layer "In6.Cu")
		(net "M_E_CPU1_SA_DQS_DN<0>")
	)
	(arc
		(start 78.318614 -223.424496)
		(mid 78.383011 -223.685802)
		(end 78.561438 -223.887284)
		(width 0.09525)
		(layer "In6.Cu")
		(net "M_E_CPU1_SA_DQS_DN<0>")
	)
	(arc
		(start 79.55026 -227.155502)
		(mid 79.827168 -227.225179)
		(end 80.102456 -227.149406)
		(width 0.09525)
		(layer "In6.Cu")
		(net "M_E_CPU1_SA_DQS_DN<0>")
	)
	(arc
		(start 79.258668 -226.66452)
		(mid 79.323065 -226.925826)
		(end 79.501492 -227.127308)
		(width 0.09525)
		(layer "In6.Cu")
		(net "M_E_CPU1_SA_DQS_DN<0>")
	)
	(arc
		(start 79.101188 -226.357688)
		(mid 79.216986 -226.492082)
		(end 79.258668 -226.66452)
		(width 0.09525)
		(layer "In6.Cu")
		(net "M_E_CPU1_SA_DQS_DN<0>")
	)
	(arc
		(start 78.564486 -224.580196)
		(mid 78.318834 -225.044508)
		(end 78.564486 -225.50882)
		(width 0.09525)
		(layer "In6.Cu")
		(net "M_E_CPU1_SA_DQS_DN<0>")
	)
	(arc
		(start 80.102456 -227.149406)
		(mid 80.286231 -227.098634)
		(end 80.471264 -227.14458)
		(width 0.09525)
		(layer "In6.Cu")
		(net "M_E_CPU1_SA_DQS_DN<0>")
	)
	(arc
		(start 80.479646 -227.149406)
		(mid 80.724072 -227.224049)
		(end 80.976216 -227.182426)
		(width 0.09525)
		(layer "In6.Cu")
		(net "M_E_CPU1_SA_DQS_DN<0>")
	)
	(segment
		(start 82.637884 -230.980234)
		(end 82.171032 -230.71455)
		(width 0.10668)
		(layer "F.Cu")
		(net "M_E_CPU1_SA_DQ<9>")
	)
	(segment
		(start 49.096168 -209.030316)
		(end 49.096168 -208.97342)
		(width 0.14478)
		(layer "In6.Cu")
		(net "M_E_CPU1_SA_DQ<9>")
	)
	(segment
		(start 55.945024 -208.97342)
		(end 55.945024 -209.037936)
		(width 0.14478)
		(layer "In6.Cu")
		(net "M_E_CPU1_SA_DQ<9>")
	)
	(segment
		(start 58.442606 -207.960468)
		(end 58.605674 -208.123536)
		(width 0.14478)
		(layer "In6.Cu")
		(net "M_E_CPU1_SA_DQ<9>")
	)
	(segment
		(start 72.436736 -223.108012)
		(end 72.436736 -223.931226)
		(width 0.14478)
		(layer "In6.Cu")
		(net "M_E_CPU1_SA_DQ<9>")
	)
	(segment
		(start 76.908406 -229.175564)
		(end 77.2287 -229.175564)
		(width 0.0889)
		(layer "In6.Cu")
		(net "M_E_CPU1_SA_DQ<9>")
	)
	(segment
		(start 30.836362 -208.580228)
		(end 30.99943 -208.41716)
		(width 0.14478)
		(layer "In6.Cu")
		(net "M_E_CPU1_SA_DQ<9>")
	)
	(segment
		(start 72.436736 -223.931226)
		(end 75.82408 -227.31857)
		(width 0.14478)
		(layer "In6.Cu")
		(net "M_E_CPU1_SA_DQ<9>")
	)
	(segment
		(start 56.501538 -209.037936)
		(end 56.501538 -208.97342)
		(width 0.14478)
		(layer "In6.Cu")
		(net "M_E_CPU1_SA_DQ<9>")
	)
	(segment
		(start 40.92067 -208.97342)
		(end 40.92067 -209.037936)
		(width 0.14478)
		(layer "In6.Cu")
		(net "M_E_CPU1_SA_DQ<9>")
	)
	(segment
		(start 59.162188 -208.189576)
		(end 59.162188 -208.123536)
		(width 0.14478)
		(layer "In6.Cu")
		(net "M_E_CPU1_SA_DQ<9>")
	)
	(segment
		(start 31.392876 -208.580228)
		(end 31.392876 -209.037682)
		(width 0.14478)
		(layer "In6.Cu")
		(net "M_E_CPU1_SA_DQ<9>")
	)
	(segment
		(start 30.99943 -208.41716)
		(end 31.229808 -208.41716)
		(width 0.14478)
		(layer "In6.Cu")
		(net "M_E_CPU1_SA_DQ<9>")
	)
	(segment
		(start 60.863226 -207.960468)
		(end 70.251066 -217.348308)
		(width 0.14478)
		(layer "In6.Cu")
		(net "M_E_CPU1_SA_DQ<9>")
	)
	(segment
		(start 54.831996 -208.97342)
		(end 54.831996 -209.037936)
		(width 0.14478)
		(layer "In6.Cu")
		(net "M_E_CPU1_SA_DQ<9>")
	)
	(segment
		(start 58.029094 -207.960468)
		(end 58.442606 -207.960468)
		(width 0.14478)
		(layer "In6.Cu")
		(net "M_E_CPU1_SA_DQ<9>")
	)
	(segment
		(start 48.539654 -209.030316)
		(end 48.702722 -209.193384)
		(width 0.14478)
		(layer "In6.Cu")
		(net "M_E_CPU1_SA_DQ<9>")
	)
	(segment
		(start 41.477184 -209.037936)
		(end 41.477184 -208.97342)
		(width 0.14478)
		(layer "In6.Cu")
		(net "M_E_CPU1_SA_DQ<9>")
	)
	(segment
		(start 30.836362 -209.037682)
		(end 30.836362 -208.580228)
		(width 0.14478)
		(layer "In6.Cu")
		(net "M_E_CPU1_SA_DQ<9>")
	)
	(segment
		(start 31.94939 -208.97342)
		(end 32.112458 -208.810352)
		(width 0.14478)
		(layer "In6.Cu")
		(net "M_E_CPU1_SA_DQ<9>")
	)
	(segment
		(start 48.9331 -209.193384)
		(end 49.096168 -209.030316)
		(width 0.14478)
		(layer "In6.Cu")
		(net "M_E_CPU1_SA_DQ<9>")
	)
	(segment
		(start 29.677106 -208.810352)
		(end 30.11678 -208.810352)
		(width 0.14478)
		(layer "In6.Cu")
		(net "M_E_CPU1_SA_DQ<9>")
	)
	(segment
		(start 31.786322 -209.20075)
		(end 31.94939 -209.037682)
		(width 0.14478)
		(layer "In6.Cu")
		(net "M_E_CPU1_SA_DQ<9>")
	)
	(segment
		(start 82.302858 -231.063038)
		(end 82.324956 -230.97998)
		(width 0.0889)
		(layer "In6.Cu")
		(net "M_E_CPU1_SA_DQ<9>")
	)
	(segment
		(start 78.164182 -230.111046)
		(end 78.639924 -230.111046)
		(width 0.0889)
		(layer "In6.Cu")
		(net "M_E_CPU1_SA_DQ<9>")
	)
	(segment
		(start 82.324956 -230.97998)
		(end 82.171032 -230.71455)
		(width 0.0889)
		(layer "In6.Cu")
		(net "M_E_CPU1_SA_DQ<9>")
	)
	(segment
		(start 30.279848 -209.037682)
		(end 30.442916 -209.20075)
		(width 0.14478)
		(layer "In6.Cu")
		(net "M_E_CPU1_SA_DQ<9>")
	)
	(segment
		(start 76.442316 -228.709474)
		(end 76.908406 -229.175564)
		(width 0.0889)
		(layer "In6.Cu")
		(net "M_E_CPU1_SA_DQ<9>")
	)
	(segment
		(start 75.82408 -227.31857)
		(end 76.442316 -227.936806)
		(width 0.0889)
		(layer "In6.Cu")
		(net "M_E_CPU1_SA_DQ<9>")
	)
	(segment
		(start 59.162188 -208.123536)
		(end 59.325256 -207.960468)
		(width 0.14478)
		(layer "In6.Cu")
		(net "M_E_CPU1_SA_DQ<9>")
	)
	(segment
		(start 59.88177 -208.352644)
		(end 60.112148 -208.352644)
		(width 0.14478)
		(layer "In6.Cu")
		(net "M_E_CPU1_SA_DQ<9>")
	)
	(segment
		(start 29.252164 -208.38541)
		(end 29.677106 -208.810352)
		(width 0.14478)
		(layer "In6.Cu")
		(net "M_E_CPU1_SA_DQ<9>")
	)
	(segment
		(start 31.555944 -209.20075)
		(end 31.786322 -209.20075)
		(width 0.14478)
		(layer "In6.Cu")
		(net "M_E_CPU1_SA_DQ<9>")
	)
	(segment
		(start 35.324034 -207.960468)
		(end 38.01491 -207.960468)
		(width 0.14478)
		(layer "In6.Cu")
		(net "M_E_CPU1_SA_DQ<9>")
	)
	(segment
		(start 46.540674 -208.810352)
		(end 48.376586 -208.810352)
		(width 0.14478)
		(layer "In6.Cu")
		(net "M_E_CPU1_SA_DQ<9>")
	)
	(segment
		(start 49.096168 -208.97342)
		(end 49.259236 -208.810352)
		(width 0.14478)
		(layer "In6.Cu")
		(net "M_E_CPU1_SA_DQ<9>")
	)
	(segment
		(start 58.605674 -208.123536)
		(end 58.605674 -208.189576)
		(width 0.14478)
		(layer "In6.Cu")
		(net "M_E_CPU1_SA_DQ<9>")
	)
	(segment
		(start 41.477184 -208.97342)
		(end 41.640252 -208.810352)
		(width 0.14478)
		(layer "In6.Cu")
		(net "M_E_CPU1_SA_DQ<9>")
	)
	(segment
		(start 54.831996 -209.037936)
		(end 54.995064 -209.201004)
		(width 0.14478)
		(layer "In6.Cu")
		(net "M_E_CPU1_SA_DQ<9>")
	)
	(segment
		(start 57.17921 -208.810352)
		(end 58.029094 -207.960468)
		(width 0.14478)
		(layer "In6.Cu")
		(net "M_E_CPU1_SA_DQ<9>")
	)
	(segment
		(start 48.376586 -208.810352)
		(end 48.539654 -208.97342)
		(width 0.14478)
		(layer "In6.Cu")
		(net "M_E_CPU1_SA_DQ<9>")
	)
	(segment
		(start 77.2287 -229.175564)
		(end 78.164182 -230.111046)
		(width 0.0889)
		(layer "In6.Cu")
		(net "M_E_CPU1_SA_DQ<9>")
	)
	(segment
		(start 58.768742 -208.352644)
		(end 58.99912 -208.352644)
		(width 0.14478)
		(layer "In6.Cu")
		(net "M_E_CPU1_SA_DQ<9>")
	)
	(segment
		(start 30.442916 -209.20075)
		(end 30.673294 -209.20075)
		(width 0.14478)
		(layer "In6.Cu")
		(net "M_E_CPU1_SA_DQ<9>")
	)
	(segment
		(start 70.251066 -220.922342)
		(end 72.436736 -223.108012)
		(width 0.14478)
		(layer "In6.Cu")
		(net "M_E_CPU1_SA_DQ<9>")
	)
	(segment
		(start 56.108092 -209.201004)
		(end 56.33847 -209.201004)
		(width 0.14478)
		(layer "In6.Cu")
		(net "M_E_CPU1_SA_DQ<9>")
	)
	(segment
		(start 30.11678 -208.810352)
		(end 30.279848 -208.97342)
		(width 0.14478)
		(layer "In6.Cu")
		(net "M_E_CPU1_SA_DQ<9>")
	)
	(segment
		(start 38.01491 -207.960468)
		(end 38.864794 -208.810352)
		(width 0.14478)
		(layer "In6.Cu")
		(net "M_E_CPU1_SA_DQ<9>")
	)
	(segment
		(start 40.757602 -208.810352)
		(end 40.92067 -208.97342)
		(width 0.14478)
		(layer "In6.Cu")
		(net "M_E_CPU1_SA_DQ<9>")
	)
	(segment
		(start 59.718702 -208.123536)
		(end 59.718702 -208.189576)
		(width 0.14478)
		(layer "In6.Cu")
		(net "M_E_CPU1_SA_DQ<9>")
	)
	(segment
		(start 55.38851 -208.97342)
		(end 55.551578 -208.810352)
		(width 0.14478)
		(layer "In6.Cu")
		(net "M_E_CPU1_SA_DQ<9>")
	)
	(segment
		(start 54.995064 -209.201004)
		(end 55.225442 -209.201004)
		(width 0.14478)
		(layer "In6.Cu")
		(net "M_E_CPU1_SA_DQ<9>")
	)
	(segment
		(start 78.639924 -230.111046)
		(end 79.328264 -230.799386)
		(width 0.0889)
		(layer "In6.Cu")
		(net "M_E_CPU1_SA_DQ<9>")
	)
	(segment
		(start 81.044034 -231.036876)
		(end 81.052416 -231.041702)
		(width 0.0889)
		(layer "In6.Cu")
		(net "M_E_CPU1_SA_DQ<9>")
	)
	(segment
		(start 56.501538 -208.97342)
		(end 56.664606 -208.810352)
		(width 0.14478)
		(layer "In6.Cu")
		(net "M_E_CPU1_SA_DQ<9>")
	)
	(segment
		(start 55.38851 -209.037936)
		(end 55.38851 -208.97342)
		(width 0.14478)
		(layer "In6.Cu")
		(net "M_E_CPU1_SA_DQ<9>")
	)
	(segment
		(start 60.438284 -207.960468)
		(end 60.863226 -207.960468)
		(width 0.14478)
		(layer "In6.Cu")
		(net "M_E_CPU1_SA_DQ<9>")
	)
	(segment
		(start 76.442316 -227.936806)
		(end 76.442316 -228.709474)
		(width 0.0889)
		(layer "In6.Cu")
		(net "M_E_CPU1_SA_DQ<9>")
	)
	(segment
		(start 31.229808 -208.41716)
		(end 31.392876 -208.580228)
		(width 0.14478)
		(layer "In6.Cu")
		(net "M_E_CPU1_SA_DQ<9>")
	)
	(segment
		(start 55.945024 -209.037936)
		(end 56.108092 -209.201004)
		(width 0.14478)
		(layer "In6.Cu")
		(net "M_E_CPU1_SA_DQ<9>")
	)
	(segment
		(start 56.33847 -209.201004)
		(end 56.501538 -209.037936)
		(width 0.14478)
		(layer "In6.Cu")
		(net "M_E_CPU1_SA_DQ<9>")
	)
	(segment
		(start 54.668928 -208.810352)
		(end 54.831996 -208.97342)
		(width 0.14478)
		(layer "In6.Cu")
		(net "M_E_CPU1_SA_DQ<9>")
	)
	(segment
		(start 41.640252 -208.810352)
		(end 41.97985 -208.810352)
		(width 0.14478)
		(layer "In6.Cu")
		(net "M_E_CPU1_SA_DQ<9>")
	)
	(segment
		(start 59.555634 -207.960468)
		(end 59.718702 -208.123536)
		(width 0.14478)
		(layer "In6.Cu")
		(net "M_E_CPU1_SA_DQ<9>")
	)
	(segment
		(start 80.46974 -231.041702)
		(end 80.478122 -231.036876)
		(width 0.0889)
		(layer "In6.Cu")
		(net "M_E_CPU1_SA_DQ<9>")
	)
	(segment
		(start 30.673294 -209.20075)
		(end 30.836362 -209.037682)
		(width 0.14478)
		(layer "In6.Cu")
		(net "M_E_CPU1_SA_DQ<9>")
	)
	(segment
		(start 53.23459 -207.960468)
		(end 54.084474 -208.810352)
		(width 0.14478)
		(layer "In6.Cu")
		(net "M_E_CPU1_SA_DQ<9>")
	)
	(segment
		(start 32.112458 -208.810352)
		(end 34.47415 -208.810352)
		(width 0.14478)
		(layer "In6.Cu")
		(net "M_E_CPU1_SA_DQ<9>")
	)
	(segment
		(start 41.97985 -208.810352)
		(end 42.829734 -207.960468)
		(width 0.14478)
		(layer "In6.Cu")
		(net "M_E_CPU1_SA_DQ<9>")
	)
	(segment
		(start 49.259236 -208.810352)
		(end 49.63541 -208.810352)
		(width 0.14478)
		(layer "In6.Cu")
		(net "M_E_CPU1_SA_DQ<9>")
	)
	(segment
		(start 54.084474 -208.810352)
		(end 54.668928 -208.810352)
		(width 0.14478)
		(layer "In6.Cu")
		(net "M_E_CPU1_SA_DQ<9>")
	)
	(segment
		(start 58.605674 -208.189576)
		(end 58.768742 -208.352644)
		(width 0.14478)
		(layer "In6.Cu")
		(net "M_E_CPU1_SA_DQ<9>")
	)
	(segment
		(start 58.99912 -208.352644)
		(end 59.162188 -208.189576)
		(width 0.14478)
		(layer "In6.Cu")
		(net "M_E_CPU1_SA_DQ<9>")
	)
	(segment
		(start 70.251066 -217.348308)
		(end 70.251066 -220.922342)
		(width 0.14478)
		(layer "In6.Cu")
		(net "M_E_CPU1_SA_DQ<9>")
	)
	(segment
		(start 31.94939 -209.037682)
		(end 31.94939 -208.97342)
		(width 0.14478)
		(layer "In6.Cu")
		(net "M_E_CPU1_SA_DQ<9>")
	)
	(segment
		(start 41.083738 -209.201004)
		(end 41.314116 -209.201004)
		(width 0.14478)
		(layer "In6.Cu")
		(net "M_E_CPU1_SA_DQ<9>")
	)
	(segment
		(start 59.325256 -207.960468)
		(end 59.555634 -207.960468)
		(width 0.14478)
		(layer "In6.Cu")
		(net "M_E_CPU1_SA_DQ<9>")
	)
	(segment
		(start 41.314116 -209.201004)
		(end 41.477184 -209.037936)
		(width 0.14478)
		(layer "In6.Cu")
		(net "M_E_CPU1_SA_DQ<9>")
	)
	(segment
		(start 48.702722 -209.193384)
		(end 48.9331 -209.193384)
		(width 0.14478)
		(layer "In6.Cu")
		(net "M_E_CPU1_SA_DQ<9>")
	)
	(segment
		(start 55.551578 -208.810352)
		(end 55.781956 -208.810352)
		(width 0.14478)
		(layer "In6.Cu")
		(net "M_E_CPU1_SA_DQ<9>")
	)
	(segment
		(start 42.829734 -207.960468)
		(end 45.69079 -207.960468)
		(width 0.14478)
		(layer "In6.Cu")
		(net "M_E_CPU1_SA_DQ<9>")
	)
	(segment
		(start 45.69079 -207.960468)
		(end 46.540674 -208.810352)
		(width 0.14478)
		(layer "In6.Cu")
		(net "M_E_CPU1_SA_DQ<9>")
	)
	(segment
		(start 55.781956 -208.810352)
		(end 55.945024 -208.97342)
		(width 0.14478)
		(layer "In6.Cu")
		(net "M_E_CPU1_SA_DQ<9>")
	)
	(segment
		(start 55.225442 -209.201004)
		(end 55.38851 -209.037936)
		(width 0.14478)
		(layer "In6.Cu")
		(net "M_E_CPU1_SA_DQ<9>")
	)
	(segment
		(start 60.275216 -208.189576)
		(end 60.275216 -208.123536)
		(width 0.14478)
		(layer "In6.Cu")
		(net "M_E_CPU1_SA_DQ<9>")
	)
	(segment
		(start 34.47415 -208.810352)
		(end 35.324034 -207.960468)
		(width 0.14478)
		(layer "In6.Cu")
		(net "M_E_CPU1_SA_DQ<9>")
	)
	(segment
		(start 50.485294 -207.960468)
		(end 53.23459 -207.960468)
		(width 0.14478)
		(layer "In6.Cu")
		(net "M_E_CPU1_SA_DQ<9>")
	)
	(segment
		(start 60.275216 -208.123536)
		(end 60.438284 -207.960468)
		(width 0.14478)
		(layer "In6.Cu")
		(net "M_E_CPU1_SA_DQ<9>")
	)
	(segment
		(start 40.92067 -209.037936)
		(end 41.083738 -209.201004)
		(width 0.14478)
		(layer "In6.Cu")
		(net "M_E_CPU1_SA_DQ<9>")
	)
	(segment
		(start 38.864794 -208.810352)
		(end 40.757602 -208.810352)
		(width 0.14478)
		(layer "In6.Cu")
		(net "M_E_CPU1_SA_DQ<9>")
	)
	(segment
		(start 31.392876 -209.037682)
		(end 31.555944 -209.20075)
		(width 0.14478)
		(layer "In6.Cu")
		(net "M_E_CPU1_SA_DQ<9>")
	)
	(segment
		(start 49.63541 -208.810352)
		(end 50.485294 -207.960468)
		(width 0.14478)
		(layer "In6.Cu")
		(net "M_E_CPU1_SA_DQ<9>")
	)
	(segment
		(start 60.112148 -208.352644)
		(end 60.275216 -208.189576)
		(width 0.14478)
		(layer "In6.Cu")
		(net "M_E_CPU1_SA_DQ<9>")
	)
	(segment
		(start 30.279848 -208.97342)
		(end 30.279848 -209.037682)
		(width 0.14478)
		(layer "In6.Cu")
		(net "M_E_CPU1_SA_DQ<9>")
	)
	(segment
		(start 59.718702 -208.189576)
		(end 59.88177 -208.352644)
		(width 0.14478)
		(layer "In6.Cu")
		(net "M_E_CPU1_SA_DQ<9>")
	)
	(segment
		(start 56.664606 -208.810352)
		(end 57.17921 -208.810352)
		(width 0.14478)
		(layer "In6.Cu")
		(net "M_E_CPU1_SA_DQ<9>")
	)
	(segment
		(start 48.539654 -208.97342)
		(end 48.539654 -209.030316)
		(width 0.14478)
		(layer "In6.Cu")
		(net "M_E_CPU1_SA_DQ<9>")
	)
	(arc
		(start 81.984088 -231.036876)
		(mid 82.140525 -231.085914)
		(end 82.302858 -231.063038)
		(width 0.0889)
		(layer "In6.Cu")
		(net "M_E_CPU1_SA_DQ<9>")
	)
	(arc
		(start 80.478122 -231.036876)
		(mid 80.761078 -230.960699)
		(end 81.044034 -231.036876)
		(width 0.0889)
		(layer "In6.Cu")
		(net "M_E_CPU1_SA_DQ<9>")
	)
	(arc
		(start 81.052416 -231.041702)
		(mid 81.235924 -231.087227)
		(end 81.418176 -231.036876)
		(width 0.0889)
		(layer "In6.Cu")
		(net "M_E_CPU1_SA_DQ<9>")
	)
	(arc
		(start 79.77378 -230.962454)
		(mid 79.944608 -230.974266)
		(end 80.10398 -231.036876)
		(width 0.0889)
		(layer "In6.Cu")
		(net "M_E_CPU1_SA_DQ<9>")
	)
	(arc
		(start 81.418176 -231.036876)
		(mid 81.701132 -230.960699)
		(end 81.984088 -231.036876)
		(width 0.0889)
		(layer "In6.Cu")
		(net "M_E_CPU1_SA_DQ<9>")
	)
	(arc
		(start 80.10398 -231.036876)
		(mid 80.286231 -231.08726)
		(end 80.46974 -231.041702)
		(width 0.0889)
		(layer "In6.Cu")
		(net "M_E_CPU1_SA_DQ<9>")
	)
	(arc
		(start 79.328264 -230.799386)
		(mid 79.533024 -230.930106)
		(end 79.77378 -230.962454)
		(width 0.0889)
		(layer "In6.Cu")
		(net "M_E_CPU1_SA_DQ<9>")
	)
	(segment
		(start 81.22793 -230.170228)
		(end 80.761078 -229.90429)
		(width 0.10668)
		(layer "F.Cu")
		(net "M_E_CPU1_SA_DQ<8>")
	)
	(segment
		(start 59.977274 -206.650844)
		(end 60.825634 -206.650844)
		(width 0.14478)
		(layer "In6.Cu")
		(net "M_E_CPU1_SA_DQ<8>")
	)
	(segment
		(start 58.701178 -206.487776)
		(end 58.864246 -206.650844)
		(width 0.14478)
		(layer "In6.Cu")
		(net "M_E_CPU1_SA_DQ<8>")
	)
	(segment
		(start 38.01491 -206.260446)
		(end 38.864794 -207.11033)
		(width 0.14478)
		(layer "In6.Cu")
		(net "M_E_CPU1_SA_DQ<8>")
	)
	(segment
		(start 59.814206 -206.487776)
		(end 59.977274 -206.650844)
		(width 0.14478)
		(layer "In6.Cu")
		(net "M_E_CPU1_SA_DQ<8>")
	)
	(segment
		(start 78.999334 -229.609904)
		(end 79.557372 -230.167942)
		(width 0.0889)
		(layer "In6.Cu")
		(net "M_E_CPU1_SA_DQ<8>")
	)
	(segment
		(start 80.89265 -230.253032)
		(end 80.915002 -230.16972)
		(width 0.0889)
		(layer "In6.Cu")
		(net "M_E_CPU1_SA_DQ<8>")
	)
	(segment
		(start 55.974742 -207.273398)
		(end 55.974742 -207.336136)
		(width 0.14478)
		(layer "In6.Cu")
		(net "M_E_CPU1_SA_DQ<8>")
	)
	(segment
		(start 32.303212 -207.11033)
		(end 33.124394 -207.11033)
		(width 0.14478)
		(layer "In6.Cu")
		(net "M_E_CPU1_SA_DQ<8>")
	)
	(segment
		(start 80.915002 -230.16972)
		(end 80.761078 -229.90429)
		(width 0.0889)
		(layer "In6.Cu")
		(net "M_E_CPU1_SA_DQ<8>")
	)
	(segment
		(start 31.450026 -206.956406)
		(end 31.450026 -207.346804)
		(width 0.14478)
		(layer "In6.Cu")
		(net "M_E_CPU1_SA_DQ<8>")
	)
	(segment
		(start 50.485294 -206.260446)
		(end 53.23459 -206.260446)
		(width 0.14478)
		(layer "In6.Cu")
		(net "M_E_CPU1_SA_DQ<8>")
	)
	(segment
		(start 53.23459 -206.260446)
		(end 54.084474 -207.11033)
		(width 0.14478)
		(layer "In6.Cu")
		(net "M_E_CPU1_SA_DQ<8>")
	)
	(segment
		(start 38.864794 -207.11033)
		(end 40.786558 -207.11033)
		(width 0.14478)
		(layer "In6.Cu")
		(net "M_E_CPU1_SA_DQ<8>")
	)
	(segment
		(start 58.53811 -206.260446)
		(end 58.701178 -206.423514)
		(width 0.14478)
		(layer "In6.Cu")
		(net "M_E_CPU1_SA_DQ<8>")
	)
	(segment
		(start 56.531256 -207.273398)
		(end 56.694324 -207.11033)
		(width 0.14478)
		(layer "In6.Cu")
		(net "M_E_CPU1_SA_DQ<8>")
	)
	(segment
		(start 57.17921 -207.11033)
		(end 58.029094 -206.260446)
		(width 0.14478)
		(layer "In6.Cu")
		(net "M_E_CPU1_SA_DQ<8>")
	)
	(segment
		(start 76.381102 -227.00488)
		(end 76.976986 -227.600764)
		(width 0.0889)
		(layer "In6.Cu")
		(net "M_E_CPU1_SA_DQ<8>")
	)
	(segment
		(start 31.594806 -207.491584)
		(end 31.921958 -207.491584)
		(width 0.14478)
		(layer "In6.Cu")
		(net "M_E_CPU1_SA_DQ<8>")
	)
	(segment
		(start 41.50614 -207.273398)
		(end 41.669208 -207.11033)
		(width 0.14478)
		(layer "In6.Cu")
		(net "M_E_CPU1_SA_DQ<8>")
	)
	(segment
		(start 29.252164 -206.685388)
		(end 30.05836 -207.491584)
		(width 0.14478)
		(layer "In6.Cu")
		(net "M_E_CPU1_SA_DQ<8>")
	)
	(segment
		(start 41.343072 -207.504284)
		(end 41.50614 -207.341216)
		(width 0.14478)
		(layer "In6.Cu")
		(net "M_E_CPU1_SA_DQ<8>")
	)
	(segment
		(start 56.13781 -207.499204)
		(end 56.368188 -207.499204)
		(width 0.14478)
		(layer "In6.Cu")
		(net "M_E_CPU1_SA_DQ<8>")
	)
	(segment
		(start 49.202594 -207.341216)
		(end 49.202594 -207.273398)
		(width 0.14478)
		(layer "In6.Cu")
		(net "M_E_CPU1_SA_DQ<8>")
	)
	(segment
		(start 34.2646 -207.31988)
		(end 34.2646 -207.115156)
		(width 0.14478)
		(layer "In6.Cu")
		(net "M_E_CPU1_SA_DQ<8>")
	)
	(segment
		(start 49.039526 -207.504284)
		(end 49.202594 -207.341216)
		(width 0.14478)
		(layer "In6.Cu")
		(net "M_E_CPU1_SA_DQ<8>")
	)
	(segment
		(start 76.088748 -226.296982)
		(end 76.381102 -226.589336)
		(width 0.0889)
		(layer "In6.Cu")
		(net "M_E_CPU1_SA_DQ<8>")
	)
	(segment
		(start 30.741366 -207.491584)
		(end 30.886146 -207.346804)
		(width 0.14478)
		(layer "In6.Cu")
		(net "M_E_CPU1_SA_DQ<8>")
	)
	(segment
		(start 42.829734 -206.260446)
		(end 45.69079 -206.260446)
		(width 0.14478)
		(layer "In6.Cu")
		(net "M_E_CPU1_SA_DQ<8>")
	)
	(segment
		(start 49.202594 -207.273398)
		(end 49.365662 -207.11033)
		(width 0.14478)
		(layer "In6.Cu")
		(net "M_E_CPU1_SA_DQ<8>")
	)
	(segment
		(start 54.698646 -207.11033)
		(end 54.861714 -207.273398)
		(width 0.14478)
		(layer "In6.Cu")
		(net "M_E_CPU1_SA_DQ<8>")
	)
	(segment
		(start 77.396086 -228.642164)
		(end 78.363826 -229.609904)
		(width 0.0889)
		(layer "In6.Cu")
		(net "M_E_CPU1_SA_DQ<8>")
	)
	(segment
		(start 35.324034 -206.260446)
		(end 38.01491 -206.260446)
		(width 0.14478)
		(layer "In6.Cu")
		(net "M_E_CPU1_SA_DQ<8>")
	)
	(segment
		(start 60.825634 -206.650844)
		(end 71.171054 -216.996264)
		(width 0.14478)
		(layer "In6.Cu")
		(net "M_E_CPU1_SA_DQ<8>")
	)
	(segment
		(start 59.094624 -206.650844)
		(end 59.257692 -206.487776)
		(width 0.14478)
		(layer "In6.Cu")
		(net "M_E_CPU1_SA_DQ<8>")
	)
	(segment
		(start 34.2646 -207.115156)
		(end 34.034222 -206.884778)
		(width 0.14478)
		(layer "In6.Cu")
		(net "M_E_CPU1_SA_DQ<8>")
	)
	(segment
		(start 31.305246 -206.811626)
		(end 31.450026 -206.956406)
		(width 0.14478)
		(layer "In6.Cu")
		(net "M_E_CPU1_SA_DQ<8>")
	)
	(segment
		(start 34.228278 -206.485998)
		(end 34.433002 -206.485998)
		(width 0.14478)
		(layer "In6.Cu")
		(net "M_E_CPU1_SA_DQ<8>")
	)
	(segment
		(start 34.034222 -206.680054)
		(end 34.228278 -206.485998)
		(width 0.14478)
		(layer "In6.Cu")
		(net "M_E_CPU1_SA_DQ<8>")
	)
	(segment
		(start 76.381102 -226.589336)
		(end 76.381102 -227.00488)
		(width 0.0889)
		(layer "In6.Cu")
		(net "M_E_CPU1_SA_DQ<8>")
	)
	(segment
		(start 30.886146 -206.956406)
		(end 31.030926 -206.811626)
		(width 0.14478)
		(layer "In6.Cu")
		(net "M_E_CPU1_SA_DQ<8>")
	)
	(segment
		(start 58.029094 -206.260446)
		(end 58.53811 -206.260446)
		(width 0.14478)
		(layer "In6.Cu")
		(net "M_E_CPU1_SA_DQ<8>")
	)
	(segment
		(start 41.669208 -207.11033)
		(end 41.97985 -207.11033)
		(width 0.14478)
		(layer "In6.Cu")
		(net "M_E_CPU1_SA_DQ<8>")
	)
	(segment
		(start 40.949626 -207.273398)
		(end 40.949626 -207.341216)
		(width 0.14478)
		(layer "In6.Cu")
		(net "M_E_CPU1_SA_DQ<8>")
	)
	(segment
		(start 49.365662 -207.11033)
		(end 49.63541 -207.11033)
		(width 0.14478)
		(layer "In6.Cu")
		(net "M_E_CPU1_SA_DQ<8>")
	)
	(segment
		(start 55.25516 -207.499204)
		(end 55.418228 -207.336136)
		(width 0.14478)
		(layer "In6.Cu")
		(net "M_E_CPU1_SA_DQ<8>")
	)
	(segment
		(start 73.335896 -222.73514)
		(end 73.335896 -223.54413)
		(width 0.14478)
		(layer "In6.Cu")
		(net "M_E_CPU1_SA_DQ<8>")
	)
	(segment
		(start 55.418228 -207.273398)
		(end 55.581296 -207.11033)
		(width 0.14478)
		(layer "In6.Cu")
		(net "M_E_CPU1_SA_DQ<8>")
	)
	(segment
		(start 49.63541 -207.11033)
		(end 50.485294 -206.260446)
		(width 0.14478)
		(layer "In6.Cu")
		(net "M_E_CPU1_SA_DQ<8>")
	)
	(segment
		(start 58.701178 -206.423514)
		(end 58.701178 -206.487776)
		(width 0.14478)
		(layer "In6.Cu")
		(net "M_E_CPU1_SA_DQ<8>")
	)
	(segment
		(start 71.171054 -220.570298)
		(end 73.335896 -222.73514)
		(width 0.14478)
		(layer "In6.Cu")
		(net "M_E_CPU1_SA_DQ<8>")
	)
	(segment
		(start 46.540674 -207.11033)
		(end 48.483012 -207.11033)
		(width 0.14478)
		(layer "In6.Cu")
		(net "M_E_CPU1_SA_DQ<8>")
	)
	(segment
		(start 31.450026 -207.346804)
		(end 31.594806 -207.491584)
		(width 0.14478)
		(layer "In6.Cu")
		(net "M_E_CPU1_SA_DQ<8>")
	)
	(segment
		(start 40.949626 -207.341216)
		(end 41.112694 -207.504284)
		(width 0.14478)
		(layer "In6.Cu")
		(net "M_E_CPU1_SA_DQ<8>")
	)
	(segment
		(start 40.786558 -207.11033)
		(end 40.949626 -207.273398)
		(width 0.14478)
		(layer "In6.Cu")
		(net "M_E_CPU1_SA_DQ<8>")
	)
	(segment
		(start 55.418228 -207.336136)
		(end 55.418228 -207.273398)
		(width 0.14478)
		(layer "In6.Cu")
		(net "M_E_CPU1_SA_DQ<8>")
	)
	(segment
		(start 48.809148 -207.504284)
		(end 49.039526 -207.504284)
		(width 0.14478)
		(layer "In6.Cu")
		(net "M_E_CPU1_SA_DQ<8>")
	)
	(segment
		(start 56.694324 -207.11033)
		(end 57.17921 -207.11033)
		(width 0.14478)
		(layer "In6.Cu")
		(net "M_E_CPU1_SA_DQ<8>")
	)
	(segment
		(start 59.651138 -206.260446)
		(end 59.814206 -206.423514)
		(width 0.14478)
		(layer "In6.Cu")
		(net "M_E_CPU1_SA_DQ<8>")
	)
	(segment
		(start 54.084474 -207.11033)
		(end 54.698646 -207.11033)
		(width 0.14478)
		(layer "In6.Cu")
		(net "M_E_CPU1_SA_DQ<8>")
	)
	(segment
		(start 45.69079 -206.260446)
		(end 46.540674 -207.11033)
		(width 0.14478)
		(layer "In6.Cu")
		(net "M_E_CPU1_SA_DQ<8>")
	)
	(segment
		(start 34.034222 -206.884778)
		(end 34.034222 -206.680054)
		(width 0.14478)
		(layer "In6.Cu")
		(net "M_E_CPU1_SA_DQ<8>")
	)
	(segment
		(start 71.171054 -216.996264)
		(end 71.171054 -220.570298)
		(width 0.14478)
		(layer "In6.Cu")
		(net "M_E_CPU1_SA_DQ<8>")
	)
	(segment
		(start 59.814206 -206.423514)
		(end 59.814206 -206.487776)
		(width 0.14478)
		(layer "In6.Cu")
		(net "M_E_CPU1_SA_DQ<8>")
	)
	(segment
		(start 31.921958 -207.491584)
		(end 32.303212 -207.11033)
		(width 0.14478)
		(layer "In6.Cu")
		(net "M_E_CPU1_SA_DQ<8>")
	)
	(segment
		(start 58.864246 -206.650844)
		(end 59.094624 -206.650844)
		(width 0.14478)
		(layer "In6.Cu")
		(net "M_E_CPU1_SA_DQ<8>")
	)
	(segment
		(start 78.363826 -229.609904)
		(end 78.999334 -229.609904)
		(width 0.0889)
		(layer "In6.Cu")
		(net "M_E_CPU1_SA_DQ<8>")
	)
	(segment
		(start 55.024782 -207.499204)
		(end 55.25516 -207.499204)
		(width 0.14478)
		(layer "In6.Cu")
		(net "M_E_CPU1_SA_DQ<8>")
	)
	(segment
		(start 54.861714 -207.273398)
		(end 54.861714 -207.336136)
		(width 0.14478)
		(layer "In6.Cu")
		(net "M_E_CPU1_SA_DQ<8>")
	)
	(segment
		(start 59.257692 -206.423514)
		(end 59.42076 -206.260446)
		(width 0.14478)
		(layer "In6.Cu")
		(net "M_E_CPU1_SA_DQ<8>")
	)
	(segment
		(start 55.811674 -207.11033)
		(end 55.974742 -207.273398)
		(width 0.14478)
		(layer "In6.Cu")
		(net "M_E_CPU1_SA_DQ<8>")
	)
	(segment
		(start 73.335896 -223.54413)
		(end 76.088748 -226.296982)
		(width 0.14478)
		(layer "In6.Cu")
		(net "M_E_CPU1_SA_DQ<8>")
	)
	(segment
		(start 55.974742 -207.336136)
		(end 56.13781 -207.499204)
		(width 0.14478)
		(layer "In6.Cu")
		(net "M_E_CPU1_SA_DQ<8>")
	)
	(segment
		(start 30.05836 -207.491584)
		(end 30.741366 -207.491584)
		(width 0.14478)
		(layer "In6.Cu")
		(net "M_E_CPU1_SA_DQ<8>")
	)
	(segment
		(start 34.433002 -206.485998)
		(end 34.66338 -206.716376)
		(width 0.14478)
		(layer "In6.Cu")
		(net "M_E_CPU1_SA_DQ<8>")
	)
	(segment
		(start 48.64608 -207.341216)
		(end 48.809148 -207.504284)
		(width 0.14478)
		(layer "In6.Cu")
		(net "M_E_CPU1_SA_DQ<8>")
	)
	(segment
		(start 48.483012 -207.11033)
		(end 48.64608 -207.273398)
		(width 0.14478)
		(layer "In6.Cu")
		(net "M_E_CPU1_SA_DQ<8>")
	)
	(segment
		(start 59.42076 -206.260446)
		(end 59.651138 -206.260446)
		(width 0.14478)
		(layer "In6.Cu")
		(net "M_E_CPU1_SA_DQ<8>")
	)
	(segment
		(start 54.861714 -207.336136)
		(end 55.024782 -207.499204)
		(width 0.14478)
		(layer "In6.Cu")
		(net "M_E_CPU1_SA_DQ<8>")
	)
	(segment
		(start 48.64608 -207.273398)
		(end 48.64608 -207.341216)
		(width 0.14478)
		(layer "In6.Cu")
		(net "M_E_CPU1_SA_DQ<8>")
	)
	(segment
		(start 41.97985 -207.11033)
		(end 42.829734 -206.260446)
		(width 0.14478)
		(layer "In6.Cu")
		(net "M_E_CPU1_SA_DQ<8>")
	)
	(segment
		(start 76.976986 -227.743004)
		(end 77.396086 -228.162104)
		(width 0.0889)
		(layer "In6.Cu")
		(net "M_E_CPU1_SA_DQ<8>")
	)
	(segment
		(start 34.092896 -207.491584)
		(end 34.2646 -207.31988)
		(width 0.14478)
		(layer "In6.Cu")
		(net "M_E_CPU1_SA_DQ<8>")
	)
	(segment
		(start 41.50614 -207.341216)
		(end 41.50614 -207.273398)
		(width 0.14478)
		(layer "In6.Cu")
		(net "M_E_CPU1_SA_DQ<8>")
	)
	(segment
		(start 77.396086 -228.162104)
		(end 77.396086 -228.642164)
		(width 0.0889)
		(layer "In6.Cu")
		(net "M_E_CPU1_SA_DQ<8>")
	)
	(segment
		(start 30.886146 -207.346804)
		(end 30.886146 -206.956406)
		(width 0.14478)
		(layer "In6.Cu")
		(net "M_E_CPU1_SA_DQ<8>")
	)
	(segment
		(start 33.124394 -207.11033)
		(end 33.505648 -207.491584)
		(width 0.14478)
		(layer "In6.Cu")
		(net "M_E_CPU1_SA_DQ<8>")
	)
	(segment
		(start 31.030926 -206.811626)
		(end 31.305246 -206.811626)
		(width 0.14478)
		(layer "In6.Cu")
		(net "M_E_CPU1_SA_DQ<8>")
	)
	(segment
		(start 34.66338 -206.716376)
		(end 34.868104 -206.716376)
		(width 0.14478)
		(layer "In6.Cu")
		(net "M_E_CPU1_SA_DQ<8>")
	)
	(segment
		(start 76.976986 -227.600764)
		(end 76.976986 -227.743004)
		(width 0.0889)
		(layer "In6.Cu")
		(net "M_E_CPU1_SA_DQ<8>")
	)
	(segment
		(start 56.531256 -207.336136)
		(end 56.531256 -207.273398)
		(width 0.14478)
		(layer "In6.Cu")
		(net "M_E_CPU1_SA_DQ<8>")
	)
	(segment
		(start 34.868104 -206.716376)
		(end 35.324034 -206.260446)
		(width 0.14478)
		(layer "In6.Cu")
		(net "M_E_CPU1_SA_DQ<8>")
	)
	(segment
		(start 55.581296 -207.11033)
		(end 55.811674 -207.11033)
		(width 0.14478)
		(layer "In6.Cu")
		(net "M_E_CPU1_SA_DQ<8>")
	)
	(segment
		(start 41.112694 -207.504284)
		(end 41.343072 -207.504284)
		(width 0.14478)
		(layer "In6.Cu")
		(net "M_E_CPU1_SA_DQ<8>")
	)
	(segment
		(start 59.257692 -206.487776)
		(end 59.257692 -206.423514)
		(width 0.14478)
		(layer "In6.Cu")
		(net "M_E_CPU1_SA_DQ<8>")
	)
	(segment
		(start 33.505648 -207.491584)
		(end 34.092896 -207.491584)
		(width 0.14478)
		(layer "In6.Cu")
		(net "M_E_CPU1_SA_DQ<8>")
	)
	(segment
		(start 56.368188 -207.499204)
		(end 56.531256 -207.336136)
		(width 0.14478)
		(layer "In6.Cu")
		(net "M_E_CPU1_SA_DQ<8>")
	)
	(arc
		(start 79.557372 -230.167942)
		(mid 79.772766 -230.274014)
		(end 80.008222 -230.22687)
		(width 0.0889)
		(layer "In6.Cu")
		(net "M_E_CPU1_SA_DQ<8>")
	)
	(arc
		(start 80.574134 -230.22687)
		(mid 80.730453 -230.275865)
		(end 80.89265 -230.253032)
		(width 0.0889)
		(layer "In6.Cu")
		(net "M_E_CPU1_SA_DQ<8>")
	)
	(arc
		(start 80.008222 -230.22687)
		(mid 80.291178 -230.150727)
		(end 80.574134 -230.22687)
		(width 0.0889)
		(layer "In6.Cu")
		(net "M_E_CPU1_SA_DQ<8>")
	)
	(segment
		(start 83.107784 -230.170228)
		(end 82.640932 -229.90429)
		(width 0.10668)
		(layer "F.Cu")
		(net "M_E_CPU1_SA_DQ<7>")
	)
	(segment
		(start 33.199324 -206.260446)
		(end 33.544764 -205.915006)
		(width 0.14478)
		(layer "In6.Cu")
		(net "M_E_CPU1_SA_DQ<7>")
	)
	(segment
		(start 54.106572 -206.260446)
		(end 57.164732 -206.260446)
		(width 0.14478)
		(layer "In6.Cu")
		(net "M_E_CPU1_SA_DQ<7>")
	)
	(segment
		(start 46.562772 -206.260446)
		(end 49.620932 -206.260446)
		(width 0.14478)
		(layer "In6.Cu")
		(net "M_E_CPU1_SA_DQ<7>")
	)
	(segment
		(start 78.287626 -228.731064)
		(end 78.569566 -228.731064)
		(width 0.0889)
		(layer "In6.Cu")
		(net "M_E_CPU1_SA_DQ<7>")
	)
	(segment
		(start 27.04465 -205.587092)
		(end 27.04465 -206.097378)
		(width 0.14478)
		(layer "In6.Cu")
		(net "M_E_CPU1_SA_DQ<7>")
	)
	(segment
		(start 35.11931 -205.410308)
		(end 38.0238 -205.410308)
		(width 0.14478)
		(layer "In6.Cu")
		(net "M_E_CPU1_SA_DQ<7>")
	)
	(segment
		(start 77.236066 -227.679504)
		(end 78.287626 -228.731064)
		(width 0.0889)
		(layer "In6.Cu")
		(net "M_E_CPU1_SA_DQ<7>")
	)
	(segment
		(start 27.207718 -206.260446)
		(end 27.438096 -206.260446)
		(width 0.14478)
		(layer "In6.Cu")
		(net "M_E_CPU1_SA_DQ<7>")
	)
	(segment
		(start 71.722234 -216.767918)
		(end 71.722234 -220.341952)
		(width 0.14478)
		(layer "In6.Cu")
		(net "M_E_CPU1_SA_DQ<7>")
	)
	(segment
		(start 58.01487 -205.410308)
		(end 60.364624 -205.410308)
		(width 0.14478)
		(layer "In6.Cu")
		(net "M_E_CPU1_SA_DQ<7>")
	)
	(segment
		(start 34.614612 -205.915006)
		(end 35.11931 -205.410308)
		(width 0.14478)
		(layer "In6.Cu")
		(net "M_E_CPU1_SA_DQ<7>")
	)
	(segment
		(start 25.577292 -206.260446)
		(end 26.325068 -206.260446)
		(width 0.14478)
		(layer "In6.Cu")
		(net "M_E_CPU1_SA_DQ<7>")
	)
	(segment
		(start 42.673524 -205.410308)
		(end 45.712634 -205.410308)
		(width 0.14478)
		(layer "In6.Cu")
		(net "M_E_CPU1_SA_DQ<7>")
	)
	(segment
		(start 82.487008 -229.63886)
		(end 82.640932 -229.90429)
		(width 0.0889)
		(layer "In6.Cu")
		(net "M_E_CPU1_SA_DQ<7>")
	)
	(segment
		(start 27.764232 -205.424024)
		(end 27.99461 -205.424024)
		(width 0.14478)
		(layer "In6.Cu")
		(net "M_E_CPU1_SA_DQ<7>")
	)
	(segment
		(start 26.488136 -205.587092)
		(end 26.651204 -205.424024)
		(width 0.14478)
		(layer "In6.Cu")
		(net "M_E_CPU1_SA_DQ<7>")
	)
	(segment
		(start 49.620932 -206.260446)
		(end 50.47107 -205.410308)
		(width 0.14478)
		(layer "In6.Cu")
		(net "M_E_CPU1_SA_DQ<7>")
	)
	(segment
		(start 28.157678 -205.587092)
		(end 28.157678 -206.097378)
		(width 0.14478)
		(layer "In6.Cu")
		(net "M_E_CPU1_SA_DQ<7>")
	)
	(segment
		(start 27.04465 -206.097378)
		(end 27.207718 -206.260446)
		(width 0.14478)
		(layer "In6.Cu")
		(net "M_E_CPU1_SA_DQ<7>")
	)
	(segment
		(start 41.823386 -206.260446)
		(end 42.673524 -205.410308)
		(width 0.14478)
		(layer "In6.Cu")
		(net "M_E_CPU1_SA_DQ<7>")
	)
	(segment
		(start 26.651204 -205.424024)
		(end 26.881582 -205.424024)
		(width 0.14478)
		(layer "In6.Cu")
		(net "M_E_CPU1_SA_DQ<7>")
	)
	(segment
		(start 28.320746 -206.260446)
		(end 33.199324 -206.260446)
		(width 0.14478)
		(layer "In6.Cu")
		(net "M_E_CPU1_SA_DQ<7>")
	)
	(segment
		(start 45.712634 -205.410308)
		(end 46.562772 -206.260446)
		(width 0.14478)
		(layer "In6.Cu")
		(net "M_E_CPU1_SA_DQ<7>")
	)
	(segment
		(start 28.157678 -206.097378)
		(end 28.320746 -206.260446)
		(width 0.14478)
		(layer "In6.Cu")
		(net "M_E_CPU1_SA_DQ<7>")
	)
	(segment
		(start 76.641706 -226.947984)
		(end 77.236066 -227.542344)
		(width 0.0889)
		(layer "In6.Cu")
		(net "M_E_CPU1_SA_DQ<7>")
	)
	(segment
		(start 38.873938 -206.260446)
		(end 41.823386 -206.260446)
		(width 0.14478)
		(layer "In6.Cu")
		(net "M_E_CPU1_SA_DQ<7>")
	)
	(segment
		(start 33.544764 -205.915006)
		(end 34.614612 -205.915006)
		(width 0.14478)
		(layer "In6.Cu")
		(net "M_E_CPU1_SA_DQ<7>")
	)
	(segment
		(start 27.601164 -205.587092)
		(end 27.764232 -205.424024)
		(width 0.14478)
		(layer "In6.Cu")
		(net "M_E_CPU1_SA_DQ<7>")
	)
	(segment
		(start 38.0238 -205.410308)
		(end 38.873938 -206.260446)
		(width 0.14478)
		(layer "In6.Cu")
		(net "M_E_CPU1_SA_DQ<7>")
	)
	(segment
		(start 27.99461 -205.424024)
		(end 28.157678 -205.587092)
		(width 0.14478)
		(layer "In6.Cu")
		(net "M_E_CPU1_SA_DQ<7>")
	)
	(segment
		(start 53.256434 -205.410308)
		(end 54.106572 -206.260446)
		(width 0.14478)
		(layer "In6.Cu")
		(net "M_E_CPU1_SA_DQ<7>")
	)
	(segment
		(start 57.164732 -206.260446)
		(end 58.01487 -205.410308)
		(width 0.14478)
		(layer "In6.Cu")
		(net "M_E_CPU1_SA_DQ<7>")
	)
	(segment
		(start 82.39125 -229.61346)
		(end 82.487008 -229.63886)
		(width 0.0889)
		(layer "In6.Cu")
		(net "M_E_CPU1_SA_DQ<7>")
	)
	(segment
		(start 76.641706 -226.058984)
		(end 76.641706 -226.947984)
		(width 0.0889)
		(layer "In6.Cu")
		(net "M_E_CPU1_SA_DQ<7>")
	)
	(segment
		(start 71.722234 -220.341952)
		(end 73.887076 -222.506794)
		(width 0.14478)
		(layer "In6.Cu")
		(net "M_E_CPU1_SA_DQ<7>")
	)
	(segment
		(start 75.855576 -225.272854)
		(end 76.641706 -226.058984)
		(width 0.0889)
		(layer "In6.Cu")
		(net "M_E_CPU1_SA_DQ<7>")
	)
	(segment
		(start 27.438096 -206.260446)
		(end 27.601164 -206.097378)
		(width 0.14478)
		(layer "In6.Cu")
		(net "M_E_CPU1_SA_DQ<7>")
	)
	(segment
		(start 50.47107 -205.410308)
		(end 53.256434 -205.410308)
		(width 0.14478)
		(layer "In6.Cu")
		(net "M_E_CPU1_SA_DQ<7>")
	)
	(segment
		(start 26.488136 -206.097378)
		(end 26.488136 -205.587092)
		(width 0.14478)
		(layer "In6.Cu")
		(net "M_E_CPU1_SA_DQ<7>")
	)
	(segment
		(start 73.887076 -222.506794)
		(end 73.887076 -223.304354)
		(width 0.14478)
		(layer "In6.Cu")
		(net "M_E_CPU1_SA_DQ<7>")
	)
	(segment
		(start 77.236066 -227.542344)
		(end 77.236066 -227.679504)
		(width 0.0889)
		(layer "In6.Cu")
		(net "M_E_CPU1_SA_DQ<7>")
	)
	(segment
		(start 73.887076 -223.304354)
		(end 75.855576 -225.272854)
		(width 0.14478)
		(layer "In6.Cu")
		(net "M_E_CPU1_SA_DQ<7>")
	)
	(segment
		(start 81.879694 -229.577138)
		(end 81.888076 -229.581964)
		(width 0.0889)
		(layer "In6.Cu")
		(net "M_E_CPU1_SA_DQ<7>")
	)
	(segment
		(start 60.364624 -205.410308)
		(end 71.722234 -216.767918)
		(width 0.14478)
		(layer "In6.Cu")
		(net "M_E_CPU1_SA_DQ<7>")
	)
	(segment
		(start 25.152096 -205.83525)
		(end 25.577292 -206.260446)
		(width 0.14478)
		(layer "In6.Cu")
		(net "M_E_CPU1_SA_DQ<7>")
	)
	(segment
		(start 26.325068 -206.260446)
		(end 26.488136 -206.097378)
		(width 0.14478)
		(layer "In6.Cu")
		(net "M_E_CPU1_SA_DQ<7>")
	)
	(segment
		(start 78.569566 -228.731064)
		(end 79.369666 -229.531164)
		(width 0.0889)
		(layer "In6.Cu")
		(net "M_E_CPU1_SA_DQ<7>")
	)
	(segment
		(start 27.601164 -206.097378)
		(end 27.601164 -205.587092)
		(width 0.14478)
		(layer "In6.Cu")
		(net "M_E_CPU1_SA_DQ<7>")
	)
	(segment
		(start 79.369666 -229.531164)
		(end 79.821024 -229.531164)
		(width 0.0889)
		(layer "In6.Cu")
		(net "M_E_CPU1_SA_DQ<7>")
	)
	(segment
		(start 26.881582 -205.424024)
		(end 27.04465 -205.587092)
		(width 0.14478)
		(layer "In6.Cu")
		(net "M_E_CPU1_SA_DQ<7>")
	)
	(arc
		(start 81.513934 -229.581964)
		(mid 81.696185 -229.53158)
		(end 81.879694 -229.577138)
		(width 0.0889)
		(layer "In6.Cu")
		(net "M_E_CPU1_SA_DQ<7>")
	)
	(arc
		(start 81.888076 -229.581964)
		(mid 82.135936 -229.657047)
		(end 82.39125 -229.61346)
		(width 0.0889)
		(layer "In6.Cu")
		(net "M_E_CPU1_SA_DQ<7>")
	)
	(arc
		(start 79.821024 -229.531164)
		(mid 79.917977 -229.544195)
		(end 80.008222 -229.581964)
		(width 0.0889)
		(layer "In6.Cu")
		(net "M_E_CPU1_SA_DQ<7>")
	)
	(arc
		(start 80.574134 -229.581964)
		(mid 80.761078 -229.531675)
		(end 80.948022 -229.581964)
		(width 0.0889)
		(layer "In6.Cu")
		(net "M_E_CPU1_SA_DQ<7>")
	)
	(arc
		(start 80.008222 -229.581964)
		(mid 80.291178 -229.658141)
		(end 80.574134 -229.581964)
		(width 0.0889)
		(layer "In6.Cu")
		(net "M_E_CPU1_SA_DQ<7>")
	)
	(arc
		(start 80.948022 -229.581964)
		(mid 81.230978 -229.658141)
		(end 81.513934 -229.581964)
		(width 0.0889)
		(layer "In6.Cu")
		(net "M_E_CPU1_SA_DQ<7>")
	)
	(segment
		(start 81.69783 -229.360476)
		(end 81.230978 -229.094538)
		(width 0.10668)
		(layer "F.Cu")
		(net "M_E_CPU1_SA_DQ<6>")
	)
	(segment
		(start 49.620932 -204.560424)
		(end 50.47107 -203.710286)
		(width 0.14478)
		(layer "In6.Cu")
		(net "M_E_CPU1_SA_DQ<6>")
	)
	(segment
		(start 53.256434 -203.710286)
		(end 54.106572 -204.560424)
		(width 0.14478)
		(layer "In6.Cu")
		(net "M_E_CPU1_SA_DQ<6>")
	)
	(segment
		(start 46.50486 -204.560424)
		(end 49.620932 -204.560424)
		(width 0.14478)
		(layer "In6.Cu")
		(net "M_E_CPU1_SA_DQ<6>")
	)
	(segment
		(start 26.579068 -203.951332)
		(end 26.742136 -203.788264)
		(width 0.14478)
		(layer "In6.Cu")
		(net "M_E_CPU1_SA_DQ<6>")
	)
	(segment
		(start 79.65567 -228.848158)
		(end 79.821024 -228.848158)
		(width 0.0889)
		(layer "In6.Cu")
		(net "M_E_CPU1_SA_DQ<6>")
	)
	(segment
		(start 28.085542 -203.333604)
		(end 28.24861 -203.496672)
		(width 0.14478)
		(layer "In6.Cu")
		(net "M_E_CPU1_SA_DQ<6>")
	)
	(segment
		(start 34.269172 -204.560424)
		(end 35.11931 -203.710286)
		(width 0.14478)
		(layer "In6.Cu")
		(net "M_E_CPU1_SA_DQ<6>")
	)
	(segment
		(start 26.579068 -204.397356)
		(end 26.579068 -203.951332)
		(width 0.14478)
		(layer "In6.Cu")
		(net "M_E_CPU1_SA_DQ<6>")
	)
	(segment
		(start 76.418948 -224.421446)
		(end 76.639166 -224.641664)
		(width 0.0889)
		(layer "In6.Cu")
		(net "M_E_CPU1_SA_DQ<6>")
	)
	(segment
		(start 69.782182 -213.555834)
		(end 70.426834 -213.555834)
		(width 0.14478)
		(layer "In6.Cu")
		(net "M_E_CPU1_SA_DQ<6>")
	)
	(segment
		(start 79.459582 -228.854508)
		(end 79.65567 -228.848158)
		(width 0.0889)
		(layer "In6.Cu")
		(net "M_E_CPU1_SA_DQ<6>")
	)
	(segment
		(start 27.855164 -203.333604)
		(end 28.085542 -203.333604)
		(width 0.14478)
		(layer "In6.Cu")
		(net "M_E_CPU1_SA_DQ<6>")
	)
	(segment
		(start 72.750426 -220.098112)
		(end 74.786236 -222.133922)
		(width 0.14478)
		(layer "In6.Cu")
		(net "M_E_CPU1_SA_DQ<6>")
	)
	(segment
		(start 70.426834 -213.555834)
		(end 72.750426 -215.879426)
		(width 0.14478)
		(layer "In6.Cu")
		(net "M_E_CPU1_SA_DQ<6>")
	)
	(segment
		(start 59.936634 -203.710286)
		(end 69.782182 -213.555834)
		(width 0.14478)
		(layer "In6.Cu")
		(net "M_E_CPU1_SA_DQ<6>")
	)
	(segment
		(start 27.135582 -204.397356)
		(end 27.29865 -204.560424)
		(width 0.14478)
		(layer "In6.Cu")
		(net "M_E_CPU1_SA_DQ<6>")
	)
	(segment
		(start 77.515466 -226.302824)
		(end 77.794866 -226.977702)
		(width 0.0889)
		(layer "In6.Cu")
		(net "M_E_CPU1_SA_DQ<6>")
	)
	(segment
		(start 74.786236 -222.788734)
		(end 76.418948 -224.421446)
		(width 0.14478)
		(layer "In6.Cu")
		(net "M_E_CPU1_SA_DQ<6>")
	)
	(segment
		(start 28.411678 -204.560424)
		(end 34.269172 -204.560424)
		(width 0.14478)
		(layer "In6.Cu")
		(net "M_E_CPU1_SA_DQ<6>")
	)
	(segment
		(start 54.106572 -204.560424)
		(end 57.164732 -204.560424)
		(width 0.14478)
		(layer "In6.Cu")
		(net "M_E_CPU1_SA_DQ<6>")
	)
	(segment
		(start 25.577292 -204.560424)
		(end 26.416 -204.560424)
		(width 0.14478)
		(layer "In6.Cu")
		(net "M_E_CPU1_SA_DQ<6>")
	)
	(segment
		(start 38.0238 -203.710286)
		(end 38.873938 -204.560424)
		(width 0.14478)
		(layer "In6.Cu")
		(net "M_E_CPU1_SA_DQ<6>")
	)
	(segment
		(start 27.529028 -204.560424)
		(end 27.692096 -204.397356)
		(width 0.14478)
		(layer "In6.Cu")
		(net "M_E_CPU1_SA_DQ<6>")
	)
	(segment
		(start 26.416 -204.560424)
		(end 26.579068 -204.397356)
		(width 0.14478)
		(layer "In6.Cu")
		(net "M_E_CPU1_SA_DQ<6>")
	)
	(segment
		(start 77.794866 -227.656644)
		(end 78.305406 -228.167184)
		(width 0.0889)
		(layer "In6.Cu")
		(net "M_E_CPU1_SA_DQ<6>")
	)
	(segment
		(start 42.673524 -203.710286)
		(end 45.654722 -203.710286)
		(width 0.14478)
		(layer "In6.Cu")
		(net "M_E_CPU1_SA_DQ<6>")
	)
	(segment
		(start 26.972514 -203.788264)
		(end 27.135582 -203.951332)
		(width 0.14478)
		(layer "In6.Cu")
		(net "M_E_CPU1_SA_DQ<6>")
	)
	(segment
		(start 72.750426 -215.879426)
		(end 72.750426 -220.098112)
		(width 0.14478)
		(layer "In6.Cu")
		(net "M_E_CPU1_SA_DQ<6>")
	)
	(segment
		(start 76.639166 -224.641664)
		(end 76.639166 -225.426524)
		(width 0.0889)
		(layer "In6.Cu")
		(net "M_E_CPU1_SA_DQ<6>")
	)
	(segment
		(start 26.742136 -203.788264)
		(end 26.972514 -203.788264)
		(width 0.14478)
		(layer "In6.Cu")
		(net "M_E_CPU1_SA_DQ<6>")
	)
	(segment
		(start 27.29865 -204.560424)
		(end 27.529028 -204.560424)
		(width 0.14478)
		(layer "In6.Cu")
		(net "M_E_CPU1_SA_DQ<6>")
	)
	(segment
		(start 76.639166 -225.426524)
		(end 77.515466 -226.302824)
		(width 0.0889)
		(layer "In6.Cu")
		(net "M_E_CPU1_SA_DQ<6>")
	)
	(segment
		(start 74.786236 -222.133922)
		(end 74.786236 -222.788734)
		(width 0.14478)
		(layer "In6.Cu")
		(net "M_E_CPU1_SA_DQ<6>")
	)
	(segment
		(start 28.24861 -203.496672)
		(end 28.24861 -204.397356)
		(width 0.14478)
		(layer "In6.Cu")
		(net "M_E_CPU1_SA_DQ<6>")
	)
	(segment
		(start 50.47107 -203.710286)
		(end 53.256434 -203.710286)
		(width 0.14478)
		(layer "In6.Cu")
		(net "M_E_CPU1_SA_DQ<6>")
	)
	(segment
		(start 27.692096 -204.397356)
		(end 27.692096 -203.496672)
		(width 0.14478)
		(layer "In6.Cu")
		(net "M_E_CPU1_SA_DQ<6>")
	)
	(segment
		(start 41.823386 -204.560424)
		(end 42.673524 -203.710286)
		(width 0.14478)
		(layer "In6.Cu")
		(net "M_E_CPU1_SA_DQ<6>")
	)
	(segment
		(start 81.077054 -228.829108)
		(end 81.230978 -229.094538)
		(width 0.0889)
		(layer "In6.Cu")
		(net "M_E_CPU1_SA_DQ<6>")
	)
	(segment
		(start 45.654722 -203.710286)
		(end 46.50486 -204.560424)
		(width 0.14478)
		(layer "In6.Cu")
		(net "M_E_CPU1_SA_DQ<6>")
	)
	(segment
		(start 27.692096 -203.496672)
		(end 27.855164 -203.333604)
		(width 0.14478)
		(layer "In6.Cu")
		(net "M_E_CPU1_SA_DQ<6>")
	)
	(segment
		(start 57.164732 -204.560424)
		(end 58.01487 -203.710286)
		(width 0.14478)
		(layer "In6.Cu")
		(net "M_E_CPU1_SA_DQ<6>")
	)
	(segment
		(start 77.794866 -226.977702)
		(end 77.794866 -227.656644)
		(width 0.0889)
		(layer "In6.Cu")
		(net "M_E_CPU1_SA_DQ<6>")
	)
	(segment
		(start 80.46974 -228.767132)
		(end 80.478122 -228.771958)
		(width 0.0889)
		(layer "In6.Cu")
		(net "M_E_CPU1_SA_DQ<6>")
	)
	(segment
		(start 38.873938 -204.560424)
		(end 41.823386 -204.560424)
		(width 0.14478)
		(layer "In6.Cu")
		(net "M_E_CPU1_SA_DQ<6>")
	)
	(segment
		(start 78.305406 -228.167184)
		(end 78.772258 -228.167184)
		(width 0.0889)
		(layer "In6.Cu")
		(net "M_E_CPU1_SA_DQ<6>")
	)
	(segment
		(start 80.981042 -228.803708)
		(end 81.077054 -228.829108)
		(width 0.0889)
		(layer "In6.Cu")
		(net "M_E_CPU1_SA_DQ<6>")
	)
	(segment
		(start 25.152096 -204.135228)
		(end 25.577292 -204.560424)
		(width 0.14478)
		(layer "In6.Cu")
		(net "M_E_CPU1_SA_DQ<6>")
	)
	(segment
		(start 78.772258 -228.167184)
		(end 79.459582 -228.854508)
		(width 0.0889)
		(layer "In6.Cu")
		(net "M_E_CPU1_SA_DQ<6>")
	)
	(segment
		(start 35.11931 -203.710286)
		(end 38.0238 -203.710286)
		(width 0.14478)
		(layer "In6.Cu")
		(net "M_E_CPU1_SA_DQ<6>")
	)
	(segment
		(start 58.01487 -203.710286)
		(end 59.936634 -203.710286)
		(width 0.14478)
		(layer "In6.Cu")
		(net "M_E_CPU1_SA_DQ<6>")
	)
	(segment
		(start 27.135582 -203.951332)
		(end 27.135582 -204.397356)
		(width 0.14478)
		(layer "In6.Cu")
		(net "M_E_CPU1_SA_DQ<6>")
	)
	(segment
		(start 28.24861 -204.397356)
		(end 28.411678 -204.560424)
		(width 0.14478)
		(layer "In6.Cu")
		(net "M_E_CPU1_SA_DQ<6>")
	)
	(arc
		(start 79.821024 -228.848158)
		(mid 79.967541 -228.828772)
		(end 80.10398 -228.771958)
		(width 0.0889)
		(layer "In6.Cu")
		(net "M_E_CPU1_SA_DQ<6>")
	)
	(arc
		(start 80.10398 -228.771958)
		(mid 80.286231 -228.721608)
		(end 80.46974 -228.767132)
		(width 0.0889)
		(layer "In6.Cu")
		(net "M_E_CPU1_SA_DQ<6>")
	)
	(arc
		(start 80.478122 -228.771958)
		(mid 80.725835 -228.847178)
		(end 80.981042 -228.803708)
		(width 0.0889)
		(layer "In6.Cu")
		(net "M_E_CPU1_SA_DQ<6>")
	)
	(segment
		(start 82.637884 -229.360476)
		(end 82.171032 -229.094538)
		(width 0.10668)
		(layer "F.Cu")
		(net "M_E_CPU1_SA_DQ<5>")
	)
	(segment
		(start 31.500318 -205.639416)
		(end 31.663386 -205.802484)
		(width 0.14478)
		(layer "In6.Cu")
		(net "M_E_CPU1_SA_DQ<5>")
	)
	(segment
		(start 72.043036 -216.030556)
		(end 71.934324 -216.139268)
		(width 0.14478)
		(layer "In6.Cu")
		(net "M_E_CPU1_SA_DQ<5>")
	)
	(segment
		(start 58.219594 -204.560424)
		(end 58.541158 -204.560424)
		(width 0.14478)
		(layer "In6.Cu")
		(net "M_E_CPU1_SA_DQ<5>")
	)
	(segment
		(start 77.538326 -227.689664)
		(end 78.368906 -228.520244)
		(width 0.0889)
		(layer "In6.Cu")
		(net "M_E_CPU1_SA_DQ<5>")
	)
	(segment
		(start 55.36057 -205.616556)
		(end 55.523638 -205.779624)
		(width 0.14478)
		(layer "In6.Cu")
		(net "M_E_CPU1_SA_DQ<5>")
	)
	(segment
		(start 32.2199 -205.410308)
		(end 34.47415 -205.410308)
		(width 0.14478)
		(layer "In6.Cu")
		(net "M_E_CPU1_SA_DQ<5>")
	)
	(segment
		(start 29.677106 -205.410308)
		(end 30.224222 -205.410308)
		(width 0.14478)
		(layer "In6.Cu")
		(net "M_E_CPU1_SA_DQ<5>")
	)
	(segment
		(start 56.473598 -205.236572)
		(end 56.473598 -205.616556)
		(width 0.14478)
		(layer "In6.Cu")
		(net "M_E_CPU1_SA_DQ<5>")
	)
	(segment
		(start 30.943804 -205.1812)
		(end 31.106872 -205.018132)
		(width 0.14478)
		(layer "In6.Cu")
		(net "M_E_CPU1_SA_DQ<5>")
	)
	(segment
		(start 78.734666 -228.520244)
		(end 79.548736 -229.334314)
		(width 0.0889)
		(layer "In6.Cu")
		(net "M_E_CPU1_SA_DQ<5>")
	)
	(segment
		(start 57.19318 -205.410308)
		(end 57.36971 -205.410308)
		(width 0.14478)
		(layer "In6.Cu")
		(net "M_E_CPU1_SA_DQ<5>")
	)
	(segment
		(start 55.36057 -205.573376)
		(end 55.36057 -205.616556)
		(width 0.14478)
		(layer "In6.Cu")
		(net "M_E_CPU1_SA_DQ<5>")
	)
	(segment
		(start 48.967898 -205.802484)
		(end 49.130966 -205.639416)
		(width 0.14478)
		(layer "In6.Cu")
		(net "M_E_CPU1_SA_DQ<5>")
	)
	(segment
		(start 59.423808 -204.560424)
		(end 59.654186 -204.560424)
		(width 0.14478)
		(layer "In6.Cu")
		(net "M_E_CPU1_SA_DQ<5>")
	)
	(segment
		(start 56.867044 -205.779624)
		(end 57.030112 -205.616556)
		(width 0.14478)
		(layer "In6.Cu")
		(net "M_E_CPU1_SA_DQ<5>")
	)
	(segment
		(start 32.056832 -205.573376)
		(end 32.2199 -205.410308)
		(width 0.14478)
		(layer "In6.Cu")
		(net "M_E_CPU1_SA_DQ<5>")
	)
	(segment
		(start 30.38729 -205.639416)
		(end 30.550358 -205.802484)
		(width 0.14478)
		(layer "In6.Cu")
		(net "M_E_CPU1_SA_DQ<5>")
	)
	(segment
		(start 70.447916 -214.230712)
		(end 70.447916 -214.435436)
		(width 0.14478)
		(layer "In6.Cu")
		(net "M_E_CPU1_SA_DQ<5>")
	)
	(segment
		(start 31.663386 -205.802484)
		(end 31.893764 -205.802484)
		(width 0.14478)
		(layer "In6.Cu")
		(net "M_E_CPU1_SA_DQ<5>")
	)
	(segment
		(start 76.192126 -224.951544)
		(end 76.402946 -225.162364)
		(width 0.0889)
		(layer "In6.Cu")
		(net "M_E_CPU1_SA_DQ<5>")
	)
	(segment
		(start 58.704226 -204.770736)
		(end 58.867294 -204.933804)
		(width 0.14478)
		(layer "In6.Cu")
		(net "M_E_CPU1_SA_DQ<5>")
	)
	(segment
		(start 31.893764 -205.802484)
		(end 32.056832 -205.639416)
		(width 0.14478)
		(layer "In6.Cu")
		(net "M_E_CPU1_SA_DQ<5>")
	)
	(segment
		(start 31.106872 -205.018132)
		(end 31.33725 -205.018132)
		(width 0.14478)
		(layer "In6.Cu")
		(net "M_E_CPU1_SA_DQ<5>")
	)
	(segment
		(start 55.523638 -205.779624)
		(end 55.754016 -205.779624)
		(width 0.14478)
		(layer "In6.Cu")
		(net "M_E_CPU1_SA_DQ<5>")
	)
	(segment
		(start 48.411384 -205.410308)
		(end 48.574452 -205.573376)
		(width 0.14478)
		(layer "In6.Cu")
		(net "M_E_CPU1_SA_DQ<5>")
	)
	(segment
		(start 40.77462 -205.410308)
		(end 40.937688 -205.573376)
		(width 0.14478)
		(layer "In6.Cu")
		(net "M_E_CPU1_SA_DQ<5>")
	)
	(segment
		(start 30.224222 -205.410308)
		(end 30.38729 -205.573376)
		(width 0.14478)
		(layer "In6.Cu")
		(net "M_E_CPU1_SA_DQ<5>")
	)
	(segment
		(start 71.644256 -215.631776)
		(end 71.84898 -215.631776)
		(width 0.14478)
		(layer "In6.Cu")
		(net "M_E_CPU1_SA_DQ<5>")
	)
	(segment
		(start 81.044034 -229.416864)
		(end 81.052416 -229.42169)
		(width 0.0889)
		(layer "In6.Cu")
		(net "M_E_CPU1_SA_DQ<5>")
	)
	(segment
		(start 49.130966 -205.573376)
		(end 49.294034 -205.410308)
		(width 0.14478)
		(layer "In6.Cu")
		(net "M_E_CPU1_SA_DQ<5>")
	)
	(segment
		(start 71.934324 -216.343992)
		(end 72.215248 -216.624916)
		(width 0.14478)
		(layer "In6.Cu")
		(net "M_E_CPU1_SA_DQ<5>")
	)
	(segment
		(start 38.864794 -205.410308)
		(end 40.77462 -205.410308)
		(width 0.14478)
		(layer "In6.Cu")
		(net "M_E_CPU1_SA_DQ<5>")
	)
	(segment
		(start 55.754016 -205.779624)
		(end 55.917084 -205.616556)
		(width 0.14478)
		(layer "In6.Cu")
		(net "M_E_CPU1_SA_DQ<5>")
	)
	(segment
		(start 30.38729 -205.573376)
		(end 30.38729 -205.639416)
		(width 0.14478)
		(layer "In6.Cu")
		(net "M_E_CPU1_SA_DQ<5>")
	)
	(segment
		(start 72.215248 -220.19895)
		(end 74.336656 -222.320358)
		(width 0.14478)
		(layer "In6.Cu")
		(net "M_E_CPU1_SA_DQ<5>")
	)
	(segment
		(start 59.817254 -204.723492)
		(end 59.817254 -204.770736)
		(width 0.14478)
		(layer "In6.Cu")
		(net "M_E_CPU1_SA_DQ<5>")
	)
	(segment
		(start 40.937688 -205.573376)
		(end 40.937688 -205.634336)
		(width 0.14478)
		(layer "In6.Cu")
		(net "M_E_CPU1_SA_DQ<5>")
	)
	(segment
		(start 60.524136 -204.933804)
		(end 69.7357 -214.145368)
		(width 0.14478)
		(layer "In6.Cu")
		(net "M_E_CPU1_SA_DQ<5>")
	)
	(segment
		(start 54.804056 -205.573376)
		(end 54.967124 -205.410308)
		(width 0.14478)
		(layer "In6.Cu")
		(net "M_E_CPU1_SA_DQ<5>")
	)
	(segment
		(start 41.65727 -205.410308)
		(end 41.97985 -205.410308)
		(width 0.14478)
		(layer "In6.Cu")
		(net "M_E_CPU1_SA_DQ<5>")
	)
	(segment
		(start 59.26074 -204.770736)
		(end 59.26074 -204.723492)
		(width 0.14478)
		(layer "In6.Cu")
		(net "M_E_CPU1_SA_DQ<5>")
	)
	(segment
		(start 32.056832 -205.639416)
		(end 32.056832 -205.573376)
		(width 0.14478)
		(layer "In6.Cu")
		(net "M_E_CPU1_SA_DQ<5>")
	)
	(segment
		(start 59.817254 -204.770736)
		(end 59.980322 -204.933804)
		(width 0.14478)
		(layer "In6.Cu")
		(net "M_E_CPU1_SA_DQ<5>")
	)
	(segment
		(start 80.46974 -229.42169)
		(end 80.478122 -229.416864)
		(width 0.0889)
		(layer "In6.Cu")
		(net "M_E_CPU1_SA_DQ<5>")
	)
	(segment
		(start 69.7357 -214.145368)
		(end 69.940424 -214.145368)
		(width 0.14478)
		(layer "In6.Cu")
		(net "M_E_CPU1_SA_DQ<5>")
	)
	(segment
		(start 42.829734 -204.560424)
		(end 45.69079 -204.560424)
		(width 0.14478)
		(layer "In6.Cu")
		(net "M_E_CPU1_SA_DQ<5>")
	)
	(segment
		(start 30.943804 -205.639416)
		(end 30.943804 -205.1812)
		(width 0.14478)
		(layer "In6.Cu")
		(net "M_E_CPU1_SA_DQ<5>")
	)
	(segment
		(start 55.917084 -205.616556)
		(end 55.917084 -205.236572)
		(width 0.14478)
		(layer "In6.Cu")
		(net "M_E_CPU1_SA_DQ<5>")
	)
	(segment
		(start 71.05142 -214.834216)
		(end 71.245476 -215.028272)
		(width 0.14478)
		(layer "In6.Cu")
		(net "M_E_CPU1_SA_DQ<5>")
	)
	(segment
		(start 78.368906 -228.520244)
		(end 78.734666 -228.520244)
		(width 0.0889)
		(layer "In6.Cu")
		(net "M_E_CPU1_SA_DQ<5>")
	)
	(segment
		(start 30.780736 -205.802484)
		(end 30.943804 -205.639416)
		(width 0.14478)
		(layer "In6.Cu")
		(net "M_E_CPU1_SA_DQ<5>")
	)
	(segment
		(start 71.934324 -216.139268)
		(end 71.934324 -216.343992)
		(width 0.14478)
		(layer "In6.Cu")
		(net "M_E_CPU1_SA_DQ<5>")
	)
	(segment
		(start 71.535544 -215.740488)
		(end 71.644256 -215.631776)
		(width 0.14478)
		(layer "In6.Cu")
		(net "M_E_CPU1_SA_DQ<5>")
	)
	(segment
		(start 74.336656 -223.096074)
		(end 76.192126 -224.951544)
		(width 0.14478)
		(layer "In6.Cu")
		(net "M_E_CPU1_SA_DQ<5>")
	)
	(segment
		(start 82.324956 -229.359968)
		(end 82.171032 -229.094538)
		(width 0.0889)
		(layer "In6.Cu")
		(net "M_E_CPU1_SA_DQ<5>")
	)
	(segment
		(start 58.704226 -204.723492)
		(end 58.704226 -204.770736)
		(width 0.14478)
		(layer "In6.Cu")
		(net "M_E_CPU1_SA_DQ<5>")
	)
	(segment
		(start 54.41061 -205.779624)
		(end 54.640988 -205.779624)
		(width 0.14478)
		(layer "In6.Cu")
		(net "M_E_CPU1_SA_DQ<5>")
	)
	(segment
		(start 72.043036 -215.825832)
		(end 72.043036 -216.030556)
		(width 0.14478)
		(layer "In6.Cu")
		(net "M_E_CPU1_SA_DQ<5>")
	)
	(segment
		(start 70.53326 -214.942928)
		(end 70.737984 -214.942928)
		(width 0.14478)
		(layer "In6.Cu")
		(net "M_E_CPU1_SA_DQ<5>")
	)
	(segment
		(start 35.324034 -204.560424)
		(end 38.01491 -204.560424)
		(width 0.14478)
		(layer "In6.Cu")
		(net "M_E_CPU1_SA_DQ<5>")
	)
	(segment
		(start 49.82591 -205.410308)
		(end 50.675794 -204.560424)
		(width 0.14478)
		(layer "In6.Cu")
		(net "M_E_CPU1_SA_DQ<5>")
	)
	(segment
		(start 59.26074 -204.723492)
		(end 59.423808 -204.560424)
		(width 0.14478)
		(layer "In6.Cu")
		(net "M_E_CPU1_SA_DQ<5>")
	)
	(segment
		(start 56.080152 -205.073504)
		(end 56.31053 -205.073504)
		(width 0.14478)
		(layer "In6.Cu")
		(net "M_E_CPU1_SA_DQ<5>")
	)
	(segment
		(start 41.100756 -205.797404)
		(end 41.331134 -205.797404)
		(width 0.14478)
		(layer "In6.Cu")
		(net "M_E_CPU1_SA_DQ<5>")
	)
	(segment
		(start 59.654186 -204.560424)
		(end 59.817254 -204.723492)
		(width 0.14478)
		(layer "In6.Cu")
		(net "M_E_CPU1_SA_DQ<5>")
	)
	(segment
		(start 74.336656 -222.320358)
		(end 74.336656 -223.096074)
		(width 0.14478)
		(layer "In6.Cu")
		(net "M_E_CPU1_SA_DQ<5>")
	)
	(segment
		(start 48.574452 -205.639416)
		(end 48.73752 -205.802484)
		(width 0.14478)
		(layer "In6.Cu")
		(net "M_E_CPU1_SA_DQ<5>")
	)
	(segment
		(start 57.030112 -205.616556)
		(end 57.030112 -205.573376)
		(width 0.14478)
		(layer "In6.Cu")
		(net "M_E_CPU1_SA_DQ<5>")
	)
	(segment
		(start 54.967124 -205.410308)
		(end 55.197502 -205.410308)
		(width 0.14478)
		(layer "In6.Cu")
		(net "M_E_CPU1_SA_DQ<5>")
	)
	(segment
		(start 41.97985 -205.410308)
		(end 42.829734 -204.560424)
		(width 0.14478)
		(layer "In6.Cu")
		(net "M_E_CPU1_SA_DQ<5>")
	)
	(segment
		(start 54.247542 -205.616556)
		(end 54.41061 -205.779624)
		(width 0.14478)
		(layer "In6.Cu")
		(net "M_E_CPU1_SA_DQ<5>")
	)
	(segment
		(start 71.136764 -215.341708)
		(end 71.136764 -215.546432)
		(width 0.14478)
		(layer "In6.Cu")
		(net "M_E_CPU1_SA_DQ<5>")
	)
	(segment
		(start 70.25386 -214.036656)
		(end 70.447916 -214.230712)
		(width 0.14478)
		(layer "In6.Cu")
		(net "M_E_CPU1_SA_DQ<5>")
	)
	(segment
		(start 30.550358 -205.802484)
		(end 30.780736 -205.802484)
		(width 0.14478)
		(layer "In6.Cu")
		(net "M_E_CPU1_SA_DQ<5>")
	)
	(segment
		(start 49.294034 -205.410308)
		(end 49.82591 -205.410308)
		(width 0.14478)
		(layer "In6.Cu")
		(net "M_E_CPU1_SA_DQ<5>")
	)
	(segment
		(start 31.33725 -205.018132)
		(end 31.500318 -205.1812)
		(width 0.14478)
		(layer "In6.Cu")
		(net "M_E_CPU1_SA_DQ<5>")
	)
	(segment
		(start 41.331134 -205.797404)
		(end 41.494202 -205.634336)
		(width 0.14478)
		(layer "In6.Cu")
		(net "M_E_CPU1_SA_DQ<5>")
	)
	(segment
		(start 54.640988 -205.779624)
		(end 54.804056 -205.616556)
		(width 0.14478)
		(layer "In6.Cu")
		(net "M_E_CPU1_SA_DQ<5>")
	)
	(segment
		(start 70.737984 -214.942928)
		(end 70.846696 -214.834216)
		(width 0.14478)
		(layer "In6.Cu")
		(net "M_E_CPU1_SA_DQ<5>")
	)
	(segment
		(start 76.402946 -225.509582)
		(end 77.285088 -226.391724)
		(width 0.0889)
		(layer "In6.Cu")
		(net "M_E_CPU1_SA_DQ<5>")
	)
	(segment
		(start 79.548736 -229.334314)
		(end 79.649828 -229.340664)
		(width 0.0889)
		(layer "In6.Cu")
		(net "M_E_CPU1_SA_DQ<5>")
	)
	(segment
		(start 70.339204 -214.544148)
		(end 70.339204 -214.748872)
		(width 0.14478)
		(layer "In6.Cu")
		(net "M_E_CPU1_SA_DQ<5>")
	)
	(segment
		(start 59.980322 -204.933804)
		(end 60.524136 -204.933804)
		(width 0.14478)
		(layer "In6.Cu")
		(net "M_E_CPU1_SA_DQ<5>")
	)
	(segment
		(start 57.36971 -205.410308)
		(end 58.219594 -204.560424)
		(width 0.14478)
		(layer "In6.Cu")
		(net "M_E_CPU1_SA_DQ<5>")
	)
	(segment
		(start 72.215248 -216.624916)
		(end 72.215248 -220.19895)
		(width 0.14478)
		(layer "In6.Cu")
		(net "M_E_CPU1_SA_DQ<5>")
	)
	(segment
		(start 56.636666 -205.779624)
		(end 56.867044 -205.779624)
		(width 0.14478)
		(layer "In6.Cu")
		(net "M_E_CPU1_SA_DQ<5>")
	)
	(segment
		(start 41.494202 -205.634336)
		(end 41.494202 -205.573376)
		(width 0.14478)
		(layer "In6.Cu")
		(net "M_E_CPU1_SA_DQ<5>")
	)
	(segment
		(start 48.73752 -205.802484)
		(end 48.967898 -205.802484)
		(width 0.14478)
		(layer "In6.Cu")
		(net "M_E_CPU1_SA_DQ<5>")
	)
	(segment
		(start 57.030112 -205.573376)
		(end 57.19318 -205.410308)
		(width 0.14478)
		(layer "In6.Cu")
		(net "M_E_CPU1_SA_DQ<5>")
	)
	(segment
		(start 59.097672 -204.933804)
		(end 59.26074 -204.770736)
		(width 0.14478)
		(layer "In6.Cu")
		(net "M_E_CPU1_SA_DQ<5>")
	)
	(segment
		(start 38.01491 -204.560424)
		(end 38.864794 -205.410308)
		(width 0.14478)
		(layer "In6.Cu")
		(net "M_E_CPU1_SA_DQ<5>")
	)
	(segment
		(start 41.494202 -205.573376)
		(end 41.65727 -205.410308)
		(width 0.14478)
		(layer "In6.Cu")
		(net "M_E_CPU1_SA_DQ<5>")
	)
	(segment
		(start 77.285088 -226.391724)
		(end 77.538326 -227.00361)
		(width 0.0889)
		(layer "In6.Cu")
		(net "M_E_CPU1_SA_DQ<5>")
	)
	(segment
		(start 69.940424 -214.145368)
		(end 70.049136 -214.036656)
		(width 0.14478)
		(layer "In6.Cu")
		(net "M_E_CPU1_SA_DQ<5>")
	)
	(segment
		(start 77.538326 -227.00361)
		(end 77.538326 -227.689664)
		(width 0.0889)
		(layer "In6.Cu")
		(net "M_E_CPU1_SA_DQ<5>")
	)
	(segment
		(start 45.69079 -204.560424)
		(end 46.540674 -205.410308)
		(width 0.14478)
		(layer "In6.Cu")
		(net "M_E_CPU1_SA_DQ<5>")
	)
	(segment
		(start 70.339204 -214.748872)
		(end 70.53326 -214.942928)
		(width 0.14478)
		(layer "In6.Cu")
		(net "M_E_CPU1_SA_DQ<5>")
	)
	(segment
		(start 46.540674 -205.410308)
		(end 48.411384 -205.410308)
		(width 0.14478)
		(layer "In6.Cu")
		(net "M_E_CPU1_SA_DQ<5>")
	)
	(segment
		(start 70.846696 -214.834216)
		(end 71.05142 -214.834216)
		(width 0.14478)
		(layer "In6.Cu")
		(net "M_E_CPU1_SA_DQ<5>")
	)
	(segment
		(start 54.804056 -205.616556)
		(end 54.804056 -205.573376)
		(width 0.14478)
		(layer "In6.Cu")
		(net "M_E_CPU1_SA_DQ<5>")
	)
	(segment
		(start 40.937688 -205.634336)
		(end 41.100756 -205.797404)
		(width 0.14478)
		(layer "In6.Cu")
		(net "M_E_CPU1_SA_DQ<5>")
	)
	(segment
		(start 55.197502 -205.410308)
		(end 55.36057 -205.573376)
		(width 0.14478)
		(layer "In6.Cu")
		(net "M_E_CPU1_SA_DQ<5>")
	)
	(segment
		(start 58.541158 -204.560424)
		(end 58.704226 -204.723492)
		(width 0.14478)
		(layer "In6.Cu")
		(net "M_E_CPU1_SA_DQ<5>")
	)
	(segment
		(start 55.917084 -205.236572)
		(end 56.080152 -205.073504)
		(width 0.14478)
		(layer "In6.Cu")
		(net "M_E_CPU1_SA_DQ<5>")
	)
	(segment
		(start 71.33082 -215.740488)
		(end 71.535544 -215.740488)
		(width 0.14478)
		(layer "In6.Cu")
		(net "M_E_CPU1_SA_DQ<5>")
	)
	(segment
		(start 49.130966 -205.639416)
		(end 49.130966 -205.573376)
		(width 0.14478)
		(layer "In6.Cu")
		(net "M_E_CPU1_SA_DQ<5>")
	)
	(segment
		(start 79.649828 -229.340664)
		(end 79.821278 -229.340664)
		(width 0.0889)
		(layer "In6.Cu")
		(net "M_E_CPU1_SA_DQ<5>")
	)
	(segment
		(start 71.136764 -215.546432)
		(end 71.33082 -215.740488)
		(width 0.14478)
		(layer "In6.Cu")
		(net "M_E_CPU1_SA_DQ<5>")
	)
	(segment
		(start 48.574452 -205.573376)
		(end 48.574452 -205.639416)
		(width 0.14478)
		(layer "In6.Cu")
		(net "M_E_CPU1_SA_DQ<5>")
	)
	(segment
		(start 71.245476 -215.232996)
		(end 71.136764 -215.341708)
		(width 0.14478)
		(layer "In6.Cu")
		(net "M_E_CPU1_SA_DQ<5>")
	)
	(segment
		(start 71.84898 -215.631776)
		(end 72.043036 -215.825832)
		(width 0.14478)
		(layer "In6.Cu")
		(net "M_E_CPU1_SA_DQ<5>")
	)
	(segment
		(start 54.247542 -205.573376)
		(end 54.247542 -205.616556)
		(width 0.14478)
		(layer "In6.Cu")
		(net "M_E_CPU1_SA_DQ<5>")
	)
	(segment
		(start 34.47415 -205.410308)
		(end 35.324034 -204.560424)
		(width 0.14478)
		(layer "In6.Cu")
		(net "M_E_CPU1_SA_DQ<5>")
	)
	(segment
		(start 58.867294 -204.933804)
		(end 59.097672 -204.933804)
		(width 0.14478)
		(layer "In6.Cu")
		(net "M_E_CPU1_SA_DQ<5>")
	)
	(segment
		(start 70.049136 -214.036656)
		(end 70.25386 -214.036656)
		(width 0.14478)
		(layer "In6.Cu")
		(net "M_E_CPU1_SA_DQ<5>")
	)
	(segment
		(start 82.302858 -229.443026)
		(end 82.324956 -229.359968)
		(width 0.0889)
		(layer "In6.Cu")
		(net "M_E_CPU1_SA_DQ<5>")
	)
	(segment
		(start 29.252164 -204.985366)
		(end 29.677106 -205.410308)
		(width 0.14478)
		(layer "In6.Cu")
		(net "M_E_CPU1_SA_DQ<5>")
	)
	(segment
		(start 56.31053 -205.073504)
		(end 56.473598 -205.236572)
		(width 0.14478)
		(layer "In6.Cu")
		(net "M_E_CPU1_SA_DQ<5>")
	)
	(segment
		(start 50.675794 -204.560424)
		(end 53.23459 -204.560424)
		(width 0.14478)
		(layer "In6.Cu")
		(net "M_E_CPU1_SA_DQ<5>")
	)
	(segment
		(start 53.23459 -204.560424)
		(end 54.247542 -205.573376)
		(width 0.14478)
		(layer "In6.Cu")
		(net "M_E_CPU1_SA_DQ<5>")
	)
	(segment
		(start 71.245476 -215.028272)
		(end 71.245476 -215.232996)
		(width 0.14478)
		(layer "In6.Cu")
		(net "M_E_CPU1_SA_DQ<5>")
	)
	(segment
		(start 56.473598 -205.616556)
		(end 56.636666 -205.779624)
		(width 0.14478)
		(layer "In6.Cu")
		(net "M_E_CPU1_SA_DQ<5>")
	)
	(segment
		(start 70.447916 -214.435436)
		(end 70.339204 -214.544148)
		(width 0.14478)
		(layer "In6.Cu")
		(net "M_E_CPU1_SA_DQ<5>")
	)
	(segment
		(start 76.402946 -225.162364)
		(end 76.402946 -225.509582)
		(width 0.0889)
		(layer "In6.Cu")
		(net "M_E_CPU1_SA_DQ<5>")
	)
	(segment
		(start 31.500318 -205.1812)
		(end 31.500318 -205.639416)
		(width 0.14478)
		(layer "In6.Cu")
		(net "M_E_CPU1_SA_DQ<5>")
	)
	(arc
		(start 79.821278 -229.340664)
		(mid 79.967668 -229.360075)
		(end 80.10398 -229.416864)
		(width 0.0889)
		(layer "In6.Cu")
		(net "M_E_CPU1_SA_DQ<5>")
	)
	(arc
		(start 80.478122 -229.416864)
		(mid 80.761078 -229.340687)
		(end 81.044034 -229.416864)
		(width 0.0889)
		(layer "In6.Cu")
		(net "M_E_CPU1_SA_DQ<5>")
	)
	(arc
		(start 81.984088 -229.416864)
		(mid 82.140525 -229.465902)
		(end 82.302858 -229.443026)
		(width 0.0889)
		(layer "In6.Cu")
		(net "M_E_CPU1_SA_DQ<5>")
	)
	(arc
		(start 81.052416 -229.42169)
		(mid 81.235924 -229.467215)
		(end 81.418176 -229.416864)
		(width 0.0889)
		(layer "In6.Cu")
		(net "M_E_CPU1_SA_DQ<5>")
	)
	(arc
		(start 80.10398 -229.416864)
		(mid 80.286231 -229.467248)
		(end 80.46974 -229.42169)
		(width 0.0889)
		(layer "In6.Cu")
		(net "M_E_CPU1_SA_DQ<5>")
	)
	(arc
		(start 81.418176 -229.416864)
		(mid 81.701132 -229.340687)
		(end 81.984088 -229.416864)
		(width 0.0889)
		(layer "In6.Cu")
		(net "M_E_CPU1_SA_DQ<5>")
	)
	(segment
		(start 81.22793 -228.55047)
		(end 80.761078 -228.284532)
		(width 0.10668)
		(layer "F.Cu")
		(net "M_E_CPU1_SA_DQ<4>")
	)
	(segment
		(start 30.254448 -202.917044)
		(end 30.484826 -202.917044)
		(width 0.14478)
		(layer "In6.Cu")
		(net "M_E_CPU1_SA_DQ<4>")
	)
	(segment
		(start 68.217796 -210.917536)
		(end 68.42252 -210.917536)
		(width 0.14478)
		(layer "In6.Cu")
		(net "M_E_CPU1_SA_DQ<4>")
	)
	(segment
		(start 69.015356 -211.715096)
		(end 69.22008 -211.715096)
		(width 0.14478)
		(layer "In6.Cu")
		(net "M_E_CPU1_SA_DQ<4>")
	)
	(segment
		(start 67.899026 -211.031582)
		(end 68.10375 -211.031582)
		(width 0.14478)
		(layer "In6.Cu")
		(net "M_E_CPU1_SA_DQ<4>")
	)
	(segment
		(start 53.18125 -202.870054)
		(end 54.021482 -203.710286)
		(width 0.14478)
		(layer "In6.Cu")
		(net "M_E_CPU1_SA_DQ<4>")
	)
	(segment
		(start 67.30619 -210.234022)
		(end 67.420236 -210.119976)
		(width 0.14478)
		(layer "In6.Cu")
		(net "M_E_CPU1_SA_DQ<4>")
	)
	(segment
		(start 38.874446 -203.719938)
		(end 40.79621 -203.719938)
		(width 0.14478)
		(layer "In6.Cu")
		(net "M_E_CPU1_SA_DQ<4>")
	)
	(segment
		(start 80.915002 -228.549962)
		(end 80.761078 -228.284532)
		(width 0.0889)
		(layer "In6.Cu")
		(net "M_E_CPU1_SA_DQ<4>")
	)
	(segment
		(start 69.30009 -212.227922)
		(end 69.30009 -212.432646)
		(width 0.14478)
		(layer "In6.Cu")
		(net "M_E_CPU1_SA_DQ<4>")
	)
	(segment
		(start 77.063346 -224.128584)
		(end 77.063346 -224.331784)
		(width 0.0889)
		(layer "In6.Cu")
		(net "M_E_CPU1_SA_DQ<4>")
	)
	(segment
		(start 75.235816 -221.947486)
		(end 75.235816 -222.301054)
		(width 0.14478)
		(layer "In6.Cu")
		(net "M_E_CPU1_SA_DQ<4>")
	)
	(segment
		(start 65.19545 -208.333086)
		(end 65.20053 -208.333086)
		(width 0.14478)
		(layer "In6.Cu")
		(net "M_E_CPU1_SA_DQ<4>")
	)
	(segment
		(start 31.507684 -203.873354)
		(end 31.507684 -203.935076)
		(width 0.14478)
		(layer "In6.Cu")
		(net "M_E_CPU1_SA_DQ<4>")
	)
	(segment
		(start 68.90131 -211.829142)
		(end 69.015356 -211.715096)
		(width 0.14478)
		(layer "In6.Cu")
		(net "M_E_CPU1_SA_DQ<4>")
	)
	(segment
		(start 80.89265 -228.633274)
		(end 80.915002 -228.549962)
		(width 0.0889)
		(layer "In6.Cu")
		(net "M_E_CPU1_SA_DQ<4>")
	)
	(segment
		(start 54.605174 -203.932536)
		(end 54.768242 -204.095604)
		(width 0.14478)
		(layer "In6.Cu")
		(net "M_E_CPU1_SA_DQ<4>")
	)
	(segment
		(start 40.949626 -203.873354)
		(end 40.949626 -203.937616)
		(width 0.14478)
		(layer "In6.Cu")
		(net "M_E_CPU1_SA_DQ<4>")
	)
	(segment
		(start 33.303718 -203.719938)
		(end 33.457134 -203.873354)
		(width 0.14478)
		(layer "In6.Cu")
		(net "M_E_CPU1_SA_DQ<4>")
	)
	(segment
		(start 31.90113 -204.098144)
		(end 32.064198 -203.935076)
		(width 0.14478)
		(layer "In6.Cu")
		(net "M_E_CPU1_SA_DQ<4>")
	)
	(segment
		(start 68.42252 -210.917536)
		(end 68.616576 -211.111592)
		(width 0.14478)
		(layer "In6.Cu")
		(net "M_E_CPU1_SA_DQ<4>")
	)
	(segment
		(start 30.09138 -203.547218)
		(end 30.09138 -203.080112)
		(width 0.14478)
		(layer "In6.Cu")
		(net "M_E_CPU1_SA_DQ<4>")
	)
	(segment
		(start 66.303906 -209.436462)
		(end 66.50863 -209.436462)
		(width 0.14478)
		(layer "In6.Cu")
		(net "M_E_CPU1_SA_DQ<4>")
	)
	(segment
		(start 66.223896 -208.923636)
		(end 66.10985 -209.037682)
		(width 0.14478)
		(layer "In6.Cu")
		(net "M_E_CPU1_SA_DQ<4>")
	)
	(segment
		(start 49.137062 -203.937616)
		(end 49.137062 -203.873354)
		(width 0.14478)
		(layer "In6.Cu")
		(net "M_E_CPU1_SA_DQ<4>")
	)
	(segment
		(start 48.973994 -204.100684)
		(end 49.137062 -203.937616)
		(width 0.14478)
		(layer "In6.Cu")
		(net "M_E_CPU1_SA_DQ<4>")
	)
	(segment
		(start 68.616576 -211.316316)
		(end 68.50253 -211.430362)
		(width 0.14478)
		(layer "In6.Cu")
		(net "M_E_CPU1_SA_DQ<4>")
	)
	(segment
		(start 68.10375 -211.031582)
		(end 68.217796 -210.917536)
		(width 0.14478)
		(layer "In6.Cu")
		(net "M_E_CPU1_SA_DQ<4>")
	)
	(segment
		(start 69.22008 -211.715096)
		(end 69.414136 -211.909152)
		(width 0.14478)
		(layer "In6.Cu")
		(net "M_E_CPU1_SA_DQ<4>")
	)
	(segment
		(start 55.88127 -204.095604)
		(end 56.111648 -204.095604)
		(width 0.14478)
		(layer "In6.Cu")
		(net "M_E_CPU1_SA_DQ<4>")
	)
	(segment
		(start 41.97985 -203.710286)
		(end 42.829734 -202.860402)
		(width 0.14478)
		(layer "In6.Cu")
		(net "M_E_CPU1_SA_DQ<4>")
	)
	(segment
		(start 34.013648 -203.873354)
		(end 34.176716 -203.710286)
		(width 0.14478)
		(layer "In6.Cu")
		(net "M_E_CPU1_SA_DQ<4>")
	)
	(segment
		(start 35.324034 -202.860402)
		(end 35.602418 -202.860402)
		(width 0.14478)
		(layer "In6.Cu")
		(net "M_E_CPU1_SA_DQ<4>")
	)
	(segment
		(start 54.768242 -204.095604)
		(end 54.99862 -204.095604)
		(width 0.14478)
		(layer "In6.Cu")
		(net "M_E_CPU1_SA_DQ<4>")
	)
	(segment
		(start 30.647894 -203.080112)
		(end 30.647894 -203.547218)
		(width 0.14478)
		(layer "In6.Cu")
		(net "M_E_CPU1_SA_DQ<4>")
	)
	(segment
		(start 33.457134 -203.873354)
		(end 33.457134 -203.937616)
		(width 0.14478)
		(layer "In6.Cu")
		(net "M_E_CPU1_SA_DQ<4>")
	)
	(segment
		(start 69.902578 -212.83041)
		(end 70.01764 -212.715348)
		(width 0.14478)
		(layer "In6.Cu")
		(net "M_E_CPU1_SA_DQ<4>")
	)
	(segment
		(start 69.30009 -212.432646)
		(end 69.697854 -212.83041)
		(width 0.14478)
		(layer "In6.Cu")
		(net "M_E_CPU1_SA_DQ<4>")
	)
	(segment
		(start 67.021456 -209.721196)
		(end 66.90741 -209.835242)
		(width 0.14478)
		(layer "In6.Cu")
		(net "M_E_CPU1_SA_DQ<4>")
	)
	(segment
		(start 31.344616 -203.710286)
		(end 31.507684 -203.873354)
		(width 0.14478)
		(layer "In6.Cu")
		(net "M_E_CPU1_SA_DQ<4>")
	)
	(segment
		(start 66.50863 -209.436462)
		(end 66.622676 -209.322416)
		(width 0.14478)
		(layer "In6.Cu")
		(net "M_E_CPU1_SA_DQ<4>")
	)
	(segment
		(start 32.064198 -203.873354)
		(end 32.217614 -203.719938)
		(width 0.14478)
		(layer "In6.Cu")
		(net "M_E_CPU1_SA_DQ<4>")
	)
	(segment
		(start 66.223896 -208.718912)
		(end 66.223896 -208.923636)
		(width 0.14478)
		(layer "In6.Cu")
		(net "M_E_CPU1_SA_DQ<4>")
	)
	(segment
		(start 66.8274 -209.322416)
		(end 67.021456 -209.516472)
		(width 0.14478)
		(layer "In6.Cu")
		(net "M_E_CPU1_SA_DQ<4>")
	)
	(segment
		(start 69.414136 -211.909152)
		(end 69.414136 -212.113876)
		(width 0.14478)
		(layer "In6.Cu")
		(net "M_E_CPU1_SA_DQ<4>")
	)
	(segment
		(start 77.540866 -225.749104)
		(end 77.540866 -226.035108)
		(width 0.0889)
		(layer "In6.Cu")
		(net "M_E_CPU1_SA_DQ<4>")
	)
	(segment
		(start 77.613002 -224.88144)
		(end 77.613002 -225.676968)
		(width 0.0889)
		(layer "In6.Cu")
		(net "M_E_CPU1_SA_DQ<4>")
	)
	(segment
		(start 55.161688 -203.873354)
		(end 55.324756 -203.710286)
		(width 0.14478)
		(layer "In6.Cu")
		(net "M_E_CPU1_SA_DQ<4>")
	)
	(segment
		(start 36.409122 -202.870054)
		(end 38.024562 -202.870054)
		(width 0.14478)
		(layer "In6.Cu")
		(net "M_E_CPU1_SA_DQ<4>")
	)
	(segment
		(start 66.10985 -209.242406)
		(end 66.303906 -209.436462)
		(width 0.14478)
		(layer "In6.Cu")
		(net "M_E_CPU1_SA_DQ<4>")
	)
	(segment
		(start 57.36971 -203.710286)
		(end 57.832752 -203.247244)
		(width 0.14478)
		(layer "In6.Cu")
		(net "M_E_CPU1_SA_DQ<4>")
	)
	(segment
		(start 29.252164 -203.285344)
		(end 29.677106 -203.710286)
		(width 0.14478)
		(layer "In6.Cu")
		(net "M_E_CPU1_SA_DQ<4>")
	)
	(segment
		(start 45.61459 -202.870054)
		(end 46.464474 -203.719938)
		(width 0.14478)
		(layer "In6.Cu")
		(net "M_E_CPU1_SA_DQ<4>")
	)
	(segment
		(start 55.718202 -203.873354)
		(end 55.718202 -203.932536)
		(width 0.14478)
		(layer "In6.Cu")
		(net "M_E_CPU1_SA_DQ<4>")
	)
	(segment
		(start 54.442106 -203.710286)
		(end 54.605174 -203.873354)
		(width 0.14478)
		(layer "In6.Cu")
		(net "M_E_CPU1_SA_DQ<4>")
	)
	(segment
		(start 41.669208 -203.710286)
		(end 41.97985 -203.710286)
		(width 0.14478)
		(layer "In6.Cu")
		(net "M_E_CPU1_SA_DQ<4>")
	)
	(segment
		(start 69.697854 -212.83041)
		(end 69.902578 -212.83041)
		(width 0.14478)
		(layer "In6.Cu")
		(net "M_E_CPU1_SA_DQ<4>")
	)
	(segment
		(start 30.647894 -203.547218)
		(end 30.810962 -203.710286)
		(width 0.14478)
		(layer "In6.Cu")
		(net "M_E_CPU1_SA_DQ<4>")
	)
	(segment
		(start 42.829734 -202.860402)
		(end 43.068494 -202.860402)
		(width 0.14478)
		(layer "In6.Cu")
		(net "M_E_CPU1_SA_DQ<4>")
	)
	(segment
		(start 34.013648 -203.937616)
		(end 34.013648 -203.873354)
		(width 0.14478)
		(layer "In6.Cu")
		(net "M_E_CPU1_SA_DQ<4>")
	)
	(segment
		(start 30.09138 -203.080112)
		(end 30.254448 -202.917044)
		(width 0.14478)
		(layer "In6.Cu")
		(net "M_E_CPU1_SA_DQ<4>")
	)
	(segment
		(start 65.20053 -208.333086)
		(end 65.506346 -208.638902)
		(width 0.14478)
		(layer "In6.Cu")
		(net "M_E_CPU1_SA_DQ<4>")
	)
	(segment
		(start 77.721968 -226.21621)
		(end 78.033626 -226.968558)
		(width 0.0889)
		(layer "In6.Cu")
		(net "M_E_CPU1_SA_DQ<4>")
	)
	(segment
		(start 65.506346 -208.638902)
		(end 65.71107 -208.638902)
		(width 0.14478)
		(layer "In6.Cu")
		(net "M_E_CPU1_SA_DQ<4>")
	)
	(segment
		(start 57.832752 -203.247244)
		(end 60.109608 -203.247244)
		(width 0.14478)
		(layer "In6.Cu")
		(net "M_E_CPU1_SA_DQ<4>")
	)
	(segment
		(start 55.718202 -203.932536)
		(end 55.88127 -204.095604)
		(width 0.14478)
		(layer "In6.Cu")
		(net "M_E_CPU1_SA_DQ<4>")
	)
	(segment
		(start 73.205086 -215.69807)
		(end 73.205086 -219.916756)
		(width 0.14478)
		(layer "In6.Cu")
		(net "M_E_CPU1_SA_DQ<4>")
	)
	(segment
		(start 43.231562 -203.089256)
		(end 43.39463 -203.252324)
		(width 0.14478)
		(layer "In6.Cu")
		(net "M_E_CPU1_SA_DQ<4>")
	)
	(segment
		(start 48.743616 -204.100684)
		(end 48.973994 -204.100684)
		(width 0.14478)
		(layer "In6.Cu")
		(net "M_E_CPU1_SA_DQ<4>")
	)
	(segment
		(start 36.158932 -203.120244)
		(end 36.409122 -202.870054)
		(width 0.14478)
		(layer "In6.Cu")
		(net "M_E_CPU1_SA_DQ<4>")
	)
	(segment
		(start 70.222364 -212.715348)
		(end 73.205086 -215.69807)
		(width 0.14478)
		(layer "In6.Cu")
		(net "M_E_CPU1_SA_DQ<4>")
	)
	(segment
		(start 67.62496 -210.119976)
		(end 67.819016 -210.314032)
		(width 0.14478)
		(layer "In6.Cu")
		(net "M_E_CPU1_SA_DQ<4>")
	)
	(segment
		(start 75.235816 -222.301054)
		(end 76.778866 -223.844104)
		(width 0.14478)
		(layer "In6.Cu")
		(net "M_E_CPU1_SA_DQ<4>")
	)
	(segment
		(start 79.55026 -228.657658)
		(end 79.821024 -228.657658)
		(width 0.0889)
		(layer "In6.Cu")
		(net "M_E_CPU1_SA_DQ<4>")
	)
	(segment
		(start 43.941492 -202.870054)
		(end 45.61459 -202.870054)
		(width 0.14478)
		(layer "In6.Cu")
		(net "M_E_CPU1_SA_DQ<4>")
	)
	(segment
		(start 76.778866 -223.844104)
		(end 77.063346 -224.128584)
		(width 0.0889)
		(layer "In6.Cu")
		(net "M_E_CPU1_SA_DQ<4>")
	)
	(segment
		(start 67.70497 -210.837526)
		(end 67.899026 -211.031582)
		(width 0.14478)
		(layer "In6.Cu")
		(net "M_E_CPU1_SA_DQ<4>")
	)
	(segment
		(start 67.70497 -210.632802)
		(end 67.70497 -210.837526)
		(width 0.14478)
		(layer "In6.Cu")
		(net "M_E_CPU1_SA_DQ<4>")
	)
	(segment
		(start 54.021482 -203.710286)
		(end 54.442106 -203.710286)
		(width 0.14478)
		(layer "In6.Cu")
		(net "M_E_CPU1_SA_DQ<4>")
	)
	(segment
		(start 77.063346 -224.331784)
		(end 77.613002 -224.88144)
		(width 0.0889)
		(layer "In6.Cu")
		(net "M_E_CPU1_SA_DQ<4>")
	)
	(segment
		(start 66.622676 -209.322416)
		(end 66.8274 -209.322416)
		(width 0.14478)
		(layer "In6.Cu")
		(net "M_E_CPU1_SA_DQ<4>")
	)
	(segment
		(start 65.71107 -208.638902)
		(end 65.825116 -208.524856)
		(width 0.14478)
		(layer "In6.Cu")
		(net "M_E_CPU1_SA_DQ<4>")
	)
	(segment
		(start 60.109608 -203.247244)
		(end 65.19545 -208.333086)
		(width 0.14478)
		(layer "In6.Cu")
		(net "M_E_CPU1_SA_DQ<4>")
	)
	(segment
		(start 67.819016 -210.518756)
		(end 67.70497 -210.632802)
		(width 0.14478)
		(layer "In6.Cu")
		(net "M_E_CPU1_SA_DQ<4>")
	)
	(segment
		(start 49.82591 -203.710286)
		(end 50.666142 -202.870054)
		(width 0.14478)
		(layer "In6.Cu")
		(net "M_E_CPU1_SA_DQ<4>")
	)
	(segment
		(start 43.39463 -203.252324)
		(end 43.625008 -203.252324)
		(width 0.14478)
		(layer "In6.Cu")
		(net "M_E_CPU1_SA_DQ<4>")
	)
	(segment
		(start 49.30013 -203.710286)
		(end 49.82591 -203.710286)
		(width 0.14478)
		(layer "In6.Cu")
		(net "M_E_CPU1_SA_DQ<4>")
	)
	(segment
		(start 77.540866 -226.035108)
		(end 77.721968 -226.21621)
		(width 0.0889)
		(layer "In6.Cu")
		(net "M_E_CPU1_SA_DQ<4>")
	)
	(segment
		(start 66.02984 -208.524856)
		(end 66.223896 -208.718912)
		(width 0.14478)
		(layer "In6.Cu")
		(net "M_E_CPU1_SA_DQ<4>")
	)
	(segment
		(start 67.021456 -209.516472)
		(end 67.021456 -209.721196)
		(width 0.14478)
		(layer "In6.Cu")
		(net "M_E_CPU1_SA_DQ<4>")
	)
	(segment
		(start 48.427132 -203.719938)
		(end 48.580548 -203.873354)
		(width 0.14478)
		(layer "In6.Cu")
		(net "M_E_CPU1_SA_DQ<4>")
	)
	(segment
		(start 56.274716 -203.873354)
		(end 56.437784 -203.710286)
		(width 0.14478)
		(layer "In6.Cu")
		(net "M_E_CPU1_SA_DQ<4>")
	)
	(segment
		(start 34.176716 -203.710286)
		(end 34.47415 -203.710286)
		(width 0.14478)
		(layer "In6.Cu")
		(net "M_E_CPU1_SA_DQ<4>")
	)
	(segment
		(start 41.112694 -204.100684)
		(end 41.343072 -204.100684)
		(width 0.14478)
		(layer "In6.Cu")
		(net "M_E_CPU1_SA_DQ<4>")
	)
	(segment
		(start 78.033626 -226.968558)
		(end 78.033626 -227.605844)
		(width 0.0889)
		(layer "In6.Cu")
		(net "M_E_CPU1_SA_DQ<4>")
	)
	(segment
		(start 33.620202 -204.100684)
		(end 33.85058 -204.100684)
		(width 0.14478)
		(layer "In6.Cu")
		(net "M_E_CPU1_SA_DQ<4>")
	)
	(segment
		(start 43.788076 -203.02347)
		(end 43.941492 -202.870054)
		(width 0.14478)
		(layer "In6.Cu")
		(net "M_E_CPU1_SA_DQ<4>")
	)
	(segment
		(start 29.677106 -203.710286)
		(end 29.928312 -203.710286)
		(width 0.14478)
		(layer "In6.Cu")
		(net "M_E_CPU1_SA_DQ<4>")
	)
	(segment
		(start 41.50614 -203.937616)
		(end 41.50614 -203.873354)
		(width 0.14478)
		(layer "In6.Cu")
		(net "M_E_CPU1_SA_DQ<4>")
	)
	(segment
		(start 49.137062 -203.873354)
		(end 49.30013 -203.710286)
		(width 0.14478)
		(layer "In6.Cu")
		(net "M_E_CPU1_SA_DQ<4>")
	)
	(segment
		(start 56.111648 -204.095604)
		(end 56.274716 -203.932536)
		(width 0.14478)
		(layer "In6.Cu")
		(net "M_E_CPU1_SA_DQ<4>")
	)
	(segment
		(start 43.625008 -203.252324)
		(end 43.788076 -203.089256)
		(width 0.14478)
		(layer "In6.Cu")
		(net "M_E_CPU1_SA_DQ<4>")
	)
	(segment
		(start 40.949626 -203.937616)
		(end 41.112694 -204.100684)
		(width 0.14478)
		(layer "In6.Cu")
		(net "M_E_CPU1_SA_DQ<4>")
	)
	(segment
		(start 38.024562 -202.870054)
		(end 38.874446 -203.719938)
		(width 0.14478)
		(layer "In6.Cu")
		(net "M_E_CPU1_SA_DQ<4>")
	)
	(segment
		(start 30.484826 -202.917044)
		(end 30.647894 -203.080112)
		(width 0.14478)
		(layer "In6.Cu")
		(net "M_E_CPU1_SA_DQ<4>")
	)
	(segment
		(start 54.605174 -203.873354)
		(end 54.605174 -203.932536)
		(width 0.14478)
		(layer "In6.Cu")
		(net "M_E_CPU1_SA_DQ<4>")
	)
	(segment
		(start 55.555134 -203.710286)
		(end 55.718202 -203.873354)
		(width 0.14478)
		(layer "In6.Cu")
		(net "M_E_CPU1_SA_DQ<4>")
	)
	(segment
		(start 33.85058 -204.100684)
		(end 34.013648 -203.937616)
		(width 0.14478)
		(layer "In6.Cu")
		(net "M_E_CPU1_SA_DQ<4>")
	)
	(segment
		(start 50.666142 -202.870054)
		(end 53.18125 -202.870054)
		(width 0.14478)
		(layer "In6.Cu")
		(net "M_E_CPU1_SA_DQ<4>")
	)
	(segment
		(start 56.274716 -203.932536)
		(end 56.274716 -203.873354)
		(width 0.14478)
		(layer "In6.Cu")
		(net "M_E_CPU1_SA_DQ<4>")
	)
	(segment
		(start 40.79621 -203.719938)
		(end 40.949626 -203.873354)
		(width 0.14478)
		(layer "In6.Cu")
		(net "M_E_CPU1_SA_DQ<4>")
	)
	(segment
		(start 55.324756 -203.710286)
		(end 55.555134 -203.710286)
		(width 0.14478)
		(layer "In6.Cu")
		(net "M_E_CPU1_SA_DQ<4>")
	)
	(segment
		(start 55.161688 -203.932536)
		(end 55.161688 -203.873354)
		(width 0.14478)
		(layer "In6.Cu")
		(net "M_E_CPU1_SA_DQ<4>")
	)
	(segment
		(start 43.231562 -203.02347)
		(end 43.231562 -203.089256)
		(width 0.14478)
		(layer "In6.Cu")
		(net "M_E_CPU1_SA_DQ<4>")
	)
	(segment
		(start 66.10985 -209.037682)
		(end 66.10985 -209.242406)
		(width 0.14478)
		(layer "In6.Cu")
		(net "M_E_CPU1_SA_DQ<4>")
	)
	(segment
		(start 31.507684 -203.935076)
		(end 31.670752 -204.098144)
		(width 0.14478)
		(layer "In6.Cu")
		(net "M_E_CPU1_SA_DQ<4>")
	)
	(segment
		(start 35.602418 -202.860402)
		(end 35.86226 -203.120244)
		(width 0.14478)
		(layer "In6.Cu")
		(net "M_E_CPU1_SA_DQ<4>")
	)
	(segment
		(start 46.464474 -203.719938)
		(end 48.427132 -203.719938)
		(width 0.14478)
		(layer "In6.Cu")
		(net "M_E_CPU1_SA_DQ<4>")
	)
	(segment
		(start 68.50253 -211.635086)
		(end 68.696586 -211.829142)
		(width 0.14478)
		(layer "In6.Cu")
		(net "M_E_CPU1_SA_DQ<4>")
	)
	(segment
		(start 32.064198 -203.935076)
		(end 32.064198 -203.873354)
		(width 0.14478)
		(layer "In6.Cu")
		(net "M_E_CPU1_SA_DQ<4>")
	)
	(segment
		(start 56.437784 -203.710286)
		(end 57.36971 -203.710286)
		(width 0.14478)
		(layer "In6.Cu")
		(net "M_E_CPU1_SA_DQ<4>")
	)
	(segment
		(start 41.50614 -203.873354)
		(end 41.669208 -203.710286)
		(width 0.14478)
		(layer "In6.Cu")
		(net "M_E_CPU1_SA_DQ<4>")
	)
	(segment
		(start 31.670752 -204.098144)
		(end 31.90113 -204.098144)
		(width 0.14478)
		(layer "In6.Cu")
		(net "M_E_CPU1_SA_DQ<4>")
	)
	(segment
		(start 29.928312 -203.710286)
		(end 30.09138 -203.547218)
		(width 0.14478)
		(layer "In6.Cu")
		(net "M_E_CPU1_SA_DQ<4>")
	)
	(segment
		(start 30.810962 -203.710286)
		(end 31.344616 -203.710286)
		(width 0.14478)
		(layer "In6.Cu")
		(net "M_E_CPU1_SA_DQ<4>")
	)
	(segment
		(start 48.580548 -203.937616)
		(end 48.743616 -204.100684)
		(width 0.14478)
		(layer "In6.Cu")
		(net "M_E_CPU1_SA_DQ<4>")
	)
	(segment
		(start 54.99862 -204.095604)
		(end 55.161688 -203.932536)
		(width 0.14478)
		(layer "In6.Cu")
		(net "M_E_CPU1_SA_DQ<4>")
	)
	(segment
		(start 48.580548 -203.873354)
		(end 48.580548 -203.937616)
		(width 0.14478)
		(layer "In6.Cu")
		(net "M_E_CPU1_SA_DQ<4>")
	)
	(segment
		(start 68.616576 -211.111592)
		(end 68.616576 -211.316316)
		(width 0.14478)
		(layer "In6.Cu")
		(net "M_E_CPU1_SA_DQ<4>")
	)
	(segment
		(start 77.613002 -225.676968)
		(end 77.540866 -225.749104)
		(width 0.0889)
		(layer "In6.Cu")
		(net "M_E_CPU1_SA_DQ<4>")
	)
	(segment
		(start 67.420236 -210.119976)
		(end 67.62496 -210.119976)
		(width 0.14478)
		(layer "In6.Cu")
		(net "M_E_CPU1_SA_DQ<4>")
	)
	(segment
		(start 78.391766 -227.963984)
		(end 78.856586 -227.963984)
		(width 0.0889)
		(layer "In6.Cu")
		(net "M_E_CPU1_SA_DQ<4>")
	)
	(segment
		(start 70.01764 -212.715348)
		(end 70.222364 -212.715348)
		(width 0.14478)
		(layer "In6.Cu")
		(net "M_E_CPU1_SA_DQ<4>")
	)
	(segment
		(start 43.068494 -202.860402)
		(end 43.231562 -203.02347)
		(width 0.14478)
		(layer "In6.Cu")
		(net "M_E_CPU1_SA_DQ<4>")
	)
	(segment
		(start 66.90741 -209.835242)
		(end 66.90741 -210.039966)
		(width 0.14478)
		(layer "In6.Cu")
		(net "M_E_CPU1_SA_DQ<4>")
	)
	(segment
		(start 32.217614 -203.719938)
		(end 33.303718 -203.719938)
		(width 0.14478)
		(layer "In6.Cu")
		(net "M_E_CPU1_SA_DQ<4>")
	)
	(segment
		(start 78.033626 -227.605844)
		(end 78.391766 -227.963984)
		(width 0.0889)
		(layer "In6.Cu")
		(net "M_E_CPU1_SA_DQ<4>")
	)
	(segment
		(start 65.825116 -208.524856)
		(end 66.02984 -208.524856)
		(width 0.14478)
		(layer "In6.Cu")
		(net "M_E_CPU1_SA_DQ<4>")
	)
	(segment
		(start 33.457134 -203.937616)
		(end 33.620202 -204.100684)
		(width 0.14478)
		(layer "In6.Cu")
		(net "M_E_CPU1_SA_DQ<4>")
	)
	(segment
		(start 41.343072 -204.100684)
		(end 41.50614 -203.937616)
		(width 0.14478)
		(layer "In6.Cu")
		(net "M_E_CPU1_SA_DQ<4>")
	)
	(segment
		(start 35.86226 -203.120244)
		(end 36.158932 -203.120244)
		(width 0.14478)
		(layer "In6.Cu")
		(net "M_E_CPU1_SA_DQ<4>")
	)
	(segment
		(start 69.414136 -212.113876)
		(end 69.30009 -212.227922)
		(width 0.14478)
		(layer "In6.Cu")
		(net "M_E_CPU1_SA_DQ<4>")
	)
	(segment
		(start 73.205086 -219.916756)
		(end 75.235816 -221.947486)
		(width 0.14478)
		(layer "In6.Cu")
		(net "M_E_CPU1_SA_DQ<4>")
	)
	(segment
		(start 78.856586 -227.963984)
		(end 79.55026 -228.657658)
		(width 0.0889)
		(layer "In6.Cu")
		(net "M_E_CPU1_SA_DQ<4>")
	)
	(segment
		(start 67.819016 -210.314032)
		(end 67.819016 -210.518756)
		(width 0.14478)
		(layer "In6.Cu")
		(net "M_E_CPU1_SA_DQ<4>")
	)
	(segment
		(start 67.101466 -210.234022)
		(end 67.30619 -210.234022)
		(width 0.14478)
		(layer "In6.Cu")
		(net "M_E_CPU1_SA_DQ<4>")
	)
	(segment
		(start 68.696586 -211.829142)
		(end 68.90131 -211.829142)
		(width 0.14478)
		(layer "In6.Cu")
		(net "M_E_CPU1_SA_DQ<4>")
	)
	(segment
		(start 66.90741 -210.039966)
		(end 67.101466 -210.234022)
		(width 0.14478)
		(layer "In6.Cu")
		(net "M_E_CPU1_SA_DQ<4>")
	)
	(segment
		(start 34.47415 -203.710286)
		(end 35.324034 -202.860402)
		(width 0.14478)
		(layer "In6.Cu")
		(net "M_E_CPU1_SA_DQ<4>")
	)
	(segment
		(start 43.788076 -203.089256)
		(end 43.788076 -203.02347)
		(width 0.14478)
		(layer "In6.Cu")
		(net "M_E_CPU1_SA_DQ<4>")
	)
	(segment
		(start 68.50253 -211.430362)
		(end 68.50253 -211.635086)
		(width 0.14478)
		(layer "In6.Cu")
		(net "M_E_CPU1_SA_DQ<4>")
	)
	(arc
		(start 79.821024 -228.657658)
		(mid 79.917966 -228.644767)
		(end 80.008222 -228.607112)
		(width 0.0889)
		(layer "In6.Cu")
		(net "M_E_CPU1_SA_DQ<4>")
	)
	(arc
		(start 80.008222 -228.607112)
		(mid 80.291178 -228.530935)
		(end 80.574134 -228.607112)
		(width 0.0889)
		(layer "In6.Cu")
		(net "M_E_CPU1_SA_DQ<4>")
	)
	(arc
		(start 80.574134 -228.607112)
		(mid 80.730453 -228.656107)
		(end 80.89265 -228.633274)
		(width 0.0889)
		(layer "In6.Cu")
		(net "M_E_CPU1_SA_DQ<4>")
	)
	(segment
		(start 83.107784 -226.930458)
		(end 82.640932 -226.66452)
		(width 0.10668)
		(layer "F.Cu")
		(net "M_E_CPU1_SA_DQ<3>")
	)
	(segment
		(start 25.152096 -199.8853)
		(end 25.567386 -200.30059)
		(width 0.14478)
		(layer "In6.Cu")
		(net "M_E_CPU1_SA_DQ<3>")
	)
	(segment
		(start 38.014148 -199.450706)
		(end 38.864032 -200.30059)
		(width 0.14478)
		(layer "In6.Cu")
		(net "M_E_CPU1_SA_DQ<3>")
	)
	(segment
		(start 66.222626 -205.4479)
		(end 75.630786 -214.85606)
		(width 0.14478)
		(layer "In6.Cu")
		(net "M_E_CPU1_SA_DQ<3>")
	)
	(segment
		(start 50.241962 -199.450706)
		(end 53.246782 -199.450706)
		(width 0.14478)
		(layer "In6.Cu")
		(net "M_E_CPU1_SA_DQ<3>")
	)
	(segment
		(start 79.498952 -225.509074)
		(end 79.538068 -225.531934)
		(width 0.0889)
		(layer "In6.Cu")
		(net "M_E_CPU1_SA_DQ<3>")
	)
	(segment
		(start 78.23835 -222.049086)
		(end 78.481174 -222.29191)
		(width 0.0889)
		(layer "In6.Cu")
		(net "M_E_CPU1_SA_DQ<3>")
	)
	(segment
		(start 66.222626 -204.500734)
		(end 66.222626 -205.4479)
		(width 0.14478)
		(layer "In6.Cu")
		(net "M_E_CPU1_SA_DQ<3>")
	)
	(segment
		(start 46.552866 -200.30059)
		(end 49.392078 -200.30059)
		(width 0.14478)
		(layer "In6.Cu")
		(net "M_E_CPU1_SA_DQ<3>")
	)
	(segment
		(start 79.538322 -223.911922)
		(end 79.570072 -223.93021)
		(width 0.0889)
		(layer "In6.Cu")
		(net "M_E_CPU1_SA_DQ<3>")
	)
	(segment
		(start 62.287404 -200.565512)
		(end 66.222626 -204.500734)
		(width 0.14478)
		(layer "In6.Cu")
		(net "M_E_CPU1_SA_DQ<3>")
	)
	(segment
		(start 79.570072 -224.538794)
		(end 79.538322 -224.557082)
		(width 0.0889)
		(layer "In6.Cu")
		(net "M_E_CPU1_SA_DQ<3>")
	)
	(segment
		(start 79.969106 -226.31908)
		(end 80.008222 -226.34194)
		(width 0.0889)
		(layer "In6.Cu")
		(net "M_E_CPU1_SA_DQ<3>")
	)
	(segment
		(start 53.246782 -199.450706)
		(end 54.106572 -200.310496)
		(width 0.14478)
		(layer "In6.Cu")
		(net "M_E_CPU1_SA_DQ<3>")
	)
	(segment
		(start 81.879694 -226.337114)
		(end 81.888076 -226.34194)
		(width 0.0889)
		(layer "In6.Cu")
		(net "M_E_CPU1_SA_DQ<3>")
	)
	(segment
		(start 79.538322 -224.557082)
		(end 79.497936 -224.580704)
		(width 0.0889)
		(layer "In6.Cu")
		(net "M_E_CPU1_SA_DQ<3>")
	)
	(segment
		(start 79.03337 -223.081596)
		(end 79.068168 -223.101916)
		(width 0.0889)
		(layer "In6.Cu")
		(net "M_E_CPU1_SA_DQ<3>")
	)
	(segment
		(start 78.598268 -222.29191)
		(end 78.631034 -222.31096)
		(width 0.0889)
		(layer "In6.Cu")
		(net "M_E_CPU1_SA_DQ<3>")
	)
	(segment
		(start 79.538068 -225.531934)
		(end 79.570834 -225.550984)
		(width 0.0889)
		(layer "In6.Cu")
		(net "M_E_CPU1_SA_DQ<3>")
	)
	(segment
		(start 38.864032 -200.30059)
		(end 41.858692 -200.30059)
		(width 0.14478)
		(layer "In6.Cu")
		(net "M_E_CPU1_SA_DQ<3>")
	)
	(segment
		(start 57.77611 -199.460358)
		(end 58.71337 -199.460358)
		(width 0.14478)
		(layer "In6.Cu")
		(net "M_E_CPU1_SA_DQ<3>")
	)
	(segment
		(start 82.487008 -226.39909)
		(end 82.640932 -226.66452)
		(width 0.0889)
		(layer "In6.Cu")
		(net "M_E_CPU1_SA_DQ<3>")
	)
	(segment
		(start 45.702982 -199.450706)
		(end 46.552866 -200.30059)
		(width 0.14478)
		(layer "In6.Cu")
		(net "M_E_CPU1_SA_DQ<3>")
	)
	(segment
		(start 35.113722 -199.450706)
		(end 38.014148 -199.450706)
		(width 0.14478)
		(layer "In6.Cu")
		(net "M_E_CPU1_SA_DQ<3>")
	)
	(segment
		(start 34.263838 -200.30059)
		(end 35.113722 -199.450706)
		(width 0.14478)
		(layer "In6.Cu")
		(net "M_E_CPU1_SA_DQ<3>")
	)
	(segment
		(start 78.481174 -222.29191)
		(end 78.598268 -222.29191)
		(width 0.0889)
		(layer "In6.Cu")
		(net "M_E_CPU1_SA_DQ<3>")
	)
	(segment
		(start 78.23835 -221.645988)
		(end 78.23835 -222.049086)
		(width 0.0889)
		(layer "In6.Cu")
		(net "M_E_CPU1_SA_DQ<3>")
	)
	(segment
		(start 79.068168 -223.101916)
		(end 79.100934 -223.120966)
		(width 0.0889)
		(layer "In6.Cu")
		(net "M_E_CPU1_SA_DQ<3>")
	)
	(segment
		(start 79.499206 -223.889062)
		(end 79.538322 -223.911922)
		(width 0.0889)
		(layer "In6.Cu")
		(net "M_E_CPU1_SA_DQ<3>")
	)
	(segment
		(start 75.630786 -219.038424)
		(end 78.158848 -221.566486)
		(width 0.14478)
		(layer "In6.Cu")
		(net "M_E_CPU1_SA_DQ<3>")
	)
	(segment
		(start 59.818524 -200.565512)
		(end 62.287404 -200.565512)
		(width 0.14478)
		(layer "In6.Cu")
		(net "M_E_CPU1_SA_DQ<3>")
	)
	(segment
		(start 78.158848 -221.566486)
		(end 78.23835 -221.645988)
		(width 0.0889)
		(layer "In6.Cu")
		(net "M_E_CPU1_SA_DQ<3>")
	)
	(segment
		(start 56.925972 -200.310496)
		(end 57.77611 -199.460358)
		(width 0.14478)
		(layer "In6.Cu")
		(net "M_E_CPU1_SA_DQ<3>")
	)
	(segment
		(start 42.708576 -199.450706)
		(end 45.702982 -199.450706)
		(width 0.14478)
		(layer "In6.Cu")
		(net "M_E_CPU1_SA_DQ<3>")
	)
	(segment
		(start 75.630786 -214.85606)
		(end 75.630786 -219.038424)
		(width 0.14478)
		(layer "In6.Cu")
		(net "M_E_CPU1_SA_DQ<3>")
	)
	(segment
		(start 58.71337 -199.460358)
		(end 59.818524 -200.565512)
		(width 0.14478)
		(layer "In6.Cu")
		(net "M_E_CPU1_SA_DQ<3>")
	)
	(segment
		(start 25.567386 -200.30059)
		(end 34.263838 -200.30059)
		(width 0.14478)
		(layer "In6.Cu")
		(net "M_E_CPU1_SA_DQ<3>")
	)
	(segment
		(start 82.390996 -226.37369)
		(end 82.487008 -226.39909)
		(width 0.0889)
		(layer "In6.Cu")
		(net "M_E_CPU1_SA_DQ<3>")
	)
	(segment
		(start 41.858692 -200.30059)
		(end 42.708576 -199.450706)
		(width 0.14478)
		(layer "In6.Cu")
		(net "M_E_CPU1_SA_DQ<3>")
	)
	(segment
		(start 49.392078 -200.30059)
		(end 50.241962 -199.450706)
		(width 0.14478)
		(layer "In6.Cu")
		(net "M_E_CPU1_SA_DQ<3>")
	)
	(segment
		(start 54.106572 -200.310496)
		(end 56.925972 -200.310496)
		(width 0.14478)
		(layer "In6.Cu")
		(net "M_E_CPU1_SA_DQ<3>")
	)
	(arc
		(start 81.888076 -226.34194)
		(mid 82.135789 -226.41716)
		(end 82.390996 -226.37369)
		(width 0.0889)
		(layer "In6.Cu")
		(net "M_E_CPU1_SA_DQ<3>")
	)
	(arc
		(start 79.570072 -223.93021)
		(mid 79.726 -224.234502)
		(end 79.570072 -224.538794)
		(width 0.0889)
		(layer "In6.Cu")
		(net "M_E_CPU1_SA_DQ<3>")
	)
	(arc
		(start 81.513934 -226.34194)
		(mid 81.696185 -226.29159)
		(end 81.879694 -226.337114)
		(width 0.0889)
		(layer "In6.Cu")
		(net "M_E_CPU1_SA_DQ<3>")
	)
	(arc
		(start 79.570834 -225.550984)
		(mid 79.684763 -225.684131)
		(end 79.725774 -225.854514)
		(width 0.0889)
		(layer "In6.Cu")
		(net "M_E_CPU1_SA_DQ<3>")
	)
	(arc
		(start 78.631034 -222.31096)
		(mid 78.745187 -222.444036)
		(end 78.786228 -222.61449)
		(width 0.0889)
		(layer "In6.Cu")
		(net "M_E_CPU1_SA_DQ<3>")
	)
	(arc
		(start 79.497936 -224.580704)
		(mid 79.319871 -224.782881)
		(end 79.25562 -225.044508)
		(width 0.0889)
		(layer "In6.Cu")
		(net "M_E_CPU1_SA_DQ<3>")
	)
	(arc
		(start 78.786228 -222.61449)
		(mid 78.851829 -222.878709)
		(end 79.03337 -223.081596)
		(width 0.0889)
		(layer "In6.Cu")
		(net "M_E_CPU1_SA_DQ<3>")
	)
	(arc
		(start 80.008222 -226.34194)
		(mid 80.291178 -226.418117)
		(end 80.574134 -226.34194)
		(width 0.0889)
		(layer "In6.Cu")
		(net "M_E_CPU1_SA_DQ<3>")
	)
	(arc
		(start 79.25562 -225.044508)
		(mid 79.320135 -225.306727)
		(end 79.498952 -225.509074)
		(width 0.0889)
		(layer "In6.Cu")
		(net "M_E_CPU1_SA_DQ<3>")
	)
	(arc
		(start 79.725774 -225.854514)
		(mid 79.790289 -226.116733)
		(end 79.969106 -226.31908)
		(width 0.0889)
		(layer "In6.Cu")
		(net "M_E_CPU1_SA_DQ<3>")
	)
	(arc
		(start 79.100934 -223.120966)
		(mid 79.214863 -223.254113)
		(end 79.255874 -223.424496)
		(width 0.0889)
		(layer "In6.Cu")
		(net "M_E_CPU1_SA_DQ<3>")
	)
	(arc
		(start 80.574134 -226.34194)
		(mid 80.761078 -226.291685)
		(end 80.948022 -226.34194)
		(width 0.0889)
		(layer "In6.Cu")
		(net "M_E_CPU1_SA_DQ<3>")
	)
	(arc
		(start 80.948022 -226.34194)
		(mid 81.230978 -226.418117)
		(end 81.513934 -226.34194)
		(width 0.0889)
		(layer "In6.Cu")
		(net "M_E_CPU1_SA_DQ<3>")
	)
	(arc
		(start 79.255874 -223.424496)
		(mid 79.320389 -223.686715)
		(end 79.499206 -223.889062)
		(width 0.0889)
		(layer "In6.Cu")
		(net "M_E_CPU1_SA_DQ<3>")
	)
	(segment
		(start 83.107784 -244.750336)
		(end 82.640932 -244.484398)
		(width 0.10668)
		(layer "F.Cu")
		(net "M_E_CPU1_SA_DQ<31>")
	)
	(segment
		(start 79.634334 -244.161818)
		(end 79.646018 -244.15496)
		(width 0.0889)
		(layer "In6.Cu")
		(net "M_E_CPU1_SA_DQ<31>")
	)
	(segment
		(start 25.577292 -234.310428)
		(end 27.382978 -234.310428)
		(width 0.14478)
		(layer "In6.Cu")
		(net "M_E_CPU1_SA_DQ<31>")
	)
	(segment
		(start 27.939492 -233.705146)
		(end 28.10256 -233.868214)
		(width 0.14478)
		(layer "In6.Cu")
		(net "M_E_CPU1_SA_DQ<31>")
	)
	(segment
		(start 60.75807 -234.176824)
		(end 62.30112 -237.901988)
		(width 0.14478)
		(layer "In6.Cu")
		(net "M_E_CPU1_SA_DQ<31>")
	)
	(segment
		(start 27.709114 -233.705146)
		(end 27.939492 -233.705146)
		(width 0.14478)
		(layer "In6.Cu")
		(net "M_E_CPU1_SA_DQ<31>")
	)
	(segment
		(start 81.879694 -244.156992)
		(end 81.888076 -244.161818)
		(width 0.0889)
		(layer "In6.Cu")
		(net "M_E_CPU1_SA_DQ<31>")
	)
	(segment
		(start 41.813226 -234.310428)
		(end 42.663364 -233.46029)
		(width 0.14478)
		(layer "In6.Cu")
		(net "M_E_CPU1_SA_DQ<31>")
	)
	(segment
		(start 76.207366 -243.521484)
		(end 76.502006 -243.816124)
		(width 0.0889)
		(layer "In6.Cu")
		(net "M_E_CPU1_SA_DQ<31>")
	)
	(segment
		(start 79.056992 -244.15496)
		(end 79.068676 -244.161818)
		(width 0.0889)
		(layer "In6.Cu")
		(net "M_E_CPU1_SA_DQ<31>")
	)
	(segment
		(start 77.814932 -244.238018)
		(end 78.411324 -244.238018)
		(width 0.0889)
		(layer "In6.Cu")
		(net "M_E_CPU1_SA_DQ<31>")
	)
	(segment
		(start 75.935586 -243.521484)
		(end 76.207366 -243.521484)
		(width 0.0889)
		(layer "In6.Cu")
		(net "M_E_CPU1_SA_DQ<31>")
	)
	(segment
		(start 28.10256 -233.868214)
		(end 28.10256 -234.14736)
		(width 0.14478)
		(layer "In6.Cu")
		(net "M_E_CPU1_SA_DQ<31>")
	)
	(segment
		(start 50.26787 -233.46029)
		(end 53.256434 -233.46029)
		(width 0.14478)
		(layer "In6.Cu")
		(net "M_E_CPU1_SA_DQ<31>")
	)
	(segment
		(start 67.920362 -243.521484)
		(end 75.935586 -243.521484)
		(width 0.14478)
		(layer "In6.Cu")
		(net "M_E_CPU1_SA_DQ<31>")
	)
	(segment
		(start 27.546046 -233.868214)
		(end 27.709114 -233.705146)
		(width 0.14478)
		(layer "In6.Cu")
		(net "M_E_CPU1_SA_DQ<31>")
	)
	(segment
		(start 25.152096 -233.885232)
		(end 25.577292 -234.310428)
		(width 0.14478)
		(layer "In6.Cu")
		(net "M_E_CPU1_SA_DQ<31>")
	)
	(segment
		(start 27.382978 -234.310428)
		(end 27.546046 -234.14736)
		(width 0.14478)
		(layer "In6.Cu")
		(net "M_E_CPU1_SA_DQ<31>")
	)
	(segment
		(start 82.390996 -244.193568)
		(end 82.487008 -244.218968)
		(width 0.0889)
		(layer "In6.Cu")
		(net "M_E_CPU1_SA_DQ<31>")
	)
	(segment
		(start 28.265628 -234.310428)
		(end 34.261552 -234.310428)
		(width 0.14478)
		(layer "In6.Cu")
		(net "M_E_CPU1_SA_DQ<31>")
	)
	(segment
		(start 42.663364 -233.46029)
		(end 45.712634 -233.46029)
		(width 0.14478)
		(layer "In6.Cu")
		(net "M_E_CPU1_SA_DQ<31>")
	)
	(segment
		(start 45.712634 -233.46029)
		(end 46.562772 -234.310428)
		(width 0.14478)
		(layer "In6.Cu")
		(net "M_E_CPU1_SA_DQ<31>")
	)
	(segment
		(start 34.261552 -234.310428)
		(end 35.11169 -233.46029)
		(width 0.14478)
		(layer "In6.Cu")
		(net "M_E_CPU1_SA_DQ<31>")
	)
	(segment
		(start 62.30112 -237.902242)
		(end 67.920362 -243.521484)
		(width 0.14478)
		(layer "In6.Cu")
		(net "M_E_CPU1_SA_DQ<31>")
	)
	(segment
		(start 57.81167 -233.46029)
		(end 60.041536 -233.46029)
		(width 0.14478)
		(layer "In6.Cu")
		(net "M_E_CPU1_SA_DQ<31>")
	)
	(segment
		(start 27.546046 -234.14736)
		(end 27.546046 -233.868214)
		(width 0.14478)
		(layer "In6.Cu")
		(net "M_E_CPU1_SA_DQ<31>")
	)
	(segment
		(start 60.041536 -233.46029)
		(end 60.75807 -234.176824)
		(width 0.14478)
		(layer "In6.Cu")
		(net "M_E_CPU1_SA_DQ<31>")
	)
	(segment
		(start 35.11169 -233.46029)
		(end 38.0238 -233.46029)
		(width 0.14478)
		(layer "In6.Cu")
		(net "M_E_CPU1_SA_DQ<31>")
	)
	(segment
		(start 38.873938 -234.310428)
		(end 41.813226 -234.310428)
		(width 0.14478)
		(layer "In6.Cu")
		(net "M_E_CPU1_SA_DQ<31>")
	)
	(segment
		(start 38.0238 -233.46029)
		(end 38.873938 -234.310428)
		(width 0.14478)
		(layer "In6.Cu")
		(net "M_E_CPU1_SA_DQ<31>")
	)
	(segment
		(start 28.10256 -234.14736)
		(end 28.265628 -234.310428)
		(width 0.14478)
		(layer "In6.Cu")
		(net "M_E_CPU1_SA_DQ<31>")
	)
	(segment
		(start 46.562772 -234.310428)
		(end 49.417732 -234.310428)
		(width 0.14478)
		(layer "In6.Cu")
		(net "M_E_CPU1_SA_DQ<31>")
	)
	(segment
		(start 49.417732 -234.310428)
		(end 50.26787 -233.46029)
		(width 0.14478)
		(layer "In6.Cu")
		(net "M_E_CPU1_SA_DQ<31>")
	)
	(segment
		(start 62.30112 -237.901988)
		(end 62.30112 -237.902242)
		(width 0.14478)
		(layer "In6.Cu")
		(net "M_E_CPU1_SA_DQ<31>")
	)
	(segment
		(start 79.62392 -244.167914)
		(end 79.634334 -244.161818)
		(width 0.0889)
		(layer "In6.Cu")
		(net "M_E_CPU1_SA_DQ<31>")
	)
	(segment
		(start 82.487008 -244.218968)
		(end 82.640932 -244.484398)
		(width 0.0889)
		(layer "In6.Cu")
		(net "M_E_CPU1_SA_DQ<31>")
	)
	(segment
		(start 77.393038 -243.816124)
		(end 77.814932 -244.238018)
		(width 0.0889)
		(layer "In6.Cu")
		(net "M_E_CPU1_SA_DQ<31>")
	)
	(segment
		(start 76.502006 -243.816124)
		(end 77.393038 -243.816124)
		(width 0.0889)
		(layer "In6.Cu")
		(net "M_E_CPU1_SA_DQ<31>")
	)
	(segment
		(start 54.106572 -234.310428)
		(end 56.961532 -234.310428)
		(width 0.14478)
		(layer "In6.Cu")
		(net "M_E_CPU1_SA_DQ<31>")
	)
	(segment
		(start 53.256434 -233.46029)
		(end 54.106572 -234.310428)
		(width 0.14478)
		(layer "In6.Cu")
		(net "M_E_CPU1_SA_DQ<31>")
	)
	(segment
		(start 56.961532 -234.310428)
		(end 57.81167 -233.46029)
		(width 0.14478)
		(layer "In6.Cu")
		(net "M_E_CPU1_SA_DQ<31>")
	)
	(arc
		(start 80.574134 -244.161818)
		(mid 80.761078 -244.111563)
		(end 80.948022 -244.161818)
		(width 0.0889)
		(layer "In6.Cu")
		(net "M_E_CPU1_SA_DQ<31>")
	)
	(arc
		(start 81.513934 -244.161818)
		(mid 81.696185 -244.111468)
		(end 81.879694 -244.156992)
		(width 0.0889)
		(layer "In6.Cu")
		(net "M_E_CPU1_SA_DQ<31>")
	)
	(arc
		(start 79.646018 -244.15496)
		(mid 79.828019 -244.111427)
		(end 80.008222 -244.161818)
		(width 0.0889)
		(layer "In6.Cu")
		(net "M_E_CPU1_SA_DQ<31>")
	)
	(arc
		(start 78.69428 -244.161818)
		(mid 78.874738 -244.111374)
		(end 79.056992 -244.15496)
		(width 0.0889)
		(layer "In6.Cu")
		(net "M_E_CPU1_SA_DQ<31>")
	)
	(arc
		(start 80.948022 -244.161818)
		(mid 81.230978 -244.237995)
		(end 81.513934 -244.161818)
		(width 0.0889)
		(layer "In6.Cu")
		(net "M_E_CPU1_SA_DQ<31>")
	)
	(arc
		(start 78.411324 -244.238018)
		(mid 78.557845 -244.21864)
		(end 78.69428 -244.161818)
		(width 0.0889)
		(layer "In6.Cu")
		(net "M_E_CPU1_SA_DQ<31>")
	)
	(arc
		(start 79.068676 -244.161818)
		(mid 79.345489 -244.237961)
		(end 79.62392 -244.167914)
		(width 0.0889)
		(layer "In6.Cu")
		(net "M_E_CPU1_SA_DQ<31>")
	)
	(arc
		(start 81.888076 -244.161818)
		(mid 82.135789 -244.237038)
		(end 82.390996 -244.193568)
		(width 0.0889)
		(layer "In6.Cu")
		(net "M_E_CPU1_SA_DQ<31>")
	)
	(arc
		(start 80.008222 -244.161818)
		(mid 80.291178 -244.237995)
		(end 80.574134 -244.161818)
		(width 0.0889)
		(layer "In6.Cu")
		(net "M_E_CPU1_SA_DQ<31>")
	)
	(segment
		(start 81.69783 -243.94033)
		(end 81.230978 -243.674392)
		(width 0.10668)
		(layer "F.Cu")
		(net "M_E_CPU1_SA_DQ<30>")
	)
	(segment
		(start 27.704034 -232.447338)
		(end 27.704034 -231.444292)
		(width 0.14478)
		(layer "In6.Cu")
		(net "M_E_CPU1_SA_DQ<30>")
	)
	(segment
		(start 35.11169 -231.760268)
		(end 38.0238 -231.760268)
		(width 0.14478)
		(layer "In6.Cu")
		(net "M_E_CPU1_SA_DQ<30>")
	)
	(segment
		(start 80.46974 -243.346986)
		(end 80.478122 -243.351812)
		(width 0.0889)
		(layer "In6.Cu")
		(net "M_E_CPU1_SA_DQ<30>")
	)
	(segment
		(start 28.260548 -232.447338)
		(end 28.423616 -232.610406)
		(width 0.14478)
		(layer "In6.Cu")
		(net "M_E_CPU1_SA_DQ<30>")
	)
	(segment
		(start 42.663364 -231.760268)
		(end 45.712634 -231.760268)
		(width 0.14478)
		(layer "In6.Cu")
		(net "M_E_CPU1_SA_DQ<30>")
	)
	(segment
		(start 53.082698 -231.760268)
		(end 53.932836 -232.610406)
		(width 0.14478)
		(layer "In6.Cu")
		(net "M_E_CPU1_SA_DQ<30>")
	)
	(segment
		(start 49.417732 -232.610406)
		(end 50.26787 -231.760268)
		(width 0.14478)
		(layer "In6.Cu")
		(net "M_E_CPU1_SA_DQ<30>")
	)
	(segment
		(start 77.098906 -242.769644)
		(end 77.630528 -243.301266)
		(width 0.0889)
		(layer "In6.Cu")
		(net "M_E_CPU1_SA_DQ<30>")
	)
	(segment
		(start 50.26787 -231.760268)
		(end 53.082698 -231.760268)
		(width 0.14478)
		(layer "In6.Cu")
		(net "M_E_CPU1_SA_DQ<30>")
	)
	(segment
		(start 56.961532 -232.610406)
		(end 57.81167 -231.760268)
		(width 0.14478)
		(layer "In6.Cu")
		(net "M_E_CPU1_SA_DQ<30>")
	)
	(segment
		(start 66.345816 -240.664746)
		(end 66.72072 -240.664746)
		(width 0.14478)
		(layer "In6.Cu")
		(net "M_E_CPU1_SA_DQ<30>")
	)
	(segment
		(start 27.867102 -231.281224)
		(end 28.09748 -231.281224)
		(width 0.14478)
		(layer "In6.Cu")
		(net "M_E_CPU1_SA_DQ<30>")
	)
	(segment
		(start 76.273406 -242.612164)
		(end 76.430886 -242.769644)
		(width 0.0889)
		(layer "In6.Cu")
		(net "M_E_CPU1_SA_DQ<30>")
	)
	(segment
		(start 61.548518 -233.69524)
		(end 63.084202 -237.403132)
		(width 0.14478)
		(layer "In6.Cu")
		(net "M_E_CPU1_SA_DQ<30>")
	)
	(segment
		(start 53.932836 -232.610406)
		(end 56.961532 -232.610406)
		(width 0.14478)
		(layer "In6.Cu")
		(net "M_E_CPU1_SA_DQ<30>")
	)
	(segment
		(start 45.712634 -231.760268)
		(end 46.562772 -232.610406)
		(width 0.14478)
		(layer "In6.Cu")
		(net "M_E_CPU1_SA_DQ<30>")
	)
	(segment
		(start 79.163164 -243.351812)
		(end 79.171546 -243.346986)
		(width 0.0889)
		(layer "In6.Cu")
		(net "M_E_CPU1_SA_DQ<30>")
	)
	(segment
		(start 41.813226 -232.610406)
		(end 42.663364 -231.760268)
		(width 0.14478)
		(layer "In6.Cu")
		(net "M_E_CPU1_SA_DQ<30>")
	)
	(segment
		(start 77.630528 -243.301266)
		(end 78.41107 -243.301266)
		(width 0.0889)
		(layer "In6.Cu")
		(net "M_E_CPU1_SA_DQ<30>")
	)
	(segment
		(start 59.613546 -231.760268)
		(end 61.548518 -233.69524)
		(width 0.14478)
		(layer "In6.Cu")
		(net "M_E_CPU1_SA_DQ<30>")
	)
	(segment
		(start 57.81167 -231.760268)
		(end 59.613546 -231.760268)
		(width 0.14478)
		(layer "In6.Cu")
		(net "M_E_CPU1_SA_DQ<30>")
	)
	(segment
		(start 66.72072 -240.664746)
		(end 68.668138 -242.612164)
		(width 0.14478)
		(layer "In6.Cu")
		(net "M_E_CPU1_SA_DQ<30>")
	)
	(segment
		(start 68.668138 -242.612164)
		(end 75.950826 -242.612164)
		(width 0.14478)
		(layer "In6.Cu")
		(net "M_E_CPU1_SA_DQ<30>")
	)
	(segment
		(start 28.423616 -232.610406)
		(end 34.261552 -232.610406)
		(width 0.14478)
		(layer "In6.Cu")
		(net "M_E_CPU1_SA_DQ<30>")
	)
	(segment
		(start 27.704034 -231.444292)
		(end 27.867102 -231.281224)
		(width 0.14478)
		(layer "In6.Cu")
		(net "M_E_CPU1_SA_DQ<30>")
	)
	(segment
		(start 28.09748 -231.281224)
		(end 28.260548 -231.444292)
		(width 0.14478)
		(layer "In6.Cu")
		(net "M_E_CPU1_SA_DQ<30>")
	)
	(segment
		(start 28.260548 -231.444292)
		(end 28.260548 -232.447338)
		(width 0.14478)
		(layer "In6.Cu")
		(net "M_E_CPU1_SA_DQ<30>")
	)
	(segment
		(start 38.873938 -232.610406)
		(end 41.813226 -232.610406)
		(width 0.14478)
		(layer "In6.Cu")
		(net "M_E_CPU1_SA_DQ<30>")
	)
	(segment
		(start 81.077054 -243.408962)
		(end 81.230978 -243.674392)
		(width 0.0889)
		(layer "In6.Cu")
		(net "M_E_CPU1_SA_DQ<30>")
	)
	(segment
		(start 27.540966 -232.610406)
		(end 27.704034 -232.447338)
		(width 0.14478)
		(layer "In6.Cu")
		(net "M_E_CPU1_SA_DQ<30>")
	)
	(segment
		(start 46.562772 -232.610406)
		(end 49.417732 -232.610406)
		(width 0.14478)
		(layer "In6.Cu")
		(net "M_E_CPU1_SA_DQ<30>")
	)
	(segment
		(start 76.430886 -242.769644)
		(end 77.098906 -242.769644)
		(width 0.0889)
		(layer "In6.Cu")
		(net "M_E_CPU1_SA_DQ<30>")
	)
	(segment
		(start 38.0238 -231.760268)
		(end 38.873938 -232.610406)
		(width 0.14478)
		(layer "In6.Cu")
		(net "M_E_CPU1_SA_DQ<30>")
	)
	(segment
		(start 80.981042 -243.383562)
		(end 81.077054 -243.408962)
		(width 0.0889)
		(layer "In6.Cu")
		(net "M_E_CPU1_SA_DQ<30>")
	)
	(segment
		(start 63.084202 -237.403132)
		(end 66.345816 -240.664746)
		(width 0.14478)
		(layer "In6.Cu")
		(net "M_E_CPU1_SA_DQ<30>")
	)
	(segment
		(start 78.59776 -243.352066)
		(end 78.603348 -243.355368)
		(width 0.0889)
		(layer "In6.Cu")
		(net "M_E_CPU1_SA_DQ<30>")
	)
	(segment
		(start 34.261552 -232.610406)
		(end 35.11169 -231.760268)
		(width 0.14478)
		(layer "In6.Cu")
		(net "M_E_CPU1_SA_DQ<30>")
	)
	(segment
		(start 25.152096 -232.18521)
		(end 25.577292 -232.610406)
		(width 0.14478)
		(layer "In6.Cu")
		(net "M_E_CPU1_SA_DQ<30>")
	)
	(segment
		(start 25.577292 -232.610406)
		(end 27.540966 -232.610406)
		(width 0.14478)
		(layer "In6.Cu")
		(net "M_E_CPU1_SA_DQ<30>")
	)
	(segment
		(start 80.093566 -243.357908)
		(end 80.10398 -243.351812)
		(width 0.0889)
		(layer "In6.Cu")
		(net "M_E_CPU1_SA_DQ<30>")
	)
	(segment
		(start 75.950826 -242.612164)
		(end 76.273406 -242.612164)
		(width 0.0889)
		(layer "In6.Cu")
		(net "M_E_CPU1_SA_DQ<30>")
	)
	(arc
		(start 79.537814 -243.351812)
		(mid 79.814881 -243.428083)
		(end 80.093566 -243.357908)
		(width 0.0889)
		(layer "In6.Cu")
		(net "M_E_CPU1_SA_DQ<30>")
	)
	(arc
		(start 80.10398 -243.351812)
		(mid 80.286231 -243.301462)
		(end 80.46974 -243.346986)
		(width 0.0889)
		(layer "In6.Cu")
		(net "M_E_CPU1_SA_DQ<30>")
	)
	(arc
		(start 78.41107 -243.301266)
		(mid 78.507761 -243.314362)
		(end 78.59776 -243.352066)
		(width 0.0889)
		(layer "In6.Cu")
		(net "M_E_CPU1_SA_DQ<30>")
	)
	(arc
		(start 79.171546 -243.346986)
		(mid 79.355308 -243.30137)
		(end 79.537814 -243.351812)
		(width 0.0889)
		(layer "In6.Cu")
		(net "M_E_CPU1_SA_DQ<30>")
	)
	(arc
		(start 78.603348 -243.355368)
		(mid 78.883737 -243.428037)
		(end 79.163164 -243.351812)
		(width 0.0889)
		(layer "In6.Cu")
		(net "M_E_CPU1_SA_DQ<30>")
	)
	(arc
		(start 80.478122 -243.351812)
		(mid 80.725835 -243.427032)
		(end 80.981042 -243.383562)
		(width 0.0889)
		(layer "In6.Cu")
		(net "M_E_CPU1_SA_DQ<30>")
	)
	(segment
		(start 81.69783 -226.120452)
		(end 81.230978 -225.854514)
		(width 0.10668)
		(layer "F.Cu")
		(net "M_E_CPU1_SA_DQ<2>")
	)
	(segment
		(start 56.925972 -198.610474)
		(end 57.77611 -197.760336)
		(width 0.14478)
		(layer "In6.Cu")
		(net "M_E_CPU1_SA_DQ<2>")
	)
	(segment
		(start 25.577292 -198.610474)
		(end 26.823162 -198.610474)
		(width 0.14478)
		(layer "In6.Cu")
		(net "M_E_CPU1_SA_DQ<2>")
	)
	(segment
		(start 34.253932 -198.610474)
		(end 35.10407 -197.760336)
		(width 0.14478)
		(layer "In6.Cu")
		(net "M_E_CPU1_SA_DQ<2>")
	)
	(segment
		(start 26.98623 -198.447406)
		(end 26.98623 -198.116952)
		(width 0.14478)
		(layer "In6.Cu")
		(net "M_E_CPU1_SA_DQ<2>")
	)
	(segment
		(start 49.382172 -198.610474)
		(end 50.23231 -197.760336)
		(width 0.14478)
		(layer "In6.Cu")
		(net "M_E_CPU1_SA_DQ<2>")
	)
	(segment
		(start 79.538322 -222.29191)
		(end 79.570072 -222.310198)
		(width 0.0889)
		(layer "In6.Cu")
		(net "M_E_CPU1_SA_DQ<2>")
	)
	(segment
		(start 60.847224 -197.760336)
		(end 69.361812 -206.274924)
		(width 0.14478)
		(layer "In6.Cu")
		(net "M_E_CPU1_SA_DQ<2>")
	)
	(segment
		(start 26.98623 -198.116952)
		(end 27.149298 -197.953884)
		(width 0.14478)
		(layer "In6.Cu")
		(net "M_E_CPU1_SA_DQ<2>")
	)
	(segment
		(start 50.23231 -197.760336)
		(end 53.256434 -197.760336)
		(width 0.14478)
		(layer "In6.Cu")
		(net "M_E_CPU1_SA_DQ<2>")
	)
	(segment
		(start 27.705812 -198.610474)
		(end 34.253932 -198.610474)
		(width 0.14478)
		(layer "In6.Cu")
		(net "M_E_CPU1_SA_DQ<2>")
	)
	(segment
		(start 79.9719 -223.080834)
		(end 80.008222 -223.101916)
		(width 0.0889)
		(layer "In6.Cu")
		(net "M_E_CPU1_SA_DQ<2>")
	)
	(segment
		(start 38.0238 -197.760336)
		(end 38.873938 -198.610474)
		(width 0.14478)
		(layer "In6.Cu")
		(net "M_E_CPU1_SA_DQ<2>")
	)
	(segment
		(start 79.049626 -221.437962)
		(end 79.25562 -221.643956)
		(width 0.0889)
		(layer "In6.Cu")
		(net "M_E_CPU1_SA_DQ<2>")
	)
	(segment
		(start 76.601066 -214.536528)
		(end 76.601066 -218.632024)
		(width 0.14478)
		(layer "In6.Cu")
		(net "M_E_CPU1_SA_DQ<2>")
	)
	(segment
		(start 80.008222 -223.101916)
		(end 80.039972 -223.120204)
		(width 0.0889)
		(layer "In6.Cu")
		(net "M_E_CPU1_SA_DQ<2>")
	)
	(segment
		(start 81.077054 -225.589084)
		(end 81.230978 -225.854514)
		(width 0.0889)
		(layer "In6.Cu")
		(net "M_E_CPU1_SA_DQ<2>")
	)
	(segment
		(start 79.497936 -222.268288)
		(end 79.538322 -222.29191)
		(width 0.0889)
		(layer "In6.Cu")
		(net "M_E_CPU1_SA_DQ<2>")
	)
	(segment
		(start 57.77611 -197.760336)
		(end 60.847224 -197.760336)
		(width 0.14478)
		(layer "In6.Cu")
		(net "M_E_CPU1_SA_DQ<2>")
	)
	(segment
		(start 27.149298 -197.953884)
		(end 27.379676 -197.953884)
		(width 0.14478)
		(layer "In6.Cu")
		(net "M_E_CPU1_SA_DQ<2>")
	)
	(segment
		(start 46.562772 -198.610474)
		(end 49.382172 -198.610474)
		(width 0.14478)
		(layer "In6.Cu")
		(net "M_E_CPU1_SA_DQ<2>")
	)
	(segment
		(start 80.478122 -223.911922)
		(end 80.509872 -223.93021)
		(width 0.0889)
		(layer "In6.Cu")
		(net "M_E_CPU1_SA_DQ<2>")
	)
	(segment
		(start 79.25562 -221.643956)
		(end 79.25562 -221.804484)
		(width 0.0889)
		(layer "In6.Cu")
		(net "M_E_CPU1_SA_DQ<2>")
	)
	(segment
		(start 80.981042 -225.563684)
		(end 81.077054 -225.589084)
		(width 0.0889)
		(layer "In6.Cu")
		(net "M_E_CPU1_SA_DQ<2>")
	)
	(segment
		(start 80.4418 -223.89084)
		(end 80.478122 -223.911922)
		(width 0.0889)
		(layer "In6.Cu")
		(net "M_E_CPU1_SA_DQ<2>")
	)
	(segment
		(start 35.10407 -197.760336)
		(end 38.0238 -197.760336)
		(width 0.14478)
		(layer "In6.Cu")
		(net "M_E_CPU1_SA_DQ<2>")
	)
	(segment
		(start 53.256434 -197.760336)
		(end 54.106572 -198.610474)
		(width 0.14478)
		(layer "In6.Cu")
		(net "M_E_CPU1_SA_DQ<2>")
	)
	(segment
		(start 76.601066 -218.632024)
		(end 79.049626 -221.080584)
		(width 0.14478)
		(layer "In6.Cu")
		(net "M_E_CPU1_SA_DQ<2>")
	)
	(segment
		(start 42.698924 -197.760336)
		(end 45.712634 -197.760336)
		(width 0.14478)
		(layer "In6.Cu")
		(net "M_E_CPU1_SA_DQ<2>")
	)
	(segment
		(start 27.542744 -198.116952)
		(end 27.542744 -198.447406)
		(width 0.14478)
		(layer "In6.Cu")
		(net "M_E_CPU1_SA_DQ<2>")
	)
	(segment
		(start 69.361812 -206.274924)
		(end 69.361812 -207.297274)
		(width 0.14478)
		(layer "In6.Cu")
		(net "M_E_CPU1_SA_DQ<2>")
	)
	(segment
		(start 41.848786 -198.610474)
		(end 42.698924 -197.760336)
		(width 0.14478)
		(layer "In6.Cu")
		(net "M_E_CPU1_SA_DQ<2>")
	)
	(segment
		(start 27.379676 -197.953884)
		(end 27.542744 -198.116952)
		(width 0.14478)
		(layer "In6.Cu")
		(net "M_E_CPU1_SA_DQ<2>")
	)
	(segment
		(start 79.049626 -221.080584)
		(end 79.049626 -221.258384)
		(width 0.14478)
		(layer "In6.Cu")
		(net "M_E_CPU1_SA_DQ<2>")
	)
	(segment
		(start 80.509872 -224.538794)
		(end 80.478122 -224.557082)
		(width 0.0889)
		(layer "In6.Cu")
		(net "M_E_CPU1_SA_DQ<2>")
	)
	(segment
		(start 26.823162 -198.610474)
		(end 26.98623 -198.447406)
		(width 0.14478)
		(layer "In6.Cu")
		(net "M_E_CPU1_SA_DQ<2>")
	)
	(segment
		(start 69.361812 -207.297274)
		(end 76.601066 -214.536528)
		(width 0.14478)
		(layer "In6.Cu")
		(net "M_E_CPU1_SA_DQ<2>")
	)
	(segment
		(start 80.478122 -224.557082)
		(end 80.439006 -224.579942)
		(width 0.0889)
		(layer "In6.Cu")
		(net "M_E_CPU1_SA_DQ<2>")
	)
	(segment
		(start 45.712634 -197.760336)
		(end 46.562772 -198.610474)
		(width 0.14478)
		(layer "In6.Cu")
		(net "M_E_CPU1_SA_DQ<2>")
	)
	(segment
		(start 25.152096 -198.185278)
		(end 25.577292 -198.610474)
		(width 0.14478)
		(layer "In6.Cu")
		(net "M_E_CPU1_SA_DQ<2>")
	)
	(segment
		(start 79.049626 -221.258384)
		(end 79.049626 -221.437962)
		(width 0.0889)
		(layer "In6.Cu")
		(net "M_E_CPU1_SA_DQ<2>")
	)
	(segment
		(start 54.106572 -198.610474)
		(end 56.925972 -198.610474)
		(width 0.14478)
		(layer "In6.Cu")
		(net "M_E_CPU1_SA_DQ<2>")
	)
	(segment
		(start 38.873938 -198.610474)
		(end 41.848786 -198.610474)
		(width 0.14478)
		(layer "In6.Cu")
		(net "M_E_CPU1_SA_DQ<2>")
	)
	(segment
		(start 27.542744 -198.447406)
		(end 27.705812 -198.610474)
		(width 0.14478)
		(layer "In6.Cu")
		(net "M_E_CPU1_SA_DQ<2>")
	)
	(segment
		(start 80.439006 -225.509074)
		(end 80.478122 -225.531934)
		(width 0.0889)
		(layer "In6.Cu")
		(net "M_E_CPU1_SA_DQ<2>")
	)
	(arc
		(start 80.509872 -223.93021)
		(mid 80.6658 -224.234502)
		(end 80.509872 -224.538794)
		(width 0.0889)
		(layer "In6.Cu")
		(net "M_E_CPU1_SA_DQ<2>")
	)
	(arc
		(start 79.570072 -222.310198)
		(mid 79.684748 -222.443532)
		(end 79.726028 -222.61449)
		(width 0.0889)
		(layer "In6.Cu")
		(net "M_E_CPU1_SA_DQ<2>")
	)
	(arc
		(start 80.439006 -224.579942)
		(mid 80.195679 -225.044508)
		(end 80.439006 -225.509074)
		(width 0.0889)
		(layer "In6.Cu")
		(net "M_E_CPU1_SA_DQ<2>")
	)
	(arc
		(start 80.039972 -223.120204)
		(mid 80.154648 -223.253538)
		(end 80.195928 -223.424496)
		(width 0.0889)
		(layer "In6.Cu")
		(net "M_E_CPU1_SA_DQ<2>")
	)
	(arc
		(start 79.726028 -222.61449)
		(mid 79.791264 -222.878081)
		(end 79.9719 -223.080834)
		(width 0.0889)
		(layer "In6.Cu")
		(net "M_E_CPU1_SA_DQ<2>")
	)
	(arc
		(start 80.478122 -225.531934)
		(mid 80.725835 -225.607154)
		(end 80.981042 -225.563684)
		(width 0.0889)
		(layer "In6.Cu")
		(net "M_E_CPU1_SA_DQ<2>")
	)
	(arc
		(start 79.25562 -221.804484)
		(mid 79.319913 -222.066089)
		(end 79.497936 -222.268288)
		(width 0.0889)
		(layer "In6.Cu")
		(net "M_E_CPU1_SA_DQ<2>")
	)
	(arc
		(start 80.195928 -223.424496)
		(mid 80.261164 -223.688087)
		(end 80.4418 -223.89084)
		(width 0.0889)
		(layer "In6.Cu")
		(net "M_E_CPU1_SA_DQ<2>")
	)
	(segment
		(start 82.637884 -243.94033)
		(end 82.171032 -243.674392)
		(width 0.10668)
		(layer "F.Cu")
		(net "M_E_CPU1_SA_DQ<29>")
	)
	(segment
		(start 49.295304 -233.46029)
		(end 49.62271 -233.46029)
		(width 0.14478)
		(layer "In6.Cu")
		(net "M_E_CPU1_SA_DQ<29>")
	)
	(segment
		(start 45.69079 -232.610406)
		(end 46.540674 -233.46029)
		(width 0.14478)
		(layer "In6.Cu")
		(net "M_E_CPU1_SA_DQ<29>")
	)
	(segment
		(start 31.987744 -233.688636)
		(end 31.987744 -233.623358)
		(width 0.14478)
		(layer "In6.Cu")
		(net "M_E_CPU1_SA_DQ<29>")
	)
	(segment
		(start 67.52209 -242.10264)
		(end 67.52209 -242.480084)
		(width 0.14478)
		(layer "In6.Cu")
		(net "M_E_CPU1_SA_DQ<29>")
	)
	(segment
		(start 30.711648 -233.851704)
		(end 30.874716 -233.688636)
		(width 0.14478)
		(layer "In6.Cu")
		(net "M_E_CPU1_SA_DQ<29>")
	)
	(segment
		(start 41.96969 -233.46029)
		(end 42.51833 -232.91165)
		(width 0.14478)
		(layer "In6.Cu")
		(net "M_E_CPU1_SA_DQ<29>")
	)
	(segment
		(start 49.132236 -233.623358)
		(end 49.295304 -233.46029)
		(width 0.14478)
		(layer "In6.Cu")
		(net "M_E_CPU1_SA_DQ<29>")
	)
	(segment
		(start 56.31307 -233.854244)
		(end 56.476138 -233.691176)
		(width 0.14478)
		(layer "In6.Cu")
		(net "M_E_CPU1_SA_DQ<29>")
	)
	(segment
		(start 76.187046 -243.066824)
		(end 76.616306 -243.496084)
		(width 0.0889)
		(layer "In6.Cu")
		(net "M_E_CPU1_SA_DQ<29>")
	)
	(segment
		(start 62.677294 -237.635288)
		(end 66.158364 -241.116358)
		(width 0.14478)
		(layer "In6.Cu")
		(net "M_E_CPU1_SA_DQ<29>")
	)
	(segment
		(start 41.531286 -233.678476)
		(end 41.531286 -233.623358)
		(width 0.14478)
		(layer "In6.Cu")
		(net "M_E_CPU1_SA_DQ<29>")
	)
	(segment
		(start 54.806596 -233.691176)
		(end 54.969664 -233.854244)
		(width 0.14478)
		(layer "In6.Cu")
		(net "M_E_CPU1_SA_DQ<29>")
	)
	(segment
		(start 55.756556 -233.46029)
		(end 55.919624 -233.623358)
		(width 0.14478)
		(layer "In6.Cu")
		(net "M_E_CPU1_SA_DQ<29>")
	)
	(segment
		(start 42.8498 -232.209848)
		(end 43.45559 -232.209848)
		(width 0.14478)
		(layer "In6.Cu")
		(net "M_E_CPU1_SA_DQ<29>")
	)
	(segment
		(start 30.48127 -233.851704)
		(end 30.711648 -233.851704)
		(width 0.14478)
		(layer "In6.Cu")
		(net "M_E_CPU1_SA_DQ<29>")
	)
	(segment
		(start 79.52994 -244.001798)
		(end 79.538322 -243.996972)
		(width 0.0889)
		(layer "In6.Cu")
		(net "M_E_CPU1_SA_DQ<29>")
	)
	(segment
		(start 46.540674 -233.46029)
		(end 48.412654 -233.46029)
		(width 0.14478)
		(layer "In6.Cu")
		(net "M_E_CPU1_SA_DQ<29>")
	)
	(segment
		(start 56.639206 -233.46029)
		(end 56.931306 -233.46029)
		(width 0.14478)
		(layer "In6.Cu")
		(net "M_E_CPU1_SA_DQ<29>")
	)
	(segment
		(start 42.51833 -232.541318)
		(end 42.8498 -232.209848)
		(width 0.14478)
		(layer "In6.Cu")
		(net "M_E_CPU1_SA_DQ<29>")
	)
	(segment
		(start 58.00471 -232.386886)
		(end 58.54065 -232.386886)
		(width 0.14478)
		(layer "In6.Cu")
		(net "M_E_CPU1_SA_DQ<29>")
	)
	(segment
		(start 42.51833 -232.91165)
		(end 42.51833 -232.541318)
		(width 0.14478)
		(layer "In6.Cu")
		(net "M_E_CPU1_SA_DQ<29>")
	)
	(segment
		(start 60.205366 -232.988104)
		(end 61.13907 -233.921808)
		(width 0.14478)
		(layer "In6.Cu")
		(net "M_E_CPU1_SA_DQ<29>")
	)
	(segment
		(start 29.252164 -233.035348)
		(end 29.677106 -233.46029)
		(width 0.14478)
		(layer "In6.Cu")
		(net "M_E_CPU1_SA_DQ<29>")
	)
	(segment
		(start 54.806596 -233.623358)
		(end 54.806596 -233.691176)
		(width 0.14478)
		(layer "In6.Cu")
		(net "M_E_CPU1_SA_DQ<29>")
	)
	(segment
		(start 55.36311 -233.623358)
		(end 55.526178 -233.46029)
		(width 0.14478)
		(layer "In6.Cu")
		(net "M_E_CPU1_SA_DQ<29>")
	)
	(segment
		(start 31.268162 -233.068876)
		(end 31.43123 -233.231944)
		(width 0.14478)
		(layer "In6.Cu")
		(net "M_E_CPU1_SA_DQ<29>")
	)
	(segment
		(start 61.13907 -233.921808)
		(end 62.677294 -237.635288)
		(width 0.14478)
		(layer "In6.Cu")
		(net "M_E_CPU1_SA_DQ<29>")
	)
	(segment
		(start 66.535808 -241.116358)
		(end 66.738754 -241.319304)
		(width 0.14478)
		(layer "In6.Cu")
		(net "M_E_CPU1_SA_DQ<29>")
	)
	(segment
		(start 67.319144 -241.899694)
		(end 67.52209 -242.10264)
		(width 0.14478)
		(layer "In6.Cu")
		(net "M_E_CPU1_SA_DQ<29>")
	)
	(segment
		(start 40.974772 -233.678476)
		(end 41.13784 -233.841544)
		(width 0.14478)
		(layer "In6.Cu")
		(net "M_E_CPU1_SA_DQ<29>")
	)
	(segment
		(start 30.318202 -233.688636)
		(end 30.48127 -233.851704)
		(width 0.14478)
		(layer "In6.Cu")
		(net "M_E_CPU1_SA_DQ<29>")
	)
	(segment
		(start 30.874716 -233.688636)
		(end 30.874716 -233.231944)
		(width 0.14478)
		(layer "In6.Cu")
		(net "M_E_CPU1_SA_DQ<29>")
	)
	(segment
		(start 43.856148 -232.610406)
		(end 45.69079 -232.610406)
		(width 0.14478)
		(layer "In6.Cu")
		(net "M_E_CPU1_SA_DQ<29>")
	)
	(segment
		(start 54.084474 -233.46029)
		(end 54.643528 -233.46029)
		(width 0.14478)
		(layer "In6.Cu")
		(net "M_E_CPU1_SA_DQ<29>")
	)
	(segment
		(start 50.472594 -232.610406)
		(end 53.23459 -232.610406)
		(width 0.14478)
		(layer "In6.Cu")
		(net "M_E_CPU1_SA_DQ<29>")
	)
	(segment
		(start 48.969168 -233.849164)
		(end 49.132236 -233.686096)
		(width 0.14478)
		(layer "In6.Cu")
		(net "M_E_CPU1_SA_DQ<29>")
	)
	(segment
		(start 54.643528 -233.46029)
		(end 54.806596 -233.623358)
		(width 0.14478)
		(layer "In6.Cu")
		(net "M_E_CPU1_SA_DQ<29>")
	)
	(segment
		(start 48.73879 -233.849164)
		(end 48.969168 -233.849164)
		(width 0.14478)
		(layer "In6.Cu")
		(net "M_E_CPU1_SA_DQ<29>")
	)
	(segment
		(start 41.13784 -233.841544)
		(end 41.368218 -233.841544)
		(width 0.14478)
		(layer "In6.Cu")
		(net "M_E_CPU1_SA_DQ<29>")
	)
	(segment
		(start 48.575722 -233.623358)
		(end 48.575722 -233.686096)
		(width 0.14478)
		(layer "In6.Cu")
		(net "M_E_CPU1_SA_DQ<29>")
	)
	(segment
		(start 31.987744 -233.623358)
		(end 32.150812 -233.46029)
		(width 0.14478)
		(layer "In6.Cu")
		(net "M_E_CPU1_SA_DQ<29>")
	)
	(segment
		(start 41.368218 -233.841544)
		(end 41.531286 -233.678476)
		(width 0.14478)
		(layer "In6.Cu")
		(net "M_E_CPU1_SA_DQ<29>")
	)
	(segment
		(start 31.43123 -233.688636)
		(end 31.594298 -233.851704)
		(width 0.14478)
		(layer "In6.Cu")
		(net "M_E_CPU1_SA_DQ<29>")
	)
	(segment
		(start 43.45559 -232.209848)
		(end 43.856148 -232.610406)
		(width 0.14478)
		(layer "In6.Cu")
		(net "M_E_CPU1_SA_DQ<29>")
	)
	(segment
		(start 32.150812 -233.46029)
		(end 34.46653 -233.46029)
		(width 0.14478)
		(layer "In6.Cu")
		(net "M_E_CPU1_SA_DQ<29>")
	)
	(segment
		(start 66.158364 -241.116358)
		(end 66.535808 -241.116358)
		(width 0.14478)
		(layer "In6.Cu")
		(net "M_E_CPU1_SA_DQ<29>")
	)
	(segment
		(start 30.155134 -233.46029)
		(end 30.318202 -233.623358)
		(width 0.14478)
		(layer "In6.Cu")
		(net "M_E_CPU1_SA_DQ<29>")
	)
	(segment
		(start 56.476138 -233.623358)
		(end 56.639206 -233.46029)
		(width 0.14478)
		(layer "In6.Cu")
		(net "M_E_CPU1_SA_DQ<29>")
	)
	(segment
		(start 30.318202 -233.623358)
		(end 30.318202 -233.688636)
		(width 0.14478)
		(layer "In6.Cu")
		(net "M_E_CPU1_SA_DQ<29>")
	)
	(segment
		(start 55.919624 -233.691176)
		(end 56.082692 -233.854244)
		(width 0.14478)
		(layer "In6.Cu")
		(net "M_E_CPU1_SA_DQ<29>")
	)
	(segment
		(start 56.476138 -233.691176)
		(end 56.476138 -233.623358)
		(width 0.14478)
		(layer "In6.Cu")
		(net "M_E_CPU1_SA_DQ<29>")
	)
	(segment
		(start 55.919624 -233.623358)
		(end 55.919624 -233.691176)
		(width 0.14478)
		(layer "In6.Cu")
		(net "M_E_CPU1_SA_DQ<29>")
	)
	(segment
		(start 66.738754 -241.319304)
		(end 66.738754 -241.696748)
		(width 0.14478)
		(layer "In6.Cu")
		(net "M_E_CPU1_SA_DQ<29>")
	)
	(segment
		(start 59.141868 -232.988104)
		(end 60.205366 -232.988104)
		(width 0.14478)
		(layer "In6.Cu")
		(net "M_E_CPU1_SA_DQ<29>")
	)
	(segment
		(start 38.01491 -232.610406)
		(end 38.864794 -233.46029)
		(width 0.14478)
		(layer "In6.Cu")
		(net "M_E_CPU1_SA_DQ<29>")
	)
	(segment
		(start 29.677106 -233.46029)
		(end 30.155134 -233.46029)
		(width 0.14478)
		(layer "In6.Cu")
		(net "M_E_CPU1_SA_DQ<29>")
	)
	(segment
		(start 31.594298 -233.851704)
		(end 31.824676 -233.851704)
		(width 0.14478)
		(layer "In6.Cu")
		(net "M_E_CPU1_SA_DQ<29>")
	)
	(segment
		(start 56.082692 -233.854244)
		(end 56.31307 -233.854244)
		(width 0.14478)
		(layer "In6.Cu")
		(net "M_E_CPU1_SA_DQ<29>")
	)
	(segment
		(start 41.694354 -233.46029)
		(end 41.96969 -233.46029)
		(width 0.14478)
		(layer "In6.Cu")
		(net "M_E_CPU1_SA_DQ<29>")
	)
	(segment
		(start 54.969664 -233.854244)
		(end 55.200042 -233.854244)
		(width 0.14478)
		(layer "In6.Cu")
		(net "M_E_CPU1_SA_DQ<29>")
	)
	(segment
		(start 80.46974 -244.001798)
		(end 80.478122 -243.996972)
		(width 0.0889)
		(layer "In6.Cu")
		(net "M_E_CPU1_SA_DQ<29>")
	)
	(segment
		(start 49.62271 -233.46029)
		(end 50.472594 -232.610406)
		(width 0.14478)
		(layer "In6.Cu")
		(net "M_E_CPU1_SA_DQ<29>")
	)
	(segment
		(start 53.23459 -232.610406)
		(end 54.084474 -233.46029)
		(width 0.14478)
		(layer "In6.Cu")
		(net "M_E_CPU1_SA_DQ<29>")
	)
	(segment
		(start 40.974772 -233.623358)
		(end 40.974772 -233.678476)
		(width 0.14478)
		(layer "In6.Cu")
		(net "M_E_CPU1_SA_DQ<29>")
	)
	(segment
		(start 76.616306 -243.496084)
		(end 77.353668 -243.496084)
		(width 0.0889)
		(layer "In6.Cu")
		(net "M_E_CPU1_SA_DQ<29>")
	)
	(segment
		(start 31.824676 -233.851704)
		(end 31.987744 -233.688636)
		(width 0.14478)
		(layer "In6.Cu")
		(net "M_E_CPU1_SA_DQ<29>")
	)
	(segment
		(start 58.54065 -232.386886)
		(end 59.141868 -232.988104)
		(width 0.14478)
		(layer "In6.Cu")
		(net "M_E_CPU1_SA_DQ<29>")
	)
	(segment
		(start 38.864794 -233.46029)
		(end 40.811704 -233.46029)
		(width 0.14478)
		(layer "In6.Cu")
		(net "M_E_CPU1_SA_DQ<29>")
	)
	(segment
		(start 31.037784 -233.068876)
		(end 31.268162 -233.068876)
		(width 0.14478)
		(layer "In6.Cu")
		(net "M_E_CPU1_SA_DQ<29>")
	)
	(segment
		(start 67.52209 -242.480084)
		(end 68.10883 -243.066824)
		(width 0.14478)
		(layer "In6.Cu")
		(net "M_E_CPU1_SA_DQ<29>")
	)
	(segment
		(start 55.36311 -233.691176)
		(end 55.36311 -233.623358)
		(width 0.14478)
		(layer "In6.Cu")
		(net "M_E_CPU1_SA_DQ<29>")
	)
	(segment
		(start 66.738754 -241.696748)
		(end 66.9417 -241.899694)
		(width 0.14478)
		(layer "In6.Cu")
		(net "M_E_CPU1_SA_DQ<29>")
	)
	(segment
		(start 48.575722 -233.686096)
		(end 48.73879 -233.849164)
		(width 0.14478)
		(layer "In6.Cu")
		(net "M_E_CPU1_SA_DQ<29>")
	)
	(segment
		(start 79.154274 -243.990876)
		(end 79.164688 -243.996972)
		(width 0.0889)
		(layer "In6.Cu")
		(net "M_E_CPU1_SA_DQ<29>")
	)
	(segment
		(start 68.10883 -243.066824)
		(end 75.953366 -243.066824)
		(width 0.14478)
		(layer "In6.Cu")
		(net "M_E_CPU1_SA_DQ<29>")
	)
	(segment
		(start 40.811704 -233.46029)
		(end 40.974772 -233.623358)
		(width 0.14478)
		(layer "In6.Cu")
		(net "M_E_CPU1_SA_DQ<29>")
	)
	(segment
		(start 34.46653 -233.46029)
		(end 35.316414 -232.610406)
		(width 0.14478)
		(layer "In6.Cu")
		(net "M_E_CPU1_SA_DQ<29>")
	)
	(segment
		(start 41.531286 -233.623358)
		(end 41.694354 -233.46029)
		(width 0.14478)
		(layer "In6.Cu")
		(net "M_E_CPU1_SA_DQ<29>")
	)
	(segment
		(start 30.874716 -233.231944)
		(end 31.037784 -233.068876)
		(width 0.14478)
		(layer "In6.Cu")
		(net "M_E_CPU1_SA_DQ<29>")
	)
	(segment
		(start 55.200042 -233.854244)
		(end 55.36311 -233.691176)
		(width 0.14478)
		(layer "In6.Cu")
		(net "M_E_CPU1_SA_DQ<29>")
	)
	(segment
		(start 35.316414 -232.610406)
		(end 38.01491 -232.610406)
		(width 0.14478)
		(layer "In6.Cu")
		(net "M_E_CPU1_SA_DQ<29>")
	)
	(segment
		(start 77.353668 -243.496084)
		(end 77.905102 -244.047518)
		(width 0.0889)
		(layer "In6.Cu")
		(net "M_E_CPU1_SA_DQ<29>")
	)
	(segment
		(start 77.905102 -244.047518)
		(end 78.41107 -244.047518)
		(width 0.0889)
		(layer "In6.Cu")
		(net "M_E_CPU1_SA_DQ<29>")
	)
	(segment
		(start 82.324956 -243.939822)
		(end 82.171032 -243.674392)
		(width 0.0889)
		(layer "In6.Cu")
		(net "M_E_CPU1_SA_DQ<29>")
	)
	(segment
		(start 31.43123 -233.231944)
		(end 31.43123 -233.688636)
		(width 0.14478)
		(layer "In6.Cu")
		(net "M_E_CPU1_SA_DQ<29>")
	)
	(segment
		(start 49.132236 -233.686096)
		(end 49.132236 -233.623358)
		(width 0.14478)
		(layer "In6.Cu")
		(net "M_E_CPU1_SA_DQ<29>")
	)
	(segment
		(start 81.044034 -243.996972)
		(end 81.052416 -244.001798)
		(width 0.0889)
		(layer "In6.Cu")
		(net "M_E_CPU1_SA_DQ<29>")
	)
	(segment
		(start 55.526178 -233.46029)
		(end 55.756556 -233.46029)
		(width 0.14478)
		(layer "In6.Cu")
		(net "M_E_CPU1_SA_DQ<29>")
	)
	(segment
		(start 82.302604 -244.023134)
		(end 82.324956 -243.939822)
		(width 0.0889)
		(layer "In6.Cu")
		(net "M_E_CPU1_SA_DQ<29>")
	)
	(segment
		(start 66.9417 -241.899694)
		(end 67.319144 -241.899694)
		(width 0.14478)
		(layer "In6.Cu")
		(net "M_E_CPU1_SA_DQ<29>")
	)
	(segment
		(start 48.412654 -233.46029)
		(end 48.575722 -233.623358)
		(width 0.14478)
		(layer "In6.Cu")
		(net "M_E_CPU1_SA_DQ<29>")
	)
	(segment
		(start 56.931306 -233.46029)
		(end 58.00471 -232.386886)
		(width 0.14478)
		(layer "In6.Cu")
		(net "M_E_CPU1_SA_DQ<29>")
	)
	(segment
		(start 75.953366 -243.066824)
		(end 76.187046 -243.066824)
		(width 0.0889)
		(layer "In6.Cu")
		(net "M_E_CPU1_SA_DQ<29>")
	)
	(segment
		(start 79.538322 -243.996972)
		(end 79.548736 -243.990876)
		(width 0.0889)
		(layer "In6.Cu")
		(net "M_E_CPU1_SA_DQ<29>")
	)
	(arc
		(start 80.10398 -243.996972)
		(mid 80.286231 -244.047322)
		(end 80.46974 -244.001798)
		(width 0.0889)
		(layer "In6.Cu")
		(net "M_E_CPU1_SA_DQ<29>")
	)
	(arc
		(start 81.052416 -244.001798)
		(mid 81.235924 -244.047292)
		(end 81.418176 -243.996972)
		(width 0.0889)
		(layer "In6.Cu")
		(net "M_E_CPU1_SA_DQ<29>")
	)
	(arc
		(start 80.478122 -243.996972)
		(mid 80.761078 -243.920795)
		(end 81.044034 -243.996972)
		(width 0.0889)
		(layer "In6.Cu")
		(net "M_E_CPU1_SA_DQ<29>")
	)
	(arc
		(start 81.984088 -243.996972)
		(mid 82.140407 -244.045967)
		(end 82.302604 -244.023134)
		(width 0.0889)
		(layer "In6.Cu")
		(net "M_E_CPU1_SA_DQ<29>")
	)
	(arc
		(start 78.41107 -244.047518)
		(mid 78.508148 -244.034668)
		(end 78.598522 -243.996972)
		(width 0.0889)
		(layer "In6.Cu")
		(net "M_E_CPU1_SA_DQ<29>")
	)
	(arc
		(start 81.418176 -243.996972)
		(mid 81.701132 -243.920795)
		(end 81.984088 -243.996972)
		(width 0.0889)
		(layer "In6.Cu")
		(net "M_E_CPU1_SA_DQ<29>")
	)
	(arc
		(start 79.164688 -243.996972)
		(mid 79.346685 -244.047194)
		(end 79.52994 -244.001798)
		(width 0.0889)
		(layer "In6.Cu")
		(net "M_E_CPU1_SA_DQ<29>")
	)
	(arc
		(start 79.548736 -243.990876)
		(mid 79.827168 -243.920778)
		(end 80.10398 -243.996972)
		(width 0.0889)
		(layer "In6.Cu")
		(net "M_E_CPU1_SA_DQ<29>")
	)
	(arc
		(start 78.598522 -243.996972)
		(mid 78.875589 -243.920701)
		(end 79.154274 -243.990876)
		(width 0.0889)
		(layer "In6.Cu")
		(net "M_E_CPU1_SA_DQ<29>")
	)
	(segment
		(start 81.22793 -243.130324)
		(end 80.761078 -242.864386)
		(width 0.10668)
		(layer "F.Cu")
		(net "M_E_CPU1_SA_DQ<28>")
	)
	(segment
		(start 66.402204 -239.385094)
		(end 66.402204 -239.589818)
		(width 0.14478)
		(layer "In6.Cu")
		(net "M_E_CPU1_SA_DQ<28>")
	)
	(segment
		(start 55.616602 -231.989376)
		(end 55.77967 -232.152444)
		(width 0.14478)
		(layer "In6.Cu")
		(net "M_E_CPU1_SA_DQ<28>")
	)
	(segment
		(start 79.99984 -243.191792)
		(end 80.008222 -243.186966)
		(width 0.0889)
		(layer "In6.Cu")
		(net "M_E_CPU1_SA_DQ<28>")
	)
	(segment
		(start 65.081912 -238.560102)
		(end 65.2272 -238.414814)
		(width 0.14478)
		(layer "In6.Cu")
		(net "M_E_CPU1_SA_DQ<28>")
	)
	(segment
		(start 64.298576 -237.776766)
		(end 64.443864 -237.631478)
		(width 0.14478)
		(layer "In6.Cu")
		(net "M_E_CPU1_SA_DQ<28>")
	)
	(segment
		(start 78.693518 -243.186712)
		(end 78.709774 -243.19611)
		(width 0.0889)
		(layer "In6.Cu")
		(net "M_E_CPU1_SA_DQ<28>")
	)
	(segment
		(start 66.914268 -240.215166)
		(end 67.295522 -240.59642)
		(width 0.14478)
		(layer "In6.Cu")
		(net "M_E_CPU1_SA_DQ<28>")
	)
	(segment
		(start 32.157924 -231.76992)
		(end 33.21431 -231.76992)
		(width 0.14478)
		(layer "In6.Cu")
		(net "M_E_CPU1_SA_DQ<28>")
	)
	(segment
		(start 67.846194 -241.146838)
		(end 68.078858 -241.379502)
		(width 0.14478)
		(layer "In6.Cu")
		(net "M_E_CPU1_SA_DQ<28>")
	)
	(segment
		(start 29.910532 -231.760268)
		(end 30.0736 -231.5972)
		(width 0.14478)
		(layer "In6.Cu")
		(net "M_E_CPU1_SA_DQ<28>")
	)
	(segment
		(start 34.087308 -231.760268)
		(end 34.46653 -231.760268)
		(width 0.14478)
		(layer "In6.Cu")
		(net "M_E_CPU1_SA_DQ<28>")
	)
	(segment
		(start 41.96969 -231.760268)
		(end 42.809922 -230.920036)
		(width 0.14478)
		(layer "In6.Cu")
		(net "M_E_CPU1_SA_DQ<28>")
	)
	(segment
		(start 80.915002 -243.129816)
		(end 80.761078 -242.864386)
		(width 0.0889)
		(layer "In6.Cu")
		(net "M_E_CPU1_SA_DQ<28>")
	)
	(segment
		(start 68.396866 -241.38001)
		(end 68.62953 -241.612674)
		(width 0.14478)
		(layer "In6.Cu")
		(net "M_E_CPU1_SA_DQ<28>")
	)
	(segment
		(start 30.0736 -231.154732)
		(end 30.236668 -230.991664)
		(width 0.14478)
		(layer "In6.Cu")
		(net "M_E_CPU1_SA_DQ<28>")
	)
	(segment
		(start 54.89702 -232.152444)
		(end 55.060088 -231.989376)
		(width 0.14478)
		(layer "In6.Cu")
		(net "M_E_CPU1_SA_DQ<28>")
	)
	(segment
		(start 67.613276 -240.59642)
		(end 67.846194 -240.829338)
		(width 0.14478)
		(layer "In6.Cu")
		(net "M_E_CPU1_SA_DQ<28>")
	)
	(segment
		(start 65.2272 -238.414814)
		(end 65.431924 -238.414814)
		(width 0.14478)
		(layer "In6.Cu")
		(net "M_E_CPU1_SA_DQ<28>")
	)
	(segment
		(start 56.336184 -231.760268)
		(end 57.16651 -231.760268)
		(width 0.14478)
		(layer "In6.Cu")
		(net "M_E_CPU1_SA_DQ<28>")
	)
	(segment
		(start 64.648588 -237.631478)
		(end 64.835532 -237.818422)
		(width 0.14478)
		(layer "In6.Cu")
		(net "M_E_CPU1_SA_DQ<28>")
	)
	(segment
		(start 63.469012 -237.151926)
		(end 64.093852 -237.776766)
		(width 0.14478)
		(layer "In6.Cu")
		(net "M_E_CPU1_SA_DQ<28>")
	)
	(segment
		(start 76.199746 -242.157504)
		(end 76.547472 -242.50523)
		(width 0.0889)
		(layer "In6.Cu")
		(net "M_E_CPU1_SA_DQ<28>")
	)
	(segment
		(start 65.865248 -239.343438)
		(end 66.010536 -239.19815)
		(width 0.14478)
		(layer "In6.Cu")
		(net "M_E_CPU1_SA_DQ<28>")
	)
	(segment
		(start 31.284926 -231.760268)
		(end 31.447994 -231.923336)
		(width 0.14478)
		(layer "In6.Cu")
		(net "M_E_CPU1_SA_DQ<28>")
	)
	(segment
		(start 61.93282 -233.443526)
		(end 63.469012 -237.151926)
		(width 0.14478)
		(layer "In6.Cu")
		(net "M_E_CPU1_SA_DQ<28>")
	)
	(segment
		(start 41.62044 -231.976676)
		(end 41.62044 -231.923336)
		(width 0.14478)
		(layer "In6.Cu")
		(net "M_E_CPU1_SA_DQ<28>")
	)
	(segment
		(start 55.77967 -232.152444)
		(end 56.010048 -232.152444)
		(width 0.14478)
		(layer "In6.Cu")
		(net "M_E_CPU1_SA_DQ<28>")
	)
	(segment
		(start 65.431924 -238.414814)
		(end 65.618868 -238.601758)
		(width 0.14478)
		(layer "In6.Cu")
		(net "M_E_CPU1_SA_DQ<28>")
	)
	(segment
		(start 46.43755 -231.76992)
		(end 49.613058 -231.76992)
		(width 0.14478)
		(layer "In6.Cu")
		(net "M_E_CPU1_SA_DQ<28>")
	)
	(segment
		(start 80.89265 -243.213128)
		(end 80.915002 -243.129816)
		(width 0.0889)
		(layer "In6.Cu")
		(net "M_E_CPU1_SA_DQ<28>")
	)
	(segment
		(start 54.340506 -231.760268)
		(end 54.503574 -231.923336)
		(width 0.14478)
		(layer "In6.Cu")
		(net "M_E_CPU1_SA_DQ<28>")
	)
	(segment
		(start 64.690244 -238.168434)
		(end 64.690244 -238.373158)
		(width 0.14478)
		(layer "In6.Cu")
		(net "M_E_CPU1_SA_DQ<28>")
	)
	(segment
		(start 68.078858 -241.379502)
		(end 68.396866 -241.38001)
		(width 0.14478)
		(layer "In6.Cu")
		(net "M_E_CPU1_SA_DQ<28>")
	)
	(segment
		(start 54.666642 -232.152444)
		(end 54.89702 -232.152444)
		(width 0.14478)
		(layer "In6.Cu")
		(net "M_E_CPU1_SA_DQ<28>")
	)
	(segment
		(start 56.173116 -231.923336)
		(end 56.336184 -231.760268)
		(width 0.14478)
		(layer "In6.Cu")
		(net "M_E_CPU1_SA_DQ<28>")
	)
	(segment
		(start 66.532252 -240.215166)
		(end 66.914268 -240.215166)
		(width 0.14478)
		(layer "In6.Cu")
		(net "M_E_CPU1_SA_DQ<28>")
	)
	(segment
		(start 55.616602 -231.634792)
		(end 55.616602 -231.989376)
		(width 0.14478)
		(layer "In6.Cu")
		(net "M_E_CPU1_SA_DQ<28>")
	)
	(segment
		(start 53.090826 -230.920036)
		(end 53.931058 -231.760268)
		(width 0.14478)
		(layer "In6.Cu")
		(net "M_E_CPU1_SA_DQ<28>")
	)
	(segment
		(start 57.706514 -231.220264)
		(end 59.709558 -231.220264)
		(width 0.14478)
		(layer "In6.Cu")
		(net "M_E_CPU1_SA_DQ<28>")
	)
	(segment
		(start 68.62953 -241.612674)
		(end 68.629276 -241.930174)
		(width 0.14478)
		(layer "In6.Cu")
		(net "M_E_CPU1_SA_DQ<28>")
	)
	(segment
		(start 33.530794 -232.139744)
		(end 33.761172 -232.139744)
		(width 0.14478)
		(layer "In6.Cu")
		(net "M_E_CPU1_SA_DQ<28>")
	)
	(segment
		(start 45.587666 -230.920036)
		(end 46.43755 -231.76992)
		(width 0.14478)
		(layer "In6.Cu")
		(net "M_E_CPU1_SA_DQ<28>")
	)
	(segment
		(start 68.629276 -241.930174)
		(end 68.856606 -242.157504)
		(width 0.14478)
		(layer "In6.Cu")
		(net "M_E_CPU1_SA_DQ<28>")
	)
	(segment
		(start 30.630114 -231.154732)
		(end 30.630114 -231.5972)
		(width 0.14478)
		(layer "In6.Cu")
		(net "M_E_CPU1_SA_DQ<28>")
	)
	(segment
		(start 68.856606 -242.157504)
		(end 75.920346 -242.157504)
		(width 0.14478)
		(layer "In6.Cu")
		(net "M_E_CPU1_SA_DQ<28>")
	)
	(segment
		(start 65.660524 -239.343438)
		(end 65.865248 -239.343438)
		(width 0.14478)
		(layer "In6.Cu")
		(net "M_E_CPU1_SA_DQ<28>")
	)
	(segment
		(start 55.453534 -231.471724)
		(end 55.616602 -231.634792)
		(width 0.14478)
		(layer "In6.Cu")
		(net "M_E_CPU1_SA_DQ<28>")
	)
	(segment
		(start 33.92424 -231.923336)
		(end 34.087308 -231.760268)
		(width 0.14478)
		(layer "In6.Cu")
		(net "M_E_CPU1_SA_DQ<28>")
	)
	(segment
		(start 65.618868 -238.806482)
		(end 65.47358 -238.95177)
		(width 0.14478)
		(layer "In6.Cu")
		(net "M_E_CPU1_SA_DQ<28>")
	)
	(segment
		(start 56.173116 -231.989376)
		(end 56.173116 -231.923336)
		(width 0.14478)
		(layer "In6.Cu")
		(net "M_E_CPU1_SA_DQ<28>")
	)
	(segment
		(start 41.226994 -232.139744)
		(end 41.457372 -232.139744)
		(width 0.14478)
		(layer "In6.Cu")
		(net "M_E_CPU1_SA_DQ<28>")
	)
	(segment
		(start 65.47358 -238.95177)
		(end 65.47358 -239.156494)
		(width 0.14478)
		(layer "In6.Cu")
		(net "M_E_CPU1_SA_DQ<28>")
	)
	(segment
		(start 53.931058 -231.760268)
		(end 54.340506 -231.760268)
		(width 0.14478)
		(layer "In6.Cu")
		(net "M_E_CPU1_SA_DQ<28>")
	)
	(segment
		(start 40.91051 -231.76992)
		(end 41.063926 -231.923336)
		(width 0.14478)
		(layer "In6.Cu")
		(net "M_E_CPU1_SA_DQ<28>")
	)
	(segment
		(start 49.613058 -231.76992)
		(end 50.462942 -230.920036)
		(width 0.14478)
		(layer "In6.Cu")
		(net "M_E_CPU1_SA_DQ<28>")
	)
	(segment
		(start 35.306762 -230.920036)
		(end 38.024562 -230.920036)
		(width 0.14478)
		(layer "In6.Cu")
		(net "M_E_CPU1_SA_DQ<28>")
	)
	(segment
		(start 31.84144 -232.144824)
		(end 32.004508 -231.981756)
		(width 0.14478)
		(layer "In6.Cu")
		(net "M_E_CPU1_SA_DQ<28>")
	)
	(segment
		(start 66.256916 -239.93983)
		(end 66.532252 -240.215166)
		(width 0.14478)
		(layer "In6.Cu")
		(net "M_E_CPU1_SA_DQ<28>")
	)
	(segment
		(start 65.47358 -239.156494)
		(end 65.660524 -239.343438)
		(width 0.14478)
		(layer "In6.Cu")
		(net "M_E_CPU1_SA_DQ<28>")
	)
	(segment
		(start 38.874446 -231.76992)
		(end 40.91051 -231.76992)
		(width 0.14478)
		(layer "In6.Cu")
		(net "M_E_CPU1_SA_DQ<28>")
	)
	(segment
		(start 56.010048 -232.152444)
		(end 56.173116 -231.989376)
		(width 0.14478)
		(layer "In6.Cu")
		(net "M_E_CPU1_SA_DQ<28>")
	)
	(segment
		(start 66.010536 -239.19815)
		(end 66.21526 -239.19815)
		(width 0.14478)
		(layer "In6.Cu")
		(net "M_E_CPU1_SA_DQ<28>")
	)
	(segment
		(start 77.12202 -242.50523)
		(end 77.727556 -243.110766)
		(width 0.0889)
		(layer "In6.Cu")
		(net "M_E_CPU1_SA_DQ<28>")
	)
	(segment
		(start 42.809922 -230.920036)
		(end 45.587666 -230.920036)
		(width 0.14478)
		(layer "In6.Cu")
		(net "M_E_CPU1_SA_DQ<28>")
	)
	(segment
		(start 54.503574 -231.989376)
		(end 54.666642 -232.152444)
		(width 0.14478)
		(layer "In6.Cu")
		(net "M_E_CPU1_SA_DQ<28>")
	)
	(segment
		(start 67.846194 -240.829338)
		(end 67.846194 -241.146838)
		(width 0.14478)
		(layer "In6.Cu")
		(net "M_E_CPU1_SA_DQ<28>")
	)
	(segment
		(start 30.630114 -231.5972)
		(end 30.793182 -231.760268)
		(width 0.14478)
		(layer "In6.Cu")
		(net "M_E_CPU1_SA_DQ<28>")
	)
	(segment
		(start 41.063926 -231.976676)
		(end 41.226994 -232.139744)
		(width 0.14478)
		(layer "In6.Cu")
		(net "M_E_CPU1_SA_DQ<28>")
	)
	(segment
		(start 30.236668 -230.991664)
		(end 30.467046 -230.991664)
		(width 0.14478)
		(layer "In6.Cu")
		(net "M_E_CPU1_SA_DQ<28>")
	)
	(segment
		(start 41.063926 -231.923336)
		(end 41.063926 -231.976676)
		(width 0.14478)
		(layer "In6.Cu")
		(net "M_E_CPU1_SA_DQ<28>")
	)
	(segment
		(start 29.252164 -231.335326)
		(end 29.677106 -231.760268)
		(width 0.14478)
		(layer "In6.Cu")
		(net "M_E_CPU1_SA_DQ<28>")
	)
	(segment
		(start 55.060088 -231.634792)
		(end 55.223156 -231.471724)
		(width 0.14478)
		(layer "In6.Cu")
		(net "M_E_CPU1_SA_DQ<28>")
	)
	(segment
		(start 33.761172 -232.139744)
		(end 33.92424 -231.976676)
		(width 0.14478)
		(layer "In6.Cu")
		(net "M_E_CPU1_SA_DQ<28>")
	)
	(segment
		(start 75.920346 -242.157504)
		(end 76.199746 -242.157504)
		(width 0.0889)
		(layer "In6.Cu")
		(net "M_E_CPU1_SA_DQ<28>")
	)
	(segment
		(start 54.503574 -231.923336)
		(end 54.503574 -231.989376)
		(width 0.14478)
		(layer "In6.Cu")
		(net "M_E_CPU1_SA_DQ<28>")
	)
	(segment
		(start 64.835532 -237.818422)
		(end 64.835532 -238.023146)
		(width 0.14478)
		(layer "In6.Cu")
		(net "M_E_CPU1_SA_DQ<28>")
	)
	(segment
		(start 59.709558 -231.220264)
		(end 61.93282 -233.443526)
		(width 0.14478)
		(layer "In6.Cu")
		(net "M_E_CPU1_SA_DQ<28>")
	)
	(segment
		(start 34.46653 -231.760268)
		(end 35.306762 -230.920036)
		(width 0.14478)
		(layer "In6.Cu")
		(net "M_E_CPU1_SA_DQ<28>")
	)
	(segment
		(start 65.618868 -238.601758)
		(end 65.618868 -238.806482)
		(width 0.14478)
		(layer "In6.Cu")
		(net "M_E_CPU1_SA_DQ<28>")
	)
	(segment
		(start 33.92424 -231.976676)
		(end 33.92424 -231.923336)
		(width 0.14478)
		(layer "In6.Cu")
		(net "M_E_CPU1_SA_DQ<28>")
	)
	(segment
		(start 31.611062 -232.144824)
		(end 31.84144 -232.144824)
		(width 0.14478)
		(layer "In6.Cu")
		(net "M_E_CPU1_SA_DQ<28>")
	)
	(segment
		(start 41.783508 -231.760268)
		(end 41.96969 -231.760268)
		(width 0.14478)
		(layer "In6.Cu")
		(net "M_E_CPU1_SA_DQ<28>")
	)
	(segment
		(start 32.004508 -231.923336)
		(end 32.157924 -231.76992)
		(width 0.14478)
		(layer "In6.Cu")
		(net "M_E_CPU1_SA_DQ<28>")
	)
	(segment
		(start 64.877188 -238.560102)
		(end 65.081912 -238.560102)
		(width 0.14478)
		(layer "In6.Cu")
		(net "M_E_CPU1_SA_DQ<28>")
	)
	(segment
		(start 31.447994 -231.981756)
		(end 31.611062 -232.144824)
		(width 0.14478)
		(layer "In6.Cu")
		(net "M_E_CPU1_SA_DQ<28>")
	)
	(segment
		(start 66.256916 -239.735106)
		(end 66.256916 -239.93983)
		(width 0.14478)
		(layer "In6.Cu")
		(net "M_E_CPU1_SA_DQ<28>")
	)
	(segment
		(start 29.677106 -231.760268)
		(end 29.910532 -231.760268)
		(width 0.14478)
		(layer "In6.Cu")
		(net "M_E_CPU1_SA_DQ<28>")
	)
	(segment
		(start 30.793182 -231.760268)
		(end 31.284926 -231.760268)
		(width 0.14478)
		(layer "In6.Cu")
		(net "M_E_CPU1_SA_DQ<28>")
	)
	(segment
		(start 67.295522 -240.59642)
		(end 67.613276 -240.59642)
		(width 0.14478)
		(layer "In6.Cu")
		(net "M_E_CPU1_SA_DQ<28>")
	)
	(segment
		(start 32.004508 -231.981756)
		(end 32.004508 -231.923336)
		(width 0.14478)
		(layer "In6.Cu")
		(net "M_E_CPU1_SA_DQ<28>")
	)
	(segment
		(start 30.0736 -231.5972)
		(end 30.0736 -231.154732)
		(width 0.14478)
		(layer "In6.Cu")
		(net "M_E_CPU1_SA_DQ<28>")
	)
	(segment
		(start 77.727556 -243.110766)
		(end 78.411578 -243.110766)
		(width 0.0889)
		(layer "In6.Cu")
		(net "M_E_CPU1_SA_DQ<28>")
	)
	(segment
		(start 50.462942 -230.920036)
		(end 53.090826 -230.920036)
		(width 0.14478)
		(layer "In6.Cu")
		(net "M_E_CPU1_SA_DQ<28>")
	)
	(segment
		(start 55.060088 -231.989376)
		(end 55.060088 -231.634792)
		(width 0.14478)
		(layer "In6.Cu")
		(net "M_E_CPU1_SA_DQ<28>")
	)
	(segment
		(start 64.443864 -237.631478)
		(end 64.648588 -237.631478)
		(width 0.14478)
		(layer "In6.Cu")
		(net "M_E_CPU1_SA_DQ<28>")
	)
	(segment
		(start 55.223156 -231.471724)
		(end 55.453534 -231.471724)
		(width 0.14478)
		(layer "In6.Cu")
		(net "M_E_CPU1_SA_DQ<28>")
	)
	(segment
		(start 57.16651 -231.760268)
		(end 57.706514 -231.220264)
		(width 0.14478)
		(layer "In6.Cu")
		(net "M_E_CPU1_SA_DQ<28>")
	)
	(segment
		(start 41.62044 -231.923336)
		(end 41.783508 -231.760268)
		(width 0.14478)
		(layer "In6.Cu")
		(net "M_E_CPU1_SA_DQ<28>")
	)
	(segment
		(start 66.402204 -239.589818)
		(end 66.256916 -239.735106)
		(width 0.14478)
		(layer "In6.Cu")
		(net "M_E_CPU1_SA_DQ<28>")
	)
	(segment
		(start 30.467046 -230.991664)
		(end 30.630114 -231.154732)
		(width 0.14478)
		(layer "In6.Cu")
		(net "M_E_CPU1_SA_DQ<28>")
	)
	(segment
		(start 33.367726 -231.976676)
		(end 33.530794 -232.139744)
		(width 0.14478)
		(layer "In6.Cu")
		(net "M_E_CPU1_SA_DQ<28>")
	)
	(segment
		(start 76.547472 -242.50523)
		(end 77.12202 -242.50523)
		(width 0.0889)
		(layer "In6.Cu")
		(net "M_E_CPU1_SA_DQ<28>")
	)
	(segment
		(start 79.067406 -243.186966)
		(end 79.07782 -243.18087)
		(width 0.0889)
		(layer "In6.Cu")
		(net "M_E_CPU1_SA_DQ<28>")
	)
	(segment
		(start 64.093852 -237.776766)
		(end 64.298576 -237.776766)
		(width 0.14478)
		(layer "In6.Cu")
		(net "M_E_CPU1_SA_DQ<28>")
	)
	(segment
		(start 33.367726 -231.923336)
		(end 33.367726 -231.976676)
		(width 0.14478)
		(layer "In6.Cu")
		(net "M_E_CPU1_SA_DQ<28>")
	)
	(segment
		(start 41.457372 -232.139744)
		(end 41.62044 -231.976676)
		(width 0.14478)
		(layer "In6.Cu")
		(net "M_E_CPU1_SA_DQ<28>")
	)
	(segment
		(start 33.21431 -231.76992)
		(end 33.367726 -231.923336)
		(width 0.14478)
		(layer "In6.Cu")
		(net "M_E_CPU1_SA_DQ<28>")
	)
	(segment
		(start 64.690244 -238.373158)
		(end 64.877188 -238.560102)
		(width 0.14478)
		(layer "In6.Cu")
		(net "M_E_CPU1_SA_DQ<28>")
	)
	(segment
		(start 31.447994 -231.923336)
		(end 31.447994 -231.981756)
		(width 0.14478)
		(layer "In6.Cu")
		(net "M_E_CPU1_SA_DQ<28>")
	)
	(segment
		(start 38.024562 -230.920036)
		(end 38.874446 -231.76992)
		(width 0.14478)
		(layer "In6.Cu")
		(net "M_E_CPU1_SA_DQ<28>")
	)
	(segment
		(start 66.21526 -239.19815)
		(end 66.402204 -239.385094)
		(width 0.14478)
		(layer "In6.Cu")
		(net "M_E_CPU1_SA_DQ<28>")
	)
	(segment
		(start 64.835532 -238.023146)
		(end 64.690244 -238.168434)
		(width 0.14478)
		(layer "In6.Cu")
		(net "M_E_CPU1_SA_DQ<28>")
	)
	(arc
		(start 79.07782 -243.18087)
		(mid 79.356506 -243.11065)
		(end 79.633572 -243.186966)
		(width 0.0889)
		(layer "In6.Cu")
		(net "M_E_CPU1_SA_DQ<28>")
	)
	(arc
		(start 80.008222 -243.186966)
		(mid 80.291178 -243.110789)
		(end 80.574134 -243.186966)
		(width 0.0889)
		(layer "In6.Cu")
		(net "M_E_CPU1_SA_DQ<28>")
	)
	(arc
		(start 78.709774 -243.19611)
		(mid 78.889756 -243.23721)
		(end 79.067406 -243.186966)
		(width 0.0889)
		(layer "In6.Cu")
		(net "M_E_CPU1_SA_DQ<28>")
	)
	(arc
		(start 80.574134 -243.186966)
		(mid 80.730453 -243.235961)
		(end 80.89265 -243.213128)
		(width 0.0889)
		(layer "In6.Cu")
		(net "M_E_CPU1_SA_DQ<28>")
	)
	(arc
		(start 78.411578 -243.110766)
		(mid 78.427458 -243.110925)
		(end 78.443328 -243.111528)
		(width 0.0889)
		(layer "In6.Cu")
		(net "M_E_CPU1_SA_DQ<28>")
	)
	(arc
		(start 78.443328 -243.111528)
		(mid 78.572832 -243.134442)
		(end 78.693518 -243.186712)
		(width 0.0889)
		(layer "In6.Cu")
		(net "M_E_CPU1_SA_DQ<28>")
	)
	(arc
		(start 79.633572 -243.186966)
		(mid 79.816077 -243.237443)
		(end 79.99984 -243.191792)
		(width 0.0889)
		(layer "In6.Cu")
		(net "M_E_CPU1_SA_DQ<28>")
	)
	(segment
		(start 83.107784 -241.510312)
		(end 82.640932 -241.244374)
		(width 0.10668)
		(layer "F.Cu")
		(net "M_E_CPU1_SA_DQ<27>")
	)
	(segment
		(start 82.487008 -240.978944)
		(end 82.640932 -241.244374)
		(width 0.0889)
		(layer "In6.Cu")
		(net "M_E_CPU1_SA_DQ<27>")
	)
	(segment
		(start 50.335942 -227.500688)
		(end 53.246782 -227.500688)
		(width 0.14478)
		(layer "In6.Cu")
		(net "M_E_CPU1_SA_DQ<27>")
	)
	(segment
		(start 71.30415 -239.818164)
		(end 75.945746 -239.818164)
		(width 0.14478)
		(layer "In6.Cu")
		(net "M_E_CPU1_SA_DQ<27>")
	)
	(segment
		(start 38.864032 -228.350572)
		(end 41.919652 -228.350572)
		(width 0.14478)
		(layer "In6.Cu")
		(net "M_E_CPU1_SA_DQ<27>")
	)
	(segment
		(start 38.014148 -227.500688)
		(end 38.864032 -228.350572)
		(width 0.14478)
		(layer "In6.Cu")
		(net "M_E_CPU1_SA_DQ<27>")
	)
	(segment
		(start 45.702982 -227.500688)
		(end 46.552866 -228.350572)
		(width 0.14478)
		(layer "In6.Cu")
		(net "M_E_CPU1_SA_DQ<27>")
	)
	(segment
		(start 66.755772 -235.269786)
		(end 71.30415 -239.818164)
		(width 0.14478)
		(layer "In6.Cu")
		(net "M_E_CPU1_SA_DQ<27>")
	)
	(segment
		(start 42.769536 -227.500688)
		(end 45.702982 -227.500688)
		(width 0.14478)
		(layer "In6.Cu")
		(net "M_E_CPU1_SA_DQ<27>")
	)
	(segment
		(start 34.309558 -228.350572)
		(end 35.159442 -227.500688)
		(width 0.14478)
		(layer "In6.Cu")
		(net "M_E_CPU1_SA_DQ<27>")
	)
	(segment
		(start 79.056992 -240.914936)
		(end 79.068676 -240.921794)
		(width 0.0889)
		(layer "In6.Cu")
		(net "M_E_CPU1_SA_DQ<27>")
	)
	(segment
		(start 41.919652 -228.350572)
		(end 42.769536 -227.500688)
		(width 0.14478)
		(layer "In6.Cu")
		(net "M_E_CPU1_SA_DQ<27>")
	)
	(segment
		(start 66.07175 -235.269786)
		(end 66.755772 -235.269786)
		(width 0.14478)
		(layer "In6.Cu")
		(net "M_E_CPU1_SA_DQ<27>")
	)
	(segment
		(start 49.486058 -228.350572)
		(end 50.335942 -227.500688)
		(width 0.14478)
		(layer "In6.Cu")
		(net "M_E_CPU1_SA_DQ<27>")
	)
	(segment
		(start 81.879694 -240.916968)
		(end 81.888076 -240.921794)
		(width 0.0889)
		(layer "In6.Cu")
		(net "M_E_CPU1_SA_DQ<27>")
	)
	(segment
		(start 64.580516 -233.778552)
		(end 66.07175 -235.269786)
		(width 0.14478)
		(layer "In6.Cu")
		(net "M_E_CPU1_SA_DQ<27>")
	)
	(segment
		(start 26.10993 -227.935282)
		(end 27.112722 -228.350572)
		(width 0.14478)
		(layer "In6.Cu")
		(net "M_E_CPU1_SA_DQ<27>")
	)
	(segment
		(start 75.945746 -239.818164)
		(end 76.181966 -239.818164)
		(width 0.0889)
		(layer "In6.Cu")
		(net "M_E_CPU1_SA_DQ<27>")
	)
	(segment
		(start 46.552866 -228.350572)
		(end 49.486058 -228.350572)
		(width 0.14478)
		(layer "In6.Cu")
		(net "M_E_CPU1_SA_DQ<27>")
	)
	(segment
		(start 53.246782 -227.500688)
		(end 54.106572 -228.360478)
		(width 0.14478)
		(layer "In6.Cu")
		(net "M_E_CPU1_SA_DQ<27>")
	)
	(segment
		(start 76.651866 -240.288064)
		(end 77.015086 -240.288064)
		(width 0.0889)
		(layer "In6.Cu")
		(net "M_E_CPU1_SA_DQ<27>")
	)
	(segment
		(start 57.019952 -228.360478)
		(end 57.87009 -227.51034)
		(width 0.14478)
		(layer "In6.Cu")
		(net "M_E_CPU1_SA_DQ<27>")
	)
	(segment
		(start 59.24169 -227.51034)
		(end 63.92291 -232.19156)
		(width 0.14478)
		(layer "In6.Cu")
		(net "M_E_CPU1_SA_DQ<27>")
	)
	(segment
		(start 25.152096 -227.935282)
		(end 26.10993 -227.935282)
		(width 0.14478)
		(layer "In6.Cu")
		(net "M_E_CPU1_SA_DQ<27>")
	)
	(segment
		(start 79.62392 -240.92789)
		(end 79.634334 -240.921794)
		(width 0.0889)
		(layer "In6.Cu")
		(net "M_E_CPU1_SA_DQ<27>")
	)
	(segment
		(start 79.634334 -240.921794)
		(end 79.646018 -240.914936)
		(width 0.0889)
		(layer "In6.Cu")
		(net "M_E_CPU1_SA_DQ<27>")
	)
	(segment
		(start 77.766926 -241.039904)
		(end 78.255876 -241.039904)
		(width 0.0889)
		(layer "In6.Cu")
		(net "M_E_CPU1_SA_DQ<27>")
	)
	(segment
		(start 82.390996 -240.953544)
		(end 82.487008 -240.978944)
		(width 0.0889)
		(layer "In6.Cu")
		(net "M_E_CPU1_SA_DQ<27>")
	)
	(segment
		(start 77.015086 -240.288064)
		(end 77.766926 -241.039904)
		(width 0.0889)
		(layer "In6.Cu")
		(net "M_E_CPU1_SA_DQ<27>")
	)
	(segment
		(start 57.87009 -227.51034)
		(end 59.24169 -227.51034)
		(width 0.14478)
		(layer "In6.Cu")
		(net "M_E_CPU1_SA_DQ<27>")
	)
	(segment
		(start 35.159442 -227.500688)
		(end 38.014148 -227.500688)
		(width 0.14478)
		(layer "In6.Cu")
		(net "M_E_CPU1_SA_DQ<27>")
	)
	(segment
		(start 63.92291 -232.19156)
		(end 64.580516 -233.778552)
		(width 0.14478)
		(layer "In6.Cu")
		(net "M_E_CPU1_SA_DQ<27>")
	)
	(segment
		(start 76.181966 -239.818164)
		(end 76.651866 -240.288064)
		(width 0.0889)
		(layer "In6.Cu")
		(net "M_E_CPU1_SA_DQ<27>")
	)
	(segment
		(start 54.106572 -228.360478)
		(end 57.019952 -228.360478)
		(width 0.14478)
		(layer "In6.Cu")
		(net "M_E_CPU1_SA_DQ<27>")
	)
	(segment
		(start 27.112722 -228.350572)
		(end 34.309558 -228.350572)
		(width 0.14478)
		(layer "In6.Cu")
		(net "M_E_CPU1_SA_DQ<27>")
	)
	(arc
		(start 79.068676 -240.921794)
		(mid 79.345489 -240.997937)
		(end 79.62392 -240.92789)
		(width 0.0889)
		(layer "In6.Cu")
		(net "M_E_CPU1_SA_DQ<27>")
	)
	(arc
		(start 79.646018 -240.914936)
		(mid 79.828019 -240.871403)
		(end 80.008222 -240.921794)
		(width 0.0889)
		(layer "In6.Cu")
		(net "M_E_CPU1_SA_DQ<27>")
	)
	(arc
		(start 80.008222 -240.921794)
		(mid 80.291178 -240.997971)
		(end 80.574134 -240.921794)
		(width 0.0889)
		(layer "In6.Cu")
		(net "M_E_CPU1_SA_DQ<27>")
	)
	(arc
		(start 81.513934 -240.921794)
		(mid 81.696185 -240.871444)
		(end 81.879694 -240.916968)
		(width 0.0889)
		(layer "In6.Cu")
		(net "M_E_CPU1_SA_DQ<27>")
	)
	(arc
		(start 81.888076 -240.921794)
		(mid 82.135789 -240.997014)
		(end 82.390996 -240.953544)
		(width 0.0889)
		(layer "In6.Cu")
		(net "M_E_CPU1_SA_DQ<27>")
	)
	(arc
		(start 78.69428 -240.921794)
		(mid 78.874738 -240.87135)
		(end 79.056992 -240.914936)
		(width 0.0889)
		(layer "In6.Cu")
		(net "M_E_CPU1_SA_DQ<27>")
	)
	(arc
		(start 80.574134 -240.921794)
		(mid 80.761078 -240.871539)
		(end 80.948022 -240.921794)
		(width 0.0889)
		(layer "In6.Cu")
		(net "M_E_CPU1_SA_DQ<27>")
	)
	(arc
		(start 80.948022 -240.921794)
		(mid 81.230978 -240.997971)
		(end 81.513934 -240.921794)
		(width 0.0889)
		(layer "In6.Cu")
		(net "M_E_CPU1_SA_DQ<27>")
	)
	(arc
		(start 78.255876 -241.039904)
		(mid 78.48289 -241.009853)
		(end 78.69428 -240.921794)
		(width 0.0889)
		(layer "In6.Cu")
		(net "M_E_CPU1_SA_DQ<27>")
	)
	(segment
		(start 81.69783 -240.700306)
		(end 81.230978 -240.434368)
		(width 0.10668)
		(layer "F.Cu")
		(net "M_E_CPU1_SA_DQ<26>")
	)
	(segment
		(start 26.49855 -225.921824)
		(end 26.728928 -225.921824)
		(width 0.14478)
		(layer "In6.Cu")
		(net "M_E_CPU1_SA_DQ<26>")
	)
	(segment
		(start 59.76239 -225.810318)
		(end 60.74537 -226.793298)
		(width 0.14478)
		(layer "In6.Cu")
		(net "M_E_CPU1_SA_DQ<26>")
	)
	(segment
		(start 59.107578 -225.810318)
		(end 59.76239 -225.810318)
		(width 0.14478)
		(layer "In6.Cu")
		(net "M_E_CPU1_SA_DQ<26>")
	)
	(segment
		(start 50.32629 -225.810318)
		(end 53.256434 -225.810318)
		(width 0.14478)
		(layer "In6.Cu")
		(net "M_E_CPU1_SA_DQ<26>")
	)
	(segment
		(start 80.46974 -240.106962)
		(end 80.478122 -240.111788)
		(width 0.0889)
		(layer "In6.Cu")
		(net "M_E_CPU1_SA_DQ<26>")
	)
	(segment
		(start 57.125362 -226.555046)
		(end 58.36285 -226.555046)
		(width 0.14478)
		(layer "In6.Cu")
		(net "M_E_CPU1_SA_DQ<26>")
	)
	(segment
		(start 46.562772 -226.660456)
		(end 49.476152 -226.660456)
		(width 0.14478)
		(layer "In6.Cu")
		(net "M_E_CPU1_SA_DQ<26>")
	)
	(segment
		(start 64.71539 -231.695752)
		(end 64.88557 -232.106216)
		(width 0.14478)
		(layer "In6.Cu")
		(net "M_E_CPU1_SA_DQ<26>")
	)
	(segment
		(start 49.476152 -226.660456)
		(end 50.32629 -225.810318)
		(width 0.14478)
		(layer "In6.Cu")
		(net "M_E_CPU1_SA_DQ<26>")
	)
	(segment
		(start 26.172414 -226.660456)
		(end 26.335482 -226.497388)
		(width 0.14478)
		(layer "In6.Cu")
		(net "M_E_CPU1_SA_DQ<26>")
	)
	(segment
		(start 26.728928 -225.921824)
		(end 26.891996 -226.084892)
		(width 0.14478)
		(layer "In6.Cu")
		(net "M_E_CPU1_SA_DQ<26>")
	)
	(segment
		(start 57.019952 -226.660456)
		(end 57.125362 -226.555046)
		(width 0.14478)
		(layer "In6.Cu")
		(net "M_E_CPU1_SA_DQ<26>")
	)
	(segment
		(start 27.055064 -226.660456)
		(end 34.299652 -226.660456)
		(width 0.14478)
		(layer "In6.Cu")
		(net "M_E_CPU1_SA_DQ<26>")
	)
	(segment
		(start 34.299652 -226.660456)
		(end 35.14979 -225.810318)
		(width 0.14478)
		(layer "In6.Cu")
		(net "M_E_CPU1_SA_DQ<26>")
	)
	(segment
		(start 38.873938 -226.660456)
		(end 41.909746 -226.660456)
		(width 0.14478)
		(layer "In6.Cu")
		(net "M_E_CPU1_SA_DQ<26>")
	)
	(segment
		(start 35.14979 -225.810318)
		(end 38.0238 -225.810318)
		(width 0.14478)
		(layer "In6.Cu")
		(net "M_E_CPU1_SA_DQ<26>")
	)
	(segment
		(start 79.15402 -240.117884)
		(end 79.164434 -240.111788)
		(width 0.0889)
		(layer "In6.Cu")
		(net "M_E_CPU1_SA_DQ<26>")
	)
	(segment
		(start 26.891996 -226.084892)
		(end 26.891996 -226.497388)
		(width 0.14478)
		(layer "In6.Cu")
		(net "M_E_CPU1_SA_DQ<26>")
	)
	(segment
		(start 26.335482 -226.084892)
		(end 26.49855 -225.921824)
		(width 0.14478)
		(layer "In6.Cu")
		(net "M_E_CPU1_SA_DQ<26>")
	)
	(segment
		(start 81.077054 -240.168938)
		(end 81.230978 -240.434368)
		(width 0.0889)
		(layer "In6.Cu")
		(net "M_E_CPU1_SA_DQ<26>")
	)
	(segment
		(start 25.152096 -226.23526)
		(end 25.577292 -226.660456)
		(width 0.14478)
		(layer "In6.Cu")
		(net "M_E_CPU1_SA_DQ<26>")
	)
	(segment
		(start 75.935586 -238.903764)
		(end 76.369926 -238.903764)
		(width 0.0889)
		(layer "In6.Cu")
		(net "M_E_CPU1_SA_DQ<26>")
	)
	(segment
		(start 60.74537 -226.793298)
		(end 60.74537 -227.725732)
		(width 0.14478)
		(layer "In6.Cu")
		(net "M_E_CPU1_SA_DQ<26>")
	)
	(segment
		(start 60.74537 -227.725732)
		(end 64.71539 -231.695752)
		(width 0.14478)
		(layer "In6.Cu")
		(net "M_E_CPU1_SA_DQ<26>")
	)
	(segment
		(start 42.759884 -225.810318)
		(end 45.712634 -225.810318)
		(width 0.14478)
		(layer "In6.Cu")
		(net "M_E_CPU1_SA_DQ<26>")
	)
	(segment
		(start 76.507086 -239.040924)
		(end 76.964286 -239.040924)
		(width 0.0889)
		(layer "In6.Cu")
		(net "M_E_CPU1_SA_DQ<26>")
	)
	(segment
		(start 79.538322 -240.111788)
		(end 79.548736 -240.117884)
		(width 0.0889)
		(layer "In6.Cu")
		(net "M_E_CPU1_SA_DQ<26>")
	)
	(segment
		(start 58.36285 -226.555046)
		(end 59.107578 -225.810318)
		(width 0.14478)
		(layer "In6.Cu")
		(net "M_E_CPU1_SA_DQ<26>")
	)
	(segment
		(start 41.909746 -226.660456)
		(end 42.759884 -225.810318)
		(width 0.14478)
		(layer "In6.Cu")
		(net "M_E_CPU1_SA_DQ<26>")
	)
	(segment
		(start 25.577292 -226.660456)
		(end 26.172414 -226.660456)
		(width 0.14478)
		(layer "In6.Cu")
		(net "M_E_CPU1_SA_DQ<26>")
	)
	(segment
		(start 80.981042 -240.143538)
		(end 81.077054 -240.168938)
		(width 0.0889)
		(layer "In6.Cu")
		(net "M_E_CPU1_SA_DQ<26>")
	)
	(segment
		(start 64.88557 -232.106216)
		(end 71.683118 -238.903764)
		(width 0.14478)
		(layer "In6.Cu")
		(net "M_E_CPU1_SA_DQ<26>")
	)
	(segment
		(start 38.0238 -225.810318)
		(end 38.873938 -226.660456)
		(width 0.14478)
		(layer "In6.Cu")
		(net "M_E_CPU1_SA_DQ<26>")
	)
	(segment
		(start 26.891996 -226.497388)
		(end 27.055064 -226.660456)
		(width 0.14478)
		(layer "In6.Cu")
		(net "M_E_CPU1_SA_DQ<26>")
	)
	(segment
		(start 71.683118 -238.903764)
		(end 75.935586 -238.903764)
		(width 0.14478)
		(layer "In6.Cu")
		(net "M_E_CPU1_SA_DQ<26>")
	)
	(segment
		(start 76.369926 -238.903764)
		(end 76.507086 -239.040924)
		(width 0.0889)
		(layer "In6.Cu")
		(net "M_E_CPU1_SA_DQ<26>")
	)
	(segment
		(start 53.256434 -225.810318)
		(end 54.106572 -226.660456)
		(width 0.14478)
		(layer "In6.Cu")
		(net "M_E_CPU1_SA_DQ<26>")
	)
	(segment
		(start 77.984604 -240.061242)
		(end 78.41107 -240.061242)
		(width 0.0889)
		(layer "In6.Cu")
		(net "M_E_CPU1_SA_DQ<26>")
	)
	(segment
		(start 76.964286 -239.040924)
		(end 77.984604 -240.061242)
		(width 0.0889)
		(layer "In6.Cu")
		(net "M_E_CPU1_SA_DQ<26>")
	)
	(segment
		(start 26.335482 -226.497388)
		(end 26.335482 -226.084892)
		(width 0.14478)
		(layer "In6.Cu")
		(net "M_E_CPU1_SA_DQ<26>")
	)
	(segment
		(start 45.712634 -225.810318)
		(end 46.562772 -226.660456)
		(width 0.14478)
		(layer "In6.Cu")
		(net "M_E_CPU1_SA_DQ<26>")
	)
	(segment
		(start 54.106572 -226.660456)
		(end 57.019952 -226.660456)
		(width 0.14478)
		(layer "In6.Cu")
		(net "M_E_CPU1_SA_DQ<26>")
	)
	(arc
		(start 79.548736 -240.117884)
		(mid 79.827168 -240.187982)
		(end 80.10398 -240.111788)
		(width 0.0889)
		(layer "In6.Cu")
		(net "M_E_CPU1_SA_DQ<26>")
	)
	(arc
		(start 80.478122 -240.111788)
		(mid 80.725835 -240.187008)
		(end 80.981042 -240.143538)
		(width 0.0889)
		(layer "In6.Cu")
		(net "M_E_CPU1_SA_DQ<26>")
	)
	(arc
		(start 78.41107 -240.061242)
		(mid 78.508017 -240.074125)
		(end 78.598268 -240.111788)
		(width 0.0889)
		(layer "In6.Cu")
		(net "M_E_CPU1_SA_DQ<26>")
	)
	(arc
		(start 79.164434 -240.111788)
		(mid 79.351378 -240.061533)
		(end 79.538322 -240.111788)
		(width 0.0889)
		(layer "In6.Cu")
		(net "M_E_CPU1_SA_DQ<26>")
	)
	(arc
		(start 78.598268 -240.111788)
		(mid 78.875335 -240.188059)
		(end 79.15402 -240.117884)
		(width 0.0889)
		(layer "In6.Cu")
		(net "M_E_CPU1_SA_DQ<26>")
	)
	(arc
		(start 80.10398 -240.111788)
		(mid 80.286231 -240.061438)
		(end 80.46974 -240.106962)
		(width 0.0889)
		(layer "In6.Cu")
		(net "M_E_CPU1_SA_DQ<26>")
	)
	(segment
		(start 82.637884 -240.700306)
		(end 82.171032 -240.434368)
		(width 0.10668)
		(layer "F.Cu")
		(net "M_E_CPU1_SA_DQ<25>")
	)
	(segment
		(start 54.736238 -227.51034)
		(end 54.899306 -227.673408)
		(width 0.14478)
		(layer "In6.Cu")
		(net "M_E_CPU1_SA_DQ<25>")
	)
	(segment
		(start 64.873378 -232.744264)
		(end 64.873378 -233.299254)
		(width 0.14478)
		(layer "In6.Cu")
		(net "M_E_CPU1_SA_DQ<25>")
	)
	(segment
		(start 38.864794 -227.51034)
		(end 40.695118 -227.51034)
		(width 0.14478)
		(layer "In6.Cu")
		(net "M_E_CPU1_SA_DQ<25>")
	)
	(segment
		(start 59.541918 -227.17252)
		(end 59.746642 -227.172774)
		(width 0.14478)
		(layer "In6.Cu")
		(net "M_E_CPU1_SA_DQ<25>")
	)
	(segment
		(start 60.279788 -227.232972)
		(end 60.279534 -227.437188)
		(width 0.14478)
		(layer "In6.Cu")
		(net "M_E_CPU1_SA_DQ<25>")
	)
	(segment
		(start 66.336418 -234.761786)
		(end 66.890138 -234.761024)
		(width 0.14478)
		(layer "In6.Cu")
		(net "M_E_CPU1_SA_DQ<25>")
	)
	(segment
		(start 31.38678 -227.283264)
		(end 31.38678 -227.737416)
		(width 0.14478)
		(layer "In6.Cu")
		(net "M_E_CPU1_SA_DQ<25>")
	)
	(segment
		(start 77.70114 -240.201958)
		(end 77.70114 -240.290858)
		(width 0.0889)
		(layer "In6.Cu")
		(net "M_E_CPU1_SA_DQ<25>")
	)
	(segment
		(start 56.568848 -227.734876)
		(end 56.568848 -227.673408)
		(width 0.14478)
		(layer "In6.Cu")
		(net "M_E_CPU1_SA_DQ<25>")
	)
	(segment
		(start 64.303402 -231.934004)
		(end 64.473074 -232.34396)
		(width 0.14478)
		(layer "In6.Cu")
		(net "M_E_CPU1_SA_DQ<25>")
	)
	(segment
		(start 34.50463 -227.51034)
		(end 35.354514 -226.660456)
		(width 0.14478)
		(layer "In6.Cu")
		(net "M_E_CPU1_SA_DQ<25>")
	)
	(segment
		(start 41.4147 -227.734876)
		(end 41.4147 -227.673408)
		(width 0.14478)
		(layer "In6.Cu")
		(net "M_E_CPU1_SA_DQ<25>")
	)
	(segment
		(start 60.085478 -227.038662)
		(end 60.279788 -227.232972)
		(width 0.14478)
		(layer "In6.Cu")
		(net "M_E_CPU1_SA_DQ<25>")
	)
	(segment
		(start 76.959206 -239.460024)
		(end 77.70114 -240.201958)
		(width 0.0889)
		(layer "In6.Cu")
		(net "M_E_CPU1_SA_DQ<25>")
	)
	(segment
		(start 59.374024 -227.004626)
		(end 59.541918 -227.17252)
		(width 0.14478)
		(layer "In6.Cu")
		(net "M_E_CPU1_SA_DQ<25>")
	)
	(segment
		(start 31.38678 -227.737416)
		(end 31.549848 -227.900484)
		(width 0.14478)
		(layer "In6.Cu")
		(net "M_E_CPU1_SA_DQ<25>")
	)
	(segment
		(start 49.29632 -227.729796)
		(end 49.29632 -227.673408)
		(width 0.14478)
		(layer "In6.Cu")
		(net "M_E_CPU1_SA_DQ<25>")
	)
	(segment
		(start 56.568848 -227.673408)
		(end 56.731916 -227.51034)
		(width 0.14478)
		(layer "In6.Cu")
		(net "M_E_CPU1_SA_DQ<25>")
	)
	(segment
		(start 35.354514 -226.660456)
		(end 38.01491 -226.660456)
		(width 0.14478)
		(layer "In6.Cu")
		(net "M_E_CPU1_SA_DQ<25>")
	)
	(segment
		(start 31.780226 -227.900484)
		(end 31.943294 -227.737416)
		(width 0.14478)
		(layer "In6.Cu")
		(net "M_E_CPU1_SA_DQ<25>")
	)
	(segment
		(start 56.731916 -227.51034)
		(end 57.22493 -227.51034)
		(width 0.14478)
		(layer "In6.Cu")
		(net "M_E_CPU1_SA_DQ<25>")
	)
	(segment
		(start 64.473074 -232.34396)
		(end 64.873378 -232.744264)
		(width 0.14478)
		(layer "In6.Cu")
		(net "M_E_CPU1_SA_DQ<25>")
	)
	(segment
		(start 59.746642 -227.172774)
		(end 59.880754 -227.038662)
		(width 0.14478)
		(layer "In6.Cu")
		(net "M_E_CPU1_SA_DQ<25>")
	)
	(segment
		(start 57.22493 -227.51034)
		(end 57.730644 -227.004626)
		(width 0.14478)
		(layer "In6.Cu")
		(net "M_E_CPU1_SA_DQ<25>")
	)
	(segment
		(start 31.943294 -227.673408)
		(end 32.106362 -227.51034)
		(width 0.14478)
		(layer "In6.Cu")
		(net "M_E_CPU1_SA_DQ<25>")
	)
	(segment
		(start 56.012334 -227.734876)
		(end 56.175402 -227.897944)
		(width 0.14478)
		(layer "In6.Cu")
		(net "M_E_CPU1_SA_DQ<25>")
	)
	(segment
		(start 41.4147 -227.673408)
		(end 41.577768 -227.51034)
		(width 0.14478)
		(layer "In6.Cu")
		(net "M_E_CPU1_SA_DQ<25>")
	)
	(segment
		(start 66.890138 -234.761024)
		(end 71.492618 -239.363504)
		(width 0.14478)
		(layer "In6.Cu")
		(net "M_E_CPU1_SA_DQ<25>")
	)
	(segment
		(start 79.538322 -240.756948)
		(end 79.548736 -240.750852)
		(width 0.0889)
		(layer "In6.Cu")
		(net "M_E_CPU1_SA_DQ<25>")
	)
	(segment
		(start 30.993334 -227.120196)
		(end 31.223712 -227.120196)
		(width 0.14478)
		(layer "In6.Cu")
		(net "M_E_CPU1_SA_DQ<25>")
	)
	(segment
		(start 32.106362 -227.51034)
		(end 34.50463 -227.51034)
		(width 0.14478)
		(layer "In6.Cu")
		(net "M_E_CPU1_SA_DQ<25>")
	)
	(segment
		(start 55.45582 -227.734876)
		(end 55.45582 -227.673408)
		(width 0.14478)
		(layer "In6.Cu")
		(net "M_E_CPU1_SA_DQ<25>")
	)
	(segment
		(start 56.175402 -227.897944)
		(end 56.40578 -227.897944)
		(width 0.14478)
		(layer "In6.Cu")
		(net "M_E_CPU1_SA_DQ<25>")
	)
	(segment
		(start 54.084474 -227.51034)
		(end 54.736238 -227.51034)
		(width 0.14478)
		(layer "In6.Cu")
		(net "M_E_CPU1_SA_DQ<25>")
	)
	(segment
		(start 59.880754 -227.038662)
		(end 60.085478 -227.038662)
		(width 0.14478)
		(layer "In6.Cu")
		(net "M_E_CPU1_SA_DQ<25>")
	)
	(segment
		(start 30.273752 -227.737416)
		(end 30.43682 -227.900484)
		(width 0.14478)
		(layer "In6.Cu")
		(net "M_E_CPU1_SA_DQ<25>")
	)
	(segment
		(start 78.104746 -240.688622)
		(end 78.242668 -240.767108)
		(width 0.0889)
		(layer "In6.Cu")
		(net "M_E_CPU1_SA_DQ<25>")
	)
	(segment
		(start 77.70114 -240.290858)
		(end 78.098904 -240.688622)
		(width 0.0889)
		(layer "In6.Cu")
		(net "M_E_CPU1_SA_DQ<25>")
	)
	(segment
		(start 66.02857 -233.899456)
		(end 66.02857 -234.453938)
		(width 0.14478)
		(layer "In6.Cu")
		(net "M_E_CPU1_SA_DQ<25>")
	)
	(segment
		(start 41.021254 -227.897944)
		(end 41.251632 -227.897944)
		(width 0.14478)
		(layer "In6.Cu")
		(net "M_E_CPU1_SA_DQ<25>")
	)
	(segment
		(start 50.531014 -226.660456)
		(end 53.23459 -226.660456)
		(width 0.14478)
		(layer "In6.Cu")
		(net "M_E_CPU1_SA_DQ<25>")
	)
	(segment
		(start 56.012334 -227.673408)
		(end 56.012334 -227.734876)
		(width 0.14478)
		(layer "In6.Cu")
		(net "M_E_CPU1_SA_DQ<25>")
	)
	(segment
		(start 48.902874 -227.892864)
		(end 49.133252 -227.892864)
		(width 0.14478)
		(layer "In6.Cu")
		(net "M_E_CPU1_SA_DQ<25>")
	)
	(segment
		(start 49.68113 -227.51034)
		(end 50.531014 -226.660456)
		(width 0.14478)
		(layer "In6.Cu")
		(net "M_E_CPU1_SA_DQ<25>")
	)
	(segment
		(start 29.677106 -227.51034)
		(end 30.110684 -227.51034)
		(width 0.14478)
		(layer "In6.Cu")
		(net "M_E_CPU1_SA_DQ<25>")
	)
	(segment
		(start 30.43682 -227.900484)
		(end 30.667198 -227.900484)
		(width 0.14478)
		(layer "In6.Cu")
		(net "M_E_CPU1_SA_DQ<25>")
	)
	(segment
		(start 40.858186 -227.734876)
		(end 41.021254 -227.897944)
		(width 0.14478)
		(layer "In6.Cu")
		(net "M_E_CPU1_SA_DQ<25>")
	)
	(segment
		(start 41.251632 -227.897944)
		(end 41.4147 -227.734876)
		(width 0.14478)
		(layer "In6.Cu")
		(net "M_E_CPU1_SA_DQ<25>")
	)
	(segment
		(start 41.577768 -227.51034)
		(end 42.06621 -227.51034)
		(width 0.14478)
		(layer "In6.Cu")
		(net "M_E_CPU1_SA_DQ<25>")
	)
	(segment
		(start 31.549848 -227.900484)
		(end 31.780226 -227.900484)
		(width 0.14478)
		(layer "In6.Cu")
		(net "M_E_CPU1_SA_DQ<25>")
	)
	(segment
		(start 48.739806 -227.673408)
		(end 48.739806 -227.729796)
		(width 0.14478)
		(layer "In6.Cu")
		(net "M_E_CPU1_SA_DQ<25>")
	)
	(segment
		(start 54.899306 -227.673408)
		(end 54.899306 -227.734876)
		(width 0.14478)
		(layer "In6.Cu")
		(net "M_E_CPU1_SA_DQ<25>")
	)
	(segment
		(start 80.46974 -240.761774)
		(end 80.478122 -240.756948)
		(width 0.0889)
		(layer "In6.Cu")
		(net "M_E_CPU1_SA_DQ<25>")
	)
	(segment
		(start 46.540674 -227.51034)
		(end 48.576738 -227.51034)
		(width 0.14478)
		(layer "In6.Cu")
		(net "M_E_CPU1_SA_DQ<25>")
	)
	(segment
		(start 71.492618 -239.363504)
		(end 75.950826 -239.363504)
		(width 0.14478)
		(layer "In6.Cu")
		(net "M_E_CPU1_SA_DQ<25>")
	)
	(segment
		(start 76.484226 -239.460024)
		(end 76.959206 -239.460024)
		(width 0.0889)
		(layer "In6.Cu")
		(net "M_E_CPU1_SA_DQ<25>")
	)
	(segment
		(start 78.098904 -240.688622)
		(end 78.104746 -240.688622)
		(width 0.0889)
		(layer "In6.Cu")
		(net "M_E_CPU1_SA_DQ<25>")
	)
	(segment
		(start 42.06621 -227.51034)
		(end 42.916094 -226.660456)
		(width 0.14478)
		(layer "In6.Cu")
		(net "M_E_CPU1_SA_DQ<25>")
	)
	(segment
		(start 29.252164 -227.085398)
		(end 29.677106 -227.51034)
		(width 0.14478)
		(layer "In6.Cu")
		(net "M_E_CPU1_SA_DQ<25>")
	)
	(segment
		(start 30.667198 -227.900484)
		(end 30.830266 -227.737416)
		(width 0.14478)
		(layer "In6.Cu")
		(net "M_E_CPU1_SA_DQ<25>")
	)
	(segment
		(start 56.40578 -227.897944)
		(end 56.568848 -227.734876)
		(width 0.14478)
		(layer "In6.Cu")
		(net "M_E_CPU1_SA_DQ<25>")
	)
	(segment
		(start 55.849266 -227.51034)
		(end 56.012334 -227.673408)
		(width 0.14478)
		(layer "In6.Cu")
		(net "M_E_CPU1_SA_DQ<25>")
	)
	(segment
		(start 75.950826 -239.363504)
		(end 76.387706 -239.363504)
		(width 0.0889)
		(layer "In6.Cu")
		(net "M_E_CPU1_SA_DQ<25>")
	)
	(segment
		(start 48.739806 -227.729796)
		(end 48.902874 -227.892864)
		(width 0.14478)
		(layer "In6.Cu")
		(net "M_E_CPU1_SA_DQ<25>")
	)
	(segment
		(start 55.45582 -227.673408)
		(end 55.618888 -227.51034)
		(width 0.14478)
		(layer "In6.Cu")
		(net "M_E_CPU1_SA_DQ<25>")
	)
	(segment
		(start 30.110684 -227.51034)
		(end 30.273752 -227.673408)
		(width 0.14478)
		(layer "In6.Cu")
		(net "M_E_CPU1_SA_DQ<25>")
	)
	(segment
		(start 42.916094 -226.660456)
		(end 45.69079 -226.660456)
		(width 0.14478)
		(layer "In6.Cu")
		(net "M_E_CPU1_SA_DQ<25>")
	)
	(segment
		(start 48.576738 -227.51034)
		(end 48.739806 -227.673408)
		(width 0.14478)
		(layer "In6.Cu")
		(net "M_E_CPU1_SA_DQ<25>")
	)
	(segment
		(start 64.873378 -233.299254)
		(end 65.198498 -233.624374)
		(width 0.14478)
		(layer "In6.Cu")
		(net "M_E_CPU1_SA_DQ<25>")
	)
	(segment
		(start 45.69079 -226.660456)
		(end 46.540674 -227.51034)
		(width 0.14478)
		(layer "In6.Cu")
		(net "M_E_CPU1_SA_DQ<25>")
	)
	(segment
		(start 55.618888 -227.51034)
		(end 55.849266 -227.51034)
		(width 0.14478)
		(layer "In6.Cu")
		(net "M_E_CPU1_SA_DQ<25>")
	)
	(segment
		(start 60.145422 -227.5713)
		(end 60.145422 -227.776024)
		(width 0.14478)
		(layer "In6.Cu")
		(net "M_E_CPU1_SA_DQ<25>")
	)
	(segment
		(start 55.292752 -227.897944)
		(end 55.45582 -227.734876)
		(width 0.14478)
		(layer "In6.Cu")
		(net "M_E_CPU1_SA_DQ<25>")
	)
	(segment
		(start 54.899306 -227.734876)
		(end 55.062374 -227.897944)
		(width 0.14478)
		(layer "In6.Cu")
		(net "M_E_CPU1_SA_DQ<25>")
	)
	(segment
		(start 57.730644 -227.004626)
		(end 59.374024 -227.004626)
		(width 0.14478)
		(layer "In6.Cu")
		(net "M_E_CPU1_SA_DQ<25>")
	)
	(segment
		(start 82.324956 -240.699798)
		(end 82.171032 -240.434368)
		(width 0.0889)
		(layer "In6.Cu")
		(net "M_E_CPU1_SA_DQ<25>")
	)
	(segment
		(start 65.752472 -233.623358)
		(end 66.02857 -233.899456)
		(width 0.14478)
		(layer "In6.Cu")
		(net "M_E_CPU1_SA_DQ<25>")
	)
	(segment
		(start 30.830266 -227.737416)
		(end 30.830266 -227.283264)
		(width 0.14478)
		(layer "In6.Cu")
		(net "M_E_CPU1_SA_DQ<25>")
	)
	(segment
		(start 60.279534 -227.437188)
		(end 60.145422 -227.5713)
		(width 0.14478)
		(layer "In6.Cu")
		(net "M_E_CPU1_SA_DQ<25>")
	)
	(segment
		(start 49.459388 -227.51034)
		(end 49.68113 -227.51034)
		(width 0.14478)
		(layer "In6.Cu")
		(net "M_E_CPU1_SA_DQ<25>")
	)
	(segment
		(start 30.273752 -227.673408)
		(end 30.273752 -227.737416)
		(width 0.14478)
		(layer "In6.Cu")
		(net "M_E_CPU1_SA_DQ<25>")
	)
	(segment
		(start 31.223712 -227.120196)
		(end 31.38678 -227.283264)
		(width 0.14478)
		(layer "In6.Cu")
		(net "M_E_CPU1_SA_DQ<25>")
	)
	(segment
		(start 49.133252 -227.892864)
		(end 49.29632 -227.729796)
		(width 0.14478)
		(layer "In6.Cu")
		(net "M_E_CPU1_SA_DQ<25>")
	)
	(segment
		(start 79.52994 -240.761774)
		(end 79.538322 -240.756948)
		(width 0.0889)
		(layer "In6.Cu")
		(net "M_E_CPU1_SA_DQ<25>")
	)
	(segment
		(start 81.044034 -240.756948)
		(end 81.052416 -240.761774)
		(width 0.0889)
		(layer "In6.Cu")
		(net "M_E_CPU1_SA_DQ<25>")
	)
	(segment
		(start 53.23459 -226.660456)
		(end 54.084474 -227.51034)
		(width 0.14478)
		(layer "In6.Cu")
		(net "M_E_CPU1_SA_DQ<25>")
	)
	(segment
		(start 65.198498 -233.624374)
		(end 65.752472 -233.623358)
		(width 0.14478)
		(layer "In6.Cu")
		(net "M_E_CPU1_SA_DQ<25>")
	)
	(segment
		(start 30.830266 -227.283264)
		(end 30.993334 -227.120196)
		(width 0.14478)
		(layer "In6.Cu")
		(net "M_E_CPU1_SA_DQ<25>")
	)
	(segment
		(start 40.695118 -227.51034)
		(end 40.858186 -227.673408)
		(width 0.14478)
		(layer "In6.Cu")
		(net "M_E_CPU1_SA_DQ<25>")
	)
	(segment
		(start 82.302604 -240.78311)
		(end 82.324956 -240.699798)
		(width 0.0889)
		(layer "In6.Cu")
		(net "M_E_CPU1_SA_DQ<25>")
	)
	(segment
		(start 38.01491 -226.660456)
		(end 38.864794 -227.51034)
		(width 0.14478)
		(layer "In6.Cu")
		(net "M_E_CPU1_SA_DQ<25>")
	)
	(segment
		(start 60.145422 -227.776024)
		(end 64.303402 -231.934004)
		(width 0.14478)
		(layer "In6.Cu")
		(net "M_E_CPU1_SA_DQ<25>")
	)
	(segment
		(start 31.943294 -227.737416)
		(end 31.943294 -227.673408)
		(width 0.14478)
		(layer "In6.Cu")
		(net "M_E_CPU1_SA_DQ<25>")
	)
	(segment
		(start 76.387706 -239.363504)
		(end 76.484226 -239.460024)
		(width 0.0889)
		(layer "In6.Cu")
		(net "M_E_CPU1_SA_DQ<25>")
	)
	(segment
		(start 79.154274 -240.750852)
		(end 79.164688 -240.756948)
		(width 0.0889)
		(layer "In6.Cu")
		(net "M_E_CPU1_SA_DQ<25>")
	)
	(segment
		(start 49.29632 -227.673408)
		(end 49.459388 -227.51034)
		(width 0.14478)
		(layer "In6.Cu")
		(net "M_E_CPU1_SA_DQ<25>")
	)
	(segment
		(start 40.858186 -227.673408)
		(end 40.858186 -227.734876)
		(width 0.14478)
		(layer "In6.Cu")
		(net "M_E_CPU1_SA_DQ<25>")
	)
	(segment
		(start 66.02857 -234.453938)
		(end 66.336418 -234.761786)
		(width 0.14478)
		(layer "In6.Cu")
		(net "M_E_CPU1_SA_DQ<25>")
	)
	(segment
		(start 55.062374 -227.897944)
		(end 55.292752 -227.897944)
		(width 0.14478)
		(layer "In6.Cu")
		(net "M_E_CPU1_SA_DQ<25>")
	)
	(arc
		(start 81.052416 -240.761774)
		(mid 81.235924 -240.807268)
		(end 81.418176 -240.756948)
		(width 0.0889)
		(layer "In6.Cu")
		(net "M_E_CPU1_SA_DQ<25>")
	)
	(arc
		(start 80.10398 -240.756948)
		(mid 80.286231 -240.807298)
		(end 80.46974 -240.761774)
		(width 0.0889)
		(layer "In6.Cu")
		(net "M_E_CPU1_SA_DQ<25>")
	)
	(arc
		(start 81.418176 -240.756948)
		(mid 81.701132 -240.680771)
		(end 81.984088 -240.756948)
		(width 0.0889)
		(layer "In6.Cu")
		(net "M_E_CPU1_SA_DQ<25>")
	)
	(arc
		(start 81.984088 -240.756948)
		(mid 82.140407 -240.805943)
		(end 82.302604 -240.78311)
		(width 0.0889)
		(layer "In6.Cu")
		(net "M_E_CPU1_SA_DQ<25>")
	)
	(arc
		(start 80.478122 -240.756948)
		(mid 80.761078 -240.680771)
		(end 81.044034 -240.756948)
		(width 0.0889)
		(layer "In6.Cu")
		(net "M_E_CPU1_SA_DQ<25>")
	)
	(arc
		(start 79.164688 -240.756948)
		(mid 79.346685 -240.80717)
		(end 79.52994 -240.761774)
		(width 0.0889)
		(layer "In6.Cu")
		(net "M_E_CPU1_SA_DQ<25>")
	)
	(arc
		(start 78.242668 -240.767108)
		(mid 78.421897 -240.807261)
		(end 78.598522 -240.756948)
		(width 0.0889)
		(layer "In6.Cu")
		(net "M_E_CPU1_SA_DQ<25>")
	)
	(arc
		(start 78.598522 -240.756948)
		(mid 78.875589 -240.680677)
		(end 79.154274 -240.750852)
		(width 0.0889)
		(layer "In6.Cu")
		(net "M_E_CPU1_SA_DQ<25>")
	)
	(arc
		(start 79.548736 -240.750852)
		(mid 79.827168 -240.680754)
		(end 80.10398 -240.756948)
		(width 0.0889)
		(layer "In6.Cu")
		(net "M_E_CPU1_SA_DQ<25>")
	)
	(segment
		(start 81.22793 -239.8903)
		(end 80.761078 -239.624362)
		(width 0.10668)
		(layer "F.Cu")
		(net "M_E_CPU1_SA_DQ<24>")
	)
	(segment
		(start 33.72104 -226.198684)
		(end 33.884108 -226.035616)
		(width 0.14478)
		(layer "In6.Cu")
		(net "M_E_CPU1_SA_DQ<24>")
	)
	(segment
		(start 62.247526 -227.58781)
		(end 62.24778 -227.792534)
		(width 0.14478)
		(layer "In6.Cu")
		(net "M_E_CPU1_SA_DQ<24>")
	)
	(segment
		(start 48.755554 -226.198684)
		(end 48.985932 -226.198684)
		(width 0.14478)
		(layer "In6.Cu")
		(net "M_E_CPU1_SA_DQ<24>")
	)
	(segment
		(start 30.438852 -225.953828)
		(end 30.582108 -226.097084)
		(width 0.14478)
		(layer "In6.Cu")
		(net "M_E_CPU1_SA_DQ<24>")
	)
	(segment
		(start 46.540674 -225.810318)
		(end 48.429418 -225.810318)
		(width 0.14478)
		(layer "In6.Cu")
		(net "M_E_CPU1_SA_DQ<24>")
	)
	(segment
		(start 55.626762 -225.810318)
		(end 55.78983 -225.973386)
		(width 0.14478)
		(layer "In6.Cu")
		(net "M_E_CPU1_SA_DQ<24>")
	)
	(segment
		(start 40.818308 -226.040696)
		(end 40.981376 -226.203764)
		(width 0.14478)
		(layer "In6.Cu")
		(net "M_E_CPU1_SA_DQ<24>")
	)
	(segment
		(start 30.295596 -225.810318)
		(end 30.438852 -225.953574)
		(width 0.14478)
		(layer "In6.Cu")
		(net "M_E_CPU1_SA_DQ<24>")
	)
	(segment
		(start 29.677106 -225.810318)
		(end 30.295596 -225.810318)
		(width 0.14478)
		(layer "In6.Cu")
		(net "M_E_CPU1_SA_DQ<24>")
	)
	(segment
		(start 41.53789 -225.810318)
		(end 42.06621 -225.810318)
		(width 0.14478)
		(layer "In6.Cu")
		(net "M_E_CPU1_SA_DQ<24>")
	)
	(segment
		(start 62.24778 -227.792534)
		(end 62.03061 -228.009704)
		(width 0.14478)
		(layer "In6.Cu")
		(net "M_E_CPU1_SA_DQ<24>")
	)
	(segment
		(start 35.354514 -224.960434)
		(end 38.01491 -224.960434)
		(width 0.14478)
		(layer "In6.Cu")
		(net "M_E_CPU1_SA_DQ<24>")
	)
	(segment
		(start 58.382408 -225.105214)
		(end 58.527188 -224.960434)
		(width 0.14478)
		(layer "In6.Cu")
		(net "M_E_CPU1_SA_DQ<24>")
	)
	(segment
		(start 61.631576 -227.610924)
		(end 61.848746 -227.393754)
		(width 0.14478)
		(layer "In6.Cu")
		(net "M_E_CPU1_SA_DQ<24>")
	)
	(segment
		(start 34.047176 -225.810318)
		(end 34.50463 -225.810318)
		(width 0.14478)
		(layer "In6.Cu")
		(net "M_E_CPU1_SA_DQ<24>")
	)
	(segment
		(start 57.973468 -225.831146)
		(end 58.237628 -225.831146)
		(width 0.14478)
		(layer "In6.Cu")
		(net "M_E_CPU1_SA_DQ<24>")
	)
	(segment
		(start 30.582108 -226.097084)
		(end 30.85211 -226.097084)
		(width 0.14478)
		(layer "In6.Cu")
		(net "M_E_CPU1_SA_DQ<24>")
	)
	(segment
		(start 56.183276 -226.198684)
		(end 56.346344 -226.035616)
		(width 0.14478)
		(layer "In6.Cu")
		(net "M_E_CPU1_SA_DQ<24>")
	)
	(segment
		(start 58.382408 -225.686366)
		(end 58.382408 -225.105214)
		(width 0.14478)
		(layer "In6.Cu")
		(net "M_E_CPU1_SA_DQ<24>")
	)
	(segment
		(start 57.683908 -224.960434)
		(end 57.828688 -225.105214)
		(width 0.14478)
		(layer "In6.Cu")
		(net "M_E_CPU1_SA_DQ<24>")
	)
	(segment
		(start 55.396384 -225.810318)
		(end 55.626762 -225.810318)
		(width 0.14478)
		(layer "In6.Cu")
		(net "M_E_CPU1_SA_DQ<24>")
	)
	(segment
		(start 31.408624 -225.523552)
		(end 31.55188 -225.666808)
		(width 0.14478)
		(layer "In6.Cu")
		(net "M_E_CPU1_SA_DQ<24>")
	)
	(segment
		(start 48.985932 -226.198684)
		(end 49.149 -226.035616)
		(width 0.14478)
		(layer "In6.Cu")
		(net "M_E_CPU1_SA_DQ<24>")
	)
	(segment
		(start 30.995366 -225.666808)
		(end 31.138622 -225.523552)
		(width 0.14478)
		(layer "In6.Cu")
		(net "M_E_CPU1_SA_DQ<24>")
	)
	(segment
		(start 33.490662 -226.198684)
		(end 33.72104 -226.198684)
		(width 0.14478)
		(layer "In6.Cu")
		(net "M_E_CPU1_SA_DQ<24>")
	)
	(segment
		(start 59.636406 -224.960434)
		(end 61.20511 -226.529138)
		(width 0.14478)
		(layer "In6.Cu")
		(net "M_E_CPU1_SA_DQ<24>")
	)
	(segment
		(start 29.252164 -225.385376)
		(end 29.677106 -225.810318)
		(width 0.14478)
		(layer "In6.Cu")
		(net "M_E_CPU1_SA_DQ<24>")
	)
	(segment
		(start 45.69079 -224.960434)
		(end 46.540674 -225.810318)
		(width 0.14478)
		(layer "In6.Cu")
		(net "M_E_CPU1_SA_DQ<24>")
	)
	(segment
		(start 33.327594 -226.035616)
		(end 33.490662 -226.198684)
		(width 0.14478)
		(layer "In6.Cu")
		(net "M_E_CPU1_SA_DQ<24>")
	)
	(segment
		(start 62.03061 -228.214428)
		(end 65.26149 -231.445308)
		(width 0.14478)
		(layer "In6.Cu")
		(net "M_E_CPU1_SA_DQ<24>")
	)
	(segment
		(start 61.20511 -226.529138)
		(end 61.20511 -227.388928)
		(width 0.14478)
		(layer "In6.Cu")
		(net "M_E_CPU1_SA_DQ<24>")
	)
	(segment
		(start 58.237628 -225.831146)
		(end 58.382408 -225.686366)
		(width 0.14478)
		(layer "In6.Cu")
		(net "M_E_CPU1_SA_DQ<24>")
	)
	(segment
		(start 33.164526 -225.810318)
		(end 33.327594 -225.973386)
		(width 0.14478)
		(layer "In6.Cu")
		(net "M_E_CPU1_SA_DQ<24>")
	)
	(segment
		(start 79.623666 -239.940846)
		(end 79.63408 -239.946942)
		(width 0.0889)
		(layer "In6.Cu")
		(net "M_E_CPU1_SA_DQ<24>")
	)
	(segment
		(start 31.55188 -225.667062)
		(end 31.695136 -225.810318)
		(width 0.14478)
		(layer "In6.Cu")
		(net "M_E_CPU1_SA_DQ<24>")
	)
	(segment
		(start 57.216548 -224.960434)
		(end 57.683908 -224.960434)
		(width 0.14478)
		(layer "In6.Cu")
		(net "M_E_CPU1_SA_DQ<24>")
	)
	(segment
		(start 79.63408 -239.946942)
		(end 79.642462 -239.951768)
		(width 0.0889)
		(layer "In6.Cu")
		(net "M_E_CPU1_SA_DQ<24>")
	)
	(segment
		(start 55.78983 -225.973386)
		(end 55.78983 -226.035616)
		(width 0.14478)
		(layer "In6.Cu")
		(net "M_E_CPU1_SA_DQ<24>")
	)
	(segment
		(start 65.26149 -231.445308)
		(end 65.26149 -231.839008)
		(width 0.14478)
		(layer "In6.Cu")
		(net "M_E_CPU1_SA_DQ<24>")
	)
	(segment
		(start 49.68113 -225.810318)
		(end 50.531014 -224.960434)
		(width 0.14478)
		(layer "In6.Cu")
		(net "M_E_CPU1_SA_DQ<24>")
	)
	(segment
		(start 38.864794 -225.810318)
		(end 40.65524 -225.810318)
		(width 0.14478)
		(layer "In6.Cu")
		(net "M_E_CPU1_SA_DQ<24>")
	)
	(segment
		(start 33.884108 -225.973386)
		(end 34.047176 -225.810318)
		(width 0.14478)
		(layer "In6.Cu")
		(net "M_E_CPU1_SA_DQ<24>")
	)
	(segment
		(start 71.871586 -238.449104)
		(end 75.960986 -238.449104)
		(width 0.14478)
		(layer "In6.Cu")
		(net "M_E_CPU1_SA_DQ<24>")
	)
	(segment
		(start 41.211754 -226.203764)
		(end 41.374822 -226.040696)
		(width 0.14478)
		(layer "In6.Cu")
		(net "M_E_CPU1_SA_DQ<24>")
	)
	(segment
		(start 61.848746 -227.393754)
		(end 62.05347 -227.393754)
		(width 0.14478)
		(layer "In6.Cu")
		(net "M_E_CPU1_SA_DQ<24>")
	)
	(segment
		(start 55.233316 -226.035616)
		(end 55.233316 -225.973386)
		(width 0.14478)
		(layer "In6.Cu")
		(net "M_E_CPU1_SA_DQ<24>")
	)
	(segment
		(start 62.05347 -227.393754)
		(end 62.247526 -227.58781)
		(width 0.14478)
		(layer "In6.Cu")
		(net "M_E_CPU1_SA_DQ<24>")
	)
	(segment
		(start 30.995366 -225.953828)
		(end 30.995366 -225.666808)
		(width 0.14478)
		(layer "In6.Cu")
		(net "M_E_CPU1_SA_DQ<24>")
	)
	(segment
		(start 62.03061 -228.009704)
		(end 62.03061 -228.214428)
		(width 0.14478)
		(layer "In6.Cu")
		(net "M_E_CPU1_SA_DQ<24>")
	)
	(segment
		(start 79.06004 -239.951768)
		(end 79.068422 -239.946942)
		(width 0.0889)
		(layer "In6.Cu")
		(net "M_E_CPU1_SA_DQ<24>")
	)
	(segment
		(start 33.884108 -226.035616)
		(end 33.884108 -225.973386)
		(width 0.14478)
		(layer "In6.Cu")
		(net "M_E_CPU1_SA_DQ<24>")
	)
	(segment
		(start 49.149 -225.973386)
		(end 49.312068 -225.810318)
		(width 0.14478)
		(layer "In6.Cu")
		(net "M_E_CPU1_SA_DQ<24>")
	)
	(segment
		(start 48.592486 -225.973386)
		(end 48.592486 -226.035616)
		(width 0.14478)
		(layer "In6.Cu")
		(net "M_E_CPU1_SA_DQ<24>")
	)
	(segment
		(start 50.531014 -224.960434)
		(end 53.23459 -224.960434)
		(width 0.14478)
		(layer "In6.Cu")
		(net "M_E_CPU1_SA_DQ<24>")
	)
	(segment
		(start 49.149 -226.035616)
		(end 49.149 -225.973386)
		(width 0.14478)
		(layer "In6.Cu")
		(net "M_E_CPU1_SA_DQ<24>")
	)
	(segment
		(start 57.828688 -225.105214)
		(end 57.828688 -225.686366)
		(width 0.14478)
		(layer "In6.Cu")
		(net "M_E_CPU1_SA_DQ<24>")
	)
	(segment
		(start 31.695136 -225.810318)
		(end 33.164526 -225.810318)
		(width 0.14478)
		(layer "In6.Cu")
		(net "M_E_CPU1_SA_DQ<24>")
	)
	(segment
		(start 78.172564 -239.870742)
		(end 78.41107 -239.870742)
		(width 0.0889)
		(layer "In6.Cu")
		(net "M_E_CPU1_SA_DQ<24>")
	)
	(segment
		(start 48.429418 -225.810318)
		(end 48.592486 -225.973386)
		(width 0.14478)
		(layer "In6.Cu")
		(net "M_E_CPU1_SA_DQ<24>")
	)
	(segment
		(start 76.629006 -238.649764)
		(end 76.951586 -238.649764)
		(width 0.0889)
		(layer "In6.Cu")
		(net "M_E_CPU1_SA_DQ<24>")
	)
	(segment
		(start 30.438852 -225.953574)
		(end 30.438852 -225.953828)
		(width 0.14478)
		(layer "In6.Cu")
		(net "M_E_CPU1_SA_DQ<24>")
	)
	(segment
		(start 33.327594 -225.973386)
		(end 33.327594 -226.035616)
		(width 0.14478)
		(layer "In6.Cu")
		(net "M_E_CPU1_SA_DQ<24>")
	)
	(segment
		(start 41.374822 -226.040696)
		(end 41.374822 -225.973386)
		(width 0.14478)
		(layer "In6.Cu")
		(net "M_E_CPU1_SA_DQ<24>")
	)
	(segment
		(start 61.42736 -227.611178)
		(end 61.631576 -227.610924)
		(width 0.14478)
		(layer "In6.Cu")
		(net "M_E_CPU1_SA_DQ<24>")
	)
	(segment
		(start 55.952898 -226.198684)
		(end 56.183276 -226.198684)
		(width 0.14478)
		(layer "In6.Cu")
		(net "M_E_CPU1_SA_DQ<24>")
	)
	(segment
		(start 54.676802 -225.973386)
		(end 54.676802 -226.035616)
		(width 0.14478)
		(layer "In6.Cu")
		(net "M_E_CPU1_SA_DQ<24>")
	)
	(segment
		(start 80.89265 -239.973104)
		(end 80.915002 -239.889792)
		(width 0.0889)
		(layer "In6.Cu")
		(net "M_E_CPU1_SA_DQ<24>")
	)
	(segment
		(start 55.78983 -226.035616)
		(end 55.952898 -226.198684)
		(width 0.14478)
		(layer "In6.Cu")
		(net "M_E_CPU1_SA_DQ<24>")
	)
	(segment
		(start 30.85211 -226.097084)
		(end 30.995366 -225.953828)
		(width 0.14478)
		(layer "In6.Cu")
		(net "M_E_CPU1_SA_DQ<24>")
	)
	(segment
		(start 54.676802 -226.035616)
		(end 54.83987 -226.198684)
		(width 0.14478)
		(layer "In6.Cu")
		(net "M_E_CPU1_SA_DQ<24>")
	)
	(segment
		(start 57.828688 -225.686366)
		(end 57.973468 -225.831146)
		(width 0.14478)
		(layer "In6.Cu")
		(net "M_E_CPU1_SA_DQ<24>")
	)
	(segment
		(start 54.513734 -225.810318)
		(end 54.676802 -225.973386)
		(width 0.14478)
		(layer "In6.Cu")
		(net "M_E_CPU1_SA_DQ<24>")
	)
	(segment
		(start 76.428346 -238.449104)
		(end 76.629006 -238.649764)
		(width 0.0889)
		(layer "In6.Cu")
		(net "M_E_CPU1_SA_DQ<24>")
	)
	(segment
		(start 76.951586 -238.649764)
		(end 78.172564 -239.870742)
		(width 0.0889)
		(layer "In6.Cu")
		(net "M_E_CPU1_SA_DQ<24>")
	)
	(segment
		(start 80.915002 -239.889792)
		(end 80.761078 -239.624362)
		(width 0.0889)
		(layer "In6.Cu")
		(net "M_E_CPU1_SA_DQ<24>")
	)
	(segment
		(start 49.312068 -225.810318)
		(end 49.68113 -225.810318)
		(width 0.14478)
		(layer "In6.Cu")
		(net "M_E_CPU1_SA_DQ<24>")
	)
	(segment
		(start 55.070248 -226.198684)
		(end 55.233316 -226.035616)
		(width 0.14478)
		(layer "In6.Cu")
		(net "M_E_CPU1_SA_DQ<24>")
	)
	(segment
		(start 38.01491 -224.960434)
		(end 38.864794 -225.810318)
		(width 0.14478)
		(layer "In6.Cu")
		(net "M_E_CPU1_SA_DQ<24>")
	)
	(segment
		(start 65.26149 -231.839008)
		(end 71.871586 -238.449104)
		(width 0.14478)
		(layer "In6.Cu")
		(net "M_E_CPU1_SA_DQ<24>")
	)
	(segment
		(start 40.981376 -226.203764)
		(end 41.211754 -226.203764)
		(width 0.14478)
		(layer "In6.Cu")
		(net "M_E_CPU1_SA_DQ<24>")
	)
	(segment
		(start 34.50463 -225.810318)
		(end 35.354514 -224.960434)
		(width 0.14478)
		(layer "In6.Cu")
		(net "M_E_CPU1_SA_DQ<24>")
	)
	(segment
		(start 31.138622 -225.523552)
		(end 31.408624 -225.523552)
		(width 0.14478)
		(layer "In6.Cu")
		(net "M_E_CPU1_SA_DQ<24>")
	)
	(segment
		(start 31.55188 -225.666808)
		(end 31.55188 -225.667062)
		(width 0.14478)
		(layer "In6.Cu")
		(net "M_E_CPU1_SA_DQ<24>")
	)
	(segment
		(start 75.960986 -238.449104)
		(end 76.428346 -238.449104)
		(width 0.0889)
		(layer "In6.Cu")
		(net "M_E_CPU1_SA_DQ<24>")
	)
	(segment
		(start 40.818308 -225.973386)
		(end 40.818308 -226.040696)
		(width 0.14478)
		(layer "In6.Cu")
		(net "M_E_CPU1_SA_DQ<24>")
	)
	(segment
		(start 54.83987 -226.198684)
		(end 55.070248 -226.198684)
		(width 0.14478)
		(layer "In6.Cu")
		(net "M_E_CPU1_SA_DQ<24>")
	)
	(segment
		(start 56.346344 -225.830638)
		(end 57.216548 -224.960434)
		(width 0.14478)
		(layer "In6.Cu")
		(net "M_E_CPU1_SA_DQ<24>")
	)
	(segment
		(start 55.233316 -225.973386)
		(end 55.396384 -225.810318)
		(width 0.14478)
		(layer "In6.Cu")
		(net "M_E_CPU1_SA_DQ<24>")
	)
	(segment
		(start 58.527188 -224.960434)
		(end 59.636406 -224.960434)
		(width 0.14478)
		(layer "In6.Cu")
		(net "M_E_CPU1_SA_DQ<24>")
	)
	(segment
		(start 40.65524 -225.810318)
		(end 40.818308 -225.973386)
		(width 0.14478)
		(layer "In6.Cu")
		(net "M_E_CPU1_SA_DQ<24>")
	)
	(segment
		(start 56.346344 -226.035616)
		(end 56.346344 -225.830638)
		(width 0.14478)
		(layer "In6.Cu")
		(net "M_E_CPU1_SA_DQ<24>")
	)
	(segment
		(start 48.592486 -226.035616)
		(end 48.755554 -226.198684)
		(width 0.14478)
		(layer "In6.Cu")
		(net "M_E_CPU1_SA_DQ<24>")
	)
	(segment
		(start 42.06621 -225.810318)
		(end 42.916094 -224.960434)
		(width 0.14478)
		(layer "In6.Cu")
		(net "M_E_CPU1_SA_DQ<24>")
	)
	(segment
		(start 42.916094 -224.960434)
		(end 45.69079 -224.960434)
		(width 0.14478)
		(layer "In6.Cu")
		(net "M_E_CPU1_SA_DQ<24>")
	)
	(segment
		(start 41.374822 -225.973386)
		(end 41.53789 -225.810318)
		(width 0.14478)
		(layer "In6.Cu")
		(net "M_E_CPU1_SA_DQ<24>")
	)
	(segment
		(start 61.20511 -227.388928)
		(end 61.42736 -227.611178)
		(width 0.14478)
		(layer "In6.Cu")
		(net "M_E_CPU1_SA_DQ<24>")
	)
	(segment
		(start 54.084474 -225.810318)
		(end 54.513734 -225.810318)
		(width 0.14478)
		(layer "In6.Cu")
		(net "M_E_CPU1_SA_DQ<24>")
	)
	(segment
		(start 53.23459 -224.960434)
		(end 54.084474 -225.810318)
		(width 0.14478)
		(layer "In6.Cu")
		(net "M_E_CPU1_SA_DQ<24>")
	)
	(arc
		(start 80.574134 -239.946942)
		(mid 80.730453 -239.995937)
		(end 80.89265 -239.973104)
		(width 0.0889)
		(layer "In6.Cu")
		(net "M_E_CPU1_SA_DQ<24>")
	)
	(arc
		(start 79.068422 -239.946942)
		(mid 79.345235 -239.870799)
		(end 79.623666 -239.940846)
		(width 0.0889)
		(layer "In6.Cu")
		(net "M_E_CPU1_SA_DQ<24>")
	)
	(arc
		(start 80.008222 -239.946942)
		(mid 80.291178 -239.870765)
		(end 80.574134 -239.946942)
		(width 0.0889)
		(layer "In6.Cu")
		(net "M_E_CPU1_SA_DQ<24>")
	)
	(arc
		(start 78.41107 -239.870742)
		(mid 78.557723 -239.890087)
		(end 78.69428 -239.946942)
		(width 0.0889)
		(layer "In6.Cu")
		(net "M_E_CPU1_SA_DQ<24>")
	)
	(arc
		(start 78.69428 -239.946942)
		(mid 78.876531 -239.997292)
		(end 79.06004 -239.951768)
		(width 0.0889)
		(layer "In6.Cu")
		(net "M_E_CPU1_SA_DQ<24>")
	)
	(arc
		(start 79.642462 -239.951768)
		(mid 79.82597 -239.997262)
		(end 80.008222 -239.946942)
		(width 0.0889)
		(layer "In6.Cu")
		(net "M_E_CPU1_SA_DQ<24>")
	)
	(segment
		(start 83.107784 -239.8903)
		(end 82.640932 -239.624362)
		(width 0.10668)
		(layer "F.Cu")
		(net "M_E_CPU1_SA_DQ<23>")
	)
	(segment
		(start 35.41141 -224.110296)
		(end 38.0238 -224.110296)
		(width 0.14478)
		(layer "In6.Cu")
		(net "M_E_CPU1_SA_DQ<23>")
	)
	(segment
		(start 38.873938 -224.960434)
		(end 42.013886 -224.960434)
		(width 0.14478)
		(layer "In6.Cu")
		(net "M_E_CPU1_SA_DQ<23>")
	)
	(segment
		(start 27.960828 -224.797366)
		(end 28.123896 -224.960434)
		(width 0.14478)
		(layer "In6.Cu")
		(net "M_E_CPU1_SA_DQ<23>")
	)
	(segment
		(start 78.128622 -239.302036)
		(end 78.14056 -239.308894)
		(width 0.0889)
		(layer "In6.Cu")
		(net "M_E_CPU1_SA_DQ<23>")
	)
	(segment
		(start 42.013886 -224.960434)
		(end 42.864024 -224.110296)
		(width 0.14478)
		(layer "In6.Cu")
		(net "M_E_CPU1_SA_DQ<23>")
	)
	(segment
		(start 57.8993 -224.225866)
		(end 58.01487 -224.110296)
		(width 0.14478)
		(layer "In6.Cu")
		(net "M_E_CPU1_SA_DQ<23>")
	)
	(segment
		(start 77.004926 -237.892844)
		(end 77.464666 -238.352584)
		(width 0.0889)
		(layer "In6.Cu")
		(net "M_E_CPU1_SA_DQ<23>")
	)
	(segment
		(start 26.8478 -224.322132)
		(end 26.8478 -224.797366)
		(width 0.14478)
		(layer "In6.Cu")
		(net "M_E_CPU1_SA_DQ<23>")
	)
	(segment
		(start 62.79896 -228.179122)
		(end 65.81775 -231.197912)
		(width 0.14478)
		(layer "In6.Cu")
		(net "M_E_CPU1_SA_DQ<23>")
	)
	(segment
		(start 27.960828 -224.322132)
		(end 27.960828 -224.797366)
		(width 0.14478)
		(layer "In6.Cu")
		(net "M_E_CPU1_SA_DQ<23>")
	)
	(segment
		(start 60.19165 -224.594166)
		(end 60.19165 -224.736152)
		(width 0.14478)
		(layer "In6.Cu")
		(net "M_E_CPU1_SA_DQ<23>")
	)
	(segment
		(start 58.01487 -224.110296)
		(end 59.70778 -224.110296)
		(width 0.14478)
		(layer "In6.Cu")
		(net "M_E_CPU1_SA_DQ<23>")
	)
	(segment
		(start 26.8478 -224.797366)
		(end 27.010868 -224.960434)
		(width 0.14478)
		(layer "In6.Cu")
		(net "M_E_CPU1_SA_DQ<23>")
	)
	(segment
		(start 28.123896 -224.960434)
		(end 34.561272 -224.960434)
		(width 0.14478)
		(layer "In6.Cu")
		(net "M_E_CPU1_SA_DQ<23>")
	)
	(segment
		(start 27.404314 -224.322132)
		(end 27.567382 -224.159064)
		(width 0.14478)
		(layer "In6.Cu")
		(net "M_E_CPU1_SA_DQ<23>")
	)
	(segment
		(start 34.561272 -224.960434)
		(end 35.41141 -224.110296)
		(width 0.14478)
		(layer "In6.Cu")
		(net "M_E_CPU1_SA_DQ<23>")
	)
	(segment
		(start 27.567382 -224.159064)
		(end 27.79776 -224.159064)
		(width 0.14478)
		(layer "In6.Cu")
		(net "M_E_CPU1_SA_DQ<23>")
	)
	(segment
		(start 72.108822 -237.892844)
		(end 75.948286 -237.892844)
		(width 0.14478)
		(layer "In6.Cu")
		(net "M_E_CPU1_SA_DQ<23>")
	)
	(segment
		(start 45.712634 -224.110296)
		(end 46.562772 -224.960434)
		(width 0.14478)
		(layer "In6.Cu")
		(net "M_E_CPU1_SA_DQ<23>")
	)
	(segment
		(start 25.152096 -224.535238)
		(end 25.577292 -224.960434)
		(width 0.14478)
		(layer "In6.Cu")
		(net "M_E_CPU1_SA_DQ<23>")
	)
	(segment
		(start 77.464666 -238.352584)
		(end 77.464666 -238.780828)
		(width 0.0889)
		(layer "In6.Cu")
		(net "M_E_CPU1_SA_DQ<23>")
	)
	(segment
		(start 79.62392 -239.307878)
		(end 79.634334 -239.301782)
		(width 0.0889)
		(layer "In6.Cu")
		(net "M_E_CPU1_SA_DQ<23>")
	)
	(segment
		(start 53.256434 -224.110296)
		(end 54.106572 -224.960434)
		(width 0.14478)
		(layer "In6.Cu")
		(net "M_E_CPU1_SA_DQ<23>")
	)
	(segment
		(start 79.056992 -239.294924)
		(end 79.068676 -239.301782)
		(width 0.0889)
		(layer "In6.Cu")
		(net "M_E_CPU1_SA_DQ<23>")
	)
	(segment
		(start 57.14365 -224.225866)
		(end 57.8993 -224.225866)
		(width 0.14478)
		(layer "In6.Cu")
		(net "M_E_CPU1_SA_DQ<23>")
	)
	(segment
		(start 82.487008 -239.358932)
		(end 82.640932 -239.624362)
		(width 0.0889)
		(layer "In6.Cu")
		(net "M_E_CPU1_SA_DQ<23>")
	)
	(segment
		(start 42.864024 -224.110296)
		(end 45.712634 -224.110296)
		(width 0.14478)
		(layer "In6.Cu")
		(net "M_E_CPU1_SA_DQ<23>")
	)
	(segment
		(start 50.47107 -224.110296)
		(end 53.256434 -224.110296)
		(width 0.14478)
		(layer "In6.Cu")
		(net "M_E_CPU1_SA_DQ<23>")
	)
	(segment
		(start 81.879694 -239.296956)
		(end 81.888076 -239.301782)
		(width 0.0889)
		(layer "In6.Cu")
		(net "M_E_CPU1_SA_DQ<23>")
	)
	(segment
		(start 75.948286 -237.892844)
		(end 77.004926 -237.892844)
		(width 0.0889)
		(layer "In6.Cu")
		(net "M_E_CPU1_SA_DQ<23>")
	)
	(segment
		(start 27.010868 -224.960434)
		(end 27.241246 -224.960434)
		(width 0.14478)
		(layer "In6.Cu")
		(net "M_E_CPU1_SA_DQ<23>")
	)
	(segment
		(start 27.404314 -224.797366)
		(end 27.404314 -224.322132)
		(width 0.14478)
		(layer "In6.Cu")
		(net "M_E_CPU1_SA_DQ<23>")
	)
	(segment
		(start 65.81775 -231.601772)
		(end 72.108822 -237.892844)
		(width 0.14478)
		(layer "In6.Cu")
		(net "M_E_CPU1_SA_DQ<23>")
	)
	(segment
		(start 25.577292 -224.960434)
		(end 26.128218 -224.960434)
		(width 0.14478)
		(layer "In6.Cu")
		(net "M_E_CPU1_SA_DQ<23>")
	)
	(segment
		(start 26.291286 -224.797366)
		(end 26.291286 -224.322132)
		(width 0.14478)
		(layer "In6.Cu")
		(net "M_E_CPU1_SA_DQ<23>")
	)
	(segment
		(start 60.19165 -224.736152)
		(end 62.79896 -227.343462)
		(width 0.14478)
		(layer "In6.Cu")
		(net "M_E_CPU1_SA_DQ<23>")
	)
	(segment
		(start 27.241246 -224.960434)
		(end 27.404314 -224.797366)
		(width 0.14478)
		(layer "In6.Cu")
		(net "M_E_CPU1_SA_DQ<23>")
	)
	(segment
		(start 77.941424 -239.257586)
		(end 77.961998 -239.257586)
		(width 0.0889)
		(layer "In6.Cu")
		(net "M_E_CPU1_SA_DQ<23>")
	)
	(segment
		(start 62.79896 -227.343462)
		(end 62.79896 -228.179122)
		(width 0.14478)
		(layer "In6.Cu")
		(net "M_E_CPU1_SA_DQ<23>")
	)
	(segment
		(start 26.291286 -224.322132)
		(end 26.454354 -224.159064)
		(width 0.14478)
		(layer "In6.Cu")
		(net "M_E_CPU1_SA_DQ<23>")
	)
	(segment
		(start 77.464666 -238.780828)
		(end 77.941424 -239.257586)
		(width 0.0889)
		(layer "In6.Cu")
		(net "M_E_CPU1_SA_DQ<23>")
	)
	(segment
		(start 26.684732 -224.159064)
		(end 26.8478 -224.322132)
		(width 0.14478)
		(layer "In6.Cu")
		(net "M_E_CPU1_SA_DQ<23>")
	)
	(segment
		(start 79.634334 -239.301782)
		(end 79.646018 -239.294924)
		(width 0.0889)
		(layer "In6.Cu")
		(net "M_E_CPU1_SA_DQ<23>")
	)
	(segment
		(start 65.81775 -231.197912)
		(end 65.81775 -231.601772)
		(width 0.14478)
		(layer "In6.Cu")
		(net "M_E_CPU1_SA_DQ<23>")
	)
	(segment
		(start 54.106572 -224.960434)
		(end 56.409082 -224.960434)
		(width 0.14478)
		(layer "In6.Cu")
		(net "M_E_CPU1_SA_DQ<23>")
	)
	(segment
		(start 26.128218 -224.960434)
		(end 26.291286 -224.797366)
		(width 0.14478)
		(layer "In6.Cu")
		(net "M_E_CPU1_SA_DQ<23>")
	)
	(segment
		(start 49.620932 -224.960434)
		(end 50.47107 -224.110296)
		(width 0.14478)
		(layer "In6.Cu")
		(net "M_E_CPU1_SA_DQ<23>")
	)
	(segment
		(start 46.562772 -224.960434)
		(end 49.620932 -224.960434)
		(width 0.14478)
		(layer "In6.Cu")
		(net "M_E_CPU1_SA_DQ<23>")
	)
	(segment
		(start 59.70778 -224.110296)
		(end 60.19165 -224.594166)
		(width 0.14478)
		(layer "In6.Cu")
		(net "M_E_CPU1_SA_DQ<23>")
	)
	(segment
		(start 56.409082 -224.960434)
		(end 57.14365 -224.225866)
		(width 0.14478)
		(layer "In6.Cu")
		(net "M_E_CPU1_SA_DQ<23>")
	)
	(segment
		(start 26.454354 -224.159064)
		(end 26.684732 -224.159064)
		(width 0.14478)
		(layer "In6.Cu")
		(net "M_E_CPU1_SA_DQ<23>")
	)
	(segment
		(start 27.79776 -224.159064)
		(end 27.960828 -224.322132)
		(width 0.14478)
		(layer "In6.Cu")
		(net "M_E_CPU1_SA_DQ<23>")
	)
	(segment
		(start 82.390996 -239.333532)
		(end 82.487008 -239.358932)
		(width 0.0889)
		(layer "In6.Cu")
		(net "M_E_CPU1_SA_DQ<23>")
	)
	(segment
		(start 38.0238 -224.110296)
		(end 38.873938 -224.960434)
		(width 0.14478)
		(layer "In6.Cu")
		(net "M_E_CPU1_SA_DQ<23>")
	)
	(arc
		(start 78.14056 -239.308894)
		(mid 78.418348 -239.377996)
		(end 78.69428 -239.301782)
		(width 0.0889)
		(layer "In6.Cu")
		(net "M_E_CPU1_SA_DQ<23>")
	)
	(arc
		(start 79.646018 -239.294924)
		(mid 79.828019 -239.251391)
		(end 80.008222 -239.301782)
		(width 0.0889)
		(layer "In6.Cu")
		(net "M_E_CPU1_SA_DQ<23>")
	)
	(arc
		(start 81.888076 -239.301782)
		(mid 82.135789 -239.377002)
		(end 82.390996 -239.333532)
		(width 0.0889)
		(layer "In6.Cu")
		(net "M_E_CPU1_SA_DQ<23>")
	)
	(arc
		(start 78.69428 -239.301782)
		(mid 78.874738 -239.251338)
		(end 79.056992 -239.294924)
		(width 0.0889)
		(layer "In6.Cu")
		(net "M_E_CPU1_SA_DQ<23>")
	)
	(arc
		(start 80.948022 -239.301782)
		(mid 81.230978 -239.377959)
		(end 81.513934 -239.301782)
		(width 0.0889)
		(layer "In6.Cu")
		(net "M_E_CPU1_SA_DQ<23>")
	)
	(arc
		(start 80.574134 -239.301782)
		(mid 80.761078 -239.251527)
		(end 80.948022 -239.301782)
		(width 0.0889)
		(layer "In6.Cu")
		(net "M_E_CPU1_SA_DQ<23>")
	)
	(arc
		(start 79.068676 -239.301782)
		(mid 79.345489 -239.377925)
		(end 79.62392 -239.307878)
		(width 0.0889)
		(layer "In6.Cu")
		(net "M_E_CPU1_SA_DQ<23>")
	)
	(arc
		(start 77.961998 -239.257586)
		(mid 78.048223 -239.26889)
		(end 78.128622 -239.302036)
		(width 0.0889)
		(layer "In6.Cu")
		(net "M_E_CPU1_SA_DQ<23>")
	)
	(arc
		(start 80.008222 -239.301782)
		(mid 80.291178 -239.377959)
		(end 80.574134 -239.301782)
		(width 0.0889)
		(layer "In6.Cu")
		(net "M_E_CPU1_SA_DQ<23>")
	)
	(arc
		(start 81.513934 -239.301782)
		(mid 81.696185 -239.251432)
		(end 81.879694 -239.296956)
		(width 0.0889)
		(layer "In6.Cu")
		(net "M_E_CPU1_SA_DQ<23>")
	)
	(segment
		(start 81.69783 -239.080294)
		(end 81.230978 -238.814356)
		(width 0.10668)
		(layer "F.Cu")
		(net "M_E_CPU1_SA_DQ<22>")
	)
	(segment
		(start 80.093566 -238.497872)
		(end 80.10398 -238.491776)
		(width 0.0889)
		(layer "In6.Cu")
		(net "M_E_CPU1_SA_DQ<22>")
	)
	(segment
		(start 25.577292 -223.260412)
		(end 26.472896 -223.260412)
		(width 0.14478)
		(layer "In6.Cu")
		(net "M_E_CPU1_SA_DQ<22>")
	)
	(segment
		(start 63.69812 -226.78771)
		(end 63.69812 -227.792026)
		(width 0.14478)
		(layer "In6.Cu")
		(net "M_E_CPU1_SA_DQ<22>")
	)
	(segment
		(start 78.193392 -238.44123)
		(end 78.41107 -238.44123)
		(width 0.0889)
		(layer "In6.Cu")
		(net "M_E_CPU1_SA_DQ<22>")
	)
	(segment
		(start 26.635964 -222.678752)
		(end 26.799032 -222.515684)
		(width 0.14478)
		(layer "In6.Cu")
		(net "M_E_CPU1_SA_DQ<22>")
	)
	(segment
		(start 26.799032 -222.515684)
		(end 27.02941 -222.515684)
		(width 0.14478)
		(layer "In6.Cu")
		(net "M_E_CPU1_SA_DQ<22>")
	)
	(segment
		(start 26.635964 -223.097344)
		(end 26.635964 -222.678752)
		(width 0.14478)
		(layer "In6.Cu")
		(net "M_E_CPU1_SA_DQ<22>")
	)
	(segment
		(start 27.02941 -222.515684)
		(end 27.192478 -222.678752)
		(width 0.14478)
		(layer "In6.Cu")
		(net "M_E_CPU1_SA_DQ<22>")
	)
	(segment
		(start 28.305506 -223.097344)
		(end 28.468574 -223.260412)
		(width 0.14478)
		(layer "In6.Cu")
		(net "M_E_CPU1_SA_DQ<22>")
	)
	(segment
		(start 53.256434 -222.410274)
		(end 54.106572 -223.260412)
		(width 0.14478)
		(layer "In6.Cu")
		(net "M_E_CPU1_SA_DQ<22>")
	)
	(segment
		(start 78.59776 -238.49203)
		(end 78.603348 -238.495332)
		(width 0.0889)
		(layer "In6.Cu")
		(net "M_E_CPU1_SA_DQ<22>")
	)
	(segment
		(start 72.478646 -236.983524)
		(end 75.953366 -236.983524)
		(width 0.14478)
		(layer "In6.Cu")
		(net "M_E_CPU1_SA_DQ<22>")
	)
	(segment
		(start 27.192478 -223.097344)
		(end 27.355546 -223.260412)
		(width 0.14478)
		(layer "In6.Cu")
		(net "M_E_CPU1_SA_DQ<22>")
	)
	(segment
		(start 42.013886 -223.260412)
		(end 42.864024 -222.410274)
		(width 0.14478)
		(layer "In6.Cu")
		(net "M_E_CPU1_SA_DQ<22>")
	)
	(segment
		(start 49.620932 -223.260412)
		(end 50.47107 -222.410274)
		(width 0.14478)
		(layer "In6.Cu")
		(net "M_E_CPU1_SA_DQ<22>")
	)
	(segment
		(start 27.91206 -221.893384)
		(end 28.142438 -221.893384)
		(width 0.14478)
		(layer "In6.Cu")
		(net "M_E_CPU1_SA_DQ<22>")
	)
	(segment
		(start 50.47107 -222.410274)
		(end 53.256434 -222.410274)
		(width 0.14478)
		(layer "In6.Cu")
		(net "M_E_CPU1_SA_DQ<22>")
	)
	(segment
		(start 80.46974 -238.48695)
		(end 80.478122 -238.491776)
		(width 0.0889)
		(layer "In6.Cu")
		(net "M_E_CPU1_SA_DQ<22>")
	)
	(segment
		(start 38.0238 -222.410274)
		(end 38.873938 -223.260412)
		(width 0.14478)
		(layer "In6.Cu")
		(net "M_E_CPU1_SA_DQ<22>")
	)
	(segment
		(start 66.75501 -231.259888)
		(end 72.478646 -236.983524)
		(width 0.14478)
		(layer "In6.Cu")
		(net "M_E_CPU1_SA_DQ<22>")
	)
	(segment
		(start 46.562772 -223.260412)
		(end 49.620932 -223.260412)
		(width 0.14478)
		(layer "In6.Cu")
		(net "M_E_CPU1_SA_DQ<22>")
	)
	(segment
		(start 76.189586 -236.983524)
		(end 76.486766 -237.280704)
		(width 0.0889)
		(layer "In6.Cu")
		(net "M_E_CPU1_SA_DQ<22>")
	)
	(segment
		(start 45.712634 -222.410274)
		(end 46.562772 -223.260412)
		(width 0.14478)
		(layer "In6.Cu")
		(net "M_E_CPU1_SA_DQ<22>")
	)
	(segment
		(start 80.981042 -238.523526)
		(end 81.077054 -238.548926)
		(width 0.0889)
		(layer "In6.Cu")
		(net "M_E_CPU1_SA_DQ<22>")
	)
	(segment
		(start 27.355546 -223.260412)
		(end 27.585924 -223.260412)
		(width 0.14478)
		(layer "In6.Cu")
		(net "M_E_CPU1_SA_DQ<22>")
	)
	(segment
		(start 59.878214 -222.410274)
		(end 61.33211 -223.86417)
		(width 0.14478)
		(layer "In6.Cu")
		(net "M_E_CPU1_SA_DQ<22>")
	)
	(segment
		(start 54.106572 -223.260412)
		(end 57.164732 -223.260412)
		(width 0.14478)
		(layer "In6.Cu")
		(net "M_E_CPU1_SA_DQ<22>")
	)
	(segment
		(start 34.561272 -223.260412)
		(end 35.41141 -222.410274)
		(width 0.14478)
		(layer "In6.Cu")
		(net "M_E_CPU1_SA_DQ<22>")
	)
	(segment
		(start 77.032866 -237.280704)
		(end 78.193392 -238.44123)
		(width 0.0889)
		(layer "In6.Cu")
		(net "M_E_CPU1_SA_DQ<22>")
	)
	(segment
		(start 58.01487 -222.410274)
		(end 59.878214 -222.410274)
		(width 0.14478)
		(layer "In6.Cu")
		(net "M_E_CPU1_SA_DQ<22>")
	)
	(segment
		(start 75.953366 -236.983524)
		(end 76.189586 -236.983524)
		(width 0.0889)
		(layer "In6.Cu")
		(net "M_E_CPU1_SA_DQ<22>")
	)
	(segment
		(start 35.41141 -222.410274)
		(end 38.0238 -222.410274)
		(width 0.14478)
		(layer "In6.Cu")
		(net "M_E_CPU1_SA_DQ<22>")
	)
	(segment
		(start 57.164732 -223.260412)
		(end 58.01487 -222.410274)
		(width 0.14478)
		(layer "In6.Cu")
		(net "M_E_CPU1_SA_DQ<22>")
	)
	(segment
		(start 25.152096 -222.835216)
		(end 25.577292 -223.260412)
		(width 0.14478)
		(layer "In6.Cu")
		(net "M_E_CPU1_SA_DQ<22>")
	)
	(segment
		(start 79.163164 -238.491776)
		(end 79.171546 -238.48695)
		(width 0.0889)
		(layer "In6.Cu")
		(net "M_E_CPU1_SA_DQ<22>")
	)
	(segment
		(start 28.142438 -221.893384)
		(end 28.305506 -222.056452)
		(width 0.14478)
		(layer "In6.Cu")
		(net "M_E_CPU1_SA_DQ<22>")
	)
	(segment
		(start 42.864024 -222.410274)
		(end 45.712634 -222.410274)
		(width 0.14478)
		(layer "In6.Cu")
		(net "M_E_CPU1_SA_DQ<22>")
	)
	(segment
		(start 27.748992 -223.097344)
		(end 27.748992 -222.056452)
		(width 0.14478)
		(layer "In6.Cu")
		(net "M_E_CPU1_SA_DQ<22>")
	)
	(segment
		(start 61.33211 -224.4217)
		(end 63.69812 -226.78771)
		(width 0.14478)
		(layer "In6.Cu")
		(net "M_E_CPU1_SA_DQ<22>")
	)
	(segment
		(start 81.077054 -238.548926)
		(end 81.230978 -238.814356)
		(width 0.0889)
		(layer "In6.Cu")
		(net "M_E_CPU1_SA_DQ<22>")
	)
	(segment
		(start 27.585924 -223.260412)
		(end 27.748992 -223.097344)
		(width 0.14478)
		(layer "In6.Cu")
		(net "M_E_CPU1_SA_DQ<22>")
	)
	(segment
		(start 63.69812 -227.792026)
		(end 66.75501 -230.848916)
		(width 0.14478)
		(layer "In6.Cu")
		(net "M_E_CPU1_SA_DQ<22>")
	)
	(segment
		(start 38.873938 -223.260412)
		(end 42.013886 -223.260412)
		(width 0.14478)
		(layer "In6.Cu")
		(net "M_E_CPU1_SA_DQ<22>")
	)
	(segment
		(start 26.472896 -223.260412)
		(end 26.635964 -223.097344)
		(width 0.14478)
		(layer "In6.Cu")
		(net "M_E_CPU1_SA_DQ<22>")
	)
	(segment
		(start 28.305506 -222.056452)
		(end 28.305506 -223.097344)
		(width 0.14478)
		(layer "In6.Cu")
		(net "M_E_CPU1_SA_DQ<22>")
	)
	(segment
		(start 61.33211 -223.86417)
		(end 61.33211 -224.4217)
		(width 0.14478)
		(layer "In6.Cu")
		(net "M_E_CPU1_SA_DQ<22>")
	)
	(segment
		(start 28.468574 -223.260412)
		(end 34.561272 -223.260412)
		(width 0.14478)
		(layer "In6.Cu")
		(net "M_E_CPU1_SA_DQ<22>")
	)
	(segment
		(start 27.748992 -222.056452)
		(end 27.91206 -221.893384)
		(width 0.14478)
		(layer "In6.Cu")
		(net "M_E_CPU1_SA_DQ<22>")
	)
	(segment
		(start 27.192478 -222.678752)
		(end 27.192478 -223.097344)
		(width 0.14478)
		(layer "In6.Cu")
		(net "M_E_CPU1_SA_DQ<22>")
	)
	(segment
		(start 76.486766 -237.280704)
		(end 77.032866 -237.280704)
		(width 0.0889)
		(layer "In6.Cu")
		(net "M_E_CPU1_SA_DQ<22>")
	)
	(segment
		(start 66.75501 -230.848916)
		(end 66.75501 -231.259888)
		(width 0.14478)
		(layer "In6.Cu")
		(net "M_E_CPU1_SA_DQ<22>")
	)
	(arc
		(start 79.171546 -238.48695)
		(mid 79.355308 -238.441334)
		(end 79.537814 -238.491776)
		(width 0.0889)
		(layer "In6.Cu")
		(net "M_E_CPU1_SA_DQ<22>")
	)
	(arc
		(start 78.603348 -238.495332)
		(mid 78.883737 -238.568001)
		(end 79.163164 -238.491776)
		(width 0.0889)
		(layer "In6.Cu")
		(net "M_E_CPU1_SA_DQ<22>")
	)
	(arc
		(start 80.10398 -238.491776)
		(mid 80.286231 -238.441426)
		(end 80.46974 -238.48695)
		(width 0.0889)
		(layer "In6.Cu")
		(net "M_E_CPU1_SA_DQ<22>")
	)
	(arc
		(start 78.41107 -238.44123)
		(mid 78.507761 -238.454326)
		(end 78.59776 -238.49203)
		(width 0.0889)
		(layer "In6.Cu")
		(net "M_E_CPU1_SA_DQ<22>")
	)
	(arc
		(start 79.537814 -238.491776)
		(mid 79.814881 -238.568047)
		(end 80.093566 -238.497872)
		(width 0.0889)
		(layer "In6.Cu")
		(net "M_E_CPU1_SA_DQ<22>")
	)
	(arc
		(start 80.478122 -238.491776)
		(mid 80.725835 -238.566996)
		(end 80.981042 -238.523526)
		(width 0.0889)
		(layer "In6.Cu")
		(net "M_E_CPU1_SA_DQ<22>")
	)
	(segment
		(start 82.637884 -239.080294)
		(end 82.171032 -238.814356)
		(width 0.10668)
		(layer "F.Cu")
		(net "M_E_CPU1_SA_DQ<21>")
	)
	(segment
		(start 53.23459 -223.260412)
		(end 54.084474 -224.110296)
		(width 0.14478)
		(layer "In6.Cu")
		(net "M_E_CPU1_SA_DQ<21>")
	)
	(segment
		(start 56.21909 -224.496884)
		(end 56.382158 -224.333816)
		(width 0.14478)
		(layer "In6.Cu")
		(net "M_E_CPU1_SA_DQ<21>")
	)
	(segment
		(start 31.871666 -224.321116)
		(end 31.871666 -224.273364)
		(width 0.14478)
		(layer "In6.Cu")
		(net "M_E_CPU1_SA_DQ<21>")
	)
	(segment
		(start 41.876218 -224.360486)
		(end 41.876218 -223.854772)
		(width 0.14478)
		(layer "In6.Cu")
		(net "M_E_CPU1_SA_DQ<21>")
	)
	(segment
		(start 54.084474 -224.110296)
		(end 54.549548 -224.110296)
		(width 0.14478)
		(layer "In6.Cu")
		(net "M_E_CPU1_SA_DQ<21>")
	)
	(segment
		(start 80.46974 -239.141762)
		(end 80.478122 -239.136936)
		(width 0.0889)
		(layer "In6.Cu")
		(net "M_E_CPU1_SA_DQ<21>")
	)
	(segment
		(start 58.76671 -223.42348)
		(end 58.76671 -223.485456)
		(width 0.14478)
		(layer "In6.Cu")
		(net "M_E_CPU1_SA_DQ<21>")
	)
	(segment
		(start 30.921706 -223.736408)
		(end 31.152084 -223.736408)
		(width 0.14478)
		(layer "In6.Cu")
		(net "M_E_CPU1_SA_DQ<21>")
	)
	(segment
		(start 77.037946 -237.603284)
		(end 77.744066 -238.309404)
		(width 0.0889)
		(layer "In6.Cu")
		(net "M_E_CPU1_SA_DQ<21>")
	)
	(segment
		(start 31.708598 -224.484184)
		(end 31.871666 -224.321116)
		(width 0.14478)
		(layer "In6.Cu")
		(net "M_E_CPU1_SA_DQ<21>")
	)
	(segment
		(start 42.859198 -223.260412)
		(end 45.69079 -223.260412)
		(width 0.14478)
		(layer "In6.Cu")
		(net "M_E_CPU1_SA_DQ<21>")
	)
	(segment
		(start 63.24854 -227.157026)
		(end 63.24854 -227.985574)
		(width 0.14478)
		(layer "In6.Cu")
		(net "M_E_CPU1_SA_DQ<21>")
	)
	(segment
		(start 55.662576 -224.110296)
		(end 55.825644 -224.273364)
		(width 0.14478)
		(layer "In6.Cu")
		(net "M_E_CPU1_SA_DQ<21>")
	)
	(segment
		(start 66.29019 -231.431084)
		(end 72.29729 -237.438184)
		(width 0.14478)
		(layer "In6.Cu")
		(net "M_E_CPU1_SA_DQ<21>")
	)
	(segment
		(start 55.106062 -224.496884)
		(end 55.26913 -224.333816)
		(width 0.14478)
		(layer "In6.Cu")
		(net "M_E_CPU1_SA_DQ<21>")
	)
	(segment
		(start 30.039056 -224.110296)
		(end 30.202124 -224.273364)
		(width 0.14478)
		(layer "In6.Cu")
		(net "M_E_CPU1_SA_DQ<21>")
	)
	(segment
		(start 31.315152 -224.321116)
		(end 31.47822 -224.484184)
		(width 0.14478)
		(layer "In6.Cu")
		(net "M_E_CPU1_SA_DQ<21>")
	)
	(segment
		(start 82.302604 -239.163098)
		(end 82.324956 -239.079786)
		(width 0.0889)
		(layer "In6.Cu")
		(net "M_E_CPU1_SA_DQ<21>")
	)
	(segment
		(start 40.909494 -223.709992)
		(end 41.167558 -223.709992)
		(width 0.14478)
		(layer "In6.Cu")
		(net "M_E_CPU1_SA_DQ<21>")
	)
	(segment
		(start 54.875684 -224.496884)
		(end 55.106062 -224.496884)
		(width 0.14478)
		(layer "In6.Cu")
		(net "M_E_CPU1_SA_DQ<21>")
	)
	(segment
		(start 42.409618 -223.709992)
		(end 42.859198 -223.260412)
		(width 0.14478)
		(layer "In6.Cu")
		(net "M_E_CPU1_SA_DQ<21>")
	)
	(segment
		(start 58.006996 -223.072706)
		(end 58.415936 -223.072706)
		(width 0.14478)
		(layer "In6.Cu")
		(net "M_E_CPU1_SA_DQ<21>")
	)
	(segment
		(start 59.323224 -223.485456)
		(end 59.323224 -223.42348)
		(width 0.14478)
		(layer "In6.Cu")
		(net "M_E_CPU1_SA_DQ<21>")
	)
	(segment
		(start 32.034734 -224.110296)
		(end 33.556956 -224.110296)
		(width 0.14478)
		(layer "In6.Cu")
		(net "M_E_CPU1_SA_DQ<21>")
	)
	(segment
		(start 30.365192 -224.484184)
		(end 30.59557 -224.484184)
		(width 0.14478)
		(layer "In6.Cu")
		(net "M_E_CPU1_SA_DQ<21>")
	)
	(segment
		(start 59.71667 -223.260412)
		(end 59.879738 -223.42348)
		(width 0.14478)
		(layer "In6.Cu")
		(net "M_E_CPU1_SA_DQ<21>")
	)
	(segment
		(start 34.439606 -224.110296)
		(end 34.76625 -224.110296)
		(width 0.14478)
		(layer "In6.Cu")
		(net "M_E_CPU1_SA_DQ<21>")
	)
	(segment
		(start 33.720024 -224.341436)
		(end 33.883092 -224.504504)
		(width 0.14478)
		(layer "In6.Cu")
		(net "M_E_CPU1_SA_DQ<21>")
	)
	(segment
		(start 55.825644 -224.273364)
		(end 55.825644 -224.333816)
		(width 0.14478)
		(layer "In6.Cu")
		(net "M_E_CPU1_SA_DQ<21>")
	)
	(segment
		(start 34.76625 -224.110296)
		(end 35.03549 -223.841056)
		(width 0.14478)
		(layer "In6.Cu")
		(net "M_E_CPU1_SA_DQ<21>")
	)
	(segment
		(start 54.549548 -224.110296)
		(end 54.712616 -224.273364)
		(width 0.14478)
		(layer "In6.Cu")
		(net "M_E_CPU1_SA_DQ<21>")
	)
	(segment
		(start 54.712616 -224.273364)
		(end 54.712616 -224.333816)
		(width 0.14478)
		(layer "In6.Cu")
		(net "M_E_CPU1_SA_DQ<21>")
	)
	(segment
		(start 40.50919 -224.110296)
		(end 40.909494 -223.709992)
		(width 0.14478)
		(layer "In6.Cu")
		(net "M_E_CPU1_SA_DQ<21>")
	)
	(segment
		(start 81.044034 -239.136936)
		(end 81.052416 -239.141762)
		(width 0.0889)
		(layer "In6.Cu")
		(net "M_E_CPU1_SA_DQ<21>")
	)
	(segment
		(start 72.29729 -237.438184)
		(end 75.935586 -237.438184)
		(width 0.14478)
		(layer "In6.Cu")
		(net "M_E_CPU1_SA_DQ<21>")
	)
	(segment
		(start 76.154026 -237.438184)
		(end 76.319126 -237.603284)
		(width 0.0889)
		(layer "In6.Cu")
		(net "M_E_CPU1_SA_DQ<21>")
	)
	(segment
		(start 58.415936 -223.072706)
		(end 58.76671 -223.42348)
		(width 0.14478)
		(layer "In6.Cu")
		(net "M_E_CPU1_SA_DQ<21>")
	)
	(segment
		(start 79.52994 -239.141762)
		(end 79.538322 -239.136936)
		(width 0.0889)
		(layer "In6.Cu")
		(net "M_E_CPU1_SA_DQ<21>")
	)
	(segment
		(start 33.556956 -224.110296)
		(end 33.720024 -224.273364)
		(width 0.14478)
		(layer "In6.Cu")
		(net "M_E_CPU1_SA_DQ<21>")
	)
	(segment
		(start 77.744066 -238.309404)
		(end 77.744066 -238.656368)
		(width 0.0889)
		(layer "In6.Cu")
		(net "M_E_CPU1_SA_DQ<21>")
	)
	(segment
		(start 58.76671 -223.485456)
		(end 58.929778 -223.648524)
		(width 0.14478)
		(layer "In6.Cu")
		(net "M_E_CPU1_SA_DQ<21>")
	)
	(segment
		(start 34.276538 -224.273364)
		(end 34.439606 -224.110296)
		(width 0.14478)
		(layer "In6.Cu")
		(net "M_E_CPU1_SA_DQ<21>")
	)
	(segment
		(start 30.202124 -224.273364)
		(end 30.202124 -224.321116)
		(width 0.14478)
		(layer "In6.Cu")
		(net "M_E_CPU1_SA_DQ<21>")
	)
	(segment
		(start 56.382158 -223.958404)
		(end 56.627776 -223.712786)
		(width 0.14478)
		(layer "In6.Cu")
		(net "M_E_CPU1_SA_DQ<21>")
	)
	(segment
		(start 54.712616 -224.333816)
		(end 54.875684 -224.496884)
		(width 0.14478)
		(layer "In6.Cu")
		(net "M_E_CPU1_SA_DQ<21>")
	)
	(segment
		(start 35.50285 -222.963486)
		(end 36.10991 -222.963486)
		(width 0.14478)
		(layer "In6.Cu")
		(net "M_E_CPU1_SA_DQ<21>")
	)
	(segment
		(start 29.677106 -224.110296)
		(end 30.039056 -224.110296)
		(width 0.14478)
		(layer "In6.Cu")
		(net "M_E_CPU1_SA_DQ<21>")
	)
	(segment
		(start 31.315152 -223.899476)
		(end 31.315152 -224.321116)
		(width 0.14478)
		(layer "In6.Cu")
		(net "M_E_CPU1_SA_DQ<21>")
	)
	(segment
		(start 30.202124 -224.321116)
		(end 30.365192 -224.484184)
		(width 0.14478)
		(layer "In6.Cu")
		(net "M_E_CPU1_SA_DQ<21>")
	)
	(segment
		(start 38.01491 -223.260412)
		(end 38.864794 -224.110296)
		(width 0.14478)
		(layer "In6.Cu")
		(net "M_E_CPU1_SA_DQ<21>")
	)
	(segment
		(start 59.879738 -223.485456)
		(end 60.042806 -223.648524)
		(width 0.14478)
		(layer "In6.Cu")
		(net "M_E_CPU1_SA_DQ<21>")
	)
	(segment
		(start 41.312338 -223.854772)
		(end 41.312338 -224.360486)
		(width 0.14478)
		(layer "In6.Cu")
		(net "M_E_CPU1_SA_DQ<21>")
	)
	(segment
		(start 41.457118 -224.505266)
		(end 41.731438 -224.505266)
		(width 0.14478)
		(layer "In6.Cu")
		(net "M_E_CPU1_SA_DQ<21>")
	)
	(segment
		(start 34.276538 -224.341436)
		(end 34.276538 -224.273364)
		(width 0.14478)
		(layer "In6.Cu")
		(net "M_E_CPU1_SA_DQ<21>")
	)
	(segment
		(start 34.11347 -224.504504)
		(end 34.276538 -224.341436)
		(width 0.14478)
		(layer "In6.Cu")
		(net "M_E_CPU1_SA_DQ<21>")
	)
	(segment
		(start 35.03549 -223.841056)
		(end 35.03549 -223.430846)
		(width 0.14478)
		(layer "In6.Cu")
		(net "M_E_CPU1_SA_DQ<21>")
	)
	(segment
		(start 49.12614 -224.273364)
		(end 49.289208 -224.110296)
		(width 0.14478)
		(layer "In6.Cu")
		(net "M_E_CPU1_SA_DQ<21>")
	)
	(segment
		(start 31.871666 -224.273364)
		(end 32.034734 -224.110296)
		(width 0.14478)
		(layer "In6.Cu")
		(net "M_E_CPU1_SA_DQ<21>")
	)
	(segment
		(start 55.26913 -224.273364)
		(end 55.432198 -224.110296)
		(width 0.14478)
		(layer "In6.Cu")
		(net "M_E_CPU1_SA_DQ<21>")
	)
	(segment
		(start 30.59557 -224.484184)
		(end 30.758638 -224.321116)
		(width 0.14478)
		(layer "In6.Cu")
		(net "M_E_CPU1_SA_DQ<21>")
	)
	(segment
		(start 60.480448 -223.648524)
		(end 60.81649 -223.984566)
		(width 0.14478)
		(layer "In6.Cu")
		(net "M_E_CPU1_SA_DQ<21>")
	)
	(segment
		(start 48.732694 -224.496884)
		(end 48.963072 -224.496884)
		(width 0.14478)
		(layer "In6.Cu")
		(net "M_E_CPU1_SA_DQ<21>")
	)
	(segment
		(start 77.744066 -238.656368)
		(end 78.22438 -239.136682)
		(width 0.0889)
		(layer "In6.Cu")
		(net "M_E_CPU1_SA_DQ<21>")
	)
	(segment
		(start 82.324956 -239.079786)
		(end 82.171032 -238.814356)
		(width 0.0889)
		(layer "In6.Cu")
		(net "M_E_CPU1_SA_DQ<21>")
	)
	(segment
		(start 49.82591 -224.110296)
		(end 50.675794 -223.260412)
		(width 0.14478)
		(layer "In6.Cu")
		(net "M_E_CPU1_SA_DQ<21>")
	)
	(segment
		(start 55.432198 -224.110296)
		(end 55.662576 -224.110296)
		(width 0.14478)
		(layer "In6.Cu")
		(net "M_E_CPU1_SA_DQ<21>")
	)
	(segment
		(start 35.03549 -223.430846)
		(end 35.50285 -222.963486)
		(width 0.14478)
		(layer "In6.Cu")
		(net "M_E_CPU1_SA_DQ<21>")
	)
	(segment
		(start 55.26913 -224.333816)
		(end 55.26913 -224.273364)
		(width 0.14478)
		(layer "In6.Cu")
		(net "M_E_CPU1_SA_DQ<21>")
	)
	(segment
		(start 46.540674 -224.110296)
		(end 48.406558 -224.110296)
		(width 0.14478)
		(layer "In6.Cu")
		(net "M_E_CPU1_SA_DQ<21>")
	)
	(segment
		(start 48.569626 -224.333816)
		(end 48.732694 -224.496884)
		(width 0.14478)
		(layer "In6.Cu")
		(net "M_E_CPU1_SA_DQ<21>")
	)
	(segment
		(start 66.29019 -231.027224)
		(end 66.29019 -231.431084)
		(width 0.14478)
		(layer "In6.Cu")
		(net "M_E_CPU1_SA_DQ<21>")
	)
	(segment
		(start 75.935586 -237.438184)
		(end 76.154026 -237.438184)
		(width 0.0889)
		(layer "In6.Cu")
		(net "M_E_CPU1_SA_DQ<21>")
	)
	(segment
		(start 55.988712 -224.496884)
		(end 56.21909 -224.496884)
		(width 0.14478)
		(layer "In6.Cu")
		(net "M_E_CPU1_SA_DQ<21>")
	)
	(segment
		(start 45.69079 -223.260412)
		(end 46.540674 -224.110296)
		(width 0.14478)
		(layer "In6.Cu")
		(net "M_E_CPU1_SA_DQ<21>")
	)
	(segment
		(start 59.879738 -223.42348)
		(end 59.879738 -223.485456)
		(width 0.14478)
		(layer "In6.Cu")
		(net "M_E_CPU1_SA_DQ<21>")
	)
	(segment
		(start 31.47822 -224.484184)
		(end 31.708598 -224.484184)
		(width 0.14478)
		(layer "In6.Cu")
		(net "M_E_CPU1_SA_DQ<21>")
	)
	(segment
		(start 30.758638 -224.321116)
		(end 30.758638 -223.899476)
		(width 0.14478)
		(layer "In6.Cu")
		(net "M_E_CPU1_SA_DQ<21>")
	)
	(segment
		(start 55.825644 -224.333816)
		(end 55.988712 -224.496884)
		(width 0.14478)
		(layer "In6.Cu")
		(net "M_E_CPU1_SA_DQ<21>")
	)
	(segment
		(start 41.312338 -224.360486)
		(end 41.457118 -224.505266)
		(width 0.14478)
		(layer "In6.Cu")
		(net "M_E_CPU1_SA_DQ<21>")
	)
	(segment
		(start 41.167558 -223.709992)
		(end 41.312338 -223.854772)
		(width 0.14478)
		(layer "In6.Cu")
		(net "M_E_CPU1_SA_DQ<21>")
	)
	(segment
		(start 79.538322 -239.136936)
		(end 79.548736 -239.13084)
		(width 0.0889)
		(layer "In6.Cu")
		(net "M_E_CPU1_SA_DQ<21>")
	)
	(segment
		(start 41.876218 -223.854772)
		(end 42.020998 -223.709992)
		(width 0.14478)
		(layer "In6.Cu")
		(net "M_E_CPU1_SA_DQ<21>")
	)
	(segment
		(start 56.382158 -224.333816)
		(end 56.382158 -223.958404)
		(width 0.14478)
		(layer "In6.Cu")
		(net "M_E_CPU1_SA_DQ<21>")
	)
	(segment
		(start 36.10991 -222.963486)
		(end 36.406836 -223.260412)
		(width 0.14478)
		(layer "In6.Cu")
		(net "M_E_CPU1_SA_DQ<21>")
	)
	(segment
		(start 60.042806 -223.648524)
		(end 60.480448 -223.648524)
		(width 0.14478)
		(layer "In6.Cu")
		(net "M_E_CPU1_SA_DQ<21>")
	)
	(segment
		(start 59.323224 -223.42348)
		(end 59.486292 -223.260412)
		(width 0.14478)
		(layer "In6.Cu")
		(net "M_E_CPU1_SA_DQ<21>")
	)
	(segment
		(start 59.486292 -223.260412)
		(end 59.71667 -223.260412)
		(width 0.14478)
		(layer "In6.Cu")
		(net "M_E_CPU1_SA_DQ<21>")
	)
	(segment
		(start 60.81649 -223.984566)
		(end 60.81649 -224.724976)
		(width 0.14478)
		(layer "In6.Cu")
		(net "M_E_CPU1_SA_DQ<21>")
	)
	(segment
		(start 50.675794 -223.260412)
		(end 53.23459 -223.260412)
		(width 0.14478)
		(layer "In6.Cu")
		(net "M_E_CPU1_SA_DQ<21>")
	)
	(segment
		(start 48.963072 -224.496884)
		(end 49.12614 -224.333816)
		(width 0.14478)
		(layer "In6.Cu")
		(net "M_E_CPU1_SA_DQ<21>")
	)
	(segment
		(start 30.758638 -223.899476)
		(end 30.921706 -223.736408)
		(width 0.14478)
		(layer "In6.Cu")
		(net "M_E_CPU1_SA_DQ<21>")
	)
	(segment
		(start 42.020998 -223.709992)
		(end 42.409618 -223.709992)
		(width 0.14478)
		(layer "In6.Cu")
		(net "M_E_CPU1_SA_DQ<21>")
	)
	(segment
		(start 76.319126 -237.603284)
		(end 77.037946 -237.603284)
		(width 0.0889)
		(layer "In6.Cu")
		(net "M_E_CPU1_SA_DQ<21>")
	)
	(segment
		(start 48.569626 -224.273364)
		(end 48.569626 -224.333816)
		(width 0.14478)
		(layer "In6.Cu")
		(net "M_E_CPU1_SA_DQ<21>")
	)
	(segment
		(start 29.252164 -223.685354)
		(end 29.677106 -224.110296)
		(width 0.14478)
		(layer "In6.Cu")
		(net "M_E_CPU1_SA_DQ<21>")
	)
	(segment
		(start 58.929778 -223.648524)
		(end 59.160156 -223.648524)
		(width 0.14478)
		(layer "In6.Cu")
		(net "M_E_CPU1_SA_DQ<21>")
	)
	(segment
		(start 49.289208 -224.110296)
		(end 49.82591 -224.110296)
		(width 0.14478)
		(layer "In6.Cu")
		(net "M_E_CPU1_SA_DQ<21>")
	)
	(segment
		(start 31.152084 -223.736408)
		(end 31.315152 -223.899476)
		(width 0.14478)
		(layer "In6.Cu")
		(net "M_E_CPU1_SA_DQ<21>")
	)
	(segment
		(start 78.22438 -239.136682)
		(end 78.242668 -239.147096)
		(width 0.0889)
		(layer "In6.Cu")
		(net "M_E_CPU1_SA_DQ<21>")
	)
	(segment
		(start 63.24854 -227.985574)
		(end 66.29019 -231.027224)
		(width 0.14478)
		(layer "In6.Cu")
		(net "M_E_CPU1_SA_DQ<21>")
	)
	(segment
		(start 60.81649 -224.724976)
		(end 63.24854 -227.157026)
		(width 0.14478)
		(layer "In6.Cu")
		(net "M_E_CPU1_SA_DQ<21>")
	)
	(segment
		(start 59.160156 -223.648524)
		(end 59.323224 -223.485456)
		(width 0.14478)
		(layer "In6.Cu")
		(net "M_E_CPU1_SA_DQ<21>")
	)
	(segment
		(start 36.406836 -223.260412)
		(end 38.01491 -223.260412)
		(width 0.14478)
		(layer "In6.Cu")
		(net "M_E_CPU1_SA_DQ<21>")
	)
	(segment
		(start 57.366916 -223.712786)
		(end 58.006996 -223.072706)
		(width 0.14478)
		(layer "In6.Cu")
		(net "M_E_CPU1_SA_DQ<21>")
	)
	(segment
		(start 33.720024 -224.273364)
		(end 33.720024 -224.341436)
		(width 0.14478)
		(layer "In6.Cu")
		(net "M_E_CPU1_SA_DQ<21>")
	)
	(segment
		(start 48.406558 -224.110296)
		(end 48.569626 -224.273364)
		(width 0.14478)
		(layer "In6.Cu")
		(net "M_E_CPU1_SA_DQ<21>")
	)
	(segment
		(start 56.627776 -223.712786)
		(end 57.366916 -223.712786)
		(width 0.14478)
		(layer "In6.Cu")
		(net "M_E_CPU1_SA_DQ<21>")
	)
	(segment
		(start 33.883092 -224.504504)
		(end 34.11347 -224.504504)
		(width 0.14478)
		(layer "In6.Cu")
		(net "M_E_CPU1_SA_DQ<21>")
	)
	(segment
		(start 49.12614 -224.333816)
		(end 49.12614 -224.273364)
		(width 0.14478)
		(layer "In6.Cu")
		(net "M_E_CPU1_SA_DQ<21>")
	)
	(segment
		(start 38.864794 -224.110296)
		(end 40.50919 -224.110296)
		(width 0.14478)
		(layer "In6.Cu")
		(net "M_E_CPU1_SA_DQ<21>")
	)
	(segment
		(start 41.731438 -224.505266)
		(end 41.876218 -224.360486)
		(width 0.14478)
		(layer "In6.Cu")
		(net "M_E_CPU1_SA_DQ<21>")
	)
	(segment
		(start 79.154274 -239.13084)
		(end 79.164688 -239.136936)
		(width 0.0889)
		(layer "In6.Cu")
		(net "M_E_CPU1_SA_DQ<21>")
	)
	(arc
		(start 79.548736 -239.13084)
		(mid 79.827168 -239.060742)
		(end 80.10398 -239.136936)
		(width 0.0889)
		(layer "In6.Cu")
		(net "M_E_CPU1_SA_DQ<21>")
	)
	(arc
		(start 81.984088 -239.136936)
		(mid 82.140407 -239.185931)
		(end 82.302604 -239.163098)
		(width 0.0889)
		(layer "In6.Cu")
		(net "M_E_CPU1_SA_DQ<21>")
	)
	(arc
		(start 79.164688 -239.136936)
		(mid 79.346685 -239.187158)
		(end 79.52994 -239.141762)
		(width 0.0889)
		(layer "In6.Cu")
		(net "M_E_CPU1_SA_DQ<21>")
	)
	(arc
		(start 80.478122 -239.136936)
		(mid 80.761078 -239.060759)
		(end 81.044034 -239.136936)
		(width 0.0889)
		(layer "In6.Cu")
		(net "M_E_CPU1_SA_DQ<21>")
	)
	(arc
		(start 81.418176 -239.136936)
		(mid 81.701132 -239.060759)
		(end 81.984088 -239.136936)
		(width 0.0889)
		(layer "In6.Cu")
		(net "M_E_CPU1_SA_DQ<21>")
	)
	(arc
		(start 78.598522 -239.136936)
		(mid 78.875589 -239.060665)
		(end 79.154274 -239.13084)
		(width 0.0889)
		(layer "In6.Cu")
		(net "M_E_CPU1_SA_DQ<21>")
	)
	(arc
		(start 78.242668 -239.147096)
		(mid 78.421897 -239.187249)
		(end 78.598522 -239.136936)
		(width 0.0889)
		(layer "In6.Cu")
		(net "M_E_CPU1_SA_DQ<21>")
	)
	(arc
		(start 81.052416 -239.141762)
		(mid 81.235924 -239.187256)
		(end 81.418176 -239.136936)
		(width 0.0889)
		(layer "In6.Cu")
		(net "M_E_CPU1_SA_DQ<21>")
	)
	(arc
		(start 80.10398 -239.136936)
		(mid 80.286231 -239.187286)
		(end 80.46974 -239.141762)
		(width 0.0889)
		(layer "In6.Cu")
		(net "M_E_CPU1_SA_DQ<21>")
	)
	(segment
		(start 81.22793 -238.270288)
		(end 80.761078 -238.00435)
		(width 0.10668)
		(layer "F.Cu")
		(net "M_E_CPU1_SA_DQ<20>")
	)
	(segment
		(start 55.863236 -222.795084)
		(end 56.093614 -222.795084)
		(width 0.14478)
		(layer "In6.Cu")
		(net "M_E_CPU1_SA_DQ<20>")
	)
	(segment
		(start 78.322678 -238.25073)
		(end 78.411578 -238.25073)
		(width 0.0889)
		(layer "In6.Cu")
		(net "M_E_CPU1_SA_DQ<20>")
	)
	(segment
		(start 61.78169 -224.20072)
		(end 64.1477 -226.56673)
		(width 0.14478)
		(layer "In6.Cu")
		(net "M_E_CPU1_SA_DQ<20>")
	)
	(segment
		(start 34.031682 -222.639636)
		(end 34.031682 -222.573342)
		(width 0.14478)
		(layer "In6.Cu")
		(net "M_E_CPU1_SA_DQ<20>")
	)
	(segment
		(start 64.1477 -227.598478)
		(end 67.20459 -230.655368)
		(width 0.14478)
		(layer "In6.Cu")
		(net "M_E_CPU1_SA_DQ<20>")
	)
	(segment
		(start 33.321752 -222.419926)
		(end 33.475168 -222.573342)
		(width 0.14478)
		(layer "In6.Cu")
		(net "M_E_CPU1_SA_DQ<20>")
	)
	(segment
		(start 70.632828 -234.50169)
		(end 70.927468 -234.50169)
		(width 0.14478)
		(layer "In6.Cu")
		(net "M_E_CPU1_SA_DQ<20>")
	)
	(segment
		(start 70.927468 -234.50169)
		(end 71.178928 -234.75315)
		(width 0.14478)
		(layer "In6.Cu")
		(net "M_E_CPU1_SA_DQ<20>")
	)
	(segment
		(start 56.256682 -222.573342)
		(end 56.41975 -222.410274)
		(width 0.14478)
		(layer "In6.Cu")
		(net "M_E_CPU1_SA_DQ<20>")
	)
	(segment
		(start 55.5371 -222.139764)
		(end 55.700168 -222.302832)
		(width 0.14478)
		(layer "In6.Cu")
		(net "M_E_CPU1_SA_DQ<20>")
	)
	(segment
		(start 69.835268 -233.70413)
		(end 70.129908 -233.70413)
		(width 0.14478)
		(layer "In6.Cu")
		(net "M_E_CPU1_SA_DQ<20>")
	)
	(segment
		(start 40.977566 -222.419926)
		(end 41.352724 -222.795084)
		(width 0.14478)
		(layer "In6.Cu")
		(net "M_E_CPU1_SA_DQ<20>")
	)
	(segment
		(start 31.75635 -222.795084)
		(end 31.919418 -222.632016)
		(width 0.14478)
		(layer "In6.Cu")
		(net "M_E_CPU1_SA_DQ<20>")
	)
	(segment
		(start 61.40958 -222.50908)
		(end 61.614304 -222.50908)
		(width 0.14478)
		(layer "In6.Cu")
		(net "M_E_CPU1_SA_DQ<20>")
	)
	(segment
		(start 61.11367 -222.80499)
		(end 61.40958 -222.50908)
		(width 0.14478)
		(layer "In6.Cu")
		(net "M_E_CPU1_SA_DQ<20>")
	)
	(segment
		(start 49.233582 -222.639636)
		(end 49.233582 -222.573342)
		(width 0.14478)
		(layer "In6.Cu")
		(net "M_E_CPU1_SA_DQ<20>")
	)
	(segment
		(start 80.89265 -238.353092)
		(end 80.915002 -238.26978)
		(width 0.0889)
		(layer "In6.Cu")
		(net "M_E_CPU1_SA_DQ<20>")
	)
	(segment
		(start 34.76625 -222.410274)
		(end 35.606482 -221.570042)
		(width 0.14478)
		(layer "In6.Cu")
		(net "M_E_CPU1_SA_DQ<20>")
	)
	(segment
		(start 38.024562 -221.570042)
		(end 38.874446 -222.419926)
		(width 0.14478)
		(layer "In6.Cu")
		(net "M_E_CPU1_SA_DQ<20>")
	)
	(segment
		(start 42.17035 -222.410274)
		(end 43.010582 -221.570042)
		(width 0.14478)
		(layer "In6.Cu")
		(net "M_E_CPU1_SA_DQ<20>")
	)
	(segment
		(start 33.638236 -222.802704)
		(end 33.868614 -222.802704)
		(width 0.14478)
		(layer "In6.Cu")
		(net "M_E_CPU1_SA_DQ<20>")
	)
	(segment
		(start 55.143654 -222.302832)
		(end 55.306722 -222.139764)
		(width 0.14478)
		(layer "In6.Cu")
		(net "M_E_CPU1_SA_DQ<20>")
	)
	(segment
		(start 54.58714 -222.573342)
		(end 54.58714 -222.632016)
		(width 0.14478)
		(layer "In6.Cu")
		(net "M_E_CPU1_SA_DQ<20>")
	)
	(segment
		(start 33.475168 -222.573342)
		(end 33.475168 -222.639636)
		(width 0.14478)
		(layer "In6.Cu")
		(net "M_E_CPU1_SA_DQ<20>")
	)
	(segment
		(start 31.919418 -222.632016)
		(end 31.919418 -222.573342)
		(width 0.14478)
		(layer "In6.Cu")
		(net "M_E_CPU1_SA_DQ<20>")
	)
	(segment
		(start 56.256682 -222.632016)
		(end 56.256682 -222.573342)
		(width 0.14478)
		(layer "In6.Cu")
		(net "M_E_CPU1_SA_DQ<20>")
	)
	(segment
		(start 50.666142 -221.570042)
		(end 53.072538 -221.570042)
		(width 0.14478)
		(layer "In6.Cu")
		(net "M_E_CPU1_SA_DQ<20>")
	)
	(segment
		(start 41.909238 -222.410274)
		(end 42.17035 -222.410274)
		(width 0.14478)
		(layer "In6.Cu")
		(net "M_E_CPU1_SA_DQ<20>")
	)
	(segment
		(start 68.240148 -232.10901)
		(end 68.534788 -232.10901)
		(width 0.14478)
		(layer "In6.Cu")
		(net "M_E_CPU1_SA_DQ<20>")
	)
	(segment
		(start 33.475168 -222.639636)
		(end 33.638236 -222.802704)
		(width 0.14478)
		(layer "In6.Cu")
		(net "M_E_CPU1_SA_DQ<20>")
	)
	(segment
		(start 35.606482 -221.570042)
		(end 38.024562 -221.570042)
		(width 0.14478)
		(layer "In6.Cu")
		(net "M_E_CPU1_SA_DQ<20>")
	)
	(segment
		(start 71.976488 -235.84535)
		(end 72.660002 -236.528864)
		(width 0.14478)
		(layer "In6.Cu")
		(net "M_E_CPU1_SA_DQ<20>")
	)
	(segment
		(start 54.750208 -222.795084)
		(end 54.980586 -222.795084)
		(width 0.14478)
		(layer "In6.Cu")
		(net "M_E_CPU1_SA_DQ<20>")
	)
	(segment
		(start 68.786248 -232.36047)
		(end 68.786248 -232.65511)
		(width 0.14478)
		(layer "In6.Cu")
		(net "M_E_CPU1_SA_DQ<20>")
	)
	(segment
		(start 60.72378 -222.619824)
		(end 60.908946 -222.80499)
		(width 0.14478)
		(layer "In6.Cu")
		(net "M_E_CPU1_SA_DQ<20>")
	)
	(segment
		(start 30.249876 -222.632016)
		(end 30.412944 -222.795084)
		(width 0.14478)
		(layer "In6.Cu")
		(net "M_E_CPU1_SA_DQ<20>")
	)
	(segment
		(start 41.74617 -222.573342)
		(end 41.909238 -222.410274)
		(width 0.14478)
		(layer "In6.Cu")
		(net "M_E_CPU1_SA_DQ<20>")
	)
	(segment
		(start 70.381368 -233.95559)
		(end 70.381368 -234.25023)
		(width 0.14478)
		(layer "In6.Cu")
		(net "M_E_CPU1_SA_DQ<20>")
	)
	(segment
		(start 30.80639 -222.186754)
		(end 30.969458 -222.023686)
		(width 0.14478)
		(layer "In6.Cu")
		(net "M_E_CPU1_SA_DQ<20>")
	)
	(segment
		(start 57.83326 -221.946724)
		(end 60.412376 -221.946724)
		(width 0.14478)
		(layer "In6.Cu")
		(net "M_E_CPU1_SA_DQ<20>")
	)
	(segment
		(start 71.178928 -234.75315)
		(end 71.178928 -235.04779)
		(width 0.14478)
		(layer "In6.Cu")
		(net "M_E_CPU1_SA_DQ<20>")
	)
	(segment
		(start 57.36971 -222.410274)
		(end 57.83326 -221.946724)
		(width 0.14478)
		(layer "In6.Cu")
		(net "M_E_CPU1_SA_DQ<20>")
	)
	(segment
		(start 48.523652 -222.419926)
		(end 48.677068 -222.573342)
		(width 0.14478)
		(layer "In6.Cu")
		(net "M_E_CPU1_SA_DQ<20>")
	)
	(segment
		(start 71.976488 -235.55071)
		(end 71.976488 -235.84535)
		(width 0.14478)
		(layer "In6.Cu")
		(net "M_E_CPU1_SA_DQ<20>")
	)
	(segment
		(start 29.252164 -221.985332)
		(end 29.576014 -221.661482)
		(width 0.14478)
		(layer "In6.Cu")
		(net "M_E_CPU1_SA_DQ<20>")
	)
	(segment
		(start 49.82591 -222.410274)
		(end 50.666142 -221.570042)
		(width 0.14478)
		(layer "In6.Cu")
		(net "M_E_CPU1_SA_DQ<20>")
	)
	(segment
		(start 41.74617 -222.632016)
		(end 41.74617 -222.573342)
		(width 0.14478)
		(layer "In6.Cu")
		(net "M_E_CPU1_SA_DQ<20>")
	)
	(segment
		(start 68.534788 -232.10901)
		(end 68.786248 -232.36047)
		(width 0.14478)
		(layer "In6.Cu")
		(net "M_E_CPU1_SA_DQ<20>")
	)
	(segment
		(start 56.41975 -222.410274)
		(end 57.36971 -222.410274)
		(width 0.14478)
		(layer "In6.Cu")
		(net "M_E_CPU1_SA_DQ<20>")
	)
	(segment
		(start 30.105096 -221.661482)
		(end 30.249876 -221.806262)
		(width 0.14478)
		(layer "In6.Cu")
		(net "M_E_CPU1_SA_DQ<20>")
	)
	(segment
		(start 76.184506 -236.528864)
		(end 76.669646 -237.014004)
		(width 0.0889)
		(layer "In6.Cu")
		(net "M_E_CPU1_SA_DQ<20>")
	)
	(segment
		(start 49.39665 -222.410274)
		(end 49.82591 -222.410274)
		(width 0.14478)
		(layer "In6.Cu")
		(net "M_E_CPU1_SA_DQ<20>")
	)
	(segment
		(start 68.786248 -232.65511)
		(end 69.037708 -232.90657)
		(width 0.14478)
		(layer "In6.Cu")
		(net "M_E_CPU1_SA_DQ<20>")
	)
	(segment
		(start 71.430388 -235.29925)
		(end 71.725028 -235.29925)
		(width 0.14478)
		(layer "In6.Cu")
		(net "M_E_CPU1_SA_DQ<20>")
	)
	(segment
		(start 53.91277 -222.410274)
		(end 54.424072 -222.410274)
		(width 0.14478)
		(layer "In6.Cu")
		(net "M_E_CPU1_SA_DQ<20>")
	)
	(segment
		(start 48.840136 -222.802704)
		(end 49.070514 -222.802704)
		(width 0.14478)
		(layer "In6.Cu")
		(net "M_E_CPU1_SA_DQ<20>")
	)
	(segment
		(start 71.725028 -235.29925)
		(end 71.976488 -235.55071)
		(width 0.14478)
		(layer "In6.Cu")
		(net "M_E_CPU1_SA_DQ<20>")
	)
	(segment
		(start 54.980586 -222.795084)
		(end 55.143654 -222.632016)
		(width 0.14478)
		(layer "In6.Cu")
		(net "M_E_CPU1_SA_DQ<20>")
	)
	(segment
		(start 64.1477 -226.56673)
		(end 64.1477 -227.598478)
		(width 0.14478)
		(layer "In6.Cu")
		(net "M_E_CPU1_SA_DQ<20>")
	)
	(segment
		(start 30.412944 -222.795084)
		(end 30.643322 -222.795084)
		(width 0.14478)
		(layer "In6.Cu")
		(net "M_E_CPU1_SA_DQ<20>")
	)
	(segment
		(start 80.915002 -238.26978)
		(end 80.761078 -238.00435)
		(width 0.0889)
		(layer "In6.Cu")
		(net "M_E_CPU1_SA_DQ<20>")
	)
	(segment
		(start 61.79947 -222.89897)
		(end 61.50356 -223.19488)
		(width 0.14478)
		(layer "In6.Cu")
		(net "M_E_CPU1_SA_DQ<20>")
	)
	(segment
		(start 69.583808 -233.15803)
		(end 69.583808 -233.45267)
		(width 0.14478)
		(layer "In6.Cu")
		(net "M_E_CPU1_SA_DQ<20>")
	)
	(segment
		(start 31.362904 -222.632016)
		(end 31.525972 -222.795084)
		(width 0.14478)
		(layer "In6.Cu")
		(net "M_E_CPU1_SA_DQ<20>")
	)
	(segment
		(start 48.677068 -222.639636)
		(end 48.840136 -222.802704)
		(width 0.14478)
		(layer "In6.Cu")
		(net "M_E_CPU1_SA_DQ<20>")
	)
	(segment
		(start 71.178928 -235.04779)
		(end 71.430388 -235.29925)
		(width 0.14478)
		(layer "In6.Cu")
		(net "M_E_CPU1_SA_DQ<20>")
	)
	(segment
		(start 76.669646 -237.014004)
		(end 77.085952 -237.014004)
		(width 0.0889)
		(layer "In6.Cu")
		(net "M_E_CPU1_SA_DQ<20>")
	)
	(segment
		(start 61.614304 -222.50908)
		(end 61.79947 -222.694246)
		(width 0.14478)
		(layer "In6.Cu")
		(net "M_E_CPU1_SA_DQ<20>")
	)
	(segment
		(start 70.129908 -233.70413)
		(end 70.381368 -233.95559)
		(width 0.14478)
		(layer "In6.Cu")
		(net "M_E_CPU1_SA_DQ<20>")
	)
	(segment
		(start 41.583102 -222.795084)
		(end 41.74617 -222.632016)
		(width 0.14478)
		(layer "In6.Cu")
		(net "M_E_CPU1_SA_DQ<20>")
	)
	(segment
		(start 34.031682 -222.573342)
		(end 34.19475 -222.410274)
		(width 0.14478)
		(layer "In6.Cu")
		(net "M_E_CPU1_SA_DQ<20>")
	)
	(segment
		(start 70.381368 -234.25023)
		(end 70.632828 -234.50169)
		(width 0.14478)
		(layer "In6.Cu")
		(net "M_E_CPU1_SA_DQ<20>")
	)
	(segment
		(start 61.50356 -223.399604)
		(end 61.78169 -223.677734)
		(width 0.14478)
		(layer "In6.Cu")
		(net "M_E_CPU1_SA_DQ<20>")
	)
	(segment
		(start 32.072834 -222.419926)
		(end 33.321752 -222.419926)
		(width 0.14478)
		(layer "In6.Cu")
		(net "M_E_CPU1_SA_DQ<20>")
	)
	(segment
		(start 48.677068 -222.573342)
		(end 48.677068 -222.639636)
		(width 0.14478)
		(layer "In6.Cu")
		(net "M_E_CPU1_SA_DQ<20>")
	)
	(segment
		(start 54.424072 -222.410274)
		(end 54.58714 -222.573342)
		(width 0.14478)
		(layer "In6.Cu")
		(net "M_E_CPU1_SA_DQ<20>")
	)
	(segment
		(start 43.010582 -221.570042)
		(end 45.602398 -221.570042)
		(width 0.14478)
		(layer "In6.Cu")
		(net "M_E_CPU1_SA_DQ<20>")
	)
	(segment
		(start 69.037708 -232.90657)
		(end 69.332348 -232.90657)
		(width 0.14478)
		(layer "In6.Cu")
		(net "M_E_CPU1_SA_DQ<20>")
	)
	(segment
		(start 53.072538 -221.570042)
		(end 53.91277 -222.410274)
		(width 0.14478)
		(layer "In6.Cu")
		(net "M_E_CPU1_SA_DQ<20>")
	)
	(segment
		(start 33.868614 -222.802704)
		(end 34.031682 -222.639636)
		(width 0.14478)
		(layer "In6.Cu")
		(net "M_E_CPU1_SA_DQ<20>")
	)
	(segment
		(start 79.067406 -238.32693)
		(end 79.07782 -238.320834)
		(width 0.0889)
		(layer "In6.Cu")
		(net "M_E_CPU1_SA_DQ<20>")
	)
	(segment
		(start 54.58714 -222.632016)
		(end 54.750208 -222.795084)
		(width 0.14478)
		(layer "In6.Cu")
		(net "M_E_CPU1_SA_DQ<20>")
	)
	(segment
		(start 49.070514 -222.802704)
		(end 49.233582 -222.639636)
		(width 0.14478)
		(layer "In6.Cu")
		(net "M_E_CPU1_SA_DQ<20>")
	)
	(segment
		(start 75.943206 -236.528864)
		(end 76.184506 -236.528864)
		(width 0.0889)
		(layer "In6.Cu")
		(net "M_E_CPU1_SA_DQ<20>")
	)
	(segment
		(start 45.602398 -221.570042)
		(end 46.452282 -222.419926)
		(width 0.14478)
		(layer "In6.Cu")
		(net "M_E_CPU1_SA_DQ<20>")
	)
	(segment
		(start 61.79947 -222.694246)
		(end 61.79947 -222.89897)
		(width 0.14478)
		(layer "In6.Cu")
		(net "M_E_CPU1_SA_DQ<20>")
	)
	(segment
		(start 29.576014 -221.661482)
		(end 30.105096 -221.661482)
		(width 0.14478)
		(layer "In6.Cu")
		(net "M_E_CPU1_SA_DQ<20>")
	)
	(segment
		(start 55.306722 -222.139764)
		(end 55.5371 -222.139764)
		(width 0.14478)
		(layer "In6.Cu")
		(net "M_E_CPU1_SA_DQ<20>")
	)
	(segment
		(start 61.78169 -223.677734)
		(end 61.78169 -224.20072)
		(width 0.14478)
		(layer "In6.Cu")
		(net "M_E_CPU1_SA_DQ<20>")
	)
	(segment
		(start 55.700168 -222.302832)
		(end 55.700168 -222.632016)
		(width 0.14478)
		(layer "In6.Cu")
		(net "M_E_CPU1_SA_DQ<20>")
	)
	(segment
		(start 31.919418 -222.573342)
		(end 32.072834 -222.419926)
		(width 0.14478)
		(layer "In6.Cu")
		(net "M_E_CPU1_SA_DQ<20>")
	)
	(segment
		(start 77.085952 -237.014004)
		(end 78.322678 -238.25073)
		(width 0.0889)
		(layer "In6.Cu")
		(net "M_E_CPU1_SA_DQ<20>")
	)
	(segment
		(start 55.700168 -222.632016)
		(end 55.863236 -222.795084)
		(width 0.14478)
		(layer "In6.Cu")
		(net "M_E_CPU1_SA_DQ<20>")
	)
	(segment
		(start 55.143654 -222.632016)
		(end 55.143654 -222.302832)
		(width 0.14478)
		(layer "In6.Cu")
		(net "M_E_CPU1_SA_DQ<20>")
	)
	(segment
		(start 30.969458 -222.023686)
		(end 31.199836 -222.023686)
		(width 0.14478)
		(layer "In6.Cu")
		(net "M_E_CPU1_SA_DQ<20>")
	)
	(segment
		(start 38.874446 -222.419926)
		(end 40.977566 -222.419926)
		(width 0.14478)
		(layer "In6.Cu")
		(net "M_E_CPU1_SA_DQ<20>")
	)
	(segment
		(start 67.20459 -231.073452)
		(end 67.442588 -231.31145)
		(width 0.14478)
		(layer "In6.Cu")
		(net "M_E_CPU1_SA_DQ<20>")
	)
	(segment
		(start 31.525972 -222.795084)
		(end 31.75635 -222.795084)
		(width 0.14478)
		(layer "In6.Cu")
		(net "M_E_CPU1_SA_DQ<20>")
	)
	(segment
		(start 69.583808 -233.45267)
		(end 69.835268 -233.70413)
		(width 0.14478)
		(layer "In6.Cu")
		(net "M_E_CPU1_SA_DQ<20>")
	)
	(segment
		(start 30.80639 -222.632016)
		(end 30.80639 -222.186754)
		(width 0.14478)
		(layer "In6.Cu")
		(net "M_E_CPU1_SA_DQ<20>")
	)
	(segment
		(start 46.452282 -222.419926)
		(end 48.523652 -222.419926)
		(width 0.14478)
		(layer "In6.Cu")
		(net "M_E_CPU1_SA_DQ<20>")
	)
	(segment
		(start 67.737228 -231.31145)
		(end 67.988688 -231.56291)
		(width 0.14478)
		(layer "In6.Cu")
		(net "M_E_CPU1_SA_DQ<20>")
	)
	(segment
		(start 69.332348 -232.90657)
		(end 69.583808 -233.15803)
		(width 0.14478)
		(layer "In6.Cu")
		(net "M_E_CPU1_SA_DQ<20>")
	)
	(segment
		(start 78.693518 -238.326676)
		(end 78.709774 -238.336074)
		(width 0.0889)
		(layer "In6.Cu")
		(net "M_E_CPU1_SA_DQ<20>")
	)
	(segment
		(start 60.908946 -222.80499)
		(end 61.11367 -222.80499)
		(width 0.14478)
		(layer "In6.Cu")
		(net "M_E_CPU1_SA_DQ<20>")
	)
	(segment
		(start 41.352724 -222.795084)
		(end 41.583102 -222.795084)
		(width 0.14478)
		(layer "In6.Cu")
		(net "M_E_CPU1_SA_DQ<20>")
	)
	(segment
		(start 30.249876 -221.806262)
		(end 30.249876 -222.632016)
		(width 0.14478)
		(layer "In6.Cu")
		(net "M_E_CPU1_SA_DQ<20>")
	)
	(segment
		(start 49.233582 -222.573342)
		(end 49.39665 -222.410274)
		(width 0.14478)
		(layer "In6.Cu")
		(net "M_E_CPU1_SA_DQ<20>")
	)
	(segment
		(start 67.20459 -230.655368)
		(end 67.20459 -231.073452)
		(width 0.14478)
		(layer "In6.Cu")
		(net "M_E_CPU1_SA_DQ<20>")
	)
	(segment
		(start 31.199836 -222.023686)
		(end 31.362904 -222.186754)
		(width 0.14478)
		(layer "In6.Cu")
		(net "M_E_CPU1_SA_DQ<20>")
	)
	(segment
		(start 60.72378 -222.258128)
		(end 60.72378 -222.619824)
		(width 0.14478)
		(layer "In6.Cu")
		(net "M_E_CPU1_SA_DQ<20>")
	)
	(segment
		(start 60.412376 -221.946724)
		(end 60.72378 -222.258128)
		(width 0.14478)
		(layer "In6.Cu")
		(net "M_E_CPU1_SA_DQ<20>")
	)
	(segment
		(start 67.988688 -231.56291)
		(end 67.988688 -231.85755)
		(width 0.14478)
		(layer "In6.Cu")
		(net "M_E_CPU1_SA_DQ<20>")
	)
	(segment
		(start 67.988688 -231.85755)
		(end 68.240148 -232.10901)
		(width 0.14478)
		(layer "In6.Cu")
		(net "M_E_CPU1_SA_DQ<20>")
	)
	(segment
		(start 79.99984 -238.331756)
		(end 80.008222 -238.32693)
		(width 0.0889)
		(layer "In6.Cu")
		(net "M_E_CPU1_SA_DQ<20>")
	)
	(segment
		(start 56.093614 -222.795084)
		(end 56.256682 -222.632016)
		(width 0.14478)
		(layer "In6.Cu")
		(net "M_E_CPU1_SA_DQ<20>")
	)
	(segment
		(start 67.442588 -231.31145)
		(end 67.737228 -231.31145)
		(width 0.14478)
		(layer "In6.Cu")
		(net "M_E_CPU1_SA_DQ<20>")
	)
	(segment
		(start 30.643322 -222.795084)
		(end 30.80639 -222.632016)
		(width 0.14478)
		(layer "In6.Cu")
		(net "M_E_CPU1_SA_DQ<20>")
	)
	(segment
		(start 61.50356 -223.19488)
		(end 61.50356 -223.399604)
		(width 0.14478)
		(layer "In6.Cu")
		(net "M_E_CPU1_SA_DQ<20>")
	)
	(segment
		(start 72.660002 -236.528864)
		(end 75.943206 -236.528864)
		(width 0.14478)
		(layer "In6.Cu")
		(net "M_E_CPU1_SA_DQ<20>")
	)
	(segment
		(start 31.362904 -222.186754)
		(end 31.362904 -222.632016)
		(width 0.14478)
		(layer "In6.Cu")
		(net "M_E_CPU1_SA_DQ<20>")
	)
	(segment
		(start 34.19475 -222.410274)
		(end 34.76625 -222.410274)
		(width 0.14478)
		(layer "In6.Cu")
		(net "M_E_CPU1_SA_DQ<20>")
	)
	(arc
		(start 79.07782 -238.320834)
		(mid 79.356506 -238.250614)
		(end 79.633572 -238.32693)
		(width 0.0889)
		(layer "In6.Cu")
		(net "M_E_CPU1_SA_DQ<20>")
	)
	(arc
		(start 78.709774 -238.336074)
		(mid 78.889756 -238.377174)
		(end 79.067406 -238.32693)
		(width 0.0889)
		(layer "In6.Cu")
		(net "M_E_CPU1_SA_DQ<20>")
	)
	(arc
		(start 78.411578 -238.25073)
		(mid 78.427458 -238.250889)
		(end 78.443328 -238.251492)
		(width 0.0889)
		(layer "In6.Cu")
		(net "M_E_CPU1_SA_DQ<20>")
	)
	(arc
		(start 79.633572 -238.32693)
		(mid 79.816077 -238.377407)
		(end 79.99984 -238.331756)
		(width 0.0889)
		(layer "In6.Cu")
		(net "M_E_CPU1_SA_DQ<20>")
	)
	(arc
		(start 80.574134 -238.32693)
		(mid 80.730453 -238.375925)
		(end 80.89265 -238.353092)
		(width 0.0889)
		(layer "In6.Cu")
		(net "M_E_CPU1_SA_DQ<20>")
	)
	(arc
		(start 78.443328 -238.251492)
		(mid 78.572832 -238.274406)
		(end 78.693518 -238.326676)
		(width 0.0889)
		(layer "In6.Cu")
		(net "M_E_CPU1_SA_DQ<20>")
	)
	(arc
		(start 80.008222 -238.32693)
		(mid 80.291178 -238.250753)
		(end 80.574134 -238.32693)
		(width 0.0889)
		(layer "In6.Cu")
		(net "M_E_CPU1_SA_DQ<20>")
	)
	(segment
		(start 82.637884 -226.120452)
		(end 82.171032 -225.854514)
		(width 0.10668)
		(layer "F.Cu")
		(net "M_E_CPU1_SA_DQ<1>")
	)
	(segment
		(start 42.00525 -199.460358)
		(end 42.855134 -198.610474)
		(width 0.14478)
		(layer "In6.Cu")
		(net "M_E_CPU1_SA_DQ<1>")
	)
	(segment
		(start 82.324956 -226.119944)
		(end 82.171032 -225.854514)
		(width 0.0889)
		(layer "In6.Cu")
		(net "M_E_CPU1_SA_DQ<1>")
	)
	(segment
		(start 67.927728 -206.294736)
		(end 68.218558 -206.003906)
		(width 0.14478)
		(layer "In6.Cu")
		(net "M_E_CPU1_SA_DQ<1>")
	)
	(segment
		(start 38.864794 -199.460358)
		(end 42.00525 -199.460358)
		(width 0.14478)
		(layer "In6.Cu")
		(net "M_E_CPU1_SA_DQ<1>")
	)
	(segment
		(start 76.093066 -218.830144)
		(end 78.523846 -221.260924)
		(width 0.14478)
		(layer "In6.Cu")
		(net "M_E_CPU1_SA_DQ<1>")
	)
	(segment
		(start 67.529202 -206.10068)
		(end 67.723512 -206.29499)
		(width 0.14478)
		(layer "In6.Cu")
		(net "M_E_CPU1_SA_DQ<1>")
	)
	(segment
		(start 79.633826 -225.367088)
		(end 79.672942 -225.389948)
		(width 0.0889)
		(layer "In6.Cu")
		(net "M_E_CPU1_SA_DQ<1>")
	)
	(segment
		(start 38.01491 -198.610474)
		(end 38.864794 -199.460358)
		(width 0.14478)
		(layer "In6.Cu")
		(net "M_E_CPU1_SA_DQ<1>")
	)
	(segment
		(start 68.617338 -206.197962)
		(end 68.617592 -206.402686)
		(width 0.14478)
		(layer "In6.Cu")
		(net "M_E_CPU1_SA_DQ<1>")
	)
	(segment
		(start 60.143136 -199.085962)
		(end 60.143136 -199.940926)
		(width 0.14478)
		(layer "In6.Cu")
		(net "M_E_CPU1_SA_DQ<1>")
	)
	(segment
		(start 68.326762 -206.89824)
		(end 76.093066 -214.664544)
		(width 0.14478)
		(layer "In6.Cu")
		(net "M_E_CPU1_SA_DQ<1>")
	)
	(segment
		(start 80.46974 -226.18192)
		(end 80.478122 -226.177094)
		(width 0.0889)
		(layer "In6.Cu")
		(net "M_E_CPU1_SA_DQ<1>")
	)
	(segment
		(start 35.308794 -198.610474)
		(end 38.01491 -198.610474)
		(width 0.14478)
		(layer "In6.Cu")
		(net "M_E_CPU1_SA_DQ<1>")
	)
	(segment
		(start 67.130168 -205.497176)
		(end 67.420998 -205.206346)
		(width 0.14478)
		(layer "In6.Cu")
		(net "M_E_CPU1_SA_DQ<1>")
	)
	(segment
		(start 66.677286 -204.301598)
		(end 66.677286 -205.248764)
		(width 0.14478)
		(layer "In6.Cu")
		(net "M_E_CPU1_SA_DQ<1>")
	)
	(segment
		(start 79.603346 -225.349308)
		(end 79.633826 -225.367088)
		(width 0.0889)
		(layer "In6.Cu")
		(net "M_E_CPU1_SA_DQ<1>")
	)
	(segment
		(start 67.723512 -206.29499)
		(end 67.927728 -206.294736)
		(width 0.14478)
		(layer "In6.Cu")
		(net "M_E_CPU1_SA_DQ<1>")
	)
	(segment
		(start 67.820032 -205.605126)
		(end 67.529202 -205.895956)
		(width 0.14478)
		(layer "In6.Cu")
		(net "M_E_CPU1_SA_DQ<1>")
	)
	(segment
		(start 61.31687 -198.941182)
		(end 66.677286 -204.301598)
		(width 0.14478)
		(layer "In6.Cu")
		(net "M_E_CPU1_SA_DQ<1>")
	)
	(segment
		(start 76.093066 -214.664544)
		(end 76.093066 -218.830144)
		(width 0.14478)
		(layer "In6.Cu")
		(net "M_E_CPU1_SA_DQ<1>")
	)
	(segment
		(start 29.252164 -199.035416)
		(end 29.677106 -199.460358)
		(width 0.14478)
		(layer "In6.Cu")
		(net "M_E_CPU1_SA_DQ<1>")
	)
	(segment
		(start 82.302604 -226.203256)
		(end 82.324956 -226.119944)
		(width 0.0889)
		(layer "In6.Cu")
		(net "M_E_CPU1_SA_DQ<1>")
	)
	(segment
		(start 79.16418 -222.93707)
		(end 79.201772 -222.958914)
		(width 0.0889)
		(layer "In6.Cu")
		(net "M_E_CPU1_SA_DQ<1>")
	)
	(segment
		(start 68.423282 -206.003906)
		(end 68.617338 -206.197962)
		(width 0.14478)
		(layer "In6.Cu")
		(net "M_E_CPU1_SA_DQ<1>")
	)
	(segment
		(start 79.1337 -222.91929)
		(end 79.16418 -222.93707)
		(width 0.0889)
		(layer "In6.Cu")
		(net "M_E_CPU1_SA_DQ<1>")
	)
	(segment
		(start 60.851796 -198.941182)
		(end 61.31687 -198.941182)
		(width 0.14478)
		(layer "In6.Cu")
		(net "M_E_CPU1_SA_DQ<1>")
	)
	(segment
		(start 78.523846 -221.260924)
		(end 78.523846 -221.97314)
		(width 0.0889)
		(layer "In6.Cu")
		(net "M_E_CPU1_SA_DQ<1>")
	)
	(segment
		(start 49.58715 -199.460358)
		(end 50.437034 -198.610474)
		(width 0.14478)
		(layer "In6.Cu")
		(net "M_E_CPU1_SA_DQ<1>")
	)
	(segment
		(start 50.437034 -198.610474)
		(end 53.23459 -198.610474)
		(width 0.14478)
		(layer "In6.Cu")
		(net "M_E_CPU1_SA_DQ<1>")
	)
	(segment
		(start 79.671926 -224.700084)
		(end 79.63408 -224.721928)
		(width 0.0889)
		(layer "In6.Cu")
		(net "M_E_CPU1_SA_DQ<1>")
	)
	(segment
		(start 60.707016 -199.085962)
		(end 60.851796 -198.941182)
		(width 0.14478)
		(layer "In6.Cu")
		(net "M_E_CPU1_SA_DQ<1>")
	)
	(segment
		(start 80.0735 -226.159314)
		(end 80.10398 -226.177094)
		(width 0.0889)
		(layer "In6.Cu")
		(net "M_E_CPU1_SA_DQ<1>")
	)
	(segment
		(start 68.218558 -206.003906)
		(end 68.423282 -206.003906)
		(width 0.14478)
		(layer "In6.Cu")
		(net "M_E_CPU1_SA_DQ<1>")
	)
	(segment
		(start 60.707016 -199.940926)
		(end 60.707016 -199.085962)
		(width 0.14478)
		(layer "In6.Cu")
		(net "M_E_CPU1_SA_DQ<1>")
	)
	(segment
		(start 34.45891 -199.460358)
		(end 35.308794 -198.610474)
		(width 0.14478)
		(layer "In6.Cu")
		(net "M_E_CPU1_SA_DQ<1>")
	)
	(segment
		(start 79.634334 -223.747076)
		(end 79.670656 -223.768158)
		(width 0.0889)
		(layer "In6.Cu")
		(net "M_E_CPU1_SA_DQ<1>")
	)
	(segment
		(start 46.540674 -199.460358)
		(end 49.58715 -199.460358)
		(width 0.14478)
		(layer "In6.Cu")
		(net "M_E_CPU1_SA_DQ<1>")
	)
	(segment
		(start 81.044034 -226.177094)
		(end 81.052416 -226.18192)
		(width 0.0889)
		(layer "In6.Cu")
		(net "M_E_CPU1_SA_DQ<1>")
	)
	(segment
		(start 79.600552 -223.727518)
		(end 79.634334 -223.747076)
		(width 0.0889)
		(layer "In6.Cu")
		(net "M_E_CPU1_SA_DQ<1>")
	)
	(segment
		(start 78.523846 -221.97314)
		(end 78.655164 -222.104458)
		(width 0.0889)
		(layer "In6.Cu")
		(net "M_E_CPU1_SA_DQ<1>")
	)
	(segment
		(start 79.916274 -225.854514)
		(end 79.916528 -225.854514)
		(width 0.0889)
		(layer "In6.Cu")
		(net "M_E_CPU1_SA_DQ<1>")
	)
	(segment
		(start 60.143136 -199.940926)
		(end 60.287916 -200.085706)
		(width 0.14478)
		(layer "In6.Cu")
		(net "M_E_CPU1_SA_DQ<1>")
	)
	(segment
		(start 57.13095 -199.460358)
		(end 57.650126 -198.941182)
		(width 0.14478)
		(layer "In6.Cu")
		(net "M_E_CPU1_SA_DQ<1>")
	)
	(segment
		(start 67.529202 -205.895956)
		(end 67.529202 -206.10068)
		(width 0.14478)
		(layer "In6.Cu")
		(net "M_E_CPU1_SA_DQ<1>")
	)
	(segment
		(start 59.998356 -198.941182)
		(end 60.143136 -199.085962)
		(width 0.14478)
		(layer "In6.Cu")
		(net "M_E_CPU1_SA_DQ<1>")
	)
	(segment
		(start 29.677106 -199.460358)
		(end 34.45891 -199.460358)
		(width 0.14478)
		(layer "In6.Cu")
		(net "M_E_CPU1_SA_DQ<1>")
	)
	(segment
		(start 66.925952 -205.49743)
		(end 67.130168 -205.497176)
		(width 0.14478)
		(layer "In6.Cu")
		(net "M_E_CPU1_SA_DQ<1>")
	)
	(segment
		(start 67.819778 -205.400402)
		(end 67.820032 -205.605126)
		(width 0.14478)
		(layer "In6.Cu")
		(net "M_E_CPU1_SA_DQ<1>")
	)
	(segment
		(start 57.650126 -198.941182)
		(end 59.998356 -198.941182)
		(width 0.14478)
		(layer "In6.Cu")
		(net "M_E_CPU1_SA_DQ<1>")
	)
	(segment
		(start 60.287916 -200.085706)
		(end 60.562236 -200.085706)
		(width 0.14478)
		(layer "In6.Cu")
		(net "M_E_CPU1_SA_DQ<1>")
	)
	(segment
		(start 79.63408 -224.721928)
		(end 79.60233 -224.740216)
		(width 0.0889)
		(layer "In6.Cu")
		(net "M_E_CPU1_SA_DQ<1>")
	)
	(segment
		(start 54.084474 -199.460358)
		(end 57.13095 -199.460358)
		(width 0.14478)
		(layer "In6.Cu")
		(net "M_E_CPU1_SA_DQ<1>")
	)
	(segment
		(start 53.23459 -198.610474)
		(end 54.084474 -199.460358)
		(width 0.14478)
		(layer "In6.Cu")
		(net "M_E_CPU1_SA_DQ<1>")
	)
	(segment
		(start 68.326762 -206.693516)
		(end 68.326762 -206.89824)
		(width 0.14478)
		(layer "In6.Cu")
		(net "M_E_CPU1_SA_DQ<1>")
	)
	(segment
		(start 60.562236 -200.085706)
		(end 60.707016 -199.940926)
		(width 0.14478)
		(layer "In6.Cu")
		(net "M_E_CPU1_SA_DQ<1>")
	)
	(segment
		(start 78.655164 -222.104458)
		(end 78.732126 -222.148908)
		(width 0.0889)
		(layer "In6.Cu")
		(net "M_E_CPU1_SA_DQ<1>")
	)
	(segment
		(start 45.69079 -198.610474)
		(end 46.540674 -199.460358)
		(width 0.14478)
		(layer "In6.Cu")
		(net "M_E_CPU1_SA_DQ<1>")
	)
	(segment
		(start 42.855134 -198.610474)
		(end 45.69079 -198.610474)
		(width 0.14478)
		(layer "In6.Cu")
		(net "M_E_CPU1_SA_DQ<1>")
	)
	(segment
		(start 67.625722 -205.206346)
		(end 67.819778 -205.400402)
		(width 0.14478)
		(layer "In6.Cu")
		(net "M_E_CPU1_SA_DQ<1>")
	)
	(segment
		(start 66.677286 -205.248764)
		(end 66.925952 -205.49743)
		(width 0.14478)
		(layer "In6.Cu")
		(net "M_E_CPU1_SA_DQ<1>")
	)
	(segment
		(start 67.420998 -205.206346)
		(end 67.625722 -205.206346)
		(width 0.14478)
		(layer "In6.Cu")
		(net "M_E_CPU1_SA_DQ<1>")
	)
	(segment
		(start 68.617592 -206.402686)
		(end 68.326762 -206.693516)
		(width 0.14478)
		(layer "In6.Cu")
		(net "M_E_CPU1_SA_DQ<1>")
	)
	(arc
		(start 79.670656 -223.768158)
		(mid 79.851308 -223.970903)
		(end 79.916528 -224.234502)
		(width 0.0889)
		(layer "In6.Cu")
		(net "M_E_CPU1_SA_DQ<1>")
	)
	(arc
		(start 78.732126 -222.148908)
		(mid 78.911855 -222.351528)
		(end 78.976728 -222.61449)
		(width 0.0889)
		(layer "In6.Cu")
		(net "M_E_CPU1_SA_DQ<1>")
	)
	(arc
		(start 79.60233 -224.740216)
		(mid 79.487654 -224.87355)
		(end 79.446374 -225.044508)
		(width 0.0889)
		(layer "In6.Cu")
		(net "M_E_CPU1_SA_DQ<1>")
	)
	(arc
		(start 81.984088 -226.177094)
		(mid 82.140407 -226.226089)
		(end 82.302604 -226.203256)
		(width 0.0889)
		(layer "In6.Cu")
		(net "M_E_CPU1_SA_DQ<1>")
	)
	(arc
		(start 81.418176 -226.177094)
		(mid 81.701132 -226.100917)
		(end 81.984088 -226.177094)
		(width 0.0889)
		(layer "In6.Cu")
		(net "M_E_CPU1_SA_DQ<1>")
	)
	(arc
		(start 79.446374 -225.044508)
		(mid 79.487923 -225.21593)
		(end 79.603346 -225.349308)
		(width 0.0889)
		(layer "In6.Cu")
		(net "M_E_CPU1_SA_DQ<1>")
	)
	(arc
		(start 79.916528 -224.234502)
		(mid 79.851656 -224.497465)
		(end 79.671926 -224.700084)
		(width 0.0889)
		(layer "In6.Cu")
		(net "M_E_CPU1_SA_DQ<1>")
	)
	(arc
		(start 81.052416 -226.18192)
		(mid 81.235924 -226.227414)
		(end 81.418176 -226.177094)
		(width 0.0889)
		(layer "In6.Cu")
		(net "M_E_CPU1_SA_DQ<1>")
	)
	(arc
		(start 78.976728 -222.61449)
		(mid 79.018277 -222.785912)
		(end 79.1337 -222.91929)
		(width 0.0889)
		(layer "In6.Cu")
		(net "M_E_CPU1_SA_DQ<1>")
	)
	(arc
		(start 79.672942 -225.389948)
		(mid 79.851755 -225.592298)
		(end 79.916274 -225.854514)
		(width 0.0889)
		(layer "In6.Cu")
		(net "M_E_CPU1_SA_DQ<1>")
	)
	(arc
		(start 79.446374 -223.424496)
		(mid 79.487132 -223.594494)
		(end 79.600552 -223.727518)
		(width 0.0889)
		(layer "In6.Cu")
		(net "M_E_CPU1_SA_DQ<1>")
	)
	(arc
		(start 79.201772 -222.958914)
		(mid 79.381501 -223.161534)
		(end 79.446374 -223.424496)
		(width 0.0889)
		(layer "In6.Cu")
		(net "M_E_CPU1_SA_DQ<1>")
	)
	(arc
		(start 80.478122 -226.177094)
		(mid 80.761078 -226.100917)
		(end 81.044034 -226.177094)
		(width 0.0889)
		(layer "In6.Cu")
		(net "M_E_CPU1_SA_DQ<1>")
	)
	(arc
		(start 80.10398 -226.177094)
		(mid 80.286231 -226.227444)
		(end 80.46974 -226.18192)
		(width 0.0889)
		(layer "In6.Cu")
		(net "M_E_CPU1_SA_DQ<1>")
	)
	(arc
		(start 79.916528 -225.854514)
		(mid 79.958077 -226.025936)
		(end 80.0735 -226.159314)
		(width 0.0889)
		(layer "In6.Cu")
		(net "M_E_CPU1_SA_DQ<1>")
	)
	(segment
		(start 83.107784 -236.650276)
		(end 82.640932 -236.384338)
		(width 0.10668)
		(layer "F.Cu")
		(net "M_E_CPU1_SA_DQ<19>")
	)
	(segment
		(start 62.941962 -218.508326)
		(end 64.099186 -219.66555)
		(width 0.14478)
		(layer "In6.Cu")
		(net "M_E_CPU1_SA_DQ<19>")
	)
	(segment
		(start 79.056992 -236.0549)
		(end 79.068676 -236.061758)
		(width 0.0889)
		(layer "In6.Cu")
		(net "M_E_CPU1_SA_DQ<19>")
	)
	(segment
		(start 77.180186 -234.890564)
		(end 77.180186 -235.172504)
		(width 0.0889)
		(layer "In6.Cu")
		(net "M_E_CPU1_SA_DQ<19>")
	)
	(segment
		(start 66.44259 -225.60153)
		(end 66.44259 -226.554792)
		(width 0.14478)
		(layer "In6.Cu")
		(net "M_E_CPU1_SA_DQ<19>")
	)
	(segment
		(start 38.014148 -218.150694)
		(end 38.864032 -219.000578)
		(width 0.14478)
		(layer "In6.Cu")
		(net "M_E_CPU1_SA_DQ<19>")
	)
	(segment
		(start 53.246782 -218.150694)
		(end 54.106572 -219.010484)
		(width 0.14478)
		(layer "In6.Cu")
		(net "M_E_CPU1_SA_DQ<19>")
	)
	(segment
		(start 49.440338 -219.000578)
		(end 50.290222 -218.150694)
		(width 0.14478)
		(layer "In6.Cu")
		(net "M_E_CPU1_SA_DQ<19>")
	)
	(segment
		(start 79.634334 -236.061758)
		(end 79.646018 -236.0549)
		(width 0.0889)
		(layer "In6.Cu")
		(net "M_E_CPU1_SA_DQ<19>")
	)
	(segment
		(start 58.72861 -218.160346)
		(end 59.07659 -218.508326)
		(width 0.14478)
		(layer "In6.Cu")
		(net "M_E_CPU1_SA_DQ<19>")
	)
	(segment
		(start 76.037186 -234.166664)
		(end 76.545186 -234.674664)
		(width 0.0889)
		(layer "In6.Cu")
		(net "M_E_CPU1_SA_DQ<19>")
	)
	(segment
		(start 82.390996 -236.093508)
		(end 82.487008 -236.118908)
		(width 0.0889)
		(layer "In6.Cu")
		(net "M_E_CPU1_SA_DQ<19>")
	)
	(segment
		(start 77.180186 -235.172504)
		(end 78.076552 -236.06887)
		(width 0.0889)
		(layer "In6.Cu")
		(net "M_E_CPU1_SA_DQ<19>")
	)
	(segment
		(start 78.076552 -236.06887)
		(end 78.14056 -236.06887)
		(width 0.0889)
		(layer "In6.Cu")
		(net "M_E_CPU1_SA_DQ<19>")
	)
	(segment
		(start 57.82437 -218.160346)
		(end 58.72861 -218.160346)
		(width 0.14478)
		(layer "In6.Cu")
		(net "M_E_CPU1_SA_DQ<19>")
	)
	(segment
		(start 66.44259 -226.554792)
		(end 74.054462 -234.166664)
		(width 0.14478)
		(layer "In6.Cu")
		(net "M_E_CPU1_SA_DQ<19>")
	)
	(segment
		(start 26.116534 -218.585288)
		(end 27.121104 -219.00134)
		(width 0.14478)
		(layer "In6.Cu")
		(net "M_E_CPU1_SA_DQ<19>")
	)
	(segment
		(start 25.152096 -218.585288)
		(end 26.116534 -218.585288)
		(width 0.14478)
		(layer "In6.Cu")
		(net "M_E_CPU1_SA_DQ<19>")
	)
	(segment
		(start 38.864032 -219.000578)
		(end 41.929812 -219.000578)
		(width 0.14478)
		(layer "In6.Cu")
		(net "M_E_CPU1_SA_DQ<19>")
	)
	(segment
		(start 56.974232 -219.010484)
		(end 57.82437 -218.160346)
		(width 0.14478)
		(layer "In6.Cu")
		(net "M_E_CPU1_SA_DQ<19>")
	)
	(segment
		(start 75.607926 -234.166664)
		(end 76.037186 -234.166664)
		(width 0.0889)
		(layer "In6.Cu")
		(net "M_E_CPU1_SA_DQ<19>")
	)
	(segment
		(start 41.929812 -219.000578)
		(end 42.779696 -218.150694)
		(width 0.14478)
		(layer "In6.Cu")
		(net "M_E_CPU1_SA_DQ<19>")
	)
	(segment
		(start 50.290222 -218.150694)
		(end 53.246782 -218.150694)
		(width 0.14478)
		(layer "In6.Cu")
		(net "M_E_CPU1_SA_DQ<19>")
	)
	(segment
		(start 42.779696 -218.150694)
		(end 45.702982 -218.150694)
		(width 0.14478)
		(layer "In6.Cu")
		(net "M_E_CPU1_SA_DQ<19>")
	)
	(segment
		(start 79.62392 -236.067854)
		(end 79.634334 -236.061758)
		(width 0.0889)
		(layer "In6.Cu")
		(net "M_E_CPU1_SA_DQ<19>")
	)
	(segment
		(start 81.879694 -236.056932)
		(end 81.888076 -236.061758)
		(width 0.0889)
		(layer "In6.Cu")
		(net "M_E_CPU1_SA_DQ<19>")
	)
	(segment
		(start 35.134804 -218.150694)
		(end 38.014148 -218.150694)
		(width 0.14478)
		(layer "In6.Cu")
		(net "M_E_CPU1_SA_DQ<19>")
	)
	(segment
		(start 54.106572 -219.010484)
		(end 56.974232 -219.010484)
		(width 0.14478)
		(layer "In6.Cu")
		(net "M_E_CPU1_SA_DQ<19>")
	)
	(segment
		(start 45.702982 -218.150694)
		(end 46.552866 -219.000578)
		(width 0.14478)
		(layer "In6.Cu")
		(net "M_E_CPU1_SA_DQ<19>")
	)
	(segment
		(start 76.545186 -234.674664)
		(end 76.964286 -234.674664)
		(width 0.0889)
		(layer "In6.Cu")
		(net "M_E_CPU1_SA_DQ<19>")
	)
	(segment
		(start 59.07659 -218.508326)
		(end 62.941962 -218.508326)
		(width 0.14478)
		(layer "In6.Cu")
		(net "M_E_CPU1_SA_DQ<19>")
	)
	(segment
		(start 64.099186 -219.66555)
		(end 64.099186 -223.258126)
		(width 0.14478)
		(layer "In6.Cu")
		(net "M_E_CPU1_SA_DQ<19>")
	)
	(segment
		(start 46.552866 -219.000578)
		(end 49.440338 -219.000578)
		(width 0.14478)
		(layer "In6.Cu")
		(net "M_E_CPU1_SA_DQ<19>")
	)
	(segment
		(start 82.487008 -236.118908)
		(end 82.640932 -236.384338)
		(width 0.0889)
		(layer "In6.Cu")
		(net "M_E_CPU1_SA_DQ<19>")
	)
	(segment
		(start 74.054462 -234.166664)
		(end 75.607926 -234.166664)
		(width 0.14478)
		(layer "In6.Cu")
		(net "M_E_CPU1_SA_DQ<19>")
	)
	(segment
		(start 27.121104 -219.00134)
		(end 34.284158 -219.00134)
		(width 0.14478)
		(layer "In6.Cu")
		(net "M_E_CPU1_SA_DQ<19>")
	)
	(segment
		(start 76.964286 -234.674664)
		(end 77.180186 -234.890564)
		(width 0.0889)
		(layer "In6.Cu")
		(net "M_E_CPU1_SA_DQ<19>")
	)
	(segment
		(start 64.099186 -223.258126)
		(end 66.44259 -225.60153)
		(width 0.14478)
		(layer "In6.Cu")
		(net "M_E_CPU1_SA_DQ<19>")
	)
	(segment
		(start 34.284158 -219.00134)
		(end 35.134804 -218.150694)
		(width 0.14478)
		(layer "In6.Cu")
		(net "M_E_CPU1_SA_DQ<19>")
	)
	(arc
		(start 80.574134 -236.061758)
		(mid 80.761078 -236.011503)
		(end 80.948022 -236.061758)
		(width 0.0889)
		(layer "In6.Cu")
		(net "M_E_CPU1_SA_DQ<19>")
	)
	(arc
		(start 81.888076 -236.061758)
		(mid 82.135789 -236.136978)
		(end 82.390996 -236.093508)
		(width 0.0889)
		(layer "In6.Cu")
		(net "M_E_CPU1_SA_DQ<19>")
	)
	(arc
		(start 78.14056 -236.06887)
		(mid 78.418348 -236.137972)
		(end 78.69428 -236.061758)
		(width 0.0889)
		(layer "In6.Cu")
		(net "M_E_CPU1_SA_DQ<19>")
	)
	(arc
		(start 78.69428 -236.061758)
		(mid 78.874738 -236.011314)
		(end 79.056992 -236.0549)
		(width 0.0889)
		(layer "In6.Cu")
		(net "M_E_CPU1_SA_DQ<19>")
	)
	(arc
		(start 81.513934 -236.061758)
		(mid 81.696185 -236.011408)
		(end 81.879694 -236.056932)
		(width 0.0889)
		(layer "In6.Cu")
		(net "M_E_CPU1_SA_DQ<19>")
	)
	(arc
		(start 79.068676 -236.061758)
		(mid 79.345489 -236.137901)
		(end 79.62392 -236.067854)
		(width 0.0889)
		(layer "In6.Cu")
		(net "M_E_CPU1_SA_DQ<19>")
	)
	(arc
		(start 79.646018 -236.0549)
		(mid 79.828019 -236.011367)
		(end 80.008222 -236.061758)
		(width 0.0889)
		(layer "In6.Cu")
		(net "M_E_CPU1_SA_DQ<19>")
	)
	(arc
		(start 80.008222 -236.061758)
		(mid 80.291178 -236.137935)
		(end 80.574134 -236.061758)
		(width 0.0889)
		(layer "In6.Cu")
		(net "M_E_CPU1_SA_DQ<19>")
	)
	(arc
		(start 80.948022 -236.061758)
		(mid 81.230978 -236.137935)
		(end 81.513934 -236.061758)
		(width 0.0889)
		(layer "In6.Cu")
		(net "M_E_CPU1_SA_DQ<19>")
	)
	(segment
		(start 81.69783 -235.84027)
		(end 81.230978 -235.574332)
		(width 0.10668)
		(layer "F.Cu")
		(net "M_E_CPU1_SA_DQ<18>")
	)
	(segment
		(start 78.484984 -235.206286)
		(end 78.603348 -235.255308)
		(width 0.0889)
		(layer "In6.Cu")
		(net "M_E_CPU1_SA_DQ<18>")
	)
	(segment
		(start 54.057296 -217.261186)
		(end 59.101482 -217.261186)
		(width 0.14478)
		(layer "In6.Cu")
		(net "M_E_CPU1_SA_DQ<18>")
	)
	(segment
		(start 80.093566 -235.257848)
		(end 80.10398 -235.251752)
		(width 0.0889)
		(layer "In6.Cu")
		(net "M_E_CPU1_SA_DQ<18>")
	)
	(segment
		(start 27.017472 -217.147394)
		(end 27.017472 -216.824814)
		(width 0.14478)
		(layer "In6.Cu")
		(net "M_E_CPU1_SA_DQ<18>")
	)
	(segment
		(start 65.008506 -219.302838)
		(end 65.008506 -222.895414)
		(width 0.14478)
		(layer "In6.Cu")
		(net "M_E_CPU1_SA_DQ<18>")
	)
	(segment
		(start 27.573986 -216.824814)
		(end 27.573986 -217.147394)
		(width 0.14478)
		(layer "In6.Cu")
		(net "M_E_CPU1_SA_DQ<18>")
	)
	(segment
		(start 45.712634 -216.460324)
		(end 46.562772 -217.310462)
		(width 0.14478)
		(layer "In6.Cu")
		(net "M_E_CPU1_SA_DQ<18>")
	)
	(segment
		(start 35.12439 -216.460324)
		(end 38.0238 -216.460324)
		(width 0.14478)
		(layer "In6.Cu")
		(net "M_E_CPU1_SA_DQ<18>")
	)
	(segment
		(start 67.34175 -226.167696)
		(end 74.431398 -233.257344)
		(width 0.14478)
		(layer "In6.Cu")
		(net "M_E_CPU1_SA_DQ<18>")
	)
	(segment
		(start 38.873938 -217.310462)
		(end 41.919906 -217.310462)
		(width 0.14478)
		(layer "In6.Cu")
		(net "M_E_CPU1_SA_DQ<18>")
	)
	(segment
		(start 59.449462 -217.609166)
		(end 63.314834 -217.609166)
		(width 0.14478)
		(layer "In6.Cu")
		(net "M_E_CPU1_SA_DQ<18>")
	)
	(segment
		(start 34.274252 -217.310462)
		(end 35.12439 -216.460324)
		(width 0.14478)
		(layer "In6.Cu")
		(net "M_E_CPU1_SA_DQ<18>")
	)
	(segment
		(start 25.152096 -216.885266)
		(end 25.577292 -217.310462)
		(width 0.14478)
		(layer "In6.Cu")
		(net "M_E_CPU1_SA_DQ<18>")
	)
	(segment
		(start 74.431398 -233.257344)
		(end 75.607926 -233.257344)
		(width 0.14478)
		(layer "In6.Cu")
		(net "M_E_CPU1_SA_DQ<18>")
	)
	(segment
		(start 78.14818 -235.206286)
		(end 78.484984 -235.206286)
		(width 0.0889)
		(layer "In6.Cu")
		(net "M_E_CPU1_SA_DQ<18>")
	)
	(segment
		(start 41.919906 -217.310462)
		(end 42.770044 -216.460324)
		(width 0.14478)
		(layer "In6.Cu")
		(net "M_E_CPU1_SA_DQ<18>")
	)
	(segment
		(start 59.101482 -217.261186)
		(end 59.449462 -217.609166)
		(width 0.14478)
		(layer "In6.Cu")
		(net "M_E_CPU1_SA_DQ<18>")
	)
	(segment
		(start 25.577292 -217.310462)
		(end 26.854404 -217.310462)
		(width 0.14478)
		(layer "In6.Cu")
		(net "M_E_CPU1_SA_DQ<18>")
	)
	(segment
		(start 81.077054 -235.308902)
		(end 81.230978 -235.574332)
		(width 0.0889)
		(layer "In6.Cu")
		(net "M_E_CPU1_SA_DQ<18>")
	)
	(segment
		(start 77.045058 -234.103164)
		(end 78.14818 -235.206286)
		(width 0.0889)
		(layer "In6.Cu")
		(net "M_E_CPU1_SA_DQ<18>")
	)
	(segment
		(start 65.008506 -222.895414)
		(end 67.34175 -225.228658)
		(width 0.14478)
		(layer "In6.Cu")
		(net "M_E_CPU1_SA_DQ<18>")
	)
	(segment
		(start 80.46974 -235.246926)
		(end 80.478122 -235.251752)
		(width 0.0889)
		(layer "In6.Cu")
		(net "M_E_CPU1_SA_DQ<18>")
	)
	(segment
		(start 27.410918 -216.661746)
		(end 27.573986 -216.824814)
		(width 0.14478)
		(layer "In6.Cu")
		(net "M_E_CPU1_SA_DQ<18>")
	)
	(segment
		(start 79.163164 -235.251752)
		(end 79.171546 -235.246926)
		(width 0.0889)
		(layer "In6.Cu")
		(net "M_E_CPU1_SA_DQ<18>")
	)
	(segment
		(start 50.28057 -216.460324)
		(end 53.256434 -216.460324)
		(width 0.14478)
		(layer "In6.Cu")
		(net "M_E_CPU1_SA_DQ<18>")
	)
	(segment
		(start 49.430432 -217.310462)
		(end 50.28057 -216.460324)
		(width 0.14478)
		(layer "In6.Cu")
		(net "M_E_CPU1_SA_DQ<18>")
	)
	(segment
		(start 76.214986 -233.628692)
		(end 76.689458 -234.103164)
		(width 0.0889)
		(layer "In6.Cu")
		(net "M_E_CPU1_SA_DQ<18>")
	)
	(segment
		(start 75.607926 -233.257344)
		(end 75.955906 -233.257344)
		(width 0.0889)
		(layer "In6.Cu")
		(net "M_E_CPU1_SA_DQ<18>")
	)
	(segment
		(start 76.214986 -233.516424)
		(end 76.214986 -233.628692)
		(width 0.0889)
		(layer "In6.Cu")
		(net "M_E_CPU1_SA_DQ<18>")
	)
	(segment
		(start 42.770044 -216.460324)
		(end 45.712634 -216.460324)
		(width 0.14478)
		(layer "In6.Cu")
		(net "M_E_CPU1_SA_DQ<18>")
	)
	(segment
		(start 76.689458 -234.103164)
		(end 77.045058 -234.103164)
		(width 0.0889)
		(layer "In6.Cu")
		(net "M_E_CPU1_SA_DQ<18>")
	)
	(segment
		(start 80.981042 -235.283502)
		(end 81.077054 -235.308902)
		(width 0.0889)
		(layer "In6.Cu")
		(net "M_E_CPU1_SA_DQ<18>")
	)
	(segment
		(start 27.18054 -216.661746)
		(end 27.410918 -216.661746)
		(width 0.14478)
		(layer "In6.Cu")
		(net "M_E_CPU1_SA_DQ<18>")
	)
	(segment
		(start 38.0238 -216.460324)
		(end 38.873938 -217.310462)
		(width 0.14478)
		(layer "In6.Cu")
		(net "M_E_CPU1_SA_DQ<18>")
	)
	(segment
		(start 27.737054 -217.310462)
		(end 34.274252 -217.310462)
		(width 0.14478)
		(layer "In6.Cu")
		(net "M_E_CPU1_SA_DQ<18>")
	)
	(segment
		(start 67.34175 -225.228658)
		(end 67.34175 -226.167696)
		(width 0.14478)
		(layer "In6.Cu")
		(net "M_E_CPU1_SA_DQ<18>")
	)
	(segment
		(start 53.256434 -216.460324)
		(end 54.057296 -217.261186)
		(width 0.14478)
		(layer "In6.Cu")
		(net "M_E_CPU1_SA_DQ<18>")
	)
	(segment
		(start 27.573986 -217.147394)
		(end 27.737054 -217.310462)
		(width 0.14478)
		(layer "In6.Cu")
		(net "M_E_CPU1_SA_DQ<18>")
	)
	(segment
		(start 26.854404 -217.310462)
		(end 27.017472 -217.147394)
		(width 0.14478)
		(layer "In6.Cu")
		(net "M_E_CPU1_SA_DQ<18>")
	)
	(segment
		(start 46.562772 -217.310462)
		(end 49.430432 -217.310462)
		(width 0.14478)
		(layer "In6.Cu")
		(net "M_E_CPU1_SA_DQ<18>")
	)
	(segment
		(start 27.017472 -216.824814)
		(end 27.18054 -216.661746)
		(width 0.14478)
		(layer "In6.Cu")
		(net "M_E_CPU1_SA_DQ<18>")
	)
	(segment
		(start 75.955906 -233.257344)
		(end 76.214986 -233.516424)
		(width 0.0889)
		(layer "In6.Cu")
		(net "M_E_CPU1_SA_DQ<18>")
	)
	(segment
		(start 63.314834 -217.609166)
		(end 65.008506 -219.302838)
		(width 0.14478)
		(layer "In6.Cu")
		(net "M_E_CPU1_SA_DQ<18>")
	)
	(arc
		(start 80.10398 -235.251752)
		(mid 80.286231 -235.201402)
		(end 80.46974 -235.246926)
		(width 0.0889)
		(layer "In6.Cu")
		(net "M_E_CPU1_SA_DQ<18>")
	)
	(arc
		(start 79.537814 -235.251752)
		(mid 79.814881 -235.328023)
		(end 80.093566 -235.257848)
		(width 0.0889)
		(layer "In6.Cu")
		(net "M_E_CPU1_SA_DQ<18>")
	)
	(arc
		(start 79.171546 -235.246926)
		(mid 79.355308 -235.20131)
		(end 79.537814 -235.251752)
		(width 0.0889)
		(layer "In6.Cu")
		(net "M_E_CPU1_SA_DQ<18>")
	)
	(arc
		(start 80.478122 -235.251752)
		(mid 80.725835 -235.326972)
		(end 80.981042 -235.283502)
		(width 0.0889)
		(layer "In6.Cu")
		(net "M_E_CPU1_SA_DQ<18>")
	)
	(arc
		(start 78.603348 -235.255308)
		(mid 78.883737 -235.327977)
		(end 79.163164 -235.251752)
		(width 0.0889)
		(layer "In6.Cu")
		(net "M_E_CPU1_SA_DQ<18>")
	)
	(segment
		(start 82.637884 -235.84027)
		(end 82.171032 -235.574332)
		(width 0.10668)
		(layer "F.Cu")
		(net "M_E_CPU1_SA_DQ<17>")
	)
	(segment
		(start 35.329114 -217.310462)
		(end 38.01491 -217.310462)
		(width 0.14478)
		(layer "In6.Cu")
		(net "M_E_CPU1_SA_DQ<17>")
	)
	(segment
		(start 42.07637 -218.160346)
		(end 42.926254 -217.310462)
		(width 0.14478)
		(layer "In6.Cu")
		(net "M_E_CPU1_SA_DQ<17>")
	)
	(segment
		(start 66.89217 -226.361244)
		(end 74.24293 -233.712004)
		(width 0.14478)
		(layer "In6.Cu")
		(net "M_E_CPU1_SA_DQ<17>")
	)
	(segment
		(start 40.696896 -218.160346)
		(end 40.859964 -218.323414)
		(width 0.14478)
		(layer "In6.Cu")
		(net "M_E_CPU1_SA_DQ<17>")
	)
	(segment
		(start 41.25341 -218.550744)
		(end 41.416478 -218.387676)
		(width 0.14478)
		(layer "In6.Cu")
		(net "M_E_CPU1_SA_DQ<17>")
	)
	(segment
		(start 32.23768 -218.160346)
		(end 33.186624 -218.160346)
		(width 0.14478)
		(layer "In6.Cu")
		(net "M_E_CPU1_SA_DQ<17>")
	)
	(segment
		(start 54.651148 -218.160346)
		(end 54.814216 -218.323414)
		(width 0.14478)
		(layer "In6.Cu")
		(net "M_E_CPU1_SA_DQ<17>")
	)
	(segment
		(start 30.961584 -217.938096)
		(end 31.124652 -217.775028)
		(width 0.14478)
		(layer "In6.Cu")
		(net "M_E_CPU1_SA_DQ<17>")
	)
	(segment
		(start 50.485294 -217.310462)
		(end 53.23459 -217.310462)
		(width 0.14478)
		(layer "In6.Cu")
		(net "M_E_CPU1_SA_DQ<17>")
	)
	(segment
		(start 56.090312 -218.555824)
		(end 56.32069 -218.555824)
		(width 0.14478)
		(layer "In6.Cu")
		(net "M_E_CPU1_SA_DQ<17>")
	)
	(segment
		(start 31.35503 -217.775028)
		(end 31.518098 -217.938096)
		(width 0.14478)
		(layer "In6.Cu")
		(net "M_E_CPU1_SA_DQ<17>")
	)
	(segment
		(start 55.927244 -218.323414)
		(end 55.927244 -218.392756)
		(width 0.14478)
		(layer "In6.Cu")
		(net "M_E_CPU1_SA_DQ<17>")
	)
	(segment
		(start 49.222406 -218.160346)
		(end 49.63541 -218.160346)
		(width 0.14478)
		(layer "In6.Cu")
		(net "M_E_CPU1_SA_DQ<17>")
	)
	(segment
		(start 64.553846 -223.07677)
		(end 66.89217 -225.415094)
		(width 0.14478)
		(layer "In6.Cu")
		(net "M_E_CPU1_SA_DQ<17>")
	)
	(segment
		(start 30.568138 -218.545664)
		(end 30.798516 -218.545664)
		(width 0.14478)
		(layer "In6.Cu")
		(net "M_E_CPU1_SA_DQ<17>")
	)
	(segment
		(start 75.607926 -233.712004)
		(end 75.950826 -233.712004)
		(width 0.0889)
		(layer "In6.Cu")
		(net "M_E_CPU1_SA_DQ<17>")
	)
	(segment
		(start 79.154274 -235.890816)
		(end 79.164688 -235.896912)
		(width 0.0889)
		(layer "In6.Cu")
		(net "M_E_CPU1_SA_DQ<17>")
	)
	(segment
		(start 48.502824 -218.387676)
		(end 48.665892 -218.550744)
		(width 0.14478)
		(layer "In6.Cu")
		(net "M_E_CPU1_SA_DQ<17>")
	)
	(segment
		(start 58.915046 -217.710766)
		(end 59.263026 -218.058746)
		(width 0.14478)
		(layer "In6.Cu")
		(net "M_E_CPU1_SA_DQ<17>")
	)
	(segment
		(start 33.743138 -218.550744)
		(end 33.906206 -218.387676)
		(width 0.14478)
		(layer "In6.Cu")
		(net "M_E_CPU1_SA_DQ<17>")
	)
	(segment
		(start 48.89627 -218.550744)
		(end 49.059338 -218.387676)
		(width 0.14478)
		(layer "In6.Cu")
		(net "M_E_CPU1_SA_DQ<17>")
	)
	(segment
		(start 56.32069 -218.555824)
		(end 56.483758 -218.392756)
		(width 0.14478)
		(layer "In6.Cu")
		(net "M_E_CPU1_SA_DQ<17>")
	)
	(segment
		(start 80.46974 -235.901738)
		(end 80.478122 -235.896912)
		(width 0.0889)
		(layer "In6.Cu")
		(net "M_E_CPU1_SA_DQ<17>")
	)
	(segment
		(start 30.40507 -218.382596)
		(end 30.568138 -218.545664)
		(width 0.14478)
		(layer "In6.Cu")
		(net "M_E_CPU1_SA_DQ<17>")
	)
	(segment
		(start 32.074612 -218.323414)
		(end 32.23768 -218.160346)
		(width 0.14478)
		(layer "In6.Cu")
		(net "M_E_CPU1_SA_DQ<17>")
	)
	(segment
		(start 41.023032 -218.550744)
		(end 41.25341 -218.550744)
		(width 0.14478)
		(layer "In6.Cu")
		(net "M_E_CPU1_SA_DQ<17>")
	)
	(segment
		(start 30.40507 -218.323414)
		(end 30.40507 -218.382596)
		(width 0.14478)
		(layer "In6.Cu")
		(net "M_E_CPU1_SA_DQ<17>")
	)
	(segment
		(start 40.859964 -218.323414)
		(end 40.859964 -218.387676)
		(width 0.14478)
		(layer "In6.Cu")
		(net "M_E_CPU1_SA_DQ<17>")
	)
	(segment
		(start 54.084474 -218.160346)
		(end 54.651148 -218.160346)
		(width 0.14478)
		(layer "In6.Cu")
		(net "M_E_CPU1_SA_DQ<17>")
	)
	(segment
		(start 42.926254 -217.310462)
		(end 45.69079 -217.310462)
		(width 0.14478)
		(layer "In6.Cu")
		(net "M_E_CPU1_SA_DQ<17>")
	)
	(segment
		(start 55.764176 -218.160346)
		(end 55.927244 -218.323414)
		(width 0.14478)
		(layer "In6.Cu")
		(net "M_E_CPU1_SA_DQ<17>")
	)
	(segment
		(start 31.681166 -218.545664)
		(end 31.911544 -218.545664)
		(width 0.14478)
		(layer "In6.Cu")
		(net "M_E_CPU1_SA_DQ<17>")
	)
	(segment
		(start 31.911544 -218.545664)
		(end 32.074612 -218.382596)
		(width 0.14478)
		(layer "In6.Cu")
		(net "M_E_CPU1_SA_DQ<17>")
	)
	(segment
		(start 55.207662 -218.555824)
		(end 55.37073 -218.392756)
		(width 0.14478)
		(layer "In6.Cu")
		(net "M_E_CPU1_SA_DQ<17>")
	)
	(segment
		(start 74.24293 -233.712004)
		(end 75.607926 -233.712004)
		(width 0.14478)
		(layer "In6.Cu")
		(net "M_E_CPU1_SA_DQ<17>")
	)
	(segment
		(start 54.977284 -218.555824)
		(end 55.207662 -218.555824)
		(width 0.14478)
		(layer "In6.Cu")
		(net "M_E_CPU1_SA_DQ<17>")
	)
	(segment
		(start 63.128398 -218.058746)
		(end 64.553846 -219.484194)
		(width 0.14478)
		(layer "In6.Cu")
		(net "M_E_CPU1_SA_DQ<17>")
	)
	(segment
		(start 29.677106 -218.160346)
		(end 30.242002 -218.160346)
		(width 0.14478)
		(layer "In6.Cu")
		(net "M_E_CPU1_SA_DQ<17>")
	)
	(segment
		(start 66.89217 -225.415094)
		(end 66.89217 -226.361244)
		(width 0.14478)
		(layer "In6.Cu")
		(net "M_E_CPU1_SA_DQ<17>")
	)
	(segment
		(start 81.044034 -235.896912)
		(end 81.052416 -235.901738)
		(width 0.0889)
		(layer "In6.Cu")
		(net "M_E_CPU1_SA_DQ<17>")
	)
	(segment
		(start 45.69079 -217.310462)
		(end 46.540674 -218.160346)
		(width 0.14478)
		(layer "In6.Cu")
		(net "M_E_CPU1_SA_DQ<17>")
	)
	(segment
		(start 33.51276 -218.550744)
		(end 33.743138 -218.550744)
		(width 0.14478)
		(layer "In6.Cu")
		(net "M_E_CPU1_SA_DQ<17>")
	)
	(segment
		(start 54.814216 -218.392756)
		(end 54.977284 -218.555824)
		(width 0.14478)
		(layer "In6.Cu")
		(net "M_E_CPU1_SA_DQ<17>")
	)
	(segment
		(start 31.124652 -217.775028)
		(end 31.35503 -217.775028)
		(width 0.14478)
		(layer "In6.Cu")
		(net "M_E_CPU1_SA_DQ<17>")
	)
	(segment
		(start 31.518098 -217.938096)
		(end 31.518098 -218.382596)
		(width 0.14478)
		(layer "In6.Cu")
		(net "M_E_CPU1_SA_DQ<17>")
	)
	(segment
		(start 82.324956 -235.839762)
		(end 82.171032 -235.574332)
		(width 0.0889)
		(layer "In6.Cu")
		(net "M_E_CPU1_SA_DQ<17>")
	)
	(segment
		(start 77.383386 -235.04779)
		(end 78.242668 -235.907072)
		(width 0.0889)
		(layer "In6.Cu")
		(net "M_E_CPU1_SA_DQ<17>")
	)
	(segment
		(start 33.349692 -218.323414)
		(end 33.349692 -218.387676)
		(width 0.14478)
		(layer "In6.Cu")
		(net "M_E_CPU1_SA_DQ<17>")
	)
	(segment
		(start 41.579546 -218.160346)
		(end 42.07637 -218.160346)
		(width 0.14478)
		(layer "In6.Cu")
		(net "M_E_CPU1_SA_DQ<17>")
	)
	(segment
		(start 49.059338 -218.387676)
		(end 49.059338 -218.323414)
		(width 0.14478)
		(layer "In6.Cu")
		(net "M_E_CPU1_SA_DQ<17>")
	)
	(segment
		(start 59.263026 -218.058746)
		(end 63.128398 -218.058746)
		(width 0.14478)
		(layer "In6.Cu")
		(net "M_E_CPU1_SA_DQ<17>")
	)
	(segment
		(start 77.078586 -234.458764)
		(end 77.383386 -234.763564)
		(width 0.0889)
		(layer "In6.Cu")
		(net "M_E_CPU1_SA_DQ<17>")
	)
	(segment
		(start 77.383386 -234.763564)
		(end 77.383386 -235.04779)
		(width 0.0889)
		(layer "In6.Cu")
		(net "M_E_CPU1_SA_DQ<17>")
	)
	(segment
		(start 76.697586 -234.458764)
		(end 77.078586 -234.458764)
		(width 0.0889)
		(layer "In6.Cu")
		(net "M_E_CPU1_SA_DQ<17>")
	)
	(segment
		(start 34.069274 -218.160346)
		(end 34.47923 -218.160346)
		(width 0.14478)
		(layer "In6.Cu")
		(net "M_E_CPU1_SA_DQ<17>")
	)
	(segment
		(start 30.961584 -218.382596)
		(end 30.961584 -217.938096)
		(width 0.14478)
		(layer "In6.Cu")
		(net "M_E_CPU1_SA_DQ<17>")
	)
	(segment
		(start 41.416478 -218.387676)
		(end 41.416478 -218.323414)
		(width 0.14478)
		(layer "In6.Cu")
		(net "M_E_CPU1_SA_DQ<17>")
	)
	(segment
		(start 79.538322 -235.896912)
		(end 79.548736 -235.890816)
		(width 0.0889)
		(layer "In6.Cu")
		(net "M_E_CPU1_SA_DQ<17>")
	)
	(segment
		(start 82.302604 -235.923074)
		(end 82.324956 -235.839762)
		(width 0.0889)
		(layer "In6.Cu")
		(net "M_E_CPU1_SA_DQ<17>")
	)
	(segment
		(start 48.665892 -218.550744)
		(end 48.89627 -218.550744)
		(width 0.14478)
		(layer "In6.Cu")
		(net "M_E_CPU1_SA_DQ<17>")
	)
	(segment
		(start 30.242002 -218.160346)
		(end 30.40507 -218.323414)
		(width 0.14478)
		(layer "In6.Cu")
		(net "M_E_CPU1_SA_DQ<17>")
	)
	(segment
		(start 29.252164 -217.735404)
		(end 29.677106 -218.160346)
		(width 0.14478)
		(layer "In6.Cu")
		(net "M_E_CPU1_SA_DQ<17>")
	)
	(segment
		(start 30.798516 -218.545664)
		(end 30.961584 -218.382596)
		(width 0.14478)
		(layer "In6.Cu")
		(net "M_E_CPU1_SA_DQ<17>")
	)
	(segment
		(start 40.859964 -218.387676)
		(end 41.023032 -218.550744)
		(width 0.14478)
		(layer "In6.Cu")
		(net "M_E_CPU1_SA_DQ<17>")
	)
	(segment
		(start 54.814216 -218.323414)
		(end 54.814216 -218.392756)
		(width 0.14478)
		(layer "In6.Cu")
		(net "M_E_CPU1_SA_DQ<17>")
	)
	(segment
		(start 56.646826 -218.160346)
		(end 57.17921 -218.160346)
		(width 0.14478)
		(layer "In6.Cu")
		(net "M_E_CPU1_SA_DQ<17>")
	)
	(segment
		(start 75.950826 -233.712004)
		(end 76.697586 -234.458764)
		(width 0.0889)
		(layer "In6.Cu")
		(net "M_E_CPU1_SA_DQ<17>")
	)
	(segment
		(start 53.23459 -217.310462)
		(end 54.084474 -218.160346)
		(width 0.14478)
		(layer "In6.Cu")
		(net "M_E_CPU1_SA_DQ<17>")
	)
	(segment
		(start 55.37073 -218.323414)
		(end 55.533798 -218.160346)
		(width 0.14478)
		(layer "In6.Cu")
		(net "M_E_CPU1_SA_DQ<17>")
	)
	(segment
		(start 48.502824 -218.323414)
		(end 48.502824 -218.387676)
		(width 0.14478)
		(layer "In6.Cu")
		(net "M_E_CPU1_SA_DQ<17>")
	)
	(segment
		(start 55.927244 -218.392756)
		(end 56.090312 -218.555824)
		(width 0.14478)
		(layer "In6.Cu")
		(net "M_E_CPU1_SA_DQ<17>")
	)
	(segment
		(start 32.074612 -218.382596)
		(end 32.074612 -218.323414)
		(width 0.14478)
		(layer "In6.Cu")
		(net "M_E_CPU1_SA_DQ<17>")
	)
	(segment
		(start 33.186624 -218.160346)
		(end 33.349692 -218.323414)
		(width 0.14478)
		(layer "In6.Cu")
		(net "M_E_CPU1_SA_DQ<17>")
	)
	(segment
		(start 33.906206 -218.387676)
		(end 33.906206 -218.323414)
		(width 0.14478)
		(layer "In6.Cu")
		(net "M_E_CPU1_SA_DQ<17>")
	)
	(segment
		(start 31.518098 -218.382596)
		(end 31.681166 -218.545664)
		(width 0.14478)
		(layer "In6.Cu")
		(net "M_E_CPU1_SA_DQ<17>")
	)
	(segment
		(start 56.483758 -218.392756)
		(end 56.483758 -218.323414)
		(width 0.14478)
		(layer "In6.Cu")
		(net "M_E_CPU1_SA_DQ<17>")
	)
	(segment
		(start 64.553846 -219.484194)
		(end 64.553846 -223.07677)
		(width 0.14478)
		(layer "In6.Cu")
		(net "M_E_CPU1_SA_DQ<17>")
	)
	(segment
		(start 79.52994 -235.901738)
		(end 79.538322 -235.896912)
		(width 0.0889)
		(layer "In6.Cu")
		(net "M_E_CPU1_SA_DQ<17>")
	)
	(segment
		(start 34.47923 -218.160346)
		(end 35.329114 -217.310462)
		(width 0.14478)
		(layer "In6.Cu")
		(net "M_E_CPU1_SA_DQ<17>")
	)
	(segment
		(start 33.349692 -218.387676)
		(end 33.51276 -218.550744)
		(width 0.14478)
		(layer "In6.Cu")
		(net "M_E_CPU1_SA_DQ<17>")
	)
	(segment
		(start 57.17921 -218.160346)
		(end 57.62879 -217.710766)
		(width 0.14478)
		(layer "In6.Cu")
		(net "M_E_CPU1_SA_DQ<17>")
	)
	(segment
		(start 49.059338 -218.323414)
		(end 49.222406 -218.160346)
		(width 0.14478)
		(layer "In6.Cu")
		(net "M_E_CPU1_SA_DQ<17>")
	)
	(segment
		(start 56.483758 -218.323414)
		(end 56.646826 -218.160346)
		(width 0.14478)
		(layer "In6.Cu")
		(net "M_E_CPU1_SA_DQ<17>")
	)
	(segment
		(start 49.63541 -218.160346)
		(end 50.485294 -217.310462)
		(width 0.14478)
		(layer "In6.Cu")
		(net "M_E_CPU1_SA_DQ<17>")
	)
	(segment
		(start 46.540674 -218.160346)
		(end 48.339756 -218.160346)
		(width 0.14478)
		(layer "In6.Cu")
		(net "M_E_CPU1_SA_DQ<17>")
	)
	(segment
		(start 38.01491 -217.310462)
		(end 38.864794 -218.160346)
		(width 0.14478)
		(layer "In6.Cu")
		(net "M_E_CPU1_SA_DQ<17>")
	)
	(segment
		(start 33.906206 -218.323414)
		(end 34.069274 -218.160346)
		(width 0.14478)
		(layer "In6.Cu")
		(net "M_E_CPU1_SA_DQ<17>")
	)
	(segment
		(start 38.864794 -218.160346)
		(end 40.696896 -218.160346)
		(width 0.14478)
		(layer "In6.Cu")
		(net "M_E_CPU1_SA_DQ<17>")
	)
	(segment
		(start 41.416478 -218.323414)
		(end 41.579546 -218.160346)
		(width 0.14478)
		(layer "In6.Cu")
		(net "M_E_CPU1_SA_DQ<17>")
	)
	(segment
		(start 48.339756 -218.160346)
		(end 48.502824 -218.323414)
		(width 0.14478)
		(layer "In6.Cu")
		(net "M_E_CPU1_SA_DQ<17>")
	)
	(segment
		(start 55.533798 -218.160346)
		(end 55.764176 -218.160346)
		(width 0.14478)
		(layer "In6.Cu")
		(net "M_E_CPU1_SA_DQ<17>")
	)
	(segment
		(start 57.62879 -217.710766)
		(end 58.915046 -217.710766)
		(width 0.14478)
		(layer "In6.Cu")
		(net "M_E_CPU1_SA_DQ<17>")
	)
	(segment
		(start 55.37073 -218.392756)
		(end 55.37073 -218.323414)
		(width 0.14478)
		(layer "In6.Cu")
		(net "M_E_CPU1_SA_DQ<17>")
	)
	(arc
		(start 78.242668 -235.907072)
		(mid 78.421897 -235.947225)
		(end 78.598522 -235.896912)
		(width 0.0889)
		(layer "In6.Cu")
		(net "M_E_CPU1_SA_DQ<17>")
	)
	(arc
		(start 78.598522 -235.896912)
		(mid 78.875589 -235.820641)
		(end 79.154274 -235.890816)
		(width 0.0889)
		(layer "In6.Cu")
		(net "M_E_CPU1_SA_DQ<17>")
	)
	(arc
		(start 79.548736 -235.890816)
		(mid 79.827168 -235.820718)
		(end 80.10398 -235.896912)
		(width 0.0889)
		(layer "In6.Cu")
		(net "M_E_CPU1_SA_DQ<17>")
	)
	(arc
		(start 81.984088 -235.896912)
		(mid 82.140407 -235.945907)
		(end 82.302604 -235.923074)
		(width 0.0889)
		(layer "In6.Cu")
		(net "M_E_CPU1_SA_DQ<17>")
	)
	(arc
		(start 79.164688 -235.896912)
		(mid 79.346685 -235.947134)
		(end 79.52994 -235.901738)
		(width 0.0889)
		(layer "In6.Cu")
		(net "M_E_CPU1_SA_DQ<17>")
	)
	(arc
		(start 81.418176 -235.896912)
		(mid 81.701132 -235.820735)
		(end 81.984088 -235.896912)
		(width 0.0889)
		(layer "In6.Cu")
		(net "M_E_CPU1_SA_DQ<17>")
	)
	(arc
		(start 80.478122 -235.896912)
		(mid 80.761078 -235.820735)
		(end 81.044034 -235.896912)
		(width 0.0889)
		(layer "In6.Cu")
		(net "M_E_CPU1_SA_DQ<17>")
	)
	(arc
		(start 80.10398 -235.896912)
		(mid 80.286231 -235.947262)
		(end 80.46974 -235.901738)
		(width 0.0889)
		(layer "In6.Cu")
		(net "M_E_CPU1_SA_DQ<17>")
	)
	(arc
		(start 81.052416 -235.901738)
		(mid 81.235924 -235.947232)
		(end 81.418176 -235.896912)
		(width 0.0889)
		(layer "In6.Cu")
		(net "M_E_CPU1_SA_DQ<17>")
	)
	(segment
		(start 81.22793 -235.030264)
		(end 80.761078 -234.764326)
		(width 0.10668)
		(layer "F.Cu")
		(net "M_E_CPU1_SA_DQ<16>")
	)
	(segment
		(start 40.950388 -216.623392)
		(end 40.950388 -216.690956)
		(width 0.14478)
		(layer "In6.Cu")
		(net "M_E_CPU1_SA_DQ<16>")
	)
	(segment
		(start 56.345836 -216.171526)
		(end 56.490616 -216.316306)
		(width 0.14478)
		(layer "In6.Cu")
		(net "M_E_CPU1_SA_DQ<16>")
	)
	(segment
		(start 30.794452 -216.3064)
		(end 30.794452 -216.692226)
		(width 0.14478)
		(layer "In6.Cu")
		(net "M_E_CPU1_SA_DQ<16>")
	)
	(segment
		(start 75.955906 -232.802684)
		(end 76.418186 -233.264964)
		(width 0.0889)
		(layer "In6.Cu")
		(net "M_E_CPU1_SA_DQ<16>")
	)
	(segment
		(start 42.926254 -215.61044)
		(end 45.69079 -215.61044)
		(width 0.14478)
		(layer "In6.Cu")
		(net "M_E_CPU1_SA_DQ<16>")
	)
	(segment
		(start 48.723804 -216.841324)
		(end 48.954182 -216.841324)
		(width 0.14478)
		(layer "In6.Cu")
		(net "M_E_CPU1_SA_DQ<16>")
	)
	(segment
		(start 59.658504 -216.410286)
		(end 60.407804 -217.159586)
		(width 0.14478)
		(layer "In6.Cu")
		(net "M_E_CPU1_SA_DQ<16>")
	)
	(segment
		(start 33.234376 -216.460324)
		(end 33.397444 -216.623392)
		(width 0.14478)
		(layer "In6.Cu")
		(net "M_E_CPU1_SA_DQ<16>")
	)
	(segment
		(start 58.91657 -216.410286)
		(end 59.658504 -216.410286)
		(width 0.14478)
		(layer "In6.Cu")
		(net "M_E_CPU1_SA_DQ<16>")
	)
	(segment
		(start 38.01491 -215.61044)
		(end 38.864794 -216.460324)
		(width 0.14478)
		(layer "In6.Cu")
		(net "M_E_CPU1_SA_DQ<16>")
	)
	(segment
		(start 48.397668 -216.460324)
		(end 48.560736 -216.623392)
		(width 0.14478)
		(layer "In6.Cu")
		(net "M_E_CPU1_SA_DQ<16>")
	)
	(segment
		(start 80.915002 -235.029756)
		(end 80.761078 -234.764326)
		(width 0.0889)
		(layer "In6.Cu")
		(net "M_E_CPU1_SA_DQ<16>")
	)
	(segment
		(start 57.199276 -216.171526)
		(end 57.473596 -216.171526)
		(width 0.14478)
		(layer "In6.Cu")
		(net "M_E_CPU1_SA_DQ<16>")
	)
	(segment
		(start 55.926736 -216.316306)
		(end 56.071516 -216.171526)
		(width 0.14478)
		(layer "In6.Cu")
		(net "M_E_CPU1_SA_DQ<16>")
	)
	(segment
		(start 75.607926 -232.802684)
		(end 75.955906 -232.802684)
		(width 0.0889)
		(layer "In6.Cu")
		(net "M_E_CPU1_SA_DQ<16>")
	)
	(segment
		(start 29.677106 -216.460324)
		(end 29.949394 -216.460324)
		(width 0.14478)
		(layer "In6.Cu")
		(net "M_E_CPU1_SA_DQ<16>")
	)
	(segment
		(start 57.763156 -216.811606)
		(end 58.51525 -216.811606)
		(width 0.14478)
		(layer "In6.Cu")
		(net "M_E_CPU1_SA_DQ<16>")
	)
	(segment
		(start 33.953958 -216.623392)
		(end 34.117026 -216.460324)
		(width 0.14478)
		(layer "In6.Cu")
		(net "M_E_CPU1_SA_DQ<16>")
	)
	(segment
		(start 33.953958 -216.685876)
		(end 33.953958 -216.623392)
		(width 0.14478)
		(layer "In6.Cu")
		(net "M_E_CPU1_SA_DQ<16>")
	)
	(segment
		(start 45.69079 -215.61044)
		(end 46.540674 -216.460324)
		(width 0.14478)
		(layer "In6.Cu")
		(net "M_E_CPU1_SA_DQ<16>")
	)
	(segment
		(start 56.635396 -216.811606)
		(end 56.909716 -216.811606)
		(width 0.14478)
		(layer "In6.Cu")
		(net "M_E_CPU1_SA_DQ<16>")
	)
	(segment
		(start 57.618376 -216.316306)
		(end 57.618376 -216.666826)
		(width 0.14478)
		(layer "In6.Cu")
		(net "M_E_CPU1_SA_DQ<16>")
	)
	(segment
		(start 76.418186 -233.264964)
		(end 76.418186 -233.544364)
		(width 0.0889)
		(layer "In6.Cu")
		(net "M_E_CPU1_SA_DQ<16>")
	)
	(segment
		(start 60.407804 -217.159586)
		(end 63.50127 -217.159586)
		(width 0.14478)
		(layer "In6.Cu")
		(net "M_E_CPU1_SA_DQ<16>")
	)
	(segment
		(start 56.490616 -216.316306)
		(end 56.490616 -216.666826)
		(width 0.14478)
		(layer "In6.Cu")
		(net "M_E_CPU1_SA_DQ<16>")
	)
	(segment
		(start 56.490616 -216.666826)
		(end 56.635396 -216.811606)
		(width 0.14478)
		(layer "In6.Cu")
		(net "M_E_CPU1_SA_DQ<16>")
	)
	(segment
		(start 49.11725 -216.678256)
		(end 49.11725 -216.623392)
		(width 0.14478)
		(layer "In6.Cu")
		(net "M_E_CPU1_SA_DQ<16>")
	)
	(segment
		(start 57.473596 -216.171526)
		(end 57.618376 -216.316306)
		(width 0.14478)
		(layer "In6.Cu")
		(net "M_E_CPU1_SA_DQ<16>")
	)
	(segment
		(start 31.358332 -216.692226)
		(end 31.358332 -216.3064)
		(width 0.14478)
		(layer "In6.Cu")
		(net "M_E_CPU1_SA_DQ<16>")
	)
	(segment
		(start 40.78732 -216.460324)
		(end 40.950388 -216.623392)
		(width 0.14478)
		(layer "In6.Cu")
		(net "M_E_CPU1_SA_DQ<16>")
	)
	(segment
		(start 34.117026 -216.460324)
		(end 34.47923 -216.460324)
		(width 0.14478)
		(layer "In6.Cu")
		(net "M_E_CPU1_SA_DQ<16>")
	)
	(segment
		(start 57.054496 -216.666826)
		(end 57.054496 -216.316306)
		(width 0.14478)
		(layer "In6.Cu")
		(net "M_E_CPU1_SA_DQ<16>")
	)
	(segment
		(start 35.329114 -215.61044)
		(end 38.01491 -215.61044)
		(width 0.14478)
		(layer "In6.Cu")
		(net "M_E_CPU1_SA_DQ<16>")
	)
	(segment
		(start 65.463166 -219.121482)
		(end 65.463166 -222.714058)
		(width 0.14478)
		(layer "In6.Cu")
		(net "M_E_CPU1_SA_DQ<16>")
	)
	(segment
		(start 30.794452 -216.692226)
		(end 30.939232 -216.837006)
		(width 0.14478)
		(layer "In6.Cu")
		(net "M_E_CPU1_SA_DQ<16>")
	)
	(segment
		(start 76.418186 -233.544364)
		(end 76.773786 -233.899964)
		(width 0.0889)
		(layer "In6.Cu")
		(net "M_E_CPU1_SA_DQ<16>")
	)
	(segment
		(start 29.949394 -216.460324)
		(end 30.248098 -216.16162)
		(width 0.14478)
		(layer "In6.Cu")
		(net "M_E_CPU1_SA_DQ<16>")
	)
	(segment
		(start 56.909716 -216.811606)
		(end 57.054496 -216.666826)
		(width 0.14478)
		(layer "In6.Cu")
		(net "M_E_CPU1_SA_DQ<16>")
	)
	(segment
		(start 31.358332 -216.3064)
		(end 31.503112 -216.16162)
		(width 0.14478)
		(layer "In6.Cu")
		(net "M_E_CPU1_SA_DQ<16>")
	)
	(segment
		(start 33.397444 -216.685876)
		(end 33.560512 -216.848944)
		(width 0.14478)
		(layer "In6.Cu")
		(net "M_E_CPU1_SA_DQ<16>")
	)
	(segment
		(start 65.463166 -222.714058)
		(end 67.79133 -225.042222)
		(width 0.14478)
		(layer "In6.Cu")
		(net "M_E_CPU1_SA_DQ<16>")
	)
	(segment
		(start 30.939232 -216.837006)
		(end 31.213552 -216.837006)
		(width 0.14478)
		(layer "In6.Cu")
		(net "M_E_CPU1_SA_DQ<16>")
	)
	(segment
		(start 74.619866 -232.802684)
		(end 75.607926 -232.802684)
		(width 0.14478)
		(layer "In6.Cu")
		(net "M_E_CPU1_SA_DQ<16>")
	)
	(segment
		(start 31.213552 -216.837006)
		(end 31.358332 -216.692226)
		(width 0.14478)
		(layer "In6.Cu")
		(net "M_E_CPU1_SA_DQ<16>")
	)
	(segment
		(start 55.781956 -216.811606)
		(end 55.926736 -216.666826)
		(width 0.14478)
		(layer "In6.Cu")
		(net "M_E_CPU1_SA_DQ<16>")
	)
	(segment
		(start 79.99984 -235.091732)
		(end 80.008222 -235.086906)
		(width 0.0889)
		(layer "In6.Cu")
		(net "M_E_CPU1_SA_DQ<16>")
	)
	(segment
		(start 48.954182 -216.841324)
		(end 49.11725 -216.678256)
		(width 0.14478)
		(layer "In6.Cu")
		(net "M_E_CPU1_SA_DQ<16>")
	)
	(segment
		(start 50.485294 -215.61044)
		(end 53.23459 -215.61044)
		(width 0.14478)
		(layer "In6.Cu")
		(net "M_E_CPU1_SA_DQ<16>")
	)
	(segment
		(start 41.343834 -216.854024)
		(end 41.506902 -216.690956)
		(width 0.14478)
		(layer "In6.Cu")
		(net "M_E_CPU1_SA_DQ<16>")
	)
	(segment
		(start 80.89265 -235.113068)
		(end 80.915002 -235.029756)
		(width 0.0889)
		(layer "In6.Cu")
		(net "M_E_CPU1_SA_DQ<16>")
	)
	(segment
		(start 53.23459 -215.61044)
		(end 54.435756 -216.811606)
		(width 0.14478)
		(layer "In6.Cu")
		(net "M_E_CPU1_SA_DQ<16>")
	)
	(segment
		(start 49.11725 -216.623392)
		(end 49.280318 -216.460324)
		(width 0.14478)
		(layer "In6.Cu")
		(net "M_E_CPU1_SA_DQ<16>")
	)
	(segment
		(start 29.252164 -216.035382)
		(end 29.677106 -216.460324)
		(width 0.14478)
		(layer "In6.Cu")
		(net "M_E_CPU1_SA_DQ<16>")
	)
	(segment
		(start 41.506902 -216.623392)
		(end 41.66997 -216.460324)
		(width 0.14478)
		(layer "In6.Cu")
		(net "M_E_CPU1_SA_DQ<16>")
	)
	(segment
		(start 78.233778 -235.004356)
		(end 78.448408 -235.004356)
		(width 0.0889)
		(layer "In6.Cu")
		(net "M_E_CPU1_SA_DQ<16>")
	)
	(segment
		(start 67.79133 -225.042222)
		(end 67.79133 -225.974148)
		(width 0.14478)
		(layer "In6.Cu")
		(net "M_E_CPU1_SA_DQ<16>")
	)
	(segment
		(start 56.071516 -216.171526)
		(end 56.345836 -216.171526)
		(width 0.14478)
		(layer "In6.Cu")
		(net "M_E_CPU1_SA_DQ<16>")
	)
	(segment
		(start 30.248098 -216.16162)
		(end 30.649672 -216.16162)
		(width 0.14478)
		(layer "In6.Cu")
		(net "M_E_CPU1_SA_DQ<16>")
	)
	(segment
		(start 48.560736 -216.678256)
		(end 48.723804 -216.841324)
		(width 0.14478)
		(layer "In6.Cu")
		(net "M_E_CPU1_SA_DQ<16>")
	)
	(segment
		(start 49.63541 -216.460324)
		(end 50.485294 -215.61044)
		(width 0.14478)
		(layer "In6.Cu")
		(net "M_E_CPU1_SA_DQ<16>")
	)
	(segment
		(start 42.07637 -216.460324)
		(end 42.926254 -215.61044)
		(width 0.14478)
		(layer "In6.Cu")
		(net "M_E_CPU1_SA_DQ<16>")
	)
	(segment
		(start 32.26181 -216.460324)
		(end 33.234376 -216.460324)
		(width 0.14478)
		(layer "In6.Cu")
		(net "M_E_CPU1_SA_DQ<16>")
	)
	(segment
		(start 67.79133 -225.974148)
		(end 74.619866 -232.802684)
		(width 0.14478)
		(layer "In6.Cu")
		(net "M_E_CPU1_SA_DQ<16>")
	)
	(segment
		(start 31.503112 -216.16162)
		(end 31.963106 -216.16162)
		(width 0.14478)
		(layer "In6.Cu")
		(net "M_E_CPU1_SA_DQ<16>")
	)
	(segment
		(start 57.618376 -216.666826)
		(end 57.763156 -216.811606)
		(width 0.14478)
		(layer "In6.Cu")
		(net "M_E_CPU1_SA_DQ<16>")
	)
	(segment
		(start 31.963106 -216.16162)
		(end 32.26181 -216.460324)
		(width 0.14478)
		(layer "In6.Cu")
		(net "M_E_CPU1_SA_DQ<16>")
	)
	(segment
		(start 54.435756 -216.811606)
		(end 55.781956 -216.811606)
		(width 0.14478)
		(layer "In6.Cu")
		(net "M_E_CPU1_SA_DQ<16>")
	)
	(segment
		(start 63.50127 -217.159586)
		(end 65.463166 -219.121482)
		(width 0.14478)
		(layer "In6.Cu")
		(net "M_E_CPU1_SA_DQ<16>")
	)
	(segment
		(start 38.864794 -216.460324)
		(end 40.78732 -216.460324)
		(width 0.14478)
		(layer "In6.Cu")
		(net "M_E_CPU1_SA_DQ<16>")
	)
	(segment
		(start 55.926736 -216.666826)
		(end 55.926736 -216.316306)
		(width 0.14478)
		(layer "In6.Cu")
		(net "M_E_CPU1_SA_DQ<16>")
	)
	(segment
		(start 57.054496 -216.316306)
		(end 57.199276 -216.171526)
		(width 0.14478)
		(layer "In6.Cu")
		(net "M_E_CPU1_SA_DQ<16>")
	)
	(segment
		(start 41.506902 -216.690956)
		(end 41.506902 -216.623392)
		(width 0.14478)
		(layer "In6.Cu")
		(net "M_E_CPU1_SA_DQ<16>")
	)
	(segment
		(start 33.79089 -216.848944)
		(end 33.953958 -216.685876)
		(width 0.14478)
		(layer "In6.Cu")
		(net "M_E_CPU1_SA_DQ<16>")
	)
	(segment
		(start 33.560512 -216.848944)
		(end 33.79089 -216.848944)
		(width 0.14478)
		(layer "In6.Cu")
		(net "M_E_CPU1_SA_DQ<16>")
	)
	(segment
		(start 30.649672 -216.16162)
		(end 30.794452 -216.3064)
		(width 0.14478)
		(layer "In6.Cu")
		(net "M_E_CPU1_SA_DQ<16>")
	)
	(segment
		(start 33.397444 -216.623392)
		(end 33.397444 -216.685876)
		(width 0.14478)
		(layer "In6.Cu")
		(net "M_E_CPU1_SA_DQ<16>")
	)
	(segment
		(start 34.47923 -216.460324)
		(end 35.329114 -215.61044)
		(width 0.14478)
		(layer "In6.Cu")
		(net "M_E_CPU1_SA_DQ<16>")
	)
	(segment
		(start 49.280318 -216.460324)
		(end 49.63541 -216.460324)
		(width 0.14478)
		(layer "In6.Cu")
		(net "M_E_CPU1_SA_DQ<16>")
	)
	(segment
		(start 41.113456 -216.854024)
		(end 41.343834 -216.854024)
		(width 0.14478)
		(layer "In6.Cu")
		(net "M_E_CPU1_SA_DQ<16>")
	)
	(segment
		(start 48.560736 -216.623392)
		(end 48.560736 -216.678256)
		(width 0.14478)
		(layer "In6.Cu")
		(net "M_E_CPU1_SA_DQ<16>")
	)
	(segment
		(start 79.067406 -235.086906)
		(end 79.07782 -235.08081)
		(width 0.0889)
		(layer "In6.Cu")
		(net "M_E_CPU1_SA_DQ<16>")
	)
	(segment
		(start 76.773786 -233.899964)
		(end 77.129386 -233.899964)
		(width 0.0889)
		(layer "In6.Cu")
		(net "M_E_CPU1_SA_DQ<16>")
	)
	(segment
		(start 41.66997 -216.460324)
		(end 42.07637 -216.460324)
		(width 0.14478)
		(layer "In6.Cu")
		(net "M_E_CPU1_SA_DQ<16>")
	)
	(segment
		(start 46.540674 -216.460324)
		(end 48.397668 -216.460324)
		(width 0.14478)
		(layer "In6.Cu")
		(net "M_E_CPU1_SA_DQ<16>")
	)
	(segment
		(start 40.950388 -216.690956)
		(end 41.113456 -216.854024)
		(width 0.14478)
		(layer "In6.Cu")
		(net "M_E_CPU1_SA_DQ<16>")
	)
	(segment
		(start 58.51525 -216.811606)
		(end 58.91657 -216.410286)
		(width 0.14478)
		(layer "In6.Cu")
		(net "M_E_CPU1_SA_DQ<16>")
	)
	(segment
		(start 77.129386 -233.899964)
		(end 78.233778 -235.004356)
		(width 0.0889)
		(layer "In6.Cu")
		(net "M_E_CPU1_SA_DQ<16>")
	)
	(arc
		(start 78.536546 -235.017818)
		(mid 78.625409 -235.051953)
		(end 78.709774 -235.09605)
		(width 0.0889)
		(layer "In6.Cu")
		(net "M_E_CPU1_SA_DQ<16>")
	)
	(arc
		(start 78.448408 -235.004356)
		(mid 78.492996 -235.007685)
		(end 78.536546 -235.017818)
		(width 0.0889)
		(layer "In6.Cu")
		(net "M_E_CPU1_SA_DQ<16>")
	)
	(arc
		(start 79.633572 -235.086906)
		(mid 79.816077 -235.137383)
		(end 79.99984 -235.091732)
		(width 0.0889)
		(layer "In6.Cu")
		(net "M_E_CPU1_SA_DQ<16>")
	)
	(arc
		(start 78.709774 -235.09605)
		(mid 78.889756 -235.13715)
		(end 79.067406 -235.086906)
		(width 0.0889)
		(layer "In6.Cu")
		(net "M_E_CPU1_SA_DQ<16>")
	)
	(arc
		(start 80.008222 -235.086906)
		(mid 80.291178 -235.010729)
		(end 80.574134 -235.086906)
		(width 0.0889)
		(layer "In6.Cu")
		(net "M_E_CPU1_SA_DQ<16>")
	)
	(arc
		(start 79.07782 -235.08081)
		(mid 79.356506 -235.01059)
		(end 79.633572 -235.086906)
		(width 0.0889)
		(layer "In6.Cu")
		(net "M_E_CPU1_SA_DQ<16>")
	)
	(arc
		(start 80.574134 -235.086906)
		(mid 80.730453 -235.135901)
		(end 80.89265 -235.113068)
		(width 0.0889)
		(layer "In6.Cu")
		(net "M_E_CPU1_SA_DQ<16>")
	)
	(segment
		(start 83.107784 -235.030264)
		(end 82.640932 -234.764326)
		(width 0.10668)
		(layer "F.Cu")
		(net "M_E_CPU1_SA_DQ<15>")
	)
	(segment
		(start 58.32983 -215.859106)
		(end 59.88685 -215.859106)
		(width 0.14478)
		(layer "In6.Cu")
		(net "M_E_CPU1_SA_DQ<15>")
	)
	(segment
		(start 66.049906 -218.928696)
		(end 66.049906 -222.521272)
		(width 0.14478)
		(layer "In6.Cu")
		(net "M_E_CPU1_SA_DQ<15>")
	)
	(segment
		(start 26.256234 -215.61044)
		(end 26.419302 -215.447372)
		(width 0.14478)
		(layer "In6.Cu")
		(net "M_E_CPU1_SA_DQ<15>")
	)
	(segment
		(start 27.53233 -215.447372)
		(end 27.53233 -215.148414)
		(width 0.14478)
		(layer "In6.Cu")
		(net "M_E_CPU1_SA_DQ<15>")
	)
	(segment
		(start 34.299652 -215.61044)
		(end 35.14979 -214.760302)
		(width 0.14478)
		(layer "In6.Cu")
		(net "M_E_CPU1_SA_DQ<15>")
	)
	(segment
		(start 79.62392 -234.447842)
		(end 79.634334 -234.441746)
		(width 0.0889)
		(layer "In6.Cu")
		(net "M_E_CPU1_SA_DQ<15>")
	)
	(segment
		(start 27.925776 -214.985346)
		(end 28.088844 -215.148414)
		(width 0.14478)
		(layer "In6.Cu")
		(net "M_E_CPU1_SA_DQ<15>")
	)
	(segment
		(start 63.729616 -216.608406)
		(end 66.049906 -218.928696)
		(width 0.14478)
		(layer "In6.Cu")
		(net "M_E_CPU1_SA_DQ<15>")
	)
	(segment
		(start 25.152096 -215.185244)
		(end 25.577292 -215.61044)
		(width 0.14478)
		(layer "In6.Cu")
		(net "M_E_CPU1_SA_DQ<15>")
	)
	(segment
		(start 49.620932 -215.61044)
		(end 50.47107 -214.760302)
		(width 0.14478)
		(layer "In6.Cu")
		(net "M_E_CPU1_SA_DQ<15>")
	)
	(segment
		(start 58.081164 -215.61044)
		(end 58.32983 -215.859106)
		(width 0.14478)
		(layer "In6.Cu")
		(net "M_E_CPU1_SA_DQ<15>")
	)
	(segment
		(start 26.419302 -215.447372)
		(end 26.419302 -215.110314)
		(width 0.14478)
		(layer "In6.Cu")
		(net "M_E_CPU1_SA_DQ<15>")
	)
	(segment
		(start 27.695398 -214.985346)
		(end 27.925776 -214.985346)
		(width 0.14478)
		(layer "In6.Cu")
		(net "M_E_CPU1_SA_DQ<15>")
	)
	(segment
		(start 41.980866 -215.61044)
		(end 42.831004 -214.760302)
		(width 0.14478)
		(layer "In6.Cu")
		(net "M_E_CPU1_SA_DQ<15>")
	)
	(segment
		(start 26.975816 -215.110314)
		(end 26.975816 -215.447372)
		(width 0.14478)
		(layer "In6.Cu")
		(net "M_E_CPU1_SA_DQ<15>")
	)
	(segment
		(start 68.34251 -224.813876)
		(end 68.34251 -225.731832)
		(width 0.14478)
		(layer "In6.Cu")
		(net "M_E_CPU1_SA_DQ<15>")
	)
	(segment
		(start 77.17663 -233.58348)
		(end 77.922882 -234.329732)
		(width 0.0889)
		(layer "In6.Cu")
		(net "M_E_CPU1_SA_DQ<15>")
	)
	(segment
		(start 38.873938 -215.61044)
		(end 41.980866 -215.61044)
		(width 0.14478)
		(layer "In6.Cu")
		(net "M_E_CPU1_SA_DQ<15>")
	)
	(segment
		(start 46.562772 -215.61044)
		(end 49.620932 -215.61044)
		(width 0.14478)
		(layer "In6.Cu")
		(net "M_E_CPU1_SA_DQ<15>")
	)
	(segment
		(start 79.056992 -234.434888)
		(end 79.068676 -234.441746)
		(width 0.0889)
		(layer "In6.Cu")
		(net "M_E_CPU1_SA_DQ<15>")
	)
	(segment
		(start 79.634334 -234.441746)
		(end 79.646018 -234.434888)
		(width 0.0889)
		(layer "In6.Cu")
		(net "M_E_CPU1_SA_DQ<15>")
	)
	(segment
		(start 45.712634 -214.760302)
		(end 46.562772 -215.61044)
		(width 0.14478)
		(layer "In6.Cu")
		(net "M_E_CPU1_SA_DQ<15>")
	)
	(segment
		(start 25.577292 -215.61044)
		(end 26.256234 -215.61044)
		(width 0.14478)
		(layer "In6.Cu")
		(net "M_E_CPU1_SA_DQ<15>")
	)
	(segment
		(start 35.14979 -214.760302)
		(end 38.0238 -214.760302)
		(width 0.14478)
		(layer "In6.Cu")
		(net "M_E_CPU1_SA_DQ<15>")
	)
	(segment
		(start 42.831004 -214.760302)
		(end 45.712634 -214.760302)
		(width 0.14478)
		(layer "In6.Cu")
		(net "M_E_CPU1_SA_DQ<15>")
	)
	(segment
		(start 26.419302 -215.110314)
		(end 26.58237 -214.947246)
		(width 0.14478)
		(layer "In6.Cu")
		(net "M_E_CPU1_SA_DQ<15>")
	)
	(segment
		(start 27.138884 -215.61044)
		(end 27.369262 -215.61044)
		(width 0.14478)
		(layer "In6.Cu")
		(net "M_E_CPU1_SA_DQ<15>")
	)
	(segment
		(start 77.922882 -234.329732)
		(end 78.14056 -234.448858)
		(width 0.0889)
		(layer "In6.Cu")
		(net "M_E_CPU1_SA_DQ<15>")
	)
	(segment
		(start 26.58237 -214.947246)
		(end 26.812748 -214.947246)
		(width 0.14478)
		(layer "In6.Cu")
		(net "M_E_CPU1_SA_DQ<15>")
	)
	(segment
		(start 82.487008 -234.498896)
		(end 82.640932 -234.764326)
		(width 0.0889)
		(layer "In6.Cu")
		(net "M_E_CPU1_SA_DQ<15>")
	)
	(segment
		(start 28.088844 -215.148414)
		(end 28.088844 -215.447372)
		(width 0.14478)
		(layer "In6.Cu")
		(net "M_E_CPU1_SA_DQ<15>")
	)
	(segment
		(start 82.390996 -234.473496)
		(end 82.487008 -234.498896)
		(width 0.0889)
		(layer "In6.Cu")
		(net "M_E_CPU1_SA_DQ<15>")
	)
	(segment
		(start 74.857102 -232.246424)
		(end 75.607926 -232.246424)
		(width 0.14478)
		(layer "In6.Cu")
		(net "M_E_CPU1_SA_DQ<15>")
	)
	(segment
		(start 66.049906 -222.521272)
		(end 68.34251 -224.813876)
		(width 0.14478)
		(layer "In6.Cu")
		(net "M_E_CPU1_SA_DQ<15>")
	)
	(segment
		(start 77.17663 -233.223816)
		(end 77.17663 -233.58348)
		(width 0.0889)
		(layer "In6.Cu")
		(net "M_E_CPU1_SA_DQ<15>")
	)
	(segment
		(start 76.992734 -233.03992)
		(end 77.17663 -233.223816)
		(width 0.0889)
		(layer "In6.Cu")
		(net "M_E_CPU1_SA_DQ<15>")
	)
	(segment
		(start 75.607926 -232.246424)
		(end 75.915266 -232.246424)
		(width 0.0889)
		(layer "In6.Cu")
		(net "M_E_CPU1_SA_DQ<15>")
	)
	(segment
		(start 28.088844 -215.447372)
		(end 28.251912 -215.61044)
		(width 0.14478)
		(layer "In6.Cu")
		(net "M_E_CPU1_SA_DQ<15>")
	)
	(segment
		(start 75.915266 -232.246424)
		(end 76.708762 -233.03992)
		(width 0.0889)
		(layer "In6.Cu")
		(net "M_E_CPU1_SA_DQ<15>")
	)
	(segment
		(start 59.88685 -215.859106)
		(end 60.63615 -216.608406)
		(width 0.14478)
		(layer "In6.Cu")
		(net "M_E_CPU1_SA_DQ<15>")
	)
	(segment
		(start 53.256434 -214.760302)
		(end 54.106572 -215.61044)
		(width 0.14478)
		(layer "In6.Cu")
		(net "M_E_CPU1_SA_DQ<15>")
	)
	(segment
		(start 27.369262 -215.61044)
		(end 27.53233 -215.447372)
		(width 0.14478)
		(layer "In6.Cu")
		(net "M_E_CPU1_SA_DQ<15>")
	)
	(segment
		(start 76.708762 -233.03992)
		(end 76.992734 -233.03992)
		(width 0.0889)
		(layer "In6.Cu")
		(net "M_E_CPU1_SA_DQ<15>")
	)
	(segment
		(start 68.34251 -225.731832)
		(end 74.857102 -232.246424)
		(width 0.14478)
		(layer "In6.Cu")
		(net "M_E_CPU1_SA_DQ<15>")
	)
	(segment
		(start 54.106572 -215.61044)
		(end 58.081164 -215.61044)
		(width 0.14478)
		(layer "In6.Cu")
		(net "M_E_CPU1_SA_DQ<15>")
	)
	(segment
		(start 27.53233 -215.148414)
		(end 27.695398 -214.985346)
		(width 0.14478)
		(layer "In6.Cu")
		(net "M_E_CPU1_SA_DQ<15>")
	)
	(segment
		(start 81.879694 -234.43692)
		(end 81.888076 -234.441746)
		(width 0.0889)
		(layer "In6.Cu")
		(net "M_E_CPU1_SA_DQ<15>")
	)
	(segment
		(start 50.47107 -214.760302)
		(end 53.256434 -214.760302)
		(width 0.14478)
		(layer "In6.Cu")
		(net "M_E_CPU1_SA_DQ<15>")
	)
	(segment
		(start 60.63615 -216.608406)
		(end 63.729616 -216.608406)
		(width 0.14478)
		(layer "In6.Cu")
		(net "M_E_CPU1_SA_DQ<15>")
	)
	(segment
		(start 26.975816 -215.447372)
		(end 27.138884 -215.61044)
		(width 0.14478)
		(layer "In6.Cu")
		(net "M_E_CPU1_SA_DQ<15>")
	)
	(segment
		(start 38.0238 -214.760302)
		(end 38.873938 -215.61044)
		(width 0.14478)
		(layer "In6.Cu")
		(net "M_E_CPU1_SA_DQ<15>")
	)
	(segment
		(start 26.812748 -214.947246)
		(end 26.975816 -215.110314)
		(width 0.14478)
		(layer "In6.Cu")
		(net "M_E_CPU1_SA_DQ<15>")
	)
	(segment
		(start 28.251912 -215.61044)
		(end 34.299652 -215.61044)
		(width 0.14478)
		(layer "In6.Cu")
		(net "M_E_CPU1_SA_DQ<15>")
	)
	(arc
		(start 81.888076 -234.441746)
		(mid 82.135789 -234.516966)
		(end 82.390996 -234.473496)
		(width 0.0889)
		(layer "In6.Cu")
		(net "M_E_CPU1_SA_DQ<15>")
	)
	(arc
		(start 79.646018 -234.434888)
		(mid 79.828019 -234.391355)
		(end 80.008222 -234.441746)
		(width 0.0889)
		(layer "In6.Cu")
		(net "M_E_CPU1_SA_DQ<15>")
	)
	(arc
		(start 80.574134 -234.441746)
		(mid 80.761078 -234.391491)
		(end 80.948022 -234.441746)
		(width 0.0889)
		(layer "In6.Cu")
		(net "M_E_CPU1_SA_DQ<15>")
	)
	(arc
		(start 80.008222 -234.441746)
		(mid 80.291178 -234.517923)
		(end 80.574134 -234.441746)
		(width 0.0889)
		(layer "In6.Cu")
		(net "M_E_CPU1_SA_DQ<15>")
	)
	(arc
		(start 81.513934 -234.441746)
		(mid 81.696185 -234.391396)
		(end 81.879694 -234.43692)
		(width 0.0889)
		(layer "In6.Cu")
		(net "M_E_CPU1_SA_DQ<15>")
	)
	(arc
		(start 80.948022 -234.441746)
		(mid 81.230978 -234.517923)
		(end 81.513934 -234.441746)
		(width 0.0889)
		(layer "In6.Cu")
		(net "M_E_CPU1_SA_DQ<15>")
	)
	(arc
		(start 78.14056 -234.448858)
		(mid 78.418348 -234.51796)
		(end 78.69428 -234.441746)
		(width 0.0889)
		(layer "In6.Cu")
		(net "M_E_CPU1_SA_DQ<15>")
	)
	(arc
		(start 79.068676 -234.441746)
		(mid 79.345489 -234.517889)
		(end 79.62392 -234.447842)
		(width 0.0889)
		(layer "In6.Cu")
		(net "M_E_CPU1_SA_DQ<15>")
	)
	(arc
		(start 78.69428 -234.441746)
		(mid 78.874738 -234.391302)
		(end 79.056992 -234.434888)
		(width 0.0889)
		(layer "In6.Cu")
		(net "M_E_CPU1_SA_DQ<15>")
	)
	(segment
		(start 81.69783 -234.220258)
		(end 81.230978 -233.95432)
		(width 0.10668)
		(layer "F.Cu")
		(net "M_E_CPU1_SA_DQ<14>")
	)
	(segment
		(start 38.0238 -213.06028)
		(end 38.873938 -213.910418)
		(width 0.14478)
		(layer "In6.Cu")
		(net "M_E_CPU1_SA_DQ<14>")
	)
	(segment
		(start 58.711338 -214.063326)
		(end 58.856118 -213.918546)
		(width 0.14478)
		(layer "In6.Cu")
		(net "M_E_CPU1_SA_DQ<14>")
	)
	(segment
		(start 58.711338 -214.457026)
		(end 58.711338 -214.063326)
		(width 0.14478)
		(layer "In6.Cu")
		(net "M_E_CPU1_SA_DQ<14>")
	)
	(segment
		(start 69.24167 -225.344736)
		(end 75.234038 -231.337104)
		(width 0.14478)
		(layer "In6.Cu")
		(net "M_E_CPU1_SA_DQ<14>")
	)
	(segment
		(start 58.147458 -214.063326)
		(end 58.147458 -214.457026)
		(width 0.14478)
		(layer "In6.Cu")
		(net "M_E_CPU1_SA_DQ<14>")
	)
	(segment
		(start 75.607926 -231.337104)
		(end 75.955906 -231.337104)
		(width 0.0889)
		(layer "In6.Cu")
		(net "M_E_CPU1_SA_DQ<14>")
	)
	(segment
		(start 28.397962 -213.332314)
		(end 28.397962 -213.74735)
		(width 0.14478)
		(layer "In6.Cu")
		(net "M_E_CPU1_SA_DQ<14>")
	)
	(segment
		(start 25.152096 -213.485222)
		(end 25.577292 -213.910418)
		(width 0.14478)
		(layer "In6.Cu")
		(net "M_E_CPU1_SA_DQ<14>")
	)
	(segment
		(start 50.47107 -213.06028)
		(end 52.889658 -213.06028)
		(width 0.14478)
		(layer "In6.Cu")
		(net "M_E_CPU1_SA_DQ<14>")
	)
	(segment
		(start 28.234894 -213.169246)
		(end 28.397962 -213.332314)
		(width 0.14478)
		(layer "In6.Cu")
		(net "M_E_CPU1_SA_DQ<14>")
	)
	(segment
		(start 52.889658 -213.06028)
		(end 53.747924 -213.918546)
		(width 0.14478)
		(layer "In6.Cu")
		(net "M_E_CPU1_SA_DQ<14>")
	)
	(segment
		(start 27.448002 -213.910418)
		(end 27.67838 -213.910418)
		(width 0.14478)
		(layer "In6.Cu")
		(net "M_E_CPU1_SA_DQ<14>")
	)
	(segment
		(start 79.15402 -233.637836)
		(end 79.164434 -233.63174)
		(width 0.0889)
		(layer "In6.Cu")
		(net "M_E_CPU1_SA_DQ<14>")
	)
	(segment
		(start 25.577292 -213.910418)
		(end 26.565352 -213.910418)
		(width 0.14478)
		(layer "In6.Cu")
		(net "M_E_CPU1_SA_DQ<14>")
	)
	(segment
		(start 28.397962 -213.74735)
		(end 28.56103 -213.910418)
		(width 0.14478)
		(layer "In6.Cu")
		(net "M_E_CPU1_SA_DQ<14>")
	)
	(segment
		(start 79.538322 -233.63174)
		(end 79.548736 -233.637836)
		(width 0.0889)
		(layer "In6.Cu")
		(net "M_E_CPU1_SA_DQ<14>")
	)
	(segment
		(start 61.35624 -215.709246)
		(end 64.102742 -215.709246)
		(width 0.14478)
		(layer "In6.Cu")
		(net "M_E_CPU1_SA_DQ<14>")
	)
	(segment
		(start 45.712634 -213.06028)
		(end 46.562772 -213.910418)
		(width 0.14478)
		(layer "In6.Cu")
		(net "M_E_CPU1_SA_DQ<14>")
	)
	(segment
		(start 66.974466 -222.1738)
		(end 69.24167 -224.441004)
		(width 0.14478)
		(layer "In6.Cu")
		(net "M_E_CPU1_SA_DQ<14>")
	)
	(segment
		(start 27.284934 -213.74735)
		(end 27.448002 -213.910418)
		(width 0.14478)
		(layer "In6.Cu")
		(net "M_E_CPU1_SA_DQ<14>")
	)
	(segment
		(start 76.938378 -232.579164)
		(end 77.172058 -232.579164)
		(width 0.0889)
		(layer "In6.Cu")
		(net "M_E_CPU1_SA_DQ<14>")
	)
	(segment
		(start 28.56103 -213.910418)
		(end 34.299652 -213.910418)
		(width 0.14478)
		(layer "In6.Cu")
		(net "M_E_CPU1_SA_DQ<14>")
	)
	(segment
		(start 81.077054 -233.68889)
		(end 81.230978 -233.95432)
		(width 0.0889)
		(layer "In6.Cu")
		(net "M_E_CPU1_SA_DQ<14>")
	)
	(segment
		(start 75.234038 -231.337104)
		(end 75.607926 -231.337104)
		(width 0.14478)
		(layer "In6.Cu")
		(net "M_E_CPU1_SA_DQ<14>")
	)
	(segment
		(start 35.14979 -213.06028)
		(end 38.0238 -213.06028)
		(width 0.14478)
		(layer "In6.Cu")
		(net "M_E_CPU1_SA_DQ<14>")
	)
	(segment
		(start 58.856118 -213.918546)
		(end 59.56554 -213.918546)
		(width 0.14478)
		(layer "In6.Cu")
		(net "M_E_CPU1_SA_DQ<14>")
	)
	(segment
		(start 27.841448 -213.332314)
		(end 28.004516 -213.169246)
		(width 0.14478)
		(layer "In6.Cu")
		(net "M_E_CPU1_SA_DQ<14>")
	)
	(segment
		(start 26.72842 -213.367874)
		(end 26.891488 -213.204806)
		(width 0.14478)
		(layer "In6.Cu")
		(net "M_E_CPU1_SA_DQ<14>")
	)
	(segment
		(start 59.56554 -213.918546)
		(end 61.35624 -215.709246)
		(width 0.14478)
		(layer "In6.Cu")
		(net "M_E_CPU1_SA_DQ<14>")
	)
	(segment
		(start 28.004516 -213.169246)
		(end 28.234894 -213.169246)
		(width 0.14478)
		(layer "In6.Cu")
		(net "M_E_CPU1_SA_DQ<14>")
	)
	(segment
		(start 76.443586 -232.084372)
		(end 76.938378 -232.579164)
		(width 0.0889)
		(layer "In6.Cu")
		(net "M_E_CPU1_SA_DQ<14>")
	)
	(segment
		(start 66.974466 -218.58097)
		(end 66.974466 -222.1738)
		(width 0.14478)
		(layer "In6.Cu")
		(net "M_E_CPU1_SA_DQ<14>")
	)
	(segment
		(start 38.873938 -213.910418)
		(end 41.980866 -213.910418)
		(width 0.14478)
		(layer "In6.Cu")
		(net "M_E_CPU1_SA_DQ<14>")
	)
	(segment
		(start 78.17866 -233.585766)
		(end 78.42758 -233.585766)
		(width 0.0889)
		(layer "In6.Cu")
		(net "M_E_CPU1_SA_DQ<14>")
	)
	(segment
		(start 69.24167 -224.441004)
		(end 69.24167 -225.344736)
		(width 0.14478)
		(layer "In6.Cu")
		(net "M_E_CPU1_SA_DQ<14>")
	)
	(segment
		(start 27.284934 -213.367874)
		(end 27.284934 -213.74735)
		(width 0.14478)
		(layer "In6.Cu")
		(net "M_E_CPU1_SA_DQ<14>")
	)
	(segment
		(start 80.981042 -233.66349)
		(end 81.077054 -233.68889)
		(width 0.0889)
		(layer "In6.Cu")
		(net "M_E_CPU1_SA_DQ<14>")
	)
	(segment
		(start 77.172058 -232.579164)
		(end 78.17866 -233.585766)
		(width 0.0889)
		(layer "In6.Cu")
		(net "M_E_CPU1_SA_DQ<14>")
	)
	(segment
		(start 26.891488 -213.204806)
		(end 27.121866 -213.204806)
		(width 0.14478)
		(layer "In6.Cu")
		(net "M_E_CPU1_SA_DQ<14>")
	)
	(segment
		(start 49.620932 -213.910418)
		(end 50.47107 -213.06028)
		(width 0.14478)
		(layer "In6.Cu")
		(net "M_E_CPU1_SA_DQ<14>")
	)
	(segment
		(start 76.443586 -231.824784)
		(end 76.443586 -232.084372)
		(width 0.0889)
		(layer "In6.Cu")
		(net "M_E_CPU1_SA_DQ<14>")
	)
	(segment
		(start 80.46974 -233.626914)
		(end 80.478122 -233.63174)
		(width 0.0889)
		(layer "In6.Cu")
		(net "M_E_CPU1_SA_DQ<14>")
	)
	(segment
		(start 26.72842 -213.74735)
		(end 26.72842 -213.367874)
		(width 0.14478)
		(layer "In6.Cu")
		(net "M_E_CPU1_SA_DQ<14>")
	)
	(segment
		(start 27.841448 -213.74735)
		(end 27.841448 -213.332314)
		(width 0.14478)
		(layer "In6.Cu")
		(net "M_E_CPU1_SA_DQ<14>")
	)
	(segment
		(start 42.831004 -213.06028)
		(end 45.712634 -213.06028)
		(width 0.14478)
		(layer "In6.Cu")
		(net "M_E_CPU1_SA_DQ<14>")
	)
	(segment
		(start 34.299652 -213.910418)
		(end 35.14979 -213.06028)
		(width 0.14478)
		(layer "In6.Cu")
		(net "M_E_CPU1_SA_DQ<14>")
	)
	(segment
		(start 58.002678 -213.918546)
		(end 58.147458 -214.063326)
		(width 0.14478)
		(layer "In6.Cu")
		(net "M_E_CPU1_SA_DQ<14>")
	)
	(segment
		(start 53.747924 -213.918546)
		(end 58.002678 -213.918546)
		(width 0.14478)
		(layer "In6.Cu")
		(net "M_E_CPU1_SA_DQ<14>")
	)
	(segment
		(start 75.955906 -231.337104)
		(end 76.443586 -231.824784)
		(width 0.0889)
		(layer "In6.Cu")
		(net "M_E_CPU1_SA_DQ<14>")
	)
	(segment
		(start 64.102742 -215.709246)
		(end 66.974466 -218.58097)
		(width 0.14478)
		(layer "In6.Cu")
		(net "M_E_CPU1_SA_DQ<14>")
	)
	(segment
		(start 26.565352 -213.910418)
		(end 26.72842 -213.74735)
		(width 0.14478)
		(layer "In6.Cu")
		(net "M_E_CPU1_SA_DQ<14>")
	)
	(segment
		(start 41.980866 -213.910418)
		(end 42.831004 -213.06028)
		(width 0.14478)
		(layer "In6.Cu")
		(net "M_E_CPU1_SA_DQ<14>")
	)
	(segment
		(start 27.67838 -213.910418)
		(end 27.841448 -213.74735)
		(width 0.14478)
		(layer "In6.Cu")
		(net "M_E_CPU1_SA_DQ<14>")
	)
	(segment
		(start 58.147458 -214.457026)
		(end 58.292238 -214.601806)
		(width 0.14478)
		(layer "In6.Cu")
		(net "M_E_CPU1_SA_DQ<14>")
	)
	(segment
		(start 46.562772 -213.910418)
		(end 49.620932 -213.910418)
		(width 0.14478)
		(layer "In6.Cu")
		(net "M_E_CPU1_SA_DQ<14>")
	)
	(segment
		(start 58.292238 -214.601806)
		(end 58.566558 -214.601806)
		(width 0.14478)
		(layer "In6.Cu")
		(net "M_E_CPU1_SA_DQ<14>")
	)
	(segment
		(start 58.566558 -214.601806)
		(end 58.711338 -214.457026)
		(width 0.14478)
		(layer "In6.Cu")
		(net "M_E_CPU1_SA_DQ<14>")
	)
	(segment
		(start 27.121866 -213.204806)
		(end 27.284934 -213.367874)
		(width 0.14478)
		(layer "In6.Cu")
		(net "M_E_CPU1_SA_DQ<14>")
	)
	(arc
		(start 78.598268 -233.63174)
		(mid 78.875335 -233.708011)
		(end 79.15402 -233.637836)
		(width 0.0889)
		(layer "In6.Cu")
		(net "M_E_CPU1_SA_DQ<14>")
	)
	(arc
		(start 80.10398 -233.63174)
		(mid 80.286231 -233.58139)
		(end 80.46974 -233.626914)
		(width 0.0889)
		(layer "In6.Cu")
		(net "M_E_CPU1_SA_DQ<14>")
	)
	(arc
		(start 80.478122 -233.63174)
		(mid 80.725835 -233.70696)
		(end 80.981042 -233.66349)
		(width 0.0889)
		(layer "In6.Cu")
		(net "M_E_CPU1_SA_DQ<14>")
	)
	(arc
		(start 78.42758 -233.585766)
		(mid 78.515961 -233.597468)
		(end 78.598268 -233.63174)
		(width 0.0889)
		(layer "In6.Cu")
		(net "M_E_CPU1_SA_DQ<14>")
	)
	(arc
		(start 79.164434 -233.63174)
		(mid 79.351378 -233.581485)
		(end 79.538322 -233.63174)
		(width 0.0889)
		(layer "In6.Cu")
		(net "M_E_CPU1_SA_DQ<14>")
	)
	(arc
		(start 79.548736 -233.637836)
		(mid 79.827168 -233.707934)
		(end 80.10398 -233.63174)
		(width 0.0889)
		(layer "In6.Cu")
		(net "M_E_CPU1_SA_DQ<14>")
	)
	(segment
		(start 82.637884 -234.220258)
		(end 82.171032 -233.95432)
		(width 0.10668)
		(layer "F.Cu")
		(net "M_E_CPU1_SA_DQ<13>")
	)
	(segment
		(start 79.538322 -234.2769)
		(end 79.548736 -234.270804)
		(width 0.0889)
		(layer "In6.Cu")
		(net "M_E_CPU1_SA_DQ<13>")
	)
	(segment
		(start 32.189928 -214.760302)
		(end 33.294066 -214.760302)
		(width 0.14478)
		(layer "In6.Cu")
		(net "M_E_CPU1_SA_DQ<13>")
	)
	(segment
		(start 33.457134 -214.989156)
		(end 33.620202 -215.152224)
		(width 0.14478)
		(layer "In6.Cu")
		(net "M_E_CPU1_SA_DQ<13>")
	)
	(segment
		(start 41.16578 -214.92337)
		(end 41.16578 -214.984076)
		(width 0.14478)
		(layer "In6.Cu")
		(net "M_E_CPU1_SA_DQ<13>")
	)
	(segment
		(start 81.044034 -234.2769)
		(end 81.052416 -234.281726)
		(width 0.0889)
		(layer "In6.Cu")
		(net "M_E_CPU1_SA_DQ<13>")
	)
	(segment
		(start 60.460128 -215.796368)
		(end 60.822586 -216.158826)
		(width 0.14478)
		(layer "In6.Cu")
		(net "M_E_CPU1_SA_DQ<13>")
	)
	(segment
		(start 56.933592 -215.01608)
		(end 56.933592 -214.512906)
		(width 0.14478)
		(layer "In6.Cu")
		(net "M_E_CPU1_SA_DQ<13>")
	)
	(segment
		(start 48.597566 -214.760302)
		(end 48.760634 -214.92337)
		(width 0.14478)
		(layer "In6.Cu")
		(net "M_E_CPU1_SA_DQ<13>")
	)
	(segment
		(start 48.923702 -215.147144)
		(end 49.15408 -215.147144)
		(width 0.14478)
		(layer "In6.Cu")
		(net "M_E_CPU1_SA_DQ<13>")
	)
	(segment
		(start 30.357318 -214.989156)
		(end 30.520386 -215.152224)
		(width 0.14478)
		(layer "In6.Cu")
		(net "M_E_CPU1_SA_DQ<13>")
	)
	(segment
		(start 75.607926 -231.791764)
		(end 75.950826 -231.791764)
		(width 0.0889)
		(layer "In6.Cu")
		(net "M_E_CPU1_SA_DQ<13>")
	)
	(segment
		(start 30.520386 -215.152224)
		(end 30.750764 -215.152224)
		(width 0.14478)
		(layer "In6.Cu")
		(net "M_E_CPU1_SA_DQ<13>")
	)
	(segment
		(start 29.677106 -214.760302)
		(end 30.19425 -214.760302)
		(width 0.14478)
		(layer "In6.Cu")
		(net "M_E_CPU1_SA_DQ<13>")
	)
	(segment
		(start 29.252164 -214.33536)
		(end 29.677106 -214.760302)
		(width 0.14478)
		(layer "In6.Cu")
		(net "M_E_CPU1_SA_DQ<13>")
	)
	(segment
		(start 56.514492 -215.16086)
		(end 56.788812 -215.16086)
		(width 0.14478)
		(layer "In6.Cu")
		(net "M_E_CPU1_SA_DQ<13>")
	)
	(segment
		(start 76.903326 -232.833164)
		(end 77.078586 -232.833164)
		(width 0.0889)
		(layer "In6.Cu")
		(net "M_E_CPU1_SA_DQ<13>")
	)
	(segment
		(start 68.79209 -225.538284)
		(end 75.04557 -231.791764)
		(width 0.14478)
		(layer "In6.Cu")
		(net "M_E_CPU1_SA_DQ<13>")
	)
	(segment
		(start 42.987214 -213.910418)
		(end 45.69079 -213.910418)
		(width 0.14478)
		(layer "In6.Cu")
		(net "M_E_CPU1_SA_DQ<13>")
	)
	(segment
		(start 56.224932 -214.368126)
		(end 56.369712 -214.512906)
		(width 0.14478)
		(layer "In6.Cu")
		(net "M_E_CPU1_SA_DQ<13>")
	)
	(segment
		(start 30.19425 -214.760302)
		(end 30.357318 -214.92337)
		(width 0.14478)
		(layer "In6.Cu")
		(net "M_E_CPU1_SA_DQ<13>")
	)
	(segment
		(start 77.078586 -232.833164)
		(end 77.383386 -233.137964)
		(width 0.0889)
		(layer "In6.Cu")
		(net "M_E_CPU1_SA_DQ<13>")
	)
	(segment
		(start 56.933592 -214.512906)
		(end 57.078372 -214.368126)
		(width 0.14478)
		(layer "In6.Cu")
		(net "M_E_CPU1_SA_DQ<13>")
	)
	(segment
		(start 31.0769 -214.36838)
		(end 31.307278 -214.36838)
		(width 0.14478)
		(layer "In6.Cu")
		(net "M_E_CPU1_SA_DQ<13>")
	)
	(segment
		(start 54.293008 -215.16086)
		(end 55.661052 -215.16086)
		(width 0.14478)
		(layer "In6.Cu")
		(net "M_E_CPU1_SA_DQ<13>")
	)
	(segment
		(start 59.15787 -214.688166)
		(end 59.69889 -214.688166)
		(width 0.14478)
		(layer "In6.Cu")
		(net "M_E_CPU1_SA_DQ<13>")
	)
	(segment
		(start 76.199746 -232.129584)
		(end 76.903326 -232.833164)
		(width 0.0889)
		(layer "In6.Cu")
		(net "M_E_CPU1_SA_DQ<13>")
	)
	(segment
		(start 41.885362 -214.760302)
		(end 42.13733 -214.760302)
		(width 0.14478)
		(layer "In6.Cu")
		(net "M_E_CPU1_SA_DQ<13>")
	)
	(segment
		(start 56.369712 -214.512906)
		(end 56.369712 -215.01608)
		(width 0.14478)
		(layer "In6.Cu")
		(net "M_E_CPU1_SA_DQ<13>")
	)
	(segment
		(start 33.294066 -214.760302)
		(end 33.457134 -214.92337)
		(width 0.14478)
		(layer "In6.Cu")
		(net "M_E_CPU1_SA_DQ<13>")
	)
	(segment
		(start 30.357318 -214.92337)
		(end 30.357318 -214.989156)
		(width 0.14478)
		(layer "In6.Cu")
		(net "M_E_CPU1_SA_DQ<13>")
	)
	(segment
		(start 82.324956 -234.21975)
		(end 82.171032 -233.95432)
		(width 0.0889)
		(layer "In6.Cu")
		(net "M_E_CPU1_SA_DQ<13>")
	)
	(segment
		(start 77.383386 -233.137964)
		(end 77.383386 -233.51236)
		(width 0.0889)
		(layer "In6.Cu")
		(net "M_E_CPU1_SA_DQ<13>")
	)
	(segment
		(start 31.863792 -215.152224)
		(end 32.02686 -214.989156)
		(width 0.14478)
		(layer "In6.Cu")
		(net "M_E_CPU1_SA_DQ<13>")
	)
	(segment
		(start 35.354514 -213.910418)
		(end 38.01491 -213.910418)
		(width 0.14478)
		(layer "In6.Cu")
		(net "M_E_CPU1_SA_DQ<13>")
	)
	(segment
		(start 77.383386 -233.51236)
		(end 78.046072 -234.175046)
		(width 0.0889)
		(layer "In6.Cu")
		(net "M_E_CPU1_SA_DQ<13>")
	)
	(segment
		(start 33.457134 -214.92337)
		(end 33.457134 -214.989156)
		(width 0.14478)
		(layer "In6.Cu")
		(net "M_E_CPU1_SA_DQ<13>")
	)
	(segment
		(start 80.46974 -234.281726)
		(end 80.478122 -234.2769)
		(width 0.0889)
		(layer "In6.Cu")
		(net "M_E_CPU1_SA_DQ<13>")
	)
	(segment
		(start 56.369712 -215.01608)
		(end 56.514492 -215.16086)
		(width 0.14478)
		(layer "In6.Cu")
		(net "M_E_CPU1_SA_DQ<13>")
	)
	(segment
		(start 55.805832 -215.01608)
		(end 55.805832 -214.512906)
		(width 0.14478)
		(layer "In6.Cu")
		(net "M_E_CPU1_SA_DQ<13>")
	)
	(segment
		(start 46.540674 -214.760302)
		(end 48.597566 -214.760302)
		(width 0.14478)
		(layer "In6.Cu")
		(net "M_E_CPU1_SA_DQ<13>")
	)
	(segment
		(start 45.69079 -213.910418)
		(end 46.540674 -214.760302)
		(width 0.14478)
		(layer "In6.Cu")
		(net "M_E_CPU1_SA_DQ<13>")
	)
	(segment
		(start 82.302604 -234.303062)
		(end 82.324956 -234.21975)
		(width 0.0889)
		(layer "In6.Cu")
		(net "M_E_CPU1_SA_DQ<13>")
	)
	(segment
		(start 41.559226 -215.147144)
		(end 41.722294 -214.984076)
		(width 0.14478)
		(layer "In6.Cu")
		(net "M_E_CPU1_SA_DQ<13>")
	)
	(segment
		(start 60.460128 -215.449404)
		(end 60.460128 -215.796368)
		(width 0.14478)
		(layer "In6.Cu")
		(net "M_E_CPU1_SA_DQ<13>")
	)
	(segment
		(start 48.760634 -214.92337)
		(end 48.760634 -214.984076)
		(width 0.14478)
		(layer "In6.Cu")
		(net "M_E_CPU1_SA_DQ<13>")
	)
	(segment
		(start 30.913832 -214.989156)
		(end 30.913832 -214.531448)
		(width 0.14478)
		(layer "In6.Cu")
		(net "M_E_CPU1_SA_DQ<13>")
	)
	(segment
		(start 30.913832 -214.531448)
		(end 31.0769 -214.36838)
		(width 0.14478)
		(layer "In6.Cu")
		(net "M_E_CPU1_SA_DQ<13>")
	)
	(segment
		(start 31.633414 -215.152224)
		(end 31.863792 -215.152224)
		(width 0.14478)
		(layer "In6.Cu")
		(net "M_E_CPU1_SA_DQ<13>")
	)
	(segment
		(start 58.685176 -215.16086)
		(end 59.15787 -214.688166)
		(width 0.14478)
		(layer "In6.Cu")
		(net "M_E_CPU1_SA_DQ<13>")
	)
	(segment
		(start 78.046072 -234.175046)
		(end 78.242668 -234.28706)
		(width 0.0889)
		(layer "In6.Cu")
		(net "M_E_CPU1_SA_DQ<13>")
	)
	(segment
		(start 30.750764 -215.152224)
		(end 30.913832 -214.989156)
		(width 0.14478)
		(layer "In6.Cu")
		(net "M_E_CPU1_SA_DQ<13>")
	)
	(segment
		(start 34.50463 -214.760302)
		(end 35.354514 -213.910418)
		(width 0.14478)
		(layer "In6.Cu")
		(net "M_E_CPU1_SA_DQ<13>")
	)
	(segment
		(start 49.317148 -214.984076)
		(end 49.317148 -214.92337)
		(width 0.14478)
		(layer "In6.Cu")
		(net "M_E_CPU1_SA_DQ<13>")
	)
	(segment
		(start 57.642252 -215.16086)
		(end 58.685176 -215.16086)
		(width 0.14478)
		(layer "In6.Cu")
		(net "M_E_CPU1_SA_DQ<13>")
	)
	(segment
		(start 55.950612 -214.368126)
		(end 56.224932 -214.368126)
		(width 0.14478)
		(layer "In6.Cu")
		(net "M_E_CPU1_SA_DQ<13>")
	)
	(segment
		(start 41.002712 -214.760302)
		(end 41.16578 -214.92337)
		(width 0.14478)
		(layer "In6.Cu")
		(net "M_E_CPU1_SA_DQ<13>")
	)
	(segment
		(start 31.470346 -214.989156)
		(end 31.633414 -215.152224)
		(width 0.14478)
		(layer "In6.Cu")
		(net "M_E_CPU1_SA_DQ<13>")
	)
	(segment
		(start 60.822586 -216.158826)
		(end 63.916306 -216.158826)
		(width 0.14478)
		(layer "In6.Cu")
		(net "M_E_CPU1_SA_DQ<13>")
	)
	(segment
		(start 55.661052 -215.16086)
		(end 55.805832 -215.01608)
		(width 0.14478)
		(layer "In6.Cu")
		(net "M_E_CPU1_SA_DQ<13>")
	)
	(segment
		(start 79.52994 -234.281726)
		(end 79.538322 -234.2769)
		(width 0.0889)
		(layer "In6.Cu")
		(net "M_E_CPU1_SA_DQ<13>")
	)
	(segment
		(start 75.04557 -231.791764)
		(end 75.607926 -231.791764)
		(width 0.14478)
		(layer "In6.Cu")
		(net "M_E_CPU1_SA_DQ<13>")
	)
	(segment
		(start 66.519806 -218.762326)
		(end 66.519806 -222.355156)
		(width 0.14478)
		(layer "In6.Cu")
		(net "M_E_CPU1_SA_DQ<13>")
	)
	(segment
		(start 75.950826 -231.791764)
		(end 76.199746 -232.040684)
		(width 0.0889)
		(layer "In6.Cu")
		(net "M_E_CPU1_SA_DQ<13>")
	)
	(segment
		(start 53.042566 -213.910418)
		(end 54.293008 -215.16086)
		(width 0.14478)
		(layer "In6.Cu")
		(net "M_E_CPU1_SA_DQ<13>")
	)
	(segment
		(start 49.317148 -214.92337)
		(end 49.480216 -214.760302)
		(width 0.14478)
		(layer "In6.Cu")
		(net "M_E_CPU1_SA_DQ<13>")
	)
	(segment
		(start 34.013648 -214.92337)
		(end 34.176716 -214.760302)
		(width 0.14478)
		(layer "In6.Cu")
		(net "M_E_CPU1_SA_DQ<13>")
	)
	(segment
		(start 41.722294 -214.92337)
		(end 41.885362 -214.760302)
		(width 0.14478)
		(layer "In6.Cu")
		(net "M_E_CPU1_SA_DQ<13>")
	)
	(segment
		(start 57.352692 -214.368126)
		(end 57.497472 -214.512906)
		(width 0.14478)
		(layer "In6.Cu")
		(net "M_E_CPU1_SA_DQ<13>")
	)
	(segment
		(start 31.470346 -214.531448)
		(end 31.470346 -214.989156)
		(width 0.14478)
		(layer "In6.Cu")
		(net "M_E_CPU1_SA_DQ<13>")
	)
	(segment
		(start 49.82591 -214.760302)
		(end 50.675794 -213.910418)
		(width 0.14478)
		(layer "In6.Cu")
		(net "M_E_CPU1_SA_DQ<13>")
	)
	(segment
		(start 63.916306 -216.158826)
		(end 66.519806 -218.762326)
		(width 0.14478)
		(layer "In6.Cu")
		(net "M_E_CPU1_SA_DQ<13>")
	)
	(segment
		(start 33.620202 -215.152224)
		(end 33.85058 -215.152224)
		(width 0.14478)
		(layer "In6.Cu")
		(net "M_E_CPU1_SA_DQ<13>")
	)
	(segment
		(start 50.675794 -213.910418)
		(end 53.042566 -213.910418)
		(width 0.14478)
		(layer "In6.Cu")
		(net "M_E_CPU1_SA_DQ<13>")
	)
	(segment
		(start 57.497472 -215.01608)
		(end 57.642252 -215.16086)
		(width 0.14478)
		(layer "In6.Cu")
		(net "M_E_CPU1_SA_DQ<13>")
	)
	(segment
		(start 33.85058 -215.152224)
		(end 34.013648 -214.989156)
		(width 0.14478)
		(layer "In6.Cu")
		(net "M_E_CPU1_SA_DQ<13>")
	)
	(segment
		(start 38.864794 -214.760302)
		(end 41.002712 -214.760302)
		(width 0.14478)
		(layer "In6.Cu")
		(net "M_E_CPU1_SA_DQ<13>")
	)
	(segment
		(start 49.15408 -215.147144)
		(end 49.317148 -214.984076)
		(width 0.14478)
		(layer "In6.Cu")
		(net "M_E_CPU1_SA_DQ<13>")
	)
	(segment
		(start 59.69889 -214.688166)
		(end 60.460128 -215.449404)
		(width 0.14478)
		(layer "In6.Cu")
		(net "M_E_CPU1_SA_DQ<13>")
	)
	(segment
		(start 34.176716 -214.760302)
		(end 34.50463 -214.760302)
		(width 0.14478)
		(layer "In6.Cu")
		(net "M_E_CPU1_SA_DQ<13>")
	)
	(segment
		(start 41.16578 -214.984076)
		(end 41.328848 -215.147144)
		(width 0.14478)
		(layer "In6.Cu")
		(net "M_E_CPU1_SA_DQ<13>")
	)
	(segment
		(start 48.760634 -214.984076)
		(end 48.923702 -215.147144)
		(width 0.14478)
		(layer "In6.Cu")
		(net "M_E_CPU1_SA_DQ<13>")
	)
	(segment
		(start 31.307278 -214.36838)
		(end 31.470346 -214.531448)
		(width 0.14478)
		(layer "In6.Cu")
		(net "M_E_CPU1_SA_DQ<13>")
	)
	(segment
		(start 32.02686 -214.92337)
		(end 32.189928 -214.760302)
		(width 0.14478)
		(layer "In6.Cu")
		(net "M_E_CPU1_SA_DQ<13>")
	)
	(segment
		(start 32.02686 -214.989156)
		(end 32.02686 -214.92337)
		(width 0.14478)
		(layer "In6.Cu")
		(net "M_E_CPU1_SA_DQ<13>")
	)
	(segment
		(start 68.79209 -224.62744)
		(end 68.79209 -225.538284)
		(width 0.14478)
		(layer "In6.Cu")
		(net "M_E_CPU1_SA_DQ<13>")
	)
	(segment
		(start 38.01491 -213.910418)
		(end 38.864794 -214.760302)
		(width 0.14478)
		(layer "In6.Cu")
		(net "M_E_CPU1_SA_DQ<13>")
	)
	(segment
		(start 57.078372 -214.368126)
		(end 57.352692 -214.368126)
		(width 0.14478)
		(layer "In6.Cu")
		(net "M_E_CPU1_SA_DQ<13>")
	)
	(segment
		(start 41.722294 -214.984076)
		(end 41.722294 -214.92337)
		(width 0.14478)
		(layer "In6.Cu")
		(net "M_E_CPU1_SA_DQ<13>")
	)
	(segment
		(start 66.519806 -222.355156)
		(end 68.79209 -224.62744)
		(width 0.14478)
		(layer "In6.Cu")
		(net "M_E_CPU1_SA_DQ<13>")
	)
	(segment
		(start 41.328848 -215.147144)
		(end 41.559226 -215.147144)
		(width 0.14478)
		(layer "In6.Cu")
		(net "M_E_CPU1_SA_DQ<13>")
	)
	(segment
		(start 34.013648 -214.989156)
		(end 34.013648 -214.92337)
		(width 0.14478)
		(layer "In6.Cu")
		(net "M_E_CPU1_SA_DQ<13>")
	)
	(segment
		(start 42.13733 -214.760302)
		(end 42.987214 -213.910418)
		(width 0.14478)
		(layer "In6.Cu")
		(net "M_E_CPU1_SA_DQ<13>")
	)
	(segment
		(start 57.497472 -214.512906)
		(end 57.497472 -215.01608)
		(width 0.14478)
		(layer "In6.Cu")
		(net "M_E_CPU1_SA_DQ<13>")
	)
	(segment
		(start 49.480216 -214.760302)
		(end 49.82591 -214.760302)
		(width 0.14478)
		(layer "In6.Cu")
		(net "M_E_CPU1_SA_DQ<13>")
	)
	(segment
		(start 76.199746 -232.040684)
		(end 76.199746 -232.129584)
		(width 0.0889)
		(layer "In6.Cu")
		(net "M_E_CPU1_SA_DQ<13>")
	)
	(segment
		(start 79.154274 -234.270804)
		(end 79.164688 -234.2769)
		(width 0.0889)
		(layer "In6.Cu")
		(net "M_E_CPU1_SA_DQ<13>")
	)
	(segment
		(start 55.805832 -214.512906)
		(end 55.950612 -214.368126)
		(width 0.14478)
		(layer "In6.Cu")
		(net "M_E_CPU1_SA_DQ<13>")
	)
	(segment
		(start 56.788812 -215.16086)
		(end 56.933592 -215.01608)
		(width 0.14478)
		(layer "In6.Cu")
		(net "M_E_CPU1_SA_DQ<13>")
	)
	(arc
		(start 78.598522 -234.2769)
		(mid 78.875589 -234.200629)
		(end 79.154274 -234.270804)
		(width 0.0889)
		(layer "In6.Cu")
		(net "M_E_CPU1_SA_DQ<13>")
	)
	(arc
		(start 79.548736 -234.270804)
		(mid 79.827168 -234.200706)
		(end 80.10398 -234.2769)
		(width 0.0889)
		(layer "In6.Cu")
		(net "M_E_CPU1_SA_DQ<13>")
	)
	(arc
		(start 81.418176 -234.2769)
		(mid 81.701132 -234.200723)
		(end 81.984088 -234.2769)
		(width 0.0889)
		(layer "In6.Cu")
		(net "M_E_CPU1_SA_DQ<13>")
	)
	(arc
		(start 81.052416 -234.281726)
		(mid 81.235924 -234.32722)
		(end 81.418176 -234.2769)
		(width 0.0889)
		(layer "In6.Cu")
		(net "M_E_CPU1_SA_DQ<13>")
	)
	(arc
		(start 80.478122 -234.2769)
		(mid 80.761078 -234.200723)
		(end 81.044034 -234.2769)
		(width 0.0889)
		(layer "In6.Cu")
		(net "M_E_CPU1_SA_DQ<13>")
	)
	(arc
		(start 78.242668 -234.28706)
		(mid 78.421897 -234.327213)
		(end 78.598522 -234.2769)
		(width 0.0889)
		(layer "In6.Cu")
		(net "M_E_CPU1_SA_DQ<13>")
	)
	(arc
		(start 81.984088 -234.2769)
		(mid 82.140407 -234.325895)
		(end 82.302604 -234.303062)
		(width 0.0889)
		(layer "In6.Cu")
		(net "M_E_CPU1_SA_DQ<13>")
	)
	(arc
		(start 80.10398 -234.2769)
		(mid 80.286231 -234.32725)
		(end 80.46974 -234.281726)
		(width 0.0889)
		(layer "In6.Cu")
		(net "M_E_CPU1_SA_DQ<13>")
	)
	(arc
		(start 79.164688 -234.2769)
		(mid 79.346685 -234.327122)
		(end 79.52994 -234.281726)
		(width 0.0889)
		(layer "In6.Cu")
		(net "M_E_CPU1_SA_DQ<13>")
	)
	(segment
		(start 81.22793 -233.410252)
		(end 80.761078 -233.144314)
		(width 0.10668)
		(layer "F.Cu")
		(net "M_E_CPU1_SA_DQ<12>")
	)
	(segment
		(start 54.79669 -212.734398)
		(end 54.94147 -212.879178)
		(width 0.14478)
		(layer "In6.Cu")
		(net "M_E_CPU1_SA_DQ<12>")
	)
	(segment
		(start 39.254938 -213.450424)
		(end 39.540688 -213.450424)
		(width 0.14478)
		(layer "In6.Cu")
		(net "M_E_CPU1_SA_DQ<12>")
	)
	(segment
		(start 34.230564 -213.06028)
		(end 34.50463 -213.06028)
		(width 0.14478)
		(layer "In6.Cu")
		(net "M_E_CPU1_SA_DQ<12>")
	)
	(segment
		(start 29.883608 -213.06028)
		(end 30.046676 -212.897212)
		(width 0.14478)
		(layer "In6.Cu")
		(net "M_E_CPU1_SA_DQ<12>")
	)
	(segment
		(start 56.711342 -213.460838)
		(end 58.672984 -213.460838)
		(width 0.14478)
		(layer "In6.Cu")
		(net "M_E_CPU1_SA_DQ<12>")
	)
	(segment
		(start 35.850322 -212.602064)
		(end 36.0807 -212.602064)
		(width 0.14478)
		(layer "In6.Cu")
		(net "M_E_CPU1_SA_DQ<12>")
	)
	(segment
		(start 36.0807 -212.602064)
		(end 36.243768 -212.438996)
		(width 0.14478)
		(layer "In6.Cu")
		(net "M_E_CPU1_SA_DQ<12>")
	)
	(segment
		(start 53.81371 -212.879178)
		(end 53.81371 -213.308946)
		(width 0.14478)
		(layer "In6.Cu")
		(net "M_E_CPU1_SA_DQ<12>")
	)
	(segment
		(start 54.37759 -213.308946)
		(end 54.37759 -212.879178)
		(width 0.14478)
		(layer "In6.Cu")
		(net "M_E_CPU1_SA_DQ<12>")
	)
	(segment
		(start 54.37759 -212.879178)
		(end 54.52237 -212.734398)
		(width 0.14478)
		(layer "In6.Cu")
		(net "M_E_CPU1_SA_DQ<12>")
	)
	(segment
		(start 51.219862 -212.591904)
		(end 51.38293 -212.428836)
		(width 0.14478)
		(layer "In6.Cu")
		(net "M_E_CPU1_SA_DQ<12>")
	)
	(segment
		(start 43.297094 -212.433916)
		(end 43.460162 -212.596984)
		(width 0.14478)
		(layer "In6.Cu")
		(net "M_E_CPU1_SA_DQ<12>")
	)
	(segment
		(start 33.293558 -213.069932)
		(end 33.67405 -213.450424)
		(width 0.14478)
		(layer "In6.Cu")
		(net "M_E_CPU1_SA_DQ<12>")
	)
	(segment
		(start 34.50463 -213.06028)
		(end 35.354514 -212.210396)
		(width 0.14478)
		(layer "In6.Cu")
		(net "M_E_CPU1_SA_DQ<12>")
	)
	(segment
		(start 45.589698 -212.220048)
		(end 46.439582 -213.069932)
		(width 0.14478)
		(layer "In6.Cu")
		(net "M_E_CPU1_SA_DQ<12>")
	)
	(segment
		(start 35.687254 -212.438996)
		(end 35.850322 -212.602064)
		(width 0.14478)
		(layer "In6.Cu")
		(net "M_E_CPU1_SA_DQ<12>")
	)
	(segment
		(start 50.826416 -212.428836)
		(end 50.989484 -212.591904)
		(width 0.14478)
		(layer "In6.Cu")
		(net "M_E_CPU1_SA_DQ<12>")
	)
	(segment
		(start 58.672984 -213.460838)
		(end 59.122056 -213.011766)
		(width 0.14478)
		(layer "In6.Cu")
		(net "M_E_CPU1_SA_DQ<12>")
	)
	(segment
		(start 31.211012 -213.223348)
		(end 31.211012 -213.287356)
		(width 0.14478)
		(layer "In6.Cu")
		(net "M_E_CPU1_SA_DQ<12>")
	)
	(segment
		(start 59.670696 -213.011766)
		(end 61.918596 -215.259666)
		(width 0.14478)
		(layer "In6.Cu")
		(net "M_E_CPU1_SA_DQ<12>")
	)
	(segment
		(start 42.13733 -213.06028)
		(end 42.987214 -212.210396)
		(width 0.14478)
		(layer "In6.Cu")
		(net "M_E_CPU1_SA_DQ<12>")
	)
	(segment
		(start 30.440122 -212.282024)
		(end 30.60319 -212.445092)
		(width 0.14478)
		(layer "In6.Cu")
		(net "M_E_CPU1_SA_DQ<12>")
	)
	(segment
		(start 41.25087 -213.445344)
		(end 41.481248 -213.445344)
		(width 0.14478)
		(layer "In6.Cu")
		(net "M_E_CPU1_SA_DQ<12>")
	)
	(segment
		(start 67.44589 -218.416378)
		(end 67.44589 -222.009208)
		(width 0.14478)
		(layer "In6.Cu")
		(net "M_E_CPU1_SA_DQ<12>")
	)
	(segment
		(start 48.54321 -213.069932)
		(end 48.923702 -213.450424)
		(width 0.14478)
		(layer "In6.Cu")
		(net "M_E_CPU1_SA_DQ<12>")
	)
	(segment
		(start 43.69054 -212.596984)
		(end 43.853608 -212.433916)
		(width 0.14478)
		(layer "In6.Cu")
		(net "M_E_CPU1_SA_DQ<12>")
	)
	(segment
		(start 30.60319 -212.897212)
		(end 30.766258 -213.06028)
		(width 0.14478)
		(layer "In6.Cu")
		(net "M_E_CPU1_SA_DQ<12>")
	)
	(segment
		(start 43.853608 -212.373464)
		(end 44.007024 -212.220048)
		(width 0.14478)
		(layer "In6.Cu")
		(net "M_E_CPU1_SA_DQ<12>")
	)
	(segment
		(start 69.69125 -225.151188)
		(end 75.422506 -230.882444)
		(width 0.14478)
		(layer "In6.Cu")
		(net "M_E_CPU1_SA_DQ<12>")
	)
	(segment
		(start 51.38293 -212.428836)
		(end 51.38293 -212.373464)
		(width 0.14478)
		(layer "In6.Cu")
		(net "M_E_CPU1_SA_DQ<12>")
	)
	(segment
		(start 36.397184 -212.220048)
		(end 38.024562 -212.220048)
		(width 0.14478)
		(layer "In6.Cu")
		(net "M_E_CPU1_SA_DQ<12>")
	)
	(segment
		(start 42.987214 -212.210396)
		(end 43.134026 -212.210396)
		(width 0.14478)
		(layer "In6.Cu")
		(net "M_E_CPU1_SA_DQ<12>")
	)
	(segment
		(start 36.243768 -212.373464)
		(end 36.397184 -212.220048)
		(width 0.14478)
		(layer "In6.Cu")
		(net "M_E_CPU1_SA_DQ<12>")
	)
	(segment
		(start 30.046676 -212.445092)
		(end 30.209744 -212.282024)
		(width 0.14478)
		(layer "In6.Cu")
		(net "M_E_CPU1_SA_DQ<12>")
	)
	(segment
		(start 55.50535 -212.879178)
		(end 55.65013 -212.734398)
		(width 0.14478)
		(layer "In6.Cu")
		(net "M_E_CPU1_SA_DQ<12>")
	)
	(segment
		(start 59.122056 -213.011766)
		(end 59.670696 -213.011766)
		(width 0.14478)
		(layer "In6.Cu")
		(net "M_E_CPU1_SA_DQ<12>")
	)
	(segment
		(start 53.95849 -213.453726)
		(end 54.23281 -213.453726)
		(width 0.14478)
		(layer "In6.Cu")
		(net "M_E_CPU1_SA_DQ<12>")
	)
	(segment
		(start 54.52237 -212.734398)
		(end 54.79669 -212.734398)
		(width 0.14478)
		(layer "In6.Cu")
		(net "M_E_CPU1_SA_DQ<12>")
	)
	(segment
		(start 39.540688 -213.450424)
		(end 39.703756 -213.287356)
		(width 0.14478)
		(layer "In6.Cu")
		(net "M_E_CPU1_SA_DQ<12>")
	)
	(segment
		(start 34.067496 -213.223348)
		(end 34.230564 -213.06028)
		(width 0.14478)
		(layer "In6.Cu")
		(net "M_E_CPU1_SA_DQ<12>")
	)
	(segment
		(start 29.252164 -212.635338)
		(end 29.677106 -213.06028)
		(width 0.14478)
		(layer "In6.Cu")
		(net "M_E_CPU1_SA_DQ<12>")
	)
	(segment
		(start 35.687254 -212.373464)
		(end 35.687254 -212.438996)
		(width 0.14478)
		(layer "In6.Cu")
		(net "M_E_CPU1_SA_DQ<12>")
	)
	(segment
		(start 30.766258 -213.06028)
		(end 31.047944 -213.06028)
		(width 0.14478)
		(layer "In6.Cu")
		(net "M_E_CPU1_SA_DQ<12>")
	)
	(segment
		(start 75.955906 -230.882444)
		(end 76.508102 -231.43464)
		(width 0.0889)
		(layer "In6.Cu")
		(net "M_E_CPU1_SA_DQ<12>")
	)
	(segment
		(start 39.703756 -213.287356)
		(end 39.703756 -213.223348)
		(width 0.14478)
		(layer "In6.Cu")
		(net "M_E_CPU1_SA_DQ<12>")
	)
	(segment
		(start 67.44589 -222.009208)
		(end 69.69125 -224.254568)
		(width 0.14478)
		(layer "In6.Cu")
		(net "M_E_CPU1_SA_DQ<12>")
	)
	(segment
		(start 49.480216 -213.06028)
		(end 49.630838 -213.06028)
		(width 0.14478)
		(layer "In6.Cu")
		(net "M_E_CPU1_SA_DQ<12>")
	)
	(segment
		(start 31.604458 -213.450424)
		(end 31.767526 -213.287356)
		(width 0.14478)
		(layer "In6.Cu")
		(net "M_E_CPU1_SA_DQ<12>")
	)
	(segment
		(start 31.37408 -213.450424)
		(end 31.604458 -213.450424)
		(width 0.14478)
		(layer "In6.Cu")
		(net "M_E_CPU1_SA_DQ<12>")
	)
	(segment
		(start 30.60319 -212.445092)
		(end 30.60319 -212.897212)
		(width 0.14478)
		(layer "In6.Cu")
		(net "M_E_CPU1_SA_DQ<12>")
	)
	(segment
		(start 54.94147 -212.879178)
		(end 54.94147 -213.308946)
		(width 0.14478)
		(layer "In6.Cu")
		(net "M_E_CPU1_SA_DQ<12>")
	)
	(segment
		(start 80.915002 -233.409744)
		(end 80.761078 -233.144314)
		(width 0.0889)
		(layer "In6.Cu")
		(net "M_E_CPU1_SA_DQ<12>")
	)
	(segment
		(start 61.918596 -215.259666)
		(end 64.289178 -215.259666)
		(width 0.14478)
		(layer "In6.Cu")
		(net "M_E_CPU1_SA_DQ<12>")
	)
	(segment
		(start 53.15458 -212.220048)
		(end 53.81371 -212.879178)
		(width 0.14478)
		(layer "In6.Cu")
		(net "M_E_CPU1_SA_DQ<12>")
	)
	(segment
		(start 55.65013 -212.734398)
		(end 55.984902 -212.734398)
		(width 0.14478)
		(layer "In6.Cu")
		(net "M_E_CPU1_SA_DQ<12>")
	)
	(segment
		(start 40.875458 -213.069932)
		(end 41.25087 -213.445344)
		(width 0.14478)
		(layer "In6.Cu")
		(net "M_E_CPU1_SA_DQ<12>")
	)
	(segment
		(start 43.134026 -212.210396)
		(end 43.297094 -212.373464)
		(width 0.14478)
		(layer "In6.Cu")
		(net "M_E_CPU1_SA_DQ<12>")
	)
	(segment
		(start 50.480722 -212.210396)
		(end 50.663348 -212.210396)
		(width 0.14478)
		(layer "In6.Cu")
		(net "M_E_CPU1_SA_DQ<12>")
	)
	(segment
		(start 50.663348 -212.210396)
		(end 50.826416 -212.373464)
		(width 0.14478)
		(layer "In6.Cu")
		(net "M_E_CPU1_SA_DQ<12>")
	)
	(segment
		(start 31.920942 -213.069932)
		(end 33.293558 -213.069932)
		(width 0.14478)
		(layer "In6.Cu")
		(net "M_E_CPU1_SA_DQ<12>")
	)
	(segment
		(start 49.15408 -213.450424)
		(end 49.317148 -213.287356)
		(width 0.14478)
		(layer "In6.Cu")
		(net "M_E_CPU1_SA_DQ<12>")
	)
	(segment
		(start 54.23281 -213.453726)
		(end 54.37759 -213.308946)
		(width 0.14478)
		(layer "In6.Cu")
		(net "M_E_CPU1_SA_DQ<12>")
	)
	(segment
		(start 75.422506 -230.882444)
		(end 75.607926 -230.882444)
		(width 0.14478)
		(layer "In6.Cu")
		(net "M_E_CPU1_SA_DQ<12>")
	)
	(segment
		(start 34.067496 -213.287356)
		(end 34.067496 -213.223348)
		(width 0.14478)
		(layer "In6.Cu")
		(net "M_E_CPU1_SA_DQ<12>")
	)
	(segment
		(start 69.69125 -224.254568)
		(end 69.69125 -225.151188)
		(width 0.14478)
		(layer "In6.Cu")
		(net "M_E_CPU1_SA_DQ<12>")
	)
	(segment
		(start 43.460162 -212.596984)
		(end 43.69054 -212.596984)
		(width 0.14478)
		(layer "In6.Cu")
		(net "M_E_CPU1_SA_DQ<12>")
	)
	(segment
		(start 79.06004 -233.47172)
		(end 79.068422 -233.466894)
		(width 0.0889)
		(layer "In6.Cu")
		(net "M_E_CPU1_SA_DQ<12>")
	)
	(segment
		(start 43.853608 -212.433916)
		(end 43.853608 -212.373464)
		(width 0.14478)
		(layer "In6.Cu")
		(net "M_E_CPU1_SA_DQ<12>")
	)
	(segment
		(start 76.972922 -231.43464)
		(end 77.168502 -231.63022)
		(width 0.0889)
		(layer "In6.Cu")
		(net "M_E_CPU1_SA_DQ<12>")
	)
	(segment
		(start 31.047944 -213.06028)
		(end 31.211012 -213.223348)
		(width 0.14478)
		(layer "In6.Cu")
		(net "M_E_CPU1_SA_DQ<12>")
	)
	(segment
		(start 43.297094 -212.373464)
		(end 43.297094 -212.433916)
		(width 0.14478)
		(layer "In6.Cu")
		(net "M_E_CPU1_SA_DQ<12>")
	)
	(segment
		(start 41.644316 -213.282276)
		(end 41.644316 -213.223348)
		(width 0.14478)
		(layer "In6.Cu")
		(net "M_E_CPU1_SA_DQ<12>")
	)
	(segment
		(start 79.623666 -233.460798)
		(end 79.63408 -233.466894)
		(width 0.0889)
		(layer "In6.Cu")
		(net "M_E_CPU1_SA_DQ<12>")
	)
	(segment
		(start 33.904428 -213.450424)
		(end 34.067496 -213.287356)
		(width 0.14478)
		(layer "In6.Cu")
		(net "M_E_CPU1_SA_DQ<12>")
	)
	(segment
		(start 38.024562 -212.220048)
		(end 39.254938 -213.450424)
		(width 0.14478)
		(layer "In6.Cu")
		(net "M_E_CPU1_SA_DQ<12>")
	)
	(segment
		(start 36.243768 -212.438996)
		(end 36.243768 -212.373464)
		(width 0.14478)
		(layer "In6.Cu")
		(net "M_E_CPU1_SA_DQ<12>")
	)
	(segment
		(start 79.63408 -233.466894)
		(end 79.642462 -233.47172)
		(width 0.0889)
		(layer "In6.Cu")
		(net "M_E_CPU1_SA_DQ<12>")
	)
	(segment
		(start 49.630838 -213.06028)
		(end 50.480722 -212.210396)
		(width 0.14478)
		(layer "In6.Cu")
		(net "M_E_CPU1_SA_DQ<12>")
	)
	(segment
		(start 44.007024 -212.220048)
		(end 45.589698 -212.220048)
		(width 0.14478)
		(layer "In6.Cu")
		(net "M_E_CPU1_SA_DQ<12>")
	)
	(segment
		(start 29.677106 -213.06028)
		(end 29.883608 -213.06028)
		(width 0.14478)
		(layer "In6.Cu")
		(net "M_E_CPU1_SA_DQ<12>")
	)
	(segment
		(start 35.524186 -212.210396)
		(end 35.687254 -212.373464)
		(width 0.14478)
		(layer "In6.Cu")
		(net "M_E_CPU1_SA_DQ<12>")
	)
	(segment
		(start 41.481248 -213.445344)
		(end 41.644316 -213.282276)
		(width 0.14478)
		(layer "In6.Cu")
		(net "M_E_CPU1_SA_DQ<12>")
	)
	(segment
		(start 55.984902 -212.734398)
		(end 56.711342 -213.460838)
		(width 0.14478)
		(layer "In6.Cu")
		(net "M_E_CPU1_SA_DQ<12>")
	)
	(segment
		(start 31.211012 -213.287356)
		(end 31.37408 -213.450424)
		(width 0.14478)
		(layer "In6.Cu")
		(net "M_E_CPU1_SA_DQ<12>")
	)
	(segment
		(start 30.209744 -212.282024)
		(end 30.440122 -212.282024)
		(width 0.14478)
		(layer "In6.Cu")
		(net "M_E_CPU1_SA_DQ<12>")
	)
	(segment
		(start 78.27645 -233.382566)
		(end 78.380844 -233.382566)
		(width 0.0889)
		(layer "In6.Cu")
		(net "M_E_CPU1_SA_DQ<12>")
	)
	(segment
		(start 30.046676 -212.897212)
		(end 30.046676 -212.445092)
		(width 0.14478)
		(layer "In6.Cu")
		(net "M_E_CPU1_SA_DQ<12>")
	)
	(segment
		(start 50.826416 -212.373464)
		(end 50.826416 -212.428836)
		(width 0.14478)
		(layer "In6.Cu")
		(net "M_E_CPU1_SA_DQ<12>")
	)
	(segment
		(start 55.36057 -213.453726)
		(end 55.50535 -213.308946)
		(width 0.14478)
		(layer "In6.Cu")
		(net "M_E_CPU1_SA_DQ<12>")
	)
	(segment
		(start 39.857172 -213.069932)
		(end 40.875458 -213.069932)
		(width 0.14478)
		(layer "In6.Cu")
		(net "M_E_CPU1_SA_DQ<12>")
	)
	(segment
		(start 39.703756 -213.223348)
		(end 39.857172 -213.069932)
		(width 0.14478)
		(layer "In6.Cu")
		(net "M_E_CPU1_SA_DQ<12>")
	)
	(segment
		(start 31.767526 -213.287356)
		(end 31.767526 -213.223348)
		(width 0.14478)
		(layer "In6.Cu")
		(net "M_E_CPU1_SA_DQ<12>")
	)
	(segment
		(start 41.644316 -213.223348)
		(end 41.807384 -213.06028)
		(width 0.14478)
		(layer "In6.Cu")
		(net "M_E_CPU1_SA_DQ<12>")
	)
	(segment
		(start 76.508102 -231.43464)
		(end 76.972922 -231.43464)
		(width 0.0889)
		(layer "In6.Cu")
		(net "M_E_CPU1_SA_DQ<12>")
	)
	(segment
		(start 49.317148 -213.223348)
		(end 49.480216 -213.06028)
		(width 0.14478)
		(layer "In6.Cu")
		(net "M_E_CPU1_SA_DQ<12>")
	)
	(segment
		(start 48.923702 -213.450424)
		(end 49.15408 -213.450424)
		(width 0.14478)
		(layer "In6.Cu")
		(net "M_E_CPU1_SA_DQ<12>")
	)
	(segment
		(start 64.289178 -215.259666)
		(end 67.44589 -218.416378)
		(width 0.14478)
		(layer "In6.Cu")
		(net "M_E_CPU1_SA_DQ<12>")
	)
	(segment
		(start 55.08625 -213.453726)
		(end 55.36057 -213.453726)
		(width 0.14478)
		(layer "In6.Cu")
		(net "M_E_CPU1_SA_DQ<12>")
	)
	(segment
		(start 77.168502 -231.63022)
		(end 77.168502 -232.274618)
		(width 0.0889)
		(layer "In6.Cu")
		(net "M_E_CPU1_SA_DQ<12>")
	)
	(segment
		(start 51.38293 -212.373464)
		(end 51.536346 -212.220048)
		(width 0.14478)
		(layer "In6.Cu")
		(net "M_E_CPU1_SA_DQ<12>")
	)
	(segment
		(start 49.317148 -213.287356)
		(end 49.317148 -213.223348)
		(width 0.14478)
		(layer "In6.Cu")
		(net "M_E_CPU1_SA_DQ<12>")
	)
	(segment
		(start 77.168502 -232.274618)
		(end 78.27645 -233.382566)
		(width 0.0889)
		(layer "In6.Cu")
		(net "M_E_CPU1_SA_DQ<12>")
	)
	(segment
		(start 50.989484 -212.591904)
		(end 51.219862 -212.591904)
		(width 0.14478)
		(layer "In6.Cu")
		(net "M_E_CPU1_SA_DQ<12>")
	)
	(segment
		(start 31.767526 -213.223348)
		(end 31.920942 -213.069932)
		(width 0.14478)
		(layer "In6.Cu")
		(net "M_E_CPU1_SA_DQ<12>")
	)
	(segment
		(start 35.354514 -212.210396)
		(end 35.524186 -212.210396)
		(width 0.14478)
		(layer "In6.Cu")
		(net "M_E_CPU1_SA_DQ<12>")
	)
	(segment
		(start 46.439582 -213.069932)
		(end 48.54321 -213.069932)
		(width 0.14478)
		(layer "In6.Cu")
		(net "M_E_CPU1_SA_DQ<12>")
	)
	(segment
		(start 51.536346 -212.220048)
		(end 53.15458 -212.220048)
		(width 0.14478)
		(layer "In6.Cu")
		(net "M_E_CPU1_SA_DQ<12>")
	)
	(segment
		(start 54.94147 -213.308946)
		(end 55.08625 -213.453726)
		(width 0.14478)
		(layer "In6.Cu")
		(net "M_E_CPU1_SA_DQ<12>")
	)
	(segment
		(start 41.807384 -213.06028)
		(end 42.13733 -213.06028)
		(width 0.14478)
		(layer "In6.Cu")
		(net "M_E_CPU1_SA_DQ<12>")
	)
	(segment
		(start 53.81371 -213.308946)
		(end 53.95849 -213.453726)
		(width 0.14478)
		(layer "In6.Cu")
		(net "M_E_CPU1_SA_DQ<12>")
	)
	(segment
		(start 80.89265 -233.493056)
		(end 80.915002 -233.409744)
		(width 0.0889)
		(layer "In6.Cu")
		(net "M_E_CPU1_SA_DQ<12>")
	)
	(segment
		(start 75.607926 -230.882444)
		(end 75.955906 -230.882444)
		(width 0.0889)
		(layer "In6.Cu")
		(net "M_E_CPU1_SA_DQ<12>")
	)
	(segment
		(start 55.50535 -213.308946)
		(end 55.50535 -212.879178)
		(width 0.14478)
		(layer "In6.Cu")
		(net "M_E_CPU1_SA_DQ<12>")
	)
	(segment
		(start 33.67405 -213.450424)
		(end 33.904428 -213.450424)
		(width 0.14478)
		(layer "In6.Cu")
		(net "M_E_CPU1_SA_DQ<12>")
	)
	(arc
		(start 79.068422 -233.466894)
		(mid 79.345235 -233.390751)
		(end 79.623666 -233.460798)
		(width 0.0889)
		(layer "In6.Cu")
		(net "M_E_CPU1_SA_DQ<12>")
	)
	(arc
		(start 78.69428 -233.466894)
		(mid 78.876531 -233.517244)
		(end 79.06004 -233.47172)
		(width 0.0889)
		(layer "In6.Cu")
		(net "M_E_CPU1_SA_DQ<12>")
	)
	(arc
		(start 78.380844 -233.382566)
		(mid 78.543129 -233.404027)
		(end 78.69428 -233.466894)
		(width 0.0889)
		(layer "In6.Cu")
		(net "M_E_CPU1_SA_DQ<12>")
	)
	(arc
		(start 80.574134 -233.466894)
		(mid 80.730453 -233.515889)
		(end 80.89265 -233.493056)
		(width 0.0889)
		(layer "In6.Cu")
		(net "M_E_CPU1_SA_DQ<12>")
	)
	(arc
		(start 79.642462 -233.47172)
		(mid 79.82597 -233.517214)
		(end 80.008222 -233.466894)
		(width 0.0889)
		(layer "In6.Cu")
		(net "M_E_CPU1_SA_DQ<12>")
	)
	(arc
		(start 80.008222 -233.466894)
		(mid 80.291178 -233.390717)
		(end 80.574134 -233.466894)
		(width 0.0889)
		(layer "In6.Cu")
		(net "M_E_CPU1_SA_DQ<12>")
	)
	(segment
		(start 83.107784 -231.79024)
		(end 82.640932 -231.524302)
		(width 0.10668)
		(layer "F.Cu")
		(net "M_E_CPU1_SA_DQ<11>")
	)
	(segment
		(start 53.246782 -208.8007)
		(end 54.106572 -209.66049)
		(width 0.14478)
		(layer "In6.Cu")
		(net "M_E_CPU1_SA_DQ<11>")
	)
	(segment
		(start 38.864032 -209.650584)
		(end 41.833292 -209.650584)
		(width 0.14478)
		(layer "In6.Cu")
		(net "M_E_CPU1_SA_DQ<11>")
	)
	(segment
		(start 78.085188 -230.301546)
		(end 78.56093 -230.301546)
		(width 0.0889)
		(layer "In6.Cu")
		(net "M_E_CPU1_SA_DQ<11>")
	)
	(segment
		(start 54.106572 -209.66049)
		(end 56.974232 -209.66049)
		(width 0.14478)
		(layer "In6.Cu")
		(net "M_E_CPU1_SA_DQ<11>")
	)
	(segment
		(start 71.987156 -224.124774)
		(end 76.006706 -228.144324)
		(width 0.14478)
		(layer "In6.Cu")
		(net "M_E_CPU1_SA_DQ<11>")
	)
	(segment
		(start 76.239116 -228.376734)
		(end 76.239116 -228.826314)
		(width 0.0889)
		(layer "In6.Cu")
		(net "M_E_CPU1_SA_DQ<11>")
	)
	(segment
		(start 25.152096 -209.235294)
		(end 26.154888 -209.650584)
		(width 0.14478)
		(layer "In6.Cu")
		(net "M_E_CPU1_SA_DQ<11>")
	)
	(segment
		(start 78.56093 -230.301546)
		(end 79.218028 -230.958644)
		(width 0.0889)
		(layer "In6.Cu")
		(net "M_E_CPU1_SA_DQ<11>")
	)
	(segment
		(start 69.796406 -221.103698)
		(end 71.987156 -223.294448)
		(width 0.14478)
		(layer "In6.Cu")
		(net "M_E_CPU1_SA_DQ<11>")
	)
	(segment
		(start 46.552866 -209.650584)
		(end 49.440338 -209.650584)
		(width 0.14478)
		(layer "In6.Cu")
		(net "M_E_CPU1_SA_DQ<11>")
	)
	(segment
		(start 57.82437 -208.810352)
		(end 61.077094 -208.810352)
		(width 0.14478)
		(layer "In6.Cu")
		(net "M_E_CPU1_SA_DQ<11>")
	)
	(segment
		(start 56.974232 -209.66049)
		(end 57.82437 -208.810352)
		(width 0.14478)
		(layer "In6.Cu")
		(net "M_E_CPU1_SA_DQ<11>")
	)
	(segment
		(start 82.487008 -231.258872)
		(end 82.640932 -231.524302)
		(width 0.0889)
		(layer "In6.Cu")
		(net "M_E_CPU1_SA_DQ<11>")
	)
	(segment
		(start 76.239116 -228.826314)
		(end 76.801726 -229.388924)
		(width 0.0889)
		(layer "In6.Cu")
		(net "M_E_CPU1_SA_DQ<11>")
	)
	(segment
		(start 82.39125 -231.233472)
		(end 82.487008 -231.258872)
		(width 0.0889)
		(layer "In6.Cu")
		(net "M_E_CPU1_SA_DQ<11>")
	)
	(segment
		(start 35.128962 -208.8007)
		(end 38.014148 -208.8007)
		(width 0.14478)
		(layer "In6.Cu")
		(net "M_E_CPU1_SA_DQ<11>")
	)
	(segment
		(start 76.801726 -229.388924)
		(end 77.172566 -229.388924)
		(width 0.0889)
		(layer "In6.Cu")
		(net "M_E_CPU1_SA_DQ<11>")
	)
	(segment
		(start 45.702982 -208.8007)
		(end 46.552866 -209.650584)
		(width 0.14478)
		(layer "In6.Cu")
		(net "M_E_CPU1_SA_DQ<11>")
	)
	(segment
		(start 61.077094 -208.810352)
		(end 69.796406 -217.529664)
		(width 0.14478)
		(layer "In6.Cu")
		(net "M_E_CPU1_SA_DQ<11>")
	)
	(segment
		(start 50.290222 -208.8007)
		(end 53.246782 -208.8007)
		(width 0.14478)
		(layer "In6.Cu")
		(net "M_E_CPU1_SA_DQ<11>")
	)
	(segment
		(start 77.172566 -229.388924)
		(end 78.085188 -230.301546)
		(width 0.0889)
		(layer "In6.Cu")
		(net "M_E_CPU1_SA_DQ<11>")
	)
	(segment
		(start 49.440338 -209.650584)
		(end 50.290222 -208.8007)
		(width 0.14478)
		(layer "In6.Cu")
		(net "M_E_CPU1_SA_DQ<11>")
	)
	(segment
		(start 38.014148 -208.8007)
		(end 38.864032 -209.650584)
		(width 0.14478)
		(layer "In6.Cu")
		(net "M_E_CPU1_SA_DQ<11>")
	)
	(segment
		(start 34.279078 -209.650584)
		(end 35.128962 -208.8007)
		(width 0.14478)
		(layer "In6.Cu")
		(net "M_E_CPU1_SA_DQ<11>")
	)
	(segment
		(start 71.987156 -223.294448)
		(end 71.987156 -224.124774)
		(width 0.14478)
		(layer "In6.Cu")
		(net "M_E_CPU1_SA_DQ<11>")
	)
	(segment
		(start 42.683176 -208.8007)
		(end 45.702982 -208.8007)
		(width 0.14478)
		(layer "In6.Cu")
		(net "M_E_CPU1_SA_DQ<11>")
	)
	(segment
		(start 76.006706 -228.144324)
		(end 76.239116 -228.376734)
		(width 0.0889)
		(layer "In6.Cu")
		(net "M_E_CPU1_SA_DQ<11>")
	)
	(segment
		(start 41.833292 -209.650584)
		(end 42.683176 -208.8007)
		(width 0.14478)
		(layer "In6.Cu")
		(net "M_E_CPU1_SA_DQ<11>")
	)
	(segment
		(start 69.796406 -217.529664)
		(end 69.796406 -221.103698)
		(width 0.14478)
		(layer "In6.Cu")
		(net "M_E_CPU1_SA_DQ<11>")
	)
	(segment
		(start 26.154888 -209.650584)
		(end 34.279078 -209.650584)
		(width 0.14478)
		(layer "In6.Cu")
		(net "M_E_CPU1_SA_DQ<11>")
	)
	(segment
		(start 81.879694 -231.19715)
		(end 81.888076 -231.201976)
		(width 0.0889)
		(layer "In6.Cu")
		(net "M_E_CPU1_SA_DQ<11>")
	)
	(arc
		(start 80.574134 -231.201976)
		(mid 80.761078 -231.151687)
		(end 80.948022 -231.201976)
		(width 0.0889)
		(layer "In6.Cu")
		(net "M_E_CPU1_SA_DQ<11>")
	)
	(arc
		(start 80.948022 -231.201976)
		(mid 81.230978 -231.278153)
		(end 81.513934 -231.201976)
		(width 0.0889)
		(layer "In6.Cu")
		(net "M_E_CPU1_SA_DQ<11>")
	)
	(arc
		(start 80.008222 -231.201976)
		(mid 80.291178 -231.278153)
		(end 80.574134 -231.201976)
		(width 0.0889)
		(layer "In6.Cu")
		(net "M_E_CPU1_SA_DQ<11>")
	)
	(arc
		(start 79.718662 -231.165908)
		(mid 79.867115 -231.154437)
		(end 80.008222 -231.201976)
		(width 0.0889)
		(layer "In6.Cu")
		(net "M_E_CPU1_SA_DQ<11>")
	)
	(arc
		(start 81.888076 -231.201976)
		(mid 82.135936 -231.277059)
		(end 82.39125 -231.233472)
		(width 0.0889)
		(layer "In6.Cu")
		(net "M_E_CPU1_SA_DQ<11>")
	)
	(arc
		(start 81.513934 -231.201976)
		(mid 81.696185 -231.151592)
		(end 81.879694 -231.19715)
		(width 0.0889)
		(layer "In6.Cu")
		(net "M_E_CPU1_SA_DQ<11>")
	)
	(arc
		(start 79.218028 -230.958644)
		(mid 79.447735 -231.112066)
		(end 79.718662 -231.165908)
		(width 0.0889)
		(layer "In6.Cu")
		(net "M_E_CPU1_SA_DQ<11>")
	)
	(segment
		(start 81.69783 -230.980234)
		(end 81.230978 -230.71455)
		(width 0.10668)
		(layer "F.Cu")
		(net "M_E_CPU1_SA_DQ<10>")
	)
	(segment
		(start 79.538322 -230.39197)
		(end 79.548736 -230.398066)
		(width 0.0889)
		(layer "In6.Cu")
		(net "M_E_CPU1_SA_DQ<10>")
	)
	(segment
		(start 26.40457 -207.479392)
		(end 26.567638 -207.316324)
		(width 0.14478)
		(layer "In6.Cu")
		(net "M_E_CPU1_SA_DQ<10>")
	)
	(segment
		(start 26.241502 -207.960468)
		(end 26.40457 -207.7974)
		(width 0.14478)
		(layer "In6.Cu")
		(net "M_E_CPU1_SA_DQ<10>")
	)
	(segment
		(start 34.269172 -207.960468)
		(end 35.11931 -207.11033)
		(width 0.14478)
		(layer "In6.Cu")
		(net "M_E_CPU1_SA_DQ<10>")
	)
	(segment
		(start 78.279498 -229.813104)
		(end 78.932786 -229.813104)
		(width 0.0889)
		(layer "In6.Cu")
		(net "M_E_CPU1_SA_DQ<10>")
	)
	(segment
		(start 46.562772 -207.960468)
		(end 49.430432 -207.960468)
		(width 0.14478)
		(layer "In6.Cu")
		(net "M_E_CPU1_SA_DQ<10>")
	)
	(segment
		(start 72.886316 -223.737678)
		(end 75.925934 -226.777296)
		(width 0.14478)
		(layer "In6.Cu")
		(net "M_E_CPU1_SA_DQ<10>")
	)
	(segment
		(start 25.577292 -207.960468)
		(end 26.241502 -207.960468)
		(width 0.14478)
		(layer "In6.Cu")
		(net "M_E_CPU1_SA_DQ<10>")
	)
	(segment
		(start 77.400912 -228.934518)
		(end 78.279498 -229.813104)
		(width 0.0889)
		(layer "In6.Cu")
		(net "M_E_CPU1_SA_DQ<10>")
	)
	(segment
		(start 35.11931 -207.11033)
		(end 38.0238 -207.11033)
		(width 0.14478)
		(layer "In6.Cu")
		(net "M_E_CPU1_SA_DQ<10>")
	)
	(segment
		(start 26.567638 -207.316324)
		(end 26.798016 -207.316324)
		(width 0.14478)
		(layer "In6.Cu")
		(net "M_E_CPU1_SA_DQ<10>")
	)
	(segment
		(start 26.40457 -207.7974)
		(end 26.40457 -207.479392)
		(width 0.14478)
		(layer "In6.Cu")
		(net "M_E_CPU1_SA_DQ<10>")
	)
	(segment
		(start 54.106572 -207.960468)
		(end 56.974232 -207.960468)
		(width 0.14478)
		(layer "In6.Cu")
		(net "M_E_CPU1_SA_DQ<10>")
	)
	(segment
		(start 25.152096 -207.535272)
		(end 25.577292 -207.960468)
		(width 0.14478)
		(layer "In6.Cu")
		(net "M_E_CPU1_SA_DQ<10>")
	)
	(segment
		(start 76.98994 -228.934518)
		(end 77.400912 -228.934518)
		(width 0.0889)
		(layer "In6.Cu")
		(net "M_E_CPU1_SA_DQ<10>")
	)
	(segment
		(start 38.0238 -207.11033)
		(end 38.873938 -207.960468)
		(width 0.14478)
		(layer "In6.Cu")
		(net "M_E_CPU1_SA_DQ<10>")
	)
	(segment
		(start 76.179426 -227.105464)
		(end 76.645516 -227.571554)
		(width 0.0889)
		(layer "In6.Cu")
		(net "M_E_CPU1_SA_DQ<10>")
	)
	(segment
		(start 49.430432 -207.960468)
		(end 50.28057 -207.11033)
		(width 0.14478)
		(layer "In6.Cu")
		(net "M_E_CPU1_SA_DQ<10>")
	)
	(segment
		(start 26.798016 -207.316324)
		(end 26.961084 -207.479392)
		(width 0.14478)
		(layer "In6.Cu")
		(net "M_E_CPU1_SA_DQ<10>")
	)
	(segment
		(start 75.925934 -226.777296)
		(end 75.940158 -226.777296)
		(width 0.0889)
		(layer "In6.Cu")
		(net "M_E_CPU1_SA_DQ<10>")
	)
	(segment
		(start 75.940158 -226.777296)
		(end 76.179426 -227.016564)
		(width 0.0889)
		(layer "In6.Cu")
		(net "M_E_CPU1_SA_DQ<10>")
	)
	(segment
		(start 42.673524 -207.11033)
		(end 45.712634 -207.11033)
		(width 0.14478)
		(layer "In6.Cu")
		(net "M_E_CPU1_SA_DQ<10>")
	)
	(segment
		(start 60.649104 -207.11033)
		(end 70.721474 -217.1827)
		(width 0.14478)
		(layer "In6.Cu")
		(net "M_E_CPU1_SA_DQ<10>")
	)
	(segment
		(start 70.721474 -220.756734)
		(end 72.886316 -222.921576)
		(width 0.14478)
		(layer "In6.Cu")
		(net "M_E_CPU1_SA_DQ<10>")
	)
	(segment
		(start 26.961084 -207.479392)
		(end 26.961084 -207.7974)
		(width 0.14478)
		(layer "In6.Cu")
		(net "M_E_CPU1_SA_DQ<10>")
	)
	(segment
		(start 72.886316 -222.921576)
		(end 72.886316 -223.737678)
		(width 0.14478)
		(layer "In6.Cu")
		(net "M_E_CPU1_SA_DQ<10>")
	)
	(segment
		(start 50.28057 -207.11033)
		(end 53.256434 -207.11033)
		(width 0.14478)
		(layer "In6.Cu")
		(net "M_E_CPU1_SA_DQ<10>")
	)
	(segment
		(start 38.873938 -207.960468)
		(end 41.823386 -207.960468)
		(width 0.14478)
		(layer "In6.Cu")
		(net "M_E_CPU1_SA_DQ<10>")
	)
	(segment
		(start 26.961084 -207.7974)
		(end 27.124152 -207.960468)
		(width 0.14478)
		(layer "In6.Cu")
		(net "M_E_CPU1_SA_DQ<10>")
	)
	(segment
		(start 56.974232 -207.960468)
		(end 57.82437 -207.11033)
		(width 0.14478)
		(layer "In6.Cu")
		(net "M_E_CPU1_SA_DQ<10>")
	)
	(segment
		(start 76.645516 -227.571554)
		(end 76.645516 -228.590094)
		(width 0.0889)
		(layer "In6.Cu")
		(net "M_E_CPU1_SA_DQ<10>")
	)
	(segment
		(start 76.179426 -227.016564)
		(end 76.179426 -227.105464)
		(width 0.0889)
		(layer "In6.Cu")
		(net "M_E_CPU1_SA_DQ<10>")
	)
	(segment
		(start 81.077054 -230.44912)
		(end 81.230978 -230.71455)
		(width 0.0889)
		(layer "In6.Cu")
		(net "M_E_CPU1_SA_DQ<10>")
	)
	(segment
		(start 80.981042 -230.42372)
		(end 81.077054 -230.44912)
		(width 0.0889)
		(layer "In6.Cu")
		(net "M_E_CPU1_SA_DQ<10>")
	)
	(segment
		(start 70.721474 -217.1827)
		(end 70.721474 -220.756734)
		(width 0.14478)
		(layer "In6.Cu")
		(net "M_E_CPU1_SA_DQ<10>")
	)
	(segment
		(start 78.932786 -229.813104)
		(end 79.422498 -230.302816)
		(width 0.0889)
		(layer "In6.Cu")
		(net "M_E_CPU1_SA_DQ<10>")
	)
	(segment
		(start 57.82437 -207.11033)
		(end 60.649104 -207.11033)
		(width 0.14478)
		(layer "In6.Cu")
		(net "M_E_CPU1_SA_DQ<10>")
	)
	(segment
		(start 53.256434 -207.11033)
		(end 54.106572 -207.960468)
		(width 0.14478)
		(layer "In6.Cu")
		(net "M_E_CPU1_SA_DQ<10>")
	)
	(segment
		(start 80.46974 -230.387144)
		(end 80.478122 -230.39197)
		(width 0.0889)
		(layer "In6.Cu")
		(net "M_E_CPU1_SA_DQ<10>")
	)
	(segment
		(start 45.712634 -207.11033)
		(end 46.562772 -207.960468)
		(width 0.14478)
		(layer "In6.Cu")
		(net "M_E_CPU1_SA_DQ<10>")
	)
	(segment
		(start 27.124152 -207.960468)
		(end 34.269172 -207.960468)
		(width 0.14478)
		(layer "In6.Cu")
		(net "M_E_CPU1_SA_DQ<10>")
	)
	(segment
		(start 41.823386 -207.960468)
		(end 42.673524 -207.11033)
		(width 0.14478)
		(layer "In6.Cu")
		(net "M_E_CPU1_SA_DQ<10>")
	)
	(segment
		(start 76.645516 -228.590094)
		(end 76.98994 -228.934518)
		(width 0.0889)
		(layer "In6.Cu")
		(net "M_E_CPU1_SA_DQ<10>")
	)
	(arc
		(start 80.478122 -230.39197)
		(mid 80.725835 -230.467156)
		(end 80.981042 -230.42372)
		(width 0.0889)
		(layer "In6.Cu")
		(net "M_E_CPU1_SA_DQ<10>")
	)
	(arc
		(start 80.10398 -230.39197)
		(mid 80.286231 -230.34162)
		(end 80.46974 -230.387144)
		(width 0.0889)
		(layer "In6.Cu")
		(net "M_E_CPU1_SA_DQ<10>")
	)
	(arc
		(start 79.548736 -230.398066)
		(mid 79.827168 -230.468132)
		(end 80.10398 -230.39197)
		(width 0.0889)
		(layer "In6.Cu")
		(net "M_E_CPU1_SA_DQ<10>")
	)
	(arc
		(start 79.422498 -230.302816)
		(mid 79.477508 -230.351163)
		(end 79.538322 -230.39197)
		(width 0.0889)
		(layer "In6.Cu")
		(net "M_E_CPU1_SA_DQ<10>")
	)
	(segment
		(start 81.22793 -225.310446)
		(end 80.761078 -225.044508)
		(width 0.10668)
		(layer "F.Cu")
		(net "M_E_CPU1_SA_DQ<0>")
	)
	(segment
		(start 29.252164 -197.335394)
		(end 29.677106 -197.760336)
		(width 0.14478)
		(layer "In6.Cu")
		(net "M_E_CPU1_SA_DQ<0>")
	)
	(segment
		(start 80.915002 -225.309938)
		(end 80.761078 -225.044508)
		(width 0.0889)
		(layer "In6.Cu")
		(net "M_E_CPU1_SA_DQ<0>")
	)
	(segment
		(start 30.959806 -197.001384)
		(end 31.122874 -197.164452)
		(width 0.14478)
		(layer "In6.Cu")
		(net "M_E_CPU1_SA_DQ<0>")
	)
	(segment
		(start 72.477884 -209.572606)
		(end 72.477884 -209.77733)
		(width 0.14478)
		(layer "In6.Cu")
		(net "M_E_CPU1_SA_DQ<0>")
	)
	(segment
		(start 53.23459 -196.910452)
		(end 54.084474 -197.760336)
		(width 0.14478)
		(layer "In6.Cu")
		(net "M_E_CPU1_SA_DQ<0>")
	)
	(segment
		(start 80.610456 -224.700846)
		(end 80.574134 -224.721928)
		(width 0.0889)
		(layer "In6.Cu")
		(net "M_E_CPU1_SA_DQ<0>")
	)
	(segment
		(start 79.44612 -221.565216)
		(end 79.44612 -221.80423)
		(width 0.0889)
		(layer "In6.Cu")
		(net "M_E_CPU1_SA_DQ<0>")
	)
	(segment
		(start 80.574134 -223.747076)
		(end 80.610456 -223.768158)
		(width 0.0889)
		(layer "In6.Cu")
		(net "M_E_CPU1_SA_DQ<0>")
	)
	(segment
		(start 31.122874 -197.597268)
		(end 31.285942 -197.760336)
		(width 0.14478)
		(layer "In6.Cu")
		(net "M_E_CPU1_SA_DQ<0>")
	)
	(segment
		(start 71.680324 -208.775046)
		(end 71.680324 -208.97977)
		(width 0.14478)
		(layer "In6.Cu")
		(net "M_E_CPU1_SA_DQ<0>")
	)
	(segment
		(start 70.279514 -207.57896)
		(end 70.48373 -207.578706)
		(width 0.14478)
		(layer "In6.Cu")
		(net "M_E_CPU1_SA_DQ<0>")
	)
	(segment
		(start 80.072484 -222.918782)
		(end 80.104234 -222.93707)
		(width 0.0889)
		(layer "In6.Cu")
		(net "M_E_CPU1_SA_DQ<0>")
	)
	(segment
		(start 77.060806 -214.360252)
		(end 77.060806 -218.441524)
		(width 0.14478)
		(layer "In6.Cu")
		(net "M_E_CPU1_SA_DQ<0>")
	)
	(segment
		(start 70.982078 -207.285082)
		(end 71.176134 -207.479138)
		(width 0.14478)
		(layer "In6.Cu")
		(net "M_E_CPU1_SA_DQ<0>")
	)
	(segment
		(start 35.308794 -196.910452)
		(end 38.01491 -196.910452)
		(width 0.14478)
		(layer "In6.Cu")
		(net "M_E_CPU1_SA_DQ<0>")
	)
	(segment
		(start 71.779638 -208.082642)
		(end 71.973694 -208.276698)
		(width 0.14478)
		(layer "In6.Cu")
		(net "M_E_CPU1_SA_DQ<0>")
	)
	(segment
		(start 80.574134 -224.721928)
		(end 80.542384 -224.740216)
		(width 0.0889)
		(layer "In6.Cu")
		(net "M_E_CPU1_SA_DQ<0>")
	)
	(segment
		(start 71.973694 -208.276698)
		(end 71.973948 -208.481422)
		(width 0.14478)
		(layer "In6.Cu")
		(net "M_E_CPU1_SA_DQ<0>")
	)
	(segment
		(start 71.176388 -207.683862)
		(end 70.882764 -207.977486)
		(width 0.14478)
		(layer "In6.Cu")
		(net "M_E_CPU1_SA_DQ<0>")
	)
	(segment
		(start 71.28129 -208.376266)
		(end 71.574914 -208.082642)
		(width 0.14478)
		(layer "In6.Cu")
		(net "M_E_CPU1_SA_DQ<0>")
	)
	(segment
		(start 70.882764 -207.977486)
		(end 70.882764 -208.18221)
		(width 0.14478)
		(layer "In6.Cu")
		(net "M_E_CPU1_SA_DQ<0>")
	)
	(segment
		(start 79.562706 -221.232984)
		(end 79.562706 -221.44863)
		(width 0.0889)
		(layer "In6.Cu")
		(net "M_E_CPU1_SA_DQ<0>")
	)
	(segment
		(start 71.680324 -208.97977)
		(end 71.874634 -209.17408)
		(width 0.14478)
		(layer "In6.Cu")
		(net "M_E_CPU1_SA_DQ<0>")
	)
	(segment
		(start 71.077074 -208.37652)
		(end 71.28129 -208.376266)
		(width 0.14478)
		(layer "In6.Cu")
		(net "M_E_CPU1_SA_DQ<0>")
	)
	(segment
		(start 30.729428 -197.001384)
		(end 30.959806 -197.001384)
		(width 0.14478)
		(layer "In6.Cu")
		(net "M_E_CPU1_SA_DQ<0>")
	)
	(segment
		(start 57.980834 -196.910452)
		(end 60.64758 -196.910452)
		(width 0.14478)
		(layer "In6.Cu")
		(net "M_E_CPU1_SA_DQ<0>")
	)
	(segment
		(start 54.084474 -197.760336)
		(end 57.13095 -197.760336)
		(width 0.14478)
		(layer "In6.Cu")
		(net "M_E_CPU1_SA_DQ<0>")
	)
	(segment
		(start 80.89265 -225.39325)
		(end 80.915002 -225.309938)
		(width 0.0889)
		(layer "In6.Cu")
		(net "M_E_CPU1_SA_DQ<0>")
	)
	(segment
		(start 29.677106 -197.760336)
		(end 30.403292 -197.760336)
		(width 0.14478)
		(layer "In6.Cu")
		(net "M_E_CPU1_SA_DQ<0>")
	)
	(segment
		(start 72.771254 -209.074258)
		(end 72.771508 -209.278982)
		(width 0.14478)
		(layer "In6.Cu")
		(net "M_E_CPU1_SA_DQ<0>")
	)
	(segment
		(start 34.45891 -197.760336)
		(end 35.308794 -196.910452)
		(width 0.14478)
		(layer "In6.Cu")
		(net "M_E_CPU1_SA_DQ<0>")
	)
	(segment
		(start 79.562706 -221.44863)
		(end 79.44612 -221.565216)
		(width 0.0889)
		(layer "In6.Cu")
		(net "M_E_CPU1_SA_DQ<0>")
	)
	(segment
		(start 30.403292 -197.760336)
		(end 30.56636 -197.597268)
		(width 0.14478)
		(layer "In6.Cu")
		(net "M_E_CPU1_SA_DQ<0>")
	)
	(segment
		(start 77.060806 -218.441524)
		(end 79.562706 -220.943424)
		(width 0.14478)
		(layer "In6.Cu")
		(net "M_E_CPU1_SA_DQ<0>")
	)
	(segment
		(start 72.771508 -209.278982)
		(end 72.477884 -209.572606)
		(width 0.14478)
		(layer "In6.Cu")
		(net "M_E_CPU1_SA_DQ<0>")
	)
	(segment
		(start 46.540674 -197.760336)
		(end 49.58715 -197.760336)
		(width 0.14478)
		(layer "In6.Cu")
		(net "M_E_CPU1_SA_DQ<0>")
	)
	(segment
		(start 79.562706 -220.943424)
		(end 79.562706 -221.232984)
		(width 0.14478)
		(layer "In6.Cu")
		(net "M_E_CPU1_SA_DQ<0>")
	)
	(segment
		(start 30.56636 -197.164452)
		(end 30.729428 -197.001384)
		(width 0.14478)
		(layer "In6.Cu")
		(net "M_E_CPU1_SA_DQ<0>")
	)
	(segment
		(start 80.104234 -222.93707)
		(end 80.140556 -222.958152)
		(width 0.0889)
		(layer "In6.Cu")
		(net "M_E_CPU1_SA_DQ<0>")
	)
	(segment
		(start 70.48373 -207.578706)
		(end 70.777354 -207.285082)
		(width 0.14478)
		(layer "In6.Cu")
		(net "M_E_CPU1_SA_DQ<0>")
	)
	(segment
		(start 45.69079 -196.910452)
		(end 46.540674 -197.760336)
		(width 0.14478)
		(layer "In6.Cu")
		(net "M_E_CPU1_SA_DQ<0>")
	)
	(segment
		(start 38.01491 -196.910452)
		(end 38.864794 -197.760336)
		(width 0.14478)
		(layer "In6.Cu")
		(net "M_E_CPU1_SA_DQ<0>")
	)
	(segment
		(start 50.437034 -196.910452)
		(end 53.23459 -196.910452)
		(width 0.14478)
		(layer "In6.Cu")
		(net "M_E_CPU1_SA_DQ<0>")
	)
	(segment
		(start 71.176134 -207.479138)
		(end 71.176388 -207.683862)
		(width 0.14478)
		(layer "In6.Cu")
		(net "M_E_CPU1_SA_DQ<0>")
	)
	(segment
		(start 72.372474 -208.880202)
		(end 72.577198 -208.880202)
		(width 0.14478)
		(layer "In6.Cu")
		(net "M_E_CPU1_SA_DQ<0>")
	)
	(segment
		(start 30.56636 -197.597268)
		(end 30.56636 -197.164452)
		(width 0.14478)
		(layer "In6.Cu")
		(net "M_E_CPU1_SA_DQ<0>")
	)
	(segment
		(start 72.477884 -209.77733)
		(end 77.060806 -214.360252)
		(width 0.14478)
		(layer "In6.Cu")
		(net "M_E_CPU1_SA_DQ<0>")
	)
	(segment
		(start 31.122874 -197.164452)
		(end 31.122874 -197.597268)
		(width 0.14478)
		(layer "In6.Cu")
		(net "M_E_CPU1_SA_DQ<0>")
	)
	(segment
		(start 79.60233 -222.108776)
		(end 79.671926 -222.148908)
		(width 0.0889)
		(layer "In6.Cu")
		(net "M_E_CPU1_SA_DQ<0>")
	)
	(segment
		(start 80.542384 -223.728788)
		(end 80.574134 -223.747076)
		(width 0.0889)
		(layer "In6.Cu")
		(net "M_E_CPU1_SA_DQ<0>")
	)
	(segment
		(start 71.574914 -208.082642)
		(end 71.779638 -208.082642)
		(width 0.14478)
		(layer "In6.Cu")
		(net "M_E_CPU1_SA_DQ<0>")
	)
	(segment
		(start 38.864794 -197.760336)
		(end 42.00525 -197.760336)
		(width 0.14478)
		(layer "In6.Cu")
		(net "M_E_CPU1_SA_DQ<0>")
	)
	(segment
		(start 60.64758 -196.910452)
		(end 69.811392 -206.074264)
		(width 0.14478)
		(layer "In6.Cu")
		(net "M_E_CPU1_SA_DQ<0>")
	)
	(segment
		(start 69.811392 -207.110838)
		(end 70.279514 -207.57896)
		(width 0.14478)
		(layer "In6.Cu")
		(net "M_E_CPU1_SA_DQ<0>")
	)
	(segment
		(start 72.07885 -209.173826)
		(end 72.372474 -208.880202)
		(width 0.14478)
		(layer "In6.Cu")
		(net "M_E_CPU1_SA_DQ<0>")
	)
	(segment
		(start 80.542384 -225.3488)
		(end 80.574134 -225.367088)
		(width 0.0889)
		(layer "In6.Cu")
		(net "M_E_CPU1_SA_DQ<0>")
	)
	(segment
		(start 72.577198 -208.880202)
		(end 72.771254 -209.074258)
		(width 0.14478)
		(layer "In6.Cu")
		(net "M_E_CPU1_SA_DQ<0>")
	)
	(segment
		(start 42.855134 -196.910452)
		(end 45.69079 -196.910452)
		(width 0.14478)
		(layer "In6.Cu")
		(net "M_E_CPU1_SA_DQ<0>")
	)
	(segment
		(start 57.13095 -197.760336)
		(end 57.980834 -196.910452)
		(width 0.14478)
		(layer "In6.Cu")
		(net "M_E_CPU1_SA_DQ<0>")
	)
	(segment
		(start 71.874634 -209.17408)
		(end 72.07885 -209.173826)
		(width 0.14478)
		(layer "In6.Cu")
		(net "M_E_CPU1_SA_DQ<0>")
	)
	(segment
		(start 49.58715 -197.760336)
		(end 50.437034 -196.910452)
		(width 0.14478)
		(layer "In6.Cu")
		(net "M_E_CPU1_SA_DQ<0>")
	)
	(segment
		(start 70.882764 -208.18221)
		(end 71.077074 -208.37652)
		(width 0.14478)
		(layer "In6.Cu")
		(net "M_E_CPU1_SA_DQ<0>")
	)
	(segment
		(start 31.285942 -197.760336)
		(end 34.45891 -197.760336)
		(width 0.14478)
		(layer "In6.Cu")
		(net "M_E_CPU1_SA_DQ<0>")
	)
	(segment
		(start 70.777354 -207.285082)
		(end 70.982078 -207.285082)
		(width 0.14478)
		(layer "In6.Cu")
		(net "M_E_CPU1_SA_DQ<0>")
	)
	(segment
		(start 71.973948 -208.481422)
		(end 71.680324 -208.775046)
		(width 0.14478)
		(layer "In6.Cu")
		(net "M_E_CPU1_SA_DQ<0>")
	)
	(segment
		(start 42.00525 -197.760336)
		(end 42.855134 -196.910452)
		(width 0.14478)
		(layer "In6.Cu")
		(net "M_E_CPU1_SA_DQ<0>")
	)
	(segment
		(start 69.811392 -206.074264)
		(end 69.811392 -207.110838)
		(width 0.14478)
		(layer "In6.Cu")
		(net "M_E_CPU1_SA_DQ<0>")
	)
	(arc
		(start 80.610456 -223.768158)
		(mid 80.856346 -224.234502)
		(end 80.610456 -224.700846)
		(width 0.0889)
		(layer "In6.Cu")
		(net "M_E_CPU1_SA_DQ<0>")
	)
	(arc
		(start 79.581502 -222.09252)
		(mid 79.591772 -222.100832)
		(end 79.60233 -222.108776)
		(width 0.0889)
		(layer "In6.Cu")
		(net "M_E_CPU1_SA_DQ<0>")
	)
	(arc
		(start 80.140556 -222.958152)
		(mid 80.321208 -223.160897)
		(end 80.386428 -223.424496)
		(width 0.0889)
		(layer "In6.Cu")
		(net "M_E_CPU1_SA_DQ<0>")
	)
	(arc
		(start 79.916528 -222.61449)
		(mid 79.957783 -222.785461)
		(end 80.072484 -222.918782)
		(width 0.0889)
		(layer "In6.Cu")
		(net "M_E_CPU1_SA_DQ<0>")
	)
	(arc
		(start 79.44612 -221.80423)
		(mid 79.48165 -221.963478)
		(end 79.581502 -222.09252)
		(width 0.0889)
		(layer "In6.Cu")
		(net "M_E_CPU1_SA_DQ<0>")
	)
	(arc
		(start 80.542384 -224.740216)
		(mid 80.386456 -225.044508)
		(end 80.542384 -225.3488)
		(width 0.0889)
		(layer "In6.Cu")
		(net "M_E_CPU1_SA_DQ<0>")
	)
	(arc
		(start 80.386428 -223.424496)
		(mid 80.427683 -223.595467)
		(end 80.542384 -223.728788)
		(width 0.0889)
		(layer "In6.Cu")
		(net "M_E_CPU1_SA_DQ<0>")
	)
	(arc
		(start 79.671926 -222.148908)
		(mid 79.851655 -222.351528)
		(end 79.916528 -222.61449)
		(width 0.0889)
		(layer "In6.Cu")
		(net "M_E_CPU1_SA_DQ<0>")
	)
	(arc
		(start 80.574134 -225.367088)
		(mid 80.730453 -225.416083)
		(end 80.89265 -225.39325)
		(width 0.0889)
		(layer "In6.Cu")
		(net "M_E_CPU1_SA_DQ<0>")
	)
	(segment
		(start 83.107784 -252.850396)
		(end 82.640932 -252.584458)
		(width 0.10668)
		(layer "F.Cu")
		(net "M_E_CPU1_SA_CS_N<1>")
	)
	(segment
		(start 76.273406 -252.833124)
		(end 76.644246 -252.462284)
		(width 0.0889)
		(layer "In6.Cu")
		(net "M_E_CPU1_SA_CS_N<1>")
	)
	(segment
		(start 74.357738 -252.833124)
		(end 75.981306 -252.833124)
		(width 0.14478)
		(layer "In6.Cu")
		(net "M_E_CPU1_SA_CS_N<1>")
	)
	(segment
		(start 73.042018 -251.517404)
		(end 74.357738 -252.833124)
		(width 0.14478)
		(layer "In6.Cu")
		(net "M_E_CPU1_SA_CS_N<1>")
	)
	(segment
		(start 82.390996 -252.293628)
		(end 82.487008 -252.319028)
		(width 0.0889)
		(layer "In6.Cu")
		(net "M_E_CPU1_SA_CS_N<1>")
	)
	(segment
		(start 25.577038 -247.060212)
		(end 29.613098 -247.060212)
		(width 0.14478)
		(layer "In6.Cu")
		(net "M_E_CPU1_SA_CS_N<1>")
	)
	(segment
		(start 79.634334 -252.261878)
		(end 79.646018 -252.25502)
		(width 0.0889)
		(layer "In6.Cu")
		(net "M_E_CPU1_SA_CS_N<1>")
	)
	(segment
		(start 82.487008 -252.319028)
		(end 82.640932 -252.584458)
		(width 0.0889)
		(layer "In6.Cu")
		(net "M_E_CPU1_SA_CS_N<1>")
	)
	(segment
		(start 29.613098 -247.060212)
		(end 31.31312 -248.760234)
		(width 0.14478)
		(layer "In6.Cu")
		(net "M_E_CPU1_SA_CS_N<1>")
	)
	(segment
		(start 79.62392 -252.267974)
		(end 79.634334 -252.261878)
		(width 0.0889)
		(layer "In6.Cu")
		(net "M_E_CPU1_SA_CS_N<1>")
	)
	(segment
		(start 31.31312 -248.760234)
		(end 59.77001 -248.760234)
		(width 0.14478)
		(layer "In6.Cu")
		(net "M_E_CPU1_SA_CS_N<1>")
	)
	(segment
		(start 62.52718 -251.517404)
		(end 73.042018 -251.517404)
		(width 0.14478)
		(layer "In6.Cu")
		(net "M_E_CPU1_SA_CS_N<1>")
	)
	(segment
		(start 81.879694 -252.257052)
		(end 81.888076 -252.261878)
		(width 0.0889)
		(layer "In6.Cu")
		(net "M_E_CPU1_SA_CS_N<1>")
	)
	(segment
		(start 77.157326 -252.462284)
		(end 77.352144 -252.267466)
		(width 0.0889)
		(layer "In6.Cu")
		(net "M_E_CPU1_SA_CS_N<1>")
	)
	(segment
		(start 79.056992 -252.25502)
		(end 79.068676 -252.261878)
		(width 0.0889)
		(layer "In6.Cu")
		(net "M_E_CPU1_SA_CS_N<1>")
	)
	(segment
		(start 76.644246 -252.462284)
		(end 77.157326 -252.462284)
		(width 0.0889)
		(layer "In6.Cu")
		(net "M_E_CPU1_SA_CS_N<1>")
	)
	(segment
		(start 78.128622 -252.262132)
		(end 78.14056 -252.26899)
		(width 0.0889)
		(layer "In6.Cu")
		(net "M_E_CPU1_SA_CS_N<1>")
	)
	(segment
		(start 77.352144 -252.267466)
		(end 77.758036 -252.267466)
		(width 0.0889)
		(layer "In6.Cu")
		(net "M_E_CPU1_SA_CS_N<1>")
	)
	(segment
		(start 59.77001 -248.760234)
		(end 62.52718 -251.517404)
		(width 0.14478)
		(layer "In6.Cu")
		(net "M_E_CPU1_SA_CS_N<1>")
	)
	(segment
		(start 25.152096 -246.63527)
		(end 25.577038 -247.060212)
		(width 0.14478)
		(layer "In6.Cu")
		(net "M_E_CPU1_SA_CS_N<1>")
	)
	(segment
		(start 75.981306 -252.833124)
		(end 76.273406 -252.833124)
		(width 0.0889)
		(layer "In6.Cu")
		(net "M_E_CPU1_SA_CS_N<1>")
	)
	(arc
		(start 80.948022 -252.261878)
		(mid 81.230978 -252.338055)
		(end 81.513934 -252.261878)
		(width 0.0889)
		(layer "In6.Cu")
		(net "M_E_CPU1_SA_CS_N<1>")
	)
	(arc
		(start 77.758036 -252.267466)
		(mid 77.942591 -252.213954)
		(end 78.128622 -252.262132)
		(width 0.0889)
		(layer "In6.Cu")
		(net "M_E_CPU1_SA_CS_N<1>")
	)
	(arc
		(start 78.14056 -252.26899)
		(mid 78.418348 -252.338092)
		(end 78.69428 -252.261878)
		(width 0.0889)
		(layer "In6.Cu")
		(net "M_E_CPU1_SA_CS_N<1>")
	)
	(arc
		(start 81.513934 -252.261878)
		(mid 81.696185 -252.211528)
		(end 81.879694 -252.257052)
		(width 0.0889)
		(layer "In6.Cu")
		(net "M_E_CPU1_SA_CS_N<1>")
	)
	(arc
		(start 79.068676 -252.261878)
		(mid 79.345489 -252.338021)
		(end 79.62392 -252.267974)
		(width 0.0889)
		(layer "In6.Cu")
		(net "M_E_CPU1_SA_CS_N<1>")
	)
	(arc
		(start 79.646018 -252.25502)
		(mid 79.828019 -252.211487)
		(end 80.008222 -252.261878)
		(width 0.0889)
		(layer "In6.Cu")
		(net "M_E_CPU1_SA_CS_N<1>")
	)
	(arc
		(start 81.888076 -252.261878)
		(mid 82.135789 -252.337098)
		(end 82.390996 -252.293628)
		(width 0.0889)
		(layer "In6.Cu")
		(net "M_E_CPU1_SA_CS_N<1>")
	)
	(arc
		(start 80.008222 -252.261878)
		(mid 80.291178 -252.338055)
		(end 80.574134 -252.261878)
		(width 0.0889)
		(layer "In6.Cu")
		(net "M_E_CPU1_SA_CS_N<1>")
	)
	(arc
		(start 80.574134 -252.261878)
		(mid 80.761078 -252.211623)
		(end 80.948022 -252.261878)
		(width 0.0889)
		(layer "In6.Cu")
		(net "M_E_CPU1_SA_CS_N<1>")
	)
	(arc
		(start 78.69428 -252.261878)
		(mid 78.874738 -252.211434)
		(end 79.056992 -252.25502)
		(width 0.0889)
		(layer "In6.Cu")
		(net "M_E_CPU1_SA_CS_N<1>")
	)
	(segment
		(start 81.69783 -252.04039)
		(end 81.230978 -251.774452)
		(width 0.10668)
		(layer "F.Cu")
		(net "M_E_CPU1_SA_CS_N<0>")
	)
	(segment
		(start 77.68463 -251.45746)
		(end 78.223618 -251.45746)
		(width 0.0889)
		(layer "In6.Cu")
		(net "M_E_CPU1_SA_CS_N<0>")
	)
	(segment
		(start 43.248834 -247.91035)
		(end 45.346112 -247.91035)
		(width 0.14478)
		(layer "In6.Cu")
		(net "M_E_CPU1_SA_CS_N<0>")
	)
	(segment
		(start 39.060628 -247.91035)
		(end 41.253156 -247.91035)
		(width 0.14478)
		(layer "In6.Cu")
		(net "M_E_CPU1_SA_CS_N<0>")
	)
	(segment
		(start 81.077054 -251.509022)
		(end 81.230978 -251.774452)
		(width 0.0889)
		(layer "In6.Cu")
		(net "M_E_CPU1_SA_CS_N<0>")
	)
	(segment
		(start 77.063346 -252.078744)
		(end 77.68463 -251.45746)
		(width 0.0889)
		(layer "In6.Cu")
		(net "M_E_CPU1_SA_CS_N<0>")
	)
	(segment
		(start 38.89756 -248.073418)
		(end 39.060628 -247.91035)
		(width 0.14478)
		(layer "In6.Cu")
		(net "M_E_CPU1_SA_CS_N<0>")
	)
	(segment
		(start 75.991466 -252.378464)
		(end 76.291186 -252.078744)
		(width 0.0889)
		(layer "In6.Cu")
		(net "M_E_CPU1_SA_CS_N<0>")
	)
	(segment
		(start 41.416224 -248.133616)
		(end 41.579292 -248.296684)
		(width 0.14478)
		(layer "In6.Cu")
		(net "M_E_CPU1_SA_CS_N<0>")
	)
	(segment
		(start 41.972738 -248.133616)
		(end 41.972738 -248.073418)
		(width 0.14478)
		(layer "In6.Cu")
		(net "M_E_CPU1_SA_CS_N<0>")
	)
	(segment
		(start 59.77001 -247.91035)
		(end 62.922404 -251.062744)
		(width 0.14478)
		(layer "In6.Cu")
		(net "M_E_CPU1_SA_CS_N<0>")
	)
	(segment
		(start 31.377128 -247.91035)
		(end 33.67659 -247.91035)
		(width 0.14478)
		(layer "In6.Cu")
		(net "M_E_CPU1_SA_CS_N<0>")
	)
	(segment
		(start 45.50918 -248.141236)
		(end 45.672248 -248.304304)
		(width 0.14478)
		(layer "In6.Cu")
		(net "M_E_CPU1_SA_CS_N<0>")
	)
	(segment
		(start 43.085766 -248.133616)
		(end 43.085766 -248.073418)
		(width 0.14478)
		(layer "In6.Cu")
		(net "M_E_CPU1_SA_CS_N<0>")
	)
	(segment
		(start 38.341046 -248.141236)
		(end 38.504114 -248.304304)
		(width 0.14478)
		(layer "In6.Cu")
		(net "M_E_CPU1_SA_CS_N<0>")
	)
	(segment
		(start 79.15402 -251.457968)
		(end 79.164434 -251.451872)
		(width 0.0889)
		(layer "In6.Cu")
		(net "M_E_CPU1_SA_CS_N<0>")
	)
	(segment
		(start 46.228762 -247.91035)
		(end 59.77001 -247.91035)
		(width 0.14478)
		(layer "In6.Cu")
		(net "M_E_CPU1_SA_CS_N<0>")
	)
	(segment
		(start 80.981042 -251.483622)
		(end 81.077054 -251.509022)
		(width 0.0889)
		(layer "In6.Cu")
		(net "M_E_CPU1_SA_CS_N<0>")
	)
	(segment
		(start 45.672248 -248.304304)
		(end 45.902626 -248.304304)
		(width 0.14478)
		(layer "In6.Cu")
		(net "M_E_CPU1_SA_CS_N<0>")
	)
	(segment
		(start 46.065694 -248.073418)
		(end 46.228762 -247.91035)
		(width 0.14478)
		(layer "In6.Cu")
		(net "M_E_CPU1_SA_CS_N<0>")
	)
	(segment
		(start 79.538322 -251.451872)
		(end 79.548736 -251.457968)
		(width 0.0889)
		(layer "In6.Cu")
		(net "M_E_CPU1_SA_CS_N<0>")
	)
	(segment
		(start 42.529252 -248.133616)
		(end 42.69232 -248.296684)
		(width 0.14478)
		(layer "In6.Cu")
		(net "M_E_CPU1_SA_CS_N<0>")
	)
	(segment
		(start 33.839658 -248.073418)
		(end 33.839658 -248.141236)
		(width 0.14478)
		(layer "In6.Cu")
		(net "M_E_CPU1_SA_CS_N<0>")
	)
	(segment
		(start 35.346132 -248.304304)
		(end 35.5092 -248.141236)
		(width 0.14478)
		(layer "In6.Cu")
		(net "M_E_CPU1_SA_CS_N<0>")
	)
	(segment
		(start 46.065694 -248.141236)
		(end 46.065694 -248.073418)
		(width 0.14478)
		(layer "In6.Cu")
		(net "M_E_CPU1_SA_CS_N<0>")
	)
	(segment
		(start 62.922404 -251.062744)
		(end 73.230486 -251.062744)
		(width 0.14478)
		(layer "In6.Cu")
		(net "M_E_CPU1_SA_CS_N<0>")
	)
	(segment
		(start 41.579292 -248.296684)
		(end 41.80967 -248.296684)
		(width 0.14478)
		(layer "In6.Cu")
		(net "M_E_CPU1_SA_CS_N<0>")
	)
	(segment
		(start 41.416224 -248.073418)
		(end 41.416224 -248.133616)
		(width 0.14478)
		(layer "In6.Cu")
		(net "M_E_CPU1_SA_CS_N<0>")
	)
	(segment
		(start 41.80967 -248.296684)
		(end 41.972738 -248.133616)
		(width 0.14478)
		(layer "In6.Cu")
		(net "M_E_CPU1_SA_CS_N<0>")
	)
	(segment
		(start 42.366184 -247.91035)
		(end 42.529252 -248.073418)
		(width 0.14478)
		(layer "In6.Cu")
		(net "M_E_CPU1_SA_CS_N<0>")
	)
	(segment
		(start 74.546206 -252.378464)
		(end 75.991466 -252.378464)
		(width 0.14478)
		(layer "In6.Cu")
		(net "M_E_CPU1_SA_CS_N<0>")
	)
	(segment
		(start 33.839658 -248.141236)
		(end 34.002726 -248.304304)
		(width 0.14478)
		(layer "In6.Cu")
		(net "M_E_CPU1_SA_CS_N<0>")
	)
	(segment
		(start 29.252164 -245.785386)
		(end 31.377128 -247.91035)
		(width 0.14478)
		(layer "In6.Cu")
		(net "M_E_CPU1_SA_CS_N<0>")
	)
	(segment
		(start 35.672268 -247.91035)
		(end 38.177978 -247.91035)
		(width 0.14478)
		(layer "In6.Cu")
		(net "M_E_CPU1_SA_CS_N<0>")
	)
	(segment
		(start 38.341046 -248.073418)
		(end 38.341046 -248.141236)
		(width 0.14478)
		(layer "In6.Cu")
		(net "M_E_CPU1_SA_CS_N<0>")
	)
	(segment
		(start 41.253156 -247.91035)
		(end 41.416224 -248.073418)
		(width 0.14478)
		(layer "In6.Cu")
		(net "M_E_CPU1_SA_CS_N<0>")
	)
	(segment
		(start 76.291186 -252.078744)
		(end 77.063346 -252.078744)
		(width 0.0889)
		(layer "In6.Cu")
		(net "M_E_CPU1_SA_CS_N<0>")
	)
	(segment
		(start 38.89756 -248.141236)
		(end 38.89756 -248.073418)
		(width 0.14478)
		(layer "In6.Cu")
		(net "M_E_CPU1_SA_CS_N<0>")
	)
	(segment
		(start 38.177978 -247.91035)
		(end 38.341046 -248.073418)
		(width 0.14478)
		(layer "In6.Cu")
		(net "M_E_CPU1_SA_CS_N<0>")
	)
	(segment
		(start 45.50918 -248.073418)
		(end 45.50918 -248.141236)
		(width 0.14478)
		(layer "In6.Cu")
		(net "M_E_CPU1_SA_CS_N<0>")
	)
	(segment
		(start 33.67659 -247.91035)
		(end 33.839658 -248.073418)
		(width 0.14478)
		(layer "In6.Cu")
		(net "M_E_CPU1_SA_CS_N<0>")
	)
	(segment
		(start 41.972738 -248.073418)
		(end 42.135806 -247.91035)
		(width 0.14478)
		(layer "In6.Cu")
		(net "M_E_CPU1_SA_CS_N<0>")
	)
	(segment
		(start 42.922698 -248.296684)
		(end 43.085766 -248.133616)
		(width 0.14478)
		(layer "In6.Cu")
		(net "M_E_CPU1_SA_CS_N<0>")
	)
	(segment
		(start 35.115754 -248.304304)
		(end 35.346132 -248.304304)
		(width 0.14478)
		(layer "In6.Cu")
		(net "M_E_CPU1_SA_CS_N<0>")
	)
	(segment
		(start 78.223618 -251.45746)
		(end 78.236064 -251.445014)
		(width 0.0889)
		(layer "In6.Cu")
		(net "M_E_CPU1_SA_CS_N<0>")
	)
	(segment
		(start 42.529252 -248.073418)
		(end 42.529252 -248.133616)
		(width 0.14478)
		(layer "In6.Cu")
		(net "M_E_CPU1_SA_CS_N<0>")
	)
	(segment
		(start 73.230486 -251.062744)
		(end 74.546206 -252.378464)
		(width 0.14478)
		(layer "In6.Cu")
		(net "M_E_CPU1_SA_CS_N<0>")
	)
	(segment
		(start 42.69232 -248.296684)
		(end 42.922698 -248.296684)
		(width 0.14478)
		(layer "In6.Cu")
		(net "M_E_CPU1_SA_CS_N<0>")
	)
	(segment
		(start 45.902626 -248.304304)
		(end 46.065694 -248.141236)
		(width 0.14478)
		(layer "In6.Cu")
		(net "M_E_CPU1_SA_CS_N<0>")
	)
	(segment
		(start 34.952686 -248.141236)
		(end 35.115754 -248.304304)
		(width 0.14478)
		(layer "In6.Cu")
		(net "M_E_CPU1_SA_CS_N<0>")
	)
	(segment
		(start 34.002726 -248.304304)
		(end 34.233104 -248.304304)
		(width 0.14478)
		(layer "In6.Cu")
		(net "M_E_CPU1_SA_CS_N<0>")
	)
	(segment
		(start 38.504114 -248.304304)
		(end 38.734492 -248.304304)
		(width 0.14478)
		(layer "In6.Cu")
		(net "M_E_CPU1_SA_CS_N<0>")
	)
	(segment
		(start 35.5092 -248.073418)
		(end 35.672268 -247.91035)
		(width 0.14478)
		(layer "In6.Cu")
		(net "M_E_CPU1_SA_CS_N<0>")
	)
	(segment
		(start 45.346112 -247.91035)
		(end 45.50918 -248.073418)
		(width 0.14478)
		(layer "In6.Cu")
		(net "M_E_CPU1_SA_CS_N<0>")
	)
	(segment
		(start 35.5092 -248.141236)
		(end 35.5092 -248.073418)
		(width 0.14478)
		(layer "In6.Cu")
		(net "M_E_CPU1_SA_CS_N<0>")
	)
	(segment
		(start 42.135806 -247.91035)
		(end 42.366184 -247.91035)
		(width 0.14478)
		(layer "In6.Cu")
		(net "M_E_CPU1_SA_CS_N<0>")
	)
	(segment
		(start 34.233104 -248.304304)
		(end 34.396172 -248.141236)
		(width 0.14478)
		(layer "In6.Cu")
		(net "M_E_CPU1_SA_CS_N<0>")
	)
	(segment
		(start 34.789618 -247.91035)
		(end 34.952686 -248.073418)
		(width 0.14478)
		(layer "In6.Cu")
		(net "M_E_CPU1_SA_CS_N<0>")
	)
	(segment
		(start 38.734492 -248.304304)
		(end 38.89756 -248.141236)
		(width 0.14478)
		(layer "In6.Cu")
		(net "M_E_CPU1_SA_CS_N<0>")
	)
	(segment
		(start 34.396172 -248.073418)
		(end 34.55924 -247.91035)
		(width 0.14478)
		(layer "In6.Cu")
		(net "M_E_CPU1_SA_CS_N<0>")
	)
	(segment
		(start 34.396172 -248.141236)
		(end 34.396172 -248.073418)
		(width 0.14478)
		(layer "In6.Cu")
		(net "M_E_CPU1_SA_CS_N<0>")
	)
	(segment
		(start 80.46974 -251.447046)
		(end 80.478122 -251.451872)
		(width 0.0889)
		(layer "In6.Cu")
		(net "M_E_CPU1_SA_CS_N<0>")
	)
	(segment
		(start 34.952686 -248.073418)
		(end 34.952686 -248.141236)
		(width 0.14478)
		(layer "In6.Cu")
		(net "M_E_CPU1_SA_CS_N<0>")
	)
	(segment
		(start 34.55924 -247.91035)
		(end 34.789618 -247.91035)
		(width 0.14478)
		(layer "In6.Cu")
		(net "M_E_CPU1_SA_CS_N<0>")
	)
	(segment
		(start 43.085766 -248.073418)
		(end 43.248834 -247.91035)
		(width 0.14478)
		(layer "In6.Cu")
		(net "M_E_CPU1_SA_CS_N<0>")
	)
	(arc
		(start 80.10398 -251.451872)
		(mid 80.286231 -251.401522)
		(end 80.46974 -251.447046)
		(width 0.0889)
		(layer "In6.Cu")
		(net "M_E_CPU1_SA_CS_N<0>")
	)
	(arc
		(start 78.236064 -251.445014)
		(mid 78.418065 -251.401481)
		(end 78.598268 -251.451872)
		(width 0.0889)
		(layer "In6.Cu")
		(net "M_E_CPU1_SA_CS_N<0>")
	)
	(arc
		(start 79.164434 -251.451872)
		(mid 79.351378 -251.401617)
		(end 79.538322 -251.451872)
		(width 0.0889)
		(layer "In6.Cu")
		(net "M_E_CPU1_SA_CS_N<0>")
	)
	(arc
		(start 78.598268 -251.451872)
		(mid 78.875335 -251.528143)
		(end 79.15402 -251.457968)
		(width 0.0889)
		(layer "In6.Cu")
		(net "M_E_CPU1_SA_CS_N<0>")
	)
	(arc
		(start 79.548736 -251.457968)
		(mid 79.827168 -251.528066)
		(end 80.10398 -251.451872)
		(width 0.0889)
		(layer "In6.Cu")
		(net "M_E_CPU1_SA_CS_N<0>")
	)
	(arc
		(start 80.478122 -251.451872)
		(mid 80.725835 -251.527092)
		(end 80.981042 -251.483622)
		(width 0.0889)
		(layer "In6.Cu")
		(net "M_E_CPU1_SA_CS_N<0>")
	)
	(segment
		(start 83.107784 -249.610372)
		(end 82.640932 -249.344434)
		(width 0.10668)
		(layer "F.Cu")
		(net "M_E_CPU1_SA_CB<7>")
	)
	(segment
		(start 74.848466 -249.968004)
		(end 76.248006 -249.968004)
		(width 0.14478)
		(layer "In6.Cu")
		(net "M_E_CPU1_SA_CB<7>")
	)
	(segment
		(start 82.487008 -249.079004)
		(end 82.640932 -249.344434)
		(width 0.0889)
		(layer "In6.Cu")
		(net "M_E_CPU1_SA_CB<7>")
	)
	(segment
		(start 35.02406 -245.360444)
		(end 59.941714 -245.360444)
		(width 0.14478)
		(layer "In6.Cu")
		(net "M_E_CPU1_SA_CB<7>")
	)
	(segment
		(start 81.879694 -249.017028)
		(end 81.888076 -249.021854)
		(width 0.0889)
		(layer "In6.Cu")
		(net "M_E_CPU1_SA_CB<7>")
	)
	(segment
		(start 27.065478 -244.049296)
		(end 27.228546 -244.212364)
		(width 0.14478)
		(layer "In6.Cu")
		(net "M_E_CPU1_SA_CB<7>")
	)
	(segment
		(start 27.621992 -244.049296)
		(end 27.621992 -242.937792)
		(width 0.14478)
		(layer "In6.Cu")
		(net "M_E_CPU1_SA_CB<7>")
	)
	(segment
		(start 79.056992 -249.014996)
		(end 79.068676 -249.021854)
		(width 0.0889)
		(layer "In6.Cu")
		(net "M_E_CPU1_SA_CB<7>")
	)
	(segment
		(start 33.324038 -243.660422)
		(end 35.02406 -245.360444)
		(width 0.14478)
		(layer "In6.Cu")
		(net "M_E_CPU1_SA_CB<7>")
	)
	(segment
		(start 27.065478 -243.123212)
		(end 27.065478 -244.049296)
		(width 0.14478)
		(layer "In6.Cu")
		(net "M_E_CPU1_SA_CB<7>")
	)
	(segment
		(start 28.015438 -242.774724)
		(end 28.178506 -242.937792)
		(width 0.14478)
		(layer "In6.Cu")
		(net "M_E_CPU1_SA_CB<7>")
	)
	(segment
		(start 27.621992 -242.937792)
		(end 27.78506 -242.774724)
		(width 0.14478)
		(layer "In6.Cu")
		(net "M_E_CPU1_SA_CB<7>")
	)
	(segment
		(start 25.152096 -243.235226)
		(end 26.39695 -243.235226)
		(width 0.14478)
		(layer "In6.Cu")
		(net "M_E_CPU1_SA_CB<7>")
	)
	(segment
		(start 28.178506 -243.497354)
		(end 28.341574 -243.660422)
		(width 0.14478)
		(layer "In6.Cu")
		(net "M_E_CPU1_SA_CB<7>")
	)
	(segment
		(start 79.62392 -249.02795)
		(end 79.634334 -249.021854)
		(width 0.0889)
		(layer "In6.Cu")
		(net "M_E_CPU1_SA_CB<7>")
	)
	(segment
		(start 77.75702 -249.968004)
		(end 78.69428 -249.021854)
		(width 0.0889)
		(layer "In6.Cu")
		(net "M_E_CPU1_SA_CB<7>")
	)
	(segment
		(start 26.39695 -243.235226)
		(end 26.672032 -242.960144)
		(width 0.14478)
		(layer "In6.Cu")
		(net "M_E_CPU1_SA_CB<7>")
	)
	(segment
		(start 59.941714 -245.360444)
		(end 63.726314 -249.145044)
		(width 0.14478)
		(layer "In6.Cu")
		(net "M_E_CPU1_SA_CB<7>")
	)
	(segment
		(start 26.90241 -242.960144)
		(end 27.065478 -243.123212)
		(width 0.14478)
		(layer "In6.Cu")
		(net "M_E_CPU1_SA_CB<7>")
	)
	(segment
		(start 76.248006 -249.968004)
		(end 77.75702 -249.968004)
		(width 0.0889)
		(layer "In6.Cu")
		(net "M_E_CPU1_SA_CB<7>")
	)
	(segment
		(start 79.634334 -249.021854)
		(end 79.646018 -249.014996)
		(width 0.0889)
		(layer "In6.Cu")
		(net "M_E_CPU1_SA_CB<7>")
	)
	(segment
		(start 74.025506 -249.145044)
		(end 74.848466 -249.968004)
		(width 0.14478)
		(layer "In6.Cu")
		(net "M_E_CPU1_SA_CB<7>")
	)
	(segment
		(start 26.672032 -242.960144)
		(end 26.90241 -242.960144)
		(width 0.14478)
		(layer "In6.Cu")
		(net "M_E_CPU1_SA_CB<7>")
	)
	(segment
		(start 28.178506 -242.937792)
		(end 28.178506 -243.497354)
		(width 0.14478)
		(layer "In6.Cu")
		(net "M_E_CPU1_SA_CB<7>")
	)
	(segment
		(start 82.390996 -249.053604)
		(end 82.487008 -249.079004)
		(width 0.0889)
		(layer "In6.Cu")
		(net "M_E_CPU1_SA_CB<7>")
	)
	(segment
		(start 27.458924 -244.212364)
		(end 27.621992 -244.049296)
		(width 0.14478)
		(layer "In6.Cu")
		(net "M_E_CPU1_SA_CB<7>")
	)
	(segment
		(start 27.228546 -244.212364)
		(end 27.458924 -244.212364)
		(width 0.14478)
		(layer "In6.Cu")
		(net "M_E_CPU1_SA_CB<7>")
	)
	(segment
		(start 28.341574 -243.660422)
		(end 33.324038 -243.660422)
		(width 0.14478)
		(layer "In6.Cu")
		(net "M_E_CPU1_SA_CB<7>")
	)
	(segment
		(start 27.78506 -242.774724)
		(end 28.015438 -242.774724)
		(width 0.14478)
		(layer "In6.Cu")
		(net "M_E_CPU1_SA_CB<7>")
	)
	(segment
		(start 63.726314 -249.145044)
		(end 74.025506 -249.145044)
		(width 0.14478)
		(layer "In6.Cu")
		(net "M_E_CPU1_SA_CB<7>")
	)
	(arc
		(start 81.888076 -249.021854)
		(mid 82.135789 -249.097074)
		(end 82.390996 -249.053604)
		(width 0.0889)
		(layer "In6.Cu")
		(net "M_E_CPU1_SA_CB<7>")
	)
	(arc
		(start 80.008222 -249.021854)
		(mid 80.291178 -249.098031)
		(end 80.574134 -249.021854)
		(width 0.0889)
		(layer "In6.Cu")
		(net "M_E_CPU1_SA_CB<7>")
	)
	(arc
		(start 80.948022 -249.021854)
		(mid 81.230978 -249.098031)
		(end 81.513934 -249.021854)
		(width 0.0889)
		(layer "In6.Cu")
		(net "M_E_CPU1_SA_CB<7>")
	)
	(arc
		(start 81.513934 -249.021854)
		(mid 81.696185 -248.971504)
		(end 81.879694 -249.017028)
		(width 0.0889)
		(layer "In6.Cu")
		(net "M_E_CPU1_SA_CB<7>")
	)
	(arc
		(start 78.69428 -249.021854)
		(mid 78.874738 -248.97141)
		(end 79.056992 -249.014996)
		(width 0.0889)
		(layer "In6.Cu")
		(net "M_E_CPU1_SA_CB<7>")
	)
	(arc
		(start 80.574134 -249.021854)
		(mid 80.761078 -248.971599)
		(end 80.948022 -249.021854)
		(width 0.0889)
		(layer "In6.Cu")
		(net "M_E_CPU1_SA_CB<7>")
	)
	(arc
		(start 79.646018 -249.014996)
		(mid 79.828019 -248.971463)
		(end 80.008222 -249.021854)
		(width 0.0889)
		(layer "In6.Cu")
		(net "M_E_CPU1_SA_CB<7>")
	)
	(arc
		(start 79.068676 -249.021854)
		(mid 79.345489 -249.097997)
		(end 79.62392 -249.02795)
		(width 0.0889)
		(layer "In6.Cu")
		(net "M_E_CPU1_SA_CB<7>")
	)
	(segment
		(start 81.69783 -248.800366)
		(end 81.230978 -248.534428)
		(width 0.10668)
		(layer "F.Cu")
		(net "M_E_CPU1_SA_CB<6>")
	)
	(segment
		(start 42.632884 -242.123468)
		(end 42.632884 -242.466876)
		(width 0.14478)
		(layer "In6.Cu")
		(net "M_E_CPU1_SA_CB<6>")
	)
	(segment
		(start 77.635608 -248.80062)
		(end 78.22438 -248.211848)
		(width 0.0889)
		(layer "In6.Cu")
		(net "M_E_CPU1_SA_CB<6>")
	)
	(segment
		(start 81.077054 -248.268998)
		(end 81.230978 -248.534428)
		(width 0.0889)
		(layer "In6.Cu")
		(net "M_E_CPU1_SA_CB<6>")
	)
	(segment
		(start 46.387004 -243.660168)
		(end 59.689746 -243.660168)
		(width 0.14478)
		(layer "In6.Cu")
		(net "M_E_CPU1_SA_CB<6>")
	)
	(segment
		(start 41.682924 -242.629944)
		(end 41.913302 -242.629944)
		(width 0.14478)
		(layer "In6.Cu")
		(net "M_E_CPU1_SA_CB<6>")
	)
	(segment
		(start 43.189398 -242.123468)
		(end 43.352466 -241.9604)
		(width 0.14478)
		(layer "In6.Cu")
		(net "M_E_CPU1_SA_CB<6>")
	)
	(segment
		(start 43.02633 -242.629944)
		(end 43.189398 -242.466876)
		(width 0.14478)
		(layer "In6.Cu")
		(net "M_E_CPU1_SA_CB<6>")
	)
	(segment
		(start 80.46974 -248.207022)
		(end 80.478122 -248.211848)
		(width 0.0889)
		(layer "In6.Cu")
		(net "M_E_CPU1_SA_CB<6>")
	)
	(segment
		(start 38.375844 -241.9604)
		(end 41.356788 -241.9604)
		(width 0.14478)
		(layer "In6.Cu")
		(net "M_E_CPU1_SA_CB<6>")
	)
	(segment
		(start 43.352466 -241.9604)
		(end 44.687236 -241.9604)
		(width 0.14478)
		(layer "In6.Cu")
		(net "M_E_CPU1_SA_CB<6>")
	)
	(segment
		(start 42.632884 -242.466876)
		(end 42.795952 -242.629944)
		(width 0.14478)
		(layer "In6.Cu")
		(net "M_E_CPU1_SA_CB<6>")
	)
	(segment
		(start 38.212776 -242.123468)
		(end 38.375844 -241.9604)
		(width 0.14478)
		(layer "In6.Cu")
		(net "M_E_CPU1_SA_CB<6>")
	)
	(segment
		(start 25.152096 -241.535204)
		(end 25.577292 -241.9604)
		(width 0.14478)
		(layer "In6.Cu")
		(net "M_E_CPU1_SA_CB<6>")
	)
	(segment
		(start 64.265302 -248.235724)
		(end 74.402442 -248.235724)
		(width 0.14478)
		(layer "In6.Cu")
		(net "M_E_CPU1_SA_CB<6>")
	)
	(segment
		(start 41.356788 -241.9604)
		(end 41.519856 -242.123468)
		(width 0.14478)
		(layer "In6.Cu")
		(net "M_E_CPU1_SA_CB<6>")
	)
	(segment
		(start 79.15402 -248.217944)
		(end 79.164434 -248.211848)
		(width 0.0889)
		(layer "In6.Cu")
		(net "M_E_CPU1_SA_CB<6>")
	)
	(segment
		(start 38.212776 -243.039138)
		(end 38.212776 -242.123468)
		(width 0.14478)
		(layer "In6.Cu")
		(net "M_E_CPU1_SA_CB<6>")
	)
	(segment
		(start 41.913302 -242.629944)
		(end 42.07637 -242.466876)
		(width 0.14478)
		(layer "In6.Cu")
		(net "M_E_CPU1_SA_CB<6>")
	)
	(segment
		(start 41.519856 -242.123468)
		(end 41.519856 -242.466876)
		(width 0.14478)
		(layer "In6.Cu")
		(net "M_E_CPU1_SA_CB<6>")
	)
	(segment
		(start 37.656262 -243.039138)
		(end 37.81933 -243.202206)
		(width 0.14478)
		(layer "In6.Cu")
		(net "M_E_CPU1_SA_CB<6>")
	)
	(segment
		(start 37.81933 -243.202206)
		(end 38.049708 -243.202206)
		(width 0.14478)
		(layer "In6.Cu")
		(net "M_E_CPU1_SA_CB<6>")
	)
	(segment
		(start 80.981042 -248.243598)
		(end 81.077054 -248.268998)
		(width 0.0889)
		(layer "In6.Cu")
		(net "M_E_CPU1_SA_CB<6>")
	)
	(segment
		(start 74.402442 -248.235724)
		(end 74.967338 -248.80062)
		(width 0.14478)
		(layer "In6.Cu")
		(net "M_E_CPU1_SA_CB<6>")
	)
	(segment
		(start 42.239438 -241.9604)
		(end 42.469816 -241.9604)
		(width 0.14478)
		(layer "In6.Cu")
		(net "M_E_CPU1_SA_CB<6>")
	)
	(segment
		(start 37.656262 -242.123468)
		(end 37.656262 -243.039138)
		(width 0.14478)
		(layer "In6.Cu")
		(net "M_E_CPU1_SA_CB<6>")
	)
	(segment
		(start 42.795952 -242.629944)
		(end 43.02633 -242.629944)
		(width 0.14478)
		(layer "In6.Cu")
		(net "M_E_CPU1_SA_CB<6>")
	)
	(segment
		(start 59.689746 -243.660168)
		(end 64.265302 -248.235724)
		(width 0.14478)
		(layer "In6.Cu")
		(net "M_E_CPU1_SA_CB<6>")
	)
	(segment
		(start 76.011786 -248.80062)
		(end 77.635608 -248.80062)
		(width 0.0889)
		(layer "In6.Cu")
		(net "M_E_CPU1_SA_CB<6>")
	)
	(segment
		(start 25.577292 -241.9604)
		(end 37.493194 -241.9604)
		(width 0.14478)
		(layer "In6.Cu")
		(net "M_E_CPU1_SA_CB<6>")
	)
	(segment
		(start 37.493194 -241.9604)
		(end 37.656262 -242.123468)
		(width 0.14478)
		(layer "In6.Cu")
		(net "M_E_CPU1_SA_CB<6>")
	)
	(segment
		(start 42.07637 -242.123468)
		(end 42.239438 -241.9604)
		(width 0.14478)
		(layer "In6.Cu")
		(net "M_E_CPU1_SA_CB<6>")
	)
	(segment
		(start 41.519856 -242.466876)
		(end 41.682924 -242.629944)
		(width 0.14478)
		(layer "In6.Cu")
		(net "M_E_CPU1_SA_CB<6>")
	)
	(segment
		(start 44.687236 -241.9604)
		(end 46.387004 -243.660168)
		(width 0.14478)
		(layer "In6.Cu")
		(net "M_E_CPU1_SA_CB<6>")
	)
	(segment
		(start 78.22438 -248.211848)
		(end 78.236064 -248.20499)
		(width 0.0889)
		(layer "In6.Cu")
		(net "M_E_CPU1_SA_CB<6>")
	)
	(segment
		(start 38.049708 -243.202206)
		(end 38.212776 -243.039138)
		(width 0.14478)
		(layer "In6.Cu")
		(net "M_E_CPU1_SA_CB<6>")
	)
	(segment
		(start 42.07637 -242.466876)
		(end 42.07637 -242.123468)
		(width 0.14478)
		(layer "In6.Cu")
		(net "M_E_CPU1_SA_CB<6>")
	)
	(segment
		(start 43.189398 -242.466876)
		(end 43.189398 -242.123468)
		(width 0.14478)
		(layer "In6.Cu")
		(net "M_E_CPU1_SA_CB<6>")
	)
	(segment
		(start 42.469816 -241.9604)
		(end 42.632884 -242.123468)
		(width 0.14478)
		(layer "In6.Cu")
		(net "M_E_CPU1_SA_CB<6>")
	)
	(segment
		(start 79.538322 -248.211848)
		(end 79.548736 -248.217944)
		(width 0.0889)
		(layer "In6.Cu")
		(net "M_E_CPU1_SA_CB<6>")
	)
	(segment
		(start 74.967338 -248.80062)
		(end 76.011786 -248.80062)
		(width 0.14478)
		(layer "In6.Cu")
		(net "M_E_CPU1_SA_CB<6>")
	)
	(arc
		(start 80.10398 -248.211848)
		(mid 80.286231 -248.161498)
		(end 80.46974 -248.207022)
		(width 0.0889)
		(layer "In6.Cu")
		(net "M_E_CPU1_SA_CB<6>")
	)
	(arc
		(start 78.236064 -248.20499)
		(mid 78.418065 -248.161457)
		(end 78.598268 -248.211848)
		(width 0.0889)
		(layer "In6.Cu")
		(net "M_E_CPU1_SA_CB<6>")
	)
	(arc
		(start 78.598268 -248.211848)
		(mid 78.875335 -248.288119)
		(end 79.15402 -248.217944)
		(width 0.0889)
		(layer "In6.Cu")
		(net "M_E_CPU1_SA_CB<6>")
	)
	(arc
		(start 79.164434 -248.211848)
		(mid 79.351378 -248.161593)
		(end 79.538322 -248.211848)
		(width 0.0889)
		(layer "In6.Cu")
		(net "M_E_CPU1_SA_CB<6>")
	)
	(arc
		(start 80.478122 -248.211848)
		(mid 80.725835 -248.287068)
		(end 80.981042 -248.243598)
		(width 0.0889)
		(layer "In6.Cu")
		(net "M_E_CPU1_SA_CB<6>")
	)
	(arc
		(start 79.548736 -248.217944)
		(mid 79.827168 -248.288042)
		(end 80.10398 -248.211848)
		(width 0.0889)
		(layer "In6.Cu")
		(net "M_E_CPU1_SA_CB<6>")
	)
	(segment
		(start 82.637884 -248.800366)
		(end 82.171032 -248.534428)
		(width 0.10668)
		(layer "F.Cu")
		(net "M_E_CPU1_SA_CB<5>")
	)
	(segment
		(start 42.061892 -243.623592)
		(end 42.22496 -243.460524)
		(width 0.14478)
		(layer "In6.Cu")
		(net "M_E_CPU1_SA_CB<5>")
	)
	(segment
		(start 82.302604 -248.88317)
		(end 82.324956 -248.799858)
		(width 0.0889)
		(layer "In6.Cu")
		(net "M_E_CPU1_SA_CB<5>")
	)
	(segment
		(start 42.781474 -244.510306)
		(end 43.011852 -244.510306)
		(width 0.14478)
		(layer "In6.Cu")
		(net "M_E_CPU1_SA_CB<5>")
	)
	(segment
		(start 43.731434 -244.347238)
		(end 43.894502 -244.510306)
		(width 0.14478)
		(layer "In6.Cu")
		(net "M_E_CPU1_SA_CB<5>")
	)
	(segment
		(start 39.05504 -244.347238)
		(end 39.05504 -243.492274)
		(width 0.14478)
		(layer "In6.Cu")
		(net "M_E_CPU1_SA_CB<5>")
	)
	(segment
		(start 79.538322 -248.857008)
		(end 79.548736 -248.850912)
		(width 0.0889)
		(layer "In6.Cu")
		(net "M_E_CPU1_SA_CB<5>")
	)
	(segment
		(start 43.568366 -243.460524)
		(end 43.731434 -243.623592)
		(width 0.14478)
		(layer "In6.Cu")
		(net "M_E_CPU1_SA_CB<5>")
	)
	(segment
		(start 34.10966 -242.810284)
		(end 35.809682 -244.510306)
		(width 0.14478)
		(layer "In6.Cu")
		(net "M_E_CPU1_SA_CB<5>")
	)
	(segment
		(start 42.618406 -244.347238)
		(end 42.781474 -244.510306)
		(width 0.14478)
		(layer "In6.Cu")
		(net "M_E_CPU1_SA_CB<5>")
	)
	(segment
		(start 76.557886 -249.254264)
		(end 77.902054 -249.254264)
		(width 0.0889)
		(layer "In6.Cu")
		(net "M_E_CPU1_SA_CB<5>")
	)
	(segment
		(start 76.496926 -249.315224)
		(end 76.557886 -249.254264)
		(width 0.0889)
		(layer "In6.Cu")
		(net "M_E_CPU1_SA_CB<5>")
	)
	(segment
		(start 75.940666 -249.315224)
		(end 76.496926 -249.315224)
		(width 0.0889)
		(layer "In6.Cu")
		(net "M_E_CPU1_SA_CB<5>")
	)
	(segment
		(start 74.213974 -248.690384)
		(end 74.838814 -249.315224)
		(width 0.14478)
		(layer "In6.Cu")
		(net "M_E_CPU1_SA_CB<5>")
	)
	(segment
		(start 41.111932 -243.460524)
		(end 41.34231 -243.460524)
		(width 0.14478)
		(layer "In6.Cu")
		(net "M_E_CPU1_SA_CB<5>")
	)
	(segment
		(start 29.677106 -242.810284)
		(end 34.10966 -242.810284)
		(width 0.14478)
		(layer "In6.Cu")
		(net "M_E_CPU1_SA_CB<5>")
	)
	(segment
		(start 39.774622 -244.510306)
		(end 40.785796 -244.510306)
		(width 0.14478)
		(layer "In6.Cu")
		(net "M_E_CPU1_SA_CB<5>")
	)
	(segment
		(start 41.505378 -243.623592)
		(end 41.505378 -244.347238)
		(width 0.14478)
		(layer "In6.Cu")
		(net "M_E_CPU1_SA_CB<5>")
	)
	(segment
		(start 81.044034 -248.857008)
		(end 81.052416 -248.861834)
		(width 0.0889)
		(layer "In6.Cu")
		(net "M_E_CPU1_SA_CB<5>")
	)
	(segment
		(start 41.34231 -243.460524)
		(end 41.505378 -243.623592)
		(width 0.14478)
		(layer "In6.Cu")
		(net "M_E_CPU1_SA_CB<5>")
	)
	(segment
		(start 43.17492 -244.347238)
		(end 43.17492 -243.623592)
		(width 0.14478)
		(layer "In6.Cu")
		(net "M_E_CPU1_SA_CB<5>")
	)
	(segment
		(start 41.668446 -244.510306)
		(end 41.898824 -244.510306)
		(width 0.14478)
		(layer "In6.Cu")
		(net "M_E_CPU1_SA_CB<5>")
	)
	(segment
		(start 79.154274 -248.850912)
		(end 79.164688 -248.857008)
		(width 0.0889)
		(layer "In6.Cu")
		(net "M_E_CPU1_SA_CB<5>")
	)
	(segment
		(start 41.898824 -244.510306)
		(end 42.061892 -244.347238)
		(width 0.14478)
		(layer "In6.Cu")
		(net "M_E_CPU1_SA_CB<5>")
	)
	(segment
		(start 40.948864 -243.623592)
		(end 41.111932 -243.460524)
		(width 0.14478)
		(layer "In6.Cu")
		(net "M_E_CPU1_SA_CB<5>")
	)
	(segment
		(start 39.611554 -243.492274)
		(end 39.611554 -244.347238)
		(width 0.14478)
		(layer "In6.Cu")
		(net "M_E_CPU1_SA_CB<5>")
	)
	(segment
		(start 38.891972 -244.510306)
		(end 39.05504 -244.347238)
		(width 0.14478)
		(layer "In6.Cu")
		(net "M_E_CPU1_SA_CB<5>")
	)
	(segment
		(start 43.337988 -243.460524)
		(end 43.568366 -243.460524)
		(width 0.14478)
		(layer "In6.Cu")
		(net "M_E_CPU1_SA_CB<5>")
	)
	(segment
		(start 59.800744 -244.510306)
		(end 63.980822 -248.690384)
		(width 0.14478)
		(layer "In6.Cu")
		(net "M_E_CPU1_SA_CB<5>")
	)
	(segment
		(start 43.731434 -243.623592)
		(end 43.731434 -244.347238)
		(width 0.14478)
		(layer "In6.Cu")
		(net "M_E_CPU1_SA_CB<5>")
	)
	(segment
		(start 39.448486 -243.329206)
		(end 39.611554 -243.492274)
		(width 0.14478)
		(layer "In6.Cu")
		(net "M_E_CPU1_SA_CB<5>")
	)
	(segment
		(start 42.618406 -243.623592)
		(end 42.618406 -244.347238)
		(width 0.14478)
		(layer "In6.Cu")
		(net "M_E_CPU1_SA_CB<5>")
	)
	(segment
		(start 39.218108 -243.329206)
		(end 39.448486 -243.329206)
		(width 0.14478)
		(layer "In6.Cu")
		(net "M_E_CPU1_SA_CB<5>")
	)
	(segment
		(start 79.52994 -248.861834)
		(end 79.538322 -248.857008)
		(width 0.0889)
		(layer "In6.Cu")
		(net "M_E_CPU1_SA_CB<5>")
	)
	(segment
		(start 43.894502 -244.510306)
		(end 59.800744 -244.510306)
		(width 0.14478)
		(layer "In6.Cu")
		(net "M_E_CPU1_SA_CB<5>")
	)
	(segment
		(start 43.011852 -244.510306)
		(end 43.17492 -244.347238)
		(width 0.14478)
		(layer "In6.Cu")
		(net "M_E_CPU1_SA_CB<5>")
	)
	(segment
		(start 39.611554 -244.347238)
		(end 39.774622 -244.510306)
		(width 0.14478)
		(layer "In6.Cu")
		(net "M_E_CPU1_SA_CB<5>")
	)
	(segment
		(start 41.505378 -244.347238)
		(end 41.668446 -244.510306)
		(width 0.14478)
		(layer "In6.Cu")
		(net "M_E_CPU1_SA_CB<5>")
	)
	(segment
		(start 80.46974 -248.861834)
		(end 80.478122 -248.857008)
		(width 0.0889)
		(layer "In6.Cu")
		(net "M_E_CPU1_SA_CB<5>")
	)
	(segment
		(start 42.22496 -243.460524)
		(end 42.455338 -243.460524)
		(width 0.14478)
		(layer "In6.Cu")
		(net "M_E_CPU1_SA_CB<5>")
	)
	(segment
		(start 29.252164 -242.385342)
		(end 29.677106 -242.810284)
		(width 0.14478)
		(layer "In6.Cu")
		(net "M_E_CPU1_SA_CB<5>")
	)
	(segment
		(start 77.902054 -249.254264)
		(end 78.598522 -248.857008)
		(width 0.0889)
		(layer "In6.Cu")
		(net "M_E_CPU1_SA_CB<5>")
	)
	(segment
		(start 82.324956 -248.799858)
		(end 82.171032 -248.534428)
		(width 0.0889)
		(layer "In6.Cu")
		(net "M_E_CPU1_SA_CB<5>")
	)
	(segment
		(start 39.05504 -243.492274)
		(end 39.218108 -243.329206)
		(width 0.14478)
		(layer "In6.Cu")
		(net "M_E_CPU1_SA_CB<5>")
	)
	(segment
		(start 40.948864 -244.347238)
		(end 40.948864 -243.623592)
		(width 0.14478)
		(layer "In6.Cu")
		(net "M_E_CPU1_SA_CB<5>")
	)
	(segment
		(start 42.455338 -243.460524)
		(end 42.618406 -243.623592)
		(width 0.14478)
		(layer "In6.Cu")
		(net "M_E_CPU1_SA_CB<5>")
	)
	(segment
		(start 43.17492 -243.623592)
		(end 43.337988 -243.460524)
		(width 0.14478)
		(layer "In6.Cu")
		(net "M_E_CPU1_SA_CB<5>")
	)
	(segment
		(start 40.785796 -244.510306)
		(end 40.948864 -244.347238)
		(width 0.14478)
		(layer "In6.Cu")
		(net "M_E_CPU1_SA_CB<5>")
	)
	(segment
		(start 74.838814 -249.315224)
		(end 75.940666 -249.315224)
		(width 0.14478)
		(layer "In6.Cu")
		(net "M_E_CPU1_SA_CB<5>")
	)
	(segment
		(start 35.809682 -244.510306)
		(end 38.891972 -244.510306)
		(width 0.14478)
		(layer "In6.Cu")
		(net "M_E_CPU1_SA_CB<5>")
	)
	(segment
		(start 42.061892 -244.347238)
		(end 42.061892 -243.623592)
		(width 0.14478)
		(layer "In6.Cu")
		(net "M_E_CPU1_SA_CB<5>")
	)
	(segment
		(start 63.980822 -248.690384)
		(end 74.213974 -248.690384)
		(width 0.14478)
		(layer "In6.Cu")
		(net "M_E_CPU1_SA_CB<5>")
	)
	(arc
		(start 80.478122 -248.857008)
		(mid 80.761078 -248.780831)
		(end 81.044034 -248.857008)
		(width 0.0889)
		(layer "In6.Cu")
		(net "M_E_CPU1_SA_CB<5>")
	)
	(arc
		(start 81.052416 -248.861834)
		(mid 81.235924 -248.907328)
		(end 81.418176 -248.857008)
		(width 0.0889)
		(layer "In6.Cu")
		(net "M_E_CPU1_SA_CB<5>")
	)
	(arc
		(start 80.10398 -248.857008)
		(mid 80.286231 -248.907358)
		(end 80.46974 -248.861834)
		(width 0.0889)
		(layer "In6.Cu")
		(net "M_E_CPU1_SA_CB<5>")
	)
	(arc
		(start 79.164688 -248.857008)
		(mid 79.346685 -248.90723)
		(end 79.52994 -248.861834)
		(width 0.0889)
		(layer "In6.Cu")
		(net "M_E_CPU1_SA_CB<5>")
	)
	(arc
		(start 78.598522 -248.857008)
		(mid 78.875589 -248.780737)
		(end 79.154274 -248.850912)
		(width 0.0889)
		(layer "In6.Cu")
		(net "M_E_CPU1_SA_CB<5>")
	)
	(arc
		(start 81.418176 -248.857008)
		(mid 81.701132 -248.780831)
		(end 81.984088 -248.857008)
		(width 0.0889)
		(layer "In6.Cu")
		(net "M_E_CPU1_SA_CB<5>")
	)
	(arc
		(start 81.984088 -248.857008)
		(mid 82.140407 -248.906003)
		(end 82.302604 -248.88317)
		(width 0.0889)
		(layer "In6.Cu")
		(net "M_E_CPU1_SA_CB<5>")
	)
	(arc
		(start 79.548736 -248.850912)
		(mid 79.827168 -248.780814)
		(end 80.10398 -248.857008)
		(width 0.0889)
		(layer "In6.Cu")
		(net "M_E_CPU1_SA_CB<5>")
	)
	(segment
		(start 81.22793 -247.99036)
		(end 80.761078 -247.724422)
		(width 0.10668)
		(layer "F.Cu")
		(net "M_E_CPU1_SA_CB<4>")
	)
	(segment
		(start 46.919642 -242.460018)
		(end 46.919642 -241.27333)
		(width 0.14478)
		(layer "In6.Cu")
		(net "M_E_CPU1_SA_CB<4>")
	)
	(segment
		(start 49.04867 -242.205764)
		(end 49.211738 -242.042696)
		(width 0.14478)
		(layer "In6.Cu")
		(net "M_E_CPU1_SA_CB<4>")
	)
	(segment
		(start 76.029566 -248.34596)
		(end 76.0349 -248.340626)
		(width 0.0889)
		(layer "In6.Cu")
		(net "M_E_CPU1_SA_CB<4>")
	)
	(segment
		(start 46.526196 -242.623086)
		(end 46.756574 -242.623086)
		(width 0.14478)
		(layer "In6.Cu")
		(net "M_E_CPU1_SA_CB<4>")
	)
	(segment
		(start 47.073058 -241.119914)
		(end 48.501808 -241.119914)
		(width 0.14478)
		(layer "In6.Cu")
		(net "M_E_CPU1_SA_CB<4>")
	)
	(segment
		(start 50.88128 -242.042696)
		(end 51.044348 -242.205764)
		(width 0.14478)
		(layer "In6.Cu")
		(net "M_E_CPU1_SA_CB<4>")
	)
	(segment
		(start 56.388508 -242.810284)
		(end 59.982862 -242.810284)
		(width 0.14478)
		(layer "In6.Cu")
		(net "M_E_CPU1_SA_CB<4>")
	)
	(segment
		(start 51.274726 -242.205764)
		(end 51.437794 -242.042696)
		(width 0.14478)
		(layer "In6.Cu")
		(net "M_E_CPU1_SA_CB<4>")
	)
	(segment
		(start 76.0349 -248.340626)
		(end 77.658976 -248.340626)
		(width 0.0889)
		(layer "In6.Cu")
		(net "M_E_CPU1_SA_CB<4>")
	)
	(segment
		(start 48.655224 -241.27333)
		(end 48.655224 -242.042696)
		(width 0.14478)
		(layer "In6.Cu")
		(net "M_E_CPU1_SA_CB<4>")
	)
	(segment
		(start 50.324766 -241.27333)
		(end 50.487834 -241.110262)
		(width 0.14478)
		(layer "In6.Cu")
		(net "M_E_CPU1_SA_CB<4>")
	)
	(segment
		(start 46.756574 -242.623086)
		(end 46.919642 -242.460018)
		(width 0.14478)
		(layer "In6.Cu")
		(net "M_E_CPU1_SA_CB<4>")
	)
	(segment
		(start 50.324766 -242.042696)
		(end 50.324766 -241.27333)
		(width 0.14478)
		(layer "In6.Cu")
		(net "M_E_CPU1_SA_CB<4>")
	)
	(segment
		(start 64.953642 -247.781064)
		(end 74.59091 -247.781064)
		(width 0.14478)
		(layer "In6.Cu")
		(net "M_E_CPU1_SA_CB<4>")
	)
	(segment
		(start 79.63408 -248.047002)
		(end 79.642462 -248.051828)
		(width 0.0889)
		(layer "In6.Cu")
		(net "M_E_CPU1_SA_CB<4>")
	)
	(segment
		(start 50.161698 -242.205764)
		(end 50.324766 -242.042696)
		(width 0.14478)
		(layer "In6.Cu")
		(net "M_E_CPU1_SA_CB<4>")
	)
	(segment
		(start 46.363128 -242.460018)
		(end 46.526196 -242.623086)
		(width 0.14478)
		(layer "In6.Cu")
		(net "M_E_CPU1_SA_CB<4>")
	)
	(segment
		(start 29.252164 -240.68532)
		(end 29.686758 -241.119914)
		(width 0.14478)
		(layer "In6.Cu")
		(net "M_E_CPU1_SA_CB<4>")
	)
	(segment
		(start 48.818292 -242.205764)
		(end 49.04867 -242.205764)
		(width 0.14478)
		(layer "In6.Cu")
		(net "M_E_CPU1_SA_CB<4>")
	)
	(segment
		(start 77.70368 -248.295922)
		(end 78.1431 -248.038366)
		(width 0.0889)
		(layer "In6.Cu")
		(net "M_E_CPU1_SA_CB<4>")
	)
	(segment
		(start 51.044348 -242.205764)
		(end 51.274726 -242.205764)
		(width 0.14478)
		(layer "In6.Cu")
		(net "M_E_CPU1_SA_CB<4>")
	)
	(segment
		(start 48.655224 -242.042696)
		(end 48.818292 -242.205764)
		(width 0.14478)
		(layer "In6.Cu")
		(net "M_E_CPU1_SA_CB<4>")
	)
	(segment
		(start 49.211738 -241.27333)
		(end 49.374806 -241.110262)
		(width 0.14478)
		(layer "In6.Cu")
		(net "M_E_CPU1_SA_CB<4>")
	)
	(segment
		(start 49.768252 -242.042696)
		(end 49.93132 -242.205764)
		(width 0.14478)
		(layer "In6.Cu")
		(net "M_E_CPU1_SA_CB<4>")
	)
	(segment
		(start 77.658976 -248.340626)
		(end 77.70368 -248.295922)
		(width 0.0889)
		(layer "In6.Cu")
		(net "M_E_CPU1_SA_CB<4>")
	)
	(segment
		(start 50.718212 -241.110262)
		(end 50.88128 -241.27333)
		(width 0.14478)
		(layer "In6.Cu")
		(net "M_E_CPU1_SA_CB<4>")
	)
	(segment
		(start 51.600862 -241.110262)
		(end 54.688486 -241.110262)
		(width 0.14478)
		(layer "In6.Cu")
		(net "M_E_CPU1_SA_CB<4>")
	)
	(segment
		(start 50.88128 -241.27333)
		(end 50.88128 -242.042696)
		(width 0.14478)
		(layer "In6.Cu")
		(net "M_E_CPU1_SA_CB<4>")
	)
	(segment
		(start 80.89265 -248.073164)
		(end 80.915002 -247.989852)
		(width 0.0889)
		(layer "In6.Cu")
		(net "M_E_CPU1_SA_CB<4>")
	)
	(segment
		(start 46.919642 -241.27333)
		(end 47.073058 -241.119914)
		(width 0.14478)
		(layer "In6.Cu")
		(net "M_E_CPU1_SA_CB<4>")
	)
	(segment
		(start 29.686758 -241.119914)
		(end 46.209712 -241.119914)
		(width 0.14478)
		(layer "In6.Cu")
		(net "M_E_CPU1_SA_CB<4>")
	)
	(segment
		(start 49.211738 -242.042696)
		(end 49.211738 -241.27333)
		(width 0.14478)
		(layer "In6.Cu")
		(net "M_E_CPU1_SA_CB<4>")
	)
	(segment
		(start 51.437794 -241.27333)
		(end 51.600862 -241.110262)
		(width 0.14478)
		(layer "In6.Cu")
		(net "M_E_CPU1_SA_CB<4>")
	)
	(segment
		(start 75.155806 -248.34596)
		(end 76.029566 -248.34596)
		(width 0.14478)
		(layer "In6.Cu")
		(net "M_E_CPU1_SA_CB<4>")
	)
	(segment
		(start 51.437794 -242.042696)
		(end 51.437794 -241.27333)
		(width 0.14478)
		(layer "In6.Cu")
		(net "M_E_CPU1_SA_CB<4>")
	)
	(segment
		(start 49.605184 -241.110262)
		(end 49.768252 -241.27333)
		(width 0.14478)
		(layer "In6.Cu")
		(net "M_E_CPU1_SA_CB<4>")
	)
	(segment
		(start 74.59091 -247.781064)
		(end 75.155806 -248.34596)
		(width 0.14478)
		(layer "In6.Cu")
		(net "M_E_CPU1_SA_CB<4>")
	)
	(segment
		(start 49.374806 -241.110262)
		(end 49.605184 -241.110262)
		(width 0.14478)
		(layer "In6.Cu")
		(net "M_E_CPU1_SA_CB<4>")
	)
	(segment
		(start 80.915002 -247.989852)
		(end 80.761078 -247.724422)
		(width 0.0889)
		(layer "In6.Cu")
		(net "M_E_CPU1_SA_CB<4>")
	)
	(segment
		(start 50.487834 -241.110262)
		(end 50.718212 -241.110262)
		(width 0.14478)
		(layer "In6.Cu")
		(net "M_E_CPU1_SA_CB<4>")
	)
	(segment
		(start 59.982862 -242.810284)
		(end 64.953642 -247.781064)
		(width 0.14478)
		(layer "In6.Cu")
		(net "M_E_CPU1_SA_CB<4>")
	)
	(segment
		(start 46.209712 -241.119914)
		(end 46.363128 -241.27333)
		(width 0.14478)
		(layer "In6.Cu")
		(net "M_E_CPU1_SA_CB<4>")
	)
	(segment
		(start 79.623666 -248.040906)
		(end 79.63408 -248.047002)
		(width 0.0889)
		(layer "In6.Cu")
		(net "M_E_CPU1_SA_CB<4>")
	)
	(segment
		(start 79.06004 -248.051828)
		(end 79.068422 -248.047002)
		(width 0.0889)
		(layer "In6.Cu")
		(net "M_E_CPU1_SA_CB<4>")
	)
	(segment
		(start 48.501808 -241.119914)
		(end 48.655224 -241.27333)
		(width 0.14478)
		(layer "In6.Cu")
		(net "M_E_CPU1_SA_CB<4>")
	)
	(segment
		(start 54.688486 -241.110262)
		(end 56.388508 -242.810284)
		(width 0.14478)
		(layer "In6.Cu")
		(net "M_E_CPU1_SA_CB<4>")
	)
	(segment
		(start 49.768252 -241.27333)
		(end 49.768252 -242.042696)
		(width 0.14478)
		(layer "In6.Cu")
		(net "M_E_CPU1_SA_CB<4>")
	)
	(segment
		(start 46.363128 -241.27333)
		(end 46.363128 -242.460018)
		(width 0.14478)
		(layer "In6.Cu")
		(net "M_E_CPU1_SA_CB<4>")
	)
	(segment
		(start 49.93132 -242.205764)
		(end 50.161698 -242.205764)
		(width 0.14478)
		(layer "In6.Cu")
		(net "M_E_CPU1_SA_CB<4>")
	)
	(arc
		(start 78.1431 -248.038366)
		(mid 78.419829 -247.970683)
		(end 78.69428 -248.047002)
		(width 0.0889)
		(layer "In6.Cu")
		(net "M_E_CPU1_SA_CB<4>")
	)
	(arc
		(start 79.068422 -248.047002)
		(mid 79.345235 -247.970859)
		(end 79.623666 -248.040906)
		(width 0.0889)
		(layer "In6.Cu")
		(net "M_E_CPU1_SA_CB<4>")
	)
	(arc
		(start 80.008222 -248.047002)
		(mid 80.291178 -247.970825)
		(end 80.574134 -248.047002)
		(width 0.0889)
		(layer "In6.Cu")
		(net "M_E_CPU1_SA_CB<4>")
	)
	(arc
		(start 78.69428 -248.047002)
		(mid 78.876531 -248.097352)
		(end 79.06004 -248.051828)
		(width 0.0889)
		(layer "In6.Cu")
		(net "M_E_CPU1_SA_CB<4>")
	)
	(arc
		(start 80.574134 -248.047002)
		(mid 80.730453 -248.095997)
		(end 80.89265 -248.073164)
		(width 0.0889)
		(layer "In6.Cu")
		(net "M_E_CPU1_SA_CB<4>")
	)
	(arc
		(start 79.642462 -248.051828)
		(mid 79.82597 -248.097322)
		(end 80.008222 -248.047002)
		(width 0.0889)
		(layer "In6.Cu")
		(net "M_E_CPU1_SA_CB<4>")
	)
	(segment
		(start 83.107784 -246.370348)
		(end 82.640932 -246.10441)
		(width 0.10668)
		(layer "F.Cu")
		(net "M_E_CPU1_SA_CB<3>")
	)
	(segment
		(start 46.552866 -237.700566)
		(end 49.392078 -237.700566)
		(width 0.14478)
		(layer "In6.Cu")
		(net "M_E_CPU1_SA_CB<3>")
	)
	(segment
		(start 81.879694 -245.777004)
		(end 81.888076 -245.78183)
		(width 0.0889)
		(layer "In6.Cu")
		(net "M_E_CPU1_SA_CB<3>")
	)
	(segment
		(start 58.00852 -236.627924)
		(end 58.575702 -236.627924)
		(width 0.14478)
		(layer "In6.Cu")
		(net "M_E_CPU1_SA_CB<3>")
	)
	(segment
		(start 41.820592 -237.700566)
		(end 42.670476 -236.850682)
		(width 0.14478)
		(layer "In6.Cu")
		(net "M_E_CPU1_SA_CB<3>")
	)
	(segment
		(start 58.575702 -236.627924)
		(end 60.42787 -238.480092)
		(width 0.14478)
		(layer "In6.Cu")
		(net "M_E_CPU1_SA_CB<3>")
	)
	(segment
		(start 79.634334 -245.78183)
		(end 79.646018 -245.774972)
		(width 0.0889)
		(layer "In6.Cu")
		(net "M_E_CPU1_SA_CB<3>")
	)
	(segment
		(start 57.32653 -237.309914)
		(end 58.00852 -236.627924)
		(width 0.14478)
		(layer "In6.Cu")
		(net "M_E_CPU1_SA_CB<3>")
	)
	(segment
		(start 60.42787 -238.480092)
		(end 60.42787 -238.787432)
		(width 0.14478)
		(layer "In6.Cu")
		(net "M_E_CPU1_SA_CB<3>")
	)
	(segment
		(start 45.702982 -236.850682)
		(end 46.552866 -237.700566)
		(width 0.14478)
		(layer "In6.Cu")
		(net "M_E_CPU1_SA_CB<3>")
	)
	(segment
		(start 53.246782 -236.850682)
		(end 53.706014 -237.309914)
		(width 0.14478)
		(layer "In6.Cu")
		(net "M_E_CPU1_SA_CB<3>")
	)
	(segment
		(start 76.056236 -245.864634)
		(end 78.38694 -245.864634)
		(width 0.0889)
		(layer "In6.Cu")
		(net "M_E_CPU1_SA_CB<3>")
	)
	(segment
		(start 60.42787 -238.787432)
		(end 67.082162 -245.441724)
		(width 0.14478)
		(layer "In6.Cu")
		(net "M_E_CPU1_SA_CB<3>")
	)
	(segment
		(start 50.241962 -236.850682)
		(end 53.246782 -236.850682)
		(width 0.14478)
		(layer "In6.Cu")
		(net "M_E_CPU1_SA_CB<3>")
	)
	(segment
		(start 38.864032 -237.700566)
		(end 41.820592 -237.700566)
		(width 0.14478)
		(layer "In6.Cu")
		(net "M_E_CPU1_SA_CB<3>")
	)
	(segment
		(start 42.670476 -236.850682)
		(end 45.702982 -236.850682)
		(width 0.14478)
		(layer "In6.Cu")
		(net "M_E_CPU1_SA_CB<3>")
	)
	(segment
		(start 38.014148 -236.850682)
		(end 38.864032 -237.700566)
		(width 0.14478)
		(layer "In6.Cu")
		(net "M_E_CPU1_SA_CB<3>")
	)
	(segment
		(start 82.487008 -245.83898)
		(end 82.640932 -246.10441)
		(width 0.0889)
		(layer "In6.Cu")
		(net "M_E_CPU1_SA_CB<3>")
	)
	(segment
		(start 75.999086 -245.807484)
		(end 76.056236 -245.864634)
		(width 0.0889)
		(layer "In6.Cu")
		(net "M_E_CPU1_SA_CB<3>")
	)
	(segment
		(start 26.154888 -237.700566)
		(end 34.223198 -237.700566)
		(width 0.14478)
		(layer "In6.Cu")
		(net "M_E_CPU1_SA_CB<3>")
	)
	(segment
		(start 82.390996 -245.81358)
		(end 82.487008 -245.83898)
		(width 0.0889)
		(layer "In6.Cu")
		(net "M_E_CPU1_SA_CB<3>")
	)
	(segment
		(start 79.62392 -245.787926)
		(end 79.634334 -245.78183)
		(width 0.0889)
		(layer "In6.Cu")
		(net "M_E_CPU1_SA_CB<3>")
	)
	(segment
		(start 75.633326 -245.441724)
		(end 75.999086 -245.807484)
		(width 0.14478)
		(layer "In6.Cu")
		(net "M_E_CPU1_SA_CB<3>")
	)
	(segment
		(start 49.392078 -237.700566)
		(end 50.241962 -236.850682)
		(width 0.14478)
		(layer "In6.Cu")
		(net "M_E_CPU1_SA_CB<3>")
	)
	(segment
		(start 53.706014 -237.309914)
		(end 57.32653 -237.309914)
		(width 0.14478)
		(layer "In6.Cu")
		(net "M_E_CPU1_SA_CB<3>")
	)
	(segment
		(start 35.073082 -236.850682)
		(end 38.014148 -236.850682)
		(width 0.14478)
		(layer "In6.Cu")
		(net "M_E_CPU1_SA_CB<3>")
	)
	(segment
		(start 34.223198 -237.700566)
		(end 35.073082 -236.850682)
		(width 0.14478)
		(layer "In6.Cu")
		(net "M_E_CPU1_SA_CB<3>")
	)
	(segment
		(start 67.082162 -245.441724)
		(end 75.633326 -245.441724)
		(width 0.14478)
		(layer "In6.Cu")
		(net "M_E_CPU1_SA_CB<3>")
	)
	(segment
		(start 79.056992 -245.774972)
		(end 79.068676 -245.78183)
		(width 0.0889)
		(layer "In6.Cu")
		(net "M_E_CPU1_SA_CB<3>")
	)
	(segment
		(start 25.152096 -237.285276)
		(end 26.154888 -237.700566)
		(width 0.14478)
		(layer "In6.Cu")
		(net "M_E_CPU1_SA_CB<3>")
	)
	(arc
		(start 80.574134 -245.78183)
		(mid 80.761078 -245.731575)
		(end 80.948022 -245.78183)
		(width 0.0889)
		(layer "In6.Cu")
		(net "M_E_CPU1_SA_CB<3>")
	)
	(arc
		(start 80.948022 -245.78183)
		(mid 81.230978 -245.858007)
		(end 81.513934 -245.78183)
		(width 0.0889)
		(layer "In6.Cu")
		(net "M_E_CPU1_SA_CB<3>")
	)
	(arc
		(start 79.068676 -245.78183)
		(mid 79.345489 -245.857973)
		(end 79.62392 -245.787926)
		(width 0.0889)
		(layer "In6.Cu")
		(net "M_E_CPU1_SA_CB<3>")
	)
	(arc
		(start 80.008222 -245.78183)
		(mid 80.291178 -245.858007)
		(end 80.574134 -245.78183)
		(width 0.0889)
		(layer "In6.Cu")
		(net "M_E_CPU1_SA_CB<3>")
	)
	(arc
		(start 79.646018 -245.774972)
		(mid 79.828019 -245.731439)
		(end 80.008222 -245.78183)
		(width 0.0889)
		(layer "In6.Cu")
		(net "M_E_CPU1_SA_CB<3>")
	)
	(arc
		(start 78.38694 -245.864634)
		(mid 78.546096 -245.843582)
		(end 78.69428 -245.78183)
		(width 0.0889)
		(layer "In6.Cu")
		(net "M_E_CPU1_SA_CB<3>")
	)
	(arc
		(start 81.888076 -245.78183)
		(mid 82.135789 -245.85705)
		(end 82.390996 -245.81358)
		(width 0.0889)
		(layer "In6.Cu")
		(net "M_E_CPU1_SA_CB<3>")
	)
	(arc
		(start 78.69428 -245.78183)
		(mid 78.874738 -245.731386)
		(end 79.056992 -245.774972)
		(width 0.0889)
		(layer "In6.Cu")
		(net "M_E_CPU1_SA_CB<3>")
	)
	(arc
		(start 81.513934 -245.78183)
		(mid 81.696185 -245.73148)
		(end 81.879694 -245.777004)
		(width 0.0889)
		(layer "In6.Cu")
		(net "M_E_CPU1_SA_CB<3>")
	)
	(segment
		(start 81.69783 -245.560342)
		(end 81.230978 -245.294404)
		(width 0.10668)
		(layer "F.Cu")
		(net "M_E_CPU1_SA_CB<2>")
	)
	(segment
		(start 38.873938 -236.01045)
		(end 41.810686 -236.01045)
		(width 0.14478)
		(layer "In6.Cu")
		(net "M_E_CPU1_SA_CB<2>")
	)
	(segment
		(start 38.0238 -235.160312)
		(end 38.873938 -236.01045)
		(width 0.14478)
		(layer "In6.Cu")
		(net "M_E_CPU1_SA_CB<2>")
	)
	(segment
		(start 49.382172 -236.01045)
		(end 50.23231 -235.160312)
		(width 0.14478)
		(layer "In6.Cu")
		(net "M_E_CPU1_SA_CB<2>")
	)
	(segment
		(start 26.178764 -236.01045)
		(end 34.213292 -236.01045)
		(width 0.14478)
		(layer "In6.Cu")
		(net "M_E_CPU1_SA_CB<2>")
	)
	(segment
		(start 77.167486 -245.233444)
		(end 77.353414 -245.047516)
		(width 0.0889)
		(layer "In6.Cu")
		(net "M_E_CPU1_SA_CB<2>")
	)
	(segment
		(start 76.080366 -244.532404)
		(end 76.781406 -245.233444)
		(width 0.0889)
		(layer "In6.Cu")
		(net "M_E_CPU1_SA_CB<2>")
	)
	(segment
		(start 57.77611 -235.160312)
		(end 59.830716 -235.160312)
		(width 0.14478)
		(layer "In6.Cu")
		(net "M_E_CPU1_SA_CB<2>")
	)
	(segment
		(start 54.106572 -236.01045)
		(end 56.925972 -236.01045)
		(width 0.14478)
		(layer "In6.Cu")
		(net "M_E_CPU1_SA_CB<2>")
	)
	(segment
		(start 67.459098 -244.532404)
		(end 75.935586 -244.532404)
		(width 0.14478)
		(layer "In6.Cu")
		(net "M_E_CPU1_SA_CB<2>")
	)
	(segment
		(start 35.06343 -235.160312)
		(end 38.0238 -235.160312)
		(width 0.14478)
		(layer "In6.Cu")
		(net "M_E_CPU1_SA_CB<2>")
	)
	(segment
		(start 42.660824 -235.160312)
		(end 45.712634 -235.160312)
		(width 0.14478)
		(layer "In6.Cu")
		(net "M_E_CPU1_SA_CB<2>")
	)
	(segment
		(start 50.23231 -235.160312)
		(end 53.256434 -235.160312)
		(width 0.14478)
		(layer "In6.Cu")
		(net "M_E_CPU1_SA_CB<2>")
	)
	(segment
		(start 77.353414 -245.047516)
		(end 77.942186 -245.047516)
		(width 0.0889)
		(layer "In6.Cu")
		(net "M_E_CPU1_SA_CB<2>")
	)
	(segment
		(start 78.22438 -244.971824)
		(end 78.236064 -244.964966)
		(width 0.0889)
		(layer "In6.Cu")
		(net "M_E_CPU1_SA_CB<2>")
	)
	(segment
		(start 80.981042 -245.003574)
		(end 81.077054 -245.028974)
		(width 0.0889)
		(layer "In6.Cu")
		(net "M_E_CPU1_SA_CB<2>")
	)
	(segment
		(start 53.256434 -235.160312)
		(end 54.106572 -236.01045)
		(width 0.14478)
		(layer "In6.Cu")
		(net "M_E_CPU1_SA_CB<2>")
	)
	(segment
		(start 59.830716 -235.160312)
		(end 60.259214 -235.58881)
		(width 0.14478)
		(layer "In6.Cu")
		(net "M_E_CPU1_SA_CB<2>")
	)
	(segment
		(start 41.810686 -236.01045)
		(end 42.660824 -235.160312)
		(width 0.14478)
		(layer "In6.Cu")
		(net "M_E_CPU1_SA_CB<2>")
	)
	(segment
		(start 79.538322 -244.971824)
		(end 79.548736 -244.97792)
		(width 0.0889)
		(layer "In6.Cu")
		(net "M_E_CPU1_SA_CB<2>")
	)
	(segment
		(start 79.15402 -244.97792)
		(end 79.164434 -244.971824)
		(width 0.0889)
		(layer "In6.Cu")
		(net "M_E_CPU1_SA_CB<2>")
	)
	(segment
		(start 81.077054 -245.028974)
		(end 81.230978 -245.294404)
		(width 0.0889)
		(layer "In6.Cu")
		(net "M_E_CPU1_SA_CB<2>")
	)
	(segment
		(start 34.213292 -236.01045)
		(end 35.06343 -235.160312)
		(width 0.14478)
		(layer "In6.Cu")
		(net "M_E_CPU1_SA_CB<2>")
	)
	(segment
		(start 25.152096 -235.585254)
		(end 26.178764 -236.01045)
		(width 0.14478)
		(layer "In6.Cu")
		(net "M_E_CPU1_SA_CB<2>")
	)
	(segment
		(start 56.925972 -236.01045)
		(end 57.77611 -235.160312)
		(width 0.14478)
		(layer "In6.Cu")
		(net "M_E_CPU1_SA_CB<2>")
	)
	(segment
		(start 46.562772 -236.01045)
		(end 49.382172 -236.01045)
		(width 0.14478)
		(layer "In6.Cu")
		(net "M_E_CPU1_SA_CB<2>")
	)
	(segment
		(start 80.46974 -244.966998)
		(end 80.478122 -244.971824)
		(width 0.0889)
		(layer "In6.Cu")
		(net "M_E_CPU1_SA_CB<2>")
	)
	(segment
		(start 45.712634 -235.160312)
		(end 46.562772 -236.01045)
		(width 0.14478)
		(layer "In6.Cu")
		(net "M_E_CPU1_SA_CB<2>")
	)
	(segment
		(start 61.492384 -238.56569)
		(end 67.459098 -244.532404)
		(width 0.14478)
		(layer "In6.Cu")
		(net "M_E_CPU1_SA_CB<2>")
	)
	(segment
		(start 76.781406 -245.233444)
		(end 77.167486 -245.233444)
		(width 0.0889)
		(layer "In6.Cu")
		(net "M_E_CPU1_SA_CB<2>")
	)
	(segment
		(start 60.259214 -235.58881)
		(end 61.492384 -238.56569)
		(width 0.14478)
		(layer "In6.Cu")
		(net "M_E_CPU1_SA_CB<2>")
	)
	(segment
		(start 75.935586 -244.532404)
		(end 76.080366 -244.532404)
		(width 0.0889)
		(layer "In6.Cu")
		(net "M_E_CPU1_SA_CB<2>")
	)
	(arc
		(start 78.236064 -244.964966)
		(mid 78.418065 -244.921433)
		(end 78.598268 -244.971824)
		(width 0.0889)
		(layer "In6.Cu")
		(net "M_E_CPU1_SA_CB<2>")
	)
	(arc
		(start 79.548736 -244.97792)
		(mid 79.827168 -245.048018)
		(end 80.10398 -244.971824)
		(width 0.0889)
		(layer "In6.Cu")
		(net "M_E_CPU1_SA_CB<2>")
	)
	(arc
		(start 79.164434 -244.971824)
		(mid 79.351378 -244.921569)
		(end 79.538322 -244.971824)
		(width 0.0889)
		(layer "In6.Cu")
		(net "M_E_CPU1_SA_CB<2>")
	)
	(arc
		(start 80.10398 -244.971824)
		(mid 80.286231 -244.921474)
		(end 80.46974 -244.966998)
		(width 0.0889)
		(layer "In6.Cu")
		(net "M_E_CPU1_SA_CB<2>")
	)
	(arc
		(start 80.478122 -244.971824)
		(mid 80.725835 -245.047044)
		(end 80.981042 -245.003574)
		(width 0.0889)
		(layer "In6.Cu")
		(net "M_E_CPU1_SA_CB<2>")
	)
	(arc
		(start 77.942186 -245.047516)
		(mid 78.08827 -245.028264)
		(end 78.22438 -244.971824)
		(width 0.0889)
		(layer "In6.Cu")
		(net "M_E_CPU1_SA_CB<2>")
	)
	(arc
		(start 78.598268 -244.971824)
		(mid 78.875335 -245.048095)
		(end 79.15402 -244.97792)
		(width 0.0889)
		(layer "In6.Cu")
		(net "M_E_CPU1_SA_CB<2>")
	)
	(segment
		(start 82.637884 -245.560342)
		(end 82.171032 -245.294404)
		(width 0.10668)
		(layer "F.Cu")
		(net "M_E_CPU1_SA_CB<1>")
	)
	(segment
		(start 31.274258 -236.483144)
		(end 31.437326 -236.646212)
		(width 0.14478)
		(layer "In6.Cu")
		(net "M_E_CPU1_SA_CB<1>")
	)
	(segment
		(start 31.99384 -237.023402)
		(end 32.156908 -236.860334)
		(width 0.14478)
		(layer "In6.Cu")
		(net "M_E_CPU1_SA_CB<1>")
	)
	(segment
		(start 79.52994 -245.62181)
		(end 79.538322 -245.616984)
		(width 0.0889)
		(layer "In6.Cu")
		(net "M_E_CPU1_SA_CB<1>")
	)
	(segment
		(start 82.302604 -245.643146)
		(end 82.324956 -245.559834)
		(width 0.0889)
		(layer "In6.Cu")
		(net "M_E_CPU1_SA_CB<1>")
	)
	(segment
		(start 40.991282 -237.250224)
		(end 41.22166 -237.250224)
		(width 0.14478)
		(layer "In6.Cu")
		(net "M_E_CPU1_SA_CB<1>")
	)
	(segment
		(start 41.96715 -236.860334)
		(end 42.817034 -236.01045)
		(width 0.14478)
		(layer "In6.Cu")
		(net "M_E_CPU1_SA_CB<1>")
	)
	(segment
		(start 79.538322 -245.616984)
		(end 79.548736 -245.610888)
		(width 0.0889)
		(layer "In6.Cu")
		(net "M_E_CPU1_SA_CB<1>")
	)
	(segment
		(start 30.324298 -237.074456)
		(end 30.487366 -237.237524)
		(width 0.14478)
		(layer "In6.Cu")
		(net "M_E_CPU1_SA_CB<1>")
	)
	(segment
		(start 59.789822 -236.964982)
		(end 59.789568 -237.169198)
		(width 0.14478)
		(layer "In6.Cu")
		(net "M_E_CPU1_SA_CB<1>")
	)
	(segment
		(start 76.043536 -245.194074)
		(end 76.460858 -245.611396)
		(width 0.0889)
		(layer "In6.Cu")
		(net "M_E_CPU1_SA_CB<1>")
	)
	(segment
		(start 80.46974 -245.62181)
		(end 80.478122 -245.616984)
		(width 0.0889)
		(layer "In6.Cu")
		(net "M_E_CPU1_SA_CB<1>")
	)
	(segment
		(start 30.880812 -237.074456)
		(end 30.880812 -236.646212)
		(width 0.14478)
		(layer "In6.Cu")
		(net "M_E_CPU1_SA_CB<1>")
	)
	(segment
		(start 32.156908 -236.860334)
		(end 34.41827 -236.860334)
		(width 0.14478)
		(layer "In6.Cu")
		(net "M_E_CPU1_SA_CB<1>")
	)
	(segment
		(start 82.324956 -245.559834)
		(end 82.171032 -245.294404)
		(width 0.0889)
		(layer "In6.Cu")
		(net "M_E_CPU1_SA_CB<1>")
	)
	(segment
		(start 57.980834 -236.01045)
		(end 58.63082 -236.01045)
		(width 0.14478)
		(layer "In6.Cu")
		(net "M_E_CPU1_SA_CB<1>")
	)
	(segment
		(start 54.084474 -236.860334)
		(end 57.13095 -236.860334)
		(width 0.14478)
		(layer "In6.Cu")
		(net "M_E_CPU1_SA_CB<1>")
	)
	(segment
		(start 48.858678 -237.250224)
		(end 49.021746 -237.087156)
		(width 0.14478)
		(layer "In6.Cu")
		(net "M_E_CPU1_SA_CB<1>")
	)
	(segment
		(start 60.014358 -236.740446)
		(end 59.789822 -236.964982)
		(width 0.14478)
		(layer "In6.Cu")
		(net "M_E_CPU1_SA_CB<1>")
	)
	(segment
		(start 78.22692 -245.611396)
		(end 78.242668 -245.627144)
		(width 0.0889)
		(layer "In6.Cu")
		(net "M_E_CPU1_SA_CB<1>")
	)
	(segment
		(start 40.828214 -237.087156)
		(end 40.991282 -237.250224)
		(width 0.14478)
		(layer "In6.Cu")
		(net "M_E_CPU1_SA_CB<1>")
	)
	(segment
		(start 31.437326 -236.646212)
		(end 31.437326 -237.074456)
		(width 0.14478)
		(layer "In6.Cu")
		(net "M_E_CPU1_SA_CB<1>")
	)
	(segment
		(start 59.381898 -236.556804)
		(end 59.606434 -236.332268)
		(width 0.14478)
		(layer "In6.Cu")
		(net "M_E_CPU1_SA_CB<1>")
	)
	(segment
		(start 49.184814 -236.860334)
		(end 49.58715 -236.860334)
		(width 0.14478)
		(layer "In6.Cu")
		(net "M_E_CPU1_SA_CB<1>")
	)
	(segment
		(start 35.268154 -236.01045)
		(end 35.425634 -236.01045)
		(width 0.14478)
		(layer "In6.Cu")
		(net "M_E_CPU1_SA_CB<1>")
	)
	(segment
		(start 59.811158 -236.332522)
		(end 60.014358 -236.535722)
		(width 0.14478)
		(layer "In6.Cu")
		(net "M_E_CPU1_SA_CB<1>")
	)
	(segment
		(start 31.99384 -237.074456)
		(end 31.99384 -237.023402)
		(width 0.14478)
		(layer "In6.Cu")
		(net "M_E_CPU1_SA_CB<1>")
	)
	(segment
		(start 42.817034 -236.01045)
		(end 45.69079 -236.01045)
		(width 0.14478)
		(layer "In6.Cu")
		(net "M_E_CPU1_SA_CB<1>")
	)
	(segment
		(start 31.04388 -236.483144)
		(end 31.274258 -236.483144)
		(width 0.14478)
		(layer "In6.Cu")
		(net "M_E_CPU1_SA_CB<1>")
	)
	(segment
		(start 31.437326 -237.074456)
		(end 31.600394 -237.237524)
		(width 0.14478)
		(layer "In6.Cu")
		(net "M_E_CPU1_SA_CB<1>")
	)
	(segment
		(start 36.308284 -236.01045)
		(end 38.01491 -236.01045)
		(width 0.14478)
		(layer "In6.Cu")
		(net "M_E_CPU1_SA_CB<1>")
	)
	(segment
		(start 38.864794 -236.860334)
		(end 40.665146 -236.860334)
		(width 0.14478)
		(layer "In6.Cu")
		(net "M_E_CPU1_SA_CB<1>")
	)
	(segment
		(start 81.044034 -245.616984)
		(end 81.052416 -245.62181)
		(width 0.0889)
		(layer "In6.Cu")
		(net "M_E_CPU1_SA_CB<1>")
	)
	(segment
		(start 35.588702 -236.173518)
		(end 35.588702 -236.233716)
		(width 0.14478)
		(layer "In6.Cu")
		(net "M_E_CPU1_SA_CB<1>")
	)
	(segment
		(start 31.600394 -237.237524)
		(end 31.830772 -237.237524)
		(width 0.14478)
		(layer "In6.Cu")
		(net "M_E_CPU1_SA_CB<1>")
	)
	(segment
		(start 59.789568 -237.169198)
		(end 60.87745 -238.25708)
		(width 0.14478)
		(layer "In6.Cu")
		(net "M_E_CPU1_SA_CB<1>")
	)
	(segment
		(start 57.13095 -236.860334)
		(end 57.980834 -236.01045)
		(width 0.14478)
		(layer "In6.Cu")
		(net "M_E_CPU1_SA_CB<1>")
	)
	(segment
		(start 30.487366 -237.237524)
		(end 30.717744 -237.237524)
		(width 0.14478)
		(layer "In6.Cu")
		(net "M_E_CPU1_SA_CB<1>")
	)
	(segment
		(start 30.16123 -236.860334)
		(end 30.324298 -237.023402)
		(width 0.14478)
		(layer "In6.Cu")
		(net "M_E_CPU1_SA_CB<1>")
	)
	(segment
		(start 49.021746 -237.023402)
		(end 49.184814 -236.860334)
		(width 0.14478)
		(layer "In6.Cu")
		(net "M_E_CPU1_SA_CB<1>")
	)
	(segment
		(start 58.63082 -236.01045)
		(end 59.177174 -236.556804)
		(width 0.14478)
		(layer "In6.Cu")
		(net "M_E_CPU1_SA_CB<1>")
	)
	(segment
		(start 53.23459 -236.01045)
		(end 54.084474 -236.860334)
		(width 0.14478)
		(layer "In6.Cu")
		(net "M_E_CPU1_SA_CB<1>")
	)
	(segment
		(start 35.75177 -236.396784)
		(end 35.982148 -236.396784)
		(width 0.14478)
		(layer "In6.Cu")
		(net "M_E_CPU1_SA_CB<1>")
	)
	(segment
		(start 41.384728 -237.087156)
		(end 41.384728 -237.023402)
		(width 0.14478)
		(layer "In6.Cu")
		(net "M_E_CPU1_SA_CB<1>")
	)
	(segment
		(start 35.588702 -236.233716)
		(end 35.75177 -236.396784)
		(width 0.14478)
		(layer "In6.Cu")
		(net "M_E_CPU1_SA_CB<1>")
	)
	(segment
		(start 75.836526 -244.987064)
		(end 76.043536 -245.194074)
		(width 0.14478)
		(layer "In6.Cu")
		(net "M_E_CPU1_SA_CB<1>")
	)
	(segment
		(start 34.41827 -236.860334)
		(end 35.268154 -236.01045)
		(width 0.14478)
		(layer "In6.Cu")
		(net "M_E_CPU1_SA_CB<1>")
	)
	(segment
		(start 79.154274 -245.610888)
		(end 79.164688 -245.616984)
		(width 0.0889)
		(layer "In6.Cu")
		(net "M_E_CPU1_SA_CB<1>")
	)
	(segment
		(start 48.6283 -237.250224)
		(end 48.858678 -237.250224)
		(width 0.14478)
		(layer "In6.Cu")
		(net "M_E_CPU1_SA_CB<1>")
	)
	(segment
		(start 45.69079 -236.01045)
		(end 46.540674 -236.860334)
		(width 0.14478)
		(layer "In6.Cu")
		(net "M_E_CPU1_SA_CB<1>")
	)
	(segment
		(start 29.677106 -236.860334)
		(end 30.16123 -236.860334)
		(width 0.14478)
		(layer "In6.Cu")
		(net "M_E_CPU1_SA_CB<1>")
	)
	(segment
		(start 60.87745 -238.593884)
		(end 67.27063 -244.987064)
		(width 0.14478)
		(layer "In6.Cu")
		(net "M_E_CPU1_SA_CB<1>")
	)
	(segment
		(start 49.58715 -236.860334)
		(end 50.437034 -236.01045)
		(width 0.14478)
		(layer "In6.Cu")
		(net "M_E_CPU1_SA_CB<1>")
	)
	(segment
		(start 35.425634 -236.01045)
		(end 35.588702 -236.173518)
		(width 0.14478)
		(layer "In6.Cu")
		(net "M_E_CPU1_SA_CB<1>")
	)
	(segment
		(start 60.87745 -238.25708)
		(end 60.87745 -238.593884)
		(width 0.14478)
		(layer "In6.Cu")
		(net "M_E_CPU1_SA_CB<1>")
	)
	(segment
		(start 30.717744 -237.237524)
		(end 30.880812 -237.074456)
		(width 0.14478)
		(layer "In6.Cu")
		(net "M_E_CPU1_SA_CB<1>")
	)
	(segment
		(start 60.014358 -236.535722)
		(end 60.014358 -236.740446)
		(width 0.14478)
		(layer "In6.Cu")
		(net "M_E_CPU1_SA_CB<1>")
	)
	(segment
		(start 38.01491 -236.01045)
		(end 38.864794 -236.860334)
		(width 0.14478)
		(layer "In6.Cu")
		(net "M_E_CPU1_SA_CB<1>")
	)
	(segment
		(start 30.880812 -236.646212)
		(end 31.04388 -236.483144)
		(width 0.14478)
		(layer "In6.Cu")
		(net "M_E_CPU1_SA_CB<1>")
	)
	(segment
		(start 35.982148 -236.396784)
		(end 36.145216 -236.233716)
		(width 0.14478)
		(layer "In6.Cu")
		(net "M_E_CPU1_SA_CB<1>")
	)
	(segment
		(start 40.665146 -236.860334)
		(end 40.828214 -237.023402)
		(width 0.14478)
		(layer "In6.Cu")
		(net "M_E_CPU1_SA_CB<1>")
	)
	(segment
		(start 67.27063 -244.987064)
		(end 75.836526 -244.987064)
		(width 0.14478)
		(layer "In6.Cu")
		(net "M_E_CPU1_SA_CB<1>")
	)
	(segment
		(start 48.302164 -236.860334)
		(end 48.465232 -237.023402)
		(width 0.14478)
		(layer "In6.Cu")
		(net "M_E_CPU1_SA_CB<1>")
	)
	(segment
		(start 41.384728 -237.023402)
		(end 41.547796 -236.860334)
		(width 0.14478)
		(layer "In6.Cu")
		(net "M_E_CPU1_SA_CB<1>")
	)
	(segment
		(start 48.465232 -237.023402)
		(end 48.465232 -237.087156)
		(width 0.14478)
		(layer "In6.Cu")
		(net "M_E_CPU1_SA_CB<1>")
	)
	(segment
		(start 46.540674 -236.860334)
		(end 48.302164 -236.860334)
		(width 0.14478)
		(layer "In6.Cu")
		(net "M_E_CPU1_SA_CB<1>")
	)
	(segment
		(start 49.021746 -237.087156)
		(end 49.021746 -237.023402)
		(width 0.14478)
		(layer "In6.Cu")
		(net "M_E_CPU1_SA_CB<1>")
	)
	(segment
		(start 36.145216 -236.173518)
		(end 36.308284 -236.01045)
		(width 0.14478)
		(layer "In6.Cu")
		(net "M_E_CPU1_SA_CB<1>")
	)
	(segment
		(start 59.177174 -236.556804)
		(end 59.381898 -236.556804)
		(width 0.14478)
		(layer "In6.Cu")
		(net "M_E_CPU1_SA_CB<1>")
	)
	(segment
		(start 48.465232 -237.087156)
		(end 48.6283 -237.250224)
		(width 0.14478)
		(layer "In6.Cu")
		(net "M_E_CPU1_SA_CB<1>")
	)
	(segment
		(start 41.22166 -237.250224)
		(end 41.384728 -237.087156)
		(width 0.14478)
		(layer "In6.Cu")
		(net "M_E_CPU1_SA_CB<1>")
	)
	(segment
		(start 36.145216 -236.233716)
		(end 36.145216 -236.173518)
		(width 0.14478)
		(layer "In6.Cu")
		(net "M_E_CPU1_SA_CB<1>")
	)
	(segment
		(start 50.437034 -236.01045)
		(end 53.23459 -236.01045)
		(width 0.14478)
		(layer "In6.Cu")
		(net "M_E_CPU1_SA_CB<1>")
	)
	(segment
		(start 59.606434 -236.332268)
		(end 59.811158 -236.332522)
		(width 0.14478)
		(layer "In6.Cu")
		(net "M_E_CPU1_SA_CB<1>")
	)
	(segment
		(start 41.547796 -236.860334)
		(end 41.96715 -236.860334)
		(width 0.14478)
		(layer "In6.Cu")
		(net "M_E_CPU1_SA_CB<1>")
	)
	(segment
		(start 76.460858 -245.611396)
		(end 78.22692 -245.611396)
		(width 0.0889)
		(layer "In6.Cu")
		(net "M_E_CPU1_SA_CB<1>")
	)
	(segment
		(start 29.252164 -236.435392)
		(end 29.677106 -236.860334)
		(width 0.14478)
		(layer "In6.Cu")
		(net "M_E_CPU1_SA_CB<1>")
	)
	(segment
		(start 30.324298 -237.023402)
		(end 30.324298 -237.074456)
		(width 0.14478)
		(layer "In6.Cu")
		(net "M_E_CPU1_SA_CB<1>")
	)
	(segment
		(start 31.830772 -237.237524)
		(end 31.99384 -237.074456)
		(width 0.14478)
		(layer "In6.Cu")
		(net "M_E_CPU1_SA_CB<1>")
	)
	(segment
		(start 40.828214 -237.023402)
		(end 40.828214 -237.087156)
		(width 0.14478)
		(layer "In6.Cu")
		(net "M_E_CPU1_SA_CB<1>")
	)
	(arc
		(start 81.984088 -245.616984)
		(mid 82.140407 -245.665979)
		(end 82.302604 -245.643146)
		(width 0.0889)
		(layer "In6.Cu")
		(net "M_E_CPU1_SA_CB<1>")
	)
	(arc
		(start 81.052416 -245.62181)
		(mid 81.235924 -245.667304)
		(end 81.418176 -245.616984)
		(width 0.0889)
		(layer "In6.Cu")
		(net "M_E_CPU1_SA_CB<1>")
	)
	(arc
		(start 80.10398 -245.616984)
		(mid 80.286231 -245.667334)
		(end 80.46974 -245.62181)
		(width 0.0889)
		(layer "In6.Cu")
		(net "M_E_CPU1_SA_CB<1>")
	)
	(arc
		(start 78.242668 -245.627144)
		(mid 78.421897 -245.667297)
		(end 78.598522 -245.616984)
		(width 0.0889)
		(layer "In6.Cu")
		(net "M_E_CPU1_SA_CB<1>")
	)
	(arc
		(start 80.478122 -245.616984)
		(mid 80.761078 -245.540807)
		(end 81.044034 -245.616984)
		(width 0.0889)
		(layer "In6.Cu")
		(net "M_E_CPU1_SA_CB<1>")
	)
	(arc
		(start 79.548736 -245.610888)
		(mid 79.827168 -245.54079)
		(end 80.10398 -245.616984)
		(width 0.0889)
		(layer "In6.Cu")
		(net "M_E_CPU1_SA_CB<1>")
	)
	(arc
		(start 81.418176 -245.616984)
		(mid 81.701132 -245.540807)
		(end 81.984088 -245.616984)
		(width 0.0889)
		(layer "In6.Cu")
		(net "M_E_CPU1_SA_CB<1>")
	)
	(arc
		(start 79.164688 -245.616984)
		(mid 79.346685 -245.667206)
		(end 79.52994 -245.62181)
		(width 0.0889)
		(layer "In6.Cu")
		(net "M_E_CPU1_SA_CB<1>")
	)
	(arc
		(start 78.598522 -245.616984)
		(mid 78.875589 -245.540713)
		(end 79.154274 -245.610888)
		(width 0.0889)
		(layer "In6.Cu")
		(net "M_E_CPU1_SA_CB<1>")
	)
	(segment
		(start 81.22793 -244.750336)
		(end 80.761078 -244.484398)
		(width 0.10668)
		(layer "F.Cu")
		(net "M_E_CPU1_SA_CB<0>")
	)
	(segment
		(start 50.437034 -234.310428)
		(end 53.23459 -234.310428)
		(width 0.14478)
		(layer "In6.Cu")
		(net "M_E_CPU1_SA_CB<0>")
	)
	(segment
		(start 59.88177 -234.694984)
		(end 60.249308 -234.694984)
		(width 0.14478)
		(layer "In6.Cu")
		(net "M_E_CPU1_SA_CB<0>")
	)
	(segment
		(start 56.23687 -235.548424)
		(end 56.399938 -235.385356)
		(width 0.14478)
		(layer "In6.Cu")
		(net "M_E_CPU1_SA_CB<0>")
	)
	(segment
		(start 49.06645 -235.32338)
		(end 49.229518 -235.160312)
		(width 0.14478)
		(layer "In6.Cu")
		(net "M_E_CPU1_SA_CB<0>")
	)
	(segment
		(start 31.228538 -235.43514)
		(end 31.365952 -235.297726)
		(width 0.14478)
		(layer "In6.Cu")
		(net "M_E_CPU1_SA_CB<0>")
	)
	(segment
		(start 41.09593 -235.543344)
		(end 41.326308 -235.543344)
		(width 0.14478)
		(layer "In6.Cu")
		(net "M_E_CPU1_SA_CB<0>")
	)
	(segment
		(start 30.809438 -235.297726)
		(end 30.946852 -235.43514)
		(width 0.14478)
		(layer "In6.Cu")
		(net "M_E_CPU1_SA_CB<0>")
	)
	(segment
		(start 30.390338 -234.885484)
		(end 30.672024 -234.885484)
		(width 0.14478)
		(layer "In6.Cu")
		(net "M_E_CPU1_SA_CB<0>")
	)
	(segment
		(start 33.596834 -235.548424)
		(end 33.759902 -235.385356)
		(width 0.14478)
		(layer "In6.Cu")
		(net "M_E_CPU1_SA_CB<0>")
	)
	(segment
		(start 59.555634 -234.310428)
		(end 59.718702 -234.473496)
		(width 0.14478)
		(layer "In6.Cu")
		(net "M_E_CPU1_SA_CB<0>")
	)
	(segment
		(start 41.326308 -235.543344)
		(end 41.489376 -235.380276)
		(width 0.14478)
		(layer "In6.Cu")
		(net "M_E_CPU1_SA_CB<0>")
	)
	(segment
		(start 58.768742 -234.694984)
		(end 58.99912 -234.694984)
		(width 0.14478)
		(layer "In6.Cu")
		(net "M_E_CPU1_SA_CB<0>")
	)
	(segment
		(start 42.817034 -234.310428)
		(end 45.69079 -234.310428)
		(width 0.14478)
		(layer "In6.Cu")
		(net "M_E_CPU1_SA_CB<0>")
	)
	(segment
		(start 54.567328 -235.160312)
		(end 54.730396 -235.32338)
		(width 0.14478)
		(layer "In6.Cu")
		(net "M_E_CPU1_SA_CB<0>")
	)
	(segment
		(start 34.41827 -235.160312)
		(end 35.268154 -234.310428)
		(width 0.14478)
		(layer "In6.Cu")
		(net "M_E_CPU1_SA_CB<0>")
	)
	(segment
		(start 30.11551 -235.160312)
		(end 30.390338 -234.885484)
		(width 0.14478)
		(layer "In6.Cu")
		(net "M_E_CPU1_SA_CB<0>")
	)
	(segment
		(start 79.63408 -244.806978)
		(end 79.642462 -244.811804)
		(width 0.0889)
		(layer "In6.Cu")
		(net "M_E_CPU1_SA_CB<0>")
	)
	(segment
		(start 56.006492 -235.548424)
		(end 56.23687 -235.548424)
		(width 0.14478)
		(layer "In6.Cu")
		(net "M_E_CPU1_SA_CB<0>")
	)
	(segment
		(start 32.05988 -235.160312)
		(end 33.04032 -235.160312)
		(width 0.14478)
		(layer "In6.Cu")
		(net "M_E_CPU1_SA_CB<0>")
	)
	(segment
		(start 46.540674 -235.160312)
		(end 48.346868 -235.160312)
		(width 0.14478)
		(layer "In6.Cu")
		(net "M_E_CPU1_SA_CB<0>")
	)
	(segment
		(start 48.673004 -235.543344)
		(end 48.903382 -235.543344)
		(width 0.14478)
		(layer "In6.Cu")
		(net "M_E_CPU1_SA_CB<0>")
	)
	(segment
		(start 55.449978 -235.160312)
		(end 55.680356 -235.160312)
		(width 0.14478)
		(layer "In6.Cu")
		(net "M_E_CPU1_SA_CB<0>")
	)
	(segment
		(start 76.476606 -244.296184)
		(end 77.030326 -244.296184)
		(width 0.0889)
		(layer "In6.Cu")
		(net "M_E_CPU1_SA_CB<0>")
	)
	(segment
		(start 77.591158 -244.857016)
		(end 77.942186 -244.857016)
		(width 0.0889)
		(layer "In6.Cu")
		(net "M_E_CPU1_SA_CB<0>")
	)
	(segment
		(start 29.252164 -234.73537)
		(end 29.677106 -235.160312)
		(width 0.14478)
		(layer "In6.Cu")
		(net "M_E_CPU1_SA_CB<0>")
	)
	(segment
		(start 33.203388 -235.385356)
		(end 33.366456 -235.548424)
		(width 0.14478)
		(layer "In6.Cu")
		(net "M_E_CPU1_SA_CB<0>")
	)
	(segment
		(start 33.759902 -235.385356)
		(end 33.759902 -235.32338)
		(width 0.14478)
		(layer "In6.Cu")
		(net "M_E_CPU1_SA_CB<0>")
	)
	(segment
		(start 60.465716 -234.911392)
		(end 61.868812 -238.29899)
		(width 0.14478)
		(layer "In6.Cu")
		(net "M_E_CPU1_SA_CB<0>")
	)
	(segment
		(start 79.06004 -244.811804)
		(end 79.068422 -244.806978)
		(width 0.0889)
		(layer "In6.Cu")
		(net "M_E_CPU1_SA_CB<0>")
	)
	(segment
		(start 35.268154 -234.310428)
		(end 38.01491 -234.310428)
		(width 0.14478)
		(layer "In6.Cu")
		(net "M_E_CPU1_SA_CB<0>")
	)
	(segment
		(start 56.399938 -235.32338)
		(end 56.563006 -235.160312)
		(width 0.14478)
		(layer "In6.Cu")
		(net "M_E_CPU1_SA_CB<0>")
	)
	(segment
		(start 48.903382 -235.543344)
		(end 49.06645 -235.380276)
		(width 0.14478)
		(layer "In6.Cu")
		(net "M_E_CPU1_SA_CB<0>")
	)
	(segment
		(start 76.258166 -244.077744)
		(end 76.476606 -244.296184)
		(width 0.0889)
		(layer "In6.Cu")
		(net "M_E_CPU1_SA_CB<0>")
	)
	(segment
		(start 31.365952 -235.297726)
		(end 31.365952 -235.022898)
		(width 0.14478)
		(layer "In6.Cu")
		(net "M_E_CPU1_SA_CB<0>")
	)
	(segment
		(start 30.946852 -235.43514)
		(end 31.228538 -235.43514)
		(width 0.14478)
		(layer "In6.Cu")
		(net "M_E_CPU1_SA_CB<0>")
	)
	(segment
		(start 60.249308 -234.694984)
		(end 60.465716 -234.911392)
		(width 0.14478)
		(layer "In6.Cu")
		(net "M_E_CPU1_SA_CB<0>")
	)
	(segment
		(start 33.92297 -235.160312)
		(end 34.41827 -235.160312)
		(width 0.14478)
		(layer "In6.Cu")
		(net "M_E_CPU1_SA_CB<0>")
	)
	(segment
		(start 38.01491 -234.310428)
		(end 38.864794 -235.160312)
		(width 0.14478)
		(layer "In6.Cu")
		(net "M_E_CPU1_SA_CB<0>")
	)
	(segment
		(start 49.06645 -235.380276)
		(end 49.06645 -235.32338)
		(width 0.14478)
		(layer "In6.Cu")
		(net "M_E_CPU1_SA_CB<0>")
	)
	(segment
		(start 38.864794 -235.160312)
		(end 40.769794 -235.160312)
		(width 0.14478)
		(layer "In6.Cu")
		(net "M_E_CPU1_SA_CB<0>")
	)
	(segment
		(start 77.030326 -244.296184)
		(end 77.591158 -244.857016)
		(width 0.0889)
		(layer "In6.Cu")
		(net "M_E_CPU1_SA_CB<0>")
	)
	(segment
		(start 41.489376 -235.32338)
		(end 41.652444 -235.160312)
		(width 0.14478)
		(layer "In6.Cu")
		(net "M_E_CPU1_SA_CB<0>")
	)
	(segment
		(start 54.730396 -235.385356)
		(end 54.893464 -235.548424)
		(width 0.14478)
		(layer "In6.Cu")
		(net "M_E_CPU1_SA_CB<0>")
	)
	(segment
		(start 54.084474 -235.160312)
		(end 54.567328 -235.160312)
		(width 0.14478)
		(layer "In6.Cu")
		(net "M_E_CPU1_SA_CB<0>")
	)
	(segment
		(start 67.647566 -244.077744)
		(end 75.960986 -244.077744)
		(width 0.14478)
		(layer "In6.Cu")
		(net "M_E_CPU1_SA_CB<0>")
	)
	(segment
		(start 80.89265 -244.83314)
		(end 80.915002 -244.749828)
		(width 0.0889)
		(layer "In6.Cu")
		(net "M_E_CPU1_SA_CB<0>")
	)
	(segment
		(start 55.123842 -235.548424)
		(end 55.28691 -235.385356)
		(width 0.14478)
		(layer "In6.Cu")
		(net "M_E_CPU1_SA_CB<0>")
	)
	(segment
		(start 58.605674 -234.473496)
		(end 58.605674 -234.531916)
		(width 0.14478)
		(layer "In6.Cu")
		(net "M_E_CPU1_SA_CB<0>")
	)
	(segment
		(start 48.509936 -235.32338)
		(end 48.509936 -235.380276)
		(width 0.14478)
		(layer "In6.Cu")
		(net "M_E_CPU1_SA_CB<0>")
	)
	(segment
		(start 41.652444 -235.160312)
		(end 41.96715 -235.160312)
		(width 0.14478)
		(layer "In6.Cu")
		(net "M_E_CPU1_SA_CB<0>")
	)
	(segment
		(start 33.366456 -235.548424)
		(end 33.596834 -235.548424)
		(width 0.14478)
		(layer "In6.Cu")
		(net "M_E_CPU1_SA_CB<0>")
	)
	(segment
		(start 55.680356 -235.160312)
		(end 55.843424 -235.32338)
		(width 0.14478)
		(layer "In6.Cu")
		(net "M_E_CPU1_SA_CB<0>")
	)
	(segment
		(start 55.843424 -235.32338)
		(end 55.843424 -235.385356)
		(width 0.14478)
		(layer "In6.Cu")
		(net "M_E_CPU1_SA_CB<0>")
	)
	(segment
		(start 54.893464 -235.548424)
		(end 55.123842 -235.548424)
		(width 0.14478)
		(layer "In6.Cu")
		(net "M_E_CPU1_SA_CB<0>")
	)
	(segment
		(start 61.868812 -238.29899)
		(end 67.647566 -244.077744)
		(width 0.14478)
		(layer "In6.Cu")
		(net "M_E_CPU1_SA_CB<0>")
	)
	(segment
		(start 80.915002 -244.749828)
		(end 80.761078 -244.484398)
		(width 0.0889)
		(layer "In6.Cu")
		(net "M_E_CPU1_SA_CB<0>")
	)
	(segment
		(start 59.325256 -234.310428)
		(end 59.555634 -234.310428)
		(width 0.14478)
		(layer "In6.Cu")
		(net "M_E_CPU1_SA_CB<0>")
	)
	(segment
		(start 49.58715 -235.160312)
		(end 50.437034 -234.310428)
		(width 0.14478)
		(layer "In6.Cu")
		(net "M_E_CPU1_SA_CB<0>")
	)
	(segment
		(start 49.229518 -235.160312)
		(end 49.58715 -235.160312)
		(width 0.14478)
		(layer "In6.Cu")
		(net "M_E_CPU1_SA_CB<0>")
	)
	(segment
		(start 54.730396 -235.32338)
		(end 54.730396 -235.385356)
		(width 0.14478)
		(layer "In6.Cu")
		(net "M_E_CPU1_SA_CB<0>")
	)
	(segment
		(start 40.769794 -235.160312)
		(end 40.932862 -235.32338)
		(width 0.14478)
		(layer "In6.Cu")
		(net "M_E_CPU1_SA_CB<0>")
	)
	(segment
		(start 30.809438 -235.022898)
		(end 30.809438 -235.297726)
		(width 0.14478)
		(layer "In6.Cu")
		(net "M_E_CPU1_SA_CB<0>")
	)
	(segment
		(start 55.843424 -235.385356)
		(end 56.006492 -235.548424)
		(width 0.14478)
		(layer "In6.Cu")
		(net "M_E_CPU1_SA_CB<0>")
	)
	(segment
		(start 40.932862 -235.32338)
		(end 40.932862 -235.380276)
		(width 0.14478)
		(layer "In6.Cu")
		(net "M_E_CPU1_SA_CB<0>")
	)
	(segment
		(start 33.203388 -235.32338)
		(end 33.203388 -235.385356)
		(width 0.14478)
		(layer "In6.Cu")
		(net "M_E_CPU1_SA_CB<0>")
	)
	(segment
		(start 45.69079 -234.310428)
		(end 46.540674 -235.160312)
		(width 0.14478)
		(layer "In6.Cu")
		(net "M_E_CPU1_SA_CB<0>")
	)
	(segment
		(start 57.13095 -235.160312)
		(end 57.980834 -234.310428)
		(width 0.14478)
		(layer "In6.Cu")
		(net "M_E_CPU1_SA_CB<0>")
	)
	(segment
		(start 57.980834 -234.310428)
		(end 58.442606 -234.310428)
		(width 0.14478)
		(layer "In6.Cu")
		(net "M_E_CPU1_SA_CB<0>")
	)
	(segment
		(start 41.96715 -235.160312)
		(end 42.817034 -234.310428)
		(width 0.14478)
		(layer "In6.Cu")
		(net "M_E_CPU1_SA_CB<0>")
	)
	(segment
		(start 59.162188 -234.473496)
		(end 59.325256 -234.310428)
		(width 0.14478)
		(layer "In6.Cu")
		(net "M_E_CPU1_SA_CB<0>")
	)
	(segment
		(start 78.128368 -244.806978)
		(end 78.1431 -244.798342)
		(width 0.0889)
		(layer "In6.Cu")
		(net "M_E_CPU1_SA_CB<0>")
	)
	(segment
		(start 59.162188 -234.531916)
		(end 59.162188 -234.473496)
		(width 0.14478)
		(layer "In6.Cu")
		(net "M_E_CPU1_SA_CB<0>")
	)
	(segment
		(start 58.99912 -234.694984)
		(end 59.162188 -234.531916)
		(width 0.14478)
		(layer "In6.Cu")
		(net "M_E_CPU1_SA_CB<0>")
	)
	(segment
		(start 53.23459 -234.310428)
		(end 54.084474 -235.160312)
		(width 0.14478)
		(layer "In6.Cu")
		(net "M_E_CPU1_SA_CB<0>")
	)
	(segment
		(start 55.28691 -235.385356)
		(end 55.28691 -235.32338)
		(width 0.14478)
		(layer "In6.Cu")
		(net "M_E_CPU1_SA_CB<0>")
	)
	(segment
		(start 41.489376 -235.380276)
		(end 41.489376 -235.32338)
		(width 0.14478)
		(layer "In6.Cu")
		(net "M_E_CPU1_SA_CB<0>")
	)
	(segment
		(start 56.399938 -235.385356)
		(end 56.399938 -235.32338)
		(width 0.14478)
		(layer "In6.Cu")
		(net "M_E_CPU1_SA_CB<0>")
	)
	(segment
		(start 56.563006 -235.160312)
		(end 57.13095 -235.160312)
		(width 0.14478)
		(layer "In6.Cu")
		(net "M_E_CPU1_SA_CB<0>")
	)
	(segment
		(start 30.672024 -234.885484)
		(end 30.809438 -235.022898)
		(width 0.14478)
		(layer "In6.Cu")
		(net "M_E_CPU1_SA_CB<0>")
	)
	(segment
		(start 59.718702 -234.473496)
		(end 59.718702 -234.531916)
		(width 0.14478)
		(layer "In6.Cu")
		(net "M_E_CPU1_SA_CB<0>")
	)
	(segment
		(start 58.442606 -234.310428)
		(end 58.605674 -234.473496)
		(width 0.14478)
		(layer "In6.Cu")
		(net "M_E_CPU1_SA_CB<0>")
	)
	(segment
		(start 58.605674 -234.531916)
		(end 58.768742 -234.694984)
		(width 0.14478)
		(layer "In6.Cu")
		(net "M_E_CPU1_SA_CB<0>")
	)
	(segment
		(start 55.28691 -235.32338)
		(end 55.449978 -235.160312)
		(width 0.14478)
		(layer "In6.Cu")
		(net "M_E_CPU1_SA_CB<0>")
	)
	(segment
		(start 33.759902 -235.32338)
		(end 33.92297 -235.160312)
		(width 0.14478)
		(layer "In6.Cu")
		(net "M_E_CPU1_SA_CB<0>")
	)
	(segment
		(start 31.503366 -234.885484)
		(end 31.785052 -234.885484)
		(width 0.14478)
		(layer "In6.Cu")
		(net "M_E_CPU1_SA_CB<0>")
	)
	(segment
		(start 31.785052 -234.885484)
		(end 32.05988 -235.160312)
		(width 0.14478)
		(layer "In6.Cu")
		(net "M_E_CPU1_SA_CB<0>")
	)
	(segment
		(start 40.932862 -235.380276)
		(end 41.09593 -235.543344)
		(width 0.14478)
		(layer "In6.Cu")
		(net "M_E_CPU1_SA_CB<0>")
	)
	(segment
		(start 33.04032 -235.160312)
		(end 33.203388 -235.32338)
		(width 0.14478)
		(layer "In6.Cu")
		(net "M_E_CPU1_SA_CB<0>")
	)
	(segment
		(start 59.718702 -234.531916)
		(end 59.88177 -234.694984)
		(width 0.14478)
		(layer "In6.Cu")
		(net "M_E_CPU1_SA_CB<0>")
	)
	(segment
		(start 31.365952 -235.022898)
		(end 31.503366 -234.885484)
		(width 0.14478)
		(layer "In6.Cu")
		(net "M_E_CPU1_SA_CB<0>")
	)
	(segment
		(start 29.677106 -235.160312)
		(end 30.11551 -235.160312)
		(width 0.14478)
		(layer "In6.Cu")
		(net "M_E_CPU1_SA_CB<0>")
	)
	(segment
		(start 48.346868 -235.160312)
		(end 48.509936 -235.32338)
		(width 0.14478)
		(layer "In6.Cu")
		(net "M_E_CPU1_SA_CB<0>")
	)
	(segment
		(start 48.509936 -235.380276)
		(end 48.673004 -235.543344)
		(width 0.14478)
		(layer "In6.Cu")
		(net "M_E_CPU1_SA_CB<0>")
	)
	(segment
		(start 79.623666 -244.800882)
		(end 79.63408 -244.806978)
		(width 0.0889)
		(layer "In6.Cu")
		(net "M_E_CPU1_SA_CB<0>")
	)
	(segment
		(start 75.960986 -244.077744)
		(end 76.258166 -244.077744)
		(width 0.0889)
		(layer "In6.Cu")
		(net "M_E_CPU1_SA_CB<0>")
	)
	(arc
		(start 77.942186 -244.857016)
		(mid 78.03856 -244.844219)
		(end 78.128368 -244.806978)
		(width 0.0889)
		(layer "In6.Cu")
		(net "M_E_CPU1_SA_CB<0>")
	)
	(arc
		(start 78.69428 -244.806978)
		(mid 78.876531 -244.857328)
		(end 79.06004 -244.811804)
		(width 0.0889)
		(layer "In6.Cu")
		(net "M_E_CPU1_SA_CB<0>")
	)
	(arc
		(start 79.068422 -244.806978)
		(mid 79.345235 -244.730835)
		(end 79.623666 -244.800882)
		(width 0.0889)
		(layer "In6.Cu")
		(net "M_E_CPU1_SA_CB<0>")
	)
	(arc
		(start 80.574134 -244.806978)
		(mid 80.730453 -244.855973)
		(end 80.89265 -244.83314)
		(width 0.0889)
		(layer "In6.Cu")
		(net "M_E_CPU1_SA_CB<0>")
	)
	(arc
		(start 79.642462 -244.811804)
		(mid 79.82597 -244.857298)
		(end 80.008222 -244.806978)
		(width 0.0889)
		(layer "In6.Cu")
		(net "M_E_CPU1_SA_CB<0>")
	)
	(arc
		(start 80.008222 -244.806978)
		(mid 80.291178 -244.730801)
		(end 80.574134 -244.806978)
		(width 0.0889)
		(layer "In6.Cu")
		(net "M_E_CPU1_SA_CB<0>")
	)
	(arc
		(start 78.1431 -244.798342)
		(mid 78.419829 -244.730659)
		(end 78.69428 -244.806978)
		(width 0.0889)
		(layer "In6.Cu")
		(net "M_E_CPU1_SA_CB<0>")
	)
	(segment
		(start 82.637884 -255.280414)
		(end 82.171032 -255.014476)
		(width 0.10668)
		(layer "F.Cu")
		(net "M_E_CPU1_SA_CA<6>")
	)
	(segment
		(start 76.682346 -255.589024)
		(end 77.162406 -255.589024)
		(width 0.0889)
		(layer "In6.Cu")
		(net "M_E_CPU1_SA_CA<6>")
	)
	(segment
		(start 77.46365 -255.28778)
		(end 78.150212 -255.28778)
		(width 0.0889)
		(layer "In6.Cu")
		(net "M_E_CPU1_SA_CA<6>")
	)
	(segment
		(start 30.498796 -254.797306)
		(end 30.661864 -254.960374)
		(width 0.14478)
		(layer "In6.Cu")
		(net "M_E_CPU1_SA_CA<6>")
	)
	(segment
		(start 29.963618 -253.527052)
		(end 29.711396 -253.779274)
		(width 0.14478)
		(layer "In6.Cu")
		(net "M_E_CPU1_SA_CA<6>")
	)
	(segment
		(start 30.105096 -254.173228)
		(end 30.357318 -253.921006)
		(width 0.14478)
		(layer "In6.Cu")
		(net "M_E_CPU1_SA_CA<6>")
	)
	(segment
		(start 79.52994 -255.341882)
		(end 79.538322 -255.337056)
		(width 0.0889)
		(layer "In6.Cu")
		(net "M_E_CPU1_SA_CA<6>")
	)
	(segment
		(start 31.37535 -254.708406)
		(end 31.377382 -254.710438)
		(width 0.14478)
		(layer "In6.Cu")
		(net "M_E_CPU1_SA_CA<6>")
	)
	(segment
		(start 30.661864 -254.960374)
		(end 30.892496 -254.960628)
		(width 0.14478)
		(layer "In6.Cu")
		(net "M_E_CPU1_SA_CA<6>")
	)
	(segment
		(start 81.044034 -255.337056)
		(end 81.052416 -255.341882)
		(width 0.0889)
		(layer "In6.Cu")
		(net "M_E_CPU1_SA_CA<6>")
	)
	(segment
		(start 30.892496 -254.960628)
		(end 31.144718 -254.708406)
		(width 0.14478)
		(layer "In6.Cu")
		(net "M_E_CPU1_SA_CA<6>")
	)
	(segment
		(start 57.880758 -254.710438)
		(end 57.891172 -254.700024)
		(width 0.14478)
		(layer "In6.Cu")
		(net "M_E_CPU1_SA_CA<6>")
	)
	(segment
		(start 77.162406 -255.589024)
		(end 77.46365 -255.28778)
		(width 0.0889)
		(layer "In6.Cu")
		(net "M_E_CPU1_SA_CA<6>")
	)
	(segment
		(start 29.963872 -253.296928)
		(end 29.963618 -253.527052)
		(width 0.14478)
		(layer "In6.Cu")
		(net "M_E_CPU1_SA_CA<6>")
	)
	(segment
		(start 82.302604 -255.363218)
		(end 82.324956 -255.279906)
		(width 0.0889)
		(layer "In6.Cu")
		(net "M_E_CPU1_SA_CA<6>")
	)
	(segment
		(start 80.46974 -255.341882)
		(end 80.478122 -255.337056)
		(width 0.0889)
		(layer "In6.Cu")
		(net "M_E_CPU1_SA_CA<6>")
	)
	(segment
		(start 30.751272 -254.084328)
		(end 30.751018 -254.314452)
		(width 0.14478)
		(layer "In6.Cu")
		(net "M_E_CPU1_SA_CA<6>")
	)
	(segment
		(start 29.711396 -254.009906)
		(end 29.874464 -254.172974)
		(width 0.14478)
		(layer "In6.Cu")
		(net "M_E_CPU1_SA_CA<6>")
	)
	(segment
		(start 30.498796 -254.566674)
		(end 30.498796 -254.797306)
		(width 0.14478)
		(layer "In6.Cu")
		(net "M_E_CPU1_SA_CA<6>")
	)
	(segment
		(start 57.891172 -254.700024)
		(end 71.722742 -254.700024)
		(width 0.14478)
		(layer "In6.Cu")
		(net "M_E_CPU1_SA_CA<6>")
	)
	(segment
		(start 30.58795 -253.921006)
		(end 30.751272 -254.084328)
		(width 0.14478)
		(layer "In6.Cu")
		(net "M_E_CPU1_SA_CA<6>")
	)
	(segment
		(start 82.324956 -255.279906)
		(end 82.171032 -255.014476)
		(width 0.0889)
		(layer "In6.Cu")
		(net "M_E_CPU1_SA_CA<6>")
	)
	(segment
		(start 30.357318 -253.921006)
		(end 30.58795 -253.921006)
		(width 0.14478)
		(layer "In6.Cu")
		(net "M_E_CPU1_SA_CA<6>")
	)
	(segment
		(start 76.225146 -256.046224)
		(end 76.682346 -255.589024)
		(width 0.0889)
		(layer "In6.Cu")
		(net "M_E_CPU1_SA_CA<6>")
	)
	(segment
		(start 29.874464 -254.172974)
		(end 30.105096 -254.173228)
		(width 0.14478)
		(layer "In6.Cu")
		(net "M_E_CPU1_SA_CA<6>")
	)
	(segment
		(start 29.711396 -253.779274)
		(end 29.711396 -254.009906)
		(width 0.14478)
		(layer "In6.Cu")
		(net "M_E_CPU1_SA_CA<6>")
	)
	(segment
		(start 79.538322 -255.337056)
		(end 79.548736 -255.33096)
		(width 0.0889)
		(layer "In6.Cu")
		(net "M_E_CPU1_SA_CA<6>")
	)
	(segment
		(start 30.751018 -254.314452)
		(end 30.498796 -254.566674)
		(width 0.14478)
		(layer "In6.Cu")
		(net "M_E_CPU1_SA_CA<6>")
	)
	(segment
		(start 75.968606 -256.046224)
		(end 76.225146 -256.046224)
		(width 0.0889)
		(layer "In6.Cu")
		(net "M_E_CPU1_SA_CA<6>")
	)
	(segment
		(start 79.154274 -255.33096)
		(end 79.164688 -255.337056)
		(width 0.0889)
		(layer "In6.Cu")
		(net "M_E_CPU1_SA_CA<6>")
	)
	(segment
		(start 31.377382 -254.710438)
		(end 57.880758 -254.710438)
		(width 0.14478)
		(layer "In6.Cu")
		(net "M_E_CPU1_SA_CA<6>")
	)
	(segment
		(start 71.722742 -254.700024)
		(end 73.068942 -256.046224)
		(width 0.14478)
		(layer "In6.Cu")
		(net "M_E_CPU1_SA_CA<6>")
	)
	(segment
		(start 31.144718 -254.708406)
		(end 31.37535 -254.708406)
		(width 0.14478)
		(layer "In6.Cu")
		(net "M_E_CPU1_SA_CA<6>")
	)
	(segment
		(start 29.252164 -252.58522)
		(end 29.963872 -253.296928)
		(width 0.14478)
		(layer "In6.Cu")
		(net "M_E_CPU1_SA_CA<6>")
	)
	(segment
		(start 73.068942 -256.046224)
		(end 75.968606 -256.046224)
		(width 0.14478)
		(layer "In6.Cu")
		(net "M_E_CPU1_SA_CA<6>")
	)
	(segment
		(start 78.150212 -255.28778)
		(end 78.22438 -255.336802)
		(width 0.0889)
		(layer "In6.Cu")
		(net "M_E_CPU1_SA_CA<6>")
	)
	(segment
		(start 78.22438 -255.336802)
		(end 78.242668 -255.347216)
		(width 0.0889)
		(layer "In6.Cu")
		(net "M_E_CPU1_SA_CA<6>")
	)
	(arc
		(start 81.418176 -255.337056)
		(mid 81.701132 -255.260879)
		(end 81.984088 -255.337056)
		(width 0.0889)
		(layer "In6.Cu")
		(net "M_E_CPU1_SA_CA<6>")
	)
	(arc
		(start 81.052416 -255.341882)
		(mid 81.235924 -255.387376)
		(end 81.418176 -255.337056)
		(width 0.0889)
		(layer "In6.Cu")
		(net "M_E_CPU1_SA_CA<6>")
	)
	(arc
		(start 79.548736 -255.33096)
		(mid 79.827168 -255.260862)
		(end 80.10398 -255.337056)
		(width 0.0889)
		(layer "In6.Cu")
		(net "M_E_CPU1_SA_CA<6>")
	)
	(arc
		(start 78.242668 -255.347216)
		(mid 78.421897 -255.387369)
		(end 78.598522 -255.337056)
		(width 0.0889)
		(layer "In6.Cu")
		(net "M_E_CPU1_SA_CA<6>")
	)
	(arc
		(start 79.164688 -255.337056)
		(mid 79.346685 -255.387278)
		(end 79.52994 -255.341882)
		(width 0.0889)
		(layer "In6.Cu")
		(net "M_E_CPU1_SA_CA<6>")
	)
	(arc
		(start 81.984088 -255.337056)
		(mid 82.140407 -255.386051)
		(end 82.302604 -255.363218)
		(width 0.0889)
		(layer "In6.Cu")
		(net "M_E_CPU1_SA_CA<6>")
	)
	(arc
		(start 78.598522 -255.337056)
		(mid 78.875589 -255.260785)
		(end 79.154274 -255.33096)
		(width 0.0889)
		(layer "In6.Cu")
		(net "M_E_CPU1_SA_CA<6>")
	)
	(arc
		(start 80.10398 -255.337056)
		(mid 80.286231 -255.387406)
		(end 80.46974 -255.341882)
		(width 0.0889)
		(layer "In6.Cu")
		(net "M_E_CPU1_SA_CA<6>")
	)
	(arc
		(start 80.478122 -255.337056)
		(mid 80.761078 -255.260879)
		(end 81.044034 -255.337056)
		(width 0.0889)
		(layer "In6.Cu")
		(net "M_E_CPU1_SA_CA<6>")
	)
	(segment
		(start 81.69783 -255.280414)
		(end 81.230978 -255.014476)
		(width 0.10668)
		(layer "F.Cu")
		(net "M_E_CPU1_SA_CA<5>")
	)
	(segment
		(start 25.152096 -251.735336)
		(end 25.577038 -252.160278)
		(width 0.14478)
		(layer "In6.Cu")
		(net "M_E_CPU1_SA_CA<5>")
	)
	(segment
		(start 59.846464 -253.8603)
		(end 60.231528 -254.245364)
		(width 0.14478)
		(layer "In6.Cu")
		(net "M_E_CPU1_SA_CA<5>")
	)
	(segment
		(start 60.231528 -254.245364)
		(end 71.91121 -254.245364)
		(width 0.14478)
		(layer "In6.Cu")
		(net "M_E_CPU1_SA_CA<5>")
	)
	(segment
		(start 73.22693 -255.561084)
		(end 75.991466 -255.561084)
		(width 0.14478)
		(layer "In6.Cu")
		(net "M_E_CPU1_SA_CA<5>")
	)
	(segment
		(start 31.31312 -253.8603)
		(end 59.846464 -253.8603)
		(width 0.14478)
		(layer "In6.Cu")
		(net "M_E_CPU1_SA_CA<5>")
	)
	(segment
		(start 76.184506 -255.561084)
		(end 76.646786 -255.098804)
		(width 0.0889)
		(layer "In6.Cu")
		(net "M_E_CPU1_SA_CA<5>")
	)
	(segment
		(start 81.077054 -254.749046)
		(end 81.230978 -255.014476)
		(width 0.0889)
		(layer "In6.Cu")
		(net "M_E_CPU1_SA_CA<5>")
	)
	(segment
		(start 25.577038 -252.160278)
		(end 29.613098 -252.160278)
		(width 0.14478)
		(layer "In6.Cu")
		(net "M_E_CPU1_SA_CA<5>")
	)
	(segment
		(start 29.613098 -252.160278)
		(end 31.31312 -253.8603)
		(width 0.14478)
		(layer "In6.Cu")
		(net "M_E_CPU1_SA_CA<5>")
	)
	(segment
		(start 79.15402 -254.697992)
		(end 79.164434 -254.691896)
		(width 0.0889)
		(layer "In6.Cu")
		(net "M_E_CPU1_SA_CA<5>")
	)
	(segment
		(start 77.451204 -254.774446)
		(end 77.65669 -254.767588)
		(width 0.0889)
		(layer "In6.Cu")
		(net "M_E_CPU1_SA_CA<5>")
	)
	(segment
		(start 71.91121 -254.245364)
		(end 73.22693 -255.561084)
		(width 0.14478)
		(layer "In6.Cu")
		(net "M_E_CPU1_SA_CA<5>")
	)
	(segment
		(start 80.46974 -254.68707)
		(end 80.478122 -254.691896)
		(width 0.0889)
		(layer "In6.Cu")
		(net "M_E_CPU1_SA_CA<5>")
	)
	(segment
		(start 79.538322 -254.691896)
		(end 79.548736 -254.697992)
		(width 0.0889)
		(layer "In6.Cu")
		(net "M_E_CPU1_SA_CA<5>")
	)
	(segment
		(start 78.22438 -254.691896)
		(end 78.236064 -254.685038)
		(width 0.0889)
		(layer "In6.Cu")
		(net "M_E_CPU1_SA_CA<5>")
	)
	(segment
		(start 77.65669 -254.767588)
		(end 77.942186 -254.767588)
		(width 0.0889)
		(layer "In6.Cu")
		(net "M_E_CPU1_SA_CA<5>")
	)
	(segment
		(start 80.981042 -254.723646)
		(end 81.077054 -254.749046)
		(width 0.0889)
		(layer "In6.Cu")
		(net "M_E_CPU1_SA_CA<5>")
	)
	(segment
		(start 75.991466 -255.561084)
		(end 76.184506 -255.561084)
		(width 0.0889)
		(layer "In6.Cu")
		(net "M_E_CPU1_SA_CA<5>")
	)
	(segment
		(start 77.126846 -255.098804)
		(end 77.451204 -254.774446)
		(width 0.0889)
		(layer "In6.Cu")
		(net "M_E_CPU1_SA_CA<5>")
	)
	(segment
		(start 76.646786 -255.098804)
		(end 77.126846 -255.098804)
		(width 0.0889)
		(layer "In6.Cu")
		(net "M_E_CPU1_SA_CA<5>")
	)
	(arc
		(start 80.478122 -254.691896)
		(mid 80.725835 -254.767116)
		(end 80.981042 -254.723646)
		(width 0.0889)
		(layer "In6.Cu")
		(net "M_E_CPU1_SA_CA<5>")
	)
	(arc
		(start 77.942186 -254.767588)
		(mid 78.08827 -254.748336)
		(end 78.22438 -254.691896)
		(width 0.0889)
		(layer "In6.Cu")
		(net "M_E_CPU1_SA_CA<5>")
	)
	(arc
		(start 79.164434 -254.691896)
		(mid 79.351378 -254.641641)
		(end 79.538322 -254.691896)
		(width 0.0889)
		(layer "In6.Cu")
		(net "M_E_CPU1_SA_CA<5>")
	)
	(arc
		(start 80.10398 -254.691896)
		(mid 80.286231 -254.641546)
		(end 80.46974 -254.68707)
		(width 0.0889)
		(layer "In6.Cu")
		(net "M_E_CPU1_SA_CA<5>")
	)
	(arc
		(start 78.598268 -254.691896)
		(mid 78.875335 -254.768167)
		(end 79.15402 -254.697992)
		(width 0.0889)
		(layer "In6.Cu")
		(net "M_E_CPU1_SA_CA<5>")
	)
	(arc
		(start 78.236064 -254.685038)
		(mid 78.418065 -254.641505)
		(end 78.598268 -254.691896)
		(width 0.0889)
		(layer "In6.Cu")
		(net "M_E_CPU1_SA_CA<5>")
	)
	(arc
		(start 79.548736 -254.697992)
		(mid 79.827168 -254.76809)
		(end 80.10398 -254.691896)
		(width 0.0889)
		(layer "In6.Cu")
		(net "M_E_CPU1_SA_CA<5>")
	)
	(segment
		(start 81.22793 -254.470408)
		(end 80.761078 -254.20447)
		(width 0.10668)
		(layer "F.Cu")
		(net "M_E_CPU1_SA_CA<4>")
	)
	(segment
		(start 39.323264 -253.402084)
		(end 39.486332 -253.239016)
		(width 0.14478)
		(layer "In6.Cu")
		(net "M_E_CPU1_SA_CA<4>")
	)
	(segment
		(start 78.128368 -254.52705)
		(end 78.1431 -254.518414)
		(width 0.0889)
		(layer "In6.Cu")
		(net "M_E_CPU1_SA_CA<4>")
	)
	(segment
		(start 76.441046 -254.854964)
		(end 77.020166 -254.854964)
		(width 0.0889)
		(layer "In6.Cu")
		(net "M_E_CPU1_SA_CA<4>")
	)
	(segment
		(start 38.210236 -253.402084)
		(end 38.373304 -253.239016)
		(width 0.14478)
		(layer "In6.Cu")
		(net "M_E_CPU1_SA_CA<4>")
	)
	(segment
		(start 77.303884 -254.571246)
		(end 77.65669 -254.577088)
		(width 0.0889)
		(layer "In6.Cu")
		(net "M_E_CPU1_SA_CA<4>")
	)
	(segment
		(start 37.81679 -253.17323)
		(end 37.81679 -253.239016)
		(width 0.14478)
		(layer "In6.Cu")
		(net "M_E_CPU1_SA_CA<4>")
	)
	(segment
		(start 33.368488 -253.010162)
		(end 33.531556 -253.17323)
		(width 0.14478)
		(layer "In6.Cu")
		(net "M_E_CPU1_SA_CA<4>")
	)
	(segment
		(start 35.201098 -253.17323)
		(end 35.364166 -253.010162)
		(width 0.14478)
		(layer "In6.Cu")
		(net "M_E_CPU1_SA_CA<4>")
	)
	(segment
		(start 41.38549 -253.17323)
		(end 41.38549 -253.239016)
		(width 0.14478)
		(layer "In6.Cu")
		(net "M_E_CPU1_SA_CA<4>")
	)
	(segment
		(start 43.055032 -253.239016)
		(end 43.055032 -253.17323)
		(width 0.14478)
		(layer "In6.Cu")
		(net "M_E_CPU1_SA_CA<4>")
	)
	(segment
		(start 79.63408 -254.52705)
		(end 79.642462 -254.531876)
		(width 0.0889)
		(layer "In6.Cu")
		(net "M_E_CPU1_SA_CA<4>")
	)
	(segment
		(start 39.486332 -253.239016)
		(end 39.486332 -253.17323)
		(width 0.14478)
		(layer "In6.Cu")
		(net "M_E_CPU1_SA_CA<4>")
	)
	(segment
		(start 42.33545 -253.010162)
		(end 42.498518 -253.17323)
		(width 0.14478)
		(layer "In6.Cu")
		(net "M_E_CPU1_SA_CA<4>")
	)
	(segment
		(start 59.83605 -253.010162)
		(end 60.616592 -253.790704)
		(width 0.14478)
		(layer "In6.Cu")
		(net "M_E_CPU1_SA_CA<4>")
	)
	(segment
		(start 42.661586 -253.402084)
		(end 42.891964 -253.402084)
		(width 0.14478)
		(layer "In6.Cu")
		(net "M_E_CPU1_SA_CA<4>")
	)
	(segment
		(start 42.891964 -253.402084)
		(end 43.055032 -253.239016)
		(width 0.14478)
		(layer "In6.Cu")
		(net "M_E_CPU1_SA_CA<4>")
	)
	(segment
		(start 46.104048 -253.17323)
		(end 46.267116 -253.010162)
		(width 0.14478)
		(layer "In6.Cu")
		(net "M_E_CPU1_SA_CA<4>")
	)
	(segment
		(start 39.486332 -253.17323)
		(end 39.6494 -253.010162)
		(width 0.14478)
		(layer "In6.Cu")
		(net "M_E_CPU1_SA_CA<4>")
	)
	(segment
		(start 37.653722 -253.010162)
		(end 37.81679 -253.17323)
		(width 0.14478)
		(layer "In6.Cu")
		(net "M_E_CPU1_SA_CA<4>")
	)
	(segment
		(start 34.807652 -253.402084)
		(end 35.03803 -253.402084)
		(width 0.14478)
		(layer "In6.Cu")
		(net "M_E_CPU1_SA_CA<4>")
	)
	(segment
		(start 39.6494 -253.010162)
		(end 41.222422 -253.010162)
		(width 0.14478)
		(layer "In6.Cu")
		(net "M_E_CPU1_SA_CA<4>")
	)
	(segment
		(start 34.08807 -253.239016)
		(end 34.08807 -253.17323)
		(width 0.14478)
		(layer "In6.Cu")
		(net "M_E_CPU1_SA_CA<4>")
	)
	(segment
		(start 77.65669 -254.577088)
		(end 77.942186 -254.577088)
		(width 0.0889)
		(layer "In6.Cu")
		(net "M_E_CPU1_SA_CA<4>")
	)
	(segment
		(start 31.377128 -253.010162)
		(end 33.368488 -253.010162)
		(width 0.14478)
		(layer "In6.Cu")
		(net "M_E_CPU1_SA_CA<4>")
	)
	(segment
		(start 38.373304 -253.239016)
		(end 38.373304 -253.17323)
		(width 0.14478)
		(layer "In6.Cu")
		(net "M_E_CPU1_SA_CA<4>")
	)
	(segment
		(start 42.498518 -253.239016)
		(end 42.661586 -253.402084)
		(width 0.14478)
		(layer "In6.Cu")
		(net "M_E_CPU1_SA_CA<4>")
	)
	(segment
		(start 80.89265 -254.553212)
		(end 80.915002 -254.4699)
		(width 0.0889)
		(layer "In6.Cu")
		(net "M_E_CPU1_SA_CA<4>")
	)
	(segment
		(start 45.710602 -253.399544)
		(end 45.94098 -253.399544)
		(width 0.14478)
		(layer "In6.Cu")
		(net "M_E_CPU1_SA_CA<4>")
	)
	(segment
		(start 37.81679 -253.239016)
		(end 37.979858 -253.402084)
		(width 0.14478)
		(layer "In6.Cu")
		(net "M_E_CPU1_SA_CA<4>")
	)
	(segment
		(start 35.364166 -253.010162)
		(end 37.653722 -253.010162)
		(width 0.14478)
		(layer "In6.Cu")
		(net "M_E_CPU1_SA_CA<4>")
	)
	(segment
		(start 73.415398 -255.106424)
		(end 76.009246 -255.106424)
		(width 0.14478)
		(layer "In6.Cu")
		(net "M_E_CPU1_SA_CA<4>")
	)
	(segment
		(start 41.222422 -253.010162)
		(end 41.38549 -253.17323)
		(width 0.14478)
		(layer "In6.Cu")
		(net "M_E_CPU1_SA_CA<4>")
	)
	(segment
		(start 38.929818 -253.17323)
		(end 38.929818 -253.239016)
		(width 0.14478)
		(layer "In6.Cu")
		(net "M_E_CPU1_SA_CA<4>")
	)
	(segment
		(start 79.623666 -254.520954)
		(end 79.63408 -254.52705)
		(width 0.0889)
		(layer "In6.Cu")
		(net "M_E_CPU1_SA_CA<4>")
	)
	(segment
		(start 79.06004 -254.531876)
		(end 79.068422 -254.52705)
		(width 0.0889)
		(layer "In6.Cu")
		(net "M_E_CPU1_SA_CA<4>")
	)
	(segment
		(start 77.020166 -254.854964)
		(end 77.303884 -254.571246)
		(width 0.0889)
		(layer "In6.Cu")
		(net "M_E_CPU1_SA_CA<4>")
	)
	(segment
		(start 42.105072 -253.010162)
		(end 42.33545 -253.010162)
		(width 0.14478)
		(layer "In6.Cu")
		(net "M_E_CPU1_SA_CA<4>")
	)
	(segment
		(start 45.547534 -253.236476)
		(end 45.710602 -253.399544)
		(width 0.14478)
		(layer "In6.Cu")
		(net "M_E_CPU1_SA_CA<4>")
	)
	(segment
		(start 41.778936 -253.402084)
		(end 41.942004 -253.239016)
		(width 0.14478)
		(layer "In6.Cu")
		(net "M_E_CPU1_SA_CA<4>")
	)
	(segment
		(start 34.08807 -253.17323)
		(end 34.251138 -253.010162)
		(width 0.14478)
		(layer "In6.Cu")
		(net "M_E_CPU1_SA_CA<4>")
	)
	(segment
		(start 33.694624 -253.402084)
		(end 33.925002 -253.402084)
		(width 0.14478)
		(layer "In6.Cu")
		(net "M_E_CPU1_SA_CA<4>")
	)
	(segment
		(start 34.251138 -253.010162)
		(end 34.481516 -253.010162)
		(width 0.14478)
		(layer "In6.Cu")
		(net "M_E_CPU1_SA_CA<4>")
	)
	(segment
		(start 34.644584 -253.17323)
		(end 34.644584 -253.239016)
		(width 0.14478)
		(layer "In6.Cu")
		(net "M_E_CPU1_SA_CA<4>")
	)
	(segment
		(start 46.104048 -253.236476)
		(end 46.104048 -253.17323)
		(width 0.14478)
		(layer "In6.Cu")
		(net "M_E_CPU1_SA_CA<4>")
	)
	(segment
		(start 41.942004 -253.239016)
		(end 41.942004 -253.17323)
		(width 0.14478)
		(layer "In6.Cu")
		(net "M_E_CPU1_SA_CA<4>")
	)
	(segment
		(start 41.38549 -253.239016)
		(end 41.548558 -253.402084)
		(width 0.14478)
		(layer "In6.Cu")
		(net "M_E_CPU1_SA_CA<4>")
	)
	(segment
		(start 45.94098 -253.399544)
		(end 46.104048 -253.236476)
		(width 0.14478)
		(layer "In6.Cu")
		(net "M_E_CPU1_SA_CA<4>")
	)
	(segment
		(start 38.929818 -253.239016)
		(end 39.092886 -253.402084)
		(width 0.14478)
		(layer "In6.Cu")
		(net "M_E_CPU1_SA_CA<4>")
	)
	(segment
		(start 37.979858 -253.402084)
		(end 38.210236 -253.402084)
		(width 0.14478)
		(layer "In6.Cu")
		(net "M_E_CPU1_SA_CA<4>")
	)
	(segment
		(start 33.925002 -253.402084)
		(end 34.08807 -253.239016)
		(width 0.14478)
		(layer "In6.Cu")
		(net "M_E_CPU1_SA_CA<4>")
	)
	(segment
		(start 38.373304 -253.17323)
		(end 38.536372 -253.010162)
		(width 0.14478)
		(layer "In6.Cu")
		(net "M_E_CPU1_SA_CA<4>")
	)
	(segment
		(start 33.531556 -253.17323)
		(end 33.531556 -253.239016)
		(width 0.14478)
		(layer "In6.Cu")
		(net "M_E_CPU1_SA_CA<4>")
	)
	(segment
		(start 72.099678 -253.790704)
		(end 73.415398 -255.106424)
		(width 0.14478)
		(layer "In6.Cu")
		(net "M_E_CPU1_SA_CA<4>")
	)
	(segment
		(start 34.481516 -253.010162)
		(end 34.644584 -253.17323)
		(width 0.14478)
		(layer "In6.Cu")
		(net "M_E_CPU1_SA_CA<4>")
	)
	(segment
		(start 76.189586 -255.106424)
		(end 76.441046 -254.854964)
		(width 0.0889)
		(layer "In6.Cu")
		(net "M_E_CPU1_SA_CA<4>")
	)
	(segment
		(start 34.644584 -253.239016)
		(end 34.807652 -253.402084)
		(width 0.14478)
		(layer "In6.Cu")
		(net "M_E_CPU1_SA_CA<4>")
	)
	(segment
		(start 76.009246 -255.106424)
		(end 76.189586 -255.106424)
		(width 0.0889)
		(layer "In6.Cu")
		(net "M_E_CPU1_SA_CA<4>")
	)
	(segment
		(start 60.616592 -253.790704)
		(end 72.099678 -253.790704)
		(width 0.14478)
		(layer "In6.Cu")
		(net "M_E_CPU1_SA_CA<4>")
	)
	(segment
		(start 43.2181 -253.010162)
		(end 45.384466 -253.010162)
		(width 0.14478)
		(layer "In6.Cu")
		(net "M_E_CPU1_SA_CA<4>")
	)
	(segment
		(start 41.942004 -253.17323)
		(end 42.105072 -253.010162)
		(width 0.14478)
		(layer "In6.Cu")
		(net "M_E_CPU1_SA_CA<4>")
	)
	(segment
		(start 45.547534 -253.17323)
		(end 45.547534 -253.236476)
		(width 0.14478)
		(layer "In6.Cu")
		(net "M_E_CPU1_SA_CA<4>")
	)
	(segment
		(start 33.531556 -253.239016)
		(end 33.694624 -253.402084)
		(width 0.14478)
		(layer "In6.Cu")
		(net "M_E_CPU1_SA_CA<4>")
	)
	(segment
		(start 41.548558 -253.402084)
		(end 41.778936 -253.402084)
		(width 0.14478)
		(layer "In6.Cu")
		(net "M_E_CPU1_SA_CA<4>")
	)
	(segment
		(start 35.201098 -253.239016)
		(end 35.201098 -253.17323)
		(width 0.14478)
		(layer "In6.Cu")
		(net "M_E_CPU1_SA_CA<4>")
	)
	(segment
		(start 45.384466 -253.010162)
		(end 45.547534 -253.17323)
		(width 0.14478)
		(layer "In6.Cu")
		(net "M_E_CPU1_SA_CA<4>")
	)
	(segment
		(start 43.055032 -253.17323)
		(end 43.2181 -253.010162)
		(width 0.14478)
		(layer "In6.Cu")
		(net "M_E_CPU1_SA_CA<4>")
	)
	(segment
		(start 39.092886 -253.402084)
		(end 39.323264 -253.402084)
		(width 0.14478)
		(layer "In6.Cu")
		(net "M_E_CPU1_SA_CA<4>")
	)
	(segment
		(start 38.536372 -253.010162)
		(end 38.76675 -253.010162)
		(width 0.14478)
		(layer "In6.Cu")
		(net "M_E_CPU1_SA_CA<4>")
	)
	(segment
		(start 38.76675 -253.010162)
		(end 38.929818 -253.17323)
		(width 0.14478)
		(layer "In6.Cu")
		(net "M_E_CPU1_SA_CA<4>")
	)
	(segment
		(start 46.267116 -253.010162)
		(end 59.83605 -253.010162)
		(width 0.14478)
		(layer "In6.Cu")
		(net "M_E_CPU1_SA_CA<4>")
	)
	(segment
		(start 35.03803 -253.402084)
		(end 35.201098 -253.239016)
		(width 0.14478)
		(layer "In6.Cu")
		(net "M_E_CPU1_SA_CA<4>")
	)
	(segment
		(start 80.915002 -254.4699)
		(end 80.761078 -254.20447)
		(width 0.0889)
		(layer "In6.Cu")
		(net "M_E_CPU1_SA_CA<4>")
	)
	(segment
		(start 42.498518 -253.17323)
		(end 42.498518 -253.239016)
		(width 0.14478)
		(layer "In6.Cu")
		(net "M_E_CPU1_SA_CA<4>")
	)
	(segment
		(start 29.252164 -250.885198)
		(end 31.377128 -253.010162)
		(width 0.14478)
		(layer "In6.Cu")
		(net "M_E_CPU1_SA_CA<4>")
	)
	(arc
		(start 79.068422 -254.52705)
		(mid 79.345235 -254.450907)
		(end 79.623666 -254.520954)
		(width 0.0889)
		(layer "In6.Cu")
		(net "M_E_CPU1_SA_CA<4>")
	)
	(arc
		(start 77.942186 -254.577088)
		(mid 78.03856 -254.564291)
		(end 78.128368 -254.52705)
		(width 0.0889)
		(layer "In6.Cu")
		(net "M_E_CPU1_SA_CA<4>")
	)
	(arc
		(start 80.574134 -254.52705)
		(mid 80.730453 -254.576045)
		(end 80.89265 -254.553212)
		(width 0.0889)
		(layer "In6.Cu")
		(net "M_E_CPU1_SA_CA<4>")
	)
	(arc
		(start 78.69428 -254.52705)
		(mid 78.876531 -254.5774)
		(end 79.06004 -254.531876)
		(width 0.0889)
		(layer "In6.Cu")
		(net "M_E_CPU1_SA_CA<4>")
	)
	(arc
		(start 78.1431 -254.518414)
		(mid 78.419829 -254.450731)
		(end 78.69428 -254.52705)
		(width 0.0889)
		(layer "In6.Cu")
		(net "M_E_CPU1_SA_CA<4>")
	)
	(arc
		(start 80.008222 -254.52705)
		(mid 80.291178 -254.450873)
		(end 80.574134 -254.52705)
		(width 0.0889)
		(layer "In6.Cu")
		(net "M_E_CPU1_SA_CA<4>")
	)
	(arc
		(start 79.642462 -254.531876)
		(mid 79.82597 -254.57737)
		(end 80.008222 -254.52705)
		(width 0.0889)
		(layer "In6.Cu")
		(net "M_E_CPU1_SA_CA<4>")
	)
	(segment
		(start 83.107784 -254.470408)
		(end 82.640932 -254.20447)
		(width 0.10668)
		(layer "F.Cu")
		(net "M_E_CPU1_SA_CA<3>")
	)
	(segment
		(start 81.879694 -253.877064)
		(end 81.888076 -253.88189)
		(width 0.0889)
		(layer "In6.Cu")
		(net "M_E_CPU1_SA_CA<3>")
	)
	(segment
		(start 25.577038 -250.460256)
		(end 29.613098 -250.460256)
		(width 0.14478)
		(layer "In6.Cu")
		(net "M_E_CPU1_SA_CA<3>")
	)
	(segment
		(start 29.613098 -250.460256)
		(end 31.31312 -252.160278)
		(width 0.14478)
		(layer "In6.Cu")
		(net "M_E_CPU1_SA_CA<3>")
	)
	(segment
		(start 82.390996 -253.91364)
		(end 82.487008 -253.93904)
		(width 0.0889)
		(layer "In6.Cu")
		(net "M_E_CPU1_SA_CA<3>")
	)
	(segment
		(start 25.152096 -250.035314)
		(end 25.577038 -250.460256)
		(width 0.14478)
		(layer "In6.Cu")
		(net "M_E_CPU1_SA_CA<3>")
	)
	(segment
		(start 72.288146 -253.336044)
		(end 73.603866 -254.651764)
		(width 0.14478)
		(layer "In6.Cu")
		(net "M_E_CPU1_SA_CA<3>")
	)
	(segment
		(start 59.70397 -252.160278)
		(end 60.879736 -253.336044)
		(width 0.14478)
		(layer "In6.Cu")
		(net "M_E_CPU1_SA_CA<3>")
	)
	(segment
		(start 76.171806 -254.651764)
		(end 76.344526 -254.479044)
		(width 0.0889)
		(layer "In6.Cu")
		(net "M_E_CPU1_SA_CA<3>")
	)
	(segment
		(start 77.58049 -254.065024)
		(end 77.758036 -253.887478)
		(width 0.0889)
		(layer "In6.Cu")
		(net "M_E_CPU1_SA_CA<3>")
	)
	(segment
		(start 78.128622 -253.882144)
		(end 78.14056 -253.889002)
		(width 0.0889)
		(layer "In6.Cu")
		(net "M_E_CPU1_SA_CA<3>")
	)
	(segment
		(start 76.344526 -254.479044)
		(end 76.344526 -254.387604)
		(width 0.0889)
		(layer "In6.Cu")
		(net "M_E_CPU1_SA_CA<3>")
	)
	(segment
		(start 79.634334 -253.88189)
		(end 79.646018 -253.875032)
		(width 0.0889)
		(layer "In6.Cu")
		(net "M_E_CPU1_SA_CA<3>")
	)
	(segment
		(start 79.62392 -253.887986)
		(end 79.634334 -253.88189)
		(width 0.0889)
		(layer "In6.Cu")
		(net "M_E_CPU1_SA_CA<3>")
	)
	(segment
		(start 76.344526 -254.387604)
		(end 76.667106 -254.065024)
		(width 0.0889)
		(layer "In6.Cu")
		(net "M_E_CPU1_SA_CA<3>")
	)
	(segment
		(start 79.056992 -253.875032)
		(end 79.068676 -253.88189)
		(width 0.0889)
		(layer "In6.Cu")
		(net "M_E_CPU1_SA_CA<3>")
	)
	(segment
		(start 82.487008 -253.93904)
		(end 82.640932 -254.20447)
		(width 0.0889)
		(layer "In6.Cu")
		(net "M_E_CPU1_SA_CA<3>")
	)
	(segment
		(start 60.879736 -253.336044)
		(end 72.288146 -253.336044)
		(width 0.14478)
		(layer "In6.Cu")
		(net "M_E_CPU1_SA_CA<3>")
	)
	(segment
		(start 31.31312 -252.160278)
		(end 59.70397 -252.160278)
		(width 0.14478)
		(layer "In6.Cu")
		(net "M_E_CPU1_SA_CA<3>")
	)
	(segment
		(start 73.603866 -254.651764)
		(end 75.991466 -254.651764)
		(width 0.14478)
		(layer "In6.Cu")
		(net "M_E_CPU1_SA_CA<3>")
	)
	(segment
		(start 75.991466 -254.651764)
		(end 76.171806 -254.651764)
		(width 0.0889)
		(layer "In6.Cu")
		(net "M_E_CPU1_SA_CA<3>")
	)
	(segment
		(start 76.667106 -254.065024)
		(end 77.58049 -254.065024)
		(width 0.0889)
		(layer "In6.Cu")
		(net "M_E_CPU1_SA_CA<3>")
	)
	(arc
		(start 81.513934 -253.88189)
		(mid 81.696185 -253.83154)
		(end 81.879694 -253.877064)
		(width 0.0889)
		(layer "In6.Cu")
		(net "M_E_CPU1_SA_CA<3>")
	)
	(arc
		(start 79.646018 -253.875032)
		(mid 79.828019 -253.831499)
		(end 80.008222 -253.88189)
		(width 0.0889)
		(layer "In6.Cu")
		(net "M_E_CPU1_SA_CA<3>")
	)
	(arc
		(start 80.008222 -253.88189)
		(mid 80.291178 -253.958067)
		(end 80.574134 -253.88189)
		(width 0.0889)
		(layer "In6.Cu")
		(net "M_E_CPU1_SA_CA<3>")
	)
	(arc
		(start 80.948022 -253.88189)
		(mid 81.230978 -253.958067)
		(end 81.513934 -253.88189)
		(width 0.0889)
		(layer "In6.Cu")
		(net "M_E_CPU1_SA_CA<3>")
	)
	(arc
		(start 80.574134 -253.88189)
		(mid 80.761078 -253.831635)
		(end 80.948022 -253.88189)
		(width 0.0889)
		(layer "In6.Cu")
		(net "M_E_CPU1_SA_CA<3>")
	)
	(arc
		(start 77.758036 -253.887478)
		(mid 77.942591 -253.833966)
		(end 78.128622 -253.882144)
		(width 0.0889)
		(layer "In6.Cu")
		(net "M_E_CPU1_SA_CA<3>")
	)
	(arc
		(start 81.888076 -253.88189)
		(mid 82.135789 -253.95711)
		(end 82.390996 -253.91364)
		(width 0.0889)
		(layer "In6.Cu")
		(net "M_E_CPU1_SA_CA<3>")
	)
	(arc
		(start 78.69428 -253.88189)
		(mid 78.874738 -253.831446)
		(end 79.056992 -253.875032)
		(width 0.0889)
		(layer "In6.Cu")
		(net "M_E_CPU1_SA_CA<3>")
	)
	(arc
		(start 79.068676 -253.88189)
		(mid 79.345489 -253.958033)
		(end 79.62392 -253.887986)
		(width 0.0889)
		(layer "In6.Cu")
		(net "M_E_CPU1_SA_CA<3>")
	)
	(arc
		(start 78.14056 -253.889002)
		(mid 78.418348 -253.958104)
		(end 78.69428 -253.88189)
		(width 0.0889)
		(layer "In6.Cu")
		(net "M_E_CPU1_SA_CA<3>")
	)
	(segment
		(start 82.637884 -253.660402)
		(end 82.171032 -253.394464)
		(width 0.10668)
		(layer "F.Cu")
		(net "M_E_CPU1_SA_CA<2>")
	)
	(segment
		(start 34.75228 -251.539756)
		(end 34.915348 -251.702824)
		(width 0.14478)
		(layer "In6.Cu")
		(net "M_E_CPU1_SA_CA<2>")
	)
	(segment
		(start 82.324956 -253.659894)
		(end 82.171032 -253.394464)
		(width 0.0889)
		(layer "In6.Cu")
		(net "M_E_CPU1_SA_CA<2>")
	)
	(segment
		(start 33.80232 -251.702824)
		(end 34.032698 -251.702824)
		(width 0.14478)
		(layer "In6.Cu")
		(net "M_E_CPU1_SA_CA<2>")
	)
	(segment
		(start 35.471862 -251.31014)
		(end 38.050724 -251.31014)
		(width 0.14478)
		(layer "In6.Cu")
		(net "M_E_CPU1_SA_CA<2>")
	)
	(segment
		(start 38.770306 -251.473208)
		(end 38.933374 -251.31014)
		(width 0.14478)
		(layer "In6.Cu")
		(net "M_E_CPU1_SA_CA<2>")
	)
	(segment
		(start 82.302604 -253.743206)
		(end 82.324956 -253.659894)
		(width 0.0889)
		(layer "In6.Cu")
		(net "M_E_CPU1_SA_CA<2>")
	)
	(segment
		(start 35.308794 -251.473208)
		(end 35.471862 -251.31014)
		(width 0.14478)
		(layer "In6.Cu")
		(net "M_E_CPU1_SA_CA<2>")
	)
	(segment
		(start 72.476614 -252.881384)
		(end 73.792334 -254.197104)
		(width 0.14478)
		(layer "In6.Cu")
		(net "M_E_CPU1_SA_CA<2>")
	)
	(segment
		(start 38.37686 -251.702824)
		(end 38.607238 -251.702824)
		(width 0.14478)
		(layer "In6.Cu")
		(net "M_E_CPU1_SA_CA<2>")
	)
	(segment
		(start 33.476184 -251.31014)
		(end 33.639252 -251.473208)
		(width 0.14478)
		(layer "In6.Cu")
		(net "M_E_CPU1_SA_CA<2>")
	)
	(segment
		(start 79.154274 -253.710948)
		(end 79.164688 -253.717044)
		(width 0.0889)
		(layer "In6.Cu")
		(net "M_E_CPU1_SA_CA<2>")
	)
	(segment
		(start 75.955906 -254.197104)
		(end 76.184506 -254.197104)
		(width 0.0889)
		(layer "In6.Cu")
		(net "M_E_CPU1_SA_CA<2>")
	)
	(segment
		(start 35.308794 -251.539756)
		(end 35.308794 -251.473208)
		(width 0.14478)
		(layer "In6.Cu")
		(net "M_E_CPU1_SA_CA<2>")
	)
	(segment
		(start 34.589212 -251.31014)
		(end 34.75228 -251.473208)
		(width 0.14478)
		(layer "In6.Cu")
		(net "M_E_CPU1_SA_CA<2>")
	)
	(segment
		(start 80.46974 -253.72187)
		(end 80.478122 -253.717044)
		(width 0.0889)
		(layer "In6.Cu")
		(net "M_E_CPU1_SA_CA<2>")
	)
	(segment
		(start 79.538322 -253.717044)
		(end 79.548736 -253.710948)
		(width 0.0889)
		(layer "In6.Cu")
		(net "M_E_CPU1_SA_CA<2>")
	)
	(segment
		(start 31.376874 -251.31014)
		(end 33.476184 -251.31014)
		(width 0.14478)
		(layer "In6.Cu")
		(net "M_E_CPU1_SA_CA<2>")
	)
	(segment
		(start 59.77001 -251.31014)
		(end 61.341254 -252.881384)
		(width 0.14478)
		(layer "In6.Cu")
		(net "M_E_CPU1_SA_CA<2>")
	)
	(segment
		(start 73.792334 -254.197104)
		(end 75.955906 -254.197104)
		(width 0.14478)
		(layer "In6.Cu")
		(net "M_E_CPU1_SA_CA<2>")
	)
	(segment
		(start 34.358834 -251.31014)
		(end 34.589212 -251.31014)
		(width 0.14478)
		(layer "In6.Cu")
		(net "M_E_CPU1_SA_CA<2>")
	)
	(segment
		(start 33.639252 -251.539756)
		(end 33.80232 -251.702824)
		(width 0.14478)
		(layer "In6.Cu")
		(net "M_E_CPU1_SA_CA<2>")
	)
	(segment
		(start 34.195766 -251.539756)
		(end 34.195766 -251.473208)
		(width 0.14478)
		(layer "In6.Cu")
		(net "M_E_CPU1_SA_CA<2>")
	)
	(segment
		(start 79.52994 -253.72187)
		(end 79.538322 -253.717044)
		(width 0.0889)
		(layer "In6.Cu")
		(net "M_E_CPU1_SA_CA<2>")
	)
	(segment
		(start 38.213792 -251.473208)
		(end 38.213792 -251.539756)
		(width 0.14478)
		(layer "In6.Cu")
		(net "M_E_CPU1_SA_CA<2>")
	)
	(segment
		(start 35.145726 -251.702824)
		(end 35.308794 -251.539756)
		(width 0.14478)
		(layer "In6.Cu")
		(net "M_E_CPU1_SA_CA<2>")
	)
	(segment
		(start 76.184506 -254.197104)
		(end 76.560426 -253.821184)
		(width 0.0889)
		(layer "In6.Cu")
		(net "M_E_CPU1_SA_CA<2>")
	)
	(segment
		(start 38.213792 -251.539756)
		(end 38.37686 -251.702824)
		(width 0.14478)
		(layer "In6.Cu")
		(net "M_E_CPU1_SA_CA<2>")
	)
	(segment
		(start 34.915348 -251.702824)
		(end 35.145726 -251.702824)
		(width 0.14478)
		(layer "In6.Cu")
		(net "M_E_CPU1_SA_CA<2>")
	)
	(segment
		(start 76.560426 -253.821184)
		(end 77.126846 -253.821184)
		(width 0.0889)
		(layer "In6.Cu")
		(net "M_E_CPU1_SA_CA<2>")
	)
	(segment
		(start 34.032698 -251.702824)
		(end 34.195766 -251.539756)
		(width 0.14478)
		(layer "In6.Cu")
		(net "M_E_CPU1_SA_CA<2>")
	)
	(segment
		(start 34.75228 -251.473208)
		(end 34.75228 -251.539756)
		(width 0.14478)
		(layer "In6.Cu")
		(net "M_E_CPU1_SA_CA<2>")
	)
	(segment
		(start 33.639252 -251.473208)
		(end 33.639252 -251.539756)
		(width 0.14478)
		(layer "In6.Cu")
		(net "M_E_CPU1_SA_CA<2>")
	)
	(segment
		(start 61.341254 -252.881384)
		(end 72.476614 -252.881384)
		(width 0.14478)
		(layer "In6.Cu")
		(net "M_E_CPU1_SA_CA<2>")
	)
	(segment
		(start 34.195766 -251.473208)
		(end 34.358834 -251.31014)
		(width 0.14478)
		(layer "In6.Cu")
		(net "M_E_CPU1_SA_CA<2>")
	)
	(segment
		(start 38.607238 -251.702824)
		(end 38.770306 -251.539756)
		(width 0.14478)
		(layer "In6.Cu")
		(net "M_E_CPU1_SA_CA<2>")
	)
	(segment
		(start 38.770306 -251.539756)
		(end 38.770306 -251.473208)
		(width 0.14478)
		(layer "In6.Cu")
		(net "M_E_CPU1_SA_CA<2>")
	)
	(segment
		(start 38.933374 -251.31014)
		(end 59.77001 -251.31014)
		(width 0.14478)
		(layer "In6.Cu")
		(net "M_E_CPU1_SA_CA<2>")
	)
	(segment
		(start 81.044034 -253.717044)
		(end 81.052416 -253.72187)
		(width 0.0889)
		(layer "In6.Cu")
		(net "M_E_CPU1_SA_CA<2>")
	)
	(segment
		(start 77.126846 -253.821184)
		(end 77.236574 -253.711456)
		(width 0.0889)
		(layer "In6.Cu")
		(net "M_E_CPU1_SA_CA<2>")
	)
	(segment
		(start 77.236574 -253.711456)
		(end 77.655928 -253.711456)
		(width 0.0889)
		(layer "In6.Cu")
		(net "M_E_CPU1_SA_CA<2>")
	)
	(segment
		(start 78.22438 -253.71679)
		(end 78.242668 -253.727204)
		(width 0.0889)
		(layer "In6.Cu")
		(net "M_E_CPU1_SA_CA<2>")
	)
	(segment
		(start 38.050724 -251.31014)
		(end 38.213792 -251.473208)
		(width 0.14478)
		(layer "In6.Cu")
		(net "M_E_CPU1_SA_CA<2>")
	)
	(segment
		(start 29.252164 -249.18543)
		(end 31.376874 -251.31014)
		(width 0.14478)
		(layer "In6.Cu")
		(net "M_E_CPU1_SA_CA<2>")
	)
	(arc
		(start 79.164688 -253.717044)
		(mid 79.346685 -253.767266)
		(end 79.52994 -253.72187)
		(width 0.0889)
		(layer "In6.Cu")
		(net "M_E_CPU1_SA_CA<2>")
	)
	(arc
		(start 81.984088 -253.717044)
		(mid 82.140407 -253.766039)
		(end 82.302604 -253.743206)
		(width 0.0889)
		(layer "In6.Cu")
		(net "M_E_CPU1_SA_CA<2>")
	)
	(arc
		(start 79.548736 -253.710948)
		(mid 79.827168 -253.64085)
		(end 80.10398 -253.717044)
		(width 0.0889)
		(layer "In6.Cu")
		(net "M_E_CPU1_SA_CA<2>")
	)
	(arc
		(start 77.655928 -253.711456)
		(mid 77.940842 -253.640309)
		(end 78.22438 -253.71679)
		(width 0.0889)
		(layer "In6.Cu")
		(net "M_E_CPU1_SA_CA<2>")
	)
	(arc
		(start 78.598522 -253.717044)
		(mid 78.875589 -253.640773)
		(end 79.154274 -253.710948)
		(width 0.0889)
		(layer "In6.Cu")
		(net "M_E_CPU1_SA_CA<2>")
	)
	(arc
		(start 81.052416 -253.72187)
		(mid 81.235924 -253.767364)
		(end 81.418176 -253.717044)
		(width 0.0889)
		(layer "In6.Cu")
		(net "M_E_CPU1_SA_CA<2>")
	)
	(arc
		(start 78.242668 -253.727204)
		(mid 78.421897 -253.767357)
		(end 78.598522 -253.717044)
		(width 0.0889)
		(layer "In6.Cu")
		(net "M_E_CPU1_SA_CA<2>")
	)
	(arc
		(start 81.418176 -253.717044)
		(mid 81.701132 -253.640867)
		(end 81.984088 -253.717044)
		(width 0.0889)
		(layer "In6.Cu")
		(net "M_E_CPU1_SA_CA<2>")
	)
	(arc
		(start 80.10398 -253.717044)
		(mid 80.286231 -253.767394)
		(end 80.46974 -253.72187)
		(width 0.0889)
		(layer "In6.Cu")
		(net "M_E_CPU1_SA_CA<2>")
	)
	(arc
		(start 80.478122 -253.717044)
		(mid 80.761078 -253.640867)
		(end 81.044034 -253.717044)
		(width 0.0889)
		(layer "In6.Cu")
		(net "M_E_CPU1_SA_CA<2>")
	)
	(segment
		(start 81.69783 -253.660402)
		(end 81.230978 -253.394464)
		(width 0.10668)
		(layer "F.Cu")
		(net "M_E_CPU1_SA_CA<1>")
	)
	(segment
		(start 78.22438 -253.071884)
		(end 78.236064 -253.065026)
		(width 0.0889)
		(layer "In6.Cu")
		(net "M_E_CPU1_SA_CA<1>")
	)
	(segment
		(start 80.981042 -253.103634)
		(end 81.077054 -253.129034)
		(width 0.0889)
		(layer "In6.Cu")
		(net "M_E_CPU1_SA_CA<1>")
	)
	(segment
		(start 77.495654 -253.147576)
		(end 77.942186 -253.147576)
		(width 0.0889)
		(layer "In6.Cu")
		(net "M_E_CPU1_SA_CA<1>")
	)
	(segment
		(start 77.114146 -253.529084)
		(end 77.495654 -253.147576)
		(width 0.0889)
		(layer "In6.Cu")
		(net "M_E_CPU1_SA_CA<1>")
	)
	(segment
		(start 59.77001 -250.460256)
		(end 61.736478 -252.426724)
		(width 0.14478)
		(layer "In6.Cu")
		(net "M_E_CPU1_SA_CA<1>")
	)
	(segment
		(start 73.980802 -253.742444)
		(end 75.950826 -253.742444)
		(width 0.14478)
		(layer "In6.Cu")
		(net "M_E_CPU1_SA_CA<1>")
	)
	(segment
		(start 80.46974 -253.067058)
		(end 80.478122 -253.071884)
		(width 0.0889)
		(layer "In6.Cu")
		(net "M_E_CPU1_SA_CA<1>")
	)
	(segment
		(start 61.736478 -252.426724)
		(end 72.665082 -252.426724)
		(width 0.14478)
		(layer "In6.Cu")
		(net "M_E_CPU1_SA_CA<1>")
	)
	(segment
		(start 79.538322 -253.071884)
		(end 79.548736 -253.07798)
		(width 0.0889)
		(layer "In6.Cu")
		(net "M_E_CPU1_SA_CA<1>")
	)
	(segment
		(start 76.171806 -253.742444)
		(end 76.385166 -253.529084)
		(width 0.0889)
		(layer "In6.Cu")
		(net "M_E_CPU1_SA_CA<1>")
	)
	(segment
		(start 75.950826 -253.742444)
		(end 76.171806 -253.742444)
		(width 0.0889)
		(layer "In6.Cu")
		(net "M_E_CPU1_SA_CA<1>")
	)
	(segment
		(start 25.152096 -248.335292)
		(end 25.577038 -248.760234)
		(width 0.14478)
		(layer "In6.Cu")
		(net "M_E_CPU1_SA_CA<1>")
	)
	(segment
		(start 25.577038 -248.760234)
		(end 29.613098 -248.760234)
		(width 0.14478)
		(layer "In6.Cu")
		(net "M_E_CPU1_SA_CA<1>")
	)
	(segment
		(start 29.613098 -248.760234)
		(end 31.31312 -250.460256)
		(width 0.14478)
		(layer "In6.Cu")
		(net "M_E_CPU1_SA_CA<1>")
	)
	(segment
		(start 81.077054 -253.129034)
		(end 81.230978 -253.394464)
		(width 0.0889)
		(layer "In6.Cu")
		(net "M_E_CPU1_SA_CA<1>")
	)
	(segment
		(start 76.385166 -253.529084)
		(end 77.114146 -253.529084)
		(width 0.0889)
		(layer "In6.Cu")
		(net "M_E_CPU1_SA_CA<1>")
	)
	(segment
		(start 72.665082 -252.426724)
		(end 73.980802 -253.742444)
		(width 0.14478)
		(layer "In6.Cu")
		(net "M_E_CPU1_SA_CA<1>")
	)
	(segment
		(start 31.31312 -250.460256)
		(end 59.77001 -250.460256)
		(width 0.14478)
		(layer "In6.Cu")
		(net "M_E_CPU1_SA_CA<1>")
	)
	(segment
		(start 79.15402 -253.07798)
		(end 79.164434 -253.071884)
		(width 0.0889)
		(layer "In6.Cu")
		(net "M_E_CPU1_SA_CA<1>")
	)
	(arc
		(start 80.478122 -253.071884)
		(mid 80.725835 -253.147104)
		(end 80.981042 -253.103634)
		(width 0.0889)
		(layer "In6.Cu")
		(net "M_E_CPU1_SA_CA<1>")
	)
	(arc
		(start 79.548736 -253.07798)
		(mid 79.827168 -253.148078)
		(end 80.10398 -253.071884)
		(width 0.0889)
		(layer "In6.Cu")
		(net "M_E_CPU1_SA_CA<1>")
	)
	(arc
		(start 78.236064 -253.065026)
		(mid 78.418065 -253.021493)
		(end 78.598268 -253.071884)
		(width 0.0889)
		(layer "In6.Cu")
		(net "M_E_CPU1_SA_CA<1>")
	)
	(arc
		(start 78.598268 -253.071884)
		(mid 78.875335 -253.148155)
		(end 79.15402 -253.07798)
		(width 0.0889)
		(layer "In6.Cu")
		(net "M_E_CPU1_SA_CA<1>")
	)
	(arc
		(start 80.10398 -253.071884)
		(mid 80.286231 -253.021534)
		(end 80.46974 -253.067058)
		(width 0.0889)
		(layer "In6.Cu")
		(net "M_E_CPU1_SA_CA<1>")
	)
	(arc
		(start 77.942186 -253.147576)
		(mid 78.08827 -253.128324)
		(end 78.22438 -253.071884)
		(width 0.0889)
		(layer "In6.Cu")
		(net "M_E_CPU1_SA_CA<1>")
	)
	(arc
		(start 79.164434 -253.071884)
		(mid 79.351378 -253.021629)
		(end 79.538322 -253.071884)
		(width 0.0889)
		(layer "In6.Cu")
		(net "M_E_CPU1_SA_CA<1>")
	)
	(segment
		(start 81.22793 -252.850396)
		(end 80.761078 -252.584458)
		(width 0.10668)
		(layer "F.Cu")
		(net "M_E_CPU1_SA_CA<0>")
	)
	(segment
		(start 42.45864 -249.610372)
		(end 42.621708 -249.77344)
		(width 0.14478)
		(layer "In6.Cu")
		(net "M_E_CPU1_SA_CA<0>")
	)
	(segment
		(start 45.698918 -250.003564)
		(end 45.929296 -250.003564)
		(width 0.14478)
		(layer "In6.Cu")
		(net "M_E_CPU1_SA_CA<0>")
	)
	(segment
		(start 34.790888 -249.837956)
		(end 34.953956 -250.001024)
		(width 0.14478)
		(layer "In6.Cu")
		(net "M_E_CPU1_SA_CA<0>")
	)
	(segment
		(start 33.67786 -249.77344)
		(end 33.67786 -249.837956)
		(width 0.14478)
		(layer "In6.Cu")
		(net "M_E_CPU1_SA_CA<0>")
	)
	(segment
		(start 34.62782 -249.610372)
		(end 34.790888 -249.77344)
		(width 0.14478)
		(layer "In6.Cu")
		(net "M_E_CPU1_SA_CA<0>")
	)
	(segment
		(start 72.85355 -251.972064)
		(end 74.16927 -253.287784)
		(width 0.14478)
		(layer "In6.Cu")
		(net "M_E_CPU1_SA_CA<0>")
	)
	(segment
		(start 34.397442 -249.610372)
		(end 34.62782 -249.610372)
		(width 0.14478)
		(layer "In6.Cu")
		(net "M_E_CPU1_SA_CA<0>")
	)
	(segment
		(start 38.943788 -249.77344)
		(end 39.106856 -249.610372)
		(width 0.14478)
		(layer "In6.Cu")
		(net "M_E_CPU1_SA_CA<0>")
	)
	(segment
		(start 34.071306 -250.001024)
		(end 34.234374 -249.837956)
		(width 0.14478)
		(layer "In6.Cu")
		(net "M_E_CPU1_SA_CA<0>")
	)
	(segment
		(start 42.065194 -249.840496)
		(end 42.065194 -249.77344)
		(width 0.14478)
		(layer "In6.Cu")
		(net "M_E_CPU1_SA_CA<0>")
	)
	(segment
		(start 43.178222 -249.77344)
		(end 43.34129 -249.610372)
		(width 0.14478)
		(layer "In6.Cu")
		(net "M_E_CPU1_SA_CA<0>")
	)
	(segment
		(start 38.943788 -249.837956)
		(end 38.943788 -249.77344)
		(width 0.14478)
		(layer "In6.Cu")
		(net "M_E_CPU1_SA_CA<0>")
	)
	(segment
		(start 79.63408 -252.907038)
		(end 79.642462 -252.911864)
		(width 0.0889)
		(layer "In6.Cu")
		(net "M_E_CPU1_SA_CA<0>")
	)
	(segment
		(start 41.50868 -249.77344)
		(end 41.50868 -249.840496)
		(width 0.14478)
		(layer "In6.Cu")
		(net "M_E_CPU1_SA_CA<0>")
	)
	(segment
		(start 41.902126 -250.003564)
		(end 42.065194 -249.840496)
		(width 0.14478)
		(layer "In6.Cu")
		(net "M_E_CPU1_SA_CA<0>")
	)
	(segment
		(start 34.953956 -250.001024)
		(end 35.184334 -250.001024)
		(width 0.14478)
		(layer "In6.Cu")
		(net "M_E_CPU1_SA_CA<0>")
	)
	(segment
		(start 45.53585 -249.77344)
		(end 45.53585 -249.840496)
		(width 0.14478)
		(layer "In6.Cu")
		(net "M_E_CPU1_SA_CA<0>")
	)
	(segment
		(start 79.06004 -252.911864)
		(end 79.068422 -252.907038)
		(width 0.0889)
		(layer "In6.Cu")
		(net "M_E_CPU1_SA_CA<0>")
	)
	(segment
		(start 33.514792 -249.610372)
		(end 33.67786 -249.77344)
		(width 0.14478)
		(layer "In6.Cu")
		(net "M_E_CPU1_SA_CA<0>")
	)
	(segment
		(start 35.347402 -249.837956)
		(end 35.347402 -249.77344)
		(width 0.14478)
		(layer "In6.Cu")
		(net "M_E_CPU1_SA_CA<0>")
	)
	(segment
		(start 43.015154 -250.003564)
		(end 43.178222 -249.840496)
		(width 0.14478)
		(layer "In6.Cu")
		(net "M_E_CPU1_SA_CA<0>")
	)
	(segment
		(start 43.178222 -249.840496)
		(end 43.178222 -249.77344)
		(width 0.14478)
		(layer "In6.Cu")
		(net "M_E_CPU1_SA_CA<0>")
	)
	(segment
		(start 35.347402 -249.77344)
		(end 35.51047 -249.610372)
		(width 0.14478)
		(layer "In6.Cu")
		(net "M_E_CPU1_SA_CA<0>")
	)
	(segment
		(start 46.092364 -249.77344)
		(end 46.255432 -249.610372)
		(width 0.14478)
		(layer "In6.Cu")
		(net "M_E_CPU1_SA_CA<0>")
	)
	(segment
		(start 43.34129 -249.610372)
		(end 45.372782 -249.610372)
		(width 0.14478)
		(layer "In6.Cu")
		(net "M_E_CPU1_SA_CA<0>")
	)
	(segment
		(start 38.224206 -249.610372)
		(end 38.387274 -249.77344)
		(width 0.14478)
		(layer "In6.Cu")
		(net "M_E_CPU1_SA_CA<0>")
	)
	(segment
		(start 42.621708 -249.840496)
		(end 42.784776 -250.003564)
		(width 0.14478)
		(layer "In6.Cu")
		(net "M_E_CPU1_SA_CA<0>")
	)
	(segment
		(start 33.840928 -250.001024)
		(end 34.071306 -250.001024)
		(width 0.14478)
		(layer "In6.Cu")
		(net "M_E_CPU1_SA_CA<0>")
	)
	(segment
		(start 76.946506 -253.254764)
		(end 77.244194 -252.957076)
		(width 0.0889)
		(layer "In6.Cu")
		(net "M_E_CPU1_SA_CA<0>")
	)
	(segment
		(start 45.53585 -249.840496)
		(end 45.698918 -250.003564)
		(width 0.14478)
		(layer "In6.Cu")
		(net "M_E_CPU1_SA_CA<0>")
	)
	(segment
		(start 38.78072 -250.001024)
		(end 38.943788 -249.837956)
		(width 0.14478)
		(layer "In6.Cu")
		(net "M_E_CPU1_SA_CA<0>")
	)
	(segment
		(start 34.790888 -249.77344)
		(end 34.790888 -249.837956)
		(width 0.14478)
		(layer "In6.Cu")
		(net "M_E_CPU1_SA_CA<0>")
	)
	(segment
		(start 45.372782 -249.610372)
		(end 45.53585 -249.77344)
		(width 0.14478)
		(layer "In6.Cu")
		(net "M_E_CPU1_SA_CA<0>")
	)
	(segment
		(start 41.345612 -249.610372)
		(end 41.50868 -249.77344)
		(width 0.14478)
		(layer "In6.Cu")
		(net "M_E_CPU1_SA_CA<0>")
	)
	(segment
		(start 45.929296 -250.003564)
		(end 46.092364 -249.840496)
		(width 0.14478)
		(layer "In6.Cu")
		(net "M_E_CPU1_SA_CA<0>")
	)
	(segment
		(start 33.67786 -249.837956)
		(end 33.840928 -250.001024)
		(width 0.14478)
		(layer "In6.Cu")
		(net "M_E_CPU1_SA_CA<0>")
	)
	(segment
		(start 35.51047 -249.610372)
		(end 38.224206 -249.610372)
		(width 0.14478)
		(layer "In6.Cu")
		(net "M_E_CPU1_SA_CA<0>")
	)
	(segment
		(start 80.915002 -252.849888)
		(end 80.761078 -252.584458)
		(width 0.0889)
		(layer "In6.Cu")
		(net "M_E_CPU1_SA_CA<0>")
	)
	(segment
		(start 34.234374 -249.77344)
		(end 34.397442 -249.610372)
		(width 0.14478)
		(layer "In6.Cu")
		(net "M_E_CPU1_SA_CA<0>")
	)
	(segment
		(start 42.228262 -249.610372)
		(end 42.45864 -249.610372)
		(width 0.14478)
		(layer "In6.Cu")
		(net "M_E_CPU1_SA_CA<0>")
	)
	(segment
		(start 78.128368 -252.907038)
		(end 78.1431 -252.898402)
		(width 0.0889)
		(layer "In6.Cu")
		(net "M_E_CPU1_SA_CA<0>")
	)
	(segment
		(start 46.255432 -249.610372)
		(end 59.77001 -249.610372)
		(width 0.14478)
		(layer "In6.Cu")
		(net "M_E_CPU1_SA_CA<0>")
	)
	(segment
		(start 59.77001 -249.610372)
		(end 62.131702 -251.972064)
		(width 0.14478)
		(layer "In6.Cu")
		(net "M_E_CPU1_SA_CA<0>")
	)
	(segment
		(start 77.244194 -252.957076)
		(end 77.942186 -252.957076)
		(width 0.0889)
		(layer "In6.Cu")
		(net "M_E_CPU1_SA_CA<0>")
	)
	(segment
		(start 34.234374 -249.837956)
		(end 34.234374 -249.77344)
		(width 0.14478)
		(layer "In6.Cu")
		(net "M_E_CPU1_SA_CA<0>")
	)
	(segment
		(start 41.50868 -249.840496)
		(end 41.671748 -250.003564)
		(width 0.14478)
		(layer "In6.Cu")
		(net "M_E_CPU1_SA_CA<0>")
	)
	(segment
		(start 74.16927 -253.287784)
		(end 75.945746 -253.287784)
		(width 0.14478)
		(layer "In6.Cu")
		(net "M_E_CPU1_SA_CA<0>")
	)
	(segment
		(start 76.288646 -253.287784)
		(end 76.321666 -253.254764)
		(width 0.0889)
		(layer "In6.Cu")
		(net "M_E_CPU1_SA_CA<0>")
	)
	(segment
		(start 38.387274 -249.77344)
		(end 38.387274 -249.837956)
		(width 0.14478)
		(layer "In6.Cu")
		(net "M_E_CPU1_SA_CA<0>")
	)
	(segment
		(start 46.092364 -249.840496)
		(end 46.092364 -249.77344)
		(width 0.14478)
		(layer "In6.Cu")
		(net "M_E_CPU1_SA_CA<0>")
	)
	(segment
		(start 75.945746 -253.287784)
		(end 76.288646 -253.287784)
		(width 0.0889)
		(layer "In6.Cu")
		(net "M_E_CPU1_SA_CA<0>")
	)
	(segment
		(start 29.252164 -247.485408)
		(end 31.377128 -249.610372)
		(width 0.14478)
		(layer "In6.Cu")
		(net "M_E_CPU1_SA_CA<0>")
	)
	(segment
		(start 38.550342 -250.001024)
		(end 38.78072 -250.001024)
		(width 0.14478)
		(layer "In6.Cu")
		(net "M_E_CPU1_SA_CA<0>")
	)
	(segment
		(start 39.106856 -249.610372)
		(end 41.345612 -249.610372)
		(width 0.14478)
		(layer "In6.Cu")
		(net "M_E_CPU1_SA_CA<0>")
	)
	(segment
		(start 35.184334 -250.001024)
		(end 35.347402 -249.837956)
		(width 0.14478)
		(layer "In6.Cu")
		(net "M_E_CPU1_SA_CA<0>")
	)
	(segment
		(start 42.784776 -250.003564)
		(end 43.015154 -250.003564)
		(width 0.14478)
		(layer "In6.Cu")
		(net "M_E_CPU1_SA_CA<0>")
	)
	(segment
		(start 79.623666 -252.900942)
		(end 79.63408 -252.907038)
		(width 0.0889)
		(layer "In6.Cu")
		(net "M_E_CPU1_SA_CA<0>")
	)
	(segment
		(start 76.321666 -253.254764)
		(end 76.946506 -253.254764)
		(width 0.0889)
		(layer "In6.Cu")
		(net "M_E_CPU1_SA_CA<0>")
	)
	(segment
		(start 38.387274 -249.837956)
		(end 38.550342 -250.001024)
		(width 0.14478)
		(layer "In6.Cu")
		(net "M_E_CPU1_SA_CA<0>")
	)
	(segment
		(start 62.131702 -251.972064)
		(end 72.85355 -251.972064)
		(width 0.14478)
		(layer "In6.Cu")
		(net "M_E_CPU1_SA_CA<0>")
	)
	(segment
		(start 42.621708 -249.77344)
		(end 42.621708 -249.840496)
		(width 0.14478)
		(layer "In6.Cu")
		(net "M_E_CPU1_SA_CA<0>")
	)
	(segment
		(start 41.671748 -250.003564)
		(end 41.902126 -250.003564)
		(width 0.14478)
		(layer "In6.Cu")
		(net "M_E_CPU1_SA_CA<0>")
	)
	(segment
		(start 80.89265 -252.9332)
		(end 80.915002 -252.849888)
		(width 0.0889)
		(layer "In6.Cu")
		(net "M_E_CPU1_SA_CA<0>")
	)
	(segment
		(start 31.377128 -249.610372)
		(end 33.514792 -249.610372)
		(width 0.14478)
		(layer "In6.Cu")
		(net "M_E_CPU1_SA_CA<0>")
	)
	(segment
		(start 42.065194 -249.77344)
		(end 42.228262 -249.610372)
		(width 0.14478)
		(layer "In6.Cu")
		(net "M_E_CPU1_SA_CA<0>")
	)
	(arc
		(start 79.642462 -252.911864)
		(mid 79.82597 -252.957358)
		(end 80.008222 -252.907038)
		(width 0.0889)
		(layer "In6.Cu")
		(net "M_E_CPU1_SA_CA<0>")
	)
	(arc
		(start 78.1431 -252.898402)
		(mid 78.419829 -252.830719)
		(end 78.69428 -252.907038)
		(width 0.0889)
		(layer "In6.Cu")
		(net "M_E_CPU1_SA_CA<0>")
	)
	(arc
		(start 78.69428 -252.907038)
		(mid 78.876531 -252.957388)
		(end 79.06004 -252.911864)
		(width 0.0889)
		(layer "In6.Cu")
		(net "M_E_CPU1_SA_CA<0>")
	)
	(arc
		(start 77.942186 -252.957076)
		(mid 78.03856 -252.944279)
		(end 78.128368 -252.907038)
		(width 0.0889)
		(layer "In6.Cu")
		(net "M_E_CPU1_SA_CA<0>")
	)
	(arc
		(start 80.008222 -252.907038)
		(mid 80.291178 -252.830861)
		(end 80.574134 -252.907038)
		(width 0.0889)
		(layer "In6.Cu")
		(net "M_E_CPU1_SA_CA<0>")
	)
	(arc
		(start 79.068422 -252.907038)
		(mid 79.345235 -252.830895)
		(end 79.623666 -252.900942)
		(width 0.0889)
		(layer "In6.Cu")
		(net "M_E_CPU1_SA_CA<0>")
	)
	(arc
		(start 80.574134 -252.907038)
		(mid 80.730453 -252.956033)
		(end 80.89265 -252.9332)
		(width 0.0889)
		(layer "In6.Cu")
		(net "M_E_CPU1_SA_CA<0>")
	)
	(segment
		(start 83.107784 -251.230384)
		(end 82.640932 -250.964446)
		(width 0.10668)
		(layer "F.Cu")
		(net "M_E_CPU1_RESET_N")
	)
	(segment
		(start 30.136338 -245.36019)
		(end 31.83636 -247.060212)
		(width 0.11684)
		(layer "In6.Cu")
		(net "M_E_CPU1_RESET_N")
	)
	(segment
		(start 76.961746 -251.619004)
		(end 77.578966 -251.001784)
		(width 0.0889)
		(layer "In6.Cu")
		(net "M_E_CPU1_RESET_N")
	)
	(segment
		(start 82.487008 -250.699016)
		(end 82.640932 -250.964446)
		(width 0.0889)
		(layer "In6.Cu")
		(net "M_E_CPU1_RESET_N")
	)
	(segment
		(start 31.83636 -247.060212)
		(end 59.994038 -247.060212)
		(width 0.11684)
		(layer "In6.Cu")
		(net "M_E_CPU1_RESET_N")
	)
	(segment
		(start 77.578966 -251.001784)
		(end 78.16088 -251.001784)
		(width 0.0889)
		(layer "In6.Cu")
		(net "M_E_CPU1_RESET_N")
	)
	(segment
		(start 63.25108 -250.317254)
		(end 73.539604 -250.317254)
		(width 0.11684)
		(layer "In6.Cu")
		(net "M_E_CPU1_RESET_N")
	)
	(segment
		(start 81.879694 -250.63704)
		(end 81.888076 -250.641866)
		(width 0.0889)
		(layer "In6.Cu")
		(net "M_E_CPU1_RESET_N")
	)
	(segment
		(start 25.152096 -244.935248)
		(end 25.577038 -245.36019)
		(width 0.11684)
		(layer "In6.Cu")
		(net "M_E_CPU1_RESET_N")
	)
	(segment
		(start 73.539604 -250.317254)
		(end 74.841354 -251.619004)
		(width 0.11684)
		(layer "In6.Cu")
		(net "M_E_CPU1_RESET_N")
	)
	(segment
		(start 82.390996 -250.673616)
		(end 82.487008 -250.699016)
		(width 0.0889)
		(layer "In6.Cu")
		(net "M_E_CPU1_RESET_N")
	)
	(segment
		(start 25.577038 -245.36019)
		(end 30.136338 -245.36019)
		(width 0.11684)
		(layer "In6.Cu")
		(net "M_E_CPU1_RESET_N")
	)
	(segment
		(start 59.994038 -247.060212)
		(end 63.25108 -250.317254)
		(width 0.11684)
		(layer "In6.Cu")
		(net "M_E_CPU1_RESET_N")
	)
	(segment
		(start 76.140056 -251.619004)
		(end 76.961746 -251.619004)
		(width 0.0889)
		(layer "In6.Cu")
		(net "M_E_CPU1_RESET_N")
	)
	(segment
		(start 74.841354 -251.619004)
		(end 76.140056 -251.619004)
		(width 0.11684)
		(layer "In6.Cu")
		(net "M_E_CPU1_RESET_N")
	)
	(segment
		(start 79.634334 -250.641866)
		(end 79.646018 -250.635008)
		(width 0.0889)
		(layer "In6.Cu")
		(net "M_E_CPU1_RESET_N")
	)
	(segment
		(start 79.056992 -250.635008)
		(end 79.068676 -250.641866)
		(width 0.0889)
		(layer "In6.Cu")
		(net "M_E_CPU1_RESET_N")
	)
	(segment
		(start 78.16088 -251.001784)
		(end 78.438756 -250.717558)
		(width 0.0889)
		(layer "In6.Cu")
		(net "M_E_CPU1_RESET_N")
	)
	(segment
		(start 79.62392 -250.647962)
		(end 79.634334 -250.641866)
		(width 0.0889)
		(layer "In6.Cu")
		(net "M_E_CPU1_RESET_N")
	)
	(arc
		(start 78.438756 -250.717558)
		(mid 78.571045 -250.695004)
		(end 78.69428 -250.641866)
		(width 0.0889)
		(layer "In6.Cu")
		(net "M_E_CPU1_RESET_N")
	)
	(arc
		(start 81.513934 -250.641866)
		(mid 81.696185 -250.591516)
		(end 81.879694 -250.63704)
		(width 0.0889)
		(layer "In6.Cu")
		(net "M_E_CPU1_RESET_N")
	)
	(arc
		(start 79.068676 -250.641866)
		(mid 79.345489 -250.718009)
		(end 79.62392 -250.647962)
		(width 0.0889)
		(layer "In6.Cu")
		(net "M_E_CPU1_RESET_N")
	)
	(arc
		(start 80.574134 -250.641866)
		(mid 80.761078 -250.591611)
		(end 80.948022 -250.641866)
		(width 0.0889)
		(layer "In6.Cu")
		(net "M_E_CPU1_RESET_N")
	)
	(arc
		(start 80.948022 -250.641866)
		(mid 81.230978 -250.718043)
		(end 81.513934 -250.641866)
		(width 0.0889)
		(layer "In6.Cu")
		(net "M_E_CPU1_RESET_N")
	)
	(arc
		(start 78.69428 -250.641866)
		(mid 78.874738 -250.591422)
		(end 79.056992 -250.635008)
		(width 0.0889)
		(layer "In6.Cu")
		(net "M_E_CPU1_RESET_N")
	)
	(arc
		(start 79.646018 -250.635008)
		(mid 79.828019 -250.591475)
		(end 80.008222 -250.641866)
		(width 0.0889)
		(layer "In6.Cu")
		(net "M_E_CPU1_RESET_N")
	)
	(arc
		(start 80.008222 -250.641866)
		(mid 80.291178 -250.718043)
		(end 80.574134 -250.641866)
		(width 0.0889)
		(layer "In6.Cu")
		(net "M_E_CPU1_RESET_N")
	)
	(arc
		(start 81.888076 -250.641866)
		(mid 82.135789 -250.717086)
		(end 82.390996 -250.673616)
		(width 0.0889)
		(layer "In6.Cu")
		(net "M_E_CPU1_RESET_N")
	)
	(segment
		(start 81.22793 -256.09042)
		(end 80.761078 -255.824482)
		(width 0.14732)
		(layer "F.Cu")
		(net "M_E_CPU1_CLK_DP<0>")
	)
	(segment
		(start 26.289508 -253.70917)
		(end 29.012642 -256.432304)
		(width 0.16002)
		(layer "In6.Cu")
		(net "M_E_CPU1_CLK_DP<0>")
	)
	(segment
		(start 66.325496 -256.432304)
		(end 67.797426 -255.822704)
		(width 0.16002)
		(layer "In6.Cu")
		(net "M_E_CPU1_CLK_DP<0>")
	)
	(segment
		(start 76.837794 -257.402076)
		(end 78.008226 -256.231644)
		(width 0.09525)
		(layer "In6.Cu")
		(net "M_E_CPU1_CLK_DP<0>")
	)
	(segment
		(start 75.979528 -257.342894)
		(end 76.03871 -257.402076)
		(width 0.09525)
		(layer "In6.Cu")
		(net "M_E_CPU1_CLK_DP<0>")
	)
	(segment
		(start 79.061564 -256.154428)
		(end 79.069946 -256.149602)
		(width 0.09525)
		(layer "In6.Cu")
		(net "M_E_CPU1_CLK_DP<0>")
	)
	(segment
		(start 75.955906 -257.342894)
		(end 75.979528 -257.342894)
		(width 0.09525)
		(layer "In6.Cu")
		(net "M_E_CPU1_CLK_DP<0>")
	)
	(segment
		(start 80.915002 -256.089912)
		(end 80.761078 -255.824482)
		(width 0.09525)
		(layer "In6.Cu")
		(net "M_E_CPU1_CLK_DP<0>")
	)
	(segment
		(start 25.152096 -253.435358)
		(end 25.425908 -253.70917)
		(width 0.16002)
		(layer "In6.Cu")
		(net "M_E_CPU1_CLK_DP<0>")
	)
	(segment
		(start 29.012642 -256.432304)
		(end 65.131696 -256.432304)
		(width 0.16002)
		(layer "In6.Cu")
		(net "M_E_CPU1_CLK_DP<0>")
	)
	(segment
		(start 80.891888 -256.176526)
		(end 80.915002 -256.089912)
		(width 0.09525)
		(layer "In6.Cu")
		(net "M_E_CPU1_CLK_DP<0>")
	)
	(segment
		(start 25.425908 -253.70917)
		(end 26.289508 -253.70917)
		(width 0.16002)
		(layer "In6.Cu")
		(net "M_E_CPU1_CLK_DP<0>")
	)
	(segment
		(start 79.622142 -256.143506)
		(end 79.632556 -256.149602)
		(width 0.09525)
		(layer "In6.Cu")
		(net "M_E_CPU1_CLK_DP<0>")
	)
	(segment
		(start 65.845436 -256.432304)
		(end 66.325496 -256.432304)
		(width 0.16002)
		(layer "In6.Cu")
		(net "M_E_CPU1_CLK_DP<0>")
	)
	(segment
		(start 71.175118 -255.822704)
		(end 72.695308 -257.342894)
		(width 0.16002)
		(layer "In6.Cu")
		(net "M_E_CPU1_CLK_DP<0>")
	)
	(segment
		(start 72.695308 -257.342894)
		(end 75.955906 -257.342894)
		(width 0.16002)
		(layer "In6.Cu")
		(net "M_E_CPU1_CLK_DP<0>")
	)
	(segment
		(start 67.797426 -255.822704)
		(end 71.175118 -255.822704)
		(width 0.16002)
		(layer "In6.Cu")
		(net "M_E_CPU1_CLK_DP<0>")
	)
	(segment
		(start 79.632556 -256.149602)
		(end 79.640938 -256.154428)
		(width 0.09525)
		(layer "In6.Cu")
		(net "M_E_CPU1_CLK_DP<0>")
	)
	(segment
		(start 76.03871 -257.402076)
		(end 76.837794 -257.402076)
		(width 0.09525)
		(layer "In6.Cu")
		(net "M_E_CPU1_CLK_DP<0>")
	)
	(segment
		(start 65.131696 -256.432304)
		(end 65.248536 -256.315464)
		(width 0.16002)
		(layer "In6.Cu")
		(net "M_E_CPU1_CLK_DP<0>")
	)
	(segment
		(start 78.31582 -256.073656)
		(end 78.41107 -256.073656)
		(width 0.09525)
		(layer "In6.Cu")
		(net "M_E_CPU1_CLK_DP<0>")
	)
	(segment
		(start 65.248536 -256.315464)
		(end 65.728596 -256.315464)
		(width 0.16002)
		(layer "In6.Cu")
		(net "M_E_CPU1_CLK_DP<0>")
	)
	(segment
		(start 65.728596 -256.315464)
		(end 65.845436 -256.432304)
		(width 0.16002)
		(layer "In6.Cu")
		(net "M_E_CPU1_CLK_DP<0>")
	)
	(arc
		(start 80.57261 -256.149602)
		(mid 80.729237 -256.198788)
		(end 80.891888 -256.176526)
		(width 0.09525)
		(layer "In6.Cu")
		(net "M_E_CPU1_CLK_DP<0>")
	)
	(arc
		(start 78.008226 -256.231644)
		(mid 78.142925 -256.115472)
		(end 78.31582 -256.073656)
		(width 0.09525)
		(layer "In6.Cu")
		(net "M_E_CPU1_CLK_DP<0>")
	)
	(arc
		(start 79.069946 -256.149602)
		(mid 79.345235 -256.073881)
		(end 79.622142 -256.143506)
		(width 0.09525)
		(layer "In6.Cu")
		(net "M_E_CPU1_CLK_DP<0>")
	)
	(arc
		(start 78.692756 -256.149602)
		(mid 78.876531 -256.200374)
		(end 79.061564 -256.154428)
		(width 0.09525)
		(layer "In6.Cu")
		(net "M_E_CPU1_CLK_DP<0>")
	)
	(arc
		(start 78.41107 -256.073656)
		(mid 78.55695 -256.092961)
		(end 78.692756 -256.149602)
		(width 0.09525)
		(layer "In6.Cu")
		(net "M_E_CPU1_CLK_DP<0>")
	)
	(arc
		(start 80.009746 -256.149602)
		(mid 80.291178 -256.073847)
		(end 80.57261 -256.149602)
		(width 0.09525)
		(layer "In6.Cu")
		(net "M_E_CPU1_CLK_DP<0>")
	)
	(arc
		(start 79.640938 -256.154428)
		(mid 79.82597 -256.200342)
		(end 80.009746 -256.149602)
		(width 0.09525)
		(layer "In6.Cu")
		(net "M_E_CPU1_CLK_DP<0>")
	)
	(segment
		(start 81.69783 -256.900426)
		(end 81.230978 -256.634488)
		(width 0.14732)
		(layer "F.Cu")
		(net "M_E_CPU1_CLK_DN<0>")
	)
	(segment
		(start 80.976216 -256.342388)
		(end 81.077054 -256.369058)
		(width 0.09525)
		(layer "In6.Cu")
		(net "M_E_CPU1_CLK_DN<0>")
	)
	(segment
		(start 79.539846 -256.309368)
		(end 79.55026 -256.315464)
		(width 0.09525)
		(layer "In6.Cu")
		(net "M_E_CPU1_CLK_DN<0>")
	)
	(segment
		(start 28.88742 -256.734564)
		(end 66.385694 -256.734564)
		(width 0.16002)
		(layer "In6.Cu")
		(net "M_E_CPU1_CLK_DN<0>")
	)
	(segment
		(start 25.425908 -254.01143)
		(end 26.164286 -254.01143)
		(width 0.16002)
		(layer "In6.Cu")
		(net "M_E_CPU1_CLK_DN<0>")
	)
	(segment
		(start 75.979528 -257.645154)
		(end 76.038456 -257.586226)
		(width 0.09525)
		(layer "In6.Cu")
		(net "M_E_CPU1_CLK_DN<0>")
	)
	(segment
		(start 26.164286 -254.01143)
		(end 28.88742 -256.734564)
		(width 0.16002)
		(layer "In6.Cu")
		(net "M_E_CPU1_CLK_DN<0>")
	)
	(segment
		(start 76.038456 -257.586226)
		(end 76.914248 -257.586226)
		(width 0.09525)
		(layer "In6.Cu")
		(net "M_E_CPU1_CLK_DN<0>")
	)
	(segment
		(start 71.049896 -256.124964)
		(end 72.570086 -257.645154)
		(width 0.16002)
		(layer "In6.Cu")
		(net "M_E_CPU1_CLK_DN<0>")
	)
	(segment
		(start 81.077054 -256.369058)
		(end 81.230978 -256.634488)
		(width 0.09525)
		(layer "In6.Cu")
		(net "M_E_CPU1_CLK_DN<0>")
	)
	(segment
		(start 72.570086 -257.645154)
		(end 75.955906 -257.645154)
		(width 0.16002)
		(layer "In6.Cu")
		(net "M_E_CPU1_CLK_DN<0>")
	)
	(segment
		(start 79.152496 -256.315464)
		(end 79.16291 -256.309368)
		(width 0.09525)
		(layer "In6.Cu")
		(net "M_E_CPU1_CLK_DN<0>")
	)
	(segment
		(start 66.385694 -256.734564)
		(end 67.857624 -256.124964)
		(width 0.16002)
		(layer "In6.Cu")
		(net "M_E_CPU1_CLK_DN<0>")
	)
	(segment
		(start 25.152096 -254.285242)
		(end 25.425908 -254.01143)
		(width 0.16002)
		(layer "In6.Cu")
		(net "M_E_CPU1_CLK_DN<0>")
	)
	(segment
		(start 67.857624 -256.124964)
		(end 71.049896 -256.124964)
		(width 0.16002)
		(layer "In6.Cu")
		(net "M_E_CPU1_CLK_DN<0>")
	)
	(segment
		(start 80.471264 -256.304542)
		(end 80.479646 -256.309368)
		(width 0.09525)
		(layer "In6.Cu")
		(net "M_E_CPU1_CLK_DN<0>")
	)
	(segment
		(start 76.914248 -257.586226)
		(end 78.149196 -256.351278)
		(width 0.09525)
		(layer "In6.Cu")
		(net "M_E_CPU1_CLK_DN<0>")
	)
	(segment
		(start 78.31582 -256.257806)
		(end 78.41107 -256.257806)
		(width 0.09525)
		(layer "In6.Cu")
		(net "M_E_CPU1_CLK_DN<0>")
	)
	(segment
		(start 78.149196 -256.351278)
		(end 78.158086 -256.339086)
		(width 0.09525)
		(layer "In6.Cu")
		(net "M_E_CPU1_CLK_DN<0>")
	)
	(segment
		(start 75.955906 -257.645154)
		(end 75.979528 -257.645154)
		(width 0.09525)
		(layer "In6.Cu")
		(net "M_E_CPU1_CLK_DN<0>")
	)
	(arc
		(start 78.41107 -256.257806)
		(mid 78.508826 -256.27114)
		(end 78.599792 -256.309368)
		(width 0.09525)
		(layer "In6.Cu")
		(net "M_E_CPU1_CLK_DN<0>")
	)
	(arc
		(start 80.102456 -256.309368)
		(mid 80.286231 -256.258596)
		(end 80.471264 -256.304542)
		(width 0.09525)
		(layer "In6.Cu")
		(net "M_E_CPU1_CLK_DN<0>")
	)
	(arc
		(start 80.479646 -256.309368)
		(mid 80.713441 -256.383235)
		(end 80.956404 -256.350262)
		(width 0.09525)
		(layer "In6.Cu")
		(net "M_E_CPU1_CLK_DN<0>")
	)
	(arc
		(start 80.956404 -256.350262)
		(mid 80.966347 -256.346419)
		(end 80.976216 -256.342388)
		(width 0.09525)
		(layer "In6.Cu")
		(net "M_E_CPU1_CLK_DN<0>")
	)
	(arc
		(start 78.599792 -256.309368)
		(mid 78.875335 -256.385217)
		(end 79.152496 -256.315464)
		(width 0.09525)
		(layer "In6.Cu")
		(net "M_E_CPU1_CLK_DN<0>")
	)
	(arc
		(start 79.55026 -256.315464)
		(mid 79.827168 -256.385141)
		(end 80.102456 -256.309368)
		(width 0.09525)
		(layer "In6.Cu")
		(net "M_E_CPU1_CLK_DN<0>")
	)
	(arc
		(start 78.158086 -256.339086)
		(mid 78.227114 -256.279337)
		(end 78.31582 -256.257806)
		(width 0.09525)
		(layer "In6.Cu")
		(net "M_E_CPU1_CLK_DN<0>")
	)
	(arc
		(start 79.16291 -256.309368)
		(mid 79.351378 -256.258691)
		(end 79.539846 -256.309368)
		(width 0.09525)
		(layer "In6.Cu")
		(net "M_E_CPU1_CLK_DN<0>")
	)
	(segment
		(start 82.637884 -250.420378)
		(end 82.171032 -250.15444)
		(width 0.10668)
		(layer "F.Cu")
		(net "M_E_CPU1_ALERT_R_N")
	)
	(segment
		(start 56.70169 -246.210328)
		(end 57.033668 -246.542306)
		(width 0.11684)
		(layer "In6.Cu")
		(net "M_E_CPU1_ALERT_R_N")
	)
	(segment
		(start 57.033668 -246.542306)
		(end 58.02503 -246.542306)
		(width 0.11684)
		(layer "In6.Cu")
		(net "M_E_CPU1_ALERT_R_N")
	)
	(segment
		(start 58.357008 -246.210328)
		(end 59.743086 -246.210328)
		(width 0.11684)
		(layer "In6.Cu")
		(net "M_E_CPU1_ALERT_R_N")
	)
	(segment
		(start 81.044034 -250.47702)
		(end 81.052416 -250.481846)
		(width 0.0889)
		(layer "In6.Cu")
		(net "M_E_CPU1_ALERT_R_N")
	)
	(segment
		(start 82.324956 -250.41987)
		(end 82.171032 -250.15444)
		(width 0.0889)
		(layer "In6.Cu")
		(net "M_E_CPU1_ALERT_R_N")
	)
	(segment
		(start 63.423292 -249.890534)
		(end 73.716388 -249.890534)
		(width 0.11684)
		(layer "In6.Cu")
		(net "M_E_CPU1_ALERT_R_N")
	)
	(segment
		(start 30.649164 -244.085364)
		(end 30.649164 -244.821202)
		(width 0.11684)
		(layer "In6.Cu")
		(net "M_E_CPU1_ALERT_R_N")
	)
	(segment
		(start 77.415136 -250.712224)
		(end 77.655928 -250.471432)
		(width 0.0889)
		(layer "In6.Cu")
		(net "M_E_CPU1_ALERT_R_N")
	)
	(segment
		(start 59.743086 -246.210328)
		(end 63.423292 -249.890534)
		(width 0.11684)
		(layer "In6.Cu")
		(net "M_E_CPU1_ALERT_R_N")
	)
	(segment
		(start 76.629006 -250.882404)
		(end 76.799186 -250.712224)
		(width 0.11684)
		(layer "In6.Cu")
		(net "M_E_CPU1_ALERT_R_N")
	)
	(segment
		(start 74.708258 -250.882404)
		(end 76.629006 -250.882404)
		(width 0.11684)
		(layer "In6.Cu")
		(net "M_E_CPU1_ALERT_R_N")
	)
	(segment
		(start 58.02503 -246.542306)
		(end 58.357008 -246.210328)
		(width 0.11684)
		(layer "In6.Cu")
		(net "M_E_CPU1_ALERT_R_N")
	)
	(segment
		(start 30.649164 -244.821202)
		(end 32.03829 -246.210328)
		(width 0.11684)
		(layer "In6.Cu")
		(net "M_E_CPU1_ALERT_R_N")
	)
	(segment
		(start 79.154274 -250.470924)
		(end 79.164688 -250.47702)
		(width 0.0889)
		(layer "In6.Cu")
		(net "M_E_CPU1_ALERT_R_N")
	)
	(segment
		(start 82.302604 -250.503182)
		(end 82.324956 -250.41987)
		(width 0.0889)
		(layer "In6.Cu")
		(net "M_E_CPU1_ALERT_R_N")
	)
	(segment
		(start 79.538322 -250.47702)
		(end 79.548736 -250.470924)
		(width 0.0889)
		(layer "In6.Cu")
		(net "M_E_CPU1_ALERT_R_N")
	)
	(segment
		(start 78.22438 -250.476766)
		(end 78.242668 -250.48718)
		(width 0.0889)
		(layer "In6.Cu")
		(net "M_E_CPU1_ALERT_R_N")
	)
	(segment
		(start 73.716388 -249.890534)
		(end 74.708258 -250.882404)
		(width 0.11684)
		(layer "In6.Cu")
		(net "M_E_CPU1_ALERT_R_N")
	)
	(segment
		(start 76.799186 -250.712224)
		(end 77.415136 -250.712224)
		(width 0.0889)
		(layer "In6.Cu")
		(net "M_E_CPU1_ALERT_R_N")
	)
	(segment
		(start 80.46974 -250.481846)
		(end 80.478122 -250.47702)
		(width 0.0889)
		(layer "In6.Cu")
		(net "M_E_CPU1_ALERT_R_N")
	)
	(segment
		(start 32.03829 -246.210328)
		(end 56.70169 -246.210328)
		(width 0.11684)
		(layer "In6.Cu")
		(net "M_E_CPU1_ALERT_R_N")
	)
	(segment
		(start 79.52994 -250.481846)
		(end 79.538322 -250.47702)
		(width 0.0889)
		(layer "In6.Cu")
		(net "M_E_CPU1_ALERT_R_N")
	)
	(arc
		(start 81.984088 -250.47702)
		(mid 82.140407 -250.526015)
		(end 82.302604 -250.503182)
		(width 0.0889)
		(layer "In6.Cu")
		(net "M_E_CPU1_ALERT_R_N")
	)
	(arc
		(start 78.242668 -250.48718)
		(mid 78.421897 -250.527333)
		(end 78.598522 -250.47702)
		(width 0.0889)
		(layer "In6.Cu")
		(net "M_E_CPU1_ALERT_R_N")
	)
	(arc
		(start 81.052416 -250.481846)
		(mid 81.235924 -250.52734)
		(end 81.418176 -250.47702)
		(width 0.0889)
		(layer "In6.Cu")
		(net "M_E_CPU1_ALERT_R_N")
	)
	(arc
		(start 77.655928 -250.471432)
		(mid 77.940842 -250.400285)
		(end 78.22438 -250.476766)
		(width 0.0889)
		(layer "In6.Cu")
		(net "M_E_CPU1_ALERT_R_N")
	)
	(arc
		(start 79.548736 -250.470924)
		(mid 79.827168 -250.400826)
		(end 80.10398 -250.47702)
		(width 0.0889)
		(layer "In6.Cu")
		(net "M_E_CPU1_ALERT_R_N")
	)
	(arc
		(start 80.10398 -250.47702)
		(mid 80.286231 -250.52737)
		(end 80.46974 -250.481846)
		(width 0.0889)
		(layer "In6.Cu")
		(net "M_E_CPU1_ALERT_R_N")
	)
	(arc
		(start 81.418176 -250.47702)
		(mid 81.701132 -250.400843)
		(end 81.984088 -250.47702)
		(width 0.0889)
		(layer "In6.Cu")
		(net "M_E_CPU1_ALERT_R_N")
	)
	(arc
		(start 78.598522 -250.47702)
		(mid 78.875589 -250.400749)
		(end 79.154274 -250.470924)
		(width 0.0889)
		(layer "In6.Cu")
		(net "M_E_CPU1_ALERT_R_N")
	)
	(arc
		(start 79.164688 -250.47702)
		(mid 79.346685 -250.527242)
		(end 79.52994 -250.481846)
		(width 0.0889)
		(layer "In6.Cu")
		(net "M_E_CPU1_ALERT_R_N")
	)
	(arc
		(start 80.478122 -250.47702)
		(mid 80.761078 -250.400843)
		(end 81.044034 -250.47702)
		(width 0.0889)
		(layer "In6.Cu")
		(net "M_E_CPU1_ALERT_R_N")
	)
	(via
		(at 29.252164 -244.085364)
		(size 0.4826)
		(drill 0.254)
		(layers "F.Cu" "B.Cu")
		(net "M_E_CPU1_ALERT_N")
	)
	(segment
		(start 29.849064 -244.085364)
		(end 29.252164 -244.085364)
		(width 0.10668)
		(layer "B.Cu")
		(net "M_E_CPU1_ALERT_N")
	)
	(segment
		(start 329.937872 -267.34008)
		(end 329.47102 -267.606018)
		(width 0.10668)
		(layer "F.Cu")
		(net "M_E_CPU0_SB_RSP<0>")
	)
	(segment
		(start 289.677348 -270.010128)
		(end 289.420046 -270.010128)
		(width 0.11684)
		(layer "In6.Cu")
		(net "M_E_CPU0_SB_RSP<0>")
	)
	(segment
		(start 326.475598 -267.927836)
		(end 326.46747 -267.92301)
		(width 0.1016)
		(layer "In6.Cu")
		(net "M_E_CPU0_SB_RSP<0>")
	)
	(segment
		(start 289.948366 -269.73911)
		(end 289.677348 -270.010128)
		(width 0.11684)
		(layer "In6.Cu")
		(net "M_E_CPU0_SB_RSP<0>")
	)
	(segment
		(start 287.044892 -270.010128)
		(end 286.748474 -269.71371)
		(width 0.11684)
		(layer "In6.Cu")
		(net "M_E_CPU0_SB_RSP<0>")
	)
	(segment
		(start 286.748474 -269.71371)
		(end 286.516572 -269.71371)
		(width 0.11684)
		(layer "In6.Cu")
		(net "M_E_CPU0_SB_RSP<0>")
	)
	(segment
		(start 329.47102 -267.606018)
		(end 329.322176 -267.862304)
		(width 0.1016)
		(layer "In6.Cu")
		(net "M_E_CPU0_SB_RSP<0>")
	)
	(segment
		(start 283.99613 -270.010128)
		(end 283.699712 -269.71371)
		(width 0.11684)
		(layer "In6.Cu")
		(net "M_E_CPU0_SB_RSP<0>")
	)
	(segment
		(start 277.617174 -270.010128)
		(end 277.192232 -270.43507)
		(width 0.11684)
		(layer "In6.Cu")
		(net "M_E_CPU0_SB_RSP<0>")
	)
	(segment
		(start 295.271444 -269.73911)
		(end 295.014142 -269.73911)
		(width 0.11684)
		(layer "In6.Cu")
		(net "M_E_CPU0_SB_RSP<0>")
	)
	(segment
		(start 329.322176 -267.862304)
		(end 329.21956 -267.889482)
		(width 0.1016)
		(layer "In6.Cu")
		(net "M_E_CPU0_SB_RSP<0>")
	)
	(segment
		(start 286.220154 -270.010128)
		(end 285.988252 -270.010128)
		(width 0.11684)
		(layer "In6.Cu")
		(net "M_E_CPU0_SB_RSP<0>")
	)
	(segment
		(start 285.691834 -269.71371)
		(end 285.459932 -269.71371)
		(width 0.11684)
		(layer "In6.Cu")
		(net "M_E_CPU0_SB_RSP<0>")
	)
	(segment
		(start 285.163514 -270.010128)
		(end 283.99613 -270.010128)
		(width 0.11684)
		(layer "In6.Cu")
		(net "M_E_CPU0_SB_RSP<0>")
	)
	(segment
		(start 285.988252 -270.010128)
		(end 285.691834 -269.71371)
		(width 0.11684)
		(layer "In6.Cu")
		(net "M_E_CPU0_SB_RSP<0>")
	)
	(segment
		(start 293.158164 -269.73911)
		(end 292.900862 -269.73911)
		(width 0.11684)
		(layer "In6.Cu")
		(net "M_E_CPU0_SB_RSP<0>")
	)
	(segment
		(start 295.542462 -270.010128)
		(end 295.271444 -269.73911)
		(width 0.11684)
		(layer "In6.Cu")
		(net "M_E_CPU0_SB_RSP<0>")
	)
	(segment
		(start 291.533326 -270.010128)
		(end 291.262308 -269.73911)
		(width 0.11684)
		(layer "In6.Cu")
		(net "M_E_CPU0_SB_RSP<0>")
	)
	(segment
		(start 293.957502 -269.73911)
		(end 293.686484 -270.010128)
		(width 0.11684)
		(layer "In6.Cu")
		(net "M_E_CPU0_SB_RSP<0>")
	)
	(segment
		(start 285.459932 -269.71371)
		(end 285.163514 -270.010128)
		(width 0.11684)
		(layer "In6.Cu")
		(net "M_E_CPU0_SB_RSP<0>")
	)
	(segment
		(start 323.908674 -266.85113)
		(end 310.840374 -266.85113)
		(width 0.11684)
		(layer "In6.Cu")
		(net "M_E_CPU0_SB_RSP<0>")
	)
	(segment
		(start 310.840374 -266.85113)
		(end 307.681376 -270.010128)
		(width 0.11684)
		(layer "In6.Cu")
		(net "M_E_CPU0_SB_RSP<0>")
	)
	(segment
		(start 324.688454 -267.27531)
		(end 324.264274 -266.85113)
		(width 0.1016)
		(layer "In6.Cu")
		(net "M_E_CPU0_SB_RSP<0>")
	)
	(segment
		(start 324.264274 -266.85113)
		(end 323.908674 -266.85113)
		(width 0.1016)
		(layer "In6.Cu")
		(net "M_E_CPU0_SB_RSP<0>")
	)
	(segment
		(start 293.686484 -270.010128)
		(end 293.429182 -270.010128)
		(width 0.11684)
		(layer "In6.Cu")
		(net "M_E_CPU0_SB_RSP<0>")
	)
	(segment
		(start 283.46781 -269.71371)
		(end 283.171392 -270.010128)
		(width 0.11684)
		(layer "In6.Cu")
		(net "M_E_CPU0_SB_RSP<0>")
	)
	(segment
		(start 307.681376 -270.010128)
		(end 295.542462 -270.010128)
		(width 0.11684)
		(layer "In6.Cu")
		(net "M_E_CPU0_SB_RSP<0>")
	)
	(segment
		(start 327.78573 -267.916914)
		(end 327.775062 -267.92301)
		(width 0.1016)
		(layer "In6.Cu")
		(net "M_E_CPU0_SB_RSP<0>")
	)
	(segment
		(start 326.46747 -267.92301)
		(end 325.624952 -267.27531)
		(width 0.1016)
		(layer "In6.Cu")
		(net "M_E_CPU0_SB_RSP<0>")
	)
	(segment
		(start 292.900862 -269.73911)
		(end 292.629844 -270.010128)
		(width 0.11684)
		(layer "In6.Cu")
		(net "M_E_CPU0_SB_RSP<0>")
	)
	(segment
		(start 294.214804 -269.73911)
		(end 293.957502 -269.73911)
		(width 0.11684)
		(layer "In6.Cu")
		(net "M_E_CPU0_SB_RSP<0>")
	)
	(segment
		(start 291.262308 -269.73911)
		(end 291.005006 -269.73911)
		(width 0.11684)
		(layer "In6.Cu")
		(net "M_E_CPU0_SB_RSP<0>")
	)
	(segment
		(start 282.41117 -269.71371)
		(end 282.114752 -270.010128)
		(width 0.11684)
		(layer "In6.Cu")
		(net "M_E_CPU0_SB_RSP<0>")
	)
	(segment
		(start 288.891726 -269.73911)
		(end 288.620708 -270.010128)
		(width 0.11684)
		(layer "In6.Cu")
		(net "M_E_CPU0_SB_RSP<0>")
	)
	(segment
		(start 325.624952 -267.27531)
		(end 324.688454 -267.27531)
		(width 0.1016)
		(layer "In6.Cu")
		(net "M_E_CPU0_SB_RSP<0>")
	)
	(segment
		(start 291.005006 -269.73911)
		(end 290.733988 -270.010128)
		(width 0.11684)
		(layer "In6.Cu")
		(net "M_E_CPU0_SB_RSP<0>")
	)
	(segment
		(start 290.733988 -270.010128)
		(end 290.476686 -270.010128)
		(width 0.11684)
		(layer "In6.Cu")
		(net "M_E_CPU0_SB_RSP<0>")
	)
	(segment
		(start 326.845676 -267.916914)
		(end 326.835008 -267.92301)
		(width 0.1016)
		(layer "In6.Cu")
		(net "M_E_CPU0_SB_RSP<0>")
	)
	(segment
		(start 281.058112 -270.010128)
		(end 277.617174 -270.010128)
		(width 0.11684)
		(layer "In6.Cu")
		(net "M_E_CPU0_SB_RSP<0>")
	)
	(segment
		(start 290.476686 -270.010128)
		(end 290.205668 -269.73911)
		(width 0.11684)
		(layer "In6.Cu")
		(net "M_E_CPU0_SB_RSP<0>")
	)
	(segment
		(start 283.171392 -270.010128)
		(end 282.93949 -270.010128)
		(width 0.11684)
		(layer "In6.Cu")
		(net "M_E_CPU0_SB_RSP<0>")
	)
	(segment
		(start 288.620708 -270.010128)
		(end 287.044892 -270.010128)
		(width 0.11684)
		(layer "In6.Cu")
		(net "M_E_CPU0_SB_RSP<0>")
	)
	(segment
		(start 283.699712 -269.71371)
		(end 283.46781 -269.71371)
		(width 0.11684)
		(layer "In6.Cu")
		(net "M_E_CPU0_SB_RSP<0>")
	)
	(segment
		(start 294.743124 -270.010128)
		(end 294.485822 -270.010128)
		(width 0.11684)
		(layer "In6.Cu")
		(net "M_E_CPU0_SB_RSP<0>")
	)
	(segment
		(start 281.35453 -269.71371)
		(end 281.058112 -270.010128)
		(width 0.11684)
		(layer "In6.Cu")
		(net "M_E_CPU0_SB_RSP<0>")
	)
	(segment
		(start 281.88285 -270.010128)
		(end 281.586432 -269.71371)
		(width 0.11684)
		(layer "In6.Cu")
		(net "M_E_CPU0_SB_RSP<0>")
	)
	(segment
		(start 289.420046 -270.010128)
		(end 289.149028 -269.73911)
		(width 0.11684)
		(layer "In6.Cu")
		(net "M_E_CPU0_SB_RSP<0>")
	)
	(segment
		(start 289.149028 -269.73911)
		(end 288.891726 -269.73911)
		(width 0.11684)
		(layer "In6.Cu")
		(net "M_E_CPU0_SB_RSP<0>")
	)
	(segment
		(start 290.205668 -269.73911)
		(end 289.948366 -269.73911)
		(width 0.11684)
		(layer "In6.Cu")
		(net "M_E_CPU0_SB_RSP<0>")
	)
	(segment
		(start 281.586432 -269.71371)
		(end 281.35453 -269.71371)
		(width 0.11684)
		(layer "In6.Cu")
		(net "M_E_CPU0_SB_RSP<0>")
	)
	(segment
		(start 282.93949 -270.010128)
		(end 282.643072 -269.71371)
		(width 0.11684)
		(layer "In6.Cu")
		(net "M_E_CPU0_SB_RSP<0>")
	)
	(segment
		(start 282.643072 -269.71371)
		(end 282.41117 -269.71371)
		(width 0.11684)
		(layer "In6.Cu")
		(net "M_E_CPU0_SB_RSP<0>")
	)
	(segment
		(start 327.775062 -267.92301)
		(end 327.763378 -267.929614)
		(width 0.1016)
		(layer "In6.Cu")
		(net "M_E_CPU0_SB_RSP<0>")
	)
	(segment
		(start 286.516572 -269.71371)
		(end 286.220154 -270.010128)
		(width 0.11684)
		(layer "In6.Cu")
		(net "M_E_CPU0_SB_RSP<0>")
	)
	(segment
		(start 295.014142 -269.73911)
		(end 294.743124 -270.010128)
		(width 0.11684)
		(layer "In6.Cu")
		(net "M_E_CPU0_SB_RSP<0>")
	)
	(segment
		(start 292.629844 -270.010128)
		(end 291.533326 -270.010128)
		(width 0.11684)
		(layer "In6.Cu")
		(net "M_E_CPU0_SB_RSP<0>")
	)
	(segment
		(start 293.429182 -270.010128)
		(end 293.158164 -269.73911)
		(width 0.11684)
		(layer "In6.Cu")
		(net "M_E_CPU0_SB_RSP<0>")
	)
	(segment
		(start 294.485822 -270.010128)
		(end 294.214804 -269.73911)
		(width 0.11684)
		(layer "In6.Cu")
		(net "M_E_CPU0_SB_RSP<0>")
	)
	(segment
		(start 282.114752 -270.010128)
		(end 281.88285 -270.010128)
		(width 0.11684)
		(layer "In6.Cu")
		(net "M_E_CPU0_SB_RSP<0>")
	)
	(arc
		(start 328.715116 -267.92301)
		(mid 328.53122 -267.97249)
		(end 328.347324 -267.92301)
		(width 0.1016)
		(layer "In6.Cu")
		(net "M_E_CPU0_SB_RSP<0>")
	)
	(arc
		(start 327.40727 -267.92301)
		(mid 327.127266 -267.845965)
		(end 326.845676 -267.916914)
		(width 0.1016)
		(layer "In6.Cu")
		(net "M_E_CPU0_SB_RSP<0>")
	)
	(arc
		(start 327.763378 -267.929614)
		(mid 327.584455 -267.972524)
		(end 327.40727 -267.92301)
		(width 0.1016)
		(layer "In6.Cu")
		(net "M_E_CPU0_SB_RSP<0>")
	)
	(arc
		(start 326.835008 -267.92301)
		(mid 326.655947 -267.972458)
		(end 326.475598 -267.927836)
		(width 0.1016)
		(layer "In6.Cu")
		(net "M_E_CPU0_SB_RSP<0>")
	)
	(arc
		(start 329.21956 -267.889482)
		(mid 328.963404 -267.847218)
		(end 328.715116 -267.92301)
		(width 0.1016)
		(layer "In6.Cu")
		(net "M_E_CPU0_SB_RSP<0>")
	)
	(arc
		(start 328.347324 -267.92301)
		(mid 328.06732 -267.845965)
		(end 327.78573 -267.916914)
		(width 0.1016)
		(layer "In6.Cu")
		(net "M_E_CPU0_SB_RSP<0>")
	)
	(segment
		(start 329.467972 -264.910062)
		(end 329.00112 -265.176)
		(width 0.10668)
		(layer "F.Cu")
		(net "M_E_CPU0_SB_PAR")
	)
	(segment
		(start 326.383142 -264.862056)
		(end 326.36841 -264.85342)
		(width 0.0889)
		(layer "In6.Cu")
		(net "M_E_CPU0_SB_PAR")
	)
	(segment
		(start 326.182228 -264.803382)
		(end 325.611998 -264.803382)
		(width 0.0889)
		(layer "In6.Cu")
		(net "M_E_CPU0_SB_PAR")
	)
	(segment
		(start 327.882504 -264.848594)
		(end 327.874122 -264.85342)
		(width 0.0889)
		(layer "In6.Cu")
		(net "M_E_CPU0_SB_PAR")
	)
	(segment
		(start 329.00112 -265.176)
		(end 329.155044 -264.91057)
		(width 0.0889)
		(layer "In6.Cu")
		(net "M_E_CPU0_SB_PAR")
	)
	(segment
		(start 323.906134 -265.0744)
		(end 309.175404 -265.0744)
		(width 0.14478)
		(layer "In6.Cu")
		(net "M_E_CPU0_SB_PAR")
	)
	(segment
		(start 325.611998 -264.803382)
		(end 325.315326 -264.50671)
		(width 0.0889)
		(layer "In6.Cu")
		(net "M_E_CPU0_SB_PAR")
	)
	(segment
		(start 309.175404 -265.0744)
		(end 307.63972 -266.610084)
		(width 0.14478)
		(layer "In6.Cu")
		(net "M_E_CPU0_SB_PAR")
	)
	(segment
		(start 329.155044 -264.91057)
		(end 329.132692 -264.827258)
		(width 0.0889)
		(layer "In6.Cu")
		(net "M_E_CPU0_SB_PAR")
	)
	(segment
		(start 324.252844 -265.0744)
		(end 323.906134 -265.0744)
		(width 0.0889)
		(layer "In6.Cu")
		(net "M_E_CPU0_SB_PAR")
	)
	(segment
		(start 327.308464 -264.85342)
		(end 327.300082 -264.848594)
		(width 0.0889)
		(layer "In6.Cu")
		(net "M_E_CPU0_SB_PAR")
	)
	(segment
		(start 324.820534 -264.50671)
		(end 324.252844 -265.0744)
		(width 0.0889)
		(layer "In6.Cu")
		(net "M_E_CPU0_SB_PAR")
	)
	(segment
		(start 307.63972 -266.610084)
		(end 273.517106 -266.610084)
		(width 0.14478)
		(layer "In6.Cu")
		(net "M_E_CPU0_SB_PAR")
	)
	(segment
		(start 327.874122 -264.85342)
		(end 327.863708 -264.859516)
		(width 0.0889)
		(layer "In6.Cu")
		(net "M_E_CPU0_SB_PAR")
	)
	(segment
		(start 325.315326 -264.50671)
		(end 324.820534 -264.50671)
		(width 0.0889)
		(layer "In6.Cu")
		(net "M_E_CPU0_SB_PAR")
	)
	(segment
		(start 273.517106 -266.610084)
		(end 273.092164 -267.035026)
		(width 0.14478)
		(layer "In6.Cu")
		(net "M_E_CPU0_SB_PAR")
	)
	(arc
		(start 326.36841 -264.85342)
		(mid 326.278608 -264.816159)
		(end 326.182228 -264.803382)
		(width 0.0889)
		(layer "In6.Cu")
		(net "M_E_CPU0_SB_PAR")
	)
	(arc
		(start 326.934322 -264.85342)
		(mid 326.65987 -264.929656)
		(end 326.383142 -264.862056)
		(width 0.0889)
		(layer "In6.Cu")
		(net "M_E_CPU0_SB_PAR")
	)
	(arc
		(start 328.248264 -264.85342)
		(mid 328.066013 -264.80307)
		(end 327.882504 -264.848594)
		(width 0.0889)
		(layer "In6.Cu")
		(net "M_E_CPU0_SB_PAR")
	)
	(arc
		(start 329.132692 -264.827258)
		(mid 328.970503 -264.804523)
		(end 328.814176 -264.85342)
		(width 0.0889)
		(layer "In6.Cu")
		(net "M_E_CPU0_SB_PAR")
	)
	(arc
		(start 327.863708 -264.859516)
		(mid 327.585276 -264.929614)
		(end 327.308464 -264.85342)
		(width 0.0889)
		(layer "In6.Cu")
		(net "M_E_CPU0_SB_PAR")
	)
	(arc
		(start 328.814176 -264.85342)
		(mid 328.53122 -264.929597)
		(end 328.248264 -264.85342)
		(width 0.0889)
		(layer "In6.Cu")
		(net "M_E_CPU0_SB_PAR")
	)
	(arc
		(start 327.300082 -264.848594)
		(mid 327.116574 -264.8031)
		(end 326.934322 -264.85342)
		(width 0.0889)
		(layer "In6.Cu")
		(net "M_E_CPU0_SB_PAR")
	)
	(segment
		(start 329.937872 -270.580104)
		(end 329.47102 -270.846042)
		(width 0.12954)
		(layer "F.Cu")
		(net "M_E_CPU0_SB_DQS_DP<9>")
	)
	(segment
		(start 287.487868 -274.793456)
		(end 288.337752 -275.64334)
		(width 0.16002)
		(layer "In6.Cu")
		(net "M_E_CPU0_SB_DQS_DP<9>")
	)
	(segment
		(start 302.694594 -275.795994)
		(end 302.694594 -274.904454)
		(width 0.16002)
		(layer "In6.Cu")
		(net "M_E_CPU0_SB_DQS_DP<9>")
	)
	(segment
		(start 329.216258 -271.138142)
		(end 329.317096 -271.111472)
		(width 0.09525)
		(layer "In6.Cu")
		(net "M_E_CPU0_SB_DQS_DP<9>")
	)
	(segment
		(start 308.576218 -272.861024)
		(end 311.903872 -269.53337)
		(width 0.16002)
		(layer "In6.Cu")
		(net "M_E_CPU0_SB_DQS_DP<9>")
	)
	(segment
		(start 308.576218 -273.40306)
		(end 308.576218 -272.861024)
		(width 0.16002)
		(layer "In6.Cu")
		(net "M_E_CPU0_SB_DQS_DP<9>")
	)
	(segment
		(start 293.45382 -275.64334)
		(end 296.560748 -275.64334)
		(width 0.16002)
		(layer "In6.Cu")
		(net "M_E_CPU0_SB_DQS_DP<9>")
	)
	(segment
		(start 277.192232 -275.535136)
		(end 277.466044 -275.808948)
		(width 0.16002)
		(layer "In6.Cu")
		(net "M_E_CPU0_SB_DQS_DP<9>")
	)
	(segment
		(start 279.673558 -274.819872)
		(end 280.010616 -275.15693)
		(width 0.16002)
		(layer "In6.Cu")
		(net "M_E_CPU0_SB_DQS_DP<9>")
	)
	(segment
		(start 324.003924 -269.592298)
		(end 324.24878 -269.592298)
		(width 0.09525)
		(layer "In6.Cu")
		(net "M_E_CPU0_SB_DQS_DP<9>")
	)
	(segment
		(start 278.399748 -275.808948)
		(end 278.725376 -275.48332)
		(width 0.16002)
		(layer "In6.Cu")
		(net "M_E_CPU0_SB_DQS_DP<9>")
	)
	(segment
		(start 298.980352 -274.793456)
		(end 300.686724 -274.793456)
		(width 0.16002)
		(layer "In6.Cu")
		(net "M_E_CPU0_SB_DQS_DP<9>")
	)
	(segment
		(start 283.892752 -274.793456)
		(end 285.296864 -274.793456)
		(width 0.16002)
		(layer "In6.Cu")
		(net "M_E_CPU0_SB_DQS_DP<9>")
	)
	(segment
		(start 302.487838 -276.00275)
		(end 302.694594 -275.795994)
		(width 0.16002)
		(layer "In6.Cu")
		(net "M_E_CPU0_SB_DQS_DP<9>")
	)
	(segment
		(start 311.903872 -269.53337)
		(end 323.895974 -269.53337)
		(width 0.16002)
		(layer "In6.Cu")
		(net "M_E_CPU0_SB_DQS_DP<9>")
	)
	(segment
		(start 290.582858 -275.16455)
		(end 291.065458 -275.16455)
		(width 0.16002)
		(layer "In6.Cu")
		(net "M_E_CPU0_SB_DQS_DP<9>")
	)
	(segment
		(start 291.436552 -274.793456)
		(end 292.603936 -274.793456)
		(width 0.16002)
		(layer "In6.Cu")
		(net "M_E_CPU0_SB_DQS_DP<9>")
	)
	(segment
		(start 286.314642 -275.647912)
		(end 286.314642 -275.130514)
		(width 0.16002)
		(layer "In6.Cu")
		(net "M_E_CPU0_SB_DQS_DP<9>")
	)
	(segment
		(start 279.062434 -274.819872)
		(end 279.673558 -274.819872)
		(width 0.16002)
		(layer "In6.Cu")
		(net "M_E_CPU0_SB_DQS_DP<9>")
	)
	(segment
		(start 286.6517 -274.793456)
		(end 287.487868 -274.793456)
		(width 0.16002)
		(layer "In6.Cu")
		(net "M_E_CPU0_SB_DQS_DP<9>")
	)
	(segment
		(start 278.725376 -275.48332)
		(end 278.725376 -275.15693)
		(width 0.16002)
		(layer "In6.Cu")
		(net "M_E_CPU0_SB_DQS_DP<9>")
	)
	(segment
		(start 286.154622 -275.807932)
		(end 286.314642 -275.647912)
		(width 0.16002)
		(layer "In6.Cu")
		(net "M_E_CPU0_SB_DQS_DP<9>")
	)
	(segment
		(start 306.56149 -275.16455)
		(end 306.768246 -274.957794)
		(width 0.16002)
		(layer "In6.Cu")
		(net "M_E_CPU0_SB_DQS_DP<9>")
	)
	(segment
		(start 323.921374 -269.53337)
		(end 323.944996 -269.53337)
		(width 0.09525)
		(layer "In6.Cu")
		(net "M_E_CPU0_SB_DQS_DP<9>")
	)
	(segment
		(start 289.042348 -275.64334)
		(end 289.389058 -275.99005)
		(width 0.16002)
		(layer "In6.Cu")
		(net "M_E_CPU0_SB_DQS_DP<9>")
	)
	(segment
		(start 281.465274 -275.64334)
		(end 281.900376 -276.078442)
		(width 0.16002)
		(layer "In6.Cu")
		(net "M_E_CPU0_SB_DQS_DP<9>")
	)
	(segment
		(start 288.337752 -275.64334)
		(end 289.042348 -275.64334)
		(width 0.16002)
		(layer "In6.Cu")
		(net "M_E_CPU0_SB_DQS_DP<9>")
	)
	(segment
		(start 328.711306 -271.175988)
		(end 328.719688 -271.171162)
		(width 0.09525)
		(layer "In6.Cu")
		(net "M_E_CPU0_SB_DQS_DP<9>")
	)
	(segment
		(start 324.801992 -270.14551)
		(end 325.356982 -270.14551)
		(width 0.09525)
		(layer "In6.Cu")
		(net "M_E_CPU0_SB_DQS_DP<9>")
	)
	(segment
		(start 323.895974 -269.53337)
		(end 323.921374 -269.53337)
		(width 0.1016)
		(layer "In6.Cu")
		(net "M_E_CPU0_SB_DQS_DP<9>")
	)
	(segment
		(start 296.560748 -275.64334)
		(end 296.907458 -275.99005)
		(width 0.16002)
		(layer "In6.Cu")
		(net "M_E_CPU0_SB_DQS_DP<9>")
	)
	(segment
		(start 280.010616 -275.48332)
		(end 280.170636 -275.64334)
		(width 0.16002)
		(layer "In6.Cu")
		(net "M_E_CPU0_SB_DQS_DP<9>")
	)
	(segment
		(start 285.793942 -275.807932)
		(end 286.154622 -275.807932)
		(width 0.16002)
		(layer "In6.Cu")
		(net "M_E_CPU0_SB_DQS_DP<9>")
	)
	(segment
		(start 297.326558 -275.99005)
		(end 298.126658 -275.18995)
		(width 0.16002)
		(layer "In6.Cu")
		(net "M_E_CPU0_SB_DQS_DP<9>")
	)
	(segment
		(start 285.633922 -275.130514)
		(end 285.633922 -275.647912)
		(width 0.16002)
		(layer "In6.Cu")
		(net "M_E_CPU0_SB_DQS_DP<9>")
	)
	(segment
		(start 307.957728 -274.02155)
		(end 308.576218 -273.40306)
		(width 0.16002)
		(layer "In6.Cu")
		(net "M_E_CPU0_SB_DQS_DP<9>")
	)
	(segment
		(start 291.065458 -275.16455)
		(end 291.436552 -274.793456)
		(width 0.16002)
		(layer "In6.Cu")
		(net "M_E_CPU0_SB_DQS_DP<9>")
	)
	(segment
		(start 283.547058 -275.13915)
		(end 283.892752 -274.793456)
		(width 0.16002)
		(layer "In6.Cu")
		(net "M_E_CPU0_SB_DQS_DP<9>")
	)
	(segment
		(start 298.126658 -275.18995)
		(end 298.583858 -275.18995)
		(width 0.16002)
		(layer "In6.Cu")
		(net "M_E_CPU0_SB_DQS_DP<9>")
	)
	(segment
		(start 280.010616 -275.15693)
		(end 280.010616 -275.48332)
		(width 0.16002)
		(layer "In6.Cu")
		(net "M_E_CPU0_SB_DQS_DP<9>")
	)
	(segment
		(start 301.896018 -276.00275)
		(end 302.487838 -276.00275)
		(width 0.16002)
		(layer "In6.Cu")
		(net "M_E_CPU0_SB_DQS_DP<9>")
	)
	(segment
		(start 304.883058 -276.00275)
		(end 305.721258 -275.16455)
		(width 0.16002)
		(layer "In6.Cu")
		(net "M_E_CPU0_SB_DQS_DP<9>")
	)
	(segment
		(start 303.069498 -274.52955)
		(end 303.59985 -274.52955)
		(width 0.16002)
		(layer "In6.Cu")
		(net "M_E_CPU0_SB_DQS_DP<9>")
	)
	(segment
		(start 281.900376 -276.078442)
		(end 282.150566 -276.078442)
		(width 0.16002)
		(layer "In6.Cu")
		(net "M_E_CPU0_SB_DQS_DP<9>")
	)
	(segment
		(start 325.48703 -270.199358)
		(end 326.490838 -271.203674)
		(width 0.09525)
		(layer "In6.Cu")
		(net "M_E_CPU0_SB_DQS_DP<9>")
	)
	(segment
		(start 296.907458 -275.99005)
		(end 297.326558 -275.99005)
		(width 0.16002)
		(layer "In6.Cu")
		(net "M_E_CPU0_SB_DQS_DP<9>")
	)
	(segment
		(start 289.389058 -275.99005)
		(end 289.757358 -275.99005)
		(width 0.16002)
		(layer "In6.Cu")
		(net "M_E_CPU0_SB_DQS_DP<9>")
	)
	(segment
		(start 280.170636 -275.64334)
		(end 281.465274 -275.64334)
		(width 0.16002)
		(layer "In6.Cu")
		(net "M_E_CPU0_SB_DQS_DP<9>")
	)
	(segment
		(start 285.296864 -274.793456)
		(end 285.633922 -275.130514)
		(width 0.16002)
		(layer "In6.Cu")
		(net "M_E_CPU0_SB_DQS_DP<9>")
	)
	(segment
		(start 323.944996 -269.53337)
		(end 324.003924 -269.592298)
		(width 0.09525)
		(layer "In6.Cu")
		(net "M_E_CPU0_SB_DQS_DP<9>")
	)
	(segment
		(start 329.317096 -271.111472)
		(end 329.47102 -270.846042)
		(width 0.09525)
		(layer "In6.Cu")
		(net "M_E_CPU0_SB_DQS_DP<9>")
	)
	(segment
		(start 307.14315 -274.02155)
		(end 307.957728 -274.02155)
		(width 0.16002)
		(layer "In6.Cu")
		(net "M_E_CPU0_SB_DQS_DP<9>")
	)
	(segment
		(start 324.24878 -269.592298)
		(end 324.801992 -270.14551)
		(width 0.09525)
		(layer "In6.Cu")
		(net "M_E_CPU0_SB_DQS_DP<9>")
	)
	(segment
		(start 300.686724 -274.793456)
		(end 301.896018 -276.00275)
		(width 0.16002)
		(layer "In6.Cu")
		(net "M_E_CPU0_SB_DQS_DP<9>")
	)
	(segment
		(start 289.757358 -275.99005)
		(end 290.582858 -275.16455)
		(width 0.16002)
		(layer "In6.Cu")
		(net "M_E_CPU0_SB_DQS_DP<9>")
	)
	(segment
		(start 303.974754 -274.904454)
		(end 303.974754 -275.795994)
		(width 0.16002)
		(layer "In6.Cu")
		(net "M_E_CPU0_SB_DQS_DP<9>")
	)
	(segment
		(start 306.768246 -274.396454)
		(end 307.14315 -274.02155)
		(width 0.16002)
		(layer "In6.Cu")
		(net "M_E_CPU0_SB_DQS_DP<9>")
	)
	(segment
		(start 298.583858 -275.18995)
		(end 298.980352 -274.793456)
		(width 0.16002)
		(layer "In6.Cu")
		(net "M_E_CPU0_SB_DQS_DP<9>")
	)
	(segment
		(start 302.694594 -274.904454)
		(end 303.069498 -274.52955)
		(width 0.16002)
		(layer "In6.Cu")
		(net "M_E_CPU0_SB_DQS_DP<9>")
	)
	(segment
		(start 277.466044 -275.808948)
		(end 278.399748 -275.808948)
		(width 0.16002)
		(layer "In6.Cu")
		(net "M_E_CPU0_SB_DQS_DP<9>")
	)
	(segment
		(start 292.603936 -274.793456)
		(end 293.45382 -275.64334)
		(width 0.16002)
		(layer "In6.Cu")
		(net "M_E_CPU0_SB_DQS_DP<9>")
	)
	(segment
		(start 285.633922 -275.647912)
		(end 285.793942 -275.807932)
		(width 0.16002)
		(layer "In6.Cu")
		(net "M_E_CPU0_SB_DQS_DP<9>")
	)
	(segment
		(start 278.725376 -275.15693)
		(end 279.062434 -274.819872)
		(width 0.16002)
		(layer "In6.Cu")
		(net "M_E_CPU0_SB_DQS_DP<9>")
	)
	(segment
		(start 303.59985 -274.52955)
		(end 303.974754 -274.904454)
		(width 0.16002)
		(layer "In6.Cu")
		(net "M_E_CPU0_SB_DQS_DP<9>")
	)
	(segment
		(start 304.18151 -276.00275)
		(end 304.883058 -276.00275)
		(width 0.16002)
		(layer "In6.Cu")
		(net "M_E_CPU0_SB_DQS_DP<9>")
	)
	(segment
		(start 303.974754 -275.795994)
		(end 304.18151 -276.00275)
		(width 0.16002)
		(layer "In6.Cu")
		(net "M_E_CPU0_SB_DQS_DP<9>")
	)
	(segment
		(start 305.721258 -275.16455)
		(end 306.56149 -275.16455)
		(width 0.16002)
		(layer "In6.Cu")
		(net "M_E_CPU0_SB_DQS_DP<9>")
	)
	(segment
		(start 286.314642 -275.130514)
		(end 286.6517 -274.793456)
		(width 0.16002)
		(layer "In6.Cu")
		(net "M_E_CPU0_SB_DQS_DP<9>")
	)
	(segment
		(start 282.150566 -276.078442)
		(end 283.089858 -275.13915)
		(width 0.16002)
		(layer "In6.Cu")
		(net "M_E_CPU0_SB_DQS_DP<9>")
	)
	(segment
		(start 283.089858 -275.13915)
		(end 283.547058 -275.13915)
		(width 0.16002)
		(layer "In6.Cu")
		(net "M_E_CPU0_SB_DQS_DP<9>")
	)
	(segment
		(start 306.768246 -274.957794)
		(end 306.768246 -274.396454)
		(width 0.16002)
		(layer "In6.Cu")
		(net "M_E_CPU0_SB_DQS_DP<9>")
	)
	(arc
		(start 327.816464 -271.15135)
		(mid 328.081946 -271.095709)
		(end 328.342498 -271.171162)
		(width 0.09525)
		(layer "In6.Cu")
		(net "M_E_CPU0_SB_DQS_DP<9>")
	)
	(arc
		(start 325.356982 -270.14551)
		(mid 325.427342 -270.159523)
		(end 325.48703 -270.199358)
		(width 0.09525)
		(layer "In6.Cu")
		(net "M_E_CPU0_SB_DQS_DP<9>")
	)
	(arc
		(start 326.490838 -271.203674)
		(mid 326.530004 -271.231929)
		(end 326.576182 -271.246092)
		(width 0.09525)
		(layer "In6.Cu")
		(net "M_E_CPU0_SB_DQS_DP<9>")
	)
	(arc
		(start 329.196446 -271.130268)
		(mid 329.206389 -271.134111)
		(end 329.216258 -271.138142)
		(width 0.09525)
		(layer "In6.Cu")
		(net "M_E_CPU0_SB_DQS_DP<9>")
	)
	(arc
		(start 328.342498 -271.171162)
		(mid 328.526273 -271.221934)
		(end 328.711306 -271.175988)
		(width 0.09525)
		(layer "In6.Cu")
		(net "M_E_CPU0_SB_DQS_DP<9>")
	)
	(arc
		(start 326.576182 -271.246092)
		(mid 327.1545 -271.267883)
		(end 327.727056 -271.183608)
		(width 0.09525)
		(layer "In6.Cu")
		(net "M_E_CPU0_SB_DQS_DP<9>")
	)
	(arc
		(start 327.727056 -271.183608)
		(mid 327.772622 -271.169868)
		(end 327.816464 -271.15135)
		(width 0.09525)
		(layer "In6.Cu")
		(net "M_E_CPU0_SB_DQS_DP<9>")
	)
	(arc
		(start 328.719688 -271.171162)
		(mid 328.953483 -271.097295)
		(end 329.196446 -271.130268)
		(width 0.09525)
		(layer "In6.Cu")
		(net "M_E_CPU0_SB_DQS_DP<9>")
	)
	(segment
		(start 330.877926 -291.640006)
		(end 330.411074 -291.905944)
		(width 0.12954)
		(layer "F.Cu")
		(net "M_E_CPU0_SB_DQS_DP<8>")
	)
	(segment
		(start 286.42056 -315.129672)
		(end 283.444188 -314.18657)
		(width 0.16002)
		(layer "In6.Cu")
		(net "M_E_CPU0_SB_DQS_DP<8>")
	)
	(segment
		(start 288.595816 -315.360304)
		(end 287.581594 -315.360304)
		(width 0.16002)
		(layer "In6.Cu")
		(net "M_E_CPU0_SB_DQS_DP<8>")
	)
	(segment
		(start 275.784564 -314.163964)
		(end 273.860006 -314.361322)
		(width 0.16002)
		(layer "In6.Cu")
		(net "M_E_CPU0_SB_DQS_DP<8>")
	)
	(segment
		(start 328.061066 -291.656516)
		(end 327.712578 -291.656516)
		(width 0.09525)
		(layer "In6.Cu")
		(net "M_E_CPU0_SB_DQS_DP<8>")
	)
	(segment
		(start 283.444188 -314.18657)
		(end 283.288994 -314.18657)
		(width 0.16002)
		(layer "In6.Cu")
		(net "M_E_CPU0_SB_DQS_DP<8>")
	)
	(segment
		(start 325.812404 -294.08755)
		(end 325.17334 -294.726614)
		(width 0.09525)
		(layer "In6.Cu")
		(net "M_E_CPU0_SB_DQS_DP<8>")
	)
	(segment
		(start 287.581594 -315.360304)
		(end 286.42056 -315.129672)
		(width 0.16002)
		(layer "In6.Cu")
		(net "M_E_CPU0_SB_DQS_DP<8>")
	)
	(segment
		(start 276.263608 -314.23483)
		(end 275.784564 -314.163964)
		(width 0.16002)
		(layer "In6.Cu")
		(net "M_E_CPU0_SB_DQS_DP<8>")
	)
	(segment
		(start 290.861242 -314.16117)
		(end 288.595816 -315.360304)
		(width 0.16002)
		(layer "In6.Cu")
		(net "M_E_CPU0_SB_DQS_DP<8>")
	)
	(segment
		(start 283.089096 -314.247276)
		(end 282.270454 -314.79363)
		(width 0.16002)
		(layer "In6.Cu")
		(net "M_E_CPU0_SB_DQS_DP<8>")
	)
	(segment
		(start 330.411074 -291.905944)
		(end 330.564998 -291.640514)
		(width 0.09525)
		(layer "In6.Cu")
		(net "M_E_CPU0_SB_DQS_DP<8>")
	)
	(segment
		(start 280.406348 -315.360304)
		(end 279.125426 -314.971684)
		(width 0.16002)
		(layer "In6.Cu")
		(net "M_E_CPU0_SB_DQS_DP<8>")
	)
	(segment
		(start 305.72583 -314.17387)
		(end 304.95113 -314.94857)
		(width 0.16002)
		(layer "In6.Cu")
		(net "M_E_CPU0_SB_DQS_DP<8>")
	)
	(segment
		(start 291.03447 -314.16117)
		(end 290.861242 -314.16117)
		(width 0.16002)
		(layer "In6.Cu")
		(net "M_E_CPU0_SB_DQS_DP<8>")
	)
	(segment
		(start 327.712578 -291.656516)
		(end 325.812404 -293.55669)
		(width 0.09525)
		(layer "In6.Cu")
		(net "M_E_CPU0_SB_DQS_DP<8>")
	)
	(segment
		(start 293.556944 -314.967366)
		(end 291.03447 -314.16117)
		(width 0.16002)
		(layer "In6.Cu")
		(net "M_E_CPU0_SB_DQS_DP<8>")
	)
	(segment
		(start 276.883114 -314.525914)
		(end 276.263608 -314.23483)
		(width 0.16002)
		(layer "In6.Cu")
		(net "M_E_CPU0_SB_DQS_DP<8>")
	)
	(segment
		(start 304.95113 -314.94857)
		(end 299.866558 -314.94857)
		(width 0.16002)
		(layer "In6.Cu")
		(net "M_E_CPU0_SB_DQS_DP<8>")
	)
	(segment
		(start 314.893198 -305.090576)
		(end 314.893198 -305.491134)
		(width 0.16002)
		(layer "In6.Cu")
		(net "M_E_CPU0_SB_DQS_DP<8>")
	)
	(segment
		(start 325.17334 -294.810434)
		(end 325.156576 -294.827198)
		(width 0.09525)
		(layer "In6.Cu")
		(net "M_E_CPU0_SB_DQS_DP<8>")
	)
	(segment
		(start 299.10024 -314.182252)
		(end 298.267882 -314.182252)
		(width 0.16002)
		(layer "In6.Cu")
		(net "M_E_CPU0_SB_DQS_DP<8>")
	)
	(segment
		(start 325.812404 -293.55669)
		(end 325.812404 -294.08755)
		(width 0.09525)
		(layer "In6.Cu")
		(net "M_E_CPU0_SB_DQS_DP<8>")
	)
	(segment
		(start 299.866558 -314.94857)
		(end 299.10024 -314.182252)
		(width 0.16002)
		(layer "In6.Cu")
		(net "M_E_CPU0_SB_DQS_DP<8>")
	)
	(segment
		(start 273.365976 -314.361322)
		(end 273.092164 -314.635134)
		(width 0.16002)
		(layer "In6.Cu")
		(net "M_E_CPU0_SB_DQS_DP<8>")
	)
	(segment
		(start 283.288994 -314.18657)
		(end 283.089096 -314.247276)
		(width 0.16002)
		(layer "In6.Cu")
		(net "M_E_CPU0_SB_DQS_DP<8>")
	)
	(segment
		(start 295.9735 -315.360304)
		(end 295.533826 -315.360304)
		(width 0.16002)
		(layer "In6.Cu")
		(net "M_E_CPU0_SB_DQS_DP<8>")
	)
	(segment
		(start 273.860006 -314.361322)
		(end 273.365976 -314.361322)
		(width 0.16002)
		(layer "In6.Cu")
		(net "M_E_CPU0_SB_DQS_DP<8>")
	)
	(segment
		(start 312.297318 -309.448454)
		(end 307.571902 -314.17387)
		(width 0.16002)
		(layer "In6.Cu")
		(net "M_E_CPU0_SB_DQS_DP<8>")
	)
	(segment
		(start 312.297318 -308.087014)
		(end 312.297318 -309.448454)
		(width 0.16002)
		(layer "In6.Cu")
		(net "M_E_CPU0_SB_DQS_DP<8>")
	)
	(segment
		(start 298.267882 -314.182252)
		(end 298.248832 -314.194952)
		(width 0.16002)
		(layer "In6.Cu")
		(net "M_E_CPU0_SB_DQS_DP<8>")
	)
	(segment
		(start 295.533826 -315.360304)
		(end 293.556944 -314.967366)
		(width 0.16002)
		(layer "In6.Cu")
		(net "M_E_CPU0_SB_DQS_DP<8>")
	)
	(segment
		(start 329.290934 -291.575998)
		(end 329.282552 -291.580824)
		(width 0.09525)
		(layer "In6.Cu")
		(net "M_E_CPU0_SB_DQS_DP<8>")
	)
	(segment
		(start 307.571902 -314.17387)
		(end 305.72583 -314.17387)
		(width 0.16002)
		(layer "In6.Cu")
		(net "M_E_CPU0_SB_DQS_DP<8>")
	)
	(segment
		(start 328.719688 -291.580824)
		(end 328.711306 -291.575998)
		(width 0.09525)
		(layer "In6.Cu")
		(net "M_E_CPU0_SB_DQS_DP<8>")
	)
	(segment
		(start 325.17334 -294.726614)
		(end 325.17334 -294.810434)
		(width 0.09525)
		(layer "In6.Cu")
		(net "M_E_CPU0_SB_DQS_DP<8>")
	)
	(segment
		(start 298.248832 -314.194952)
		(end 297.375072 -314.778898)
		(width 0.16002)
		(layer "In6.Cu")
		(net "M_E_CPU0_SB_DQS_DP<8>")
	)
	(segment
		(start 325.156576 -294.827198)
		(end 314.893198 -305.090576)
		(width 0.16002)
		(layer "In6.Cu")
		(net "M_E_CPU0_SB_DQS_DP<8>")
	)
	(segment
		(start 314.893198 -305.491134)
		(end 312.297318 -308.087014)
		(width 0.16002)
		(layer "In6.Cu")
		(net "M_E_CPU0_SB_DQS_DP<8>")
	)
	(segment
		(start 282.270454 -314.79363)
		(end 280.90241 -315.360304)
		(width 0.16002)
		(layer "In6.Cu")
		(net "M_E_CPU0_SB_DQS_DP<8>")
	)
	(segment
		(start 279.125426 -314.971684)
		(end 276.883114 -314.525914)
		(width 0.16002)
		(layer "In6.Cu")
		(net "M_E_CPU0_SB_DQS_DP<8>")
	)
	(segment
		(start 330.564998 -291.640514)
		(end 330.541884 -291.5539)
		(width 0.09525)
		(layer "In6.Cu")
		(net "M_E_CPU0_SB_DQS_DP<8>")
	)
	(segment
		(start 297.375072 -314.778898)
		(end 295.9735 -315.360304)
		(width 0.16002)
		(layer "In6.Cu")
		(net "M_E_CPU0_SB_DQS_DP<8>")
	)
	(segment
		(start 280.90241 -315.360304)
		(end 280.406348 -315.360304)
		(width 0.16002)
		(layer "In6.Cu")
		(net "M_E_CPU0_SB_DQS_DP<8>")
	)
	(arc
		(start 329.282552 -291.580824)
		(mid 329.00112 -291.656579)
		(end 328.719688 -291.580824)
		(width 0.09525)
		(layer "In6.Cu")
		(net "M_E_CPU0_SB_DQS_DP<8>")
	)
	(arc
		(start 329.659742 -291.580824)
		(mid 329.475967 -291.530052)
		(end 329.290934 -291.575998)
		(width 0.09525)
		(layer "In6.Cu")
		(net "M_E_CPU0_SB_DQS_DP<8>")
	)
	(arc
		(start 328.711306 -291.575998)
		(mid 328.526274 -291.530084)
		(end 328.342498 -291.580824)
		(width 0.09525)
		(layer "In6.Cu")
		(net "M_E_CPU0_SB_DQS_DP<8>")
	)
	(arc
		(start 330.222606 -291.580824)
		(mid 329.941174 -291.656579)
		(end 329.659742 -291.580824)
		(width 0.09525)
		(layer "In6.Cu")
		(net "M_E_CPU0_SB_DQS_DP<8>")
	)
	(arc
		(start 330.541884 -291.5539)
		(mid 330.379233 -291.53164)
		(end 330.222606 -291.580824)
		(width 0.09525)
		(layer "In6.Cu")
		(net "M_E_CPU0_SB_DQS_DP<8>")
	)
	(arc
		(start 328.342498 -291.580824)
		(mid 328.206791 -291.637309)
		(end 328.061066 -291.656516)
		(width 0.09525)
		(layer "In6.Cu")
		(net "M_E_CPU0_SB_DQS_DP<8>")
	)
	(segment
		(start 330.877926 -286.780224)
		(end 330.411074 -287.045908)
		(width 0.12954)
		(layer "F.Cu")
		(net "M_E_CPU0_SB_DQS_DP<7>")
	)
	(segment
		(start 280.877772 -306.01031)
		(end 282.375356 -305.390042)
		(width 0.16002)
		(layer "In6.Cu")
		(net "M_E_CPU0_SB_DQS_DP<7>")
	)
	(segment
		(start 287.852612 -306.01031)
		(end 288.519108 -306.01031)
		(width 0.16002)
		(layer "In6.Cu")
		(net "M_E_CPU0_SB_DQS_DP<7>")
	)
	(segment
		(start 310.489854 -300.572424)
		(end 320.46672 -290.595558)
		(width 0.16002)
		(layer "In6.Cu")
		(net "M_E_CPU0_SB_DQS_DP<7>")
	)
	(segment
		(start 305.294284 -305.206908)
		(end 305.854862 -304.832258)
		(width 0.16002)
		(layer "In6.Cu")
		(net "M_E_CPU0_SB_DQS_DP<7>")
	)
	(segment
		(start 326.840088 -286.720788)
		(end 326.839834 -286.721042)
		(width 0.09525)
		(layer "In6.Cu")
		(net "M_E_CPU0_SB_DQS_DP<7>")
	)
	(segment
		(start 298.7929 -304.832258)
		(end 299.584618 -305.160172)
		(width 0.16002)
		(layer "In6.Cu")
		(net "M_E_CPU0_SB_DQS_DP<7>")
	)
	(segment
		(start 299.584618 -305.160172)
		(end 300.836076 -305.160172)
		(width 0.16002)
		(layer "In6.Cu")
		(net "M_E_CPU0_SB_DQS_DP<7>")
	)
	(segment
		(start 323.89064 -287.809432)
		(end 324.181978 -287.809432)
		(width 0.16002)
		(layer "In6.Cu")
		(net "M_E_CPU0_SB_DQS_DP<7>")
	)
	(segment
		(start 324.181978 -287.809432)
		(end 324.497446 -287.493964)
		(width 0.16002)
		(layer "In6.Cu")
		(net "M_E_CPU0_SB_DQS_DP<7>")
	)
	(segment
		(start 324.51421 -287.4772)
		(end 324.51421 -287.393888)
		(width 0.09525)
		(layer "In6.Cu")
		(net "M_E_CPU0_SB_DQS_DP<7>")
	)
	(segment
		(start 324.51421 -287.393888)
		(end 324.817486 -287.090612)
		(width 0.09525)
		(layer "In6.Cu")
		(net "M_E_CPU0_SB_DQS_DP<7>")
	)
	(segment
		(start 285.799784 -305.160172)
		(end 287.852612 -306.01031)
		(width 0.16002)
		(layer "In6.Cu")
		(net "M_E_CPU0_SB_DQS_DP<7>")
	)
	(segment
		(start 283.218636 -304.82667)
		(end 283.611828 -304.82667)
		(width 0.16002)
		(layer "In6.Cu")
		(net "M_E_CPU0_SB_DQS_DP<7>")
	)
	(segment
		(start 284.417262 -305.160172)
		(end 285.799784 -305.160172)
		(width 0.16002)
		(layer "In6.Cu")
		(net "M_E_CPU0_SB_DQS_DP<7>")
	)
	(segment
		(start 328.711306 -286.715962)
		(end 328.719688 -286.720788)
		(width 0.09525)
		(layer "In6.Cu")
		(net "M_E_CPU0_SB_DQS_DP<7>")
	)
	(segment
		(start 291.867844 -305.160172)
		(end 293.263574 -305.160172)
		(width 0.16002)
		(layer "In6.Cu")
		(net "M_E_CPU0_SB_DQS_DP<7>")
	)
	(segment
		(start 273.092164 -305.28514)
		(end 273.365976 -305.011328)
		(width 0.16002)
		(layer "In6.Cu")
		(net "M_E_CPU0_SB_DQS_DP<7>")
	)
	(segment
		(start 293.263574 -305.160172)
		(end 295.316402 -306.01031)
		(width 0.16002)
		(layer "In6.Cu")
		(net "M_E_CPU0_SB_DQS_DP<7>")
	)
	(segment
		(start 329.282552 -286.720788)
		(end 329.290934 -286.715962)
		(width 0.09525)
		(layer "In6.Cu")
		(net "M_E_CPU0_SB_DQS_DP<7>")
	)
	(segment
		(start 300.836076 -305.160172)
		(end 301.901098 -305.60137)
		(width 0.16002)
		(layer "In6.Cu")
		(net "M_E_CPU0_SB_DQS_DP<7>")
	)
	(segment
		(start 321.555618 -290.144454)
		(end 323.89064 -287.809432)
		(width 0.16002)
		(layer "In6.Cu")
		(net "M_E_CPU0_SB_DQS_DP<7>")
	)
	(segment
		(start 305.854862 -304.832258)
		(end 306.529486 -304.832258)
		(width 0.16002)
		(layer "In6.Cu")
		(net "M_E_CPU0_SB_DQS_DP<7>")
	)
	(segment
		(start 273.365976 -305.011328)
		(end 273.971004 -305.011328)
		(width 0.16002)
		(layer "In6.Cu")
		(net "M_E_CPU0_SB_DQS_DP<7>")
	)
	(segment
		(start 326.62876 -286.669734)
		(end 326.651112 -286.669734)
		(width 0.09525)
		(layer "In6.Cu")
		(net "M_E_CPU0_SB_DQS_DP<7>")
	)
	(segment
		(start 290.78809 -304.809398)
		(end 290.791646 -304.806858)
		(width 0.16002)
		(layer "In6.Cu")
		(net "M_E_CPU0_SB_DQS_DP<7>")
	)
	(segment
		(start 330.564998 -286.780478)
		(end 330.411074 -287.045908)
		(width 0.09525)
		(layer "In6.Cu")
		(net "M_E_CPU0_SB_DQS_DP<7>")
	)
	(segment
		(start 275.02739 -304.80127)
		(end 276.043136 -304.80127)
		(width 0.16002)
		(layer "In6.Cu")
		(net "M_E_CPU0_SB_DQS_DP<7>")
	)
	(segment
		(start 276.74189 -305.09083)
		(end 280.412952 -306.01031)
		(width 0.16002)
		(layer "In6.Cu")
		(net "M_E_CPU0_SB_DQS_DP<7>")
	)
	(segment
		(start 330.541884 -286.693864)
		(end 330.564998 -286.780478)
		(width 0.09525)
		(layer "In6.Cu")
		(net "M_E_CPU0_SB_DQS_DP<7>")
	)
	(segment
		(start 283.611828 -304.82667)
		(end 284.417262 -305.160172)
		(width 0.16002)
		(layer "In6.Cu")
		(net "M_E_CPU0_SB_DQS_DP<7>")
	)
	(segment
		(start 291.014658 -304.806858)
		(end 291.867844 -305.160172)
		(width 0.16002)
		(layer "In6.Cu")
		(net "M_E_CPU0_SB_DQS_DP<7>")
	)
	(segment
		(start 288.519108 -306.01031)
		(end 290.209224 -305.195986)
		(width 0.16002)
		(layer "In6.Cu")
		(net "M_E_CPU0_SB_DQS_DP<7>")
	)
	(segment
		(start 324.497446 -287.493964)
		(end 324.51421 -287.4772)
		(width 0.09525)
		(layer "In6.Cu")
		(net "M_E_CPU0_SB_DQS_DP<7>")
	)
	(segment
		(start 280.412952 -306.01031)
		(end 280.877772 -306.01031)
		(width 0.16002)
		(layer "In6.Cu")
		(net "M_E_CPU0_SB_DQS_DP<7>")
	)
	(segment
		(start 324.817486 -287.090612)
		(end 326.058022 -287.090612)
		(width 0.09525)
		(layer "In6.Cu")
		(net "M_E_CPU0_SB_DQS_DP<7>")
	)
	(segment
		(start 298.045886 -305.013614)
		(end 298.290234 -304.832258)
		(width 0.16002)
		(layer "In6.Cu")
		(net "M_E_CPU0_SB_DQS_DP<7>")
	)
	(segment
		(start 309.67426 -302.541178)
		(end 310.489854 -300.572424)
		(width 0.16002)
		(layer "In6.Cu")
		(net "M_E_CPU0_SB_DQS_DP<7>")
	)
	(segment
		(start 301.901098 -305.60137)
		(end 303.310036 -305.60137)
		(width 0.16002)
		(layer "In6.Cu")
		(net "M_E_CPU0_SB_DQS_DP<7>")
	)
	(segment
		(start 295.316402 -306.01031)
		(end 296.181018 -306.01031)
		(width 0.16002)
		(layer "In6.Cu")
		(net "M_E_CPU0_SB_DQS_DP<7>")
	)
	(segment
		(start 290.791646 -304.806858)
		(end 291.014658 -304.806858)
		(width 0.16002)
		(layer "In6.Cu")
		(net "M_E_CPU0_SB_DQS_DP<7>")
	)
	(segment
		(start 303.310036 -305.60137)
		(end 305.294284 -305.206908)
		(width 0.16002)
		(layer "In6.Cu")
		(net "M_E_CPU0_SB_DQS_DP<7>")
	)
	(segment
		(start 306.529486 -304.832258)
		(end 307.986938 -304.2285)
		(width 0.16002)
		(layer "In6.Cu")
		(net "M_E_CPU0_SB_DQS_DP<7>")
	)
	(segment
		(start 276.043136 -304.80127)
		(end 276.74189 -305.09083)
		(width 0.16002)
		(layer "In6.Cu")
		(net "M_E_CPU0_SB_DQS_DP<7>")
	)
	(segment
		(start 282.375356 -305.390042)
		(end 283.218636 -304.82667)
		(width 0.16002)
		(layer "In6.Cu")
		(net "M_E_CPU0_SB_DQS_DP<7>")
	)
	(segment
		(start 296.181018 -306.01031)
		(end 298.045886 -305.013614)
		(width 0.16002)
		(layer "In6.Cu")
		(net "M_E_CPU0_SB_DQS_DP<7>")
	)
	(segment
		(start 307.986938 -304.2285)
		(end 309.67426 -302.541178)
		(width 0.16002)
		(layer "In6.Cu")
		(net "M_E_CPU0_SB_DQS_DP<7>")
	)
	(segment
		(start 320.46672 -290.595558)
		(end 321.555618 -290.144454)
		(width 0.16002)
		(layer "In6.Cu")
		(net "M_E_CPU0_SB_DQS_DP<7>")
	)
	(segment
		(start 298.290234 -304.832258)
		(end 298.7929 -304.832258)
		(width 0.16002)
		(layer "In6.Cu")
		(net "M_E_CPU0_SB_DQS_DP<7>")
	)
	(segment
		(start 273.971004 -305.011328)
		(end 275.02739 -304.80127)
		(width 0.16002)
		(layer "In6.Cu")
		(net "M_E_CPU0_SB_DQS_DP<7>")
	)
	(segment
		(start 326.058022 -287.090612)
		(end 326.372728 -286.775906)
		(width 0.09525)
		(layer "In6.Cu")
		(net "M_E_CPU0_SB_DQS_DP<7>")
	)
	(segment
		(start 290.209224 -305.195986)
		(end 290.78809 -304.809398)
		(width 0.16002)
		(layer "In6.Cu")
		(net "M_E_CPU0_SB_DQS_DP<7>")
	)
	(segment
		(start 327.771252 -286.715962)
		(end 327.779634 -286.720788)
		(width 0.09525)
		(layer "In6.Cu")
		(net "M_E_CPU0_SB_DQS_DP<7>")
	)
	(arc
		(start 329.290934 -286.715962)
		(mid 329.475966 -286.670048)
		(end 329.659742 -286.720788)
		(width 0.09525)
		(layer "In6.Cu")
		(net "M_E_CPU0_SB_DQS_DP<7>")
	)
	(arc
		(start 327.779634 -286.720788)
		(mid 328.061066 -286.796577)
		(end 328.342498 -286.720788)
		(width 0.09525)
		(layer "In6.Cu")
		(net "M_E_CPU0_SB_DQS_DP<7>")
	)
	(arc
		(start 328.719688 -286.720788)
		(mid 329.00112 -286.796577)
		(end 329.282552 -286.720788)
		(width 0.09525)
		(layer "In6.Cu")
		(net "M_E_CPU0_SB_DQS_DP<7>")
	)
	(arc
		(start 326.839834 -286.721042)
		(mid 327.121186 -286.79667)
		(end 327.402444 -286.720788)
		(width 0.09525)
		(layer "In6.Cu")
		(net "M_E_CPU0_SB_DQS_DP<7>")
	)
	(arc
		(start 326.651112 -286.669734)
		(mid 326.748978 -286.682756)
		(end 326.840088 -286.720788)
		(width 0.09525)
		(layer "In6.Cu")
		(net "M_E_CPU0_SB_DQS_DP<7>")
	)
	(arc
		(start 326.372728 -286.775906)
		(mid 326.490181 -286.697333)
		(end 326.62876 -286.669734)
		(width 0.09525)
		(layer "In6.Cu")
		(net "M_E_CPU0_SB_DQS_DP<7>")
	)
	(arc
		(start 328.342498 -286.720788)
		(mid 328.526273 -286.670016)
		(end 328.711306 -286.715962)
		(width 0.09525)
		(layer "In6.Cu")
		(net "M_E_CPU0_SB_DQS_DP<7>")
	)
	(arc
		(start 330.222606 -286.720788)
		(mid 330.379233 -286.671602)
		(end 330.541884 -286.693864)
		(width 0.09525)
		(layer "In6.Cu")
		(net "M_E_CPU0_SB_DQS_DP<7>")
	)
	(arc
		(start 329.659742 -286.720788)
		(mid 329.941174 -286.796577)
		(end 330.222606 -286.720788)
		(width 0.09525)
		(layer "In6.Cu")
		(net "M_E_CPU0_SB_DQS_DP<7>")
	)
	(arc
		(start 327.402444 -286.720788)
		(mid 327.586219 -286.670016)
		(end 327.771252 -286.715962)
		(width 0.09525)
		(layer "In6.Cu")
		(net "M_E_CPU0_SB_DQS_DP<7>")
	)
	(segment
		(start 330.877926 -281.920188)
		(end 330.411074 -282.186126)
		(width 0.12954)
		(layer "F.Cu")
		(net "M_E_CPU0_SB_DQS_DP<6>")
	)
	(segment
		(start 282.831286 -295.826942)
		(end 283.178758 -295.47947)
		(width 0.16002)
		(layer "In6.Cu")
		(net "M_E_CPU0_SB_DQS_DP<6>")
	)
	(segment
		(start 308.219094 -294.859964)
		(end 310.958484 -292.120574)
		(width 0.16002)
		(layer "In6.Cu")
		(net "M_E_CPU0_SB_DQS_DP<6>")
	)
	(segment
		(start 287.776158 -296.660316)
		(end 288.481262 -296.660316)
		(width 0.16002)
		(layer "In6.Cu")
		(net "M_E_CPU0_SB_DQS_DP<6>")
	)
	(segment
		(start 323.895974 -281.97429)
		(end 323.919596 -281.97429)
		(width 0.09525)
		(layer "In6.Cu")
		(net "M_E_CPU0_SB_DQS_DP<6>")
	)
	(segment
		(start 286.057848 -295.810178)
		(end 286.34563 -295.929304)
		(width 0.16002)
		(layer "In6.Cu")
		(net "M_E_CPU0_SB_DQS_DP<6>")
	)
	(segment
		(start 303.19472 -296.43705)
		(end 303.67478 -296.43705)
		(width 0.16002)
		(layer "In6.Cu")
		(net "M_E_CPU0_SB_DQS_DP<6>")
	)
	(segment
		(start 283.178758 -295.47947)
		(end 283.612082 -295.47947)
		(width 0.16002)
		(layer "In6.Cu")
		(net "M_E_CPU0_SB_DQS_DP<6>")
	)
	(segment
		(start 330.541884 -281.834082)
		(end 330.564998 -281.920696)
		(width 0.09525)
		(layer "In6.Cu")
		(net "M_E_CPU0_SB_DQS_DP<6>")
	)
	(segment
		(start 327.784968 -281.864054)
		(end 327.790302 -281.867102)
		(width 0.09525)
		(layer "In6.Cu")
		(net "M_E_CPU0_SB_DQS_DP<6>")
	)
	(segment
		(start 323.919596 -281.97429)
		(end 323.978524 -281.915362)
		(width 0.09525)
		(layer "In6.Cu")
		(net "M_E_CPU0_SB_DQS_DP<6>")
	)
	(segment
		(start 286.34563 -295.929304)
		(end 286.582104 -296.165778)
		(width 0.16002)
		(layer "In6.Cu")
		(net "M_E_CPU0_SB_DQS_DP<6>")
	)
	(segment
		(start 297.264328 -296.277792)
		(end 297.639994 -296.12209)
		(width 0.16002)
		(layer "In6.Cu")
		(net "M_E_CPU0_SB_DQS_DP<6>")
	)
	(segment
		(start 273.365976 -295.661334)
		(end 274.447762 -295.661334)
		(width 0.16002)
		(layer "In6.Cu")
		(net "M_E_CPU0_SB_DQS_DP<6>")
	)
	(segment
		(start 293.785798 -295.810178)
		(end 294.166798 -296.191178)
		(width 0.16002)
		(layer "In6.Cu")
		(net "M_E_CPU0_SB_DQS_DP<6>")
	)
	(segment
		(start 306.716938 -295.482264)
		(end 308.219094 -294.859964)
		(width 0.16002)
		(layer "In6.Cu")
		(net "M_E_CPU0_SB_DQS_DP<6>")
	)
	(segment
		(start 286.582104 -296.165778)
		(end 287.776158 -296.660316)
		(width 0.16002)
		(layer "In6.Cu")
		(net "M_E_CPU0_SB_DQS_DP<6>")
	)
	(segment
		(start 301.36211 -295.810178)
		(end 301.872142 -296.32021)
		(width 0.16002)
		(layer "In6.Cu")
		(net "M_E_CPU0_SB_DQS_DP<6>")
	)
	(segment
		(start 305.43627 -295.837864)
		(end 305.79187 -295.482264)
		(width 0.16002)
		(layer "In6.Cu")
		(net "M_E_CPU0_SB_DQS_DP<6>")
	)
	(segment
		(start 296.024046 -296.660316)
		(end 296.94759 -296.277792)
		(width 0.16002)
		(layer "In6.Cu")
		(net "M_E_CPU0_SB_DQS_DP<6>")
	)
	(segment
		(start 283.612082 -295.47947)
		(end 284.410404 -295.810178)
		(width 0.16002)
		(layer "In6.Cu")
		(net "M_E_CPU0_SB_DQS_DP<6>")
	)
	(segment
		(start 295.299638 -296.660316)
		(end 296.024046 -296.660316)
		(width 0.16002)
		(layer "In6.Cu")
		(net "M_E_CPU0_SB_DQS_DP<6>")
	)
	(segment
		(start 330.564998 -281.920696)
		(end 330.411074 -282.186126)
		(width 0.09525)
		(layer "In6.Cu")
		(net "M_E_CPU0_SB_DQS_DP<6>")
	)
	(segment
		(start 298.793662 -295.497504)
		(end 299.54855 -295.810178)
		(width 0.16002)
		(layer "In6.Cu")
		(net "M_E_CPU0_SB_DQS_DP<6>")
	)
	(segment
		(start 303.67478 -296.43705)
		(end 303.79162 -296.32021)
		(width 0.16002)
		(layer "In6.Cu")
		(net "M_E_CPU0_SB_DQS_DP<6>")
	)
	(segment
		(start 278.947626 -296.660316)
		(end 280.819098 -296.660316)
		(width 0.16002)
		(layer "In6.Cu")
		(net "M_E_CPU0_SB_DQS_DP<6>")
	)
	(segment
		(start 327.779888 -281.861006)
		(end 327.784968 -281.864054)
		(width 0.09525)
		(layer "In6.Cu")
		(net "M_E_CPU0_SB_DQS_DP<6>")
	)
	(segment
		(start 310.958484 -292.120574)
		(end 311.30621 -291.281104)
		(width 0.16002)
		(layer "In6.Cu")
		(net "M_E_CPU0_SB_DQS_DP<6>")
	)
	(segment
		(start 304.27168 -296.32021)
		(end 305.43627 -295.837864)
		(width 0.16002)
		(layer "In6.Cu")
		(net "M_E_CPU0_SB_DQS_DP<6>")
	)
	(segment
		(start 303.07788 -296.32021)
		(end 303.19472 -296.43705)
		(width 0.16002)
		(layer "In6.Cu")
		(net "M_E_CPU0_SB_DQS_DP<6>")
	)
	(segment
		(start 290.668964 -295.456864)
		(end 291.130482 -295.456864)
		(width 0.16002)
		(layer "In6.Cu")
		(net "M_E_CPU0_SB_DQS_DP<6>")
	)
	(segment
		(start 323.978524 -281.915362)
		(end 325.344028 -281.915362)
		(width 0.09525)
		(layer "In6.Cu")
		(net "M_E_CPU0_SB_DQS_DP<6>")
	)
	(segment
		(start 294.166798 -296.191178)
		(end 295.299638 -296.660316)
		(width 0.16002)
		(layer "In6.Cu")
		(net "M_E_CPU0_SB_DQS_DP<6>")
	)
	(segment
		(start 296.94759 -296.277792)
		(end 297.264328 -296.277792)
		(width 0.16002)
		(layer "In6.Cu")
		(net "M_E_CPU0_SB_DQS_DP<6>")
	)
	(segment
		(start 274.447762 -295.661334)
		(end 274.978876 -295.44137)
		(width 0.16002)
		(layer "In6.Cu")
		(net "M_E_CPU0_SB_DQS_DP<6>")
	)
	(segment
		(start 327.778872 -281.859736)
		(end 327.778364 -281.860244)
		(width 0.09525)
		(layer "In6.Cu")
		(net "M_E_CPU0_SB_DQS_DP<6>")
	)
	(segment
		(start 288.481262 -296.660316)
		(end 290.161726 -295.964102)
		(width 0.16002)
		(layer "In6.Cu")
		(net "M_E_CPU0_SB_DQS_DP<6>")
	)
	(segment
		(start 301.872142 -296.32021)
		(end 303.07788 -296.32021)
		(width 0.16002)
		(layer "In6.Cu")
		(net "M_E_CPU0_SB_DQS_DP<6>")
	)
	(segment
		(start 298.26458 -295.497504)
		(end 298.793662 -295.497504)
		(width 0.16002)
		(layer "In6.Cu")
		(net "M_E_CPU0_SB_DQS_DP<6>")
	)
	(segment
		(start 280.819098 -296.660316)
		(end 282.831286 -295.826942)
		(width 0.16002)
		(layer "In6.Cu")
		(net "M_E_CPU0_SB_DQS_DP<6>")
	)
	(segment
		(start 273.092164 -295.935146)
		(end 273.365976 -295.661334)
		(width 0.16002)
		(layer "In6.Cu")
		(net "M_E_CPU0_SB_DQS_DP<6>")
	)
	(segment
		(start 329.282552 -281.861006)
		(end 329.290934 -281.85618)
		(width 0.09525)
		(layer "In6.Cu")
		(net "M_E_CPU0_SB_DQS_DP<6>")
	)
	(segment
		(start 290.161726 -295.964102)
		(end 290.668964 -295.456864)
		(width 0.16002)
		(layer "In6.Cu")
		(net "M_E_CPU0_SB_DQS_DP<6>")
	)
	(segment
		(start 276.004782 -295.44137)
		(end 278.947626 -296.660316)
		(width 0.16002)
		(layer "In6.Cu")
		(net "M_E_CPU0_SB_DQS_DP<6>")
	)
	(segment
		(start 274.978876 -295.44137)
		(end 276.004782 -295.44137)
		(width 0.16002)
		(layer "In6.Cu")
		(net "M_E_CPU0_SB_DQS_DP<6>")
	)
	(segment
		(start 291.130482 -295.456864)
		(end 291.983414 -295.810178)
		(width 0.16002)
		(layer "In6.Cu")
		(net "M_E_CPU0_SB_DQS_DP<6>")
	)
	(segment
		(start 303.79162 -296.32021)
		(end 304.27168 -296.32021)
		(width 0.16002)
		(layer "In6.Cu")
		(net "M_E_CPU0_SB_DQS_DP<6>")
	)
	(segment
		(start 305.79187 -295.482264)
		(end 306.716938 -295.482264)
		(width 0.16002)
		(layer "In6.Cu")
		(net "M_E_CPU0_SB_DQS_DP<6>")
	)
	(segment
		(start 328.711306 -281.85618)
		(end 328.719688 -281.861006)
		(width 0.09525)
		(layer "In6.Cu")
		(net "M_E_CPU0_SB_DQS_DP<6>")
	)
	(segment
		(start 325.344028 -281.915362)
		(end 325.537068 -281.722322)
		(width 0.09525)
		(layer "In6.Cu")
		(net "M_E_CPU0_SB_DQS_DP<6>")
	)
	(segment
		(start 291.983414 -295.810178)
		(end 293.785798 -295.810178)
		(width 0.16002)
		(layer "In6.Cu")
		(net "M_E_CPU0_SB_DQS_DP<6>")
	)
	(segment
		(start 311.30621 -291.281104)
		(end 320.613024 -281.97429)
		(width 0.16002)
		(layer "In6.Cu")
		(net "M_E_CPU0_SB_DQS_DP<6>")
	)
	(segment
		(start 320.613024 -281.97429)
		(end 323.895974 -281.97429)
		(width 0.16002)
		(layer "In6.Cu")
		(net "M_E_CPU0_SB_DQS_DP<6>")
	)
	(segment
		(start 284.410404 -295.810178)
		(end 286.057848 -295.810178)
		(width 0.16002)
		(layer "In6.Cu")
		(net "M_E_CPU0_SB_DQS_DP<6>")
	)
	(segment
		(start 297.639994 -296.12209)
		(end 298.26458 -295.497504)
		(width 0.16002)
		(layer "In6.Cu")
		(net "M_E_CPU0_SB_DQS_DP<6>")
	)
	(segment
		(start 325.537068 -281.722322)
		(end 327.265792 -281.722322)
		(width 0.09525)
		(layer "In6.Cu")
		(net "M_E_CPU0_SB_DQS_DP<6>")
	)
	(segment
		(start 299.54855 -295.810178)
		(end 301.36211 -295.810178)
		(width 0.16002)
		(layer "In6.Cu")
		(net "M_E_CPU0_SB_DQS_DP<6>")
	)
	(arc
		(start 327.790302 -281.867102)
		(mid 328.06721 -281.936779)
		(end 328.342498 -281.861006)
		(width 0.09525)
		(layer "In6.Cu")
		(net "M_E_CPU0_SB_DQS_DP<6>")
	)
	(arc
		(start 327.778364 -281.860244)
		(mid 327.779126 -281.860624)
		(end 327.779888 -281.861006)
		(width 0.09525)
		(layer "In6.Cu")
		(net "M_E_CPU0_SB_DQS_DP<6>")
	)
	(arc
		(start 328.719688 -281.861006)
		(mid 329.00112 -281.936761)
		(end 329.282552 -281.861006)
		(width 0.09525)
		(layer "In6.Cu")
		(net "M_E_CPU0_SB_DQS_DP<6>")
	)
	(arc
		(start 327.265792 -281.722322)
		(mid 327.531347 -281.757351)
		(end 327.778872 -281.859736)
		(width 0.09525)
		(layer "In6.Cu")
		(net "M_E_CPU0_SB_DQS_DP<6>")
	)
	(arc
		(start 328.342498 -281.861006)
		(mid 328.526273 -281.810234)
		(end 328.711306 -281.85618)
		(width 0.09525)
		(layer "In6.Cu")
		(net "M_E_CPU0_SB_DQS_DP<6>")
	)
	(arc
		(start 329.290934 -281.85618)
		(mid 329.475966 -281.810266)
		(end 329.659742 -281.861006)
		(width 0.09525)
		(layer "In6.Cu")
		(net "M_E_CPU0_SB_DQS_DP<6>")
	)
	(arc
		(start 329.659742 -281.861006)
		(mid 329.941174 -281.936761)
		(end 330.222606 -281.861006)
		(width 0.09525)
		(layer "In6.Cu")
		(net "M_E_CPU0_SB_DQS_DP<6>")
	)
	(arc
		(start 330.222606 -281.861006)
		(mid 330.379233 -281.81182)
		(end 330.541884 -281.834082)
		(width 0.09525)
		(layer "In6.Cu")
		(net "M_E_CPU0_SB_DQS_DP<6>")
	)
	(segment
		(start 330.877926 -277.060152)
		(end 330.411074 -277.32609)
		(width 0.12954)
		(layer "F.Cu")
		(net "M_E_CPU0_SB_DQS_DP<5>")
	)
	(segment
		(start 293.8907 -286.74187)
		(end 293.210996 -286.460184)
		(width 0.16002)
		(layer "In6.Cu")
		(net "M_E_CPU0_SB_DQS_DP<5>")
	)
	(segment
		(start 273.365976 -286.31134)
		(end 273.092164 -286.585152)
		(width 0.16002)
		(layer "In6.Cu")
		(net "M_E_CPU0_SB_DQS_DP<5>")
	)
	(segment
		(start 290.11753 -286.70377)
		(end 289.668458 -286.70377)
		(width 0.16002)
		(layer "In6.Cu")
		(net "M_E_CPU0_SB_DQS_DP<5>")
	)
	(segment
		(start 324.019418 -276.35073)
		(end 317.779146 -276.35073)
		(width 0.16002)
		(layer "In6.Cu")
		(net "M_E_CPU0_SB_DQS_DP<5>")
	)
	(segment
		(start 274.573492 -286.31134)
		(end 273.365976 -286.31134)
		(width 0.16002)
		(layer "In6.Cu")
		(net "M_E_CPU0_SB_DQS_DP<5>")
	)
	(segment
		(start 294.550338 -287.01492)
		(end 294.397684 -287.078166)
		(width 0.16002)
		(layer "In6.Cu")
		(net "M_E_CPU0_SB_DQS_DP<5>")
	)
	(segment
		(start 298.672758 -286.13227)
		(end 298.25823 -286.13227)
		(width 0.16002)
		(layer "In6.Cu")
		(net "M_E_CPU0_SB_DQS_DP<5>")
	)
	(segment
		(start 324.101968 -276.291802)
		(end 324.04304 -276.35073)
		(width 0.09525)
		(layer "In6.Cu")
		(net "M_E_CPU0_SB_DQS_DP<5>")
	)
	(segment
		(start 291.065458 -286.10687)
		(end 290.71443 -286.10687)
		(width 0.16002)
		(layer "In6.Cu")
		(net "M_E_CPU0_SB_DQS_DP<5>")
	)
	(segment
		(start 275.973286 -286.09417)
		(end 275.098002 -286.09417)
		(width 0.16002)
		(layer "In6.Cu")
		(net "M_E_CPU0_SB_DQS_DP<5>")
	)
	(segment
		(start 330.564998 -277.06066)
		(end 330.541884 -276.974046)
		(width 0.09525)
		(layer "In6.Cu")
		(net "M_E_CPU0_SB_DQS_DP<5>")
	)
	(segment
		(start 305.77663 -286.13227)
		(end 304.97653 -286.93237)
		(width 0.16002)
		(layer "In6.Cu")
		(net "M_E_CPU0_SB_DQS_DP<5>")
	)
	(segment
		(start 297.44543 -286.94507)
		(end 296.970958 -286.94507)
		(width 0.16002)
		(layer "In6.Cu")
		(net "M_E_CPU0_SB_DQS_DP<5>")
	)
	(segment
		(start 291.418772 -286.460184)
		(end 291.065458 -286.10687)
		(width 0.16002)
		(layer "In6.Cu")
		(net "M_E_CPU0_SB_DQS_DP<5>")
	)
	(segment
		(start 283.874972 -286.460184)
		(end 283.496258 -286.08147)
		(width 0.16002)
		(layer "In6.Cu")
		(net "M_E_CPU0_SB_DQS_DP<5>")
	)
	(segment
		(start 293.953946 -286.894524)
		(end 293.8907 -286.741616)
		(width 0.16002)
		(layer "In6.Cu")
		(net "M_E_CPU0_SB_DQS_DP<5>")
	)
	(segment
		(start 324.04304 -276.35073)
		(end 324.019418 -276.35073)
		(width 0.09525)
		(layer "In6.Cu")
		(net "M_E_CPU0_SB_DQS_DP<5>")
	)
	(segment
		(start 275.098002 -286.09417)
		(end 274.573492 -286.31134)
		(width 0.16002)
		(layer "In6.Cu")
		(net "M_E_CPU0_SB_DQS_DP<5>")
	)
	(segment
		(start 281.484578 -287.310322)
		(end 279.170638 -287.310322)
		(width 0.16002)
		(layer "In6.Cu")
		(net "M_E_CPU0_SB_DQS_DP<5>")
	)
	(segment
		(start 278.33701 -286.476694)
		(end 276.35581 -286.476694)
		(width 0.16002)
		(layer "In6.Cu")
		(net "M_E_CPU0_SB_DQS_DP<5>")
	)
	(segment
		(start 317.779146 -276.35073)
		(end 309.259478 -284.870398)
		(width 0.16002)
		(layer "In6.Cu")
		(net "M_E_CPU0_SB_DQS_DP<5>")
	)
	(segment
		(start 276.35581 -286.476694)
		(end 275.973286 -286.09417)
		(width 0.16002)
		(layer "In6.Cu")
		(net "M_E_CPU0_SB_DQS_DP<5>")
	)
	(segment
		(start 301.3837 -286.460184)
		(end 299.000672 -286.460184)
		(width 0.16002)
		(layer "In6.Cu")
		(net "M_E_CPU0_SB_DQS_DP<5>")
	)
	(segment
		(start 328.711306 -276.996144)
		(end 328.71156 -276.99589)
		(width 0.09525)
		(layer "In6.Cu")
		(net "M_E_CPU0_SB_DQS_DP<5>")
	)
	(segment
		(start 289.668458 -286.70377)
		(end 289.061906 -287.310322)
		(width 0.16002)
		(layer "In6.Cu")
		(net "M_E_CPU0_SB_DQS_DP<5>")
	)
	(segment
		(start 328.342244 -277.000716)
		(end 328.34199 -277.000716)
		(width 0.09525)
		(layer "In6.Cu")
		(net "M_E_CPU0_SB_DQS_DP<5>")
	)
	(segment
		(start 309.259478 -284.870398)
		(end 306.213002 -286.13227)
		(width 0.16002)
		(layer "In6.Cu")
		(net "M_E_CPU0_SB_DQS_DP<5>")
	)
	(segment
		(start 304.97653 -286.93237)
		(end 301.855886 -286.93237)
		(width 0.16002)
		(layer "In6.Cu")
		(net "M_E_CPU0_SB_DQS_DP<5>")
	)
	(segment
		(start 287.070038 -287.310322)
		(end 286.2199 -286.460184)
		(width 0.16002)
		(layer "In6.Cu")
		(net "M_E_CPU0_SB_DQS_DP<5>")
	)
	(segment
		(start 293.8907 -286.741616)
		(end 293.8907 -286.74187)
		(width 0.16002)
		(layer "In6.Cu")
		(net "M_E_CPU0_SB_DQS_DP<5>")
	)
	(segment
		(start 324.302628 -276.291802)
		(end 324.101968 -276.291802)
		(width 0.09525)
		(layer "In6.Cu")
		(net "M_E_CPU0_SB_DQS_DP<5>")
	)
	(segment
		(start 327.441052 -276.799802)
		(end 324.810628 -276.799802)
		(width 0.09525)
		(layer "In6.Cu")
		(net "M_E_CPU0_SB_DQS_DP<5>")
	)
	(segment
		(start 281.870404 -286.924496)
		(end 281.484578 -287.310322)
		(width 0.16002)
		(layer "In6.Cu")
		(net "M_E_CPU0_SB_DQS_DP<5>")
	)
	(segment
		(start 279.170638 -287.310322)
		(end 278.33701 -286.476694)
		(width 0.16002)
		(layer "In6.Cu")
		(net "M_E_CPU0_SB_DQS_DP<5>")
	)
	(segment
		(start 283.496258 -286.08147)
		(end 283.178758 -286.08147)
		(width 0.16002)
		(layer "In6.Cu")
		(net "M_E_CPU0_SB_DQS_DP<5>")
	)
	(segment
		(start 328.719688 -277.00097)
		(end 328.711306 -276.996144)
		(width 0.09525)
		(layer "In6.Cu")
		(net "M_E_CPU0_SB_DQS_DP<5>")
	)
	(segment
		(start 290.71443 -286.10687)
		(end 290.11753 -286.70377)
		(width 0.16002)
		(layer "In6.Cu")
		(net "M_E_CPU0_SB_DQS_DP<5>")
	)
	(segment
		(start 296.605706 -287.310322)
		(end 295.26357 -287.310322)
		(width 0.16002)
		(layer "In6.Cu")
		(net "M_E_CPU0_SB_DQS_DP<5>")
	)
	(segment
		(start 286.2199 -286.460184)
		(end 283.874972 -286.460184)
		(width 0.16002)
		(layer "In6.Cu")
		(net "M_E_CPU0_SB_DQS_DP<5>")
	)
	(segment
		(start 295.26357 -287.310322)
		(end 294.550338 -287.01492)
		(width 0.16002)
		(layer "In6.Cu")
		(net "M_E_CPU0_SB_DQS_DP<5>")
	)
	(segment
		(start 330.411074 -277.32609)
		(end 330.564998 -277.06066)
		(width 0.09525)
		(layer "In6.Cu")
		(net "M_E_CPU0_SB_DQS_DP<5>")
	)
	(segment
		(start 327.77684 -276.99843)
		(end 327.441052 -276.799802)
		(width 0.09525)
		(layer "In6.Cu")
		(net "M_E_CPU0_SB_DQS_DP<5>")
	)
	(segment
		(start 298.25823 -286.13227)
		(end 297.44543 -286.94507)
		(width 0.16002)
		(layer "In6.Cu")
		(net "M_E_CPU0_SB_DQS_DP<5>")
	)
	(segment
		(start 294.397684 -287.078166)
		(end 293.953946 -286.894524)
		(width 0.16002)
		(layer "In6.Cu")
		(net "M_E_CPU0_SB_DQS_DP<5>")
	)
	(segment
		(start 283.178758 -286.08147)
		(end 282.664916 -286.595312)
		(width 0.16002)
		(layer "In6.Cu")
		(net "M_E_CPU0_SB_DQS_DP<5>")
	)
	(segment
		(start 306.213002 -286.13227)
		(end 305.77663 -286.13227)
		(width 0.16002)
		(layer "In6.Cu")
		(net "M_E_CPU0_SB_DQS_DP<5>")
	)
	(segment
		(start 299.000672 -286.460184)
		(end 298.672758 -286.13227)
		(width 0.16002)
		(layer "In6.Cu")
		(net "M_E_CPU0_SB_DQS_DP<5>")
	)
	(segment
		(start 329.290934 -276.996144)
		(end 329.282552 -277.00097)
		(width 0.09525)
		(layer "In6.Cu")
		(net "M_E_CPU0_SB_DQS_DP<5>")
	)
	(segment
		(start 293.210996 -286.460184)
		(end 291.418772 -286.460184)
		(width 0.16002)
		(layer "In6.Cu")
		(net "M_E_CPU0_SB_DQS_DP<5>")
	)
	(segment
		(start 296.970958 -286.94507)
		(end 296.605706 -287.310322)
		(width 0.16002)
		(layer "In6.Cu")
		(net "M_E_CPU0_SB_DQS_DP<5>")
	)
	(segment
		(start 282.664916 -286.595312)
		(end 281.870404 -286.924496)
		(width 0.16002)
		(layer "In6.Cu")
		(net "M_E_CPU0_SB_DQS_DP<5>")
	)
	(segment
		(start 324.810628 -276.799802)
		(end 324.302628 -276.291802)
		(width 0.09525)
		(layer "In6.Cu")
		(net "M_E_CPU0_SB_DQS_DP<5>")
	)
	(segment
		(start 301.855886 -286.93237)
		(end 301.3837 -286.460184)
		(width 0.16002)
		(layer "In6.Cu")
		(net "M_E_CPU0_SB_DQS_DP<5>")
	)
	(segment
		(start 289.061906 -287.310322)
		(end 287.070038 -287.310322)
		(width 0.16002)
		(layer "In6.Cu")
		(net "M_E_CPU0_SB_DQS_DP<5>")
	)
	(arc
		(start 328.71156 -276.99589)
		(mid 328.526274 -276.949885)
		(end 328.342244 -277.000716)
		(width 0.09525)
		(layer "In6.Cu")
		(net "M_E_CPU0_SB_DQS_DP<5>")
	)
	(arc
		(start 329.659742 -277.00097)
		(mid 329.475967 -276.950198)
		(end 329.290934 -276.996144)
		(width 0.09525)
		(layer "In6.Cu")
		(net "M_E_CPU0_SB_DQS_DP<5>")
	)
	(arc
		(start 330.222606 -277.00097)
		(mid 329.941174 -277.076725)
		(end 329.659742 -277.00097)
		(width 0.09525)
		(layer "In6.Cu")
		(net "M_E_CPU0_SB_DQS_DP<5>")
	)
	(arc
		(start 330.541884 -276.974046)
		(mid 330.379233 -276.951786)
		(end 330.222606 -277.00097)
		(width 0.09525)
		(layer "In6.Cu")
		(net "M_E_CPU0_SB_DQS_DP<5>")
	)
	(arc
		(start 329.282552 -277.00097)
		(mid 329.00112 -277.076725)
		(end 328.719688 -277.00097)
		(width 0.09525)
		(layer "In6.Cu")
		(net "M_E_CPU0_SB_DQS_DP<5>")
	)
	(arc
		(start 328.34199 -277.000716)
		(mid 328.059098 -277.076221)
		(end 327.77684 -276.99843)
		(width 0.09525)
		(layer "In6.Cu")
		(net "M_E_CPU0_SB_DQS_DP<5>")
	)
	(segment
		(start 330.877926 -272.200116)
		(end 330.411074 -272.466054)
		(width 0.12954)
		(layer "F.Cu")
		(net "M_E_CPU0_SB_DQS_DP<4>")
	)
	(segment
		(start 275.09978 -276.961346)
		(end 274.61972 -276.961346)
		(width 0.16002)
		(layer "In6.Cu")
		(net "M_E_CPU0_SB_DQS_DP<4>")
	)
	(segment
		(start 301.754286 -277.58517)
		(end 301.279306 -277.11019)
		(width 0.16002)
		(layer "In6.Cu")
		(net "M_E_CPU0_SB_DQS_DP<4>")
	)
	(segment
		(start 287.016444 -277.960328)
		(end 286.166306 -277.11019)
		(width 0.16002)
		(layer "In6.Cu")
		(net "M_E_CPU0_SB_DQS_DP<4>")
	)
	(segment
		(start 297.11904 -277.424388)
		(end 296.5831 -277.960328)
		(width 0.16002)
		(layer "In6.Cu")
		(net "M_E_CPU0_SB_DQS_DP<4>")
	)
	(segment
		(start 290.234116 -277.248112)
		(end 289.439604 -277.577296)
		(width 0.16002)
		(layer "In6.Cu")
		(net "M_E_CPU0_SB_DQS_DP<4>")
	)
	(segment
		(start 282.492958 -277.44547)
		(end 281.984958 -277.44547)
		(width 0.16002)
		(layer "In6.Cu")
		(net "M_E_CPU0_SB_DQS_DP<4>")
	)
	(segment
		(start 293.532306 -277.11019)
		(end 291.415978 -277.11019)
		(width 0.16002)
		(layer "In6.Cu")
		(net "M_E_CPU0_SB_DQS_DP<4>")
	)
	(segment
		(start 304.984658 -277.58517)
		(end 301.754286 -277.58517)
		(width 0.16002)
		(layer "In6.Cu")
		(net "M_E_CPU0_SB_DQS_DP<4>")
	)
	(segment
		(start 327.78065 -272.140934)
		(end 327.780396 -272.14068)
		(width 0.09525)
		(layer "In6.Cu")
		(net "M_E_CPU0_SB_DQS_DP<4>")
	)
	(segment
		(start 276.345142 -277.1267)
		(end 275.940012 -276.72157)
		(width 0.16002)
		(layer "In6.Cu")
		(net "M_E_CPU0_SB_DQS_DP<4>")
	)
	(segment
		(start 273.365976 -276.961346)
		(end 273.092164 -277.235158)
		(width 0.16002)
		(layer "In6.Cu")
		(net "M_E_CPU0_SB_DQS_DP<4>")
	)
	(segment
		(start 283.153358 -276.78507)
		(end 282.492958 -277.44547)
		(width 0.16002)
		(layer "In6.Cu")
		(net "M_E_CPU0_SB_DQS_DP<4>")
	)
	(segment
		(start 291.415978 -277.11019)
		(end 291.090858 -276.78507)
		(width 0.16002)
		(layer "In6.Cu")
		(net "M_E_CPU0_SB_DQS_DP<4>")
	)
	(segment
		(start 291.090858 -276.78507)
		(end 290.697158 -276.78507)
		(width 0.16002)
		(layer "In6.Cu")
		(net "M_E_CPU0_SB_DQS_DP<4>")
	)
	(segment
		(start 324.513448 -270.95831)
		(end 324.22338 -270.668242)
		(width 0.09525)
		(layer "In6.Cu")
		(net "M_E_CPU0_SB_DQS_DP<4>")
	)
	(segment
		(start 275.940012 -276.72157)
		(end 275.339556 -276.72157)
		(width 0.16002)
		(layer "In6.Cu")
		(net "M_E_CPU0_SB_DQS_DP<4>")
	)
	(segment
		(start 273.90598 -276.961346)
		(end 273.365976 -276.961346)
		(width 0.16002)
		(layer "In6.Cu")
		(net "M_E_CPU0_SB_DQS_DP<4>")
	)
	(segment
		(start 283.872178 -277.11019)
		(end 283.547058 -276.78507)
		(width 0.16002)
		(layer "In6.Cu")
		(net "M_E_CPU0_SB_DQS_DP<4>")
	)
	(segment
		(start 326.4408 -272.03146)
		(end 325.36765 -270.95831)
		(width 0.09525)
		(layer "In6.Cu")
		(net "M_E_CPU0_SB_DQS_DP<4>")
	)
	(segment
		(start 301.279306 -277.11019)
		(end 298.942506 -277.11019)
		(width 0.16002)
		(layer "In6.Cu")
		(net "M_E_CPU0_SB_DQS_DP<4>")
	)
	(segment
		(start 274.50288 -277.078186)
		(end 274.02282 -277.078186)
		(width 0.16002)
		(layer "In6.Cu")
		(net "M_E_CPU0_SB_DQS_DP<4>")
	)
	(segment
		(start 274.02282 -277.078186)
		(end 273.90598 -276.961346)
		(width 0.16002)
		(layer "In6.Cu")
		(net "M_E_CPU0_SB_DQS_DP<4>")
	)
	(segment
		(start 297.899582 -277.101046)
		(end 297.11904 -277.424388)
		(width 0.16002)
		(layer "In6.Cu")
		(net "M_E_CPU0_SB_DQS_DP<4>")
	)
	(segment
		(start 289.439604 -277.577296)
		(end 289.056572 -277.960328)
		(width 0.16002)
		(layer "In6.Cu")
		(net "M_E_CPU0_SB_DQS_DP<4>")
	)
	(segment
		(start 327.793096 -272.147792)
		(end 327.78065 -272.140934)
		(width 0.09525)
		(layer "In6.Cu")
		(net "M_E_CPU0_SB_DQS_DP<4>")
	)
	(segment
		(start 289.056572 -277.960328)
		(end 287.016444 -277.960328)
		(width 0.16002)
		(layer "In6.Cu")
		(net "M_E_CPU0_SB_DQS_DP<4>")
	)
	(segment
		(start 305.797458 -276.77237)
		(end 304.984658 -277.58517)
		(width 0.16002)
		(layer "In6.Cu")
		(net "M_E_CPU0_SB_DQS_DP<4>")
	)
	(segment
		(start 323.895974 -270.72717)
		(end 312.366152 -270.72717)
		(width 0.16002)
		(layer "In6.Cu")
		(net "M_E_CPU0_SB_DQS_DP<4>")
	)
	(segment
		(start 298.553886 -276.72157)
		(end 298.279058 -276.72157)
		(width 0.16002)
		(layer "In6.Cu")
		(net "M_E_CPU0_SB_DQS_DP<4>")
	)
	(segment
		(start 278.111712 -277.1267)
		(end 276.345142 -277.1267)
		(width 0.16002)
		(layer "In6.Cu")
		(net "M_E_CPU0_SB_DQS_DP<4>")
	)
	(segment
		(start 309.615078 -274.02028)
		(end 306.862988 -276.77237)
		(width 0.16002)
		(layer "In6.Cu")
		(net "M_E_CPU0_SB_DQS_DP<4>")
	)
	(segment
		(start 323.944996 -270.72717)
		(end 323.921374 -270.72717)
		(width 0.09525)
		(layer "In6.Cu")
		(net "M_E_CPU0_SB_DQS_DP<4>")
	)
	(segment
		(start 286.166306 -277.11019)
		(end 283.872178 -277.11019)
		(width 0.16002)
		(layer "In6.Cu")
		(net "M_E_CPU0_SB_DQS_DP<4>")
	)
	(segment
		(start 290.697158 -276.78507)
		(end 290.234116 -277.248112)
		(width 0.16002)
		(layer "In6.Cu")
		(net "M_E_CPU0_SB_DQS_DP<4>")
	)
	(segment
		(start 330.411074 -272.466054)
		(end 330.564998 -272.200624)
		(width 0.09525)
		(layer "In6.Cu")
		(net "M_E_CPU0_SB_DQS_DP<4>")
	)
	(segment
		(start 309.998364 -273.094958)
		(end 309.615078 -274.02028)
		(width 0.16002)
		(layer "In6.Cu")
		(net "M_E_CPU0_SB_DQS_DP<4>")
	)
	(segment
		(start 281.984958 -277.44547)
		(end 281.4701 -277.960328)
		(width 0.16002)
		(layer "In6.Cu")
		(net "M_E_CPU0_SB_DQS_DP<4>")
	)
	(segment
		(start 274.61972 -276.961346)
		(end 274.50288 -277.078186)
		(width 0.16002)
		(layer "In6.Cu")
		(net "M_E_CPU0_SB_DQS_DP<4>")
	)
	(segment
		(start 280.124408 -277.960328)
		(end 278.111712 -277.1267)
		(width 0.16002)
		(layer "In6.Cu")
		(net "M_E_CPU0_SB_DQS_DP<4>")
	)
	(segment
		(start 298.279058 -276.72157)
		(end 297.899582 -277.101046)
		(width 0.16002)
		(layer "In6.Cu")
		(net "M_E_CPU0_SB_DQS_DP<4>")
	)
	(segment
		(start 323.921374 -270.72717)
		(end 323.895974 -270.72717)
		(width 0.1016)
		(layer "In6.Cu")
		(net "M_E_CPU0_SB_DQS_DP<4>")
	)
	(segment
		(start 275.339556 -276.72157)
		(end 275.09978 -276.961346)
		(width 0.16002)
		(layer "In6.Cu")
		(net "M_E_CPU0_SB_DQS_DP<4>")
	)
	(segment
		(start 294.382444 -277.960328)
		(end 293.532306 -277.11019)
		(width 0.16002)
		(layer "In6.Cu")
		(net "M_E_CPU0_SB_DQS_DP<4>")
	)
	(segment
		(start 312.366152 -270.72717)
		(end 309.998364 -273.094958)
		(width 0.16002)
		(layer "In6.Cu")
		(net "M_E_CPU0_SB_DQS_DP<4>")
	)
	(segment
		(start 325.36765 -270.95831)
		(end 324.513448 -270.95831)
		(width 0.09525)
		(layer "In6.Cu")
		(net "M_E_CPU0_SB_DQS_DP<4>")
	)
	(segment
		(start 329.290934 -272.136108)
		(end 329.282552 -272.140934)
		(width 0.09525)
		(layer "In6.Cu")
		(net "M_E_CPU0_SB_DQS_DP<4>")
	)
	(segment
		(start 330.564998 -272.200624)
		(end 330.541884 -272.11401)
		(width 0.09525)
		(layer "In6.Cu")
		(net "M_E_CPU0_SB_DQS_DP<4>")
	)
	(segment
		(start 298.942506 -277.11019)
		(end 298.553886 -276.72157)
		(width 0.16002)
		(layer "In6.Cu")
		(net "M_E_CPU0_SB_DQS_DP<4>")
	)
	(segment
		(start 281.4701 -277.960328)
		(end 280.124408 -277.960328)
		(width 0.16002)
		(layer "In6.Cu")
		(net "M_E_CPU0_SB_DQS_DP<4>")
	)
	(segment
		(start 327.37425 -272.03146)
		(end 326.4408 -272.03146)
		(width 0.09525)
		(layer "In6.Cu")
		(net "M_E_CPU0_SB_DQS_DP<4>")
	)
	(segment
		(start 296.5831 -277.960328)
		(end 294.382444 -277.960328)
		(width 0.16002)
		(layer "In6.Cu")
		(net "M_E_CPU0_SB_DQS_DP<4>")
	)
	(segment
		(start 306.862988 -276.77237)
		(end 305.797458 -276.77237)
		(width 0.16002)
		(layer "In6.Cu")
		(net "M_E_CPU0_SB_DQS_DP<4>")
	)
	(segment
		(start 324.003924 -270.668242)
		(end 323.944996 -270.72717)
		(width 0.09525)
		(layer "In6.Cu")
		(net "M_E_CPU0_SB_DQS_DP<4>")
	)
	(segment
		(start 324.22338 -270.668242)
		(end 324.003924 -270.668242)
		(width 0.09525)
		(layer "In6.Cu")
		(net "M_E_CPU0_SB_DQS_DP<4>")
	)
	(segment
		(start 328.719688 -272.140934)
		(end 328.711306 -272.136108)
		(width 0.09525)
		(layer "In6.Cu")
		(net "M_E_CPU0_SB_DQS_DP<4>")
	)
	(segment
		(start 283.547058 -276.78507)
		(end 283.153358 -276.78507)
		(width 0.16002)
		(layer "In6.Cu")
		(net "M_E_CPU0_SB_DQS_DP<4>")
	)
	(arc
		(start 329.659742 -272.140934)
		(mid 329.475967 -272.090162)
		(end 329.290934 -272.136108)
		(width 0.09525)
		(layer "In6.Cu")
		(net "M_E_CPU0_SB_DQS_DP<4>")
	)
	(arc
		(start 327.792842 -272.148554)
		(mid 327.792968 -272.148173)
		(end 327.793096 -272.147792)
		(width 0.09525)
		(layer "In6.Cu")
		(net "M_E_CPU0_SB_DQS_DP<4>")
	)
	(arc
		(start 330.541884 -272.11401)
		(mid 330.379233 -272.09175)
		(end 330.222606 -272.140934)
		(width 0.09525)
		(layer "In6.Cu")
		(net "M_E_CPU0_SB_DQS_DP<4>")
	)
	(arc
		(start 328.342498 -272.140934)
		(mid 328.068658 -272.216762)
		(end 327.792842 -272.148554)
		(width 0.09525)
		(layer "In6.Cu")
		(net "M_E_CPU0_SB_DQS_DP<4>")
	)
	(arc
		(start 330.222606 -272.140934)
		(mid 329.941174 -272.216689)
		(end 329.659742 -272.140934)
		(width 0.09525)
		(layer "In6.Cu")
		(net "M_E_CPU0_SB_DQS_DP<4>")
	)
	(arc
		(start 329.282552 -272.140934)
		(mid 329.00112 -272.216689)
		(end 328.719688 -272.140934)
		(width 0.09525)
		(layer "In6.Cu")
		(net "M_E_CPU0_SB_DQS_DP<4>")
	)
	(arc
		(start 327.780396 -272.14068)
		(mid 327.584528 -272.05928)
		(end 327.37425 -272.03146)
		(width 0.09525)
		(layer "In6.Cu")
		(net "M_E_CPU0_SB_DQS_DP<4>")
	)
	(arc
		(start 328.711306 -272.136108)
		(mid 328.526274 -272.090194)
		(end 328.342498 -272.140934)
		(width 0.09525)
		(layer "In6.Cu")
		(net "M_E_CPU0_SB_DQS_DP<4>")
	)
	(segment
		(start 329.937872 -290.019994)
		(end 329.47102 -290.285932)
		(width 0.12954)
		(layer "F.Cu")
		(net "M_E_CPU0_SB_DQS_DP<3>")
	)
	(segment
		(start 277.192232 -312.935112)
		(end 277.466044 -313.208924)
		(width 0.16002)
		(layer "In6.Cu")
		(net "M_E_CPU0_SB_DQS_DP<3>")
	)
	(segment
		(start 319.601342 -298.114466)
		(end 319.761616 -298.27474)
		(width 0.16002)
		(layer "In6.Cu")
		(net "M_E_CPU0_SB_DQS_DP<3>")
	)
	(segment
		(start 325.831454 -292.51402)
		(end 325.831454 -291.592254)
		(width 0.09525)
		(layer "In6.Cu")
		(net "M_E_CPU0_SB_DQS_DP<3>")
	)
	(segment
		(start 317.460884 -300.801532)
		(end 317.460884 -300.575472)
		(width 0.16002)
		(layer "In6.Cu")
		(net "M_E_CPU0_SB_DQS_DP<3>")
	)
	(segment
		(start 313.681618 -304.580798)
		(end 314.678568 -303.583848)
		(width 0.16002)
		(layer "In6.Cu")
		(net "M_E_CPU0_SB_DQS_DP<3>")
	)
	(segment
		(start 315.427868 -302.28794)
		(end 315.588142 -302.448214)
		(width 0.16002)
		(layer "In6.Cu")
		(net "M_E_CPU0_SB_DQS_DP<3>")
	)
	(segment
		(start 328.711306 -290.615878)
		(end 328.719688 -290.611052)
		(width 0.09525)
		(layer "In6.Cu")
		(net "M_E_CPU0_SB_DQS_DP<3>")
	)
	(segment
		(start 316.342776 -300.896782)
		(end 316.819026 -300.896782)
		(width 0.16002)
		(layer "In6.Cu")
		(net "M_E_CPU0_SB_DQS_DP<3>")
	)
	(segment
		(start 314.678568 -303.357788)
		(end 314.518548 -303.197514)
		(width 0.16002)
		(layer "In6.Cu")
		(net "M_E_CPU0_SB_DQS_DP<3>")
	)
	(segment
		(start 329.317096 -290.551362)
		(end 329.47102 -290.285932)
		(width 0.09525)
		(layer "In6.Cu")
		(net "M_E_CPU0_SB_DQS_DP<3>")
	)
	(segment
		(start 294.146224 -313.059826)
		(end 296.624502 -313.059826)
		(width 0.16002)
		(layer "In6.Cu")
		(net "M_E_CPU0_SB_DQS_DP<3>")
	)
	(segment
		(start 288.863024 -313.059826)
		(end 289.179508 -313.37631)
		(width 0.16002)
		(layer "In6.Cu")
		(net "M_E_CPU0_SB_DQS_DP<3>")
	)
	(segment
		(start 318.596518 -299.665898)
		(end 318.852042 -299.410374)
		(width 0.16002)
		(layer "In6.Cu")
		(net "M_E_CPU0_SB_DQS_DP<3>")
	)
	(segment
		(start 293.29634 -312.209942)
		(end 294.146224 -313.059826)
		(width 0.16002)
		(layer "In6.Cu")
		(net "M_E_CPU0_SB_DQS_DP<3>")
	)
	(segment
		(start 302.15078 -313.384692)
		(end 304.825908 -313.384692)
		(width 0.16002)
		(layer "In6.Cu")
		(net "M_E_CPU0_SB_DQS_DP<3>")
	)
	(segment
		(start 289.738308 -313.37631)
		(end 290.576508 -312.53811)
		(width 0.16002)
		(layer "In6.Cu")
		(net "M_E_CPU0_SB_DQS_DP<3>")
	)
	(segment
		(start 315.909706 -301.806356)
		(end 315.909706 -301.329852)
		(width 0.16002)
		(layer "In6.Cu")
		(net "M_E_CPU0_SB_DQS_DP<3>")
	)
	(segment
		(start 289.179508 -313.37631)
		(end 289.738308 -313.37631)
		(width 0.16002)
		(layer "In6.Cu")
		(net "M_E_CPU0_SB_DQS_DP<3>")
	)
	(segment
		(start 319.987676 -298.27474)
		(end 324.235064 -294.027352)
		(width 0.16002)
		(layer "In6.Cu")
		(net "M_E_CPU0_SB_DQS_DP<3>")
	)
	(segment
		(start 283.851604 -312.209942)
		(end 285.354014 -312.209942)
		(width 0.16002)
		(layer "In6.Cu")
		(net "M_E_CPU0_SB_DQS_DP<3>")
	)
	(segment
		(start 318.692022 -298.547536)
		(end 319.125092 -298.114466)
		(width 0.16002)
		(layer "In6.Cu")
		(net "M_E_CPU0_SB_DQS_DP<3>")
	)
	(segment
		(start 285.354014 -312.209942)
		(end 287.40608 -313.059826)
		(width 0.16002)
		(layer "In6.Cu")
		(net "M_E_CPU0_SB_DQS_DP<3>")
	)
	(segment
		(start 316.069726 -301.96663)
		(end 315.909706 -301.806356)
		(width 0.16002)
		(layer "In6.Cu")
		(net "M_E_CPU0_SB_DQS_DP<3>")
	)
	(segment
		(start 291.387276 -312.209942)
		(end 293.29634 -312.209942)
		(width 0.16002)
		(layer "In6.Cu")
		(net "M_E_CPU0_SB_DQS_DP<3>")
	)
	(segment
		(start 324.235064 -294.027352)
		(end 324.251828 -294.010588)
		(width 0.09525)
		(layer "In6.Cu")
		(net "M_E_CPU0_SB_DQS_DP<3>")
	)
	(segment
		(start 319.125092 -298.114466)
		(end 319.601342 -298.114466)
		(width 0.16002)
		(layer "In6.Cu")
		(net "M_E_CPU0_SB_DQS_DP<3>")
	)
	(segment
		(start 318.692022 -299.02404)
		(end 318.692022 -298.547536)
		(width 0.16002)
		(layer "In6.Cu")
		(net "M_E_CPU0_SB_DQS_DP<3>")
	)
	(segment
		(start 283.510736 -312.55081)
		(end 283.851604 -312.209942)
		(width 0.16002)
		(layer "In6.Cu")
		(net "M_E_CPU0_SB_DQS_DP<3>")
	)
	(segment
		(start 298.056808 -312.609992)
		(end 298.539408 -312.609992)
		(width 0.16002)
		(layer "In6.Cu")
		(net "M_E_CPU0_SB_DQS_DP<3>")
	)
	(segment
		(start 318.852042 -299.410374)
		(end 318.852042 -299.184314)
		(width 0.16002)
		(layer "In6.Cu")
		(net "M_E_CPU0_SB_DQS_DP<3>")
	)
	(segment
		(start 279.954228 -313.208924)
		(end 280.103326 -313.059826)
		(width 0.16002)
		(layer "In6.Cu")
		(net "M_E_CPU0_SB_DQS_DP<3>")
	)
	(segment
		(start 317.20536 -301.057056)
		(end 317.460884 -300.801532)
		(width 0.16002)
		(layer "In6.Cu")
		(net "M_E_CPU0_SB_DQS_DP<3>")
	)
	(segment
		(start 282.180538 -313.39028)
		(end 283.020008 -312.55081)
		(width 0.16002)
		(layer "In6.Cu")
		(net "M_E_CPU0_SB_DQS_DP<3>")
	)
	(segment
		(start 281.507692 -313.39028)
		(end 282.180538 -313.39028)
		(width 0.16002)
		(layer "In6.Cu")
		(net "M_E_CPU0_SB_DQS_DP<3>")
	)
	(segment
		(start 315.588142 -302.448214)
		(end 315.814202 -302.448214)
		(width 0.16002)
		(layer "In6.Cu")
		(net "M_E_CPU0_SB_DQS_DP<3>")
	)
	(segment
		(start 327.401682 -290.611052)
		(end 327.410064 -290.615878)
		(width 0.09525)
		(layer "In6.Cu")
		(net "M_E_CPU0_SB_DQS_DP<3>")
	)
	(segment
		(start 315.909706 -301.329852)
		(end 316.342776 -300.896782)
		(width 0.16002)
		(layer "In6.Cu")
		(net "M_E_CPU0_SB_DQS_DP<3>")
	)
	(segment
		(start 300.97603 -312.209942)
		(end 302.15078 -313.384692)
		(width 0.16002)
		(layer "In6.Cu")
		(net "M_E_CPU0_SB_DQS_DP<3>")
	)
	(segment
		(start 305.689508 -312.521092)
		(end 307.484018 -312.521092)
		(width 0.16002)
		(layer "In6.Cu")
		(net "M_E_CPU0_SB_DQS_DP<3>")
	)
	(segment
		(start 304.825908 -313.384692)
		(end 305.689508 -312.521092)
		(width 0.16002)
		(layer "In6.Cu")
		(net "M_E_CPU0_SB_DQS_DP<3>")
	)
	(segment
		(start 298.539408 -312.609992)
		(end 298.939458 -312.209942)
		(width 0.16002)
		(layer "In6.Cu")
		(net "M_E_CPU0_SB_DQS_DP<3>")
	)
	(segment
		(start 314.518548 -302.72101)
		(end 314.951618 -302.28794)
		(width 0.16002)
		(layer "In6.Cu")
		(net "M_E_CPU0_SB_DQS_DP<3>")
	)
	(segment
		(start 311.088278 -308.916832)
		(end 311.088278 -307.606192)
		(width 0.16002)
		(layer "In6.Cu")
		(net "M_E_CPU0_SB_DQS_DP<3>")
	)
	(segment
		(start 318.852042 -299.184314)
		(end 318.692022 -299.02404)
		(width 0.16002)
		(layer "In6.Cu")
		(net "M_E_CPU0_SB_DQS_DP<3>")
	)
	(segment
		(start 316.9793 -301.057056)
		(end 317.20536 -301.057056)
		(width 0.16002)
		(layer "In6.Cu")
		(net "M_E_CPU0_SB_DQS_DP<3>")
	)
	(segment
		(start 328.332084 -290.604956)
		(end 328.342498 -290.611052)
		(width 0.09525)
		(layer "In6.Cu")
		(net "M_E_CPU0_SB_DQS_DP<3>")
	)
	(segment
		(start 318.370458 -299.665898)
		(end 318.596518 -299.665898)
		(width 0.16002)
		(layer "In6.Cu")
		(net "M_E_CPU0_SB_DQS_DP<3>")
	)
	(segment
		(start 315.814202 -302.448214)
		(end 316.069726 -302.19269)
		(width 0.16002)
		(layer "In6.Cu")
		(net "M_E_CPU0_SB_DQS_DP<3>")
	)
	(segment
		(start 291.059108 -312.53811)
		(end 291.387276 -312.209942)
		(width 0.16002)
		(layer "In6.Cu")
		(net "M_E_CPU0_SB_DQS_DP<3>")
	)
	(segment
		(start 311.088278 -307.606192)
		(end 313.681618 -305.012852)
		(width 0.16002)
		(layer "In6.Cu")
		(net "M_E_CPU0_SB_DQS_DP<3>")
	)
	(segment
		(start 290.576508 -312.53811)
		(end 291.059108 -312.53811)
		(width 0.16002)
		(layer "In6.Cu")
		(net "M_E_CPU0_SB_DQS_DP<3>")
	)
	(segment
		(start 297.294808 -313.371992)
		(end 298.056808 -312.609992)
		(width 0.16002)
		(layer "In6.Cu")
		(net "M_E_CPU0_SB_DQS_DP<3>")
	)
	(segment
		(start 283.020008 -312.55081)
		(end 283.510736 -312.55081)
		(width 0.16002)
		(layer "In6.Cu")
		(net "M_E_CPU0_SB_DQS_DP<3>")
	)
	(segment
		(start 296.936668 -313.371992)
		(end 297.294808 -313.371992)
		(width 0.16002)
		(layer "In6.Cu")
		(net "M_E_CPU0_SB_DQS_DP<3>")
	)
	(segment
		(start 319.761616 -298.27474)
		(end 319.987676 -298.27474)
		(width 0.16002)
		(layer "In6.Cu")
		(net "M_E_CPU0_SB_DQS_DP<3>")
	)
	(segment
		(start 280.103326 -313.059826)
		(end 281.177238 -313.059826)
		(width 0.16002)
		(layer "In6.Cu")
		(net "M_E_CPU0_SB_DQS_DP<3>")
	)
	(segment
		(start 298.939458 -312.209942)
		(end 300.97603 -312.209942)
		(width 0.16002)
		(layer "In6.Cu")
		(net "M_E_CPU0_SB_DQS_DP<3>")
	)
	(segment
		(start 314.518548 -303.197514)
		(end 314.518548 -302.72101)
		(width 0.16002)
		(layer "In6.Cu")
		(net "M_E_CPU0_SB_DQS_DP<3>")
	)
	(segment
		(start 317.460884 -300.575472)
		(end 317.300864 -300.415198)
		(width 0.16002)
		(layer "In6.Cu")
		(net "M_E_CPU0_SB_DQS_DP<3>")
	)
	(segment
		(start 317.300864 -300.415198)
		(end 317.300864 -299.938694)
		(width 0.16002)
		(layer "In6.Cu")
		(net "M_E_CPU0_SB_DQS_DP<3>")
	)
	(segment
		(start 314.678568 -303.583848)
		(end 314.678568 -303.357788)
		(width 0.16002)
		(layer "In6.Cu")
		(net "M_E_CPU0_SB_DQS_DP<3>")
	)
	(segment
		(start 317.733934 -299.505624)
		(end 318.210184 -299.505624)
		(width 0.16002)
		(layer "In6.Cu")
		(net "M_E_CPU0_SB_DQS_DP<3>")
	)
	(segment
		(start 318.210184 -299.505624)
		(end 318.370458 -299.665898)
		(width 0.16002)
		(layer "In6.Cu")
		(net "M_E_CPU0_SB_DQS_DP<3>")
	)
	(segment
		(start 281.177238 -313.059826)
		(end 281.507692 -313.39028)
		(width 0.16002)
		(layer "In6.Cu")
		(net "M_E_CPU0_SB_DQS_DP<3>")
	)
	(segment
		(start 296.624502 -313.059826)
		(end 296.936668 -313.371992)
		(width 0.16002)
		(layer "In6.Cu")
		(net "M_E_CPU0_SB_DQS_DP<3>")
	)
	(segment
		(start 324.251828 -294.010588)
		(end 324.334632 -294.010842)
		(width 0.09525)
		(layer "In6.Cu")
		(net "M_E_CPU0_SB_DQS_DP<3>")
	)
	(segment
		(start 324.334632 -294.010842)
		(end 325.831454 -292.51402)
		(width 0.09525)
		(layer "In6.Cu")
		(net "M_E_CPU0_SB_DQS_DP<3>")
	)
	(segment
		(start 317.300864 -299.938694)
		(end 317.733934 -299.505624)
		(width 0.16002)
		(layer "In6.Cu")
		(net "M_E_CPU0_SB_DQS_DP<3>")
	)
	(segment
		(start 316.069726 -302.19269)
		(end 316.069726 -301.96663)
		(width 0.16002)
		(layer "In6.Cu")
		(net "M_E_CPU0_SB_DQS_DP<3>")
	)
	(segment
		(start 277.466044 -313.208924)
		(end 279.954228 -313.208924)
		(width 0.16002)
		(layer "In6.Cu")
		(net "M_E_CPU0_SB_DQS_DP<3>")
	)
	(segment
		(start 307.484018 -312.521092)
		(end 311.088278 -308.916832)
		(width 0.16002)
		(layer "In6.Cu")
		(net "M_E_CPU0_SB_DQS_DP<3>")
	)
	(segment
		(start 313.681618 -305.012852)
		(end 313.681618 -304.580798)
		(width 0.16002)
		(layer "In6.Cu")
		(net "M_E_CPU0_SB_DQS_DP<3>")
	)
	(segment
		(start 316.819026 -300.896782)
		(end 316.9793 -301.057056)
		(width 0.16002)
		(layer "In6.Cu")
		(net "M_E_CPU0_SB_DQS_DP<3>")
	)
	(segment
		(start 314.951618 -302.28794)
		(end 315.427868 -302.28794)
		(width 0.16002)
		(layer "In6.Cu")
		(net "M_E_CPU0_SB_DQS_DP<3>")
	)
	(segment
		(start 329.216258 -290.578032)
		(end 329.317096 -290.551362)
		(width 0.09525)
		(layer "In6.Cu")
		(net "M_E_CPU0_SB_DQS_DP<3>")
	)
	(segment
		(start 287.40608 -313.059826)
		(end 288.863024 -313.059826)
		(width 0.16002)
		(layer "In6.Cu")
		(net "M_E_CPU0_SB_DQS_DP<3>")
	)
	(segment
		(start 325.831454 -291.592254)
		(end 326.72401 -290.699698)
		(width 0.09525)
		(layer "In6.Cu")
		(net "M_E_CPU0_SB_DQS_DP<3>")
	)
	(arc
		(start 327.77938 -290.611052)
		(mid 328.054923 -290.535203)
		(end 328.332084 -290.604956)
		(width 0.09525)
		(layer "In6.Cu")
		(net "M_E_CPU0_SB_DQS_DP<3>")
	)
	(arc
		(start 326.85736 -290.600892)
		(mid 327.13082 -290.535519)
		(end 327.401682 -290.611052)
		(width 0.09525)
		(layer "In6.Cu")
		(net "M_E_CPU0_SB_DQS_DP<3>")
	)
	(arc
		(start 327.410064 -290.615878)
		(mid 327.59535 -290.661914)
		(end 327.77938 -290.611052)
		(width 0.09525)
		(layer "In6.Cu")
		(net "M_E_CPU0_SB_DQS_DP<3>")
	)
	(arc
		(start 326.72401 -290.699698)
		(mid 326.787004 -290.645326)
		(end 326.85736 -290.600892)
		(width 0.09525)
		(layer "In6.Cu")
		(net "M_E_CPU0_SB_DQS_DP<3>")
	)
	(arc
		(start 328.342498 -290.611052)
		(mid 328.526273 -290.661824)
		(end 328.711306 -290.615878)
		(width 0.09525)
		(layer "In6.Cu")
		(net "M_E_CPU0_SB_DQS_DP<3>")
	)
	(arc
		(start 329.196446 -290.570158)
		(mid 329.206389 -290.574001)
		(end 329.216258 -290.578032)
		(width 0.09525)
		(layer "In6.Cu")
		(net "M_E_CPU0_SB_DQS_DP<3>")
	)
	(arc
		(start 328.719688 -290.611052)
		(mid 328.953483 -290.537185)
		(end 329.196446 -290.570158)
		(width 0.09525)
		(layer "In6.Cu")
		(net "M_E_CPU0_SB_DQS_DP<3>")
	)
	(segment
		(start 329.937872 -285.160212)
		(end 329.47102 -285.42615)
		(width 0.12954)
		(layer "F.Cu")
		(net "M_E_CPU0_SB_DQS_DP<2>")
	)
	(segment
		(start 314.998354 -293.785036)
		(end 314.663074 -294.593772)
		(width 0.16002)
		(layer "In6.Cu")
		(net "M_E_CPU0_SB_DQS_DP<2>")
	)
	(segment
		(start 285.493968 -303.197006)
		(end 285.15691 -302.859948)
		(width 0.16002)
		(layer "In6.Cu")
		(net "M_E_CPU0_SB_DQS_DP<2>")
	)
	(segment
		(start 297.301158 -304.037238)
		(end 296.930318 -304.037238)
		(width 0.16002)
		(layer "In6.Cu")
		(net "M_E_CPU0_SB_DQS_DP<2>")
	)
	(segment
		(start 316.380622 -293.006018)
		(end 316.07506 -293.31158)
		(width 0.16002)
		(layer "In6.Cu")
		(net "M_E_CPU0_SB_DQS_DP<2>")
	)
	(segment
		(start 329.317096 -285.69158)
		(end 329.216258 -285.71825)
		(width 0.09525)
		(layer "In6.Cu")
		(net "M_E_CPU0_SB_DQS_DP<2>")
	)
	(segment
		(start 303.839372 -304.276252)
		(end 303.043844 -304.276252)
		(width 0.16002)
		(layer "In6.Cu")
		(net "M_E_CPU0_SB_DQS_DP<2>")
	)
	(segment
		(start 307.339492 -303.186338)
		(end 305.695858 -303.186338)
		(width 0.16002)
		(layer "In6.Cu")
		(net "M_E_CPU0_SB_DQS_DP<2>")
	)
	(segment
		(start 309.602632 -299.654214)
		(end 308.70525 -301.82058)
		(width 0.16002)
		(layer "In6.Cu")
		(net "M_E_CPU0_SB_DQS_DP<2>")
	)
	(segment
		(start 287.767776 -303.709832)
		(end 287.369758 -304.10785)
		(width 0.16002)
		(layer "In6.Cu")
		(net "M_E_CPU0_SB_DQS_DP<2>")
	)
	(segment
		(start 327.79716 -285.741618)
		(end 327.779888 -285.751524)
		(width 0.09525)
		(layer "In6.Cu")
		(net "M_E_CPU0_SB_DQS_DP<2>")
	)
	(segment
		(start 293.04234 -302.859948)
		(end 291.46246 -302.859948)
		(width 0.16002)
		(layer "In6.Cu")
		(net "M_E_CPU0_SB_DQS_DP<2>")
	)
	(segment
		(start 279.648158 -304.10785)
		(end 279.084278 -304.10785)
		(width 0.16002)
		(layer "In6.Cu")
		(net "M_E_CPU0_SB_DQS_DP<2>")
	)
	(segment
		(start 327.779888 -285.751524)
		(end 327.765918 -285.759398)
		(width 0.09525)
		(layer "In6.Cu")
		(net "M_E_CPU0_SB_DQS_DP<2>")
	)
	(segment
		(start 281.489912 -303.709832)
		(end 280.046176 -303.709832)
		(width 0.16002)
		(layer "In6.Cu")
		(net "M_E_CPU0_SB_DQS_DP<2>")
	)
	(segment
		(start 319.162938 -289.620452)
		(end 319.162938 -290.223702)
		(width 0.16002)
		(layer "In6.Cu")
		(net "M_E_CPU0_SB_DQS_DP<2>")
	)
	(segment
		(start 278.835358 -303.85893)
		(end 277.466044 -303.85893)
		(width 0.16002)
		(layer "In6.Cu")
		(net "M_E_CPU0_SB_DQS_DP<2>")
	)
	(segment
		(start 319.741804 -289.041586)
		(end 319.162938 -289.620452)
		(width 0.16002)
		(layer "In6.Cu")
		(net "M_E_CPU0_SB_DQS_DP<2>")
	)
	(segment
		(start 290.557458 -303.23155)
		(end 289.681158 -304.10785)
		(width 0.16002)
		(layer "In6.Cu")
		(net "M_E_CPU0_SB_DQS_DP<2>")
	)
	(segment
		(start 324.198742 -286.449262)
		(end 324.13956 -286.39008)
		(width 0.09525)
		(layer "In6.Cu")
		(net "M_E_CPU0_SB_DQS_DP<2>")
	)
	(segment
		(start 279.084278 -304.10785)
		(end 278.835358 -303.85893)
		(width 0.16002)
		(layer "In6.Cu")
		(net "M_E_CPU0_SB_DQS_DP<2>")
	)
	(segment
		(start 316.07506 -293.31158)
		(end 315.47181 -293.31158)
		(width 0.16002)
		(layer "In6.Cu")
		(net "M_E_CPU0_SB_DQS_DP<2>")
	)
	(segment
		(start 286.91713 -304.10785)
		(end 286.79013 -303.98085)
		(width 0.16002)
		(layer "In6.Cu")
		(net "M_E_CPU0_SB_DQS_DP<2>")
	)
	(segment
		(start 295.023286 -304.03165)
		(end 293.77513 -304.03165)
		(width 0.16002)
		(layer "In6.Cu")
		(net "M_E_CPU0_SB_DQS_DP<2>")
	)
	(segment
		(start 329.47102 -285.42615)
		(end 329.317096 -285.69158)
		(width 0.09525)
		(layer "In6.Cu")
		(net "M_E_CPU0_SB_DQS_DP<2>")
	)
	(segment
		(start 293.490904 -303.308512)
		(end 293.04234 -302.859948)
		(width 0.16002)
		(layer "In6.Cu")
		(net "M_E_CPU0_SB_DQS_DP<2>")
	)
	(segment
		(start 319.162938 -290.223702)
		(end 318.857376 -290.529264)
		(width 0.16002)
		(layer "In6.Cu")
		(net "M_E_CPU0_SB_DQS_DP<2>")
	)
	(segment
		(start 304.832258 -304.049938)
		(end 304.065686 -304.049938)
		(width 0.16002)
		(layer "In6.Cu")
		(net "M_E_CPU0_SB_DQS_DP<2>")
	)
	(segment
		(start 303.043844 -304.276252)
		(end 302.636936 -303.869344)
		(width 0.16002)
		(layer "In6.Cu")
		(net "M_E_CPU0_SB_DQS_DP<2>")
	)
	(segment
		(start 318.857376 -290.529264)
		(end 318.254126 -290.529264)
		(width 0.16002)
		(layer "In6.Cu")
		(net "M_E_CPU0_SB_DQS_DP<2>")
	)
	(segment
		(start 293.490904 -303.747424)
		(end 293.490904 -303.308512)
		(width 0.16002)
		(layer "In6.Cu")
		(net "M_E_CPU0_SB_DQS_DP<2>")
	)
	(segment
		(start 289.681158 -304.10785)
		(end 288.89833 -304.10785)
		(width 0.16002)
		(layer "In6.Cu")
		(net "M_E_CPU0_SB_DQS_DP<2>")
	)
	(segment
		(start 286.79013 -303.98085)
		(end 285.797498 -303.98085)
		(width 0.16002)
		(layer "In6.Cu")
		(net "M_E_CPU0_SB_DQS_DP<2>")
	)
	(segment
		(start 287.369758 -304.10785)
		(end 286.91713 -304.10785)
		(width 0.16002)
		(layer "In6.Cu")
		(net "M_E_CPU0_SB_DQS_DP<2>")
	)
	(segment
		(start 277.466044 -303.85893)
		(end 277.192232 -303.585118)
		(width 0.16002)
		(layer "In6.Cu")
		(net "M_E_CPU0_SB_DQS_DP<2>")
	)
	(segment
		(start 318.254126 -290.529264)
		(end 317.77178 -291.01161)
		(width 0.16002)
		(layer "In6.Cu")
		(net "M_E_CPU0_SB_DQS_DP<2>")
	)
	(segment
		(start 281.81173 -304.03165)
		(end 281.489912 -303.709832)
		(width 0.16002)
		(layer "In6.Cu")
		(net "M_E_CPU0_SB_DQS_DP<2>")
	)
	(segment
		(start 302.636936 -303.869344)
		(end 300.834552 -303.869344)
		(width 0.16002)
		(layer "In6.Cu")
		(net "M_E_CPU0_SB_DQS_DP<2>")
	)
	(segment
		(start 328.719688 -285.75127)
		(end 328.711306 -285.756096)
		(width 0.09525)
		(layer "In6.Cu")
		(net "M_E_CPU0_SB_DQS_DP<2>")
	)
	(segment
		(start 317.466218 -291.920422)
		(end 316.862968 -291.920422)
		(width 0.16002)
		(layer "In6.Cu")
		(net "M_E_CPU0_SB_DQS_DP<2>")
	)
	(segment
		(start 296.602912 -303.709832)
		(end 295.345104 -303.709832)
		(width 0.16002)
		(layer "In6.Cu")
		(net "M_E_CPU0_SB_DQS_DP<2>")
	)
	(segment
		(start 300.32071 -302.859948)
		(end 298.961048 -302.859948)
		(width 0.16002)
		(layer "In6.Cu")
		(net "M_E_CPU0_SB_DQS_DP<2>")
	)
	(segment
		(start 283.009086 -303.26965)
		(end 282.247086 -304.03165)
		(width 0.16002)
		(layer "In6.Cu")
		(net "M_E_CPU0_SB_DQS_DP<2>")
	)
	(segment
		(start 283.458158 -303.26965)
		(end 283.009086 -303.26965)
		(width 0.16002)
		(layer "In6.Cu")
		(net "M_E_CPU0_SB_DQS_DP<2>")
	)
	(segment
		(start 317.77178 -291.61486)
		(end 317.466218 -291.920422)
		(width 0.16002)
		(layer "In6.Cu")
		(net "M_E_CPU0_SB_DQS_DP<2>")
	)
	(segment
		(start 326.651112 -285.802832)
		(end 325.792338 -285.802832)
		(width 0.09525)
		(layer "In6.Cu")
		(net "M_E_CPU0_SB_DQS_DP<2>")
	)
	(segment
		(start 320.996564 -289.041586)
		(end 319.741804 -289.041586)
		(width 0.16002)
		(layer "In6.Cu")
		(net "M_E_CPU0_SB_DQS_DP<2>")
	)
	(segment
		(start 308.70525 -301.82058)
		(end 307.339492 -303.186338)
		(width 0.16002)
		(layer "In6.Cu")
		(net "M_E_CPU0_SB_DQS_DP<2>")
	)
	(segment
		(start 298.961048 -302.859948)
		(end 298.545758 -303.275238)
		(width 0.16002)
		(layer "In6.Cu")
		(net "M_E_CPU0_SB_DQS_DP<2>")
	)
	(segment
		(start 325.792338 -285.802832)
		(end 325.145908 -286.449262)
		(width 0.09525)
		(layer "In6.Cu")
		(net "M_E_CPU0_SB_DQS_DP<2>")
	)
	(segment
		(start 316.380622 -292.402768)
		(end 316.380622 -293.006018)
		(width 0.16002)
		(layer "In6.Cu")
		(net "M_E_CPU0_SB_DQS_DP<2>")
	)
	(segment
		(start 323.64807 -286.39008)
		(end 320.996564 -289.041586)
		(width 0.16002)
		(layer "In6.Cu")
		(net "M_E_CPU0_SB_DQS_DP<2>")
	)
	(segment
		(start 285.15691 -302.859948)
		(end 283.86786 -302.859948)
		(width 0.16002)
		(layer "In6.Cu")
		(net "M_E_CPU0_SB_DQS_DP<2>")
	)
	(segment
		(start 280.046176 -303.709832)
		(end 279.648158 -304.10785)
		(width 0.16002)
		(layer "In6.Cu")
		(net "M_E_CPU0_SB_DQS_DP<2>")
	)
	(segment
		(start 316.862968 -291.920422)
		(end 316.380622 -292.402768)
		(width 0.16002)
		(layer "In6.Cu")
		(net "M_E_CPU0_SB_DQS_DP<2>")
	)
	(segment
		(start 285.797498 -303.98085)
		(end 285.493968 -303.67732)
		(width 0.16002)
		(layer "In6.Cu")
		(net "M_E_CPU0_SB_DQS_DP<2>")
	)
	(segment
		(start 285.493968 -303.67732)
		(end 285.493968 -303.197006)
		(width 0.16002)
		(layer "In6.Cu")
		(net "M_E_CPU0_SB_DQS_DP<2>")
	)
	(segment
		(start 295.345104 -303.709832)
		(end 295.023286 -304.03165)
		(width 0.16002)
		(layer "In6.Cu")
		(net "M_E_CPU0_SB_DQS_DP<2>")
	)
	(segment
		(start 288.500312 -303.709832)
		(end 287.767776 -303.709832)
		(width 0.16002)
		(layer "In6.Cu")
		(net "M_E_CPU0_SB_DQS_DP<2>")
	)
	(segment
		(start 298.063158 -303.275238)
		(end 297.301158 -304.037238)
		(width 0.16002)
		(layer "In6.Cu")
		(net "M_E_CPU0_SB_DQS_DP<2>")
	)
	(segment
		(start 291.46246 -302.859948)
		(end 291.090858 -303.23155)
		(width 0.16002)
		(layer "In6.Cu")
		(net "M_E_CPU0_SB_DQS_DP<2>")
	)
	(segment
		(start 314.663074 -294.593772)
		(end 309.602632 -299.654214)
		(width 0.16002)
		(layer "In6.Cu")
		(net "M_E_CPU0_SB_DQS_DP<2>")
	)
	(segment
		(start 288.89833 -304.10785)
		(end 288.500312 -303.709832)
		(width 0.16002)
		(layer "In6.Cu")
		(net "M_E_CPU0_SB_DQS_DP<2>")
	)
	(segment
		(start 298.545758 -303.275238)
		(end 298.063158 -303.275238)
		(width 0.16002)
		(layer "In6.Cu")
		(net "M_E_CPU0_SB_DQS_DP<2>")
	)
	(segment
		(start 293.77513 -304.03165)
		(end 293.490904 -303.747424)
		(width 0.16002)
		(layer "In6.Cu")
		(net "M_E_CPU0_SB_DQS_DP<2>")
	)
	(segment
		(start 282.247086 -304.03165)
		(end 281.81173 -304.03165)
		(width 0.16002)
		(layer "In6.Cu")
		(net "M_E_CPU0_SB_DQS_DP<2>")
	)
	(segment
		(start 300.657768 -303.69256)
		(end 300.657768 -303.197006)
		(width 0.16002)
		(layer "In6.Cu")
		(net "M_E_CPU0_SB_DQS_DP<2>")
	)
	(segment
		(start 324.115938 -286.39008)
		(end 323.64807 -286.39008)
		(width 0.16002)
		(layer "In6.Cu")
		(net "M_E_CPU0_SB_DQS_DP<2>")
	)
	(segment
		(start 325.145908 -286.449262)
		(end 324.198742 -286.449262)
		(width 0.09525)
		(layer "In6.Cu")
		(net "M_E_CPU0_SB_DQS_DP<2>")
	)
	(segment
		(start 324.13956 -286.39008)
		(end 324.115938 -286.39008)
		(width 0.09525)
		(layer "In6.Cu")
		(net "M_E_CPU0_SB_DQS_DP<2>")
	)
	(segment
		(start 305.695858 -303.186338)
		(end 304.832258 -304.049938)
		(width 0.16002)
		(layer "In6.Cu")
		(net "M_E_CPU0_SB_DQS_DP<2>")
	)
	(segment
		(start 296.930318 -304.037238)
		(end 296.602912 -303.709832)
		(width 0.16002)
		(layer "In6.Cu")
		(net "M_E_CPU0_SB_DQS_DP<2>")
	)
	(segment
		(start 283.86786 -302.859948)
		(end 283.458158 -303.26965)
		(width 0.16002)
		(layer "In6.Cu")
		(net "M_E_CPU0_SB_DQS_DP<2>")
	)
	(segment
		(start 315.47181 -293.31158)
		(end 314.998354 -293.785036)
		(width 0.16002)
		(layer "In6.Cu")
		(net "M_E_CPU0_SB_DQS_DP<2>")
	)
	(segment
		(start 327.402698 -285.751778)
		(end 327.388982 -285.74365)
		(width 0.09525)
		(layer "In6.Cu")
		(net "M_E_CPU0_SB_DQS_DP<2>")
	)
	(segment
		(start 291.090858 -303.23155)
		(end 290.557458 -303.23155)
		(width 0.16002)
		(layer "In6.Cu")
		(net "M_E_CPU0_SB_DQS_DP<2>")
	)
	(segment
		(start 300.657768 -303.197006)
		(end 300.32071 -302.859948)
		(width 0.16002)
		(layer "In6.Cu")
		(net "M_E_CPU0_SB_DQS_DP<2>")
	)
	(segment
		(start 304.065686 -304.049938)
		(end 303.839372 -304.276252)
		(width 0.16002)
		(layer "In6.Cu")
		(net "M_E_CPU0_SB_DQS_DP<2>")
	)
	(segment
		(start 300.834552 -303.869344)
		(end 300.657768 -303.69256)
		(width 0.16002)
		(layer "In6.Cu")
		(net "M_E_CPU0_SB_DQS_DP<2>")
	)
	(segment
		(start 317.77178 -291.01161)
		(end 317.77178 -291.61486)
		(width 0.16002)
		(layer "In6.Cu")
		(net "M_E_CPU0_SB_DQS_DP<2>")
	)
	(arc
		(start 327.388982 -285.74365)
		(mid 327.113392 -285.675832)
		(end 326.839834 -285.751524)
		(width 0.09525)
		(layer "In6.Cu")
		(net "M_E_CPU0_SB_DQS_DP<2>")
	)
	(arc
		(start 326.839834 -285.751524)
		(mid 326.748864 -285.789651)
		(end 326.651112 -285.802832)
		(width 0.09525)
		(layer "In6.Cu")
		(net "M_E_CPU0_SB_DQS_DP<2>")
	)
	(arc
		(start 329.196446 -285.710376)
		(mid 328.953482 -285.677389)
		(end 328.719688 -285.75127)
		(width 0.09525)
		(layer "In6.Cu")
		(net "M_E_CPU0_SB_DQS_DP<2>")
	)
	(arc
		(start 327.765918 -285.759398)
		(mid 327.58332 -285.802414)
		(end 327.402698 -285.751778)
		(width 0.09525)
		(layer "In6.Cu")
		(net "M_E_CPU0_SB_DQS_DP<2>")
	)
	(arc
		(start 328.342498 -285.75127)
		(mid 328.071071 -285.675604)
		(end 327.79716 -285.741618)
		(width 0.09525)
		(layer "In6.Cu")
		(net "M_E_CPU0_SB_DQS_DP<2>")
	)
	(arc
		(start 328.711306 -285.756096)
		(mid 328.526274 -285.80201)
		(end 328.342498 -285.75127)
		(width 0.09525)
		(layer "In6.Cu")
		(net "M_E_CPU0_SB_DQS_DP<2>")
	)
	(arc
		(start 329.216258 -285.71825)
		(mid 329.20639 -285.714219)
		(end 329.196446 -285.710376)
		(width 0.09525)
		(layer "In6.Cu")
		(net "M_E_CPU0_SB_DQS_DP<2>")
	)
	(segment
		(start 329.937872 -280.300176)
		(end 329.47102 -280.566114)
		(width 0.12954)
		(layer "F.Cu")
		(net "M_E_CPU0_SB_DQS_DP<1>")
	)
	(segment
		(start 287.360614 -294.61841)
		(end 286.262572 -294.61841)
		(width 0.16002)
		(layer "In6.Cu")
		(net "M_E_CPU0_SB_DQS_DP<1>")
	)
	(segment
		(start 289.031426 -294.719756)
		(end 288.671508 -294.359838)
		(width 0.16002)
		(layer "In6.Cu")
		(net "M_E_CPU0_SB_DQS_DP<1>")
	)
	(segment
		(start 307.601874 -293.821104)
		(end 305.689508 -293.821104)
		(width 0.16002)
		(layer "In6.Cu")
		(net "M_E_CPU0_SB_DQS_DP<1>")
	)
	(segment
		(start 295.025572 -294.359838)
		(end 294.767 -294.61841)
		(width 0.16002)
		(layer "In6.Cu")
		(net "M_E_CPU0_SB_DQS_DP<1>")
	)
	(segment
		(start 286.026098 -293.890192)
		(end 285.64586 -293.509954)
		(width 0.16002)
		(layer "In6.Cu")
		(net "M_E_CPU0_SB_DQS_DP<1>")
	)
	(segment
		(start 294.767 -294.61841)
		(end 293.755826 -294.61841)
		(width 0.16002)
		(layer "In6.Cu")
		(net "M_E_CPU0_SB_DQS_DP<1>")
	)
	(segment
		(start 281.516582 -294.359838)
		(end 280.189178 -294.359838)
		(width 0.16002)
		(layer "In6.Cu")
		(net "M_E_CPU0_SB_DQS_DP<1>")
	)
	(segment
		(start 316.371224 -283.983938)
		(end 316.371224 -284.56001)
		(width 0.16002)
		(layer "In6.Cu")
		(net "M_E_CPU0_SB_DQS_DP<1>")
	)
	(segment
		(start 316.371224 -284.56001)
		(end 316.051946 -284.879288)
		(width 0.16002)
		(layer "In6.Cu")
		(net "M_E_CPU0_SB_DQS_DP<1>")
	)
	(segment
		(start 329.47102 -280.566114)
		(end 329.317096 -280.831544)
		(width 0.09525)
		(layer "In6.Cu")
		(net "M_E_CPU0_SB_DQS_DP<1>")
	)
	(segment
		(start 305.689508 -293.821104)
		(end 304.635662 -294.87495)
		(width 0.16002)
		(layer "In6.Cu")
		(net "M_E_CPU0_SB_DQS_DP<1>")
	)
	(segment
		(start 301.846996 -294.639238)
		(end 301.45609 -294.639238)
		(width 0.16002)
		(layer "In6.Cu")
		(net "M_E_CPU0_SB_DQS_DP<1>")
	)
	(segment
		(start 293.755826 -294.61841)
		(end 292.64737 -293.509954)
		(width 0.16002)
		(layer "In6.Cu")
		(net "M_E_CPU0_SB_DQS_DP<1>")
	)
	(segment
		(start 302.375062 -294.111172)
		(end 301.846996 -294.639238)
		(width 0.16002)
		(layer "In6.Cu")
		(net "M_E_CPU0_SB_DQS_DP<1>")
	)
	(segment
		(start 296.71645 -295.013126)
		(end 296.063162 -294.359838)
		(width 0.16002)
		(layer "In6.Cu")
		(net "M_E_CPU0_SB_DQS_DP<1>")
	)
	(segment
		(start 303.27092 -294.111172)
		(end 302.375062 -294.111172)
		(width 0.16002)
		(layer "In6.Cu")
		(net "M_E_CPU0_SB_DQS_DP<1>")
	)
	(segment
		(start 327.790302 -280.885138)
		(end 327.779888 -280.891234)
		(width 0.09525)
		(layer "In6.Cu")
		(net "M_E_CPU0_SB_DQS_DP<1>")
	)
	(segment
		(start 326.385428 -280.832052)
		(end 326.385428 -280.832306)
		(width 0.09525)
		(layer "In6.Cu")
		(net "M_E_CPU0_SB_DQS_DP<1>")
	)
	(segment
		(start 304.635662 -294.87495)
		(end 304.034698 -294.87495)
		(width 0.16002)
		(layer "In6.Cu")
		(net "M_E_CPU0_SB_DQS_DP<1>")
	)
	(segment
		(start 286.026098 -294.381936)
		(end 286.026098 -293.890192)
		(width 0.16002)
		(layer "In6.Cu")
		(net "M_E_CPU0_SB_DQS_DP<1>")
	)
	(segment
		(start 319.574672 -280.78049)
		(end 319.15354 -281.201622)
		(width 0.16002)
		(layer "In6.Cu")
		(net "M_E_CPU0_SB_DQS_DP<1>")
	)
	(segment
		(start 290.551108 -293.86911)
		(end 289.700462 -294.719756)
		(width 0.16002)
		(layer "In6.Cu")
		(net "M_E_CPU0_SB_DQS_DP<1>")
	)
	(segment
		(start 314.980066 -285.375096)
		(end 314.980066 -285.951168)
		(width 0.16002)
		(layer "In6.Cu")
		(net "M_E_CPU0_SB_DQS_DP<1>")
	)
	(segment
		(start 317.443104 -283.48813)
		(end 316.867032 -283.48813)
		(width 0.16002)
		(layer "In6.Cu")
		(net "M_E_CPU0_SB_DQS_DP<1>")
	)
	(segment
		(start 282.203144 -294.66921)
		(end 281.825954 -294.66921)
		(width 0.16002)
		(layer "In6.Cu")
		(net "M_E_CPU0_SB_DQS_DP<1>")
	)
	(segment
		(start 323.895974 -280.78049)
		(end 319.574672 -280.78049)
		(width 0.16002)
		(layer "In6.Cu")
		(net "M_E_CPU0_SB_DQS_DP<1>")
	)
	(segment
		(start 309.833518 -291.58946)
		(end 307.601874 -293.821104)
		(width 0.16002)
		(layer "In6.Cu")
		(net "M_E_CPU0_SB_DQS_DP<1>")
	)
	(segment
		(start 279.122886 -294.508936)
		(end 277.466044 -294.508936)
		(width 0.16002)
		(layer "In6.Cu")
		(net "M_E_CPU0_SB_DQS_DP<1>")
	)
	(segment
		(start 298.138088 -293.910004)
		(end 297.034966 -295.013126)
		(width 0.16002)
		(layer "In6.Cu")
		(net "M_E_CPU0_SB_DQS_DP<1>")
	)
	(segment
		(start 326.385428 -280.832306)
		(end 326.093074 -280.539952)
		(width 0.09525)
		(layer "In6.Cu")
		(net "M_E_CPU0_SB_DQS_DP<1>")
	)
	(segment
		(start 326.385682 -280.831798)
		(end 326.385428 -280.832052)
		(width 0.09525)
		(layer "In6.Cu")
		(net "M_E_CPU0_SB_DQS_DP<1>")
	)
	(segment
		(start 319.15354 -281.201622)
		(end 319.15354 -281.777694)
		(width 0.16002)
		(layer "In6.Cu")
		(net "M_E_CPU0_SB_DQS_DP<1>")
	)
	(segment
		(start 279.803606 -294.74541)
		(end 279.35936 -294.74541)
		(width 0.16002)
		(layer "In6.Cu")
		(net "M_E_CPU0_SB_DQS_DP<1>")
	)
	(segment
		(start 283.003244 -293.86911)
		(end 282.203144 -294.66921)
		(width 0.16002)
		(layer "In6.Cu")
		(net "M_E_CPU0_SB_DQS_DP<1>")
	)
	(segment
		(start 323.978778 -280.839672)
		(end 323.919596 -280.78049)
		(width 0.09525)
		(layer "In6.Cu")
		(net "M_E_CPU0_SB_DQS_DP<1>")
	)
	(segment
		(start 280.189178 -294.359838)
		(end 279.803606 -294.74541)
		(width 0.16002)
		(layer "In6.Cu")
		(net "M_E_CPU0_SB_DQS_DP<1>")
	)
	(segment
		(start 309.833518 -290.521644)
		(end 309.833518 -291.58946)
		(width 0.16002)
		(layer "In6.Cu")
		(net "M_E_CPU0_SB_DQS_DP<1>")
	)
	(segment
		(start 300.326806 -293.509954)
		(end 298.939458 -293.509954)
		(width 0.16002)
		(layer "In6.Cu")
		(net "M_E_CPU0_SB_DQS_DP<1>")
	)
	(segment
		(start 292.64737 -293.509954)
		(end 291.494464 -293.509954)
		(width 0.16002)
		(layer "In6.Cu")
		(net "M_E_CPU0_SB_DQS_DP<1>")
	)
	(segment
		(start 329.317096 -280.831544)
		(end 329.216258 -280.858214)
		(width 0.09525)
		(layer "In6.Cu")
		(net "M_E_CPU0_SB_DQS_DP<1>")
	)
	(segment
		(start 298.539408 -293.910004)
		(end 298.138088 -293.910004)
		(width 0.16002)
		(layer "In6.Cu")
		(net "M_E_CPU0_SB_DQS_DP<1>")
	)
	(segment
		(start 319.15354 -281.777694)
		(end 318.834262 -282.096972)
		(width 0.16002)
		(layer "In6.Cu")
		(net "M_E_CPU0_SB_DQS_DP<1>")
	)
	(segment
		(start 297.034966 -295.013126)
		(end 296.71645 -295.013126)
		(width 0.16002)
		(layer "In6.Cu")
		(net "M_E_CPU0_SB_DQS_DP<1>")
	)
	(segment
		(start 313.588908 -286.766254)
		(end 313.588908 -287.342326)
		(width 0.16002)
		(layer "In6.Cu")
		(net "M_E_CPU0_SB_DQS_DP<1>")
	)
	(segment
		(start 313.26963 -287.661604)
		(end 312.693558 -287.661604)
		(width 0.16002)
		(layer "In6.Cu")
		(net "M_E_CPU0_SB_DQS_DP<1>")
	)
	(segment
		(start 316.051946 -284.879288)
		(end 315.475874 -284.879288)
		(width 0.16002)
		(layer "In6.Cu")
		(net "M_E_CPU0_SB_DQS_DP<1>")
	)
	(segment
		(start 317.762382 -283.168852)
		(end 317.443104 -283.48813)
		(width 0.16002)
		(layer "In6.Cu")
		(net "M_E_CPU0_SB_DQS_DP<1>")
	)
	(segment
		(start 318.25819 -282.096972)
		(end 317.762382 -282.59278)
		(width 0.16002)
		(layer "In6.Cu")
		(net "M_E_CPU0_SB_DQS_DP<1>")
	)
	(segment
		(start 323.919596 -280.78049)
		(end 323.895974 -280.78049)
		(width 0.09525)
		(layer "In6.Cu")
		(net "M_E_CPU0_SB_DQS_DP<1>")
	)
	(segment
		(start 315.475874 -284.879288)
		(end 314.980066 -285.375096)
		(width 0.16002)
		(layer "In6.Cu")
		(net "M_E_CPU0_SB_DQS_DP<1>")
	)
	(segment
		(start 296.063162 -294.359838)
		(end 295.025572 -294.359838)
		(width 0.16002)
		(layer "In6.Cu")
		(net "M_E_CPU0_SB_DQS_DP<1>")
	)
	(segment
		(start 327.402952 -280.891234)
		(end 327.392538 -280.885138)
		(width 0.09525)
		(layer "In6.Cu")
		(net "M_E_CPU0_SB_DQS_DP<1>")
	)
	(segment
		(start 291.135308 -293.86911)
		(end 290.551108 -293.86911)
		(width 0.16002)
		(layer "In6.Cu")
		(net "M_E_CPU0_SB_DQS_DP<1>")
	)
	(segment
		(start 316.867032 -283.48813)
		(end 316.371224 -283.983938)
		(width 0.16002)
		(layer "In6.Cu")
		(net "M_E_CPU0_SB_DQS_DP<1>")
	)
	(segment
		(start 288.671508 -294.359838)
		(end 287.619186 -294.359838)
		(width 0.16002)
		(layer "In6.Cu")
		(net "M_E_CPU0_SB_DQS_DP<1>")
	)
	(segment
		(start 326.474836 -280.898092)
		(end 326.462898 -280.891234)
		(width 0.09525)
		(layer "In6.Cu")
		(net "M_E_CPU0_SB_DQS_DP<1>")
	)
	(segment
		(start 324.212458 -280.839672)
		(end 323.978778 -280.839672)
		(width 0.09525)
		(layer "In6.Cu")
		(net "M_E_CPU0_SB_DQS_DP<1>")
	)
	(segment
		(start 279.35936 -294.74541)
		(end 279.122886 -294.508936)
		(width 0.16002)
		(layer "In6.Cu")
		(net "M_E_CPU0_SB_DQS_DP<1>")
	)
	(segment
		(start 326.093074 -280.539952)
		(end 324.512178 -280.539952)
		(width 0.09525)
		(layer "In6.Cu")
		(net "M_E_CPU0_SB_DQS_DP<1>")
	)
	(segment
		(start 301.45609 -294.639238)
		(end 300.326806 -293.509954)
		(width 0.16002)
		(layer "In6.Cu")
		(net "M_E_CPU0_SB_DQS_DP<1>")
	)
	(segment
		(start 318.834262 -282.096972)
		(end 318.25819 -282.096972)
		(width 0.16002)
		(layer "In6.Cu")
		(net "M_E_CPU0_SB_DQS_DP<1>")
	)
	(segment
		(start 314.660788 -286.270446)
		(end 314.084716 -286.270446)
		(width 0.16002)
		(layer "In6.Cu")
		(net "M_E_CPU0_SB_DQS_DP<1>")
	)
	(segment
		(start 317.762382 -282.59278)
		(end 317.762382 -283.168852)
		(width 0.16002)
		(layer "In6.Cu")
		(net "M_E_CPU0_SB_DQS_DP<1>")
	)
	(segment
		(start 283.849064 -293.509954)
		(end 283.489908 -293.86911)
		(width 0.16002)
		(layer "In6.Cu")
		(net "M_E_CPU0_SB_DQS_DP<1>")
	)
	(segment
		(start 304.034698 -294.87495)
		(end 303.27092 -294.111172)
		(width 0.16002)
		(layer "In6.Cu")
		(net "M_E_CPU0_SB_DQS_DP<1>")
	)
	(segment
		(start 281.825954 -294.66921)
		(end 281.516582 -294.359838)
		(width 0.16002)
		(layer "In6.Cu")
		(net "M_E_CPU0_SB_DQS_DP<1>")
	)
	(segment
		(start 314.980066 -285.951168)
		(end 314.660788 -286.270446)
		(width 0.16002)
		(layer "In6.Cu")
		(net "M_E_CPU0_SB_DQS_DP<1>")
	)
	(segment
		(start 286.262572 -294.61841)
		(end 286.026098 -294.381936)
		(width 0.16002)
		(layer "In6.Cu")
		(net "M_E_CPU0_SB_DQS_DP<1>")
	)
	(segment
		(start 298.939458 -293.509954)
		(end 298.539408 -293.910004)
		(width 0.16002)
		(layer "In6.Cu")
		(net "M_E_CPU0_SB_DQS_DP<1>")
	)
	(segment
		(start 289.700462 -294.719756)
		(end 289.031426 -294.719756)
		(width 0.16002)
		(layer "In6.Cu")
		(net "M_E_CPU0_SB_DQS_DP<1>")
	)
	(segment
		(start 328.719688 -280.891234)
		(end 328.711306 -280.89606)
		(width 0.09525)
		(layer "In6.Cu")
		(net "M_E_CPU0_SB_DQS_DP<1>")
	)
	(segment
		(start 287.619186 -294.359838)
		(end 287.360614 -294.61841)
		(width 0.16002)
		(layer "In6.Cu")
		(net "M_E_CPU0_SB_DQS_DP<1>")
	)
	(segment
		(start 324.512178 -280.539952)
		(end 324.212458 -280.839672)
		(width 0.09525)
		(layer "In6.Cu")
		(net "M_E_CPU0_SB_DQS_DP<1>")
	)
	(segment
		(start 277.466044 -294.508936)
		(end 277.192232 -294.235124)
		(width 0.16002)
		(layer "In6.Cu")
		(net "M_E_CPU0_SB_DQS_DP<1>")
	)
	(segment
		(start 285.64586 -293.509954)
		(end 283.849064 -293.509954)
		(width 0.16002)
		(layer "In6.Cu")
		(net "M_E_CPU0_SB_DQS_DP<1>")
	)
	(segment
		(start 283.489908 -293.86911)
		(end 283.003244 -293.86911)
		(width 0.16002)
		(layer "In6.Cu")
		(net "M_E_CPU0_SB_DQS_DP<1>")
	)
	(segment
		(start 314.084716 -286.270446)
		(end 313.588908 -286.766254)
		(width 0.16002)
		(layer "In6.Cu")
		(net "M_E_CPU0_SB_DQS_DP<1>")
	)
	(segment
		(start 291.494464 -293.509954)
		(end 291.135308 -293.86911)
		(width 0.16002)
		(layer "In6.Cu")
		(net "M_E_CPU0_SB_DQS_DP<1>")
	)
	(segment
		(start 313.588908 -287.342326)
		(end 313.26963 -287.661604)
		(width 0.16002)
		(layer "In6.Cu")
		(net "M_E_CPU0_SB_DQS_DP<1>")
	)
	(segment
		(start 312.693558 -287.661604)
		(end 309.833518 -290.521644)
		(width 0.16002)
		(layer "In6.Cu")
		(net "M_E_CPU0_SB_DQS_DP<1>")
	)
	(arc
		(start 326.839834 -280.891234)
		(mid 326.658218 -280.941971)
		(end 326.474836 -280.898092)
		(width 0.09525)
		(layer "In6.Cu")
		(net "M_E_CPU0_SB_DQS_DP<1>")
	)
	(arc
		(start 326.462898 -280.891234)
		(mid 326.422347 -280.864039)
		(end 326.385682 -280.831798)
		(width 0.09525)
		(layer "In6.Cu")
		(net "M_E_CPU0_SB_DQS_DP<1>")
	)
	(arc
		(start 327.392538 -280.885138)
		(mid 327.115376 -280.815338)
		(end 326.839834 -280.891234)
		(width 0.09525)
		(layer "In6.Cu")
		(net "M_E_CPU0_SB_DQS_DP<1>")
	)
	(arc
		(start 328.342498 -280.891234)
		(mid 328.067209 -280.815513)
		(end 327.790302 -280.885138)
		(width 0.09525)
		(layer "In6.Cu")
		(net "M_E_CPU0_SB_DQS_DP<1>")
	)
	(arc
		(start 329.216258 -280.858214)
		(mid 328.964117 -280.816644)
		(end 328.719688 -280.891234)
		(width 0.09525)
		(layer "In6.Cu")
		(net "M_E_CPU0_SB_DQS_DP<1>")
	)
	(arc
		(start 328.711306 -280.89606)
		(mid 328.526274 -280.941974)
		(end 328.342498 -280.891234)
		(width 0.09525)
		(layer "In6.Cu")
		(net "M_E_CPU0_SB_DQS_DP<1>")
	)
	(arc
		(start 327.779888 -280.891234)
		(mid 327.59142 -280.941911)
		(end 327.402952 -280.891234)
		(width 0.09525)
		(layer "In6.Cu")
		(net "M_E_CPU0_SB_DQS_DP<1>")
	)
	(segment
		(start 329.937872 -275.44014)
		(end 329.47102 -275.706078)
		(width 0.12954)
		(layer "F.Cu")
		(net "M_E_CPU0_SB_DQS_DP<0>")
	)
	(segment
		(start 278.503126 -285.009844)
		(end 281.50566 -285.009844)
		(width 0.16002)
		(layer "In6.Cu")
		(net "M_E_CPU0_SB_DQS_DP<0>")
	)
	(segment
		(start 285.17723 -284.15996)
		(end 286.027114 -285.009844)
		(width 0.16002)
		(layer "In6.Cu")
		(net "M_E_CPU0_SB_DQS_DP<0>")
	)
	(segment
		(start 314.288932 -277.475696)
		(end 314.036456 -277.22322)
		(width 0.16002)
		(layer "In6.Cu")
		(net "M_E_CPU0_SB_DQS_DP<0>")
	)
	(segment
		(start 277.192232 -284.88513)
		(end 277.466044 -285.158942)
		(width 0.16002)
		(layer "In6.Cu")
		(net "M_E_CPU0_SB_DQS_DP<0>")
	)
	(segment
		(start 297.294808 -285.32201)
		(end 298.056808 -284.56001)
		(width 0.16002)
		(layer "In6.Cu")
		(net "M_E_CPU0_SB_DQS_DP<0>")
	)
	(segment
		(start 313.554364 -277.705312)
		(end 313.80684 -277.957788)
		(width 0.16002)
		(layer "In6.Cu")
		(net "M_E_CPU0_SB_DQS_DP<0>")
	)
	(segment
		(start 289.049714 -285.009844)
		(end 289.38728 -285.34741)
		(width 0.16002)
		(layer "In6.Cu")
		(net "M_E_CPU0_SB_DQS_DP<0>")
	)
	(segment
		(start 292.77183 -284.15996)
		(end 293.621714 -285.009844)
		(width 0.16002)
		(layer "In6.Cu")
		(net "M_E_CPU0_SB_DQS_DP<0>")
	)
	(segment
		(start 316.7253 -275.15693)
		(end 324.044818 -275.15693)
		(width 0.16002)
		(layer "In6.Cu")
		(net "M_E_CPU0_SB_DQS_DP<0>")
	)
	(segment
		(start 281.817826 -285.32201)
		(end 282.232608 -285.32201)
		(width 0.16002)
		(layer "In6.Cu")
		(net "M_E_CPU0_SB_DQS_DP<0>")
	)
	(segment
		(start 289.38728 -285.34741)
		(end 289.733736 -285.34741)
		(width 0.16002)
		(layer "In6.Cu")
		(net "M_E_CPU0_SB_DQS_DP<0>")
	)
	(segment
		(start 316.388242 -276.084792)
		(end 316.388242 -275.493988)
		(width 0.16002)
		(layer "In6.Cu")
		(net "M_E_CPU0_SB_DQS_DP<0>")
	)
	(segment
		(start 291.429186 -284.15996)
		(end 292.77183 -284.15996)
		(width 0.16002)
		(layer "In6.Cu")
		(net "M_E_CPU0_SB_DQS_DP<0>")
	)
	(segment
		(start 324.127622 -275.216112)
		(end 325.169784 -275.216112)
		(width 0.09525)
		(layer "In6.Cu")
		(net "M_E_CPU0_SB_DQS_DP<0>")
	)
	(segment
		(start 314.884562 -275.15693)
		(end 315.370464 -275.15693)
		(width 0.16002)
		(layer "In6.Cu")
		(net "M_E_CPU0_SB_DQS_DP<0>")
	)
	(segment
		(start 312.163206 -279.09647)
		(end 312.415682 -279.348946)
		(width 0.16002)
		(layer "In6.Cu")
		(net "M_E_CPU0_SB_DQS_DP<0>")
	)
	(segment
		(start 298.939458 -284.15996)
		(end 300.30039 -284.15996)
		(width 0.16002)
		(layer "In6.Cu")
		(net "M_E_CPU0_SB_DQS_DP<0>")
	)
	(segment
		(start 314.382658 -275.658834)
		(end 314.884562 -275.15693)
		(width 0.16002)
		(layer "In6.Cu")
		(net "M_E_CPU0_SB_DQS_DP<0>")
	)
	(segment
		(start 324.06844 -275.15693)
		(end 324.127622 -275.216112)
		(width 0.09525)
		(layer "In6.Cu")
		(net "M_E_CPU0_SB_DQS_DP<0>")
	)
	(segment
		(start 283.834586 -284.15996)
		(end 285.17723 -284.15996)
		(width 0.16002)
		(layer "In6.Cu")
		(net "M_E_CPU0_SB_DQS_DP<0>")
	)
	(segment
		(start 291.029136 -284.56001)
		(end 291.429186 -284.15996)
		(width 0.16002)
		(layer "In6.Cu")
		(net "M_E_CPU0_SB_DQS_DP<0>")
	)
	(segment
		(start 316.228222 -276.244812)
		(end 316.388242 -276.084792)
		(width 0.16002)
		(layer "In6.Cu")
		(net "M_E_CPU0_SB_DQS_DP<0>")
	)
	(segment
		(start 283.532072 -284.462474)
		(end 283.834586 -284.15996)
		(width 0.16002)
		(layer "In6.Cu")
		(net "M_E_CPU0_SB_DQS_DP<0>")
	)
	(segment
		(start 314.036456 -276.746716)
		(end 314.382658 -276.400514)
		(width 0.16002)
		(layer "In6.Cu")
		(net "M_E_CPU0_SB_DQS_DP<0>")
	)
	(segment
		(start 278.354028 -285.158942)
		(end 278.503126 -285.009844)
		(width 0.16002)
		(layer "In6.Cu")
		(net "M_E_CPU0_SB_DQS_DP<0>")
	)
	(segment
		(start 326.036178 -276.082506)
		(end 327.591166 -276.082506)
		(width 0.09525)
		(layer "In6.Cu")
		(net "M_E_CPU0_SB_DQS_DP<0>")
	)
	(segment
		(start 298.539408 -284.56001)
		(end 298.939458 -284.15996)
		(width 0.16002)
		(layer "In6.Cu")
		(net "M_E_CPU0_SB_DQS_DP<0>")
	)
	(segment
		(start 298.056808 -284.56001)
		(end 298.539408 -284.56001)
		(width 0.16002)
		(layer "In6.Cu")
		(net "M_E_CPU0_SB_DQS_DP<0>")
	)
	(segment
		(start 314.0329 -277.957788)
		(end 314.288932 -277.701756)
		(width 0.16002)
		(layer "In6.Cu")
		(net "M_E_CPU0_SB_DQS_DP<0>")
	)
	(segment
		(start 314.382658 -276.400514)
		(end 314.382658 -275.658834)
		(width 0.16002)
		(layer "In6.Cu")
		(net "M_E_CPU0_SB_DQS_DP<0>")
	)
	(segment
		(start 328.711306 -276.036024)
		(end 328.719688 -276.031198)
		(width 0.09525)
		(layer "In6.Cu")
		(net "M_E_CPU0_SB_DQS_DP<0>")
	)
	(segment
		(start 293.621714 -285.009844)
		(end 296.593514 -285.009844)
		(width 0.16002)
		(layer "In6.Cu")
		(net "M_E_CPU0_SB_DQS_DP<0>")
	)
	(segment
		(start 301.24654 -285.10611)
		(end 302.743108 -285.10611)
		(width 0.16002)
		(layer "In6.Cu")
		(net "M_E_CPU0_SB_DQS_DP<0>")
	)
	(segment
		(start 286.027114 -285.009844)
		(end 289.049714 -285.009844)
		(width 0.16002)
		(layer "In6.Cu")
		(net "M_E_CPU0_SB_DQS_DP<0>")
	)
	(segment
		(start 327.779888 -276.031198)
		(end 327.790302 -276.025102)
		(width 0.09525)
		(layer "In6.Cu")
		(net "M_E_CPU0_SB_DQS_DP<0>")
	)
	(segment
		(start 312.641742 -279.348946)
		(end 312.897774 -279.092914)
		(width 0.16002)
		(layer "In6.Cu")
		(net "M_E_CPU0_SB_DQS_DP<0>")
	)
	(segment
		(start 312.645298 -278.614378)
		(end 312.645298 -278.137874)
		(width 0.16002)
		(layer "In6.Cu")
		(net "M_E_CPU0_SB_DQS_DP<0>")
	)
	(segment
		(start 313.80684 -277.957788)
		(end 314.0329 -277.957788)
		(width 0.16002)
		(layer "In6.Cu")
		(net "M_E_CPU0_SB_DQS_DP<0>")
	)
	(segment
		(start 315.707522 -275.493988)
		(end 315.707522 -276.084792)
		(width 0.16002)
		(layer "In6.Cu")
		(net "M_E_CPU0_SB_DQS_DP<0>")
	)
	(segment
		(start 315.867542 -276.244812)
		(end 316.228222 -276.244812)
		(width 0.16002)
		(layer "In6.Cu")
		(net "M_E_CPU0_SB_DQS_DP<0>")
	)
	(segment
		(start 315.707522 -276.084792)
		(end 315.867542 -276.244812)
		(width 0.16002)
		(layer "In6.Cu")
		(net "M_E_CPU0_SB_DQS_DP<0>")
	)
	(segment
		(start 282.232608 -285.32201)
		(end 283.092144 -284.462474)
		(width 0.16002)
		(layer "In6.Cu")
		(net "M_E_CPU0_SB_DQS_DP<0>")
	)
	(segment
		(start 277.466044 -285.158942)
		(end 278.354028 -285.158942)
		(width 0.16002)
		(layer "In6.Cu")
		(net "M_E_CPU0_SB_DQS_DP<0>")
	)
	(segment
		(start 296.593514 -285.009844)
		(end 296.90568 -285.32201)
		(width 0.16002)
		(layer "In6.Cu")
		(net "M_E_CPU0_SB_DQS_DP<0>")
	)
	(segment
		(start 329.216258 -275.998178)
		(end 329.317096 -275.971508)
		(width 0.09525)
		(layer "In6.Cu")
		(net "M_E_CPU0_SB_DQS_DP<0>")
	)
	(segment
		(start 303.352708 -285.71571)
		(end 304.444908 -285.71571)
		(width 0.16002)
		(layer "In6.Cu")
		(net "M_E_CPU0_SB_DQS_DP<0>")
	)
	(segment
		(start 300.30039 -284.15996)
		(end 301.24654 -285.10611)
		(width 0.16002)
		(layer "In6.Cu")
		(net "M_E_CPU0_SB_DQS_DP<0>")
	)
	(segment
		(start 314.288932 -277.701756)
		(end 314.288932 -277.475696)
		(width 0.16002)
		(layer "In6.Cu")
		(net "M_E_CPU0_SB_DQS_DP<0>")
	)
	(segment
		(start 289.733736 -285.34741)
		(end 290.521136 -284.56001)
		(width 0.16002)
		(layer "In6.Cu")
		(net "M_E_CPU0_SB_DQS_DP<0>")
	)
	(segment
		(start 313.07786 -277.705312)
		(end 313.554364 -277.705312)
		(width 0.16002)
		(layer "In6.Cu")
		(net "M_E_CPU0_SB_DQS_DP<0>")
	)
	(segment
		(start 306.968906 -284.47111)
		(end 308.504336 -283.835094)
		(width 0.16002)
		(layer "In6.Cu")
		(net "M_E_CPU0_SB_DQS_DP<0>")
	)
	(segment
		(start 311.198006 -279.585166)
		(end 311.686702 -279.09647)
		(width 0.16002)
		(layer "In6.Cu")
		(net "M_E_CPU0_SB_DQS_DP<0>")
	)
	(segment
		(start 311.198006 -279.937972)
		(end 311.198006 -279.585166)
		(width 0.16002)
		(layer "In6.Cu")
		(net "M_E_CPU0_SB_DQS_DP<0>")
	)
	(segment
		(start 281.50566 -285.009844)
		(end 281.817826 -285.32201)
		(width 0.16002)
		(layer "In6.Cu")
		(net "M_E_CPU0_SB_DQS_DP<0>")
	)
	(segment
		(start 316.388242 -275.493988)
		(end 316.7253 -275.15693)
		(width 0.16002)
		(layer "In6.Cu")
		(net "M_E_CPU0_SB_DQS_DP<0>")
	)
	(segment
		(start 304.444908 -285.71571)
		(end 305.689508 -284.47111)
		(width 0.16002)
		(layer "In6.Cu")
		(net "M_E_CPU0_SB_DQS_DP<0>")
	)
	(segment
		(start 296.90568 -285.32201)
		(end 297.294808 -285.32201)
		(width 0.16002)
		(layer "In6.Cu")
		(net "M_E_CPU0_SB_DQS_DP<0>")
	)
	(segment
		(start 312.897774 -279.092914)
		(end 312.897774 -278.866854)
		(width 0.16002)
		(layer "In6.Cu")
		(net "M_E_CPU0_SB_DQS_DP<0>")
	)
	(segment
		(start 314.036456 -277.22322)
		(end 314.036456 -276.746716)
		(width 0.16002)
		(layer "In6.Cu")
		(net "M_E_CPU0_SB_DQS_DP<0>")
	)
	(segment
		(start 329.317096 -275.971508)
		(end 329.47102 -275.706078)
		(width 0.09525)
		(layer "In6.Cu")
		(net "M_E_CPU0_SB_DQS_DP<0>")
	)
	(segment
		(start 310.144668 -280.99131)
		(end 311.198006 -279.937972)
		(width 0.16002)
		(layer "In6.Cu")
		(net "M_E_CPU0_SB_DQS_DP<0>")
	)
	(segment
		(start 312.415682 -279.348946)
		(end 312.641742 -279.348946)
		(width 0.16002)
		(layer "In6.Cu")
		(net "M_E_CPU0_SB_DQS_DP<0>")
	)
	(segment
		(start 308.504336 -283.835094)
		(end 310.144668 -282.194762)
		(width 0.16002)
		(layer "In6.Cu")
		(net "M_E_CPU0_SB_DQS_DP<0>")
	)
	(segment
		(start 302.743108 -285.10611)
		(end 303.352708 -285.71571)
		(width 0.16002)
		(layer "In6.Cu")
		(net "M_E_CPU0_SB_DQS_DP<0>")
	)
	(segment
		(start 305.689508 -284.47111)
		(end 306.968906 -284.47111)
		(width 0.16002)
		(layer "In6.Cu")
		(net "M_E_CPU0_SB_DQS_DP<0>")
	)
	(segment
		(start 290.521136 -284.56001)
		(end 291.029136 -284.56001)
		(width 0.16002)
		(layer "In6.Cu")
		(net "M_E_CPU0_SB_DQS_DP<0>")
	)
	(segment
		(start 312.645298 -278.137874)
		(end 313.07786 -277.705312)
		(width 0.16002)
		(layer "In6.Cu")
		(net "M_E_CPU0_SB_DQS_DP<0>")
	)
	(segment
		(start 324.044818 -275.15693)
		(end 324.06844 -275.15693)
		(width 0.09525)
		(layer "In6.Cu")
		(net "M_E_CPU0_SB_DQS_DP<0>")
	)
	(segment
		(start 283.092144 -284.462474)
		(end 283.532072 -284.462474)
		(width 0.16002)
		(layer "In6.Cu")
		(net "M_E_CPU0_SB_DQS_DP<0>")
	)
	(segment
		(start 325.169784 -275.216112)
		(end 326.036178 -276.082506)
		(width 0.09525)
		(layer "In6.Cu")
		(net "M_E_CPU0_SB_DQS_DP<0>")
	)
	(segment
		(start 310.144668 -282.194762)
		(end 310.144668 -280.99131)
		(width 0.16002)
		(layer "In6.Cu")
		(net "M_E_CPU0_SB_DQS_DP<0>")
	)
	(segment
		(start 312.897774 -278.866854)
		(end 312.645298 -278.614378)
		(width 0.16002)
		(layer "In6.Cu")
		(net "M_E_CPU0_SB_DQS_DP<0>")
	)
	(segment
		(start 311.686702 -279.09647)
		(end 312.163206 -279.09647)
		(width 0.16002)
		(layer "In6.Cu")
		(net "M_E_CPU0_SB_DQS_DP<0>")
	)
	(segment
		(start 315.370464 -275.15693)
		(end 315.707522 -275.493988)
		(width 0.16002)
		(layer "In6.Cu")
		(net "M_E_CPU0_SB_DQS_DP<0>")
	)
	(arc
		(start 328.719688 -276.031198)
		(mid 328.953483 -275.957331)
		(end 329.196446 -275.990304)
		(width 0.09525)
		(layer "In6.Cu")
		(net "M_E_CPU0_SB_DQS_DP<0>")
	)
	(arc
		(start 327.790302 -276.025102)
		(mid 328.06721 -275.955425)
		(end 328.342498 -276.031198)
		(width 0.09525)
		(layer "In6.Cu")
		(net "M_E_CPU0_SB_DQS_DP<0>")
	)
	(arc
		(start 327.591166 -276.082506)
		(mid 327.688912 -276.069311)
		(end 327.779888 -276.031198)
		(width 0.09525)
		(layer "In6.Cu")
		(net "M_E_CPU0_SB_DQS_DP<0>")
	)
	(arc
		(start 328.342498 -276.031198)
		(mid 328.526273 -276.08197)
		(end 328.711306 -276.036024)
		(width 0.09525)
		(layer "In6.Cu")
		(net "M_E_CPU0_SB_DQS_DP<0>")
	)
	(arc
		(start 329.196446 -275.990304)
		(mid 329.206389 -275.994147)
		(end 329.216258 -275.998178)
		(width 0.09525)
		(layer "In6.Cu")
		(net "M_E_CPU0_SB_DQS_DP<0>")
	)
	(segment
		(start 329.467972 -271.39011)
		(end 329.00112 -271.656048)
		(width 0.12954)
		(layer "F.Cu")
		(net "M_E_CPU0_SB_DQS_DN<9>")
	)
	(segment
		(start 303.474628 -274.83181)
		(end 303.672494 -275.029676)
		(width 0.16002)
		(layer "In6.Cu")
		(net "M_E_CPU0_SB_DQS_DN<9>")
	)
	(segment
		(start 300.561502 -275.095716)
		(end 301.770796 -276.30501)
		(width 0.16002)
		(layer "In6.Cu")
		(net "M_E_CPU0_SB_DQS_DN<9>")
	)
	(segment
		(start 324.725538 -270.32966)
		(end 325.356728 -270.32966)
		(width 0.09525)
		(layer "In6.Cu")
		(net "M_E_CPU0_SB_DQS_DN<9>")
	)
	(segment
		(start 279.708356 -275.608542)
		(end 280.045414 -275.9456)
		(width 0.16002)
		(layer "In6.Cu")
		(net "M_E_CPU0_SB_DQS_DN<9>")
	)
	(segment
		(start 307.070506 -275.083016)
		(end 307.070506 -274.521676)
		(width 0.16002)
		(layer "In6.Cu")
		(net "M_E_CPU0_SB_DQS_DN<9>")
	)
	(segment
		(start 292.478714 -275.095716)
		(end 293.328598 -275.9456)
		(width 0.16002)
		(layer "In6.Cu")
		(net "M_E_CPU0_SB_DQS_DN<9>")
	)
	(segment
		(start 308.878478 -273.528282)
		(end 308.878478 -272.986246)
		(width 0.16002)
		(layer "In6.Cu")
		(net "M_E_CPU0_SB_DQS_DN<9>")
	)
	(segment
		(start 283.21508 -275.44141)
		(end 283.67228 -275.44141)
		(width 0.16002)
		(layer "In6.Cu")
		(net "M_E_CPU0_SB_DQS_DN<9>")
	)
	(segment
		(start 324.172326 -269.776448)
		(end 324.725538 -270.32966)
		(width 0.09525)
		(layer "In6.Cu")
		(net "M_E_CPU0_SB_DQS_DN<9>")
	)
	(segment
		(start 278.52497 -276.111208)
		(end 279.027636 -275.608542)
		(width 0.16002)
		(layer "In6.Cu")
		(net "M_E_CPU0_SB_DQS_DN<9>")
	)
	(segment
		(start 284.017974 -275.095716)
		(end 285.171642 -275.095716)
		(width 0.16002)
		(layer "In6.Cu")
		(net "M_E_CPU0_SB_DQS_DN<9>")
	)
	(segment
		(start 329.155044 -271.390618)
		(end 329.00112 -271.656048)
		(width 0.09525)
		(layer "In6.Cu")
		(net "M_E_CPU0_SB_DQS_DN<9>")
	)
	(segment
		(start 289.88258 -276.29231)
		(end 290.70808 -275.46681)
		(width 0.16002)
		(layer "In6.Cu")
		(net "M_E_CPU0_SB_DQS_DN<9>")
	)
	(segment
		(start 289.263836 -276.29231)
		(end 289.88258 -276.29231)
		(width 0.16002)
		(layer "In6.Cu")
		(net "M_E_CPU0_SB_DQS_DN<9>")
	)
	(segment
		(start 324.004178 -269.776448)
		(end 324.172326 -269.776448)
		(width 0.09525)
		(layer "In6.Cu")
		(net "M_E_CPU0_SB_DQS_DN<9>")
	)
	(segment
		(start 294.630348 -276.06244)
		(end 294.747188 -275.9456)
		(width 0.16002)
		(layer "In6.Cu")
		(net "M_E_CPU0_SB_DQS_DN<9>")
	)
	(segment
		(start 280.045414 -275.9456)
		(end 281.340052 -275.9456)
		(width 0.16002)
		(layer "In6.Cu")
		(net "M_E_CPU0_SB_DQS_DN<9>")
	)
	(segment
		(start 281.775154 -276.380702)
		(end 282.275788 -276.380702)
		(width 0.16002)
		(layer "In6.Cu")
		(net "M_E_CPU0_SB_DQS_DN<9>")
	)
	(segment
		(start 307.268372 -274.32381)
		(end 308.08295 -274.32381)
		(width 0.16002)
		(layer "In6.Cu")
		(net "M_E_CPU0_SB_DQS_DN<9>")
	)
	(segment
		(start 323.944996 -269.83563)
		(end 324.004178 -269.776448)
		(width 0.09525)
		(layer "In6.Cu")
		(net "M_E_CPU0_SB_DQS_DN<9>")
	)
	(segment
		(start 286.616902 -275.255736)
		(end 286.776922 -275.095716)
		(width 0.16002)
		(layer "In6.Cu")
		(net "M_E_CPU0_SB_DQS_DN<9>")
	)
	(segment
		(start 323.895974 -269.83563)
		(end 323.921374 -269.83563)
		(width 0.1016)
		(layer "In6.Cu")
		(net "M_E_CPU0_SB_DQS_DN<9>")
	)
	(segment
		(start 302.996854 -275.029676)
		(end 303.19472 -274.83181)
		(width 0.16002)
		(layer "In6.Cu")
		(net "M_E_CPU0_SB_DQS_DN<9>")
	)
	(segment
		(start 302.996854 -275.921216)
		(end 302.996854 -275.029676)
		(width 0.16002)
		(layer "In6.Cu")
		(net "M_E_CPU0_SB_DQS_DN<9>")
	)
	(segment
		(start 279.708356 -275.282152)
		(end 279.708356 -275.608542)
		(width 0.16002)
		(layer "In6.Cu")
		(net "M_E_CPU0_SB_DQS_DN<9>")
	)
	(segment
		(start 327.896474 -271.317466)
		(end 327.896728 -271.317974)
		(width 0.09525)
		(layer "In6.Cu")
		(net "M_E_CPU0_SB_DQS_DN<9>")
	)
	(segment
		(start 285.66872 -276.110192)
		(end 286.279844 -276.110192)
		(width 0.16002)
		(layer "In6.Cu")
		(net "M_E_CPU0_SB_DQS_DN<9>")
	)
	(segment
		(start 302.61306 -276.30501)
		(end 302.996854 -275.921216)
		(width 0.16002)
		(layer "In6.Cu")
		(net "M_E_CPU0_SB_DQS_DN<9>")
	)
	(segment
		(start 293.328598 -275.9456)
		(end 294.033448 -275.9456)
		(width 0.16002)
		(layer "In6.Cu")
		(net "M_E_CPU0_SB_DQS_DN<9>")
	)
	(segment
		(start 296.435526 -275.9456)
		(end 296.782236 -276.29231)
		(width 0.16002)
		(layer "In6.Cu")
		(net "M_E_CPU0_SB_DQS_DN<9>")
	)
	(segment
		(start 308.878478 -272.986246)
		(end 312.029094 -269.83563)
		(width 0.16002)
		(layer "In6.Cu")
		(net "M_E_CPU0_SB_DQS_DN<9>")
	)
	(segment
		(start 303.19472 -274.83181)
		(end 303.474628 -274.83181)
		(width 0.16002)
		(layer "In6.Cu")
		(net "M_E_CPU0_SB_DQS_DN<9>")
	)
	(segment
		(start 279.187656 -275.122132)
		(end 279.548336 -275.122132)
		(width 0.16002)
		(layer "In6.Cu")
		(net "M_E_CPU0_SB_DQS_DN<9>")
	)
	(segment
		(start 298.70908 -275.49221)
		(end 299.105574 -275.095716)
		(width 0.16002)
		(layer "In6.Cu")
		(net "M_E_CPU0_SB_DQS_DN<9>")
	)
	(segment
		(start 325.356728 -270.32966)
		(end 326.360282 -271.333722)
		(width 0.09525)
		(layer "In6.Cu")
		(net "M_E_CPU0_SB_DQS_DN<9>")
	)
	(segment
		(start 305.00828 -276.30501)
		(end 305.84648 -275.46681)
		(width 0.16002)
		(layer "In6.Cu")
		(net "M_E_CPU0_SB_DQS_DN<9>")
	)
	(segment
		(start 299.105574 -275.095716)
		(end 300.561502 -275.095716)
		(width 0.16002)
		(layer "In6.Cu")
		(net "M_E_CPU0_SB_DQS_DN<9>")
	)
	(segment
		(start 296.782236 -276.29231)
		(end 297.45178 -276.29231)
		(width 0.16002)
		(layer "In6.Cu")
		(net "M_E_CPU0_SB_DQS_DN<9>")
	)
	(segment
		(start 285.171642 -275.095716)
		(end 285.331662 -275.255736)
		(width 0.16002)
		(layer "In6.Cu")
		(net "M_E_CPU0_SB_DQS_DN<9>")
	)
	(segment
		(start 291.19068 -275.46681)
		(end 291.561774 -275.095716)
		(width 0.16002)
		(layer "In6.Cu")
		(net "M_E_CPU0_SB_DQS_DN<9>")
	)
	(segment
		(start 301.770796 -276.30501)
		(end 302.61306 -276.30501)
		(width 0.16002)
		(layer "In6.Cu")
		(net "M_E_CPU0_SB_DQS_DN<9>")
	)
	(segment
		(start 294.150288 -276.06244)
		(end 294.630348 -276.06244)
		(width 0.16002)
		(layer "In6.Cu")
		(net "M_E_CPU0_SB_DQS_DN<9>")
	)
	(segment
		(start 286.616902 -275.773134)
		(end 286.616902 -275.255736)
		(width 0.16002)
		(layer "In6.Cu")
		(net "M_E_CPU0_SB_DQS_DN<9>")
	)
	(segment
		(start 305.84648 -275.46681)
		(end 306.686712 -275.46681)
		(width 0.16002)
		(layer "In6.Cu")
		(net "M_E_CPU0_SB_DQS_DN<9>")
	)
	(segment
		(start 290.70808 -275.46681)
		(end 291.19068 -275.46681)
		(width 0.16002)
		(layer "In6.Cu")
		(net "M_E_CPU0_SB_DQS_DN<9>")
	)
	(segment
		(start 303.672494 -275.029676)
		(end 303.672494 -275.921216)
		(width 0.16002)
		(layer "In6.Cu")
		(net "M_E_CPU0_SB_DQS_DN<9>")
	)
	(segment
		(start 279.027636 -275.282152)
		(end 279.187656 -275.122132)
		(width 0.16002)
		(layer "In6.Cu")
		(net "M_E_CPU0_SB_DQS_DN<9>")
	)
	(segment
		(start 291.561774 -275.095716)
		(end 292.478714 -275.095716)
		(width 0.16002)
		(layer "In6.Cu")
		(net "M_E_CPU0_SB_DQS_DN<9>")
	)
	(segment
		(start 329.13193 -271.304004)
		(end 329.155044 -271.390618)
		(width 0.09525)
		(layer "In6.Cu")
		(net "M_E_CPU0_SB_DQS_DN<9>")
	)
	(segment
		(start 308.08295 -274.32381)
		(end 308.878478 -273.528282)
		(width 0.16002)
		(layer "In6.Cu")
		(net "M_E_CPU0_SB_DQS_DN<9>")
	)
	(segment
		(start 282.275788 -276.380702)
		(end 283.21508 -275.44141)
		(width 0.16002)
		(layer "In6.Cu")
		(net "M_E_CPU0_SB_DQS_DN<9>")
	)
	(segment
		(start 323.921374 -269.83563)
		(end 323.944996 -269.83563)
		(width 0.09525)
		(layer "In6.Cu")
		(net "M_E_CPU0_SB_DQS_DN<9>")
	)
	(segment
		(start 279.548336 -275.122132)
		(end 279.708356 -275.282152)
		(width 0.16002)
		(layer "In6.Cu")
		(net "M_E_CPU0_SB_DQS_DN<9>")
	)
	(segment
		(start 306.686712 -275.46681)
		(end 307.070506 -275.083016)
		(width 0.16002)
		(layer "In6.Cu")
		(net "M_E_CPU0_SB_DQS_DN<9>")
	)
	(segment
		(start 297.45178 -276.29231)
		(end 298.25188 -275.49221)
		(width 0.16002)
		(layer "In6.Cu")
		(net "M_E_CPU0_SB_DQS_DN<9>")
	)
	(segment
		(start 279.027636 -275.608542)
		(end 279.027636 -275.282152)
		(width 0.16002)
		(layer "In6.Cu")
		(net "M_E_CPU0_SB_DQS_DN<9>")
	)
	(segment
		(start 307.070506 -274.521676)
		(end 307.268372 -274.32381)
		(width 0.16002)
		(layer "In6.Cu")
		(net "M_E_CPU0_SB_DQS_DN<9>")
	)
	(segment
		(start 298.25188 -275.49221)
		(end 298.70908 -275.49221)
		(width 0.16002)
		(layer "In6.Cu")
		(net "M_E_CPU0_SB_DQS_DN<9>")
	)
	(segment
		(start 294.747188 -275.9456)
		(end 296.435526 -275.9456)
		(width 0.16002)
		(layer "In6.Cu")
		(net "M_E_CPU0_SB_DQS_DN<9>")
	)
	(segment
		(start 312.029094 -269.83563)
		(end 323.895974 -269.83563)
		(width 0.16002)
		(layer "In6.Cu")
		(net "M_E_CPU0_SB_DQS_DN<9>")
	)
	(segment
		(start 286.279844 -276.110192)
		(end 286.616902 -275.773134)
		(width 0.16002)
		(layer "In6.Cu")
		(net "M_E_CPU0_SB_DQS_DN<9>")
	)
	(segment
		(start 303.672494 -275.921216)
		(end 304.056288 -276.30501)
		(width 0.16002)
		(layer "In6.Cu")
		(net "M_E_CPU0_SB_DQS_DN<9>")
	)
	(segment
		(start 277.192232 -276.38502)
		(end 277.466044 -276.111208)
		(width 0.16002)
		(layer "In6.Cu")
		(net "M_E_CPU0_SB_DQS_DN<9>")
	)
	(segment
		(start 285.331662 -275.255736)
		(end 285.331662 -275.773134)
		(width 0.16002)
		(layer "In6.Cu")
		(net "M_E_CPU0_SB_DQS_DN<9>")
	)
	(segment
		(start 304.056288 -276.30501)
		(end 305.00828 -276.30501)
		(width 0.16002)
		(layer "In6.Cu")
		(net "M_E_CPU0_SB_DQS_DN<9>")
	)
	(segment
		(start 288.21253 -275.9456)
		(end 288.917126 -275.9456)
		(width 0.16002)
		(layer "In6.Cu")
		(net "M_E_CPU0_SB_DQS_DN<9>")
	)
	(segment
		(start 294.033448 -275.9456)
		(end 294.150288 -276.06244)
		(width 0.16002)
		(layer "In6.Cu")
		(net "M_E_CPU0_SB_DQS_DN<9>")
	)
	(segment
		(start 281.340052 -275.9456)
		(end 281.775154 -276.380702)
		(width 0.16002)
		(layer "In6.Cu")
		(net "M_E_CPU0_SB_DQS_DN<9>")
	)
	(segment
		(start 285.331662 -275.773134)
		(end 285.66872 -276.110192)
		(width 0.16002)
		(layer "In6.Cu")
		(net "M_E_CPU0_SB_DQS_DN<9>")
	)
	(segment
		(start 287.362646 -275.095716)
		(end 288.21253 -275.9456)
		(width 0.16002)
		(layer "In6.Cu")
		(net "M_E_CPU0_SB_DQS_DN<9>")
	)
	(segment
		(start 288.917126 -275.9456)
		(end 289.263836 -276.29231)
		(width 0.16002)
		(layer "In6.Cu")
		(net "M_E_CPU0_SB_DQS_DN<9>")
	)
	(segment
		(start 277.466044 -276.111208)
		(end 278.52497 -276.111208)
		(width 0.16002)
		(layer "In6.Cu")
		(net "M_E_CPU0_SB_DQS_DN<9>")
	)
	(segment
		(start 286.776922 -275.095716)
		(end 287.362646 -275.095716)
		(width 0.16002)
		(layer "In6.Cu")
		(net "M_E_CPU0_SB_DQS_DN<9>")
	)
	(segment
		(start 283.67228 -275.44141)
		(end 284.017974 -275.095716)
		(width 0.16002)
		(layer "In6.Cu")
		(net "M_E_CPU0_SB_DQS_DN<9>")
	)
	(arc
		(start 327.896728 -271.317974)
		(mid 328.074871 -271.280401)
		(end 328.249788 -271.330928)
		(width 0.09525)
		(layer "In6.Cu")
		(net "M_E_CPU0_SB_DQS_DN<9>")
	)
	(arc
		(start 326.360282 -271.333722)
		(mid 326.446098 -271.396126)
		(end 326.547226 -271.42821)
		(width 0.09525)
		(layer "In6.Cu")
		(net "M_E_CPU0_SB_DQS_DN<9>")
	)
	(arc
		(start 326.547226 -271.42821)
		(mid 327.162021 -271.452082)
		(end 327.770744 -271.362678)
		(width 0.09525)
		(layer "In6.Cu")
		(net "M_E_CPU0_SB_DQS_DN<9>")
	)
	(arc
		(start 328.249788 -271.330928)
		(mid 328.53122 -271.406683)
		(end 328.812652 -271.330928)
		(width 0.09525)
		(layer "In6.Cu")
		(net "M_E_CPU0_SB_DQS_DN<9>")
	)
	(arc
		(start 328.812652 -271.330928)
		(mid 328.969279 -271.281742)
		(end 329.13193 -271.304004)
		(width 0.09525)
		(layer "In6.Cu")
		(net "M_E_CPU0_SB_DQS_DN<9>")
	)
	(arc
		(start 327.770744 -271.362678)
		(mid 327.83481 -271.34341)
		(end 327.896474 -271.317466)
		(width 0.09525)
		(layer "In6.Cu")
		(net "M_E_CPU0_SB_DQS_DN<9>")
	)
	(segment
		(start 331.34808 -290.83)
		(end 330.880974 -291.095938)
		(width 0.12954)
		(layer "F.Cu")
		(net "M_E_CPU0_SB_DQS_DN<8>")
	)
	(segment
		(start 314.590938 -304.965354)
		(end 314.590938 -305.365912)
		(width 0.16002)
		(layer "In6.Cu")
		(net "M_E_CPU0_SB_DQS_DN<8>")
	)
	(segment
		(start 283.491178 -313.88431)
		(end 283.244036 -313.88431)
		(width 0.16002)
		(layer "In6.Cu")
		(net "M_E_CPU0_SB_DQS_DN<8>")
	)
	(segment
		(start 330.129642 -291.421058)
		(end 330.12126 -291.425884)
		(width 0.09525)
		(layer "In6.Cu")
		(net "M_E_CPU0_SB_DQS_DN<8>")
	)
	(segment
		(start 327.636124 -291.472366)
		(end 325.628254 -293.480236)
		(width 0.09525)
		(layer "In6.Cu")
		(net "M_E_CPU0_SB_DQS_DN<8>")
	)
	(segment
		(start 328.061066 -291.472366)
		(end 327.636124 -291.472366)
		(width 0.09525)
		(layer "In6.Cu")
		(net "M_E_CPU0_SB_DQS_DN<8>")
	)
	(segment
		(start 295.563798 -315.058044)
		(end 293.632636 -314.673996)
		(width 0.16002)
		(layer "In6.Cu")
		(net "M_E_CPU0_SB_DQS_DN<8>")
	)
	(segment
		(start 279.198832 -314.67806)
		(end 276.978364 -314.236608)
		(width 0.16002)
		(layer "In6.Cu")
		(net "M_E_CPU0_SB_DQS_DN<8>")
	)
	(segment
		(start 307.44668 -313.87161)
		(end 305.600608 -313.87161)
		(width 0.16002)
		(layer "In6.Cu")
		(net "M_E_CPU0_SB_DQS_DN<8>")
	)
	(segment
		(start 280.842212 -315.058044)
		(end 280.451306 -315.058044)
		(width 0.16002)
		(layer "In6.Cu")
		(net "M_E_CPU0_SB_DQS_DN<8>")
	)
	(segment
		(start 288.520632 -315.058044)
		(end 287.611566 -315.058044)
		(width 0.16002)
		(layer "In6.Cu")
		(net "M_E_CPU0_SB_DQS_DN<8>")
	)
	(segment
		(start 311.995058 -309.323232)
		(end 307.44668 -313.87161)
		(width 0.16002)
		(layer "In6.Cu")
		(net "M_E_CPU0_SB_DQS_DN<8>")
	)
	(segment
		(start 283.244036 -313.88431)
		(end 282.958286 -313.970924)
		(width 0.16002)
		(layer "In6.Cu")
		(net "M_E_CPU0_SB_DQS_DN<8>")
	)
	(segment
		(start 276.978364 -314.236608)
		(end 276.352 -313.942222)
		(width 0.16002)
		(layer "In6.Cu")
		(net "M_E_CPU0_SB_DQS_DN<8>")
	)
	(segment
		(start 276.352 -313.942222)
		(end 275.791422 -313.859164)
		(width 0.16002)
		(layer "In6.Cu")
		(net "M_E_CPU0_SB_DQS_DN<8>")
	)
	(segment
		(start 273.844512 -314.059062)
		(end 273.36623 -314.059062)
		(width 0.16002)
		(layer "In6.Cu")
		(net "M_E_CPU0_SB_DQS_DN<8>")
	)
	(segment
		(start 298.176188 -313.879992)
		(end 297.231816 -314.510928)
		(width 0.16002)
		(layer "In6.Cu")
		(net "M_E_CPU0_SB_DQS_DN<8>")
	)
	(segment
		(start 293.632636 -314.673996)
		(end 291.081714 -313.85891)
		(width 0.16002)
		(layer "In6.Cu")
		(net "M_E_CPU0_SB_DQS_DN<8>")
	)
	(segment
		(start 282.127452 -314.52566)
		(end 280.842212 -315.058044)
		(width 0.16002)
		(layer "In6.Cu")
		(net "M_E_CPU0_SB_DQS_DN<8>")
	)
	(segment
		(start 314.590938 -305.365912)
		(end 311.995058 -307.961792)
		(width 0.16002)
		(layer "In6.Cu")
		(net "M_E_CPU0_SB_DQS_DN<8>")
	)
	(segment
		(start 299.99178 -314.64631)
		(end 299.225462 -313.879992)
		(width 0.16002)
		(layer "In6.Cu")
		(net "M_E_CPU0_SB_DQS_DN<8>")
	)
	(segment
		(start 297.231816 -314.510928)
		(end 295.913048 -315.058044)
		(width 0.16002)
		(layer "In6.Cu")
		(net "M_E_CPU0_SB_DQS_DN<8>")
	)
	(segment
		(start 330.880974 -291.095938)
		(end 330.72705 -291.361368)
		(width 0.09525)
		(layer "In6.Cu")
		(net "M_E_CPU0_SB_DQS_DN<8>")
	)
	(segment
		(start 304.825908 -314.64631)
		(end 299.99178 -314.64631)
		(width 0.16002)
		(layer "In6.Cu")
		(net "M_E_CPU0_SB_DQS_DN<8>")
	)
	(segment
		(start 286.495998 -314.836302)
		(end 283.491178 -313.88431)
		(width 0.16002)
		(layer "In6.Cu")
		(net "M_E_CPU0_SB_DQS_DN<8>")
	)
	(segment
		(start 275.791422 -313.859164)
		(end 273.844512 -314.059062)
		(width 0.16002)
		(layer "In6.Cu")
		(net "M_E_CPU0_SB_DQS_DN<8>")
	)
	(segment
		(start 280.451306 -315.058044)
		(end 279.198832 -314.67806)
		(width 0.16002)
		(layer "In6.Cu")
		(net "M_E_CPU0_SB_DQS_DN<8>")
	)
	(segment
		(start 273.36623 -314.059062)
		(end 273.092164 -313.784996)
		(width 0.16002)
		(layer "In6.Cu")
		(net "M_E_CPU0_SB_DQS_DN<8>")
	)
	(segment
		(start 291.081714 -313.85891)
		(end 290.786058 -313.85891)
		(width 0.16002)
		(layer "In6.Cu")
		(net "M_E_CPU0_SB_DQS_DN<8>")
	)
	(segment
		(start 290.786058 -313.85891)
		(end 288.520632 -315.058044)
		(width 0.16002)
		(layer "In6.Cu")
		(net "M_E_CPU0_SB_DQS_DN<8>")
	)
	(segment
		(start 287.611566 -315.058044)
		(end 286.495998 -314.836302)
		(width 0.16002)
		(layer "In6.Cu")
		(net "M_E_CPU0_SB_DQS_DN<8>")
	)
	(segment
		(start 324.942962 -294.61333)
		(end 314.590938 -304.965354)
		(width 0.16002)
		(layer "In6.Cu")
		(net "M_E_CPU0_SB_DQS_DN<8>")
	)
	(segment
		(start 325.628254 -294.011096)
		(end 325.042784 -294.596566)
		(width 0.09525)
		(layer "In6.Cu")
		(net "M_E_CPU0_SB_DQS_DN<8>")
	)
	(segment
		(start 311.995058 -307.961792)
		(end 311.995058 -309.323232)
		(width 0.16002)
		(layer "In6.Cu")
		(net "M_E_CPU0_SB_DQS_DN<8>")
	)
	(segment
		(start 325.628254 -293.480236)
		(end 325.628254 -294.011096)
		(width 0.09525)
		(layer "In6.Cu")
		(net "M_E_CPU0_SB_DQS_DN<8>")
	)
	(segment
		(start 305.600608 -313.87161)
		(end 304.825908 -314.64631)
		(width 0.16002)
		(layer "In6.Cu")
		(net "M_E_CPU0_SB_DQS_DN<8>")
	)
	(segment
		(start 324.959726 -294.596566)
		(end 324.942962 -294.61333)
		(width 0.09525)
		(layer "In6.Cu")
		(net "M_E_CPU0_SB_DQS_DN<8>")
	)
	(segment
		(start 325.042784 -294.596566)
		(end 324.959726 -294.596566)
		(width 0.09525)
		(layer "In6.Cu")
		(net "M_E_CPU0_SB_DQS_DN<8>")
	)
	(segment
		(start 299.225462 -313.879992)
		(end 298.176188 -313.879992)
		(width 0.16002)
		(layer "In6.Cu")
		(net "M_E_CPU0_SB_DQS_DN<8>")
	)
	(segment
		(start 295.913048 -315.058044)
		(end 295.563798 -315.058044)
		(width 0.16002)
		(layer "In6.Cu")
		(net "M_E_CPU0_SB_DQS_DN<8>")
	)
	(segment
		(start 282.958286 -313.970924)
		(end 282.127452 -314.52566)
		(width 0.16002)
		(layer "In6.Cu")
		(net "M_E_CPU0_SB_DQS_DN<8>")
	)
	(segment
		(start 330.72705 -291.361368)
		(end 330.626212 -291.388038)
		(width 0.09525)
		(layer "In6.Cu")
		(net "M_E_CPU0_SB_DQS_DN<8>")
	)
	(arc
		(start 328.812652 -291.421058)
		(mid 328.53122 -291.345303)
		(end 328.249788 -291.421058)
		(width 0.09525)
		(layer "In6.Cu")
		(net "M_E_CPU0_SB_DQS_DN<8>")
	)
	(arc
		(start 330.12126 -291.425884)
		(mid 329.936228 -291.471798)
		(end 329.752452 -291.421058)
		(width 0.09525)
		(layer "In6.Cu")
		(net "M_E_CPU0_SB_DQS_DN<8>")
	)
	(arc
		(start 328.249788 -291.421058)
		(mid 328.158822 -291.459211)
		(end 328.061066 -291.472366)
		(width 0.09525)
		(layer "In6.Cu")
		(net "M_E_CPU0_SB_DQS_DN<8>")
	)
	(arc
		(start 330.626212 -291.388038)
		(mid 330.374071 -291.346468)
		(end 330.129642 -291.421058)
		(width 0.09525)
		(layer "In6.Cu")
		(net "M_E_CPU0_SB_DQS_DN<8>")
	)
	(arc
		(start 329.752452 -291.421058)
		(mid 329.47102 -291.345303)
		(end 329.189588 -291.421058)
		(width 0.09525)
		(layer "In6.Cu")
		(net "M_E_CPU0_SB_DQS_DN<8>")
	)
	(arc
		(start 329.189588 -291.421058)
		(mid 329.00112 -291.471735)
		(end 328.812652 -291.421058)
		(width 0.09525)
		(layer "In6.Cu")
		(net "M_E_CPU0_SB_DQS_DN<8>")
	)
	(segment
		(start 331.34808 -285.970218)
		(end 330.880974 -286.236156)
		(width 0.12954)
		(layer "F.Cu")
		(net "M_E_CPU0_SB_DQS_DN<7>")
	)
	(segment
		(start 305.176428 -304.92192)
		(end 305.763168 -304.529998)
		(width 0.16002)
		(layer "In6.Cu")
		(net "M_E_CPU0_SB_DQS_DN<7>")
	)
	(segment
		(start 330.626212 -286.528256)
		(end 330.72705 -286.501586)
		(width 0.09525)
		(layer "In6.Cu")
		(net "M_E_CPU0_SB_DQS_DN<7>")
	)
	(segment
		(start 298.190158 -304.529998)
		(end 298.853098 -304.529998)
		(width 0.16002)
		(layer "In6.Cu")
		(net "M_E_CPU0_SB_DQS_DN<7>")
	)
	(segment
		(start 303.280064 -305.29911)
		(end 305.176428 -304.92192)
		(width 0.16002)
		(layer "In6.Cu")
		(net "M_E_CPU0_SB_DQS_DN<7>")
	)
	(segment
		(start 320.895472 -290.090606)
		(end 321.384422 -289.888168)
		(width 0.16002)
		(layer "In6.Cu")
		(net "M_E_CPU0_SB_DQS_DN<7>")
	)
	(segment
		(start 301.961296 -305.29911)
		(end 303.280064 -305.29911)
		(width 0.16002)
		(layer "In6.Cu")
		(net "M_E_CPU0_SB_DQS_DN<7>")
	)
	(segment
		(start 310.233568 -300.401228)
		(end 320.295524 -290.339272)
		(width 0.16002)
		(layer "In6.Cu")
		(net "M_E_CPU0_SB_DQS_DN<7>")
	)
	(segment
		(start 276.83714 -304.802794)
		(end 280.45029 -305.70805)
		(width 0.16002)
		(layer "In6.Cu")
		(net "M_E_CPU0_SB_DQS_DN<7>")
	)
	(segment
		(start 290.699952 -304.504598)
		(end 291.074856 -304.504598)
		(width 0.16002)
		(layer "In6.Cu")
		(net "M_E_CPU0_SB_DQS_DN<7>")
	)
	(segment
		(start 320.895218 -290.09086)
		(end 320.895472 -290.090606)
		(width 0.16002)
		(layer "In6.Cu")
		(net "M_E_CPU0_SB_DQS_DN<7>")
	)
	(segment
		(start 287.91281 -305.70805)
		(end 288.45002 -305.70805)
		(width 0.16002)
		(layer "In6.Cu")
		(net "M_E_CPU0_SB_DQS_DN<7>")
	)
	(segment
		(start 324.283578 -287.28035)
		(end 324.300342 -287.263586)
		(width 0.09525)
		(layer "In6.Cu")
		(net "M_E_CPU0_SB_DQS_DN<7>")
	)
	(segment
		(start 273.36623 -304.709068)
		(end 273.941032 -304.709068)
		(width 0.16002)
		(layer "In6.Cu")
		(net "M_E_CPU0_SB_DQS_DN<7>")
	)
	(segment
		(start 284.47746 -304.857912)
		(end 285.859982 -304.857912)
		(width 0.16002)
		(layer "In6.Cu")
		(net "M_E_CPU0_SB_DQS_DN<7>")
	)
	(segment
		(start 285.859982 -304.857912)
		(end 287.91281 -305.70805)
		(width 0.16002)
		(layer "In6.Cu")
		(net "M_E_CPU0_SB_DQS_DN<7>")
	)
	(segment
		(start 283.672026 -304.52441)
		(end 284.47746 -304.857912)
		(width 0.16002)
		(layer "In6.Cu")
		(net "M_E_CPU0_SB_DQS_DN<7>")
	)
	(segment
		(start 280.45029 -305.70805)
		(end 280.817574 -305.70805)
		(width 0.16002)
		(layer "In6.Cu")
		(net "M_E_CPU0_SB_DQS_DN<7>")
	)
	(segment
		(start 276.103334 -304.49901)
		(end 276.83714 -304.802794)
		(width 0.16002)
		(layer "In6.Cu")
		(net "M_E_CPU0_SB_DQS_DN<7>")
	)
	(segment
		(start 282.2321 -305.122072)
		(end 283.126942 -304.52441)
		(width 0.16002)
		(layer "In6.Cu")
		(net "M_E_CPU0_SB_DQS_DN<7>")
	)
	(segment
		(start 288.45002 -305.70805)
		(end 290.058856 -304.932842)
		(width 0.16002)
		(layer "In6.Cu")
		(net "M_E_CPU0_SB_DQS_DN<7>")
	)
	(segment
		(start 283.126942 -304.52441)
		(end 283.672026 -304.52441)
		(width 0.16002)
		(layer "In6.Cu")
		(net "M_E_CPU0_SB_DQS_DN<7>")
	)
	(segment
		(start 309.417974 -302.369982)
		(end 310.233568 -300.401228)
		(width 0.16002)
		(layer "In6.Cu")
		(net "M_E_CPU0_SB_DQS_DN<7>")
	)
	(segment
		(start 300.896274 -304.857912)
		(end 301.961296 -305.29911)
		(width 0.16002)
		(layer "In6.Cu")
		(net "M_E_CPU0_SB_DQS_DN<7>")
	)
	(segment
		(start 293.323772 -304.857912)
		(end 295.3766 -305.70805)
		(width 0.16002)
		(layer "In6.Cu")
		(net "M_E_CPU0_SB_DQS_DN<7>")
	)
	(segment
		(start 324.300342 -287.263586)
		(end 324.383908 -287.263586)
		(width 0.09525)
		(layer "In6.Cu")
		(net "M_E_CPU0_SB_DQS_DN<7>")
	)
	(segment
		(start 324.056756 -287.507172)
		(end 324.283578 -287.28035)
		(width 0.16002)
		(layer "In6.Cu")
		(net "M_E_CPU0_SB_DQS_DN<7>")
	)
	(segment
		(start 297.88358 -304.757582)
		(end 298.190158 -304.529998)
		(width 0.16002)
		(layer "In6.Cu")
		(net "M_E_CPU0_SB_DQS_DN<7>")
	)
	(segment
		(start 273.092164 -304.435002)
		(end 273.36623 -304.709068)
		(width 0.16002)
		(layer "In6.Cu")
		(net "M_E_CPU0_SB_DQS_DN<7>")
	)
	(segment
		(start 274.997418 -304.49901)
		(end 276.103334 -304.49901)
		(width 0.16002)
		(layer "In6.Cu")
		(net "M_E_CPU0_SB_DQS_DN<7>")
	)
	(segment
		(start 325.981568 -286.906462)
		(end 326.242426 -286.645604)
		(width 0.09525)
		(layer "In6.Cu")
		(net "M_E_CPU0_SB_DQS_DN<7>")
	)
	(segment
		(start 273.941032 -304.709068)
		(end 274.997418 -304.49901)
		(width 0.16002)
		(layer "In6.Cu")
		(net "M_E_CPU0_SB_DQS_DN<7>")
	)
	(segment
		(start 306.469288 -304.529998)
		(end 307.815742 -303.972214)
		(width 0.16002)
		(layer "In6.Cu")
		(net "M_E_CPU0_SB_DQS_DN<7>")
	)
	(segment
		(start 330.72705 -286.501586)
		(end 330.880974 -286.236156)
		(width 0.09525)
		(layer "In6.Cu")
		(net "M_E_CPU0_SB_DQS_DN<7>")
	)
	(segment
		(start 295.3766 -305.70805)
		(end 296.105072 -305.70805)
		(width 0.16002)
		(layer "In6.Cu")
		(net "M_E_CPU0_SB_DQS_DN<7>")
	)
	(segment
		(start 326.62876 -286.485584)
		(end 326.651112 -286.485584)
		(width 0.09525)
		(layer "In6.Cu")
		(net "M_E_CPU0_SB_DQS_DN<7>")
	)
	(segment
		(start 323.765418 -287.507172)
		(end 324.056756 -287.507172)
		(width 0.16002)
		(layer "In6.Cu")
		(net "M_E_CPU0_SB_DQS_DN<7>")
	)
	(segment
		(start 324.383908 -287.263586)
		(end 324.741032 -286.906462)
		(width 0.09525)
		(layer "In6.Cu")
		(net "M_E_CPU0_SB_DQS_DN<7>")
	)
	(segment
		(start 307.815742 -303.972214)
		(end 309.417974 -302.369982)
		(width 0.16002)
		(layer "In6.Cu")
		(net "M_E_CPU0_SB_DQS_DN<7>")
	)
	(segment
		(start 280.817574 -305.70805)
		(end 282.2321 -305.122072)
		(width 0.16002)
		(layer "In6.Cu")
		(net "M_E_CPU0_SB_DQS_DN<7>")
	)
	(segment
		(start 291.074856 -304.504598)
		(end 291.928042 -304.857912)
		(width 0.16002)
		(layer "In6.Cu")
		(net "M_E_CPU0_SB_DQS_DN<7>")
	)
	(segment
		(start 327.872598 -286.561276)
		(end 327.88098 -286.566102)
		(width 0.09525)
		(layer "In6.Cu")
		(net "M_E_CPU0_SB_DQS_DN<7>")
	)
	(segment
		(start 299.644816 -304.857912)
		(end 300.896274 -304.857912)
		(width 0.16002)
		(layer "In6.Cu")
		(net "M_E_CPU0_SB_DQS_DN<7>")
	)
	(segment
		(start 324.741032 -286.906462)
		(end 325.981568 -286.906462)
		(width 0.09525)
		(layer "In6.Cu")
		(net "M_E_CPU0_SB_DQS_DN<7>")
	)
	(segment
		(start 330.12126 -286.566102)
		(end 330.129642 -286.561276)
		(width 0.09525)
		(layer "In6.Cu")
		(net "M_E_CPU0_SB_DQS_DN<7>")
	)
	(segment
		(start 320.295524 -290.339272)
		(end 320.895218 -290.09086)
		(width 0.16002)
		(layer "In6.Cu")
		(net "M_E_CPU0_SB_DQS_DN<7>")
	)
	(segment
		(start 298.853098 -304.529998)
		(end 299.644816 -304.857912)
		(width 0.16002)
		(layer "In6.Cu")
		(net "M_E_CPU0_SB_DQS_DN<7>")
	)
	(segment
		(start 290.058856 -304.932842)
		(end 290.699952 -304.504598)
		(width 0.16002)
		(layer "In6.Cu")
		(net "M_E_CPU0_SB_DQS_DN<7>")
	)
	(segment
		(start 326.932544 -286.561276)
		(end 326.940926 -286.566102)
		(width 0.09525)
		(layer "In6.Cu")
		(net "M_E_CPU0_SB_DQS_DN<7>")
	)
	(segment
		(start 291.928042 -304.857912)
		(end 293.323772 -304.857912)
		(width 0.16002)
		(layer "In6.Cu")
		(net "M_E_CPU0_SB_DQS_DN<7>")
	)
	(segment
		(start 321.384422 -289.888168)
		(end 323.765418 -287.507172)
		(width 0.16002)
		(layer "In6.Cu")
		(net "M_E_CPU0_SB_DQS_DN<7>")
	)
	(segment
		(start 296.105072 -305.70805)
		(end 297.88358 -304.757582)
		(width 0.16002)
		(layer "In6.Cu")
		(net "M_E_CPU0_SB_DQS_DN<7>")
	)
	(segment
		(start 305.763168 -304.529998)
		(end 306.469288 -304.529998)
		(width 0.16002)
		(layer "In6.Cu")
		(net "M_E_CPU0_SB_DQS_DN<7>")
	)
	(arc
		(start 329.189588 -286.561276)
		(mid 329.47102 -286.485487)
		(end 329.752452 -286.561276)
		(width 0.09525)
		(layer "In6.Cu")
		(net "M_E_CPU0_SB_DQS_DN<7>")
	)
	(arc
		(start 330.129642 -286.561276)
		(mid 330.374067 -286.486599)
		(end 330.626212 -286.528256)
		(width 0.09525)
		(layer "In6.Cu")
		(net "M_E_CPU0_SB_DQS_DN<7>")
	)
	(arc
		(start 327.309734 -286.561276)
		(mid 327.591166 -286.485487)
		(end 327.872598 -286.561276)
		(width 0.09525)
		(layer "In6.Cu")
		(net "M_E_CPU0_SB_DQS_DN<7>")
	)
	(arc
		(start 328.812652 -286.561276)
		(mid 329.00112 -286.611953)
		(end 329.189588 -286.561276)
		(width 0.09525)
		(layer "In6.Cu")
		(net "M_E_CPU0_SB_DQS_DN<7>")
	)
	(arc
		(start 326.940926 -286.566102)
		(mid 327.125958 -286.612016)
		(end 327.309734 -286.561276)
		(width 0.09525)
		(layer "In6.Cu")
		(net "M_E_CPU0_SB_DQS_DN<7>")
	)
	(arc
		(start 327.88098 -286.566102)
		(mid 328.066012 -286.612016)
		(end 328.249788 -286.561276)
		(width 0.09525)
		(layer "In6.Cu")
		(net "M_E_CPU0_SB_DQS_DN<7>")
	)
	(arc
		(start 328.249788 -286.561276)
		(mid 328.53122 -286.485487)
		(end 328.812652 -286.561276)
		(width 0.09525)
		(layer "In6.Cu")
		(net "M_E_CPU0_SB_DQS_DN<7>")
	)
	(arc
		(start 326.242426 -286.645604)
		(mid 326.419678 -286.527168)
		(end 326.62876 -286.485584)
		(width 0.09525)
		(layer "In6.Cu")
		(net "M_E_CPU0_SB_DQS_DN<7>")
	)
	(arc
		(start 326.651112 -286.485584)
		(mid 326.796841 -286.504798)
		(end 326.932544 -286.561276)
		(width 0.09525)
		(layer "In6.Cu")
		(net "M_E_CPU0_SB_DQS_DN<7>")
	)
	(arc
		(start 329.752452 -286.561276)
		(mid 329.936227 -286.612048)
		(end 330.12126 -286.566102)
		(width 0.09525)
		(layer "In6.Cu")
		(net "M_E_CPU0_SB_DQS_DN<7>")
	)
	(segment
		(start 331.34808 -281.110182)
		(end 330.880974 -281.37612)
		(width 0.12954)
		(layer "F.Cu")
		(net "M_E_CPU0_SB_DQS_DN<6>")
	)
	(segment
		(start 305.265074 -295.581578)
		(end 305.666648 -295.180004)
		(width 0.16002)
		(layer "In6.Cu")
		(net "M_E_CPU0_SB_DQS_DN<6>")
	)
	(segment
		(start 323.978778 -281.731212)
		(end 325.267574 -281.731212)
		(width 0.09525)
		(layer "In6.Cu")
		(net "M_E_CPU0_SB_DQS_DN<6>")
	)
	(segment
		(start 283.053536 -295.17721)
		(end 283.67228 -295.17721)
		(width 0.16002)
		(layer "In6.Cu")
		(net "M_E_CPU0_SB_DQS_DN<6>")
	)
	(segment
		(start 280.7589 -296.358056)
		(end 282.66009 -295.570656)
		(width 0.16002)
		(layer "In6.Cu")
		(net "M_E_CPU0_SB_DQS_DN<6>")
	)
	(segment
		(start 330.626212 -281.66822)
		(end 330.72705 -281.64155)
		(width 0.09525)
		(layer "In6.Cu")
		(net "M_E_CPU0_SB_DQS_DN<6>")
	)
	(segment
		(start 288.421064 -296.358056)
		(end 289.99053 -295.707816)
		(width 0.16002)
		(layer "In6.Cu")
		(net "M_E_CPU0_SB_DQS_DN<6>")
	)
	(segment
		(start 287.836356 -296.358056)
		(end 288.421064 -296.358056)
		(width 0.16002)
		(layer "In6.Cu")
		(net "M_E_CPU0_SB_DQS_DN<6>")
	)
	(segment
		(start 327.876408 -281.703272)
		(end 327.87717 -281.70378)
		(width 0.09525)
		(layer "In6.Cu")
		(net "M_E_CPU0_SB_DQS_DN<6>")
	)
	(segment
		(start 308.047898 -294.603678)
		(end 310.702198 -291.949378)
		(width 0.16002)
		(layer "In6.Cu")
		(net "M_E_CPU0_SB_DQS_DN<6>")
	)
	(segment
		(start 291.19068 -295.154604)
		(end 292.043612 -295.507918)
		(width 0.16002)
		(layer "In6.Cu")
		(net "M_E_CPU0_SB_DQS_DN<6>")
	)
	(segment
		(start 311.049924 -291.109908)
		(end 320.487802 -281.67203)
		(width 0.16002)
		(layer "In6.Cu")
		(net "M_E_CPU0_SB_DQS_DN<6>")
	)
	(segment
		(start 297.468798 -295.865804)
		(end 298.139358 -295.195244)
		(width 0.16002)
		(layer "In6.Cu")
		(net "M_E_CPU0_SB_DQS_DN<6>")
	)
	(segment
		(start 289.99053 -295.707816)
		(end 290.543742 -295.154604)
		(width 0.16002)
		(layer "In6.Cu")
		(net "M_E_CPU0_SB_DQS_DN<6>")
	)
	(segment
		(start 274.387564 -295.359074)
		(end 274.918678 -295.13911)
		(width 0.16002)
		(layer "In6.Cu")
		(net "M_E_CPU0_SB_DQS_DN<6>")
	)
	(segment
		(start 325.267574 -281.731212)
		(end 325.460614 -281.538172)
		(width 0.09525)
		(layer "In6.Cu")
		(net "M_E_CPU0_SB_DQS_DN<6>")
	)
	(segment
		(start 306.65674 -295.180004)
		(end 308.047898 -294.603678)
		(width 0.16002)
		(layer "In6.Cu")
		(net "M_E_CPU0_SB_DQS_DN<6>")
	)
	(segment
		(start 282.66009 -295.570656)
		(end 283.053536 -295.17721)
		(width 0.16002)
		(layer "In6.Cu")
		(net "M_E_CPU0_SB_DQS_DN<6>")
	)
	(segment
		(start 305.666648 -295.180004)
		(end 306.65674 -295.180004)
		(width 0.16002)
		(layer "In6.Cu")
		(net "M_E_CPU0_SB_DQS_DN<6>")
	)
	(segment
		(start 327.872852 -281.70124)
		(end 327.873614 -281.701748)
		(width 0.09525)
		(layer "In6.Cu")
		(net "M_E_CPU0_SB_DQS_DN<6>")
	)
	(segment
		(start 298.85386 -295.195244)
		(end 299.608748 -295.507918)
		(width 0.16002)
		(layer "In6.Cu")
		(net "M_E_CPU0_SB_DQS_DN<6>")
	)
	(segment
		(start 292.043612 -295.507918)
		(end 293.91102 -295.507918)
		(width 0.16002)
		(layer "In6.Cu")
		(net "M_E_CPU0_SB_DQS_DN<6>")
	)
	(segment
		(start 279.007824 -296.358056)
		(end 280.7589 -296.358056)
		(width 0.16002)
		(layer "In6.Cu")
		(net "M_E_CPU0_SB_DQS_DN<6>")
	)
	(segment
		(start 273.36623 -295.359074)
		(end 274.387564 -295.359074)
		(width 0.16002)
		(layer "In6.Cu")
		(net "M_E_CPU0_SB_DQS_DN<6>")
	)
	(segment
		(start 286.7533 -295.909492)
		(end 287.836356 -296.358056)
		(width 0.16002)
		(layer "In6.Cu")
		(net "M_E_CPU0_SB_DQS_DN<6>")
	)
	(segment
		(start 330.72705 -281.64155)
		(end 330.880974 -281.37612)
		(width 0.09525)
		(layer "In6.Cu")
		(net "M_E_CPU0_SB_DQS_DN<6>")
	)
	(segment
		(start 274.918678 -295.13911)
		(end 276.06498 -295.13911)
		(width 0.16002)
		(layer "In6.Cu")
		(net "M_E_CPU0_SB_DQS_DN<6>")
	)
	(segment
		(start 301.487332 -295.507918)
		(end 301.997364 -296.01795)
		(width 0.16002)
		(layer "In6.Cu")
		(net "M_E_CPU0_SB_DQS_DN<6>")
	)
	(segment
		(start 283.67228 -295.17721)
		(end 284.470602 -295.507918)
		(width 0.16002)
		(layer "In6.Cu")
		(net "M_E_CPU0_SB_DQS_DN<6>")
	)
	(segment
		(start 323.919596 -281.67203)
		(end 323.978778 -281.731212)
		(width 0.09525)
		(layer "In6.Cu")
		(net "M_E_CPU0_SB_DQS_DN<6>")
	)
	(segment
		(start 320.487802 -281.67203)
		(end 323.895974 -281.67203)
		(width 0.16002)
		(layer "In6.Cu")
		(net "M_E_CPU0_SB_DQS_DN<6>")
	)
	(segment
		(start 327.873614 -281.701748)
		(end 327.876408 -281.703272)
		(width 0.09525)
		(layer "In6.Cu")
		(net "M_E_CPU0_SB_DQS_DN<6>")
	)
	(segment
		(start 293.91102 -295.507918)
		(end 294.337994 -295.934892)
		(width 0.16002)
		(layer "In6.Cu")
		(net "M_E_CPU0_SB_DQS_DN<6>")
	)
	(segment
		(start 299.608748 -295.507918)
		(end 301.487332 -295.507918)
		(width 0.16002)
		(layer "In6.Cu")
		(net "M_E_CPU0_SB_DQS_DN<6>")
	)
	(segment
		(start 297.20413 -295.975532)
		(end 297.468798 -295.865804)
		(width 0.16002)
		(layer "In6.Cu")
		(net "M_E_CPU0_SB_DQS_DN<6>")
	)
	(segment
		(start 325.460614 -281.538172)
		(end 327.266046 -281.538172)
		(width 0.09525)
		(layer "In6.Cu")
		(net "M_E_CPU0_SB_DQS_DN<6>")
	)
	(segment
		(start 284.470602 -295.507918)
		(end 286.118046 -295.507918)
		(width 0.16002)
		(layer "In6.Cu")
		(net "M_E_CPU0_SB_DQS_DN<6>")
	)
	(segment
		(start 294.337994 -295.934892)
		(end 295.359836 -296.358056)
		(width 0.16002)
		(layer "In6.Cu")
		(net "M_E_CPU0_SB_DQS_DN<6>")
	)
	(segment
		(start 323.895974 -281.67203)
		(end 323.919596 -281.67203)
		(width 0.09525)
		(layer "In6.Cu")
		(net "M_E_CPU0_SB_DQS_DN<6>")
	)
	(segment
		(start 330.12126 -281.706066)
		(end 330.129642 -281.70124)
		(width 0.09525)
		(layer "In6.Cu")
		(net "M_E_CPU0_SB_DQS_DN<6>")
	)
	(segment
		(start 295.359836 -296.358056)
		(end 295.963848 -296.358056)
		(width 0.16002)
		(layer "In6.Cu")
		(net "M_E_CPU0_SB_DQS_DN<6>")
	)
	(segment
		(start 304.211482 -296.01795)
		(end 305.265074 -295.581578)
		(width 0.16002)
		(layer "In6.Cu")
		(net "M_E_CPU0_SB_DQS_DN<6>")
	)
	(segment
		(start 310.702198 -291.949378)
		(end 311.049924 -291.109908)
		(width 0.16002)
		(layer "In6.Cu")
		(net "M_E_CPU0_SB_DQS_DN<6>")
	)
	(segment
		(start 327.87717 -281.70378)
		(end 327.88479 -281.708098)
		(width 0.09525)
		(layer "In6.Cu")
		(net "M_E_CPU0_SB_DQS_DN<6>")
	)
	(segment
		(start 276.06498 -295.13911)
		(end 279.007824 -296.358056)
		(width 0.16002)
		(layer "In6.Cu")
		(net "M_E_CPU0_SB_DQS_DN<6>")
	)
	(segment
		(start 273.092164 -295.085008)
		(end 273.36623 -295.359074)
		(width 0.16002)
		(layer "In6.Cu")
		(net "M_E_CPU0_SB_DQS_DN<6>")
	)
	(segment
		(start 301.997364 -296.01795)
		(end 304.211482 -296.01795)
		(width 0.16002)
		(layer "In6.Cu")
		(net "M_E_CPU0_SB_DQS_DN<6>")
	)
	(segment
		(start 286.118046 -295.507918)
		(end 286.516826 -295.673018)
		(width 0.16002)
		(layer "In6.Cu")
		(net "M_E_CPU0_SB_DQS_DN<6>")
	)
	(segment
		(start 290.543742 -295.154604)
		(end 291.19068 -295.154604)
		(width 0.16002)
		(layer "In6.Cu")
		(net "M_E_CPU0_SB_DQS_DN<6>")
	)
	(segment
		(start 298.139358 -295.195244)
		(end 298.85386 -295.195244)
		(width 0.16002)
		(layer "In6.Cu")
		(net "M_E_CPU0_SB_DQS_DN<6>")
	)
	(segment
		(start 286.516826 -295.673018)
		(end 286.7533 -295.909492)
		(width 0.16002)
		(layer "In6.Cu")
		(net "M_E_CPU0_SB_DQS_DN<6>")
	)
	(segment
		(start 295.963848 -296.358056)
		(end 296.887392 -295.975532)
		(width 0.16002)
		(layer "In6.Cu")
		(net "M_E_CPU0_SB_DQS_DN<6>")
	)
	(segment
		(start 296.887392 -295.975532)
		(end 297.20413 -295.975532)
		(width 0.16002)
		(layer "In6.Cu")
		(net "M_E_CPU0_SB_DQS_DN<6>")
	)
	(arc
		(start 327.88479 -281.708098)
		(mid 328.068171 -281.751929)
		(end 328.249788 -281.70124)
		(width 0.09525)
		(layer "In6.Cu")
		(net "M_E_CPU0_SB_DQS_DN<6>")
	)
	(arc
		(start 327.266046 -281.538172)
		(mid 327.268586 -281.538169)
		(end 327.271126 -281.538172)
		(width 0.09525)
		(layer "In6.Cu")
		(net "M_E_CPU0_SB_DQS_DN<6>")
	)
	(arc
		(start 329.752452 -281.70124)
		(mid 329.936227 -281.752012)
		(end 330.12126 -281.706066)
		(width 0.09525)
		(layer "In6.Cu")
		(net "M_E_CPU0_SB_DQS_DN<6>")
	)
	(arc
		(start 330.129642 -281.70124)
		(mid 330.363437 -281.627373)
		(end 330.6064 -281.660346)
		(width 0.09525)
		(layer "In6.Cu")
		(net "M_E_CPU0_SB_DQS_DN<6>")
	)
	(arc
		(start 328.812652 -281.70124)
		(mid 329.00112 -281.751917)
		(end 329.189588 -281.70124)
		(width 0.09525)
		(layer "In6.Cu")
		(net "M_E_CPU0_SB_DQS_DN<6>")
	)
	(arc
		(start 329.189588 -281.70124)
		(mid 329.47102 -281.625485)
		(end 329.752452 -281.70124)
		(width 0.09525)
		(layer "In6.Cu")
		(net "M_E_CPU0_SB_DQS_DN<6>")
	)
	(arc
		(start 330.6064 -281.660346)
		(mid 330.616343 -281.664189)
		(end 330.626212 -281.66822)
		(width 0.09525)
		(layer "In6.Cu")
		(net "M_E_CPU0_SB_DQS_DN<6>")
	)
	(arc
		(start 328.249788 -281.70124)
		(mid 328.53122 -281.625485)
		(end 328.812652 -281.70124)
		(width 0.09525)
		(layer "In6.Cu")
		(net "M_E_CPU0_SB_DQS_DN<6>")
	)
	(arc
		(start 327.271126 -281.538172)
		(mid 327.582645 -281.580375)
		(end 327.872852 -281.70124)
		(width 0.09525)
		(layer "In6.Cu")
		(net "M_E_CPU0_SB_DQS_DN<6>")
	)
	(segment
		(start 331.34808 -276.250146)
		(end 330.880974 -276.516084)
		(width 0.12954)
		(layer "F.Cu")
		(net "M_E_CPU0_SB_DQS_DN<5>")
	)
	(segment
		(start 327.870566 -276.83968)
		(end 327.491598 -276.615652)
		(width 0.09525)
		(layer "In6.Cu")
		(net "M_E_CPU0_SB_DQS_DN<5>")
	)
	(segment
		(start 324.04304 -276.04847)
		(end 324.019418 -276.04847)
		(width 0.09525)
		(layer "In6.Cu")
		(net "M_E_CPU0_SB_DQS_DN<5>")
	)
	(segment
		(start 278.462232 -286.174434)
		(end 276.481032 -286.174434)
		(width 0.16002)
		(layer "In6.Cu")
		(net "M_E_CPU0_SB_DQS_DN<5>")
	)
	(segment
		(start 289.992308 -286.40151)
		(end 289.543236 -286.40151)
		(width 0.16002)
		(layer "In6.Cu")
		(net "M_E_CPU0_SB_DQS_DN<5>")
	)
	(segment
		(start 324.019418 -276.04847)
		(end 317.653924 -276.04847)
		(width 0.16002)
		(layer "In6.Cu")
		(net "M_E_CPU0_SB_DQS_DN<5>")
	)
	(segment
		(start 327.491598 -276.615652)
		(end 324.887082 -276.615652)
		(width 0.09525)
		(layer "In6.Cu")
		(net "M_E_CPU0_SB_DQS_DN<5>")
	)
	(segment
		(start 286.345122 -286.157924)
		(end 284.000194 -286.157924)
		(width 0.16002)
		(layer "In6.Cu")
		(net "M_E_CPU0_SB_DQS_DN<5>")
	)
	(segment
		(start 288.936684 -287.008062)
		(end 287.19526 -287.008062)
		(width 0.16002)
		(layer "In6.Cu")
		(net "M_E_CPU0_SB_DQS_DN<5>")
	)
	(segment
		(start 324.887082 -276.615652)
		(end 324.379082 -276.107652)
		(width 0.09525)
		(layer "In6.Cu")
		(net "M_E_CPU0_SB_DQS_DN<5>")
	)
	(segment
		(start 274.513294 -286.00908)
		(end 273.36623 -286.00908)
		(width 0.16002)
		(layer "In6.Cu")
		(net "M_E_CPU0_SB_DQS_DN<5>")
	)
	(segment
		(start 283.053536 -285.77921)
		(end 282.49372 -286.339026)
		(width 0.16002)
		(layer "In6.Cu")
		(net "M_E_CPU0_SB_DQS_DN<5>")
	)
	(segment
		(start 293.271194 -286.157924)
		(end 291.543994 -286.157924)
		(width 0.16002)
		(layer "In6.Cu")
		(net "M_E_CPU0_SB_DQS_DN<5>")
	)
	(segment
		(start 282.49372 -286.339026)
		(end 281.699208 -286.66821)
		(width 0.16002)
		(layer "In6.Cu")
		(net "M_E_CPU0_SB_DQS_DN<5>")
	)
	(segment
		(start 296.480484 -287.008062)
		(end 295.323768 -287.008062)
		(width 0.16002)
		(layer "In6.Cu")
		(net "M_E_CPU0_SB_DQS_DN<5>")
	)
	(segment
		(start 291.543994 -286.157924)
		(end 291.19068 -285.80461)
		(width 0.16002)
		(layer "In6.Cu")
		(net "M_E_CPU0_SB_DQS_DN<5>")
	)
	(segment
		(start 289.543236 -286.40151)
		(end 288.936684 -287.008062)
		(width 0.16002)
		(layer "In6.Cu")
		(net "M_E_CPU0_SB_DQS_DN<5>")
	)
	(segment
		(start 309.088282 -284.614112)
		(end 306.152804 -285.83001)
		(width 0.16002)
		(layer "In6.Cu")
		(net "M_E_CPU0_SB_DQS_DN<5>")
	)
	(segment
		(start 290.589208 -285.80461)
		(end 289.992308 -286.40151)
		(width 0.16002)
		(layer "In6.Cu")
		(net "M_E_CPU0_SB_DQS_DN<5>")
	)
	(segment
		(start 281.359356 -287.008062)
		(end 279.29586 -287.008062)
		(width 0.16002)
		(layer "In6.Cu")
		(net "M_E_CPU0_SB_DQS_DN<5>")
	)
	(segment
		(start 324.379082 -276.107652)
		(end 324.102222 -276.107652)
		(width 0.09525)
		(layer "In6.Cu")
		(net "M_E_CPU0_SB_DQS_DN<5>")
	)
	(segment
		(start 279.29586 -287.008062)
		(end 278.462232 -286.174434)
		(width 0.16002)
		(layer "In6.Cu")
		(net "M_E_CPU0_SB_DQS_DN<5>")
	)
	(segment
		(start 273.36623 -286.00908)
		(end 273.092164 -285.735014)
		(width 0.16002)
		(layer "In6.Cu")
		(net "M_E_CPU0_SB_DQS_DN<5>")
	)
	(segment
		(start 296.845736 -286.64281)
		(end 296.480484 -287.008062)
		(width 0.16002)
		(layer "In6.Cu")
		(net "M_E_CPU0_SB_DQS_DN<5>")
	)
	(segment
		(start 298.79798 -285.83001)
		(end 298.133008 -285.83001)
		(width 0.16002)
		(layer "In6.Cu")
		(net "M_E_CPU0_SB_DQS_DN<5>")
	)
	(segment
		(start 301.508922 -286.157924)
		(end 299.125894 -286.157924)
		(width 0.16002)
		(layer "In6.Cu")
		(net "M_E_CPU0_SB_DQS_DN<5>")
	)
	(segment
		(start 305.651408 -285.83001)
		(end 304.851308 -286.63011)
		(width 0.16002)
		(layer "In6.Cu")
		(net "M_E_CPU0_SB_DQS_DN<5>")
	)
	(segment
		(start 295.323768 -287.008062)
		(end 293.271194 -286.157924)
		(width 0.16002)
		(layer "In6.Cu")
		(net "M_E_CPU0_SB_DQS_DN<5>")
	)
	(segment
		(start 276.098508 -285.79191)
		(end 275.037804 -285.79191)
		(width 0.16002)
		(layer "In6.Cu")
		(net "M_E_CPU0_SB_DQS_DN<5>")
	)
	(segment
		(start 276.481032 -286.174434)
		(end 276.098508 -285.79191)
		(width 0.16002)
		(layer "In6.Cu")
		(net "M_E_CPU0_SB_DQS_DN<5>")
	)
	(segment
		(start 284.000194 -286.157924)
		(end 283.62148 -285.77921)
		(width 0.16002)
		(layer "In6.Cu")
		(net "M_E_CPU0_SB_DQS_DN<5>")
	)
	(segment
		(start 283.62148 -285.77921)
		(end 283.053536 -285.77921)
		(width 0.16002)
		(layer "In6.Cu")
		(net "M_E_CPU0_SB_DQS_DN<5>")
	)
	(segment
		(start 291.19068 -285.80461)
		(end 290.589208 -285.80461)
		(width 0.16002)
		(layer "In6.Cu")
		(net "M_E_CPU0_SB_DQS_DN<5>")
	)
	(segment
		(start 306.152804 -285.83001)
		(end 305.651408 -285.83001)
		(width 0.16002)
		(layer "In6.Cu")
		(net "M_E_CPU0_SB_DQS_DN<5>")
	)
	(segment
		(start 304.851308 -286.63011)
		(end 301.981108 -286.63011)
		(width 0.16002)
		(layer "In6.Cu")
		(net "M_E_CPU0_SB_DQS_DN<5>")
	)
	(segment
		(start 287.19526 -287.008062)
		(end 286.345122 -286.157924)
		(width 0.16002)
		(layer "In6.Cu")
		(net "M_E_CPU0_SB_DQS_DN<5>")
	)
	(segment
		(start 324.102222 -276.107652)
		(end 324.04304 -276.04847)
		(width 0.09525)
		(layer "In6.Cu")
		(net "M_E_CPU0_SB_DQS_DN<5>")
	)
	(segment
		(start 281.699208 -286.66821)
		(end 281.359356 -287.008062)
		(width 0.16002)
		(layer "In6.Cu")
		(net "M_E_CPU0_SB_DQS_DN<5>")
	)
	(segment
		(start 330.129642 -276.841204)
		(end 330.12126 -276.84603)
		(width 0.09525)
		(layer "In6.Cu")
		(net "M_E_CPU0_SB_DQS_DN<5>")
	)
	(segment
		(start 330.72705 -276.781514)
		(end 330.626212 -276.808184)
		(width 0.09525)
		(layer "In6.Cu")
		(net "M_E_CPU0_SB_DQS_DN<5>")
	)
	(segment
		(start 317.653924 -276.04847)
		(end 309.088282 -284.614112)
		(width 0.16002)
		(layer "In6.Cu")
		(net "M_E_CPU0_SB_DQS_DN<5>")
	)
	(segment
		(start 299.125894 -286.157924)
		(end 298.79798 -285.83001)
		(width 0.16002)
		(layer "In6.Cu")
		(net "M_E_CPU0_SB_DQS_DN<5>")
	)
	(segment
		(start 297.320208 -286.64281)
		(end 296.845736 -286.64281)
		(width 0.16002)
		(layer "In6.Cu")
		(net "M_E_CPU0_SB_DQS_DN<5>")
	)
	(segment
		(start 301.981108 -286.63011)
		(end 301.508922 -286.157924)
		(width 0.16002)
		(layer "In6.Cu")
		(net "M_E_CPU0_SB_DQS_DN<5>")
	)
	(segment
		(start 275.037804 -285.79191)
		(end 274.513294 -286.00908)
		(width 0.16002)
		(layer "In6.Cu")
		(net "M_E_CPU0_SB_DQS_DN<5>")
	)
	(segment
		(start 298.133008 -285.83001)
		(end 297.320208 -286.64281)
		(width 0.16002)
		(layer "In6.Cu")
		(net "M_E_CPU0_SB_DQS_DN<5>")
	)
	(segment
		(start 330.880974 -276.516084)
		(end 330.72705 -276.781514)
		(width 0.09525)
		(layer "In6.Cu")
		(net "M_E_CPU0_SB_DQS_DN<5>")
	)
	(arc
		(start 330.12126 -276.84603)
		(mid 329.936228 -276.891944)
		(end 329.752452 -276.841204)
		(width 0.09525)
		(layer "In6.Cu")
		(net "M_E_CPU0_SB_DQS_DN<5>")
	)
	(arc
		(start 330.626212 -276.808184)
		(mid 330.374071 -276.766614)
		(end 330.129642 -276.841204)
		(width 0.09525)
		(layer "In6.Cu")
		(net "M_E_CPU0_SB_DQS_DN<5>")
	)
	(arc
		(start 328.812652 -276.841204)
		(mid 328.53122 -276.765449)
		(end 328.249788 -276.841204)
		(width 0.09525)
		(layer "In6.Cu")
		(net "M_E_CPU0_SB_DQS_DN<5>")
	)
	(arc
		(start 329.189588 -276.841204)
		(mid 329.00112 -276.891881)
		(end 328.812652 -276.841204)
		(width 0.09525)
		(layer "In6.Cu")
		(net "M_E_CPU0_SB_DQS_DN<5>")
	)
	(arc
		(start 329.752452 -276.841204)
		(mid 329.47102 -276.765449)
		(end 329.189588 -276.841204)
		(width 0.09525)
		(layer "In6.Cu")
		(net "M_E_CPU0_SB_DQS_DN<5>")
	)
	(arc
		(start 328.249788 -276.841204)
		(mid 328.059984 -276.891853)
		(end 327.870566 -276.83968)
		(width 0.09525)
		(layer "In6.Cu")
		(net "M_E_CPU0_SB_DQS_DN<5>")
	)
	(segment
		(start 331.34808 -271.39011)
		(end 330.880974 -271.656048)
		(width 0.12954)
		(layer "F.Cu")
		(net "M_E_CPU0_SB_DQS_DN<4>")
	)
	(segment
		(start 306.737766 -276.47011)
		(end 305.672236 -276.47011)
		(width 0.16002)
		(layer "In6.Cu")
		(net "M_E_CPU0_SB_DQS_DN<4>")
	)
	(segment
		(start 301.879508 -277.28291)
		(end 301.404528 -276.80793)
		(width 0.16002)
		(layer "In6.Cu")
		(net "M_E_CPU0_SB_DQS_DN<4>")
	)
	(segment
		(start 275.214334 -276.41931)
		(end 274.974558 -276.659086)
		(width 0.16002)
		(layer "In6.Cu")
		(net "M_E_CPU0_SB_DQS_DN<4>")
	)
	(segment
		(start 291.5412 -276.80793)
		(end 291.21608 -276.48281)
		(width 0.16002)
		(layer "In6.Cu")
		(net "M_E_CPU0_SB_DQS_DN<4>")
	)
	(segment
		(start 309.358792 -273.849084)
		(end 306.737766 -276.47011)
		(width 0.16002)
		(layer "In6.Cu")
		(net "M_E_CPU0_SB_DQS_DN<4>")
	)
	(segment
		(start 327.374504 -271.84731)
		(end 326.517254 -271.84731)
		(width 0.09525)
		(layer "In6.Cu")
		(net "M_E_CPU0_SB_DQS_DN<4>")
	)
	(segment
		(start 276.065234 -276.41931)
		(end 275.214334 -276.41931)
		(width 0.16002)
		(layer "In6.Cu")
		(net "M_E_CPU0_SB_DQS_DN<4>")
	)
	(segment
		(start 296.457878 -277.658068)
		(end 294.507666 -277.658068)
		(width 0.16002)
		(layer "In6.Cu")
		(net "M_E_CPU0_SB_DQS_DN<4>")
	)
	(segment
		(start 276.470364 -276.82444)
		(end 276.065234 -276.41931)
		(width 0.16002)
		(layer "In6.Cu")
		(net "M_E_CPU0_SB_DQS_DN<4>")
	)
	(segment
		(start 324.589902 -270.77416)
		(end 324.299834 -270.484092)
		(width 0.09525)
		(layer "In6.Cu")
		(net "M_E_CPU0_SB_DQS_DN<4>")
	)
	(segment
		(start 296.947844 -277.168102)
		(end 296.457878 -277.658068)
		(width 0.16002)
		(layer "In6.Cu")
		(net "M_E_CPU0_SB_DQS_DN<4>")
	)
	(segment
		(start 299.067728 -276.80793)
		(end 298.679108 -276.41931)
		(width 0.16002)
		(layer "In6.Cu")
		(net "M_E_CPU0_SB_DQS_DN<4>")
	)
	(segment
		(start 324.004178 -270.484092)
		(end 323.944996 -270.42491)
		(width 0.09525)
		(layer "In6.Cu")
		(net "M_E_CPU0_SB_DQS_DN<4>")
	)
	(segment
		(start 301.404528 -276.80793)
		(end 299.067728 -276.80793)
		(width 0.16002)
		(layer "In6.Cu")
		(net "M_E_CPU0_SB_DQS_DN<4>")
	)
	(segment
		(start 283.67228 -276.48281)
		(end 283.028136 -276.48281)
		(width 0.16002)
		(layer "In6.Cu")
		(net "M_E_CPU0_SB_DQS_DN<4>")
	)
	(segment
		(start 297.728386 -276.84476)
		(end 296.947844 -277.168102)
		(width 0.16002)
		(layer "In6.Cu")
		(net "M_E_CPU0_SB_DQS_DN<4>")
	)
	(segment
		(start 278.17191 -276.82444)
		(end 276.470364 -276.82444)
		(width 0.16002)
		(layer "In6.Cu")
		(net "M_E_CPU0_SB_DQS_DN<4>")
	)
	(segment
		(start 326.517254 -271.84731)
		(end 325.444104 -270.77416)
		(width 0.09525)
		(layer "In6.Cu")
		(net "M_E_CPU0_SB_DQS_DN<4>")
	)
	(segment
		(start 330.72705 -271.921478)
		(end 330.626212 -271.948148)
		(width 0.09525)
		(layer "In6.Cu")
		(net "M_E_CPU0_SB_DQS_DN<4>")
	)
	(segment
		(start 293.657528 -276.80793)
		(end 291.5412 -276.80793)
		(width 0.16002)
		(layer "In6.Cu")
		(net "M_E_CPU0_SB_DQS_DN<4>")
	)
	(segment
		(start 290.571936 -276.48281)
		(end 290.06292 -276.991826)
		(width 0.16002)
		(layer "In6.Cu")
		(net "M_E_CPU0_SB_DQS_DN<4>")
	)
	(segment
		(start 291.21608 -276.48281)
		(end 290.571936 -276.48281)
		(width 0.16002)
		(layer "In6.Cu")
		(net "M_E_CPU0_SB_DQS_DN<4>")
	)
	(segment
		(start 282.367736 -277.14321)
		(end 281.859736 -277.14321)
		(width 0.16002)
		(layer "In6.Cu")
		(net "M_E_CPU0_SB_DQS_DN<4>")
	)
	(segment
		(start 312.24093 -270.42491)
		(end 309.742078 -272.923762)
		(width 0.16002)
		(layer "In6.Cu")
		(net "M_E_CPU0_SB_DQS_DN<4>")
	)
	(segment
		(start 330.880974 -271.656048)
		(end 330.72705 -271.921478)
		(width 0.09525)
		(layer "In6.Cu")
		(net "M_E_CPU0_SB_DQS_DN<4>")
	)
	(segment
		(start 281.344878 -277.658068)
		(end 280.184606 -277.658068)
		(width 0.16002)
		(layer "In6.Cu")
		(net "M_E_CPU0_SB_DQS_DN<4>")
	)
	(segment
		(start 309.742078 -272.923762)
		(end 309.358792 -273.849084)
		(width 0.16002)
		(layer "In6.Cu")
		(net "M_E_CPU0_SB_DQS_DN<4>")
	)
	(segment
		(start 287.141666 -277.658068)
		(end 286.291528 -276.80793)
		(width 0.16002)
		(layer "In6.Cu")
		(net "M_E_CPU0_SB_DQS_DN<4>")
	)
	(segment
		(start 324.299834 -270.484092)
		(end 324.004178 -270.484092)
		(width 0.09525)
		(layer "In6.Cu")
		(net "M_E_CPU0_SB_DQS_DN<4>")
	)
	(segment
		(start 283.9974 -276.80793)
		(end 283.67228 -276.48281)
		(width 0.16002)
		(layer "In6.Cu")
		(net "M_E_CPU0_SB_DQS_DN<4>")
	)
	(segment
		(start 281.859736 -277.14321)
		(end 281.344878 -277.658068)
		(width 0.16002)
		(layer "In6.Cu")
		(net "M_E_CPU0_SB_DQS_DN<4>")
	)
	(segment
		(start 298.679108 -276.41931)
		(end 298.153836 -276.41931)
		(width 0.16002)
		(layer "In6.Cu")
		(net "M_E_CPU0_SB_DQS_DN<4>")
	)
	(segment
		(start 280.184606 -277.658068)
		(end 278.17191 -276.82444)
		(width 0.16002)
		(layer "In6.Cu")
		(net "M_E_CPU0_SB_DQS_DN<4>")
	)
	(segment
		(start 298.153836 -276.41931)
		(end 297.728386 -276.84476)
		(width 0.16002)
		(layer "In6.Cu")
		(net "M_E_CPU0_SB_DQS_DN<4>")
	)
	(segment
		(start 288.93135 -277.658068)
		(end 287.141666 -277.658068)
		(width 0.16002)
		(layer "In6.Cu")
		(net "M_E_CPU0_SB_DQS_DN<4>")
	)
	(segment
		(start 290.06292 -276.991826)
		(end 289.268408 -277.32101)
		(width 0.16002)
		(layer "In6.Cu")
		(net "M_E_CPU0_SB_DQS_DN<4>")
	)
	(segment
		(start 323.895974 -270.42491)
		(end 312.24093 -270.42491)
		(width 0.16002)
		(layer "In6.Cu")
		(net "M_E_CPU0_SB_DQS_DN<4>")
	)
	(segment
		(start 323.944996 -270.42491)
		(end 323.921374 -270.42491)
		(width 0.09525)
		(layer "In6.Cu")
		(net "M_E_CPU0_SB_DQS_DN<4>")
	)
	(segment
		(start 325.444104 -270.77416)
		(end 324.589902 -270.77416)
		(width 0.09525)
		(layer "In6.Cu")
		(net "M_E_CPU0_SB_DQS_DN<4>")
	)
	(segment
		(start 289.268408 -277.32101)
		(end 288.93135 -277.658068)
		(width 0.16002)
		(layer "In6.Cu")
		(net "M_E_CPU0_SB_DQS_DN<4>")
	)
	(segment
		(start 273.36623 -276.659086)
		(end 273.092164 -276.38502)
		(width 0.16002)
		(layer "In6.Cu")
		(net "M_E_CPU0_SB_DQS_DN<4>")
	)
	(segment
		(start 274.974558 -276.659086)
		(end 273.36623 -276.659086)
		(width 0.16002)
		(layer "In6.Cu")
		(net "M_E_CPU0_SB_DQS_DN<4>")
	)
	(segment
		(start 304.859436 -277.28291)
		(end 301.879508 -277.28291)
		(width 0.16002)
		(layer "In6.Cu")
		(net "M_E_CPU0_SB_DQS_DN<4>")
	)
	(segment
		(start 294.507666 -277.658068)
		(end 293.657528 -276.80793)
		(width 0.16002)
		(layer "In6.Cu")
		(net "M_E_CPU0_SB_DQS_DN<4>")
	)
	(segment
		(start 305.672236 -276.47011)
		(end 304.859436 -277.28291)
		(width 0.16002)
		(layer "In6.Cu")
		(net "M_E_CPU0_SB_DQS_DN<4>")
	)
	(segment
		(start 286.291528 -276.80793)
		(end 283.9974 -276.80793)
		(width 0.16002)
		(layer "In6.Cu")
		(net "M_E_CPU0_SB_DQS_DN<4>")
	)
	(segment
		(start 323.921374 -270.42491)
		(end 323.895974 -270.42491)
		(width 0.1016)
		(layer "In6.Cu")
		(net "M_E_CPU0_SB_DQS_DN<4>")
	)
	(segment
		(start 330.129642 -271.981168)
		(end 330.12126 -271.985994)
		(width 0.09525)
		(layer "In6.Cu")
		(net "M_E_CPU0_SB_DQS_DN<4>")
	)
	(segment
		(start 327.88479 -271.988026)
		(end 327.872852 -271.981168)
		(width 0.09525)
		(layer "In6.Cu")
		(net "M_E_CPU0_SB_DQS_DN<4>")
	)
	(segment
		(start 283.028136 -276.48281)
		(end 282.367736 -277.14321)
		(width 0.16002)
		(layer "In6.Cu")
		(net "M_E_CPU0_SB_DQS_DN<4>")
	)
	(arc
		(start 330.626212 -271.948148)
		(mid 330.374071 -271.906578)
		(end 330.129642 -271.981168)
		(width 0.09525)
		(layer "In6.Cu")
		(net "M_E_CPU0_SB_DQS_DN<4>")
	)
	(arc
		(start 329.752452 -271.981168)
		(mid 329.47102 -271.905413)
		(end 329.189588 -271.981168)
		(width 0.09525)
		(layer "In6.Cu")
		(net "M_E_CPU0_SB_DQS_DN<4>")
	)
	(arc
		(start 329.189588 -271.981168)
		(mid 329.00112 -272.031845)
		(end 328.812652 -271.981168)
		(width 0.09525)
		(layer "In6.Cu")
		(net "M_E_CPU0_SB_DQS_DN<4>")
	)
	(arc
		(start 327.872852 -271.981168)
		(mid 327.6325 -271.881415)
		(end 327.374504 -271.84731)
		(width 0.09525)
		(layer "In6.Cu")
		(net "M_E_CPU0_SB_DQS_DN<4>")
	)
	(arc
		(start 328.249788 -271.981168)
		(mid 328.068172 -272.031905)
		(end 327.88479 -271.988026)
		(width 0.09525)
		(layer "In6.Cu")
		(net "M_E_CPU0_SB_DQS_DN<4>")
	)
	(arc
		(start 328.812652 -271.981168)
		(mid 328.53122 -271.905413)
		(end 328.249788 -271.981168)
		(width 0.09525)
		(layer "In6.Cu")
		(net "M_E_CPU0_SB_DQS_DN<4>")
	)
	(arc
		(start 330.12126 -271.985994)
		(mid 329.936228 -272.031908)
		(end 329.752452 -271.981168)
		(width 0.09525)
		(layer "In6.Cu")
		(net "M_E_CPU0_SB_DQS_DN<4>")
	)
	(segment
		(start 329.467972 -290.83)
		(end 329.00112 -291.095938)
		(width 0.12954)
		(layer "F.Cu")
		(net "M_E_CPU0_SB_DQS_DN<3>")
	)
	(segment
		(start 326.932036 -290.770818)
		(end 326.943974 -290.76396)
		(width 0.09525)
		(layer "In6.Cu")
		(net "M_E_CPU0_SB_DQS_DN<3>")
	)
	(segment
		(start 300.850808 -312.512202)
		(end 302.025558 -313.686952)
		(width 0.16002)
		(layer "In6.Cu")
		(net "M_E_CPU0_SB_DQS_DN<3>")
	)
	(segment
		(start 285.293816 -312.512202)
		(end 287.345882 -313.362086)
		(width 0.16002)
		(layer "In6.Cu")
		(net "M_E_CPU0_SB_DQS_DN<3>")
	)
	(segment
		(start 317.330582 -301.359316)
		(end 317.763144 -300.926754)
		(width 0.16002)
		(layer "In6.Cu")
		(net "M_E_CPU0_SB_DQS_DN<3>")
	)
	(segment
		(start 317.859156 -299.807884)
		(end 318.084962 -299.807884)
		(width 0.16002)
		(layer "In6.Cu")
		(net "M_E_CPU0_SB_DQS_DN<3>")
	)
	(segment
		(start 316.211966 -301.455074)
		(end 316.467998 -301.199042)
		(width 0.16002)
		(layer "In6.Cu")
		(net "M_E_CPU0_SB_DQS_DN<3>")
	)
	(segment
		(start 327.308972 -290.770818)
		(end 327.319386 -290.776914)
		(width 0.09525)
		(layer "In6.Cu")
		(net "M_E_CPU0_SB_DQS_DN<3>")
	)
	(segment
		(start 291.512498 -312.512202)
		(end 293.171118 -312.512202)
		(width 0.16002)
		(layer "In6.Cu")
		(net "M_E_CPU0_SB_DQS_DN<3>")
	)
	(segment
		(start 289.054286 -313.67857)
		(end 289.86353 -313.67857)
		(width 0.16002)
		(layer "In6.Cu")
		(net "M_E_CPU0_SB_DQS_DN<3>")
	)
	(segment
		(start 293.171118 -312.512202)
		(end 294.021002 -313.362086)
		(width 0.16002)
		(layer "In6.Cu")
		(net "M_E_CPU0_SB_DQS_DN<3>")
	)
	(segment
		(start 311.390538 -309.042054)
		(end 311.390538 -307.731414)
		(width 0.16002)
		(layer "In6.Cu")
		(net "M_E_CPU0_SB_DQS_DN<3>")
	)
	(segment
		(start 314.820808 -302.846232)
		(end 315.07684 -302.5902)
		(width 0.16002)
		(layer "In6.Cu")
		(net "M_E_CPU0_SB_DQS_DN<3>")
	)
	(segment
		(start 298.66463 -312.912252)
		(end 299.06468 -312.512202)
		(width 0.16002)
		(layer "In6.Cu")
		(net "M_E_CPU0_SB_DQS_DN<3>")
	)
	(segment
		(start 297.42003 -313.674252)
		(end 298.18203 -312.912252)
		(width 0.16002)
		(layer "In6.Cu")
		(net "M_E_CPU0_SB_DQS_DN<3>")
	)
	(segment
		(start 280.228548 -313.362086)
		(end 281.052016 -313.362086)
		(width 0.16002)
		(layer "In6.Cu")
		(net "M_E_CPU0_SB_DQS_DN<3>")
	)
	(segment
		(start 315.46292 -302.750474)
		(end 315.939424 -302.750474)
		(width 0.16002)
		(layer "In6.Cu")
		(net "M_E_CPU0_SB_DQS_DN<3>")
	)
	(segment
		(start 277.192232 -313.784996)
		(end 277.466044 -313.511184)
		(width 0.16002)
		(layer "In6.Cu")
		(net "M_E_CPU0_SB_DQS_DN<3>")
	)
	(segment
		(start 317.603124 -300.063916)
		(end 317.859156 -299.807884)
		(width 0.16002)
		(layer "In6.Cu")
		(net "M_E_CPU0_SB_DQS_DN<3>")
	)
	(segment
		(start 328.241406 -290.765992)
		(end 328.249788 -290.770818)
		(width 0.09525)
		(layer "In6.Cu")
		(net "M_E_CPU0_SB_DQS_DN<3>")
	)
	(segment
		(start 324.465696 -294.224202)
		(end 324.465696 -294.140382)
		(width 0.09525)
		(layer "In6.Cu")
		(net "M_E_CPU0_SB_DQS_DN<3>")
	)
	(segment
		(start 319.636394 -298.577)
		(end 320.112898 -298.577)
		(width 0.16002)
		(layer "In6.Cu")
		(net "M_E_CPU0_SB_DQS_DN<3>")
	)
	(segment
		(start 282.30576 -313.69254)
		(end 283.14523 -312.85307)
		(width 0.16002)
		(layer "In6.Cu")
		(net "M_E_CPU0_SB_DQS_DN<3>")
	)
	(segment
		(start 304.95113 -313.686952)
		(end 305.81473 -312.823352)
		(width 0.16002)
		(layer "In6.Cu")
		(net "M_E_CPU0_SB_DQS_DN<3>")
	)
	(segment
		(start 314.980828 -303.232566)
		(end 314.820808 -303.072292)
		(width 0.16002)
		(layer "In6.Cu")
		(net "M_E_CPU0_SB_DQS_DN<3>")
	)
	(segment
		(start 324.465696 -294.140382)
		(end 326.015604 -292.590474)
		(width 0.09525)
		(layer "In6.Cu")
		(net "M_E_CPU0_SB_DQS_DN<3>")
	)
	(segment
		(start 326.015604 -292.590474)
		(end 326.015604 -291.668708)
		(width 0.09525)
		(layer "In6.Cu")
		(net "M_E_CPU0_SB_DQS_DN<3>")
	)
	(segment
		(start 317.763144 -300.926754)
		(end 317.763144 -300.45025)
		(width 0.16002)
		(layer "In6.Cu")
		(net "M_E_CPU0_SB_DQS_DN<3>")
	)
	(segment
		(start 324.448932 -294.240966)
		(end 324.465696 -294.224202)
		(width 0.09525)
		(layer "In6.Cu")
		(net "M_E_CPU0_SB_DQS_DN<3>")
	)
	(segment
		(start 318.994282 -298.898818)
		(end 318.994282 -298.672758)
		(width 0.16002)
		(layer "In6.Cu")
		(net "M_E_CPU0_SB_DQS_DN<3>")
	)
	(segment
		(start 296.811446 -313.674252)
		(end 297.42003 -313.674252)
		(width 0.16002)
		(layer "In6.Cu")
		(net "M_E_CPU0_SB_DQS_DN<3>")
	)
	(segment
		(start 313.983878 -304.70602)
		(end 314.980828 -303.70907)
		(width 0.16002)
		(layer "In6.Cu")
		(net "M_E_CPU0_SB_DQS_DN<3>")
	)
	(segment
		(start 316.371986 -301.841408)
		(end 316.211966 -301.681134)
		(width 0.16002)
		(layer "In6.Cu")
		(net "M_E_CPU0_SB_DQS_DN<3>")
	)
	(segment
		(start 317.603124 -300.289976)
		(end 317.603124 -300.063916)
		(width 0.16002)
		(layer "In6.Cu")
		(net "M_E_CPU0_SB_DQS_DN<3>")
	)
	(segment
		(start 314.980828 -303.70907)
		(end 314.980828 -303.232566)
		(width 0.16002)
		(layer "In6.Cu")
		(net "M_E_CPU0_SB_DQS_DN<3>")
	)
	(segment
		(start 291.18433 -312.84037)
		(end 291.512498 -312.512202)
		(width 0.16002)
		(layer "In6.Cu")
		(net "M_E_CPU0_SB_DQS_DN<3>")
	)
	(segment
		(start 318.245236 -299.968158)
		(end 318.72174 -299.968158)
		(width 0.16002)
		(layer "In6.Cu")
		(net "M_E_CPU0_SB_DQS_DN<3>")
	)
	(segment
		(start 288.737802 -313.362086)
		(end 289.054286 -313.67857)
		(width 0.16002)
		(layer "In6.Cu")
		(net "M_E_CPU0_SB_DQS_DN<3>")
	)
	(segment
		(start 329.13193 -290.743894)
		(end 329.155044 -290.830508)
		(width 0.09525)
		(layer "In6.Cu")
		(net "M_E_CPU0_SB_DQS_DN<3>")
	)
	(segment
		(start 281.052016 -313.362086)
		(end 281.38247 -313.69254)
		(width 0.16002)
		(layer "In6.Cu")
		(net "M_E_CPU0_SB_DQS_DN<3>")
	)
	(segment
		(start 315.302646 -302.5902)
		(end 315.46292 -302.750474)
		(width 0.16002)
		(layer "In6.Cu")
		(net "M_E_CPU0_SB_DQS_DN<3>")
	)
	(segment
		(start 289.86353 -313.67857)
		(end 290.70173 -312.84037)
		(width 0.16002)
		(layer "In6.Cu")
		(net "M_E_CPU0_SB_DQS_DN<3>")
	)
	(segment
		(start 319.250314 -298.416726)
		(end 319.47612 -298.416726)
		(width 0.16002)
		(layer "In6.Cu")
		(net "M_E_CPU0_SB_DQS_DN<3>")
	)
	(segment
		(start 287.345882 -313.362086)
		(end 288.737802 -313.362086)
		(width 0.16002)
		(layer "In6.Cu")
		(net "M_E_CPU0_SB_DQS_DN<3>")
	)
	(segment
		(start 283.976826 -312.512202)
		(end 285.293816 -312.512202)
		(width 0.16002)
		(layer "In6.Cu")
		(net "M_E_CPU0_SB_DQS_DN<3>")
	)
	(segment
		(start 296.49928 -313.362086)
		(end 296.811446 -313.674252)
		(width 0.16002)
		(layer "In6.Cu")
		(net "M_E_CPU0_SB_DQS_DN<3>")
	)
	(segment
		(start 280.07945 -313.511184)
		(end 280.228548 -313.362086)
		(width 0.16002)
		(layer "In6.Cu")
		(net "M_E_CPU0_SB_DQS_DN<3>")
	)
	(segment
		(start 319.154302 -299.535596)
		(end 319.154302 -299.059092)
		(width 0.16002)
		(layer "In6.Cu")
		(net "M_E_CPU0_SB_DQS_DN<3>")
	)
	(segment
		(start 316.467998 -301.199042)
		(end 316.693804 -301.199042)
		(width 0.16002)
		(layer "In6.Cu")
		(net "M_E_CPU0_SB_DQS_DN<3>")
	)
	(segment
		(start 318.084962 -299.807884)
		(end 318.245236 -299.968158)
		(width 0.16002)
		(layer "In6.Cu")
		(net "M_E_CPU0_SB_DQS_DN<3>")
	)
	(segment
		(start 277.466044 -313.511184)
		(end 280.07945 -313.511184)
		(width 0.16002)
		(layer "In6.Cu")
		(net "M_E_CPU0_SB_DQS_DN<3>")
	)
	(segment
		(start 326.015604 -291.668708)
		(end 326.854312 -290.83)
		(width 0.09525)
		(layer "In6.Cu")
		(net "M_E_CPU0_SB_DQS_DN<3>")
	)
	(segment
		(start 316.371986 -302.317912)
		(end 316.371986 -301.841408)
		(width 0.16002)
		(layer "In6.Cu")
		(net "M_E_CPU0_SB_DQS_DN<3>")
	)
	(segment
		(start 311.390538 -307.731414)
		(end 313.983878 -305.138074)
		(width 0.16002)
		(layer "In6.Cu")
		(net "M_E_CPU0_SB_DQS_DN<3>")
	)
	(segment
		(start 329.155044 -290.830508)
		(end 329.00112 -291.095938)
		(width 0.09525)
		(layer "In6.Cu")
		(net "M_E_CPU0_SB_DQS_DN<3>")
	)
	(segment
		(start 290.70173 -312.84037)
		(end 291.18433 -312.84037)
		(width 0.16002)
		(layer "In6.Cu")
		(net "M_E_CPU0_SB_DQS_DN<3>")
	)
	(segment
		(start 318.72174 -299.968158)
		(end 319.154302 -299.535596)
		(width 0.16002)
		(layer "In6.Cu")
		(net "M_E_CPU0_SB_DQS_DN<3>")
	)
	(segment
		(start 318.994282 -298.672758)
		(end 319.250314 -298.416726)
		(width 0.16002)
		(layer "In6.Cu")
		(net "M_E_CPU0_SB_DQS_DN<3>")
	)
	(segment
		(start 307.60924 -312.823352)
		(end 311.390538 -309.042054)
		(width 0.16002)
		(layer "In6.Cu")
		(net "M_E_CPU0_SB_DQS_DN<3>")
	)
	(segment
		(start 316.854078 -301.359316)
		(end 317.330582 -301.359316)
		(width 0.16002)
		(layer "In6.Cu")
		(net "M_E_CPU0_SB_DQS_DN<3>")
	)
	(segment
		(start 317.763144 -300.45025)
		(end 317.603124 -300.289976)
		(width 0.16002)
		(layer "In6.Cu")
		(net "M_E_CPU0_SB_DQS_DN<3>")
	)
	(segment
		(start 316.693804 -301.199042)
		(end 316.854078 -301.359316)
		(width 0.16002)
		(layer "In6.Cu")
		(net "M_E_CPU0_SB_DQS_DN<3>")
	)
	(segment
		(start 320.112898 -298.577)
		(end 324.448932 -294.240966)
		(width 0.16002)
		(layer "In6.Cu")
		(net "M_E_CPU0_SB_DQS_DN<3>")
	)
	(segment
		(start 319.154302 -299.059092)
		(end 318.994282 -298.898818)
		(width 0.16002)
		(layer "In6.Cu")
		(net "M_E_CPU0_SB_DQS_DN<3>")
	)
	(segment
		(start 316.211966 -301.681134)
		(end 316.211966 -301.455074)
		(width 0.16002)
		(layer "In6.Cu")
		(net "M_E_CPU0_SB_DQS_DN<3>")
	)
	(segment
		(start 315.939424 -302.750474)
		(end 316.371986 -302.317912)
		(width 0.16002)
		(layer "In6.Cu")
		(net "M_E_CPU0_SB_DQS_DN<3>")
	)
	(segment
		(start 314.820808 -303.072292)
		(end 314.820808 -302.846232)
		(width 0.16002)
		(layer "In6.Cu")
		(net "M_E_CPU0_SB_DQS_DN<3>")
	)
	(segment
		(start 302.025558 -313.686952)
		(end 304.95113 -313.686952)
		(width 0.16002)
		(layer "In6.Cu")
		(net "M_E_CPU0_SB_DQS_DN<3>")
	)
	(segment
		(start 298.18203 -312.912252)
		(end 298.66463 -312.912252)
		(width 0.16002)
		(layer "In6.Cu")
		(net "M_E_CPU0_SB_DQS_DN<3>")
	)
	(segment
		(start 313.983878 -305.138074)
		(end 313.983878 -304.70602)
		(width 0.16002)
		(layer "In6.Cu")
		(net "M_E_CPU0_SB_DQS_DN<3>")
	)
	(segment
		(start 319.47612 -298.416726)
		(end 319.636394 -298.577)
		(width 0.16002)
		(layer "In6.Cu")
		(net "M_E_CPU0_SB_DQS_DN<3>")
	)
	(segment
		(start 294.021002 -313.362086)
		(end 296.49928 -313.362086)
		(width 0.16002)
		(layer "In6.Cu")
		(net "M_E_CPU0_SB_DQS_DN<3>")
	)
	(segment
		(start 299.06468 -312.512202)
		(end 300.850808 -312.512202)
		(width 0.16002)
		(layer "In6.Cu")
		(net "M_E_CPU0_SB_DQS_DN<3>")
	)
	(segment
		(start 281.38247 -313.69254)
		(end 282.30576 -313.69254)
		(width 0.16002)
		(layer "In6.Cu")
		(net "M_E_CPU0_SB_DQS_DN<3>")
	)
	(segment
		(start 283.635958 -312.85307)
		(end 283.976826 -312.512202)
		(width 0.16002)
		(layer "In6.Cu")
		(net "M_E_CPU0_SB_DQS_DN<3>")
	)
	(segment
		(start 283.14523 -312.85307)
		(end 283.635958 -312.85307)
		(width 0.16002)
		(layer "In6.Cu")
		(net "M_E_CPU0_SB_DQS_DN<3>")
	)
	(segment
		(start 315.07684 -302.5902)
		(end 315.302646 -302.5902)
		(width 0.16002)
		(layer "In6.Cu")
		(net "M_E_CPU0_SB_DQS_DN<3>")
	)
	(segment
		(start 305.81473 -312.823352)
		(end 307.60924 -312.823352)
		(width 0.16002)
		(layer "In6.Cu")
		(net "M_E_CPU0_SB_DQS_DN<3>")
	)
	(arc
		(start 326.943974 -290.76396)
		(mid 327.127355 -290.720129)
		(end 327.308972 -290.770818)
		(width 0.09525)
		(layer "In6.Cu")
		(net "M_E_CPU0_SB_DQS_DN<3>")
	)
	(arc
		(start 328.249788 -290.770818)
		(mid 328.53122 -290.846573)
		(end 328.812652 -290.770818)
		(width 0.09525)
		(layer "In6.Cu")
		(net "M_E_CPU0_SB_DQS_DN<3>")
	)
	(arc
		(start 326.854312 -290.83)
		(mid 326.891243 -290.797873)
		(end 326.932036 -290.770818)
		(width 0.09525)
		(layer "In6.Cu")
		(net "M_E_CPU0_SB_DQS_DN<3>")
	)
	(arc
		(start 327.319386 -290.776914)
		(mid 327.596548 -290.846714)
		(end 327.87209 -290.770818)
		(width 0.09525)
		(layer "In6.Cu")
		(net "M_E_CPU0_SB_DQS_DN<3>")
	)
	(arc
		(start 328.812652 -290.770818)
		(mid 328.969279 -290.721632)
		(end 329.13193 -290.743894)
		(width 0.09525)
		(layer "In6.Cu")
		(net "M_E_CPU0_SB_DQS_DN<3>")
	)
	(arc
		(start 327.87209 -290.770818)
		(mid 328.056119 -290.719919)
		(end 328.241406 -290.765992)
		(width 0.09525)
		(layer "In6.Cu")
		(net "M_E_CPU0_SB_DQS_DN<3>")
	)
	(segment
		(start 329.467972 -285.970218)
		(end 329.00112 -286.236156)
		(width 0.12954)
		(layer "F.Cu")
		(net "M_E_CPU0_SB_DQS_DN<2>")
	)
	(segment
		(start 286.791908 -304.41011)
		(end 286.664908 -304.28311)
		(width 0.16002)
		(layer "In6.Cu")
		(net "M_E_CPU0_SB_DQS_DN<2>")
	)
	(segment
		(start 283.134308 -303.57191)
		(end 282.372308 -304.33391)
		(width 0.16002)
		(layer "In6.Cu")
		(net "M_E_CPU0_SB_DQS_DN<2>")
	)
	(segment
		(start 319.465198 -289.745674)
		(end 319.465198 -289.971734)
		(width 0.16002)
		(layer "In6.Cu")
		(net "M_E_CPU0_SB_DQS_DN<2>")
	)
	(segment
		(start 301.78629 -304.288444)
		(end 301.30623 -304.288444)
		(width 0.16002)
		(layer "In6.Cu")
		(net "M_E_CPU0_SB_DQS_DN<2>")
	)
	(segment
		(start 304.190908 -304.352198)
		(end 303.964594 -304.578512)
		(width 0.16002)
		(layer "In6.Cu")
		(net "M_E_CPU0_SB_DQS_DN<2>")
	)
	(segment
		(start 281.686508 -304.33391)
		(end 281.36469 -304.012092)
		(width 0.16002)
		(layer "In6.Cu")
		(net "M_E_CPU0_SB_DQS_DN<2>")
	)
	(segment
		(start 304.95748 -304.352198)
		(end 304.190908 -304.352198)
		(width 0.16002)
		(layer "In6.Cu")
		(net "M_E_CPU0_SB_DQS_DN<2>")
	)
	(segment
		(start 316.98819 -292.222682)
		(end 316.682882 -292.52799)
		(width 0.16002)
		(layer "In6.Cu")
		(net "M_E_CPU0_SB_DQS_DN<2>")
	)
	(segment
		(start 302.511714 -304.171604)
		(end 301.90313 -304.171604)
		(width 0.16002)
		(layer "In6.Cu")
		(net "M_E_CPU0_SB_DQS_DN<2>")
	)
	(segment
		(start 327.872598 -285.91129)
		(end 327.855326 -285.921196)
		(width 0.09525)
		(layer "In6.Cu")
		(net "M_E_CPU0_SB_DQS_DN<2>")
	)
	(segment
		(start 329.00112 -286.236156)
		(end 329.155044 -285.970726)
		(width 0.09525)
		(layer "In6.Cu")
		(net "M_E_CPU0_SB_DQS_DN<2>")
	)
	(segment
		(start 316.683136 -293.130986)
		(end 316.200282 -293.61384)
		(width 0.16002)
		(layer "In6.Cu")
		(net "M_E_CPU0_SB_DQS_DN<2>")
	)
	(segment
		(start 287.892998 -304.012092)
		(end 287.49498 -304.41011)
		(width 0.16002)
		(layer "In6.Cu")
		(net "M_E_CPU0_SB_DQS_DN<2>")
	)
	(segment
		(start 301.18939 -304.171604)
		(end 300.70933 -304.171604)
		(width 0.16002)
		(layer "In6.Cu")
		(net "M_E_CPU0_SB_DQS_DN<2>")
	)
	(segment
		(start 326.651112 -285.986982)
		(end 325.868792 -285.986982)
		(width 0.09525)
		(layer "In6.Cu")
		(net "M_E_CPU0_SB_DQS_DN<2>")
	)
	(segment
		(start 300.70933 -304.171604)
		(end 300.355508 -303.817782)
		(width 0.16002)
		(layer "In6.Cu")
		(net "M_E_CPU0_SB_DQS_DN<2>")
	)
	(segment
		(start 324.115938 -286.69234)
		(end 323.773292 -286.69234)
		(width 0.16002)
		(layer "In6.Cu")
		(net "M_E_CPU0_SB_DQS_DN<2>")
	)
	(segment
		(start 281.36469 -304.012092)
		(end 280.171398 -304.012092)
		(width 0.16002)
		(layer "In6.Cu")
		(net "M_E_CPU0_SB_DQS_DN<2>")
	)
	(segment
		(start 300.355508 -303.817782)
		(end 300.355508 -303.322228)
		(width 0.16002)
		(layer "In6.Cu")
		(net "M_E_CPU0_SB_DQS_DN<2>")
	)
	(segment
		(start 316.682882 -292.52799)
		(end 316.682882 -292.75405)
		(width 0.16002)
		(layer "In6.Cu")
		(net "M_E_CPU0_SB_DQS_DN<2>")
	)
	(segment
		(start 303.964594 -304.578512)
		(end 302.918622 -304.578512)
		(width 0.16002)
		(layer "In6.Cu")
		(net "M_E_CPU0_SB_DQS_DN<2>")
	)
	(segment
		(start 319.465452 -290.34867)
		(end 318.982598 -290.831524)
		(width 0.16002)
		(layer "In6.Cu")
		(net "M_E_CPU0_SB_DQS_DN<2>")
	)
	(segment
		(start 298.67098 -303.577498)
		(end 298.18838 -303.577498)
		(width 0.16002)
		(layer "In6.Cu")
		(net "M_E_CPU0_SB_DQS_DN<2>")
	)
	(segment
		(start 329.155044 -285.970726)
		(end 329.13193 -285.884112)
		(width 0.09525)
		(layer "In6.Cu")
		(net "M_E_CPU0_SB_DQS_DN<2>")
	)
	(segment
		(start 309.858918 -299.82541)
		(end 308.961536 -301.991776)
		(width 0.16002)
		(layer "In6.Cu")
		(net "M_E_CPU0_SB_DQS_DN<2>")
	)
	(segment
		(start 299.08627 -303.162208)
		(end 298.67098 -303.577498)
		(width 0.16002)
		(layer "In6.Cu")
		(net "M_E_CPU0_SB_DQS_DN<2>")
	)
	(segment
		(start 314.91936 -294.764968)
		(end 309.858918 -299.82541)
		(width 0.16002)
		(layer "In6.Cu")
		(net "M_E_CPU0_SB_DQS_DN<2>")
	)
	(segment
		(start 290.68268 -303.53381)
		(end 289.80638 -304.41011)
		(width 0.16002)
		(layer "In6.Cu")
		(net "M_E_CPU0_SB_DQS_DN<2>")
	)
	(segment
		(start 307.464714 -303.488598)
		(end 305.82108 -303.488598)
		(width 0.16002)
		(layer "In6.Cu")
		(net "M_E_CPU0_SB_DQS_DN<2>")
	)
	(segment
		(start 297.42638 -304.339498)
		(end 296.805096 -304.339498)
		(width 0.16002)
		(layer "In6.Cu")
		(net "M_E_CPU0_SB_DQS_DN<2>")
	)
	(segment
		(start 308.961536 -301.991776)
		(end 307.464714 -303.488598)
		(width 0.16002)
		(layer "In6.Cu")
		(net "M_E_CPU0_SB_DQS_DN<2>")
	)
	(segment
		(start 285.031688 -303.162208)
		(end 283.993082 -303.162208)
		(width 0.16002)
		(layer "In6.Cu")
		(net "M_E_CPU0_SB_DQS_DN<2>")
	)
	(segment
		(start 301.30623 -304.288444)
		(end 301.18939 -304.171604)
		(width 0.16002)
		(layer "In6.Cu")
		(net "M_E_CPU0_SB_DQS_DN<2>")
	)
	(segment
		(start 289.80638 -304.41011)
		(end 288.773108 -304.41011)
		(width 0.16002)
		(layer "In6.Cu")
		(net "M_E_CPU0_SB_DQS_DN<2>")
	)
	(segment
		(start 318.379348 -290.831524)
		(end 318.07404 -291.136832)
		(width 0.16002)
		(layer "In6.Cu")
		(net "M_E_CPU0_SB_DQS_DN<2>")
	)
	(segment
		(start 318.07404 -291.136832)
		(end 318.07404 -291.362892)
		(width 0.16002)
		(layer "In6.Cu")
		(net "M_E_CPU0_SB_DQS_DN<2>")
	)
	(segment
		(start 285.191708 -303.802542)
		(end 285.191708 -303.322228)
		(width 0.16002)
		(layer "In6.Cu")
		(net "M_E_CPU0_SB_DQS_DN<2>")
	)
	(segment
		(start 305.82108 -303.488598)
		(end 304.95748 -304.352198)
		(width 0.16002)
		(layer "In6.Cu")
		(net "M_E_CPU0_SB_DQS_DN<2>")
	)
	(segment
		(start 296.47769 -304.012092)
		(end 295.470326 -304.012092)
		(width 0.16002)
		(layer "In6.Cu")
		(net "M_E_CPU0_SB_DQS_DN<2>")
	)
	(segment
		(start 318.07404 -291.362892)
		(end 318.074294 -291.739828)
		(width 0.16002)
		(layer "In6.Cu")
		(net "M_E_CPU0_SB_DQS_DN<2>")
	)
	(segment
		(start 315.597032 -293.61384)
		(end 315.25464 -293.956232)
		(width 0.16002)
		(layer "In6.Cu")
		(net "M_E_CPU0_SB_DQS_DN<2>")
	)
	(segment
		(start 293.649908 -304.33391)
		(end 293.188644 -303.872646)
		(width 0.16002)
		(layer "In6.Cu")
		(net "M_E_CPU0_SB_DQS_DN<2>")
	)
	(segment
		(start 300.355508 -303.322228)
		(end 300.195488 -303.162208)
		(width 0.16002)
		(layer "In6.Cu")
		(net "M_E_CPU0_SB_DQS_DN<2>")
	)
	(segment
		(start 291.21608 -303.53381)
		(end 290.68268 -303.53381)
		(width 0.16002)
		(layer "In6.Cu")
		(net "M_E_CPU0_SB_DQS_DN<2>")
	)
	(segment
		(start 285.191708 -303.322228)
		(end 285.031688 -303.162208)
		(width 0.16002)
		(layer "In6.Cu")
		(net "M_E_CPU0_SB_DQS_DN<2>")
	)
	(segment
		(start 287.49498 -304.41011)
		(end 286.791908 -304.41011)
		(width 0.16002)
		(layer "In6.Cu")
		(net "M_E_CPU0_SB_DQS_DN<2>")
	)
	(segment
		(start 300.195488 -303.162208)
		(end 299.08627 -303.162208)
		(width 0.16002)
		(layer "In6.Cu")
		(net "M_E_CPU0_SB_DQS_DN<2>")
	)
	(segment
		(start 283.993082 -303.162208)
		(end 283.58338 -303.57191)
		(width 0.16002)
		(layer "In6.Cu")
		(net "M_E_CPU0_SB_DQS_DN<2>")
	)
	(segment
		(start 327.886568 -285.903416)
		(end 327.872598 -285.91129)
		(width 0.09525)
		(layer "In6.Cu")
		(net "M_E_CPU0_SB_DQS_DN<2>")
	)
	(segment
		(start 317.59144 -292.222682)
		(end 316.98819 -292.222682)
		(width 0.16002)
		(layer "In6.Cu")
		(net "M_E_CPU0_SB_DQS_DN<2>")
	)
	(segment
		(start 319.867026 -289.343846)
		(end 319.465198 -289.745674)
		(width 0.16002)
		(layer "In6.Cu")
		(net "M_E_CPU0_SB_DQS_DN<2>")
	)
	(segment
		(start 319.465198 -289.971734)
		(end 319.465452 -290.34867)
		(width 0.16002)
		(layer "In6.Cu")
		(net "M_E_CPU0_SB_DQS_DN<2>")
	)
	(segment
		(start 282.372308 -304.33391)
		(end 281.686508 -304.33391)
		(width 0.16002)
		(layer "In6.Cu")
		(net "M_E_CPU0_SB_DQS_DN<2>")
	)
	(segment
		(start 327.309988 -285.911544)
		(end 327.299066 -285.905194)
		(width 0.09525)
		(layer "In6.Cu")
		(net "M_E_CPU0_SB_DQS_DN<2>")
	)
	(segment
		(start 280.171398 -304.012092)
		(end 279.77338 -304.41011)
		(width 0.16002)
		(layer "In6.Cu")
		(net "M_E_CPU0_SB_DQS_DN<2>")
	)
	(segment
		(start 318.074294 -291.739828)
		(end 317.59144 -292.222682)
		(width 0.16002)
		(layer "In6.Cu")
		(net "M_E_CPU0_SB_DQS_DN<2>")
	)
	(segment
		(start 324.13956 -286.69234)
		(end 324.115938 -286.69234)
		(width 0.09525)
		(layer "In6.Cu")
		(net "M_E_CPU0_SB_DQS_DN<2>")
	)
	(segment
		(start 325.222362 -286.633412)
		(end 324.198488 -286.633412)
		(width 0.09525)
		(layer "In6.Cu")
		(net "M_E_CPU0_SB_DQS_DN<2>")
	)
	(segment
		(start 283.58338 -303.57191)
		(end 283.134308 -303.57191)
		(width 0.16002)
		(layer "In6.Cu")
		(net "M_E_CPU0_SB_DQS_DN<2>")
	)
	(segment
		(start 318.982598 -290.831524)
		(end 318.379348 -290.831524)
		(width 0.16002)
		(layer "In6.Cu")
		(net "M_E_CPU0_SB_DQS_DN<2>")
	)
	(segment
		(start 286.664908 -304.28311)
		(end 285.672276 -304.28311)
		(width 0.16002)
		(layer "In6.Cu")
		(net "M_E_CPU0_SB_DQS_DN<2>")
	)
	(segment
		(start 295.148508 -304.33391)
		(end 293.649908 -304.33391)
		(width 0.16002)
		(layer "In6.Cu")
		(net "M_E_CPU0_SB_DQS_DN<2>")
	)
	(segment
		(start 279.77338 -304.41011)
		(end 278.959056 -304.41011)
		(width 0.16002)
		(layer "In6.Cu")
		(net "M_E_CPU0_SB_DQS_DN<2>")
	)
	(segment
		(start 324.198488 -286.633412)
		(end 324.13956 -286.69234)
		(width 0.09525)
		(layer "In6.Cu")
		(net "M_E_CPU0_SB_DQS_DN<2>")
	)
	(segment
		(start 277.466044 -304.16119)
		(end 277.192232 -304.435002)
		(width 0.16002)
		(layer "In6.Cu")
		(net "M_E_CPU0_SB_DQS_DN<2>")
	)
	(segment
		(start 288.773108 -304.41011)
		(end 288.37509 -304.012092)
		(width 0.16002)
		(layer "In6.Cu")
		(net "M_E_CPU0_SB_DQS_DN<2>")
	)
	(segment
		(start 295.470326 -304.012092)
		(end 295.148508 -304.33391)
		(width 0.16002)
		(layer "In6.Cu")
		(net "M_E_CPU0_SB_DQS_DN<2>")
	)
	(segment
		(start 323.773292 -286.69234)
		(end 321.121786 -289.343846)
		(width 0.16002)
		(layer "In6.Cu")
		(net "M_E_CPU0_SB_DQS_DN<2>")
	)
	(segment
		(start 315.25464 -293.956232)
		(end 314.91936 -294.764968)
		(width 0.16002)
		(layer "In6.Cu")
		(net "M_E_CPU0_SB_DQS_DN<2>")
	)
	(segment
		(start 325.868792 -285.986982)
		(end 325.222362 -286.633412)
		(width 0.09525)
		(layer "In6.Cu")
		(net "M_E_CPU0_SB_DQS_DN<2>")
	)
	(segment
		(start 316.200282 -293.61384)
		(end 315.597032 -293.61384)
		(width 0.16002)
		(layer "In6.Cu")
		(net "M_E_CPU0_SB_DQS_DN<2>")
	)
	(segment
		(start 296.805096 -304.339498)
		(end 296.47769 -304.012092)
		(width 0.16002)
		(layer "In6.Cu")
		(net "M_E_CPU0_SB_DQS_DN<2>")
	)
	(segment
		(start 291.587682 -303.162208)
		(end 291.21608 -303.53381)
		(width 0.16002)
		(layer "In6.Cu")
		(net "M_E_CPU0_SB_DQS_DN<2>")
	)
	(segment
		(start 278.710136 -304.16119)
		(end 277.466044 -304.16119)
		(width 0.16002)
		(layer "In6.Cu")
		(net "M_E_CPU0_SB_DQS_DN<2>")
	)
	(segment
		(start 285.672276 -304.28311)
		(end 285.191708 -303.802542)
		(width 0.16002)
		(layer "In6.Cu")
		(net "M_E_CPU0_SB_DQS_DN<2>")
	)
	(segment
		(start 292.917118 -303.162208)
		(end 291.587682 -303.162208)
		(width 0.16002)
		(layer "In6.Cu")
		(net "M_E_CPU0_SB_DQS_DN<2>")
	)
	(segment
		(start 298.18838 -303.577498)
		(end 297.42638 -304.339498)
		(width 0.16002)
		(layer "In6.Cu")
		(net "M_E_CPU0_SB_DQS_DN<2>")
	)
	(segment
		(start 278.959056 -304.41011)
		(end 278.710136 -304.16119)
		(width 0.16002)
		(layer "In6.Cu")
		(net "M_E_CPU0_SB_DQS_DN<2>")
	)
	(segment
		(start 321.121786 -289.343846)
		(end 319.867026 -289.343846)
		(width 0.16002)
		(layer "In6.Cu")
		(net "M_E_CPU0_SB_DQS_DN<2>")
	)
	(segment
		(start 316.682882 -292.75405)
		(end 316.683136 -293.130986)
		(width 0.16002)
		(layer "In6.Cu")
		(net "M_E_CPU0_SB_DQS_DN<2>")
	)
	(segment
		(start 293.188644 -303.872646)
		(end 293.188644 -303.433734)
		(width 0.16002)
		(layer "In6.Cu")
		(net "M_E_CPU0_SB_DQS_DN<2>")
	)
	(segment
		(start 301.90313 -304.171604)
		(end 301.78629 -304.288444)
		(width 0.16002)
		(layer "In6.Cu")
		(net "M_E_CPU0_SB_DQS_DN<2>")
	)
	(segment
		(start 288.37509 -304.012092)
		(end 287.892998 -304.012092)
		(width 0.16002)
		(layer "In6.Cu")
		(net "M_E_CPU0_SB_DQS_DN<2>")
	)
	(segment
		(start 293.188644 -303.433734)
		(end 292.917118 -303.162208)
		(width 0.16002)
		(layer "In6.Cu")
		(net "M_E_CPU0_SB_DQS_DN<2>")
	)
	(segment
		(start 302.918622 -304.578512)
		(end 302.511714 -304.171604)
		(width 0.16002)
		(layer "In6.Cu")
		(net "M_E_CPU0_SB_DQS_DN<2>")
	)
	(arc
		(start 327.855326 -285.921196)
		(mid 327.581417 -285.987117)
		(end 327.309988 -285.911544)
		(width 0.09525)
		(layer "In6.Cu")
		(net "M_E_CPU0_SB_DQS_DN<2>")
	)
	(arc
		(start 328.812652 -285.911036)
		(mid 328.53122 -285.986791)
		(end 328.249788 -285.911036)
		(width 0.09525)
		(layer "In6.Cu")
		(net "M_E_CPU0_SB_DQS_DN<2>")
	)
	(arc
		(start 328.249788 -285.911036)
		(mid 328.069165 -285.860441)
		(end 327.886568 -285.903416)
		(width 0.09525)
		(layer "In6.Cu")
		(net "M_E_CPU0_SB_DQS_DN<2>")
	)
	(arc
		(start 326.932544 -285.91129)
		(mid 326.796828 -285.967725)
		(end 326.651112 -285.986982)
		(width 0.09525)
		(layer "In6.Cu")
		(net "M_E_CPU0_SB_DQS_DN<2>")
	)
	(arc
		(start 327.299066 -285.905194)
		(mid 327.115012 -285.860571)
		(end 326.932544 -285.91129)
		(width 0.09525)
		(layer "In6.Cu")
		(net "M_E_CPU0_SB_DQS_DN<2>")
	)
	(arc
		(start 329.13193 -285.884112)
		(mid 328.969279 -285.861852)
		(end 328.812652 -285.911036)
		(width 0.09525)
		(layer "In6.Cu")
		(net "M_E_CPU0_SB_DQS_DN<2>")
	)
	(segment
		(start 329.467972 -281.110182)
		(end 329.00112 -281.37612)
		(width 0.12954)
		(layer "F.Cu")
		(net "M_E_CPU0_SB_DQS_DN<1>")
	)
	(segment
		(start 312.81878 -287.963864)
		(end 310.135778 -290.646866)
		(width 0.16002)
		(layer "In6.Cu")
		(net "M_E_CPU0_SB_DQS_DN<1>")
	)
	(segment
		(start 329.155044 -281.11069)
		(end 329.13193 -281.024076)
		(width 0.09525)
		(layer "In6.Cu")
		(net "M_E_CPU0_SB_DQS_DN<1>")
	)
	(segment
		(start 318.959484 -282.399232)
		(end 318.383412 -282.399232)
		(width 0.16002)
		(layer "In6.Cu")
		(net "M_E_CPU0_SB_DQS_DN<1>")
	)
	(segment
		(start 307.130196 -294.240204)
		(end 306.650136 -294.240204)
		(width 0.16002)
		(layer "In6.Cu")
		(net "M_E_CPU0_SB_DQS_DN<1>")
	)
	(segment
		(start 305.81473 -294.123364)
		(end 304.760884 -295.17721)
		(width 0.16002)
		(layer "In6.Cu")
		(net "M_E_CPU0_SB_DQS_DN<1>")
	)
	(segment
		(start 301.330868 -294.941498)
		(end 300.201584 -293.812214)
		(width 0.16002)
		(layer "In6.Cu")
		(net "M_E_CPU0_SB_DQS_DN<1>")
	)
	(segment
		(start 310.135778 -291.714682)
		(end 307.727096 -294.123364)
		(width 0.16002)
		(layer "In6.Cu")
		(net "M_E_CPU0_SB_DQS_DN<1>")
	)
	(segment
		(start 324.288912 -281.023822)
		(end 323.978524 -281.023822)
		(width 0.09525)
		(layer "In6.Cu")
		(net "M_E_CPU0_SB_DQS_DN<1>")
	)
	(segment
		(start 304.760884 -295.17721)
		(end 303.909476 -295.17721)
		(width 0.16002)
		(layer "In6.Cu")
		(net "M_E_CPU0_SB_DQS_DN<1>")
	)
	(segment
		(start 286.13735 -294.92067)
		(end 285.723838 -294.507158)
		(width 0.16002)
		(layer "In6.Cu")
		(net "M_E_CPU0_SB_DQS_DN<1>")
	)
	(segment
		(start 307.247036 -294.123364)
		(end 307.130196 -294.240204)
		(width 0.16002)
		(layer "In6.Cu")
		(net "M_E_CPU0_SB_DQS_DN<1>")
	)
	(segment
		(start 297.160188 -295.315386)
		(end 296.591228 -295.315386)
		(width 0.16002)
		(layer "In6.Cu")
		(net "M_E_CPU0_SB_DQS_DN<1>")
	)
	(segment
		(start 293.630604 -294.92067)
		(end 292.522148 -293.812214)
		(width 0.16002)
		(layer "In6.Cu")
		(net "M_E_CPU0_SB_DQS_DN<1>")
	)
	(segment
		(start 324.588632 -280.724102)
		(end 324.288912 -281.023822)
		(width 0.09525)
		(layer "In6.Cu")
		(net "M_E_CPU0_SB_DQS_DN<1>")
	)
	(segment
		(start 315.282326 -286.07639)
		(end 314.78601 -286.572706)
		(width 0.16002)
		(layer "In6.Cu")
		(net "M_E_CPU0_SB_DQS_DN<1>")
	)
	(segment
		(start 327.872598 -281.051)
		(end 327.862184 -281.057096)
		(width 0.09525)
		(layer "In6.Cu")
		(net "M_E_CPU0_SB_DQS_DN<1>")
	)
	(segment
		(start 323.978524 -281.023822)
		(end 323.919596 -281.08275)
		(width 0.09525)
		(layer "In6.Cu")
		(net "M_E_CPU0_SB_DQS_DN<1>")
	)
	(segment
		(start 318.064642 -282.718002)
		(end 318.064642 -283.294074)
		(width 0.16002)
		(layer "In6.Cu")
		(net "M_E_CPU0_SB_DQS_DN<1>")
	)
	(segment
		(start 288.906204 -295.022016)
		(end 288.546286 -294.662098)
		(width 0.16002)
		(layer "In6.Cu")
		(net "M_E_CPU0_SB_DQS_DN<1>")
	)
	(segment
		(start 316.177168 -285.181548)
		(end 315.601096 -285.181548)
		(width 0.16002)
		(layer "In6.Cu")
		(net "M_E_CPU0_SB_DQS_DN<1>")
	)
	(segment
		(start 316.673484 -284.10916)
		(end 316.673484 -284.685232)
		(width 0.16002)
		(layer "In6.Cu")
		(net "M_E_CPU0_SB_DQS_DN<1>")
	)
	(segment
		(start 288.546286 -294.662098)
		(end 287.744408 -294.662098)
		(width 0.16002)
		(layer "In6.Cu")
		(net "M_E_CPU0_SB_DQS_DN<1>")
	)
	(segment
		(start 300.201584 -293.812214)
		(end 299.06468 -293.812214)
		(width 0.16002)
		(layer "In6.Cu")
		(net "M_E_CPU0_SB_DQS_DN<1>")
	)
	(segment
		(start 283.128466 -294.17137)
		(end 282.328366 -294.97147)
		(width 0.16002)
		(layer "In6.Cu")
		(net "M_E_CPU0_SB_DQS_DN<1>")
	)
	(segment
		(start 314.209938 -286.572706)
		(end 313.891168 -286.891476)
		(width 0.16002)
		(layer "In6.Cu")
		(net "M_E_CPU0_SB_DQS_DN<1>")
	)
	(segment
		(start 279.928828 -295.04767)
		(end 279.234138 -295.04767)
		(width 0.16002)
		(layer "In6.Cu")
		(net "M_E_CPU0_SB_DQS_DN<1>")
	)
	(segment
		(start 315.601096 -285.181548)
		(end 315.282326 -285.500318)
		(width 0.16002)
		(layer "In6.Cu")
		(net "M_E_CPU0_SB_DQS_DN<1>")
	)
	(segment
		(start 318.383412 -282.399232)
		(end 318.064642 -282.718002)
		(width 0.16002)
		(layer "In6.Cu")
		(net "M_E_CPU0_SB_DQS_DN<1>")
	)
	(segment
		(start 295.150794 -294.662098)
		(end 294.892222 -294.92067)
		(width 0.16002)
		(layer "In6.Cu")
		(net "M_E_CPU0_SB_DQS_DN<1>")
	)
	(segment
		(start 317.568326 -283.79039)
		(end 316.992254 -283.79039)
		(width 0.16002)
		(layer "In6.Cu")
		(net "M_E_CPU0_SB_DQS_DN<1>")
	)
	(segment
		(start 295.93794 -294.662098)
		(end 295.150794 -294.662098)
		(width 0.16002)
		(layer "In6.Cu")
		(net "M_E_CPU0_SB_DQS_DN<1>")
	)
	(segment
		(start 329.00112 -281.37612)
		(end 329.155044 -281.11069)
		(width 0.09525)
		(layer "In6.Cu")
		(net "M_E_CPU0_SB_DQS_DN<1>")
	)
	(segment
		(start 319.699894 -281.08275)
		(end 319.4558 -281.326844)
		(width 0.16002)
		(layer "In6.Cu")
		(net "M_E_CPU0_SB_DQS_DN<1>")
	)
	(segment
		(start 291.619686 -293.812214)
		(end 291.26053 -294.17137)
		(width 0.16002)
		(layer "In6.Cu")
		(net "M_E_CPU0_SB_DQS_DN<1>")
	)
	(segment
		(start 296.591228 -295.315386)
		(end 295.93794 -294.662098)
		(width 0.16002)
		(layer "In6.Cu")
		(net "M_E_CPU0_SB_DQS_DN<1>")
	)
	(segment
		(start 285.520638 -293.812214)
		(end 283.974286 -293.812214)
		(width 0.16002)
		(layer "In6.Cu")
		(net "M_E_CPU0_SB_DQS_DN<1>")
	)
	(segment
		(start 283.974286 -293.812214)
		(end 283.61513 -294.17137)
		(width 0.16002)
		(layer "In6.Cu")
		(net "M_E_CPU0_SB_DQS_DN<1>")
	)
	(segment
		(start 307.727096 -294.123364)
		(end 307.247036 -294.123364)
		(width 0.16002)
		(layer "In6.Cu")
		(net "M_E_CPU0_SB_DQS_DN<1>")
	)
	(segment
		(start 279.234138 -295.04767)
		(end 278.997664 -294.811196)
		(width 0.16002)
		(layer "In6.Cu")
		(net "M_E_CPU0_SB_DQS_DN<1>")
	)
	(segment
		(start 319.4558 -281.902916)
		(end 318.959484 -282.399232)
		(width 0.16002)
		(layer "In6.Cu")
		(net "M_E_CPU0_SB_DQS_DN<1>")
	)
	(segment
		(start 298.26331 -294.212264)
		(end 297.160188 -295.315386)
		(width 0.16002)
		(layer "In6.Cu")
		(net "M_E_CPU0_SB_DQS_DN<1>")
	)
	(segment
		(start 306.533296 -294.123364)
		(end 305.81473 -294.123364)
		(width 0.16002)
		(layer "In6.Cu")
		(net "M_E_CPU0_SB_DQS_DN<1>")
	)
	(segment
		(start 315.282326 -285.500318)
		(end 315.282326 -286.07639)
		(width 0.16002)
		(layer "In6.Cu")
		(net "M_E_CPU0_SB_DQS_DN<1>")
	)
	(segment
		(start 327.309988 -281.051)
		(end 327.301606 -281.046174)
		(width 0.09525)
		(layer "In6.Cu")
		(net "M_E_CPU0_SB_DQS_DN<1>")
	)
	(segment
		(start 316.992254 -283.79039)
		(end 316.673484 -284.10916)
		(width 0.16002)
		(layer "In6.Cu")
		(net "M_E_CPU0_SB_DQS_DN<1>")
	)
	(segment
		(start 313.891168 -287.467548)
		(end 313.394852 -287.963864)
		(width 0.16002)
		(layer "In6.Cu")
		(net "M_E_CPU0_SB_DQS_DN<1>")
	)
	(segment
		(start 301.972218 -294.941498)
		(end 301.330868 -294.941498)
		(width 0.16002)
		(layer "In6.Cu")
		(net "M_E_CPU0_SB_DQS_DN<1>")
	)
	(segment
		(start 298.66463 -294.212264)
		(end 298.26331 -294.212264)
		(width 0.16002)
		(layer "In6.Cu")
		(net "M_E_CPU0_SB_DQS_DN<1>")
	)
	(segment
		(start 280.3144 -294.662098)
		(end 279.928828 -295.04767)
		(width 0.16002)
		(layer "In6.Cu")
		(net "M_E_CPU0_SB_DQS_DN<1>")
	)
	(segment
		(start 281.39136 -294.662098)
		(end 280.3144 -294.662098)
		(width 0.16002)
		(layer "In6.Cu")
		(net "M_E_CPU0_SB_DQS_DN<1>")
	)
	(segment
		(start 313.394852 -287.963864)
		(end 312.81878 -287.963864)
		(width 0.16002)
		(layer "In6.Cu")
		(net "M_E_CPU0_SB_DQS_DN<1>")
	)
	(segment
		(start 287.485836 -294.92067)
		(end 286.13735 -294.92067)
		(width 0.16002)
		(layer "In6.Cu")
		(net "M_E_CPU0_SB_DQS_DN<1>")
	)
	(segment
		(start 299.06468 -293.812214)
		(end 298.66463 -294.212264)
		(width 0.16002)
		(layer "In6.Cu")
		(net "M_E_CPU0_SB_DQS_DN<1>")
	)
	(segment
		(start 303.909476 -295.17721)
		(end 303.145698 -294.413432)
		(width 0.16002)
		(layer "In6.Cu")
		(net "M_E_CPU0_SB_DQS_DN<1>")
	)
	(segment
		(start 277.466044 -294.811196)
		(end 277.192232 -295.085008)
		(width 0.16002)
		(layer "In6.Cu")
		(net "M_E_CPU0_SB_DQS_DN<1>")
	)
	(segment
		(start 285.723838 -294.507158)
		(end 285.723838 -294.015414)
		(width 0.16002)
		(layer "In6.Cu")
		(net "M_E_CPU0_SB_DQS_DN<1>")
	)
	(segment
		(start 323.919596 -281.08275)
		(end 323.895974 -281.08275)
		(width 0.09525)
		(layer "In6.Cu")
		(net "M_E_CPU0_SB_DQS_DN<1>")
	)
	(segment
		(start 327.88098 -281.046174)
		(end 327.872598 -281.051)
		(width 0.09525)
		(layer "In6.Cu")
		(net "M_E_CPU0_SB_DQS_DN<1>")
	)
	(segment
		(start 283.61513 -294.17137)
		(end 283.128466 -294.17137)
		(width 0.16002)
		(layer "In6.Cu")
		(net "M_E_CPU0_SB_DQS_DN<1>")
	)
	(segment
		(start 310.135778 -290.646866)
		(end 310.135778 -291.714682)
		(width 0.16002)
		(layer "In6.Cu")
		(net "M_E_CPU0_SB_DQS_DN<1>")
	)
	(segment
		(start 314.78601 -286.572706)
		(end 314.209938 -286.572706)
		(width 0.16002)
		(layer "In6.Cu")
		(net "M_E_CPU0_SB_DQS_DN<1>")
	)
	(segment
		(start 294.892222 -294.92067)
		(end 293.630604 -294.92067)
		(width 0.16002)
		(layer "In6.Cu")
		(net "M_E_CPU0_SB_DQS_DN<1>")
	)
	(segment
		(start 326.254872 -280.962354)
		(end 326.01662 -280.724102)
		(width 0.09525)
		(layer "In6.Cu")
		(net "M_E_CPU0_SB_DQS_DN<1>")
	)
	(segment
		(start 326.384666 -281.059636)
		(end 326.369934 -281.051)
		(width 0.09525)
		(layer "In6.Cu")
		(net "M_E_CPU0_SB_DQS_DN<1>")
	)
	(segment
		(start 303.145698 -294.413432)
		(end 302.500284 -294.413432)
		(width 0.16002)
		(layer "In6.Cu")
		(net "M_E_CPU0_SB_DQS_DN<1>")
	)
	(segment
		(start 282.328366 -294.97147)
		(end 281.700732 -294.97147)
		(width 0.16002)
		(layer "In6.Cu")
		(net "M_E_CPU0_SB_DQS_DN<1>")
	)
	(segment
		(start 287.744408 -294.662098)
		(end 287.485836 -294.92067)
		(width 0.16002)
		(layer "In6.Cu")
		(net "M_E_CPU0_SB_DQS_DN<1>")
	)
	(segment
		(start 285.723838 -294.015414)
		(end 285.520638 -293.812214)
		(width 0.16002)
		(layer "In6.Cu")
		(net "M_E_CPU0_SB_DQS_DN<1>")
	)
	(segment
		(start 318.064642 -283.294074)
		(end 317.568326 -283.79039)
		(width 0.16002)
		(layer "In6.Cu")
		(net "M_E_CPU0_SB_DQS_DN<1>")
	)
	(segment
		(start 316.673484 -284.685232)
		(end 316.177168 -285.181548)
		(width 0.16002)
		(layer "In6.Cu")
		(net "M_E_CPU0_SB_DQS_DN<1>")
	)
	(segment
		(start 319.4558 -281.326844)
		(end 319.4558 -281.902916)
		(width 0.16002)
		(layer "In6.Cu")
		(net "M_E_CPU0_SB_DQS_DN<1>")
	)
	(segment
		(start 291.26053 -294.17137)
		(end 290.67633 -294.17137)
		(width 0.16002)
		(layer "In6.Cu")
		(net "M_E_CPU0_SB_DQS_DN<1>")
	)
	(segment
		(start 292.522148 -293.812214)
		(end 291.619686 -293.812214)
		(width 0.16002)
		(layer "In6.Cu")
		(net "M_E_CPU0_SB_DQS_DN<1>")
	)
	(segment
		(start 326.01662 -280.724102)
		(end 324.588632 -280.724102)
		(width 0.09525)
		(layer "In6.Cu")
		(net "M_E_CPU0_SB_DQS_DN<1>")
	)
	(segment
		(start 278.997664 -294.811196)
		(end 277.466044 -294.811196)
		(width 0.16002)
		(layer "In6.Cu")
		(net "M_E_CPU0_SB_DQS_DN<1>")
	)
	(segment
		(start 289.825684 -295.022016)
		(end 288.906204 -295.022016)
		(width 0.16002)
		(layer "In6.Cu")
		(net "M_E_CPU0_SB_DQS_DN<1>")
	)
	(segment
		(start 306.650136 -294.240204)
		(end 306.533296 -294.123364)
		(width 0.16002)
		(layer "In6.Cu")
		(net "M_E_CPU0_SB_DQS_DN<1>")
	)
	(segment
		(start 281.700732 -294.97147)
		(end 281.39136 -294.662098)
		(width 0.16002)
		(layer "In6.Cu")
		(net "M_E_CPU0_SB_DQS_DN<1>")
	)
	(segment
		(start 290.67633 -294.17137)
		(end 289.825684 -295.022016)
		(width 0.16002)
		(layer "In6.Cu")
		(net "M_E_CPU0_SB_DQS_DN<1>")
	)
	(segment
		(start 323.895974 -281.08275)
		(end 319.699894 -281.08275)
		(width 0.16002)
		(layer "In6.Cu")
		(net "M_E_CPU0_SB_DQS_DN<1>")
	)
	(segment
		(start 313.891168 -286.891476)
		(end 313.891168 -287.467548)
		(width 0.16002)
		(layer "In6.Cu")
		(net "M_E_CPU0_SB_DQS_DN<1>")
	)
	(segment
		(start 302.500284 -294.413432)
		(end 301.972218 -294.941498)
		(width 0.16002)
		(layer "In6.Cu")
		(net "M_E_CPU0_SB_DQS_DN<1>")
	)
	(arc
		(start 327.862184 -281.057096)
		(mid 327.585276 -281.126773)
		(end 327.309988 -281.051)
		(width 0.09525)
		(layer "In6.Cu")
		(net "M_E_CPU0_SB_DQS_DN<1>")
	)
	(arc
		(start 326.369934 -281.051)
		(mid 326.309519 -281.01042)
		(end 326.254872 -280.962354)
		(width 0.09525)
		(layer "In6.Cu")
		(net "M_E_CPU0_SB_DQS_DN<1>")
	)
	(arc
		(start 326.932798 -281.051)
		(mid 326.65987 -281.126814)
		(end 326.384666 -281.059636)
		(width 0.09525)
		(layer "In6.Cu")
		(net "M_E_CPU0_SB_DQS_DN<1>")
	)
	(arc
		(start 328.812652 -281.051)
		(mid 328.53122 -281.126755)
		(end 328.249788 -281.051)
		(width 0.09525)
		(layer "In6.Cu")
		(net "M_E_CPU0_SB_DQS_DN<1>")
	)
	(arc
		(start 328.249788 -281.051)
		(mid 328.066013 -281.000228)
		(end 327.88098 -281.046174)
		(width 0.09525)
		(layer "In6.Cu")
		(net "M_E_CPU0_SB_DQS_DN<1>")
	)
	(arc
		(start 327.301606 -281.046174)
		(mid 327.116574 -281.00026)
		(end 326.932798 -281.051)
		(width 0.09525)
		(layer "In6.Cu")
		(net "M_E_CPU0_SB_DQS_DN<1>")
	)
	(arc
		(start 329.13193 -281.024076)
		(mid 328.969279 -281.001816)
		(end 328.812652 -281.051)
		(width 0.09525)
		(layer "In6.Cu")
		(net "M_E_CPU0_SB_DQS_DN<1>")
	)
	(segment
		(start 329.467972 -276.250146)
		(end 329.00112 -276.516084)
		(width 0.12954)
		(layer "F.Cu")
		(net "M_E_CPU0_SB_DQS_DN<0>")
	)
	(segment
		(start 314.591192 -277.826978)
		(end 314.591192 -277.350474)
		(width 0.16002)
		(layer "In6.Cu")
		(net "M_E_CPU0_SB_DQS_DN<0>")
	)
	(segment
		(start 329.155044 -276.250654)
		(end 329.00112 -276.516084)
		(width 0.09525)
		(layer "In6.Cu")
		(net "M_E_CPU0_SB_DQS_DN<0>")
	)
	(segment
		(start 314.591192 -277.350474)
		(end 314.338716 -277.097998)
		(width 0.16002)
		(layer "In6.Cu")
		(net "M_E_CPU0_SB_DQS_DN<0>")
	)
	(segment
		(start 296.780458 -285.62427)
		(end 297.42003 -285.62427)
		(width 0.16002)
		(layer "In6.Cu")
		(net "M_E_CPU0_SB_DQS_DN<0>")
	)
	(segment
		(start 278.47925 -285.461202)
		(end 278.628348 -285.312104)
		(width 0.16002)
		(layer "In6.Cu")
		(net "M_E_CPU0_SB_DQS_DN<0>")
	)
	(segment
		(start 324.06844 -275.45919)
		(end 324.127368 -275.400262)
		(width 0.09525)
		(layer "In6.Cu")
		(net "M_E_CPU0_SB_DQS_DN<0>")
	)
	(segment
		(start 312.29046 -279.651206)
		(end 312.766964 -279.651206)
		(width 0.16002)
		(layer "In6.Cu")
		(net "M_E_CPU0_SB_DQS_DN<0>")
	)
	(segment
		(start 283.217366 -284.764734)
		(end 283.657294 -284.764734)
		(width 0.16002)
		(layer "In6.Cu")
		(net "M_E_CPU0_SB_DQS_DN<0>")
	)
	(segment
		(start 291.154358 -284.86227)
		(end 291.554408 -284.46222)
		(width 0.16002)
		(layer "In6.Cu")
		(net "M_E_CPU0_SB_DQS_DN<0>")
	)
	(segment
		(start 289.262058 -285.64967)
		(end 289.858958 -285.64967)
		(width 0.16002)
		(layer "In6.Cu")
		(net "M_E_CPU0_SB_DQS_DN<0>")
	)
	(segment
		(start 289.858958 -285.64967)
		(end 290.646358 -284.86227)
		(width 0.16002)
		(layer "In6.Cu")
		(net "M_E_CPU0_SB_DQS_DN<0>")
	)
	(segment
		(start 329.13193 -276.16404)
		(end 329.155044 -276.250654)
		(width 0.09525)
		(layer "In6.Cu")
		(net "M_E_CPU0_SB_DQS_DN<0>")
	)
	(segment
		(start 313.681618 -278.260048)
		(end 314.158122 -278.260048)
		(width 0.16002)
		(layer "In6.Cu")
		(net "M_E_CPU0_SB_DQS_DN<0>")
	)
	(segment
		(start 281.692604 -285.62427)
		(end 282.35783 -285.62427)
		(width 0.16002)
		(layer "In6.Cu")
		(net "M_E_CPU0_SB_DQS_DN<0>")
	)
	(segment
		(start 314.158122 -278.260048)
		(end 314.591192 -277.826978)
		(width 0.16002)
		(layer "In6.Cu")
		(net "M_E_CPU0_SB_DQS_DN<0>")
	)
	(segment
		(start 315.009784 -275.45919)
		(end 315.245242 -275.45919)
		(width 0.16002)
		(layer "In6.Cu")
		(net "M_E_CPU0_SB_DQS_DN<0>")
	)
	(segment
		(start 292.646608 -284.46222)
		(end 293.496492 -285.312104)
		(width 0.16002)
		(layer "In6.Cu")
		(net "M_E_CPU0_SB_DQS_DN<0>")
	)
	(segment
		(start 312.947558 -278.489156)
		(end 312.947558 -278.263096)
		(width 0.16002)
		(layer "In6.Cu")
		(net "M_E_CPU0_SB_DQS_DN<0>")
	)
	(segment
		(start 314.684918 -276.525736)
		(end 314.684918 -275.784056)
		(width 0.16002)
		(layer "In6.Cu")
		(net "M_E_CPU0_SB_DQS_DN<0>")
	)
	(segment
		(start 311.500266 -280.063194)
		(end 311.500266 -279.710388)
		(width 0.16002)
		(layer "In6.Cu")
		(net "M_E_CPU0_SB_DQS_DN<0>")
	)
	(segment
		(start 283.959808 -284.46222)
		(end 285.052008 -284.46222)
		(width 0.16002)
		(layer "In6.Cu")
		(net "M_E_CPU0_SB_DQS_DN<0>")
	)
	(segment
		(start 300.175168 -284.46222)
		(end 301.121318 -285.40837)
		(width 0.16002)
		(layer "In6.Cu")
		(net "M_E_CPU0_SB_DQS_DN<0>")
	)
	(segment
		(start 314.684918 -275.784056)
		(end 315.009784 -275.45919)
		(width 0.16002)
		(layer "In6.Cu")
		(net "M_E_CPU0_SB_DQS_DN<0>")
	)
	(segment
		(start 291.554408 -284.46222)
		(end 292.646608 -284.46222)
		(width 0.16002)
		(layer "In6.Cu")
		(net "M_E_CPU0_SB_DQS_DN<0>")
	)
	(segment
		(start 277.466044 -285.461202)
		(end 278.47925 -285.461202)
		(width 0.16002)
		(layer "In6.Cu")
		(net "M_E_CPU0_SB_DQS_DN<0>")
	)
	(segment
		(start 305.81473 -284.77337)
		(end 307.029104 -284.77337)
		(width 0.16002)
		(layer "In6.Cu")
		(net "M_E_CPU0_SB_DQS_DN<0>")
	)
	(segment
		(start 301.121318 -285.40837)
		(end 302.617886 -285.40837)
		(width 0.16002)
		(layer "In6.Cu")
		(net "M_E_CPU0_SB_DQS_DN<0>")
	)
	(segment
		(start 285.901892 -285.312104)
		(end 288.924492 -285.312104)
		(width 0.16002)
		(layer "In6.Cu")
		(net "M_E_CPU0_SB_DQS_DN<0>")
	)
	(segment
		(start 285.052008 -284.46222)
		(end 285.901892 -285.312104)
		(width 0.16002)
		(layer "In6.Cu")
		(net "M_E_CPU0_SB_DQS_DN<0>")
	)
	(segment
		(start 315.405262 -276.210014)
		(end 315.74232 -276.547072)
		(width 0.16002)
		(layer "In6.Cu")
		(net "M_E_CPU0_SB_DQS_DN<0>")
	)
	(segment
		(start 310.446928 -282.319984)
		(end 310.446928 -281.116532)
		(width 0.16002)
		(layer "In6.Cu")
		(net "M_E_CPU0_SB_DQS_DN<0>")
	)
	(segment
		(start 307.029104 -284.77337)
		(end 308.675532 -284.09138)
		(width 0.16002)
		(layer "In6.Cu")
		(net "M_E_CPU0_SB_DQS_DN<0>")
	)
	(segment
		(start 290.646358 -284.86227)
		(end 291.154358 -284.86227)
		(width 0.16002)
		(layer "In6.Cu")
		(net "M_E_CPU0_SB_DQS_DN<0>")
	)
	(segment
		(start 279.314148 -285.312104)
		(end 279.430988 -285.428944)
		(width 0.16002)
		(layer "In6.Cu")
		(net "M_E_CPU0_SB_DQS_DN<0>")
	)
	(segment
		(start 282.35783 -285.62427)
		(end 283.217366 -284.764734)
		(width 0.16002)
		(layer "In6.Cu")
		(net "M_E_CPU0_SB_DQS_DN<0>")
	)
	(segment
		(start 279.430988 -285.428944)
		(end 279.911048 -285.428944)
		(width 0.16002)
		(layer "In6.Cu")
		(net "M_E_CPU0_SB_DQS_DN<0>")
	)
	(segment
		(start 304.57013 -286.01797)
		(end 305.81473 -284.77337)
		(width 0.16002)
		(layer "In6.Cu")
		(net "M_E_CPU0_SB_DQS_DN<0>")
	)
	(segment
		(start 297.42003 -285.62427)
		(end 298.18203 -284.86227)
		(width 0.16002)
		(layer "In6.Cu")
		(net "M_E_CPU0_SB_DQS_DN<0>")
	)
	(segment
		(start 315.405262 -275.61921)
		(end 315.405262 -276.210014)
		(width 0.16002)
		(layer "In6.Cu")
		(net "M_E_CPU0_SB_DQS_DN<0>")
	)
	(segment
		(start 310.446928 -281.116532)
		(end 311.500266 -280.063194)
		(width 0.16002)
		(layer "In6.Cu")
		(net "M_E_CPU0_SB_DQS_DN<0>")
	)
	(segment
		(start 314.338716 -277.097998)
		(end 314.338716 -276.871938)
		(width 0.16002)
		(layer "In6.Cu")
		(net "M_E_CPU0_SB_DQS_DN<0>")
	)
	(segment
		(start 316.353444 -276.547072)
		(end 316.690502 -276.210014)
		(width 0.16002)
		(layer "In6.Cu")
		(net "M_E_CPU0_SB_DQS_DN<0>")
	)
	(segment
		(start 298.18203 -284.86227)
		(end 298.66463 -284.86227)
		(width 0.16002)
		(layer "In6.Cu")
		(net "M_E_CPU0_SB_DQS_DN<0>")
	)
	(segment
		(start 278.628348 -285.312104)
		(end 279.314148 -285.312104)
		(width 0.16002)
		(layer "In6.Cu")
		(net "M_E_CPU0_SB_DQS_DN<0>")
	)
	(segment
		(start 316.690502 -275.61921)
		(end 316.850522 -275.45919)
		(width 0.16002)
		(layer "In6.Cu")
		(net "M_E_CPU0_SB_DQS_DN<0>")
	)
	(segment
		(start 313.429142 -278.007572)
		(end 313.681618 -278.260048)
		(width 0.16002)
		(layer "In6.Cu")
		(net "M_E_CPU0_SB_DQS_DN<0>")
	)
	(segment
		(start 327.872598 -276.190964)
		(end 327.88098 -276.186138)
		(width 0.09525)
		(layer "In6.Cu")
		(net "M_E_CPU0_SB_DQS_DN<0>")
	)
	(segment
		(start 296.468292 -285.312104)
		(end 296.780458 -285.62427)
		(width 0.16002)
		(layer "In6.Cu")
		(net "M_E_CPU0_SB_DQS_DN<0>")
	)
	(segment
		(start 312.037984 -279.39873)
		(end 312.29046 -279.651206)
		(width 0.16002)
		(layer "In6.Cu")
		(net "M_E_CPU0_SB_DQS_DN<0>")
	)
	(segment
		(start 324.127368 -275.400262)
		(end 325.09333 -275.400262)
		(width 0.09525)
		(layer "In6.Cu")
		(net "M_E_CPU0_SB_DQS_DN<0>")
	)
	(segment
		(start 324.044818 -275.45919)
		(end 324.06844 -275.45919)
		(width 0.09525)
		(layer "In6.Cu")
		(net "M_E_CPU0_SB_DQS_DN<0>")
	)
	(segment
		(start 299.06468 -284.46222)
		(end 300.175168 -284.46222)
		(width 0.16002)
		(layer "In6.Cu")
		(net "M_E_CPU0_SB_DQS_DN<0>")
	)
	(segment
		(start 298.66463 -284.86227)
		(end 299.06468 -284.46222)
		(width 0.16002)
		(layer "In6.Cu")
		(net "M_E_CPU0_SB_DQS_DN<0>")
	)
	(segment
		(start 288.924492 -285.312104)
		(end 289.262058 -285.64967)
		(width 0.16002)
		(layer "In6.Cu")
		(net "M_E_CPU0_SB_DQS_DN<0>")
	)
	(segment
		(start 313.200034 -279.218136)
		(end 313.200034 -278.741632)
		(width 0.16002)
		(layer "In6.Cu")
		(net "M_E_CPU0_SB_DQS_DN<0>")
	)
	(segment
		(start 315.74232 -276.547072)
		(end 316.353444 -276.547072)
		(width 0.16002)
		(layer "In6.Cu")
		(net "M_E_CPU0_SB_DQS_DN<0>")
	)
	(segment
		(start 280.027888 -285.312104)
		(end 281.380438 -285.312104)
		(width 0.16002)
		(layer "In6.Cu")
		(net "M_E_CPU0_SB_DQS_DN<0>")
	)
	(segment
		(start 303.227486 -286.01797)
		(end 304.57013 -286.01797)
		(width 0.16002)
		(layer "In6.Cu")
		(net "M_E_CPU0_SB_DQS_DN<0>")
	)
	(segment
		(start 325.09333 -275.400262)
		(end 325.959724 -276.266656)
		(width 0.09525)
		(layer "In6.Cu")
		(net "M_E_CPU0_SB_DQS_DN<0>")
	)
	(segment
		(start 279.911048 -285.428944)
		(end 280.027888 -285.312104)
		(width 0.16002)
		(layer "In6.Cu")
		(net "M_E_CPU0_SB_DQS_DN<0>")
	)
	(segment
		(start 315.245242 -275.45919)
		(end 315.405262 -275.61921)
		(width 0.16002)
		(layer "In6.Cu")
		(net "M_E_CPU0_SB_DQS_DN<0>")
	)
	(segment
		(start 311.811924 -279.39873)
		(end 312.037984 -279.39873)
		(width 0.16002)
		(layer "In6.Cu")
		(net "M_E_CPU0_SB_DQS_DN<0>")
	)
	(segment
		(start 325.959724 -276.266656)
		(end 327.59142 -276.266656)
		(width 0.09525)
		(layer "In6.Cu")
		(net "M_E_CPU0_SB_DQS_DN<0>")
	)
	(segment
		(start 312.766964 -279.651206)
		(end 313.200034 -279.218136)
		(width 0.16002)
		(layer "In6.Cu")
		(net "M_E_CPU0_SB_DQS_DN<0>")
	)
	(segment
		(start 316.850522 -275.45919)
		(end 324.044818 -275.45919)
		(width 0.16002)
		(layer "In6.Cu")
		(net "M_E_CPU0_SB_DQS_DN<0>")
	)
	(segment
		(start 313.203082 -278.007572)
		(end 313.429142 -278.007572)
		(width 0.16002)
		(layer "In6.Cu")
		(net "M_E_CPU0_SB_DQS_DN<0>")
	)
	(segment
		(start 314.338716 -276.871938)
		(end 314.684918 -276.525736)
		(width 0.16002)
		(layer "In6.Cu")
		(net "M_E_CPU0_SB_DQS_DN<0>")
	)
	(segment
		(start 281.380438 -285.312104)
		(end 281.692604 -285.62427)
		(width 0.16002)
		(layer "In6.Cu")
		(net "M_E_CPU0_SB_DQS_DN<0>")
	)
	(segment
		(start 293.496492 -285.312104)
		(end 296.468292 -285.312104)
		(width 0.16002)
		(layer "In6.Cu")
		(net "M_E_CPU0_SB_DQS_DN<0>")
	)
	(segment
		(start 302.617886 -285.40837)
		(end 303.227486 -286.01797)
		(width 0.16002)
		(layer "In6.Cu")
		(net "M_E_CPU0_SB_DQS_DN<0>")
	)
	(segment
		(start 277.192232 -285.735014)
		(end 277.466044 -285.461202)
		(width 0.16002)
		(layer "In6.Cu")
		(net "M_E_CPU0_SB_DQS_DN<0>")
	)
	(segment
		(start 283.657294 -284.764734)
		(end 283.959808 -284.46222)
		(width 0.16002)
		(layer "In6.Cu")
		(net "M_E_CPU0_SB_DQS_DN<0>")
	)
	(segment
		(start 311.500266 -279.710388)
		(end 311.811924 -279.39873)
		(width 0.16002)
		(layer "In6.Cu")
		(net "M_E_CPU0_SB_DQS_DN<0>")
	)
	(segment
		(start 312.947558 -278.263096)
		(end 313.203082 -278.007572)
		(width 0.16002)
		(layer "In6.Cu")
		(net "M_E_CPU0_SB_DQS_DN<0>")
	)
	(segment
		(start 313.200034 -278.741632)
		(end 312.947558 -278.489156)
		(width 0.16002)
		(layer "In6.Cu")
		(net "M_E_CPU0_SB_DQS_DN<0>")
	)
	(segment
		(start 308.675532 -284.09138)
		(end 310.446928 -282.319984)
		(width 0.16002)
		(layer "In6.Cu")
		(net "M_E_CPU0_SB_DQS_DN<0>")
	)
	(segment
		(start 316.690502 -276.210014)
		(end 316.690502 -275.61921)
		(width 0.16002)
		(layer "In6.Cu")
		(net "M_E_CPU0_SB_DQS_DN<0>")
	)
	(arc
		(start 328.249788 -276.190964)
		(mid 328.53122 -276.266719)
		(end 328.812652 -276.190964)
		(width 0.09525)
		(layer "In6.Cu")
		(net "M_E_CPU0_SB_DQS_DN<0>")
	)
	(arc
		(start 328.812652 -276.190964)
		(mid 328.969279 -276.141778)
		(end 329.13193 -276.16404)
		(width 0.09525)
		(layer "In6.Cu")
		(net "M_E_CPU0_SB_DQS_DN<0>")
	)
	(arc
		(start 327.88098 -276.186138)
		(mid 328.066012 -276.140224)
		(end 328.249788 -276.190964)
		(width 0.09525)
		(layer "In6.Cu")
		(net "M_E_CPU0_SB_DQS_DN<0>")
	)
	(arc
		(start 327.59142 -276.266656)
		(mid 327.736997 -276.247355)
		(end 327.872598 -276.190964)
		(width 0.09525)
		(layer "In6.Cu")
		(net "M_E_CPU0_SB_DQS_DN<0>")
	)
	(segment
		(start 331.34808 -279.49017)
		(end 330.880974 -279.756108)
		(width 0.10668)
		(layer "F.Cu")
		(net "M_E_CPU0_SB_DQ<9>")
	)
	(segment
		(start 300.580806 -292.109906)
		(end 298.018454 -292.109906)
		(width 0.14478)
		(layer "In6.Cu")
		(net "M_E_CPU0_SB_DQ<9>")
	)
	(segment
		(start 278.511254 -292.597332)
		(end 278.34844 -292.760146)
		(width 0.14478)
		(layer "In6.Cu")
		(net "M_E_CPU0_SB_DQ<9>")
	)
	(segment
		(start 285.94685 -292.109906)
		(end 283.268166 -292.109906)
		(width 0.14478)
		(layer "In6.Cu")
		(net "M_E_CPU0_SB_DQ<9>")
	)
	(segment
		(start 281.668474 -293.153338)
		(end 281.668474 -292.778434)
		(width 0.14478)
		(layer "In6.Cu")
		(net "M_E_CPU0_SB_DQ<9>")
	)
	(segment
		(start 323.898514 -279.75306)
		(end 319.175384 -279.75306)
		(width 0.14478)
		(layer "In6.Cu")
		(net "M_E_CPU0_SB_DQ<9>")
	)
	(segment
		(start 301.430944 -292.960044)
		(end 300.580806 -292.109906)
		(width 0.14478)
		(layer "In6.Cu")
		(net "M_E_CPU0_SB_DQ<9>")
	)
	(segment
		(start 281.668474 -292.778434)
		(end 281.50566 -292.61562)
		(width 0.14478)
		(layer "In6.Cu")
		(net "M_E_CPU0_SB_DQ<9>")
	)
	(segment
		(start 327.494646 -279.92451)
		(end 324.488048 -279.92451)
		(width 0.0889)
		(layer "In6.Cu")
		(net "M_E_CPU0_SB_DQ<9>")
	)
	(segment
		(start 290.684204 -292.109906)
		(end 289.834066 -292.960044)
		(width 0.14478)
		(layer "In6.Cu")
		(net "M_E_CPU0_SB_DQ<9>")
	)
	(segment
		(start 330.72705 -280.021538)
		(end 330.631038 -280.046938)
		(width 0.0889)
		(layer "In6.Cu")
		(net "M_E_CPU0_SB_DQ<9>")
	)
	(segment
		(start 278.9047 -293.13505)
		(end 278.9047 -292.760146)
		(width 0.14478)
		(layer "In6.Cu")
		(net "M_E_CPU0_SB_DQ<9>")
	)
	(segment
		(start 324.316598 -279.75306)
		(end 323.898514 -279.75306)
		(width 0.0889)
		(layer "In6.Cu")
		(net "M_E_CPU0_SB_DQ<9>")
	)
	(segment
		(start 283.268166 -292.109906)
		(end 282.06192 -293.316152)
		(width 0.14478)
		(layer "In6.Cu")
		(net "M_E_CPU0_SB_DQ<9>")
	)
	(segment
		(start 286.796988 -292.960044)
		(end 285.94685 -292.109906)
		(width 0.14478)
		(layer "In6.Cu")
		(net "M_E_CPU0_SB_DQ<9>")
	)
	(segment
		(start 308.825138 -291.171122)
		(end 307.886354 -292.109906)
		(width 0.14478)
		(layer "In6.Cu")
		(net "M_E_CPU0_SB_DQ<9>")
	)
	(segment
		(start 278.9047 -292.760146)
		(end 278.741886 -292.597332)
		(width 0.14478)
		(layer "In6.Cu")
		(net "M_E_CPU0_SB_DQ<9>")
	)
	(segment
		(start 324.488048 -279.92451)
		(end 324.316598 -279.75306)
		(width 0.0889)
		(layer "In6.Cu")
		(net "M_E_CPU0_SB_DQ<9>")
	)
	(segment
		(start 277.954994 -293.297864)
		(end 277.192232 -292.535102)
		(width 0.14478)
		(layer "In6.Cu")
		(net "M_E_CPU0_SB_DQ<9>")
	)
	(segment
		(start 293.31285 -292.109906)
		(end 290.684204 -292.109906)
		(width 0.14478)
		(layer "In6.Cu")
		(net "M_E_CPU0_SB_DQ<9>")
	)
	(segment
		(start 278.34844 -292.760146)
		(end 278.34844 -293.13505)
		(width 0.14478)
		(layer "In6.Cu")
		(net "M_E_CPU0_SB_DQ<9>")
	)
	(segment
		(start 306.73929 -292.109906)
		(end 306.453286 -292.39591)
		(width 0.14478)
		(layer "In6.Cu")
		(net "M_E_CPU0_SB_DQ<9>")
	)
	(segment
		(start 294.719248 -293.25951)
		(end 294.462454 -293.25951)
		(width 0.14478)
		(layer "In6.Cu")
		(net "M_E_CPU0_SB_DQ<9>")
	)
	(segment
		(start 327.873868 -280.078688)
		(end 327.80986 -280.04135)
		(width 0.0889)
		(layer "In6.Cu")
		(net "M_E_CPU0_SB_DQ<9>")
	)
	(segment
		(start 308.825138 -290.103306)
		(end 308.825138 -291.171122)
		(width 0.14478)
		(layer "In6.Cu")
		(net "M_E_CPU0_SB_DQ<9>")
	)
	(segment
		(start 279.854406 -292.597332)
		(end 279.623774 -292.597332)
		(width 0.14478)
		(layer "In6.Cu")
		(net "M_E_CPU0_SB_DQ<9>")
	)
	(segment
		(start 305.897026 -292.109906)
		(end 305.536854 -292.109906)
		(width 0.14478)
		(layer "In6.Cu")
		(net "M_E_CPU0_SB_DQ<9>")
	)
	(segment
		(start 298.018454 -292.109906)
		(end 296.86885 -293.25951)
		(width 0.14478)
		(layer "In6.Cu")
		(net "M_E_CPU0_SB_DQ<9>")
	)
	(segment
		(start 330.128118 -280.078688)
		(end 330.119736 -280.083514)
		(width 0.0889)
		(layer "In6.Cu")
		(net "M_E_CPU0_SB_DQ<9>")
	)
	(segment
		(start 279.623774 -292.597332)
		(end 279.46096 -292.760146)
		(width 0.14478)
		(layer "In6.Cu")
		(net "M_E_CPU0_SB_DQ<9>")
	)
	(segment
		(start 281.831288 -293.316152)
		(end 281.668474 -293.153338)
		(width 0.14478)
		(layer "In6.Cu")
		(net "M_E_CPU0_SB_DQ<9>")
	)
	(segment
		(start 279.46096 -293.13505)
		(end 279.298146 -293.297864)
		(width 0.14478)
		(layer "In6.Cu")
		(net "M_E_CPU0_SB_DQ<9>")
	)
	(segment
		(start 296.86885 -293.25951)
		(end 296.612056 -293.25951)
		(width 0.14478)
		(layer "In6.Cu")
		(net "M_E_CPU0_SB_DQ<9>")
	)
	(segment
		(start 279.298146 -293.297864)
		(end 279.067514 -293.297864)
		(width 0.14478)
		(layer "In6.Cu")
		(net "M_E_CPU0_SB_DQ<9>")
	)
	(segment
		(start 280.930604 -292.960044)
		(end 280.217118 -292.960044)
		(width 0.14478)
		(layer "In6.Cu")
		(net "M_E_CPU0_SB_DQ<9>")
	)
	(segment
		(start 280.217118 -292.960044)
		(end 279.854406 -292.597332)
		(width 0.14478)
		(layer "In6.Cu")
		(net "M_E_CPU0_SB_DQ<9>")
	)
	(segment
		(start 281.50566 -292.61562)
		(end 281.275028 -292.61562)
		(width 0.14478)
		(layer "In6.Cu")
		(net "M_E_CPU0_SB_DQ<9>")
	)
	(segment
		(start 296.31259 -292.960044)
		(end 295.018714 -292.960044)
		(width 0.14478)
		(layer "In6.Cu")
		(net "M_E_CPU0_SB_DQ<9>")
	)
	(segment
		(start 282.06192 -293.316152)
		(end 281.831288 -293.316152)
		(width 0.14478)
		(layer "In6.Cu")
		(net "M_E_CPU0_SB_DQ<9>")
	)
	(segment
		(start 330.880974 -279.756108)
		(end 330.72705 -280.021538)
		(width 0.0889)
		(layer "In6.Cu")
		(net "M_E_CPU0_SB_DQ<9>")
	)
	(segment
		(start 294.462454 -293.25951)
		(end 293.31285 -292.109906)
		(width 0.14478)
		(layer "In6.Cu")
		(net "M_E_CPU0_SB_DQ<9>")
	)
	(segment
		(start 278.741886 -292.597332)
		(end 278.511254 -292.597332)
		(width 0.14478)
		(layer "In6.Cu")
		(net "M_E_CPU0_SB_DQ<9>")
	)
	(segment
		(start 296.612056 -293.25951)
		(end 296.31259 -292.960044)
		(width 0.14478)
		(layer "In6.Cu")
		(net "M_E_CPU0_SB_DQ<9>")
	)
	(segment
		(start 319.175384 -279.75306)
		(end 308.825138 -290.103306)
		(width 0.14478)
		(layer "In6.Cu")
		(net "M_E_CPU0_SB_DQ<9>")
	)
	(segment
		(start 281.275028 -292.61562)
		(end 280.930604 -292.960044)
		(width 0.14478)
		(layer "In6.Cu")
		(net "M_E_CPU0_SB_DQ<9>")
	)
	(segment
		(start 289.834066 -292.960044)
		(end 286.796988 -292.960044)
		(width 0.14478)
		(layer "In6.Cu")
		(net "M_E_CPU0_SB_DQ<9>")
	)
	(segment
		(start 279.46096 -292.760146)
		(end 279.46096 -293.13505)
		(width 0.14478)
		(layer "In6.Cu")
		(net "M_E_CPU0_SB_DQ<9>")
	)
	(segment
		(start 306.453286 -292.39591)
		(end 306.18303 -292.39591)
		(width 0.14478)
		(layer "In6.Cu")
		(net "M_E_CPU0_SB_DQ<9>")
	)
	(segment
		(start 295.018714 -292.960044)
		(end 294.719248 -293.25951)
		(width 0.14478)
		(layer "In6.Cu")
		(net "M_E_CPU0_SB_DQ<9>")
	)
	(segment
		(start 304.686716 -292.960044)
		(end 301.430944 -292.960044)
		(width 0.14478)
		(layer "In6.Cu")
		(net "M_E_CPU0_SB_DQ<9>")
	)
	(segment
		(start 306.18303 -292.39591)
		(end 305.897026 -292.109906)
		(width 0.14478)
		(layer "In6.Cu")
		(net "M_E_CPU0_SB_DQ<9>")
	)
	(segment
		(start 279.067514 -293.297864)
		(end 278.9047 -293.13505)
		(width 0.14478)
		(layer "In6.Cu")
		(net "M_E_CPU0_SB_DQ<9>")
	)
	(segment
		(start 278.34844 -293.13505)
		(end 278.185626 -293.297864)
		(width 0.14478)
		(layer "In6.Cu")
		(net "M_E_CPU0_SB_DQ<9>")
	)
	(segment
		(start 307.886354 -292.109906)
		(end 306.73929 -292.109906)
		(width 0.14478)
		(layer "In6.Cu")
		(net "M_E_CPU0_SB_DQ<9>")
	)
	(segment
		(start 278.185626 -293.297864)
		(end 277.954994 -293.297864)
		(width 0.14478)
		(layer "In6.Cu")
		(net "M_E_CPU0_SB_DQ<9>")
	)
	(segment
		(start 305.536854 -292.109906)
		(end 304.686716 -292.960044)
		(width 0.14478)
		(layer "In6.Cu")
		(net "M_E_CPU0_SB_DQ<9>")
	)
	(arc
		(start 327.58253 -279.938734)
		(mid 327.539162 -279.928081)
		(end 327.494646 -279.92451)
		(width 0.0889)
		(layer "In6.Cu")
		(net "M_E_CPU0_SB_DQ<9>")
	)
	(arc
		(start 328.814176 -280.078688)
		(mid 328.53122 -280.002511)
		(end 328.248264 -280.078688)
		(width 0.0889)
		(layer "In6.Cu")
		(net "M_E_CPU0_SB_DQ<9>")
	)
	(arc
		(start 329.188064 -280.078688)
		(mid 329.00112 -280.128943)
		(end 328.814176 -280.078688)
		(width 0.0889)
		(layer "In6.Cu")
		(net "M_E_CPU0_SB_DQ<9>")
	)
	(arc
		(start 328.248264 -280.078688)
		(mid 328.061066 -280.12907)
		(end 327.873868 -280.078688)
		(width 0.0889)
		(layer "In6.Cu")
		(net "M_E_CPU0_SB_DQ<9>")
	)
	(arc
		(start 329.753976 -280.078688)
		(mid 329.47102 -280.002511)
		(end 329.188064 -280.078688)
		(width 0.0889)
		(layer "In6.Cu")
		(net "M_E_CPU0_SB_DQ<9>")
	)
	(arc
		(start 330.119736 -280.083514)
		(mid 329.936228 -280.129008)
		(end 329.753976 -280.078688)
		(width 0.0889)
		(layer "In6.Cu")
		(net "M_E_CPU0_SB_DQ<9>")
	)
	(arc
		(start 327.80986 -280.04135)
		(mid 327.698804 -279.984264)
		(end 327.58253 -279.938734)
		(width 0.0889)
		(layer "In6.Cu")
		(net "M_E_CPU0_SB_DQ<9>")
	)
	(arc
		(start 330.631038 -280.046938)
		(mid 330.37583 -280.003461)
		(end 330.128118 -280.078688)
		(width 0.0889)
		(layer "In6.Cu")
		(net "M_E_CPU0_SB_DQ<9>")
	)
	(segment
		(start 329.937872 -278.680164)
		(end 329.47102 -278.946102)
		(width 0.10668)
		(layer "F.Cu")
		(net "M_E_CPU0_SB_DQ<8>")
	)
	(segment
		(start 327.404476 -279.268682)
		(end 327.394062 -279.262586)
		(width 0.0889)
		(layer "In6.Cu")
		(net "M_E_CPU0_SB_DQ<8>")
	)
	(segment
		(start 306.790344 -290.642548)
		(end 306.790344 -290.506912)
		(width 0.14478)
		(layer "In6.Cu")
		(net "M_E_CPU0_SB_DQ<8>")
	)
	(segment
		(start 299.020484 -290.71951)
		(end 298.711112 -290.410138)
		(width 0.14478)
		(layer "In6.Cu")
		(net "M_E_CPU0_SB_DQ<8>")
	)
	(segment
		(start 304.427128 -291.637212)
		(end 304.261266 -291.47135)
		(width 0.14478)
		(layer "In6.Cu")
		(net "M_E_CPU0_SB_DQ<8>")
	)
	(segment
		(start 302.698404 -291.58311)
		(end 301.780956 -291.58311)
		(width 0.14478)
		(layer "In6.Cu")
		(net "M_E_CPU0_SB_DQ<8>")
	)
	(segment
		(start 296.440098 -291.632132)
		(end 296.068242 -291.260276)
		(width 0.14478)
		(layer "In6.Cu")
		(net "M_E_CPU0_SB_DQ<8>")
	)
	(segment
		(start 303.254664 -291.260276)
		(end 303.021238 -291.260276)
		(width 0.14478)
		(layer "In6.Cu")
		(net "M_E_CPU0_SB_DQ<8>")
	)
	(segment
		(start 305.623468 -290.440872)
		(end 305.623468 -290.645596)
		(width 0.14478)
		(layer "In6.Cu")
		(net "M_E_CPU0_SB_DQ<8>")
	)
	(segment
		(start 279.57653 -291.548312)
		(end 279.300686 -291.548312)
		(width 0.14478)
		(layer "In6.Cu")
		(net "M_E_CPU0_SB_DQ<8>")
	)
	(segment
		(start 306.953158 -290.805362)
		(end 306.790344 -290.642548)
		(width 0.14478)
		(layer "In6.Cu")
		(net "M_E_CPU0_SB_DQ<8>")
	)
	(segment
		(start 304.056542 -291.47135)
		(end 303.944782 -291.58311)
		(width 0.14478)
		(layer "In6.Cu")
		(net "M_E_CPU0_SB_DQ<8>")
	)
	(segment
		(start 304.825908 -291.238432)
		(end 304.825908 -291.443156)
		(width 0.14478)
		(layer "In6.Cu")
		(net "M_E_CPU0_SB_DQ<8>")
	)
	(segment
		(start 300.894496 -290.410138)
		(end 300.585124 -290.71951)
		(width 0.14478)
		(layer "In6.Cu")
		(net "M_E_CPU0_SB_DQ<8>")
	)
	(segment
		(start 289.343846 -291.39642)
		(end 289.343846 -291.124132)
		(width 0.14478)
		(layer "In6.Cu")
		(net "M_E_CPU0_SB_DQ<8>")
	)
	(segment
		(start 329.47102 -278.946102)
		(end 329.317096 -279.211532)
		(width 0.0889)
		(layer "In6.Cu")
		(net "M_E_CPU0_SB_DQ<8>")
	)
	(segment
		(start 326.387206 -279.209754)
		(end 326.021192 -278.84374)
		(width 0.0889)
		(layer "In6.Cu")
		(net "M_E_CPU0_SB_DQ<8>")
	)
	(segment
		(start 305.429412 -290.839652)
		(end 305.224688 -290.839652)
		(width 0.14478)
		(layer "In6.Cu")
		(net "M_E_CPU0_SB_DQ<8>")
	)
	(segment
		(start 300.028864 -290.410138)
		(end 299.576744 -290.410138)
		(width 0.14478)
		(layer "In6.Cu")
		(net "M_E_CPU0_SB_DQ<8>")
	)
	(segment
		(start 288.651442 -291.260276)
		(end 286.951928 -291.260276)
		(width 0.14478)
		(layer "In6.Cu")
		(net "M_E_CPU0_SB_DQ<8>")
	)
	(segment
		(start 326.021192 -278.84374)
		(end 323.982334 -278.84374)
		(width 0.0889)
		(layer "In6.Cu")
		(net "M_E_CPU0_SB_DQ<8>")
	)
	(segment
		(start 289.763962 -291.53231)
		(end 289.479736 -291.53231)
		(width 0.14478)
		(layer "In6.Cu")
		(net "M_E_CPU0_SB_DQ<8>")
	)
	(segment
		(start 298.711112 -290.410138)
		(end 298.431966 -290.410138)
		(width 0.14478)
		(layer "In6.Cu")
		(net "M_E_CPU0_SB_DQ<8>")
	)
	(segment
		(start 304.854102 -290.67379)
		(end 304.660046 -290.867846)
		(width 0.14478)
		(layer "In6.Cu")
		(net "M_E_CPU0_SB_DQ<8>")
	)
	(segment
		(start 329.317096 -279.211532)
		(end 329.221084 -279.236932)
		(width 0.0889)
		(layer "In6.Cu")
		(net "M_E_CPU0_SB_DQ<8>")
	)
	(segment
		(start 307.781198 -290.805362)
		(end 306.953158 -290.805362)
		(width 0.14478)
		(layer "In6.Cu")
		(net "M_E_CPU0_SB_DQ<8>")
	)
	(segment
		(start 288.923476 -290.988242)
		(end 288.651442 -291.260276)
		(width 0.14478)
		(layer "In6.Cu")
		(net "M_E_CPU0_SB_DQ<8>")
	)
	(segment
		(start 305.623468 -290.645596)
		(end 305.429412 -290.839652)
		(width 0.14478)
		(layer "In6.Cu")
		(net "M_E_CPU0_SB_DQ<8>")
	)
	(segment
		(start 303.021238 -291.260276)
		(end 302.698404 -291.58311)
		(width 0.14478)
		(layer "In6.Cu")
		(net "M_E_CPU0_SB_DQ<8>")
	)
	(segment
		(start 304.631852 -291.637212)
		(end 304.427128 -291.637212)
		(width 0.14478)
		(layer "In6.Cu")
		(net "M_E_CPU0_SB_DQ<8>")
	)
	(segment
		(start 299.267372 -290.71951)
		(end 299.020484 -290.71951)
		(width 0.14478)
		(layer "In6.Cu")
		(net "M_E_CPU0_SB_DQ<8>")
	)
	(segment
		(start 279.864566 -291.260276)
		(end 279.57653 -291.548312)
		(width 0.14478)
		(layer "In6.Cu")
		(net "M_E_CPU0_SB_DQ<8>")
	)
	(segment
		(start 289.343846 -291.124132)
		(end 289.207956 -290.988242)
		(width 0.14478)
		(layer "In6.Cu")
		(net "M_E_CPU0_SB_DQ<8>")
	)
	(segment
		(start 306.790344 -290.506912)
		(end 306.780438 -290.497006)
		(width 0.14478)
		(layer "In6.Cu")
		(net "M_E_CPU0_SB_DQ<8>")
	)
	(segment
		(start 307.925978 -289.730434)
		(end 307.925978 -290.660582)
		(width 0.14478)
		(layer "In6.Cu")
		(net "M_E_CPU0_SB_DQ<8>")
	)
	(segment
		(start 282.720288 -291.26053)
		(end 282.720034 -291.260276)
		(width 0.14478)
		(layer "In6.Cu")
		(net "M_E_CPU0_SB_DQ<8>")
	)
	(segment
		(start 326.476106 -279.27554)
		(end 326.464422 -279.268682)
		(width 0.0889)
		(layer "In6.Cu")
		(net "M_E_CPU0_SB_DQ<8>")
	)
	(segment
		(start 289.207956 -290.988242)
		(end 288.923476 -290.988242)
		(width 0.14478)
		(layer "In6.Cu")
		(net "M_E_CPU0_SB_DQ<8>")
	)
	(segment
		(start 323.982334 -278.84374)
		(end 318.812672 -278.84374)
		(width 0.14478)
		(layer "In6.Cu")
		(net "M_E_CPU0_SB_DQ<8>")
	)
	(segment
		(start 304.261266 -291.47135)
		(end 304.056542 -291.47135)
		(width 0.14478)
		(layer "In6.Cu")
		(net "M_E_CPU0_SB_DQ<8>")
	)
	(segment
		(start 289.479736 -291.53231)
		(end 289.343846 -291.39642)
		(width 0.14478)
		(layer "In6.Cu")
		(net "M_E_CPU0_SB_DQ<8>")
	)
	(segment
		(start 277.617428 -291.260276)
		(end 277.192232 -290.83508)
		(width 0.14478)
		(layer "In6.Cu")
		(net "M_E_CPU0_SB_DQ<8>")
	)
	(segment
		(start 306.581302 -289.710876)
		(end 305.817016 -289.710876)
		(width 0.14478)
		(layer "In6.Cu")
		(net "M_E_CPU0_SB_DQ<8>")
	)
	(segment
		(start 290.886134 -290.410138)
		(end 289.763962 -291.53231)
		(width 0.14478)
		(layer "In6.Cu")
		(net "M_E_CPU0_SB_DQ<8>")
	)
	(segment
		(start 326.38746 -279.209754)
		(end 326.387206 -279.209754)
		(width 0.0889)
		(layer "In6.Cu")
		(net "M_E_CPU0_SB_DQ<8>")
	)
	(segment
		(start 303.944782 -291.58311)
		(end 303.577498 -291.58311)
		(width 0.14478)
		(layer "In6.Cu")
		(net "M_E_CPU0_SB_DQ<8>")
	)
	(segment
		(start 294.993314 -291.260276)
		(end 294.67048 -291.58311)
		(width 0.14478)
		(layer "In6.Cu")
		(net "M_E_CPU0_SB_DQ<8>")
	)
	(segment
		(start 300.585124 -290.71951)
		(end 300.338236 -290.71951)
		(width 0.14478)
		(layer "In6.Cu")
		(net "M_E_CPU0_SB_DQ<8>")
	)
	(segment
		(start 293.264082 -290.410138)
		(end 290.886134 -290.410138)
		(width 0.14478)
		(layer "In6.Cu")
		(net "M_E_CPU0_SB_DQ<8>")
	)
	(segment
		(start 304.825908 -291.443156)
		(end 304.631852 -291.637212)
		(width 0.14478)
		(layer "In6.Cu")
		(net "M_E_CPU0_SB_DQ<8>")
	)
	(segment
		(start 301.502318 -291.304472)
		(end 301.502318 -290.62045)
		(width 0.14478)
		(layer "In6.Cu")
		(net "M_E_CPU0_SB_DQ<8>")
	)
	(segment
		(start 279.01265 -291.260276)
		(end 277.617428 -291.260276)
		(width 0.14478)
		(layer "In6.Cu")
		(net "M_E_CPU0_SB_DQ<8>")
	)
	(segment
		(start 304.660046 -291.07257)
		(end 304.825908 -291.238432)
		(width 0.14478)
		(layer "In6.Cu")
		(net "M_E_CPU0_SB_DQ<8>")
	)
	(segment
		(start 297.209972 -291.632132)
		(end 296.440098 -291.632132)
		(width 0.14478)
		(layer "In6.Cu")
		(net "M_E_CPU0_SB_DQ<8>")
	)
	(segment
		(start 279.300686 -291.548312)
		(end 279.01265 -291.260276)
		(width 0.14478)
		(layer "In6.Cu")
		(net "M_E_CPU0_SB_DQ<8>")
	)
	(segment
		(start 307.925978 -290.660582)
		(end 307.781198 -290.805362)
		(width 0.14478)
		(layer "In6.Cu")
		(net "M_E_CPU0_SB_DQ<8>")
	)
	(segment
		(start 305.058826 -290.67379)
		(end 304.854102 -290.67379)
		(width 0.14478)
		(layer "In6.Cu")
		(net "M_E_CPU0_SB_DQ<8>")
	)
	(segment
		(start 294.67048 -291.58311)
		(end 294.437054 -291.58311)
		(width 0.14478)
		(layer "In6.Cu")
		(net "M_E_CPU0_SB_DQ<8>")
	)
	(segment
		(start 306.780438 -289.910012)
		(end 306.581302 -289.710876)
		(width 0.14478)
		(layer "In6.Cu")
		(net "M_E_CPU0_SB_DQ<8>")
	)
	(segment
		(start 306.780438 -290.497006)
		(end 306.780438 -289.910012)
		(width 0.14478)
		(layer "In6.Cu")
		(net "M_E_CPU0_SB_DQ<8>")
	)
	(segment
		(start 294.437054 -291.58311)
		(end 293.264082 -290.410138)
		(width 0.14478)
		(layer "In6.Cu")
		(net "M_E_CPU0_SB_DQ<8>")
	)
	(segment
		(start 286.10179 -290.410138)
		(end 283.570934 -290.410138)
		(width 0.14478)
		(layer "In6.Cu")
		(net "M_E_CPU0_SB_DQ<8>")
	)
	(segment
		(start 300.338236 -290.71951)
		(end 300.028864 -290.410138)
		(width 0.14478)
		(layer "In6.Cu")
		(net "M_E_CPU0_SB_DQ<8>")
	)
	(segment
		(start 301.502318 -290.62045)
		(end 301.292006 -290.410138)
		(width 0.14478)
		(layer "In6.Cu")
		(net "M_E_CPU0_SB_DQ<8>")
	)
	(segment
		(start 318.812672 -278.84374)
		(end 307.925978 -289.730434)
		(width 0.14478)
		(layer "In6.Cu")
		(net "M_E_CPU0_SB_DQ<8>")
	)
	(segment
		(start 296.068242 -291.260276)
		(end 294.993314 -291.260276)
		(width 0.14478)
		(layer "In6.Cu")
		(net "M_E_CPU0_SB_DQ<8>")
	)
	(segment
		(start 298.431966 -290.410138)
		(end 297.209972 -291.632132)
		(width 0.14478)
		(layer "In6.Cu")
		(net "M_E_CPU0_SB_DQ<8>")
	)
	(segment
		(start 299.576744 -290.410138)
		(end 299.267372 -290.71951)
		(width 0.14478)
		(layer "In6.Cu")
		(net "M_E_CPU0_SB_DQ<8>")
	)
	(segment
		(start 305.457606 -290.070286)
		(end 305.457606 -290.27501)
		(width 0.14478)
		(layer "In6.Cu")
		(net "M_E_CPU0_SB_DQ<8>")
	)
	(segment
		(start 301.292006 -290.410138)
		(end 300.894496 -290.410138)
		(width 0.14478)
		(layer "In6.Cu")
		(net "M_E_CPU0_SB_DQ<8>")
	)
	(segment
		(start 286.951928 -291.260276)
		(end 286.10179 -290.410138)
		(width 0.14478)
		(layer "In6.Cu")
		(net "M_E_CPU0_SB_DQ<8>")
	)
	(segment
		(start 301.780956 -291.58311)
		(end 301.502318 -291.304472)
		(width 0.14478)
		(layer "In6.Cu")
		(net "M_E_CPU0_SB_DQ<8>")
	)
	(segment
		(start 303.577498 -291.58311)
		(end 303.254664 -291.260276)
		(width 0.14478)
		(layer "In6.Cu")
		(net "M_E_CPU0_SB_DQ<8>")
	)
	(segment
		(start 283.570934 -290.410138)
		(end 282.720288 -291.26053)
		(width 0.14478)
		(layer "In6.Cu")
		(net "M_E_CPU0_SB_DQ<8>")
	)
	(segment
		(start 305.817016 -289.710876)
		(end 305.457606 -290.070286)
		(width 0.14478)
		(layer "In6.Cu")
		(net "M_E_CPU0_SB_DQ<8>")
	)
	(segment
		(start 305.224688 -290.839652)
		(end 305.058826 -290.67379)
		(width 0.14478)
		(layer "In6.Cu")
		(net "M_E_CPU0_SB_DQ<8>")
	)
	(segment
		(start 304.660046 -290.867846)
		(end 304.660046 -291.07257)
		(width 0.14478)
		(layer "In6.Cu")
		(net "M_E_CPU0_SB_DQ<8>")
	)
	(segment
		(start 327.788778 -279.262586)
		(end 327.778364 -279.268682)
		(width 0.0889)
		(layer "In6.Cu")
		(net "M_E_CPU0_SB_DQ<8>")
	)
	(segment
		(start 328.718164 -279.268682)
		(end 328.709782 -279.273508)
		(width 0.0889)
		(layer "In6.Cu")
		(net "M_E_CPU0_SB_DQ<8>")
	)
	(segment
		(start 282.720034 -291.260276)
		(end 279.864566 -291.260276)
		(width 0.14478)
		(layer "In6.Cu")
		(net "M_E_CPU0_SB_DQ<8>")
	)
	(segment
		(start 305.457606 -290.27501)
		(end 305.623468 -290.440872)
		(width 0.14478)
		(layer "In6.Cu")
		(net "M_E_CPU0_SB_DQ<8>")
	)
	(arc
		(start 328.344022 -279.268682)
		(mid 328.067209 -279.192539)
		(end 327.788778 -279.262586)
		(width 0.0889)
		(layer "In6.Cu")
		(net "M_E_CPU0_SB_DQ<8>")
	)
	(arc
		(start 329.221084 -279.236932)
		(mid 328.965876 -279.193455)
		(end 328.718164 -279.268682)
		(width 0.0889)
		(layer "In6.Cu")
		(net "M_E_CPU0_SB_DQ<8>")
	)
	(arc
		(start 327.394062 -279.262586)
		(mid 327.115376 -279.192366)
		(end 326.83831 -279.268682)
		(width 0.0889)
		(layer "In6.Cu")
		(net "M_E_CPU0_SB_DQ<8>")
	)
	(arc
		(start 326.83831 -279.268682)
		(mid 326.658105 -279.318999)
		(end 326.476106 -279.27554)
		(width 0.0889)
		(layer "In6.Cu")
		(net "M_E_CPU0_SB_DQ<8>")
	)
	(arc
		(start 327.778364 -279.268682)
		(mid 327.59142 -279.318937)
		(end 327.404476 -279.268682)
		(width 0.0889)
		(layer "In6.Cu")
		(net "M_E_CPU0_SB_DQ<8>")
	)
	(arc
		(start 326.464422 -279.268682)
		(mid 326.424019 -279.241728)
		(end 326.38746 -279.209754)
		(width 0.0889)
		(layer "In6.Cu")
		(net "M_E_CPU0_SB_DQ<8>")
	)
	(arc
		(start 328.709782 -279.273508)
		(mid 328.526274 -279.319002)
		(end 328.344022 -279.268682)
		(width 0.0889)
		(layer "In6.Cu")
		(net "M_E_CPU0_SB_DQ<8>")
	)
	(segment
		(start 330.877926 -278.680164)
		(end 330.411074 -278.946102)
		(width 0.10668)
		(layer "F.Cu")
		(net "M_E_CPU0_SB_DQ<7>")
	)
	(segment
		(start 273.517106 -290.410138)
		(end 273.092164 -289.985196)
		(width 0.14478)
		(layer "In6.Cu")
		(net "M_E_CPU0_SB_DQ<7>")
	)
	(segment
		(start 305.58867 -289.159696)
		(end 304.338228 -290.410138)
		(width 0.14478)
		(layer "In6.Cu")
		(net "M_E_CPU0_SB_DQ<7>")
	)
	(segment
		(start 330.411074 -278.946102)
		(end 330.564998 -278.680672)
		(width 0.0889)
		(layer "In6.Cu")
		(net "M_E_CPU0_SB_DQ<7>")
	)
	(segment
		(start 307.858414 -289.018472)
		(end 307.517546 -289.159696)
		(width 0.14478)
		(layer "In6.Cu")
		(net "M_E_CPU0_SB_DQ<7>")
	)
	(segment
		(start 302.079152 -290.410138)
		(end 301.229014 -289.56)
		(width 0.14478)
		(layer "In6.Cu")
		(net "M_E_CPU0_SB_DQ<7>")
	)
	(segment
		(start 283.633418 -289.56)
		(end 282.78328 -290.410138)
		(width 0.14478)
		(layer "In6.Cu")
		(net "M_E_CPU0_SB_DQ<7>")
	)
	(segment
		(start 298.494958 -289.56)
		(end 297.64482 -290.410138)
		(width 0.14478)
		(layer "In6.Cu")
		(net "M_E_CPU0_SB_DQ<7>")
	)
	(segment
		(start 307.517546 -289.159696)
		(end 305.58867 -289.159696)
		(width 0.14478)
		(layer "In6.Cu")
		(net "M_E_CPU0_SB_DQ<7>")
	)
	(segment
		(start 282.78328 -290.410138)
		(end 273.517106 -290.410138)
		(width 0.14478)
		(layer "In6.Cu")
		(net "M_E_CPU0_SB_DQ<7>")
	)
	(segment
		(start 301.229014 -289.56)
		(end 298.494958 -289.56)
		(width 0.14478)
		(layer "In6.Cu")
		(net "M_E_CPU0_SB_DQ<7>")
	)
	(segment
		(start 318.589406 -278.28748)
		(end 307.858414 -289.018472)
		(width 0.14478)
		(layer "In6.Cu")
		(net "M_E_CPU0_SB_DQ<7>")
	)
	(segment
		(start 286.888936 -290.410138)
		(end 286.038798 -289.56)
		(width 0.14478)
		(layer "In6.Cu")
		(net "M_E_CPU0_SB_DQ<7>")
	)
	(segment
		(start 286.038798 -289.56)
		(end 283.633418 -289.56)
		(width 0.14478)
		(layer "In6.Cu")
		(net "M_E_CPU0_SB_DQ<7>")
	)
	(segment
		(start 328.718164 -278.623522)
		(end 328.709782 -278.618696)
		(width 0.0889)
		(layer "In6.Cu")
		(net "M_E_CPU0_SB_DQ<7>")
	)
	(segment
		(start 324.643496 -278.28748)
		(end 323.97446 -278.28748)
		(width 0.0889)
		(layer "In6.Cu")
		(net "M_E_CPU0_SB_DQ<7>")
	)
	(segment
		(start 304.338228 -290.410138)
		(end 302.079152 -290.410138)
		(width 0.14478)
		(layer "In6.Cu")
		(net "M_E_CPU0_SB_DQ<7>")
	)
	(segment
		(start 293.226998 -289.56)
		(end 290.923218 -289.56)
		(width 0.14478)
		(layer "In6.Cu")
		(net "M_E_CPU0_SB_DQ<7>")
	)
	(segment
		(start 290.923218 -289.56)
		(end 290.07308 -290.410138)
		(width 0.14478)
		(layer "In6.Cu")
		(net "M_E_CPU0_SB_DQ<7>")
	)
	(segment
		(start 324.802246 -278.44623)
		(end 324.643496 -278.28748)
		(width 0.0889)
		(layer "In6.Cu")
		(net "M_E_CPU0_SB_DQ<7>")
	)
	(segment
		(start 294.077136 -290.410138)
		(end 293.226998 -289.56)
		(width 0.14478)
		(layer "In6.Cu")
		(net "M_E_CPU0_SB_DQ<7>")
	)
	(segment
		(start 290.07308 -290.410138)
		(end 286.888936 -290.410138)
		(width 0.14478)
		(layer "In6.Cu")
		(net "M_E_CPU0_SB_DQ<7>")
	)
	(segment
		(start 297.64482 -290.410138)
		(end 294.077136 -290.410138)
		(width 0.14478)
		(layer "In6.Cu")
		(net "M_E_CPU0_SB_DQ<7>")
	)
	(segment
		(start 330.564998 -278.680672)
		(end 330.542646 -278.59736)
		(width 0.0889)
		(layer "In6.Cu")
		(net "M_E_CPU0_SB_DQ<7>")
	)
	(segment
		(start 323.97446 -278.28748)
		(end 318.589406 -278.28748)
		(width 0.14478)
		(layer "In6.Cu")
		(net "M_E_CPU0_SB_DQ<7>")
	)
	(segment
		(start 329.292458 -278.618696)
		(end 329.284076 -278.623522)
		(width 0.0889)
		(layer "In6.Cu")
		(net "M_E_CPU0_SB_DQ<7>")
	)
	(segment
		(start 327.12025 -278.44623)
		(end 324.802246 -278.44623)
		(width 0.0889)
		(layer "In6.Cu")
		(net "M_E_CPU0_SB_DQ<7>")
	)
	(arc
		(start 328.709782 -278.618696)
		(mid 328.526274 -278.573202)
		(end 328.344022 -278.623522)
		(width 0.0889)
		(layer "In6.Cu")
		(net "M_E_CPU0_SB_DQ<7>")
	)
	(arc
		(start 329.658218 -278.623522)
		(mid 329.475967 -278.573172)
		(end 329.292458 -278.618696)
		(width 0.0889)
		(layer "In6.Cu")
		(net "M_E_CPU0_SB_DQ<7>")
	)
	(arc
		(start 327.77811 -278.623522)
		(mid 327.460912 -278.491349)
		(end 327.12025 -278.44623)
		(width 0.0889)
		(layer "In6.Cu")
		(net "M_E_CPU0_SB_DQ<7>")
	)
	(arc
		(start 328.344022 -278.623522)
		(mid 328.061066 -278.699699)
		(end 327.77811 -278.623522)
		(width 0.0889)
		(layer "In6.Cu")
		(net "M_E_CPU0_SB_DQ<7>")
	)
	(arc
		(start 329.284076 -278.623522)
		(mid 329.00112 -278.699699)
		(end 328.718164 -278.623522)
		(width 0.0889)
		(layer "In6.Cu")
		(net "M_E_CPU0_SB_DQ<7>")
	)
	(arc
		(start 330.22413 -278.623522)
		(mid 329.941174 -278.699699)
		(end 329.658218 -278.623522)
		(width 0.0889)
		(layer "In6.Cu")
		(net "M_E_CPU0_SB_DQ<7>")
	)
	(arc
		(start 330.542646 -278.59736)
		(mid 330.380457 -278.574625)
		(end 330.22413 -278.623522)
		(width 0.0889)
		(layer "In6.Cu")
		(net "M_E_CPU0_SB_DQ<7>")
	)
	(segment
		(start 329.467972 -277.870158)
		(end 329.00112 -278.136096)
		(width 0.10668)
		(layer "F.Cu")
		(net "M_E_CPU0_SB_DQ<6>")
	)
	(segment
		(start 274.65147 -288.547302)
		(end 274.65147 -288.139124)
		(width 0.14478)
		(layer "In6.Cu")
		(net "M_E_CPU0_SB_DQ<6>")
	)
	(segment
		(start 300.815502 -287.859978)
		(end 298.90847 -287.859978)
		(width 0.14478)
		(layer "In6.Cu")
		(net "M_E_CPU0_SB_DQ<6>")
	)
	(segment
		(start 286.040322 -287.859978)
		(end 283.908246 -287.859978)
		(width 0.14478)
		(layer "In6.Cu")
		(net "M_E_CPU0_SB_DQ<6>")
	)
	(segment
		(start 293.87546 -288.710116)
		(end 293.025322 -287.859978)
		(width 0.14478)
		(layer "In6.Cu")
		(net "M_E_CPU0_SB_DQ<6>")
	)
	(segment
		(start 307.215032 -287.504632)
		(end 305.90744 -287.504632)
		(width 0.14478)
		(layer "In6.Cu")
		(net "M_E_CPU0_SB_DQ<6>")
	)
	(segment
		(start 298.058332 -288.710116)
		(end 293.87546 -288.710116)
		(width 0.14478)
		(layer "In6.Cu")
		(net "M_E_CPU0_SB_DQ<6>")
	)
	(segment
		(start 275.20773 -288.547302)
		(end 275.044916 -288.710116)
		(width 0.14478)
		(layer "In6.Cu")
		(net "M_E_CPU0_SB_DQ<6>")
	)
	(segment
		(start 304.701956 -288.710116)
		(end 301.66564 -288.710116)
		(width 0.14478)
		(layer "In6.Cu")
		(net "M_E_CPU0_SB_DQ<6>")
	)
	(segment
		(start 323.894704 -277.37816)
		(end 318.212216 -277.37816)
		(width 0.14478)
		(layer "In6.Cu")
		(net "M_E_CPU0_SB_DQ<6>")
	)
	(segment
		(start 293.025322 -287.859978)
		(end 291.099494 -287.859978)
		(width 0.14478)
		(layer "In6.Cu")
		(net "M_E_CPU0_SB_DQ<6>")
	)
	(segment
		(start 327.882504 -277.80869)
		(end 327.874122 -277.813516)
		(width 0.0889)
		(layer "In6.Cu")
		(net "M_E_CPU0_SB_DQ<6>")
	)
	(segment
		(start 291.099494 -287.859978)
		(end 290.249356 -288.710116)
		(width 0.14478)
		(layer "In6.Cu")
		(net "M_E_CPU0_SB_DQ<6>")
	)
	(segment
		(start 305.90744 -287.504632)
		(end 304.701956 -288.710116)
		(width 0.14478)
		(layer "In6.Cu")
		(net "M_E_CPU0_SB_DQ<6>")
	)
	(segment
		(start 325.901558 -277.373588)
		(end 323.899276 -277.373588)
		(width 0.0889)
		(layer "In6.Cu")
		(net "M_E_CPU0_SB_DQ<6>")
	)
	(segment
		(start 298.90847 -287.859978)
		(end 298.058332 -288.710116)
		(width 0.14478)
		(layer "In6.Cu")
		(net "M_E_CPU0_SB_DQ<6>")
	)
	(segment
		(start 308.70144 -286.888936)
		(end 307.215032 -287.504632)
		(width 0.14478)
		(layer "In6.Cu")
		(net "M_E_CPU0_SB_DQ<6>")
	)
	(segment
		(start 274.814284 -288.710116)
		(end 274.65147 -288.547302)
		(width 0.14478)
		(layer "In6.Cu")
		(net "M_E_CPU0_SB_DQ<6>")
	)
	(segment
		(start 283.058108 -288.710116)
		(end 275.926804 -288.710116)
		(width 0.14478)
		(layer "In6.Cu")
		(net "M_E_CPU0_SB_DQ<6>")
	)
	(segment
		(start 286.89046 -288.710116)
		(end 286.040322 -287.859978)
		(width 0.14478)
		(layer "In6.Cu")
		(net "M_E_CPU0_SB_DQ<6>")
	)
	(segment
		(start 274.258024 -287.97631)
		(end 273.94916 -288.285174)
		(width 0.14478)
		(layer "In6.Cu")
		(net "M_E_CPU0_SB_DQ<6>")
	)
	(segment
		(start 323.899276 -277.373588)
		(end 323.894704 -277.37816)
		(width 0.0889)
		(layer "In6.Cu")
		(net "M_E_CPU0_SB_DQ<6>")
	)
	(segment
		(start 275.044916 -288.710116)
		(end 274.814284 -288.710116)
		(width 0.14478)
		(layer "In6.Cu")
		(net "M_E_CPU0_SB_DQ<6>")
	)
	(segment
		(start 275.370544 -287.97631)
		(end 275.20773 -288.139124)
		(width 0.14478)
		(layer "In6.Cu")
		(net "M_E_CPU0_SB_DQ<6>")
	)
	(segment
		(start 275.20773 -288.139124)
		(end 275.20773 -288.547302)
		(width 0.14478)
		(layer "In6.Cu")
		(net "M_E_CPU0_SB_DQ<6>")
	)
	(segment
		(start 275.601176 -287.97631)
		(end 275.370544 -287.97631)
		(width 0.14478)
		(layer "In6.Cu")
		(net "M_E_CPU0_SB_DQ<6>")
	)
	(segment
		(start 275.76399 -288.547302)
		(end 275.76399 -288.139124)
		(width 0.14478)
		(layer "In6.Cu")
		(net "M_E_CPU0_SB_DQ<6>")
	)
	(segment
		(start 275.926804 -288.710116)
		(end 275.76399 -288.547302)
		(width 0.14478)
		(layer "In6.Cu")
		(net "M_E_CPU0_SB_DQ<6>")
	)
	(segment
		(start 274.65147 -288.139124)
		(end 274.488656 -287.97631)
		(width 0.14478)
		(layer "In6.Cu")
		(net "M_E_CPU0_SB_DQ<6>")
	)
	(segment
		(start 301.66564 -288.710116)
		(end 300.815502 -287.859978)
		(width 0.14478)
		(layer "In6.Cu")
		(net "M_E_CPU0_SB_DQ<6>")
	)
	(segment
		(start 318.212216 -277.37816)
		(end 308.70144 -286.888936)
		(width 0.14478)
		(layer "In6.Cu")
		(net "M_E_CPU0_SB_DQ<6>")
	)
	(segment
		(start 275.76399 -288.139124)
		(end 275.601176 -287.97631)
		(width 0.14478)
		(layer "In6.Cu")
		(net "M_E_CPU0_SB_DQ<6>")
	)
	(segment
		(start 326.383142 -277.822152)
		(end 326.36841 -277.813516)
		(width 0.0889)
		(layer "In6.Cu")
		(net "M_E_CPU0_SB_DQ<6>")
	)
	(segment
		(start 327.874122 -277.813516)
		(end 327.863708 -277.819612)
		(width 0.0889)
		(layer "In6.Cu")
		(net "M_E_CPU0_SB_DQ<6>")
	)
	(segment
		(start 326.252586 -277.724616)
		(end 325.901558 -277.373588)
		(width 0.0889)
		(layer "In6.Cu")
		(net "M_E_CPU0_SB_DQ<6>")
	)
	(segment
		(start 273.94916 -288.285174)
		(end 273.092164 -288.285174)
		(width 0.14478)
		(layer "In6.Cu")
		(net "M_E_CPU0_SB_DQ<6>")
	)
	(segment
		(start 329.155044 -277.870666)
		(end 329.132692 -277.787354)
		(width 0.0889)
		(layer "In6.Cu")
		(net "M_E_CPU0_SB_DQ<6>")
	)
	(segment
		(start 290.249356 -288.710116)
		(end 286.89046 -288.710116)
		(width 0.14478)
		(layer "In6.Cu")
		(net "M_E_CPU0_SB_DQ<6>")
	)
	(segment
		(start 283.908246 -287.859978)
		(end 283.058108 -288.710116)
		(width 0.14478)
		(layer "In6.Cu")
		(net "M_E_CPU0_SB_DQ<6>")
	)
	(segment
		(start 327.308464 -277.813516)
		(end 327.300082 -277.80869)
		(width 0.0889)
		(layer "In6.Cu")
		(net "M_E_CPU0_SB_DQ<6>")
	)
	(segment
		(start 329.00112 -278.136096)
		(end 329.155044 -277.870666)
		(width 0.0889)
		(layer "In6.Cu")
		(net "M_E_CPU0_SB_DQ<6>")
	)
	(segment
		(start 274.488656 -287.97631)
		(end 274.258024 -287.97631)
		(width 0.14478)
		(layer "In6.Cu")
		(net "M_E_CPU0_SB_DQ<6>")
	)
	(arc
		(start 328.814176 -277.813516)
		(mid 328.53122 -277.889693)
		(end 328.248264 -277.813516)
		(width 0.0889)
		(layer "In6.Cu")
		(net "M_E_CPU0_SB_DQ<6>")
	)
	(arc
		(start 327.300082 -277.80869)
		(mid 327.116574 -277.763196)
		(end 326.934322 -277.813516)
		(width 0.0889)
		(layer "In6.Cu")
		(net "M_E_CPU0_SB_DQ<6>")
	)
	(arc
		(start 328.248264 -277.813516)
		(mid 328.066013 -277.763166)
		(end 327.882504 -277.80869)
		(width 0.0889)
		(layer "In6.Cu")
		(net "M_E_CPU0_SB_DQ<6>")
	)
	(arc
		(start 326.934322 -277.813516)
		(mid 326.65987 -277.889752)
		(end 326.383142 -277.822152)
		(width 0.0889)
		(layer "In6.Cu")
		(net "M_E_CPU0_SB_DQ<6>")
	)
	(arc
		(start 329.132692 -277.787354)
		(mid 328.970503 -277.764619)
		(end 328.814176 -277.813516)
		(width 0.0889)
		(layer "In6.Cu")
		(net "M_E_CPU0_SB_DQ<6>")
	)
	(arc
		(start 327.863708 -277.819612)
		(mid 327.585276 -277.88971)
		(end 327.308464 -277.813516)
		(width 0.0889)
		(layer "In6.Cu")
		(net "M_E_CPU0_SB_DQ<6>")
	)
	(arc
		(start 326.36841 -277.813516)
		(mid 326.3076 -277.772841)
		(end 326.252586 -277.724616)
		(width 0.0889)
		(layer "In6.Cu")
		(net "M_E_CPU0_SB_DQ<6>")
	)
	(segment
		(start 331.34808 -277.870158)
		(end 330.880974 -278.136096)
		(width 0.10668)
		(layer "F.Cu")
		(net "M_E_CPU0_SB_DQ<5>")
	)
	(segment
		(start 280.95702 -289.560254)
		(end 280.363422 -289.560254)
		(width 0.14478)
		(layer "In6.Cu")
		(net "M_E_CPU0_SB_DQ<5>")
	)
	(segment
		(start 278.648414 -289.188398)
		(end 278.4856 -289.351212)
		(width 0.14478)
		(layer "In6.Cu")
		(net "M_E_CPU0_SB_DQ<5>")
	)
	(segment
		(start 282.06954 -289.264598)
		(end 281.808936 -289.264598)
		(width 0.14478)
		(layer "In6.Cu")
		(net "M_E_CPU0_SB_DQ<5>")
	)
	(segment
		(start 281.808936 -289.264598)
		(end 281.661108 -289.412426)
		(width 0.14478)
		(layer "In6.Cu")
		(net "M_E_CPU0_SB_DQ<5>")
	)
	(segment
		(start 302.886618 -289.88131)
		(end 302.651414 -289.88131)
		(width 0.14478)
		(layer "In6.Cu")
		(net "M_E_CPU0_SB_DQ<5>")
	)
	(segment
		(start 327.873868 -278.458676)
		(end 327.80986 -278.421338)
		(width 0.0889)
		(layer "In6.Cu")
		(net "M_E_CPU0_SB_DQ<5>")
	)
	(segment
		(start 281.51328 -289.85591)
		(end 281.252676 -289.85591)
		(width 0.14478)
		(layer "In6.Cu")
		(net "M_E_CPU0_SB_DQ<5>")
	)
	(segment
		(start 283.746702 -288.710116)
		(end 282.896564 -289.560254)
		(width 0.14478)
		(layer "In6.Cu")
		(net "M_E_CPU0_SB_DQ<5>")
	)
	(segment
		(start 279.04186 -289.769296)
		(end 279.04186 -289.351212)
		(width 0.14478)
		(layer "In6.Cu")
		(net "M_E_CPU0_SB_DQ<5>")
	)
	(segment
		(start 290.934902 -288.710116)
		(end 289.789108 -289.85591)
		(width 0.14478)
		(layer "In6.Cu")
		(net "M_E_CPU0_SB_DQ<5>")
	)
	(segment
		(start 307.603652 -288.637218)
		(end 307.450998 -288.700464)
		(width 0.14478)
		(layer "In6.Cu")
		(net "M_E_CPU0_SB_DQ<5>")
	)
	(segment
		(start 279.204674 -289.93211)
		(end 279.04186 -289.769296)
		(width 0.14478)
		(layer "In6.Cu")
		(net "M_E_CPU0_SB_DQ<5>")
	)
	(segment
		(start 303.442878 -289.560254)
		(end 303.207674 -289.560254)
		(width 0.14478)
		(layer "In6.Cu")
		(net "M_E_CPU0_SB_DQ<5>")
	)
	(segment
		(start 281.661108 -289.412426)
		(end 281.661108 -289.708082)
		(width 0.14478)
		(layer "In6.Cu")
		(net "M_E_CPU0_SB_DQ<5>")
	)
	(segment
		(start 303.763934 -289.88131)
		(end 303.442878 -289.560254)
		(width 0.14478)
		(layer "In6.Cu")
		(net "M_E_CPU0_SB_DQ<5>")
	)
	(segment
		(start 304.552096 -289.560254)
		(end 304.320194 -289.560254)
		(width 0.14478)
		(layer "In6.Cu")
		(net "M_E_CPU0_SB_DQ<5>")
	)
	(segment
		(start 281.252676 -289.85591)
		(end 280.95702 -289.560254)
		(width 0.14478)
		(layer "In6.Cu")
		(net "M_E_CPU0_SB_DQ<5>")
	)
	(segment
		(start 302.330358 -289.560254)
		(end 301.872396 -289.560254)
		(width 0.14478)
		(layer "In6.Cu")
		(net "M_E_CPU0_SB_DQ<5>")
	)
	(segment
		(start 301.872396 -289.560254)
		(end 301.022258 -288.710116)
		(width 0.14478)
		(layer "In6.Cu")
		(net "M_E_CPU0_SB_DQ<5>")
	)
	(segment
		(start 330.128118 -278.458676)
		(end 330.119736 -278.463502)
		(width 0.0889)
		(layer "In6.Cu")
		(net "M_E_CPU0_SB_DQ<5>")
	)
	(segment
		(start 297.02506 -289.560254)
		(end 296.739056 -289.560254)
		(width 0.14478)
		(layer "In6.Cu")
		(net "M_E_CPU0_SB_DQ<5>")
	)
	(segment
		(start 279.04186 -289.351212)
		(end 278.879046 -289.188398)
		(width 0.14478)
		(layer "In6.Cu")
		(net "M_E_CPU0_SB_DQ<5>")
	)
	(segment
		(start 282.365196 -289.560254)
		(end 282.06954 -289.264598)
		(width 0.14478)
		(layer "In6.Cu")
		(net "M_E_CPU0_SB_DQ<5>")
	)
	(segment
		(start 330.72705 -278.401526)
		(end 330.631038 -278.426926)
		(width 0.0889)
		(layer "In6.Cu")
		(net "M_E_CPU0_SB_DQ<5>")
	)
	(segment
		(start 289.128454 -289.560254)
		(end 287.864042 -289.560254)
		(width 0.14478)
		(layer "In6.Cu")
		(net "M_E_CPU0_SB_DQ<5>")
	)
	(segment
		(start 279.760934 -289.188398)
		(end 279.59812 -289.351212)
		(width 0.14478)
		(layer "In6.Cu")
		(net "M_E_CPU0_SB_DQ<5>")
	)
	(segment
		(start 293.037514 -288.710116)
		(end 290.934902 -288.710116)
		(width 0.14478)
		(layer "In6.Cu")
		(net "M_E_CPU0_SB_DQ<5>")
	)
	(segment
		(start 324.891654 -278.25573)
		(end 324.468744 -277.83282)
		(width 0.0889)
		(layer "In6.Cu")
		(net "M_E_CPU0_SB_DQ<5>")
	)
	(segment
		(start 278.322786 -289.93211)
		(end 277.989284 -289.93211)
		(width 0.14478)
		(layer "In6.Cu")
		(net "M_E_CPU0_SB_DQ<5>")
	)
	(segment
		(start 279.435306 -289.93211)
		(end 279.204674 -289.93211)
		(width 0.14478)
		(layer "In6.Cu")
		(net "M_E_CPU0_SB_DQ<5>")
	)
	(segment
		(start 301.022258 -288.710116)
		(end 298.701714 -288.710116)
		(width 0.14478)
		(layer "In6.Cu")
		(net "M_E_CPU0_SB_DQ<5>")
	)
	(segment
		(start 294.208708 -289.88131)
		(end 293.037514 -288.710116)
		(width 0.14478)
		(layer "In6.Cu")
		(net "M_E_CPU0_SB_DQ<5>")
	)
	(segment
		(start 294.917114 -289.560254)
		(end 294.596058 -289.88131)
		(width 0.14478)
		(layer "In6.Cu")
		(net "M_E_CPU0_SB_DQ<5>")
	)
	(segment
		(start 303.207674 -289.560254)
		(end 302.886618 -289.88131)
		(width 0.14478)
		(layer "In6.Cu")
		(net "M_E_CPU0_SB_DQ<5>")
	)
	(segment
		(start 279.59812 -289.351212)
		(end 279.59812 -289.769296)
		(width 0.14478)
		(layer "In6.Cu")
		(net "M_E_CPU0_SB_DQ<5>")
	)
	(segment
		(start 303.999138 -289.88131)
		(end 303.763934 -289.88131)
		(width 0.14478)
		(layer "In6.Cu")
		(net "M_E_CPU0_SB_DQ<5>")
	)
	(segment
		(start 287.542986 -289.88131)
		(end 287.198308 -289.88131)
		(width 0.14478)
		(layer "In6.Cu")
		(net "M_E_CPU0_SB_DQ<5>")
	)
	(segment
		(start 280.363422 -289.560254)
		(end 279.991566 -289.188398)
		(width 0.14478)
		(layer "In6.Cu")
		(net "M_E_CPU0_SB_DQ<5>")
	)
	(segment
		(start 278.4856 -289.769296)
		(end 278.322786 -289.93211)
		(width 0.14478)
		(layer "In6.Cu")
		(net "M_E_CPU0_SB_DQ<5>")
	)
	(segment
		(start 287.864042 -289.560254)
		(end 287.542986 -289.88131)
		(width 0.14478)
		(layer "In6.Cu")
		(net "M_E_CPU0_SB_DQ<5>")
	)
	(segment
		(start 289.789108 -289.85591)
		(end 289.42411 -289.85591)
		(width 0.14478)
		(layer "In6.Cu")
		(net "M_E_CPU0_SB_DQ<5>")
	)
	(segment
		(start 302.651414 -289.88131)
		(end 302.330358 -289.560254)
		(width 0.14478)
		(layer "In6.Cu")
		(net "M_E_CPU0_SB_DQ<5>")
	)
	(segment
		(start 277.989284 -289.93211)
		(end 277.192232 -289.135058)
		(width 0.14478)
		(layer "In6.Cu")
		(net "M_E_CPU0_SB_DQ<5>")
	)
	(segment
		(start 278.4856 -289.351212)
		(end 278.4856 -289.769296)
		(width 0.14478)
		(layer "In6.Cu")
		(net "M_E_CPU0_SB_DQ<5>")
	)
	(segment
		(start 297.58132 -289.83051)
		(end 297.295316 -289.83051)
		(width 0.14478)
		(layer "In6.Cu")
		(net "M_E_CPU0_SB_DQ<5>")
	)
	(segment
		(start 279.59812 -289.769296)
		(end 279.435306 -289.93211)
		(width 0.14478)
		(layer "In6.Cu")
		(net "M_E_CPU0_SB_DQ<5>")
	)
	(segment
		(start 287.198308 -289.88131)
		(end 286.027114 -288.710116)
		(width 0.14478)
		(layer "In6.Cu")
		(net "M_E_CPU0_SB_DQ<5>")
	)
	(segment
		(start 281.661108 -289.708082)
		(end 281.51328 -289.85591)
		(width 0.14478)
		(layer "In6.Cu")
		(net "M_E_CPU0_SB_DQ<5>")
	)
	(segment
		(start 278.879046 -289.188398)
		(end 278.648414 -289.188398)
		(width 0.14478)
		(layer "In6.Cu")
		(net "M_E_CPU0_SB_DQ<5>")
	)
	(segment
		(start 307.450998 -288.700464)
		(end 305.411886 -288.700464)
		(width 0.14478)
		(layer "In6.Cu")
		(net "M_E_CPU0_SB_DQ<5>")
	)
	(segment
		(start 323.97446 -277.83282)
		(end 318.40805 -277.83282)
		(width 0.14478)
		(layer "In6.Cu")
		(net "M_E_CPU0_SB_DQ<5>")
	)
	(segment
		(start 296.739056 -289.560254)
		(end 296.4688 -289.83051)
		(width 0.14478)
		(layer "In6.Cu")
		(net "M_E_CPU0_SB_DQ<5>")
	)
	(segment
		(start 282.896564 -289.560254)
		(end 282.365196 -289.560254)
		(width 0.14478)
		(layer "In6.Cu")
		(net "M_E_CPU0_SB_DQ<5>")
	)
	(segment
		(start 305.411886 -288.700464)
		(end 304.552096 -289.560254)
		(width 0.14478)
		(layer "In6.Cu")
		(net "M_E_CPU0_SB_DQ<5>")
	)
	(segment
		(start 327.19391 -278.25573)
		(end 324.891654 -278.25573)
		(width 0.0889)
		(layer "In6.Cu")
		(net "M_E_CPU0_SB_DQ<5>")
	)
	(segment
		(start 297.295316 -289.83051)
		(end 297.02506 -289.560254)
		(width 0.14478)
		(layer "In6.Cu")
		(net "M_E_CPU0_SB_DQ<5>")
	)
	(segment
		(start 330.880974 -278.136096)
		(end 330.72705 -278.401526)
		(width 0.0889)
		(layer "In6.Cu")
		(net "M_E_CPU0_SB_DQ<5>")
	)
	(segment
		(start 324.468744 -277.83282)
		(end 323.97446 -277.83282)
		(width 0.0889)
		(layer "In6.Cu")
		(net "M_E_CPU0_SB_DQ<5>")
	)
	(segment
		(start 296.4688 -289.83051)
		(end 296.182796 -289.83051)
		(width 0.14478)
		(layer "In6.Cu")
		(net "M_E_CPU0_SB_DQ<5>")
	)
	(segment
		(start 318.40805 -277.83282)
		(end 307.603652 -288.637218)
		(width 0.14478)
		(layer "In6.Cu")
		(net "M_E_CPU0_SB_DQ<5>")
	)
	(segment
		(start 289.42411 -289.85591)
		(end 289.128454 -289.560254)
		(width 0.14478)
		(layer "In6.Cu")
		(net "M_E_CPU0_SB_DQ<5>")
	)
	(segment
		(start 304.320194 -289.560254)
		(end 303.999138 -289.88131)
		(width 0.14478)
		(layer "In6.Cu")
		(net "M_E_CPU0_SB_DQ<5>")
	)
	(segment
		(start 298.701714 -288.710116)
		(end 297.58132 -289.83051)
		(width 0.14478)
		(layer "In6.Cu")
		(net "M_E_CPU0_SB_DQ<5>")
	)
	(segment
		(start 294.596058 -289.88131)
		(end 294.208708 -289.88131)
		(width 0.14478)
		(layer "In6.Cu")
		(net "M_E_CPU0_SB_DQ<5>")
	)
	(segment
		(start 279.991566 -289.188398)
		(end 279.760934 -289.188398)
		(width 0.14478)
		(layer "In6.Cu")
		(net "M_E_CPU0_SB_DQ<5>")
	)
	(segment
		(start 295.91254 -289.560254)
		(end 294.917114 -289.560254)
		(width 0.14478)
		(layer "In6.Cu")
		(net "M_E_CPU0_SB_DQ<5>")
	)
	(segment
		(start 296.182796 -289.83051)
		(end 295.91254 -289.560254)
		(width 0.14478)
		(layer "In6.Cu")
		(net "M_E_CPU0_SB_DQ<5>")
	)
	(segment
		(start 286.027114 -288.710116)
		(end 283.746702 -288.710116)
		(width 0.14478)
		(layer "In6.Cu")
		(net "M_E_CPU0_SB_DQ<5>")
	)
	(arc
		(start 329.188064 -278.458676)
		(mid 329.00112 -278.508931)
		(end 328.814176 -278.458676)
		(width 0.0889)
		(layer "In6.Cu")
		(net "M_E_CPU0_SB_DQ<5>")
	)
	(arc
		(start 328.248264 -278.458676)
		(mid 328.061066 -278.509058)
		(end 327.873868 -278.458676)
		(width 0.0889)
		(layer "In6.Cu")
		(net "M_E_CPU0_SB_DQ<5>")
	)
	(arc
		(start 329.753976 -278.458676)
		(mid 329.47102 -278.382499)
		(end 329.188064 -278.458676)
		(width 0.0889)
		(layer "In6.Cu")
		(net "M_E_CPU0_SB_DQ<5>")
	)
	(arc
		(start 330.631038 -278.426926)
		(mid 330.37583 -278.383449)
		(end 330.128118 -278.458676)
		(width 0.0889)
		(layer "In6.Cu")
		(net "M_E_CPU0_SB_DQ<5>")
	)
	(arc
		(start 328.814176 -278.458676)
		(mid 328.53122 -278.382499)
		(end 328.248264 -278.458676)
		(width 0.0889)
		(layer "In6.Cu")
		(net "M_E_CPU0_SB_DQ<5>")
	)
	(arc
		(start 327.80986 -278.421338)
		(mid 327.512832 -278.297834)
		(end 327.19391 -278.25573)
		(width 0.0889)
		(layer "In6.Cu")
		(net "M_E_CPU0_SB_DQ<5>")
	)
	(arc
		(start 330.119736 -278.463502)
		(mid 329.936228 -278.508996)
		(end 329.753976 -278.458676)
		(width 0.0889)
		(layer "In6.Cu")
		(net "M_E_CPU0_SB_DQ<5>")
	)
	(segment
		(start 329.937872 -277.060152)
		(end 329.47102 -277.32609)
		(width 0.10668)
		(layer "F.Cu")
		(net "M_E_CPU0_SB_DQ<4>")
	)
	(segment
		(start 282.012644 -288.106612)
		(end 282.012644 -288.014664)
		(width 0.14478)
		(layer "In6.Cu")
		(net "M_E_CPU0_SB_DQ<4>")
	)
	(segment
		(start 278.20239 -287.869884)
		(end 277.767542 -287.435036)
		(width 0.14478)
		(layer "In6.Cu")
		(net "M_E_CPU0_SB_DQ<4>")
	)
	(segment
		(start 287.71977 -287.869884)
		(end 287.435544 -288.15411)
		(width 0.14478)
		(layer "In6.Cu")
		(net "M_E_CPU0_SB_DQ<4>")
	)
	(segment
		(start 304.570892 -288.20491)
		(end 304.34026 -288.20491)
		(width 0.14478)
		(layer "In6.Cu")
		(net "M_E_CPU0_SB_DQ<4>")
	)
	(segment
		(start 302.902112 -287.515554)
		(end 302.67148 -287.515554)
		(width 0.14478)
		(layer "In6.Cu")
		(net "M_E_CPU0_SB_DQ<4>")
	)
	(segment
		(start 288.955734 -288.12871)
		(end 288.667952 -288.12871)
		(width 0.14478)
		(layer "In6.Cu")
		(net "M_E_CPU0_SB_DQ<4>")
	)
	(segment
		(start 297.208194 -287.860232)
		(end 296.945812 -287.860232)
		(width 0.14478)
		(layer "In6.Cu")
		(net "M_E_CPU0_SB_DQ<4>")
	)
	(segment
		(start 304.177446 -287.678368)
		(end 304.014632 -287.515554)
		(width 0.14478)
		(layer "In6.Cu")
		(net "M_E_CPU0_SB_DQ<4>")
	)
	(segment
		(start 294.70477 -287.869884)
		(end 294.395144 -288.17951)
		(width 0.14478)
		(layer "In6.Cu")
		(net "M_E_CPU0_SB_DQ<4>")
	)
	(segment
		(start 324.514718 -277.07971)
		(end 324.358508 -276.9235)
		(width 0.0889)
		(layer "In6.Cu")
		(net "M_E_CPU0_SB_DQ<4>")
	)
	(segment
		(start 307.001418 -286.910272)
		(end 306.856638 -287.055052)
		(width 0.14478)
		(layer "In6.Cu")
		(net "M_E_CPU0_SB_DQ<4>")
	)
	(segment
		(start 325.877174 -277.07971)
		(end 324.514718 -277.07971)
		(width 0.0889)
		(layer "In6.Cu")
		(net "M_E_CPU0_SB_DQ<4>")
	)
	(segment
		(start 282.431744 -288.251392)
		(end 282.157424 -288.251392)
		(width 0.14478)
		(layer "In6.Cu")
		(net "M_E_CPU0_SB_DQ<4>")
	)
	(segment
		(start 307.332888 -286.273494)
		(end 307.001418 -286.604964)
		(width 0.14478)
		(layer "In6.Cu")
		(net "M_E_CPU0_SB_DQ<4>")
	)
	(segment
		(start 289.564572 -287.91281)
		(end 289.171634 -287.91281)
		(width 0.14478)
		(layer "In6.Cu")
		(net "M_E_CPU0_SB_DQ<4>")
	)
	(segment
		(start 326.387206 -277.589742)
		(end 325.877174 -277.07971)
		(width 0.0889)
		(layer "In6.Cu")
		(net "M_E_CPU0_SB_DQ<4>")
	)
	(segment
		(start 289.171634 -287.91281)
		(end 288.955734 -288.12871)
		(width 0.14478)
		(layer "In6.Cu")
		(net "M_E_CPU0_SB_DQ<4>")
	)
	(segment
		(start 282.576524 -288.014664)
		(end 282.576524 -288.106612)
		(width 0.14478)
		(layer "In6.Cu")
		(net "M_E_CPU0_SB_DQ<4>")
	)
	(segment
		(start 308.389782 -285.99257)
		(end 308.52491 -286.318706)
		(width 0.14478)
		(layer "In6.Cu")
		(net "M_E_CPU0_SB_DQ<4>")
	)
	(segment
		(start 294.041322 -288.17951)
		(end 292.881558 -287.019746)
		(width 0.14478)
		(layer "In6.Cu")
		(net "M_E_CPU0_SB_DQ<4>")
	)
	(segment
		(start 298.917106 -287.019746)
		(end 297.782742 -288.15411)
		(width 0.14478)
		(layer "In6.Cu")
		(net "M_E_CPU0_SB_DQ<4>")
	)
	(segment
		(start 302.11522 -288.20491)
		(end 301.770542 -287.860232)
		(width 0.14478)
		(layer "In6.Cu")
		(net "M_E_CPU0_SB_DQ<4>")
	)
	(segment
		(start 327.404476 -277.64867)
		(end 327.394062 -277.642574)
		(width 0.0889)
		(layer "In6.Cu")
		(net "M_E_CPU0_SB_DQ<4>")
	)
	(segment
		(start 297.502072 -288.15411)
		(end 297.208194 -287.860232)
		(width 0.14478)
		(layer "In6.Cu")
		(net "M_E_CPU0_SB_DQ<4>")
	)
	(segment
		(start 296.105326 -287.869884)
		(end 294.70477 -287.869884)
		(width 0.14478)
		(layer "In6.Cu")
		(net "M_E_CPU0_SB_DQ<4>")
	)
	(segment
		(start 303.064926 -288.042096)
		(end 303.064926 -287.678368)
		(width 0.14478)
		(layer "In6.Cu")
		(net "M_E_CPU0_SB_DQ<4>")
	)
	(segment
		(start 317.996824 -276.9235)
		(end 309.575962 -285.344362)
		(width 0.14478)
		(layer "In6.Cu")
		(net "M_E_CPU0_SB_DQ<4>")
	)
	(segment
		(start 306.856638 -287.055052)
		(end 305.72075 -287.055052)
		(width 0.14478)
		(layer "In6.Cu")
		(net "M_E_CPU0_SB_DQ<4>")
	)
	(segment
		(start 302.508666 -288.042096)
		(end 302.345852 -288.20491)
		(width 0.14478)
		(layer "In6.Cu")
		(net "M_E_CPU0_SB_DQ<4>")
	)
	(segment
		(start 296.945812 -287.860232)
		(end 296.651934 -288.15411)
		(width 0.14478)
		(layer "In6.Cu")
		(net "M_E_CPU0_SB_DQ<4>")
	)
	(segment
		(start 285.94939 -287.019746)
		(end 283.963618 -287.019746)
		(width 0.14478)
		(layer "In6.Cu")
		(net "M_E_CPU0_SB_DQ<4>")
	)
	(segment
		(start 304.177446 -288.042096)
		(end 304.177446 -287.678368)
		(width 0.14478)
		(layer "In6.Cu")
		(net "M_E_CPU0_SB_DQ<4>")
	)
	(segment
		(start 304.34026 -288.20491)
		(end 304.177446 -288.042096)
		(width 0.14478)
		(layer "In6.Cu")
		(net "M_E_CPU0_SB_DQ<4>")
	)
	(segment
		(start 277.767542 -287.435036)
		(end 277.192232 -287.435036)
		(width 0.14478)
		(layer "In6.Cu")
		(net "M_E_CPU0_SB_DQ<4>")
	)
	(segment
		(start 288.667952 -288.12871)
		(end 288.409126 -287.869884)
		(width 0.14478)
		(layer "In6.Cu")
		(net "M_E_CPU0_SB_DQ<4>")
	)
	(segment
		(start 304.014632 -287.515554)
		(end 303.784 -287.515554)
		(width 0.14478)
		(layer "In6.Cu")
		(net "M_E_CPU0_SB_DQ<4>")
	)
	(segment
		(start 288.409126 -287.869884)
		(end 287.71977 -287.869884)
		(width 0.14478)
		(layer "In6.Cu")
		(net "M_E_CPU0_SB_DQ<4>")
	)
	(segment
		(start 303.458372 -288.20491)
		(end 303.22774 -288.20491)
		(width 0.14478)
		(layer "In6.Cu")
		(net "M_E_CPU0_SB_DQ<4>")
	)
	(segment
		(start 303.784 -287.515554)
		(end 303.621186 -287.678368)
		(width 0.14478)
		(layer "In6.Cu")
		(net "M_E_CPU0_SB_DQ<4>")
	)
	(segment
		(start 303.064926 -287.678368)
		(end 302.902112 -287.515554)
		(width 0.14478)
		(layer "In6.Cu")
		(net "M_E_CPU0_SB_DQ<4>")
	)
	(segment
		(start 303.621186 -287.678368)
		(end 303.621186 -288.042096)
		(width 0.14478)
		(layer "In6.Cu")
		(net "M_E_CPU0_SB_DQ<4>")
	)
	(segment
		(start 326.476106 -277.655528)
		(end 326.464422 -277.64867)
		(width 0.0889)
		(layer "In6.Cu")
		(net "M_E_CPU0_SB_DQ<4>")
	)
	(segment
		(start 287.435544 -288.15411)
		(end 287.083754 -288.15411)
		(width 0.14478)
		(layer "In6.Cu")
		(net "M_E_CPU0_SB_DQ<4>")
	)
	(segment
		(start 328.718164 -277.64867)
		(end 328.709782 -277.653496)
		(width 0.0889)
		(layer "In6.Cu")
		(net "M_E_CPU0_SB_DQ<4>")
	)
	(segment
		(start 326.38746 -277.589742)
		(end 326.387206 -277.589742)
		(width 0.0889)
		(layer "In6.Cu")
		(net "M_E_CPU0_SB_DQ<4>")
	)
	(segment
		(start 302.508666 -287.678368)
		(end 302.508666 -288.042096)
		(width 0.14478)
		(layer "In6.Cu")
		(net "M_E_CPU0_SB_DQ<4>")
	)
	(segment
		(start 323.897244 -276.9235)
		(end 317.996824 -276.9235)
		(width 0.14478)
		(layer "In6.Cu")
		(net "M_E_CPU0_SB_DQ<4>")
	)
	(segment
		(start 279.666954 -287.869884)
		(end 279.387046 -288.149792)
		(width 0.14478)
		(layer "In6.Cu")
		(net "M_E_CPU0_SB_DQ<4>")
	)
	(segment
		(start 287.083754 -288.15411)
		(end 285.94939 -287.019746)
		(width 0.14478)
		(layer "In6.Cu")
		(net "M_E_CPU0_SB_DQ<4>")
	)
	(segment
		(start 308.192678 -286.612838)
		(end 308.003702 -286.534606)
		(width 0.14478)
		(layer "In6.Cu")
		(net "M_E_CPU0_SB_DQ<4>")
	)
	(segment
		(start 289.780472 -288.12871)
		(end 289.564572 -287.91281)
		(width 0.14478)
		(layer "In6.Cu")
		(net "M_E_CPU0_SB_DQ<4>")
	)
	(segment
		(start 283.11348 -287.869884)
		(end 282.721304 -287.869884)
		(width 0.14478)
		(layer "In6.Cu")
		(net "M_E_CPU0_SB_DQ<4>")
	)
	(segment
		(start 303.22774 -288.20491)
		(end 303.064926 -288.042096)
		(width 0.14478)
		(layer "In6.Cu")
		(net "M_E_CPU0_SB_DQ<4>")
	)
	(segment
		(start 327.788778 -277.642574)
		(end 327.778364 -277.64867)
		(width 0.0889)
		(layer "In6.Cu")
		(net "M_E_CPU0_SB_DQ<4>")
	)
	(segment
		(start 308.52491 -286.318706)
		(end 308.446678 -286.507682)
		(width 0.14478)
		(layer "In6.Cu")
		(net "M_E_CPU0_SB_DQ<4>")
	)
	(segment
		(start 282.012644 -288.014664)
		(end 281.867864 -287.869884)
		(width 0.14478)
		(layer "In6.Cu")
		(net "M_E_CPU0_SB_DQ<4>")
	)
	(segment
		(start 279.103074 -288.149792)
		(end 278.823166 -287.869884)
		(width 0.14478)
		(layer "In6.Cu")
		(net "M_E_CPU0_SB_DQ<4>")
	)
	(segment
		(start 307.679598 -286.129984)
		(end 307.332888 -286.273494)
		(width 0.14478)
		(layer "In6.Cu")
		(net "M_E_CPU0_SB_DQ<4>")
	)
	(segment
		(start 308.468014 -285.803594)
		(end 308.389782 -285.99257)
		(width 0.14478)
		(layer "In6.Cu")
		(net "M_E_CPU0_SB_DQ<4>")
	)
	(segment
		(start 305.72075 -287.055052)
		(end 304.570892 -288.20491)
		(width 0.14478)
		(layer "In6.Cu")
		(net "M_E_CPU0_SB_DQ<4>")
	)
	(segment
		(start 281.867864 -287.869884)
		(end 279.666954 -287.869884)
		(width 0.14478)
		(layer "In6.Cu")
		(net "M_E_CPU0_SB_DQ<4>")
	)
	(segment
		(start 282.576524 -288.106612)
		(end 282.431744 -288.251392)
		(width 0.14478)
		(layer "In6.Cu")
		(net "M_E_CPU0_SB_DQ<4>")
	)
	(segment
		(start 302.345852 -288.20491)
		(end 302.11522 -288.20491)
		(width 0.14478)
		(layer "In6.Cu")
		(net "M_E_CPU0_SB_DQ<4>")
	)
	(segment
		(start 324.358508 -276.9235)
		(end 323.897244 -276.9235)
		(width 0.0889)
		(layer "In6.Cu")
		(net "M_E_CPU0_SB_DQ<4>")
	)
	(segment
		(start 296.651934 -288.15411)
		(end 296.389552 -288.15411)
		(width 0.14478)
		(layer "In6.Cu")
		(net "M_E_CPU0_SB_DQ<4>")
	)
	(segment
		(start 279.387046 -288.149792)
		(end 279.103074 -288.149792)
		(width 0.14478)
		(layer "In6.Cu")
		(net "M_E_CPU0_SB_DQ<4>")
	)
	(segment
		(start 307.001418 -286.604964)
		(end 307.001418 -286.910272)
		(width 0.14478)
		(layer "In6.Cu")
		(net "M_E_CPU0_SB_DQ<4>")
	)
	(segment
		(start 300.618398 -287.019746)
		(end 298.917106 -287.019746)
		(width 0.14478)
		(layer "In6.Cu")
		(net "M_E_CPU0_SB_DQ<4>")
	)
	(segment
		(start 292.881558 -287.019746)
		(end 291.177218 -287.019746)
		(width 0.14478)
		(layer "In6.Cu")
		(net "M_E_CPU0_SB_DQ<4>")
	)
	(segment
		(start 290.068254 -288.12871)
		(end 289.780472 -288.12871)
		(width 0.14478)
		(layer "In6.Cu")
		(net "M_E_CPU0_SB_DQ<4>")
	)
	(segment
		(start 308.446678 -286.507682)
		(end 308.192678 -286.612838)
		(width 0.14478)
		(layer "In6.Cu")
		(net "M_E_CPU0_SB_DQ<4>")
	)
	(segment
		(start 283.963618 -287.019746)
		(end 283.11348 -287.869884)
		(width 0.14478)
		(layer "In6.Cu")
		(net "M_E_CPU0_SB_DQ<4>")
	)
	(segment
		(start 302.67148 -287.515554)
		(end 302.508666 -287.678368)
		(width 0.14478)
		(layer "In6.Cu")
		(net "M_E_CPU0_SB_DQ<4>")
	)
	(segment
		(start 278.823166 -287.869884)
		(end 278.20239 -287.869884)
		(width 0.14478)
		(layer "In6.Cu")
		(net "M_E_CPU0_SB_DQ<4>")
	)
	(segment
		(start 301.458884 -287.860232)
		(end 300.618398 -287.019746)
		(width 0.14478)
		(layer "In6.Cu")
		(net "M_E_CPU0_SB_DQ<4>")
	)
	(segment
		(start 294.395144 -288.17951)
		(end 294.041322 -288.17951)
		(width 0.14478)
		(layer "In6.Cu")
		(net "M_E_CPU0_SB_DQ<4>")
	)
	(segment
		(start 301.770542 -287.860232)
		(end 301.458884 -287.860232)
		(width 0.14478)
		(layer "In6.Cu")
		(net "M_E_CPU0_SB_DQ<4>")
	)
	(segment
		(start 308.003702 -286.534606)
		(end 307.868574 -286.20847)
		(width 0.14478)
		(layer "In6.Cu")
		(net "M_E_CPU0_SB_DQ<4>")
	)
	(segment
		(start 282.721304 -287.869884)
		(end 282.576524 -288.014664)
		(width 0.14478)
		(layer "In6.Cu")
		(net "M_E_CPU0_SB_DQ<4>")
	)
	(segment
		(start 309.575962 -285.344362)
		(end 308.468014 -285.803594)
		(width 0.14478)
		(layer "In6.Cu")
		(net "M_E_CPU0_SB_DQ<4>")
	)
	(segment
		(start 291.177218 -287.019746)
		(end 290.068254 -288.12871)
		(width 0.14478)
		(layer "In6.Cu")
		(net "M_E_CPU0_SB_DQ<4>")
	)
	(segment
		(start 307.868574 -286.20847)
		(end 307.679598 -286.129984)
		(width 0.14478)
		(layer "In6.Cu")
		(net "M_E_CPU0_SB_DQ<4>")
	)
	(segment
		(start 297.782742 -288.15411)
		(end 297.502072 -288.15411)
		(width 0.14478)
		(layer "In6.Cu")
		(net "M_E_CPU0_SB_DQ<4>")
	)
	(segment
		(start 329.47102 -277.32609)
		(end 329.317096 -277.59152)
		(width 0.0889)
		(layer "In6.Cu")
		(net "M_E_CPU0_SB_DQ<4>")
	)
	(segment
		(start 329.317096 -277.59152)
		(end 329.221084 -277.61692)
		(width 0.0889)
		(layer "In6.Cu")
		(net "M_E_CPU0_SB_DQ<4>")
	)
	(segment
		(start 296.389552 -288.15411)
		(end 296.105326 -287.869884)
		(width 0.14478)
		(layer "In6.Cu")
		(net "M_E_CPU0_SB_DQ<4>")
	)
	(segment
		(start 282.157424 -288.251392)
		(end 282.012644 -288.106612)
		(width 0.14478)
		(layer "In6.Cu")
		(net "M_E_CPU0_SB_DQ<4>")
	)
	(segment
		(start 303.621186 -288.042096)
		(end 303.458372 -288.20491)
		(width 0.14478)
		(layer "In6.Cu")
		(net "M_E_CPU0_SB_DQ<4>")
	)
	(arc
		(start 328.344022 -277.64867)
		(mid 328.067209 -277.572527)
		(end 327.788778 -277.642574)
		(width 0.0889)
		(layer "In6.Cu")
		(net "M_E_CPU0_SB_DQ<4>")
	)
	(arc
		(start 327.394062 -277.642574)
		(mid 327.115376 -277.572354)
		(end 326.83831 -277.64867)
		(width 0.0889)
		(layer "In6.Cu")
		(net "M_E_CPU0_SB_DQ<4>")
	)
	(arc
		(start 328.709782 -277.653496)
		(mid 328.526274 -277.69899)
		(end 328.344022 -277.64867)
		(width 0.0889)
		(layer "In6.Cu")
		(net "M_E_CPU0_SB_DQ<4>")
	)
	(arc
		(start 326.83831 -277.64867)
		(mid 326.658105 -277.698987)
		(end 326.476106 -277.655528)
		(width 0.0889)
		(layer "In6.Cu")
		(net "M_E_CPU0_SB_DQ<4>")
	)
	(arc
		(start 329.221084 -277.61692)
		(mid 328.965876 -277.573443)
		(end 328.718164 -277.64867)
		(width 0.0889)
		(layer "In6.Cu")
		(net "M_E_CPU0_SB_DQ<4>")
	)
	(arc
		(start 326.464422 -277.64867)
		(mid 326.424019 -277.621716)
		(end 326.38746 -277.589742)
		(width 0.0889)
		(layer "In6.Cu")
		(net "M_E_CPU0_SB_DQ<4>")
	)
	(arc
		(start 327.778364 -277.64867)
		(mid 327.59142 -277.698925)
		(end 327.404476 -277.64867)
		(width 0.0889)
		(layer "In6.Cu")
		(net "M_E_CPU0_SB_DQ<4>")
	)
	(segment
		(start 330.877926 -275.44014)
		(end 330.411074 -275.706078)
		(width 0.10668)
		(layer "F.Cu")
		(net "M_E_CPU0_SB_DQ<3>")
	)
	(segment
		(start 328.718164 -275.383498)
		(end 328.709782 -275.378672)
		(width 0.0889)
		(layer "In6.Cu")
		(net "M_E_CPU0_SB_DQ<3>")
	)
	(segment
		(start 297.660314 -283.600398)
		(end 296.81043 -284.450282)
		(width 0.14478)
		(layer "In6.Cu")
		(net "M_E_CPU0_SB_DQ<3>")
	)
	(segment
		(start 330.411074 -275.706078)
		(end 330.564998 -275.440648)
		(width 0.0889)
		(layer "In6.Cu")
		(net "M_E_CPU0_SB_DQ<3>")
	)
	(segment
		(start 314.666884 -274.58416)
		(end 313.908948 -275.342096)
		(width 0.14478)
		(layer "In6.Cu")
		(net "M_E_CPU0_SB_DQ<3>")
	)
	(segment
		(start 274.054062 -284.034992)
		(end 273.092164 -284.034992)
		(width 0.14478)
		(layer "In6.Cu")
		(net "M_E_CPU0_SB_DQ<3>")
	)
	(segment
		(start 294.048942 -284.057598)
		(end 292.945312 -283.600398)
		(width 0.14478)
		(layer "In6.Cu")
		(net "M_E_CPU0_SB_DQ<3>")
	)
	(segment
		(start 304.183796 -284.460188)
		(end 301.856648 -284.460188)
		(width 0.14478)
		(layer "In6.Cu")
		(net "M_E_CPU0_SB_DQ<3>")
	)
	(segment
		(start 324.412864 -274.58416)
		(end 314.666884 -274.58416)
		(width 0.14478)
		(layer "In6.Cu")
		(net "M_E_CPU0_SB_DQ<3>")
	)
	(segment
		(start 313.908948 -275.342096)
		(end 313.384438 -276.608286)
		(width 0.14478)
		(layer "In6.Cu")
		(net "M_E_CPU0_SB_DQ<3>")
	)
	(segment
		(start 326.292718 -275.288502)
		(end 325.239126 -274.23491)
		(width 0.0889)
		(layer "In6.Cu")
		(net "M_E_CPU0_SB_DQ<3>")
	)
	(segment
		(start 329.292458 -275.378672)
		(end 329.284076 -275.383498)
		(width 0.0889)
		(layer "In6.Cu")
		(net "M_E_CPU0_SB_DQ<3>")
	)
	(segment
		(start 327.533762 -275.288502)
		(end 326.292718 -275.288502)
		(width 0.0889)
		(layer "In6.Cu")
		(net "M_E_CPU0_SB_DQ<3>")
	)
	(segment
		(start 301.856648 -284.460188)
		(end 301.352458 -283.955998)
		(width 0.14478)
		(layer "In6.Cu")
		(net "M_E_CPU0_SB_DQ<3>")
	)
	(segment
		(start 325.239126 -274.23491)
		(end 324.762114 -274.23491)
		(width 0.0889)
		(layer "In6.Cu")
		(net "M_E_CPU0_SB_DQ<3>")
	)
	(segment
		(start 300.493684 -283.600398)
		(end 297.660314 -283.600398)
		(width 0.14478)
		(layer "In6.Cu")
		(net "M_E_CPU0_SB_DQ<3>")
	)
	(segment
		(start 330.564998 -275.440648)
		(end 330.542646 -275.357336)
		(width 0.0889)
		(layer "In6.Cu")
		(net "M_E_CPU0_SB_DQ<3>")
	)
	(segment
		(start 296.81043 -284.450282)
		(end 294.441626 -284.450282)
		(width 0.14478)
		(layer "In6.Cu")
		(net "M_E_CPU0_SB_DQ<3>")
	)
	(segment
		(start 283.014674 -283.600398)
		(end 282.16479 -284.450282)
		(width 0.14478)
		(layer "In6.Cu")
		(net "M_E_CPU0_SB_DQ<3>")
	)
	(segment
		(start 324.762114 -274.23491)
		(end 324.412864 -274.58416)
		(width 0.0889)
		(layer "In6.Cu")
		(net "M_E_CPU0_SB_DQ<3>")
	)
	(segment
		(start 294.441626 -284.450282)
		(end 294.048942 -284.057598)
		(width 0.14478)
		(layer "In6.Cu")
		(net "M_E_CPU0_SB_DQ<3>")
	)
	(segment
		(start 282.16479 -284.450282)
		(end 275.056854 -284.450282)
		(width 0.14478)
		(layer "In6.Cu")
		(net "M_E_CPU0_SB_DQ<3>")
	)
	(segment
		(start 310.639206 -279.70607)
		(end 309.585868 -280.759408)
		(width 0.14478)
		(layer "In6.Cu")
		(net "M_E_CPU0_SB_DQ<3>")
	)
	(segment
		(start 301.352458 -283.955998)
		(end 300.493684 -283.600398)
		(width 0.14478)
		(layer "In6.Cu")
		(net "M_E_CPU0_SB_DQ<3>")
	)
	(segment
		(start 305.702716 -283.61005)
		(end 304.56124 -284.082744)
		(width 0.14478)
		(layer "In6.Cu")
		(net "M_E_CPU0_SB_DQ<3>")
	)
	(segment
		(start 310.639206 -279.353518)
		(end 310.639206 -279.70607)
		(width 0.14478)
		(layer "In6.Cu")
		(net "M_E_CPU0_SB_DQ<3>")
	)
	(segment
		(start 313.384438 -276.608286)
		(end 310.639206 -279.353518)
		(width 0.14478)
		(layer "In6.Cu")
		(net "M_E_CPU0_SB_DQ<3>")
	)
	(segment
		(start 292.945312 -283.600398)
		(end 290.583874 -283.600398)
		(width 0.14478)
		(layer "In6.Cu")
		(net "M_E_CPU0_SB_DQ<3>")
	)
	(segment
		(start 307.892196 -283.30525)
		(end 307.156104 -283.61005)
		(width 0.14478)
		(layer "In6.Cu")
		(net "M_E_CPU0_SB_DQ<3>")
	)
	(segment
		(start 307.156104 -283.61005)
		(end 305.702716 -283.61005)
		(width 0.14478)
		(layer "In6.Cu")
		(net "M_E_CPU0_SB_DQ<3>")
	)
	(segment
		(start 309.585868 -280.759408)
		(end 309.585868 -281.611578)
		(width 0.14478)
		(layer "In6.Cu")
		(net "M_E_CPU0_SB_DQ<3>")
	)
	(segment
		(start 289.73399 -284.450282)
		(end 286.872426 -284.450282)
		(width 0.14478)
		(layer "In6.Cu")
		(net "M_E_CPU0_SB_DQ<3>")
	)
	(segment
		(start 304.56124 -284.082744)
		(end 304.183796 -284.460188)
		(width 0.14478)
		(layer "In6.Cu")
		(net "M_E_CPU0_SB_DQ<3>")
	)
	(segment
		(start 275.056854 -284.450282)
		(end 274.054062 -284.034992)
		(width 0.14478)
		(layer "In6.Cu")
		(net "M_E_CPU0_SB_DQ<3>")
	)
	(segment
		(start 286.872426 -284.450282)
		(end 286.542988 -284.120844)
		(width 0.14478)
		(layer "In6.Cu")
		(net "M_E_CPU0_SB_DQ<3>")
	)
	(segment
		(start 309.585868 -281.611578)
		(end 307.892196 -283.30525)
		(width 0.14478)
		(layer "In6.Cu")
		(net "M_E_CPU0_SB_DQ<3>")
	)
	(segment
		(start 285.286704 -283.600398)
		(end 283.014674 -283.600398)
		(width 0.14478)
		(layer "In6.Cu")
		(net "M_E_CPU0_SB_DQ<3>")
	)
	(segment
		(start 290.583874 -283.600398)
		(end 289.73399 -284.450282)
		(width 0.14478)
		(layer "In6.Cu")
		(net "M_E_CPU0_SB_DQ<3>")
	)
	(segment
		(start 286.542988 -284.120844)
		(end 285.286704 -283.600398)
		(width 0.14478)
		(layer "In6.Cu")
		(net "M_E_CPU0_SB_DQ<3>")
	)
	(arc
		(start 330.542646 -275.357336)
		(mid 330.380457 -275.334601)
		(end 330.22413 -275.383498)
		(width 0.0889)
		(layer "In6.Cu")
		(net "M_E_CPU0_SB_DQ<3>")
	)
	(arc
		(start 328.344022 -275.383498)
		(mid 328.061066 -275.459675)
		(end 327.77811 -275.383498)
		(width 0.0889)
		(layer "In6.Cu")
		(net "M_E_CPU0_SB_DQ<3>")
	)
	(arc
		(start 327.77811 -275.383498)
		(mid 327.701051 -275.342014)
		(end 327.621392 -275.305774)
		(width 0.0889)
		(layer "In6.Cu")
		(net "M_E_CPU0_SB_DQ<3>")
	)
	(arc
		(start 327.621392 -275.305774)
		(mid 327.578432 -275.292797)
		(end 327.533762 -275.288502)
		(width 0.0889)
		(layer "In6.Cu")
		(net "M_E_CPU0_SB_DQ<3>")
	)
	(arc
		(start 329.284076 -275.383498)
		(mid 329.00112 -275.459675)
		(end 328.718164 -275.383498)
		(width 0.0889)
		(layer "In6.Cu")
		(net "M_E_CPU0_SB_DQ<3>")
	)
	(arc
		(start 328.709782 -275.378672)
		(mid 328.526274 -275.333178)
		(end 328.344022 -275.383498)
		(width 0.0889)
		(layer "In6.Cu")
		(net "M_E_CPU0_SB_DQ<3>")
	)
	(arc
		(start 329.658218 -275.383498)
		(mid 329.475967 -275.333148)
		(end 329.292458 -275.378672)
		(width 0.0889)
		(layer "In6.Cu")
		(net "M_E_CPU0_SB_DQ<3>")
	)
	(arc
		(start 330.22413 -275.383498)
		(mid 329.941174 -275.459675)
		(end 329.658218 -275.383498)
		(width 0.0889)
		(layer "In6.Cu")
		(net "M_E_CPU0_SB_DQ<3>")
	)
	(segment
		(start 330.877926 -293.260018)
		(end 330.411074 -293.525956)
		(width 0.10668)
		(layer "F.Cu")
		(net "M_E_CPU0_SB_DQ<31>")
	)
	(segment
		(start 330.22413 -293.203376)
		(end 330.221336 -293.205154)
		(width 0.0889)
		(layer "In6.Cu")
		(net "M_E_CPU0_SB_DQ<31>")
	)
	(segment
		(start 274.411694 -317.64351)
		(end 274.020026 -318.035178)
		(width 0.14478)
		(layer "In6.Cu")
		(net "M_E_CPU0_SB_DQ<31>")
	)
	(segment
		(start 329.793092 -293.990522)
		(end 329.753976 -294.013382)
		(width 0.0889)
		(layer "In6.Cu")
		(net "M_E_CPU0_SB_DQ<31>")
	)
	(segment
		(start 307.6321 -317.585852)
		(end 307.128418 -317.585852)
		(width 0.14478)
		(layer "In6.Cu")
		(net "M_E_CPU0_SB_DQ<31>")
	)
	(segment
		(start 307.128418 -317.585852)
		(end 306.25415 -318.46012)
		(width 0.14478)
		(layer "In6.Cu")
		(net "M_E_CPU0_SB_DQ<31>")
	)
	(segment
		(start 314.616338 -310.17972)
		(end 314.616338 -310.601614)
		(width 0.14478)
		(layer "In6.Cu")
		(net "M_E_CPU0_SB_DQ<31>")
	)
	(segment
		(start 274.80514 -317.806324)
		(end 274.642326 -317.64351)
		(width 0.14478)
		(layer "In6.Cu")
		(net "M_E_CPU0_SB_DQ<31>")
	)
	(segment
		(start 330.564998 -293.260526)
		(end 330.542646 -293.177214)
		(width 0.0889)
		(layer "In6.Cu")
		(net "M_E_CPU0_SB_DQ<31>")
	)
	(segment
		(start 329.323192 -294.800528)
		(end 329.284076 -294.823388)
		(width 0.0889)
		(layer "In6.Cu")
		(net "M_E_CPU0_SB_DQ<31>")
	)
	(segment
		(start 330.411074 -293.525956)
		(end 330.564998 -293.260526)
		(width 0.0889)
		(layer "In6.Cu")
		(net "M_E_CPU0_SB_DQ<31>")
	)
	(segment
		(start 328.512932 -296.283126)
		(end 328.34707 -296.448988)
		(width 0.0889)
		(layer "In6.Cu")
		(net "M_E_CPU0_SB_DQ<31>")
	)
	(segment
		(start 274.642326 -317.64351)
		(end 274.411694 -317.64351)
		(width 0.14478)
		(layer "In6.Cu")
		(net "M_E_CPU0_SB_DQ<31>")
	)
	(segment
		(start 274.967954 -318.46012)
		(end 274.80514 -318.297306)
		(width 0.14478)
		(layer "In6.Cu")
		(net "M_E_CPU0_SB_DQ<31>")
	)
	(segment
		(start 328.34707 -296.448988)
		(end 314.616338 -310.17972)
		(width 0.14478)
		(layer "In6.Cu")
		(net "M_E_CPU0_SB_DQ<31>")
	)
	(segment
		(start 274.80514 -318.297306)
		(end 274.80514 -317.806324)
		(width 0.14478)
		(layer "In6.Cu")
		(net "M_E_CPU0_SB_DQ<31>")
	)
	(segment
		(start 328.65949 -295.833546)
		(end 328.65949 -295.92905)
		(width 0.0889)
		(layer "In6.Cu")
		(net "M_E_CPU0_SB_DQ<31>")
	)
	(segment
		(start 329.753976 -294.013382)
		(end 329.723496 -294.031162)
		(width 0.0889)
		(layer "In6.Cu")
		(net "M_E_CPU0_SB_DQ<31>")
	)
	(segment
		(start 306.25415 -318.46012)
		(end 274.967954 -318.46012)
		(width 0.14478)
		(layer "In6.Cu")
		(net "M_E_CPU0_SB_DQ<31>")
	)
	(segment
		(start 314.616338 -310.601614)
		(end 307.6321 -317.585852)
		(width 0.14478)
		(layer "In6.Cu")
		(net "M_E_CPU0_SB_DQ<31>")
	)
	(segment
		(start 328.948288 -295.507918)
		(end 328.685652 -295.770554)
		(width 0.0889)
		(layer "In6.Cu")
		(net "M_E_CPU0_SB_DQ<31>")
	)
	(segment
		(start 274.020026 -318.035178)
		(end 273.092164 -318.035178)
		(width 0.14478)
		(layer "In6.Cu")
		(net "M_E_CPU0_SB_DQ<31>")
	)
	(arc
		(start 330.542646 -293.177214)
		(mid 330.380457 -293.154479)
		(end 330.22413 -293.203376)
		(width 0.0889)
		(layer "In6.Cu")
		(net "M_E_CPU0_SB_DQ<31>")
	)
	(arc
		(start 330.036424 -293.525956)
		(mid 329.971909 -293.788175)
		(end 329.793092 -293.990522)
		(width 0.0889)
		(layer "In6.Cu")
		(net "M_E_CPU0_SB_DQ<31>")
	)
	(arc
		(start 328.685652 -295.770554)
		(mid 328.666341 -295.799455)
		(end 328.65949 -295.833546)
		(width 0.0889)
		(layer "In6.Cu")
		(net "M_E_CPU0_SB_DQ<31>")
	)
	(arc
		(start 329.284076 -294.823388)
		(mid 329.243811 -294.850363)
		(end 329.207368 -294.882316)
		(width 0.0889)
		(layer "In6.Cu")
		(net "M_E_CPU0_SB_DQ<31>")
	)
	(arc
		(start 329.207368 -294.882316)
		(mid 329.12989 -294.99827)
		(end 329.10272 -295.135046)
		(width 0.0889)
		(layer "In6.Cu")
		(net "M_E_CPU0_SB_DQ<31>")
	)
	(arc
		(start 329.566524 -294.335962)
		(mid 329.502009 -294.598181)
		(end 329.323192 -294.800528)
		(width 0.0889)
		(layer "In6.Cu")
		(net "M_E_CPU0_SB_DQ<31>")
	)
	(arc
		(start 330.221336 -293.205154)
		(mid 330.085999 -293.34083)
		(end 330.036424 -293.525956)
		(width 0.0889)
		(layer "In6.Cu")
		(net "M_E_CPU0_SB_DQ<31>")
	)
	(arc
		(start 329.10272 -295.135046)
		(mid 329.062581 -295.336837)
		(end 328.948288 -295.507918)
		(width 0.0889)
		(layer "In6.Cu")
		(net "M_E_CPU0_SB_DQ<31>")
	)
	(arc
		(start 328.65949 -295.92905)
		(mid 328.621397 -296.120649)
		(end 328.512932 -296.283126)
		(width 0.0889)
		(layer "In6.Cu")
		(net "M_E_CPU0_SB_DQ<31>")
	)
	(arc
		(start 329.723496 -294.031162)
		(mid 329.608069 -294.164538)
		(end 329.566524 -294.335962)
		(width 0.0889)
		(layer "In6.Cu")
		(net "M_E_CPU0_SB_DQ<31>")
	)
	(segment
		(start 329.467972 -292.450012)
		(end 329.00112 -292.71595)
		(width 0.10668)
		(layer "F.Cu")
		(net "M_E_CPU0_SB_DQ<30>")
	)
	(segment
		(start 328.344022 -293.203376)
		(end 328.341482 -293.2049)
		(width 0.0889)
		(layer "In6.Cu")
		(net "M_E_CPU0_SB_DQ<30>")
	)
	(segment
		(start 326.549004 -296.009314)
		(end 313.458098 -309.10022)
		(width 0.14478)
		(layer "In6.Cu")
		(net "M_E_CPU0_SB_DQ<30>")
	)
	(segment
		(start 313.458098 -310.473598)
		(end 308.291484 -315.640212)
		(width 0.14478)
		(layer "In6.Cu")
		(net "M_E_CPU0_SB_DQ<30>")
	)
	(segment
		(start 274.941538 -316.190376)
		(end 274.796758 -316.335156)
		(width 0.14478)
		(layer "In6.Cu")
		(net "M_E_CPU0_SB_DQ<30>")
	)
	(segment
		(start 327.913238 -293.990522)
		(end 327.874122 -294.013382)
		(width 0.0889)
		(layer "In6.Cu")
		(net "M_E_CPU0_SB_DQ<30>")
	)
	(segment
		(start 329.00112 -292.71595)
		(end 329.155044 -292.45052)
		(width 0.0889)
		(layer "In6.Cu")
		(net "M_E_CPU0_SB_DQ<30>")
	)
	(segment
		(start 274.941538 -315.494924)
		(end 274.941538 -316.190376)
		(width 0.14478)
		(layer "In6.Cu")
		(net "M_E_CPU0_SB_DQ<30>")
	)
	(segment
		(start 306.998878 -315.640212)
		(end 305.878992 -316.760098)
		(width 0.14478)
		(layer "In6.Cu")
		(net "M_E_CPU0_SB_DQ<30>")
	)
	(segment
		(start 275.497798 -315.494924)
		(end 275.334984 -315.33211)
		(width 0.14478)
		(layer "In6.Cu")
		(net "M_E_CPU0_SB_DQ<30>")
	)
	(segment
		(start 327.44283 -294.800528)
		(end 327.403714 -294.823388)
		(width 0.0889)
		(layer "In6.Cu")
		(net "M_E_CPU0_SB_DQ<30>")
	)
	(segment
		(start 274.796758 -316.335156)
		(end 273.092164 -316.335156)
		(width 0.14478)
		(layer "In6.Cu")
		(net "M_E_CPU0_SB_DQ<30>")
	)
	(segment
		(start 275.104352 -315.33211)
		(end 274.941538 -315.494924)
		(width 0.14478)
		(layer "In6.Cu")
		(net "M_E_CPU0_SB_DQ<30>")
	)
	(segment
		(start 327.874122 -294.013382)
		(end 327.84034 -294.03294)
		(width 0.0889)
		(layer "In6.Cu")
		(net "M_E_CPU0_SB_DQ<30>")
	)
	(segment
		(start 329.155044 -292.45052)
		(end 329.132692 -292.367208)
		(width 0.0889)
		(layer "In6.Cu")
		(net "M_E_CPU0_SB_DQ<30>")
	)
	(segment
		(start 275.660612 -316.760098)
		(end 275.497798 -316.597284)
		(width 0.14478)
		(layer "In6.Cu")
		(net "M_E_CPU0_SB_DQ<30>")
	)
	(segment
		(start 327.403714 -294.823388)
		(end 327.371964 -294.841676)
		(width 0.0889)
		(layer "In6.Cu")
		(net "M_E_CPU0_SB_DQ<30>")
	)
	(segment
		(start 305.878992 -316.760098)
		(end 275.660612 -316.760098)
		(width 0.14478)
		(layer "In6.Cu")
		(net "M_E_CPU0_SB_DQ<30>")
	)
	(segment
		(start 328.814176 -292.39337)
		(end 328.811382 -292.395148)
		(width 0.0889)
		(layer "In6.Cu")
		(net "M_E_CPU0_SB_DQ<30>")
	)
	(segment
		(start 275.497798 -316.597284)
		(end 275.497798 -315.494924)
		(width 0.14478)
		(layer "In6.Cu")
		(net "M_E_CPU0_SB_DQ<30>")
	)
	(segment
		(start 313.458098 -309.10022)
		(end 313.458098 -310.473598)
		(width 0.14478)
		(layer "In6.Cu")
		(net "M_E_CPU0_SB_DQ<30>")
	)
	(segment
		(start 308.291484 -315.640212)
		(end 306.998878 -315.640212)
		(width 0.14478)
		(layer "In6.Cu")
		(net "M_E_CPU0_SB_DQ<30>")
	)
	(segment
		(start 275.334984 -315.33211)
		(end 275.104352 -315.33211)
		(width 0.14478)
		(layer "In6.Cu")
		(net "M_E_CPU0_SB_DQ<30>")
	)
	(segment
		(start 326.8599 -295.694862)
		(end 326.549004 -296.009314)
		(width 0.0889)
		(layer "In6.Cu")
		(net "M_E_CPU0_SB_DQ<30>")
	)
	(segment
		(start 328.346562 -293.201598)
		(end 328.344022 -293.203376)
		(width 0.0889)
		(layer "In6.Cu")
		(net "M_E_CPU0_SB_DQ<30>")
	)
	(segment
		(start 327.053194 -295.539414)
		(end 326.976232 -295.616122)
		(width 0.0889)
		(layer "In6.Cu")
		(net "M_E_CPU0_SB_DQ<30>")
	)
	(arc
		(start 329.132692 -292.367208)
		(mid 328.970503 -292.344473)
		(end 328.814176 -292.39337)
		(width 0.0889)
		(layer "In6.Cu")
		(net "M_E_CPU0_SB_DQ<30>")
	)
	(arc
		(start 326.976232 -295.616122)
		(mid 326.949029 -295.638586)
		(end 326.918066 -295.655492)
		(width 0.0889)
		(layer "In6.Cu")
		(net "M_E_CPU0_SB_DQ<30>")
	)
	(arc
		(start 327.216008 -295.145968)
		(mid 327.173748 -295.358893)
		(end 327.053194 -295.539414)
		(width 0.0889)
		(layer "In6.Cu")
		(net "M_E_CPU0_SB_DQ<30>")
	)
	(arc
		(start 326.918066 -295.655492)
		(mid 326.887108 -295.672405)
		(end 326.8599 -295.694862)
		(width 0.0889)
		(layer "In6.Cu")
		(net "M_E_CPU0_SB_DQ<30>")
	)
	(arc
		(start 327.84034 -294.03294)
		(mid 327.726933 -294.16597)
		(end 327.686162 -294.335962)
		(width 0.0889)
		(layer "In6.Cu")
		(net "M_E_CPU0_SB_DQ<30>")
	)
	(arc
		(start 327.686162 -294.335962)
		(mid 327.621647 -294.598181)
		(end 327.44283 -294.800528)
		(width 0.0889)
		(layer "In6.Cu")
		(net "M_E_CPU0_SB_DQ<30>")
	)
	(arc
		(start 328.811382 -292.395148)
		(mid 328.676045 -292.530824)
		(end 328.62647 -292.71595)
		(width 0.0889)
		(layer "In6.Cu")
		(net "M_E_CPU0_SB_DQ<30>")
	)
	(arc
		(start 328.341482 -293.2049)
		(mid 328.206075 -293.340697)
		(end 328.15657 -293.525956)
		(width 0.0889)
		(layer "In6.Cu")
		(net "M_E_CPU0_SB_DQ<30>")
	)
	(arc
		(start 328.62647 -292.71595)
		(mid 328.551416 -292.996172)
		(end 328.346562 -293.201598)
		(width 0.0889)
		(layer "In6.Cu")
		(net "M_E_CPU0_SB_DQ<30>")
	)
	(arc
		(start 327.371964 -294.841676)
		(mid 327.257288 -294.97501)
		(end 327.216008 -295.145968)
		(width 0.0889)
		(layer "In6.Cu")
		(net "M_E_CPU0_SB_DQ<30>")
	)
	(arc
		(start 328.15657 -293.525956)
		(mid 328.092055 -293.788175)
		(end 327.913238 -293.990522)
		(width 0.0889)
		(layer "In6.Cu")
		(net "M_E_CPU0_SB_DQ<30>")
	)
	(segment
		(start 329.467972 -274.630134)
		(end 329.00112 -274.896072)
		(width 0.10668)
		(layer "F.Cu")
		(net "M_E_CPU0_SB_DQ<2>")
	)
	(segment
		(start 276.003512 -282.597352)
		(end 276.003512 -282.093924)
		(width 0.14478)
		(layer "In6.Cu")
		(net "M_E_CPU0_SB_DQ<2>")
	)
	(segment
		(start 297.214036 -282.760166)
		(end 294.199564 -282.760166)
		(width 0.14478)
		(layer "In6.Cu")
		(net "M_E_CPU0_SB_DQ<2>")
	)
	(segment
		(start 294.199564 -282.760166)
		(end 293.349426 -281.910028)
		(width 0.14478)
		(layer "In6.Cu")
		(net "M_E_CPU0_SB_DQ<2>")
	)
	(segment
		(start 326.383142 -274.582128)
		(end 326.36841 -274.573492)
		(width 0.0889)
		(layer "In6.Cu")
		(net "M_E_CPU0_SB_DQ<2>")
	)
	(segment
		(start 285.704026 -281.910028)
		(end 283.02839 -281.910028)
		(width 0.14478)
		(layer "In6.Cu")
		(net "M_E_CPU0_SB_DQ<2>")
	)
	(segment
		(start 298.064174 -281.910028)
		(end 297.214036 -282.760166)
		(width 0.14478)
		(layer "In6.Cu")
		(net "M_E_CPU0_SB_DQ<2>")
	)
	(segment
		(start 306.873402 -281.910028)
		(end 306.473098 -282.310332)
		(width 0.14478)
		(layer "In6.Cu")
		(net "M_E_CPU0_SB_DQ<2>")
	)
	(segment
		(start 304.597308 -282.760166)
		(end 301.768764 -282.760166)
		(width 0.14478)
		(layer "In6.Cu")
		(net "M_E_CPU0_SB_DQ<2>")
	)
	(segment
		(start 283.02839 -281.910028)
		(end 282.178252 -282.760166)
		(width 0.14478)
		(layer "In6.Cu")
		(net "M_E_CPU0_SB_DQ<2>")
	)
	(segment
		(start 274.62861 -282.33497)
		(end 273.092164 -282.33497)
		(width 0.14478)
		(layer "In6.Cu")
		(net "M_E_CPU0_SB_DQ<2>")
	)
	(segment
		(start 275.284438 -282.760166)
		(end 275.053806 -282.760166)
		(width 0.14478)
		(layer "In6.Cu")
		(net "M_E_CPU0_SB_DQ<2>")
	)
	(segment
		(start 309.740046 -278.980646)
		(end 309.740046 -279.333198)
		(width 0.14478)
		(layer "In6.Cu")
		(net "M_E_CPU0_SB_DQ<2>")
	)
	(segment
		(start 275.053806 -282.760166)
		(end 274.62861 -282.33497)
		(width 0.14478)
		(layer "In6.Cu")
		(net "M_E_CPU0_SB_DQ<2>")
	)
	(segment
		(start 307.826664 -281.910028)
		(end 306.873402 -281.910028)
		(width 0.14478)
		(layer "In6.Cu")
		(net "M_E_CPU0_SB_DQ<2>")
	)
	(segment
		(start 275.840698 -281.93111)
		(end 275.610066 -281.93111)
		(width 0.14478)
		(layer "In6.Cu")
		(net "M_E_CPU0_SB_DQ<2>")
	)
	(segment
		(start 312.62193 -276.098762)
		(end 309.740046 -278.980646)
		(width 0.14478)
		(layer "In6.Cu")
		(net "M_E_CPU0_SB_DQ<2>")
	)
	(segment
		(start 276.003512 -282.093924)
		(end 275.840698 -281.93111)
		(width 0.14478)
		(layer "In6.Cu")
		(net "M_E_CPU0_SB_DQ<2>")
	)
	(segment
		(start 329.00112 -274.896072)
		(end 329.155044 -274.630642)
		(width 0.0889)
		(layer "In6.Cu")
		(net "M_E_CPU0_SB_DQ<2>")
	)
	(segment
		(start 323.925184 -273.67484)
		(end 314.304172 -273.67484)
		(width 0.14478)
		(layer "In6.Cu")
		(net "M_E_CPU0_SB_DQ<2>")
	)
	(segment
		(start 313.14644 -274.832572)
		(end 312.62193 -276.098762)
		(width 0.14478)
		(layer "In6.Cu")
		(net "M_E_CPU0_SB_DQ<2>")
	)
	(segment
		(start 290.95319 -281.910028)
		(end 290.103052 -282.760166)
		(width 0.14478)
		(layer "In6.Cu")
		(net "M_E_CPU0_SB_DQ<2>")
	)
	(segment
		(start 325.438262 -273.670268)
		(end 323.929756 -273.670268)
		(width 0.0889)
		(layer "In6.Cu")
		(net "M_E_CPU0_SB_DQ<2>")
	)
	(segment
		(start 314.304172 -273.67484)
		(end 313.14644 -274.832572)
		(width 0.14478)
		(layer "In6.Cu")
		(net "M_E_CPU0_SB_DQ<2>")
	)
	(segment
		(start 308.686708 -280.386536)
		(end 308.686708 -281.049984)
		(width 0.14478)
		(layer "In6.Cu")
		(net "M_E_CPU0_SB_DQ<2>")
	)
	(segment
		(start 329.155044 -274.630642)
		(end 329.132692 -274.54733)
		(width 0.0889)
		(layer "In6.Cu")
		(net "M_E_CPU0_SB_DQ<2>")
	)
	(segment
		(start 327.874122 -274.573492)
		(end 327.863708 -274.579588)
		(width 0.0889)
		(layer "In6.Cu")
		(net "M_E_CPU0_SB_DQ<2>")
	)
	(segment
		(start 323.929756 -273.670268)
		(end 323.925184 -273.67484)
		(width 0.0889)
		(layer "In6.Cu")
		(net "M_E_CPU0_SB_DQ<2>")
	)
	(segment
		(start 306.473098 -282.310332)
		(end 305.047142 -282.310332)
		(width 0.14478)
		(layer "In6.Cu")
		(net "M_E_CPU0_SB_DQ<2>")
	)
	(segment
		(start 300.918626 -281.910028)
		(end 298.064174 -281.910028)
		(width 0.14478)
		(layer "In6.Cu")
		(net "M_E_CPU0_SB_DQ<2>")
	)
	(segment
		(start 308.686708 -281.049984)
		(end 307.826664 -281.910028)
		(width 0.14478)
		(layer "In6.Cu")
		(net "M_E_CPU0_SB_DQ<2>")
	)
	(segment
		(start 305.047142 -282.310332)
		(end 304.597308 -282.760166)
		(width 0.14478)
		(layer "In6.Cu")
		(net "M_E_CPU0_SB_DQ<2>")
	)
	(segment
		(start 327.308464 -274.573492)
		(end 327.300082 -274.568666)
		(width 0.0889)
		(layer "In6.Cu")
		(net "M_E_CPU0_SB_DQ<2>")
	)
	(segment
		(start 275.447252 -282.093924)
		(end 275.447252 -282.597352)
		(width 0.14478)
		(layer "In6.Cu")
		(net "M_E_CPU0_SB_DQ<2>")
	)
	(segment
		(start 275.610066 -281.93111)
		(end 275.447252 -282.093924)
		(width 0.14478)
		(layer "In6.Cu")
		(net "M_E_CPU0_SB_DQ<2>")
	)
	(segment
		(start 301.768764 -282.760166)
		(end 300.918626 -281.910028)
		(width 0.14478)
		(layer "In6.Cu")
		(net "M_E_CPU0_SB_DQ<2>")
	)
	(segment
		(start 282.178252 -282.760166)
		(end 276.166326 -282.760166)
		(width 0.14478)
		(layer "In6.Cu")
		(net "M_E_CPU0_SB_DQ<2>")
	)
	(segment
		(start 286.554164 -282.760166)
		(end 285.704026 -281.910028)
		(width 0.14478)
		(layer "In6.Cu")
		(net "M_E_CPU0_SB_DQ<2>")
	)
	(segment
		(start 293.349426 -281.910028)
		(end 290.95319 -281.910028)
		(width 0.14478)
		(layer "In6.Cu")
		(net "M_E_CPU0_SB_DQ<2>")
	)
	(segment
		(start 276.166326 -282.760166)
		(end 276.003512 -282.597352)
		(width 0.14478)
		(layer "In6.Cu")
		(net "M_E_CPU0_SB_DQ<2>")
	)
	(segment
		(start 326.252586 -274.484592)
		(end 325.438262 -273.670268)
		(width 0.0889)
		(layer "In6.Cu")
		(net "M_E_CPU0_SB_DQ<2>")
	)
	(segment
		(start 309.740046 -279.333198)
		(end 308.686708 -280.386536)
		(width 0.14478)
		(layer "In6.Cu")
		(net "M_E_CPU0_SB_DQ<2>")
	)
	(segment
		(start 275.447252 -282.597352)
		(end 275.284438 -282.760166)
		(width 0.14478)
		(layer "In6.Cu")
		(net "M_E_CPU0_SB_DQ<2>")
	)
	(segment
		(start 290.103052 -282.760166)
		(end 286.554164 -282.760166)
		(width 0.14478)
		(layer "In6.Cu")
		(net "M_E_CPU0_SB_DQ<2>")
	)
	(segment
		(start 327.882504 -274.568666)
		(end 327.874122 -274.573492)
		(width 0.0889)
		(layer "In6.Cu")
		(net "M_E_CPU0_SB_DQ<2>")
	)
	(arc
		(start 328.248264 -274.573492)
		(mid 328.066013 -274.523142)
		(end 327.882504 -274.568666)
		(width 0.0889)
		(layer "In6.Cu")
		(net "M_E_CPU0_SB_DQ<2>")
	)
	(arc
		(start 326.36841 -274.573492)
		(mid 326.3076 -274.532817)
		(end 326.252586 -274.484592)
		(width 0.0889)
		(layer "In6.Cu")
		(net "M_E_CPU0_SB_DQ<2>")
	)
	(arc
		(start 327.300082 -274.568666)
		(mid 327.116574 -274.523172)
		(end 326.934322 -274.573492)
		(width 0.0889)
		(layer "In6.Cu")
		(net "M_E_CPU0_SB_DQ<2>")
	)
	(arc
		(start 329.132692 -274.54733)
		(mid 328.970503 -274.524595)
		(end 328.814176 -274.573492)
		(width 0.0889)
		(layer "In6.Cu")
		(net "M_E_CPU0_SB_DQ<2>")
	)
	(arc
		(start 328.814176 -274.573492)
		(mid 328.53122 -274.649669)
		(end 328.248264 -274.573492)
		(width 0.0889)
		(layer "In6.Cu")
		(net "M_E_CPU0_SB_DQ<2>")
	)
	(arc
		(start 326.934322 -274.573492)
		(mid 326.65987 -274.649728)
		(end 326.383142 -274.582128)
		(width 0.0889)
		(layer "In6.Cu")
		(net "M_E_CPU0_SB_DQ<2>")
	)
	(arc
		(start 327.863708 -274.579588)
		(mid 327.585276 -274.649686)
		(end 327.308464 -274.573492)
		(width 0.0889)
		(layer "In6.Cu")
		(net "M_E_CPU0_SB_DQ<2>")
	)
	(segment
		(start 331.34808 -292.450012)
		(end 330.880974 -292.71595)
		(width 0.10668)
		(layer "F.Cu")
		(net "M_E_CPU0_SB_DQ<29>")
	)
	(segment
		(start 282.7274 -317.99911)
		(end 282.496768 -317.99911)
		(width 0.14478)
		(layer "In6.Cu")
		(net "M_E_CPU0_SB_DQ<29>")
	)
	(segment
		(start 330.880974 -292.71595)
		(end 330.72705 -292.98138)
		(width 0.0889)
		(layer "In6.Cu")
		(net "M_E_CPU0_SB_DQ<29>")
	)
	(segment
		(start 278.393398 -317.829946)
		(end 278.230584 -317.99276)
		(width 0.14478)
		(layer "In6.Cu")
		(net "M_E_CPU0_SB_DQ<29>")
	)
	(segment
		(start 286.276034 -317.221362)
		(end 286.045402 -317.221362)
		(width 0.14478)
		(layer "In6.Cu")
		(net "M_E_CPU0_SB_DQ<29>")
	)
	(segment
		(start 282.496768 -317.99911)
		(end 282.333954 -317.836296)
		(width 0.14478)
		(layer "In6.Cu")
		(net "M_E_CPU0_SB_DQ<29>")
	)
	(segment
		(start 283.609288 -317.99911)
		(end 283.446474 -317.836296)
		(width 0.14478)
		(layer "In6.Cu")
		(net "M_E_CPU0_SB_DQ<29>")
	)
	(segment
		(start 285.882588 -317.836296)
		(end 285.719774 -317.99911)
		(width 0.14478)
		(layer "In6.Cu")
		(net "M_E_CPU0_SB_DQ<29>")
	)
	(segment
		(start 285.100268 -317.610236)
		(end 284.228794 -317.610236)
		(width 0.14478)
		(layer "In6.Cu")
		(net "M_E_CPU0_SB_DQ<29>")
	)
	(segment
		(start 279.725628 -317.610236)
		(end 279.343104 -317.99276)
		(width 0.14478)
		(layer "In6.Cu")
		(net "M_E_CPU0_SB_DQ<29>")
	)
	(segment
		(start 282.17114 -317.221362)
		(end 281.940508 -317.221362)
		(width 0.14478)
		(layer "In6.Cu")
		(net "M_E_CPU0_SB_DQ<29>")
	)
	(segment
		(start 285.882588 -317.384176)
		(end 285.882588 -317.836296)
		(width 0.14478)
		(layer "In6.Cu")
		(net "M_E_CPU0_SB_DQ<29>")
	)
	(segment
		(start 283.83992 -317.99911)
		(end 283.609288 -317.99911)
		(width 0.14478)
		(layer "In6.Cu")
		(net "M_E_CPU0_SB_DQ<29>")
	)
	(segment
		(start 278.786844 -317.215012)
		(end 278.556212 -317.215012)
		(width 0.14478)
		(layer "In6.Cu")
		(net "M_E_CPU0_SB_DQ<29>")
	)
	(segment
		(start 278.230584 -317.99276)
		(end 277.999952 -317.99276)
		(width 0.14478)
		(layer "In6.Cu")
		(net "M_E_CPU0_SB_DQ<29>")
	)
	(segment
		(start 314.095638 -309.482236)
		(end 314.095638 -310.479186)
		(width 0.14478)
		(layer "In6.Cu")
		(net "M_E_CPU0_SB_DQ<29>")
	)
	(segment
		(start 286.601662 -317.99911)
		(end 286.438848 -317.836296)
		(width 0.14478)
		(layer "In6.Cu")
		(net "M_E_CPU0_SB_DQ<29>")
	)
	(segment
		(start 328.278744 -294.640762)
		(end 328.248264 -294.658542)
		(width 0.0889)
		(layer "In6.Cu")
		(net "M_E_CPU0_SB_DQ<29>")
	)
	(segment
		(start 286.438848 -317.836296)
		(end 286.438848 -317.384176)
		(width 0.14478)
		(layer "In6.Cu")
		(net "M_E_CPU0_SB_DQ<29>")
	)
	(segment
		(start 282.333954 -317.384176)
		(end 282.17114 -317.221362)
		(width 0.14478)
		(layer "In6.Cu")
		(net "M_E_CPU0_SB_DQ<29>")
	)
	(segment
		(start 283.446474 -317.384176)
		(end 283.28366 -317.221362)
		(width 0.14478)
		(layer "In6.Cu")
		(net "M_E_CPU0_SB_DQ<29>")
	)
	(segment
		(start 328.720958 -293.846758)
		(end 328.718164 -293.848536)
		(width 0.0889)
		(layer "In6.Cu")
		(net "M_E_CPU0_SB_DQ<29>")
	)
	(segment
		(start 277.999952 -317.99276)
		(end 277.192232 -317.18504)
		(width 0.14478)
		(layer "In6.Cu")
		(net "M_E_CPU0_SB_DQ<29>")
	)
	(segment
		(start 285.489142 -317.99911)
		(end 285.100268 -317.610236)
		(width 0.14478)
		(layer "In6.Cu")
		(net "M_E_CPU0_SB_DQ<29>")
	)
	(segment
		(start 285.719774 -317.99911)
		(end 285.489142 -317.99911)
		(width 0.14478)
		(layer "In6.Cu")
		(net "M_E_CPU0_SB_DQ<29>")
	)
	(segment
		(start 328.248264 -294.658542)
		(end 328.211942 -294.679624)
		(width 0.0889)
		(layer "In6.Cu")
		(net "M_E_CPU0_SB_DQ<29>")
	)
	(segment
		(start 329.188064 -293.03853)
		(end 329.186032 -293.0398)
		(width 0.0889)
		(layer "In6.Cu")
		(net "M_E_CPU0_SB_DQ<29>")
	)
	(segment
		(start 281.940508 -317.221362)
		(end 281.551634 -317.610236)
		(width 0.14478)
		(layer "In6.Cu")
		(net "M_E_CPU0_SB_DQ<29>")
	)
	(segment
		(start 279.112472 -317.99276)
		(end 278.949658 -317.829946)
		(width 0.14478)
		(layer "In6.Cu")
		(net "M_E_CPU0_SB_DQ<29>")
	)
	(segment
		(start 286.045402 -317.221362)
		(end 285.882588 -317.384176)
		(width 0.14478)
		(layer "In6.Cu")
		(net "M_E_CPU0_SB_DQ<29>")
	)
	(segment
		(start 284.228794 -317.610236)
		(end 283.83992 -317.99911)
		(width 0.14478)
		(layer "In6.Cu")
		(net "M_E_CPU0_SB_DQ<29>")
	)
	(segment
		(start 283.053028 -317.221362)
		(end 282.890214 -317.384176)
		(width 0.14478)
		(layer "In6.Cu")
		(net "M_E_CPU0_SB_DQ<29>")
	)
	(segment
		(start 328.718164 -293.848536)
		(end 328.679048 -293.871396)
		(width 0.0889)
		(layer "In6.Cu")
		(net "M_E_CPU0_SB_DQ<29>")
	)
	(segment
		(start 278.949658 -317.377826)
		(end 278.786844 -317.215012)
		(width 0.14478)
		(layer "In6.Cu")
		(net "M_E_CPU0_SB_DQ<29>")
	)
	(segment
		(start 283.446474 -317.836296)
		(end 283.446474 -317.384176)
		(width 0.14478)
		(layer "In6.Cu")
		(net "M_E_CPU0_SB_DQ<29>")
	)
	(segment
		(start 278.556212 -317.215012)
		(end 278.393398 -317.377826)
		(width 0.14478)
		(layer "In6.Cu")
		(net "M_E_CPU0_SB_DQ<29>")
	)
	(segment
		(start 330.72705 -292.98138)
		(end 330.631038 -293.00678)
		(width 0.0889)
		(layer "In6.Cu")
		(net "M_E_CPU0_SB_DQ<29>")
	)
	(segment
		(start 283.28366 -317.221362)
		(end 283.053028 -317.221362)
		(width 0.14478)
		(layer "In6.Cu")
		(net "M_E_CPU0_SB_DQ<29>")
	)
	(segment
		(start 282.890214 -317.384176)
		(end 282.890214 -317.836296)
		(width 0.14478)
		(layer "In6.Cu")
		(net "M_E_CPU0_SB_DQ<29>")
	)
	(segment
		(start 327.810114 -295.45026)
		(end 327.778364 -295.468548)
		(width 0.0889)
		(layer "In6.Cu")
		(net "M_E_CPU0_SB_DQ<29>")
	)
	(segment
		(start 307.656992 -316.917832)
		(end 306.564538 -316.917832)
		(width 0.14478)
		(layer "In6.Cu")
		(net "M_E_CPU0_SB_DQ<29>")
	)
	(segment
		(start 278.949658 -317.829946)
		(end 278.949658 -317.377826)
		(width 0.14478)
		(layer "In6.Cu")
		(net "M_E_CPU0_SB_DQ<29>")
	)
	(segment
		(start 305.872134 -317.610236)
		(end 287.221168 -317.610236)
		(width 0.14478)
		(layer "In6.Cu")
		(net "M_E_CPU0_SB_DQ<29>")
	)
	(segment
		(start 282.890214 -317.836296)
		(end 282.7274 -317.99911)
		(width 0.14478)
		(layer "In6.Cu")
		(net "M_E_CPU0_SB_DQ<29>")
	)
	(segment
		(start 327.778364 -295.468548)
		(end 327.739248 -295.491408)
		(width 0.0889)
		(layer "In6.Cu")
		(net "M_E_CPU0_SB_DQ<29>")
	)
	(segment
		(start 286.438848 -317.384176)
		(end 286.276034 -317.221362)
		(width 0.14478)
		(layer "In6.Cu")
		(net "M_E_CPU0_SB_DQ<29>")
	)
	(segment
		(start 327.067164 -296.51071)
		(end 314.095638 -309.482236)
		(width 0.14478)
		(layer "In6.Cu")
		(net "M_E_CPU0_SB_DQ<29>")
	)
	(segment
		(start 281.551634 -317.610236)
		(end 279.725628 -317.610236)
		(width 0.14478)
		(layer "In6.Cu")
		(net "M_E_CPU0_SB_DQ<29>")
	)
	(segment
		(start 282.333954 -317.836296)
		(end 282.333954 -317.384176)
		(width 0.14478)
		(layer "In6.Cu")
		(net "M_E_CPU0_SB_DQ<29>")
	)
	(segment
		(start 314.095638 -310.479186)
		(end 307.656992 -316.917832)
		(width 0.14478)
		(layer "In6.Cu")
		(net "M_E_CPU0_SB_DQ<29>")
	)
	(segment
		(start 287.221168 -317.610236)
		(end 286.832294 -317.99911)
		(width 0.14478)
		(layer "In6.Cu")
		(net "M_E_CPU0_SB_DQ<29>")
	)
	(segment
		(start 306.564538 -316.917832)
		(end 305.872134 -317.610236)
		(width 0.14478)
		(layer "In6.Cu")
		(net "M_E_CPU0_SB_DQ<29>")
	)
	(segment
		(start 286.832294 -317.99911)
		(end 286.601662 -317.99911)
		(width 0.14478)
		(layer "In6.Cu")
		(net "M_E_CPU0_SB_DQ<29>")
	)
	(segment
		(start 278.393398 -317.377826)
		(end 278.393398 -317.829946)
		(width 0.14478)
		(layer "In6.Cu")
		(net "M_E_CPU0_SB_DQ<29>")
	)
	(segment
		(start 279.343104 -317.99276)
		(end 279.112472 -317.99276)
		(width 0.14478)
		(layer "In6.Cu")
		(net "M_E_CPU0_SB_DQ<29>")
	)
	(segment
		(start 327.406762 -296.17162)
		(end 327.067672 -296.51071)
		(width 0.0889)
		(layer "In6.Cu")
		(net "M_E_CPU0_SB_DQ<29>")
	)
	(segment
		(start 330.128118 -293.03853)
		(end 330.127864 -293.03853)
		(width 0.0889)
		(layer "In6.Cu")
		(net "M_E_CPU0_SB_DQ<29>")
	)
	(arc
		(start 329.186032 -293.0398)
		(mid 328.98091 -293.245399)
		(end 328.90587 -293.525956)
		(width 0.0889)
		(layer "In6.Cu")
		(net "M_E_CPU0_SB_DQ<29>")
	)
	(arc
		(start 328.90587 -293.525956)
		(mid 328.856341 -293.711109)
		(end 328.720958 -293.846758)
		(width 0.0889)
		(layer "In6.Cu")
		(net "M_E_CPU0_SB_DQ<29>")
	)
	(arc
		(start 328.679048 -293.871396)
		(mid 328.500235 -294.073746)
		(end 328.435716 -294.335962)
		(width 0.0889)
		(layer "In6.Cu")
		(net "M_E_CPU0_SB_DQ<29>")
	)
	(arc
		(start 327.739248 -295.491408)
		(mid 327.560435 -295.693758)
		(end 327.495916 -295.955974)
		(width 0.0889)
		(layer "In6.Cu")
		(net "M_E_CPU0_SB_DQ<29>")
	)
	(arc
		(start 330.631038 -293.00678)
		(mid 330.37583 -292.963303)
		(end 330.128118 -293.03853)
		(width 0.0889)
		(layer "In6.Cu")
		(net "M_E_CPU0_SB_DQ<29>")
	)
	(arc
		(start 327.495916 -295.955974)
		(mid 327.472797 -296.07267)
		(end 327.406762 -296.17162)
		(width 0.0889)
		(layer "In6.Cu")
		(net "M_E_CPU0_SB_DQ<29>")
	)
	(arc
		(start 330.127864 -293.03853)
		(mid 329.94092 -293.088854)
		(end 329.753976 -293.03853)
		(width 0.0889)
		(layer "In6.Cu")
		(net "M_E_CPU0_SB_DQ<29>")
	)
	(arc
		(start 327.067672 -296.51071)
		(mid 327.067418 -296.51077)
		(end 327.067164 -296.51071)
		(width 0.0889)
		(layer "In6.Cu")
		(net "M_E_CPU0_SB_DQ<29>")
	)
	(arc
		(start 329.753976 -293.03853)
		(mid 329.47102 -292.962353)
		(end 329.188064 -293.03853)
		(width 0.0889)
		(layer "In6.Cu")
		(net "M_E_CPU0_SB_DQ<29>")
	)
	(arc
		(start 327.96607 -295.145968)
		(mid 327.924815 -295.316939)
		(end 327.810114 -295.45026)
		(width 0.0889)
		(layer "In6.Cu")
		(net "M_E_CPU0_SB_DQ<29>")
	)
	(arc
		(start 328.211942 -294.679624)
		(mid 328.03129 -294.882369)
		(end 327.96607 -295.145968)
		(width 0.0889)
		(layer "In6.Cu")
		(net "M_E_CPU0_SB_DQ<29>")
	)
	(arc
		(start 328.435716 -294.335962)
		(mid 328.394167 -294.507384)
		(end 328.278744 -294.640762)
		(width 0.0889)
		(layer "In6.Cu")
		(net "M_E_CPU0_SB_DQ<29>")
	)
	(segment
		(start 329.937872 -291.640006)
		(end 329.47102 -291.905944)
		(width 0.10668)
		(layer "F.Cu")
		(net "M_E_CPU0_SB_DQ<28>")
	)
	(segment
		(start 289.93211 -316.22111)
		(end 289.621214 -315.910214)
		(width 0.14478)
		(layer "In6.Cu")
		(net "M_E_CPU0_SB_DQ<28>")
	)
	(segment
		(start 305.001168 -316.22111)
		(end 304.690272 -315.910214)
		(width 0.14478)
		(layer "In6.Cu")
		(net "M_E_CPU0_SB_DQ<28>")
	)
	(segment
		(start 299.185584 -315.910214)
		(end 298.874688 -316.22111)
		(width 0.14478)
		(layer "In6.Cu")
		(net "M_E_CPU0_SB_DQ<28>")
	)
	(segment
		(start 327.77811 -292.228524)
		(end 327.77557 -292.230048)
		(width 0.0889)
		(layer "In6.Cu")
		(net "M_E_CPU0_SB_DQ<28>")
	)
	(segment
		(start 327.33869 -293.02075)
		(end 327.30821 -293.03853)
		(width 0.0889)
		(layer "In6.Cu")
		(net "M_E_CPU0_SB_DQ<28>")
	)
	(segment
		(start 300.796452 -316.22111)
		(end 300.551088 -316.22111)
		(width 0.14478)
		(layer "In6.Cu")
		(net "M_E_CPU0_SB_DQ<28>")
	)
	(segment
		(start 300.240192 -315.910214)
		(end 299.185584 -315.910214)
		(width 0.14478)
		(layer "In6.Cu")
		(net "M_E_CPU0_SB_DQ<28>")
	)
	(segment
		(start 302.776128 -316.22111)
		(end 302.465232 -315.910214)
		(width 0.14478)
		(layer "In6.Cu")
		(net "M_E_CPU0_SB_DQ<28>")
	)
	(segment
		(start 304.134012 -316.22111)
		(end 303.888648 -316.22111)
		(width 0.14478)
		(layer "In6.Cu")
		(net "M_E_CPU0_SB_DQ<28>")
	)
	(segment
		(start 289.621214 -315.910214)
		(end 289.37585 -315.910214)
		(width 0.14478)
		(layer "In6.Cu")
		(net "M_E_CPU0_SB_DQ<28>")
	)
	(segment
		(start 279.188164 -315.919866)
		(end 278.798782 -315.530484)
		(width 0.14478)
		(layer "In6.Cu")
		(net "M_E_CPU0_SB_DQ<28>")
	)
	(segment
		(start 293.407338 -315.910214)
		(end 293.096442 -316.22111)
		(width 0.14478)
		(layer "In6.Cu")
		(net "M_E_CPU0_SB_DQ<28>")
	)
	(segment
		(start 302.465232 -315.910214)
		(end 302.219868 -315.910214)
		(width 0.14478)
		(layer "In6.Cu")
		(net "M_E_CPU0_SB_DQ<28>")
	)
	(segment
		(start 321.577208 -299.95749)
		(end 321.299332 -299.679614)
		(width 0.14478)
		(layer "In6.Cu")
		(net "M_E_CPU0_SB_DQ<28>")
	)
	(segment
		(start 321.299332 -299.679614)
		(end 321.094608 -299.679614)
		(width 0.14478)
		(layer "In6.Cu")
		(net "M_E_CPU0_SB_DQ<28>")
	)
	(segment
		(start 297.762168 -316.22111)
		(end 297.516804 -316.22111)
		(width 0.14478)
		(layer "In6.Cu")
		(net "M_E_CPU0_SB_DQ<28>")
	)
	(segment
		(start 278.798782 -315.530484)
		(end 278.56815 -315.530484)
		(width 0.14478)
		(layer "In6.Cu")
		(net "M_E_CPU0_SB_DQ<28>")
	)
	(segment
		(start 328.718164 -292.228524)
		(end 328.71791 -292.228524)
		(width 0.0889)
		(layer "In6.Cu")
		(net "M_E_CPU0_SB_DQ<28>")
	)
	(segment
		(start 322.374768 -299.15993)
		(end 322.096892 -298.882054)
		(width 0.14478)
		(layer "In6.Cu")
		(net "M_E_CPU0_SB_DQ<28>")
	)
	(segment
		(start 298.318428 -315.910214)
		(end 298.073064 -315.910214)
		(width 0.14478)
		(layer "In6.Cu")
		(net "M_E_CPU0_SB_DQ<28>")
	)
	(segment
		(start 278.01189 -316.304676)
		(end 277.192232 -315.485018)
		(width 0.14478)
		(layer "In6.Cu")
		(net "M_E_CPU0_SB_DQ<28>")
	)
	(segment
		(start 325.450454 -295.79951)
		(end 323.359272 -297.890692)
		(width 0.14478)
		(layer "In6.Cu")
		(net "M_E_CPU0_SB_DQ<28>")
	)
	(segment
		(start 297.516804 -316.22111)
		(end 297.205908 -315.910214)
		(width 0.14478)
		(layer "In6.Cu")
		(net "M_E_CPU0_SB_DQ<28>")
	)
	(segment
		(start 327.30821 -293.03853)
		(end 327.30567 -293.040308)
		(width 0.0889)
		(layer "In6.Cu")
		(net "M_E_CPU0_SB_DQ<28>")
	)
	(segment
		(start 303.888648 -316.22111)
		(end 303.577752 -315.910214)
		(width 0.14478)
		(layer "In6.Cu")
		(net "M_E_CPU0_SB_DQ<28>")
	)
	(segment
		(start 286.262318 -316.14491)
		(end 286.037274 -315.919866)
		(width 0.14478)
		(layer "In6.Cu")
		(net "M_E_CPU0_SB_DQ<28>")
	)
	(segment
		(start 322.096892 -298.882054)
		(end 321.892168 -298.882054)
		(width 0.14478)
		(layer "In6.Cu")
		(net "M_E_CPU0_SB_DQ<28>")
	)
	(segment
		(start 290.177474 -316.22111)
		(end 289.93211 -316.22111)
		(width 0.14478)
		(layer "In6.Cu")
		(net "M_E_CPU0_SB_DQ<28>")
	)
	(segment
		(start 312.856118 -309.680102)
		(end 307.665628 -314.870592)
		(width 0.14478)
		(layer "In6.Cu")
		(net "M_E_CPU0_SB_DQ<28>")
	)
	(segment
		(start 326.399906 -294.640254)
		(end 326.368156 -294.658542)
		(width 0.0889)
		(layer "In6.Cu")
		(net "M_E_CPU0_SB_DQ<28>")
	)
	(segment
		(start 325.897748 -295.468548)
		(end 325.450454 -295.79951)
		(width 0.0889)
		(layer "In6.Cu")
		(net "M_E_CPU0_SB_DQ<28>")
	)
	(segment
		(start 327.778364 -292.228524)
		(end 327.77811 -292.228524)
		(width 0.0889)
		(layer "In6.Cu")
		(net "M_E_CPU0_SB_DQ<28>")
	)
	(segment
		(start 289.37585 -315.910214)
		(end 289.064954 -316.22111)
		(width 0.14478)
		(layer "In6.Cu")
		(net "M_E_CPU0_SB_DQ<28>")
	)
	(segment
		(start 278.405336 -315.693298)
		(end 278.405336 -316.141862)
		(width 0.14478)
		(layer "In6.Cu")
		(net "M_E_CPU0_SB_DQ<28>")
	)
	(segment
		(start 322.773548 -298.76115)
		(end 322.773548 -298.965874)
		(width 0.14478)
		(layer "In6.Cu")
		(net "M_E_CPU0_SB_DQ<28>")
	)
	(segment
		(start 291.04463 -316.22111)
		(end 290.733734 -315.910214)
		(width 0.14478)
		(layer "In6.Cu")
		(net "M_E_CPU0_SB_DQ<28>")
	)
	(segment
		(start 293.652702 -315.910214)
		(end 293.407338 -315.910214)
		(width 0.14478)
		(layer "In6.Cu")
		(net "M_E_CPU0_SB_DQ<28>")
	)
	(segment
		(start 326.368156 -294.658542)
		(end 326.32777 -294.682164)
		(width 0.0889)
		(layer "In6.Cu")
		(net "M_E_CPU0_SB_DQ<28>")
	)
	(segment
		(start 321.892168 -298.882054)
		(end 321.698112 -299.07611)
		(width 0.14478)
		(layer "In6.Cu")
		(net "M_E_CPU0_SB_DQ<28>")
	)
	(segment
		(start 286.818578 -315.910214)
		(end 286.583882 -316.14491)
		(width 0.14478)
		(layer "In6.Cu")
		(net "M_E_CPU0_SB_DQ<28>")
	)
	(segment
		(start 307.665628 -314.870592)
		(end 306.842414 -314.870592)
		(width 0.14478)
		(layer "In6.Cu")
		(net "M_E_CPU0_SB_DQ<28>")
	)
	(segment
		(start 326.838056 -293.848536)
		(end 326.836024 -293.849806)
		(width 0.0889)
		(layer "In6.Cu")
		(net "M_E_CPU0_SB_DQ<28>")
	)
	(segment
		(start 312.856118 -308.318662)
		(end 312.856118 -309.680102)
		(width 0.14478)
		(layer "In6.Cu")
		(net "M_E_CPU0_SB_DQ<28>")
	)
	(segment
		(start 292.540182 -315.910214)
		(end 291.60089 -315.910214)
		(width 0.14478)
		(layer "In6.Cu")
		(net "M_E_CPU0_SB_DQ<28>")
	)
	(segment
		(start 294.510206 -315.919866)
		(end 294.208962 -316.22111)
		(width 0.14478)
		(layer "In6.Cu")
		(net "M_E_CPU0_SB_DQ<28>")
	)
	(segment
		(start 291.289994 -316.22111)
		(end 291.04463 -316.22111)
		(width 0.14478)
		(layer "In6.Cu")
		(net "M_E_CPU0_SB_DQ<28>")
	)
	(segment
		(start 298.874688 -316.22111)
		(end 298.629324 -316.22111)
		(width 0.14478)
		(layer "In6.Cu")
		(net "M_E_CPU0_SB_DQ<28>")
	)
	(segment
		(start 303.332388 -315.910214)
		(end 303.021492 -316.22111)
		(width 0.14478)
		(layer "In6.Cu")
		(net "M_E_CPU0_SB_DQ<28>")
	)
	(segment
		(start 322.88353 -297.890692)
		(end 322.495672 -298.27855)
		(width 0.14478)
		(layer "In6.Cu")
		(net "M_E_CPU0_SB_DQ<28>")
	)
	(segment
		(start 301.663608 -316.22111)
		(end 301.352712 -315.910214)
		(width 0.14478)
		(layer "In6.Cu")
		(net "M_E_CPU0_SB_DQ<28>")
	)
	(segment
		(start 322.495672 -298.27855)
		(end 322.495672 -298.483274)
		(width 0.14478)
		(layer "In6.Cu")
		(net "M_E_CPU0_SB_DQ<28>")
	)
	(segment
		(start 301.107348 -315.910214)
		(end 300.796452 -316.22111)
		(width 0.14478)
		(layer "In6.Cu")
		(net "M_E_CPU0_SB_DQ<28>")
	)
	(segment
		(start 296.404284 -316.22111)
		(end 296.10304 -315.919866)
		(width 0.14478)
		(layer "In6.Cu")
		(net "M_E_CPU0_SB_DQ<28>")
	)
	(segment
		(start 296.10304 -315.919866)
		(end 294.510206 -315.919866)
		(width 0.14478)
		(layer "In6.Cu")
		(net "M_E_CPU0_SB_DQ<28>")
	)
	(segment
		(start 304.690272 -315.910214)
		(end 304.444908 -315.910214)
		(width 0.14478)
		(layer "In6.Cu")
		(net "M_E_CPU0_SB_DQ<28>")
	)
	(segment
		(start 326.869806 -293.830248)
		(end 326.838056 -293.848536)
		(width 0.0889)
		(layer "In6.Cu")
		(net "M_E_CPU0_SB_DQ<28>")
	)
	(segment
		(start 287.696402 -316.14491)
		(end 287.374838 -316.14491)
		(width 0.14478)
		(layer "In6.Cu")
		(net "M_E_CPU0_SB_DQ<28>")
	)
	(segment
		(start 329.47102 -291.905944)
		(end 329.317096 -292.171374)
		(width 0.0889)
		(layer "In6.Cu")
		(net "M_E_CPU0_SB_DQ<28>")
	)
	(segment
		(start 294.208962 -316.22111)
		(end 293.963598 -316.22111)
		(width 0.14478)
		(layer "In6.Cu")
		(net "M_E_CPU0_SB_DQ<28>")
	)
	(segment
		(start 298.073064 -315.910214)
		(end 297.762168 -316.22111)
		(width 0.14478)
		(layer "In6.Cu")
		(net "M_E_CPU0_SB_DQ<28>")
	)
	(segment
		(start 305.557428 -315.910214)
		(end 305.246532 -316.22111)
		(width 0.14478)
		(layer "In6.Cu")
		(net "M_E_CPU0_SB_DQ<28>")
	)
	(segment
		(start 301.908972 -316.22111)
		(end 301.663608 -316.22111)
		(width 0.14478)
		(layer "In6.Cu")
		(net "M_E_CPU0_SB_DQ<28>")
	)
	(segment
		(start 301.352712 -315.910214)
		(end 301.107348 -315.910214)
		(width 0.14478)
		(layer "In6.Cu")
		(net "M_E_CPU0_SB_DQ<28>")
	)
	(segment
		(start 322.495672 -298.483274)
		(end 322.773548 -298.76115)
		(width 0.14478)
		(layer "In6.Cu")
		(net "M_E_CPU0_SB_DQ<28>")
	)
	(segment
		(start 322.773548 -298.965874)
		(end 322.579492 -299.15993)
		(width 0.14478)
		(layer "In6.Cu")
		(net "M_E_CPU0_SB_DQ<28>")
	)
	(segment
		(start 297.205908 -315.910214)
		(end 296.960544 -315.910214)
		(width 0.14478)
		(layer "In6.Cu")
		(net "M_E_CPU0_SB_DQ<28>")
	)
	(segment
		(start 321.094608 -299.679614)
		(end 315.451998 -305.322224)
		(width 0.14478)
		(layer "In6.Cu")
		(net "M_E_CPU0_SB_DQ<28>")
	)
	(segment
		(start 293.096442 -316.22111)
		(end 292.851078 -316.22111)
		(width 0.14478)
		(layer "In6.Cu")
		(net "M_E_CPU0_SB_DQ<28>")
	)
	(segment
		(start 306.842414 -314.870592)
		(end 305.802792 -315.910214)
		(width 0.14478)
		(layer "In6.Cu")
		(net "M_E_CPU0_SB_DQ<28>")
	)
	(segment
		(start 286.583882 -316.14491)
		(end 286.262318 -316.14491)
		(width 0.14478)
		(layer "In6.Cu")
		(net "M_E_CPU0_SB_DQ<28>")
	)
	(segment
		(start 305.802792 -315.910214)
		(end 305.557428 -315.910214)
		(width 0.14478)
		(layer "In6.Cu")
		(net "M_E_CPU0_SB_DQ<28>")
	)
	(segment
		(start 321.975988 -299.763434)
		(end 321.781932 -299.95749)
		(width 0.14478)
		(layer "In6.Cu")
		(net "M_E_CPU0_SB_DQ<28>")
	)
	(segment
		(start 278.405336 -316.141862)
		(end 278.242522 -316.304676)
		(width 0.14478)
		(layer "In6.Cu")
		(net "M_E_CPU0_SB_DQ<28>")
	)
	(segment
		(start 287.140142 -315.910214)
		(end 286.818578 -315.910214)
		(width 0.14478)
		(layer "In6.Cu")
		(net "M_E_CPU0_SB_DQ<28>")
	)
	(segment
		(start 292.851078 -316.22111)
		(end 292.540182 -315.910214)
		(width 0.14478)
		(layer "In6.Cu")
		(net "M_E_CPU0_SB_DQ<28>")
	)
	(segment
		(start 287.921446 -315.919866)
		(end 287.696402 -316.14491)
		(width 0.14478)
		(layer "In6.Cu")
		(net "M_E_CPU0_SB_DQ<28>")
	)
	(segment
		(start 290.48837 -315.910214)
		(end 290.177474 -316.22111)
		(width 0.14478)
		(layer "In6.Cu")
		(net "M_E_CPU0_SB_DQ<28>")
	)
	(segment
		(start 321.781932 -299.95749)
		(end 321.577208 -299.95749)
		(width 0.14478)
		(layer "In6.Cu")
		(net "M_E_CPU0_SB_DQ<28>")
	)
	(segment
		(start 304.444908 -315.910214)
		(end 304.134012 -316.22111)
		(width 0.14478)
		(layer "In6.Cu")
		(net "M_E_CPU0_SB_DQ<28>")
	)
	(segment
		(start 321.975988 -299.55871)
		(end 321.975988 -299.763434)
		(width 0.14478)
		(layer "In6.Cu")
		(net "M_E_CPU0_SB_DQ<28>")
	)
	(segment
		(start 315.451998 -305.722782)
		(end 312.856118 -308.318662)
		(width 0.14478)
		(layer "In6.Cu")
		(net "M_E_CPU0_SB_DQ<28>")
	)
	(segment
		(start 289.064954 -316.22111)
		(end 288.81959 -316.22111)
		(width 0.14478)
		(layer "In6.Cu")
		(net "M_E_CPU0_SB_DQ<28>")
	)
	(segment
		(start 321.698112 -299.07611)
		(end 321.698112 -299.280834)
		(width 0.14478)
		(layer "In6.Cu")
		(net "M_E_CPU0_SB_DQ<28>")
	)
	(segment
		(start 329.317096 -292.171374)
		(end 329.221084 -292.196774)
		(width 0.0889)
		(layer "In6.Cu")
		(net "M_E_CPU0_SB_DQ<28>")
	)
	(segment
		(start 278.56815 -315.530484)
		(end 278.405336 -315.693298)
		(width 0.14478)
		(layer "In6.Cu")
		(net "M_E_CPU0_SB_DQ<28>")
	)
	(segment
		(start 296.649648 -316.22111)
		(end 296.404284 -316.22111)
		(width 0.14478)
		(layer "In6.Cu")
		(net "M_E_CPU0_SB_DQ<28>")
	)
	(segment
		(start 315.451998 -305.322224)
		(end 315.451998 -305.722782)
		(width 0.14478)
		(layer "In6.Cu")
		(net "M_E_CPU0_SB_DQ<28>")
	)
	(segment
		(start 322.579492 -299.15993)
		(end 322.374768 -299.15993)
		(width 0.14478)
		(layer "In6.Cu")
		(net "M_E_CPU0_SB_DQ<28>")
	)
	(segment
		(start 290.733734 -315.910214)
		(end 290.48837 -315.910214)
		(width 0.14478)
		(layer "In6.Cu")
		(net "M_E_CPU0_SB_DQ<28>")
	)
	(segment
		(start 298.629324 -316.22111)
		(end 298.318428 -315.910214)
		(width 0.14478)
		(layer "In6.Cu")
		(net "M_E_CPU0_SB_DQ<28>")
	)
	(segment
		(start 305.246532 -316.22111)
		(end 305.001168 -316.22111)
		(width 0.14478)
		(layer "In6.Cu")
		(net "M_E_CPU0_SB_DQ<28>")
	)
	(segment
		(start 303.577752 -315.910214)
		(end 303.332388 -315.910214)
		(width 0.14478)
		(layer "In6.Cu")
		(net "M_E_CPU0_SB_DQ<28>")
	)
	(segment
		(start 321.698112 -299.280834)
		(end 321.975988 -299.55871)
		(width 0.14478)
		(layer "In6.Cu")
		(net "M_E_CPU0_SB_DQ<28>")
	)
	(segment
		(start 325.929498 -295.45026)
		(end 325.897748 -295.468548)
		(width 0.0889)
		(layer "In6.Cu")
		(net "M_E_CPU0_SB_DQ<28>")
	)
	(segment
		(start 278.242522 -316.304676)
		(end 278.01189 -316.304676)
		(width 0.14478)
		(layer "In6.Cu")
		(net "M_E_CPU0_SB_DQ<28>")
	)
	(segment
		(start 300.551088 -316.22111)
		(end 300.240192 -315.910214)
		(width 0.14478)
		(layer "In6.Cu")
		(net "M_E_CPU0_SB_DQ<28>")
	)
	(segment
		(start 286.037274 -315.919866)
		(end 279.188164 -315.919866)
		(width 0.14478)
		(layer "In6.Cu")
		(net "M_E_CPU0_SB_DQ<28>")
	)
	(segment
		(start 303.021492 -316.22111)
		(end 302.776128 -316.22111)
		(width 0.14478)
		(layer "In6.Cu")
		(net "M_E_CPU0_SB_DQ<28>")
	)
	(segment
		(start 288.518346 -315.919866)
		(end 287.921446 -315.919866)
		(width 0.14478)
		(layer "In6.Cu")
		(net "M_E_CPU0_SB_DQ<28>")
	)
	(segment
		(start 288.81959 -316.22111)
		(end 288.518346 -315.919866)
		(width 0.14478)
		(layer "In6.Cu")
		(net "M_E_CPU0_SB_DQ<28>")
	)
	(segment
		(start 302.219868 -315.910214)
		(end 301.908972 -316.22111)
		(width 0.14478)
		(layer "In6.Cu")
		(net "M_E_CPU0_SB_DQ<28>")
	)
	(segment
		(start 323.359272 -297.890692)
		(end 322.88353 -297.890692)
		(width 0.14478)
		(layer "In6.Cu")
		(net "M_E_CPU0_SB_DQ<28>")
	)
	(segment
		(start 291.60089 -315.910214)
		(end 291.289994 -316.22111)
		(width 0.14478)
		(layer "In6.Cu")
		(net "M_E_CPU0_SB_DQ<28>")
	)
	(segment
		(start 296.960544 -315.910214)
		(end 296.649648 -316.22111)
		(width 0.14478)
		(layer "In6.Cu")
		(net "M_E_CPU0_SB_DQ<28>")
	)
	(segment
		(start 293.963598 -316.22111)
		(end 293.652702 -315.910214)
		(width 0.14478)
		(layer "In6.Cu")
		(net "M_E_CPU0_SB_DQ<28>")
	)
	(segment
		(start 287.374838 -316.14491)
		(end 287.140142 -315.910214)
		(width 0.14478)
		(layer "In6.Cu")
		(net "M_E_CPU0_SB_DQ<28>")
	)
	(arc
		(start 326.32777 -294.682164)
		(mid 326.149705 -294.884341)
		(end 326.085454 -295.145968)
		(width 0.0889)
		(layer "In6.Cu")
		(net "M_E_CPU0_SB_DQ<28>")
	)
	(arc
		(start 327.30567 -293.040308)
		(mid 327.10077 -293.245708)
		(end 327.025762 -293.525956)
		(width 0.0889)
		(layer "In6.Cu")
		(net "M_E_CPU0_SB_DQ<28>")
	)
	(arc
		(start 326.085454 -295.145968)
		(mid 326.044199 -295.316939)
		(end 325.929498 -295.45026)
		(width 0.0889)
		(layer "In6.Cu")
		(net "M_E_CPU0_SB_DQ<28>")
	)
	(arc
		(start 327.025762 -293.525956)
		(mid 326.984507 -293.696927)
		(end 326.869806 -293.830248)
		(width 0.0889)
		(layer "In6.Cu")
		(net "M_E_CPU0_SB_DQ<28>")
	)
	(arc
		(start 326.555862 -294.335962)
		(mid 326.514607 -294.506933)
		(end 326.399906 -294.640254)
		(width 0.0889)
		(layer "In6.Cu")
		(net "M_E_CPU0_SB_DQ<28>")
	)
	(arc
		(start 327.495662 -292.71595)
		(mid 327.454113 -292.887372)
		(end 327.33869 -293.02075)
		(width 0.0889)
		(layer "In6.Cu")
		(net "M_E_CPU0_SB_DQ<28>")
	)
	(arc
		(start 329.221084 -292.196774)
		(mid 328.965876 -292.153297)
		(end 328.718164 -292.228524)
		(width 0.0889)
		(layer "In6.Cu")
		(net "M_E_CPU0_SB_DQ<28>")
	)
	(arc
		(start 327.77557 -292.230048)
		(mid 327.570606 -292.435558)
		(end 327.495662 -292.71595)
		(width 0.0889)
		(layer "In6.Cu")
		(net "M_E_CPU0_SB_DQ<28>")
	)
	(arc
		(start 328.71791 -292.228524)
		(mid 328.530966 -292.278848)
		(end 328.344022 -292.228524)
		(width 0.0889)
		(layer "In6.Cu")
		(net "M_E_CPU0_SB_DQ<28>")
	)
	(arc
		(start 326.836024 -293.849806)
		(mid 326.630902 -294.055405)
		(end 326.555862 -294.335962)
		(width 0.0889)
		(layer "In6.Cu")
		(net "M_E_CPU0_SB_DQ<28>")
	)
	(arc
		(start 328.344022 -292.228524)
		(mid 328.06121 -292.152475)
		(end 327.778364 -292.228524)
		(width 0.0889)
		(layer "In6.Cu")
		(net "M_E_CPU0_SB_DQ<28>")
	)
	(segment
		(start 330.877926 -290.019994)
		(end 330.411074 -290.285932)
		(width 0.10668)
		(layer "F.Cu")
		(net "M_E_CPU0_SB_DQ<27>")
	)
	(segment
		(start 325.882254 -290.536376)
		(end 325.882254 -290.930838)
		(width 0.0889)
		(layer "In6.Cu")
		(net "M_E_CPU0_SB_DQ<27>")
	)
	(segment
		(start 324.688454 -292.758622)
		(end 324.124574 -293.322502)
		(width 0.0889)
		(layer "In6.Cu")
		(net "M_E_CPU0_SB_DQ<27>")
	)
	(segment
		(start 327.41108 -289.958526)
		(end 327.402698 -289.963352)
		(width 0.0889)
		(layer "In6.Cu")
		(net "M_E_CPU0_SB_DQ<27>")
	)
	(segment
		(start 326.849486 -289.970464)
		(end 326.837548 -289.963606)
		(width 0.0889)
		(layer "In6.Cu")
		(net "M_E_CPU0_SB_DQ<27>")
	)
	(segment
		(start 302.080168 -312.13171)
		(end 301.598838 -311.65038)
		(width 0.14478)
		(layer "In6.Cu")
		(net "M_E_CPU0_SB_DQ<27>")
	)
	(segment
		(start 325.882254 -290.930838)
		(end 324.688454 -292.124638)
		(width 0.0889)
		(layer "In6.Cu")
		(net "M_E_CPU0_SB_DQ<27>")
	)
	(segment
		(start 293.931848 -312.03265)
		(end 293.549578 -311.65038)
		(width 0.14478)
		(layer "In6.Cu")
		(net "M_E_CPU0_SB_DQ<27>")
	)
	(segment
		(start 285.980378 -311.65038)
		(end 283.054298 -311.65038)
		(width 0.14478)
		(layer "In6.Cu")
		(net "M_E_CPU0_SB_DQ<27>")
	)
	(segment
		(start 293.549578 -311.65038)
		(end 290.651438 -311.65038)
		(width 0.14478)
		(layer "In6.Cu")
		(net "M_E_CPU0_SB_DQ<27>")
	)
	(segment
		(start 301.598838 -311.65038)
		(end 298.389802 -311.65038)
		(width 0.14478)
		(layer "In6.Cu")
		(net "M_E_CPU0_SB_DQ<27>")
	)
	(segment
		(start 273.507454 -312.500264)
		(end 273.092164 -312.084974)
		(width 0.14478)
		(layer "In6.Cu")
		(net "M_E_CPU0_SB_DQ<27>")
	)
	(segment
		(start 328.344022 -289.963352)
		(end 328.325988 -289.97402)
		(width 0.0889)
		(layer "In6.Cu")
		(net "M_E_CPU0_SB_DQ<27>")
	)
	(segment
		(start 298.389802 -311.65038)
		(end 296.33799 -312.500264)
		(width 0.14478)
		(layer "In6.Cu")
		(net "M_E_CPU0_SB_DQ<27>")
	)
	(segment
		(start 310.387238 -308.750208)
		(end 307.866034 -311.271412)
		(width 0.14478)
		(layer "In6.Cu")
		(net "M_E_CPU0_SB_DQ<27>")
	)
	(segment
		(start 310.387238 -307.488336)
		(end 310.387238 -308.750208)
		(width 0.14478)
		(layer "In6.Cu")
		(net "M_E_CPU0_SB_DQ<27>")
	)
	(segment
		(start 305.718718 -311.271412)
		(end 304.85842 -312.13171)
		(width 0.14478)
		(layer "In6.Cu")
		(net "M_E_CPU0_SB_DQ<27>")
	)
	(segment
		(start 304.85842 -312.13171)
		(end 302.080168 -312.13171)
		(width 0.14478)
		(layer "In6.Cu")
		(net "M_E_CPU0_SB_DQ<27>")
	)
	(segment
		(start 296.33799 -312.500264)
		(end 295.060878 -312.500264)
		(width 0.14478)
		(layer "In6.Cu")
		(net "M_E_CPU0_SB_DQ<27>")
	)
	(segment
		(start 287.542478 -312.500264)
		(end 286.326834 -311.996836)
		(width 0.14478)
		(layer "In6.Cu")
		(net "M_E_CPU0_SB_DQ<27>")
	)
	(segment
		(start 319.213992 -297.234864)
		(end 313.899042 -302.549814)
		(width 0.14478)
		(layer "In6.Cu")
		(net "M_E_CPU0_SB_DQ<27>")
	)
	(segment
		(start 289.144456 -312.500264)
		(end 287.542478 -312.500264)
		(width 0.14478)
		(layer "In6.Cu")
		(net "M_E_CPU0_SB_DQ<27>")
	)
	(segment
		(start 320.212212 -297.234864)
		(end 319.213992 -297.234864)
		(width 0.14478)
		(layer "In6.Cu")
		(net "M_E_CPU0_SB_DQ<27>")
	)
	(segment
		(start 295.060878 -312.500264)
		(end 293.931848 -312.03265)
		(width 0.14478)
		(layer "In6.Cu")
		(net "M_E_CPU0_SB_DQ<27>")
	)
	(segment
		(start 330.411074 -290.285932)
		(end 330.564998 -290.020502)
		(width 0.0889)
		(layer "In6.Cu")
		(net "M_E_CPU0_SB_DQ<27>")
	)
	(segment
		(start 290.26612 -312.035698)
		(end 289.144456 -312.500264)
		(width 0.14478)
		(layer "In6.Cu")
		(net "M_E_CPU0_SB_DQ<27>")
	)
	(segment
		(start 329.292458 -289.958526)
		(end 329.284076 -289.963352)
		(width 0.0889)
		(layer "In6.Cu")
		(net "M_E_CPU0_SB_DQ<27>")
	)
	(segment
		(start 324.124574 -293.322502)
		(end 320.212212 -297.234864)
		(width 0.14478)
		(layer "In6.Cu")
		(net "M_E_CPU0_SB_DQ<27>")
	)
	(segment
		(start 313.899042 -302.549814)
		(end 312.893456 -304.982118)
		(width 0.14478)
		(layer "In6.Cu")
		(net "M_E_CPU0_SB_DQ<27>")
	)
	(segment
		(start 286.326834 -311.996836)
		(end 285.980378 -311.65038)
		(width 0.14478)
		(layer "In6.Cu")
		(net "M_E_CPU0_SB_DQ<27>")
	)
	(segment
		(start 281.742896 -312.500264)
		(end 273.507454 -312.500264)
		(width 0.14478)
		(layer "In6.Cu")
		(net "M_E_CPU0_SB_DQ<27>")
	)
	(segment
		(start 324.688454 -292.124638)
		(end 324.688454 -292.758622)
		(width 0.0889)
		(layer "In6.Cu")
		(net "M_E_CPU0_SB_DQ<27>")
	)
	(segment
		(start 283.054298 -311.65038)
		(end 282.53055 -312.174128)
		(width 0.14478)
		(layer "In6.Cu")
		(net "M_E_CPU0_SB_DQ<27>")
	)
	(segment
		(start 328.718164 -289.963352)
		(end 328.709782 -289.958526)
		(width 0.0889)
		(layer "In6.Cu")
		(net "M_E_CPU0_SB_DQ<27>")
	)
	(segment
		(start 290.651438 -311.65038)
		(end 290.26612 -312.035698)
		(width 0.14478)
		(layer "In6.Cu")
		(net "M_E_CPU0_SB_DQ<27>")
	)
	(segment
		(start 330.564998 -290.020502)
		(end 330.542646 -289.93719)
		(width 0.0889)
		(layer "In6.Cu")
		(net "M_E_CPU0_SB_DQ<27>")
	)
	(segment
		(start 282.53055 -312.174128)
		(end 281.742896 -312.500264)
		(width 0.14478)
		(layer "In6.Cu")
		(net "M_E_CPU0_SB_DQ<27>")
	)
	(segment
		(start 326.401176 -290.017454)
		(end 325.882254 -290.536376)
		(width 0.0889)
		(layer "In6.Cu")
		(net "M_E_CPU0_SB_DQ<27>")
	)
	(segment
		(start 312.893456 -304.982118)
		(end 310.387238 -307.488336)
		(width 0.14478)
		(layer "In6.Cu")
		(net "M_E_CPU0_SB_DQ<27>")
	)
	(segment
		(start 307.866034 -311.271412)
		(end 305.718718 -311.271412)
		(width 0.14478)
		(layer "In6.Cu")
		(net "M_E_CPU0_SB_DQ<27>")
	)
	(arc
		(start 327.777348 -289.963352)
		(mid 327.594843 -289.912875)
		(end 327.41108 -289.958526)
		(width 0.0889)
		(layer "In6.Cu")
		(net "M_E_CPU0_SB_DQ<27>")
	)
	(arc
		(start 326.837548 -289.963606)
		(mid 326.747664 -289.926027)
		(end 326.651112 -289.91306)
		(width 0.0889)
		(layer "In6.Cu")
		(net "M_E_CPU0_SB_DQ<27>")
	)
	(arc
		(start 329.284076 -289.963352)
		(mid 329.00112 -290.039529)
		(end 328.718164 -289.963352)
		(width 0.0889)
		(layer "In6.Cu")
		(net "M_E_CPU0_SB_DQ<27>")
	)
	(arc
		(start 326.651112 -289.91306)
		(mid 326.516887 -289.94311)
		(end 326.401176 -290.017454)
		(width 0.0889)
		(layer "In6.Cu")
		(net "M_E_CPU0_SB_DQ<27>")
	)
	(arc
		(start 330.542646 -289.93719)
		(mid 330.380457 -289.914455)
		(end 330.22413 -289.963352)
		(width 0.0889)
		(layer "In6.Cu")
		(net "M_E_CPU0_SB_DQ<27>")
	)
	(arc
		(start 329.658218 -289.963352)
		(mid 329.475967 -289.913002)
		(end 329.292458 -289.958526)
		(width 0.0889)
		(layer "In6.Cu")
		(net "M_E_CPU0_SB_DQ<27>")
	)
	(arc
		(start 328.325988 -289.97402)
		(mid 328.050293 -290.039863)
		(end 327.777348 -289.963352)
		(width 0.0889)
		(layer "In6.Cu")
		(net "M_E_CPU0_SB_DQ<27>")
	)
	(arc
		(start 328.709782 -289.958526)
		(mid 328.526274 -289.913032)
		(end 328.344022 -289.963352)
		(width 0.0889)
		(layer "In6.Cu")
		(net "M_E_CPU0_SB_DQ<27>")
	)
	(arc
		(start 327.402698 -289.963352)
		(mid 327.12702 -290.039482)
		(end 326.849486 -289.970464)
		(width 0.0889)
		(layer "In6.Cu")
		(net "M_E_CPU0_SB_DQ<27>")
	)
	(arc
		(start 330.22413 -289.963352)
		(mid 329.941174 -290.039529)
		(end 329.658218 -289.963352)
		(width 0.0889)
		(layer "In6.Cu")
		(net "M_E_CPU0_SB_DQ<27>")
	)
	(segment
		(start 329.467972 -289.209988)
		(end 329.00112 -289.475926)
		(width 0.10668)
		(layer "F.Cu")
		(net "M_E_CPU0_SB_DQ<26>")
	)
	(segment
		(start 304.893472 -310.810148)
		(end 302.206152 -310.810148)
		(width 0.14478)
		(layer "In6.Cu")
		(net "M_E_CPU0_SB_DQ<26>")
	)
	(segment
		(start 308.756304 -308.352444)
		(end 308.756304 -308.793642)
		(width 0.14478)
		(layer "In6.Cu")
		(net "M_E_CPU0_SB_DQ<26>")
	)
	(segment
		(start 308.756304 -308.793642)
		(end 307.589936 -309.96001)
		(width 0.14478)
		(layer "In6.Cu")
		(net "M_E_CPU0_SB_DQ<26>")
	)
	(segment
		(start 290.970462 -309.96001)
		(end 290.120324 -310.810148)
		(width 0.14478)
		(layer "In6.Cu")
		(net "M_E_CPU0_SB_DQ<26>")
	)
	(segment
		(start 312.135266 -304.456846)
		(end 309.480458 -307.111654)
		(width 0.14478)
		(layer "In6.Cu")
		(net "M_E_CPU0_SB_DQ<26>")
	)
	(segment
		(start 309.480458 -307.62829)
		(end 308.756304 -308.352444)
		(width 0.14478)
		(layer "In6.Cu")
		(net "M_E_CPU0_SB_DQ<26>")
	)
	(segment
		(start 324.680834 -291.479732)
		(end 323.917056 -292.24351)
		(width 0.0889)
		(layer "In6.Cu")
		(net "M_E_CPU0_SB_DQ<26>")
	)
	(segment
		(start 305.74361 -309.96001)
		(end 304.893472 -310.810148)
		(width 0.14478)
		(layer "In6.Cu")
		(net "M_E_CPU0_SB_DQ<26>")
	)
	(segment
		(start 274.014946 -310.810148)
		(end 273.51736 -310.810148)
		(width 0.14478)
		(layer "In6.Cu")
		(net "M_E_CPU0_SB_DQ<26>")
	)
	(segment
		(start 301.356014 -309.96001)
		(end 298.22521 -309.96001)
		(width 0.14478)
		(layer "In6.Cu")
		(net "M_E_CPU0_SB_DQ<26>")
	)
	(segment
		(start 326.454008 -289.229546)
		(end 325.263002 -290.420552)
		(width 0.0889)
		(layer "In6.Cu")
		(net "M_E_CPU0_SB_DQ<26>")
	)
	(segment
		(start 290.120324 -310.810148)
		(end 286.5882 -310.810148)
		(width 0.14478)
		(layer "In6.Cu")
		(net "M_E_CPU0_SB_DQ<26>")
	)
	(segment
		(start 285.738062 -309.96001)
		(end 283.345382 -309.96001)
		(width 0.14478)
		(layer "In6.Cu")
		(net "M_E_CPU0_SB_DQ<26>")
	)
	(segment
		(start 324.680834 -290.67633)
		(end 324.680834 -291.479732)
		(width 0.0889)
		(layer "In6.Cu")
		(net "M_E_CPU0_SB_DQ<26>")
	)
	(segment
		(start 302.206152 -310.810148)
		(end 301.356014 -309.96001)
		(width 0.14478)
		(layer "In6.Cu")
		(net "M_E_CPU0_SB_DQ<26>")
	)
	(segment
		(start 327.882504 -289.14852)
		(end 327.874122 -289.153346)
		(width 0.0889)
		(layer "In6.Cu")
		(net "M_E_CPU0_SB_DQ<26>")
	)
	(segment
		(start 274.73402 -310.647334)
		(end 274.73402 -310.389524)
		(width 0.14478)
		(layer "In6.Cu")
		(net "M_E_CPU0_SB_DQ<26>")
	)
	(segment
		(start 286.5882 -310.810148)
		(end 285.738062 -309.96001)
		(width 0.14478)
		(layer "In6.Cu")
		(net "M_E_CPU0_SB_DQ<26>")
	)
	(segment
		(start 323.917056 -292.24351)
		(end 321.020694 -295.139872)
		(width 0.14478)
		(layer "In6.Cu")
		(net "M_E_CPU0_SB_DQ<26>")
	)
	(segment
		(start 294.283892 -310.810148)
		(end 293.433754 -309.96001)
		(width 0.14478)
		(layer "In6.Cu")
		(net "M_E_CPU0_SB_DQ<26>")
	)
	(segment
		(start 327.874122 -289.153346)
		(end 327.863708 -289.159442)
		(width 0.0889)
		(layer "In6.Cu")
		(net "M_E_CPU0_SB_DQ<26>")
	)
	(segment
		(start 298.22521 -309.96001)
		(end 297.375072 -310.810148)
		(width 0.14478)
		(layer "In6.Cu")
		(net "M_E_CPU0_SB_DQ<26>")
	)
	(segment
		(start 309.480458 -307.111654)
		(end 309.480458 -307.62829)
		(width 0.14478)
		(layer "In6.Cu")
		(net "M_E_CPU0_SB_DQ<26>")
	)
	(segment
		(start 325.263002 -290.420552)
		(end 324.936612 -290.420552)
		(width 0.0889)
		(layer "In6.Cu")
		(net "M_E_CPU0_SB_DQ<26>")
	)
	(segment
		(start 327.308464 -289.153346)
		(end 327.300082 -289.14852)
		(width 0.0889)
		(layer "In6.Cu")
		(net "M_E_CPU0_SB_DQ<26>")
	)
	(segment
		(start 307.589936 -309.96001)
		(end 305.74361 -309.96001)
		(width 0.14478)
		(layer "In6.Cu")
		(net "M_E_CPU0_SB_DQ<26>")
	)
	(segment
		(start 326.651112 -289.229546)
		(end 326.454008 -289.229546)
		(width 0.0889)
		(layer "In6.Cu")
		(net "M_E_CPU0_SB_DQ<26>")
	)
	(segment
		(start 273.51736 -310.810148)
		(end 273.092164 -310.384952)
		(width 0.14478)
		(layer "In6.Cu")
		(net "M_E_CPU0_SB_DQ<26>")
	)
	(segment
		(start 321.020694 -295.139872)
		(end 320.036698 -295.139872)
		(width 0.14478)
		(layer "In6.Cu")
		(net "M_E_CPU0_SB_DQ<26>")
	)
	(segment
		(start 282.495244 -310.810148)
		(end 274.896834 -310.810148)
		(width 0.14478)
		(layer "In6.Cu")
		(net "M_E_CPU0_SB_DQ<26>")
	)
	(segment
		(start 274.17776 -310.389524)
		(end 274.17776 -310.647334)
		(width 0.14478)
		(layer "In6.Cu")
		(net "M_E_CPU0_SB_DQ<26>")
	)
	(segment
		(start 329.00112 -289.475926)
		(end 329.155044 -289.210496)
		(width 0.0889)
		(layer "In6.Cu")
		(net "M_E_CPU0_SB_DQ<26>")
	)
	(segment
		(start 274.571206 -310.22671)
		(end 274.340574 -310.22671)
		(width 0.14478)
		(layer "In6.Cu")
		(net "M_E_CPU0_SB_DQ<26>")
	)
	(segment
		(start 283.345382 -309.96001)
		(end 282.495244 -310.810148)
		(width 0.14478)
		(layer "In6.Cu")
		(net "M_E_CPU0_SB_DQ<26>")
	)
	(segment
		(start 297.375072 -310.810148)
		(end 294.283892 -310.810148)
		(width 0.14478)
		(layer "In6.Cu")
		(net "M_E_CPU0_SB_DQ<26>")
	)
	(segment
		(start 274.896834 -310.810148)
		(end 274.73402 -310.647334)
		(width 0.14478)
		(layer "In6.Cu")
		(net "M_E_CPU0_SB_DQ<26>")
	)
	(segment
		(start 329.155044 -289.210496)
		(end 329.132692 -289.127184)
		(width 0.0889)
		(layer "In6.Cu")
		(net "M_E_CPU0_SB_DQ<26>")
	)
	(segment
		(start 293.433754 -309.96001)
		(end 290.970462 -309.96001)
		(width 0.14478)
		(layer "In6.Cu")
		(net "M_E_CPU0_SB_DQ<26>")
	)
	(segment
		(start 313.13628 -302.04029)
		(end 312.135266 -304.456846)
		(width 0.14478)
		(layer "In6.Cu")
		(net "M_E_CPU0_SB_DQ<26>")
	)
	(segment
		(start 274.17776 -310.647334)
		(end 274.014946 -310.810148)
		(width 0.14478)
		(layer "In6.Cu")
		(net "M_E_CPU0_SB_DQ<26>")
	)
	(segment
		(start 274.73402 -310.389524)
		(end 274.571206 -310.22671)
		(width 0.14478)
		(layer "In6.Cu")
		(net "M_E_CPU0_SB_DQ<26>")
	)
	(segment
		(start 320.036698 -295.139872)
		(end 313.13628 -302.04029)
		(width 0.14478)
		(layer "In6.Cu")
		(net "M_E_CPU0_SB_DQ<26>")
	)
	(segment
		(start 274.340574 -310.22671)
		(end 274.17776 -310.389524)
		(width 0.14478)
		(layer "In6.Cu")
		(net "M_E_CPU0_SB_DQ<26>")
	)
	(segment
		(start 324.936612 -290.420552)
		(end 324.680834 -290.67633)
		(width 0.0889)
		(layer "In6.Cu")
		(net "M_E_CPU0_SB_DQ<26>")
	)
	(arc
		(start 328.814176 -289.153346)
		(mid 328.53122 -289.229523)
		(end 328.248264 -289.153346)
		(width 0.0889)
		(layer "In6.Cu")
		(net "M_E_CPU0_SB_DQ<26>")
	)
	(arc
		(start 326.934322 -289.153346)
		(mid 326.797759 -289.210179)
		(end 326.651112 -289.229546)
		(width 0.0889)
		(layer "In6.Cu")
		(net "M_E_CPU0_SB_DQ<26>")
	)
	(arc
		(start 328.248264 -289.153346)
		(mid 328.066013 -289.102996)
		(end 327.882504 -289.14852)
		(width 0.0889)
		(layer "In6.Cu")
		(net "M_E_CPU0_SB_DQ<26>")
	)
	(arc
		(start 329.132692 -289.127184)
		(mid 328.970503 -289.104449)
		(end 328.814176 -289.153346)
		(width 0.0889)
		(layer "In6.Cu")
		(net "M_E_CPU0_SB_DQ<26>")
	)
	(arc
		(start 327.300082 -289.14852)
		(mid 327.116574 -289.103026)
		(end 326.934322 -289.153346)
		(width 0.0889)
		(layer "In6.Cu")
		(net "M_E_CPU0_SB_DQ<26>")
	)
	(arc
		(start 327.863708 -289.159442)
		(mid 327.585276 -289.22954)
		(end 327.308464 -289.153346)
		(width 0.0889)
		(layer "In6.Cu")
		(net "M_E_CPU0_SB_DQ<26>")
	)
	(segment
		(start 331.34808 -289.209988)
		(end 330.880974 -289.475926)
		(width 0.10668)
		(layer "F.Cu")
		(net "M_E_CPU0_SB_DQ<25>")
	)
	(segment
		(start 278.396446 -311.430924)
		(end 278.396446 -311.883044)
		(width 0.14478)
		(layer "In6.Cu")
		(net "M_E_CPU0_SB_DQ<25>")
	)
	(segment
		(start 293.547546 -310.809894)
		(end 290.78047 -310.809894)
		(width 0.14478)
		(layer "In6.Cu")
		(net "M_E_CPU0_SB_DQ<25>")
	)
	(segment
		(start 279.67178 -311.26811)
		(end 279.508966 -311.430924)
		(width 0.14478)
		(layer "In6.Cu")
		(net "M_E_CPU0_SB_DQ<25>")
	)
	(segment
		(start 324.477634 -292.04793)
		(end 324.477634 -292.326314)
		(width 0.0889)
		(layer "In6.Cu")
		(net "M_E_CPU0_SB_DQ<25>")
	)
	(segment
		(start 290.78047 -310.809894)
		(end 289.930332 -311.660032)
		(width 0.14478)
		(layer "In6.Cu")
		(net "M_E_CPU0_SB_DQ<25>")
	)
	(segment
		(start 312.510932 -304.728372)
		(end 309.937658 -307.301646)
		(width 0.14478)
		(layer "In6.Cu")
		(net "M_E_CPU0_SB_DQ<25>")
	)
	(segment
		(start 325.679054 -290.84651)
		(end 324.477634 -292.04793)
		(width 0.0889)
		(layer "In6.Cu")
		(net "M_E_CPU0_SB_DQ<25>")
	)
	(segment
		(start 328.248264 -289.798506)
		(end 328.239882 -289.803332)
		(width 0.0889)
		(layer "In6.Cu")
		(net "M_E_CPU0_SB_DQ<25>")
	)
	(segment
		(start 282.90139 -311.216294)
		(end 281.830018 -311.660032)
		(width 0.14478)
		(layer "In6.Cu")
		(net "M_E_CPU0_SB_DQ<25>")
	)
	(segment
		(start 324.477634 -292.326314)
		(end 323.921374 -292.882574)
		(width 0.0889)
		(layer "In6.Cu")
		(net "M_E_CPU0_SB_DQ<25>")
	)
	(segment
		(start 330.880974 -289.475926)
		(end 330.72705 -289.741356)
		(width 0.0889)
		(layer "In6.Cu")
		(net "M_E_CPU0_SB_DQ<25>")
	)
	(segment
		(start 279.346152 -312.045858)
		(end 279.11552 -312.045858)
		(width 0.14478)
		(layer "In6.Cu")
		(net "M_E_CPU0_SB_DQ<25>")
	)
	(segment
		(start 294.397684 -311.660032)
		(end 293.547546 -310.809894)
		(width 0.14478)
		(layer "In6.Cu")
		(net "M_E_CPU0_SB_DQ<25>")
	)
	(segment
		(start 319.861184 -296.156126)
		(end 320.091562 -296.386504)
		(width 0.14478)
		(layer "In6.Cu")
		(net "M_E_CPU0_SB_DQ<25>")
	)
	(segment
		(start 326.173592 -289.894772)
		(end 326.003666 -290.064698)
		(width 0.0889)
		(layer "In6.Cu")
		(net "M_E_CPU0_SB_DQ<25>")
	)
	(segment
		(start 319.25768 -296.554906)
		(end 313.517534 -302.295052)
		(width 0.14478)
		(layer "In6.Cu")
		(net "M_E_CPU0_SB_DQ<25>")
	)
	(segment
		(start 279.11552 -312.045858)
		(end 278.952706 -311.883044)
		(width 0.14478)
		(layer "In6.Cu")
		(net "M_E_CPU0_SB_DQ<25>")
	)
	(segment
		(start 305.536854 -310.809894)
		(end 304.686716 -311.660032)
		(width 0.14478)
		(layer "In6.Cu")
		(net "M_E_CPU0_SB_DQ<25>")
	)
	(segment
		(start 278.952706 -311.883044)
		(end 278.952706 -311.430924)
		(width 0.14478)
		(layer "In6.Cu")
		(net "M_E_CPU0_SB_DQ<25>")
	)
	(segment
		(start 278.789892 -311.26811)
		(end 278.55926 -311.26811)
		(width 0.14478)
		(layer "In6.Cu")
		(net "M_E_CPU0_SB_DQ<25>")
	)
	(segment
		(start 319.861184 -295.951402)
		(end 319.861184 -296.156126)
		(width 0.14478)
		(layer "In6.Cu")
		(net "M_E_CPU0_SB_DQ<25>")
	)
	(segment
		(start 320.223134 -295.589452)
		(end 319.861184 -295.951402)
		(width 0.14478)
		(layer "In6.Cu")
		(net "M_E_CPU0_SB_DQ<25>")
	)
	(segment
		(start 285.902146 -310.809894)
		(end 283.30779 -310.809894)
		(width 0.14478)
		(layer "In6.Cu")
		(net "M_E_CPU0_SB_DQ<25>")
	)
	(segment
		(start 325.679054 -290.381182)
		(end 325.679054 -290.84651)
		(width 0.0889)
		(layer "In6.Cu")
		(net "M_E_CPU0_SB_DQ<25>")
	)
	(segment
		(start 320.091562 -296.386504)
		(end 320.091562 -296.591228)
		(width 0.14478)
		(layer "In6.Cu")
		(net "M_E_CPU0_SB_DQ<25>")
	)
	(segment
		(start 286.752284 -311.660032)
		(end 285.902146 -310.809894)
		(width 0.14478)
		(layer "In6.Cu")
		(net "M_E_CPU0_SB_DQ<25>")
	)
	(segment
		(start 302.412908 -311.660032)
		(end 301.56277 -310.809894)
		(width 0.14478)
		(layer "In6.Cu")
		(net "M_E_CPU0_SB_DQ<25>")
	)
	(segment
		(start 309.937658 -307.301646)
		(end 309.937658 -308.563772)
		(width 0.14478)
		(layer "In6.Cu")
		(net "M_E_CPU0_SB_DQ<25>")
	)
	(segment
		(start 278.396446 -311.883044)
		(end 278.233632 -312.045858)
		(width 0.14478)
		(layer "In6.Cu")
		(net "M_E_CPU0_SB_DQ<25>")
	)
	(segment
		(start 279.902412 -311.26811)
		(end 279.67178 -311.26811)
		(width 0.14478)
		(layer "In6.Cu")
		(net "M_E_CPU0_SB_DQ<25>")
	)
	(segment
		(start 319.692782 -296.785284)
		(end 319.462404 -296.554906)
		(width 0.14478)
		(layer "In6.Cu")
		(net "M_E_CPU0_SB_DQ<25>")
	)
	(segment
		(start 326.651112 -289.72256)
		(end 326.58939 -289.72256)
		(width 0.0889)
		(layer "In6.Cu")
		(net "M_E_CPU0_SB_DQ<25>")
	)
	(segment
		(start 326.951594 -289.808666)
		(end 326.933306 -289.798252)
		(width 0.0889)
		(layer "In6.Cu")
		(net "M_E_CPU0_SB_DQ<25>")
	)
	(segment
		(start 309.937658 -308.563772)
		(end 307.691536 -310.809894)
		(width 0.14478)
		(layer "In6.Cu")
		(net "M_E_CPU0_SB_DQ<25>")
	)
	(segment
		(start 277.192232 -311.787286)
		(end 277.192232 -311.23509)
		(width 0.14478)
		(layer "In6.Cu")
		(net "M_E_CPU0_SB_DQ<25>")
	)
	(segment
		(start 321.214496 -295.589452)
		(end 320.223134 -295.589452)
		(width 0.14478)
		(layer "In6.Cu")
		(net "M_E_CPU0_SB_DQ<25>")
	)
	(segment
		(start 330.72705 -289.741356)
		(end 330.631038 -289.766756)
		(width 0.0889)
		(layer "In6.Cu")
		(net "M_E_CPU0_SB_DQ<25>")
	)
	(segment
		(start 283.30779 -310.809894)
		(end 282.90139 -311.216294)
		(width 0.14478)
		(layer "In6.Cu")
		(net "M_E_CPU0_SB_DQ<25>")
	)
	(segment
		(start 278.55926 -311.26811)
		(end 278.396446 -311.430924)
		(width 0.14478)
		(layer "In6.Cu")
		(net "M_E_CPU0_SB_DQ<25>")
	)
	(segment
		(start 280.294334 -311.660032)
		(end 279.902412 -311.26811)
		(width 0.14478)
		(layer "In6.Cu")
		(net "M_E_CPU0_SB_DQ<25>")
	)
	(segment
		(start 278.952706 -311.430924)
		(end 278.789892 -311.26811)
		(width 0.14478)
		(layer "In6.Cu")
		(net "M_E_CPU0_SB_DQ<25>")
	)
	(segment
		(start 281.830018 -311.660032)
		(end 280.294334 -311.660032)
		(width 0.14478)
		(layer "In6.Cu")
		(net "M_E_CPU0_SB_DQ<25>")
	)
	(segment
		(start 304.686716 -311.660032)
		(end 302.412908 -311.660032)
		(width 0.14478)
		(layer "In6.Cu")
		(net "M_E_CPU0_SB_DQ<25>")
	)
	(segment
		(start 313.517534 -302.295052)
		(end 312.510932 -304.728372)
		(width 0.14478)
		(layer "In6.Cu")
		(net "M_E_CPU0_SB_DQ<25>")
	)
	(segment
		(start 279.508966 -311.883044)
		(end 279.346152 -312.045858)
		(width 0.14478)
		(layer "In6.Cu")
		(net "M_E_CPU0_SB_DQ<25>")
	)
	(segment
		(start 298.018454 -310.809894)
		(end 297.168316 -311.660032)
		(width 0.14478)
		(layer "In6.Cu")
		(net "M_E_CPU0_SB_DQ<25>")
	)
	(segment
		(start 301.56277 -310.809894)
		(end 298.018454 -310.809894)
		(width 0.14478)
		(layer "In6.Cu")
		(net "M_E_CPU0_SB_DQ<25>")
	)
	(segment
		(start 320.091562 -296.591228)
		(end 319.897506 -296.785284)
		(width 0.14478)
		(layer "In6.Cu")
		(net "M_E_CPU0_SB_DQ<25>")
	)
	(segment
		(start 279.508966 -311.430924)
		(end 279.508966 -311.883044)
		(width 0.14478)
		(layer "In6.Cu")
		(net "M_E_CPU0_SB_DQ<25>")
	)
	(segment
		(start 327.324974 -289.787838)
		(end 327.30694 -289.798506)
		(width 0.0889)
		(layer "In6.Cu")
		(net "M_E_CPU0_SB_DQ<25>")
	)
	(segment
		(start 325.995538 -290.064698)
		(end 325.679054 -290.381182)
		(width 0.0889)
		(layer "In6.Cu")
		(net "M_E_CPU0_SB_DQ<25>")
	)
	(segment
		(start 319.897506 -296.785284)
		(end 319.692782 -296.785284)
		(width 0.14478)
		(layer "In6.Cu")
		(net "M_E_CPU0_SB_DQ<25>")
	)
	(segment
		(start 323.921374 -292.882574)
		(end 321.214496 -295.589452)
		(width 0.14478)
		(layer "In6.Cu")
		(net "M_E_CPU0_SB_DQ<25>")
	)
	(segment
		(start 307.691536 -310.809894)
		(end 305.536854 -310.809894)
		(width 0.14478)
		(layer "In6.Cu")
		(net "M_E_CPU0_SB_DQ<25>")
	)
	(segment
		(start 326.003666 -290.064698)
		(end 325.995538 -290.064698)
		(width 0.0889)
		(layer "In6.Cu")
		(net "M_E_CPU0_SB_DQ<25>")
	)
	(segment
		(start 289.930332 -311.660032)
		(end 286.752284 -311.660032)
		(width 0.14478)
		(layer "In6.Cu")
		(net "M_E_CPU0_SB_DQ<25>")
	)
	(segment
		(start 278.233632 -312.045858)
		(end 277.450804 -312.045858)
		(width 0.14478)
		(layer "In6.Cu")
		(net "M_E_CPU0_SB_DQ<25>")
	)
	(segment
		(start 330.128118 -289.798506)
		(end 330.119736 -289.803332)
		(width 0.0889)
		(layer "In6.Cu")
		(net "M_E_CPU0_SB_DQ<25>")
	)
	(segment
		(start 277.450804 -312.045858)
		(end 277.192232 -311.787286)
		(width 0.14478)
		(layer "In6.Cu")
		(net "M_E_CPU0_SB_DQ<25>")
	)
	(segment
		(start 319.462404 -296.554906)
		(end 319.25768 -296.554906)
		(width 0.14478)
		(layer "In6.Cu")
		(net "M_E_CPU0_SB_DQ<25>")
	)
	(segment
		(start 297.168316 -311.660032)
		(end 294.397684 -311.660032)
		(width 0.14478)
		(layer "In6.Cu")
		(net "M_E_CPU0_SB_DQ<25>")
	)
	(arc
		(start 327.30694 -289.798506)
		(mid 327.130566 -289.848611)
		(end 326.951594 -289.808666)
		(width 0.0889)
		(layer "In6.Cu")
		(net "M_E_CPU0_SB_DQ<25>")
	)
	(arc
		(start 327.873614 -289.798506)
		(mid 327.60067 -289.721926)
		(end 327.324974 -289.787838)
		(width 0.0889)
		(layer "In6.Cu")
		(net "M_E_CPU0_SB_DQ<25>")
	)
	(arc
		(start 329.753976 -289.798506)
		(mid 329.47102 -289.722329)
		(end 329.188064 -289.798506)
		(width 0.0889)
		(layer "In6.Cu")
		(net "M_E_CPU0_SB_DQ<25>")
	)
	(arc
		(start 328.814176 -289.798506)
		(mid 328.53122 -289.722329)
		(end 328.248264 -289.798506)
		(width 0.0889)
		(layer "In6.Cu")
		(net "M_E_CPU0_SB_DQ<25>")
	)
	(arc
		(start 329.188064 -289.798506)
		(mid 329.00112 -289.848761)
		(end 328.814176 -289.798506)
		(width 0.0889)
		(layer "In6.Cu")
		(net "M_E_CPU0_SB_DQ<25>")
	)
	(arc
		(start 330.119736 -289.803332)
		(mid 329.936228 -289.848826)
		(end 329.753976 -289.798506)
		(width 0.0889)
		(layer "In6.Cu")
		(net "M_E_CPU0_SB_DQ<25>")
	)
	(arc
		(start 326.933306 -289.798252)
		(mid 326.797198 -289.741823)
		(end 326.651112 -289.72256)
		(width 0.0889)
		(layer "In6.Cu")
		(net "M_E_CPU0_SB_DQ<25>")
	)
	(arc
		(start 326.58939 -289.72256)
		(mid 326.364368 -289.76732)
		(end 326.173592 -289.894772)
		(width 0.0889)
		(layer "In6.Cu")
		(net "M_E_CPU0_SB_DQ<25>")
	)
	(arc
		(start 330.631038 -289.766756)
		(mid 330.37583 -289.723279)
		(end 330.128118 -289.798506)
		(width 0.0889)
		(layer "In6.Cu")
		(net "M_E_CPU0_SB_DQ<25>")
	)
	(arc
		(start 328.239882 -289.803332)
		(mid 328.05612 -289.848948)
		(end 327.873614 -289.798506)
		(width 0.0889)
		(layer "In6.Cu")
		(net "M_E_CPU0_SB_DQ<25>")
	)
	(segment
		(start 329.937872 -288.399982)
		(end 329.47102 -288.66592)
		(width 0.10668)
		(layer "F.Cu")
		(net "M_E_CPU0_SB_DQ<24>")
	)
	(segment
		(start 300.768004 -309.41391)
		(end 300.515528 -309.41391)
		(width 0.14478)
		(layer "In6.Cu")
		(net "M_E_CPU0_SB_DQ<24>")
	)
	(segment
		(start 320.55562 -294.624506)
		(end 320.338196 -294.407082)
		(width 0.14478)
		(layer "In6.Cu")
		(net "M_E_CPU0_SB_DQ<24>")
	)
	(segment
		(start 321.738498 -292.802056)
		(end 321.534536 -293.006018)
		(width 0.14478)
		(layer "In6.Cu")
		(net "M_E_CPU0_SB_DQ<24>")
	)
	(segment
		(start 307.290216 -309.110126)
		(end 306.92471 -309.475632)
		(width 0.14478)
		(layer "In6.Cu")
		(net "M_E_CPU0_SB_DQ<24>")
	)
	(segment
		(start 300.211744 -309.110126)
		(end 299.583602 -309.110126)
		(width 0.14478)
		(layer "In6.Cu")
		(net "M_E_CPU0_SB_DQ<24>")
	)
	(segment
		(start 320.736976 -293.803578)
		(end 320.736976 -294.008302)
		(width 0.14478)
		(layer "In6.Cu")
		(net "M_E_CPU0_SB_DQ<24>")
	)
	(segment
		(start 293.371778 -309.110126)
		(end 291.159438 -309.110126)
		(width 0.14478)
		(layer "In6.Cu")
		(net "M_E_CPU0_SB_DQ<24>")
	)
	(segment
		(start 327.788778 -288.982404)
		(end 327.778364 -288.9885)
		(width 0.0889)
		(layer "In6.Cu")
		(net "M_E_CPU0_SB_DQ<24>")
	)
	(segment
		(start 311.754012 -304.202084)
		(end 309.030878 -306.925218)
		(width 0.14478)
		(layer "In6.Cu")
		(net "M_E_CPU0_SB_DQ<24>")
	)
	(segment
		(start 308.091078 -308.381654)
		(end 308.091078 -308.822852)
		(width 0.14478)
		(layer "In6.Cu")
		(net "M_E_CPU0_SB_DQ<24>")
	)
	(segment
		(start 282.65882 -309.960264)
		(end 280.195528 -309.960264)
		(width 0.14478)
		(layer "In6.Cu")
		(net "M_E_CPU0_SB_DQ<24>")
	)
	(segment
		(start 321.35318 -293.826946)
		(end 321.135756 -293.609522)
		(width 0.14478)
		(layer "In6.Cu")
		(net "M_E_CPU0_SB_DQ<24>")
	)
	(segment
		(start 326.651112 -289.038792)
		(end 326.650858 -289.039046)
		(width 0.0889)
		(layer "In6.Cu")
		(net "M_E_CPU0_SB_DQ<24>")
	)
	(segment
		(start 323.9516 -291.565838)
		(end 323.406262 -292.111176)
		(width 0.14478)
		(layer "In6.Cu")
		(net "M_E_CPU0_SB_DQ<24>")
	)
	(segment
		(start 321.135756 -293.609522)
		(end 320.931032 -293.609522)
		(width 0.14478)
		(layer "In6.Cu")
		(net "M_E_CPU0_SB_DQ<24>")
	)
	(segment
		(start 324.464934 -290.58743)
		(end 324.464934 -291.052504)
		(width 0.0889)
		(layer "In6.Cu")
		(net "M_E_CPU0_SB_DQ<24>")
	)
	(segment
		(start 303.602644 -310.345328)
		(end 303.372012 -310.345328)
		(width 0.14478)
		(layer "In6.Cu")
		(net "M_E_CPU0_SB_DQ<24>")
	)
	(segment
		(start 327.404476 -288.9885)
		(end 327.394062 -288.982404)
		(width 0.0889)
		(layer "In6.Cu")
		(net "M_E_CPU0_SB_DQ<24>")
	)
	(segment
		(start 320.9544 -294.225726)
		(end 320.9544 -294.43045)
		(width 0.14478)
		(layer "In6.Cu")
		(net "M_E_CPU0_SB_DQ<24>")
	)
	(segment
		(start 300.515528 -309.41391)
		(end 300.211744 -309.110126)
		(width 0.14478)
		(layer "In6.Cu")
		(net "M_E_CPU0_SB_DQ<24>")
	)
	(segment
		(start 323.406262 -292.111176)
		(end 321.738498 -292.802056)
		(width 0.14478)
		(layer "In6.Cu")
		(net "M_E_CPU0_SB_DQ<24>")
	)
	(segment
		(start 329.47102 -288.66592)
		(end 329.317096 -288.93135)
		(width 0.0889)
		(layer "In6.Cu")
		(net "M_E_CPU0_SB_DQ<24>")
	)
	(segment
		(start 325.275194 -290.05403)
		(end 324.998334 -290.05403)
		(width 0.0889)
		(layer "In6.Cu")
		(net "M_E_CPU0_SB_DQ<24>")
	)
	(segment
		(start 294.221916 -309.960264)
		(end 293.371778 -309.110126)
		(width 0.14478)
		(layer "In6.Cu")
		(net "M_E_CPU0_SB_DQ<24>")
	)
	(segment
		(start 304.321718 -310.182514)
		(end 304.321718 -309.830724)
		(width 0.14478)
		(layer "In6.Cu")
		(net "M_E_CPU0_SB_DQ<24>")
	)
	(segment
		(start 297.581828 -309.960264)
		(end 294.221916 -309.960264)
		(width 0.14478)
		(layer "In6.Cu")
		(net "M_E_CPU0_SB_DQ<24>")
	)
	(segment
		(start 320.931032 -293.609522)
		(end 320.736976 -293.803578)
		(width 0.14478)
		(layer "In6.Cu")
		(net "M_E_CPU0_SB_DQ<24>")
	)
	(segment
		(start 299.027342 -309.41391)
		(end 298.723558 -309.110126)
		(width 0.14478)
		(layer "In6.Cu")
		(net "M_E_CPU0_SB_DQ<24>")
	)
	(segment
		(start 278.00935 -310.352186)
		(end 277.192232 -309.535068)
		(width 0.14478)
		(layer "In6.Cu")
		(net "M_E_CPU0_SB_DQ<24>")
	)
	(segment
		(start 298.723558 -309.110126)
		(end 298.431966 -309.110126)
		(width 0.14478)
		(layer "In6.Cu")
		(net "M_E_CPU0_SB_DQ<24>")
	)
	(segment
		(start 278.558498 -309.666386)
		(end 278.395684 -309.8292)
		(width 0.14478)
		(layer "In6.Cu")
		(net "M_E_CPU0_SB_DQ<24>")
	)
	(segment
		(start 301.071788 -309.110126)
		(end 300.768004 -309.41391)
		(width 0.14478)
		(layer "In6.Cu")
		(net "M_E_CPU0_SB_DQ<24>")
	)
	(segment
		(start 298.431966 -309.110126)
		(end 297.581828 -309.960264)
		(width 0.14478)
		(layer "In6.Cu")
		(net "M_E_CPU0_SB_DQ<24>")
	)
	(segment
		(start 302.986948 -309.960264)
		(end 302.142144 -309.960264)
		(width 0.14478)
		(layer "In6.Cu")
		(net "M_E_CPU0_SB_DQ<24>")
	)
	(segment
		(start 301.292006 -309.110126)
		(end 301.071788 -309.110126)
		(width 0.14478)
		(layer "In6.Cu")
		(net "M_E_CPU0_SB_DQ<24>")
	)
	(segment
		(start 306.339494 -309.121048)
		(end 305.939444 -309.121048)
		(width 0.14478)
		(layer "In6.Cu")
		(net "M_E_CPU0_SB_DQ<24>")
	)
	(segment
		(start 303.372012 -310.345328)
		(end 302.986948 -309.960264)
		(width 0.14478)
		(layer "In6.Cu")
		(net "M_E_CPU0_SB_DQ<24>")
	)
	(segment
		(start 279.508204 -309.8292)
		(end 279.508204 -310.189372)
		(width 0.14478)
		(layer "In6.Cu")
		(net "M_E_CPU0_SB_DQ<24>")
	)
	(segment
		(start 279.90165 -309.666386)
		(end 279.671018 -309.666386)
		(width 0.14478)
		(layer "In6.Cu")
		(net "M_E_CPU0_SB_DQ<24>")
	)
	(segment
		(start 306.92471 -309.475632)
		(end 306.694078 -309.475632)
		(width 0.14478)
		(layer "In6.Cu")
		(net "M_E_CPU0_SB_DQ<24>")
	)
	(segment
		(start 320.736976 -294.008302)
		(end 320.9544 -294.225726)
		(width 0.14478)
		(layer "In6.Cu")
		(net "M_E_CPU0_SB_DQ<24>")
	)
	(segment
		(start 320.760344 -294.624506)
		(end 320.55562 -294.624506)
		(width 0.14478)
		(layer "In6.Cu")
		(net "M_E_CPU0_SB_DQ<24>")
	)
	(segment
		(start 306.694078 -309.475632)
		(end 306.339494 -309.121048)
		(width 0.14478)
		(layer "In6.Cu")
		(net "M_E_CPU0_SB_DQ<24>")
	)
	(segment
		(start 309.030878 -306.925218)
		(end 309.030878 -307.441854)
		(width 0.14478)
		(layer "In6.Cu")
		(net "M_E_CPU0_SB_DQ<24>")
	)
	(segment
		(start 304.484532 -310.345328)
		(end 304.321718 -310.182514)
		(width 0.14478)
		(layer "In6.Cu")
		(net "M_E_CPU0_SB_DQ<24>")
	)
	(segment
		(start 278.395684 -309.8292)
		(end 278.395684 -310.189372)
		(width 0.14478)
		(layer "In6.Cu")
		(net "M_E_CPU0_SB_DQ<24>")
	)
	(segment
		(start 291.159438 -309.110126)
		(end 290.3093 -309.960264)
		(width 0.14478)
		(layer "In6.Cu")
		(net "M_E_CPU0_SB_DQ<24>")
	)
	(segment
		(start 286.601916 -309.960264)
		(end 285.751778 -309.110126)
		(width 0.14478)
		(layer "In6.Cu")
		(net "M_E_CPU0_SB_DQ<24>")
	)
	(segment
		(start 324.464934 -291.052504)
		(end 323.9516 -291.565838)
		(width 0.0889)
		(layer "In6.Cu")
		(net "M_E_CPU0_SB_DQ<24>")
	)
	(segment
		(start 320.338196 -294.407082)
		(end 320.133472 -294.407082)
		(width 0.14478)
		(layer "In6.Cu")
		(net "M_E_CPU0_SB_DQ<24>")
	)
	(segment
		(start 320.9544 -294.43045)
		(end 320.760344 -294.624506)
		(width 0.14478)
		(layer "In6.Cu")
		(net "M_E_CPU0_SB_DQ<24>")
	)
	(segment
		(start 321.534536 -293.006018)
		(end 321.534536 -293.210742)
		(width 0.14478)
		(layer "In6.Cu")
		(net "M_E_CPU0_SB_DQ<24>")
	)
	(segment
		(start 304.321718 -309.830724)
		(end 304.158904 -309.66791)
		(width 0.14478)
		(layer "In6.Cu")
		(net "M_E_CPU0_SB_DQ<24>")
	)
	(segment
		(start 283.508958 -309.110126)
		(end 282.65882 -309.960264)
		(width 0.14478)
		(layer "In6.Cu")
		(net "M_E_CPU0_SB_DQ<24>")
	)
	(segment
		(start 321.534536 -293.210742)
		(end 321.75196 -293.428166)
		(width 0.14478)
		(layer "In6.Cu")
		(net "M_E_CPU0_SB_DQ<24>")
	)
	(segment
		(start 285.751778 -309.110126)
		(end 283.508958 -309.110126)
		(width 0.14478)
		(layer "In6.Cu")
		(net "M_E_CPU0_SB_DQ<24>")
	)
	(segment
		(start 308.091078 -308.822852)
		(end 307.803804 -309.110126)
		(width 0.14478)
		(layer "In6.Cu")
		(net "M_E_CPU0_SB_DQ<24>")
	)
	(segment
		(start 321.557904 -293.826946)
		(end 321.35318 -293.826946)
		(width 0.14478)
		(layer "In6.Cu")
		(net "M_E_CPU0_SB_DQ<24>")
	)
	(segment
		(start 321.75196 -293.63289)
		(end 321.557904 -293.826946)
		(width 0.14478)
		(layer "In6.Cu")
		(net "M_E_CPU0_SB_DQ<24>")
	)
	(segment
		(start 304.158904 -309.66791)
		(end 303.928272 -309.66791)
		(width 0.14478)
		(layer "In6.Cu")
		(net "M_E_CPU0_SB_DQ<24>")
	)
	(segment
		(start 279.114758 -310.352186)
		(end 278.951944 -310.189372)
		(width 0.14478)
		(layer "In6.Cu")
		(net "M_E_CPU0_SB_DQ<24>")
	)
	(segment
		(start 305.939444 -309.121048)
		(end 304.715164 -310.345328)
		(width 0.14478)
		(layer "In6.Cu")
		(net "M_E_CPU0_SB_DQ<24>")
	)
	(segment
		(start 304.715164 -310.345328)
		(end 304.484532 -310.345328)
		(width 0.14478)
		(layer "In6.Cu")
		(net "M_E_CPU0_SB_DQ<24>")
	)
	(segment
		(start 278.951944 -310.189372)
		(end 278.951944 -309.8292)
		(width 0.14478)
		(layer "In6.Cu")
		(net "M_E_CPU0_SB_DQ<24>")
	)
	(segment
		(start 278.395684 -310.189372)
		(end 278.23287 -310.352186)
		(width 0.14478)
		(layer "In6.Cu")
		(net "M_E_CPU0_SB_DQ<24>")
	)
	(segment
		(start 303.928272 -309.66791)
		(end 303.765458 -309.830724)
		(width 0.14478)
		(layer "In6.Cu")
		(net "M_E_CPU0_SB_DQ<24>")
	)
	(segment
		(start 328.718164 -288.9885)
		(end 328.709782 -288.993326)
		(width 0.0889)
		(layer "In6.Cu")
		(net "M_E_CPU0_SB_DQ<24>")
	)
	(segment
		(start 302.142144 -309.960264)
		(end 301.292006 -309.110126)
		(width 0.14478)
		(layer "In6.Cu")
		(net "M_E_CPU0_SB_DQ<24>")
	)
	(segment
		(start 303.765458 -310.182514)
		(end 303.602644 -310.345328)
		(width 0.14478)
		(layer "In6.Cu")
		(net "M_E_CPU0_SB_DQ<24>")
	)
	(segment
		(start 307.803804 -309.110126)
		(end 307.290216 -309.110126)
		(width 0.14478)
		(layer "In6.Cu")
		(net "M_E_CPU0_SB_DQ<24>")
	)
	(segment
		(start 329.317096 -288.93135)
		(end 329.221084 -288.95675)
		(width 0.0889)
		(layer "In6.Cu")
		(net "M_E_CPU0_SB_DQ<24>")
	)
	(segment
		(start 309.030878 -307.441854)
		(end 308.091078 -308.381654)
		(width 0.14478)
		(layer "In6.Cu")
		(net "M_E_CPU0_SB_DQ<24>")
	)
	(segment
		(start 279.671018 -309.666386)
		(end 279.508204 -309.8292)
		(width 0.14478)
		(layer "In6.Cu")
		(net "M_E_CPU0_SB_DQ<24>")
	)
	(segment
		(start 320.133472 -294.407082)
		(end 312.755026 -301.785528)
		(width 0.14478)
		(layer "In6.Cu")
		(net "M_E_CPU0_SB_DQ<24>")
	)
	(segment
		(start 290.3093 -309.960264)
		(end 286.601916 -309.960264)
		(width 0.14478)
		(layer "In6.Cu")
		(net "M_E_CPU0_SB_DQ<24>")
	)
	(segment
		(start 278.23287 -310.352186)
		(end 278.00935 -310.352186)
		(width 0.14478)
		(layer "In6.Cu")
		(net "M_E_CPU0_SB_DQ<24>")
	)
	(segment
		(start 278.951944 -309.8292)
		(end 278.78913 -309.666386)
		(width 0.14478)
		(layer "In6.Cu")
		(net "M_E_CPU0_SB_DQ<24>")
	)
	(segment
		(start 326.290178 -289.039046)
		(end 325.275194 -290.05403)
		(width 0.0889)
		(layer "In6.Cu")
		(net "M_E_CPU0_SB_DQ<24>")
	)
	(segment
		(start 324.998334 -290.05403)
		(end 324.464934 -290.58743)
		(width 0.0889)
		(layer "In6.Cu")
		(net "M_E_CPU0_SB_DQ<24>")
	)
	(segment
		(start 303.765458 -309.830724)
		(end 303.765458 -310.182514)
		(width 0.14478)
		(layer "In6.Cu")
		(net "M_E_CPU0_SB_DQ<24>")
	)
	(segment
		(start 321.75196 -293.428166)
		(end 321.75196 -293.63289)
		(width 0.14478)
		(layer "In6.Cu")
		(net "M_E_CPU0_SB_DQ<24>")
	)
	(segment
		(start 326.650858 -289.039046)
		(end 326.290178 -289.039046)
		(width 0.0889)
		(layer "In6.Cu")
		(net "M_E_CPU0_SB_DQ<24>")
	)
	(segment
		(start 299.583602 -309.110126)
		(end 299.279818 -309.41391)
		(width 0.14478)
		(layer "In6.Cu")
		(net "M_E_CPU0_SB_DQ<24>")
	)
	(segment
		(start 280.195528 -309.960264)
		(end 279.90165 -309.666386)
		(width 0.14478)
		(layer "In6.Cu")
		(net "M_E_CPU0_SB_DQ<24>")
	)
	(segment
		(start 312.755026 -301.785528)
		(end 311.754012 -304.202084)
		(width 0.14478)
		(layer "In6.Cu")
		(net "M_E_CPU0_SB_DQ<24>")
	)
	(segment
		(start 279.508204 -310.189372)
		(end 279.34539 -310.352186)
		(width 0.14478)
		(layer "In6.Cu")
		(net "M_E_CPU0_SB_DQ<24>")
	)
	(segment
		(start 279.34539 -310.352186)
		(end 279.114758 -310.352186)
		(width 0.14478)
		(layer "In6.Cu")
		(net "M_E_CPU0_SB_DQ<24>")
	)
	(segment
		(start 299.279818 -309.41391)
		(end 299.027342 -309.41391)
		(width 0.14478)
		(layer "In6.Cu")
		(net "M_E_CPU0_SB_DQ<24>")
	)
	(segment
		(start 278.78913 -309.666386)
		(end 278.558498 -309.666386)
		(width 0.14478)
		(layer "In6.Cu")
		(net "M_E_CPU0_SB_DQ<24>")
	)
	(arc
		(start 329.221084 -288.95675)
		(mid 328.965876 -288.913273)
		(end 328.718164 -288.9885)
		(width 0.0889)
		(layer "In6.Cu")
		(net "M_E_CPU0_SB_DQ<24>")
	)
	(arc
		(start 328.709782 -288.993326)
		(mid 328.526274 -289.03882)
		(end 328.344022 -288.9885)
		(width 0.0889)
		(layer "In6.Cu")
		(net "M_E_CPU0_SB_DQ<24>")
	)
	(arc
		(start 327.394062 -288.982404)
		(mid 327.115376 -288.912184)
		(end 326.83831 -288.9885)
		(width 0.0889)
		(layer "In6.Cu")
		(net "M_E_CPU0_SB_DQ<24>")
	)
	(arc
		(start 326.83831 -288.9885)
		(mid 326.748034 -289.026005)
		(end 326.651112 -289.038792)
		(width 0.0889)
		(layer "In6.Cu")
		(net "M_E_CPU0_SB_DQ<24>")
	)
	(arc
		(start 328.344022 -288.9885)
		(mid 328.067209 -288.912357)
		(end 327.788778 -288.982404)
		(width 0.0889)
		(layer "In6.Cu")
		(net "M_E_CPU0_SB_DQ<24>")
	)
	(arc
		(start 327.778364 -288.9885)
		(mid 327.59142 -289.038755)
		(end 327.404476 -288.9885)
		(width 0.0889)
		(layer "In6.Cu")
		(net "M_E_CPU0_SB_DQ<24>")
	)
	(segment
		(start 330.877926 -288.399982)
		(end 330.411074 -288.66592)
		(width 0.10668)
		(layer "F.Cu")
		(net "M_E_CPU0_SB_DQ<23>")
	)
	(segment
		(start 288.172906 -309.110126)
		(end 286.75076 -308.827424)
		(width 0.14478)
		(layer "In6.Cu")
		(net "M_E_CPU0_SB_DQ<23>")
	)
	(segment
		(start 330.411074 -288.66592)
		(end 330.564998 -288.40049)
		(width 0.0889)
		(layer "In6.Cu")
		(net "M_E_CPU0_SB_DQ<23>")
	)
	(segment
		(start 328.718164 -288.343594)
		(end 328.709782 -288.338768)
		(width 0.0889)
		(layer "In6.Cu")
		(net "M_E_CPU0_SB_DQ<23>")
	)
	(segment
		(start 329.292458 -288.338768)
		(end 329.284076 -288.343594)
		(width 0.0889)
		(layer "In6.Cu")
		(net "M_E_CPU0_SB_DQ<23>")
	)
	(segment
		(start 326.4789 -288.335212)
		(end 326.464422 -288.343594)
		(width 0.0889)
		(layer "In6.Cu")
		(net "M_E_CPU0_SB_DQ<23>")
	)
	(segment
		(start 324.968616 -289.76193)
		(end 323.905118 -290.825428)
		(width 0.0889)
		(layer "In6.Cu")
		(net "M_E_CPU0_SB_DQ<23>")
	)
	(segment
		(start 292.53307 -308.259988)
		(end 292.240716 -308.259988)
		(width 0.14478)
		(layer "In6.Cu")
		(net "M_E_CPU0_SB_DQ<23>")
	)
	(segment
		(start 300.298612 -308.259988)
		(end 299.54982 -308.259988)
		(width 0.14478)
		(layer "In6.Cu")
		(net "M_E_CPU0_SB_DQ<23>")
	)
	(segment
		(start 284.571948 -308.259988)
		(end 281.815794 -308.951122)
		(width 0.14478)
		(layer "In6.Cu")
		(net "M_E_CPU0_SB_DQ<23>")
	)
	(segment
		(start 325.687182 -289.228022)
		(end 325.153274 -289.76193)
		(width 0.0889)
		(layer "In6.Cu")
		(net "M_E_CPU0_SB_DQ<23>")
	)
	(segment
		(start 325.898002 -288.41954)
		(end 325.687182 -288.63036)
		(width 0.0889)
		(layer "In6.Cu")
		(net "M_E_CPU0_SB_DQ<23>")
	)
	(segment
		(start 327.778364 -288.343594)
		(end 327.769982 -288.338768)
		(width 0.0889)
		(layer "In6.Cu")
		(net "M_E_CPU0_SB_DQ<23>")
	)
	(segment
		(start 321.443604 -292.317424)
		(end 312.287666 -301.473362)
		(width 0.14478)
		(layer "In6.Cu")
		(net "M_E_CPU0_SB_DQ<23>")
	)
	(segment
		(start 281.815794 -308.951122)
		(end 281.016202 -309.110126)
		(width 0.14478)
		(layer "In6.Cu")
		(net "M_E_CPU0_SB_DQ<23>")
	)
	(segment
		(start 308.479698 -307.213508)
		(end 307.869336 -307.82387)
		(width 0.14478)
		(layer "In6.Cu")
		(net "M_E_CPU0_SB_DQ<23>")
	)
	(segment
		(start 288.8488 -309.110126)
		(end 288.172906 -309.110126)
		(width 0.14478)
		(layer "In6.Cu")
		(net "M_E_CPU0_SB_DQ<23>")
	)
	(segment
		(start 312.287666 -301.473362)
		(end 311.286652 -303.889918)
		(width 0.14478)
		(layer "In6.Cu")
		(net "M_E_CPU0_SB_DQ<23>")
	)
	(segment
		(start 284.880812 -308.259988)
		(end 284.571948 -308.259988)
		(width 0.14478)
		(layer "In6.Cu")
		(net "M_E_CPU0_SB_DQ<23>")
	)
	(segment
		(start 292.240716 -308.259988)
		(end 288.8488 -309.110126)
		(width 0.14478)
		(layer "In6.Cu")
		(net "M_E_CPU0_SB_DQ<23>")
	)
	(segment
		(start 281.016202 -309.110126)
		(end 275.954998 -309.110126)
		(width 0.14478)
		(layer "In6.Cu")
		(net "M_E_CPU0_SB_DQ<23>")
	)
	(segment
		(start 327.788778 -288.34969)
		(end 327.778364 -288.343594)
		(width 0.0889)
		(layer "In6.Cu")
		(net "M_E_CPU0_SB_DQ<23>")
	)
	(segment
		(start 302.537876 -308.88051)
		(end 302.076866 -308.788816)
		(width 0.14478)
		(layer "In6.Cu")
		(net "M_E_CPU0_SB_DQ<23>")
	)
	(segment
		(start 299.54982 -308.259988)
		(end 298.401486 -308.488334)
		(width 0.14478)
		(layer "In6.Cu")
		(net "M_E_CPU0_SB_DQ<23>")
	)
	(segment
		(start 301.263558 -308.452012)
		(end 300.298612 -308.259988)
		(width 0.14478)
		(layer "In6.Cu")
		(net "M_E_CPU0_SB_DQ<23>")
	)
	(segment
		(start 330.564998 -288.40049)
		(end 330.5429 -288.317432)
		(width 0.0889)
		(layer "In6.Cu")
		(net "M_E_CPU0_SB_DQ<23>")
	)
	(segment
		(start 323.098668 -291.631878)
		(end 321.443604 -292.317424)
		(width 0.14478)
		(layer "In6.Cu")
		(net "M_E_CPU0_SB_DQ<23>")
	)
	(segment
		(start 302.076866 -308.788816)
		(end 301.263558 -308.452012)
		(width 0.14478)
		(layer "In6.Cu")
		(net "M_E_CPU0_SB_DQ<23>")
	)
	(segment
		(start 325.153274 -289.76193)
		(end 324.968616 -289.76193)
		(width 0.0889)
		(layer "In6.Cu")
		(net "M_E_CPU0_SB_DQ<23>")
	)
	(segment
		(start 296.001948 -309.110126)
		(end 295.66489 -309.110126)
		(width 0.14478)
		(layer "In6.Cu")
		(net "M_E_CPU0_SB_DQ<23>")
	)
	(segment
		(start 307.869336 -307.82387)
		(end 306.305966 -308.47157)
		(width 0.14478)
		(layer "In6.Cu")
		(net "M_E_CPU0_SB_DQ<23>")
	)
	(segment
		(start 308.479698 -306.696872)
		(end 308.479698 -307.213508)
		(width 0.14478)
		(layer "In6.Cu")
		(net "M_E_CPU0_SB_DQ<23>")
	)
	(segment
		(start 325.687182 -288.63036)
		(end 325.687182 -289.228022)
		(width 0.0889)
		(layer "In6.Cu")
		(net "M_E_CPU0_SB_DQ<23>")
	)
	(segment
		(start 286.75076 -308.827424)
		(end 284.880812 -308.259988)
		(width 0.14478)
		(layer "In6.Cu")
		(net "M_E_CPU0_SB_DQ<23>")
	)
	(segment
		(start 297.72991 -308.766464)
		(end 296.001948 -309.110126)
		(width 0.14478)
		(layer "In6.Cu")
		(net "M_E_CPU0_SB_DQ<23>")
	)
	(segment
		(start 295.66489 -309.110126)
		(end 294.706294 -308.919372)
		(width 0.14478)
		(layer "In6.Cu")
		(net "M_E_CPU0_SB_DQ<23>")
	)
	(segment
		(start 323.905118 -290.825428)
		(end 323.098668 -291.631878)
		(width 0.14478)
		(layer "In6.Cu")
		(net "M_E_CPU0_SB_DQ<23>")
	)
	(segment
		(start 304.846736 -308.88051)
		(end 302.537876 -308.88051)
		(width 0.14478)
		(layer "In6.Cu")
		(net "M_E_CPU0_SB_DQ<23>")
	)
	(segment
		(start 326.18172 -288.41954)
		(end 325.898002 -288.41954)
		(width 0.0889)
		(layer "In6.Cu")
		(net "M_E_CPU0_SB_DQ<23>")
	)
	(segment
		(start 305.813206 -308.56936)
		(end 305.261772 -308.79796)
		(width 0.14478)
		(layer "In6.Cu")
		(net "M_E_CPU0_SB_DQ<23>")
	)
	(segment
		(start 306.305966 -308.47157)
		(end 305.813206 -308.56936)
		(width 0.14478)
		(layer "In6.Cu")
		(net "M_E_CPU0_SB_DQ<23>")
	)
	(segment
		(start 298.401486 -308.488334)
		(end 297.72991 -308.766464)
		(width 0.14478)
		(layer "In6.Cu")
		(net "M_E_CPU0_SB_DQ<23>")
	)
	(segment
		(start 305.261772 -308.79796)
		(end 304.846736 -308.88051)
		(width 0.14478)
		(layer "In6.Cu")
		(net "M_E_CPU0_SB_DQ<23>")
	)
	(segment
		(start 294.706294 -308.919372)
		(end 292.53307 -308.259988)
		(width 0.14478)
		(layer "In6.Cu")
		(net "M_E_CPU0_SB_DQ<23>")
	)
	(segment
		(start 275.954998 -309.110126)
		(end 273.092164 -308.685184)
		(width 0.14478)
		(layer "In6.Cu")
		(net "M_E_CPU0_SB_DQ<23>")
	)
	(segment
		(start 327.40473 -288.343594)
		(end 327.394316 -288.34969)
		(width 0.0889)
		(layer "In6.Cu")
		(net "M_E_CPU0_SB_DQ<23>")
	)
	(segment
		(start 311.286652 -303.889918)
		(end 308.479698 -306.696872)
		(width 0.14478)
		(layer "In6.Cu")
		(net "M_E_CPU0_SB_DQ<23>")
	)
	(arc
		(start 326.838564 -288.343594)
		(mid 326.659809 -288.293151)
		(end 326.4789 -288.335212)
		(width 0.0889)
		(layer "In6.Cu")
		(net "M_E_CPU0_SB_DQ<23>")
	)
	(arc
		(start 327.769982 -288.338768)
		(mid 327.586728 -288.293364)
		(end 327.40473 -288.343594)
		(width 0.0889)
		(layer "In6.Cu")
		(net "M_E_CPU0_SB_DQ<23>")
	)
	(arc
		(start 329.284076 -288.343594)
		(mid 329.00112 -288.419771)
		(end 328.718164 -288.343594)
		(width 0.0889)
		(layer "In6.Cu")
		(net "M_E_CPU0_SB_DQ<23>")
	)
	(arc
		(start 328.709782 -288.338768)
		(mid 328.526274 -288.293243)
		(end 328.344022 -288.343594)
		(width 0.0889)
		(layer "In6.Cu")
		(net "M_E_CPU0_SB_DQ<23>")
	)
	(arc
		(start 330.5429 -288.317432)
		(mid 330.380569 -288.294583)
		(end 330.22413 -288.343594)
		(width 0.0889)
		(layer "In6.Cu")
		(net "M_E_CPU0_SB_DQ<23>")
	)
	(arc
		(start 327.394316 -288.34969)
		(mid 327.11563 -288.41991)
		(end 326.838564 -288.343594)
		(width 0.0889)
		(layer "In6.Cu")
		(net "M_E_CPU0_SB_DQ<23>")
	)
	(arc
		(start 328.344022 -288.343594)
		(mid 328.067209 -288.419737)
		(end 327.788778 -288.34969)
		(width 0.0889)
		(layer "In6.Cu")
		(net "M_E_CPU0_SB_DQ<23>")
	)
	(arc
		(start 330.22413 -288.343594)
		(mid 329.941174 -288.419771)
		(end 329.658218 -288.343594)
		(width 0.0889)
		(layer "In6.Cu")
		(net "M_E_CPU0_SB_DQ<23>")
	)
	(arc
		(start 326.464422 -288.343594)
		(mid 326.328088 -288.400237)
		(end 326.18172 -288.41954)
		(width 0.0889)
		(layer "In6.Cu")
		(net "M_E_CPU0_SB_DQ<23>")
	)
	(arc
		(start 329.658218 -288.343594)
		(mid 329.475967 -288.29321)
		(end 329.292458 -288.338768)
		(width 0.0889)
		(layer "In6.Cu")
		(net "M_E_CPU0_SB_DQ<23>")
	)
	(segment
		(start 329.467972 -287.59023)
		(end 329.00112 -287.856168)
		(width 0.10668)
		(layer "F.Cu")
		(net "M_E_CPU0_SB_DQ<22>")
	)
	(segment
		(start 327.874122 -287.533588)
		(end 327.863708 -287.539684)
		(width 0.0889)
		(layer "In6.Cu")
		(net "M_E_CPU0_SB_DQ<22>")
	)
	(segment
		(start 273.517106 -307.410104)
		(end 273.092164 -306.985162)
		(width 0.14478)
		(layer "In6.Cu")
		(net "M_E_CPU0_SB_DQ<22>")
	)
	(segment
		(start 329.155044 -287.590738)
		(end 329.132692 -287.507426)
		(width 0.0889)
		(layer "In6.Cu")
		(net "M_E_CPU0_SB_DQ<22>")
	)
	(segment
		(start 321.035172 -291.453824)
		(end 311.432448 -301.056548)
		(width 0.14478)
		(layer "In6.Cu")
		(net "M_E_CPU0_SB_DQ<22>")
	)
	(segment
		(start 325.818754 -287.616138)
		(end 325.280782 -288.15411)
		(width 0.0889)
		(layer "In6.Cu")
		(net "M_E_CPU0_SB_DQ<22>")
	)
	(segment
		(start 290.49726 -307.410104)
		(end 286.591756 -307.410104)
		(width 0.14478)
		(layer "In6.Cu")
		(net "M_E_CPU0_SB_DQ<22>")
	)
	(segment
		(start 324.421754 -289.022536)
		(end 323.89699 -289.5473)
		(width 0.0889)
		(layer "In6.Cu")
		(net "M_E_CPU0_SB_DQ<22>")
	)
	(segment
		(start 305.362864 -307.410104)
		(end 301.831248 -307.410104)
		(width 0.14478)
		(layer "In6.Cu")
		(net "M_E_CPU0_SB_DQ<22>")
	)
	(segment
		(start 324.421754 -288.725864)
		(end 324.421754 -289.022536)
		(width 0.0889)
		(layer "In6.Cu")
		(net "M_E_CPU0_SB_DQ<22>")
	)
	(segment
		(start 301.831248 -307.410104)
		(end 300.98111 -306.559966)
		(width 0.14478)
		(layer "In6.Cu")
		(net "M_E_CPU0_SB_DQ<22>")
	)
	(segment
		(start 311.432448 -301.056548)
		(end 310.616854 -303.025302)
		(width 0.14478)
		(layer "In6.Cu")
		(net "M_E_CPU0_SB_DQ<22>")
	)
	(segment
		(start 293.209218 -306.559966)
		(end 291.347398 -306.559966)
		(width 0.14478)
		(layer "In6.Cu")
		(net "M_E_CPU0_SB_DQ<22>")
	)
	(segment
		(start 283.473398 -306.559966)
		(end 282.62326 -307.410104)
		(width 0.14478)
		(layer "In6.Cu")
		(net "M_E_CPU0_SB_DQ<22>")
	)
	(segment
		(start 310.616854 -303.025302)
		(end 308.558438 -305.083718)
		(width 0.14478)
		(layer "In6.Cu")
		(net "M_E_CPU0_SB_DQ<22>")
	)
	(segment
		(start 324.993508 -288.15411)
		(end 324.421754 -288.725864)
		(width 0.0889)
		(layer "In6.Cu")
		(net "M_E_CPU0_SB_DQ<22>")
	)
	(segment
		(start 327.308464 -287.533588)
		(end 327.300082 -287.528762)
		(width 0.0889)
		(layer "In6.Cu")
		(net "M_E_CPU0_SB_DQ<22>")
	)
	(segment
		(start 300.98111 -306.559966)
		(end 298.738798 -306.559966)
		(width 0.14478)
		(layer "In6.Cu")
		(net "M_E_CPU0_SB_DQ<22>")
	)
	(segment
		(start 326.651366 -287.609788)
		(end 325.818754 -287.616138)
		(width 0.0889)
		(layer "In6.Cu")
		(net "M_E_CPU0_SB_DQ<22>")
	)
	(segment
		(start 307.074824 -305.698144)
		(end 305.362864 -307.410104)
		(width 0.14478)
		(layer "In6.Cu")
		(net "M_E_CPU0_SB_DQ<22>")
	)
	(segment
		(start 323.89699 -289.5473)
		(end 322.665852 -290.778438)
		(width 0.14478)
		(layer "In6.Cu")
		(net "M_E_CPU0_SB_DQ<22>")
	)
	(segment
		(start 325.280782 -288.15411)
		(end 324.993508 -288.15411)
		(width 0.0889)
		(layer "In6.Cu")
		(net "M_E_CPU0_SB_DQ<22>")
	)
	(segment
		(start 291.347398 -306.559966)
		(end 290.49726 -307.410104)
		(width 0.14478)
		(layer "In6.Cu")
		(net "M_E_CPU0_SB_DQ<22>")
	)
	(segment
		(start 298.738798 -306.559966)
		(end 297.88866 -307.410104)
		(width 0.14478)
		(layer "In6.Cu")
		(net "M_E_CPU0_SB_DQ<22>")
	)
	(segment
		(start 308.558438 -305.083718)
		(end 307.074824 -305.698144)
		(width 0.14478)
		(layer "In6.Cu")
		(net "M_E_CPU0_SB_DQ<22>")
	)
	(segment
		(start 327.882504 -287.528762)
		(end 327.874122 -287.533588)
		(width 0.0889)
		(layer "In6.Cu")
		(net "M_E_CPU0_SB_DQ<22>")
	)
	(segment
		(start 297.88866 -307.410104)
		(end 294.059356 -307.410104)
		(width 0.14478)
		(layer "In6.Cu")
		(net "M_E_CPU0_SB_DQ<22>")
	)
	(segment
		(start 285.741618 -306.559966)
		(end 283.473398 -306.559966)
		(width 0.14478)
		(layer "In6.Cu")
		(net "M_E_CPU0_SB_DQ<22>")
	)
	(segment
		(start 322.665852 -290.778438)
		(end 321.035172 -291.453824)
		(width 0.14478)
		(layer "In6.Cu")
		(net "M_E_CPU0_SB_DQ<22>")
	)
	(segment
		(start 282.62326 -307.410104)
		(end 273.517106 -307.410104)
		(width 0.14478)
		(layer "In6.Cu")
		(net "M_E_CPU0_SB_DQ<22>")
	)
	(segment
		(start 329.00112 -287.856168)
		(end 329.155044 -287.590738)
		(width 0.0889)
		(layer "In6.Cu")
		(net "M_E_CPU0_SB_DQ<22>")
	)
	(segment
		(start 294.059356 -307.410104)
		(end 293.209218 -306.559966)
		(width 0.14478)
		(layer "In6.Cu")
		(net "M_E_CPU0_SB_DQ<22>")
	)
	(segment
		(start 286.591756 -307.410104)
		(end 285.741618 -306.559966)
		(width 0.14478)
		(layer "In6.Cu")
		(net "M_E_CPU0_SB_DQ<22>")
	)
	(arc
		(start 329.132692 -287.507426)
		(mid 328.970503 -287.484691)
		(end 328.814176 -287.533588)
		(width 0.0889)
		(layer "In6.Cu")
		(net "M_E_CPU0_SB_DQ<22>")
	)
	(arc
		(start 327.863708 -287.539684)
		(mid 327.585276 -287.60975)
		(end 327.308464 -287.533588)
		(width 0.0889)
		(layer "In6.Cu")
		(net "M_E_CPU0_SB_DQ<22>")
	)
	(arc
		(start 327.300082 -287.528762)
		(mid 327.116574 -287.483268)
		(end 326.934322 -287.533588)
		(width 0.0889)
		(layer "In6.Cu")
		(net "M_E_CPU0_SB_DQ<22>")
	)
	(arc
		(start 326.934322 -287.533588)
		(mid 326.797877 -287.590362)
		(end 326.651366 -287.609788)
		(width 0.0889)
		(layer "In6.Cu")
		(net "M_E_CPU0_SB_DQ<22>")
	)
	(arc
		(start 328.248264 -287.533588)
		(mid 328.066013 -287.483238)
		(end 327.882504 -287.528762)
		(width 0.0889)
		(layer "In6.Cu")
		(net "M_E_CPU0_SB_DQ<22>")
	)
	(arc
		(start 328.814176 -287.533588)
		(mid 328.53122 -287.609731)
		(end 328.248264 -287.533588)
		(width 0.0889)
		(layer "In6.Cu")
		(net "M_E_CPU0_SB_DQ<22>")
	)
	(segment
		(start 331.34808 -287.59023)
		(end 330.880974 -287.856168)
		(width 0.10668)
		(layer "F.Cu")
		(net "M_E_CPU0_SB_DQ<21>")
	)
	(segment
		(start 311.849262 -301.27575)
		(end 310.961532 -303.418748)
		(width 0.14478)
		(layer "In6.Cu")
		(net "M_E_CPU0_SB_DQ<21>")
	)
	(segment
		(start 301.171102 -307.410104)
		(end 298.574714 -307.410104)
		(width 0.14478)
		(layer "In6.Cu")
		(net "M_E_CPU0_SB_DQ<21>")
	)
	(segment
		(start 323.897752 -290.189666)
		(end 322.883276 -291.204142)
		(width 0.14478)
		(layer "In6.Cu")
		(net "M_E_CPU0_SB_DQ<21>")
	)
	(segment
		(start 307.647086 -307.410104)
		(end 306.220114 -307.410104)
		(width 0.14478)
		(layer "In6.Cu")
		(net "M_E_CPU0_SB_DQ<21>")
	)
	(segment
		(start 330.72705 -288.121598)
		(end 330.631292 -288.146998)
		(width 0.0889)
		(layer "In6.Cu")
		(net "M_E_CPU0_SB_DQ<21>")
	)
	(segment
		(start 278.394922 -308.027578)
		(end 278.394922 -308.485286)
		(width 0.14478)
		(layer "In6.Cu")
		(net "M_E_CPU0_SB_DQ<21>")
	)
	(segment
		(start 278.788368 -307.864764)
		(end 278.557736 -307.864764)
		(width 0.14478)
		(layer "In6.Cu")
		(net "M_E_CPU0_SB_DQ<21>")
	)
	(segment
		(start 308.030118 -306.350162)
		(end 308.030118 -307.027072)
		(width 0.14478)
		(layer "In6.Cu")
		(net "M_E_CPU0_SB_DQ<21>")
	)
	(segment
		(start 278.005286 -308.6481)
		(end 277.192232 -307.835046)
		(width 0.14478)
		(layer "In6.Cu")
		(net "M_E_CPU0_SB_DQ<21>")
	)
	(segment
		(start 327.874376 -288.178494)
		(end 327.863962 -288.172398)
		(width 0.0889)
		(layer "In6.Cu")
		(net "M_E_CPU0_SB_DQ<21>")
	)
	(segment
		(start 294.24884 -308.260242)
		(end 293.398702 -307.410104)
		(width 0.14478)
		(layer "In6.Cu")
		(net "M_E_CPU0_SB_DQ<21>")
	)
	(segment
		(start 278.951182 -308.027578)
		(end 278.788368 -307.864764)
		(width 0.14478)
		(layer "In6.Cu")
		(net "M_E_CPU0_SB_DQ<21>")
	)
	(segment
		(start 302.02124 -308.260242)
		(end 301.171102 -307.410104)
		(width 0.14478)
		(layer "In6.Cu")
		(net "M_E_CPU0_SB_DQ<21>")
	)
	(segment
		(start 322.883276 -291.204142)
		(end 321.24015 -291.884862)
		(width 0.14478)
		(layer "In6.Cu")
		(net "M_E_CPU0_SB_DQ<21>")
	)
	(segment
		(start 325.628254 -288.40811)
		(end 325.247254 -288.40811)
		(width 0.0889)
		(layer "In6.Cu")
		(net "M_E_CPU0_SB_DQ<21>")
	)
	(segment
		(start 305.369976 -308.260242)
		(end 302.02124 -308.260242)
		(width 0.14478)
		(layer "In6.Cu")
		(net "M_E_CPU0_SB_DQ<21>")
	)
	(segment
		(start 324.668134 -289.419284)
		(end 323.897752 -290.189666)
		(width 0.0889)
		(layer "In6.Cu")
		(net "M_E_CPU0_SB_DQ<21>")
	)
	(segment
		(start 321.24015 -291.884862)
		(end 311.849262 -301.27575)
		(width 0.14478)
		(layer "In6.Cu")
		(net "M_E_CPU0_SB_DQ<21>")
	)
	(segment
		(start 298.574714 -307.410104)
		(end 297.724576 -308.260242)
		(width 0.14478)
		(layer "In6.Cu")
		(net "M_E_CPU0_SB_DQ<21>")
	)
	(segment
		(start 279.113996 -308.6481)
		(end 278.951182 -308.485286)
		(width 0.14478)
		(layer "In6.Cu")
		(net "M_E_CPU0_SB_DQ<21>")
	)
	(segment
		(start 326.143874 -288.22269)
		(end 325.860664 -288.22269)
		(width 0.0889)
		(layer "In6.Cu")
		(net "M_E_CPU0_SB_DQ<21>")
	)
	(segment
		(start 279.732486 -308.260242)
		(end 279.344628 -308.6481)
		(width 0.14478)
		(layer "In6.Cu")
		(net "M_E_CPU0_SB_DQ<21>")
	)
	(segment
		(start 330.880974 -287.856168)
		(end 330.72705 -288.121598)
		(width 0.0889)
		(layer "In6.Cu")
		(net "M_E_CPU0_SB_DQ<21>")
	)
	(segment
		(start 308.030118 -307.027072)
		(end 307.647086 -307.410104)
		(width 0.14478)
		(layer "In6.Cu")
		(net "M_E_CPU0_SB_DQ<21>")
	)
	(segment
		(start 293.398702 -307.410104)
		(end 291.157914 -307.410104)
		(width 0.14478)
		(layer "In6.Cu")
		(net "M_E_CPU0_SB_DQ<21>")
	)
	(segment
		(start 278.232108 -308.6481)
		(end 278.005286 -308.6481)
		(width 0.14478)
		(layer "In6.Cu")
		(net "M_E_CPU0_SB_DQ<21>")
	)
	(segment
		(start 290.307776 -308.260242)
		(end 286.55264 -308.260242)
		(width 0.14478)
		(layer "In6.Cu")
		(net "M_E_CPU0_SB_DQ<21>")
	)
	(segment
		(start 306.220114 -307.410104)
		(end 305.369976 -308.260242)
		(width 0.14478)
		(layer "In6.Cu")
		(net "M_E_CPU0_SB_DQ<21>")
	)
	(segment
		(start 324.668134 -288.98723)
		(end 324.668134 -289.419284)
		(width 0.0889)
		(layer "In6.Cu")
		(net "M_E_CPU0_SB_DQ<21>")
	)
	(segment
		(start 285.702502 -307.410104)
		(end 283.334714 -307.410104)
		(width 0.14478)
		(layer "In6.Cu")
		(net "M_E_CPU0_SB_DQ<21>")
	)
	(segment
		(start 310.961532 -303.418748)
		(end 308.030118 -306.350162)
		(width 0.14478)
		(layer "In6.Cu")
		(net "M_E_CPU0_SB_DQ<21>")
	)
	(segment
		(start 297.724576 -308.260242)
		(end 294.24884 -308.260242)
		(width 0.14478)
		(layer "In6.Cu")
		(net "M_E_CPU0_SB_DQ<21>")
	)
	(segment
		(start 286.55264 -308.260242)
		(end 285.702502 -307.410104)
		(width 0.14478)
		(layer "In6.Cu")
		(net "M_E_CPU0_SB_DQ<21>")
	)
	(segment
		(start 327.308718 -288.178494)
		(end 327.297034 -288.185352)
		(width 0.0889)
		(layer "In6.Cu")
		(net "M_E_CPU0_SB_DQ<21>")
	)
	(segment
		(start 330.128118 -288.178494)
		(end 330.119736 -288.18332)
		(width 0.0889)
		(layer "In6.Cu")
		(net "M_E_CPU0_SB_DQ<21>")
	)
	(segment
		(start 278.557736 -307.864764)
		(end 278.394922 -308.027578)
		(width 0.14478)
		(layer "In6.Cu")
		(net "M_E_CPU0_SB_DQ<21>")
	)
	(segment
		(start 279.344628 -308.6481)
		(end 279.113996 -308.6481)
		(width 0.14478)
		(layer "In6.Cu")
		(net "M_E_CPU0_SB_DQ<21>")
	)
	(segment
		(start 325.7804 -288.255964)
		(end 325.628254 -288.40811)
		(width 0.0889)
		(layer "In6.Cu")
		(net "M_E_CPU0_SB_DQ<21>")
	)
	(segment
		(start 291.157914 -307.410104)
		(end 290.307776 -308.260242)
		(width 0.14478)
		(layer "In6.Cu")
		(net "M_E_CPU0_SB_DQ<21>")
	)
	(segment
		(start 327.88606 -288.185352)
		(end 327.874376 -288.178494)
		(width 0.0889)
		(layer "In6.Cu")
		(net "M_E_CPU0_SB_DQ<21>")
	)
	(segment
		(start 282.484576 -308.260242)
		(end 279.732486 -308.260242)
		(width 0.14478)
		(layer "In6.Cu")
		(net "M_E_CPU0_SB_DQ<21>")
	)
	(segment
		(start 278.394922 -308.485286)
		(end 278.232108 -308.6481)
		(width 0.14478)
		(layer "In6.Cu")
		(net "M_E_CPU0_SB_DQ<21>")
	)
	(segment
		(start 278.951182 -308.485286)
		(end 278.951182 -308.027578)
		(width 0.14478)
		(layer "In6.Cu")
		(net "M_E_CPU0_SB_DQ<21>")
	)
	(segment
		(start 283.334714 -307.410104)
		(end 282.484576 -308.260242)
		(width 0.14478)
		(layer "In6.Cu")
		(net "M_E_CPU0_SB_DQ<21>")
	)
	(segment
		(start 325.247254 -288.40811)
		(end 324.668134 -288.98723)
		(width 0.0889)
		(layer "In6.Cu")
		(net "M_E_CPU0_SB_DQ<21>")
	)
	(arc
		(start 330.119736 -288.18332)
		(mid 329.936228 -288.228845)
		(end 329.753976 -288.178494)
		(width 0.0889)
		(layer "In6.Cu")
		(net "M_E_CPU0_SB_DQ<21>")
	)
	(arc
		(start 328.248264 -288.178494)
		(mid 328.068059 -288.228845)
		(end 327.88606 -288.185352)
		(width 0.0889)
		(layer "In6.Cu")
		(net "M_E_CPU0_SB_DQ<21>")
	)
	(arc
		(start 330.631292 -288.146998)
		(mid 330.37597 -288.103298)
		(end 330.128118 -288.178494)
		(width 0.0889)
		(layer "In6.Cu")
		(net "M_E_CPU0_SB_DQ<21>")
	)
	(arc
		(start 326.397366 -288.162238)
		(mid 326.274163 -288.207327)
		(end 326.143874 -288.22269)
		(width 0.0889)
		(layer "In6.Cu")
		(net "M_E_CPU0_SB_DQ<21>")
	)
	(arc
		(start 329.753976 -288.178494)
		(mid 329.47102 -288.102317)
		(end 329.188064 -288.178494)
		(width 0.0889)
		(layer "In6.Cu")
		(net "M_E_CPU0_SB_DQ<21>")
	)
	(arc
		(start 329.188064 -288.178494)
		(mid 329.00112 -288.228783)
		(end 328.814176 -288.178494)
		(width 0.0889)
		(layer "In6.Cu")
		(net "M_E_CPU0_SB_DQ<21>")
	)
	(arc
		(start 327.297034 -288.185352)
		(mid 327.114779 -288.229034)
		(end 326.934322 -288.178494)
		(width 0.0889)
		(layer "In6.Cu")
		(net "M_E_CPU0_SB_DQ<21>")
	)
	(arc
		(start 327.863962 -288.172398)
		(mid 327.58553 -288.1023)
		(end 327.308718 -288.178494)
		(width 0.0889)
		(layer "In6.Cu")
		(net "M_E_CPU0_SB_DQ<21>")
	)
	(arc
		(start 325.860664 -288.22269)
		(mid 325.817229 -288.231348)
		(end 325.7804 -288.255964)
		(width 0.0889)
		(layer "In6.Cu")
		(net "M_E_CPU0_SB_DQ<21>")
	)
	(arc
		(start 328.814176 -288.178494)
		(mid 328.53122 -288.102317)
		(end 328.248264 -288.178494)
		(width 0.0889)
		(layer "In6.Cu")
		(net "M_E_CPU0_SB_DQ<21>")
	)
	(arc
		(start 326.934322 -288.178494)
		(mid 326.667906 -288.102285)
		(end 326.397366 -288.162238)
		(width 0.0889)
		(layer "In6.Cu")
		(net "M_E_CPU0_SB_DQ<21>")
	)
	(segment
		(start 329.937872 -286.780224)
		(end 329.47102 -287.045908)
		(width 0.10668)
		(layer "F.Cu")
		(net "M_E_CPU0_SB_DQ<20>")
	)
	(segment
		(start 293.038022 -305.719734)
		(end 291.527738 -305.719734)
		(width 0.14478)
		(layer "In6.Cu")
		(net "M_E_CPU0_SB_DQ<20>")
	)
	(segment
		(start 289.018472 -306.87391)
		(end 288.714434 -306.569872)
		(width 0.14478)
		(layer "In6.Cu")
		(net "M_E_CPU0_SB_DQ<20>")
	)
	(segment
		(start 289.261042 -306.87391)
		(end 289.018472 -306.87391)
		(width 0.14478)
		(layer "In6.Cu")
		(net "M_E_CPU0_SB_DQ<20>")
	)
	(segment
		(start 289.574732 -306.56022)
		(end 289.261042 -306.87391)
		(width 0.14478)
		(layer "In6.Cu")
		(net "M_E_CPU0_SB_DQ<20>")
	)
	(segment
		(start 302.74641 -306.84851)
		(end 301.930054 -306.84851)
		(width 0.14478)
		(layer "In6.Cu")
		(net "M_E_CPU0_SB_DQ<20>")
	)
	(segment
		(start 278.906224 -306.383944)
		(end 278.74341 -306.22113)
		(width 0.14478)
		(layer "In6.Cu")
		(net "M_E_CPU0_SB_DQ<20>")
	)
	(segment
		(start 282.499562 -306.87391)
		(end 282.256992 -306.87391)
		(width 0.14478)
		(layer "In6.Cu")
		(net "M_E_CPU0_SB_DQ<20>")
	)
	(segment
		(start 303.55667 -306.310792)
		(end 303.41189 -306.166012)
		(width 0.14478)
		(layer "In6.Cu")
		(net "M_E_CPU0_SB_DQ<20>")
	)
	(segment
		(start 285.391606 -305.719734)
		(end 283.653738 -305.719734)
		(width 0.14478)
		(layer "In6.Cu")
		(net "M_E_CPU0_SB_DQ<20>")
	)
	(segment
		(start 282.256992 -306.87391)
		(end 281.943302 -306.56022)
		(width 0.14478)
		(layer "In6.Cu")
		(net "M_E_CPU0_SB_DQ<20>")
	)
	(segment
		(start 287.347406 -306.569872)
		(end 287.094168 -306.82311)
		(width 0.14478)
		(layer "In6.Cu")
		(net "M_E_CPU0_SB_DQ<20>")
	)
	(segment
		(start 278.349964 -306.736496)
		(end 278.18715 -306.89931)
		(width 0.14478)
		(layer "In6.Cu")
		(net "M_E_CPU0_SB_DQ<20>")
	)
	(segment
		(start 294.713406 -306.569872)
		(end 294.434768 -306.84851)
		(width 0.14478)
		(layer "In6.Cu")
		(net "M_E_CPU0_SB_DQ<20>")
	)
	(segment
		(start 294.166798 -306.84851)
		(end 293.038022 -305.719734)
		(width 0.14478)
		(layer "In6.Cu")
		(net "M_E_CPU0_SB_DQ<20>")
	)
	(segment
		(start 279.069038 -306.89931)
		(end 278.906224 -306.736496)
		(width 0.14478)
		(layer "In6.Cu")
		(net "M_E_CPU0_SB_DQ<20>")
	)
	(segment
		(start 311.002426 -300.850554)
		(end 310.186832 -302.819308)
		(width 0.14478)
		(layer "In6.Cu")
		(net "M_E_CPU0_SB_DQ<20>")
	)
	(segment
		(start 294.434768 -306.84851)
		(end 294.166798 -306.84851)
		(width 0.14478)
		(layer "In6.Cu")
		(net "M_E_CPU0_SB_DQ<20>")
	)
	(segment
		(start 327.788778 -287.362392)
		(end 327.778364 -287.368488)
		(width 0.0889)
		(layer "In6.Cu")
		(net "M_E_CPU0_SB_DQ<20>")
	)
	(segment
		(start 303.55667 -306.70373)
		(end 303.55667 -306.310792)
		(width 0.14478)
		(layer "In6.Cu")
		(net "M_E_CPU0_SB_DQ<20>")
	)
	(segment
		(start 288.714434 -306.569872)
		(end 287.347406 -306.569872)
		(width 0.14478)
		(layer "In6.Cu")
		(net "M_E_CPU0_SB_DQ<20>")
	)
	(segment
		(start 296.632122 -306.87391)
		(end 296.389552 -306.87391)
		(width 0.14478)
		(layer "In6.Cu")
		(net "M_E_CPU0_SB_DQ<20>")
	)
	(segment
		(start 304.420524 -306.84851)
		(end 303.70145 -306.84851)
		(width 0.14478)
		(layer "In6.Cu")
		(net "M_E_CPU0_SB_DQ<20>")
	)
	(segment
		(start 310.186832 -302.819308)
		(end 308.303676 -304.702464)
		(width 0.14478)
		(layer "In6.Cu")
		(net "M_E_CPU0_SB_DQ<20>")
	)
	(segment
		(start 296.389552 -306.87391)
		(end 296.085514 -306.569872)
		(width 0.14478)
		(layer "In6.Cu")
		(net "M_E_CPU0_SB_DQ<20>")
	)
	(segment
		(start 329.317096 -287.311338)
		(end 329.221084 -287.336738)
		(width 0.0889)
		(layer "In6.Cu")
		(net "M_E_CPU0_SB_DQ<20>")
	)
	(segment
		(start 302.89119 -306.70373)
		(end 302.74641 -306.84851)
		(width 0.14478)
		(layer "In6.Cu")
		(net "M_E_CPU0_SB_DQ<20>")
	)
	(segment
		(start 279.629108 -306.569872)
		(end 279.29967 -306.89931)
		(width 0.14478)
		(layer "In6.Cu")
		(net "M_E_CPU0_SB_DQ<20>")
	)
	(segment
		(start 297.502072 -306.87391)
		(end 297.188382 -306.56022)
		(width 0.14478)
		(layer "In6.Cu")
		(net "M_E_CPU0_SB_DQ<20>")
	)
	(segment
		(start 308.303676 -304.702464)
		(end 306.820062 -305.31689)
		(width 0.14478)
		(layer "In6.Cu")
		(net "M_E_CPU0_SB_DQ<20>")
	)
	(segment
		(start 301.930054 -306.84851)
		(end 300.949106 -305.867562)
		(width 0.14478)
		(layer "In6.Cu")
		(net "M_E_CPU0_SB_DQ<20>")
	)
	(segment
		(start 281.943302 -306.56022)
		(end 281.700732 -306.56022)
		(width 0.14478)
		(layer "In6.Cu")
		(net "M_E_CPU0_SB_DQ<20>")
	)
	(segment
		(start 280.840434 -306.569872)
		(end 279.629108 -306.569872)
		(width 0.14478)
		(layer "In6.Cu")
		(net "M_E_CPU0_SB_DQ<20>")
	)
	(segment
		(start 328.718164 -287.368488)
		(end 328.709782 -287.373314)
		(width 0.0889)
		(layer "In6.Cu")
		(net "M_E_CPU0_SB_DQ<20>")
	)
	(segment
		(start 322.399152 -290.40201)
		(end 320.78041 -291.07257)
		(width 0.14478)
		(layer "In6.Cu")
		(net "M_E_CPU0_SB_DQ<20>")
	)
	(segment
		(start 325.734426 -287.412938)
		(end 325.196454 -287.95091)
		(width 0.0889)
		(layer "In6.Cu")
		(net "M_E_CPU0_SB_DQ<20>")
	)
	(segment
		(start 287.094168 -306.82311)
		(end 286.800798 -306.82311)
		(width 0.14478)
		(layer "In6.Cu")
		(net "M_E_CPU0_SB_DQ<20>")
	)
	(segment
		(start 304.708814 -306.56022)
		(end 304.420524 -306.84851)
		(width 0.14478)
		(layer "In6.Cu")
		(net "M_E_CPU0_SB_DQ<20>")
	)
	(segment
		(start 278.349964 -306.383944)
		(end 278.349964 -306.736496)
		(width 0.14478)
		(layer "In6.Cu")
		(net "M_E_CPU0_SB_DQ<20>")
	)
	(segment
		(start 324.850252 -287.95091)
		(end 323.926454 -288.874708)
		(width 0.0889)
		(layer "In6.Cu")
		(net "M_E_CPU0_SB_DQ<20>")
	)
	(segment
		(start 327.404476 -287.368488)
		(end 327.394062 -287.362392)
		(width 0.0889)
		(layer "In6.Cu")
		(net "M_E_CPU0_SB_DQ<20>")
	)
	(segment
		(start 281.700732 -306.56022)
		(end 281.387042 -306.87391)
		(width 0.14478)
		(layer "In6.Cu")
		(net "M_E_CPU0_SB_DQ<20>")
	)
	(segment
		(start 278.18715 -306.89931)
		(end 277.956518 -306.89931)
		(width 0.14478)
		(layer "In6.Cu")
		(net "M_E_CPU0_SB_DQ<20>")
	)
	(segment
		(start 290.130992 -306.87391)
		(end 289.817302 -306.56022)
		(width 0.14478)
		(layer "In6.Cu")
		(net "M_E_CPU0_SB_DQ<20>")
	)
	(segment
		(start 290.373562 -306.87391)
		(end 290.130992 -306.87391)
		(width 0.14478)
		(layer "In6.Cu")
		(net "M_E_CPU0_SB_DQ<20>")
	)
	(segment
		(start 305.576732 -306.56022)
		(end 304.708814 -306.56022)
		(width 0.14478)
		(layer "In6.Cu")
		(net "M_E_CPU0_SB_DQ<20>")
	)
	(segment
		(start 296.945812 -306.56022)
		(end 296.632122 -306.87391)
		(width 0.14478)
		(layer "In6.Cu")
		(net "M_E_CPU0_SB_DQ<20>")
	)
	(segment
		(start 300.949106 -305.867562)
		(end 300.592236 -305.719734)
		(width 0.14478)
		(layer "In6.Cu")
		(net "M_E_CPU0_SB_DQ<20>")
	)
	(segment
		(start 297.188382 -306.56022)
		(end 296.945812 -306.56022)
		(width 0.14478)
		(layer "In6.Cu")
		(net "M_E_CPU0_SB_DQ<20>")
	)
	(segment
		(start 303.03597 -306.166012)
		(end 302.89119 -306.310792)
		(width 0.14478)
		(layer "In6.Cu")
		(net "M_E_CPU0_SB_DQ<20>")
	)
	(segment
		(start 323.926454 -288.874708)
		(end 322.399152 -290.40201)
		(width 0.14478)
		(layer "In6.Cu")
		(net "M_E_CPU0_SB_DQ<20>")
	)
	(segment
		(start 298.898818 -305.719734)
		(end 297.744642 -306.87391)
		(width 0.14478)
		(layer "In6.Cu")
		(net "M_E_CPU0_SB_DQ<20>")
	)
	(segment
		(start 278.906224 -306.736496)
		(end 278.906224 -306.383944)
		(width 0.14478)
		(layer "In6.Cu")
		(net "M_E_CPU0_SB_DQ<20>")
	)
	(segment
		(start 303.70145 -306.84851)
		(end 303.55667 -306.70373)
		(width 0.14478)
		(layer "In6.Cu")
		(net "M_E_CPU0_SB_DQ<20>")
	)
	(segment
		(start 306.820062 -305.31689)
		(end 305.576732 -306.56022)
		(width 0.14478)
		(layer "In6.Cu")
		(net "M_E_CPU0_SB_DQ<20>")
	)
	(segment
		(start 303.41189 -306.166012)
		(end 303.03597 -306.166012)
		(width 0.14478)
		(layer "In6.Cu")
		(net "M_E_CPU0_SB_DQ<20>")
	)
	(segment
		(start 278.512778 -306.22113)
		(end 278.349964 -306.383944)
		(width 0.14478)
		(layer "In6.Cu")
		(net "M_E_CPU0_SB_DQ<20>")
	)
	(segment
		(start 281.387042 -306.87391)
		(end 281.144472 -306.87391)
		(width 0.14478)
		(layer "In6.Cu")
		(net "M_E_CPU0_SB_DQ<20>")
	)
	(segment
		(start 285.913576 -305.935888)
		(end 285.391606 -305.719734)
		(width 0.14478)
		(layer "In6.Cu")
		(net "M_E_CPU0_SB_DQ<20>")
	)
	(segment
		(start 278.74341 -306.22113)
		(end 278.512778 -306.22113)
		(width 0.14478)
		(layer "In6.Cu")
		(net "M_E_CPU0_SB_DQ<20>")
	)
	(segment
		(start 279.29967 -306.89931)
		(end 279.069038 -306.89931)
		(width 0.14478)
		(layer "In6.Cu")
		(net "M_E_CPU0_SB_DQ<20>")
	)
	(segment
		(start 289.817302 -306.56022)
		(end 289.574732 -306.56022)
		(width 0.14478)
		(layer "In6.Cu")
		(net "M_E_CPU0_SB_DQ<20>")
	)
	(segment
		(start 291.527738 -305.719734)
		(end 290.373562 -306.87391)
		(width 0.14478)
		(layer "In6.Cu")
		(net "M_E_CPU0_SB_DQ<20>")
	)
	(segment
		(start 297.744642 -306.87391)
		(end 297.502072 -306.87391)
		(width 0.14478)
		(layer "In6.Cu")
		(net "M_E_CPU0_SB_DQ<20>")
	)
	(segment
		(start 281.144472 -306.87391)
		(end 280.840434 -306.569872)
		(width 0.14478)
		(layer "In6.Cu")
		(net "M_E_CPU0_SB_DQ<20>")
	)
	(segment
		(start 325.196454 -287.95091)
		(end 324.850252 -287.95091)
		(width 0.0889)
		(layer "In6.Cu")
		(net "M_E_CPU0_SB_DQ<20>")
	)
	(segment
		(start 283.653738 -305.719734)
		(end 282.499562 -306.87391)
		(width 0.14478)
		(layer "In6.Cu")
		(net "M_E_CPU0_SB_DQ<20>")
	)
	(segment
		(start 296.085514 -306.569872)
		(end 294.713406 -306.569872)
		(width 0.14478)
		(layer "In6.Cu")
		(net "M_E_CPU0_SB_DQ<20>")
	)
	(segment
		(start 329.47102 -287.045908)
		(end 329.317096 -287.311338)
		(width 0.0889)
		(layer "In6.Cu")
		(net "M_E_CPU0_SB_DQ<20>")
	)
	(segment
		(start 326.651112 -287.41878)
		(end 325.734426 -287.412938)
		(width 0.0889)
		(layer "In6.Cu")
		(net "M_E_CPU0_SB_DQ<20>")
	)
	(segment
		(start 286.800798 -306.82311)
		(end 285.913576 -305.935888)
		(width 0.14478)
		(layer "In6.Cu")
		(net "M_E_CPU0_SB_DQ<20>")
	)
	(segment
		(start 300.592236 -305.719734)
		(end 298.898818 -305.719734)
		(width 0.14478)
		(layer "In6.Cu")
		(net "M_E_CPU0_SB_DQ<20>")
	)
	(segment
		(start 320.78041 -291.07257)
		(end 311.002426 -300.850554)
		(width 0.14478)
		(layer "In6.Cu")
		(net "M_E_CPU0_SB_DQ<20>")
	)
	(segment
		(start 277.956518 -306.89931)
		(end 277.192232 -306.135024)
		(width 0.14478)
		(layer "In6.Cu")
		(net "M_E_CPU0_SB_DQ<20>")
	)
	(segment
		(start 302.89119 -306.310792)
		(end 302.89119 -306.70373)
		(width 0.14478)
		(layer "In6.Cu")
		(net "M_E_CPU0_SB_DQ<20>")
	)
	(arc
		(start 328.709782 -287.373314)
		(mid 328.526274 -287.418808)
		(end 328.344022 -287.368488)
		(width 0.0889)
		(layer "In6.Cu")
		(net "M_E_CPU0_SB_DQ<20>")
	)
	(arc
		(start 327.778364 -287.368488)
		(mid 327.59142 -287.418743)
		(end 327.404476 -287.368488)
		(width 0.0889)
		(layer "In6.Cu")
		(net "M_E_CPU0_SB_DQ<20>")
	)
	(arc
		(start 328.344022 -287.368488)
		(mid 328.067209 -287.292379)
		(end 327.788778 -287.362392)
		(width 0.0889)
		(layer "In6.Cu")
		(net "M_E_CPU0_SB_DQ<20>")
	)
	(arc
		(start 329.221084 -287.336738)
		(mid 328.965876 -287.293281)
		(end 328.718164 -287.368488)
		(width 0.0889)
		(layer "In6.Cu")
		(net "M_E_CPU0_SB_DQ<20>")
	)
	(arc
		(start 327.394062 -287.362392)
		(mid 327.115376 -287.292203)
		(end 326.83831 -287.368488)
		(width 0.0889)
		(layer "In6.Cu")
		(net "M_E_CPU0_SB_DQ<20>")
	)
	(arc
		(start 326.83831 -287.368488)
		(mid 326.748034 -287.405993)
		(end 326.651112 -287.41878)
		(width 0.0889)
		(layer "In6.Cu")
		(net "M_E_CPU0_SB_DQ<20>")
	)
	(segment
		(start 331.34808 -274.630134)
		(end 330.880974 -274.896072)
		(width 0.10668)
		(layer "F.Cu")
		(net "M_E_CPU0_SB_DQ<1>")
	)
	(segment
		(start 330.128118 -275.218652)
		(end 330.119736 -275.223478)
		(width 0.0889)
		(layer "In6.Cu")
		(net "M_E_CPU0_SB_DQ<1>")
	)
	(segment
		(start 279.410414 -283.98851)
		(end 279.179782 -283.98851)
		(width 0.14478)
		(layer "In6.Cu")
		(net "M_E_CPU0_SB_DQ<1>")
	)
	(segment
		(start 302.92421 -283.61005)
		(end 302.62195 -283.91231)
		(width 0.14478)
		(layer "In6.Cu")
		(net "M_E_CPU0_SB_DQ<1>")
	)
	(segment
		(start 285.89351 -282.759912)
		(end 283.016706 -282.759912)
		(width 0.14478)
		(layer "In6.Cu")
		(net "M_E_CPU0_SB_DQ<1>")
	)
	(segment
		(start 278.297894 -283.98851)
		(end 277.995634 -283.98851)
		(width 0.14478)
		(layer "In6.Cu")
		(net "M_E_CPU0_SB_DQ<1>")
	)
	(segment
		(start 314.485528 -274.1295)
		(end 313.527948 -275.08708)
		(width 0.14478)
		(layer "In6.Cu")
		(net "M_E_CPU0_SB_DQ<1>")
	)
	(segment
		(start 295.060624 -283.91231)
		(end 294.665908 -283.91231)
		(width 0.14478)
		(layer "In6.Cu")
		(net "M_E_CPU0_SB_DQ<1>")
	)
	(segment
		(start 294.665908 -283.91231)
		(end 293.51351 -282.759912)
		(width 0.14478)
		(layer "In6.Cu")
		(net "M_E_CPU0_SB_DQ<1>")
	)
	(segment
		(start 325.323454 -274.03171)
		(end 324.271894 -274.03171)
		(width 0.0889)
		(layer "In6.Cu")
		(net "M_E_CPU0_SB_DQ<1>")
	)
	(segment
		(start 278.623522 -283.23159)
		(end 278.460708 -283.394404)
		(width 0.14478)
		(layer "In6.Cu")
		(net "M_E_CPU0_SB_DQ<1>")
	)
	(segment
		(start 330.880974 -274.896072)
		(end 330.72705 -275.161502)
		(width 0.0889)
		(layer "In6.Cu")
		(net "M_E_CPU0_SB_DQ<1>")
	)
	(segment
		(start 293.51351 -282.759912)
		(end 291.955982 -282.759912)
		(width 0.14478)
		(layer "In6.Cu")
		(net "M_E_CPU0_SB_DQ<1>")
	)
	(segment
		(start 301.00651 -282.759912)
		(end 299.390308 -282.759912)
		(width 0.14478)
		(layer "In6.Cu")
		(net "M_E_CPU0_SB_DQ<1>")
	)
	(segment
		(start 304.088292 -283.91231)
		(end 303.48047 -283.91231)
		(width 0.14478)
		(layer "In6.Cu")
		(net "M_E_CPU0_SB_DQ<1>")
	)
	(segment
		(start 307.589174 -282.759912)
		(end 307.274976 -283.07411)
		(width 0.14478)
		(layer "In6.Cu")
		(net "M_E_CPU0_SB_DQ<1>")
	)
	(segment
		(start 297.00728 -283.61005)
		(end 295.362884 -283.61005)
		(width 0.14478)
		(layer "In6.Cu")
		(net "M_E_CPU0_SB_DQ<1>")
	)
	(segment
		(start 307.274976 -283.07411)
		(end 307.032914 -283.07411)
		(width 0.14478)
		(layer "In6.Cu")
		(net "M_E_CPU0_SB_DQ<1>")
	)
	(segment
		(start 330.72705 -275.161502)
		(end 330.631038 -275.186902)
		(width 0.0889)
		(layer "In6.Cu")
		(net "M_E_CPU0_SB_DQ<1>")
	)
	(segment
		(start 279.573228 -283.394404)
		(end 279.573228 -283.825696)
		(width 0.14478)
		(layer "In6.Cu")
		(net "M_E_CPU0_SB_DQ<1>")
	)
	(segment
		(start 306.476654 -282.759912)
		(end 306.162456 -283.07411)
		(width 0.14478)
		(layer "In6.Cu")
		(net "M_E_CPU0_SB_DQ<1>")
	)
	(segment
		(start 327.873868 -275.218652)
		(end 327.80986 -275.181314)
		(width 0.0889)
		(layer "In6.Cu")
		(net "M_E_CPU0_SB_DQ<1>")
	)
	(segment
		(start 291.955982 -282.759912)
		(end 291.641784 -283.07411)
		(width 0.14478)
		(layer "In6.Cu")
		(net "M_E_CPU0_SB_DQ<1>")
	)
	(segment
		(start 289.913568 -283.61005)
		(end 287.802574 -283.61005)
		(width 0.14478)
		(layer "In6.Cu")
		(net "M_E_CPU0_SB_DQ<1>")
	)
	(segment
		(start 310.189626 -279.519634)
		(end 309.136288 -280.572972)
		(width 0.14478)
		(layer "In6.Cu")
		(net "M_E_CPU0_SB_DQ<1>")
	)
	(segment
		(start 305.606196 -282.759912)
		(end 305.24069 -282.759912)
		(width 0.14478)
		(layer "In6.Cu")
		(net "M_E_CPU0_SB_DQ<1>")
	)
	(segment
		(start 307.801518 -282.759912)
		(end 307.589174 -282.759912)
		(width 0.14478)
		(layer "In6.Cu")
		(net "M_E_CPU0_SB_DQ<1>")
	)
	(segment
		(start 290.763706 -282.759912)
		(end 289.913568 -283.61005)
		(width 0.14478)
		(layer "In6.Cu")
		(net "M_E_CPU0_SB_DQ<1>")
	)
	(segment
		(start 279.179782 -283.98851)
		(end 279.016968 -283.825696)
		(width 0.14478)
		(layer "In6.Cu")
		(net "M_E_CPU0_SB_DQ<1>")
	)
	(segment
		(start 307.032914 -283.07411)
		(end 306.718716 -282.759912)
		(width 0.14478)
		(layer "In6.Cu")
		(net "M_E_CPU0_SB_DQ<1>")
	)
	(segment
		(start 309.136288 -280.572972)
		(end 309.136288 -281.425142)
		(width 0.14478)
		(layer "In6.Cu")
		(net "M_E_CPU0_SB_DQ<1>")
	)
	(segment
		(start 306.162456 -283.07411)
		(end 305.920394 -283.07411)
		(width 0.14478)
		(layer "In6.Cu")
		(net "M_E_CPU0_SB_DQ<1>")
	)
	(segment
		(start 305.920394 -283.07411)
		(end 305.606196 -282.759912)
		(width 0.14478)
		(layer "In6.Cu")
		(net "M_E_CPU0_SB_DQ<1>")
	)
	(segment
		(start 279.016968 -283.825696)
		(end 279.016968 -283.394404)
		(width 0.14478)
		(layer "In6.Cu")
		(net "M_E_CPU0_SB_DQ<1>")
	)
	(segment
		(start 302.158908 -283.91231)
		(end 301.00651 -282.759912)
		(width 0.14478)
		(layer "In6.Cu")
		(net "M_E_CPU0_SB_DQ<1>")
	)
	(segment
		(start 282.166568 -283.61005)
		(end 280.345134 -283.61005)
		(width 0.14478)
		(layer "In6.Cu")
		(net "M_E_CPU0_SB_DQ<1>")
	)
	(segment
		(start 291.085524 -282.759912)
		(end 290.763706 -282.759912)
		(width 0.14478)
		(layer "In6.Cu")
		(net "M_E_CPU0_SB_DQ<1>")
	)
	(segment
		(start 297.857418 -282.759912)
		(end 297.00728 -283.61005)
		(width 0.14478)
		(layer "In6.Cu")
		(net "M_E_CPU0_SB_DQ<1>")
	)
	(segment
		(start 278.460708 -283.394404)
		(end 278.460708 -283.825696)
		(width 0.14478)
		(layer "In6.Cu")
		(net "M_E_CPU0_SB_DQ<1>")
	)
	(segment
		(start 305.24069 -282.759912)
		(end 304.088292 -283.91231)
		(width 0.14478)
		(layer "In6.Cu")
		(net "M_E_CPU0_SB_DQ<1>")
	)
	(segment
		(start 287.045908 -283.91231)
		(end 285.89351 -282.759912)
		(width 0.14478)
		(layer "In6.Cu")
		(net "M_E_CPU0_SB_DQ<1>")
	)
	(segment
		(start 313.003438 -276.35327)
		(end 310.189626 -279.167082)
		(width 0.14478)
		(layer "In6.Cu")
		(net "M_E_CPU0_SB_DQ<1>")
	)
	(segment
		(start 309.136288 -281.425142)
		(end 307.801518 -282.759912)
		(width 0.14478)
		(layer "In6.Cu")
		(net "M_E_CPU0_SB_DQ<1>")
	)
	(segment
		(start 298.834048 -283.07411)
		(end 298.51985 -282.759912)
		(width 0.14478)
		(layer "In6.Cu")
		(net "M_E_CPU0_SB_DQ<1>")
	)
	(segment
		(start 278.854154 -283.23159)
		(end 278.623522 -283.23159)
		(width 0.14478)
		(layer "In6.Cu")
		(net "M_E_CPU0_SB_DQ<1>")
	)
	(segment
		(start 306.718716 -282.759912)
		(end 306.476654 -282.759912)
		(width 0.14478)
		(layer "In6.Cu")
		(net "M_E_CPU0_SB_DQ<1>")
	)
	(segment
		(start 298.51985 -282.759912)
		(end 297.857418 -282.759912)
		(width 0.14478)
		(layer "In6.Cu")
		(net "M_E_CPU0_SB_DQ<1>")
	)
	(segment
		(start 278.460708 -283.825696)
		(end 278.297894 -283.98851)
		(width 0.14478)
		(layer "In6.Cu")
		(net "M_E_CPU0_SB_DQ<1>")
	)
	(segment
		(start 313.527948 -275.08708)
		(end 313.003438 -276.35327)
		(width 0.14478)
		(layer "In6.Cu")
		(net "M_E_CPU0_SB_DQ<1>")
	)
	(segment
		(start 291.399722 -283.07411)
		(end 291.085524 -282.759912)
		(width 0.14478)
		(layer "In6.Cu")
		(net "M_E_CPU0_SB_DQ<1>")
	)
	(segment
		(start 324.271894 -274.03171)
		(end 324.174104 -274.1295)
		(width 0.0889)
		(layer "In6.Cu")
		(net "M_E_CPU0_SB_DQ<1>")
	)
	(segment
		(start 326.377046 -275.085302)
		(end 325.323454 -274.03171)
		(width 0.0889)
		(layer "In6.Cu")
		(net "M_E_CPU0_SB_DQ<1>")
	)
	(segment
		(start 303.48047 -283.91231)
		(end 303.17821 -283.61005)
		(width 0.14478)
		(layer "In6.Cu")
		(net "M_E_CPU0_SB_DQ<1>")
	)
	(segment
		(start 279.736042 -283.23159)
		(end 279.573228 -283.394404)
		(width 0.14478)
		(layer "In6.Cu")
		(net "M_E_CPU0_SB_DQ<1>")
	)
	(segment
		(start 283.016706 -282.759912)
		(end 282.166568 -283.61005)
		(width 0.14478)
		(layer "In6.Cu")
		(net "M_E_CPU0_SB_DQ<1>")
	)
	(segment
		(start 310.189626 -279.167082)
		(end 310.189626 -279.519634)
		(width 0.14478)
		(layer "In6.Cu")
		(net "M_E_CPU0_SB_DQ<1>")
	)
	(segment
		(start 279.966674 -283.23159)
		(end 279.736042 -283.23159)
		(width 0.14478)
		(layer "In6.Cu")
		(net "M_E_CPU0_SB_DQ<1>")
	)
	(segment
		(start 299.390308 -282.759912)
		(end 299.07611 -283.07411)
		(width 0.14478)
		(layer "In6.Cu")
		(net "M_E_CPU0_SB_DQ<1>")
	)
	(segment
		(start 302.62195 -283.91231)
		(end 302.158908 -283.91231)
		(width 0.14478)
		(layer "In6.Cu")
		(net "M_E_CPU0_SB_DQ<1>")
	)
	(segment
		(start 291.641784 -283.07411)
		(end 291.399722 -283.07411)
		(width 0.14478)
		(layer "In6.Cu")
		(net "M_E_CPU0_SB_DQ<1>")
	)
	(segment
		(start 299.07611 -283.07411)
		(end 298.834048 -283.07411)
		(width 0.14478)
		(layer "In6.Cu")
		(net "M_E_CPU0_SB_DQ<1>")
	)
	(segment
		(start 295.362884 -283.61005)
		(end 295.060624 -283.91231)
		(width 0.14478)
		(layer "In6.Cu")
		(net "M_E_CPU0_SB_DQ<1>")
	)
	(segment
		(start 277.995634 -283.98851)
		(end 277.192232 -283.185108)
		(width 0.14478)
		(layer "In6.Cu")
		(net "M_E_CPU0_SB_DQ<1>")
	)
	(segment
		(start 324.174104 -274.1295)
		(end 314.485528 -274.1295)
		(width 0.14478)
		(layer "In6.Cu")
		(net "M_E_CPU0_SB_DQ<1>")
	)
	(segment
		(start 287.802574 -283.61005)
		(end 287.500314 -283.91231)
		(width 0.14478)
		(layer "In6.Cu")
		(net "M_E_CPU0_SB_DQ<1>")
	)
	(segment
		(start 280.345134 -283.61005)
		(end 279.966674 -283.23159)
		(width 0.14478)
		(layer "In6.Cu")
		(net "M_E_CPU0_SB_DQ<1>")
	)
	(segment
		(start 303.17821 -283.61005)
		(end 302.92421 -283.61005)
		(width 0.14478)
		(layer "In6.Cu")
		(net "M_E_CPU0_SB_DQ<1>")
	)
	(segment
		(start 327.558654 -275.085302)
		(end 326.377046 -275.085302)
		(width 0.0889)
		(layer "In6.Cu")
		(net "M_E_CPU0_SB_DQ<1>")
	)
	(segment
		(start 279.573228 -283.825696)
		(end 279.410414 -283.98851)
		(width 0.14478)
		(layer "In6.Cu")
		(net "M_E_CPU0_SB_DQ<1>")
	)
	(segment
		(start 287.500314 -283.91231)
		(end 287.045908 -283.91231)
		(width 0.14478)
		(layer "In6.Cu")
		(net "M_E_CPU0_SB_DQ<1>")
	)
	(segment
		(start 279.016968 -283.394404)
		(end 278.854154 -283.23159)
		(width 0.14478)
		(layer "In6.Cu")
		(net "M_E_CPU0_SB_DQ<1>")
	)
	(arc
		(start 327.80986 -275.181314)
		(mid 327.729549 -275.138523)
		(end 327.646284 -275.101812)
		(width 0.0889)
		(layer "In6.Cu")
		(net "M_E_CPU0_SB_DQ<1>")
	)
	(arc
		(start 330.119736 -275.223478)
		(mid 329.936228 -275.268972)
		(end 329.753976 -275.218652)
		(width 0.0889)
		(layer "In6.Cu")
		(net "M_E_CPU0_SB_DQ<1>")
	)
	(arc
		(start 329.188064 -275.218652)
		(mid 329.00112 -275.268907)
		(end 328.814176 -275.218652)
		(width 0.0889)
		(layer "In6.Cu")
		(net "M_E_CPU0_SB_DQ<1>")
	)
	(arc
		(start 328.814176 -275.218652)
		(mid 328.53122 -275.142475)
		(end 328.248264 -275.218652)
		(width 0.0889)
		(layer "In6.Cu")
		(net "M_E_CPU0_SB_DQ<1>")
	)
	(arc
		(start 328.248264 -275.218652)
		(mid 328.061066 -275.269034)
		(end 327.873868 -275.218652)
		(width 0.0889)
		(layer "In6.Cu")
		(net "M_E_CPU0_SB_DQ<1>")
	)
	(arc
		(start 329.753976 -275.218652)
		(mid 329.47102 -275.142475)
		(end 329.188064 -275.218652)
		(width 0.0889)
		(layer "In6.Cu")
		(net "M_E_CPU0_SB_DQ<1>")
	)
	(arc
		(start 330.631038 -275.186902)
		(mid 330.37583 -275.143425)
		(end 330.128118 -275.218652)
		(width 0.0889)
		(layer "In6.Cu")
		(net "M_E_CPU0_SB_DQ<1>")
	)
	(arc
		(start 327.646284 -275.101812)
		(mid 327.60325 -275.089419)
		(end 327.558654 -275.085302)
		(width 0.0889)
		(layer "In6.Cu")
		(net "M_E_CPU0_SB_DQ<1>")
	)
	(segment
		(start 330.877926 -285.160212)
		(end 330.411074 -285.42615)
		(width 0.10668)
		(layer "F.Cu")
		(net "M_E_CPU0_SB_DQ<19>")
	)
	(segment
		(start 320.76009 -288.482786)
		(end 319.490852 -288.482786)
		(width 0.14478)
		(layer "In6.Cu")
		(net "M_E_CPU0_SB_DQ<19>")
	)
	(segment
		(start 294.055038 -302.300386)
		(end 290.399978 -302.300386)
		(width 0.14478)
		(layer "In6.Cu")
		(net "M_E_CPU0_SB_DQ<19>")
	)
	(segment
		(start 289.550094 -303.15027)
		(end 286.599122 -303.15027)
		(width 0.14478)
		(layer "In6.Cu")
		(net "M_E_CPU0_SB_DQ<19>")
	)
	(segment
		(start 285.749238 -302.300386)
		(end 283.135578 -302.300386)
		(width 0.14478)
		(layer "In6.Cu")
		(net "M_E_CPU0_SB_DQ<19>")
	)
	(segment
		(start 308.261512 -301.431452)
		(end 307.783484 -301.90948)
		(width 0.14478)
		(layer "In6.Cu")
		(net "M_E_CPU0_SB_DQ<19>")
	)
	(segment
		(start 319.490852 -288.482786)
		(end 314.534042 -293.442136)
		(width 0.14478)
		(layer "In6.Cu")
		(net "M_E_CPU0_SB_DQ<19>")
	)
	(segment
		(start 307.783484 -301.90948)
		(end 306.891436 -301.90948)
		(width 0.14478)
		(layer "In6.Cu")
		(net "M_E_CPU0_SB_DQ<19>")
	)
	(segment
		(start 282.285694 -303.15027)
		(end 273.507454 -303.15027)
		(width 0.14478)
		(layer "In6.Cu")
		(net "M_E_CPU0_SB_DQ<19>")
	)
	(segment
		(start 325.87438 -285.17977)
		(end 325.46544 -285.58871)
		(width 0.0889)
		(layer "In6.Cu")
		(net "M_E_CPU0_SB_DQ<19>")
	)
	(segment
		(start 286.599122 -303.15027)
		(end 285.749238 -302.300386)
		(width 0.14478)
		(layer "In6.Cu")
		(net "M_E_CPU0_SB_DQ<19>")
	)
	(segment
		(start 296.335704 -303.15027)
		(end 294.904922 -303.15027)
		(width 0.14478)
		(layer "In6.Cu")
		(net "M_E_CPU0_SB_DQ<19>")
	)
	(segment
		(start 304.839116 -302.759618)
		(end 302.090328 -302.759618)
		(width 0.14478)
		(layer "In6.Cu")
		(net "M_E_CPU0_SB_DQ<19>")
	)
	(segment
		(start 324.754494 -285.70809)
		(end 324.348094 -285.70809)
		(width 0.0889)
		(layer "In6.Cu")
		(net "M_E_CPU0_SB_DQ<19>")
	)
	(segment
		(start 300.576996 -302.300386)
		(end 298.38777 -302.300386)
		(width 0.14478)
		(layer "In6.Cu")
		(net "M_E_CPU0_SB_DQ<19>")
	)
	(segment
		(start 323.411596 -285.83128)
		(end 320.76009 -288.482786)
		(width 0.14478)
		(layer "In6.Cu")
		(net "M_E_CPU0_SB_DQ<19>")
	)
	(segment
		(start 330.411074 -285.42615)
		(end 330.564998 -285.16072)
		(width 0.0889)
		(layer "In6.Cu")
		(net "M_E_CPU0_SB_DQ<19>")
	)
	(segment
		(start 324.224904 -285.83128)
		(end 324.006718 -285.83128)
		(width 0.0889)
		(layer "In6.Cu")
		(net "M_E_CPU0_SB_DQ<19>")
	)
	(segment
		(start 273.507454 -303.15027)
		(end 273.092164 -302.73498)
		(width 0.14478)
		(layer "In6.Cu")
		(net "M_E_CPU0_SB_DQ<19>")
	)
	(segment
		(start 314.534042 -293.442136)
		(end 314.18911 -294.277288)
		(width 0.14478)
		(layer "In6.Cu")
		(net "M_E_CPU0_SB_DQ<19>")
	)
	(segment
		(start 302.090328 -302.759618)
		(end 300.576996 -302.300386)
		(width 0.14478)
		(layer "In6.Cu")
		(net "M_E_CPU0_SB_DQ<19>")
	)
	(segment
		(start 283.135578 -302.300386)
		(end 282.285694 -303.15027)
		(width 0.14478)
		(layer "In6.Cu")
		(net "M_E_CPU0_SB_DQ<19>")
	)
	(segment
		(start 329.292458 -285.098744)
		(end 329.284076 -285.10357)
		(width 0.0889)
		(layer "In6.Cu")
		(net "M_E_CPU0_SB_DQ<19>")
	)
	(segment
		(start 298.38777 -302.300386)
		(end 296.335704 -303.15027)
		(width 0.14478)
		(layer "In6.Cu")
		(net "M_E_CPU0_SB_DQ<19>")
	)
	(segment
		(start 290.399978 -302.300386)
		(end 289.550094 -303.15027)
		(width 0.14478)
		(layer "In6.Cu")
		(net "M_E_CPU0_SB_DQ<19>")
	)
	(segment
		(start 326.18172 -285.17977)
		(end 325.87438 -285.17977)
		(width 0.0889)
		(layer "In6.Cu")
		(net "M_E_CPU0_SB_DQ<19>")
	)
	(segment
		(start 314.18911 -294.277288)
		(end 309.128922 -299.337476)
		(width 0.14478)
		(layer "In6.Cu")
		(net "M_E_CPU0_SB_DQ<19>")
	)
	(segment
		(start 330.564998 -285.16072)
		(end 330.542646 -285.077408)
		(width 0.0889)
		(layer "In6.Cu")
		(net "M_E_CPU0_SB_DQ<19>")
	)
	(segment
		(start 326.48271 -285.09341)
		(end 326.464422 -285.103824)
		(width 0.0889)
		(layer "In6.Cu")
		(net "M_E_CPU0_SB_DQ<19>")
	)
	(segment
		(start 294.904922 -303.15027)
		(end 294.055038 -302.300386)
		(width 0.14478)
		(layer "In6.Cu")
		(net "M_E_CPU0_SB_DQ<19>")
	)
	(segment
		(start 328.718164 -285.10357)
		(end 328.709782 -285.098744)
		(width 0.0889)
		(layer "In6.Cu")
		(net "M_E_CPU0_SB_DQ<19>")
	)
	(segment
		(start 327.788778 -285.109666)
		(end 327.778364 -285.10357)
		(width 0.0889)
		(layer "In6.Cu")
		(net "M_E_CPU0_SB_DQ<19>")
	)
	(segment
		(start 325.46544 -285.58871)
		(end 324.873874 -285.58871)
		(width 0.0889)
		(layer "In6.Cu")
		(net "M_E_CPU0_SB_DQ<19>")
	)
	(segment
		(start 324.348094 -285.70809)
		(end 324.224904 -285.83128)
		(width 0.0889)
		(layer "In6.Cu")
		(net "M_E_CPU0_SB_DQ<19>")
	)
	(segment
		(start 327.778364 -285.10357)
		(end 327.769982 -285.098744)
		(width 0.0889)
		(layer "In6.Cu")
		(net "M_E_CPU0_SB_DQ<19>")
	)
	(segment
		(start 309.128922 -299.337476)
		(end 308.261512 -301.431452)
		(width 0.14478)
		(layer "In6.Cu")
		(net "M_E_CPU0_SB_DQ<19>")
	)
	(segment
		(start 327.40473 -285.10357)
		(end 327.394316 -285.109666)
		(width 0.0889)
		(layer "In6.Cu")
		(net "M_E_CPU0_SB_DQ<19>")
	)
	(segment
		(start 306.891436 -301.90948)
		(end 304.839116 -302.759618)
		(width 0.14478)
		(layer "In6.Cu")
		(net "M_E_CPU0_SB_DQ<19>")
	)
	(segment
		(start 324.006718 -285.83128)
		(end 323.411596 -285.83128)
		(width 0.14478)
		(layer "In6.Cu")
		(net "M_E_CPU0_SB_DQ<19>")
	)
	(segment
		(start 324.873874 -285.58871)
		(end 324.754494 -285.70809)
		(width 0.0889)
		(layer "In6.Cu")
		(net "M_E_CPU0_SB_DQ<19>")
	)
	(arc
		(start 327.769982 -285.098744)
		(mid 327.586728 -285.053371)
		(end 327.40473 -285.10357)
		(width 0.0889)
		(layer "In6.Cu")
		(net "M_E_CPU0_SB_DQ<19>")
	)
	(arc
		(start 328.344022 -285.10357)
		(mid 328.067209 -285.179713)
		(end 327.788778 -285.109666)
		(width 0.0889)
		(layer "In6.Cu")
		(net "M_E_CPU0_SB_DQ<19>")
	)
	(arc
		(start 329.284076 -285.10357)
		(mid 329.00112 -285.179747)
		(end 328.718164 -285.10357)
		(width 0.0889)
		(layer "In6.Cu")
		(net "M_E_CPU0_SB_DQ<19>")
	)
	(arc
		(start 327.394316 -285.109666)
		(mid 327.11563 -285.179886)
		(end 326.838564 -285.10357)
		(width 0.0889)
		(layer "In6.Cu")
		(net "M_E_CPU0_SB_DQ<19>")
	)
	(arc
		(start 329.658218 -285.10357)
		(mid 329.475967 -285.05322)
		(end 329.292458 -285.098744)
		(width 0.0889)
		(layer "In6.Cu")
		(net "M_E_CPU0_SB_DQ<19>")
	)
	(arc
		(start 326.464422 -285.103824)
		(mid 326.328083 -285.160453)
		(end 326.18172 -285.17977)
		(width 0.0889)
		(layer "In6.Cu")
		(net "M_E_CPU0_SB_DQ<19>")
	)
	(arc
		(start 328.709782 -285.098744)
		(mid 328.526274 -285.05325)
		(end 328.344022 -285.10357)
		(width 0.0889)
		(layer "In6.Cu")
		(net "M_E_CPU0_SB_DQ<19>")
	)
	(arc
		(start 330.542646 -285.077408)
		(mid 330.380457 -285.054673)
		(end 330.22413 -285.10357)
		(width 0.0889)
		(layer "In6.Cu")
		(net "M_E_CPU0_SB_DQ<19>")
	)
	(arc
		(start 330.22413 -285.10357)
		(mid 329.941174 -285.179747)
		(end 329.658218 -285.10357)
		(width 0.0889)
		(layer "In6.Cu")
		(net "M_E_CPU0_SB_DQ<19>")
	)
	(arc
		(start 326.838564 -285.10357)
		(mid 326.661936 -285.053337)
		(end 326.48271 -285.09341)
		(width 0.0889)
		(layer "In6.Cu")
		(net "M_E_CPU0_SB_DQ<19>")
	)
	(segment
		(start 329.467972 -284.350206)
		(end 329.00112 -284.616144)
		(width 0.10668)
		(layer "F.Cu")
		(net "M_E_CPU0_SB_DQ<18>")
	)
	(segment
		(start 290.465002 -300.610016)
		(end 289.614864 -301.460154)
		(width 0.14478)
		(layer "In6.Cu")
		(net "M_E_CPU0_SB_DQ<18>")
	)
	(segment
		(start 294.941752 -301.460154)
		(end 294.091614 -300.610016)
		(width 0.14478)
		(layer "In6.Cu")
		(net "M_E_CPU0_SB_DQ<18>")
	)
	(segment
		(start 275.016468 -301.29734)
		(end 275.016468 -301.027592)
		(width 0.14478)
		(layer "In6.Cu")
		(net "M_E_CPU0_SB_DQ<18>")
	)
	(segment
		(start 306.881022 -300.410372)
		(end 305.228498 -300.410372)
		(width 0.14478)
		(layer "In6.Cu")
		(net "M_E_CPU0_SB_DQ<18>")
	)
	(segment
		(start 323.00926 -284.92196)
		(end 320.347594 -287.583626)
		(width 0.14478)
		(layer "In6.Cu")
		(net "M_E_CPU0_SB_DQ<18>")
	)
	(segment
		(start 274.871688 -300.882812)
		(end 274.604988 -300.882812)
		(width 0.14478)
		(layer "In6.Cu")
		(net "M_E_CPU0_SB_DQ<18>")
	)
	(segment
		(start 274.460208 -301.29734)
		(end 274.297394 -301.460154)
		(width 0.14478)
		(layer "In6.Cu")
		(net "M_E_CPU0_SB_DQ<18>")
	)
	(segment
		(start 305.228498 -300.410372)
		(end 304.941478 -300.697392)
		(width 0.14478)
		(layer "In6.Cu")
		(net "M_E_CPU0_SB_DQ<18>")
	)
	(segment
		(start 313.425332 -293.768526)
		(end 308.038754 -299.15485)
		(width 0.14478)
		(layer "In6.Cu")
		(net "M_E_CPU0_SB_DQ<18>")
	)
	(segment
		(start 297.375072 -301.460154)
		(end 294.941752 -301.460154)
		(width 0.14478)
		(layer "In6.Cu")
		(net "M_E_CPU0_SB_DQ<18>")
	)
	(segment
		(start 325.196454 -284.92196)
		(end 323.934074 -284.92196)
		(width 0.0889)
		(layer "In6.Cu")
		(net "M_E_CPU0_SB_DQ<18>")
	)
	(segment
		(start 327.317862 -284.29966)
		(end 327.307448 -284.293564)
		(width 0.0889)
		(layer "In6.Cu")
		(net "M_E_CPU0_SB_DQ<18>")
	)
	(segment
		(start 274.297394 -301.460154)
		(end 273.51736 -301.460154)
		(width 0.14478)
		(layer "In6.Cu")
		(net "M_E_CPU0_SB_DQ<18>")
	)
	(segment
		(start 275.179282 -301.460154)
		(end 275.016468 -301.29734)
		(width 0.14478)
		(layer "In6.Cu")
		(net "M_E_CPU0_SB_DQ<18>")
	)
	(segment
		(start 329.155044 -284.350714)
		(end 329.132692 -284.267402)
		(width 0.0889)
		(layer "In6.Cu")
		(net "M_E_CPU0_SB_DQ<18>")
	)
	(segment
		(start 298.22521 -300.610016)
		(end 297.375072 -301.460154)
		(width 0.14478)
		(layer "In6.Cu")
		(net "M_E_CPU0_SB_DQ<18>")
	)
	(segment
		(start 302.206152 -301.460154)
		(end 301.356014 -300.610016)
		(width 0.14478)
		(layer "In6.Cu")
		(net "M_E_CPU0_SB_DQ<18>")
	)
	(segment
		(start 319.11798 -287.583626)
		(end 313.772042 -292.929818)
		(width 0.14478)
		(layer "In6.Cu")
		(net "M_E_CPU0_SB_DQ<18>")
	)
	(segment
		(start 285.331154 -300.610016)
		(end 283.353002 -300.610016)
		(width 0.14478)
		(layer "In6.Cu")
		(net "M_E_CPU0_SB_DQ<18>")
	)
	(segment
		(start 326.651112 -284.369764)
		(end 325.74865 -284.369764)
		(width 0.0889)
		(layer "In6.Cu")
		(net "M_E_CPU0_SB_DQ<18>")
	)
	(segment
		(start 307.969666 -299.321728)
		(end 306.881022 -300.410372)
		(width 0.14478)
		(layer "In6.Cu")
		(net "M_E_CPU0_SB_DQ<18>")
	)
	(segment
		(start 301.356014 -300.610016)
		(end 298.22521 -300.610016)
		(width 0.14478)
		(layer "In6.Cu")
		(net "M_E_CPU0_SB_DQ<18>")
	)
	(segment
		(start 283.353002 -300.610016)
		(end 282.502864 -301.460154)
		(width 0.14478)
		(layer "In6.Cu")
		(net "M_E_CPU0_SB_DQ<18>")
	)
	(segment
		(start 274.604988 -300.882812)
		(end 274.460208 -301.027592)
		(width 0.14478)
		(layer "In6.Cu")
		(net "M_E_CPU0_SB_DQ<18>")
	)
	(segment
		(start 320.347594 -287.583626)
		(end 319.11798 -287.583626)
		(width 0.14478)
		(layer "In6.Cu")
		(net "M_E_CPU0_SB_DQ<18>")
	)
	(segment
		(start 275.016468 -301.027592)
		(end 274.871688 -300.882812)
		(width 0.14478)
		(layer "In6.Cu")
		(net "M_E_CPU0_SB_DQ<18>")
	)
	(segment
		(start 304.651918 -301.460154)
		(end 302.206152 -301.460154)
		(width 0.14478)
		(layer "In6.Cu")
		(net "M_E_CPU0_SB_DQ<18>")
	)
	(segment
		(start 328.248264 -284.293564)
		(end 328.239882 -284.288738)
		(width 0.0889)
		(layer "In6.Cu")
		(net "M_E_CPU0_SB_DQ<18>")
	)
	(segment
		(start 323.934074 -284.92196)
		(end 323.00926 -284.92196)
		(width 0.14478)
		(layer "In6.Cu")
		(net "M_E_CPU0_SB_DQ<18>")
	)
	(segment
		(start 313.772042 -292.929818)
		(end 313.425332 -293.768526)
		(width 0.14478)
		(layer "In6.Cu")
		(net "M_E_CPU0_SB_DQ<18>")
	)
	(segment
		(start 329.00112 -284.616144)
		(end 329.155044 -284.350714)
		(width 0.0889)
		(layer "In6.Cu")
		(net "M_E_CPU0_SB_DQ<18>")
	)
	(segment
		(start 282.502864 -301.460154)
		(end 275.179282 -301.460154)
		(width 0.14478)
		(layer "In6.Cu")
		(net "M_E_CPU0_SB_DQ<18>")
	)
	(segment
		(start 304.941478 -301.170594)
		(end 304.651918 -301.460154)
		(width 0.14478)
		(layer "In6.Cu")
		(net "M_E_CPU0_SB_DQ<18>")
	)
	(segment
		(start 274.460208 -301.027592)
		(end 274.460208 -301.29734)
		(width 0.14478)
		(layer "In6.Cu")
		(net "M_E_CPU0_SB_DQ<18>")
	)
	(segment
		(start 286.181292 -301.460154)
		(end 285.331154 -300.610016)
		(width 0.14478)
		(layer "In6.Cu")
		(net "M_E_CPU0_SB_DQ<18>")
	)
	(segment
		(start 325.74865 -284.369764)
		(end 325.196454 -284.92196)
		(width 0.0889)
		(layer "In6.Cu")
		(net "M_E_CPU0_SB_DQ<18>")
	)
	(segment
		(start 289.614864 -301.460154)
		(end 286.181292 -301.460154)
		(width 0.14478)
		(layer "In6.Cu")
		(net "M_E_CPU0_SB_DQ<18>")
	)
	(segment
		(start 326.949816 -284.28442)
		(end 326.93356 -284.293818)
		(width 0.0889)
		(layer "In6.Cu")
		(net "M_E_CPU0_SB_DQ<18>")
	)
	(segment
		(start 273.51736 -301.460154)
		(end 273.092164 -301.034958)
		(width 0.14478)
		(layer "In6.Cu")
		(net "M_E_CPU0_SB_DQ<18>")
	)
	(segment
		(start 308.038754 -299.15485)
		(end 307.969666 -299.321728)
		(width 0.14478)
		(layer "In6.Cu")
		(net "M_E_CPU0_SB_DQ<18>")
	)
	(segment
		(start 294.091614 -300.610016)
		(end 290.465002 -300.610016)
		(width 0.14478)
		(layer "In6.Cu")
		(net "M_E_CPU0_SB_DQ<18>")
	)
	(segment
		(start 304.941478 -300.697392)
		(end 304.941478 -301.170594)
		(width 0.14478)
		(layer "In6.Cu")
		(net "M_E_CPU0_SB_DQ<18>")
	)
	(arc
		(start 328.239882 -284.288738)
		(mid 328.05612 -284.243122)
		(end 327.873614 -284.293564)
		(width 0.0889)
		(layer "In6.Cu")
		(net "M_E_CPU0_SB_DQ<18>")
	)
	(arc
		(start 327.873614 -284.293564)
		(mid 327.596547 -284.369835)
		(end 327.317862 -284.29966)
		(width 0.0889)
		(layer "In6.Cu")
		(net "M_E_CPU0_SB_DQ<18>")
	)
	(arc
		(start 326.93356 -284.293818)
		(mid 326.797345 -284.350403)
		(end 326.651112 -284.369764)
		(width 0.0889)
		(layer "In6.Cu")
		(net "M_E_CPU0_SB_DQ<18>")
	)
	(arc
		(start 327.307448 -284.293564)
		(mid 327.129798 -284.243304)
		(end 326.949816 -284.28442)
		(width 0.0889)
		(layer "In6.Cu")
		(net "M_E_CPU0_SB_DQ<18>")
	)
	(arc
		(start 328.814176 -284.293564)
		(mid 328.53122 -284.369741)
		(end 328.248264 -284.293564)
		(width 0.0889)
		(layer "In6.Cu")
		(net "M_E_CPU0_SB_DQ<18>")
	)
	(arc
		(start 329.132692 -284.267402)
		(mid 328.970503 -284.244667)
		(end 328.814176 -284.293564)
		(width 0.0889)
		(layer "In6.Cu")
		(net "M_E_CPU0_SB_DQ<18>")
	)
	(segment
		(start 331.34808 -284.350206)
		(end 330.880974 -284.616144)
		(width 0.10668)
		(layer "F.Cu")
		(net "M_E_CPU0_SB_DQ<17>")
	)
	(segment
		(start 293.04488 -301.76851)
		(end 292.796976 -301.76851)
		(width 0.14478)
		(layer "In6.Cu")
		(net "M_E_CPU0_SB_DQ<17>")
	)
	(segment
		(start 323.203824 -285.37662)
		(end 320.547238 -288.033206)
		(width 0.14478)
		(layer "In6.Cu")
		(net "M_E_CPU0_SB_DQ<17>")
	)
	(segment
		(start 299.226478 -301.4599)
		(end 298.917868 -301.76851)
		(width 0.14478)
		(layer "In6.Cu")
		(net "M_E_CPU0_SB_DQ<17>")
	)
	(segment
		(start 298.917868 -301.76851)
		(end 298.670218 -301.76851)
		(width 0.14478)
		(layer "In6.Cu")
		(net "M_E_CPU0_SB_DQ<17>")
	)
	(segment
		(start 297.168316 -302.310038)
		(end 295.004236 -302.310038)
		(width 0.14478)
		(layer "In6.Cu")
		(net "M_E_CPU0_SB_DQ<17>")
	)
	(segment
		(start 330.880974 -284.616144)
		(end 330.72705 -284.881574)
		(width 0.0889)
		(layer "In6.Cu")
		(net "M_E_CPU0_SB_DQ<17>")
	)
	(segment
		(start 327.874376 -284.938724)
		(end 327.863962 -284.932628)
		(width 0.0889)
		(layer "In6.Cu")
		(net "M_E_CPU0_SB_DQ<17>")
	)
	(segment
		(start 278.38527 -302.521874)
		(end 278.222456 -302.684688)
		(width 0.14478)
		(layer "In6.Cu")
		(net "M_E_CPU0_SB_DQ<17>")
	)
	(segment
		(start 279.891236 -301.938944)
		(end 279.660604 -301.938944)
		(width 0.14478)
		(layer "In6.Cu")
		(net "M_E_CPU0_SB_DQ<17>")
	)
	(segment
		(start 278.94153 -302.521874)
		(end 278.94153 -302.101758)
		(width 0.14478)
		(layer "In6.Cu")
		(net "M_E_CPU0_SB_DQ<17>")
	)
	(segment
		(start 298.670218 -301.76851)
		(end 298.361608 -301.4599)
		(width 0.14478)
		(layer "In6.Cu")
		(net "M_E_CPU0_SB_DQ<17>")
	)
	(segment
		(start 278.38527 -302.101758)
		(end 278.38527 -302.521874)
		(width 0.14478)
		(layer "In6.Cu")
		(net "M_E_CPU0_SB_DQ<17>")
	)
	(segment
		(start 278.94153 -302.101758)
		(end 278.778716 -301.938944)
		(width 0.14478)
		(layer "In6.Cu")
		(net "M_E_CPU0_SB_DQ<17>")
	)
	(segment
		(start 291.305996 -301.76851)
		(end 291.058092 -301.76851)
		(width 0.14478)
		(layer "In6.Cu")
		(net "M_E_CPU0_SB_DQ<17>")
	)
	(segment
		(start 280.26233 -302.310038)
		(end 279.891236 -301.938944)
		(width 0.14478)
		(layer "In6.Cu")
		(net "M_E_CPU0_SB_DQ<17>")
	)
	(segment
		(start 298.361608 -301.4599)
		(end 298.018454 -301.4599)
		(width 0.14478)
		(layer "In6.Cu")
		(net "M_E_CPU0_SB_DQ<17>")
	)
	(segment
		(start 279.660604 -301.938944)
		(end 279.49779 -302.101758)
		(width 0.14478)
		(layer "In6.Cu")
		(net "M_E_CPU0_SB_DQ<17>")
	)
	(segment
		(start 279.49779 -302.521874)
		(end 279.334976 -302.684688)
		(width 0.14478)
		(layer "In6.Cu")
		(net "M_E_CPU0_SB_DQ<17>")
	)
	(segment
		(start 292.796976 -301.76851)
		(end 292.48862 -301.460154)
		(width 0.14478)
		(layer "In6.Cu")
		(net "M_E_CPU0_SB_DQ<17>")
	)
	(segment
		(start 325.764652 -285.00197)
		(end 325.390002 -285.37662)
		(width 0.0889)
		(layer "In6.Cu")
		(net "M_E_CPU0_SB_DQ<17>")
	)
	(segment
		(start 327.308718 -284.938724)
		(end 327.297034 -284.945582)
		(width 0.0889)
		(layer "In6.Cu")
		(net "M_E_CPU0_SB_DQ<17>")
	)
	(segment
		(start 283.163518 -301.4599)
		(end 282.31338 -302.310038)
		(width 0.14478)
		(layer "In6.Cu")
		(net "M_E_CPU0_SB_DQ<17>")
	)
	(segment
		(start 298.018454 -301.4599)
		(end 297.168316 -302.310038)
		(width 0.14478)
		(layer "In6.Cu")
		(net "M_E_CPU0_SB_DQ<17>")
	)
	(segment
		(start 294.154352 -301.460154)
		(end 293.353236 -301.460154)
		(width 0.14478)
		(layer "In6.Cu")
		(net "M_E_CPU0_SB_DQ<17>")
	)
	(segment
		(start 313.80684 -294.023288)
		(end 308.747668 -299.08246)
		(width 0.14478)
		(layer "In6.Cu")
		(net "M_E_CPU0_SB_DQ<17>")
	)
	(segment
		(start 284.296358 -301.4599)
		(end 283.987748 -301.76851)
		(width 0.14478)
		(layer "In6.Cu")
		(net "M_E_CPU0_SB_DQ<17>")
	)
	(segment
		(start 279.104344 -302.684688)
		(end 278.94153 -302.521874)
		(width 0.14478)
		(layer "In6.Cu")
		(net "M_E_CPU0_SB_DQ<17>")
	)
	(segment
		(start 330.72705 -284.881574)
		(end 330.631038 -284.906974)
		(width 0.0889)
		(layer "In6.Cu")
		(net "M_E_CPU0_SB_DQ<17>")
	)
	(segment
		(start 291.058092 -301.76851)
		(end 290.749736 -301.460154)
		(width 0.14478)
		(layer "In6.Cu")
		(net "M_E_CPU0_SB_DQ<17>")
	)
	(segment
		(start 330.128118 -284.938724)
		(end 330.119736 -284.94355)
		(width 0.0889)
		(layer "In6.Cu")
		(net "M_E_CPU0_SB_DQ<17>")
	)
	(segment
		(start 301.56277 -301.4599)
		(end 299.226478 -301.4599)
		(width 0.14478)
		(layer "In6.Cu")
		(net "M_E_CPU0_SB_DQ<17>")
	)
	(segment
		(start 327.88606 -284.945582)
		(end 327.874376 -284.938724)
		(width 0.0889)
		(layer "In6.Cu")
		(net "M_E_CPU0_SB_DQ<17>")
	)
	(segment
		(start 302.412908 -302.310038)
		(end 301.56277 -301.4599)
		(width 0.14478)
		(layer "In6.Cu")
		(net "M_E_CPU0_SB_DQ<17>")
	)
	(segment
		(start 325.390002 -285.37662)
		(end 323.942964 -285.37662)
		(width 0.0889)
		(layer "In6.Cu")
		(net "M_E_CPU0_SB_DQ<17>")
	)
	(segment
		(start 290.749736 -301.460154)
		(end 290.427664 -301.460154)
		(width 0.14478)
		(layer "In6.Cu")
		(net "M_E_CPU0_SB_DQ<17>")
	)
	(segment
		(start 286.691832 -302.60671)
		(end 285.545022 -301.4599)
		(width 0.14478)
		(layer "In6.Cu")
		(net "M_E_CPU0_SB_DQ<17>")
	)
	(segment
		(start 289.255708 -302.63211)
		(end 289.02152 -302.63211)
		(width 0.14478)
		(layer "In6.Cu")
		(net "M_E_CPU0_SB_DQ<17>")
	)
	(segment
		(start 290.427664 -301.460154)
		(end 289.255708 -302.63211)
		(width 0.14478)
		(layer "In6.Cu")
		(net "M_E_CPU0_SB_DQ<17>")
	)
	(segment
		(start 279.334976 -302.684688)
		(end 279.104344 -302.684688)
		(width 0.14478)
		(layer "In6.Cu")
		(net "M_E_CPU0_SB_DQ<17>")
	)
	(segment
		(start 287.203896 -302.60671)
		(end 286.691832 -302.60671)
		(width 0.14478)
		(layer "In6.Cu")
		(net "M_E_CPU0_SB_DQ<17>")
	)
	(segment
		(start 279.49779 -302.101758)
		(end 279.49779 -302.521874)
		(width 0.14478)
		(layer "In6.Cu")
		(net "M_E_CPU0_SB_DQ<17>")
	)
	(segment
		(start 307.584856 -301.4599)
		(end 306.38242 -301.4599)
		(width 0.14478)
		(layer "In6.Cu")
		(net "M_E_CPU0_SB_DQ<17>")
	)
	(segment
		(start 306.38242 -301.4599)
		(end 304.330608 -302.310038)
		(width 0.14478)
		(layer "In6.Cu")
		(net "M_E_CPU0_SB_DQ<17>")
	)
	(segment
		(start 307.889148 -301.155608)
		(end 307.584856 -301.4599)
		(width 0.14478)
		(layer "In6.Cu")
		(net "M_E_CPU0_SB_DQ<17>")
	)
	(segment
		(start 287.500568 -302.310038)
		(end 287.203896 -302.60671)
		(width 0.14478)
		(layer "In6.Cu")
		(net "M_E_CPU0_SB_DQ<17>")
	)
	(segment
		(start 285.545022 -301.4599)
		(end 284.296358 -301.4599)
		(width 0.14478)
		(layer "In6.Cu")
		(net "M_E_CPU0_SB_DQ<17>")
	)
	(segment
		(start 319.304416 -288.033206)
		(end 314.152534 -293.187374)
		(width 0.14478)
		(layer "In6.Cu")
		(net "M_E_CPU0_SB_DQ<17>")
	)
	(segment
		(start 283.740098 -301.76851)
		(end 283.431488 -301.4599)
		(width 0.14478)
		(layer "In6.Cu")
		(net "M_E_CPU0_SB_DQ<17>")
	)
	(segment
		(start 291.614352 -301.460154)
		(end 291.305996 -301.76851)
		(width 0.14478)
		(layer "In6.Cu")
		(net "M_E_CPU0_SB_DQ<17>")
	)
	(segment
		(start 289.02152 -302.63211)
		(end 288.699448 -302.310038)
		(width 0.14478)
		(layer "In6.Cu")
		(net "M_E_CPU0_SB_DQ<17>")
	)
	(segment
		(start 308.747668 -299.08246)
		(end 307.889148 -301.155608)
		(width 0.14478)
		(layer "In6.Cu")
		(net "M_E_CPU0_SB_DQ<17>")
	)
	(segment
		(start 282.31338 -302.310038)
		(end 280.26233 -302.310038)
		(width 0.14478)
		(layer "In6.Cu")
		(net "M_E_CPU0_SB_DQ<17>")
	)
	(segment
		(start 320.547238 -288.033206)
		(end 319.304416 -288.033206)
		(width 0.14478)
		(layer "In6.Cu")
		(net "M_E_CPU0_SB_DQ<17>")
	)
	(segment
		(start 293.353236 -301.460154)
		(end 293.04488 -301.76851)
		(width 0.14478)
		(layer "In6.Cu")
		(net "M_E_CPU0_SB_DQ<17>")
	)
	(segment
		(start 288.699448 -302.310038)
		(end 287.500568 -302.310038)
		(width 0.14478)
		(layer "In6.Cu")
		(net "M_E_CPU0_SB_DQ<17>")
	)
	(segment
		(start 283.431488 -301.4599)
		(end 283.163518 -301.4599)
		(width 0.14478)
		(layer "In6.Cu")
		(net "M_E_CPU0_SB_DQ<17>")
	)
	(segment
		(start 295.004236 -302.310038)
		(end 294.154352 -301.460154)
		(width 0.14478)
		(layer "In6.Cu")
		(net "M_E_CPU0_SB_DQ<17>")
	)
	(segment
		(start 278.222456 -302.684688)
		(end 277.991824 -302.684688)
		(width 0.14478)
		(layer "In6.Cu")
		(net "M_E_CPU0_SB_DQ<17>")
	)
	(segment
		(start 283.987748 -301.76851)
		(end 283.740098 -301.76851)
		(width 0.14478)
		(layer "In6.Cu")
		(net "M_E_CPU0_SB_DQ<17>")
	)
	(segment
		(start 292.48862 -301.460154)
		(end 291.614352 -301.460154)
		(width 0.14478)
		(layer "In6.Cu")
		(net "M_E_CPU0_SB_DQ<17>")
	)
	(segment
		(start 326.173338 -284.968696)
		(end 325.844916 -284.968696)
		(width 0.0889)
		(layer "In6.Cu")
		(net "M_E_CPU0_SB_DQ<17>")
	)
	(segment
		(start 314.152534 -293.187374)
		(end 313.80684 -294.023288)
		(width 0.14478)
		(layer "In6.Cu")
		(net "M_E_CPU0_SB_DQ<17>")
	)
	(segment
		(start 278.548084 -301.938944)
		(end 278.38527 -302.101758)
		(width 0.14478)
		(layer "In6.Cu")
		(net "M_E_CPU0_SB_DQ<17>")
	)
	(segment
		(start 323.942964 -285.37662)
		(end 323.203824 -285.37662)
		(width 0.14478)
		(layer "In6.Cu")
		(net "M_E_CPU0_SB_DQ<17>")
	)
	(segment
		(start 277.991824 -302.684688)
		(end 277.192232 -301.885096)
		(width 0.14478)
		(layer "In6.Cu")
		(net "M_E_CPU0_SB_DQ<17>")
	)
	(segment
		(start 278.778716 -301.938944)
		(end 278.548084 -301.938944)
		(width 0.14478)
		(layer "In6.Cu")
		(net "M_E_CPU0_SB_DQ<17>")
	)
	(segment
		(start 304.330608 -302.310038)
		(end 302.412908 -302.310038)
		(width 0.14478)
		(layer "In6.Cu")
		(net "M_E_CPU0_SB_DQ<17>")
	)
	(arc
		(start 329.753976 -284.938724)
		(mid 329.47102 -284.862547)
		(end 329.188064 -284.938724)
		(width 0.0889)
		(layer "In6.Cu")
		(net "M_E_CPU0_SB_DQ<17>")
	)
	(arc
		(start 327.297034 -284.945582)
		(mid 327.114779 -284.989235)
		(end 326.934322 -284.938724)
		(width 0.0889)
		(layer "In6.Cu")
		(net "M_E_CPU0_SB_DQ<17>")
	)
	(arc
		(start 329.188064 -284.938724)
		(mid 329.00112 -284.988979)
		(end 328.814176 -284.938724)
		(width 0.0889)
		(layer "In6.Cu")
		(net "M_E_CPU0_SB_DQ<17>")
	)
	(arc
		(start 325.844916 -284.968696)
		(mid 325.801481 -284.977354)
		(end 325.764652 -285.00197)
		(width 0.0889)
		(layer "In6.Cu")
		(net "M_E_CPU0_SB_DQ<17>")
	)
	(arc
		(start 327.863962 -284.932628)
		(mid 327.58553 -284.86253)
		(end 327.308718 -284.938724)
		(width 0.0889)
		(layer "In6.Cu")
		(net "M_E_CPU0_SB_DQ<17>")
	)
	(arc
		(start 330.631038 -284.906974)
		(mid 330.37583 -284.863497)
		(end 330.128118 -284.938724)
		(width 0.0889)
		(layer "In6.Cu")
		(net "M_E_CPU0_SB_DQ<17>")
	)
	(arc
		(start 326.412098 -284.915356)
		(mid 326.295645 -284.955122)
		(end 326.173338 -284.968696)
		(width 0.0889)
		(layer "In6.Cu")
		(net "M_E_CPU0_SB_DQ<17>")
	)
	(arc
		(start 326.934322 -284.938724)
		(mid 326.67608 -284.862822)
		(end 326.412098 -284.915356)
		(width 0.0889)
		(layer "In6.Cu")
		(net "M_E_CPU0_SB_DQ<17>")
	)
	(arc
		(start 330.119736 -284.94355)
		(mid 329.936228 -284.989044)
		(end 329.753976 -284.938724)
		(width 0.0889)
		(layer "In6.Cu")
		(net "M_E_CPU0_SB_DQ<17>")
	)
	(arc
		(start 328.814176 -284.938724)
		(mid 328.53122 -284.862547)
		(end 328.248264 -284.938724)
		(width 0.0889)
		(layer "In6.Cu")
		(net "M_E_CPU0_SB_DQ<17>")
	)
	(arc
		(start 328.248264 -284.938724)
		(mid 328.068059 -284.989041)
		(end 327.88606 -284.945582)
		(width 0.0889)
		(layer "In6.Cu")
		(net "M_E_CPU0_SB_DQ<17>")
	)
	(segment
		(start 329.937872 -283.5402)
		(end 329.47102 -283.806138)
		(width 0.10668)
		(layer "F.Cu")
		(net "M_E_CPU0_SB_DQ<16>")
	)
	(segment
		(start 313.390534 -292.675056)
		(end 313.043824 -293.513764)
		(width 0.14478)
		(layer "In6.Cu")
		(net "M_E_CPU0_SB_DQ<16>")
	)
	(segment
		(start 279.497028 -300.82109)
		(end 279.334214 -300.983904)
		(width 0.14478)
		(layer "In6.Cu")
		(net "M_E_CPU0_SB_DQ<16>")
	)
	(segment
		(start 302.617378 -300.887892)
		(end 302.340518 -300.611032)
		(width 0.14478)
		(layer "In6.Cu")
		(net "M_E_CPU0_SB_DQ<16>")
	)
	(segment
		(start 298.431966 -299.760132)
		(end 297.581828 -300.61027)
		(width 0.14478)
		(layer "In6.Cu")
		(net "M_E_CPU0_SB_DQ<16>")
	)
	(segment
		(start 308.826154 -297.731434)
		(end 308.234842 -298.322492)
		(width 0.14478)
		(layer "In6.Cu")
		(net "M_E_CPU0_SB_DQ<16>")
	)
	(segment
		(start 329.317096 -284.071568)
		(end 329.221084 -284.096968)
		(width 0.0889)
		(layer "In6.Cu")
		(net "M_E_CPU0_SB_DQ<16>")
	)
	(segment
		(start 293.92753 -299.760132)
		(end 290.629594 -299.760132)
		(width 0.14478)
		(layer "In6.Cu")
		(net "M_E_CPU0_SB_DQ<16>")
	)
	(segment
		(start 326.651112 -284.179264)
		(end 325.736204 -284.179264)
		(width 0.0889)
		(layer "In6.Cu")
		(net "M_E_CPU0_SB_DQ<16>")
	)
	(segment
		(start 282.372308 -300.93031)
		(end 282.136088 -300.93031)
		(width 0.14478)
		(layer "In6.Cu")
		(net "M_E_CPU0_SB_DQ<16>")
	)
	(segment
		(start 302.340518 -300.209712)
		(end 302.131984 -300.001178)
		(width 0.14478)
		(layer "In6.Cu")
		(net "M_E_CPU0_SB_DQ<16>")
	)
	(segment
		(start 306.429918 -299.737272)
		(end 306.256182 -299.911008)
		(width 0.14478)
		(layer "In6.Cu")
		(net "M_E_CPU0_SB_DQ<16>")
	)
	(segment
		(start 299.24756 -300.06671)
		(end 298.997878 -300.06671)
		(width 0.14478)
		(layer "In6.Cu")
		(net "M_E_CPU0_SB_DQ<16>")
	)
	(segment
		(start 302.131984 -300.001178)
		(end 301.533052 -300.001178)
		(width 0.14478)
		(layer "In6.Cu")
		(net "M_E_CPU0_SB_DQ<16>")
	)
	(segment
		(start 286.031178 -300.003972)
		(end 285.787338 -299.760132)
		(width 0.14478)
		(layer "In6.Cu")
		(net "M_E_CPU0_SB_DQ<16>")
	)
	(segment
		(start 279.659842 -300.323504)
		(end 279.497028 -300.486318)
		(width 0.14478)
		(layer "In6.Cu")
		(net "M_E_CPU0_SB_DQ<16>")
	)
	(segment
		(start 296.784268 -300.93031)
		(end 296.548048 -300.93031)
		(width 0.14478)
		(layer "In6.Cu")
		(net "M_E_CPU0_SB_DQ<16>")
	)
	(segment
		(start 297.104308 -300.61027)
		(end 296.784268 -300.93031)
		(width 0.14478)
		(layer "In6.Cu")
		(net "M_E_CPU0_SB_DQ<16>")
	)
	(segment
		(start 297.581828 -300.61027)
		(end 297.104308 -300.61027)
		(width 0.14478)
		(layer "In6.Cu")
		(net "M_E_CPU0_SB_DQ<16>")
	)
	(segment
		(start 287.652968 -300.61027)
		(end 287.332928 -300.93031)
		(width 0.14478)
		(layer "In6.Cu")
		(net "M_E_CPU0_SB_DQ<16>")
	)
	(segment
		(start 324.260464 -284.4673)
		(end 323.931534 -284.4673)
		(width 0.0889)
		(layer "In6.Cu")
		(net "M_E_CPU0_SB_DQ<16>")
	)
	(segment
		(start 300.179486 -299.760132)
		(end 299.554138 -299.760132)
		(width 0.14478)
		(layer "In6.Cu")
		(net "M_E_CPU0_SB_DQ<16>")
	)
	(segment
		(start 278.777954 -300.323504)
		(end 278.547322 -300.323504)
		(width 0.14478)
		(layer "In6.Cu")
		(net "M_E_CPU0_SB_DQ<16>")
	)
	(segment
		(start 278.384508 -300.486318)
		(end 278.384508 -300.82109)
		(width 0.14478)
		(layer "In6.Cu")
		(net "M_E_CPU0_SB_DQ<16>")
	)
	(segment
		(start 304.316638 -300.664372)
		(end 304.093118 -300.887892)
		(width 0.14478)
		(layer "In6.Cu")
		(net "M_E_CPU0_SB_DQ<16>")
	)
	(segment
		(start 277.991062 -300.983904)
		(end 277.192232 -300.185074)
		(width 0.14478)
		(layer "In6.Cu")
		(net "M_E_CPU0_SB_DQ<16>")
	)
	(segment
		(start 281.290268 -300.61027)
		(end 280.17724 -300.61027)
		(width 0.14478)
		(layer "In6.Cu")
		(net "M_E_CPU0_SB_DQ<16>")
	)
	(segment
		(start 294.777668 -300.61027)
		(end 293.92753 -299.760132)
		(width 0.14478)
		(layer "In6.Cu")
		(net "M_E_CPU0_SB_DQ<16>")
	)
	(segment
		(start 323.931534 -284.4673)
		(end 322.53936 -284.4673)
		(width 0.14478)
		(layer "In6.Cu")
		(net "M_E_CPU0_SB_DQ<16>")
	)
	(segment
		(start 278.547322 -300.323504)
		(end 278.384508 -300.486318)
		(width 0.14478)
		(layer "In6.Cu")
		(net "M_E_CPU0_SB_DQ<16>")
	)
	(segment
		(start 281.816048 -300.32071)
		(end 281.579828 -300.32071)
		(width 0.14478)
		(layer "In6.Cu")
		(net "M_E_CPU0_SB_DQ<16>")
	)
	(segment
		(start 298.997878 -300.06671)
		(end 298.6913 -299.760132)
		(width 0.14478)
		(layer "In6.Cu")
		(net "M_E_CPU0_SB_DQ<16>")
	)
	(segment
		(start 320.56832 -286.438086)
		(end 319.87236 -287.134046)
		(width 0.14478)
		(layer "In6.Cu")
		(net "M_E_CPU0_SB_DQ<16>")
	)
	(segment
		(start 298.6913 -299.760132)
		(end 298.431966 -299.760132)
		(width 0.14478)
		(layer "In6.Cu")
		(net "M_E_CPU0_SB_DQ<16>")
	)
	(segment
		(start 300.486064 -300.06671)
		(end 300.179486 -299.760132)
		(width 0.14478)
		(layer "In6.Cu")
		(net "M_E_CPU0_SB_DQ<16>")
	)
	(segment
		(start 304.316638 -300.113192)
		(end 304.316638 -300.664372)
		(width 0.14478)
		(layer "In6.Cu")
		(net "M_E_CPU0_SB_DQ<16>")
	)
	(segment
		(start 328.718164 -284.128718)
		(end 328.709782 -284.133544)
		(width 0.0889)
		(layer "In6.Cu")
		(net "M_E_CPU0_SB_DQ<16>")
	)
	(segment
		(start 301.292006 -299.760132)
		(end 301.042324 -299.760132)
		(width 0.14478)
		(layer "In6.Cu")
		(net "M_E_CPU0_SB_DQ<16>")
	)
	(segment
		(start 279.334214 -300.983904)
		(end 279.103582 -300.983904)
		(width 0.14478)
		(layer "In6.Cu")
		(net "M_E_CPU0_SB_DQ<16>")
	)
	(segment
		(start 278.940768 -300.82109)
		(end 278.940768 -300.486318)
		(width 0.14478)
		(layer "In6.Cu")
		(net "M_E_CPU0_SB_DQ<16>")
	)
	(segment
		(start 322.53936 -284.4673)
		(end 320.56832 -286.43834)
		(width 0.14478)
		(layer "In6.Cu")
		(net "M_E_CPU0_SB_DQ<16>")
	)
	(segment
		(start 327.411588 -284.133544)
		(end 327.403206 -284.128718)
		(width 0.0889)
		(layer "In6.Cu")
		(net "M_E_CPU0_SB_DQ<16>")
	)
	(segment
		(start 278.384508 -300.82109)
		(end 278.221694 -300.983904)
		(width 0.14478)
		(layer "In6.Cu")
		(net "M_E_CPU0_SB_DQ<16>")
	)
	(segment
		(start 278.940768 -300.486318)
		(end 278.777954 -300.323504)
		(width 0.14478)
		(layer "In6.Cu")
		(net "M_E_CPU0_SB_DQ<16>")
	)
	(segment
		(start 290.62934 -299.759878)
		(end 289.458908 -300.93031)
		(width 0.14478)
		(layer "In6.Cu")
		(net "M_E_CPU0_SB_DQ<16>")
	)
	(segment
		(start 325.434452 -283.877512)
		(end 324.850252 -283.877512)
		(width 0.0889)
		(layer "In6.Cu")
		(net "M_E_CPU0_SB_DQ<16>")
	)
	(segment
		(start 301.042324 -299.760132)
		(end 300.735746 -300.06671)
		(width 0.14478)
		(layer "In6.Cu")
		(net "M_E_CPU0_SB_DQ<16>")
	)
	(segment
		(start 278.221694 -300.983904)
		(end 277.991062 -300.983904)
		(width 0.14478)
		(layer "In6.Cu")
		(net "M_E_CPU0_SB_DQ<16>")
	)
	(segment
		(start 288.902648 -300.61027)
		(end 287.652968 -300.61027)
		(width 0.14478)
		(layer "In6.Cu")
		(net "M_E_CPU0_SB_DQ<16>")
	)
	(segment
		(start 281.976068 -300.77029)
		(end 281.976068 -300.48073)
		(width 0.14478)
		(layer "In6.Cu")
		(net "M_E_CPU0_SB_DQ<16>")
	)
	(segment
		(start 296.548048 -300.93031)
		(end 296.228008 -300.61027)
		(width 0.14478)
		(layer "In6.Cu")
		(net "M_E_CPU0_SB_DQ<16>")
	)
	(segment
		(start 304.093118 -300.887892)
		(end 302.617378 -300.887892)
		(width 0.14478)
		(layer "In6.Cu")
		(net "M_E_CPU0_SB_DQ<16>")
	)
	(segment
		(start 290.629594 -299.760132)
		(end 290.62934 -299.759878)
		(width 0.14478)
		(layer "In6.Cu")
		(net "M_E_CPU0_SB_DQ<16>")
	)
	(segment
		(start 289.222688 -300.93031)
		(end 288.902648 -300.61027)
		(width 0.14478)
		(layer "In6.Cu")
		(net "M_E_CPU0_SB_DQ<16>")
	)
	(segment
		(start 318.931544 -287.134046)
		(end 313.390534 -292.675056)
		(width 0.14478)
		(layer "In6.Cu")
		(net "M_E_CPU0_SB_DQ<16>")
	)
	(segment
		(start 300.735746 -300.06671)
		(end 300.486064 -300.06671)
		(width 0.14478)
		(layer "In6.Cu")
		(net "M_E_CPU0_SB_DQ<16>")
	)
	(segment
		(start 328.344022 -284.128718)
		(end 328.333608 -284.122622)
		(width 0.0889)
		(layer "In6.Cu")
		(net "M_E_CPU0_SB_DQ<16>")
	)
	(segment
		(start 279.103582 -300.983904)
		(end 278.940768 -300.82109)
		(width 0.14478)
		(layer "In6.Cu")
		(net "M_E_CPU0_SB_DQ<16>")
	)
	(segment
		(start 285.787338 -299.760132)
		(end 283.542486 -299.760132)
		(width 0.14478)
		(layer "In6.Cu")
		(net "M_E_CPU0_SB_DQ<16>")
	)
	(segment
		(start 304.518822 -299.911008)
		(end 304.316638 -300.113192)
		(width 0.14478)
		(layer "In6.Cu")
		(net "M_E_CPU0_SB_DQ<16>")
	)
	(segment
		(start 320.56832 -286.43834)
		(end 320.56832 -286.438086)
		(width 0.14478)
		(layer "In6.Cu")
		(net "M_E_CPU0_SB_DQ<16>")
	)
	(segment
		(start 306.256182 -299.911008)
		(end 304.518822 -299.911008)
		(width 0.14478)
		(layer "In6.Cu")
		(net "M_E_CPU0_SB_DQ<16>")
	)
	(segment
		(start 280.17724 -300.61027)
		(end 279.890474 -300.323504)
		(width 0.14478)
		(layer "In6.Cu")
		(net "M_E_CPU0_SB_DQ<16>")
	)
	(segment
		(start 282.136088 -300.93031)
		(end 281.976068 -300.77029)
		(width 0.14478)
		(layer "In6.Cu")
		(net "M_E_CPU0_SB_DQ<16>")
	)
	(segment
		(start 289.458908 -300.93031)
		(end 289.222688 -300.93031)
		(width 0.14478)
		(layer "In6.Cu")
		(net "M_E_CPU0_SB_DQ<16>")
	)
	(segment
		(start 301.533052 -300.001178)
		(end 301.292006 -299.760132)
		(width 0.14478)
		(layer "In6.Cu")
		(net "M_E_CPU0_SB_DQ<16>")
	)
	(segment
		(start 319.87236 -287.134046)
		(end 318.931544 -287.134046)
		(width 0.14478)
		(layer "In6.Cu")
		(net "M_E_CPU0_SB_DQ<16>")
	)
	(segment
		(start 299.554138 -299.760132)
		(end 299.24756 -300.06671)
		(width 0.14478)
		(layer "In6.Cu")
		(net "M_E_CPU0_SB_DQ<16>")
	)
	(segment
		(start 279.890474 -300.323504)
		(end 279.659842 -300.323504)
		(width 0.14478)
		(layer "In6.Cu")
		(net "M_E_CPU0_SB_DQ<16>")
	)
	(segment
		(start 287.332928 -300.93031)
		(end 286.462216 -300.93031)
		(width 0.14478)
		(layer "In6.Cu")
		(net "M_E_CPU0_SB_DQ<16>")
	)
	(segment
		(start 281.976068 -300.48073)
		(end 281.816048 -300.32071)
		(width 0.14478)
		(layer "In6.Cu")
		(net "M_E_CPU0_SB_DQ<16>")
	)
	(segment
		(start 296.228008 -300.61027)
		(end 294.777668 -300.61027)
		(width 0.14478)
		(layer "In6.Cu")
		(net "M_E_CPU0_SB_DQ<16>")
	)
	(segment
		(start 324.850252 -283.877512)
		(end 324.260464 -284.4673)
		(width 0.0889)
		(layer "In6.Cu")
		(net "M_E_CPU0_SB_DQ<16>")
	)
	(segment
		(start 308.234842 -298.322492)
		(end 306.793138 -298.919646)
		(width 0.14478)
		(layer "In6.Cu")
		(net "M_E_CPU0_SB_DQ<16>")
	)
	(segment
		(start 283.542486 -299.760132)
		(end 282.372308 -300.93031)
		(width 0.14478)
		(layer "In6.Cu")
		(net "M_E_CPU0_SB_DQ<16>")
	)
	(segment
		(start 325.736204 -284.179264)
		(end 325.434452 -283.877512)
		(width 0.0889)
		(layer "In6.Cu")
		(net "M_E_CPU0_SB_DQ<16>")
	)
	(segment
		(start 329.47102 -283.806138)
		(end 329.317096 -284.071568)
		(width 0.0889)
		(layer "In6.Cu")
		(net "M_E_CPU0_SB_DQ<16>")
	)
	(segment
		(start 306.793138 -298.919646)
		(end 306.429918 -299.282866)
		(width 0.14478)
		(layer "In6.Cu")
		(net "M_E_CPU0_SB_DQ<16>")
	)
	(segment
		(start 326.84339 -284.125162)
		(end 326.837802 -284.128464)
		(width 0.0889)
		(layer "In6.Cu")
		(net "M_E_CPU0_SB_DQ<16>")
	)
	(segment
		(start 281.579828 -300.32071)
		(end 281.290268 -300.61027)
		(width 0.14478)
		(layer "In6.Cu")
		(net "M_E_CPU0_SB_DQ<16>")
	)
	(segment
		(start 279.497028 -300.486318)
		(end 279.497028 -300.82109)
		(width 0.14478)
		(layer "In6.Cu")
		(net "M_E_CPU0_SB_DQ<16>")
	)
	(segment
		(start 302.340518 -300.611032)
		(end 302.340518 -300.209712)
		(width 0.14478)
		(layer "In6.Cu")
		(net "M_E_CPU0_SB_DQ<16>")
	)
	(segment
		(start 286.462216 -300.93031)
		(end 286.031178 -300.499272)
		(width 0.14478)
		(layer "In6.Cu")
		(net "M_E_CPU0_SB_DQ<16>")
	)
	(segment
		(start 313.043824 -293.513764)
		(end 308.826154 -297.731434)
		(width 0.14478)
		(layer "In6.Cu")
		(net "M_E_CPU0_SB_DQ<16>")
	)
	(segment
		(start 286.031178 -300.499272)
		(end 286.031178 -300.003972)
		(width 0.14478)
		(layer "In6.Cu")
		(net "M_E_CPU0_SB_DQ<16>")
	)
	(segment
		(start 306.429918 -299.282866)
		(end 306.429918 -299.737272)
		(width 0.14478)
		(layer "In6.Cu")
		(net "M_E_CPU0_SB_DQ<16>")
	)
	(arc
		(start 326.837802 -284.128464)
		(mid 326.747811 -284.166199)
		(end 326.651112 -284.179264)
		(width 0.0889)
		(layer "In6.Cu")
		(net "M_E_CPU0_SB_DQ<16>")
	)
	(arc
		(start 327.403206 -284.128718)
		(mid 327.123778 -284.052552)
		(end 326.84339 -284.125162)
		(width 0.0889)
		(layer "In6.Cu")
		(net "M_E_CPU0_SB_DQ<16>")
	)
	(arc
		(start 328.709782 -284.133544)
		(mid 328.526274 -284.179038)
		(end 328.344022 -284.128718)
		(width 0.0889)
		(layer "In6.Cu")
		(net "M_E_CPU0_SB_DQ<16>")
	)
	(arc
		(start 328.333608 -284.122622)
		(mid 328.054922 -284.052402)
		(end 327.777856 -284.128718)
		(width 0.0889)
		(layer "In6.Cu")
		(net "M_E_CPU0_SB_DQ<16>")
	)
	(arc
		(start 329.221084 -284.096968)
		(mid 328.965876 -284.053491)
		(end 328.718164 -284.128718)
		(width 0.0889)
		(layer "In6.Cu")
		(net "M_E_CPU0_SB_DQ<16>")
	)
	(arc
		(start 327.777856 -284.128718)
		(mid 327.595351 -284.179195)
		(end 327.411588 -284.133544)
		(width 0.0889)
		(layer "In6.Cu")
		(net "M_E_CPU0_SB_DQ<16>")
	)
	(segment
		(start 330.877926 -283.5402)
		(end 330.411074 -283.806138)
		(width 0.10668)
		(layer "F.Cu")
		(net "M_E_CPU0_SB_DQ<15>")
	)
	(segment
		(start 305.165252 -299.359828)
		(end 301.733712 -299.359828)
		(width 0.14478)
		(layer "In6.Cu")
		(net "M_E_CPU0_SB_DQ<15>")
	)
	(segment
		(start 330.564998 -283.540708)
		(end 330.542646 -283.457396)
		(width 0.0889)
		(layer "In6.Cu")
		(net "M_E_CPU0_SB_DQ<15>")
	)
	(segment
		(start 295.39565 -299.760132)
		(end 294.276526 -299.296582)
		(width 0.14478)
		(layer "In6.Cu")
		(net "M_E_CPU0_SB_DQ<15>")
	)
	(segment
		(start 327.788778 -283.489654)
		(end 327.778364 -283.483558)
		(width 0.0889)
		(layer "In6.Cu")
		(net "M_E_CPU0_SB_DQ<15>")
	)
	(segment
		(start 290.688268 -298.913804)
		(end 290.363656 -299.238416)
		(width 0.14478)
		(layer "In6.Cu")
		(net "M_E_CPU0_SB_DQ<15>")
	)
	(segment
		(start 298.494958 -298.909994)
		(end 298.011596 -299.393356)
		(width 0.14478)
		(layer "In6.Cu")
		(net "M_E_CPU0_SB_DQ<15>")
	)
	(segment
		(start 283.372052 -299.11802)
		(end 282.995878 -299.494194)
		(width 0.14478)
		(layer "In6.Cu")
		(net "M_E_CPU0_SB_DQ<15>")
	)
	(segment
		(start 301.733712 -299.359828)
		(end 301.639986 -299.320966)
		(width 0.14478)
		(layer "In6.Cu")
		(net "M_E_CPU0_SB_DQ<15>")
	)
	(segment
		(start 312.724038 -292.843966)
		(end 312.575448 -293.20236)
		(width 0.14478)
		(layer "In6.Cu")
		(net "M_E_CPU0_SB_DQ<15>")
	)
	(segment
		(start 322.31584 -283.91104)
		(end 319.644014 -286.582866)
		(width 0.14478)
		(layer "In6.Cu")
		(net "M_E_CPU0_SB_DQ<15>")
	)
	(segment
		(start 305.783996 -298.741084)
		(end 305.165252 -299.359828)
		(width 0.14478)
		(layer "In6.Cu")
		(net "M_E_CPU0_SB_DQ<15>")
	)
	(segment
		(start 326.307958 -283.552392)
		(end 324.779132 -283.552392)
		(width 0.0889)
		(layer "In6.Cu")
		(net "M_E_CPU0_SB_DQ<15>")
	)
	(segment
		(start 307.922676 -297.855132)
		(end 305.783996 -298.741084)
		(width 0.14478)
		(layer "In6.Cu")
		(net "M_E_CPU0_SB_DQ<15>")
	)
	(segment
		(start 287.554416 -299.760132)
		(end 285.501842 -298.909994)
		(width 0.14478)
		(layer "In6.Cu")
		(net "M_E_CPU0_SB_DQ<15>")
	)
	(segment
		(start 301.229014 -298.909994)
		(end 298.494958 -298.909994)
		(width 0.14478)
		(layer "In6.Cu")
		(net "M_E_CPU0_SB_DQ<15>")
	)
	(segment
		(start 297.125898 -299.760132)
		(end 295.39565 -299.760132)
		(width 0.14478)
		(layer "In6.Cu")
		(net "M_E_CPU0_SB_DQ<15>")
	)
	(segment
		(start 327.40473 -283.483558)
		(end 327.394316 -283.489654)
		(width 0.0889)
		(layer "In6.Cu")
		(net "M_E_CPU0_SB_DQ<15>")
	)
	(segment
		(start 327.778364 -283.483558)
		(end 327.769982 -283.478732)
		(width 0.0889)
		(layer "In6.Cu")
		(net "M_E_CPU0_SB_DQ<15>")
	)
	(segment
		(start 282.995878 -299.494194)
		(end 282.353766 -299.760132)
		(width 0.14478)
		(layer "In6.Cu")
		(net "M_E_CPU0_SB_DQ<15>")
	)
	(segment
		(start 282.353766 -299.760132)
		(end 273.517106 -299.760132)
		(width 0.14478)
		(layer "In6.Cu")
		(net "M_E_CPU0_SB_DQ<15>")
	)
	(segment
		(start 283.87421 -298.909994)
		(end 283.372052 -299.11802)
		(width 0.14478)
		(layer "In6.Cu")
		(net "M_E_CPU0_SB_DQ<15>")
	)
	(segment
		(start 324.779132 -283.552392)
		(end 324.420484 -283.91104)
		(width 0.0889)
		(layer "In6.Cu")
		(net "M_E_CPU0_SB_DQ<15>")
	)
	(segment
		(start 326.475598 -283.48432)
		(end 326.474074 -283.483558)
		(width 0.0889)
		(layer "In6.Cu")
		(net "M_E_CPU0_SB_DQ<15>")
	)
	(segment
		(start 312.575448 -293.20236)
		(end 307.922676 -297.855132)
		(width 0.14478)
		(layer "In6.Cu")
		(net "M_E_CPU0_SB_DQ<15>")
	)
	(segment
		(start 323.884544 -283.91104)
		(end 322.31584 -283.91104)
		(width 0.14478)
		(layer "In6.Cu")
		(net "M_E_CPU0_SB_DQ<15>")
	)
	(segment
		(start 285.501842 -298.909994)
		(end 283.87421 -298.909994)
		(width 0.14478)
		(layer "In6.Cu")
		(net "M_E_CPU0_SB_DQ<15>")
	)
	(segment
		(start 318.703198 -286.582866)
		(end 312.923174 -292.36289)
		(width 0.14478)
		(layer "In6.Cu")
		(net "M_E_CPU0_SB_DQ<15>")
	)
	(segment
		(start 293.893748 -298.913804)
		(end 290.688268 -298.913804)
		(width 0.14478)
		(layer "In6.Cu")
		(net "M_E_CPU0_SB_DQ<15>")
	)
	(segment
		(start 324.420484 -283.91104)
		(end 323.884544 -283.91104)
		(width 0.0889)
		(layer "In6.Cu")
		(net "M_E_CPU0_SB_DQ<15>")
	)
	(segment
		(start 301.639986 -299.320966)
		(end 301.229014 -298.909994)
		(width 0.14478)
		(layer "In6.Cu")
		(net "M_E_CPU0_SB_DQ<15>")
	)
	(segment
		(start 319.644014 -286.582866)
		(end 318.703198 -286.582866)
		(width 0.14478)
		(layer "In6.Cu")
		(net "M_E_CPU0_SB_DQ<15>")
	)
	(segment
		(start 312.923174 -292.36289)
		(end 312.724038 -292.843966)
		(width 0.14478)
		(layer "In6.Cu")
		(net "M_E_CPU0_SB_DQ<15>")
	)
	(segment
		(start 328.718164 -283.483558)
		(end 328.709782 -283.478732)
		(width 0.0889)
		(layer "In6.Cu")
		(net "M_E_CPU0_SB_DQ<15>")
	)
	(segment
		(start 326.474074 -283.483558)
		(end 326.307958 -283.552392)
		(width 0.0889)
		(layer "In6.Cu")
		(net "M_E_CPU0_SB_DQ<15>")
	)
	(segment
		(start 330.411074 -283.806138)
		(end 330.564998 -283.540708)
		(width 0.0889)
		(layer "In6.Cu")
		(net "M_E_CPU0_SB_DQ<15>")
	)
	(segment
		(start 290.363656 -299.238416)
		(end 289.103816 -299.760132)
		(width 0.14478)
		(layer "In6.Cu")
		(net "M_E_CPU0_SB_DQ<15>")
	)
	(segment
		(start 326.651112 -283.433012)
		(end 326.59955 -283.433012)
		(width 0.0889)
		(layer "In6.Cu")
		(net "M_E_CPU0_SB_DQ<15>")
	)
	(segment
		(start 294.276526 -299.296582)
		(end 293.893748 -298.913804)
		(width 0.14478)
		(layer "In6.Cu")
		(net "M_E_CPU0_SB_DQ<15>")
	)
	(segment
		(start 298.011596 -299.393356)
		(end 297.125898 -299.760132)
		(width 0.14478)
		(layer "In6.Cu")
		(net "M_E_CPU0_SB_DQ<15>")
	)
	(segment
		(start 329.292458 -283.478732)
		(end 329.284076 -283.483558)
		(width 0.0889)
		(layer "In6.Cu")
		(net "M_E_CPU0_SB_DQ<15>")
	)
	(segment
		(start 289.103816 -299.760132)
		(end 287.554416 -299.760132)
		(width 0.14478)
		(layer "In6.Cu")
		(net "M_E_CPU0_SB_DQ<15>")
	)
	(segment
		(start 273.517106 -299.760132)
		(end 273.092164 -299.33519)
		(width 0.14478)
		(layer "In6.Cu")
		(net "M_E_CPU0_SB_DQ<15>")
	)
	(arc
		(start 326.838564 -283.483558)
		(mid 326.748185 -283.445871)
		(end 326.651112 -283.433012)
		(width 0.0889)
		(layer "In6.Cu")
		(net "M_E_CPU0_SB_DQ<15>")
	)
	(arc
		(start 329.658218 -283.483558)
		(mid 329.475967 -283.433208)
		(end 329.292458 -283.478732)
		(width 0.0889)
		(layer "In6.Cu")
		(net "M_E_CPU0_SB_DQ<15>")
	)
	(arc
		(start 328.344022 -283.483558)
		(mid 328.067209 -283.559701)
		(end 327.788778 -283.489654)
		(width 0.0889)
		(layer "In6.Cu")
		(net "M_E_CPU0_SB_DQ<15>")
	)
	(arc
		(start 327.394316 -283.489654)
		(mid 327.11563 -283.559874)
		(end 326.838564 -283.483558)
		(width 0.0889)
		(layer "In6.Cu")
		(net "M_E_CPU0_SB_DQ<15>")
	)
	(arc
		(start 330.542646 -283.457396)
		(mid 330.380457 -283.434661)
		(end 330.22413 -283.483558)
		(width 0.0889)
		(layer "In6.Cu")
		(net "M_E_CPU0_SB_DQ<15>")
	)
	(arc
		(start 327.769982 -283.478732)
		(mid 327.586728 -283.433359)
		(end 327.40473 -283.483558)
		(width 0.0889)
		(layer "In6.Cu")
		(net "M_E_CPU0_SB_DQ<15>")
	)
	(arc
		(start 329.284076 -283.483558)
		(mid 329.00112 -283.559735)
		(end 328.718164 -283.483558)
		(width 0.0889)
		(layer "In6.Cu")
		(net "M_E_CPU0_SB_DQ<15>")
	)
	(arc
		(start 330.22413 -283.483558)
		(mid 329.941174 -283.559735)
		(end 329.658218 -283.483558)
		(width 0.0889)
		(layer "In6.Cu")
		(net "M_E_CPU0_SB_DQ<15>")
	)
	(arc
		(start 328.709782 -283.478732)
		(mid 328.526274 -283.433238)
		(end 328.344022 -283.483558)
		(width 0.0889)
		(layer "In6.Cu")
		(net "M_E_CPU0_SB_DQ<15>")
	)
	(arc
		(start 326.59955 -283.433012)
		(mid 326.532481 -283.446353)
		(end 326.475598 -283.48432)
		(width 0.0889)
		(layer "In6.Cu")
		(net "M_E_CPU0_SB_DQ<15>")
	)
	(segment
		(start 329.467972 -282.730194)
		(end 329.00112 -282.996132)
		(width 0.10668)
		(layer "F.Cu")
		(net "M_E_CPU0_SB_DQ<14>")
	)
	(segment
		(start 311.813194 -292.692582)
		(end 308.791102 -295.714674)
		(width 0.14478)
		(layer "In6.Cu")
		(net "M_E_CPU0_SB_DQ<14>")
	)
	(segment
		(start 290.969446 -297.209972)
		(end 290.119308 -298.06011)
		(width 0.14478)
		(layer "In6.Cu")
		(net "M_E_CPU0_SB_DQ<14>")
	)
	(segment
		(start 318.330326 -285.683706)
		(end 312.16092 -291.853112)
		(width 0.14478)
		(layer "In6.Cu")
		(net "M_E_CPU0_SB_DQ<14>")
	)
	(segment
		(start 325.696326 -282.36291)
		(end 324.84314 -282.36291)
		(width 0.0889)
		(layer "In6.Cu")
		(net "M_E_CPU0_SB_DQ<14>")
	)
	(segment
		(start 321.938904 -283.00172)
		(end 319.256918 -285.683706)
		(width 0.14478)
		(layer "In6.Cu")
		(net "M_E_CPU0_SB_DQ<14>")
	)
	(segment
		(start 306.651914 -296.60088)
		(end 305.192684 -298.06011)
		(width 0.14478)
		(layer "In6.Cu")
		(net "M_E_CPU0_SB_DQ<14>")
	)
	(segment
		(start 294.437308 -298.06011)
		(end 293.58717 -297.209972)
		(width 0.14478)
		(layer "In6.Cu")
		(net "M_E_CPU0_SB_DQ<14>")
	)
	(segment
		(start 329.00112 -282.996132)
		(end 329.155044 -282.730702)
		(width 0.0889)
		(layer "In6.Cu")
		(net "M_E_CPU0_SB_DQ<14>")
	)
	(segment
		(start 326.651112 -282.749752)
		(end 326.083168 -282.749752)
		(width 0.0889)
		(layer "In6.Cu")
		(net "M_E_CPU0_SB_DQ<14>")
	)
	(segment
		(start 329.155044 -282.730702)
		(end 329.132692 -282.64739)
		(width 0.0889)
		(layer "In6.Cu")
		(net "M_E_CPU0_SB_DQ<14>")
	)
	(segment
		(start 326.949816 -282.664408)
		(end 326.93356 -282.673806)
		(width 0.0889)
		(layer "In6.Cu")
		(net "M_E_CPU0_SB_DQ<14>")
	)
	(segment
		(start 308.791102 -295.714674)
		(end 306.651914 -296.60088)
		(width 0.14478)
		(layer "In6.Cu")
		(net "M_E_CPU0_SB_DQ<14>")
	)
	(segment
		(start 327.317862 -282.679648)
		(end 327.307448 -282.673552)
		(width 0.0889)
		(layer "In6.Cu")
		(net "M_E_CPU0_SB_DQ<14>")
	)
	(segment
		(start 328.248264 -282.673552)
		(end 328.239882 -282.668726)
		(width 0.0889)
		(layer "In6.Cu")
		(net "M_E_CPU0_SB_DQ<14>")
	)
	(segment
		(start 326.083168 -282.749752)
		(end 325.696326 -282.36291)
		(width 0.0889)
		(layer "In6.Cu")
		(net "M_E_CPU0_SB_DQ<14>")
	)
	(segment
		(start 282.905708 -298.06011)
		(end 273.517106 -298.06011)
		(width 0.14478)
		(layer "In6.Cu")
		(net "M_E_CPU0_SB_DQ<14>")
	)
	(segment
		(start 293.58717 -297.209972)
		(end 290.969446 -297.209972)
		(width 0.14478)
		(layer "In6.Cu")
		(net "M_E_CPU0_SB_DQ<14>")
	)
	(segment
		(start 273.517106 -298.06011)
		(end 273.092164 -297.635168)
		(width 0.14478)
		(layer "In6.Cu")
		(net "M_E_CPU0_SB_DQ<14>")
	)
	(segment
		(start 324.20433 -283.00172)
		(end 323.871844 -283.00172)
		(width 0.0889)
		(layer "In6.Cu")
		(net "M_E_CPU0_SB_DQ<14>")
	)
	(segment
		(start 319.256918 -285.683706)
		(end 318.330326 -285.683706)
		(width 0.14478)
		(layer "In6.Cu")
		(net "M_E_CPU0_SB_DQ<14>")
	)
	(segment
		(start 312.16092 -291.853112)
		(end 311.813194 -292.692582)
		(width 0.14478)
		(layer "In6.Cu")
		(net "M_E_CPU0_SB_DQ<14>")
	)
	(segment
		(start 290.119308 -298.06011)
		(end 286.791908 -298.06011)
		(width 0.14478)
		(layer "In6.Cu")
		(net "M_E_CPU0_SB_DQ<14>")
	)
	(segment
		(start 286.791908 -298.06011)
		(end 285.94177 -297.209972)
		(width 0.14478)
		(layer "In6.Cu")
		(net "M_E_CPU0_SB_DQ<14>")
	)
	(segment
		(start 301.66564 -298.06011)
		(end 300.815502 -297.209972)
		(width 0.14478)
		(layer "In6.Cu")
		(net "M_E_CPU0_SB_DQ<14>")
	)
	(segment
		(start 298.058332 -298.06011)
		(end 294.437308 -298.06011)
		(width 0.14478)
		(layer "In6.Cu")
		(net "M_E_CPU0_SB_DQ<14>")
	)
	(segment
		(start 300.815502 -297.209972)
		(end 298.90847 -297.209972)
		(width 0.14478)
		(layer "In6.Cu")
		(net "M_E_CPU0_SB_DQ<14>")
	)
	(segment
		(start 285.94177 -297.209972)
		(end 283.755846 -297.209972)
		(width 0.14478)
		(layer "In6.Cu")
		(net "M_E_CPU0_SB_DQ<14>")
	)
	(segment
		(start 298.90847 -297.209972)
		(end 298.058332 -298.06011)
		(width 0.14478)
		(layer "In6.Cu")
		(net "M_E_CPU0_SB_DQ<14>")
	)
	(segment
		(start 324.84314 -282.36291)
		(end 324.20433 -283.00172)
		(width 0.0889)
		(layer "In6.Cu")
		(net "M_E_CPU0_SB_DQ<14>")
	)
	(segment
		(start 305.192684 -298.06011)
		(end 301.66564 -298.06011)
		(width 0.14478)
		(layer "In6.Cu")
		(net "M_E_CPU0_SB_DQ<14>")
	)
	(segment
		(start 323.871844 -283.00172)
		(end 321.938904 -283.00172)
		(width 0.14478)
		(layer "In6.Cu")
		(net "M_E_CPU0_SB_DQ<14>")
	)
	(segment
		(start 283.755846 -297.209972)
		(end 282.905708 -298.06011)
		(width 0.14478)
		(layer "In6.Cu")
		(net "M_E_CPU0_SB_DQ<14>")
	)
	(arc
		(start 327.873614 -282.673552)
		(mid 327.596547 -282.749823)
		(end 327.317862 -282.679648)
		(width 0.0889)
		(layer "In6.Cu")
		(net "M_E_CPU0_SB_DQ<14>")
	)
	(arc
		(start 328.814176 -282.673552)
		(mid 328.53122 -282.749729)
		(end 328.248264 -282.673552)
		(width 0.0889)
		(layer "In6.Cu")
		(net "M_E_CPU0_SB_DQ<14>")
	)
	(arc
		(start 329.132692 -282.64739)
		(mid 328.970503 -282.624655)
		(end 328.814176 -282.673552)
		(width 0.0889)
		(layer "In6.Cu")
		(net "M_E_CPU0_SB_DQ<14>")
	)
	(arc
		(start 328.239882 -282.668726)
		(mid 328.05612 -282.62311)
		(end 327.873614 -282.673552)
		(width 0.0889)
		(layer "In6.Cu")
		(net "M_E_CPU0_SB_DQ<14>")
	)
	(arc
		(start 326.93356 -282.673806)
		(mid 326.797345 -282.730391)
		(end 326.651112 -282.749752)
		(width 0.0889)
		(layer "In6.Cu")
		(net "M_E_CPU0_SB_DQ<14>")
	)
	(arc
		(start 327.307448 -282.673552)
		(mid 327.129798 -282.623292)
		(end 326.949816 -282.664408)
		(width 0.0889)
		(layer "In6.Cu")
		(net "M_E_CPU0_SB_DQ<14>")
	)
	(segment
		(start 331.34808 -282.730194)
		(end 330.880974 -282.996132)
		(width 0.10668)
		(layer "F.Cu")
		(net "M_E_CPU0_SB_DQ<13>")
	)
	(segment
		(start 301.022258 -298.06011)
		(end 298.701714 -298.06011)
		(width 0.14478)
		(layer "In6.Cu")
		(net "M_E_CPU0_SB_DQ<13>")
	)
	(segment
		(start 330.880974 -282.996132)
		(end 330.72705 -283.261562)
		(width 0.0889)
		(layer "In6.Cu")
		(net "M_E_CPU0_SB_DQ<13>")
	)
	(segment
		(start 282.063952 -298.76369)
		(end 281.917648 -298.617386)
		(width 0.14478)
		(layer "In6.Cu")
		(net "M_E_CPU0_SB_DQ<13>")
	)
	(segment
		(start 319.450466 -286.133286)
		(end 318.516762 -286.133286)
		(width 0.14478)
		(layer "In6.Cu")
		(net "M_E_CPU0_SB_DQ<13>")
	)
	(segment
		(start 286.9311 -298.910248)
		(end 286.080962 -298.06011)
		(width 0.14478)
		(layer "In6.Cu")
		(net "M_E_CPU0_SB_DQ<13>")
	)
	(segment
		(start 282.063952 -299.056806)
		(end 282.063952 -298.76369)
		(width 0.14478)
		(layer "In6.Cu")
		(net "M_E_CPU0_SB_DQ<13>")
	)
	(segment
		(start 322.127372 -283.45638)
		(end 319.450466 -286.133286)
		(width 0.14478)
		(layer "In6.Cu")
		(net "M_E_CPU0_SB_DQ<13>")
	)
	(segment
		(start 301.872396 -298.910248)
		(end 301.022258 -298.06011)
		(width 0.14478)
		(layer "In6.Cu")
		(net "M_E_CPU0_SB_DQ<13>")
	)
	(segment
		(start 297.851576 -298.910248)
		(end 294.6273 -298.910248)
		(width 0.14478)
		(layer "In6.Cu")
		(net "M_E_CPU0_SB_DQ<13>")
	)
	(segment
		(start 293.777162 -298.06011)
		(end 290.779454 -298.06011)
		(width 0.14478)
		(layer "In6.Cu")
		(net "M_E_CPU0_SB_DQ<13>")
	)
	(segment
		(start 286.080962 -298.06011)
		(end 283.616654 -298.06011)
		(width 0.14478)
		(layer "In6.Cu")
		(net "M_E_CPU0_SB_DQ<13>")
	)
	(segment
		(start 298.701714 -298.06011)
		(end 297.851576 -298.910248)
		(width 0.14478)
		(layer "In6.Cu")
		(net "M_E_CPU0_SB_DQ<13>")
	)
	(segment
		(start 281.917648 -298.617386)
		(end 281.653996 -298.617386)
		(width 0.14478)
		(layer "In6.Cu")
		(net "M_E_CPU0_SB_DQ<13>")
	)
	(segment
		(start 282.210256 -299.20311)
		(end 282.063952 -299.056806)
		(width 0.14478)
		(layer "In6.Cu")
		(net "M_E_CPU0_SB_DQ<13>")
	)
	(segment
		(start 330.72705 -283.261562)
		(end 330.631038 -283.286962)
		(width 0.0889)
		(layer "In6.Cu")
		(net "M_E_CPU0_SB_DQ<13>")
	)
	(segment
		(start 279.876758 -298.532042)
		(end 279.646126 -298.532042)
		(width 0.14478)
		(layer "In6.Cu")
		(net "M_E_CPU0_SB_DQ<13>")
	)
	(segment
		(start 318.516762 -286.133286)
		(end 312.54192 -292.108128)
		(width 0.14478)
		(layer "In6.Cu")
		(net "M_E_CPU0_SB_DQ<13>")
	)
	(segment
		(start 330.128118 -283.318712)
		(end 330.119736 -283.323538)
		(width 0.0889)
		(layer "In6.Cu")
		(net "M_E_CPU0_SB_DQ<13>")
	)
	(segment
		(start 279.483312 -298.694856)
		(end 279.483312 -299.107352)
		(width 0.14478)
		(layer "In6.Cu")
		(net "M_E_CPU0_SB_DQ<13>")
	)
	(segment
		(start 324.420738 -283.349446)
		(end 324.313804 -283.45638)
		(width 0.0889)
		(layer "In6.Cu")
		(net "M_E_CPU0_SB_DQ<13>")
	)
	(segment
		(start 294.6273 -298.910248)
		(end 293.777162 -298.06011)
		(width 0.14478)
		(layer "In6.Cu")
		(net "M_E_CPU0_SB_DQ<13>")
	)
	(segment
		(start 282.473654 -299.20311)
		(end 282.210256 -299.20311)
		(width 0.14478)
		(layer "In6.Cu")
		(net "M_E_CPU0_SB_DQ<13>")
	)
	(segment
		(start 279.483312 -299.107352)
		(end 279.320498 -299.270166)
		(width 0.14478)
		(layer "In6.Cu")
		(net "M_E_CPU0_SB_DQ<13>")
	)
	(segment
		(start 278.207978 -299.270166)
		(end 277.977346 -299.270166)
		(width 0.14478)
		(layer "In6.Cu")
		(net "M_E_CPU0_SB_DQ<13>")
	)
	(segment
		(start 326.428862 -283.276294)
		(end 326.252332 -283.349446)
		(width 0.0889)
		(layer "In6.Cu")
		(net "M_E_CPU0_SB_DQ<13>")
	)
	(segment
		(start 280.804874 -298.910248)
		(end 280.254964 -298.910248)
		(width 0.14478)
		(layer "In6.Cu")
		(net "M_E_CPU0_SB_DQ<13>")
	)
	(segment
		(start 327.308718 -283.318712)
		(end 327.297034 -283.32557)
		(width 0.0889)
		(layer "In6.Cu")
		(net "M_E_CPU0_SB_DQ<13>")
	)
	(segment
		(start 281.097736 -299.20311)
		(end 280.804874 -298.910248)
		(width 0.14478)
		(layer "In6.Cu")
		(net "M_E_CPU0_SB_DQ<13>")
	)
	(segment
		(start 280.254964 -298.910248)
		(end 279.876758 -298.532042)
		(width 0.14478)
		(layer "In6.Cu")
		(net "M_E_CPU0_SB_DQ<13>")
	)
	(segment
		(start 278.533606 -298.532042)
		(end 278.370792 -298.694856)
		(width 0.14478)
		(layer "In6.Cu")
		(net "M_E_CPU0_SB_DQ<13>")
	)
	(segment
		(start 277.977346 -299.270166)
		(end 277.192232 -298.485052)
		(width 0.14478)
		(layer "In6.Cu")
		(net "M_E_CPU0_SB_DQ<13>")
	)
	(segment
		(start 326.252332 -283.349446)
		(end 324.420738 -283.349446)
		(width 0.0889)
		(layer "In6.Cu")
		(net "M_E_CPU0_SB_DQ<13>")
	)
	(segment
		(start 323.882004 -283.45638)
		(end 322.127372 -283.45638)
		(width 0.14478)
		(layer "In6.Cu")
		(net "M_E_CPU0_SB_DQ<13>")
	)
	(segment
		(start 279.320498 -299.270166)
		(end 279.089866 -299.270166)
		(width 0.14478)
		(layer "In6.Cu")
		(net "M_E_CPU0_SB_DQ<13>")
	)
	(segment
		(start 306.906676 -296.982134)
		(end 304.978562 -298.910248)
		(width 0.14478)
		(layer "In6.Cu")
		(net "M_E_CPU0_SB_DQ<13>")
	)
	(segment
		(start 327.88606 -283.32557)
		(end 327.874376 -283.318712)
		(width 0.0889)
		(layer "In6.Cu")
		(net "M_E_CPU0_SB_DQ<13>")
	)
	(segment
		(start 279.646126 -298.532042)
		(end 279.483312 -298.694856)
		(width 0.14478)
		(layer "In6.Cu")
		(net "M_E_CPU0_SB_DQ<13>")
	)
	(segment
		(start 309.045864 -296.095928)
		(end 306.906676 -296.982134)
		(width 0.14478)
		(layer "In6.Cu")
		(net "M_E_CPU0_SB_DQ<13>")
	)
	(segment
		(start 289.929316 -298.910248)
		(end 286.9311 -298.910248)
		(width 0.14478)
		(layer "In6.Cu")
		(net "M_E_CPU0_SB_DQ<13>")
	)
	(segment
		(start 278.927052 -298.694856)
		(end 278.764238 -298.532042)
		(width 0.14478)
		(layer "In6.Cu")
		(net "M_E_CPU0_SB_DQ<13>")
	)
	(segment
		(start 278.764238 -298.532042)
		(end 278.533606 -298.532042)
		(width 0.14478)
		(layer "In6.Cu")
		(net "M_E_CPU0_SB_DQ<13>")
	)
	(segment
		(start 279.089866 -299.270166)
		(end 278.927052 -299.107352)
		(width 0.14478)
		(layer "In6.Cu")
		(net "M_E_CPU0_SB_DQ<13>")
	)
	(segment
		(start 281.361388 -299.20311)
		(end 281.097736 -299.20311)
		(width 0.14478)
		(layer "In6.Cu")
		(net "M_E_CPU0_SB_DQ<13>")
	)
	(segment
		(start 278.370792 -298.694856)
		(end 278.370792 -299.107352)
		(width 0.14478)
		(layer "In6.Cu")
		(net "M_E_CPU0_SB_DQ<13>")
	)
	(segment
		(start 283.616654 -298.06011)
		(end 282.473654 -299.20311)
		(width 0.14478)
		(layer "In6.Cu")
		(net "M_E_CPU0_SB_DQ<13>")
	)
	(segment
		(start 278.370792 -299.107352)
		(end 278.207978 -299.270166)
		(width 0.14478)
		(layer "In6.Cu")
		(net "M_E_CPU0_SB_DQ<13>")
	)
	(segment
		(start 312.54192 -292.108128)
		(end 312.194194 -292.947598)
		(width 0.14478)
		(layer "In6.Cu")
		(net "M_E_CPU0_SB_DQ<13>")
	)
	(segment
		(start 326.651112 -283.242512)
		(end 326.59955 -283.242512)
		(width 0.0889)
		(layer "In6.Cu")
		(net "M_E_CPU0_SB_DQ<13>")
	)
	(segment
		(start 278.927052 -299.107352)
		(end 278.927052 -298.694856)
		(width 0.14478)
		(layer "In6.Cu")
		(net "M_E_CPU0_SB_DQ<13>")
	)
	(segment
		(start 304.978562 -298.910248)
		(end 301.872396 -298.910248)
		(width 0.14478)
		(layer "In6.Cu")
		(net "M_E_CPU0_SB_DQ<13>")
	)
	(segment
		(start 281.653996 -298.617386)
		(end 281.507692 -298.76369)
		(width 0.14478)
		(layer "In6.Cu")
		(net "M_E_CPU0_SB_DQ<13>")
	)
	(segment
		(start 281.507692 -298.76369)
		(end 281.507692 -299.056806)
		(width 0.14478)
		(layer "In6.Cu")
		(net "M_E_CPU0_SB_DQ<13>")
	)
	(segment
		(start 324.313804 -283.45638)
		(end 323.882004 -283.45638)
		(width 0.0889)
		(layer "In6.Cu")
		(net "M_E_CPU0_SB_DQ<13>")
	)
	(segment
		(start 327.874376 -283.318712)
		(end 327.863962 -283.312616)
		(width 0.0889)
		(layer "In6.Cu")
		(net "M_E_CPU0_SB_DQ<13>")
	)
	(segment
		(start 290.779454 -298.06011)
		(end 289.929316 -298.910248)
		(width 0.14478)
		(layer "In6.Cu")
		(net "M_E_CPU0_SB_DQ<13>")
	)
	(segment
		(start 312.194194 -292.947598)
		(end 309.045864 -296.095928)
		(width 0.14478)
		(layer "In6.Cu")
		(net "M_E_CPU0_SB_DQ<13>")
	)
	(segment
		(start 281.507692 -299.056806)
		(end 281.361388 -299.20311)
		(width 0.14478)
		(layer "In6.Cu")
		(net "M_E_CPU0_SB_DQ<13>")
	)
	(arc
		(start 327.297034 -283.32557)
		(mid 327.114779 -283.369223)
		(end 326.934322 -283.318712)
		(width 0.0889)
		(layer "In6.Cu")
		(net "M_E_CPU0_SB_DQ<13>")
	)
	(arc
		(start 330.119736 -283.323538)
		(mid 329.936228 -283.369032)
		(end 329.753976 -283.318712)
		(width 0.0889)
		(layer "In6.Cu")
		(net "M_E_CPU0_SB_DQ<13>")
	)
	(arc
		(start 329.188064 -283.318712)
		(mid 329.00112 -283.368967)
		(end 328.814176 -283.318712)
		(width 0.0889)
		(layer "In6.Cu")
		(net "M_E_CPU0_SB_DQ<13>")
	)
	(arc
		(start 326.59955 -283.242512)
		(mid 326.512543 -283.250994)
		(end 326.428862 -283.276294)
		(width 0.0889)
		(layer "In6.Cu")
		(net "M_E_CPU0_SB_DQ<13>")
	)
	(arc
		(start 329.753976 -283.318712)
		(mid 329.47102 -283.242535)
		(end 329.188064 -283.318712)
		(width 0.0889)
		(layer "In6.Cu")
		(net "M_E_CPU0_SB_DQ<13>")
	)
	(arc
		(start 326.934322 -283.318712)
		(mid 326.797763 -283.261854)
		(end 326.651112 -283.242512)
		(width 0.0889)
		(layer "In6.Cu")
		(net "M_E_CPU0_SB_DQ<13>")
	)
	(arc
		(start 328.248264 -283.318712)
		(mid 328.068059 -283.369029)
		(end 327.88606 -283.32557)
		(width 0.0889)
		(layer "In6.Cu")
		(net "M_E_CPU0_SB_DQ<13>")
	)
	(arc
		(start 327.863962 -283.312616)
		(mid 327.58553 -283.242518)
		(end 327.308718 -283.318712)
		(width 0.0889)
		(layer "In6.Cu")
		(net "M_E_CPU0_SB_DQ<13>")
	)
	(arc
		(start 330.631038 -283.286962)
		(mid 330.37583 -283.243485)
		(end 330.128118 -283.318712)
		(width 0.0889)
		(layer "In6.Cu")
		(net "M_E_CPU0_SB_DQ<13>")
	)
	(arc
		(start 328.814176 -283.318712)
		(mid 328.53122 -283.242535)
		(end 328.248264 -283.318712)
		(width 0.0889)
		(layer "In6.Cu")
		(net "M_E_CPU0_SB_DQ<13>")
	)
	(segment
		(start 329.937872 -281.920188)
		(end 329.47102 -282.186126)
		(width 0.10668)
		(layer "F.Cu")
		(net "M_E_CPU0_SB_DQ<12>")
	)
	(segment
		(start 294.275256 -297.219878)
		(end 293.425118 -296.36974)
		(width 0.14478)
		(layer "In6.Cu")
		(net "M_E_CPU0_SB_DQ<12>")
	)
	(segment
		(start 293.425118 -296.36974)
		(end 291.149278 -296.36974)
		(width 0.14478)
		(layer "In6.Cu")
		(net "M_E_CPU0_SB_DQ<12>")
	)
	(segment
		(start 319.7987 -283.78404)
		(end 320.052446 -284.037786)
		(width 0.14478)
		(layer "In6.Cu")
		(net "M_E_CPU0_SB_DQ<12>")
	)
	(segment
		(start 319.254886 -285.04007)
		(end 319.06083 -285.234126)
		(width 0.14478)
		(layer "In6.Cu")
		(net "M_E_CPU0_SB_DQ<12>")
	)
	(segment
		(start 278.173688 -297.52671)
		(end 277.933912 -297.52671)
		(width 0.14478)
		(layer "In6.Cu")
		(net "M_E_CPU0_SB_DQ<12>")
	)
	(segment
		(start 320.850006 -283.44495)
		(end 320.65595 -283.639006)
		(width 0.14478)
		(layer "In6.Cu")
		(net "M_E_CPU0_SB_DQ<12>")
	)
	(segment
		(start 319.7987 -283.579316)
		(end 319.7987 -283.78404)
		(width 0.14478)
		(layer "In6.Cu")
		(net "M_E_CPU0_SB_DQ<12>")
	)
	(segment
		(start 279.046432 -297.52671)
		(end 278.729948 -297.210226)
		(width 0.14478)
		(layer "In6.Cu")
		(net "M_E_CPU0_SB_DQ<12>")
	)
	(segment
		(start 308.53634 -295.33342)
		(end 306.397152 -296.219626)
		(width 0.14478)
		(layer "In6.Cu")
		(net "M_E_CPU0_SB_DQ<12>")
	)
	(segment
		(start 282.767024 -297.50131)
		(end 282.501848 -297.50131)
		(width 0.14478)
		(layer "In6.Cu")
		(net "M_E_CPU0_SB_DQ<12>")
	)
	(segment
		(start 300.849538 -296.36974)
		(end 298.898818 -296.36974)
		(width 0.14478)
		(layer "In6.Cu")
		(net "M_E_CPU0_SB_DQ<12>")
	)
	(segment
		(start 327.411588 -282.513532)
		(end 327.403206 -282.508706)
		(width 0.0889)
		(layer "In6.Cu")
		(net "M_E_CPU0_SB_DQ<12>")
	)
	(segment
		(start 278.490172 -297.210226)
		(end 278.173688 -297.52671)
		(width 0.14478)
		(layer "In6.Cu")
		(net "M_E_CPU0_SB_DQ<12>")
	)
	(segment
		(start 324.362318 -282.15971)
		(end 323.974968 -282.54706)
		(width 0.0889)
		(layer "In6.Cu")
		(net "M_E_CPU0_SB_DQ<12>")
	)
	(segment
		(start 303.675288 -297.210226)
		(end 303.358804 -297.52671)
		(width 0.14478)
		(layer "In6.Cu")
		(net "M_E_CPU0_SB_DQ<12>")
	)
	(segment
		(start 298.04868 -297.219878)
		(end 294.275256 -297.219878)
		(width 0.14478)
		(layer "In6.Cu")
		(net "M_E_CPU0_SB_DQ<12>")
	)
	(segment
		(start 277.933912 -297.52671)
		(end 277.192232 -296.78503)
		(width 0.14478)
		(layer "In6.Cu")
		(net "M_E_CPU0_SB_DQ<12>")
	)
	(segment
		(start 328.344022 -282.508706)
		(end 328.333608 -282.50261)
		(width 0.0889)
		(layer "In6.Cu")
		(net "M_E_CPU0_SB_DQ<12>")
	)
	(segment
		(start 279.59304 -297.219878)
		(end 279.286208 -297.52671)
		(width 0.14478)
		(layer "In6.Cu")
		(net "M_E_CPU0_SB_DQ<12>")
	)
	(segment
		(start 302.404526 -297.051984)
		(end 302.404526 -297.368468)
		(width 0.14478)
		(layer "In6.Cu")
		(net "M_E_CPU0_SB_DQ<12>")
	)
	(segment
		(start 320.59626 -282.781756)
		(end 320.59626 -282.98648)
		(width 0.14478)
		(layer "In6.Cu")
		(net "M_E_CPU0_SB_DQ<12>")
	)
	(segment
		(start 302.802544 -296.893742)
		(end 302.562768 -296.893742)
		(width 0.14478)
		(layer "In6.Cu")
		(net "M_E_CPU0_SB_DQ<12>")
	)
	(segment
		(start 320.850006 -283.240226)
		(end 320.850006 -283.44495)
		(width 0.14478)
		(layer "In6.Cu")
		(net "M_E_CPU0_SB_DQ<12>")
	)
	(segment
		(start 320.052446 -284.037786)
		(end 320.052446 -284.24251)
		(width 0.14478)
		(layer "In6.Cu")
		(net "M_E_CPU0_SB_DQ<12>")
	)
	(segment
		(start 302.960786 -297.368468)
		(end 302.960786 -297.051984)
		(width 0.14478)
		(layer "In6.Cu")
		(net "M_E_CPU0_SB_DQ<12>")
	)
	(segment
		(start 278.729948 -297.210226)
		(end 278.490172 -297.210226)
		(width 0.14478)
		(layer "In6.Cu")
		(net "M_E_CPU0_SB_DQ<12>")
	)
	(segment
		(start 298.898818 -296.36974)
		(end 298.04868 -297.219878)
		(width 0.14478)
		(layer "In6.Cu")
		(net "M_E_CPU0_SB_DQ<12>")
	)
	(segment
		(start 282.501848 -297.50131)
		(end 282.210764 -297.210226)
		(width 0.14478)
		(layer "In6.Cu")
		(net "M_E_CPU0_SB_DQ<12>")
	)
	(segment
		(start 302.006508 -297.52671)
		(end 300.849538 -296.36974)
		(width 0.14478)
		(layer "In6.Cu")
		(net "M_E_CPU0_SB_DQ<12>")
	)
	(segment
		(start 281.945588 -297.210226)
		(end 281.654504 -297.50131)
		(width 0.14478)
		(layer "In6.Cu")
		(net "M_E_CPU0_SB_DQ<12>")
	)
	(segment
		(start 285.838138 -296.36974)
		(end 283.898594 -296.36974)
		(width 0.14478)
		(layer "In6.Cu")
		(net "M_E_CPU0_SB_DQ<12>")
	)
	(segment
		(start 319.653666 -284.436566)
		(end 319.39992 -284.18282)
		(width 0.14478)
		(layer "In6.Cu")
		(net "M_E_CPU0_SB_DQ<12>")
	)
	(segment
		(start 326.651112 -282.559252)
		(end 326.180196 -282.559252)
		(width 0.0889)
		(layer "In6.Cu")
		(net "M_E_CPU0_SB_DQ<12>")
	)
	(segment
		(start 305.406552 -297.210226)
		(end 303.675288 -297.210226)
		(width 0.14478)
		(layer "In6.Cu")
		(net "M_E_CPU0_SB_DQ<12>")
	)
	(segment
		(start 290.29914 -297.219878)
		(end 286.688276 -297.219878)
		(width 0.14478)
		(layer "In6.Cu")
		(net "M_E_CPU0_SB_DQ<12>")
	)
	(segment
		(start 281.654504 -297.50131)
		(end 281.389328 -297.50131)
		(width 0.14478)
		(layer "In6.Cu")
		(net "M_E_CPU0_SB_DQ<12>")
	)
	(segment
		(start 325.780654 -282.15971)
		(end 324.362318 -282.15971)
		(width 0.0889)
		(layer "In6.Cu")
		(net "M_E_CPU0_SB_DQ<12>")
	)
	(segment
		(start 319.992756 -283.38526)
		(end 319.7987 -283.579316)
		(width 0.14478)
		(layer "In6.Cu")
		(net "M_E_CPU0_SB_DQ<12>")
	)
	(segment
		(start 302.246284 -297.52671)
		(end 302.006508 -297.52671)
		(width 0.14478)
		(layer "In6.Cu")
		(net "M_E_CPU0_SB_DQ<12>")
	)
	(segment
		(start 302.404526 -297.368468)
		(end 302.246284 -297.52671)
		(width 0.14478)
		(layer "In6.Cu")
		(net "M_E_CPU0_SB_DQ<12>")
	)
	(segment
		(start 279.286208 -297.52671)
		(end 279.046432 -297.52671)
		(width 0.14478)
		(layer "In6.Cu")
		(net "M_E_CPU0_SB_DQ<12>")
	)
	(segment
		(start 318.856106 -285.234126)
		(end 318.60236 -284.98038)
		(width 0.14478)
		(layer "In6.Cu")
		(net "M_E_CPU0_SB_DQ<12>")
	)
	(segment
		(start 328.718164 -282.508706)
		(end 328.709782 -282.513532)
		(width 0.0889)
		(layer "In6.Cu")
		(net "M_E_CPU0_SB_DQ<12>")
	)
	(segment
		(start 306.397152 -296.219626)
		(end 305.406552 -297.210226)
		(width 0.14478)
		(layer "In6.Cu")
		(net "M_E_CPU0_SB_DQ<12>")
	)
	(segment
		(start 326.84339 -282.50515)
		(end 326.837802 -282.508452)
		(width 0.0889)
		(layer "In6.Cu")
		(net "M_E_CPU0_SB_DQ<12>")
	)
	(segment
		(start 320.65595 -283.639006)
		(end 320.451226 -283.639006)
		(width 0.14478)
		(layer "In6.Cu")
		(net "M_E_CPU0_SB_DQ<12>")
	)
	(segment
		(start 283.898594 -296.36974)
		(end 282.767024 -297.50131)
		(width 0.14478)
		(layer "In6.Cu")
		(net "M_E_CPU0_SB_DQ<12>")
	)
	(segment
		(start 318.397636 -284.98038)
		(end 311.779666 -291.59835)
		(width 0.14478)
		(layer "In6.Cu")
		(net "M_E_CPU0_SB_DQ<12>")
	)
	(segment
		(start 320.59626 -282.98648)
		(end 320.850006 -283.240226)
		(width 0.14478)
		(layer "In6.Cu")
		(net "M_E_CPU0_SB_DQ<12>")
	)
	(segment
		(start 311.779666 -291.59835)
		(end 311.43194 -292.43782)
		(width 0.14478)
		(layer "In6.Cu")
		(net "M_E_CPU0_SB_DQ<12>")
	)
	(segment
		(start 319.85839 -284.436566)
		(end 319.653666 -284.436566)
		(width 0.14478)
		(layer "In6.Cu")
		(net "M_E_CPU0_SB_DQ<12>")
	)
	(segment
		(start 319.00114 -284.5816)
		(end 319.254886 -284.835346)
		(width 0.14478)
		(layer "In6.Cu")
		(net "M_E_CPU0_SB_DQ<12>")
	)
	(segment
		(start 329.317096 -282.451556)
		(end 329.221084 -282.476956)
		(width 0.0889)
		(layer "In6.Cu")
		(net "M_E_CPU0_SB_DQ<12>")
	)
	(segment
		(start 303.119028 -297.52671)
		(end 302.960786 -297.368468)
		(width 0.14478)
		(layer "In6.Cu")
		(net "M_E_CPU0_SB_DQ<12>")
	)
	(segment
		(start 319.39992 -284.18282)
		(end 319.195196 -284.18282)
		(width 0.14478)
		(layer "In6.Cu")
		(net "M_E_CPU0_SB_DQ<12>")
	)
	(segment
		(start 329.47102 -282.186126)
		(end 329.317096 -282.451556)
		(width 0.0889)
		(layer "In6.Cu")
		(net "M_E_CPU0_SB_DQ<12>")
	)
	(segment
		(start 326.180196 -282.559252)
		(end 325.780654 -282.15971)
		(width 0.0889)
		(layer "In6.Cu")
		(net "M_E_CPU0_SB_DQ<12>")
	)
	(segment
		(start 319.195196 -284.18282)
		(end 319.00114 -284.376876)
		(width 0.14478)
		(layer "In6.Cu")
		(net "M_E_CPU0_SB_DQ<12>")
	)
	(segment
		(start 323.974968 -282.54706)
		(end 320.830956 -282.54706)
		(width 0.14478)
		(layer "In6.Cu")
		(net "M_E_CPU0_SB_DQ<12>")
	)
	(segment
		(start 286.688276 -297.219878)
		(end 285.838138 -296.36974)
		(width 0.14478)
		(layer "In6.Cu")
		(net "M_E_CPU0_SB_DQ<12>")
	)
	(segment
		(start 319.06083 -285.234126)
		(end 318.856106 -285.234126)
		(width 0.14478)
		(layer "In6.Cu")
		(net "M_E_CPU0_SB_DQ<12>")
	)
	(segment
		(start 302.960786 -297.051984)
		(end 302.802544 -296.893742)
		(width 0.14478)
		(layer "In6.Cu")
		(net "M_E_CPU0_SB_DQ<12>")
	)
	(segment
		(start 320.052446 -284.24251)
		(end 319.85839 -284.436566)
		(width 0.14478)
		(layer "In6.Cu")
		(net "M_E_CPU0_SB_DQ<12>")
	)
	(segment
		(start 291.149278 -296.36974)
		(end 290.29914 -297.219878)
		(width 0.14478)
		(layer "In6.Cu")
		(net "M_E_CPU0_SB_DQ<12>")
	)
	(segment
		(start 281.107896 -297.219878)
		(end 279.59304 -297.219878)
		(width 0.14478)
		(layer "In6.Cu")
		(net "M_E_CPU0_SB_DQ<12>")
	)
	(segment
		(start 319.254886 -284.835346)
		(end 319.254886 -285.04007)
		(width 0.14478)
		(layer "In6.Cu")
		(net "M_E_CPU0_SB_DQ<12>")
	)
	(segment
		(start 319.00114 -284.376876)
		(end 319.00114 -284.5816)
		(width 0.14478)
		(layer "In6.Cu")
		(net "M_E_CPU0_SB_DQ<12>")
	)
	(segment
		(start 281.389328 -297.50131)
		(end 281.107896 -297.219878)
		(width 0.14478)
		(layer "In6.Cu")
		(net "M_E_CPU0_SB_DQ<12>")
	)
	(segment
		(start 318.60236 -284.98038)
		(end 318.397636 -284.98038)
		(width 0.14478)
		(layer "In6.Cu")
		(net "M_E_CPU0_SB_DQ<12>")
	)
	(segment
		(start 282.210764 -297.210226)
		(end 281.945588 -297.210226)
		(width 0.14478)
		(layer "In6.Cu")
		(net "M_E_CPU0_SB_DQ<12>")
	)
	(segment
		(start 320.451226 -283.639006)
		(end 320.19748 -283.38526)
		(width 0.14478)
		(layer "In6.Cu")
		(net "M_E_CPU0_SB_DQ<12>")
	)
	(segment
		(start 311.43194 -292.43782)
		(end 308.53634 -295.33342)
		(width 0.14478)
		(layer "In6.Cu")
		(net "M_E_CPU0_SB_DQ<12>")
	)
	(segment
		(start 303.358804 -297.52671)
		(end 303.119028 -297.52671)
		(width 0.14478)
		(layer "In6.Cu")
		(net "M_E_CPU0_SB_DQ<12>")
	)
	(segment
		(start 302.562768 -296.893742)
		(end 302.404526 -297.051984)
		(width 0.14478)
		(layer "In6.Cu")
		(net "M_E_CPU0_SB_DQ<12>")
	)
	(segment
		(start 320.830956 -282.54706)
		(end 320.59626 -282.781756)
		(width 0.14478)
		(layer "In6.Cu")
		(net "M_E_CPU0_SB_DQ<12>")
	)
	(segment
		(start 320.19748 -283.38526)
		(end 319.992756 -283.38526)
		(width 0.14478)
		(layer "In6.Cu")
		(net "M_E_CPU0_SB_DQ<12>")
	)
	(arc
		(start 327.777856 -282.508706)
		(mid 327.595351 -282.559183)
		(end 327.411588 -282.513532)
		(width 0.0889)
		(layer "In6.Cu")
		(net "M_E_CPU0_SB_DQ<12>")
	)
	(arc
		(start 329.221084 -282.476956)
		(mid 328.965876 -282.433479)
		(end 328.718164 -282.508706)
		(width 0.0889)
		(layer "In6.Cu")
		(net "M_E_CPU0_SB_DQ<12>")
	)
	(arc
		(start 328.333608 -282.50261)
		(mid 328.054922 -282.43239)
		(end 327.777856 -282.508706)
		(width 0.0889)
		(layer "In6.Cu")
		(net "M_E_CPU0_SB_DQ<12>")
	)
	(arc
		(start 327.403206 -282.508706)
		(mid 327.123778 -282.43254)
		(end 326.84339 -282.50515)
		(width 0.0889)
		(layer "In6.Cu")
		(net "M_E_CPU0_SB_DQ<12>")
	)
	(arc
		(start 328.709782 -282.513532)
		(mid 328.526274 -282.559026)
		(end 328.344022 -282.508706)
		(width 0.0889)
		(layer "In6.Cu")
		(net "M_E_CPU0_SB_DQ<12>")
	)
	(arc
		(start 326.837802 -282.508452)
		(mid 326.747811 -282.546187)
		(end 326.651112 -282.559252)
		(width 0.0889)
		(layer "In6.Cu")
		(net "M_E_CPU0_SB_DQ<12>")
	)
	(segment
		(start 330.877926 -280.300176)
		(end 330.411074 -280.566114)
		(width 0.10668)
		(layer "F.Cu")
		(net "M_E_CPU0_SB_DQ<11>")
	)
	(segment
		(start 309.274718 -291.357558)
		(end 307.786786 -292.84549)
		(width 0.14478)
		(layer "In6.Cu")
		(net "M_E_CPU0_SB_DQ<11>")
	)
	(segment
		(start 290.555426 -292.950392)
		(end 289.705542 -293.800276)
		(width 0.14478)
		(layer "In6.Cu")
		(net "M_E_CPU0_SB_DQ<11>")
	)
	(segment
		(start 319.35674 -280.20772)
		(end 309.274718 -290.289742)
		(width 0.14478)
		(layer "In6.Cu")
		(net "M_E_CPU0_SB_DQ<11>")
	)
	(segment
		(start 307.786786 -292.84549)
		(end 305.444652 -292.84549)
		(width 0.14478)
		(layer "In6.Cu")
		(net "M_E_CPU0_SB_DQ<11>")
	)
	(segment
		(start 324.180454 -280.12771)
		(end 324.100444 -280.20772)
		(width 0.0889)
		(layer "In6.Cu")
		(net "M_E_CPU0_SB_DQ<11>")
	)
	(segment
		(start 305.444652 -292.84549)
		(end 304.880518 -293.409624)
		(width 0.14478)
		(layer "In6.Cu")
		(net "M_E_CPU0_SB_DQ<11>")
	)
	(segment
		(start 304.880518 -293.409624)
		(end 301.017178 -293.409624)
		(width 0.14478)
		(layer "In6.Cu")
		(net "M_E_CPU0_SB_DQ<11>")
	)
	(segment
		(start 294.266874 -293.800276)
		(end 293.41699 -292.950392)
		(width 0.14478)
		(layer "In6.Cu")
		(net "M_E_CPU0_SB_DQ<11>")
	)
	(segment
		(start 282.237942 -293.800276)
		(end 273.507454 -293.800276)
		(width 0.14478)
		(layer "In6.Cu")
		(net "M_E_CPU0_SB_DQ<11>")
	)
	(segment
		(start 323.908674 -280.20772)
		(end 319.35674 -280.20772)
		(width 0.14478)
		(layer "In6.Cu")
		(net "M_E_CPU0_SB_DQ<11>")
	)
	(segment
		(start 329.292458 -280.238708)
		(end 329.284076 -280.243534)
		(width 0.0889)
		(layer "In6.Cu")
		(net "M_E_CPU0_SB_DQ<11>")
	)
	(segment
		(start 289.705542 -293.800276)
		(end 286.900874 -293.800276)
		(width 0.14478)
		(layer "In6.Cu")
		(net "M_E_CPU0_SB_DQ<11>")
	)
	(segment
		(start 330.564998 -280.300684)
		(end 330.542646 -280.217372)
		(width 0.0889)
		(layer "In6.Cu")
		(net "M_E_CPU0_SB_DQ<11>")
	)
	(segment
		(start 297.82135 -292.950392)
		(end 296.971466 -293.800276)
		(width 0.14478)
		(layer "In6.Cu")
		(net "M_E_CPU0_SB_DQ<11>")
	)
	(segment
		(start 273.507454 -293.800276)
		(end 273.092164 -293.384986)
		(width 0.14478)
		(layer "In6.Cu")
		(net "M_E_CPU0_SB_DQ<11>")
	)
	(segment
		(start 296.971466 -293.800276)
		(end 294.266874 -293.800276)
		(width 0.14478)
		(layer "In6.Cu")
		(net "M_E_CPU0_SB_DQ<11>")
	)
	(segment
		(start 330.411074 -280.566114)
		(end 330.564998 -280.300684)
		(width 0.0889)
		(layer "In6.Cu")
		(net "M_E_CPU0_SB_DQ<11>")
	)
	(segment
		(start 286.05099 -292.950392)
		(end 283.087826 -292.950392)
		(width 0.14478)
		(layer "In6.Cu")
		(net "M_E_CPU0_SB_DQ<11>")
	)
	(segment
		(start 286.900874 -293.800276)
		(end 286.05099 -292.950392)
		(width 0.14478)
		(layer "In6.Cu")
		(net "M_E_CPU0_SB_DQ<11>")
	)
	(segment
		(start 293.41699 -292.950392)
		(end 290.555426 -292.950392)
		(width 0.14478)
		(layer "In6.Cu")
		(net "M_E_CPU0_SB_DQ<11>")
	)
	(segment
		(start 309.274718 -290.289742)
		(end 309.274718 -291.357558)
		(width 0.14478)
		(layer "In6.Cu")
		(net "M_E_CPU0_SB_DQ<11>")
	)
	(segment
		(start 283.087826 -292.950392)
		(end 282.237942 -293.800276)
		(width 0.14478)
		(layer "In6.Cu")
		(net "M_E_CPU0_SB_DQ<11>")
	)
	(segment
		(start 300.557946 -292.950392)
		(end 297.82135 -292.950392)
		(width 0.14478)
		(layer "In6.Cu")
		(net "M_E_CPU0_SB_DQ<11>")
	)
	(segment
		(start 324.100444 -280.20772)
		(end 323.908674 -280.20772)
		(width 0.0889)
		(layer "In6.Cu")
		(net "M_E_CPU0_SB_DQ<11>")
	)
	(segment
		(start 328.718164 -280.243534)
		(end 328.709782 -280.238708)
		(width 0.0889)
		(layer "In6.Cu")
		(net "M_E_CPU0_SB_DQ<11>")
	)
	(segment
		(start 301.017178 -293.409624)
		(end 300.557946 -292.950392)
		(width 0.14478)
		(layer "In6.Cu")
		(net "M_E_CPU0_SB_DQ<11>")
	)
	(segment
		(start 327.474072 -280.12771)
		(end 324.180454 -280.12771)
		(width 0.0889)
		(layer "In6.Cu")
		(net "M_E_CPU0_SB_DQ<11>")
	)
	(arc
		(start 328.709782 -280.238708)
		(mid 328.526274 -280.193214)
		(end 328.344022 -280.243534)
		(width 0.0889)
		(layer "In6.Cu")
		(net "M_E_CPU0_SB_DQ<11>")
	)
	(arc
		(start 330.542646 -280.217372)
		(mid 330.380457 -280.194637)
		(end 330.22413 -280.243534)
		(width 0.0889)
		(layer "In6.Cu")
		(net "M_E_CPU0_SB_DQ<11>")
	)
	(arc
		(start 330.22413 -280.243534)
		(mid 329.941174 -280.319711)
		(end 329.658218 -280.243534)
		(width 0.0889)
		(layer "In6.Cu")
		(net "M_E_CPU0_SB_DQ<11>")
	)
	(arc
		(start 329.284076 -280.243534)
		(mid 329.00112 -280.319711)
		(end 328.718164 -280.243534)
		(width 0.0889)
		(layer "In6.Cu")
		(net "M_E_CPU0_SB_DQ<11>")
	)
	(arc
		(start 327.561956 -280.142696)
		(mid 327.51866 -280.131423)
		(end 327.474072 -280.12771)
		(width 0.0889)
		(layer "In6.Cu")
		(net "M_E_CPU0_SB_DQ<11>")
	)
	(arc
		(start 328.344022 -280.243534)
		(mid 328.061066 -280.319711)
		(end 327.77811 -280.243534)
		(width 0.0889)
		(layer "In6.Cu")
		(net "M_E_CPU0_SB_DQ<11>")
	)
	(arc
		(start 329.658218 -280.243534)
		(mid 329.475967 -280.193184)
		(end 329.292458 -280.238708)
		(width 0.0889)
		(layer "In6.Cu")
		(net "M_E_CPU0_SB_DQ<11>")
	)
	(arc
		(start 327.77811 -280.243534)
		(mid 327.672338 -280.188172)
		(end 327.561956 -280.142696)
		(width 0.0889)
		(layer "In6.Cu")
		(net "M_E_CPU0_SB_DQ<11>")
	)
	(segment
		(start 329.467972 -279.49017)
		(end 329.00112 -279.756108)
		(width 0.10668)
		(layer "F.Cu")
		(net "M_E_CPU0_SB_DQ<10>")
	)
	(segment
		(start 327.874122 -279.433528)
		(end 327.863708 -279.439624)
		(width 0.0889)
		(layer "In6.Cu")
		(net "M_E_CPU0_SB_DQ<10>")
	)
	(segment
		(start 300.587918 -291.260022)
		(end 298.22521 -291.260022)
		(width 0.14478)
		(layer "In6.Cu")
		(net "M_E_CPU0_SB_DQ<10>")
	)
	(segment
		(start 325.954898 -279.04694)
		(end 324.570344 -279.04694)
		(width 0.0889)
		(layer "In6.Cu")
		(net "M_E_CPU0_SB_DQ<10>")
	)
	(segment
		(start 282.582112 -292.11016)
		(end 274.781772 -292.11016)
		(width 0.14478)
		(layer "In6.Cu")
		(net "M_E_CPU0_SB_DQ<10>")
	)
	(segment
		(start 318.994028 -279.2984)
		(end 308.375558 -289.91687)
		(width 0.14478)
		(layer "In6.Cu")
		(net "M_E_CPU0_SB_DQ<10>")
	)
	(segment
		(start 274.618958 -291.454332)
		(end 274.474178 -291.309552)
		(width 0.14478)
		(layer "In6.Cu")
		(net "M_E_CPU0_SB_DQ<10>")
	)
	(segment
		(start 329.155044 -279.490678)
		(end 329.132692 -279.407366)
		(width 0.0889)
		(layer "In6.Cu")
		(net "M_E_CPU0_SB_DQ<10>")
	)
	(segment
		(start 298.22521 -291.260022)
		(end 297.375072 -292.11016)
		(width 0.14478)
		(layer "In6.Cu")
		(net "M_E_CPU0_SB_DQ<10>")
	)
	(segment
		(start 308.105048 -291.254942)
		(end 305.74869 -291.254942)
		(width 0.14478)
		(layer "In6.Cu")
		(net "M_E_CPU0_SB_DQ<10>")
	)
	(segment
		(start 286.887412 -292.11016)
		(end 286.037274 -291.260022)
		(width 0.14478)
		(layer "In6.Cu")
		(net "M_E_CPU0_SB_DQ<10>")
	)
	(segment
		(start 274.474178 -291.309552)
		(end 274.207478 -291.309552)
		(width 0.14478)
		(layer "In6.Cu")
		(net "M_E_CPU0_SB_DQ<10>")
	)
	(segment
		(start 274.062698 -291.454332)
		(end 274.062698 -291.947346)
		(width 0.14478)
		(layer "In6.Cu")
		(net "M_E_CPU0_SB_DQ<10>")
	)
	(segment
		(start 324.570344 -279.04694)
		(end 324.318884 -279.2984)
		(width 0.0889)
		(layer "In6.Cu")
		(net "M_E_CPU0_SB_DQ<10>")
	)
	(segment
		(start 327.882504 -279.428702)
		(end 327.874122 -279.433528)
		(width 0.0889)
		(layer "In6.Cu")
		(net "M_E_CPU0_SB_DQ<10>")
	)
	(segment
		(start 283.43225 -291.260022)
		(end 282.582112 -292.11016)
		(width 0.14478)
		(layer "In6.Cu")
		(net "M_E_CPU0_SB_DQ<10>")
	)
	(segment
		(start 274.207478 -291.309552)
		(end 274.062698 -291.454332)
		(width 0.14478)
		(layer "In6.Cu")
		(net "M_E_CPU0_SB_DQ<10>")
	)
	(segment
		(start 293.276274 -291.260022)
		(end 290.823142 -291.260022)
		(width 0.14478)
		(layer "In6.Cu")
		(net "M_E_CPU0_SB_DQ<10>")
	)
	(segment
		(start 274.618958 -291.947346)
		(end 274.618958 -291.454332)
		(width 0.14478)
		(layer "In6.Cu")
		(net "M_E_CPU0_SB_DQ<10>")
	)
	(segment
		(start 304.893472 -292.11016)
		(end 301.438056 -292.11016)
		(width 0.14478)
		(layer "In6.Cu")
		(net "M_E_CPU0_SB_DQ<10>")
	)
	(segment
		(start 308.375558 -289.91687)
		(end 308.375558 -290.984432)
		(width 0.14478)
		(layer "In6.Cu")
		(net "M_E_CPU0_SB_DQ<10>")
	)
	(segment
		(start 327.308464 -279.433528)
		(end 327.300082 -279.428702)
		(width 0.0889)
		(layer "In6.Cu")
		(net "M_E_CPU0_SB_DQ<10>")
	)
	(segment
		(start 301.438056 -292.11016)
		(end 300.587918 -291.260022)
		(width 0.14478)
		(layer "In6.Cu")
		(net "M_E_CPU0_SB_DQ<10>")
	)
	(segment
		(start 326.383142 -279.442164)
		(end 326.36841 -279.433528)
		(width 0.0889)
		(layer "In6.Cu")
		(net "M_E_CPU0_SB_DQ<10>")
	)
	(segment
		(start 290.823142 -291.260022)
		(end 289.973004 -292.11016)
		(width 0.14478)
		(layer "In6.Cu")
		(net "M_E_CPU0_SB_DQ<10>")
	)
	(segment
		(start 286.037274 -291.260022)
		(end 283.43225 -291.260022)
		(width 0.14478)
		(layer "In6.Cu")
		(net "M_E_CPU0_SB_DQ<10>")
	)
	(segment
		(start 273.899884 -292.11016)
		(end 273.51736 -292.11016)
		(width 0.14478)
		(layer "In6.Cu")
		(net "M_E_CPU0_SB_DQ<10>")
	)
	(segment
		(start 273.51736 -292.11016)
		(end 273.092164 -291.684964)
		(width 0.14478)
		(layer "In6.Cu")
		(net "M_E_CPU0_SB_DQ<10>")
	)
	(segment
		(start 289.973004 -292.11016)
		(end 286.887412 -292.11016)
		(width 0.14478)
		(layer "In6.Cu")
		(net "M_E_CPU0_SB_DQ<10>")
	)
	(segment
		(start 274.062698 -291.947346)
		(end 273.899884 -292.11016)
		(width 0.14478)
		(layer "In6.Cu")
		(net "M_E_CPU0_SB_DQ<10>")
	)
	(segment
		(start 308.375558 -290.984432)
		(end 308.105048 -291.254942)
		(width 0.14478)
		(layer "In6.Cu")
		(net "M_E_CPU0_SB_DQ<10>")
	)
	(segment
		(start 274.781772 -292.11016)
		(end 274.618958 -291.947346)
		(width 0.14478)
		(layer "In6.Cu")
		(net "M_E_CPU0_SB_DQ<10>")
	)
	(segment
		(start 305.74869 -291.254942)
		(end 304.893472 -292.11016)
		(width 0.14478)
		(layer "In6.Cu")
		(net "M_E_CPU0_SB_DQ<10>")
	)
	(segment
		(start 294.126412 -292.11016)
		(end 293.276274 -291.260022)
		(width 0.14478)
		(layer "In6.Cu")
		(net "M_E_CPU0_SB_DQ<10>")
	)
	(segment
		(start 297.375072 -292.11016)
		(end 294.126412 -292.11016)
		(width 0.14478)
		(layer "In6.Cu")
		(net "M_E_CPU0_SB_DQ<10>")
	)
	(segment
		(start 324.318884 -279.2984)
		(end 318.994028 -279.2984)
		(width 0.14478)
		(layer "In6.Cu")
		(net "M_E_CPU0_SB_DQ<10>")
	)
	(segment
		(start 326.252586 -279.344628)
		(end 325.954898 -279.04694)
		(width 0.0889)
		(layer "In6.Cu")
		(net "M_E_CPU0_SB_DQ<10>")
	)
	(segment
		(start 329.00112 -279.756108)
		(end 329.155044 -279.490678)
		(width 0.0889)
		(layer "In6.Cu")
		(net "M_E_CPU0_SB_DQ<10>")
	)
	(arc
		(start 327.300082 -279.428702)
		(mid 327.116574 -279.383208)
		(end 326.934322 -279.433528)
		(width 0.0889)
		(layer "In6.Cu")
		(net "M_E_CPU0_SB_DQ<10>")
	)
	(arc
		(start 329.132692 -279.407366)
		(mid 328.970503 -279.384631)
		(end 328.814176 -279.433528)
		(width 0.0889)
		(layer "In6.Cu")
		(net "M_E_CPU0_SB_DQ<10>")
	)
	(arc
		(start 326.934322 -279.433528)
		(mid 326.65987 -279.509764)
		(end 326.383142 -279.442164)
		(width 0.0889)
		(layer "In6.Cu")
		(net "M_E_CPU0_SB_DQ<10>")
	)
	(arc
		(start 327.863708 -279.439624)
		(mid 327.585276 -279.509722)
		(end 327.308464 -279.433528)
		(width 0.0889)
		(layer "In6.Cu")
		(net "M_E_CPU0_SB_DQ<10>")
	)
	(arc
		(start 326.36841 -279.433528)
		(mid 326.3076 -279.392853)
		(end 326.252586 -279.344628)
		(width 0.0889)
		(layer "In6.Cu")
		(net "M_E_CPU0_SB_DQ<10>")
	)
	(arc
		(start 328.814176 -279.433528)
		(mid 328.53122 -279.509705)
		(end 328.248264 -279.433528)
		(width 0.0889)
		(layer "In6.Cu")
		(net "M_E_CPU0_SB_DQ<10>")
	)
	(arc
		(start 328.248264 -279.433528)
		(mid 328.066013 -279.383178)
		(end 327.882504 -279.428702)
		(width 0.0889)
		(layer "In6.Cu")
		(net "M_E_CPU0_SB_DQ<10>")
	)
	(segment
		(start 329.937872 -273.820128)
		(end 329.47102 -274.086066)
		(width 0.10668)
		(layer "F.Cu")
		(net "M_E_CPU0_SB_DQ<0>")
	)
	(segment
		(start 303.688242 -282.21051)
		(end 303.38776 -281.910028)
		(width 0.14478)
		(layer "In6.Cu")
		(net "M_E_CPU0_SB_DQ<0>")
	)
	(segment
		(start 302.27524 -281.910028)
		(end 301.654972 -281.910028)
		(width 0.14478)
		(layer "In6.Cu")
		(net "M_E_CPU0_SB_DQ<0>")
	)
	(segment
		(start 310.705246 -277.174452)
		(end 310.53913 -277.008336)
		(width 0.14478)
		(layer "In6.Cu")
		(net "M_E_CPU0_SB_DQ<0>")
	)
	(segment
		(start 290.242244 -281.910028)
		(end 289.366452 -281.910028)
		(width 0.14478)
		(layer "In6.Cu")
		(net "M_E_CPU0_SB_DQ<0>")
	)
	(segment
		(start 287.544256 -282.18511)
		(end 287.263078 -282.18511)
		(width 0.14478)
		(layer "In6.Cu")
		(net "M_E_CPU0_SB_DQ<0>")
	)
	(segment
		(start 305.809142 -281.82443)
		(end 305.449478 -281.466544)
		(width 0.14478)
		(layer "In6.Cu")
		(net "M_E_CPU0_SB_DQ<0>")
	)
	(segment
		(start 303.38776 -281.910028)
		(end 303.131982 -281.910028)
		(width 0.14478)
		(layer "In6.Cu")
		(net "M_E_CPU0_SB_DQ<0>")
	)
	(segment
		(start 324.890384 -273.44751)
		(end 324.663054 -273.22018)
		(width 0.0889)
		(layer "In6.Cu")
		(net "M_E_CPU0_SB_DQ<0>")
	)
	(segment
		(start 303.131982 -281.910028)
		(end 302.8315 -282.21051)
		(width 0.14478)
		(layer "In6.Cu")
		(net "M_E_CPU0_SB_DQ<0>")
	)
	(segment
		(start 310.90997 -277.174452)
		(end 310.705246 -277.174452)
		(width 0.14478)
		(layer "In6.Cu")
		(net "M_E_CPU0_SB_DQ<0>")
	)
	(segment
		(start 310.14035 -277.202646)
		(end 310.14035 -277.40737)
		(width 0.14478)
		(layer "In6.Cu")
		(net "M_E_CPU0_SB_DQ<0>")
	)
	(segment
		(start 297.420792 -281.910028)
		(end 297.001184 -281.910028)
		(width 0.14478)
		(layer "In6.Cu")
		(net "M_E_CPU0_SB_DQ<0>")
	)
	(segment
		(start 307.378862 -281.37231)
		(end 306.571904 -280.565352)
		(width 0.14478)
		(layer "In6.Cu")
		(net "M_E_CPU0_SB_DQ<0>")
	)
	(segment
		(start 282.266644 -281.910028)
		(end 281.74188 -281.910028)
		(width 0.14478)
		(layer "In6.Cu")
		(net "M_E_CPU0_SB_DQ<0>")
	)
	(segment
		(start 326.38746 -274.349718)
		(end 326.387206 -274.349718)
		(width 0.0889)
		(layer "In6.Cu")
		(net "M_E_CPU0_SB_DQ<0>")
	)
	(segment
		(start 328.718164 -274.408646)
		(end 328.709782 -274.413472)
		(width 0.0889)
		(layer "In6.Cu")
		(net "M_E_CPU0_SB_DQ<0>")
	)
	(segment
		(start 305.847242 -281.06624)
		(end 306.206906 -281.424126)
		(width 0.14478)
		(layer "In6.Cu")
		(net "M_E_CPU0_SB_DQ<0>")
	)
	(segment
		(start 298.931838 -281.34691)
		(end 298.644818 -281.05989)
		(width 0.14478)
		(layer "In6.Cu")
		(net "M_E_CPU0_SB_DQ<0>")
	)
	(segment
		(start 288.810192 -282.21051)
		(end 288.50971 -281.910028)
		(width 0.14478)
		(layer "In6.Cu")
		(net "M_E_CPU0_SB_DQ<0>")
	)
	(segment
		(start 285.590234 -281.05989)
		(end 284.271466 -281.05989)
		(width 0.14478)
		(layer "In6.Cu")
		(net "M_E_CPU0_SB_DQ<0>")
	)
	(segment
		(start 279.175972 -281.924252)
		(end 278.79675 -281.924252)
		(width 0.14478)
		(layer "In6.Cu")
		(net "M_E_CPU0_SB_DQ<0>")
	)
	(segment
		(start 286.987996 -281.910028)
		(end 286.440372 -281.910028)
		(width 0.14478)
		(layer "In6.Cu")
		(net "M_E_CPU0_SB_DQ<0>")
	)
	(segment
		(start 312.167778 -275.916644)
		(end 310.90997 -277.174452)
		(width 0.14478)
		(layer "In6.Cu")
		(net "M_E_CPU0_SB_DQ<0>")
	)
	(segment
		(start 308.237128 -280.863548)
		(end 307.728366 -281.37231)
		(width 0.14478)
		(layer "In6.Cu")
		(net "M_E_CPU0_SB_DQ<0>")
	)
	(segment
		(start 305.84648 -280.86177)
		(end 305.847242 -281.06624)
		(width 0.14478)
		(layer "In6.Cu")
		(net "M_E_CPU0_SB_DQ<0>")
	)
	(segment
		(start 306.206906 -281.424126)
		(end 306.207668 -281.62885)
		(width 0.14478)
		(layer "In6.Cu")
		(net "M_E_CPU0_SB_DQ<0>")
	)
	(segment
		(start 310.306466 -277.573486)
		(end 310.30672 -277.777702)
		(width 0.14478)
		(layer "In6.Cu")
		(net "M_E_CPU0_SB_DQ<0>")
	)
	(segment
		(start 284.271466 -281.05989)
		(end 283.959046 -281.37231)
		(width 0.14478)
		(layer "In6.Cu")
		(net "M_E_CPU0_SB_DQ<0>")
	)
	(segment
		(start 280.284682 -281.910028)
		(end 279.9842 -282.21051)
		(width 0.14478)
		(layer "In6.Cu")
		(net "M_E_CPU0_SB_DQ<0>")
	)
	(segment
		(start 286.440372 -281.910028)
		(end 285.590234 -281.05989)
		(width 0.14478)
		(layer "In6.Cu")
		(net "M_E_CPU0_SB_DQ<0>")
	)
	(segment
		(start 329.47102 -274.086066)
		(end 329.317096 -274.351496)
		(width 0.0889)
		(layer "In6.Cu")
		(net "M_E_CPU0_SB_DQ<0>")
	)
	(segment
		(start 297.001184 -281.910028)
		(end 296.700702 -282.21051)
		(width 0.14478)
		(layer "In6.Cu")
		(net "M_E_CPU0_SB_DQ<0>")
	)
	(segment
		(start 314.122816 -273.22018)
		(end 312.692288 -274.650708)
		(width 0.14478)
		(layer "In6.Cu")
		(net "M_E_CPU0_SB_DQ<0>")
	)
	(segment
		(start 294.310054 -282.21051)
		(end 293.159434 -281.05989)
		(width 0.14478)
		(layer "In6.Cu")
		(net "M_E_CPU0_SB_DQ<0>")
	)
	(segment
		(start 293.159434 -281.05989)
		(end 291.092382 -281.05989)
		(width 0.14478)
		(layer "In6.Cu")
		(net "M_E_CPU0_SB_DQ<0>")
	)
	(segment
		(start 309.74157 -277.805896)
		(end 309.536846 -277.80615)
		(width 0.14478)
		(layer "In6.Cu")
		(net "M_E_CPU0_SB_DQ<0>")
	)
	(segment
		(start 324.663054 -273.22018)
		(end 323.927724 -273.22018)
		(width 0.0889)
		(layer "In6.Cu")
		(net "M_E_CPU0_SB_DQ<0>")
	)
	(segment
		(start 298.644818 -281.05989)
		(end 298.27093 -281.05989)
		(width 0.14478)
		(layer "In6.Cu")
		(net "M_E_CPU0_SB_DQ<0>")
	)
	(segment
		(start 304.244502 -281.910028)
		(end 303.94402 -282.21051)
		(width 0.14478)
		(layer "In6.Cu")
		(net "M_E_CPU0_SB_DQ<0>")
	)
	(segment
		(start 310.30672 -277.777702)
		(end 310.11241 -277.972012)
		(width 0.14478)
		(layer "In6.Cu")
		(net "M_E_CPU0_SB_DQ<0>")
	)
	(segment
		(start 304.804064 -281.910028)
		(end 304.244502 -281.910028)
		(width 0.14478)
		(layer "In6.Cu")
		(net "M_E_CPU0_SB_DQ<0>")
	)
	(segment
		(start 298.27093 -281.05989)
		(end 297.420792 -281.910028)
		(width 0.14478)
		(layer "In6.Cu")
		(net "M_E_CPU0_SB_DQ<0>")
	)
	(segment
		(start 291.092382 -281.05989)
		(end 290.242244 -281.910028)
		(width 0.14478)
		(layer "In6.Cu")
		(net "M_E_CPU0_SB_DQ<0>")
	)
	(segment
		(start 329.317096 -274.351496)
		(end 329.221084 -274.376896)
		(width 0.0889)
		(layer "In6.Cu")
		(net "M_E_CPU0_SB_DQ<0>")
	)
	(segment
		(start 302.575722 -282.21051)
		(end 302.27524 -281.910028)
		(width 0.14478)
		(layer "In6.Cu")
		(net "M_E_CPU0_SB_DQ<0>")
	)
	(segment
		(start 281.441398 -282.21051)
		(end 281.18562 -282.21051)
		(width 0.14478)
		(layer "In6.Cu")
		(net "M_E_CPU0_SB_DQ<0>")
	)
	(segment
		(start 281.18562 -282.21051)
		(end 280.885138 -281.910028)
		(width 0.14478)
		(layer "In6.Cu")
		(net "M_E_CPU0_SB_DQ<0>")
	)
	(segment
		(start 283.959046 -281.37231)
		(end 283.715206 -281.37231)
		(width 0.14478)
		(layer "In6.Cu")
		(net "M_E_CPU0_SB_DQ<0>")
	)
	(segment
		(start 299.201078 -281.34691)
		(end 298.931838 -281.34691)
		(width 0.14478)
		(layer "In6.Cu")
		(net "M_E_CPU0_SB_DQ<0>")
	)
	(segment
		(start 309.221378 -278.121618)
		(end 309.221378 -279.21585)
		(width 0.14478)
		(layer "In6.Cu")
		(net "M_E_CPU0_SB_DQ<0>")
	)
	(segment
		(start 307.728366 -281.37231)
		(end 307.378862 -281.37231)
		(width 0.14478)
		(layer "In6.Cu")
		(net "M_E_CPU0_SB_DQ<0>")
	)
	(segment
		(start 288.50971 -281.910028)
		(end 287.819338 -281.910028)
		(width 0.14478)
		(layer "In6.Cu")
		(net "M_E_CPU0_SB_DQ<0>")
	)
	(segment
		(start 281.74188 -281.910028)
		(end 281.441398 -282.21051)
		(width 0.14478)
		(layer "In6.Cu")
		(net "M_E_CPU0_SB_DQ<0>")
	)
	(segment
		(start 295.0845 -281.910028)
		(end 294.784018 -282.21051)
		(width 0.14478)
		(layer "In6.Cu")
		(net "M_E_CPU0_SB_DQ<0>")
	)
	(segment
		(start 323.927724 -273.22018)
		(end 314.122816 -273.22018)
		(width 0.14478)
		(layer "In6.Cu")
		(net "M_E_CPU0_SB_DQ<0>")
	)
	(segment
		(start 300.804834 -281.05989)
		(end 299.488098 -281.05989)
		(width 0.14478)
		(layer "In6.Cu")
		(net "M_E_CPU0_SB_DQ<0>")
	)
	(segment
		(start 305.245008 -281.467052)
		(end 304.804064 -281.910028)
		(width 0.14478)
		(layer "In6.Cu")
		(net "M_E_CPU0_SB_DQ<0>")
	)
	(segment
		(start 326.387206 -274.349718)
		(end 325.484998 -273.44751)
		(width 0.0889)
		(layer "In6.Cu")
		(net "M_E_CPU0_SB_DQ<0>")
	)
	(segment
		(start 296.144442 -281.910028)
		(end 295.0845 -281.910028)
		(width 0.14478)
		(layer "In6.Cu")
		(net "M_E_CPU0_SB_DQ<0>")
	)
	(segment
		(start 302.8315 -282.21051)
		(end 302.575722 -282.21051)
		(width 0.14478)
		(layer "In6.Cu")
		(net "M_E_CPU0_SB_DQ<0>")
	)
	(segment
		(start 326.476106 -274.415504)
		(end 326.464422 -274.408646)
		(width 0.0889)
		(layer "In6.Cu")
		(net "M_E_CPU0_SB_DQ<0>")
	)
	(segment
		(start 306.571904 -280.565352)
		(end 306.141374 -280.565352)
		(width 0.14478)
		(layer "In6.Cu")
		(net "M_E_CPU0_SB_DQ<0>")
	)
	(segment
		(start 296.700702 -282.21051)
		(end 296.444924 -282.21051)
		(width 0.14478)
		(layer "In6.Cu")
		(net "M_E_CPU0_SB_DQ<0>")
	)
	(segment
		(start 306.141374 -280.565352)
		(end 305.84648 -280.86177)
		(width 0.14478)
		(layer "In6.Cu")
		(net "M_E_CPU0_SB_DQ<0>")
	)
	(segment
		(start 327.788778 -274.40255)
		(end 327.778364 -274.408646)
		(width 0.0889)
		(layer "In6.Cu")
		(net "M_E_CPU0_SB_DQ<0>")
	)
	(segment
		(start 312.692288 -274.650708)
		(end 312.167778 -275.916644)
		(width 0.14478)
		(layer "In6.Cu")
		(net "M_E_CPU0_SB_DQ<0>")
	)
	(segment
		(start 287.819338 -281.910028)
		(end 287.544256 -282.18511)
		(width 0.14478)
		(layer "In6.Cu")
		(net "M_E_CPU0_SB_DQ<0>")
	)
	(segment
		(start 289.366452 -281.910028)
		(end 289.06597 -282.21051)
		(width 0.14478)
		(layer "In6.Cu")
		(net "M_E_CPU0_SB_DQ<0>")
	)
	(segment
		(start 279.46223 -282.21051)
		(end 279.175972 -281.924252)
		(width 0.14478)
		(layer "In6.Cu")
		(net "M_E_CPU0_SB_DQ<0>")
	)
	(segment
		(start 327.404476 -274.408646)
		(end 327.394062 -274.40255)
		(width 0.0889)
		(layer "In6.Cu")
		(net "M_E_CPU0_SB_DQ<0>")
	)
	(segment
		(start 309.536846 -277.80615)
		(end 309.221378 -278.121618)
		(width 0.14478)
		(layer "In6.Cu")
		(net "M_E_CPU0_SB_DQ<0>")
	)
	(segment
		(start 325.484998 -273.44751)
		(end 324.890384 -273.44751)
		(width 0.0889)
		(layer "In6.Cu")
		(net "M_E_CPU0_SB_DQ<0>")
	)
	(segment
		(start 278.79675 -281.924252)
		(end 278.510492 -282.21051)
		(width 0.14478)
		(layer "In6.Cu")
		(net "M_E_CPU0_SB_DQ<0>")
	)
	(segment
		(start 277.917656 -282.21051)
		(end 277.192232 -281.485086)
		(width 0.14478)
		(layer "In6.Cu")
		(net "M_E_CPU0_SB_DQ<0>")
	)
	(segment
		(start 301.654972 -281.910028)
		(end 300.804834 -281.05989)
		(width 0.14478)
		(layer "In6.Cu")
		(net "M_E_CPU0_SB_DQ<0>")
	)
	(segment
		(start 310.11241 -277.972012)
		(end 309.907686 -277.972012)
		(width 0.14478)
		(layer "In6.Cu")
		(net "M_E_CPU0_SB_DQ<0>")
	)
	(segment
		(start 310.334406 -277.00859)
		(end 310.14035 -277.202646)
		(width 0.14478)
		(layer "In6.Cu")
		(net "M_E_CPU0_SB_DQ<0>")
	)
	(segment
		(start 305.449478 -281.466544)
		(end 305.245008 -281.467052)
		(width 0.14478)
		(layer "In6.Cu")
		(net "M_E_CPU0_SB_DQ<0>")
	)
	(segment
		(start 303.94402 -282.21051)
		(end 303.688242 -282.21051)
		(width 0.14478)
		(layer "In6.Cu")
		(net "M_E_CPU0_SB_DQ<0>")
	)
	(segment
		(start 283.116782 -281.05989)
		(end 282.266644 -281.910028)
		(width 0.14478)
		(layer "In6.Cu")
		(net "M_E_CPU0_SB_DQ<0>")
	)
	(segment
		(start 278.510492 -282.21051)
		(end 277.917656 -282.21051)
		(width 0.14478)
		(layer "In6.Cu")
		(net "M_E_CPU0_SB_DQ<0>")
	)
	(segment
		(start 306.013866 -281.823668)
		(end 305.809142 -281.82443)
		(width 0.14478)
		(layer "In6.Cu")
		(net "M_E_CPU0_SB_DQ<0>")
	)
	(segment
		(start 296.444924 -282.21051)
		(end 296.144442 -281.910028)
		(width 0.14478)
		(layer "In6.Cu")
		(net "M_E_CPU0_SB_DQ<0>")
	)
	(segment
		(start 309.221378 -279.21585)
		(end 308.237128 -280.2001)
		(width 0.14478)
		(layer "In6.Cu")
		(net "M_E_CPU0_SB_DQ<0>")
	)
	(segment
		(start 309.907686 -277.972012)
		(end 309.74157 -277.805896)
		(width 0.14478)
		(layer "In6.Cu")
		(net "M_E_CPU0_SB_DQ<0>")
	)
	(segment
		(start 289.06597 -282.21051)
		(end 288.810192 -282.21051)
		(width 0.14478)
		(layer "In6.Cu")
		(net "M_E_CPU0_SB_DQ<0>")
	)
	(segment
		(start 306.207668 -281.62885)
		(end 306.013866 -281.823668)
		(width 0.14478)
		(layer "In6.Cu")
		(net "M_E_CPU0_SB_DQ<0>")
	)
	(segment
		(start 308.237128 -280.2001)
		(end 308.237128 -280.863548)
		(width 0.14478)
		(layer "In6.Cu")
		(net "M_E_CPU0_SB_DQ<0>")
	)
	(segment
		(start 299.488098 -281.05989)
		(end 299.201078 -281.34691)
		(width 0.14478)
		(layer "In6.Cu")
		(net "M_E_CPU0_SB_DQ<0>")
	)
	(segment
		(start 310.53913 -277.008336)
		(end 310.334406 -277.00859)
		(width 0.14478)
		(layer "In6.Cu")
		(net "M_E_CPU0_SB_DQ<0>")
	)
	(segment
		(start 283.402786 -281.05989)
		(end 283.116782 -281.05989)
		(width 0.14478)
		(layer "In6.Cu")
		(net "M_E_CPU0_SB_DQ<0>")
	)
	(segment
		(start 287.263078 -282.18511)
		(end 286.987996 -281.910028)
		(width 0.14478)
		(layer "In6.Cu")
		(net "M_E_CPU0_SB_DQ<0>")
	)
	(segment
		(start 294.784018 -282.21051)
		(end 294.310054 -282.21051)
		(width 0.14478)
		(layer "In6.Cu")
		(net "M_E_CPU0_SB_DQ<0>")
	)
	(segment
		(start 310.14035 -277.40737)
		(end 310.306466 -277.573486)
		(width 0.14478)
		(layer "In6.Cu")
		(net "M_E_CPU0_SB_DQ<0>")
	)
	(segment
		(start 283.715206 -281.37231)
		(end 283.402786 -281.05989)
		(width 0.14478)
		(layer "In6.Cu")
		(net "M_E_CPU0_SB_DQ<0>")
	)
	(segment
		(start 280.885138 -281.910028)
		(end 280.284682 -281.910028)
		(width 0.14478)
		(layer "In6.Cu")
		(net "M_E_CPU0_SB_DQ<0>")
	)
	(segment
		(start 279.9842 -282.21051)
		(end 279.46223 -282.21051)
		(width 0.14478)
		(layer "In6.Cu")
		(net "M_E_CPU0_SB_DQ<0>")
	)
	(arc
		(start 327.394062 -274.40255)
		(mid 327.115376 -274.33233)
		(end 326.83831 -274.408646)
		(width 0.0889)
		(layer "In6.Cu")
		(net "M_E_CPU0_SB_DQ<0>")
	)
	(arc
		(start 328.709782 -274.413472)
		(mid 328.526274 -274.458966)
		(end 328.344022 -274.408646)
		(width 0.0889)
		(layer "In6.Cu")
		(net "M_E_CPU0_SB_DQ<0>")
	)
	(arc
		(start 327.778364 -274.408646)
		(mid 327.59142 -274.458901)
		(end 327.404476 -274.408646)
		(width 0.0889)
		(layer "In6.Cu")
		(net "M_E_CPU0_SB_DQ<0>")
	)
	(arc
		(start 329.221084 -274.376896)
		(mid 328.965876 -274.333419)
		(end 328.718164 -274.408646)
		(width 0.0889)
		(layer "In6.Cu")
		(net "M_E_CPU0_SB_DQ<0>")
	)
	(arc
		(start 326.83831 -274.408646)
		(mid 326.658105 -274.458963)
		(end 326.476106 -274.415504)
		(width 0.0889)
		(layer "In6.Cu")
		(net "M_E_CPU0_SB_DQ<0>")
	)
	(arc
		(start 328.344022 -274.408646)
		(mid 328.067209 -274.332503)
		(end 327.788778 -274.40255)
		(width 0.0889)
		(layer "In6.Cu")
		(net "M_E_CPU0_SB_DQ<0>")
	)
	(arc
		(start 326.464422 -274.408646)
		(mid 326.424019 -274.381692)
		(end 326.38746 -274.349718)
		(width 0.0889)
		(layer "In6.Cu")
		(net "M_E_CPU0_SB_DQ<0>")
	)
	(segment
		(start 329.467972 -266.530074)
		(end 329.00112 -266.796012)
		(width 0.10668)
		(layer "F.Cu")
		(net "M_E_CPU0_SB_CS_N<1>")
	)
	(segment
		(start 309.919116 -265.98372)
		(end 307.59273 -268.310106)
		(width 0.14478)
		(layer "In6.Cu")
		(net "M_E_CPU0_SB_CS_N<1>")
	)
	(segment
		(start 323.897244 -265.98372)
		(end 309.919116 -265.98372)
		(width 0.14478)
		(layer "In6.Cu")
		(net "M_E_CPU0_SB_CS_N<1>")
	)
	(segment
		(start 273.517106 -268.310106)
		(end 273.092164 -268.735048)
		(width 0.14478)
		(layer "In6.Cu")
		(net "M_E_CPU0_SB_CS_N<1>")
	)
	(segment
		(start 329.155044 -266.530582)
		(end 329.132692 -266.44727)
		(width 0.0889)
		(layer "In6.Cu")
		(net "M_E_CPU0_SB_CS_N<1>")
	)
	(segment
		(start 327.971912 -266.433808)
		(end 326.285098 -266.433808)
		(width 0.0889)
		(layer "In6.Cu")
		(net "M_E_CPU0_SB_CS_N<1>")
	)
	(segment
		(start 325.83501 -265.98372)
		(end 323.897244 -265.98372)
		(width 0.0889)
		(layer "In6.Cu")
		(net "M_E_CPU0_SB_CS_N<1>")
	)
	(segment
		(start 329.00112 -266.796012)
		(end 329.155044 -266.530582)
		(width 0.0889)
		(layer "In6.Cu")
		(net "M_E_CPU0_SB_CS_N<1>")
	)
	(segment
		(start 307.59273 -268.310106)
		(end 273.517106 -268.310106)
		(width 0.14478)
		(layer "In6.Cu")
		(net "M_E_CPU0_SB_CS_N<1>")
	)
	(segment
		(start 326.285098 -266.433808)
		(end 325.83501 -265.98372)
		(width 0.0889)
		(layer "In6.Cu")
		(net "M_E_CPU0_SB_CS_N<1>")
	)
	(arc
		(start 329.132692 -266.44727)
		(mid 328.970503 -266.424535)
		(end 328.814176 -266.473432)
		(width 0.0889)
		(layer "In6.Cu")
		(net "M_E_CPU0_SB_CS_N<1>")
	)
	(arc
		(start 328.248264 -266.473432)
		(mid 328.113936 -266.426816)
		(end 327.971912 -266.433808)
		(width 0.0889)
		(layer "In6.Cu")
		(net "M_E_CPU0_SB_CS_N<1>")
	)
	(arc
		(start 328.814176 -266.473432)
		(mid 328.53122 -266.549609)
		(end 328.248264 -266.473432)
		(width 0.0889)
		(layer "In6.Cu")
		(net "M_E_CPU0_SB_CS_N<1>")
	)
	(segment
		(start 330.877926 -265.720068)
		(end 330.411074 -265.986006)
		(width 0.10668)
		(layer "F.Cu")
		(net "M_E_CPU0_SB_CS_N<0>")
	)
	(segment
		(start 279.597866 -267.848334)
		(end 279.44191 -267.692378)
		(width 0.14478)
		(layer "In6.Cu")
		(net "M_E_CPU0_SB_CS_N<0>")
	)
	(segment
		(start 279.285954 -267.14831)
		(end 279.041606 -267.14831)
		(width 0.14478)
		(layer "In6.Cu")
		(net "M_E_CPU0_SB_CS_N<0>")
	)
	(segment
		(start 309.576216 -265.52906)
		(end 307.645054 -267.460222)
		(width 0.14478)
		(layer "In6.Cu")
		(net "M_E_CPU0_SB_CS_N<0>")
	)
	(segment
		(start 279.041606 -267.14831)
		(end 278.88565 -267.304266)
		(width 0.14478)
		(layer "In6.Cu")
		(net "M_E_CPU0_SB_CS_N<0>")
	)
	(segment
		(start 278.32939 -267.304266)
		(end 278.173434 -267.14831)
		(width 0.14478)
		(layer "In6.Cu")
		(net "M_E_CPU0_SB_CS_N<0>")
	)
	(segment
		(start 327.410572 -265.52906)
		(end 324.059804 -265.52906)
		(width 0.0889)
		(layer "In6.Cu")
		(net "M_E_CPU0_SB_CS_N<0>")
	)
	(segment
		(start 278.729694 -267.848334)
		(end 278.485346 -267.848334)
		(width 0.14478)
		(layer "In6.Cu")
		(net "M_E_CPU0_SB_CS_N<0>")
	)
	(segment
		(start 328.718164 -265.663426)
		(end 328.709782 -265.6586)
		(width 0.0889)
		(layer "In6.Cu")
		(net "M_E_CPU0_SB_CS_N<0>")
	)
	(segment
		(start 278.88565 -267.692378)
		(end 278.729694 -267.848334)
		(width 0.14478)
		(layer "In6.Cu")
		(net "M_E_CPU0_SB_CS_N<0>")
	)
	(segment
		(start 278.485346 -267.848334)
		(end 278.32939 -267.692378)
		(width 0.14478)
		(layer "In6.Cu")
		(net "M_E_CPU0_SB_CS_N<0>")
	)
	(segment
		(start 279.44191 -267.304266)
		(end 279.285954 -267.14831)
		(width 0.14478)
		(layer "In6.Cu")
		(net "M_E_CPU0_SB_CS_N<0>")
	)
	(segment
		(start 278.173434 -267.14831)
		(end 277.929086 -267.14831)
		(width 0.14478)
		(layer "In6.Cu")
		(net "M_E_CPU0_SB_CS_N<0>")
	)
	(segment
		(start 279.842214 -267.848334)
		(end 279.597866 -267.848334)
		(width 0.14478)
		(layer "In6.Cu")
		(net "M_E_CPU0_SB_CS_N<0>")
	)
	(segment
		(start 330.564998 -265.720576)
		(end 330.542646 -265.637264)
		(width 0.0889)
		(layer "In6.Cu")
		(net "M_E_CPU0_SB_CS_N<0>")
	)
	(segment
		(start 329.292458 -265.6586)
		(end 329.284076 -265.663426)
		(width 0.0889)
		(layer "In6.Cu")
		(net "M_E_CPU0_SB_CS_N<0>")
	)
	(segment
		(start 278.32939 -267.692378)
		(end 278.32939 -267.304266)
		(width 0.14478)
		(layer "In6.Cu")
		(net "M_E_CPU0_SB_CS_N<0>")
	)
	(segment
		(start 324.059804 -265.52906)
		(end 309.576216 -265.52906)
		(width 0.14478)
		(layer "In6.Cu")
		(net "M_E_CPU0_SB_CS_N<0>")
	)
	(segment
		(start 307.645054 -267.460222)
		(end 280.230326 -267.460222)
		(width 0.14478)
		(layer "In6.Cu")
		(net "M_E_CPU0_SB_CS_N<0>")
	)
	(segment
		(start 278.88565 -267.304266)
		(end 278.88565 -267.692378)
		(width 0.14478)
		(layer "In6.Cu")
		(net "M_E_CPU0_SB_CS_N<0>")
	)
	(segment
		(start 330.411074 -265.986006)
		(end 330.564998 -265.720576)
		(width 0.0889)
		(layer "In6.Cu")
		(net "M_E_CPU0_SB_CS_N<0>")
	)
	(segment
		(start 280.230326 -267.460222)
		(end 279.842214 -267.848334)
		(width 0.14478)
		(layer "In6.Cu")
		(net "M_E_CPU0_SB_CS_N<0>")
	)
	(segment
		(start 279.44191 -267.692378)
		(end 279.44191 -267.304266)
		(width 0.14478)
		(layer "In6.Cu")
		(net "M_E_CPU0_SB_CS_N<0>")
	)
	(segment
		(start 277.929086 -267.14831)
		(end 277.192232 -267.885164)
		(width 0.14478)
		(layer "In6.Cu")
		(net "M_E_CPU0_SB_CS_N<0>")
	)
	(arc
		(start 327.498964 -265.542014)
		(mid 327.455246 -265.532269)
		(end 327.410572 -265.52906)
		(width 0.0889)
		(layer "In6.Cu")
		(net "M_E_CPU0_SB_CS_N<0>")
	)
	(arc
		(start 330.22413 -265.663426)
		(mid 329.941174 -265.739603)
		(end 329.658218 -265.663426)
		(width 0.0889)
		(layer "In6.Cu")
		(net "M_E_CPU0_SB_CS_N<0>")
	)
	(arc
		(start 330.542646 -265.637264)
		(mid 330.380457 -265.614529)
		(end 330.22413 -265.663426)
		(width 0.0889)
		(layer "In6.Cu")
		(net "M_E_CPU0_SB_CS_N<0>")
	)
	(arc
		(start 329.284076 -265.663426)
		(mid 329.00112 -265.739603)
		(end 328.718164 -265.663426)
		(width 0.0889)
		(layer "In6.Cu")
		(net "M_E_CPU0_SB_CS_N<0>")
	)
	(arc
		(start 328.709782 -265.6586)
		(mid 328.526274 -265.613106)
		(end 328.344022 -265.663426)
		(width 0.0889)
		(layer "In6.Cu")
		(net "M_E_CPU0_SB_CS_N<0>")
	)
	(arc
		(start 327.77811 -265.663426)
		(mid 327.642082 -265.594569)
		(end 327.498964 -265.542014)
		(width 0.0889)
		(layer "In6.Cu")
		(net "M_E_CPU0_SB_CS_N<0>")
	)
	(arc
		(start 329.658218 -265.663426)
		(mid 329.475967 -265.613076)
		(end 329.292458 -265.6586)
		(width 0.0889)
		(layer "In6.Cu")
		(net "M_E_CPU0_SB_CS_N<0>")
	)
	(arc
		(start 328.344022 -265.663426)
		(mid 328.061066 -265.739603)
		(end 327.77811 -265.663426)
		(width 0.0889)
		(layer "In6.Cu")
		(net "M_E_CPU0_SB_CS_N<0>")
	)
	(segment
		(start 330.877926 -270.580104)
		(end 330.411074 -270.846042)
		(width 0.10668)
		(layer "F.Cu")
		(net "M_E_CPU0_SB_CB<7>")
	)
	(segment
		(start 276.08022 -273.659346)
		(end 275.917406 -273.496532)
		(width 0.14478)
		(layer "In6.Cu")
		(net "M_E_CPU0_SB_CB<7>")
	)
	(segment
		(start 274.248626 -274.260056)
		(end 273.517106 -274.260056)
		(width 0.14478)
		(layer "In6.Cu")
		(net "M_E_CPU0_SB_CB<7>")
	)
	(segment
		(start 307.778658 -273.410172)
		(end 282.841446 -273.410172)
		(width 0.14478)
		(layer "In6.Cu")
		(net "M_E_CPU0_SB_CB<7>")
	)
	(segment
		(start 328.718164 -270.523462)
		(end 328.709782 -270.518636)
		(width 0.0889)
		(layer "In6.Cu")
		(net "M_E_CPU0_SB_CB<7>")
	)
	(segment
		(start 324.282054 -269.10411)
		(end 324.138544 -268.9606)
		(width 0.0889)
		(layer "In6.Cu")
		(net "M_E_CPU0_SB_CB<7>")
	)
	(segment
		(start 275.52396 -273.659346)
		(end 275.52396 -274.097242)
		(width 0.14478)
		(layer "In6.Cu")
		(net "M_E_CPU0_SB_CB<7>")
	)
	(segment
		(start 274.41144 -273.254724)
		(end 274.41144 -274.097242)
		(width 0.14478)
		(layer "In6.Cu")
		(net "M_E_CPU0_SB_CB<7>")
	)
	(segment
		(start 274.574254 -273.09191)
		(end 274.41144 -273.254724)
		(width 0.14478)
		(layer "In6.Cu")
		(net "M_E_CPU0_SB_CB<7>")
	)
	(segment
		(start 330.564998 -270.580612)
		(end 330.542646 -270.4973)
		(width 0.0889)
		(layer "In6.Cu")
		(net "M_E_CPU0_SB_CB<7>")
	)
	(segment
		(start 282.841446 -273.410172)
		(end 281.991562 -274.260056)
		(width 0.14478)
		(layer "In6.Cu")
		(net "M_E_CPU0_SB_CB<7>")
	)
	(segment
		(start 274.9677 -273.254724)
		(end 274.804886 -273.09191)
		(width 0.14478)
		(layer "In6.Cu")
		(net "M_E_CPU0_SB_CB<7>")
	)
	(segment
		(start 330.411074 -270.846042)
		(end 330.564998 -270.580612)
		(width 0.0889)
		(layer "In6.Cu")
		(net "M_E_CPU0_SB_CB<7>")
	)
	(segment
		(start 329.292458 -270.518636)
		(end 329.284076 -270.523462)
		(width 0.0889)
		(layer "In6.Cu")
		(net "M_E_CPU0_SB_CB<7>")
	)
	(segment
		(start 274.9677 -274.097242)
		(end 274.9677 -273.254724)
		(width 0.14478)
		(layer "In6.Cu")
		(net "M_E_CPU0_SB_CB<7>")
	)
	(segment
		(start 275.917406 -273.496532)
		(end 275.686774 -273.496532)
		(width 0.14478)
		(layer "In6.Cu")
		(net "M_E_CPU0_SB_CB<7>")
	)
	(segment
		(start 273.517106 -274.260056)
		(end 273.092164 -274.684998)
		(width 0.14478)
		(layer "In6.Cu")
		(net "M_E_CPU0_SB_CB<7>")
	)
	(segment
		(start 275.686774 -273.496532)
		(end 275.52396 -273.659346)
		(width 0.14478)
		(layer "In6.Cu")
		(net "M_E_CPU0_SB_CB<7>")
	)
	(segment
		(start 275.361146 -274.260056)
		(end 275.130514 -274.260056)
		(width 0.14478)
		(layer "In6.Cu")
		(net "M_E_CPU0_SB_CB<7>")
	)
	(segment
		(start 308.017418 -273.171412)
		(end 307.778658 -273.410172)
		(width 0.14478)
		(layer "In6.Cu")
		(net "M_E_CPU0_SB_CB<7>")
	)
	(segment
		(start 275.130514 -274.260056)
		(end 274.9677 -274.097242)
		(width 0.14478)
		(layer "In6.Cu")
		(net "M_E_CPU0_SB_CB<7>")
	)
	(segment
		(start 275.52396 -274.097242)
		(end 275.361146 -274.260056)
		(width 0.14478)
		(layer "In6.Cu")
		(net "M_E_CPU0_SB_CB<7>")
	)
	(segment
		(start 274.41144 -274.097242)
		(end 274.248626 -274.260056)
		(width 0.14478)
		(layer "In6.Cu")
		(net "M_E_CPU0_SB_CB<7>")
	)
	(segment
		(start 326.234298 -270.404082)
		(end 324.934326 -269.10411)
		(width 0.0889)
		(layer "In6.Cu")
		(net "M_E_CPU0_SB_CB<7>")
	)
	(segment
		(start 311.686194 -268.9606)
		(end 308.017418 -272.629376)
		(width 0.14478)
		(layer "In6.Cu")
		(net "M_E_CPU0_SB_CB<7>")
	)
	(segment
		(start 276.243034 -274.260056)
		(end 276.08022 -274.097242)
		(width 0.14478)
		(layer "In6.Cu")
		(net "M_E_CPU0_SB_CB<7>")
	)
	(segment
		(start 324.138544 -268.9606)
		(end 323.874892 -268.9606)
		(width 0.0889)
		(layer "In6.Cu")
		(net "M_E_CPU0_SB_CB<7>")
	)
	(segment
		(start 323.874892 -268.9606)
		(end 311.686194 -268.9606)
		(width 0.14478)
		(layer "In6.Cu")
		(net "M_E_CPU0_SB_CB<7>")
	)
	(segment
		(start 276.08022 -274.097242)
		(end 276.08022 -273.659346)
		(width 0.14478)
		(layer "In6.Cu")
		(net "M_E_CPU0_SB_CB<7>")
	)
	(segment
		(start 324.934326 -269.10411)
		(end 324.282054 -269.10411)
		(width 0.0889)
		(layer "In6.Cu")
		(net "M_E_CPU0_SB_CB<7>")
	)
	(segment
		(start 327.462642 -270.404082)
		(end 326.234298 -270.404082)
		(width 0.0889)
		(layer "In6.Cu")
		(net "M_E_CPU0_SB_CB<7>")
	)
	(segment
		(start 274.804886 -273.09191)
		(end 274.574254 -273.09191)
		(width 0.14478)
		(layer "In6.Cu")
		(net "M_E_CPU0_SB_CB<7>")
	)
	(segment
		(start 281.991562 -274.260056)
		(end 276.243034 -274.260056)
		(width 0.14478)
		(layer "In6.Cu")
		(net "M_E_CPU0_SB_CB<7>")
	)
	(segment
		(start 308.017418 -272.629376)
		(end 308.017418 -273.171412)
		(width 0.14478)
		(layer "In6.Cu")
		(net "M_E_CPU0_SB_CB<7>")
	)
	(arc
		(start 330.542646 -270.4973)
		(mid 330.380457 -270.474565)
		(end 330.22413 -270.523462)
		(width 0.0889)
		(layer "In6.Cu")
		(net "M_E_CPU0_SB_CB<7>")
	)
	(arc
		(start 328.344022 -270.523462)
		(mid 328.061066 -270.599639)
		(end 327.77811 -270.523462)
		(width 0.0889)
		(layer "In6.Cu")
		(net "M_E_CPU0_SB_CB<7>")
	)
	(arc
		(start 328.709782 -270.518636)
		(mid 328.526274 -270.473142)
		(end 328.344022 -270.523462)
		(width 0.0889)
		(layer "In6.Cu")
		(net "M_E_CPU0_SB_CB<7>")
	)
	(arc
		(start 330.22413 -270.523462)
		(mid 329.941174 -270.599639)
		(end 329.658218 -270.523462)
		(width 0.0889)
		(layer "In6.Cu")
		(net "M_E_CPU0_SB_CB<7>")
	)
	(arc
		(start 329.658218 -270.523462)
		(mid 329.475967 -270.473112)
		(end 329.292458 -270.518636)
		(width 0.0889)
		(layer "In6.Cu")
		(net "M_E_CPU0_SB_CB<7>")
	)
	(arc
		(start 327.550526 -270.418814)
		(mid 327.507203 -270.407758)
		(end 327.462642 -270.404082)
		(width 0.0889)
		(layer "In6.Cu")
		(net "M_E_CPU0_SB_CB<7>")
	)
	(arc
		(start 329.284076 -270.523462)
		(mid 329.00112 -270.599639)
		(end 328.718164 -270.523462)
		(width 0.0889)
		(layer "In6.Cu")
		(net "M_E_CPU0_SB_CB<7>")
	)
	(arc
		(start 327.77811 -270.523462)
		(mid 327.666829 -270.465677)
		(end 327.550526 -270.418814)
		(width 0.0889)
		(layer "In6.Cu")
		(net "M_E_CPU0_SB_CB<7>")
	)
	(segment
		(start 329.467972 -269.770098)
		(end 329.00112 -270.036036)
		(width 0.10668)
		(layer "F.Cu")
		(net "M_E_CPU0_SB_CB<6>")
	)
	(segment
		(start 274.23618 -271.578324)
		(end 274.073366 -271.41551)
		(width 0.14478)
		(layer "In6.Cu")
		(net "M_E_CPU0_SB_CB<6>")
	)
	(segment
		(start 326.22617 -269.625826)
		(end 325.171562 -268.57071)
		(width 0.0889)
		(layer "In6.Cu")
		(net "M_E_CPU0_SB_CB<6>")
	)
	(segment
		(start 274.073366 -271.41551)
		(end 273.842734 -271.41551)
		(width 0.14478)
		(layer "In6.Cu")
		(net "M_E_CPU0_SB_CB<6>")
	)
	(segment
		(start 274.79244 -271.578324)
		(end 274.79244 -272.39722)
		(width 0.14478)
		(layer "In6.Cu")
		(net "M_E_CPU0_SB_CB<6>")
	)
	(segment
		(start 276.624034 -272.560034)
		(end 276.46122 -272.39722)
		(width 0.14478)
		(layer "In6.Cu")
		(net "M_E_CPU0_SB_CB<6>")
	)
	(segment
		(start 281.659584 -272.560034)
		(end 276.624034 -272.560034)
		(width 0.14478)
		(layer "In6.Cu")
		(net "M_E_CPU0_SB_CB<6>")
	)
	(segment
		(start 273.842734 -271.41551)
		(end 273.67992 -271.578324)
		(width 0.14478)
		(layer "In6.Cu")
		(net "M_E_CPU0_SB_CB<6>")
	)
	(segment
		(start 311.323482 -268.05128)
		(end 307.664612 -271.71015)
		(width 0.14478)
		(layer "In6.Cu")
		(net "M_E_CPU0_SB_CB<6>")
	)
	(segment
		(start 275.3487 -271.578324)
		(end 275.185886 -271.41551)
		(width 0.14478)
		(layer "In6.Cu")
		(net "M_E_CPU0_SB_CB<6>")
	)
	(segment
		(start 276.067774 -271.832832)
		(end 275.90496 -271.995646)
		(width 0.14478)
		(layer "In6.Cu")
		(net "M_E_CPU0_SB_CB<6>")
	)
	(segment
		(start 276.46122 -271.995646)
		(end 276.298406 -271.832832)
		(width 0.14478)
		(layer "In6.Cu")
		(net "M_E_CPU0_SB_CB<6>")
	)
	(segment
		(start 324.688454 -268.57071)
		(end 324.169024 -268.05128)
		(width 0.0889)
		(layer "In6.Cu")
		(net "M_E_CPU0_SB_CB<6>")
	)
	(segment
		(start 274.955254 -271.41551)
		(end 274.79244 -271.578324)
		(width 0.14478)
		(layer "In6.Cu")
		(net "M_E_CPU0_SB_CB<6>")
	)
	(segment
		(start 329.155044 -269.770606)
		(end 329.132692 -269.687294)
		(width 0.0889)
		(layer "In6.Cu")
		(net "M_E_CPU0_SB_CB<6>")
	)
	(segment
		(start 327.318878 -269.719552)
		(end 327.308464 -269.713456)
		(width 0.0889)
		(layer "In6.Cu")
		(net "M_E_CPU0_SB_CB<6>")
	)
	(segment
		(start 274.398994 -272.560034)
		(end 274.23618 -272.39722)
		(width 0.14478)
		(layer "In6.Cu")
		(net "M_E_CPU0_SB_CB<6>")
	)
	(segment
		(start 275.90496 -271.995646)
		(end 275.90496 -272.39722)
		(width 0.14478)
		(layer "In6.Cu")
		(net "M_E_CPU0_SB_CB<6>")
	)
	(segment
		(start 276.298406 -271.832832)
		(end 276.067774 -271.832832)
		(width 0.14478)
		(layer "In6.Cu")
		(net "M_E_CPU0_SB_CB<6>")
	)
	(segment
		(start 274.23618 -272.39722)
		(end 274.23618 -271.578324)
		(width 0.14478)
		(layer "In6.Cu")
		(net "M_E_CPU0_SB_CB<6>")
	)
	(segment
		(start 323.915024 -268.05128)
		(end 311.323482 -268.05128)
		(width 0.14478)
		(layer "In6.Cu")
		(net "M_E_CPU0_SB_CB<6>")
	)
	(segment
		(start 327.882504 -269.70863)
		(end 327.874122 -269.713456)
		(width 0.0889)
		(layer "In6.Cu")
		(net "M_E_CPU0_SB_CB<6>")
	)
	(segment
		(start 275.185886 -271.41551)
		(end 274.955254 -271.41551)
		(width 0.14478)
		(layer "In6.Cu")
		(net "M_E_CPU0_SB_CB<6>")
	)
	(segment
		(start 273.67992 -271.578324)
		(end 273.67992 -272.39722)
		(width 0.14478)
		(layer "In6.Cu")
		(net "M_E_CPU0_SB_CB<6>")
	)
	(segment
		(start 327.308464 -269.713456)
		(end 327.300082 -269.70863)
		(width 0.0889)
		(layer "In6.Cu")
		(net "M_E_CPU0_SB_CB<6>")
	)
	(segment
		(start 274.79244 -272.39722)
		(end 274.629626 -272.560034)
		(width 0.14478)
		(layer "In6.Cu")
		(net "M_E_CPU0_SB_CB<6>")
	)
	(segment
		(start 282.509468 -271.71015)
		(end 281.659584 -272.560034)
		(width 0.14478)
		(layer "In6.Cu")
		(net "M_E_CPU0_SB_CB<6>")
	)
	(segment
		(start 275.742146 -272.560034)
		(end 275.511514 -272.560034)
		(width 0.14478)
		(layer "In6.Cu")
		(net "M_E_CPU0_SB_CB<6>")
	)
	(segment
		(start 329.00112 -270.036036)
		(end 329.155044 -269.770606)
		(width 0.0889)
		(layer "In6.Cu")
		(net "M_E_CPU0_SB_CB<6>")
	)
	(segment
		(start 326.383142 -269.722092)
		(end 326.36841 -269.713456)
		(width 0.0889)
		(layer "In6.Cu")
		(net "M_E_CPU0_SB_CB<6>")
	)
	(segment
		(start 275.511514 -272.560034)
		(end 275.3487 -272.39722)
		(width 0.14478)
		(layer "In6.Cu")
		(net "M_E_CPU0_SB_CB<6>")
	)
	(segment
		(start 307.664612 -271.71015)
		(end 282.509468 -271.71015)
		(width 0.14478)
		(layer "In6.Cu")
		(net "M_E_CPU0_SB_CB<6>")
	)
	(segment
		(start 275.90496 -272.39722)
		(end 275.742146 -272.560034)
		(width 0.14478)
		(layer "In6.Cu")
		(net "M_E_CPU0_SB_CB<6>")
	)
	(segment
		(start 325.171562 -268.57071)
		(end 324.688454 -268.57071)
		(width 0.0889)
		(layer "In6.Cu")
		(net "M_E_CPU0_SB_CB<6>")
	)
	(segment
		(start 275.3487 -272.39722)
		(end 275.3487 -271.578324)
		(width 0.14478)
		(layer "In6.Cu")
		(net "M_E_CPU0_SB_CB<6>")
	)
	(segment
		(start 273.67992 -272.39722)
		(end 273.092164 -272.984976)
		(width 0.14478)
		(layer "In6.Cu")
		(net "M_E_CPU0_SB_CB<6>")
	)
	(segment
		(start 274.629626 -272.560034)
		(end 274.398994 -272.560034)
		(width 0.14478)
		(layer "In6.Cu")
		(net "M_E_CPU0_SB_CB<6>")
	)
	(segment
		(start 276.46122 -272.39722)
		(end 276.46122 -271.995646)
		(width 0.14478)
		(layer "In6.Cu")
		(net "M_E_CPU0_SB_CB<6>")
	)
	(segment
		(start 324.169024 -268.05128)
		(end 323.915024 -268.05128)
		(width 0.0889)
		(layer "In6.Cu")
		(net "M_E_CPU0_SB_CB<6>")
	)
	(segment
		(start 326.36841 -269.713456)
		(end 326.22617 -269.625826)
		(width 0.0889)
		(layer "In6.Cu")
		(net "M_E_CPU0_SB_CB<6>")
	)
	(arc
		(start 327.300082 -269.70863)
		(mid 327.116574 -269.663136)
		(end 326.934322 -269.713456)
		(width 0.0889)
		(layer "In6.Cu")
		(net "M_E_CPU0_SB_CB<6>")
	)
	(arc
		(start 326.934322 -269.713456)
		(mid 326.65987 -269.789692)
		(end 326.383142 -269.722092)
		(width 0.0889)
		(layer "In6.Cu")
		(net "M_E_CPU0_SB_CB<6>")
	)
	(arc
		(start 328.248264 -269.713456)
		(mid 328.066013 -269.663106)
		(end 327.882504 -269.70863)
		(width 0.0889)
		(layer "In6.Cu")
		(net "M_E_CPU0_SB_CB<6>")
	)
	(arc
		(start 327.874122 -269.713456)
		(mid 327.597309 -269.789599)
		(end 327.318878 -269.719552)
		(width 0.0889)
		(layer "In6.Cu")
		(net "M_E_CPU0_SB_CB<6>")
	)
	(arc
		(start 328.814176 -269.713456)
		(mid 328.53122 -269.789633)
		(end 328.248264 -269.713456)
		(width 0.0889)
		(layer "In6.Cu")
		(net "M_E_CPU0_SB_CB<6>")
	)
	(arc
		(start 329.132692 -269.687294)
		(mid 328.970503 -269.664559)
		(end 328.814176 -269.713456)
		(width 0.0889)
		(layer "In6.Cu")
		(net "M_E_CPU0_SB_CB<6>")
	)
	(segment
		(start 331.34808 -269.770098)
		(end 330.880974 -270.036036)
		(width 0.10668)
		(layer "F.Cu")
		(net "M_E_CPU0_SB_CB<5>")
	)
	(segment
		(start 324.510654 -268.82471)
		(end 324.191884 -268.50594)
		(width 0.0889)
		(layer "In6.Cu")
		(net "M_E_CPU0_SB_CB<5>")
	)
	(segment
		(start 286.806132 -272.17751)
		(end 286.556196 -272.17751)
		(width 0.14478)
		(layer "In6.Cu")
		(net "M_E_CPU0_SB_CB<5>")
	)
	(segment
		(start 283.38526 -272.786348)
		(end 283.38526 -272.32737)
		(width 0.14478)
		(layer "In6.Cu")
		(net "M_E_CPU0_SB_CB<5>")
	)
	(segment
		(start 285.999936 -272.93951)
		(end 285.846774 -272.786348)
		(width 0.14478)
		(layer "In6.Cu")
		(net "M_E_CPU0_SB_CB<5>")
	)
	(segment
		(start 283.007562 -272.17751)
		(end 281.7749 -273.410172)
		(width 0.14478)
		(layer "In6.Cu")
		(net "M_E_CPU0_SB_CB<5>")
	)
	(segment
		(start 280.30805 -273.410172)
		(end 279.914604 -273.803618)
		(width 0.14478)
		(layer "In6.Cu")
		(net "M_E_CPU0_SB_CB<5>")
	)
	(segment
		(start 279.683972 -273.803618)
		(end 279.521158 -273.640804)
		(width 0.14478)
		(layer "In6.Cu")
		(net "M_E_CPU0_SB_CB<5>")
	)
	(segment
		(start 330.128118 -270.358616)
		(end 330.119736 -270.363442)
		(width 0.0889)
		(layer "In6.Cu")
		(net "M_E_CPU0_SB_CB<5>")
	)
	(segment
		(start 278.408638 -273.640804)
		(end 278.408638 -273.177508)
		(width 0.14478)
		(layer "In6.Cu")
		(net "M_E_CPU0_SB_CB<5>")
	)
	(segment
		(start 286.403034 -272.786348)
		(end 286.249872 -272.93951)
		(width 0.14478)
		(layer "In6.Cu")
		(net "M_E_CPU0_SB_CB<5>")
	)
	(segment
		(start 287.112456 -272.942558)
		(end 286.959294 -272.789396)
		(width 0.14478)
		(layer "In6.Cu")
		(net "M_E_CPU0_SB_CB<5>")
	)
	(segment
		(start 281.7749 -273.410172)
		(end 280.30805 -273.410172)
		(width 0.14478)
		(layer "In6.Cu")
		(net "M_E_CPU0_SB_CB<5>")
	)
	(segment
		(start 278.408638 -273.177508)
		(end 278.245824 -273.014694)
		(width 0.14478)
		(layer "In6.Cu")
		(net "M_E_CPU0_SB_CB<5>")
	)
	(segment
		(start 290.04006 -272.93951)
		(end 289.877246 -272.776696)
		(width 0.14478)
		(layer "In6.Cu")
		(net "M_E_CPU0_SB_CB<5>")
	)
	(segment
		(start 289.877246 -272.776696)
		(end 289.877246 -272.343372)
		(width 0.14478)
		(layer "In6.Cu")
		(net "M_E_CPU0_SB_CB<5>")
	)
	(segment
		(start 327.873868 -270.358616)
		(end 327.80986 -270.321278)
		(width 0.0889)
		(layer "In6.Cu")
		(net "M_E_CPU0_SB_CB<5>")
	)
	(segment
		(start 286.556196 -272.17751)
		(end 286.403034 -272.330672)
		(width 0.14478)
		(layer "In6.Cu")
		(net "M_E_CPU0_SB_CB<5>")
	)
	(segment
		(start 290.989766 -272.776696)
		(end 290.989766 -272.343372)
		(width 0.14478)
		(layer "In6.Cu")
		(net "M_E_CPU0_SB_CB<5>")
	)
	(segment
		(start 279.358344 -273.014694)
		(end 279.127712 -273.014694)
		(width 0.14478)
		(layer "In6.Cu")
		(net "M_E_CPU0_SB_CB<5>")
	)
	(segment
		(start 290.59632 -272.180558)
		(end 290.433506 -272.343372)
		(width 0.14478)
		(layer "In6.Cu")
		(net "M_E_CPU0_SB_CB<5>")
	)
	(segment
		(start 290.826952 -272.180558)
		(end 290.59632 -272.180558)
		(width 0.14478)
		(layer "In6.Cu")
		(net "M_E_CPU0_SB_CB<5>")
	)
	(segment
		(start 279.521158 -273.177508)
		(end 279.358344 -273.014694)
		(width 0.14478)
		(layer "In6.Cu")
		(net "M_E_CPU0_SB_CB<5>")
	)
	(segment
		(start 285.418276 -272.17751)
		(end 285.035752 -272.560034)
		(width 0.14478)
		(layer "In6.Cu")
		(net "M_E_CPU0_SB_CB<5>")
	)
	(segment
		(start 283.2354 -272.17751)
		(end 283.007562 -272.17751)
		(width 0.14478)
		(layer "In6.Cu")
		(net "M_E_CPU0_SB_CB<5>")
	)
	(segment
		(start 278.964898 -273.640804)
		(end 278.802084 -273.803618)
		(width 0.14478)
		(layer "In6.Cu")
		(net "M_E_CPU0_SB_CB<5>")
	)
	(segment
		(start 279.914604 -273.803618)
		(end 279.683972 -273.803618)
		(width 0.14478)
		(layer "In6.Cu")
		(net "M_E_CPU0_SB_CB<5>")
	)
	(segment
		(start 283.788358 -272.93951)
		(end 283.538422 -272.93951)
		(width 0.14478)
		(layer "In6.Cu")
		(net "M_E_CPU0_SB_CB<5>")
	)
	(segment
		(start 291.383212 -272.93951)
		(end 291.15258 -272.93951)
		(width 0.14478)
		(layer "In6.Cu")
		(net "M_E_CPU0_SB_CB<5>")
	)
	(segment
		(start 290.989766 -272.343372)
		(end 290.826952 -272.180558)
		(width 0.14478)
		(layer "In6.Cu")
		(net "M_E_CPU0_SB_CB<5>")
	)
	(segment
		(start 286.403034 -272.330672)
		(end 286.403034 -272.786348)
		(width 0.14478)
		(layer "In6.Cu")
		(net "M_E_CPU0_SB_CB<5>")
	)
	(segment
		(start 278.802084 -273.803618)
		(end 278.571452 -273.803618)
		(width 0.14478)
		(layer "In6.Cu")
		(net "M_E_CPU0_SB_CB<5>")
	)
	(segment
		(start 289.714432 -272.180558)
		(end 289.4838 -272.180558)
		(width 0.14478)
		(layer "In6.Cu")
		(net "M_E_CPU0_SB_CB<5>")
	)
	(segment
		(start 284.167834 -272.560034)
		(end 283.788358 -272.93951)
		(width 0.14478)
		(layer "In6.Cu")
		(net "M_E_CPU0_SB_CB<5>")
	)
	(segment
		(start 323.887084 -268.50594)
		(end 311.504838 -268.50594)
		(width 0.14478)
		(layer "In6.Cu")
		(net "M_E_CPU0_SB_CB<5>")
	)
	(segment
		(start 290.433506 -272.343372)
		(end 290.433506 -272.776696)
		(width 0.14478)
		(layer "In6.Cu")
		(net "M_E_CPU0_SB_CB<5>")
	)
	(segment
		(start 289.4838 -272.180558)
		(end 289.320986 -272.343372)
		(width 0.14478)
		(layer "In6.Cu")
		(net "M_E_CPU0_SB_CB<5>")
	)
	(segment
		(start 330.880974 -270.036036)
		(end 330.72705 -270.301466)
		(width 0.0889)
		(layer "In6.Cu")
		(net "M_E_CPU0_SB_CB<5>")
	)
	(segment
		(start 278.571452 -273.803618)
		(end 278.408638 -273.640804)
		(width 0.14478)
		(layer "In6.Cu")
		(net "M_E_CPU0_SB_CB<5>")
	)
	(segment
		(start 311.504838 -268.50594)
		(end 307.450744 -272.560034)
		(width 0.14478)
		(layer "In6.Cu")
		(net "M_E_CPU0_SB_CB<5>")
	)
	(segment
		(start 289.320986 -272.343372)
		(end 289.320986 -272.776696)
		(width 0.14478)
		(layer "In6.Cu")
		(net "M_E_CPU0_SB_CB<5>")
	)
	(segment
		(start 288.92754 -272.93951)
		(end 288.548064 -272.560034)
		(width 0.14478)
		(layer "In6.Cu")
		(net "M_E_CPU0_SB_CB<5>")
	)
	(segment
		(start 286.959294 -272.330672)
		(end 286.806132 -272.17751)
		(width 0.14478)
		(layer "In6.Cu")
		(net "M_E_CPU0_SB_CB<5>")
	)
	(segment
		(start 278.245824 -273.014694)
		(end 278.012652 -273.014694)
		(width 0.14478)
		(layer "In6.Cu")
		(net "M_E_CPU0_SB_CB<5>")
	)
	(segment
		(start 291.762688 -272.560034)
		(end 291.383212 -272.93951)
		(width 0.14478)
		(layer "In6.Cu")
		(net "M_E_CPU0_SB_CB<5>")
	)
	(segment
		(start 290.433506 -272.776696)
		(end 290.270692 -272.93951)
		(width 0.14478)
		(layer "In6.Cu")
		(net "M_E_CPU0_SB_CB<5>")
	)
	(segment
		(start 285.846774 -272.786348)
		(end 285.846774 -272.356072)
		(width 0.14478)
		(layer "In6.Cu")
		(net "M_E_CPU0_SB_CB<5>")
	)
	(segment
		(start 283.38526 -272.32737)
		(end 283.2354 -272.17751)
		(width 0.14478)
		(layer "In6.Cu")
		(net "M_E_CPU0_SB_CB<5>")
	)
	(segment
		(start 324.942454 -268.82471)
		(end 324.510654 -268.82471)
		(width 0.0889)
		(layer "In6.Cu")
		(net "M_E_CPU0_SB_CB<5>")
	)
	(segment
		(start 285.035752 -272.560034)
		(end 284.167834 -272.560034)
		(width 0.14478)
		(layer "In6.Cu")
		(net "M_E_CPU0_SB_CB<5>")
	)
	(segment
		(start 279.127712 -273.014694)
		(end 278.964898 -273.177508)
		(width 0.14478)
		(layer "In6.Cu")
		(net "M_E_CPU0_SB_CB<5>")
	)
	(segment
		(start 289.877246 -272.343372)
		(end 289.714432 -272.180558)
		(width 0.14478)
		(layer "In6.Cu")
		(net "M_E_CPU0_SB_CB<5>")
	)
	(segment
		(start 285.846774 -272.356072)
		(end 285.668212 -272.17751)
		(width 0.14478)
		(layer "In6.Cu")
		(net "M_E_CPU0_SB_CB<5>")
	)
	(segment
		(start 286.249872 -272.93951)
		(end 285.999936 -272.93951)
		(width 0.14478)
		(layer "In6.Cu")
		(net "M_E_CPU0_SB_CB<5>")
	)
	(segment
		(start 283.538422 -272.93951)
		(end 283.38526 -272.786348)
		(width 0.14478)
		(layer "In6.Cu")
		(net "M_E_CPU0_SB_CB<5>")
	)
	(segment
		(start 324.191884 -268.50594)
		(end 323.887084 -268.50594)
		(width 0.0889)
		(layer "In6.Cu")
		(net "M_E_CPU0_SB_CB<5>")
	)
	(segment
		(start 307.450744 -272.560034)
		(end 291.762688 -272.560034)
		(width 0.14478)
		(layer "In6.Cu")
		(net "M_E_CPU0_SB_CB<5>")
	)
	(segment
		(start 287.362392 -272.942558)
		(end 287.112456 -272.942558)
		(width 0.14478)
		(layer "In6.Cu")
		(net "M_E_CPU0_SB_CB<5>")
	)
	(segment
		(start 290.270692 -272.93951)
		(end 290.04006 -272.93951)
		(width 0.14478)
		(layer "In6.Cu")
		(net "M_E_CPU0_SB_CB<5>")
	)
	(segment
		(start 278.964898 -273.177508)
		(end 278.964898 -273.640804)
		(width 0.14478)
		(layer "In6.Cu")
		(net "M_E_CPU0_SB_CB<5>")
	)
	(segment
		(start 289.320986 -272.776696)
		(end 289.158172 -272.93951)
		(width 0.14478)
		(layer "In6.Cu")
		(net "M_E_CPU0_SB_CB<5>")
	)
	(segment
		(start 291.15258 -272.93951)
		(end 290.989766 -272.776696)
		(width 0.14478)
		(layer "In6.Cu")
		(net "M_E_CPU0_SB_CB<5>")
	)
	(segment
		(start 278.012652 -273.014694)
		(end 277.192232 -273.835114)
		(width 0.14478)
		(layer "In6.Cu")
		(net "M_E_CPU0_SB_CB<5>")
	)
	(segment
		(start 326.318626 -270.200882)
		(end 324.942454 -268.82471)
		(width 0.0889)
		(layer "In6.Cu")
		(net "M_E_CPU0_SB_CB<5>")
	)
	(segment
		(start 327.4822 -270.200882)
		(end 326.318626 -270.200882)
		(width 0.0889)
		(layer "In6.Cu")
		(net "M_E_CPU0_SB_CB<5>")
	)
	(segment
		(start 289.158172 -272.93951)
		(end 288.92754 -272.93951)
		(width 0.14478)
		(layer "In6.Cu")
		(net "M_E_CPU0_SB_CB<5>")
	)
	(segment
		(start 287.744916 -272.560034)
		(end 287.362392 -272.942558)
		(width 0.14478)
		(layer "In6.Cu")
		(net "M_E_CPU0_SB_CB<5>")
	)
	(segment
		(start 286.959294 -272.789396)
		(end 286.959294 -272.330672)
		(width 0.14478)
		(layer "In6.Cu")
		(net "M_E_CPU0_SB_CB<5>")
	)
	(segment
		(start 279.521158 -273.640804)
		(end 279.521158 -273.177508)
		(width 0.14478)
		(layer "In6.Cu")
		(net "M_E_CPU0_SB_CB<5>")
	)
	(segment
		(start 288.548064 -272.560034)
		(end 287.744916 -272.560034)
		(width 0.14478)
		(layer "In6.Cu")
		(net "M_E_CPU0_SB_CB<5>")
	)
	(segment
		(start 285.668212 -272.17751)
		(end 285.418276 -272.17751)
		(width 0.14478)
		(layer "In6.Cu")
		(net "M_E_CPU0_SB_CB<5>")
	)
	(segment
		(start 330.72705 -270.301466)
		(end 330.631038 -270.326866)
		(width 0.0889)
		(layer "In6.Cu")
		(net "M_E_CPU0_SB_CB<5>")
	)
	(arc
		(start 328.814176 -270.358616)
		(mid 328.53122 -270.282439)
		(end 328.248264 -270.358616)
		(width 0.0889)
		(layer "In6.Cu")
		(net "M_E_CPU0_SB_CB<5>")
	)
	(arc
		(start 330.119736 -270.363442)
		(mid 329.936228 -270.408936)
		(end 329.753976 -270.358616)
		(width 0.0889)
		(layer "In6.Cu")
		(net "M_E_CPU0_SB_CB<5>")
	)
	(arc
		(start 327.80986 -270.321278)
		(mid 327.692954 -270.26153)
		(end 327.570338 -270.214598)
		(width 0.0889)
		(layer "In6.Cu")
		(net "M_E_CPU0_SB_CB<5>")
	)
	(arc
		(start 329.753976 -270.358616)
		(mid 329.47102 -270.282439)
		(end 329.188064 -270.358616)
		(width 0.0889)
		(layer "In6.Cu")
		(net "M_E_CPU0_SB_CB<5>")
	)
	(arc
		(start 329.188064 -270.358616)
		(mid 329.00112 -270.408871)
		(end 328.814176 -270.358616)
		(width 0.0889)
		(layer "In6.Cu")
		(net "M_E_CPU0_SB_CB<5>")
	)
	(arc
		(start 330.631038 -270.326866)
		(mid 330.37583 -270.283389)
		(end 330.128118 -270.358616)
		(width 0.0889)
		(layer "In6.Cu")
		(net "M_E_CPU0_SB_CB<5>")
	)
	(arc
		(start 328.248264 -270.358616)
		(mid 328.061066 -270.408998)
		(end 327.873868 -270.358616)
		(width 0.0889)
		(layer "In6.Cu")
		(net "M_E_CPU0_SB_CB<5>")
	)
	(arc
		(start 327.570338 -270.214598)
		(mid 327.526806 -270.204292)
		(end 327.4822 -270.200882)
		(width 0.0889)
		(layer "In6.Cu")
		(net "M_E_CPU0_SB_CB<5>")
	)
	(segment
		(start 329.937872 -268.960092)
		(end 329.47102 -269.22603)
		(width 0.10668)
		(layer "F.Cu")
		(net "M_E_CPU0_SB_CB<4>")
	)
	(segment
		(start 292.496494 -270.860012)
		(end 291.615368 -270.860012)
		(width 0.14478)
		(layer "In6.Cu")
		(net "M_E_CPU0_SB_CB<4>")
	)
	(segment
		(start 286.324802 -271.13611)
		(end 286.048704 -270.860012)
		(width 0.14478)
		(layer "In6.Cu")
		(net "M_E_CPU0_SB_CB<4>")
	)
	(segment
		(start 329.317096 -269.49146)
		(end 329.221084 -269.51686)
		(width 0.0889)
		(layer "In6.Cu")
		(net "M_E_CPU0_SB_CB<4>")
	)
	(segment
		(start 289.64509 -270.860012)
		(end 289.390328 -270.860012)
		(width 0.14478)
		(layer "In6.Cu")
		(net "M_E_CPU0_SB_CB<4>")
	)
	(segment
		(start 287.717484 -271.13611)
		(end 287.437322 -271.13611)
		(width 0.14478)
		(layer "In6.Cu")
		(net "M_E_CPU0_SB_CB<4>")
	)
	(segment
		(start 286.881062 -270.860012)
		(end 286.604964 -271.13611)
		(width 0.14478)
		(layer "In6.Cu")
		(net "M_E_CPU0_SB_CB<4>")
	)
	(segment
		(start 279.842214 -272.10131)
		(end 279.611582 -272.10131)
		(width 0.14478)
		(layer "In6.Cu")
		(net "M_E_CPU0_SB_CB<4>")
	)
	(segment
		(start 300.490382 -271.16151)
		(end 300.188884 -270.860012)
		(width 0.14478)
		(layer "In6.Cu")
		(net "M_E_CPU0_SB_CB<4>")
	)
	(segment
		(start 311.142126 -267.59662)
		(end 307.878734 -270.860012)
		(width 0.14478)
		(layer "In6.Cu")
		(net "M_E_CPU0_SB_CB<4>")
	)
	(segment
		(start 305.751484 -270.860012)
		(end 305.496722 -270.860012)
		(width 0.14478)
		(layer "In6.Cu")
		(net "M_E_CPU0_SB_CB<4>")
	)
	(segment
		(start 300.188884 -270.860012)
		(end 299.085254 -270.860012)
		(width 0.14478)
		(layer "In6.Cu")
		(net "M_E_CPU0_SB_CB<4>")
	)
	(segment
		(start 305.496722 -270.860012)
		(end 305.195224 -271.16151)
		(width 0.14478)
		(layer "In6.Cu")
		(net "M_E_CPU0_SB_CB<4>")
	)
	(segment
		(start 326.476106 -269.555468)
		(end 326.464422 -269.54861)
		(width 0.0889)
		(layer "In6.Cu")
		(net "M_E_CPU0_SB_CB<4>")
	)
	(segment
		(start 298.528994 -271.16151)
		(end 298.227496 -270.860012)
		(width 0.14478)
		(layer "In6.Cu")
		(net "M_E_CPU0_SB_CB<4>")
	)
	(segment
		(start 297.972734 -270.860012)
		(end 297.671236 -271.16151)
		(width 0.14478)
		(layer "In6.Cu")
		(net "M_E_CPU0_SB_CB<4>")
	)
	(segment
		(start 291.059108 -271.16151)
		(end 290.75761 -270.860012)
		(width 0.14478)
		(layer "In6.Cu")
		(net "M_E_CPU0_SB_CB<4>")
	)
	(segment
		(start 289.390328 -270.860012)
		(end 289.08883 -271.16151)
		(width 0.14478)
		(layer "In6.Cu")
		(net "M_E_CPU0_SB_CB<4>")
	)
	(segment
		(start 296.303954 -271.16151)
		(end 296.002456 -270.860012)
		(width 0.14478)
		(layer "In6.Cu")
		(net "M_E_CPU0_SB_CB<4>")
	)
	(segment
		(start 278.173434 -270.80591)
		(end 277.942802 -270.80591)
		(width 0.14478)
		(layer "In6.Cu")
		(net "M_E_CPU0_SB_CB<4>")
	)
	(segment
		(start 284.936184 -270.860012)
		(end 283.884624 -270.860012)
		(width 0.14478)
		(layer "In6.Cu")
		(net "M_E_CPU0_SB_CB<4>")
	)
	(segment
		(start 303.526444 -270.860012)
		(end 303.271682 -270.860012)
		(width 0.14478)
		(layer "In6.Cu")
		(net "M_E_CPU0_SB_CB<4>")
	)
	(segment
		(start 282.54706 -270.860012)
		(end 281.696922 -271.71015)
		(width 0.14478)
		(layer "In6.Cu")
		(net "M_E_CPU0_SB_CB<4>")
	)
	(segment
		(start 301.857664 -271.16151)
		(end 301.602902 -271.16151)
		(width 0.14478)
		(layer "In6.Cu")
		(net "M_E_CPU0_SB_CB<4>")
	)
	(segment
		(start 286.604964 -271.13611)
		(end 286.324802 -271.13611)
		(width 0.14478)
		(layer "In6.Cu")
		(net "M_E_CPU0_SB_CB<4>")
	)
	(segment
		(start 278.892508 -270.968724)
		(end 278.892508 -271.938496)
		(width 0.14478)
		(layer "In6.Cu")
		(net "M_E_CPU0_SB_CB<4>")
	)
	(segment
		(start 289.946588 -271.16151)
		(end 289.64509 -270.860012)
		(width 0.14478)
		(layer "In6.Cu")
		(net "M_E_CPU0_SB_CB<4>")
	)
	(segment
		(start 303.827942 -271.16151)
		(end 303.526444 -270.860012)
		(width 0.14478)
		(layer "In6.Cu")
		(net "M_E_CPU0_SB_CB<4>")
	)
	(segment
		(start 285.212282 -271.13611)
		(end 284.936184 -270.860012)
		(width 0.14478)
		(layer "In6.Cu")
		(net "M_E_CPU0_SB_CB<4>")
	)
	(segment
		(start 278.892508 -271.938496)
		(end 278.729694 -272.10131)
		(width 0.14478)
		(layer "In6.Cu")
		(net "M_E_CPU0_SB_CB<4>")
	)
	(segment
		(start 278.336248 -270.968724)
		(end 278.173434 -270.80591)
		(width 0.14478)
		(layer "In6.Cu")
		(net "M_E_CPU0_SB_CB<4>")
	)
	(segment
		(start 279.285954 -270.80591)
		(end 279.055322 -270.80591)
		(width 0.14478)
		(layer "In6.Cu")
		(net "M_E_CPU0_SB_CB<4>")
	)
	(segment
		(start 297.416474 -271.16151)
		(end 297.114976 -270.860012)
		(width 0.14478)
		(layer "In6.Cu")
		(net "M_E_CPU0_SB_CB<4>")
	)
	(segment
		(start 285.768542 -270.860012)
		(end 285.492444 -271.13611)
		(width 0.14478)
		(layer "In6.Cu")
		(net "M_E_CPU0_SB_CB<4>")
	)
	(segment
		(start 296.860214 -270.860012)
		(end 296.558716 -271.16151)
		(width 0.14478)
		(layer "In6.Cu")
		(net "M_E_CPU0_SB_CB<4>")
	)
	(segment
		(start 305.195224 -271.16151)
		(end 304.940462 -271.16151)
		(width 0.14478)
		(layer "In6.Cu")
		(net "M_E_CPU0_SB_CB<4>")
	)
	(segment
		(start 327.404222 -269.54861)
		(end 327.38949 -269.539974)
		(width 0.0889)
		(layer "In6.Cu")
		(net "M_E_CPU0_SB_CB<4>")
	)
	(segment
		(start 298.783756 -271.16151)
		(end 298.528994 -271.16151)
		(width 0.14478)
		(layer "In6.Cu")
		(net "M_E_CPU0_SB_CB<4>")
	)
	(segment
		(start 293.052754 -271.13611)
		(end 292.772592 -271.13611)
		(width 0.14478)
		(layer "In6.Cu")
		(net "M_E_CPU0_SB_CB<4>")
	)
	(segment
		(start 299.085254 -270.860012)
		(end 298.783756 -271.16151)
		(width 0.14478)
		(layer "In6.Cu")
		(net "M_E_CPU0_SB_CB<4>")
	)
	(segment
		(start 306.052982 -271.16151)
		(end 305.751484 -270.860012)
		(width 0.14478)
		(layer "In6.Cu")
		(net "M_E_CPU0_SB_CB<4>")
	)
	(segment
		(start 323.909944 -267.59662)
		(end 311.142126 -267.59662)
		(width 0.14478)
		(layer "In6.Cu")
		(net "M_E_CPU0_SB_CB<4>")
	)
	(segment
		(start 294.441372 -270.860012)
		(end 294.165274 -271.13611)
		(width 0.14478)
		(layer "In6.Cu")
		(net "M_E_CPU0_SB_CB<4>")
	)
	(segment
		(start 304.384202 -270.860012)
		(end 304.082704 -271.16151)
		(width 0.14478)
		(layer "In6.Cu")
		(net "M_E_CPU0_SB_CB<4>")
	)
	(segment
		(start 302.970184 -271.16151)
		(end 302.715422 -271.16151)
		(width 0.14478)
		(layer "In6.Cu")
		(net "M_E_CPU0_SB_CB<4>")
	)
	(segment
		(start 292.772592 -271.13611)
		(end 292.496494 -270.860012)
		(width 0.14478)
		(layer "In6.Cu")
		(net "M_E_CPU0_SB_CB<4>")
	)
	(segment
		(start 287.993582 -270.860012)
		(end 287.717484 -271.13611)
		(width 0.14478)
		(layer "In6.Cu")
		(net "M_E_CPU0_SB_CB<4>")
	)
	(segment
		(start 290.502848 -270.860012)
		(end 290.20135 -271.16151)
		(width 0.14478)
		(layer "In6.Cu")
		(net "M_E_CPU0_SB_CB<4>")
	)
	(segment
		(start 281.696922 -271.71015)
		(end 280.233374 -271.71015)
		(width 0.14478)
		(layer "In6.Cu")
		(net "M_E_CPU0_SB_CB<4>")
	)
	(segment
		(start 295.277794 -271.13611)
		(end 294.997632 -271.13611)
		(width 0.14478)
		(layer "In6.Cu")
		(net "M_E_CPU0_SB_CB<4>")
	)
	(segment
		(start 283.328364 -271.16151)
		(end 283.026866 -270.860012)
		(width 0.14478)
		(layer "In6.Cu")
		(net "M_E_CPU0_SB_CB<4>")
	)
	(segment
		(start 278.499062 -272.10131)
		(end 278.336248 -271.938496)
		(width 0.14478)
		(layer "In6.Cu")
		(net "M_E_CPU0_SB_CB<4>")
	)
	(segment
		(start 294.997632 -271.13611)
		(end 294.721534 -270.860012)
		(width 0.14478)
		(layer "In6.Cu")
		(net "M_E_CPU0_SB_CB<4>")
	)
	(segment
		(start 302.413924 -270.860012)
		(end 302.159162 -270.860012)
		(width 0.14478)
		(layer "In6.Cu")
		(net "M_E_CPU0_SB_CB<4>")
	)
	(segment
		(start 283.026866 -270.860012)
		(end 282.54706 -270.860012)
		(width 0.14478)
		(layer "In6.Cu")
		(net "M_E_CPU0_SB_CB<4>")
	)
	(segment
		(start 301.301404 -270.860012)
		(end 301.046642 -270.860012)
		(width 0.14478)
		(layer "In6.Cu")
		(net "M_E_CPU0_SB_CB<4>")
	)
	(segment
		(start 290.20135 -271.16151)
		(end 289.946588 -271.16151)
		(width 0.14478)
		(layer "In6.Cu")
		(net "M_E_CPU0_SB_CB<4>")
	)
	(segment
		(start 296.002456 -270.860012)
		(end 295.553892 -270.860012)
		(width 0.14478)
		(layer "In6.Cu")
		(net "M_E_CPU0_SB_CB<4>")
	)
	(segment
		(start 302.159162 -270.860012)
		(end 301.857664 -271.16151)
		(width 0.14478)
		(layer "In6.Cu")
		(net "M_E_CPU0_SB_CB<4>")
	)
	(segment
		(start 302.715422 -271.16151)
		(end 302.413924 -270.860012)
		(width 0.14478)
		(layer "In6.Cu")
		(net "M_E_CPU0_SB_CB<4>")
	)
	(segment
		(start 279.611582 -272.10131)
		(end 279.448768 -271.938496)
		(width 0.14478)
		(layer "In6.Cu")
		(net "M_E_CPU0_SB_CB<4>")
	)
	(segment
		(start 293.885112 -271.13611)
		(end 293.609014 -270.860012)
		(width 0.14478)
		(layer "In6.Cu")
		(net "M_E_CPU0_SB_CB<4>")
	)
	(segment
		(start 306.307744 -271.16151)
		(end 306.052982 -271.16151)
		(width 0.14478)
		(layer "In6.Cu")
		(net "M_E_CPU0_SB_CB<4>")
	)
	(segment
		(start 325.425054 -268.519656)
		(end 325.425054 -267.986764)
		(width 0.0889)
		(layer "In6.Cu")
		(net "M_E_CPU0_SB_CB<4>")
	)
	(segment
		(start 293.328852 -270.860012)
		(end 293.052754 -271.13611)
		(width 0.14478)
		(layer "In6.Cu")
		(net "M_E_CPU0_SB_CB<4>")
	)
	(segment
		(start 283.884624 -270.860012)
		(end 283.583126 -271.16151)
		(width 0.14478)
		(layer "In6.Cu")
		(net "M_E_CPU0_SB_CB<4>")
	)
	(segment
		(start 285.492444 -271.13611)
		(end 285.212282 -271.13611)
		(width 0.14478)
		(layer "In6.Cu")
		(net "M_E_CPU0_SB_CB<4>")
	)
	(segment
		(start 290.75761 -270.860012)
		(end 290.502848 -270.860012)
		(width 0.14478)
		(layer "In6.Cu")
		(net "M_E_CPU0_SB_CB<4>")
	)
	(segment
		(start 304.940462 -271.16151)
		(end 304.638964 -270.860012)
		(width 0.14478)
		(layer "In6.Cu")
		(net "M_E_CPU0_SB_CB<4>")
	)
	(segment
		(start 296.558716 -271.16151)
		(end 296.303954 -271.16151)
		(width 0.14478)
		(layer "In6.Cu")
		(net "M_E_CPU0_SB_CB<4>")
	)
	(segment
		(start 278.729694 -272.10131)
		(end 278.499062 -272.10131)
		(width 0.14478)
		(layer "In6.Cu")
		(net "M_E_CPU0_SB_CB<4>")
	)
	(segment
		(start 294.165274 -271.13611)
		(end 293.885112 -271.13611)
		(width 0.14478)
		(layer "In6.Cu")
		(net "M_E_CPU0_SB_CB<4>")
	)
	(segment
		(start 287.437322 -271.13611)
		(end 287.161224 -270.860012)
		(width 0.14478)
		(layer "In6.Cu")
		(net "M_E_CPU0_SB_CB<4>")
	)
	(segment
		(start 325.425054 -267.986764)
		(end 325.03491 -267.59662)
		(width 0.0889)
		(layer "In6.Cu")
		(net "M_E_CPU0_SB_CB<4>")
	)
	(segment
		(start 287.161224 -270.860012)
		(end 286.881062 -270.860012)
		(width 0.14478)
		(layer "In6.Cu")
		(net "M_E_CPU0_SB_CB<4>")
	)
	(segment
		(start 279.055322 -270.80591)
		(end 278.892508 -270.968724)
		(width 0.14478)
		(layer "In6.Cu")
		(net "M_E_CPU0_SB_CB<4>")
	)
	(segment
		(start 328.718164 -269.54861)
		(end 328.709782 -269.553436)
		(width 0.0889)
		(layer "In6.Cu")
		(net "M_E_CPU0_SB_CB<4>")
	)
	(segment
		(start 288.834068 -271.16151)
		(end 288.53257 -270.860012)
		(width 0.14478)
		(layer "In6.Cu")
		(net "M_E_CPU0_SB_CB<4>")
	)
	(segment
		(start 291.615368 -270.860012)
		(end 291.31387 -271.16151)
		(width 0.14478)
		(layer "In6.Cu")
		(net "M_E_CPU0_SB_CB<4>")
	)
	(segment
		(start 283.583126 -271.16151)
		(end 283.328364 -271.16151)
		(width 0.14478)
		(layer "In6.Cu")
		(net "M_E_CPU0_SB_CB<4>")
	)
	(segment
		(start 289.08883 -271.16151)
		(end 288.834068 -271.16151)
		(width 0.14478)
		(layer "In6.Cu")
		(net "M_E_CPU0_SB_CB<4>")
	)
	(segment
		(start 279.448768 -271.938496)
		(end 279.448768 -270.968724)
		(width 0.14478)
		(layer "In6.Cu")
		(net "M_E_CPU0_SB_CB<4>")
	)
	(segment
		(start 288.53257 -270.860012)
		(end 287.993582 -270.860012)
		(width 0.14478)
		(layer "In6.Cu")
		(net "M_E_CPU0_SB_CB<4>")
	)
	(segment
		(start 301.046642 -270.860012)
		(end 300.745144 -271.16151)
		(width 0.14478)
		(layer "In6.Cu")
		(net "M_E_CPU0_SB_CB<4>")
	)
	(segment
		(start 295.553892 -270.860012)
		(end 295.277794 -271.13611)
		(width 0.14478)
		(layer "In6.Cu")
		(net "M_E_CPU0_SB_CB<4>")
	)
	(segment
		(start 306.609242 -270.860012)
		(end 306.307744 -271.16151)
		(width 0.14478)
		(layer "In6.Cu")
		(net "M_E_CPU0_SB_CB<4>")
	)
	(segment
		(start 304.082704 -271.16151)
		(end 303.827942 -271.16151)
		(width 0.14478)
		(layer "In6.Cu")
		(net "M_E_CPU0_SB_CB<4>")
	)
	(segment
		(start 304.638964 -270.860012)
		(end 304.384202 -270.860012)
		(width 0.14478)
		(layer "In6.Cu")
		(net "M_E_CPU0_SB_CB<4>")
	)
	(segment
		(start 298.227496 -270.860012)
		(end 297.972734 -270.860012)
		(width 0.14478)
		(layer "In6.Cu")
		(net "M_E_CPU0_SB_CB<4>")
	)
	(segment
		(start 307.878734 -270.860012)
		(end 306.609242 -270.860012)
		(width 0.14478)
		(layer "In6.Cu")
		(net "M_E_CPU0_SB_CB<4>")
	)
	(segment
		(start 277.779988 -271.547336)
		(end 277.192232 -272.135092)
		(width 0.14478)
		(layer "In6.Cu")
		(net "M_E_CPU0_SB_CB<4>")
	)
	(segment
		(start 329.47102 -269.22603)
		(end 329.317096 -269.49146)
		(width 0.0889)
		(layer "In6.Cu")
		(net "M_E_CPU0_SB_CB<4>")
	)
	(segment
		(start 301.602902 -271.16151)
		(end 301.301404 -270.860012)
		(width 0.14478)
		(layer "In6.Cu")
		(net "M_E_CPU0_SB_CB<4>")
	)
	(segment
		(start 297.114976 -270.860012)
		(end 296.860214 -270.860012)
		(width 0.14478)
		(layer "In6.Cu")
		(net "M_E_CPU0_SB_CB<4>")
	)
	(segment
		(start 303.271682 -270.860012)
		(end 302.970184 -271.16151)
		(width 0.14478)
		(layer "In6.Cu")
		(net "M_E_CPU0_SB_CB<4>")
	)
	(segment
		(start 279.448768 -270.968724)
		(end 279.285954 -270.80591)
		(width 0.14478)
		(layer "In6.Cu")
		(net "M_E_CPU0_SB_CB<4>")
	)
	(segment
		(start 325.03491 -267.59662)
		(end 323.909944 -267.59662)
		(width 0.0889)
		(layer "In6.Cu")
		(net "M_E_CPU0_SB_CB<4>")
	)
	(segment
		(start 277.779988 -270.968724)
		(end 277.779988 -271.547336)
		(width 0.14478)
		(layer "In6.Cu")
		(net "M_E_CPU0_SB_CB<4>")
	)
	(segment
		(start 278.336248 -271.938496)
		(end 278.336248 -270.968724)
		(width 0.14478)
		(layer "In6.Cu")
		(net "M_E_CPU0_SB_CB<4>")
	)
	(segment
		(start 291.31387 -271.16151)
		(end 291.059108 -271.16151)
		(width 0.14478)
		(layer "In6.Cu")
		(net "M_E_CPU0_SB_CB<4>")
	)
	(segment
		(start 293.609014 -270.860012)
		(end 293.328852 -270.860012)
		(width 0.14478)
		(layer "In6.Cu")
		(net "M_E_CPU0_SB_CB<4>")
	)
	(segment
		(start 280.233374 -271.71015)
		(end 279.842214 -272.10131)
		(width 0.14478)
		(layer "In6.Cu")
		(net "M_E_CPU0_SB_CB<4>")
	)
	(segment
		(start 300.745144 -271.16151)
		(end 300.490382 -271.16151)
		(width 0.14478)
		(layer "In6.Cu")
		(net "M_E_CPU0_SB_CB<4>")
	)
	(segment
		(start 277.942802 -270.80591)
		(end 277.779988 -270.968724)
		(width 0.14478)
		(layer "In6.Cu")
		(net "M_E_CPU0_SB_CB<4>")
	)
	(segment
		(start 286.048704 -270.860012)
		(end 285.768542 -270.860012)
		(width 0.14478)
		(layer "In6.Cu")
		(net "M_E_CPU0_SB_CB<4>")
	)
	(segment
		(start 326.464422 -269.54861)
		(end 325.425054 -268.519656)
		(width 0.0889)
		(layer "In6.Cu")
		(net "M_E_CPU0_SB_CB<4>")
	)
	(segment
		(start 297.671236 -271.16151)
		(end 297.416474 -271.16151)
		(width 0.14478)
		(layer "In6.Cu")
		(net "M_E_CPU0_SB_CB<4>")
	)
	(segment
		(start 294.721534 -270.860012)
		(end 294.441372 -270.860012)
		(width 0.14478)
		(layer "In6.Cu")
		(net "M_E_CPU0_SB_CB<4>")
	)
	(arc
		(start 327.77811 -269.54861)
		(mid 327.591166 -269.598865)
		(end 327.404222 -269.54861)
		(width 0.0889)
		(layer "In6.Cu")
		(net "M_E_CPU0_SB_CB<4>")
	)
	(arc
		(start 329.221084 -269.51686)
		(mid 328.965876 -269.473383)
		(end 328.718164 -269.54861)
		(width 0.0889)
		(layer "In6.Cu")
		(net "M_E_CPU0_SB_CB<4>")
	)
	(arc
		(start 328.344022 -269.54861)
		(mid 328.061066 -269.472433)
		(end 327.77811 -269.54861)
		(width 0.0889)
		(layer "In6.Cu")
		(net "M_E_CPU0_SB_CB<4>")
	)
	(arc
		(start 328.709782 -269.553436)
		(mid 328.526274 -269.59893)
		(end 328.344022 -269.54861)
		(width 0.0889)
		(layer "In6.Cu")
		(net "M_E_CPU0_SB_CB<4>")
	)
	(arc
		(start 327.38949 -269.539974)
		(mid 327.112761 -269.472291)
		(end 326.83831 -269.54861)
		(width 0.0889)
		(layer "In6.Cu")
		(net "M_E_CPU0_SB_CB<4>")
	)
	(arc
		(start 326.83831 -269.54861)
		(mid 326.658105 -269.598927)
		(end 326.476106 -269.555468)
		(width 0.0889)
		(layer "In6.Cu")
		(net "M_E_CPU0_SB_CB<4>")
	)
	(segment
		(start 330.877926 -273.820128)
		(end 330.411074 -274.086066)
		(width 0.10668)
		(layer "F.Cu")
		(net "M_E_CPU0_SB_CB<3>")
	)
	(segment
		(start 293.947596 -281.060144)
		(end 293.099236 -280.211784)
		(width 0.14478)
		(layer "In6.Cu")
		(net "M_E_CPU0_SB_CB<3>")
	)
	(segment
		(start 290.30422 -281.060144)
		(end 286.436308 -281.060144)
		(width 0.14478)
		(layer "In6.Cu")
		(net "M_E_CPU0_SB_CB<3>")
	)
	(segment
		(start 324.317614 -272.50771)
		(end 324.161404 -272.66392)
		(width 0.0889)
		(layer "In6.Cu")
		(net "M_E_CPU0_SB_CB<3>")
	)
	(segment
		(start 329.292458 -273.75866)
		(end 329.284076 -273.763486)
		(width 0.0889)
		(layer "In6.Cu")
		(net "M_E_CPU0_SB_CB<3>")
	)
	(segment
		(start 324.161404 -272.66392)
		(end 313.899296 -272.66392)
		(width 0.14478)
		(layer "In6.Cu")
		(net "M_E_CPU0_SB_CB<3>")
	)
	(segment
		(start 283.127958 -280.210006)
		(end 282.27782 -281.060144)
		(width 0.14478)
		(layer "In6.Cu")
		(net "M_E_CPU0_SB_CB<3>")
	)
	(segment
		(start 307.848254 -279.809448)
		(end 306.117752 -279.809448)
		(width 0.14478)
		(layer "In6.Cu")
		(net "M_E_CPU0_SB_CB<3>")
	)
	(segment
		(start 301.618396 -281.060144)
		(end 300.768258 -280.210006)
		(width 0.14478)
		(layer "In6.Cu")
		(net "M_E_CPU0_SB_CB<3>")
	)
	(segment
		(start 293.099236 -280.211784)
		(end 291.15258 -280.211784)
		(width 0.14478)
		(layer "In6.Cu")
		(net "M_E_CPU0_SB_CB<3>")
	)
	(segment
		(start 308.581298 -277.981918)
		(end 308.581298 -279.076404)
		(width 0.14478)
		(layer "In6.Cu")
		(net "M_E_CPU0_SB_CB<3>")
	)
	(segment
		(start 273.51736 -281.060144)
		(end 273.092164 -280.634948)
		(width 0.14478)
		(layer "In6.Cu")
		(net "M_E_CPU0_SB_CB<3>")
	)
	(segment
		(start 304.867056 -281.060144)
		(end 301.618396 -281.060144)
		(width 0.14478)
		(layer "In6.Cu")
		(net "M_E_CPU0_SB_CB<3>")
	)
	(segment
		(start 313.899296 -272.66392)
		(end 308.581298 -277.981918)
		(width 0.14478)
		(layer "In6.Cu")
		(net "M_E_CPU0_SB_CB<3>")
	)
	(segment
		(start 328.718164 -273.763486)
		(end 328.709782 -273.75866)
		(width 0.0889)
		(layer "In6.Cu")
		(net "M_E_CPU0_SB_CB<3>")
	)
	(segment
		(start 297.483784 -281.060144)
		(end 293.947596 -281.060144)
		(width 0.14478)
		(layer "In6.Cu")
		(net "M_E_CPU0_SB_CB<3>")
	)
	(segment
		(start 308.581298 -279.076404)
		(end 307.848254 -279.809448)
		(width 0.14478)
		(layer "In6.Cu")
		(net "M_E_CPU0_SB_CB<3>")
	)
	(segment
		(start 325.162926 -272.50771)
		(end 324.317614 -272.50771)
		(width 0.0889)
		(layer "In6.Cu")
		(net "M_E_CPU0_SB_CB<3>")
	)
	(segment
		(start 291.15258 -280.211784)
		(end 290.30422 -281.060144)
		(width 0.14478)
		(layer "In6.Cu")
		(net "M_E_CPU0_SB_CB<3>")
	)
	(segment
		(start 285.58617 -280.210006)
		(end 283.127958 -280.210006)
		(width 0.14478)
		(layer "In6.Cu")
		(net "M_E_CPU0_SB_CB<3>")
	)
	(segment
		(start 298.333922 -280.210006)
		(end 297.483784 -281.060144)
		(width 0.14478)
		(layer "In6.Cu")
		(net "M_E_CPU0_SB_CB<3>")
	)
	(segment
		(start 300.768258 -280.210006)
		(end 298.333922 -280.210006)
		(width 0.14478)
		(layer "In6.Cu")
		(net "M_E_CPU0_SB_CB<3>")
	)
	(segment
		(start 306.117752 -279.809448)
		(end 304.867056 -281.060144)
		(width 0.14478)
		(layer "In6.Cu")
		(net "M_E_CPU0_SB_CB<3>")
	)
	(segment
		(start 327.556114 -273.720306)
		(end 326.375522 -273.720306)
		(width 0.0889)
		(layer "In6.Cu")
		(net "M_E_CPU0_SB_CB<3>")
	)
	(segment
		(start 330.564998 -273.820636)
		(end 330.542646 -273.737324)
		(width 0.0889)
		(layer "In6.Cu")
		(net "M_E_CPU0_SB_CB<3>")
	)
	(segment
		(start 286.436308 -281.060144)
		(end 285.58617 -280.210006)
		(width 0.14478)
		(layer "In6.Cu")
		(net "M_E_CPU0_SB_CB<3>")
	)
	(segment
		(start 330.411074 -274.086066)
		(end 330.564998 -273.820636)
		(width 0.0889)
		(layer "In6.Cu")
		(net "M_E_CPU0_SB_CB<3>")
	)
	(segment
		(start 326.375522 -273.720306)
		(end 325.162926 -272.50771)
		(width 0.0889)
		(layer "In6.Cu")
		(net "M_E_CPU0_SB_CB<3>")
	)
	(segment
		(start 282.27782 -281.060144)
		(end 273.51736 -281.060144)
		(width 0.14478)
		(layer "In6.Cu")
		(net "M_E_CPU0_SB_CB<3>")
	)
	(arc
		(start 330.22413 -273.763486)
		(mid 329.941174 -273.839663)
		(end 329.658218 -273.763486)
		(width 0.0889)
		(layer "In6.Cu")
		(net "M_E_CPU0_SB_CB<3>")
	)
	(arc
		(start 327.80859 -273.779996)
		(mid 327.685834 -273.735417)
		(end 327.556114 -273.720306)
		(width 0.0889)
		(layer "In6.Cu")
		(net "M_E_CPU0_SB_CB<3>")
	)
	(arc
		(start 328.709782 -273.75866)
		(mid 328.526274 -273.713166)
		(end 328.344022 -273.763486)
		(width 0.0889)
		(layer "In6.Cu")
		(net "M_E_CPU0_SB_CB<3>")
	)
	(arc
		(start 328.344022 -273.763486)
		(mid 328.078397 -273.839396)
		(end 327.80859 -273.779996)
		(width 0.0889)
		(layer "In6.Cu")
		(net "M_E_CPU0_SB_CB<3>")
	)
	(arc
		(start 329.284076 -273.763486)
		(mid 329.00112 -273.839663)
		(end 328.718164 -273.763486)
		(width 0.0889)
		(layer "In6.Cu")
		(net "M_E_CPU0_SB_CB<3>")
	)
	(arc
		(start 330.542646 -273.737324)
		(mid 330.380457 -273.714589)
		(end 330.22413 -273.763486)
		(width 0.0889)
		(layer "In6.Cu")
		(net "M_E_CPU0_SB_CB<3>")
	)
	(arc
		(start 329.658218 -273.763486)
		(mid 329.475967 -273.713136)
		(end 329.292458 -273.75866)
		(width 0.0889)
		(layer "In6.Cu")
		(net "M_E_CPU0_SB_CB<3>")
	)
	(segment
		(start 329.467972 -273.010122)
		(end 329.00112 -273.27606)
		(width 0.10668)
		(layer "F.Cu")
		(net "M_E_CPU0_SB_CB<2>")
	)
	(segment
		(start 276.642322 -279.197308)
		(end 276.642322 -278.918924)
		(width 0.14478)
		(layer "In6.Cu")
		(net "M_E_CPU0_SB_CB<2>")
	)
	(segment
		(start 305.280568 -279.360122)
		(end 301.61992 -279.360122)
		(width 0.14478)
		(layer "In6.Cu")
		(net "M_E_CPU0_SB_CB<2>")
	)
	(segment
		(start 276.805136 -279.360122)
		(end 276.642322 -279.197308)
		(width 0.14478)
		(layer "In6.Cu")
		(net "M_E_CPU0_SB_CB<2>")
	)
	(segment
		(start 276.479508 -278.75611)
		(end 276.248876 -278.75611)
		(width 0.14478)
		(layer "In6.Cu")
		(net "M_E_CPU0_SB_CB<2>")
	)
	(segment
		(start 329.155044 -273.01063)
		(end 329.132692 -272.927318)
		(width 0.0889)
		(layer "In6.Cu")
		(net "M_E_CPU0_SB_CB<2>")
	)
	(segment
		(start 275.923248 -279.360122)
		(end 275.692616 -279.360122)
		(width 0.14478)
		(layer "In6.Cu")
		(net "M_E_CPU0_SB_CB<2>")
	)
	(segment
		(start 313.536584 -271.7546)
		(end 307.181504 -278.10968)
		(width 0.14478)
		(layer "In6.Cu")
		(net "M_E_CPU0_SB_CB<2>")
	)
	(segment
		(start 276.086062 -279.197308)
		(end 275.923248 -279.360122)
		(width 0.14478)
		(layer "In6.Cu")
		(net "M_E_CPU0_SB_CB<2>")
	)
	(segment
		(start 275.136356 -278.75611)
		(end 274.973542 -278.918924)
		(width 0.14478)
		(layer "In6.Cu")
		(net "M_E_CPU0_SB_CB<2>")
	)
	(segment
		(start 293.99992 -279.360122)
		(end 293.149782 -278.509984)
		(width 0.14478)
		(layer "In6.Cu")
		(net "M_E_CPU0_SB_CB<2>")
	)
	(segment
		(start 325.33209 -271.944592)
		(end 324.752208 -271.944592)
		(width 0.0889)
		(layer "In6.Cu")
		(net "M_E_CPU0_SB_CB<2>")
	)
	(segment
		(start 326.949816 -272.944336)
		(end 326.93356 -272.953734)
		(width 0.0889)
		(layer "In6.Cu")
		(net "M_E_CPU0_SB_CB<2>")
	)
	(segment
		(start 290.607496 -279.360122)
		(end 286.410908 -279.360122)
		(width 0.14478)
		(layer "In6.Cu")
		(net "M_E_CPU0_SB_CB<2>")
	)
	(segment
		(start 301.61992 -279.360122)
		(end 300.769782 -278.509984)
		(width 0.14478)
		(layer "In6.Cu")
		(net "M_E_CPU0_SB_CB<2>")
	)
	(segment
		(start 298.747434 -278.509984)
		(end 297.897296 -279.360122)
		(width 0.14478)
		(layer "In6.Cu")
		(net "M_E_CPU0_SB_CB<2>")
	)
	(segment
		(start 274.973542 -278.918924)
		(end 274.973542 -279.197308)
		(width 0.14478)
		(layer "In6.Cu")
		(net "M_E_CPU0_SB_CB<2>")
	)
	(segment
		(start 274.973542 -279.197308)
		(end 274.810728 -279.360122)
		(width 0.14478)
		(layer "In6.Cu")
		(net "M_E_CPU0_SB_CB<2>")
	)
	(segment
		(start 324.752208 -271.944592)
		(end 324.562216 -271.7546)
		(width 0.0889)
		(layer "In6.Cu")
		(net "M_E_CPU0_SB_CB<2>")
	)
	(segment
		(start 326.93356 -272.953734)
		(end 326.914764 -272.964656)
		(width 0.0889)
		(layer "In6.Cu")
		(net "M_E_CPU0_SB_CB<2>")
	)
	(segment
		(start 324.562216 -271.7546)
		(end 323.901054 -271.7546)
		(width 0.0889)
		(layer "In6.Cu")
		(net "M_E_CPU0_SB_CB<2>")
	)
	(segment
		(start 276.086062 -278.918924)
		(end 276.086062 -279.197308)
		(width 0.14478)
		(layer "In6.Cu")
		(net "M_E_CPU0_SB_CB<2>")
	)
	(segment
		(start 323.901054 -271.7546)
		(end 313.536584 -271.7546)
		(width 0.14478)
		(layer "In6.Cu")
		(net "M_E_CPU0_SB_CB<2>")
	)
	(segment
		(start 274.810728 -279.360122)
		(end 273.517106 -279.360122)
		(width 0.14478)
		(layer "In6.Cu")
		(net "M_E_CPU0_SB_CB<2>")
	)
	(segment
		(start 273.517106 -279.360122)
		(end 273.092164 -278.93518)
		(width 0.14478)
		(layer "In6.Cu")
		(net "M_E_CPU0_SB_CB<2>")
	)
	(segment
		(start 328.248264 -272.95348)
		(end 328.239882 -272.948654)
		(width 0.0889)
		(layer "In6.Cu")
		(net "M_E_CPU0_SB_CB<2>")
	)
	(segment
		(start 306.53101 -278.10968)
		(end 305.280568 -279.360122)
		(width 0.14478)
		(layer "In6.Cu")
		(net "M_E_CPU0_SB_CB<2>")
	)
	(segment
		(start 293.149782 -278.509984)
		(end 291.457634 -278.509984)
		(width 0.14478)
		(layer "In6.Cu")
		(net "M_E_CPU0_SB_CB<2>")
	)
	(segment
		(start 276.248876 -278.75611)
		(end 276.086062 -278.918924)
		(width 0.14478)
		(layer "In6.Cu")
		(net "M_E_CPU0_SB_CB<2>")
	)
	(segment
		(start 275.529802 -279.197308)
		(end 275.529802 -278.918924)
		(width 0.14478)
		(layer "In6.Cu")
		(net "M_E_CPU0_SB_CB<2>")
	)
	(segment
		(start 275.366988 -278.75611)
		(end 275.136356 -278.75611)
		(width 0.14478)
		(layer "In6.Cu")
		(net "M_E_CPU0_SB_CB<2>")
	)
	(segment
		(start 326.252332 -272.864834)
		(end 325.33209 -271.944592)
		(width 0.0889)
		(layer "In6.Cu")
		(net "M_E_CPU0_SB_CB<2>")
	)
	(segment
		(start 307.181504 -278.10968)
		(end 306.53101 -278.10968)
		(width 0.14478)
		(layer "In6.Cu")
		(net "M_E_CPU0_SB_CB<2>")
	)
	(segment
		(start 283.355034 -278.509984)
		(end 282.504896 -279.360122)
		(width 0.14478)
		(layer "In6.Cu")
		(net "M_E_CPU0_SB_CB<2>")
	)
	(segment
		(start 286.410908 -279.360122)
		(end 285.56077 -278.509984)
		(width 0.14478)
		(layer "In6.Cu")
		(net "M_E_CPU0_SB_CB<2>")
	)
	(segment
		(start 275.529802 -278.918924)
		(end 275.366988 -278.75611)
		(width 0.14478)
		(layer "In6.Cu")
		(net "M_E_CPU0_SB_CB<2>")
	)
	(segment
		(start 285.56077 -278.509984)
		(end 283.355034 -278.509984)
		(width 0.14478)
		(layer "In6.Cu")
		(net "M_E_CPU0_SB_CB<2>")
	)
	(segment
		(start 275.692616 -279.360122)
		(end 275.529802 -279.197308)
		(width 0.14478)
		(layer "In6.Cu")
		(net "M_E_CPU0_SB_CB<2>")
	)
	(segment
		(start 329.00112 -273.27606)
		(end 329.155044 -273.01063)
		(width 0.0889)
		(layer "In6.Cu")
		(net "M_E_CPU0_SB_CB<2>")
	)
	(segment
		(start 300.769782 -278.509984)
		(end 298.747434 -278.509984)
		(width 0.14478)
		(layer "In6.Cu")
		(net "M_E_CPU0_SB_CB<2>")
	)
	(segment
		(start 282.504896 -279.360122)
		(end 276.805136 -279.360122)
		(width 0.14478)
		(layer "In6.Cu")
		(net "M_E_CPU0_SB_CB<2>")
	)
	(segment
		(start 297.897296 -279.360122)
		(end 293.99992 -279.360122)
		(width 0.14478)
		(layer "In6.Cu")
		(net "M_E_CPU0_SB_CB<2>")
	)
	(segment
		(start 327.317862 -272.959576)
		(end 327.307448 -272.95348)
		(width 0.0889)
		(layer "In6.Cu")
		(net "M_E_CPU0_SB_CB<2>")
	)
	(segment
		(start 291.457634 -278.509984)
		(end 290.607496 -279.360122)
		(width 0.14478)
		(layer "In6.Cu")
		(net "M_E_CPU0_SB_CB<2>")
	)
	(segment
		(start 276.642322 -278.918924)
		(end 276.479508 -278.75611)
		(width 0.14478)
		(layer "In6.Cu")
		(net "M_E_CPU0_SB_CB<2>")
	)
	(arc
		(start 326.367394 -272.95348)
		(mid 326.306989 -272.912886)
		(end 326.252332 -272.864834)
		(width 0.0889)
		(layer "In6.Cu")
		(net "M_E_CPU0_SB_CB<2>")
	)
	(arc
		(start 328.814176 -272.95348)
		(mid 328.53122 -273.029657)
		(end 328.248264 -272.95348)
		(width 0.0889)
		(layer "In6.Cu")
		(net "M_E_CPU0_SB_CB<2>")
	)
	(arc
		(start 327.873614 -272.95348)
		(mid 327.596547 -273.029751)
		(end 327.317862 -272.959576)
		(width 0.0889)
		(layer "In6.Cu")
		(net "M_E_CPU0_SB_CB<2>")
	)
	(arc
		(start 326.914764 -272.964656)
		(mid 326.639627 -273.029955)
		(end 326.367394 -272.95348)
		(width 0.0889)
		(layer "In6.Cu")
		(net "M_E_CPU0_SB_CB<2>")
	)
	(arc
		(start 329.132692 -272.927318)
		(mid 328.970503 -272.904583)
		(end 328.814176 -272.95348)
		(width 0.0889)
		(layer "In6.Cu")
		(net "M_E_CPU0_SB_CB<2>")
	)
	(arc
		(start 327.307448 -272.95348)
		(mid 327.129798 -272.90322)
		(end 326.949816 -272.944336)
		(width 0.0889)
		(layer "In6.Cu")
		(net "M_E_CPU0_SB_CB<2>")
	)
	(arc
		(start 328.239882 -272.948654)
		(mid 328.05612 -272.903038)
		(end 327.873614 -272.95348)
		(width 0.0889)
		(layer "In6.Cu")
		(net "M_E_CPU0_SB_CB<2>")
	)
	(segment
		(start 331.34808 -273.010122)
		(end 330.880974 -273.27606)
		(width 0.10668)
		(layer "F.Cu")
		(net "M_E_CPU0_SB_CB<1>")
	)
	(segment
		(start 305.92395 -279.359868)
		(end 305.073812 -280.210006)
		(width 0.14478)
		(layer "In6.Cu")
		(net "M_E_CPU0_SB_CB<1>")
	)
	(segment
		(start 288.396172 -280.210006)
		(end 286.258508 -280.210006)
		(width 0.14478)
		(layer "In6.Cu")
		(net "M_E_CPU0_SB_CB<1>")
	)
	(segment
		(start 278.373586 -280.410158)
		(end 278.210772 -280.572972)
		(width 0.14478)
		(layer "In6.Cu")
		(net "M_E_CPU0_SB_CB<1>")
	)
	(segment
		(start 279.486106 -280.410158)
		(end 279.323292 -280.572972)
		(width 0.14478)
		(layer "In6.Cu")
		(net "M_E_CPU0_SB_CB<1>")
	)
	(segment
		(start 289.723322 -280.061924)
		(end 289.560508 -279.89911)
		(width 0.14478)
		(layer "In6.Cu")
		(net "M_E_CPU0_SB_CB<1>")
	)
	(segment
		(start 293.960804 -280.210006)
		(end 293.112444 -279.361646)
		(width 0.14478)
		(layer "In6.Cu")
		(net "M_E_CPU0_SB_CB<1>")
	)
	(segment
		(start 289.560508 -279.89911)
		(end 289.329876 -279.89911)
		(width 0.14478)
		(layer "In6.Cu")
		(net "M_E_CPU0_SB_CB<1>")
	)
	(segment
		(start 278.929846 -280.410158)
		(end 278.929846 -279.985978)
		(width 0.14478)
		(layer "In6.Cu")
		(net "M_E_CPU0_SB_CB<1>")
	)
	(segment
		(start 278.373586 -279.985978)
		(end 278.373586 -280.410158)
		(width 0.14478)
		(layer "In6.Cu")
		(net "M_E_CPU0_SB_CB<1>")
	)
	(segment
		(start 300.857666 -279.359868)
		(end 298.540678 -279.359868)
		(width 0.14478)
		(layer "In6.Cu")
		(net "M_E_CPU0_SB_CB<1>")
	)
	(segment
		(start 291.342572 -279.361646)
		(end 290.116768 -280.58745)
		(width 0.14478)
		(layer "In6.Cu")
		(net "M_E_CPU0_SB_CB<1>")
	)
	(segment
		(start 298.540678 -279.359868)
		(end 297.69054 -280.210006)
		(width 0.14478)
		(layer "In6.Cu")
		(net "M_E_CPU0_SB_CB<1>")
	)
	(segment
		(start 325.152004 -272.20926)
		(end 323.901054 -272.20926)
		(width 0.0889)
		(layer "In6.Cu")
		(net "M_E_CPU0_SB_CB<1>")
	)
	(segment
		(start 288.773616 -280.58745)
		(end 288.396172 -280.210006)
		(width 0.14478)
		(layer "In6.Cu")
		(net "M_E_CPU0_SB_CB<1>")
	)
	(segment
		(start 327.873868 -273.59864)
		(end 327.80986 -273.561302)
		(width 0.0889)
		(layer "In6.Cu")
		(net "M_E_CPU0_SB_CB<1>")
	)
	(segment
		(start 278.929846 -279.985978)
		(end 278.767032 -279.823164)
		(width 0.14478)
		(layer "In6.Cu")
		(net "M_E_CPU0_SB_CB<1>")
	)
	(segment
		(start 301.707804 -280.210006)
		(end 300.857666 -279.359868)
		(width 0.14478)
		(layer "In6.Cu")
		(net "M_E_CPU0_SB_CB<1>")
	)
	(segment
		(start 308.103778 -277.823422)
		(end 308.103778 -278.917654)
		(width 0.14478)
		(layer "In6.Cu")
		(net "M_E_CPU0_SB_CB<1>")
	)
	(segment
		(start 313.71794 -272.20926)
		(end 308.103778 -277.823422)
		(width 0.14478)
		(layer "In6.Cu")
		(net "M_E_CPU0_SB_CB<1>")
	)
	(segment
		(start 323.901054 -272.20926)
		(end 313.71794 -272.20926)
		(width 0.14478)
		(layer "In6.Cu")
		(net "M_E_CPU0_SB_CB<1>")
	)
	(segment
		(start 289.167062 -280.061924)
		(end 289.167062 -280.424636)
		(width 0.14478)
		(layer "In6.Cu")
		(net "M_E_CPU0_SB_CB<1>")
	)
	(segment
		(start 281.567636 -280.009854)
		(end 281.404822 -279.84704)
		(width 0.14478)
		(layer "In6.Cu")
		(net "M_E_CPU0_SB_CB<1>")
	)
	(segment
		(start 283.198062 -279.359868)
		(end 281.961082 -280.596848)
		(width 0.14478)
		(layer "In6.Cu")
		(net "M_E_CPU0_SB_CB<1>")
	)
	(segment
		(start 289.723322 -280.424636)
		(end 289.723322 -280.061924)
		(width 0.14478)
		(layer "In6.Cu")
		(net "M_E_CPU0_SB_CB<1>")
	)
	(segment
		(start 290.116768 -280.58745)
		(end 289.886136 -280.58745)
		(width 0.14478)
		(layer "In6.Cu")
		(net "M_E_CPU0_SB_CB<1>")
	)
	(segment
		(start 278.210772 -280.572972)
		(end 277.98014 -280.572972)
		(width 0.14478)
		(layer "In6.Cu")
		(net "M_E_CPU0_SB_CB<1>")
	)
	(segment
		(start 279.09266 -280.572972)
		(end 278.929846 -280.410158)
		(width 0.14478)
		(layer "In6.Cu")
		(net "M_E_CPU0_SB_CB<1>")
	)
	(segment
		(start 281.567636 -280.434034)
		(end 281.567636 -280.009854)
		(width 0.14478)
		(layer "In6.Cu")
		(net "M_E_CPU0_SB_CB<1>")
	)
	(segment
		(start 308.103778 -278.917654)
		(end 307.661564 -279.359868)
		(width 0.14478)
		(layer "In6.Cu")
		(net "M_E_CPU0_SB_CB<1>")
	)
	(segment
		(start 326.45985 -273.517106)
		(end 325.152004 -272.20926)
		(width 0.0889)
		(layer "In6.Cu")
		(net "M_E_CPU0_SB_CB<1>")
	)
	(segment
		(start 327.682352 -273.517106)
		(end 326.45985 -273.517106)
		(width 0.0889)
		(layer "In6.Cu")
		(net "M_E_CPU0_SB_CB<1>")
	)
	(segment
		(start 279.879552 -279.823164)
		(end 279.64892 -279.823164)
		(width 0.14478)
		(layer "In6.Cu")
		(net "M_E_CPU0_SB_CB<1>")
	)
	(segment
		(start 281.404822 -279.84704)
		(end 281.17419 -279.84704)
		(width 0.14478)
		(layer "In6.Cu")
		(net "M_E_CPU0_SB_CB<1>")
	)
	(segment
		(start 280.266394 -280.210006)
		(end 279.879552 -279.823164)
		(width 0.14478)
		(layer "In6.Cu")
		(net "M_E_CPU0_SB_CB<1>")
	)
	(segment
		(start 286.258508 -280.210006)
		(end 285.40837 -279.359868)
		(width 0.14478)
		(layer "In6.Cu")
		(net "M_E_CPU0_SB_CB<1>")
	)
	(segment
		(start 281.961082 -280.596848)
		(end 281.73045 -280.596848)
		(width 0.14478)
		(layer "In6.Cu")
		(net "M_E_CPU0_SB_CB<1>")
	)
	(segment
		(start 277.98014 -280.572972)
		(end 277.192232 -279.785064)
		(width 0.14478)
		(layer "In6.Cu")
		(net "M_E_CPU0_SB_CB<1>")
	)
	(segment
		(start 330.880974 -273.27606)
		(end 330.72705 -273.54149)
		(width 0.0889)
		(layer "In6.Cu")
		(net "M_E_CPU0_SB_CB<1>")
	)
	(segment
		(start 330.128118 -273.59864)
		(end 330.119736 -273.603466)
		(width 0.0889)
		(layer "In6.Cu")
		(net "M_E_CPU0_SB_CB<1>")
	)
	(segment
		(start 289.004248 -280.58745)
		(end 288.773616 -280.58745)
		(width 0.14478)
		(layer "In6.Cu")
		(net "M_E_CPU0_SB_CB<1>")
	)
	(segment
		(start 293.112444 -279.361646)
		(end 291.342572 -279.361646)
		(width 0.14478)
		(layer "In6.Cu")
		(net "M_E_CPU0_SB_CB<1>")
	)
	(segment
		(start 289.886136 -280.58745)
		(end 289.723322 -280.424636)
		(width 0.14478)
		(layer "In6.Cu")
		(net "M_E_CPU0_SB_CB<1>")
	)
	(segment
		(start 289.167062 -280.424636)
		(end 289.004248 -280.58745)
		(width 0.14478)
		(layer "In6.Cu")
		(net "M_E_CPU0_SB_CB<1>")
	)
	(segment
		(start 280.811224 -280.210006)
		(end 280.266394 -280.210006)
		(width 0.14478)
		(layer "In6.Cu")
		(net "M_E_CPU0_SB_CB<1>")
	)
	(segment
		(start 285.40837 -279.359868)
		(end 283.198062 -279.359868)
		(width 0.14478)
		(layer "In6.Cu")
		(net "M_E_CPU0_SB_CB<1>")
	)
	(segment
		(start 297.69054 -280.210006)
		(end 293.960804 -280.210006)
		(width 0.14478)
		(layer "In6.Cu")
		(net "M_E_CPU0_SB_CB<1>")
	)
	(segment
		(start 330.72705 -273.54149)
		(end 330.631038 -273.56689)
		(width 0.0889)
		(layer "In6.Cu")
		(net "M_E_CPU0_SB_CB<1>")
	)
	(segment
		(start 305.073812 -280.210006)
		(end 301.707804 -280.210006)
		(width 0.14478)
		(layer "In6.Cu")
		(net "M_E_CPU0_SB_CB<1>")
	)
	(segment
		(start 279.486106 -279.985978)
		(end 279.486106 -280.410158)
		(width 0.14478)
		(layer "In6.Cu")
		(net "M_E_CPU0_SB_CB<1>")
	)
	(segment
		(start 278.5364 -279.823164)
		(end 278.373586 -279.985978)
		(width 0.14478)
		(layer "In6.Cu")
		(net "M_E_CPU0_SB_CB<1>")
	)
	(segment
		(start 307.661564 -279.359868)
		(end 305.92395 -279.359868)
		(width 0.14478)
		(layer "In6.Cu")
		(net "M_E_CPU0_SB_CB<1>")
	)
	(segment
		(start 289.329876 -279.89911)
		(end 289.167062 -280.061924)
		(width 0.14478)
		(layer "In6.Cu")
		(net "M_E_CPU0_SB_CB<1>")
	)
	(segment
		(start 278.767032 -279.823164)
		(end 278.5364 -279.823164)
		(width 0.14478)
		(layer "In6.Cu")
		(net "M_E_CPU0_SB_CB<1>")
	)
	(segment
		(start 279.323292 -280.572972)
		(end 279.09266 -280.572972)
		(width 0.14478)
		(layer "In6.Cu")
		(net "M_E_CPU0_SB_CB<1>")
	)
	(segment
		(start 279.64892 -279.823164)
		(end 279.486106 -279.985978)
		(width 0.14478)
		(layer "In6.Cu")
		(net "M_E_CPU0_SB_CB<1>")
	)
	(segment
		(start 281.17419 -279.84704)
		(end 280.811224 -280.210006)
		(width 0.14478)
		(layer "In6.Cu")
		(net "M_E_CPU0_SB_CB<1>")
	)
	(segment
		(start 281.73045 -280.596848)
		(end 281.567636 -280.434034)
		(width 0.14478)
		(layer "In6.Cu")
		(net "M_E_CPU0_SB_CB<1>")
	)
	(arc
		(start 330.119736 -273.603466)
		(mid 329.936228 -273.64896)
		(end 329.753976 -273.59864)
		(width 0.0889)
		(layer "In6.Cu")
		(net "M_E_CPU0_SB_CB<1>")
	)
	(arc
		(start 328.248264 -273.59864)
		(mid 328.061066 -273.649022)
		(end 327.873868 -273.59864)
		(width 0.0889)
		(layer "In6.Cu")
		(net "M_E_CPU0_SB_CB<1>")
	)
	(arc
		(start 329.188064 -273.59864)
		(mid 329.00112 -273.648895)
		(end 328.814176 -273.59864)
		(width 0.0889)
		(layer "In6.Cu")
		(net "M_E_CPU0_SB_CB<1>")
	)
	(arc
		(start 327.80986 -273.561302)
		(mid 327.789523 -273.549676)
		(end 327.768966 -273.538442)
		(width 0.0889)
		(layer "In6.Cu")
		(net "M_E_CPU0_SB_CB<1>")
	)
	(arc
		(start 329.753976 -273.59864)
		(mid 329.47102 -273.522463)
		(end 329.188064 -273.59864)
		(width 0.0889)
		(layer "In6.Cu")
		(net "M_E_CPU0_SB_CB<1>")
	)
	(arc
		(start 327.768966 -273.538442)
		(mid 327.726969 -273.522457)
		(end 327.682352 -273.517106)
		(width 0.0889)
		(layer "In6.Cu")
		(net "M_E_CPU0_SB_CB<1>")
	)
	(arc
		(start 328.814176 -273.59864)
		(mid 328.53122 -273.522463)
		(end 328.248264 -273.59864)
		(width 0.0889)
		(layer "In6.Cu")
		(net "M_E_CPU0_SB_CB<1>")
	)
	(arc
		(start 330.631038 -273.56689)
		(mid 330.37583 -273.523413)
		(end 330.128118 -273.59864)
		(width 0.0889)
		(layer "In6.Cu")
		(net "M_E_CPU0_SB_CB<1>")
	)
	(segment
		(start 329.937872 -272.200116)
		(end 329.47102 -272.466054)
		(width 0.10668)
		(layer "F.Cu")
		(net "M_E_CPU0_SB_CB<0>")
	)
	(segment
		(start 302.919892 -278.683974)
		(end 302.919892 -278.334724)
		(width 0.14478)
		(layer "In6.Cu")
		(net "M_E_CPU0_SB_CB<0>")
	)
	(segment
		(start 278.558498 -278.012652)
		(end 278.413718 -277.867872)
		(width 0.14478)
		(layer "In6.Cu")
		(net "M_E_CPU0_SB_CB<0>")
	)
	(segment
		(start 281.40533 -278.83231)
		(end 281.09291 -278.51989)
		(width 0.14478)
		(layer "In6.Cu")
		(net "M_E_CPU0_SB_CB<0>")
	)
	(segment
		(start 278.703278 -278.899112)
		(end 278.558498 -278.754332)
		(width 0.14478)
		(layer "In6.Cu")
		(net "M_E_CPU0_SB_CB<0>")
	)
	(segment
		(start 306.76596 -277.6601)
		(end 306.201318 -277.6601)
		(width 0.14478)
		(layer "In6.Cu")
		(net "M_E_CPU0_SB_CB<0>")
	)
	(segment
		(start 312.09996 -272.330672)
		(end 311.929018 -272.15973)
		(width 0.14478)
		(layer "In6.Cu")
		(net "M_E_CPU0_SB_CB<0>")
	)
	(segment
		(start 311.724294 -272.15973)
		(end 311.530238 -272.353786)
		(width 0.14478)
		(layer "In6.Cu")
		(net "M_E_CPU0_SB_CB<0>")
	)
	(segment
		(start 303.476152 -278.683974)
		(end 303.313338 -278.846788)
		(width 0.14478)
		(layer "In6.Cu")
		(net "M_E_CPU0_SB_CB<0>")
	)
	(segment
		(start 312.498486 -272.136616)
		(end 312.304176 -272.330926)
		(width 0.14478)
		(layer "In6.Cu")
		(net "M_E_CPU0_SB_CB<0>")
	)
	(segment
		(start 302.919892 -278.334724)
		(end 302.757078 -278.17191)
		(width 0.14478)
		(layer "In6.Cu")
		(net "M_E_CPU0_SB_CB<0>")
	)
	(segment
		(start 310.926734 -272.95729)
		(end 310.472328 -273.411696)
		(width 0.14478)
		(layer "In6.Cu")
		(net "M_E_CPU0_SB_CB<0>")
	)
	(segment
		(start 301.970186 -278.846788)
		(end 300.79315 -277.669752)
		(width 0.14478)
		(layer "In6.Cu")
		(net "M_E_CPU0_SB_CB<0>")
	)
	(segment
		(start 291.383466 -277.669752)
		(end 290.246308 -278.80691)
		(width 0.14478)
		(layer "In6.Cu")
		(net "M_E_CPU0_SB_CB<0>")
	)
	(segment
		(start 278.139398 -277.867872)
		(end 277.994618 -278.012652)
		(width 0.14478)
		(layer "In6.Cu")
		(net "M_E_CPU0_SB_CB<0>")
	)
	(segment
		(start 277.994618 -278.012652)
		(end 277.994618 -278.37511)
		(width 0.14478)
		(layer "In6.Cu")
		(net "M_E_CPU0_SB_CB<0>")
	)
	(segment
		(start 297.688 -278.794718)
		(end 297.475656 -278.794718)
		(width 0.14478)
		(layer "In6.Cu")
		(net "M_E_CPU0_SB_CB<0>")
	)
	(segment
		(start 310.472328 -273.411696)
		(end 310.08955 -274.33651)
		(width 0.14478)
		(layer "In6.Cu")
		(net "M_E_CPU0_SB_CB<0>")
	)
	(segment
		(start 293.063422 -277.669752)
		(end 291.383466 -277.669752)
		(width 0.14478)
		(layer "In6.Cu")
		(net "M_E_CPU0_SB_CB<0>")
	)
	(segment
		(start 289.6997 -278.51989)
		(end 287.459928 -278.51989)
		(width 0.14478)
		(layer "In6.Cu")
		(net "M_E_CPU0_SB_CB<0>")
	)
	(segment
		(start 305.35118 -278.510238)
		(end 304.207926 -278.510238)
		(width 0.14478)
		(layer "In6.Cu")
		(net "M_E_CPU0_SB_CB<0>")
	)
	(segment
		(start 312.304176 -272.330926)
		(end 312.09996 -272.330672)
		(width 0.14478)
		(layer "In6.Cu")
		(net "M_E_CPU0_SB_CB<0>")
	)
	(segment
		(start 286.58058 -278.78151)
		(end 285.468822 -277.669752)
		(width 0.14478)
		(layer "In6.Cu")
		(net "M_E_CPU0_SB_CB<0>")
	)
	(segment
		(start 311.530238 -272.353786)
		(end 311.529984 -272.55851)
		(width 0.14478)
		(layer "In6.Cu")
		(net "M_E_CPU0_SB_CB<0>")
	)
	(segment
		(start 277.62708 -278.51989)
		(end 277.192232 -278.085042)
		(width 0.14478)
		(layer "In6.Cu")
		(net "M_E_CPU0_SB_CB<0>")
	)
	(segment
		(start 289.98672 -278.80691)
		(end 289.6997 -278.51989)
		(width 0.14478)
		(layer "In6.Cu")
		(net "M_E_CPU0_SB_CB<0>")
	)
	(segment
		(start 311.700926 -272.934176)
		(end 311.506616 -273.128486)
		(width 0.14478)
		(layer "In6.Cu")
		(net "M_E_CPU0_SB_CB<0>")
	)
	(segment
		(start 290.246308 -278.80691)
		(end 289.98672 -278.80691)
		(width 0.14478)
		(layer "In6.Cu")
		(net "M_E_CPU0_SB_CB<0>")
	)
	(segment
		(start 306.201318 -277.6601)
		(end 305.35118 -278.510238)
		(width 0.14478)
		(layer "In6.Cu")
		(net "M_E_CPU0_SB_CB<0>")
	)
	(segment
		(start 303.476152 -278.334724)
		(end 303.476152 -278.683974)
		(width 0.14478)
		(layer "In6.Cu")
		(net "M_E_CPU0_SB_CB<0>")
	)
	(segment
		(start 287.198308 -278.78151)
		(end 286.58058 -278.78151)
		(width 0.14478)
		(layer "In6.Cu")
		(net "M_E_CPU0_SB_CB<0>")
	)
	(segment
		(start 311.131458 -272.95729)
		(end 310.926734 -272.95729)
		(width 0.14478)
		(layer "In6.Cu")
		(net "M_E_CPU0_SB_CB<0>")
	)
	(segment
		(start 310.08955 -274.33651)
		(end 306.76596 -277.6601)
		(width 0.14478)
		(layer "In6.Cu")
		(net "M_E_CPU0_SB_CB<0>")
	)
	(segment
		(start 323.901054 -271.29994)
		(end 312.584084 -271.29994)
		(width 0.14478)
		(layer "In6.Cu")
		(net "M_E_CPU0_SB_CB<0>")
	)
	(segment
		(start 324.840854 -271.74571)
		(end 324.395084 -271.29994)
		(width 0.0889)
		(layer "In6.Cu")
		(net "M_E_CPU0_SB_CB<0>")
	)
	(segment
		(start 297.191176 -278.510238)
		(end 296.931588 -278.510238)
		(width 0.14478)
		(layer "In6.Cu")
		(net "M_E_CPU0_SB_CB<0>")
	)
	(segment
		(start 277.849838 -278.51989)
		(end 277.62708 -278.51989)
		(width 0.14478)
		(layer "In6.Cu")
		(net "M_E_CPU0_SB_CB<0>")
	)
	(segment
		(start 311.529984 -272.55851)
		(end 311.700926 -272.729452)
		(width 0.14478)
		(layer "In6.Cu")
		(net "M_E_CPU0_SB_CB<0>")
	)
	(segment
		(start 283.534866 -277.669752)
		(end 282.69438 -278.510238)
		(width 0.14478)
		(layer "In6.Cu")
		(net "M_E_CPU0_SB_CB<0>")
	)
	(segment
		(start 303.313338 -278.846788)
		(end 303.082706 -278.846788)
		(width 0.14478)
		(layer "In6.Cu")
		(net "M_E_CPU0_SB_CB<0>")
	)
	(segment
		(start 327.411588 -272.79346)
		(end 327.403206 -272.788634)
		(width 0.0889)
		(layer "In6.Cu")
		(net "M_E_CPU0_SB_CB<0>")
	)
	(segment
		(start 287.459928 -278.51989)
		(end 287.198308 -278.78151)
		(width 0.14478)
		(layer "In6.Cu")
		(net "M_E_CPU0_SB_CB<0>")
	)
	(segment
		(start 311.506616 -273.128486)
		(end 311.3024 -273.128232)
		(width 0.14478)
		(layer "In6.Cu")
		(net "M_E_CPU0_SB_CB<0>")
	)
	(segment
		(start 297.475656 -278.794718)
		(end 297.191176 -278.510238)
		(width 0.14478)
		(layer "In6.Cu")
		(net "M_E_CPU0_SB_CB<0>")
	)
	(segment
		(start 302.200818 -278.846788)
		(end 301.970186 -278.846788)
		(width 0.14478)
		(layer "In6.Cu")
		(net "M_E_CPU0_SB_CB<0>")
	)
	(segment
		(start 296.931588 -278.510238)
		(end 296.634916 -278.80691)
		(width 0.14478)
		(layer "In6.Cu")
		(net "M_E_CPU0_SB_CB<0>")
	)
	(segment
		(start 312.327544 -271.76095)
		(end 312.498486 -271.931892)
		(width 0.14478)
		(layer "In6.Cu")
		(net "M_E_CPU0_SB_CB<0>")
	)
	(segment
		(start 294.22598 -278.83231)
		(end 293.063422 -277.669752)
		(width 0.14478)
		(layer "In6.Cu")
		(net "M_E_CPU0_SB_CB<0>")
	)
	(segment
		(start 325.365618 -271.74571)
		(end 324.840854 -271.74571)
		(width 0.0889)
		(layer "In6.Cu")
		(net "M_E_CPU0_SB_CB<0>")
	)
	(segment
		(start 298.812966 -277.669752)
		(end 297.688 -278.794718)
		(width 0.14478)
		(layer "In6.Cu")
		(net "M_E_CPU0_SB_CB<0>")
	)
	(segment
		(start 304.207926 -278.510238)
		(end 303.869598 -278.17191)
		(width 0.14478)
		(layer "In6.Cu")
		(net "M_E_CPU0_SB_CB<0>")
	)
	(segment
		(start 303.869598 -278.17191)
		(end 303.638966 -278.17191)
		(width 0.14478)
		(layer "In6.Cu")
		(net "M_E_CPU0_SB_CB<0>")
	)
	(segment
		(start 296.088308 -278.51989)
		(end 294.772588 -278.51989)
		(width 0.14478)
		(layer "In6.Cu")
		(net "M_E_CPU0_SB_CB<0>")
	)
	(segment
		(start 302.526446 -278.17191)
		(end 302.363632 -278.334724)
		(width 0.14478)
		(layer "In6.Cu")
		(net "M_E_CPU0_SB_CB<0>")
	)
	(segment
		(start 326.84339 -272.785078)
		(end 326.819514 -272.798794)
		(width 0.0889)
		(layer "In6.Cu")
		(net "M_E_CPU0_SB_CB<0>")
	)
	(segment
		(start 312.327798 -271.556226)
		(end 312.327544 -271.76095)
		(width 0.14478)
		(layer "In6.Cu")
		(net "M_E_CPU0_SB_CB<0>")
	)
	(segment
		(start 311.700926 -272.729452)
		(end 311.700926 -272.934176)
		(width 0.14478)
		(layer "In6.Cu")
		(net "M_E_CPU0_SB_CB<0>")
	)
	(segment
		(start 300.79315 -277.669752)
		(end 298.812966 -277.669752)
		(width 0.14478)
		(layer "In6.Cu")
		(net "M_E_CPU0_SB_CB<0>")
	)
	(segment
		(start 329.317096 -272.731484)
		(end 329.221084 -272.756884)
		(width 0.0889)
		(layer "In6.Cu")
		(net "M_E_CPU0_SB_CB<0>")
	)
	(segment
		(start 329.47102 -272.466054)
		(end 329.317096 -272.731484)
		(width 0.0889)
		(layer "In6.Cu")
		(net "M_E_CPU0_SB_CB<0>")
	)
	(segment
		(start 311.3024 -273.128232)
		(end 311.131458 -272.95729)
		(width 0.14478)
		(layer "In6.Cu")
		(net "M_E_CPU0_SB_CB<0>")
	)
	(segment
		(start 303.638966 -278.17191)
		(end 303.476152 -278.334724)
		(width 0.14478)
		(layer "In6.Cu")
		(net "M_E_CPU0_SB_CB<0>")
	)
	(segment
		(start 312.584084 -271.29994)
		(end 312.327798 -271.556226)
		(width 0.14478)
		(layer "In6.Cu")
		(net "M_E_CPU0_SB_CB<0>")
	)
	(segment
		(start 328.718164 -272.788634)
		(end 328.709782 -272.79346)
		(width 0.0889)
		(layer "In6.Cu")
		(net "M_E_CPU0_SB_CB<0>")
	)
	(segment
		(start 279.35682 -278.51989)
		(end 278.977598 -278.899112)
		(width 0.14478)
		(layer "In6.Cu")
		(net "M_E_CPU0_SB_CB<0>")
	)
	(segment
		(start 312.498486 -271.931892)
		(end 312.498486 -272.136616)
		(width 0.14478)
		(layer "In6.Cu")
		(net "M_E_CPU0_SB_CB<0>")
	)
	(segment
		(start 277.994618 -278.37511)
		(end 277.849838 -278.51989)
		(width 0.14478)
		(layer "In6.Cu")
		(net "M_E_CPU0_SB_CB<0>")
	)
	(segment
		(start 296.375328 -278.80691)
		(end 296.088308 -278.51989)
		(width 0.14478)
		(layer "In6.Cu")
		(net "M_E_CPU0_SB_CB<0>")
	)
	(segment
		(start 324.395084 -271.29994)
		(end 323.901054 -271.29994)
		(width 0.0889)
		(layer "In6.Cu")
		(net "M_E_CPU0_SB_CB<0>")
	)
	(segment
		(start 328.344022 -272.788634)
		(end 328.333608 -272.782538)
		(width 0.0889)
		(layer "In6.Cu")
		(net "M_E_CPU0_SB_CB<0>")
	)
	(segment
		(start 294.460168 -278.83231)
		(end 294.22598 -278.83231)
		(width 0.14478)
		(layer "In6.Cu")
		(net "M_E_CPU0_SB_CB<0>")
	)
	(segment
		(start 282.69438 -278.510238)
		(end 282.330398 -278.510238)
		(width 0.14478)
		(layer "In6.Cu")
		(net "M_E_CPU0_SB_CB<0>")
	)
	(segment
		(start 302.363632 -278.334724)
		(end 302.363632 -278.683974)
		(width 0.14478)
		(layer "In6.Cu")
		(net "M_E_CPU0_SB_CB<0>")
	)
	(segment
		(start 302.363632 -278.683974)
		(end 302.200818 -278.846788)
		(width 0.14478)
		(layer "In6.Cu")
		(net "M_E_CPU0_SB_CB<0>")
	)
	(segment
		(start 311.929018 -272.15973)
		(end 311.724294 -272.15973)
		(width 0.14478)
		(layer "In6.Cu")
		(net "M_E_CPU0_SB_CB<0>")
	)
	(segment
		(start 302.757078 -278.17191)
		(end 302.526446 -278.17191)
		(width 0.14478)
		(layer "In6.Cu")
		(net "M_E_CPU0_SB_CB<0>")
	)
	(segment
		(start 294.772588 -278.51989)
		(end 294.460168 -278.83231)
		(width 0.14478)
		(layer "In6.Cu")
		(net "M_E_CPU0_SB_CB<0>")
	)
	(segment
		(start 278.558498 -278.754332)
		(end 278.558498 -278.012652)
		(width 0.14478)
		(layer "In6.Cu")
		(net "M_E_CPU0_SB_CB<0>")
	)
	(segment
		(start 278.977598 -278.899112)
		(end 278.703278 -278.899112)
		(width 0.14478)
		(layer "In6.Cu")
		(net "M_E_CPU0_SB_CB<0>")
	)
	(segment
		(start 282.330398 -278.510238)
		(end 282.008326 -278.83231)
		(width 0.14478)
		(layer "In6.Cu")
		(net "M_E_CPU0_SB_CB<0>")
	)
	(segment
		(start 285.468822 -277.669752)
		(end 283.534866 -277.669752)
		(width 0.14478)
		(layer "In6.Cu")
		(net "M_E_CPU0_SB_CB<0>")
	)
	(segment
		(start 278.413718 -277.867872)
		(end 278.139398 -277.867872)
		(width 0.14478)
		(layer "In6.Cu")
		(net "M_E_CPU0_SB_CB<0>")
	)
	(segment
		(start 282.008326 -278.83231)
		(end 281.40533 -278.83231)
		(width 0.14478)
		(layer "In6.Cu")
		(net "M_E_CPU0_SB_CB<0>")
	)
	(segment
		(start 303.082706 -278.846788)
		(end 302.919892 -278.683974)
		(width 0.14478)
		(layer "In6.Cu")
		(net "M_E_CPU0_SB_CB<0>")
	)
	(segment
		(start 281.09291 -278.51989)
		(end 279.35682 -278.51989)
		(width 0.14478)
		(layer "In6.Cu")
		(net "M_E_CPU0_SB_CB<0>")
	)
	(segment
		(start 296.634916 -278.80691)
		(end 296.375328 -278.80691)
		(width 0.14478)
		(layer "In6.Cu")
		(net "M_E_CPU0_SB_CB<0>")
	)
	(segment
		(start 326.425814 -272.75663)
		(end 325.445882 -271.77873)
		(width 0.0889)
		(layer "In6.Cu")
		(net "M_E_CPU0_SB_CB<0>")
	)
	(arc
		(start 326.49922 -272.807176)
		(mid 326.460188 -272.785284)
		(end 326.425814 -272.75663)
		(width 0.0889)
		(layer "In6.Cu")
		(net "M_E_CPU0_SB_CB<0>")
	)
	(arc
		(start 329.221084 -272.756884)
		(mid 328.965876 -272.713407)
		(end 328.718164 -272.788634)
		(width 0.0889)
		(layer "In6.Cu")
		(net "M_E_CPU0_SB_CB<0>")
	)
	(arc
		(start 327.403206 -272.788634)
		(mid 327.123778 -272.712468)
		(end 326.84339 -272.785078)
		(width 0.0889)
		(layer "In6.Cu")
		(net "M_E_CPU0_SB_CB<0>")
	)
	(arc
		(start 327.777856 -272.788634)
		(mid 327.595351 -272.839111)
		(end 327.411588 -272.79346)
		(width 0.0889)
		(layer "In6.Cu")
		(net "M_E_CPU0_SB_CB<0>")
	)
	(arc
		(start 328.333608 -272.782538)
		(mid 328.054922 -272.712318)
		(end 327.777856 -272.788634)
		(width 0.0889)
		(layer "In6.Cu")
		(net "M_E_CPU0_SB_CB<0>")
	)
	(arc
		(start 325.445882 -271.77873)
		(mid 325.409027 -271.754261)
		(end 325.365618 -271.74571)
		(width 0.0889)
		(layer "In6.Cu")
		(net "M_E_CPU0_SB_CB<0>")
	)
	(arc
		(start 326.819514 -272.798794)
		(mid 326.660317 -272.839112)
		(end 326.49922 -272.807176)
		(width 0.0889)
		(layer "In6.Cu")
		(net "M_E_CPU0_SB_CB<0>")
	)
	(arc
		(start 328.709782 -272.79346)
		(mid 328.526274 -272.838954)
		(end 328.344022 -272.788634)
		(width 0.0889)
		(layer "In6.Cu")
		(net "M_E_CPU0_SB_CB<0>")
	)
	(segment
		(start 329.937872 -264.100056)
		(end 329.47102 -264.365994)
		(width 0.10668)
		(layer "F.Cu")
		(net "M_E_CPU0_SB_CA<6>")
	)
	(segment
		(start 308.946296 -264.61974)
		(end 307.805836 -265.7602)
		(width 0.14478)
		(layer "In6.Cu")
		(net "M_E_CPU0_SB_CA<6>")
	)
	(segment
		(start 278.000206 -265.377168)
		(end 277.192232 -266.185142)
		(width 0.14478)
		(layer "In6.Cu")
		(net "M_E_CPU0_SB_CA<6>")
	)
	(segment
		(start 278.787098 -266.131548)
		(end 278.556466 -266.131548)
		(width 0.14478)
		(layer "In6.Cu")
		(net "M_E_CPU0_SB_CA<6>")
	)
	(segment
		(start 278.556466 -266.131548)
		(end 278.393652 -265.968734)
		(width 0.14478)
		(layer "In6.Cu")
		(net "M_E_CPU0_SB_CA<6>")
	)
	(segment
		(start 324.199504 -264.61974)
		(end 323.908674 -264.61974)
		(width 0.0889)
		(layer "In6.Cu")
		(net "M_E_CPU0_SB_CA<6>")
	)
	(segment
		(start 282.473908 -266.13231)
		(end 282.311094 -265.969496)
		(width 0.14478)
		(layer "In6.Cu")
		(net "M_E_CPU0_SB_CA<6>")
	)
	(segment
		(start 325.709026 -264.612882)
		(end 325.399654 -264.30351)
		(width 0.0889)
		(layer "In6.Cu")
		(net "M_E_CPU0_SB_CA<6>")
	)
	(segment
		(start 282.70454 -266.13231)
		(end 282.473908 -266.13231)
		(width 0.14478)
		(layer "In6.Cu")
		(net "M_E_CPU0_SB_CA<6>")
	)
	(segment
		(start 281.754834 -265.550904)
		(end 281.754834 -265.969496)
		(width 0.14478)
		(layer "In6.Cu")
		(net "M_E_CPU0_SB_CA<6>")
	)
	(segment
		(start 326.182482 -264.612882)
		(end 325.709026 -264.612882)
		(width 0.0889)
		(layer "In6.Cu")
		(net "M_E_CPU0_SB_CA<6>")
	)
	(segment
		(start 279.899618 -266.131548)
		(end 279.668986 -266.131548)
		(width 0.14478)
		(layer "In6.Cu")
		(net "M_E_CPU0_SB_CA<6>")
	)
	(segment
		(start 282.311094 -265.550904)
		(end 282.14828 -265.38809)
		(width 0.14478)
		(layer "In6.Cu")
		(net "M_E_CPU0_SB_CA<6>")
	)
	(segment
		(start 324.515734 -264.30351)
		(end 324.199504 -264.61974)
		(width 0.0889)
		(layer "In6.Cu")
		(net "M_E_CPU0_SB_CA<6>")
	)
	(segment
		(start 307.805836 -265.7602)
		(end 283.07665 -265.7602)
		(width 0.14478)
		(layer "In6.Cu")
		(net "M_E_CPU0_SB_CA<6>")
	)
	(segment
		(start 281.361388 -266.13231)
		(end 280.989278 -265.7602)
		(width 0.14478)
		(layer "In6.Cu")
		(net "M_E_CPU0_SB_CA<6>")
	)
	(segment
		(start 281.917648 -265.38809)
		(end 281.754834 -265.550904)
		(width 0.14478)
		(layer "In6.Cu")
		(net "M_E_CPU0_SB_CA<6>")
	)
	(segment
		(start 279.506172 -265.968734)
		(end 279.506172 -265.539982)
		(width 0.14478)
		(layer "In6.Cu")
		(net "M_E_CPU0_SB_CA<6>")
	)
	(segment
		(start 323.908674 -264.61974)
		(end 308.946296 -264.61974)
		(width 0.14478)
		(layer "In6.Cu")
		(net "M_E_CPU0_SB_CA<6>")
	)
	(segment
		(start 278.230838 -265.377168)
		(end 278.000206 -265.377168)
		(width 0.14478)
		(layer "In6.Cu")
		(net "M_E_CPU0_SB_CA<6>")
	)
	(segment
		(start 326.476106 -264.695432)
		(end 326.464422 -264.688574)
		(width 0.0889)
		(layer "In6.Cu")
		(net "M_E_CPU0_SB_CA<6>")
	)
	(segment
		(start 279.112726 -265.377168)
		(end 278.949912 -265.539982)
		(width 0.14478)
		(layer "In6.Cu")
		(net "M_E_CPU0_SB_CA<6>")
	)
	(segment
		(start 278.949912 -265.968734)
		(end 278.787098 -266.131548)
		(width 0.14478)
		(layer "In6.Cu")
		(net "M_E_CPU0_SB_CA<6>")
	)
	(segment
		(start 283.07665 -265.7602)
		(end 282.70454 -266.13231)
		(width 0.14478)
		(layer "In6.Cu")
		(net "M_E_CPU0_SB_CA<6>")
	)
	(segment
		(start 282.14828 -265.38809)
		(end 281.917648 -265.38809)
		(width 0.14478)
		(layer "In6.Cu")
		(net "M_E_CPU0_SB_CA<6>")
	)
	(segment
		(start 280.989278 -265.7602)
		(end 280.270966 -265.7602)
		(width 0.14478)
		(layer "In6.Cu")
		(net "M_E_CPU0_SB_CA<6>")
	)
	(segment
		(start 281.754834 -265.969496)
		(end 281.59202 -266.13231)
		(width 0.14478)
		(layer "In6.Cu")
		(net "M_E_CPU0_SB_CA<6>")
	)
	(segment
		(start 280.270966 -265.7602)
		(end 279.899618 -266.131548)
		(width 0.14478)
		(layer "In6.Cu")
		(net "M_E_CPU0_SB_CA<6>")
	)
	(segment
		(start 329.317096 -264.631424)
		(end 329.221084 -264.656824)
		(width 0.0889)
		(layer "In6.Cu")
		(net "M_E_CPU0_SB_CA<6>")
	)
	(segment
		(start 327.788778 -264.682478)
		(end 327.778364 -264.688574)
		(width 0.0889)
		(layer "In6.Cu")
		(net "M_E_CPU0_SB_CA<6>")
	)
	(segment
		(start 329.47102 -264.365994)
		(end 329.317096 -264.631424)
		(width 0.0889)
		(layer "In6.Cu")
		(net "M_E_CPU0_SB_CA<6>")
	)
	(segment
		(start 279.668986 -266.131548)
		(end 279.506172 -265.968734)
		(width 0.14478)
		(layer "In6.Cu")
		(net "M_E_CPU0_SB_CA<6>")
	)
	(segment
		(start 278.393652 -265.968734)
		(end 278.393652 -265.539982)
		(width 0.14478)
		(layer "In6.Cu")
		(net "M_E_CPU0_SB_CA<6>")
	)
	(segment
		(start 282.311094 -265.969496)
		(end 282.311094 -265.550904)
		(width 0.14478)
		(layer "In6.Cu")
		(net "M_E_CPU0_SB_CA<6>")
	)
	(segment
		(start 279.506172 -265.539982)
		(end 279.343358 -265.377168)
		(width 0.14478)
		(layer "In6.Cu")
		(net "M_E_CPU0_SB_CA<6>")
	)
	(segment
		(start 279.343358 -265.377168)
		(end 279.112726 -265.377168)
		(width 0.14478)
		(layer "In6.Cu")
		(net "M_E_CPU0_SB_CA<6>")
	)
	(segment
		(start 278.949912 -265.539982)
		(end 278.949912 -265.968734)
		(width 0.14478)
		(layer "In6.Cu")
		(net "M_E_CPU0_SB_CA<6>")
	)
	(segment
		(start 327.404476 -264.688574)
		(end 327.394062 -264.682478)
		(width 0.0889)
		(layer "In6.Cu")
		(net "M_E_CPU0_SB_CA<6>")
	)
	(segment
		(start 328.718164 -264.688574)
		(end 328.709782 -264.6934)
		(width 0.0889)
		(layer "In6.Cu")
		(net "M_E_CPU0_SB_CA<6>")
	)
	(segment
		(start 278.393652 -265.539982)
		(end 278.230838 -265.377168)
		(width 0.14478)
		(layer "In6.Cu")
		(net "M_E_CPU0_SB_CA<6>")
	)
	(segment
		(start 325.399654 -264.30351)
		(end 324.515734 -264.30351)
		(width 0.0889)
		(layer "In6.Cu")
		(net "M_E_CPU0_SB_CA<6>")
	)
	(segment
		(start 281.59202 -266.13231)
		(end 281.361388 -266.13231)
		(width 0.14478)
		(layer "In6.Cu")
		(net "M_E_CPU0_SB_CA<6>")
	)
	(arc
		(start 328.709782 -264.6934)
		(mid 328.526274 -264.738894)
		(end 328.344022 -264.688574)
		(width 0.0889)
		(layer "In6.Cu")
		(net "M_E_CPU0_SB_CA<6>")
	)
	(arc
		(start 327.394062 -264.682478)
		(mid 327.115376 -264.612258)
		(end 326.83831 -264.688574)
		(width 0.0889)
		(layer "In6.Cu")
		(net "M_E_CPU0_SB_CA<6>")
	)
	(arc
		(start 329.221084 -264.656824)
		(mid 328.965876 -264.613347)
		(end 328.718164 -264.688574)
		(width 0.0889)
		(layer "In6.Cu")
		(net "M_E_CPU0_SB_CA<6>")
	)
	(arc
		(start 327.778364 -264.688574)
		(mid 327.59142 -264.738829)
		(end 327.404476 -264.688574)
		(width 0.0889)
		(layer "In6.Cu")
		(net "M_E_CPU0_SB_CA<6>")
	)
	(arc
		(start 328.344022 -264.688574)
		(mid 328.067209 -264.612431)
		(end 327.788778 -264.682478)
		(width 0.0889)
		(layer "In6.Cu")
		(net "M_E_CPU0_SB_CA<6>")
	)
	(arc
		(start 326.83831 -264.688574)
		(mid 326.658105 -264.738891)
		(end 326.476106 -264.695432)
		(width 0.0889)
		(layer "In6.Cu")
		(net "M_E_CPU0_SB_CA<6>")
	)
	(arc
		(start 326.464422 -264.688574)
		(mid 326.32844 -264.632141)
		(end 326.182482 -264.612882)
		(width 0.0889)
		(layer "In6.Cu")
		(net "M_E_CPU0_SB_CA<6>")
	)
	(segment
		(start 330.877926 -264.100056)
		(end 330.411074 -264.365994)
		(width 0.10668)
		(layer "F.Cu")
		(net "M_E_CPU0_SB_CA<5>")
	)
	(segment
		(start 330.564998 -264.100564)
		(end 330.542646 -264.017252)
		(width 0.0889)
		(layer "In6.Cu")
		(net "M_E_CPU0_SB_CA<5>")
	)
	(segment
		(start 328.718164 -264.043414)
		(end 328.709782 -264.038588)
		(width 0.0889)
		(layer "In6.Cu")
		(net "M_E_CPU0_SB_CA<5>")
	)
	(segment
		(start 329.292458 -264.038588)
		(end 329.284076 -264.043414)
		(width 0.0889)
		(layer "In6.Cu")
		(net "M_E_CPU0_SB_CA<5>")
	)
	(segment
		(start 327.57364 -264.00887)
		(end 324.279514 -264.00887)
		(width 0.0889)
		(layer "In6.Cu")
		(net "M_E_CPU0_SB_CA<5>")
	)
	(segment
		(start 330.411074 -264.365994)
		(end 330.564998 -264.100564)
		(width 0.0889)
		(layer "In6.Cu")
		(net "M_E_CPU0_SB_CA<5>")
	)
	(segment
		(start 273.517106 -264.910062)
		(end 273.092164 -265.335004)
		(width 0.14478)
		(layer "In6.Cu")
		(net "M_E_CPU0_SB_CA<5>")
	)
	(segment
		(start 324.279514 -264.00887)
		(end 324.123304 -264.16508)
		(width 0.0889)
		(layer "In6.Cu")
		(net "M_E_CPU0_SB_CA<5>")
	)
	(segment
		(start 324.123304 -264.16508)
		(end 323.908674 -264.16508)
		(width 0.0889)
		(layer "In6.Cu")
		(net "M_E_CPU0_SB_CA<5>")
	)
	(segment
		(start 308.54269 -264.16508)
		(end 307.797708 -264.910062)
		(width 0.14478)
		(layer "In6.Cu")
		(net "M_E_CPU0_SB_CA<5>")
	)
	(segment
		(start 323.908674 -264.16508)
		(end 308.54269 -264.16508)
		(width 0.14478)
		(layer "In6.Cu")
		(net "M_E_CPU0_SB_CA<5>")
	)
	(segment
		(start 307.797708 -264.910062)
		(end 273.517106 -264.910062)
		(width 0.14478)
		(layer "In6.Cu")
		(net "M_E_CPU0_SB_CA<5>")
	)
	(arc
		(start 327.817226 -264.064242)
		(mid 327.698538 -264.022899)
		(end 327.57364 -264.00887)
		(width 0.0889)
		(layer "In6.Cu")
		(net "M_E_CPU0_SB_CA<5>")
	)
	(arc
		(start 329.658218 -264.043414)
		(mid 329.475967 -263.993064)
		(end 329.292458 -264.038588)
		(width 0.0889)
		(layer "In6.Cu")
		(net "M_E_CPU0_SB_CA<5>")
	)
	(arc
		(start 328.344022 -264.043414)
		(mid 328.083221 -264.119155)
		(end 327.817226 -264.064242)
		(width 0.0889)
		(layer "In6.Cu")
		(net "M_E_CPU0_SB_CA<5>")
	)
	(arc
		(start 330.542646 -264.017252)
		(mid 330.380457 -263.994517)
		(end 330.22413 -264.043414)
		(width 0.0889)
		(layer "In6.Cu")
		(net "M_E_CPU0_SB_CA<5>")
	)
	(arc
		(start 329.284076 -264.043414)
		(mid 329.00112 -264.119591)
		(end 328.718164 -264.043414)
		(width 0.0889)
		(layer "In6.Cu")
		(net "M_E_CPU0_SB_CA<5>")
	)
	(arc
		(start 328.709782 -264.038588)
		(mid 328.526274 -263.993094)
		(end 328.344022 -264.043414)
		(width 0.0889)
		(layer "In6.Cu")
		(net "M_E_CPU0_SB_CA<5>")
	)
	(arc
		(start 330.22413 -264.043414)
		(mid 329.941174 -264.119591)
		(end 329.658218 -264.043414)
		(width 0.0889)
		(layer "In6.Cu")
		(net "M_E_CPU0_SB_CA<5>")
	)
	(segment
		(start 331.34808 -263.29005)
		(end 330.880974 -263.555988)
		(width 0.10668)
		(layer "F.Cu")
		(net "M_E_CPU0_SB_CA<4>")
	)
	(segment
		(start 278.950928 -264.270744)
		(end 278.788114 -264.433558)
		(width 0.14478)
		(layer "In6.Cu")
		(net "M_E_CPU0_SB_CA<4>")
	)
	(segment
		(start 283.82595 -264.37971)
		(end 283.506164 -264.059924)
		(width 0.14478)
		(layer "In6.Cu")
		(net "M_E_CPU0_SB_CA<4>")
	)
	(segment
		(start 281.837384 -264.37971)
		(end 281.60091 -264.37971)
		(width 0.14478)
		(layer "In6.Cu")
		(net "M_E_CPU0_SB_CA<4>")
	)
	(segment
		(start 282.949904 -264.37971)
		(end 282.71343 -264.37971)
		(width 0.14478)
		(layer "In6.Cu")
		(net "M_E_CPU0_SB_CA<4>")
	)
	(segment
		(start 282.71343 -264.37971)
		(end 282.393644 -264.059924)
		(width 0.14478)
		(layer "In6.Cu")
		(net "M_E_CPU0_SB_CA<4>")
	)
	(segment
		(start 284.062424 -264.37971)
		(end 283.82595 -264.37971)
		(width 0.14478)
		(layer "In6.Cu")
		(net "M_E_CPU0_SB_CA<4>")
	)
	(segment
		(start 278.001222 -263.67613)
		(end 277.192232 -264.48512)
		(width 0.14478)
		(layer "In6.Cu")
		(net "M_E_CPU0_SB_CA<4>")
	)
	(segment
		(start 282.15717 -264.059924)
		(end 281.837384 -264.37971)
		(width 0.14478)
		(layer "In6.Cu")
		(net "M_E_CPU0_SB_CA<4>")
	)
	(segment
		(start 279.507188 -263.838944)
		(end 279.344374 -263.67613)
		(width 0.14478)
		(layer "In6.Cu")
		(net "M_E_CPU0_SB_CA<4>")
	)
	(segment
		(start 327.44283 -263.71042)
		(end 323.887084 -263.71042)
		(width 0.0889)
		(layer "In6.Cu")
		(net "M_E_CPU0_SB_CA<4>")
	)
	(segment
		(start 281.60091 -264.37971)
		(end 281.281124 -264.059924)
		(width 0.14478)
		(layer "In6.Cu")
		(net "M_E_CPU0_SB_CA<4>")
	)
	(segment
		(start 283.506164 -264.059924)
		(end 283.26969 -264.059924)
		(width 0.14478)
		(layer "In6.Cu")
		(net "M_E_CPU0_SB_CA<4>")
	)
	(segment
		(start 278.394668 -263.838944)
		(end 278.231854 -263.67613)
		(width 0.14478)
		(layer "In6.Cu")
		(net "M_E_CPU0_SB_CA<4>")
	)
	(segment
		(start 278.788114 -264.433558)
		(end 278.557482 -264.433558)
		(width 0.14478)
		(layer "In6.Cu")
		(net "M_E_CPU0_SB_CA<4>")
	)
	(segment
		(start 330.880974 -263.555988)
		(end 330.72705 -263.821418)
		(width 0.0889)
		(layer "In6.Cu")
		(net "M_E_CPU0_SB_CA<4>")
	)
	(segment
		(start 278.557482 -264.433558)
		(end 278.394668 -264.270744)
		(width 0.14478)
		(layer "In6.Cu")
		(net "M_E_CPU0_SB_CA<4>")
	)
	(segment
		(start 279.344374 -263.67613)
		(end 279.113742 -263.67613)
		(width 0.14478)
		(layer "In6.Cu")
		(net "M_E_CPU0_SB_CA<4>")
	)
	(segment
		(start 279.900634 -264.433558)
		(end 279.670002 -264.433558)
		(width 0.14478)
		(layer "In6.Cu")
		(net "M_E_CPU0_SB_CA<4>")
	)
	(segment
		(start 330.128118 -263.878568)
		(end 330.119736 -263.883394)
		(width 0.0889)
		(layer "In6.Cu")
		(net "M_E_CPU0_SB_CA<4>")
	)
	(segment
		(start 282.393644 -264.059924)
		(end 282.15717 -264.059924)
		(width 0.14478)
		(layer "In6.Cu")
		(net "M_E_CPU0_SB_CA<4>")
	)
	(segment
		(start 330.72705 -263.821418)
		(end 330.631038 -263.846818)
		(width 0.0889)
		(layer "In6.Cu")
		(net "M_E_CPU0_SB_CA<4>")
	)
	(segment
		(start 327.873868 -263.878568)
		(end 327.80986 -263.84123)
		(width 0.0889)
		(layer "In6.Cu")
		(net "M_E_CPU0_SB_CA<4>")
	)
	(segment
		(start 280.274268 -264.059924)
		(end 279.900634 -264.433558)
		(width 0.14478)
		(layer "In6.Cu")
		(net "M_E_CPU0_SB_CA<4>")
	)
	(segment
		(start 278.394668 -264.270744)
		(end 278.394668 -263.838944)
		(width 0.14478)
		(layer "In6.Cu")
		(net "M_E_CPU0_SB_CA<4>")
	)
	(segment
		(start 281.281124 -264.059924)
		(end 280.274268 -264.059924)
		(width 0.14478)
		(layer "In6.Cu")
		(net "M_E_CPU0_SB_CA<4>")
	)
	(segment
		(start 308.268624 -263.71042)
		(end 307.91912 -264.059924)
		(width 0.14478)
		(layer "In6.Cu")
		(net "M_E_CPU0_SB_CA<4>")
	)
	(segment
		(start 279.670002 -264.433558)
		(end 279.507188 -264.270744)
		(width 0.14478)
		(layer "In6.Cu")
		(net "M_E_CPU0_SB_CA<4>")
	)
	(segment
		(start 284.38221 -264.059924)
		(end 284.062424 -264.37971)
		(width 0.14478)
		(layer "In6.Cu")
		(net "M_E_CPU0_SB_CA<4>")
	)
	(segment
		(start 307.91912 -264.059924)
		(end 284.38221 -264.059924)
		(width 0.14478)
		(layer "In6.Cu")
		(net "M_E_CPU0_SB_CA<4>")
	)
	(segment
		(start 279.507188 -264.270744)
		(end 279.507188 -263.838944)
		(width 0.14478)
		(layer "In6.Cu")
		(net "M_E_CPU0_SB_CA<4>")
	)
	(segment
		(start 283.26969 -264.059924)
		(end 282.949904 -264.37971)
		(width 0.14478)
		(layer "In6.Cu")
		(net "M_E_CPU0_SB_CA<4>")
	)
	(segment
		(start 278.950928 -263.838944)
		(end 278.950928 -264.270744)
		(width 0.14478)
		(layer "In6.Cu")
		(net "M_E_CPU0_SB_CA<4>")
	)
	(segment
		(start 323.887084 -263.71042)
		(end 308.268624 -263.71042)
		(width 0.14478)
		(layer "In6.Cu")
		(net "M_E_CPU0_SB_CA<4>")
	)
	(segment
		(start 278.231854 -263.67613)
		(end 278.001222 -263.67613)
		(width 0.14478)
		(layer "In6.Cu")
		(net "M_E_CPU0_SB_CA<4>")
	)
	(segment
		(start 279.113742 -263.67613)
		(end 278.950928 -263.838944)
		(width 0.14478)
		(layer "In6.Cu")
		(net "M_E_CPU0_SB_CA<4>")
	)
	(arc
		(start 327.80986 -263.84123)
		(mid 327.674214 -263.773293)
		(end 327.531222 -263.722612)
		(width 0.0889)
		(layer "In6.Cu")
		(net "M_E_CPU0_SB_CA<4>")
	)
	(arc
		(start 328.814176 -263.878568)
		(mid 328.53122 -263.802391)
		(end 328.248264 -263.878568)
		(width 0.0889)
		(layer "In6.Cu")
		(net "M_E_CPU0_SB_CA<4>")
	)
	(arc
		(start 328.248264 -263.878568)
		(mid 328.061066 -263.92895)
		(end 327.873868 -263.878568)
		(width 0.0889)
		(layer "In6.Cu")
		(net "M_E_CPU0_SB_CA<4>")
	)
	(arc
		(start 330.119736 -263.883394)
		(mid 329.936228 -263.928888)
		(end 329.753976 -263.878568)
		(width 0.0889)
		(layer "In6.Cu")
		(net "M_E_CPU0_SB_CA<4>")
	)
	(arc
		(start 330.631038 -263.846818)
		(mid 330.37583 -263.803341)
		(end 330.128118 -263.878568)
		(width 0.0889)
		(layer "In6.Cu")
		(net "M_E_CPU0_SB_CA<4>")
	)
	(arc
		(start 327.531222 -263.722612)
		(mid 327.487452 -263.713424)
		(end 327.44283 -263.71042)
		(width 0.0889)
		(layer "In6.Cu")
		(net "M_E_CPU0_SB_CA<4>")
	)
	(arc
		(start 329.753976 -263.878568)
		(mid 329.47102 -263.802391)
		(end 329.188064 -263.878568)
		(width 0.0889)
		(layer "In6.Cu")
		(net "M_E_CPU0_SB_CA<4>")
	)
	(arc
		(start 329.188064 -263.878568)
		(mid 329.00112 -263.928823)
		(end 328.814176 -263.878568)
		(width 0.0889)
		(layer "In6.Cu")
		(net "M_E_CPU0_SB_CA<4>")
	)
	(segment
		(start 329.467972 -263.29005)
		(end 329.00112 -263.555988)
		(width 0.10668)
		(layer "F.Cu")
		(net "M_E_CPU0_SB_CA<3>")
	)
	(segment
		(start 325.865744 -262.90143)
		(end 324.767194 -262.90143)
		(width 0.0889)
		(layer "In6.Cu")
		(net "M_E_CPU0_SB_CA<3>")
	)
	(segment
		(start 329.155044 -263.290558)
		(end 329.132692 -263.207246)
		(width 0.0889)
		(layer "In6.Cu")
		(net "M_E_CPU0_SB_CA<3>")
	)
	(segment
		(start 329.00112 -263.555988)
		(end 329.155044 -263.290558)
		(width 0.0889)
		(layer "In6.Cu")
		(net "M_E_CPU0_SB_CA<3>")
	)
	(segment
		(start 324.458584 -263.21004)
		(end 323.908674 -263.21004)
		(width 0.0889)
		(layer "In6.Cu")
		(net "M_E_CPU0_SB_CA<3>")
	)
	(segment
		(start 324.767194 -262.90143)
		(end 324.458584 -263.21004)
		(width 0.0889)
		(layer "In6.Cu")
		(net "M_E_CPU0_SB_CA<3>")
	)
	(segment
		(start 327.882504 -263.228582)
		(end 327.874122 -263.233408)
		(width 0.0889)
		(layer "In6.Cu")
		(net "M_E_CPU0_SB_CA<3>")
	)
	(segment
		(start 323.908674 -263.21004)
		(end 273.517106 -263.21004)
		(width 0.14478)
		(layer "In6.Cu")
		(net "M_E_CPU0_SB_CA<3>")
	)
	(segment
		(start 326.273922 -263.309608)
		(end 325.865744 -262.90143)
		(width 0.0889)
		(layer "In6.Cu")
		(net "M_E_CPU0_SB_CA<3>")
	)
	(segment
		(start 327.590912 -263.309608)
		(end 326.273922 -263.309608)
		(width 0.0889)
		(layer "In6.Cu")
		(net "M_E_CPU0_SB_CA<3>")
	)
	(segment
		(start 273.517106 -263.21004)
		(end 273.092164 -263.634982)
		(width 0.14478)
		(layer "In6.Cu")
		(net "M_E_CPU0_SB_CA<3>")
	)
	(arc
		(start 328.248264 -263.233408)
		(mid 328.066013 -263.183058)
		(end 327.882504 -263.228582)
		(width 0.0889)
		(layer "In6.Cu")
		(net "M_E_CPU0_SB_CA<3>")
	)
	(arc
		(start 328.814176 -263.233408)
		(mid 328.53122 -263.309585)
		(end 328.248264 -263.233408)
		(width 0.0889)
		(layer "In6.Cu")
		(net "M_E_CPU0_SB_CA<3>")
	)
	(arc
		(start 327.874122 -263.233408)
		(mid 327.737559 -263.290241)
		(end 327.590912 -263.309608)
		(width 0.0889)
		(layer "In6.Cu")
		(net "M_E_CPU0_SB_CA<3>")
	)
	(arc
		(start 329.132692 -263.207246)
		(mid 328.970503 -263.184511)
		(end 328.814176 -263.233408)
		(width 0.0889)
		(layer "In6.Cu")
		(net "M_E_CPU0_SB_CA<3>")
	)
	(segment
		(start 329.937872 -262.480044)
		(end 329.47102 -262.745982)
		(width 0.10668)
		(layer "F.Cu")
		(net "M_E_CPU0_SB_CA<2>")
	)
	(segment
		(start 279.110948 -261.978902)
		(end 278.948134 -262.141716)
		(width 0.14478)
		(layer "In6.Cu")
		(net "M_E_CPU0_SB_CA<2>")
	)
	(segment
		(start 282.787852 -262.75411)
		(end 282.55722 -262.75411)
		(width 0.14478)
		(layer "In6.Cu")
		(net "M_E_CPU0_SB_CA<2>")
	)
	(segment
		(start 281.057858 -262.367268)
		(end 280.28519 -262.367268)
		(width 0.14478)
		(layer "In6.Cu")
		(net "M_E_CPU0_SB_CA<2>")
	)
	(segment
		(start 327.591166 -263.119108)
		(end 326.35825 -263.119108)
		(width 0.0889)
		(layer "In6.Cu")
		(net "M_E_CPU0_SB_CA<2>")
	)
	(segment
		(start 282.55722 -262.75411)
		(end 282.394406 -262.591296)
		(width 0.14478)
		(layer "In6.Cu")
		(net "M_E_CPU0_SB_CA<2>")
	)
	(segment
		(start 278.391874 -262.141716)
		(end 278.22906 -261.978902)
		(width 0.14478)
		(layer "In6.Cu")
		(net "M_E_CPU0_SB_CA<2>")
	)
	(segment
		(start 329.47102 -262.745982)
		(end 329.317096 -263.011412)
		(width 0.0889)
		(layer "In6.Cu")
		(net "M_E_CPU0_SB_CA<2>")
	)
	(segment
		(start 329.317096 -263.011412)
		(end 329.221084 -263.036812)
		(width 0.0889)
		(layer "In6.Cu")
		(net "M_E_CPU0_SB_CA<2>")
	)
	(segment
		(start 280.28519 -262.367268)
		(end 279.89784 -262.754618)
		(width 0.14478)
		(layer "In6.Cu")
		(net "M_E_CPU0_SB_CA<2>")
	)
	(segment
		(start 279.667208 -262.754618)
		(end 279.504394 -262.591804)
		(width 0.14478)
		(layer "In6.Cu")
		(net "M_E_CPU0_SB_CA<2>")
	)
	(segment
		(start 279.504394 -262.591804)
		(end 279.504394 -262.141716)
		(width 0.14478)
		(layer "In6.Cu")
		(net "M_E_CPU0_SB_CA<2>")
	)
	(segment
		(start 282.394406 -262.14324)
		(end 282.231592 -261.980426)
		(width 0.14478)
		(layer "In6.Cu")
		(net "M_E_CPU0_SB_CA<2>")
	)
	(segment
		(start 277.998428 -261.978902)
		(end 277.192232 -262.785098)
		(width 0.14478)
		(layer "In6.Cu")
		(net "M_E_CPU0_SB_CA<2>")
	)
	(segment
		(start 327.77811 -263.068562)
		(end 327.778364 -263.068562)
		(width 0.0889)
		(layer "In6.Cu")
		(net "M_E_CPU0_SB_CA<2>")
	)
	(segment
		(start 281.4447 -262.75411)
		(end 281.057858 -262.367268)
		(width 0.14478)
		(layer "In6.Cu")
		(net "M_E_CPU0_SB_CA<2>")
	)
	(segment
		(start 323.874638 -262.755126)
		(end 314.92698 -262.755126)
		(width 0.14478)
		(layer "In6.Cu")
		(net "M_E_CPU0_SB_CA<2>")
	)
	(segment
		(start 278.948134 -262.141716)
		(end 278.948134 -262.591804)
		(width 0.14478)
		(layer "In6.Cu")
		(net "M_E_CPU0_SB_CA<2>")
	)
	(segment
		(start 281.838146 -262.591296)
		(end 281.675332 -262.75411)
		(width 0.14478)
		(layer "In6.Cu")
		(net "M_E_CPU0_SB_CA<2>")
	)
	(segment
		(start 278.948134 -262.591804)
		(end 278.78532 -262.754618)
		(width 0.14478)
		(layer "In6.Cu")
		(net "M_E_CPU0_SB_CA<2>")
	)
	(segment
		(start 279.34158 -261.978902)
		(end 279.110948 -261.978902)
		(width 0.14478)
		(layer "In6.Cu")
		(net "M_E_CPU0_SB_CA<2>")
	)
	(segment
		(start 278.78532 -262.754618)
		(end 278.554688 -262.754618)
		(width 0.14478)
		(layer "In6.Cu")
		(net "M_E_CPU0_SB_CA<2>")
	)
	(segment
		(start 283.174694 -262.367268)
		(end 282.787852 -262.75411)
		(width 0.14478)
		(layer "In6.Cu")
		(net "M_E_CPU0_SB_CA<2>")
	)
	(segment
		(start 281.675332 -262.75411)
		(end 281.4447 -262.75411)
		(width 0.14478)
		(layer "In6.Cu")
		(net "M_E_CPU0_SB_CA<2>")
	)
	(segment
		(start 282.231592 -261.980426)
		(end 282.00096 -261.980426)
		(width 0.14478)
		(layer "In6.Cu")
		(net "M_E_CPU0_SB_CA<2>")
	)
	(segment
		(start 279.89784 -262.754618)
		(end 279.667208 -262.754618)
		(width 0.14478)
		(layer "In6.Cu")
		(net "M_E_CPU0_SB_CA<2>")
	)
	(segment
		(start 325.840852 -262.60171)
		(end 324.442074 -262.60171)
		(width 0.0889)
		(layer "In6.Cu")
		(net "M_E_CPU0_SB_CA<2>")
	)
	(segment
		(start 278.22906 -261.978902)
		(end 277.998428 -261.978902)
		(width 0.14478)
		(layer "In6.Cu")
		(net "M_E_CPU0_SB_CA<2>")
	)
	(segment
		(start 282.394406 -262.591296)
		(end 282.394406 -262.14324)
		(width 0.14478)
		(layer "In6.Cu")
		(net "M_E_CPU0_SB_CA<2>")
	)
	(segment
		(start 282.00096 -261.980426)
		(end 281.838146 -262.14324)
		(width 0.14478)
		(layer "In6.Cu")
		(net "M_E_CPU0_SB_CA<2>")
	)
	(segment
		(start 324.288658 -262.755126)
		(end 323.874638 -262.755126)
		(width 0.0889)
		(layer "In6.Cu")
		(net "M_E_CPU0_SB_CA<2>")
	)
	(segment
		(start 328.718164 -263.068562)
		(end 328.709782 -263.073388)
		(width 0.0889)
		(layer "In6.Cu")
		(net "M_E_CPU0_SB_CA<2>")
	)
	(segment
		(start 281.838146 -262.14324)
		(end 281.838146 -262.591296)
		(width 0.14478)
		(layer "In6.Cu")
		(net "M_E_CPU0_SB_CA<2>")
	)
	(segment
		(start 314.539122 -262.367268)
		(end 283.174694 -262.367268)
		(width 0.14478)
		(layer "In6.Cu")
		(net "M_E_CPU0_SB_CA<2>")
	)
	(segment
		(start 278.391874 -262.591804)
		(end 278.391874 -262.141716)
		(width 0.14478)
		(layer "In6.Cu")
		(net "M_E_CPU0_SB_CA<2>")
	)
	(segment
		(start 279.504394 -262.141716)
		(end 279.34158 -261.978902)
		(width 0.14478)
		(layer "In6.Cu")
		(net "M_E_CPU0_SB_CA<2>")
	)
	(segment
		(start 314.92698 -262.755126)
		(end 314.539122 -262.367268)
		(width 0.14478)
		(layer "In6.Cu")
		(net "M_E_CPU0_SB_CA<2>")
	)
	(segment
		(start 326.35825 -263.119108)
		(end 325.840852 -262.60171)
		(width 0.0889)
		(layer "In6.Cu")
		(net "M_E_CPU0_SB_CA<2>")
	)
	(segment
		(start 324.442074 -262.60171)
		(end 324.288658 -262.755126)
		(width 0.0889)
		(layer "In6.Cu")
		(net "M_E_CPU0_SB_CA<2>")
	)
	(segment
		(start 278.554688 -262.754618)
		(end 278.391874 -262.591804)
		(width 0.14478)
		(layer "In6.Cu")
		(net "M_E_CPU0_SB_CA<2>")
	)
	(arc
		(start 327.778364 -263.068562)
		(mid 327.688104 -263.10619)
		(end 327.591166 -263.119108)
		(width 0.0889)
		(layer "In6.Cu")
		(net "M_E_CPU0_SB_CA<2>")
	)
	(arc
		(start 329.221084 -263.036812)
		(mid 328.965876 -262.993335)
		(end 328.718164 -263.068562)
		(width 0.0889)
		(layer "In6.Cu")
		(net "M_E_CPU0_SB_CA<2>")
	)
	(arc
		(start 328.344022 -263.068562)
		(mid 328.061066 -262.992385)
		(end 327.77811 -263.068562)
		(width 0.0889)
		(layer "In6.Cu")
		(net "M_E_CPU0_SB_CA<2>")
	)
	(arc
		(start 328.709782 -263.073388)
		(mid 328.526274 -263.118882)
		(end 328.344022 -263.068562)
		(width 0.0889)
		(layer "In6.Cu")
		(net "M_E_CPU0_SB_CA<2>")
	)
	(segment
		(start 330.877926 -262.480044)
		(end 330.411074 -262.745982)
		(width 0.10668)
		(layer "F.Cu")
		(net "M_E_CPU0_SB_CA<1>")
	)
	(segment
		(start 330.564998 -262.480552)
		(end 330.542646 -262.39724)
		(width 0.0889)
		(layer "In6.Cu")
		(net "M_E_CPU0_SB_CA<1>")
	)
	(segment
		(start 327.12025 -262.24611)
		(end 323.926454 -262.24611)
		(width 0.0889)
		(layer "In6.Cu")
		(net "M_E_CPU0_SB_CA<1>")
	)
	(segment
		(start 328.718164 -262.423402)
		(end 328.709782 -262.418576)
		(width 0.0889)
		(layer "In6.Cu")
		(net "M_E_CPU0_SB_CA<1>")
	)
	(segment
		(start 273.517106 -261.510018)
		(end 273.092164 -261.93496)
		(width 0.14478)
		(layer "In6.Cu")
		(net "M_E_CPU0_SB_CA<1>")
	)
	(segment
		(start 323.926454 -262.24611)
		(end 315.05398 -262.24611)
		(width 0.14478)
		(layer "In6.Cu")
		(net "M_E_CPU0_SB_CA<1>")
	)
	(segment
		(start 329.292458 -262.418576)
		(end 329.284076 -262.423402)
		(width 0.0889)
		(layer "In6.Cu")
		(net "M_E_CPU0_SB_CA<1>")
	)
	(segment
		(start 330.411074 -262.745982)
		(end 330.564998 -262.480552)
		(width 0.0889)
		(layer "In6.Cu")
		(net "M_E_CPU0_SB_CA<1>")
	)
	(segment
		(start 315.05398 -262.24611)
		(end 314.317888 -261.510018)
		(width 0.14478)
		(layer "In6.Cu")
		(net "M_E_CPU0_SB_CA<1>")
	)
	(segment
		(start 314.317888 -261.510018)
		(end 273.517106 -261.510018)
		(width 0.14478)
		(layer "In6.Cu")
		(net "M_E_CPU0_SB_CA<1>")
	)
	(arc
		(start 327.77811 -262.423402)
		(mid 327.460912 -262.291229)
		(end 327.12025 -262.24611)
		(width 0.0889)
		(layer "In6.Cu")
		(net "M_E_CPU0_SB_CA<1>")
	)
	(arc
		(start 329.284076 -262.423402)
		(mid 329.00112 -262.499579)
		(end 328.718164 -262.423402)
		(width 0.0889)
		(layer "In6.Cu")
		(net "M_E_CPU0_SB_CA<1>")
	)
	(arc
		(start 328.709782 -262.418576)
		(mid 328.526274 -262.373082)
		(end 328.344022 -262.423402)
		(width 0.0889)
		(layer "In6.Cu")
		(net "M_E_CPU0_SB_CA<1>")
	)
	(arc
		(start 330.542646 -262.39724)
		(mid 330.380457 -262.374505)
		(end 330.22413 -262.423402)
		(width 0.0889)
		(layer "In6.Cu")
		(net "M_E_CPU0_SB_CA<1>")
	)
	(arc
		(start 330.22413 -262.423402)
		(mid 329.941174 -262.499579)
		(end 329.658218 -262.423402)
		(width 0.0889)
		(layer "In6.Cu")
		(net "M_E_CPU0_SB_CA<1>")
	)
	(arc
		(start 329.658218 -262.423402)
		(mid 329.475967 -262.373052)
		(end 329.292458 -262.418576)
		(width 0.0889)
		(layer "In6.Cu")
		(net "M_E_CPU0_SB_CA<1>")
	)
	(arc
		(start 328.344022 -262.423402)
		(mid 328.061066 -262.499579)
		(end 327.77811 -262.423402)
		(width 0.0889)
		(layer "In6.Cu")
		(net "M_E_CPU0_SB_CA<1>")
	)
	(segment
		(start 331.34808 -261.670038)
		(end 330.880974 -261.935976)
		(width 0.10668)
		(layer "F.Cu")
		(net "M_E_CPU0_SB_CA<0>")
	)
	(segment
		(start 330.128118 -262.258556)
		(end 330.119736 -262.263382)
		(width 0.0889)
		(layer "In6.Cu")
		(net "M_E_CPU0_SB_CA<0>")
	)
	(segment
		(start 278.57196 -261.052056)
		(end 278.409146 -260.889242)
		(width 0.14478)
		(layer "In6.Cu")
		(net "M_E_CPU0_SB_CA<0>")
	)
	(segment
		(start 279.521666 -260.424422)
		(end 279.358852 -260.261608)
		(width 0.14478)
		(layer "In6.Cu")
		(net "M_E_CPU0_SB_CA<0>")
	)
	(segment
		(start 278.0157 -260.261608)
		(end 277.192232 -261.085076)
		(width 0.14478)
		(layer "In6.Cu")
		(net "M_E_CPU0_SB_CA<0>")
	)
	(segment
		(start 279.358852 -260.261608)
		(end 279.12822 -260.261608)
		(width 0.14478)
		(layer "In6.Cu")
		(net "M_E_CPU0_SB_CA<0>")
	)
	(segment
		(start 279.68448 -261.052056)
		(end 279.521666 -260.889242)
		(width 0.14478)
		(layer "In6.Cu")
		(net "M_E_CPU0_SB_CA<0>")
	)
	(segment
		(start 324.739254 -262.05561)
		(end 324.4596 -261.775956)
		(width 0.0889)
		(layer "In6.Cu")
		(net "M_E_CPU0_SB_CA<0>")
	)
	(segment
		(start 278.409146 -260.424422)
		(end 278.246332 -260.261608)
		(width 0.14478)
		(layer "In6.Cu")
		(net "M_E_CPU0_SB_CA<0>")
	)
	(segment
		(start 278.246332 -260.261608)
		(end 278.0157 -260.261608)
		(width 0.14478)
		(layer "In6.Cu")
		(net "M_E_CPU0_SB_CA<0>")
	)
	(segment
		(start 278.965406 -260.424422)
		(end 278.965406 -260.889242)
		(width 0.14478)
		(layer "In6.Cu")
		(net "M_E_CPU0_SB_CA<0>")
	)
	(segment
		(start 327.19391 -262.05561)
		(end 324.739254 -262.05561)
		(width 0.0889)
		(layer "In6.Cu")
		(net "M_E_CPU0_SB_CA<0>")
	)
	(segment
		(start 330.72705 -262.201406)
		(end 330.631038 -262.226806)
		(width 0.0889)
		(layer "In6.Cu")
		(net "M_E_CPU0_SB_CA<0>")
	)
	(segment
		(start 330.880974 -261.935976)
		(end 330.72705 -262.201406)
		(width 0.0889)
		(layer "In6.Cu")
		(net "M_E_CPU0_SB_CA<0>")
	)
	(segment
		(start 278.409146 -260.889242)
		(end 278.409146 -260.424422)
		(width 0.14478)
		(layer "In6.Cu")
		(net "M_E_CPU0_SB_CA<0>")
	)
	(segment
		(start 323.956934 -261.775956)
		(end 315.219842 -261.775956)
		(width 0.14478)
		(layer "In6.Cu")
		(net "M_E_CPU0_SB_CA<0>")
	)
	(segment
		(start 279.915112 -261.052056)
		(end 279.68448 -261.052056)
		(width 0.14478)
		(layer "In6.Cu")
		(net "M_E_CPU0_SB_CA<0>")
	)
	(segment
		(start 280.307034 -260.660134)
		(end 279.915112 -261.052056)
		(width 0.14478)
		(layer "In6.Cu")
		(net "M_E_CPU0_SB_CA<0>")
	)
	(segment
		(start 315.219842 -261.775956)
		(end 314.10402 -260.660134)
		(width 0.14478)
		(layer "In6.Cu")
		(net "M_E_CPU0_SB_CA<0>")
	)
	(segment
		(start 327.873868 -262.258556)
		(end 327.80986 -262.221218)
		(width 0.0889)
		(layer "In6.Cu")
		(net "M_E_CPU0_SB_CA<0>")
	)
	(segment
		(start 279.521666 -260.889242)
		(end 279.521666 -260.424422)
		(width 0.14478)
		(layer "In6.Cu")
		(net "M_E_CPU0_SB_CA<0>")
	)
	(segment
		(start 324.4596 -261.775956)
		(end 323.956934 -261.775956)
		(width 0.0889)
		(layer "In6.Cu")
		(net "M_E_CPU0_SB_CA<0>")
	)
	(segment
		(start 278.965406 -260.889242)
		(end 278.802592 -261.052056)
		(width 0.14478)
		(layer "In6.Cu")
		(net "M_E_CPU0_SB_CA<0>")
	)
	(segment
		(start 278.802592 -261.052056)
		(end 278.57196 -261.052056)
		(width 0.14478)
		(layer "In6.Cu")
		(net "M_E_CPU0_SB_CA<0>")
	)
	(segment
		(start 279.12822 -260.261608)
		(end 278.965406 -260.424422)
		(width 0.14478)
		(layer "In6.Cu")
		(net "M_E_CPU0_SB_CA<0>")
	)
	(segment
		(start 314.10402 -260.660134)
		(end 280.307034 -260.660134)
		(width 0.14478)
		(layer "In6.Cu")
		(net "M_E_CPU0_SB_CA<0>")
	)
	(arc
		(start 328.248264 -262.258556)
		(mid 328.061066 -262.308938)
		(end 327.873868 -262.258556)
		(width 0.0889)
		(layer "In6.Cu")
		(net "M_E_CPU0_SB_CA<0>")
	)
	(arc
		(start 329.753976 -262.258556)
		(mid 329.47102 -262.182379)
		(end 329.188064 -262.258556)
		(width 0.0889)
		(layer "In6.Cu")
		(net "M_E_CPU0_SB_CA<0>")
	)
	(arc
		(start 327.80986 -262.221218)
		(mid 327.512832 -262.097714)
		(end 327.19391 -262.05561)
		(width 0.0889)
		(layer "In6.Cu")
		(net "M_E_CPU0_SB_CA<0>")
	)
	(arc
		(start 329.188064 -262.258556)
		(mid 329.00112 -262.308811)
		(end 328.814176 -262.258556)
		(width 0.0889)
		(layer "In6.Cu")
		(net "M_E_CPU0_SB_CA<0>")
	)
	(arc
		(start 330.119736 -262.263382)
		(mid 329.936228 -262.308876)
		(end 329.753976 -262.258556)
		(width 0.0889)
		(layer "In6.Cu")
		(net "M_E_CPU0_SB_CA<0>")
	)
	(arc
		(start 328.814176 -262.258556)
		(mid 328.53122 -262.182379)
		(end 328.248264 -262.258556)
		(width 0.0889)
		(layer "In6.Cu")
		(net "M_E_CPU0_SB_CA<0>")
	)
	(arc
		(start 330.631038 -262.226806)
		(mid 330.37583 -262.183329)
		(end 330.128118 -262.258556)
		(width 0.0889)
		(layer "In6.Cu")
		(net "M_E_CPU0_SB_CA<0>")
	)
	(segment
		(start 331.34808 -266.530074)
		(end 330.880974 -266.796012)
		(width 0.10668)
		(layer "F.Cu")
		(net "M_E_CPU0_SA_RSP<0>")
	)
	(segment
		(start 278.003508 -268.77391)
		(end 277.192232 -269.585186)
		(width 0.11684)
		(layer "In6.Cu")
		(net "M_E_CPU0_SA_RSP<0>")
	)
	(segment
		(start 323.989954 -266.42441)
		(end 310.428894 -266.42441)
		(width 0.11684)
		(layer "In6.Cu")
		(net "M_E_CPU0_SA_RSP<0>")
	)
	(segment
		(start 279.12187 -269.391384)
		(end 278.967184 -269.54607)
		(width 0.11684)
		(layer "In6.Cu")
		(net "M_E_CPU0_SA_RSP<0>")
	)
	(segment
		(start 307.693314 -269.15999)
		(end 279.881584 -269.15999)
		(width 0.11684)
		(layer "In6.Cu")
		(net "M_E_CPU0_SA_RSP<0>")
	)
	(segment
		(start 330.72705 -267.061442)
		(end 330.631038 -267.086842)
		(width 0.0889)
		(layer "In6.Cu")
		(net "M_E_CPU0_SA_RSP<0>")
	)
	(segment
		(start 278.438864 -268.77391)
		(end 278.003508 -268.77391)
		(width 0.11684)
		(layer "In6.Cu")
		(net "M_E_CPU0_SA_RSP<0>")
	)
	(segment
		(start 279.881584 -269.15999)
		(end 279.495504 -268.77391)
		(width 0.11684)
		(layer "In6.Cu")
		(net "M_E_CPU0_SA_RSP<0>")
	)
	(segment
		(start 330.128118 -267.118592)
		(end 330.119736 -267.123418)
		(width 0.0889)
		(layer "In6.Cu")
		(net "M_E_CPU0_SA_RSP<0>")
	)
	(segment
		(start 278.59355 -269.391384)
		(end 278.59355 -268.928596)
		(width 0.11684)
		(layer "In6.Cu")
		(net "M_E_CPU0_SA_RSP<0>")
	)
	(segment
		(start 310.428894 -266.42441)
		(end 307.693314 -269.15999)
		(width 0.11684)
		(layer "In6.Cu")
		(net "M_E_CPU0_SA_RSP<0>")
	)
	(segment
		(start 330.880974 -266.796012)
		(end 330.72705 -267.061442)
		(width 0.0889)
		(layer "In6.Cu")
		(net "M_E_CPU0_SA_RSP<0>")
	)
	(segment
		(start 279.276556 -268.77391)
		(end 279.12187 -268.928596)
		(width 0.11684)
		(layer "In6.Cu")
		(net "M_E_CPU0_SA_RSP<0>")
	)
	(segment
		(start 327.873868 -267.118592)
		(end 327.80986 -267.081254)
		(width 0.0889)
		(layer "In6.Cu")
		(net "M_E_CPU0_SA_RSP<0>")
	)
	(segment
		(start 278.59355 -268.928596)
		(end 278.438864 -268.77391)
		(width 0.11684)
		(layer "In6.Cu")
		(net "M_E_CPU0_SA_RSP<0>")
	)
	(segment
		(start 279.495504 -268.77391)
		(end 279.276556 -268.77391)
		(width 0.11684)
		(layer "In6.Cu")
		(net "M_E_CPU0_SA_RSP<0>")
	)
	(segment
		(start 279.12187 -268.928596)
		(end 279.12187 -269.391384)
		(width 0.11684)
		(layer "In6.Cu")
		(net "M_E_CPU0_SA_RSP<0>")
	)
	(segment
		(start 324.396354 -266.42441)
		(end 323.989954 -266.42441)
		(width 0.0889)
		(layer "In6.Cu")
		(net "M_E_CPU0_SA_RSP<0>")
	)
	(segment
		(start 278.748236 -269.54607)
		(end 278.59355 -269.391384)
		(width 0.11684)
		(layer "In6.Cu")
		(net "M_E_CPU0_SA_RSP<0>")
	)
	(segment
		(start 327.683622 -267.037566)
		(end 325.00951 -267.037566)
		(width 0.0889)
		(layer "In6.Cu")
		(net "M_E_CPU0_SA_RSP<0>")
	)
	(segment
		(start 278.967184 -269.54607)
		(end 278.748236 -269.54607)
		(width 0.11684)
		(layer "In6.Cu")
		(net "M_E_CPU0_SA_RSP<0>")
	)
	(segment
		(start 325.00951 -267.037566)
		(end 324.396354 -266.42441)
		(width 0.0889)
		(layer "In6.Cu")
		(net "M_E_CPU0_SA_RSP<0>")
	)
	(arc
		(start 330.631038 -267.086842)
		(mid 330.37583 -267.043365)
		(end 330.128118 -267.118592)
		(width 0.0889)
		(layer "In6.Cu")
		(net "M_E_CPU0_SA_RSP<0>")
	)
	(arc
		(start 328.814176 -267.118592)
		(mid 328.53122 -267.042415)
		(end 328.248264 -267.118592)
		(width 0.0889)
		(layer "In6.Cu")
		(net "M_E_CPU0_SA_RSP<0>")
	)
	(arc
		(start 329.188064 -267.118592)
		(mid 329.00112 -267.168847)
		(end 328.814176 -267.118592)
		(width 0.0889)
		(layer "In6.Cu")
		(net "M_E_CPU0_SA_RSP<0>")
	)
	(arc
		(start 329.753976 -267.118592)
		(mid 329.47102 -267.042415)
		(end 329.188064 -267.118592)
		(width 0.0889)
		(layer "In6.Cu")
		(net "M_E_CPU0_SA_RSP<0>")
	)
	(arc
		(start 330.119736 -267.123418)
		(mid 329.936228 -267.168912)
		(end 329.753976 -267.118592)
		(width 0.0889)
		(layer "In6.Cu")
		(net "M_E_CPU0_SA_RSP<0>")
	)
	(arc
		(start 327.80986 -267.081254)
		(mid 327.790025 -267.069892)
		(end 327.769982 -267.058902)
		(width 0.0889)
		(layer "In6.Cu")
		(net "M_E_CPU0_SA_RSP<0>")
	)
	(arc
		(start 328.248264 -267.118592)
		(mid 328.061066 -267.168974)
		(end 327.873868 -267.118592)
		(width 0.0889)
		(layer "In6.Cu")
		(net "M_E_CPU0_SA_RSP<0>")
	)
	(arc
		(start 327.769982 -267.058902)
		(mid 327.728115 -267.042904)
		(end 327.683622 -267.037566)
		(width 0.0889)
		(layer "In6.Cu")
		(net "M_E_CPU0_SA_RSP<0>")
	)
	(segment
		(start 331.047852 -256.090166)
		(end 330.581 -255.824228)
		(width 0.10668)
		(layer "F.Cu")
		(net "M_E_CPU0_SA_PAR")
	)
	(segment
		(start 281.72918 -255.580642)
		(end 281.566112 -255.74371)
		(width 0.14478)
		(layer "In6.Cu")
		(net "M_E_CPU0_SA_PAR")
	)
	(segment
		(start 282.842208 -255.580642)
		(end 282.67914 -255.74371)
		(width 0.14478)
		(layer "In6.Cu")
		(net "M_E_CPU0_SA_PAR")
	)
	(segment
		(start 320.988182 -256.66827)
		(end 319.474342 -255.15443)
		(width 0.14478)
		(layer "In6.Cu")
		(net "M_E_CPU0_SA_PAR")
	)
	(segment
		(start 283.56179 -255.74371)
		(end 283.398722 -255.580642)
		(width 0.14478)
		(layer "In6.Cu")
		(net "M_E_CPU0_SA_PAR")
	)
	(segment
		(start 283.398722 -255.580642)
		(end 283.398722 -255.368298)
		(width 0.14478)
		(layer "In6.Cu")
		(net "M_E_CPU0_SA_PAR")
	)
	(segment
		(start 330.581 -255.824228)
		(end 330.427076 -255.558798)
		(width 0.0889)
		(layer "In6.Cu")
		(net "M_E_CPU0_SA_PAR")
	)
	(segment
		(start 323.995034 -256.66827)
		(end 320.988182 -256.66827)
		(width 0.14478)
		(layer "In6.Cu")
		(net "M_E_CPU0_SA_PAR")
	)
	(segment
		(start 311.678066 -255.74371)
		(end 283.56179 -255.74371)
		(width 0.14478)
		(layer "In6.Cu")
		(net "M_E_CPU0_SA_PAR")
	)
	(segment
		(start 281.892248 -255.20523)
		(end 281.72918 -255.368298)
		(width 0.14478)
		(layer "In6.Cu")
		(net "M_E_CPU0_SA_PAR")
	)
	(segment
		(start 282.122626 -255.20523)
		(end 281.892248 -255.20523)
		(width 0.14478)
		(layer "In6.Cu")
		(net "M_E_CPU0_SA_PAR")
	)
	(segment
		(start 327.586086 -255.49479)
		(end 327.574402 -255.501648)
		(width 0.0889)
		(layer "In6.Cu")
		(net "M_E_CPU0_SA_PAR")
	)
	(segment
		(start 319.474342 -255.15443)
		(end 312.267346 -255.15443)
		(width 0.14478)
		(layer "In6.Cu")
		(net "M_E_CPU0_SA_PAR")
	)
	(segment
		(start 282.842208 -255.368298)
		(end 282.842208 -255.580642)
		(width 0.14478)
		(layer "In6.Cu")
		(net "M_E_CPU0_SA_PAR")
	)
	(segment
		(start 281.72918 -255.368298)
		(end 281.72918 -255.580642)
		(width 0.14478)
		(layer "In6.Cu")
		(net "M_E_CPU0_SA_PAR")
	)
	(segment
		(start 282.67914 -255.74371)
		(end 282.448762 -255.74371)
		(width 0.14478)
		(layer "In6.Cu")
		(net "M_E_CPU0_SA_PAR")
	)
	(segment
		(start 282.448762 -255.74371)
		(end 282.285694 -255.580642)
		(width 0.14478)
		(layer "In6.Cu")
		(net "M_E_CPU0_SA_PAR")
	)
	(segment
		(start 283.005276 -255.20523)
		(end 282.842208 -255.368298)
		(width 0.14478)
		(layer "In6.Cu")
		(net "M_E_CPU0_SA_PAR")
	)
	(segment
		(start 327.574402 -255.501648)
		(end 327.563988 -255.507744)
		(width 0.0889)
		(layer "In6.Cu")
		(net "M_E_CPU0_SA_PAR")
	)
	(segment
		(start 312.267346 -255.15443)
		(end 311.678066 -255.74371)
		(width 0.14478)
		(layer "In6.Cu")
		(net "M_E_CPU0_SA_PAR")
	)
	(segment
		(start 329.828144 -255.501648)
		(end 329.819762 -255.496822)
		(width 0.0889)
		(layer "In6.Cu")
		(net "M_E_CPU0_SA_PAR")
	)
	(segment
		(start 327.008744 -255.501648)
		(end 326.99706 -255.49479)
		(width 0.0889)
		(layer "In6.Cu")
		(net "M_E_CPU0_SA_PAR")
	)
	(segment
		(start 330.427076 -255.558798)
		(end 330.331064 -255.533398)
		(width 0.0889)
		(layer "In6.Cu")
		(net "M_E_CPU0_SA_PAR")
	)
	(segment
		(start 283.398722 -255.368298)
		(end 283.235654 -255.20523)
		(width 0.14478)
		(layer "In6.Cu")
		(net "M_E_CPU0_SA_PAR")
	)
	(segment
		(start 278.650954 -255.74371)
		(end 277.192232 -254.284988)
		(width 0.14478)
		(layer "In6.Cu")
		(net "M_E_CPU0_SA_PAR")
	)
	(segment
		(start 282.285694 -255.580642)
		(end 282.285694 -255.368298)
		(width 0.14478)
		(layer "In6.Cu")
		(net "M_E_CPU0_SA_PAR")
	)
	(segment
		(start 283.235654 -255.20523)
		(end 283.005276 -255.20523)
		(width 0.14478)
		(layer "In6.Cu")
		(net "M_E_CPU0_SA_PAR")
	)
	(segment
		(start 324.736714 -256.66827)
		(end 323.995034 -256.66827)
		(width 0.0889)
		(layer "In6.Cu")
		(net "M_E_CPU0_SA_PAR")
	)
	(segment
		(start 325.752714 -255.65227)
		(end 324.736714 -256.66827)
		(width 0.0889)
		(layer "In6.Cu")
		(net "M_E_CPU0_SA_PAR")
	)
	(segment
		(start 282.285694 -255.368298)
		(end 282.122626 -255.20523)
		(width 0.14478)
		(layer "In6.Cu")
		(net "M_E_CPU0_SA_PAR")
	)
	(segment
		(start 281.566112 -255.74371)
		(end 278.650954 -255.74371)
		(width 0.14478)
		(layer "In6.Cu")
		(net "M_E_CPU0_SA_PAR")
	)
	(arc
		(start 329.454002 -255.501648)
		(mid 329.171046 -255.577825)
		(end 328.88809 -255.501648)
		(width 0.0889)
		(layer "In6.Cu")
		(net "M_E_CPU0_SA_PAR")
	)
	(arc
		(start 329.819762 -255.496822)
		(mid 329.636254 -255.451328)
		(end 329.454002 -255.501648)
		(width 0.0889)
		(layer "In6.Cu")
		(net "M_E_CPU0_SA_PAR")
	)
	(arc
		(start 328.514202 -255.501648)
		(mid 328.231246 -255.577825)
		(end 327.94829 -255.501648)
		(width 0.0889)
		(layer "In6.Cu")
		(net "M_E_CPU0_SA_PAR")
	)
	(arc
		(start 327.94829 -255.501648)
		(mid 327.768085 -255.451331)
		(end 327.586086 -255.49479)
		(width 0.0889)
		(layer "In6.Cu")
		(net "M_E_CPU0_SA_PAR")
	)
	(arc
		(start 330.331064 -255.533398)
		(mid 330.075856 -255.576875)
		(end 329.828144 -255.501648)
		(width 0.0889)
		(layer "In6.Cu")
		(net "M_E_CPU0_SA_PAR")
	)
	(arc
		(start 326.473058 -255.56464)
		(mid 326.115011 -255.625922)
		(end 325.752714 -255.65227)
		(width 0.0889)
		(layer "In6.Cu")
		(net "M_E_CPU0_SA_PAR")
	)
	(arc
		(start 326.634348 -255.501648)
		(mid 326.556132 -255.53936)
		(end 326.473058 -255.56464)
		(width 0.0889)
		(layer "In6.Cu")
		(net "M_E_CPU0_SA_PAR")
	)
	(arc
		(start 326.99706 -255.49479)
		(mid 326.814805 -255.451137)
		(end 326.634348 -255.501648)
		(width 0.0889)
		(layer "In6.Cu")
		(net "M_E_CPU0_SA_PAR")
	)
	(arc
		(start 327.563988 -255.507744)
		(mid 327.285556 -255.577842)
		(end 327.008744 -255.501648)
		(width 0.0889)
		(layer "In6.Cu")
		(net "M_E_CPU0_SA_PAR")
	)
	(arc
		(start 328.88809 -255.501648)
		(mid 328.701146 -255.451393)
		(end 328.514202 -255.501648)
		(width 0.0889)
		(layer "In6.Cu")
		(net "M_E_CPU0_SA_PAR")
	)
	(segment
		(start 331.047852 -247.990106)
		(end 330.581 -247.724168)
		(width 0.12954)
		(layer "F.Cu")
		(net "M_E_CPU0_SA_DQS_DP<9>")
	)
	(segment
		(start 325.200264 -247.624092)
		(end 324.844664 -247.624092)
		(width 0.09525)
		(layer "In6.Cu")
		(net "M_E_CPU0_SA_DQS_DP<9>")
	)
	(segment
		(start 285.075122 -239.726978)
		(end 283.893768 -239.726978)
		(width 0.16002)
		(layer "In6.Cu")
		(net "M_E_CPU0_SA_DQS_DP<9>")
	)
	(segment
		(start 327.584816 -247.39219)
		(end 327.572878 -247.399048)
		(width 0.09525)
		(layer "In6.Cu")
		(net "M_E_CPU0_SA_DQS_DP<9>")
	)
	(segment
		(start 297.396916 -240.225326)
		(end 296.589196 -240.225326)
		(width 0.16002)
		(layer "In6.Cu")
		(net "M_E_CPU0_SA_DQS_DP<9>")
	)
	(segment
		(start 283.193236 -239.341152)
		(end 282.309062 -240.225326)
		(width 0.16002)
		(layer "In6.Cu")
		(net "M_E_CPU0_SA_DQS_DP<9>")
	)
	(segment
		(start 275.523452 -239.380522)
		(end 275.342604 -239.56137)
		(width 0.16002)
		(layer "In6.Cu")
		(net "M_E_CPU0_SA_DQS_DP<9>")
	)
	(segment
		(start 289.852862 -240.225326)
		(end 289.375342 -240.225326)
		(width 0.16002)
		(layer "In6.Cu")
		(net "M_E_CPU0_SA_DQS_DP<9>")
	)
	(segment
		(start 323.248528 -247.682004)
		(end 322.741036 -247.174512)
		(width 0.16002)
		(layer "In6.Cu")
		(net "M_E_CPU0_SA_DQS_DP<9>")
	)
	(segment
		(start 325.658226 -247.40616)
		(end 325.611236 -247.453658)
		(width 0.09525)
		(layer "In6.Cu")
		(net "M_E_CPU0_SA_DQS_DP<9>")
	)
	(segment
		(start 324.843648 -247.623076)
		(end 323.978524 -247.623076)
		(width 0.09525)
		(layer "In6.Cu")
		(net "M_E_CPU0_SA_DQS_DP<9>")
	)
	(segment
		(start 292.711378 -239.726978)
		(end 291.437568 -239.726978)
		(width 0.16002)
		(layer "In6.Cu")
		(net "M_E_CPU0_SA_DQS_DP<9>")
	)
	(segment
		(start 298.981622 -239.726978)
		(end 298.595796 -239.341152)
		(width 0.16002)
		(layer "In6.Cu")
		(net "M_E_CPU0_SA_DQS_DP<9>")
	)
	(segment
		(start 313.07786 -247.174512)
		(end 307.801518 -241.89817)
		(width 0.16002)
		(layer "In6.Cu")
		(net "M_E_CPU0_SA_DQS_DP<9>")
	)
	(segment
		(start 326.070214 -247.399048)
		(end 326.061832 -247.394222)
		(width 0.09525)
		(layer "In6.Cu")
		(net "M_E_CPU0_SA_DQS_DP<9>")
	)
	(segment
		(start 289.375342 -240.225326)
		(end 289.040316 -240.560352)
		(width 0.16002)
		(layer "In6.Cu")
		(net "M_E_CPU0_SA_DQS_DP<9>")
	)
	(segment
		(start 307.801518 -241.008662)
		(end 307.484526 -240.69167)
		(width 0.16002)
		(layer "In6.Cu")
		(net "M_E_CPU0_SA_DQS_DP<9>")
	)
	(segment
		(start 279.57653 -240.560352)
		(end 277.564342 -239.726978)
		(width 0.16002)
		(layer "In6.Cu")
		(net "M_E_CPU0_SA_DQS_DP<9>")
	)
	(segment
		(start 296.25417 -240.560352)
		(end 294.723566 -240.560352)
		(width 0.16002)
		(layer "In6.Cu")
		(net "M_E_CPU0_SA_DQS_DP<9>")
	)
	(segment
		(start 287.08731 -240.560352)
		(end 285.075122 -239.726978)
		(width 0.16002)
		(layer "In6.Cu")
		(net "M_E_CPU0_SA_DQS_DP<9>")
	)
	(segment
		(start 290.737036 -239.341152)
		(end 289.852862 -240.225326)
		(width 0.16002)
		(layer "In6.Cu")
		(net "M_E_CPU0_SA_DQS_DP<9>")
	)
	(segment
		(start 300.729396 -239.726978)
		(end 298.981622 -239.726978)
		(width 0.16002)
		(layer "In6.Cu")
		(net "M_E_CPU0_SA_DQS_DP<9>")
	)
	(segment
		(start 298.28109 -239.341152)
		(end 297.396916 -240.225326)
		(width 0.16002)
		(layer "In6.Cu")
		(net "M_E_CPU0_SA_DQS_DP<9>")
	)
	(segment
		(start 327.572878 -247.399048)
		(end 327.562464 -247.405144)
		(width 0.09525)
		(layer "In6.Cu")
		(net "M_E_CPU0_SA_DQS_DP<9>")
	)
	(segment
		(start 282.309062 -240.225326)
		(end 281.831542 -240.225326)
		(width 0.16002)
		(layer "In6.Cu")
		(net "M_E_CPU0_SA_DQS_DP<9>")
	)
	(segment
		(start 323.895974 -247.682004)
		(end 323.248528 -247.682004)
		(width 0.16002)
		(layer "In6.Cu")
		(net "M_E_CPU0_SA_DQS_DP<9>")
	)
	(segment
		(start 305.166522 -240.225326)
		(end 301.932594 -240.225326)
		(width 0.16002)
		(layer "In6.Cu")
		(net "M_E_CPU0_SA_DQS_DP<9>")
	)
	(segment
		(start 294.723566 -240.560352)
		(end 292.711378 -239.726978)
		(width 0.16002)
		(layer "In6.Cu")
		(net "M_E_CPU0_SA_DQS_DP<9>")
	)
	(segment
		(start 324.844664 -247.624092)
		(end 324.843648 -247.623076)
		(width 0.09525)
		(layer "In6.Cu")
		(net "M_E_CPU0_SA_DQS_DP<9>")
	)
	(segment
		(start 323.919596 -247.682004)
		(end 323.895974 -247.682004)
		(width 0.09525)
		(layer "In6.Cu")
		(net "M_E_CPU0_SA_DQS_DP<9>")
	)
	(segment
		(start 307.801518 -241.89817)
		(end 307.801518 -241.008662)
		(width 0.16002)
		(layer "In6.Cu")
		(net "M_E_CPU0_SA_DQS_DP<9>")
	)
	(segment
		(start 277.564342 -239.726978)
		(end 276.353016 -239.726978)
		(width 0.16002)
		(layer "In6.Cu")
		(net "M_E_CPU0_SA_DQS_DP<9>")
	)
	(segment
		(start 296.589196 -240.225326)
		(end 296.25417 -240.560352)
		(width 0.16002)
		(layer "In6.Cu")
		(net "M_E_CPU0_SA_DQS_DP<9>")
	)
	(segment
		(start 322.741036 -247.174512)
		(end 313.07786 -247.174512)
		(width 0.16002)
		(layer "In6.Cu")
		(net "M_E_CPU0_SA_DQS_DP<9>")
	)
	(segment
		(start 276.353016 -239.726978)
		(end 276.00656 -239.380522)
		(width 0.16002)
		(layer "In6.Cu")
		(net "M_E_CPU0_SA_DQS_DP<9>")
	)
	(segment
		(start 298.595796 -239.341152)
		(end 298.28109 -239.341152)
		(width 0.16002)
		(layer "In6.Cu")
		(net "M_E_CPU0_SA_DQS_DP<9>")
	)
	(segment
		(start 323.978524 -247.623076)
		(end 323.919596 -247.682004)
		(width 0.09525)
		(layer "In6.Cu")
		(net "M_E_CPU0_SA_DQS_DP<9>")
	)
	(segment
		(start 275.342604 -239.56137)
		(end 273.365976 -239.56137)
		(width 0.16002)
		(layer "In6.Cu")
		(net "M_E_CPU0_SA_DQS_DP<9>")
	)
	(segment
		(start 305.632866 -240.69167)
		(end 305.166522 -240.225326)
		(width 0.16002)
		(layer "In6.Cu")
		(net "M_E_CPU0_SA_DQS_DP<9>")
	)
	(segment
		(start 281.831542 -240.225326)
		(end 281.496516 -240.560352)
		(width 0.16002)
		(layer "In6.Cu")
		(net "M_E_CPU0_SA_DQS_DP<9>")
	)
	(segment
		(start 283.893768 -239.726978)
		(end 283.507942 -239.341152)
		(width 0.16002)
		(layer "In6.Cu")
		(net "M_E_CPU0_SA_DQS_DP<9>")
	)
	(segment
		(start 273.365976 -239.56137)
		(end 273.092164 -239.835182)
		(width 0.16002)
		(layer "In6.Cu")
		(net "M_E_CPU0_SA_DQS_DP<9>")
	)
	(segment
		(start 301.932594 -240.225326)
		(end 300.729396 -239.726978)
		(width 0.16002)
		(layer "In6.Cu")
		(net "M_E_CPU0_SA_DQS_DP<9>")
	)
	(segment
		(start 283.507942 -239.341152)
		(end 283.193236 -239.341152)
		(width 0.16002)
		(layer "In6.Cu")
		(net "M_E_CPU0_SA_DQS_DP<9>")
	)
	(segment
		(start 307.484526 -240.69167)
		(end 305.632866 -240.69167)
		(width 0.16002)
		(layer "In6.Cu")
		(net "M_E_CPU0_SA_DQS_DP<9>")
	)
	(segment
		(start 326.088248 -247.409462)
		(end 326.070214 -247.399048)
		(width 0.09525)
		(layer "In6.Cu")
		(net "M_E_CPU0_SA_DQS_DP<9>")
	)
	(segment
		(start 281.496516 -240.560352)
		(end 279.57653 -240.560352)
		(width 0.16002)
		(layer "In6.Cu")
		(net "M_E_CPU0_SA_DQS_DP<9>")
	)
	(segment
		(start 327.010268 -247.399048)
		(end 326.99833 -247.39219)
		(width 0.09525)
		(layer "In6.Cu")
		(net "M_E_CPU0_SA_DQS_DP<9>")
	)
	(segment
		(start 330.427076 -247.458738)
		(end 330.326238 -247.432068)
		(width 0.09525)
		(layer "In6.Cu")
		(net "M_E_CPU0_SA_DQS_DP<9>")
	)
	(segment
		(start 291.051742 -239.341152)
		(end 290.737036 -239.341152)
		(width 0.16002)
		(layer "In6.Cu")
		(net "M_E_CPU0_SA_DQS_DP<9>")
	)
	(segment
		(start 289.040316 -240.560352)
		(end 287.08731 -240.560352)
		(width 0.16002)
		(layer "In6.Cu")
		(net "M_E_CPU0_SA_DQS_DP<9>")
	)
	(segment
		(start 330.581 -247.724168)
		(end 330.427076 -247.458738)
		(width 0.09525)
		(layer "In6.Cu")
		(net "M_E_CPU0_SA_DQS_DP<9>")
	)
	(segment
		(start 325.780146 -247.362472)
		(end 325.779638 -247.362726)
		(width 0.09525)
		(layer "In6.Cu")
		(net "M_E_CPU0_SA_DQS_DP<9>")
	)
	(segment
		(start 291.437568 -239.726978)
		(end 291.051742 -239.341152)
		(width 0.16002)
		(layer "In6.Cu")
		(net "M_E_CPU0_SA_DQS_DP<9>")
	)
	(segment
		(start 276.00656 -239.380522)
		(end 275.523452 -239.380522)
		(width 0.16002)
		(layer "In6.Cu")
		(net "M_E_CPU0_SA_DQS_DP<9>")
	)
	(segment
		(start 325.779638 -247.362726)
		(end 325.779384 -247.362218)
		(width 0.09525)
		(layer "In6.Cu")
		(net "M_E_CPU0_SA_DQS_DP<9>")
	)
	(segment
		(start 329.829668 -247.399048)
		(end 329.821286 -247.394222)
		(width 0.09525)
		(layer "In6.Cu")
		(net "M_E_CPU0_SA_DQS_DP<9>")
	)
	(arc
		(start 329.452478 -247.399048)
		(mid 329.171046 -247.474803)
		(end 328.889614 -247.399048)
		(width 0.09525)
		(layer "In6.Cu")
		(net "M_E_CPU0_SA_DQS_DP<9>")
	)
	(arc
		(start 329.821286 -247.394222)
		(mid 329.636254 -247.348308)
		(end 329.452478 -247.399048)
		(width 0.09525)
		(layer "In6.Cu")
		(net "M_E_CPU0_SA_DQS_DP<9>")
	)
	(arc
		(start 325.611236 -247.453658)
		(mid 325.422751 -247.579887)
		(end 325.200264 -247.624092)
		(width 0.09525)
		(layer "In6.Cu")
		(net "M_E_CPU0_SA_DQS_DP<9>")
	)
	(arc
		(start 328.889614 -247.399048)
		(mid 328.701146 -247.348371)
		(end 328.512678 -247.399048)
		(width 0.09525)
		(layer "In6.Cu")
		(net "M_E_CPU0_SA_DQS_DP<9>")
	)
	(arc
		(start 327.949814 -247.399048)
		(mid 327.768198 -247.348311)
		(end 327.584816 -247.39219)
		(width 0.09525)
		(layer "In6.Cu")
		(net "M_E_CPU0_SA_DQS_DP<9>")
	)
	(arc
		(start 330.326238 -247.432068)
		(mid 330.31637 -247.436099)
		(end 330.306426 -247.439942)
		(width 0.09525)
		(layer "In6.Cu")
		(net "M_E_CPU0_SA_DQS_DP<9>")
	)
	(arc
		(start 326.061832 -247.394222)
		(mid 325.924097 -247.350762)
		(end 325.780146 -247.362472)
		(width 0.09525)
		(layer "In6.Cu")
		(net "M_E_CPU0_SA_DQS_DP<9>")
	)
	(arc
		(start 330.306426 -247.439942)
		(mid 330.063462 -247.472929)
		(end 329.829668 -247.399048)
		(width 0.09525)
		(layer "In6.Cu")
		(net "M_E_CPU0_SA_DQS_DP<9>")
	)
	(arc
		(start 326.632824 -247.399048)
		(mid 326.361882 -247.474828)
		(end 326.088248 -247.409462)
		(width 0.09525)
		(layer "In6.Cu")
		(net "M_E_CPU0_SA_DQS_DP<9>")
	)
	(arc
		(start 328.512678 -247.399048)
		(mid 328.231246 -247.474803)
		(end 327.949814 -247.399048)
		(width 0.09525)
		(layer "In6.Cu")
		(net "M_E_CPU0_SA_DQS_DP<9>")
	)
	(arc
		(start 325.779384 -247.362218)
		(mid 325.743332 -247.371572)
		(end 325.706994 -247.379744)
		(width 0.09525)
		(layer "In6.Cu")
		(net "M_E_CPU0_SA_DQS_DP<9>")
	)
	(arc
		(start 325.706994 -247.379744)
		(mid 325.680641 -247.38932)
		(end 325.658226 -247.40616)
		(width 0.09525)
		(layer "In6.Cu")
		(net "M_E_CPU0_SA_DQS_DP<9>")
	)
	(arc
		(start 326.99833 -247.39219)
		(mid 326.814695 -247.34824)
		(end 326.632824 -247.399048)
		(width 0.09525)
		(layer "In6.Cu")
		(net "M_E_CPU0_SA_DQS_DP<9>")
	)
	(arc
		(start 327.562464 -247.405144)
		(mid 327.285556 -247.474821)
		(end 327.010268 -247.399048)
		(width 0.09525)
		(layer "In6.Cu")
		(net "M_E_CPU0_SA_DQS_DP<9>")
	)
	(segment
		(start 331.047852 -243.13007)
		(end 330.581 -242.864132)
		(width 0.12954)
		(layer "F.Cu")
		(net "M_E_CPU0_SA_DQS_DP<8>")
	)
	(segment
		(start 297.396916 -230.875332)
		(end 296.919396 -230.875332)
		(width 0.16002)
		(layer "In6.Cu")
		(net "M_E_CPU0_SA_DQS_DP<8>")
	)
	(segment
		(start 307.871876 -230.651812)
		(end 306.800504 -230.651812)
		(width 0.16002)
		(layer "In6.Cu")
		(net "M_E_CPU0_SA_DQS_DP<8>")
	)
	(segment
		(start 306.13985 -229.991158)
		(end 305.825144 -229.991158)
		(width 0.16002)
		(layer "In6.Cu")
		(net "M_E_CPU0_SA_DQS_DP<8>")
	)
	(segment
		(start 306.800504 -230.651812)
		(end 306.13985 -229.991158)
		(width 0.16002)
		(layer "In6.Cu")
		(net "M_E_CPU0_SA_DQS_DP<8>")
	)
	(segment
		(start 324.608698 -242.1382)
		(end 324.186804 -241.716306)
		(width 0.09525)
		(layer "In6.Cu")
		(net "M_E_CPU0_SA_DQS_DP<8>")
	)
	(segment
		(start 280.105358 -231.210358)
		(end 279.202134 -230.836216)
		(width 0.16002)
		(layer "In6.Cu")
		(net "M_E_CPU0_SA_DQS_DP<8>")
	)
	(segment
		(start 324.186804 -241.620802)
		(end 324.091554 -241.525552)
		(width 0.09525)
		(layer "In6.Cu")
		(net "M_E_CPU0_SA_DQS_DP<8>")
	)
	(segment
		(start 298.28109 -229.991158)
		(end 297.396916 -230.875332)
		(width 0.16002)
		(layer "In6.Cu")
		(net "M_E_CPU0_SA_DQS_DP<8>")
	)
	(segment
		(start 278.417274 -230.376984)
		(end 276.69109 -230.376984)
		(width 0.16002)
		(layer "In6.Cu")
		(net "M_E_CPU0_SA_DQS_DP<8>")
	)
	(segment
		(start 291.420804 -230.36022)
		(end 291.051742 -229.991158)
		(width 0.16002)
		(layer "In6.Cu")
		(net "M_E_CPU0_SA_DQS_DP<8>")
	)
	(segment
		(start 286.237172 -230.36022)
		(end 283.877004 -230.36022)
		(width 0.16002)
		(layer "In6.Cu")
		(net "M_E_CPU0_SA_DQS_DP<8>")
	)
	(segment
		(start 310.362346 -233.142282)
		(end 307.871876 -230.651812)
		(width 0.16002)
		(layer "In6.Cu")
		(net "M_E_CPU0_SA_DQS_DP<8>")
	)
	(segment
		(start 325.881746 -242.487704)
		(end 325.696072 -242.487704)
		(width 0.09525)
		(layer "In6.Cu")
		(net "M_E_CPU0_SA_DQS_DP<8>")
	)
	(segment
		(start 281.766518 -230.875332)
		(end 280.957528 -231.210358)
		(width 0.16002)
		(layer "In6.Cu")
		(net "M_E_CPU0_SA_DQS_DP<8>")
	)
	(segment
		(start 323.919596 -241.58448)
		(end 323.895974 -241.58448)
		(width 0.09525)
		(layer "In6.Cu")
		(net "M_E_CPU0_SA_DQS_DP<8>")
	)
	(segment
		(start 323.978524 -241.525552)
		(end 323.919596 -241.58448)
		(width 0.09525)
		(layer "In6.Cu")
		(net "M_E_CPU0_SA_DQS_DP<8>")
	)
	(segment
		(start 275.504148 -230.030528)
		(end 275.067522 -230.211376)
		(width 0.16002)
		(layer "In6.Cu")
		(net "M_E_CPU0_SA_DQS_DP<8>")
	)
	(segment
		(start 289.375342 -230.875332)
		(end 289.040316 -231.210358)
		(width 0.16002)
		(layer "In6.Cu")
		(net "M_E_CPU0_SA_DQS_DP<8>")
	)
	(segment
		(start 287.08731 -231.210358)
		(end 286.237172 -230.36022)
		(width 0.16002)
		(layer "In6.Cu")
		(net "M_E_CPU0_SA_DQS_DP<8>")
	)
	(segment
		(start 327.010268 -242.539012)
		(end 326.99833 -242.532154)
		(width 0.09525)
		(layer "In6.Cu")
		(net "M_E_CPU0_SA_DQS_DP<8>")
	)
	(segment
		(start 298.964858 -230.36022)
		(end 298.595796 -229.991158)
		(width 0.16002)
		(layer "In6.Cu")
		(net "M_E_CPU0_SA_DQS_DP<8>")
	)
	(segment
		(start 325.346568 -242.1382)
		(end 324.608698 -242.1382)
		(width 0.09525)
		(layer "In6.Cu")
		(net "M_E_CPU0_SA_DQS_DP<8>")
	)
	(segment
		(start 283.193236 -229.991158)
		(end 282.309062 -230.875332)
		(width 0.16002)
		(layer "In6.Cu")
		(net "M_E_CPU0_SA_DQS_DP<8>")
	)
	(segment
		(start 279.202134 -230.836216)
		(end 278.973534 -230.607616)
		(width 0.16002)
		(layer "In6.Cu")
		(net "M_E_CPU0_SA_DQS_DP<8>")
	)
	(segment
		(start 327.572878 -242.539012)
		(end 327.562464 -242.545108)
		(width 0.09525)
		(layer "In6.Cu")
		(net "M_E_CPU0_SA_DQS_DP<8>")
	)
	(segment
		(start 291.051742 -229.991158)
		(end 290.737036 -229.991158)
		(width 0.16002)
		(layer "In6.Cu")
		(net "M_E_CPU0_SA_DQS_DP<8>")
	)
	(segment
		(start 280.957528 -231.210358)
		(end 280.105358 -231.210358)
		(width 0.16002)
		(layer "In6.Cu")
		(net "M_E_CPU0_SA_DQS_DP<8>")
	)
	(segment
		(start 298.595796 -229.991158)
		(end 298.28109 -229.991158)
		(width 0.16002)
		(layer "In6.Cu")
		(net "M_E_CPU0_SA_DQS_DP<8>")
	)
	(segment
		(start 275.067522 -230.211376)
		(end 273.365976 -230.211376)
		(width 0.16002)
		(layer "In6.Cu")
		(net "M_E_CPU0_SA_DQS_DP<8>")
	)
	(segment
		(start 283.877004 -230.36022)
		(end 283.507942 -229.991158)
		(width 0.16002)
		(layer "In6.Cu")
		(net "M_E_CPU0_SA_DQS_DP<8>")
	)
	(segment
		(start 276.69109 -230.376984)
		(end 275.854668 -230.030528)
		(width 0.16002)
		(layer "In6.Cu")
		(net "M_E_CPU0_SA_DQS_DP<8>")
	)
	(segment
		(start 283.507942 -229.991158)
		(end 283.193236 -229.991158)
		(width 0.16002)
		(layer "In6.Cu")
		(net "M_E_CPU0_SA_DQS_DP<8>")
	)
	(segment
		(start 305.825144 -229.991158)
		(end 304.94097 -230.875332)
		(width 0.16002)
		(layer "In6.Cu")
		(net "M_E_CPU0_SA_DQS_DP<8>")
	)
	(segment
		(start 330.581 -242.864132)
		(end 330.427076 -242.598702)
		(width 0.09525)
		(layer "In6.Cu")
		(net "M_E_CPU0_SA_DQS_DP<8>")
	)
	(segment
		(start 311.387998 -235.617766)
		(end 310.362346 -233.142282)
		(width 0.16002)
		(layer "In6.Cu")
		(net "M_E_CPU0_SA_DQS_DP<8>")
	)
	(segment
		(start 317.354712 -241.58448)
		(end 311.387998 -235.617766)
		(width 0.16002)
		(layer "In6.Cu")
		(net "M_E_CPU0_SA_DQS_DP<8>")
	)
	(segment
		(start 275.854668 -230.030528)
		(end 275.504148 -230.030528)
		(width 0.16002)
		(layer "In6.Cu")
		(net "M_E_CPU0_SA_DQS_DP<8>")
	)
	(segment
		(start 289.852862 -230.875332)
		(end 289.375342 -230.875332)
		(width 0.16002)
		(layer "In6.Cu")
		(net "M_E_CPU0_SA_DQS_DP<8>")
	)
	(segment
		(start 324.091554 -241.525552)
		(end 323.978524 -241.525552)
		(width 0.09525)
		(layer "In6.Cu")
		(net "M_E_CPU0_SA_DQS_DP<8>")
	)
	(segment
		(start 323.895974 -241.58448)
		(end 317.354712 -241.58448)
		(width 0.16002)
		(layer "In6.Cu")
		(net "M_E_CPU0_SA_DQS_DP<8>")
	)
	(segment
		(start 330.427076 -242.598702)
		(end 330.326238 -242.572032)
		(width 0.09525)
		(layer "In6.Cu")
		(net "M_E_CPU0_SA_DQS_DP<8>")
	)
	(segment
		(start 326.088248 -242.549426)
		(end 326.070214 -242.539012)
		(width 0.09525)
		(layer "In6.Cu")
		(net "M_E_CPU0_SA_DQS_DP<8>")
	)
	(segment
		(start 296.58437 -231.210358)
		(end 294.723566 -231.210358)
		(width 0.16002)
		(layer "In6.Cu")
		(net "M_E_CPU0_SA_DQS_DP<8>")
	)
	(segment
		(start 278.973534 -230.607616)
		(end 278.417274 -230.376984)
		(width 0.16002)
		(layer "In6.Cu")
		(net "M_E_CPU0_SA_DQS_DP<8>")
	)
	(segment
		(start 327.584816 -242.532154)
		(end 327.572878 -242.539012)
		(width 0.09525)
		(layer "In6.Cu")
		(net "M_E_CPU0_SA_DQS_DP<8>")
	)
	(segment
		(start 290.737036 -229.991158)
		(end 289.852862 -230.875332)
		(width 0.16002)
		(layer "In6.Cu")
		(net "M_E_CPU0_SA_DQS_DP<8>")
	)
	(segment
		(start 282.309062 -230.875332)
		(end 281.766518 -230.875332)
		(width 0.16002)
		(layer "In6.Cu")
		(net "M_E_CPU0_SA_DQS_DP<8>")
	)
	(segment
		(start 273.365976 -230.211376)
		(end 273.092164 -230.485188)
		(width 0.16002)
		(layer "In6.Cu")
		(net "M_E_CPU0_SA_DQS_DP<8>")
	)
	(segment
		(start 294.723566 -231.210358)
		(end 293.873428 -230.36022)
		(width 0.16002)
		(layer "In6.Cu")
		(net "M_E_CPU0_SA_DQS_DP<8>")
	)
	(segment
		(start 296.919396 -230.875332)
		(end 296.58437 -231.210358)
		(width 0.16002)
		(layer "In6.Cu")
		(net "M_E_CPU0_SA_DQS_DP<8>")
	)
	(segment
		(start 329.829668 -242.539012)
		(end 329.821286 -242.534186)
		(width 0.09525)
		(layer "In6.Cu")
		(net "M_E_CPU0_SA_DQS_DP<8>")
	)
	(segment
		(start 289.040316 -231.210358)
		(end 287.08731 -231.210358)
		(width 0.16002)
		(layer "In6.Cu")
		(net "M_E_CPU0_SA_DQS_DP<8>")
	)
	(segment
		(start 293.873428 -230.36022)
		(end 291.420804 -230.36022)
		(width 0.16002)
		(layer "In6.Cu")
		(net "M_E_CPU0_SA_DQS_DP<8>")
	)
	(segment
		(start 324.186804 -241.716306)
		(end 324.186804 -241.620802)
		(width 0.09525)
		(layer "In6.Cu")
		(net "M_E_CPU0_SA_DQS_DP<8>")
	)
	(segment
		(start 301.417482 -230.36022)
		(end 298.964858 -230.36022)
		(width 0.16002)
		(layer "In6.Cu")
		(net "M_E_CPU0_SA_DQS_DP<8>")
	)
	(segment
		(start 304.94097 -230.875332)
		(end 301.932594 -230.875332)
		(width 0.16002)
		(layer "In6.Cu")
		(net "M_E_CPU0_SA_DQS_DP<8>")
	)
	(segment
		(start 301.932594 -230.875332)
		(end 301.417482 -230.36022)
		(width 0.16002)
		(layer "In6.Cu")
		(net "M_E_CPU0_SA_DQS_DP<8>")
	)
	(segment
		(start 325.696072 -242.487704)
		(end 325.346568 -242.1382)
		(width 0.09525)
		(layer "In6.Cu")
		(net "M_E_CPU0_SA_DQS_DP<8>")
	)
	(arc
		(start 326.070214 -242.539012)
		(mid 325.979371 -242.500893)
		(end 325.881746 -242.487704)
		(width 0.09525)
		(layer "In6.Cu")
		(net "M_E_CPU0_SA_DQS_DP<8>")
	)
	(arc
		(start 327.949814 -242.539012)
		(mid 327.768198 -242.488275)
		(end 327.584816 -242.532154)
		(width 0.09525)
		(layer "In6.Cu")
		(net "M_E_CPU0_SA_DQS_DP<8>")
	)
	(arc
		(start 329.452478 -242.539012)
		(mid 329.171046 -242.614767)
		(end 328.889614 -242.539012)
		(width 0.09525)
		(layer "In6.Cu")
		(net "M_E_CPU0_SA_DQS_DP<8>")
	)
	(arc
		(start 326.99833 -242.532154)
		(mid 326.814695 -242.488204)
		(end 326.632824 -242.539012)
		(width 0.09525)
		(layer "In6.Cu")
		(net "M_E_CPU0_SA_DQS_DP<8>")
	)
	(arc
		(start 326.632824 -242.539012)
		(mid 326.361882 -242.614792)
		(end 326.088248 -242.549426)
		(width 0.09525)
		(layer "In6.Cu")
		(net "M_E_CPU0_SA_DQS_DP<8>")
	)
	(arc
		(start 330.306426 -242.579906)
		(mid 330.063462 -242.612893)
		(end 329.829668 -242.539012)
		(width 0.09525)
		(layer "In6.Cu")
		(net "M_E_CPU0_SA_DQS_DP<8>")
	)
	(arc
		(start 328.512678 -242.539012)
		(mid 328.231246 -242.614767)
		(end 327.949814 -242.539012)
		(width 0.09525)
		(layer "In6.Cu")
		(net "M_E_CPU0_SA_DQS_DP<8>")
	)
	(arc
		(start 327.562464 -242.545108)
		(mid 327.285556 -242.614785)
		(end 327.010268 -242.539012)
		(width 0.09525)
		(layer "In6.Cu")
		(net "M_E_CPU0_SA_DQS_DP<8>")
	)
	(arc
		(start 328.889614 -242.539012)
		(mid 328.701146 -242.488335)
		(end 328.512678 -242.539012)
		(width 0.09525)
		(layer "In6.Cu")
		(net "M_E_CPU0_SA_DQS_DP<8>")
	)
	(arc
		(start 329.821286 -242.534186)
		(mid 329.636254 -242.488272)
		(end 329.452478 -242.539012)
		(width 0.09525)
		(layer "In6.Cu")
		(net "M_E_CPU0_SA_DQS_DP<8>")
	)
	(arc
		(start 330.326238 -242.572032)
		(mid 330.31637 -242.576063)
		(end 330.306426 -242.579906)
		(width 0.09525)
		(layer "In6.Cu")
		(net "M_E_CPU0_SA_DQS_DP<8>")
	)
	(segment
		(start 331.047852 -238.270034)
		(end 330.581 -238.004096)
		(width 0.12954)
		(layer "F.Cu")
		(net "M_E_CPU0_SA_DQS_DP<7>")
	)
	(segment
		(start 296.088562 -221.86011)
		(end 294.701976 -221.86011)
		(width 0.16002)
		(layer "In6.Cu")
		(net "M_E_CPU0_SA_DQS_DP<7>")
	)
	(segment
		(start 323.895974 -235.915962)
		(end 321.198494 -235.915962)
		(width 0.16002)
		(layer "In6.Cu")
		(net "M_E_CPU0_SA_DQS_DP<7>")
	)
	(segment
		(start 329.829668 -237.678976)
		(end 329.821286 -237.67415)
		(width 0.09525)
		(layer "In6.Cu")
		(net "M_E_CPU0_SA_DQS_DP<7>")
	)
	(segment
		(start 276.346666 -221.041976)
		(end 276.00021 -220.69552)
		(width 0.16002)
		(layer "In6.Cu")
		(net "M_E_CPU0_SA_DQS_DP<7>")
	)
	(segment
		(start 324.924928 -236.26826)
		(end 324.5104 -236.26826)
		(width 0.09525)
		(layer "In6.Cu")
		(net "M_E_CPU0_SA_DQS_DP<7>")
	)
	(segment
		(start 289.243516 -221.540324)
		(end 288.471356 -221.86011)
		(width 0.16002)
		(layer "In6.Cu")
		(net "M_E_CPU0_SA_DQS_DP<7>")
	)
	(segment
		(start 325.164704 -236.508036)
		(end 324.924928 -236.26826)
		(width 0.09525)
		(layer "In6.Cu")
		(net "M_E_CPU0_SA_DQS_DP<7>")
	)
	(segment
		(start 305.831494 -220.656404)
		(end 304.94732 -221.540578)
		(width 0.16002)
		(layer "In6.Cu")
		(net "M_E_CPU0_SA_DQS_DP<7>")
	)
	(segment
		(start 301.926244 -221.540578)
		(end 301.395892 -221.010226)
		(width 0.16002)
		(layer "In6.Cu")
		(net "M_E_CPU0_SA_DQS_DP<7>")
	)
	(segment
		(start 282.315412 -221.540324)
		(end 281.772868 -221.540324)
		(width 0.16002)
		(layer "In6.Cu")
		(net "M_E_CPU0_SA_DQS_DP<7>")
	)
	(segment
		(start 325.164704 -236.657642)
		(end 325.164704 -236.508036)
		(width 0.09525)
		(layer "In6.Cu")
		(net "M_E_CPU0_SA_DQS_DP<7>")
	)
	(segment
		(start 326.012048 -237.63224)
		(end 325.254112 -236.87405)
		(width 0.09525)
		(layer "In6.Cu")
		(net "M_E_CPU0_SA_DQS_DP<7>")
	)
	(segment
		(start 324.099174 -235.857034)
		(end 323.978524 -235.857034)
		(width 0.09525)
		(layer "In6.Cu")
		(net "M_E_CPU0_SA_DQS_DP<7>")
	)
	(segment
		(start 290.743386 -220.65615)
		(end 289.859212 -221.540324)
		(width 0.16002)
		(layer "In6.Cu")
		(net "M_E_CPU0_SA_DQS_DP<7>")
	)
	(segment
		(start 310.298338 -223.986598)
		(end 310.298338 -222.405194)
		(width 0.16002)
		(layer "In6.Cu")
		(net "M_E_CPU0_SA_DQS_DP<7>")
	)
	(segment
		(start 330.581 -238.004096)
		(end 330.427076 -237.738666)
		(width 0.09525)
		(layer "In6.Cu")
		(net "M_E_CPU0_SA_DQS_DP<7>")
	)
	(segment
		(start 297.403266 -221.540324)
		(end 296.860722 -221.540324)
		(width 0.16002)
		(layer "In6.Cu")
		(net "M_E_CPU0_SA_DQS_DP<7>")
	)
	(segment
		(start 298.943522 -221.010226)
		(end 298.589446 -220.65615)
		(width 0.16002)
		(layer "In6.Cu")
		(net "M_E_CPU0_SA_DQS_DP<7>")
	)
	(segment
		(start 296.860722 -221.540324)
		(end 296.088562 -221.86011)
		(width 0.16002)
		(layer "In6.Cu")
		(net "M_E_CPU0_SA_DQS_DP<7>")
	)
	(segment
		(start 298.589446 -220.65615)
		(end 298.28744 -220.65615)
		(width 0.16002)
		(layer "In6.Cu")
		(net "M_E_CPU0_SA_DQS_DP<7>")
	)
	(segment
		(start 323.978524 -235.857034)
		(end 323.919596 -235.915962)
		(width 0.09525)
		(layer "In6.Cu")
		(net "M_E_CPU0_SA_DQS_DP<7>")
	)
	(segment
		(start 281.772868 -221.540324)
		(end 281.000708 -221.86011)
		(width 0.16002)
		(layer "In6.Cu")
		(net "M_E_CPU0_SA_DQS_DP<7>")
	)
	(segment
		(start 286.215836 -221.010226)
		(end 284.356556 -221.010226)
		(width 0.16002)
		(layer "In6.Cu")
		(net "M_E_CPU0_SA_DQS_DP<7>")
	)
	(segment
		(start 280.247852 -221.86011)
		(end 278.272748 -221.041976)
		(width 0.16002)
		(layer "In6.Cu")
		(net "M_E_CPU0_SA_DQS_DP<7>")
	)
	(segment
		(start 312.652918 -227.370386)
		(end 312.652918 -226.341178)
		(width 0.16002)
		(layer "In6.Cu")
		(net "M_E_CPU0_SA_DQS_DP<7>")
	)
	(segment
		(start 306.834286 -221.35719)
		(end 306.1335 -220.656404)
		(width 0.16002)
		(layer "In6.Cu")
		(net "M_E_CPU0_SA_DQS_DP<7>")
	)
	(segment
		(start 291.110416 -220.65615)
		(end 290.743386 -220.65615)
		(width 0.16002)
		(layer "In6.Cu")
		(net "M_E_CPU0_SA_DQS_DP<7>")
	)
	(segment
		(start 275.44014 -220.69552)
		(end 275.274532 -220.861128)
		(width 0.16002)
		(layer "In6.Cu")
		(net "M_E_CPU0_SA_DQS_DP<7>")
	)
	(segment
		(start 293.852092 -221.010226)
		(end 291.96538 -221.010226)
		(width 0.16002)
		(layer "In6.Cu")
		(net "M_E_CPU0_SA_DQS_DP<7>")
	)
	(segment
		(start 301.395892 -221.010226)
		(end 298.943522 -221.010226)
		(width 0.16002)
		(layer "In6.Cu")
		(net "M_E_CPU0_SA_DQS_DP<7>")
	)
	(segment
		(start 304.94732 -221.540578)
		(end 301.926244 -221.540578)
		(width 0.16002)
		(layer "In6.Cu")
		(net "M_E_CPU0_SA_DQS_DP<7>")
	)
	(segment
		(start 291.96538 -221.010226)
		(end 291.110416 -220.65615)
		(width 0.16002)
		(layer "In6.Cu")
		(net "M_E_CPU0_SA_DQS_DP<7>")
	)
	(segment
		(start 288.471356 -221.86011)
		(end 287.06572 -221.86011)
		(width 0.16002)
		(layer "In6.Cu")
		(net "M_E_CPU0_SA_DQS_DP<7>")
	)
	(segment
		(start 278.272748 -221.041976)
		(end 276.346666 -221.041976)
		(width 0.16002)
		(layer "In6.Cu")
		(net "M_E_CPU0_SA_DQS_DP<7>")
	)
	(segment
		(start 283.501592 -220.65615)
		(end 283.199586 -220.65615)
		(width 0.16002)
		(layer "In6.Cu")
		(net "M_E_CPU0_SA_DQS_DP<7>")
	)
	(segment
		(start 327.584816 -237.672118)
		(end 327.572878 -237.678976)
		(width 0.09525)
		(layer "In6.Cu")
		(net "M_E_CPU0_SA_DQS_DP<7>")
	)
	(segment
		(start 330.427076 -237.738666)
		(end 330.326238 -237.711996)
		(width 0.09525)
		(layer "In6.Cu")
		(net "M_E_CPU0_SA_DQS_DP<7>")
	)
	(segment
		(start 281.000708 -221.86011)
		(end 280.247852 -221.86011)
		(width 0.16002)
		(layer "In6.Cu")
		(net "M_E_CPU0_SA_DQS_DP<7>")
	)
	(segment
		(start 276.00021 -220.69552)
		(end 275.44014 -220.69552)
		(width 0.16002)
		(layer "In6.Cu")
		(net "M_E_CPU0_SA_DQS_DP<7>")
	)
	(segment
		(start 283.199586 -220.65615)
		(end 282.315412 -221.540324)
		(width 0.16002)
		(layer "In6.Cu")
		(net "M_E_CPU0_SA_DQS_DP<7>")
	)
	(segment
		(start 327.572878 -237.678976)
		(end 327.562464 -237.685072)
		(width 0.09525)
		(layer "In6.Cu")
		(net "M_E_CPU0_SA_DQS_DP<7>")
	)
	(segment
		(start 312.652918 -226.341178)
		(end 310.298338 -223.986598)
		(width 0.16002)
		(layer "In6.Cu")
		(net "M_E_CPU0_SA_DQS_DP<7>")
	)
	(segment
		(start 273.365976 -220.861128)
		(end 273.092164 -221.13494)
		(width 0.16002)
		(layer "In6.Cu")
		(net "M_E_CPU0_SA_DQS_DP<7>")
	)
	(segment
		(start 310.298338 -222.405194)
		(end 309.250334 -221.35719)
		(width 0.16002)
		(layer "In6.Cu")
		(net "M_E_CPU0_SA_DQS_DP<7>")
	)
	(segment
		(start 287.06572 -221.86011)
		(end 286.215836 -221.010226)
		(width 0.16002)
		(layer "In6.Cu")
		(net "M_E_CPU0_SA_DQS_DP<7>")
	)
	(segment
		(start 284.356556 -221.010226)
		(end 283.501592 -220.65615)
		(width 0.16002)
		(layer "In6.Cu")
		(net "M_E_CPU0_SA_DQS_DP<7>")
	)
	(segment
		(start 294.701976 -221.86011)
		(end 293.852092 -221.010226)
		(width 0.16002)
		(layer "In6.Cu")
		(net "M_E_CPU0_SA_DQS_DP<7>")
	)
	(segment
		(start 298.28744 -220.65615)
		(end 297.403266 -221.540324)
		(width 0.16002)
		(layer "In6.Cu")
		(net "M_E_CPU0_SA_DQS_DP<7>")
	)
	(segment
		(start 321.198494 -235.915962)
		(end 312.652918 -227.370386)
		(width 0.16002)
		(layer "In6.Cu")
		(net "M_E_CPU0_SA_DQS_DP<7>")
	)
	(segment
		(start 324.5104 -236.26826)
		(end 324.099174 -235.857034)
		(width 0.09525)
		(layer "In6.Cu")
		(net "M_E_CPU0_SA_DQS_DP<7>")
	)
	(segment
		(start 327.010268 -237.678976)
		(end 326.99833 -237.672118)
		(width 0.09525)
		(layer "In6.Cu")
		(net "M_E_CPU0_SA_DQS_DP<7>")
	)
	(segment
		(start 309.250334 -221.35719)
		(end 306.834286 -221.35719)
		(width 0.16002)
		(layer "In6.Cu")
		(net "M_E_CPU0_SA_DQS_DP<7>")
	)
	(segment
		(start 306.1335 -220.656404)
		(end 305.831494 -220.656404)
		(width 0.16002)
		(layer "In6.Cu")
		(net "M_E_CPU0_SA_DQS_DP<7>")
	)
	(segment
		(start 275.274532 -220.861128)
		(end 273.365976 -220.861128)
		(width 0.16002)
		(layer "In6.Cu")
		(net "M_E_CPU0_SA_DQS_DP<7>")
	)
	(segment
		(start 289.859212 -221.540324)
		(end 289.243516 -221.540324)
		(width 0.16002)
		(layer "In6.Cu")
		(net "M_E_CPU0_SA_DQS_DP<7>")
	)
	(segment
		(start 323.919596 -235.915962)
		(end 323.895974 -235.915962)
		(width 0.09525)
		(layer "In6.Cu")
		(net "M_E_CPU0_SA_DQS_DP<7>")
	)
	(arc
		(start 328.512678 -237.678976)
		(mid 328.231246 -237.754731)
		(end 327.949814 -237.678976)
		(width 0.09525)
		(layer "In6.Cu")
		(net "M_E_CPU0_SA_DQS_DP<7>")
	)
	(arc
		(start 325.254112 -236.87405)
		(mid 325.187882 -236.774745)
		(end 325.164704 -236.657642)
		(width 0.09525)
		(layer "In6.Cu")
		(net "M_E_CPU0_SA_DQS_DP<7>")
	)
	(arc
		(start 327.949814 -237.678976)
		(mid 327.768198 -237.628239)
		(end 327.584816 -237.672118)
		(width 0.09525)
		(layer "In6.Cu")
		(net "M_E_CPU0_SA_DQS_DP<7>")
	)
	(arc
		(start 329.452478 -237.678976)
		(mid 329.171046 -237.754731)
		(end 328.889614 -237.678976)
		(width 0.09525)
		(layer "In6.Cu")
		(net "M_E_CPU0_SA_DQS_DP<7>")
	)
	(arc
		(start 326.632824 -237.678976)
		(mid 326.404211 -237.753443)
		(end 326.16521 -237.727236)
		(width 0.09525)
		(layer "In6.Cu")
		(net "M_E_CPU0_SA_DQS_DP<7>")
	)
	(arc
		(start 326.16521 -237.727236)
		(mid 326.08308 -237.688682)
		(end 326.012048 -237.63224)
		(width 0.09525)
		(layer "In6.Cu")
		(net "M_E_CPU0_SA_DQS_DP<7>")
	)
	(arc
		(start 326.99833 -237.672118)
		(mid 326.814695 -237.628168)
		(end 326.632824 -237.678976)
		(width 0.09525)
		(layer "In6.Cu")
		(net "M_E_CPU0_SA_DQS_DP<7>")
	)
	(arc
		(start 330.326238 -237.711996)
		(mid 330.31637 -237.716027)
		(end 330.306426 -237.71987)
		(width 0.09525)
		(layer "In6.Cu")
		(net "M_E_CPU0_SA_DQS_DP<7>")
	)
	(arc
		(start 330.306426 -237.71987)
		(mid 330.063462 -237.752857)
		(end 329.829668 -237.678976)
		(width 0.09525)
		(layer "In6.Cu")
		(net "M_E_CPU0_SA_DQS_DP<7>")
	)
	(arc
		(start 327.562464 -237.685072)
		(mid 327.285556 -237.754749)
		(end 327.010268 -237.678976)
		(width 0.09525)
		(layer "In6.Cu")
		(net "M_E_CPU0_SA_DQS_DP<7>")
	)
	(arc
		(start 328.889614 -237.678976)
		(mid 328.701146 -237.628299)
		(end 328.512678 -237.678976)
		(width 0.09525)
		(layer "In6.Cu")
		(net "M_E_CPU0_SA_DQS_DP<7>")
	)
	(arc
		(start 329.821286 -237.67415)
		(mid 329.636254 -237.628236)
		(end 329.452478 -237.678976)
		(width 0.09525)
		(layer "In6.Cu")
		(net "M_E_CPU0_SA_DQS_DP<7>")
	)
	(segment
		(start 331.047852 -233.409998)
		(end 330.581 -233.14406)
		(width 0.12954)
		(layer "F.Cu")
		(net "M_E_CPU0_SA_DQS_DP<6>")
	)
	(segment
		(start 306.49926 -212.749892)
		(end 305.670712 -212.749892)
		(width 0.16002)
		(layer "In6.Cu")
		(net "M_E_CPU0_SA_DQS_DP<6>")
	)
	(segment
		(start 288.501328 -212.510116)
		(end 287.08731 -212.510116)
		(width 0.16002)
		(layer "In6.Cu")
		(net "M_E_CPU0_SA_DQS_DP<6>")
	)
	(segment
		(start 305.096164 -212.175344)
		(end 301.932594 -212.175344)
		(width 0.16002)
		(layer "In6.Cu")
		(net "M_E_CPU0_SA_DQS_DP<6>")
	)
	(segment
		(start 286.237426 -211.660232)
		(end 283.877258 -211.660232)
		(width 0.16002)
		(layer "In6.Cu")
		(net "M_E_CPU0_SA_DQS_DP<6>")
	)
	(segment
		(start 283.507942 -211.290916)
		(end 283.193236 -211.290916)
		(width 0.16002)
		(layer "In6.Cu")
		(net "M_E_CPU0_SA_DQS_DP<6>")
	)
	(segment
		(start 296.045382 -212.510116)
		(end 294.723566 -212.510116)
		(width 0.16002)
		(layer "In6.Cu")
		(net "M_E_CPU0_SA_DQS_DP<6>")
	)
	(segment
		(start 327.010268 -232.81894)
		(end 327.010268 -232.818178)
		(width 0.09525)
		(layer "In6.Cu")
		(net "M_E_CPU0_SA_DQS_DP<6>")
	)
	(segment
		(start 283.877258 -211.660232)
		(end 283.507942 -211.290916)
		(width 0.16002)
		(layer "In6.Cu")
		(net "M_E_CPU0_SA_DQS_DP<6>")
	)
	(segment
		(start 301.417482 -211.660232)
		(end 298.965112 -211.660232)
		(width 0.16002)
		(layer "In6.Cu")
		(net "M_E_CPU0_SA_DQS_DP<6>")
	)
	(segment
		(start 325.318628 -231.530906)
		(end 324.997064 -231.209342)
		(width 0.09525)
		(layer "In6.Cu")
		(net "M_E_CPU0_SA_DQS_DP<6>")
	)
	(segment
		(start 323.626734 -230.183944)
		(end 323.505068 -230.183944)
		(width 0.09525)
		(layer "In6.Cu")
		(net "M_E_CPU0_SA_DQS_DP<6>")
	)
	(segment
		(start 293.873682 -211.660232)
		(end 291.421058 -211.660232)
		(width 0.16002)
		(layer "In6.Cu")
		(net "M_E_CPU0_SA_DQS_DP<6>")
	)
	(segment
		(start 327.584816 -232.812082)
		(end 327.572878 -232.81894)
		(width 0.09525)
		(layer "In6.Cu")
		(net "M_E_CPU0_SA_DQS_DP<6>")
	)
	(segment
		(start 273.365976 -211.511134)
		(end 273.092164 -211.784946)
		(width 0.16002)
		(layer "In6.Cu")
		(net "M_E_CPU0_SA_DQS_DP<6>")
	)
	(segment
		(start 306.79644 -212.452712)
		(end 306.49926 -212.749892)
		(width 0.16002)
		(layer "In6.Cu")
		(net "M_E_CPU0_SA_DQS_DP<6>")
	)
	(segment
		(start 330.427076 -232.87863)
		(end 330.326238 -232.85196)
		(width 0.09525)
		(layer "In6.Cu")
		(net "M_E_CPU0_SA_DQS_DP<6>")
	)
	(segment
		(start 276.353016 -211.676742)
		(end 276.00656 -211.330286)
		(width 0.16002)
		(layer "In6.Cu")
		(net "M_E_CPU0_SA_DQS_DP<6>")
	)
	(segment
		(start 287.08731 -212.510116)
		(end 286.237426 -211.660232)
		(width 0.16002)
		(layer "In6.Cu")
		(net "M_E_CPU0_SA_DQS_DP<6>")
	)
	(segment
		(start 301.932594 -212.175344)
		(end 301.417482 -211.660232)
		(width 0.16002)
		(layer "In6.Cu")
		(net "M_E_CPU0_SA_DQS_DP<6>")
	)
	(segment
		(start 312.460894 -214.700612)
		(end 310.090312 -214.700612)
		(width 0.16002)
		(layer "In6.Cu")
		(net "M_E_CPU0_SA_DQS_DP<6>")
	)
	(segment
		(start 327.010268 -232.818178)
		(end 327.001886 -232.813352)
		(width 0.09525)
		(layer "In6.Cu")
		(net "M_E_CPU0_SA_DQS_DP<6>")
	)
	(segment
		(start 315.982858 -218.222576)
		(end 312.460894 -214.700612)
		(width 0.16002)
		(layer "In6.Cu")
		(net "M_E_CPU0_SA_DQS_DP<6>")
	)
	(segment
		(start 324.997064 -231.209342)
		(end 324.796404 -231.209342)
		(width 0.09525)
		(layer "In6.Cu")
		(net "M_E_CPU0_SA_DQS_DP<6>")
	)
	(segment
		(start 282.692856 -211.791296)
		(end 280.957782 -212.510116)
		(width 0.16002)
		(layer "In6.Cu")
		(net "M_E_CPU0_SA_DQS_DP<6>")
	)
	(segment
		(start 276.00656 -211.330286)
		(end 275.383244 -211.330286)
		(width 0.16002)
		(layer "In6.Cu")
		(net "M_E_CPU0_SA_DQS_DP<6>")
	)
	(segment
		(start 307.842412 -212.452712)
		(end 306.79644 -212.452712)
		(width 0.16002)
		(layer "In6.Cu")
		(net "M_E_CPU0_SA_DQS_DP<6>")
	)
	(segment
		(start 323.802502 -230.359712)
		(end 323.626734 -230.183944)
		(width 0.09525)
		(layer "In6.Cu")
		(net "M_E_CPU0_SA_DQS_DP<6>")
	)
	(segment
		(start 323.488304 -230.16718)
		(end 318.190118 -224.868994)
		(width 0.16002)
		(layer "In6.Cu")
		(net "M_E_CPU0_SA_DQS_DP<6>")
	)
	(segment
		(start 325.965566 -232.731564)
		(end 325.318628 -232.084626)
		(width 0.09525)
		(layer "In6.Cu")
		(net "M_E_CPU0_SA_DQS_DP<6>")
	)
	(segment
		(start 305.670712 -212.749892)
		(end 305.096164 -212.175344)
		(width 0.16002)
		(layer "In6.Cu")
		(net "M_E_CPU0_SA_DQS_DP<6>")
	)
	(segment
		(start 280.957782 -212.510116)
		(end 279.57653 -212.510116)
		(width 0.16002)
		(layer "In6.Cu")
		(net "M_E_CPU0_SA_DQS_DP<6>")
	)
	(segment
		(start 298.595796 -211.290916)
		(end 298.28109 -211.290916)
		(width 0.16002)
		(layer "In6.Cu")
		(net "M_E_CPU0_SA_DQS_DP<6>")
	)
	(segment
		(start 310.090312 -214.700612)
		(end 307.842412 -212.452712)
		(width 0.16002)
		(layer "In6.Cu")
		(net "M_E_CPU0_SA_DQS_DP<6>")
	)
	(segment
		(start 283.193236 -211.290916)
		(end 282.692856 -211.791296)
		(width 0.16002)
		(layer "In6.Cu")
		(net "M_E_CPU0_SA_DQS_DP<6>")
	)
	(segment
		(start 296.854372 -212.17509)
		(end 296.045382 -212.510116)
		(width 0.16002)
		(layer "In6.Cu")
		(net "M_E_CPU0_SA_DQS_DP<6>")
	)
	(segment
		(start 278.743156 -211.676742)
		(end 276.353016 -211.676742)
		(width 0.16002)
		(layer "In6.Cu")
		(net "M_E_CPU0_SA_DQS_DP<6>")
	)
	(segment
		(start 329.829668 -232.81894)
		(end 329.821286 -232.814114)
		(width 0.09525)
		(layer "In6.Cu")
		(net "M_E_CPU0_SA_DQS_DP<6>")
	)
	(segment
		(start 291.051742 -211.290916)
		(end 290.737036 -211.290916)
		(width 0.16002)
		(layer "In6.Cu")
		(net "M_E_CPU0_SA_DQS_DP<6>")
	)
	(segment
		(start 274.946618 -211.511134)
		(end 273.365976 -211.511134)
		(width 0.16002)
		(layer "In6.Cu")
		(net "M_E_CPU0_SA_DQS_DP<6>")
	)
	(segment
		(start 327.572878 -232.81894)
		(end 327.562464 -232.825036)
		(width 0.09525)
		(layer "In6.Cu")
		(net "M_E_CPU0_SA_DQS_DP<6>")
	)
	(segment
		(start 318.190118 -224.868994)
		(end 318.190118 -224.022666)
		(width 0.16002)
		(layer "In6.Cu")
		(net "M_E_CPU0_SA_DQS_DP<6>")
	)
	(segment
		(start 290.737036 -211.290916)
		(end 289.852862 -212.17509)
		(width 0.16002)
		(layer "In6.Cu")
		(net "M_E_CPU0_SA_DQS_DP<6>")
	)
	(segment
		(start 323.505068 -230.183944)
		(end 323.488304 -230.16718)
		(width 0.09525)
		(layer "In6.Cu")
		(net "M_E_CPU0_SA_DQS_DP<6>")
	)
	(segment
		(start 289.852862 -212.17509)
		(end 289.310318 -212.17509)
		(width 0.16002)
		(layer "In6.Cu")
		(net "M_E_CPU0_SA_DQS_DP<6>")
	)
	(segment
		(start 291.421058 -211.660232)
		(end 291.051742 -211.290916)
		(width 0.16002)
		(layer "In6.Cu")
		(net "M_E_CPU0_SA_DQS_DP<6>")
	)
	(segment
		(start 315.982858 -221.815406)
		(end 315.982858 -218.222576)
		(width 0.16002)
		(layer "In6.Cu")
		(net "M_E_CPU0_SA_DQS_DP<6>")
	)
	(segment
		(start 297.396916 -212.17509)
		(end 296.854372 -212.17509)
		(width 0.16002)
		(layer "In6.Cu")
		(net "M_E_CPU0_SA_DQS_DP<6>")
	)
	(segment
		(start 294.723566 -212.510116)
		(end 293.873682 -211.660232)
		(width 0.16002)
		(layer "In6.Cu")
		(net "M_E_CPU0_SA_DQS_DP<6>")
	)
	(segment
		(start 330.581 -233.14406)
		(end 330.427076 -232.87863)
		(width 0.09525)
		(layer "In6.Cu")
		(net "M_E_CPU0_SA_DQS_DP<6>")
	)
	(segment
		(start 324.796404 -231.209342)
		(end 323.946774 -230.359712)
		(width 0.09525)
		(layer "In6.Cu")
		(net "M_E_CPU0_SA_DQS_DP<6>")
	)
	(segment
		(start 275.383244 -211.330286)
		(end 274.946618 -211.511134)
		(width 0.16002)
		(layer "In6.Cu")
		(net "M_E_CPU0_SA_DQS_DP<6>")
	)
	(segment
		(start 323.946774 -230.359712)
		(end 323.802502 -230.359712)
		(width 0.09525)
		(layer "In6.Cu")
		(net "M_E_CPU0_SA_DQS_DP<6>")
	)
	(segment
		(start 325.318628 -232.084626)
		(end 325.318628 -231.530906)
		(width 0.09525)
		(layer "In6.Cu")
		(net "M_E_CPU0_SA_DQS_DP<6>")
	)
	(segment
		(start 289.310318 -212.17509)
		(end 288.501328 -212.510116)
		(width 0.16002)
		(layer "In6.Cu")
		(net "M_E_CPU0_SA_DQS_DP<6>")
	)
	(segment
		(start 298.28109 -211.290916)
		(end 297.396916 -212.17509)
		(width 0.16002)
		(layer "In6.Cu")
		(net "M_E_CPU0_SA_DQS_DP<6>")
	)
	(segment
		(start 298.965112 -211.660232)
		(end 298.595796 -211.290916)
		(width 0.16002)
		(layer "In6.Cu")
		(net "M_E_CPU0_SA_DQS_DP<6>")
	)
	(segment
		(start 279.57653 -212.510116)
		(end 278.743156 -211.676742)
		(width 0.16002)
		(layer "In6.Cu")
		(net "M_E_CPU0_SA_DQS_DP<6>")
	)
	(segment
		(start 318.190118 -224.022666)
		(end 315.982858 -221.815406)
		(width 0.16002)
		(layer "In6.Cu")
		(net "M_E_CPU0_SA_DQS_DP<6>")
	)
	(arc
		(start 326.63257 -232.818686)
		(mid 326.284257 -232.888562)
		(end 325.965566 -232.731564)
		(width 0.09525)
		(layer "In6.Cu")
		(net "M_E_CPU0_SA_DQS_DP<6>")
	)
	(arc
		(start 327.001886 -232.813352)
		(mid 326.816541 -232.76766)
		(end 326.63257 -232.818686)
		(width 0.09525)
		(layer "In6.Cu")
		(net "M_E_CPU0_SA_DQS_DP<6>")
	)
	(arc
		(start 330.306426 -232.859834)
		(mid 330.063462 -232.892821)
		(end 329.829668 -232.81894)
		(width 0.09525)
		(layer "In6.Cu")
		(net "M_E_CPU0_SA_DQS_DP<6>")
	)
	(arc
		(start 329.821286 -232.814114)
		(mid 329.636254 -232.7682)
		(end 329.452478 -232.81894)
		(width 0.09525)
		(layer "In6.Cu")
		(net "M_E_CPU0_SA_DQS_DP<6>")
	)
	(arc
		(start 328.512678 -232.81894)
		(mid 328.231246 -232.894695)
		(end 327.949814 -232.81894)
		(width 0.09525)
		(layer "In6.Cu")
		(net "M_E_CPU0_SA_DQS_DP<6>")
	)
	(arc
		(start 327.562464 -232.825036)
		(mid 327.285556 -232.894713)
		(end 327.010268 -232.81894)
		(width 0.09525)
		(layer "In6.Cu")
		(net "M_E_CPU0_SA_DQS_DP<6>")
	)
	(arc
		(start 327.949814 -232.81894)
		(mid 327.768198 -232.768203)
		(end 327.584816 -232.812082)
		(width 0.09525)
		(layer "In6.Cu")
		(net "M_E_CPU0_SA_DQS_DP<6>")
	)
	(arc
		(start 330.326238 -232.85196)
		(mid 330.31637 -232.855991)
		(end 330.306426 -232.859834)
		(width 0.09525)
		(layer "In6.Cu")
		(net "M_E_CPU0_SA_DQS_DP<6>")
	)
	(arc
		(start 328.889614 -232.81894)
		(mid 328.701146 -232.768263)
		(end 328.512678 -232.81894)
		(width 0.09525)
		(layer "In6.Cu")
		(net "M_E_CPU0_SA_DQS_DP<6>")
	)
	(arc
		(start 329.452478 -232.81894)
		(mid 329.171046 -232.894695)
		(end 328.889614 -232.81894)
		(width 0.09525)
		(layer "In6.Cu")
		(net "M_E_CPU0_SA_DQS_DP<6>")
	)
	(segment
		(start 331.047852 -228.550216)
		(end 330.581 -228.284278)
		(width 0.12954)
		(layer "F.Cu")
		(net "M_E_CPU0_SA_DQS_DP<5>")
	)
	(segment
		(start 325.318882 -223.215962)
		(end 324.993762 -222.890842)
		(width 0.09525)
		(layer "In6.Cu")
		(net "M_E_CPU0_SA_DQS_DP<5>")
	)
	(segment
		(start 325.599806 -223.909128)
		(end 325.561706 -223.88703)
		(width 0.09525)
		(layer "In6.Cu")
		(net "M_E_CPU0_SA_DQS_DP<5>")
	)
	(segment
		(start 290.737036 -201.940922)
		(end 290.236656 -202.441302)
		(width 0.16002)
		(layer "In6.Cu")
		(net "M_E_CPU0_SA_DQS_DP<5>")
	)
	(segment
		(start 298.965112 -202.310238)
		(end 298.595796 -201.940922)
		(width 0.16002)
		(layer "In6.Cu")
		(net "M_E_CPU0_SA_DQS_DP<5>")
	)
	(segment
		(start 283.877258 -202.310238)
		(end 283.507942 -201.940922)
		(width 0.16002)
		(layer "In6.Cu")
		(net "M_E_CPU0_SA_DQS_DP<5>")
	)
	(segment
		(start 330.427076 -228.018848)
		(end 330.326238 -227.992178)
		(width 0.09525)
		(layer "In6.Cu")
		(net "M_E_CPU0_SA_DQS_DP<5>")
	)
	(segment
		(start 304.159158 -203.129642)
		(end 302.236886 -203.129642)
		(width 0.16002)
		(layer "In6.Cu")
		(net "M_E_CPU0_SA_DQS_DP<5>")
	)
	(segment
		(start 305.825144 -201.941176)
		(end 305.324764 -202.441556)
		(width 0.16002)
		(layer "In6.Cu")
		(net "M_E_CPU0_SA_DQS_DP<5>")
	)
	(segment
		(start 286.237426 -202.310238)
		(end 283.877258 -202.310238)
		(width 0.16002)
		(layer "In6.Cu")
		(net "M_E_CPU0_SA_DQS_DP<5>")
	)
	(segment
		(start 305.324764 -202.441556)
		(end 304.509424 -202.779376)
		(width 0.16002)
		(layer "In6.Cu")
		(net "M_E_CPU0_SA_DQS_DP<5>")
	)
	(segment
		(start 287.08731 -203.160122)
		(end 286.237426 -202.310238)
		(width 0.16002)
		(layer "In6.Cu")
		(net "M_E_CPU0_SA_DQS_DP<5>")
	)
	(segment
		(start 330.581 -228.284278)
		(end 330.427076 -228.018848)
		(width 0.09525)
		(layer "In6.Cu")
		(net "M_E_CPU0_SA_DQS_DP<5>")
	)
	(segment
		(start 324.993762 -222.890842)
		(end 324.909942 -222.890842)
		(width 0.09525)
		(layer "In6.Cu")
		(net "M_E_CPU0_SA_DQS_DP<5>")
	)
	(segment
		(start 274.580858 -202.16114)
		(end 273.365976 -202.16114)
		(width 0.16002)
		(layer "In6.Cu")
		(net "M_E_CPU0_SA_DQS_DP<5>")
	)
	(segment
		(start 276.353016 -202.326748)
		(end 276.00656 -201.980292)
		(width 0.16002)
		(layer "In6.Cu")
		(net "M_E_CPU0_SA_DQS_DP<5>")
	)
	(segment
		(start 329.829668 -227.959158)
		(end 329.821286 -227.954332)
		(width 0.09525)
		(layer "In6.Cu")
		(net "M_E_CPU0_SA_DQS_DP<5>")
	)
	(segment
		(start 324.909942 -222.890842)
		(end 324.893178 -222.874078)
		(width 0.09525)
		(layer "In6.Cu")
		(net "M_E_CPU0_SA_DQS_DP<5>")
	)
	(segment
		(start 306.859686 -202.661012)
		(end 306.13985 -201.941176)
		(width 0.16002)
		(layer "In6.Cu")
		(net "M_E_CPU0_SA_DQS_DP<5>")
	)
	(segment
		(start 321.812158 -215.574372)
		(end 314.085478 -207.847692)
		(width 0.16002)
		(layer "In6.Cu")
		(net "M_E_CPU0_SA_DQS_DP<5>")
	)
	(segment
		(start 321.812158 -219.793058)
		(end 321.812158 -215.574372)
		(width 0.16002)
		(layer "In6.Cu")
		(net "M_E_CPU0_SA_DQS_DP<5>")
	)
	(segment
		(start 279.57653 -203.160122)
		(end 278.743156 -202.326748)
		(width 0.16002)
		(layer "In6.Cu")
		(net "M_E_CPU0_SA_DQS_DP<5>")
	)
	(segment
		(start 327.11136 -227.718874)
		(end 326.751188 -227.358702)
		(width 0.09525)
		(layer "In6.Cu")
		(net "M_E_CPU0_SA_DQS_DP<5>")
	)
	(segment
		(start 276.00656 -201.980292)
		(end 275.017484 -201.980292)
		(width 0.16002)
		(layer "In6.Cu")
		(net "M_E_CPU0_SA_DQS_DP<5>")
	)
	(segment
		(start 308.254146 -202.661012)
		(end 306.859686 -202.661012)
		(width 0.16002)
		(layer "In6.Cu")
		(net "M_E_CPU0_SA_DQS_DP<5>")
	)
	(segment
		(start 296.58437 -203.160122)
		(end 294.723566 -203.160122)
		(width 0.16002)
		(layer "In6.Cu")
		(net "M_E_CPU0_SA_DQS_DP<5>")
	)
	(segment
		(start 327.761092 -227.90785)
		(end 327.567544 -227.90785)
		(width 0.09525)
		(layer "In6.Cu")
		(net "M_E_CPU0_SA_DQS_DP<5>")
	)
	(segment
		(start 281.496516 -203.160122)
		(end 279.57653 -203.160122)
		(width 0.16002)
		(layer "In6.Cu")
		(net "M_E_CPU0_SA_DQS_DP<5>")
	)
	(segment
		(start 298.28109 -201.940922)
		(end 297.78071 -202.441302)
		(width 0.16002)
		(layer "In6.Cu")
		(net "M_E_CPU0_SA_DQS_DP<5>")
	)
	(segment
		(start 283.193236 -201.940922)
		(end 282.309062 -202.825096)
		(width 0.16002)
		(layer "In6.Cu")
		(net "M_E_CPU0_SA_DQS_DP<5>")
	)
	(segment
		(start 325.788782 -225.774758)
		(end 325.788782 -224.234248)
		(width 0.09525)
		(layer "In6.Cu")
		(net "M_E_CPU0_SA_DQS_DP<5>")
	)
	(segment
		(start 296.96537 -202.779122)
		(end 296.58437 -203.160122)
		(width 0.16002)
		(layer "In6.Cu")
		(net "M_E_CPU0_SA_DQS_DP<5>")
	)
	(segment
		(start 283.507942 -201.940922)
		(end 283.193236 -201.940922)
		(width 0.16002)
		(layer "In6.Cu")
		(net "M_E_CPU0_SA_DQS_DP<5>")
	)
	(segment
		(start 324.893178 -222.874078)
		(end 321.812158 -219.793058)
		(width 0.16002)
		(layer "In6.Cu")
		(net "M_E_CPU0_SA_DQS_DP<5>")
	)
	(segment
		(start 290.236656 -202.441302)
		(end 289.421316 -202.779122)
		(width 0.16002)
		(layer "In6.Cu")
		(net "M_E_CPU0_SA_DQS_DP<5>")
	)
	(segment
		(start 289.421316 -202.779122)
		(end 289.040316 -203.160122)
		(width 0.16002)
		(layer "In6.Cu")
		(net "M_E_CPU0_SA_DQS_DP<5>")
	)
	(segment
		(start 326.751188 -227.358702)
		(end 326.751188 -227.358448)
		(width 0.09525)
		(layer "In6.Cu")
		(net "M_E_CPU0_SA_DQS_DP<5>")
	)
	(segment
		(start 291.051742 -201.940922)
		(end 290.737036 -201.940922)
		(width 0.16002)
		(layer "In6.Cu")
		(net "M_E_CPU0_SA_DQS_DP<5>")
	)
	(segment
		(start 281.831542 -202.825096)
		(end 281.496516 -203.160122)
		(width 0.16002)
		(layer "In6.Cu")
		(net "M_E_CPU0_SA_DQS_DP<5>")
	)
	(segment
		(start 275.017484 -201.980292)
		(end 274.580858 -202.16114)
		(width 0.16002)
		(layer "In6.Cu")
		(net "M_E_CPU0_SA_DQS_DP<5>")
	)
	(segment
		(start 325.318882 -223.424242)
		(end 325.318882 -223.215962)
		(width 0.09525)
		(layer "In6.Cu")
		(net "M_E_CPU0_SA_DQS_DP<5>")
	)
	(segment
		(start 289.040316 -203.160122)
		(end 287.08731 -203.160122)
		(width 0.16002)
		(layer "In6.Cu")
		(net "M_E_CPU0_SA_DQS_DP<5>")
	)
	(segment
		(start 302.236886 -203.129642)
		(end 301.417482 -202.310238)
		(width 0.16002)
		(layer "In6.Cu")
		(net "M_E_CPU0_SA_DQS_DP<5>")
	)
	(segment
		(start 278.743156 -202.326748)
		(end 276.353016 -202.326748)
		(width 0.16002)
		(layer "In6.Cu")
		(net "M_E_CPU0_SA_DQS_DP<5>")
	)
	(segment
		(start 298.595796 -201.940922)
		(end 298.28109 -201.940922)
		(width 0.16002)
		(layer "In6.Cu")
		(net "M_E_CPU0_SA_DQS_DP<5>")
	)
	(segment
		(start 293.873682 -202.310238)
		(end 291.421058 -202.310238)
		(width 0.16002)
		(layer "In6.Cu")
		(net "M_E_CPU0_SA_DQS_DP<5>")
	)
	(segment
		(start 313.440826 -207.847692)
		(end 308.254146 -202.661012)
		(width 0.16002)
		(layer "In6.Cu")
		(net "M_E_CPU0_SA_DQS_DP<5>")
	)
	(segment
		(start 301.417482 -202.310238)
		(end 298.965112 -202.310238)
		(width 0.16002)
		(layer "In6.Cu")
		(net "M_E_CPU0_SA_DQS_DP<5>")
	)
	(segment
		(start 294.723566 -203.160122)
		(end 293.873682 -202.310238)
		(width 0.16002)
		(layer "In6.Cu")
		(net "M_E_CPU0_SA_DQS_DP<5>")
	)
	(segment
		(start 304.509424 -202.779376)
		(end 304.159158 -203.129642)
		(width 0.16002)
		(layer "In6.Cu")
		(net "M_E_CPU0_SA_DQS_DP<5>")
	)
	(segment
		(start 314.085478 -207.847692)
		(end 313.440826 -207.847692)
		(width 0.16002)
		(layer "In6.Cu")
		(net "M_E_CPU0_SA_DQS_DP<5>")
	)
	(segment
		(start 273.365976 -202.16114)
		(end 273.092164 -202.434952)
		(width 0.16002)
		(layer "In6.Cu")
		(net "M_E_CPU0_SA_DQS_DP<5>")
	)
	(segment
		(start 297.78071 -202.441302)
		(end 296.96537 -202.779122)
		(width 0.16002)
		(layer "In6.Cu")
		(net "M_E_CPU0_SA_DQS_DP<5>")
	)
	(segment
		(start 282.309062 -202.825096)
		(end 281.831542 -202.825096)
		(width 0.16002)
		(layer "In6.Cu")
		(net "M_E_CPU0_SA_DQS_DP<5>")
	)
	(segment
		(start 325.631302 -223.927416)
		(end 325.599806 -223.909128)
		(width 0.09525)
		(layer "In6.Cu")
		(net "M_E_CPU0_SA_DQS_DP<5>")
	)
	(segment
		(start 306.13985 -201.941176)
		(end 305.825144 -201.941176)
		(width 0.16002)
		(layer "In6.Cu")
		(net "M_E_CPU0_SA_DQS_DP<5>")
	)
	(segment
		(start 291.421058 -202.310238)
		(end 291.051742 -201.940922)
		(width 0.16002)
		(layer "In6.Cu")
		(net "M_E_CPU0_SA_DQS_DP<5>")
	)
	(arc
		(start 325.561706 -223.88703)
		(mid 325.383256 -223.68556)
		(end 325.318882 -223.424242)
		(width 0.09525)
		(layer "In6.Cu")
		(net "M_E_CPU0_SA_DQS_DP<5>")
	)
	(arc
		(start 326.57161 -226.983798)
		(mid 326.531352 -226.881722)
		(end 326.445118 -226.813872)
		(width 0.09525)
		(layer "In6.Cu")
		(net "M_E_CPU0_SA_DQS_DP<5>")
	)
	(arc
		(start 326.751188 -227.358448)
		(mid 326.629443 -227.186438)
		(end 326.57161 -226.983798)
		(width 0.09525)
		(layer "In6.Cu")
		(net "M_E_CPU0_SA_DQS_DP<5>")
	)
	(arc
		(start 328.889614 -227.959158)
		(mid 328.701146 -227.908481)
		(end 328.512678 -227.959158)
		(width 0.09525)
		(layer "In6.Cu")
		(net "M_E_CPU0_SA_DQS_DP<5>")
	)
	(arc
		(start 329.821286 -227.954332)
		(mid 329.636254 -227.908418)
		(end 329.452478 -227.959158)
		(width 0.09525)
		(layer "In6.Cu")
		(net "M_E_CPU0_SA_DQS_DP<5>")
	)
	(arc
		(start 326.235314 -226.585526)
		(mid 326.162729 -226.439746)
		(end 326.051418 -226.320858)
		(width 0.09525)
		(layer "In6.Cu")
		(net "M_E_CPU0_SA_DQS_DP<5>")
	)
	(arc
		(start 328.512678 -227.959158)
		(mid 328.231246 -228.034913)
		(end 327.949814 -227.959158)
		(width 0.09525)
		(layer "In6.Cu")
		(net "M_E_CPU0_SA_DQS_DP<5>")
	)
	(arc
		(start 327.567544 -227.90785)
		(mid 327.320652 -227.85874)
		(end 327.11136 -227.718874)
		(width 0.09525)
		(layer "In6.Cu")
		(net "M_E_CPU0_SA_DQS_DP<5>")
	)
	(arc
		(start 329.452478 -227.959158)
		(mid 329.171046 -228.034913)
		(end 328.889614 -227.959158)
		(width 0.09525)
		(layer "In6.Cu")
		(net "M_E_CPU0_SA_DQS_DP<5>")
	)
	(arc
		(start 327.949814 -227.959158)
		(mid 327.858848 -227.921005)
		(end 327.761092 -227.90785)
		(width 0.09525)
		(layer "In6.Cu")
		(net "M_E_CPU0_SA_DQS_DP<5>")
	)
	(arc
		(start 326.445118 -226.813872)
		(mid 326.315645 -226.722292)
		(end 326.235314 -226.585526)
		(width 0.09525)
		(layer "In6.Cu")
		(net "M_E_CPU0_SA_DQS_DP<5>")
	)
	(arc
		(start 326.051418 -226.320858)
		(mid 325.857811 -226.077776)
		(end 325.788782 -225.774758)
		(width 0.09525)
		(layer "In6.Cu")
		(net "M_E_CPU0_SA_DQS_DP<5>")
	)
	(arc
		(start 325.788782 -224.234248)
		(mid 325.747117 -224.061801)
		(end 325.631302 -223.927416)
		(width 0.09525)
		(layer "In6.Cu")
		(net "M_E_CPU0_SA_DQS_DP<5>")
	)
	(arc
		(start 330.326238 -227.992178)
		(mid 330.31637 -227.996209)
		(end 330.306426 -228.000052)
		(width 0.09525)
		(layer "In6.Cu")
		(net "M_E_CPU0_SA_DQS_DP<5>")
	)
	(arc
		(start 330.306426 -228.000052)
		(mid 330.063462 -228.033039)
		(end 329.829668 -227.959158)
		(width 0.09525)
		(layer "In6.Cu")
		(net "M_E_CPU0_SA_DQS_DP<5>")
	)
	(segment
		(start 329.167998 -246.370094)
		(end 328.701146 -246.104156)
		(width 0.12954)
		(layer "F.Cu")
		(net "M_E_CPU0_SA_DQS_DP<4>")
	)
	(segment
		(start 327.572624 -246.429276)
		(end 327.56221 -246.42318)
		(width 0.09525)
		(layer "In6.Cu")
		(net "M_E_CPU0_SA_DQS_DP<4>")
	)
	(segment
		(start 278.793448 -238.408972)
		(end 278.676608 -238.292132)
		(width 0.16002)
		(layer "In6.Cu")
		(net "M_E_CPU0_SA_DQS_DP<4>")
	)
	(segment
		(start 309.261256 -241.150648)
		(end 308.982364 -240.871756)
		(width 0.16002)
		(layer "In6.Cu")
		(net "M_E_CPU0_SA_DQS_DP<4>")
	)
	(segment
		(start 324.919594 -246.74195)
		(end 324.589394 -246.74195)
		(width 0.09525)
		(layer "In6.Cu")
		(net "M_E_CPU0_SA_DQS_DP<4>")
	)
	(segment
		(start 310.373522 -241.58321)
		(end 309.94096 -241.150648)
		(width 0.16002)
		(layer "In6.Cu")
		(net "M_E_CPU0_SA_DQS_DP<4>")
	)
	(segment
		(start 324.414896 -246.567452)
		(end 323.978778 -246.567452)
		(width 0.09525)
		(layer "In6.Cu")
		(net "M_E_CPU0_SA_DQS_DP<4>")
	)
	(segment
		(start 278.676608 -238.292132)
		(end 278.196548 -238.292132)
		(width 0.16002)
		(layer "In6.Cu")
		(net "M_E_CPU0_SA_DQS_DP<4>")
	)
	(segment
		(start 325.909178 -246.470678)
		(end 325.190866 -246.470678)
		(width 0.09525)
		(layer "In6.Cu")
		(net "M_E_CPU0_SA_DQS_DP<4>")
	)
	(segment
		(start 323.742812 -246.50827)
		(end 323.238114 -246.003572)
		(width 0.16002)
		(layer "In6.Cu")
		(net "M_E_CPU0_SA_DQS_DP<4>")
	)
	(segment
		(start 289.799268 -238.589312)
		(end 289.384232 -238.589312)
		(width 0.16002)
		(layer "In6.Cu")
		(net "M_E_CPU0_SA_DQS_DP<4>")
	)
	(segment
		(start 313.63793 -245.324122)
		(end 313.37504 -245.587012)
		(width 0.16002)
		(layer "In6.Cu")
		(net "M_E_CPU0_SA_DQS_DP<4>")
	)
	(segment
		(start 304.414428 -238.589312)
		(end 304.100484 -238.275368)
		(width 0.16002)
		(layer "In6.Cu")
		(net "M_E_CPU0_SA_DQS_DP<4>")
	)
	(segment
		(start 281.510994 -238.259874)
		(end 279.617932 -238.259874)
		(width 0.16002)
		(layer "In6.Cu")
		(net "M_E_CPU0_SA_DQS_DP<4>")
	)
	(segment
		(start 311.50179 -243.713762)
		(end 311.76468 -243.450872)
		(width 0.16002)
		(layer "In6.Cu")
		(net "M_E_CPU0_SA_DQS_DP<4>")
	)
	(segment
		(start 311.332118 -242.541806)
		(end 310.855614 -242.541806)
		(width 0.16002)
		(layer "In6.Cu")
		(net "M_E_CPU0_SA_DQS_DP<4>")
	)
	(segment
		(start 277.466044 -238.408972)
		(end 277.192232 -238.13516)
		(width 0.16002)
		(layer "In6.Cu")
		(net "M_E_CPU0_SA_DQS_DP<4>")
	)
	(segment
		(start 328.701146 -246.104156)
		(end 328.85507 -246.369586)
		(width 0.09525)
		(layer "In6.Cu")
		(net "M_E_CPU0_SA_DQS_DP<4>")
	)
	(segment
		(start 326.3519 -246.35333)
		(end 326.303132 -246.35333)
		(width 0.09525)
		(layer "In6.Cu")
		(net "M_E_CPU0_SA_DQS_DP<4>")
	)
	(segment
		(start 312.892948 -245.10492)
		(end 313.155838 -244.84203)
		(width 0.16002)
		(layer "In6.Cu")
		(net "M_E_CPU0_SA_DQS_DP<4>")
	)
	(segment
		(start 314.114434 -245.324122)
		(end 313.63793 -245.324122)
		(width 0.16002)
		(layer "In6.Cu")
		(net "M_E_CPU0_SA_DQS_DP<4>")
	)
	(segment
		(start 311.50179 -243.939822)
		(end 311.50179 -243.713762)
		(width 0.16002)
		(layer "In6.Cu")
		(net "M_E_CPU0_SA_DQS_DP<4>")
	)
	(segment
		(start 278.196548 -238.292132)
		(end 278.079708 -238.408972)
		(width 0.16002)
		(layer "In6.Cu")
		(net "M_E_CPU0_SA_DQS_DP<4>")
	)
	(segment
		(start 327.010014 -246.429276)
		(end 327.001632 -246.434102)
		(width 0.09525)
		(layer "In6.Cu")
		(net "M_E_CPU0_SA_DQS_DP<4>")
	)
	(segment
		(start 310.592724 -242.804696)
		(end 310.366664 -242.804696)
		(width 0.16002)
		(layer "In6.Cu")
		(net "M_E_CPU0_SA_DQS_DP<4>")
	)
	(segment
		(start 306.85613 -237.758732)
		(end 305.717956 -237.758732)
		(width 0.16002)
		(layer "In6.Cu")
		(net "M_E_CPU0_SA_DQS_DP<4>")
	)
	(segment
		(start 328.85507 -246.369586)
		(end 328.831956 -246.4562)
		(width 0.09525)
		(layer "In6.Cu")
		(net "M_E_CPU0_SA_DQS_DP<4>")
	)
	(segment
		(start 298.173902 -237.758732)
		(end 297.343322 -238.589312)
		(width 0.16002)
		(layer "In6.Cu")
		(net "M_E_CPU0_SA_DQS_DP<4>")
	)
	(segment
		(start 312.246772 -243.932964)
		(end 311.983882 -244.195854)
		(width 0.16002)
		(layer "In6.Cu")
		(net "M_E_CPU0_SA_DQS_DP<4>")
	)
	(segment
		(start 311.757822 -244.195854)
		(end 311.50179 -243.939822)
		(width 0.16002)
		(layer "In6.Cu")
		(net "M_E_CPU0_SA_DQS_DP<4>")
	)
	(segment
		(start 314.793884 -246.003572)
		(end 314.114434 -245.324122)
		(width 0.16002)
		(layer "In6.Cu")
		(net "M_E_CPU0_SA_DQS_DP<4>")
	)
	(segment
		(start 298.590208 -237.758732)
		(end 298.173902 -237.758732)
		(width 0.16002)
		(layer "In6.Cu")
		(net "M_E_CPU0_SA_DQS_DP<4>")
	)
	(segment
		(start 327.581006 -246.434102)
		(end 327.572624 -246.429276)
		(width 0.09525)
		(layer "In6.Cu")
		(net "M_E_CPU0_SA_DQS_DP<4>")
	)
	(segment
		(start 307.809138 -239.018826)
		(end 307.809138 -238.71174)
		(width 0.16002)
		(layer "In6.Cu")
		(net "M_E_CPU0_SA_DQS_DP<4>")
	)
	(segment
		(start 309.94096 -241.150648)
		(end 309.261256 -241.150648)
		(width 0.16002)
		(layer "In6.Cu")
		(net "M_E_CPU0_SA_DQS_DP<4>")
	)
	(segment
		(start 283.851096 -237.40999)
		(end 283.502354 -237.758732)
		(width 0.16002)
		(layer "In6.Cu")
		(net "M_E_CPU0_SA_DQS_DP<4>")
	)
	(segment
		(start 289.384232 -238.589312)
		(end 289.054794 -238.259874)
		(width 0.16002)
		(layer "In6.Cu")
		(net "M_E_CPU0_SA_DQS_DP<4>")
	)
	(segment
		(start 323.895974 -246.50827)
		(end 323.742812 -246.50827)
		(width 0.16002)
		(layer "In6.Cu")
		(net "M_E_CPU0_SA_DQS_DP<4>")
	)
	(segment
		(start 279.468834 -238.408972)
		(end 278.793448 -238.408972)
		(width 0.16002)
		(layer "In6.Cu")
		(net "M_E_CPU0_SA_DQS_DP<4>")
	)
	(segment
		(start 281.840432 -238.589312)
		(end 281.510994 -238.259874)
		(width 0.16002)
		(layer "In6.Cu")
		(net "M_E_CPU0_SA_DQS_DP<4>")
	)
	(segment
		(start 305.717956 -237.758732)
		(end 304.887376 -238.589312)
		(width 0.16002)
		(layer "In6.Cu")
		(net "M_E_CPU0_SA_DQS_DP<4>")
	)
	(segment
		(start 286.442912 -238.259874)
		(end 285.593028 -237.40999)
		(width 0.16002)
		(layer "In6.Cu")
		(net "M_E_CPU0_SA_DQS_DP<4>")
	)
	(segment
		(start 300.72203 -237.40999)
		(end 298.93895 -237.40999)
		(width 0.16002)
		(layer "In6.Cu")
		(net "M_E_CPU0_SA_DQS_DP<4>")
	)
	(segment
		(start 294.02786 -238.259874)
		(end 293.177976 -237.40999)
		(width 0.16002)
		(layer "In6.Cu")
		(net "M_E_CPU0_SA_DQS_DP<4>")
	)
	(segment
		(start 293.177976 -237.40999)
		(end 291.394896 -237.40999)
		(width 0.16002)
		(layer "In6.Cu")
		(net "M_E_CPU0_SA_DQS_DP<4>")
	)
	(segment
		(start 296.598848 -238.259874)
		(end 294.02786 -238.259874)
		(width 0.16002)
		(layer "In6.Cu")
		(net "M_E_CPU0_SA_DQS_DP<4>")
	)
	(segment
		(start 291.394896 -237.40999)
		(end 291.046154 -237.758732)
		(width 0.16002)
		(layer "In6.Cu")
		(net "M_E_CPU0_SA_DQS_DP<4>")
	)
	(segment
		(start 310.110632 -242.322604)
		(end 310.373522 -242.059714)
		(width 0.16002)
		(layer "In6.Cu")
		(net "M_E_CPU0_SA_DQS_DP<4>")
	)
	(segment
		(start 323.919596 -246.50827)
		(end 323.895974 -246.50827)
		(width 0.09525)
		(layer "In6.Cu")
		(net "M_E_CPU0_SA_DQS_DP<4>")
	)
	(segment
		(start 308.982364 -240.871756)
		(end 308.982364 -240.192052)
		(width 0.16002)
		(layer "In6.Cu")
		(net "M_E_CPU0_SA_DQS_DP<4>")
	)
	(segment
		(start 291.046154 -237.758732)
		(end 290.629848 -237.758732)
		(width 0.16002)
		(layer "In6.Cu")
		(net "M_E_CPU0_SA_DQS_DP<4>")
	)
	(segment
		(start 311.76468 -243.450872)
		(end 311.76468 -242.974368)
		(width 0.16002)
		(layer "In6.Cu")
		(net "M_E_CPU0_SA_DQS_DP<4>")
	)
	(segment
		(start 307.809138 -238.71174)
		(end 306.85613 -237.758732)
		(width 0.16002)
		(layer "In6.Cu")
		(net "M_E_CPU0_SA_DQS_DP<4>")
	)
	(segment
		(start 297.343322 -238.589312)
		(end 296.928286 -238.589312)
		(width 0.16002)
		(layer "In6.Cu")
		(net "M_E_CPU0_SA_DQS_DP<4>")
	)
	(segment
		(start 283.502354 -237.758732)
		(end 283.0576 -237.758732)
		(width 0.16002)
		(layer "In6.Cu")
		(net "M_E_CPU0_SA_DQS_DP<4>")
	)
	(segment
		(start 313.37504 -245.587012)
		(end 313.14898 -245.587012)
		(width 0.16002)
		(layer "In6.Cu")
		(net "M_E_CPU0_SA_DQS_DP<4>")
	)
	(segment
		(start 313.155838 -244.365526)
		(end 312.723276 -243.932964)
		(width 0.16002)
		(layer "In6.Cu")
		(net "M_E_CPU0_SA_DQS_DP<4>")
	)
	(segment
		(start 310.110632 -242.548664)
		(end 310.110632 -242.322604)
		(width 0.16002)
		(layer "In6.Cu")
		(net "M_E_CPU0_SA_DQS_DP<4>")
	)
	(segment
		(start 304.100484 -238.275368)
		(end 301.587408 -238.275368)
		(width 0.16002)
		(layer "In6.Cu")
		(net "M_E_CPU0_SA_DQS_DP<4>")
	)
	(segment
		(start 308.982364 -240.192052)
		(end 307.809138 -239.018826)
		(width 0.16002)
		(layer "In6.Cu")
		(net "M_E_CPU0_SA_DQS_DP<4>")
	)
	(segment
		(start 310.373522 -242.059714)
		(end 310.373522 -241.58321)
		(width 0.16002)
		(layer "In6.Cu")
		(net "M_E_CPU0_SA_DQS_DP<4>")
	)
	(segment
		(start 312.723276 -243.932964)
		(end 312.246772 -243.932964)
		(width 0.16002)
		(layer "In6.Cu")
		(net "M_E_CPU0_SA_DQS_DP<4>")
	)
	(segment
		(start 283.0576 -237.758732)
		(end 282.22702 -238.589312)
		(width 0.16002)
		(layer "In6.Cu")
		(net "M_E_CPU0_SA_DQS_DP<4>")
	)
	(segment
		(start 289.054794 -238.259874)
		(end 286.442912 -238.259874)
		(width 0.16002)
		(layer "In6.Cu")
		(net "M_E_CPU0_SA_DQS_DP<4>")
	)
	(segment
		(start 324.589394 -246.74195)
		(end 324.414896 -246.567452)
		(width 0.09525)
		(layer "In6.Cu")
		(net "M_E_CPU0_SA_DQS_DP<4>")
	)
	(segment
		(start 313.155838 -244.84203)
		(end 313.155838 -244.365526)
		(width 0.16002)
		(layer "In6.Cu")
		(net "M_E_CPU0_SA_DQS_DP<4>")
	)
	(segment
		(start 311.76468 -242.974368)
		(end 311.332118 -242.541806)
		(width 0.16002)
		(layer "In6.Cu")
		(net "M_E_CPU0_SA_DQS_DP<4>")
	)
	(segment
		(start 285.593028 -237.40999)
		(end 283.851096 -237.40999)
		(width 0.16002)
		(layer "In6.Cu")
		(net "M_E_CPU0_SA_DQS_DP<4>")
	)
	(segment
		(start 311.983882 -244.195854)
		(end 311.757822 -244.195854)
		(width 0.16002)
		(layer "In6.Cu")
		(net "M_E_CPU0_SA_DQS_DP<4>")
	)
	(segment
		(start 279.617932 -238.259874)
		(end 279.468834 -238.408972)
		(width 0.16002)
		(layer "In6.Cu")
		(net "M_E_CPU0_SA_DQS_DP<4>")
	)
	(segment
		(start 290.629848 -237.758732)
		(end 289.799268 -238.589312)
		(width 0.16002)
		(layer "In6.Cu")
		(net "M_E_CPU0_SA_DQS_DP<4>")
	)
	(segment
		(start 282.22702 -238.589312)
		(end 281.840432 -238.589312)
		(width 0.16002)
		(layer "In6.Cu")
		(net "M_E_CPU0_SA_DQS_DP<4>")
	)
	(segment
		(start 310.366664 -242.804696)
		(end 310.110632 -242.548664)
		(width 0.16002)
		(layer "In6.Cu")
		(net "M_E_CPU0_SA_DQS_DP<4>")
	)
	(segment
		(start 323.978778 -246.567452)
		(end 323.919596 -246.50827)
		(width 0.09525)
		(layer "In6.Cu")
		(net "M_E_CPU0_SA_DQS_DP<4>")
	)
	(segment
		(start 326.091804 -246.39524)
		(end 325.909178 -246.470678)
		(width 0.09525)
		(layer "In6.Cu")
		(net "M_E_CPU0_SA_DQS_DP<4>")
	)
	(segment
		(start 298.93895 -237.40999)
		(end 298.590208 -237.758732)
		(width 0.16002)
		(layer "In6.Cu")
		(net "M_E_CPU0_SA_DQS_DP<4>")
	)
	(segment
		(start 278.079708 -238.408972)
		(end 277.466044 -238.408972)
		(width 0.16002)
		(layer "In6.Cu")
		(net "M_E_CPU0_SA_DQS_DP<4>")
	)
	(segment
		(start 296.928286 -238.589312)
		(end 296.598848 -238.259874)
		(width 0.16002)
		(layer "In6.Cu")
		(net "M_E_CPU0_SA_DQS_DP<4>")
	)
	(segment
		(start 312.892948 -245.33098)
		(end 312.892948 -245.10492)
		(width 0.16002)
		(layer "In6.Cu")
		(net "M_E_CPU0_SA_DQS_DP<4>")
	)
	(segment
		(start 325.190866 -246.470678)
		(end 324.919594 -246.74195)
		(width 0.09525)
		(layer "In6.Cu")
		(net "M_E_CPU0_SA_DQS_DP<4>")
	)
	(segment
		(start 310.855614 -242.541806)
		(end 310.592724 -242.804696)
		(width 0.16002)
		(layer "In6.Cu")
		(net "M_E_CPU0_SA_DQS_DP<4>")
	)
	(segment
		(start 304.887376 -238.589312)
		(end 304.414428 -238.589312)
		(width 0.16002)
		(layer "In6.Cu")
		(net "M_E_CPU0_SA_DQS_DP<4>")
	)
	(segment
		(start 323.238114 -246.003572)
		(end 314.793884 -246.003572)
		(width 0.16002)
		(layer "In6.Cu")
		(net "M_E_CPU0_SA_DQS_DP<4>")
	)
	(segment
		(start 301.587408 -238.275368)
		(end 300.72203 -237.40999)
		(width 0.16002)
		(layer "In6.Cu")
		(net "M_E_CPU0_SA_DQS_DP<4>")
	)
	(segment
		(start 313.14898 -245.587012)
		(end 312.892948 -245.33098)
		(width 0.16002)
		(layer "In6.Cu")
		(net "M_E_CPU0_SA_DQS_DP<4>")
	)
	(arc
		(start 327.949814 -246.429276)
		(mid 327.766039 -246.480048)
		(end 327.581006 -246.434102)
		(width 0.09525)
		(layer "In6.Cu")
		(net "M_E_CPU0_SA_DQS_DP<4>")
	)
	(arc
		(start 326.632824 -246.429276)
		(mid 326.49737 -246.372795)
		(end 326.3519 -246.35333)
		(width 0.09525)
		(layer "In6.Cu")
		(net "M_E_CPU0_SA_DQS_DP<4>")
	)
	(arc
		(start 327.56221 -246.42318)
		(mid 327.285302 -246.353503)
		(end 327.010014 -246.429276)
		(width 0.09525)
		(layer "In6.Cu")
		(net "M_E_CPU0_SA_DQS_DP<4>")
	)
	(arc
		(start 328.831956 -246.4562)
		(mid 328.669305 -246.47846)
		(end 328.512678 -246.429276)
		(width 0.09525)
		(layer "In6.Cu")
		(net "M_E_CPU0_SA_DQS_DP<4>")
	)
	(arc
		(start 328.512678 -246.429276)
		(mid 328.231246 -246.353521)
		(end 327.949814 -246.429276)
		(width 0.09525)
		(layer "In6.Cu")
		(net "M_E_CPU0_SA_DQS_DP<4>")
	)
	(arc
		(start 326.303132 -246.35333)
		(mid 326.19541 -246.363909)
		(end 326.091804 -246.39524)
		(width 0.09525)
		(layer "In6.Cu")
		(net "M_E_CPU0_SA_DQS_DP<4>")
	)
	(arc
		(start 327.001632 -246.434102)
		(mid 326.8166 -246.480016)
		(end 326.632824 -246.429276)
		(width 0.09525)
		(layer "In6.Cu")
		(net "M_E_CPU0_SA_DQS_DP<4>")
	)
	(segment
		(start 329.167998 -241.510058)
		(end 328.701146 -241.24412)
		(width 0.12954)
		(layer "F.Cu")
		(net "M_E_CPU0_SA_DQS_DP<3>")
	)
	(segment
		(start 317.830454 -240.39068)
		(end 317.439802 -240.000028)
		(width 0.16002)
		(layer "In6.Cu")
		(net "M_E_CPU0_SA_DQS_DP<3>")
	)
	(segment
		(start 304.445162 -229.681532)
		(end 303.06899 -229.681532)
		(width 0.16002)
		(layer "In6.Cu")
		(net "M_E_CPU0_SA_DQS_DP<3>")
	)
	(segment
		(start 316.276228 -237.678722)
		(end 315.843158 -237.245652)
		(width 0.16002)
		(layer "In6.Cu")
		(net "M_E_CPU0_SA_DQS_DP<3>")
	)
	(segment
		(start 316.276228 -238.155226)
		(end 316.276228 -237.678722)
		(width 0.16002)
		(layer "In6.Cu")
		(net "M_E_CPU0_SA_DQS_DP<3>")
	)
	(segment
		(start 317.667386 -239.06988)
		(end 317.234316 -238.63681)
		(width 0.16002)
		(layer "In6.Cu")
		(net "M_E_CPU0_SA_DQS_DP<3>")
	)
	(segment
		(start 307.412898 -229.463092)
		(end 307.252878 -229.303072)
		(width 0.16002)
		(layer "In6.Cu")
		(net "M_E_CPU0_SA_DQS_DP<3>")
	)
	(segment
		(start 327.572624 -241.56924)
		(end 327.56221 -241.563144)
		(width 0.09525)
		(layer "In6.Cu")
		(net "M_E_CPU0_SA_DQS_DP<3>")
	)
	(segment
		(start 278.267668 -228.942138)
		(end 278.150828 -229.058978)
		(width 0.16002)
		(layer "In6.Cu")
		(net "M_E_CPU0_SA_DQS_DP<3>")
	)
	(segment
		(start 307.252878 -229.303072)
		(end 307.252878 -228.856286)
		(width 0.16002)
		(layer "In6.Cu")
		(net "M_E_CPU0_SA_DQS_DP<3>")
	)
	(segment
		(start 283.502354 -228.408738)
		(end 283.0576 -228.408738)
		(width 0.16002)
		(layer "In6.Cu")
		(net "M_E_CPU0_SA_DQS_DP<3>")
	)
	(segment
		(start 326.351138 -241.493294)
		(end 325.513954 -241.493294)
		(width 0.09525)
		(layer "In6.Cu")
		(net "M_E_CPU0_SA_DQS_DP<3>")
	)
	(segment
		(start 323.919596 -240.39068)
		(end 323.895974 -240.39068)
		(width 0.09525)
		(layer "In6.Cu")
		(net "M_E_CPU0_SA_DQS_DP<3>")
	)
	(segment
		(start 317.439802 -239.773968)
		(end 317.667386 -239.546384)
		(width 0.16002)
		(layer "In6.Cu")
		(net "M_E_CPU0_SA_DQS_DP<3>")
	)
	(segment
		(start 302.379888 -228.99243)
		(end 301.654464 -228.99243)
		(width 0.16002)
		(layer "In6.Cu")
		(net "M_E_CPU0_SA_DQS_DP<3>")
	)
	(segment
		(start 308.341014 -229.463092)
		(end 307.412898 -229.463092)
		(width 0.16002)
		(layer "In6.Cu")
		(net "M_E_CPU0_SA_DQS_DP<3>")
	)
	(segment
		(start 290.629848 -228.408738)
		(end 289.616896 -229.42169)
		(width 0.16002)
		(layer "In6.Cu")
		(net "M_E_CPU0_SA_DQS_DP<3>")
	)
	(segment
		(start 301.654464 -228.99243)
		(end 300.72203 -228.059996)
		(width 0.16002)
		(layer "In6.Cu")
		(net "M_E_CPU0_SA_DQS_DP<3>")
	)
	(segment
		(start 314.452 -235.854494)
		(end 313.975496 -235.854494)
		(width 0.16002)
		(layer "In6.Cu")
		(net "M_E_CPU0_SA_DQS_DP<3>")
	)
	(segment
		(start 281.955748 -229.51059)
		(end 281.640788 -229.51059)
		(width 0.16002)
		(layer "In6.Cu")
		(net "M_E_CPU0_SA_DQS_DP<3>")
	)
	(segment
		(start 316.530228 -238.864394)
		(end 316.304168 -238.864394)
		(width 0.16002)
		(layer "In6.Cu")
		(net "M_E_CPU0_SA_DQS_DP<3>")
	)
	(segment
		(start 289.616896 -229.42169)
		(end 289.149028 -229.42169)
		(width 0.16002)
		(layer "In6.Cu")
		(net "M_E_CPU0_SA_DQS_DP<3>")
	)
	(segment
		(start 323.895974 -240.39068)
		(end 317.830454 -240.39068)
		(width 0.16002)
		(layer "In6.Cu")
		(net "M_E_CPU0_SA_DQS_DP<3>")
	)
	(segment
		(start 314.657486 -237.217712)
		(end 314.657486 -236.991652)
		(width 0.16002)
		(layer "In6.Cu")
		(net "M_E_CPU0_SA_DQS_DP<3>")
	)
	(segment
		(start 316.757812 -238.63681)
		(end 316.530228 -238.864394)
		(width 0.16002)
		(layer "In6.Cu")
		(net "M_E_CPU0_SA_DQS_DP<3>")
	)
	(segment
		(start 278.864568 -229.058978)
		(end 278.747728 -228.942138)
		(width 0.16002)
		(layer "In6.Cu")
		(net "M_E_CPU0_SA_DQS_DP<3>")
	)
	(segment
		(start 291.394896 -228.059996)
		(end 291.046154 -228.408738)
		(width 0.16002)
		(layer "In6.Cu")
		(net "M_E_CPU0_SA_DQS_DP<3>")
	)
	(segment
		(start 286.253682 -229.17023)
		(end 285.143448 -228.059996)
		(width 0.16002)
		(layer "In6.Cu")
		(net "M_E_CPU0_SA_DQS_DP<3>")
	)
	(segment
		(start 296.708322 -229.45217)
		(end 296.166032 -228.90988)
		(width 0.16002)
		(layer "In6.Cu")
		(net "M_E_CPU0_SA_DQS_DP<3>")
	)
	(segment
		(start 315.366654 -237.245652)
		(end 315.13907 -237.473236)
		(width 0.16002)
		(layer "In6.Cu")
		(net "M_E_CPU0_SA_DQS_DP<3>")
	)
	(segment
		(start 314.88507 -236.764068)
		(end 314.88507 -236.287564)
		(width 0.16002)
		(layer "In6.Cu")
		(net "M_E_CPU0_SA_DQS_DP<3>")
	)
	(segment
		(start 328.85507 -241.50955)
		(end 328.831956 -241.596164)
		(width 0.09525)
		(layer "In6.Cu")
		(net "M_E_CPU0_SA_DQS_DP<3>")
	)
	(segment
		(start 313.747912 -236.082078)
		(end 313.521852 -236.082078)
		(width 0.16002)
		(layer "In6.Cu")
		(net "M_E_CPU0_SA_DQS_DP<3>")
	)
	(segment
		(start 328.701146 -241.24412)
		(end 328.85507 -241.50955)
		(width 0.09525)
		(layer "In6.Cu")
		(net "M_E_CPU0_SA_DQS_DP<3>")
	)
	(segment
		(start 278.150828 -229.058978)
		(end 277.466044 -229.058978)
		(width 0.16002)
		(layer "In6.Cu")
		(net "M_E_CPU0_SA_DQS_DP<3>")
	)
	(segment
		(start 283.0576 -228.408738)
		(end 281.955748 -229.51059)
		(width 0.16002)
		(layer "In6.Cu")
		(net "M_E_CPU0_SA_DQS_DP<3>")
	)
	(segment
		(start 317.439802 -240.000028)
		(end 317.439802 -239.773968)
		(width 0.16002)
		(layer "In6.Cu")
		(net "M_E_CPU0_SA_DQS_DP<3>")
	)
	(segment
		(start 314.88507 -236.287564)
		(end 314.452 -235.854494)
		(width 0.16002)
		(layer "In6.Cu")
		(net "M_E_CPU0_SA_DQS_DP<3>")
	)
	(segment
		(start 278.747728 -228.942138)
		(end 278.267668 -228.942138)
		(width 0.16002)
		(layer "In6.Cu")
		(net "M_E_CPU0_SA_DQS_DP<3>")
	)
	(segment
		(start 313.521852 -236.082078)
		(end 312.401966 -234.962192)
		(width 0.16002)
		(layer "In6.Cu")
		(net "M_E_CPU0_SA_DQS_DP<3>")
	)
	(segment
		(start 294.02786 -228.90988)
		(end 293.177976 -228.059996)
		(width 0.16002)
		(layer "In6.Cu")
		(net "M_E_CPU0_SA_DQS_DP<3>")
	)
	(segment
		(start 283.851096 -228.059996)
		(end 283.502354 -228.408738)
		(width 0.16002)
		(layer "In6.Cu")
		(net "M_E_CPU0_SA_DQS_DP<3>")
	)
	(segment
		(start 315.13907 -237.473236)
		(end 314.91301 -237.473236)
		(width 0.16002)
		(layer "In6.Cu")
		(net "M_E_CPU0_SA_DQS_DP<3>")
	)
	(segment
		(start 287.626806 -228.90988)
		(end 287.366456 -229.17023)
		(width 0.16002)
		(layer "In6.Cu")
		(net "M_E_CPU0_SA_DQS_DP<3>")
	)
	(segment
		(start 316.304168 -238.864394)
		(end 316.048644 -238.60887)
		(width 0.16002)
		(layer "In6.Cu")
		(net "M_E_CPU0_SA_DQS_DP<3>")
	)
	(segment
		(start 324.94982 -240.92916)
		(end 324.65518 -240.92916)
		(width 0.09525)
		(layer "In6.Cu")
		(net "M_E_CPU0_SA_DQS_DP<3>")
	)
	(segment
		(start 325.513954 -241.493294)
		(end 324.94982 -240.92916)
		(width 0.09525)
		(layer "In6.Cu")
		(net "M_E_CPU0_SA_DQS_DP<3>")
	)
	(segment
		(start 324.182994 -240.456974)
		(end 323.98589 -240.456974)
		(width 0.09525)
		(layer "In6.Cu")
		(net "M_E_CPU0_SA_DQS_DP<3>")
	)
	(segment
		(start 317.234316 -238.63681)
		(end 316.757812 -238.63681)
		(width 0.16002)
		(layer "In6.Cu")
		(net "M_E_CPU0_SA_DQS_DP<3>")
	)
	(segment
		(start 298.590208 -228.408738)
		(end 298.173902 -228.408738)
		(width 0.16002)
		(layer "In6.Cu")
		(net "M_E_CPU0_SA_DQS_DP<3>")
	)
	(segment
		(start 297.13047 -229.45217)
		(end 296.708322 -229.45217)
		(width 0.16002)
		(layer "In6.Cu")
		(net "M_E_CPU0_SA_DQS_DP<3>")
	)
	(segment
		(start 287.366456 -229.17023)
		(end 286.253682 -229.17023)
		(width 0.16002)
		(layer "In6.Cu")
		(net "M_E_CPU0_SA_DQS_DP<3>")
	)
	(segment
		(start 312.401966 -234.962192)
		(end 311.38495 -232.507028)
		(width 0.16002)
		(layer "In6.Cu")
		(net "M_E_CPU0_SA_DQS_DP<3>")
	)
	(segment
		(start 281.040078 -228.90988)
		(end 279.617932 -228.90988)
		(width 0.16002)
		(layer "In6.Cu")
		(net "M_E_CPU0_SA_DQS_DP<3>")
	)
	(segment
		(start 293.177976 -228.059996)
		(end 291.394896 -228.059996)
		(width 0.16002)
		(layer "In6.Cu")
		(net "M_E_CPU0_SA_DQS_DP<3>")
	)
	(segment
		(start 285.143448 -228.059996)
		(end 283.851096 -228.059996)
		(width 0.16002)
		(layer "In6.Cu")
		(net "M_E_CPU0_SA_DQS_DP<3>")
	)
	(segment
		(start 317.667386 -239.546384)
		(end 317.667386 -239.06988)
		(width 0.16002)
		(layer "In6.Cu")
		(net "M_E_CPU0_SA_DQS_DP<3>")
	)
	(segment
		(start 279.468834 -229.058978)
		(end 278.864568 -229.058978)
		(width 0.16002)
		(layer "In6.Cu")
		(net "M_E_CPU0_SA_DQS_DP<3>")
	)
	(segment
		(start 327.581006 -241.574066)
		(end 327.572624 -241.56924)
		(width 0.09525)
		(layer "In6.Cu")
		(net "M_E_CPU0_SA_DQS_DP<3>")
	)
	(segment
		(start 305.717956 -228.408738)
		(end 304.445162 -229.681532)
		(width 0.16002)
		(layer "In6.Cu")
		(net "M_E_CPU0_SA_DQS_DP<3>")
	)
	(segment
		(start 296.166032 -228.90988)
		(end 294.02786 -228.90988)
		(width 0.16002)
		(layer "In6.Cu")
		(net "M_E_CPU0_SA_DQS_DP<3>")
	)
	(segment
		(start 306.80533 -228.408738)
		(end 305.717956 -228.408738)
		(width 0.16002)
		(layer "In6.Cu")
		(net "M_E_CPU0_SA_DQS_DP<3>")
	)
	(segment
		(start 291.046154 -228.408738)
		(end 290.629848 -228.408738)
		(width 0.16002)
		(layer "In6.Cu")
		(net "M_E_CPU0_SA_DQS_DP<3>")
	)
	(segment
		(start 313.975496 -235.854494)
		(end 313.747912 -236.082078)
		(width 0.16002)
		(layer "In6.Cu")
		(net "M_E_CPU0_SA_DQS_DP<3>")
	)
	(segment
		(start 316.048644 -238.38281)
		(end 316.276228 -238.155226)
		(width 0.16002)
		(layer "In6.Cu")
		(net "M_E_CPU0_SA_DQS_DP<3>")
	)
	(segment
		(start 281.640788 -229.51059)
		(end 281.040078 -228.90988)
		(width 0.16002)
		(layer "In6.Cu")
		(net "M_E_CPU0_SA_DQS_DP<3>")
	)
	(segment
		(start 307.252878 -228.856286)
		(end 306.80533 -228.408738)
		(width 0.16002)
		(layer "In6.Cu")
		(net "M_E_CPU0_SA_DQS_DP<3>")
	)
	(segment
		(start 303.06899 -229.681532)
		(end 302.379888 -228.99243)
		(width 0.16002)
		(layer "In6.Cu")
		(net "M_E_CPU0_SA_DQS_DP<3>")
	)
	(segment
		(start 323.98589 -240.456974)
		(end 323.919596 -240.39068)
		(width 0.09525)
		(layer "In6.Cu")
		(net "M_E_CPU0_SA_DQS_DP<3>")
	)
	(segment
		(start 311.38495 -232.507028)
		(end 308.341014 -229.463092)
		(width 0.16002)
		(layer "In6.Cu")
		(net "M_E_CPU0_SA_DQS_DP<3>")
	)
	(segment
		(start 316.048644 -238.60887)
		(end 316.048644 -238.38281)
		(width 0.16002)
		(layer "In6.Cu")
		(net "M_E_CPU0_SA_DQS_DP<3>")
	)
	(segment
		(start 314.657486 -236.991652)
		(end 314.88507 -236.764068)
		(width 0.16002)
		(layer "In6.Cu")
		(net "M_E_CPU0_SA_DQS_DP<3>")
	)
	(segment
		(start 324.65518 -240.92916)
		(end 324.182994 -240.456974)
		(width 0.09525)
		(layer "In6.Cu")
		(net "M_E_CPU0_SA_DQS_DP<3>")
	)
	(segment
		(start 298.173902 -228.408738)
		(end 297.13047 -229.45217)
		(width 0.16002)
		(layer "In6.Cu")
		(net "M_E_CPU0_SA_DQS_DP<3>")
	)
	(segment
		(start 300.72203 -228.059996)
		(end 298.93895 -228.059996)
		(width 0.16002)
		(layer "In6.Cu")
		(net "M_E_CPU0_SA_DQS_DP<3>")
	)
	(segment
		(start 314.91301 -237.473236)
		(end 314.657486 -237.217712)
		(width 0.16002)
		(layer "In6.Cu")
		(net "M_E_CPU0_SA_DQS_DP<3>")
	)
	(segment
		(start 327.010014 -241.56924)
		(end 327.001632 -241.574066)
		(width 0.09525)
		(layer "In6.Cu")
		(net "M_E_CPU0_SA_DQS_DP<3>")
	)
	(segment
		(start 315.843158 -237.245652)
		(end 315.366654 -237.245652)
		(width 0.16002)
		(layer "In6.Cu")
		(net "M_E_CPU0_SA_DQS_DP<3>")
	)
	(segment
		(start 289.149028 -229.42169)
		(end 288.637218 -228.90988)
		(width 0.16002)
		(layer "In6.Cu")
		(net "M_E_CPU0_SA_DQS_DP<3>")
	)
	(segment
		(start 277.466044 -229.058978)
		(end 277.192232 -228.785166)
		(width 0.16002)
		(layer "In6.Cu")
		(net "M_E_CPU0_SA_DQS_DP<3>")
	)
	(segment
		(start 288.637218 -228.90988)
		(end 287.626806 -228.90988)
		(width 0.16002)
		(layer "In6.Cu")
		(net "M_E_CPU0_SA_DQS_DP<3>")
	)
	(segment
		(start 298.93895 -228.059996)
		(end 298.590208 -228.408738)
		(width 0.16002)
		(layer "In6.Cu")
		(net "M_E_CPU0_SA_DQS_DP<3>")
	)
	(segment
		(start 279.617932 -228.90988)
		(end 279.468834 -229.058978)
		(width 0.16002)
		(layer "In6.Cu")
		(net "M_E_CPU0_SA_DQS_DP<3>")
	)
	(arc
		(start 327.949814 -241.56924)
		(mid 327.766039 -241.620012)
		(end 327.581006 -241.574066)
		(width 0.09525)
		(layer "In6.Cu")
		(net "M_E_CPU0_SA_DQS_DP<3>")
	)
	(arc
		(start 328.831956 -241.596164)
		(mid 328.669305 -241.618424)
		(end 328.512678 -241.56924)
		(width 0.09525)
		(layer "In6.Cu")
		(net "M_E_CPU0_SA_DQS_DP<3>")
	)
	(arc
		(start 326.632824 -241.56924)
		(mid 326.497002 -241.51266)
		(end 326.351138 -241.493294)
		(width 0.09525)
		(layer "In6.Cu")
		(net "M_E_CPU0_SA_DQS_DP<3>")
	)
	(arc
		(start 327.56221 -241.563144)
		(mid 327.285302 -241.493467)
		(end 327.010014 -241.56924)
		(width 0.09525)
		(layer "In6.Cu")
		(net "M_E_CPU0_SA_DQS_DP<3>")
	)
	(arc
		(start 327.001632 -241.574066)
		(mid 326.8166 -241.61998)
		(end 326.632824 -241.56924)
		(width 0.09525)
		(layer "In6.Cu")
		(net "M_E_CPU0_SA_DQS_DP<3>")
	)
	(arc
		(start 328.512678 -241.56924)
		(mid 328.231246 -241.493485)
		(end 327.949814 -241.56924)
		(width 0.09525)
		(layer "In6.Cu")
		(net "M_E_CPU0_SA_DQS_DP<3>")
	)
	(segment
		(start 329.167998 -236.650022)
		(end 328.701146 -236.384084)
		(width 0.12954)
		(layer "F.Cu")
		(net "M_E_CPU0_SA_DQS_DP<2>")
	)
	(segment
		(start 326.183498 -236.633258)
		(end 325.143622 -235.593382)
		(width 0.09525)
		(layer "In6.Cu")
		(net "M_E_CPU0_SA_DQS_DP<2>")
	)
	(segment
		(start 304.47869 -220.29801)
		(end 303.329594 -220.29801)
		(width 0.16002)
		(layer "In6.Cu")
		(net "M_E_CPU0_SA_DQS_DP<2>")
	)
	(segment
		(start 293.177976 -218.710002)
		(end 291.394896 -218.710002)
		(width 0.16002)
		(layer "In6.Cu")
		(net "M_E_CPU0_SA_DQS_DP<2>")
	)
	(segment
		(start 289.522662 -220.16593)
		(end 289.135566 -220.16593)
		(width 0.16002)
		(layer "In6.Cu")
		(net "M_E_CPU0_SA_DQS_DP<2>")
	)
	(segment
		(start 324.180708 -234.797854)
		(end 323.978524 -234.797854)
		(width 0.09525)
		(layer "In6.Cu")
		(net "M_E_CPU0_SA_DQS_DP<2>")
	)
	(segment
		(start 311.471818 -223.489012)
		(end 311.471818 -219.888562)
		(width 0.16002)
		(layer "In6.Cu")
		(net "M_E_CPU0_SA_DQS_DP<2>")
	)
	(segment
		(start 309.384446 -220.184472)
		(end 309.224426 -220.024452)
		(width 0.16002)
		(layer "In6.Cu")
		(net "M_E_CPU0_SA_DQS_DP<2>")
	)
	(segment
		(start 327.581006 -236.71403)
		(end 327.572624 -236.709204)
		(width 0.09525)
		(layer "In6.Cu")
		(net "M_E_CPU0_SA_DQS_DP<2>")
	)
	(segment
		(start 308.276244 -219.066872)
		(end 307.939186 -219.40393)
		(width 0.16002)
		(layer "In6.Cu")
		(net "M_E_CPU0_SA_DQS_DP<2>")
	)
	(segment
		(start 307.939186 -220.024452)
		(end 307.779166 -220.184472)
		(width 0.16002)
		(layer "In6.Cu")
		(net "M_E_CPU0_SA_DQS_DP<2>")
	)
	(segment
		(start 307.258466 -219.395802)
		(end 306.921408 -219.058744)
		(width 0.16002)
		(layer "In6.Cu")
		(net "M_E_CPU0_SA_DQS_DP<2>")
	)
	(segment
		(start 309.905146 -220.024452)
		(end 309.745126 -220.184472)
		(width 0.16002)
		(layer "In6.Cu")
		(net "M_E_CPU0_SA_DQS_DP<2>")
	)
	(segment
		(start 281.006042 -219.559886)
		(end 279.617932 -219.559886)
		(width 0.16002)
		(layer "In6.Cu")
		(net "M_E_CPU0_SA_DQS_DP<2>")
	)
	(segment
		(start 323.978524 -234.797854)
		(end 323.919596 -234.738926)
		(width 0.09525)
		(layer "In6.Cu")
		(net "M_E_CPU0_SA_DQS_DP<2>")
	)
	(segment
		(start 325.143622 -235.593382)
		(end 324.713854 -235.593382)
		(width 0.09525)
		(layer "In6.Cu")
		(net "M_E_CPU0_SA_DQS_DP<2>")
	)
	(segment
		(start 327.572624 -236.709204)
		(end 327.56221 -236.703108)
		(width 0.09525)
		(layer "In6.Cu")
		(net "M_E_CPU0_SA_DQS_DP<2>")
	)
	(segment
		(start 313.823858 -225.841052)
		(end 311.471818 -223.489012)
		(width 0.16002)
		(layer "In6.Cu")
		(net "M_E_CPU0_SA_DQS_DP<2>")
	)
	(segment
		(start 324.383654 -235.263182)
		(end 324.383654 -235.0008)
		(width 0.09525)
		(layer "In6.Cu")
		(net "M_E_CPU0_SA_DQS_DP<2>")
	)
	(segment
		(start 303.329594 -220.29801)
		(end 302.606964 -219.57538)
		(width 0.16002)
		(layer "In6.Cu")
		(net "M_E_CPU0_SA_DQS_DP<2>")
	)
	(segment
		(start 298.590208 -219.058744)
		(end 298.173902 -219.058744)
		(width 0.16002)
		(layer "In6.Cu")
		(net "M_E_CPU0_SA_DQS_DP<2>")
	)
	(segment
		(start 323.919596 -234.738926)
		(end 323.895974 -234.738926)
		(width 0.09525)
		(layer "In6.Cu")
		(net "M_E_CPU0_SA_DQS_DP<2>")
	)
	(segment
		(start 291.046154 -219.058744)
		(end 290.629848 -219.058744)
		(width 0.16002)
		(layer "In6.Cu")
		(net "M_E_CPU0_SA_DQS_DP<2>")
	)
	(segment
		(start 328.85507 -236.649514)
		(end 328.831956 -236.736128)
		(width 0.09525)
		(layer "In6.Cu")
		(net "M_E_CPU0_SA_DQS_DP<2>")
	)
	(segment
		(start 309.224426 -219.40393)
		(end 308.887368 -219.066872)
		(width 0.16002)
		(layer "In6.Cu")
		(net "M_E_CPU0_SA_DQS_DP<2>")
	)
	(segment
		(start 296.101516 -219.559886)
		(end 294.02786 -219.559886)
		(width 0.16002)
		(layer "In6.Cu")
		(net "M_E_CPU0_SA_DQS_DP<2>")
	)
	(segment
		(start 309.905146 -219.67317)
		(end 309.905146 -220.024452)
		(width 0.16002)
		(layer "In6.Cu")
		(net "M_E_CPU0_SA_DQS_DP<2>")
	)
	(segment
		(start 281.960574 -220.15577)
		(end 281.601926 -220.15577)
		(width 0.16002)
		(layer "In6.Cu")
		(net "M_E_CPU0_SA_DQS_DP<2>")
	)
	(segment
		(start 324.713854 -235.593382)
		(end 324.383654 -235.263182)
		(width 0.09525)
		(layer "In6.Cu")
		(net "M_E_CPU0_SA_DQS_DP<2>")
	)
	(segment
		(start 307.418486 -220.184472)
		(end 307.258466 -220.024452)
		(width 0.16002)
		(layer "In6.Cu")
		(net "M_E_CPU0_SA_DQS_DP<2>")
	)
	(segment
		(start 311.471818 -219.888562)
		(end 310.919368 -219.336112)
		(width 0.16002)
		(layer "In6.Cu")
		(net "M_E_CPU0_SA_DQS_DP<2>")
	)
	(segment
		(start 283.0576 -219.058744)
		(end 281.960574 -220.15577)
		(width 0.16002)
		(layer "In6.Cu")
		(net "M_E_CPU0_SA_DQS_DP<2>")
	)
	(segment
		(start 310.242204 -219.336112)
		(end 309.905146 -219.67317)
		(width 0.16002)
		(layer "In6.Cu")
		(net "M_E_CPU0_SA_DQS_DP<2>")
	)
	(segment
		(start 300.72203 -218.710002)
		(end 298.93895 -218.710002)
		(width 0.16002)
		(layer "In6.Cu")
		(net "M_E_CPU0_SA_DQS_DP<2>")
	)
	(segment
		(start 321.68338 -234.738926)
		(end 313.823858 -226.879404)
		(width 0.16002)
		(layer "In6.Cu")
		(net "M_E_CPU0_SA_DQS_DP<2>")
	)
	(segment
		(start 285.63316 -218.710002)
		(end 283.851096 -218.710002)
		(width 0.16002)
		(layer "In6.Cu")
		(net "M_E_CPU0_SA_DQS_DP<2>")
	)
	(segment
		(start 290.629848 -219.058744)
		(end 289.522662 -220.16593)
		(width 0.16002)
		(layer "In6.Cu")
		(net "M_E_CPU0_SA_DQS_DP<2>")
	)
	(segment
		(start 278.275034 -219.708984)
		(end 277.466044 -219.708984)
		(width 0.16002)
		(layer "In6.Cu")
		(net "M_E_CPU0_SA_DQS_DP<2>")
	)
	(segment
		(start 301.587408 -219.57538)
		(end 300.72203 -218.710002)
		(width 0.16002)
		(layer "In6.Cu")
		(net "M_E_CPU0_SA_DQS_DP<2>")
	)
	(segment
		(start 288.529522 -219.559886)
		(end 286.483044 -219.559886)
		(width 0.16002)
		(layer "In6.Cu")
		(net "M_E_CPU0_SA_DQS_DP<2>")
	)
	(segment
		(start 291.394896 -218.710002)
		(end 291.046154 -219.058744)
		(width 0.16002)
		(layer "In6.Cu")
		(net "M_E_CPU0_SA_DQS_DP<2>")
	)
	(segment
		(start 307.258466 -220.024452)
		(end 307.258466 -219.395802)
		(width 0.16002)
		(layer "In6.Cu")
		(net "M_E_CPU0_SA_DQS_DP<2>")
	)
	(segment
		(start 277.466044 -219.708984)
		(end 277.192232 -219.435172)
		(width 0.16002)
		(layer "In6.Cu")
		(net "M_E_CPU0_SA_DQS_DP<2>")
	)
	(segment
		(start 323.895974 -234.738926)
		(end 321.68338 -234.738926)
		(width 0.16002)
		(layer "In6.Cu")
		(net "M_E_CPU0_SA_DQS_DP<2>")
	)
	(segment
		(start 278.391874 -219.592144)
		(end 278.275034 -219.708984)
		(width 0.16002)
		(layer "In6.Cu")
		(net "M_E_CPU0_SA_DQS_DP<2>")
	)
	(segment
		(start 289.135566 -220.16593)
		(end 288.529522 -219.559886)
		(width 0.16002)
		(layer "In6.Cu")
		(net "M_E_CPU0_SA_DQS_DP<2>")
	)
	(segment
		(start 297.066716 -220.16593)
		(end 296.70756 -220.16593)
		(width 0.16002)
		(layer "In6.Cu")
		(net "M_E_CPU0_SA_DQS_DP<2>")
	)
	(segment
		(start 302.606964 -219.57538)
		(end 301.587408 -219.57538)
		(width 0.16002)
		(layer "In6.Cu")
		(net "M_E_CPU0_SA_DQS_DP<2>")
	)
	(segment
		(start 298.173902 -219.058744)
		(end 297.066716 -220.16593)
		(width 0.16002)
		(layer "In6.Cu")
		(net "M_E_CPU0_SA_DQS_DP<2>")
	)
	(segment
		(start 307.939186 -219.40393)
		(end 307.939186 -220.024452)
		(width 0.16002)
		(layer "In6.Cu")
		(net "M_E_CPU0_SA_DQS_DP<2>")
	)
	(segment
		(start 309.224426 -220.024452)
		(end 309.224426 -219.40393)
		(width 0.16002)
		(layer "In6.Cu")
		(net "M_E_CPU0_SA_DQS_DP<2>")
	)
	(segment
		(start 307.779166 -220.184472)
		(end 307.418486 -220.184472)
		(width 0.16002)
		(layer "In6.Cu")
		(net "M_E_CPU0_SA_DQS_DP<2>")
	)
	(segment
		(start 278.988774 -219.708984)
		(end 278.871934 -219.592144)
		(width 0.16002)
		(layer "In6.Cu")
		(net "M_E_CPU0_SA_DQS_DP<2>")
	)
	(segment
		(start 308.887368 -219.066872)
		(end 308.276244 -219.066872)
		(width 0.16002)
		(layer "In6.Cu")
		(net "M_E_CPU0_SA_DQS_DP<2>")
	)
	(segment
		(start 278.871934 -219.592144)
		(end 278.391874 -219.592144)
		(width 0.16002)
		(layer "In6.Cu")
		(net "M_E_CPU0_SA_DQS_DP<2>")
	)
	(segment
		(start 281.601926 -220.15577)
		(end 281.006042 -219.559886)
		(width 0.16002)
		(layer "In6.Cu")
		(net "M_E_CPU0_SA_DQS_DP<2>")
	)
	(segment
		(start 279.468834 -219.708984)
		(end 278.988774 -219.708984)
		(width 0.16002)
		(layer "In6.Cu")
		(net "M_E_CPU0_SA_DQS_DP<2>")
	)
	(segment
		(start 324.383654 -235.0008)
		(end 324.180708 -234.797854)
		(width 0.09525)
		(layer "In6.Cu")
		(net "M_E_CPU0_SA_DQS_DP<2>")
	)
	(segment
		(start 309.745126 -220.184472)
		(end 309.384446 -220.184472)
		(width 0.16002)
		(layer "In6.Cu")
		(net "M_E_CPU0_SA_DQS_DP<2>")
	)
	(segment
		(start 310.919368 -219.336112)
		(end 310.242204 -219.336112)
		(width 0.16002)
		(layer "In6.Cu")
		(net "M_E_CPU0_SA_DQS_DP<2>")
	)
	(segment
		(start 286.483044 -219.559886)
		(end 285.63316 -218.710002)
		(width 0.16002)
		(layer "In6.Cu")
		(net "M_E_CPU0_SA_DQS_DP<2>")
	)
	(segment
		(start 326.351138 -236.633258)
		(end 326.183498 -236.633258)
		(width 0.09525)
		(layer "In6.Cu")
		(net "M_E_CPU0_SA_DQS_DP<2>")
	)
	(segment
		(start 328.701146 -236.384084)
		(end 328.85507 -236.649514)
		(width 0.09525)
		(layer "In6.Cu")
		(net "M_E_CPU0_SA_DQS_DP<2>")
	)
	(segment
		(start 327.010014 -236.709204)
		(end 327.001632 -236.71403)
		(width 0.09525)
		(layer "In6.Cu")
		(net "M_E_CPU0_SA_DQS_DP<2>")
	)
	(segment
		(start 283.851096 -218.710002)
		(end 283.502354 -219.058744)
		(width 0.16002)
		(layer "In6.Cu")
		(net "M_E_CPU0_SA_DQS_DP<2>")
	)
	(segment
		(start 294.02786 -219.559886)
		(end 293.177976 -218.710002)
		(width 0.16002)
		(layer "In6.Cu")
		(net "M_E_CPU0_SA_DQS_DP<2>")
	)
	(segment
		(start 306.921408 -219.058744)
		(end 305.717956 -219.058744)
		(width 0.16002)
		(layer "In6.Cu")
		(net "M_E_CPU0_SA_DQS_DP<2>")
	)
	(segment
		(start 283.502354 -219.058744)
		(end 283.0576 -219.058744)
		(width 0.16002)
		(layer "In6.Cu")
		(net "M_E_CPU0_SA_DQS_DP<2>")
	)
	(segment
		(start 298.93895 -218.710002)
		(end 298.590208 -219.058744)
		(width 0.16002)
		(layer "In6.Cu")
		(net "M_E_CPU0_SA_DQS_DP<2>")
	)
	(segment
		(start 305.717956 -219.058744)
		(end 304.47869 -220.29801)
		(width 0.16002)
		(layer "In6.Cu")
		(net "M_E_CPU0_SA_DQS_DP<2>")
	)
	(segment
		(start 279.617932 -219.559886)
		(end 279.468834 -219.708984)
		(width 0.16002)
		(layer "In6.Cu")
		(net "M_E_CPU0_SA_DQS_DP<2>")
	)
	(segment
		(start 313.823858 -226.879404)
		(end 313.823858 -225.841052)
		(width 0.16002)
		(layer "In6.Cu")
		(net "M_E_CPU0_SA_DQS_DP<2>")
	)
	(segment
		(start 296.70756 -220.16593)
		(end 296.101516 -219.559886)
		(width 0.16002)
		(layer "In6.Cu")
		(net "M_E_CPU0_SA_DQS_DP<2>")
	)
	(arc
		(start 326.632824 -236.709204)
		(mid 326.497002 -236.652624)
		(end 326.351138 -236.633258)
		(width 0.09525)
		(layer "In6.Cu")
		(net "M_E_CPU0_SA_DQS_DP<2>")
	)
	(arc
		(start 327.56221 -236.703108)
		(mid 327.285302 -236.633431)
		(end 327.010014 -236.709204)
		(width 0.09525)
		(layer "In6.Cu")
		(net "M_E_CPU0_SA_DQS_DP<2>")
	)
	(arc
		(start 328.831956 -236.736128)
		(mid 328.669305 -236.758388)
		(end 328.512678 -236.709204)
		(width 0.09525)
		(layer "In6.Cu")
		(net "M_E_CPU0_SA_DQS_DP<2>")
	)
	(arc
		(start 327.001632 -236.71403)
		(mid 326.8166 -236.759944)
		(end 326.632824 -236.709204)
		(width 0.09525)
		(layer "In6.Cu")
		(net "M_E_CPU0_SA_DQS_DP<2>")
	)
	(arc
		(start 327.949814 -236.709204)
		(mid 327.766039 -236.759976)
		(end 327.581006 -236.71403)
		(width 0.09525)
		(layer "In6.Cu")
		(net "M_E_CPU0_SA_DQS_DP<2>")
	)
	(arc
		(start 328.512678 -236.709204)
		(mid 328.231246 -236.633449)
		(end 327.949814 -236.709204)
		(width 0.09525)
		(layer "In6.Cu")
		(net "M_E_CPU0_SA_DQS_DP<2>")
	)
	(segment
		(start 329.167998 -231.789986)
		(end 328.701146 -231.524048)
		(width 0.12954)
		(layer "F.Cu")
		(net "M_E_CPU0_SA_DQS_DP<1>")
	)
	(segment
		(start 310.300624 -213.254844)
		(end 310.300624 -213.028784)
		(width 0.16002)
		(layer "In6.Cu")
		(net "M_E_CPU0_SA_DQS_DP<1>")
	)
	(segment
		(start 298.590208 -209.70875)
		(end 298.173902 -209.70875)
		(width 0.16002)
		(layer "In6.Cu")
		(net "M_E_CPU0_SA_DQS_DP<1>")
	)
	(segment
		(start 308.542436 -210.185508)
		(end 307.999892 -210.728052)
		(width 0.16002)
		(layer "In6.Cu")
		(net "M_E_CPU0_SA_DQS_DP<1>")
	)
	(segment
		(start 297.079162 -210.80349)
		(end 296.720006 -210.80349)
		(width 0.16002)
		(layer "In6.Cu")
		(net "M_E_CPU0_SA_DQS_DP<1>")
	)
	(segment
		(start 307.773832 -210.728052)
		(end 306.75453 -209.70875)
		(width 0.16002)
		(layer "In6.Cu")
		(net "M_E_CPU0_SA_DQS_DP<1>")
	)
	(segment
		(start 327.572624 -231.849168)
		(end 327.56221 -231.843072)
		(width 0.09525)
		(layer "In6.Cu")
		(net "M_E_CPU0_SA_DQS_DP<1>")
	)
	(segment
		(start 289.20694 -210.71967)
		(end 288.697162 -210.209892)
		(width 0.16002)
		(layer "In6.Cu")
		(net "M_E_CPU0_SA_DQS_DP<1>")
	)
	(segment
		(start 323.716904 -228.71176)
		(end 319.363598 -224.358454)
		(width 0.16002)
		(layer "In6.Cu")
		(net "M_E_CPU0_SA_DQS_DP<1>")
	)
	(segment
		(start 310.410098 -211.576666)
		(end 309.933594 -211.576666)
		(width 0.16002)
		(layer "In6.Cu")
		(net "M_E_CPU0_SA_DQS_DP<1>")
	)
	(segment
		(start 304.455576 -210.97113)
		(end 303.18202 -210.97113)
		(width 0.16002)
		(layer "In6.Cu")
		(net "M_E_CPU0_SA_DQS_DP<1>")
	)
	(segment
		(start 290.629848 -209.70875)
		(end 289.618928 -210.71967)
		(width 0.16002)
		(layer "In6.Cu")
		(net "M_E_CPU0_SA_DQS_DP<1>")
	)
	(segment
		(start 309.45201 -211.095082)
		(end 309.45201 -210.618578)
		(width 0.16002)
		(layer "In6.Cu")
		(net "M_E_CPU0_SA_DQS_DP<1>")
	)
	(segment
		(start 310.843168 -212.009736)
		(end 310.410098 -211.576666)
		(width 0.16002)
		(layer "In6.Cu")
		(net "M_E_CPU0_SA_DQS_DP<1>")
	)
	(segment
		(start 282.22702 -210.53933)
		(end 281.840432 -210.53933)
		(width 0.16002)
		(layer "In6.Cu")
		(net "M_E_CPU0_SA_DQS_DP<1>")
	)
	(segment
		(start 310.300624 -213.028784)
		(end 310.843168 -212.48624)
		(width 0.16002)
		(layer "In6.Cu")
		(net "M_E_CPU0_SA_DQS_DP<1>")
	)
	(segment
		(start 309.01894 -210.185508)
		(end 308.542436 -210.185508)
		(width 0.16002)
		(layer "In6.Cu")
		(net "M_E_CPU0_SA_DQS_DP<1>")
	)
	(segment
		(start 319.363598 -224.358454)
		(end 319.363598 -223.534224)
		(width 0.16002)
		(layer "In6.Cu")
		(net "M_E_CPU0_SA_DQS_DP<1>")
	)
	(segment
		(start 291.046154 -209.70875)
		(end 290.629848 -209.70875)
		(width 0.16002)
		(layer "In6.Cu")
		(net "M_E_CPU0_SA_DQS_DP<1>")
	)
	(segment
		(start 286.345884 -210.209892)
		(end 285.496 -209.360008)
		(width 0.16002)
		(layer "In6.Cu")
		(net "M_E_CPU0_SA_DQS_DP<1>")
	)
	(segment
		(start 323.733668 -228.811582)
		(end 323.733668 -228.728524)
		(width 0.09525)
		(layer "In6.Cu")
		(net "M_E_CPU0_SA_DQS_DP<1>")
	)
	(segment
		(start 298.173902 -209.70875)
		(end 297.079162 -210.80349)
		(width 0.16002)
		(layer "In6.Cu")
		(net "M_E_CPU0_SA_DQS_DP<1>")
	)
	(segment
		(start 301.682912 -210.32089)
		(end 300.72203 -209.360008)
		(width 0.16002)
		(layer "In6.Cu")
		(net "M_E_CPU0_SA_DQS_DP<1>")
	)
	(segment
		(start 310.575452 -213.529672)
		(end 310.300624 -213.254844)
		(width 0.16002)
		(layer "In6.Cu")
		(net "M_E_CPU0_SA_DQS_DP<1>")
	)
	(segment
		(start 327.010014 -231.849168)
		(end 327.001632 -231.853994)
		(width 0.09525)
		(layer "In6.Cu")
		(net "M_E_CPU0_SA_DQS_DP<1>")
	)
	(segment
		(start 308.909466 -211.863686)
		(end 308.909466 -211.637626)
		(width 0.16002)
		(layer "In6.Cu")
		(net "M_E_CPU0_SA_DQS_DP<1>")
	)
	(segment
		(start 302.53178 -210.32089)
		(end 301.682912 -210.32089)
		(width 0.16002)
		(layer "In6.Cu")
		(net "M_E_CPU0_SA_DQS_DP<1>")
	)
	(segment
		(start 291.394896 -209.360008)
		(end 291.046154 -209.70875)
		(width 0.16002)
		(layer "In6.Cu")
		(net "M_E_CPU0_SA_DQS_DP<1>")
	)
	(segment
		(start 303.18202 -210.97113)
		(end 302.53178 -210.32089)
		(width 0.16002)
		(layer "In6.Cu")
		(net "M_E_CPU0_SA_DQS_DP<1>")
	)
	(segment
		(start 281.840432 -210.53933)
		(end 281.510994 -210.209892)
		(width 0.16002)
		(layer "In6.Cu")
		(net "M_E_CPU0_SA_DQS_DP<1>")
	)
	(segment
		(start 281.510994 -210.209892)
		(end 279.617932 -210.209892)
		(width 0.16002)
		(layer "In6.Cu")
		(net "M_E_CPU0_SA_DQS_DP<1>")
	)
	(segment
		(start 309.16499 -212.11921)
		(end 308.909466 -211.863686)
		(width 0.16002)
		(layer "In6.Cu")
		(net "M_E_CPU0_SA_DQS_DP<1>")
	)
	(segment
		(start 310.843168 -212.48624)
		(end 310.843168 -212.009736)
		(width 0.16002)
		(layer "In6.Cu")
		(net "M_E_CPU0_SA_DQS_DP<1>")
	)
	(segment
		(start 300.72203 -209.360008)
		(end 298.93895 -209.360008)
		(width 0.16002)
		(layer "In6.Cu")
		(net "M_E_CPU0_SA_DQS_DP<1>")
	)
	(segment
		(start 296.126408 -210.209892)
		(end 294.02786 -210.209892)
		(width 0.16002)
		(layer "In6.Cu")
		(net "M_E_CPU0_SA_DQS_DP<1>")
	)
	(segment
		(start 298.93895 -209.360008)
		(end 298.590208 -209.70875)
		(width 0.16002)
		(layer "In6.Cu")
		(net "M_E_CPU0_SA_DQS_DP<1>")
	)
	(segment
		(start 309.39105 -212.11921)
		(end 309.16499 -212.11921)
		(width 0.16002)
		(layer "In6.Cu")
		(net "M_E_CPU0_SA_DQS_DP<1>")
	)
	(segment
		(start 277.466044 -210.35899)
		(end 277.192232 -210.085178)
		(width 0.16002)
		(layer "In6.Cu")
		(net "M_E_CPU0_SA_DQS_DP<1>")
	)
	(segment
		(start 328.701146 -231.524048)
		(end 328.85507 -231.789478)
		(width 0.09525)
		(layer "In6.Cu")
		(net "M_E_CPU0_SA_DQS_DP<1>")
	)
	(segment
		(start 296.720006 -210.80349)
		(end 296.126408 -210.209892)
		(width 0.16002)
		(layer "In6.Cu")
		(net "M_E_CPU0_SA_DQS_DP<1>")
	)
	(segment
		(start 323.733668 -228.728524)
		(end 323.716904 -228.71176)
		(width 0.09525)
		(layer "In6.Cu")
		(net "M_E_CPU0_SA_DQS_DP<1>")
	)
	(segment
		(start 285.496 -209.360008)
		(end 283.851096 -209.360008)
		(width 0.16002)
		(layer "In6.Cu")
		(net "M_E_CPU0_SA_DQS_DP<1>")
	)
	(segment
		(start 305.717956 -209.70875)
		(end 304.455576 -210.97113)
		(width 0.16002)
		(layer "In6.Cu")
		(net "M_E_CPU0_SA_DQS_DP<1>")
	)
	(segment
		(start 293.177976 -209.360008)
		(end 291.394896 -209.360008)
		(width 0.16002)
		(layer "In6.Cu")
		(net "M_E_CPU0_SA_DQS_DP<1>")
	)
	(segment
		(start 317.173356 -221.343982)
		(end 317.173356 -217.75674)
		(width 0.16002)
		(layer "In6.Cu")
		(net "M_E_CPU0_SA_DQS_DP<1>")
	)
	(segment
		(start 325.418704 -230.65359)
		(end 325.418704 -230.05542)
		(width 0.09525)
		(layer "In6.Cu")
		(net "M_E_CPU0_SA_DQS_DP<1>")
	)
	(segment
		(start 279.617932 -210.209892)
		(end 279.468834 -210.35899)
		(width 0.16002)
		(layer "In6.Cu")
		(net "M_E_CPU0_SA_DQS_DP<1>")
	)
	(segment
		(start 324.989444 -229.62616)
		(end 324.548246 -229.62616)
		(width 0.09525)
		(layer "In6.Cu")
		(net "M_E_CPU0_SA_DQS_DP<1>")
	)
	(segment
		(start 317.173356 -217.75674)
		(end 312.946288 -213.529672)
		(width 0.16002)
		(layer "In6.Cu")
		(net "M_E_CPU0_SA_DQS_DP<1>")
	)
	(segment
		(start 309.933594 -211.576666)
		(end 309.39105 -212.11921)
		(width 0.16002)
		(layer "In6.Cu")
		(net "M_E_CPU0_SA_DQS_DP<1>")
	)
	(segment
		(start 294.02786 -210.209892)
		(end 293.177976 -209.360008)
		(width 0.16002)
		(layer "In6.Cu")
		(net "M_E_CPU0_SA_DQS_DP<1>")
	)
	(segment
		(start 283.0576 -209.70875)
		(end 282.22702 -210.53933)
		(width 0.16002)
		(layer "In6.Cu")
		(net "M_E_CPU0_SA_DQS_DP<1>")
	)
	(segment
		(start 325.418704 -230.05542)
		(end 324.989444 -229.62616)
		(width 0.09525)
		(layer "In6.Cu")
		(net "M_E_CPU0_SA_DQS_DP<1>")
	)
	(segment
		(start 319.363598 -223.534224)
		(end 317.173356 -221.343982)
		(width 0.16002)
		(layer "In6.Cu")
		(net "M_E_CPU0_SA_DQS_DP<1>")
	)
	(segment
		(start 327.581006 -231.853994)
		(end 327.572624 -231.849168)
		(width 0.09525)
		(layer "In6.Cu")
		(net "M_E_CPU0_SA_DQS_DP<1>")
	)
	(segment
		(start 289.618928 -210.71967)
		(end 289.20694 -210.71967)
		(width 0.16002)
		(layer "In6.Cu")
		(net "M_E_CPU0_SA_DQS_DP<1>")
	)
	(segment
		(start 324.548246 -229.62616)
		(end 323.733668 -228.811582)
		(width 0.09525)
		(layer "In6.Cu")
		(net "M_E_CPU0_SA_DQS_DP<1>")
	)
	(segment
		(start 326.555354 -231.79024)
		(end 325.418704 -230.65359)
		(width 0.09525)
		(layer "In6.Cu")
		(net "M_E_CPU0_SA_DQS_DP<1>")
	)
	(segment
		(start 328.85507 -231.789478)
		(end 328.831956 -231.876092)
		(width 0.09525)
		(layer "In6.Cu")
		(net "M_E_CPU0_SA_DQS_DP<1>")
	)
	(segment
		(start 288.697162 -210.209892)
		(end 286.345884 -210.209892)
		(width 0.16002)
		(layer "In6.Cu")
		(net "M_E_CPU0_SA_DQS_DP<1>")
	)
	(segment
		(start 307.999892 -210.728052)
		(end 307.773832 -210.728052)
		(width 0.16002)
		(layer "In6.Cu")
		(net "M_E_CPU0_SA_DQS_DP<1>")
	)
	(segment
		(start 308.909466 -211.637626)
		(end 309.45201 -211.095082)
		(width 0.16002)
		(layer "In6.Cu")
		(net "M_E_CPU0_SA_DQS_DP<1>")
	)
	(segment
		(start 279.468834 -210.35899)
		(end 277.466044 -210.35899)
		(width 0.16002)
		(layer "In6.Cu")
		(net "M_E_CPU0_SA_DQS_DP<1>")
	)
	(segment
		(start 283.851096 -209.360008)
		(end 283.502354 -209.70875)
		(width 0.16002)
		(layer "In6.Cu")
		(net "M_E_CPU0_SA_DQS_DP<1>")
	)
	(segment
		(start 309.45201 -210.618578)
		(end 309.01894 -210.185508)
		(width 0.16002)
		(layer "In6.Cu")
		(net "M_E_CPU0_SA_DQS_DP<1>")
	)
	(segment
		(start 312.946288 -213.529672)
		(end 310.575452 -213.529672)
		(width 0.16002)
		(layer "In6.Cu")
		(net "M_E_CPU0_SA_DQS_DP<1>")
	)
	(segment
		(start 306.75453 -209.70875)
		(end 305.717956 -209.70875)
		(width 0.16002)
		(layer "In6.Cu")
		(net "M_E_CPU0_SA_DQS_DP<1>")
	)
	(segment
		(start 283.502354 -209.70875)
		(end 283.0576 -209.70875)
		(width 0.16002)
		(layer "In6.Cu")
		(net "M_E_CPU0_SA_DQS_DP<1>")
	)
	(arc
		(start 326.632824 -231.849168)
		(mid 326.592181 -231.822214)
		(end 326.555354 -231.79024)
		(width 0.09525)
		(layer "In6.Cu")
		(net "M_E_CPU0_SA_DQS_DP<1>")
	)
	(arc
		(start 327.001632 -231.853994)
		(mid 326.8166 -231.899908)
		(end 326.632824 -231.849168)
		(width 0.09525)
		(layer "In6.Cu")
		(net "M_E_CPU0_SA_DQS_DP<1>")
	)
	(arc
		(start 327.56221 -231.843072)
		(mid 327.285302 -231.773395)
		(end 327.010014 -231.849168)
		(width 0.09525)
		(layer "In6.Cu")
		(net "M_E_CPU0_SA_DQS_DP<1>")
	)
	(arc
		(start 328.831956 -231.876092)
		(mid 328.669305 -231.898352)
		(end 328.512678 -231.849168)
		(width 0.09525)
		(layer "In6.Cu")
		(net "M_E_CPU0_SA_DQS_DP<1>")
	)
	(arc
		(start 328.512678 -231.849168)
		(mid 328.231246 -231.773413)
		(end 327.949814 -231.849168)
		(width 0.09525)
		(layer "In6.Cu")
		(net "M_E_CPU0_SA_DQS_DP<1>")
	)
	(arc
		(start 327.949814 -231.849168)
		(mid 327.766039 -231.89994)
		(end 327.581006 -231.853994)
		(width 0.09525)
		(layer "In6.Cu")
		(net "M_E_CPU0_SA_DQS_DP<1>")
	)
	(segment
		(start 329.167998 -226.930204)
		(end 328.701146 -226.664266)
		(width 0.12954)
		(layer "F.Cu")
		(net "M_E_CPU0_SA_DQS_DP<0>")
	)
	(segment
		(start 310.77408 -203.298552)
		(end 310.54802 -203.298552)
		(width 0.16002)
		(layer "In6.Cu")
		(net "M_E_CPU0_SA_DQS_DP<0>")
	)
	(segment
		(start 277.466044 -201.008996)
		(end 277.192232 -200.735184)
		(width 0.16002)
		(layer "In6.Cu")
		(net "M_E_CPU0_SA_DQS_DP<0>")
	)
	(segment
		(start 313.074812 -205.599284)
		(end 313.486546 -205.18755)
		(width 0.16002)
		(layer "In6.Cu")
		(net "M_E_CPU0_SA_DQS_DP<0>")
	)
	(segment
		(start 310.70423 -202.405234)
		(end 310.70423 -201.92873)
		(width 0.16002)
		(layer "In6.Cu")
		(net "M_E_CPU0_SA_DQS_DP<0>")
	)
	(segment
		(start 293.177976 -200.010014)
		(end 291.394896 -200.010014)
		(width 0.16002)
		(layer "In6.Cu")
		(net "M_E_CPU0_SA_DQS_DP<0>")
	)
	(segment
		(start 304.13706 -201.18197)
		(end 303.783492 -201.535538)
		(width 0.16002)
		(layer "In6.Cu")
		(net "M_E_CPU0_SA_DQS_DP<0>")
	)
	(segment
		(start 303.107598 -201.710544)
		(end 303.107598 -201.259186)
		(width 0.16002)
		(layer "In6.Cu")
		(net "M_E_CPU0_SA_DQS_DP<0>")
	)
	(segment
		(start 325.76008 -222.040958)
		(end 325.743316 -222.024194)
		(width 0.09525)
		(layer "In6.Cu")
		(net "M_E_CPU0_SA_DQS_DP<0>")
	)
	(segment
		(start 279.625552 -200.859898)
		(end 279.476454 -201.008996)
		(width 0.16002)
		(layer "In6.Cu")
		(net "M_E_CPU0_SA_DQS_DP<0>")
	)
	(segment
		(start 300.72203 -200.010014)
		(end 298.93895 -200.010014)
		(width 0.16002)
		(layer "In6.Cu")
		(net "M_E_CPU0_SA_DQS_DP<0>")
	)
	(segment
		(start 325.962518 -222.594424)
		(end 325.962518 -222.3262)
		(width 0.09525)
		(layer "In6.Cu")
		(net "M_E_CPU0_SA_DQS_DP<0>")
	)
	(segment
		(start 327.10247 -226.17938)
		(end 327.070974 -226.161092)
		(width 0.09525)
		(layer "In6.Cu")
		(net "M_E_CPU0_SA_DQS_DP<0>")
	)
	(segment
		(start 309.382922 -201.907394)
		(end 309.156862 -201.907394)
		(width 0.16002)
		(layer "In6.Cu")
		(net "M_E_CPU0_SA_DQS_DP<0>")
	)
	(segment
		(start 285.507176 -200.010014)
		(end 283.851096 -200.010014)
		(width 0.16002)
		(layer "In6.Cu")
		(net "M_E_CPU0_SA_DQS_DP<0>")
	)
	(segment
		(start 296.928286 -201.189336)
		(end 296.598848 -200.859898)
		(width 0.16002)
		(layer "In6.Cu")
		(net "M_E_CPU0_SA_DQS_DP<0>")
	)
	(segment
		(start 327.581006 -226.994212)
		(end 327.572624 -226.989386)
		(width 0.09525)
		(layer "In6.Cu")
		(net "M_E_CPU0_SA_DQS_DP<0>")
	)
	(segment
		(start 281.510994 -200.859898)
		(end 279.625552 -200.859898)
		(width 0.16002)
		(layer "In6.Cu")
		(net "M_E_CPU0_SA_DQS_DP<0>")
	)
	(segment
		(start 312.576972 -204.277976)
		(end 312.165238 -204.68971)
		(width 0.16002)
		(layer "In6.Cu")
		(net "M_E_CPU0_SA_DQS_DP<0>")
	)
	(segment
		(start 311.939178 -204.68971)
		(end 311.683654 -204.434186)
		(width 0.16002)
		(layer "In6.Cu")
		(net "M_E_CPU0_SA_DQS_DP<0>")
	)
	(segment
		(start 326.63257 -225.369374)
		(end 326.600058 -225.350578)
		(width 0.09525)
		(layer "In6.Cu")
		(net "M_E_CPU0_SA_DQS_DP<0>")
	)
	(segment
		(start 313.486546 -205.18755)
		(end 313.486546 -204.711046)
		(width 0.16002)
		(layer "In6.Cu")
		(net "M_E_CPU0_SA_DQS_DP<0>")
	)
	(segment
		(start 289.054794 -200.859898)
		(end 286.35706 -200.859898)
		(width 0.16002)
		(layer "In6.Cu")
		(net "M_E_CPU0_SA_DQS_DP<0>")
	)
	(segment
		(start 312.095388 -203.319888)
		(end 311.662318 -202.886818)
		(width 0.16002)
		(layer "In6.Cu")
		(net "M_E_CPU0_SA_DQS_DP<0>")
	)
	(segment
		(start 309.156862 -201.907394)
		(end 308.73954 -201.490072)
		(width 0.16002)
		(layer "In6.Cu")
		(net "M_E_CPU0_SA_DQS_DP<0>")
	)
	(segment
		(start 279.476454 -201.008996)
		(end 277.466044 -201.008996)
		(width 0.16002)
		(layer "In6.Cu")
		(net "M_E_CPU0_SA_DQS_DP<0>")
	)
	(segment
		(start 326.17791 -222.949008)
		(end 326.12965 -222.921068)
		(width 0.09525)
		(layer "In6.Cu")
		(net "M_E_CPU0_SA_DQS_DP<0>")
	)
	(segment
		(start 310.54802 -203.298552)
		(end 310.292496 -203.043028)
		(width 0.16002)
		(layer "In6.Cu")
		(net "M_E_CPU0_SA_DQS_DP<0>")
	)
	(segment
		(start 313.486546 -204.711046)
		(end 313.053476 -204.277976)
		(width 0.16002)
		(layer "In6.Cu")
		(net "M_E_CPU0_SA_DQS_DP<0>")
	)
	(segment
		(start 323.000878 -219.281756)
		(end 323.000878 -215.081866)
		(width 0.16002)
		(layer "In6.Cu")
		(net "M_E_CPU0_SA_DQS_DP<0>")
	)
	(segment
		(start 326.67067 -223.77146)
		(end 326.63257 -223.749362)
		(width 0.09525)
		(layer "In6.Cu")
		(net "M_E_CPU0_SA_DQS_DP<0>")
	)
	(segment
		(start 297.343322 -201.189336)
		(end 296.928286 -201.189336)
		(width 0.16002)
		(layer "In6.Cu")
		(net "M_E_CPU0_SA_DQS_DP<0>")
	)
	(segment
		(start 312.095388 -203.796392)
		(end 312.095388 -203.319888)
		(width 0.16002)
		(layer "In6.Cu")
		(net "M_E_CPU0_SA_DQS_DP<0>")
	)
	(segment
		(start 325.76008 -222.123762)
		(end 325.76008 -222.040958)
		(width 0.09525)
		(layer "In6.Cu")
		(net "M_E_CPU0_SA_DQS_DP<0>")
	)
	(segment
		(start 311.662318 -202.886818)
		(end 311.185814 -202.886818)
		(width 0.16002)
		(layer "In6.Cu")
		(net "M_E_CPU0_SA_DQS_DP<0>")
	)
	(segment
		(start 283.502354 -200.358756)
		(end 283.0576 -200.358756)
		(width 0.16002)
		(layer "In6.Cu")
		(net "M_E_CPU0_SA_DQS_DP<0>")
	)
	(segment
		(start 310.292496 -202.816968)
		(end 310.70423 -202.405234)
		(width 0.16002)
		(layer "In6.Cu")
		(net "M_E_CPU0_SA_DQS_DP<0>")
	)
	(segment
		(start 303.783492 -201.710544)
		(end 303.585626 -201.90841)
		(width 0.16002)
		(layer "In6.Cu")
		(net "M_E_CPU0_SA_DQS_DP<0>")
	)
	(segment
		(start 283.0576 -200.358756)
		(end 282.22702 -201.189336)
		(width 0.16002)
		(layer "In6.Cu")
		(net "M_E_CPU0_SA_DQS_DP<0>")
	)
	(segment
		(start 327.57237 -226.989386)
		(end 327.540874 -226.971098)
		(width 0.09525)
		(layer "In6.Cu")
		(net "M_E_CPU0_SA_DQS_DP<0>")
	)
	(segment
		(start 290.629848 -200.358756)
		(end 289.799268 -201.189336)
		(width 0.16002)
		(layer "In6.Cu")
		(net "M_E_CPU0_SA_DQS_DP<0>")
	)
	(segment
		(start 294.02786 -200.859898)
		(end 293.177976 -200.010014)
		(width 0.16002)
		(layer "In6.Cu")
		(net "M_E_CPU0_SA_DQS_DP<0>")
	)
	(segment
		(start 326.63257 -224.719134)
		(end 326.67067 -224.697036)
		(width 0.09525)
		(layer "In6.Cu")
		(net "M_E_CPU0_SA_DQS_DP<0>")
	)
	(segment
		(start 310.292496 -203.043028)
		(end 310.292496 -202.816968)
		(width 0.16002)
		(layer "In6.Cu")
		(net "M_E_CPU0_SA_DQS_DP<0>")
	)
	(segment
		(start 326.67067 -225.391472)
		(end 326.63257 -225.369374)
		(width 0.09525)
		(layer "In6.Cu")
		(net "M_E_CPU0_SA_DQS_DP<0>")
	)
	(segment
		(start 283.851096 -200.010014)
		(end 283.502354 -200.358756)
		(width 0.16002)
		(layer "In6.Cu")
		(net "M_E_CPU0_SA_DQS_DP<0>")
	)
	(segment
		(start 303.107598 -201.259186)
		(end 302.723804 -200.875392)
		(width 0.16002)
		(layer "In6.Cu")
		(net "M_E_CPU0_SA_DQS_DP<0>")
	)
	(segment
		(start 325.962518 -222.3262)
		(end 325.76008 -222.123762)
		(width 0.09525)
		(layer "In6.Cu")
		(net "M_E_CPU0_SA_DQS_DP<0>")
	)
	(segment
		(start 314.595764 -206.676752)
		(end 313.92622 -206.676752)
		(width 0.16002)
		(layer "In6.Cu")
		(net "M_E_CPU0_SA_DQS_DP<0>")
	)
	(segment
		(start 310.70423 -201.92873)
		(end 310.27116 -201.49566)
		(width 0.16002)
		(layer "In6.Cu")
		(net "M_E_CPU0_SA_DQS_DP<0>")
	)
	(segment
		(start 308.73954 -201.490072)
		(end 307.77688 -201.490072)
		(width 0.16002)
		(layer "In6.Cu")
		(net "M_E_CPU0_SA_DQS_DP<0>")
	)
	(segment
		(start 289.799268 -201.189336)
		(end 289.384232 -201.189336)
		(width 0.16002)
		(layer "In6.Cu")
		(net "M_E_CPU0_SA_DQS_DP<0>")
	)
	(segment
		(start 302.723804 -200.875392)
		(end 301.587408 -200.875392)
		(width 0.16002)
		(layer "In6.Cu")
		(net "M_E_CPU0_SA_DQS_DP<0>")
	)
	(segment
		(start 298.93895 -200.010014)
		(end 298.590208 -200.358756)
		(width 0.16002)
		(layer "In6.Cu")
		(net "M_E_CPU0_SA_DQS_DP<0>")
	)
	(segment
		(start 291.046154 -200.358756)
		(end 290.629848 -200.358756)
		(width 0.16002)
		(layer "In6.Cu")
		(net "M_E_CPU0_SA_DQS_DP<0>")
	)
	(segment
		(start 307.77688 -201.490072)
		(end 306.645564 -200.358756)
		(width 0.16002)
		(layer "In6.Cu")
		(net "M_E_CPU0_SA_DQS_DP<0>")
	)
	(segment
		(start 313.053476 -204.277976)
		(end 312.576972 -204.277976)
		(width 0.16002)
		(layer "In6.Cu")
		(net "M_E_CPU0_SA_DQS_DP<0>")
	)
	(segment
		(start 303.585626 -201.90841)
		(end 303.305464 -201.90841)
		(width 0.16002)
		(layer "In6.Cu")
		(net "M_E_CPU0_SA_DQS_DP<0>")
	)
	(segment
		(start 311.185814 -202.886818)
		(end 310.77408 -203.298552)
		(width 0.16002)
		(layer "In6.Cu")
		(net "M_E_CPU0_SA_DQS_DP<0>")
	)
	(segment
		(start 298.173902 -200.358756)
		(end 297.343322 -201.189336)
		(width 0.16002)
		(layer "In6.Cu")
		(net "M_E_CPU0_SA_DQS_DP<0>")
	)
	(segment
		(start 305.717956 -200.358756)
		(end 304.894742 -201.18197)
		(width 0.16002)
		(layer "In6.Cu")
		(net "M_E_CPU0_SA_DQS_DP<0>")
	)
	(segment
		(start 326.63257 -223.749362)
		(end 326.597772 -223.729296)
		(width 0.09525)
		(layer "In6.Cu")
		(net "M_E_CPU0_SA_DQS_DP<0>")
	)
	(segment
		(start 327.14057 -226.201478)
		(end 327.10247 -226.17938)
		(width 0.09525)
		(layer "In6.Cu")
		(net "M_E_CPU0_SA_DQS_DP<0>")
	)
	(segment
		(start 286.35706 -200.859898)
		(end 285.507176 -200.010014)
		(width 0.16002)
		(layer "In6.Cu")
		(net "M_E_CPU0_SA_DQS_DP<0>")
	)
	(segment
		(start 303.783492 -201.535538)
		(end 303.783492 -201.710544)
		(width 0.16002)
		(layer "In6.Cu")
		(net "M_E_CPU0_SA_DQS_DP<0>")
	)
	(segment
		(start 328.85507 -226.929696)
		(end 328.831956 -227.01631)
		(width 0.09525)
		(layer "In6.Cu")
		(net "M_E_CPU0_SA_DQS_DP<0>")
	)
	(segment
		(start 301.587408 -200.875392)
		(end 300.72203 -200.010014)
		(width 0.16002)
		(layer "In6.Cu")
		(net "M_E_CPU0_SA_DQS_DP<0>")
	)
	(segment
		(start 323.000878 -215.081866)
		(end 314.595764 -206.676752)
		(width 0.16002)
		(layer "In6.Cu")
		(net "M_E_CPU0_SA_DQS_DP<0>")
	)
	(segment
		(start 326.600058 -224.73793)
		(end 326.63257 -224.719134)
		(width 0.09525)
		(layer "In6.Cu")
		(net "M_E_CPU0_SA_DQS_DP<0>")
	)
	(segment
		(start 281.840432 -201.189336)
		(end 281.510994 -200.859898)
		(width 0.16002)
		(layer "In6.Cu")
		(net "M_E_CPU0_SA_DQS_DP<0>")
	)
	(segment
		(start 326.198992 -222.960692)
		(end 326.17791 -222.949008)
		(width 0.09525)
		(layer "In6.Cu")
		(net "M_E_CPU0_SA_DQS_DP<0>")
	)
	(segment
		(start 325.743316 -222.024194)
		(end 323.000878 -219.281756)
		(width 0.16002)
		(layer "In6.Cu")
		(net "M_E_CPU0_SA_DQS_DP<0>")
	)
	(segment
		(start 289.384232 -201.189336)
		(end 289.054794 -200.859898)
		(width 0.16002)
		(layer "In6.Cu")
		(net "M_E_CPU0_SA_DQS_DP<0>")
	)
	(segment
		(start 310.27116 -201.49566)
		(end 309.794656 -201.49566)
		(width 0.16002)
		(layer "In6.Cu")
		(net "M_E_CPU0_SA_DQS_DP<0>")
	)
	(segment
		(start 328.701146 -226.664266)
		(end 328.85507 -226.929696)
		(width 0.09525)
		(layer "In6.Cu")
		(net "M_E_CPU0_SA_DQS_DP<0>")
	)
	(segment
		(start 306.645564 -200.358756)
		(end 305.717956 -200.358756)
		(width 0.16002)
		(layer "In6.Cu")
		(net "M_E_CPU0_SA_DQS_DP<0>")
	)
	(segment
		(start 312.165238 -204.68971)
		(end 311.939178 -204.68971)
		(width 0.16002)
		(layer "In6.Cu")
		(net "M_E_CPU0_SA_DQS_DP<0>")
	)
	(segment
		(start 304.894742 -201.18197)
		(end 304.13706 -201.18197)
		(width 0.16002)
		(layer "In6.Cu")
		(net "M_E_CPU0_SA_DQS_DP<0>")
	)
	(segment
		(start 282.22702 -201.189336)
		(end 281.840432 -201.189336)
		(width 0.16002)
		(layer "In6.Cu")
		(net "M_E_CPU0_SA_DQS_DP<0>")
	)
	(segment
		(start 296.598848 -200.859898)
		(end 294.02786 -200.859898)
		(width 0.16002)
		(layer "In6.Cu")
		(net "M_E_CPU0_SA_DQS_DP<0>")
	)
	(segment
		(start 327.572624 -226.989386)
		(end 327.57237 -226.989386)
		(width 0.09525)
		(layer "In6.Cu")
		(net "M_E_CPU0_SA_DQS_DP<0>")
	)
	(segment
		(start 313.92622 -206.676752)
		(end 313.074812 -205.825344)
		(width 0.16002)
		(layer "In6.Cu")
		(net "M_E_CPU0_SA_DQS_DP<0>")
	)
	(segment
		(start 311.683654 -204.434186)
		(end 311.683654 -204.208126)
		(width 0.16002)
		(layer "In6.Cu")
		(net "M_E_CPU0_SA_DQS_DP<0>")
	)
	(segment
		(start 291.394896 -200.010014)
		(end 291.046154 -200.358756)
		(width 0.16002)
		(layer "In6.Cu")
		(net "M_E_CPU0_SA_DQS_DP<0>")
	)
	(segment
		(start 311.683654 -204.208126)
		(end 312.095388 -203.796392)
		(width 0.16002)
		(layer "In6.Cu")
		(net "M_E_CPU0_SA_DQS_DP<0>")
	)
	(segment
		(start 298.590208 -200.358756)
		(end 298.173902 -200.358756)
		(width 0.16002)
		(layer "In6.Cu")
		(net "M_E_CPU0_SA_DQS_DP<0>")
	)
	(segment
		(start 313.074812 -205.825344)
		(end 313.074812 -205.599284)
		(width 0.16002)
		(layer "In6.Cu")
		(net "M_E_CPU0_SA_DQS_DP<0>")
	)
	(segment
		(start 303.305464 -201.90841)
		(end 303.107598 -201.710544)
		(width 0.16002)
		(layer "In6.Cu")
		(net "M_E_CPU0_SA_DQS_DP<0>")
	)
	(segment
		(start 309.794656 -201.49566)
		(end 309.382922 -201.907394)
		(width 0.16002)
		(layer "In6.Cu")
		(net "M_E_CPU0_SA_DQS_DP<0>")
	)
	(arc
		(start 327.383394 -226.664266)
		(mid 327.318997 -226.40296)
		(end 327.14057 -226.201478)
		(width 0.09525)
		(layer "In6.Cu")
		(net "M_E_CPU0_SA_DQS_DP<0>")
	)
	(arc
		(start 328.831956 -227.01631)
		(mid 328.669305 -227.03857)
		(end 328.512678 -226.989386)
		(width 0.09525)
		(layer "In6.Cu")
		(net "M_E_CPU0_SA_DQS_DP<0>")
	)
	(arc
		(start 326.12965 -222.921068)
		(mid 326.006751 -222.777876)
		(end 325.962518 -222.594424)
		(width 0.09525)
		(layer "In6.Cu")
		(net "M_E_CPU0_SA_DQS_DP<0>")
	)
	(arc
		(start 327.070974 -226.161092)
		(mid 326.955176 -226.026698)
		(end 326.913494 -225.85426)
		(width 0.09525)
		(layer "In6.Cu")
		(net "M_E_CPU0_SA_DQS_DP<0>")
	)
	(arc
		(start 328.512678 -226.989386)
		(mid 328.231246 -226.913631)
		(end 327.949814 -226.989386)
		(width 0.09525)
		(layer "In6.Cu")
		(net "M_E_CPU0_SA_DQS_DP<0>")
	)
	(arc
		(start 326.597772 -223.729296)
		(mid 326.483987 -223.595252)
		(end 326.443086 -223.424242)
		(width 0.09525)
		(layer "In6.Cu")
		(net "M_E_CPU0_SA_DQS_DP<0>")
	)
	(arc
		(start 327.540874 -226.971098)
		(mid 327.425076 -226.836704)
		(end 327.383394 -226.664266)
		(width 0.09525)
		(layer "In6.Cu")
		(net "M_E_CPU0_SA_DQS_DP<0>")
	)
	(arc
		(start 326.67067 -224.697036)
		(mid 326.91352 -224.234248)
		(end 326.67067 -223.77146)
		(width 0.09525)
		(layer "In6.Cu")
		(net "M_E_CPU0_SA_DQS_DP<0>")
	)
	(arc
		(start 326.443086 -223.424242)
		(mid 326.378326 -223.162307)
		(end 326.198992 -222.960692)
		(width 0.09525)
		(layer "In6.Cu")
		(net "M_E_CPU0_SA_DQS_DP<0>")
	)
	(arc
		(start 326.913494 -225.85426)
		(mid 326.849097 -225.592954)
		(end 326.67067 -225.391472)
		(width 0.09525)
		(layer "In6.Cu")
		(net "M_E_CPU0_SA_DQS_DP<0>")
	)
	(arc
		(start 327.949814 -226.989386)
		(mid 327.766039 -227.040158)
		(end 327.581006 -226.994212)
		(width 0.09525)
		(layer "In6.Cu")
		(net "M_E_CPU0_SA_DQS_DP<0>")
	)
	(arc
		(start 326.600058 -225.350578)
		(mid 326.443326 -225.044254)
		(end 326.600058 -224.73793)
		(width 0.09525)
		(layer "In6.Cu")
		(net "M_E_CPU0_SA_DQS_DP<0>")
	)
	(segment
		(start 330.577952 -247.1801)
		(end 330.1111 -246.914162)
		(width 0.12954)
		(layer "F.Cu")
		(net "M_E_CPU0_SA_DQS_DN<9>")
	)
	(segment
		(start 303.060608 -239.923066)
		(end 301.992792 -239.923066)
		(width 0.16002)
		(layer "In6.Cu")
		(net "M_E_CPU0_SA_DQS_DN<9>")
	)
	(segment
		(start 289.72764 -239.923066)
		(end 289.25012 -239.923066)
		(width 0.16002)
		(layer "In6.Cu")
		(net "M_E_CPU0_SA_DQS_DN<9>")
	)
	(segment
		(start 326.177402 -247.247664)
		(end 326.15505 -247.23471)
		(width 0.09525)
		(layer "In6.Cu")
		(net "M_E_CPU0_SA_DQS_DN<9>")
	)
	(segment
		(start 297.271694 -239.923066)
		(end 296.463974 -239.923066)
		(width 0.16002)
		(layer "In6.Cu")
		(net "M_E_CPU0_SA_DQS_DN<9>")
	)
	(segment
		(start 277.62454 -239.424718)
		(end 276.478238 -239.424718)
		(width 0.16002)
		(layer "In6.Cu")
		(net "M_E_CPU0_SA_DQS_DN<9>")
	)
	(segment
		(start 313.203082 -246.872252)
		(end 308.103778 -241.772948)
		(width 0.16002)
		(layer "In6.Cu")
		(net "M_E_CPU0_SA_DQS_DN<9>")
	)
	(segment
		(start 323.978778 -247.438926)
		(end 323.919596 -247.379744)
		(width 0.09525)
		(layer "In6.Cu")
		(net "M_E_CPU0_SA_DQS_DN<9>")
	)
	(segment
		(start 307.609748 -240.38941)
		(end 305.758088 -240.38941)
		(width 0.16002)
		(layer "In6.Cu")
		(net "M_E_CPU0_SA_DQS_DN<9>")
	)
	(segment
		(start 283.633164 -239.038892)
		(end 283.068014 -239.038892)
		(width 0.16002)
		(layer "In6.Cu")
		(net "M_E_CPU0_SA_DQS_DN<9>")
	)
	(segment
		(start 327.479914 -247.239282)
		(end 327.471532 -247.244108)
		(width 0.09525)
		(layer "In6.Cu")
		(net "M_E_CPU0_SA_DQS_DN<9>")
	)
	(segment
		(start 324.921118 -247.439942)
		(end 324.920102 -247.438926)
		(width 0.09525)
		(layer "In6.Cu")
		(net "M_E_CPU0_SA_DQS_DN<9>")
	)
	(segment
		(start 296.463974 -239.923066)
		(end 296.128948 -240.258092)
		(width 0.16002)
		(layer "In6.Cu")
		(net "M_E_CPU0_SA_DQS_DN<9>")
	)
	(segment
		(start 283.068014 -239.038892)
		(end 282.18384 -239.923066)
		(width 0.16002)
		(layer "In6.Cu")
		(net "M_E_CPU0_SA_DQS_DN<9>")
	)
	(segment
		(start 281.70632 -239.923066)
		(end 281.371294 -240.258092)
		(width 0.16002)
		(layer "In6.Cu")
		(net "M_E_CPU0_SA_DQS_DN<9>")
	)
	(segment
		(start 299.106844 -239.424718)
		(end 298.721018 -239.038892)
		(width 0.16002)
		(layer "In6.Cu")
		(net "M_E_CPU0_SA_DQS_DN<9>")
	)
	(segment
		(start 322.866258 -246.872252)
		(end 313.203082 -246.872252)
		(width 0.16002)
		(layer "In6.Cu")
		(net "M_E_CPU0_SA_DQS_DN<9>")
	)
	(segment
		(start 308.103778 -240.88344)
		(end 307.609748 -240.38941)
		(width 0.16002)
		(layer "In6.Cu")
		(net "M_E_CPU0_SA_DQS_DN<9>")
	)
	(segment
		(start 325.527924 -247.275858)
		(end 325.480426 -247.32361)
		(width 0.09525)
		(layer "In6.Cu")
		(net "M_E_CPU0_SA_DQS_DN<9>")
	)
	(segment
		(start 330.265024 -247.179592)
		(end 330.24191 -247.266206)
		(width 0.09525)
		(layer "In6.Cu")
		(net "M_E_CPU0_SA_DQS_DN<9>")
	)
	(segment
		(start 298.155868 -239.038892)
		(end 297.271694 -239.923066)
		(width 0.16002)
		(layer "In6.Cu")
		(net "M_E_CPU0_SA_DQS_DN<9>")
	)
	(segment
		(start 330.1111 -246.914162)
		(end 330.265024 -247.179592)
		(width 0.09525)
		(layer "In6.Cu")
		(net "M_E_CPU0_SA_DQS_DN<9>")
	)
	(segment
		(start 328.99096 -247.244108)
		(end 328.982578 -247.239282)
		(width 0.09525)
		(layer "In6.Cu")
		(net "M_E_CPU0_SA_DQS_DN<9>")
	)
	(segment
		(start 281.371294 -240.258092)
		(end 279.636728 -240.258092)
		(width 0.16002)
		(layer "In6.Cu")
		(net "M_E_CPU0_SA_DQS_DN<9>")
	)
	(segment
		(start 325.200264 -247.439942)
		(end 324.921118 -247.439942)
		(width 0.09525)
		(layer "In6.Cu")
		(net "M_E_CPU0_SA_DQS_DN<9>")
	)
	(segment
		(start 328.419714 -247.239282)
		(end 328.411332 -247.244108)
		(width 0.09525)
		(layer "In6.Cu")
		(net "M_E_CPU0_SA_DQS_DN<9>")
	)
	(segment
		(start 324.920102 -247.438926)
		(end 323.978778 -247.438926)
		(width 0.09525)
		(layer "In6.Cu")
		(net "M_E_CPU0_SA_DQS_DN<9>")
	)
	(segment
		(start 327.490328 -247.233186)
		(end 327.479914 -247.239282)
		(width 0.09525)
		(layer "In6.Cu")
		(net "M_E_CPU0_SA_DQS_DN<9>")
	)
	(segment
		(start 296.128948 -240.258092)
		(end 294.783764 -240.258092)
		(width 0.16002)
		(layer "In6.Cu")
		(net "M_E_CPU0_SA_DQS_DN<9>")
	)
	(segment
		(start 305.291744 -239.923066)
		(end 303.774348 -239.923066)
		(width 0.16002)
		(layer "In6.Cu")
		(net "M_E_CPU0_SA_DQS_DN<9>")
	)
	(segment
		(start 282.18384 -239.923066)
		(end 281.70632 -239.923066)
		(width 0.16002)
		(layer "In6.Cu")
		(net "M_E_CPU0_SA_DQS_DN<9>")
	)
	(segment
		(start 273.36623 -239.25911)
		(end 273.092164 -238.985044)
		(width 0.16002)
		(layer "In6.Cu")
		(net "M_E_CPU0_SA_DQS_DN<9>")
	)
	(segment
		(start 275.39823 -239.078262)
		(end 275.217382 -239.25911)
		(width 0.16002)
		(layer "In6.Cu")
		(net "M_E_CPU0_SA_DQS_DN<9>")
	)
	(segment
		(start 301.992792 -239.923066)
		(end 300.789594 -239.424718)
		(width 0.16002)
		(layer "In6.Cu")
		(net "M_E_CPU0_SA_DQS_DN<9>")
	)
	(segment
		(start 285.13532 -239.424718)
		(end 284.01899 -239.424718)
		(width 0.16002)
		(layer "In6.Cu")
		(net "M_E_CPU0_SA_DQS_DN<9>")
	)
	(segment
		(start 303.657508 -239.806226)
		(end 303.177448 -239.806226)
		(width 0.16002)
		(layer "In6.Cu")
		(net "M_E_CPU0_SA_DQS_DN<9>")
	)
	(segment
		(start 303.774348 -239.923066)
		(end 303.657508 -239.806226)
		(width 0.16002)
		(layer "In6.Cu")
		(net "M_E_CPU0_SA_DQS_DN<9>")
	)
	(segment
		(start 290.611814 -239.038892)
		(end 289.72764 -239.923066)
		(width 0.16002)
		(layer "In6.Cu")
		(net "M_E_CPU0_SA_DQS_DN<9>")
	)
	(segment
		(start 287.147508 -240.258092)
		(end 285.13532 -239.424718)
		(width 0.16002)
		(layer "In6.Cu")
		(net "M_E_CPU0_SA_DQS_DN<9>")
	)
	(segment
		(start 289.25012 -239.923066)
		(end 288.915094 -240.258092)
		(width 0.16002)
		(layer "In6.Cu")
		(net "M_E_CPU0_SA_DQS_DN<9>")
	)
	(segment
		(start 291.176964 -239.038892)
		(end 290.611814 -239.038892)
		(width 0.16002)
		(layer "In6.Cu")
		(net "M_E_CPU0_SA_DQS_DN<9>")
	)
	(segment
		(start 323.895974 -247.379744)
		(end 323.37375 -247.379744)
		(width 0.16002)
		(layer "In6.Cu")
		(net "M_E_CPU0_SA_DQS_DN<9>")
	)
	(segment
		(start 275.217382 -239.25911)
		(end 273.36623 -239.25911)
		(width 0.16002)
		(layer "In6.Cu")
		(net "M_E_CPU0_SA_DQS_DN<9>")
	)
	(segment
		(start 292.771576 -239.424718)
		(end 291.56279 -239.424718)
		(width 0.16002)
		(layer "In6.Cu")
		(net "M_E_CPU0_SA_DQS_DN<9>")
	)
	(segment
		(start 276.131782 -239.078262)
		(end 275.39823 -239.078262)
		(width 0.16002)
		(layer "In6.Cu")
		(net "M_E_CPU0_SA_DQS_DN<9>")
	)
	(segment
		(start 276.478238 -239.424718)
		(end 276.131782 -239.078262)
		(width 0.16002)
		(layer "In6.Cu")
		(net "M_E_CPU0_SA_DQS_DN<9>")
	)
	(segment
		(start 303.177448 -239.806226)
		(end 303.060608 -239.923066)
		(width 0.16002)
		(layer "In6.Cu")
		(net "M_E_CPU0_SA_DQS_DN<9>")
	)
	(segment
		(start 327.103232 -247.239282)
		(end 327.092818 -247.233186)
		(width 0.09525)
		(layer "In6.Cu")
		(net "M_E_CPU0_SA_DQS_DN<9>")
	)
	(segment
		(start 294.783764 -240.258092)
		(end 292.771576 -239.424718)
		(width 0.16002)
		(layer "In6.Cu")
		(net "M_E_CPU0_SA_DQS_DN<9>")
	)
	(segment
		(start 308.103778 -241.772948)
		(end 308.103778 -240.88344)
		(width 0.16002)
		(layer "In6.Cu")
		(net "M_E_CPU0_SA_DQS_DN<9>")
	)
	(segment
		(start 288.915094 -240.258092)
		(end 287.147508 -240.258092)
		(width 0.16002)
		(layer "In6.Cu")
		(net "M_E_CPU0_SA_DQS_DN<9>")
	)
	(segment
		(start 284.01899 -239.424718)
		(end 283.633164 -239.038892)
		(width 0.16002)
		(layer "In6.Cu")
		(net "M_E_CPU0_SA_DQS_DN<9>")
	)
	(segment
		(start 326.150478 -247.231916)
		(end 326.14997 -247.232424)
		(width 0.09525)
		(layer "In6.Cu")
		(net "M_E_CPU0_SA_DQS_DN<9>")
	)
	(segment
		(start 323.37375 -247.379744)
		(end 322.866258 -246.872252)
		(width 0.16002)
		(layer "In6.Cu")
		(net "M_E_CPU0_SA_DQS_DN<9>")
	)
	(segment
		(start 323.919596 -247.379744)
		(end 323.895974 -247.379744)
		(width 0.09525)
		(layer "In6.Cu")
		(net "M_E_CPU0_SA_DQS_DN<9>")
	)
	(segment
		(start 291.56279 -239.424718)
		(end 291.176964 -239.038892)
		(width 0.16002)
		(layer "In6.Cu")
		(net "M_E_CPU0_SA_DQS_DN<9>")
	)
	(segment
		(start 279.636728 -240.258092)
		(end 277.62454 -239.424718)
		(width 0.16002)
		(layer "In6.Cu")
		(net "M_E_CPU0_SA_DQS_DN<9>")
	)
	(segment
		(start 305.758088 -240.38941)
		(end 305.291744 -239.923066)
		(width 0.16002)
		(layer "In6.Cu")
		(net "M_E_CPU0_SA_DQS_DN<9>")
	)
	(segment
		(start 326.15505 -247.23471)
		(end 326.150478 -247.231916)
		(width 0.09525)
		(layer "In6.Cu")
		(net "M_E_CPU0_SA_DQS_DN<9>")
	)
	(segment
		(start 298.721018 -239.038892)
		(end 298.155868 -239.038892)
		(width 0.16002)
		(layer "In6.Cu")
		(net "M_E_CPU0_SA_DQS_DN<9>")
	)
	(segment
		(start 300.789594 -239.424718)
		(end 299.106844 -239.424718)
		(width 0.16002)
		(layer "In6.Cu")
		(net "M_E_CPU0_SA_DQS_DN<9>")
	)
	(arc
		(start 325.669656 -247.199404)
		(mid 325.593152 -247.227185)
		(end 325.527924 -247.275858)
		(width 0.09525)
		(layer "In6.Cu")
		(net "M_E_CPU0_SA_DQS_DN<9>")
	)
	(arc
		(start 328.411332 -247.244108)
		(mid 328.2263 -247.290022)
		(end 328.042524 -247.239282)
		(width 0.09525)
		(layer "In6.Cu")
		(net "M_E_CPU0_SA_DQS_DN<9>")
	)
	(arc
		(start 329.922632 -247.239282)
		(mid 329.6412 -247.163527)
		(end 329.359768 -247.239282)
		(width 0.09525)
		(layer "In6.Cu")
		(net "M_E_CPU0_SA_DQS_DN<9>")
	)
	(arc
		(start 327.092818 -247.233186)
		(mid 326.815656 -247.163386)
		(end 326.540114 -247.239282)
		(width 0.09525)
		(layer "In6.Cu")
		(net "M_E_CPU0_SA_DQS_DN<9>")
	)
	(arc
		(start 326.540114 -247.239282)
		(mid 326.359835 -247.290113)
		(end 326.177402 -247.247664)
		(width 0.09525)
		(layer "In6.Cu")
		(net "M_E_CPU0_SA_DQS_DN<9>")
	)
	(arc
		(start 326.14997 -247.232424)
		(mid 325.945757 -247.167575)
		(end 325.73214 -247.184164)
		(width 0.09525)
		(layer "In6.Cu")
		(net "M_E_CPU0_SA_DQS_DN<9>")
	)
	(arc
		(start 325.73214 -247.184164)
		(mid 325.701028 -247.192316)
		(end 325.669656 -247.199404)
		(width 0.09525)
		(layer "In6.Cu")
		(net "M_E_CPU0_SA_DQS_DN<9>")
	)
	(arc
		(start 328.982578 -247.239282)
		(mid 328.701146 -247.163527)
		(end 328.419714 -247.239282)
		(width 0.09525)
		(layer "In6.Cu")
		(net "M_E_CPU0_SA_DQS_DN<9>")
	)
	(arc
		(start 327.471532 -247.244108)
		(mid 327.286754 -247.289901)
		(end 327.103232 -247.239282)
		(width 0.09525)
		(layer "In6.Cu")
		(net "M_E_CPU0_SA_DQS_DN<9>")
	)
	(arc
		(start 325.480426 -247.32361)
		(mid 325.351944 -247.409713)
		(end 325.200264 -247.439942)
		(width 0.09525)
		(layer "In6.Cu")
		(net "M_E_CPU0_SA_DQS_DN<9>")
	)
	(arc
		(start 329.359768 -247.239282)
		(mid 329.175993 -247.290054)
		(end 328.99096 -247.244108)
		(width 0.09525)
		(layer "In6.Cu")
		(net "M_E_CPU0_SA_DQS_DN<9>")
	)
	(arc
		(start 330.24191 -247.266206)
		(mid 330.079259 -247.288466)
		(end 329.922632 -247.239282)
		(width 0.09525)
		(layer "In6.Cu")
		(net "M_E_CPU0_SA_DQS_DN<9>")
	)
	(arc
		(start 328.042524 -247.239282)
		(mid 327.767235 -247.163561)
		(end 327.490328 -247.233186)
		(width 0.09525)
		(layer "In6.Cu")
		(net "M_E_CPU0_SA_DQS_DN<9>")
	)
	(segment
		(start 330.577952 -242.320064)
		(end 330.1111 -242.054126)
		(width 0.12954)
		(layer "F.Cu")
		(net "M_E_CPU0_SA_DQS_DN<8>")
	)
	(segment
		(start 323.978778 -241.341402)
		(end 323.919596 -241.28222)
		(width 0.09525)
		(layer "In6.Cu")
		(net "M_E_CPU0_SA_DQS_DN<8>")
	)
	(segment
		(start 324.370954 -241.639852)
		(end 324.370954 -241.544348)
		(width 0.09525)
		(layer "In6.Cu")
		(net "M_E_CPU0_SA_DQS_DN<8>")
	)
	(segment
		(start 317.479934 -241.28222)
		(end 311.644284 -235.44657)
		(width 0.16002)
		(layer "In6.Cu")
		(net "M_E_CPU0_SA_DQS_DN<8>")
	)
	(segment
		(start 301.542704 -230.05796)
		(end 301.062644 -230.05796)
		(width 0.16002)
		(layer "In6.Cu")
		(net "M_E_CPU0_SA_DQS_DN<8>")
	)
	(segment
		(start 301.062644 -230.05796)
		(end 300.945804 -229.94112)
		(width 0.16002)
		(layer "In6.Cu")
		(net "M_E_CPU0_SA_DQS_DN<8>")
	)
	(segment
		(start 324.370954 -241.544348)
		(end 324.168008 -241.341402)
		(width 0.09525)
		(layer "In6.Cu")
		(net "M_E_CPU0_SA_DQS_DN<8>")
	)
	(segment
		(start 280.165556 -230.908098)
		(end 279.37333 -230.57993)
		(width 0.16002)
		(layer "In6.Cu")
		(net "M_E_CPU0_SA_DQS_DN<8>")
	)
	(segment
		(start 323.895974 -241.28222)
		(end 317.479934 -241.28222)
		(width 0.16002)
		(layer "In6.Cu")
		(net "M_E_CPU0_SA_DQS_DN<8>")
	)
	(segment
		(start 323.919596 -241.28222)
		(end 323.895974 -241.28222)
		(width 0.09525)
		(layer "In6.Cu")
		(net "M_E_CPU0_SA_DQS_DN<8>")
	)
	(segment
		(start 327.103232 -242.379246)
		(end 327.092818 -242.37315)
		(width 0.09525)
		(layer "In6.Cu")
		(net "M_E_CPU0_SA_DQS_DN<8>")
	)
	(segment
		(start 280.89733 -230.908098)
		(end 280.165556 -230.908098)
		(width 0.16002)
		(layer "In6.Cu")
		(net "M_E_CPU0_SA_DQS_DN<8>")
	)
	(segment
		(start 276.751288 -230.074724)
		(end 275.914866 -229.728268)
		(width 0.16002)
		(layer "In6.Cu")
		(net "M_E_CPU0_SA_DQS_DN<8>")
	)
	(segment
		(start 286.362394 -230.05796)
		(end 284.002226 -230.05796)
		(width 0.16002)
		(layer "In6.Cu")
		(net "M_E_CPU0_SA_DQS_DN<8>")
	)
	(segment
		(start 289.72764 -230.573072)
		(end 289.25012 -230.573072)
		(width 0.16002)
		(layer "In6.Cu")
		(net "M_E_CPU0_SA_DQS_DN<8>")
	)
	(segment
		(start 288.915094 -230.908098)
		(end 287.212532 -230.908098)
		(width 0.16002)
		(layer "In6.Cu")
		(net "M_E_CPU0_SA_DQS_DN<8>")
	)
	(segment
		(start 330.1111 -242.054126)
		(end 330.265024 -242.319556)
		(width 0.09525)
		(layer "In6.Cu")
		(net "M_E_CPU0_SA_DQS_DN<8>")
	)
	(segment
		(start 284.002226 -230.05796)
		(end 283.633164 -229.688898)
		(width 0.16002)
		(layer "In6.Cu")
		(net "M_E_CPU0_SA_DQS_DN<8>")
	)
	(segment
		(start 330.265024 -242.319556)
		(end 330.24191 -242.40617)
		(width 0.09525)
		(layer "In6.Cu")
		(net "M_E_CPU0_SA_DQS_DN<8>")
	)
	(segment
		(start 297.271694 -230.573072)
		(end 296.794174 -230.573072)
		(width 0.16002)
		(layer "In6.Cu")
		(net "M_E_CPU0_SA_DQS_DN<8>")
	)
	(segment
		(start 306.925726 -230.349552)
		(end 306.265072 -229.688898)
		(width 0.16002)
		(layer "In6.Cu")
		(net "M_E_CPU0_SA_DQS_DN<8>")
	)
	(segment
		(start 300.465744 -229.94112)
		(end 300.348904 -230.05796)
		(width 0.16002)
		(layer "In6.Cu")
		(net "M_E_CPU0_SA_DQS_DN<8>")
	)
	(segment
		(start 311.644284 -235.44657)
		(end 310.618632 -232.971086)
		(width 0.16002)
		(layer "In6.Cu")
		(net "M_E_CPU0_SA_DQS_DN<8>")
	)
	(segment
		(start 275.914866 -229.728268)
		(end 275.44395 -229.728268)
		(width 0.16002)
		(layer "In6.Cu")
		(net "M_E_CPU0_SA_DQS_DN<8>")
	)
	(segment
		(start 299.09008 -230.05796)
		(end 298.721018 -229.688898)
		(width 0.16002)
		(layer "In6.Cu")
		(net "M_E_CPU0_SA_DQS_DN<8>")
	)
	(segment
		(start 324.685152 -241.95405)
		(end 324.370954 -241.639852)
		(width 0.09525)
		(layer "In6.Cu")
		(net "M_E_CPU0_SA_DQS_DN<8>")
	)
	(segment
		(start 296.459148 -230.908098)
		(end 294.848788 -230.908098)
		(width 0.16002)
		(layer "In6.Cu")
		(net "M_E_CPU0_SA_DQS_DN<8>")
	)
	(segment
		(start 302.057816 -230.573072)
		(end 301.542704 -230.05796)
		(width 0.16002)
		(layer "In6.Cu")
		(net "M_E_CPU0_SA_DQS_DN<8>")
	)
	(segment
		(start 325.423022 -241.95405)
		(end 324.685152 -241.95405)
		(width 0.09525)
		(layer "In6.Cu")
		(net "M_E_CPU0_SA_DQS_DN<8>")
	)
	(segment
		(start 291.546026 -230.05796)
		(end 291.176964 -229.688898)
		(width 0.16002)
		(layer "In6.Cu")
		(net "M_E_CPU0_SA_DQS_DN<8>")
	)
	(segment
		(start 275.44395 -229.728268)
		(end 275.007324 -229.909116)
		(width 0.16002)
		(layer "In6.Cu")
		(net "M_E_CPU0_SA_DQS_DN<8>")
	)
	(segment
		(start 287.212532 -230.908098)
		(end 286.362394 -230.05796)
		(width 0.16002)
		(layer "In6.Cu")
		(net "M_E_CPU0_SA_DQS_DN<8>")
	)
	(segment
		(start 279.37333 -230.57993)
		(end 279.14473 -230.35133)
		(width 0.16002)
		(layer "In6.Cu")
		(net "M_E_CPU0_SA_DQS_DN<8>")
	)
	(segment
		(start 278.477472 -230.074724)
		(end 276.751288 -230.074724)
		(width 0.16002)
		(layer "In6.Cu")
		(net "M_E_CPU0_SA_DQS_DN<8>")
	)
	(segment
		(start 305.699922 -229.688898)
		(end 304.815748 -230.573072)
		(width 0.16002)
		(layer "In6.Cu")
		(net "M_E_CPU0_SA_DQS_DN<8>")
	)
	(segment
		(start 300.945804 -229.94112)
		(end 300.465744 -229.94112)
		(width 0.16002)
		(layer "In6.Cu")
		(net "M_E_CPU0_SA_DQS_DN<8>")
	)
	(segment
		(start 298.155868 -229.688898)
		(end 297.271694 -230.573072)
		(width 0.16002)
		(layer "In6.Cu")
		(net "M_E_CPU0_SA_DQS_DN<8>")
	)
	(segment
		(start 325.772526 -242.303554)
		(end 325.423022 -241.95405)
		(width 0.09525)
		(layer "In6.Cu")
		(net "M_E_CPU0_SA_DQS_DN<8>")
	)
	(segment
		(start 328.99096 -242.384072)
		(end 328.982578 -242.379246)
		(width 0.09525)
		(layer "In6.Cu")
		(net "M_E_CPU0_SA_DQS_DN<8>")
	)
	(segment
		(start 328.419714 -242.379246)
		(end 328.411332 -242.384072)
		(width 0.09525)
		(layer "In6.Cu")
		(net "M_E_CPU0_SA_DQS_DN<8>")
	)
	(segment
		(start 327.490328 -242.37315)
		(end 327.479914 -242.379246)
		(width 0.09525)
		(layer "In6.Cu")
		(net "M_E_CPU0_SA_DQS_DN<8>")
	)
	(segment
		(start 310.618632 -232.971086)
		(end 307.997098 -230.349552)
		(width 0.16002)
		(layer "In6.Cu")
		(net "M_E_CPU0_SA_DQS_DN<8>")
	)
	(segment
		(start 327.479914 -242.379246)
		(end 327.471532 -242.384072)
		(width 0.09525)
		(layer "In6.Cu")
		(net "M_E_CPU0_SA_DQS_DN<8>")
	)
	(segment
		(start 294.848788 -230.908098)
		(end 293.99865 -230.05796)
		(width 0.16002)
		(layer "In6.Cu")
		(net "M_E_CPU0_SA_DQS_DN<8>")
	)
	(segment
		(start 273.36623 -229.909116)
		(end 273.092164 -229.63505)
		(width 0.16002)
		(layer "In6.Cu")
		(net "M_E_CPU0_SA_DQS_DN<8>")
	)
	(segment
		(start 324.168008 -241.341402)
		(end 323.978778 -241.341402)
		(width 0.09525)
		(layer "In6.Cu")
		(net "M_E_CPU0_SA_DQS_DN<8>")
	)
	(segment
		(start 300.348904 -230.05796)
		(end 299.09008 -230.05796)
		(width 0.16002)
		(layer "In6.Cu")
		(net "M_E_CPU0_SA_DQS_DN<8>")
	)
	(segment
		(start 290.611814 -229.688898)
		(end 289.72764 -230.573072)
		(width 0.16002)
		(layer "In6.Cu")
		(net "M_E_CPU0_SA_DQS_DN<8>")
	)
	(segment
		(start 296.794174 -230.573072)
		(end 296.459148 -230.908098)
		(width 0.16002)
		(layer "In6.Cu")
		(net "M_E_CPU0_SA_DQS_DN<8>")
	)
	(segment
		(start 281.70632 -230.573072)
		(end 280.89733 -230.908098)
		(width 0.16002)
		(layer "In6.Cu")
		(net "M_E_CPU0_SA_DQS_DN<8>")
	)
	(segment
		(start 326.177402 -242.387628)
		(end 326.162924 -242.379246)
		(width 0.09525)
		(layer "In6.Cu")
		(net "M_E_CPU0_SA_DQS_DN<8>")
	)
	(segment
		(start 306.265072 -229.688898)
		(end 305.699922 -229.688898)
		(width 0.16002)
		(layer "In6.Cu")
		(net "M_E_CPU0_SA_DQS_DN<8>")
	)
	(segment
		(start 325.881746 -242.303554)
		(end 325.772526 -242.303554)
		(width 0.09525)
		(layer "In6.Cu")
		(net "M_E_CPU0_SA_DQS_DN<8>")
	)
	(segment
		(start 283.633164 -229.688898)
		(end 283.068014 -229.688898)
		(width 0.16002)
		(layer "In6.Cu")
		(net "M_E_CPU0_SA_DQS_DN<8>")
	)
	(segment
		(start 275.007324 -229.909116)
		(end 273.36623 -229.909116)
		(width 0.16002)
		(layer "In6.Cu")
		(net "M_E_CPU0_SA_DQS_DN<8>")
	)
	(segment
		(start 298.721018 -229.688898)
		(end 298.155868 -229.688898)
		(width 0.16002)
		(layer "In6.Cu")
		(net "M_E_CPU0_SA_DQS_DN<8>")
	)
	(segment
		(start 279.14473 -230.35133)
		(end 278.477472 -230.074724)
		(width 0.16002)
		(layer "In6.Cu")
		(net "M_E_CPU0_SA_DQS_DN<8>")
	)
	(segment
		(start 304.815748 -230.573072)
		(end 302.057816 -230.573072)
		(width 0.16002)
		(layer "In6.Cu")
		(net "M_E_CPU0_SA_DQS_DN<8>")
	)
	(segment
		(start 291.176964 -229.688898)
		(end 290.611814 -229.688898)
		(width 0.16002)
		(layer "In6.Cu")
		(net "M_E_CPU0_SA_DQS_DN<8>")
	)
	(segment
		(start 283.068014 -229.688898)
		(end 282.18384 -230.573072)
		(width 0.16002)
		(layer "In6.Cu")
		(net "M_E_CPU0_SA_DQS_DN<8>")
	)
	(segment
		(start 307.997098 -230.349552)
		(end 306.925726 -230.349552)
		(width 0.16002)
		(layer "In6.Cu")
		(net "M_E_CPU0_SA_DQS_DN<8>")
	)
	(segment
		(start 289.25012 -230.573072)
		(end 288.915094 -230.908098)
		(width 0.16002)
		(layer "In6.Cu")
		(net "M_E_CPU0_SA_DQS_DN<8>")
	)
	(segment
		(start 282.18384 -230.573072)
		(end 281.70632 -230.573072)
		(width 0.16002)
		(layer "In6.Cu")
		(net "M_E_CPU0_SA_DQS_DN<8>")
	)
	(segment
		(start 293.99865 -230.05796)
		(end 291.546026 -230.05796)
		(width 0.16002)
		(layer "In6.Cu")
		(net "M_E_CPU0_SA_DQS_DN<8>")
	)
	(arc
		(start 329.922632 -242.379246)
		(mid 329.6412 -242.303491)
		(end 329.359768 -242.379246)
		(width 0.09525)
		(layer "In6.Cu")
		(net "M_E_CPU0_SA_DQS_DN<8>")
	)
	(arc
		(start 328.411332 -242.384072)
		(mid 328.2263 -242.429986)
		(end 328.042524 -242.379246)
		(width 0.09525)
		(layer "In6.Cu")
		(net "M_E_CPU0_SA_DQS_DN<8>")
	)
	(arc
		(start 329.359768 -242.379246)
		(mid 329.175993 -242.430018)
		(end 328.99096 -242.384072)
		(width 0.09525)
		(layer "In6.Cu")
		(net "M_E_CPU0_SA_DQS_DN<8>")
	)
	(arc
		(start 326.162924 -242.379246)
		(mid 326.027332 -242.322855)
		(end 325.881746 -242.303554)
		(width 0.09525)
		(layer "In6.Cu")
		(net "M_E_CPU0_SA_DQS_DN<8>")
	)
	(arc
		(start 326.540114 -242.379246)
		(mid 326.359835 -242.430077)
		(end 326.177402 -242.387628)
		(width 0.09525)
		(layer "In6.Cu")
		(net "M_E_CPU0_SA_DQS_DN<8>")
	)
	(arc
		(start 330.24191 -242.40617)
		(mid 330.079259 -242.42843)
		(end 329.922632 -242.379246)
		(width 0.09525)
		(layer "In6.Cu")
		(net "M_E_CPU0_SA_DQS_DN<8>")
	)
	(arc
		(start 327.471532 -242.384072)
		(mid 327.286754 -242.429865)
		(end 327.103232 -242.379246)
		(width 0.09525)
		(layer "In6.Cu")
		(net "M_E_CPU0_SA_DQS_DN<8>")
	)
	(arc
		(start 327.092818 -242.37315)
		(mid 326.815656 -242.30335)
		(end 326.540114 -242.379246)
		(width 0.09525)
		(layer "In6.Cu")
		(net "M_E_CPU0_SA_DQS_DN<8>")
	)
	(arc
		(start 328.042524 -242.379246)
		(mid 327.767235 -242.303525)
		(end 327.490328 -242.37315)
		(width 0.09525)
		(layer "In6.Cu")
		(net "M_E_CPU0_SA_DQS_DN<8>")
	)
	(arc
		(start 328.982578 -242.379246)
		(mid 328.701146 -242.303491)
		(end 328.419714 -242.379246)
		(width 0.09525)
		(layer "In6.Cu")
		(net "M_E_CPU0_SA_DQS_DN<8>")
	)
	(segment
		(start 330.577952 -237.460028)
		(end 330.1111 -237.19409)
		(width 0.12954)
		(layer "F.Cu")
		(net "M_E_CPU0_SA_DQS_DN<7>")
	)
	(segment
		(start 323.978778 -235.672884)
		(end 323.919596 -235.613702)
		(width 0.09525)
		(layer "In6.Cu")
		(net "M_E_CPU0_SA_DQS_DN<7>")
	)
	(segment
		(start 275.314918 -220.39326)
		(end 275.14931 -220.558868)
		(width 0.16002)
		(layer "In6.Cu")
		(net "M_E_CPU0_SA_DQS_DN<7>")
	)
	(segment
		(start 302.051466 -221.238318)
		(end 301.521114 -220.707966)
		(width 0.16002)
		(layer "In6.Cu")
		(net "M_E_CPU0_SA_DQS_DN<7>")
	)
	(segment
		(start 306.258722 -220.354144)
		(end 305.706272 -220.354144)
		(width 0.16002)
		(layer "In6.Cu")
		(net "M_E_CPU0_SA_DQS_DN<7>")
	)
	(segment
		(start 291.170614 -220.35389)
		(end 290.618164 -220.35389)
		(width 0.16002)
		(layer "In6.Cu")
		(net "M_E_CPU0_SA_DQS_DN<7>")
	)
	(segment
		(start 290.618164 -220.35389)
		(end 289.73399 -221.238064)
		(width 0.16002)
		(layer "In6.Cu")
		(net "M_E_CPU0_SA_DQS_DN<7>")
	)
	(segment
		(start 292.025578 -220.707966)
		(end 291.170614 -220.35389)
		(width 0.16002)
		(layer "In6.Cu")
		(net "M_E_CPU0_SA_DQS_DN<7>")
	)
	(segment
		(start 324.586854 -236.08411)
		(end 324.175628 -235.672884)
		(width 0.09525)
		(layer "In6.Cu")
		(net "M_E_CPU0_SA_DQS_DN<7>")
	)
	(segment
		(start 281.71267 -221.238064)
		(end 280.94051 -221.55785)
		(width 0.16002)
		(layer "In6.Cu")
		(net "M_E_CPU0_SA_DQS_DN<7>")
	)
	(segment
		(start 296.028364 -221.55785)
		(end 294.827198 -221.55785)
		(width 0.16002)
		(layer "In6.Cu")
		(net "M_E_CPU0_SA_DQS_DN<7>")
	)
	(segment
		(start 278.332946 -220.739716)
		(end 276.471888 -220.739716)
		(width 0.16002)
		(layer "In6.Cu")
		(net "M_E_CPU0_SA_DQS_DN<7>")
	)
	(segment
		(start 287.190942 -221.55785)
		(end 286.341058 -220.707966)
		(width 0.16002)
		(layer "In6.Cu")
		(net "M_E_CPU0_SA_DQS_DN<7>")
	)
	(segment
		(start 289.73399 -221.238064)
		(end 289.183318 -221.238064)
		(width 0.16002)
		(layer "In6.Cu")
		(net "M_E_CPU0_SA_DQS_DN<7>")
	)
	(segment
		(start 273.365976 -220.558868)
		(end 273.092164 -220.285056)
		(width 0.16002)
		(layer "In6.Cu")
		(net "M_E_CPU0_SA_DQS_DN<7>")
	)
	(segment
		(start 324.175628 -235.672884)
		(end 323.978778 -235.672884)
		(width 0.09525)
		(layer "In6.Cu")
		(net "M_E_CPU0_SA_DQS_DN<7>")
	)
	(segment
		(start 327.103232 -237.51921)
		(end 327.102724 -237.51921)
		(width 0.09525)
		(layer "In6.Cu")
		(net "M_E_CPU0_SA_DQS_DN<7>")
	)
	(segment
		(start 330.1111 -237.19409)
		(end 330.265024 -237.45952)
		(width 0.09525)
		(layer "In6.Cu")
		(net "M_E_CPU0_SA_DQS_DN<7>")
	)
	(segment
		(start 312.955178 -226.215956)
		(end 310.600598 -223.861376)
		(width 0.16002)
		(layer "In6.Cu")
		(net "M_E_CPU0_SA_DQS_DN<7>")
	)
	(segment
		(start 284.416754 -220.707966)
		(end 283.56179 -220.35389)
		(width 0.16002)
		(layer "In6.Cu")
		(net "M_E_CPU0_SA_DQS_DN<7>")
	)
	(segment
		(start 280.30805 -221.55785)
		(end 278.332946 -220.739716)
		(width 0.16002)
		(layer "In6.Cu")
		(net "M_E_CPU0_SA_DQS_DN<7>")
	)
	(segment
		(start 325.348854 -236.657896)
		(end 325.348854 -236.431582)
		(width 0.09525)
		(layer "In6.Cu")
		(net "M_E_CPU0_SA_DQS_DN<7>")
	)
	(segment
		(start 293.977314 -220.707966)
		(end 292.025578 -220.707966)
		(width 0.16002)
		(layer "In6.Cu")
		(net "M_E_CPU0_SA_DQS_DN<7>")
	)
	(segment
		(start 283.074364 -220.35389)
		(end 282.19019 -221.238064)
		(width 0.16002)
		(layer "In6.Cu")
		(net "M_E_CPU0_SA_DQS_DN<7>")
	)
	(segment
		(start 276.125432 -220.39326)
		(end 275.314918 -220.39326)
		(width 0.16002)
		(layer "In6.Cu")
		(net "M_E_CPU0_SA_DQS_DN<7>")
	)
	(segment
		(start 306.959508 -221.05493)
		(end 306.258722 -220.354144)
		(width 0.16002)
		(layer "In6.Cu")
		(net "M_E_CPU0_SA_DQS_DN<7>")
	)
	(segment
		(start 310.600598 -222.279972)
		(end 309.375556 -221.05493)
		(width 0.16002)
		(layer "In6.Cu")
		(net "M_E_CPU0_SA_DQS_DN<7>")
	)
	(segment
		(start 309.375556 -221.05493)
		(end 306.959508 -221.05493)
		(width 0.16002)
		(layer "In6.Cu")
		(net "M_E_CPU0_SA_DQS_DN<7>")
	)
	(segment
		(start 299.068744 -220.707966)
		(end 298.714668 -220.35389)
		(width 0.16002)
		(layer "In6.Cu")
		(net "M_E_CPU0_SA_DQS_DN<7>")
	)
	(segment
		(start 327.479914 -237.51921)
		(end 327.471532 -237.524036)
		(width 0.09525)
		(layer "In6.Cu")
		(net "M_E_CPU0_SA_DQS_DN<7>")
	)
	(segment
		(start 298.162218 -220.35389)
		(end 297.278044 -221.238064)
		(width 0.16002)
		(layer "In6.Cu")
		(net "M_E_CPU0_SA_DQS_DN<7>")
	)
	(segment
		(start 323.895974 -235.613702)
		(end 321.323716 -235.613702)
		(width 0.16002)
		(layer "In6.Cu")
		(net "M_E_CPU0_SA_DQS_DN<7>")
	)
	(segment
		(start 327.490328 -237.513114)
		(end 327.479914 -237.51921)
		(width 0.09525)
		(layer "In6.Cu")
		(net "M_E_CPU0_SA_DQS_DN<7>")
	)
	(segment
		(start 330.265024 -237.45952)
		(end 330.24191 -237.546134)
		(width 0.09525)
		(layer "In6.Cu")
		(net "M_E_CPU0_SA_DQS_DN<7>")
	)
	(segment
		(start 321.323716 -235.613702)
		(end 312.955178 -227.245164)
		(width 0.16002)
		(layer "In6.Cu")
		(net "M_E_CPU0_SA_DQS_DN<7>")
	)
	(segment
		(start 289.183318 -221.238064)
		(end 288.411158 -221.55785)
		(width 0.16002)
		(layer "In6.Cu")
		(net "M_E_CPU0_SA_DQS_DN<7>")
	)
	(segment
		(start 325.348854 -236.431582)
		(end 325.001382 -236.08411)
		(width 0.09525)
		(layer "In6.Cu")
		(net "M_E_CPU0_SA_DQS_DN<7>")
	)
	(segment
		(start 282.19019 -221.238064)
		(end 281.71267 -221.238064)
		(width 0.16002)
		(layer "In6.Cu")
		(net "M_E_CPU0_SA_DQS_DN<7>")
	)
	(segment
		(start 288.411158 -221.55785)
		(end 287.190942 -221.55785)
		(width 0.16002)
		(layer "In6.Cu")
		(net "M_E_CPU0_SA_DQS_DN<7>")
	)
	(segment
		(start 326.142604 -237.501938)
		(end 325.384414 -236.743748)
		(width 0.09525)
		(layer "In6.Cu")
		(net "M_E_CPU0_SA_DQS_DN<7>")
	)
	(segment
		(start 296.800524 -221.238064)
		(end 296.028364 -221.55785)
		(width 0.16002)
		(layer "In6.Cu")
		(net "M_E_CPU0_SA_DQS_DN<7>")
	)
	(segment
		(start 298.714668 -220.35389)
		(end 298.162218 -220.35389)
		(width 0.16002)
		(layer "In6.Cu")
		(net "M_E_CPU0_SA_DQS_DN<7>")
	)
	(segment
		(start 274.518628 -220.442028)
		(end 274.038568 -220.442028)
		(width 0.16002)
		(layer "In6.Cu")
		(net "M_E_CPU0_SA_DQS_DN<7>")
	)
	(segment
		(start 273.921728 -220.558868)
		(end 273.365976 -220.558868)
		(width 0.16002)
		(layer "In6.Cu")
		(net "M_E_CPU0_SA_DQS_DN<7>")
	)
	(segment
		(start 297.278044 -221.238064)
		(end 296.800524 -221.238064)
		(width 0.16002)
		(layer "In6.Cu")
		(net "M_E_CPU0_SA_DQS_DN<7>")
	)
	(segment
		(start 301.521114 -220.707966)
		(end 299.068744 -220.707966)
		(width 0.16002)
		(layer "In6.Cu")
		(net "M_E_CPU0_SA_DQS_DN<7>")
	)
	(segment
		(start 327.102724 -237.51921)
		(end 327.087738 -237.511082)
		(width 0.09525)
		(layer "In6.Cu")
		(net "M_E_CPU0_SA_DQS_DN<7>")
	)
	(segment
		(start 294.827198 -221.55785)
		(end 293.977314 -220.707966)
		(width 0.16002)
		(layer "In6.Cu")
		(net "M_E_CPU0_SA_DQS_DN<7>")
	)
	(segment
		(start 312.955178 -227.245164)
		(end 312.955178 -226.215956)
		(width 0.16002)
		(layer "In6.Cu")
		(net "M_E_CPU0_SA_DQS_DN<7>")
	)
	(segment
		(start 280.94051 -221.55785)
		(end 280.30805 -221.55785)
		(width 0.16002)
		(layer "In6.Cu")
		(net "M_E_CPU0_SA_DQS_DN<7>")
	)
	(segment
		(start 304.822098 -221.238318)
		(end 302.051466 -221.238318)
		(width 0.16002)
		(layer "In6.Cu")
		(net "M_E_CPU0_SA_DQS_DN<7>")
	)
	(segment
		(start 323.919596 -235.613702)
		(end 323.895974 -235.613702)
		(width 0.09525)
		(layer "In6.Cu")
		(net "M_E_CPU0_SA_DQS_DN<7>")
	)
	(segment
		(start 305.706272 -220.354144)
		(end 304.822098 -221.238318)
		(width 0.16002)
		(layer "In6.Cu")
		(net "M_E_CPU0_SA_DQS_DN<7>")
	)
	(segment
		(start 328.99096 -237.524036)
		(end 328.982578 -237.51921)
		(width 0.09525)
		(layer "In6.Cu")
		(net "M_E_CPU0_SA_DQS_DN<7>")
	)
	(segment
		(start 283.56179 -220.35389)
		(end 283.074364 -220.35389)
		(width 0.16002)
		(layer "In6.Cu")
		(net "M_E_CPU0_SA_DQS_DN<7>")
	)
	(segment
		(start 328.419714 -237.51921)
		(end 328.411332 -237.524036)
		(width 0.09525)
		(layer "In6.Cu")
		(net "M_E_CPU0_SA_DQS_DN<7>")
	)
	(segment
		(start 276.471888 -220.739716)
		(end 276.125432 -220.39326)
		(width 0.16002)
		(layer "In6.Cu")
		(net "M_E_CPU0_SA_DQS_DN<7>")
	)
	(segment
		(start 286.341058 -220.707966)
		(end 284.416754 -220.707966)
		(width 0.16002)
		(layer "In6.Cu")
		(net "M_E_CPU0_SA_DQS_DN<7>")
	)
	(segment
		(start 274.635468 -220.558868)
		(end 274.518628 -220.442028)
		(width 0.16002)
		(layer "In6.Cu")
		(net "M_E_CPU0_SA_DQS_DN<7>")
	)
	(segment
		(start 275.14931 -220.558868)
		(end 274.635468 -220.558868)
		(width 0.16002)
		(layer "In6.Cu")
		(net "M_E_CPU0_SA_DQS_DN<7>")
	)
	(segment
		(start 325.001382 -236.08411)
		(end 324.586854 -236.08411)
		(width 0.09525)
		(layer "In6.Cu")
		(net "M_E_CPU0_SA_DQS_DN<7>")
	)
	(segment
		(start 274.038568 -220.442028)
		(end 273.921728 -220.558868)
		(width 0.16002)
		(layer "In6.Cu")
		(net "M_E_CPU0_SA_DQS_DN<7>")
	)
	(segment
		(start 310.600598 -223.861376)
		(end 310.600598 -222.279972)
		(width 0.16002)
		(layer "In6.Cu")
		(net "M_E_CPU0_SA_DQS_DN<7>")
	)
	(arc
		(start 329.359768 -237.51921)
		(mid 329.175993 -237.569982)
		(end 328.99096 -237.524036)
		(width 0.09525)
		(layer "In6.Cu")
		(net "M_E_CPU0_SA_DQS_DN<7>")
	)
	(arc
		(start 330.24191 -237.546134)
		(mid 330.079259 -237.568394)
		(end 329.922632 -237.51921)
		(width 0.09525)
		(layer "In6.Cu")
		(net "M_E_CPU0_SA_DQS_DN<7>")
	)
	(arc
		(start 329.922632 -237.51921)
		(mid 329.6412 -237.443455)
		(end 329.359768 -237.51921)
		(width 0.09525)
		(layer "In6.Cu")
		(net "M_E_CPU0_SA_DQS_DN<7>")
	)
	(arc
		(start 328.042524 -237.51921)
		(mid 327.767235 -237.443489)
		(end 327.490328 -237.513114)
		(width 0.09525)
		(layer "In6.Cu")
		(net "M_E_CPU0_SA_DQS_DN<7>")
	)
	(arc
		(start 328.982578 -237.51921)
		(mid 328.701146 -237.443455)
		(end 328.419714 -237.51921)
		(width 0.09525)
		(layer "In6.Cu")
		(net "M_E_CPU0_SA_DQS_DN<7>")
	)
	(arc
		(start 327.087738 -237.511082)
		(mid 326.812961 -237.443875)
		(end 326.540368 -237.519464)
		(width 0.09525)
		(layer "In6.Cu")
		(net "M_E_CPU0_SA_DQS_DN<7>")
	)
	(arc
		(start 326.540368 -237.519464)
		(mid 326.385531 -237.56992)
		(end 326.22363 -237.55223)
		(width 0.09525)
		(layer "In6.Cu")
		(net "M_E_CPU0_SA_DQS_DN<7>")
	)
	(arc
		(start 327.471532 -237.524036)
		(mid 327.286754 -237.569829)
		(end 327.103232 -237.51921)
		(width 0.09525)
		(layer "In6.Cu")
		(net "M_E_CPU0_SA_DQS_DN<7>")
	)
	(arc
		(start 325.384414 -236.743748)
		(mid 325.358041 -236.704373)
		(end 325.348854 -236.657896)
		(width 0.09525)
		(layer "In6.Cu")
		(net "M_E_CPU0_SA_DQS_DN<7>")
	)
	(arc
		(start 328.411332 -237.524036)
		(mid 328.2263 -237.56995)
		(end 328.042524 -237.51921)
		(width 0.09525)
		(layer "In6.Cu")
		(net "M_E_CPU0_SA_DQS_DN<7>")
	)
	(arc
		(start 326.22363 -237.55223)
		(mid 326.180187 -237.531806)
		(end 326.142604 -237.501938)
		(width 0.09525)
		(layer "In6.Cu")
		(net "M_E_CPU0_SA_DQS_DN<7>")
	)
	(segment
		(start 330.577952 -232.599992)
		(end 330.1111 -232.334054)
		(width 0.12954)
		(layer "F.Cu")
		(net "M_E_CPU0_SA_DQS_DN<6>")
	)
	(segment
		(start 278.868378 -211.374482)
		(end 276.478238 -211.374482)
		(width 0.16002)
		(layer "In6.Cu")
		(net "M_E_CPU0_SA_DQS_DN<6>")
	)
	(segment
		(start 298.155868 -210.988656)
		(end 297.271694 -211.87283)
		(width 0.16002)
		(layer "In6.Cu")
		(net "M_E_CPU0_SA_DQS_DN<6>")
	)
	(segment
		(start 291.176964 -210.988656)
		(end 290.611814 -210.988656)
		(width 0.16002)
		(layer "In6.Cu")
		(net "M_E_CPU0_SA_DQS_DN<6>")
	)
	(segment
		(start 306.374038 -212.447632)
		(end 305.795934 -212.447632)
		(width 0.16002)
		(layer "In6.Cu")
		(net "M_E_CPU0_SA_DQS_DN<6>")
	)
	(segment
		(start 323.878956 -230.175562)
		(end 323.718936 -230.015542)
		(width 0.09525)
		(layer "In6.Cu")
		(net "M_E_CPU0_SA_DQS_DN<6>")
	)
	(segment
		(start 295.985184 -212.207856)
		(end 294.848788 -212.207856)
		(width 0.16002)
		(layer "In6.Cu")
		(net "M_E_CPU0_SA_DQS_DN<6>")
	)
	(segment
		(start 274.88642 -211.208874)
		(end 273.365976 -211.208874)
		(width 0.16002)
		(layer "In6.Cu")
		(net "M_E_CPU0_SA_DQS_DN<6>")
	)
	(segment
		(start 276.131782 -211.028026)
		(end 275.323046 -211.028026)
		(width 0.16002)
		(layer "In6.Cu")
		(net "M_E_CPU0_SA_DQS_DN<6>")
	)
	(segment
		(start 324.023228 -230.175562)
		(end 323.878956 -230.175562)
		(width 0.09525)
		(layer "In6.Cu")
		(net "M_E_CPU0_SA_DQS_DN<6>")
	)
	(segment
		(start 327.103232 -232.659174)
		(end 327.092818 -232.653078)
		(width 0.09525)
		(layer "In6.Cu")
		(net "M_E_CPU0_SA_DQS_DN<6>")
	)
	(segment
		(start 283.068014 -210.988656)
		(end 282.52166 -211.53501)
		(width 0.16002)
		(layer "In6.Cu")
		(net "M_E_CPU0_SA_DQS_DN<6>")
	)
	(segment
		(start 280.897584 -212.207856)
		(end 279.701752 -212.207856)
		(width 0.16002)
		(layer "In6.Cu")
		(net "M_E_CPU0_SA_DQS_DN<6>")
	)
	(segment
		(start 291.54628 -211.357972)
		(end 291.176964 -210.988656)
		(width 0.16002)
		(layer "In6.Cu")
		(net "M_E_CPU0_SA_DQS_DN<6>")
	)
	(segment
		(start 290.611814 -210.988656)
		(end 289.72764 -211.87283)
		(width 0.16002)
		(layer "In6.Cu")
		(net "M_E_CPU0_SA_DQS_DN<6>")
	)
	(segment
		(start 312.586116 -214.398352)
		(end 310.215534 -214.398352)
		(width 0.16002)
		(layer "In6.Cu")
		(net "M_E_CPU0_SA_DQS_DN<6>")
	)
	(segment
		(start 324.872858 -231.025192)
		(end 324.023228 -230.175562)
		(width 0.09525)
		(layer "In6.Cu")
		(net "M_E_CPU0_SA_DQS_DN<6>")
	)
	(segment
		(start 282.52166 -211.53501)
		(end 280.897584 -212.207856)
		(width 0.16002)
		(layer "In6.Cu")
		(net "M_E_CPU0_SA_DQS_DN<6>")
	)
	(segment
		(start 299.090334 -211.357972)
		(end 298.721018 -210.988656)
		(width 0.16002)
		(layer "In6.Cu")
		(net "M_E_CPU0_SA_DQS_DN<6>")
	)
	(segment
		(start 301.542704 -211.357972)
		(end 299.090334 -211.357972)
		(width 0.16002)
		(layer "In6.Cu")
		(net "M_E_CPU0_SA_DQS_DN<6>")
	)
	(segment
		(start 286.362648 -211.357972)
		(end 284.00248 -211.357972)
		(width 0.16002)
		(layer "In6.Cu")
		(net "M_E_CPU0_SA_DQS_DN<6>")
	)
	(segment
		(start 275.323046 -211.028026)
		(end 274.88642 -211.208874)
		(width 0.16002)
		(layer "In6.Cu")
		(net "M_E_CPU0_SA_DQS_DN<6>")
	)
	(segment
		(start 298.721018 -210.988656)
		(end 298.155868 -210.988656)
		(width 0.16002)
		(layer "In6.Cu")
		(net "M_E_CPU0_SA_DQS_DN<6>")
	)
	(segment
		(start 293.998904 -211.357972)
		(end 291.54628 -211.357972)
		(width 0.16002)
		(layer "In6.Cu")
		(net "M_E_CPU0_SA_DQS_DN<6>")
	)
	(segment
		(start 323.718936 -230.015542)
		(end 323.718936 -229.97033)
		(width 0.09525)
		(layer "In6.Cu")
		(net "M_E_CPU0_SA_DQS_DN<6>")
	)
	(segment
		(start 283.633164 -210.988656)
		(end 283.068014 -210.988656)
		(width 0.16002)
		(layer "In6.Cu")
		(net "M_E_CPU0_SA_DQS_DN<6>")
	)
	(segment
		(start 306.671218 -212.150452)
		(end 306.374038 -212.447632)
		(width 0.16002)
		(layer "In6.Cu")
		(net "M_E_CPU0_SA_DQS_DN<6>")
	)
	(segment
		(start 323.702172 -229.953566)
		(end 318.492378 -224.743772)
		(width 0.16002)
		(layer "In6.Cu")
		(net "M_E_CPU0_SA_DQS_DN<6>")
	)
	(segment
		(start 294.848788 -212.207856)
		(end 293.998904 -211.357972)
		(width 0.16002)
		(layer "In6.Cu")
		(net "M_E_CPU0_SA_DQS_DN<6>")
	)
	(segment
		(start 289.25012 -211.87283)
		(end 288.44113 -212.207856)
		(width 0.16002)
		(layer "In6.Cu")
		(net "M_E_CPU0_SA_DQS_DN<6>")
	)
	(segment
		(start 326.095868 -232.601262)
		(end 325.502778 -232.008172)
		(width 0.09525)
		(layer "In6.Cu")
		(net "M_E_CPU0_SA_DQS_DN<6>")
	)
	(segment
		(start 328.99096 -232.664)
		(end 328.982578 -232.659174)
		(width 0.09525)
		(layer "In6.Cu")
		(net "M_E_CPU0_SA_DQS_DN<6>")
	)
	(segment
		(start 310.215534 -214.398352)
		(end 307.967634 -212.150452)
		(width 0.16002)
		(layer "In6.Cu")
		(net "M_E_CPU0_SA_DQS_DN<6>")
	)
	(segment
		(start 288.44113 -212.207856)
		(end 287.212532 -212.207856)
		(width 0.16002)
		(layer "In6.Cu")
		(net "M_E_CPU0_SA_DQS_DN<6>")
	)
	(segment
		(start 284.00248 -211.357972)
		(end 283.633164 -210.988656)
		(width 0.16002)
		(layer "In6.Cu")
		(net "M_E_CPU0_SA_DQS_DN<6>")
	)
	(segment
		(start 323.718936 -229.97033)
		(end 323.702172 -229.953566)
		(width 0.09525)
		(layer "In6.Cu")
		(net "M_E_CPU0_SA_DQS_DN<6>")
	)
	(segment
		(start 316.285118 -218.097354)
		(end 312.586116 -214.398352)
		(width 0.16002)
		(layer "In6.Cu")
		(net "M_E_CPU0_SA_DQS_DN<6>")
	)
	(segment
		(start 297.271694 -211.87283)
		(end 296.794174 -211.87283)
		(width 0.16002)
		(layer "In6.Cu")
		(net "M_E_CPU0_SA_DQS_DN<6>")
	)
	(segment
		(start 273.365976 -211.208874)
		(end 273.092164 -210.935062)
		(width 0.16002)
		(layer "In6.Cu")
		(net "M_E_CPU0_SA_DQS_DN<6>")
	)
	(segment
		(start 305.221386 -211.873084)
		(end 302.057816 -211.873084)
		(width 0.16002)
		(layer "In6.Cu")
		(net "M_E_CPU0_SA_DQS_DN<6>")
	)
	(segment
		(start 289.72764 -211.87283)
		(end 289.25012 -211.87283)
		(width 0.16002)
		(layer "In6.Cu")
		(net "M_E_CPU0_SA_DQS_DN<6>")
	)
	(segment
		(start 305.795934 -212.447632)
		(end 305.221386 -211.873084)
		(width 0.16002)
		(layer "In6.Cu")
		(net "M_E_CPU0_SA_DQS_DN<6>")
	)
	(segment
		(start 327.490328 -232.653078)
		(end 327.479914 -232.659174)
		(width 0.09525)
		(layer "In6.Cu")
		(net "M_E_CPU0_SA_DQS_DN<6>")
	)
	(segment
		(start 307.967634 -212.150452)
		(end 306.671218 -212.150452)
		(width 0.16002)
		(layer "In6.Cu")
		(net "M_E_CPU0_SA_DQS_DN<6>")
	)
	(segment
		(start 316.285118 -221.690184)
		(end 316.285118 -218.097354)
		(width 0.16002)
		(layer "In6.Cu")
		(net "M_E_CPU0_SA_DQS_DN<6>")
	)
	(segment
		(start 287.212532 -212.207856)
		(end 286.362648 -211.357972)
		(width 0.16002)
		(layer "In6.Cu")
		(net "M_E_CPU0_SA_DQS_DN<6>")
	)
	(segment
		(start 302.057816 -211.873084)
		(end 301.542704 -211.357972)
		(width 0.16002)
		(layer "In6.Cu")
		(net "M_E_CPU0_SA_DQS_DN<6>")
	)
	(segment
		(start 325.073518 -231.025192)
		(end 324.872858 -231.025192)
		(width 0.09525)
		(layer "In6.Cu")
		(net "M_E_CPU0_SA_DQS_DN<6>")
	)
	(segment
		(start 318.492378 -223.897444)
		(end 316.285118 -221.690184)
		(width 0.16002)
		(layer "In6.Cu")
		(net "M_E_CPU0_SA_DQS_DN<6>")
	)
	(segment
		(start 318.492378 -224.743772)
		(end 318.492378 -223.897444)
		(width 0.16002)
		(layer "In6.Cu")
		(net "M_E_CPU0_SA_DQS_DN<6>")
	)
	(segment
		(start 325.502778 -232.008172)
		(end 325.502778 -231.454452)
		(width 0.09525)
		(layer "In6.Cu")
		(net "M_E_CPU0_SA_DQS_DN<6>")
	)
	(segment
		(start 328.419714 -232.659174)
		(end 328.411332 -232.664)
		(width 0.09525)
		(layer "In6.Cu")
		(net "M_E_CPU0_SA_DQS_DN<6>")
	)
	(segment
		(start 327.479914 -232.659174)
		(end 327.471532 -232.664)
		(width 0.09525)
		(layer "In6.Cu")
		(net "M_E_CPU0_SA_DQS_DN<6>")
	)
	(segment
		(start 296.794174 -211.87283)
		(end 295.985184 -212.207856)
		(width 0.16002)
		(layer "In6.Cu")
		(net "M_E_CPU0_SA_DQS_DN<6>")
	)
	(segment
		(start 330.1111 -232.334054)
		(end 330.265024 -232.599484)
		(width 0.09525)
		(layer "In6.Cu")
		(net "M_E_CPU0_SA_DQS_DN<6>")
	)
	(segment
		(start 325.502778 -231.454452)
		(end 325.073518 -231.025192)
		(width 0.09525)
		(layer "In6.Cu")
		(net "M_E_CPU0_SA_DQS_DN<6>")
	)
	(segment
		(start 330.265024 -232.599484)
		(end 330.24191 -232.686098)
		(width 0.09525)
		(layer "In6.Cu")
		(net "M_E_CPU0_SA_DQS_DN<6>")
	)
	(segment
		(start 279.701752 -212.207856)
		(end 278.868378 -211.374482)
		(width 0.16002)
		(layer "In6.Cu")
		(net "M_E_CPU0_SA_DQS_DN<6>")
	)
	(segment
		(start 276.478238 -211.374482)
		(end 276.131782 -211.028026)
		(width 0.16002)
		(layer "In6.Cu")
		(net "M_E_CPU0_SA_DQS_DN<6>")
	)
	(arc
		(start 327.471532 -232.664)
		(mid 327.286754 -232.709793)
		(end 327.103232 -232.659174)
		(width 0.09525)
		(layer "In6.Cu")
		(net "M_E_CPU0_SA_DQS_DN<6>")
	)
	(arc
		(start 328.982578 -232.659174)
		(mid 328.701146 -232.583419)
		(end 328.419714 -232.659174)
		(width 0.09525)
		(layer "In6.Cu")
		(net "M_E_CPU0_SA_DQS_DN<6>")
	)
	(arc
		(start 330.24191 -232.686098)
		(mid 330.079259 -232.708358)
		(end 329.922632 -232.659174)
		(width 0.09525)
		(layer "In6.Cu")
		(net "M_E_CPU0_SA_DQS_DN<6>")
	)
	(arc
		(start 326.540114 -232.659174)
		(mid 326.308166 -232.705749)
		(end 326.095868 -232.601262)
		(width 0.09525)
		(layer "In6.Cu")
		(net "M_E_CPU0_SA_DQS_DN<6>")
	)
	(arc
		(start 329.359768 -232.659174)
		(mid 329.175993 -232.709946)
		(end 328.99096 -232.664)
		(width 0.09525)
		(layer "In6.Cu")
		(net "M_E_CPU0_SA_DQS_DN<6>")
	)
	(arc
		(start 328.411332 -232.664)
		(mid 328.2263 -232.709914)
		(end 328.042524 -232.659174)
		(width 0.09525)
		(layer "In6.Cu")
		(net "M_E_CPU0_SA_DQS_DN<6>")
	)
	(arc
		(start 327.092818 -232.653078)
		(mid 326.815656 -232.583278)
		(end 326.540114 -232.659174)
		(width 0.09525)
		(layer "In6.Cu")
		(net "M_E_CPU0_SA_DQS_DN<6>")
	)
	(arc
		(start 328.042524 -232.659174)
		(mid 327.767235 -232.583453)
		(end 327.490328 -232.653078)
		(width 0.09525)
		(layer "In6.Cu")
		(net "M_E_CPU0_SA_DQS_DN<6>")
	)
	(arc
		(start 329.922632 -232.659174)
		(mid 329.6412 -232.583419)
		(end 329.359768 -232.659174)
		(width 0.09525)
		(layer "In6.Cu")
		(net "M_E_CPU0_SA_DQS_DN<6>")
	)
	(segment
		(start 330.577952 -227.74021)
		(end 330.1111 -227.474272)
		(width 0.12954)
		(layer "F.Cu")
		(net "M_E_CPU0_SA_DQS_DN<5>")
	)
	(segment
		(start 328.419714 -227.799392)
		(end 328.411332 -227.804218)
		(width 0.09525)
		(layer "In6.Cu")
		(net "M_E_CPU0_SA_DQS_DN<5>")
	)
	(segment
		(start 304.033936 -202.827382)
		(end 302.362108 -202.827382)
		(width 0.16002)
		(layer "In6.Cu")
		(net "M_E_CPU0_SA_DQS_DN<5>")
	)
	(segment
		(start 325.503032 -223.424242)
		(end 325.503032 -223.139508)
		(width 0.09525)
		(layer "In6.Cu")
		(net "M_E_CPU0_SA_DQS_DN<5>")
	)
	(segment
		(start 302.362108 -202.827382)
		(end 301.542704 -202.007978)
		(width 0.16002)
		(layer "In6.Cu")
		(net "M_E_CPU0_SA_DQS_DN<5>")
	)
	(segment
		(start 283.068014 -201.638662)
		(end 282.18384 -202.522836)
		(width 0.16002)
		(layer "In6.Cu")
		(net "M_E_CPU0_SA_DQS_DN<5>")
	)
	(segment
		(start 305.153568 -202.18527)
		(end 304.338228 -202.52309)
		(width 0.16002)
		(layer "In6.Cu")
		(net "M_E_CPU0_SA_DQS_DN<5>")
	)
	(segment
		(start 276.131782 -201.678032)
		(end 274.957286 -201.678032)
		(width 0.16002)
		(layer "In6.Cu")
		(net "M_E_CPU0_SA_DQS_DN<5>")
	)
	(segment
		(start 297.609514 -202.185016)
		(end 296.794174 -202.522836)
		(width 0.16002)
		(layer "In6.Cu")
		(net "M_E_CPU0_SA_DQS_DN<5>")
	)
	(segment
		(start 273.365976 -201.85888)
		(end 273.092164 -201.585068)
		(width 0.16002)
		(layer "In6.Cu")
		(net "M_E_CPU0_SA_DQS_DN<5>")
	)
	(segment
		(start 294.848788 -202.857862)
		(end 293.998904 -202.007978)
		(width 0.16002)
		(layer "In6.Cu")
		(net "M_E_CPU0_SA_DQS_DN<5>")
	)
	(segment
		(start 282.18384 -202.522836)
		(end 281.70632 -202.522836)
		(width 0.16002)
		(layer "In6.Cu")
		(net "M_E_CPU0_SA_DQS_DN<5>")
	)
	(segment
		(start 326.754744 -226.963986)
		(end 326.754744 -226.963732)
		(width 0.09525)
		(layer "In6.Cu")
		(net "M_E_CPU0_SA_DQS_DN<5>")
	)
	(segment
		(start 299.090334 -202.007978)
		(end 298.721018 -201.638662)
		(width 0.16002)
		(layer "In6.Cu")
		(net "M_E_CPU0_SA_DQS_DN<5>")
	)
	(segment
		(start 301.542704 -202.007978)
		(end 299.090334 -202.007978)
		(width 0.16002)
		(layer "In6.Cu")
		(net "M_E_CPU0_SA_DQS_DN<5>")
	)
	(segment
		(start 325.972932 -224.383092)
		(end 325.97344 -224.383092)
		(width 0.09525)
		(layer "In6.Cu")
		(net "M_E_CPU0_SA_DQS_DN<5>")
	)
	(segment
		(start 306.265072 -201.638916)
		(end 305.699922 -201.638916)
		(width 0.16002)
		(layer "In6.Cu")
		(net "M_E_CPU0_SA_DQS_DN<5>")
	)
	(segment
		(start 298.721018 -201.638662)
		(end 298.155868 -201.638662)
		(width 0.16002)
		(layer "In6.Cu")
		(net "M_E_CPU0_SA_DQS_DN<5>")
	)
	(segment
		(start 290.611814 -201.638662)
		(end 290.06546 -202.185016)
		(width 0.16002)
		(layer "In6.Cu")
		(net "M_E_CPU0_SA_DQS_DN<5>")
	)
	(segment
		(start 314.2107 -207.545432)
		(end 313.566048 -207.545432)
		(width 0.16002)
		(layer "In6.Cu")
		(net "M_E_CPU0_SA_DQS_DN<5>")
	)
	(segment
		(start 279.701752 -202.857862)
		(end 278.868378 -202.024488)
		(width 0.16002)
		(layer "In6.Cu")
		(net "M_E_CPU0_SA_DQS_DN<5>")
	)
	(segment
		(start 325.972932 -225.775012)
		(end 325.972932 -224.383092)
		(width 0.09525)
		(layer "In6.Cu")
		(net "M_E_CPU0_SA_DQS_DN<5>")
	)
	(segment
		(start 296.794174 -202.522836)
		(end 296.459148 -202.857862)
		(width 0.16002)
		(layer "In6.Cu")
		(net "M_E_CPU0_SA_DQS_DN<5>")
	)
	(segment
		(start 325.973186 -225.774758)
		(end 325.972932 -225.775012)
		(width 0.09525)
		(layer "In6.Cu")
		(net "M_E_CPU0_SA_DQS_DN<5>")
	)
	(segment
		(start 287.212532 -202.857862)
		(end 286.362648 -202.007978)
		(width 0.16002)
		(layer "In6.Cu")
		(net "M_E_CPU0_SA_DQS_DN<5>")
	)
	(segment
		(start 308.379368 -202.358752)
		(end 306.984908 -202.358752)
		(width 0.16002)
		(layer "In6.Cu")
		(net "M_E_CPU0_SA_DQS_DN<5>")
	)
	(segment
		(start 293.998904 -202.007978)
		(end 291.54628 -202.007978)
		(width 0.16002)
		(layer "In6.Cu")
		(net "M_E_CPU0_SA_DQS_DN<5>")
	)
	(segment
		(start 306.984908 -202.358752)
		(end 306.265072 -201.638916)
		(width 0.16002)
		(layer "In6.Cu")
		(net "M_E_CPU0_SA_DQS_DN<5>")
	)
	(segment
		(start 330.1111 -227.474272)
		(end 330.265024 -227.739702)
		(width 0.09525)
		(layer "In6.Cu")
		(net "M_E_CPU0_SA_DQS_DN<5>")
	)
	(segment
		(start 291.54628 -202.007978)
		(end 291.176964 -201.638662)
		(width 0.16002)
		(layer "In6.Cu")
		(net "M_E_CPU0_SA_DQS_DN<5>")
	)
	(segment
		(start 291.176964 -201.638662)
		(end 290.611814 -201.638662)
		(width 0.16002)
		(layer "In6.Cu")
		(net "M_E_CPU0_SA_DQS_DN<5>")
	)
	(segment
		(start 296.459148 -202.857862)
		(end 294.848788 -202.857862)
		(width 0.16002)
		(layer "In6.Cu")
		(net "M_E_CPU0_SA_DQS_DN<5>")
	)
	(segment
		(start 325.66102 -223.731074)
		(end 325.660766 -223.731328)
		(width 0.09525)
		(layer "In6.Cu")
		(net "M_E_CPU0_SA_DQS_DN<5>")
	)
	(segment
		(start 278.868378 -202.024488)
		(end 276.478238 -202.024488)
		(width 0.16002)
		(layer "In6.Cu")
		(net "M_E_CPU0_SA_DQS_DN<5>")
	)
	(segment
		(start 305.699922 -201.638916)
		(end 305.153568 -202.18527)
		(width 0.16002)
		(layer "In6.Cu")
		(net "M_E_CPU0_SA_DQS_DN<5>")
	)
	(segment
		(start 327.241662 -227.588572)
		(end 326.88149 -227.228146)
		(width 0.09525)
		(layer "In6.Cu")
		(net "M_E_CPU0_SA_DQS_DN<5>")
	)
	(segment
		(start 322.114418 -219.667836)
		(end 322.114418 -215.44915)
		(width 0.16002)
		(layer "In6.Cu")
		(net "M_E_CPU0_SA_DQS_DN<5>")
	)
	(segment
		(start 284.00248 -202.007978)
		(end 283.633164 -201.638662)
		(width 0.16002)
		(layer "In6.Cu")
		(net "M_E_CPU0_SA_DQS_DN<5>")
	)
	(segment
		(start 288.915094 -202.857862)
		(end 287.212532 -202.857862)
		(width 0.16002)
		(layer "In6.Cu")
		(net "M_E_CPU0_SA_DQS_DN<5>")
	)
	(segment
		(start 325.107046 -222.660464)
		(end 322.114418 -219.667836)
		(width 0.16002)
		(layer "In6.Cu")
		(net "M_E_CPU0_SA_DQS_DN<5>")
	)
	(segment
		(start 289.25012 -202.522836)
		(end 288.915094 -202.857862)
		(width 0.16002)
		(layer "In6.Cu")
		(net "M_E_CPU0_SA_DQS_DN<5>")
	)
	(segment
		(start 298.155868 -201.638662)
		(end 297.609514 -202.185016)
		(width 0.16002)
		(layer "In6.Cu")
		(net "M_E_CPU0_SA_DQS_DN<5>")
	)
	(segment
		(start 286.362648 -202.007978)
		(end 284.00248 -202.007978)
		(width 0.16002)
		(layer "In6.Cu")
		(net "M_E_CPU0_SA_DQS_DN<5>")
	)
	(segment
		(start 304.338228 -202.52309)
		(end 304.033936 -202.827382)
		(width 0.16002)
		(layer "In6.Cu")
		(net "M_E_CPU0_SA_DQS_DN<5>")
	)
	(segment
		(start 325.503032 -223.139508)
		(end 325.380604 -223.01708)
		(width 0.09525)
		(layer "In6.Cu")
		(net "M_E_CPU0_SA_DQS_DN<5>")
	)
	(segment
		(start 325.730616 -223.77146)
		(end 325.66102 -223.731074)
		(width 0.09525)
		(layer "In6.Cu")
		(net "M_E_CPU0_SA_DQS_DN<5>")
	)
	(segment
		(start 276.478238 -202.024488)
		(end 276.131782 -201.678032)
		(width 0.16002)
		(layer "In6.Cu")
		(net "M_E_CPU0_SA_DQS_DN<5>")
	)
	(segment
		(start 325.380604 -223.01708)
		(end 325.12381 -222.760032)
		(width 0.09525)
		(layer "In6.Cu")
		(net "M_E_CPU0_SA_DQS_DN<5>")
	)
	(segment
		(start 274.52066 -201.85888)
		(end 273.365976 -201.85888)
		(width 0.16002)
		(layer "In6.Cu")
		(net "M_E_CPU0_SA_DQS_DN<5>")
	)
	(segment
		(start 325.12381 -222.677228)
		(end 325.107046 -222.660464)
		(width 0.09525)
		(layer "In6.Cu")
		(net "M_E_CPU0_SA_DQS_DN<5>")
	)
	(segment
		(start 330.265024 -227.739702)
		(end 330.24191 -227.826316)
		(width 0.09525)
		(layer "In6.Cu")
		(net "M_E_CPU0_SA_DQS_DN<5>")
	)
	(segment
		(start 325.12381 -222.760032)
		(end 325.12381 -222.677228)
		(width 0.09525)
		(layer "In6.Cu")
		(net "M_E_CPU0_SA_DQS_DN<5>")
	)
	(segment
		(start 281.371294 -202.857862)
		(end 279.701752 -202.857862)
		(width 0.16002)
		(layer "In6.Cu")
		(net "M_E_CPU0_SA_DQS_DN<5>")
	)
	(segment
		(start 281.70632 -202.522836)
		(end 281.371294 -202.857862)
		(width 0.16002)
		(layer "In6.Cu")
		(net "M_E_CPU0_SA_DQS_DN<5>")
	)
	(segment
		(start 325.97344 -224.383092)
		(end 325.97344 -224.234248)
		(width 0.09525)
		(layer "In6.Cu")
		(net "M_E_CPU0_SA_DQS_DN<5>")
	)
	(segment
		(start 327.761346 -227.7237)
		(end 327.567544 -227.7237)
		(width 0.09525)
		(layer "In6.Cu")
		(net "M_E_CPU0_SA_DQS_DN<5>")
	)
	(segment
		(start 283.633164 -201.638662)
		(end 283.068014 -201.638662)
		(width 0.16002)
		(layer "In6.Cu")
		(net "M_E_CPU0_SA_DQS_DN<5>")
	)
	(segment
		(start 290.06546 -202.185016)
		(end 289.25012 -202.522836)
		(width 0.16002)
		(layer "In6.Cu")
		(net "M_E_CPU0_SA_DQS_DN<5>")
	)
	(segment
		(start 322.114418 -215.44915)
		(end 314.2107 -207.545432)
		(width 0.16002)
		(layer "In6.Cu")
		(net "M_E_CPU0_SA_DQS_DN<5>")
	)
	(segment
		(start 274.957286 -201.678032)
		(end 274.52066 -201.85888)
		(width 0.16002)
		(layer "In6.Cu")
		(net "M_E_CPU0_SA_DQS_DN<5>")
	)
	(segment
		(start 313.566048 -207.545432)
		(end 308.379368 -202.358752)
		(width 0.16002)
		(layer "In6.Cu")
		(net "M_E_CPU0_SA_DQS_DN<5>")
	)
	(segment
		(start 328.99096 -227.804218)
		(end 328.982578 -227.799392)
		(width 0.09525)
		(layer "In6.Cu")
		(net "M_E_CPU0_SA_DQS_DN<5>")
	)
	(arc
		(start 326.88149 -227.228146)
		(mid 326.795646 -227.106852)
		(end 326.754744 -226.963986)
		(width 0.09525)
		(layer "In6.Cu")
		(net "M_E_CPU0_SA_DQS_DN<5>")
	)
	(arc
		(start 329.922632 -227.799392)
		(mid 329.6412 -227.723637)
		(end 329.359768 -227.799392)
		(width 0.09525)
		(layer "In6.Cu")
		(net "M_E_CPU0_SA_DQS_DN<5>")
	)
	(arc
		(start 328.411332 -227.804218)
		(mid 328.2263 -227.850132)
		(end 328.042524 -227.799392)
		(width 0.09525)
		(layer "In6.Cu")
		(net "M_E_CPU0_SA_DQS_DN<5>")
	)
	(arc
		(start 327.567544 -227.7237)
		(mid 327.391177 -227.688525)
		(end 327.241662 -227.588572)
		(width 0.09525)
		(layer "In6.Cu")
		(net "M_E_CPU0_SA_DQS_DN<5>")
	)
	(arc
		(start 325.97344 -224.234248)
		(mid 325.909043 -223.972942)
		(end 325.730616 -223.77146)
		(width 0.09525)
		(layer "In6.Cu")
		(net "M_E_CPU0_SA_DQS_DN<5>")
	)
	(arc
		(start 325.660766 -223.731328)
		(mid 325.544743 -223.596865)
		(end 325.503032 -223.424242)
		(width 0.09525)
		(layer "In6.Cu")
		(net "M_E_CPU0_SA_DQS_DN<5>")
	)
	(arc
		(start 326.410574 -226.527868)
		(mid 326.314113 -226.334452)
		(end 326.166226 -226.17684)
		(width 0.09525)
		(layer "In6.Cu")
		(net "M_E_CPU0_SA_DQS_DN<5>")
	)
	(arc
		(start 328.982578 -227.799392)
		(mid 328.701146 -227.723637)
		(end 328.419714 -227.799392)
		(width 0.09525)
		(layer "In6.Cu")
		(net "M_E_CPU0_SA_DQS_DN<5>")
	)
	(arc
		(start 326.754744 -226.963732)
		(mid 326.679414 -226.771805)
		(end 326.517508 -226.6442)
		(width 0.09525)
		(layer "In6.Cu")
		(net "M_E_CPU0_SA_DQS_DN<5>")
	)
	(arc
		(start 330.24191 -227.826316)
		(mid 330.079259 -227.848576)
		(end 329.922632 -227.799392)
		(width 0.09525)
		(layer "In6.Cu")
		(net "M_E_CPU0_SA_DQS_DN<5>")
	)
	(arc
		(start 328.042524 -227.799392)
		(mid 327.906939 -227.74294)
		(end 327.761346 -227.7237)
		(width 0.09525)
		(layer "In6.Cu")
		(net "M_E_CPU0_SA_DQS_DN<5>")
	)
	(arc
		(start 326.517508 -226.6442)
		(mid 326.451479 -226.597572)
		(end 326.410574 -226.527868)
		(width 0.09525)
		(layer "In6.Cu")
		(net "M_E_CPU0_SA_DQS_DN<5>")
	)
	(arc
		(start 326.166226 -226.17684)
		(mid 326.023811 -225.997828)
		(end 325.973186 -225.774758)
		(width 0.09525)
		(layer "In6.Cu")
		(net "M_E_CPU0_SA_DQS_DN<5>")
	)
	(arc
		(start 329.359768 -227.799392)
		(mid 329.175993 -227.850164)
		(end 328.99096 -227.804218)
		(width 0.09525)
		(layer "In6.Cu")
		(net "M_E_CPU0_SA_DQS_DN<5>")
	)
	(segment
		(start 329.637898 -247.1801)
		(end 329.171046 -246.914162)
		(width 0.12954)
		(layer "F.Cu")
		(net "M_E_CPU0_SA_DQS_DN<4>")
	)
	(segment
		(start 305.012598 -238.891572)
		(end 304.289206 -238.891572)
		(width 0.16002)
		(layer "In6.Cu")
		(net "M_E_CPU0_SA_DQS_DN<4>")
	)
	(segment
		(start 281.385772 -238.562134)
		(end 279.743154 -238.562134)
		(width 0.16002)
		(layer "In6.Cu")
		(net "M_E_CPU0_SA_DQS_DN<4>")
	)
	(segment
		(start 310.071262 -241.934492)
		(end 310.071262 -241.708432)
		(width 0.16002)
		(layer "In6.Cu")
		(net "M_E_CPU0_SA_DQS_DN<4>")
	)
	(segment
		(start 327.490328 -246.595138)
		(end 327.479914 -246.589042)
		(width 0.09525)
		(layer "In6.Cu")
		(net "M_E_CPU0_SA_DQS_DN<4>")
	)
	(segment
		(start 282.352242 -238.891572)
		(end 281.71521 -238.891572)
		(width 0.16002)
		(layer "In6.Cu")
		(net "M_E_CPU0_SA_DQS_DN<4>")
	)
	(segment
		(start 323.895974 -246.81053)
		(end 323.61759 -246.81053)
		(width 0.16002)
		(layer "In6.Cu")
		(net "M_E_CPU0_SA_DQS_DN<4>")
	)
	(segment
		(start 324.51294 -246.9261)
		(end 324.338442 -246.751602)
		(width 0.09525)
		(layer "In6.Cu")
		(net "M_E_CPU0_SA_DQS_DN<4>")
	)
	(segment
		(start 301.462186 -238.577628)
		(end 300.596808 -237.71225)
		(width 0.16002)
		(layer "In6.Cu")
		(net "M_E_CPU0_SA_DQS_DN<4>")
	)
	(segment
		(start 325.945754 -246.654828)
		(end 325.26732 -246.654828)
		(width 0.09525)
		(layer "In6.Cu")
		(net "M_E_CPU0_SA_DQS_DN<4>")
	)
	(segment
		(start 296.473626 -238.562134)
		(end 293.902638 -238.562134)
		(width 0.16002)
		(layer "In6.Cu")
		(net "M_E_CPU0_SA_DQS_DN<4>")
	)
	(segment
		(start 283.627576 -238.060992)
		(end 283.182822 -238.060992)
		(width 0.16002)
		(layer "In6.Cu")
		(net "M_E_CPU0_SA_DQS_DN<4>")
	)
	(segment
		(start 323.61759 -246.81053)
		(end 323.112892 -246.305832)
		(width 0.16002)
		(layer "In6.Cu")
		(net "M_E_CPU0_SA_DQS_DN<4>")
	)
	(segment
		(start 323.919596 -246.81053)
		(end 323.895974 -246.81053)
		(width 0.09525)
		(layer "In6.Cu")
		(net "M_E_CPU0_SA_DQS_DN<4>")
	)
	(segment
		(start 313.023758 -245.889272)
		(end 312.590688 -245.456202)
		(width 0.16002)
		(layer "In6.Cu")
		(net "M_E_CPU0_SA_DQS_DN<4>")
	)
	(segment
		(start 312.590688 -245.456202)
		(end 312.590688 -244.979698)
		(width 0.16002)
		(layer "In6.Cu")
		(net "M_E_CPU0_SA_DQS_DN<4>")
	)
	(segment
		(start 329.017122 -246.648732)
		(end 328.916284 -246.622062)
		(width 0.09525)
		(layer "In6.Cu")
		(net "M_E_CPU0_SA_DQS_DN<4>")
	)
	(segment
		(start 286.31769 -238.562134)
		(end 285.467806 -237.71225)
		(width 0.16002)
		(layer "In6.Cu")
		(net "M_E_CPU0_SA_DQS_DN<4>")
	)
	(segment
		(start 309.808372 -242.673886)
		(end 309.808372 -242.197382)
		(width 0.16002)
		(layer "In6.Cu")
		(net "M_E_CPU0_SA_DQS_DN<4>")
	)
	(segment
		(start 311.6326 -244.498114)
		(end 311.19953 -244.065044)
		(width 0.16002)
		(layer "In6.Cu")
		(net "M_E_CPU0_SA_DQS_DN<4>")
	)
	(segment
		(start 279.743154 -238.562134)
		(end 279.594056 -238.711232)
		(width 0.16002)
		(layer "In6.Cu")
		(net "M_E_CPU0_SA_DQS_DN<4>")
	)
	(segment
		(start 312.109104 -244.498114)
		(end 311.6326 -244.498114)
		(width 0.16002)
		(layer "In6.Cu")
		(net "M_E_CPU0_SA_DQS_DN<4>")
	)
	(segment
		(start 311.206896 -242.844066)
		(end 310.980836 -242.844066)
		(width 0.16002)
		(layer "In6.Cu")
		(net "M_E_CPU0_SA_DQS_DN<4>")
	)
	(segment
		(start 303.975262 -238.577628)
		(end 301.462186 -238.577628)
		(width 0.16002)
		(layer "In6.Cu")
		(net "M_E_CPU0_SA_DQS_DN<4>")
	)
	(segment
		(start 310.717946 -243.106956)
		(end 310.241442 -243.106956)
		(width 0.16002)
		(layer "In6.Cu")
		(net "M_E_CPU0_SA_DQS_DN<4>")
	)
	(segment
		(start 312.598054 -244.235224)
		(end 312.371994 -244.235224)
		(width 0.16002)
		(layer "In6.Cu")
		(net "M_E_CPU0_SA_DQS_DN<4>")
	)
	(segment
		(start 309.808372 -242.197382)
		(end 310.071262 -241.934492)
		(width 0.16002)
		(layer "In6.Cu")
		(net "M_E_CPU0_SA_DQS_DN<4>")
	)
	(segment
		(start 297.468544 -238.891572)
		(end 296.803064 -238.891572)
		(width 0.16002)
		(layer "In6.Cu")
		(net "M_E_CPU0_SA_DQS_DN<4>")
	)
	(segment
		(start 323.112892 -246.305832)
		(end 314.668662 -246.305832)
		(width 0.16002)
		(layer "In6.Cu")
		(net "M_E_CPU0_SA_DQS_DN<4>")
	)
	(segment
		(start 293.902638 -238.562134)
		(end 293.052754 -237.71225)
		(width 0.16002)
		(layer "In6.Cu")
		(net "M_E_CPU0_SA_DQS_DN<4>")
	)
	(segment
		(start 308.680104 -240.317274)
		(end 307.506878 -239.144048)
		(width 0.16002)
		(layer "In6.Cu")
		(net "M_E_CPU0_SA_DQS_DN<4>")
	)
	(segment
		(start 291.520118 -237.71225)
		(end 291.171376 -238.060992)
		(width 0.16002)
		(layer "In6.Cu")
		(net "M_E_CPU0_SA_DQS_DN<4>")
	)
	(segment
		(start 326.351138 -246.53748)
		(end 326.303132 -246.53748)
		(width 0.09525)
		(layer "In6.Cu")
		(net "M_E_CPU0_SA_DQS_DN<4>")
	)
	(segment
		(start 279.594056 -238.711232)
		(end 277.466044 -238.711232)
		(width 0.16002)
		(layer "In6.Cu")
		(net "M_E_CPU0_SA_DQS_DN<4>")
	)
	(segment
		(start 289.25901 -238.891572)
		(end 288.929572 -238.562134)
		(width 0.16002)
		(layer "In6.Cu")
		(net "M_E_CPU0_SA_DQS_DN<4>")
	)
	(segment
		(start 296.803064 -238.891572)
		(end 296.473626 -238.562134)
		(width 0.16002)
		(layer "In6.Cu")
		(net "M_E_CPU0_SA_DQS_DN<4>")
	)
	(segment
		(start 324.338442 -246.751602)
		(end 323.978524 -246.751602)
		(width 0.09525)
		(layer "In6.Cu")
		(net "M_E_CPU0_SA_DQS_DN<4>")
	)
	(segment
		(start 304.289206 -238.891572)
		(end 303.975262 -238.577628)
		(width 0.16002)
		(layer "In6.Cu")
		(net "M_E_CPU0_SA_DQS_DN<4>")
	)
	(segment
		(start 325.26732 -246.654828)
		(end 324.996048 -246.9261)
		(width 0.09525)
		(layer "In6.Cu")
		(net "M_E_CPU0_SA_DQS_DN<4>")
	)
	(segment
		(start 283.976318 -237.71225)
		(end 283.627576 -238.060992)
		(width 0.16002)
		(layer "In6.Cu")
		(net "M_E_CPU0_SA_DQS_DN<4>")
	)
	(segment
		(start 314.668662 -246.305832)
		(end 313.989212 -245.626382)
		(width 0.16002)
		(layer "In6.Cu")
		(net "M_E_CPU0_SA_DQS_DN<4>")
	)
	(segment
		(start 307.506878 -239.144048)
		(end 307.506878 -238.836962)
		(width 0.16002)
		(layer "In6.Cu")
		(net "M_E_CPU0_SA_DQS_DN<4>")
	)
	(segment
		(start 293.052754 -237.71225)
		(end 291.520118 -237.71225)
		(width 0.16002)
		(layer "In6.Cu")
		(net "M_E_CPU0_SA_DQS_DN<4>")
	)
	(segment
		(start 307.506878 -238.836962)
		(end 306.730908 -238.060992)
		(width 0.16002)
		(layer "In6.Cu")
		(net "M_E_CPU0_SA_DQS_DN<4>")
	)
	(segment
		(start 277.466044 -238.711232)
		(end 277.192232 -238.985044)
		(width 0.16002)
		(layer "In6.Cu")
		(net "M_E_CPU0_SA_DQS_DN<4>")
	)
	(segment
		(start 310.241442 -243.106956)
		(end 309.808372 -242.673886)
		(width 0.16002)
		(layer "In6.Cu")
		(net "M_E_CPU0_SA_DQS_DN<4>")
	)
	(segment
		(start 309.815738 -241.452908)
		(end 309.136034 -241.452908)
		(width 0.16002)
		(layer "In6.Cu")
		(net "M_E_CPU0_SA_DQS_DN<4>")
	)
	(segment
		(start 328.419714 -246.589042)
		(end 328.411332 -246.584216)
		(width 0.09525)
		(layer "In6.Cu")
		(net "M_E_CPU0_SA_DQS_DN<4>")
	)
	(segment
		(start 312.853578 -244.716808)
		(end 312.853578 -244.490748)
		(width 0.16002)
		(layer "In6.Cu")
		(net "M_E_CPU0_SA_DQS_DN<4>")
	)
	(segment
		(start 323.978524 -246.751602)
		(end 323.919596 -246.81053)
		(width 0.09525)
		(layer "In6.Cu")
		(net "M_E_CPU0_SA_DQS_DN<4>")
	)
	(segment
		(start 313.500262 -245.889272)
		(end 313.023758 -245.889272)
		(width 0.16002)
		(layer "In6.Cu")
		(net "M_E_CPU0_SA_DQS_DN<4>")
	)
	(segment
		(start 281.71521 -238.891572)
		(end 281.385772 -238.562134)
		(width 0.16002)
		(layer "In6.Cu")
		(net "M_E_CPU0_SA_DQS_DN<4>")
	)
	(segment
		(start 290.75507 -238.060992)
		(end 289.92449 -238.891572)
		(width 0.16002)
		(layer "In6.Cu")
		(net "M_E_CPU0_SA_DQS_DN<4>")
	)
	(segment
		(start 288.929572 -238.562134)
		(end 286.31769 -238.562134)
		(width 0.16002)
		(layer "In6.Cu")
		(net "M_E_CPU0_SA_DQS_DN<4>")
	)
	(segment
		(start 306.730908 -238.060992)
		(end 305.843178 -238.060992)
		(width 0.16002)
		(layer "In6.Cu")
		(net "M_E_CPU0_SA_DQS_DN<4>")
	)
	(segment
		(start 309.136034 -241.452908)
		(end 308.680104 -240.996978)
		(width 0.16002)
		(layer "In6.Cu")
		(net "M_E_CPU0_SA_DQS_DN<4>")
	)
	(segment
		(start 285.467806 -237.71225)
		(end 283.976318 -237.71225)
		(width 0.16002)
		(layer "In6.Cu")
		(net "M_E_CPU0_SA_DQS_DN<4>")
	)
	(segment
		(start 311.19953 -243.58854)
		(end 311.46242 -243.32565)
		(width 0.16002)
		(layer "In6.Cu")
		(net "M_E_CPU0_SA_DQS_DN<4>")
	)
	(segment
		(start 313.989212 -245.626382)
		(end 313.763152 -245.626382)
		(width 0.16002)
		(layer "In6.Cu")
		(net "M_E_CPU0_SA_DQS_DN<4>")
	)
	(segment
		(start 300.596808 -237.71225)
		(end 299.064172 -237.71225)
		(width 0.16002)
		(layer "In6.Cu")
		(net "M_E_CPU0_SA_DQS_DN<4>")
	)
	(segment
		(start 312.590688 -244.979698)
		(end 312.853578 -244.716808)
		(width 0.16002)
		(layer "In6.Cu")
		(net "M_E_CPU0_SA_DQS_DN<4>")
	)
	(segment
		(start 326.162162 -246.56542)
		(end 325.945754 -246.654828)
		(width 0.09525)
		(layer "In6.Cu")
		(net "M_E_CPU0_SA_DQS_DN<4>")
	)
	(segment
		(start 324.996048 -246.9261)
		(end 324.51294 -246.9261)
		(width 0.09525)
		(layer "In6.Cu")
		(net "M_E_CPU0_SA_DQS_DN<4>")
	)
	(segment
		(start 299.064172 -237.71225)
		(end 298.71543 -238.060992)
		(width 0.16002)
		(layer "In6.Cu")
		(net "M_E_CPU0_SA_DQS_DN<4>")
	)
	(segment
		(start 308.680104 -240.996978)
		(end 308.680104 -240.317274)
		(width 0.16002)
		(layer "In6.Cu")
		(net "M_E_CPU0_SA_DQS_DN<4>")
	)
	(segment
		(start 327.102978 -246.589042)
		(end 327.092564 -246.595138)
		(width 0.09525)
		(layer "In6.Cu")
		(net "M_E_CPU0_SA_DQS_DN<4>")
	)
	(segment
		(start 305.843178 -238.060992)
		(end 305.012598 -238.891572)
		(width 0.16002)
		(layer "In6.Cu")
		(net "M_E_CPU0_SA_DQS_DN<4>")
	)
	(segment
		(start 313.763152 -245.626382)
		(end 313.500262 -245.889272)
		(width 0.16002)
		(layer "In6.Cu")
		(net "M_E_CPU0_SA_DQS_DN<4>")
	)
	(segment
		(start 312.853578 -244.490748)
		(end 312.598054 -244.235224)
		(width 0.16002)
		(layer "In6.Cu")
		(net "M_E_CPU0_SA_DQS_DN<4>")
	)
	(segment
		(start 311.46242 -243.09959)
		(end 311.206896 -242.844066)
		(width 0.16002)
		(layer "In6.Cu")
		(net "M_E_CPU0_SA_DQS_DN<4>")
	)
	(segment
		(start 312.371994 -244.235224)
		(end 312.109104 -244.498114)
		(width 0.16002)
		(layer "In6.Cu")
		(net "M_E_CPU0_SA_DQS_DN<4>")
	)
	(segment
		(start 310.980836 -242.844066)
		(end 310.717946 -243.106956)
		(width 0.16002)
		(layer "In6.Cu")
		(net "M_E_CPU0_SA_DQS_DN<4>")
	)
	(segment
		(start 291.171376 -238.060992)
		(end 290.75507 -238.060992)
		(width 0.16002)
		(layer "In6.Cu")
		(net "M_E_CPU0_SA_DQS_DN<4>")
	)
	(segment
		(start 298.71543 -238.060992)
		(end 298.299124 -238.060992)
		(width 0.16002)
		(layer "In6.Cu")
		(net "M_E_CPU0_SA_DQS_DN<4>")
	)
	(segment
		(start 311.46242 -243.32565)
		(end 311.46242 -243.09959)
		(width 0.16002)
		(layer "In6.Cu")
		(net "M_E_CPU0_SA_DQS_DN<4>")
	)
	(segment
		(start 311.19953 -244.065044)
		(end 311.19953 -243.58854)
		(width 0.16002)
		(layer "In6.Cu")
		(net "M_E_CPU0_SA_DQS_DN<4>")
	)
	(segment
		(start 289.92449 -238.891572)
		(end 289.25901 -238.891572)
		(width 0.16002)
		(layer "In6.Cu")
		(net "M_E_CPU0_SA_DQS_DN<4>")
	)
	(segment
		(start 310.071262 -241.708432)
		(end 309.815738 -241.452908)
		(width 0.16002)
		(layer "In6.Cu")
		(net "M_E_CPU0_SA_DQS_DN<4>")
	)
	(segment
		(start 283.182822 -238.060992)
		(end 282.352242 -238.891572)
		(width 0.16002)
		(layer "In6.Cu")
		(net "M_E_CPU0_SA_DQS_DN<4>")
	)
	(segment
		(start 298.299124 -238.060992)
		(end 297.468544 -238.891572)
		(width 0.16002)
		(layer "In6.Cu")
		(net "M_E_CPU0_SA_DQS_DN<4>")
	)
	(segment
		(start 329.171046 -246.914162)
		(end 329.017122 -246.648732)
		(width 0.09525)
		(layer "In6.Cu")
		(net "M_E_CPU0_SA_DQS_DN<4>")
	)
	(arc
		(start 327.092564 -246.595138)
		(mid 326.815402 -246.664938)
		(end 326.53986 -246.589042)
		(width 0.09525)
		(layer "In6.Cu")
		(net "M_E_CPU0_SA_DQS_DN<4>")
	)
	(arc
		(start 328.916284 -246.622062)
		(mid 328.906416 -246.626093)
		(end 328.896472 -246.629936)
		(width 0.09525)
		(layer "In6.Cu")
		(net "M_E_CPU0_SA_DQS_DN<4>")
	)
	(arc
		(start 326.303132 -246.53748)
		(mid 326.231276 -246.544533)
		(end 326.162162 -246.56542)
		(width 0.09525)
		(layer "In6.Cu")
		(net "M_E_CPU0_SA_DQS_DN<4>")
	)
	(arc
		(start 328.411332 -246.584216)
		(mid 328.2263 -246.538302)
		(end 328.042524 -246.589042)
		(width 0.09525)
		(layer "In6.Cu")
		(net "M_E_CPU0_SA_DQS_DN<4>")
	)
	(arc
		(start 327.479914 -246.589042)
		(mid 327.291446 -246.538365)
		(end 327.102978 -246.589042)
		(width 0.09525)
		(layer "In6.Cu")
		(net "M_E_CPU0_SA_DQS_DN<4>")
	)
	(arc
		(start 328.042524 -246.589042)
		(mid 327.767235 -246.664763)
		(end 327.490328 -246.595138)
		(width 0.09525)
		(layer "In6.Cu")
		(net "M_E_CPU0_SA_DQS_DN<4>")
	)
	(arc
		(start 326.53986 -246.589042)
		(mid 326.448914 -246.550741)
		(end 326.351138 -246.53748)
		(width 0.09525)
		(layer "In6.Cu")
		(net "M_E_CPU0_SA_DQS_DN<4>")
	)
	(arc
		(start 328.896472 -246.629936)
		(mid 328.653508 -246.662923)
		(end 328.419714 -246.589042)
		(width 0.09525)
		(layer "In6.Cu")
		(net "M_E_CPU0_SA_DQS_DN<4>")
	)
	(segment
		(start 329.637898 -242.320064)
		(end 329.171046 -242.054126)
		(width 0.12954)
		(layer "F.Cu")
		(net "M_E_CPU0_SA_DQS_DN<3>")
	)
	(segment
		(start 289.742118 -229.72395)
		(end 289.023806 -229.72395)
		(width 0.16002)
		(layer "In6.Cu")
		(net "M_E_CPU0_SA_DQS_DN<3>")
	)
	(segment
		(start 325.4375 -241.677444)
		(end 324.873366 -241.11331)
		(width 0.09525)
		(layer "In6.Cu")
		(net "M_E_CPU0_SA_DQS_DN<3>")
	)
	(segment
		(start 327.490328 -241.735102)
		(end 327.479914 -241.729006)
		(width 0.09525)
		(layer "In6.Cu")
		(net "M_E_CPU0_SA_DQS_DN<3>")
	)
	(segment
		(start 291.520118 -228.362256)
		(end 291.171376 -228.710998)
		(width 0.16002)
		(layer "In6.Cu")
		(net "M_E_CPU0_SA_DQS_DN<3>")
	)
	(segment
		(start 297.255692 -229.75443)
		(end 296.5831 -229.75443)
		(width 0.16002)
		(layer "In6.Cu")
		(net "M_E_CPU0_SA_DQS_DN<3>")
	)
	(segment
		(start 306.950618 -229.428294)
		(end 306.950618 -228.981508)
		(width 0.16002)
		(layer "In6.Cu")
		(net "M_E_CPU0_SA_DQS_DN<3>")
	)
	(segment
		(start 296.5831 -229.75443)
		(end 296.04081 -229.21214)
		(width 0.16002)
		(layer "In6.Cu")
		(net "M_E_CPU0_SA_DQS_DN<3>")
	)
	(segment
		(start 315.491876 -237.547912)
		(end 315.264292 -237.775496)
		(width 0.16002)
		(layer "In6.Cu")
		(net "M_E_CPU0_SA_DQS_DN<3>")
	)
	(segment
		(start 304.570384 -229.983792)
		(end 302.943768 -229.983792)
		(width 0.16002)
		(layer "In6.Cu")
		(net "M_E_CPU0_SA_DQS_DN<3>")
	)
	(segment
		(start 279.594056 -229.361238)
		(end 277.466044 -229.361238)
		(width 0.16002)
		(layer "In6.Cu")
		(net "M_E_CPU0_SA_DQS_DN<3>")
	)
	(segment
		(start 277.466044 -229.361238)
		(end 277.192232 -229.63505)
		(width 0.16002)
		(layer "In6.Cu")
		(net "M_E_CPU0_SA_DQS_DN<3>")
	)
	(segment
		(start 315.746384 -238.257588)
		(end 315.973968 -238.030004)
		(width 0.16002)
		(layer "In6.Cu")
		(net "M_E_CPU0_SA_DQS_DN<3>")
	)
	(segment
		(start 313.873134 -236.384338)
		(end 313.39663 -236.384338)
		(width 0.16002)
		(layer "In6.Cu")
		(net "M_E_CPU0_SA_DQS_DN<3>")
	)
	(segment
		(start 283.976318 -228.362256)
		(end 283.627576 -228.710998)
		(width 0.16002)
		(layer "In6.Cu")
		(net "M_E_CPU0_SA_DQS_DN<3>")
	)
	(segment
		(start 311.128664 -232.678224)
		(end 308.215792 -229.765352)
		(width 0.16002)
		(layer "In6.Cu")
		(net "M_E_CPU0_SA_DQS_DN<3>")
	)
	(segment
		(start 317.109094 -238.93907)
		(end 316.883034 -238.93907)
		(width 0.16002)
		(layer "In6.Cu")
		(net "M_E_CPU0_SA_DQS_DN<3>")
	)
	(segment
		(start 301.529242 -229.29469)
		(end 300.596808 -228.362256)
		(width 0.16002)
		(layer "In6.Cu")
		(net "M_E_CPU0_SA_DQS_DN<3>")
	)
	(segment
		(start 315.973968 -238.030004)
		(end 315.973968 -237.803944)
		(width 0.16002)
		(layer "In6.Cu")
		(net "M_E_CPU0_SA_DQS_DN<3>")
	)
	(segment
		(start 315.746384 -238.734092)
		(end 315.746384 -238.257588)
		(width 0.16002)
		(layer "In6.Cu")
		(net "M_E_CPU0_SA_DQS_DN<3>")
	)
	(segment
		(start 307.287676 -229.765352)
		(end 306.950618 -229.428294)
		(width 0.16002)
		(layer "In6.Cu")
		(net "M_E_CPU0_SA_DQS_DN<3>")
	)
	(segment
		(start 314.100718 -236.156754)
		(end 313.873134 -236.384338)
		(width 0.16002)
		(layer "In6.Cu")
		(net "M_E_CPU0_SA_DQS_DN<3>")
	)
	(segment
		(start 314.58281 -236.412786)
		(end 314.326778 -236.156754)
		(width 0.16002)
		(layer "In6.Cu")
		(net "M_E_CPU0_SA_DQS_DN<3>")
	)
	(segment
		(start 317.705232 -240.69294)
		(end 317.137542 -240.12525)
		(width 0.16002)
		(layer "In6.Cu")
		(net "M_E_CPU0_SA_DQS_DN<3>")
	)
	(segment
		(start 281.515566 -229.81285)
		(end 280.914856 -229.21214)
		(width 0.16002)
		(layer "In6.Cu")
		(net "M_E_CPU0_SA_DQS_DN<3>")
	)
	(segment
		(start 315.973968 -237.803944)
		(end 315.717936 -237.547912)
		(width 0.16002)
		(layer "In6.Cu")
		(net "M_E_CPU0_SA_DQS_DN<3>")
	)
	(segment
		(start 298.299124 -228.710998)
		(end 297.255692 -229.75443)
		(width 0.16002)
		(layer "In6.Cu")
		(net "M_E_CPU0_SA_DQS_DN<3>")
	)
	(segment
		(start 314.787788 -237.775496)
		(end 314.355226 -237.342934)
		(width 0.16002)
		(layer "In6.Cu")
		(net "M_E_CPU0_SA_DQS_DN<3>")
	)
	(segment
		(start 305.843178 -228.710998)
		(end 304.570384 -229.983792)
		(width 0.16002)
		(layer "In6.Cu")
		(net "M_E_CPU0_SA_DQS_DN<3>")
	)
	(segment
		(start 306.950618 -228.981508)
		(end 306.680108 -228.710998)
		(width 0.16002)
		(layer "In6.Cu")
		(net "M_E_CPU0_SA_DQS_DN<3>")
	)
	(segment
		(start 316.178946 -239.166654)
		(end 315.746384 -238.734092)
		(width 0.16002)
		(layer "In6.Cu")
		(net "M_E_CPU0_SA_DQS_DN<3>")
	)
	(segment
		(start 302.943768 -229.983792)
		(end 302.254666 -229.29469)
		(width 0.16002)
		(layer "In6.Cu")
		(net "M_E_CPU0_SA_DQS_DN<3>")
	)
	(segment
		(start 324.10654 -240.641124)
		(end 323.971412 -240.641124)
		(width 0.09525)
		(layer "In6.Cu")
		(net "M_E_CPU0_SA_DQS_DN<3>")
	)
	(segment
		(start 283.627576 -228.710998)
		(end 283.182822 -228.710998)
		(width 0.16002)
		(layer "In6.Cu")
		(net "M_E_CPU0_SA_DQS_DN<3>")
	)
	(segment
		(start 283.182822 -228.710998)
		(end 282.08097 -229.81285)
		(width 0.16002)
		(layer "In6.Cu")
		(net "M_E_CPU0_SA_DQS_DN<3>")
	)
	(segment
		(start 323.895974 -240.69294)
		(end 317.705232 -240.69294)
		(width 0.16002)
		(layer "In6.Cu")
		(net "M_E_CPU0_SA_DQS_DN<3>")
	)
	(segment
		(start 314.326778 -236.156754)
		(end 314.100718 -236.156754)
		(width 0.16002)
		(layer "In6.Cu")
		(net "M_E_CPU0_SA_DQS_DN<3>")
	)
	(segment
		(start 329.017122 -241.788696)
		(end 328.916284 -241.762026)
		(width 0.09525)
		(layer "In6.Cu")
		(net "M_E_CPU0_SA_DQS_DN<3>")
	)
	(segment
		(start 317.365126 -239.195102)
		(end 317.109094 -238.93907)
		(width 0.16002)
		(layer "In6.Cu")
		(net "M_E_CPU0_SA_DQS_DN<3>")
	)
	(segment
		(start 300.596808 -228.362256)
		(end 299.064172 -228.362256)
		(width 0.16002)
		(layer "In6.Cu")
		(net "M_E_CPU0_SA_DQS_DN<3>")
	)
	(segment
		(start 296.04081 -229.21214)
		(end 293.902638 -229.21214)
		(width 0.16002)
		(layer "In6.Cu")
		(net "M_E_CPU0_SA_DQS_DN<3>")
	)
	(segment
		(start 327.102978 -241.729006)
		(end 327.092564 -241.735102)
		(width 0.09525)
		(layer "In6.Cu")
		(net "M_E_CPU0_SA_DQS_DN<3>")
	)
	(segment
		(start 315.264292 -237.775496)
		(end 314.787788 -237.775496)
		(width 0.16002)
		(layer "In6.Cu")
		(net "M_E_CPU0_SA_DQS_DN<3>")
	)
	(segment
		(start 314.58281 -236.638846)
		(end 314.58281 -236.412786)
		(width 0.16002)
		(layer "In6.Cu")
		(net "M_E_CPU0_SA_DQS_DN<3>")
	)
	(segment
		(start 328.419714 -241.729006)
		(end 328.411332 -241.72418)
		(width 0.09525)
		(layer "In6.Cu")
		(net "M_E_CPU0_SA_DQS_DN<3>")
	)
	(segment
		(start 314.355226 -237.342934)
		(end 314.355226 -236.86643)
		(width 0.16002)
		(layer "In6.Cu")
		(net "M_E_CPU0_SA_DQS_DN<3>")
	)
	(segment
		(start 317.137542 -240.12525)
		(end 317.137542 -239.648746)
		(width 0.16002)
		(layer "In6.Cu")
		(net "M_E_CPU0_SA_DQS_DN<3>")
	)
	(segment
		(start 315.717936 -237.547912)
		(end 315.491876 -237.547912)
		(width 0.16002)
		(layer "In6.Cu")
		(net "M_E_CPU0_SA_DQS_DN<3>")
	)
	(segment
		(start 324.873366 -241.11331)
		(end 324.578726 -241.11331)
		(width 0.09525)
		(layer "In6.Cu")
		(net "M_E_CPU0_SA_DQS_DN<3>")
	)
	(segment
		(start 306.680108 -228.710998)
		(end 305.843178 -228.710998)
		(width 0.16002)
		(layer "In6.Cu")
		(net "M_E_CPU0_SA_DQS_DN<3>")
	)
	(segment
		(start 314.355226 -236.86643)
		(end 314.58281 -236.638846)
		(width 0.16002)
		(layer "In6.Cu")
		(net "M_E_CPU0_SA_DQS_DN<3>")
	)
	(segment
		(start 288.511996 -229.21214)
		(end 287.752028 -229.21214)
		(width 0.16002)
		(layer "In6.Cu")
		(net "M_E_CPU0_SA_DQS_DN<3>")
	)
	(segment
		(start 285.018226 -228.362256)
		(end 283.976318 -228.362256)
		(width 0.16002)
		(layer "In6.Cu")
		(net "M_E_CPU0_SA_DQS_DN<3>")
	)
	(segment
		(start 302.254666 -229.29469)
		(end 301.529242 -229.29469)
		(width 0.16002)
		(layer "In6.Cu")
		(net "M_E_CPU0_SA_DQS_DN<3>")
	)
	(segment
		(start 329.171046 -242.054126)
		(end 329.017122 -241.788696)
		(width 0.09525)
		(layer "In6.Cu")
		(net "M_E_CPU0_SA_DQS_DN<3>")
	)
	(segment
		(start 279.743154 -229.21214)
		(end 279.594056 -229.361238)
		(width 0.16002)
		(layer "In6.Cu")
		(net "M_E_CPU0_SA_DQS_DN<3>")
	)
	(segment
		(start 324.578726 -241.11331)
		(end 324.10654 -240.641124)
		(width 0.09525)
		(layer "In6.Cu")
		(net "M_E_CPU0_SA_DQS_DN<3>")
	)
	(segment
		(start 298.71543 -228.710998)
		(end 298.299124 -228.710998)
		(width 0.16002)
		(layer "In6.Cu")
		(net "M_E_CPU0_SA_DQS_DN<3>")
	)
	(segment
		(start 293.902638 -229.21214)
		(end 293.052754 -228.362256)
		(width 0.16002)
		(layer "In6.Cu")
		(net "M_E_CPU0_SA_DQS_DN<3>")
	)
	(segment
		(start 323.919596 -240.69294)
		(end 323.895974 -240.69294)
		(width 0.09525)
		(layer "In6.Cu")
		(net "M_E_CPU0_SA_DQS_DN<3>")
	)
	(segment
		(start 287.752028 -229.21214)
		(end 287.491678 -229.47249)
		(width 0.16002)
		(layer "In6.Cu")
		(net "M_E_CPU0_SA_DQS_DN<3>")
	)
	(segment
		(start 282.08097 -229.81285)
		(end 281.515566 -229.81285)
		(width 0.16002)
		(layer "In6.Cu")
		(net "M_E_CPU0_SA_DQS_DN<3>")
	)
	(segment
		(start 317.137542 -239.648746)
		(end 317.365126 -239.421162)
		(width 0.16002)
		(layer "In6.Cu")
		(net "M_E_CPU0_SA_DQS_DN<3>")
	)
	(segment
		(start 312.14568 -235.133388)
		(end 311.128664 -232.678224)
		(width 0.16002)
		(layer "In6.Cu")
		(net "M_E_CPU0_SA_DQS_DN<3>")
	)
	(segment
		(start 293.052754 -228.362256)
		(end 291.520118 -228.362256)
		(width 0.16002)
		(layer "In6.Cu")
		(net "M_E_CPU0_SA_DQS_DN<3>")
	)
	(segment
		(start 299.064172 -228.362256)
		(end 298.71543 -228.710998)
		(width 0.16002)
		(layer "In6.Cu")
		(net "M_E_CPU0_SA_DQS_DN<3>")
	)
	(segment
		(start 286.12846 -229.47249)
		(end 285.018226 -228.362256)
		(width 0.16002)
		(layer "In6.Cu")
		(net "M_E_CPU0_SA_DQS_DN<3>")
	)
	(segment
		(start 308.215792 -229.765352)
		(end 307.287676 -229.765352)
		(width 0.16002)
		(layer "In6.Cu")
		(net "M_E_CPU0_SA_DQS_DN<3>")
	)
	(segment
		(start 287.491678 -229.47249)
		(end 286.12846 -229.47249)
		(width 0.16002)
		(layer "In6.Cu")
		(net "M_E_CPU0_SA_DQS_DN<3>")
	)
	(segment
		(start 289.023806 -229.72395)
		(end 288.511996 -229.21214)
		(width 0.16002)
		(layer "In6.Cu")
		(net "M_E_CPU0_SA_DQS_DN<3>")
	)
	(segment
		(start 323.971412 -240.641124)
		(end 323.919596 -240.69294)
		(width 0.09525)
		(layer "In6.Cu")
		(net "M_E_CPU0_SA_DQS_DN<3>")
	)
	(segment
		(start 326.351138 -241.677444)
		(end 325.4375 -241.677444)
		(width 0.09525)
		(layer "In6.Cu")
		(net "M_E_CPU0_SA_DQS_DN<3>")
	)
	(segment
		(start 291.171376 -228.710998)
		(end 290.75507 -228.710998)
		(width 0.16002)
		(layer "In6.Cu")
		(net "M_E_CPU0_SA_DQS_DN<3>")
	)
	(segment
		(start 290.75507 -228.710998)
		(end 289.742118 -229.72395)
		(width 0.16002)
		(layer "In6.Cu")
		(net "M_E_CPU0_SA_DQS_DN<3>")
	)
	(segment
		(start 280.914856 -229.21214)
		(end 279.743154 -229.21214)
		(width 0.16002)
		(layer "In6.Cu")
		(net "M_E_CPU0_SA_DQS_DN<3>")
	)
	(segment
		(start 316.65545 -239.166654)
		(end 316.178946 -239.166654)
		(width 0.16002)
		(layer "In6.Cu")
		(net "M_E_CPU0_SA_DQS_DN<3>")
	)
	(segment
		(start 316.883034 -238.93907)
		(end 316.65545 -239.166654)
		(width 0.16002)
		(layer "In6.Cu")
		(net "M_E_CPU0_SA_DQS_DN<3>")
	)
	(segment
		(start 317.365126 -239.421162)
		(end 317.365126 -239.195102)
		(width 0.16002)
		(layer "In6.Cu")
		(net "M_E_CPU0_SA_DQS_DN<3>")
	)
	(segment
		(start 313.39663 -236.384338)
		(end 312.14568 -235.133388)
		(width 0.16002)
		(layer "In6.Cu")
		(net "M_E_CPU0_SA_DQS_DN<3>")
	)
	(arc
		(start 327.092564 -241.735102)
		(mid 326.815402 -241.804902)
		(end 326.53986 -241.729006)
		(width 0.09525)
		(layer "In6.Cu")
		(net "M_E_CPU0_SA_DQS_DN<3>")
	)
	(arc
		(start 327.479914 -241.729006)
		(mid 327.291446 -241.678329)
		(end 327.102978 -241.729006)
		(width 0.09525)
		(layer "In6.Cu")
		(net "M_E_CPU0_SA_DQS_DN<3>")
	)
	(arc
		(start 328.042524 -241.729006)
		(mid 327.767235 -241.804727)
		(end 327.490328 -241.735102)
		(width 0.09525)
		(layer "In6.Cu")
		(net "M_E_CPU0_SA_DQS_DN<3>")
	)
	(arc
		(start 328.916284 -241.762026)
		(mid 328.906416 -241.766057)
		(end 328.896472 -241.7699)
		(width 0.09525)
		(layer "In6.Cu")
		(net "M_E_CPU0_SA_DQS_DN<3>")
	)
	(arc
		(start 326.53986 -241.729006)
		(mid 326.448914 -241.690705)
		(end 326.351138 -241.677444)
		(width 0.09525)
		(layer "In6.Cu")
		(net "M_E_CPU0_SA_DQS_DN<3>")
	)
	(arc
		(start 328.896472 -241.7699)
		(mid 328.653508 -241.802887)
		(end 328.419714 -241.729006)
		(width 0.09525)
		(layer "In6.Cu")
		(net "M_E_CPU0_SA_DQS_DN<3>")
	)
	(arc
		(start 328.411332 -241.72418)
		(mid 328.2263 -241.678266)
		(end 328.042524 -241.729006)
		(width 0.09525)
		(layer "In6.Cu")
		(net "M_E_CPU0_SA_DQS_DN<3>")
	)
	(segment
		(start 329.637898 -237.460028)
		(end 329.171046 -237.19409)
		(width 0.12954)
		(layer "F.Cu")
		(net "M_E_CPU0_SA_DQS_DN<2>")
	)
	(segment
		(start 283.976318 -219.012262)
		(end 283.627576 -219.361004)
		(width 0.16002)
		(layer "In6.Cu")
		(net "M_E_CPU0_SA_DQS_DN<2>")
	)
	(segment
		(start 326.351138 -236.817408)
		(end 326.107044 -236.817408)
		(width 0.09525)
		(layer "In6.Cu")
		(net "M_E_CPU0_SA_DQS_DN<2>")
	)
	(segment
		(start 327.490328 -236.875066)
		(end 327.479914 -236.86897)
		(width 0.09525)
		(layer "In6.Cu")
		(net "M_E_CPU0_SA_DQS_DN<2>")
	)
	(segment
		(start 311.169558 -223.614234)
		(end 311.169558 -220.013784)
		(width 0.16002)
		(layer "In6.Cu")
		(net "M_E_CPU0_SA_DQS_DN<2>")
	)
	(segment
		(start 323.919596 -235.041186)
		(end 323.895974 -235.041186)
		(width 0.09525)
		(layer "In6.Cu")
		(net "M_E_CPU0_SA_DQS_DN<2>")
	)
	(segment
		(start 302.481742 -219.87764)
		(end 301.462186 -219.87764)
		(width 0.16002)
		(layer "In6.Cu")
		(net "M_E_CPU0_SA_DQS_DN<2>")
	)
	(segment
		(start 279.743154 -219.862146)
		(end 279.594056 -220.011244)
		(width 0.16002)
		(layer "In6.Cu")
		(net "M_E_CPU0_SA_DQS_DN<2>")
	)
	(segment
		(start 309.870348 -220.486732)
		(end 309.259224 -220.486732)
		(width 0.16002)
		(layer "In6.Cu")
		(net "M_E_CPU0_SA_DQS_DN<2>")
	)
	(segment
		(start 325.067168 -235.777532)
		(end 324.6374 -235.777532)
		(width 0.09525)
		(layer "In6.Cu")
		(net "M_E_CPU0_SA_DQS_DN<2>")
	)
	(segment
		(start 323.978778 -234.982004)
		(end 323.919596 -235.041186)
		(width 0.09525)
		(layer "In6.Cu")
		(net "M_E_CPU0_SA_DQS_DN<2>")
	)
	(segment
		(start 293.902638 -219.862146)
		(end 293.052754 -219.012262)
		(width 0.16002)
		(layer "In6.Cu")
		(net "M_E_CPU0_SA_DQS_DN<2>")
	)
	(segment
		(start 289.647884 -220.46819)
		(end 289.010344 -220.46819)
		(width 0.16002)
		(layer "In6.Cu")
		(net "M_E_CPU0_SA_DQS_DN<2>")
	)
	(segment
		(start 308.762146 -219.369132)
		(end 308.401466 -219.369132)
		(width 0.16002)
		(layer "In6.Cu")
		(net "M_E_CPU0_SA_DQS_DN<2>")
	)
	(segment
		(start 313.521598 -227.004626)
		(end 313.521598 -225.966274)
		(width 0.16002)
		(layer "In6.Cu")
		(net "M_E_CPU0_SA_DQS_DN<2>")
	)
	(segment
		(start 291.520118 -219.012262)
		(end 291.171376 -219.361004)
		(width 0.16002)
		(layer "In6.Cu")
		(net "M_E_CPU0_SA_DQS_DN<2>")
	)
	(segment
		(start 311.169558 -220.013784)
		(end 310.794146 -219.638372)
		(width 0.16002)
		(layer "In6.Cu")
		(net "M_E_CPU0_SA_DQS_DN<2>")
	)
	(segment
		(start 323.895974 -235.041186)
		(end 321.558158 -235.041186)
		(width 0.16002)
		(layer "In6.Cu")
		(net "M_E_CPU0_SA_DQS_DN<2>")
	)
	(segment
		(start 304.603912 -220.60027)
		(end 303.204372 -220.60027)
		(width 0.16002)
		(layer "In6.Cu")
		(net "M_E_CPU0_SA_DQS_DN<2>")
	)
	(segment
		(start 282.085796 -220.45803)
		(end 281.476704 -220.45803)
		(width 0.16002)
		(layer "In6.Cu")
		(net "M_E_CPU0_SA_DQS_DN<2>")
	)
	(segment
		(start 328.419714 -236.86897)
		(end 328.411332 -236.864144)
		(width 0.09525)
		(layer "In6.Cu")
		(net "M_E_CPU0_SA_DQS_DN<2>")
	)
	(segment
		(start 308.922166 -219.529152)
		(end 308.762146 -219.369132)
		(width 0.16002)
		(layer "In6.Cu")
		(net "M_E_CPU0_SA_DQS_DN<2>")
	)
	(segment
		(start 308.401466 -219.369132)
		(end 308.241446 -219.529152)
		(width 0.16002)
		(layer "In6.Cu")
		(net "M_E_CPU0_SA_DQS_DN<2>")
	)
	(segment
		(start 308.241446 -220.149674)
		(end 307.904388 -220.486732)
		(width 0.16002)
		(layer "In6.Cu")
		(net "M_E_CPU0_SA_DQS_DN<2>")
	)
	(segment
		(start 277.466044 -220.011244)
		(end 277.192232 -220.285056)
		(width 0.16002)
		(layer "In6.Cu")
		(net "M_E_CPU0_SA_DQS_DN<2>")
	)
	(segment
		(start 297.191938 -220.46819)
		(end 296.582338 -220.46819)
		(width 0.16002)
		(layer "In6.Cu")
		(net "M_E_CPU0_SA_DQS_DN<2>")
	)
	(segment
		(start 305.843178 -219.361004)
		(end 304.603912 -220.60027)
		(width 0.16002)
		(layer "In6.Cu")
		(net "M_E_CPU0_SA_DQS_DN<2>")
	)
	(segment
		(start 324.199504 -235.077254)
		(end 324.104254 -234.982004)
		(width 0.09525)
		(layer "In6.Cu")
		(net "M_E_CPU0_SA_DQS_DN<2>")
	)
	(segment
		(start 324.6374 -235.777532)
		(end 324.199504 -235.339636)
		(width 0.09525)
		(layer "In6.Cu")
		(net "M_E_CPU0_SA_DQS_DN<2>")
	)
	(segment
		(start 295.976294 -219.862146)
		(end 293.902638 -219.862146)
		(width 0.16002)
		(layer "In6.Cu")
		(net "M_E_CPU0_SA_DQS_DN<2>")
	)
	(segment
		(start 324.104254 -234.982004)
		(end 323.978778 -234.982004)
		(width 0.09525)
		(layer "In6.Cu")
		(net "M_E_CPU0_SA_DQS_DN<2>")
	)
	(segment
		(start 308.922166 -220.149674)
		(end 308.922166 -219.529152)
		(width 0.16002)
		(layer "In6.Cu")
		(net "M_E_CPU0_SA_DQS_DN<2>")
	)
	(segment
		(start 301.462186 -219.87764)
		(end 300.596808 -219.012262)
		(width 0.16002)
		(layer "In6.Cu")
		(net "M_E_CPU0_SA_DQS_DN<2>")
	)
	(segment
		(start 309.259224 -220.486732)
		(end 308.922166 -220.149674)
		(width 0.16002)
		(layer "In6.Cu")
		(net "M_E_CPU0_SA_DQS_DN<2>")
	)
	(segment
		(start 288.4043 -219.862146)
		(end 286.357822 -219.862146)
		(width 0.16002)
		(layer "In6.Cu")
		(net "M_E_CPU0_SA_DQS_DN<2>")
	)
	(segment
		(start 279.594056 -220.011244)
		(end 277.466044 -220.011244)
		(width 0.16002)
		(layer "In6.Cu")
		(net "M_E_CPU0_SA_DQS_DN<2>")
	)
	(segment
		(start 306.956206 -220.149674)
		(end 306.956206 -219.521024)
		(width 0.16002)
		(layer "In6.Cu")
		(net "M_E_CPU0_SA_DQS_DN<2>")
	)
	(segment
		(start 313.521598 -225.966274)
		(end 311.169558 -223.614234)
		(width 0.16002)
		(layer "In6.Cu")
		(net "M_E_CPU0_SA_DQS_DN<2>")
	)
	(segment
		(start 299.064172 -219.012262)
		(end 298.71543 -219.361004)
		(width 0.16002)
		(layer "In6.Cu")
		(net "M_E_CPU0_SA_DQS_DN<2>")
	)
	(segment
		(start 283.627576 -219.361004)
		(end 283.182822 -219.361004)
		(width 0.16002)
		(layer "In6.Cu")
		(net "M_E_CPU0_SA_DQS_DN<2>")
	)
	(segment
		(start 329.017122 -236.92866)
		(end 328.916284 -236.90199)
		(width 0.09525)
		(layer "In6.Cu")
		(net "M_E_CPU0_SA_DQS_DN<2>")
	)
	(segment
		(start 310.207406 -219.798392)
		(end 310.207406 -220.149674)
		(width 0.16002)
		(layer "In6.Cu")
		(net "M_E_CPU0_SA_DQS_DN<2>")
	)
	(segment
		(start 303.204372 -220.60027)
		(end 302.481742 -219.87764)
		(width 0.16002)
		(layer "In6.Cu")
		(net "M_E_CPU0_SA_DQS_DN<2>")
	)
	(segment
		(start 307.293264 -220.486732)
		(end 306.956206 -220.149674)
		(width 0.16002)
		(layer "In6.Cu")
		(net "M_E_CPU0_SA_DQS_DN<2>")
	)
	(segment
		(start 321.558158 -235.041186)
		(end 313.521598 -227.004626)
		(width 0.16002)
		(layer "In6.Cu")
		(net "M_E_CPU0_SA_DQS_DN<2>")
	)
	(segment
		(start 308.241446 -219.529152)
		(end 308.241446 -220.149674)
		(width 0.16002)
		(layer "In6.Cu")
		(net "M_E_CPU0_SA_DQS_DN<2>")
	)
	(segment
		(start 289.010344 -220.46819)
		(end 288.4043 -219.862146)
		(width 0.16002)
		(layer "In6.Cu")
		(net "M_E_CPU0_SA_DQS_DN<2>")
	)
	(segment
		(start 326.107044 -236.817408)
		(end 325.067168 -235.777532)
		(width 0.09525)
		(layer "In6.Cu")
		(net "M_E_CPU0_SA_DQS_DN<2>")
	)
	(segment
		(start 298.299124 -219.361004)
		(end 297.191938 -220.46819)
		(width 0.16002)
		(layer "In6.Cu")
		(net "M_E_CPU0_SA_DQS_DN<2>")
	)
	(segment
		(start 286.357822 -219.862146)
		(end 285.507938 -219.012262)
		(width 0.16002)
		(layer "In6.Cu")
		(net "M_E_CPU0_SA_DQS_DN<2>")
	)
	(segment
		(start 285.507938 -219.012262)
		(end 283.976318 -219.012262)
		(width 0.16002)
		(layer "In6.Cu")
		(net "M_E_CPU0_SA_DQS_DN<2>")
	)
	(segment
		(start 310.794146 -219.638372)
		(end 310.367426 -219.638372)
		(width 0.16002)
		(layer "In6.Cu")
		(net "M_E_CPU0_SA_DQS_DN<2>")
	)
	(segment
		(start 306.956206 -219.521024)
		(end 306.796186 -219.361004)
		(width 0.16002)
		(layer "In6.Cu")
		(net "M_E_CPU0_SA_DQS_DN<2>")
	)
	(segment
		(start 300.596808 -219.012262)
		(end 299.064172 -219.012262)
		(width 0.16002)
		(layer "In6.Cu")
		(net "M_E_CPU0_SA_DQS_DN<2>")
	)
	(segment
		(start 290.75507 -219.361004)
		(end 289.647884 -220.46819)
		(width 0.16002)
		(layer "In6.Cu")
		(net "M_E_CPU0_SA_DQS_DN<2>")
	)
	(segment
		(start 293.052754 -219.012262)
		(end 291.520118 -219.012262)
		(width 0.16002)
		(layer "In6.Cu")
		(net "M_E_CPU0_SA_DQS_DN<2>")
	)
	(segment
		(start 281.476704 -220.45803)
		(end 280.88082 -219.862146)
		(width 0.16002)
		(layer "In6.Cu")
		(net "M_E_CPU0_SA_DQS_DN<2>")
	)
	(segment
		(start 324.199504 -235.339636)
		(end 324.199504 -235.077254)
		(width 0.09525)
		(layer "In6.Cu")
		(net "M_E_CPU0_SA_DQS_DN<2>")
	)
	(segment
		(start 327.102978 -236.86897)
		(end 327.092564 -236.875066)
		(width 0.09525)
		(layer "In6.Cu")
		(net "M_E_CPU0_SA_DQS_DN<2>")
	)
	(segment
		(start 298.71543 -219.361004)
		(end 298.299124 -219.361004)
		(width 0.16002)
		(layer "In6.Cu")
		(net "M_E_CPU0_SA_DQS_DN<2>")
	)
	(segment
		(start 306.796186 -219.361004)
		(end 305.843178 -219.361004)
		(width 0.16002)
		(layer "In6.Cu")
		(net "M_E_CPU0_SA_DQS_DN<2>")
	)
	(segment
		(start 310.367426 -219.638372)
		(end 310.207406 -219.798392)
		(width 0.16002)
		(layer "In6.Cu")
		(net "M_E_CPU0_SA_DQS_DN<2>")
	)
	(segment
		(start 280.88082 -219.862146)
		(end 279.743154 -219.862146)
		(width 0.16002)
		(layer "In6.Cu")
		(net "M_E_CPU0_SA_DQS_DN<2>")
	)
	(segment
		(start 307.904388 -220.486732)
		(end 307.293264 -220.486732)
		(width 0.16002)
		(layer "In6.Cu")
		(net "M_E_CPU0_SA_DQS_DN<2>")
	)
	(segment
		(start 283.182822 -219.361004)
		(end 282.085796 -220.45803)
		(width 0.16002)
		(layer "In6.Cu")
		(net "M_E_CPU0_SA_DQS_DN<2>")
	)
	(segment
		(start 310.207406 -220.149674)
		(end 309.870348 -220.486732)
		(width 0.16002)
		(layer "In6.Cu")
		(net "M_E_CPU0_SA_DQS_DN<2>")
	)
	(segment
		(start 291.171376 -219.361004)
		(end 290.75507 -219.361004)
		(width 0.16002)
		(layer "In6.Cu")
		(net "M_E_CPU0_SA_DQS_DN<2>")
	)
	(segment
		(start 296.582338 -220.46819)
		(end 295.976294 -219.862146)
		(width 0.16002)
		(layer "In6.Cu")
		(net "M_E_CPU0_SA_DQS_DN<2>")
	)
	(segment
		(start 329.171046 -237.19409)
		(end 329.017122 -236.92866)
		(width 0.09525)
		(layer "In6.Cu")
		(net "M_E_CPU0_SA_DQS_DN<2>")
	)
	(arc
		(start 328.896472 -236.909864)
		(mid 328.653508 -236.942851)
		(end 328.419714 -236.86897)
		(width 0.09525)
		(layer "In6.Cu")
		(net "M_E_CPU0_SA_DQS_DN<2>")
	)
	(arc
		(start 327.479914 -236.86897)
		(mid 327.291446 -236.818293)
		(end 327.102978 -236.86897)
		(width 0.09525)
		(layer "In6.Cu")
		(net "M_E_CPU0_SA_DQS_DN<2>")
	)
	(arc
		(start 328.411332 -236.864144)
		(mid 328.2263 -236.81823)
		(end 328.042524 -236.86897)
		(width 0.09525)
		(layer "In6.Cu")
		(net "M_E_CPU0_SA_DQS_DN<2>")
	)
	(arc
		(start 328.042524 -236.86897)
		(mid 327.767235 -236.944691)
		(end 327.490328 -236.875066)
		(width 0.09525)
		(layer "In6.Cu")
		(net "M_E_CPU0_SA_DQS_DN<2>")
	)
	(arc
		(start 326.53986 -236.86897)
		(mid 326.448914 -236.830669)
		(end 326.351138 -236.817408)
		(width 0.09525)
		(layer "In6.Cu")
		(net "M_E_CPU0_SA_DQS_DN<2>")
	)
	(arc
		(start 327.092564 -236.875066)
		(mid 326.815402 -236.944866)
		(end 326.53986 -236.86897)
		(width 0.09525)
		(layer "In6.Cu")
		(net "M_E_CPU0_SA_DQS_DN<2>")
	)
	(arc
		(start 328.916284 -236.90199)
		(mid 328.906416 -236.906021)
		(end 328.896472 -236.909864)
		(width 0.09525)
		(layer "In6.Cu")
		(net "M_E_CPU0_SA_DQS_DN<2>")
	)
	(segment
		(start 329.637898 -232.599992)
		(end 329.171046 -232.334054)
		(width 0.12954)
		(layer "F.Cu")
		(net "M_E_CPU0_SA_DQS_DN<1>")
	)
	(segment
		(start 310.058816 -211.878926)
		(end 309.516272 -212.42147)
		(width 0.16002)
		(layer "In6.Cu")
		(net "M_E_CPU0_SA_DQS_DN<1>")
	)
	(segment
		(start 293.902638 -210.512152)
		(end 293.052754 -209.662268)
		(width 0.16002)
		(layer "In6.Cu")
		(net "M_E_CPU0_SA_DQS_DN<1>")
	)
	(segment
		(start 323.60362 -228.942138)
		(end 323.5198 -228.942138)
		(width 0.09525)
		(layer "In6.Cu")
		(net "M_E_CPU0_SA_DQS_DN<1>")
	)
	(segment
		(start 310.45023 -213.831932)
		(end 309.998364 -213.380066)
		(width 0.16002)
		(layer "In6.Cu")
		(net "M_E_CPU0_SA_DQS_DN<1>")
	)
	(segment
		(start 327.490328 -232.01503)
		(end 327.479914 -232.008934)
		(width 0.09525)
		(layer "In6.Cu")
		(net "M_E_CPU0_SA_DQS_DN<1>")
	)
	(segment
		(start 328.419714 -232.008934)
		(end 328.411332 -232.004108)
		(width 0.09525)
		(layer "In6.Cu")
		(net "M_E_CPU0_SA_DQS_DN<1>")
	)
	(segment
		(start 329.171046 -232.334054)
		(end 329.017122 -232.068624)
		(width 0.09525)
		(layer "In6.Cu")
		(net "M_E_CPU0_SA_DQS_DN<1>")
	)
	(segment
		(start 316.871096 -217.881962)
		(end 312.821066 -213.831932)
		(width 0.16002)
		(layer "In6.Cu")
		(net "M_E_CPU0_SA_DQS_DN<1>")
	)
	(segment
		(start 282.352242 -210.84159)
		(end 281.71521 -210.84159)
		(width 0.16002)
		(layer "In6.Cu")
		(net "M_E_CPU0_SA_DQS_DN<1>")
	)
	(segment
		(start 289.74415 -211.02193)
		(end 289.081718 -211.02193)
		(width 0.16002)
		(layer "In6.Cu")
		(net "M_E_CPU0_SA_DQS_DN<1>")
	)
	(segment
		(start 303.056798 -211.27339)
		(end 302.406558 -210.62315)
		(width 0.16002)
		(layer "In6.Cu")
		(net "M_E_CPU0_SA_DQS_DN<1>")
	)
	(segment
		(start 306.629308 -210.01101)
		(end 305.843178 -210.01101)
		(width 0.16002)
		(layer "In6.Cu")
		(net "M_E_CPU0_SA_DQS_DN<1>")
	)
	(segment
		(start 308.893718 -210.487768)
		(end 308.667658 -210.487768)
		(width 0.16002)
		(layer "In6.Cu")
		(net "M_E_CPU0_SA_DQS_DN<1>")
	)
	(segment
		(start 291.171376 -210.01101)
		(end 290.75507 -210.01101)
		(width 0.16002)
		(layer "In6.Cu")
		(net "M_E_CPU0_SA_DQS_DN<1>")
	)
	(segment
		(start 310.540908 -212.134958)
		(end 310.284876 -211.878926)
		(width 0.16002)
		(layer "In6.Cu")
		(net "M_E_CPU0_SA_DQS_DN<1>")
	)
	(segment
		(start 298.299124 -210.01101)
		(end 297.204384 -211.10575)
		(width 0.16002)
		(layer "In6.Cu")
		(net "M_E_CPU0_SA_DQS_DN<1>")
	)
	(segment
		(start 326.425052 -231.920542)
		(end 325.234554 -230.730044)
		(width 0.09525)
		(layer "In6.Cu")
		(net "M_E_CPU0_SA_DQS_DN<1>")
	)
	(segment
		(start 308.607206 -211.512404)
		(end 309.14975 -210.96986)
		(width 0.16002)
		(layer "In6.Cu")
		(net "M_E_CPU0_SA_DQS_DN<1>")
	)
	(segment
		(start 281.71521 -210.84159)
		(end 281.385772 -210.512152)
		(width 0.16002)
		(layer "In6.Cu")
		(net "M_E_CPU0_SA_DQS_DN<1>")
	)
	(segment
		(start 307.64861 -211.030312)
		(end 306.629308 -210.01101)
		(width 0.16002)
		(layer "In6.Cu")
		(net "M_E_CPU0_SA_DQS_DN<1>")
	)
	(segment
		(start 296.594784 -211.10575)
		(end 296.001186 -210.512152)
		(width 0.16002)
		(layer "In6.Cu")
		(net "M_E_CPU0_SA_DQS_DN<1>")
	)
	(segment
		(start 309.998364 -212.903562)
		(end 310.540908 -212.361018)
		(width 0.16002)
		(layer "In6.Cu")
		(net "M_E_CPU0_SA_DQS_DN<1>")
	)
	(segment
		(start 324.91299 -229.81031)
		(end 324.471792 -229.81031)
		(width 0.09525)
		(layer "In6.Cu")
		(net "M_E_CPU0_SA_DQS_DN<1>")
	)
	(segment
		(start 290.75507 -210.01101)
		(end 289.74415 -211.02193)
		(width 0.16002)
		(layer "In6.Cu")
		(net "M_E_CPU0_SA_DQS_DN<1>")
	)
	(segment
		(start 305.843178 -210.01101)
		(end 304.580798 -211.27339)
		(width 0.16002)
		(layer "In6.Cu")
		(net "M_E_CPU0_SA_DQS_DN<1>")
	)
	(segment
		(start 308.667658 -210.487768)
		(end 308.125114 -211.030312)
		(width 0.16002)
		(layer "In6.Cu")
		(net "M_E_CPU0_SA_DQS_DN<1>")
	)
	(segment
		(start 309.039768 -212.42147)
		(end 308.607206 -211.988908)
		(width 0.16002)
		(layer "In6.Cu")
		(net "M_E_CPU0_SA_DQS_DN<1>")
	)
	(segment
		(start 291.520118 -209.662268)
		(end 291.171376 -210.01101)
		(width 0.16002)
		(layer "In6.Cu")
		(net "M_E_CPU0_SA_DQS_DN<1>")
	)
	(segment
		(start 298.71543 -210.01101)
		(end 298.299124 -210.01101)
		(width 0.16002)
		(layer "In6.Cu")
		(net "M_E_CPU0_SA_DQS_DN<1>")
	)
	(segment
		(start 325.234554 -230.730044)
		(end 325.234554 -230.131874)
		(width 0.09525)
		(layer "In6.Cu")
		(net "M_E_CPU0_SA_DQS_DN<1>")
	)
	(segment
		(start 310.540908 -212.361018)
		(end 310.540908 -212.134958)
		(width 0.16002)
		(layer "In6.Cu")
		(net "M_E_CPU0_SA_DQS_DN<1>")
	)
	(segment
		(start 316.871096 -221.469204)
		(end 316.871096 -217.881962)
		(width 0.16002)
		(layer "In6.Cu")
		(net "M_E_CPU0_SA_DQS_DN<1>")
	)
	(segment
		(start 323.5198 -228.942138)
		(end 323.503036 -228.925374)
		(width 0.09525)
		(layer "In6.Cu")
		(net "M_E_CPU0_SA_DQS_DN<1>")
	)
	(segment
		(start 299.064172 -209.662268)
		(end 298.71543 -210.01101)
		(width 0.16002)
		(layer "In6.Cu")
		(net "M_E_CPU0_SA_DQS_DN<1>")
	)
	(segment
		(start 308.125114 -211.030312)
		(end 307.64861 -211.030312)
		(width 0.16002)
		(layer "In6.Cu")
		(net "M_E_CPU0_SA_DQS_DN<1>")
	)
	(segment
		(start 296.001186 -210.512152)
		(end 293.902638 -210.512152)
		(width 0.16002)
		(layer "In6.Cu")
		(net "M_E_CPU0_SA_DQS_DN<1>")
	)
	(segment
		(start 329.017122 -232.068624)
		(end 328.916284 -232.041954)
		(width 0.09525)
		(layer "In6.Cu")
		(net "M_E_CPU0_SA_DQS_DN<1>")
	)
	(segment
		(start 309.516272 -212.42147)
		(end 309.039768 -212.42147)
		(width 0.16002)
		(layer "In6.Cu")
		(net "M_E_CPU0_SA_DQS_DN<1>")
	)
	(segment
		(start 288.57194 -210.512152)
		(end 286.220662 -210.512152)
		(width 0.16002)
		(layer "In6.Cu")
		(net "M_E_CPU0_SA_DQS_DN<1>")
	)
	(segment
		(start 283.976318 -209.662268)
		(end 283.627576 -210.01101)
		(width 0.16002)
		(layer "In6.Cu")
		(net "M_E_CPU0_SA_DQS_DN<1>")
	)
	(segment
		(start 279.743154 -210.512152)
		(end 279.594056 -210.66125)
		(width 0.16002)
		(layer "In6.Cu")
		(net "M_E_CPU0_SA_DQS_DN<1>")
	)
	(segment
		(start 293.052754 -209.662268)
		(end 291.520118 -209.662268)
		(width 0.16002)
		(layer "In6.Cu")
		(net "M_E_CPU0_SA_DQS_DN<1>")
	)
	(segment
		(start 325.234554 -230.131874)
		(end 324.91299 -229.81031)
		(width 0.09525)
		(layer "In6.Cu")
		(net "M_E_CPU0_SA_DQS_DN<1>")
	)
	(segment
		(start 286.220662 -210.512152)
		(end 285.370778 -209.662268)
		(width 0.16002)
		(layer "In6.Cu")
		(net "M_E_CPU0_SA_DQS_DN<1>")
	)
	(segment
		(start 283.182822 -210.01101)
		(end 282.352242 -210.84159)
		(width 0.16002)
		(layer "In6.Cu")
		(net "M_E_CPU0_SA_DQS_DN<1>")
	)
	(segment
		(start 302.406558 -210.62315)
		(end 301.55769 -210.62315)
		(width 0.16002)
		(layer "In6.Cu")
		(net "M_E_CPU0_SA_DQS_DN<1>")
	)
	(segment
		(start 304.580798 -211.27339)
		(end 303.056798 -211.27339)
		(width 0.16002)
		(layer "In6.Cu")
		(net "M_E_CPU0_SA_DQS_DN<1>")
	)
	(segment
		(start 285.370778 -209.662268)
		(end 283.976318 -209.662268)
		(width 0.16002)
		(layer "In6.Cu")
		(net "M_E_CPU0_SA_DQS_DN<1>")
	)
	(segment
		(start 312.821066 -213.831932)
		(end 310.45023 -213.831932)
		(width 0.16002)
		(layer "In6.Cu")
		(net "M_E_CPU0_SA_DQS_DN<1>")
	)
	(segment
		(start 309.14975 -210.96986)
		(end 309.14975 -210.7438)
		(width 0.16002)
		(layer "In6.Cu")
		(net "M_E_CPU0_SA_DQS_DN<1>")
	)
	(segment
		(start 324.471792 -229.81031)
		(end 323.60362 -228.942138)
		(width 0.09525)
		(layer "In6.Cu")
		(net "M_E_CPU0_SA_DQS_DN<1>")
	)
	(segment
		(start 300.596808 -209.662268)
		(end 299.064172 -209.662268)
		(width 0.16002)
		(layer "In6.Cu")
		(net "M_E_CPU0_SA_DQS_DN<1>")
	)
	(segment
		(start 283.627576 -210.01101)
		(end 283.182822 -210.01101)
		(width 0.16002)
		(layer "In6.Cu")
		(net "M_E_CPU0_SA_DQS_DN<1>")
	)
	(segment
		(start 319.061338 -224.483676)
		(end 319.061338 -223.659446)
		(width 0.16002)
		(layer "In6.Cu")
		(net "M_E_CPU0_SA_DQS_DN<1>")
	)
	(segment
		(start 289.081718 -211.02193)
		(end 288.57194 -210.512152)
		(width 0.16002)
		(layer "In6.Cu")
		(net "M_E_CPU0_SA_DQS_DN<1>")
	)
	(segment
		(start 297.204384 -211.10575)
		(end 296.594784 -211.10575)
		(width 0.16002)
		(layer "In6.Cu")
		(net "M_E_CPU0_SA_DQS_DN<1>")
	)
	(segment
		(start 323.503036 -228.925374)
		(end 319.061338 -224.483676)
		(width 0.16002)
		(layer "In6.Cu")
		(net "M_E_CPU0_SA_DQS_DN<1>")
	)
	(segment
		(start 309.14975 -210.7438)
		(end 308.893718 -210.487768)
		(width 0.16002)
		(layer "In6.Cu")
		(net "M_E_CPU0_SA_DQS_DN<1>")
	)
	(segment
		(start 310.284876 -211.878926)
		(end 310.058816 -211.878926)
		(width 0.16002)
		(layer "In6.Cu")
		(net "M_E_CPU0_SA_DQS_DN<1>")
	)
	(segment
		(start 309.998364 -213.380066)
		(end 309.998364 -212.903562)
		(width 0.16002)
		(layer "In6.Cu")
		(net "M_E_CPU0_SA_DQS_DN<1>")
	)
	(segment
		(start 277.466044 -210.66125)
		(end 277.192232 -210.935062)
		(width 0.16002)
		(layer "In6.Cu")
		(net "M_E_CPU0_SA_DQS_DN<1>")
	)
	(segment
		(start 327.102978 -232.008934)
		(end 327.092564 -232.01503)
		(width 0.09525)
		(layer "In6.Cu")
		(net "M_E_CPU0_SA_DQS_DN<1>")
	)
	(segment
		(start 279.594056 -210.66125)
		(end 277.466044 -210.66125)
		(width 0.16002)
		(layer "In6.Cu")
		(net "M_E_CPU0_SA_DQS_DN<1>")
	)
	(segment
		(start 301.55769 -210.62315)
		(end 300.596808 -209.662268)
		(width 0.16002)
		(layer "In6.Cu")
		(net "M_E_CPU0_SA_DQS_DN<1>")
	)
	(segment
		(start 319.061338 -223.659446)
		(end 316.871096 -221.469204)
		(width 0.16002)
		(layer "In6.Cu")
		(net "M_E_CPU0_SA_DQS_DN<1>")
	)
	(segment
		(start 281.385772 -210.512152)
		(end 279.743154 -210.512152)
		(width 0.16002)
		(layer "In6.Cu")
		(net "M_E_CPU0_SA_DQS_DN<1>")
	)
	(segment
		(start 308.607206 -211.988908)
		(end 308.607206 -211.512404)
		(width 0.16002)
		(layer "In6.Cu")
		(net "M_E_CPU0_SA_DQS_DN<1>")
	)
	(arc
		(start 328.042524 -232.008934)
		(mid 327.767235 -232.084655)
		(end 327.490328 -232.01503)
		(width 0.09525)
		(layer "In6.Cu")
		(net "M_E_CPU0_SA_DQS_DN<1>")
	)
	(arc
		(start 327.479914 -232.008934)
		(mid 327.291446 -231.958257)
		(end 327.102978 -232.008934)
		(width 0.09525)
		(layer "In6.Cu")
		(net "M_E_CPU0_SA_DQS_DN<1>")
	)
	(arc
		(start 328.916284 -232.041954)
		(mid 328.906416 -232.045985)
		(end 328.896472 -232.049828)
		(width 0.09525)
		(layer "In6.Cu")
		(net "M_E_CPU0_SA_DQS_DN<1>")
	)
	(arc
		(start 326.540114 -232.008934)
		(mid 326.47971 -231.968478)
		(end 326.425052 -231.920542)
		(width 0.09525)
		(layer "In6.Cu")
		(net "M_E_CPU0_SA_DQS_DN<1>")
	)
	(arc
		(start 328.411332 -232.004108)
		(mid 328.2263 -231.958194)
		(end 328.042524 -232.008934)
		(width 0.09525)
		(layer "In6.Cu")
		(net "M_E_CPU0_SA_DQS_DN<1>")
	)
	(arc
		(start 327.092564 -232.01503)
		(mid 326.815547 -232.084706)
		(end 326.540114 -232.008934)
		(width 0.09525)
		(layer "In6.Cu")
		(net "M_E_CPU0_SA_DQS_DN<1>")
	)
	(arc
		(start 328.896472 -232.049828)
		(mid 328.653508 -232.082815)
		(end 328.419714 -232.008934)
		(width 0.09525)
		(layer "In6.Cu")
		(net "M_E_CPU0_SA_DQS_DN<1>")
	)
	(segment
		(start 329.637898 -227.74021)
		(end 329.171046 -227.474272)
		(width 0.12954)
		(layer "F.Cu")
		(net "M_E_CPU0_SA_DQS_DN<0>")
	)
	(segment
		(start 309.919878 -201.79792)
		(end 309.508144 -202.209654)
		(width 0.16002)
		(layer "In6.Cu")
		(net "M_E_CPU0_SA_DQS_DN<0>")
	)
	(segment
		(start 309.990236 -203.16825)
		(end 309.990236 -202.691746)
		(width 0.16002)
		(layer "In6.Cu")
		(net "M_E_CPU0_SA_DQS_DN<0>")
	)
	(segment
		(start 325.778368 -222.594678)
		(end 325.778368 -222.402654)
		(width 0.09525)
		(layer "In6.Cu")
		(net "M_E_CPU0_SA_DQS_DN<0>")
	)
	(segment
		(start 293.052754 -200.312274)
		(end 291.520118 -200.312274)
		(width 0.16002)
		(layer "In6.Cu")
		(net "M_E_CPU0_SA_DQS_DN<0>")
	)
	(segment
		(start 326.574404 -223.929194)
		(end 326.539606 -223.909128)
		(width 0.09525)
		(layer "In6.Cu")
		(net "M_E_CPU0_SA_DQS_DN<0>")
	)
	(segment
		(start 312.772552 -205.474062)
		(end 313.184286 -205.062328)
		(width 0.16002)
		(layer "In6.Cu")
		(net "M_E_CPU0_SA_DQS_DN<0>")
	)
	(segment
		(start 312.702194 -204.580236)
		(end 312.29046 -204.99197)
		(width 0.16002)
		(layer "In6.Cu")
		(net "M_E_CPU0_SA_DQS_DN<0>")
	)
	(segment
		(start 283.182822 -200.661016)
		(end 282.352242 -201.491596)
		(width 0.16002)
		(layer "In6.Cu")
		(net "M_E_CPU0_SA_DQS_DN<0>")
	)
	(segment
		(start 312.928254 -204.580236)
		(end 312.702194 -204.580236)
		(width 0.16002)
		(layer "In6.Cu")
		(net "M_E_CPU0_SA_DQS_DN<0>")
	)
	(segment
		(start 327.490328 -227.155248)
		(end 327.479914 -227.149152)
		(width 0.09525)
		(layer "In6.Cu")
		(net "M_E_CPU0_SA_DQS_DN<0>")
	)
	(segment
		(start 328.419714 -227.149152)
		(end 328.411332 -227.144326)
		(width 0.09525)
		(layer "In6.Cu")
		(net "M_E_CPU0_SA_DQS_DN<0>")
	)
	(segment
		(start 281.385772 -201.162158)
		(end 279.750774 -201.162158)
		(width 0.16002)
		(layer "In6.Cu")
		(net "M_E_CPU0_SA_DQS_DN<0>")
	)
	(segment
		(start 311.537096 -203.189078)
		(end 311.311036 -203.189078)
		(width 0.16002)
		(layer "In6.Cu")
		(net "M_E_CPU0_SA_DQS_DN<0>")
	)
	(segment
		(start 283.976318 -200.312274)
		(end 283.627576 -200.661016)
		(width 0.16002)
		(layer "In6.Cu")
		(net "M_E_CPU0_SA_DQS_DN<0>")
	)
	(segment
		(start 305.019964 -201.48423)
		(end 304.262282 -201.48423)
		(width 0.16002)
		(layer "In6.Cu")
		(net "M_E_CPU0_SA_DQS_DN<0>")
	)
	(segment
		(start 293.902638 -201.162158)
		(end 293.052754 -200.312274)
		(width 0.16002)
		(layer "In6.Cu")
		(net "M_E_CPU0_SA_DQS_DN<0>")
	)
	(segment
		(start 326.539606 -225.52914)
		(end 326.504554 -225.508566)
		(width 0.09525)
		(layer "In6.Cu")
		(net "M_E_CPU0_SA_DQS_DN<0>")
	)
	(segment
		(start 325.63054 -222.254826)
		(end 325.546466 -222.254826)
		(width 0.09525)
		(layer "In6.Cu")
		(net "M_E_CPU0_SA_DQS_DN<0>")
	)
	(segment
		(start 286.231838 -201.162158)
		(end 285.381954 -200.312274)
		(width 0.16002)
		(layer "In6.Cu")
		(net "M_E_CPU0_SA_DQS_DN<0>")
	)
	(segment
		(start 326.504554 -224.579942)
		(end 326.539606 -224.559368)
		(width 0.09525)
		(layer "In6.Cu")
		(net "M_E_CPU0_SA_DQS_DN<0>")
	)
	(segment
		(start 322.698618 -215.207088)
		(end 314.470542 -206.979012)
		(width 0.16002)
		(layer "In6.Cu")
		(net "M_E_CPU0_SA_DQS_DN<0>")
	)
	(segment
		(start 302.805338 -201.835766)
		(end 302.805338 -201.384408)
		(width 0.16002)
		(layer "In6.Cu")
		(net "M_E_CPU0_SA_DQS_DN<0>")
	)
	(segment
		(start 314.470542 -206.979012)
		(end 313.800998 -206.979012)
		(width 0.16002)
		(layer "In6.Cu")
		(net "M_E_CPU0_SA_DQS_DN<0>")
	)
	(segment
		(start 312.29046 -204.99197)
		(end 311.813956 -204.99197)
		(width 0.16002)
		(layer "In6.Cu")
		(net "M_E_CPU0_SA_DQS_DN<0>")
	)
	(segment
		(start 302.598582 -201.177652)
		(end 301.462186 -201.177652)
		(width 0.16002)
		(layer "In6.Cu")
		(net "M_E_CPU0_SA_DQS_DN<0>")
	)
	(segment
		(start 302.805338 -201.384408)
		(end 302.598582 -201.177652)
		(width 0.16002)
		(layer "In6.Cu")
		(net "M_E_CPU0_SA_DQS_DN<0>")
	)
	(segment
		(start 310.40197 -202.280012)
		(end 310.40197 -202.053952)
		(width 0.16002)
		(layer "In6.Cu")
		(net "M_E_CPU0_SA_DQS_DN<0>")
	)
	(segment
		(start 304.085752 -201.835766)
		(end 303.710848 -202.21067)
		(width 0.16002)
		(layer "In6.Cu")
		(net "M_E_CPU0_SA_DQS_DN<0>")
	)
	(segment
		(start 289.25901 -201.491596)
		(end 288.929572 -201.162158)
		(width 0.16002)
		(layer "In6.Cu")
		(net "M_E_CPU0_SA_DQS_DN<0>")
	)
	(segment
		(start 311.793128 -203.44511)
		(end 311.537096 -203.189078)
		(width 0.16002)
		(layer "In6.Cu")
		(net "M_E_CPU0_SA_DQS_DN<0>")
	)
	(segment
		(start 285.381954 -200.312274)
		(end 283.976318 -200.312274)
		(width 0.16002)
		(layer "In6.Cu")
		(net "M_E_CPU0_SA_DQS_DN<0>")
	)
	(segment
		(start 313.800998 -206.979012)
		(end 312.772552 -205.950566)
		(width 0.16002)
		(layer "In6.Cu")
		(net "M_E_CPU0_SA_DQS_DN<0>")
	)
	(segment
		(start 310.145938 -201.79792)
		(end 309.919878 -201.79792)
		(width 0.16002)
		(layer "In6.Cu")
		(net "M_E_CPU0_SA_DQS_DN<0>")
	)
	(segment
		(start 327.00976 -226.339146)
		(end 326.97166 -226.317048)
		(width 0.09525)
		(layer "In6.Cu")
		(net "M_E_CPU0_SA_DQS_DN<0>")
	)
	(segment
		(start 311.381394 -204.082904)
		(end 311.793128 -203.67117)
		(width 0.16002)
		(layer "In6.Cu")
		(net "M_E_CPU0_SA_DQS_DN<0>")
	)
	(segment
		(start 306.520342 -200.661016)
		(end 305.843178 -200.661016)
		(width 0.16002)
		(layer "In6.Cu")
		(net "M_E_CPU0_SA_DQS_DN<0>")
	)
	(segment
		(start 301.462186 -201.177652)
		(end 300.596808 -200.312274)
		(width 0.16002)
		(layer "In6.Cu")
		(net "M_E_CPU0_SA_DQS_DN<0>")
	)
	(segment
		(start 279.601676 -201.311256)
		(end 277.466044 -201.311256)
		(width 0.16002)
		(layer "In6.Cu")
		(net "M_E_CPU0_SA_DQS_DN<0>")
	)
	(segment
		(start 312.772552 -205.950566)
		(end 312.772552 -205.474062)
		(width 0.16002)
		(layer "In6.Cu")
		(net "M_E_CPU0_SA_DQS_DN<0>")
	)
	(segment
		(start 310.422798 -203.600812)
		(end 309.990236 -203.16825)
		(width 0.16002)
		(layer "In6.Cu")
		(net "M_E_CPU0_SA_DQS_DN<0>")
	)
	(segment
		(start 309.03164 -202.209654)
		(end 308.614318 -201.792332)
		(width 0.16002)
		(layer "In6.Cu")
		(net "M_E_CPU0_SA_DQS_DN<0>")
	)
	(segment
		(start 277.466044 -201.311256)
		(end 277.192232 -201.585068)
		(width 0.16002)
		(layer "In6.Cu")
		(net "M_E_CPU0_SA_DQS_DN<0>")
	)
	(segment
		(start 313.184286 -204.836268)
		(end 312.928254 -204.580236)
		(width 0.16002)
		(layer "In6.Cu")
		(net "M_E_CPU0_SA_DQS_DN<0>")
	)
	(segment
		(start 326.572118 -225.547936)
		(end 326.539606 -225.52914)
		(width 0.09525)
		(layer "In6.Cu")
		(net "M_E_CPU0_SA_DQS_DN<0>")
	)
	(segment
		(start 309.508144 -202.209654)
		(end 309.03164 -202.209654)
		(width 0.16002)
		(layer "In6.Cu")
		(net "M_E_CPU0_SA_DQS_DN<0>")
	)
	(segment
		(start 325.778368 -222.402654)
		(end 325.63054 -222.254826)
		(width 0.09525)
		(layer "In6.Cu")
		(net "M_E_CPU0_SA_DQS_DN<0>")
	)
	(segment
		(start 307.651658 -201.792332)
		(end 306.520342 -200.661016)
		(width 0.16002)
		(layer "In6.Cu")
		(net "M_E_CPU0_SA_DQS_DN<0>")
	)
	(segment
		(start 311.813956 -204.99197)
		(end 311.381394 -204.559408)
		(width 0.16002)
		(layer "In6.Cu")
		(net "M_E_CPU0_SA_DQS_DN<0>")
	)
	(segment
		(start 296.803064 -201.491596)
		(end 296.473626 -201.162158)
		(width 0.16002)
		(layer "In6.Cu")
		(net "M_E_CPU0_SA_DQS_DN<0>")
	)
	(segment
		(start 298.299124 -200.661016)
		(end 297.468544 -201.491596)
		(width 0.16002)
		(layer "In6.Cu")
		(net "M_E_CPU0_SA_DQS_DN<0>")
	)
	(segment
		(start 310.40197 -202.053952)
		(end 310.145938 -201.79792)
		(width 0.16002)
		(layer "In6.Cu")
		(net "M_E_CPU0_SA_DQS_DN<0>")
	)
	(segment
		(start 327.479914 -227.149152)
		(end 327.47966 -227.149152)
		(width 0.09525)
		(layer "In6.Cu")
		(net "M_E_CPU0_SA_DQS_DN<0>")
	)
	(segment
		(start 327.47966 -227.149152)
		(end 327.44156 -227.127054)
		(width 0.09525)
		(layer "In6.Cu")
		(net "M_E_CPU0_SA_DQS_DN<0>")
	)
	(segment
		(start 325.546466 -222.254826)
		(end 325.529702 -222.238062)
		(width 0.09525)
		(layer "In6.Cu")
		(net "M_E_CPU0_SA_DQS_DN<0>")
	)
	(segment
		(start 303.710848 -202.21067)
		(end 303.180242 -202.21067)
		(width 0.16002)
		(layer "In6.Cu")
		(net "M_E_CPU0_SA_DQS_DN<0>")
	)
	(segment
		(start 305.843178 -200.661016)
		(end 305.019964 -201.48423)
		(width 0.16002)
		(layer "In6.Cu")
		(net "M_E_CPU0_SA_DQS_DN<0>")
	)
	(segment
		(start 325.529702 -222.238062)
		(end 322.698618 -219.406978)
		(width 0.16002)
		(layer "In6.Cu")
		(net "M_E_CPU0_SA_DQS_DN<0>")
	)
	(segment
		(start 291.171376 -200.661016)
		(end 290.75507 -200.661016)
		(width 0.16002)
		(layer "In6.Cu")
		(net "M_E_CPU0_SA_DQS_DN<0>")
	)
	(segment
		(start 288.929572 -201.162158)
		(end 286.231838 -201.162158)
		(width 0.16002)
		(layer "In6.Cu")
		(net "M_E_CPU0_SA_DQS_DN<0>")
	)
	(segment
		(start 279.750774 -201.162158)
		(end 279.601676 -201.311256)
		(width 0.16002)
		(layer "In6.Cu")
		(net "M_E_CPU0_SA_DQS_DN<0>")
	)
	(segment
		(start 310.899302 -203.600812)
		(end 310.422798 -203.600812)
		(width 0.16002)
		(layer "In6.Cu")
		(net "M_E_CPU0_SA_DQS_DN<0>")
	)
	(segment
		(start 303.180242 -202.21067)
		(end 302.805338 -201.835766)
		(width 0.16002)
		(layer "In6.Cu")
		(net "M_E_CPU0_SA_DQS_DN<0>")
	)
	(segment
		(start 326.539606 -223.909128)
		(end 326.501506 -223.88703)
		(width 0.09525)
		(layer "In6.Cu")
		(net "M_E_CPU0_SA_DQS_DN<0>")
	)
	(segment
		(start 291.520118 -200.312274)
		(end 291.171376 -200.661016)
		(width 0.16002)
		(layer "In6.Cu")
		(net "M_E_CPU0_SA_DQS_DN<0>")
	)
	(segment
		(start 289.92449 -201.491596)
		(end 289.25901 -201.491596)
		(width 0.16002)
		(layer "In6.Cu")
		(net "M_E_CPU0_SA_DQS_DN<0>")
	)
	(segment
		(start 297.468544 -201.491596)
		(end 296.803064 -201.491596)
		(width 0.16002)
		(layer "In6.Cu")
		(net "M_E_CPU0_SA_DQS_DN<0>")
	)
	(segment
		(start 329.171046 -227.474272)
		(end 329.017122 -227.208842)
		(width 0.09525)
		(layer "In6.Cu")
		(net "M_E_CPU0_SA_DQS_DN<0>")
	)
	(segment
		(start 311.381394 -204.559408)
		(end 311.381394 -204.082904)
		(width 0.16002)
		(layer "In6.Cu")
		(net "M_E_CPU0_SA_DQS_DN<0>")
	)
	(segment
		(start 308.614318 -201.792332)
		(end 307.651658 -201.792332)
		(width 0.16002)
		(layer "In6.Cu")
		(net "M_E_CPU0_SA_DQS_DN<0>")
	)
	(segment
		(start 283.627576 -200.661016)
		(end 283.182822 -200.661016)
		(width 0.16002)
		(layer "In6.Cu")
		(net "M_E_CPU0_SA_DQS_DN<0>")
	)
	(segment
		(start 326.103234 -223.11868)
		(end 326.030082 -223.076262)
		(width 0.09525)
		(layer "In6.Cu")
		(net "M_E_CPU0_SA_DQS_DN<0>")
	)
	(segment
		(start 322.698618 -219.406978)
		(end 322.698618 -215.207088)
		(width 0.16002)
		(layer "In6.Cu")
		(net "M_E_CPU0_SA_DQS_DN<0>")
	)
	(segment
		(start 296.473626 -201.162158)
		(end 293.902638 -201.162158)
		(width 0.16002)
		(layer "In6.Cu")
		(net "M_E_CPU0_SA_DQS_DN<0>")
	)
	(segment
		(start 299.064172 -200.312274)
		(end 298.71543 -200.661016)
		(width 0.16002)
		(layer "In6.Cu")
		(net "M_E_CPU0_SA_DQS_DN<0>")
	)
	(segment
		(start 327.041256 -226.357434)
		(end 327.00976 -226.339146)
		(width 0.09525)
		(layer "In6.Cu")
		(net "M_E_CPU0_SA_DQS_DN<0>")
	)
	(segment
		(start 282.352242 -201.491596)
		(end 281.71521 -201.491596)
		(width 0.16002)
		(layer "In6.Cu")
		(net "M_E_CPU0_SA_DQS_DN<0>")
	)
	(segment
		(start 309.990236 -202.691746)
		(end 310.40197 -202.280012)
		(width 0.16002)
		(layer "In6.Cu")
		(net "M_E_CPU0_SA_DQS_DN<0>")
	)
	(segment
		(start 281.71521 -201.491596)
		(end 281.385772 -201.162158)
		(width 0.16002)
		(layer "In6.Cu")
		(net "M_E_CPU0_SA_DQS_DN<0>")
	)
	(segment
		(start 298.71543 -200.661016)
		(end 298.299124 -200.661016)
		(width 0.16002)
		(layer "In6.Cu")
		(net "M_E_CPU0_SA_DQS_DN<0>")
	)
	(segment
		(start 313.184286 -205.062328)
		(end 313.184286 -204.836268)
		(width 0.16002)
		(layer "In6.Cu")
		(net "M_E_CPU0_SA_DQS_DN<0>")
	)
	(segment
		(start 326.539606 -224.559368)
		(end 326.574404 -224.539302)
		(width 0.09525)
		(layer "In6.Cu")
		(net "M_E_CPU0_SA_DQS_DN<0>")
	)
	(segment
		(start 311.793128 -203.67117)
		(end 311.793128 -203.44511)
		(width 0.16002)
		(layer "In6.Cu")
		(net "M_E_CPU0_SA_DQS_DN<0>")
	)
	(segment
		(start 300.596808 -200.312274)
		(end 299.064172 -200.312274)
		(width 0.16002)
		(layer "In6.Cu")
		(net "M_E_CPU0_SA_DQS_DN<0>")
	)
	(segment
		(start 304.262282 -201.48423)
		(end 304.085752 -201.66076)
		(width 0.16002)
		(layer "In6.Cu")
		(net "M_E_CPU0_SA_DQS_DN<0>")
	)
	(segment
		(start 290.75507 -200.661016)
		(end 289.92449 -201.491596)
		(width 0.16002)
		(layer "In6.Cu")
		(net "M_E_CPU0_SA_DQS_DN<0>")
	)
	(segment
		(start 304.085752 -201.66076)
		(end 304.085752 -201.835766)
		(width 0.16002)
		(layer "In6.Cu")
		(net "M_E_CPU0_SA_DQS_DN<0>")
	)
	(segment
		(start 329.017122 -227.208842)
		(end 328.916284 -227.182172)
		(width 0.09525)
		(layer "In6.Cu")
		(net "M_E_CPU0_SA_DQS_DN<0>")
	)
	(segment
		(start 311.311036 -203.189078)
		(end 310.899302 -203.600812)
		(width 0.16002)
		(layer "In6.Cu")
		(net "M_E_CPU0_SA_DQS_DN<0>")
	)
	(arc
		(start 327.44156 -227.127054)
		(mid 327.26311 -226.925584)
		(end 327.198736 -226.664266)
		(width 0.09525)
		(layer "In6.Cu")
		(net "M_E_CPU0_SA_DQS_DN<0>")
	)
	(arc
		(start 327.198736 -226.664266)
		(mid 327.157071 -226.491819)
		(end 327.041256 -226.357434)
		(width 0.09525)
		(layer "In6.Cu")
		(net "M_E_CPU0_SA_DQS_DN<0>")
	)
	(arc
		(start 326.574404 -224.539302)
		(mid 326.729063 -224.234248)
		(end 326.574404 -223.929194)
		(width 0.09525)
		(layer "In6.Cu")
		(net "M_E_CPU0_SA_DQS_DN<0>")
	)
	(arc
		(start 326.504554 -225.508566)
		(mid 326.258902 -225.044254)
		(end 326.504554 -224.579942)
		(width 0.09525)
		(layer "In6.Cu")
		(net "M_E_CPU0_SA_DQS_DN<0>")
	)
	(arc
		(start 328.916284 -227.182172)
		(mid 328.664143 -227.223742)
		(end 328.419714 -227.149152)
		(width 0.09525)
		(layer "In6.Cu")
		(net "M_E_CPU0_SA_DQS_DN<0>")
	)
	(arc
		(start 328.411332 -227.144326)
		(mid 328.2263 -227.098412)
		(end 328.042524 -227.149152)
		(width 0.09525)
		(layer "In6.Cu")
		(net "M_E_CPU0_SA_DQS_DN<0>")
	)
	(arc
		(start 328.042524 -227.149152)
		(mid 327.767235 -227.224873)
		(end 327.490328 -227.155248)
		(width 0.09525)
		(layer "In6.Cu")
		(net "M_E_CPU0_SA_DQS_DN<0>")
	)
	(arc
		(start 326.030082 -223.076262)
		(mid 325.845136 -222.866353)
		(end 325.778368 -222.594678)
		(width 0.09525)
		(layer "In6.Cu")
		(net "M_E_CPU0_SA_DQS_DN<0>")
	)
	(arc
		(start 326.501506 -223.88703)
		(mid 326.323056 -223.68556)
		(end 326.258682 -223.424242)
		(width 0.09525)
		(layer "In6.Cu")
		(net "M_E_CPU0_SA_DQS_DN<0>")
	)
	(arc
		(start 326.258682 -223.424242)
		(mid 326.21758 -223.252836)
		(end 326.103234 -223.11868)
		(width 0.09525)
		(layer "In6.Cu")
		(net "M_E_CPU0_SA_DQS_DN<0>")
	)
	(arc
		(start 326.97166 -226.317048)
		(mid 326.79321 -226.115578)
		(end 326.728836 -225.85426)
		(width 0.09525)
		(layer "In6.Cu")
		(net "M_E_CPU0_SA_DQS_DN<0>")
	)
	(arc
		(start 326.728836 -225.85426)
		(mid 326.687379 -225.68222)
		(end 326.572118 -225.547936)
		(width 0.09525)
		(layer "In6.Cu")
		(net "M_E_CPU0_SA_DQS_DN<0>")
	)
	(segment
		(start 330.577952 -230.97998)
		(end 330.1111 -230.714296)
		(width 0.10668)
		(layer "F.Cu")
		(net "M_E_CPU0_SA_DQ<9>")
	)
	(segment
		(start 278.77643 -209.037428)
		(end 278.613362 -209.200496)
		(width 0.14478)
		(layer "In6.Cu")
		(net "M_E_CPU0_SA_DQ<9>")
	)
	(segment
		(start 290.769802 -207.960214)
		(end 289.919918 -208.810098)
		(width 0.14478)
		(layer "In6.Cu")
		(net "M_E_CPU0_SA_DQ<9>")
	)
	(segment
		(start 323.764148 -227.318316)
		(end 320.376804 -223.930972)
		(width 0.14478)
		(layer "In6.Cu")
		(net "M_E_CPU0_SA_DQ<9>")
	)
	(segment
		(start 325.168768 -229.17531)
		(end 324.848474 -229.17531)
		(width 0.0889)
		(layer "In6.Cu")
		(net "M_E_CPU0_SA_DQ<9>")
	)
	(segment
		(start 296.316654 -208.810098)
		(end 294.480742 -208.810098)
		(width 0.14478)
		(layer "In6.Cu")
		(net "M_E_CPU0_SA_DQ<9>")
	)
	(segment
		(start 307.102256 -208.189322)
		(end 306.939188 -208.35239)
		(width 0.14478)
		(layer "In6.Cu")
		(net "M_E_CPU0_SA_DQ<9>")
	)
	(segment
		(start 279.889458 -208.973166)
		(end 279.889458 -209.037428)
		(width 0.14478)
		(layer "In6.Cu")
		(net "M_E_CPU0_SA_DQ<9>")
	)
	(segment
		(start 296.64279 -209.19313)
		(end 296.479722 -209.030062)
		(width 0.14478)
		(layer "In6.Cu")
		(net "M_E_CPU0_SA_DQ<9>")
	)
	(segment
		(start 288.860738 -209.037682)
		(end 288.860738 -208.973166)
		(width 0.14478)
		(layer "In6.Cu")
		(net "M_E_CPU0_SA_DQ<9>")
	)
	(segment
		(start 286.804862 -208.810098)
		(end 285.954978 -207.960214)
		(width 0.14478)
		(layer "In6.Cu")
		(net "M_E_CPU0_SA_DQ<9>")
	)
	(segment
		(start 307.265324 -207.960214)
		(end 307.102256 -208.123282)
		(width 0.14478)
		(layer "In6.Cu")
		(net "M_E_CPU0_SA_DQ<9>")
	)
	(segment
		(start 328.992484 -231.041448)
		(end 328.984102 -231.036622)
		(width 0.0889)
		(layer "In6.Cu")
		(net "M_E_CPU0_SA_DQ<9>")
	)
	(segment
		(start 293.630858 -207.960214)
		(end 290.769802 -207.960214)
		(width 0.14478)
		(layer "In6.Cu")
		(net "M_E_CPU0_SA_DQ<9>")
	)
	(segment
		(start 308.803294 -207.960214)
		(end 308.378352 -207.960214)
		(width 0.14478)
		(layer "In6.Cu")
		(net "M_E_CPU0_SA_DQ<9>")
	)
	(segment
		(start 305.119278 -208.810098)
		(end 304.604674 -208.810098)
		(width 0.14478)
		(layer "In6.Cu")
		(net "M_E_CPU0_SA_DQ<9>")
	)
	(segment
		(start 307.495702 -207.960214)
		(end 307.265324 -207.960214)
		(width 0.14478)
		(layer "In6.Cu")
		(net "M_E_CPU0_SA_DQ<9>")
	)
	(segment
		(start 289.58032 -208.810098)
		(end 289.417252 -208.973166)
		(width 0.14478)
		(layer "In6.Cu")
		(net "M_E_CPU0_SA_DQ<9>")
	)
	(segment
		(start 301.174658 -207.960214)
		(end 298.425362 -207.960214)
		(width 0.14478)
		(layer "In6.Cu")
		(net "M_E_CPU0_SA_DQ<9>")
	)
	(segment
		(start 278.219916 -209.037428)
		(end 278.219916 -208.973166)
		(width 0.14478)
		(layer "In6.Cu")
		(net "M_E_CPU0_SA_DQ<9>")
	)
	(segment
		(start 289.919918 -208.810098)
		(end 289.58032 -208.810098)
		(width 0.14478)
		(layer "In6.Cu")
		(net "M_E_CPU0_SA_DQ<9>")
	)
	(segment
		(start 304.441606 -209.037682)
		(end 304.278538 -209.20075)
		(width 0.14478)
		(layer "In6.Cu")
		(net "M_E_CPU0_SA_DQ<9>")
	)
	(segment
		(start 306.939188 -208.35239)
		(end 306.70881 -208.35239)
		(width 0.14478)
		(layer "In6.Cu")
		(net "M_E_CPU0_SA_DQ<9>")
	)
	(segment
		(start 285.954978 -207.960214)
		(end 283.264102 -207.960214)
		(width 0.14478)
		(layer "In6.Cu")
		(net "M_E_CPU0_SA_DQ<9>")
	)
	(segment
		(start 297.575478 -208.810098)
		(end 297.199304 -208.810098)
		(width 0.14478)
		(layer "In6.Cu")
		(net "M_E_CPU0_SA_DQ<9>")
	)
	(segment
		(start 279.496012 -209.200496)
		(end 279.332944 -209.037428)
		(width 0.14478)
		(layer "In6.Cu")
		(net "M_E_CPU0_SA_DQ<9>")
	)
	(segment
		(start 330.1111 -230.714296)
		(end 330.265024 -230.979726)
		(width 0.0889)
		(layer "In6.Cu")
		(net "M_E_CPU0_SA_DQ<9>")
	)
	(segment
		(start 304.441606 -208.973166)
		(end 304.441606 -209.037682)
		(width 0.14478)
		(layer "In6.Cu")
		(net "M_E_CPU0_SA_DQ<9>")
	)
	(segment
		(start 303.885092 -209.037682)
		(end 303.885092 -208.973166)
		(width 0.14478)
		(layer "In6.Cu")
		(net "M_E_CPU0_SA_DQ<9>")
	)
	(segment
		(start 320.376804 -223.107758)
		(end 318.191134 -220.922088)
		(width 0.14478)
		(layer "In6.Cu")
		(net "M_E_CPU0_SA_DQ<9>")
	)
	(segment
		(start 278.939498 -208.416906)
		(end 278.77643 -208.579974)
		(width 0.14478)
		(layer "In6.Cu")
		(net "M_E_CPU0_SA_DQ<9>")
	)
	(segment
		(start 304.04816 -209.20075)
		(end 303.885092 -209.037682)
		(width 0.14478)
		(layer "In6.Cu")
		(net "M_E_CPU0_SA_DQ<9>")
	)
	(segment
		(start 324.382384 -228.70922)
		(end 324.382384 -227.936552)
		(width 0.0889)
		(layer "In6.Cu")
		(net "M_E_CPU0_SA_DQ<9>")
	)
	(segment
		(start 277.617174 -208.810098)
		(end 277.192232 -208.385156)
		(width 0.14478)
		(layer "In6.Cu")
		(net "M_E_CPU0_SA_DQ<9>")
	)
	(segment
		(start 302.935132 -209.20075)
		(end 302.772064 -209.037682)
		(width 0.14478)
		(layer "In6.Cu")
		(net "M_E_CPU0_SA_DQ<9>")
	)
	(segment
		(start 288.69767 -208.810098)
		(end 286.804862 -208.810098)
		(width 0.14478)
		(layer "In6.Cu")
		(net "M_E_CPU0_SA_DQ<9>")
	)
	(segment
		(start 289.023806 -209.20075)
		(end 288.860738 -209.037682)
		(width 0.14478)
		(layer "In6.Cu")
		(net "M_E_CPU0_SA_DQ<9>")
	)
	(segment
		(start 282.414218 -208.810098)
		(end 280.052526 -208.810098)
		(width 0.14478)
		(layer "In6.Cu")
		(net "M_E_CPU0_SA_DQ<9>")
	)
	(segment
		(start 304.604674 -208.810098)
		(end 304.441606 -208.973166)
		(width 0.14478)
		(layer "In6.Cu")
		(net "M_E_CPU0_SA_DQ<9>")
	)
	(segment
		(start 306.545742 -208.189322)
		(end 306.545742 -208.123282)
		(width 0.14478)
		(layer "In6.Cu")
		(net "M_E_CPU0_SA_DQ<9>")
	)
	(segment
		(start 289.254184 -209.20075)
		(end 289.023806 -209.20075)
		(width 0.14478)
		(layer "In6.Cu")
		(net "M_E_CPU0_SA_DQ<9>")
	)
	(segment
		(start 283.264102 -207.960214)
		(end 282.414218 -208.810098)
		(width 0.14478)
		(layer "In6.Cu")
		(net "M_E_CPU0_SA_DQ<9>")
	)
	(segment
		(start 307.102256 -208.123282)
		(end 307.102256 -208.189322)
		(width 0.14478)
		(layer "In6.Cu")
		(net "M_E_CPU0_SA_DQ<9>")
	)
	(segment
		(start 308.215284 -208.123282)
		(end 308.215284 -208.189322)
		(width 0.14478)
		(layer "In6.Cu")
		(net "M_E_CPU0_SA_DQ<9>")
	)
	(segment
		(start 294.480742 -208.810098)
		(end 293.630858 -207.960214)
		(width 0.14478)
		(layer "In6.Cu")
		(net "M_E_CPU0_SA_DQ<9>")
	)
	(segment
		(start 302.608996 -208.810098)
		(end 302.024542 -208.810098)
		(width 0.14478)
		(layer "In6.Cu")
		(net "M_E_CPU0_SA_DQ<9>")
	)
	(segment
		(start 297.036236 -208.973166)
		(end 297.036236 -209.030062)
		(width 0.14478)
		(layer "In6.Cu")
		(net "M_E_CPU0_SA_DQ<9>")
	)
	(segment
		(start 302.772064 -208.973166)
		(end 302.608996 -208.810098)
		(width 0.14478)
		(layer "In6.Cu")
		(net "M_E_CPU0_SA_DQ<9>")
	)
	(segment
		(start 306.70881 -208.35239)
		(end 306.545742 -208.189322)
		(width 0.14478)
		(layer "In6.Cu")
		(net "M_E_CPU0_SA_DQ<9>")
	)
	(segment
		(start 318.191134 -217.348054)
		(end 308.803294 -207.960214)
		(width 0.14478)
		(layer "In6.Cu")
		(net "M_E_CPU0_SA_DQ<9>")
	)
	(segment
		(start 324.382384 -227.936552)
		(end 323.764148 -227.318316)
		(width 0.0889)
		(layer "In6.Cu")
		(net "M_E_CPU0_SA_DQ<9>")
	)
	(segment
		(start 304.278538 -209.20075)
		(end 304.04816 -209.20075)
		(width 0.14478)
		(layer "In6.Cu")
		(net "M_E_CPU0_SA_DQ<9>")
	)
	(segment
		(start 324.848474 -229.17531)
		(end 324.382384 -228.70922)
		(width 0.0889)
		(layer "In6.Cu")
		(net "M_E_CPU0_SA_DQ<9>")
	)
	(segment
		(start 280.052526 -208.810098)
		(end 279.889458 -208.973166)
		(width 0.14478)
		(layer "In6.Cu")
		(net "M_E_CPU0_SA_DQ<9>")
	)
	(segment
		(start 326.10425 -230.110792)
		(end 325.168768 -229.17531)
		(width 0.0889)
		(layer "In6.Cu")
		(net "M_E_CPU0_SA_DQ<9>")
	)
	(segment
		(start 297.199304 -208.810098)
		(end 297.036236 -208.973166)
		(width 0.14478)
		(layer "In6.Cu")
		(net "M_E_CPU0_SA_DQ<9>")
	)
	(segment
		(start 303.491646 -208.810098)
		(end 303.328578 -208.973166)
		(width 0.14478)
		(layer "In6.Cu")
		(net "M_E_CPU0_SA_DQ<9>")
	)
	(segment
		(start 306.382674 -207.960214)
		(end 305.969162 -207.960214)
		(width 0.14478)
		(layer "In6.Cu")
		(net "M_E_CPU0_SA_DQ<9>")
	)
	(segment
		(start 279.72639 -209.200496)
		(end 279.496012 -209.200496)
		(width 0.14478)
		(layer "In6.Cu")
		(net "M_E_CPU0_SA_DQ<9>")
	)
	(segment
		(start 296.479722 -209.030062)
		(end 296.479722 -208.973166)
		(width 0.14478)
		(layer "In6.Cu")
		(net "M_E_CPU0_SA_DQ<9>")
	)
	(segment
		(start 296.873168 -209.19313)
		(end 296.64279 -209.19313)
		(width 0.14478)
		(layer "In6.Cu")
		(net "M_E_CPU0_SA_DQ<9>")
	)
	(segment
		(start 306.545742 -208.123282)
		(end 306.382674 -207.960214)
		(width 0.14478)
		(layer "In6.Cu")
		(net "M_E_CPU0_SA_DQ<9>")
	)
	(segment
		(start 278.77643 -208.579974)
		(end 278.77643 -209.037428)
		(width 0.14478)
		(layer "In6.Cu")
		(net "M_E_CPU0_SA_DQ<9>")
	)
	(segment
		(start 320.376804 -223.930972)
		(end 320.376804 -223.107758)
		(width 0.14478)
		(layer "In6.Cu")
		(net "M_E_CPU0_SA_DQ<9>")
	)
	(segment
		(start 279.332944 -208.579974)
		(end 279.169876 -208.416906)
		(width 0.14478)
		(layer "In6.Cu")
		(net "M_E_CPU0_SA_DQ<9>")
	)
	(segment
		(start 298.425362 -207.960214)
		(end 297.575478 -208.810098)
		(width 0.14478)
		(layer "In6.Cu")
		(net "M_E_CPU0_SA_DQ<9>")
	)
	(segment
		(start 308.378352 -207.960214)
		(end 308.215284 -208.123282)
		(width 0.14478)
		(layer "In6.Cu")
		(net "M_E_CPU0_SA_DQ<9>")
	)
	(segment
		(start 279.889458 -209.037428)
		(end 279.72639 -209.200496)
		(width 0.14478)
		(layer "In6.Cu")
		(net "M_E_CPU0_SA_DQ<9>")
	)
	(segment
		(start 302.772064 -209.037682)
		(end 302.772064 -208.973166)
		(width 0.14478)
		(layer "In6.Cu")
		(net "M_E_CPU0_SA_DQ<9>")
	)
	(segment
		(start 307.821838 -208.35239)
		(end 307.65877 -208.189322)
		(width 0.14478)
		(layer "In6.Cu")
		(net "M_E_CPU0_SA_DQ<9>")
	)
	(segment
		(start 278.613362 -209.200496)
		(end 278.382984 -209.200496)
		(width 0.14478)
		(layer "In6.Cu")
		(net "M_E_CPU0_SA_DQ<9>")
	)
	(segment
		(start 318.191134 -220.922088)
		(end 318.191134 -217.348054)
		(width 0.14478)
		(layer "In6.Cu")
		(net "M_E_CPU0_SA_DQ<9>")
	)
	(segment
		(start 289.417252 -208.973166)
		(end 289.417252 -209.037682)
		(width 0.14478)
		(layer "In6.Cu")
		(net "M_E_CPU0_SA_DQ<9>")
	)
	(segment
		(start 297.036236 -209.030062)
		(end 296.873168 -209.19313)
		(width 0.14478)
		(layer "In6.Cu")
		(net "M_E_CPU0_SA_DQ<9>")
	)
	(segment
		(start 278.056848 -208.810098)
		(end 277.617174 -208.810098)
		(width 0.14478)
		(layer "In6.Cu")
		(net "M_E_CPU0_SA_DQ<9>")
	)
	(segment
		(start 303.328578 -209.037682)
		(end 303.16551 -209.20075)
		(width 0.14478)
		(layer "In6.Cu")
		(net "M_E_CPU0_SA_DQ<9>")
	)
	(segment
		(start 288.860738 -208.973166)
		(end 288.69767 -208.810098)
		(width 0.14478)
		(layer "In6.Cu")
		(net "M_E_CPU0_SA_DQ<9>")
	)
	(segment
		(start 308.052216 -208.35239)
		(end 307.821838 -208.35239)
		(width 0.14478)
		(layer "In6.Cu")
		(net "M_E_CPU0_SA_DQ<9>")
	)
	(segment
		(start 303.722024 -208.810098)
		(end 303.491646 -208.810098)
		(width 0.14478)
		(layer "In6.Cu")
		(net "M_E_CPU0_SA_DQ<9>")
	)
	(segment
		(start 326.579992 -230.110792)
		(end 326.10425 -230.110792)
		(width 0.0889)
		(layer "In6.Cu")
		(net "M_E_CPU0_SA_DQ<9>")
	)
	(segment
		(start 279.169876 -208.416906)
		(end 278.939498 -208.416906)
		(width 0.14478)
		(layer "In6.Cu")
		(net "M_E_CPU0_SA_DQ<9>")
	)
	(segment
		(start 303.16551 -209.20075)
		(end 302.935132 -209.20075)
		(width 0.14478)
		(layer "In6.Cu")
		(net "M_E_CPU0_SA_DQ<9>")
	)
	(segment
		(start 330.265024 -230.979726)
		(end 330.242926 -231.062784)
		(width 0.0889)
		(layer "In6.Cu")
		(net "M_E_CPU0_SA_DQ<9>")
	)
	(segment
		(start 279.332944 -209.037428)
		(end 279.332944 -208.579974)
		(width 0.14478)
		(layer "In6.Cu")
		(net "M_E_CPU0_SA_DQ<9>")
	)
	(segment
		(start 296.479722 -208.973166)
		(end 296.316654 -208.810098)
		(width 0.14478)
		(layer "In6.Cu")
		(net "M_E_CPU0_SA_DQ<9>")
	)
	(segment
		(start 307.65877 -208.189322)
		(end 307.65877 -208.123282)
		(width 0.14478)
		(layer "In6.Cu")
		(net "M_E_CPU0_SA_DQ<9>")
	)
	(segment
		(start 303.328578 -208.973166)
		(end 303.328578 -209.037682)
		(width 0.14478)
		(layer "In6.Cu")
		(net "M_E_CPU0_SA_DQ<9>")
	)
	(segment
		(start 305.969162 -207.960214)
		(end 305.119278 -208.810098)
		(width 0.14478)
		(layer "In6.Cu")
		(net "M_E_CPU0_SA_DQ<9>")
	)
	(segment
		(start 278.219916 -208.973166)
		(end 278.056848 -208.810098)
		(width 0.14478)
		(layer "In6.Cu")
		(net "M_E_CPU0_SA_DQ<9>")
	)
	(segment
		(start 328.41819 -231.036622)
		(end 328.409808 -231.041448)
		(width 0.0889)
		(layer "In6.Cu")
		(net "M_E_CPU0_SA_DQ<9>")
	)
	(segment
		(start 289.417252 -209.037682)
		(end 289.254184 -209.20075)
		(width 0.14478)
		(layer "In6.Cu")
		(net "M_E_CPU0_SA_DQ<9>")
	)
	(segment
		(start 307.65877 -208.123282)
		(end 307.495702 -207.960214)
		(width 0.14478)
		(layer "In6.Cu")
		(net "M_E_CPU0_SA_DQ<9>")
	)
	(segment
		(start 327.268332 -230.799132)
		(end 326.579992 -230.110792)
		(width 0.0889)
		(layer "In6.Cu")
		(net "M_E_CPU0_SA_DQ<9>")
	)
	(segment
		(start 302.024542 -208.810098)
		(end 301.174658 -207.960214)
		(width 0.14478)
		(layer "In6.Cu")
		(net "M_E_CPU0_SA_DQ<9>")
	)
	(segment
		(start 303.885092 -208.973166)
		(end 303.722024 -208.810098)
		(width 0.14478)
		(layer "In6.Cu")
		(net "M_E_CPU0_SA_DQ<9>")
	)
	(segment
		(start 308.215284 -208.189322)
		(end 308.052216 -208.35239)
		(width 0.14478)
		(layer "In6.Cu")
		(net "M_E_CPU0_SA_DQ<9>")
	)
	(segment
		(start 278.382984 -209.200496)
		(end 278.219916 -209.037428)
		(width 0.14478)
		(layer "In6.Cu")
		(net "M_E_CPU0_SA_DQ<9>")
	)
	(arc
		(start 328.044048 -231.036622)
		(mid 327.884666 -230.974057)
		(end 327.713848 -230.9622)
		(width 0.0889)
		(layer "In6.Cu")
		(net "M_E_CPU0_SA_DQ<9>")
	)
	(arc
		(start 328.409808 -231.041448)
		(mid 328.2263 -231.086973)
		(end 328.044048 -231.036622)
		(width 0.0889)
		(layer "In6.Cu")
		(net "M_E_CPU0_SA_DQ<9>")
	)
	(arc
		(start 328.984102 -231.036622)
		(mid 328.701146 -230.960445)
		(end 328.41819 -231.036622)
		(width 0.0889)
		(layer "In6.Cu")
		(net "M_E_CPU0_SA_DQ<9>")
	)
	(arc
		(start 327.713848 -230.9622)
		(mid 327.473108 -230.92981)
		(end 327.268332 -230.799132)
		(width 0.0889)
		(layer "In6.Cu")
		(net "M_E_CPU0_SA_DQ<9>")
	)
	(arc
		(start 330.242926 -231.062784)
		(mid 330.080595 -231.085633)
		(end 329.924156 -231.036622)
		(width 0.0889)
		(layer "In6.Cu")
		(net "M_E_CPU0_SA_DQ<9>")
	)
	(arc
		(start 329.358244 -231.036622)
		(mid 329.175993 -231.087006)
		(end 328.992484 -231.041448)
		(width 0.0889)
		(layer "In6.Cu")
		(net "M_E_CPU0_SA_DQ<9>")
	)
	(arc
		(start 329.924156 -231.036622)
		(mid 329.6412 -230.960445)
		(end 329.358244 -231.036622)
		(width 0.0889)
		(layer "In6.Cu")
		(net "M_E_CPU0_SA_DQ<9>")
	)
	(segment
		(start 329.167998 -230.169974)
		(end 328.701146 -229.904036)
		(width 0.10668)
		(layer "F.Cu")
		(net "M_E_CPU0_SA_DQ<8>")
	)
	(segment
		(start 321.275964 -223.543876)
		(end 321.275964 -222.734886)
		(width 0.14478)
		(layer "In6.Cu")
		(net "M_E_CPU0_SA_DQ<8>")
	)
	(segment
		(start 304.308256 -207.49895)
		(end 304.077878 -207.49895)
		(width 0.14478)
		(layer "In6.Cu")
		(net "M_E_CPU0_SA_DQ<8>")
	)
	(segment
		(start 282.808172 -206.716122)
		(end 282.603448 -206.716122)
		(width 0.14478)
		(layer "In6.Cu")
		(net "M_E_CPU0_SA_DQ<8>")
	)
	(segment
		(start 306.641246 -206.42326)
		(end 306.478178 -206.260192)
		(width 0.14478)
		(layer "In6.Cu")
		(net "M_E_CPU0_SA_DQ<8>")
	)
	(segment
		(start 302.638714 -207.110076)
		(end 302.024542 -207.110076)
		(width 0.14478)
		(layer "In6.Cu")
		(net "M_E_CPU0_SA_DQ<8>")
	)
	(segment
		(start 307.917342 -206.65059)
		(end 307.754274 -206.487522)
		(width 0.14478)
		(layer "In6.Cu")
		(net "M_E_CPU0_SA_DQ<8>")
	)
	(segment
		(start 281.064462 -207.110076)
		(end 280.24328 -207.110076)
		(width 0.14478)
		(layer "In6.Cu")
		(net "M_E_CPU0_SA_DQ<8>")
	)
	(segment
		(start 288.726626 -207.110076)
		(end 286.804862 -207.110076)
		(width 0.14478)
		(layer "In6.Cu")
		(net "M_E_CPU0_SA_DQ<8>")
	)
	(segment
		(start 303.358296 -207.273144)
		(end 303.358296 -207.335882)
		(width 0.14478)
		(layer "In6.Cu")
		(net "M_E_CPU0_SA_DQ<8>")
	)
	(segment
		(start 297.575478 -207.110076)
		(end 297.30573 -207.110076)
		(width 0.14478)
		(layer "In6.Cu")
		(net "M_E_CPU0_SA_DQ<8>")
	)
	(segment
		(start 302.96485 -207.49895)
		(end 302.801782 -207.335882)
		(width 0.14478)
		(layer "In6.Cu")
		(net "M_E_CPU0_SA_DQ<8>")
	)
	(segment
		(start 307.754274 -206.42326)
		(end 307.591206 -206.260192)
		(width 0.14478)
		(layer "In6.Cu")
		(net "M_E_CPU0_SA_DQ<8>")
	)
	(segment
		(start 324.32117 -226.589082)
		(end 324.028816 -226.296728)
		(width 0.0889)
		(layer "In6.Cu")
		(net "M_E_CPU0_SA_DQ<8>")
	)
	(segment
		(start 289.28314 -207.50403)
		(end 289.052762 -207.50403)
		(width 0.14478)
		(layer "In6.Cu")
		(net "M_E_CPU0_SA_DQ<8>")
	)
	(segment
		(start 282.204668 -207.114902)
		(end 282.204668 -207.319626)
		(width 0.14478)
		(layer "In6.Cu")
		(net "M_E_CPU0_SA_DQ<8>")
	)
	(segment
		(start 289.446208 -207.340962)
		(end 289.28314 -207.50403)
		(width 0.14478)
		(layer "In6.Cu")
		(net "M_E_CPU0_SA_DQ<8>")
	)
	(segment
		(start 286.804862 -207.110076)
		(end 285.954978 -206.260192)
		(width 0.14478)
		(layer "In6.Cu")
		(net "M_E_CPU0_SA_DQ<8>")
	)
	(segment
		(start 303.195228 -207.49895)
		(end 302.96485 -207.49895)
		(width 0.14478)
		(layer "In6.Cu")
		(net "M_E_CPU0_SA_DQ<8>")
	)
	(segment
		(start 288.889694 -207.273144)
		(end 288.726626 -207.110076)
		(width 0.14478)
		(layer "In6.Cu")
		(net "M_E_CPU0_SA_DQ<8>")
	)
	(segment
		(start 308.765702 -206.65059)
		(end 307.917342 -206.65059)
		(width 0.14478)
		(layer "In6.Cu")
		(net "M_E_CPU0_SA_DQ<8>")
	)
	(segment
		(start 307.360828 -206.260192)
		(end 307.19776 -206.42326)
		(width 0.14478)
		(layer "In6.Cu")
		(net "M_E_CPU0_SA_DQ<8>")
	)
	(segment
		(start 278.970994 -206.811372)
		(end 278.826214 -206.956152)
		(width 0.14478)
		(layer "In6.Cu")
		(net "M_E_CPU0_SA_DQ<8>")
	)
	(segment
		(start 296.586148 -207.340962)
		(end 296.586148 -207.273144)
		(width 0.14478)
		(layer "In6.Cu")
		(net "M_E_CPU0_SA_DQ<8>")
	)
	(segment
		(start 327.49744 -230.167688)
		(end 326.939402 -229.60965)
		(width 0.0889)
		(layer "In6.Cu")
		(net "M_E_CPU0_SA_DQ<8>")
	)
	(segment
		(start 307.034692 -206.65059)
		(end 306.804314 -206.65059)
		(width 0.14478)
		(layer "In6.Cu")
		(net "M_E_CPU0_SA_DQ<8>")
	)
	(segment
		(start 307.19776 -206.487522)
		(end 307.034692 -206.65059)
		(width 0.14478)
		(layer "In6.Cu")
		(net "M_E_CPU0_SA_DQ<8>")
	)
	(segment
		(start 283.264102 -206.260192)
		(end 282.808172 -206.716122)
		(width 0.14478)
		(layer "In6.Cu")
		(net "M_E_CPU0_SA_DQ<8>")
	)
	(segment
		(start 325.336154 -228.64191)
		(end 325.336154 -228.16185)
		(width 0.0889)
		(layer "In6.Cu")
		(net "M_E_CPU0_SA_DQ<8>")
	)
	(segment
		(start 307.754274 -206.487522)
		(end 307.754274 -206.42326)
		(width 0.14478)
		(layer "In6.Cu")
		(net "M_E_CPU0_SA_DQ<8>")
	)
	(segment
		(start 304.471324 -207.335882)
		(end 304.308256 -207.49895)
		(width 0.14478)
		(layer "In6.Cu")
		(net "M_E_CPU0_SA_DQ<8>")
	)
	(segment
		(start 294.480742 -207.110076)
		(end 293.630858 -206.260192)
		(width 0.14478)
		(layer "In6.Cu")
		(net "M_E_CPU0_SA_DQ<8>")
	)
	(segment
		(start 297.142662 -207.340962)
		(end 296.979594 -207.50403)
		(width 0.14478)
		(layer "In6.Cu")
		(net "M_E_CPU0_SA_DQ<8>")
	)
	(segment
		(start 328.701146 -229.904036)
		(end 328.85507 -230.169466)
		(width 0.0889)
		(layer "In6.Cu")
		(net "M_E_CPU0_SA_DQ<8>")
	)
	(segment
		(start 324.028816 -226.296728)
		(end 321.275964 -223.543876)
		(width 0.14478)
		(layer "In6.Cu")
		(net "M_E_CPU0_SA_DQ<8>")
	)
	(segment
		(start 324.917054 -227.74275)
		(end 324.917054 -227.60051)
		(width 0.0889)
		(layer "In6.Cu")
		(net "M_E_CPU0_SA_DQ<8>")
	)
	(segment
		(start 289.919918 -207.110076)
		(end 289.609276 -207.110076)
		(width 0.14478)
		(layer "In6.Cu")
		(net "M_E_CPU0_SA_DQ<8>")
	)
	(segment
		(start 296.979594 -207.50403)
		(end 296.749216 -207.50403)
		(width 0.14478)
		(layer "In6.Cu")
		(net "M_E_CPU0_SA_DQ<8>")
	)
	(segment
		(start 288.889694 -207.340962)
		(end 288.889694 -207.273144)
		(width 0.14478)
		(layer "In6.Cu")
		(net "M_E_CPU0_SA_DQ<8>")
	)
	(segment
		(start 296.749216 -207.50403)
		(end 296.586148 -207.340962)
		(width 0.14478)
		(layer "In6.Cu")
		(net "M_E_CPU0_SA_DQ<8>")
	)
	(segment
		(start 328.85507 -230.169466)
		(end 328.832718 -230.252778)
		(width 0.0889)
		(layer "In6.Cu")
		(net "M_E_CPU0_SA_DQ<8>")
	)
	(segment
		(start 290.769802 -206.260192)
		(end 289.919918 -207.110076)
		(width 0.14478)
		(layer "In6.Cu")
		(net "M_E_CPU0_SA_DQ<8>")
	)
	(segment
		(start 304.634392 -207.110076)
		(end 304.471324 -207.273144)
		(width 0.14478)
		(layer "In6.Cu")
		(net "M_E_CPU0_SA_DQ<8>")
	)
	(segment
		(start 282.603448 -206.716122)
		(end 282.37307 -206.485744)
		(width 0.14478)
		(layer "In6.Cu")
		(net "M_E_CPU0_SA_DQ<8>")
	)
	(segment
		(start 289.052762 -207.50403)
		(end 288.889694 -207.340962)
		(width 0.14478)
		(layer "In6.Cu")
		(net "M_E_CPU0_SA_DQ<8>")
	)
	(segment
		(start 305.119278 -207.110076)
		(end 304.634392 -207.110076)
		(width 0.14478)
		(layer "In6.Cu")
		(net "M_E_CPU0_SA_DQ<8>")
	)
	(segment
		(start 301.174658 -206.260192)
		(end 298.425362 -206.260192)
		(width 0.14478)
		(layer "In6.Cu")
		(net "M_E_CPU0_SA_DQ<8>")
	)
	(segment
		(start 319.111122 -220.570044)
		(end 319.111122 -216.99601)
		(width 0.14478)
		(layer "In6.Cu")
		(net "M_E_CPU0_SA_DQ<8>")
	)
	(segment
		(start 302.801782 -207.273144)
		(end 302.638714 -207.110076)
		(width 0.14478)
		(layer "In6.Cu")
		(net "M_E_CPU0_SA_DQ<8>")
	)
	(segment
		(start 303.91481 -207.335882)
		(end 303.91481 -207.273144)
		(width 0.14478)
		(layer "In6.Cu")
		(net "M_E_CPU0_SA_DQ<8>")
	)
	(segment
		(start 304.077878 -207.49895)
		(end 303.91481 -207.335882)
		(width 0.14478)
		(layer "In6.Cu")
		(net "M_E_CPU0_SA_DQ<8>")
	)
	(segment
		(start 296.42308 -207.110076)
		(end 294.480742 -207.110076)
		(width 0.14478)
		(layer "In6.Cu")
		(net "M_E_CPU0_SA_DQ<8>")
	)
	(segment
		(start 319.111122 -216.99601)
		(end 308.765702 -206.65059)
		(width 0.14478)
		(layer "In6.Cu")
		(net "M_E_CPU0_SA_DQ<8>")
	)
	(segment
		(start 281.97429 -206.6798)
		(end 281.97429 -206.884524)
		(width 0.14478)
		(layer "In6.Cu")
		(net "M_E_CPU0_SA_DQ<8>")
	)
	(segment
		(start 302.024542 -207.110076)
		(end 301.174658 -206.260192)
		(width 0.14478)
		(layer "In6.Cu")
		(net "M_E_CPU0_SA_DQ<8>")
	)
	(segment
		(start 297.142662 -207.273144)
		(end 297.142662 -207.340962)
		(width 0.14478)
		(layer "In6.Cu")
		(net "M_E_CPU0_SA_DQ<8>")
	)
	(segment
		(start 306.641246 -206.487522)
		(end 306.641246 -206.42326)
		(width 0.14478)
		(layer "In6.Cu")
		(net "M_E_CPU0_SA_DQ<8>")
	)
	(segment
		(start 303.521364 -207.110076)
		(end 303.358296 -207.273144)
		(width 0.14478)
		(layer "In6.Cu")
		(net "M_E_CPU0_SA_DQ<8>")
	)
	(segment
		(start 281.445716 -207.49133)
		(end 281.064462 -207.110076)
		(width 0.14478)
		(layer "In6.Cu")
		(net "M_E_CPU0_SA_DQ<8>")
	)
	(segment
		(start 279.390094 -206.956152)
		(end 279.245314 -206.811372)
		(width 0.14478)
		(layer "In6.Cu")
		(net "M_E_CPU0_SA_DQ<8>")
	)
	(segment
		(start 326.303894 -229.60965)
		(end 325.336154 -228.64191)
		(width 0.0889)
		(layer "In6.Cu")
		(net "M_E_CPU0_SA_DQ<8>")
	)
	(segment
		(start 285.954978 -206.260192)
		(end 283.264102 -206.260192)
		(width 0.14478)
		(layer "In6.Cu")
		(net "M_E_CPU0_SA_DQ<8>")
	)
	(segment
		(start 306.804314 -206.65059)
		(end 306.641246 -206.487522)
		(width 0.14478)
		(layer "In6.Cu")
		(net "M_E_CPU0_SA_DQ<8>")
	)
	(segment
		(start 303.751742 -207.110076)
		(end 303.521364 -207.110076)
		(width 0.14478)
		(layer "In6.Cu")
		(net "M_E_CPU0_SA_DQ<8>")
	)
	(segment
		(start 303.91481 -207.273144)
		(end 303.751742 -207.110076)
		(width 0.14478)
		(layer "In6.Cu")
		(net "M_E_CPU0_SA_DQ<8>")
	)
	(segment
		(start 280.24328 -207.110076)
		(end 279.862026 -207.49133)
		(width 0.14478)
		(layer "In6.Cu")
		(net "M_E_CPU0_SA_DQ<8>")
	)
	(segment
		(start 278.681434 -207.49133)
		(end 277.998428 -207.49133)
		(width 0.14478)
		(layer "In6.Cu")
		(net "M_E_CPU0_SA_DQ<8>")
	)
	(segment
		(start 278.826214 -207.34655)
		(end 278.681434 -207.49133)
		(width 0.14478)
		(layer "In6.Cu")
		(net "M_E_CPU0_SA_DQ<8>")
	)
	(segment
		(start 279.862026 -207.49133)
		(end 279.534874 -207.49133)
		(width 0.14478)
		(layer "In6.Cu")
		(net "M_E_CPU0_SA_DQ<8>")
	)
	(segment
		(start 281.97429 -206.884524)
		(end 282.204668 -207.114902)
		(width 0.14478)
		(layer "In6.Cu")
		(net "M_E_CPU0_SA_DQ<8>")
	)
	(segment
		(start 307.19776 -206.42326)
		(end 307.19776 -206.487522)
		(width 0.14478)
		(layer "In6.Cu")
		(net "M_E_CPU0_SA_DQ<8>")
	)
	(segment
		(start 306.478178 -206.260192)
		(end 305.969162 -206.260192)
		(width 0.14478)
		(layer "In6.Cu")
		(net "M_E_CPU0_SA_DQ<8>")
	)
	(segment
		(start 282.032964 -207.49133)
		(end 281.445716 -207.49133)
		(width 0.14478)
		(layer "In6.Cu")
		(net "M_E_CPU0_SA_DQ<8>")
	)
	(segment
		(start 279.534874 -207.49133)
		(end 279.390094 -207.34655)
		(width 0.14478)
		(layer "In6.Cu")
		(net "M_E_CPU0_SA_DQ<8>")
	)
	(segment
		(start 296.586148 -207.273144)
		(end 296.42308 -207.110076)
		(width 0.14478)
		(layer "In6.Cu")
		(net "M_E_CPU0_SA_DQ<8>")
	)
	(segment
		(start 278.826214 -206.956152)
		(end 278.826214 -207.34655)
		(width 0.14478)
		(layer "In6.Cu")
		(net "M_E_CPU0_SA_DQ<8>")
	)
	(segment
		(start 324.32117 -227.004626)
		(end 324.32117 -226.589082)
		(width 0.0889)
		(layer "In6.Cu")
		(net "M_E_CPU0_SA_DQ<8>")
	)
	(segment
		(start 324.917054 -227.60051)
		(end 324.32117 -227.004626)
		(width 0.0889)
		(layer "In6.Cu")
		(net "M_E_CPU0_SA_DQ<8>")
	)
	(segment
		(start 293.630858 -206.260192)
		(end 290.769802 -206.260192)
		(width 0.14478)
		(layer "In6.Cu")
		(net "M_E_CPU0_SA_DQ<8>")
	)
	(segment
		(start 279.390094 -207.34655)
		(end 279.390094 -206.956152)
		(width 0.14478)
		(layer "In6.Cu")
		(net "M_E_CPU0_SA_DQ<8>")
	)
	(segment
		(start 282.37307 -206.485744)
		(end 282.168346 -206.485744)
		(width 0.14478)
		(layer "In6.Cu")
		(net "M_E_CPU0_SA_DQ<8>")
	)
	(segment
		(start 298.425362 -206.260192)
		(end 297.575478 -207.110076)
		(width 0.14478)
		(layer "In6.Cu")
		(net "M_E_CPU0_SA_DQ<8>")
	)
	(segment
		(start 325.336154 -228.16185)
		(end 324.917054 -227.74275)
		(width 0.0889)
		(layer "In6.Cu")
		(net "M_E_CPU0_SA_DQ<8>")
	)
	(segment
		(start 304.471324 -207.273144)
		(end 304.471324 -207.335882)
		(width 0.14478)
		(layer "In6.Cu")
		(net "M_E_CPU0_SA_DQ<8>")
	)
	(segment
		(start 277.998428 -207.49133)
		(end 277.192232 -206.685134)
		(width 0.14478)
		(layer "In6.Cu")
		(net "M_E_CPU0_SA_DQ<8>")
	)
	(segment
		(start 326.939402 -229.60965)
		(end 326.303894 -229.60965)
		(width 0.0889)
		(layer "In6.Cu")
		(net "M_E_CPU0_SA_DQ<8>")
	)
	(segment
		(start 297.30573 -207.110076)
		(end 297.142662 -207.273144)
		(width 0.14478)
		(layer "In6.Cu")
		(net "M_E_CPU0_SA_DQ<8>")
	)
	(segment
		(start 305.969162 -206.260192)
		(end 305.119278 -207.110076)
		(width 0.14478)
		(layer "In6.Cu")
		(net "M_E_CPU0_SA_DQ<8>")
	)
	(segment
		(start 321.275964 -222.734886)
		(end 319.111122 -220.570044)
		(width 0.14478)
		(layer "In6.Cu")
		(net "M_E_CPU0_SA_DQ<8>")
	)
	(segment
		(start 307.591206 -206.260192)
		(end 307.360828 -206.260192)
		(width 0.14478)
		(layer "In6.Cu")
		(net "M_E_CPU0_SA_DQ<8>")
	)
	(segment
		(start 302.801782 -207.335882)
		(end 302.801782 -207.273144)
		(width 0.14478)
		(layer "In6.Cu")
		(net "M_E_CPU0_SA_DQ<8>")
	)
	(segment
		(start 289.609276 -207.110076)
		(end 289.446208 -207.273144)
		(width 0.14478)
		(layer "In6.Cu")
		(net "M_E_CPU0_SA_DQ<8>")
	)
	(segment
		(start 282.204668 -207.319626)
		(end 282.032964 -207.49133)
		(width 0.14478)
		(layer "In6.Cu")
		(net "M_E_CPU0_SA_DQ<8>")
	)
	(segment
		(start 279.245314 -206.811372)
		(end 278.970994 -206.811372)
		(width 0.14478)
		(layer "In6.Cu")
		(net "M_E_CPU0_SA_DQ<8>")
	)
	(segment
		(start 282.168346 -206.485744)
		(end 281.97429 -206.6798)
		(width 0.14478)
		(layer "In6.Cu")
		(net "M_E_CPU0_SA_DQ<8>")
	)
	(segment
		(start 289.446208 -207.273144)
		(end 289.446208 -207.340962)
		(width 0.14478)
		(layer "In6.Cu")
		(net "M_E_CPU0_SA_DQ<8>")
	)
	(segment
		(start 303.358296 -207.335882)
		(end 303.195228 -207.49895)
		(width 0.14478)
		(layer "In6.Cu")
		(net "M_E_CPU0_SA_DQ<8>")
	)
	(arc
		(start 328.832718 -230.252778)
		(mid 328.670529 -230.275513)
		(end 328.514202 -230.226616)
		(width 0.0889)
		(layer "In6.Cu")
		(net "M_E_CPU0_SA_DQ<8>")
	)
	(arc
		(start 327.94829 -230.226616)
		(mid 327.712821 -230.273861)
		(end 327.49744 -230.167688)
		(width 0.0889)
		(layer "In6.Cu")
		(net "M_E_CPU0_SA_DQ<8>")
	)
	(arc
		(start 328.514202 -230.226616)
		(mid 328.231246 -230.150473)
		(end 327.94829 -230.226616)
		(width 0.0889)
		(layer "In6.Cu")
		(net "M_E_CPU0_SA_DQ<8>")
	)
	(segment
		(start 331.047852 -230.169974)
		(end 330.581 -229.904036)
		(width 0.10668)
		(layer "F.Cu")
		(net "M_E_CPU0_SA_DQ<7>")
	)
	(segment
		(start 305.954938 -205.410054)
		(end 305.1048 -206.260192)
		(width 0.14478)
		(layer "In6.Cu")
		(net "M_E_CPU0_SA_DQ<7>")
	)
	(segment
		(start 308.304692 -205.410054)
		(end 305.954938 -205.410054)
		(width 0.14478)
		(layer "In6.Cu")
		(net "M_E_CPU0_SA_DQ<7>")
	)
	(segment
		(start 330.581 -229.904036)
		(end 330.427076 -229.638606)
		(width 0.0889)
		(layer "In6.Cu")
		(net "M_E_CPU0_SA_DQ<7>")
	)
	(segment
		(start 297.561 -206.260192)
		(end 294.50284 -206.260192)
		(width 0.14478)
		(layer "In6.Cu")
		(net "M_E_CPU0_SA_DQ<7>")
	)
	(segment
		(start 285.963868 -205.410054)
		(end 283.059378 -205.410054)
		(width 0.14478)
		(layer "In6.Cu")
		(net "M_E_CPU0_SA_DQ<7>")
	)
	(segment
		(start 276.260814 -206.260192)
		(end 276.097746 -206.097124)
		(width 0.14478)
		(layer "In6.Cu")
		(net "M_E_CPU0_SA_DQ<7>")
	)
	(segment
		(start 330.427076 -229.638606)
		(end 330.331318 -229.613206)
		(width 0.0889)
		(layer "In6.Cu")
		(net "M_E_CPU0_SA_DQ<7>")
	)
	(segment
		(start 324.581774 -226.94773)
		(end 324.581774 -226.05873)
		(width 0.0889)
		(layer "In6.Cu")
		(net "M_E_CPU0_SA_DQ<7>")
	)
	(segment
		(start 273.51736 -206.260192)
		(end 273.092164 -205.834996)
		(width 0.14478)
		(layer "In6.Cu")
		(net "M_E_CPU0_SA_DQ<7>")
	)
	(segment
		(start 274.428204 -205.586838)
		(end 274.428204 -206.097124)
		(width 0.14478)
		(layer "In6.Cu")
		(net "M_E_CPU0_SA_DQ<7>")
	)
	(segment
		(start 321.827144 -222.50654)
		(end 319.662302 -220.341698)
		(width 0.14478)
		(layer "In6.Cu")
		(net "M_E_CPU0_SA_DQ<7>")
	)
	(segment
		(start 325.176134 -227.67925)
		(end 325.176134 -227.54209)
		(width 0.0889)
		(layer "In6.Cu")
		(net "M_E_CPU0_SA_DQ<7>")
	)
	(segment
		(start 276.097746 -206.097124)
		(end 276.097746 -205.586838)
		(width 0.14478)
		(layer "In6.Cu")
		(net "M_E_CPU0_SA_DQ<7>")
	)
	(segment
		(start 274.428204 -206.097124)
		(end 274.265136 -206.260192)
		(width 0.14478)
		(layer "In6.Cu")
		(net "M_E_CPU0_SA_DQ<7>")
	)
	(segment
		(start 281.484832 -205.914752)
		(end 281.139392 -206.260192)
		(width 0.14478)
		(layer "In6.Cu")
		(net "M_E_CPU0_SA_DQ<7>")
	)
	(segment
		(start 275.378164 -206.260192)
		(end 275.147786 -206.260192)
		(width 0.14478)
		(layer "In6.Cu")
		(net "M_E_CPU0_SA_DQ<7>")
	)
	(segment
		(start 325.176134 -227.54209)
		(end 324.581774 -226.94773)
		(width 0.0889)
		(layer "In6.Cu")
		(net "M_E_CPU0_SA_DQ<7>")
	)
	(segment
		(start 281.139392 -206.260192)
		(end 276.260814 -206.260192)
		(width 0.14478)
		(layer "In6.Cu")
		(net "M_E_CPU0_SA_DQ<7>")
	)
	(segment
		(start 324.581774 -226.05873)
		(end 323.795644 -225.2726)
		(width 0.0889)
		(layer "In6.Cu")
		(net "M_E_CPU0_SA_DQ<7>")
	)
	(segment
		(start 283.059378 -205.410054)
		(end 282.55468 -205.914752)
		(width 0.14478)
		(layer "In6.Cu")
		(net "M_E_CPU0_SA_DQ<7>")
	)
	(segment
		(start 305.1048 -206.260192)
		(end 302.04664 -206.260192)
		(width 0.14478)
		(layer "In6.Cu")
		(net "M_E_CPU0_SA_DQ<7>")
	)
	(segment
		(start 275.7043 -205.42377)
		(end 275.541232 -205.586838)
		(width 0.14478)
		(layer "In6.Cu")
		(net "M_E_CPU0_SA_DQ<7>")
	)
	(segment
		(start 321.827144 -223.3041)
		(end 321.827144 -222.50654)
		(width 0.14478)
		(layer "In6.Cu")
		(net "M_E_CPU0_SA_DQ<7>")
	)
	(segment
		(start 302.04664 -206.260192)
		(end 301.196502 -205.410054)
		(width 0.14478)
		(layer "In6.Cu")
		(net "M_E_CPU0_SA_DQ<7>")
	)
	(segment
		(start 274.984718 -206.097124)
		(end 274.984718 -205.586838)
		(width 0.14478)
		(layer "In6.Cu")
		(net "M_E_CPU0_SA_DQ<7>")
	)
	(segment
		(start 319.662302 -220.341698)
		(end 319.662302 -216.767664)
		(width 0.14478)
		(layer "In6.Cu")
		(net "M_E_CPU0_SA_DQ<7>")
	)
	(segment
		(start 282.55468 -205.914752)
		(end 281.484832 -205.914752)
		(width 0.14478)
		(layer "In6.Cu")
		(net "M_E_CPU0_SA_DQ<7>")
	)
	(segment
		(start 275.934678 -205.42377)
		(end 275.7043 -205.42377)
		(width 0.14478)
		(layer "In6.Cu")
		(net "M_E_CPU0_SA_DQ<7>")
	)
	(segment
		(start 327.761092 -229.53091)
		(end 327.309734 -229.53091)
		(width 0.0889)
		(layer "In6.Cu")
		(net "M_E_CPU0_SA_DQ<7>")
	)
	(segment
		(start 329.828144 -229.58171)
		(end 329.819762 -229.576884)
		(width 0.0889)
		(layer "In6.Cu")
		(net "M_E_CPU0_SA_DQ<7>")
	)
	(segment
		(start 286.814006 -206.260192)
		(end 285.963868 -205.410054)
		(width 0.14478)
		(layer "In6.Cu")
		(net "M_E_CPU0_SA_DQ<7>")
	)
	(segment
		(start 274.984718 -205.586838)
		(end 274.82165 -205.42377)
		(width 0.14478)
		(layer "In6.Cu")
		(net "M_E_CPU0_SA_DQ<7>")
	)
	(segment
		(start 275.147786 -206.260192)
		(end 274.984718 -206.097124)
		(width 0.14478)
		(layer "In6.Cu")
		(net "M_E_CPU0_SA_DQ<7>")
	)
	(segment
		(start 275.541232 -206.097124)
		(end 275.378164 -206.260192)
		(width 0.14478)
		(layer "In6.Cu")
		(net "M_E_CPU0_SA_DQ<7>")
	)
	(segment
		(start 323.795644 -225.2726)
		(end 321.827144 -223.3041)
		(width 0.14478)
		(layer "In6.Cu")
		(net "M_E_CPU0_SA_DQ<7>")
	)
	(segment
		(start 327.309734 -229.53091)
		(end 326.509634 -228.73081)
		(width 0.0889)
		(layer "In6.Cu")
		(net "M_E_CPU0_SA_DQ<7>")
	)
	(segment
		(start 326.509634 -228.73081)
		(end 326.227694 -228.73081)
		(width 0.0889)
		(layer "In6.Cu")
		(net "M_E_CPU0_SA_DQ<7>")
	)
	(segment
		(start 274.591272 -205.42377)
		(end 274.428204 -205.586838)
		(width 0.14478)
		(layer "In6.Cu")
		(net "M_E_CPU0_SA_DQ<7>")
	)
	(segment
		(start 274.265136 -206.260192)
		(end 273.51736 -206.260192)
		(width 0.14478)
		(layer "In6.Cu")
		(net "M_E_CPU0_SA_DQ<7>")
	)
	(segment
		(start 326.227694 -228.73081)
		(end 325.176134 -227.67925)
		(width 0.0889)
		(layer "In6.Cu")
		(net "M_E_CPU0_SA_DQ<7>")
	)
	(segment
		(start 274.82165 -205.42377)
		(end 274.591272 -205.42377)
		(width 0.14478)
		(layer "In6.Cu")
		(net "M_E_CPU0_SA_DQ<7>")
	)
	(segment
		(start 298.411138 -205.410054)
		(end 297.561 -206.260192)
		(width 0.14478)
		(layer "In6.Cu")
		(net "M_E_CPU0_SA_DQ<7>")
	)
	(segment
		(start 275.541232 -205.586838)
		(end 275.541232 -206.097124)
		(width 0.14478)
		(layer "In6.Cu")
		(net "M_E_CPU0_SA_DQ<7>")
	)
	(segment
		(start 289.763454 -206.260192)
		(end 286.814006 -206.260192)
		(width 0.14478)
		(layer "In6.Cu")
		(net "M_E_CPU0_SA_DQ<7>")
	)
	(segment
		(start 319.662302 -216.767664)
		(end 308.304692 -205.410054)
		(width 0.14478)
		(layer "In6.Cu")
		(net "M_E_CPU0_SA_DQ<7>")
	)
	(segment
		(start 301.196502 -205.410054)
		(end 298.411138 -205.410054)
		(width 0.14478)
		(layer "In6.Cu")
		(net "M_E_CPU0_SA_DQ<7>")
	)
	(segment
		(start 293.652702 -205.410054)
		(end 290.613592 -205.410054)
		(width 0.14478)
		(layer "In6.Cu")
		(net "M_E_CPU0_SA_DQ<7>")
	)
	(segment
		(start 294.50284 -206.260192)
		(end 293.652702 -205.410054)
		(width 0.14478)
		(layer "In6.Cu")
		(net "M_E_CPU0_SA_DQ<7>")
	)
	(segment
		(start 276.097746 -205.586838)
		(end 275.934678 -205.42377)
		(width 0.14478)
		(layer "In6.Cu")
		(net "M_E_CPU0_SA_DQ<7>")
	)
	(segment
		(start 290.613592 -205.410054)
		(end 289.763454 -206.260192)
		(width 0.14478)
		(layer "In6.Cu")
		(net "M_E_CPU0_SA_DQ<7>")
	)
	(arc
		(start 329.454002 -229.58171)
		(mid 329.171046 -229.657887)
		(end 328.88809 -229.58171)
		(width 0.0889)
		(layer "In6.Cu")
		(net "M_E_CPU0_SA_DQ<7>")
	)
	(arc
		(start 327.94829 -229.58171)
		(mid 327.858054 -229.543908)
		(end 327.761092 -229.53091)
		(width 0.0889)
		(layer "In6.Cu")
		(net "M_E_CPU0_SA_DQ<7>")
	)
	(arc
		(start 328.514202 -229.58171)
		(mid 328.231246 -229.657887)
		(end 327.94829 -229.58171)
		(width 0.0889)
		(layer "In6.Cu")
		(net "M_E_CPU0_SA_DQ<7>")
	)
	(arc
		(start 328.88809 -229.58171)
		(mid 328.701146 -229.531421)
		(end 328.514202 -229.58171)
		(width 0.0889)
		(layer "In6.Cu")
		(net "M_E_CPU0_SA_DQ<7>")
	)
	(arc
		(start 329.819762 -229.576884)
		(mid 329.636254 -229.531359)
		(end 329.454002 -229.58171)
		(width 0.0889)
		(layer "In6.Cu")
		(net "M_E_CPU0_SA_DQ<7>")
	)
	(arc
		(start 330.331318 -229.613206)
		(mid 330.075996 -229.656906)
		(end 329.828144 -229.58171)
		(width 0.0889)
		(layer "In6.Cu")
		(net "M_E_CPU0_SA_DQ<7>")
	)
	(segment
		(start 329.637898 -229.360222)
		(end 329.171046 -229.094284)
		(width 0.10668)
		(layer "F.Cu")
		(net "M_E_CPU0_SA_DQ<6>")
	)
	(segment
		(start 324.579234 -225.42627)
		(end 324.579234 -224.64141)
		(width 0.0889)
		(layer "In6.Cu")
		(net "M_E_CPU0_SA_DQ<6>")
	)
	(segment
		(start 290.613592 -203.710032)
		(end 289.763454 -204.56017)
		(width 0.14478)
		(layer "In6.Cu")
		(net "M_E_CPU0_SA_DQ<6>")
	)
	(segment
		(start 275.632164 -204.397102)
		(end 275.469096 -204.56017)
		(width 0.14478)
		(layer "In6.Cu")
		(net "M_E_CPU0_SA_DQ<6>")
	)
	(segment
		(start 305.1048 -204.56017)
		(end 302.04664 -204.56017)
		(width 0.14478)
		(layer "In6.Cu")
		(net "M_E_CPU0_SA_DQ<6>")
	)
	(segment
		(start 327.39965 -228.854254)
		(end 326.712326 -228.16693)
		(width 0.0889)
		(layer "In6.Cu")
		(net "M_E_CPU0_SA_DQ<6>")
	)
	(segment
		(start 293.59479 -203.710032)
		(end 290.613592 -203.710032)
		(width 0.14478)
		(layer "In6.Cu")
		(net "M_E_CPU0_SA_DQ<6>")
	)
	(segment
		(start 325.734934 -226.977448)
		(end 325.455534 -226.30257)
		(width 0.0889)
		(layer "In6.Cu")
		(net "M_E_CPU0_SA_DQ<6>")
	)
	(segment
		(start 276.351746 -204.56017)
		(end 276.188678 -204.397102)
		(width 0.14478)
		(layer "In6.Cu")
		(net "M_E_CPU0_SA_DQ<6>")
	)
	(segment
		(start 326.245474 -228.16693)
		(end 325.734934 -227.65639)
		(width 0.0889)
		(layer "In6.Cu")
		(net "M_E_CPU0_SA_DQ<6>")
	)
	(segment
		(start 318.366902 -213.55558)
		(end 317.72225 -213.55558)
		(width 0.14478)
		(layer "In6.Cu")
		(net "M_E_CPU0_SA_DQ<6>")
	)
	(segment
		(start 275.469096 -204.56017)
		(end 275.238718 -204.56017)
		(width 0.14478)
		(layer "In6.Cu")
		(net "M_E_CPU0_SA_DQ<6>")
	)
	(segment
		(start 329.171046 -229.094284)
		(end 329.017122 -228.828854)
		(width 0.0889)
		(layer "In6.Cu")
		(net "M_E_CPU0_SA_DQ<6>")
	)
	(segment
		(start 274.682204 -203.78801)
		(end 274.519136 -203.951078)
		(width 0.14478)
		(layer "In6.Cu")
		(net "M_E_CPU0_SA_DQ<6>")
	)
	(segment
		(start 276.188678 -204.397102)
		(end 276.188678 -203.496418)
		(width 0.14478)
		(layer "In6.Cu")
		(net "M_E_CPU0_SA_DQ<6>")
	)
	(segment
		(start 324.579234 -224.64141)
		(end 324.359016 -224.421192)
		(width 0.0889)
		(layer "In6.Cu")
		(net "M_E_CPU0_SA_DQ<6>")
	)
	(segment
		(start 325.455534 -226.30257)
		(end 324.579234 -225.42627)
		(width 0.0889)
		(layer "In6.Cu")
		(net "M_E_CPU0_SA_DQ<6>")
	)
	(segment
		(start 274.519136 -204.397102)
		(end 274.356068 -204.56017)
		(width 0.14478)
		(layer "In6.Cu")
		(net "M_E_CPU0_SA_DQ<6>")
	)
	(segment
		(start 294.444928 -204.56017)
		(end 293.59479 -203.710032)
		(width 0.14478)
		(layer "In6.Cu")
		(net "M_E_CPU0_SA_DQ<6>")
	)
	(segment
		(start 305.954938 -203.710032)
		(end 305.1048 -204.56017)
		(width 0.14478)
		(layer "In6.Cu")
		(net "M_E_CPU0_SA_DQ<6>")
	)
	(segment
		(start 322.726304 -222.133668)
		(end 320.690494 -220.097858)
		(width 0.14478)
		(layer "In6.Cu")
		(net "M_E_CPU0_SA_DQ<6>")
	)
	(segment
		(start 275.07565 -203.951078)
		(end 274.912582 -203.78801)
		(width 0.14478)
		(layer "In6.Cu")
		(net "M_E_CPU0_SA_DQ<6>")
	)
	(segment
		(start 273.51736 -204.56017)
		(end 273.092164 -204.134974)
		(width 0.14478)
		(layer "In6.Cu")
		(net "M_E_CPU0_SA_DQ<6>")
	)
	(segment
		(start 275.632164 -203.496418)
		(end 275.632164 -204.397102)
		(width 0.14478)
		(layer "In6.Cu")
		(net "M_E_CPU0_SA_DQ<6>")
	)
	(segment
		(start 325.734934 -227.65639)
		(end 325.734934 -226.977448)
		(width 0.0889)
		(layer "In6.Cu")
		(net "M_E_CPU0_SA_DQ<6>")
	)
	(segment
		(start 320.690494 -220.097858)
		(end 320.690494 -215.879172)
		(width 0.14478)
		(layer "In6.Cu")
		(net "M_E_CPU0_SA_DQ<6>")
	)
	(segment
		(start 302.04664 -204.56017)
		(end 301.196502 -203.710032)
		(width 0.14478)
		(layer "In6.Cu")
		(net "M_E_CPU0_SA_DQ<6>")
	)
	(segment
		(start 276.02561 -203.33335)
		(end 275.795232 -203.33335)
		(width 0.14478)
		(layer "In6.Cu")
		(net "M_E_CPU0_SA_DQ<6>")
	)
	(segment
		(start 329.017122 -228.828854)
		(end 328.92111 -228.803454)
		(width 0.0889)
		(layer "In6.Cu")
		(net "M_E_CPU0_SA_DQ<6>")
	)
	(segment
		(start 274.356068 -204.56017)
		(end 273.51736 -204.56017)
		(width 0.14478)
		(layer "In6.Cu")
		(net "M_E_CPU0_SA_DQ<6>")
	)
	(segment
		(start 285.963868 -203.710032)
		(end 283.059378 -203.710032)
		(width 0.14478)
		(layer "In6.Cu")
		(net "M_E_CPU0_SA_DQ<6>")
	)
	(segment
		(start 282.20924 -204.56017)
		(end 276.351746 -204.56017)
		(width 0.14478)
		(layer "In6.Cu")
		(net "M_E_CPU0_SA_DQ<6>")
	)
	(segment
		(start 286.814006 -204.56017)
		(end 285.963868 -203.710032)
		(width 0.14478)
		(layer "In6.Cu")
		(net "M_E_CPU0_SA_DQ<6>")
	)
	(segment
		(start 276.188678 -203.496418)
		(end 276.02561 -203.33335)
		(width 0.14478)
		(layer "In6.Cu")
		(net "M_E_CPU0_SA_DQ<6>")
	)
	(segment
		(start 324.359016 -224.421192)
		(end 322.726304 -222.78848)
		(width 0.14478)
		(layer "In6.Cu")
		(net "M_E_CPU0_SA_DQ<6>")
	)
	(segment
		(start 327.595738 -228.847904)
		(end 327.39965 -228.854254)
		(width 0.0889)
		(layer "In6.Cu")
		(net "M_E_CPU0_SA_DQ<6>")
	)
	(segment
		(start 307.876702 -203.710032)
		(end 305.954938 -203.710032)
		(width 0.14478)
		(layer "In6.Cu")
		(net "M_E_CPU0_SA_DQ<6>")
	)
	(segment
		(start 327.761092 -228.847904)
		(end 327.595738 -228.847904)
		(width 0.0889)
		(layer "In6.Cu")
		(net "M_E_CPU0_SA_DQ<6>")
	)
	(segment
		(start 326.712326 -228.16693)
		(end 326.245474 -228.16693)
		(width 0.0889)
		(layer "In6.Cu")
		(net "M_E_CPU0_SA_DQ<6>")
	)
	(segment
		(start 301.196502 -203.710032)
		(end 298.411138 -203.710032)
		(width 0.14478)
		(layer "In6.Cu")
		(net "M_E_CPU0_SA_DQ<6>")
	)
	(segment
		(start 298.411138 -203.710032)
		(end 297.561 -204.56017)
		(width 0.14478)
		(layer "In6.Cu")
		(net "M_E_CPU0_SA_DQ<6>")
	)
	(segment
		(start 317.72225 -213.55558)
		(end 307.876702 -203.710032)
		(width 0.14478)
		(layer "In6.Cu")
		(net "M_E_CPU0_SA_DQ<6>")
	)
	(segment
		(start 275.238718 -204.56017)
		(end 275.07565 -204.397102)
		(width 0.14478)
		(layer "In6.Cu")
		(net "M_E_CPU0_SA_DQ<6>")
	)
	(segment
		(start 274.912582 -203.78801)
		(end 274.682204 -203.78801)
		(width 0.14478)
		(layer "In6.Cu")
		(net "M_E_CPU0_SA_DQ<6>")
	)
	(segment
		(start 289.763454 -204.56017)
		(end 286.814006 -204.56017)
		(width 0.14478)
		(layer "In6.Cu")
		(net "M_E_CPU0_SA_DQ<6>")
	)
	(segment
		(start 320.690494 -215.879172)
		(end 318.366902 -213.55558)
		(width 0.14478)
		(layer "In6.Cu")
		(net "M_E_CPU0_SA_DQ<6>")
	)
	(segment
		(start 275.07565 -204.397102)
		(end 275.07565 -203.951078)
		(width 0.14478)
		(layer "In6.Cu")
		(net "M_E_CPU0_SA_DQ<6>")
	)
	(segment
		(start 328.41819 -228.771704)
		(end 328.409808 -228.766878)
		(width 0.0889)
		(layer "In6.Cu")
		(net "M_E_CPU0_SA_DQ<6>")
	)
	(segment
		(start 297.561 -204.56017)
		(end 294.444928 -204.56017)
		(width 0.14478)
		(layer "In6.Cu")
		(net "M_E_CPU0_SA_DQ<6>")
	)
	(segment
		(start 274.519136 -203.951078)
		(end 274.519136 -204.397102)
		(width 0.14478)
		(layer "In6.Cu")
		(net "M_E_CPU0_SA_DQ<6>")
	)
	(segment
		(start 275.795232 -203.33335)
		(end 275.632164 -203.496418)
		(width 0.14478)
		(layer "In6.Cu")
		(net "M_E_CPU0_SA_DQ<6>")
	)
	(segment
		(start 283.059378 -203.710032)
		(end 282.20924 -204.56017)
		(width 0.14478)
		(layer "In6.Cu")
		(net "M_E_CPU0_SA_DQ<6>")
	)
	(segment
		(start 322.726304 -222.78848)
		(end 322.726304 -222.133668)
		(width 0.14478)
		(layer "In6.Cu")
		(net "M_E_CPU0_SA_DQ<6>")
	)
	(arc
		(start 328.92111 -228.803454)
		(mid 328.665902 -228.846931)
		(end 328.41819 -228.771704)
		(width 0.0889)
		(layer "In6.Cu")
		(net "M_E_CPU0_SA_DQ<6>")
	)
	(arc
		(start 328.044048 -228.771704)
		(mid 327.907612 -228.828529)
		(end 327.761092 -228.847904)
		(width 0.0889)
		(layer "In6.Cu")
		(net "M_E_CPU0_SA_DQ<6>")
	)
	(arc
		(start 328.409808 -228.766878)
		(mid 328.2263 -228.721384)
		(end 328.044048 -228.771704)
		(width 0.0889)
		(layer "In6.Cu")
		(net "M_E_CPU0_SA_DQ<6>")
	)
	(segment
		(start 330.577952 -229.360222)
		(end 330.1111 -229.094284)
		(width 0.10668)
		(layer "F.Cu")
		(net "M_E_CPU0_SA_DQ<5>")
	)
	(segment
		(start 279.603454 -205.80223)
		(end 279.440386 -205.639162)
		(width 0.14478)
		(layer "In6.Cu")
		(net "M_E_CPU0_SA_DQ<5>")
	)
	(segment
		(start 278.883872 -205.639162)
		(end 278.720804 -205.80223)
		(width 0.14478)
		(layer "In6.Cu")
		(net "M_E_CPU0_SA_DQ<5>")
	)
	(segment
		(start 307.757322 -204.770482)
		(end 307.757322 -204.723238)
		(width 0.14478)
		(layer "In6.Cu")
		(net "M_E_CPU0_SA_DQ<5>")
	)
	(segment
		(start 330.265024 -229.359714)
		(end 330.242926 -229.442772)
		(width 0.0889)
		(layer "In6.Cu")
		(net "M_E_CPU0_SA_DQ<5>")
	)
	(segment
		(start 302.350678 -205.77937)
		(end 302.18761 -205.616302)
		(width 0.14478)
		(layer "In6.Cu")
		(net "M_E_CPU0_SA_DQ<5>")
	)
	(segment
		(start 318.387984 -214.435182)
		(end 318.387984 -214.230458)
		(width 0.14478)
		(layer "In6.Cu")
		(net "M_E_CPU0_SA_DQ<5>")
	)
	(segment
		(start 317.880492 -214.145114)
		(end 317.675768 -214.145114)
		(width 0.14478)
		(layer "In6.Cu")
		(net "M_E_CPU0_SA_DQ<5>")
	)
	(segment
		(start 318.678052 -214.942674)
		(end 318.473328 -214.942674)
		(width 0.14478)
		(layer "In6.Cu")
		(net "M_E_CPU0_SA_DQ<5>")
	)
	(segment
		(start 303.694084 -205.77937)
		(end 303.463706 -205.77937)
		(width 0.14478)
		(layer "In6.Cu")
		(net "M_E_CPU0_SA_DQ<5>")
	)
	(segment
		(start 303.300638 -205.573122)
		(end 303.13757 -205.410054)
		(width 0.14478)
		(layer "In6.Cu")
		(net "M_E_CPU0_SA_DQ<5>")
	)
	(segment
		(start 306.807362 -204.93355)
		(end 306.644294 -204.770482)
		(width 0.14478)
		(layer "In6.Cu")
		(net "M_E_CPU0_SA_DQ<5>")
	)
	(segment
		(start 319.874392 -216.343738)
		(end 319.874392 -216.139014)
		(width 0.14478)
		(layer "In6.Cu")
		(net "M_E_CPU0_SA_DQ<5>")
	)
	(segment
		(start 318.279272 -214.748618)
		(end 318.279272 -214.543894)
		(width 0.14478)
		(layer "In6.Cu")
		(net "M_E_CPU0_SA_DQ<5>")
	)
	(segment
		(start 306.481226 -204.56017)
		(end 306.159662 -204.56017)
		(width 0.14478)
		(layer "In6.Cu")
		(net "M_E_CPU0_SA_DQ<5>")
	)
	(segment
		(start 322.276724 -223.09582)
		(end 322.276724 -222.320104)
		(width 0.14478)
		(layer "In6.Cu")
		(net "M_E_CPU0_SA_DQ<5>")
	)
	(segment
		(start 318.279272 -214.543894)
		(end 318.387984 -214.435182)
		(width 0.14478)
		(layer "In6.Cu")
		(net "M_E_CPU0_SA_DQ<5>")
	)
	(segment
		(start 330.1111 -229.094284)
		(end 330.265024 -229.359714)
		(width 0.0889)
		(layer "In6.Cu")
		(net "M_E_CPU0_SA_DQ<5>")
	)
	(segment
		(start 303.300638 -205.616302)
		(end 303.300638 -205.573122)
		(width 0.14478)
		(layer "In6.Cu")
		(net "M_E_CPU0_SA_DQ<5>")
	)
	(segment
		(start 322.276724 -222.320104)
		(end 320.155316 -220.198696)
		(width 0.14478)
		(layer "In6.Cu")
		(net "M_E_CPU0_SA_DQ<5>")
	)
	(segment
		(start 325.478394 -227.003356)
		(end 325.225156 -226.39147)
		(width 0.0889)
		(layer "In6.Cu")
		(net "M_E_CPU0_SA_DQ<5>")
	)
	(segment
		(start 303.463706 -205.77937)
		(end 303.300638 -205.616302)
		(width 0.14478)
		(layer "In6.Cu")
		(net "M_E_CPU0_SA_DQ<5>")
	)
	(segment
		(start 289.43427 -205.634082)
		(end 289.271202 -205.79715)
		(width 0.14478)
		(layer "In6.Cu")
		(net "M_E_CPU0_SA_DQ<5>")
	)
	(segment
		(start 305.309778 -205.410054)
		(end 305.133248 -205.410054)
		(width 0.14478)
		(layer "In6.Cu")
		(net "M_E_CPU0_SA_DQ<5>")
	)
	(segment
		(start 319.076832 -215.546178)
		(end 319.076832 -215.341454)
		(width 0.14478)
		(layer "In6.Cu")
		(net "M_E_CPU0_SA_DQ<5>")
	)
	(segment
		(start 304.97018 -205.616302)
		(end 304.807112 -205.77937)
		(width 0.14478)
		(layer "In6.Cu")
		(net "M_E_CPU0_SA_DQ<5>")
	)
	(segment
		(start 302.18761 -205.616302)
		(end 302.18761 -205.573122)
		(width 0.14478)
		(layer "In6.Cu")
		(net "M_E_CPU0_SA_DQ<5>")
	)
	(segment
		(start 318.387984 -214.230458)
		(end 318.193928 -214.036402)
		(width 0.14478)
		(layer "In6.Cu")
		(net "M_E_CPU0_SA_DQ<5>")
	)
	(segment
		(start 306.159662 -204.56017)
		(end 305.309778 -205.410054)
		(width 0.14478)
		(layer "In6.Cu")
		(net "M_E_CPU0_SA_DQ<5>")
	)
	(segment
		(start 305.133248 -205.410054)
		(end 304.97018 -205.573122)
		(width 0.14478)
		(layer "In6.Cu")
		(net "M_E_CPU0_SA_DQ<5>")
	)
	(segment
		(start 289.919918 -205.410054)
		(end 289.597338 -205.410054)
		(width 0.14478)
		(layer "In6.Cu")
		(net "M_E_CPU0_SA_DQ<5>")
	)
	(segment
		(start 306.644294 -204.770482)
		(end 306.644294 -204.723238)
		(width 0.14478)
		(layer "In6.Cu")
		(net "M_E_CPU0_SA_DQ<5>")
	)
	(segment
		(start 289.43427 -205.573122)
		(end 289.43427 -205.634082)
		(width 0.14478)
		(layer "In6.Cu")
		(net "M_E_CPU0_SA_DQ<5>")
	)
	(segment
		(start 304.576734 -205.77937)
		(end 304.413666 -205.616302)
		(width 0.14478)
		(layer "In6.Cu")
		(net "M_E_CPU0_SA_DQ<5>")
	)
	(segment
		(start 304.807112 -205.77937)
		(end 304.576734 -205.77937)
		(width 0.14478)
		(layer "In6.Cu")
		(net "M_E_CPU0_SA_DQ<5>")
	)
	(segment
		(start 326.674734 -228.51999)
		(end 326.308974 -228.51999)
		(width 0.0889)
		(layer "In6.Cu")
		(net "M_E_CPU0_SA_DQ<5>")
	)
	(segment
		(start 286.804862 -205.410054)
		(end 285.954978 -204.56017)
		(width 0.14478)
		(layer "In6.Cu")
		(net "M_E_CPU0_SA_DQ<5>")
	)
	(segment
		(start 279.277318 -205.017878)
		(end 279.04694 -205.017878)
		(width 0.14478)
		(layer "In6.Cu")
		(net "M_E_CPU0_SA_DQ<5>")
	)
	(segment
		(start 304.97018 -205.573122)
		(end 304.97018 -205.616302)
		(width 0.14478)
		(layer "In6.Cu")
		(net "M_E_CPU0_SA_DQ<5>")
	)
	(segment
		(start 297.071034 -205.639162)
		(end 296.907966 -205.80223)
		(width 0.14478)
		(layer "In6.Cu")
		(net "M_E_CPU0_SA_DQ<5>")
	)
	(segment
		(start 307.03774 -204.93355)
		(end 306.807362 -204.93355)
		(width 0.14478)
		(layer "In6.Cu")
		(net "M_E_CPU0_SA_DQ<5>")
	)
	(segment
		(start 320.155316 -216.624662)
		(end 319.874392 -216.343738)
		(width 0.14478)
		(layer "In6.Cu")
		(net "M_E_CPU0_SA_DQ<5>")
	)
	(segment
		(start 319.185544 -215.232742)
		(end 319.185544 -215.028018)
		(width 0.14478)
		(layer "In6.Cu")
		(net "M_E_CPU0_SA_DQ<5>")
	)
	(segment
		(start 278.327358 -205.639162)
		(end 278.327358 -205.573122)
		(width 0.14478)
		(layer "In6.Cu")
		(net "M_E_CPU0_SA_DQ<5>")
	)
	(segment
		(start 304.413666 -205.236318)
		(end 304.250598 -205.07325)
		(width 0.14478)
		(layer "In6.Cu")
		(net "M_E_CPU0_SA_DQ<5>")
	)
	(segment
		(start 319.185544 -215.028018)
		(end 318.991488 -214.833962)
		(width 0.14478)
		(layer "In6.Cu")
		(net "M_E_CPU0_SA_DQ<5>")
	)
	(segment
		(start 278.720804 -205.80223)
		(end 278.490426 -205.80223)
		(width 0.14478)
		(layer "In6.Cu")
		(net "M_E_CPU0_SA_DQ<5>")
	)
	(segment
		(start 320.155316 -220.198696)
		(end 320.155316 -216.624662)
		(width 0.14478)
		(layer "In6.Cu")
		(net "M_E_CPU0_SA_DQ<5>")
	)
	(segment
		(start 319.983104 -215.825578)
		(end 319.789048 -215.631522)
		(width 0.14478)
		(layer "In6.Cu")
		(net "M_E_CPU0_SA_DQ<5>")
	)
	(segment
		(start 296.907966 -205.80223)
		(end 296.677588 -205.80223)
		(width 0.14478)
		(layer "In6.Cu")
		(net "M_E_CPU0_SA_DQ<5>")
	)
	(segment
		(start 303.13757 -205.410054)
		(end 302.907192 -205.410054)
		(width 0.14478)
		(layer "In6.Cu")
		(net "M_E_CPU0_SA_DQ<5>")
	)
	(segment
		(start 319.983104 -216.030302)
		(end 319.983104 -215.825578)
		(width 0.14478)
		(layer "In6.Cu")
		(net "M_E_CPU0_SA_DQ<5>")
	)
	(segment
		(start 282.414218 -205.410054)
		(end 280.159968 -205.410054)
		(width 0.14478)
		(layer "In6.Cu")
		(net "M_E_CPU0_SA_DQ<5>")
	)
	(segment
		(start 307.757322 -204.723238)
		(end 307.594254 -204.56017)
		(width 0.14478)
		(layer "In6.Cu")
		(net "M_E_CPU0_SA_DQ<5>")
	)
	(segment
		(start 317.675768 -214.145114)
		(end 308.464204 -204.93355)
		(width 0.14478)
		(layer "In6.Cu")
		(net "M_E_CPU0_SA_DQ<5>")
	)
	(segment
		(start 278.327358 -205.573122)
		(end 278.16429 -205.410054)
		(width 0.14478)
		(layer "In6.Cu")
		(net "M_E_CPU0_SA_DQ<5>")
	)
	(segment
		(start 288.714688 -205.410054)
		(end 286.804862 -205.410054)
		(width 0.14478)
		(layer "In6.Cu")
		(net "M_E_CPU0_SA_DQ<5>")
	)
	(segment
		(start 280.159968 -205.410054)
		(end 279.9969 -205.573122)
		(width 0.14478)
		(layer "In6.Cu")
		(net "M_E_CPU0_SA_DQ<5>")
	)
	(segment
		(start 307.200808 -204.723238)
		(end 307.200808 -204.770482)
		(width 0.14478)
		(layer "In6.Cu")
		(net "M_E_CPU0_SA_DQ<5>")
	)
	(segment
		(start 307.594254 -204.56017)
		(end 307.363876 -204.56017)
		(width 0.14478)
		(layer "In6.Cu")
		(net "M_E_CPU0_SA_DQ<5>")
	)
	(segment
		(start 279.833832 -205.80223)
		(end 279.603454 -205.80223)
		(width 0.14478)
		(layer "In6.Cu")
		(net "M_E_CPU0_SA_DQ<5>")
	)
	(segment
		(start 326.308974 -228.51999)
		(end 325.478394 -227.68941)
		(width 0.0889)
		(layer "In6.Cu")
		(net "M_E_CPU0_SA_DQ<5>")
	)
	(segment
		(start 279.440386 -205.180946)
		(end 279.277318 -205.017878)
		(width 0.14478)
		(layer "In6.Cu")
		(net "M_E_CPU0_SA_DQ<5>")
	)
	(segment
		(start 297.071034 -205.573122)
		(end 297.071034 -205.639162)
		(width 0.14478)
		(layer "In6.Cu")
		(net "M_E_CPU0_SA_DQ<5>")
	)
	(segment
		(start 303.857152 -205.616302)
		(end 303.694084 -205.77937)
		(width 0.14478)
		(layer "In6.Cu")
		(net "M_E_CPU0_SA_DQ<5>")
	)
	(segment
		(start 294.480742 -205.410054)
		(end 293.630858 -204.56017)
		(width 0.14478)
		(layer "In6.Cu")
		(net "M_E_CPU0_SA_DQ<5>")
	)
	(segment
		(start 308.464204 -204.93355)
		(end 307.92039 -204.93355)
		(width 0.14478)
		(layer "In6.Cu")
		(net "M_E_CPU0_SA_DQ<5>")
	)
	(segment
		(start 307.200808 -204.770482)
		(end 307.03774 -204.93355)
		(width 0.14478)
		(layer "In6.Cu")
		(net "M_E_CPU0_SA_DQ<5>")
	)
	(segment
		(start 289.597338 -205.410054)
		(end 289.43427 -205.573122)
		(width 0.14478)
		(layer "In6.Cu")
		(net "M_E_CPU0_SA_DQ<5>")
	)
	(segment
		(start 328.992484 -229.421436)
		(end 328.984102 -229.41661)
		(width 0.0889)
		(layer "In6.Cu")
		(net "M_E_CPU0_SA_DQ<5>")
	)
	(segment
		(start 279.9969 -205.639162)
		(end 279.833832 -205.80223)
		(width 0.14478)
		(layer "In6.Cu")
		(net "M_E_CPU0_SA_DQ<5>")
	)
	(segment
		(start 327.488804 -229.33406)
		(end 326.674734 -228.51999)
		(width 0.0889)
		(layer "In6.Cu")
		(net "M_E_CPU0_SA_DQ<5>")
	)
	(segment
		(start 296.351452 -205.410054)
		(end 294.480742 -205.410054)
		(width 0.14478)
		(layer "In6.Cu")
		(net "M_E_CPU0_SA_DQ<5>")
	)
	(segment
		(start 307.363876 -204.56017)
		(end 307.200808 -204.723238)
		(width 0.14478)
		(layer "In6.Cu")
		(net "M_E_CPU0_SA_DQ<5>")
	)
	(segment
		(start 279.9969 -205.573122)
		(end 279.9969 -205.639162)
		(width 0.14478)
		(layer "In6.Cu")
		(net "M_E_CPU0_SA_DQ<5>")
	)
	(segment
		(start 279.440386 -205.639162)
		(end 279.440386 -205.180946)
		(width 0.14478)
		(layer "In6.Cu")
		(net "M_E_CPU0_SA_DQ<5>")
	)
	(segment
		(start 278.16429 -205.410054)
		(end 277.617174 -205.410054)
		(width 0.14478)
		(layer "In6.Cu")
		(net "M_E_CPU0_SA_DQ<5>")
	)
	(segment
		(start 327.761346 -229.34041)
		(end 327.589896 -229.34041)
		(width 0.0889)
		(layer "In6.Cu")
		(net "M_E_CPU0_SA_DQ<5>")
	)
	(segment
		(start 298.615862 -204.56017)
		(end 297.765978 -205.410054)
		(width 0.14478)
		(layer "In6.Cu")
		(net "M_E_CPU0_SA_DQ<5>")
	)
	(segment
		(start 302.18761 -205.573122)
		(end 301.174658 -204.56017)
		(width 0.14478)
		(layer "In6.Cu")
		(net "M_E_CPU0_SA_DQ<5>")
	)
	(segment
		(start 319.789048 -215.631522)
		(end 319.584324 -215.631522)
		(width 0.14478)
		(layer "In6.Cu")
		(net "M_E_CPU0_SA_DQ<5>")
	)
	(segment
		(start 304.250598 -205.07325)
		(end 304.02022 -205.07325)
		(width 0.14478)
		(layer "In6.Cu")
		(net "M_E_CPU0_SA_DQ<5>")
	)
	(segment
		(start 288.877756 -205.634082)
		(end 288.877756 -205.573122)
		(width 0.14478)
		(layer "In6.Cu")
		(net "M_E_CPU0_SA_DQ<5>")
	)
	(segment
		(start 319.475612 -215.740234)
		(end 319.270888 -215.740234)
		(width 0.14478)
		(layer "In6.Cu")
		(net "M_E_CPU0_SA_DQ<5>")
	)
	(segment
		(start 319.076832 -215.341454)
		(end 319.185544 -215.232742)
		(width 0.14478)
		(layer "In6.Cu")
		(net "M_E_CPU0_SA_DQ<5>")
	)
	(segment
		(start 318.473328 -214.942674)
		(end 318.279272 -214.748618)
		(width 0.14478)
		(layer "In6.Cu")
		(net "M_E_CPU0_SA_DQ<5>")
	)
	(segment
		(start 297.234102 -205.410054)
		(end 297.071034 -205.573122)
		(width 0.14478)
		(layer "In6.Cu")
		(net "M_E_CPU0_SA_DQ<5>")
	)
	(segment
		(start 302.744124 -205.573122)
		(end 302.744124 -205.616302)
		(width 0.14478)
		(layer "In6.Cu")
		(net "M_E_CPU0_SA_DQ<5>")
	)
	(segment
		(start 304.413666 -205.616302)
		(end 304.413666 -205.236318)
		(width 0.14478)
		(layer "In6.Cu")
		(net "M_E_CPU0_SA_DQ<5>")
	)
	(segment
		(start 306.644294 -204.723238)
		(end 306.481226 -204.56017)
		(width 0.14478)
		(layer "In6.Cu")
		(net "M_E_CPU0_SA_DQ<5>")
	)
	(segment
		(start 324.132194 -224.95129)
		(end 322.276724 -223.09582)
		(width 0.14478)
		(layer "In6.Cu")
		(net "M_E_CPU0_SA_DQ<5>")
	)
	(segment
		(start 325.478394 -227.68941)
		(end 325.478394 -227.003356)
		(width 0.0889)
		(layer "In6.Cu")
		(net "M_E_CPU0_SA_DQ<5>")
	)
	(segment
		(start 302.581056 -205.77937)
		(end 302.350678 -205.77937)
		(width 0.14478)
		(layer "In6.Cu")
		(net "M_E_CPU0_SA_DQ<5>")
	)
	(segment
		(start 318.786764 -214.833962)
		(end 318.678052 -214.942674)
		(width 0.14478)
		(layer "In6.Cu")
		(net "M_E_CPU0_SA_DQ<5>")
	)
	(segment
		(start 283.264102 -204.56017)
		(end 282.414218 -205.410054)
		(width 0.14478)
		(layer "In6.Cu")
		(net "M_E_CPU0_SA_DQ<5>")
	)
	(segment
		(start 302.744124 -205.616302)
		(end 302.581056 -205.77937)
		(width 0.14478)
		(layer "In6.Cu")
		(net "M_E_CPU0_SA_DQ<5>")
	)
	(segment
		(start 293.630858 -204.56017)
		(end 290.769802 -204.56017)
		(width 0.14478)
		(layer "In6.Cu")
		(net "M_E_CPU0_SA_DQ<5>")
	)
	(segment
		(start 296.51452 -205.573122)
		(end 296.351452 -205.410054)
		(width 0.14478)
		(layer "In6.Cu")
		(net "M_E_CPU0_SA_DQ<5>")
	)
	(segment
		(start 327.589896 -229.34041)
		(end 327.488804 -229.33406)
		(width 0.0889)
		(layer "In6.Cu")
		(net "M_E_CPU0_SA_DQ<5>")
	)
	(segment
		(start 297.765978 -205.410054)
		(end 297.234102 -205.410054)
		(width 0.14478)
		(layer "In6.Cu")
		(net "M_E_CPU0_SA_DQ<5>")
	)
	(segment
		(start 328.41819 -229.41661)
		(end 328.409808 -229.421436)
		(width 0.0889)
		(layer "In6.Cu")
		(net "M_E_CPU0_SA_DQ<5>")
	)
	(segment
		(start 317.989204 -214.036402)
		(end 317.880492 -214.145114)
		(width 0.14478)
		(layer "In6.Cu")
		(net "M_E_CPU0_SA_DQ<5>")
	)
	(segment
		(start 307.92039 -204.93355)
		(end 307.757322 -204.770482)
		(width 0.14478)
		(layer "In6.Cu")
		(net "M_E_CPU0_SA_DQ<5>")
	)
	(segment
		(start 325.225156 -226.39147)
		(end 324.343014 -225.509328)
		(width 0.0889)
		(layer "In6.Cu")
		(net "M_E_CPU0_SA_DQ<5>")
	)
	(segment
		(start 289.040824 -205.79715)
		(end 288.877756 -205.634082)
		(width 0.14478)
		(layer "In6.Cu")
		(net "M_E_CPU0_SA_DQ<5>")
	)
	(segment
		(start 296.677588 -205.80223)
		(end 296.51452 -205.639162)
		(width 0.14478)
		(layer "In6.Cu")
		(net "M_E_CPU0_SA_DQ<5>")
	)
	(segment
		(start 318.193928 -214.036402)
		(end 317.989204 -214.036402)
		(width 0.14478)
		(layer "In6.Cu")
		(net "M_E_CPU0_SA_DQ<5>")
	)
	(segment
		(start 319.874392 -216.139014)
		(end 319.983104 -216.030302)
		(width 0.14478)
		(layer "In6.Cu")
		(net "M_E_CPU0_SA_DQ<5>")
	)
	(segment
		(start 319.270888 -215.740234)
		(end 319.076832 -215.546178)
		(width 0.14478)
		(layer "In6.Cu")
		(net "M_E_CPU0_SA_DQ<5>")
	)
	(segment
		(start 288.877756 -205.573122)
		(end 288.714688 -205.410054)
		(width 0.14478)
		(layer "In6.Cu")
		(net "M_E_CPU0_SA_DQ<5>")
	)
	(segment
		(start 278.883872 -205.180946)
		(end 278.883872 -205.639162)
		(width 0.14478)
		(layer "In6.Cu")
		(net "M_E_CPU0_SA_DQ<5>")
	)
	(segment
		(start 279.04694 -205.017878)
		(end 278.883872 -205.180946)
		(width 0.14478)
		(layer "In6.Cu")
		(net "M_E_CPU0_SA_DQ<5>")
	)
	(segment
		(start 303.857152 -205.236318)
		(end 303.857152 -205.616302)
		(width 0.14478)
		(layer "In6.Cu")
		(net "M_E_CPU0_SA_DQ<5>")
	)
	(segment
		(start 304.02022 -205.07325)
		(end 303.857152 -205.236318)
		(width 0.14478)
		(layer "In6.Cu")
		(net "M_E_CPU0_SA_DQ<5>")
	)
	(segment
		(start 285.954978 -204.56017)
		(end 283.264102 -204.56017)
		(width 0.14478)
		(layer "In6.Cu")
		(net "M_E_CPU0_SA_DQ<5>")
	)
	(segment
		(start 319.584324 -215.631522)
		(end 319.475612 -215.740234)
		(width 0.14478)
		(layer "In6.Cu")
		(net "M_E_CPU0_SA_DQ<5>")
	)
	(segment
		(start 278.490426 -205.80223)
		(end 278.327358 -205.639162)
		(width 0.14478)
		(layer "In6.Cu")
		(net "M_E_CPU0_SA_DQ<5>")
	)
	(segment
		(start 318.991488 -214.833962)
		(end 318.786764 -214.833962)
		(width 0.14478)
		(layer "In6.Cu")
		(net "M_E_CPU0_SA_DQ<5>")
	)
	(segment
		(start 302.907192 -205.410054)
		(end 302.744124 -205.573122)
		(width 0.14478)
		(layer "In6.Cu")
		(net "M_E_CPU0_SA_DQ<5>")
	)
	(segment
		(start 277.617174 -205.410054)
		(end 277.192232 -204.985112)
		(width 0.14478)
		(layer "In6.Cu")
		(net "M_E_CPU0_SA_DQ<5>")
	)
	(segment
		(start 301.174658 -204.56017)
		(end 298.615862 -204.56017)
		(width 0.14478)
		(layer "In6.Cu")
		(net "M_E_CPU0_SA_DQ<5>")
	)
	(segment
		(start 324.343014 -225.16211)
		(end 324.132194 -224.95129)
		(width 0.0889)
		(layer "In6.Cu")
		(net "M_E_CPU0_SA_DQ<5>")
	)
	(segment
		(start 289.271202 -205.79715)
		(end 289.040824 -205.79715)
		(width 0.14478)
		(layer "In6.Cu")
		(net "M_E_CPU0_SA_DQ<5>")
	)
	(segment
		(start 324.343014 -225.509328)
		(end 324.343014 -225.16211)
		(width 0.0889)
		(layer "In6.Cu")
		(net "M_E_CPU0_SA_DQ<5>")
	)
	(segment
		(start 296.51452 -205.639162)
		(end 296.51452 -205.573122)
		(width 0.14478)
		(layer "In6.Cu")
		(net "M_E_CPU0_SA_DQ<5>")
	)
	(segment
		(start 290.769802 -204.56017)
		(end 289.919918 -205.410054)
		(width 0.14478)
		(layer "In6.Cu")
		(net "M_E_CPU0_SA_DQ<5>")
	)
	(arc
		(start 329.358244 -229.41661)
		(mid 329.175993 -229.466994)
		(end 328.992484 -229.421436)
		(width 0.0889)
		(layer "In6.Cu")
		(net "M_E_CPU0_SA_DQ<5>")
	)
	(arc
		(start 329.924156 -229.41661)
		(mid 329.6412 -229.340433)
		(end 329.358244 -229.41661)
		(width 0.0889)
		(layer "In6.Cu")
		(net "M_E_CPU0_SA_DQ<5>")
	)
	(arc
		(start 330.242926 -229.442772)
		(mid 330.080595 -229.465621)
		(end 329.924156 -229.41661)
		(width 0.0889)
		(layer "In6.Cu")
		(net "M_E_CPU0_SA_DQ<5>")
	)
	(arc
		(start 328.409808 -229.421436)
		(mid 328.2263 -229.466961)
		(end 328.044048 -229.41661)
		(width 0.0889)
		(layer "In6.Cu")
		(net "M_E_CPU0_SA_DQ<5>")
	)
	(arc
		(start 328.044048 -229.41661)
		(mid 327.90773 -229.359843)
		(end 327.761346 -229.34041)
		(width 0.0889)
		(layer "In6.Cu")
		(net "M_E_CPU0_SA_DQ<5>")
	)
	(arc
		(start 328.984102 -229.41661)
		(mid 328.701146 -229.340433)
		(end 328.41819 -229.41661)
		(width 0.0889)
		(layer "In6.Cu")
		(net "M_E_CPU0_SA_DQ<5>")
	)
	(segment
		(start 329.167998 -228.550216)
		(end 328.701146 -228.284278)
		(width 0.10668)
		(layer "F.Cu")
		(net "M_E_CPU0_SA_DQ<4>")
	)
	(segment
		(start 316.636654 -211.828888)
		(end 316.442598 -211.634832)
		(width 0.14478)
		(layer "In6.Cu")
		(net "M_E_CPU0_SA_DQ<4>")
	)
	(segment
		(start 314.448698 -209.436208)
		(end 314.243974 -209.436208)
		(width 0.14478)
		(layer "In6.Cu")
		(net "M_E_CPU0_SA_DQ<4>")
	)
	(segment
		(start 308.049676 -203.24699)
		(end 305.77282 -203.24699)
		(width 0.14478)
		(layer "In6.Cu")
		(net "M_E_CPU0_SA_DQ<4>")
	)
	(segment
		(start 303.101756 -203.8731)
		(end 303.101756 -203.932282)
		(width 0.14478)
		(layer "In6.Cu")
		(net "M_E_CPU0_SA_DQ<4>")
	)
	(segment
		(start 296.520616 -203.8731)
		(end 296.3672 -203.719684)
		(width 0.14478)
		(layer "In6.Cu")
		(net "M_E_CPU0_SA_DQ<4>")
	)
	(segment
		(start 316.442598 -211.430108)
		(end 316.556644 -211.316062)
		(width 0.14478)
		(layer "In6.Cu")
		(net "M_E_CPU0_SA_DQ<4>")
	)
	(segment
		(start 303.495202 -203.710032)
		(end 303.264824 -203.710032)
		(width 0.14478)
		(layer "In6.Cu")
		(net "M_E_CPU0_SA_DQ<4>")
	)
	(segment
		(start 303.821338 -204.09535)
		(end 303.65827 -203.932282)
		(width 0.14478)
		(layer "In6.Cu")
		(net "M_E_CPU0_SA_DQ<4>")
	)
	(segment
		(start 305.77282 -203.24699)
		(end 305.309778 -203.710032)
		(width 0.14478)
		(layer "In6.Cu")
		(net "M_E_CPU0_SA_DQ<4>")
	)
	(segment
		(start 304.214784 -203.932282)
		(end 304.051716 -204.09535)
		(width 0.14478)
		(layer "In6.Cu")
		(net "M_E_CPU0_SA_DQ<4>")
	)
	(segment
		(start 313.135518 -208.332832)
		(end 308.049676 -203.24699)
		(width 0.14478)
		(layer "In6.Cu")
		(net "M_E_CPU0_SA_DQ<4>")
	)
	(segment
		(start 278.587962 -203.546964)
		(end 278.587962 -203.079858)
		(width 0.14478)
		(layer "In6.Cu")
		(net "M_E_CPU0_SA_DQ<4>")
	)
	(segment
		(start 281.397202 -203.937362)
		(end 281.397202 -203.8731)
		(width 0.14478)
		(layer "In6.Cu")
		(net "M_E_CPU0_SA_DQ<4>")
	)
	(segment
		(start 325.003414 -224.33153)
		(end 325.003414 -224.12833)
		(width 0.0889)
		(layer "In6.Cu")
		(net "M_E_CPU0_SA_DQ<4>")
	)
	(segment
		(start 291.17163 -203.023216)
		(end 291.008562 -202.860148)
		(width 0.14478)
		(layer "In6.Cu")
		(net "M_E_CPU0_SA_DQ<4>")
	)
	(segment
		(start 317.354204 -212.113622)
		(end 317.354204 -211.908898)
		(width 0.14478)
		(layer "In6.Cu")
		(net "M_E_CPU0_SA_DQ<4>")
	)
	(segment
		(start 297.07713 -203.8731)
		(end 297.07713 -203.937362)
		(width 0.14478)
		(layer "In6.Cu")
		(net "M_E_CPU0_SA_DQ<4>")
	)
	(segment
		(start 317.354204 -211.908898)
		(end 317.160148 -211.714842)
		(width 0.14478)
		(layer "In6.Cu")
		(net "M_E_CPU0_SA_DQ<4>")
	)
	(segment
		(start 281.243786 -203.719684)
		(end 280.157682 -203.719684)
		(width 0.14478)
		(layer "In6.Cu")
		(net "M_E_CPU0_SA_DQ<4>")
	)
	(segment
		(start 289.446208 -203.937362)
		(end 289.28314 -204.10043)
		(width 0.14478)
		(layer "In6.Cu")
		(net "M_E_CPU0_SA_DQ<4>")
	)
	(segment
		(start 316.043818 -211.031328)
		(end 315.839094 -211.031328)
		(width 0.14478)
		(layer "In6.Cu")
		(net "M_E_CPU0_SA_DQ<4>")
	)
	(segment
		(start 317.160148 -211.714842)
		(end 316.955424 -211.714842)
		(width 0.14478)
		(layer "In6.Cu")
		(net "M_E_CPU0_SA_DQ<4>")
	)
	(segment
		(start 314.163964 -208.718658)
		(end 313.969908 -208.524602)
		(width 0.14478)
		(layer "In6.Cu")
		(net "M_E_CPU0_SA_DQ<4>")
	)
	(segment
		(start 296.683684 -204.10043)
		(end 296.520616 -203.937362)
		(width 0.14478)
		(layer "In6.Cu")
		(net "M_E_CPU0_SA_DQ<4>")
	)
	(segment
		(start 324.718934 -223.84385)
		(end 323.175884 -222.3008)
		(width 0.14478)
		(layer "In6.Cu")
		(net "M_E_CPU0_SA_DQ<4>")
	)
	(segment
		(start 315.041534 -210.233768)
		(end 314.847478 -210.039712)
		(width 0.14478)
		(layer "In6.Cu")
		(net "M_E_CPU0_SA_DQ<4>")
	)
	(segment
		(start 321.145154 -215.697816)
		(end 318.162432 -212.715094)
		(width 0.14478)
		(layer "In6.Cu")
		(net "M_E_CPU0_SA_DQ<4>")
	)
	(segment
		(start 297.765978 -203.710032)
		(end 297.240198 -203.710032)
		(width 0.14478)
		(layer "In6.Cu")
		(net "M_E_CPU0_SA_DQ<4>")
	)
	(segment
		(start 314.049918 -209.242152)
		(end 314.049918 -209.037428)
		(width 0.14478)
		(layer "In6.Cu")
		(net "M_E_CPU0_SA_DQ<4>")
	)
	(segment
		(start 289.446208 -203.8731)
		(end 289.446208 -203.937362)
		(width 0.14478)
		(layer "In6.Cu")
		(net "M_E_CPU0_SA_DQ<4>")
	)
	(segment
		(start 328.701146 -228.284278)
		(end 328.85507 -228.549708)
		(width 0.0889)
		(layer "In6.Cu")
		(net "M_E_CPU0_SA_DQ<4>")
	)
	(segment
		(start 282.414218 -203.710032)
		(end 282.116784 -203.710032)
		(width 0.14478)
		(layer "In6.Cu")
		(net "M_E_CPU0_SA_DQ<4>")
	)
	(segment
		(start 326.331834 -227.96373)
		(end 325.973694 -227.60559)
		(width 0.0889)
		(layer "In6.Cu")
		(net "M_E_CPU0_SA_DQ<4>")
	)
	(segment
		(start 281.397202 -203.8731)
		(end 281.243786 -203.719684)
		(width 0.14478)
		(layer "In6.Cu")
		(net "M_E_CPU0_SA_DQ<4>")
	)
	(segment
		(start 284.099 -203.11999)
		(end 283.802328 -203.11999)
		(width 0.14478)
		(layer "In6.Cu")
		(net "M_E_CPU0_SA_DQ<4>")
	)
	(segment
		(start 291.728144 -203.089002)
		(end 291.565076 -203.25207)
		(width 0.14478)
		(layer "In6.Cu")
		(net "M_E_CPU0_SA_DQ<4>")
	)
	(segment
		(start 313.969908 -208.524602)
		(end 313.765184 -208.524602)
		(width 0.14478)
		(layer "In6.Cu")
		(net "M_E_CPU0_SA_DQ<4>")
	)
	(segment
		(start 314.767468 -209.322162)
		(end 314.562744 -209.322162)
		(width 0.14478)
		(layer "In6.Cu")
		(net "M_E_CPU0_SA_DQ<4>")
	)
	(segment
		(start 302.938688 -204.09535)
		(end 302.70831 -204.09535)
		(width 0.14478)
		(layer "In6.Cu")
		(net "M_E_CPU0_SA_DQ<4>")
	)
	(segment
		(start 313.140598 -208.332832)
		(end 313.135518 -208.332832)
		(width 0.14478)
		(layer "In6.Cu")
		(net "M_E_CPU0_SA_DQ<4>")
	)
	(segment
		(start 277.617174 -203.710032)
		(end 277.192232 -203.28509)
		(width 0.14478)
		(layer "In6.Cu")
		(net "M_E_CPU0_SA_DQ<4>")
	)
	(segment
		(start 279.841198 -204.09789)
		(end 279.61082 -204.09789)
		(width 0.14478)
		(layer "In6.Cu")
		(net "M_E_CPU0_SA_DQ<4>")
	)
	(segment
		(start 278.75103 -203.710032)
		(end 278.587962 -203.546964)
		(width 0.14478)
		(layer "In6.Cu")
		(net "M_E_CPU0_SA_DQ<4>")
	)
	(segment
		(start 314.163964 -208.923382)
		(end 314.163964 -208.718658)
		(width 0.14478)
		(layer "In6.Cu")
		(net "M_E_CPU0_SA_DQ<4>")
	)
	(segment
		(start 325.55307 -224.881186)
		(end 325.003414 -224.33153)
		(width 0.0889)
		(layer "In6.Cu")
		(net "M_E_CPU0_SA_DQ<4>")
	)
	(segment
		(start 288.889694 -203.8731)
		(end 288.736278 -203.719684)
		(width 0.14478)
		(layer "In6.Cu")
		(net "M_E_CPU0_SA_DQ<4>")
	)
	(segment
		(start 278.587962 -203.079858)
		(end 278.424894 -202.91679)
		(width 0.14478)
		(layer "In6.Cu")
		(net "M_E_CPU0_SA_DQ<4>")
	)
	(segment
		(start 289.919918 -203.710032)
		(end 289.609276 -203.710032)
		(width 0.14478)
		(layer "In6.Cu")
		(net "M_E_CPU0_SA_DQ<4>")
	)
	(segment
		(start 279.447752 -203.934822)
		(end 279.447752 -203.8731)
		(width 0.14478)
		(layer "In6.Cu")
		(net "M_E_CPU0_SA_DQ<4>")
	)
	(segment
		(start 315.839094 -211.031328)
		(end 315.645038 -210.837272)
		(width 0.14478)
		(layer "In6.Cu")
		(net "M_E_CPU0_SA_DQ<4>")
	)
	(segment
		(start 293.554658 -202.8698)
		(end 291.88156 -202.8698)
		(width 0.14478)
		(layer "In6.Cu")
		(net "M_E_CPU0_SA_DQ<4>")
	)
	(segment
		(start 313.765184 -208.524602)
		(end 313.651138 -208.638648)
		(width 0.14478)
		(layer "In6.Cu")
		(net "M_E_CPU0_SA_DQ<4>")
	)
	(segment
		(start 315.759084 -210.313778)
		(end 315.565028 -210.119722)
		(width 0.14478)
		(layer "In6.Cu")
		(net "M_E_CPU0_SA_DQ<4>")
	)
	(segment
		(start 289.28314 -204.10043)
		(end 289.052762 -204.10043)
		(width 0.14478)
		(layer "In6.Cu")
		(net "M_E_CPU0_SA_DQ<4>")
	)
	(segment
		(start 325.003414 -224.12833)
		(end 324.718934 -223.84385)
		(width 0.0889)
		(layer "In6.Cu")
		(net "M_E_CPU0_SA_DQ<4>")
	)
	(segment
		(start 291.565076 -203.25207)
		(end 291.334698 -203.25207)
		(width 0.14478)
		(layer "In6.Cu")
		(net "M_E_CPU0_SA_DQ<4>")
	)
	(segment
		(start 315.759084 -210.518502)
		(end 315.759084 -210.313778)
		(width 0.14478)
		(layer "In6.Cu")
		(net "M_E_CPU0_SA_DQ<4>")
	)
	(segment
		(start 316.841378 -211.828888)
		(end 316.636654 -211.828888)
		(width 0.14478)
		(layer "In6.Cu")
		(net "M_E_CPU0_SA_DQ<4>")
	)
	(segment
		(start 316.556644 -211.111338)
		(end 316.362588 -210.917282)
		(width 0.14478)
		(layer "In6.Cu")
		(net "M_E_CPU0_SA_DQ<4>")
	)
	(segment
		(start 316.556644 -211.316062)
		(end 316.556644 -211.111338)
		(width 0.14478)
		(layer "In6.Cu")
		(net "M_E_CPU0_SA_DQ<4>")
	)
	(segment
		(start 301.96155 -203.710032)
		(end 301.121318 -202.8698)
		(width 0.14478)
		(layer "In6.Cu")
		(net "M_E_CPU0_SA_DQ<4>")
	)
	(segment
		(start 316.955424 -211.714842)
		(end 316.841378 -211.828888)
		(width 0.14478)
		(layer "In6.Cu")
		(net "M_E_CPU0_SA_DQ<4>")
	)
	(segment
		(start 302.70831 -204.09535)
		(end 302.545242 -203.932282)
		(width 0.14478)
		(layer "In6.Cu")
		(net "M_E_CPU0_SA_DQ<4>")
	)
	(segment
		(start 290.769802 -202.860148)
		(end 289.919918 -203.710032)
		(width 0.14478)
		(layer "In6.Cu")
		(net "M_E_CPU0_SA_DQ<4>")
	)
	(segment
		(start 303.65827 -203.8731)
		(end 303.495202 -203.710032)
		(width 0.14478)
		(layer "In6.Cu")
		(net "M_E_CPU0_SA_DQ<4>")
	)
	(segment
		(start 281.953716 -203.8731)
		(end 281.953716 -203.937362)
		(width 0.14478)
		(layer "In6.Cu")
		(net "M_E_CPU0_SA_DQ<4>")
	)
	(segment
		(start 327.490328 -228.657404)
		(end 326.796654 -227.96373)
		(width 0.0889)
		(layer "In6.Cu")
		(net "M_E_CPU0_SA_DQ<4>")
	)
	(segment
		(start 317.240158 -212.227668)
		(end 317.354204 -212.113622)
		(width 0.14478)
		(layer "In6.Cu")
		(net "M_E_CPU0_SA_DQ<4>")
	)
	(segment
		(start 328.85507 -228.549708)
		(end 328.832718 -228.63302)
		(width 0.0889)
		(layer "In6.Cu")
		(net "M_E_CPU0_SA_DQ<4>")
	)
	(segment
		(start 314.562744 -209.322162)
		(end 314.448698 -209.436208)
		(width 0.14478)
		(layer "In6.Cu")
		(net "M_E_CPU0_SA_DQ<4>")
	)
	(segment
		(start 305.309778 -203.710032)
		(end 304.377852 -203.710032)
		(width 0.14478)
		(layer "In6.Cu")
		(net "M_E_CPU0_SA_DQ<4>")
	)
	(segment
		(start 325.662036 -226.215956)
		(end 325.480934 -226.034854)
		(width 0.0889)
		(layer "In6.Cu")
		(net "M_E_CPU0_SA_DQ<4>")
	)
	(segment
		(start 325.973694 -226.968304)
		(end 325.662036 -226.215956)
		(width 0.0889)
		(layer "In6.Cu")
		(net "M_E_CPU0_SA_DQ<4>")
	)
	(segment
		(start 289.052762 -204.10043)
		(end 288.889694 -203.937362)
		(width 0.14478)
		(layer "In6.Cu")
		(net "M_E_CPU0_SA_DQ<4>")
	)
	(segment
		(start 314.961524 -209.516218)
		(end 314.767468 -209.322162)
		(width 0.14478)
		(layer "In6.Cu")
		(net "M_E_CPU0_SA_DQ<4>")
	)
	(segment
		(start 325.55307 -225.676714)
		(end 325.55307 -224.881186)
		(width 0.0889)
		(layer "In6.Cu")
		(net "M_E_CPU0_SA_DQ<4>")
	)
	(segment
		(start 283.542486 -202.860148)
		(end 283.264102 -202.860148)
		(width 0.14478)
		(layer "In6.Cu")
		(net "M_E_CPU0_SA_DQ<4>")
	)
	(segment
		(start 280.004266 -203.934822)
		(end 279.841198 -204.09789)
		(width 0.14478)
		(layer "In6.Cu")
		(net "M_E_CPU0_SA_DQ<4>")
	)
	(segment
		(start 296.3672 -203.719684)
		(end 294.404542 -203.719684)
		(width 0.14478)
		(layer "In6.Cu")
		(net "M_E_CPU0_SA_DQ<4>")
	)
	(segment
		(start 286.814514 -203.719684)
		(end 285.96463 -202.8698)
		(width 0.14478)
		(layer "In6.Cu")
		(net "M_E_CPU0_SA_DQ<4>")
	)
	(segment
		(start 291.88156 -202.8698)
		(end 291.728144 -203.023216)
		(width 0.14478)
		(layer "In6.Cu")
		(net "M_E_CPU0_SA_DQ<4>")
	)
	(segment
		(start 288.736278 -203.719684)
		(end 286.814514 -203.719684)
		(width 0.14478)
		(layer "In6.Cu")
		(net "M_E_CPU0_SA_DQ<4>")
	)
	(segment
		(start 316.157864 -210.917282)
		(end 316.043818 -211.031328)
		(width 0.14478)
		(layer "In6.Cu")
		(net "M_E_CPU0_SA_DQ<4>")
	)
	(segment
		(start 281.56027 -204.10043)
		(end 281.397202 -203.937362)
		(width 0.14478)
		(layer "In6.Cu")
		(net "M_E_CPU0_SA_DQ<4>")
	)
	(segment
		(start 291.17163 -203.089002)
		(end 291.17163 -203.023216)
		(width 0.14478)
		(layer "In6.Cu")
		(net "M_E_CPU0_SA_DQ<4>")
	)
	(segment
		(start 315.645038 -210.837272)
		(end 315.645038 -210.632548)
		(width 0.14478)
		(layer "In6.Cu")
		(net "M_E_CPU0_SA_DQ<4>")
	)
	(segment
		(start 279.61082 -204.09789)
		(end 279.447752 -203.934822)
		(width 0.14478)
		(layer "In6.Cu")
		(net "M_E_CPU0_SA_DQ<4>")
	)
	(segment
		(start 291.728144 -203.023216)
		(end 291.728144 -203.089002)
		(width 0.14478)
		(layer "In6.Cu")
		(net "M_E_CPU0_SA_DQ<4>")
	)
	(segment
		(start 315.360304 -210.119722)
		(end 315.246258 -210.233768)
		(width 0.14478)
		(layer "In6.Cu")
		(net "M_E_CPU0_SA_DQ<4>")
	)
	(segment
		(start 315.565028 -210.119722)
		(end 315.360304 -210.119722)
		(width 0.14478)
		(layer "In6.Cu")
		(net "M_E_CPU0_SA_DQ<4>")
	)
	(segment
		(start 284.34919 -202.8698)
		(end 284.099 -203.11999)
		(width 0.14478)
		(layer "In6.Cu")
		(net "M_E_CPU0_SA_DQ<4>")
	)
	(segment
		(start 325.973694 -227.60559)
		(end 325.973694 -226.968304)
		(width 0.0889)
		(layer "In6.Cu")
		(net "M_E_CPU0_SA_DQ<4>")
	)
	(segment
		(start 323.175884 -222.3008)
		(end 323.175884 -221.947232)
		(width 0.14478)
		(layer "In6.Cu")
		(net "M_E_CPU0_SA_DQ<4>")
	)
	(segment
		(start 281.953716 -203.937362)
		(end 281.790648 -204.10043)
		(width 0.14478)
		(layer "In6.Cu")
		(net "M_E_CPU0_SA_DQ<4>")
	)
	(segment
		(start 314.049918 -209.037428)
		(end 314.163964 -208.923382)
		(width 0.14478)
		(layer "In6.Cu")
		(net "M_E_CPU0_SA_DQ<4>")
	)
	(segment
		(start 313.651138 -208.638648)
		(end 313.446414 -208.638648)
		(width 0.14478)
		(layer "In6.Cu")
		(net "M_E_CPU0_SA_DQ<4>")
	)
	(segment
		(start 304.214784 -203.8731)
		(end 304.214784 -203.932282)
		(width 0.14478)
		(layer "In6.Cu")
		(net "M_E_CPU0_SA_DQ<4>")
	)
	(segment
		(start 291.334698 -203.25207)
		(end 291.17163 -203.089002)
		(width 0.14478)
		(layer "In6.Cu")
		(net "M_E_CPU0_SA_DQ<4>")
	)
	(segment
		(start 325.480934 -225.74885)
		(end 325.55307 -225.676714)
		(width 0.0889)
		(layer "In6.Cu")
		(net "M_E_CPU0_SA_DQ<4>")
	)
	(segment
		(start 278.194516 -202.91679)
		(end 278.031448 -203.079858)
		(width 0.14478)
		(layer "In6.Cu")
		(net "M_E_CPU0_SA_DQ<4>")
	)
	(segment
		(start 302.545242 -203.932282)
		(end 302.545242 -203.8731)
		(width 0.14478)
		(layer "In6.Cu")
		(net "M_E_CPU0_SA_DQ<4>")
	)
	(segment
		(start 327.761092 -228.657404)
		(end 327.490328 -228.657404)
		(width 0.0889)
		(layer "In6.Cu")
		(net "M_E_CPU0_SA_DQ<4>")
	)
	(segment
		(start 318.162432 -212.715094)
		(end 317.957708 -212.715094)
		(width 0.14478)
		(layer "In6.Cu")
		(net "M_E_CPU0_SA_DQ<4>")
	)
	(segment
		(start 278.424894 -202.91679)
		(end 278.194516 -202.91679)
		(width 0.14478)
		(layer "In6.Cu")
		(net "M_E_CPU0_SA_DQ<4>")
	)
	(segment
		(start 288.889694 -203.937362)
		(end 288.889694 -203.8731)
		(width 0.14478)
		(layer "In6.Cu")
		(net "M_E_CPU0_SA_DQ<4>")
	)
	(segment
		(start 283.264102 -202.860148)
		(end 282.414218 -203.710032)
		(width 0.14478)
		(layer "In6.Cu")
		(net "M_E_CPU0_SA_DQ<4>")
	)
	(segment
		(start 277.86838 -203.710032)
		(end 277.617174 -203.710032)
		(width 0.14478)
		(layer "In6.Cu")
		(net "M_E_CPU0_SA_DQ<4>")
	)
	(segment
		(start 316.362588 -210.917282)
		(end 316.157864 -210.917282)
		(width 0.14478)
		(layer "In6.Cu")
		(net "M_E_CPU0_SA_DQ<4>")
	)
	(segment
		(start 302.545242 -203.8731)
		(end 302.382174 -203.710032)
		(width 0.14478)
		(layer "In6.Cu")
		(net "M_E_CPU0_SA_DQ<4>")
	)
	(segment
		(start 315.645038 -210.632548)
		(end 315.759084 -210.518502)
		(width 0.14478)
		(layer "In6.Cu")
		(net "M_E_CPU0_SA_DQ<4>")
	)
	(segment
		(start 280.157682 -203.719684)
		(end 280.004266 -203.8731)
		(width 0.14478)
		(layer "In6.Cu")
		(net "M_E_CPU0_SA_DQ<4>")
	)
	(segment
		(start 317.637922 -212.830156)
		(end 317.240158 -212.432392)
		(width 0.14478)
		(layer "In6.Cu")
		(net "M_E_CPU0_SA_DQ<4>")
	)
	(segment
		(start 294.404542 -203.719684)
		(end 293.554658 -202.8698)
		(width 0.14478)
		(layer "In6.Cu")
		(net "M_E_CPU0_SA_DQ<4>")
	)
	(segment
		(start 325.480934 -226.034854)
		(end 325.480934 -225.74885)
		(width 0.0889)
		(layer "In6.Cu")
		(net "M_E_CPU0_SA_DQ<4>")
	)
	(segment
		(start 314.243974 -209.436208)
		(end 314.049918 -209.242152)
		(width 0.14478)
		(layer "In6.Cu")
		(net "M_E_CPU0_SA_DQ<4>")
	)
	(segment
		(start 326.796654 -227.96373)
		(end 326.331834 -227.96373)
		(width 0.0889)
		(layer "In6.Cu")
		(net "M_E_CPU0_SA_DQ<4>")
	)
	(segment
		(start 296.914062 -204.10043)
		(end 296.683684 -204.10043)
		(width 0.14478)
		(layer "In6.Cu")
		(net "M_E_CPU0_SA_DQ<4>")
	)
	(segment
		(start 314.961524 -209.720942)
		(end 314.961524 -209.516218)
		(width 0.14478)
		(layer "In6.Cu")
		(net "M_E_CPU0_SA_DQ<4>")
	)
	(segment
		(start 291.008562 -202.860148)
		(end 290.769802 -202.860148)
		(width 0.14478)
		(layer "In6.Cu")
		(net "M_E_CPU0_SA_DQ<4>")
	)
	(segment
		(start 317.842646 -212.830156)
		(end 317.637922 -212.830156)
		(width 0.14478)
		(layer "In6.Cu")
		(net "M_E_CPU0_SA_DQ<4>")
	)
	(segment
		(start 303.65827 -203.932282)
		(end 303.65827 -203.8731)
		(width 0.14478)
		(layer "In6.Cu")
		(net "M_E_CPU0_SA_DQ<4>")
	)
	(segment
		(start 296.520616 -203.937362)
		(end 296.520616 -203.8731)
		(width 0.14478)
		(layer "In6.Cu")
		(net "M_E_CPU0_SA_DQ<4>")
	)
	(segment
		(start 297.07713 -203.937362)
		(end 296.914062 -204.10043)
		(width 0.14478)
		(layer "In6.Cu")
		(net "M_E_CPU0_SA_DQ<4>")
	)
	(segment
		(start 285.96463 -202.8698)
		(end 284.34919 -202.8698)
		(width 0.14478)
		(layer "In6.Cu")
		(net "M_E_CPU0_SA_DQ<4>")
	)
	(segment
		(start 282.116784 -203.710032)
		(end 281.953716 -203.8731)
		(width 0.14478)
		(layer "In6.Cu")
		(net "M_E_CPU0_SA_DQ<4>")
	)
	(segment
		(start 317.957708 -212.715094)
		(end 317.842646 -212.830156)
		(width 0.14478)
		(layer "In6.Cu")
		(net "M_E_CPU0_SA_DQ<4>")
	)
	(segment
		(start 279.447752 -203.8731)
		(end 279.284684 -203.710032)
		(width 0.14478)
		(layer "In6.Cu")
		(net "M_E_CPU0_SA_DQ<4>")
	)
	(segment
		(start 314.847478 -210.039712)
		(end 314.847478 -209.834988)
		(width 0.14478)
		(layer "In6.Cu")
		(net "M_E_CPU0_SA_DQ<4>")
	)
	(segment
		(start 297.240198 -203.710032)
		(end 297.07713 -203.8731)
		(width 0.14478)
		(layer "In6.Cu")
		(net "M_E_CPU0_SA_DQ<4>")
	)
	(segment
		(start 302.382174 -203.710032)
		(end 301.96155 -203.710032)
		(width 0.14478)
		(layer "In6.Cu")
		(net "M_E_CPU0_SA_DQ<4>")
	)
	(segment
		(start 281.790648 -204.10043)
		(end 281.56027 -204.10043)
		(width 0.14478)
		(layer "In6.Cu")
		(net "M_E_CPU0_SA_DQ<4>")
	)
	(segment
		(start 321.145154 -219.916502)
		(end 321.145154 -215.697816)
		(width 0.14478)
		(layer "In6.Cu")
		(net "M_E_CPU0_SA_DQ<4>")
	)
	(segment
		(start 301.121318 -202.8698)
		(end 298.60621 -202.8698)
		(width 0.14478)
		(layer "In6.Cu")
		(net "M_E_CPU0_SA_DQ<4>")
	)
	(segment
		(start 316.442598 -211.634832)
		(end 316.442598 -211.430108)
		(width 0.14478)
		(layer "In6.Cu")
		(net "M_E_CPU0_SA_DQ<4>")
	)
	(segment
		(start 278.031448 -203.546964)
		(end 277.86838 -203.710032)
		(width 0.14478)
		(layer "In6.Cu")
		(net "M_E_CPU0_SA_DQ<4>")
	)
	(segment
		(start 304.377852 -203.710032)
		(end 304.214784 -203.8731)
		(width 0.14478)
		(layer "In6.Cu")
		(net "M_E_CPU0_SA_DQ<4>")
	)
	(segment
		(start 323.175884 -221.947232)
		(end 321.145154 -219.916502)
		(width 0.14478)
		(layer "In6.Cu")
		(net "M_E_CPU0_SA_DQ<4>")
	)
	(segment
		(start 280.004266 -203.8731)
		(end 280.004266 -203.934822)
		(width 0.14478)
		(layer "In6.Cu")
		(net "M_E_CPU0_SA_DQ<4>")
	)
	(segment
		(start 278.031448 -203.079858)
		(end 278.031448 -203.546964)
		(width 0.14478)
		(layer "In6.Cu")
		(net "M_E_CPU0_SA_DQ<4>")
	)
	(segment
		(start 314.847478 -209.834988)
		(end 314.961524 -209.720942)
		(width 0.14478)
		(layer "In6.Cu")
		(net "M_E_CPU0_SA_DQ<4>")
	)
	(segment
		(start 304.051716 -204.09535)
		(end 303.821338 -204.09535)
		(width 0.14478)
		(layer "In6.Cu")
		(net "M_E_CPU0_SA_DQ<4>")
	)
	(segment
		(start 313.446414 -208.638648)
		(end 313.140598 -208.332832)
		(width 0.14478)
		(layer "In6.Cu")
		(net "M_E_CPU0_SA_DQ<4>")
	)
	(segment
		(start 289.609276 -203.710032)
		(end 289.446208 -203.8731)
		(width 0.14478)
		(layer "In6.Cu")
		(net "M_E_CPU0_SA_DQ<4>")
	)
	(segment
		(start 317.240158 -212.432392)
		(end 317.240158 -212.227668)
		(width 0.14478)
		(layer "In6.Cu")
		(net "M_E_CPU0_SA_DQ<4>")
	)
	(segment
		(start 298.60621 -202.8698)
		(end 297.765978 -203.710032)
		(width 0.14478)
		(layer "In6.Cu")
		(net "M_E_CPU0_SA_DQ<4>")
	)
	(segment
		(start 303.101756 -203.932282)
		(end 302.938688 -204.09535)
		(width 0.14478)
		(layer "In6.Cu")
		(net "M_E_CPU0_SA_DQ<4>")
	)
	(segment
		(start 315.246258 -210.233768)
		(end 315.041534 -210.233768)
		(width 0.14478)
		(layer "In6.Cu")
		(net "M_E_CPU0_SA_DQ<4>")
	)
	(segment
		(start 283.802328 -203.11999)
		(end 283.542486 -202.860148)
		(width 0.14478)
		(layer "In6.Cu")
		(net "M_E_CPU0_SA_DQ<4>")
	)
	(segment
		(start 303.264824 -203.710032)
		(end 303.101756 -203.8731)
		(width 0.14478)
		(layer "In6.Cu")
		(net "M_E_CPU0_SA_DQ<4>")
	)
	(segment
		(start 279.284684 -203.710032)
		(end 278.75103 -203.710032)
		(width 0.14478)
		(layer "In6.Cu")
		(net "M_E_CPU0_SA_DQ<4>")
	)
	(arc
		(start 328.832718 -228.63302)
		(mid 328.670529 -228.655755)
		(end 328.514202 -228.606858)
		(width 0.0889)
		(layer "In6.Cu")
		(net "M_E_CPU0_SA_DQ<4>")
	)
	(arc
		(start 327.94829 -228.606858)
		(mid 327.858034 -228.644511)
		(end 327.761092 -228.657404)
		(width 0.0889)
		(layer "In6.Cu")
		(net "M_E_CPU0_SA_DQ<4>")
	)
	(arc
		(start 328.514202 -228.606858)
		(mid 328.231246 -228.530681)
		(end 327.94829 -228.606858)
		(width 0.0889)
		(layer "In6.Cu")
		(net "M_E_CPU0_SA_DQ<4>")
	)
	(segment
		(start 331.047852 -226.930204)
		(end 330.581 -226.664266)
		(width 0.10668)
		(layer "F.Cu")
		(net "M_E_CPU0_SA_DQ<3>")
	)
	(segment
		(start 290.648644 -199.450452)
		(end 289.79876 -200.300336)
		(width 0.14478)
		(layer "In6.Cu")
		(net "M_E_CPU0_SA_DQ<3>")
	)
	(segment
		(start 293.64305 -199.450452)
		(end 290.648644 -199.450452)
		(width 0.14478)
		(layer "In6.Cu")
		(net "M_E_CPU0_SA_DQ<3>")
	)
	(segment
		(start 327.47839 -224.556828)
		(end 327.51014 -224.53854)
		(width 0.0889)
		(layer "In6.Cu")
		(net "M_E_CPU0_SA_DQ<3>")
	)
	(segment
		(start 326.178418 -221.645734)
		(end 326.098916 -221.566232)
		(width 0.0889)
		(layer "In6.Cu")
		(net "M_E_CPU0_SA_DQ<3>")
	)
	(segment
		(start 273.507454 -200.300336)
		(end 273.092164 -199.885046)
		(width 0.14478)
		(layer "In6.Cu")
		(net "M_E_CPU0_SA_DQ<3>")
	)
	(segment
		(start 326.098916 -221.566232)
		(end 323.570854 -219.03817)
		(width 0.14478)
		(layer "In6.Cu")
		(net "M_E_CPU0_SA_DQ<3>")
	)
	(segment
		(start 314.162694 -204.50048)
		(end 310.227472 -200.565258)
		(width 0.14478)
		(layer "In6.Cu")
		(net "M_E_CPU0_SA_DQ<3>")
	)
	(segment
		(start 297.332146 -200.300336)
		(end 294.492934 -200.300336)
		(width 0.14478)
		(layer "In6.Cu")
		(net "M_E_CPU0_SA_DQ<3>")
	)
	(segment
		(start 326.538336 -222.291656)
		(end 326.421242 -222.291656)
		(width 0.0889)
		(layer "In6.Cu")
		(net "M_E_CPU0_SA_DQ<3>")
	)
	(segment
		(start 302.04664 -200.310242)
		(end 301.18685 -199.450452)
		(width 0.14478)
		(layer "In6.Cu")
		(net "M_E_CPU0_SA_DQ<3>")
	)
	(segment
		(start 323.570854 -219.03817)
		(end 323.570854 -214.855806)
		(width 0.14478)
		(layer "In6.Cu")
		(net "M_E_CPU0_SA_DQ<3>")
	)
	(segment
		(start 314.162694 -205.447646)
		(end 314.162694 -204.50048)
		(width 0.14478)
		(layer "In6.Cu")
		(net "M_E_CPU0_SA_DQ<3>")
	)
	(segment
		(start 330.581 -226.664266)
		(end 330.427076 -226.398836)
		(width 0.0889)
		(layer "In6.Cu")
		(net "M_E_CPU0_SA_DQ<3>")
	)
	(segment
		(start 306.653438 -199.460104)
		(end 305.716178 -199.460104)
		(width 0.14478)
		(layer "In6.Cu")
		(net "M_E_CPU0_SA_DQ<3>")
	)
	(segment
		(start 330.427076 -226.398836)
		(end 330.331064 -226.373436)
		(width 0.0889)
		(layer "In6.Cu")
		(net "M_E_CPU0_SA_DQ<3>")
	)
	(segment
		(start 327.47839 -223.911668)
		(end 327.439274 -223.888808)
		(width 0.0889)
		(layer "In6.Cu")
		(net "M_E_CPU0_SA_DQ<3>")
	)
	(segment
		(start 323.570854 -214.855806)
		(end 314.162694 -205.447646)
		(width 0.14478)
		(layer "In6.Cu")
		(net "M_E_CPU0_SA_DQ<3>")
	)
	(segment
		(start 282.203906 -200.300336)
		(end 273.507454 -200.300336)
		(width 0.14478)
		(layer "In6.Cu")
		(net "M_E_CPU0_SA_DQ<3>")
	)
	(segment
		(start 327.94829 -226.341686)
		(end 327.909174 -226.318826)
		(width 0.0889)
		(layer "In6.Cu")
		(net "M_E_CPU0_SA_DQ<3>")
	)
	(segment
		(start 329.828144 -226.341686)
		(end 329.819762 -226.33686)
		(width 0.0889)
		(layer "In6.Cu")
		(net "M_E_CPU0_SA_DQ<3>")
	)
	(segment
		(start 326.571102 -222.310706)
		(end 326.538336 -222.291656)
		(width 0.0889)
		(layer "In6.Cu")
		(net "M_E_CPU0_SA_DQ<3>")
	)
	(segment
		(start 327.008236 -223.101662)
		(end 326.973438 -223.081342)
		(width 0.0889)
		(layer "In6.Cu")
		(net "M_E_CPU0_SA_DQ<3>")
	)
	(segment
		(start 310.227472 -200.565258)
		(end 307.758592 -200.565258)
		(width 0.14478)
		(layer "In6.Cu")
		(net "M_E_CPU0_SA_DQ<3>")
	)
	(segment
		(start 283.05379 -199.450452)
		(end 282.203906 -200.300336)
		(width 0.14478)
		(layer "In6.Cu")
		(net "M_E_CPU0_SA_DQ<3>")
	)
	(segment
		(start 305.716178 -199.460104)
		(end 304.86604 -200.310242)
		(width 0.14478)
		(layer "In6.Cu")
		(net "M_E_CPU0_SA_DQ<3>")
	)
	(segment
		(start 304.86604 -200.310242)
		(end 302.04664 -200.310242)
		(width 0.14478)
		(layer "In6.Cu")
		(net "M_E_CPU0_SA_DQ<3>")
	)
	(segment
		(start 327.510902 -225.55073)
		(end 327.478136 -225.53168)
		(width 0.0889)
		(layer "In6.Cu")
		(net "M_E_CPU0_SA_DQ<3>")
	)
	(segment
		(start 327.041002 -223.120712)
		(end 327.008236 -223.101662)
		(width 0.0889)
		(layer "In6.Cu")
		(net "M_E_CPU0_SA_DQ<3>")
	)
	(segment
		(start 326.178418 -222.048832)
		(end 326.178418 -221.645734)
		(width 0.0889)
		(layer "In6.Cu")
		(net "M_E_CPU0_SA_DQ<3>")
	)
	(segment
		(start 294.492934 -200.300336)
		(end 293.64305 -199.450452)
		(width 0.14478)
		(layer "In6.Cu")
		(net "M_E_CPU0_SA_DQ<3>")
	)
	(segment
		(start 327.438004 -224.58045)
		(end 327.47839 -224.556828)
		(width 0.0889)
		(layer "In6.Cu")
		(net "M_E_CPU0_SA_DQ<3>")
	)
	(segment
		(start 286.8041 -200.300336)
		(end 285.954216 -199.450452)
		(width 0.14478)
		(layer "In6.Cu")
		(net "M_E_CPU0_SA_DQ<3>")
	)
	(segment
		(start 326.421242 -222.291656)
		(end 326.178418 -222.048832)
		(width 0.0889)
		(layer "In6.Cu")
		(net "M_E_CPU0_SA_DQ<3>")
	)
	(segment
		(start 285.954216 -199.450452)
		(end 283.05379 -199.450452)
		(width 0.14478)
		(layer "In6.Cu")
		(net "M_E_CPU0_SA_DQ<3>")
	)
	(segment
		(start 307.758592 -200.565258)
		(end 306.653438 -199.460104)
		(width 0.14478)
		(layer "In6.Cu")
		(net "M_E_CPU0_SA_DQ<3>")
	)
	(segment
		(start 301.18685 -199.450452)
		(end 298.18203 -199.450452)
		(width 0.14478)
		(layer "In6.Cu")
		(net "M_E_CPU0_SA_DQ<3>")
	)
	(segment
		(start 298.18203 -199.450452)
		(end 297.332146 -200.300336)
		(width 0.14478)
		(layer "In6.Cu")
		(net "M_E_CPU0_SA_DQ<3>")
	)
	(segment
		(start 327.478136 -225.53168)
		(end 327.43902 -225.50882)
		(width 0.0889)
		(layer "In6.Cu")
		(net "M_E_CPU0_SA_DQ<3>")
	)
	(segment
		(start 289.79876 -200.300336)
		(end 286.8041 -200.300336)
		(width 0.14478)
		(layer "In6.Cu")
		(net "M_E_CPU0_SA_DQ<3>")
	)
	(segment
		(start 327.51014 -223.929956)
		(end 327.47839 -223.911668)
		(width 0.0889)
		(layer "In6.Cu")
		(net "M_E_CPU0_SA_DQ<3>")
	)
	(arc
		(start 326.726296 -222.614236)
		(mid 326.685246 -222.443786)
		(end 326.571102 -222.310706)
		(width 0.0889)
		(layer "In6.Cu")
		(net "M_E_CPU0_SA_DQ<3>")
	)
	(arc
		(start 328.514202 -226.341686)
		(mid 328.231246 -226.417863)
		(end 327.94829 -226.341686)
		(width 0.0889)
		(layer "In6.Cu")
		(net "M_E_CPU0_SA_DQ<3>")
	)
	(arc
		(start 330.331064 -226.373436)
		(mid 330.075856 -226.416913)
		(end 329.828144 -226.341686)
		(width 0.0889)
		(layer "In6.Cu")
		(net "M_E_CPU0_SA_DQ<3>")
	)
	(arc
		(start 328.88809 -226.341686)
		(mid 328.701146 -226.291431)
		(end 328.514202 -226.341686)
		(width 0.0889)
		(layer "In6.Cu")
		(net "M_E_CPU0_SA_DQ<3>")
	)
	(arc
		(start 327.51014 -224.53854)
		(mid 327.666068 -224.234248)
		(end 327.51014 -223.929956)
		(width 0.0889)
		(layer "In6.Cu")
		(net "M_E_CPU0_SA_DQ<3>")
	)
	(arc
		(start 327.195688 -225.044254)
		(mid 327.259981 -224.782649)
		(end 327.438004 -224.58045)
		(width 0.0889)
		(layer "In6.Cu")
		(net "M_E_CPU0_SA_DQ<3>")
	)
	(arc
		(start 329.454002 -226.341686)
		(mid 329.171046 -226.417863)
		(end 328.88809 -226.341686)
		(width 0.0889)
		(layer "In6.Cu")
		(net "M_E_CPU0_SA_DQ<3>")
	)
	(arc
		(start 327.909174 -226.318826)
		(mid 327.730361 -226.116476)
		(end 327.665842 -225.85426)
		(width 0.0889)
		(layer "In6.Cu")
		(net "M_E_CPU0_SA_DQ<3>")
	)
	(arc
		(start 327.43902 -225.50882)
		(mid 327.260207 -225.30647)
		(end 327.195688 -225.044254)
		(width 0.0889)
		(layer "In6.Cu")
		(net "M_E_CPU0_SA_DQ<3>")
	)
	(arc
		(start 327.439274 -223.888808)
		(mid 327.260461 -223.686458)
		(end 327.195942 -223.424242)
		(width 0.0889)
		(layer "In6.Cu")
		(net "M_E_CPU0_SA_DQ<3>")
	)
	(arc
		(start 327.665842 -225.85426)
		(mid 327.624876 -225.683854)
		(end 327.510902 -225.55073)
		(width 0.0889)
		(layer "In6.Cu")
		(net "M_E_CPU0_SA_DQ<3>")
	)
	(arc
		(start 327.195942 -223.424242)
		(mid 327.154976 -223.253836)
		(end 327.041002 -223.120712)
		(width 0.0889)
		(layer "In6.Cu")
		(net "M_E_CPU0_SA_DQ<3>")
	)
	(arc
		(start 329.819762 -226.33686)
		(mid 329.636254 -226.291366)
		(end 329.454002 -226.341686)
		(width 0.0889)
		(layer "In6.Cu")
		(net "M_E_CPU0_SA_DQ<3>")
	)
	(arc
		(start 326.973438 -223.081342)
		(mid 326.791859 -222.878475)
		(end 326.726296 -222.614236)
		(width 0.0889)
		(layer "In6.Cu")
		(net "M_E_CPU0_SA_DQ<3>")
	)
	(segment
		(start 331.047852 -244.750082)
		(end 330.581 -244.484144)
		(width 0.10668)
		(layer "F.Cu")
		(net "M_E_CPU0_SA_DQ<31>")
	)
	(segment
		(start 276.042628 -234.147106)
		(end 276.042628 -233.86796)
		(width 0.14478)
		(layer "In6.Cu")
		(net "M_E_CPU0_SA_DQ<31>")
	)
	(segment
		(start 276.042628 -233.86796)
		(end 275.87956 -233.704892)
		(width 0.14478)
		(layer "In6.Cu")
		(net "M_E_CPU0_SA_DQ<31>")
	)
	(segment
		(start 297.3578 -234.310174)
		(end 294.50284 -234.310174)
		(width 0.14478)
		(layer "In6.Cu")
		(net "M_E_CPU0_SA_DQ<31>")
	)
	(segment
		(start 275.87956 -233.704892)
		(end 275.649182 -233.704892)
		(width 0.14478)
		(layer "In6.Cu")
		(net "M_E_CPU0_SA_DQ<31>")
	)
	(segment
		(start 310.241188 -237.901734)
		(end 308.698138 -234.17657)
		(width 0.14478)
		(layer "In6.Cu")
		(net "M_E_CPU0_SA_DQ<31>")
	)
	(segment
		(start 330.581 -244.484144)
		(end 330.427076 -244.218714)
		(width 0.0889)
		(layer "In6.Cu")
		(net "M_E_CPU0_SA_DQ<31>")
	)
	(segment
		(start 324.147434 -243.52123)
		(end 323.875654 -243.52123)
		(width 0.0889)
		(layer "In6.Cu")
		(net "M_E_CPU0_SA_DQ<31>")
	)
	(segment
		(start 307.981604 -233.460036)
		(end 305.751738 -233.460036)
		(width 0.14478)
		(layer "In6.Cu")
		(net "M_E_CPU0_SA_DQ<31>")
	)
	(segment
		(start 324.442074 -243.81587)
		(end 324.147434 -243.52123)
		(width 0.0889)
		(layer "In6.Cu")
		(net "M_E_CPU0_SA_DQ<31>")
	)
	(segment
		(start 325.755 -244.237764)
		(end 325.333106 -243.81587)
		(width 0.0889)
		(layer "In6.Cu")
		(net "M_E_CPU0_SA_DQ<31>")
	)
	(segment
		(start 304.9016 -234.310174)
		(end 302.04664 -234.310174)
		(width 0.14478)
		(layer "In6.Cu")
		(net "M_E_CPU0_SA_DQ<31>")
	)
	(segment
		(start 329.828144 -244.161564)
		(end 329.819762 -244.156738)
		(width 0.0889)
		(layer "In6.Cu")
		(net "M_E_CPU0_SA_DQ<31>")
	)
	(segment
		(start 285.963868 -233.460036)
		(end 283.051758 -233.460036)
		(width 0.14478)
		(layer "In6.Cu")
		(net "M_E_CPU0_SA_DQ<31>")
	)
	(segment
		(start 327.008744 -244.161564)
		(end 326.99706 -244.154706)
		(width 0.0889)
		(layer "In6.Cu")
		(net "M_E_CPU0_SA_DQ<31>")
	)
	(segment
		(start 275.649182 -233.704892)
		(end 275.486114 -233.86796)
		(width 0.14478)
		(layer "In6.Cu")
		(net "M_E_CPU0_SA_DQ<31>")
	)
	(segment
		(start 298.207938 -233.460036)
		(end 297.3578 -234.310174)
		(width 0.14478)
		(layer "In6.Cu")
		(net "M_E_CPU0_SA_DQ<31>")
	)
	(segment
		(start 310.241188 -237.901988)
		(end 310.241188 -237.901734)
		(width 0.14478)
		(layer "In6.Cu")
		(net "M_E_CPU0_SA_DQ<31>")
	)
	(segment
		(start 276.205696 -234.310174)
		(end 276.042628 -234.147106)
		(width 0.14478)
		(layer "In6.Cu")
		(net "M_E_CPU0_SA_DQ<31>")
	)
	(segment
		(start 293.652702 -233.460036)
		(end 290.603432 -233.460036)
		(width 0.14478)
		(layer "In6.Cu")
		(net "M_E_CPU0_SA_DQ<31>")
	)
	(segment
		(start 325.333106 -243.81587)
		(end 324.442074 -243.81587)
		(width 0.0889)
		(layer "In6.Cu")
		(net "M_E_CPU0_SA_DQ<31>")
	)
	(segment
		(start 289.753294 -234.310174)
		(end 286.814006 -234.310174)
		(width 0.14478)
		(layer "In6.Cu")
		(net "M_E_CPU0_SA_DQ<31>")
	)
	(segment
		(start 283.051758 -233.460036)
		(end 282.20162 -234.310174)
		(width 0.14478)
		(layer "In6.Cu")
		(net "M_E_CPU0_SA_DQ<31>")
	)
	(segment
		(start 315.86043 -243.52123)
		(end 310.241188 -237.901988)
		(width 0.14478)
		(layer "In6.Cu")
		(net "M_E_CPU0_SA_DQ<31>")
	)
	(segment
		(start 308.698138 -234.17657)
		(end 307.981604 -233.460036)
		(width 0.14478)
		(layer "In6.Cu")
		(net "M_E_CPU0_SA_DQ<31>")
	)
	(segment
		(start 327.574402 -244.161564)
		(end 327.563988 -244.16766)
		(width 0.0889)
		(layer "In6.Cu")
		(net "M_E_CPU0_SA_DQ<31>")
	)
	(segment
		(start 275.486114 -234.147106)
		(end 275.323046 -234.310174)
		(width 0.14478)
		(layer "In6.Cu")
		(net "M_E_CPU0_SA_DQ<31>")
	)
	(segment
		(start 305.751738 -233.460036)
		(end 304.9016 -234.310174)
		(width 0.14478)
		(layer "In6.Cu")
		(net "M_E_CPU0_SA_DQ<31>")
	)
	(segment
		(start 301.196502 -233.460036)
		(end 298.207938 -233.460036)
		(width 0.14478)
		(layer "In6.Cu")
		(net "M_E_CPU0_SA_DQ<31>")
	)
	(segment
		(start 294.50284 -234.310174)
		(end 293.652702 -233.460036)
		(width 0.14478)
		(layer "In6.Cu")
		(net "M_E_CPU0_SA_DQ<31>")
	)
	(segment
		(start 282.20162 -234.310174)
		(end 276.205696 -234.310174)
		(width 0.14478)
		(layer "In6.Cu")
		(net "M_E_CPU0_SA_DQ<31>")
	)
	(segment
		(start 302.04664 -234.310174)
		(end 301.196502 -233.460036)
		(width 0.14478)
		(layer "In6.Cu")
		(net "M_E_CPU0_SA_DQ<31>")
	)
	(segment
		(start 273.51736 -234.310174)
		(end 273.092164 -233.884978)
		(width 0.14478)
		(layer "In6.Cu")
		(net "M_E_CPU0_SA_DQ<31>")
	)
	(segment
		(start 275.323046 -234.310174)
		(end 273.51736 -234.310174)
		(width 0.14478)
		(layer "In6.Cu")
		(net "M_E_CPU0_SA_DQ<31>")
	)
	(segment
		(start 326.351392 -244.237764)
		(end 325.755 -244.237764)
		(width 0.0889)
		(layer "In6.Cu")
		(net "M_E_CPU0_SA_DQ<31>")
	)
	(segment
		(start 330.427076 -244.218714)
		(end 330.331064 -244.193314)
		(width 0.0889)
		(layer "In6.Cu")
		(net "M_E_CPU0_SA_DQ<31>")
	)
	(segment
		(start 290.603432 -233.460036)
		(end 289.753294 -234.310174)
		(width 0.14478)
		(layer "In6.Cu")
		(net "M_E_CPU0_SA_DQ<31>")
	)
	(segment
		(start 327.586086 -244.154706)
		(end 327.574402 -244.161564)
		(width 0.0889)
		(layer "In6.Cu")
		(net "M_E_CPU0_SA_DQ<31>")
	)
	(segment
		(start 275.486114 -233.86796)
		(end 275.486114 -234.147106)
		(width 0.14478)
		(layer "In6.Cu")
		(net "M_E_CPU0_SA_DQ<31>")
	)
	(segment
		(start 323.875654 -243.52123)
		(end 315.86043 -243.52123)
		(width 0.14478)
		(layer "In6.Cu")
		(net "M_E_CPU0_SA_DQ<31>")
	)
	(segment
		(start 286.814006 -234.310174)
		(end 285.963868 -233.460036)
		(width 0.14478)
		(layer "In6.Cu")
		(net "M_E_CPU0_SA_DQ<31>")
	)
	(arc
		(start 328.514202 -244.161564)
		(mid 328.231246 -244.237741)
		(end 327.94829 -244.161564)
		(width 0.0889)
		(layer "In6.Cu")
		(net "M_E_CPU0_SA_DQ<31>")
	)
	(arc
		(start 327.563988 -244.16766)
		(mid 327.285556 -244.237758)
		(end 327.008744 -244.161564)
		(width 0.0889)
		(layer "In6.Cu")
		(net "M_E_CPU0_SA_DQ<31>")
	)
	(arc
		(start 326.634348 -244.161564)
		(mid 326.497907 -244.218364)
		(end 326.351392 -244.237764)
		(width 0.0889)
		(layer "In6.Cu")
		(net "M_E_CPU0_SA_DQ<31>")
	)
	(arc
		(start 328.88809 -244.161564)
		(mid 328.701146 -244.111309)
		(end 328.514202 -244.161564)
		(width 0.0889)
		(layer "In6.Cu")
		(net "M_E_CPU0_SA_DQ<31>")
	)
	(arc
		(start 329.819762 -244.156738)
		(mid 329.636254 -244.111244)
		(end 329.454002 -244.161564)
		(width 0.0889)
		(layer "In6.Cu")
		(net "M_E_CPU0_SA_DQ<31>")
	)
	(arc
		(start 330.331064 -244.193314)
		(mid 330.075856 -244.236791)
		(end 329.828144 -244.161564)
		(width 0.0889)
		(layer "In6.Cu")
		(net "M_E_CPU0_SA_DQ<31>")
	)
	(arc
		(start 326.99706 -244.154706)
		(mid 326.814805 -244.111053)
		(end 326.634348 -244.161564)
		(width 0.0889)
		(layer "In6.Cu")
		(net "M_E_CPU0_SA_DQ<31>")
	)
	(arc
		(start 329.454002 -244.161564)
		(mid 329.171046 -244.237741)
		(end 328.88809 -244.161564)
		(width 0.0889)
		(layer "In6.Cu")
		(net "M_E_CPU0_SA_DQ<31>")
	)
	(arc
		(start 327.94829 -244.161564)
		(mid 327.768085 -244.111247)
		(end 327.586086 -244.154706)
		(width 0.0889)
		(layer "In6.Cu")
		(net "M_E_CPU0_SA_DQ<31>")
	)
	(segment
		(start 329.637898 -243.940076)
		(end 329.171046 -243.674138)
		(width 0.10668)
		(layer "F.Cu")
		(net "M_E_CPU0_SA_DQ<30>")
	)
	(segment
		(start 326.543416 -243.355114)
		(end 326.537828 -243.351812)
		(width 0.0889)
		(layer "In6.Cu")
		(net "M_E_CPU0_SA_DQ<30>")
	)
	(segment
		(start 311.02427 -237.402878)
		(end 309.488586 -233.694986)
		(width 0.14478)
		(layer "In6.Cu")
		(net "M_E_CPU0_SA_DQ<30>")
	)
	(segment
		(start 304.9016 -232.610152)
		(end 301.872904 -232.610152)
		(width 0.14478)
		(layer "In6.Cu")
		(net "M_E_CPU0_SA_DQ<30>")
	)
	(segment
		(start 282.20162 -232.610152)
		(end 276.363684 -232.610152)
		(width 0.14478)
		(layer "In6.Cu")
		(net "M_E_CPU0_SA_DQ<30>")
	)
	(segment
		(start 293.652702 -231.760014)
		(end 290.603432 -231.760014)
		(width 0.14478)
		(layer "In6.Cu")
		(net "M_E_CPU0_SA_DQ<30>")
	)
	(segment
		(start 301.022766 -231.760014)
		(end 298.207938 -231.760014)
		(width 0.14478)
		(layer "In6.Cu")
		(net "M_E_CPU0_SA_DQ<30>")
	)
	(segment
		(start 294.50284 -232.610152)
		(end 293.652702 -231.760014)
		(width 0.14478)
		(layer "In6.Cu")
		(net "M_E_CPU0_SA_DQ<30>")
	)
	(segment
		(start 325.570596 -243.301012)
		(end 325.038974 -242.76939)
		(width 0.0889)
		(layer "In6.Cu")
		(net "M_E_CPU0_SA_DQ<30>")
	)
	(segment
		(start 324.213474 -242.61191)
		(end 323.890894 -242.61191)
		(width 0.0889)
		(layer "In6.Cu")
		(net "M_E_CPU0_SA_DQ<30>")
	)
	(segment
		(start 307.553614 -231.760014)
		(end 305.751738 -231.760014)
		(width 0.14478)
		(layer "In6.Cu")
		(net "M_E_CPU0_SA_DQ<30>")
	)
	(segment
		(start 273.51736 -232.610152)
		(end 273.092164 -232.184956)
		(width 0.14478)
		(layer "In6.Cu")
		(net "M_E_CPU0_SA_DQ<30>")
	)
	(segment
		(start 327.111614 -243.346732)
		(end 327.103232 -243.351558)
		(width 0.0889)
		(layer "In6.Cu")
		(net "M_E_CPU0_SA_DQ<30>")
	)
	(segment
		(start 314.660788 -240.664492)
		(end 314.285884 -240.664492)
		(width 0.14478)
		(layer "In6.Cu")
		(net "M_E_CPU0_SA_DQ<30>")
	)
	(segment
		(start 283.051758 -231.760014)
		(end 282.20162 -232.610152)
		(width 0.14478)
		(layer "In6.Cu")
		(net "M_E_CPU0_SA_DQ<30>")
	)
	(segment
		(start 275.644102 -231.444038)
		(end 275.644102 -232.447084)
		(width 0.14478)
		(layer "In6.Cu")
		(net "M_E_CPU0_SA_DQ<30>")
	)
	(segment
		(start 275.644102 -232.447084)
		(end 275.481034 -232.610152)
		(width 0.14478)
		(layer "In6.Cu")
		(net "M_E_CPU0_SA_DQ<30>")
	)
	(segment
		(start 329.017122 -243.408708)
		(end 328.92111 -243.383308)
		(width 0.0889)
		(layer "In6.Cu")
		(net "M_E_CPU0_SA_DQ<30>")
	)
	(segment
		(start 275.481034 -232.610152)
		(end 273.51736 -232.610152)
		(width 0.14478)
		(layer "In6.Cu")
		(net "M_E_CPU0_SA_DQ<30>")
	)
	(segment
		(start 276.363684 -232.610152)
		(end 276.200616 -232.447084)
		(width 0.14478)
		(layer "In6.Cu")
		(net "M_E_CPU0_SA_DQ<30>")
	)
	(segment
		(start 325.038974 -242.76939)
		(end 324.370954 -242.76939)
		(width 0.0889)
		(layer "In6.Cu")
		(net "M_E_CPU0_SA_DQ<30>")
	)
	(segment
		(start 290.603432 -231.760014)
		(end 289.753294 -232.610152)
		(width 0.14478)
		(layer "In6.Cu")
		(net "M_E_CPU0_SA_DQ<30>")
	)
	(segment
		(start 326.351138 -243.301012)
		(end 325.570596 -243.301012)
		(width 0.0889)
		(layer "In6.Cu")
		(net "M_E_CPU0_SA_DQ<30>")
	)
	(segment
		(start 328.41819 -243.351558)
		(end 328.409808 -243.346732)
		(width 0.0889)
		(layer "In6.Cu")
		(net "M_E_CPU0_SA_DQ<30>")
	)
	(segment
		(start 323.890894 -242.61191)
		(end 316.608206 -242.61191)
		(width 0.14478)
		(layer "In6.Cu")
		(net "M_E_CPU0_SA_DQ<30>")
	)
	(segment
		(start 324.370954 -242.76939)
		(end 324.213474 -242.61191)
		(width 0.0889)
		(layer "In6.Cu")
		(net "M_E_CPU0_SA_DQ<30>")
	)
	(segment
		(start 305.751738 -231.760014)
		(end 304.9016 -232.610152)
		(width 0.14478)
		(layer "In6.Cu")
		(net "M_E_CPU0_SA_DQ<30>")
	)
	(segment
		(start 328.044048 -243.351558)
		(end 328.033634 -243.357654)
		(width 0.0889)
		(layer "In6.Cu")
		(net "M_E_CPU0_SA_DQ<30>")
	)
	(segment
		(start 298.207938 -231.760014)
		(end 297.3578 -232.610152)
		(width 0.14478)
		(layer "In6.Cu")
		(net "M_E_CPU0_SA_DQ<30>")
	)
	(segment
		(start 301.872904 -232.610152)
		(end 301.022766 -231.760014)
		(width 0.14478)
		(layer "In6.Cu")
		(net "M_E_CPU0_SA_DQ<30>")
	)
	(segment
		(start 297.3578 -232.610152)
		(end 294.50284 -232.610152)
		(width 0.14478)
		(layer "In6.Cu")
		(net "M_E_CPU0_SA_DQ<30>")
	)
	(segment
		(start 289.753294 -232.610152)
		(end 286.814006 -232.610152)
		(width 0.14478)
		(layer "In6.Cu")
		(net "M_E_CPU0_SA_DQ<30>")
	)
	(segment
		(start 309.488586 -233.694986)
		(end 307.553614 -231.760014)
		(width 0.14478)
		(layer "In6.Cu")
		(net "M_E_CPU0_SA_DQ<30>")
	)
	(segment
		(start 276.200616 -232.447084)
		(end 276.200616 -231.444038)
		(width 0.14478)
		(layer "In6.Cu")
		(net "M_E_CPU0_SA_DQ<30>")
	)
	(segment
		(start 275.80717 -231.28097)
		(end 275.644102 -231.444038)
		(width 0.14478)
		(layer "In6.Cu")
		(net "M_E_CPU0_SA_DQ<30>")
	)
	(segment
		(start 276.200616 -231.444038)
		(end 276.037548 -231.28097)
		(width 0.14478)
		(layer "In6.Cu")
		(net "M_E_CPU0_SA_DQ<30>")
	)
	(segment
		(start 314.285884 -240.664492)
		(end 311.02427 -237.402878)
		(width 0.14478)
		(layer "In6.Cu")
		(net "M_E_CPU0_SA_DQ<30>")
	)
	(segment
		(start 276.037548 -231.28097)
		(end 275.80717 -231.28097)
		(width 0.14478)
		(layer "In6.Cu")
		(net "M_E_CPU0_SA_DQ<30>")
	)
	(segment
		(start 316.608206 -242.61191)
		(end 314.660788 -240.664492)
		(width 0.14478)
		(layer "In6.Cu")
		(net "M_E_CPU0_SA_DQ<30>")
	)
	(segment
		(start 286.814006 -232.610152)
		(end 285.963868 -231.760014)
		(width 0.14478)
		(layer "In6.Cu")
		(net "M_E_CPU0_SA_DQ<30>")
	)
	(segment
		(start 329.171046 -243.674138)
		(end 329.017122 -243.408708)
		(width 0.0889)
		(layer "In6.Cu")
		(net "M_E_CPU0_SA_DQ<30>")
	)
	(segment
		(start 285.963868 -231.760014)
		(end 283.051758 -231.760014)
		(width 0.14478)
		(layer "In6.Cu")
		(net "M_E_CPU0_SA_DQ<30>")
	)
	(arc
		(start 326.537828 -243.351812)
		(mid 326.447837 -243.314077)
		(end 326.351138 -243.301012)
		(width 0.0889)
		(layer "In6.Cu")
		(net "M_E_CPU0_SA_DQ<30>")
	)
	(arc
		(start 328.409808 -243.346732)
		(mid 328.2263 -243.301238)
		(end 328.044048 -243.351558)
		(width 0.0889)
		(layer "In6.Cu")
		(net "M_E_CPU0_SA_DQ<30>")
	)
	(arc
		(start 328.92111 -243.383308)
		(mid 328.665902 -243.426785)
		(end 328.41819 -243.351558)
		(width 0.0889)
		(layer "In6.Cu")
		(net "M_E_CPU0_SA_DQ<30>")
	)
	(arc
		(start 327.477882 -243.351558)
		(mid 327.295377 -243.301081)
		(end 327.111614 -243.346732)
		(width 0.0889)
		(layer "In6.Cu")
		(net "M_E_CPU0_SA_DQ<30>")
	)
	(arc
		(start 328.033634 -243.357654)
		(mid 327.754948 -243.427874)
		(end 327.477882 -243.351558)
		(width 0.0889)
		(layer "In6.Cu")
		(net "M_E_CPU0_SA_DQ<30>")
	)
	(arc
		(start 327.103232 -243.351558)
		(mid 326.823804 -243.427724)
		(end 326.543416 -243.355114)
		(width 0.0889)
		(layer "In6.Cu")
		(net "M_E_CPU0_SA_DQ<30>")
	)
	(segment
		(start 329.637898 -226.120198)
		(end 329.171046 -225.85426)
		(width 0.10668)
		(layer "F.Cu")
		(net "M_E_CPU0_SA_DQ<2>")
	)
	(segment
		(start 304.86604 -198.61022)
		(end 302.04664 -198.61022)
		(width 0.14478)
		(layer "In6.Cu")
		(net "M_E_CPU0_SA_DQ<2>")
	)
	(segment
		(start 275.482812 -198.116698)
		(end 275.319744 -197.95363)
		(width 0.14478)
		(layer "In6.Cu")
		(net "M_E_CPU0_SA_DQ<2>")
	)
	(segment
		(start 274.76323 -198.61022)
		(end 273.51736 -198.61022)
		(width 0.14478)
		(layer "In6.Cu")
		(net "M_E_CPU0_SA_DQ<2>")
	)
	(segment
		(start 328.41819 -225.53168)
		(end 328.379074 -225.50882)
		(width 0.0889)
		(layer "In6.Cu")
		(net "M_E_CPU0_SA_DQ<2>")
	)
	(segment
		(start 286.814006 -198.61022)
		(end 285.963868 -197.760082)
		(width 0.14478)
		(layer "In6.Cu")
		(net "M_E_CPU0_SA_DQ<2>")
	)
	(segment
		(start 305.716178 -197.760082)
		(end 304.86604 -198.61022)
		(width 0.14478)
		(layer "In6.Cu")
		(net "M_E_CPU0_SA_DQ<2>")
	)
	(segment
		(start 289.788854 -198.61022)
		(end 286.814006 -198.61022)
		(width 0.14478)
		(layer "In6.Cu")
		(net "M_E_CPU0_SA_DQ<2>")
	)
	(segment
		(start 302.04664 -198.61022)
		(end 301.196502 -197.760082)
		(width 0.14478)
		(layer "In6.Cu")
		(net "M_E_CPU0_SA_DQ<2>")
	)
	(segment
		(start 327.98004 -223.11995)
		(end 327.94829 -223.101662)
		(width 0.0889)
		(layer "In6.Cu")
		(net "M_E_CPU0_SA_DQ<2>")
	)
	(segment
		(start 329.171046 -225.85426)
		(end 329.017122 -225.58883)
		(width 0.0889)
		(layer "In6.Cu")
		(net "M_E_CPU0_SA_DQ<2>")
	)
	(segment
		(start 283.044138 -197.760082)
		(end 282.194 -198.61022)
		(width 0.14478)
		(layer "In6.Cu")
		(net "M_E_CPU0_SA_DQ<2>")
	)
	(segment
		(start 274.926298 -198.447152)
		(end 274.76323 -198.61022)
		(width 0.14478)
		(layer "In6.Cu")
		(net "M_E_CPU0_SA_DQ<2>")
	)
	(segment
		(start 328.41819 -223.911668)
		(end 328.381868 -223.890586)
		(width 0.0889)
		(layer "In6.Cu")
		(net "M_E_CPU0_SA_DQ<2>")
	)
	(segment
		(start 328.379074 -224.579688)
		(end 328.41819 -224.556828)
		(width 0.0889)
		(layer "In6.Cu")
		(net "M_E_CPU0_SA_DQ<2>")
	)
	(segment
		(start 275.64588 -198.61022)
		(end 275.482812 -198.447152)
		(width 0.14478)
		(layer "In6.Cu")
		(net "M_E_CPU0_SA_DQ<2>")
	)
	(segment
		(start 328.41819 -224.556828)
		(end 328.44994 -224.53854)
		(width 0.0889)
		(layer "In6.Cu")
		(net "M_E_CPU0_SA_DQ<2>")
	)
	(segment
		(start 317.30188 -207.29702)
		(end 317.30188 -206.27467)
		(width 0.14478)
		(layer "In6.Cu")
		(net "M_E_CPU0_SA_DQ<2>")
	)
	(segment
		(start 327.195688 -221.643702)
		(end 326.989694 -221.437708)
		(width 0.0889)
		(layer "In6.Cu")
		(net "M_E_CPU0_SA_DQ<2>")
	)
	(segment
		(start 326.989694 -221.25813)
		(end 326.989694 -221.08033)
		(width 0.14478)
		(layer "In6.Cu")
		(net "M_E_CPU0_SA_DQ<2>")
	)
	(segment
		(start 274.926298 -198.116698)
		(end 274.926298 -198.447152)
		(width 0.14478)
		(layer "In6.Cu")
		(net "M_E_CPU0_SA_DQ<2>")
	)
	(segment
		(start 301.196502 -197.760082)
		(end 298.172378 -197.760082)
		(width 0.14478)
		(layer "In6.Cu")
		(net "M_E_CPU0_SA_DQ<2>")
	)
	(segment
		(start 290.638992 -197.760082)
		(end 289.788854 -198.61022)
		(width 0.14478)
		(layer "In6.Cu")
		(net "M_E_CPU0_SA_DQ<2>")
	)
	(segment
		(start 317.30188 -206.27467)
		(end 308.787292 -197.760082)
		(width 0.14478)
		(layer "In6.Cu")
		(net "M_E_CPU0_SA_DQ<2>")
	)
	(segment
		(start 328.44994 -223.929956)
		(end 328.41819 -223.911668)
		(width 0.0889)
		(layer "In6.Cu")
		(net "M_E_CPU0_SA_DQ<2>")
	)
	(segment
		(start 297.32224 -198.61022)
		(end 294.50284 -198.61022)
		(width 0.14478)
		(layer "In6.Cu")
		(net "M_E_CPU0_SA_DQ<2>")
	)
	(segment
		(start 324.541134 -214.536274)
		(end 317.30188 -207.29702)
		(width 0.14478)
		(layer "In6.Cu")
		(net "M_E_CPU0_SA_DQ<2>")
	)
	(segment
		(start 285.963868 -197.760082)
		(end 283.044138 -197.760082)
		(width 0.14478)
		(layer "In6.Cu")
		(net "M_E_CPU0_SA_DQ<2>")
	)
	(segment
		(start 308.787292 -197.760082)
		(end 305.716178 -197.760082)
		(width 0.14478)
		(layer "In6.Cu")
		(net "M_E_CPU0_SA_DQ<2>")
	)
	(segment
		(start 326.989694 -221.437708)
		(end 326.989694 -221.25813)
		(width 0.0889)
		(layer "In6.Cu")
		(net "M_E_CPU0_SA_DQ<2>")
	)
	(segment
		(start 273.51736 -198.61022)
		(end 273.092164 -198.185024)
		(width 0.14478)
		(layer "In6.Cu")
		(net "M_E_CPU0_SA_DQ<2>")
	)
	(segment
		(start 327.47839 -222.291656)
		(end 327.438004 -222.268034)
		(width 0.0889)
		(layer "In6.Cu")
		(net "M_E_CPU0_SA_DQ<2>")
	)
	(segment
		(start 324.541134 -218.63177)
		(end 324.541134 -214.536274)
		(width 0.14478)
		(layer "In6.Cu")
		(net "M_E_CPU0_SA_DQ<2>")
	)
	(segment
		(start 275.319744 -197.95363)
		(end 275.089366 -197.95363)
		(width 0.14478)
		(layer "In6.Cu")
		(net "M_E_CPU0_SA_DQ<2>")
	)
	(segment
		(start 282.194 -198.61022)
		(end 275.64588 -198.61022)
		(width 0.14478)
		(layer "In6.Cu")
		(net "M_E_CPU0_SA_DQ<2>")
	)
	(segment
		(start 327.51014 -222.309944)
		(end 327.47839 -222.291656)
		(width 0.0889)
		(layer "In6.Cu")
		(net "M_E_CPU0_SA_DQ<2>")
	)
	(segment
		(start 275.089366 -197.95363)
		(end 274.926298 -198.116698)
		(width 0.14478)
		(layer "In6.Cu")
		(net "M_E_CPU0_SA_DQ<2>")
	)
	(segment
		(start 329.017122 -225.58883)
		(end 328.92111 -225.56343)
		(width 0.0889)
		(layer "In6.Cu")
		(net "M_E_CPU0_SA_DQ<2>")
	)
	(segment
		(start 294.50284 -198.61022)
		(end 293.652702 -197.760082)
		(width 0.14478)
		(layer "In6.Cu")
		(net "M_E_CPU0_SA_DQ<2>")
	)
	(segment
		(start 327.94829 -223.101662)
		(end 327.911968 -223.08058)
		(width 0.0889)
		(layer "In6.Cu")
		(net "M_E_CPU0_SA_DQ<2>")
	)
	(segment
		(start 293.652702 -197.760082)
		(end 290.638992 -197.760082)
		(width 0.14478)
		(layer "In6.Cu")
		(net "M_E_CPU0_SA_DQ<2>")
	)
	(segment
		(start 326.989694 -221.08033)
		(end 324.541134 -218.63177)
		(width 0.14478)
		(layer "In6.Cu")
		(net "M_E_CPU0_SA_DQ<2>")
	)
	(segment
		(start 298.172378 -197.760082)
		(end 297.32224 -198.61022)
		(width 0.14478)
		(layer "In6.Cu")
		(net "M_E_CPU0_SA_DQ<2>")
	)
	(segment
		(start 275.482812 -198.447152)
		(end 275.482812 -198.116698)
		(width 0.14478)
		(layer "In6.Cu")
		(net "M_E_CPU0_SA_DQ<2>")
	)
	(segment
		(start 327.195688 -221.80423)
		(end 327.195688 -221.643702)
		(width 0.0889)
		(layer "In6.Cu")
		(net "M_E_CPU0_SA_DQ<2>")
	)
	(arc
		(start 327.438004 -222.268034)
		(mid 327.259939 -222.065857)
		(end 327.195688 -221.80423)
		(width 0.0889)
		(layer "In6.Cu")
		(net "M_E_CPU0_SA_DQ<2>")
	)
	(arc
		(start 328.381868 -223.890586)
		(mid 328.201216 -223.687841)
		(end 328.135996 -223.424242)
		(width 0.0889)
		(layer "In6.Cu")
		(net "M_E_CPU0_SA_DQ<2>")
	)
	(arc
		(start 328.135996 -223.424242)
		(mid 328.094741 -223.253271)
		(end 327.98004 -223.11995)
		(width 0.0889)
		(layer "In6.Cu")
		(net "M_E_CPU0_SA_DQ<2>")
	)
	(arc
		(start 328.379074 -225.50882)
		(mid 328.135747 -225.044254)
		(end 328.379074 -224.579688)
		(width 0.0889)
		(layer "In6.Cu")
		(net "M_E_CPU0_SA_DQ<2>")
	)
	(arc
		(start 327.911968 -223.08058)
		(mid 327.731316 -222.877835)
		(end 327.666096 -222.614236)
		(width 0.0889)
		(layer "In6.Cu")
		(net "M_E_CPU0_SA_DQ<2>")
	)
	(arc
		(start 327.666096 -222.614236)
		(mid 327.624841 -222.443265)
		(end 327.51014 -222.309944)
		(width 0.0889)
		(layer "In6.Cu")
		(net "M_E_CPU0_SA_DQ<2>")
	)
	(arc
		(start 328.44994 -224.53854)
		(mid 328.605868 -224.234248)
		(end 328.44994 -223.929956)
		(width 0.0889)
		(layer "In6.Cu")
		(net "M_E_CPU0_SA_DQ<2>")
	)
	(arc
		(start 328.92111 -225.56343)
		(mid 328.665902 -225.606907)
		(end 328.41819 -225.53168)
		(width 0.0889)
		(layer "In6.Cu")
		(net "M_E_CPU0_SA_DQ<2>")
	)
	(segment
		(start 330.577952 -243.940076)
		(end 330.1111 -243.674138)
		(width 0.10668)
		(layer "F.Cu")
		(net "M_E_CPU0_SA_DQ<29>")
	)
	(segment
		(start 323.893434 -243.06657)
		(end 316.048898 -243.06657)
		(width 0.14478)
		(layer "In6.Cu")
		(net "M_E_CPU0_SA_DQ<29>")
	)
	(segment
		(start 293.630858 -232.610152)
		(end 291.796216 -232.610152)
		(width 0.14478)
		(layer "In6.Cu")
		(net "M_E_CPU0_SA_DQ<29>")
	)
	(segment
		(start 278.421338 -233.85145)
		(end 278.25827 -233.688382)
		(width 0.14478)
		(layer "In6.Cu")
		(net "M_E_CPU0_SA_DQ<29>")
	)
	(segment
		(start 291.796216 -232.610152)
		(end 291.395658 -232.209594)
		(width 0.14478)
		(layer "In6.Cu")
		(net "M_E_CPU0_SA_DQ<29>")
	)
	(segment
		(start 325.293736 -243.49583)
		(end 324.556374 -243.49583)
		(width 0.0889)
		(layer "In6.Cu")
		(net "M_E_CPU0_SA_DQ<29>")
	)
	(segment
		(start 328.992484 -244.001544)
		(end 328.984102 -243.996718)
		(width 0.0889)
		(layer "In6.Cu")
		(net "M_E_CPU0_SA_DQ<29>")
	)
	(segment
		(start 289.909758 -233.460036)
		(end 289.634422 -233.460036)
		(width 0.14478)
		(layer "In6.Cu")
		(net "M_E_CPU0_SA_DQ<29>")
	)
	(segment
		(start 303.466246 -233.460036)
		(end 303.303178 -233.623104)
		(width 0.14478)
		(layer "In6.Cu")
		(net "M_E_CPU0_SA_DQ<29>")
	)
	(segment
		(start 327.47839 -243.996718)
		(end 327.470008 -244.001544)
		(width 0.0889)
		(layer "In6.Cu")
		(net "M_E_CPU0_SA_DQ<29>")
	)
	(segment
		(start 303.303178 -233.623104)
		(end 303.303178 -233.690922)
		(width 0.14478)
		(layer "In6.Cu")
		(net "M_E_CPU0_SA_DQ<29>")
	)
	(segment
		(start 301.174658 -232.610152)
		(end 298.412662 -232.610152)
		(width 0.14478)
		(layer "In6.Cu")
		(net "M_E_CPU0_SA_DQ<29>")
	)
	(segment
		(start 327.488804 -243.990622)
		(end 327.47839 -243.996718)
		(width 0.0889)
		(layer "In6.Cu")
		(net "M_E_CPU0_SA_DQ<29>")
	)
	(segment
		(start 303.859692 -233.690922)
		(end 303.859692 -233.623104)
		(width 0.14478)
		(layer "In6.Cu")
		(net "M_E_CPU0_SA_DQ<29>")
	)
	(segment
		(start 315.259212 -241.89944)
		(end 314.881768 -241.89944)
		(width 0.14478)
		(layer "In6.Cu")
		(net "M_E_CPU0_SA_DQ<29>")
	)
	(segment
		(start 283.256482 -232.610152)
		(end 282.406598 -233.460036)
		(width 0.14478)
		(layer "In6.Cu")
		(net "M_E_CPU0_SA_DQ<29>")
	)
	(segment
		(start 304.416206 -233.623104)
		(end 304.416206 -233.690922)
		(width 0.14478)
		(layer "In6.Cu")
		(net "M_E_CPU0_SA_DQ<29>")
	)
	(segment
		(start 288.751772 -233.460036)
		(end 286.804862 -233.460036)
		(width 0.14478)
		(layer "In6.Cu")
		(net "M_E_CPU0_SA_DQ<29>")
	)
	(segment
		(start 303.696624 -233.460036)
		(end 303.466246 -233.460036)
		(width 0.14478)
		(layer "In6.Cu")
		(net "M_E_CPU0_SA_DQ<29>")
	)
	(segment
		(start 278.25827 -233.623104)
		(end 278.095202 -233.460036)
		(width 0.14478)
		(layer "In6.Cu")
		(net "M_E_CPU0_SA_DQ<29>")
	)
	(segment
		(start 279.764744 -233.85145)
		(end 279.534366 -233.85145)
		(width 0.14478)
		(layer "In6.Cu")
		(net "M_E_CPU0_SA_DQ<29>")
	)
	(segment
		(start 316.048898 -243.06657)
		(end 315.462158 -242.47983)
		(width 0.14478)
		(layer "In6.Cu")
		(net "M_E_CPU0_SA_DQ<29>")
	)
	(segment
		(start 327.104756 -243.996718)
		(end 327.094342 -243.990622)
		(width 0.0889)
		(layer "In6.Cu")
		(net "M_E_CPU0_SA_DQ<29>")
	)
	(segment
		(start 297.235372 -233.460036)
		(end 297.072304 -233.623104)
		(width 0.14478)
		(layer "In6.Cu")
		(net "M_E_CPU0_SA_DQ<29>")
	)
	(segment
		(start 289.471354 -233.678222)
		(end 289.308286 -233.84129)
		(width 0.14478)
		(layer "In6.Cu")
		(net "M_E_CPU0_SA_DQ<29>")
	)
	(segment
		(start 289.471354 -233.623104)
		(end 289.471354 -233.678222)
		(width 0.14478)
		(layer "In6.Cu")
		(net "M_E_CPU0_SA_DQ<29>")
	)
	(segment
		(start 302.024542 -233.460036)
		(end 301.174658 -232.610152)
		(width 0.14478)
		(layer "In6.Cu")
		(net "M_E_CPU0_SA_DQ<29>")
	)
	(segment
		(start 302.746664 -233.623104)
		(end 302.583596 -233.460036)
		(width 0.14478)
		(layer "In6.Cu")
		(net "M_E_CPU0_SA_DQ<29>")
	)
	(segment
		(start 282.406598 -233.460036)
		(end 280.09088 -233.460036)
		(width 0.14478)
		(layer "In6.Cu")
		(net "M_E_CPU0_SA_DQ<29>")
	)
	(segment
		(start 279.534366 -233.85145)
		(end 279.371298 -233.688382)
		(width 0.14478)
		(layer "In6.Cu")
		(net "M_E_CPU0_SA_DQ<29>")
	)
	(segment
		(start 328.41819 -243.996718)
		(end 328.409808 -244.001544)
		(width 0.0889)
		(layer "In6.Cu")
		(net "M_E_CPU0_SA_DQ<29>")
	)
	(segment
		(start 296.678858 -233.84891)
		(end 296.51579 -233.685842)
		(width 0.14478)
		(layer "In6.Cu")
		(net "M_E_CPU0_SA_DQ<29>")
	)
	(segment
		(start 304.579274 -233.460036)
		(end 304.416206 -233.623104)
		(width 0.14478)
		(layer "In6.Cu")
		(net "M_E_CPU0_SA_DQ<29>")
	)
	(segment
		(start 308.145434 -232.98785)
		(end 307.081936 -232.98785)
		(width 0.14478)
		(layer "In6.Cu")
		(net "M_E_CPU0_SA_DQ<29>")
	)
	(segment
		(start 302.583596 -233.460036)
		(end 302.024542 -233.460036)
		(width 0.14478)
		(layer "In6.Cu")
		(net "M_E_CPU0_SA_DQ<29>")
	)
	(segment
		(start 314.475876 -241.116104)
		(end 314.098432 -241.116104)
		(width 0.14478)
		(layer "In6.Cu")
		(net "M_E_CPU0_SA_DQ<29>")
	)
	(segment
		(start 309.079138 -233.921554)
		(end 308.145434 -232.98785)
		(width 0.14478)
		(layer "In6.Cu")
		(net "M_E_CPU0_SA_DQ<29>")
	)
	(segment
		(start 304.416206 -233.690922)
		(end 304.253138 -233.85399)
		(width 0.14478)
		(layer "In6.Cu")
		(net "M_E_CPU0_SA_DQ<29>")
	)
	(segment
		(start 286.804862 -233.460036)
		(end 285.954978 -232.610152)
		(width 0.14478)
		(layer "In6.Cu")
		(net "M_E_CPU0_SA_DQ<29>")
	)
	(segment
		(start 296.909236 -233.84891)
		(end 296.678858 -233.84891)
		(width 0.14478)
		(layer "In6.Cu")
		(net "M_E_CPU0_SA_DQ<29>")
	)
	(segment
		(start 278.814784 -233.688382)
		(end 278.651716 -233.85145)
		(width 0.14478)
		(layer "In6.Cu")
		(net "M_E_CPU0_SA_DQ<29>")
	)
	(segment
		(start 296.51579 -233.623104)
		(end 296.352722 -233.460036)
		(width 0.14478)
		(layer "In6.Cu")
		(net "M_E_CPU0_SA_DQ<29>")
	)
	(segment
		(start 288.91484 -233.678222)
		(end 288.91484 -233.623104)
		(width 0.14478)
		(layer "In6.Cu")
		(net "M_E_CPU0_SA_DQ<29>")
	)
	(segment
		(start 278.651716 -233.85145)
		(end 278.421338 -233.85145)
		(width 0.14478)
		(layer "In6.Cu")
		(net "M_E_CPU0_SA_DQ<29>")
	)
	(segment
		(start 279.371298 -233.23169)
		(end 279.20823 -233.068622)
		(width 0.14478)
		(layer "In6.Cu")
		(net "M_E_CPU0_SA_DQ<29>")
	)
	(segment
		(start 324.556374 -243.49583)
		(end 324.127114 -243.06657)
		(width 0.0889)
		(layer "In6.Cu")
		(net "M_E_CPU0_SA_DQ<29>")
	)
	(segment
		(start 302.909732 -233.85399)
		(end 302.746664 -233.690922)
		(width 0.14478)
		(layer "In6.Cu")
		(net "M_E_CPU0_SA_DQ<29>")
	)
	(segment
		(start 278.095202 -233.460036)
		(end 277.617174 -233.460036)
		(width 0.14478)
		(layer "In6.Cu")
		(net "M_E_CPU0_SA_DQ<29>")
	)
	(segment
		(start 290.458398 -232.911396)
		(end 289.909758 -233.460036)
		(width 0.14478)
		(layer "In6.Cu")
		(net "M_E_CPU0_SA_DQ<29>")
	)
	(segment
		(start 298.412662 -232.610152)
		(end 297.562778 -233.460036)
		(width 0.14478)
		(layer "In6.Cu")
		(net "M_E_CPU0_SA_DQ<29>")
	)
	(segment
		(start 279.20823 -233.068622)
		(end 278.977852 -233.068622)
		(width 0.14478)
		(layer "In6.Cu")
		(net "M_E_CPU0_SA_DQ<29>")
	)
	(segment
		(start 291.395658 -232.209594)
		(end 290.789868 -232.209594)
		(width 0.14478)
		(layer "In6.Cu")
		(net "M_E_CPU0_SA_DQ<29>")
	)
	(segment
		(start 279.927812 -233.623104)
		(end 279.927812 -233.688382)
		(width 0.14478)
		(layer "In6.Cu")
		(net "M_E_CPU0_SA_DQ<29>")
	)
	(segment
		(start 315.462158 -242.47983)
		(end 315.462158 -242.102386)
		(width 0.14478)
		(layer "In6.Cu")
		(net "M_E_CPU0_SA_DQ<29>")
	)
	(segment
		(start 297.072304 -233.685842)
		(end 296.909236 -233.84891)
		(width 0.14478)
		(layer "In6.Cu")
		(net "M_E_CPU0_SA_DQ<29>")
	)
	(segment
		(start 297.562778 -233.460036)
		(end 297.235372 -233.460036)
		(width 0.14478)
		(layer "In6.Cu")
		(net "M_E_CPU0_SA_DQ<29>")
	)
	(segment
		(start 278.25827 -233.688382)
		(end 278.25827 -233.623104)
		(width 0.14478)
		(layer "In6.Cu")
		(net "M_E_CPU0_SA_DQ<29>")
	)
	(segment
		(start 304.02276 -233.85399)
		(end 303.859692 -233.690922)
		(width 0.14478)
		(layer "In6.Cu")
		(net "M_E_CPU0_SA_DQ<29>")
	)
	(segment
		(start 297.072304 -233.623104)
		(end 297.072304 -233.685842)
		(width 0.14478)
		(layer "In6.Cu")
		(net "M_E_CPU0_SA_DQ<29>")
	)
	(segment
		(start 303.303178 -233.690922)
		(end 303.14011 -233.85399)
		(width 0.14478)
		(layer "In6.Cu")
		(net "M_E_CPU0_SA_DQ<29>")
	)
	(segment
		(start 315.462158 -242.102386)
		(end 315.259212 -241.89944)
		(width 0.14478)
		(layer "In6.Cu")
		(net "M_E_CPU0_SA_DQ<29>")
	)
	(segment
		(start 289.634422 -233.460036)
		(end 289.471354 -233.623104)
		(width 0.14478)
		(layer "In6.Cu")
		(net "M_E_CPU0_SA_DQ<29>")
	)
	(segment
		(start 314.098432 -241.116104)
		(end 310.617362 -237.635034)
		(width 0.14478)
		(layer "In6.Cu")
		(net "M_E_CPU0_SA_DQ<29>")
	)
	(segment
		(start 278.814784 -233.23169)
		(end 278.814784 -233.688382)
		(width 0.14478)
		(layer "In6.Cu")
		(net "M_E_CPU0_SA_DQ<29>")
	)
	(segment
		(start 330.265024 -243.939568)
		(end 330.242672 -244.02288)
		(width 0.0889)
		(layer "In6.Cu")
		(net "M_E_CPU0_SA_DQ<29>")
	)
	(segment
		(start 303.859692 -233.623104)
		(end 303.696624 -233.460036)
		(width 0.14478)
		(layer "In6.Cu")
		(net "M_E_CPU0_SA_DQ<29>")
	)
	(segment
		(start 290.458398 -232.541064)
		(end 290.458398 -232.911396)
		(width 0.14478)
		(layer "In6.Cu")
		(net "M_E_CPU0_SA_DQ<29>")
	)
	(segment
		(start 278.977852 -233.068622)
		(end 278.814784 -233.23169)
		(width 0.14478)
		(layer "In6.Cu")
		(net "M_E_CPU0_SA_DQ<29>")
	)
	(segment
		(start 296.352722 -233.460036)
		(end 294.480742 -233.460036)
		(width 0.14478)
		(layer "In6.Cu")
		(net "M_E_CPU0_SA_DQ<29>")
	)
	(segment
		(start 304.871374 -233.460036)
		(end 304.579274 -233.460036)
		(width 0.14478)
		(layer "In6.Cu")
		(net "M_E_CPU0_SA_DQ<29>")
	)
	(segment
		(start 290.789868 -232.209594)
		(end 290.458398 -232.541064)
		(width 0.14478)
		(layer "In6.Cu")
		(net "M_E_CPU0_SA_DQ<29>")
	)
	(segment
		(start 303.14011 -233.85399)
		(end 302.909732 -233.85399)
		(width 0.14478)
		(layer "In6.Cu")
		(net "M_E_CPU0_SA_DQ<29>")
	)
	(segment
		(start 314.678822 -241.696494)
		(end 314.678822 -241.31905)
		(width 0.14478)
		(layer "In6.Cu")
		(net "M_E_CPU0_SA_DQ<29>")
	)
	(segment
		(start 314.881768 -241.89944)
		(end 314.678822 -241.696494)
		(width 0.14478)
		(layer "In6.Cu")
		(net "M_E_CPU0_SA_DQ<29>")
	)
	(segment
		(start 280.09088 -233.460036)
		(end 279.927812 -233.623104)
		(width 0.14478)
		(layer "In6.Cu")
		(net "M_E_CPU0_SA_DQ<29>")
	)
	(segment
		(start 325.84517 -244.047264)
		(end 325.293736 -243.49583)
		(width 0.0889)
		(layer "In6.Cu")
		(net "M_E_CPU0_SA_DQ<29>")
	)
	(segment
		(start 330.1111 -243.674138)
		(end 330.265024 -243.939568)
		(width 0.0889)
		(layer "In6.Cu")
		(net "M_E_CPU0_SA_DQ<29>")
	)
	(segment
		(start 285.954978 -232.610152)
		(end 283.256482 -232.610152)
		(width 0.14478)
		(layer "In6.Cu")
		(net "M_E_CPU0_SA_DQ<29>")
	)
	(segment
		(start 307.081936 -232.98785)
		(end 306.480718 -232.386632)
		(width 0.14478)
		(layer "In6.Cu")
		(net "M_E_CPU0_SA_DQ<29>")
	)
	(segment
		(start 279.927812 -233.688382)
		(end 279.764744 -233.85145)
		(width 0.14478)
		(layer "In6.Cu")
		(net "M_E_CPU0_SA_DQ<29>")
	)
	(segment
		(start 289.308286 -233.84129)
		(end 289.077908 -233.84129)
		(width 0.14478)
		(layer "In6.Cu")
		(net "M_E_CPU0_SA_DQ<29>")
	)
	(segment
		(start 279.371298 -233.688382)
		(end 279.371298 -233.23169)
		(width 0.14478)
		(layer "In6.Cu")
		(net "M_E_CPU0_SA_DQ<29>")
	)
	(segment
		(start 289.077908 -233.84129)
		(end 288.91484 -233.678222)
		(width 0.14478)
		(layer "In6.Cu")
		(net "M_E_CPU0_SA_DQ<29>")
	)
	(segment
		(start 324.127114 -243.06657)
		(end 323.893434 -243.06657)
		(width 0.0889)
		(layer "In6.Cu")
		(net "M_E_CPU0_SA_DQ<29>")
	)
	(segment
		(start 326.351138 -244.047264)
		(end 325.84517 -244.047264)
		(width 0.0889)
		(layer "In6.Cu")
		(net "M_E_CPU0_SA_DQ<29>")
	)
	(segment
		(start 296.51579 -233.685842)
		(end 296.51579 -233.623104)
		(width 0.14478)
		(layer "In6.Cu")
		(net "M_E_CPU0_SA_DQ<29>")
	)
	(segment
		(start 302.746664 -233.690922)
		(end 302.746664 -233.623104)
		(width 0.14478)
		(layer "In6.Cu")
		(net "M_E_CPU0_SA_DQ<29>")
	)
	(segment
		(start 288.91484 -233.623104)
		(end 288.751772 -233.460036)
		(width 0.14478)
		(layer "In6.Cu")
		(net "M_E_CPU0_SA_DQ<29>")
	)
	(segment
		(start 277.617174 -233.460036)
		(end 277.192232 -233.035094)
		(width 0.14478)
		(layer "In6.Cu")
		(net "M_E_CPU0_SA_DQ<29>")
	)
	(segment
		(start 310.617362 -237.635034)
		(end 309.079138 -233.921554)
		(width 0.14478)
		(layer "In6.Cu")
		(net "M_E_CPU0_SA_DQ<29>")
	)
	(segment
		(start 306.480718 -232.386632)
		(end 305.944778 -232.386632)
		(width 0.14478)
		(layer "In6.Cu")
		(net "M_E_CPU0_SA_DQ<29>")
	)
	(segment
		(start 304.253138 -233.85399)
		(end 304.02276 -233.85399)
		(width 0.14478)
		(layer "In6.Cu")
		(net "M_E_CPU0_SA_DQ<29>")
	)
	(segment
		(start 314.678822 -241.31905)
		(end 314.475876 -241.116104)
		(width 0.14478)
		(layer "In6.Cu")
		(net "M_E_CPU0_SA_DQ<29>")
	)
	(segment
		(start 305.944778 -232.386632)
		(end 304.871374 -233.460036)
		(width 0.14478)
		(layer "In6.Cu")
		(net "M_E_CPU0_SA_DQ<29>")
	)
	(segment
		(start 294.480742 -233.460036)
		(end 293.630858 -232.610152)
		(width 0.14478)
		(layer "In6.Cu")
		(net "M_E_CPU0_SA_DQ<29>")
	)
	(arc
		(start 329.924156 -243.996718)
		(mid 329.6412 -243.920541)
		(end 329.358244 -243.996718)
		(width 0.0889)
		(layer "In6.Cu")
		(net "M_E_CPU0_SA_DQ<29>")
	)
	(arc
		(start 329.358244 -243.996718)
		(mid 329.175993 -244.047068)
		(end 328.992484 -244.001544)
		(width 0.0889)
		(layer "In6.Cu")
		(net "M_E_CPU0_SA_DQ<29>")
	)
	(arc
		(start 326.53859 -243.996718)
		(mid 326.448207 -244.034379)
		(end 326.351138 -244.047264)
		(width 0.0889)
		(layer "In6.Cu")
		(net "M_E_CPU0_SA_DQ<29>")
	)
	(arc
		(start 328.044048 -243.996718)
		(mid 327.767235 -243.920575)
		(end 327.488804 -243.990622)
		(width 0.0889)
		(layer "In6.Cu")
		(net "M_E_CPU0_SA_DQ<29>")
	)
	(arc
		(start 328.984102 -243.996718)
		(mid 328.701146 -243.920541)
		(end 328.41819 -243.996718)
		(width 0.0889)
		(layer "In6.Cu")
		(net "M_E_CPU0_SA_DQ<29>")
	)
	(arc
		(start 327.470008 -244.001544)
		(mid 327.286754 -244.046917)
		(end 327.104756 -243.996718)
		(width 0.0889)
		(layer "In6.Cu")
		(net "M_E_CPU0_SA_DQ<29>")
	)
	(arc
		(start 330.242672 -244.02288)
		(mid 330.080483 -244.045615)
		(end 329.924156 -243.996718)
		(width 0.0889)
		(layer "In6.Cu")
		(net "M_E_CPU0_SA_DQ<29>")
	)
	(arc
		(start 327.094342 -243.990622)
		(mid 326.815656 -243.920402)
		(end 326.53859 -243.996718)
		(width 0.0889)
		(layer "In6.Cu")
		(net "M_E_CPU0_SA_DQ<29>")
	)
	(arc
		(start 328.409808 -244.001544)
		(mid 328.2263 -244.047038)
		(end 328.044048 -243.996718)
		(width 0.0889)
		(layer "In6.Cu")
		(net "M_E_CPU0_SA_DQ<29>")
	)
	(segment
		(start 329.167998 -243.13007)
		(end 328.701146 -242.864132)
		(width 0.10668)
		(layer "F.Cu")
		(net "M_E_CPU0_SA_DQ<28>")
	)
	(segment
		(start 278.570182 -231.154478)
		(end 278.407114 -230.99141)
		(width 0.14478)
		(layer "In6.Cu")
		(net "M_E_CPU0_SA_DQ<28>")
	)
	(segment
		(start 279.944576 -231.923082)
		(end 279.944576 -231.981502)
		(width 0.14478)
		(layer "In6.Cu")
		(net "M_E_CPU0_SA_DQ<28>")
	)
	(segment
		(start 289.003994 -231.923082)
		(end 288.850578 -231.769666)
		(width 0.14478)
		(layer "In6.Cu")
		(net "M_E_CPU0_SA_DQ<28>")
	)
	(segment
		(start 282.406598 -231.760014)
		(end 282.027376 -231.760014)
		(width 0.14478)
		(layer "In6.Cu")
		(net "M_E_CPU0_SA_DQ<28>")
	)
	(segment
		(start 313.413648 -239.15624)
		(end 313.413648 -238.951516)
		(width 0.14478)
		(layer "In6.Cu")
		(net "M_E_CPU0_SA_DQ<28>")
	)
	(segment
		(start 305.106578 -231.760014)
		(end 304.276252 -231.760014)
		(width 0.14478)
		(layer "In6.Cu")
		(net "M_E_CPU0_SA_DQ<28>")
	)
	(segment
		(start 312.630312 -238.16818)
		(end 312.7756 -238.022892)
		(width 0.14478)
		(layer "In6.Cu")
		(net "M_E_CPU0_SA_DQ<28>")
	)
	(segment
		(start 313.600592 -239.343184)
		(end 313.413648 -239.15624)
		(width 0.14478)
		(layer "In6.Cu")
		(net "M_E_CPU0_SA_DQ<28>")
	)
	(segment
		(start 314.342272 -239.589564)
		(end 314.342272 -239.38484)
		(width 0.14478)
		(layer "In6.Cu")
		(net "M_E_CPU0_SA_DQ<28>")
	)
	(segment
		(start 279.944576 -231.981502)
		(end 279.781508 -232.14457)
		(width 0.14478)
		(layer "In6.Cu")
		(net "M_E_CPU0_SA_DQ<28>")
	)
	(segment
		(start 311.40908 -237.151672)
		(end 309.872888 -233.443272)
		(width 0.14478)
		(layer "In6.Cu")
		(net "M_E_CPU0_SA_DQ<28>")
	)
	(segment
		(start 283.24683 -230.919782)
		(end 282.406598 -231.760014)
		(width 0.14478)
		(layer "In6.Cu")
		(net "M_E_CPU0_SA_DQ<28>")
	)
	(segment
		(start 316.018926 -241.379248)
		(end 315.786262 -241.146584)
		(width 0.14478)
		(layer "In6.Cu")
		(net "M_E_CPU0_SA_DQ<28>")
	)
	(segment
		(start 314.342272 -239.38484)
		(end 314.155328 -239.197896)
		(width 0.14478)
		(layer "In6.Cu")
		(net "M_E_CPU0_SA_DQ<28>")
	)
	(segment
		(start 301.871126 -231.760014)
		(end 301.030894 -230.919782)
		(width 0.14478)
		(layer "In6.Cu")
		(net "M_E_CPU0_SA_DQ<28>")
	)
	(segment
		(start 315.786262 -240.829084)
		(end 315.553344 -240.596166)
		(width 0.14478)
		(layer "In6.Cu")
		(net "M_E_CPU0_SA_DQ<28>")
	)
	(segment
		(start 281.307794 -231.976422)
		(end 281.307794 -231.923082)
		(width 0.14478)
		(layer "In6.Cu")
		(net "M_E_CPU0_SA_DQ<28>")
	)
	(segment
		(start 282.027376 -231.760014)
		(end 281.864308 -231.923082)
		(width 0.14478)
		(layer "In6.Cu")
		(net "M_E_CPU0_SA_DQ<28>")
	)
	(segment
		(start 277.8506 -231.760014)
		(end 277.617174 -231.760014)
		(width 0.14478)
		(layer "In6.Cu")
		(net "M_E_CPU0_SA_DQ<28>")
	)
	(segment
		(start 315.553344 -240.596166)
		(end 315.23559 -240.596166)
		(width 0.14478)
		(layer "In6.Cu")
		(net "M_E_CPU0_SA_DQ<28>")
	)
	(segment
		(start 316.569344 -241.92992)
		(end 316.569598 -241.61242)
		(width 0.14478)
		(layer "In6.Cu")
		(net "M_E_CPU0_SA_DQ<28>")
	)
	(segment
		(start 315.23559 -240.596166)
		(end 314.854336 -240.214912)
		(width 0.14478)
		(layer "In6.Cu")
		(net "M_E_CPU0_SA_DQ<28>")
	)
	(segment
		(start 314.854336 -240.214912)
		(end 314.47232 -240.214912)
		(width 0.14478)
		(layer "In6.Cu")
		(net "M_E_CPU0_SA_DQ<28>")
	)
	(segment
		(start 314.47232 -240.214912)
		(end 314.196984 -239.939576)
		(width 0.14478)
		(layer "In6.Cu")
		(net "M_E_CPU0_SA_DQ<28>")
	)
	(segment
		(start 304.113184 -231.989122)
		(end 303.950116 -232.15219)
		(width 0.14478)
		(layer "In6.Cu")
		(net "M_E_CPU0_SA_DQ<28>")
	)
	(segment
		(start 303.55667 -231.989122)
		(end 303.55667 -231.634538)
		(width 0.14478)
		(layer "In6.Cu")
		(net "M_E_CPU0_SA_DQ<28>")
	)
	(segment
		(start 289.560508 -231.923082)
		(end 289.560508 -231.976422)
		(width 0.14478)
		(layer "In6.Cu")
		(net "M_E_CPU0_SA_DQ<28>")
	)
	(segment
		(start 280.097992 -231.769666)
		(end 279.944576 -231.923082)
		(width 0.14478)
		(layer "In6.Cu")
		(net "M_E_CPU0_SA_DQ<28>")
	)
	(segment
		(start 307.649626 -231.22001)
		(end 305.646582 -231.22001)
		(width 0.14478)
		(layer "In6.Cu")
		(net "M_E_CPU0_SA_DQ<28>")
	)
	(segment
		(start 313.558936 -238.601504)
		(end 313.371992 -238.41456)
		(width 0.14478)
		(layer "In6.Cu")
		(net "M_E_CPU0_SA_DQ<28>")
	)
	(segment
		(start 278.013668 -231.596946)
		(end 277.8506 -231.760014)
		(width 0.14478)
		(layer "In6.Cu")
		(net "M_E_CPU0_SA_DQ<28>")
	)
	(segment
		(start 312.7756 -237.818168)
		(end 312.588656 -237.631224)
		(width 0.14478)
		(layer "In6.Cu")
		(net "M_E_CPU0_SA_DQ<28>")
	)
	(segment
		(start 312.588656 -237.631224)
		(end 312.383932 -237.631224)
		(width 0.14478)
		(layer "In6.Cu")
		(net "M_E_CPU0_SA_DQ<28>")
	)
	(segment
		(start 316.569598 -241.61242)
		(end 316.336934 -241.379756)
		(width 0.14478)
		(layer "In6.Cu")
		(net "M_E_CPU0_SA_DQ<28>")
	)
	(segment
		(start 305.646582 -231.22001)
		(end 305.106578 -231.760014)
		(width 0.14478)
		(layer "In6.Cu")
		(net "M_E_CPU0_SA_DQ<28>")
	)
	(segment
		(start 281.307794 -231.923082)
		(end 281.154378 -231.769666)
		(width 0.14478)
		(layer "In6.Cu")
		(net "M_E_CPU0_SA_DQ<28>")
	)
	(segment
		(start 312.7756 -238.022892)
		(end 312.7756 -237.818168)
		(width 0.14478)
		(layer "In6.Cu")
		(net "M_E_CPU0_SA_DQ<28>")
	)
	(segment
		(start 325.667624 -243.110512)
		(end 325.062088 -242.504976)
		(width 0.0889)
		(layer "In6.Cu")
		(net "M_E_CPU0_SA_DQ<28>")
	)
	(segment
		(start 324.48754 -242.504976)
		(end 324.139814 -242.15725)
		(width 0.0889)
		(layer "In6.Cu")
		(net "M_E_CPU0_SA_DQ<28>")
	)
	(segment
		(start 313.805316 -239.343184)
		(end 313.600592 -239.343184)
		(width 0.14478)
		(layer "In6.Cu")
		(net "M_E_CPU0_SA_DQ<28>")
	)
	(segment
		(start 312.383932 -237.631224)
		(end 312.238644 -237.776512)
		(width 0.14478)
		(layer "In6.Cu")
		(net "M_E_CPU0_SA_DQ<28>")
	)
	(segment
		(start 312.630312 -238.372904)
		(end 312.630312 -238.16818)
		(width 0.14478)
		(layer "In6.Cu")
		(net "M_E_CPU0_SA_DQ<28>")
	)
	(segment
		(start 316.796674 -242.15725)
		(end 316.569344 -241.92992)
		(width 0.14478)
		(layer "In6.Cu")
		(net "M_E_CPU0_SA_DQ<28>")
	)
	(segment
		(start 281.864308 -231.923082)
		(end 281.864308 -231.976422)
		(width 0.14478)
		(layer "In6.Cu")
		(net "M_E_CPU0_SA_DQ<28>")
	)
	(segment
		(start 279.388062 -231.981502)
		(end 279.388062 -231.923082)
		(width 0.14478)
		(layer "In6.Cu")
		(net "M_E_CPU0_SA_DQ<28>")
	)
	(segment
		(start 327.017888 -243.180616)
		(end 327.007474 -243.186712)
		(width 0.0889)
		(layer "In6.Cu")
		(net "M_E_CPU0_SA_DQ<28>")
	)
	(segment
		(start 313.02198 -238.559848)
		(end 312.817256 -238.559848)
		(width 0.14478)
		(layer "In6.Cu")
		(net "M_E_CPU0_SA_DQ<28>")
	)
	(segment
		(start 278.407114 -230.99141)
		(end 278.176736 -230.99141)
		(width 0.14478)
		(layer "In6.Cu")
		(net "M_E_CPU0_SA_DQ<28>")
	)
	(segment
		(start 289.723576 -231.760014)
		(end 289.560508 -231.923082)
		(width 0.14478)
		(layer "In6.Cu")
		(net "M_E_CPU0_SA_DQ<28>")
	)
	(segment
		(start 281.864308 -231.976422)
		(end 281.70124 -232.13949)
		(width 0.14478)
		(layer "In6.Cu")
		(net "M_E_CPU0_SA_DQ<28>")
	)
	(segment
		(start 281.154378 -231.769666)
		(end 280.097992 -231.769666)
		(width 0.14478)
		(layer "In6.Cu")
		(net "M_E_CPU0_SA_DQ<28>")
	)
	(segment
		(start 312.03392 -237.776512)
		(end 311.40908 -237.151672)
		(width 0.14478)
		(layer "In6.Cu")
		(net "M_E_CPU0_SA_DQ<28>")
	)
	(segment
		(start 279.781508 -232.14457)
		(end 279.55113 -232.14457)
		(width 0.14478)
		(layer "In6.Cu")
		(net "M_E_CPU0_SA_DQ<28>")
	)
	(segment
		(start 303.163224 -231.47147)
		(end 303.000156 -231.634538)
		(width 0.14478)
		(layer "In6.Cu")
		(net "M_E_CPU0_SA_DQ<28>")
	)
	(segment
		(start 312.238644 -237.776512)
		(end 312.03392 -237.776512)
		(width 0.14478)
		(layer "In6.Cu")
		(net "M_E_CPU0_SA_DQ<28>")
	)
	(segment
		(start 313.167268 -238.41456)
		(end 313.02198 -238.559848)
		(width 0.14478)
		(layer "In6.Cu")
		(net "M_E_CPU0_SA_DQ<28>")
	)
	(segment
		(start 278.013668 -231.154478)
		(end 278.013668 -231.596946)
		(width 0.14478)
		(layer "In6.Cu")
		(net "M_E_CPU0_SA_DQ<28>")
	)
	(segment
		(start 293.527734 -230.919782)
		(end 290.74999 -230.919782)
		(width 0.14478)
		(layer "In6.Cu")
		(net "M_E_CPU0_SA_DQ<28>")
	)
	(segment
		(start 288.850578 -231.769666)
		(end 286.814514 -231.769666)
		(width 0.14478)
		(layer "In6.Cu")
		(net "M_E_CPU0_SA_DQ<28>")
	)
	(segment
		(start 278.570182 -231.596946)
		(end 278.570182 -231.154478)
		(width 0.14478)
		(layer "In6.Cu")
		(net "M_E_CPU0_SA_DQ<28>")
	)
	(segment
		(start 328.701146 -242.864132)
		(end 328.85507 -243.129562)
		(width 0.0889)
		(layer "In6.Cu")
		(net "M_E_CPU0_SA_DQ<28>")
	)
	(segment
		(start 281.470862 -232.13949)
		(end 281.307794 -231.976422)
		(width 0.14478)
		(layer "In6.Cu")
		(net "M_E_CPU0_SA_DQ<28>")
	)
	(segment
		(start 289.167062 -232.13949)
		(end 289.003994 -231.976422)
		(width 0.14478)
		(layer "In6.Cu")
		(net "M_E_CPU0_SA_DQ<28>")
	)
	(segment
		(start 314.196984 -239.734852)
		(end 314.342272 -239.589564)
		(width 0.14478)
		(layer "In6.Cu")
		(net "M_E_CPU0_SA_DQ<28>")
	)
	(segment
		(start 279.55113 -232.14457)
		(end 279.388062 -231.981502)
		(width 0.14478)
		(layer "In6.Cu")
		(net "M_E_CPU0_SA_DQ<28>")
	)
	(segment
		(start 289.560508 -231.976422)
		(end 289.39744 -232.13949)
		(width 0.14478)
		(layer "In6.Cu")
		(net "M_E_CPU0_SA_DQ<28>")
	)
	(segment
		(start 312.817256 -238.559848)
		(end 312.630312 -238.372904)
		(width 0.14478)
		(layer "In6.Cu")
		(net "M_E_CPU0_SA_DQ<28>")
	)
	(segment
		(start 313.950604 -239.197896)
		(end 313.805316 -239.343184)
		(width 0.14478)
		(layer "In6.Cu")
		(net "M_E_CPU0_SA_DQ<28>")
	)
	(segment
		(start 303.950116 -232.15219)
		(end 303.719738 -232.15219)
		(width 0.14478)
		(layer "In6.Cu")
		(net "M_E_CPU0_SA_DQ<28>")
	)
	(segment
		(start 303.55667 -231.634538)
		(end 303.393602 -231.47147)
		(width 0.14478)
		(layer "In6.Cu")
		(net "M_E_CPU0_SA_DQ<28>")
	)
	(segment
		(start 303.393602 -231.47147)
		(end 303.163224 -231.47147)
		(width 0.14478)
		(layer "In6.Cu")
		(net "M_E_CPU0_SA_DQ<28>")
	)
	(segment
		(start 324.139814 -242.15725)
		(end 323.860414 -242.15725)
		(width 0.0889)
		(layer "In6.Cu")
		(net "M_E_CPU0_SA_DQ<28>")
	)
	(segment
		(start 313.558936 -238.806228)
		(end 313.558936 -238.601504)
		(width 0.14478)
		(layer "In6.Cu")
		(net "M_E_CPU0_SA_DQ<28>")
	)
	(segment
		(start 328.85507 -243.129562)
		(end 328.832718 -243.212874)
		(width 0.0889)
		(layer "In6.Cu")
		(net "M_E_CPU0_SA_DQ<28>")
	)
	(segment
		(start 302.280574 -231.760014)
		(end 301.871126 -231.760014)
		(width 0.14478)
		(layer "In6.Cu")
		(net "M_E_CPU0_SA_DQ<28>")
	)
	(segment
		(start 285.96463 -230.919782)
		(end 283.24683 -230.919782)
		(width 0.14478)
		(layer "In6.Cu")
		(net "M_E_CPU0_SA_DQ<28>")
	)
	(segment
		(start 277.617174 -231.760014)
		(end 277.192232 -231.335072)
		(width 0.14478)
		(layer "In6.Cu")
		(net "M_E_CPU0_SA_DQ<28>")
	)
	(segment
		(start 304.113184 -231.923082)
		(end 304.113184 -231.989122)
		(width 0.14478)
		(layer "In6.Cu")
		(net "M_E_CPU0_SA_DQ<28>")
	)
	(segment
		(start 304.276252 -231.760014)
		(end 304.113184 -231.923082)
		(width 0.14478)
		(layer "In6.Cu")
		(net "M_E_CPU0_SA_DQ<28>")
	)
	(segment
		(start 298.40301 -230.919782)
		(end 297.553126 -231.769666)
		(width 0.14478)
		(layer "In6.Cu")
		(net "M_E_CPU0_SA_DQ<28>")
	)
	(segment
		(start 301.030894 -230.919782)
		(end 298.40301 -230.919782)
		(width 0.14478)
		(layer "In6.Cu")
		(net "M_E_CPU0_SA_DQ<28>")
	)
	(segment
		(start 289.909758 -231.760014)
		(end 289.723576 -231.760014)
		(width 0.14478)
		(layer "In6.Cu")
		(net "M_E_CPU0_SA_DQ<28>")
	)
	(segment
		(start 323.860414 -242.15725)
		(end 316.796674 -242.15725)
		(width 0.14478)
		(layer "In6.Cu")
		(net "M_E_CPU0_SA_DQ<28>")
	)
	(segment
		(start 309.872888 -233.443272)
		(end 307.649626 -231.22001)
		(width 0.14478)
		(layer "In6.Cu")
		(net "M_E_CPU0_SA_DQ<28>")
	)
	(segment
		(start 303.000156 -231.989122)
		(end 302.837088 -232.15219)
		(width 0.14478)
		(layer "In6.Cu")
		(net "M_E_CPU0_SA_DQ<28>")
	)
	(segment
		(start 289.003994 -231.976422)
		(end 289.003994 -231.923082)
		(width 0.14478)
		(layer "In6.Cu")
		(net "M_E_CPU0_SA_DQ<28>")
	)
	(segment
		(start 289.39744 -232.13949)
		(end 289.167062 -232.13949)
		(width 0.14478)
		(layer "In6.Cu")
		(net "M_E_CPU0_SA_DQ<28>")
	)
	(segment
		(start 286.814514 -231.769666)
		(end 285.96463 -230.919782)
		(width 0.14478)
		(layer "In6.Cu")
		(net "M_E_CPU0_SA_DQ<28>")
	)
	(segment
		(start 302.443642 -231.989122)
		(end 302.443642 -231.923082)
		(width 0.14478)
		(layer "In6.Cu")
		(net "M_E_CPU0_SA_DQ<28>")
	)
	(segment
		(start 327.94829 -243.186712)
		(end 327.939908 -243.191538)
		(width 0.0889)
		(layer "In6.Cu")
		(net "M_E_CPU0_SA_DQ<28>")
	)
	(segment
		(start 281.70124 -232.13949)
		(end 281.470862 -232.13949)
		(width 0.14478)
		(layer "In6.Cu")
		(net "M_E_CPU0_SA_DQ<28>")
	)
	(segment
		(start 314.196984 -239.939576)
		(end 314.196984 -239.734852)
		(width 0.14478)
		(layer "In6.Cu")
		(net "M_E_CPU0_SA_DQ<28>")
	)
	(segment
		(start 302.60671 -232.15219)
		(end 302.443642 -231.989122)
		(width 0.14478)
		(layer "In6.Cu")
		(net "M_E_CPU0_SA_DQ<28>")
	)
	(segment
		(start 290.74999 -230.919782)
		(end 289.909758 -231.760014)
		(width 0.14478)
		(layer "In6.Cu")
		(net "M_E_CPU0_SA_DQ<28>")
	)
	(segment
		(start 303.719738 -232.15219)
		(end 303.55667 -231.989122)
		(width 0.14478)
		(layer "In6.Cu")
		(net "M_E_CPU0_SA_DQ<28>")
	)
	(segment
		(start 294.377618 -231.769666)
		(end 293.527734 -230.919782)
		(width 0.14478)
		(layer "In6.Cu")
		(net "M_E_CPU0_SA_DQ<28>")
	)
	(segment
		(start 302.443642 -231.923082)
		(end 302.280574 -231.760014)
		(width 0.14478)
		(layer "In6.Cu")
		(net "M_E_CPU0_SA_DQ<28>")
	)
	(segment
		(start 279.388062 -231.923082)
		(end 279.224994 -231.760014)
		(width 0.14478)
		(layer "In6.Cu")
		(net "M_E_CPU0_SA_DQ<28>")
	)
	(segment
		(start 325.062088 -242.504976)
		(end 324.48754 -242.504976)
		(width 0.0889)
		(layer "In6.Cu")
		(net "M_E_CPU0_SA_DQ<28>")
	)
	(segment
		(start 326.351646 -243.110512)
		(end 325.667624 -243.110512)
		(width 0.0889)
		(layer "In6.Cu")
		(net "M_E_CPU0_SA_DQ<28>")
	)
	(segment
		(start 326.649842 -243.195856)
		(end 326.633586 -243.186458)
		(width 0.0889)
		(layer "In6.Cu")
		(net "M_E_CPU0_SA_DQ<28>")
	)
	(segment
		(start 315.786262 -241.146584)
		(end 315.786262 -240.829084)
		(width 0.14478)
		(layer "In6.Cu")
		(net "M_E_CPU0_SA_DQ<28>")
	)
	(segment
		(start 278.73325 -231.760014)
		(end 278.570182 -231.596946)
		(width 0.14478)
		(layer "In6.Cu")
		(net "M_E_CPU0_SA_DQ<28>")
	)
	(segment
		(start 302.837088 -232.15219)
		(end 302.60671 -232.15219)
		(width 0.14478)
		(layer "In6.Cu")
		(net "M_E_CPU0_SA_DQ<28>")
	)
	(segment
		(start 314.155328 -239.197896)
		(end 313.950604 -239.197896)
		(width 0.14478)
		(layer "In6.Cu")
		(net "M_E_CPU0_SA_DQ<28>")
	)
	(segment
		(start 278.176736 -230.99141)
		(end 278.013668 -231.154478)
		(width 0.14478)
		(layer "In6.Cu")
		(net "M_E_CPU0_SA_DQ<28>")
	)
	(segment
		(start 313.413648 -238.951516)
		(end 313.558936 -238.806228)
		(width 0.14478)
		(layer "In6.Cu")
		(net "M_E_CPU0_SA_DQ<28>")
	)
	(segment
		(start 313.371992 -238.41456)
		(end 313.167268 -238.41456)
		(width 0.14478)
		(layer "In6.Cu")
		(net "M_E_CPU0_SA_DQ<28>")
	)
	(segment
		(start 316.336934 -241.379756)
		(end 316.018926 -241.379248)
		(width 0.14478)
		(layer "In6.Cu")
		(net "M_E_CPU0_SA_DQ<28>")
	)
	(segment
		(start 279.224994 -231.760014)
		(end 278.73325 -231.760014)
		(width 0.14478)
		(layer "In6.Cu")
		(net "M_E_CPU0_SA_DQ<28>")
	)
	(segment
		(start 303.000156 -231.634538)
		(end 303.000156 -231.989122)
		(width 0.14478)
		(layer "In6.Cu")
		(net "M_E_CPU0_SA_DQ<28>")
	)
	(segment
		(start 297.553126 -231.769666)
		(end 294.377618 -231.769666)
		(width 0.14478)
		(layer "In6.Cu")
		(net "M_E_CPU0_SA_DQ<28>")
	)
	(arc
		(start 326.383396 -243.111274)
		(mid 326.367526 -243.110667)
		(end 326.351646 -243.110512)
		(width 0.0889)
		(layer "In6.Cu")
		(net "M_E_CPU0_SA_DQ<28>")
	)
	(arc
		(start 328.832718 -243.212874)
		(mid 328.670529 -243.235609)
		(end 328.514202 -243.186712)
		(width 0.0889)
		(layer "In6.Cu")
		(net "M_E_CPU0_SA_DQ<28>")
	)
	(arc
		(start 328.514202 -243.186712)
		(mid 328.231246 -243.110535)
		(end 327.94829 -243.186712)
		(width 0.0889)
		(layer "In6.Cu")
		(net "M_E_CPU0_SA_DQ<28>")
	)
	(arc
		(start 326.633586 -243.186458)
		(mid 326.512911 -243.13415)
		(end 326.383396 -243.111274)
		(width 0.0889)
		(layer "In6.Cu")
		(net "M_E_CPU0_SA_DQ<28>")
	)
	(arc
		(start 327.007474 -243.186712)
		(mid 326.829824 -243.236972)
		(end 326.649842 -243.195856)
		(width 0.0889)
		(layer "In6.Cu")
		(net "M_E_CPU0_SA_DQ<28>")
	)
	(arc
		(start 327.57364 -243.186712)
		(mid 327.296573 -243.110441)
		(end 327.017888 -243.180616)
		(width 0.0889)
		(layer "In6.Cu")
		(net "M_E_CPU0_SA_DQ<28>")
	)
	(arc
		(start 327.939908 -243.191538)
		(mid 327.756146 -243.237154)
		(end 327.57364 -243.186712)
		(width 0.0889)
		(layer "In6.Cu")
		(net "M_E_CPU0_SA_DQ<28>")
	)
	(segment
		(start 331.047852 -241.510058)
		(end 330.581 -241.24412)
		(width 0.10668)
		(layer "F.Cu")
		(net "M_E_CPU0_SA_DQ<27>")
	)
	(segment
		(start 275.05279 -228.350318)
		(end 274.049998 -227.935028)
		(width 0.14478)
		(layer "In6.Cu")
		(net "M_E_CPU0_SA_DQ<27>")
	)
	(segment
		(start 285.954216 -227.500434)
		(end 283.09951 -227.500434)
		(width 0.14478)
		(layer "In6.Cu")
		(net "M_E_CPU0_SA_DQ<27>")
	)
	(segment
		(start 302.04664 -228.360224)
		(end 301.18685 -227.500434)
		(width 0.14478)
		(layer "In6.Cu")
		(net "M_E_CPU0_SA_DQ<27>")
	)
	(segment
		(start 319.244218 -239.81791)
		(end 314.69584 -235.269532)
		(width 0.14478)
		(layer "In6.Cu")
		(net "M_E_CPU0_SA_DQ<27>")
	)
	(segment
		(start 314.011818 -235.269532)
		(end 312.520584 -233.778298)
		(width 0.14478)
		(layer "In6.Cu")
		(net "M_E_CPU0_SA_DQ<27>")
	)
	(segment
		(start 327.008744 -240.92154)
		(end 326.99706 -240.914682)
		(width 0.0889)
		(layer "In6.Cu")
		(net "M_E_CPU0_SA_DQ<27>")
	)
	(segment
		(start 329.828144 -240.92154)
		(end 329.819762 -240.916714)
		(width 0.0889)
		(layer "In6.Cu")
		(net "M_E_CPU0_SA_DQ<27>")
	)
	(segment
		(start 330.581 -241.24412)
		(end 330.427076 -240.97869)
		(width 0.0889)
		(layer "In6.Cu")
		(net "M_E_CPU0_SA_DQ<27>")
	)
	(segment
		(start 293.64305 -227.500434)
		(end 290.709604 -227.500434)
		(width 0.14478)
		(layer "In6.Cu")
		(net "M_E_CPU0_SA_DQ<27>")
	)
	(segment
		(start 283.09951 -227.500434)
		(end 282.249626 -228.350318)
		(width 0.14478)
		(layer "In6.Cu")
		(net "M_E_CPU0_SA_DQ<27>")
	)
	(segment
		(start 324.122034 -239.81791)
		(end 323.885814 -239.81791)
		(width 0.0889)
		(layer "In6.Cu")
		(net "M_E_CPU0_SA_DQ<27>")
	)
	(segment
		(start 274.049998 -227.935028)
		(end 273.092164 -227.935028)
		(width 0.14478)
		(layer "In6.Cu")
		(net "M_E_CPU0_SA_DQ<27>")
	)
	(segment
		(start 297.426126 -228.350318)
		(end 294.492934 -228.350318)
		(width 0.14478)
		(layer "In6.Cu")
		(net "M_E_CPU0_SA_DQ<27>")
	)
	(segment
		(start 327.586086 -240.914682)
		(end 327.574402 -240.92154)
		(width 0.0889)
		(layer "In6.Cu")
		(net "M_E_CPU0_SA_DQ<27>")
	)
	(segment
		(start 307.181758 -227.510086)
		(end 305.810158 -227.510086)
		(width 0.14478)
		(layer "In6.Cu")
		(net "M_E_CPU0_SA_DQ<27>")
	)
	(segment
		(start 304.96002 -228.360224)
		(end 302.04664 -228.360224)
		(width 0.14478)
		(layer "In6.Cu")
		(net "M_E_CPU0_SA_DQ<27>")
	)
	(segment
		(start 324.591934 -240.28781)
		(end 324.122034 -239.81791)
		(width 0.0889)
		(layer "In6.Cu")
		(net "M_E_CPU0_SA_DQ<27>")
	)
	(segment
		(start 314.69584 -235.269532)
		(end 314.011818 -235.269532)
		(width 0.14478)
		(layer "In6.Cu")
		(net "M_E_CPU0_SA_DQ<27>")
	)
	(segment
		(start 324.955154 -240.28781)
		(end 324.591934 -240.28781)
		(width 0.0889)
		(layer "In6.Cu")
		(net "M_E_CPU0_SA_DQ<27>")
	)
	(segment
		(start 301.18685 -227.500434)
		(end 298.27601 -227.500434)
		(width 0.14478)
		(layer "In6.Cu")
		(net "M_E_CPU0_SA_DQ<27>")
	)
	(segment
		(start 294.492934 -228.350318)
		(end 293.64305 -227.500434)
		(width 0.14478)
		(layer "In6.Cu")
		(net "M_E_CPU0_SA_DQ<27>")
	)
	(segment
		(start 286.8041 -228.350318)
		(end 285.954216 -227.500434)
		(width 0.14478)
		(layer "In6.Cu")
		(net "M_E_CPU0_SA_DQ<27>")
	)
	(segment
		(start 289.85972 -228.350318)
		(end 286.8041 -228.350318)
		(width 0.14478)
		(layer "In6.Cu")
		(net "M_E_CPU0_SA_DQ<27>")
	)
	(segment
		(start 312.520584 -233.778298)
		(end 311.862978 -232.191306)
		(width 0.14478)
		(layer "In6.Cu")
		(net "M_E_CPU0_SA_DQ<27>")
	)
	(segment
		(start 323.885814 -239.81791)
		(end 319.244218 -239.81791)
		(width 0.14478)
		(layer "In6.Cu")
		(net "M_E_CPU0_SA_DQ<27>")
	)
	(segment
		(start 325.706994 -241.03965)
		(end 324.955154 -240.28781)
		(width 0.0889)
		(layer "In6.Cu")
		(net "M_E_CPU0_SA_DQ<27>")
	)
	(segment
		(start 290.709604 -227.500434)
		(end 289.85972 -228.350318)
		(width 0.14478)
		(layer "In6.Cu")
		(net "M_E_CPU0_SA_DQ<27>")
	)
	(segment
		(start 305.810158 -227.510086)
		(end 304.96002 -228.360224)
		(width 0.14478)
		(layer "In6.Cu")
		(net "M_E_CPU0_SA_DQ<27>")
	)
	(segment
		(start 327.574402 -240.92154)
		(end 327.563988 -240.927636)
		(width 0.0889)
		(layer "In6.Cu")
		(net "M_E_CPU0_SA_DQ<27>")
	)
	(segment
		(start 298.27601 -227.500434)
		(end 297.426126 -228.350318)
		(width 0.14478)
		(layer "In6.Cu")
		(net "M_E_CPU0_SA_DQ<27>")
	)
	(segment
		(start 326.195944 -241.03965)
		(end 325.706994 -241.03965)
		(width 0.0889)
		(layer "In6.Cu")
		(net "M_E_CPU0_SA_DQ<27>")
	)
	(segment
		(start 282.249626 -228.350318)
		(end 275.05279 -228.350318)
		(width 0.14478)
		(layer "In6.Cu")
		(net "M_E_CPU0_SA_DQ<27>")
	)
	(segment
		(start 311.862978 -232.191306)
		(end 307.181758 -227.510086)
		(width 0.14478)
		(layer "In6.Cu")
		(net "M_E_CPU0_SA_DQ<27>")
	)
	(segment
		(start 330.427076 -240.97869)
		(end 330.331064 -240.95329)
		(width 0.0889)
		(layer "In6.Cu")
		(net "M_E_CPU0_SA_DQ<27>")
	)
	(arc
		(start 329.819762 -240.916714)
		(mid 329.636254 -240.87122)
		(end 329.454002 -240.92154)
		(width 0.0889)
		(layer "In6.Cu")
		(net "M_E_CPU0_SA_DQ<27>")
	)
	(arc
		(start 330.331064 -240.95329)
		(mid 330.075856 -240.996767)
		(end 329.828144 -240.92154)
		(width 0.0889)
		(layer "In6.Cu")
		(net "M_E_CPU0_SA_DQ<27>")
	)
	(arc
		(start 327.94829 -240.92154)
		(mid 327.768085 -240.871223)
		(end 327.586086 -240.914682)
		(width 0.0889)
		(layer "In6.Cu")
		(net "M_E_CPU0_SA_DQ<27>")
	)
	(arc
		(start 328.88809 -240.92154)
		(mid 328.701146 -240.871285)
		(end 328.514202 -240.92154)
		(width 0.0889)
		(layer "In6.Cu")
		(net "M_E_CPU0_SA_DQ<27>")
	)
	(arc
		(start 329.454002 -240.92154)
		(mid 329.171046 -240.997717)
		(end 328.88809 -240.92154)
		(width 0.0889)
		(layer "In6.Cu")
		(net "M_E_CPU0_SA_DQ<27>")
	)
	(arc
		(start 328.514202 -240.92154)
		(mid 328.231246 -240.997717)
		(end 327.94829 -240.92154)
		(width 0.0889)
		(layer "In6.Cu")
		(net "M_E_CPU0_SA_DQ<27>")
	)
	(arc
		(start 327.563988 -240.927636)
		(mid 327.285556 -240.997734)
		(end 327.008744 -240.92154)
		(width 0.0889)
		(layer "In6.Cu")
		(net "M_E_CPU0_SA_DQ<27>")
	)
	(arc
		(start 326.634348 -240.92154)
		(mid 326.422965 -241.009626)
		(end 326.195944 -241.03965)
		(width 0.0889)
		(layer "In6.Cu")
		(net "M_E_CPU0_SA_DQ<27>")
	)
	(arc
		(start 326.99706 -240.914682)
		(mid 326.814805 -240.871029)
		(end 326.634348 -240.92154)
		(width 0.0889)
		(layer "In6.Cu")
		(net "M_E_CPU0_SA_DQ<27>")
	)
	(segment
		(start 329.637898 -240.700052)
		(end 329.171046 -240.434114)
		(width 0.10668)
		(layer "F.Cu")
		(net "M_E_CPU0_SA_DQ<26>")
	)
	(segment
		(start 324.309994 -238.90351)
		(end 323.875654 -238.90351)
		(width 0.0889)
		(layer "In6.Cu")
		(net "M_E_CPU0_SA_DQ<26>")
	)
	(segment
		(start 329.017122 -240.168684)
		(end 328.92111 -240.143284)
		(width 0.0889)
		(layer "In6.Cu")
		(net "M_E_CPU0_SA_DQ<26>")
	)
	(segment
		(start 274.668996 -225.92157)
		(end 274.438618 -225.92157)
		(width 0.14478)
		(layer "In6.Cu")
		(net "M_E_CPU0_SA_DQ<26>")
	)
	(segment
		(start 312.655458 -231.695498)
		(end 308.685438 -227.725478)
		(width 0.14478)
		(layer "In6.Cu")
		(net "M_E_CPU0_SA_DQ<26>")
	)
	(segment
		(start 307.702458 -225.810064)
		(end 307.047646 -225.810064)
		(width 0.14478)
		(layer "In6.Cu")
		(net "M_E_CPU0_SA_DQ<26>")
	)
	(segment
		(start 283.089858 -225.810064)
		(end 282.23972 -226.660202)
		(width 0.14478)
		(layer "In6.Cu")
		(net "M_E_CPU0_SA_DQ<26>")
	)
	(segment
		(start 327.488804 -240.11763)
		(end 327.47839 -240.111534)
		(width 0.0889)
		(layer "In6.Cu")
		(net "M_E_CPU0_SA_DQ<26>")
	)
	(segment
		(start 286.814006 -226.660202)
		(end 285.963868 -225.810064)
		(width 0.14478)
		(layer "In6.Cu")
		(net "M_E_CPU0_SA_DQ<26>")
	)
	(segment
		(start 285.963868 -225.810064)
		(end 283.089858 -225.810064)
		(width 0.14478)
		(layer "In6.Cu")
		(net "M_E_CPU0_SA_DQ<26>")
	)
	(segment
		(start 319.623186 -238.90351)
		(end 312.825638 -232.105962)
		(width 0.14478)
		(layer "In6.Cu")
		(net "M_E_CPU0_SA_DQ<26>")
	)
	(segment
		(start 302.04664 -226.660202)
		(end 301.196502 -225.810064)
		(width 0.14478)
		(layer "In6.Cu")
		(net "M_E_CPU0_SA_DQ<26>")
	)
	(segment
		(start 297.41622 -226.660202)
		(end 294.50284 -226.660202)
		(width 0.14478)
		(layer "In6.Cu")
		(net "M_E_CPU0_SA_DQ<26>")
	)
	(segment
		(start 290.699952 -225.810064)
		(end 289.849814 -226.660202)
		(width 0.14478)
		(layer "In6.Cu")
		(net "M_E_CPU0_SA_DQ<26>")
	)
	(segment
		(start 324.447154 -239.04067)
		(end 324.309994 -238.90351)
		(width 0.0889)
		(layer "In6.Cu")
		(net "M_E_CPU0_SA_DQ<26>")
	)
	(segment
		(start 274.27555 -226.084638)
		(end 274.27555 -226.497134)
		(width 0.14478)
		(layer "In6.Cu")
		(net "M_E_CPU0_SA_DQ<26>")
	)
	(segment
		(start 308.685438 -226.793044)
		(end 307.702458 -225.810064)
		(width 0.14478)
		(layer "In6.Cu")
		(net "M_E_CPU0_SA_DQ<26>")
	)
	(segment
		(start 327.104502 -240.111534)
		(end 327.094088 -240.11763)
		(width 0.0889)
		(layer "In6.Cu")
		(net "M_E_CPU0_SA_DQ<26>")
	)
	(segment
		(start 301.196502 -225.810064)
		(end 298.266358 -225.810064)
		(width 0.14478)
		(layer "In6.Cu")
		(net "M_E_CPU0_SA_DQ<26>")
	)
	(segment
		(start 273.51736 -226.660202)
		(end 273.092164 -226.235006)
		(width 0.14478)
		(layer "In6.Cu")
		(net "M_E_CPU0_SA_DQ<26>")
	)
	(segment
		(start 274.832064 -226.497134)
		(end 274.832064 -226.084638)
		(width 0.14478)
		(layer "In6.Cu")
		(net "M_E_CPU0_SA_DQ<26>")
	)
	(segment
		(start 293.652702 -225.810064)
		(end 290.699952 -225.810064)
		(width 0.14478)
		(layer "In6.Cu")
		(net "M_E_CPU0_SA_DQ<26>")
	)
	(segment
		(start 274.438618 -225.92157)
		(end 274.27555 -226.084638)
		(width 0.14478)
		(layer "In6.Cu")
		(net "M_E_CPU0_SA_DQ<26>")
	)
	(segment
		(start 306.302918 -226.554792)
		(end 305.06543 -226.554792)
		(width 0.14478)
		(layer "In6.Cu")
		(net "M_E_CPU0_SA_DQ<26>")
	)
	(segment
		(start 328.41819 -240.111534)
		(end 328.409808 -240.106708)
		(width 0.0889)
		(layer "In6.Cu")
		(net "M_E_CPU0_SA_DQ<26>")
	)
	(segment
		(start 312.825638 -232.105962)
		(end 312.655458 -231.695498)
		(width 0.14478)
		(layer "In6.Cu")
		(net "M_E_CPU0_SA_DQ<26>")
	)
	(segment
		(start 326.351138 -240.060988)
		(end 325.924672 -240.060988)
		(width 0.0889)
		(layer "In6.Cu")
		(net "M_E_CPU0_SA_DQ<26>")
	)
	(segment
		(start 323.875654 -238.90351)
		(end 319.623186 -238.90351)
		(width 0.14478)
		(layer "In6.Cu")
		(net "M_E_CPU0_SA_DQ<26>")
	)
	(segment
		(start 274.27555 -226.497134)
		(end 274.112482 -226.660202)
		(width 0.14478)
		(layer "In6.Cu")
		(net "M_E_CPU0_SA_DQ<26>")
	)
	(segment
		(start 307.047646 -225.810064)
		(end 306.302918 -226.554792)
		(width 0.14478)
		(layer "In6.Cu")
		(net "M_E_CPU0_SA_DQ<26>")
	)
	(segment
		(start 329.171046 -240.434114)
		(end 329.017122 -240.168684)
		(width 0.0889)
		(layer "In6.Cu")
		(net "M_E_CPU0_SA_DQ<26>")
	)
	(segment
		(start 325.924672 -240.060988)
		(end 324.904354 -239.04067)
		(width 0.0889)
		(layer "In6.Cu")
		(net "M_E_CPU0_SA_DQ<26>")
	)
	(segment
		(start 274.995132 -226.660202)
		(end 274.832064 -226.497134)
		(width 0.14478)
		(layer "In6.Cu")
		(net "M_E_CPU0_SA_DQ<26>")
	)
	(segment
		(start 298.266358 -225.810064)
		(end 297.41622 -226.660202)
		(width 0.14478)
		(layer "In6.Cu")
		(net "M_E_CPU0_SA_DQ<26>")
	)
	(segment
		(start 274.112482 -226.660202)
		(end 273.51736 -226.660202)
		(width 0.14478)
		(layer "In6.Cu")
		(net "M_E_CPU0_SA_DQ<26>")
	)
	(segment
		(start 294.50284 -226.660202)
		(end 293.652702 -225.810064)
		(width 0.14478)
		(layer "In6.Cu")
		(net "M_E_CPU0_SA_DQ<26>")
	)
	(segment
		(start 282.23972 -226.660202)
		(end 274.995132 -226.660202)
		(width 0.14478)
		(layer "In6.Cu")
		(net "M_E_CPU0_SA_DQ<26>")
	)
	(segment
		(start 305.06543 -226.554792)
		(end 304.96002 -226.660202)
		(width 0.14478)
		(layer "In6.Cu")
		(net "M_E_CPU0_SA_DQ<26>")
	)
	(segment
		(start 324.904354 -239.04067)
		(end 324.447154 -239.04067)
		(width 0.0889)
		(layer "In6.Cu")
		(net "M_E_CPU0_SA_DQ<26>")
	)
	(segment
		(start 289.849814 -226.660202)
		(end 286.814006 -226.660202)
		(width 0.14478)
		(layer "In6.Cu")
		(net "M_E_CPU0_SA_DQ<26>")
	)
	(segment
		(start 274.832064 -226.084638)
		(end 274.668996 -225.92157)
		(width 0.14478)
		(layer "In6.Cu")
		(net "M_E_CPU0_SA_DQ<26>")
	)
	(segment
		(start 304.96002 -226.660202)
		(end 302.04664 -226.660202)
		(width 0.14478)
		(layer "In6.Cu")
		(net "M_E_CPU0_SA_DQ<26>")
	)
	(segment
		(start 308.685438 -227.725478)
		(end 308.685438 -226.793044)
		(width 0.14478)
		(layer "In6.Cu")
		(net "M_E_CPU0_SA_DQ<26>")
	)
	(arc
		(start 327.094088 -240.11763)
		(mid 326.815402 -240.18785)
		(end 326.538336 -240.111534)
		(width 0.0889)
		(layer "In6.Cu")
		(net "M_E_CPU0_SA_DQ<26>")
	)
	(arc
		(start 328.044048 -240.111534)
		(mid 327.767235 -240.187677)
		(end 327.488804 -240.11763)
		(width 0.0889)
		(layer "In6.Cu")
		(net "M_E_CPU0_SA_DQ<26>")
	)
	(arc
		(start 326.538336 -240.111534)
		(mid 326.448076 -240.073906)
		(end 326.351138 -240.060988)
		(width 0.0889)
		(layer "In6.Cu")
		(net "M_E_CPU0_SA_DQ<26>")
	)
	(arc
		(start 328.92111 -240.143284)
		(mid 328.665902 -240.186761)
		(end 328.41819 -240.111534)
		(width 0.0889)
		(layer "In6.Cu")
		(net "M_E_CPU0_SA_DQ<26>")
	)
	(arc
		(start 327.47839 -240.111534)
		(mid 327.291446 -240.061279)
		(end 327.104502 -240.111534)
		(width 0.0889)
		(layer "In6.Cu")
		(net "M_E_CPU0_SA_DQ<26>")
	)
	(arc
		(start 328.409808 -240.106708)
		(mid 328.2263 -240.061214)
		(end 328.044048 -240.111534)
		(width 0.0889)
		(layer "In6.Cu")
		(net "M_E_CPU0_SA_DQ<26>")
	)
	(segment
		(start 330.577952 -240.700052)
		(end 330.1111 -240.434114)
		(width 0.10668)
		(layer "F.Cu")
		(net "M_E_CPU0_SA_DQ<25>")
	)
	(segment
		(start 324.327774 -239.36325)
		(end 323.890894 -239.36325)
		(width 0.0889)
		(layer "In6.Cu")
		(net "M_E_CPU0_SA_DQ<25>")
	)
	(segment
		(start 288.635186 -227.510086)
		(end 286.804862 -227.510086)
		(width 0.14478)
		(layer "In6.Cu")
		(net "M_E_CPU0_SA_DQ<25>")
	)
	(segment
		(start 294.480742 -227.510086)
		(end 293.630858 -226.660202)
		(width 0.14478)
		(layer "In6.Cu")
		(net "M_E_CPU0_SA_DQ<25>")
	)
	(segment
		(start 296.842942 -227.89261)
		(end 296.679874 -227.729542)
		(width 0.14478)
		(layer "In6.Cu")
		(net "M_E_CPU0_SA_DQ<25>")
	)
	(segment
		(start 290.006278 -227.510086)
		(end 289.517836 -227.510086)
		(width 0.14478)
		(layer "In6.Cu")
		(net "M_E_CPU0_SA_DQ<25>")
	)
	(segment
		(start 296.679874 -227.673154)
		(end 296.516806 -227.510086)
		(width 0.14478)
		(layer "In6.Cu")
		(net "M_E_CPU0_SA_DQ<25>")
	)
	(segment
		(start 289.354768 -227.734622)
		(end 289.1917 -227.89769)
		(width 0.14478)
		(layer "In6.Cu")
		(net "M_E_CPU0_SA_DQ<25>")
	)
	(segment
		(start 313.968638 -233.899202)
		(end 313.69254 -233.623104)
		(width 0.14478)
		(layer "In6.Cu")
		(net "M_E_CPU0_SA_DQ<25>")
	)
	(segment
		(start 279.489916 -227.90023)
		(end 279.326848 -227.737162)
		(width 0.14478)
		(layer "In6.Cu")
		(net "M_E_CPU0_SA_DQ<25>")
	)
	(segment
		(start 313.69254 -233.623104)
		(end 313.138566 -233.62412)
		(width 0.14478)
		(layer "In6.Cu")
		(net "M_E_CPU0_SA_DQ<25>")
	)
	(segment
		(start 290.856162 -226.660202)
		(end 290.006278 -227.510086)
		(width 0.14478)
		(layer "In6.Cu")
		(net "M_E_CPU0_SA_DQ<25>")
	)
	(segment
		(start 312.24347 -231.93375)
		(end 308.08549 -227.77577)
		(width 0.14478)
		(layer "In6.Cu")
		(net "M_E_CPU0_SA_DQ<25>")
	)
	(segment
		(start 297.399456 -227.510086)
		(end 297.236388 -227.673154)
		(width 0.14478)
		(layer "In6.Cu")
		(net "M_E_CPU0_SA_DQ<25>")
	)
	(segment
		(start 303.952402 -227.734622)
		(end 303.952402 -227.673154)
		(width 0.14478)
		(layer "In6.Cu")
		(net "M_E_CPU0_SA_DQ<25>")
	)
	(segment
		(start 286.804862 -227.510086)
		(end 285.954978 -226.660202)
		(width 0.14478)
		(layer "In6.Cu")
		(net "M_E_CPU0_SA_DQ<25>")
	)
	(segment
		(start 326.038972 -240.688368)
		(end 325.641208 -240.290604)
		(width 0.0889)
		(layer "In6.Cu")
		(net "M_E_CPU0_SA_DQ<25>")
	)
	(segment
		(start 327.104756 -240.756694)
		(end 327.094342 -240.750598)
		(width 0.0889)
		(layer "In6.Cu")
		(net "M_E_CPU0_SA_DQ<25>")
	)
	(segment
		(start 283.294582 -226.660202)
		(end 282.444698 -227.510086)
		(width 0.14478)
		(layer "In6.Cu")
		(net "M_E_CPU0_SA_DQ<25>")
	)
	(segment
		(start 297.236388 -227.673154)
		(end 297.236388 -227.729542)
		(width 0.14478)
		(layer "In6.Cu")
		(net "M_E_CPU0_SA_DQ<25>")
	)
	(segment
		(start 313.138566 -233.62412)
		(end 312.813446 -233.299)
		(width 0.14478)
		(layer "In6.Cu")
		(net "M_E_CPU0_SA_DQ<25>")
	)
	(segment
		(start 307.820822 -227.038408)
		(end 307.68671 -227.17252)
		(width 0.14478)
		(layer "In6.Cu")
		(net "M_E_CPU0_SA_DQ<25>")
	)
	(segment
		(start 308.08549 -227.571046)
		(end 308.219602 -227.436934)
		(width 0.14478)
		(layer "In6.Cu")
		(net "M_E_CPU0_SA_DQ<25>")
	)
	(segment
		(start 328.41819 -240.756694)
		(end 328.409808 -240.76152)
		(width 0.0889)
		(layer "In6.Cu")
		(net "M_E_CPU0_SA_DQ<25>")
	)
	(segment
		(start 293.630858 -226.660202)
		(end 290.856162 -226.660202)
		(width 0.14478)
		(layer "In6.Cu")
		(net "M_E_CPU0_SA_DQ<25>")
	)
	(segment
		(start 314.830206 -234.76077)
		(end 314.276486 -234.761532)
		(width 0.14478)
		(layer "In6.Cu")
		(net "M_E_CPU0_SA_DQ<25>")
	)
	(segment
		(start 279.326848 -227.737162)
		(end 279.326848 -227.28301)
		(width 0.14478)
		(layer "In6.Cu")
		(net "M_E_CPU0_SA_DQ<25>")
	)
	(segment
		(start 303.558956 -227.510086)
		(end 303.395888 -227.673154)
		(width 0.14478)
		(layer "In6.Cu")
		(net "M_E_CPU0_SA_DQ<25>")
	)
	(segment
		(start 278.376888 -227.90023)
		(end 278.21382 -227.737162)
		(width 0.14478)
		(layer "In6.Cu")
		(net "M_E_CPU0_SA_DQ<25>")
	)
	(segment
		(start 288.961322 -227.89769)
		(end 288.798254 -227.734622)
		(width 0.14478)
		(layer "In6.Cu")
		(net "M_E_CPU0_SA_DQ<25>")
	)
	(segment
		(start 278.050752 -227.510086)
		(end 277.617174 -227.510086)
		(width 0.14478)
		(layer "In6.Cu")
		(net "M_E_CPU0_SA_DQ<25>")
	)
	(segment
		(start 282.444698 -227.510086)
		(end 280.04643 -227.510086)
		(width 0.14478)
		(layer "In6.Cu")
		(net "M_E_CPU0_SA_DQ<25>")
	)
	(segment
		(start 307.481986 -227.172266)
		(end 307.314092 -227.004372)
		(width 0.14478)
		(layer "In6.Cu")
		(net "M_E_CPU0_SA_DQ<25>")
	)
	(segment
		(start 279.883362 -227.737162)
		(end 279.720294 -227.90023)
		(width 0.14478)
		(layer "In6.Cu")
		(net "M_E_CPU0_SA_DQ<25>")
	)
	(segment
		(start 303.002442 -227.89769)
		(end 302.839374 -227.734622)
		(width 0.14478)
		(layer "In6.Cu")
		(net "M_E_CPU0_SA_DQ<25>")
	)
	(segment
		(start 323.890894 -239.36325)
		(end 319.432686 -239.36325)
		(width 0.14478)
		(layer "In6.Cu")
		(net "M_E_CPU0_SA_DQ<25>")
	)
	(segment
		(start 330.265024 -240.699544)
		(end 330.242672 -240.782856)
		(width 0.0889)
		(layer "In6.Cu")
		(net "M_E_CPU0_SA_DQ<25>")
	)
	(segment
		(start 325.641208 -240.290604)
		(end 325.641208 -240.201704)
		(width 0.0889)
		(layer "In6.Cu")
		(net "M_E_CPU0_SA_DQ<25>")
	)
	(segment
		(start 288.798254 -227.734622)
		(end 288.798254 -227.673154)
		(width 0.14478)
		(layer "In6.Cu")
		(net "M_E_CPU0_SA_DQ<25>")
	)
	(segment
		(start 289.354768 -227.673154)
		(end 289.354768 -227.734622)
		(width 0.14478)
		(layer "In6.Cu")
		(net "M_E_CPU0_SA_DQ<25>")
	)
	(segment
		(start 303.789334 -227.510086)
		(end 303.558956 -227.510086)
		(width 0.14478)
		(layer "In6.Cu")
		(net "M_E_CPU0_SA_DQ<25>")
	)
	(segment
		(start 303.23282 -227.89769)
		(end 303.002442 -227.89769)
		(width 0.14478)
		(layer "In6.Cu")
		(net "M_E_CPU0_SA_DQ<25>")
	)
	(segment
		(start 312.813446 -232.74401)
		(end 312.413142 -232.343706)
		(width 0.14478)
		(layer "In6.Cu")
		(net "M_E_CPU0_SA_DQ<25>")
	)
	(segment
		(start 324.899274 -239.45977)
		(end 324.424294 -239.45977)
		(width 0.0889)
		(layer "In6.Cu")
		(net "M_E_CPU0_SA_DQ<25>")
	)
	(segment
		(start 305.670712 -227.004372)
		(end 305.164998 -227.510086)
		(width 0.14478)
		(layer "In6.Cu")
		(net "M_E_CPU0_SA_DQ<25>")
	)
	(segment
		(start 328.992484 -240.76152)
		(end 328.984102 -240.756694)
		(width 0.0889)
		(layer "In6.Cu")
		(net "M_E_CPU0_SA_DQ<25>")
	)
	(segment
		(start 285.954978 -226.660202)
		(end 283.294582 -226.660202)
		(width 0.14478)
		(layer "In6.Cu")
		(net "M_E_CPU0_SA_DQ<25>")
	)
	(segment
		(start 278.770334 -227.737162)
		(end 278.607266 -227.90023)
		(width 0.14478)
		(layer "In6.Cu")
		(net "M_E_CPU0_SA_DQ<25>")
	)
	(segment
		(start 279.883362 -227.673154)
		(end 279.883362 -227.737162)
		(width 0.14478)
		(layer "In6.Cu")
		(net "M_E_CPU0_SA_DQ<25>")
	)
	(segment
		(start 327.488804 -240.750598)
		(end 327.47839 -240.756694)
		(width 0.0889)
		(layer "In6.Cu")
		(net "M_E_CPU0_SA_DQ<25>")
	)
	(segment
		(start 297.621198 -227.510086)
		(end 297.399456 -227.510086)
		(width 0.14478)
		(layer "In6.Cu")
		(net "M_E_CPU0_SA_DQ<25>")
	)
	(segment
		(start 302.839374 -227.734622)
		(end 302.839374 -227.673154)
		(width 0.14478)
		(layer "In6.Cu")
		(net "M_E_CPU0_SA_DQ<25>")
	)
	(segment
		(start 301.174658 -226.660202)
		(end 298.471082 -226.660202)
		(width 0.14478)
		(layer "In6.Cu")
		(net "M_E_CPU0_SA_DQ<25>")
	)
	(segment
		(start 305.164998 -227.510086)
		(end 304.671984 -227.510086)
		(width 0.14478)
		(layer "In6.Cu")
		(net "M_E_CPU0_SA_DQ<25>")
	)
	(segment
		(start 279.16378 -227.119942)
		(end 278.933402 -227.119942)
		(width 0.14478)
		(layer "In6.Cu")
		(net "M_E_CPU0_SA_DQ<25>")
	)
	(segment
		(start 278.21382 -227.737162)
		(end 278.21382 -227.673154)
		(width 0.14478)
		(layer "In6.Cu")
		(net "M_E_CPU0_SA_DQ<25>")
	)
	(segment
		(start 307.314092 -227.004372)
		(end 305.670712 -227.004372)
		(width 0.14478)
		(layer "In6.Cu")
		(net "M_E_CPU0_SA_DQ<25>")
	)
	(segment
		(start 296.516806 -227.510086)
		(end 294.480742 -227.510086)
		(width 0.14478)
		(layer "In6.Cu")
		(net "M_E_CPU0_SA_DQ<25>")
	)
	(segment
		(start 312.413142 -232.343706)
		(end 312.24347 -231.93375)
		(width 0.14478)
		(layer "In6.Cu")
		(net "M_E_CPU0_SA_DQ<25>")
	)
	(segment
		(start 278.21382 -227.673154)
		(end 278.050752 -227.510086)
		(width 0.14478)
		(layer "In6.Cu")
		(net "M_E_CPU0_SA_DQ<25>")
	)
	(segment
		(start 324.424294 -239.45977)
		(end 324.327774 -239.36325)
		(width 0.0889)
		(layer "In6.Cu")
		(net "M_E_CPU0_SA_DQ<25>")
	)
	(segment
		(start 279.326848 -227.28301)
		(end 279.16378 -227.119942)
		(width 0.14478)
		(layer "In6.Cu")
		(net "M_E_CPU0_SA_DQ<25>")
	)
	(segment
		(start 302.839374 -227.673154)
		(end 302.676306 -227.510086)
		(width 0.14478)
		(layer "In6.Cu")
		(net "M_E_CPU0_SA_DQ<25>")
	)
	(segment
		(start 313.968638 -234.453684)
		(end 313.968638 -233.899202)
		(width 0.14478)
		(layer "In6.Cu")
		(net "M_E_CPU0_SA_DQ<25>")
	)
	(segment
		(start 308.219602 -227.436934)
		(end 308.219856 -227.232718)
		(width 0.14478)
		(layer "In6.Cu")
		(net "M_E_CPU0_SA_DQ<25>")
	)
	(segment
		(start 308.025546 -227.038408)
		(end 307.820822 -227.038408)
		(width 0.14478)
		(layer "In6.Cu")
		(net "M_E_CPU0_SA_DQ<25>")
	)
	(segment
		(start 280.04643 -227.510086)
		(end 279.883362 -227.673154)
		(width 0.14478)
		(layer "In6.Cu")
		(net "M_E_CPU0_SA_DQ<25>")
	)
	(segment
		(start 303.952402 -227.673154)
		(end 303.789334 -227.510086)
		(width 0.14478)
		(layer "In6.Cu")
		(net "M_E_CPU0_SA_DQ<25>")
	)
	(segment
		(start 278.770334 -227.28301)
		(end 278.770334 -227.737162)
		(width 0.14478)
		(layer "In6.Cu")
		(net "M_E_CPU0_SA_DQ<25>")
	)
	(segment
		(start 289.1917 -227.89769)
		(end 288.961322 -227.89769)
		(width 0.14478)
		(layer "In6.Cu")
		(net "M_E_CPU0_SA_DQ<25>")
	)
	(segment
		(start 277.617174 -227.510086)
		(end 277.192232 -227.085144)
		(width 0.14478)
		(layer "In6.Cu")
		(net "M_E_CPU0_SA_DQ<25>")
	)
	(segment
		(start 325.641208 -240.201704)
		(end 324.899274 -239.45977)
		(width 0.0889)
		(layer "In6.Cu")
		(net "M_E_CPU0_SA_DQ<25>")
	)
	(segment
		(start 308.219856 -227.232718)
		(end 308.025546 -227.038408)
		(width 0.14478)
		(layer "In6.Cu")
		(net "M_E_CPU0_SA_DQ<25>")
	)
	(segment
		(start 303.395888 -227.734622)
		(end 303.23282 -227.89769)
		(width 0.14478)
		(layer "In6.Cu")
		(net "M_E_CPU0_SA_DQ<25>")
	)
	(segment
		(start 304.508916 -227.673154)
		(end 304.508916 -227.734622)
		(width 0.14478)
		(layer "In6.Cu")
		(net "M_E_CPU0_SA_DQ<25>")
	)
	(segment
		(start 288.798254 -227.673154)
		(end 288.635186 -227.510086)
		(width 0.14478)
		(layer "In6.Cu")
		(net "M_E_CPU0_SA_DQ<25>")
	)
	(segment
		(start 327.47839 -240.756694)
		(end 327.470008 -240.76152)
		(width 0.0889)
		(layer "In6.Cu")
		(net "M_E_CPU0_SA_DQ<25>")
	)
	(segment
		(start 302.676306 -227.510086)
		(end 302.024542 -227.510086)
		(width 0.14478)
		(layer "In6.Cu")
		(net "M_E_CPU0_SA_DQ<25>")
	)
	(segment
		(start 326.044814 -240.688368)
		(end 326.038972 -240.688368)
		(width 0.0889)
		(layer "In6.Cu")
		(net "M_E_CPU0_SA_DQ<25>")
	)
	(segment
		(start 319.432686 -239.36325)
		(end 314.830206 -234.76077)
		(width 0.14478)
		(layer "In6.Cu")
		(net "M_E_CPU0_SA_DQ<25>")
	)
	(segment
		(start 278.607266 -227.90023)
		(end 278.376888 -227.90023)
		(width 0.14478)
		(layer "In6.Cu")
		(net "M_E_CPU0_SA_DQ<25>")
	)
	(segment
		(start 302.024542 -227.510086)
		(end 301.174658 -226.660202)
		(width 0.14478)
		(layer "In6.Cu")
		(net "M_E_CPU0_SA_DQ<25>")
	)
	(segment
		(start 326.182736 -240.766854)
		(end 326.044814 -240.688368)
		(width 0.0889)
		(layer "In6.Cu")
		(net "M_E_CPU0_SA_DQ<25>")
	)
	(segment
		(start 296.679874 -227.729542)
		(end 296.679874 -227.673154)
		(width 0.14478)
		(layer "In6.Cu")
		(net "M_E_CPU0_SA_DQ<25>")
	)
	(segment
		(start 304.671984 -227.510086)
		(end 304.508916 -227.673154)
		(width 0.14478)
		(layer "In6.Cu")
		(net "M_E_CPU0_SA_DQ<25>")
	)
	(segment
		(start 330.1111 -240.434114)
		(end 330.265024 -240.699544)
		(width 0.0889)
		(layer "In6.Cu")
		(net "M_E_CPU0_SA_DQ<25>")
	)
	(segment
		(start 279.720294 -227.90023)
		(end 279.489916 -227.90023)
		(width 0.14478)
		(layer "In6.Cu")
		(net "M_E_CPU0_SA_DQ<25>")
	)
	(segment
		(start 304.345848 -227.89769)
		(end 304.11547 -227.89769)
		(width 0.14478)
		(layer "In6.Cu")
		(net "M_E_CPU0_SA_DQ<25>")
	)
	(segment
		(start 289.517836 -227.510086)
		(end 289.354768 -227.673154)
		(width 0.14478)
		(layer "In6.Cu")
		(net "M_E_CPU0_SA_DQ<25>")
	)
	(segment
		(start 278.933402 -227.119942)
		(end 278.770334 -227.28301)
		(width 0.14478)
		(layer "In6.Cu")
		(net "M_E_CPU0_SA_DQ<25>")
	)
	(segment
		(start 312.813446 -233.299)
		(end 312.813446 -232.74401)
		(width 0.14478)
		(layer "In6.Cu")
		(net "M_E_CPU0_SA_DQ<25>")
	)
	(segment
		(start 314.276486 -234.761532)
		(end 313.968638 -234.453684)
		(width 0.14478)
		(layer "In6.Cu")
		(net "M_E_CPU0_SA_DQ<25>")
	)
	(segment
		(start 308.08549 -227.77577)
		(end 308.08549 -227.571046)
		(width 0.14478)
		(layer "In6.Cu")
		(net "M_E_CPU0_SA_DQ<25>")
	)
	(segment
		(start 307.68671 -227.17252)
		(end 307.481986 -227.172266)
		(width 0.14478)
		(layer "In6.Cu")
		(net "M_E_CPU0_SA_DQ<25>")
	)
	(segment
		(start 297.07332 -227.89261)
		(end 296.842942 -227.89261)
		(width 0.14478)
		(layer "In6.Cu")
		(net "M_E_CPU0_SA_DQ<25>")
	)
	(segment
		(start 297.236388 -227.729542)
		(end 297.07332 -227.89261)
		(width 0.14478)
		(layer "In6.Cu")
		(net "M_E_CPU0_SA_DQ<25>")
	)
	(segment
		(start 304.11547 -227.89769)
		(end 303.952402 -227.734622)
		(width 0.14478)
		(layer "In6.Cu")
		(net "M_E_CPU0_SA_DQ<25>")
	)
	(segment
		(start 298.471082 -226.660202)
		(end 297.621198 -227.510086)
		(width 0.14478)
		(layer "In6.Cu")
		(net "M_E_CPU0_SA_DQ<25>")
	)
	(segment
		(start 304.508916 -227.734622)
		(end 304.345848 -227.89769)
		(width 0.14478)
		(layer "In6.Cu")
		(net "M_E_CPU0_SA_DQ<25>")
	)
	(segment
		(start 303.395888 -227.673154)
		(end 303.395888 -227.734622)
		(width 0.14478)
		(layer "In6.Cu")
		(net "M_E_CPU0_SA_DQ<25>")
	)
	(arc
		(start 327.470008 -240.76152)
		(mid 327.286754 -240.806893)
		(end 327.104756 -240.756694)
		(width 0.0889)
		(layer "In6.Cu")
		(net "M_E_CPU0_SA_DQ<25>")
	)
	(arc
		(start 329.358244 -240.756694)
		(mid 329.175993 -240.807044)
		(end 328.992484 -240.76152)
		(width 0.0889)
		(layer "In6.Cu")
		(net "M_E_CPU0_SA_DQ<25>")
	)
	(arc
		(start 330.242672 -240.782856)
		(mid 330.080483 -240.805591)
		(end 329.924156 -240.756694)
		(width 0.0889)
		(layer "In6.Cu")
		(net "M_E_CPU0_SA_DQ<25>")
	)
	(arc
		(start 329.924156 -240.756694)
		(mid 329.6412 -240.680517)
		(end 329.358244 -240.756694)
		(width 0.0889)
		(layer "In6.Cu")
		(net "M_E_CPU0_SA_DQ<25>")
	)
	(arc
		(start 328.044048 -240.756694)
		(mid 327.767235 -240.680551)
		(end 327.488804 -240.750598)
		(width 0.0889)
		(layer "In6.Cu")
		(net "M_E_CPU0_SA_DQ<25>")
	)
	(arc
		(start 327.094342 -240.750598)
		(mid 326.815656 -240.680378)
		(end 326.53859 -240.756694)
		(width 0.0889)
		(layer "In6.Cu")
		(net "M_E_CPU0_SA_DQ<25>")
	)
	(arc
		(start 328.984102 -240.756694)
		(mid 328.701146 -240.680517)
		(end 328.41819 -240.756694)
		(width 0.0889)
		(layer "In6.Cu")
		(net "M_E_CPU0_SA_DQ<25>")
	)
	(arc
		(start 328.409808 -240.76152)
		(mid 328.2263 -240.807014)
		(end 328.044048 -240.756694)
		(width 0.0889)
		(layer "In6.Cu")
		(net "M_E_CPU0_SA_DQ<25>")
	)
	(arc
		(start 326.53859 -240.756694)
		(mid 326.361962 -240.806927)
		(end 326.182736 -240.766854)
		(width 0.0889)
		(layer "In6.Cu")
		(net "M_E_CPU0_SA_DQ<25>")
	)
	(segment
		(start 329.167998 -239.890046)
		(end 328.701146 -239.624108)
		(width 0.10668)
		(layer "F.Cu")
		(net "M_E_CPU0_SA_DQ<24>")
	)
	(segment
		(start 293.630858 -224.96018)
		(end 290.856162 -224.96018)
		(width 0.14478)
		(layer "In6.Cu")
		(net "M_E_CPU0_SA_DQ<24>")
	)
	(segment
		(start 306.467256 -224.96018)
		(end 306.322476 -225.10496)
		(width 0.14478)
		(layer "In6.Cu")
		(net "M_E_CPU0_SA_DQ<24>")
	)
	(segment
		(start 313.201558 -231.445054)
		(end 309.970678 -228.214174)
		(width 0.14478)
		(layer "In6.Cu")
		(net "M_E_CPU0_SA_DQ<24>")
	)
	(segment
		(start 286.804862 -225.810064)
		(end 285.954978 -224.96018)
		(width 0.14478)
		(layer "In6.Cu")
		(net "M_E_CPU0_SA_DQ<24>")
	)
	(segment
		(start 296.532554 -226.035362)
		(end 296.532554 -225.973132)
		(width 0.14478)
		(layer "In6.Cu")
		(net "M_E_CPU0_SA_DQ<24>")
	)
	(segment
		(start 297.252136 -225.810064)
		(end 297.089068 -225.973132)
		(width 0.14478)
		(layer "In6.Cu")
		(net "M_E_CPU0_SA_DQ<24>")
	)
	(segment
		(start 303.56683 -225.810064)
		(end 303.336452 -225.810064)
		(width 0.14478)
		(layer "In6.Cu")
		(net "M_E_CPU0_SA_DQ<24>")
	)
	(segment
		(start 296.695622 -226.19843)
		(end 296.532554 -226.035362)
		(width 0.14478)
		(layer "In6.Cu")
		(net "M_E_CPU0_SA_DQ<24>")
	)
	(segment
		(start 305.768756 -225.686112)
		(end 305.768756 -225.10496)
		(width 0.14478)
		(layer "In6.Cu")
		(net "M_E_CPU0_SA_DQ<24>")
	)
	(segment
		(start 309.993538 -227.3935)
		(end 309.788814 -227.3935)
		(width 0.14478)
		(layer "In6.Cu")
		(net "M_E_CPU0_SA_DQ<24>")
	)
	(segment
		(start 278.935434 -225.953574)
		(end 278.792178 -226.09683)
		(width 0.14478)
		(layer "In6.Cu")
		(net "M_E_CPU0_SA_DQ<24>")
	)
	(segment
		(start 290.006278 -225.810064)
		(end 289.477958 -225.810064)
		(width 0.14478)
		(layer "In6.Cu")
		(net "M_E_CPU0_SA_DQ<24>")
	)
	(segment
		(start 328.85507 -239.889538)
		(end 328.832718 -239.97285)
		(width 0.0889)
		(layer "In6.Cu")
		(net "M_E_CPU0_SA_DQ<24>")
	)
	(segment
		(start 281.824176 -226.035362)
		(end 281.661108 -226.19843)
		(width 0.14478)
		(layer "In6.Cu")
		(net "M_E_CPU0_SA_DQ<24>")
	)
	(segment
		(start 277.617174 -225.810064)
		(end 277.192232 -225.385122)
		(width 0.14478)
		(layer "In6.Cu")
		(net "M_E_CPU0_SA_DQ<24>")
	)
	(segment
		(start 278.792178 -226.09683)
		(end 278.522176 -226.09683)
		(width 0.14478)
		(layer "In6.Cu")
		(net "M_E_CPU0_SA_DQ<24>")
	)
	(segment
		(start 304.123344 -226.19843)
		(end 303.892966 -226.19843)
		(width 0.14478)
		(layer "In6.Cu")
		(net "M_E_CPU0_SA_DQ<24>")
	)
	(segment
		(start 309.571644 -227.61067)
		(end 309.367428 -227.610924)
		(width 0.14478)
		(layer "In6.Cu")
		(net "M_E_CPU0_SA_DQ<24>")
	)
	(segment
		(start 303.173384 -226.035362)
		(end 303.010316 -226.19843)
		(width 0.14478)
		(layer "In6.Cu")
		(net "M_E_CPU0_SA_DQ<24>")
	)
	(segment
		(start 282.444698 -225.810064)
		(end 281.987244 -225.810064)
		(width 0.14478)
		(layer "In6.Cu")
		(net "M_E_CPU0_SA_DQ<24>")
	)
	(segment
		(start 301.174658 -224.96018)
		(end 298.471082 -224.96018)
		(width 0.14478)
		(layer "In6.Cu")
		(net "M_E_CPU0_SA_DQ<24>")
	)
	(segment
		(start 309.970678 -228.214174)
		(end 309.970678 -228.00945)
		(width 0.14478)
		(layer "In6.Cu")
		(net "M_E_CPU0_SA_DQ<24>")
	)
	(segment
		(start 303.729898 -226.035362)
		(end 303.729898 -225.973132)
		(width 0.14478)
		(layer "In6.Cu")
		(net "M_E_CPU0_SA_DQ<24>")
	)
	(segment
		(start 310.187848 -227.79228)
		(end 310.187594 -227.587556)
		(width 0.14478)
		(layer "In6.Cu")
		(net "M_E_CPU0_SA_DQ<24>")
	)
	(segment
		(start 278.37892 -225.953574)
		(end 278.37892 -225.95332)
		(width 0.14478)
		(layer "In6.Cu")
		(net "M_E_CPU0_SA_DQ<24>")
	)
	(segment
		(start 305.768756 -225.10496)
		(end 305.623976 -224.96018)
		(width 0.14478)
		(layer "In6.Cu")
		(net "M_E_CPU0_SA_DQ<24>")
	)
	(segment
		(start 285.954978 -224.96018)
		(end 283.294582 -224.96018)
		(width 0.14478)
		(layer "In6.Cu")
		(net "M_E_CPU0_SA_DQ<24>")
	)
	(segment
		(start 304.286412 -225.830384)
		(end 304.286412 -226.035362)
		(width 0.14478)
		(layer "In6.Cu")
		(net "M_E_CPU0_SA_DQ<24>")
	)
	(segment
		(start 302.024542 -225.810064)
		(end 301.174658 -224.96018)
		(width 0.14478)
		(layer "In6.Cu")
		(net "M_E_CPU0_SA_DQ<24>")
	)
	(segment
		(start 304.286412 -226.035362)
		(end 304.123344 -226.19843)
		(width 0.14478)
		(layer "In6.Cu")
		(net "M_E_CPU0_SA_DQ<24>")
	)
	(segment
		(start 306.177696 -225.830892)
		(end 305.913536 -225.830892)
		(width 0.14478)
		(layer "In6.Cu")
		(net "M_E_CPU0_SA_DQ<24>")
	)
	(segment
		(start 323.901054 -238.44885)
		(end 319.811654 -238.44885)
		(width 0.14478)
		(layer "In6.Cu")
		(net "M_E_CPU0_SA_DQ<24>")
	)
	(segment
		(start 302.61687 -226.035362)
		(end 302.61687 -225.973132)
		(width 0.14478)
		(layer "In6.Cu")
		(net "M_E_CPU0_SA_DQ<24>")
	)
	(segment
		(start 278.37892 -225.95332)
		(end 278.235664 -225.810064)
		(width 0.14478)
		(layer "In6.Cu")
		(net "M_E_CPU0_SA_DQ<24>")
	)
	(segment
		(start 310.187594 -227.587556)
		(end 309.993538 -227.3935)
		(width 0.14478)
		(layer "In6.Cu")
		(net "M_E_CPU0_SA_DQ<24>")
	)
	(segment
		(start 289.31489 -226.040442)
		(end 289.151822 -226.20351)
		(width 0.14478)
		(layer "In6.Cu")
		(net "M_E_CPU0_SA_DQ<24>")
	)
	(segment
		(start 288.758376 -225.973132)
		(end 288.595308 -225.810064)
		(width 0.14478)
		(layer "In6.Cu")
		(net "M_E_CPU0_SA_DQ<24>")
	)
	(segment
		(start 327.00849 -239.946688)
		(end 327.000108 -239.951514)
		(width 0.0889)
		(layer "In6.Cu")
		(net "M_E_CPU0_SA_DQ<24>")
	)
	(segment
		(start 296.926 -226.19843)
		(end 296.695622 -226.19843)
		(width 0.14478)
		(layer "In6.Cu")
		(net "M_E_CPU0_SA_DQ<24>")
	)
	(segment
		(start 283.294582 -224.96018)
		(end 282.444698 -225.810064)
		(width 0.14478)
		(layer "In6.Cu")
		(net "M_E_CPU0_SA_DQ<24>")
	)
	(segment
		(start 281.824176 -225.973132)
		(end 281.824176 -226.035362)
		(width 0.14478)
		(layer "In6.Cu")
		(net "M_E_CPU0_SA_DQ<24>")
	)
	(segment
		(start 279.635204 -225.810064)
		(end 279.491948 -225.666808)
		(width 0.14478)
		(layer "In6.Cu")
		(net "M_E_CPU0_SA_DQ<24>")
	)
	(segment
		(start 326.112632 -239.870488)
		(end 324.891654 -238.64951)
		(width 0.0889)
		(layer "In6.Cu")
		(net "M_E_CPU0_SA_DQ<24>")
	)
	(segment
		(start 297.089068 -226.035362)
		(end 296.926 -226.19843)
		(width 0.14478)
		(layer "In6.Cu")
		(net "M_E_CPU0_SA_DQ<24>")
	)
	(segment
		(start 327.574148 -239.946688)
		(end 327.563734 -239.940592)
		(width 0.0889)
		(layer "In6.Cu")
		(net "M_E_CPU0_SA_DQ<24>")
	)
	(segment
		(start 288.921444 -226.20351)
		(end 288.758376 -226.040442)
		(width 0.14478)
		(layer "In6.Cu")
		(net "M_E_CPU0_SA_DQ<24>")
	)
	(segment
		(start 309.788814 -227.3935)
		(end 309.571644 -227.61067)
		(width 0.14478)
		(layer "In6.Cu")
		(net "M_E_CPU0_SA_DQ<24>")
	)
	(segment
		(start 297.089068 -225.973132)
		(end 297.089068 -226.035362)
		(width 0.14478)
		(layer "In6.Cu")
		(net "M_E_CPU0_SA_DQ<24>")
	)
	(segment
		(start 278.235664 -225.810064)
		(end 277.617174 -225.810064)
		(width 0.14478)
		(layer "In6.Cu")
		(net "M_E_CPU0_SA_DQ<24>")
	)
	(segment
		(start 278.522176 -226.09683)
		(end 278.37892 -225.953574)
		(width 0.14478)
		(layer "In6.Cu")
		(net "M_E_CPU0_SA_DQ<24>")
	)
	(segment
		(start 324.368414 -238.44885)
		(end 323.901054 -238.44885)
		(width 0.0889)
		(layer "In6.Cu")
		(net "M_E_CPU0_SA_DQ<24>")
	)
	(segment
		(start 294.480742 -225.810064)
		(end 293.630858 -224.96018)
		(width 0.14478)
		(layer "In6.Cu")
		(net "M_E_CPU0_SA_DQ<24>")
	)
	(segment
		(start 296.532554 -225.973132)
		(end 296.369486 -225.810064)
		(width 0.14478)
		(layer "In6.Cu")
		(net "M_E_CPU0_SA_DQ<24>")
	)
	(segment
		(start 309.145178 -226.528884)
		(end 307.576474 -224.96018)
		(width 0.14478)
		(layer "In6.Cu")
		(net "M_E_CPU0_SA_DQ<24>")
	)
	(segment
		(start 303.892966 -226.19843)
		(end 303.729898 -226.035362)
		(width 0.14478)
		(layer "In6.Cu")
		(net "M_E_CPU0_SA_DQ<24>")
	)
	(segment
		(start 309.970678 -228.00945)
		(end 310.187848 -227.79228)
		(width 0.14478)
		(layer "In6.Cu")
		(net "M_E_CPU0_SA_DQ<24>")
	)
	(segment
		(start 313.201558 -231.838754)
		(end 313.201558 -231.445054)
		(width 0.14478)
		(layer "In6.Cu")
		(net "M_E_CPU0_SA_DQ<24>")
	)
	(segment
		(start 281.104594 -225.810064)
		(end 279.635204 -225.810064)
		(width 0.14478)
		(layer "In6.Cu")
		(net "M_E_CPU0_SA_DQ<24>")
	)
	(segment
		(start 289.477958 -225.810064)
		(end 289.31489 -225.973132)
		(width 0.14478)
		(layer "In6.Cu")
		(net "M_E_CPU0_SA_DQ<24>")
	)
	(segment
		(start 303.010316 -226.19843)
		(end 302.779938 -226.19843)
		(width 0.14478)
		(layer "In6.Cu")
		(net "M_E_CPU0_SA_DQ<24>")
	)
	(segment
		(start 306.322476 -225.10496)
		(end 306.322476 -225.686112)
		(width 0.14478)
		(layer "In6.Cu")
		(net "M_E_CPU0_SA_DQ<24>")
	)
	(segment
		(start 281.267662 -225.973132)
		(end 281.104594 -225.810064)
		(width 0.14478)
		(layer "In6.Cu")
		(net "M_E_CPU0_SA_DQ<24>")
	)
	(segment
		(start 305.913536 -225.830892)
		(end 305.768756 -225.686112)
		(width 0.14478)
		(layer "In6.Cu")
		(net "M_E_CPU0_SA_DQ<24>")
	)
	(segment
		(start 302.453802 -225.810064)
		(end 302.024542 -225.810064)
		(width 0.14478)
		(layer "In6.Cu")
		(net "M_E_CPU0_SA_DQ<24>")
	)
	(segment
		(start 324.891654 -238.64951)
		(end 324.569074 -238.64951)
		(width 0.0889)
		(layer "In6.Cu")
		(net "M_E_CPU0_SA_DQ<24>")
	)
	(segment
		(start 305.623976 -224.96018)
		(end 305.156616 -224.96018)
		(width 0.14478)
		(layer "In6.Cu")
		(net "M_E_CPU0_SA_DQ<24>")
	)
	(segment
		(start 302.779938 -226.19843)
		(end 302.61687 -226.035362)
		(width 0.14478)
		(layer "In6.Cu")
		(net "M_E_CPU0_SA_DQ<24>")
	)
	(segment
		(start 303.173384 -225.973132)
		(end 303.173384 -226.035362)
		(width 0.14478)
		(layer "In6.Cu")
		(net "M_E_CPU0_SA_DQ<24>")
	)
	(segment
		(start 302.61687 -225.973132)
		(end 302.453802 -225.810064)
		(width 0.14478)
		(layer "In6.Cu")
		(net "M_E_CPU0_SA_DQ<24>")
	)
	(segment
		(start 278.935434 -225.666554)
		(end 278.935434 -225.953574)
		(width 0.14478)
		(layer "In6.Cu")
		(net "M_E_CPU0_SA_DQ<24>")
	)
	(segment
		(start 281.661108 -226.19843)
		(end 281.43073 -226.19843)
		(width 0.14478)
		(layer "In6.Cu")
		(net "M_E_CPU0_SA_DQ<24>")
	)
	(segment
		(start 309.145178 -227.388674)
		(end 309.145178 -226.528884)
		(width 0.14478)
		(layer "In6.Cu")
		(net "M_E_CPU0_SA_DQ<24>")
	)
	(segment
		(start 279.348692 -225.523298)
		(end 279.07869 -225.523298)
		(width 0.14478)
		(layer "In6.Cu")
		(net "M_E_CPU0_SA_DQ<24>")
	)
	(segment
		(start 281.267662 -226.035362)
		(end 281.267662 -225.973132)
		(width 0.14478)
		(layer "In6.Cu")
		(net "M_E_CPU0_SA_DQ<24>")
	)
	(segment
		(start 290.856162 -224.96018)
		(end 290.006278 -225.810064)
		(width 0.14478)
		(layer "In6.Cu")
		(net "M_E_CPU0_SA_DQ<24>")
	)
	(segment
		(start 281.987244 -225.810064)
		(end 281.824176 -225.973132)
		(width 0.14478)
		(layer "In6.Cu")
		(net "M_E_CPU0_SA_DQ<24>")
	)
	(segment
		(start 328.701146 -239.624108)
		(end 328.85507 -239.889538)
		(width 0.0889)
		(layer "In6.Cu")
		(net "M_E_CPU0_SA_DQ<24>")
	)
	(segment
		(start 327.58253 -239.951514)
		(end 327.574148 -239.946688)
		(width 0.0889)
		(layer "In6.Cu")
		(net "M_E_CPU0_SA_DQ<24>")
	)
	(segment
		(start 309.367428 -227.610924)
		(end 309.145178 -227.388674)
		(width 0.14478)
		(layer "In6.Cu")
		(net "M_E_CPU0_SA_DQ<24>")
	)
	(segment
		(start 303.729898 -225.973132)
		(end 303.56683 -225.810064)
		(width 0.14478)
		(layer "In6.Cu")
		(net "M_E_CPU0_SA_DQ<24>")
	)
	(segment
		(start 281.43073 -226.19843)
		(end 281.267662 -226.035362)
		(width 0.14478)
		(layer "In6.Cu")
		(net "M_E_CPU0_SA_DQ<24>")
	)
	(segment
		(start 306.322476 -225.686112)
		(end 306.177696 -225.830892)
		(width 0.14478)
		(layer "In6.Cu")
		(net "M_E_CPU0_SA_DQ<24>")
	)
	(segment
		(start 288.758376 -226.040442)
		(end 288.758376 -225.973132)
		(width 0.14478)
		(layer "In6.Cu")
		(net "M_E_CPU0_SA_DQ<24>")
	)
	(segment
		(start 289.31489 -225.973132)
		(end 289.31489 -226.040442)
		(width 0.14478)
		(layer "In6.Cu")
		(net "M_E_CPU0_SA_DQ<24>")
	)
	(segment
		(start 305.156616 -224.96018)
		(end 304.286412 -225.830384)
		(width 0.14478)
		(layer "In6.Cu")
		(net "M_E_CPU0_SA_DQ<24>")
	)
	(segment
		(start 319.811654 -238.44885)
		(end 313.201558 -231.838754)
		(width 0.14478)
		(layer "In6.Cu")
		(net "M_E_CPU0_SA_DQ<24>")
	)
	(segment
		(start 279.07869 -225.523298)
		(end 278.935434 -225.666554)
		(width 0.14478)
		(layer "In6.Cu")
		(net "M_E_CPU0_SA_DQ<24>")
	)
	(segment
		(start 303.336452 -225.810064)
		(end 303.173384 -225.973132)
		(width 0.14478)
		(layer "In6.Cu")
		(net "M_E_CPU0_SA_DQ<24>")
	)
	(segment
		(start 279.491948 -225.666808)
		(end 279.491948 -225.666554)
		(width 0.14478)
		(layer "In6.Cu")
		(net "M_E_CPU0_SA_DQ<24>")
	)
	(segment
		(start 297.621198 -225.810064)
		(end 297.252136 -225.810064)
		(width 0.14478)
		(layer "In6.Cu")
		(net "M_E_CPU0_SA_DQ<24>")
	)
	(segment
		(start 289.151822 -226.20351)
		(end 288.921444 -226.20351)
		(width 0.14478)
		(layer "In6.Cu")
		(net "M_E_CPU0_SA_DQ<24>")
	)
	(segment
		(start 296.369486 -225.810064)
		(end 294.480742 -225.810064)
		(width 0.14478)
		(layer "In6.Cu")
		(net "M_E_CPU0_SA_DQ<24>")
	)
	(segment
		(start 298.471082 -224.96018)
		(end 297.621198 -225.810064)
		(width 0.14478)
		(layer "In6.Cu")
		(net "M_E_CPU0_SA_DQ<24>")
	)
	(segment
		(start 324.569074 -238.64951)
		(end 324.368414 -238.44885)
		(width 0.0889)
		(layer "In6.Cu")
		(net "M_E_CPU0_SA_DQ<24>")
	)
	(segment
		(start 326.351138 -239.870488)
		(end 326.112632 -239.870488)
		(width 0.0889)
		(layer "In6.Cu")
		(net "M_E_CPU0_SA_DQ<24>")
	)
	(segment
		(start 307.576474 -224.96018)
		(end 306.467256 -224.96018)
		(width 0.14478)
		(layer "In6.Cu")
		(net "M_E_CPU0_SA_DQ<24>")
	)
	(segment
		(start 288.595308 -225.810064)
		(end 286.804862 -225.810064)
		(width 0.14478)
		(layer "In6.Cu")
		(net "M_E_CPU0_SA_DQ<24>")
	)
	(segment
		(start 279.491948 -225.666554)
		(end 279.348692 -225.523298)
		(width 0.14478)
		(layer "In6.Cu")
		(net "M_E_CPU0_SA_DQ<24>")
	)
	(arc
		(start 328.514202 -239.946688)
		(mid 328.231246 -239.870511)
		(end 327.94829 -239.946688)
		(width 0.0889)
		(layer "In6.Cu")
		(net "M_E_CPU0_SA_DQ<24>")
	)
	(arc
		(start 327.94829 -239.946688)
		(mid 327.766039 -239.997038)
		(end 327.58253 -239.951514)
		(width 0.0889)
		(layer "In6.Cu")
		(net "M_E_CPU0_SA_DQ<24>")
	)
	(arc
		(start 327.563734 -239.940592)
		(mid 327.285302 -239.870494)
		(end 327.00849 -239.946688)
		(width 0.0889)
		(layer "In6.Cu")
		(net "M_E_CPU0_SA_DQ<24>")
	)
	(arc
		(start 326.634348 -239.946688)
		(mid 326.497785 -239.889855)
		(end 326.351138 -239.870488)
		(width 0.0889)
		(layer "In6.Cu")
		(net "M_E_CPU0_SA_DQ<24>")
	)
	(arc
		(start 328.832718 -239.97285)
		(mid 328.670529 -239.995585)
		(end 328.514202 -239.946688)
		(width 0.0889)
		(layer "In6.Cu")
		(net "M_E_CPU0_SA_DQ<24>")
	)
	(arc
		(start 327.000108 -239.951514)
		(mid 326.8166 -239.997008)
		(end 326.634348 -239.946688)
		(width 0.0889)
		(layer "In6.Cu")
		(net "M_E_CPU0_SA_DQ<24>")
	)
	(segment
		(start 331.047852 -239.890046)
		(end 330.581 -239.624108)
		(width 0.10668)
		(layer "F.Cu")
		(net "M_E_CPU0_SA_DQ<23>")
	)
	(segment
		(start 274.231354 -224.321878)
		(end 274.231354 -224.797112)
		(width 0.14478)
		(layer "In6.Cu")
		(net "M_E_CPU0_SA_DQ<23>")
	)
	(segment
		(start 274.950936 -224.96018)
		(end 274.787868 -224.797112)
		(width 0.14478)
		(layer "In6.Cu")
		(net "M_E_CPU0_SA_DQ<23>")
	)
	(segment
		(start 325.881492 -239.257332)
		(end 325.404734 -238.780574)
		(width 0.0889)
		(layer "In6.Cu")
		(net "M_E_CPU0_SA_DQ<23>")
	)
	(segment
		(start 275.737828 -224.15881)
		(end 275.50745 -224.15881)
		(width 0.14478)
		(layer "In6.Cu")
		(net "M_E_CPU0_SA_DQ<23>")
	)
	(segment
		(start 320.04889 -237.89259)
		(end 313.757818 -231.601518)
		(width 0.14478)
		(layer "In6.Cu")
		(net "M_E_CPU0_SA_DQ<23>")
	)
	(segment
		(start 275.900896 -224.321878)
		(end 275.737828 -224.15881)
		(width 0.14478)
		(layer "In6.Cu")
		(net "M_E_CPU0_SA_DQ<23>")
	)
	(segment
		(start 313.757818 -231.197658)
		(end 310.739028 -228.178868)
		(width 0.14478)
		(layer "In6.Cu")
		(net "M_E_CPU0_SA_DQ<23>")
	)
	(segment
		(start 290.804092 -224.110042)
		(end 289.953954 -224.96018)
		(width 0.14478)
		(layer "In6.Cu")
		(net "M_E_CPU0_SA_DQ<23>")
	)
	(segment
		(start 313.757818 -231.601518)
		(end 313.757818 -231.197658)
		(width 0.14478)
		(layer "In6.Cu")
		(net "M_E_CPU0_SA_DQ<23>")
	)
	(segment
		(start 293.652702 -224.110042)
		(end 290.804092 -224.110042)
		(width 0.14478)
		(layer "In6.Cu")
		(net "M_E_CPU0_SA_DQ<23>")
	)
	(segment
		(start 274.068286 -224.96018)
		(end 273.51736 -224.96018)
		(width 0.14478)
		(layer "In6.Cu")
		(net "M_E_CPU0_SA_DQ<23>")
	)
	(segment
		(start 274.787868 -224.797112)
		(end 274.787868 -224.321878)
		(width 0.14478)
		(layer "In6.Cu")
		(net "M_E_CPU0_SA_DQ<23>")
	)
	(segment
		(start 330.427076 -239.358678)
		(end 330.331064 -239.333278)
		(width 0.0889)
		(layer "In6.Cu")
		(net "M_E_CPU0_SA_DQ<23>")
	)
	(segment
		(start 330.581 -239.624108)
		(end 330.427076 -239.358678)
		(width 0.0889)
		(layer "In6.Cu")
		(net "M_E_CPU0_SA_DQ<23>")
	)
	(segment
		(start 327.008744 -239.301528)
		(end 326.99706 -239.29467)
		(width 0.0889)
		(layer "In6.Cu")
		(net "M_E_CPU0_SA_DQ<23>")
	)
	(segment
		(start 273.51736 -224.96018)
		(end 273.092164 -224.534984)
		(width 0.14478)
		(layer "In6.Cu")
		(net "M_E_CPU0_SA_DQ<23>")
	)
	(segment
		(start 305.839368 -224.225612)
		(end 305.083718 -224.225612)
		(width 0.14478)
		(layer "In6.Cu")
		(net "M_E_CPU0_SA_DQ<23>")
	)
	(segment
		(start 325.404734 -238.35233)
		(end 324.944994 -237.89259)
		(width 0.0889)
		(layer "In6.Cu")
		(net "M_E_CPU0_SA_DQ<23>")
	)
	(segment
		(start 327.574402 -239.301528)
		(end 327.563988 -239.307624)
		(width 0.0889)
		(layer "In6.Cu")
		(net "M_E_CPU0_SA_DQ<23>")
	)
	(segment
		(start 305.083718 -224.225612)
		(end 304.34915 -224.96018)
		(width 0.14478)
		(layer "In6.Cu")
		(net "M_E_CPU0_SA_DQ<23>")
	)
	(segment
		(start 274.6248 -224.15881)
		(end 274.394422 -224.15881)
		(width 0.14478)
		(layer "In6.Cu")
		(net "M_E_CPU0_SA_DQ<23>")
	)
	(segment
		(start 308.131718 -224.735898)
		(end 308.131718 -224.593912)
		(width 0.14478)
		(layer "In6.Cu")
		(net "M_E_CPU0_SA_DQ<23>")
	)
	(segment
		(start 324.944994 -237.89259)
		(end 323.888354 -237.89259)
		(width 0.0889)
		(layer "In6.Cu")
		(net "M_E_CPU0_SA_DQ<23>")
	)
	(segment
		(start 275.900896 -224.797112)
		(end 275.900896 -224.321878)
		(width 0.14478)
		(layer "In6.Cu")
		(net "M_E_CPU0_SA_DQ<23>")
	)
	(segment
		(start 289.953954 -224.96018)
		(end 286.814006 -224.96018)
		(width 0.14478)
		(layer "In6.Cu")
		(net "M_E_CPU0_SA_DQ<23>")
	)
	(segment
		(start 302.04664 -224.96018)
		(end 301.196502 -224.110042)
		(width 0.14478)
		(layer "In6.Cu")
		(net "M_E_CPU0_SA_DQ<23>")
	)
	(segment
		(start 275.181314 -224.96018)
		(end 274.950936 -224.96018)
		(width 0.14478)
		(layer "In6.Cu")
		(net "M_E_CPU0_SA_DQ<23>")
	)
	(segment
		(start 298.411138 -224.110042)
		(end 297.561 -224.96018)
		(width 0.14478)
		(layer "In6.Cu")
		(net "M_E_CPU0_SA_DQ<23>")
	)
	(segment
		(start 304.34915 -224.96018)
		(end 302.04664 -224.96018)
		(width 0.14478)
		(layer "In6.Cu")
		(net "M_E_CPU0_SA_DQ<23>")
	)
	(segment
		(start 274.787868 -224.321878)
		(end 274.6248 -224.15881)
		(width 0.14478)
		(layer "In6.Cu")
		(net "M_E_CPU0_SA_DQ<23>")
	)
	(segment
		(start 307.647848 -224.110042)
		(end 305.954938 -224.110042)
		(width 0.14478)
		(layer "In6.Cu")
		(net "M_E_CPU0_SA_DQ<23>")
	)
	(segment
		(start 274.394422 -224.15881)
		(end 274.231354 -224.321878)
		(width 0.14478)
		(layer "In6.Cu")
		(net "M_E_CPU0_SA_DQ<23>")
	)
	(segment
		(start 275.344382 -224.321878)
		(end 275.344382 -224.797112)
		(width 0.14478)
		(layer "In6.Cu")
		(net "M_E_CPU0_SA_DQ<23>")
	)
	(segment
		(start 301.196502 -224.110042)
		(end 298.411138 -224.110042)
		(width 0.14478)
		(layer "In6.Cu")
		(net "M_E_CPU0_SA_DQ<23>")
	)
	(segment
		(start 310.739028 -227.343208)
		(end 308.131718 -224.735898)
		(width 0.14478)
		(layer "In6.Cu")
		(net "M_E_CPU0_SA_DQ<23>")
	)
	(segment
		(start 325.902066 -239.257332)
		(end 325.881492 -239.257332)
		(width 0.0889)
		(layer "In6.Cu")
		(net "M_E_CPU0_SA_DQ<23>")
	)
	(segment
		(start 275.344382 -224.797112)
		(end 275.181314 -224.96018)
		(width 0.14478)
		(layer "In6.Cu")
		(net "M_E_CPU0_SA_DQ<23>")
	)
	(segment
		(start 310.739028 -228.178868)
		(end 310.739028 -227.343208)
		(width 0.14478)
		(layer "In6.Cu")
		(net "M_E_CPU0_SA_DQ<23>")
	)
	(segment
		(start 305.954938 -224.110042)
		(end 305.839368 -224.225612)
		(width 0.14478)
		(layer "In6.Cu")
		(net "M_E_CPU0_SA_DQ<23>")
	)
	(segment
		(start 308.131718 -224.593912)
		(end 307.647848 -224.110042)
		(width 0.14478)
		(layer "In6.Cu")
		(net "M_E_CPU0_SA_DQ<23>")
	)
	(segment
		(start 294.50284 -224.96018)
		(end 293.652702 -224.110042)
		(width 0.14478)
		(layer "In6.Cu")
		(net "M_E_CPU0_SA_DQ<23>")
	)
	(segment
		(start 327.586086 -239.29467)
		(end 327.574402 -239.301528)
		(width 0.0889)
		(layer "In6.Cu")
		(net "M_E_CPU0_SA_DQ<23>")
	)
	(segment
		(start 285.963868 -224.110042)
		(end 283.351478 -224.110042)
		(width 0.14478)
		(layer "In6.Cu")
		(net "M_E_CPU0_SA_DQ<23>")
	)
	(segment
		(start 283.351478 -224.110042)
		(end 282.50134 -224.96018)
		(width 0.14478)
		(layer "In6.Cu")
		(net "M_E_CPU0_SA_DQ<23>")
	)
	(segment
		(start 275.50745 -224.15881)
		(end 275.344382 -224.321878)
		(width 0.14478)
		(layer "In6.Cu")
		(net "M_E_CPU0_SA_DQ<23>")
	)
	(segment
		(start 282.50134 -224.96018)
		(end 276.063964 -224.96018)
		(width 0.14478)
		(layer "In6.Cu")
		(net "M_E_CPU0_SA_DQ<23>")
	)
	(segment
		(start 297.561 -224.96018)
		(end 294.50284 -224.96018)
		(width 0.14478)
		(layer "In6.Cu")
		(net "M_E_CPU0_SA_DQ<23>")
	)
	(segment
		(start 329.828144 -239.301528)
		(end 329.819762 -239.296702)
		(width 0.0889)
		(layer "In6.Cu")
		(net "M_E_CPU0_SA_DQ<23>")
	)
	(segment
		(start 276.063964 -224.96018)
		(end 275.900896 -224.797112)
		(width 0.14478)
		(layer "In6.Cu")
		(net "M_E_CPU0_SA_DQ<23>")
	)
	(segment
		(start 323.888354 -237.89259)
		(end 320.04889 -237.89259)
		(width 0.14478)
		(layer "In6.Cu")
		(net "M_E_CPU0_SA_DQ<23>")
	)
	(segment
		(start 274.231354 -224.797112)
		(end 274.068286 -224.96018)
		(width 0.14478)
		(layer "In6.Cu")
		(net "M_E_CPU0_SA_DQ<23>")
	)
	(segment
		(start 325.404734 -238.780574)
		(end 325.404734 -238.35233)
		(width 0.0889)
		(layer "In6.Cu")
		(net "M_E_CPU0_SA_DQ<23>")
	)
	(segment
		(start 326.080628 -239.30864)
		(end 326.06869 -239.301782)
		(width 0.0889)
		(layer "In6.Cu")
		(net "M_E_CPU0_SA_DQ<23>")
	)
	(segment
		(start 286.814006 -224.96018)
		(end 285.963868 -224.110042)
		(width 0.14478)
		(layer "In6.Cu")
		(net "M_E_CPU0_SA_DQ<23>")
	)
	(arc
		(start 327.94829 -239.301528)
		(mid 327.768085 -239.251211)
		(end 327.586086 -239.29467)
		(width 0.0889)
		(layer "In6.Cu")
		(net "M_E_CPU0_SA_DQ<23>")
	)
	(arc
		(start 326.634348 -239.301528)
		(mid 326.358416 -239.377785)
		(end 326.080628 -239.30864)
		(width 0.0889)
		(layer "In6.Cu")
		(net "M_E_CPU0_SA_DQ<23>")
	)
	(arc
		(start 329.454002 -239.301528)
		(mid 329.171046 -239.377705)
		(end 328.88809 -239.301528)
		(width 0.0889)
		(layer "In6.Cu")
		(net "M_E_CPU0_SA_DQ<23>")
	)
	(arc
		(start 330.331064 -239.333278)
		(mid 330.075856 -239.376755)
		(end 329.828144 -239.301528)
		(width 0.0889)
		(layer "In6.Cu")
		(net "M_E_CPU0_SA_DQ<23>")
	)
	(arc
		(start 328.88809 -239.301528)
		(mid 328.701146 -239.251273)
		(end 328.514202 -239.301528)
		(width 0.0889)
		(layer "In6.Cu")
		(net "M_E_CPU0_SA_DQ<23>")
	)
	(arc
		(start 327.563988 -239.307624)
		(mid 327.285556 -239.377722)
		(end 327.008744 -239.301528)
		(width 0.0889)
		(layer "In6.Cu")
		(net "M_E_CPU0_SA_DQ<23>")
	)
	(arc
		(start 329.819762 -239.296702)
		(mid 329.636254 -239.251208)
		(end 329.454002 -239.301528)
		(width 0.0889)
		(layer "In6.Cu")
		(net "M_E_CPU0_SA_DQ<23>")
	)
	(arc
		(start 326.06869 -239.301782)
		(mid 325.988292 -239.268635)
		(end 325.902066 -239.257332)
		(width 0.0889)
		(layer "In6.Cu")
		(net "M_E_CPU0_SA_DQ<23>")
	)
	(arc
		(start 328.514202 -239.301528)
		(mid 328.231246 -239.377705)
		(end 327.94829 -239.301528)
		(width 0.0889)
		(layer "In6.Cu")
		(net "M_E_CPU0_SA_DQ<23>")
	)
	(arc
		(start 326.99706 -239.29467)
		(mid 326.814805 -239.251017)
		(end 326.634348 -239.301528)
		(width 0.0889)
		(layer "In6.Cu")
		(net "M_E_CPU0_SA_DQ<23>")
	)
	(segment
		(start 329.637898 -239.08004)
		(end 329.171046 -238.814102)
		(width 0.10668)
		(layer "F.Cu")
		(net "M_E_CPU0_SA_DQ<22>")
	)
	(segment
		(start 305.954938 -222.41002)
		(end 305.1048 -223.260158)
		(width 0.14478)
		(layer "In6.Cu")
		(net "M_E_CPU0_SA_DQ<22>")
	)
	(segment
		(start 282.50134 -223.260158)
		(end 276.408642 -223.260158)
		(width 0.14478)
		(layer "In6.Cu")
		(net "M_E_CPU0_SA_DQ<22>")
	)
	(segment
		(start 274.7391 -222.51543)
		(end 274.576032 -222.678498)
		(width 0.14478)
		(layer "In6.Cu")
		(net "M_E_CPU0_SA_DQ<22>")
	)
	(segment
		(start 328.044048 -238.491522)
		(end 328.033634 -238.497618)
		(width 0.0889)
		(layer "In6.Cu")
		(net "M_E_CPU0_SA_DQ<22>")
	)
	(segment
		(start 329.017122 -238.548672)
		(end 328.92111 -238.523272)
		(width 0.0889)
		(layer "In6.Cu")
		(net "M_E_CPU0_SA_DQ<22>")
	)
	(segment
		(start 326.543416 -238.495078)
		(end 326.537828 -238.491776)
		(width 0.0889)
		(layer "In6.Cu")
		(net "M_E_CPU0_SA_DQ<22>")
	)
	(segment
		(start 324.129654 -236.98327)
		(end 323.893434 -236.98327)
		(width 0.0889)
		(layer "In6.Cu")
		(net "M_E_CPU0_SA_DQ<22>")
	)
	(segment
		(start 289.953954 -223.260158)
		(end 286.814006 -223.260158)
		(width 0.14478)
		(layer "In6.Cu")
		(net "M_E_CPU0_SA_DQ<22>")
	)
	(segment
		(start 276.245574 -223.09709)
		(end 276.245574 -222.056198)
		(width 0.14478)
		(layer "In6.Cu")
		(net "M_E_CPU0_SA_DQ<22>")
	)
	(segment
		(start 302.04664 -223.260158)
		(end 301.196502 -222.41002)
		(width 0.14478)
		(layer "In6.Cu")
		(net "M_E_CPU0_SA_DQ<22>")
	)
	(segment
		(start 297.561 -223.260158)
		(end 294.50284 -223.260158)
		(width 0.14478)
		(layer "In6.Cu")
		(net "M_E_CPU0_SA_DQ<22>")
	)
	(segment
		(start 275.132546 -223.09709)
		(end 275.132546 -222.678498)
		(width 0.14478)
		(layer "In6.Cu")
		(net "M_E_CPU0_SA_DQ<22>")
	)
	(segment
		(start 305.1048 -223.260158)
		(end 302.04664 -223.260158)
		(width 0.14478)
		(layer "In6.Cu")
		(net "M_E_CPU0_SA_DQ<22>")
	)
	(segment
		(start 293.652702 -222.41002)
		(end 290.804092 -222.41002)
		(width 0.14478)
		(layer "In6.Cu")
		(net "M_E_CPU0_SA_DQ<22>")
	)
	(segment
		(start 324.972934 -237.28045)
		(end 324.426834 -237.28045)
		(width 0.0889)
		(layer "In6.Cu")
		(net "M_E_CPU0_SA_DQ<22>")
	)
	(segment
		(start 274.576032 -222.678498)
		(end 274.576032 -223.09709)
		(width 0.14478)
		(layer "In6.Cu")
		(net "M_E_CPU0_SA_DQ<22>")
	)
	(segment
		(start 275.68906 -223.09709)
		(end 275.525992 -223.260158)
		(width 0.14478)
		(layer "In6.Cu")
		(net "M_E_CPU0_SA_DQ<22>")
	)
	(segment
		(start 329.171046 -238.814102)
		(end 329.017122 -238.548672)
		(width 0.0889)
		(layer "In6.Cu")
		(net "M_E_CPU0_SA_DQ<22>")
	)
	(segment
		(start 276.408642 -223.260158)
		(end 276.245574 -223.09709)
		(width 0.14478)
		(layer "In6.Cu")
		(net "M_E_CPU0_SA_DQ<22>")
	)
	(segment
		(start 275.852128 -221.89313)
		(end 275.68906 -222.056198)
		(width 0.14478)
		(layer "In6.Cu")
		(net "M_E_CPU0_SA_DQ<22>")
	)
	(segment
		(start 290.804092 -222.41002)
		(end 289.953954 -223.260158)
		(width 0.14478)
		(layer "In6.Cu")
		(net "M_E_CPU0_SA_DQ<22>")
	)
	(segment
		(start 314.695078 -231.259634)
		(end 314.695078 -230.848662)
		(width 0.14478)
		(layer "In6.Cu")
		(net "M_E_CPU0_SA_DQ<22>")
	)
	(segment
		(start 324.426834 -237.28045)
		(end 324.129654 -236.98327)
		(width 0.0889)
		(layer "In6.Cu")
		(net "M_E_CPU0_SA_DQ<22>")
	)
	(segment
		(start 294.50284 -223.260158)
		(end 293.652702 -222.41002)
		(width 0.14478)
		(layer "In6.Cu")
		(net "M_E_CPU0_SA_DQ<22>")
	)
	(segment
		(start 275.132546 -222.678498)
		(end 274.969478 -222.51543)
		(width 0.14478)
		(layer "In6.Cu")
		(net "M_E_CPU0_SA_DQ<22>")
	)
	(segment
		(start 276.082506 -221.89313)
		(end 275.852128 -221.89313)
		(width 0.14478)
		(layer "In6.Cu")
		(net "M_E_CPU0_SA_DQ<22>")
	)
	(segment
		(start 274.969478 -222.51543)
		(end 274.7391 -222.51543)
		(width 0.14478)
		(layer "In6.Cu")
		(net "M_E_CPU0_SA_DQ<22>")
	)
	(segment
		(start 273.51736 -223.260158)
		(end 273.092164 -222.834962)
		(width 0.14478)
		(layer "In6.Cu")
		(net "M_E_CPU0_SA_DQ<22>")
	)
	(segment
		(start 274.412964 -223.260158)
		(end 273.51736 -223.260158)
		(width 0.14478)
		(layer "In6.Cu")
		(net "M_E_CPU0_SA_DQ<22>")
	)
	(segment
		(start 274.576032 -223.09709)
		(end 274.412964 -223.260158)
		(width 0.14478)
		(layer "In6.Cu")
		(net "M_E_CPU0_SA_DQ<22>")
	)
	(segment
		(start 275.68906 -222.056198)
		(end 275.68906 -223.09709)
		(width 0.14478)
		(layer "In6.Cu")
		(net "M_E_CPU0_SA_DQ<22>")
	)
	(segment
		(start 323.893434 -236.98327)
		(end 320.418714 -236.98327)
		(width 0.14478)
		(layer "In6.Cu")
		(net "M_E_CPU0_SA_DQ<22>")
	)
	(segment
		(start 320.418714 -236.98327)
		(end 314.695078 -231.259634)
		(width 0.14478)
		(layer "In6.Cu")
		(net "M_E_CPU0_SA_DQ<22>")
	)
	(segment
		(start 286.814006 -223.260158)
		(end 285.963868 -222.41002)
		(width 0.14478)
		(layer "In6.Cu")
		(net "M_E_CPU0_SA_DQ<22>")
	)
	(segment
		(start 275.295614 -223.260158)
		(end 275.132546 -223.09709)
		(width 0.14478)
		(layer "In6.Cu")
		(net "M_E_CPU0_SA_DQ<22>")
	)
	(segment
		(start 309.272178 -224.421446)
		(end 309.272178 -223.863916)
		(width 0.14478)
		(layer "In6.Cu")
		(net "M_E_CPU0_SA_DQ<22>")
	)
	(segment
		(start 311.638188 -226.787456)
		(end 309.272178 -224.421446)
		(width 0.14478)
		(layer "In6.Cu")
		(net "M_E_CPU0_SA_DQ<22>")
	)
	(segment
		(start 298.411138 -222.41002)
		(end 297.561 -223.260158)
		(width 0.14478)
		(layer "In6.Cu")
		(net "M_E_CPU0_SA_DQ<22>")
	)
	(segment
		(start 309.272178 -223.863916)
		(end 307.818282 -222.41002)
		(width 0.14478)
		(layer "In6.Cu")
		(net "M_E_CPU0_SA_DQ<22>")
	)
	(segment
		(start 327.111614 -238.486696)
		(end 327.103232 -238.491522)
		(width 0.0889)
		(layer "In6.Cu")
		(net "M_E_CPU0_SA_DQ<22>")
	)
	(segment
		(start 307.818282 -222.41002)
		(end 305.954938 -222.41002)
		(width 0.14478)
		(layer "In6.Cu")
		(net "M_E_CPU0_SA_DQ<22>")
	)
	(segment
		(start 326.351138 -238.440976)
		(end 326.13346 -238.440976)
		(width 0.0889)
		(layer "In6.Cu")
		(net "M_E_CPU0_SA_DQ<22>")
	)
	(segment
		(start 275.525992 -223.260158)
		(end 275.295614 -223.260158)
		(width 0.14478)
		(layer "In6.Cu")
		(net "M_E_CPU0_SA_DQ<22>")
	)
	(segment
		(start 328.41819 -238.491522)
		(end 328.409808 -238.486696)
		(width 0.0889)
		(layer "In6.Cu")
		(net "M_E_CPU0_SA_DQ<22>")
	)
	(segment
		(start 311.638188 -227.791772)
		(end 311.638188 -226.787456)
		(width 0.14478)
		(layer "In6.Cu")
		(net "M_E_CPU0_SA_DQ<22>")
	)
	(segment
		(start 301.196502 -222.41002)
		(end 298.411138 -222.41002)
		(width 0.14478)
		(layer "In6.Cu")
		(net "M_E_CPU0_SA_DQ<22>")
	)
	(segment
		(start 285.963868 -222.41002)
		(end 283.351478 -222.41002)
		(width 0.14478)
		(layer "In6.Cu")
		(net "M_E_CPU0_SA_DQ<22>")
	)
	(segment
		(start 283.351478 -222.41002)
		(end 282.50134 -223.260158)
		(width 0.14478)
		(layer "In6.Cu")
		(net "M_E_CPU0_SA_DQ<22>")
	)
	(segment
		(start 276.245574 -222.056198)
		(end 276.082506 -221.89313)
		(width 0.14478)
		(layer "In6.Cu")
		(net "M_E_CPU0_SA_DQ<22>")
	)
	(segment
		(start 326.13346 -238.440976)
		(end 324.972934 -237.28045)
		(width 0.0889)
		(layer "In6.Cu")
		(net "M_E_CPU0_SA_DQ<22>")
	)
	(segment
		(start 314.695078 -230.848662)
		(end 311.638188 -227.791772)
		(width 0.14478)
		(layer "In6.Cu")
		(net "M_E_CPU0_SA_DQ<22>")
	)
	(arc
		(start 328.409808 -238.486696)
		(mid 328.2263 -238.441202)
		(end 328.044048 -238.491522)
		(width 0.0889)
		(layer "In6.Cu")
		(net "M_E_CPU0_SA_DQ<22>")
	)
	(arc
		(start 328.033634 -238.497618)
		(mid 327.754948 -238.567838)
		(end 327.477882 -238.491522)
		(width 0.0889)
		(layer "In6.Cu")
		(net "M_E_CPU0_SA_DQ<22>")
	)
	(arc
		(start 327.103232 -238.491522)
		(mid 326.823804 -238.567688)
		(end 326.543416 -238.495078)
		(width 0.0889)
		(layer "In6.Cu")
		(net "M_E_CPU0_SA_DQ<22>")
	)
	(arc
		(start 328.92111 -238.523272)
		(mid 328.665902 -238.566749)
		(end 328.41819 -238.491522)
		(width 0.0889)
		(layer "In6.Cu")
		(net "M_E_CPU0_SA_DQ<22>")
	)
	(arc
		(start 326.537828 -238.491776)
		(mid 326.447837 -238.454041)
		(end 326.351138 -238.440976)
		(width 0.0889)
		(layer "In6.Cu")
		(net "M_E_CPU0_SA_DQ<22>")
	)
	(arc
		(start 327.477882 -238.491522)
		(mid 327.295377 -238.441045)
		(end 327.111614 -238.486696)
		(width 0.0889)
		(layer "In6.Cu")
		(net "M_E_CPU0_SA_DQ<22>")
	)
	(segment
		(start 330.577952 -239.08004)
		(end 330.1111 -238.814102)
		(width 0.10668)
		(layer "F.Cu")
		(net "M_E_CPU0_SA_DQ<21>")
	)
	(segment
		(start 323.875654 -237.43793)
		(end 320.237358 -237.43793)
		(width 0.14478)
		(layer "In6.Cu")
		(net "M_E_CPU0_SA_DQ<21>")
	)
	(segment
		(start 289.107626 -223.709738)
		(end 288.849562 -223.709738)
		(width 0.14478)
		(layer "In6.Cu")
		(net "M_E_CPU0_SA_DQ<21>")
	)
	(segment
		(start 297.066208 -224.333562)
		(end 296.90314 -224.49663)
		(width 0.14478)
		(layer "In6.Cu")
		(net "M_E_CPU0_SA_DQ<21>")
	)
	(segment
		(start 308.420516 -223.64827)
		(end 307.982874 -223.64827)
		(width 0.14478)
		(layer "In6.Cu")
		(net "M_E_CPU0_SA_DQ<21>")
	)
	(segment
		(start 296.90314 -224.49663)
		(end 296.672762 -224.49663)
		(width 0.14478)
		(layer "In6.Cu")
		(net "M_E_CPU0_SA_DQ<21>")
	)
	(segment
		(start 279.974802 -224.110042)
		(end 279.811734 -224.27311)
		(width 0.14478)
		(layer "In6.Cu")
		(net "M_E_CPU0_SA_DQ<21>")
	)
	(segment
		(start 290.799266 -223.260158)
		(end 290.349686 -223.709738)
		(width 0.14478)
		(layer "In6.Cu")
		(net "M_E_CPU0_SA_DQ<21>")
	)
	(segment
		(start 307.263292 -223.485202)
		(end 307.100224 -223.64827)
		(width 0.14478)
		(layer "In6.Cu")
		(net "M_E_CPU0_SA_DQ<21>")
	)
	(segment
		(start 278.30526 -224.48393)
		(end 278.142192 -224.320862)
		(width 0.14478)
		(layer "In6.Cu")
		(net "M_E_CPU0_SA_DQ<21>")
	)
	(segment
		(start 290.349686 -223.709738)
		(end 289.961066 -223.709738)
		(width 0.14478)
		(layer "In6.Cu")
		(net "M_E_CPU0_SA_DQ<21>")
	)
	(segment
		(start 307.819806 -223.423226)
		(end 307.656738 -223.260158)
		(width 0.14478)
		(layer "In6.Cu")
		(net "M_E_CPU0_SA_DQ<21>")
	)
	(segment
		(start 289.816286 -223.854518)
		(end 289.816286 -224.360232)
		(width 0.14478)
		(layer "In6.Cu")
		(net "M_E_CPU0_SA_DQ<21>")
	)
	(segment
		(start 293.630858 -223.260158)
		(end 290.799266 -223.260158)
		(width 0.14478)
		(layer "In6.Cu")
		(net "M_E_CPU0_SA_DQ<21>")
	)
	(segment
		(start 307.819806 -223.485202)
		(end 307.819806 -223.423226)
		(width 0.14478)
		(layer "In6.Cu")
		(net "M_E_CPU0_SA_DQ<21>")
	)
	(segment
		(start 304.159158 -224.49663)
		(end 303.92878 -224.49663)
		(width 0.14478)
		(layer "In6.Cu")
		(net "M_E_CPU0_SA_DQ<21>")
	)
	(segment
		(start 303.04613 -224.49663)
		(end 302.815752 -224.49663)
		(width 0.14478)
		(layer "In6.Cu")
		(net "M_E_CPU0_SA_DQ<21>")
	)
	(segment
		(start 327.488804 -239.130586)
		(end 327.47839 -239.136682)
		(width 0.0889)
		(layer "In6.Cu")
		(net "M_E_CPU0_SA_DQ<21>")
	)
	(segment
		(start 307.100224 -223.64827)
		(end 306.869846 -223.64827)
		(width 0.14478)
		(layer "In6.Cu")
		(net "M_E_CPU0_SA_DQ<21>")
	)
	(segment
		(start 286.804862 -224.110042)
		(end 285.954978 -223.260158)
		(width 0.14478)
		(layer "In6.Cu")
		(net "M_E_CPU0_SA_DQ<21>")
	)
	(segment
		(start 279.418288 -224.48393)
		(end 279.25522 -224.320862)
		(width 0.14478)
		(layer "In6.Cu")
		(net "M_E_CPU0_SA_DQ<21>")
	)
	(segment
		(start 304.322226 -223.95815)
		(end 304.322226 -224.333562)
		(width 0.14478)
		(layer "In6.Cu")
		(net "M_E_CPU0_SA_DQ<21>")
	)
	(segment
		(start 281.497024 -224.110042)
		(end 279.974802 -224.110042)
		(width 0.14478)
		(layer "In6.Cu")
		(net "M_E_CPU0_SA_DQ<21>")
	)
	(segment
		(start 304.567844 -223.712532)
		(end 304.322226 -223.95815)
		(width 0.14478)
		(layer "In6.Cu")
		(net "M_E_CPU0_SA_DQ<21>")
	)
	(segment
		(start 289.397186 -224.505012)
		(end 289.252406 -224.360232)
		(width 0.14478)
		(layer "In6.Cu")
		(net "M_E_CPU0_SA_DQ<21>")
	)
	(segment
		(start 328.992484 -239.141508)
		(end 328.984102 -239.136682)
		(width 0.0889)
		(layer "In6.Cu")
		(net "M_E_CPU0_SA_DQ<21>")
	)
	(segment
		(start 307.656738 -223.260158)
		(end 307.42636 -223.260158)
		(width 0.14478)
		(layer "In6.Cu")
		(net "M_E_CPU0_SA_DQ<21>")
	)
	(segment
		(start 301.174658 -223.260158)
		(end 298.615862 -223.260158)
		(width 0.14478)
		(layer "In6.Cu")
		(net "M_E_CPU0_SA_DQ<21>")
	)
	(segment
		(start 279.648666 -224.48393)
		(end 279.418288 -224.48393)
		(width 0.14478)
		(layer "In6.Cu")
		(net "M_E_CPU0_SA_DQ<21>")
	)
	(segment
		(start 294.480742 -224.110042)
		(end 293.630858 -223.260158)
		(width 0.14478)
		(layer "In6.Cu")
		(net "M_E_CPU0_SA_DQ<21>")
	)
	(segment
		(start 278.698706 -224.320862)
		(end 278.535638 -224.48393)
		(width 0.14478)
		(layer "In6.Cu")
		(net "M_E_CPU0_SA_DQ<21>")
	)
	(segment
		(start 297.229276 -224.110042)
		(end 297.066208 -224.27311)
		(width 0.14478)
		(layer "In6.Cu")
		(net "M_E_CPU0_SA_DQ<21>")
	)
	(segment
		(start 288.849562 -223.709738)
		(end 288.449258 -224.110042)
		(width 0.14478)
		(layer "In6.Cu")
		(net "M_E_CPU0_SA_DQ<21>")
	)
	(segment
		(start 296.346626 -224.110042)
		(end 294.480742 -224.110042)
		(width 0.14478)
		(layer "In6.Cu")
		(net "M_E_CPU0_SA_DQ<21>")
	)
	(segment
		(start 302.024542 -224.110042)
		(end 301.174658 -223.260158)
		(width 0.14478)
		(layer "In6.Cu")
		(net "M_E_CPU0_SA_DQ<21>")
	)
	(segment
		(start 289.252406 -223.854518)
		(end 289.107626 -223.709738)
		(width 0.14478)
		(layer "In6.Cu")
		(net "M_E_CPU0_SA_DQ<21>")
	)
	(segment
		(start 282.975558 -223.840802)
		(end 282.706318 -224.110042)
		(width 0.14478)
		(layer "In6.Cu")
		(net "M_E_CPU0_SA_DQ<21>")
	)
	(segment
		(start 278.142192 -224.27311)
		(end 277.979124 -224.110042)
		(width 0.14478)
		(layer "In6.Cu")
		(net "M_E_CPU0_SA_DQ<21>")
	)
	(segment
		(start 282.379674 -224.110042)
		(end 282.216606 -224.27311)
		(width 0.14478)
		(layer "In6.Cu")
		(net "M_E_CPU0_SA_DQ<21>")
	)
	(segment
		(start 302.489616 -224.110042)
		(end 302.024542 -224.110042)
		(width 0.14478)
		(layer "In6.Cu")
		(net "M_E_CPU0_SA_DQ<21>")
	)
	(segment
		(start 303.209198 -224.27311)
		(end 303.209198 -224.333562)
		(width 0.14478)
		(layer "In6.Cu")
		(net "M_E_CPU0_SA_DQ<21>")
	)
	(segment
		(start 298.615862 -223.260158)
		(end 297.765978 -224.110042)
		(width 0.14478)
		(layer "In6.Cu")
		(net "M_E_CPU0_SA_DQ<21>")
	)
	(segment
		(start 303.602644 -224.110042)
		(end 303.372266 -224.110042)
		(width 0.14478)
		(layer "In6.Cu")
		(net "M_E_CPU0_SA_DQ<21>")
	)
	(segment
		(start 283.442918 -222.963232)
		(end 282.975558 -223.430592)
		(width 0.14478)
		(layer "In6.Cu")
		(net "M_E_CPU0_SA_DQ<21>")
	)
	(segment
		(start 306.706778 -223.423226)
		(end 306.356004 -223.072452)
		(width 0.14478)
		(layer "In6.Cu")
		(net "M_E_CPU0_SA_DQ<21>")
	)
	(segment
		(start 288.449258 -224.110042)
		(end 286.804862 -224.110042)
		(width 0.14478)
		(layer "In6.Cu")
		(net "M_E_CPU0_SA_DQ<21>")
	)
	(segment
		(start 278.698706 -223.899222)
		(end 278.698706 -224.320862)
		(width 0.14478)
		(layer "In6.Cu")
		(net "M_E_CPU0_SA_DQ<21>")
	)
	(segment
		(start 281.660092 -224.341182)
		(end 281.660092 -224.27311)
		(width 0.14478)
		(layer "In6.Cu")
		(net "M_E_CPU0_SA_DQ<21>")
	)
	(segment
		(start 297.066208 -224.27311)
		(end 297.066208 -224.333562)
		(width 0.14478)
		(layer "In6.Cu")
		(net "M_E_CPU0_SA_DQ<21>")
	)
	(segment
		(start 302.652684 -224.333562)
		(end 302.652684 -224.27311)
		(width 0.14478)
		(layer "In6.Cu")
		(net "M_E_CPU0_SA_DQ<21>")
	)
	(segment
		(start 289.816286 -224.360232)
		(end 289.671506 -224.505012)
		(width 0.14478)
		(layer "In6.Cu")
		(net "M_E_CPU0_SA_DQ<21>")
	)
	(segment
		(start 296.509694 -224.333562)
		(end 296.509694 -224.27311)
		(width 0.14478)
		(layer "In6.Cu")
		(net "M_E_CPU0_SA_DQ<21>")
	)
	(segment
		(start 311.188608 -227.98532)
		(end 311.188608 -227.156772)
		(width 0.14478)
		(layer "In6.Cu")
		(net "M_E_CPU0_SA_DQ<21>")
	)
	(segment
		(start 307.42636 -223.260158)
		(end 307.263292 -223.423226)
		(width 0.14478)
		(layer "In6.Cu")
		(net "M_E_CPU0_SA_DQ<21>")
	)
	(segment
		(start 281.660092 -224.27311)
		(end 281.497024 -224.110042)
		(width 0.14478)
		(layer "In6.Cu")
		(net "M_E_CPU0_SA_DQ<21>")
	)
	(segment
		(start 311.188608 -227.156772)
		(end 308.756558 -224.724722)
		(width 0.14478)
		(layer "In6.Cu")
		(net "M_E_CPU0_SA_DQ<21>")
	)
	(segment
		(start 279.092152 -223.736154)
		(end 278.861774 -223.736154)
		(width 0.14478)
		(layer "In6.Cu")
		(net "M_E_CPU0_SA_DQ<21>")
	)
	(segment
		(start 328.41819 -239.136682)
		(end 328.409808 -239.141508)
		(width 0.0889)
		(layer "In6.Cu")
		(net "M_E_CPU0_SA_DQ<21>")
	)
	(segment
		(start 282.706318 -224.110042)
		(end 282.379674 -224.110042)
		(width 0.14478)
		(layer "In6.Cu")
		(net "M_E_CPU0_SA_DQ<21>")
	)
	(segment
		(start 305.306984 -223.712532)
		(end 304.567844 -223.712532)
		(width 0.14478)
		(layer "In6.Cu")
		(net "M_E_CPU0_SA_DQ<21>")
	)
	(segment
		(start 304.322226 -224.333562)
		(end 304.159158 -224.49663)
		(width 0.14478)
		(layer "In6.Cu")
		(net "M_E_CPU0_SA_DQ<21>")
	)
	(segment
		(start 325.684134 -238.656114)
		(end 325.684134 -238.30915)
		(width 0.0889)
		(layer "In6.Cu")
		(net "M_E_CPU0_SA_DQ<21>")
	)
	(segment
		(start 278.142192 -224.320862)
		(end 278.142192 -224.27311)
		(width 0.14478)
		(layer "In6.Cu")
		(net "M_E_CPU0_SA_DQ<21>")
	)
	(segment
		(start 324.094094 -237.43793)
		(end 323.875654 -237.43793)
		(width 0.0889)
		(layer "In6.Cu")
		(net "M_E_CPU0_SA_DQ<21>")
	)
	(segment
		(start 303.765712 -224.333562)
		(end 303.765712 -224.27311)
		(width 0.14478)
		(layer "In6.Cu")
		(net "M_E_CPU0_SA_DQ<21>")
	)
	(segment
		(start 307.263292 -223.423226)
		(end 307.263292 -223.485202)
		(width 0.14478)
		(layer "In6.Cu")
		(net "M_E_CPU0_SA_DQ<21>")
	)
	(segment
		(start 308.756558 -223.984312)
		(end 308.420516 -223.64827)
		(width 0.14478)
		(layer "In6.Cu")
		(net "M_E_CPU0_SA_DQ<21>")
	)
	(segment
		(start 324.259194 -237.60303)
		(end 324.094094 -237.43793)
		(width 0.0889)
		(layer "In6.Cu")
		(net "M_E_CPU0_SA_DQ<21>")
	)
	(segment
		(start 279.25522 -223.899222)
		(end 279.092152 -223.736154)
		(width 0.14478)
		(layer "In6.Cu")
		(net "M_E_CPU0_SA_DQ<21>")
	)
	(segment
		(start 308.756558 -224.724722)
		(end 308.756558 -223.984312)
		(width 0.14478)
		(layer "In6.Cu")
		(net "M_E_CPU0_SA_DQ<21>")
	)
	(segment
		(start 285.954978 -223.260158)
		(end 284.346904 -223.260158)
		(width 0.14478)
		(layer "In6.Cu")
		(net "M_E_CPU0_SA_DQ<21>")
	)
	(segment
		(start 279.811734 -224.27311)
		(end 279.811734 -224.320862)
		(width 0.14478)
		(layer "In6.Cu")
		(net "M_E_CPU0_SA_DQ<21>")
	)
	(segment
		(start 326.164448 -239.136428)
		(end 325.684134 -238.656114)
		(width 0.0889)
		(layer "In6.Cu")
		(net "M_E_CPU0_SA_DQ<21>")
	)
	(segment
		(start 279.25522 -224.320862)
		(end 279.25522 -223.899222)
		(width 0.14478)
		(layer "In6.Cu")
		(net "M_E_CPU0_SA_DQ<21>")
	)
	(segment
		(start 282.053538 -224.50425)
		(end 281.82316 -224.50425)
		(width 0.14478)
		(layer "In6.Cu")
		(net "M_E_CPU0_SA_DQ<21>")
	)
	(segment
		(start 296.672762 -224.49663)
		(end 296.509694 -224.333562)
		(width 0.14478)
		(layer "In6.Cu")
		(net "M_E_CPU0_SA_DQ<21>")
	)
	(segment
		(start 303.372266 -224.110042)
		(end 303.209198 -224.27311)
		(width 0.14478)
		(layer "In6.Cu")
		(net "M_E_CPU0_SA_DQ<21>")
	)
	(segment
		(start 327.47839 -239.136682)
		(end 327.470008 -239.141508)
		(width 0.0889)
		(layer "In6.Cu")
		(net "M_E_CPU0_SA_DQ<21>")
	)
	(segment
		(start 289.252406 -224.360232)
		(end 289.252406 -223.854518)
		(width 0.14478)
		(layer "In6.Cu")
		(net "M_E_CPU0_SA_DQ<21>")
	)
	(segment
		(start 277.617174 -224.110042)
		(end 277.192232 -223.6851)
		(width 0.14478)
		(layer "In6.Cu")
		(net "M_E_CPU0_SA_DQ<21>")
	)
	(segment
		(start 324.978014 -237.60303)
		(end 324.259194 -237.60303)
		(width 0.0889)
		(layer "In6.Cu")
		(net "M_E_CPU0_SA_DQ<21>")
	)
	(segment
		(start 284.049978 -222.963232)
		(end 283.442918 -222.963232)
		(width 0.14478)
		(layer "In6.Cu")
		(net "M_E_CPU0_SA_DQ<21>")
	)
	(segment
		(start 302.815752 -224.49663)
		(end 302.652684 -224.333562)
		(width 0.14478)
		(layer "In6.Cu")
		(net "M_E_CPU0_SA_DQ<21>")
	)
	(segment
		(start 303.209198 -224.333562)
		(end 303.04613 -224.49663)
		(width 0.14478)
		(layer "In6.Cu")
		(net "M_E_CPU0_SA_DQ<21>")
	)
	(segment
		(start 314.230258 -231.02697)
		(end 311.188608 -227.98532)
		(width 0.14478)
		(layer "In6.Cu")
		(net "M_E_CPU0_SA_DQ<21>")
	)
	(segment
		(start 296.509694 -224.27311)
		(end 296.346626 -224.110042)
		(width 0.14478)
		(layer "In6.Cu")
		(net "M_E_CPU0_SA_DQ<21>")
	)
	(segment
		(start 282.216606 -224.341182)
		(end 282.053538 -224.50425)
		(width 0.14478)
		(layer "In6.Cu")
		(net "M_E_CPU0_SA_DQ<21>")
	)
	(segment
		(start 278.535638 -224.48393)
		(end 278.30526 -224.48393)
		(width 0.14478)
		(layer "In6.Cu")
		(net "M_E_CPU0_SA_DQ<21>")
	)
	(segment
		(start 330.1111 -238.814102)
		(end 330.265024 -239.079532)
		(width 0.0889)
		(layer "In6.Cu")
		(net "M_E_CPU0_SA_DQ<21>")
	)
	(segment
		(start 282.975558 -223.430592)
		(end 282.975558 -223.840802)
		(width 0.14478)
		(layer "In6.Cu")
		(net "M_E_CPU0_SA_DQ<21>")
	)
	(segment
		(start 289.961066 -223.709738)
		(end 289.816286 -223.854518)
		(width 0.14478)
		(layer "In6.Cu")
		(net "M_E_CPU0_SA_DQ<21>")
	)
	(segment
		(start 281.82316 -224.50425)
		(end 281.660092 -224.341182)
		(width 0.14478)
		(layer "In6.Cu")
		(net "M_E_CPU0_SA_DQ<21>")
	)
	(segment
		(start 289.671506 -224.505012)
		(end 289.397186 -224.505012)
		(width 0.14478)
		(layer "In6.Cu")
		(net "M_E_CPU0_SA_DQ<21>")
	)
	(segment
		(start 303.765712 -224.27311)
		(end 303.602644 -224.110042)
		(width 0.14478)
		(layer "In6.Cu")
		(net "M_E_CPU0_SA_DQ<21>")
	)
	(segment
		(start 306.706778 -223.485202)
		(end 306.706778 -223.423226)
		(width 0.14478)
		(layer "In6.Cu")
		(net "M_E_CPU0_SA_DQ<21>")
	)
	(segment
		(start 278.861774 -223.736154)
		(end 278.698706 -223.899222)
		(width 0.14478)
		(layer "In6.Cu")
		(net "M_E_CPU0_SA_DQ<21>")
	)
	(segment
		(start 303.92878 -224.49663)
		(end 303.765712 -224.333562)
		(width 0.14478)
		(layer "In6.Cu")
		(net "M_E_CPU0_SA_DQ<21>")
	)
	(segment
		(start 314.230258 -231.43083)
		(end 314.230258 -231.02697)
		(width 0.14478)
		(layer "In6.Cu")
		(net "M_E_CPU0_SA_DQ<21>")
	)
	(segment
		(start 305.947064 -223.072452)
		(end 305.306984 -223.712532)
		(width 0.14478)
		(layer "In6.Cu")
		(net "M_E_CPU0_SA_DQ<21>")
	)
	(segment
		(start 307.982874 -223.64827)
		(end 307.819806 -223.485202)
		(width 0.14478)
		(layer "In6.Cu")
		(net "M_E_CPU0_SA_DQ<21>")
	)
	(segment
		(start 330.265024 -239.079532)
		(end 330.242672 -239.162844)
		(width 0.0889)
		(layer "In6.Cu")
		(net "M_E_CPU0_SA_DQ<21>")
	)
	(segment
		(start 325.684134 -238.30915)
		(end 324.978014 -237.60303)
		(width 0.0889)
		(layer "In6.Cu")
		(net "M_E_CPU0_SA_DQ<21>")
	)
	(segment
		(start 284.346904 -223.260158)
		(end 284.049978 -222.963232)
		(width 0.14478)
		(layer "In6.Cu")
		(net "M_E_CPU0_SA_DQ<21>")
	)
	(segment
		(start 327.104756 -239.136682)
		(end 327.094342 -239.130586)
		(width 0.0889)
		(layer "In6.Cu")
		(net "M_E_CPU0_SA_DQ<21>")
	)
	(segment
		(start 279.811734 -224.320862)
		(end 279.648666 -224.48393)
		(width 0.14478)
		(layer "In6.Cu")
		(net "M_E_CPU0_SA_DQ<21>")
	)
	(segment
		(start 326.182736 -239.146842)
		(end 326.164448 -239.136428)
		(width 0.0889)
		(layer "In6.Cu")
		(net "M_E_CPU0_SA_DQ<21>")
	)
	(segment
		(start 282.216606 -224.27311)
		(end 282.216606 -224.341182)
		(width 0.14478)
		(layer "In6.Cu")
		(net "M_E_CPU0_SA_DQ<21>")
	)
	(segment
		(start 320.237358 -237.43793)
		(end 314.230258 -231.43083)
		(width 0.14478)
		(layer "In6.Cu")
		(net "M_E_CPU0_SA_DQ<21>")
	)
	(segment
		(start 306.356004 -223.072452)
		(end 305.947064 -223.072452)
		(width 0.14478)
		(layer "In6.Cu")
		(net "M_E_CPU0_SA_DQ<21>")
	)
	(segment
		(start 277.979124 -224.110042)
		(end 277.617174 -224.110042)
		(width 0.14478)
		(layer "In6.Cu")
		(net "M_E_CPU0_SA_DQ<21>")
	)
	(segment
		(start 302.652684 -224.27311)
		(end 302.489616 -224.110042)
		(width 0.14478)
		(layer "In6.Cu")
		(net "M_E_CPU0_SA_DQ<21>")
	)
	(segment
		(start 306.869846 -223.64827)
		(end 306.706778 -223.485202)
		(width 0.14478)
		(layer "In6.Cu")
		(net "M_E_CPU0_SA_DQ<21>")
	)
	(segment
		(start 297.765978 -224.110042)
		(end 297.229276 -224.110042)
		(width 0.14478)
		(layer "In6.Cu")
		(net "M_E_CPU0_SA_DQ<21>")
	)
	(arc
		(start 328.984102 -239.136682)
		(mid 328.701146 -239.060505)
		(end 328.41819 -239.136682)
		(width 0.0889)
		(layer "In6.Cu")
		(net "M_E_CPU0_SA_DQ<21>")
	)
	(arc
		(start 327.094342 -239.130586)
		(mid 326.815656 -239.060366)
		(end 326.53859 -239.136682)
		(width 0.0889)
		(layer "In6.Cu")
		(net "M_E_CPU0_SA_DQ<21>")
	)
	(arc
		(start 326.53859 -239.136682)
		(mid 326.361962 -239.186915)
		(end 326.182736 -239.146842)
		(width 0.0889)
		(layer "In6.Cu")
		(net "M_E_CPU0_SA_DQ<21>")
	)
	(arc
		(start 328.409808 -239.141508)
		(mid 328.2263 -239.187002)
		(end 328.044048 -239.136682)
		(width 0.0889)
		(layer "In6.Cu")
		(net "M_E_CPU0_SA_DQ<21>")
	)
	(arc
		(start 328.044048 -239.136682)
		(mid 327.767235 -239.060539)
		(end 327.488804 -239.130586)
		(width 0.0889)
		(layer "In6.Cu")
		(net "M_E_CPU0_SA_DQ<21>")
	)
	(arc
		(start 329.358244 -239.136682)
		(mid 329.175993 -239.187032)
		(end 328.992484 -239.141508)
		(width 0.0889)
		(layer "In6.Cu")
		(net "M_E_CPU0_SA_DQ<21>")
	)
	(arc
		(start 329.924156 -239.136682)
		(mid 329.6412 -239.060505)
		(end 329.358244 -239.136682)
		(width 0.0889)
		(layer "In6.Cu")
		(net "M_E_CPU0_SA_DQ<21>")
	)
	(arc
		(start 327.470008 -239.141508)
		(mid 327.286754 -239.186881)
		(end 327.104756 -239.136682)
		(width 0.0889)
		(layer "In6.Cu")
		(net "M_E_CPU0_SA_DQ<21>")
	)
	(arc
		(start 330.242672 -239.162844)
		(mid 330.080483 -239.185579)
		(end 329.924156 -239.136682)
		(width 0.0889)
		(layer "In6.Cu")
		(net "M_E_CPU0_SA_DQ<21>")
	)
	(segment
		(start 329.167998 -238.270034)
		(end 328.701146 -238.004096)
		(width 0.10668)
		(layer "F.Cu")
		(net "M_E_CPU0_SA_DQ<20>")
	)
	(segment
		(start 302.527208 -222.573088)
		(end 302.36414 -222.41002)
		(width 0.14478)
		(layer "In6.Cu")
		(net "M_E_CPU0_SA_DQ<20>")
	)
	(segment
		(start 304.19675 -222.573088)
		(end 304.19675 -222.631762)
		(width 0.14478)
		(layer "In6.Cu")
		(net "M_E_CPU0_SA_DQ<20>")
	)
	(segment
		(start 290.95065 -221.569788)
		(end 290.110418 -222.41002)
		(width 0.14478)
		(layer "In6.Cu")
		(net "M_E_CPU0_SA_DQ<20>")
	)
	(segment
		(start 318.321436 -233.955336)
		(end 318.069976 -233.703876)
		(width 0.14478)
		(layer "In6.Cu")
		(net "M_E_CPU0_SA_DQ<20>")
	)
	(segment
		(start 290.110418 -222.41002)
		(end 289.849306 -222.41002)
		(width 0.14478)
		(layer "In6.Cu")
		(net "M_E_CPU0_SA_DQ<20>")
	)
	(segment
		(start 316.474856 -232.108756)
		(end 316.180216 -232.108756)
		(width 0.14478)
		(layer "In6.Cu")
		(net "M_E_CPU0_SA_DQ<20>")
	)
	(segment
		(start 283.54655 -221.569788)
		(end 282.706318 -222.41002)
		(width 0.14478)
		(layer "In6.Cu")
		(net "M_E_CPU0_SA_DQ<20>")
	)
	(segment
		(start 316.180216 -232.108756)
		(end 315.928756 -231.857296)
		(width 0.14478)
		(layer "In6.Cu")
		(net "M_E_CPU0_SA_DQ<20>")
	)
	(segment
		(start 326.262746 -238.250476)
		(end 325.02602 -237.01375)
		(width 0.0889)
		(layer "In6.Cu")
		(net "M_E_CPU0_SA_DQ<20>")
	)
	(segment
		(start 319.665096 -235.298996)
		(end 319.370456 -235.298996)
		(width 0.14478)
		(layer "In6.Cu")
		(net "M_E_CPU0_SA_DQ<20>")
	)
	(segment
		(start 281.26182 -222.419672)
		(end 280.012902 -222.419672)
		(width 0.14478)
		(layer "In6.Cu")
		(net "M_E_CPU0_SA_DQ<20>")
	)
	(segment
		(start 308.663848 -222.61957)
		(end 308.663848 -222.257874)
		(width 0.14478)
		(layer "In6.Cu")
		(net "M_E_CPU0_SA_DQ<20>")
	)
	(segment
		(start 319.118996 -234.752896)
		(end 318.867536 -234.501436)
		(width 0.14478)
		(layer "In6.Cu")
		(net "M_E_CPU0_SA_DQ<20>")
	)
	(segment
		(start 281.415236 -222.639382)
		(end 281.415236 -222.573088)
		(width 0.14478)
		(layer "In6.Cu")
		(net "M_E_CPU0_SA_DQ<20>")
	)
	(segment
		(start 279.302972 -222.631762)
		(end 279.302972 -222.1865)
		(width 0.14478)
		(layer "In6.Cu")
		(net "M_E_CPU0_SA_DQ<20>")
	)
	(segment
		(start 325.02602 -237.01375)
		(end 324.609714 -237.01375)
		(width 0.0889)
		(layer "In6.Cu")
		(net "M_E_CPU0_SA_DQ<20>")
	)
	(segment
		(start 278.909526 -222.023432)
		(end 278.746458 -222.1865)
		(width 0.14478)
		(layer "In6.Cu")
		(net "M_E_CPU0_SA_DQ<20>")
	)
	(segment
		(start 315.928756 -231.562656)
		(end 315.677296 -231.311196)
		(width 0.14478)
		(layer "In6.Cu")
		(net "M_E_CPU0_SA_DQ<20>")
	)
	(segment
		(start 316.726316 -232.360216)
		(end 316.474856 -232.108756)
		(width 0.14478)
		(layer "In6.Cu")
		(net "M_E_CPU0_SA_DQ<20>")
	)
	(segment
		(start 315.677296 -231.311196)
		(end 315.382656 -231.311196)
		(width 0.14478)
		(layer "In6.Cu")
		(net "M_E_CPU0_SA_DQ<20>")
	)
	(segment
		(start 303.24679 -222.13951)
		(end 303.083722 -222.302578)
		(width 0.14478)
		(layer "In6.Cu")
		(net "M_E_CPU0_SA_DQ<20>")
	)
	(segment
		(start 309.721758 -224.200466)
		(end 309.721758 -223.67748)
		(width 0.14478)
		(layer "In6.Cu")
		(net "M_E_CPU0_SA_DQ<20>")
	)
	(segment
		(start 278.353012 -222.79483)
		(end 278.189944 -222.631762)
		(width 0.14478)
		(layer "In6.Cu")
		(net "M_E_CPU0_SA_DQ<20>")
	)
	(segment
		(start 319.916556 -235.845096)
		(end 319.916556 -235.550456)
		(width 0.14478)
		(layer "In6.Cu")
		(net "M_E_CPU0_SA_DQ<20>")
	)
	(segment
		(start 278.189944 -221.806008)
		(end 278.045164 -221.661228)
		(width 0.14478)
		(layer "In6.Cu")
		(net "M_E_CPU0_SA_DQ<20>")
	)
	(segment
		(start 309.721758 -223.67748)
		(end 309.443628 -223.39935)
		(width 0.14478)
		(layer "In6.Cu")
		(net "M_E_CPU0_SA_DQ<20>")
	)
	(segment
		(start 304.19675 -222.631762)
		(end 304.033682 -222.79483)
		(width 0.14478)
		(layer "In6.Cu")
		(net "M_E_CPU0_SA_DQ<20>")
	)
	(segment
		(start 309.053738 -222.804736)
		(end 308.849014 -222.804736)
		(width 0.14478)
		(layer "In6.Cu")
		(net "M_E_CPU0_SA_DQ<20>")
	)
	(segment
		(start 318.321436 -234.249976)
		(end 318.321436 -233.955336)
		(width 0.14478)
		(layer "In6.Cu")
		(net "M_E_CPU0_SA_DQ<20>")
	)
	(segment
		(start 279.302972 -222.1865)
		(end 279.139904 -222.023432)
		(width 0.14478)
		(layer "In6.Cu")
		(net "M_E_CPU0_SA_DQ<20>")
	)
	(segment
		(start 308.663848 -222.257874)
		(end 308.352444 -221.94647)
		(width 0.14478)
		(layer "In6.Cu")
		(net "M_E_CPU0_SA_DQ<20>")
	)
	(segment
		(start 303.640236 -222.631762)
		(end 303.640236 -222.302578)
		(width 0.14478)
		(layer "In6.Cu")
		(net "M_E_CPU0_SA_DQ<20>")
	)
	(segment
		(start 294.39235 -222.419672)
		(end 293.542466 -221.569788)
		(width 0.14478)
		(layer "In6.Cu")
		(net "M_E_CPU0_SA_DQ<20>")
	)
	(segment
		(start 281.97175 -222.639382)
		(end 281.808682 -222.80245)
		(width 0.14478)
		(layer "In6.Cu")
		(net "M_E_CPU0_SA_DQ<20>")
	)
	(segment
		(start 319.916556 -235.550456)
		(end 319.665096 -235.298996)
		(width 0.14478)
		(layer "In6.Cu")
		(net "M_E_CPU0_SA_DQ<20>")
	)
	(segment
		(start 328.85507 -238.269526)
		(end 328.832718 -238.352838)
		(width 0.0889)
		(layer "In6.Cu")
		(net "M_E_CPU0_SA_DQ<20>")
	)
	(segment
		(start 289.686238 -222.573088)
		(end 289.686238 -222.631762)
		(width 0.14478)
		(layer "In6.Cu")
		(net "M_E_CPU0_SA_DQ<20>")
	)
	(segment
		(start 309.443628 -223.39935)
		(end 309.443628 -223.194626)
		(width 0.14478)
		(layer "In6.Cu")
		(net "M_E_CPU0_SA_DQ<20>")
	)
	(segment
		(start 309.443628 -223.194626)
		(end 309.739538 -222.898716)
		(width 0.14478)
		(layer "In6.Cu")
		(net "M_E_CPU0_SA_DQ<20>")
	)
	(segment
		(start 317.775336 -233.703876)
		(end 317.523876 -233.452416)
		(width 0.14478)
		(layer "In6.Cu")
		(net "M_E_CPU0_SA_DQ<20>")
	)
	(segment
		(start 296.46372 -222.419672)
		(end 294.39235 -222.419672)
		(width 0.14478)
		(layer "In6.Cu")
		(net "M_E_CPU0_SA_DQ<20>")
	)
	(segment
		(start 279.46604 -222.79483)
		(end 279.302972 -222.631762)
		(width 0.14478)
		(layer "In6.Cu")
		(net "M_E_CPU0_SA_DQ<20>")
	)
	(segment
		(start 304.359818 -222.41002)
		(end 304.19675 -222.573088)
		(width 0.14478)
		(layer "In6.Cu")
		(net "M_E_CPU0_SA_DQ<20>")
	)
	(segment
		(start 315.928756 -231.857296)
		(end 315.928756 -231.562656)
		(width 0.14478)
		(layer "In6.Cu")
		(net "M_E_CPU0_SA_DQ<20>")
	)
	(segment
		(start 308.352444 -221.94647)
		(end 305.773328 -221.94647)
		(width 0.14478)
		(layer "In6.Cu")
		(net "M_E_CPU0_SA_DQ<20>")
	)
	(segment
		(start 305.309778 -222.41002)
		(end 304.359818 -222.41002)
		(width 0.14478)
		(layer "In6.Cu")
		(net "M_E_CPU0_SA_DQ<20>")
	)
	(segment
		(start 303.477168 -222.13951)
		(end 303.24679 -222.13951)
		(width 0.14478)
		(layer "In6.Cu")
		(net "M_E_CPU0_SA_DQ<20>")
	)
	(segment
		(start 318.069976 -233.703876)
		(end 317.775336 -233.703876)
		(width 0.14478)
		(layer "In6.Cu")
		(net "M_E_CPU0_SA_DQ<20>")
	)
	(segment
		(start 297.765978 -222.41002)
		(end 297.336718 -222.41002)
		(width 0.14478)
		(layer "In6.Cu")
		(net "M_E_CPU0_SA_DQ<20>")
	)
	(segment
		(start 324.124574 -236.52861)
		(end 323.883274 -236.52861)
		(width 0.0889)
		(layer "In6.Cu")
		(net "M_E_CPU0_SA_DQ<20>")
	)
	(segment
		(start 297.336718 -222.41002)
		(end 297.17365 -222.573088)
		(width 0.14478)
		(layer "In6.Cu")
		(net "M_E_CPU0_SA_DQ<20>")
	)
	(segment
		(start 327.017888 -238.32058)
		(end 327.007474 -238.326676)
		(width 0.0889)
		(layer "In6.Cu")
		(net "M_E_CPU0_SA_DQ<20>")
	)
	(segment
		(start 302.920654 -222.79483)
		(end 302.690276 -222.79483)
		(width 0.14478)
		(layer "In6.Cu")
		(net "M_E_CPU0_SA_DQ<20>")
	)
	(segment
		(start 279.859486 -222.631762)
		(end 279.696418 -222.79483)
		(width 0.14478)
		(layer "In6.Cu")
		(net "M_E_CPU0_SA_DQ<20>")
	)
	(segment
		(start 282.706318 -222.41002)
		(end 282.134818 -222.41002)
		(width 0.14478)
		(layer "In6.Cu")
		(net "M_E_CPU0_SA_DQ<20>")
	)
	(segment
		(start 279.859486 -222.573088)
		(end 279.859486 -222.631762)
		(width 0.14478)
		(layer "In6.Cu")
		(net "M_E_CPU0_SA_DQ<20>")
	)
	(segment
		(start 323.883274 -236.52861)
		(end 320.60007 -236.52861)
		(width 0.14478)
		(layer "In6.Cu")
		(net "M_E_CPU0_SA_DQ<20>")
	)
	(segment
		(start 293.542466 -221.569788)
		(end 290.95065 -221.569788)
		(width 0.14478)
		(layer "In6.Cu")
		(net "M_E_CPU0_SA_DQ<20>")
	)
	(segment
		(start 281.415236 -222.573088)
		(end 281.26182 -222.419672)
		(width 0.14478)
		(layer "In6.Cu")
		(net "M_E_CPU0_SA_DQ<20>")
	)
	(segment
		(start 289.686238 -222.631762)
		(end 289.52317 -222.79483)
		(width 0.14478)
		(layer "In6.Cu")
		(net "M_E_CPU0_SA_DQ<20>")
	)
	(segment
		(start 320.60007 -236.52861)
		(end 319.916556 -235.845096)
		(width 0.14478)
		(layer "In6.Cu")
		(net "M_E_CPU0_SA_DQ<20>")
	)
	(segment
		(start 312.087768 -227.598224)
		(end 312.087768 -226.566476)
		(width 0.14478)
		(layer "In6.Cu")
		(net "M_E_CPU0_SA_DQ<20>")
	)
	(segment
		(start 309.349648 -222.508826)
		(end 309.053738 -222.804736)
		(width 0.14478)
		(layer "In6.Cu")
		(net "M_E_CPU0_SA_DQ<20>")
	)
	(segment
		(start 301.852838 -222.41002)
		(end 301.012606 -221.569788)
		(width 0.14478)
		(layer "In6.Cu")
		(net "M_E_CPU0_SA_DQ<20>")
	)
	(segment
		(start 316.726316 -232.654856)
		(end 316.726316 -232.360216)
		(width 0.14478)
		(layer "In6.Cu")
		(net "M_E_CPU0_SA_DQ<20>")
	)
	(segment
		(start 301.012606 -221.569788)
		(end 298.60621 -221.569788)
		(width 0.14478)
		(layer "In6.Cu")
		(net "M_E_CPU0_SA_DQ<20>")
	)
	(segment
		(start 277.516082 -221.661228)
		(end 277.192232 -221.985078)
		(width 0.14478)
		(layer "In6.Cu")
		(net "M_E_CPU0_SA_DQ<20>")
	)
	(segment
		(start 303.803304 -222.79483)
		(end 303.640236 -222.631762)
		(width 0.14478)
		(layer "In6.Cu")
		(net "M_E_CPU0_SA_DQ<20>")
	)
	(segment
		(start 280.012902 -222.419672)
		(end 279.859486 -222.573088)
		(width 0.14478)
		(layer "In6.Cu")
		(net "M_E_CPU0_SA_DQ<20>")
	)
	(segment
		(start 319.370456 -235.298996)
		(end 319.118996 -235.047536)
		(width 0.14478)
		(layer "In6.Cu")
		(net "M_E_CPU0_SA_DQ<20>")
	)
	(segment
		(start 282.134818 -222.41002)
		(end 281.97175 -222.573088)
		(width 0.14478)
		(layer "In6.Cu")
		(net "M_E_CPU0_SA_DQ<20>")
	)
	(segment
		(start 328.701146 -238.004096)
		(end 328.85507 -238.269526)
		(width 0.0889)
		(layer "In6.Cu")
		(net "M_E_CPU0_SA_DQ<20>")
	)
	(segment
		(start 317.523876 -233.157776)
		(end 317.272416 -232.906316)
		(width 0.14478)
		(layer "In6.Cu")
		(net "M_E_CPU0_SA_DQ<20>")
	)
	(segment
		(start 278.045164 -221.661228)
		(end 277.516082 -221.661228)
		(width 0.14478)
		(layer "In6.Cu")
		(net "M_E_CPU0_SA_DQ<20>")
	)
	(segment
		(start 303.083722 -222.631762)
		(end 302.920654 -222.79483)
		(width 0.14478)
		(layer "In6.Cu")
		(net "M_E_CPU0_SA_DQ<20>")
	)
	(segment
		(start 317.272416 -232.906316)
		(end 316.977776 -232.906316)
		(width 0.14478)
		(layer "In6.Cu")
		(net "M_E_CPU0_SA_DQ<20>")
	)
	(segment
		(start 326.649842 -238.33582)
		(end 326.633586 -238.326422)
		(width 0.0889)
		(layer "In6.Cu")
		(net "M_E_CPU0_SA_DQ<20>")
	)
	(segment
		(start 296.617136 -222.573088)
		(end 296.46372 -222.419672)
		(width 0.14478)
		(layer "In6.Cu")
		(net "M_E_CPU0_SA_DQ<20>")
	)
	(segment
		(start 279.139904 -222.023432)
		(end 278.909526 -222.023432)
		(width 0.14478)
		(layer "In6.Cu")
		(net "M_E_CPU0_SA_DQ<20>")
	)
	(segment
		(start 309.739538 -222.898716)
		(end 309.739538 -222.693992)
		(width 0.14478)
		(layer "In6.Cu")
		(net "M_E_CPU0_SA_DQ<20>")
	)
	(segment
		(start 296.617136 -222.639382)
		(end 296.617136 -222.573088)
		(width 0.14478)
		(layer "In6.Cu")
		(net "M_E_CPU0_SA_DQ<20>")
	)
	(segment
		(start 279.696418 -222.79483)
		(end 279.46604 -222.79483)
		(width 0.14478)
		(layer "In6.Cu")
		(net "M_E_CPU0_SA_DQ<20>")
	)
	(segment
		(start 278.58339 -222.79483)
		(end 278.353012 -222.79483)
		(width 0.14478)
		(layer "In6.Cu")
		(net "M_E_CPU0_SA_DQ<20>")
	)
	(segment
		(start 319.118996 -235.047536)
		(end 319.118996 -234.752896)
		(width 0.14478)
		(layer "In6.Cu")
		(net "M_E_CPU0_SA_DQ<20>")
	)
	(segment
		(start 315.144658 -230.655114)
		(end 312.087768 -227.598224)
		(width 0.14478)
		(layer "In6.Cu")
		(net "M_E_CPU0_SA_DQ<20>")
	)
	(segment
		(start 297.17365 -222.573088)
		(end 297.17365 -222.639382)
		(width 0.14478)
		(layer "In6.Cu")
		(net "M_E_CPU0_SA_DQ<20>")
	)
	(segment
		(start 318.867536 -234.501436)
		(end 318.572896 -234.501436)
		(width 0.14478)
		(layer "In6.Cu")
		(net "M_E_CPU0_SA_DQ<20>")
	)
	(segment
		(start 289.292792 -222.79483)
		(end 288.917634 -222.419672)
		(width 0.14478)
		(layer "In6.Cu")
		(net "M_E_CPU0_SA_DQ<20>")
	)
	(segment
		(start 315.382656 -231.311196)
		(end 315.144658 -231.073198)
		(width 0.14478)
		(layer "In6.Cu")
		(net "M_E_CPU0_SA_DQ<20>")
	)
	(segment
		(start 327.94829 -238.326676)
		(end 327.939908 -238.331502)
		(width 0.0889)
		(layer "In6.Cu")
		(net "M_E_CPU0_SA_DQ<20>")
	)
	(segment
		(start 302.690276 -222.79483)
		(end 302.527208 -222.631762)
		(width 0.14478)
		(layer "In6.Cu")
		(net "M_E_CPU0_SA_DQ<20>")
	)
	(segment
		(start 303.640236 -222.302578)
		(end 303.477168 -222.13951)
		(width 0.14478)
		(layer "In6.Cu")
		(net "M_E_CPU0_SA_DQ<20>")
	)
	(segment
		(start 288.917634 -222.419672)
		(end 286.814514 -222.419672)
		(width 0.14478)
		(layer "In6.Cu")
		(net "M_E_CPU0_SA_DQ<20>")
	)
	(segment
		(start 296.780204 -222.80245)
		(end 296.617136 -222.639382)
		(width 0.14478)
		(layer "In6.Cu")
		(net "M_E_CPU0_SA_DQ<20>")
	)
	(segment
		(start 302.36414 -222.41002)
		(end 301.852838 -222.41002)
		(width 0.14478)
		(layer "In6.Cu")
		(net "M_E_CPU0_SA_DQ<20>")
	)
	(segment
		(start 312.087768 -226.566476)
		(end 309.721758 -224.200466)
		(width 0.14478)
		(layer "In6.Cu")
		(net "M_E_CPU0_SA_DQ<20>")
	)
	(segment
		(start 289.52317 -222.79483)
		(end 289.292792 -222.79483)
		(width 0.14478)
		(layer "In6.Cu")
		(net "M_E_CPU0_SA_DQ<20>")
	)
	(segment
		(start 309.739538 -222.693992)
		(end 309.554372 -222.508826)
		(width 0.14478)
		(layer "In6.Cu")
		(net "M_E_CPU0_SA_DQ<20>")
	)
	(segment
		(start 317.523876 -233.452416)
		(end 317.523876 -233.157776)
		(width 0.14478)
		(layer "In6.Cu")
		(net "M_E_CPU0_SA_DQ<20>")
	)
	(segment
		(start 326.351646 -238.250476)
		(end 326.262746 -238.250476)
		(width 0.0889)
		(layer "In6.Cu")
		(net "M_E_CPU0_SA_DQ<20>")
	)
	(segment
		(start 304.033682 -222.79483)
		(end 303.803304 -222.79483)
		(width 0.14478)
		(layer "In6.Cu")
		(net "M_E_CPU0_SA_DQ<20>")
	)
	(segment
		(start 316.977776 -232.906316)
		(end 316.726316 -232.654856)
		(width 0.14478)
		(layer "In6.Cu")
		(net "M_E_CPU0_SA_DQ<20>")
	)
	(segment
		(start 318.572896 -234.501436)
		(end 318.321436 -234.249976)
		(width 0.14478)
		(layer "In6.Cu")
		(net "M_E_CPU0_SA_DQ<20>")
	)
	(segment
		(start 278.746458 -222.1865)
		(end 278.746458 -222.631762)
		(width 0.14478)
		(layer "In6.Cu")
		(net "M_E_CPU0_SA_DQ<20>")
	)
	(segment
		(start 324.609714 -237.01375)
		(end 324.124574 -236.52861)
		(width 0.0889)
		(layer "In6.Cu")
		(net "M_E_CPU0_SA_DQ<20>")
	)
	(segment
		(start 281.97175 -222.573088)
		(end 281.97175 -222.639382)
		(width 0.14478)
		(layer "In6.Cu")
		(net "M_E_CPU0_SA_DQ<20>")
	)
	(segment
		(start 278.189944 -222.631762)
		(end 278.189944 -221.806008)
		(width 0.14478)
		(layer "In6.Cu")
		(net "M_E_CPU0_SA_DQ<20>")
	)
	(segment
		(start 302.527208 -222.631762)
		(end 302.527208 -222.573088)
		(width 0.14478)
		(layer "In6.Cu")
		(net "M_E_CPU0_SA_DQ<20>")
	)
	(segment
		(start 289.849306 -222.41002)
		(end 289.686238 -222.573088)
		(width 0.14478)
		(layer "In6.Cu")
		(net "M_E_CPU0_SA_DQ<20>")
	)
	(segment
		(start 309.554372 -222.508826)
		(end 309.349648 -222.508826)
		(width 0.14478)
		(layer "In6.Cu")
		(net "M_E_CPU0_SA_DQ<20>")
	)
	(segment
		(start 281.808682 -222.80245)
		(end 281.578304 -222.80245)
		(width 0.14478)
		(layer "In6.Cu")
		(net "M_E_CPU0_SA_DQ<20>")
	)
	(segment
		(start 297.17365 -222.639382)
		(end 297.010582 -222.80245)
		(width 0.14478)
		(layer "In6.Cu")
		(net "M_E_CPU0_SA_DQ<20>")
	)
	(segment
		(start 285.96463 -221.569788)
		(end 283.54655 -221.569788)
		(width 0.14478)
		(layer "In6.Cu")
		(net "M_E_CPU0_SA_DQ<20>")
	)
	(segment
		(start 286.814514 -222.419672)
		(end 285.96463 -221.569788)
		(width 0.14478)
		(layer "In6.Cu")
		(net "M_E_CPU0_SA_DQ<20>")
	)
	(segment
		(start 281.578304 -222.80245)
		(end 281.415236 -222.639382)
		(width 0.14478)
		(layer "In6.Cu")
		(net "M_E_CPU0_SA_DQ<20>")
	)
	(segment
		(start 315.144658 -231.073198)
		(end 315.144658 -230.655114)
		(width 0.14478)
		(layer "In6.Cu")
		(net "M_E_CPU0_SA_DQ<20>")
	)
	(segment
		(start 297.010582 -222.80245)
		(end 296.780204 -222.80245)
		(width 0.14478)
		(layer "In6.Cu")
		(net "M_E_CPU0_SA_DQ<20>")
	)
	(segment
		(start 303.083722 -222.302578)
		(end 303.083722 -222.631762)
		(width 0.14478)
		(layer "In6.Cu")
		(net "M_E_CPU0_SA_DQ<20>")
	)
	(segment
		(start 278.746458 -222.631762)
		(end 278.58339 -222.79483)
		(width 0.14478)
		(layer "In6.Cu")
		(net "M_E_CPU0_SA_DQ<20>")
	)
	(segment
		(start 298.60621 -221.569788)
		(end 297.765978 -222.41002)
		(width 0.14478)
		(layer "In6.Cu")
		(net "M_E_CPU0_SA_DQ<20>")
	)
	(segment
		(start 305.773328 -221.94647)
		(end 305.309778 -222.41002)
		(width 0.14478)
		(layer "In6.Cu")
		(net "M_E_CPU0_SA_DQ<20>")
	)
	(segment
		(start 308.849014 -222.804736)
		(end 308.663848 -222.61957)
		(width 0.14478)
		(layer "In6.Cu")
		(net "M_E_CPU0_SA_DQ<20>")
	)
	(arc
		(start 327.939908 -238.331502)
		(mid 327.756146 -238.377118)
		(end 327.57364 -238.326676)
		(width 0.0889)
		(layer "In6.Cu")
		(net "M_E_CPU0_SA_DQ<20>")
	)
	(arc
		(start 326.383396 -238.251238)
		(mid 326.367526 -238.250631)
		(end 326.351646 -238.250476)
		(width 0.0889)
		(layer "In6.Cu")
		(net "M_E_CPU0_SA_DQ<20>")
	)
	(arc
		(start 328.514202 -238.326676)
		(mid 328.231246 -238.250499)
		(end 327.94829 -238.326676)
		(width 0.0889)
		(layer "In6.Cu")
		(net "M_E_CPU0_SA_DQ<20>")
	)
	(arc
		(start 326.633586 -238.326422)
		(mid 326.512911 -238.274114)
		(end 326.383396 -238.251238)
		(width 0.0889)
		(layer "In6.Cu")
		(net "M_E_CPU0_SA_DQ<20>")
	)
	(arc
		(start 328.832718 -238.352838)
		(mid 328.670529 -238.375573)
		(end 328.514202 -238.326676)
		(width 0.0889)
		(layer "In6.Cu")
		(net "M_E_CPU0_SA_DQ<20>")
	)
	(arc
		(start 327.007474 -238.326676)
		(mid 326.829824 -238.376936)
		(end 326.649842 -238.33582)
		(width 0.0889)
		(layer "In6.Cu")
		(net "M_E_CPU0_SA_DQ<20>")
	)
	(arc
		(start 327.57364 -238.326676)
		(mid 327.296573 -238.250405)
		(end 327.017888 -238.32058)
		(width 0.0889)
		(layer "In6.Cu")
		(net "M_E_CPU0_SA_DQ<20>")
	)
	(segment
		(start 330.577952 -226.120198)
		(end 330.1111 -225.85426)
		(width 0.10668)
		(layer "F.Cu")
		(net "M_E_CPU0_SA_DQ<1>")
	)
	(segment
		(start 327.573894 -225.366834)
		(end 327.543414 -225.349054)
		(width 0.0889)
		(layer "In6.Cu")
		(net "M_E_CPU0_SA_DQ<1>")
	)
	(segment
		(start 316.26683 -206.693262)
		(end 316.55766 -206.402432)
		(width 0.14478)
		(layer "In6.Cu")
		(net "M_E_CPU0_SA_DQ<1>")
	)
	(segment
		(start 316.557406 -206.197708)
		(end 316.36335 -206.003652)
		(width 0.14478)
		(layer "In6.Cu")
		(net "M_E_CPU0_SA_DQ<1>")
	)
	(segment
		(start 308.791864 -198.940928)
		(end 308.647084 -199.085708)
		(width 0.14478)
		(layer "In6.Cu")
		(net "M_E_CPU0_SA_DQ<1>")
	)
	(segment
		(start 326.463914 -221.26067)
		(end 324.033134 -218.82989)
		(width 0.14478)
		(layer "In6.Cu")
		(net "M_E_CPU0_SA_DQ<1>")
	)
	(segment
		(start 324.033134 -214.66429)
		(end 316.26683 -206.897986)
		(width 0.14478)
		(layer "In6.Cu")
		(net "M_E_CPU0_SA_DQ<1>")
	)
	(segment
		(start 316.158626 -206.003652)
		(end 315.867796 -206.294482)
		(width 0.14478)
		(layer "In6.Cu")
		(net "M_E_CPU0_SA_DQ<1>")
	)
	(segment
		(start 308.502304 -200.085452)
		(end 308.227984 -200.085452)
		(width 0.14478)
		(layer "In6.Cu")
		(net "M_E_CPU0_SA_DQ<1>")
	)
	(segment
		(start 315.46927 -205.895702)
		(end 315.7601 -205.604872)
		(width 0.14478)
		(layer "In6.Cu")
		(net "M_E_CPU0_SA_DQ<1>")
	)
	(segment
		(start 327.610724 -223.767904)
		(end 327.574402 -223.746822)
		(width 0.0889)
		(layer "In6.Cu")
		(net "M_E_CPU0_SA_DQ<1>")
	)
	(segment
		(start 328.41819 -226.17684)
		(end 328.409808 -226.181666)
		(width 0.0889)
		(layer "In6.Cu")
		(net "M_E_CPU0_SA_DQ<1>")
	)
	(segment
		(start 327.104248 -222.936816)
		(end 327.073768 -222.919036)
		(width 0.0889)
		(layer "In6.Cu")
		(net "M_E_CPU0_SA_DQ<1>")
	)
	(segment
		(start 285.954978 -198.61022)
		(end 283.248862 -198.61022)
		(width 0.14478)
		(layer "In6.Cu")
		(net "M_E_CPU0_SA_DQ<1>")
	)
	(segment
		(start 297.527218 -199.460104)
		(end 294.480742 -199.460104)
		(width 0.14478)
		(layer "In6.Cu")
		(net "M_E_CPU0_SA_DQ<1>")
	)
	(segment
		(start 302.024542 -199.460104)
		(end 301.174658 -198.61022)
		(width 0.14478)
		(layer "In6.Cu")
		(net "M_E_CPU0_SA_DQ<1>")
	)
	(segment
		(start 327.61301 -225.389694)
		(end 327.573894 -225.366834)
		(width 0.0889)
		(layer "In6.Cu")
		(net "M_E_CPU0_SA_DQ<1>")
	)
	(segment
		(start 308.083204 -199.940672)
		(end 308.083204 -199.085708)
		(width 0.14478)
		(layer "In6.Cu")
		(net "M_E_CPU0_SA_DQ<1>")
	)
	(segment
		(start 315.66358 -206.294736)
		(end 315.46927 -206.100426)
		(width 0.14478)
		(layer "In6.Cu")
		(net "M_E_CPU0_SA_DQ<1>")
	)
	(segment
		(start 315.361066 -205.206092)
		(end 315.070236 -205.496922)
		(width 0.14478)
		(layer "In6.Cu")
		(net "M_E_CPU0_SA_DQ<1>")
	)
	(segment
		(start 326.672194 -222.148654)
		(end 326.595232 -222.104204)
		(width 0.0889)
		(layer "In6.Cu")
		(net "M_E_CPU0_SA_DQ<1>")
	)
	(segment
		(start 307.938424 -198.940928)
		(end 305.590194 -198.940928)
		(width 0.14478)
		(layer "In6.Cu")
		(net "M_E_CPU0_SA_DQ<1>")
	)
	(segment
		(start 316.36335 -206.003652)
		(end 316.158626 -206.003652)
		(width 0.14478)
		(layer "In6.Cu")
		(net "M_E_CPU0_SA_DQ<1>")
	)
	(segment
		(start 308.227984 -200.085452)
		(end 308.083204 -199.940672)
		(width 0.14478)
		(layer "In6.Cu")
		(net "M_E_CPU0_SA_DQ<1>")
	)
	(segment
		(start 327.542398 -224.739962)
		(end 327.574148 -224.721674)
		(width 0.0889)
		(layer "In6.Cu")
		(net "M_E_CPU0_SA_DQ<1>")
	)
	(segment
		(start 308.647084 -199.940672)
		(end 308.502304 -200.085452)
		(width 0.14478)
		(layer "In6.Cu")
		(net "M_E_CPU0_SA_DQ<1>")
	)
	(segment
		(start 315.759846 -205.400148)
		(end 315.56579 -205.206092)
		(width 0.14478)
		(layer "In6.Cu")
		(net "M_E_CPU0_SA_DQ<1>")
	)
	(segment
		(start 314.86602 -205.497176)
		(end 314.617354 -205.24851)
		(width 0.14478)
		(layer "In6.Cu")
		(net "M_E_CPU0_SA_DQ<1>")
	)
	(segment
		(start 305.590194 -198.940928)
		(end 305.071018 -199.460104)
		(width 0.14478)
		(layer "In6.Cu")
		(net "M_E_CPU0_SA_DQ<1>")
	)
	(segment
		(start 286.804862 -199.460104)
		(end 285.954978 -198.61022)
		(width 0.14478)
		(layer "In6.Cu")
		(net "M_E_CPU0_SA_DQ<1>")
	)
	(segment
		(start 326.595232 -222.104204)
		(end 326.463914 -221.972886)
		(width 0.0889)
		(layer "In6.Cu")
		(net "M_E_CPU0_SA_DQ<1>")
	)
	(segment
		(start 290.795202 -198.61022)
		(end 289.945318 -199.460104)
		(width 0.14478)
		(layer "In6.Cu")
		(net "M_E_CPU0_SA_DQ<1>")
	)
	(segment
		(start 315.070236 -205.496922)
		(end 314.86602 -205.497176)
		(width 0.14478)
		(layer "In6.Cu")
		(net "M_E_CPU0_SA_DQ<1>")
	)
	(segment
		(start 316.55766 -206.402432)
		(end 316.557406 -206.197708)
		(width 0.14478)
		(layer "In6.Cu")
		(net "M_E_CPU0_SA_DQ<1>")
	)
	(segment
		(start 293.630858 -198.61022)
		(end 290.795202 -198.61022)
		(width 0.14478)
		(layer "In6.Cu")
		(net "M_E_CPU0_SA_DQ<1>")
	)
	(segment
		(start 327.856596 -225.85426)
		(end 327.856342 -225.85426)
		(width 0.0889)
		(layer "In6.Cu")
		(net "M_E_CPU0_SA_DQ<1>")
	)
	(segment
		(start 308.083204 -199.085708)
		(end 307.938424 -198.940928)
		(width 0.14478)
		(layer "In6.Cu")
		(net "M_E_CPU0_SA_DQ<1>")
	)
	(segment
		(start 328.044048 -226.17684)
		(end 328.013568 -226.15906)
		(width 0.0889)
		(layer "In6.Cu")
		(net "M_E_CPU0_SA_DQ<1>")
	)
	(segment
		(start 283.248862 -198.61022)
		(end 282.398978 -199.460104)
		(width 0.14478)
		(layer "In6.Cu")
		(net "M_E_CPU0_SA_DQ<1>")
	)
	(segment
		(start 327.574148 -224.721674)
		(end 327.611994 -224.69983)
		(width 0.0889)
		(layer "In6.Cu")
		(net "M_E_CPU0_SA_DQ<1>")
	)
	(segment
		(start 326.463914 -221.972886)
		(end 326.463914 -221.26067)
		(width 0.0889)
		(layer "In6.Cu")
		(net "M_E_CPU0_SA_DQ<1>")
	)
	(segment
		(start 301.174658 -198.61022)
		(end 298.377102 -198.61022)
		(width 0.14478)
		(layer "In6.Cu")
		(net "M_E_CPU0_SA_DQ<1>")
	)
	(segment
		(start 289.945318 -199.460104)
		(end 286.804862 -199.460104)
		(width 0.14478)
		(layer "In6.Cu")
		(net "M_E_CPU0_SA_DQ<1>")
	)
	(segment
		(start 305.071018 -199.460104)
		(end 302.024542 -199.460104)
		(width 0.14478)
		(layer "In6.Cu")
		(net "M_E_CPU0_SA_DQ<1>")
	)
	(segment
		(start 315.46927 -206.100426)
		(end 315.46927 -205.895702)
		(width 0.14478)
		(layer "In6.Cu")
		(net "M_E_CPU0_SA_DQ<1>")
	)
	(segment
		(start 330.1111 -225.85426)
		(end 330.265024 -226.11969)
		(width 0.0889)
		(layer "In6.Cu")
		(net "M_E_CPU0_SA_DQ<1>")
	)
	(segment
		(start 314.617354 -205.24851)
		(end 314.617354 -204.301344)
		(width 0.14478)
		(layer "In6.Cu")
		(net "M_E_CPU0_SA_DQ<1>")
	)
	(segment
		(start 277.617174 -199.460104)
		(end 277.192232 -199.035162)
		(width 0.14478)
		(layer "In6.Cu")
		(net "M_E_CPU0_SA_DQ<1>")
	)
	(segment
		(start 315.56579 -205.206092)
		(end 315.361066 -205.206092)
		(width 0.14478)
		(layer "In6.Cu")
		(net "M_E_CPU0_SA_DQ<1>")
	)
	(segment
		(start 294.480742 -199.460104)
		(end 293.630858 -198.61022)
		(width 0.14478)
		(layer "In6.Cu")
		(net "M_E_CPU0_SA_DQ<1>")
	)
	(segment
		(start 316.26683 -206.897986)
		(end 316.26683 -206.693262)
		(width 0.14478)
		(layer "In6.Cu")
		(net "M_E_CPU0_SA_DQ<1>")
	)
	(segment
		(start 328.992484 -226.181666)
		(end 328.984102 -226.17684)
		(width 0.0889)
		(layer "In6.Cu")
		(net "M_E_CPU0_SA_DQ<1>")
	)
	(segment
		(start 327.14184 -222.95866)
		(end 327.104248 -222.936816)
		(width 0.0889)
		(layer "In6.Cu")
		(net "M_E_CPU0_SA_DQ<1>")
	)
	(segment
		(start 315.7601 -205.604872)
		(end 315.759846 -205.400148)
		(width 0.14478)
		(layer "In6.Cu")
		(net "M_E_CPU0_SA_DQ<1>")
	)
	(segment
		(start 314.617354 -204.301344)
		(end 309.256938 -198.940928)
		(width 0.14478)
		(layer "In6.Cu")
		(net "M_E_CPU0_SA_DQ<1>")
	)
	(segment
		(start 330.265024 -226.11969)
		(end 330.242672 -226.203002)
		(width 0.0889)
		(layer "In6.Cu")
		(net "M_E_CPU0_SA_DQ<1>")
	)
	(segment
		(start 327.574402 -223.746822)
		(end 327.54062 -223.727264)
		(width 0.0889)
		(layer "In6.Cu")
		(net "M_E_CPU0_SA_DQ<1>")
	)
	(segment
		(start 282.398978 -199.460104)
		(end 277.617174 -199.460104)
		(width 0.14478)
		(layer "In6.Cu")
		(net "M_E_CPU0_SA_DQ<1>")
	)
	(segment
		(start 309.256938 -198.940928)
		(end 308.791864 -198.940928)
		(width 0.14478)
		(layer "In6.Cu")
		(net "M_E_CPU0_SA_DQ<1>")
	)
	(segment
		(start 298.377102 -198.61022)
		(end 297.527218 -199.460104)
		(width 0.14478)
		(layer "In6.Cu")
		(net "M_E_CPU0_SA_DQ<1>")
	)
	(segment
		(start 324.033134 -218.82989)
		(end 324.033134 -214.66429)
		(width 0.14478)
		(layer "In6.Cu")
		(net "M_E_CPU0_SA_DQ<1>")
	)
	(segment
		(start 308.647084 -199.085708)
		(end 308.647084 -199.940672)
		(width 0.14478)
		(layer "In6.Cu")
		(net "M_E_CPU0_SA_DQ<1>")
	)
	(segment
		(start 315.867796 -206.294482)
		(end 315.66358 -206.294736)
		(width 0.14478)
		(layer "In6.Cu")
		(net "M_E_CPU0_SA_DQ<1>")
	)
	(arc
		(start 328.984102 -226.17684)
		(mid 328.701146 -226.100663)
		(end 328.41819 -226.17684)
		(width 0.0889)
		(layer "In6.Cu")
		(net "M_E_CPU0_SA_DQ<1>")
	)
	(arc
		(start 327.54062 -223.727264)
		(mid 327.427213 -223.594234)
		(end 327.386442 -223.424242)
		(width 0.0889)
		(layer "In6.Cu")
		(net "M_E_CPU0_SA_DQ<1>")
	)
	(arc
		(start 328.013568 -226.15906)
		(mid 327.898141 -226.025684)
		(end 327.856596 -225.85426)
		(width 0.0889)
		(layer "In6.Cu")
		(net "M_E_CPU0_SA_DQ<1>")
	)
	(arc
		(start 327.856342 -225.85426)
		(mid 327.791827 -225.592041)
		(end 327.61301 -225.389694)
		(width 0.0889)
		(layer "In6.Cu")
		(net "M_E_CPU0_SA_DQ<1>")
	)
	(arc
		(start 327.856596 -224.234248)
		(mid 327.79136 -223.970657)
		(end 327.610724 -223.767904)
		(width 0.0889)
		(layer "In6.Cu")
		(net "M_E_CPU0_SA_DQ<1>")
	)
	(arc
		(start 327.543414 -225.349054)
		(mid 327.427987 -225.215678)
		(end 327.386442 -225.044254)
		(width 0.0889)
		(layer "In6.Cu")
		(net "M_E_CPU0_SA_DQ<1>")
	)
	(arc
		(start 327.386442 -223.424242)
		(mid 327.32157 -223.161279)
		(end 327.14184 -222.95866)
		(width 0.0889)
		(layer "In6.Cu")
		(net "M_E_CPU0_SA_DQ<1>")
	)
	(arc
		(start 327.073768 -222.919036)
		(mid 326.958341 -222.78566)
		(end 326.916796 -222.614236)
		(width 0.0889)
		(layer "In6.Cu")
		(net "M_E_CPU0_SA_DQ<1>")
	)
	(arc
		(start 327.611994 -224.69983)
		(mid 327.791723 -224.49721)
		(end 327.856596 -224.234248)
		(width 0.0889)
		(layer "In6.Cu")
		(net "M_E_CPU0_SA_DQ<1>")
	)
	(arc
		(start 329.358244 -226.17684)
		(mid 329.175993 -226.22719)
		(end 328.992484 -226.181666)
		(width 0.0889)
		(layer "In6.Cu")
		(net "M_E_CPU0_SA_DQ<1>")
	)
	(arc
		(start 326.916796 -222.614236)
		(mid 326.851924 -222.351273)
		(end 326.672194 -222.148654)
		(width 0.0889)
		(layer "In6.Cu")
		(net "M_E_CPU0_SA_DQ<1>")
	)
	(arc
		(start 329.924156 -226.17684)
		(mid 329.6412 -226.100663)
		(end 329.358244 -226.17684)
		(width 0.0889)
		(layer "In6.Cu")
		(net "M_E_CPU0_SA_DQ<1>")
	)
	(arc
		(start 328.409808 -226.181666)
		(mid 328.2263 -226.22716)
		(end 328.044048 -226.17684)
		(width 0.0889)
		(layer "In6.Cu")
		(net "M_E_CPU0_SA_DQ<1>")
	)
	(arc
		(start 330.242672 -226.203002)
		(mid 330.080483 -226.225737)
		(end 329.924156 -226.17684)
		(width 0.0889)
		(layer "In6.Cu")
		(net "M_E_CPU0_SA_DQ<1>")
	)
	(arc
		(start 327.386442 -225.044254)
		(mid 327.427697 -224.873283)
		(end 327.542398 -224.739962)
		(width 0.0889)
		(layer "In6.Cu")
		(net "M_E_CPU0_SA_DQ<1>")
	)
	(segment
		(start 331.047852 -236.650022)
		(end 330.581 -236.384084)
		(width 0.10668)
		(layer "F.Cu")
		(net "M_E_CPU0_SA_DQ<19>")
	)
	(segment
		(start 312.039254 -219.665296)
		(end 310.88203 -218.508072)
		(width 0.14478)
		(layer "In6.Cu")
		(net "M_E_CPU0_SA_DQ<19>")
	)
	(segment
		(start 324.485254 -234.67441)
		(end 323.977254 -234.16641)
		(width 0.0889)
		(layer "In6.Cu")
		(net "M_E_CPU0_SA_DQ<19>")
	)
	(segment
		(start 325.120254 -234.89031)
		(end 324.904354 -234.67441)
		(width 0.0889)
		(layer "In6.Cu")
		(net "M_E_CPU0_SA_DQ<19>")
	)
	(segment
		(start 321.99453 -234.16641)
		(end 314.382658 -226.554538)
		(width 0.14478)
		(layer "In6.Cu")
		(net "M_E_CPU0_SA_DQ<19>")
	)
	(segment
		(start 301.18685 -218.15044)
		(end 298.23029 -218.15044)
		(width 0.14478)
		(layer "In6.Cu")
		(net "M_E_CPU0_SA_DQ<19>")
	)
	(segment
		(start 327.008744 -236.061504)
		(end 326.99706 -236.054646)
		(width 0.0889)
		(layer "In6.Cu")
		(net "M_E_CPU0_SA_DQ<19>")
	)
	(segment
		(start 305.764438 -218.160092)
		(end 304.9143 -219.01023)
		(width 0.14478)
		(layer "In6.Cu")
		(net "M_E_CPU0_SA_DQ<19>")
	)
	(segment
		(start 298.23029 -218.15044)
		(end 297.380406 -219.000324)
		(width 0.14478)
		(layer "In6.Cu")
		(net "M_E_CPU0_SA_DQ<19>")
	)
	(segment
		(start 302.04664 -219.01023)
		(end 301.18685 -218.15044)
		(width 0.14478)
		(layer "In6.Cu")
		(net "M_E_CPU0_SA_DQ<19>")
	)
	(segment
		(start 327.586086 -236.054646)
		(end 327.574402 -236.061504)
		(width 0.0889)
		(layer "In6.Cu")
		(net "M_E_CPU0_SA_DQ<19>")
	)
	(segment
		(start 274.056602 -218.585034)
		(end 273.092164 -218.585034)
		(width 0.14478)
		(layer "In6.Cu")
		(net "M_E_CPU0_SA_DQ<19>")
	)
	(segment
		(start 286.8041 -219.000324)
		(end 285.954216 -218.15044)
		(width 0.14478)
		(layer "In6.Cu")
		(net "M_E_CPU0_SA_DQ<19>")
	)
	(segment
		(start 330.581 -236.384084)
		(end 330.427076 -236.118654)
		(width 0.0889)
		(layer "In6.Cu")
		(net "M_E_CPU0_SA_DQ<19>")
	)
	(segment
		(start 323.547994 -234.16641)
		(end 321.99453 -234.16641)
		(width 0.14478)
		(layer "In6.Cu")
		(net "M_E_CPU0_SA_DQ<19>")
	)
	(segment
		(start 306.668678 -218.160092)
		(end 305.764438 -218.160092)
		(width 0.14478)
		(layer "In6.Cu")
		(net "M_E_CPU0_SA_DQ<19>")
	)
	(segment
		(start 324.904354 -234.67441)
		(end 324.485254 -234.67441)
		(width 0.0889)
		(layer "In6.Cu")
		(net "M_E_CPU0_SA_DQ<19>")
	)
	(segment
		(start 312.039254 -223.257872)
		(end 312.039254 -219.665296)
		(width 0.14478)
		(layer "In6.Cu")
		(net "M_E_CPU0_SA_DQ<19>")
	)
	(segment
		(start 285.954216 -218.15044)
		(end 283.074872 -218.15044)
		(width 0.14478)
		(layer "In6.Cu")
		(net "M_E_CPU0_SA_DQ<19>")
	)
	(segment
		(start 310.88203 -218.508072)
		(end 307.016658 -218.508072)
		(width 0.14478)
		(layer "In6.Cu")
		(net "M_E_CPU0_SA_DQ<19>")
	)
	(segment
		(start 282.224226 -219.001086)
		(end 275.061172 -219.001086)
		(width 0.14478)
		(layer "In6.Cu")
		(net "M_E_CPU0_SA_DQ<19>")
	)
	(segment
		(start 294.492934 -219.000324)
		(end 293.64305 -218.15044)
		(width 0.14478)
		(layer "In6.Cu")
		(net "M_E_CPU0_SA_DQ<19>")
	)
	(segment
		(start 329.828144 -236.061504)
		(end 329.819762 -236.056678)
		(width 0.0889)
		(layer "In6.Cu")
		(net "M_E_CPU0_SA_DQ<19>")
	)
	(segment
		(start 314.382658 -226.554538)
		(end 314.382658 -225.601276)
		(width 0.14478)
		(layer "In6.Cu")
		(net "M_E_CPU0_SA_DQ<19>")
	)
	(segment
		(start 326.01662 -236.068616)
		(end 325.120254 -235.17225)
		(width 0.0889)
		(layer "In6.Cu")
		(net "M_E_CPU0_SA_DQ<19>")
	)
	(segment
		(start 325.120254 -235.17225)
		(end 325.120254 -234.89031)
		(width 0.0889)
		(layer "In6.Cu")
		(net "M_E_CPU0_SA_DQ<19>")
	)
	(segment
		(start 289.86988 -219.000324)
		(end 286.8041 -219.000324)
		(width 0.14478)
		(layer "In6.Cu")
		(net "M_E_CPU0_SA_DQ<19>")
	)
	(segment
		(start 283.074872 -218.15044)
		(end 282.224226 -219.001086)
		(width 0.14478)
		(layer "In6.Cu")
		(net "M_E_CPU0_SA_DQ<19>")
	)
	(segment
		(start 326.080628 -236.068616)
		(end 326.01662 -236.068616)
		(width 0.0889)
		(layer "In6.Cu")
		(net "M_E_CPU0_SA_DQ<19>")
	)
	(segment
		(start 307.016658 -218.508072)
		(end 306.668678 -218.160092)
		(width 0.14478)
		(layer "In6.Cu")
		(net "M_E_CPU0_SA_DQ<19>")
	)
	(segment
		(start 314.382658 -225.601276)
		(end 312.039254 -223.257872)
		(width 0.14478)
		(layer "In6.Cu")
		(net "M_E_CPU0_SA_DQ<19>")
	)
	(segment
		(start 290.719764 -218.15044)
		(end 289.86988 -219.000324)
		(width 0.14478)
		(layer "In6.Cu")
		(net "M_E_CPU0_SA_DQ<19>")
	)
	(segment
		(start 323.977254 -234.16641)
		(end 323.547994 -234.16641)
		(width 0.0889)
		(layer "In6.Cu")
		(net "M_E_CPU0_SA_DQ<19>")
	)
	(segment
		(start 275.061172 -219.001086)
		(end 274.056602 -218.585034)
		(width 0.14478)
		(layer "In6.Cu")
		(net "M_E_CPU0_SA_DQ<19>")
	)
	(segment
		(start 330.427076 -236.118654)
		(end 330.331064 -236.093254)
		(width 0.0889)
		(layer "In6.Cu")
		(net "M_E_CPU0_SA_DQ<19>")
	)
	(segment
		(start 297.380406 -219.000324)
		(end 294.492934 -219.000324)
		(width 0.14478)
		(layer "In6.Cu")
		(net "M_E_CPU0_SA_DQ<19>")
	)
	(segment
		(start 327.574402 -236.061504)
		(end 327.563988 -236.0676)
		(width 0.0889)
		(layer "In6.Cu")
		(net "M_E_CPU0_SA_DQ<19>")
	)
	(segment
		(start 293.64305 -218.15044)
		(end 290.719764 -218.15044)
		(width 0.14478)
		(layer "In6.Cu")
		(net "M_E_CPU0_SA_DQ<19>")
	)
	(segment
		(start 304.9143 -219.01023)
		(end 302.04664 -219.01023)
		(width 0.14478)
		(layer "In6.Cu")
		(net "M_E_CPU0_SA_DQ<19>")
	)
	(arc
		(start 328.514202 -236.061504)
		(mid 328.231246 -236.137681)
		(end 327.94829 -236.061504)
		(width 0.0889)
		(layer "In6.Cu")
		(net "M_E_CPU0_SA_DQ<19>")
	)
	(arc
		(start 326.99706 -236.054646)
		(mid 326.814805 -236.010993)
		(end 326.634348 -236.061504)
		(width 0.0889)
		(layer "In6.Cu")
		(net "M_E_CPU0_SA_DQ<19>")
	)
	(arc
		(start 326.634348 -236.061504)
		(mid 326.358416 -236.137761)
		(end 326.080628 -236.068616)
		(width 0.0889)
		(layer "In6.Cu")
		(net "M_E_CPU0_SA_DQ<19>")
	)
	(arc
		(start 329.454002 -236.061504)
		(mid 329.171046 -236.137681)
		(end 328.88809 -236.061504)
		(width 0.0889)
		(layer "In6.Cu")
		(net "M_E_CPU0_SA_DQ<19>")
	)
	(arc
		(start 329.819762 -236.056678)
		(mid 329.636254 -236.011184)
		(end 329.454002 -236.061504)
		(width 0.0889)
		(layer "In6.Cu")
		(net "M_E_CPU0_SA_DQ<19>")
	)
	(arc
		(start 327.563988 -236.0676)
		(mid 327.285556 -236.137698)
		(end 327.008744 -236.061504)
		(width 0.0889)
		(layer "In6.Cu")
		(net "M_E_CPU0_SA_DQ<19>")
	)
	(arc
		(start 328.88809 -236.061504)
		(mid 328.701146 -236.011249)
		(end 328.514202 -236.061504)
		(width 0.0889)
		(layer "In6.Cu")
		(net "M_E_CPU0_SA_DQ<19>")
	)
	(arc
		(start 330.331064 -236.093254)
		(mid 330.075856 -236.136731)
		(end 329.828144 -236.061504)
		(width 0.0889)
		(layer "In6.Cu")
		(net "M_E_CPU0_SA_DQ<19>")
	)
	(arc
		(start 327.94829 -236.061504)
		(mid 327.768085 -236.011187)
		(end 327.586086 -236.054646)
		(width 0.0889)
		(layer "In6.Cu")
		(net "M_E_CPU0_SA_DQ<19>")
	)
	(segment
		(start 329.637898 -235.840016)
		(end 329.171046 -235.574078)
		(width 0.10668)
		(layer "F.Cu")
		(net "M_E_CPU0_SA_DQ<18>")
	)
	(segment
		(start 290.710112 -216.46007)
		(end 289.859974 -217.310208)
		(width 0.14478)
		(layer "In6.Cu")
		(net "M_E_CPU0_SA_DQ<18>")
	)
	(segment
		(start 282.21432 -217.310208)
		(end 275.677122 -217.310208)
		(width 0.14478)
		(layer "In6.Cu")
		(net "M_E_CPU0_SA_DQ<18>")
	)
	(segment
		(start 307.38953 -217.608912)
		(end 307.04155 -217.260932)
		(width 0.14478)
		(layer "In6.Cu")
		(net "M_E_CPU0_SA_DQ<18>")
	)
	(segment
		(start 315.281818 -226.167442)
		(end 315.281818 -225.228404)
		(width 0.14478)
		(layer "In6.Cu")
		(net "M_E_CPU0_SA_DQ<18>")
	)
	(segment
		(start 307.04155 -217.260932)
		(end 301.997364 -217.260932)
		(width 0.14478)
		(layer "In6.Cu")
		(net "M_E_CPU0_SA_DQ<18>")
	)
	(segment
		(start 323.895974 -233.25709)
		(end 323.547994 -233.25709)
		(width 0.0889)
		(layer "In6.Cu")
		(net "M_E_CPU0_SA_DQ<18>")
	)
	(segment
		(start 312.948574 -219.302584)
		(end 311.254902 -217.608912)
		(width 0.14478)
		(layer "In6.Cu")
		(net "M_E_CPU0_SA_DQ<18>")
	)
	(segment
		(start 324.985126 -234.10291)
		(end 324.629526 -234.10291)
		(width 0.0889)
		(layer "In6.Cu")
		(net "M_E_CPU0_SA_DQ<18>")
	)
	(segment
		(start 326.088248 -235.206032)
		(end 324.985126 -234.10291)
		(width 0.0889)
		(layer "In6.Cu")
		(net "M_E_CPU0_SA_DQ<18>")
	)
	(segment
		(start 297.3705 -217.310208)
		(end 294.50284 -217.310208)
		(width 0.14478)
		(layer "In6.Cu")
		(net "M_E_CPU0_SA_DQ<18>")
	)
	(segment
		(start 275.514054 -217.14714)
		(end 275.514054 -216.82456)
		(width 0.14478)
		(layer "In6.Cu")
		(net "M_E_CPU0_SA_DQ<18>")
	)
	(segment
		(start 301.196502 -216.46007)
		(end 298.220638 -216.46007)
		(width 0.14478)
		(layer "In6.Cu")
		(net "M_E_CPU0_SA_DQ<18>")
	)
	(segment
		(start 326.425052 -235.206032)
		(end 326.088248 -235.206032)
		(width 0.0889)
		(layer "In6.Cu")
		(net "M_E_CPU0_SA_DQ<18>")
	)
	(segment
		(start 274.95754 -217.14714)
		(end 274.794472 -217.310208)
		(width 0.14478)
		(layer "In6.Cu")
		(net "M_E_CPU0_SA_DQ<18>")
	)
	(segment
		(start 324.155054 -233.628438)
		(end 324.155054 -233.51617)
		(width 0.0889)
		(layer "In6.Cu")
		(net "M_E_CPU0_SA_DQ<18>")
	)
	(segment
		(start 289.859974 -217.310208)
		(end 286.814006 -217.310208)
		(width 0.14478)
		(layer "In6.Cu")
		(net "M_E_CPU0_SA_DQ<18>")
	)
	(segment
		(start 329.017122 -235.308648)
		(end 328.92111 -235.283248)
		(width 0.0889)
		(layer "In6.Cu")
		(net "M_E_CPU0_SA_DQ<18>")
	)
	(segment
		(start 324.629526 -234.10291)
		(end 324.155054 -233.628438)
		(width 0.0889)
		(layer "In6.Cu")
		(net "M_E_CPU0_SA_DQ<18>")
	)
	(segment
		(start 275.677122 -217.310208)
		(end 275.514054 -217.14714)
		(width 0.14478)
		(layer "In6.Cu")
		(net "M_E_CPU0_SA_DQ<18>")
	)
	(segment
		(start 285.963868 -216.46007)
		(end 283.064458 -216.46007)
		(width 0.14478)
		(layer "In6.Cu")
		(net "M_E_CPU0_SA_DQ<18>")
	)
	(segment
		(start 311.254902 -217.608912)
		(end 307.38953 -217.608912)
		(width 0.14478)
		(layer "In6.Cu")
		(net "M_E_CPU0_SA_DQ<18>")
	)
	(segment
		(start 327.111614 -235.246672)
		(end 327.103232 -235.251498)
		(width 0.0889)
		(layer "In6.Cu")
		(net "M_E_CPU0_SA_DQ<18>")
	)
	(segment
		(start 324.155054 -233.51617)
		(end 323.895974 -233.25709)
		(width 0.0889)
		(layer "In6.Cu")
		(net "M_E_CPU0_SA_DQ<18>")
	)
	(segment
		(start 275.120608 -216.661492)
		(end 274.95754 -216.82456)
		(width 0.14478)
		(layer "In6.Cu")
		(net "M_E_CPU0_SA_DQ<18>")
	)
	(segment
		(start 322.371466 -233.25709)
		(end 315.281818 -226.167442)
		(width 0.14478)
		(layer "In6.Cu")
		(net "M_E_CPU0_SA_DQ<18>")
	)
	(segment
		(start 315.281818 -225.228404)
		(end 312.948574 -222.89516)
		(width 0.14478)
		(layer "In6.Cu")
		(net "M_E_CPU0_SA_DQ<18>")
	)
	(segment
		(start 286.814006 -217.310208)
		(end 285.963868 -216.46007)
		(width 0.14478)
		(layer "In6.Cu")
		(net "M_E_CPU0_SA_DQ<18>")
	)
	(segment
		(start 274.794472 -217.310208)
		(end 273.51736 -217.310208)
		(width 0.14478)
		(layer "In6.Cu")
		(net "M_E_CPU0_SA_DQ<18>")
	)
	(segment
		(start 323.547994 -233.25709)
		(end 322.371466 -233.25709)
		(width 0.14478)
		(layer "In6.Cu")
		(net "M_E_CPU0_SA_DQ<18>")
	)
	(segment
		(start 273.51736 -217.310208)
		(end 273.092164 -216.885012)
		(width 0.14478)
		(layer "In6.Cu")
		(net "M_E_CPU0_SA_DQ<18>")
	)
	(segment
		(start 328.41819 -235.251498)
		(end 328.409808 -235.246672)
		(width 0.0889)
		(layer "In6.Cu")
		(net "M_E_CPU0_SA_DQ<18>")
	)
	(segment
		(start 312.948574 -222.89516)
		(end 312.948574 -219.302584)
		(width 0.14478)
		(layer "In6.Cu")
		(net "M_E_CPU0_SA_DQ<18>")
	)
	(segment
		(start 298.220638 -216.46007)
		(end 297.3705 -217.310208)
		(width 0.14478)
		(layer "In6.Cu")
		(net "M_E_CPU0_SA_DQ<18>")
	)
	(segment
		(start 329.171046 -235.574078)
		(end 329.017122 -235.308648)
		(width 0.0889)
		(layer "In6.Cu")
		(net "M_E_CPU0_SA_DQ<18>")
	)
	(segment
		(start 274.95754 -216.82456)
		(end 274.95754 -217.14714)
		(width 0.14478)
		(layer "In6.Cu")
		(net "M_E_CPU0_SA_DQ<18>")
	)
	(segment
		(start 326.543416 -235.255054)
		(end 326.425052 -235.206032)
		(width 0.0889)
		(layer "In6.Cu")
		(net "M_E_CPU0_SA_DQ<18>")
	)
	(segment
		(start 293.652702 -216.46007)
		(end 290.710112 -216.46007)
		(width 0.14478)
		(layer "In6.Cu")
		(net "M_E_CPU0_SA_DQ<18>")
	)
	(segment
		(start 283.064458 -216.46007)
		(end 282.21432 -217.310208)
		(width 0.14478)
		(layer "In6.Cu")
		(net "M_E_CPU0_SA_DQ<18>")
	)
	(segment
		(start 294.50284 -217.310208)
		(end 293.652702 -216.46007)
		(width 0.14478)
		(layer "In6.Cu")
		(net "M_E_CPU0_SA_DQ<18>")
	)
	(segment
		(start 301.997364 -217.260932)
		(end 301.196502 -216.46007)
		(width 0.14478)
		(layer "In6.Cu")
		(net "M_E_CPU0_SA_DQ<18>")
	)
	(segment
		(start 328.044048 -235.251498)
		(end 328.033634 -235.257594)
		(width 0.0889)
		(layer "In6.Cu")
		(net "M_E_CPU0_SA_DQ<18>")
	)
	(segment
		(start 275.350986 -216.661492)
		(end 275.120608 -216.661492)
		(width 0.14478)
		(layer "In6.Cu")
		(net "M_E_CPU0_SA_DQ<18>")
	)
	(segment
		(start 275.514054 -216.82456)
		(end 275.350986 -216.661492)
		(width 0.14478)
		(layer "In6.Cu")
		(net "M_E_CPU0_SA_DQ<18>")
	)
	(arc
		(start 327.103232 -235.251498)
		(mid 326.823804 -235.327664)
		(end 326.543416 -235.255054)
		(width 0.0889)
		(layer "In6.Cu")
		(net "M_E_CPU0_SA_DQ<18>")
	)
	(arc
		(start 328.033634 -235.257594)
		(mid 327.754948 -235.327814)
		(end 327.477882 -235.251498)
		(width 0.0889)
		(layer "In6.Cu")
		(net "M_E_CPU0_SA_DQ<18>")
	)
	(arc
		(start 328.92111 -235.283248)
		(mid 328.665902 -235.326725)
		(end 328.41819 -235.251498)
		(width 0.0889)
		(layer "In6.Cu")
		(net "M_E_CPU0_SA_DQ<18>")
	)
	(arc
		(start 327.477882 -235.251498)
		(mid 327.295377 -235.201021)
		(end 327.111614 -235.246672)
		(width 0.0889)
		(layer "In6.Cu")
		(net "M_E_CPU0_SA_DQ<18>")
	)
	(arc
		(start 328.409808 -235.246672)
		(mid 328.2263 -235.201178)
		(end 328.044048 -235.251498)
		(width 0.0889)
		(layer "In6.Cu")
		(net "M_E_CPU0_SA_DQ<18>")
	)
	(segment
		(start 330.577952 -235.840016)
		(end 330.1111 -235.574078)
		(width 0.10668)
		(layer "F.Cu")
		(net "M_E_CPU0_SA_DQ<17>")
	)
	(segment
		(start 303.310798 -218.392502)
		(end 303.14773 -218.55557)
		(width 0.14478)
		(layer "In6.Cu")
		(net "M_E_CPU0_SA_DQ<17>")
	)
	(segment
		(start 279.06472 -217.774774)
		(end 278.901652 -217.937842)
		(width 0.14478)
		(layer "In6.Cu")
		(net "M_E_CPU0_SA_DQ<17>")
	)
	(segment
		(start 290.866322 -217.310208)
		(end 290.016438 -218.160092)
		(width 0.14478)
		(layer "In6.Cu")
		(net "M_E_CPU0_SA_DQ<17>")
	)
	(segment
		(start 288.800032 -218.387422)
		(end 288.800032 -218.32316)
		(width 0.14478)
		(layer "In6.Cu")
		(net "M_E_CPU0_SA_DQ<17>")
	)
	(segment
		(start 305.568858 -217.710512)
		(end 305.119278 -218.160092)
		(width 0.14478)
		(layer "In6.Cu")
		(net "M_E_CPU0_SA_DQ<17>")
	)
	(segment
		(start 296.442892 -218.387422)
		(end 296.442892 -218.32316)
		(width 0.14478)
		(layer "In6.Cu")
		(net "M_E_CPU0_SA_DQ<17>")
	)
	(segment
		(start 279.621234 -218.54541)
		(end 279.458166 -218.382342)
		(width 0.14478)
		(layer "In6.Cu")
		(net "M_E_CPU0_SA_DQ<17>")
	)
	(segment
		(start 303.310798 -218.32316)
		(end 303.310798 -218.392502)
		(width 0.14478)
		(layer "In6.Cu")
		(net "M_E_CPU0_SA_DQ<17>")
	)
	(segment
		(start 294.480742 -218.160092)
		(end 293.630858 -217.310208)
		(width 0.14478)
		(layer "In6.Cu")
		(net "M_E_CPU0_SA_DQ<17>")
	)
	(segment
		(start 277.617174 -218.160092)
		(end 277.192232 -217.73515)
		(width 0.14478)
		(layer "In6.Cu")
		(net "M_E_CPU0_SA_DQ<17>")
	)
	(segment
		(start 314.832238 -225.41484)
		(end 312.493914 -223.076516)
		(width 0.14478)
		(layer "In6.Cu")
		(net "M_E_CPU0_SA_DQ<17>")
	)
	(segment
		(start 306.855114 -217.710512)
		(end 305.568858 -217.710512)
		(width 0.14478)
		(layer "In6.Cu")
		(net "M_E_CPU0_SA_DQ<17>")
	)
	(segment
		(start 328.992484 -235.901484)
		(end 328.984102 -235.896658)
		(width 0.0889)
		(layer "In6.Cu")
		(net "M_E_CPU0_SA_DQ<17>")
	)
	(segment
		(start 279.851612 -218.54541)
		(end 279.621234 -218.54541)
		(width 0.14478)
		(layer "In6.Cu")
		(net "M_E_CPU0_SA_DQ<17>")
	)
	(segment
		(start 298.425362 -217.310208)
		(end 297.575478 -218.160092)
		(width 0.14478)
		(layer "In6.Cu")
		(net "M_E_CPU0_SA_DQ<17>")
	)
	(segment
		(start 288.9631 -218.55049)
		(end 288.800032 -218.387422)
		(width 0.14478)
		(layer "In6.Cu")
		(net "M_E_CPU0_SA_DQ<17>")
	)
	(segment
		(start 305.119278 -218.160092)
		(end 304.586894 -218.160092)
		(width 0.14478)
		(layer "In6.Cu")
		(net "M_E_CPU0_SA_DQ<17>")
	)
	(segment
		(start 288.800032 -218.32316)
		(end 288.636964 -218.160092)
		(width 0.14478)
		(layer "In6.Cu")
		(net "M_E_CPU0_SA_DQ<17>")
	)
	(segment
		(start 303.867312 -218.32316)
		(end 303.704244 -218.160092)
		(width 0.14478)
		(layer "In6.Cu")
		(net "M_E_CPU0_SA_DQ<17>")
	)
	(segment
		(start 314.832238 -226.36099)
		(end 314.832238 -225.41484)
		(width 0.14478)
		(layer "In6.Cu")
		(net "M_E_CPU0_SA_DQ<17>")
	)
	(segment
		(start 322.182998 -233.71175)
		(end 314.832238 -226.36099)
		(width 0.14478)
		(layer "In6.Cu")
		(net "M_E_CPU0_SA_DQ<17>")
	)
	(segment
		(start 290.016438 -218.160092)
		(end 289.519614 -218.160092)
		(width 0.14478)
		(layer "In6.Cu")
		(net "M_E_CPU0_SA_DQ<17>")
	)
	(segment
		(start 280.01468 -218.32316)
		(end 280.01468 -218.382342)
		(width 0.14478)
		(layer "In6.Cu")
		(net "M_E_CPU0_SA_DQ<17>")
	)
	(segment
		(start 297.162474 -218.160092)
		(end 296.999406 -218.32316)
		(width 0.14478)
		(layer "In6.Cu")
		(net "M_E_CPU0_SA_DQ<17>")
	)
	(segment
		(start 282.419298 -218.160092)
		(end 282.009342 -218.160092)
		(width 0.14478)
		(layer "In6.Cu")
		(net "M_E_CPU0_SA_DQ<17>")
	)
	(segment
		(start 281.28976 -218.387422)
		(end 281.28976 -218.32316)
		(width 0.14478)
		(layer "In6.Cu")
		(net "M_E_CPU0_SA_DQ<17>")
	)
	(segment
		(start 301.174658 -217.310208)
		(end 298.425362 -217.310208)
		(width 0.14478)
		(layer "In6.Cu")
		(net "M_E_CPU0_SA_DQ<17>")
	)
	(segment
		(start 297.575478 -218.160092)
		(end 297.162474 -218.160092)
		(width 0.14478)
		(layer "In6.Cu")
		(net "M_E_CPU0_SA_DQ<17>")
	)
	(segment
		(start 325.018654 -234.45851)
		(end 324.637654 -234.45851)
		(width 0.0889)
		(layer "In6.Cu")
		(net "M_E_CPU0_SA_DQ<17>")
	)
	(segment
		(start 289.193478 -218.55049)
		(end 288.9631 -218.55049)
		(width 0.14478)
		(layer "In6.Cu")
		(net "M_E_CPU0_SA_DQ<17>")
	)
	(segment
		(start 327.104756 -235.896658)
		(end 327.094342 -235.890562)
		(width 0.0889)
		(layer "In6.Cu")
		(net "M_E_CPU0_SA_DQ<17>")
	)
	(segment
		(start 296.999406 -218.387422)
		(end 296.836338 -218.55049)
		(width 0.14478)
		(layer "In6.Cu")
		(net "M_E_CPU0_SA_DQ<17>")
	)
	(segment
		(start 296.836338 -218.55049)
		(end 296.60596 -218.55049)
		(width 0.14478)
		(layer "In6.Cu")
		(net "M_E_CPU0_SA_DQ<17>")
	)
	(segment
		(start 328.41819 -235.896658)
		(end 328.409808 -235.901484)
		(width 0.0889)
		(layer "In6.Cu")
		(net "M_E_CPU0_SA_DQ<17>")
	)
	(segment
		(start 279.295098 -217.774774)
		(end 279.06472 -217.774774)
		(width 0.14478)
		(layer "In6.Cu")
		(net "M_E_CPU0_SA_DQ<17>")
	)
	(segment
		(start 302.754284 -218.392502)
		(end 302.754284 -218.32316)
		(width 0.14478)
		(layer "In6.Cu")
		(net "M_E_CPU0_SA_DQ<17>")
	)
	(segment
		(start 312.493914 -223.076516)
		(end 312.493914 -219.48394)
		(width 0.14478)
		(layer "In6.Cu")
		(net "M_E_CPU0_SA_DQ<17>")
	)
	(segment
		(start 288.636964 -218.160092)
		(end 286.804862 -218.160092)
		(width 0.14478)
		(layer "In6.Cu")
		(net "M_E_CPU0_SA_DQ<17>")
	)
	(segment
		(start 296.442892 -218.32316)
		(end 296.279824 -218.160092)
		(width 0.14478)
		(layer "In6.Cu")
		(net "M_E_CPU0_SA_DQ<17>")
	)
	(segment
		(start 302.917352 -218.55557)
		(end 302.754284 -218.392502)
		(width 0.14478)
		(layer "In6.Cu")
		(net "M_E_CPU0_SA_DQ<17>")
	)
	(segment
		(start 281.126692 -218.160092)
		(end 280.177748 -218.160092)
		(width 0.14478)
		(layer "In6.Cu")
		(net "M_E_CPU0_SA_DQ<17>")
	)
	(segment
		(start 296.999406 -218.32316)
		(end 296.999406 -218.387422)
		(width 0.14478)
		(layer "In6.Cu")
		(net "M_E_CPU0_SA_DQ<17>")
	)
	(segment
		(start 325.323454 -235.047536)
		(end 325.323454 -234.76331)
		(width 0.0889)
		(layer "In6.Cu")
		(net "M_E_CPU0_SA_DQ<17>")
	)
	(segment
		(start 330.265024 -235.839508)
		(end 330.242672 -235.92282)
		(width 0.0889)
		(layer "In6.Cu")
		(net "M_E_CPU0_SA_DQ<17>")
	)
	(segment
		(start 302.754284 -218.32316)
		(end 302.591216 -218.160092)
		(width 0.14478)
		(layer "In6.Cu")
		(net "M_E_CPU0_SA_DQ<17>")
	)
	(segment
		(start 302.591216 -218.160092)
		(end 302.024542 -218.160092)
		(width 0.14478)
		(layer "In6.Cu")
		(net "M_E_CPU0_SA_DQ<17>")
	)
	(segment
		(start 278.345138 -218.32316)
		(end 278.18207 -218.160092)
		(width 0.14478)
		(layer "In6.Cu")
		(net "M_E_CPU0_SA_DQ<17>")
	)
	(segment
		(start 304.423826 -218.32316)
		(end 304.423826 -218.392502)
		(width 0.14478)
		(layer "In6.Cu")
		(net "M_E_CPU0_SA_DQ<17>")
	)
	(segment
		(start 286.804862 -218.160092)
		(end 285.954978 -217.310208)
		(width 0.14478)
		(layer "In6.Cu")
		(net "M_E_CPU0_SA_DQ<17>")
	)
	(segment
		(start 289.356546 -218.387422)
		(end 289.193478 -218.55049)
		(width 0.14478)
		(layer "In6.Cu")
		(net "M_E_CPU0_SA_DQ<17>")
	)
	(segment
		(start 278.901652 -218.382342)
		(end 278.738584 -218.54541)
		(width 0.14478)
		(layer "In6.Cu")
		(net "M_E_CPU0_SA_DQ<17>")
	)
	(segment
		(start 289.356546 -218.32316)
		(end 289.356546 -218.387422)
		(width 0.14478)
		(layer "In6.Cu")
		(net "M_E_CPU0_SA_DQ<17>")
	)
	(segment
		(start 330.1111 -235.574078)
		(end 330.265024 -235.839508)
		(width 0.0889)
		(layer "In6.Cu")
		(net "M_E_CPU0_SA_DQ<17>")
	)
	(segment
		(start 327.488804 -235.890562)
		(end 327.47839 -235.896658)
		(width 0.0889)
		(layer "In6.Cu")
		(net "M_E_CPU0_SA_DQ<17>")
	)
	(segment
		(start 285.954978 -217.310208)
		(end 283.269182 -217.310208)
		(width 0.14478)
		(layer "In6.Cu")
		(net "M_E_CPU0_SA_DQ<17>")
	)
	(segment
		(start 296.279824 -218.160092)
		(end 294.480742 -218.160092)
		(width 0.14478)
		(layer "In6.Cu")
		(net "M_E_CPU0_SA_DQ<17>")
	)
	(segment
		(start 280.177748 -218.160092)
		(end 280.01468 -218.32316)
		(width 0.14478)
		(layer "In6.Cu")
		(net "M_E_CPU0_SA_DQ<17>")
	)
	(segment
		(start 281.683206 -218.55049)
		(end 281.452828 -218.55049)
		(width 0.14478)
		(layer "In6.Cu")
		(net "M_E_CPU0_SA_DQ<17>")
	)
	(segment
		(start 278.738584 -218.54541)
		(end 278.508206 -218.54541)
		(width 0.14478)
		(layer "In6.Cu")
		(net "M_E_CPU0_SA_DQ<17>")
	)
	(segment
		(start 303.867312 -218.392502)
		(end 303.867312 -218.32316)
		(width 0.14478)
		(layer "In6.Cu")
		(net "M_E_CPU0_SA_DQ<17>")
	)
	(segment
		(start 303.704244 -218.160092)
		(end 303.473866 -218.160092)
		(width 0.14478)
		(layer "In6.Cu")
		(net "M_E_CPU0_SA_DQ<17>")
	)
	(segment
		(start 282.009342 -218.160092)
		(end 281.846274 -218.32316)
		(width 0.14478)
		(layer "In6.Cu")
		(net "M_E_CPU0_SA_DQ<17>")
	)
	(segment
		(start 304.423826 -218.392502)
		(end 304.260758 -218.55557)
		(width 0.14478)
		(layer "In6.Cu")
		(net "M_E_CPU0_SA_DQ<17>")
	)
	(segment
		(start 303.473866 -218.160092)
		(end 303.310798 -218.32316)
		(width 0.14478)
		(layer "In6.Cu")
		(net "M_E_CPU0_SA_DQ<17>")
	)
	(segment
		(start 293.630858 -217.310208)
		(end 290.866322 -217.310208)
		(width 0.14478)
		(layer "In6.Cu")
		(net "M_E_CPU0_SA_DQ<17>")
	)
	(segment
		(start 323.890894 -233.71175)
		(end 323.547994 -233.71175)
		(width 0.0889)
		(layer "In6.Cu")
		(net "M_E_CPU0_SA_DQ<17>")
	)
	(segment
		(start 304.03038 -218.55557)
		(end 303.867312 -218.392502)
		(width 0.14478)
		(layer "In6.Cu")
		(net "M_E_CPU0_SA_DQ<17>")
	)
	(segment
		(start 281.846274 -218.32316)
		(end 281.846274 -218.387422)
		(width 0.14478)
		(layer "In6.Cu")
		(net "M_E_CPU0_SA_DQ<17>")
	)
	(segment
		(start 327.47839 -235.896658)
		(end 327.470008 -235.901484)
		(width 0.0889)
		(layer "In6.Cu")
		(net "M_E_CPU0_SA_DQ<17>")
	)
	(segment
		(start 307.203094 -218.058492)
		(end 306.855114 -217.710512)
		(width 0.14478)
		(layer "In6.Cu")
		(net "M_E_CPU0_SA_DQ<17>")
	)
	(segment
		(start 289.519614 -218.160092)
		(end 289.356546 -218.32316)
		(width 0.14478)
		(layer "In6.Cu")
		(net "M_E_CPU0_SA_DQ<17>")
	)
	(segment
		(start 281.28976 -218.32316)
		(end 281.126692 -218.160092)
		(width 0.14478)
		(layer "In6.Cu")
		(net "M_E_CPU0_SA_DQ<17>")
	)
	(segment
		(start 325.323454 -234.76331)
		(end 325.018654 -234.45851)
		(width 0.0889)
		(layer "In6.Cu")
		(net "M_E_CPU0_SA_DQ<17>")
	)
	(segment
		(start 303.14773 -218.55557)
		(end 302.917352 -218.55557)
		(width 0.14478)
		(layer "In6.Cu")
		(net "M_E_CPU0_SA_DQ<17>")
	)
	(segment
		(start 304.260758 -218.55557)
		(end 304.03038 -218.55557)
		(width 0.14478)
		(layer "In6.Cu")
		(net "M_E_CPU0_SA_DQ<17>")
	)
	(segment
		(start 283.269182 -217.310208)
		(end 282.419298 -218.160092)
		(width 0.14478)
		(layer "In6.Cu")
		(net "M_E_CPU0_SA_DQ<17>")
	)
	(segment
		(start 296.60596 -218.55049)
		(end 296.442892 -218.387422)
		(width 0.14478)
		(layer "In6.Cu")
		(net "M_E_CPU0_SA_DQ<17>")
	)
	(segment
		(start 279.458166 -217.937842)
		(end 279.295098 -217.774774)
		(width 0.14478)
		(layer "In6.Cu")
		(net "M_E_CPU0_SA_DQ<17>")
	)
	(segment
		(start 281.846274 -218.387422)
		(end 281.683206 -218.55049)
		(width 0.14478)
		(layer "In6.Cu")
		(net "M_E_CPU0_SA_DQ<17>")
	)
	(segment
		(start 278.345138 -218.382342)
		(end 278.345138 -218.32316)
		(width 0.14478)
		(layer "In6.Cu")
		(net "M_E_CPU0_SA_DQ<17>")
	)
	(segment
		(start 280.01468 -218.382342)
		(end 279.851612 -218.54541)
		(width 0.14478)
		(layer "In6.Cu")
		(net "M_E_CPU0_SA_DQ<17>")
	)
	(segment
		(start 326.182736 -235.906818)
		(end 325.323454 -235.047536)
		(width 0.0889)
		(layer "In6.Cu")
		(net "M_E_CPU0_SA_DQ<17>")
	)
	(segment
		(start 281.452828 -218.55049)
		(end 281.28976 -218.387422)
		(width 0.14478)
		(layer "In6.Cu")
		(net "M_E_CPU0_SA_DQ<17>")
	)
	(segment
		(start 278.18207 -218.160092)
		(end 277.617174 -218.160092)
		(width 0.14478)
		(layer "In6.Cu")
		(net "M_E_CPU0_SA_DQ<17>")
	)
	(segment
		(start 304.586894 -218.160092)
		(end 304.423826 -218.32316)
		(width 0.14478)
		(layer "In6.Cu")
		(net "M_E_CPU0_SA_DQ<17>")
	)
	(segment
		(start 312.493914 -219.48394)
		(end 311.068466 -218.058492)
		(width 0.14478)
		(layer "In6.Cu")
		(net "M_E_CPU0_SA_DQ<17>")
	)
	(segment
		(start 302.024542 -218.160092)
		(end 301.174658 -217.310208)
		(width 0.14478)
		(layer "In6.Cu")
		(net "M_E_CPU0_SA_DQ<17>")
	)
	(segment
		(start 279.458166 -218.382342)
		(end 279.458166 -217.937842)
		(width 0.14478)
		(layer "In6.Cu")
		(net "M_E_CPU0_SA_DQ<17>")
	)
	(segment
		(start 278.901652 -217.937842)
		(end 278.901652 -218.382342)
		(width 0.14478)
		(layer "In6.Cu")
		(net "M_E_CPU0_SA_DQ<17>")
	)
	(segment
		(start 311.068466 -218.058492)
		(end 307.203094 -218.058492)
		(width 0.14478)
		(layer "In6.Cu")
		(net "M_E_CPU0_SA_DQ<17>")
	)
	(segment
		(start 278.508206 -218.54541)
		(end 278.345138 -218.382342)
		(width 0.14478)
		(layer "In6.Cu")
		(net "M_E_CPU0_SA_DQ<17>")
	)
	(segment
		(start 324.637654 -234.45851)
		(end 323.890894 -233.71175)
		(width 0.0889)
		(layer "In6.Cu")
		(net "M_E_CPU0_SA_DQ<17>")
	)
	(segment
		(start 323.547994 -233.71175)
		(end 322.182998 -233.71175)
		(width 0.14478)
		(layer "In6.Cu")
		(net "M_E_CPU0_SA_DQ<17>")
	)
	(arc
		(start 328.044048 -235.896658)
		(mid 327.767235 -235.820515)
		(end 327.488804 -235.890562)
		(width 0.0889)
		(layer "In6.Cu")
		(net "M_E_CPU0_SA_DQ<17>")
	)
	(arc
		(start 328.409808 -235.901484)
		(mid 328.2263 -235.946978)
		(end 328.044048 -235.896658)
		(width 0.0889)
		(layer "In6.Cu")
		(net "M_E_CPU0_SA_DQ<17>")
	)
	(arc
		(start 330.242672 -235.92282)
		(mid 330.080483 -235.945555)
		(end 329.924156 -235.896658)
		(width 0.0889)
		(layer "In6.Cu")
		(net "M_E_CPU0_SA_DQ<17>")
	)
	(arc
		(start 328.984102 -235.896658)
		(mid 328.701146 -235.820481)
		(end 328.41819 -235.896658)
		(width 0.0889)
		(layer "In6.Cu")
		(net "M_E_CPU0_SA_DQ<17>")
	)
	(arc
		(start 329.924156 -235.896658)
		(mid 329.6412 -235.820481)
		(end 329.358244 -235.896658)
		(width 0.0889)
		(layer "In6.Cu")
		(net "M_E_CPU0_SA_DQ<17>")
	)
	(arc
		(start 329.358244 -235.896658)
		(mid 329.175993 -235.947008)
		(end 328.992484 -235.901484)
		(width 0.0889)
		(layer "In6.Cu")
		(net "M_E_CPU0_SA_DQ<17>")
	)
	(arc
		(start 327.470008 -235.901484)
		(mid 327.286754 -235.946857)
		(end 327.104756 -235.896658)
		(width 0.0889)
		(layer "In6.Cu")
		(net "M_E_CPU0_SA_DQ<17>")
	)
	(arc
		(start 327.094342 -235.890562)
		(mid 326.815656 -235.820342)
		(end 326.53859 -235.896658)
		(width 0.0889)
		(layer "In6.Cu")
		(net "M_E_CPU0_SA_DQ<17>")
	)
	(arc
		(start 326.53859 -235.896658)
		(mid 326.361962 -235.946891)
		(end 326.182736 -235.906818)
		(width 0.0889)
		(layer "In6.Cu")
		(net "M_E_CPU0_SA_DQ<17>")
	)
	(segment
		(start 329.167998 -235.03001)
		(end 328.701146 -234.764072)
		(width 0.10668)
		(layer "F.Cu")
		(net "M_E_CPU0_SA_DQ<16>")
	)
	(segment
		(start 281.894026 -216.685622)
		(end 281.730958 -216.84869)
		(width 0.14478)
		(layer "In6.Cu")
		(net "M_E_CPU0_SA_DQ<16>")
	)
	(segment
		(start 296.337736 -216.46007)
		(end 294.480742 -216.46007)
		(width 0.14478)
		(layer "In6.Cu")
		(net "M_E_CPU0_SA_DQ<16>")
	)
	(segment
		(start 305.703224 -216.811352)
		(end 305.558444 -216.666572)
		(width 0.14478)
		(layer "In6.Cu")
		(net "M_E_CPU0_SA_DQ<16>")
	)
	(segment
		(start 313.403234 -219.121228)
		(end 311.441338 -217.159332)
		(width 0.14478)
		(layer "In6.Cu")
		(net "M_E_CPU0_SA_DQ<16>")
	)
	(segment
		(start 307.598572 -216.410032)
		(end 306.856638 -216.410032)
		(width 0.14478)
		(layer "In6.Cu")
		(net "M_E_CPU0_SA_DQ<16>")
	)
	(segment
		(start 282.419298 -216.46007)
		(end 282.057094 -216.46007)
		(width 0.14478)
		(layer "In6.Cu")
		(net "M_E_CPU0_SA_DQ<16>")
	)
	(segment
		(start 277.617174 -216.46007)
		(end 277.192232 -216.035128)
		(width 0.14478)
		(layer "In6.Cu")
		(net "M_E_CPU0_SA_DQ<16>")
	)
	(segment
		(start 327.017888 -235.080556)
		(end 327.007474 -235.086652)
		(width 0.0889)
		(layer "In6.Cu")
		(net "M_E_CPU0_SA_DQ<16>")
	)
	(segment
		(start 305.558444 -216.666572)
		(end 305.558444 -216.316052)
		(width 0.14478)
		(layer "In6.Cu")
		(net "M_E_CPU0_SA_DQ<16>")
	)
	(segment
		(start 324.713854 -233.89971)
		(end 324.358254 -233.54411)
		(width 0.0889)
		(layer "In6.Cu")
		(net "M_E_CPU0_SA_DQ<16>")
	)
	(segment
		(start 289.053524 -216.85377)
		(end 288.890456 -216.690702)
		(width 0.14478)
		(layer "In6.Cu")
		(net "M_E_CPU0_SA_DQ<16>")
	)
	(segment
		(start 288.890456 -216.623138)
		(end 288.727388 -216.46007)
		(width 0.14478)
		(layer "In6.Cu")
		(net "M_E_CPU0_SA_DQ<16>")
	)
	(segment
		(start 280.201878 -216.46007)
		(end 279.903174 -216.161366)
		(width 0.14478)
		(layer "In6.Cu")
		(net "M_E_CPU0_SA_DQ<16>")
	)
	(segment
		(start 305.558444 -216.316052)
		(end 305.413664 -216.171272)
		(width 0.14478)
		(layer "In6.Cu")
		(net "M_E_CPU0_SA_DQ<16>")
	)
	(segment
		(start 289.283902 -216.85377)
		(end 289.053524 -216.85377)
		(width 0.14478)
		(layer "In6.Cu")
		(net "M_E_CPU0_SA_DQ<16>")
	)
	(segment
		(start 279.2984 -216.306146)
		(end 279.2984 -216.691972)
		(width 0.14478)
		(layer "In6.Cu")
		(net "M_E_CPU0_SA_DQ<16>")
	)
	(segment
		(start 296.89425 -216.84107)
		(end 296.663872 -216.84107)
		(width 0.14478)
		(layer "In6.Cu")
		(net "M_E_CPU0_SA_DQ<16>")
	)
	(segment
		(start 282.057094 -216.46007)
		(end 281.894026 -216.623138)
		(width 0.14478)
		(layer "In6.Cu")
		(net "M_E_CPU0_SA_DQ<16>")
	)
	(segment
		(start 279.15362 -216.836752)
		(end 278.8793 -216.836752)
		(width 0.14478)
		(layer "In6.Cu")
		(net "M_E_CPU0_SA_DQ<16>")
	)
	(segment
		(start 283.269182 -215.610186)
		(end 282.419298 -216.46007)
		(width 0.14478)
		(layer "In6.Cu")
		(net "M_E_CPU0_SA_DQ<16>")
	)
	(segment
		(start 315.731398 -225.973894)
		(end 315.731398 -225.041968)
		(width 0.14478)
		(layer "In6.Cu")
		(net "M_E_CPU0_SA_DQ<16>")
	)
	(segment
		(start 281.174444 -216.46007)
		(end 280.201878 -216.46007)
		(width 0.14478)
		(layer "In6.Cu")
		(net "M_E_CPU0_SA_DQ<16>")
	)
	(segment
		(start 325.069454 -233.89971)
		(end 324.713854 -233.89971)
		(width 0.0889)
		(layer "In6.Cu")
		(net "M_E_CPU0_SA_DQ<16>")
	)
	(segment
		(start 306.455318 -216.811352)
		(end 305.703224 -216.811352)
		(width 0.14478)
		(layer "In6.Cu")
		(net "M_E_CPU0_SA_DQ<16>")
	)
	(segment
		(start 304.994564 -216.666572)
		(end 304.849784 -216.811352)
		(width 0.14478)
		(layer "In6.Cu")
		(net "M_E_CPU0_SA_DQ<16>")
	)
	(segment
		(start 294.480742 -216.46007)
		(end 293.630858 -215.610186)
		(width 0.14478)
		(layer "In6.Cu")
		(net "M_E_CPU0_SA_DQ<16>")
	)
	(segment
		(start 288.890456 -216.690702)
		(end 288.890456 -216.623138)
		(width 0.14478)
		(layer "In6.Cu")
		(net "M_E_CPU0_SA_DQ<16>")
	)
	(segment
		(start 328.701146 -234.764072)
		(end 328.85507 -235.029502)
		(width 0.0889)
		(layer "In6.Cu")
		(net "M_E_CPU0_SA_DQ<16>")
	)
	(segment
		(start 281.337512 -216.685622)
		(end 281.337512 -216.623138)
		(width 0.14478)
		(layer "In6.Cu")
		(net "M_E_CPU0_SA_DQ<16>")
	)
	(segment
		(start 305.139344 -216.171272)
		(end 304.994564 -216.316052)
		(width 0.14478)
		(layer "In6.Cu")
		(net "M_E_CPU0_SA_DQ<16>")
	)
	(segment
		(start 324.358254 -233.26471)
		(end 323.895974 -232.80243)
		(width 0.0889)
		(layer "In6.Cu")
		(net "M_E_CPU0_SA_DQ<16>")
	)
	(segment
		(start 281.50058 -216.84869)
		(end 281.337512 -216.685622)
		(width 0.14478)
		(layer "In6.Cu")
		(net "M_E_CPU0_SA_DQ<16>")
	)
	(segment
		(start 304.430684 -216.666572)
		(end 304.430684 -216.316052)
		(width 0.14478)
		(layer "In6.Cu")
		(net "M_E_CPU0_SA_DQ<16>")
	)
	(segment
		(start 297.575478 -216.46007)
		(end 297.220386 -216.46007)
		(width 0.14478)
		(layer "In6.Cu")
		(net "M_E_CPU0_SA_DQ<16>")
	)
	(segment
		(start 289.610038 -216.46007)
		(end 289.44697 -216.623138)
		(width 0.14478)
		(layer "In6.Cu")
		(net "M_E_CPU0_SA_DQ<16>")
	)
	(segment
		(start 304.994564 -216.316052)
		(end 304.994564 -216.666572)
		(width 0.14478)
		(layer "In6.Cu")
		(net "M_E_CPU0_SA_DQ<16>")
	)
	(segment
		(start 311.441338 -217.159332)
		(end 308.347872 -217.159332)
		(width 0.14478)
		(layer "In6.Cu")
		(net "M_E_CPU0_SA_DQ<16>")
	)
	(segment
		(start 328.85507 -235.029502)
		(end 328.832718 -235.112814)
		(width 0.0889)
		(layer "In6.Cu")
		(net "M_E_CPU0_SA_DQ<16>")
	)
	(segment
		(start 315.731398 -225.041968)
		(end 313.403234 -222.713804)
		(width 0.14478)
		(layer "In6.Cu")
		(net "M_E_CPU0_SA_DQ<16>")
	)
	(segment
		(start 278.188166 -216.161366)
		(end 277.889462 -216.46007)
		(width 0.14478)
		(layer "In6.Cu")
		(net "M_E_CPU0_SA_DQ<16>")
	)
	(segment
		(start 303.866804 -216.666572)
		(end 303.722024 -216.811352)
		(width 0.14478)
		(layer "In6.Cu")
		(net "M_E_CPU0_SA_DQ<16>")
	)
	(segment
		(start 303.722024 -216.811352)
		(end 302.375824 -216.811352)
		(width 0.14478)
		(layer "In6.Cu")
		(net "M_E_CPU0_SA_DQ<16>")
	)
	(segment
		(start 296.663872 -216.84107)
		(end 296.500804 -216.678002)
		(width 0.14478)
		(layer "In6.Cu")
		(net "M_E_CPU0_SA_DQ<16>")
	)
	(segment
		(start 308.347872 -217.159332)
		(end 307.598572 -216.410032)
		(width 0.14478)
		(layer "In6.Cu")
		(net "M_E_CPU0_SA_DQ<16>")
	)
	(segment
		(start 303.866804 -216.316052)
		(end 303.866804 -216.666572)
		(width 0.14478)
		(layer "In6.Cu")
		(net "M_E_CPU0_SA_DQ<16>")
	)
	(segment
		(start 304.849784 -216.811352)
		(end 304.575464 -216.811352)
		(width 0.14478)
		(layer "In6.Cu")
		(net "M_E_CPU0_SA_DQ<16>")
	)
	(segment
		(start 304.575464 -216.811352)
		(end 304.430684 -216.666572)
		(width 0.14478)
		(layer "In6.Cu")
		(net "M_E_CPU0_SA_DQ<16>")
	)
	(segment
		(start 296.500804 -216.678002)
		(end 296.500804 -216.623138)
		(width 0.14478)
		(layer "In6.Cu")
		(net "M_E_CPU0_SA_DQ<16>")
	)
	(segment
		(start 279.2984 -216.691972)
		(end 279.15362 -216.836752)
		(width 0.14478)
		(layer "In6.Cu")
		(net "M_E_CPU0_SA_DQ<16>")
	)
	(segment
		(start 322.559934 -232.80243)
		(end 315.731398 -225.973894)
		(width 0.14478)
		(layer "In6.Cu")
		(net "M_E_CPU0_SA_DQ<16>")
	)
	(segment
		(start 293.630858 -215.610186)
		(end 290.866322 -215.610186)
		(width 0.14478)
		(layer "In6.Cu")
		(net "M_E_CPU0_SA_DQ<16>")
	)
	(segment
		(start 304.011584 -216.171272)
		(end 303.866804 -216.316052)
		(width 0.14478)
		(layer "In6.Cu")
		(net "M_E_CPU0_SA_DQ<16>")
	)
	(segment
		(start 297.057318 -216.678002)
		(end 296.89425 -216.84107)
		(width 0.14478)
		(layer "In6.Cu")
		(net "M_E_CPU0_SA_DQ<16>")
	)
	(segment
		(start 301.174658 -215.610186)
		(end 298.425362 -215.610186)
		(width 0.14478)
		(layer "In6.Cu")
		(net "M_E_CPU0_SA_DQ<16>")
	)
	(segment
		(start 278.8793 -216.836752)
		(end 278.73452 -216.691972)
		(width 0.14478)
		(layer "In6.Cu")
		(net "M_E_CPU0_SA_DQ<16>")
	)
	(segment
		(start 281.730958 -216.84869)
		(end 281.50058 -216.84869)
		(width 0.14478)
		(layer "In6.Cu")
		(net "M_E_CPU0_SA_DQ<16>")
	)
	(segment
		(start 297.220386 -216.46007)
		(end 297.057318 -216.623138)
		(width 0.14478)
		(layer "In6.Cu")
		(net "M_E_CPU0_SA_DQ<16>")
	)
	(segment
		(start 290.016438 -216.46007)
		(end 289.610038 -216.46007)
		(width 0.14478)
		(layer "In6.Cu")
		(net "M_E_CPU0_SA_DQ<16>")
	)
	(segment
		(start 302.375824 -216.811352)
		(end 301.174658 -215.610186)
		(width 0.14478)
		(layer "In6.Cu")
		(net "M_E_CPU0_SA_DQ<16>")
	)
	(segment
		(start 313.403234 -222.713804)
		(end 313.403234 -219.121228)
		(width 0.14478)
		(layer "In6.Cu")
		(net "M_E_CPU0_SA_DQ<16>")
	)
	(segment
		(start 323.547994 -232.80243)
		(end 322.559934 -232.80243)
		(width 0.14478)
		(layer "In6.Cu")
		(net "M_E_CPU0_SA_DQ<16>")
	)
	(segment
		(start 279.903174 -216.161366)
		(end 279.44318 -216.161366)
		(width 0.14478)
		(layer "In6.Cu")
		(net "M_E_CPU0_SA_DQ<16>")
	)
	(segment
		(start 281.337512 -216.623138)
		(end 281.174444 -216.46007)
		(width 0.14478)
		(layer "In6.Cu")
		(net "M_E_CPU0_SA_DQ<16>")
	)
	(segment
		(start 288.727388 -216.46007)
		(end 286.804862 -216.46007)
		(width 0.14478)
		(layer "In6.Cu")
		(net "M_E_CPU0_SA_DQ<16>")
	)
	(segment
		(start 278.73452 -216.306146)
		(end 278.58974 -216.161366)
		(width 0.14478)
		(layer "In6.Cu")
		(net "M_E_CPU0_SA_DQ<16>")
	)
	(segment
		(start 304.430684 -216.316052)
		(end 304.285904 -216.171272)
		(width 0.14478)
		(layer "In6.Cu")
		(net "M_E_CPU0_SA_DQ<16>")
	)
	(segment
		(start 286.804862 -216.46007)
		(end 285.954978 -215.610186)
		(width 0.14478)
		(layer "In6.Cu")
		(net "M_E_CPU0_SA_DQ<16>")
	)
	(segment
		(start 326.388476 -235.004102)
		(end 326.173846 -235.004102)
		(width 0.0889)
		(layer "In6.Cu")
		(net "M_E_CPU0_SA_DQ<16>")
	)
	(segment
		(start 281.894026 -216.623138)
		(end 281.894026 -216.685622)
		(width 0.14478)
		(layer "In6.Cu")
		(net "M_E_CPU0_SA_DQ<16>")
	)
	(segment
		(start 326.173846 -235.004102)
		(end 325.069454 -233.89971)
		(width 0.0889)
		(layer "In6.Cu")
		(net "M_E_CPU0_SA_DQ<16>")
	)
	(segment
		(start 306.856638 -216.410032)
		(end 306.455318 -216.811352)
		(width 0.14478)
		(layer "In6.Cu")
		(net "M_E_CPU0_SA_DQ<16>")
	)
	(segment
		(start 324.358254 -233.54411)
		(end 324.358254 -233.26471)
		(width 0.0889)
		(layer "In6.Cu")
		(net "M_E_CPU0_SA_DQ<16>")
	)
	(segment
		(start 277.889462 -216.46007)
		(end 277.617174 -216.46007)
		(width 0.14478)
		(layer "In6.Cu")
		(net "M_E_CPU0_SA_DQ<16>")
	)
	(segment
		(start 304.285904 -216.171272)
		(end 304.011584 -216.171272)
		(width 0.14478)
		(layer "In6.Cu")
		(net "M_E_CPU0_SA_DQ<16>")
	)
	(segment
		(start 290.866322 -215.610186)
		(end 290.016438 -216.46007)
		(width 0.14478)
		(layer "In6.Cu")
		(net "M_E_CPU0_SA_DQ<16>")
	)
	(segment
		(start 289.44697 -216.690702)
		(end 289.283902 -216.85377)
		(width 0.14478)
		(layer "In6.Cu")
		(net "M_E_CPU0_SA_DQ<16>")
	)
	(segment
		(start 296.500804 -216.623138)
		(end 296.337736 -216.46007)
		(width 0.14478)
		(layer "In6.Cu")
		(net "M_E_CPU0_SA_DQ<16>")
	)
	(segment
		(start 279.44318 -216.161366)
		(end 279.2984 -216.306146)
		(width 0.14478)
		(layer "In6.Cu")
		(net "M_E_CPU0_SA_DQ<16>")
	)
	(segment
		(start 298.425362 -215.610186)
		(end 297.575478 -216.46007)
		(width 0.14478)
		(layer "In6.Cu")
		(net "M_E_CPU0_SA_DQ<16>")
	)
	(segment
		(start 278.58974 -216.161366)
		(end 278.188166 -216.161366)
		(width 0.14478)
		(layer "In6.Cu")
		(net "M_E_CPU0_SA_DQ<16>")
	)
	(segment
		(start 327.94829 -235.086652)
		(end 327.939908 -235.091478)
		(width 0.0889)
		(layer "In6.Cu")
		(net "M_E_CPU0_SA_DQ<16>")
	)
	(segment
		(start 297.057318 -216.623138)
		(end 297.057318 -216.678002)
		(width 0.14478)
		(layer "In6.Cu")
		(net "M_E_CPU0_SA_DQ<16>")
	)
	(segment
		(start 289.44697 -216.623138)
		(end 289.44697 -216.690702)
		(width 0.14478)
		(layer "In6.Cu")
		(net "M_E_CPU0_SA_DQ<16>")
	)
	(segment
		(start 285.954978 -215.610186)
		(end 283.269182 -215.610186)
		(width 0.14478)
		(layer "In6.Cu")
		(net "M_E_CPU0_SA_DQ<16>")
	)
	(segment
		(start 305.413664 -216.171272)
		(end 305.139344 -216.171272)
		(width 0.14478)
		(layer "In6.Cu")
		(net "M_E_CPU0_SA_DQ<16>")
	)
	(segment
		(start 278.73452 -216.691972)
		(end 278.73452 -216.306146)
		(width 0.14478)
		(layer "In6.Cu")
		(net "M_E_CPU0_SA_DQ<16>")
	)
	(segment
		(start 323.895974 -232.80243)
		(end 323.547994 -232.80243)
		(width 0.0889)
		(layer "In6.Cu")
		(net "M_E_CPU0_SA_DQ<16>")
	)
	(arc
		(start 327.57364 -235.086652)
		(mid 327.296573 -235.010381)
		(end 327.017888 -235.080556)
		(width 0.0889)
		(layer "In6.Cu")
		(net "M_E_CPU0_SA_DQ<16>")
	)
	(arc
		(start 326.649842 -235.095796)
		(mid 326.565483 -235.051685)
		(end 326.476614 -235.017564)
		(width 0.0889)
		(layer "In6.Cu")
		(net "M_E_CPU0_SA_DQ<16>")
	)
	(arc
		(start 327.007474 -235.086652)
		(mid 326.829824 -235.136912)
		(end 326.649842 -235.095796)
		(width 0.0889)
		(layer "In6.Cu")
		(net "M_E_CPU0_SA_DQ<16>")
	)
	(arc
		(start 326.476614 -235.017564)
		(mid 326.433066 -235.007422)
		(end 326.388476 -235.004102)
		(width 0.0889)
		(layer "In6.Cu")
		(net "M_E_CPU0_SA_DQ<16>")
	)
	(arc
		(start 328.514202 -235.086652)
		(mid 328.231246 -235.010475)
		(end 327.94829 -235.086652)
		(width 0.0889)
		(layer "In6.Cu")
		(net "M_E_CPU0_SA_DQ<16>")
	)
	(arc
		(start 327.939908 -235.091478)
		(mid 327.756146 -235.137094)
		(end 327.57364 -235.086652)
		(width 0.0889)
		(layer "In6.Cu")
		(net "M_E_CPU0_SA_DQ<16>")
	)
	(arc
		(start 328.832718 -235.112814)
		(mid 328.670529 -235.135549)
		(end 328.514202 -235.086652)
		(width 0.0889)
		(layer "In6.Cu")
		(net "M_E_CPU0_SA_DQ<16>")
	)
	(segment
		(start 331.047852 -235.03001)
		(end 330.581 -234.764072)
		(width 0.10668)
		(layer "F.Cu")
		(net "M_E_CPU0_SA_DQ<15>")
	)
	(segment
		(start 275.078952 -215.610186)
		(end 274.915884 -215.447118)
		(width 0.14478)
		(layer "In6.Cu")
		(net "M_E_CPU0_SA_DQ<15>")
	)
	(segment
		(start 325.116698 -233.583226)
		(end 325.116698 -233.223562)
		(width 0.0889)
		(layer "In6.Cu")
		(net "M_E_CPU0_SA_DQ<15>")
	)
	(segment
		(start 325.116698 -233.223562)
		(end 324.932802 -233.039666)
		(width 0.0889)
		(layer "In6.Cu")
		(net "M_E_CPU0_SA_DQ<15>")
	)
	(segment
		(start 290.771072 -214.760048)
		(end 289.920934 -215.610186)
		(width 0.14478)
		(layer "In6.Cu")
		(net "M_E_CPU0_SA_DQ<15>")
	)
	(segment
		(start 323.547994 -232.24617)
		(end 322.79717 -232.24617)
		(width 0.14478)
		(layer "In6.Cu")
		(net "M_E_CPU0_SA_DQ<15>")
	)
	(segment
		(start 274.35937 -215.11006)
		(end 274.35937 -215.447118)
		(width 0.14478)
		(layer "In6.Cu")
		(net "M_E_CPU0_SA_DQ<15>")
	)
	(segment
		(start 329.828144 -234.441492)
		(end 329.819762 -234.436666)
		(width 0.0889)
		(layer "In6.Cu")
		(net "M_E_CPU0_SA_DQ<15>")
	)
	(segment
		(start 283.089858 -214.760048)
		(end 282.23972 -215.610186)
		(width 0.14478)
		(layer "In6.Cu")
		(net "M_E_CPU0_SA_DQ<15>")
	)
	(segment
		(start 286.814006 -215.610186)
		(end 285.963868 -214.760048)
		(width 0.14478)
		(layer "In6.Cu")
		(net "M_E_CPU0_SA_DQ<15>")
	)
	(segment
		(start 316.282578 -224.813622)
		(end 313.989974 -222.521018)
		(width 0.14478)
		(layer "In6.Cu")
		(net "M_E_CPU0_SA_DQ<15>")
	)
	(segment
		(start 324.932802 -233.039666)
		(end 324.64883 -233.039666)
		(width 0.0889)
		(layer "In6.Cu")
		(net "M_E_CPU0_SA_DQ<15>")
	)
	(segment
		(start 327.586086 -234.434634)
		(end 327.574402 -234.441492)
		(width 0.0889)
		(layer "In6.Cu")
		(net "M_E_CPU0_SA_DQ<15>")
	)
	(segment
		(start 274.752816 -214.946992)
		(end 274.522438 -214.946992)
		(width 0.14478)
		(layer "In6.Cu")
		(net "M_E_CPU0_SA_DQ<15>")
	)
	(segment
		(start 308.576218 -216.608152)
		(end 307.826918 -215.858852)
		(width 0.14478)
		(layer "In6.Cu")
		(net "M_E_CPU0_SA_DQ<15>")
	)
	(segment
		(start 294.50284 -215.610186)
		(end 293.652702 -214.760048)
		(width 0.14478)
		(layer "In6.Cu")
		(net "M_E_CPU0_SA_DQ<15>")
	)
	(segment
		(start 275.30933 -215.610186)
		(end 275.078952 -215.610186)
		(width 0.14478)
		(layer "In6.Cu")
		(net "M_E_CPU0_SA_DQ<15>")
	)
	(segment
		(start 313.989974 -222.521018)
		(end 313.989974 -218.928442)
		(width 0.14478)
		(layer "In6.Cu")
		(net "M_E_CPU0_SA_DQ<15>")
	)
	(segment
		(start 325.86295 -234.329478)
		(end 325.116698 -233.583226)
		(width 0.0889)
		(layer "In6.Cu")
		(net "M_E_CPU0_SA_DQ<15>")
	)
	(segment
		(start 274.915884 -215.11006)
		(end 274.752816 -214.946992)
		(width 0.14478)
		(layer "In6.Cu")
		(net "M_E_CPU0_SA_DQ<15>")
	)
	(segment
		(start 298.411138 -214.760048)
		(end 297.561 -215.610186)
		(width 0.14478)
		(layer "In6.Cu")
		(net "M_E_CPU0_SA_DQ<15>")
	)
	(segment
		(start 316.282578 -225.731578)
		(end 316.282578 -224.813622)
		(width 0.14478)
		(layer "In6.Cu")
		(net "M_E_CPU0_SA_DQ<15>")
	)
	(segment
		(start 274.915884 -215.447118)
		(end 274.915884 -215.11006)
		(width 0.14478)
		(layer "In6.Cu")
		(net "M_E_CPU0_SA_DQ<15>")
	)
	(segment
		(start 306.269898 -215.858852)
		(end 306.021232 -215.610186)
		(width 0.14478)
		(layer "In6.Cu")
		(net "M_E_CPU0_SA_DQ<15>")
	)
	(segment
		(start 327.008744 -234.441492)
		(end 326.99706 -234.434634)
		(width 0.0889)
		(layer "In6.Cu")
		(net "M_E_CPU0_SA_DQ<15>")
	)
	(segment
		(start 276.028912 -215.14816)
		(end 275.865844 -214.985092)
		(width 0.14478)
		(layer "In6.Cu")
		(net "M_E_CPU0_SA_DQ<15>")
	)
	(segment
		(start 323.855334 -232.24617)
		(end 323.547994 -232.24617)
		(width 0.0889)
		(layer "In6.Cu")
		(net "M_E_CPU0_SA_DQ<15>")
	)
	(segment
		(start 306.021232 -215.610186)
		(end 302.04664 -215.610186)
		(width 0.14478)
		(layer "In6.Cu")
		(net "M_E_CPU0_SA_DQ<15>")
	)
	(segment
		(start 311.669684 -216.608152)
		(end 308.576218 -216.608152)
		(width 0.14478)
		(layer "In6.Cu")
		(net "M_E_CPU0_SA_DQ<15>")
	)
	(segment
		(start 307.826918 -215.858852)
		(end 306.269898 -215.858852)
		(width 0.14478)
		(layer "In6.Cu")
		(net "M_E_CPU0_SA_DQ<15>")
	)
	(segment
		(start 297.561 -215.610186)
		(end 294.50284 -215.610186)
		(width 0.14478)
		(layer "In6.Cu")
		(net "M_E_CPU0_SA_DQ<15>")
	)
	(segment
		(start 275.865844 -214.985092)
		(end 275.635466 -214.985092)
		(width 0.14478)
		(layer "In6.Cu")
		(net "M_E_CPU0_SA_DQ<15>")
	)
	(segment
		(start 326.080628 -234.448604)
		(end 325.86295 -234.329478)
		(width 0.0889)
		(layer "In6.Cu")
		(net "M_E_CPU0_SA_DQ<15>")
	)
	(segment
		(start 273.51736 -215.610186)
		(end 273.092164 -215.18499)
		(width 0.14478)
		(layer "In6.Cu")
		(net "M_E_CPU0_SA_DQ<15>")
	)
	(segment
		(start 275.472398 -215.14816)
		(end 275.472398 -215.447118)
		(width 0.14478)
		(layer "In6.Cu")
		(net "M_E_CPU0_SA_DQ<15>")
	)
	(segment
		(start 324.64883 -233.039666)
		(end 323.855334 -232.24617)
		(width 0.0889)
		(layer "In6.Cu")
		(net "M_E_CPU0_SA_DQ<15>")
	)
	(segment
		(start 330.581 -234.764072)
		(end 330.427076 -234.498642)
		(width 0.0889)
		(layer "In6.Cu")
		(net "M_E_CPU0_SA_DQ<15>")
	)
	(segment
		(start 322.79717 -232.24617)
		(end 316.282578 -225.731578)
		(width 0.14478)
		(layer "In6.Cu")
		(net "M_E_CPU0_SA_DQ<15>")
	)
	(segment
		(start 285.963868 -214.760048)
		(end 283.089858 -214.760048)
		(width 0.14478)
		(layer "In6.Cu")
		(net "M_E_CPU0_SA_DQ<15>")
	)
	(segment
		(start 275.472398 -215.447118)
		(end 275.30933 -215.610186)
		(width 0.14478)
		(layer "In6.Cu")
		(net "M_E_CPU0_SA_DQ<15>")
	)
	(segment
		(start 313.989974 -218.928442)
		(end 311.669684 -216.608152)
		(width 0.14478)
		(layer "In6.Cu")
		(net "M_E_CPU0_SA_DQ<15>")
	)
	(segment
		(start 289.920934 -215.610186)
		(end 286.814006 -215.610186)
		(width 0.14478)
		(layer "In6.Cu")
		(net "M_E_CPU0_SA_DQ<15>")
	)
	(segment
		(start 301.196502 -214.760048)
		(end 298.411138 -214.760048)
		(width 0.14478)
		(layer "In6.Cu")
		(net "M_E_CPU0_SA_DQ<15>")
	)
	(segment
		(start 274.196302 -215.610186)
		(end 273.51736 -215.610186)
		(width 0.14478)
		(layer "In6.Cu")
		(net "M_E_CPU0_SA_DQ<15>")
	)
	(segment
		(start 274.522438 -214.946992)
		(end 274.35937 -215.11006)
		(width 0.14478)
		(layer "In6.Cu")
		(net "M_E_CPU0_SA_DQ<15>")
	)
	(segment
		(start 276.028912 -215.447118)
		(end 276.028912 -215.14816)
		(width 0.14478)
		(layer "In6.Cu")
		(net "M_E_CPU0_SA_DQ<15>")
	)
	(segment
		(start 330.427076 -234.498642)
		(end 330.331064 -234.473242)
		(width 0.0889)
		(layer "In6.Cu")
		(net "M_E_CPU0_SA_DQ<15>")
	)
	(segment
		(start 302.04664 -215.610186)
		(end 301.196502 -214.760048)
		(width 0.14478)
		(layer "In6.Cu")
		(net "M_E_CPU0_SA_DQ<15>")
	)
	(segment
		(start 275.635466 -214.985092)
		(end 275.472398 -215.14816)
		(width 0.14478)
		(layer "In6.Cu")
		(net "M_E_CPU0_SA_DQ<15>")
	)
	(segment
		(start 293.652702 -214.760048)
		(end 290.771072 -214.760048)
		(width 0.14478)
		(layer "In6.Cu")
		(net "M_E_CPU0_SA_DQ<15>")
	)
	(segment
		(start 327.574402 -234.441492)
		(end 327.563988 -234.447588)
		(width 0.0889)
		(layer "In6.Cu")
		(net "M_E_CPU0_SA_DQ<15>")
	)
	(segment
		(start 274.35937 -215.447118)
		(end 274.196302 -215.610186)
		(width 0.14478)
		(layer "In6.Cu")
		(net "M_E_CPU0_SA_DQ<15>")
	)
	(segment
		(start 276.19198 -215.610186)
		(end 276.028912 -215.447118)
		(width 0.14478)
		(layer "In6.Cu")
		(net "M_E_CPU0_SA_DQ<15>")
	)
	(segment
		(start 282.23972 -215.610186)
		(end 276.19198 -215.610186)
		(width 0.14478)
		(layer "In6.Cu")
		(net "M_E_CPU0_SA_DQ<15>")
	)
	(arc
		(start 327.94829 -234.441492)
		(mid 327.768085 -234.391175)
		(end 327.586086 -234.434634)
		(width 0.0889)
		(layer "In6.Cu")
		(net "M_E_CPU0_SA_DQ<15>")
	)
	(arc
		(start 328.88809 -234.441492)
		(mid 328.701146 -234.391237)
		(end 328.514202 -234.441492)
		(width 0.0889)
		(layer "In6.Cu")
		(net "M_E_CPU0_SA_DQ<15>")
	)
	(arc
		(start 326.99706 -234.434634)
		(mid 326.814805 -234.390981)
		(end 326.634348 -234.441492)
		(width 0.0889)
		(layer "In6.Cu")
		(net "M_E_CPU0_SA_DQ<15>")
	)
	(arc
		(start 329.819762 -234.436666)
		(mid 329.636254 -234.391172)
		(end 329.454002 -234.441492)
		(width 0.0889)
		(layer "In6.Cu")
		(net "M_E_CPU0_SA_DQ<15>")
	)
	(arc
		(start 327.563988 -234.447588)
		(mid 327.285556 -234.517686)
		(end 327.008744 -234.441492)
		(width 0.0889)
		(layer "In6.Cu")
		(net "M_E_CPU0_SA_DQ<15>")
	)
	(arc
		(start 326.634348 -234.441492)
		(mid 326.358416 -234.517749)
		(end 326.080628 -234.448604)
		(width 0.0889)
		(layer "In6.Cu")
		(net "M_E_CPU0_SA_DQ<15>")
	)
	(arc
		(start 329.454002 -234.441492)
		(mid 329.171046 -234.517669)
		(end 328.88809 -234.441492)
		(width 0.0889)
		(layer "In6.Cu")
		(net "M_E_CPU0_SA_DQ<15>")
	)
	(arc
		(start 328.514202 -234.441492)
		(mid 328.231246 -234.517669)
		(end 327.94829 -234.441492)
		(width 0.0889)
		(layer "In6.Cu")
		(net "M_E_CPU0_SA_DQ<15>")
	)
	(arc
		(start 330.331064 -234.473242)
		(mid 330.075856 -234.516719)
		(end 329.828144 -234.441492)
		(width 0.0889)
		(layer "In6.Cu")
		(net "M_E_CPU0_SA_DQ<15>")
	)
	(segment
		(start 329.637898 -234.220004)
		(end 329.171046 -233.954066)
		(width 0.10668)
		(layer "F.Cu")
		(net "M_E_CPU0_SA_DQ<14>")
	)
	(segment
		(start 294.50284 -213.910164)
		(end 293.652702 -213.060026)
		(width 0.14478)
		(layer "In6.Cu")
		(net "M_E_CPU0_SA_DQ<14>")
	)
	(segment
		(start 285.963868 -213.060026)
		(end 283.089858 -213.060026)
		(width 0.14478)
		(layer "In6.Cu")
		(net "M_E_CPU0_SA_DQ<14>")
	)
	(segment
		(start 324.383654 -232.084118)
		(end 324.383654 -231.82453)
		(width 0.0889)
		(layer "In6.Cu")
		(net "M_E_CPU0_SA_DQ<14>")
	)
	(segment
		(start 300.829726 -213.060026)
		(end 298.411138 -213.060026)
		(width 0.14478)
		(layer "In6.Cu")
		(net "M_E_CPU0_SA_DQ<14>")
	)
	(segment
		(start 323.174106 -231.33685)
		(end 317.181738 -225.344482)
		(width 0.14478)
		(layer "In6.Cu")
		(net "M_E_CPU0_SA_DQ<14>")
	)
	(segment
		(start 274.50542 -213.910164)
		(end 273.51736 -213.910164)
		(width 0.14478)
		(layer "In6.Cu")
		(net "M_E_CPU0_SA_DQ<14>")
	)
	(segment
		(start 324.878446 -232.57891)
		(end 324.383654 -232.084118)
		(width 0.0889)
		(layer "In6.Cu")
		(net "M_E_CPU0_SA_DQ<14>")
	)
	(segment
		(start 306.651406 -214.456772)
		(end 306.506626 -214.601552)
		(width 0.14478)
		(layer "In6.Cu")
		(net "M_E_CPU0_SA_DQ<14>")
	)
	(segment
		(start 275.618448 -213.910164)
		(end 275.38807 -213.910164)
		(width 0.14478)
		(layer "In6.Cu")
		(net "M_E_CPU0_SA_DQ<14>")
	)
	(segment
		(start 275.225002 -213.747096)
		(end 275.225002 -213.36762)
		(width 0.14478)
		(layer "In6.Cu")
		(net "M_E_CPU0_SA_DQ<14>")
	)
	(segment
		(start 329.171046 -233.954066)
		(end 329.017122 -233.688636)
		(width 0.0889)
		(layer "In6.Cu")
		(net "M_E_CPU0_SA_DQ<14>")
	)
	(segment
		(start 297.561 -213.910164)
		(end 294.50284 -213.910164)
		(width 0.14478)
		(layer "In6.Cu")
		(net "M_E_CPU0_SA_DQ<14>")
	)
	(segment
		(start 324.383654 -231.82453)
		(end 323.895974 -231.33685)
		(width 0.0889)
		(layer "In6.Cu")
		(net "M_E_CPU0_SA_DQ<14>")
	)
	(segment
		(start 306.232306 -214.601552)
		(end 306.087526 -214.456772)
		(width 0.14478)
		(layer "In6.Cu")
		(net "M_E_CPU0_SA_DQ<14>")
	)
	(segment
		(start 286.814006 -213.910164)
		(end 285.963868 -213.060026)
		(width 0.14478)
		(layer "In6.Cu")
		(net "M_E_CPU0_SA_DQ<14>")
	)
	(segment
		(start 309.296308 -215.708992)
		(end 307.505608 -213.918292)
		(width 0.14478)
		(layer "In6.Cu")
		(net "M_E_CPU0_SA_DQ<14>")
	)
	(segment
		(start 317.181738 -225.344482)
		(end 317.181738 -224.44075)
		(width 0.14478)
		(layer "In6.Cu")
		(net "M_E_CPU0_SA_DQ<14>")
	)
	(segment
		(start 306.087526 -214.063072)
		(end 305.942746 -213.918292)
		(width 0.14478)
		(layer "In6.Cu")
		(net "M_E_CPU0_SA_DQ<14>")
	)
	(segment
		(start 298.411138 -213.060026)
		(end 297.561 -213.910164)
		(width 0.14478)
		(layer "In6.Cu")
		(net "M_E_CPU0_SA_DQ<14>")
	)
	(segment
		(start 327.488804 -233.637582)
		(end 327.47839 -233.631486)
		(width 0.0889)
		(layer "In6.Cu")
		(net "M_E_CPU0_SA_DQ<14>")
	)
	(segment
		(start 273.51736 -213.910164)
		(end 273.092164 -213.484968)
		(width 0.14478)
		(layer "In6.Cu")
		(net "M_E_CPU0_SA_DQ<14>")
	)
	(segment
		(start 305.942746 -213.918292)
		(end 301.687992 -213.918292)
		(width 0.14478)
		(layer "In6.Cu")
		(net "M_E_CPU0_SA_DQ<14>")
	)
	(segment
		(start 314.914534 -222.173546)
		(end 314.914534 -218.580716)
		(width 0.14478)
		(layer "In6.Cu")
		(net "M_E_CPU0_SA_DQ<14>")
	)
	(segment
		(start 328.41819 -233.631486)
		(end 328.409808 -233.62666)
		(width 0.0889)
		(layer "In6.Cu")
		(net "M_E_CPU0_SA_DQ<14>")
	)
	(segment
		(start 275.944584 -213.168992)
		(end 275.781516 -213.33206)
		(width 0.14478)
		(layer "In6.Cu")
		(net "M_E_CPU0_SA_DQ<14>")
	)
	(segment
		(start 275.781516 -213.33206)
		(end 275.781516 -213.747096)
		(width 0.14478)
		(layer "In6.Cu")
		(net "M_E_CPU0_SA_DQ<14>")
	)
	(segment
		(start 274.668488 -213.36762)
		(end 274.668488 -213.747096)
		(width 0.14478)
		(layer "In6.Cu")
		(net "M_E_CPU0_SA_DQ<14>")
	)
	(segment
		(start 306.796186 -213.918292)
		(end 306.651406 -214.063072)
		(width 0.14478)
		(layer "In6.Cu")
		(net "M_E_CPU0_SA_DQ<14>")
	)
	(segment
		(start 307.505608 -213.918292)
		(end 306.796186 -213.918292)
		(width 0.14478)
		(layer "In6.Cu")
		(net "M_E_CPU0_SA_DQ<14>")
	)
	(segment
		(start 327.104502 -233.631486)
		(end 327.094088 -233.637582)
		(width 0.0889)
		(layer "In6.Cu")
		(net "M_E_CPU0_SA_DQ<14>")
	)
	(segment
		(start 276.33803 -213.747096)
		(end 276.33803 -213.33206)
		(width 0.14478)
		(layer "In6.Cu")
		(net "M_E_CPU0_SA_DQ<14>")
	)
	(segment
		(start 306.651406 -214.063072)
		(end 306.651406 -214.456772)
		(width 0.14478)
		(layer "In6.Cu")
		(net "M_E_CPU0_SA_DQ<14>")
	)
	(segment
		(start 275.061934 -213.204552)
		(end 274.831556 -213.204552)
		(width 0.14478)
		(layer "In6.Cu")
		(net "M_E_CPU0_SA_DQ<14>")
	)
	(segment
		(start 275.225002 -213.36762)
		(end 275.061934 -213.204552)
		(width 0.14478)
		(layer "In6.Cu")
		(net "M_E_CPU0_SA_DQ<14>")
	)
	(segment
		(start 293.652702 -213.060026)
		(end 290.771072 -213.060026)
		(width 0.14478)
		(layer "In6.Cu")
		(net "M_E_CPU0_SA_DQ<14>")
	)
	(segment
		(start 306.087526 -214.456772)
		(end 306.087526 -214.063072)
		(width 0.14478)
		(layer "In6.Cu")
		(net "M_E_CPU0_SA_DQ<14>")
	)
	(segment
		(start 283.089858 -213.060026)
		(end 282.23972 -213.910164)
		(width 0.14478)
		(layer "In6.Cu")
		(net "M_E_CPU0_SA_DQ<14>")
	)
	(segment
		(start 326.118728 -233.585512)
		(end 325.112126 -232.57891)
		(width 0.0889)
		(layer "In6.Cu")
		(net "M_E_CPU0_SA_DQ<14>")
	)
	(segment
		(start 274.831556 -213.204552)
		(end 274.668488 -213.36762)
		(width 0.14478)
		(layer "In6.Cu")
		(net "M_E_CPU0_SA_DQ<14>")
	)
	(segment
		(start 312.04281 -215.708992)
		(end 309.296308 -215.708992)
		(width 0.14478)
		(layer "In6.Cu")
		(net "M_E_CPU0_SA_DQ<14>")
	)
	(segment
		(start 274.668488 -213.747096)
		(end 274.50542 -213.910164)
		(width 0.14478)
		(layer "In6.Cu")
		(net "M_E_CPU0_SA_DQ<14>")
	)
	(segment
		(start 275.38807 -213.910164)
		(end 275.225002 -213.747096)
		(width 0.14478)
		(layer "In6.Cu")
		(net "M_E_CPU0_SA_DQ<14>")
	)
	(segment
		(start 276.501098 -213.910164)
		(end 276.33803 -213.747096)
		(width 0.14478)
		(layer "In6.Cu")
		(net "M_E_CPU0_SA_DQ<14>")
	)
	(segment
		(start 323.547994 -231.33685)
		(end 323.174106 -231.33685)
		(width 0.14478)
		(layer "In6.Cu")
		(net "M_E_CPU0_SA_DQ<14>")
	)
	(segment
		(start 314.914534 -218.580716)
		(end 312.04281 -215.708992)
		(width 0.14478)
		(layer "In6.Cu")
		(net "M_E_CPU0_SA_DQ<14>")
	)
	(segment
		(start 290.771072 -213.060026)
		(end 289.920934 -213.910164)
		(width 0.14478)
		(layer "In6.Cu")
		(net "M_E_CPU0_SA_DQ<14>")
	)
	(segment
		(start 289.920934 -213.910164)
		(end 286.814006 -213.910164)
		(width 0.14478)
		(layer "In6.Cu")
		(net "M_E_CPU0_SA_DQ<14>")
	)
	(segment
		(start 323.895974 -231.33685)
		(end 323.547994 -231.33685)
		(width 0.0889)
		(layer "In6.Cu")
		(net "M_E_CPU0_SA_DQ<14>")
	)
	(segment
		(start 317.181738 -224.44075)
		(end 314.914534 -222.173546)
		(width 0.14478)
		(layer "In6.Cu")
		(net "M_E_CPU0_SA_DQ<14>")
	)
	(segment
		(start 325.112126 -232.57891)
		(end 324.878446 -232.57891)
		(width 0.0889)
		(layer "In6.Cu")
		(net "M_E_CPU0_SA_DQ<14>")
	)
	(segment
		(start 276.33803 -213.33206)
		(end 276.174962 -213.168992)
		(width 0.14478)
		(layer "In6.Cu")
		(net "M_E_CPU0_SA_DQ<14>")
	)
	(segment
		(start 301.687992 -213.918292)
		(end 300.829726 -213.060026)
		(width 0.14478)
		(layer "In6.Cu")
		(net "M_E_CPU0_SA_DQ<14>")
	)
	(segment
		(start 329.017122 -233.688636)
		(end 328.92111 -233.663236)
		(width 0.0889)
		(layer "In6.Cu")
		(net "M_E_CPU0_SA_DQ<14>")
	)
	(segment
		(start 276.174962 -213.168992)
		(end 275.944584 -213.168992)
		(width 0.14478)
		(layer "In6.Cu")
		(net "M_E_CPU0_SA_DQ<14>")
	)
	(segment
		(start 326.367648 -233.585512)
		(end 326.118728 -233.585512)
		(width 0.0889)
		(layer "In6.Cu")
		(net "M_E_CPU0_SA_DQ<14>")
	)
	(segment
		(start 306.506626 -214.601552)
		(end 306.232306 -214.601552)
		(width 0.14478)
		(layer "In6.Cu")
		(net "M_E_CPU0_SA_DQ<14>")
	)
	(segment
		(start 282.23972 -213.910164)
		(end 276.501098 -213.910164)
		(width 0.14478)
		(layer "In6.Cu")
		(net "M_E_CPU0_SA_DQ<14>")
	)
	(segment
		(start 275.781516 -213.747096)
		(end 275.618448 -213.910164)
		(width 0.14478)
		(layer "In6.Cu")
		(net "M_E_CPU0_SA_DQ<14>")
	)
	(arc
		(start 327.094088 -233.637582)
		(mid 326.815402 -233.707802)
		(end 326.538336 -233.631486)
		(width 0.0889)
		(layer "In6.Cu")
		(net "M_E_CPU0_SA_DQ<14>")
	)
	(arc
		(start 327.47839 -233.631486)
		(mid 327.291446 -233.581231)
		(end 327.104502 -233.631486)
		(width 0.0889)
		(layer "In6.Cu")
		(net "M_E_CPU0_SA_DQ<14>")
	)
	(arc
		(start 326.538336 -233.631486)
		(mid 326.456038 -233.597182)
		(end 326.367648 -233.585512)
		(width 0.0889)
		(layer "In6.Cu")
		(net "M_E_CPU0_SA_DQ<14>")
	)
	(arc
		(start 328.044048 -233.631486)
		(mid 327.767235 -233.707629)
		(end 327.488804 -233.637582)
		(width 0.0889)
		(layer "In6.Cu")
		(net "M_E_CPU0_SA_DQ<14>")
	)
	(arc
		(start 328.409808 -233.62666)
		(mid 328.2263 -233.581166)
		(end 328.044048 -233.631486)
		(width 0.0889)
		(layer "In6.Cu")
		(net "M_E_CPU0_SA_DQ<14>")
	)
	(arc
		(start 328.92111 -233.663236)
		(mid 328.665902 -233.706713)
		(end 328.41819 -233.631486)
		(width 0.0889)
		(layer "In6.Cu")
		(net "M_E_CPU0_SA_DQ<14>")
	)
	(segment
		(start 330.577952 -234.220004)
		(end 330.1111 -233.954066)
		(width 0.10668)
		(layer "F.Cu")
		(net "M_E_CPU0_SA_DQ<13>")
	)
	(segment
		(start 289.105848 -214.983822)
		(end 289.105848 -214.923116)
		(width 0.14478)
		(layer "In6.Cu")
		(net "M_E_CPU0_SA_DQ<13>")
	)
	(segment
		(start 305.58232 -215.160606)
		(end 305.43754 -215.015826)
		(width 0.14478)
		(layer "In6.Cu")
		(net "M_E_CPU0_SA_DQ<13>")
	)
	(segment
		(start 281.790648 -215.15197)
		(end 281.56027 -215.15197)
		(width 0.14478)
		(layer "In6.Cu")
		(net "M_E_CPU0_SA_DQ<13>")
	)
	(segment
		(start 279.966928 -214.988902)
		(end 279.80386 -215.15197)
		(width 0.14478)
		(layer "In6.Cu")
		(net "M_E_CPU0_SA_DQ<13>")
	)
	(segment
		(start 325.323454 -233.13771)
		(end 325.018654 -232.83291)
		(width 0.0889)
		(layer "In6.Cu")
		(net "M_E_CPU0_SA_DQ<13>")
	)
	(segment
		(start 328.41819 -234.276646)
		(end 328.409808 -234.281472)
		(width 0.0889)
		(layer "In6.Cu")
		(net "M_E_CPU0_SA_DQ<13>")
	)
	(segment
		(start 297.257216 -214.983822)
		(end 297.094148 -215.14689)
		(width 0.14478)
		(layer "In6.Cu")
		(net "M_E_CPU0_SA_DQ<13>")
	)
	(segment
		(start 278.8539 -214.531194)
		(end 278.8539 -214.988902)
		(width 0.14478)
		(layer "In6.Cu")
		(net "M_E_CPU0_SA_DQ<13>")
	)
	(segment
		(start 278.134318 -214.760048)
		(end 277.617174 -214.760048)
		(width 0.14478)
		(layer "In6.Cu")
		(net "M_E_CPU0_SA_DQ<13>")
	)
	(segment
		(start 311.856374 -216.158572)
		(end 308.762654 -216.158572)
		(width 0.14478)
		(layer "In6.Cu")
		(net "M_E_CPU0_SA_DQ<13>")
	)
	(segment
		(start 324.843394 -232.83291)
		(end 324.139814 -232.12933)
		(width 0.0889)
		(layer "In6.Cu")
		(net "M_E_CPU0_SA_DQ<13>")
	)
	(segment
		(start 294.480742 -214.760048)
		(end 293.630858 -213.910164)
		(width 0.14478)
		(layer "In6.Cu")
		(net "M_E_CPU0_SA_DQ<13>")
	)
	(segment
		(start 279.247346 -214.368126)
		(end 279.016968 -214.368126)
		(width 0.14478)
		(layer "In6.Cu")
		(net "M_E_CPU0_SA_DQ<13>")
	)
	(segment
		(start 297.765978 -214.760048)
		(end 297.420284 -214.760048)
		(width 0.14478)
		(layer "In6.Cu")
		(net "M_E_CPU0_SA_DQ<13>")
	)
	(segment
		(start 281.234134 -214.760048)
		(end 280.129996 -214.760048)
		(width 0.14478)
		(layer "In6.Cu")
		(net "M_E_CPU0_SA_DQ<13>")
	)
	(segment
		(start 322.985638 -231.79151)
		(end 316.732158 -225.53803)
		(width 0.14478)
		(layer "In6.Cu")
		(net "M_E_CPU0_SA_DQ<13>")
	)
	(segment
		(start 304.30978 -215.015826)
		(end 304.30978 -214.512652)
		(width 0.14478)
		(layer "In6.Cu")
		(net "M_E_CPU0_SA_DQ<13>")
	)
	(segment
		(start 278.460454 -215.15197)
		(end 278.297386 -214.988902)
		(width 0.14478)
		(layer "In6.Cu")
		(net "M_E_CPU0_SA_DQ<13>")
	)
	(segment
		(start 278.297386 -214.923116)
		(end 278.134318 -214.760048)
		(width 0.14478)
		(layer "In6.Cu")
		(net "M_E_CPU0_SA_DQ<13>")
	)
	(segment
		(start 278.297386 -214.988902)
		(end 278.297386 -214.923116)
		(width 0.14478)
		(layer "In6.Cu")
		(net "M_E_CPU0_SA_DQ<13>")
	)
	(segment
		(start 323.547994 -231.79151)
		(end 322.985638 -231.79151)
		(width 0.14478)
		(layer "In6.Cu")
		(net "M_E_CPU0_SA_DQ<13>")
	)
	(segment
		(start 282.444698 -214.760048)
		(end 282.116784 -214.760048)
		(width 0.14478)
		(layer "In6.Cu")
		(net "M_E_CPU0_SA_DQ<13>")
	)
	(segment
		(start 305.43754 -215.015826)
		(end 305.43754 -214.512652)
		(width 0.14478)
		(layer "In6.Cu")
		(net "M_E_CPU0_SA_DQ<13>")
	)
	(segment
		(start 288.94278 -214.760048)
		(end 286.804862 -214.760048)
		(width 0.14478)
		(layer "In6.Cu")
		(net "M_E_CPU0_SA_DQ<13>")
	)
	(segment
		(start 278.690832 -215.15197)
		(end 278.460454 -215.15197)
		(width 0.14478)
		(layer "In6.Cu")
		(net "M_E_CPU0_SA_DQ<13>")
	)
	(segment
		(start 296.700702 -214.983822)
		(end 296.700702 -214.923116)
		(width 0.14478)
		(layer "In6.Cu")
		(net "M_E_CPU0_SA_DQ<13>")
	)
	(segment
		(start 330.1111 -233.954066)
		(end 330.265024 -234.219496)
		(width 0.0889)
		(layer "In6.Cu")
		(net "M_E_CPU0_SA_DQ<13>")
	)
	(segment
		(start 302.233076 -215.160606)
		(end 300.982634 -213.910164)
		(width 0.14478)
		(layer "In6.Cu")
		(net "M_E_CPU0_SA_DQ<13>")
	)
	(segment
		(start 328.992484 -234.281472)
		(end 328.984102 -234.276646)
		(width 0.0889)
		(layer "In6.Cu")
		(net "M_E_CPU0_SA_DQ<13>")
	)
	(segment
		(start 296.700702 -214.923116)
		(end 296.537634 -214.760048)
		(width 0.14478)
		(layer "In6.Cu")
		(net "M_E_CPU0_SA_DQ<13>")
	)
	(segment
		(start 297.094148 -215.14689)
		(end 296.86377 -215.14689)
		(width 0.14478)
		(layer "In6.Cu")
		(net "M_E_CPU0_SA_DQ<13>")
	)
	(segment
		(start 305.29276 -214.367872)
		(end 305.01844 -214.367872)
		(width 0.14478)
		(layer "In6.Cu")
		(net "M_E_CPU0_SA_DQ<13>")
	)
	(segment
		(start 289.105848 -214.923116)
		(end 288.94278 -214.760048)
		(width 0.14478)
		(layer "In6.Cu")
		(net "M_E_CPU0_SA_DQ<13>")
	)
	(segment
		(start 279.573482 -215.15197)
		(end 279.410414 -214.988902)
		(width 0.14478)
		(layer "In6.Cu")
		(net "M_E_CPU0_SA_DQ<13>")
	)
	(segment
		(start 289.662362 -214.923116)
		(end 289.662362 -214.983822)
		(width 0.14478)
		(layer "In6.Cu")
		(net "M_E_CPU0_SA_DQ<13>")
	)
	(segment
		(start 281.56027 -215.15197)
		(end 281.397202 -214.988902)
		(width 0.14478)
		(layer "In6.Cu")
		(net "M_E_CPU0_SA_DQ<13>")
	)
	(segment
		(start 296.537634 -214.760048)
		(end 294.480742 -214.760048)
		(width 0.14478)
		(layer "In6.Cu")
		(net "M_E_CPU0_SA_DQ<13>")
	)
	(segment
		(start 277.617174 -214.760048)
		(end 277.192232 -214.335106)
		(width 0.14478)
		(layer "In6.Cu")
		(net "M_E_CPU0_SA_DQ<13>")
	)
	(segment
		(start 293.630858 -213.910164)
		(end 290.927282 -213.910164)
		(width 0.14478)
		(layer "In6.Cu")
		(net "M_E_CPU0_SA_DQ<13>")
	)
	(segment
		(start 289.82543 -214.760048)
		(end 289.662362 -214.923116)
		(width 0.14478)
		(layer "In6.Cu")
		(net "M_E_CPU0_SA_DQ<13>")
	)
	(segment
		(start 304.87366 -214.512652)
		(end 304.87366 -215.015826)
		(width 0.14478)
		(layer "In6.Cu")
		(net "M_E_CPU0_SA_DQ<13>")
	)
	(segment
		(start 278.8539 -214.988902)
		(end 278.690832 -215.15197)
		(width 0.14478)
		(layer "In6.Cu")
		(net "M_E_CPU0_SA_DQ<13>")
	)
	(segment
		(start 308.400196 -215.44915)
		(end 307.638958 -214.687912)
		(width 0.14478)
		(layer "In6.Cu")
		(net "M_E_CPU0_SA_DQ<13>")
	)
	(segment
		(start 279.016968 -214.368126)
		(end 278.8539 -214.531194)
		(width 0.14478)
		(layer "In6.Cu")
		(net "M_E_CPU0_SA_DQ<13>")
	)
	(segment
		(start 305.43754 -214.512652)
		(end 305.29276 -214.367872)
		(width 0.14478)
		(layer "In6.Cu")
		(net "M_E_CPU0_SA_DQ<13>")
	)
	(segment
		(start 283.294582 -213.910164)
		(end 282.444698 -214.760048)
		(width 0.14478)
		(layer "In6.Cu")
		(net "M_E_CPU0_SA_DQ<13>")
	)
	(segment
		(start 297.420284 -214.760048)
		(end 297.257216 -214.923116)
		(width 0.14478)
		(layer "In6.Cu")
		(net "M_E_CPU0_SA_DQ<13>")
	)
	(segment
		(start 304.87366 -215.015826)
		(end 304.72888 -215.160606)
		(width 0.14478)
		(layer "In6.Cu")
		(net "M_E_CPU0_SA_DQ<13>")
	)
	(segment
		(start 326.182736 -234.286806)
		(end 325.98614 -234.174792)
		(width 0.0889)
		(layer "In6.Cu")
		(net "M_E_CPU0_SA_DQ<13>")
	)
	(segment
		(start 305.01844 -214.367872)
		(end 304.87366 -214.512652)
		(width 0.14478)
		(layer "In6.Cu")
		(net "M_E_CPU0_SA_DQ<13>")
	)
	(segment
		(start 280.129996 -214.760048)
		(end 279.966928 -214.923116)
		(width 0.14478)
		(layer "In6.Cu")
		(net "M_E_CPU0_SA_DQ<13>")
	)
	(segment
		(start 303.7459 -215.015826)
		(end 303.60112 -215.160606)
		(width 0.14478)
		(layer "In6.Cu")
		(net "M_E_CPU0_SA_DQ<13>")
	)
	(segment
		(start 281.397202 -214.923116)
		(end 281.234134 -214.760048)
		(width 0.14478)
		(layer "In6.Cu")
		(net "M_E_CPU0_SA_DQ<13>")
	)
	(segment
		(start 324.139814 -232.12933)
		(end 324.139814 -232.04043)
		(width 0.0889)
		(layer "In6.Cu")
		(net "M_E_CPU0_SA_DQ<13>")
	)
	(segment
		(start 304.45456 -215.160606)
		(end 304.30978 -215.015826)
		(width 0.14478)
		(layer "In6.Cu")
		(net "M_E_CPU0_SA_DQ<13>")
	)
	(segment
		(start 308.762654 -216.158572)
		(end 308.400196 -215.796114)
		(width 0.14478)
		(layer "In6.Cu")
		(net "M_E_CPU0_SA_DQ<13>")
	)
	(segment
		(start 304.165 -214.367872)
		(end 303.89068 -214.367872)
		(width 0.14478)
		(layer "In6.Cu")
		(net "M_E_CPU0_SA_DQ<13>")
	)
	(segment
		(start 289.662362 -214.983822)
		(end 289.499294 -215.14689)
		(width 0.14478)
		(layer "In6.Cu")
		(net "M_E_CPU0_SA_DQ<13>")
	)
	(segment
		(start 296.86377 -215.14689)
		(end 296.700702 -214.983822)
		(width 0.14478)
		(layer "In6.Cu")
		(net "M_E_CPU0_SA_DQ<13>")
	)
	(segment
		(start 290.927282 -213.910164)
		(end 290.077398 -214.760048)
		(width 0.14478)
		(layer "In6.Cu")
		(net "M_E_CPU0_SA_DQ<13>")
	)
	(segment
		(start 290.077398 -214.760048)
		(end 289.82543 -214.760048)
		(width 0.14478)
		(layer "In6.Cu")
		(net "M_E_CPU0_SA_DQ<13>")
	)
	(segment
		(start 314.459874 -218.762072)
		(end 311.856374 -216.158572)
		(width 0.14478)
		(layer "In6.Cu")
		(net "M_E_CPU0_SA_DQ<13>")
	)
	(segment
		(start 327.104756 -234.276646)
		(end 327.094342 -234.27055)
		(width 0.0889)
		(layer "In6.Cu")
		(net "M_E_CPU0_SA_DQ<13>")
	)
	(segment
		(start 281.953716 -214.923116)
		(end 281.953716 -214.988902)
		(width 0.14478)
		(layer "In6.Cu")
		(net "M_E_CPU0_SA_DQ<13>")
	)
	(segment
		(start 324.139814 -232.04043)
		(end 323.890894 -231.79151)
		(width 0.0889)
		(layer "In6.Cu")
		(net "M_E_CPU0_SA_DQ<13>")
	)
	(segment
		(start 316.732158 -224.627186)
		(end 314.459874 -222.354902)
		(width 0.14478)
		(layer "In6.Cu")
		(net "M_E_CPU0_SA_DQ<13>")
	)
	(segment
		(start 325.323454 -233.512106)
		(end 325.323454 -233.13771)
		(width 0.0889)
		(layer "In6.Cu")
		(net "M_E_CPU0_SA_DQ<13>")
	)
	(segment
		(start 304.72888 -215.160606)
		(end 304.45456 -215.160606)
		(width 0.14478)
		(layer "In6.Cu")
		(net "M_E_CPU0_SA_DQ<13>")
	)
	(segment
		(start 306.625244 -215.160606)
		(end 305.58232 -215.160606)
		(width 0.14478)
		(layer "In6.Cu")
		(net "M_E_CPU0_SA_DQ<13>")
	)
	(segment
		(start 298.615862 -213.910164)
		(end 297.765978 -214.760048)
		(width 0.14478)
		(layer "In6.Cu")
		(net "M_E_CPU0_SA_DQ<13>")
	)
	(segment
		(start 297.257216 -214.923116)
		(end 297.257216 -214.983822)
		(width 0.14478)
		(layer "In6.Cu")
		(net "M_E_CPU0_SA_DQ<13>")
	)
	(segment
		(start 303.60112 -215.160606)
		(end 302.233076 -215.160606)
		(width 0.14478)
		(layer "In6.Cu")
		(net "M_E_CPU0_SA_DQ<13>")
	)
	(segment
		(start 308.400196 -215.796114)
		(end 308.400196 -215.44915)
		(width 0.14478)
		(layer "In6.Cu")
		(net "M_E_CPU0_SA_DQ<13>")
	)
	(segment
		(start 330.265024 -234.219496)
		(end 330.242672 -234.302808)
		(width 0.0889)
		(layer "In6.Cu")
		(net "M_E_CPU0_SA_DQ<13>")
	)
	(segment
		(start 323.890894 -231.79151)
		(end 323.547994 -231.79151)
		(width 0.0889)
		(layer "In6.Cu")
		(net "M_E_CPU0_SA_DQ<13>")
	)
	(segment
		(start 286.804862 -214.760048)
		(end 285.954978 -213.910164)
		(width 0.14478)
		(layer "In6.Cu")
		(net "M_E_CPU0_SA_DQ<13>")
	)
	(segment
		(start 300.982634 -213.910164)
		(end 298.615862 -213.910164)
		(width 0.14478)
		(layer "In6.Cu")
		(net "M_E_CPU0_SA_DQ<13>")
	)
	(segment
		(start 303.7459 -214.512652)
		(end 303.7459 -215.015826)
		(width 0.14478)
		(layer "In6.Cu")
		(net "M_E_CPU0_SA_DQ<13>")
	)
	(segment
		(start 279.410414 -214.531194)
		(end 279.247346 -214.368126)
		(width 0.14478)
		(layer "In6.Cu")
		(net "M_E_CPU0_SA_DQ<13>")
	)
	(segment
		(start 325.98614 -234.174792)
		(end 325.323454 -233.512106)
		(width 0.0889)
		(layer "In6.Cu")
		(net "M_E_CPU0_SA_DQ<13>")
	)
	(segment
		(start 307.638958 -214.687912)
		(end 307.097938 -214.687912)
		(width 0.14478)
		(layer "In6.Cu")
		(net "M_E_CPU0_SA_DQ<13>")
	)
	(segment
		(start 314.459874 -222.354902)
		(end 314.459874 -218.762072)
		(width 0.14478)
		(layer "In6.Cu")
		(net "M_E_CPU0_SA_DQ<13>")
	)
	(segment
		(start 279.966928 -214.923116)
		(end 279.966928 -214.988902)
		(width 0.14478)
		(layer "In6.Cu")
		(net "M_E_CPU0_SA_DQ<13>")
	)
	(segment
		(start 316.732158 -225.53803)
		(end 316.732158 -224.627186)
		(width 0.14478)
		(layer "In6.Cu")
		(net "M_E_CPU0_SA_DQ<13>")
	)
	(segment
		(start 307.097938 -214.687912)
		(end 306.625244 -215.160606)
		(width 0.14478)
		(layer "In6.Cu")
		(net "M_E_CPU0_SA_DQ<13>")
	)
	(segment
		(start 279.410414 -214.988902)
		(end 279.410414 -214.531194)
		(width 0.14478)
		(layer "In6.Cu")
		(net "M_E_CPU0_SA_DQ<13>")
	)
	(segment
		(start 289.499294 -215.14689)
		(end 289.268916 -215.14689)
		(width 0.14478)
		(layer "In6.Cu")
		(net "M_E_CPU0_SA_DQ<13>")
	)
	(segment
		(start 281.953716 -214.988902)
		(end 281.790648 -215.15197)
		(width 0.14478)
		(layer "In6.Cu")
		(net "M_E_CPU0_SA_DQ<13>")
	)
	(segment
		(start 327.47839 -234.276646)
		(end 327.470008 -234.281472)
		(width 0.0889)
		(layer "In6.Cu")
		(net "M_E_CPU0_SA_DQ<13>")
	)
	(segment
		(start 279.80386 -215.15197)
		(end 279.573482 -215.15197)
		(width 0.14478)
		(layer "In6.Cu")
		(net "M_E_CPU0_SA_DQ<13>")
	)
	(segment
		(start 282.116784 -214.760048)
		(end 281.953716 -214.923116)
		(width 0.14478)
		(layer "In6.Cu")
		(net "M_E_CPU0_SA_DQ<13>")
	)
	(segment
		(start 327.488804 -234.27055)
		(end 327.47839 -234.276646)
		(width 0.0889)
		(layer "In6.Cu")
		(net "M_E_CPU0_SA_DQ<13>")
	)
	(segment
		(start 285.954978 -213.910164)
		(end 283.294582 -213.910164)
		(width 0.14478)
		(layer "In6.Cu")
		(net "M_E_CPU0_SA_DQ<13>")
	)
	(segment
		(start 281.397202 -214.988902)
		(end 281.397202 -214.923116)
		(width 0.14478)
		(layer "In6.Cu")
		(net "M_E_CPU0_SA_DQ<13>")
	)
	(segment
		(start 289.268916 -215.14689)
		(end 289.105848 -214.983822)
		(width 0.14478)
		(layer "In6.Cu")
		(net "M_E_CPU0_SA_DQ<13>")
	)
	(segment
		(start 304.30978 -214.512652)
		(end 304.165 -214.367872)
		(width 0.14478)
		(layer "In6.Cu")
		(net "M_E_CPU0_SA_DQ<13>")
	)
	(segment
		(start 325.018654 -232.83291)
		(end 324.843394 -232.83291)
		(width 0.0889)
		(layer "In6.Cu")
		(net "M_E_CPU0_SA_DQ<13>")
	)
	(segment
		(start 303.89068 -214.367872)
		(end 303.7459 -214.512652)
		(width 0.14478)
		(layer "In6.Cu")
		(net "M_E_CPU0_SA_DQ<13>")
	)
	(arc
		(start 330.242672 -234.302808)
		(mid 330.080483 -234.325543)
		(end 329.924156 -234.276646)
		(width 0.0889)
		(layer "In6.Cu")
		(net "M_E_CPU0_SA_DQ<13>")
	)
	(arc
		(start 329.358244 -234.276646)
		(mid 329.175993 -234.326996)
		(end 328.992484 -234.281472)
		(width 0.0889)
		(layer "In6.Cu")
		(net "M_E_CPU0_SA_DQ<13>")
	)
	(arc
		(start 328.409808 -234.281472)
		(mid 328.2263 -234.326966)
		(end 328.044048 -234.276646)
		(width 0.0889)
		(layer "In6.Cu")
		(net "M_E_CPU0_SA_DQ<13>")
	)
	(arc
		(start 327.470008 -234.281472)
		(mid 327.286754 -234.326845)
		(end 327.104756 -234.276646)
		(width 0.0889)
		(layer "In6.Cu")
		(net "M_E_CPU0_SA_DQ<13>")
	)
	(arc
		(start 328.044048 -234.276646)
		(mid 327.767235 -234.200503)
		(end 327.488804 -234.27055)
		(width 0.0889)
		(layer "In6.Cu")
		(net "M_E_CPU0_SA_DQ<13>")
	)
	(arc
		(start 329.924156 -234.276646)
		(mid 329.6412 -234.200469)
		(end 329.358244 -234.276646)
		(width 0.0889)
		(layer "In6.Cu")
		(net "M_E_CPU0_SA_DQ<13>")
	)
	(arc
		(start 327.094342 -234.27055)
		(mid 326.815656 -234.20033)
		(end 326.53859 -234.276646)
		(width 0.0889)
		(layer "In6.Cu")
		(net "M_E_CPU0_SA_DQ<13>")
	)
	(arc
		(start 328.984102 -234.276646)
		(mid 328.701146 -234.200469)
		(end 328.41819 -234.276646)
		(width 0.0889)
		(layer "In6.Cu")
		(net "M_E_CPU0_SA_DQ<13>")
	)
	(arc
		(start 326.53859 -234.276646)
		(mid 326.361962 -234.326879)
		(end 326.182736 -234.286806)
		(width 0.0889)
		(layer "In6.Cu")
		(net "M_E_CPU0_SA_DQ<13>")
	)
	(segment
		(start 329.167998 -233.409998)
		(end 328.701146 -233.14406)
		(width 0.10668)
		(layer "F.Cu")
		(net "M_E_CPU0_SA_DQ<12>")
	)
	(segment
		(start 301.094648 -212.219794)
		(end 299.476414 -212.219794)
		(width 0.14478)
		(layer "In6.Cu")
		(net "M_E_CPU0_SA_DQ<12>")
	)
	(segment
		(start 291.793676 -212.37321)
		(end 291.793676 -212.433662)
		(width 0.14478)
		(layer "In6.Cu")
		(net "M_E_CPU0_SA_DQ<12>")
	)
	(segment
		(start 287.480756 -213.45017)
		(end 287.195006 -213.45017)
		(width 0.14478)
		(layer "In6.Cu")
		(net "M_E_CPU0_SA_DQ<12>")
	)
	(segment
		(start 291.630608 -212.59673)
		(end 291.40023 -212.59673)
		(width 0.14478)
		(layer "In6.Cu")
		(net "M_E_CPU0_SA_DQ<12>")
	)
	(segment
		(start 289.190938 -213.44509)
		(end 288.815526 -213.069678)
		(width 0.14478)
		(layer "In6.Cu")
		(net "M_E_CPU0_SA_DQ<12>")
	)
	(segment
		(start 303.92497 -212.734144)
		(end 303.590198 -212.734144)
		(width 0.14478)
		(layer "In6.Cu")
		(net "M_E_CPU0_SA_DQ<12>")
	)
	(segment
		(start 284.183836 -212.438742)
		(end 284.020768 -212.60181)
		(width 0.14478)
		(layer "In6.Cu")
		(net "M_E_CPU0_SA_DQ<12>")
	)
	(segment
		(start 279.86101 -213.069678)
		(end 279.707594 -213.223094)
		(width 0.14478)
		(layer "In6.Cu")
		(net "M_E_CPU0_SA_DQ<12>")
	)
	(segment
		(start 301.753778 -213.308692)
		(end 301.753778 -212.878924)
		(width 0.14478)
		(layer "In6.Cu")
		(net "M_E_CPU0_SA_DQ<12>")
	)
	(segment
		(start 299.322998 -212.428582)
		(end 299.15993 -212.59165)
		(width 0.14478)
		(layer "In6.Cu")
		(net "M_E_CPU0_SA_DQ<12>")
	)
	(segment
		(start 297.570906 -213.060026)
		(end 297.420284 -213.060026)
		(width 0.14478)
		(layer "In6.Cu")
		(net "M_E_CPU0_SA_DQ<12>")
	)
	(segment
		(start 317.631318 -225.150934)
		(end 317.631318 -224.254314)
		(width 0.14478)
		(layer "In6.Cu")
		(net "M_E_CPU0_SA_DQ<12>")
	)
	(segment
		(start 289.584384 -213.282022)
		(end 289.421316 -213.44509)
		(width 0.14478)
		(layer "In6.Cu")
		(net "M_E_CPU0_SA_DQ<12>")
	)
	(segment
		(start 281.614118 -213.45017)
		(end 281.233626 -213.069678)
		(width 0.14478)
		(layer "In6.Cu")
		(net "M_E_CPU0_SA_DQ<12>")
	)
	(segment
		(start 302.736758 -212.734144)
		(end 302.462438 -212.734144)
		(width 0.14478)
		(layer "In6.Cu")
		(net "M_E_CPU0_SA_DQ<12>")
	)
	(segment
		(start 317.631318 -224.254314)
		(end 315.385958 -222.008954)
		(width 0.14478)
		(layer "In6.Cu")
		(net "M_E_CPU0_SA_DQ<12>")
	)
	(segment
		(start 281.844496 -213.45017)
		(end 281.614118 -213.45017)
		(width 0.14478)
		(layer "In6.Cu")
		(net "M_E_CPU0_SA_DQ<12>")
	)
	(segment
		(start 302.317658 -213.308692)
		(end 302.172878 -213.453472)
		(width 0.14478)
		(layer "In6.Cu")
		(net "M_E_CPU0_SA_DQ<12>")
	)
	(segment
		(start 299.322998 -212.37321)
		(end 299.322998 -212.428582)
		(width 0.14478)
		(layer "In6.Cu")
		(net "M_E_CPU0_SA_DQ<12>")
	)
	(segment
		(start 323.362574 -230.88219)
		(end 317.631318 -225.150934)
		(width 0.14478)
		(layer "In6.Cu")
		(net "M_E_CPU0_SA_DQ<12>")
	)
	(segment
		(start 289.747452 -213.060026)
		(end 289.584384 -213.223094)
		(width 0.14478)
		(layer "In6.Cu")
		(net "M_E_CPU0_SA_DQ<12>")
	)
	(segment
		(start 290.077398 -213.060026)
		(end 289.747452 -213.060026)
		(width 0.14478)
		(layer "In6.Cu")
		(net "M_E_CPU0_SA_DQ<12>")
	)
	(segment
		(start 291.947092 -212.219794)
		(end 291.793676 -212.37321)
		(width 0.14478)
		(layer "In6.Cu")
		(net "M_E_CPU0_SA_DQ<12>")
	)
	(segment
		(start 278.543258 -212.896958)
		(end 278.543258 -212.444838)
		(width 0.14478)
		(layer "In6.Cu")
		(net "M_E_CPU0_SA_DQ<12>")
	)
	(segment
		(start 288.815526 -213.069678)
		(end 287.79724 -213.069678)
		(width 0.14478)
		(layer "In6.Cu")
		(net "M_E_CPU0_SA_DQ<12>")
	)
	(segment
		(start 279.15108 -213.223094)
		(end 278.988012 -213.060026)
		(width 0.14478)
		(layer "In6.Cu")
		(net "M_E_CPU0_SA_DQ<12>")
	)
	(segment
		(start 279.544526 -213.45017)
		(end 279.314148 -213.45017)
		(width 0.14478)
		(layer "In6.Cu")
		(net "M_E_CPU0_SA_DQ<12>")
	)
	(segment
		(start 326.216518 -233.382312)
		(end 325.10857 -232.274364)
		(width 0.0889)
		(layer "In6.Cu")
		(net "M_E_CPU0_SA_DQ<12>")
	)
	(segment
		(start 283.79039 -212.60181)
		(end 283.627322 -212.438742)
		(width 0.14478)
		(layer "In6.Cu")
		(net "M_E_CPU0_SA_DQ<12>")
	)
	(segment
		(start 278.543258 -212.444838)
		(end 278.38019 -212.28177)
		(width 0.14478)
		(layer "In6.Cu")
		(net "M_E_CPU0_SA_DQ<12>")
	)
	(segment
		(start 284.020768 -212.60181)
		(end 283.79039 -212.60181)
		(width 0.14478)
		(layer "In6.Cu")
		(net "M_E_CPU0_SA_DQ<12>")
	)
	(segment
		(start 302.881538 -213.308692)
		(end 302.881538 -212.878924)
		(width 0.14478)
		(layer "In6.Cu")
		(net "M_E_CPU0_SA_DQ<12>")
	)
	(segment
		(start 301.753778 -212.878924)
		(end 301.094648 -212.219794)
		(width 0.14478)
		(layer "In6.Cu")
		(net "M_E_CPU0_SA_DQ<12>")
	)
	(segment
		(start 291.074094 -212.210142)
		(end 290.927282 -212.210142)
		(width 0.14478)
		(layer "In6.Cu")
		(net "M_E_CPU0_SA_DQ<12>")
	)
	(segment
		(start 287.79724 -213.069678)
		(end 287.643824 -213.223094)
		(width 0.14478)
		(layer "In6.Cu")
		(net "M_E_CPU0_SA_DQ<12>")
	)
	(segment
		(start 328.85507 -233.40949)
		(end 328.832718 -233.492802)
		(width 0.0889)
		(layer "In6.Cu")
		(net "M_E_CPU0_SA_DQ<12>")
	)
	(segment
		(start 324.44817 -231.434386)
		(end 323.895974 -230.88219)
		(width 0.0889)
		(layer "In6.Cu")
		(net "M_E_CPU0_SA_DQ<12>")
	)
	(segment
		(start 277.617174 -213.060026)
		(end 277.192232 -212.635084)
		(width 0.14478)
		(layer "In6.Cu")
		(net "M_E_CPU0_SA_DQ<12>")
	)
	(segment
		(start 303.590198 -212.734144)
		(end 303.445418 -212.878924)
		(width 0.14478)
		(layer "In6.Cu")
		(net "M_E_CPU0_SA_DQ<12>")
	)
	(segment
		(start 282.007564 -213.223094)
		(end 282.007564 -213.287102)
		(width 0.14478)
		(layer "In6.Cu")
		(net "M_E_CPU0_SA_DQ<12>")
	)
	(segment
		(start 279.15108 -213.287102)
		(end 279.15108 -213.223094)
		(width 0.14478)
		(layer "In6.Cu")
		(net "M_E_CPU0_SA_DQ<12>")
	)
	(segment
		(start 298.766484 -212.428582)
		(end 298.766484 -212.37321)
		(width 0.14478)
		(layer "In6.Cu")
		(net "M_E_CPU0_SA_DQ<12>")
	)
	(segment
		(start 279.707594 -213.287102)
		(end 279.544526 -213.45017)
		(width 0.14478)
		(layer "In6.Cu")
		(net "M_E_CPU0_SA_DQ<12>")
	)
	(segment
		(start 278.149812 -212.28177)
		(end 277.986744 -212.444838)
		(width 0.14478)
		(layer "In6.Cu")
		(net "M_E_CPU0_SA_DQ<12>")
	)
	(segment
		(start 323.895974 -230.88219)
		(end 323.547994 -230.88219)
		(width 0.0889)
		(layer "In6.Cu")
		(net "M_E_CPU0_SA_DQ<12>")
	)
	(segment
		(start 283.294582 -212.210142)
		(end 282.444698 -213.060026)
		(width 0.14478)
		(layer "In6.Cu")
		(net "M_E_CPU0_SA_DQ<12>")
	)
	(segment
		(start 312.229246 -215.259412)
		(end 309.858664 -215.259412)
		(width 0.14478)
		(layer "In6.Cu")
		(net "M_E_CPU0_SA_DQ<12>")
	)
	(segment
		(start 323.547994 -230.88219)
		(end 323.362574 -230.88219)
		(width 0.14478)
		(layer "In6.Cu")
		(net "M_E_CPU0_SA_DQ<12>")
	)
	(segment
		(start 298.603416 -212.210142)
		(end 298.42079 -212.210142)
		(width 0.14478)
		(layer "In6.Cu")
		(net "M_E_CPU0_SA_DQ<12>")
	)
	(segment
		(start 298.929552 -212.59165)
		(end 298.766484 -212.428582)
		(width 0.14478)
		(layer "In6.Cu")
		(net "M_E_CPU0_SA_DQ<12>")
	)
	(segment
		(start 296.483278 -213.069678)
		(end 294.37965 -213.069678)
		(width 0.14478)
		(layer "In6.Cu")
		(net "M_E_CPU0_SA_DQ<12>")
	)
	(segment
		(start 287.643824 -213.287102)
		(end 287.480756 -213.45017)
		(width 0.14478)
		(layer "In6.Cu")
		(net "M_E_CPU0_SA_DQ<12>")
	)
	(segment
		(start 278.706326 -213.060026)
		(end 278.543258 -212.896958)
		(width 0.14478)
		(layer "In6.Cu")
		(net "M_E_CPU0_SA_DQ<12>")
	)
	(segment
		(start 303.445418 -213.308692)
		(end 303.300638 -213.453472)
		(width 0.14478)
		(layer "In6.Cu")
		(net "M_E_CPU0_SA_DQ<12>")
	)
	(segment
		(start 289.421316 -213.44509)
		(end 289.190938 -213.44509)
		(width 0.14478)
		(layer "In6.Cu")
		(net "M_E_CPU0_SA_DQ<12>")
	)
	(segment
		(start 325.10857 -232.274364)
		(end 325.10857 -231.629966)
		(width 0.0889)
		(layer "In6.Cu")
		(net "M_E_CPU0_SA_DQ<12>")
	)
	(segment
		(start 281.233626 -213.069678)
		(end 279.86101 -213.069678)
		(width 0.14478)
		(layer "In6.Cu")
		(net "M_E_CPU0_SA_DQ<12>")
	)
	(segment
		(start 289.584384 -213.223094)
		(end 289.584384 -213.282022)
		(width 0.14478)
		(layer "In6.Cu")
		(net "M_E_CPU0_SA_DQ<12>")
	)
	(segment
		(start 324.91299 -231.434386)
		(end 324.44817 -231.434386)
		(width 0.0889)
		(layer "In6.Cu")
		(net "M_E_CPU0_SA_DQ<12>")
	)
	(segment
		(start 278.38019 -212.28177)
		(end 278.149812 -212.28177)
		(width 0.14478)
		(layer "In6.Cu")
		(net "M_E_CPU0_SA_DQ<12>")
	)
	(segment
		(start 278.988012 -213.060026)
		(end 278.706326 -213.060026)
		(width 0.14478)
		(layer "In6.Cu")
		(net "M_E_CPU0_SA_DQ<12>")
	)
	(segment
		(start 277.986744 -212.896958)
		(end 277.823676 -213.060026)
		(width 0.14478)
		(layer "In6.Cu")
		(net "M_E_CPU0_SA_DQ<12>")
	)
	(segment
		(start 298.42079 -212.210142)
		(end 297.570906 -213.060026)
		(width 0.14478)
		(layer "In6.Cu")
		(net "M_E_CPU0_SA_DQ<12>")
	)
	(segment
		(start 297.094148 -213.45017)
		(end 296.86377 -213.45017)
		(width 0.14478)
		(layer "In6.Cu")
		(net "M_E_CPU0_SA_DQ<12>")
	)
	(segment
		(start 291.237162 -212.433662)
		(end 291.237162 -212.37321)
		(width 0.14478)
		(layer "In6.Cu")
		(net "M_E_CPU0_SA_DQ<12>")
	)
	(segment
		(start 302.172878 -213.453472)
		(end 301.898558 -213.453472)
		(width 0.14478)
		(layer "In6.Cu")
		(net "M_E_CPU0_SA_DQ<12>")
	)
	(segment
		(start 297.420284 -213.060026)
		(end 297.257216 -213.223094)
		(width 0.14478)
		(layer "In6.Cu")
		(net "M_E_CPU0_SA_DQ<12>")
	)
	(segment
		(start 309.858664 -215.259412)
		(end 307.610764 -213.011512)
		(width 0.14478)
		(layer "In6.Cu")
		(net "M_E_CPU0_SA_DQ<12>")
	)
	(segment
		(start 277.823676 -213.060026)
		(end 277.617174 -213.060026)
		(width 0.14478)
		(layer "In6.Cu")
		(net "M_E_CPU0_SA_DQ<12>")
	)
	(segment
		(start 279.314148 -213.45017)
		(end 279.15108 -213.287102)
		(width 0.14478)
		(layer "In6.Cu")
		(net "M_E_CPU0_SA_DQ<12>")
	)
	(segment
		(start 327.58253 -233.471466)
		(end 327.574148 -233.46664)
		(width 0.0889)
		(layer "In6.Cu")
		(net "M_E_CPU0_SA_DQ<12>")
	)
	(segment
		(start 282.444698 -213.060026)
		(end 282.170632 -213.060026)
		(width 0.14478)
		(layer "In6.Cu")
		(net "M_E_CPU0_SA_DQ<12>")
	)
	(segment
		(start 287.195006 -213.45017)
		(end 285.96463 -212.219794)
		(width 0.14478)
		(layer "In6.Cu")
		(net "M_E_CPU0_SA_DQ<12>")
	)
	(segment
		(start 297.257216 -213.287102)
		(end 297.094148 -213.45017)
		(width 0.14478)
		(layer "In6.Cu")
		(net "M_E_CPU0_SA_DQ<12>")
	)
	(segment
		(start 290.927282 -212.210142)
		(end 290.077398 -213.060026)
		(width 0.14478)
		(layer "In6.Cu")
		(net "M_E_CPU0_SA_DQ<12>")
	)
	(segment
		(start 282.007564 -213.287102)
		(end 281.844496 -213.45017)
		(width 0.14478)
		(layer "In6.Cu")
		(net "M_E_CPU0_SA_DQ<12>")
	)
	(segment
		(start 282.170632 -213.060026)
		(end 282.007564 -213.223094)
		(width 0.14478)
		(layer "In6.Cu")
		(net "M_E_CPU0_SA_DQ<12>")
	)
	(segment
		(start 327.574148 -233.46664)
		(end 327.563734 -233.460544)
		(width 0.0889)
		(layer "In6.Cu")
		(net "M_E_CPU0_SA_DQ<12>")
	)
	(segment
		(start 325.10857 -231.629966)
		(end 324.91299 -231.434386)
		(width 0.0889)
		(layer "In6.Cu")
		(net "M_E_CPU0_SA_DQ<12>")
	)
	(segment
		(start 327.00849 -233.46664)
		(end 327.000108 -233.471466)
		(width 0.0889)
		(layer "In6.Cu")
		(net "M_E_CPU0_SA_DQ<12>")
	)
	(segment
		(start 301.898558 -213.453472)
		(end 301.753778 -213.308692)
		(width 0.14478)
		(layer "In6.Cu")
		(net "M_E_CPU0_SA_DQ<12>")
	)
	(segment
		(start 285.96463 -212.219794)
		(end 284.337252 -212.219794)
		(width 0.14478)
		(layer "In6.Cu")
		(net "M_E_CPU0_SA_DQ<12>")
	)
	(segment
		(start 298.766484 -212.37321)
		(end 298.603416 -212.210142)
		(width 0.14478)
		(layer "In6.Cu")
		(net "M_E_CPU0_SA_DQ<12>")
	)
	(segment
		(start 299.476414 -212.219794)
		(end 299.322998 -212.37321)
		(width 0.14478)
		(layer "In6.Cu")
		(net "M_E_CPU0_SA_DQ<12>")
	)
	(segment
		(start 304.65141 -213.460584)
		(end 303.92497 -212.734144)
		(width 0.14478)
		(layer "In6.Cu")
		(net "M_E_CPU0_SA_DQ<12>")
	)
	(segment
		(start 283.627322 -212.37321)
		(end 283.464254 -212.210142)
		(width 0.14478)
		(layer "In6.Cu")
		(net "M_E_CPU0_SA_DQ<12>")
	)
	(segment
		(start 303.445418 -212.878924)
		(end 303.445418 -213.308692)
		(width 0.14478)
		(layer "In6.Cu")
		(net "M_E_CPU0_SA_DQ<12>")
	)
	(segment
		(start 293.529766 -212.219794)
		(end 291.947092 -212.219794)
		(width 0.14478)
		(layer "In6.Cu")
		(net "M_E_CPU0_SA_DQ<12>")
	)
	(segment
		(start 315.385958 -222.008954)
		(end 315.385958 -218.416124)
		(width 0.14478)
		(layer "In6.Cu")
		(net "M_E_CPU0_SA_DQ<12>")
	)
	(segment
		(start 294.37965 -213.069678)
		(end 293.529766 -212.219794)
		(width 0.14478)
		(layer "In6.Cu")
		(net "M_E_CPU0_SA_DQ<12>")
	)
	(segment
		(start 306.613052 -213.460584)
		(end 304.65141 -213.460584)
		(width 0.14478)
		(layer "In6.Cu")
		(net "M_E_CPU0_SA_DQ<12>")
	)
	(segment
		(start 284.337252 -212.219794)
		(end 284.183836 -212.37321)
		(width 0.14478)
		(layer "In6.Cu")
		(net "M_E_CPU0_SA_DQ<12>")
	)
	(segment
		(start 303.026318 -213.453472)
		(end 302.881538 -213.308692)
		(width 0.14478)
		(layer "In6.Cu")
		(net "M_E_CPU0_SA_DQ<12>")
	)
	(segment
		(start 299.15993 -212.59165)
		(end 298.929552 -212.59165)
		(width 0.14478)
		(layer "In6.Cu")
		(net "M_E_CPU0_SA_DQ<12>")
	)
	(segment
		(start 283.464254 -212.210142)
		(end 283.294582 -212.210142)
		(width 0.14478)
		(layer "In6.Cu")
		(net "M_E_CPU0_SA_DQ<12>")
	)
	(segment
		(start 326.320912 -233.382312)
		(end 326.216518 -233.382312)
		(width 0.0889)
		(layer "In6.Cu")
		(net "M_E_CPU0_SA_DQ<12>")
	)
	(segment
		(start 291.40023 -212.59673)
		(end 291.237162 -212.433662)
		(width 0.14478)
		(layer "In6.Cu")
		(net "M_E_CPU0_SA_DQ<12>")
	)
	(segment
		(start 302.881538 -212.878924)
		(end 302.736758 -212.734144)
		(width 0.14478)
		(layer "In6.Cu")
		(net "M_E_CPU0_SA_DQ<12>")
	)
	(segment
		(start 277.986744 -212.444838)
		(end 277.986744 -212.896958)
		(width 0.14478)
		(layer "In6.Cu")
		(net "M_E_CPU0_SA_DQ<12>")
	)
	(segment
		(start 283.627322 -212.438742)
		(end 283.627322 -212.37321)
		(width 0.14478)
		(layer "In6.Cu")
		(net "M_E_CPU0_SA_DQ<12>")
	)
	(segment
		(start 279.707594 -213.223094)
		(end 279.707594 -213.287102)
		(width 0.14478)
		(layer "In6.Cu")
		(net "M_E_CPU0_SA_DQ<12>")
	)
	(segment
		(start 297.257216 -213.223094)
		(end 297.257216 -213.287102)
		(width 0.14478)
		(layer "In6.Cu")
		(net "M_E_CPU0_SA_DQ<12>")
	)
	(segment
		(start 296.86377 -213.45017)
		(end 296.483278 -213.069678)
		(width 0.14478)
		(layer "In6.Cu")
		(net "M_E_CPU0_SA_DQ<12>")
	)
	(segment
		(start 303.300638 -213.453472)
		(end 303.026318 -213.453472)
		(width 0.14478)
		(layer "In6.Cu")
		(net "M_E_CPU0_SA_DQ<12>")
	)
	(segment
		(start 287.643824 -213.223094)
		(end 287.643824 -213.287102)
		(width 0.14478)
		(layer "In6.Cu")
		(net "M_E_CPU0_SA_DQ<12>")
	)
	(segment
		(start 307.062124 -213.011512)
		(end 306.613052 -213.460584)
		(width 0.14478)
		(layer "In6.Cu")
		(net "M_E_CPU0_SA_DQ<12>")
	)
	(segment
		(start 291.793676 -212.433662)
		(end 291.630608 -212.59673)
		(width 0.14478)
		(layer "In6.Cu")
		(net "M_E_CPU0_SA_DQ<12>")
	)
	(segment
		(start 307.610764 -213.011512)
		(end 307.062124 -213.011512)
		(width 0.14478)
		(layer "In6.Cu")
		(net "M_E_CPU0_SA_DQ<12>")
	)
	(segment
		(start 328.701146 -233.14406)
		(end 328.85507 -233.40949)
		(width 0.0889)
		(layer "In6.Cu")
		(net "M_E_CPU0_SA_DQ<12>")
	)
	(segment
		(start 291.237162 -212.37321)
		(end 291.074094 -212.210142)
		(width 0.14478)
		(layer "In6.Cu")
		(net "M_E_CPU0_SA_DQ<12>")
	)
	(segment
		(start 302.317658 -212.878924)
		(end 302.317658 -213.308692)
		(width 0.14478)
		(layer "In6.Cu")
		(net "M_E_CPU0_SA_DQ<12>")
	)
	(segment
		(start 315.385958 -218.416124)
		(end 312.229246 -215.259412)
		(width 0.14478)
		(layer "In6.Cu")
		(net "M_E_CPU0_SA_DQ<12>")
	)
	(segment
		(start 302.462438 -212.734144)
		(end 302.317658 -212.878924)
		(width 0.14478)
		(layer "In6.Cu")
		(net "M_E_CPU0_SA_DQ<12>")
	)
	(segment
		(start 284.183836 -212.37321)
		(end 284.183836 -212.438742)
		(width 0.14478)
		(layer "In6.Cu")
		(net "M_E_CPU0_SA_DQ<12>")
	)
	(arc
		(start 327.94829 -233.46664)
		(mid 327.766039 -233.51699)
		(end 327.58253 -233.471466)
		(width 0.0889)
		(layer "In6.Cu")
		(net "M_E_CPU0_SA_DQ<12>")
	)
	(arc
		(start 328.832718 -233.492802)
		(mid 328.670529 -233.515537)
		(end 328.514202 -233.46664)
		(width 0.0889)
		(layer "In6.Cu")
		(net "M_E_CPU0_SA_DQ<12>")
	)
	(arc
		(start 327.000108 -233.471466)
		(mid 326.8166 -233.51696)
		(end 326.634348 -233.46664)
		(width 0.0889)
		(layer "In6.Cu")
		(net "M_E_CPU0_SA_DQ<12>")
	)
	(arc
		(start 328.514202 -233.46664)
		(mid 328.231246 -233.390463)
		(end 327.94829 -233.46664)
		(width 0.0889)
		(layer "In6.Cu")
		(net "M_E_CPU0_SA_DQ<12>")
	)
	(arc
		(start 327.563734 -233.460544)
		(mid 327.285302 -233.390446)
		(end 327.00849 -233.46664)
		(width 0.0889)
		(layer "In6.Cu")
		(net "M_E_CPU0_SA_DQ<12>")
	)
	(arc
		(start 326.634348 -233.46664)
		(mid 326.483209 -233.403729)
		(end 326.320912 -233.382312)
		(width 0.0889)
		(layer "In6.Cu")
		(net "M_E_CPU0_SA_DQ<12>")
	)
	(segment
		(start 331.047852 -231.789986)
		(end 330.581 -231.524048)
		(width 0.10668)
		(layer "F.Cu")
		(net "M_E_CPU0_SA_DQ<11>")
	)
	(segment
		(start 298.23029 -208.800446)
		(end 301.18685 -208.800446)
		(width 0.14478)
		(layer "In6.Cu")
		(net "M_E_CPU0_SA_DQ<11>")
	)
	(segment
		(start 323.946774 -228.14407)
		(end 324.179184 -228.37648)
		(width 0.0889)
		(layer "In6.Cu")
		(net "M_E_CPU0_SA_DQ<11>")
	)
	(segment
		(start 282.219146 -209.65033)
		(end 283.06903 -208.800446)
		(width 0.14478)
		(layer "In6.Cu")
		(net "M_E_CPU0_SA_DQ<11>")
	)
	(segment
		(start 289.77336 -209.65033)
		(end 290.623244 -208.800446)
		(width 0.14478)
		(layer "In6.Cu")
		(net "M_E_CPU0_SA_DQ<11>")
	)
	(segment
		(start 293.64305 -208.800446)
		(end 294.492934 -209.65033)
		(width 0.14478)
		(layer "In6.Cu")
		(net "M_E_CPU0_SA_DQ<11>")
	)
	(segment
		(start 302.04664 -209.660236)
		(end 304.9143 -209.660236)
		(width 0.14478)
		(layer "In6.Cu")
		(net "M_E_CPU0_SA_DQ<11>")
	)
	(segment
		(start 274.094956 -209.65033)
		(end 282.219146 -209.65033)
		(width 0.14478)
		(layer "In6.Cu")
		(net "M_E_CPU0_SA_DQ<11>")
	)
	(segment
		(start 283.06903 -208.800446)
		(end 285.954216 -208.800446)
		(width 0.14478)
		(layer "In6.Cu")
		(net "M_E_CPU0_SA_DQ<11>")
	)
	(segment
		(start 324.179184 -228.82606)
		(end 324.741794 -229.38867)
		(width 0.0889)
		(layer "In6.Cu")
		(net "M_E_CPU0_SA_DQ<11>")
	)
	(segment
		(start 297.380406 -209.65033)
		(end 298.23029 -208.800446)
		(width 0.14478)
		(layer "In6.Cu")
		(net "M_E_CPU0_SA_DQ<11>")
	)
	(segment
		(start 317.736474 -221.103444)
		(end 319.927224 -223.294194)
		(width 0.14478)
		(layer "In6.Cu")
		(net "M_E_CPU0_SA_DQ<11>")
	)
	(segment
		(start 319.927224 -224.12452)
		(end 323.946774 -228.14407)
		(width 0.14478)
		(layer "In6.Cu")
		(net "M_E_CPU0_SA_DQ<11>")
	)
	(segment
		(start 329.819762 -231.196896)
		(end 329.828144 -231.201722)
		(width 0.0889)
		(layer "In6.Cu")
		(net "M_E_CPU0_SA_DQ<11>")
	)
	(segment
		(start 325.112634 -229.38867)
		(end 326.025256 -230.301292)
		(width 0.0889)
		(layer "In6.Cu")
		(net "M_E_CPU0_SA_DQ<11>")
	)
	(segment
		(start 330.427076 -231.258618)
		(end 330.581 -231.524048)
		(width 0.0889)
		(layer "In6.Cu")
		(net "M_E_CPU0_SA_DQ<11>")
	)
	(segment
		(start 304.9143 -209.660236)
		(end 305.764438 -208.810098)
		(width 0.14478)
		(layer "In6.Cu")
		(net "M_E_CPU0_SA_DQ<11>")
	)
	(segment
		(start 330.331318 -231.233218)
		(end 330.427076 -231.258618)
		(width 0.0889)
		(layer "In6.Cu")
		(net "M_E_CPU0_SA_DQ<11>")
	)
	(segment
		(start 301.18685 -208.800446)
		(end 302.04664 -209.660236)
		(width 0.14478)
		(layer "In6.Cu")
		(net "M_E_CPU0_SA_DQ<11>")
	)
	(segment
		(start 317.736474 -217.52941)
		(end 317.736474 -221.103444)
		(width 0.14478)
		(layer "In6.Cu")
		(net "M_E_CPU0_SA_DQ<11>")
	)
	(segment
		(start 319.927224 -223.294194)
		(end 319.927224 -224.12452)
		(width 0.14478)
		(layer "In6.Cu")
		(net "M_E_CPU0_SA_DQ<11>")
	)
	(segment
		(start 324.179184 -228.37648)
		(end 324.179184 -228.82606)
		(width 0.0889)
		(layer "In6.Cu")
		(net "M_E_CPU0_SA_DQ<11>")
	)
	(segment
		(start 286.8041 -209.65033)
		(end 289.77336 -209.65033)
		(width 0.14478)
		(layer "In6.Cu")
		(net "M_E_CPU0_SA_DQ<11>")
	)
	(segment
		(start 285.954216 -208.800446)
		(end 286.8041 -209.65033)
		(width 0.14478)
		(layer "In6.Cu")
		(net "M_E_CPU0_SA_DQ<11>")
	)
	(segment
		(start 290.623244 -208.800446)
		(end 293.64305 -208.800446)
		(width 0.14478)
		(layer "In6.Cu")
		(net "M_E_CPU0_SA_DQ<11>")
	)
	(segment
		(start 326.025256 -230.301292)
		(end 326.500998 -230.301292)
		(width 0.0889)
		(layer "In6.Cu")
		(net "M_E_CPU0_SA_DQ<11>")
	)
	(segment
		(start 294.492934 -209.65033)
		(end 297.380406 -209.65033)
		(width 0.14478)
		(layer "In6.Cu")
		(net "M_E_CPU0_SA_DQ<11>")
	)
	(segment
		(start 326.500998 -230.301292)
		(end 327.158096 -230.95839)
		(width 0.0889)
		(layer "In6.Cu")
		(net "M_E_CPU0_SA_DQ<11>")
	)
	(segment
		(start 305.764438 -208.810098)
		(end 309.017162 -208.810098)
		(width 0.14478)
		(layer "In6.Cu")
		(net "M_E_CPU0_SA_DQ<11>")
	)
	(segment
		(start 309.017162 -208.810098)
		(end 317.736474 -217.52941)
		(width 0.14478)
		(layer "In6.Cu")
		(net "M_E_CPU0_SA_DQ<11>")
	)
	(segment
		(start 273.092164 -209.23504)
		(end 274.094956 -209.65033)
		(width 0.14478)
		(layer "In6.Cu")
		(net "M_E_CPU0_SA_DQ<11>")
	)
	(segment
		(start 324.741794 -229.38867)
		(end 325.112634 -229.38867)
		(width 0.0889)
		(layer "In6.Cu")
		(net "M_E_CPU0_SA_DQ<11>")
	)
	(arc
		(start 327.65873 -231.165654)
		(mid 327.807183 -231.154183)
		(end 327.94829 -231.201722)
		(width 0.0889)
		(layer "In6.Cu")
		(net "M_E_CPU0_SA_DQ<11>")
	)
	(arc
		(start 328.514202 -231.201722)
		(mid 328.701146 -231.151433)
		(end 328.88809 -231.201722)
		(width 0.0889)
		(layer "In6.Cu")
		(net "M_E_CPU0_SA_DQ<11>")
	)
	(arc
		(start 329.454002 -231.201722)
		(mid 329.636253 -231.151338)
		(end 329.819762 -231.196896)
		(width 0.0889)
		(layer "In6.Cu")
		(net "M_E_CPU0_SA_DQ<11>")
	)
	(arc
		(start 329.828144 -231.201722)
		(mid 330.076004 -231.276805)
		(end 330.331318 -231.233218)
		(width 0.0889)
		(layer "In6.Cu")
		(net "M_E_CPU0_SA_DQ<11>")
	)
	(arc
		(start 327.94829 -231.201722)
		(mid 328.231246 -231.277899)
		(end 328.514202 -231.201722)
		(width 0.0889)
		(layer "In6.Cu")
		(net "M_E_CPU0_SA_DQ<11>")
	)
	(arc
		(start 327.158096 -230.95839)
		(mid 327.387803 -231.111812)
		(end 327.65873 -231.165654)
		(width 0.0889)
		(layer "In6.Cu")
		(net "M_E_CPU0_SA_DQ<11>")
	)
	(arc
		(start 328.88809 -231.201722)
		(mid 329.171046 -231.277899)
		(end 329.454002 -231.201722)
		(width 0.0889)
		(layer "In6.Cu")
		(net "M_E_CPU0_SA_DQ<11>")
	)
	(segment
		(start 329.637898 -230.97998)
		(end 329.171046 -230.714296)
		(width 0.10668)
		(layer "F.Cu")
		(net "M_E_CPU0_SA_DQ<10>")
	)
	(segment
		(start 305.764438 -207.110076)
		(end 304.9143 -207.960214)
		(width 0.14478)
		(layer "In6.Cu")
		(net "M_E_CPU0_SA_DQ<10>")
	)
	(segment
		(start 329.171046 -230.714296)
		(end 329.017122 -230.448866)
		(width 0.0889)
		(layer "In6.Cu")
		(net "M_E_CPU0_SA_DQ<10>")
	)
	(segment
		(start 274.344638 -207.797146)
		(end 274.18157 -207.960214)
		(width 0.14478)
		(layer "In6.Cu")
		(net "M_E_CPU0_SA_DQ<10>")
	)
	(segment
		(start 327.488804 -230.397812)
		(end 327.47839 -230.391716)
		(width 0.0889)
		(layer "In6.Cu")
		(net "M_E_CPU0_SA_DQ<10>")
	)
	(segment
		(start 318.661542 -217.182446)
		(end 308.589172 -207.110076)
		(width 0.14478)
		(layer "In6.Cu")
		(net "M_E_CPU0_SA_DQ<10>")
	)
	(segment
		(start 324.119494 -227.10521)
		(end 324.119494 -227.01631)
		(width 0.0889)
		(layer "In6.Cu")
		(net "M_E_CPU0_SA_DQ<10>")
	)
	(segment
		(start 324.119494 -227.01631)
		(end 323.880226 -226.777042)
		(width 0.0889)
		(layer "In6.Cu")
		(net "M_E_CPU0_SA_DQ<10>")
	)
	(segment
		(start 324.585584 -228.58984)
		(end 324.585584 -227.5713)
		(width 0.0889)
		(layer "In6.Cu")
		(net "M_E_CPU0_SA_DQ<10>")
	)
	(segment
		(start 324.930008 -228.934264)
		(end 324.585584 -228.58984)
		(width 0.0889)
		(layer "In6.Cu")
		(net "M_E_CPU0_SA_DQ<10>")
	)
	(segment
		(start 323.866002 -226.777042)
		(end 320.826384 -223.737424)
		(width 0.14478)
		(layer "In6.Cu")
		(net "M_E_CPU0_SA_DQ<10>")
	)
	(segment
		(start 275.06422 -207.960214)
		(end 274.901152 -207.797146)
		(width 0.14478)
		(layer "In6.Cu")
		(net "M_E_CPU0_SA_DQ<10>")
	)
	(segment
		(start 318.661542 -220.75648)
		(end 318.661542 -217.182446)
		(width 0.14478)
		(layer "In6.Cu")
		(net "M_E_CPU0_SA_DQ<10>")
	)
	(segment
		(start 298.220638 -207.110076)
		(end 297.3705 -207.960214)
		(width 0.14478)
		(layer "In6.Cu")
		(net "M_E_CPU0_SA_DQ<10>")
	)
	(segment
		(start 286.814006 -207.960214)
		(end 285.963868 -207.110076)
		(width 0.14478)
		(layer "In6.Cu")
		(net "M_E_CPU0_SA_DQ<10>")
	)
	(segment
		(start 274.901152 -207.797146)
		(end 274.901152 -207.479138)
		(width 0.14478)
		(layer "In6.Cu")
		(net "M_E_CPU0_SA_DQ<10>")
	)
	(segment
		(start 273.51736 -207.960214)
		(end 273.092164 -207.535018)
		(width 0.14478)
		(layer "In6.Cu")
		(net "M_E_CPU0_SA_DQ<10>")
	)
	(segment
		(start 326.872854 -229.81285)
		(end 326.219566 -229.81285)
		(width 0.0889)
		(layer "In6.Cu")
		(net "M_E_CPU0_SA_DQ<10>")
	)
	(segment
		(start 320.826384 -223.737424)
		(end 320.826384 -222.921322)
		(width 0.14478)
		(layer "In6.Cu")
		(net "M_E_CPU0_SA_DQ<10>")
	)
	(segment
		(start 320.826384 -222.921322)
		(end 318.661542 -220.75648)
		(width 0.14478)
		(layer "In6.Cu")
		(net "M_E_CPU0_SA_DQ<10>")
	)
	(segment
		(start 282.20924 -207.960214)
		(end 275.06422 -207.960214)
		(width 0.14478)
		(layer "In6.Cu")
		(net "M_E_CPU0_SA_DQ<10>")
	)
	(segment
		(start 308.589172 -207.110076)
		(end 305.764438 -207.110076)
		(width 0.14478)
		(layer "In6.Cu")
		(net "M_E_CPU0_SA_DQ<10>")
	)
	(segment
		(start 328.41819 -230.391716)
		(end 328.409808 -230.38689)
		(width 0.0889)
		(layer "In6.Cu")
		(net "M_E_CPU0_SA_DQ<10>")
	)
	(segment
		(start 274.507706 -207.31607)
		(end 274.344638 -207.479138)
		(width 0.14478)
		(layer "In6.Cu")
		(net "M_E_CPU0_SA_DQ<10>")
	)
	(segment
		(start 324.585584 -227.5713)
		(end 324.119494 -227.10521)
		(width 0.0889)
		(layer "In6.Cu")
		(net "M_E_CPU0_SA_DQ<10>")
	)
	(segment
		(start 302.04664 -207.960214)
		(end 301.196502 -207.110076)
		(width 0.14478)
		(layer "In6.Cu")
		(net "M_E_CPU0_SA_DQ<10>")
	)
	(segment
		(start 290.613592 -207.110076)
		(end 289.763454 -207.960214)
		(width 0.14478)
		(layer "In6.Cu")
		(net "M_E_CPU0_SA_DQ<10>")
	)
	(segment
		(start 323.880226 -226.777042)
		(end 323.866002 -226.777042)
		(width 0.0889)
		(layer "In6.Cu")
		(net "M_E_CPU0_SA_DQ<10>")
	)
	(segment
		(start 301.196502 -207.110076)
		(end 298.220638 -207.110076)
		(width 0.14478)
		(layer "In6.Cu")
		(net "M_E_CPU0_SA_DQ<10>")
	)
	(segment
		(start 289.763454 -207.960214)
		(end 286.814006 -207.960214)
		(width 0.14478)
		(layer "In6.Cu")
		(net "M_E_CPU0_SA_DQ<10>")
	)
	(segment
		(start 274.901152 -207.479138)
		(end 274.738084 -207.31607)
		(width 0.14478)
		(layer "In6.Cu")
		(net "M_E_CPU0_SA_DQ<10>")
	)
	(segment
		(start 325.34098 -228.934264)
		(end 324.930008 -228.934264)
		(width 0.0889)
		(layer "In6.Cu")
		(net "M_E_CPU0_SA_DQ<10>")
	)
	(segment
		(start 274.344638 -207.479138)
		(end 274.344638 -207.797146)
		(width 0.14478)
		(layer "In6.Cu")
		(net "M_E_CPU0_SA_DQ<10>")
	)
	(segment
		(start 293.652702 -207.110076)
		(end 290.613592 -207.110076)
		(width 0.14478)
		(layer "In6.Cu")
		(net "M_E_CPU0_SA_DQ<10>")
	)
	(segment
		(start 283.059378 -207.110076)
		(end 282.20924 -207.960214)
		(width 0.14478)
		(layer "In6.Cu")
		(net "M_E_CPU0_SA_DQ<10>")
	)
	(segment
		(start 327.362566 -230.302562)
		(end 326.872854 -229.81285)
		(width 0.0889)
		(layer "In6.Cu")
		(net "M_E_CPU0_SA_DQ<10>")
	)
	(segment
		(start 329.017122 -230.448866)
		(end 328.92111 -230.423466)
		(width 0.0889)
		(layer "In6.Cu")
		(net "M_E_CPU0_SA_DQ<10>")
	)
	(segment
		(start 294.50284 -207.960214)
		(end 293.652702 -207.110076)
		(width 0.14478)
		(layer "In6.Cu")
		(net "M_E_CPU0_SA_DQ<10>")
	)
	(segment
		(start 304.9143 -207.960214)
		(end 302.04664 -207.960214)
		(width 0.14478)
		(layer "In6.Cu")
		(net "M_E_CPU0_SA_DQ<10>")
	)
	(segment
		(start 297.3705 -207.960214)
		(end 294.50284 -207.960214)
		(width 0.14478)
		(layer "In6.Cu")
		(net "M_E_CPU0_SA_DQ<10>")
	)
	(segment
		(start 326.219566 -229.81285)
		(end 325.34098 -228.934264)
		(width 0.0889)
		(layer "In6.Cu")
		(net "M_E_CPU0_SA_DQ<10>")
	)
	(segment
		(start 274.738084 -207.31607)
		(end 274.507706 -207.31607)
		(width 0.14478)
		(layer "In6.Cu")
		(net "M_E_CPU0_SA_DQ<10>")
	)
	(segment
		(start 285.963868 -207.110076)
		(end 283.059378 -207.110076)
		(width 0.14478)
		(layer "In6.Cu")
		(net "M_E_CPU0_SA_DQ<10>")
	)
	(segment
		(start 274.18157 -207.960214)
		(end 273.51736 -207.960214)
		(width 0.14478)
		(layer "In6.Cu")
		(net "M_E_CPU0_SA_DQ<10>")
	)
	(arc
		(start 328.409808 -230.38689)
		(mid 328.2263 -230.341396)
		(end 328.044048 -230.391716)
		(width 0.0889)
		(layer "In6.Cu")
		(net "M_E_CPU0_SA_DQ<10>")
	)
	(arc
		(start 328.92111 -230.423466)
		(mid 328.665902 -230.466923)
		(end 328.41819 -230.391716)
		(width 0.0889)
		(layer "In6.Cu")
		(net "M_E_CPU0_SA_DQ<10>")
	)
	(arc
		(start 327.47839 -230.391716)
		(mid 327.417575 -230.35091)
		(end 327.362566 -230.302562)
		(width 0.0889)
		(layer "In6.Cu")
		(net "M_E_CPU0_SA_DQ<10>")
	)
	(arc
		(start 328.044048 -230.391716)
		(mid 327.767235 -230.467825)
		(end 327.488804 -230.397812)
		(width 0.0889)
		(layer "In6.Cu")
		(net "M_E_CPU0_SA_DQ<10>")
	)
	(segment
		(start 329.167998 -225.310192)
		(end 328.701146 -225.044254)
		(width 0.10668)
		(layer "F.Cu")
		(net "M_E_CPU0_SA_DQ<0>")
	)
	(segment
		(start 302.024542 -197.760082)
		(end 301.174658 -196.910198)
		(width 0.14478)
		(layer "In6.Cu")
		(net "M_E_CPU0_SA_DQ<0>")
	)
	(segment
		(start 290.795202 -196.910198)
		(end 289.945318 -197.760082)
		(width 0.14478)
		(layer "In6.Cu")
		(net "M_E_CPU0_SA_DQ<0>")
	)
	(segment
		(start 279.062942 -197.164198)
		(end 278.899874 -197.00113)
		(width 0.14478)
		(layer "In6.Cu")
		(net "M_E_CPU0_SA_DQ<0>")
	)
	(segment
		(start 320.417952 -209.572352)
		(end 320.711576 -209.278728)
		(width 0.14478)
		(layer "In6.Cu")
		(net "M_E_CPU0_SA_DQ<0>")
	)
	(segment
		(start 327.502774 -221.23273)
		(end 327.502774 -220.94317)
		(width 0.14478)
		(layer "In6.Cu")
		(net "M_E_CPU0_SA_DQ<0>")
	)
	(segment
		(start 305.071018 -197.760082)
		(end 302.024542 -197.760082)
		(width 0.14478)
		(layer "In6.Cu")
		(net "M_E_CPU0_SA_DQ<0>")
	)
	(segment
		(start 328.080624 -222.957898)
		(end 328.044302 -222.936816)
		(width 0.0889)
		(layer "In6.Cu")
		(net "M_E_CPU0_SA_DQ<0>")
	)
	(segment
		(start 279.22601 -197.760082)
		(end 279.062942 -197.597014)
		(width 0.14478)
		(layer "In6.Cu")
		(net "M_E_CPU0_SA_DQ<0>")
	)
	(segment
		(start 289.945318 -197.760082)
		(end 286.804862 -197.760082)
		(width 0.14478)
		(layer "In6.Cu")
		(net "M_E_CPU0_SA_DQ<0>")
	)
	(segment
		(start 297.527218 -197.760082)
		(end 294.480742 -197.760082)
		(width 0.14478)
		(layer "In6.Cu")
		(net "M_E_CPU0_SA_DQ<0>")
	)
	(segment
		(start 320.312542 -208.879948)
		(end 320.018918 -209.173572)
		(width 0.14478)
		(layer "In6.Cu")
		(net "M_E_CPU0_SA_DQ<0>")
	)
	(segment
		(start 318.922146 -207.284828)
		(end 318.717422 -207.284828)
		(width 0.14478)
		(layer "In6.Cu")
		(net "M_E_CPU0_SA_DQ<0>")
	)
	(segment
		(start 328.85507 -225.309684)
		(end 328.832718 -225.392996)
		(width 0.0889)
		(layer "In6.Cu")
		(net "M_E_CPU0_SA_DQ<0>")
	)
	(segment
		(start 320.711576 -209.278728)
		(end 320.711322 -209.074004)
		(width 0.14478)
		(layer "In6.Cu")
		(net "M_E_CPU0_SA_DQ<0>")
	)
	(segment
		(start 294.480742 -197.760082)
		(end 293.630858 -196.910198)
		(width 0.14478)
		(layer "In6.Cu")
		(net "M_E_CPU0_SA_DQ<0>")
	)
	(segment
		(start 278.669496 -197.00113)
		(end 278.506428 -197.164198)
		(width 0.14478)
		(layer "In6.Cu")
		(net "M_E_CPU0_SA_DQ<0>")
	)
	(segment
		(start 305.920902 -196.910198)
		(end 305.071018 -197.760082)
		(width 0.14478)
		(layer "In6.Cu")
		(net "M_E_CPU0_SA_DQ<0>")
	)
	(segment
		(start 283.248862 -196.910198)
		(end 282.398978 -197.760082)
		(width 0.14478)
		(layer "In6.Cu")
		(net "M_E_CPU0_SA_DQ<0>")
	)
	(segment
		(start 328.514202 -223.746822)
		(end 328.482452 -223.728534)
		(width 0.0889)
		(layer "In6.Cu")
		(net "M_E_CPU0_SA_DQ<0>")
	)
	(segment
		(start 328.044302 -222.936816)
		(end 328.012552 -222.918528)
		(width 0.0889)
		(layer "In6.Cu")
		(net "M_E_CPU0_SA_DQ<0>")
	)
	(segment
		(start 286.804862 -197.760082)
		(end 285.954978 -196.910198)
		(width 0.14478)
		(layer "In6.Cu")
		(net "M_E_CPU0_SA_DQ<0>")
	)
	(segment
		(start 318.219582 -207.578706)
		(end 317.75146 -207.110584)
		(width 0.14478)
		(layer "In6.Cu")
		(net "M_E_CPU0_SA_DQ<0>")
	)
	(segment
		(start 301.174658 -196.910198)
		(end 298.377102 -196.910198)
		(width 0.14478)
		(layer "In6.Cu")
		(net "M_E_CPU0_SA_DQ<0>")
	)
	(segment
		(start 327.611994 -222.148654)
		(end 327.542398 -222.108522)
		(width 0.0889)
		(layer "In6.Cu")
		(net "M_E_CPU0_SA_DQ<0>")
	)
	(segment
		(start 285.954978 -196.910198)
		(end 283.248862 -196.910198)
		(width 0.14478)
		(layer "In6.Cu")
		(net "M_E_CPU0_SA_DQ<0>")
	)
	(segment
		(start 278.34336 -197.760082)
		(end 277.617174 -197.760082)
		(width 0.14478)
		(layer "In6.Cu")
		(net "M_E_CPU0_SA_DQ<0>")
	)
	(segment
		(start 319.017142 -208.376266)
		(end 318.822832 -208.181956)
		(width 0.14478)
		(layer "In6.Cu")
		(net "M_E_CPU0_SA_DQ<0>")
	)
	(segment
		(start 319.221358 -208.376012)
		(end 319.017142 -208.376266)
		(width 0.14478)
		(layer "In6.Cu")
		(net "M_E_CPU0_SA_DQ<0>")
	)
	(segment
		(start 298.377102 -196.910198)
		(end 297.527218 -197.760082)
		(width 0.14478)
		(layer "In6.Cu")
		(net "M_E_CPU0_SA_DQ<0>")
	)
	(segment
		(start 279.062942 -197.597014)
		(end 279.062942 -197.164198)
		(width 0.14478)
		(layer "In6.Cu")
		(net "M_E_CPU0_SA_DQ<0>")
	)
	(segment
		(start 319.620392 -208.774792)
		(end 319.914016 -208.481168)
		(width 0.14478)
		(layer "In6.Cu")
		(net "M_E_CPU0_SA_DQ<0>")
	)
	(segment
		(start 278.506428 -197.597014)
		(end 278.34336 -197.760082)
		(width 0.14478)
		(layer "In6.Cu")
		(net "M_E_CPU0_SA_DQ<0>")
	)
	(segment
		(start 327.386188 -221.564962)
		(end 327.502774 -221.448376)
		(width 0.0889)
		(layer "In6.Cu")
		(net "M_E_CPU0_SA_DQ<0>")
	)
	(segment
		(start 328.514202 -224.721674)
		(end 328.550524 -224.700592)
		(width 0.0889)
		(layer "In6.Cu")
		(net "M_E_CPU0_SA_DQ<0>")
	)
	(segment
		(start 319.116456 -207.683608)
		(end 319.116202 -207.478884)
		(width 0.14478)
		(layer "In6.Cu")
		(net "M_E_CPU0_SA_DQ<0>")
	)
	(segment
		(start 318.822832 -208.181956)
		(end 318.822832 -207.977232)
		(width 0.14478)
		(layer "In6.Cu")
		(net "M_E_CPU0_SA_DQ<0>")
	)
	(segment
		(start 317.75146 -206.07401)
		(end 308.587648 -196.910198)
		(width 0.14478)
		(layer "In6.Cu")
		(net "M_E_CPU0_SA_DQ<0>")
	)
	(segment
		(start 319.514982 -208.082388)
		(end 319.221358 -208.376012)
		(width 0.14478)
		(layer "In6.Cu")
		(net "M_E_CPU0_SA_DQ<0>")
	)
	(segment
		(start 327.502774 -221.448376)
		(end 327.502774 -221.23273)
		(width 0.0889)
		(layer "In6.Cu")
		(net "M_E_CPU0_SA_DQ<0>")
	)
	(segment
		(start 319.116202 -207.478884)
		(end 318.922146 -207.284828)
		(width 0.14478)
		(layer "In6.Cu")
		(net "M_E_CPU0_SA_DQ<0>")
	)
	(segment
		(start 327.386188 -221.803976)
		(end 327.386188 -221.564962)
		(width 0.0889)
		(layer "In6.Cu")
		(net "M_E_CPU0_SA_DQ<0>")
	)
	(segment
		(start 278.899874 -197.00113)
		(end 278.669496 -197.00113)
		(width 0.14478)
		(layer "In6.Cu")
		(net "M_E_CPU0_SA_DQ<0>")
	)
	(segment
		(start 327.502774 -220.94317)
		(end 325.000874 -218.44127)
		(width 0.14478)
		(layer "In6.Cu")
		(net "M_E_CPU0_SA_DQ<0>")
	)
	(segment
		(start 328.514202 -225.366834)
		(end 328.482452 -225.348546)
		(width 0.0889)
		(layer "In6.Cu")
		(net "M_E_CPU0_SA_DQ<0>")
	)
	(segment
		(start 318.423798 -207.578452)
		(end 318.219582 -207.578706)
		(width 0.14478)
		(layer "In6.Cu")
		(net "M_E_CPU0_SA_DQ<0>")
	)
	(segment
		(start 325.000874 -218.44127)
		(end 325.000874 -214.359998)
		(width 0.14478)
		(layer "In6.Cu")
		(net "M_E_CPU0_SA_DQ<0>")
	)
	(segment
		(start 319.913762 -208.276444)
		(end 319.719706 -208.082388)
		(width 0.14478)
		(layer "In6.Cu")
		(net "M_E_CPU0_SA_DQ<0>")
	)
	(segment
		(start 319.719706 -208.082388)
		(end 319.514982 -208.082388)
		(width 0.14478)
		(layer "In6.Cu")
		(net "M_E_CPU0_SA_DQ<0>")
	)
	(segment
		(start 320.711322 -209.074004)
		(end 320.517266 -208.879948)
		(width 0.14478)
		(layer "In6.Cu")
		(net "M_E_CPU0_SA_DQ<0>")
	)
	(segment
		(start 282.398978 -197.760082)
		(end 279.22601 -197.760082)
		(width 0.14478)
		(layer "In6.Cu")
		(net "M_E_CPU0_SA_DQ<0>")
	)
	(segment
		(start 328.482452 -224.739962)
		(end 328.514202 -224.721674)
		(width 0.0889)
		(layer "In6.Cu")
		(net "M_E_CPU0_SA_DQ<0>")
	)
	(segment
		(start 325.000874 -214.359998)
		(end 320.417952 -209.777076)
		(width 0.14478)
		(layer "In6.Cu")
		(net "M_E_CPU0_SA_DQ<0>")
	)
	(segment
		(start 293.630858 -196.910198)
		(end 290.795202 -196.910198)
		(width 0.14478)
		(layer "In6.Cu")
		(net "M_E_CPU0_SA_DQ<0>")
	)
	(segment
		(start 319.814702 -209.173826)
		(end 319.620392 -208.979516)
		(width 0.14478)
		(layer "In6.Cu")
		(net "M_E_CPU0_SA_DQ<0>")
	)
	(segment
		(start 328.550524 -223.767904)
		(end 328.514202 -223.746822)
		(width 0.0889)
		(layer "In6.Cu")
		(net "M_E_CPU0_SA_DQ<0>")
	)
	(segment
		(start 317.75146 -207.110584)
		(end 317.75146 -206.07401)
		(width 0.14478)
		(layer "In6.Cu")
		(net "M_E_CPU0_SA_DQ<0>")
	)
	(segment
		(start 278.506428 -197.164198)
		(end 278.506428 -197.597014)
		(width 0.14478)
		(layer "In6.Cu")
		(net "M_E_CPU0_SA_DQ<0>")
	)
	(segment
		(start 320.517266 -208.879948)
		(end 320.312542 -208.879948)
		(width 0.14478)
		(layer "In6.Cu")
		(net "M_E_CPU0_SA_DQ<0>")
	)
	(segment
		(start 318.822832 -207.977232)
		(end 319.116456 -207.683608)
		(width 0.14478)
		(layer "In6.Cu")
		(net "M_E_CPU0_SA_DQ<0>")
	)
	(segment
		(start 277.617174 -197.760082)
		(end 277.192232 -197.33514)
		(width 0.14478)
		(layer "In6.Cu")
		(net "M_E_CPU0_SA_DQ<0>")
	)
	(segment
		(start 328.701146 -225.044254)
		(end 328.85507 -225.309684)
		(width 0.0889)
		(layer "In6.Cu")
		(net "M_E_CPU0_SA_DQ<0>")
	)
	(segment
		(start 320.417952 -209.777076)
		(end 320.417952 -209.572352)
		(width 0.14478)
		(layer "In6.Cu")
		(net "M_E_CPU0_SA_DQ<0>")
	)
	(segment
		(start 308.587648 -196.910198)
		(end 305.920902 -196.910198)
		(width 0.14478)
		(layer "In6.Cu")
		(net "M_E_CPU0_SA_DQ<0>")
	)
	(segment
		(start 318.717422 -207.284828)
		(end 318.423798 -207.578452)
		(width 0.14478)
		(layer "In6.Cu")
		(net "M_E_CPU0_SA_DQ<0>")
	)
	(segment
		(start 319.620392 -208.979516)
		(end 319.620392 -208.774792)
		(width 0.14478)
		(layer "In6.Cu")
		(net "M_E_CPU0_SA_DQ<0>")
	)
	(segment
		(start 319.914016 -208.481168)
		(end 319.913762 -208.276444)
		(width 0.14478)
		(layer "In6.Cu")
		(net "M_E_CPU0_SA_DQ<0>")
	)
	(segment
		(start 320.018918 -209.173572)
		(end 319.814702 -209.173826)
		(width 0.14478)
		(layer "In6.Cu")
		(net "M_E_CPU0_SA_DQ<0>")
	)
	(arc
		(start 328.326496 -223.424242)
		(mid 328.26126 -223.160651)
		(end 328.080624 -222.957898)
		(width 0.0889)
		(layer "In6.Cu")
		(net "M_E_CPU0_SA_DQ<0>")
	)
	(arc
		(start 328.550524 -224.700592)
		(mid 328.796414 -224.234248)
		(end 328.550524 -223.767904)
		(width 0.0889)
		(layer "In6.Cu")
		(net "M_E_CPU0_SA_DQ<0>")
	)
	(arc
		(start 327.542398 -222.108522)
		(mid 327.531841 -222.100577)
		(end 327.52157 -222.092266)
		(width 0.0889)
		(layer "In6.Cu")
		(net "M_E_CPU0_SA_DQ<0>")
	)
	(arc
		(start 328.832718 -225.392996)
		(mid 328.670529 -225.415731)
		(end 328.514202 -225.366834)
		(width 0.0889)
		(layer "In6.Cu")
		(net "M_E_CPU0_SA_DQ<0>")
	)
	(arc
		(start 328.482452 -225.348546)
		(mid 328.326524 -225.044254)
		(end 328.482452 -224.739962)
		(width 0.0889)
		(layer "In6.Cu")
		(net "M_E_CPU0_SA_DQ<0>")
	)
	(arc
		(start 327.856596 -222.614236)
		(mid 327.791724 -222.351273)
		(end 327.611994 -222.148654)
		(width 0.0889)
		(layer "In6.Cu")
		(net "M_E_CPU0_SA_DQ<0>")
	)
	(arc
		(start 328.482452 -223.728534)
		(mid 328.367776 -223.5952)
		(end 328.326496 -223.424242)
		(width 0.0889)
		(layer "In6.Cu")
		(net "M_E_CPU0_SA_DQ<0>")
	)
	(arc
		(start 327.52157 -222.092266)
		(mid 327.421721 -221.963223)
		(end 327.386188 -221.803976)
		(width 0.0889)
		(layer "In6.Cu")
		(net "M_E_CPU0_SA_DQ<0>")
	)
	(arc
		(start 328.012552 -222.918528)
		(mid 327.897876 -222.785194)
		(end 327.856596 -222.614236)
		(width 0.0889)
		(layer "In6.Cu")
		(net "M_E_CPU0_SA_DQ<0>")
	)
	(segment
		(start 331.047852 -252.850142)
		(end 330.581 -252.584204)
		(width 0.10668)
		(layer "F.Cu")
		(net "M_E_CPU0_SA_CS_N<1>")
	)
	(segment
		(start 322.297806 -252.83287)
		(end 320.982086 -251.51715)
		(width 0.14478)
		(layer "In6.Cu")
		(net "M_E_CPU0_SA_CS_N<1>")
	)
	(segment
		(start 327.574402 -252.261624)
		(end 327.563988 -252.26772)
		(width 0.0889)
		(layer "In6.Cu")
		(net "M_E_CPU0_SA_CS_N<1>")
	)
	(segment
		(start 324.584314 -252.46203)
		(end 324.213474 -252.83287)
		(width 0.0889)
		(layer "In6.Cu")
		(net "M_E_CPU0_SA_CS_N<1>")
	)
	(segment
		(start 307.710078 -248.75998)
		(end 279.253188 -248.75998)
		(width 0.14478)
		(layer "In6.Cu")
		(net "M_E_CPU0_SA_CS_N<1>")
	)
	(segment
		(start 273.517106 -247.059958)
		(end 273.092164 -246.635016)
		(width 0.14478)
		(layer "In6.Cu")
		(net "M_E_CPU0_SA_CS_N<1>")
	)
	(segment
		(start 329.828144 -252.261624)
		(end 329.819762 -252.256798)
		(width 0.0889)
		(layer "In6.Cu")
		(net "M_E_CPU0_SA_CS_N<1>")
	)
	(segment
		(start 320.982086 -251.51715)
		(end 310.467248 -251.51715)
		(width 0.14478)
		(layer "In6.Cu")
		(net "M_E_CPU0_SA_CS_N<1>")
	)
	(segment
		(start 325.292212 -252.267212)
		(end 325.097394 -252.46203)
		(width 0.0889)
		(layer "In6.Cu")
		(net "M_E_CPU0_SA_CS_N<1>")
	)
	(segment
		(start 327.008744 -252.261624)
		(end 326.99706 -252.254766)
		(width 0.0889)
		(layer "In6.Cu")
		(net "M_E_CPU0_SA_CS_N<1>")
	)
	(segment
		(start 277.553166 -247.059958)
		(end 273.517106 -247.059958)
		(width 0.14478)
		(layer "In6.Cu")
		(net "M_E_CPU0_SA_CS_N<1>")
	)
	(segment
		(start 326.080628 -252.268736)
		(end 326.06869 -252.261878)
		(width 0.0889)
		(layer "In6.Cu")
		(net "M_E_CPU0_SA_CS_N<1>")
	)
	(segment
		(start 279.253188 -248.75998)
		(end 277.553166 -247.059958)
		(width 0.14478)
		(layer "In6.Cu")
		(net "M_E_CPU0_SA_CS_N<1>")
	)
	(segment
		(start 330.427076 -252.318774)
		(end 330.331064 -252.293374)
		(width 0.0889)
		(layer "In6.Cu")
		(net "M_E_CPU0_SA_CS_N<1>")
	)
	(segment
		(start 325.698104 -252.267212)
		(end 325.292212 -252.267212)
		(width 0.0889)
		(layer "In6.Cu")
		(net "M_E_CPU0_SA_CS_N<1>")
	)
	(segment
		(start 323.921374 -252.83287)
		(end 322.297806 -252.83287)
		(width 0.14478)
		(layer "In6.Cu")
		(net "M_E_CPU0_SA_CS_N<1>")
	)
	(segment
		(start 325.097394 -252.46203)
		(end 324.584314 -252.46203)
		(width 0.0889)
		(layer "In6.Cu")
		(net "M_E_CPU0_SA_CS_N<1>")
	)
	(segment
		(start 310.467248 -251.51715)
		(end 307.710078 -248.75998)
		(width 0.14478)
		(layer "In6.Cu")
		(net "M_E_CPU0_SA_CS_N<1>")
	)
	(segment
		(start 330.581 -252.584204)
		(end 330.427076 -252.318774)
		(width 0.0889)
		(layer "In6.Cu")
		(net "M_E_CPU0_SA_CS_N<1>")
	)
	(segment
		(start 324.213474 -252.83287)
		(end 323.921374 -252.83287)
		(width 0.0889)
		(layer "In6.Cu")
		(net "M_E_CPU0_SA_CS_N<1>")
	)
	(segment
		(start 327.586086 -252.254766)
		(end 327.574402 -252.261624)
		(width 0.0889)
		(layer "In6.Cu")
		(net "M_E_CPU0_SA_CS_N<1>")
	)
	(arc
		(start 328.514202 -252.261624)
		(mid 328.231246 -252.337801)
		(end 327.94829 -252.261624)
		(width 0.0889)
		(layer "In6.Cu")
		(net "M_E_CPU0_SA_CS_N<1>")
	)
	(arc
		(start 328.88809 -252.261624)
		(mid 328.701146 -252.211369)
		(end 328.514202 -252.261624)
		(width 0.0889)
		(layer "In6.Cu")
		(net "M_E_CPU0_SA_CS_N<1>")
	)
	(arc
		(start 326.634348 -252.261624)
		(mid 326.358416 -252.337881)
		(end 326.080628 -252.268736)
		(width 0.0889)
		(layer "In6.Cu")
		(net "M_E_CPU0_SA_CS_N<1>")
	)
	(arc
		(start 326.06869 -252.261878)
		(mid 325.882658 -252.213653)
		(end 325.698104 -252.267212)
		(width 0.0889)
		(layer "In6.Cu")
		(net "M_E_CPU0_SA_CS_N<1>")
	)
	(arc
		(start 326.99706 -252.254766)
		(mid 326.814805 -252.211113)
		(end 326.634348 -252.261624)
		(width 0.0889)
		(layer "In6.Cu")
		(net "M_E_CPU0_SA_CS_N<1>")
	)
	(arc
		(start 327.94829 -252.261624)
		(mid 327.768085 -252.211307)
		(end 327.586086 -252.254766)
		(width 0.0889)
		(layer "In6.Cu")
		(net "M_E_CPU0_SA_CS_N<1>")
	)
	(arc
		(start 329.454002 -252.261624)
		(mid 329.171046 -252.337801)
		(end 328.88809 -252.261624)
		(width 0.0889)
		(layer "In6.Cu")
		(net "M_E_CPU0_SA_CS_N<1>")
	)
	(arc
		(start 327.563988 -252.26772)
		(mid 327.285556 -252.337818)
		(end 327.008744 -252.261624)
		(width 0.0889)
		(layer "In6.Cu")
		(net "M_E_CPU0_SA_CS_N<1>")
	)
	(arc
		(start 330.331064 -252.293374)
		(mid 330.075856 -252.336851)
		(end 329.828144 -252.261624)
		(width 0.0889)
		(layer "In6.Cu")
		(net "M_E_CPU0_SA_CS_N<1>")
	)
	(arc
		(start 329.819762 -252.256798)
		(mid 329.636254 -252.211304)
		(end 329.454002 -252.261624)
		(width 0.0889)
		(layer "In6.Cu")
		(net "M_E_CPU0_SA_CS_N<1>")
	)
	(segment
		(start 329.637898 -252.040136)
		(end 329.171046 -251.774198)
		(width 0.10668)
		(layer "F.Cu")
		(net "M_E_CPU0_SA_CS_N<0>")
	)
	(segment
		(start 294.16883 -247.910096)
		(end 294.005762 -248.073164)
		(width 0.14478)
		(layer "In6.Cu")
		(net "M_E_CPU0_SA_CS_N<0>")
	)
	(segment
		(start 290.075874 -247.910096)
		(end 289.912806 -248.073164)
		(width 0.14478)
		(layer "In6.Cu")
		(net "M_E_CPU0_SA_CS_N<0>")
	)
	(segment
		(start 286.281114 -248.073164)
		(end 286.118046 -247.910096)
		(width 0.14478)
		(layer "In6.Cu")
		(net "M_E_CPU0_SA_CS_N<0>")
	)
	(segment
		(start 283.2862 -248.30405)
		(end 283.055822 -248.30405)
		(width 0.14478)
		(layer "In6.Cu")
		(net "M_E_CPU0_SA_CS_N<0>")
	)
	(segment
		(start 307.710078 -247.910096)
		(end 294.16883 -247.910096)
		(width 0.14478)
		(layer "In6.Cu")
		(net "M_E_CPU0_SA_CS_N<0>")
	)
	(segment
		(start 290.306252 -247.910096)
		(end 290.075874 -247.910096)
		(width 0.14478)
		(layer "In6.Cu")
		(net "M_E_CPU0_SA_CS_N<0>")
	)
	(segment
		(start 327.488804 -251.457714)
		(end 327.47839 -251.451618)
		(width 0.0889)
		(layer "In6.Cu")
		(net "M_E_CPU0_SA_CS_N<0>")
	)
	(segment
		(start 281.779726 -248.073164)
		(end 281.616658 -247.910096)
		(width 0.14478)
		(layer "In6.Cu")
		(net "M_E_CPU0_SA_CS_N<0>")
	)
	(segment
		(start 293.842694 -248.30405)
		(end 293.612316 -248.30405)
		(width 0.14478)
		(layer "In6.Cu")
		(net "M_E_CPU0_SA_CS_N<0>")
	)
	(segment
		(start 326.176132 -251.44476)
		(end 326.163686 -251.457206)
		(width 0.0889)
		(layer "In6.Cu")
		(net "M_E_CPU0_SA_CS_N<0>")
	)
	(segment
		(start 289.356292 -248.133362)
		(end 289.356292 -248.073164)
		(width 0.14478)
		(layer "In6.Cu")
		(net "M_E_CPU0_SA_CS_N<0>")
	)
	(segment
		(start 281.616658 -247.910096)
		(end 279.317196 -247.910096)
		(width 0.14478)
		(layer "In6.Cu")
		(net "M_E_CPU0_SA_CS_N<0>")
	)
	(segment
		(start 289.912806 -248.073164)
		(end 289.912806 -248.133362)
		(width 0.14478)
		(layer "In6.Cu")
		(net "M_E_CPU0_SA_CS_N<0>")
	)
	(segment
		(start 294.005762 -248.140982)
		(end 293.842694 -248.30405)
		(width 0.14478)
		(layer "In6.Cu")
		(net "M_E_CPU0_SA_CS_N<0>")
	)
	(segment
		(start 328.41819 -251.451618)
		(end 328.409808 -251.446792)
		(width 0.0889)
		(layer "In6.Cu")
		(net "M_E_CPU0_SA_CS_N<0>")
	)
	(segment
		(start 282.892754 -248.073164)
		(end 282.729686 -247.910096)
		(width 0.14478)
		(layer "In6.Cu")
		(net "M_E_CPU0_SA_CS_N<0>")
	)
	(segment
		(start 291.188902 -247.910096)
		(end 291.025834 -248.073164)
		(width 0.14478)
		(layer "In6.Cu")
		(net "M_E_CPU0_SA_CS_N<0>")
	)
	(segment
		(start 286.67456 -248.30405)
		(end 286.444182 -248.30405)
		(width 0.14478)
		(layer "In6.Cu")
		(net "M_E_CPU0_SA_CS_N<0>")
	)
	(segment
		(start 289.356292 -248.073164)
		(end 289.193224 -247.910096)
		(width 0.14478)
		(layer "In6.Cu")
		(net "M_E_CPU0_SA_CS_N<0>")
	)
	(segment
		(start 293.612316 -248.30405)
		(end 293.449248 -248.140982)
		(width 0.14478)
		(layer "In6.Cu")
		(net "M_E_CPU0_SA_CS_N<0>")
	)
	(segment
		(start 324.231254 -252.07849)
		(end 323.931534 -252.37821)
		(width 0.0889)
		(layer "In6.Cu")
		(net "M_E_CPU0_SA_CS_N<0>")
	)
	(segment
		(start 281.942794 -248.30405)
		(end 281.779726 -248.140982)
		(width 0.14478)
		(layer "In6.Cu")
		(net "M_E_CPU0_SA_CS_N<0>")
	)
	(segment
		(start 282.499308 -247.910096)
		(end 282.33624 -248.073164)
		(width 0.14478)
		(layer "In6.Cu")
		(net "M_E_CPU0_SA_CS_N<0>")
	)
	(segment
		(start 323.931534 -252.37821)
		(end 322.486274 -252.37821)
		(width 0.14478)
		(layer "In6.Cu")
		(net "M_E_CPU0_SA_CS_N<0>")
	)
	(segment
		(start 294.005762 -248.073164)
		(end 294.005762 -248.140982)
		(width 0.14478)
		(layer "In6.Cu")
		(net "M_E_CPU0_SA_CS_N<0>")
	)
	(segment
		(start 281.779726 -248.140982)
		(end 281.779726 -248.073164)
		(width 0.14478)
		(layer "In6.Cu")
		(net "M_E_CPU0_SA_CS_N<0>")
	)
	(segment
		(start 327.104502 -251.451618)
		(end 327.094088 -251.457714)
		(width 0.0889)
		(layer "In6.Cu")
		(net "M_E_CPU0_SA_CS_N<0>")
	)
	(segment
		(start 321.170554 -251.06249)
		(end 310.862472 -251.06249)
		(width 0.14478)
		(layer "In6.Cu")
		(net "M_E_CPU0_SA_CS_N<0>")
	)
	(segment
		(start 286.837628 -248.073164)
		(end 286.837628 -248.140982)
		(width 0.14478)
		(layer "In6.Cu")
		(net "M_E_CPU0_SA_CS_N<0>")
	)
	(segment
		(start 293.28618 -247.910096)
		(end 291.188902 -247.910096)
		(width 0.14478)
		(layer "In6.Cu")
		(net "M_E_CPU0_SA_CS_N<0>")
	)
	(segment
		(start 289.51936 -248.29643)
		(end 289.356292 -248.133362)
		(width 0.14478)
		(layer "In6.Cu")
		(net "M_E_CPU0_SA_CS_N<0>")
	)
	(segment
		(start 325.003414 -252.07849)
		(end 324.231254 -252.07849)
		(width 0.0889)
		(layer "In6.Cu")
		(net "M_E_CPU0_SA_CS_N<0>")
	)
	(segment
		(start 289.749738 -248.29643)
		(end 289.51936 -248.29643)
		(width 0.14478)
		(layer "In6.Cu")
		(net "M_E_CPU0_SA_CS_N<0>")
	)
	(segment
		(start 291.025834 -248.133362)
		(end 290.862766 -248.29643)
		(width 0.14478)
		(layer "In6.Cu")
		(net "M_E_CPU0_SA_CS_N<0>")
	)
	(segment
		(start 283.449268 -248.073164)
		(end 283.449268 -248.140982)
		(width 0.14478)
		(layer "In6.Cu")
		(net "M_E_CPU0_SA_CS_N<0>")
	)
	(segment
		(start 287.000696 -247.910096)
		(end 286.837628 -248.073164)
		(width 0.14478)
		(layer "In6.Cu")
		(net "M_E_CPU0_SA_CS_N<0>")
	)
	(segment
		(start 325.624698 -251.457206)
		(end 325.003414 -252.07849)
		(width 0.0889)
		(layer "In6.Cu")
		(net "M_E_CPU0_SA_CS_N<0>")
	)
	(segment
		(start 326.163686 -251.457206)
		(end 325.624698 -251.457206)
		(width 0.0889)
		(layer "In6.Cu")
		(net "M_E_CPU0_SA_CS_N<0>")
	)
	(segment
		(start 290.46932 -248.133362)
		(end 290.46932 -248.073164)
		(width 0.14478)
		(layer "In6.Cu")
		(net "M_E_CPU0_SA_CS_N<0>")
	)
	(segment
		(start 283.449268 -248.140982)
		(end 283.2862 -248.30405)
		(width 0.14478)
		(layer "In6.Cu")
		(net "M_E_CPU0_SA_CS_N<0>")
	)
	(segment
		(start 283.612336 -247.910096)
		(end 283.449268 -248.073164)
		(width 0.14478)
		(layer "In6.Cu")
		(net "M_E_CPU0_SA_CS_N<0>")
	)
	(segment
		(start 310.862472 -251.06249)
		(end 307.710078 -247.910096)
		(width 0.14478)
		(layer "In6.Cu")
		(net "M_E_CPU0_SA_CS_N<0>")
	)
	(segment
		(start 286.837628 -248.140982)
		(end 286.67456 -248.30405)
		(width 0.14478)
		(layer "In6.Cu")
		(net "M_E_CPU0_SA_CS_N<0>")
	)
	(segment
		(start 290.862766 -248.29643)
		(end 290.632388 -248.29643)
		(width 0.14478)
		(layer "In6.Cu")
		(net "M_E_CPU0_SA_CS_N<0>")
	)
	(segment
		(start 293.449248 -248.140982)
		(end 293.449248 -248.073164)
		(width 0.14478)
		(layer "In6.Cu")
		(net "M_E_CPU0_SA_CS_N<0>")
	)
	(segment
		(start 290.46932 -248.073164)
		(end 290.306252 -247.910096)
		(width 0.14478)
		(layer "In6.Cu")
		(net "M_E_CPU0_SA_CS_N<0>")
	)
	(segment
		(start 322.486274 -252.37821)
		(end 321.170554 -251.06249)
		(width 0.14478)
		(layer "In6.Cu")
		(net "M_E_CPU0_SA_CS_N<0>")
	)
	(segment
		(start 293.449248 -248.073164)
		(end 293.28618 -247.910096)
		(width 0.14478)
		(layer "In6.Cu")
		(net "M_E_CPU0_SA_CS_N<0>")
	)
	(segment
		(start 282.892754 -248.140982)
		(end 282.892754 -248.073164)
		(width 0.14478)
		(layer "In6.Cu")
		(net "M_E_CPU0_SA_CS_N<0>")
	)
	(segment
		(start 329.017122 -251.508768)
		(end 328.92111 -251.483368)
		(width 0.0889)
		(layer "In6.Cu")
		(net "M_E_CPU0_SA_CS_N<0>")
	)
	(segment
		(start 289.912806 -248.133362)
		(end 289.749738 -248.29643)
		(width 0.14478)
		(layer "In6.Cu")
		(net "M_E_CPU0_SA_CS_N<0>")
	)
	(segment
		(start 279.317196 -247.910096)
		(end 277.192232 -245.785132)
		(width 0.14478)
		(layer "In6.Cu")
		(net "M_E_CPU0_SA_CS_N<0>")
	)
	(segment
		(start 282.729686 -247.910096)
		(end 282.499308 -247.910096)
		(width 0.14478)
		(layer "In6.Cu")
		(net "M_E_CPU0_SA_CS_N<0>")
	)
	(segment
		(start 282.33624 -248.140982)
		(end 282.173172 -248.30405)
		(width 0.14478)
		(layer "In6.Cu")
		(net "M_E_CPU0_SA_CS_N<0>")
	)
	(segment
		(start 283.055822 -248.30405)
		(end 282.892754 -248.140982)
		(width 0.14478)
		(layer "In6.Cu")
		(net "M_E_CPU0_SA_CS_N<0>")
	)
	(segment
		(start 290.632388 -248.29643)
		(end 290.46932 -248.133362)
		(width 0.14478)
		(layer "In6.Cu")
		(net "M_E_CPU0_SA_CS_N<0>")
	)
	(segment
		(start 329.171046 -251.774198)
		(end 329.017122 -251.508768)
		(width 0.0889)
		(layer "In6.Cu")
		(net "M_E_CPU0_SA_CS_N<0>")
	)
	(segment
		(start 282.173172 -248.30405)
		(end 281.942794 -248.30405)
		(width 0.14478)
		(layer "In6.Cu")
		(net "M_E_CPU0_SA_CS_N<0>")
	)
	(segment
		(start 289.193224 -247.910096)
		(end 287.000696 -247.910096)
		(width 0.14478)
		(layer "In6.Cu")
		(net "M_E_CPU0_SA_CS_N<0>")
	)
	(segment
		(start 286.444182 -248.30405)
		(end 286.281114 -248.140982)
		(width 0.14478)
		(layer "In6.Cu")
		(net "M_E_CPU0_SA_CS_N<0>")
	)
	(segment
		(start 286.118046 -247.910096)
		(end 283.612336 -247.910096)
		(width 0.14478)
		(layer "In6.Cu")
		(net "M_E_CPU0_SA_CS_N<0>")
	)
	(segment
		(start 286.281114 -248.140982)
		(end 286.281114 -248.073164)
		(width 0.14478)
		(layer "In6.Cu")
		(net "M_E_CPU0_SA_CS_N<0>")
	)
	(segment
		(start 291.025834 -248.073164)
		(end 291.025834 -248.133362)
		(width 0.14478)
		(layer "In6.Cu")
		(net "M_E_CPU0_SA_CS_N<0>")
	)
	(segment
		(start 282.33624 -248.073164)
		(end 282.33624 -248.140982)
		(width 0.14478)
		(layer "In6.Cu")
		(net "M_E_CPU0_SA_CS_N<0>")
	)
	(arc
		(start 327.094088 -251.457714)
		(mid 326.815402 -251.527934)
		(end 326.538336 -251.451618)
		(width 0.0889)
		(layer "In6.Cu")
		(net "M_E_CPU0_SA_CS_N<0>")
	)
	(arc
		(start 328.409808 -251.446792)
		(mid 328.2263 -251.401298)
		(end 328.044048 -251.451618)
		(width 0.0889)
		(layer "In6.Cu")
		(net "M_E_CPU0_SA_CS_N<0>")
	)
	(arc
		(start 328.044048 -251.451618)
		(mid 327.767235 -251.527761)
		(end 327.488804 -251.457714)
		(width 0.0889)
		(layer "In6.Cu")
		(net "M_E_CPU0_SA_CS_N<0>")
	)
	(arc
		(start 328.92111 -251.483368)
		(mid 328.665902 -251.526845)
		(end 328.41819 -251.451618)
		(width 0.0889)
		(layer "In6.Cu")
		(net "M_E_CPU0_SA_CS_N<0>")
	)
	(arc
		(start 326.538336 -251.451618)
		(mid 326.358131 -251.401301)
		(end 326.176132 -251.44476)
		(width 0.0889)
		(layer "In6.Cu")
		(net "M_E_CPU0_SA_CS_N<0>")
	)
	(arc
		(start 327.47839 -251.451618)
		(mid 327.291446 -251.401363)
		(end 327.104502 -251.451618)
		(width 0.0889)
		(layer "In6.Cu")
		(net "M_E_CPU0_SA_CS_N<0>")
	)
	(segment
		(start 331.047852 -249.610118)
		(end 330.581 -249.34418)
		(width 0.10668)
		(layer "F.Cu")
		(net "M_E_CPU0_SA_CB<7>")
	)
	(segment
		(start 275.725128 -242.77447)
		(end 275.56206 -242.937538)
		(width 0.14478)
		(layer "In6.Cu")
		(net "M_E_CPU0_SA_CB<7>")
	)
	(segment
		(start 275.56206 -242.937538)
		(end 275.56206 -244.049042)
		(width 0.14478)
		(layer "In6.Cu")
		(net "M_E_CPU0_SA_CB<7>")
	)
	(segment
		(start 275.955506 -242.77447)
		(end 275.725128 -242.77447)
		(width 0.14478)
		(layer "In6.Cu")
		(net "M_E_CPU0_SA_CB<7>")
	)
	(segment
		(start 326.634348 -249.0216)
		(end 325.697088 -249.96775)
		(width 0.0889)
		(layer "In6.Cu")
		(net "M_E_CPU0_SA_CB<7>")
	)
	(segment
		(start 281.264106 -243.660168)
		(end 276.281642 -243.660168)
		(width 0.14478)
		(layer "In6.Cu")
		(net "M_E_CPU0_SA_CB<7>")
	)
	(segment
		(start 274.6121 -242.95989)
		(end 274.337018 -243.234972)
		(width 0.14478)
		(layer "In6.Cu")
		(net "M_E_CPU0_SA_CB<7>")
	)
	(segment
		(start 330.427076 -249.07875)
		(end 330.331064 -249.05335)
		(width 0.0889)
		(layer "In6.Cu")
		(net "M_E_CPU0_SA_CB<7>")
	)
	(segment
		(start 274.337018 -243.234972)
		(end 273.092164 -243.234972)
		(width 0.14478)
		(layer "In6.Cu")
		(net "M_E_CPU0_SA_CB<7>")
	)
	(segment
		(start 275.56206 -244.049042)
		(end 275.398992 -244.21211)
		(width 0.14478)
		(layer "In6.Cu")
		(net "M_E_CPU0_SA_CB<7>")
	)
	(segment
		(start 275.005546 -244.049042)
		(end 275.005546 -243.122958)
		(width 0.14478)
		(layer "In6.Cu")
		(net "M_E_CPU0_SA_CB<7>")
	)
	(segment
		(start 329.828144 -249.0216)
		(end 329.819762 -249.016774)
		(width 0.0889)
		(layer "In6.Cu")
		(net "M_E_CPU0_SA_CB<7>")
	)
	(segment
		(start 276.118574 -242.937538)
		(end 275.955506 -242.77447)
		(width 0.14478)
		(layer "In6.Cu")
		(net "M_E_CPU0_SA_CB<7>")
	)
	(segment
		(start 327.008744 -249.0216)
		(end 326.99706 -249.014742)
		(width 0.0889)
		(layer "In6.Cu")
		(net "M_E_CPU0_SA_CB<7>")
	)
	(segment
		(start 276.118574 -243.4971)
		(end 276.118574 -242.937538)
		(width 0.14478)
		(layer "In6.Cu")
		(net "M_E_CPU0_SA_CB<7>")
	)
	(segment
		(start 327.574402 -249.0216)
		(end 327.563988 -249.027696)
		(width 0.0889)
		(layer "In6.Cu")
		(net "M_E_CPU0_SA_CB<7>")
	)
	(segment
		(start 327.586086 -249.014742)
		(end 327.574402 -249.0216)
		(width 0.0889)
		(layer "In6.Cu")
		(net "M_E_CPU0_SA_CB<7>")
	)
	(segment
		(start 307.881782 -245.36019)
		(end 282.964128 -245.36019)
		(width 0.14478)
		(layer "In6.Cu")
		(net "M_E_CPU0_SA_CB<7>")
	)
	(segment
		(start 321.965574 -249.14479)
		(end 311.666382 -249.14479)
		(width 0.14478)
		(layer "In6.Cu")
		(net "M_E_CPU0_SA_CB<7>")
	)
	(segment
		(start 275.005546 -243.122958)
		(end 274.842478 -242.95989)
		(width 0.14478)
		(layer "In6.Cu")
		(net "M_E_CPU0_SA_CB<7>")
	)
	(segment
		(start 324.188074 -249.96775)
		(end 322.788534 -249.96775)
		(width 0.14478)
		(layer "In6.Cu")
		(net "M_E_CPU0_SA_CB<7>")
	)
	(segment
		(start 325.697088 -249.96775)
		(end 324.188074 -249.96775)
		(width 0.0889)
		(layer "In6.Cu")
		(net "M_E_CPU0_SA_CB<7>")
	)
	(segment
		(start 322.788534 -249.96775)
		(end 321.965574 -249.14479)
		(width 0.14478)
		(layer "In6.Cu")
		(net "M_E_CPU0_SA_CB<7>")
	)
	(segment
		(start 276.281642 -243.660168)
		(end 276.118574 -243.4971)
		(width 0.14478)
		(layer "In6.Cu")
		(net "M_E_CPU0_SA_CB<7>")
	)
	(segment
		(start 275.168614 -244.21211)
		(end 275.005546 -244.049042)
		(width 0.14478)
		(layer "In6.Cu")
		(net "M_E_CPU0_SA_CB<7>")
	)
	(segment
		(start 274.842478 -242.95989)
		(end 274.6121 -242.95989)
		(width 0.14478)
		(layer "In6.Cu")
		(net "M_E_CPU0_SA_CB<7>")
	)
	(segment
		(start 275.398992 -244.21211)
		(end 275.168614 -244.21211)
		(width 0.14478)
		(layer "In6.Cu")
		(net "M_E_CPU0_SA_CB<7>")
	)
	(segment
		(start 311.666382 -249.14479)
		(end 307.881782 -245.36019)
		(width 0.14478)
		(layer "In6.Cu")
		(net "M_E_CPU0_SA_CB<7>")
	)
	(segment
		(start 330.581 -249.34418)
		(end 330.427076 -249.07875)
		(width 0.0889)
		(layer "In6.Cu")
		(net "M_E_CPU0_SA_CB<7>")
	)
	(segment
		(start 282.964128 -245.36019)
		(end 281.264106 -243.660168)
		(width 0.14478)
		(layer "In6.Cu")
		(net "M_E_CPU0_SA_CB<7>")
	)
	(arc
		(start 329.819762 -249.016774)
		(mid 329.636254 -248.97128)
		(end 329.454002 -249.0216)
		(width 0.0889)
		(layer "In6.Cu")
		(net "M_E_CPU0_SA_CB<7>")
	)
	(arc
		(start 327.94829 -249.0216)
		(mid 327.768085 -248.971283)
		(end 327.586086 -249.014742)
		(width 0.0889)
		(layer "In6.Cu")
		(net "M_E_CPU0_SA_CB<7>")
	)
	(arc
		(start 328.514202 -249.0216)
		(mid 328.231246 -249.097777)
		(end 327.94829 -249.0216)
		(width 0.0889)
		(layer "In6.Cu")
		(net "M_E_CPU0_SA_CB<7>")
	)
	(arc
		(start 330.331064 -249.05335)
		(mid 330.075856 -249.096827)
		(end 329.828144 -249.0216)
		(width 0.0889)
		(layer "In6.Cu")
		(net "M_E_CPU0_SA_CB<7>")
	)
	(arc
		(start 327.563988 -249.027696)
		(mid 327.285556 -249.097794)
		(end 327.008744 -249.0216)
		(width 0.0889)
		(layer "In6.Cu")
		(net "M_E_CPU0_SA_CB<7>")
	)
	(arc
		(start 329.454002 -249.0216)
		(mid 329.171046 -249.097777)
		(end 328.88809 -249.0216)
		(width 0.0889)
		(layer "In6.Cu")
		(net "M_E_CPU0_SA_CB<7>")
	)
	(arc
		(start 326.99706 -249.014742)
		(mid 326.814805 -248.971089)
		(end 326.634348 -249.0216)
		(width 0.0889)
		(layer "In6.Cu")
		(net "M_E_CPU0_SA_CB<7>")
	)
	(arc
		(start 328.88809 -249.0216)
		(mid 328.701146 -248.971345)
		(end 328.514202 -249.0216)
		(width 0.0889)
		(layer "In6.Cu")
		(net "M_E_CPU0_SA_CB<7>")
	)
	(segment
		(start 329.637898 -248.800112)
		(end 329.171046 -248.534174)
		(width 0.10668)
		(layer "F.Cu")
		(net "M_E_CPU0_SA_CB<6>")
	)
	(segment
		(start 285.59633 -243.038884)
		(end 285.59633 -242.123214)
		(width 0.14478)
		(layer "In6.Cu")
		(net "M_E_CPU0_SA_CB<6>")
	)
	(segment
		(start 290.572952 -242.466622)
		(end 290.572952 -242.123214)
		(width 0.14478)
		(layer "In6.Cu")
		(net "M_E_CPU0_SA_CB<6>")
	)
	(segment
		(start 285.989776 -243.201952)
		(end 285.759398 -243.201952)
		(width 0.14478)
		(layer "In6.Cu")
		(net "M_E_CPU0_SA_CB<6>")
	)
	(segment
		(start 323.951854 -248.800366)
		(end 322.907406 -248.800366)
		(width 0.14478)
		(layer "In6.Cu")
		(net "M_E_CPU0_SA_CB<6>")
	)
	(segment
		(start 290.966398 -242.62969)
		(end 290.73602 -242.62969)
		(width 0.14478)
		(layer "In6.Cu")
		(net "M_E_CPU0_SA_CB<6>")
	)
	(segment
		(start 290.73602 -242.62969)
		(end 290.572952 -242.466622)
		(width 0.14478)
		(layer "In6.Cu")
		(net "M_E_CPU0_SA_CB<6>")
	)
	(segment
		(start 290.572952 -242.123214)
		(end 290.409884 -241.960146)
		(width 0.14478)
		(layer "In6.Cu")
		(net "M_E_CPU0_SA_CB<6>")
	)
	(segment
		(start 289.296856 -241.960146)
		(end 286.315912 -241.960146)
		(width 0.14478)
		(layer "In6.Cu")
		(net "M_E_CPU0_SA_CB<6>")
	)
	(segment
		(start 322.907406 -248.800366)
		(end 322.34251 -248.23547)
		(width 0.14478)
		(layer "In6.Cu")
		(net "M_E_CPU0_SA_CB<6>")
	)
	(segment
		(start 286.152844 -243.038884)
		(end 285.989776 -243.201952)
		(width 0.14478)
		(layer "In6.Cu")
		(net "M_E_CPU0_SA_CB<6>")
	)
	(segment
		(start 322.34251 -248.23547)
		(end 312.20537 -248.23547)
		(width 0.14478)
		(layer "In6.Cu")
		(net "M_E_CPU0_SA_CB<6>")
	)
	(segment
		(start 327.488804 -248.21769)
		(end 327.47839 -248.211594)
		(width 0.0889)
		(layer "In6.Cu")
		(net "M_E_CPU0_SA_CB<6>")
	)
	(segment
		(start 289.459924 -242.466622)
		(end 289.459924 -242.123214)
		(width 0.14478)
		(layer "In6.Cu")
		(net "M_E_CPU0_SA_CB<6>")
	)
	(segment
		(start 326.176132 -248.204736)
		(end 326.164448 -248.211594)
		(width 0.0889)
		(layer "In6.Cu")
		(net "M_E_CPU0_SA_CB<6>")
	)
	(segment
		(start 290.179506 -241.960146)
		(end 290.016438 -242.123214)
		(width 0.14478)
		(layer "In6.Cu")
		(net "M_E_CPU0_SA_CB<6>")
	)
	(segment
		(start 329.171046 -248.534174)
		(end 329.017122 -248.268744)
		(width 0.0889)
		(layer "In6.Cu")
		(net "M_E_CPU0_SA_CB<6>")
	)
	(segment
		(start 286.315912 -241.960146)
		(end 286.152844 -242.123214)
		(width 0.14478)
		(layer "In6.Cu")
		(net "M_E_CPU0_SA_CB<6>")
	)
	(segment
		(start 325.575676 -248.800366)
		(end 323.951854 -248.800366)
		(width 0.0889)
		(layer "In6.Cu")
		(net "M_E_CPU0_SA_CB<6>")
	)
	(segment
		(start 312.20537 -248.23547)
		(end 307.629814 -243.659914)
		(width 0.14478)
		(layer "In6.Cu")
		(net "M_E_CPU0_SA_CB<6>")
	)
	(segment
		(start 326.164448 -248.211594)
		(end 325.575676 -248.800366)
		(width 0.0889)
		(layer "In6.Cu")
		(net "M_E_CPU0_SA_CB<6>")
	)
	(segment
		(start 307.629814 -243.659914)
		(end 294.327072 -243.659914)
		(width 0.14478)
		(layer "In6.Cu")
		(net "M_E_CPU0_SA_CB<6>")
	)
	(segment
		(start 273.51736 -241.960146)
		(end 273.092164 -241.53495)
		(width 0.14478)
		(layer "In6.Cu")
		(net "M_E_CPU0_SA_CB<6>")
	)
	(segment
		(start 286.152844 -242.123214)
		(end 286.152844 -243.038884)
		(width 0.14478)
		(layer "In6.Cu")
		(net "M_E_CPU0_SA_CB<6>")
	)
	(segment
		(start 290.016438 -242.466622)
		(end 289.85337 -242.62969)
		(width 0.14478)
		(layer "In6.Cu")
		(net "M_E_CPU0_SA_CB<6>")
	)
	(segment
		(start 329.017122 -248.268744)
		(end 328.92111 -248.243344)
		(width 0.0889)
		(layer "In6.Cu")
		(net "M_E_CPU0_SA_CB<6>")
	)
	(segment
		(start 289.622992 -242.62969)
		(end 289.459924 -242.466622)
		(width 0.14478)
		(layer "In6.Cu")
		(net "M_E_CPU0_SA_CB<6>")
	)
	(segment
		(start 290.409884 -241.960146)
		(end 290.179506 -241.960146)
		(width 0.14478)
		(layer "In6.Cu")
		(net "M_E_CPU0_SA_CB<6>")
	)
	(segment
		(start 327.104502 -248.211594)
		(end 327.094088 -248.21769)
		(width 0.0889)
		(layer "In6.Cu")
		(net "M_E_CPU0_SA_CB<6>")
	)
	(segment
		(start 291.129466 -242.123214)
		(end 291.129466 -242.466622)
		(width 0.14478)
		(layer "In6.Cu")
		(net "M_E_CPU0_SA_CB<6>")
	)
	(segment
		(start 285.59633 -242.123214)
		(end 285.433262 -241.960146)
		(width 0.14478)
		(layer "In6.Cu")
		(net "M_E_CPU0_SA_CB<6>")
	)
	(segment
		(start 292.627304 -241.960146)
		(end 291.292534 -241.960146)
		(width 0.14478)
		(layer "In6.Cu")
		(net "M_E_CPU0_SA_CB<6>")
	)
	(segment
		(start 285.759398 -243.201952)
		(end 285.59633 -243.038884)
		(width 0.14478)
		(layer "In6.Cu")
		(net "M_E_CPU0_SA_CB<6>")
	)
	(segment
		(start 328.41819 -248.211594)
		(end 328.409808 -248.206768)
		(width 0.0889)
		(layer "In6.Cu")
		(net "M_E_CPU0_SA_CB<6>")
	)
	(segment
		(start 285.433262 -241.960146)
		(end 273.51736 -241.960146)
		(width 0.14478)
		(layer "In6.Cu")
		(net "M_E_CPU0_SA_CB<6>")
	)
	(segment
		(start 289.85337 -242.62969)
		(end 289.622992 -242.62969)
		(width 0.14478)
		(layer "In6.Cu")
		(net "M_E_CPU0_SA_CB<6>")
	)
	(segment
		(start 294.327072 -243.659914)
		(end 292.627304 -241.960146)
		(width 0.14478)
		(layer "In6.Cu")
		(net "M_E_CPU0_SA_CB<6>")
	)
	(segment
		(start 290.016438 -242.123214)
		(end 290.016438 -242.466622)
		(width 0.14478)
		(layer "In6.Cu")
		(net "M_E_CPU0_SA_CB<6>")
	)
	(segment
		(start 289.459924 -242.123214)
		(end 289.296856 -241.960146)
		(width 0.14478)
		(layer "In6.Cu")
		(net "M_E_CPU0_SA_CB<6>")
	)
	(segment
		(start 291.129466 -242.466622)
		(end 290.966398 -242.62969)
		(width 0.14478)
		(layer "In6.Cu")
		(net "M_E_CPU0_SA_CB<6>")
	)
	(segment
		(start 291.292534 -241.960146)
		(end 291.129466 -242.123214)
		(width 0.14478)
		(layer "In6.Cu")
		(net "M_E_CPU0_SA_CB<6>")
	)
	(arc
		(start 328.044048 -248.211594)
		(mid 327.767235 -248.287737)
		(end 327.488804 -248.21769)
		(width 0.0889)
		(layer "In6.Cu")
		(net "M_E_CPU0_SA_CB<6>")
	)
	(arc
		(start 327.094088 -248.21769)
		(mid 326.815402 -248.28791)
		(end 326.538336 -248.211594)
		(width 0.0889)
		(layer "In6.Cu")
		(net "M_E_CPU0_SA_CB<6>")
	)
	(arc
		(start 326.538336 -248.211594)
		(mid 326.358131 -248.161277)
		(end 326.176132 -248.204736)
		(width 0.0889)
		(layer "In6.Cu")
		(net "M_E_CPU0_SA_CB<6>")
	)
	(arc
		(start 328.92111 -248.243344)
		(mid 328.665902 -248.286821)
		(end 328.41819 -248.211594)
		(width 0.0889)
		(layer "In6.Cu")
		(net "M_E_CPU0_SA_CB<6>")
	)
	(arc
		(start 327.47839 -248.211594)
		(mid 327.291446 -248.161339)
		(end 327.104502 -248.211594)
		(width 0.0889)
		(layer "In6.Cu")
		(net "M_E_CPU0_SA_CB<6>")
	)
	(arc
		(start 328.409808 -248.206768)
		(mid 328.2263 -248.161274)
		(end 328.044048 -248.211594)
		(width 0.0889)
		(layer "In6.Cu")
		(net "M_E_CPU0_SA_CB<6>")
	)
	(segment
		(start 330.577952 -248.800112)
		(end 330.1111 -248.534174)
		(width 0.10668)
		(layer "F.Cu")
		(net "M_E_CPU0_SA_CB<5>")
	)
	(segment
		(start 290.558474 -244.346984)
		(end 290.558474 -243.623338)
		(width 0.14478)
		(layer "In6.Cu")
		(net "M_E_CPU0_SA_CB<5>")
	)
	(segment
		(start 330.265024 -248.799604)
		(end 330.242672 -248.882916)
		(width 0.0889)
		(layer "In6.Cu")
		(net "M_E_CPU0_SA_CB<5>")
	)
	(segment
		(start 289.838892 -244.510052)
		(end 289.608514 -244.510052)
		(width 0.14478)
		(layer "In6.Cu")
		(net "M_E_CPU0_SA_CB<5>")
	)
	(segment
		(start 326.53859 -248.856754)
		(end 325.842122 -249.25401)
		(width 0.0889)
		(layer "In6.Cu")
		(net "M_E_CPU0_SA_CB<5>")
	)
	(segment
		(start 289.282378 -243.46027)
		(end 289.052 -243.46027)
		(width 0.14478)
		(layer "In6.Cu")
		(net "M_E_CPU0_SA_CB<5>")
	)
	(segment
		(start 327.488804 -248.850658)
		(end 327.47839 -248.856754)
		(width 0.0889)
		(layer "In6.Cu")
		(net "M_E_CPU0_SA_CB<5>")
	)
	(segment
		(start 327.104756 -248.856754)
		(end 327.094342 -248.850658)
		(width 0.0889)
		(layer "In6.Cu")
		(net "M_E_CPU0_SA_CB<5>")
	)
	(segment
		(start 291.508434 -243.46027)
		(end 291.278056 -243.46027)
		(width 0.14478)
		(layer "In6.Cu")
		(net "M_E_CPU0_SA_CB<5>")
	)
	(segment
		(start 291.83457 -244.510052)
		(end 291.671502 -244.346984)
		(width 0.14478)
		(layer "In6.Cu")
		(net "M_E_CPU0_SA_CB<5>")
	)
	(segment
		(start 290.721542 -244.510052)
		(end 290.558474 -244.346984)
		(width 0.14478)
		(layer "In6.Cu")
		(net "M_E_CPU0_SA_CB<5>")
	)
	(segment
		(start 307.740812 -244.510052)
		(end 291.83457 -244.510052)
		(width 0.14478)
		(layer "In6.Cu")
		(net "M_E_CPU0_SA_CB<5>")
	)
	(segment
		(start 324.436994 -249.31497)
		(end 323.880734 -249.31497)
		(width 0.0889)
		(layer "In6.Cu")
		(net "M_E_CPU0_SA_CB<5>")
	)
	(segment
		(start 325.842122 -249.25401)
		(end 324.497954 -249.25401)
		(width 0.0889)
		(layer "In6.Cu")
		(net "M_E_CPU0_SA_CB<5>")
	)
	(segment
		(start 286.83204 -244.510052)
		(end 283.74975 -244.510052)
		(width 0.14478)
		(layer "In6.Cu")
		(net "M_E_CPU0_SA_CB<5>")
	)
	(segment
		(start 322.778882 -249.31497)
		(end 322.154042 -248.69013)
		(width 0.14478)
		(layer "In6.Cu")
		(net "M_E_CPU0_SA_CB<5>")
	)
	(segment
		(start 327.47839 -248.856754)
		(end 327.470008 -248.86158)
		(width 0.0889)
		(layer "In6.Cu")
		(net "M_E_CPU0_SA_CB<5>")
	)
	(segment
		(start 289.608514 -244.510052)
		(end 289.445446 -244.346984)
		(width 0.14478)
		(layer "In6.Cu")
		(net "M_E_CPU0_SA_CB<5>")
	)
	(segment
		(start 324.497954 -249.25401)
		(end 324.436994 -249.31497)
		(width 0.0889)
		(layer "In6.Cu")
		(net "M_E_CPU0_SA_CB<5>")
	)
	(segment
		(start 289.445446 -243.623338)
		(end 289.282378 -243.46027)
		(width 0.14478)
		(layer "In6.Cu")
		(net "M_E_CPU0_SA_CB<5>")
	)
	(segment
		(start 291.278056 -243.46027)
		(end 291.114988 -243.623338)
		(width 0.14478)
		(layer "In6.Cu")
		(net "M_E_CPU0_SA_CB<5>")
	)
	(segment
		(start 291.671502 -243.623338)
		(end 291.508434 -243.46027)
		(width 0.14478)
		(layer "In6.Cu")
		(net "M_E_CPU0_SA_CB<5>")
	)
	(segment
		(start 287.388554 -243.328952)
		(end 287.158176 -243.328952)
		(width 0.14478)
		(layer "In6.Cu")
		(net "M_E_CPU0_SA_CB<5>")
	)
	(segment
		(start 287.158176 -243.328952)
		(end 286.995108 -243.49202)
		(width 0.14478)
		(layer "In6.Cu")
		(net "M_E_CPU0_SA_CB<5>")
	)
	(segment
		(start 290.395406 -243.46027)
		(end 290.165028 -243.46027)
		(width 0.14478)
		(layer "In6.Cu")
		(net "M_E_CPU0_SA_CB<5>")
	)
	(segment
		(start 290.00196 -244.346984)
		(end 289.838892 -244.510052)
		(width 0.14478)
		(layer "In6.Cu")
		(net "M_E_CPU0_SA_CB<5>")
	)
	(segment
		(start 282.049728 -242.81003)
		(end 277.617174 -242.81003)
		(width 0.14478)
		(layer "In6.Cu")
		(net "M_E_CPU0_SA_CB<5>")
	)
	(segment
		(start 290.95192 -244.510052)
		(end 290.721542 -244.510052)
		(width 0.14478)
		(layer "In6.Cu")
		(net "M_E_CPU0_SA_CB<5>")
	)
	(segment
		(start 291.114988 -243.623338)
		(end 291.114988 -244.346984)
		(width 0.14478)
		(layer "In6.Cu")
		(net "M_E_CPU0_SA_CB<5>")
	)
	(segment
		(start 289.445446 -244.346984)
		(end 289.445446 -243.623338)
		(width 0.14478)
		(layer "In6.Cu")
		(net "M_E_CPU0_SA_CB<5>")
	)
	(segment
		(start 328.41819 -248.856754)
		(end 328.409808 -248.86158)
		(width 0.0889)
		(layer "In6.Cu")
		(net "M_E_CPU0_SA_CB<5>")
	)
	(segment
		(start 330.1111 -248.534174)
		(end 330.265024 -248.799604)
		(width 0.0889)
		(layer "In6.Cu")
		(net "M_E_CPU0_SA_CB<5>")
	)
	(segment
		(start 323.880734 -249.31497)
		(end 322.778882 -249.31497)
		(width 0.14478)
		(layer "In6.Cu")
		(net "M_E_CPU0_SA_CB<5>")
	)
	(segment
		(start 287.551622 -244.346984)
		(end 287.551622 -243.49202)
		(width 0.14478)
		(layer "In6.Cu")
		(net "M_E_CPU0_SA_CB<5>")
	)
	(segment
		(start 288.888932 -243.623338)
		(end 288.888932 -244.346984)
		(width 0.14478)
		(layer "In6.Cu")
		(net "M_E_CPU0_SA_CB<5>")
	)
	(segment
		(start 322.154042 -248.69013)
		(end 311.92089 -248.69013)
		(width 0.14478)
		(layer "In6.Cu")
		(net "M_E_CPU0_SA_CB<5>")
	)
	(segment
		(start 289.052 -243.46027)
		(end 288.888932 -243.623338)
		(width 0.14478)
		(layer "In6.Cu")
		(net "M_E_CPU0_SA_CB<5>")
	)
	(segment
		(start 291.114988 -244.346984)
		(end 290.95192 -244.510052)
		(width 0.14478)
		(layer "In6.Cu")
		(net "M_E_CPU0_SA_CB<5>")
	)
	(segment
		(start 277.617174 -242.81003)
		(end 277.192232 -242.385088)
		(width 0.14478)
		(layer "In6.Cu")
		(net "M_E_CPU0_SA_CB<5>")
	)
	(segment
		(start 290.558474 -243.623338)
		(end 290.395406 -243.46027)
		(width 0.14478)
		(layer "In6.Cu")
		(net "M_E_CPU0_SA_CB<5>")
	)
	(segment
		(start 287.71469 -244.510052)
		(end 287.551622 -244.346984)
		(width 0.14478)
		(layer "In6.Cu")
		(net "M_E_CPU0_SA_CB<5>")
	)
	(segment
		(start 286.995108 -243.49202)
		(end 286.995108 -244.346984)
		(width 0.14478)
		(layer "In6.Cu")
		(net "M_E_CPU0_SA_CB<5>")
	)
	(segment
		(start 283.74975 -244.510052)
		(end 282.049728 -242.81003)
		(width 0.14478)
		(layer "In6.Cu")
		(net "M_E_CPU0_SA_CB<5>")
	)
	(segment
		(start 291.671502 -244.346984)
		(end 291.671502 -243.623338)
		(width 0.14478)
		(layer "In6.Cu")
		(net "M_E_CPU0_SA_CB<5>")
	)
	(segment
		(start 311.92089 -248.69013)
		(end 307.740812 -244.510052)
		(width 0.14478)
		(layer "In6.Cu")
		(net "M_E_CPU0_SA_CB<5>")
	)
	(segment
		(start 328.992484 -248.86158)
		(end 328.984102 -248.856754)
		(width 0.0889)
		(layer "In6.Cu")
		(net "M_E_CPU0_SA_CB<5>")
	)
	(segment
		(start 288.888932 -244.346984)
		(end 288.725864 -244.510052)
		(width 0.14478)
		(layer "In6.Cu")
		(net "M_E_CPU0_SA_CB<5>")
	)
	(segment
		(start 290.165028 -243.46027)
		(end 290.00196 -243.623338)
		(width 0.14478)
		(layer "In6.Cu")
		(net "M_E_CPU0_SA_CB<5>")
	)
	(segment
		(start 287.551622 -243.49202)
		(end 287.388554 -243.328952)
		(width 0.14478)
		(layer "In6.Cu")
		(net "M_E_CPU0_SA_CB<5>")
	)
	(segment
		(start 290.00196 -243.623338)
		(end 290.00196 -244.346984)
		(width 0.14478)
		(layer "In6.Cu")
		(net "M_E_CPU0_SA_CB<5>")
	)
	(segment
		(start 286.995108 -244.346984)
		(end 286.83204 -244.510052)
		(width 0.14478)
		(layer "In6.Cu")
		(net "M_E_CPU0_SA_CB<5>")
	)
	(segment
		(start 288.725864 -244.510052)
		(end 287.71469 -244.510052)
		(width 0.14478)
		(layer "In6.Cu")
		(net "M_E_CPU0_SA_CB<5>")
	)
	(arc
		(start 327.470008 -248.86158)
		(mid 327.286754 -248.906953)
		(end 327.104756 -248.856754)
		(width 0.0889)
		(layer "In6.Cu")
		(net "M_E_CPU0_SA_CB<5>")
	)
	(arc
		(start 329.358244 -248.856754)
		(mid 329.175993 -248.907104)
		(end 328.992484 -248.86158)
		(width 0.0889)
		(layer "In6.Cu")
		(net "M_E_CPU0_SA_CB<5>")
	)
	(arc
		(start 328.044048 -248.856754)
		(mid 327.767235 -248.780611)
		(end 327.488804 -248.850658)
		(width 0.0889)
		(layer "In6.Cu")
		(net "M_E_CPU0_SA_CB<5>")
	)
	(arc
		(start 328.984102 -248.856754)
		(mid 328.701146 -248.780577)
		(end 328.41819 -248.856754)
		(width 0.0889)
		(layer "In6.Cu")
		(net "M_E_CPU0_SA_CB<5>")
	)
	(arc
		(start 329.924156 -248.856754)
		(mid 329.6412 -248.780577)
		(end 329.358244 -248.856754)
		(width 0.0889)
		(layer "In6.Cu")
		(net "M_E_CPU0_SA_CB<5>")
	)
	(arc
		(start 327.094342 -248.850658)
		(mid 326.815656 -248.780438)
		(end 326.53859 -248.856754)
		(width 0.0889)
		(layer "In6.Cu")
		(net "M_E_CPU0_SA_CB<5>")
	)
	(arc
		(start 328.409808 -248.86158)
		(mid 328.2263 -248.907074)
		(end 328.044048 -248.856754)
		(width 0.0889)
		(layer "In6.Cu")
		(net "M_E_CPU0_SA_CB<5>")
	)
	(arc
		(start 330.242672 -248.882916)
		(mid 330.080483 -248.905651)
		(end 329.924156 -248.856754)
		(width 0.0889)
		(layer "In6.Cu")
		(net "M_E_CPU0_SA_CB<5>")
	)
	(segment
		(start 329.167998 -247.990106)
		(end 328.701146 -247.724168)
		(width 0.10668)
		(layer "F.Cu")
		(net "M_E_CPU0_SA_CB<4>")
	)
	(segment
		(start 297.70832 -242.042442)
		(end 297.70832 -241.273076)
		(width 0.14478)
		(layer "In6.Cu")
		(net "M_E_CPU0_SA_CB<4>")
	)
	(segment
		(start 294.303196 -241.273076)
		(end 294.14978 -241.11966)
		(width 0.14478)
		(layer "In6.Cu")
		(net "M_E_CPU0_SA_CB<4>")
	)
	(segment
		(start 327.58253 -248.051574)
		(end 327.574148 -248.046748)
		(width 0.0889)
		(layer "In6.Cu")
		(net "M_E_CPU0_SA_CB<4>")
	)
	(segment
		(start 328.701146 -247.724168)
		(end 328.85507 -247.989598)
		(width 0.0889)
		(layer "In6.Cu")
		(net "M_E_CPU0_SA_CB<4>")
	)
	(segment
		(start 299.377862 -242.042442)
		(end 299.214794 -242.20551)
		(width 0.14478)
		(layer "In6.Cu")
		(net "M_E_CPU0_SA_CB<4>")
	)
	(segment
		(start 312.89371 -247.78081)
		(end 307.92293 -242.81003)
		(width 0.14478)
		(layer "In6.Cu")
		(net "M_E_CPU0_SA_CB<4>")
	)
	(segment
		(start 294.85971 -241.273076)
		(end 294.85971 -242.459764)
		(width 0.14478)
		(layer "In6.Cu")
		(net "M_E_CPU0_SA_CB<4>")
	)
	(segment
		(start 296.595292 -241.273076)
		(end 296.441876 -241.11966)
		(width 0.14478)
		(layer "In6.Cu")
		(net "M_E_CPU0_SA_CB<4>")
	)
	(segment
		(start 299.377862 -241.273076)
		(end 299.377862 -242.042442)
		(width 0.14478)
		(layer "In6.Cu")
		(net "M_E_CPU0_SA_CB<4>")
	)
	(segment
		(start 295.013126 -241.11966)
		(end 294.85971 -241.273076)
		(width 0.14478)
		(layer "In6.Cu")
		(net "M_E_CPU0_SA_CB<4>")
	)
	(segment
		(start 307.92293 -242.81003)
		(end 304.328576 -242.81003)
		(width 0.14478)
		(layer "In6.Cu")
		(net "M_E_CPU0_SA_CB<4>")
	)
	(segment
		(start 327.574148 -248.046748)
		(end 327.563734 -248.040652)
		(width 0.0889)
		(layer "In6.Cu")
		(net "M_E_CPU0_SA_CB<4>")
	)
	(segment
		(start 327.00849 -248.046748)
		(end 327.000108 -248.051574)
		(width 0.0889)
		(layer "In6.Cu")
		(net "M_E_CPU0_SA_CB<4>")
	)
	(segment
		(start 299.214794 -242.20551)
		(end 298.984416 -242.20551)
		(width 0.14478)
		(layer "In6.Cu")
		(net "M_E_CPU0_SA_CB<4>")
	)
	(segment
		(start 298.65828 -241.110008)
		(end 298.427902 -241.110008)
		(width 0.14478)
		(layer "In6.Cu")
		(net "M_E_CPU0_SA_CB<4>")
	)
	(segment
		(start 323.969634 -248.345706)
		(end 323.095874 -248.345706)
		(width 0.14478)
		(layer "In6.Cu")
		(net "M_E_CPU0_SA_CB<4>")
	)
	(segment
		(start 294.696642 -242.622832)
		(end 294.466264 -242.622832)
		(width 0.14478)
		(layer "In6.Cu")
		(net "M_E_CPU0_SA_CB<4>")
	)
	(segment
		(start 302.628554 -241.110008)
		(end 299.54093 -241.110008)
		(width 0.14478)
		(layer "In6.Cu")
		(net "M_E_CPU0_SA_CB<4>")
	)
	(segment
		(start 298.101766 -242.20551)
		(end 297.871388 -242.20551)
		(width 0.14478)
		(layer "In6.Cu")
		(net "M_E_CPU0_SA_CB<4>")
	)
	(segment
		(start 297.151806 -242.042442)
		(end 296.988738 -242.20551)
		(width 0.14478)
		(layer "In6.Cu")
		(net "M_E_CPU0_SA_CB<4>")
	)
	(segment
		(start 296.75836 -242.20551)
		(end 296.595292 -242.042442)
		(width 0.14478)
		(layer "In6.Cu")
		(net "M_E_CPU0_SA_CB<4>")
	)
	(segment
		(start 298.984416 -242.20551)
		(end 298.821348 -242.042442)
		(width 0.14478)
		(layer "In6.Cu")
		(net "M_E_CPU0_SA_CB<4>")
	)
	(segment
		(start 297.545252 -241.110008)
		(end 297.314874 -241.110008)
		(width 0.14478)
		(layer "In6.Cu")
		(net "M_E_CPU0_SA_CB<4>")
	)
	(segment
		(start 298.821348 -241.273076)
		(end 298.65828 -241.110008)
		(width 0.14478)
		(layer "In6.Cu")
		(net "M_E_CPU0_SA_CB<4>")
	)
	(segment
		(start 297.871388 -242.20551)
		(end 297.70832 -242.042442)
		(width 0.14478)
		(layer "In6.Cu")
		(net "M_E_CPU0_SA_CB<4>")
	)
	(segment
		(start 298.821348 -242.042442)
		(end 298.821348 -241.273076)
		(width 0.14478)
		(layer "In6.Cu")
		(net "M_E_CPU0_SA_CB<4>")
	)
	(segment
		(start 299.54093 -241.110008)
		(end 299.377862 -241.273076)
		(width 0.14478)
		(layer "In6.Cu")
		(net "M_E_CPU0_SA_CB<4>")
	)
	(segment
		(start 296.441876 -241.11966)
		(end 295.013126 -241.11966)
		(width 0.14478)
		(layer "In6.Cu")
		(net "M_E_CPU0_SA_CB<4>")
	)
	(segment
		(start 297.70832 -241.273076)
		(end 297.545252 -241.110008)
		(width 0.14478)
		(layer "In6.Cu")
		(net "M_E_CPU0_SA_CB<4>")
	)
	(segment
		(start 326.083168 -248.038112)
		(end 325.643748 -248.295668)
		(width 0.0889)
		(layer "In6.Cu")
		(net "M_E_CPU0_SA_CB<4>")
	)
	(segment
		(start 325.599044 -248.340372)
		(end 323.974968 -248.340372)
		(width 0.0889)
		(layer "In6.Cu")
		(net "M_E_CPU0_SA_CB<4>")
	)
	(segment
		(start 277.626826 -241.11966)
		(end 277.192232 -240.685066)
		(width 0.14478)
		(layer "In6.Cu")
		(net "M_E_CPU0_SA_CB<4>")
	)
	(segment
		(start 298.427902 -241.110008)
		(end 298.264834 -241.273076)
		(width 0.14478)
		(layer "In6.Cu")
		(net "M_E_CPU0_SA_CB<4>")
	)
	(segment
		(start 298.264834 -241.273076)
		(end 298.264834 -242.042442)
		(width 0.14478)
		(layer "In6.Cu")
		(net "M_E_CPU0_SA_CB<4>")
	)
	(segment
		(start 323.095874 -248.345706)
		(end 322.530978 -247.78081)
		(width 0.14478)
		(layer "In6.Cu")
		(net "M_E_CPU0_SA_CB<4>")
	)
	(segment
		(start 294.14978 -241.11966)
		(end 277.626826 -241.11966)
		(width 0.14478)
		(layer "In6.Cu")
		(net "M_E_CPU0_SA_CB<4>")
	)
	(segment
		(start 322.530978 -247.78081)
		(end 312.89371 -247.78081)
		(width 0.14478)
		(layer "In6.Cu")
		(net "M_E_CPU0_SA_CB<4>")
	)
	(segment
		(start 297.314874 -241.110008)
		(end 297.151806 -241.273076)
		(width 0.14478)
		(layer "In6.Cu")
		(net "M_E_CPU0_SA_CB<4>")
	)
	(segment
		(start 296.595292 -242.042442)
		(end 296.595292 -241.273076)
		(width 0.14478)
		(layer "In6.Cu")
		(net "M_E_CPU0_SA_CB<4>")
	)
	(segment
		(start 297.151806 -241.273076)
		(end 297.151806 -242.042442)
		(width 0.14478)
		(layer "In6.Cu")
		(net "M_E_CPU0_SA_CB<4>")
	)
	(segment
		(start 325.643748 -248.295668)
		(end 325.599044 -248.340372)
		(width 0.0889)
		(layer "In6.Cu")
		(net "M_E_CPU0_SA_CB<4>")
	)
	(segment
		(start 328.85507 -247.989598)
		(end 328.832718 -248.07291)
		(width 0.0889)
		(layer "In6.Cu")
		(net "M_E_CPU0_SA_CB<4>")
	)
	(segment
		(start 294.85971 -242.459764)
		(end 294.696642 -242.622832)
		(width 0.14478)
		(layer "In6.Cu")
		(net "M_E_CPU0_SA_CB<4>")
	)
	(segment
		(start 294.466264 -242.622832)
		(end 294.303196 -242.459764)
		(width 0.14478)
		(layer "In6.Cu")
		(net "M_E_CPU0_SA_CB<4>")
	)
	(segment
		(start 298.264834 -242.042442)
		(end 298.101766 -242.20551)
		(width 0.14478)
		(layer "In6.Cu")
		(net "M_E_CPU0_SA_CB<4>")
	)
	(segment
		(start 304.328576 -242.81003)
		(end 302.628554 -241.110008)
		(width 0.14478)
		(layer "In6.Cu")
		(net "M_E_CPU0_SA_CB<4>")
	)
	(segment
		(start 323.974968 -248.340372)
		(end 323.969634 -248.345706)
		(width 0.0889)
		(layer "In6.Cu")
		(net "M_E_CPU0_SA_CB<4>")
	)
	(segment
		(start 296.988738 -242.20551)
		(end 296.75836 -242.20551)
		(width 0.14478)
		(layer "In6.Cu")
		(net "M_E_CPU0_SA_CB<4>")
	)
	(segment
		(start 294.303196 -242.459764)
		(end 294.303196 -241.273076)
		(width 0.14478)
		(layer "In6.Cu")
		(net "M_E_CPU0_SA_CB<4>")
	)
	(arc
		(start 327.94829 -248.046748)
		(mid 327.766039 -248.097098)
		(end 327.58253 -248.051574)
		(width 0.0889)
		(layer "In6.Cu")
		(net "M_E_CPU0_SA_CB<4>")
	)
	(arc
		(start 327.563734 -248.040652)
		(mid 327.285302 -247.970554)
		(end 327.00849 -248.046748)
		(width 0.0889)
		(layer "In6.Cu")
		(net "M_E_CPU0_SA_CB<4>")
	)
	(arc
		(start 327.000108 -248.051574)
		(mid 326.8166 -248.097068)
		(end 326.634348 -248.046748)
		(width 0.0889)
		(layer "In6.Cu")
		(net "M_E_CPU0_SA_CB<4>")
	)
	(arc
		(start 328.832718 -248.07291)
		(mid 328.670529 -248.095645)
		(end 328.514202 -248.046748)
		(width 0.0889)
		(layer "In6.Cu")
		(net "M_E_CPU0_SA_CB<4>")
	)
	(arc
		(start 326.634348 -248.046748)
		(mid 326.359896 -247.970512)
		(end 326.083168 -248.038112)
		(width 0.0889)
		(layer "In6.Cu")
		(net "M_E_CPU0_SA_CB<4>")
	)
	(arc
		(start 328.514202 -248.046748)
		(mid 328.231246 -247.970571)
		(end 327.94829 -248.046748)
		(width 0.0889)
		(layer "In6.Cu")
		(net "M_E_CPU0_SA_CB<4>")
	)
	(segment
		(start 331.047852 -246.370094)
		(end 330.581 -246.104156)
		(width 0.10668)
		(layer "F.Cu")
		(net "M_E_CPU0_SA_CB<3>")
	)
	(segment
		(start 327.008744 -245.781576)
		(end 326.99706 -245.774718)
		(width 0.0889)
		(layer "In6.Cu")
		(net "M_E_CPU0_SA_CB<3>")
	)
	(segment
		(start 283.01315 -236.850428)
		(end 282.163266 -237.700312)
		(width 0.14478)
		(layer "In6.Cu")
		(net "M_E_CPU0_SA_CB<3>")
	)
	(segment
		(start 294.492934 -237.700312)
		(end 293.64305 -236.850428)
		(width 0.14478)
		(layer "In6.Cu")
		(net "M_E_CPU0_SA_CB<3>")
	)
	(segment
		(start 301.646082 -237.30966)
		(end 301.18685 -236.850428)
		(width 0.14478)
		(layer "In6.Cu")
		(net "M_E_CPU0_SA_CB<3>")
	)
	(segment
		(start 308.367938 -238.479838)
		(end 306.51577 -236.62767)
		(width 0.14478)
		(layer "In6.Cu")
		(net "M_E_CPU0_SA_CB<3>")
	)
	(segment
		(start 323.573394 -245.44147)
		(end 315.02223 -245.44147)
		(width 0.14478)
		(layer "In6.Cu")
		(net "M_E_CPU0_SA_CB<3>")
	)
	(segment
		(start 293.64305 -236.850428)
		(end 290.610544 -236.850428)
		(width 0.14478)
		(layer "In6.Cu")
		(net "M_E_CPU0_SA_CB<3>")
	)
	(segment
		(start 323.939154 -245.80723)
		(end 323.573394 -245.44147)
		(width 0.14478)
		(layer "In6.Cu")
		(net "M_E_CPU0_SA_CB<3>")
	)
	(segment
		(start 274.094956 -237.700312)
		(end 273.092164 -237.285022)
		(width 0.14478)
		(layer "In6.Cu")
		(net "M_E_CPU0_SA_CB<3>")
	)
	(segment
		(start 315.02223 -245.44147)
		(end 308.367938 -238.787178)
		(width 0.14478)
		(layer "In6.Cu")
		(net "M_E_CPU0_SA_CB<3>")
	)
	(segment
		(start 289.76066 -237.700312)
		(end 286.8041 -237.700312)
		(width 0.14478)
		(layer "In6.Cu")
		(net "M_E_CPU0_SA_CB<3>")
	)
	(segment
		(start 323.996304 -245.86438)
		(end 323.939154 -245.80723)
		(width 0.0889)
		(layer "In6.Cu")
		(net "M_E_CPU0_SA_CB<3>")
	)
	(segment
		(start 298.18203 -236.850428)
		(end 297.332146 -237.700312)
		(width 0.14478)
		(layer "In6.Cu")
		(net "M_E_CPU0_SA_CB<3>")
	)
	(segment
		(start 286.8041 -237.700312)
		(end 285.954216 -236.850428)
		(width 0.14478)
		(layer "In6.Cu")
		(net "M_E_CPU0_SA_CB<3>")
	)
	(segment
		(start 290.610544 -236.850428)
		(end 289.76066 -237.700312)
		(width 0.14478)
		(layer "In6.Cu")
		(net "M_E_CPU0_SA_CB<3>")
	)
	(segment
		(start 308.367938 -238.787178)
		(end 308.367938 -238.479838)
		(width 0.14478)
		(layer "In6.Cu")
		(net "M_E_CPU0_SA_CB<3>")
	)
	(segment
		(start 282.163266 -237.700312)
		(end 274.094956 -237.700312)
		(width 0.14478)
		(layer "In6.Cu")
		(net "M_E_CPU0_SA_CB<3>")
	)
	(segment
		(start 305.266598 -237.30966)
		(end 301.646082 -237.30966)
		(width 0.14478)
		(layer "In6.Cu")
		(net "M_E_CPU0_SA_CB<3>")
	)
	(segment
		(start 329.828144 -245.781576)
		(end 329.819762 -245.77675)
		(width 0.0889)
		(layer "In6.Cu")
		(net "M_E_CPU0_SA_CB<3>")
	)
	(segment
		(start 326.327008 -245.86438)
		(end 323.996304 -245.86438)
		(width 0.0889)
		(layer "In6.Cu")
		(net "M_E_CPU0_SA_CB<3>")
	)
	(segment
		(start 330.581 -246.104156)
		(end 330.427076 -245.838726)
		(width 0.0889)
		(layer "In6.Cu")
		(net "M_E_CPU0_SA_CB<3>")
	)
	(segment
		(start 327.574402 -245.781576)
		(end 327.563988 -245.787672)
		(width 0.0889)
		(layer "In6.Cu")
		(net "M_E_CPU0_SA_CB<3>")
	)
	(segment
		(start 285.954216 -236.850428)
		(end 283.01315 -236.850428)
		(width 0.14478)
		(layer "In6.Cu")
		(net "M_E_CPU0_SA_CB<3>")
	)
	(segment
		(start 306.51577 -236.62767)
		(end 305.948588 -236.62767)
		(width 0.14478)
		(layer "In6.Cu")
		(net "M_E_CPU0_SA_CB<3>")
	)
	(segment
		(start 327.586086 -245.774718)
		(end 327.574402 -245.781576)
		(width 0.0889)
		(layer "In6.Cu")
		(net "M_E_CPU0_SA_CB<3>")
	)
	(segment
		(start 330.427076 -245.838726)
		(end 330.331064 -245.813326)
		(width 0.0889)
		(layer "In6.Cu")
		(net "M_E_CPU0_SA_CB<3>")
	)
	(segment
		(start 301.18685 -236.850428)
		(end 298.18203 -236.850428)
		(width 0.14478)
		(layer "In6.Cu")
		(net "M_E_CPU0_SA_CB<3>")
	)
	(segment
		(start 305.948588 -236.62767)
		(end 305.266598 -237.30966)
		(width 0.14478)
		(layer "In6.Cu")
		(net "M_E_CPU0_SA_CB<3>")
	)
	(segment
		(start 297.332146 -237.700312)
		(end 294.492934 -237.700312)
		(width 0.14478)
		(layer "In6.Cu")
		(net "M_E_CPU0_SA_CB<3>")
	)
	(arc
		(start 329.454002 -245.781576)
		(mid 329.171046 -245.857753)
		(end 328.88809 -245.781576)
		(width 0.0889)
		(layer "In6.Cu")
		(net "M_E_CPU0_SA_CB<3>")
	)
	(arc
		(start 327.563988 -245.787672)
		(mid 327.285556 -245.85777)
		(end 327.008744 -245.781576)
		(width 0.0889)
		(layer "In6.Cu")
		(net "M_E_CPU0_SA_CB<3>")
	)
	(arc
		(start 327.94829 -245.781576)
		(mid 327.768085 -245.731259)
		(end 327.586086 -245.774718)
		(width 0.0889)
		(layer "In6.Cu")
		(net "M_E_CPU0_SA_CB<3>")
	)
	(arc
		(start 326.99706 -245.774718)
		(mid 326.814805 -245.731065)
		(end 326.634348 -245.781576)
		(width 0.0889)
		(layer "In6.Cu")
		(net "M_E_CPU0_SA_CB<3>")
	)
	(arc
		(start 329.819762 -245.77675)
		(mid 329.636254 -245.731256)
		(end 329.454002 -245.781576)
		(width 0.0889)
		(layer "In6.Cu")
		(net "M_E_CPU0_SA_CB<3>")
	)
	(arc
		(start 330.331064 -245.813326)
		(mid 330.075856 -245.856803)
		(end 329.828144 -245.781576)
		(width 0.0889)
		(layer "In6.Cu")
		(net "M_E_CPU0_SA_CB<3>")
	)
	(arc
		(start 328.514202 -245.781576)
		(mid 328.231246 -245.857753)
		(end 327.94829 -245.781576)
		(width 0.0889)
		(layer "In6.Cu")
		(net "M_E_CPU0_SA_CB<3>")
	)
	(arc
		(start 328.88809 -245.781576)
		(mid 328.701146 -245.731321)
		(end 328.514202 -245.781576)
		(width 0.0889)
		(layer "In6.Cu")
		(net "M_E_CPU0_SA_CB<3>")
	)
	(arc
		(start 326.634348 -245.781576)
		(mid 326.486151 -245.84328)
		(end 326.327008 -245.86438)
		(width 0.0889)
		(layer "In6.Cu")
		(net "M_E_CPU0_SA_CB<3>")
	)
	(segment
		(start 329.637898 -245.560088)
		(end 329.171046 -245.29415)
		(width 0.10668)
		(layer "F.Cu")
		(net "M_E_CPU0_SA_CB<2>")
	)
	(segment
		(start 305.716178 -235.160058)
		(end 304.86604 -236.010196)
		(width 0.14478)
		(layer "In6.Cu")
		(net "M_E_CPU0_SA_CB<2>")
	)
	(segment
		(start 329.017122 -245.02872)
		(end 328.92111 -245.00332)
		(width 0.0889)
		(layer "In6.Cu")
		(net "M_E_CPU0_SA_CB<2>")
	)
	(segment
		(start 289.750754 -236.010196)
		(end 286.814006 -236.010196)
		(width 0.14478)
		(layer "In6.Cu")
		(net "M_E_CPU0_SA_CB<2>")
	)
	(segment
		(start 308.199282 -235.588556)
		(end 307.770784 -235.160058)
		(width 0.14478)
		(layer "In6.Cu")
		(net "M_E_CPU0_SA_CB<2>")
	)
	(segment
		(start 282.15336 -236.010196)
		(end 274.118832 -236.010196)
		(width 0.14478)
		(layer "In6.Cu")
		(net "M_E_CPU0_SA_CB<2>")
	)
	(segment
		(start 325.107554 -245.23319)
		(end 324.721474 -245.23319)
		(width 0.0889)
		(layer "In6.Cu")
		(net "M_E_CPU0_SA_CB<2>")
	)
	(segment
		(start 327.488804 -244.977666)
		(end 327.47839 -244.97157)
		(width 0.0889)
		(layer "In6.Cu")
		(net "M_E_CPU0_SA_CB<2>")
	)
	(segment
		(start 286.814006 -236.010196)
		(end 285.963868 -235.160058)
		(width 0.14478)
		(layer "In6.Cu")
		(net "M_E_CPU0_SA_CB<2>")
	)
	(segment
		(start 298.172378 -235.160058)
		(end 297.32224 -236.010196)
		(width 0.14478)
		(layer "In6.Cu")
		(net "M_E_CPU0_SA_CB<2>")
	)
	(segment
		(start 325.293482 -245.047262)
		(end 325.107554 -245.23319)
		(width 0.0889)
		(layer "In6.Cu")
		(net "M_E_CPU0_SA_CB<2>")
	)
	(segment
		(start 307.770784 -235.160058)
		(end 305.716178 -235.160058)
		(width 0.14478)
		(layer "In6.Cu")
		(net "M_E_CPU0_SA_CB<2>")
	)
	(segment
		(start 315.399166 -244.53215)
		(end 309.432452 -238.565436)
		(width 0.14478)
		(layer "In6.Cu")
		(net "M_E_CPU0_SA_CB<2>")
	)
	(segment
		(start 327.104502 -244.97157)
		(end 327.094088 -244.977666)
		(width 0.0889)
		(layer "In6.Cu")
		(net "M_E_CPU0_SA_CB<2>")
	)
	(segment
		(start 325.882254 -245.047262)
		(end 325.293482 -245.047262)
		(width 0.0889)
		(layer "In6.Cu")
		(net "M_E_CPU0_SA_CB<2>")
	)
	(segment
		(start 309.432452 -238.565436)
		(end 308.199282 -235.588556)
		(width 0.14478)
		(layer "In6.Cu")
		(net "M_E_CPU0_SA_CB<2>")
	)
	(segment
		(start 297.32224 -236.010196)
		(end 294.50284 -236.010196)
		(width 0.14478)
		(layer "In6.Cu")
		(net "M_E_CPU0_SA_CB<2>")
	)
	(segment
		(start 323.875654 -244.53215)
		(end 315.399166 -244.53215)
		(width 0.14478)
		(layer "In6.Cu")
		(net "M_E_CPU0_SA_CB<2>")
	)
	(segment
		(start 285.963868 -235.160058)
		(end 283.003498 -235.160058)
		(width 0.14478)
		(layer "In6.Cu")
		(net "M_E_CPU0_SA_CB<2>")
	)
	(segment
		(start 329.171046 -245.29415)
		(end 329.017122 -245.02872)
		(width 0.0889)
		(layer "In6.Cu")
		(net "M_E_CPU0_SA_CB<2>")
	)
	(segment
		(start 326.176132 -244.964712)
		(end 326.164448 -244.97157)
		(width 0.0889)
		(layer "In6.Cu")
		(net "M_E_CPU0_SA_CB<2>")
	)
	(segment
		(start 301.196502 -235.160058)
		(end 298.172378 -235.160058)
		(width 0.14478)
		(layer "In6.Cu")
		(net "M_E_CPU0_SA_CB<2>")
	)
	(segment
		(start 294.50284 -236.010196)
		(end 293.652702 -235.160058)
		(width 0.14478)
		(layer "In6.Cu")
		(net "M_E_CPU0_SA_CB<2>")
	)
	(segment
		(start 324.020434 -244.53215)
		(end 323.875654 -244.53215)
		(width 0.0889)
		(layer "In6.Cu")
		(net "M_E_CPU0_SA_CB<2>")
	)
	(segment
		(start 293.652702 -235.160058)
		(end 290.600892 -235.160058)
		(width 0.14478)
		(layer "In6.Cu")
		(net "M_E_CPU0_SA_CB<2>")
	)
	(segment
		(start 302.04664 -236.010196)
		(end 301.196502 -235.160058)
		(width 0.14478)
		(layer "In6.Cu")
		(net "M_E_CPU0_SA_CB<2>")
	)
	(segment
		(start 283.003498 -235.160058)
		(end 282.15336 -236.010196)
		(width 0.14478)
		(layer "In6.Cu")
		(net "M_E_CPU0_SA_CB<2>")
	)
	(segment
		(start 290.600892 -235.160058)
		(end 289.750754 -236.010196)
		(width 0.14478)
		(layer "In6.Cu")
		(net "M_E_CPU0_SA_CB<2>")
	)
	(segment
		(start 328.41819 -244.97157)
		(end 328.409808 -244.966744)
		(width 0.0889)
		(layer "In6.Cu")
		(net "M_E_CPU0_SA_CB<2>")
	)
	(segment
		(start 274.118832 -236.010196)
		(end 273.092164 -235.585)
		(width 0.14478)
		(layer "In6.Cu")
		(net "M_E_CPU0_SA_CB<2>")
	)
	(segment
		(start 304.86604 -236.010196)
		(end 302.04664 -236.010196)
		(width 0.14478)
		(layer "In6.Cu")
		(net "M_E_CPU0_SA_CB<2>")
	)
	(segment
		(start 324.721474 -245.23319)
		(end 324.020434 -244.53215)
		(width 0.0889)
		(layer "In6.Cu")
		(net "M_E_CPU0_SA_CB<2>")
	)
	(arc
		(start 328.044048 -244.97157)
		(mid 327.767235 -245.047713)
		(end 327.488804 -244.977666)
		(width 0.0889)
		(layer "In6.Cu")
		(net "M_E_CPU0_SA_CB<2>")
	)
	(arc
		(start 328.92111 -245.00332)
		(mid 328.665902 -245.046797)
		(end 328.41819 -244.97157)
		(width 0.0889)
		(layer "In6.Cu")
		(net "M_E_CPU0_SA_CB<2>")
	)
	(arc
		(start 326.164448 -244.97157)
		(mid 326.028339 -245.028011)
		(end 325.882254 -245.047262)
		(width 0.0889)
		(layer "In6.Cu")
		(net "M_E_CPU0_SA_CB<2>")
	)
	(arc
		(start 328.409808 -244.966744)
		(mid 328.2263 -244.92125)
		(end 328.044048 -244.97157)
		(width 0.0889)
		(layer "In6.Cu")
		(net "M_E_CPU0_SA_CB<2>")
	)
	(arc
		(start 327.47839 -244.97157)
		(mid 327.291446 -244.921315)
		(end 327.104502 -244.97157)
		(width 0.0889)
		(layer "In6.Cu")
		(net "M_E_CPU0_SA_CB<2>")
	)
	(arc
		(start 326.538336 -244.97157)
		(mid 326.358131 -244.921253)
		(end 326.176132 -244.964712)
		(width 0.0889)
		(layer "In6.Cu")
		(net "M_E_CPU0_SA_CB<2>")
	)
	(arc
		(start 327.094088 -244.977666)
		(mid 326.815402 -245.047886)
		(end 326.538336 -244.97157)
		(width 0.0889)
		(layer "In6.Cu")
		(net "M_E_CPU0_SA_CB<2>")
	)
	(segment
		(start 330.577952 -245.560088)
		(end 330.1111 -245.29415)
		(width 0.10668)
		(layer "F.Cu")
		(net "M_E_CPU0_SA_CB<1>")
	)
	(segment
		(start 296.4053 -237.023148)
		(end 296.242232 -236.86008)
		(width 0.14478)
		(layer "In6.Cu")
		(net "M_E_CPU0_SA_CB<1>")
	)
	(segment
		(start 307.954426 -236.535468)
		(end 307.751226 -236.332268)
		(width 0.14478)
		(layer "In6.Cu")
		(net "M_E_CPU0_SA_CB<1>")
	)
	(segment
		(start 278.427434 -237.23727)
		(end 278.264366 -237.074202)
		(width 0.14478)
		(layer "In6.Cu")
		(net "M_E_CPU0_SA_CB<1>")
	)
	(segment
		(start 283.208222 -236.010196)
		(end 282.358338 -236.86008)
		(width 0.14478)
		(layer "In6.Cu")
		(net "M_E_CPU0_SA_CB<1>")
	)
	(segment
		(start 296.4053 -237.086902)
		(end 296.4053 -237.023148)
		(width 0.14478)
		(layer "In6.Cu")
		(net "M_E_CPU0_SA_CB<1>")
	)
	(segment
		(start 288.768282 -237.086902)
		(end 288.768282 -237.023148)
		(width 0.14478)
		(layer "In6.Cu")
		(net "M_E_CPU0_SA_CB<1>")
	)
	(segment
		(start 288.768282 -237.023148)
		(end 288.605214 -236.86008)
		(width 0.14478)
		(layer "In6.Cu")
		(net "M_E_CPU0_SA_CB<1>")
	)
	(segment
		(start 307.546502 -236.332014)
		(end 307.321966 -236.55655)
		(width 0.14478)
		(layer "In6.Cu")
		(net "M_E_CPU0_SA_CB<1>")
	)
	(segment
		(start 280.096976 -236.86008)
		(end 279.933908 -237.023148)
		(width 0.14478)
		(layer "In6.Cu")
		(net "M_E_CPU0_SA_CB<1>")
	)
	(segment
		(start 278.657812 -237.23727)
		(end 278.427434 -237.23727)
		(width 0.14478)
		(layer "In6.Cu")
		(net "M_E_CPU0_SA_CB<1>")
	)
	(segment
		(start 328.41819 -245.61673)
		(end 328.409808 -245.621556)
		(width 0.0889)
		(layer "In6.Cu")
		(net "M_E_CPU0_SA_CB<1>")
	)
	(segment
		(start 283.691838 -236.39653)
		(end 283.52877 -236.233462)
		(width 0.14478)
		(layer "In6.Cu")
		(net "M_E_CPU0_SA_CB<1>")
	)
	(segment
		(start 307.117242 -236.55655)
		(end 306.570888 -236.010196)
		(width 0.14478)
		(layer "In6.Cu")
		(net "M_E_CPU0_SA_CB<1>")
	)
	(segment
		(start 305.071018 -236.86008)
		(end 302.024542 -236.86008)
		(width 0.14478)
		(layer "In6.Cu")
		(net "M_E_CPU0_SA_CB<1>")
	)
	(segment
		(start 327.488804 -245.610634)
		(end 327.47839 -245.61673)
		(width 0.0889)
		(layer "In6.Cu")
		(net "M_E_CPU0_SA_CB<1>")
	)
	(segment
		(start 284.085284 -236.173264)
		(end 284.085284 -236.233462)
		(width 0.14478)
		(layer "In6.Cu")
		(net "M_E_CPU0_SA_CB<1>")
	)
	(segment
		(start 283.52877 -236.233462)
		(end 283.52877 -236.173264)
		(width 0.14478)
		(layer "In6.Cu")
		(net "M_E_CPU0_SA_CB<1>")
	)
	(segment
		(start 297.124882 -236.86008)
		(end 296.961814 -237.023148)
		(width 0.14478)
		(layer "In6.Cu")
		(net "M_E_CPU0_SA_CB<1>")
	)
	(segment
		(start 278.101298 -236.86008)
		(end 277.617174 -236.86008)
		(width 0.14478)
		(layer "In6.Cu")
		(net "M_E_CPU0_SA_CB<1>")
	)
	(segment
		(start 307.729636 -237.168944)
		(end 307.72989 -236.964728)
		(width 0.14478)
		(layer "In6.Cu")
		(net "M_E_CPU0_SA_CB<1>")
	)
	(segment
		(start 278.82088 -236.645958)
		(end 278.82088 -237.074202)
		(width 0.14478)
		(layer "In6.Cu")
		(net "M_E_CPU0_SA_CB<1>")
	)
	(segment
		(start 279.540462 -237.23727)
		(end 279.377394 -237.074202)
		(width 0.14478)
		(layer "In6.Cu")
		(net "M_E_CPU0_SA_CB<1>")
	)
	(segment
		(start 323.983604 -245.19382)
		(end 323.776594 -244.98681)
		(width 0.14478)
		(layer "In6.Cu")
		(net "M_E_CPU0_SA_CB<1>")
	)
	(segment
		(start 308.817518 -238.256826)
		(end 307.729636 -237.168944)
		(width 0.14478)
		(layer "In6.Cu")
		(net "M_E_CPU0_SA_CB<1>")
	)
	(segment
		(start 278.264366 -237.023148)
		(end 278.101298 -236.86008)
		(width 0.14478)
		(layer "In6.Cu")
		(net "M_E_CPU0_SA_CB<1>")
	)
	(segment
		(start 282.358338 -236.86008)
		(end 280.096976 -236.86008)
		(width 0.14478)
		(layer "In6.Cu")
		(net "M_E_CPU0_SA_CB<1>")
	)
	(segment
		(start 289.324796 -237.023148)
		(end 289.324796 -237.086902)
		(width 0.14478)
		(layer "In6.Cu")
		(net "M_E_CPU0_SA_CB<1>")
	)
	(segment
		(start 307.751226 -236.332268)
		(end 307.546502 -236.332014)
		(width 0.14478)
		(layer "In6.Cu")
		(net "M_E_CPU0_SA_CB<1>")
	)
	(segment
		(start 326.166988 -245.611142)
		(end 324.400926 -245.611142)
		(width 0.0889)
		(layer "In6.Cu")
		(net "M_E_CPU0_SA_CB<1>")
	)
	(segment
		(start 307.321966 -236.55655)
		(end 307.117242 -236.55655)
		(width 0.14478)
		(layer "In6.Cu")
		(net "M_E_CPU0_SA_CB<1>")
	)
	(segment
		(start 298.377102 -236.010196)
		(end 297.527218 -236.86008)
		(width 0.14478)
		(layer "In6.Cu")
		(net "M_E_CPU0_SA_CB<1>")
	)
	(segment
		(start 296.961814 -237.086902)
		(end 296.798746 -237.24997)
		(width 0.14478)
		(layer "In6.Cu")
		(net "M_E_CPU0_SA_CB<1>")
	)
	(segment
		(start 297.527218 -236.86008)
		(end 297.124882 -236.86008)
		(width 0.14478)
		(layer "In6.Cu")
		(net "M_E_CPU0_SA_CB<1>")
	)
	(segment
		(start 296.568368 -237.24997)
		(end 296.4053 -237.086902)
		(width 0.14478)
		(layer "In6.Cu")
		(net "M_E_CPU0_SA_CB<1>")
	)
	(segment
		(start 308.817518 -238.59363)
		(end 308.817518 -238.256826)
		(width 0.14478)
		(layer "In6.Cu")
		(net "M_E_CPU0_SA_CB<1>")
	)
	(segment
		(start 279.377394 -236.645958)
		(end 279.214326 -236.48289)
		(width 0.14478)
		(layer "In6.Cu")
		(net "M_E_CPU0_SA_CB<1>")
	)
	(segment
		(start 284.085284 -236.233462)
		(end 283.922216 -236.39653)
		(width 0.14478)
		(layer "In6.Cu")
		(net "M_E_CPU0_SA_CB<1>")
	)
	(segment
		(start 283.365702 -236.010196)
		(end 283.208222 -236.010196)
		(width 0.14478)
		(layer "In6.Cu")
		(net "M_E_CPU0_SA_CB<1>")
	)
	(segment
		(start 288.605214 -236.86008)
		(end 286.804862 -236.86008)
		(width 0.14478)
		(layer "In6.Cu")
		(net "M_E_CPU0_SA_CB<1>")
	)
	(segment
		(start 326.182736 -245.62689)
		(end 326.166988 -245.611142)
		(width 0.0889)
		(layer "In6.Cu")
		(net "M_E_CPU0_SA_CB<1>")
	)
	(segment
		(start 279.214326 -236.48289)
		(end 278.983948 -236.48289)
		(width 0.14478)
		(layer "In6.Cu")
		(net "M_E_CPU0_SA_CB<1>")
	)
	(segment
		(start 327.104756 -245.61673)
		(end 327.094342 -245.610634)
		(width 0.0889)
		(layer "In6.Cu")
		(net "M_E_CPU0_SA_CB<1>")
	)
	(segment
		(start 278.264366 -237.074202)
		(end 278.264366 -237.023148)
		(width 0.14478)
		(layer "In6.Cu")
		(net "M_E_CPU0_SA_CB<1>")
	)
	(segment
		(start 284.248352 -236.010196)
		(end 284.085284 -236.173264)
		(width 0.14478)
		(layer "In6.Cu")
		(net "M_E_CPU0_SA_CB<1>")
	)
	(segment
		(start 289.907218 -236.86008)
		(end 289.487864 -236.86008)
		(width 0.14478)
		(layer "In6.Cu")
		(net "M_E_CPU0_SA_CB<1>")
	)
	(segment
		(start 293.630858 -236.010196)
		(end 290.757102 -236.010196)
		(width 0.14478)
		(layer "In6.Cu")
		(net "M_E_CPU0_SA_CB<1>")
	)
	(segment
		(start 330.1111 -245.29415)
		(end 330.265024 -245.55958)
		(width 0.0889)
		(layer "In6.Cu")
		(net "M_E_CPU0_SA_CB<1>")
	)
	(segment
		(start 277.617174 -236.86008)
		(end 277.192232 -236.435138)
		(width 0.14478)
		(layer "In6.Cu")
		(net "M_E_CPU0_SA_CB<1>")
	)
	(segment
		(start 283.52877 -236.173264)
		(end 283.365702 -236.010196)
		(width 0.14478)
		(layer "In6.Cu")
		(net "M_E_CPU0_SA_CB<1>")
	)
	(segment
		(start 289.324796 -237.086902)
		(end 289.161728 -237.24997)
		(width 0.14478)
		(layer "In6.Cu")
		(net "M_E_CPU0_SA_CB<1>")
	)
	(segment
		(start 324.400926 -245.611142)
		(end 323.983604 -245.19382)
		(width 0.0889)
		(layer "In6.Cu")
		(net "M_E_CPU0_SA_CB<1>")
	)
	(segment
		(start 327.47839 -245.61673)
		(end 327.470008 -245.621556)
		(width 0.0889)
		(layer "In6.Cu")
		(net "M_E_CPU0_SA_CB<1>")
	)
	(segment
		(start 301.174658 -236.010196)
		(end 298.377102 -236.010196)
		(width 0.14478)
		(layer "In6.Cu")
		(net "M_E_CPU0_SA_CB<1>")
	)
	(segment
		(start 279.933908 -237.023148)
		(end 279.933908 -237.074202)
		(width 0.14478)
		(layer "In6.Cu")
		(net "M_E_CPU0_SA_CB<1>")
	)
	(segment
		(start 279.377394 -237.074202)
		(end 279.377394 -236.645958)
		(width 0.14478)
		(layer "In6.Cu")
		(net "M_E_CPU0_SA_CB<1>")
	)
	(segment
		(start 288.93135 -237.24997)
		(end 288.768282 -237.086902)
		(width 0.14478)
		(layer "In6.Cu")
		(net "M_E_CPU0_SA_CB<1>")
	)
	(segment
		(start 296.798746 -237.24997)
		(end 296.568368 -237.24997)
		(width 0.14478)
		(layer "In6.Cu")
		(net "M_E_CPU0_SA_CB<1>")
	)
	(segment
		(start 289.161728 -237.24997)
		(end 288.93135 -237.24997)
		(width 0.14478)
		(layer "In6.Cu")
		(net "M_E_CPU0_SA_CB<1>")
	)
	(segment
		(start 307.954426 -236.740192)
		(end 307.954426 -236.535468)
		(width 0.14478)
		(layer "In6.Cu")
		(net "M_E_CPU0_SA_CB<1>")
	)
	(segment
		(start 296.242232 -236.86008)
		(end 294.480742 -236.86008)
		(width 0.14478)
		(layer "In6.Cu")
		(net "M_E_CPU0_SA_CB<1>")
	)
	(segment
		(start 296.961814 -237.023148)
		(end 296.961814 -237.086902)
		(width 0.14478)
		(layer "In6.Cu")
		(net "M_E_CPU0_SA_CB<1>")
	)
	(segment
		(start 283.922216 -236.39653)
		(end 283.691838 -236.39653)
		(width 0.14478)
		(layer "In6.Cu")
		(net "M_E_CPU0_SA_CB<1>")
	)
	(segment
		(start 278.82088 -237.074202)
		(end 278.657812 -237.23727)
		(width 0.14478)
		(layer "In6.Cu")
		(net "M_E_CPU0_SA_CB<1>")
	)
	(segment
		(start 305.920902 -236.010196)
		(end 305.071018 -236.86008)
		(width 0.14478)
		(layer "In6.Cu")
		(net "M_E_CPU0_SA_CB<1>")
	)
	(segment
		(start 323.776594 -244.98681)
		(end 315.210698 -244.98681)
		(width 0.14478)
		(layer "In6.Cu")
		(net "M_E_CPU0_SA_CB<1>")
	)
	(segment
		(start 294.480742 -236.86008)
		(end 293.630858 -236.010196)
		(width 0.14478)
		(layer "In6.Cu")
		(net "M_E_CPU0_SA_CB<1>")
	)
	(segment
		(start 290.757102 -236.010196)
		(end 289.907218 -236.86008)
		(width 0.14478)
		(layer "In6.Cu")
		(net "M_E_CPU0_SA_CB<1>")
	)
	(segment
		(start 330.265024 -245.55958)
		(end 330.242672 -245.642892)
		(width 0.0889)
		(layer "In6.Cu")
		(net "M_E_CPU0_SA_CB<1>")
	)
	(segment
		(start 302.024542 -236.86008)
		(end 301.174658 -236.010196)
		(width 0.14478)
		(layer "In6.Cu")
		(net "M_E_CPU0_SA_CB<1>")
	)
	(segment
		(start 285.954978 -236.010196)
		(end 284.248352 -236.010196)
		(width 0.14478)
		(layer "In6.Cu")
		(net "M_E_CPU0_SA_CB<1>")
	)
	(segment
		(start 286.804862 -236.86008)
		(end 285.954978 -236.010196)
		(width 0.14478)
		(layer "In6.Cu")
		(net "M_E_CPU0_SA_CB<1>")
	)
	(segment
		(start 315.210698 -244.98681)
		(end 308.817518 -238.59363)
		(width 0.14478)
		(layer "In6.Cu")
		(net "M_E_CPU0_SA_CB<1>")
	)
	(segment
		(start 306.570888 -236.010196)
		(end 305.920902 -236.010196)
		(width 0.14478)
		(layer "In6.Cu")
		(net "M_E_CPU0_SA_CB<1>")
	)
	(segment
		(start 328.992484 -245.621556)
		(end 328.984102 -245.61673)
		(width 0.0889)
		(layer "In6.Cu")
		(net "M_E_CPU0_SA_CB<1>")
	)
	(segment
		(start 279.933908 -237.074202)
		(end 279.77084 -237.23727)
		(width 0.14478)
		(layer "In6.Cu")
		(net "M_E_CPU0_SA_CB<1>")
	)
	(segment
		(start 278.983948 -236.48289)
		(end 278.82088 -236.645958)
		(width 0.14478)
		(layer "In6.Cu")
		(net "M_E_CPU0_SA_CB<1>")
	)
	(segment
		(start 307.72989 -236.964728)
		(end 307.954426 -236.740192)
		(width 0.14478)
		(layer "In6.Cu")
		(net "M_E_CPU0_SA_CB<1>")
	)
	(segment
		(start 279.77084 -237.23727)
		(end 279.540462 -237.23727)
		(width 0.14478)
		(layer "In6.Cu")
		(net "M_E_CPU0_SA_CB<1>")
	)
	(segment
		(start 289.487864 -236.86008)
		(end 289.324796 -237.023148)
		(width 0.14478)
		(layer "In6.Cu")
		(net "M_E_CPU0_SA_CB<1>")
	)
	(arc
		(start 329.924156 -245.61673)
		(mid 329.6412 -245.540553)
		(end 329.358244 -245.61673)
		(width 0.0889)
		(layer "In6.Cu")
		(net "M_E_CPU0_SA_CB<1>")
	)
	(arc
		(start 328.409808 -245.621556)
		(mid 328.2263 -245.66705)
		(end 328.044048 -245.61673)
		(width 0.0889)
		(layer "In6.Cu")
		(net "M_E_CPU0_SA_CB<1>")
	)
	(arc
		(start 330.242672 -245.642892)
		(mid 330.080483 -245.665627)
		(end 329.924156 -245.61673)
		(width 0.0889)
		(layer "In6.Cu")
		(net "M_E_CPU0_SA_CB<1>")
	)
	(arc
		(start 328.044048 -245.61673)
		(mid 327.767235 -245.540587)
		(end 327.488804 -245.610634)
		(width 0.0889)
		(layer "In6.Cu")
		(net "M_E_CPU0_SA_CB<1>")
	)
	(arc
		(start 327.470008 -245.621556)
		(mid 327.286754 -245.666929)
		(end 327.104756 -245.61673)
		(width 0.0889)
		(layer "In6.Cu")
		(net "M_E_CPU0_SA_CB<1>")
	)
	(arc
		(start 329.358244 -245.61673)
		(mid 329.175993 -245.66708)
		(end 328.992484 -245.621556)
		(width 0.0889)
		(layer "In6.Cu")
		(net "M_E_CPU0_SA_CB<1>")
	)
	(arc
		(start 327.094342 -245.610634)
		(mid 326.815656 -245.540414)
		(end 326.53859 -245.61673)
		(width 0.0889)
		(layer "In6.Cu")
		(net "M_E_CPU0_SA_CB<1>")
	)
	(arc
		(start 326.53859 -245.61673)
		(mid 326.361962 -245.666963)
		(end 326.182736 -245.62689)
		(width 0.0889)
		(layer "In6.Cu")
		(net "M_E_CPU0_SA_CB<1>")
	)
	(arc
		(start 328.984102 -245.61673)
		(mid 328.701146 -245.540553)
		(end 328.41819 -245.61673)
		(width 0.0889)
		(layer "In6.Cu")
		(net "M_E_CPU0_SA_CB<1>")
	)
	(segment
		(start 329.167998 -244.750082)
		(end 328.701146 -244.484144)
		(width 0.10668)
		(layer "F.Cu")
		(net "M_E_CPU0_SA_CB<0>")
	)
	(segment
		(start 296.450004 -235.380022)
		(end 296.450004 -235.323126)
		(width 0.14478)
		(layer "In6.Cu")
		(net "M_E_CPU0_SA_CB<0>")
	)
	(segment
		(start 296.613072 -235.54309)
		(end 296.450004 -235.380022)
		(width 0.14478)
		(layer "In6.Cu")
		(net "M_E_CPU0_SA_CB<0>")
	)
	(segment
		(start 278.749506 -235.297472)
		(end 278.749506 -235.022644)
		(width 0.14478)
		(layer "In6.Cu")
		(net "M_E_CPU0_SA_CB<0>")
	)
	(segment
		(start 278.330406 -234.88523)
		(end 278.055578 -235.160058)
		(width 0.14478)
		(layer "In6.Cu")
		(net "M_E_CPU0_SA_CB<0>")
	)
	(segment
		(start 303.226978 -235.385102)
		(end 303.06391 -235.54817)
		(width 0.14478)
		(layer "In6.Cu")
		(net "M_E_CPU0_SA_CB<0>")
	)
	(segment
		(start 289.907218 -235.160058)
		(end 289.592512 -235.160058)
		(width 0.14478)
		(layer "In6.Cu")
		(net "M_E_CPU0_SA_CB<0>")
	)
	(segment
		(start 324.970394 -244.29593)
		(end 324.416674 -244.29593)
		(width 0.0889)
		(layer "In6.Cu")
		(net "M_E_CPU0_SA_CB<0>")
	)
	(segment
		(start 327.574148 -244.806724)
		(end 327.563734 -244.800628)
		(width 0.0889)
		(layer "In6.Cu")
		(net "M_E_CPU0_SA_CB<0>")
	)
	(segment
		(start 306.939188 -234.69473)
		(end 306.70881 -234.69473)
		(width 0.14478)
		(layer "In6.Cu")
		(net "M_E_CPU0_SA_CB<0>")
	)
	(segment
		(start 302.670464 -235.385102)
		(end 302.670464 -235.323126)
		(width 0.14478)
		(layer "In6.Cu")
		(net "M_E_CPU0_SA_CB<0>")
	)
	(segment
		(start 325.882254 -244.856762)
		(end 325.531226 -244.856762)
		(width 0.0889)
		(layer "In6.Cu")
		(net "M_E_CPU0_SA_CB<0>")
	)
	(segment
		(start 298.377102 -234.310174)
		(end 297.527218 -235.160058)
		(width 0.14478)
		(layer "In6.Cu")
		(net "M_E_CPU0_SA_CB<0>")
	)
	(segment
		(start 281.143456 -235.385102)
		(end 281.143456 -235.323126)
		(width 0.14478)
		(layer "In6.Cu")
		(net "M_E_CPU0_SA_CB<0>")
	)
	(segment
		(start 297.169586 -235.160058)
		(end 297.006518 -235.323126)
		(width 0.14478)
		(layer "In6.Cu")
		(net "M_E_CPU0_SA_CB<0>")
	)
	(segment
		(start 281.536902 -235.54817)
		(end 281.306524 -235.54817)
		(width 0.14478)
		(layer "In6.Cu")
		(net "M_E_CPU0_SA_CB<0>")
	)
	(segment
		(start 283.208222 -234.310174)
		(end 282.358338 -235.160058)
		(width 0.14478)
		(layer "In6.Cu")
		(net "M_E_CPU0_SA_CB<0>")
	)
	(segment
		(start 327.00849 -244.806724)
		(end 327.000108 -244.81155)
		(width 0.0889)
		(layer "In6.Cu")
		(net "M_E_CPU0_SA_CB<0>")
	)
	(segment
		(start 328.701146 -244.484144)
		(end 328.85507 -244.749574)
		(width 0.0889)
		(layer "In6.Cu")
		(net "M_E_CPU0_SA_CB<0>")
	)
	(segment
		(start 281.143456 -235.323126)
		(end 280.980388 -235.160058)
		(width 0.14478)
		(layer "In6.Cu")
		(net "M_E_CPU0_SA_CB<0>")
	)
	(segment
		(start 304.503074 -235.160058)
		(end 304.340006 -235.323126)
		(width 0.14478)
		(layer "In6.Cu")
		(net "M_E_CPU0_SA_CB<0>")
	)
	(segment
		(start 303.94656 -235.54817)
		(end 303.783492 -235.385102)
		(width 0.14478)
		(layer "In6.Cu")
		(net "M_E_CPU0_SA_CB<0>")
	)
	(segment
		(start 303.620424 -235.160058)
		(end 303.390046 -235.160058)
		(width 0.14478)
		(layer "In6.Cu")
		(net "M_E_CPU0_SA_CB<0>")
	)
	(segment
		(start 279.30602 -235.022644)
		(end 279.30602 -235.297472)
		(width 0.14478)
		(layer "In6.Cu")
		(net "M_E_CPU0_SA_CB<0>")
	)
	(segment
		(start 303.783492 -235.385102)
		(end 303.783492 -235.323126)
		(width 0.14478)
		(layer "In6.Cu")
		(net "M_E_CPU0_SA_CB<0>")
	)
	(segment
		(start 306.382674 -234.310174)
		(end 305.920902 -234.310174)
		(width 0.14478)
		(layer "In6.Cu")
		(net "M_E_CPU0_SA_CB<0>")
	)
	(segment
		(start 279.443434 -234.88523)
		(end 279.30602 -235.022644)
		(width 0.14478)
		(layer "In6.Cu")
		(net "M_E_CPU0_SA_CB<0>")
	)
	(segment
		(start 281.69997 -235.323126)
		(end 281.69997 -235.385102)
		(width 0.14478)
		(layer "In6.Cu")
		(net "M_E_CPU0_SA_CB<0>")
	)
	(segment
		(start 302.024542 -235.160058)
		(end 301.174658 -234.310174)
		(width 0.14478)
		(layer "In6.Cu")
		(net "M_E_CPU0_SA_CB<0>")
	)
	(segment
		(start 307.821838 -234.69473)
		(end 307.65877 -234.531662)
		(width 0.14478)
		(layer "In6.Cu")
		(net "M_E_CPU0_SA_CB<0>")
	)
	(segment
		(start 303.06391 -235.54817)
		(end 302.833532 -235.54817)
		(width 0.14478)
		(layer "In6.Cu")
		(net "M_E_CPU0_SA_CB<0>")
	)
	(segment
		(start 289.035998 -235.54309)
		(end 288.87293 -235.380022)
		(width 0.14478)
		(layer "In6.Cu")
		(net "M_E_CPU0_SA_CB<0>")
	)
	(segment
		(start 307.102256 -234.473242)
		(end 307.102256 -234.531662)
		(width 0.14478)
		(layer "In6.Cu")
		(net "M_E_CPU0_SA_CB<0>")
	)
	(segment
		(start 303.226978 -235.323126)
		(end 303.226978 -235.385102)
		(width 0.14478)
		(layer "In6.Cu")
		(net "M_E_CPU0_SA_CB<0>")
	)
	(segment
		(start 288.87293 -235.380022)
		(end 288.87293 -235.323126)
		(width 0.14478)
		(layer "In6.Cu")
		(net "M_E_CPU0_SA_CB<0>")
	)
	(segment
		(start 296.450004 -235.323126)
		(end 296.286936 -235.160058)
		(width 0.14478)
		(layer "In6.Cu")
		(net "M_E_CPU0_SA_CB<0>")
	)
	(segment
		(start 302.507396 -235.160058)
		(end 302.024542 -235.160058)
		(width 0.14478)
		(layer "In6.Cu")
		(net "M_E_CPU0_SA_CB<0>")
	)
	(segment
		(start 308.405784 -234.911138)
		(end 308.189376 -234.69473)
		(width 0.14478)
		(layer "In6.Cu")
		(net "M_E_CPU0_SA_CB<0>")
	)
	(segment
		(start 305.920902 -234.310174)
		(end 305.071018 -235.160058)
		(width 0.14478)
		(layer "In6.Cu")
		(net "M_E_CPU0_SA_CB<0>")
	)
	(segment
		(start 289.429444 -235.323126)
		(end 289.429444 -235.380022)
		(width 0.14478)
		(layer "In6.Cu")
		(net "M_E_CPU0_SA_CB<0>")
	)
	(segment
		(start 278.055578 -235.160058)
		(end 277.617174 -235.160058)
		(width 0.14478)
		(layer "In6.Cu")
		(net "M_E_CPU0_SA_CB<0>")
	)
	(segment
		(start 289.429444 -235.380022)
		(end 289.266376 -235.54309)
		(width 0.14478)
		(layer "In6.Cu")
		(net "M_E_CPU0_SA_CB<0>")
	)
	(segment
		(start 288.87293 -235.323126)
		(end 288.709862 -235.160058)
		(width 0.14478)
		(layer "In6.Cu")
		(net "M_E_CPU0_SA_CB<0>")
	)
	(segment
		(start 301.174658 -234.310174)
		(end 298.377102 -234.310174)
		(width 0.14478)
		(layer "In6.Cu")
		(net "M_E_CPU0_SA_CB<0>")
	)
	(segment
		(start 279.72512 -234.88523)
		(end 279.443434 -234.88523)
		(width 0.14478)
		(layer "In6.Cu")
		(net "M_E_CPU0_SA_CB<0>")
	)
	(segment
		(start 297.527218 -235.160058)
		(end 297.169586 -235.160058)
		(width 0.14478)
		(layer "In6.Cu")
		(net "M_E_CPU0_SA_CB<0>")
	)
	(segment
		(start 281.69997 -235.385102)
		(end 281.536902 -235.54817)
		(width 0.14478)
		(layer "In6.Cu")
		(net "M_E_CPU0_SA_CB<0>")
	)
	(segment
		(start 306.545742 -234.531662)
		(end 306.545742 -234.473242)
		(width 0.14478)
		(layer "In6.Cu")
		(net "M_E_CPU0_SA_CB<0>")
	)
	(segment
		(start 303.390046 -235.160058)
		(end 303.226978 -235.323126)
		(width 0.14478)
		(layer "In6.Cu")
		(net "M_E_CPU0_SA_CB<0>")
	)
	(segment
		(start 296.286936 -235.160058)
		(end 294.480742 -235.160058)
		(width 0.14478)
		(layer "In6.Cu")
		(net "M_E_CPU0_SA_CB<0>")
	)
	(segment
		(start 297.006518 -235.323126)
		(end 297.006518 -235.380022)
		(width 0.14478)
		(layer "In6.Cu")
		(net "M_E_CPU0_SA_CB<0>")
	)
	(segment
		(start 279.168606 -235.434886)
		(end 278.88692 -235.434886)
		(width 0.14478)
		(layer "In6.Cu")
		(net "M_E_CPU0_SA_CB<0>")
	)
	(segment
		(start 307.265324 -234.310174)
		(end 307.102256 -234.473242)
		(width 0.14478)
		(layer "In6.Cu")
		(net "M_E_CPU0_SA_CB<0>")
	)
	(segment
		(start 327.58253 -244.81155)
		(end 327.574148 -244.806724)
		(width 0.0889)
		(layer "In6.Cu")
		(net "M_E_CPU0_SA_CB<0>")
	)
	(segment
		(start 304.340006 -235.323126)
		(end 304.340006 -235.385102)
		(width 0.14478)
		(layer "In6.Cu")
		(net "M_E_CPU0_SA_CB<0>")
	)
	(segment
		(start 282.358338 -235.160058)
		(end 281.863038 -235.160058)
		(width 0.14478)
		(layer "In6.Cu")
		(net "M_E_CPU0_SA_CB<0>")
	)
	(segment
		(start 325.531226 -244.856762)
		(end 324.970394 -244.29593)
		(width 0.0889)
		(layer "In6.Cu")
		(net "M_E_CPU0_SA_CB<0>")
	)
	(segment
		(start 307.65877 -234.473242)
		(end 307.495702 -234.310174)
		(width 0.14478)
		(layer "In6.Cu")
		(net "M_E_CPU0_SA_CB<0>")
	)
	(segment
		(start 290.757102 -234.310174)
		(end 289.907218 -235.160058)
		(width 0.14478)
		(layer "In6.Cu")
		(net "M_E_CPU0_SA_CB<0>")
	)
	(segment
		(start 293.630858 -234.310174)
		(end 290.757102 -234.310174)
		(width 0.14478)
		(layer "In6.Cu")
		(net "M_E_CPU0_SA_CB<0>")
	)
	(segment
		(start 302.670464 -235.323126)
		(end 302.507396 -235.160058)
		(width 0.14478)
		(layer "In6.Cu")
		(net "M_E_CPU0_SA_CB<0>")
	)
	(segment
		(start 306.545742 -234.473242)
		(end 306.382674 -234.310174)
		(width 0.14478)
		(layer "In6.Cu")
		(net "M_E_CPU0_SA_CB<0>")
	)
	(segment
		(start 315.587634 -244.07749)
		(end 309.80888 -238.298736)
		(width 0.14478)
		(layer "In6.Cu")
		(net "M_E_CPU0_SA_CB<0>")
	)
	(segment
		(start 289.592512 -235.160058)
		(end 289.429444 -235.323126)
		(width 0.14478)
		(layer "In6.Cu")
		(net "M_E_CPU0_SA_CB<0>")
	)
	(segment
		(start 289.266376 -235.54309)
		(end 289.035998 -235.54309)
		(width 0.14478)
		(layer "In6.Cu")
		(net "M_E_CPU0_SA_CB<0>")
	)
	(segment
		(start 309.80888 -238.298736)
		(end 308.405784 -234.911138)
		(width 0.14478)
		(layer "In6.Cu")
		(net "M_E_CPU0_SA_CB<0>")
	)
	(segment
		(start 304.340006 -235.385102)
		(end 304.176938 -235.54817)
		(width 0.14478)
		(layer "In6.Cu")
		(net "M_E_CPU0_SA_CB<0>")
	)
	(segment
		(start 326.083168 -244.798088)
		(end 326.068436 -244.806724)
		(width 0.0889)
		(layer "In6.Cu")
		(net "M_E_CPU0_SA_CB<0>")
	)
	(segment
		(start 278.88692 -235.434886)
		(end 278.749506 -235.297472)
		(width 0.14478)
		(layer "In6.Cu")
		(net "M_E_CPU0_SA_CB<0>")
	)
	(segment
		(start 279.999948 -235.160058)
		(end 279.72512 -234.88523)
		(width 0.14478)
		(layer "In6.Cu")
		(net "M_E_CPU0_SA_CB<0>")
	)
	(segment
		(start 294.480742 -235.160058)
		(end 293.630858 -234.310174)
		(width 0.14478)
		(layer "In6.Cu")
		(net "M_E_CPU0_SA_CB<0>")
	)
	(segment
		(start 278.749506 -235.022644)
		(end 278.612092 -234.88523)
		(width 0.14478)
		(layer "In6.Cu")
		(net "M_E_CPU0_SA_CB<0>")
	)
	(segment
		(start 306.70881 -234.69473)
		(end 306.545742 -234.531662)
		(width 0.14478)
		(layer "In6.Cu")
		(net "M_E_CPU0_SA_CB<0>")
	)
	(segment
		(start 307.65877 -234.531662)
		(end 307.65877 -234.473242)
		(width 0.14478)
		(layer "In6.Cu")
		(net "M_E_CPU0_SA_CB<0>")
	)
	(segment
		(start 304.176938 -235.54817)
		(end 303.94656 -235.54817)
		(width 0.14478)
		(layer "In6.Cu")
		(net "M_E_CPU0_SA_CB<0>")
	)
	(segment
		(start 279.30602 -235.297472)
		(end 279.168606 -235.434886)
		(width 0.14478)
		(layer "In6.Cu")
		(net "M_E_CPU0_SA_CB<0>")
	)
	(segment
		(start 285.954978 -234.310174)
		(end 283.208222 -234.310174)
		(width 0.14478)
		(layer "In6.Cu")
		(net "M_E_CPU0_SA_CB<0>")
	)
	(segment
		(start 307.102256 -234.531662)
		(end 306.939188 -234.69473)
		(width 0.14478)
		(layer "In6.Cu")
		(net "M_E_CPU0_SA_CB<0>")
	)
	(segment
		(start 288.709862 -235.160058)
		(end 286.804862 -235.160058)
		(width 0.14478)
		(layer "In6.Cu")
		(net "M_E_CPU0_SA_CB<0>")
	)
	(segment
		(start 324.198234 -244.07749)
		(end 323.901054 -244.07749)
		(width 0.0889)
		(layer "In6.Cu")
		(net "M_E_CPU0_SA_CB<0>")
	)
	(segment
		(start 307.495702 -234.310174)
		(end 307.265324 -234.310174)
		(width 0.14478)
		(layer "In6.Cu")
		(net "M_E_CPU0_SA_CB<0>")
	)
	(segment
		(start 303.783492 -235.323126)
		(end 303.620424 -235.160058)
		(width 0.14478)
		(layer "In6.Cu")
		(net "M_E_CPU0_SA_CB<0>")
	)
	(segment
		(start 302.833532 -235.54817)
		(end 302.670464 -235.385102)
		(width 0.14478)
		(layer "In6.Cu")
		(net "M_E_CPU0_SA_CB<0>")
	)
	(segment
		(start 278.612092 -234.88523)
		(end 278.330406 -234.88523)
		(width 0.14478)
		(layer "In6.Cu")
		(net "M_E_CPU0_SA_CB<0>")
	)
	(segment
		(start 308.189376 -234.69473)
		(end 307.821838 -234.69473)
		(width 0.14478)
		(layer "In6.Cu")
		(net "M_E_CPU0_SA_CB<0>")
	)
	(segment
		(start 277.617174 -235.160058)
		(end 277.192232 -234.735116)
		(width 0.14478)
		(layer "In6.Cu")
		(net "M_E_CPU0_SA_CB<0>")
	)
	(segment
		(start 323.901054 -244.07749)
		(end 315.587634 -244.07749)
		(width 0.14478)
		(layer "In6.Cu")
		(net "M_E_CPU0_SA_CB<0>")
	)
	(segment
		(start 286.804862 -235.160058)
		(end 285.954978 -234.310174)
		(width 0.14478)
		(layer "In6.Cu")
		(net "M_E_CPU0_SA_CB<0>")
	)
	(segment
		(start 324.416674 -244.29593)
		(end 324.198234 -244.07749)
		(width 0.0889)
		(layer "In6.Cu")
		(net "M_E_CPU0_SA_CB<0>")
	)
	(segment
		(start 305.071018 -235.160058)
		(end 304.503074 -235.160058)
		(width 0.14478)
		(layer "In6.Cu")
		(net "M_E_CPU0_SA_CB<0>")
	)
	(segment
		(start 281.306524 -235.54817)
		(end 281.143456 -235.385102)
		(width 0.14478)
		(layer "In6.Cu")
		(net "M_E_CPU0_SA_CB<0>")
	)
	(segment
		(start 280.980388 -235.160058)
		(end 279.999948 -235.160058)
		(width 0.14478)
		(layer "In6.Cu")
		(net "M_E_CPU0_SA_CB<0>")
	)
	(segment
		(start 281.863038 -235.160058)
		(end 281.69997 -235.323126)
		(width 0.14478)
		(layer "In6.Cu")
		(net "M_E_CPU0_SA_CB<0>")
	)
	(segment
		(start 296.84345 -235.54309)
		(end 296.613072 -235.54309)
		(width 0.14478)
		(layer "In6.Cu")
		(net "M_E_CPU0_SA_CB<0>")
	)
	(segment
		(start 328.85507 -244.749574)
		(end 328.832718 -244.832886)
		(width 0.0889)
		(layer "In6.Cu")
		(net "M_E_CPU0_SA_CB<0>")
	)
	(segment
		(start 297.006518 -235.380022)
		(end 296.84345 -235.54309)
		(width 0.14478)
		(layer "In6.Cu")
		(net "M_E_CPU0_SA_CB<0>")
	)
	(arc
		(start 326.634348 -244.806724)
		(mid 326.359896 -244.730488)
		(end 326.083168 -244.798088)
		(width 0.0889)
		(layer "In6.Cu")
		(net "M_E_CPU0_SA_CB<0>")
	)
	(arc
		(start 327.563734 -244.800628)
		(mid 327.285302 -244.73053)
		(end 327.00849 -244.806724)
		(width 0.0889)
		(layer "In6.Cu")
		(net "M_E_CPU0_SA_CB<0>")
	)
	(arc
		(start 328.514202 -244.806724)
		(mid 328.231246 -244.730547)
		(end 327.94829 -244.806724)
		(width 0.0889)
		(layer "In6.Cu")
		(net "M_E_CPU0_SA_CB<0>")
	)
	(arc
		(start 326.068436 -244.806724)
		(mid 325.978634 -244.843985)
		(end 325.882254 -244.856762)
		(width 0.0889)
		(layer "In6.Cu")
		(net "M_E_CPU0_SA_CB<0>")
	)
	(arc
		(start 327.94829 -244.806724)
		(mid 327.766039 -244.857074)
		(end 327.58253 -244.81155)
		(width 0.0889)
		(layer "In6.Cu")
		(net "M_E_CPU0_SA_CB<0>")
	)
	(arc
		(start 327.000108 -244.81155)
		(mid 326.8166 -244.857044)
		(end 326.634348 -244.806724)
		(width 0.0889)
		(layer "In6.Cu")
		(net "M_E_CPU0_SA_CB<0>")
	)
	(arc
		(start 328.832718 -244.832886)
		(mid 328.670529 -244.855621)
		(end 328.514202 -244.806724)
		(width 0.0889)
		(layer "In6.Cu")
		(net "M_E_CPU0_SA_CB<0>")
	)
	(segment
		(start 330.577952 -255.28016)
		(end 330.1111 -255.014222)
		(width 0.10668)
		(layer "F.Cu")
		(net "M_E_CPU0_SA_CA<6>")
	)
	(segment
		(start 319.66281 -254.69977)
		(end 305.83124 -254.69977)
		(width 0.14478)
		(layer "In6.Cu")
		(net "M_E_CPU0_SA_CA<6>")
	)
	(segment
		(start 277.814532 -254.17272)
		(end 277.651464 -254.009652)
		(width 0.14478)
		(layer "In6.Cu")
		(net "M_E_CPU0_SA_CA<6>")
	)
	(segment
		(start 278.691086 -254.314198)
		(end 278.69134 -254.084074)
		(width 0.14478)
		(layer "In6.Cu")
		(net "M_E_CPU0_SA_CA<6>")
	)
	(segment
		(start 327.47839 -255.336802)
		(end 327.470008 -255.341628)
		(width 0.0889)
		(layer "In6.Cu")
		(net "M_E_CPU0_SA_CA<6>")
	)
	(segment
		(start 326.182736 -255.346962)
		(end 326.164448 -255.336548)
		(width 0.0889)
		(layer "In6.Cu")
		(net "M_E_CPU0_SA_CA<6>")
	)
	(segment
		(start 278.438864 -254.797052)
		(end 278.438864 -254.56642)
		(width 0.14478)
		(layer "In6.Cu")
		(net "M_E_CPU0_SA_CA<6>")
	)
	(segment
		(start 278.601932 -254.96012)
		(end 278.438864 -254.797052)
		(width 0.14478)
		(layer "In6.Cu")
		(net "M_E_CPU0_SA_CA<6>")
	)
	(segment
		(start 278.045164 -254.172974)
		(end 277.814532 -254.17272)
		(width 0.14478)
		(layer "In6.Cu")
		(net "M_E_CPU0_SA_CA<6>")
	)
	(segment
		(start 279.31745 -254.710184)
		(end 279.315418 -254.708152)
		(width 0.14478)
		(layer "In6.Cu")
		(net "M_E_CPU0_SA_CA<6>")
	)
	(segment
		(start 305.820826 -254.710184)
		(end 279.31745 -254.710184)
		(width 0.14478)
		(layer "In6.Cu")
		(net "M_E_CPU0_SA_CA<6>")
	)
	(segment
		(start 326.09028 -255.287526)
		(end 325.403718 -255.287526)
		(width 0.0889)
		(layer "In6.Cu")
		(net "M_E_CPU0_SA_CA<6>")
	)
	(segment
		(start 324.165214 -256.04597)
		(end 323.908674 -256.04597)
		(width 0.0889)
		(layer "In6.Cu")
		(net "M_E_CPU0_SA_CA<6>")
	)
	(segment
		(start 278.297386 -253.920752)
		(end 278.045164 -254.172974)
		(width 0.14478)
		(layer "In6.Cu")
		(net "M_E_CPU0_SA_CA<6>")
	)
	(segment
		(start 323.908674 -256.04597)
		(end 321.00901 -256.04597)
		(width 0.14478)
		(layer "In6.Cu")
		(net "M_E_CPU0_SA_CA<6>")
	)
	(segment
		(start 325.403718 -255.287526)
		(end 325.102474 -255.58877)
		(width 0.0889)
		(layer "In6.Cu")
		(net "M_E_CPU0_SA_CA<6>")
	)
	(segment
		(start 279.084786 -254.708152)
		(end 278.832564 -254.960374)
		(width 0.14478)
		(layer "In6.Cu")
		(net "M_E_CPU0_SA_CA<6>")
	)
	(segment
		(start 277.90394 -253.296674)
		(end 277.192232 -252.584966)
		(width 0.14478)
		(layer "In6.Cu")
		(net "M_E_CPU0_SA_CA<6>")
	)
	(segment
		(start 328.41819 -255.336802)
		(end 328.409808 -255.341628)
		(width 0.0889)
		(layer "In6.Cu")
		(net "M_E_CPU0_SA_CA<6>")
	)
	(segment
		(start 305.83124 -254.69977)
		(end 305.820826 -254.710184)
		(width 0.14478)
		(layer "In6.Cu")
		(net "M_E_CPU0_SA_CA<6>")
	)
	(segment
		(start 278.528018 -253.920752)
		(end 278.297386 -253.920752)
		(width 0.14478)
		(layer "In6.Cu")
		(net "M_E_CPU0_SA_CA<6>")
	)
	(segment
		(start 325.102474 -255.58877)
		(end 324.622414 -255.58877)
		(width 0.0889)
		(layer "In6.Cu")
		(net "M_E_CPU0_SA_CA<6>")
	)
	(segment
		(start 277.651464 -253.77902)
		(end 277.903686 -253.526798)
		(width 0.14478)
		(layer "In6.Cu")
		(net "M_E_CPU0_SA_CA<6>")
	)
	(segment
		(start 327.104756 -255.336802)
		(end 327.094342 -255.330706)
		(width 0.0889)
		(layer "In6.Cu")
		(net "M_E_CPU0_SA_CA<6>")
	)
	(segment
		(start 278.438864 -254.56642)
		(end 278.691086 -254.314198)
		(width 0.14478)
		(layer "In6.Cu")
		(net "M_E_CPU0_SA_CA<6>")
	)
	(segment
		(start 278.832564 -254.960374)
		(end 278.601932 -254.96012)
		(width 0.14478)
		(layer "In6.Cu")
		(net "M_E_CPU0_SA_CA<6>")
	)
	(segment
		(start 330.1111 -255.014222)
		(end 330.265024 -255.279652)
		(width 0.0889)
		(layer "In6.Cu")
		(net "M_E_CPU0_SA_CA<6>")
	)
	(segment
		(start 326.164448 -255.336548)
		(end 326.09028 -255.287526)
		(width 0.0889)
		(layer "In6.Cu")
		(net "M_E_CPU0_SA_CA<6>")
	)
	(segment
		(start 279.315418 -254.708152)
		(end 279.084786 -254.708152)
		(width 0.14478)
		(layer "In6.Cu")
		(net "M_E_CPU0_SA_CA<6>")
	)
	(segment
		(start 321.00901 -256.04597)
		(end 319.66281 -254.69977)
		(width 0.14478)
		(layer "In6.Cu")
		(net "M_E_CPU0_SA_CA<6>")
	)
	(segment
		(start 328.992484 -255.341628)
		(end 328.984102 -255.336802)
		(width 0.0889)
		(layer "In6.Cu")
		(net "M_E_CPU0_SA_CA<6>")
	)
	(segment
		(start 277.903686 -253.526798)
		(end 277.90394 -253.296674)
		(width 0.14478)
		(layer "In6.Cu")
		(net "M_E_CPU0_SA_CA<6>")
	)
	(segment
		(start 327.488804 -255.330706)
		(end 327.47839 -255.336802)
		(width 0.0889)
		(layer "In6.Cu")
		(net "M_E_CPU0_SA_CA<6>")
	)
	(segment
		(start 330.265024 -255.279652)
		(end 330.242672 -255.362964)
		(width 0.0889)
		(layer "In6.Cu")
		(net "M_E_CPU0_SA_CA<6>")
	)
	(segment
		(start 278.69134 -254.084074)
		(end 278.528018 -253.920752)
		(width 0.14478)
		(layer "In6.Cu")
		(net "M_E_CPU0_SA_CA<6>")
	)
	(segment
		(start 277.651464 -254.009652)
		(end 277.651464 -253.77902)
		(width 0.14478)
		(layer "In6.Cu")
		(net "M_E_CPU0_SA_CA<6>")
	)
	(segment
		(start 324.622414 -255.58877)
		(end 324.165214 -256.04597)
		(width 0.0889)
		(layer "In6.Cu")
		(net "M_E_CPU0_SA_CA<6>")
	)
	(arc
		(start 330.242672 -255.362964)
		(mid 330.080483 -255.385699)
		(end 329.924156 -255.336802)
		(width 0.0889)
		(layer "In6.Cu")
		(net "M_E_CPU0_SA_CA<6>")
	)
	(arc
		(start 327.470008 -255.341628)
		(mid 327.286754 -255.387001)
		(end 327.104756 -255.336802)
		(width 0.0889)
		(layer "In6.Cu")
		(net "M_E_CPU0_SA_CA<6>")
	)
	(arc
		(start 328.044048 -255.336802)
		(mid 327.767235 -255.260659)
		(end 327.488804 -255.330706)
		(width 0.0889)
		(layer "In6.Cu")
		(net "M_E_CPU0_SA_CA<6>")
	)
	(arc
		(start 328.409808 -255.341628)
		(mid 328.2263 -255.387122)
		(end 328.044048 -255.336802)
		(width 0.0889)
		(layer "In6.Cu")
		(net "M_E_CPU0_SA_CA<6>")
	)
	(arc
		(start 326.53859 -255.336802)
		(mid 326.361962 -255.387035)
		(end 326.182736 -255.346962)
		(width 0.0889)
		(layer "In6.Cu")
		(net "M_E_CPU0_SA_CA<6>")
	)
	(arc
		(start 328.984102 -255.336802)
		(mid 328.701146 -255.260625)
		(end 328.41819 -255.336802)
		(width 0.0889)
		(layer "In6.Cu")
		(net "M_E_CPU0_SA_CA<6>")
	)
	(arc
		(start 329.924156 -255.336802)
		(mid 329.6412 -255.260625)
		(end 329.358244 -255.336802)
		(width 0.0889)
		(layer "In6.Cu")
		(net "M_E_CPU0_SA_CA<6>")
	)
	(arc
		(start 327.094342 -255.330706)
		(mid 326.815656 -255.260486)
		(end 326.53859 -255.336802)
		(width 0.0889)
		(layer "In6.Cu")
		(net "M_E_CPU0_SA_CA<6>")
	)
	(arc
		(start 329.358244 -255.336802)
		(mid 329.175993 -255.387152)
		(end 328.992484 -255.341628)
		(width 0.0889)
		(layer "In6.Cu")
		(net "M_E_CPU0_SA_CA<6>")
	)
	(segment
		(start 329.637898 -255.28016)
		(end 329.171046 -255.014222)
		(width 0.10668)
		(layer "F.Cu")
		(net "M_E_CPU0_SA_CA<5>")
	)
	(segment
		(start 319.851278 -254.24511)
		(end 308.171596 -254.24511)
		(width 0.14478)
		(layer "In6.Cu")
		(net "M_E_CPU0_SA_CA<5>")
	)
	(segment
		(start 325.066914 -255.09855)
		(end 324.586854 -255.09855)
		(width 0.0889)
		(layer "In6.Cu")
		(net "M_E_CPU0_SA_CA<5>")
	)
	(segment
		(start 321.166998 -255.56083)
		(end 319.851278 -254.24511)
		(width 0.14478)
		(layer "In6.Cu")
		(net "M_E_CPU0_SA_CA<5>")
	)
	(segment
		(start 277.553166 -252.160024)
		(end 273.517106 -252.160024)
		(width 0.14478)
		(layer "In6.Cu")
		(net "M_E_CPU0_SA_CA<5>")
	)
	(segment
		(start 325.882254 -254.767334)
		(end 325.596758 -254.767334)
		(width 0.0889)
		(layer "In6.Cu")
		(net "M_E_CPU0_SA_CA<5>")
	)
	(segment
		(start 327.488804 -254.697738)
		(end 327.47839 -254.691642)
		(width 0.0889)
		(layer "In6.Cu")
		(net "M_E_CPU0_SA_CA<5>")
	)
	(segment
		(start 328.41819 -254.691642)
		(end 328.409808 -254.686816)
		(width 0.0889)
		(layer "In6.Cu")
		(net "M_E_CPU0_SA_CA<5>")
	)
	(segment
		(start 323.931534 -255.56083)
		(end 321.166998 -255.56083)
		(width 0.14478)
		(layer "In6.Cu")
		(net "M_E_CPU0_SA_CA<5>")
	)
	(segment
		(start 326.176132 -254.684784)
		(end 326.164448 -254.691642)
		(width 0.0889)
		(layer "In6.Cu")
		(net "M_E_CPU0_SA_CA<5>")
	)
	(segment
		(start 325.391272 -254.774192)
		(end 325.066914 -255.09855)
		(width 0.0889)
		(layer "In6.Cu")
		(net "M_E_CPU0_SA_CA<5>")
	)
	(segment
		(start 325.596758 -254.767334)
		(end 325.391272 -254.774192)
		(width 0.0889)
		(layer "In6.Cu")
		(net "M_E_CPU0_SA_CA<5>")
	)
	(segment
		(start 327.104502 -254.691642)
		(end 327.094088 -254.697738)
		(width 0.0889)
		(layer "In6.Cu")
		(net "M_E_CPU0_SA_CA<5>")
	)
	(segment
		(start 324.124574 -255.56083)
		(end 323.931534 -255.56083)
		(width 0.0889)
		(layer "In6.Cu")
		(net "M_E_CPU0_SA_CA<5>")
	)
	(segment
		(start 307.786532 -253.860046)
		(end 279.253188 -253.860046)
		(width 0.14478)
		(layer "In6.Cu")
		(net "M_E_CPU0_SA_CA<5>")
	)
	(segment
		(start 329.171046 -255.014222)
		(end 329.017122 -254.748792)
		(width 0.0889)
		(layer "In6.Cu")
		(net "M_E_CPU0_SA_CA<5>")
	)
	(segment
		(start 308.171596 -254.24511)
		(end 307.786532 -253.860046)
		(width 0.14478)
		(layer "In6.Cu")
		(net "M_E_CPU0_SA_CA<5>")
	)
	(segment
		(start 279.253188 -253.860046)
		(end 277.553166 -252.160024)
		(width 0.14478)
		(layer "In6.Cu")
		(net "M_E_CPU0_SA_CA<5>")
	)
	(segment
		(start 273.517106 -252.160024)
		(end 273.092164 -251.735082)
		(width 0.14478)
		(layer "In6.Cu")
		(net "M_E_CPU0_SA_CA<5>")
	)
	(segment
		(start 324.586854 -255.09855)
		(end 324.124574 -255.56083)
		(width 0.0889)
		(layer "In6.Cu")
		(net "M_E_CPU0_SA_CA<5>")
	)
	(segment
		(start 329.017122 -254.748792)
		(end 328.92111 -254.723392)
		(width 0.0889)
		(layer "In6.Cu")
		(net "M_E_CPU0_SA_CA<5>")
	)
	(arc
		(start 326.538336 -254.691642)
		(mid 326.358131 -254.641325)
		(end 326.176132 -254.684784)
		(width 0.0889)
		(layer "In6.Cu")
		(net "M_E_CPU0_SA_CA<5>")
	)
	(arc
		(start 327.47839 -254.691642)
		(mid 327.291446 -254.641387)
		(end 327.104502 -254.691642)
		(width 0.0889)
		(layer "In6.Cu")
		(net "M_E_CPU0_SA_CA<5>")
	)
	(arc
		(start 328.044048 -254.691642)
		(mid 327.767235 -254.767785)
		(end 327.488804 -254.697738)
		(width 0.0889)
		(layer "In6.Cu")
		(net "M_E_CPU0_SA_CA<5>")
	)
	(arc
		(start 328.409808 -254.686816)
		(mid 328.2263 -254.641322)
		(end 328.044048 -254.691642)
		(width 0.0889)
		(layer "In6.Cu")
		(net "M_E_CPU0_SA_CA<5>")
	)
	(arc
		(start 328.92111 -254.723392)
		(mid 328.665902 -254.766869)
		(end 328.41819 -254.691642)
		(width 0.0889)
		(layer "In6.Cu")
		(net "M_E_CPU0_SA_CA<5>")
	)
	(arc
		(start 327.094088 -254.697738)
		(mid 326.815402 -254.767958)
		(end 326.538336 -254.691642)
		(width 0.0889)
		(layer "In6.Cu")
		(net "M_E_CPU0_SA_CA<5>")
	)
	(arc
		(start 326.164448 -254.691642)
		(mid 326.028339 -254.748083)
		(end 325.882254 -254.767334)
		(width 0.0889)
		(layer "In6.Cu")
		(net "M_E_CPU0_SA_CA<5>")
	)
	(segment
		(start 329.167998 -254.470154)
		(end 328.701146 -254.204216)
		(width 0.10668)
		(layer "F.Cu")
		(net "M_E_CPU0_SA_CA<4>")
	)
	(segment
		(start 293.65067 -253.39929)
		(end 293.487602 -253.236222)
		(width 0.14478)
		(layer "In6.Cu")
		(net "M_E_CPU0_SA_CA<4>")
	)
	(segment
		(start 286.313372 -253.172976)
		(end 286.313372 -253.238762)
		(width 0.14478)
		(layer "In6.Cu")
		(net "M_E_CPU0_SA_CA<4>")
	)
	(segment
		(start 293.324534 -253.009908)
		(end 291.158168 -253.009908)
		(width 0.14478)
		(layer "In6.Cu")
		(net "M_E_CPU0_SA_CA<4>")
	)
	(segment
		(start 279.317196 -253.009908)
		(end 277.192232 -250.884944)
		(width 0.14478)
		(layer "In6.Cu")
		(net "M_E_CPU0_SA_CA<4>")
	)
	(segment
		(start 283.141166 -253.172976)
		(end 283.141166 -253.238762)
		(width 0.14478)
		(layer "In6.Cu")
		(net "M_E_CPU0_SA_CA<4>")
	)
	(segment
		(start 282.421584 -253.009908)
		(end 282.191206 -253.009908)
		(width 0.14478)
		(layer "In6.Cu")
		(net "M_E_CPU0_SA_CA<4>")
	)
	(segment
		(start 281.471624 -253.172976)
		(end 281.308556 -253.009908)
		(width 0.14478)
		(layer "In6.Cu")
		(net "M_E_CPU0_SA_CA<4>")
	)
	(segment
		(start 324.129654 -255.10617)
		(end 323.949314 -255.10617)
		(width 0.0889)
		(layer "In6.Cu")
		(net "M_E_CPU0_SA_CA<4>")
	)
	(segment
		(start 286.150304 -253.40183)
		(end 285.919926 -253.40183)
		(width 0.14478)
		(layer "In6.Cu")
		(net "M_E_CPU0_SA_CA<4>")
	)
	(segment
		(start 281.471624 -253.238762)
		(end 281.471624 -253.172976)
		(width 0.14478)
		(layer "In6.Cu")
		(net "M_E_CPU0_SA_CA<4>")
	)
	(segment
		(start 283.304234 -253.009908)
		(end 283.141166 -253.172976)
		(width 0.14478)
		(layer "In6.Cu")
		(net "M_E_CPU0_SA_CA<4>")
	)
	(segment
		(start 287.4264 -253.172976)
		(end 287.4264 -253.238762)
		(width 0.14478)
		(layer "In6.Cu")
		(net "M_E_CPU0_SA_CA<4>")
	)
	(segment
		(start 325.882254 -254.576834)
		(end 325.596758 -254.576834)
		(width 0.0889)
		(layer "In6.Cu")
		(net "M_E_CPU0_SA_CA<4>")
	)
	(segment
		(start 293.487602 -253.236222)
		(end 293.487602 -253.172976)
		(width 0.14478)
		(layer "In6.Cu")
		(net "M_E_CPU0_SA_CA<4>")
	)
	(segment
		(start 327.58253 -254.531622)
		(end 327.574148 -254.526796)
		(width 0.0889)
		(layer "In6.Cu")
		(net "M_E_CPU0_SA_CA<4>")
	)
	(segment
		(start 281.86507 -253.40183)
		(end 281.634692 -253.40183)
		(width 0.14478)
		(layer "In6.Cu")
		(net "M_E_CPU0_SA_CA<4>")
	)
	(segment
		(start 281.308556 -253.009908)
		(end 279.317196 -253.009908)
		(width 0.14478)
		(layer "In6.Cu")
		(net "M_E_CPU0_SA_CA<4>")
	)
	(segment
		(start 328.85507 -254.469646)
		(end 328.832718 -254.552958)
		(width 0.0889)
		(layer "In6.Cu")
		(net "M_E_CPU0_SA_CA<4>")
	)
	(segment
		(start 289.882072 -253.238762)
		(end 289.719004 -253.40183)
		(width 0.14478)
		(layer "In6.Cu")
		(net "M_E_CPU0_SA_CA<4>")
	)
	(segment
		(start 320.039746 -253.79045)
		(end 308.55666 -253.79045)
		(width 0.14478)
		(layer "In6.Cu")
		(net "M_E_CPU0_SA_CA<4>")
	)
	(segment
		(start 327.574148 -254.526796)
		(end 327.563734 -254.5207)
		(width 0.0889)
		(layer "In6.Cu")
		(net "M_E_CPU0_SA_CA<4>")
	)
	(segment
		(start 293.487602 -253.172976)
		(end 293.324534 -253.009908)
		(width 0.14478)
		(layer "In6.Cu")
		(net "M_E_CPU0_SA_CA<4>")
	)
	(segment
		(start 291.158168 -253.009908)
		(end 290.9951 -253.172976)
		(width 0.14478)
		(layer "In6.Cu")
		(net "M_E_CPU0_SA_CA<4>")
	)
	(segment
		(start 287.4264 -253.238762)
		(end 287.263332 -253.40183)
		(width 0.14478)
		(layer "In6.Cu")
		(net "M_E_CPU0_SA_CA<4>")
	)
	(segment
		(start 290.832032 -253.40183)
		(end 290.601654 -253.40183)
		(width 0.14478)
		(layer "In6.Cu")
		(net "M_E_CPU0_SA_CA<4>")
	)
	(segment
		(start 281.634692 -253.40183)
		(end 281.471624 -253.238762)
		(width 0.14478)
		(layer "In6.Cu")
		(net "M_E_CPU0_SA_CA<4>")
	)
	(segment
		(start 324.960234 -254.85471)
		(end 324.381114 -254.85471)
		(width 0.0889)
		(layer "In6.Cu")
		(net "M_E_CPU0_SA_CA<4>")
	)
	(segment
		(start 285.919926 -253.40183)
		(end 285.756858 -253.238762)
		(width 0.14478)
		(layer "In6.Cu")
		(net "M_E_CPU0_SA_CA<4>")
	)
	(segment
		(start 290.438586 -253.172976)
		(end 290.275518 -253.009908)
		(width 0.14478)
		(layer "In6.Cu")
		(net "M_E_CPU0_SA_CA<4>")
	)
	(segment
		(start 282.028138 -253.238762)
		(end 281.86507 -253.40183)
		(width 0.14478)
		(layer "In6.Cu")
		(net "M_E_CPU0_SA_CA<4>")
	)
	(segment
		(start 290.9951 -253.172976)
		(end 290.9951 -253.238762)
		(width 0.14478)
		(layer "In6.Cu")
		(net "M_E_CPU0_SA_CA<4>")
	)
	(segment
		(start 290.438586 -253.238762)
		(end 290.438586 -253.172976)
		(width 0.14478)
		(layer "In6.Cu")
		(net "M_E_CPU0_SA_CA<4>")
	)
	(segment
		(start 282.978098 -253.40183)
		(end 282.74772 -253.40183)
		(width 0.14478)
		(layer "In6.Cu")
		(net "M_E_CPU0_SA_CA<4>")
	)
	(segment
		(start 283.141166 -253.238762)
		(end 282.978098 -253.40183)
		(width 0.14478)
		(layer "In6.Cu")
		(net "M_E_CPU0_SA_CA<4>")
	)
	(segment
		(start 285.59379 -253.009908)
		(end 283.304234 -253.009908)
		(width 0.14478)
		(layer "In6.Cu")
		(net "M_E_CPU0_SA_CA<4>")
	)
	(segment
		(start 308.55666 -253.79045)
		(end 307.776118 -253.009908)
		(width 0.14478)
		(layer "In6.Cu")
		(net "M_E_CPU0_SA_CA<4>")
	)
	(segment
		(start 282.191206 -253.009908)
		(end 282.028138 -253.172976)
		(width 0.14478)
		(layer "In6.Cu")
		(net "M_E_CPU0_SA_CA<4>")
	)
	(segment
		(start 282.74772 -253.40183)
		(end 282.584652 -253.238762)
		(width 0.14478)
		(layer "In6.Cu")
		(net "M_E_CPU0_SA_CA<4>")
	)
	(segment
		(start 287.589468 -253.009908)
		(end 287.4264 -253.172976)
		(width 0.14478)
		(layer "In6.Cu")
		(net "M_E_CPU0_SA_CA<4>")
	)
	(segment
		(start 285.756858 -253.172976)
		(end 285.59379 -253.009908)
		(width 0.14478)
		(layer "In6.Cu")
		(net "M_E_CPU0_SA_CA<4>")
	)
	(segment
		(start 290.9951 -253.238762)
		(end 290.832032 -253.40183)
		(width 0.14478)
		(layer "In6.Cu")
		(net "M_E_CPU0_SA_CA<4>")
	)
	(segment
		(start 282.028138 -253.172976)
		(end 282.028138 -253.238762)
		(width 0.14478)
		(layer "In6.Cu")
		(net "M_E_CPU0_SA_CA<4>")
	)
	(segment
		(start 325.596758 -254.576834)
		(end 325.243952 -254.570992)
		(width 0.0889)
		(layer "In6.Cu")
		(net "M_E_CPU0_SA_CA<4>")
	)
	(segment
		(start 327.00849 -254.526796)
		(end 327.000108 -254.531622)
		(width 0.0889)
		(layer "In6.Cu")
		(net "M_E_CPU0_SA_CA<4>")
	)
	(segment
		(start 289.16249 -253.009908)
		(end 287.589468 -253.009908)
		(width 0.14478)
		(layer "In6.Cu")
		(net "M_E_CPU0_SA_CA<4>")
	)
	(segment
		(start 328.701146 -254.204216)
		(end 328.85507 -254.469646)
		(width 0.0889)
		(layer "In6.Cu")
		(net "M_E_CPU0_SA_CA<4>")
	)
	(segment
		(start 282.584652 -253.238762)
		(end 282.584652 -253.172976)
		(width 0.14478)
		(layer "In6.Cu")
		(net "M_E_CPU0_SA_CA<4>")
	)
	(segment
		(start 286.706818 -253.009908)
		(end 286.47644 -253.009908)
		(width 0.14478)
		(layer "In6.Cu")
		(net "M_E_CPU0_SA_CA<4>")
	)
	(segment
		(start 286.313372 -253.238762)
		(end 286.150304 -253.40183)
		(width 0.14478)
		(layer "In6.Cu")
		(net "M_E_CPU0_SA_CA<4>")
	)
	(segment
		(start 290.275518 -253.009908)
		(end 290.04514 -253.009908)
		(width 0.14478)
		(layer "In6.Cu")
		(net "M_E_CPU0_SA_CA<4>")
	)
	(segment
		(start 321.355466 -255.10617)
		(end 320.039746 -253.79045)
		(width 0.14478)
		(layer "In6.Cu")
		(net "M_E_CPU0_SA_CA<4>")
	)
	(segment
		(start 294.207184 -253.009908)
		(end 294.044116 -253.172976)
		(width 0.14478)
		(layer "In6.Cu")
		(net "M_E_CPU0_SA_CA<4>")
	)
	(segment
		(start 294.044116 -253.172976)
		(end 294.044116 -253.236222)
		(width 0.14478)
		(layer "In6.Cu")
		(net "M_E_CPU0_SA_CA<4>")
	)
	(segment
		(start 289.325558 -253.238762)
		(end 289.325558 -253.172976)
		(width 0.14478)
		(layer "In6.Cu")
		(net "M_E_CPU0_SA_CA<4>")
	)
	(segment
		(start 287.032954 -253.40183)
		(end 286.869886 -253.238762)
		(width 0.14478)
		(layer "In6.Cu")
		(net "M_E_CPU0_SA_CA<4>")
	)
	(segment
		(start 323.949314 -255.10617)
		(end 321.355466 -255.10617)
		(width 0.14478)
		(layer "In6.Cu")
		(net "M_E_CPU0_SA_CA<4>")
	)
	(segment
		(start 289.882072 -253.172976)
		(end 289.882072 -253.238762)
		(width 0.14478)
		(layer "In6.Cu")
		(net "M_E_CPU0_SA_CA<4>")
	)
	(segment
		(start 287.263332 -253.40183)
		(end 287.032954 -253.40183)
		(width 0.14478)
		(layer "In6.Cu")
		(net "M_E_CPU0_SA_CA<4>")
	)
	(segment
		(start 326.083168 -254.51816)
		(end 326.068436 -254.526796)
		(width 0.0889)
		(layer "In6.Cu")
		(net "M_E_CPU0_SA_CA<4>")
	)
	(segment
		(start 324.381114 -254.85471)
		(end 324.129654 -255.10617)
		(width 0.0889)
		(layer "In6.Cu")
		(net "M_E_CPU0_SA_CA<4>")
	)
	(segment
		(start 286.869886 -253.172976)
		(end 286.706818 -253.009908)
		(width 0.14478)
		(layer "In6.Cu")
		(net "M_E_CPU0_SA_CA<4>")
	)
	(segment
		(start 282.584652 -253.172976)
		(end 282.421584 -253.009908)
		(width 0.14478)
		(layer "In6.Cu")
		(net "M_E_CPU0_SA_CA<4>")
	)
	(segment
		(start 293.881048 -253.39929)
		(end 293.65067 -253.39929)
		(width 0.14478)
		(layer "In6.Cu")
		(net "M_E_CPU0_SA_CA<4>")
	)
	(segment
		(start 286.869886 -253.238762)
		(end 286.869886 -253.172976)
		(width 0.14478)
		(layer "In6.Cu")
		(net "M_E_CPU0_SA_CA<4>")
	)
	(segment
		(start 289.488626 -253.40183)
		(end 289.325558 -253.238762)
		(width 0.14478)
		(layer "In6.Cu")
		(net "M_E_CPU0_SA_CA<4>")
	)
	(segment
		(start 325.243952 -254.570992)
		(end 324.960234 -254.85471)
		(width 0.0889)
		(layer "In6.Cu")
		(net "M_E_CPU0_SA_CA<4>")
	)
	(segment
		(start 290.04514 -253.009908)
		(end 289.882072 -253.172976)
		(width 0.14478)
		(layer "In6.Cu")
		(net "M_E_CPU0_SA_CA<4>")
	)
	(segment
		(start 285.756858 -253.238762)
		(end 285.756858 -253.172976)
		(width 0.14478)
		(layer "In6.Cu")
		(net "M_E_CPU0_SA_CA<4>")
	)
	(segment
		(start 289.719004 -253.40183)
		(end 289.488626 -253.40183)
		(width 0.14478)
		(layer "In6.Cu")
		(net "M_E_CPU0_SA_CA<4>")
	)
	(segment
		(start 290.601654 -253.40183)
		(end 290.438586 -253.238762)
		(width 0.14478)
		(layer "In6.Cu")
		(net "M_E_CPU0_SA_CA<4>")
	)
	(segment
		(start 289.325558 -253.172976)
		(end 289.16249 -253.009908)
		(width 0.14478)
		(layer "In6.Cu")
		(net "M_E_CPU0_SA_CA<4>")
	)
	(segment
		(start 307.776118 -253.009908)
		(end 294.207184 -253.009908)
		(width 0.14478)
		(layer "In6.Cu")
		(net "M_E_CPU0_SA_CA<4>")
	)
	(segment
		(start 286.47644 -253.009908)
		(end 286.313372 -253.172976)
		(width 0.14478)
		(layer "In6.Cu")
		(net "M_E_CPU0_SA_CA<4>")
	)
	(segment
		(start 294.044116 -253.236222)
		(end 293.881048 -253.39929)
		(width 0.14478)
		(layer "In6.Cu")
		(net "M_E_CPU0_SA_CA<4>")
	)
	(arc
		(start 328.514202 -254.526796)
		(mid 328.231246 -254.450619)
		(end 327.94829 -254.526796)
		(width 0.0889)
		(layer "In6.Cu")
		(net "M_E_CPU0_SA_CA<4>")
	)
	(arc
		(start 327.94829 -254.526796)
		(mid 327.766039 -254.577146)
		(end 327.58253 -254.531622)
		(width 0.0889)
		(layer "In6.Cu")
		(net "M_E_CPU0_SA_CA<4>")
	)
	(arc
		(start 326.634348 -254.526796)
		(mid 326.359896 -254.45056)
		(end 326.083168 -254.51816)
		(width 0.0889)
		(layer "In6.Cu")
		(net "M_E_CPU0_SA_CA<4>")
	)
	(arc
		(start 327.563734 -254.5207)
		(mid 327.285302 -254.450602)
		(end 327.00849 -254.526796)
		(width 0.0889)
		(layer "In6.Cu")
		(net "M_E_CPU0_SA_CA<4>")
	)
	(arc
		(start 328.832718 -254.552958)
		(mid 328.670529 -254.575693)
		(end 328.514202 -254.526796)
		(width 0.0889)
		(layer "In6.Cu")
		(net "M_E_CPU0_SA_CA<4>")
	)
	(arc
		(start 327.000108 -254.531622)
		(mid 326.8166 -254.577116)
		(end 326.634348 -254.526796)
		(width 0.0889)
		(layer "In6.Cu")
		(net "M_E_CPU0_SA_CA<4>")
	)
	(arc
		(start 326.068436 -254.526796)
		(mid 325.978634 -254.564057)
		(end 325.882254 -254.576834)
		(width 0.0889)
		(layer "In6.Cu")
		(net "M_E_CPU0_SA_CA<4>")
	)
	(segment
		(start 331.047852 -254.470154)
		(end 330.581 -254.204216)
		(width 0.10668)
		(layer "F.Cu")
		(net "M_E_CPU0_SA_CA<3>")
	)
	(segment
		(start 325.698104 -253.887224)
		(end 325.520558 -254.06477)
		(width 0.0889)
		(layer "In6.Cu")
		(net "M_E_CPU0_SA_CA<3>")
	)
	(segment
		(start 327.008744 -253.881636)
		(end 326.99706 -253.874778)
		(width 0.0889)
		(layer "In6.Cu")
		(net "M_E_CPU0_SA_CA<3>")
	)
	(segment
		(start 330.581 -254.204216)
		(end 330.427076 -253.938786)
		(width 0.0889)
		(layer "In6.Cu")
		(net "M_E_CPU0_SA_CA<3>")
	)
	(segment
		(start 273.517106 -250.460002)
		(end 273.092164 -250.03506)
		(width 0.14478)
		(layer "In6.Cu")
		(net "M_E_CPU0_SA_CA<3>")
	)
	(segment
		(start 323.931534 -254.65151)
		(end 321.543934 -254.65151)
		(width 0.14478)
		(layer "In6.Cu")
		(net "M_E_CPU0_SA_CA<3>")
	)
	(segment
		(start 324.111874 -254.65151)
		(end 323.931534 -254.65151)
		(width 0.0889)
		(layer "In6.Cu")
		(net "M_E_CPU0_SA_CA<3>")
	)
	(segment
		(start 279.253188 -252.160024)
		(end 277.553166 -250.460002)
		(width 0.14478)
		(layer "In6.Cu")
		(net "M_E_CPU0_SA_CA<3>")
	)
	(segment
		(start 324.284594 -254.47879)
		(end 324.111874 -254.65151)
		(width 0.0889)
		(layer "In6.Cu")
		(net "M_E_CPU0_SA_CA<3>")
	)
	(segment
		(start 307.644038 -252.160024)
		(end 279.253188 -252.160024)
		(width 0.14478)
		(layer "In6.Cu")
		(net "M_E_CPU0_SA_CA<3>")
	)
	(segment
		(start 324.284594 -254.38735)
		(end 324.284594 -254.47879)
		(width 0.0889)
		(layer "In6.Cu")
		(net "M_E_CPU0_SA_CA<3>")
	)
	(segment
		(start 326.080628 -253.888748)
		(end 326.06869 -253.88189)
		(width 0.0889)
		(layer "In6.Cu")
		(net "M_E_CPU0_SA_CA<3>")
	)
	(segment
		(start 325.520558 -254.06477)
		(end 324.607174 -254.06477)
		(width 0.0889)
		(layer "In6.Cu")
		(net "M_E_CPU0_SA_CA<3>")
	)
	(segment
		(start 277.553166 -250.460002)
		(end 273.517106 -250.460002)
		(width 0.14478)
		(layer "In6.Cu")
		(net "M_E_CPU0_SA_CA<3>")
	)
	(segment
		(start 330.427076 -253.938786)
		(end 330.331064 -253.913386)
		(width 0.0889)
		(layer "In6.Cu")
		(net "M_E_CPU0_SA_CA<3>")
	)
	(segment
		(start 329.828144 -253.881636)
		(end 329.819762 -253.87681)
		(width 0.0889)
		(layer "In6.Cu")
		(net "M_E_CPU0_SA_CA<3>")
	)
	(segment
		(start 320.228214 -253.33579)
		(end 308.819804 -253.33579)
		(width 0.14478)
		(layer "In6.Cu")
		(net "M_E_CPU0_SA_CA<3>")
	)
	(segment
		(start 308.819804 -253.33579)
		(end 307.644038 -252.160024)
		(width 0.14478)
		(layer "In6.Cu")
		(net "M_E_CPU0_SA_CA<3>")
	)
	(segment
		(start 324.607174 -254.06477)
		(end 324.284594 -254.38735)
		(width 0.0889)
		(layer "In6.Cu")
		(net "M_E_CPU0_SA_CA<3>")
	)
	(segment
		(start 327.586086 -253.874778)
		(end 327.574402 -253.881636)
		(width 0.0889)
		(layer "In6.Cu")
		(net "M_E_CPU0_SA_CA<3>")
	)
	(segment
		(start 321.543934 -254.65151)
		(end 320.228214 -253.33579)
		(width 0.14478)
		(layer "In6.Cu")
		(net "M_E_CPU0_SA_CA<3>")
	)
	(segment
		(start 327.574402 -253.881636)
		(end 327.563988 -253.887732)
		(width 0.0889)
		(layer "In6.Cu")
		(net "M_E_CPU0_SA_CA<3>")
	)
	(arc
		(start 327.94829 -253.881636)
		(mid 327.768085 -253.831319)
		(end 327.586086 -253.874778)
		(width 0.0889)
		(layer "In6.Cu")
		(net "M_E_CPU0_SA_CA<3>")
	)
	(arc
		(start 329.819762 -253.87681)
		(mid 329.636254 -253.831316)
		(end 329.454002 -253.881636)
		(width 0.0889)
		(layer "In6.Cu")
		(net "M_E_CPU0_SA_CA<3>")
	)
	(arc
		(start 328.514202 -253.881636)
		(mid 328.231246 -253.957813)
		(end 327.94829 -253.881636)
		(width 0.0889)
		(layer "In6.Cu")
		(net "M_E_CPU0_SA_CA<3>")
	)
	(arc
		(start 328.88809 -253.881636)
		(mid 328.701146 -253.831381)
		(end 328.514202 -253.881636)
		(width 0.0889)
		(layer "In6.Cu")
		(net "M_E_CPU0_SA_CA<3>")
	)
	(arc
		(start 326.99706 -253.874778)
		(mid 326.814805 -253.831125)
		(end 326.634348 -253.881636)
		(width 0.0889)
		(layer "In6.Cu")
		(net "M_E_CPU0_SA_CA<3>")
	)
	(arc
		(start 326.06869 -253.88189)
		(mid 325.882658 -253.833665)
		(end 325.698104 -253.887224)
		(width 0.0889)
		(layer "In6.Cu")
		(net "M_E_CPU0_SA_CA<3>")
	)
	(arc
		(start 330.331064 -253.913386)
		(mid 330.075856 -253.956863)
		(end 329.828144 -253.881636)
		(width 0.0889)
		(layer "In6.Cu")
		(net "M_E_CPU0_SA_CA<3>")
	)
	(arc
		(start 329.454002 -253.881636)
		(mid 329.171046 -253.957813)
		(end 328.88809 -253.881636)
		(width 0.0889)
		(layer "In6.Cu")
		(net "M_E_CPU0_SA_CA<3>")
	)
	(arc
		(start 327.563988 -253.887732)
		(mid 327.285556 -253.95783)
		(end 327.008744 -253.881636)
		(width 0.0889)
		(layer "In6.Cu")
		(net "M_E_CPU0_SA_CA<3>")
	)
	(arc
		(start 326.634348 -253.881636)
		(mid 326.358416 -253.957893)
		(end 326.080628 -253.888748)
		(width 0.0889)
		(layer "In6.Cu")
		(net "M_E_CPU0_SA_CA<3>")
	)
	(segment
		(start 330.577952 -253.660148)
		(end 330.1111 -253.39421)
		(width 0.10668)
		(layer "F.Cu")
		(net "M_E_CPU0_SA_CA<2>")
	)
	(segment
		(start 279.316942 -251.309886)
		(end 277.192232 -249.185176)
		(width 0.14478)
		(layer "In6.Cu")
		(net "M_E_CPU0_SA_CA<2>")
	)
	(segment
		(start 283.248862 -251.472954)
		(end 283.248862 -251.539502)
		(width 0.14478)
		(layer "In6.Cu")
		(net "M_E_CPU0_SA_CA<2>")
	)
	(segment
		(start 283.41193 -251.309886)
		(end 283.248862 -251.472954)
		(width 0.14478)
		(layer "In6.Cu")
		(net "M_E_CPU0_SA_CA<2>")
	)
	(segment
		(start 286.15386 -251.472954)
		(end 285.990792 -251.309886)
		(width 0.14478)
		(layer "In6.Cu")
		(net "M_E_CPU0_SA_CA<2>")
	)
	(segment
		(start 327.47839 -253.71679)
		(end 327.470008 -253.721616)
		(width 0.0889)
		(layer "In6.Cu")
		(net "M_E_CPU0_SA_CA<2>")
	)
	(segment
		(start 283.085794 -251.70257)
		(end 282.855416 -251.70257)
		(width 0.14478)
		(layer "In6.Cu")
		(net "M_E_CPU0_SA_CA<2>")
	)
	(segment
		(start 282.855416 -251.70257)
		(end 282.692348 -251.539502)
		(width 0.14478)
		(layer "In6.Cu")
		(net "M_E_CPU0_SA_CA<2>")
	)
	(segment
		(start 325.595996 -253.711202)
		(end 325.176642 -253.711202)
		(width 0.0889)
		(layer "In6.Cu")
		(net "M_E_CPU0_SA_CA<2>")
	)
	(segment
		(start 323.895974 -254.19685)
		(end 321.732402 -254.19685)
		(width 0.14478)
		(layer "In6.Cu")
		(net "M_E_CPU0_SA_CA<2>")
	)
	(segment
		(start 327.104756 -253.71679)
		(end 327.094342 -253.710694)
		(width 0.0889)
		(layer "In6.Cu")
		(net "M_E_CPU0_SA_CA<2>")
	)
	(segment
		(start 321.732402 -254.19685)
		(end 320.416682 -252.88113)
		(width 0.14478)
		(layer "In6.Cu")
		(net "M_E_CPU0_SA_CA<2>")
	)
	(segment
		(start 307.710078 -251.309886)
		(end 286.873442 -251.309886)
		(width 0.14478)
		(layer "In6.Cu")
		(net "M_E_CPU0_SA_CA<2>")
	)
	(segment
		(start 326.182736 -253.72695)
		(end 326.164448 -253.716536)
		(width 0.0889)
		(layer "In6.Cu")
		(net "M_E_CPU0_SA_CA<2>")
	)
	(segment
		(start 286.873442 -251.309886)
		(end 286.710374 -251.472954)
		(width 0.14478)
		(layer "In6.Cu")
		(net "M_E_CPU0_SA_CA<2>")
	)
	(segment
		(start 325.066914 -253.82093)
		(end 324.500494 -253.82093)
		(width 0.0889)
		(layer "In6.Cu")
		(net "M_E_CPU0_SA_CA<2>")
	)
	(segment
		(start 281.972766 -251.70257)
		(end 281.742388 -251.70257)
		(width 0.14478)
		(layer "In6.Cu")
		(net "M_E_CPU0_SA_CA<2>")
	)
	(segment
		(start 282.135834 -251.472954)
		(end 282.135834 -251.539502)
		(width 0.14478)
		(layer "In6.Cu")
		(net "M_E_CPU0_SA_CA<2>")
	)
	(segment
		(start 285.990792 -251.309886)
		(end 283.41193 -251.309886)
		(width 0.14478)
		(layer "In6.Cu")
		(net "M_E_CPU0_SA_CA<2>")
	)
	(segment
		(start 286.15386 -251.539502)
		(end 286.15386 -251.472954)
		(width 0.14478)
		(layer "In6.Cu")
		(net "M_E_CPU0_SA_CA<2>")
	)
	(segment
		(start 286.547306 -251.70257)
		(end 286.316928 -251.70257)
		(width 0.14478)
		(layer "In6.Cu")
		(net "M_E_CPU0_SA_CA<2>")
	)
	(segment
		(start 281.57932 -251.539502)
		(end 281.57932 -251.472954)
		(width 0.14478)
		(layer "In6.Cu")
		(net "M_E_CPU0_SA_CA<2>")
	)
	(segment
		(start 330.265024 -253.65964)
		(end 330.242672 -253.742952)
		(width 0.0889)
		(layer "In6.Cu")
		(net "M_E_CPU0_SA_CA<2>")
	)
	(segment
		(start 283.248862 -251.539502)
		(end 283.085794 -251.70257)
		(width 0.14478)
		(layer "In6.Cu")
		(net "M_E_CPU0_SA_CA<2>")
	)
	(segment
		(start 327.488804 -253.710694)
		(end 327.47839 -253.71679)
		(width 0.0889)
		(layer "In6.Cu")
		(net "M_E_CPU0_SA_CA<2>")
	)
	(segment
		(start 328.41819 -253.71679)
		(end 328.409808 -253.721616)
		(width 0.0889)
		(layer "In6.Cu")
		(net "M_E_CPU0_SA_CA<2>")
	)
	(segment
		(start 330.1111 -253.39421)
		(end 330.265024 -253.65964)
		(width 0.0889)
		(layer "In6.Cu")
		(net "M_E_CPU0_SA_CA<2>")
	)
	(segment
		(start 309.281322 -252.88113)
		(end 307.710078 -251.309886)
		(width 0.14478)
		(layer "In6.Cu")
		(net "M_E_CPU0_SA_CA<2>")
	)
	(segment
		(start 286.710374 -251.539502)
		(end 286.547306 -251.70257)
		(width 0.14478)
		(layer "In6.Cu")
		(net "M_E_CPU0_SA_CA<2>")
	)
	(segment
		(start 324.124574 -254.19685)
		(end 323.895974 -254.19685)
		(width 0.0889)
		(layer "In6.Cu")
		(net "M_E_CPU0_SA_CA<2>")
	)
	(segment
		(start 324.500494 -253.82093)
		(end 324.124574 -254.19685)
		(width 0.0889)
		(layer "In6.Cu")
		(net "M_E_CPU0_SA_CA<2>")
	)
	(segment
		(start 320.416682 -252.88113)
		(end 309.281322 -252.88113)
		(width 0.14478)
		(layer "In6.Cu")
		(net "M_E_CPU0_SA_CA<2>")
	)
	(segment
		(start 282.135834 -251.539502)
		(end 281.972766 -251.70257)
		(width 0.14478)
		(layer "In6.Cu")
		(net "M_E_CPU0_SA_CA<2>")
	)
	(segment
		(start 286.316928 -251.70257)
		(end 286.15386 -251.539502)
		(width 0.14478)
		(layer "In6.Cu")
		(net "M_E_CPU0_SA_CA<2>")
	)
	(segment
		(start 281.742388 -251.70257)
		(end 281.57932 -251.539502)
		(width 0.14478)
		(layer "In6.Cu")
		(net "M_E_CPU0_SA_CA<2>")
	)
	(segment
		(start 281.57932 -251.472954)
		(end 281.416252 -251.309886)
		(width 0.14478)
		(layer "In6.Cu")
		(net "M_E_CPU0_SA_CA<2>")
	)
	(segment
		(start 282.52928 -251.309886)
		(end 282.298902 -251.309886)
		(width 0.14478)
		(layer "In6.Cu")
		(net "M_E_CPU0_SA_CA<2>")
	)
	(segment
		(start 282.692348 -251.539502)
		(end 282.692348 -251.472954)
		(width 0.14478)
		(layer "In6.Cu")
		(net "M_E_CPU0_SA_CA<2>")
	)
	(segment
		(start 282.298902 -251.309886)
		(end 282.135834 -251.472954)
		(width 0.14478)
		(layer "In6.Cu")
		(net "M_E_CPU0_SA_CA<2>")
	)
	(segment
		(start 281.416252 -251.309886)
		(end 279.316942 -251.309886)
		(width 0.14478)
		(layer "In6.Cu")
		(net "M_E_CPU0_SA_CA<2>")
	)
	(segment
		(start 325.176642 -253.711202)
		(end 325.066914 -253.82093)
		(width 0.0889)
		(layer "In6.Cu")
		(net "M_E_CPU0_SA_CA<2>")
	)
	(segment
		(start 286.710374 -251.472954)
		(end 286.710374 -251.539502)
		(width 0.14478)
		(layer "In6.Cu")
		(net "M_E_CPU0_SA_CA<2>")
	)
	(segment
		(start 282.692348 -251.472954)
		(end 282.52928 -251.309886)
		(width 0.14478)
		(layer "In6.Cu")
		(net "M_E_CPU0_SA_CA<2>")
	)
	(segment
		(start 328.992484 -253.721616)
		(end 328.984102 -253.71679)
		(width 0.0889)
		(layer "In6.Cu")
		(net "M_E_CPU0_SA_CA<2>")
	)
	(arc
		(start 326.164448 -253.716536)
		(mid 325.88091 -253.640017)
		(end 325.595996 -253.711202)
		(width 0.0889)
		(layer "In6.Cu")
		(net "M_E_CPU0_SA_CA<2>")
	)
	(arc
		(start 328.409808 -253.721616)
		(mid 328.2263 -253.76711)
		(end 328.044048 -253.71679)
		(width 0.0889)
		(layer "In6.Cu")
		(net "M_E_CPU0_SA_CA<2>")
	)
	(arc
		(start 327.094342 -253.710694)
		(mid 326.815656 -253.640474)
		(end 326.53859 -253.71679)
		(width 0.0889)
		(layer "In6.Cu")
		(net "M_E_CPU0_SA_CA<2>")
	)
	(arc
		(start 326.53859 -253.71679)
		(mid 326.361962 -253.767023)
		(end 326.182736 -253.72695)
		(width 0.0889)
		(layer "In6.Cu")
		(net "M_E_CPU0_SA_CA<2>")
	)
	(arc
		(start 328.984102 -253.71679)
		(mid 328.701146 -253.640613)
		(end 328.41819 -253.71679)
		(width 0.0889)
		(layer "In6.Cu")
		(net "M_E_CPU0_SA_CA<2>")
	)
	(arc
		(start 329.358244 -253.71679)
		(mid 329.175993 -253.76714)
		(end 328.992484 -253.721616)
		(width 0.0889)
		(layer "In6.Cu")
		(net "M_E_CPU0_SA_CA<2>")
	)
	(arc
		(start 330.242672 -253.742952)
		(mid 330.080483 -253.765687)
		(end 329.924156 -253.71679)
		(width 0.0889)
		(layer "In6.Cu")
		(net "M_E_CPU0_SA_CA<2>")
	)
	(arc
		(start 327.470008 -253.721616)
		(mid 327.286754 -253.766989)
		(end 327.104756 -253.71679)
		(width 0.0889)
		(layer "In6.Cu")
		(net "M_E_CPU0_SA_CA<2>")
	)
	(arc
		(start 328.044048 -253.71679)
		(mid 327.767235 -253.640647)
		(end 327.488804 -253.710694)
		(width 0.0889)
		(layer "In6.Cu")
		(net "M_E_CPU0_SA_CA<2>")
	)
	(arc
		(start 329.924156 -253.71679)
		(mid 329.6412 -253.640613)
		(end 329.358244 -253.71679)
		(width 0.0889)
		(layer "In6.Cu")
		(net "M_E_CPU0_SA_CA<2>")
	)
	(segment
		(start 329.637898 -253.660148)
		(end 329.171046 -253.39421)
		(width 0.10668)
		(layer "F.Cu")
		(net "M_E_CPU0_SA_CA<1>")
	)
	(segment
		(start 321.92087 -253.74219)
		(end 320.60515 -252.42647)
		(width 0.14478)
		(layer "In6.Cu")
		(net "M_E_CPU0_SA_CA<1>")
	)
	(segment
		(start 309.676546 -252.42647)
		(end 307.710078 -250.460002)
		(width 0.14478)
		(layer "In6.Cu")
		(net "M_E_CPU0_SA_CA<1>")
	)
	(segment
		(start 279.253188 -250.460002)
		(end 277.553166 -248.75998)
		(width 0.14478)
		(layer "In6.Cu")
		(net "M_E_CPU0_SA_CA<1>")
	)
	(segment
		(start 277.553166 -248.75998)
		(end 273.517106 -248.75998)
		(width 0.14478)
		(layer "In6.Cu")
		(net "M_E_CPU0_SA_CA<1>")
	)
	(segment
		(start 320.60515 -252.42647)
		(end 309.676546 -252.42647)
		(width 0.14478)
		(layer "In6.Cu")
		(net "M_E_CPU0_SA_CA<1>")
	)
	(segment
		(start 307.710078 -250.460002)
		(end 279.253188 -250.460002)
		(width 0.14478)
		(layer "In6.Cu")
		(net "M_E_CPU0_SA_CA<1>")
	)
	(segment
		(start 325.054214 -253.52883)
		(end 324.325234 -253.52883)
		(width 0.0889)
		(layer "In6.Cu")
		(net "M_E_CPU0_SA_CA<1>")
	)
	(segment
		(start 328.41819 -253.07163)
		(end 328.409808 -253.066804)
		(width 0.0889)
		(layer "In6.Cu")
		(net "M_E_CPU0_SA_CA<1>")
	)
	(segment
		(start 327.488804 -253.077726)
		(end 327.47839 -253.07163)
		(width 0.0889)
		(layer "In6.Cu")
		(net "M_E_CPU0_SA_CA<1>")
	)
	(segment
		(start 329.017122 -253.12878)
		(end 328.92111 -253.10338)
		(width 0.0889)
		(layer "In6.Cu")
		(net "M_E_CPU0_SA_CA<1>")
	)
	(segment
		(start 329.171046 -253.39421)
		(end 329.017122 -253.12878)
		(width 0.0889)
		(layer "In6.Cu")
		(net "M_E_CPU0_SA_CA<1>")
	)
	(segment
		(start 323.890894 -253.74219)
		(end 321.92087 -253.74219)
		(width 0.14478)
		(layer "In6.Cu")
		(net "M_E_CPU0_SA_CA<1>")
	)
	(segment
		(start 324.325234 -253.52883)
		(end 324.111874 -253.74219)
		(width 0.0889)
		(layer "In6.Cu")
		(net "M_E_CPU0_SA_CA<1>")
	)
	(segment
		(start 325.882254 -253.147322)
		(end 325.435722 -253.147322)
		(width 0.0889)
		(layer "In6.Cu")
		(net "M_E_CPU0_SA_CA<1>")
	)
	(segment
		(start 327.104502 -253.07163)
		(end 327.094088 -253.077726)
		(width 0.0889)
		(layer "In6.Cu")
		(net "M_E_CPU0_SA_CA<1>")
	)
	(segment
		(start 273.517106 -248.75998)
		(end 273.092164 -248.335038)
		(width 0.14478)
		(layer "In6.Cu")
		(net "M_E_CPU0_SA_CA<1>")
	)
	(segment
		(start 325.435722 -253.147322)
		(end 325.054214 -253.52883)
		(width 0.0889)
		(layer "In6.Cu")
		(net "M_E_CPU0_SA_CA<1>")
	)
	(segment
		(start 326.176132 -253.064772)
		(end 326.164448 -253.07163)
		(width 0.0889)
		(layer "In6.Cu")
		(net "M_E_CPU0_SA_CA<1>")
	)
	(segment
		(start 324.111874 -253.74219)
		(end 323.890894 -253.74219)
		(width 0.0889)
		(layer "In6.Cu")
		(net "M_E_CPU0_SA_CA<1>")
	)
	(arc
		(start 327.094088 -253.077726)
		(mid 326.815402 -253.147946)
		(end 326.538336 -253.07163)
		(width 0.0889)
		(layer "In6.Cu")
		(net "M_E_CPU0_SA_CA<1>")
	)
	(arc
		(start 326.538336 -253.07163)
		(mid 326.358131 -253.021313)
		(end 326.176132 -253.064772)
		(width 0.0889)
		(layer "In6.Cu")
		(net "M_E_CPU0_SA_CA<1>")
	)
	(arc
		(start 328.92111 -253.10338)
		(mid 328.665902 -253.146857)
		(end 328.41819 -253.07163)
		(width 0.0889)
		(layer "In6.Cu")
		(net "M_E_CPU0_SA_CA<1>")
	)
	(arc
		(start 328.044048 -253.07163)
		(mid 327.767235 -253.147773)
		(end 327.488804 -253.077726)
		(width 0.0889)
		(layer "In6.Cu")
		(net "M_E_CPU0_SA_CA<1>")
	)
	(arc
		(start 326.164448 -253.07163)
		(mid 326.028339 -253.128071)
		(end 325.882254 -253.147322)
		(width 0.0889)
		(layer "In6.Cu")
		(net "M_E_CPU0_SA_CA<1>")
	)
	(arc
		(start 327.47839 -253.07163)
		(mid 327.291446 -253.021375)
		(end 327.104502 -253.07163)
		(width 0.0889)
		(layer "In6.Cu")
		(net "M_E_CPU0_SA_CA<1>")
	)
	(arc
		(start 328.409808 -253.066804)
		(mid 328.2263 -253.02131)
		(end 328.044048 -253.07163)
		(width 0.0889)
		(layer "In6.Cu")
		(net "M_E_CPU0_SA_CA<1>")
	)
	(segment
		(start 329.167998 -252.850142)
		(end 328.701146 -252.584204)
		(width 0.10668)
		(layer "F.Cu")
		(net "M_E_CPU0_SA_CA<0>")
	)
	(segment
		(start 283.124402 -250.00077)
		(end 282.894024 -250.00077)
		(width 0.14478)
		(layer "In6.Cu")
		(net "M_E_CPU0_SA_CA<0>")
	)
	(segment
		(start 283.450538 -249.610118)
		(end 283.28747 -249.773186)
		(width 0.14478)
		(layer "In6.Cu")
		(net "M_E_CPU0_SA_CA<0>")
	)
	(segment
		(start 282.567888 -249.610118)
		(end 282.33751 -249.610118)
		(width 0.14478)
		(layer "In6.Cu")
		(net "M_E_CPU0_SA_CA<0>")
	)
	(segment
		(start 325.882254 -252.956822)
		(end 325.184262 -252.956822)
		(width 0.0889)
		(layer "In6.Cu")
		(net "M_E_CPU0_SA_CA<0>")
	)
	(segment
		(start 291.11829 -249.840242)
		(end 290.955222 -250.00331)
		(width 0.14478)
		(layer "In6.Cu")
		(net "M_E_CPU0_SA_CA<0>")
	)
	(segment
		(start 290.561776 -249.773186)
		(end 290.398708 -249.610118)
		(width 0.14478)
		(layer "In6.Cu")
		(net "M_E_CPU0_SA_CA<0>")
	)
	(segment
		(start 328.85507 -252.849634)
		(end 328.832718 -252.932946)
		(width 0.0889)
		(layer "In6.Cu")
		(net "M_E_CPU0_SA_CA<0>")
	)
	(segment
		(start 293.475918 -249.773186)
		(end 293.31285 -249.610118)
		(width 0.14478)
		(layer "In6.Cu")
		(net "M_E_CPU0_SA_CA<0>")
	)
	(segment
		(start 286.327342 -249.773186)
		(end 286.164274 -249.610118)
		(width 0.14478)
		(layer "In6.Cu")
		(net "M_E_CPU0_SA_CA<0>")
	)
	(segment
		(start 289.448748 -249.773186)
		(end 289.28568 -249.610118)
		(width 0.14478)
		(layer "In6.Cu")
		(net "M_E_CPU0_SA_CA<0>")
	)
	(segment
		(start 289.611816 -250.00331)
		(end 289.448748 -249.840242)
		(width 0.14478)
		(layer "In6.Cu")
		(net "M_E_CPU0_SA_CA<0>")
	)
	(segment
		(start 293.869364 -250.00331)
		(end 293.638986 -250.00331)
		(width 0.14478)
		(layer "In6.Cu")
		(net "M_E_CPU0_SA_CA<0>")
	)
	(segment
		(start 289.842194 -250.00331)
		(end 289.611816 -250.00331)
		(width 0.14478)
		(layer "In6.Cu")
		(net "M_E_CPU0_SA_CA<0>")
	)
	(segment
		(start 281.780996 -250.00077)
		(end 281.617928 -249.837702)
		(width 0.14478)
		(layer "In6.Cu")
		(net "M_E_CPU0_SA_CA<0>")
	)
	(segment
		(start 282.011374 -250.00077)
		(end 281.780996 -250.00077)
		(width 0.14478)
		(layer "In6.Cu")
		(net "M_E_CPU0_SA_CA<0>")
	)
	(segment
		(start 281.617928 -249.773186)
		(end 281.45486 -249.610118)
		(width 0.14478)
		(layer "In6.Cu")
		(net "M_E_CPU0_SA_CA<0>")
	)
	(segment
		(start 282.174442 -249.837702)
		(end 282.011374 -250.00077)
		(width 0.14478)
		(layer "In6.Cu")
		(net "M_E_CPU0_SA_CA<0>")
	)
	(segment
		(start 286.720788 -250.00077)
		(end 286.49041 -250.00077)
		(width 0.14478)
		(layer "In6.Cu")
		(net "M_E_CPU0_SA_CA<0>")
	)
	(segment
		(start 324.886574 -253.25451)
		(end 324.261734 -253.25451)
		(width 0.0889)
		(layer "In6.Cu")
		(net "M_E_CPU0_SA_CA<0>")
	)
	(segment
		(start 286.327342 -249.837702)
		(end 286.327342 -249.773186)
		(width 0.14478)
		(layer "In6.Cu")
		(net "M_E_CPU0_SA_CA<0>")
	)
	(segment
		(start 324.261734 -253.25451)
		(end 324.228714 -253.28753)
		(width 0.0889)
		(layer "In6.Cu")
		(net "M_E_CPU0_SA_CA<0>")
	)
	(segment
		(start 289.448748 -249.840242)
		(end 289.448748 -249.773186)
		(width 0.14478)
		(layer "In6.Cu")
		(net "M_E_CPU0_SA_CA<0>")
	)
	(segment
		(start 282.730956 -249.837702)
		(end 282.730956 -249.773186)
		(width 0.14478)
		(layer "In6.Cu")
		(net "M_E_CPU0_SA_CA<0>")
	)
	(segment
		(start 289.28568 -249.610118)
		(end 287.046924 -249.610118)
		(width 0.14478)
		(layer "In6.Cu")
		(net "M_E_CPU0_SA_CA<0>")
	)
	(segment
		(start 286.49041 -250.00077)
		(end 286.327342 -249.837702)
		(width 0.14478)
		(layer "In6.Cu")
		(net "M_E_CPU0_SA_CA<0>")
	)
	(segment
		(start 290.724844 -250.00331)
		(end 290.561776 -249.840242)
		(width 0.14478)
		(layer "In6.Cu")
		(net "M_E_CPU0_SA_CA<0>")
	)
	(segment
		(start 327.00849 -252.906784)
		(end 327.000108 -252.91161)
		(width 0.0889)
		(layer "In6.Cu")
		(net "M_E_CPU0_SA_CA<0>")
	)
	(segment
		(start 294.1955 -249.610118)
		(end 294.032432 -249.773186)
		(width 0.14478)
		(layer "In6.Cu")
		(net "M_E_CPU0_SA_CA<0>")
	)
	(segment
		(start 283.28747 -249.773186)
		(end 283.28747 -249.837702)
		(width 0.14478)
		(layer "In6.Cu")
		(net "M_E_CPU0_SA_CA<0>")
	)
	(segment
		(start 322.109338 -253.28753)
		(end 320.793618 -251.97181)
		(width 0.14478)
		(layer "In6.Cu")
		(net "M_E_CPU0_SA_CA<0>")
	)
	(segment
		(start 293.638986 -250.00331)
		(end 293.475918 -249.840242)
		(width 0.14478)
		(layer "In6.Cu")
		(net "M_E_CPU0_SA_CA<0>")
	)
	(segment
		(start 282.730956 -249.773186)
		(end 282.567888 -249.610118)
		(width 0.14478)
		(layer "In6.Cu")
		(net "M_E_CPU0_SA_CA<0>")
	)
	(segment
		(start 281.45486 -249.610118)
		(end 279.317196 -249.610118)
		(width 0.14478)
		(layer "In6.Cu")
		(net "M_E_CPU0_SA_CA<0>")
	)
	(segment
		(start 293.475918 -249.840242)
		(end 293.475918 -249.773186)
		(width 0.14478)
		(layer "In6.Cu")
		(net "M_E_CPU0_SA_CA<0>")
	)
	(segment
		(start 326.083168 -252.898148)
		(end 326.068436 -252.906784)
		(width 0.0889)
		(layer "In6.Cu")
		(net "M_E_CPU0_SA_CA<0>")
	)
	(segment
		(start 327.58253 -252.91161)
		(end 327.574148 -252.906784)
		(width 0.0889)
		(layer "In6.Cu")
		(net "M_E_CPU0_SA_CA<0>")
	)
	(segment
		(start 320.793618 -251.97181)
		(end 310.07177 -251.97181)
		(width 0.14478)
		(layer "In6.Cu")
		(net "M_E_CPU0_SA_CA<0>")
	)
	(segment
		(start 282.33751 -249.610118)
		(end 282.174442 -249.773186)
		(width 0.14478)
		(layer "In6.Cu")
		(net "M_E_CPU0_SA_CA<0>")
	)
	(segment
		(start 294.032432 -249.840242)
		(end 293.869364 -250.00331)
		(width 0.14478)
		(layer "In6.Cu")
		(net "M_E_CPU0_SA_CA<0>")
	)
	(segment
		(start 286.164274 -249.610118)
		(end 283.450538 -249.610118)
		(width 0.14478)
		(layer "In6.Cu")
		(net "M_E_CPU0_SA_CA<0>")
	)
	(segment
		(start 327.574148 -252.906784)
		(end 327.563734 -252.900688)
		(width 0.0889)
		(layer "In6.Cu")
		(net "M_E_CPU0_SA_CA<0>")
	)
	(segment
		(start 290.005262 -249.840242)
		(end 289.842194 -250.00331)
		(width 0.14478)
		(layer "In6.Cu")
		(net "M_E_CPU0_SA_CA<0>")
	)
	(segment
		(start 328.701146 -252.584204)
		(end 328.85507 -252.849634)
		(width 0.0889)
		(layer "In6.Cu")
		(net "M_E_CPU0_SA_CA<0>")
	)
	(segment
		(start 290.16833 -249.610118)
		(end 290.005262 -249.773186)
		(width 0.14478)
		(layer "In6.Cu")
		(net "M_E_CPU0_SA_CA<0>")
	)
	(segment
		(start 286.883856 -249.837702)
		(end 286.720788 -250.00077)
		(width 0.14478)
		(layer "In6.Cu")
		(net "M_E_CPU0_SA_CA<0>")
	)
	(segment
		(start 282.894024 -250.00077)
		(end 282.730956 -249.837702)
		(width 0.14478)
		(layer "In6.Cu")
		(net "M_E_CPU0_SA_CA<0>")
	)
	(segment
		(start 293.31285 -249.610118)
		(end 291.281358 -249.610118)
		(width 0.14478)
		(layer "In6.Cu")
		(net "M_E_CPU0_SA_CA<0>")
	)
	(segment
		(start 290.955222 -250.00331)
		(end 290.724844 -250.00331)
		(width 0.14478)
		(layer "In6.Cu")
		(net "M_E_CPU0_SA_CA<0>")
	)
	(segment
		(start 290.561776 -249.840242)
		(end 290.561776 -249.773186)
		(width 0.14478)
		(layer "In6.Cu")
		(net "M_E_CPU0_SA_CA<0>")
	)
	(segment
		(start 290.005262 -249.773186)
		(end 290.005262 -249.840242)
		(width 0.14478)
		(layer "In6.Cu")
		(net "M_E_CPU0_SA_CA<0>")
	)
	(segment
		(start 291.11829 -249.773186)
		(end 291.11829 -249.840242)
		(width 0.14478)
		(layer "In6.Cu")
		(net "M_E_CPU0_SA_CA<0>")
	)
	(segment
		(start 324.228714 -253.28753)
		(end 323.885814 -253.28753)
		(width 0.0889)
		(layer "In6.Cu")
		(net "M_E_CPU0_SA_CA<0>")
	)
	(segment
		(start 307.710078 -249.610118)
		(end 294.1955 -249.610118)
		(width 0.14478)
		(layer "In6.Cu")
		(net "M_E_CPU0_SA_CA<0>")
	)
	(segment
		(start 294.032432 -249.773186)
		(end 294.032432 -249.840242)
		(width 0.14478)
		(layer "In6.Cu")
		(net "M_E_CPU0_SA_CA<0>")
	)
	(segment
		(start 279.317196 -249.610118)
		(end 277.192232 -247.485154)
		(width 0.14478)
		(layer "In6.Cu")
		(net "M_E_CPU0_SA_CA<0>")
	)
	(segment
		(start 281.617928 -249.837702)
		(end 281.617928 -249.773186)
		(width 0.14478)
		(layer "In6.Cu")
		(net "M_E_CPU0_SA_CA<0>")
	)
	(segment
		(start 282.174442 -249.773186)
		(end 282.174442 -249.837702)
		(width 0.14478)
		(layer "In6.Cu")
		(net "M_E_CPU0_SA_CA<0>")
	)
	(segment
		(start 290.398708 -249.610118)
		(end 290.16833 -249.610118)
		(width 0.14478)
		(layer "In6.Cu")
		(net "M_E_CPU0_SA_CA<0>")
	)
	(segment
		(start 323.885814 -253.28753)
		(end 322.109338 -253.28753)
		(width 0.14478)
		(layer "In6.Cu")
		(net "M_E_CPU0_SA_CA<0>")
	)
	(segment
		(start 291.281358 -249.610118)
		(end 291.11829 -249.773186)
		(width 0.14478)
		(layer "In6.Cu")
		(net "M_E_CPU0_SA_CA<0>")
	)
	(segment
		(start 286.883856 -249.773186)
		(end 286.883856 -249.837702)
		(width 0.14478)
		(layer "In6.Cu")
		(net "M_E_CPU0_SA_CA<0>")
	)
	(segment
		(start 283.28747 -249.837702)
		(end 283.124402 -250.00077)
		(width 0.14478)
		(layer "In6.Cu")
		(net "M_E_CPU0_SA_CA<0>")
	)
	(segment
		(start 287.046924 -249.610118)
		(end 286.883856 -249.773186)
		(width 0.14478)
		(layer "In6.Cu")
		(net "M_E_CPU0_SA_CA<0>")
	)
	(segment
		(start 310.07177 -251.97181)
		(end 307.710078 -249.610118)
		(width 0.14478)
		(layer "In6.Cu")
		(net "M_E_CPU0_SA_CA<0>")
	)
	(segment
		(start 325.184262 -252.956822)
		(end 324.886574 -253.25451)
		(width 0.0889)
		(layer "In6.Cu")
		(net "M_E_CPU0_SA_CA<0>")
	)
	(arc
		(start 328.514202 -252.906784)
		(mid 328.231246 -252.830607)
		(end 327.94829 -252.906784)
		(width 0.0889)
		(layer "In6.Cu")
		(net "M_E_CPU0_SA_CA<0>")
	)
	(arc
		(start 328.832718 -252.932946)
		(mid 328.670529 -252.955681)
		(end 328.514202 -252.906784)
		(width 0.0889)
		(layer "In6.Cu")
		(net "M_E_CPU0_SA_CA<0>")
	)
	(arc
		(start 326.068436 -252.906784)
		(mid 325.978634 -252.944045)
		(end 325.882254 -252.956822)
		(width 0.0889)
		(layer "In6.Cu")
		(net "M_E_CPU0_SA_CA<0>")
	)
	(arc
		(start 327.563734 -252.900688)
		(mid 327.285302 -252.83059)
		(end 327.00849 -252.906784)
		(width 0.0889)
		(layer "In6.Cu")
		(net "M_E_CPU0_SA_CA<0>")
	)
	(arc
		(start 326.634348 -252.906784)
		(mid 326.359896 -252.830548)
		(end 326.083168 -252.898148)
		(width 0.0889)
		(layer "In6.Cu")
		(net "M_E_CPU0_SA_CA<0>")
	)
	(arc
		(start 327.94829 -252.906784)
		(mid 327.766039 -252.957134)
		(end 327.58253 -252.91161)
		(width 0.0889)
		(layer "In6.Cu")
		(net "M_E_CPU0_SA_CA<0>")
	)
	(arc
		(start 327.000108 -252.91161)
		(mid 326.8166 -252.957104)
		(end 326.634348 -252.906784)
		(width 0.0889)
		(layer "In6.Cu")
		(net "M_E_CPU0_SA_CA<0>")
	)
	(segment
		(start 331.047852 -251.23013)
		(end 330.581 -250.964192)
		(width 0.10668)
		(layer "F.Cu")
		(net "M_E_CPU0_RESET_N")
	)
	(segment
		(start 324.080124 -251.61875)
		(end 322.781422 -251.61875)
		(width 0.11684)
		(layer "In6.Cu")
		(net "M_E_CPU0_RESET_N")
	)
	(segment
		(start 324.901814 -251.61875)
		(end 324.080124 -251.61875)
		(width 0.0889)
		(layer "In6.Cu")
		(net "M_E_CPU0_RESET_N")
	)
	(segment
		(start 278.076406 -245.359936)
		(end 273.517106 -245.359936)
		(width 0.11684)
		(layer "In6.Cu")
		(net "M_E_CPU0_RESET_N")
	)
	(segment
		(start 326.100948 -251.00153)
		(end 325.519034 -251.00153)
		(width 0.0889)
		(layer "In6.Cu")
		(net "M_E_CPU0_RESET_N")
	)
	(segment
		(start 273.517106 -245.359936)
		(end 273.092164 -244.934994)
		(width 0.11684)
		(layer "In6.Cu")
		(net "M_E_CPU0_RESET_N")
	)
	(segment
		(start 327.008744 -250.641612)
		(end 326.99706 -250.634754)
		(width 0.0889)
		(layer "In6.Cu")
		(net "M_E_CPU0_RESET_N")
	)
	(segment
		(start 330.581 -250.964192)
		(end 330.427076 -250.698762)
		(width 0.0889)
		(layer "In6.Cu")
		(net "M_E_CPU0_RESET_N")
	)
	(segment
		(start 322.781422 -251.61875)
		(end 321.479672 -250.317)
		(width 0.11684)
		(layer "In6.Cu")
		(net "M_E_CPU0_RESET_N")
	)
	(segment
		(start 307.934106 -247.059958)
		(end 279.776428 -247.059958)
		(width 0.11684)
		(layer "In6.Cu")
		(net "M_E_CPU0_RESET_N")
	)
	(segment
		(start 321.479672 -250.317)
		(end 311.191148 -250.317)
		(width 0.11684)
		(layer "In6.Cu")
		(net "M_E_CPU0_RESET_N")
	)
	(segment
		(start 279.776428 -247.059958)
		(end 278.076406 -245.359936)
		(width 0.11684)
		(layer "In6.Cu")
		(net "M_E_CPU0_RESET_N")
	)
	(segment
		(start 326.378824 -250.717304)
		(end 326.100948 -251.00153)
		(width 0.0889)
		(layer "In6.Cu")
		(net "M_E_CPU0_RESET_N")
	)
	(segment
		(start 311.191148 -250.317)
		(end 307.934106 -247.059958)
		(width 0.11684)
		(layer "In6.Cu")
		(net "M_E_CPU0_RESET_N")
	)
	(segment
		(start 327.586086 -250.634754)
		(end 327.574402 -250.641612)
		(width 0.0889)
		(layer "In6.Cu")
		(net "M_E_CPU0_RESET_N")
	)
	(segment
		(start 327.574402 -250.641612)
		(end 327.563988 -250.647708)
		(width 0.0889)
		(layer "In6.Cu")
		(net "M_E_CPU0_RESET_N")
	)
	(segment
		(start 330.427076 -250.698762)
		(end 330.331064 -250.673362)
		(width 0.0889)
		(layer "In6.Cu")
		(net "M_E_CPU0_RESET_N")
	)
	(segment
		(start 325.519034 -251.00153)
		(end 324.901814 -251.61875)
		(width 0.0889)
		(layer "In6.Cu")
		(net "M_E_CPU0_RESET_N")
	)
	(segment
		(start 329.828144 -250.641612)
		(end 329.819762 -250.636786)
		(width 0.0889)
		(layer "In6.Cu")
		(net "M_E_CPU0_RESET_N")
	)
	(arc
		(start 327.94829 -250.641612)
		(mid 327.768085 -250.591295)
		(end 327.586086 -250.634754)
		(width 0.0889)
		(layer "In6.Cu")
		(net "M_E_CPU0_RESET_N")
	)
	(arc
		(start 328.88809 -250.641612)
		(mid 328.701146 -250.591357)
		(end 328.514202 -250.641612)
		(width 0.0889)
		(layer "In6.Cu")
		(net "M_E_CPU0_RESET_N")
	)
	(arc
		(start 326.99706 -250.634754)
		(mid 326.814805 -250.591101)
		(end 326.634348 -250.641612)
		(width 0.0889)
		(layer "In6.Cu")
		(net "M_E_CPU0_RESET_N")
	)
	(arc
		(start 329.819762 -250.636786)
		(mid 329.636254 -250.591292)
		(end 329.454002 -250.641612)
		(width 0.0889)
		(layer "In6.Cu")
		(net "M_E_CPU0_RESET_N")
	)
	(arc
		(start 329.454002 -250.641612)
		(mid 329.171046 -250.717789)
		(end 328.88809 -250.641612)
		(width 0.0889)
		(layer "In6.Cu")
		(net "M_E_CPU0_RESET_N")
	)
	(arc
		(start 326.634348 -250.641612)
		(mid 326.511126 -250.694795)
		(end 326.378824 -250.717304)
		(width 0.0889)
		(layer "In6.Cu")
		(net "M_E_CPU0_RESET_N")
	)
	(arc
		(start 330.331064 -250.673362)
		(mid 330.075856 -250.716839)
		(end 329.828144 -250.641612)
		(width 0.0889)
		(layer "In6.Cu")
		(net "M_E_CPU0_RESET_N")
	)
	(arc
		(start 327.563988 -250.647708)
		(mid 327.285556 -250.717806)
		(end 327.008744 -250.641612)
		(width 0.0889)
		(layer "In6.Cu")
		(net "M_E_CPU0_RESET_N")
	)
	(arc
		(start 328.514202 -250.641612)
		(mid 328.231246 -250.717789)
		(end 327.94829 -250.641612)
		(width 0.0889)
		(layer "In6.Cu")
		(net "M_E_CPU0_RESET_N")
	)
	(segment
		(start 329.167998 -256.090166)
		(end 328.701146 -255.824228)
		(width 0.14732)
		(layer "F.Cu")
		(net "M_E_CPU0_CLK_DP<0>")
	)
	(segment
		(start 327.581006 -256.154174)
		(end 327.572624 -256.149348)
		(width 0.09525)
		(layer "In6.Cu")
		(net "M_E_CPU0_CLK_DP<0>")
	)
	(segment
		(start 313.188604 -256.31521)
		(end 313.071764 -256.43205)
		(width 0.16002)
		(layer "In6.Cu")
		(net "M_E_CPU0_CLK_DP<0>")
	)
	(segment
		(start 324.777862 -257.401822)
		(end 323.978778 -257.401822)
		(width 0.09525)
		(layer "In6.Cu")
		(net "M_E_CPU0_CLK_DP<0>")
	)
	(segment
		(start 328.701146 -255.824228)
		(end 328.85507 -256.089658)
		(width 0.09525)
		(layer "In6.Cu")
		(net "M_E_CPU0_CLK_DP<0>")
	)
	(segment
		(start 319.115186 -255.82245)
		(end 315.737494 -255.82245)
		(width 0.16002)
		(layer "In6.Cu")
		(net "M_E_CPU0_CLK_DP<0>")
	)
	(segment
		(start 327.572624 -256.149348)
		(end 327.56221 -256.143252)
		(width 0.09525)
		(layer "In6.Cu")
		(net "M_E_CPU0_CLK_DP<0>")
	)
	(segment
		(start 323.978778 -257.401822)
		(end 323.919596 -257.34264)
		(width 0.09525)
		(layer "In6.Cu")
		(net "M_E_CPU0_CLK_DP<0>")
	)
	(segment
		(start 325.948294 -256.23139)
		(end 324.777862 -257.401822)
		(width 0.09525)
		(layer "In6.Cu")
		(net "M_E_CPU0_CLK_DP<0>")
	)
	(segment
		(start 323.919596 -257.34264)
		(end 323.895974 -257.34264)
		(width 0.09525)
		(layer "In6.Cu")
		(net "M_E_CPU0_CLK_DP<0>")
	)
	(segment
		(start 276.95271 -256.43205)
		(end 274.229576 -253.708916)
		(width 0.16002)
		(layer "In6.Cu")
		(net "M_E_CPU0_CLK_DP<0>")
	)
	(segment
		(start 313.668664 -256.31521)
		(end 313.188604 -256.31521)
		(width 0.16002)
		(layer "In6.Cu")
		(net "M_E_CPU0_CLK_DP<0>")
	)
	(segment
		(start 328.85507 -256.089658)
		(end 328.831956 -256.176272)
		(width 0.09525)
		(layer "In6.Cu")
		(net "M_E_CPU0_CLK_DP<0>")
	)
	(segment
		(start 320.635376 -257.34264)
		(end 319.115186 -255.82245)
		(width 0.16002)
		(layer "In6.Cu")
		(net "M_E_CPU0_CLK_DP<0>")
	)
	(segment
		(start 313.785504 -256.43205)
		(end 313.668664 -256.31521)
		(width 0.16002)
		(layer "In6.Cu")
		(net "M_E_CPU0_CLK_DP<0>")
	)
	(segment
		(start 273.365976 -253.708916)
		(end 273.092164 -253.435104)
		(width 0.16002)
		(layer "In6.Cu")
		(net "M_E_CPU0_CLK_DP<0>")
	)
	(segment
		(start 327.010014 -256.149348)
		(end 327.001632 -256.154174)
		(width 0.09525)
		(layer "In6.Cu")
		(net "M_E_CPU0_CLK_DP<0>")
	)
	(segment
		(start 323.895974 -257.34264)
		(end 320.635376 -257.34264)
		(width 0.16002)
		(layer "In6.Cu")
		(net "M_E_CPU0_CLK_DP<0>")
	)
	(segment
		(start 326.351138 -256.073402)
		(end 326.255888 -256.073402)
		(width 0.09525)
		(layer "In6.Cu")
		(net "M_E_CPU0_CLK_DP<0>")
	)
	(segment
		(start 314.265564 -256.43205)
		(end 313.785504 -256.43205)
		(width 0.16002)
		(layer "In6.Cu")
		(net "M_E_CPU0_CLK_DP<0>")
	)
	(segment
		(start 274.229576 -253.708916)
		(end 273.365976 -253.708916)
		(width 0.16002)
		(layer "In6.Cu")
		(net "M_E_CPU0_CLK_DP<0>")
	)
	(segment
		(start 315.737494 -255.82245)
		(end 314.265564 -256.43205)
		(width 0.16002)
		(layer "In6.Cu")
		(net "M_E_CPU0_CLK_DP<0>")
	)
	(segment
		(start 313.071764 -256.43205)
		(end 276.95271 -256.43205)
		(width 0.16002)
		(layer "In6.Cu")
		(net "M_E_CPU0_CLK_DP<0>")
	)
	(arc
		(start 327.56221 -256.143252)
		(mid 327.285302 -256.073575)
		(end 327.010014 -256.149348)
		(width 0.09525)
		(layer "In6.Cu")
		(net "M_E_CPU0_CLK_DP<0>")
	)
	(arc
		(start 328.512678 -256.149348)
		(mid 328.231246 -256.073593)
		(end 327.949814 -256.149348)
		(width 0.09525)
		(layer "In6.Cu")
		(net "M_E_CPU0_CLK_DP<0>")
	)
	(arc
		(start 327.949814 -256.149348)
		(mid 327.766039 -256.20012)
		(end 327.581006 -256.154174)
		(width 0.09525)
		(layer "In6.Cu")
		(net "M_E_CPU0_CLK_DP<0>")
	)
	(arc
		(start 326.632824 -256.149348)
		(mid 326.497002 -256.092768)
		(end 326.351138 -256.073402)
		(width 0.09525)
		(layer "In6.Cu")
		(net "M_E_CPU0_CLK_DP<0>")
	)
	(arc
		(start 327.001632 -256.154174)
		(mid 326.8166 -256.200088)
		(end 326.632824 -256.149348)
		(width 0.09525)
		(layer "In6.Cu")
		(net "M_E_CPU0_CLK_DP<0>")
	)
	(arc
		(start 326.255888 -256.073402)
		(mid 326.082987 -256.115206)
		(end 325.948294 -256.23139)
		(width 0.09525)
		(layer "In6.Cu")
		(net "M_E_CPU0_CLK_DP<0>")
	)
	(arc
		(start 328.831956 -256.176272)
		(mid 328.669305 -256.198532)
		(end 328.512678 -256.149348)
		(width 0.09525)
		(layer "In6.Cu")
		(net "M_E_CPU0_CLK_DP<0>")
	)
	(segment
		(start 329.637898 -256.900172)
		(end 329.171046 -256.634234)
		(width 0.14732)
		(layer "F.Cu")
		(net "M_E_CPU0_CLK_DN<0>")
	)
	(segment
		(start 326.351138 -256.257552)
		(end 326.255888 -256.257552)
		(width 0.09525)
		(layer "In6.Cu")
		(net "M_E_CPU0_CLK_DN<0>")
	)
	(segment
		(start 327.490328 -256.31521)
		(end 327.479914 -256.309114)
		(width 0.09525)
		(layer "In6.Cu")
		(net "M_E_CPU0_CLK_DN<0>")
	)
	(segment
		(start 323.978524 -257.585972)
		(end 323.919596 -257.6449)
		(width 0.09525)
		(layer "In6.Cu")
		(net "M_E_CPU0_CLK_DN<0>")
	)
	(segment
		(start 318.989964 -256.12471)
		(end 315.797692 -256.12471)
		(width 0.16002)
		(layer "In6.Cu")
		(net "M_E_CPU0_CLK_DN<0>")
	)
	(segment
		(start 274.104354 -254.011176)
		(end 273.365976 -254.011176)
		(width 0.16002)
		(layer "In6.Cu")
		(net "M_E_CPU0_CLK_DN<0>")
	)
	(segment
		(start 329.171046 -256.634234)
		(end 329.017122 -256.368804)
		(width 0.09525)
		(layer "In6.Cu")
		(net "M_E_CPU0_CLK_DN<0>")
	)
	(segment
		(start 314.325762 -256.73431)
		(end 276.827488 -256.73431)
		(width 0.16002)
		(layer "In6.Cu")
		(net "M_E_CPU0_CLK_DN<0>")
	)
	(segment
		(start 326.098154 -256.338832)
		(end 326.089264 -256.351024)
		(width 0.09525)
		(layer "In6.Cu")
		(net "M_E_CPU0_CLK_DN<0>")
	)
	(segment
		(start 326.089264 -256.351024)
		(end 324.854316 -257.585972)
		(width 0.09525)
		(layer "In6.Cu")
		(net "M_E_CPU0_CLK_DN<0>")
	)
	(segment
		(start 324.854316 -257.585972)
		(end 323.978524 -257.585972)
		(width 0.09525)
		(layer "In6.Cu")
		(net "M_E_CPU0_CLK_DN<0>")
	)
	(segment
		(start 323.895974 -257.6449)
		(end 320.510154 -257.6449)
		(width 0.16002)
		(layer "In6.Cu")
		(net "M_E_CPU0_CLK_DN<0>")
	)
	(segment
		(start 328.419714 -256.309114)
		(end 328.411332 -256.304288)
		(width 0.09525)
		(layer "In6.Cu")
		(net "M_E_CPU0_CLK_DN<0>")
	)
	(segment
		(start 315.797692 -256.12471)
		(end 314.325762 -256.73431)
		(width 0.16002)
		(layer "In6.Cu")
		(net "M_E_CPU0_CLK_DN<0>")
	)
	(segment
		(start 329.017122 -256.368804)
		(end 328.916284 -256.342134)
		(width 0.09525)
		(layer "In6.Cu")
		(net "M_E_CPU0_CLK_DN<0>")
	)
	(segment
		(start 276.827488 -256.73431)
		(end 274.104354 -254.011176)
		(width 0.16002)
		(layer "In6.Cu")
		(net "M_E_CPU0_CLK_DN<0>")
	)
	(segment
		(start 273.365976 -254.011176)
		(end 273.092164 -254.284988)
		(width 0.16002)
		(layer "In6.Cu")
		(net "M_E_CPU0_CLK_DN<0>")
	)
	(segment
		(start 327.102978 -256.309114)
		(end 327.092564 -256.31521)
		(width 0.09525)
		(layer "In6.Cu")
		(net "M_E_CPU0_CLK_DN<0>")
	)
	(segment
		(start 320.510154 -257.6449)
		(end 318.989964 -256.12471)
		(width 0.16002)
		(layer "In6.Cu")
		(net "M_E_CPU0_CLK_DN<0>")
	)
	(segment
		(start 323.919596 -257.6449)
		(end 323.895974 -257.6449)
		(width 0.09525)
		(layer "In6.Cu")
		(net "M_E_CPU0_CLK_DN<0>")
	)
	(arc
		(start 326.53986 -256.309114)
		(mid 326.448914 -256.270813)
		(end 326.351138 -256.257552)
		(width 0.09525)
		(layer "In6.Cu")
		(net "M_E_CPU0_CLK_DN<0>")
	)
	(arc
		(start 328.411332 -256.304288)
		(mid 328.2263 -256.258374)
		(end 328.042524 -256.309114)
		(width 0.09525)
		(layer "In6.Cu")
		(net "M_E_CPU0_CLK_DN<0>")
	)
	(arc
		(start 328.896472 -256.350008)
		(mid 328.653508 -256.382995)
		(end 328.419714 -256.309114)
		(width 0.09525)
		(layer "In6.Cu")
		(net "M_E_CPU0_CLK_DN<0>")
	)
	(arc
		(start 327.092564 -256.31521)
		(mid 326.815402 -256.38501)
		(end 326.53986 -256.309114)
		(width 0.09525)
		(layer "In6.Cu")
		(net "M_E_CPU0_CLK_DN<0>")
	)
	(arc
		(start 326.255888 -256.257552)
		(mid 326.167206 -256.279131)
		(end 326.098154 -256.338832)
		(width 0.09525)
		(layer "In6.Cu")
		(net "M_E_CPU0_CLK_DN<0>")
	)
	(arc
		(start 328.042524 -256.309114)
		(mid 327.767235 -256.384835)
		(end 327.490328 -256.31521)
		(width 0.09525)
		(layer "In6.Cu")
		(net "M_E_CPU0_CLK_DN<0>")
	)
	(arc
		(start 327.479914 -256.309114)
		(mid 327.291446 -256.258437)
		(end 327.102978 -256.309114)
		(width 0.09525)
		(layer "In6.Cu")
		(net "M_E_CPU0_CLK_DN<0>")
	)
	(arc
		(start 328.916284 -256.342134)
		(mid 328.906416 -256.346165)
		(end 328.896472 -256.350008)
		(width 0.09525)
		(layer "In6.Cu")
		(net "M_E_CPU0_CLK_DN<0>")
	)
	(segment
		(start 330.577952 -250.420124)
		(end 330.1111 -250.154186)
		(width 0.10668)
		(layer "F.Cu")
		(net "M_E_CPU0_ALERT_R_N")
	)
	(segment
		(start 325.355204 -250.71197)
		(end 324.739254 -250.71197)
		(width 0.0889)
		(layer "In6.Cu")
		(net "M_E_CPU0_ALERT_R_N")
	)
	(segment
		(start 306.297076 -246.210074)
		(end 305.965098 -246.542052)
		(width 0.11684)
		(layer "In6.Cu")
		(net "M_E_CPU0_ALERT_R_N")
	)
	(segment
		(start 328.41819 -250.476766)
		(end 328.409808 -250.481592)
		(width 0.0889)
		(layer "In6.Cu")
		(net "M_E_CPU0_ALERT_R_N")
	)
	(segment
		(start 311.36336 -249.89028)
		(end 307.683154 -246.210074)
		(width 0.11684)
		(layer "In6.Cu")
		(net "M_E_CPU0_ALERT_R_N")
	)
	(segment
		(start 304.641758 -246.210074)
		(end 279.978358 -246.210074)
		(width 0.11684)
		(layer "In6.Cu")
		(net "M_E_CPU0_ALERT_R_N")
	)
	(segment
		(start 327.488804 -250.47067)
		(end 327.47839 -250.476766)
		(width 0.0889)
		(layer "In6.Cu")
		(net "M_E_CPU0_ALERT_R_N")
	)
	(segment
		(start 328.992484 -250.481592)
		(end 328.984102 -250.476766)
		(width 0.0889)
		(layer "In6.Cu")
		(net "M_E_CPU0_ALERT_R_N")
	)
	(segment
		(start 330.1111 -250.154186)
		(end 330.265024 -250.419616)
		(width 0.0889)
		(layer "In6.Cu")
		(net "M_E_CPU0_ALERT_R_N")
	)
	(segment
		(start 327.47839 -250.476766)
		(end 327.470008 -250.481592)
		(width 0.0889)
		(layer "In6.Cu")
		(net "M_E_CPU0_ALERT_R_N")
	)
	(segment
		(start 324.569074 -250.88215)
		(end 322.648326 -250.88215)
		(width 0.11684)
		(layer "In6.Cu")
		(net "M_E_CPU0_ALERT_R_N")
	)
	(segment
		(start 330.265024 -250.419616)
		(end 330.242672 -250.502928)
		(width 0.0889)
		(layer "In6.Cu")
		(net "M_E_CPU0_ALERT_R_N")
	)
	(segment
		(start 327.104756 -250.476766)
		(end 327.094342 -250.47067)
		(width 0.0889)
		(layer "In6.Cu")
		(net "M_E_CPU0_ALERT_R_N")
	)
	(segment
		(start 307.683154 -246.210074)
		(end 306.297076 -246.210074)
		(width 0.11684)
		(layer "In6.Cu")
		(net "M_E_CPU0_ALERT_R_N")
	)
	(segment
		(start 322.648326 -250.88215)
		(end 321.656456 -249.89028)
		(width 0.11684)
		(layer "In6.Cu")
		(net "M_E_CPU0_ALERT_R_N")
	)
	(segment
		(start 324.739254 -250.71197)
		(end 324.569074 -250.88215)
		(width 0.11684)
		(layer "In6.Cu")
		(net "M_E_CPU0_ALERT_R_N")
	)
	(segment
		(start 326.182736 -250.486926)
		(end 326.164448 -250.476512)
		(width 0.0889)
		(layer "In6.Cu")
		(net "M_E_CPU0_ALERT_R_N")
	)
	(segment
		(start 304.973736 -246.542052)
		(end 304.641758 -246.210074)
		(width 0.11684)
		(layer "In6.Cu")
		(net "M_E_CPU0_ALERT_R_N")
	)
	(segment
		(start 278.589232 -244.820948)
		(end 278.589232 -244.08511)
		(width 0.11684)
		(layer "In6.Cu")
		(net "M_E_CPU0_ALERT_R_N")
	)
	(segment
		(start 279.978358 -246.210074)
		(end 278.589232 -244.820948)
		(width 0.11684)
		(layer "In6.Cu")
		(net "M_E_CPU0_ALERT_R_N")
	)
	(segment
		(start 321.656456 -249.89028)
		(end 311.36336 -249.89028)
		(width 0.11684)
		(layer "In6.Cu")
		(net "M_E_CPU0_ALERT_R_N")
	)
	(segment
		(start 305.965098 -246.542052)
		(end 304.973736 -246.542052)
		(width 0.11684)
		(layer "In6.Cu")
		(net "M_E_CPU0_ALERT_R_N")
	)
	(segment
		(start 325.595996 -250.471178)
		(end 325.355204 -250.71197)
		(width 0.0889)
		(layer "In6.Cu")
		(net "M_E_CPU0_ALERT_R_N")
	)
	(arc
		(start 328.409808 -250.481592)
		(mid 328.2263 -250.527086)
		(end 328.044048 -250.476766)
		(width 0.0889)
		(layer "In6.Cu")
		(net "M_E_CPU0_ALERT_R_N")
	)
	(arc
		(start 329.358244 -250.476766)
		(mid 329.175993 -250.527116)
		(end 328.992484 -250.481592)
		(width 0.0889)
		(layer "In6.Cu")
		(net "M_E_CPU0_ALERT_R_N")
	)
	(arc
		(start 327.094342 -250.47067)
		(mid 326.815656 -250.40045)
		(end 326.53859 -250.476766)
		(width 0.0889)
		(layer "In6.Cu")
		(net "M_E_CPU0_ALERT_R_N")
	)
	(arc
		(start 327.470008 -250.481592)
		(mid 327.286754 -250.526965)
		(end 327.104756 -250.476766)
		(width 0.0889)
		(layer "In6.Cu")
		(net "M_E_CPU0_ALERT_R_N")
	)
	(arc
		(start 326.164448 -250.476512)
		(mid 325.88091 -250.399993)
		(end 325.595996 -250.471178)
		(width 0.0889)
		(layer "In6.Cu")
		(net "M_E_CPU0_ALERT_R_N")
	)
	(arc
		(start 329.924156 -250.476766)
		(mid 329.6412 -250.400589)
		(end 329.358244 -250.476766)
		(width 0.0889)
		(layer "In6.Cu")
		(net "M_E_CPU0_ALERT_R_N")
	)
	(arc
		(start 330.242672 -250.502928)
		(mid 330.080483 -250.525663)
		(end 329.924156 -250.476766)
		(width 0.0889)
		(layer "In6.Cu")
		(net "M_E_CPU0_ALERT_R_N")
	)
	(arc
		(start 328.984102 -250.476766)
		(mid 328.701146 -250.400589)
		(end 328.41819 -250.476766)
		(width 0.0889)
		(layer "In6.Cu")
		(net "M_E_CPU0_ALERT_R_N")
	)
	(arc
		(start 328.044048 -250.476766)
		(mid 327.767235 -250.400623)
		(end 327.488804 -250.47067)
		(width 0.0889)
		(layer "In6.Cu")
		(net "M_E_CPU0_ALERT_R_N")
	)
	(arc
		(start 326.53859 -250.476766)
		(mid 326.361962 -250.526999)
		(end 326.182736 -250.486926)
		(width 0.0889)
		(layer "In6.Cu")
		(net "M_E_CPU0_ALERT_R_N")
	)
	(via
		(at 277.192232 -244.08511)
		(size 0.4826)
		(drill 0.254)
		(layers "F.Cu" "B.Cu")
		(net "M_E_CPU0_ALERT_N")
	)
	(segment
		(start 277.789132 -244.08511)
		(end 277.192232 -244.08511)
		(width 0.10668)
		(layer "B.Cu")
		(net "M_E_CPU0_ALERT_N")
	)
	(segment
		(start 91.397836 -267.340334)
		(end 90.930984 -267.606272)
		(width 0.10668)
		(layer "F.Cu")
		(net "M_D_CPU1_SB_RSP<0>")
	)
	(segment
		(start 48.03775 -270.010382)
		(end 48.334168 -269.713964)
		(width 0.11684)
		(layer "In4.Cu")
		(net "M_D_CPU1_SB_RSP<0>")
	)
	(segment
		(start 39.640256 -270.010382)
		(end 40.713152 -270.010382)
		(width 0.11684)
		(layer "In4.Cu")
		(net "M_D_CPU1_SB_RSP<0>")
	)
	(segment
		(start 79.812388 -267.936726)
		(end 79.83601 -267.923264)
		(width 0.0889)
		(layer "In4.Cu")
		(net "M_D_CPU1_SB_RSP<0>")
	)
	(segment
		(start 78.89494 -267.923264)
		(end 78.918308 -267.909548)
		(width 0.0889)
		(layer "In4.Cu")
		(net "M_D_CPU1_SB_RSP<0>")
	)
	(segment
		(start 54.80685 -269.713964)
		(end 55.103268 -270.010382)
		(width 0.11684)
		(layer "In4.Cu")
		(net "M_D_CPU1_SB_RSP<0>")
	)
	(segment
		(start 87.354918 -267.923264)
		(end 87.365586 -267.917168)
		(width 0.0889)
		(layer "In4.Cu")
		(net "M_D_CPU1_SB_RSP<0>")
	)
	(segment
		(start 55.655718 -270.010382)
		(end 55.952136 -269.713964)
		(width 0.11684)
		(layer "In4.Cu")
		(net "M_D_CPU1_SB_RSP<0>")
	)
	(segment
		(start 49.919128 -270.010382)
		(end 50.15103 -270.010382)
		(width 0.11684)
		(layer "In4.Cu")
		(net "M_D_CPU1_SB_RSP<0>")
	)
	(segment
		(start 44.570396 -270.010382)
		(end 44.866814 -269.713964)
		(width 0.11684)
		(layer "In4.Cu")
		(net "M_D_CPU1_SB_RSP<0>")
	)
	(segment
		(start 83.594956 -267.923264)
		(end 83.605624 -267.917168)
		(width 0.0889)
		(layer "In4.Cu")
		(net "M_D_CPU1_SB_RSP<0>")
	)
	(segment
		(start 53.75021 -269.713964)
		(end 54.046628 -270.010382)
		(width 0.11684)
		(layer "In4.Cu")
		(net "M_D_CPU1_SB_RSP<0>")
	)
	(segment
		(start 38.055296 -269.739364)
		(end 38.312598 -269.739364)
		(width 0.11684)
		(layer "In4.Cu")
		(net "M_D_CPU1_SB_RSP<0>")
	)
	(segment
		(start 57.008776 -269.713964)
		(end 57.240678 -269.713964)
		(width 0.11684)
		(layer "In4.Cu")
		(net "M_D_CPU1_SB_RSP<0>")
	)
	(segment
		(start 46.451774 -270.010382)
		(end 46.683676 -270.010382)
		(width 0.11684)
		(layer "In4.Cu")
		(net "M_D_CPU1_SB_RSP<0>")
	)
	(segment
		(start 49.390808 -269.713964)
		(end 49.62271 -269.713964)
		(width 0.11684)
		(layer "In4.Cu")
		(net "M_D_CPU1_SB_RSP<0>")
	)
	(segment
		(start 50.447448 -269.713964)
		(end 50.67935 -269.713964)
		(width 0.11684)
		(layer "In4.Cu")
		(net "M_D_CPU1_SB_RSP<0>")
	)
	(segment
		(start 48.56607 -269.713964)
		(end 48.862488 -270.010382)
		(width 0.11684)
		(layer "In4.Cu")
		(net "M_D_CPU1_SB_RSP<0>")
	)
	(segment
		(start 39.111936 -269.739364)
		(end 39.369238 -269.739364)
		(width 0.11684)
		(layer "In4.Cu")
		(net "M_D_CPU1_SB_RSP<0>")
	)
	(segment
		(start 52.69357 -269.713964)
		(end 52.989988 -270.010382)
		(width 0.11684)
		(layer "In4.Cu")
		(net "M_D_CPU1_SB_RSP<0>")
	)
	(segment
		(start 41.00957 -269.713964)
		(end 41.241472 -269.713964)
		(width 0.11684)
		(layer "In4.Cu")
		(net "M_D_CPU1_SB_RSP<0>")
	)
	(segment
		(start 90.73642 -267.917168)
		(end 90.747088 -267.923264)
		(width 0.0889)
		(layer "In4.Cu")
		(net "M_D_CPU1_SB_RSP<0>")
	)
	(segment
		(start 42.298112 -269.713964)
		(end 42.59453 -270.010382)
		(width 0.11684)
		(layer "In4.Cu")
		(net "M_D_CPU1_SB_RSP<0>")
	)
	(segment
		(start 54.27853 -270.010382)
		(end 54.574948 -269.713964)
		(width 0.11684)
		(layer "In4.Cu")
		(net "M_D_CPU1_SB_RSP<0>")
	)
	(segment
		(start 58.297318 -269.713964)
		(end 58.593736 -270.010382)
		(width 0.11684)
		(layer "In4.Cu")
		(net "M_D_CPU1_SB_RSP<0>")
	)
	(segment
		(start 42.06621 -269.713964)
		(end 42.298112 -269.713964)
		(width 0.11684)
		(layer "In4.Cu")
		(net "M_D_CPU1_SB_RSP<0>")
	)
	(segment
		(start 57.768998 -270.010382)
		(end 58.065416 -269.713964)
		(width 0.11684)
		(layer "In4.Cu")
		(net "M_D_CPU1_SB_RSP<0>")
	)
	(segment
		(start 45.395134 -270.010382)
		(end 45.627036 -270.010382)
		(width 0.11684)
		(layer "In4.Cu")
		(net "M_D_CPU1_SB_RSP<0>")
	)
	(segment
		(start 56.480456 -270.010382)
		(end 56.712358 -270.010382)
		(width 0.11684)
		(layer "In4.Cu")
		(net "M_D_CPU1_SB_RSP<0>")
	)
	(segment
		(start 82.276442 -267.917168)
		(end 82.28711 -267.923264)
		(width 0.0889)
		(layer "In4.Cu")
		(net "M_D_CPU1_SB_RSP<0>")
	)
	(segment
		(start 45.098716 -269.713964)
		(end 45.395134 -270.010382)
		(width 0.11684)
		(layer "In4.Cu")
		(net "M_D_CPU1_SB_RSP<0>")
	)
	(segment
		(start 36.795964 -270.435324)
		(end 37.220906 -270.010382)
		(width 0.11684)
		(layer "In4.Cu")
		(net "M_D_CPU1_SB_RSP<0>")
	)
	(segment
		(start 42.826432 -270.010382)
		(end 43.12285 -269.713964)
		(width 0.11684)
		(layer "In4.Cu")
		(net "M_D_CPU1_SB_RSP<0>")
	)
	(segment
		(start 47.211996 -269.713964)
		(end 47.508414 -270.010382)
		(width 0.11684)
		(layer "In4.Cu")
		(net "M_D_CPU1_SB_RSP<0>")
	)
	(segment
		(start 49.62271 -269.713964)
		(end 49.919128 -270.010382)
		(width 0.11684)
		(layer "In4.Cu")
		(net "M_D_CPU1_SB_RSP<0>")
	)
	(segment
		(start 86.976458 -267.917168)
		(end 86.987126 -267.923264)
		(width 0.0889)
		(layer "In4.Cu")
		(net "M_D_CPU1_SB_RSP<0>")
	)
	(segment
		(start 59.650376 -270.010382)
		(end 59.882278 -270.010382)
		(width 0.11684)
		(layer "In4.Cu")
		(net "M_D_CPU1_SB_RSP<0>")
	)
	(segment
		(start 58.825638 -270.010382)
		(end 59.122056 -269.713964)
		(width 0.11684)
		(layer "In4.Cu")
		(net "M_D_CPU1_SB_RSP<0>")
	)
	(segment
		(start 52.989988 -270.010382)
		(end 53.22189 -270.010382)
		(width 0.11684)
		(layer "In4.Cu")
		(net "M_D_CPU1_SB_RSP<0>")
	)
	(segment
		(start 91.079828 -267.862558)
		(end 90.930984 -267.606272)
		(width 0.0889)
		(layer "In4.Cu")
		(net "M_D_CPU1_SB_RSP<0>")
	)
	(segment
		(start 88.294972 -267.923264)
		(end 88.30564 -267.917168)
		(width 0.0889)
		(layer "In4.Cu")
		(net "M_D_CPU1_SB_RSP<0>")
	)
	(segment
		(start 59.882278 -270.010382)
		(end 60.178696 -269.713964)
		(width 0.11684)
		(layer "In4.Cu")
		(net "M_D_CPU1_SB_RSP<0>")
	)
	(segment
		(start 78.528164 -267.923264)
		(end 78.544674 -267.932662)
		(width 0.0889)
		(layer "In4.Cu")
		(net "M_D_CPU1_SB_RSP<0>")
	)
	(segment
		(start 77.817726 -267.230606)
		(end 78.452218 -267.865098)
		(width 0.0889)
		(layer "In4.Cu")
		(net "M_D_CPU1_SB_RSP<0>")
	)
	(segment
		(start 52.461668 -269.713964)
		(end 52.69357 -269.713964)
		(width 0.11684)
		(layer "In4.Cu")
		(net "M_D_CPU1_SB_RSP<0>")
	)
	(segment
		(start 59.122056 -269.713964)
		(end 59.353958 -269.713964)
		(width 0.11684)
		(layer "In4.Cu")
		(net "M_D_CPU1_SB_RSP<0>")
	)
	(segment
		(start 52.16525 -270.010382)
		(end 52.461668 -269.713964)
		(width 0.11684)
		(layer "In4.Cu")
		(net "M_D_CPU1_SB_RSP<0>")
	)
	(segment
		(start 91.05646 -267.950442)
		(end 91.079828 -267.862558)
		(width 0.0889)
		(layer "In4.Cu")
		(net "M_D_CPU1_SB_RSP<0>")
	)
	(segment
		(start 55.952136 -269.713964)
		(end 56.184038 -269.713964)
		(width 0.11684)
		(layer "In4.Cu")
		(net "M_D_CPU1_SB_RSP<0>")
	)
	(segment
		(start 38.312598 -269.739364)
		(end 38.583616 -270.010382)
		(width 0.11684)
		(layer "In4.Cu")
		(net "M_D_CPU1_SB_RSP<0>")
	)
	(segment
		(start 76.451968 -266.851384)
		(end 76.83119 -267.230606)
		(width 0.0889)
		(layer "In4.Cu")
		(net "M_D_CPU1_SB_RSP<0>")
	)
	(segment
		(start 57.240678 -269.713964)
		(end 57.537096 -270.010382)
		(width 0.11684)
		(layer "In4.Cu")
		(net "M_D_CPU1_SB_RSP<0>")
	)
	(segment
		(start 60.543186 -269.713964)
		(end 63.405766 -266.851384)
		(width 0.11684)
		(layer "In4.Cu")
		(net "M_D_CPU1_SB_RSP<0>")
	)
	(segment
		(start 46.155356 -269.713964)
		(end 46.451774 -270.010382)
		(width 0.11684)
		(layer "In4.Cu")
		(net "M_D_CPU1_SB_RSP<0>")
	)
	(segment
		(start 45.923454 -269.713964)
		(end 46.155356 -269.713964)
		(width 0.11684)
		(layer "In4.Cu")
		(net "M_D_CPU1_SB_RSP<0>")
	)
	(segment
		(start 42.59453 -270.010382)
		(end 42.826432 -270.010382)
		(width 0.11684)
		(layer "In4.Cu")
		(net "M_D_CPU1_SB_RSP<0>")
	)
	(segment
		(start 54.046628 -270.010382)
		(end 54.27853 -270.010382)
		(width 0.11684)
		(layer "In4.Cu")
		(net "M_D_CPU1_SB_RSP<0>")
	)
	(segment
		(start 41.241472 -269.713964)
		(end 41.53789 -270.010382)
		(width 0.11684)
		(layer "In4.Cu")
		(net "M_D_CPU1_SB_RSP<0>")
	)
	(segment
		(start 79.83601 -267.923264)
		(end 79.859378 -267.909548)
		(width 0.0889)
		(layer "In4.Cu")
		(net "M_D_CPU1_SB_RSP<0>")
	)
	(segment
		(start 56.184038 -269.713964)
		(end 56.480456 -270.010382)
		(width 0.11684)
		(layer "In4.Cu")
		(net "M_D_CPU1_SB_RSP<0>")
	)
	(segment
		(start 49.09439 -270.010382)
		(end 49.390808 -269.713964)
		(width 0.11684)
		(layer "In4.Cu")
		(net "M_D_CPU1_SB_RSP<0>")
	)
	(segment
		(start 75.968606 -266.851384)
		(end 76.451968 -266.851384)
		(width 0.0889)
		(layer "In4.Cu")
		(net "M_D_CPU1_SB_RSP<0>")
	)
	(segment
		(start 38.840918 -270.010382)
		(end 39.111936 -269.739364)
		(width 0.11684)
		(layer "In4.Cu")
		(net "M_D_CPU1_SB_RSP<0>")
	)
	(segment
		(start 53.518308 -269.713964)
		(end 53.75021 -269.713964)
		(width 0.11684)
		(layer "In4.Cu")
		(net "M_D_CPU1_SB_RSP<0>")
	)
	(segment
		(start 54.574948 -269.713964)
		(end 54.80685 -269.713964)
		(width 0.11684)
		(layer "In4.Cu")
		(net "M_D_CPU1_SB_RSP<0>")
	)
	(segment
		(start 43.354752 -269.713964)
		(end 43.65117 -270.010382)
		(width 0.11684)
		(layer "In4.Cu")
		(net "M_D_CPU1_SB_RSP<0>")
	)
	(segment
		(start 86.036404 -267.917168)
		(end 86.047072 -267.923264)
		(width 0.0889)
		(layer "In4.Cu")
		(net "M_D_CPU1_SB_RSP<0>")
	)
	(segment
		(start 39.369238 -269.739364)
		(end 39.640256 -270.010382)
		(width 0.11684)
		(layer "In4.Cu")
		(net "M_D_CPU1_SB_RSP<0>")
	)
	(segment
		(start 48.334168 -269.713964)
		(end 48.56607 -269.713964)
		(width 0.11684)
		(layer "In4.Cu")
		(net "M_D_CPU1_SB_RSP<0>")
	)
	(segment
		(start 50.975768 -270.010382)
		(end 52.16525 -270.010382)
		(width 0.11684)
		(layer "In4.Cu")
		(net "M_D_CPU1_SB_RSP<0>")
	)
	(segment
		(start 57.537096 -270.010382)
		(end 57.768998 -270.010382)
		(width 0.11684)
		(layer "In4.Cu")
		(net "M_D_CPU1_SB_RSP<0>")
	)
	(segment
		(start 38.583616 -270.010382)
		(end 38.840918 -270.010382)
		(width 0.11684)
		(layer "In4.Cu")
		(net "M_D_CPU1_SB_RSP<0>")
	)
	(segment
		(start 37.220906 -270.010382)
		(end 37.784278 -270.010382)
		(width 0.11684)
		(layer "In4.Cu")
		(net "M_D_CPU1_SB_RSP<0>")
	)
	(segment
		(start 63.405766 -266.851384)
		(end 75.968606 -266.851384)
		(width 0.11684)
		(layer "In4.Cu")
		(net "M_D_CPU1_SB_RSP<0>")
	)
	(segment
		(start 48.862488 -270.010382)
		(end 49.09439 -270.010382)
		(width 0.11684)
		(layer "In4.Cu")
		(net "M_D_CPU1_SB_RSP<0>")
	)
	(segment
		(start 41.53789 -270.010382)
		(end 41.769792 -270.010382)
		(width 0.11684)
		(layer "In4.Cu")
		(net "M_D_CPU1_SB_RSP<0>")
	)
	(segment
		(start 53.22189 -270.010382)
		(end 53.518308 -269.713964)
		(width 0.11684)
		(layer "In4.Cu")
		(net "M_D_CPU1_SB_RSP<0>")
	)
	(segment
		(start 46.980094 -269.713964)
		(end 47.211996 -269.713964)
		(width 0.11684)
		(layer "In4.Cu")
		(net "M_D_CPU1_SB_RSP<0>")
	)
	(segment
		(start 43.12285 -269.713964)
		(end 43.354752 -269.713964)
		(width 0.11684)
		(layer "In4.Cu")
		(net "M_D_CPU1_SB_RSP<0>")
	)
	(segment
		(start 40.713152 -270.010382)
		(end 41.00957 -269.713964)
		(width 0.11684)
		(layer "In4.Cu")
		(net "M_D_CPU1_SB_RSP<0>")
	)
	(segment
		(start 58.593736 -270.010382)
		(end 58.825638 -270.010382)
		(width 0.11684)
		(layer "In4.Cu")
		(net "M_D_CPU1_SB_RSP<0>")
	)
	(segment
		(start 43.65117 -270.010382)
		(end 44.570396 -270.010382)
		(width 0.11684)
		(layer "In4.Cu")
		(net "M_D_CPU1_SB_RSP<0>")
	)
	(segment
		(start 50.67935 -269.713964)
		(end 50.975768 -270.010382)
		(width 0.11684)
		(layer "In4.Cu")
		(net "M_D_CPU1_SB_RSP<0>")
	)
	(segment
		(start 47.508414 -270.010382)
		(end 48.03775 -270.010382)
		(width 0.11684)
		(layer "In4.Cu")
		(net "M_D_CPU1_SB_RSP<0>")
	)
	(segment
		(start 50.15103 -270.010382)
		(end 50.447448 -269.713964)
		(width 0.11684)
		(layer "In4.Cu")
		(net "M_D_CPU1_SB_RSP<0>")
	)
	(segment
		(start 45.627036 -270.010382)
		(end 45.923454 -269.713964)
		(width 0.11684)
		(layer "In4.Cu")
		(net "M_D_CPU1_SB_RSP<0>")
	)
	(segment
		(start 44.866814 -269.713964)
		(end 45.098716 -269.713964)
		(width 0.11684)
		(layer "In4.Cu")
		(net "M_D_CPU1_SB_RSP<0>")
	)
	(segment
		(start 60.178696 -269.713964)
		(end 60.543186 -269.713964)
		(width 0.11684)
		(layer "In4.Cu")
		(net "M_D_CPU1_SB_RSP<0>")
	)
	(segment
		(start 46.683676 -270.010382)
		(end 46.980094 -269.713964)
		(width 0.11684)
		(layer "In4.Cu")
		(net "M_D_CPU1_SB_RSP<0>")
	)
	(segment
		(start 58.065416 -269.713964)
		(end 58.297318 -269.713964)
		(width 0.11684)
		(layer "In4.Cu")
		(net "M_D_CPU1_SB_RSP<0>")
	)
	(segment
		(start 59.353958 -269.713964)
		(end 59.650376 -270.010382)
		(width 0.11684)
		(layer "In4.Cu")
		(net "M_D_CPU1_SB_RSP<0>")
	)
	(segment
		(start 82.654902 -267.923264)
		(end 82.66557 -267.917168)
		(width 0.0889)
		(layer "In4.Cu")
		(net "M_D_CPU1_SB_RSP<0>")
	)
	(segment
		(start 56.712358 -270.010382)
		(end 57.008776 -269.713964)
		(width 0.11684)
		(layer "In4.Cu")
		(net "M_D_CPU1_SB_RSP<0>")
	)
	(segment
		(start 76.83119 -267.230606)
		(end 77.817726 -267.230606)
		(width 0.0889)
		(layer "In4.Cu")
		(net "M_D_CPU1_SB_RSP<0>")
	)
	(segment
		(start 55.103268 -270.010382)
		(end 55.655718 -270.010382)
		(width 0.11684)
		(layer "In4.Cu")
		(net "M_D_CPU1_SB_RSP<0>")
	)
	(segment
		(start 37.784278 -270.010382)
		(end 38.055296 -269.739364)
		(width 0.11684)
		(layer "In4.Cu")
		(net "M_D_CPU1_SB_RSP<0>")
	)
	(segment
		(start 41.769792 -270.010382)
		(end 42.06621 -269.713964)
		(width 0.11684)
		(layer "In4.Cu")
		(net "M_D_CPU1_SB_RSP<0>")
	)
	(arc
		(start 80.775048 -267.923264)
		(mid 81.061052 -267.846312)
		(end 81.347056 -267.923264)
		(width 0.0889)
		(layer "In4.Cu")
		(net "M_D_CPU1_SB_RSP<0>")
	)
	(arc
		(start 80.407256 -267.923264)
		(mid 80.591152 -267.972744)
		(end 80.775048 -267.923264)
		(width 0.0889)
		(layer "In4.Cu")
		(net "M_D_CPU1_SB_RSP<0>")
	)
	(arc
		(start 79.859378 -267.909548)
		(mid 80.135065 -267.846293)
		(end 80.407256 -267.923264)
		(width 0.0889)
		(layer "In4.Cu")
		(net "M_D_CPU1_SB_RSP<0>")
	)
	(arc
		(start 79.468218 -267.923264)
		(mid 79.638616 -267.97285)
		(end 79.812388 -267.936726)
		(width 0.0889)
		(layer "In4.Cu")
		(net "M_D_CPU1_SB_RSP<0>")
	)
	(arc
		(start 84.167218 -267.923264)
		(mid 84.351114 -267.972744)
		(end 84.53501 -267.923264)
		(width 0.0889)
		(layer "In4.Cu")
		(net "M_D_CPU1_SB_RSP<0>")
	)
	(arc
		(start 86.987126 -267.923264)
		(mid 87.171022 -267.972744)
		(end 87.354918 -267.923264)
		(width 0.0889)
		(layer "In4.Cu")
		(net "M_D_CPU1_SB_RSP<0>")
	)
	(arc
		(start 78.544674 -267.932662)
		(mid 78.72102 -267.972604)
		(end 78.89494 -267.923264)
		(width 0.0889)
		(layer "In4.Cu")
		(net "M_D_CPU1_SB_RSP<0>")
	)
	(arc
		(start 86.047072 -267.923264)
		(mid 86.230968 -267.972744)
		(end 86.414864 -267.923264)
		(width 0.0889)
		(layer "In4.Cu")
		(net "M_D_CPU1_SB_RSP<0>")
	)
	(arc
		(start 90.174826 -267.923264)
		(mid 90.45483 -267.846219)
		(end 90.73642 -267.917168)
		(width 0.0889)
		(layer "In4.Cu")
		(net "M_D_CPU1_SB_RSP<0>")
	)
	(arc
		(start 83.227164 -267.923264)
		(mid 83.41106 -267.972744)
		(end 83.594956 -267.923264)
		(width 0.0889)
		(layer "In4.Cu")
		(net "M_D_CPU1_SB_RSP<0>")
	)
	(arc
		(start 82.66557 -267.917168)
		(mid 82.947159 -267.846294)
		(end 83.227164 -267.923264)
		(width 0.0889)
		(layer "In4.Cu")
		(net "M_D_CPU1_SB_RSP<0>")
	)
	(arc
		(start 81.347056 -267.923264)
		(mid 81.530952 -267.972744)
		(end 81.714848 -267.923264)
		(width 0.0889)
		(layer "In4.Cu")
		(net "M_D_CPU1_SB_RSP<0>")
	)
	(arc
		(start 89.807034 -267.923264)
		(mid 89.99093 -267.972744)
		(end 90.174826 -267.923264)
		(width 0.0889)
		(layer "In4.Cu")
		(net "M_D_CPU1_SB_RSP<0>")
	)
	(arc
		(start 88.30564 -267.917168)
		(mid 88.587229 -267.846294)
		(end 88.867234 -267.923264)
		(width 0.0889)
		(layer "In4.Cu")
		(net "M_D_CPU1_SB_RSP<0>")
	)
	(arc
		(start 78.918308 -267.909548)
		(mid 79.19501 -267.845827)
		(end 79.468218 -267.923264)
		(width 0.0889)
		(layer "In4.Cu")
		(net "M_D_CPU1_SB_RSP<0>")
	)
	(arc
		(start 85.47481 -267.923264)
		(mid 85.754814 -267.846219)
		(end 86.036404 -267.917168)
		(width 0.0889)
		(layer "In4.Cu")
		(net "M_D_CPU1_SB_RSP<0>")
	)
	(arc
		(start 83.605624 -267.917168)
		(mid 83.887213 -267.846294)
		(end 84.167218 -267.923264)
		(width 0.0889)
		(layer "In4.Cu")
		(net "M_D_CPU1_SB_RSP<0>")
	)
	(arc
		(start 89.235026 -267.923264)
		(mid 89.52103 -267.846312)
		(end 89.807034 -267.923264)
		(width 0.0889)
		(layer "In4.Cu")
		(net "M_D_CPU1_SB_RSP<0>")
	)
	(arc
		(start 82.28711 -267.923264)
		(mid 82.471006 -267.972744)
		(end 82.654902 -267.923264)
		(width 0.0889)
		(layer "In4.Cu")
		(net "M_D_CPU1_SB_RSP<0>")
	)
	(arc
		(start 90.747088 -267.923264)
		(mid 90.898747 -267.971218)
		(end 91.05646 -267.950442)
		(width 0.0889)
		(layer "In4.Cu")
		(net "M_D_CPU1_SB_RSP<0>")
	)
	(arc
		(start 88.867234 -267.923264)
		(mid 89.05113 -267.972744)
		(end 89.235026 -267.923264)
		(width 0.0889)
		(layer "In4.Cu")
		(net "M_D_CPU1_SB_RSP<0>")
	)
	(arc
		(start 78.452218 -267.865098)
		(mid 78.488289 -267.896664)
		(end 78.528164 -267.923264)
		(width 0.0889)
		(layer "In4.Cu")
		(net "M_D_CPU1_SB_RSP<0>")
	)
	(arc
		(start 86.414864 -267.923264)
		(mid 86.694868 -267.846219)
		(end 86.976458 -267.917168)
		(width 0.0889)
		(layer "In4.Cu")
		(net "M_D_CPU1_SB_RSP<0>")
	)
	(arc
		(start 87.365586 -267.917168)
		(mid 87.647175 -267.846294)
		(end 87.92718 -267.923264)
		(width 0.0889)
		(layer "In4.Cu")
		(net "M_D_CPU1_SB_RSP<0>")
	)
	(arc
		(start 84.53501 -267.923264)
		(mid 84.821014 -267.846312)
		(end 85.107018 -267.923264)
		(width 0.0889)
		(layer "In4.Cu")
		(net "M_D_CPU1_SB_RSP<0>")
	)
	(arc
		(start 87.92718 -267.923264)
		(mid 88.111076 -267.972744)
		(end 88.294972 -267.923264)
		(width 0.0889)
		(layer "In4.Cu")
		(net "M_D_CPU1_SB_RSP<0>")
	)
	(arc
		(start 81.714848 -267.923264)
		(mid 81.994852 -267.846219)
		(end 82.276442 -267.917168)
		(width 0.0889)
		(layer "In4.Cu")
		(net "M_D_CPU1_SB_RSP<0>")
	)
	(arc
		(start 85.107018 -267.923264)
		(mid 85.290914 -267.972744)
		(end 85.47481 -267.923264)
		(width 0.0889)
		(layer "In4.Cu")
		(net "M_D_CPU1_SB_RSP<0>")
	)
	(segment
		(start 91.86799 -264.910316)
		(end 91.401138 -265.176254)
		(width 0.10668)
		(layer "F.Cu")
		(net "M_D_CPU1_SB_PAR")
	)
	(segment
		(start 90.639646 -264.848848)
		(end 90.648028 -264.853674)
		(width 0.0889)
		(layer "In4.Cu")
		(net "M_D_CPU1_SB_PAR")
	)
	(segment
		(start 88.394032 -264.853674)
		(end 88.402414 -264.848848)
		(width 0.0889)
		(layer "In4.Cu")
		(net "M_D_CPU1_SB_PAR")
	)
	(segment
		(start 91.150694 -264.885424)
		(end 91.24696 -264.910824)
		(width 0.0889)
		(layer "In4.Cu")
		(net "M_D_CPU1_SB_PAR")
	)
	(segment
		(start 87.453978 -264.853674)
		(end 87.46236 -264.848848)
		(width 0.0889)
		(layer "In4.Cu")
		(net "M_D_CPU1_SB_PAR")
	)
	(segment
		(start 78.977744 -264.863072)
		(end 78.993492 -264.853928)
		(width 0.0889)
		(layer "In4.Cu")
		(net "M_D_CPU1_SB_PAR")
	)
	(segment
		(start 32.695896 -267.03528)
		(end 33.120838 -266.610338)
		(width 0.14478)
		(layer "In4.Cu")
		(net "M_D_CPU1_SB_PAR")
	)
	(segment
		(start 91.24696 -264.910824)
		(end 91.401138 -265.176254)
		(width 0.0889)
		(layer "In4.Cu")
		(net "M_D_CPU1_SB_PAR")
	)
	(segment
		(start 75.966066 -265.074654)
		(end 76.304902 -265.074654)
		(width 0.0889)
		(layer "In4.Cu")
		(net "M_D_CPU1_SB_PAR")
	)
	(segment
		(start 85.93963 -264.848848)
		(end 85.948012 -264.853674)
		(width 0.0889)
		(layer "In4.Cu")
		(net "M_D_CPU1_SB_PAR")
	)
	(segment
		(start 60.294012 -266.610338)
		(end 61.829696 -265.074654)
		(width 0.14478)
		(layer "In4.Cu")
		(net "M_D_CPU1_SB_PAR")
	)
	(segment
		(start 86.879684 -264.848848)
		(end 86.888066 -264.853674)
		(width 0.0889)
		(layer "In4.Cu")
		(net "M_D_CPU1_SB_PAR")
	)
	(segment
		(start 79.36738 -264.853674)
		(end 79.377794 -264.85977)
		(width 0.0889)
		(layer "In4.Cu")
		(net "M_D_CPU1_SB_PAR")
	)
	(segment
		(start 76.85151 -264.528046)
		(end 78.075282 -264.528046)
		(width 0.0889)
		(layer "In4.Cu")
		(net "M_D_CPU1_SB_PAR")
	)
	(segment
		(start 76.304902 -265.074654)
		(end 76.85151 -264.528046)
		(width 0.0889)
		(layer "In4.Cu")
		(net "M_D_CPU1_SB_PAR")
	)
	(segment
		(start 82.179668 -264.848848)
		(end 82.18805 -264.853674)
		(width 0.0889)
		(layer "In4.Cu")
		(net "M_D_CPU1_SB_PAR")
	)
	(segment
		(start 83.119722 -264.848848)
		(end 83.128104 -264.853674)
		(width 0.0889)
		(layer "In4.Cu")
		(net "M_D_CPU1_SB_PAR")
	)
	(segment
		(start 80.299814 -264.848848)
		(end 80.308196 -264.853674)
		(width 0.0889)
		(layer "In4.Cu")
		(net "M_D_CPU1_SB_PAR")
	)
	(segment
		(start 83.694016 -264.853674)
		(end 83.702398 -264.848848)
		(width 0.0889)
		(layer "In4.Cu")
		(net "M_D_CPU1_SB_PAR")
	)
	(segment
		(start 78.993492 -264.853928)
		(end 79.009748 -264.84453)
		(width 0.0889)
		(layer "In4.Cu")
		(net "M_D_CPU1_SB_PAR")
	)
	(segment
		(start 33.120838 -266.610338)
		(end 60.294012 -266.610338)
		(width 0.14478)
		(layer "In4.Cu")
		(net "M_D_CPU1_SB_PAR")
	)
	(segment
		(start 78.075282 -264.528046)
		(end 78.312264 -264.765028)
		(width 0.0889)
		(layer "In4.Cu")
		(net "M_D_CPU1_SB_PAR")
	)
	(segment
		(start 61.829696 -265.074654)
		(end 75.966066 -265.074654)
		(width 0.14478)
		(layer "In4.Cu")
		(net "M_D_CPU1_SB_PAR")
	)
	(arc
		(start 82.753962 -264.853674)
		(mid 82.936213 -264.803324)
		(end 83.119722 -264.848848)
		(width 0.0889)
		(layer "In4.Cu")
		(net "M_D_CPU1_SB_PAR")
	)
	(arc
		(start 83.128104 -264.853674)
		(mid 83.41106 -264.929851)
		(end 83.694016 -264.853674)
		(width 0.0889)
		(layer "In4.Cu")
		(net "M_D_CPU1_SB_PAR")
	)
	(arc
		(start 79.377794 -264.85977)
		(mid 79.65648 -264.92999)
		(end 79.933546 -264.853674)
		(width 0.0889)
		(layer "In4.Cu")
		(net "M_D_CPU1_SB_PAR")
	)
	(arc
		(start 85.57387 -264.853674)
		(mid 85.756121 -264.803324)
		(end 85.93963 -264.848848)
		(width 0.0889)
		(layer "In4.Cu")
		(net "M_D_CPU1_SB_PAR")
	)
	(arc
		(start 89.707974 -264.853674)
		(mid 89.99093 -264.929851)
		(end 90.273886 -264.853674)
		(width 0.0889)
		(layer "In4.Cu")
		(net "M_D_CPU1_SB_PAR")
	)
	(arc
		(start 85.948012 -264.853674)
		(mid 86.230968 -264.929851)
		(end 86.513924 -264.853674)
		(width 0.0889)
		(layer "In4.Cu")
		(net "M_D_CPU1_SB_PAR")
	)
	(arc
		(start 82.18805 -264.853674)
		(mid 82.471006 -264.929851)
		(end 82.753962 -264.853674)
		(width 0.0889)
		(layer "In4.Cu")
		(net "M_D_CPU1_SB_PAR")
	)
	(arc
		(start 86.888066 -264.853674)
		(mid 87.171022 -264.929851)
		(end 87.453978 -264.853674)
		(width 0.0889)
		(layer "In4.Cu")
		(net "M_D_CPU1_SB_PAR")
	)
	(arc
		(start 81.813908 -264.853674)
		(mid 81.996159 -264.803324)
		(end 82.179668 -264.848848)
		(width 0.0889)
		(layer "In4.Cu")
		(net "M_D_CPU1_SB_PAR")
	)
	(arc
		(start 83.702398 -264.848848)
		(mid 83.885906 -264.803354)
		(end 84.068158 -264.853674)
		(width 0.0889)
		(layer "In4.Cu")
		(net "M_D_CPU1_SB_PAR")
	)
	(arc
		(start 81.247996 -264.853674)
		(mid 81.530952 -264.929851)
		(end 81.813908 -264.853674)
		(width 0.0889)
		(layer "In4.Cu")
		(net "M_D_CPU1_SB_PAR")
	)
	(arc
		(start 79.933546 -264.853674)
		(mid 80.116051 -264.803197)
		(end 80.299814 -264.848848)
		(width 0.0889)
		(layer "In4.Cu")
		(net "M_D_CPU1_SB_PAR")
	)
	(arc
		(start 84.63407 -264.853674)
		(mid 84.821014 -264.803419)
		(end 85.007958 -264.853674)
		(width 0.0889)
		(layer "In4.Cu")
		(net "M_D_CPU1_SB_PAR")
	)
	(arc
		(start 88.768174 -264.853674)
		(mid 89.05113 -264.929851)
		(end 89.334086 -264.853674)
		(width 0.0889)
		(layer "In4.Cu")
		(net "M_D_CPU1_SB_PAR")
	)
	(arc
		(start 79.009748 -264.84453)
		(mid 79.18973 -264.80343)
		(end 79.36738 -264.853674)
		(width 0.0889)
		(layer "In4.Cu")
		(net "M_D_CPU1_SB_PAR")
	)
	(arc
		(start 78.42758 -264.853674)
		(mid 78.701435 -264.930024)
		(end 78.977744 -264.863072)
		(width 0.0889)
		(layer "In4.Cu")
		(net "M_D_CPU1_SB_PAR")
	)
	(arc
		(start 86.513924 -264.853674)
		(mid 86.696175 -264.803324)
		(end 86.879684 -264.848848)
		(width 0.0889)
		(layer "In4.Cu")
		(net "M_D_CPU1_SB_PAR")
	)
	(arc
		(start 85.007958 -264.853674)
		(mid 85.290914 -264.929851)
		(end 85.57387 -264.853674)
		(width 0.0889)
		(layer "In4.Cu")
		(net "M_D_CPU1_SB_PAR")
	)
	(arc
		(start 89.334086 -264.853674)
		(mid 89.52103 -264.803419)
		(end 89.707974 -264.853674)
		(width 0.0889)
		(layer "In4.Cu")
		(net "M_D_CPU1_SB_PAR")
	)
	(arc
		(start 90.648028 -264.853674)
		(mid 90.895624 -264.928852)
		(end 91.150694 -264.885424)
		(width 0.0889)
		(layer "In4.Cu")
		(net "M_D_CPU1_SB_PAR")
	)
	(arc
		(start 87.82812 -264.853674)
		(mid 88.111076 -264.929851)
		(end 88.394032 -264.853674)
		(width 0.0889)
		(layer "In4.Cu")
		(net "M_D_CPU1_SB_PAR")
	)
	(arc
		(start 88.402414 -264.848848)
		(mid 88.585922 -264.803354)
		(end 88.768174 -264.853674)
		(width 0.0889)
		(layer "In4.Cu")
		(net "M_D_CPU1_SB_PAR")
	)
	(arc
		(start 80.874108 -264.853674)
		(mid 81.061052 -264.803419)
		(end 81.247996 -264.853674)
		(width 0.0889)
		(layer "In4.Cu")
		(net "M_D_CPU1_SB_PAR")
	)
	(arc
		(start 84.068158 -264.853674)
		(mid 84.351114 -264.929851)
		(end 84.63407 -264.853674)
		(width 0.0889)
		(layer "In4.Cu")
		(net "M_D_CPU1_SB_PAR")
	)
	(arc
		(start 87.46236 -264.848848)
		(mid 87.645868 -264.803354)
		(end 87.82812 -264.853674)
		(width 0.0889)
		(layer "In4.Cu")
		(net "M_D_CPU1_SB_PAR")
	)
	(arc
		(start 80.308196 -264.853674)
		(mid 80.591152 -264.929851)
		(end 80.874108 -264.853674)
		(width 0.0889)
		(layer "In4.Cu")
		(net "M_D_CPU1_SB_PAR")
	)
	(arc
		(start 78.312264 -264.765028)
		(mid 78.367049 -264.813088)
		(end 78.42758 -264.853674)
		(width 0.0889)
		(layer "In4.Cu")
		(net "M_D_CPU1_SB_PAR")
	)
	(arc
		(start 90.273886 -264.853674)
		(mid 90.456137 -264.803324)
		(end 90.639646 -264.848848)
		(width 0.0889)
		(layer "In4.Cu")
		(net "M_D_CPU1_SB_PAR")
	)
	(segment
		(start 91.397836 -270.580358)
		(end 90.930984 -270.846296)
		(width 0.12954)
		(layer "F.Cu")
		(net "M_D_CPU1_SB_DQS_DP<9>")
	)
	(segment
		(start 39.4208 -275.519134)
		(end 39.53764 -275.635974)
		(width 0.16002)
		(layer "In4.Cu")
		(net "M_D_CPU1_SB_DQS_DP<9>")
	)
	(segment
		(start 75.972924 -269.533624)
		(end 75.996546 -269.533624)
		(width 0.09525)
		(layer "In4.Cu")
		(net "M_D_CPU1_SB_DQS_DP<9>")
	)
	(segment
		(start 91.084908 -271.111726)
		(end 90.930984 -270.846296)
		(width 0.09525)
		(layer "In4.Cu")
		(net "M_D_CPU1_SB_DQS_DP<9>")
	)
	(segment
		(start 51.353466 -274.685252)
		(end 51.914044 -274.685252)
		(width 0.16002)
		(layer "In4.Cu")
		(net "M_D_CPU1_SB_DQS_DP<9>")
	)
	(segment
		(start 55.857648 -274.773898)
		(end 55.857648 -275.79193)
		(width 0.16002)
		(layer "In4.Cu")
		(net "M_D_CPU1_SB_DQS_DP<9>")
	)
	(segment
		(start 89.802462 -271.171416)
		(end 89.810844 -271.176242)
		(width 0.09525)
		(layer "In4.Cu")
		(net "M_D_CPU1_SB_DQS_DP<9>")
	)
	(segment
		(start 55.857648 -275.79193)
		(end 56.053482 -275.987764)
		(width 0.16002)
		(layer "In4.Cu")
		(net "M_D_CPU1_SB_DQS_DP<9>")
	)
	(segment
		(start 83.591146 -271.176242)
		(end 83.599528 -271.171416)
		(width 0.09525)
		(layer "In4.Cu")
		(net "M_D_CPU1_SB_DQS_DP<9>")
	)
	(segment
		(start 36.795964 -275.53539)
		(end 37.069776 -275.809202)
		(width 0.16002)
		(layer "In4.Cu")
		(net "M_D_CPU1_SB_DQS_DP<9>")
	)
	(segment
		(start 46.891702 -274.405598)
		(end 46.891702 -275.43252)
		(width 0.16002)
		(layer "In4.Cu")
		(net "M_D_CPU1_SB_DQS_DP<9>")
	)
	(segment
		(start 49.379886 -275.975064)
		(end 50.179986 -275.174964)
		(width 0.16002)
		(layer "In4.Cu")
		(net "M_D_CPU1_SB_DQS_DP<9>")
	)
	(segment
		(start 46.51883 -274.032726)
		(end 46.891702 -274.405598)
		(width 0.16002)
		(layer "In4.Cu")
		(net "M_D_CPU1_SB_DQS_DP<9>")
	)
	(segment
		(start 52.61229 -273.987006)
		(end 53.47081 -273.987006)
		(width 0.16002)
		(layer "In4.Cu")
		(net "M_D_CPU1_SB_DQS_DP<9>")
	)
	(segment
		(start 84.5312 -271.176242)
		(end 84.539582 -271.171416)
		(width 0.09525)
		(layer "In4.Cu")
		(net "M_D_CPU1_SB_DQS_DP<9>")
	)
	(segment
		(start 45.618908 -274.405598)
		(end 45.99178 -274.032726)
		(width 0.16002)
		(layer "In4.Cu")
		(net "M_D_CPU1_SB_DQS_DP<9>")
	)
	(segment
		(start 37.069776 -275.809202)
		(end 37.953696 -275.809202)
		(width 0.16002)
		(layer "In4.Cu")
		(net "M_D_CPU1_SB_DQS_DP<9>")
	)
	(segment
		(start 43.118786 -275.149564)
		(end 43.48988 -274.77847)
		(width 0.16002)
		(layer "In4.Cu")
		(net "M_D_CPU1_SB_DQS_DP<9>")
	)
	(segment
		(start 59.749944 -275.149564)
		(end 65.365884 -269.533624)
		(width 0.16002)
		(layer "In4.Cu")
		(net "M_D_CPU1_SB_DQS_DP<9>")
	)
	(segment
		(start 50.179986 -275.174964)
		(end 50.863754 -275.174964)
		(width 0.16002)
		(layer "In4.Cu")
		(net "M_D_CPU1_SB_DQS_DP<9>")
	)
	(segment
		(start 54.039516 -275.987764)
		(end 54.38902 -275.987764)
		(width 0.16002)
		(layer "In4.Cu")
		(net "M_D_CPU1_SB_DQS_DP<9>")
	)
	(segment
		(start 45.99178 -274.032726)
		(end 46.51883 -274.032726)
		(width 0.16002)
		(layer "In4.Cu")
		(net "M_D_CPU1_SB_DQS_DP<9>")
	)
	(segment
		(start 46.891702 -275.43252)
		(end 47.087536 -275.628354)
		(width 0.16002)
		(layer "In4.Cu")
		(net "M_D_CPU1_SB_DQS_DP<9>")
	)
	(segment
		(start 53.843682 -275.79193)
		(end 54.039516 -275.987764)
		(width 0.16002)
		(layer "In4.Cu")
		(net "M_D_CPU1_SB_DQS_DP<9>")
	)
	(segment
		(start 55.484776 -274.401026)
		(end 55.857648 -274.773898)
		(width 0.16002)
		(layer "In4.Cu")
		(net "M_D_CPU1_SB_DQS_DP<9>")
	)
	(segment
		(start 76.833476 -270.143986)
		(end 77.46111 -270.143986)
		(width 0.09525)
		(layer "In4.Cu")
		(net "M_D_CPU1_SB_DQS_DP<9>")
	)
	(segment
		(start 54.38902 -275.987764)
		(end 54.584854 -275.79193)
		(width 0.16002)
		(layer "In4.Cu")
		(net "M_D_CPU1_SB_DQS_DP<9>")
	)
	(segment
		(start 42.636186 -275.149564)
		(end 43.118786 -275.149564)
		(width 0.16002)
		(layer "In4.Cu")
		(net "M_D_CPU1_SB_DQS_DP<9>")
	)
	(segment
		(start 45.618908 -274.61845)
		(end 45.618908 -274.405598)
		(width 0.16002)
		(layer "In4.Cu")
		(net "M_D_CPU1_SB_DQS_DP<9>")
	)
	(segment
		(start 91.06154 -271.198594)
		(end 91.084908 -271.111726)
		(width 0.09525)
		(layer "In4.Cu")
		(net "M_D_CPU1_SB_DQS_DP<9>")
	)
	(segment
		(start 80.771238 -271.176242)
		(end 80.77962 -271.171416)
		(width 0.09525)
		(layer "In4.Cu")
		(net "M_D_CPU1_SB_DQS_DP<9>")
	)
	(segment
		(start 54.584854 -275.79193)
		(end 54.584854 -274.773898)
		(width 0.16002)
		(layer "In4.Cu")
		(net "M_D_CPU1_SB_DQS_DP<9>")
	)
	(segment
		(start 38.126924 -275.635974)
		(end 38.8239 -275.635974)
		(width 0.16002)
		(layer "In4.Cu")
		(net "M_D_CPU1_SB_DQS_DP<9>")
	)
	(segment
		(start 77.46111 -270.143986)
		(end 78.540102 -271.222978)
		(width 0.09525)
		(layer "In4.Cu")
		(net "M_D_CPU1_SB_DQS_DP<9>")
	)
	(segment
		(start 85.102446 -271.171416)
		(end 85.110828 -271.176242)
		(width 0.09525)
		(layer "In4.Cu")
		(net "M_D_CPU1_SB_DQS_DP<9>")
	)
	(segment
		(start 56.936386 -275.987764)
		(end 57.774586 -275.149564)
		(width 0.16002)
		(layer "In4.Cu")
		(net "M_D_CPU1_SB_DQS_DP<9>")
	)
	(segment
		(start 65.365884 -269.533624)
		(end 75.972924 -269.533624)
		(width 0.16002)
		(layer "In4.Cu")
		(net "M_D_CPU1_SB_DQS_DP<9>")
	)
	(segment
		(start 47.087536 -275.628354)
		(end 48.626776 -275.628354)
		(width 0.16002)
		(layer "In4.Cu")
		(net "M_D_CPU1_SB_DQS_DP<9>")
	)
	(segment
		(start 81.342484 -271.171416)
		(end 81.350866 -271.176242)
		(width 0.09525)
		(layer "In4.Cu")
		(net "M_D_CPU1_SB_DQS_DP<9>")
	)
	(segment
		(start 38.94074 -275.519134)
		(end 39.4208 -275.519134)
		(width 0.16002)
		(layer "In4.Cu")
		(net "M_D_CPU1_SB_DQS_DP<9>")
	)
	(segment
		(start 57.774586 -275.149564)
		(end 59.749944 -275.149564)
		(width 0.16002)
		(layer "In4.Cu")
		(net "M_D_CPU1_SB_DQS_DP<9>")
	)
	(segment
		(start 56.053482 -275.987764)
		(end 56.936386 -275.987764)
		(width 0.16002)
		(layer "In4.Cu")
		(net "M_D_CPU1_SB_DQS_DP<9>")
	)
	(segment
		(start 76.055728 -269.592806)
		(end 76.282296 -269.592806)
		(width 0.09525)
		(layer "In4.Cu")
		(net "M_D_CPU1_SB_DQS_DP<9>")
	)
	(segment
		(start 48.626776 -275.628354)
		(end 48.973486 -275.975064)
		(width 0.16002)
		(layer "In4.Cu")
		(net "M_D_CPU1_SB_DQS_DP<9>")
	)
	(segment
		(start 89.231216 -271.176242)
		(end 89.239598 -271.171416)
		(width 0.09525)
		(layer "In4.Cu")
		(net "M_D_CPU1_SB_DQS_DP<9>")
	)
	(segment
		(start 43.48988 -274.77847)
		(end 45.458888 -274.77847)
		(width 0.16002)
		(layer "In4.Cu")
		(net "M_D_CPU1_SB_DQS_DP<9>")
	)
	(segment
		(start 90.742516 -271.171416)
		(end 90.750898 -271.176242)
		(width 0.09525)
		(layer "In4.Cu")
		(net "M_D_CPU1_SB_DQS_DP<9>")
	)
	(segment
		(start 48.973486 -275.975064)
		(end 49.379886 -275.975064)
		(width 0.16002)
		(layer "In4.Cu")
		(net "M_D_CPU1_SB_DQS_DP<9>")
	)
	(segment
		(start 88.291162 -271.176242)
		(end 88.299544 -271.171416)
		(width 0.09525)
		(layer "In4.Cu")
		(net "M_D_CPU1_SB_DQS_DP<9>")
	)
	(segment
		(start 78.540102 -271.222978)
		(end 79.650336 -271.222978)
		(width 0.09525)
		(layer "In4.Cu")
		(net "M_D_CPU1_SB_DQS_DP<9>")
	)
	(segment
		(start 80.392016 -271.16532)
		(end 80.40243 -271.171416)
		(width 0.09525)
		(layer "In4.Cu")
		(net "M_D_CPU1_SB_DQS_DP<9>")
	)
	(segment
		(start 41.455086 -275.975064)
		(end 41.810686 -275.975064)
		(width 0.16002)
		(layer "In4.Cu")
		(net "M_D_CPU1_SB_DQS_DP<9>")
	)
	(segment
		(start 75.996546 -269.533624)
		(end 76.055728 -269.592806)
		(width 0.09525)
		(layer "In4.Cu")
		(net "M_D_CPU1_SB_DQS_DP<9>")
	)
	(segment
		(start 53.47081 -273.987006)
		(end 53.843682 -274.359878)
		(width 0.16002)
		(layer "In4.Cu")
		(net "M_D_CPU1_SB_DQS_DP<9>")
	)
	(segment
		(start 51.914044 -274.685252)
		(end 52.61229 -273.987006)
		(width 0.16002)
		(layer "In4.Cu")
		(net "M_D_CPU1_SB_DQS_DP<9>")
	)
	(segment
		(start 76.282296 -269.592806)
		(end 76.833476 -270.143986)
		(width 0.09525)
		(layer "In4.Cu")
		(net "M_D_CPU1_SB_DQS_DP<9>")
	)
	(segment
		(start 86.0425 -271.171416)
		(end 86.050882 -271.176242)
		(width 0.09525)
		(layer "In4.Cu")
		(net "M_D_CPU1_SB_DQS_DP<9>")
	)
	(segment
		(start 41.810686 -275.975064)
		(end 42.636186 -275.149564)
		(width 0.16002)
		(layer "In4.Cu")
		(net "M_D_CPU1_SB_DQS_DP<9>")
	)
	(segment
		(start 39.53764 -275.635974)
		(end 41.115996 -275.635974)
		(width 0.16002)
		(layer "In4.Cu")
		(net "M_D_CPU1_SB_DQS_DP<9>")
	)
	(segment
		(start 53.843682 -274.359878)
		(end 53.843682 -275.79193)
		(width 0.16002)
		(layer "In4.Cu")
		(net "M_D_CPU1_SB_DQS_DP<9>")
	)
	(segment
		(start 37.953696 -275.809202)
		(end 38.126924 -275.635974)
		(width 0.16002)
		(layer "In4.Cu")
		(net "M_D_CPU1_SB_DQS_DP<9>")
	)
	(segment
		(start 45.458888 -274.77847)
		(end 45.618908 -274.61845)
		(width 0.16002)
		(layer "In4.Cu")
		(net "M_D_CPU1_SB_DQS_DP<9>")
	)
	(segment
		(start 50.863754 -275.174964)
		(end 51.353466 -274.685252)
		(width 0.16002)
		(layer "In4.Cu")
		(net "M_D_CPU1_SB_DQS_DP<9>")
	)
	(segment
		(start 54.957726 -274.401026)
		(end 55.484776 -274.401026)
		(width 0.16002)
		(layer "In4.Cu")
		(net "M_D_CPU1_SB_DQS_DP<9>")
	)
	(segment
		(start 41.115996 -275.635974)
		(end 41.455086 -275.975064)
		(width 0.16002)
		(layer "In4.Cu")
		(net "M_D_CPU1_SB_DQS_DP<9>")
	)
	(segment
		(start 38.8239 -275.635974)
		(end 38.94074 -275.519134)
		(width 0.16002)
		(layer "In4.Cu")
		(net "M_D_CPU1_SB_DQS_DP<9>")
	)
	(segment
		(start 54.584854 -274.773898)
		(end 54.957726 -274.401026)
		(width 0.16002)
		(layer "In4.Cu")
		(net "M_D_CPU1_SB_DQS_DP<9>")
	)
	(arc
		(start 81.719674 -271.171416)
		(mid 82.001106 -271.095661)
		(end 82.282538 -271.171416)
		(width 0.09525)
		(layer "In4.Cu")
		(net "M_D_CPU1_SB_DQS_DP<9>")
	)
	(arc
		(start 80.40243 -271.171416)
		(mid 80.586205 -271.222188)
		(end 80.771238 -271.176242)
		(width 0.09525)
		(layer "In4.Cu")
		(net "M_D_CPU1_SB_DQS_DP<9>")
	)
	(arc
		(start 82.282538 -271.171416)
		(mid 82.471006 -271.222093)
		(end 82.659474 -271.171416)
		(width 0.09525)
		(layer "In4.Cu")
		(net "M_D_CPU1_SB_DQS_DP<9>")
	)
	(arc
		(start 86.050882 -271.176242)
		(mid 86.235914 -271.222156)
		(end 86.41969 -271.171416)
		(width 0.09525)
		(layer "In4.Cu")
		(net "M_D_CPU1_SB_DQS_DP<9>")
	)
	(arc
		(start 90.750898 -271.176242)
		(mid 90.903793 -271.22107)
		(end 91.06154 -271.198594)
		(width 0.09525)
		(layer "In4.Cu")
		(net "M_D_CPU1_SB_DQS_DP<9>")
	)
	(arc
		(start 81.350866 -271.176242)
		(mid 81.535898 -271.222156)
		(end 81.719674 -271.171416)
		(width 0.09525)
		(layer "In4.Cu")
		(net "M_D_CPU1_SB_DQS_DP<9>")
	)
	(arc
		(start 85.110828 -271.176242)
		(mid 85.29586 -271.222156)
		(end 85.479636 -271.171416)
		(width 0.09525)
		(layer "In4.Cu")
		(net "M_D_CPU1_SB_DQS_DP<9>")
	)
	(arc
		(start 84.162392 -271.171416)
		(mid 84.346167 -271.222188)
		(end 84.5312 -271.176242)
		(width 0.09525)
		(layer "In4.Cu")
		(net "M_D_CPU1_SB_DQS_DP<9>")
	)
	(arc
		(start 79.650336 -271.222978)
		(mid 79.748233 -271.209692)
		(end 79.839312 -271.171416)
		(width 0.09525)
		(layer "In4.Cu")
		(net "M_D_CPU1_SB_DQS_DP<9>")
	)
	(arc
		(start 85.479636 -271.171416)
		(mid 85.761068 -271.095661)
		(end 86.0425 -271.171416)
		(width 0.09525)
		(layer "In4.Cu")
		(net "M_D_CPU1_SB_DQS_DP<9>")
	)
	(arc
		(start 80.77962 -271.171416)
		(mid 81.061052 -271.095661)
		(end 81.342484 -271.171416)
		(width 0.09525)
		(layer "In4.Cu")
		(net "M_D_CPU1_SB_DQS_DP<9>")
	)
	(arc
		(start 82.659474 -271.171416)
		(mid 82.940906 -271.095661)
		(end 83.222338 -271.171416)
		(width 0.09525)
		(layer "In4.Cu")
		(net "M_D_CPU1_SB_DQS_DP<9>")
	)
	(arc
		(start 83.599528 -271.171416)
		(mid 83.88096 -271.095661)
		(end 84.162392 -271.171416)
		(width 0.09525)
		(layer "In4.Cu")
		(net "M_D_CPU1_SB_DQS_DP<9>")
	)
	(arc
		(start 83.222338 -271.171416)
		(mid 83.406113 -271.222188)
		(end 83.591146 -271.176242)
		(width 0.09525)
		(layer "In4.Cu")
		(net "M_D_CPU1_SB_DQS_DP<9>")
	)
	(arc
		(start 86.982554 -271.171416)
		(mid 87.171022 -271.222093)
		(end 87.35949 -271.171416)
		(width 0.09525)
		(layer "In4.Cu")
		(net "M_D_CPU1_SB_DQS_DP<9>")
	)
	(arc
		(start 90.179652 -271.171416)
		(mid 90.461084 -271.095661)
		(end 90.742516 -271.171416)
		(width 0.09525)
		(layer "In4.Cu")
		(net "M_D_CPU1_SB_DQS_DP<9>")
	)
	(arc
		(start 88.862408 -271.171416)
		(mid 89.046183 -271.222188)
		(end 89.231216 -271.176242)
		(width 0.09525)
		(layer "In4.Cu")
		(net "M_D_CPU1_SB_DQS_DP<9>")
	)
	(arc
		(start 87.922354 -271.171416)
		(mid 88.106129 -271.222188)
		(end 88.291162 -271.176242)
		(width 0.09525)
		(layer "In4.Cu")
		(net "M_D_CPU1_SB_DQS_DP<9>")
	)
	(arc
		(start 86.41969 -271.171416)
		(mid 86.701122 -271.095661)
		(end 86.982554 -271.171416)
		(width 0.09525)
		(layer "In4.Cu")
		(net "M_D_CPU1_SB_DQS_DP<9>")
	)
	(arc
		(start 89.239598 -271.171416)
		(mid 89.52103 -271.095661)
		(end 89.802462 -271.171416)
		(width 0.09525)
		(layer "In4.Cu")
		(net "M_D_CPU1_SB_DQS_DP<9>")
	)
	(arc
		(start 88.299544 -271.171416)
		(mid 88.580976 -271.095661)
		(end 88.862408 -271.171416)
		(width 0.09525)
		(layer "In4.Cu")
		(net "M_D_CPU1_SB_DQS_DP<9>")
	)
	(arc
		(start 87.35949 -271.171416)
		(mid 87.640922 -271.095661)
		(end 87.922354 -271.171416)
		(width 0.09525)
		(layer "In4.Cu")
		(net "M_D_CPU1_SB_DQS_DP<9>")
	)
	(arc
		(start 84.539582 -271.171416)
		(mid 84.821014 -271.095661)
		(end 85.102446 -271.171416)
		(width 0.09525)
		(layer "In4.Cu")
		(net "M_D_CPU1_SB_DQS_DP<9>")
	)
	(arc
		(start 89.810844 -271.176242)
		(mid 89.995876 -271.222156)
		(end 90.179652 -271.171416)
		(width 0.09525)
		(layer "In4.Cu")
		(net "M_D_CPU1_SB_DQS_DP<9>")
	)
	(arc
		(start 79.839312 -271.171416)
		(mid 80.114855 -271.095567)
		(end 80.392016 -271.16532)
		(width 0.09525)
		(layer "In4.Cu")
		(net "M_D_CPU1_SB_DQS_DP<9>")
	)
	(segment
		(start 93.277944 -291.64026)
		(end 92.811092 -291.906198)
		(width 0.12954)
		(layer "F.Cu")
		(net "M_D_CPU1_SB_DQS_DP<8>")
	)
	(segment
		(start 34.247074 -314.097924)
		(end 35.505136 -314.097924)
		(width 0.16002)
		(layer "In4.Cu")
		(net "M_D_CPU1_SB_DQS_DP<8>")
	)
	(segment
		(start 62.376304 -312.928762)
		(end 74.65441 -300.650656)
		(width 0.16002)
		(layer "In4.Cu")
		(net "M_D_CPU1_SB_DQS_DP<8>")
	)
	(segment
		(start 57.842658 -314.197746)
		(end 59.313064 -314.197746)
		(width 0.16002)
		(layer "In4.Cu")
		(net "M_D_CPU1_SB_DQS_DP<8>")
	)
	(segment
		(start 74.65441 -300.650656)
		(end 74.65441 -298.248324)
		(width 0.16002)
		(layer "In4.Cu")
		(net "M_D_CPU1_SB_DQS_DP<8>")
	)
	(segment
		(start 77.375004 -295.44518)
		(end 77.374496 -295.444926)
		(width 0.09525)
		(layer "In4.Cu")
		(net "M_D_CPU1_SB_DQS_DP<8>")
	)
	(segment
		(start 77.869796 -294.099488)
		(end 78.98765 -292.426644)
		(width 0.09525)
		(layer "In4.Cu")
		(net "M_D_CPU1_SB_DQS_DP<8>")
	)
	(segment
		(start 88.291162 -291.576252)
		(end 88.299544 -291.581078)
		(width 0.09525)
		(layer "In4.Cu")
		(net "M_D_CPU1_SB_DQS_DP<8>")
	)
	(segment
		(start 42.751756 -314.195206)
		(end 42.764202 -314.186824)
		(width 0.16002)
		(layer "In4.Cu")
		(net "M_D_CPU1_SB_DQS_DP<8>")
	)
	(segment
		(start 47.938944 -315.360558)
		(end 49.587658 -314.677552)
		(width 0.16002)
		(layer "In4.Cu")
		(net "M_D_CPU1_SB_DQS_DP<8>")
	)
	(segment
		(start 90.742516 -291.581078)
		(end 90.750898 -291.576252)
		(width 0.09525)
		(layer "In4.Cu")
		(net "M_D_CPU1_SB_DQS_DP<8>")
	)
	(segment
		(start 41.008046 -315.360558)
		(end 42.751756 -314.195206)
		(width 0.16002)
		(layer "In4.Cu")
		(net "M_D_CPU1_SB_DQS_DP<8>")
	)
	(segment
		(start 92.55633 -291.614098)
		(end 92.657168 -291.640768)
		(width 0.09525)
		(layer "In4.Cu")
		(net "M_D_CPU1_SB_DQS_DP<8>")
	)
	(segment
		(start 35.934142 -314.52693)
		(end 37.661342 -314.52693)
		(width 0.16002)
		(layer "In4.Cu")
		(net "M_D_CPU1_SB_DQS_DP<8>")
	)
	(segment
		(start 37.661342 -314.52693)
		(end 38.49497 -315.360558)
		(width 0.16002)
		(layer "In4.Cu")
		(net "M_D_CPU1_SB_DQS_DP<8>")
	)
	(segment
		(start 77.374496 -295.444926)
		(end 77.72654 -295.094152)
		(width 0.09525)
		(layer "In4.Cu")
		(net "M_D_CPU1_SB_DQS_DP<8>")
	)
	(segment
		(start 92.657168 -291.640768)
		(end 92.811092 -291.906198)
		(width 0.09525)
		(layer "In4.Cu")
		(net "M_D_CPU1_SB_DQS_DP<8>")
	)
	(segment
		(start 50.687986 -314.182506)
		(end 51.479704 -314.989464)
		(width 0.16002)
		(layer "In4.Cu")
		(net "M_D_CPU1_SB_DQS_DP<8>")
	)
	(segment
		(start 89.231216 -291.576252)
		(end 89.239598 -291.581078)
		(width 0.09525)
		(layer "In4.Cu")
		(net "M_D_CPU1_SB_DQS_DP<8>")
	)
	(segment
		(start 81.342484 -291.581078)
		(end 81.350866 -291.576252)
		(width 0.09525)
		(layer "In4.Cu")
		(net "M_D_CPU1_SB_DQS_DP<8>")
	)
	(segment
		(start 38.49497 -315.360558)
		(end 41.008046 -315.360558)
		(width 0.16002)
		(layer "In4.Cu")
		(net "M_D_CPU1_SB_DQS_DP<8>")
	)
	(segment
		(start 59.313064 -314.197746)
		(end 62.376304 -312.928762)
		(width 0.16002)
		(layer "In4.Cu")
		(net "M_D_CPU1_SB_DQS_DP<8>")
	)
	(segment
		(start 84.5312 -291.576252)
		(end 84.539582 -291.581078)
		(width 0.09525)
		(layer "In4.Cu")
		(net "M_D_CPU1_SB_DQS_DP<8>")
	)
	(segment
		(start 46.028864 -315.360558)
		(end 47.938944 -315.360558)
		(width 0.16002)
		(layer "In4.Cu")
		(net "M_D_CPU1_SB_DQS_DP<8>")
	)
	(segment
		(start 35.505136 -314.097924)
		(end 35.934142 -314.52693)
		(width 0.16002)
		(layer "In4.Cu")
		(net "M_D_CPU1_SB_DQS_DP<8>")
	)
	(segment
		(start 77.72654 -294.444674)
		(end 77.869796 -294.099488)
		(width 0.09525)
		(layer "In4.Cu")
		(net "M_D_CPU1_SB_DQS_DP<8>")
	)
	(segment
		(start 86.0425 -291.581078)
		(end 86.050882 -291.576252)
		(width 0.09525)
		(layer "In4.Cu")
		(net "M_D_CPU1_SB_DQS_DP<8>")
	)
	(segment
		(start 32.695896 -314.635388)
		(end 32.969708 -314.361576)
		(width 0.16002)
		(layer "In4.Cu")
		(net "M_D_CPU1_SB_DQS_DP<8>")
	)
	(segment
		(start 85.102446 -291.581078)
		(end 85.110828 -291.576252)
		(width 0.09525)
		(layer "In4.Cu")
		(net "M_D_CPU1_SB_DQS_DP<8>")
	)
	(segment
		(start 43.23207 -314.186824)
		(end 43.252136 -314.195206)
		(width 0.16002)
		(layer "In4.Cu")
		(net "M_D_CPU1_SB_DQS_DP<8>")
	)
	(segment
		(start 80.771238 -291.576252)
		(end 80.77962 -291.581078)
		(width 0.09525)
		(layer "In4.Cu")
		(net "M_D_CPU1_SB_DQS_DP<8>")
	)
	(segment
		(start 57.05094 -314.989464)
		(end 57.842658 -314.197746)
		(width 0.16002)
		(layer "In4.Cu")
		(net "M_D_CPU1_SB_DQS_DP<8>")
	)
	(segment
		(start 83.591146 -291.576252)
		(end 83.599528 -291.581078)
		(width 0.09525)
		(layer "In4.Cu")
		(net "M_D_CPU1_SB_DQS_DP<8>")
	)
	(segment
		(start 77.357478 -295.545256)
		(end 77.374242 -295.528492)
		(width 0.09525)
		(layer "In4.Cu")
		(net "M_D_CPU1_SB_DQS_DP<8>")
	)
	(segment
		(start 89.802462 -291.581078)
		(end 89.810844 -291.576252)
		(width 0.09525)
		(layer "In4.Cu")
		(net "M_D_CPU1_SB_DQS_DP<8>")
	)
	(segment
		(start 50.328322 -314.182506)
		(end 50.687986 -314.182506)
		(width 0.16002)
		(layer "In4.Cu")
		(net "M_D_CPU1_SB_DQS_DP<8>")
	)
	(segment
		(start 32.969708 -314.361576)
		(end 33.983422 -314.361576)
		(width 0.16002)
		(layer "In4.Cu")
		(net "M_D_CPU1_SB_DQS_DP<8>")
	)
	(segment
		(start 43.252136 -314.195206)
		(end 46.028864 -315.360558)
		(width 0.16002)
		(layer "In4.Cu")
		(net "M_D_CPU1_SB_DQS_DP<8>")
	)
	(segment
		(start 33.983422 -314.361576)
		(end 34.247074 -314.097924)
		(width 0.16002)
		(layer "In4.Cu")
		(net "M_D_CPU1_SB_DQS_DP<8>")
	)
	(segment
		(start 74.65441 -298.248324)
		(end 77.357478 -295.545256)
		(width 0.16002)
		(layer "In4.Cu")
		(net "M_D_CPU1_SB_DQS_DP<8>")
	)
	(segment
		(start 50.309272 -314.195206)
		(end 50.328322 -314.182506)
		(width 0.16002)
		(layer "In4.Cu")
		(net "M_D_CPU1_SB_DQS_DP<8>")
	)
	(segment
		(start 78.98765 -292.426644)
		(end 79.75727 -291.65677)
		(width 0.09525)
		(layer "In4.Cu")
		(net "M_D_CPU1_SB_DQS_DP<8>")
	)
	(segment
		(start 77.374242 -295.445688)
		(end 77.375004 -295.44518)
		(width 0.09525)
		(layer "In4.Cu")
		(net "M_D_CPU1_SB_DQS_DP<8>")
	)
	(segment
		(start 51.479704 -314.989464)
		(end 57.05094 -314.989464)
		(width 0.16002)
		(layer "In4.Cu")
		(net "M_D_CPU1_SB_DQS_DP<8>")
	)
	(segment
		(start 42.764202 -314.186824)
		(end 43.23207 -314.186824)
		(width 0.16002)
		(layer "In4.Cu")
		(net "M_D_CPU1_SB_DQS_DP<8>")
	)
	(segment
		(start 77.374242 -295.528492)
		(end 77.374242 -295.445688)
		(width 0.09525)
		(layer "In4.Cu")
		(net "M_D_CPU1_SB_DQS_DP<8>")
	)
	(segment
		(start 49.587658 -314.677552)
		(end 50.309272 -314.195206)
		(width 0.16002)
		(layer "In4.Cu")
		(net "M_D_CPU1_SB_DQS_DP<8>")
	)
	(segment
		(start 77.72654 -295.094152)
		(end 77.72654 -294.444674)
		(width 0.09525)
		(layer "In4.Cu")
		(net "M_D_CPU1_SB_DQS_DP<8>")
	)
	(segment
		(start 79.75727 -291.65677)
		(end 80.120998 -291.65677)
		(width 0.09525)
		(layer "In4.Cu")
		(net "M_D_CPU1_SB_DQS_DP<8>")
	)
	(arc
		(start 84.539582 -291.581078)
		(mid 84.821014 -291.656833)
		(end 85.102446 -291.581078)
		(width 0.09525)
		(layer "In4.Cu")
		(net "M_D_CPU1_SB_DQS_DP<8>")
	)
	(arc
		(start 80.120998 -291.65677)
		(mid 80.266706 -291.637502)
		(end 80.40243 -291.581078)
		(width 0.09525)
		(layer "In4.Cu")
		(net "M_D_CPU1_SB_DQS_DP<8>")
	)
	(arc
		(start 92.059506 -291.581078)
		(mid 92.29302 -291.654921)
		(end 92.535756 -291.622226)
		(width 0.09525)
		(layer "In4.Cu")
		(net "M_D_CPU1_SB_DQS_DP<8>")
	)
	(arc
		(start 90.179652 -291.581078)
		(mid 90.461084 -291.656833)
		(end 90.742516 -291.581078)
		(width 0.09525)
		(layer "In4.Cu")
		(net "M_D_CPU1_SB_DQS_DP<8>")
	)
	(arc
		(start 86.982554 -291.581078)
		(mid 87.171022 -291.530401)
		(end 87.35949 -291.581078)
		(width 0.09525)
		(layer "In4.Cu")
		(net "M_D_CPU1_SB_DQS_DP<8>")
	)
	(arc
		(start 82.282538 -291.581078)
		(mid 82.471006 -291.530401)
		(end 82.659474 -291.581078)
		(width 0.09525)
		(layer "In4.Cu")
		(net "M_D_CPU1_SB_DQS_DP<8>")
	)
	(arc
		(start 86.41969 -291.581078)
		(mid 86.701122 -291.656833)
		(end 86.982554 -291.581078)
		(width 0.09525)
		(layer "In4.Cu")
		(net "M_D_CPU1_SB_DQS_DP<8>")
	)
	(arc
		(start 80.77962 -291.581078)
		(mid 81.061052 -291.656833)
		(end 81.342484 -291.581078)
		(width 0.09525)
		(layer "In4.Cu")
		(net "M_D_CPU1_SB_DQS_DP<8>")
	)
	(arc
		(start 84.162392 -291.581078)
		(mid 84.346167 -291.530306)
		(end 84.5312 -291.576252)
		(width 0.09525)
		(layer "In4.Cu")
		(net "M_D_CPU1_SB_DQS_DP<8>")
	)
	(arc
		(start 82.659474 -291.581078)
		(mid 82.940906 -291.656833)
		(end 83.222338 -291.581078)
		(width 0.09525)
		(layer "In4.Cu")
		(net "M_D_CPU1_SB_DQS_DP<8>")
	)
	(arc
		(start 83.599528 -291.581078)
		(mid 83.88096 -291.656833)
		(end 84.162392 -291.581078)
		(width 0.09525)
		(layer "In4.Cu")
		(net "M_D_CPU1_SB_DQS_DP<8>")
	)
	(arc
		(start 87.922354 -291.581078)
		(mid 88.106129 -291.530306)
		(end 88.291162 -291.576252)
		(width 0.09525)
		(layer "In4.Cu")
		(net "M_D_CPU1_SB_DQS_DP<8>")
	)
	(arc
		(start 87.35949 -291.581078)
		(mid 87.640922 -291.656833)
		(end 87.922354 -291.581078)
		(width 0.09525)
		(layer "In4.Cu")
		(net "M_D_CPU1_SB_DQS_DP<8>")
	)
	(arc
		(start 80.40243 -291.581078)
		(mid 80.586205 -291.530306)
		(end 80.771238 -291.576252)
		(width 0.09525)
		(layer "In4.Cu")
		(net "M_D_CPU1_SB_DQS_DP<8>")
	)
	(arc
		(start 83.222338 -291.581078)
		(mid 83.406113 -291.530306)
		(end 83.591146 -291.576252)
		(width 0.09525)
		(layer "In4.Cu")
		(net "M_D_CPU1_SB_DQS_DP<8>")
	)
	(arc
		(start 85.479636 -291.581078)
		(mid 85.761068 -291.656833)
		(end 86.0425 -291.581078)
		(width 0.09525)
		(layer "In4.Cu")
		(net "M_D_CPU1_SB_DQS_DP<8>")
	)
	(arc
		(start 91.119706 -291.581078)
		(mid 91.401138 -291.656833)
		(end 91.68257 -291.581078)
		(width 0.09525)
		(layer "In4.Cu")
		(net "M_D_CPU1_SB_DQS_DP<8>")
	)
	(arc
		(start 85.110828 -291.576252)
		(mid 85.29586 -291.530338)
		(end 85.479636 -291.581078)
		(width 0.09525)
		(layer "In4.Cu")
		(net "M_D_CPU1_SB_DQS_DP<8>")
	)
	(arc
		(start 88.862408 -291.581078)
		(mid 89.046183 -291.530306)
		(end 89.231216 -291.576252)
		(width 0.09525)
		(layer "In4.Cu")
		(net "M_D_CPU1_SB_DQS_DP<8>")
	)
	(arc
		(start 86.050882 -291.576252)
		(mid 86.235914 -291.530338)
		(end 86.41969 -291.581078)
		(width 0.09525)
		(layer "In4.Cu")
		(net "M_D_CPU1_SB_DQS_DP<8>")
	)
	(arc
		(start 89.810844 -291.576252)
		(mid 89.995876 -291.530338)
		(end 90.179652 -291.581078)
		(width 0.09525)
		(layer "In4.Cu")
		(net "M_D_CPU1_SB_DQS_DP<8>")
	)
	(arc
		(start 92.535756 -291.622226)
		(mid 92.546084 -291.618266)
		(end 92.55633 -291.614098)
		(width 0.09525)
		(layer "In4.Cu")
		(net "M_D_CPU1_SB_DQS_DP<8>")
	)
	(arc
		(start 89.239598 -291.581078)
		(mid 89.52103 -291.656833)
		(end 89.802462 -291.581078)
		(width 0.09525)
		(layer "In4.Cu")
		(net "M_D_CPU1_SB_DQS_DP<8>")
	)
	(arc
		(start 91.68257 -291.581078)
		(mid 91.871038 -291.530401)
		(end 92.059506 -291.581078)
		(width 0.09525)
		(layer "In4.Cu")
		(net "M_D_CPU1_SB_DQS_DP<8>")
	)
	(arc
		(start 90.750898 -291.576252)
		(mid 90.93593 -291.530338)
		(end 91.119706 -291.581078)
		(width 0.09525)
		(layer "In4.Cu")
		(net "M_D_CPU1_SB_DQS_DP<8>")
	)
	(arc
		(start 88.299544 -291.581078)
		(mid 88.580976 -291.656833)
		(end 88.862408 -291.581078)
		(width 0.09525)
		(layer "In4.Cu")
		(net "M_D_CPU1_SB_DQS_DP<8>")
	)
	(arc
		(start 81.719674 -291.581078)
		(mid 82.001106 -291.656833)
		(end 82.282538 -291.581078)
		(width 0.09525)
		(layer "In4.Cu")
		(net "M_D_CPU1_SB_DQS_DP<8>")
	)
	(arc
		(start 81.350866 -291.576252)
		(mid 81.535898 -291.530338)
		(end 81.719674 -291.581078)
		(width 0.09525)
		(layer "In4.Cu")
		(net "M_D_CPU1_SB_DQS_DP<8>")
	)
	(segment
		(start 93.277944 -286.780478)
		(end 92.811092 -287.046162)
		(width 0.12954)
		(layer "F.Cu")
		(net "M_D_CPU1_SB_DQS_DP<7>")
	)
	(segment
		(start 32.969708 -305.011582)
		(end 34.881566 -305.011582)
		(width 0.16002)
		(layer "In4.Cu")
		(net "M_D_CPU1_SB_DQS_DP<7>")
	)
	(segment
		(start 36.604702 -305.176936)
		(end 37.232336 -305.436778)
		(width 0.16002)
		(layer "In4.Cu")
		(net "M_D_CPU1_SB_DQS_DP<7>")
	)
	(segment
		(start 76.169774 -288.02711)
		(end 76.186538 -288.010346)
		(width 0.09525)
		(layer "In4.Cu")
		(net "M_D_CPU1_SB_DQS_DP<7>")
	)
	(segment
		(start 78.899258 -286.721296)
		(end 78.904846 -286.724598)
		(width 0.09525)
		(layer "In4.Cu")
		(net "M_D_CPU1_SB_DQS_DP<7>")
	)
	(segment
		(start 76.186538 -287.927542)
		(end 77.02804 -287.085786)
		(width 0.09525)
		(layer "In4.Cu")
		(net "M_D_CPU1_SB_DQS_DP<7>")
	)
	(segment
		(start 56.990996 -305.677824)
		(end 57.77738 -304.89144)
		(width 0.16002)
		(layer "In4.Cu")
		(net "M_D_CPU1_SB_DQS_DP<7>")
	)
	(segment
		(start 92.55633 -286.754062)
		(end 92.657168 -286.780732)
		(width 0.09525)
		(layer "In4.Cu")
		(net "M_D_CPU1_SB_DQS_DP<7>")
	)
	(segment
		(start 35.56381 -304.783998)
		(end 35.956748 -305.176936)
		(width 0.16002)
		(layer "In4.Cu")
		(net "M_D_CPU1_SB_DQS_DP<7>")
	)
	(segment
		(start 68.96481 -295.231566)
		(end 76.169774 -288.02711)
		(width 0.16002)
		(layer "In4.Cu")
		(net "M_D_CPU1_SB_DQS_DP<7>")
	)
	(segment
		(start 77.02804 -287.085786)
		(end 77.741526 -287.085786)
		(width 0.09525)
		(layer "In4.Cu")
		(net "M_D_CPU1_SB_DQS_DP<7>")
	)
	(segment
		(start 35.10915 -304.783998)
		(end 35.56381 -304.783998)
		(width 0.16002)
		(layer "In4.Cu")
		(net "M_D_CPU1_SB_DQS_DP<7>")
	)
	(segment
		(start 83.591146 -286.716216)
		(end 83.599528 -286.721042)
		(width 0.09525)
		(layer "In4.Cu")
		(net "M_D_CPU1_SB_DQS_DP<7>")
	)
	(segment
		(start 42.77868 -304.807112)
		(end 43.125136 -304.807112)
		(width 0.16002)
		(layer "In4.Cu")
		(net "M_D_CPU1_SB_DQS_DP<7>")
	)
	(segment
		(start 89.231216 -286.716216)
		(end 89.239598 -286.721042)
		(width 0.09525)
		(layer "In4.Cu")
		(net "M_D_CPU1_SB_DQS_DP<7>")
	)
	(segment
		(start 40.11676 -306.010564)
		(end 40.426894 -306.010564)
		(width 0.16002)
		(layer "In4.Cu")
		(net "M_D_CPU1_SB_DQS_DP<7>")
	)
	(segment
		(start 52.846732 -305.160426)
		(end 54.096158 -305.677824)
		(width 0.16002)
		(layer "In4.Cu")
		(net "M_D_CPU1_SB_DQS_DP<7>")
	)
	(segment
		(start 84.5312 -286.716216)
		(end 84.539582 -286.721042)
		(width 0.09525)
		(layer "In4.Cu")
		(net "M_D_CPU1_SB_DQS_DP<7>")
	)
	(segment
		(start 51.486054 -305.160426)
		(end 52.846732 -305.160426)
		(width 0.16002)
		(layer "In4.Cu")
		(net "M_D_CPU1_SB_DQS_DP<7>")
	)
	(segment
		(start 85.102446 -286.721042)
		(end 85.110828 -286.716216)
		(width 0.09525)
		(layer "In4.Cu")
		(net "M_D_CPU1_SB_DQS_DP<7>")
	)
	(segment
		(start 81.342484 -286.721042)
		(end 81.350866 -286.716216)
		(width 0.09525)
		(layer "In4.Cu")
		(net "M_D_CPU1_SB_DQS_DP<7>")
	)
	(segment
		(start 50.694336 -304.832512)
		(end 51.486054 -305.160426)
		(width 0.16002)
		(layer "In4.Cu")
		(net "M_D_CPU1_SB_DQS_DP<7>")
	)
	(segment
		(start 45.233336 -305.160426)
		(end 47.28591 -306.010564)
		(width 0.16002)
		(layer "In4.Cu")
		(net "M_D_CPU1_SB_DQS_DP<7>")
	)
	(segment
		(start 76.186538 -288.010346)
		(end 76.186538 -287.927542)
		(width 0.09525)
		(layer "In4.Cu")
		(net "M_D_CPU1_SB_DQS_DP<7>")
	)
	(segment
		(start 49.225708 -305.562254)
		(end 50.317908 -304.832512)
		(width 0.16002)
		(layer "In4.Cu")
		(net "M_D_CPU1_SB_DQS_DP<7>")
	)
	(segment
		(start 89.802462 -286.721042)
		(end 89.810844 -286.716216)
		(width 0.09525)
		(layer "In4.Cu")
		(net "M_D_CPU1_SB_DQS_DP<7>")
	)
	(segment
		(start 78.88097 -286.710882)
		(end 78.899258 -286.721296)
		(width 0.09525)
		(layer "In4.Cu")
		(net "M_D_CPU1_SB_DQS_DP<7>")
	)
	(segment
		(start 57.77738 -304.89144)
		(end 60.528454 -304.344324)
		(width 0.16002)
		(layer "In4.Cu")
		(net "M_D_CPU1_SB_DQS_DP<7>")
	)
	(segment
		(start 78.03007 -286.797242)
		(end 78.240128 -286.797242)
		(width 0.09525)
		(layer "In4.Cu")
		(net "M_D_CPU1_SB_DQS_DP<7>")
	)
	(segment
		(start 50.317908 -304.832512)
		(end 50.694336 -304.832512)
		(width 0.16002)
		(layer "In4.Cu")
		(net "M_D_CPU1_SB_DQS_DP<7>")
	)
	(segment
		(start 54.096158 -305.677824)
		(end 56.990996 -305.677824)
		(width 0.16002)
		(layer "In4.Cu")
		(net "M_D_CPU1_SB_DQS_DP<7>")
	)
	(segment
		(start 60.528454 -304.344324)
		(end 61.455808 -303.960022)
		(width 0.16002)
		(layer "In4.Cu")
		(net "M_D_CPU1_SB_DQS_DP<7>")
	)
	(segment
		(start 40.426894 -306.010564)
		(end 42.387012 -305.19878)
		(width 0.16002)
		(layer "In4.Cu")
		(net "M_D_CPU1_SB_DQS_DP<7>")
	)
	(segment
		(start 35.956748 -305.176936)
		(end 36.604702 -305.176936)
		(width 0.16002)
		(layer "In4.Cu")
		(net "M_D_CPU1_SB_DQS_DP<7>")
	)
	(segment
		(start 80.771238 -286.716216)
		(end 80.77962 -286.721042)
		(width 0.09525)
		(layer "In4.Cu")
		(net "M_D_CPU1_SB_DQS_DP<7>")
	)
	(segment
		(start 42.387012 -305.19878)
		(end 42.77868 -304.807112)
		(width 0.16002)
		(layer "In4.Cu")
		(net "M_D_CPU1_SB_DQS_DP<7>")
	)
	(segment
		(start 68.96481 -296.45102)
		(end 68.96481 -295.231566)
		(width 0.16002)
		(layer "In4.Cu")
		(net "M_D_CPU1_SB_DQS_DP<7>")
	)
	(segment
		(start 34.881566 -305.011582)
		(end 35.10915 -304.783998)
		(width 0.16002)
		(layer "In4.Cu")
		(net "M_D_CPU1_SB_DQS_DP<7>")
	)
	(segment
		(start 79.461614 -286.721042)
		(end 79.473552 -286.714184)
		(width 0.09525)
		(layer "In4.Cu")
		(net "M_D_CPU1_SB_DQS_DP<7>")
	)
	(segment
		(start 43.47845 -305.160426)
		(end 45.233336 -305.160426)
		(width 0.16002)
		(layer "In4.Cu")
		(net "M_D_CPU1_SB_DQS_DP<7>")
	)
	(segment
		(start 88.291162 -286.716216)
		(end 88.299544 -286.721042)
		(width 0.09525)
		(layer "In4.Cu")
		(net "M_D_CPU1_SB_DQS_DP<7>")
	)
	(segment
		(start 43.125136 -304.807112)
		(end 43.47845 -305.160426)
		(width 0.16002)
		(layer "In4.Cu")
		(net "M_D_CPU1_SB_DQS_DP<7>")
	)
	(segment
		(start 48.14316 -306.010564)
		(end 49.225708 -305.562254)
		(width 0.16002)
		(layer "In4.Cu")
		(net "M_D_CPU1_SB_DQS_DP<7>")
	)
	(segment
		(start 61.455808 -303.960022)
		(end 68.96481 -296.45102)
		(width 0.16002)
		(layer "In4.Cu")
		(net "M_D_CPU1_SB_DQS_DP<7>")
	)
	(segment
		(start 32.695896 -305.285394)
		(end 32.969708 -305.011582)
		(width 0.16002)
		(layer "In4.Cu")
		(net "M_D_CPU1_SB_DQS_DP<7>")
	)
	(segment
		(start 77.741526 -287.085786)
		(end 78.03007 -286.797242)
		(width 0.09525)
		(layer "In4.Cu")
		(net "M_D_CPU1_SB_DQS_DP<7>")
	)
	(segment
		(start 47.28591 -306.010564)
		(end 48.14316 -306.010564)
		(width 0.16002)
		(layer "In4.Cu")
		(net "M_D_CPU1_SB_DQS_DP<7>")
	)
	(segment
		(start 80.387698 -286.729678)
		(end 80.40243 -286.721042)
		(width 0.09525)
		(layer "In4.Cu")
		(net "M_D_CPU1_SB_DQS_DP<7>")
	)
	(segment
		(start 92.657168 -286.780732)
		(end 92.811092 -287.046162)
		(width 0.09525)
		(layer "In4.Cu")
		(net "M_D_CPU1_SB_DQS_DP<7>")
	)
	(segment
		(start 90.742516 -286.721042)
		(end 90.750898 -286.716216)
		(width 0.09525)
		(layer "In4.Cu")
		(net "M_D_CPU1_SB_DQS_DP<7>")
	)
	(segment
		(start 86.0425 -286.721042)
		(end 86.050882 -286.716216)
		(width 0.09525)
		(layer "In4.Cu")
		(net "M_D_CPU1_SB_DQS_DP<7>")
	)
	(segment
		(start 37.232336 -305.436778)
		(end 40.11676 -306.010564)
		(width 0.16002)
		(layer "In4.Cu")
		(net "M_D_CPU1_SB_DQS_DP<7>")
	)
	(arc
		(start 85.110828 -286.716216)
		(mid 85.29586 -286.670302)
		(end 85.479636 -286.721042)
		(width 0.09525)
		(layer "In4.Cu")
		(net "M_D_CPU1_SB_DQS_DP<7>")
	)
	(arc
		(start 78.904846 -286.724598)
		(mid 79.183711 -286.796879)
		(end 79.461614 -286.721042)
		(width 0.09525)
		(layer "In4.Cu")
		(net "M_D_CPU1_SB_DQS_DP<7>")
	)
	(arc
		(start 83.599528 -286.721042)
		(mid 83.88096 -286.796831)
		(end 84.162392 -286.721042)
		(width 0.09525)
		(layer "In4.Cu")
		(net "M_D_CPU1_SB_DQS_DP<7>")
	)
	(arc
		(start 92.059506 -286.721042)
		(mid 92.293019 -286.794919)
		(end 92.535756 -286.76219)
		(width 0.09525)
		(layer "In4.Cu")
		(net "M_D_CPU1_SB_DQS_DP<7>")
	)
	(arc
		(start 89.239598 -286.721042)
		(mid 89.52103 -286.796831)
		(end 89.802462 -286.721042)
		(width 0.09525)
		(layer "In4.Cu")
		(net "M_D_CPU1_SB_DQS_DP<7>")
	)
	(arc
		(start 90.179652 -286.721042)
		(mid 90.461084 -286.796831)
		(end 90.742516 -286.721042)
		(width 0.09525)
		(layer "In4.Cu")
		(net "M_D_CPU1_SB_DQS_DP<7>")
	)
	(arc
		(start 84.539582 -286.721042)
		(mid 84.821014 -286.796831)
		(end 85.102446 -286.721042)
		(width 0.09525)
		(layer "In4.Cu")
		(net "M_D_CPU1_SB_DQS_DP<7>")
	)
	(arc
		(start 89.810844 -286.716216)
		(mid 89.995876 -286.670302)
		(end 90.179652 -286.721042)
		(width 0.09525)
		(layer "In4.Cu")
		(net "M_D_CPU1_SB_DQS_DP<7>")
	)
	(arc
		(start 81.719674 -286.721042)
		(mid 82.001106 -286.796831)
		(end 82.282538 -286.721042)
		(width 0.09525)
		(layer "In4.Cu")
		(net "M_D_CPU1_SB_DQS_DP<7>")
	)
	(arc
		(start 84.162392 -286.721042)
		(mid 84.346167 -286.67027)
		(end 84.5312 -286.716216)
		(width 0.09525)
		(layer "In4.Cu")
		(net "M_D_CPU1_SB_DQS_DP<7>")
	)
	(arc
		(start 87.922354 -286.721042)
		(mid 88.106129 -286.67027)
		(end 88.291162 -286.716216)
		(width 0.09525)
		(layer "In4.Cu")
		(net "M_D_CPU1_SB_DQS_DP<7>")
	)
	(arc
		(start 78.240128 -286.797242)
		(mid 78.386151 -286.77783)
		(end 78.522068 -286.721042)
		(width 0.09525)
		(layer "In4.Cu")
		(net "M_D_CPU1_SB_DQS_DP<7>")
	)
	(arc
		(start 78.522068 -286.721042)
		(mid 78.70022 -286.670386)
		(end 78.88097 -286.710882)
		(width 0.09525)
		(layer "In4.Cu")
		(net "M_D_CPU1_SB_DQS_DP<7>")
	)
	(arc
		(start 85.479636 -286.721042)
		(mid 85.761068 -286.796831)
		(end 86.0425 -286.721042)
		(width 0.09525)
		(layer "In4.Cu")
		(net "M_D_CPU1_SB_DQS_DP<7>")
	)
	(arc
		(start 87.35949 -286.721042)
		(mid 87.640922 -286.796831)
		(end 87.922354 -286.721042)
		(width 0.09525)
		(layer "In4.Cu")
		(net "M_D_CPU1_SB_DQS_DP<7>")
	)
	(arc
		(start 82.282538 -286.721042)
		(mid 82.471006 -286.670365)
		(end 82.659474 -286.721042)
		(width 0.09525)
		(layer "In4.Cu")
		(net "M_D_CPU1_SB_DQS_DP<7>")
	)
	(arc
		(start 80.77962 -286.721042)
		(mid 81.061052 -286.796831)
		(end 81.342484 -286.721042)
		(width 0.09525)
		(layer "In4.Cu")
		(net "M_D_CPU1_SB_DQS_DP<7>")
	)
	(arc
		(start 90.750898 -286.716216)
		(mid 90.93593 -286.670302)
		(end 91.119706 -286.721042)
		(width 0.09525)
		(layer "In4.Cu")
		(net "M_D_CPU1_SB_DQS_DP<7>")
	)
	(arc
		(start 92.535756 -286.76219)
		(mid 92.546083 -286.758228)
		(end 92.55633 -286.754062)
		(width 0.09525)
		(layer "In4.Cu")
		(net "M_D_CPU1_SB_DQS_DP<7>")
	)
	(arc
		(start 82.659474 -286.721042)
		(mid 82.940906 -286.796831)
		(end 83.222338 -286.721042)
		(width 0.09525)
		(layer "In4.Cu")
		(net "M_D_CPU1_SB_DQS_DP<7>")
	)
	(arc
		(start 86.41969 -286.721042)
		(mid 86.701122 -286.796831)
		(end 86.982554 -286.721042)
		(width 0.09525)
		(layer "In4.Cu")
		(net "M_D_CPU1_SB_DQS_DP<7>")
	)
	(arc
		(start 83.222338 -286.721042)
		(mid 83.406113 -286.67027)
		(end 83.591146 -286.716216)
		(width 0.09525)
		(layer "In4.Cu")
		(net "M_D_CPU1_SB_DQS_DP<7>")
	)
	(arc
		(start 91.119706 -286.721042)
		(mid 91.401138 -286.796831)
		(end 91.68257 -286.721042)
		(width 0.09525)
		(layer "In4.Cu")
		(net "M_D_CPU1_SB_DQS_DP<7>")
	)
	(arc
		(start 91.68257 -286.721042)
		(mid 91.871038 -286.670365)
		(end 92.059506 -286.721042)
		(width 0.09525)
		(layer "In4.Cu")
		(net "M_D_CPU1_SB_DQS_DP<7>")
	)
	(arc
		(start 81.350866 -286.716216)
		(mid 81.535898 -286.670302)
		(end 81.719674 -286.721042)
		(width 0.09525)
		(layer "In4.Cu")
		(net "M_D_CPU1_SB_DQS_DP<7>")
	)
	(arc
		(start 79.839058 -286.721042)
		(mid 80.11224 -286.797018)
		(end 80.387698 -286.729678)
		(width 0.09525)
		(layer "In4.Cu")
		(net "M_D_CPU1_SB_DQS_DP<7>")
	)
	(arc
		(start 86.982554 -286.721042)
		(mid 87.171022 -286.670365)
		(end 87.35949 -286.721042)
		(width 0.09525)
		(layer "In4.Cu")
		(net "M_D_CPU1_SB_DQS_DP<7>")
	)
	(arc
		(start 86.050882 -286.716216)
		(mid 86.235914 -286.670302)
		(end 86.41969 -286.721042)
		(width 0.09525)
		(layer "In4.Cu")
		(net "M_D_CPU1_SB_DQS_DP<7>")
	)
	(arc
		(start 80.40243 -286.721042)
		(mid 80.586205 -286.67027)
		(end 80.771238 -286.716216)
		(width 0.09525)
		(layer "In4.Cu")
		(net "M_D_CPU1_SB_DQS_DP<7>")
	)
	(arc
		(start 88.862408 -286.721042)
		(mid 89.046183 -286.67027)
		(end 89.231216 -286.716216)
		(width 0.09525)
		(layer "In4.Cu")
		(net "M_D_CPU1_SB_DQS_DP<7>")
	)
	(arc
		(start 88.299544 -286.721042)
		(mid 88.580976 -286.796831)
		(end 88.862408 -286.721042)
		(width 0.09525)
		(layer "In4.Cu")
		(net "M_D_CPU1_SB_DQS_DP<7>")
	)
	(arc
		(start 79.473552 -286.714184)
		(mid 79.657187 -286.670234)
		(end 79.839058 -286.721042)
		(width 0.09525)
		(layer "In4.Cu")
		(net "M_D_CPU1_SB_DQS_DP<7>")
	)
	(segment
		(start 93.277944 -281.920442)
		(end 92.811092 -282.18638)
		(width 0.12954)
		(layer "F.Cu")
		(net "M_D_CPU1_SB_DQS_DP<6>")
	)
	(segment
		(start 43.813476 -295.810432)
		(end 45.851826 -295.810432)
		(width 0.16002)
		(layer "In4.Cu")
		(net "M_D_CPU1_SB_DQS_DP<6>")
	)
	(segment
		(start 46.147736 -296.106342)
		(end 47.485554 -296.66057)
		(width 0.16002)
		(layer "In4.Cu")
		(net "M_D_CPU1_SB_DQS_DP<6>")
	)
	(segment
		(start 84.5312 -281.856434)
		(end 84.539582 -281.86126)
		(width 0.09525)
		(layer "In4.Cu")
		(net "M_D_CPU1_SB_DQS_DP<6>")
	)
	(segment
		(start 80.771238 -281.856434)
		(end 80.77962 -281.86126)
		(width 0.09525)
		(layer "In4.Cu")
		(net "M_D_CPU1_SB_DQS_DP<6>")
	)
	(segment
		(start 32.969708 -295.661588)
		(end 33.378394 -295.661588)
		(width 0.16002)
		(layer "In4.Cu")
		(net "M_D_CPU1_SB_DQS_DP<6>")
	)
	(segment
		(start 92.55633 -281.89428)
		(end 92.657168 -281.92095)
		(width 0.09525)
		(layer "In4.Cu")
		(net "M_D_CPU1_SB_DQS_DP<6>")
	)
	(segment
		(start 76.513944 -281.915616)
		(end 76.701904 -281.727656)
		(width 0.09525)
		(layer "In4.Cu")
		(net "M_D_CPU1_SB_DQS_DP<6>")
	)
	(segment
		(start 76.701904 -281.727656)
		(end 79.345282 -281.727656)
		(width 0.09525)
		(layer "In4.Cu")
		(net "M_D_CPU1_SB_DQS_DP<6>")
	)
	(segment
		(start 75.979528 -281.974544)
		(end 76.038456 -281.915616)
		(width 0.09525)
		(layer "In4.Cu")
		(net "M_D_CPU1_SB_DQS_DP<6>")
	)
	(segment
		(start 47.485554 -296.66057)
		(end 48.083724 -296.66057)
		(width 0.16002)
		(layer "In4.Cu")
		(net "M_D_CPU1_SB_DQS_DP<6>")
	)
	(segment
		(start 32.695896 -295.9354)
		(end 32.969708 -295.661588)
		(width 0.16002)
		(layer "In4.Cu")
		(net "M_D_CPU1_SB_DQS_DP<6>")
	)
	(segment
		(start 89.802462 -281.86126)
		(end 89.810844 -281.856434)
		(width 0.09525)
		(layer "In4.Cu")
		(net "M_D_CPU1_SB_DQS_DP<6>")
	)
	(segment
		(start 88.291162 -281.856434)
		(end 88.299544 -281.86126)
		(width 0.09525)
		(layer "In4.Cu")
		(net "M_D_CPU1_SB_DQS_DP<6>")
	)
	(segment
		(start 35.67176 -295.479724)
		(end 38.52291 -296.66057)
		(width 0.16002)
		(layer "In4.Cu")
		(net "M_D_CPU1_SB_DQS_DP<6>")
	)
	(segment
		(start 86.0425 -281.86126)
		(end 86.050882 -281.856434)
		(width 0.09525)
		(layer "In4.Cu")
		(net "M_D_CPU1_SB_DQS_DP<6>")
	)
	(segment
		(start 83.591146 -281.856434)
		(end 83.599528 -281.86126)
		(width 0.09525)
		(layer "In4.Cu")
		(net "M_D_CPU1_SB_DQS_DP<6>")
	)
	(segment
		(start 42.783252 -295.49471)
		(end 43.05046 -295.49471)
		(width 0.16002)
		(layer "In4.Cu")
		(net "M_D_CPU1_SB_DQS_DP<6>")
	)
	(segment
		(start 49.43729 -296.099992)
		(end 50.361596 -295.482518)
		(width 0.16002)
		(layer "In4.Cu")
		(net "M_D_CPU1_SB_DQS_DP<6>")
	)
	(segment
		(start 74.115676 -281.974544)
		(end 75.955906 -281.974544)
		(width 0.16002)
		(layer "In4.Cu")
		(net "M_D_CPU1_SB_DQS_DP<6>")
	)
	(segment
		(start 38.52291 -296.66057)
		(end 40.65016 -296.66057)
		(width 0.16002)
		(layer "In4.Cu")
		(net "M_D_CPU1_SB_DQS_DP<6>")
	)
	(segment
		(start 51.5493 -295.810432)
		(end 52.955698 -295.810432)
		(width 0.16002)
		(layer "In4.Cu")
		(net "M_D_CPU1_SB_DQS_DP<6>")
	)
	(segment
		(start 45.851826 -295.810432)
		(end 46.147736 -296.106342)
		(width 0.16002)
		(layer "In4.Cu")
		(net "M_D_CPU1_SB_DQS_DP<6>")
	)
	(segment
		(start 53.42509 -296.279824)
		(end 57.039002 -296.279824)
		(width 0.16002)
		(layer "In4.Cu")
		(net "M_D_CPU1_SB_DQS_DP<6>")
	)
	(segment
		(start 57.836308 -295.482518)
		(end 60.607702 -295.482518)
		(width 0.16002)
		(layer "In4.Cu")
		(net "M_D_CPU1_SB_DQS_DP<6>")
	)
	(segment
		(start 52.955698 -295.810432)
		(end 53.42509 -296.279824)
		(width 0.16002)
		(layer "In4.Cu")
		(net "M_D_CPU1_SB_DQS_DP<6>")
	)
	(segment
		(start 33.378394 -295.661588)
		(end 34.253424 -295.479724)
		(width 0.16002)
		(layer "In4.Cu")
		(net "M_D_CPU1_SB_DQS_DP<6>")
	)
	(segment
		(start 34.253424 -295.479724)
		(end 35.67176 -295.479724)
		(width 0.16002)
		(layer "In4.Cu")
		(net "M_D_CPU1_SB_DQS_DP<6>")
	)
	(segment
		(start 81.342484 -281.86126)
		(end 81.350866 -281.856434)
		(width 0.09525)
		(layer "In4.Cu")
		(net "M_D_CPU1_SB_DQS_DP<6>")
	)
	(segment
		(start 43.05046 -295.49471)
		(end 43.813476 -295.810432)
		(width 0.16002)
		(layer "In4.Cu")
		(net "M_D_CPU1_SB_DQS_DP<6>")
	)
	(segment
		(start 76.038456 -281.915616)
		(end 76.513944 -281.915616)
		(width 0.09525)
		(layer "In4.Cu")
		(net "M_D_CPU1_SB_DQS_DP<6>")
	)
	(segment
		(start 75.955906 -281.974544)
		(end 75.979528 -281.974544)
		(width 0.09525)
		(layer "In4.Cu")
		(net "M_D_CPU1_SB_DQS_DP<6>")
	)
	(segment
		(start 57.039002 -296.279824)
		(end 57.836308 -295.482518)
		(width 0.16002)
		(layer "In4.Cu")
		(net "M_D_CPU1_SB_DQS_DP<6>")
	)
	(segment
		(start 41.679876 -296.234358)
		(end 42.783252 -295.49471)
		(width 0.16002)
		(layer "In4.Cu")
		(net "M_D_CPU1_SB_DQS_DP<6>")
	)
	(segment
		(start 40.65016 -296.66057)
		(end 41.679876 -296.234358)
		(width 0.16002)
		(layer "In4.Cu")
		(net "M_D_CPU1_SB_DQS_DP<6>")
	)
	(segment
		(start 48.083724 -296.66057)
		(end 49.43729 -296.099992)
		(width 0.16002)
		(layer "In4.Cu")
		(net "M_D_CPU1_SB_DQS_DP<6>")
	)
	(segment
		(start 80.390746 -281.867356)
		(end 80.395826 -281.864562)
		(width 0.09525)
		(layer "In4.Cu")
		(net "M_D_CPU1_SB_DQS_DP<6>")
	)
	(segment
		(start 50.361596 -295.482518)
		(end 50.824892 -295.482518)
		(width 0.16002)
		(layer "In4.Cu")
		(net "M_D_CPU1_SB_DQS_DP<6>")
	)
	(segment
		(start 90.742516 -281.86126)
		(end 90.750898 -281.856434)
		(width 0.09525)
		(layer "In4.Cu")
		(net "M_D_CPU1_SB_DQS_DP<6>")
	)
	(segment
		(start 92.657168 -281.92095)
		(end 92.811092 -282.18638)
		(width 0.09525)
		(layer "In4.Cu")
		(net "M_D_CPU1_SB_DQS_DP<6>")
	)
	(segment
		(start 89.231216 -281.856434)
		(end 89.239598 -281.86126)
		(width 0.09525)
		(layer "In4.Cu")
		(net "M_D_CPU1_SB_DQS_DP<6>")
	)
	(segment
		(start 50.824892 -295.482518)
		(end 51.5493 -295.810432)
		(width 0.16002)
		(layer "In4.Cu")
		(net "M_D_CPU1_SB_DQS_DP<6>")
	)
	(segment
		(start 85.102446 -281.86126)
		(end 85.110828 -281.856434)
		(width 0.09525)
		(layer "In4.Cu")
		(net "M_D_CPU1_SB_DQS_DP<6>")
	)
	(segment
		(start 60.607702 -295.482518)
		(end 74.115676 -281.974544)
		(width 0.16002)
		(layer "In4.Cu")
		(net "M_D_CPU1_SB_DQS_DP<6>")
	)
	(segment
		(start 80.395826 -281.864562)
		(end 80.40243 -281.86126)
		(width 0.09525)
		(layer "In4.Cu")
		(net "M_D_CPU1_SB_DQS_DP<6>")
	)
	(arc
		(start 83.599528 -281.86126)
		(mid 83.88096 -281.937015)
		(end 84.162392 -281.86126)
		(width 0.09525)
		(layer "In4.Cu")
		(net "M_D_CPU1_SB_DQS_DP<6>")
	)
	(arc
		(start 92.535756 -281.902408)
		(mid 92.546084 -281.898448)
		(end 92.55633 -281.89428)
		(width 0.09525)
		(layer "In4.Cu")
		(net "M_D_CPU1_SB_DQS_DP<6>")
	)
	(arc
		(start 87.35949 -281.86126)
		(mid 87.640922 -281.937015)
		(end 87.922354 -281.86126)
		(width 0.09525)
		(layer "In4.Cu")
		(net "M_D_CPU1_SB_DQS_DP<6>")
	)
	(arc
		(start 87.922354 -281.86126)
		(mid 88.106129 -281.810488)
		(end 88.291162 -281.856434)
		(width 0.09525)
		(layer "In4.Cu")
		(net "M_D_CPU1_SB_DQS_DP<6>")
	)
	(arc
		(start 84.539582 -281.86126)
		(mid 84.821014 -281.937015)
		(end 85.102446 -281.86126)
		(width 0.09525)
		(layer "In4.Cu")
		(net "M_D_CPU1_SB_DQS_DP<6>")
	)
	(arc
		(start 90.179652 -281.86126)
		(mid 90.461084 -281.937015)
		(end 90.742516 -281.86126)
		(width 0.09525)
		(layer "In4.Cu")
		(net "M_D_CPU1_SB_DQS_DP<6>")
	)
	(arc
		(start 85.479636 -281.86126)
		(mid 85.761068 -281.937015)
		(end 86.0425 -281.86126)
		(width 0.09525)
		(layer "In4.Cu")
		(net "M_D_CPU1_SB_DQS_DP<6>")
	)
	(arc
		(start 89.810844 -281.856434)
		(mid 89.995876 -281.81052)
		(end 90.179652 -281.86126)
		(width 0.09525)
		(layer "In4.Cu")
		(net "M_D_CPU1_SB_DQS_DP<6>")
	)
	(arc
		(start 86.41969 -281.86126)
		(mid 86.701122 -281.937015)
		(end 86.982554 -281.86126)
		(width 0.09525)
		(layer "In4.Cu")
		(net "M_D_CPU1_SB_DQS_DP<6>")
	)
	(arc
		(start 82.659474 -281.86126)
		(mid 82.940906 -281.937015)
		(end 83.222338 -281.86126)
		(width 0.09525)
		(layer "In4.Cu")
		(net "M_D_CPU1_SB_DQS_DP<6>")
	)
	(arc
		(start 81.719674 -281.86126)
		(mid 82.001106 -281.937015)
		(end 82.282538 -281.86126)
		(width 0.09525)
		(layer "In4.Cu")
		(net "M_D_CPU1_SB_DQS_DP<6>")
	)
	(arc
		(start 91.119706 -281.86126)
		(mid 91.401138 -281.937015)
		(end 91.68257 -281.86126)
		(width 0.09525)
		(layer "In4.Cu")
		(net "M_D_CPU1_SB_DQS_DP<6>")
	)
	(arc
		(start 86.050882 -281.856434)
		(mid 86.235914 -281.81052)
		(end 86.41969 -281.86126)
		(width 0.09525)
		(layer "In4.Cu")
		(net "M_D_CPU1_SB_DQS_DP<6>")
	)
	(arc
		(start 80.40243 -281.86126)
		(mid 80.586205 -281.810488)
		(end 80.771238 -281.856434)
		(width 0.09525)
		(layer "In4.Cu")
		(net "M_D_CPU1_SB_DQS_DP<6>")
	)
	(arc
		(start 79.839312 -281.861006)
		(mid 80.114206 -281.936757)
		(end 80.390746 -281.867356)
		(width 0.09525)
		(layer "In4.Cu")
		(net "M_D_CPU1_SB_DQS_DP<6>")
	)
	(arc
		(start 80.77962 -281.86126)
		(mid 81.061052 -281.937015)
		(end 81.342484 -281.86126)
		(width 0.09525)
		(layer "In4.Cu")
		(net "M_D_CPU1_SB_DQS_DP<6>")
	)
	(arc
		(start 91.68257 -281.86126)
		(mid 91.871038 -281.810583)
		(end 92.059506 -281.86126)
		(width 0.09525)
		(layer "In4.Cu")
		(net "M_D_CPU1_SB_DQS_DP<6>")
	)
	(arc
		(start 85.110828 -281.856434)
		(mid 85.29586 -281.81052)
		(end 85.479636 -281.86126)
		(width 0.09525)
		(layer "In4.Cu")
		(net "M_D_CPU1_SB_DQS_DP<6>")
	)
	(arc
		(start 84.162392 -281.86126)
		(mid 84.346167 -281.810488)
		(end 84.5312 -281.856434)
		(width 0.09525)
		(layer "In4.Cu")
		(net "M_D_CPU1_SB_DQS_DP<6>")
	)
	(arc
		(start 82.282538 -281.86126)
		(mid 82.471006 -281.810583)
		(end 82.659474 -281.86126)
		(width 0.09525)
		(layer "In4.Cu")
		(net "M_D_CPU1_SB_DQS_DP<6>")
	)
	(arc
		(start 92.059506 -281.86126)
		(mid 92.29302 -281.935103)
		(end 92.535756 -281.902408)
		(width 0.09525)
		(layer "In4.Cu")
		(net "M_D_CPU1_SB_DQS_DP<6>")
	)
	(arc
		(start 83.222338 -281.86126)
		(mid 83.406113 -281.810488)
		(end 83.591146 -281.856434)
		(width 0.09525)
		(layer "In4.Cu")
		(net "M_D_CPU1_SB_DQS_DP<6>")
	)
	(arc
		(start 88.862408 -281.86126)
		(mid 89.046183 -281.810488)
		(end 89.231216 -281.856434)
		(width 0.09525)
		(layer "In4.Cu")
		(net "M_D_CPU1_SB_DQS_DP<6>")
	)
	(arc
		(start 88.299544 -281.86126)
		(mid 88.580976 -281.937015)
		(end 88.862408 -281.86126)
		(width 0.09525)
		(layer "In4.Cu")
		(net "M_D_CPU1_SB_DQS_DP<6>")
	)
	(arc
		(start 79.345282 -281.727656)
		(mid 79.601112 -281.761659)
		(end 79.839312 -281.861006)
		(width 0.09525)
		(layer "In4.Cu")
		(net "M_D_CPU1_SB_DQS_DP<6>")
	)
	(arc
		(start 89.239598 -281.86126)
		(mid 89.52103 -281.937015)
		(end 89.802462 -281.86126)
		(width 0.09525)
		(layer "In4.Cu")
		(net "M_D_CPU1_SB_DQS_DP<6>")
	)
	(arc
		(start 81.350866 -281.856434)
		(mid 81.535898 -281.81052)
		(end 81.719674 -281.86126)
		(width 0.09525)
		(layer "In4.Cu")
		(net "M_D_CPU1_SB_DQS_DP<6>")
	)
	(arc
		(start 90.750898 -281.856434)
		(mid 90.93593 -281.81052)
		(end 91.119706 -281.86126)
		(width 0.09525)
		(layer "In4.Cu")
		(net "M_D_CPU1_SB_DQS_DP<6>")
	)
	(arc
		(start 86.982554 -281.86126)
		(mid 87.171022 -281.810583)
		(end 87.35949 -281.86126)
		(width 0.09525)
		(layer "In4.Cu")
		(net "M_D_CPU1_SB_DQS_DP<6>")
	)
	(segment
		(start 93.277944 -277.060406)
		(end 92.811092 -277.326344)
		(width 0.12954)
		(layer "F.Cu")
		(net "M_D_CPU1_SB_DQS_DP<5>")
	)
	(segment
		(start 83.591146 -276.996398)
		(end 83.599528 -277.001224)
		(width 0.09525)
		(layer "In4.Cu")
		(net "M_D_CPU1_SB_DQS_DP<5>")
	)
	(segment
		(start 45.247306 -286.460438)
		(end 47.29988 -287.310576)
		(width 0.16002)
		(layer "In4.Cu")
		(net "M_D_CPU1_SB_DQS_DP<5>")
	)
	(segment
		(start 89.231216 -276.996398)
		(end 89.239598 -277.001224)
		(width 0.09525)
		(layer "In4.Cu")
		(net "M_D_CPU1_SB_DQS_DP<5>")
	)
	(segment
		(start 32.695896 -286.585406)
		(end 32.969708 -286.311594)
		(width 0.16002)
		(layer "In4.Cu")
		(net "M_D_CPU1_SB_DQS_DP<5>")
	)
	(segment
		(start 39.90213 -287.310576)
		(end 40.577008 -287.310576)
		(width 0.16002)
		(layer "In4.Cu")
		(net "M_D_CPU1_SB_DQS_DP<5>")
	)
	(segment
		(start 76.30033 -276.292056)
		(end 76.89215 -276.883876)
		(width 0.09525)
		(layer "In4.Cu")
		(net "M_D_CPU1_SB_DQS_DP<5>")
	)
	(segment
		(start 85.102446 -277.001224)
		(end 85.110828 -276.996398)
		(width 0.09525)
		(layer "In4.Cu")
		(net "M_D_CPU1_SB_DQS_DP<5>")
	)
	(segment
		(start 32.969708 -286.311594)
		(end 33.889188 -286.311594)
		(width 0.16002)
		(layer "In4.Cu")
		(net "M_D_CPU1_SB_DQS_DP<5>")
	)
	(segment
		(start 43.238928 -286.107124)
		(end 44.042076 -286.460438)
		(width 0.16002)
		(layer "In4.Cu")
		(net "M_D_CPU1_SB_DQS_DP<5>")
	)
	(segment
		(start 92.55633 -277.034244)
		(end 92.657168 -277.060914)
		(width 0.09525)
		(layer "In4.Cu")
		(net "M_D_CPU1_SB_DQS_DP<5>")
	)
	(segment
		(start 76.038456 -276.292056)
		(end 76.30033 -276.292056)
		(width 0.09525)
		(layer "In4.Cu")
		(net "M_D_CPU1_SB_DQS_DP<5>")
	)
	(segment
		(start 57.836308 -286.132524)
		(end 60.318904 -286.132524)
		(width 0.16002)
		(layer "In4.Cu")
		(net "M_D_CPU1_SB_DQS_DP<5>")
	)
	(segment
		(start 80.771238 -276.996398)
		(end 80.77962 -277.001224)
		(width 0.09525)
		(layer "In4.Cu")
		(net "M_D_CPU1_SB_DQS_DP<5>")
	)
	(segment
		(start 80.387698 -277.00986)
		(end 80.40243 -277.001224)
		(width 0.09525)
		(layer "In4.Cu")
		(net "M_D_CPU1_SB_DQS_DP<5>")
	)
	(segment
		(start 92.657168 -277.060914)
		(end 92.811092 -277.326344)
		(width 0.09525)
		(layer "In4.Cu")
		(net "M_D_CPU1_SB_DQS_DP<5>")
	)
	(segment
		(start 36.576762 -286.47771)
		(end 39.90213 -287.310576)
		(width 0.16002)
		(layer "In4.Cu")
		(net "M_D_CPU1_SB_DQS_DP<5>")
	)
	(segment
		(start 89.802462 -277.001224)
		(end 89.810844 -276.996398)
		(width 0.09525)
		(layer "In4.Cu")
		(net "M_D_CPU1_SB_DQS_DP<5>")
	)
	(segment
		(start 53.450236 -286.932624)
		(end 57.036208 -286.932624)
		(width 0.16002)
		(layer "In4.Cu")
		(net "M_D_CPU1_SB_DQS_DP<5>")
	)
	(segment
		(start 88.291162 -276.996398)
		(end 88.299544 -277.001224)
		(width 0.09525)
		(layer "In4.Cu")
		(net "M_D_CPU1_SB_DQS_DP<5>")
	)
	(segment
		(start 48.057054 -287.310576)
		(end 49.876202 -286.556958)
		(width 0.16002)
		(layer "In4.Cu")
		(net "M_D_CPU1_SB_DQS_DP<5>")
	)
	(segment
		(start 49.876202 -286.556958)
		(end 50.300636 -286.132524)
		(width 0.16002)
		(layer "In4.Cu")
		(net "M_D_CPU1_SB_DQS_DP<5>")
	)
	(segment
		(start 60.318904 -286.132524)
		(end 70.100444 -276.350984)
		(width 0.16002)
		(layer "In4.Cu")
		(net "M_D_CPU1_SB_DQS_DP<5>")
	)
	(segment
		(start 50.694336 -286.132524)
		(end 51.02225 -286.460438)
		(width 0.16002)
		(layer "In4.Cu")
		(net "M_D_CPU1_SB_DQS_DP<5>")
	)
	(segment
		(start 35.62096 -286.081724)
		(end 36.576762 -286.47771)
		(width 0.16002)
		(layer "In4.Cu")
		(net "M_D_CPU1_SB_DQS_DP<5>")
	)
	(segment
		(start 84.5312 -276.996398)
		(end 84.539582 -277.001224)
		(width 0.09525)
		(layer "In4.Cu")
		(net "M_D_CPU1_SB_DQS_DP<5>")
	)
	(segment
		(start 86.0425 -277.001224)
		(end 86.050882 -276.996398)
		(width 0.09525)
		(layer "In4.Cu")
		(net "M_D_CPU1_SB_DQS_DP<5>")
	)
	(segment
		(start 33.889188 -286.311594)
		(end 35.001708 -286.081724)
		(width 0.16002)
		(layer "In4.Cu")
		(net "M_D_CPU1_SB_DQS_DP<5>")
	)
	(segment
		(start 52.97805 -286.460438)
		(end 53.450236 -286.932624)
		(width 0.16002)
		(layer "In4.Cu")
		(net "M_D_CPU1_SB_DQS_DP<5>")
	)
	(segment
		(start 75.955906 -276.350984)
		(end 75.979528 -276.350984)
		(width 0.09525)
		(layer "In4.Cu")
		(net "M_D_CPU1_SB_DQS_DP<5>")
	)
	(segment
		(start 50.300636 -286.132524)
		(end 50.694336 -286.132524)
		(width 0.16002)
		(layer "In4.Cu")
		(net "M_D_CPU1_SB_DQS_DP<5>")
	)
	(segment
		(start 70.100444 -276.350984)
		(end 75.955906 -276.350984)
		(width 0.16002)
		(layer "In4.Cu")
		(net "M_D_CPU1_SB_DQS_DP<5>")
	)
	(segment
		(start 47.29988 -287.310576)
		(end 48.057054 -287.310576)
		(width 0.16002)
		(layer "In4.Cu")
		(net "M_D_CPU1_SB_DQS_DP<5>")
	)
	(segment
		(start 79.837534 -276.9997)
		(end 79.83728 -277.000208)
		(width 0.09525)
		(layer "In4.Cu")
		(net "M_D_CPU1_SB_DQS_DP<5>")
	)
	(segment
		(start 35.001708 -286.081724)
		(end 35.62096 -286.081724)
		(width 0.16002)
		(layer "In4.Cu")
		(net "M_D_CPU1_SB_DQS_DP<5>")
	)
	(segment
		(start 75.979528 -276.350984)
		(end 76.038456 -276.292056)
		(width 0.09525)
		(layer "In4.Cu")
		(net "M_D_CPU1_SB_DQS_DP<5>")
	)
	(segment
		(start 57.036208 -286.932624)
		(end 57.836308 -286.132524)
		(width 0.16002)
		(layer "In4.Cu")
		(net "M_D_CPU1_SB_DQS_DP<5>")
	)
	(segment
		(start 90.742516 -277.001224)
		(end 90.750898 -276.996398)
		(width 0.09525)
		(layer "In4.Cu")
		(net "M_D_CPU1_SB_DQS_DP<5>")
	)
	(segment
		(start 40.577008 -287.310576)
		(end 42.273728 -286.607504)
		(width 0.16002)
		(layer "In4.Cu")
		(net "M_D_CPU1_SB_DQS_DP<5>")
	)
	(segment
		(start 81.342484 -277.001224)
		(end 81.350866 -276.996398)
		(width 0.09525)
		(layer "In4.Cu")
		(net "M_D_CPU1_SB_DQS_DP<5>")
	)
	(segment
		(start 51.02225 -286.460438)
		(end 52.97805 -286.460438)
		(width 0.16002)
		(layer "In4.Cu")
		(net "M_D_CPU1_SB_DQS_DP<5>")
	)
	(segment
		(start 44.042076 -286.460438)
		(end 45.247306 -286.460438)
		(width 0.16002)
		(layer "In4.Cu")
		(net "M_D_CPU1_SB_DQS_DP<5>")
	)
	(segment
		(start 76.89215 -276.883876)
		(end 79.405988 -276.883876)
		(width 0.09525)
		(layer "In4.Cu")
		(net "M_D_CPU1_SB_DQS_DP<5>")
	)
	(segment
		(start 42.774108 -286.107124)
		(end 43.238928 -286.107124)
		(width 0.16002)
		(layer "In4.Cu")
		(net "M_D_CPU1_SB_DQS_DP<5>")
	)
	(segment
		(start 42.273728 -286.607504)
		(end 42.774108 -286.107124)
		(width 0.16002)
		(layer "In4.Cu")
		(net "M_D_CPU1_SB_DQS_DP<5>")
	)
	(arc
		(start 88.299544 -277.001224)
		(mid 88.305997 -277.004824)
		(end 88.312498 -277.008336)
		(width 0.09525)
		(layer "In4.Cu")
		(net "M_D_CPU1_SB_DQS_DP<5>")
	)
	(arc
		(start 81.350866 -276.996398)
		(mid 81.535898 -276.950484)
		(end 81.719674 -277.001224)
		(width 0.09525)
		(layer "In4.Cu")
		(net "M_D_CPU1_SB_DQS_DP<5>")
	)
	(arc
		(start 91.68257 -277.001224)
		(mid 91.871038 -276.950547)
		(end 92.059506 -277.001224)
		(width 0.09525)
		(layer "In4.Cu")
		(net "M_D_CPU1_SB_DQS_DP<5>")
	)
	(arc
		(start 89.810844 -276.996398)
		(mid 89.995876 -276.950484)
		(end 90.179652 -277.001224)
		(width 0.09525)
		(layer "In4.Cu")
		(net "M_D_CPU1_SB_DQS_DP<5>")
	)
	(arc
		(start 79.405988 -276.883876)
		(mid 79.629373 -276.913412)
		(end 79.837534 -276.9997)
		(width 0.09525)
		(layer "In4.Cu")
		(net "M_D_CPU1_SB_DQS_DP<5>")
	)
	(arc
		(start 80.40243 -277.001224)
		(mid 80.586205 -276.950452)
		(end 80.771238 -276.996398)
		(width 0.09525)
		(layer "In4.Cu")
		(net "M_D_CPU1_SB_DQS_DP<5>")
	)
	(arc
		(start 87.37219 -277.008336)
		(mid 87.6482 -277.076897)
		(end 87.922354 -277.001224)
		(width 0.09525)
		(layer "In4.Cu")
		(net "M_D_CPU1_SB_DQS_DP<5>")
	)
	(arc
		(start 84.162392 -277.001224)
		(mid 84.346167 -276.950452)
		(end 84.5312 -276.996398)
		(width 0.09525)
		(layer "In4.Cu")
		(net "M_D_CPU1_SB_DQS_DP<5>")
	)
	(arc
		(start 82.672174 -277.008336)
		(mid 82.948184 -277.076897)
		(end 83.222338 -277.001224)
		(width 0.09525)
		(layer "In4.Cu")
		(net "M_D_CPU1_SB_DQS_DP<5>")
	)
	(arc
		(start 83.612482 -277.008336)
		(mid 83.888382 -277.076898)
		(end 84.162392 -277.001224)
		(width 0.09525)
		(layer "In4.Cu")
		(net "M_D_CPU1_SB_DQS_DP<5>")
	)
	(arc
		(start 88.312498 -277.008336)
		(mid 88.588398 -277.076898)
		(end 88.862408 -277.001224)
		(width 0.09525)
		(layer "In4.Cu")
		(net "M_D_CPU1_SB_DQS_DP<5>")
	)
	(arc
		(start 91.119706 -277.001224)
		(mid 91.401138 -277.076979)
		(end 91.68257 -277.001224)
		(width 0.09525)
		(layer "In4.Cu")
		(net "M_D_CPU1_SB_DQS_DP<5>")
	)
	(arc
		(start 92.059506 -277.001224)
		(mid 92.29302 -277.075067)
		(end 92.535756 -277.042372)
		(width 0.09525)
		(layer "In4.Cu")
		(net "M_D_CPU1_SB_DQS_DP<5>")
	)
	(arc
		(start 86.050882 -276.996398)
		(mid 86.235914 -276.950484)
		(end 86.41969 -277.001224)
		(width 0.09525)
		(layer "In4.Cu")
		(net "M_D_CPU1_SB_DQS_DP<5>")
	)
	(arc
		(start 85.479636 -277.001224)
		(mid 85.761068 -277.076979)
		(end 86.0425 -277.001224)
		(width 0.09525)
		(layer "In4.Cu")
		(net "M_D_CPU1_SB_DQS_DP<5>")
	)
	(arc
		(start 87.35949 -277.001224)
		(mid 87.365818 -277.00482)
		(end 87.37219 -277.008336)
		(width 0.09525)
		(layer "In4.Cu")
		(net "M_D_CPU1_SB_DQS_DP<5>")
	)
	(arc
		(start 83.222338 -277.001224)
		(mid 83.406113 -276.950452)
		(end 83.591146 -276.996398)
		(width 0.09525)
		(layer "In4.Cu")
		(net "M_D_CPU1_SB_DQS_DP<5>")
	)
	(arc
		(start 85.110828 -276.996398)
		(mid 85.29586 -276.950484)
		(end 85.479636 -277.001224)
		(width 0.09525)
		(layer "In4.Cu")
		(net "M_D_CPU1_SB_DQS_DP<5>")
	)
	(arc
		(start 89.239598 -277.001224)
		(mid 89.52103 -277.076979)
		(end 89.802462 -277.001224)
		(width 0.09525)
		(layer "In4.Cu")
		(net "M_D_CPU1_SB_DQS_DP<5>")
	)
	(arc
		(start 79.839058 -277.001224)
		(mid 80.11224 -277.077166)
		(end 80.387698 -277.00986)
		(width 0.09525)
		(layer "In4.Cu")
		(net "M_D_CPU1_SB_DQS_DP<5>")
	)
	(arc
		(start 88.862408 -277.001224)
		(mid 89.046183 -276.950452)
		(end 89.231216 -276.996398)
		(width 0.09525)
		(layer "In4.Cu")
		(net "M_D_CPU1_SB_DQS_DP<5>")
	)
	(arc
		(start 90.750898 -276.996398)
		(mid 90.93593 -276.950484)
		(end 91.119706 -277.001224)
		(width 0.09525)
		(layer "In4.Cu")
		(net "M_D_CPU1_SB_DQS_DP<5>")
	)
	(arc
		(start 87.922354 -277.001224)
		(mid 88.106129 -276.950452)
		(end 88.291162 -276.996398)
		(width 0.09525)
		(layer "In4.Cu")
		(net "M_D_CPU1_SB_DQS_DP<5>")
	)
	(arc
		(start 86.41969 -277.001224)
		(mid 86.701122 -277.076979)
		(end 86.982554 -277.001224)
		(width 0.09525)
		(layer "In4.Cu")
		(net "M_D_CPU1_SB_DQS_DP<5>")
	)
	(arc
		(start 90.179652 -277.001224)
		(mid 90.461084 -277.076979)
		(end 90.742516 -277.001224)
		(width 0.09525)
		(layer "In4.Cu")
		(net "M_D_CPU1_SB_DQS_DP<5>")
	)
	(arc
		(start 80.77962 -277.001224)
		(mid 81.061052 -277.076979)
		(end 81.342484 -277.001224)
		(width 0.09525)
		(layer "In4.Cu")
		(net "M_D_CPU1_SB_DQS_DP<5>")
	)
	(arc
		(start 79.83728 -277.000208)
		(mid 79.83817 -277.000715)
		(end 79.839058 -277.001224)
		(width 0.09525)
		(layer "In4.Cu")
		(net "M_D_CPU1_SB_DQS_DP<5>")
	)
	(arc
		(start 81.719674 -277.001224)
		(mid 82.001106 -277.076979)
		(end 82.282538 -277.001224)
		(width 0.09525)
		(layer "In4.Cu")
		(net "M_D_CPU1_SB_DQS_DP<5>")
	)
	(arc
		(start 92.535756 -277.042372)
		(mid 92.546084 -277.038412)
		(end 92.55633 -277.034244)
		(width 0.09525)
		(layer "In4.Cu")
		(net "M_D_CPU1_SB_DQS_DP<5>")
	)
	(arc
		(start 82.282538 -277.001224)
		(mid 82.471006 -276.950547)
		(end 82.659474 -277.001224)
		(width 0.09525)
		(layer "In4.Cu")
		(net "M_D_CPU1_SB_DQS_DP<5>")
	)
	(arc
		(start 86.982554 -277.001224)
		(mid 87.171022 -276.950547)
		(end 87.35949 -277.001224)
		(width 0.09525)
		(layer "In4.Cu")
		(net "M_D_CPU1_SB_DQS_DP<5>")
	)
	(arc
		(start 82.659474 -277.001224)
		(mid 82.665802 -277.00482)
		(end 82.672174 -277.008336)
		(width 0.09525)
		(layer "In4.Cu")
		(net "M_D_CPU1_SB_DQS_DP<5>")
	)
	(arc
		(start 83.599528 -277.001224)
		(mid 83.605981 -277.004824)
		(end 83.612482 -277.008336)
		(width 0.09525)
		(layer "In4.Cu")
		(net "M_D_CPU1_SB_DQS_DP<5>")
	)
	(arc
		(start 84.539582 -277.001224)
		(mid 84.821014 -277.076979)
		(end 85.102446 -277.001224)
		(width 0.09525)
		(layer "In4.Cu")
		(net "M_D_CPU1_SB_DQS_DP<5>")
	)
	(segment
		(start 93.277944 -272.20037)
		(end 92.811092 -272.466308)
		(width 0.12954)
		(layer "F.Cu")
		(net "M_D_CPU1_SB_DQS_DP<4>")
	)
	(segment
		(start 57.044336 -277.585424)
		(end 57.857136 -276.772624)
		(width 0.16002)
		(layer "In4.Cu")
		(net "M_D_CPU1_SB_DQS_DP<4>")
	)
	(segment
		(start 43.150536 -276.785324)
		(end 43.475656 -277.110444)
		(width 0.16002)
		(layer "In4.Cu")
		(net "M_D_CPU1_SB_DQS_DP<4>")
	)
	(segment
		(start 78.506066 -272.089626)
		(end 79.650082 -272.089626)
		(width 0.09525)
		(layer "In4.Cu")
		(net "M_D_CPU1_SB_DQS_DP<4>")
	)
	(segment
		(start 34.19856 -276.746462)
		(end 35.567874 -276.746462)
		(width 0.16002)
		(layer "In4.Cu")
		(net "M_D_CPU1_SB_DQS_DP<4>")
	)
	(segment
		(start 89.231216 -272.136362)
		(end 89.239598 -272.141188)
		(width 0.09525)
		(layer "In4.Cu")
		(net "M_D_CPU1_SB_DQS_DP<4>")
	)
	(segment
		(start 81.342484 -272.141188)
		(end 81.350866 -272.136362)
		(width 0.09525)
		(layer "In4.Cu")
		(net "M_D_CPU1_SB_DQS_DP<4>")
	)
	(segment
		(start 59.789314 -276.772624)
		(end 65.834514 -270.727424)
		(width 0.16002)
		(layer "In4.Cu")
		(net "M_D_CPU1_SB_DQS_DP<4>")
	)
	(segment
		(start 49.6824 -277.37816)
		(end 50.338736 -276.721824)
		(width 0.16002)
		(layer "In4.Cu")
		(net "M_D_CPU1_SB_DQS_DP<4>")
	)
	(segment
		(start 90.742516 -272.141188)
		(end 90.750898 -272.136362)
		(width 0.09525)
		(layer "In4.Cu")
		(net "M_D_CPU1_SB_DQS_DP<4>")
	)
	(segment
		(start 33.983422 -276.9616)
		(end 34.19856 -276.746462)
		(width 0.16002)
		(layer "In4.Cu")
		(net "M_D_CPU1_SB_DQS_DP<4>")
	)
	(segment
		(start 92.55633 -272.174208)
		(end 92.657168 -272.200878)
		(width 0.09525)
		(layer "In4.Cu")
		(net "M_D_CPU1_SB_DQS_DP<4>")
	)
	(segment
		(start 41.453308 -277.623524)
		(end 41.918636 -277.623524)
		(width 0.16002)
		(layer "In4.Cu")
		(net "M_D_CPU1_SB_DQS_DP<4>")
	)
	(segment
		(start 88.291162 -272.136362)
		(end 88.299544 -272.141188)
		(width 0.09525)
		(layer "In4.Cu")
		(net "M_D_CPU1_SB_DQS_DP<4>")
	)
	(segment
		(start 75.979528 -270.727424)
		(end 76.038456 -270.668496)
		(width 0.09525)
		(layer "In4.Cu")
		(net "M_D_CPU1_SB_DQS_DP<4>")
	)
	(segment
		(start 38.026086 -277.960582)
		(end 41.11625 -277.960582)
		(width 0.16002)
		(layer "In4.Cu")
		(net "M_D_CPU1_SB_DQS_DP<4>")
	)
	(segment
		(start 89.802462 -272.141188)
		(end 89.810844 -272.136362)
		(width 0.09525)
		(layer "In4.Cu")
		(net "M_D_CPU1_SB_DQS_DP<4>")
	)
	(segment
		(start 76.427076 -270.879316)
		(end 77.295756 -270.879316)
		(width 0.09525)
		(layer "In4.Cu")
		(net "M_D_CPU1_SB_DQS_DP<4>")
	)
	(segment
		(start 92.657168 -272.200878)
		(end 92.811092 -272.466308)
		(width 0.09525)
		(layer "In4.Cu")
		(net "M_D_CPU1_SB_DQS_DP<4>")
	)
	(segment
		(start 77.295756 -270.879316)
		(end 78.506066 -272.089626)
		(width 0.09525)
		(layer "In4.Cu")
		(net "M_D_CPU1_SB_DQS_DP<4>")
	)
	(segment
		(start 41.11625 -277.960582)
		(end 41.453308 -277.623524)
		(width 0.16002)
		(layer "In4.Cu")
		(net "M_D_CPU1_SB_DQS_DP<4>")
	)
	(segment
		(start 76.216256 -270.668496)
		(end 76.427076 -270.879316)
		(width 0.09525)
		(layer "In4.Cu")
		(net "M_D_CPU1_SB_DQS_DP<4>")
	)
	(segment
		(start 32.695896 -277.235412)
		(end 32.969708 -276.9616)
		(width 0.16002)
		(layer "In4.Cu")
		(net "M_D_CPU1_SB_DQS_DP<4>")
	)
	(segment
		(start 49.24679 -277.37816)
		(end 49.6824 -277.37816)
		(width 0.16002)
		(layer "In4.Cu")
		(net "M_D_CPU1_SB_DQS_DP<4>")
	)
	(segment
		(start 51.002184 -277.110444)
		(end 53.338984 -277.110444)
		(width 0.16002)
		(layer "In4.Cu")
		(net "M_D_CPU1_SB_DQS_DP<4>")
	)
	(segment
		(start 35.567874 -276.746462)
		(end 35.902392 -277.08098)
		(width 0.16002)
		(layer "In4.Cu")
		(net "M_D_CPU1_SB_DQS_DP<4>")
	)
	(segment
		(start 65.834514 -270.727424)
		(end 75.955906 -270.727424)
		(width 0.16002)
		(layer "In4.Cu")
		(net "M_D_CPU1_SB_DQS_DP<4>")
	)
	(segment
		(start 35.902392 -277.08098)
		(end 38.026086 -277.960582)
		(width 0.16002)
		(layer "In4.Cu")
		(net "M_D_CPU1_SB_DQS_DP<4>")
	)
	(segment
		(start 50.613564 -276.721824)
		(end 51.002184 -277.110444)
		(width 0.16002)
		(layer "In4.Cu")
		(net "M_D_CPU1_SB_DQS_DP<4>")
	)
	(segment
		(start 85.102446 -272.141188)
		(end 85.110828 -272.136362)
		(width 0.09525)
		(layer "In4.Cu")
		(net "M_D_CPU1_SB_DQS_DP<4>")
	)
	(segment
		(start 45.585634 -277.110444)
		(end 46.435772 -277.960582)
		(width 0.16002)
		(layer "In4.Cu")
		(net "M_D_CPU1_SB_DQS_DP<4>")
	)
	(segment
		(start 84.5312 -272.136362)
		(end 84.539582 -272.141188)
		(width 0.09525)
		(layer "In4.Cu")
		(net "M_D_CPU1_SB_DQS_DP<4>")
	)
	(segment
		(start 46.435772 -277.960582)
		(end 48.664368 -277.960582)
		(width 0.16002)
		(layer "In4.Cu")
		(net "M_D_CPU1_SB_DQS_DP<4>")
	)
	(segment
		(start 86.0425 -272.141188)
		(end 86.050882 -272.136362)
		(width 0.09525)
		(layer "In4.Cu")
		(net "M_D_CPU1_SB_DQS_DP<4>")
	)
	(segment
		(start 80.387698 -272.149824)
		(end 80.40243 -272.141188)
		(width 0.09525)
		(layer "In4.Cu")
		(net "M_D_CPU1_SB_DQS_DP<4>")
	)
	(segment
		(start 32.969708 -276.9616)
		(end 33.983422 -276.9616)
		(width 0.16002)
		(layer "In4.Cu")
		(net "M_D_CPU1_SB_DQS_DP<4>")
	)
	(segment
		(start 50.338736 -276.721824)
		(end 50.613564 -276.721824)
		(width 0.16002)
		(layer "In4.Cu")
		(net "M_D_CPU1_SB_DQS_DP<4>")
	)
	(segment
		(start 53.813964 -277.585424)
		(end 57.044336 -277.585424)
		(width 0.16002)
		(layer "In4.Cu")
		(net "M_D_CPU1_SB_DQS_DP<4>")
	)
	(segment
		(start 57.857136 -276.772624)
		(end 59.789314 -276.772624)
		(width 0.16002)
		(layer "In4.Cu")
		(net "M_D_CPU1_SB_DQS_DP<4>")
	)
	(segment
		(start 75.955906 -270.727424)
		(end 75.979528 -270.727424)
		(width 0.09525)
		(layer "In4.Cu")
		(net "M_D_CPU1_SB_DQS_DP<4>")
	)
	(segment
		(start 48.664368 -277.960582)
		(end 49.24679 -277.37816)
		(width 0.16002)
		(layer "In4.Cu")
		(net "M_D_CPU1_SB_DQS_DP<4>")
	)
	(segment
		(start 83.591146 -272.136362)
		(end 83.599528 -272.141188)
		(width 0.09525)
		(layer "In4.Cu")
		(net "M_D_CPU1_SB_DQS_DP<4>")
	)
	(segment
		(start 76.038456 -270.668496)
		(end 76.216256 -270.668496)
		(width 0.09525)
		(layer "In4.Cu")
		(net "M_D_CPU1_SB_DQS_DP<4>")
	)
	(segment
		(start 53.338984 -277.110444)
		(end 53.813964 -277.585424)
		(width 0.16002)
		(layer "In4.Cu")
		(net "M_D_CPU1_SB_DQS_DP<4>")
	)
	(segment
		(start 80.771238 -272.136362)
		(end 80.77962 -272.141188)
		(width 0.09525)
		(layer "In4.Cu")
		(net "M_D_CPU1_SB_DQS_DP<4>")
	)
	(segment
		(start 42.756836 -276.785324)
		(end 43.150536 -276.785324)
		(width 0.16002)
		(layer "In4.Cu")
		(net "M_D_CPU1_SB_DQS_DP<4>")
	)
	(segment
		(start 43.475656 -277.110444)
		(end 45.585634 -277.110444)
		(width 0.16002)
		(layer "In4.Cu")
		(net "M_D_CPU1_SB_DQS_DP<4>")
	)
	(segment
		(start 41.918636 -277.623524)
		(end 42.756836 -276.785324)
		(width 0.16002)
		(layer "In4.Cu")
		(net "M_D_CPU1_SB_DQS_DP<4>")
	)
	(arc
		(start 86.41969 -272.141188)
		(mid 86.701122 -272.216943)
		(end 86.982554 -272.141188)
		(width 0.09525)
		(layer "In4.Cu")
		(net "M_D_CPU1_SB_DQS_DP<4>")
	)
	(arc
		(start 81.350866 -272.136362)
		(mid 81.535898 -272.090448)
		(end 81.719674 -272.141188)
		(width 0.09525)
		(layer "In4.Cu")
		(net "M_D_CPU1_SB_DQS_DP<4>")
	)
	(arc
		(start 79.839058 -272.141188)
		(mid 80.11224 -272.21713)
		(end 80.387698 -272.149824)
		(width 0.09525)
		(layer "In4.Cu")
		(net "M_D_CPU1_SB_DQS_DP<4>")
	)
	(arc
		(start 89.810844 -272.136362)
		(mid 89.995876 -272.090448)
		(end 90.179652 -272.141188)
		(width 0.09525)
		(layer "In4.Cu")
		(net "M_D_CPU1_SB_DQS_DP<4>")
	)
	(arc
		(start 82.659474 -272.141188)
		(mid 82.940906 -272.216943)
		(end 83.222338 -272.141188)
		(width 0.09525)
		(layer "In4.Cu")
		(net "M_D_CPU1_SB_DQS_DP<4>")
	)
	(arc
		(start 91.68257 -272.141188)
		(mid 91.871038 -272.090511)
		(end 92.059506 -272.141188)
		(width 0.09525)
		(layer "In4.Cu")
		(net "M_D_CPU1_SB_DQS_DP<4>")
	)
	(arc
		(start 92.059506 -272.141188)
		(mid 92.29302 -272.215031)
		(end 92.535756 -272.182336)
		(width 0.09525)
		(layer "In4.Cu")
		(net "M_D_CPU1_SB_DQS_DP<4>")
	)
	(arc
		(start 88.862408 -272.141188)
		(mid 89.046183 -272.090416)
		(end 89.231216 -272.136362)
		(width 0.09525)
		(layer "In4.Cu")
		(net "M_D_CPU1_SB_DQS_DP<4>")
	)
	(arc
		(start 83.599528 -272.141188)
		(mid 83.88096 -272.216943)
		(end 84.162392 -272.141188)
		(width 0.09525)
		(layer "In4.Cu")
		(net "M_D_CPU1_SB_DQS_DP<4>")
	)
	(arc
		(start 84.539582 -272.141188)
		(mid 84.821014 -272.216943)
		(end 85.102446 -272.141188)
		(width 0.09525)
		(layer "In4.Cu")
		(net "M_D_CPU1_SB_DQS_DP<4>")
	)
	(arc
		(start 90.750898 -272.136362)
		(mid 90.93593 -272.090448)
		(end 91.119706 -272.141188)
		(width 0.09525)
		(layer "In4.Cu")
		(net "M_D_CPU1_SB_DQS_DP<4>")
	)
	(arc
		(start 86.050882 -272.136362)
		(mid 86.235914 -272.090448)
		(end 86.41969 -272.141188)
		(width 0.09525)
		(layer "In4.Cu")
		(net "M_D_CPU1_SB_DQS_DP<4>")
	)
	(arc
		(start 80.40243 -272.141188)
		(mid 80.586205 -272.090416)
		(end 80.771238 -272.136362)
		(width 0.09525)
		(layer "In4.Cu")
		(net "M_D_CPU1_SB_DQS_DP<4>")
	)
	(arc
		(start 79.650082 -272.089626)
		(mid 79.747979 -272.102912)
		(end 79.839058 -272.141188)
		(width 0.09525)
		(layer "In4.Cu")
		(net "M_D_CPU1_SB_DQS_DP<4>")
	)
	(arc
		(start 91.119706 -272.141188)
		(mid 91.401138 -272.216943)
		(end 91.68257 -272.141188)
		(width 0.09525)
		(layer "In4.Cu")
		(net "M_D_CPU1_SB_DQS_DP<4>")
	)
	(arc
		(start 87.922354 -272.141188)
		(mid 88.106129 -272.090416)
		(end 88.291162 -272.136362)
		(width 0.09525)
		(layer "In4.Cu")
		(net "M_D_CPU1_SB_DQS_DP<4>")
	)
	(arc
		(start 88.299544 -272.141188)
		(mid 88.580976 -272.216943)
		(end 88.862408 -272.141188)
		(width 0.09525)
		(layer "In4.Cu")
		(net "M_D_CPU1_SB_DQS_DP<4>")
	)
	(arc
		(start 82.282538 -272.141188)
		(mid 82.471006 -272.090511)
		(end 82.659474 -272.141188)
		(width 0.09525)
		(layer "In4.Cu")
		(net "M_D_CPU1_SB_DQS_DP<4>")
	)
	(arc
		(start 80.77962 -272.141188)
		(mid 81.061052 -272.216943)
		(end 81.342484 -272.141188)
		(width 0.09525)
		(layer "In4.Cu")
		(net "M_D_CPU1_SB_DQS_DP<4>")
	)
	(arc
		(start 90.179652 -272.141188)
		(mid 90.461084 -272.216943)
		(end 90.742516 -272.141188)
		(width 0.09525)
		(layer "In4.Cu")
		(net "M_D_CPU1_SB_DQS_DP<4>")
	)
	(arc
		(start 83.222338 -272.141188)
		(mid 83.406113 -272.090416)
		(end 83.591146 -272.136362)
		(width 0.09525)
		(layer "In4.Cu")
		(net "M_D_CPU1_SB_DQS_DP<4>")
	)
	(arc
		(start 87.35949 -272.141188)
		(mid 87.640922 -272.216943)
		(end 87.922354 -272.141188)
		(width 0.09525)
		(layer "In4.Cu")
		(net "M_D_CPU1_SB_DQS_DP<4>")
	)
	(arc
		(start 81.719674 -272.141188)
		(mid 82.001106 -272.216943)
		(end 82.282538 -272.141188)
		(width 0.09525)
		(layer "In4.Cu")
		(net "M_D_CPU1_SB_DQS_DP<4>")
	)
	(arc
		(start 92.535756 -272.182336)
		(mid 92.546084 -272.178376)
		(end 92.55633 -272.174208)
		(width 0.09525)
		(layer "In4.Cu")
		(net "M_D_CPU1_SB_DQS_DP<4>")
	)
	(arc
		(start 85.479636 -272.141188)
		(mid 85.761068 -272.216943)
		(end 86.0425 -272.141188)
		(width 0.09525)
		(layer "In4.Cu")
		(net "M_D_CPU1_SB_DQS_DP<4>")
	)
	(arc
		(start 84.162392 -272.141188)
		(mid 84.346167 -272.090416)
		(end 84.5312 -272.136362)
		(width 0.09525)
		(layer "In4.Cu")
		(net "M_D_CPU1_SB_DQS_DP<4>")
	)
	(arc
		(start 85.110828 -272.136362)
		(mid 85.29586 -272.090448)
		(end 85.479636 -272.141188)
		(width 0.09525)
		(layer "In4.Cu")
		(net "M_D_CPU1_SB_DQS_DP<4>")
	)
	(arc
		(start 86.982554 -272.141188)
		(mid 87.171022 -272.090511)
		(end 87.35949 -272.141188)
		(width 0.09525)
		(layer "In4.Cu")
		(net "M_D_CPU1_SB_DQS_DP<4>")
	)
	(arc
		(start 89.239598 -272.141188)
		(mid 89.52103 -272.216943)
		(end 89.802462 -272.141188)
		(width 0.09525)
		(layer "In4.Cu")
		(net "M_D_CPU1_SB_DQS_DP<4>")
	)
	(segment
		(start 91.397836 -290.020248)
		(end 90.930984 -290.286186)
		(width 0.12954)
		(layer "F.Cu")
		(net "M_D_CPU1_SB_DQS_DP<3>")
	)
	(segment
		(start 61.64199 -311.504076)
		(end 61.535564 -311.39765)
		(width 0.16002)
		(layer "In4.Cu")
		(net "M_D_CPU1_SB_DQS_DP<3>")
	)
	(segment
		(start 76.665328 -293.718488)
		(end 77.131672 -293.25189)
		(width 0.09525)
		(layer "In4.Cu")
		(net "M_D_CPU1_SB_DQS_DP<3>")
	)
	(segment
		(start 85.102446 -290.611306)
		(end 85.110828 -290.616132)
		(width 0.09525)
		(layer "In4.Cu")
		(net "M_D_CPU1_SB_DQS_DP<3>")
	)
	(segment
		(start 65.28943 -307.856636)
		(end 65.56629 -307.856636)
		(width 0.16002)
		(layer "In4.Cu")
		(net "M_D_CPU1_SB_DQS_DP<3>")
	)
	(segment
		(start 68.313554 -305.109372)
		(end 68.51015 -304.912776)
		(width 0.16002)
		(layer "In4.Cu")
		(net "M_D_CPU1_SB_DQS_DP<3>")
	)
	(segment
		(start 64.389254 -308.756812)
		(end 64.282828 -308.650386)
		(width 0.16002)
		(layer "In4.Cu")
		(net "M_D_CPU1_SB_DQS_DP<3>")
	)
	(segment
		(start 59.88431 -312.521346)
		(end 60.534804 -311.870852)
		(width 0.16002)
		(layer "In4.Cu")
		(net "M_D_CPU1_SB_DQS_DP<3>")
	)
	(segment
		(start 66.663062 -306.483004)
		(end 66.939922 -306.483004)
		(width 0.16002)
		(layer "In4.Cu")
		(net "M_D_CPU1_SB_DQS_DP<3>")
	)
	(segment
		(start 86.0425 -290.611306)
		(end 86.050882 -290.616132)
		(width 0.09525)
		(layer "In4.Cu")
		(net "M_D_CPU1_SB_DQS_DP<3>")
	)
	(segment
		(start 42.636186 -312.538364)
		(end 43.118786 -312.538364)
		(width 0.16002)
		(layer "In4.Cu")
		(net "M_D_CPU1_SB_DQS_DP<3>")
	)
	(segment
		(start 61.908436 -310.49722)
		(end 62.435486 -310.49722)
		(width 0.16002)
		(layer "In4.Cu")
		(net "M_D_CPU1_SB_DQS_DP<3>")
	)
	(segment
		(start 53.405786 -313.384946)
		(end 54.367938 -313.384946)
		(width 0.16002)
		(layer "In4.Cu")
		(net "M_D_CPU1_SB_DQS_DP<3>")
	)
	(segment
		(start 65.762886 -307.66004)
		(end 65.762886 -307.38318)
		(width 0.16002)
		(layer "In4.Cu")
		(net "M_D_CPU1_SB_DQS_DP<3>")
	)
	(segment
		(start 68.403724 -304.001932)
		(end 68.776596 -303.62906)
		(width 0.16002)
		(layer "In4.Cu")
		(net "M_D_CPU1_SB_DQS_DP<3>")
	)
	(segment
		(start 63.915798 -309.230268)
		(end 64.192658 -309.230268)
		(width 0.16002)
		(layer "In4.Cu")
		(net "M_D_CPU1_SB_DQS_DP<3>")
	)
	(segment
		(start 84.5312 -290.616132)
		(end 84.539582 -290.611306)
		(width 0.09525)
		(layer "In4.Cu")
		(net "M_D_CPU1_SB_DQS_DP<3>")
	)
	(segment
		(start 69.883782 -303.539144)
		(end 69.883782 -303.262284)
		(width 0.16002)
		(layer "In4.Cu")
		(net "M_D_CPU1_SB_DQS_DP<3>")
	)
	(segment
		(start 59.14644 -312.404506)
		(end 59.26328 -312.521346)
		(width 0.16002)
		(layer "In4.Cu")
		(net "M_D_CPU1_SB_DQS_DP<3>")
	)
	(segment
		(start 37.93236 -313.209178)
		(end 38.0492 -313.092338)
		(width 0.16002)
		(layer "In4.Cu")
		(net "M_D_CPU1_SB_DQS_DP<3>")
	)
	(segment
		(start 79.744824 -290.535614)
		(end 80.121252 -290.535614)
		(width 0.09525)
		(layer "In4.Cu")
		(net "M_D_CPU1_SB_DQS_DP<3>")
	)
	(segment
		(start 50.116486 -312.610246)
		(end 50.599086 -312.610246)
		(width 0.16002)
		(layer "In4.Cu")
		(net "M_D_CPU1_SB_DQS_DP<3>")
	)
	(segment
		(start 55.06212 -312.690764)
		(end 55.605172 -312.690764)
		(width 0.16002)
		(layer "In4.Cu")
		(net "M_D_CPU1_SB_DQS_DP<3>")
	)
	(segment
		(start 68.51015 -304.912776)
		(end 68.51015 -304.635916)
		(width 0.16002)
		(layer "In4.Cu")
		(net "M_D_CPU1_SB_DQS_DP<3>")
	)
	(segment
		(start 61.445394 -311.977532)
		(end 61.64199 -311.780936)
		(width 0.16002)
		(layer "In4.Cu")
		(net "M_D_CPU1_SB_DQS_DP<3>")
	)
	(segment
		(start 67.030092 -305.375564)
		(end 67.402964 -305.002692)
		(width 0.16002)
		(layer "In4.Cu")
		(net "M_D_CPU1_SB_DQS_DP<3>")
	)
	(segment
		(start 56.299354 -313.384946)
		(end 56.885586 -313.384946)
		(width 0.16002)
		(layer "In4.Cu")
		(net "M_D_CPU1_SB_DQS_DP<3>")
	)
	(segment
		(start 43.118786 -312.538364)
		(end 43.446954 -312.210196)
		(width 0.16002)
		(layer "In4.Cu")
		(net "M_D_CPU1_SB_DQS_DP<3>")
	)
	(segment
		(start 64.282828 -308.650386)
		(end 64.282828 -308.122828)
		(width 0.16002)
		(layer "In4.Cu")
		(net "M_D_CPU1_SB_DQS_DP<3>")
	)
	(segment
		(start 63.809118 -309.123588)
		(end 63.915798 -309.230268)
		(width 0.16002)
		(layer "In4.Cu")
		(net "M_D_CPU1_SB_DQS_DP<3>")
	)
	(segment
		(start 64.192658 -309.230268)
		(end 64.389254 -309.033672)
		(width 0.16002)
		(layer "In4.Cu")
		(net "M_D_CPU1_SB_DQS_DP<3>")
	)
	(segment
		(start 55.605172 -312.690764)
		(end 56.299354 -313.384946)
		(width 0.16002)
		(layer "In4.Cu")
		(net "M_D_CPU1_SB_DQS_DP<3>")
	)
	(segment
		(start 62.909196 -310.024018)
		(end 62.909196 -309.49646)
		(width 0.16002)
		(layer "In4.Cu")
		(net "M_D_CPU1_SB_DQS_DP<3>")
	)
	(segment
		(start 67.930014 -305.002692)
		(end 68.036694 -305.109372)
		(width 0.16002)
		(layer "In4.Cu")
		(net "M_D_CPU1_SB_DQS_DP<3>")
	)
	(segment
		(start 89.231216 -290.616132)
		(end 89.239598 -290.611306)
		(width 0.09525)
		(layer "In4.Cu")
		(net "M_D_CPU1_SB_DQS_DP<3>")
	)
	(segment
		(start 39.194232 -313.209178)
		(end 39.34333 -313.06008)
		(width 0.16002)
		(layer "In4.Cu")
		(net "M_D_CPU1_SB_DQS_DP<3>")
	)
	(segment
		(start 76.43749 -294.860472)
		(end 76.43749 -294.268652)
		(width 0.09525)
		(layer "In4.Cu")
		(net "M_D_CPU1_SB_DQS_DP<3>")
	)
	(segment
		(start 38.6461 -313.209178)
		(end 39.194232 -313.209178)
		(width 0.16002)
		(layer "In4.Cu")
		(net "M_D_CPU1_SB_DQS_DP<3>")
	)
	(segment
		(start 69.777356 -302.6283)
		(end 73.43775 -298.967906)
		(width 0.16002)
		(layer "In4.Cu")
		(net "M_D_CPU1_SB_DQS_DP<3>")
	)
	(segment
		(start 68.036694 -305.109372)
		(end 68.313554 -305.109372)
		(width 0.16002)
		(layer "In4.Cu")
		(net "M_D_CPU1_SB_DQS_DP<3>")
	)
	(segment
		(start 77.131672 -293.25189)
		(end 78.30312 -291.499036)
		(width 0.09525)
		(layer "In4.Cu")
		(net "M_D_CPU1_SB_DQS_DP<3>")
	)
	(segment
		(start 67.402964 -305.002692)
		(end 67.930014 -305.002692)
		(width 0.16002)
		(layer "In4.Cu")
		(net "M_D_CPU1_SB_DQS_DP<3>")
	)
	(segment
		(start 36.795964 -312.935366)
		(end 37.069776 -313.209178)
		(width 0.16002)
		(layer "In4.Cu")
		(net "M_D_CPU1_SB_DQS_DP<3>")
	)
	(segment
		(start 61.535564 -310.870092)
		(end 61.908436 -310.49722)
		(width 0.16002)
		(layer "In4.Cu")
		(net "M_D_CPU1_SB_DQS_DP<3>")
	)
	(segment
		(start 61.64199 -311.780936)
		(end 61.64199 -311.504076)
		(width 0.16002)
		(layer "In4.Cu")
		(net "M_D_CPU1_SB_DQS_DP<3>")
	)
	(segment
		(start 67.136518 -306.009548)
		(end 67.030092 -305.903122)
		(width 0.16002)
		(layer "In4.Cu")
		(net "M_D_CPU1_SB_DQS_DP<3>")
	)
	(segment
		(start 61.535564 -311.39765)
		(end 61.535564 -310.870092)
		(width 0.16002)
		(layer "In4.Cu")
		(net "M_D_CPU1_SB_DQS_DP<3>")
	)
	(segment
		(start 67.030092 -305.903122)
		(end 67.030092 -305.375564)
		(width 0.16002)
		(layer "In4.Cu")
		(net "M_D_CPU1_SB_DQS_DP<3>")
	)
	(segment
		(start 69.687186 -303.73574)
		(end 69.883782 -303.539144)
		(width 0.16002)
		(layer "In4.Cu")
		(net "M_D_CPU1_SB_DQS_DP<3>")
	)
	(segment
		(start 61.168534 -311.977532)
		(end 61.445394 -311.977532)
		(width 0.16002)
		(layer "In4.Cu")
		(net "M_D_CPU1_SB_DQS_DP<3>")
	)
	(segment
		(start 89.802462 -290.611306)
		(end 89.810844 -290.616132)
		(width 0.09525)
		(layer "In4.Cu")
		(net "M_D_CPU1_SB_DQS_DP<3>")
	)
	(segment
		(start 62.819026 -310.6039)
		(end 63.015622 -310.407304)
		(width 0.16002)
		(layer "In4.Cu")
		(net "M_D_CPU1_SB_DQS_DP<3>")
	)
	(segment
		(start 81.342484 -290.611306)
		(end 81.350866 -290.616132)
		(width 0.09525)
		(layer "In4.Cu")
		(net "M_D_CPU1_SB_DQS_DP<3>")
	)
	(segment
		(start 50.599086 -312.610246)
		(end 50.999136 -312.210196)
		(width 0.16002)
		(layer "In4.Cu")
		(net "M_D_CPU1_SB_DQS_DP<3>")
	)
	(segment
		(start 63.015622 -310.407304)
		(end 63.015622 -310.130444)
		(width 0.16002)
		(layer "In4.Cu")
		(net "M_D_CPU1_SB_DQS_DP<3>")
	)
	(segment
		(start 88.291162 -290.616132)
		(end 88.299544 -290.611306)
		(width 0.09525)
		(layer "In4.Cu")
		(net "M_D_CPU1_SB_DQS_DP<3>")
	)
	(segment
		(start 73.43775 -298.967906)
		(end 73.43775 -297.775884)
		(width 0.16002)
		(layer "In4.Cu")
		(net "M_D_CPU1_SB_DQS_DP<3>")
	)
	(segment
		(start 69.883782 -303.262284)
		(end 69.777356 -303.155858)
		(width 0.16002)
		(layer "In4.Cu")
		(net "M_D_CPU1_SB_DQS_DP<3>")
	)
	(segment
		(start 76.1492 -295.064942)
		(end 76.23302 -295.064942)
		(width 0.09525)
		(layer "In4.Cu")
		(net "M_D_CPU1_SB_DQS_DP<3>")
	)
	(segment
		(start 65.18275 -307.749956)
		(end 65.28943 -307.856636)
		(width 0.16002)
		(layer "In4.Cu")
		(net "M_D_CPU1_SB_DQS_DP<3>")
	)
	(segment
		(start 60.534804 -311.870852)
		(end 61.061854 -311.870852)
		(width 0.16002)
		(layer "In4.Cu")
		(net "M_D_CPU1_SB_DQS_DP<3>")
	)
	(segment
		(start 64.282828 -308.122828)
		(end 64.6557 -307.749956)
		(width 0.16002)
		(layer "In4.Cu")
		(net "M_D_CPU1_SB_DQS_DP<3>")
	)
	(segment
		(start 73.43775 -297.775884)
		(end 76.132436 -295.081706)
		(width 0.16002)
		(layer "In4.Cu")
		(net "M_D_CPU1_SB_DQS_DP<3>")
	)
	(segment
		(start 39.34333 -313.06008)
		(end 40.922702 -313.06008)
		(width 0.16002)
		(layer "In4.Cu")
		(net "M_D_CPU1_SB_DQS_DP<3>")
	)
	(segment
		(start 66.939922 -306.483004)
		(end 67.136518 -306.286408)
		(width 0.16002)
		(layer "In4.Cu")
		(net "M_D_CPU1_SB_DQS_DP<3>")
	)
	(segment
		(start 46.205902 -313.06008)
		(end 48.68418 -313.06008)
		(width 0.16002)
		(layer "In4.Cu")
		(net "M_D_CPU1_SB_DQS_DP<3>")
	)
	(segment
		(start 40.922702 -313.06008)
		(end 41.239186 -313.376564)
		(width 0.16002)
		(layer "In4.Cu")
		(net "M_D_CPU1_SB_DQS_DP<3>")
	)
	(segment
		(start 69.410326 -303.73574)
		(end 69.687186 -303.73574)
		(width 0.16002)
		(layer "In4.Cu")
		(net "M_D_CPU1_SB_DQS_DP<3>")
	)
	(segment
		(start 63.015622 -310.130444)
		(end 62.909196 -310.024018)
		(width 0.16002)
		(layer "In4.Cu")
		(net "M_D_CPU1_SB_DQS_DP<3>")
	)
	(segment
		(start 76.132436 -295.081706)
		(end 76.1492 -295.064942)
		(width 0.09525)
		(layer "In4.Cu")
		(net "M_D_CPU1_SB_DQS_DP<3>")
	)
	(segment
		(start 43.446954 -312.210196)
		(end 45.356018 -312.210196)
		(width 0.16002)
		(layer "In4.Cu")
		(net "M_D_CPU1_SB_DQS_DP<3>")
	)
	(segment
		(start 78.30312 -291.499036)
		(end 79.744824 -290.535614)
		(width 0.09525)
		(layer "In4.Cu")
		(net "M_D_CPU1_SB_DQS_DP<3>")
	)
	(segment
		(start 62.542166 -310.6039)
		(end 62.819026 -310.6039)
		(width 0.16002)
		(layer "In4.Cu")
		(net "M_D_CPU1_SB_DQS_DP<3>")
	)
	(segment
		(start 48.68418 -313.06008)
		(end 48.996346 -313.372246)
		(width 0.16002)
		(layer "In4.Cu")
		(net "M_D_CPU1_SB_DQS_DP<3>")
	)
	(segment
		(start 41.239186 -313.376564)
		(end 41.797986 -313.376564)
		(width 0.16002)
		(layer "In4.Cu")
		(net "M_D_CPU1_SB_DQS_DP<3>")
	)
	(segment
		(start 38.0492 -313.092338)
		(end 38.52926 -313.092338)
		(width 0.16002)
		(layer "In4.Cu")
		(net "M_D_CPU1_SB_DQS_DP<3>")
	)
	(segment
		(start 67.136518 -306.286408)
		(end 67.136518 -306.009548)
		(width 0.16002)
		(layer "In4.Cu")
		(net "M_D_CPU1_SB_DQS_DP<3>")
	)
	(segment
		(start 64.6557 -307.749956)
		(end 65.18275 -307.749956)
		(width 0.16002)
		(layer "In4.Cu")
		(net "M_D_CPU1_SB_DQS_DP<3>")
	)
	(segment
		(start 62.435486 -310.49722)
		(end 62.542166 -310.6039)
		(width 0.16002)
		(layer "In4.Cu")
		(net "M_D_CPU1_SB_DQS_DP<3>")
	)
	(segment
		(start 66.556382 -306.376324)
		(end 66.663062 -306.483004)
		(width 0.16002)
		(layer "In4.Cu")
		(net "M_D_CPU1_SB_DQS_DP<3>")
	)
	(segment
		(start 50.999136 -312.210196)
		(end 52.231036 -312.210196)
		(width 0.16002)
		(layer "In4.Cu")
		(net "M_D_CPU1_SB_DQS_DP<3>")
	)
	(segment
		(start 91.084908 -290.551616)
		(end 90.930984 -290.286186)
		(width 0.09525)
		(layer "In4.Cu")
		(net "M_D_CPU1_SB_DQS_DP<3>")
	)
	(segment
		(start 65.56629 -307.856636)
		(end 65.762886 -307.66004)
		(width 0.16002)
		(layer "In4.Cu")
		(net "M_D_CPU1_SB_DQS_DP<3>")
	)
	(segment
		(start 48.996346 -313.372246)
		(end 49.354486 -313.372246)
		(width 0.16002)
		(layer "In4.Cu")
		(net "M_D_CPU1_SB_DQS_DP<3>")
	)
	(segment
		(start 64.389254 -309.033672)
		(end 64.389254 -308.756812)
		(width 0.16002)
		(layer "In4.Cu")
		(net "M_D_CPU1_SB_DQS_DP<3>")
	)
	(segment
		(start 38.52926 -313.092338)
		(end 38.6461 -313.209178)
		(width 0.16002)
		(layer "In4.Cu")
		(net "M_D_CPU1_SB_DQS_DP<3>")
	)
	(segment
		(start 63.282068 -309.123588)
		(end 63.809118 -309.123588)
		(width 0.16002)
		(layer "In4.Cu")
		(net "M_D_CPU1_SB_DQS_DP<3>")
	)
	(segment
		(start 65.762886 -307.38318)
		(end 65.65646 -307.276754)
		(width 0.16002)
		(layer "In4.Cu")
		(net "M_D_CPU1_SB_DQS_DP<3>")
	)
	(segment
		(start 62.909196 -309.49646)
		(end 63.282068 -309.123588)
		(width 0.16002)
		(layer "In4.Cu")
		(net "M_D_CPU1_SB_DQS_DP<3>")
	)
	(segment
		(start 69.303646 -303.62906)
		(end 69.410326 -303.73574)
		(width 0.16002)
		(layer "In4.Cu")
		(net "M_D_CPU1_SB_DQS_DP<3>")
	)
	(segment
		(start 37.069776 -313.209178)
		(end 37.93236 -313.209178)
		(width 0.16002)
		(layer "In4.Cu")
		(net "M_D_CPU1_SB_DQS_DP<3>")
	)
	(segment
		(start 90.742516 -290.611306)
		(end 90.750898 -290.616132)
		(width 0.09525)
		(layer "In4.Cu")
		(net "M_D_CPU1_SB_DQS_DP<3>")
	)
	(segment
		(start 56.885586 -313.384946)
		(end 57.749186 -312.521346)
		(width 0.16002)
		(layer "In4.Cu")
		(net "M_D_CPU1_SB_DQS_DP<3>")
	)
	(segment
		(start 58.54954 -312.521346)
		(end 58.66638 -312.404506)
		(width 0.16002)
		(layer "In4.Cu")
		(net "M_D_CPU1_SB_DQS_DP<3>")
	)
	(segment
		(start 45.356018 -312.210196)
		(end 46.205902 -313.06008)
		(width 0.16002)
		(layer "In4.Cu")
		(net "M_D_CPU1_SB_DQS_DP<3>")
	)
	(segment
		(start 68.403724 -304.52949)
		(end 68.403724 -304.001932)
		(width 0.16002)
		(layer "In4.Cu")
		(net "M_D_CPU1_SB_DQS_DP<3>")
	)
	(segment
		(start 65.65646 -307.276754)
		(end 65.65646 -306.749196)
		(width 0.16002)
		(layer "In4.Cu")
		(net "M_D_CPU1_SB_DQS_DP<3>")
	)
	(segment
		(start 49.354486 -313.372246)
		(end 50.116486 -312.610246)
		(width 0.16002)
		(layer "In4.Cu")
		(net "M_D_CPU1_SB_DQS_DP<3>")
	)
	(segment
		(start 68.51015 -304.635916)
		(end 68.403724 -304.52949)
		(width 0.16002)
		(layer "In4.Cu")
		(net "M_D_CPU1_SB_DQS_DP<3>")
	)
	(segment
		(start 66.029332 -306.376324)
		(end 66.556382 -306.376324)
		(width 0.16002)
		(layer "In4.Cu")
		(net "M_D_CPU1_SB_DQS_DP<3>")
	)
	(segment
		(start 76.23302 -295.064942)
		(end 76.43749 -294.860472)
		(width 0.09525)
		(layer "In4.Cu")
		(net "M_D_CPU1_SB_DQS_DP<3>")
	)
	(segment
		(start 83.591146 -290.616132)
		(end 83.599528 -290.611306)
		(width 0.09525)
		(layer "In4.Cu")
		(net "M_D_CPU1_SB_DQS_DP<3>")
	)
	(segment
		(start 41.797986 -313.376564)
		(end 42.636186 -312.538364)
		(width 0.16002)
		(layer "In4.Cu")
		(net "M_D_CPU1_SB_DQS_DP<3>")
	)
	(segment
		(start 54.367938 -313.384946)
		(end 55.06212 -312.690764)
		(width 0.16002)
		(layer "In4.Cu")
		(net "M_D_CPU1_SB_DQS_DP<3>")
	)
	(segment
		(start 68.776596 -303.62906)
		(end 69.303646 -303.62906)
		(width 0.16002)
		(layer "In4.Cu")
		(net "M_D_CPU1_SB_DQS_DP<3>")
	)
	(segment
		(start 61.061854 -311.870852)
		(end 61.168534 -311.977532)
		(width 0.16002)
		(layer "In4.Cu")
		(net "M_D_CPU1_SB_DQS_DP<3>")
	)
	(segment
		(start 59.26328 -312.521346)
		(end 59.88431 -312.521346)
		(width 0.16002)
		(layer "In4.Cu")
		(net "M_D_CPU1_SB_DQS_DP<3>")
	)
	(segment
		(start 80.771238 -290.616132)
		(end 80.77962 -290.611306)
		(width 0.09525)
		(layer "In4.Cu")
		(net "M_D_CPU1_SB_DQS_DP<3>")
	)
	(segment
		(start 65.65646 -306.749196)
		(end 66.029332 -306.376324)
		(width 0.16002)
		(layer "In4.Cu")
		(net "M_D_CPU1_SB_DQS_DP<3>")
	)
	(segment
		(start 57.749186 -312.521346)
		(end 58.54954 -312.521346)
		(width 0.16002)
		(layer "In4.Cu")
		(net "M_D_CPU1_SB_DQS_DP<3>")
	)
	(segment
		(start 52.231036 -312.210196)
		(end 53.405786 -313.384946)
		(width 0.16002)
		(layer "In4.Cu")
		(net "M_D_CPU1_SB_DQS_DP<3>")
	)
	(segment
		(start 58.66638 -312.404506)
		(end 59.14644 -312.404506)
		(width 0.16002)
		(layer "In4.Cu")
		(net "M_D_CPU1_SB_DQS_DP<3>")
	)
	(segment
		(start 76.43749 -294.268652)
		(end 76.665328 -293.718488)
		(width 0.09525)
		(layer "In4.Cu")
		(net "M_D_CPU1_SB_DQS_DP<3>")
	)
	(segment
		(start 91.06154 -290.638484)
		(end 91.084908 -290.551616)
		(width 0.09525)
		(layer "In4.Cu")
		(net "M_D_CPU1_SB_DQS_DP<3>")
	)
	(segment
		(start 69.777356 -303.155858)
		(end 69.777356 -302.6283)
		(width 0.16002)
		(layer "In4.Cu")
		(net "M_D_CPU1_SB_DQS_DP<3>")
	)
	(arc
		(start 86.41969 -290.611306)
		(mid 86.701122 -290.535551)
		(end 86.982554 -290.611306)
		(width 0.09525)
		(layer "In4.Cu")
		(net "M_D_CPU1_SB_DQS_DP<3>")
	)
	(arc
		(start 81.350866 -290.616132)
		(mid 81.535898 -290.662046)
		(end 81.719674 -290.611306)
		(width 0.09525)
		(layer "In4.Cu")
		(net "M_D_CPU1_SB_DQS_DP<3>")
	)
	(arc
		(start 82.659474 -290.611306)
		(mid 82.940906 -290.535551)
		(end 83.222338 -290.611306)
		(width 0.09525)
		(layer "In4.Cu")
		(net "M_D_CPU1_SB_DQS_DP<3>")
	)
	(arc
		(start 80.121252 -290.535614)
		(mid 80.266829 -290.554915)
		(end 80.40243 -290.611306)
		(width 0.09525)
		(layer "In4.Cu")
		(net "M_D_CPU1_SB_DQS_DP<3>")
	)
	(arc
		(start 87.35949 -290.611306)
		(mid 87.640922 -290.535551)
		(end 87.922354 -290.611306)
		(width 0.09525)
		(layer "In4.Cu")
		(net "M_D_CPU1_SB_DQS_DP<3>")
	)
	(arc
		(start 80.40243 -290.611306)
		(mid 80.586205 -290.662078)
		(end 80.771238 -290.616132)
		(width 0.09525)
		(layer "In4.Cu")
		(net "M_D_CPU1_SB_DQS_DP<3>")
	)
	(arc
		(start 80.77962 -290.611306)
		(mid 81.061052 -290.535551)
		(end 81.342484 -290.611306)
		(width 0.09525)
		(layer "In4.Cu")
		(net "M_D_CPU1_SB_DQS_DP<3>")
	)
	(arc
		(start 85.479636 -290.611306)
		(mid 85.761068 -290.535551)
		(end 86.0425 -290.611306)
		(width 0.09525)
		(layer "In4.Cu")
		(net "M_D_CPU1_SB_DQS_DP<3>")
	)
	(arc
		(start 83.222338 -290.611306)
		(mid 83.406113 -290.662078)
		(end 83.591146 -290.616132)
		(width 0.09525)
		(layer "In4.Cu")
		(net "M_D_CPU1_SB_DQS_DP<3>")
	)
	(arc
		(start 83.599528 -290.611306)
		(mid 83.88096 -290.535551)
		(end 84.162392 -290.611306)
		(width 0.09525)
		(layer "In4.Cu")
		(net "M_D_CPU1_SB_DQS_DP<3>")
	)
	(arc
		(start 90.179652 -290.611306)
		(mid 90.461084 -290.535551)
		(end 90.742516 -290.611306)
		(width 0.09525)
		(layer "In4.Cu")
		(net "M_D_CPU1_SB_DQS_DP<3>")
	)
	(arc
		(start 86.982554 -290.611306)
		(mid 87.171022 -290.661983)
		(end 87.35949 -290.611306)
		(width 0.09525)
		(layer "In4.Cu")
		(net "M_D_CPU1_SB_DQS_DP<3>")
	)
	(arc
		(start 87.922354 -290.611306)
		(mid 88.106129 -290.662078)
		(end 88.291162 -290.616132)
		(width 0.09525)
		(layer "In4.Cu")
		(net "M_D_CPU1_SB_DQS_DP<3>")
	)
	(arc
		(start 88.862408 -290.611306)
		(mid 89.046183 -290.662078)
		(end 89.231216 -290.616132)
		(width 0.09525)
		(layer "In4.Cu")
		(net "M_D_CPU1_SB_DQS_DP<3>")
	)
	(arc
		(start 86.050882 -290.616132)
		(mid 86.235914 -290.662046)
		(end 86.41969 -290.611306)
		(width 0.09525)
		(layer "In4.Cu")
		(net "M_D_CPU1_SB_DQS_DP<3>")
	)
	(arc
		(start 82.282538 -290.611306)
		(mid 82.471006 -290.661983)
		(end 82.659474 -290.611306)
		(width 0.09525)
		(layer "In4.Cu")
		(net "M_D_CPU1_SB_DQS_DP<3>")
	)
	(arc
		(start 81.719674 -290.611306)
		(mid 82.001106 -290.535551)
		(end 82.282538 -290.611306)
		(width 0.09525)
		(layer "In4.Cu")
		(net "M_D_CPU1_SB_DQS_DP<3>")
	)
	(arc
		(start 89.810844 -290.616132)
		(mid 89.995876 -290.662046)
		(end 90.179652 -290.611306)
		(width 0.09525)
		(layer "In4.Cu")
		(net "M_D_CPU1_SB_DQS_DP<3>")
	)
	(arc
		(start 89.239598 -290.611306)
		(mid 89.52103 -290.535551)
		(end 89.802462 -290.611306)
		(width 0.09525)
		(layer "In4.Cu")
		(net "M_D_CPU1_SB_DQS_DP<3>")
	)
	(arc
		(start 84.539582 -290.611306)
		(mid 84.821014 -290.535551)
		(end 85.102446 -290.611306)
		(width 0.09525)
		(layer "In4.Cu")
		(net "M_D_CPU1_SB_DQS_DP<3>")
	)
	(arc
		(start 90.750898 -290.616132)
		(mid 90.903793 -290.66096)
		(end 91.06154 -290.638484)
		(width 0.09525)
		(layer "In4.Cu")
		(net "M_D_CPU1_SB_DQS_DP<3>")
	)
	(arc
		(start 84.162392 -290.611306)
		(mid 84.346167 -290.662078)
		(end 84.5312 -290.616132)
		(width 0.09525)
		(layer "In4.Cu")
		(net "M_D_CPU1_SB_DQS_DP<3>")
	)
	(arc
		(start 88.299544 -290.611306)
		(mid 88.580976 -290.535551)
		(end 88.862408 -290.611306)
		(width 0.09525)
		(layer "In4.Cu")
		(net "M_D_CPU1_SB_DQS_DP<3>")
	)
	(arc
		(start 85.110828 -290.616132)
		(mid 85.29586 -290.662046)
		(end 85.479636 -290.611306)
		(width 0.09525)
		(layer "In4.Cu")
		(net "M_D_CPU1_SB_DQS_DP<3>")
	)
	(segment
		(start 91.397836 -285.160466)
		(end 90.930984 -285.426404)
		(width 0.12954)
		(layer "F.Cu")
		(net "M_D_CPU1_SB_DQS_DP<2>")
	)
	(segment
		(start 41.123108 -303.710086)
		(end 41.442386 -304.029364)
		(width 0.16002)
		(layer "In4.Cu")
		(net "M_D_CPU1_SB_DQS_DP<2>")
	)
	(segment
		(start 54.390798 -304.092864)
		(end 55.140098 -303.343564)
		(width 0.16002)
		(layer "In4.Cu")
		(net "M_D_CPU1_SB_DQS_DP<2>")
	)
	(segment
		(start 43.500548 -302.860202)
		(end 45.835824 -302.860202)
		(width 0.16002)
		(layer "In4.Cu")
		(net "M_D_CPU1_SB_DQS_DP<2>")
	)
	(segment
		(start 61.41847 -301.09033)
		(end 61.860684 -300.648116)
		(width 0.16002)
		(layer "In4.Cu")
		(net "M_D_CPU1_SB_DQS_DP<2>")
	)
	(segment
		(start 65.622932 -298.11218)
		(end 65.819782 -297.91533)
		(width 0.16002)
		(layer "In4.Cu")
		(net "M_D_CPU1_SB_DQS_DP<2>")
	)
	(segment
		(start 66.508884 -296.52722)
		(end 66.720212 -296.738548)
		(width 0.16002)
		(layer "In4.Cu")
		(net "M_D_CPU1_SB_DQS_DP<2>")
	)
	(segment
		(start 85.102446 -285.751524)
		(end 85.110828 -285.75635)
		(width 0.09525)
		(layer "In4.Cu")
		(net "M_D_CPU1_SB_DQS_DP<2>")
	)
	(segment
		(start 49.354486 -304.022252)
		(end 50.116486 -303.260252)
		(width 0.16002)
		(layer "In4.Cu")
		(net "M_D_CPU1_SB_DQS_DP<2>")
	)
	(segment
		(start 56.500014 -304.473864)
		(end 57.802526 -303.171352)
		(width 0.16002)
		(layer "In4.Cu")
		(net "M_D_CPU1_SB_DQS_DP<2>")
	)
	(segment
		(start 56.066944 -304.275998)
		(end 56.26481 -304.473864)
		(width 0.16002)
		(layer "In4.Cu")
		(net "M_D_CPU1_SB_DQS_DP<2>")
	)
	(segment
		(start 64.44615 -299.012356)
		(end 64.235076 -298.801282)
		(width 0.16002)
		(layer "In4.Cu")
		(net "M_D_CPU1_SB_DQS_DP<2>")
	)
	(segment
		(start 41.797986 -304.029364)
		(end 42.610786 -303.216564)
		(width 0.16002)
		(layer "In4.Cu")
		(net "M_D_CPU1_SB_DQS_DP<2>")
	)
	(segment
		(start 91.06154 -285.778702)
		(end 91.084908 -285.691834)
		(width 0.09525)
		(layer "In4.Cu")
		(net "M_D_CPU1_SB_DQS_DP<2>")
	)
	(segment
		(start 75.955906 -286.552894)
		(end 75.97267 -286.53613)
		(width 0.09525)
		(layer "In4.Cu")
		(net "M_D_CPU1_SB_DQS_DP<2>")
	)
	(segment
		(start 42.610786 -303.216564)
		(end 43.144186 -303.216564)
		(width 0.16002)
		(layer "In4.Cu")
		(net "M_D_CPU1_SB_DQS_DP<2>")
	)
	(segment
		(start 60.230004 -303.171352)
		(end 61.41847 -301.982886)
		(width 0.16002)
		(layer "In4.Cu")
		(net "M_D_CPU1_SB_DQS_DP<2>")
	)
	(segment
		(start 56.26481 -304.473864)
		(end 56.500014 -304.473864)
		(width 0.16002)
		(layer "In4.Cu")
		(net "M_D_CPU1_SB_DQS_DP<2>")
	)
	(segment
		(start 66.720212 -296.738548)
		(end 66.996564 -296.738548)
		(width 0.16002)
		(layer "In4.Cu")
		(net "M_D_CPU1_SB_DQS_DP<2>")
	)
	(segment
		(start 64.607948 -297.900852)
		(end 65.135252 -297.900852)
		(width 0.16002)
		(layer "In4.Cu")
		(net "M_D_CPU1_SB_DQS_DP<2>")
	)
	(segment
		(start 63.072518 -300.385988)
		(end 62.861444 -300.174914)
		(width 0.16002)
		(layer "In4.Cu")
		(net "M_D_CPU1_SB_DQS_DP<2>")
	)
	(segment
		(start 36.795964 -303.585372)
		(end 37.069776 -303.859184)
		(width 0.16002)
		(layer "In4.Cu")
		(net "M_D_CPU1_SB_DQS_DP<2>")
	)
	(segment
		(start 62.861444 -300.174914)
		(end 62.861444 -299.647356)
		(width 0.16002)
		(layer "In4.Cu")
		(net "M_D_CPU1_SB_DQS_DP<2>")
	)
	(segment
		(start 39.804086 -303.710086)
		(end 41.123108 -303.710086)
		(width 0.16002)
		(layer "In4.Cu")
		(net "M_D_CPU1_SB_DQS_DP<2>")
	)
	(segment
		(start 63.76162 -299.274484)
		(end 63.972948 -299.485812)
		(width 0.16002)
		(layer "In4.Cu")
		(net "M_D_CPU1_SB_DQS_DP<2>")
	)
	(segment
		(start 39.654988 -303.859184)
		(end 39.804086 -303.710086)
		(width 0.16002)
		(layer "In4.Cu")
		(net "M_D_CPU1_SB_DQS_DP<2>")
	)
	(segment
		(start 66.98234 -295.52646)
		(end 75.955906 -286.552894)
		(width 0.16002)
		(layer "In4.Cu")
		(net "M_D_CPU1_SB_DQS_DP<2>")
	)
	(segment
		(start 46.685708 -303.710086)
		(end 48.68418 -303.710086)
		(width 0.16002)
		(layer "In4.Cu")
		(net "M_D_CPU1_SB_DQS_DP<2>")
	)
	(segment
		(start 43.144186 -303.216564)
		(end 43.500548 -302.860202)
		(width 0.16002)
		(layer "In4.Cu")
		(net "M_D_CPU1_SB_DQS_DP<2>")
	)
	(segment
		(start 89.231216 -285.75635)
		(end 89.239598 -285.751524)
		(width 0.09525)
		(layer "In4.Cu")
		(net "M_D_CPU1_SB_DQS_DP<2>")
	)
	(segment
		(start 59.63158 -303.171352)
		(end 60.230004 -303.171352)
		(width 0.16002)
		(layer "In4.Cu")
		(net "M_D_CPU1_SB_DQS_DP<2>")
	)
	(segment
		(start 67.193414 -296.265092)
		(end 66.98234 -296.054018)
		(width 0.16002)
		(layer "In4.Cu")
		(net "M_D_CPU1_SB_DQS_DP<2>")
	)
	(segment
		(start 62.875668 -300.859444)
		(end 63.072518 -300.662594)
		(width 0.16002)
		(layer "In4.Cu")
		(net "M_D_CPU1_SB_DQS_DP<2>")
	)
	(segment
		(start 50.999136 -302.860202)
		(end 52.363878 -302.860202)
		(width 0.16002)
		(layer "In4.Cu")
		(net "M_D_CPU1_SB_DQS_DP<2>")
	)
	(segment
		(start 86.0425 -285.751524)
		(end 86.050882 -285.75635)
		(width 0.09525)
		(layer "In4.Cu")
		(net "M_D_CPU1_SB_DQS_DP<2>")
	)
	(segment
		(start 65.608708 -296.900092)
		(end 65.98158 -296.52722)
		(width 0.16002)
		(layer "In4.Cu")
		(net "M_D_CPU1_SB_DQS_DP<2>")
	)
	(segment
		(start 53.59654 -304.092864)
		(end 54.390798 -304.092864)
		(width 0.16002)
		(layer "In4.Cu")
		(net "M_D_CPU1_SB_DQS_DP<2>")
	)
	(segment
		(start 78.005686 -285.803086)
		(end 78.711044 -285.803086)
		(width 0.09525)
		(layer "In4.Cu")
		(net "M_D_CPU1_SB_DQS_DP<2>")
	)
	(segment
		(start 66.98234 -296.054018)
		(end 66.98234 -295.52646)
		(width 0.16002)
		(layer "In4.Cu")
		(net "M_D_CPU1_SB_DQS_DP<2>")
	)
	(segment
		(start 38.3794 -303.742344)
		(end 38.49624 -303.859184)
		(width 0.16002)
		(layer "In4.Cu")
		(net "M_D_CPU1_SB_DQS_DP<2>")
	)
	(segment
		(start 89.802462 -285.751524)
		(end 89.810844 -285.75635)
		(width 0.09525)
		(layer "In4.Cu")
		(net "M_D_CPU1_SB_DQS_DP<2>")
	)
	(segment
		(start 57.802526 -303.171352)
		(end 58.91784 -303.171352)
		(width 0.16002)
		(layer "In4.Cu")
		(net "M_D_CPU1_SB_DQS_DP<2>")
	)
	(segment
		(start 50.116486 -303.260252)
		(end 50.599086 -303.260252)
		(width 0.16002)
		(layer "In4.Cu")
		(net "M_D_CPU1_SB_DQS_DP<2>")
	)
	(segment
		(start 61.41847 -301.982886)
		(end 61.41847 -301.09033)
		(width 0.16002)
		(layer "In4.Cu")
		(net "M_D_CPU1_SB_DQS_DP<2>")
	)
	(segment
		(start 79.45247 -285.745428)
		(end 79.462884 -285.751524)
		(width 0.09525)
		(layer "In4.Cu")
		(net "M_D_CPU1_SB_DQS_DP<2>")
	)
	(segment
		(start 63.072518 -300.662594)
		(end 63.072518 -300.385988)
		(width 0.16002)
		(layer "In4.Cu")
		(net "M_D_CPU1_SB_DQS_DP<2>")
	)
	(segment
		(start 90.742516 -285.751524)
		(end 90.750898 -285.75635)
		(width 0.09525)
		(layer "In4.Cu")
		(net "M_D_CPU1_SB_DQS_DP<2>")
	)
	(segment
		(start 41.442386 -304.029364)
		(end 41.797986 -304.029364)
		(width 0.16002)
		(layer "In4.Cu")
		(net "M_D_CPU1_SB_DQS_DP<2>")
	)
	(segment
		(start 48.996346 -304.022252)
		(end 49.354486 -304.022252)
		(width 0.16002)
		(layer "In4.Cu")
		(net "M_D_CPU1_SB_DQS_DP<2>")
	)
	(segment
		(start 45.835824 -302.860202)
		(end 46.685708 -303.710086)
		(width 0.16002)
		(layer "In4.Cu")
		(net "M_D_CPU1_SB_DQS_DP<2>")
	)
	(segment
		(start 79.83982 -285.751524)
		(end 79.850234 -285.745428)
		(width 0.09525)
		(layer "In4.Cu")
		(net "M_D_CPU1_SB_DQS_DP<2>")
	)
	(segment
		(start 58.91784 -303.171352)
		(end 59.03468 -303.054512)
		(width 0.16002)
		(layer "In4.Cu")
		(net "M_D_CPU1_SB_DQS_DP<2>")
	)
	(segment
		(start 77.443076 -286.365696)
		(end 78.005686 -285.803086)
		(width 0.09525)
		(layer "In4.Cu")
		(net "M_D_CPU1_SB_DQS_DP<2>")
	)
	(segment
		(start 55.68315 -303.343564)
		(end 56.066944 -303.727358)
		(width 0.16002)
		(layer "In4.Cu")
		(net "M_D_CPU1_SB_DQS_DP<2>")
	)
	(segment
		(start 81.342484 -285.751524)
		(end 81.350866 -285.75635)
		(width 0.09525)
		(layer "In4.Cu")
		(net "M_D_CPU1_SB_DQS_DP<2>")
	)
	(segment
		(start 62.599316 -300.859444)
		(end 62.875668 -300.859444)
		(width 0.16002)
		(layer "In4.Cu")
		(net "M_D_CPU1_SB_DQS_DP<2>")
	)
	(segment
		(start 65.819782 -297.638724)
		(end 65.608708 -297.42765)
		(width 0.16002)
		(layer "In4.Cu")
		(net "M_D_CPU1_SB_DQS_DP<2>")
	)
	(segment
		(start 50.599086 -303.260252)
		(end 50.999136 -302.860202)
		(width 0.16002)
		(layer "In4.Cu")
		(net "M_D_CPU1_SB_DQS_DP<2>")
	)
	(segment
		(start 65.135252 -297.900852)
		(end 65.34658 -298.11218)
		(width 0.16002)
		(layer "In4.Cu")
		(net "M_D_CPU1_SB_DQS_DP<2>")
	)
	(segment
		(start 64.44615 -299.288962)
		(end 64.44615 -299.012356)
		(width 0.16002)
		(layer "In4.Cu")
		(net "M_D_CPU1_SB_DQS_DP<2>")
	)
	(segment
		(start 76.05649 -286.53613)
		(end 76.226924 -286.365696)
		(width 0.09525)
		(layer "In4.Cu")
		(net "M_D_CPU1_SB_DQS_DP<2>")
	)
	(segment
		(start 62.861444 -299.647356)
		(end 63.234316 -299.274484)
		(width 0.16002)
		(layer "In4.Cu")
		(net "M_D_CPU1_SB_DQS_DP<2>")
	)
	(segment
		(start 80.771238 -285.75635)
		(end 80.77962 -285.751524)
		(width 0.09525)
		(layer "In4.Cu")
		(net "M_D_CPU1_SB_DQS_DP<2>")
	)
	(segment
		(start 67.193414 -296.541698)
		(end 67.193414 -296.265092)
		(width 0.16002)
		(layer "In4.Cu")
		(net "M_D_CPU1_SB_DQS_DP<2>")
	)
	(segment
		(start 52.363878 -302.860202)
		(end 53.59654 -304.092864)
		(width 0.16002)
		(layer "In4.Cu")
		(net "M_D_CPU1_SB_DQS_DP<2>")
	)
	(segment
		(start 84.5312 -285.75635)
		(end 84.539582 -285.751524)
		(width 0.09525)
		(layer "In4.Cu")
		(net "M_D_CPU1_SB_DQS_DP<2>")
	)
	(segment
		(start 37.069776 -303.859184)
		(end 37.7825 -303.859184)
		(width 0.16002)
		(layer "In4.Cu")
		(net "M_D_CPU1_SB_DQS_DP<2>")
	)
	(segment
		(start 91.084908 -285.691834)
		(end 90.930984 -285.426404)
		(width 0.09525)
		(layer "In4.Cu")
		(net "M_D_CPU1_SB_DQS_DP<2>")
	)
	(segment
		(start 83.591146 -285.75635)
		(end 83.599528 -285.751524)
		(width 0.09525)
		(layer "In4.Cu")
		(net "M_D_CPU1_SB_DQS_DP<2>")
	)
	(segment
		(start 37.7825 -303.859184)
		(end 37.89934 -303.742344)
		(width 0.16002)
		(layer "In4.Cu")
		(net "M_D_CPU1_SB_DQS_DP<2>")
	)
	(segment
		(start 61.860684 -300.648116)
		(end 62.387988 -300.648116)
		(width 0.16002)
		(layer "In4.Cu")
		(net "M_D_CPU1_SB_DQS_DP<2>")
	)
	(segment
		(start 59.03468 -303.054512)
		(end 59.51474 -303.054512)
		(width 0.16002)
		(layer "In4.Cu")
		(net "M_D_CPU1_SB_DQS_DP<2>")
	)
	(segment
		(start 64.235076 -298.801282)
		(end 64.235076 -298.273724)
		(width 0.16002)
		(layer "In4.Cu")
		(net "M_D_CPU1_SB_DQS_DP<2>")
	)
	(segment
		(start 75.97267 -286.53613)
		(end 76.05649 -286.53613)
		(width 0.09525)
		(layer "In4.Cu")
		(net "M_D_CPU1_SB_DQS_DP<2>")
	)
	(segment
		(start 76.226924 -286.365696)
		(end 77.443076 -286.365696)
		(width 0.09525)
		(layer "In4.Cu")
		(net "M_D_CPU1_SB_DQS_DP<2>")
	)
	(segment
		(start 65.98158 -296.52722)
		(end 66.508884 -296.52722)
		(width 0.16002)
		(layer "In4.Cu")
		(net "M_D_CPU1_SB_DQS_DP<2>")
	)
	(segment
		(start 56.066944 -303.727358)
		(end 56.066944 -304.275998)
		(width 0.16002)
		(layer "In4.Cu")
		(net "M_D_CPU1_SB_DQS_DP<2>")
	)
	(segment
		(start 63.972948 -299.485812)
		(end 64.2493 -299.485812)
		(width 0.16002)
		(layer "In4.Cu")
		(net "M_D_CPU1_SB_DQS_DP<2>")
	)
	(segment
		(start 66.996564 -296.738548)
		(end 67.193414 -296.541698)
		(width 0.16002)
		(layer "In4.Cu")
		(net "M_D_CPU1_SB_DQS_DP<2>")
	)
	(segment
		(start 63.234316 -299.274484)
		(end 63.76162 -299.274484)
		(width 0.16002)
		(layer "In4.Cu")
		(net "M_D_CPU1_SB_DQS_DP<2>")
	)
	(segment
		(start 59.51474 -303.054512)
		(end 59.63158 -303.171352)
		(width 0.16002)
		(layer "In4.Cu")
		(net "M_D_CPU1_SB_DQS_DP<2>")
	)
	(segment
		(start 65.608708 -297.42765)
		(end 65.608708 -296.900092)
		(width 0.16002)
		(layer "In4.Cu")
		(net "M_D_CPU1_SB_DQS_DP<2>")
	)
	(segment
		(start 64.235076 -298.273724)
		(end 64.607948 -297.900852)
		(width 0.16002)
		(layer "In4.Cu")
		(net "M_D_CPU1_SB_DQS_DP<2>")
	)
	(segment
		(start 65.819782 -297.91533)
		(end 65.819782 -297.638724)
		(width 0.16002)
		(layer "In4.Cu")
		(net "M_D_CPU1_SB_DQS_DP<2>")
	)
	(segment
		(start 55.140098 -303.343564)
		(end 55.68315 -303.343564)
		(width 0.16002)
		(layer "In4.Cu")
		(net "M_D_CPU1_SB_DQS_DP<2>")
	)
	(segment
		(start 37.89934 -303.742344)
		(end 38.3794 -303.742344)
		(width 0.16002)
		(layer "In4.Cu")
		(net "M_D_CPU1_SB_DQS_DP<2>")
	)
	(segment
		(start 38.49624 -303.859184)
		(end 39.654988 -303.859184)
		(width 0.16002)
		(layer "In4.Cu")
		(net "M_D_CPU1_SB_DQS_DP<2>")
	)
	(segment
		(start 65.34658 -298.11218)
		(end 65.622932 -298.11218)
		(width 0.16002)
		(layer "In4.Cu")
		(net "M_D_CPU1_SB_DQS_DP<2>")
	)
	(segment
		(start 64.2493 -299.485812)
		(end 64.44615 -299.288962)
		(width 0.16002)
		(layer "In4.Cu")
		(net "M_D_CPU1_SB_DQS_DP<2>")
	)
	(segment
		(start 88.291162 -285.75635)
		(end 88.299544 -285.751524)
		(width 0.09525)
		(layer "In4.Cu")
		(net "M_D_CPU1_SB_DQS_DP<2>")
	)
	(segment
		(start 48.68418 -303.710086)
		(end 48.996346 -304.022252)
		(width 0.16002)
		(layer "In4.Cu")
		(net "M_D_CPU1_SB_DQS_DP<2>")
	)
	(segment
		(start 62.387988 -300.648116)
		(end 62.599316 -300.859444)
		(width 0.16002)
		(layer "In4.Cu")
		(net "M_D_CPU1_SB_DQS_DP<2>")
	)
	(arc
		(start 87.922354 -285.751524)
		(mid 88.106129 -285.802296)
		(end 88.291162 -285.75635)
		(width 0.09525)
		(layer "In4.Cu")
		(net "M_D_CPU1_SB_DQS_DP<2>")
	)
	(arc
		(start 79.462884 -285.751524)
		(mid 79.651352 -285.802201)
		(end 79.83982 -285.751524)
		(width 0.09525)
		(layer "In4.Cu")
		(net "M_D_CPU1_SB_DQS_DP<2>")
	)
	(arc
		(start 79.850234 -285.745428)
		(mid 80.127142 -285.675751)
		(end 80.40243 -285.751524)
		(width 0.09525)
		(layer "In4.Cu")
		(net "M_D_CPU1_SB_DQS_DP<2>")
	)
	(arc
		(start 80.77962 -285.751524)
		(mid 81.061052 -285.675769)
		(end 81.342484 -285.751524)
		(width 0.09525)
		(layer "In4.Cu")
		(net "M_D_CPU1_SB_DQS_DP<2>")
	)
	(arc
		(start 89.810844 -285.75635)
		(mid 89.995876 -285.802264)
		(end 90.179652 -285.751524)
		(width 0.09525)
		(layer "In4.Cu")
		(net "M_D_CPU1_SB_DQS_DP<2>")
	)
	(arc
		(start 85.479636 -285.751524)
		(mid 85.761068 -285.675769)
		(end 86.0425 -285.751524)
		(width 0.09525)
		(layer "In4.Cu")
		(net "M_D_CPU1_SB_DQS_DP<2>")
	)
	(arc
		(start 82.282538 -285.751524)
		(mid 82.471006 -285.802201)
		(end 82.659474 -285.751524)
		(width 0.09525)
		(layer "In4.Cu")
		(net "M_D_CPU1_SB_DQS_DP<2>")
	)
	(arc
		(start 86.982554 -285.751524)
		(mid 87.171022 -285.802201)
		(end 87.35949 -285.751524)
		(width 0.09525)
		(layer "In4.Cu")
		(net "M_D_CPU1_SB_DQS_DP<2>")
	)
	(arc
		(start 82.659474 -285.751524)
		(mid 82.940906 -285.675769)
		(end 83.222338 -285.751524)
		(width 0.09525)
		(layer "In4.Cu")
		(net "M_D_CPU1_SB_DQS_DP<2>")
	)
	(arc
		(start 83.599528 -285.751524)
		(mid 83.88096 -285.675769)
		(end 84.162392 -285.751524)
		(width 0.09525)
		(layer "In4.Cu")
		(net "M_D_CPU1_SB_DQS_DP<2>")
	)
	(arc
		(start 81.719674 -285.751524)
		(mid 82.001106 -285.675769)
		(end 82.282538 -285.751524)
		(width 0.09525)
		(layer "In4.Cu")
		(net "M_D_CPU1_SB_DQS_DP<2>")
	)
	(arc
		(start 86.41969 -285.751524)
		(mid 86.701122 -285.675769)
		(end 86.982554 -285.751524)
		(width 0.09525)
		(layer "In4.Cu")
		(net "M_D_CPU1_SB_DQS_DP<2>")
	)
	(arc
		(start 81.350866 -285.75635)
		(mid 81.535898 -285.802264)
		(end 81.719674 -285.751524)
		(width 0.09525)
		(layer "In4.Cu")
		(net "M_D_CPU1_SB_DQS_DP<2>")
	)
	(arc
		(start 89.239598 -285.751524)
		(mid 89.52103 -285.675769)
		(end 89.802462 -285.751524)
		(width 0.09525)
		(layer "In4.Cu")
		(net "M_D_CPU1_SB_DQS_DP<2>")
	)
	(arc
		(start 84.539582 -285.751524)
		(mid 84.821014 -285.675769)
		(end 85.102446 -285.751524)
		(width 0.09525)
		(layer "In4.Cu")
		(net "M_D_CPU1_SB_DQS_DP<2>")
	)
	(arc
		(start 85.110828 -285.75635)
		(mid 85.29586 -285.802264)
		(end 85.479636 -285.751524)
		(width 0.09525)
		(layer "In4.Cu")
		(net "M_D_CPU1_SB_DQS_DP<2>")
	)
	(arc
		(start 80.40243 -285.751524)
		(mid 80.586205 -285.802296)
		(end 80.771238 -285.75635)
		(width 0.09525)
		(layer "In4.Cu")
		(net "M_D_CPU1_SB_DQS_DP<2>")
	)
	(arc
		(start 83.222338 -285.751524)
		(mid 83.406113 -285.802296)
		(end 83.591146 -285.75635)
		(width 0.09525)
		(layer "In4.Cu")
		(net "M_D_CPU1_SB_DQS_DP<2>")
	)
	(arc
		(start 87.35949 -285.751524)
		(mid 87.640922 -285.675769)
		(end 87.922354 -285.751524)
		(width 0.09525)
		(layer "In4.Cu")
		(net "M_D_CPU1_SB_DQS_DP<2>")
	)
	(arc
		(start 90.179652 -285.751524)
		(mid 90.461084 -285.675769)
		(end 90.742516 -285.751524)
		(width 0.09525)
		(layer "In4.Cu")
		(net "M_D_CPU1_SB_DQS_DP<2>")
	)
	(arc
		(start 90.750898 -285.75635)
		(mid 90.903793 -285.801178)
		(end 91.06154 -285.778702)
		(width 0.09525)
		(layer "In4.Cu")
		(net "M_D_CPU1_SB_DQS_DP<2>")
	)
	(arc
		(start 84.162392 -285.751524)
		(mid 84.346167 -285.802296)
		(end 84.5312 -285.75635)
		(width 0.09525)
		(layer "In4.Cu")
		(net "M_D_CPU1_SB_DQS_DP<2>")
	)
	(arc
		(start 78.899766 -285.751524)
		(mid 79.175309 -285.675675)
		(end 79.45247 -285.745428)
		(width 0.09525)
		(layer "In4.Cu")
		(net "M_D_CPU1_SB_DQS_DP<2>")
	)
	(arc
		(start 88.862408 -285.751524)
		(mid 89.046183 -285.802296)
		(end 89.231216 -285.75635)
		(width 0.09525)
		(layer "In4.Cu")
		(net "M_D_CPU1_SB_DQS_DP<2>")
	)
	(arc
		(start 86.050882 -285.75635)
		(mid 86.235914 -285.802264)
		(end 86.41969 -285.751524)
		(width 0.09525)
		(layer "In4.Cu")
		(net "M_D_CPU1_SB_DQS_DP<2>")
	)
	(arc
		(start 78.711044 -285.803086)
		(mid 78.8088 -285.789752)
		(end 78.899766 -285.751524)
		(width 0.09525)
		(layer "In4.Cu")
		(net "M_D_CPU1_SB_DQS_DP<2>")
	)
	(arc
		(start 88.299544 -285.751524)
		(mid 88.580976 -285.675769)
		(end 88.862408 -285.751524)
		(width 0.09525)
		(layer "In4.Cu")
		(net "M_D_CPU1_SB_DQS_DP<2>")
	)
	(segment
		(start 91.397836 -280.30043)
		(end 90.930984 -280.566368)
		(width 0.12954)
		(layer "F.Cu")
		(net "M_D_CPU1_SB_DQS_DP<1>")
	)
	(segment
		(start 41.76014 -294.72001)
		(end 42.610786 -293.869364)
		(width 0.16002)
		(layer "In4.Cu")
		(net "M_D_CPU1_SB_DQS_DP<1>")
	)
	(segment
		(start 69.795898 -284.361382)
		(end 70.072758 -284.361382)
		(width 0.16002)
		(layer "In4.Cu")
		(net "M_D_CPU1_SB_DQS_DP<1>")
	)
	(segment
		(start 70.463156 -282.80868)
		(end 70.99046 -282.80868)
		(width 0.16002)
		(layer "In4.Cu")
		(net "M_D_CPU1_SB_DQS_DP<1>")
	)
	(segment
		(start 38.43782 -294.50919)
		(end 39.294054 -294.50919)
		(width 0.16002)
		(layer "In4.Cu")
		(net "M_D_CPU1_SB_DQS_DP<1>")
	)
	(segment
		(start 41.454832 -294.72001)
		(end 41.76014 -294.72001)
		(width 0.16002)
		(layer "In4.Cu")
		(net "M_D_CPU1_SB_DQS_DP<1>")
	)
	(segment
		(start 71.836788 -281.435048)
		(end 72.364092 -281.435048)
		(width 0.16002)
		(layer "In4.Cu")
		(net "M_D_CPU1_SB_DQS_DP<1>")
	)
	(segment
		(start 80.771238 -280.896314)
		(end 80.77962 -280.891488)
		(width 0.09525)
		(layer "In4.Cu")
		(net "M_D_CPU1_SB_DQS_DP<1>")
	)
	(segment
		(start 76.155296 -280.780236)
		(end 76.214478 -280.839418)
		(width 0.09525)
		(layer "In4.Cu")
		(net "M_D_CPU1_SB_DQS_DP<1>")
	)
	(segment
		(start 86.0425 -280.891488)
		(end 86.050882 -280.896314)
		(width 0.09525)
		(layer "In4.Cu")
		(net "M_D_CPU1_SB_DQS_DP<1>")
	)
	(segment
		(start 39.294054 -294.50919)
		(end 39.443152 -294.360092)
		(width 0.16002)
		(layer "In4.Cu")
		(net "M_D_CPU1_SB_DQS_DP<1>")
	)
	(segment
		(start 37.72408 -294.50919)
		(end 37.84092 -294.39235)
		(width 0.16002)
		(layer "In4.Cu")
		(net "M_D_CPU1_SB_DQS_DP<1>")
	)
	(segment
		(start 56.885586 -294.684958)
		(end 57.749186 -293.821358)
		(width 0.16002)
		(layer "In4.Cu")
		(net "M_D_CPU1_SB_DQS_DP<1>")
	)
	(segment
		(start 43.554142 -293.510208)
		(end 45.223684 -293.510208)
		(width 0.16002)
		(layer "In4.Cu")
		(net "M_D_CPU1_SB_DQS_DP<1>")
	)
	(segment
		(start 66.147696 -288.009584)
		(end 65.968626 -287.830514)
		(width 0.16002)
		(layer "In4.Cu")
		(net "M_D_CPU1_SB_DQS_DP<1>")
	)
	(segment
		(start 49.354486 -294.672258)
		(end 50.116486 -293.910258)
		(width 0.16002)
		(layer "In4.Cu")
		(net "M_D_CPU1_SB_DQS_DP<1>")
	)
	(segment
		(start 53.527706 -294.684958)
		(end 56.885586 -294.684958)
		(width 0.16002)
		(layer "In4.Cu")
		(net "M_D_CPU1_SB_DQS_DP<1>")
	)
	(segment
		(start 88.291162 -280.896314)
		(end 88.299544 -280.891488)
		(width 0.09525)
		(layer "In4.Cu")
		(net "M_D_CPU1_SB_DQS_DP<1>")
	)
	(segment
		(start 67.048634 -287.108646)
		(end 67.325494 -287.108646)
		(width 0.16002)
		(layer "In4.Cu")
		(net "M_D_CPU1_SB_DQS_DP<1>")
	)
	(segment
		(start 37.84092 -294.39235)
		(end 38.32098 -294.39235)
		(width 0.16002)
		(layer "In4.Cu")
		(net "M_D_CPU1_SB_DQS_DP<1>")
	)
	(segment
		(start 83.591146 -280.896314)
		(end 83.599528 -280.891488)
		(width 0.09525)
		(layer "In4.Cu")
		(net "M_D_CPU1_SB_DQS_DP<1>")
	)
	(segment
		(start 70.089522 -283.182314)
		(end 70.463156 -282.80868)
		(width 0.16002)
		(layer "In4.Cu")
		(net "M_D_CPU1_SB_DQS_DP<1>")
	)
	(segment
		(start 70.268592 -284.165548)
		(end 70.268592 -283.888688)
		(width 0.16002)
		(layer "In4.Cu")
		(net "M_D_CPU1_SB_DQS_DP<1>")
	)
	(segment
		(start 52.352956 -293.510208)
		(end 53.527706 -294.684958)
		(width 0.16002)
		(layer "In4.Cu")
		(net "M_D_CPU1_SB_DQS_DP<1>")
	)
	(segment
		(start 89.802462 -280.891488)
		(end 89.810844 -280.896314)
		(width 0.09525)
		(layer "In4.Cu")
		(net "M_D_CPU1_SB_DQS_DP<1>")
	)
	(segment
		(start 66.147696 -288.286444)
		(end 66.147696 -288.009584)
		(width 0.16002)
		(layer "In4.Cu")
		(net "M_D_CPU1_SB_DQS_DP<1>")
	)
	(segment
		(start 67.342258 -285.929578)
		(end 67.715892 -285.555944)
		(width 0.16002)
		(layer "In4.Cu")
		(net "M_D_CPU1_SB_DQS_DP<1>")
	)
	(segment
		(start 72.364092 -281.435048)
		(end 72.543162 -281.614118)
		(width 0.16002)
		(layer "In4.Cu")
		(net "M_D_CPU1_SB_DQS_DP<1>")
	)
	(segment
		(start 78.52283 -280.891488)
		(end 78.534768 -280.898346)
		(width 0.09525)
		(layer "In4.Cu")
		(net "M_D_CPU1_SB_DQS_DP<1>")
	)
	(segment
		(start 43.194986 -293.869364)
		(end 43.554142 -293.510208)
		(width 0.16002)
		(layer "In4.Cu")
		(net "M_D_CPU1_SB_DQS_DP<1>")
	)
	(segment
		(start 68.71589 -285.08325)
		(end 68.71589 -284.555946)
		(width 0.16002)
		(layer "In4.Cu")
		(net "M_D_CPU1_SB_DQS_DP<1>")
	)
	(segment
		(start 67.325494 -287.108646)
		(end 67.521328 -286.912812)
		(width 0.16002)
		(layer "In4.Cu")
		(net "M_D_CPU1_SB_DQS_DP<1>")
	)
	(segment
		(start 90.742516 -280.891488)
		(end 90.750898 -280.896314)
		(width 0.09525)
		(layer "In4.Cu")
		(net "M_D_CPU1_SB_DQS_DP<1>")
	)
	(segment
		(start 66.34226 -286.929576)
		(end 66.869564 -286.929576)
		(width 0.16002)
		(layer "In4.Cu")
		(net "M_D_CPU1_SB_DQS_DP<1>")
	)
	(segment
		(start 50.599086 -293.910258)
		(end 50.999136 -293.510208)
		(width 0.16002)
		(layer "In4.Cu")
		(net "M_D_CPU1_SB_DQS_DP<1>")
	)
	(segment
		(start 76.478638 -280.839418)
		(end 76.782168 -280.535888)
		(width 0.09525)
		(layer "In4.Cu")
		(net "M_D_CPU1_SB_DQS_DP<1>")
	)
	(segment
		(start 42.610786 -293.869364)
		(end 43.194986 -293.869364)
		(width 0.16002)
		(layer "In4.Cu")
		(net "M_D_CPU1_SB_DQS_DP<1>")
	)
	(segment
		(start 71.16953 -282.98775)
		(end 71.44639 -282.98775)
		(width 0.16002)
		(layer "In4.Cu")
		(net "M_D_CPU1_SB_DQS_DP<1>")
	)
	(segment
		(start 68.422266 -285.735014)
		(end 68.699126 -285.735014)
		(width 0.16002)
		(layer "In4.Cu")
		(net "M_D_CPU1_SB_DQS_DP<1>")
	)
	(segment
		(start 71.642224 -282.515056)
		(end 71.463154 -282.335986)
		(width 0.16002)
		(layer "In4.Cu")
		(net "M_D_CPU1_SB_DQS_DP<1>")
	)
	(segment
		(start 38.32098 -294.39235)
		(end 38.43782 -294.50919)
		(width 0.16002)
		(layer "In4.Cu")
		(net "M_D_CPU1_SB_DQS_DP<1>")
	)
	(segment
		(start 46.073568 -294.360092)
		(end 48.653192 -294.360092)
		(width 0.16002)
		(layer "In4.Cu")
		(net "M_D_CPU1_SB_DQS_DP<1>")
	)
	(segment
		(start 67.521328 -286.912812)
		(end 67.521328 -286.635952)
		(width 0.16002)
		(layer "In4.Cu")
		(net "M_D_CPU1_SB_DQS_DP<1>")
	)
	(segment
		(start 79.45247 -280.885392)
		(end 79.462884 -280.891488)
		(width 0.09525)
		(layer "In4.Cu")
		(net "M_D_CPU1_SB_DQS_DP<1>")
	)
	(segment
		(start 41.094914 -294.360092)
		(end 41.454832 -294.72001)
		(width 0.16002)
		(layer "In4.Cu")
		(net "M_D_CPU1_SB_DQS_DP<1>")
	)
	(segment
		(start 68.89496 -285.26232)
		(end 68.71589 -285.08325)
		(width 0.16002)
		(layer "In4.Cu")
		(net "M_D_CPU1_SB_DQS_DP<1>")
	)
	(segment
		(start 67.521328 -286.635952)
		(end 67.342258 -286.456882)
		(width 0.16002)
		(layer "In4.Cu")
		(net "M_D_CPU1_SB_DQS_DP<1>")
	)
	(segment
		(start 84.5312 -280.896314)
		(end 84.539582 -280.891488)
		(width 0.09525)
		(layer "In4.Cu")
		(net "M_D_CPU1_SB_DQS_DP<1>")
	)
	(segment
		(start 48.653192 -294.360092)
		(end 48.965358 -294.672258)
		(width 0.16002)
		(layer "In4.Cu")
		(net "M_D_CPU1_SB_DQS_DP<1>")
	)
	(segment
		(start 68.699126 -285.735014)
		(end 68.89496 -285.53918)
		(width 0.16002)
		(layer "In4.Cu")
		(net "M_D_CPU1_SB_DQS_DP<1>")
	)
	(segment
		(start 81.342484 -280.891488)
		(end 81.350866 -280.896314)
		(width 0.09525)
		(layer "In4.Cu")
		(net "M_D_CPU1_SB_DQS_DP<1>")
	)
	(segment
		(start 70.089522 -283.709618)
		(end 70.089522 -283.182314)
		(width 0.16002)
		(layer "In4.Cu")
		(net "M_D_CPU1_SB_DQS_DP<1>")
	)
	(segment
		(start 70.268592 -283.888688)
		(end 70.089522 -283.709618)
		(width 0.16002)
		(layer "In4.Cu")
		(net "M_D_CPU1_SB_DQS_DP<1>")
	)
	(segment
		(start 37.069776 -294.50919)
		(end 37.72408 -294.50919)
		(width 0.16002)
		(layer "In4.Cu")
		(net "M_D_CPU1_SB_DQS_DP<1>")
	)
	(segment
		(start 68.243196 -285.555944)
		(end 68.422266 -285.735014)
		(width 0.16002)
		(layer "In4.Cu")
		(net "M_D_CPU1_SB_DQS_DP<1>")
	)
	(segment
		(start 78.148688 -280.535888)
		(end 78.445106 -280.832306)
		(width 0.09525)
		(layer "In4.Cu")
		(net "M_D_CPU1_SB_DQS_DP<1>")
	)
	(segment
		(start 50.116486 -293.910258)
		(end 50.599086 -293.910258)
		(width 0.16002)
		(layer "In4.Cu")
		(net "M_D_CPU1_SB_DQS_DP<1>")
	)
	(segment
		(start 67.342258 -286.456882)
		(end 67.342258 -285.929578)
		(width 0.16002)
		(layer "In4.Cu")
		(net "M_D_CPU1_SB_DQS_DP<1>")
	)
	(segment
		(start 71.44639 -282.98775)
		(end 71.642224 -282.791916)
		(width 0.16002)
		(layer "In4.Cu")
		(net "M_D_CPU1_SB_DQS_DP<1>")
	)
	(segment
		(start 71.642224 -282.791916)
		(end 71.642224 -282.515056)
		(width 0.16002)
		(layer "In4.Cu")
		(net "M_D_CPU1_SB_DQS_DP<1>")
	)
	(segment
		(start 76.214478 -280.839418)
		(end 76.478638 -280.839418)
		(width 0.09525)
		(layer "In4.Cu")
		(net "M_D_CPU1_SB_DQS_DP<1>")
	)
	(segment
		(start 70.072758 -284.361382)
		(end 70.268592 -284.165548)
		(width 0.16002)
		(layer "In4.Cu")
		(net "M_D_CPU1_SB_DQS_DP<1>")
	)
	(segment
		(start 89.231216 -280.896314)
		(end 89.239598 -280.891488)
		(width 0.09525)
		(layer "In4.Cu")
		(net "M_D_CPU1_SB_DQS_DP<1>")
	)
	(segment
		(start 67.715892 -285.555944)
		(end 68.243196 -285.555944)
		(width 0.16002)
		(layer "In4.Cu")
		(net "M_D_CPU1_SB_DQS_DP<1>")
	)
	(segment
		(start 68.89496 -285.53918)
		(end 68.89496 -285.26232)
		(width 0.16002)
		(layer "In4.Cu")
		(net "M_D_CPU1_SB_DQS_DP<1>")
	)
	(segment
		(start 60.612782 -293.821358)
		(end 66.147696 -288.286444)
		(width 0.16002)
		(layer "In4.Cu")
		(net "M_D_CPU1_SB_DQS_DP<1>")
	)
	(segment
		(start 65.968626 -287.30321)
		(end 66.34226 -286.929576)
		(width 0.16002)
		(layer "In4.Cu")
		(net "M_D_CPU1_SB_DQS_DP<1>")
	)
	(segment
		(start 50.999136 -293.510208)
		(end 52.352956 -293.510208)
		(width 0.16002)
		(layer "In4.Cu")
		(net "M_D_CPU1_SB_DQS_DP<1>")
	)
	(segment
		(start 48.965358 -294.672258)
		(end 49.354486 -294.672258)
		(width 0.16002)
		(layer "In4.Cu")
		(net "M_D_CPU1_SB_DQS_DP<1>")
	)
	(segment
		(start 79.83982 -280.891488)
		(end 79.850234 -280.885392)
		(width 0.09525)
		(layer "In4.Cu")
		(net "M_D_CPU1_SB_DQS_DP<1>")
	)
	(segment
		(start 69.089524 -284.182312)
		(end 69.616828 -284.182312)
		(width 0.16002)
		(layer "In4.Cu")
		(net "M_D_CPU1_SB_DQS_DP<1>")
	)
	(segment
		(start 72.820022 -281.614118)
		(end 73.653904 -280.780236)
		(width 0.16002)
		(layer "In4.Cu")
		(net "M_D_CPU1_SB_DQS_DP<1>")
	)
	(segment
		(start 70.99046 -282.80868)
		(end 71.16953 -282.98775)
		(width 0.16002)
		(layer "In4.Cu")
		(net "M_D_CPU1_SB_DQS_DP<1>")
	)
	(segment
		(start 71.463154 -281.808682)
		(end 71.836788 -281.435048)
		(width 0.16002)
		(layer "In4.Cu")
		(net "M_D_CPU1_SB_DQS_DP<1>")
	)
	(segment
		(start 76.131674 -280.780236)
		(end 76.155296 -280.780236)
		(width 0.09525)
		(layer "In4.Cu")
		(net "M_D_CPU1_SB_DQS_DP<1>")
	)
	(segment
		(start 85.102446 -280.891488)
		(end 85.110828 -280.896314)
		(width 0.09525)
		(layer "In4.Cu")
		(net "M_D_CPU1_SB_DQS_DP<1>")
	)
	(segment
		(start 66.869564 -286.929576)
		(end 67.048634 -287.108646)
		(width 0.16002)
		(layer "In4.Cu")
		(net "M_D_CPU1_SB_DQS_DP<1>")
	)
	(segment
		(start 72.543162 -281.614118)
		(end 72.820022 -281.614118)
		(width 0.16002)
		(layer "In4.Cu")
		(net "M_D_CPU1_SB_DQS_DP<1>")
	)
	(segment
		(start 39.443152 -294.360092)
		(end 41.094914 -294.360092)
		(width 0.16002)
		(layer "In4.Cu")
		(net "M_D_CPU1_SB_DQS_DP<1>")
	)
	(segment
		(start 65.968626 -287.830514)
		(end 65.968626 -287.30321)
		(width 0.16002)
		(layer "In4.Cu")
		(net "M_D_CPU1_SB_DQS_DP<1>")
	)
	(segment
		(start 91.084908 -280.831798)
		(end 90.930984 -280.566368)
		(width 0.09525)
		(layer "In4.Cu")
		(net "M_D_CPU1_SB_DQS_DP<1>")
	)
	(segment
		(start 73.653904 -280.780236)
		(end 76.131674 -280.780236)
		(width 0.16002)
		(layer "In4.Cu")
		(net "M_D_CPU1_SB_DQS_DP<1>")
	)
	(segment
		(start 91.06154 -280.918666)
		(end 91.084908 -280.831798)
		(width 0.09525)
		(layer "In4.Cu")
		(net "M_D_CPU1_SB_DQS_DP<1>")
	)
	(segment
		(start 45.223684 -293.510208)
		(end 46.073568 -294.360092)
		(width 0.16002)
		(layer "In4.Cu")
		(net "M_D_CPU1_SB_DQS_DP<1>")
	)
	(segment
		(start 69.616828 -284.182312)
		(end 69.795898 -284.361382)
		(width 0.16002)
		(layer "In4.Cu")
		(net "M_D_CPU1_SB_DQS_DP<1>")
	)
	(segment
		(start 76.782168 -280.535888)
		(end 78.148688 -280.535888)
		(width 0.09525)
		(layer "In4.Cu")
		(net "M_D_CPU1_SB_DQS_DP<1>")
	)
	(segment
		(start 71.463154 -282.335986)
		(end 71.463154 -281.808682)
		(width 0.16002)
		(layer "In4.Cu")
		(net "M_D_CPU1_SB_DQS_DP<1>")
	)
	(segment
		(start 57.749186 -293.821358)
		(end 60.612782 -293.821358)
		(width 0.16002)
		(layer "In4.Cu")
		(net "M_D_CPU1_SB_DQS_DP<1>")
	)
	(segment
		(start 68.71589 -284.555946)
		(end 69.089524 -284.182312)
		(width 0.16002)
		(layer "In4.Cu")
		(net "M_D_CPU1_SB_DQS_DP<1>")
	)
	(segment
		(start 36.795964 -294.235378)
		(end 37.069776 -294.50919)
		(width 0.16002)
		(layer "In4.Cu")
		(net "M_D_CPU1_SB_DQS_DP<1>")
	)
	(arc
		(start 85.479636 -280.891488)
		(mid 85.761068 -280.815733)
		(end 86.0425 -280.891488)
		(width 0.09525)
		(layer "In4.Cu")
		(net "M_D_CPU1_SB_DQS_DP<1>")
	)
	(arc
		(start 85.110828 -280.896314)
		(mid 85.29586 -280.942228)
		(end 85.479636 -280.891488)
		(width 0.09525)
		(layer "In4.Cu")
		(net "M_D_CPU1_SB_DQS_DP<1>")
	)
	(arc
		(start 81.719674 -280.891488)
		(mid 82.001106 -280.815733)
		(end 82.282538 -280.891488)
		(width 0.09525)
		(layer "In4.Cu")
		(net "M_D_CPU1_SB_DQS_DP<1>")
	)
	(arc
		(start 78.899766 -280.891488)
		(mid 79.175309 -280.815639)
		(end 79.45247 -280.885392)
		(width 0.09525)
		(layer "In4.Cu")
		(net "M_D_CPU1_SB_DQS_DP<1>")
	)
	(arc
		(start 78.445106 -280.832306)
		(mid 78.482037 -280.864433)
		(end 78.52283 -280.891488)
		(width 0.09525)
		(layer "In4.Cu")
		(net "M_D_CPU1_SB_DQS_DP<1>")
	)
	(arc
		(start 79.850234 -280.885392)
		(mid 80.127142 -280.815715)
		(end 80.40243 -280.891488)
		(width 0.09525)
		(layer "In4.Cu")
		(net "M_D_CPU1_SB_DQS_DP<1>")
	)
	(arc
		(start 82.659474 -280.891488)
		(mid 82.940906 -280.815733)
		(end 83.222338 -280.891488)
		(width 0.09525)
		(layer "In4.Cu")
		(net "M_D_CPU1_SB_DQS_DP<1>")
	)
	(arc
		(start 89.239598 -280.891488)
		(mid 89.52103 -280.815733)
		(end 89.802462 -280.891488)
		(width 0.09525)
		(layer "In4.Cu")
		(net "M_D_CPU1_SB_DQS_DP<1>")
	)
	(arc
		(start 83.599528 -280.891488)
		(mid 83.88096 -280.815733)
		(end 84.162392 -280.891488)
		(width 0.09525)
		(layer "In4.Cu")
		(net "M_D_CPU1_SB_DQS_DP<1>")
	)
	(arc
		(start 84.539582 -280.891488)
		(mid 84.821014 -280.815733)
		(end 85.102446 -280.891488)
		(width 0.09525)
		(layer "In4.Cu")
		(net "M_D_CPU1_SB_DQS_DP<1>")
	)
	(arc
		(start 81.350866 -280.896314)
		(mid 81.535898 -280.942228)
		(end 81.719674 -280.891488)
		(width 0.09525)
		(layer "In4.Cu")
		(net "M_D_CPU1_SB_DQS_DP<1>")
	)
	(arc
		(start 87.922354 -280.891488)
		(mid 88.106129 -280.94226)
		(end 88.291162 -280.896314)
		(width 0.09525)
		(layer "In4.Cu")
		(net "M_D_CPU1_SB_DQS_DP<1>")
	)
	(arc
		(start 80.40243 -280.891488)
		(mid 80.586205 -280.94226)
		(end 80.771238 -280.896314)
		(width 0.09525)
		(layer "In4.Cu")
		(net "M_D_CPU1_SB_DQS_DP<1>")
	)
	(arc
		(start 90.179652 -280.891488)
		(mid 90.461084 -280.815733)
		(end 90.742516 -280.891488)
		(width 0.09525)
		(layer "In4.Cu")
		(net "M_D_CPU1_SB_DQS_DP<1>")
	)
	(arc
		(start 90.750898 -280.896314)
		(mid 90.903793 -280.941142)
		(end 91.06154 -280.918666)
		(width 0.09525)
		(layer "In4.Cu")
		(net "M_D_CPU1_SB_DQS_DP<1>")
	)
	(arc
		(start 89.810844 -280.896314)
		(mid 89.995876 -280.942228)
		(end 90.179652 -280.891488)
		(width 0.09525)
		(layer "In4.Cu")
		(net "M_D_CPU1_SB_DQS_DP<1>")
	)
	(arc
		(start 84.162392 -280.891488)
		(mid 84.346167 -280.94226)
		(end 84.5312 -280.896314)
		(width 0.09525)
		(layer "In4.Cu")
		(net "M_D_CPU1_SB_DQS_DP<1>")
	)
	(arc
		(start 88.862408 -280.891488)
		(mid 89.046183 -280.94226)
		(end 89.231216 -280.896314)
		(width 0.09525)
		(layer "In4.Cu")
		(net "M_D_CPU1_SB_DQS_DP<1>")
	)
	(arc
		(start 86.41969 -280.891488)
		(mid 86.701122 -280.815733)
		(end 86.982554 -280.891488)
		(width 0.09525)
		(layer "In4.Cu")
		(net "M_D_CPU1_SB_DQS_DP<1>")
	)
	(arc
		(start 87.35949 -280.891488)
		(mid 87.640922 -280.815733)
		(end 87.922354 -280.891488)
		(width 0.09525)
		(layer "In4.Cu")
		(net "M_D_CPU1_SB_DQS_DP<1>")
	)
	(arc
		(start 88.299544 -280.891488)
		(mid 88.580976 -280.815733)
		(end 88.862408 -280.891488)
		(width 0.09525)
		(layer "In4.Cu")
		(net "M_D_CPU1_SB_DQS_DP<1>")
	)
	(arc
		(start 86.050882 -280.896314)
		(mid 86.235914 -280.942228)
		(end 86.41969 -280.891488)
		(width 0.09525)
		(layer "In4.Cu")
		(net "M_D_CPU1_SB_DQS_DP<1>")
	)
	(arc
		(start 82.282538 -280.891488)
		(mid 82.471006 -280.942165)
		(end 82.659474 -280.891488)
		(width 0.09525)
		(layer "In4.Cu")
		(net "M_D_CPU1_SB_DQS_DP<1>")
	)
	(arc
		(start 83.222338 -280.891488)
		(mid 83.406113 -280.94226)
		(end 83.591146 -280.896314)
		(width 0.09525)
		(layer "In4.Cu")
		(net "M_D_CPU1_SB_DQS_DP<1>")
	)
	(arc
		(start 86.982554 -280.891488)
		(mid 87.171022 -280.942165)
		(end 87.35949 -280.891488)
		(width 0.09525)
		(layer "In4.Cu")
		(net "M_D_CPU1_SB_DQS_DP<1>")
	)
	(arc
		(start 78.534768 -280.898346)
		(mid 78.718149 -280.942177)
		(end 78.899766 -280.891488)
		(width 0.09525)
		(layer "In4.Cu")
		(net "M_D_CPU1_SB_DQS_DP<1>")
	)
	(arc
		(start 80.77962 -280.891488)
		(mid 81.061052 -280.815733)
		(end 81.342484 -280.891488)
		(width 0.09525)
		(layer "In4.Cu")
		(net "M_D_CPU1_SB_DQS_DP<1>")
	)
	(arc
		(start 79.462884 -280.891488)
		(mid 79.651352 -280.942165)
		(end 79.83982 -280.891488)
		(width 0.09525)
		(layer "In4.Cu")
		(net "M_D_CPU1_SB_DQS_DP<1>")
	)
	(segment
		(start 91.397836 -275.440394)
		(end 90.930984 -275.706332)
		(width 0.12954)
		(layer "F.Cu")
		(net "M_D_CPU1_SB_DQS_DP<0>")
	)
	(segment
		(start 65.704974 -278.81326)
		(end 65.981834 -278.81326)
		(width 0.16002)
		(layer "In4.Cu")
		(net "M_D_CPU1_SB_DQS_DP<0>")
	)
	(segment
		(start 65.981834 -278.81326)
		(end 66.17843 -278.616664)
		(width 0.16002)
		(layer "In4.Cu")
		(net "M_D_CPU1_SB_DQS_DP<0>")
	)
	(segment
		(start 62.323726 -281.453844)
		(end 62.85103 -281.453844)
		(width 0.16002)
		(layer "In4.Cu")
		(net "M_D_CPU1_SB_DQS_DP<0>")
	)
	(segment
		(start 59.576462 -284.201108)
		(end 60.103766 -284.201108)
		(width 0.16002)
		(layer "In4.Cu")
		(net "M_D_CPU1_SB_DQS_DP<0>")
	)
	(segment
		(start 63.324486 -280.980388)
		(end 63.324486 -280.453084)
		(width 0.16002)
		(layer "In4.Cu")
		(net "M_D_CPU1_SB_DQS_DP<0>")
	)
	(segment
		(start 63.431166 -281.363928)
		(end 63.431166 -281.087068)
		(width 0.16002)
		(layer "In4.Cu")
		(net "M_D_CPU1_SB_DQS_DP<0>")
	)
	(segment
		(start 80.771238 -276.036278)
		(end 80.77962 -276.031452)
		(width 0.09525)
		(layer "In4.Cu")
		(net "M_D_CPU1_SB_DQS_DP<0>")
	)
	(segment
		(start 64.698118 -279.606756)
		(end 64.698118 -279.079452)
		(width 0.16002)
		(layer "In4.Cu")
		(net "M_D_CPU1_SB_DQS_DP<0>")
	)
	(segment
		(start 61.477398 -282.827476)
		(end 61.584078 -282.934156)
		(width 0.16002)
		(layer "In4.Cu")
		(net "M_D_CPU1_SB_DQS_DP<0>")
	)
	(segment
		(start 67.445382 -276.859492)
		(end 67.445382 -276.332188)
		(width 0.16002)
		(layer "In4.Cu")
		(net "M_D_CPU1_SB_DQS_DP<0>")
	)
	(segment
		(start 65.598294 -278.70658)
		(end 65.704974 -278.81326)
		(width 0.16002)
		(layer "In4.Cu")
		(net "M_D_CPU1_SB_DQS_DP<0>")
	)
	(segment
		(start 55.511192 -285.334964)
		(end 55.904892 -285.728664)
		(width 0.16002)
		(layer "In4.Cu")
		(net "M_D_CPU1_SB_DQS_DP<0>")
	)
	(segment
		(start 56.491886 -285.728664)
		(end 57.660286 -284.560264)
		(width 0.16002)
		(layer "In4.Cu")
		(net "M_D_CPU1_SB_DQS_DP<0>")
	)
	(segment
		(start 49.143666 -285.533084)
		(end 50.116486 -284.560264)
		(width 0.16002)
		(layer "In4.Cu")
		(net "M_D_CPU1_SB_DQS_DP<0>")
	)
	(segment
		(start 39.278052 -285.010098)
		(end 41.109392 -285.010098)
		(width 0.16002)
		(layer "In4.Cu")
		(net "M_D_CPU1_SB_DQS_DP<0>")
	)
	(segment
		(start 64.331342 -280.186892)
		(end 64.608202 -280.186892)
		(width 0.16002)
		(layer "In4.Cu")
		(net "M_D_CPU1_SB_DQS_DP<0>")
	)
	(segment
		(start 86.0425 -276.031452)
		(end 86.050882 -276.036278)
		(width 0.09525)
		(layer "In4.Cu")
		(net "M_D_CPU1_SB_DQS_DP<0>")
	)
	(segment
		(start 91.06154 -276.05863)
		(end 91.084908 -275.971762)
		(width 0.09525)
		(layer "In4.Cu")
		(net "M_D_CPU1_SB_DQS_DP<0>")
	)
	(segment
		(start 66.07175 -278.233124)
		(end 66.07175 -277.70582)
		(width 0.16002)
		(layer "In4.Cu")
		(net "M_D_CPU1_SB_DQS_DP<0>")
	)
	(segment
		(start 76.03871 -275.216366)
		(end 77.26934 -275.216366)
		(width 0.09525)
		(layer "In4.Cu")
		(net "M_D_CPU1_SB_DQS_DP<0>")
	)
	(segment
		(start 89.802462 -276.031452)
		(end 89.810844 -276.036278)
		(width 0.09525)
		(layer "In4.Cu")
		(net "M_D_CPU1_SB_DQS_DP<0>")
	)
	(segment
		(start 85.102446 -276.031452)
		(end 85.110828 -276.036278)
		(width 0.09525)
		(layer "In4.Cu")
		(net "M_D_CPU1_SB_DQS_DP<0>")
	)
	(segment
		(start 64.804798 -279.713436)
		(end 64.698118 -279.606756)
		(width 0.16002)
		(layer "In4.Cu")
		(net "M_D_CPU1_SB_DQS_DP<0>")
	)
	(segment
		(start 50.599086 -284.560264)
		(end 50.999136 -284.160214)
		(width 0.16002)
		(layer "In4.Cu")
		(net "M_D_CPU1_SB_DQS_DP<0>")
	)
	(segment
		(start 66.07175 -277.70582)
		(end 66.444622 -277.332948)
		(width 0.16002)
		(layer "In4.Cu")
		(net "M_D_CPU1_SB_DQS_DP<0>")
	)
	(segment
		(start 61.584078 -282.934156)
		(end 61.860938 -282.934156)
		(width 0.16002)
		(layer "In4.Cu")
		(net "M_D_CPU1_SB_DQS_DP<0>")
	)
	(segment
		(start 43.488864 -284.160214)
		(end 44.704508 -284.160214)
		(width 0.16002)
		(layer "In4.Cu")
		(net "M_D_CPU1_SB_DQS_DP<0>")
	)
	(segment
		(start 66.971926 -277.332948)
		(end 67.078606 -277.439628)
		(width 0.16002)
		(layer "In4.Cu")
		(net "M_D_CPU1_SB_DQS_DP<0>")
	)
	(segment
		(start 77.26934 -275.216366)
		(end 78.135988 -276.083014)
		(width 0.09525)
		(layer "In4.Cu")
		(net "M_D_CPU1_SB_DQS_DP<0>")
	)
	(segment
		(start 63.23457 -281.560524)
		(end 63.431166 -281.363928)
		(width 0.16002)
		(layer "In4.Cu")
		(net "M_D_CPU1_SB_DQS_DP<0>")
	)
	(segment
		(start 37.069776 -285.159196)
		(end 37.81806 -285.159196)
		(width 0.16002)
		(layer "In4.Cu")
		(net "M_D_CPU1_SB_DQS_DP<0>")
	)
	(segment
		(start 83.591146 -276.036278)
		(end 83.599528 -276.031452)
		(width 0.09525)
		(layer "In4.Cu")
		(net "M_D_CPU1_SB_DQS_DP<0>")
	)
	(segment
		(start 53.524658 -285.334964)
		(end 55.511192 -285.334964)
		(width 0.16002)
		(layer "In4.Cu")
		(net "M_D_CPU1_SB_DQS_DP<0>")
	)
	(segment
		(start 67.078606 -277.439628)
		(end 67.355466 -277.439628)
		(width 0.16002)
		(layer "In4.Cu")
		(net "M_D_CPU1_SB_DQS_DP<0>")
	)
	(segment
		(start 41.793414 -285.347664)
		(end 42.580814 -284.560264)
		(width 0.16002)
		(layer "In4.Cu")
		(net "M_D_CPU1_SB_DQS_DP<0>")
	)
	(segment
		(start 67.445382 -276.332188)
		(end 68.620386 -275.157184)
		(width 0.16002)
		(layer "In4.Cu")
		(net "M_D_CPU1_SB_DQS_DP<0>")
	)
	(segment
		(start 38.41496 -285.042356)
		(end 38.5318 -285.159196)
		(width 0.16002)
		(layer "In4.Cu")
		(net "M_D_CPU1_SB_DQS_DP<0>")
	)
	(segment
		(start 91.084908 -275.971762)
		(end 90.930984 -275.706332)
		(width 0.09525)
		(layer "In4.Cu")
		(net "M_D_CPU1_SB_DQS_DP<0>")
	)
	(segment
		(start 64.224662 -280.080212)
		(end 64.331342 -280.186892)
		(width 0.16002)
		(layer "In4.Cu")
		(net "M_D_CPU1_SB_DQS_DP<0>")
	)
	(segment
		(start 63.324486 -280.453084)
		(end 63.697358 -280.080212)
		(width 0.16002)
		(layer "In4.Cu")
		(net "M_D_CPU1_SB_DQS_DP<0>")
	)
	(segment
		(start 60.950094 -282.827476)
		(end 61.477398 -282.827476)
		(width 0.16002)
		(layer "In4.Cu")
		(net "M_D_CPU1_SB_DQS_DP<0>")
	)
	(segment
		(start 80.392016 -276.025356)
		(end 80.40243 -276.031452)
		(width 0.09525)
		(layer "In4.Cu")
		(net "M_D_CPU1_SB_DQS_DP<0>")
	)
	(segment
		(start 84.5312 -276.036278)
		(end 84.539582 -276.031452)
		(width 0.09525)
		(layer "In4.Cu")
		(net "M_D_CPU1_SB_DQS_DP<0>")
	)
	(segment
		(start 60.683902 -284.111192)
		(end 60.683902 -283.834332)
		(width 0.16002)
		(layer "In4.Cu")
		(net "M_D_CPU1_SB_DQS_DP<0>")
	)
	(segment
		(start 67.552062 -276.966172)
		(end 67.445382 -276.859492)
		(width 0.16002)
		(layer "In4.Cu")
		(net "M_D_CPU1_SB_DQS_DP<0>")
	)
	(segment
		(start 75.979528 -275.157184)
		(end 76.03871 -275.216366)
		(width 0.09525)
		(layer "In4.Cu")
		(net "M_D_CPU1_SB_DQS_DP<0>")
	)
	(segment
		(start 62.85103 -281.453844)
		(end 62.95771 -281.560524)
		(width 0.16002)
		(layer "In4.Cu")
		(net "M_D_CPU1_SB_DQS_DP<0>")
	)
	(segment
		(start 64.804798 -279.990296)
		(end 64.804798 -279.713436)
		(width 0.16002)
		(layer "In4.Cu")
		(net "M_D_CPU1_SB_DQS_DP<0>")
	)
	(segment
		(start 61.950854 -282.35402)
		(end 61.950854 -281.826716)
		(width 0.16002)
		(layer "In4.Cu")
		(net "M_D_CPU1_SB_DQS_DP<0>")
	)
	(segment
		(start 55.904892 -285.728664)
		(end 56.491886 -285.728664)
		(width 0.16002)
		(layer "In4.Cu")
		(net "M_D_CPU1_SB_DQS_DP<0>")
	)
	(segment
		(start 41.446958 -285.347664)
		(end 41.793414 -285.347664)
		(width 0.16002)
		(layer "In4.Cu")
		(net "M_D_CPU1_SB_DQS_DP<0>")
	)
	(segment
		(start 60.103766 -284.201108)
		(end 60.210446 -284.307788)
		(width 0.16002)
		(layer "In4.Cu")
		(net "M_D_CPU1_SB_DQS_DP<0>")
	)
	(segment
		(start 68.620386 -275.157184)
		(end 75.955906 -275.157184)
		(width 0.16002)
		(layer "In4.Cu")
		(net "M_D_CPU1_SB_DQS_DP<0>")
	)
	(segment
		(start 67.355466 -277.439628)
		(end 67.552062 -277.243032)
		(width 0.16002)
		(layer "In4.Cu")
		(net "M_D_CPU1_SB_DQS_DP<0>")
	)
	(segment
		(start 90.742516 -276.031452)
		(end 90.750898 -276.036278)
		(width 0.09525)
		(layer "In4.Cu")
		(net "M_D_CPU1_SB_DQS_DP<0>")
	)
	(segment
		(start 60.683902 -283.834332)
		(end 60.577222 -283.727652)
		(width 0.16002)
		(layer "In4.Cu")
		(net "M_D_CPU1_SB_DQS_DP<0>")
	)
	(segment
		(start 43.088814 -284.560264)
		(end 43.488864 -284.160214)
		(width 0.16002)
		(layer "In4.Cu")
		(net "M_D_CPU1_SB_DQS_DP<0>")
	)
	(segment
		(start 66.17843 -278.339804)
		(end 66.07175 -278.233124)
		(width 0.16002)
		(layer "In4.Cu")
		(net "M_D_CPU1_SB_DQS_DP<0>")
	)
	(segment
		(start 64.698118 -279.079452)
		(end 65.07099 -278.70658)
		(width 0.16002)
		(layer "In4.Cu")
		(net "M_D_CPU1_SB_DQS_DP<0>")
	)
	(segment
		(start 45.554392 -285.010098)
		(end 48.195992 -285.010098)
		(width 0.16002)
		(layer "In4.Cu")
		(net "M_D_CPU1_SB_DQS_DP<0>")
	)
	(segment
		(start 42.580814 -284.560264)
		(end 43.088814 -284.560264)
		(width 0.16002)
		(layer "In4.Cu")
		(net "M_D_CPU1_SB_DQS_DP<0>")
	)
	(segment
		(start 63.431166 -281.087068)
		(end 63.324486 -280.980388)
		(width 0.16002)
		(layer "In4.Cu")
		(net "M_D_CPU1_SB_DQS_DP<0>")
	)
	(segment
		(start 78.135988 -276.083014)
		(end 79.650336 -276.083014)
		(width 0.09525)
		(layer "In4.Cu")
		(net "M_D_CPU1_SB_DQS_DP<0>")
	)
	(segment
		(start 81.342484 -276.031452)
		(end 81.350866 -276.036278)
		(width 0.09525)
		(layer "In4.Cu")
		(net "M_D_CPU1_SB_DQS_DP<0>")
	)
	(segment
		(start 52.349908 -284.160214)
		(end 53.524658 -285.334964)
		(width 0.16002)
		(layer "In4.Cu")
		(net "M_D_CPU1_SB_DQS_DP<0>")
	)
	(segment
		(start 62.057534 -282.73756)
		(end 62.057534 -282.4607)
		(width 0.16002)
		(layer "In4.Cu")
		(net "M_D_CPU1_SB_DQS_DP<0>")
	)
	(segment
		(start 41.109392 -285.010098)
		(end 41.446958 -285.347664)
		(width 0.16002)
		(layer "In4.Cu")
		(net "M_D_CPU1_SB_DQS_DP<0>")
	)
	(segment
		(start 44.704508 -284.160214)
		(end 45.554392 -285.010098)
		(width 0.16002)
		(layer "In4.Cu")
		(net "M_D_CPU1_SB_DQS_DP<0>")
	)
	(segment
		(start 57.660286 -284.560264)
		(end 59.217306 -284.560264)
		(width 0.16002)
		(layer "In4.Cu")
		(net "M_D_CPU1_SB_DQS_DP<0>")
	)
	(segment
		(start 75.955906 -275.157184)
		(end 75.979528 -275.157184)
		(width 0.09525)
		(layer "In4.Cu")
		(net "M_D_CPU1_SB_DQS_DP<0>")
	)
	(segment
		(start 37.9349 -285.042356)
		(end 38.41496 -285.042356)
		(width 0.16002)
		(layer "In4.Cu")
		(net "M_D_CPU1_SB_DQS_DP<0>")
	)
	(segment
		(start 67.552062 -277.243032)
		(end 67.552062 -276.966172)
		(width 0.16002)
		(layer "In4.Cu")
		(net "M_D_CPU1_SB_DQS_DP<0>")
	)
	(segment
		(start 60.577222 -283.727652)
		(end 60.577222 -283.200348)
		(width 0.16002)
		(layer "In4.Cu")
		(net "M_D_CPU1_SB_DQS_DP<0>")
	)
	(segment
		(start 50.999136 -284.160214)
		(end 52.349908 -284.160214)
		(width 0.16002)
		(layer "In4.Cu")
		(net "M_D_CPU1_SB_DQS_DP<0>")
	)
	(segment
		(start 88.291162 -276.036278)
		(end 88.299544 -276.031452)
		(width 0.09525)
		(layer "In4.Cu")
		(net "M_D_CPU1_SB_DQS_DP<0>")
	)
	(segment
		(start 89.231216 -276.036278)
		(end 89.239598 -276.031452)
		(width 0.09525)
		(layer "In4.Cu")
		(net "M_D_CPU1_SB_DQS_DP<0>")
	)
	(segment
		(start 50.116486 -284.560264)
		(end 50.599086 -284.560264)
		(width 0.16002)
		(layer "In4.Cu")
		(net "M_D_CPU1_SB_DQS_DP<0>")
	)
	(segment
		(start 39.128954 -285.159196)
		(end 39.278052 -285.010098)
		(width 0.16002)
		(layer "In4.Cu")
		(net "M_D_CPU1_SB_DQS_DP<0>")
	)
	(segment
		(start 66.17843 -278.616664)
		(end 66.17843 -278.339804)
		(width 0.16002)
		(layer "In4.Cu")
		(net "M_D_CPU1_SB_DQS_DP<0>")
	)
	(segment
		(start 38.5318 -285.159196)
		(end 39.128954 -285.159196)
		(width 0.16002)
		(layer "In4.Cu")
		(net "M_D_CPU1_SB_DQS_DP<0>")
	)
	(segment
		(start 64.608202 -280.186892)
		(end 64.804798 -279.990296)
		(width 0.16002)
		(layer "In4.Cu")
		(net "M_D_CPU1_SB_DQS_DP<0>")
	)
	(segment
		(start 66.444622 -277.332948)
		(end 66.971926 -277.332948)
		(width 0.16002)
		(layer "In4.Cu")
		(net "M_D_CPU1_SB_DQS_DP<0>")
	)
	(segment
		(start 37.81806 -285.159196)
		(end 37.9349 -285.042356)
		(width 0.16002)
		(layer "In4.Cu")
		(net "M_D_CPU1_SB_DQS_DP<0>")
	)
	(segment
		(start 36.795964 -284.885384)
		(end 37.069776 -285.159196)
		(width 0.16002)
		(layer "In4.Cu")
		(net "M_D_CPU1_SB_DQS_DP<0>")
	)
	(segment
		(start 63.697358 -280.080212)
		(end 64.224662 -280.080212)
		(width 0.16002)
		(layer "In4.Cu")
		(net "M_D_CPU1_SB_DQS_DP<0>")
	)
	(segment
		(start 60.487306 -284.307788)
		(end 60.683902 -284.111192)
		(width 0.16002)
		(layer "In4.Cu")
		(net "M_D_CPU1_SB_DQS_DP<0>")
	)
	(segment
		(start 61.860938 -282.934156)
		(end 62.057534 -282.73756)
		(width 0.16002)
		(layer "In4.Cu")
		(net "M_D_CPU1_SB_DQS_DP<0>")
	)
	(segment
		(start 59.217306 -284.560264)
		(end 59.576462 -284.201108)
		(width 0.16002)
		(layer "In4.Cu")
		(net "M_D_CPU1_SB_DQS_DP<0>")
	)
	(segment
		(start 48.195992 -285.010098)
		(end 48.718978 -285.533084)
		(width 0.16002)
		(layer "In4.Cu")
		(net "M_D_CPU1_SB_DQS_DP<0>")
	)
	(segment
		(start 60.577222 -283.200348)
		(end 60.950094 -282.827476)
		(width 0.16002)
		(layer "In4.Cu")
		(net "M_D_CPU1_SB_DQS_DP<0>")
	)
	(segment
		(start 65.07099 -278.70658)
		(end 65.598294 -278.70658)
		(width 0.16002)
		(layer "In4.Cu")
		(net "M_D_CPU1_SB_DQS_DP<0>")
	)
	(segment
		(start 60.210446 -284.307788)
		(end 60.487306 -284.307788)
		(width 0.16002)
		(layer "In4.Cu")
		(net "M_D_CPU1_SB_DQS_DP<0>")
	)
	(segment
		(start 48.718978 -285.533084)
		(end 49.143666 -285.533084)
		(width 0.16002)
		(layer "In4.Cu")
		(net "M_D_CPU1_SB_DQS_DP<0>")
	)
	(segment
		(start 62.95771 -281.560524)
		(end 63.23457 -281.560524)
		(width 0.16002)
		(layer "In4.Cu")
		(net "M_D_CPU1_SB_DQS_DP<0>")
	)
	(segment
		(start 61.950854 -281.826716)
		(end 62.323726 -281.453844)
		(width 0.16002)
		(layer "In4.Cu")
		(net "M_D_CPU1_SB_DQS_DP<0>")
	)
	(segment
		(start 62.057534 -282.4607)
		(end 61.950854 -282.35402)
		(width 0.16002)
		(layer "In4.Cu")
		(net "M_D_CPU1_SB_DQS_DP<0>")
	)
	(arc
		(start 87.37219 -276.02434)
		(mid 87.6482 -275.955779)
		(end 87.922354 -276.031452)
		(width 0.09525)
		(layer "In4.Cu")
		(net "M_D_CPU1_SB_DQS_DP<0>")
	)
	(arc
		(start 88.312498 -276.02434)
		(mid 88.588398 -275.955778)
		(end 88.862408 -276.031452)
		(width 0.09525)
		(layer "In4.Cu")
		(net "M_D_CPU1_SB_DQS_DP<0>")
	)
	(arc
		(start 90.750898 -276.036278)
		(mid 90.903793 -276.081106)
		(end 91.06154 -276.05863)
		(width 0.09525)
		(layer "In4.Cu")
		(net "M_D_CPU1_SB_DQS_DP<0>")
	)
	(arc
		(start 79.839312 -276.031452)
		(mid 80.114855 -275.955603)
		(end 80.392016 -276.025356)
		(width 0.09525)
		(layer "In4.Cu")
		(net "M_D_CPU1_SB_DQS_DP<0>")
	)
	(arc
		(start 88.862408 -276.031452)
		(mid 89.046183 -276.082224)
		(end 89.231216 -276.036278)
		(width 0.09525)
		(layer "In4.Cu")
		(net "M_D_CPU1_SB_DQS_DP<0>")
	)
	(arc
		(start 87.35949 -276.031452)
		(mid 87.365818 -276.027856)
		(end 87.37219 -276.02434)
		(width 0.09525)
		(layer "In4.Cu")
		(net "M_D_CPU1_SB_DQS_DP<0>")
	)
	(arc
		(start 83.612482 -276.02434)
		(mid 83.888382 -275.955778)
		(end 84.162392 -276.031452)
		(width 0.09525)
		(layer "In4.Cu")
		(net "M_D_CPU1_SB_DQS_DP<0>")
	)
	(arc
		(start 87.922354 -276.031452)
		(mid 88.106129 -276.082224)
		(end 88.291162 -276.036278)
		(width 0.09525)
		(layer "In4.Cu")
		(net "M_D_CPU1_SB_DQS_DP<0>")
	)
	(arc
		(start 82.659474 -276.031452)
		(mid 82.665802 -276.027856)
		(end 82.672174 -276.02434)
		(width 0.09525)
		(layer "In4.Cu")
		(net "M_D_CPU1_SB_DQS_DP<0>")
	)
	(arc
		(start 90.179652 -276.031452)
		(mid 90.461084 -275.955697)
		(end 90.742516 -276.031452)
		(width 0.09525)
		(layer "In4.Cu")
		(net "M_D_CPU1_SB_DQS_DP<0>")
	)
	(arc
		(start 82.672174 -276.02434)
		(mid 82.948184 -275.955779)
		(end 83.222338 -276.031452)
		(width 0.09525)
		(layer "In4.Cu")
		(net "M_D_CPU1_SB_DQS_DP<0>")
	)
	(arc
		(start 83.599528 -276.031452)
		(mid 83.605981 -276.027852)
		(end 83.612482 -276.02434)
		(width 0.09525)
		(layer "In4.Cu")
		(net "M_D_CPU1_SB_DQS_DP<0>")
	)
	(arc
		(start 84.162392 -276.031452)
		(mid 84.346167 -276.082224)
		(end 84.5312 -276.036278)
		(width 0.09525)
		(layer "In4.Cu")
		(net "M_D_CPU1_SB_DQS_DP<0>")
	)
	(arc
		(start 88.299544 -276.031452)
		(mid 88.305997 -276.027852)
		(end 88.312498 -276.02434)
		(width 0.09525)
		(layer "In4.Cu")
		(net "M_D_CPU1_SB_DQS_DP<0>")
	)
	(arc
		(start 79.650336 -276.083014)
		(mid 79.748233 -276.069728)
		(end 79.839312 -276.031452)
		(width 0.09525)
		(layer "In4.Cu")
		(net "M_D_CPU1_SB_DQS_DP<0>")
	)
	(arc
		(start 86.982554 -276.031452)
		(mid 87.171022 -276.082129)
		(end 87.35949 -276.031452)
		(width 0.09525)
		(layer "In4.Cu")
		(net "M_D_CPU1_SB_DQS_DP<0>")
	)
	(arc
		(start 81.350866 -276.036278)
		(mid 81.535898 -276.082192)
		(end 81.719674 -276.031452)
		(width 0.09525)
		(layer "In4.Cu")
		(net "M_D_CPU1_SB_DQS_DP<0>")
	)
	(arc
		(start 89.239598 -276.031452)
		(mid 89.52103 -275.955697)
		(end 89.802462 -276.031452)
		(width 0.09525)
		(layer "In4.Cu")
		(net "M_D_CPU1_SB_DQS_DP<0>")
	)
	(arc
		(start 84.539582 -276.031452)
		(mid 84.821014 -275.955697)
		(end 85.102446 -276.031452)
		(width 0.09525)
		(layer "In4.Cu")
		(net "M_D_CPU1_SB_DQS_DP<0>")
	)
	(arc
		(start 86.050882 -276.036278)
		(mid 86.235914 -276.082192)
		(end 86.41969 -276.031452)
		(width 0.09525)
		(layer "In4.Cu")
		(net "M_D_CPU1_SB_DQS_DP<0>")
	)
	(arc
		(start 86.41969 -276.031452)
		(mid 86.701122 -275.955697)
		(end 86.982554 -276.031452)
		(width 0.09525)
		(layer "In4.Cu")
		(net "M_D_CPU1_SB_DQS_DP<0>")
	)
	(arc
		(start 83.222338 -276.031452)
		(mid 83.406113 -276.082224)
		(end 83.591146 -276.036278)
		(width 0.09525)
		(layer "In4.Cu")
		(net "M_D_CPU1_SB_DQS_DP<0>")
	)
	(arc
		(start 80.40243 -276.031452)
		(mid 80.586205 -276.082224)
		(end 80.771238 -276.036278)
		(width 0.09525)
		(layer "In4.Cu")
		(net "M_D_CPU1_SB_DQS_DP<0>")
	)
	(arc
		(start 80.77962 -276.031452)
		(mid 81.061052 -275.955697)
		(end 81.342484 -276.031452)
		(width 0.09525)
		(layer "In4.Cu")
		(net "M_D_CPU1_SB_DQS_DP<0>")
	)
	(arc
		(start 82.282538 -276.031452)
		(mid 82.471006 -276.082129)
		(end 82.659474 -276.031452)
		(width 0.09525)
		(layer "In4.Cu")
		(net "M_D_CPU1_SB_DQS_DP<0>")
	)
	(arc
		(start 85.479636 -276.031452)
		(mid 85.761068 -275.955697)
		(end 86.0425 -276.031452)
		(width 0.09525)
		(layer "In4.Cu")
		(net "M_D_CPU1_SB_DQS_DP<0>")
	)
	(arc
		(start 81.719674 -276.031452)
		(mid 82.001106 -275.955697)
		(end 82.282538 -276.031452)
		(width 0.09525)
		(layer "In4.Cu")
		(net "M_D_CPU1_SB_DQS_DP<0>")
	)
	(arc
		(start 85.110828 -276.036278)
		(mid 85.29586 -276.082192)
		(end 85.479636 -276.031452)
		(width 0.09525)
		(layer "In4.Cu")
		(net "M_D_CPU1_SB_DQS_DP<0>")
	)
	(arc
		(start 89.810844 -276.036278)
		(mid 89.995876 -276.082192)
		(end 90.179652 -276.031452)
		(width 0.09525)
		(layer "In4.Cu")
		(net "M_D_CPU1_SB_DQS_DP<0>")
	)
	(segment
		(start 91.86799 -271.390364)
		(end 91.401138 -271.656302)
		(width 0.12954)
		(layer "F.Cu")
		(net "M_D_CPU1_SB_DQS_DN<9>")
	)
	(segment
		(start 38.252146 -275.938234)
		(end 40.990774 -275.938234)
		(width 0.16002)
		(layer "In4.Cu")
		(net "M_D_CPU1_SB_DQS_DN<9>")
	)
	(segment
		(start 88.392508 -271.331182)
		(end 88.40089 -271.326356)
		(width 0.09525)
		(layer "In4.Cu")
		(net "M_D_CPU1_SB_DQS_DN<9>")
	)
	(segment
		(start 57.899808 -275.451824)
		(end 59.875166 -275.451824)
		(width 0.16002)
		(layer "In4.Cu")
		(net "M_D_CPU1_SB_DQS_DN<9>")
	)
	(segment
		(start 51.478688 -274.987512)
		(end 52.039266 -274.987512)
		(width 0.16002)
		(layer "In4.Cu")
		(net "M_D_CPU1_SB_DQS_DN<9>")
	)
	(segment
		(start 45.921168 -274.743672)
		(end 45.921168 -274.53082)
		(width 0.16002)
		(layer "In4.Cu")
		(net "M_D_CPU1_SB_DQS_DN<9>")
	)
	(segment
		(start 57.061608 -276.290024)
		(end 57.899808 -275.451824)
		(width 0.16002)
		(layer "In4.Cu")
		(net "M_D_CPU1_SB_DQS_DN<9>")
	)
	(segment
		(start 76.055474 -269.776956)
		(end 76.205842 -269.776956)
		(width 0.09525)
		(layer "In4.Cu")
		(net "M_D_CPU1_SB_DQS_DN<9>")
	)
	(segment
		(start 46.117002 -274.334986)
		(end 46.393608 -274.334986)
		(width 0.16002)
		(layer "In4.Cu")
		(net "M_D_CPU1_SB_DQS_DN<9>")
	)
	(segment
		(start 41.329864 -276.277324)
		(end 41.935908 -276.277324)
		(width 0.16002)
		(layer "In4.Cu")
		(net "M_D_CPU1_SB_DQS_DN<9>")
	)
	(segment
		(start 82.752438 -271.331182)
		(end 82.76082 -271.326356)
		(width 0.09525)
		(layer "In4.Cu")
		(net "M_D_CPU1_SB_DQS_DN<9>")
	)
	(segment
		(start 75.972924 -269.835884)
		(end 75.996546 -269.835884)
		(width 0.09525)
		(layer "In4.Cu")
		(net "M_D_CPU1_SB_DQS_DN<9>")
	)
	(segment
		(start 55.359554 -274.703286)
		(end 55.555388 -274.89912)
		(width 0.16002)
		(layer "In4.Cu")
		(net "M_D_CPU1_SB_DQS_DN<9>")
	)
	(segment
		(start 36.795964 -276.385274)
		(end 37.069776 -276.111462)
		(width 0.16002)
		(layer "In4.Cu")
		(net "M_D_CPU1_SB_DQS_DN<9>")
	)
	(segment
		(start 43.244008 -275.451824)
		(end 43.615102 -275.08073)
		(width 0.16002)
		(layer "In4.Cu")
		(net "M_D_CPU1_SB_DQS_DN<9>")
	)
	(segment
		(start 46.589442 -274.53082)
		(end 46.589442 -275.557742)
		(width 0.16002)
		(layer "In4.Cu")
		(net "M_D_CPU1_SB_DQS_DN<9>")
	)
	(segment
		(start 91.247214 -271.390872)
		(end 91.401138 -271.656302)
		(width 0.09525)
		(layer "In4.Cu")
		(net "M_D_CPU1_SB_DQS_DN<9>")
	)
	(segment
		(start 43.615102 -275.08073)
		(end 45.58411 -275.08073)
		(width 0.16002)
		(layer "In4.Cu")
		(net "M_D_CPU1_SB_DQS_DN<9>")
	)
	(segment
		(start 53.914294 -276.290024)
		(end 54.514242 -276.290024)
		(width 0.16002)
		(layer "In4.Cu")
		(net "M_D_CPU1_SB_DQS_DN<9>")
	)
	(segment
		(start 53.541422 -275.917152)
		(end 53.914294 -276.290024)
		(width 0.16002)
		(layer "In4.Cu")
		(net "M_D_CPU1_SB_DQS_DN<9>")
	)
	(segment
		(start 41.935908 -276.277324)
		(end 42.761408 -275.451824)
		(width 0.16002)
		(layer "In4.Cu")
		(net "M_D_CPU1_SB_DQS_DN<9>")
	)
	(segment
		(start 38.078918 -276.111462)
		(end 38.252146 -275.938234)
		(width 0.16002)
		(layer "In4.Cu")
		(net "M_D_CPU1_SB_DQS_DN<9>")
	)
	(segment
		(start 53.345588 -274.289266)
		(end 53.541422 -274.4851)
		(width 0.16002)
		(layer "In4.Cu")
		(net "M_D_CPU1_SB_DQS_DN<9>")
	)
	(segment
		(start 54.887114 -274.89912)
		(end 55.082948 -274.703286)
		(width 0.16002)
		(layer "In4.Cu")
		(net "M_D_CPU1_SB_DQS_DN<9>")
	)
	(segment
		(start 87.452454 -271.331182)
		(end 87.460836 -271.326356)
		(width 0.09525)
		(layer "In4.Cu")
		(net "M_D_CPU1_SB_DQS_DN<9>")
	)
	(segment
		(start 50.988976 -275.477224)
		(end 51.478688 -274.987512)
		(width 0.16002)
		(layer "In4.Cu")
		(net "M_D_CPU1_SB_DQS_DN<9>")
	)
	(segment
		(start 91.146376 -271.364202)
		(end 91.247214 -271.390872)
		(width 0.09525)
		(layer "In4.Cu")
		(net "M_D_CPU1_SB_DQS_DN<9>")
	)
	(segment
		(start 76.205842 -269.776956)
		(end 76.757022 -270.328136)
		(width 0.09525)
		(layer "In4.Cu")
		(net "M_D_CPU1_SB_DQS_DN<9>")
	)
	(segment
		(start 59.875166 -275.451824)
		(end 65.491106 -269.835884)
		(width 0.16002)
		(layer "In4.Cu")
		(net "M_D_CPU1_SB_DQS_DN<9>")
	)
	(segment
		(start 52.039266 -274.987512)
		(end 52.737512 -274.289266)
		(width 0.16002)
		(layer "In4.Cu")
		(net "M_D_CPU1_SB_DQS_DN<9>")
	)
	(segment
		(start 46.962314 -275.930614)
		(end 48.501554 -275.930614)
		(width 0.16002)
		(layer "In4.Cu")
		(net "M_D_CPU1_SB_DQS_DN<9>")
	)
	(segment
		(start 40.990774 -275.938234)
		(end 41.329864 -276.277324)
		(width 0.16002)
		(layer "In4.Cu")
		(net "M_D_CPU1_SB_DQS_DN<9>")
	)
	(segment
		(start 48.848264 -276.277324)
		(end 49.505108 -276.277324)
		(width 0.16002)
		(layer "In4.Cu")
		(net "M_D_CPU1_SB_DQS_DN<9>")
	)
	(segment
		(start 42.761408 -275.451824)
		(end 43.244008 -275.451824)
		(width 0.16002)
		(layer "In4.Cu")
		(net "M_D_CPU1_SB_DQS_DN<9>")
	)
	(segment
		(start 53.541422 -274.4851)
		(end 53.541422 -275.917152)
		(width 0.16002)
		(layer "In4.Cu")
		(net "M_D_CPU1_SB_DQS_DN<9>")
	)
	(segment
		(start 65.491106 -269.835884)
		(end 75.972924 -269.835884)
		(width 0.16002)
		(layer "In4.Cu")
		(net "M_D_CPU1_SB_DQS_DN<9>")
	)
	(segment
		(start 55.92826 -276.290024)
		(end 57.061608 -276.290024)
		(width 0.16002)
		(layer "In4.Cu")
		(net "M_D_CPU1_SB_DQS_DN<9>")
	)
	(segment
		(start 45.58411 -275.08073)
		(end 45.921168 -274.743672)
		(width 0.16002)
		(layer "In4.Cu")
		(net "M_D_CPU1_SB_DQS_DN<9>")
	)
	(segment
		(start 75.996546 -269.835884)
		(end 76.055474 -269.776956)
		(width 0.09525)
		(layer "In4.Cu")
		(net "M_D_CPU1_SB_DQS_DN<9>")
	)
	(segment
		(start 49.505108 -276.277324)
		(end 50.305208 -275.477224)
		(width 0.16002)
		(layer "In4.Cu")
		(net "M_D_CPU1_SB_DQS_DN<9>")
	)
	(segment
		(start 45.921168 -274.53082)
		(end 46.117002 -274.334986)
		(width 0.16002)
		(layer "In4.Cu")
		(net "M_D_CPU1_SB_DQS_DN<9>")
	)
	(segment
		(start 54.887114 -275.917152)
		(end 54.887114 -274.89912)
		(width 0.16002)
		(layer "In4.Cu")
		(net "M_D_CPU1_SB_DQS_DN<9>")
	)
	(segment
		(start 48.501554 -275.930614)
		(end 48.848264 -276.277324)
		(width 0.16002)
		(layer "In4.Cu")
		(net "M_D_CPU1_SB_DQS_DN<9>")
	)
	(segment
		(start 82.181192 -271.326356)
		(end 82.189574 -271.331182)
		(width 0.09525)
		(layer "In4.Cu")
		(net "M_D_CPU1_SB_DQS_DN<9>")
	)
	(segment
		(start 83.692492 -271.331182)
		(end 83.700874 -271.326356)
		(width 0.09525)
		(layer "In4.Cu")
		(net "M_D_CPU1_SB_DQS_DN<9>")
	)
	(segment
		(start 37.069776 -276.111462)
		(end 38.078918 -276.111462)
		(width 0.16002)
		(layer "In4.Cu")
		(net "M_D_CPU1_SB_DQS_DN<9>")
	)
	(segment
		(start 54.514242 -276.290024)
		(end 54.887114 -275.917152)
		(width 0.16002)
		(layer "In4.Cu")
		(net "M_D_CPU1_SB_DQS_DN<9>")
	)
	(segment
		(start 52.737512 -274.289266)
		(end 53.345588 -274.289266)
		(width 0.16002)
		(layer "In4.Cu")
		(net "M_D_CPU1_SB_DQS_DN<9>")
	)
	(segment
		(start 90.64117 -271.326356)
		(end 90.649552 -271.331182)
		(width 0.09525)
		(layer "In4.Cu")
		(net "M_D_CPU1_SB_DQS_DN<9>")
	)
	(segment
		(start 85.941154 -271.326356)
		(end 85.949536 -271.331182)
		(width 0.09525)
		(layer "In4.Cu")
		(net "M_D_CPU1_SB_DQS_DN<9>")
	)
	(segment
		(start 46.393608 -274.334986)
		(end 46.589442 -274.53082)
		(width 0.16002)
		(layer "In4.Cu")
		(net "M_D_CPU1_SB_DQS_DN<9>")
	)
	(segment
		(start 78.463648 -271.407128)
		(end 79.650336 -271.407128)
		(width 0.09525)
		(layer "In4.Cu")
		(net "M_D_CPU1_SB_DQS_DN<9>")
	)
	(segment
		(start 86.881208 -271.326356)
		(end 86.88959 -271.331182)
		(width 0.09525)
		(layer "In4.Cu")
		(net "M_D_CPU1_SB_DQS_DN<9>")
	)
	(segment
		(start 77.384656 -270.328136)
		(end 78.463648 -271.407128)
		(width 0.09525)
		(layer "In4.Cu")
		(net "M_D_CPU1_SB_DQS_DN<9>")
	)
	(segment
		(start 46.589442 -275.557742)
		(end 46.962314 -275.930614)
		(width 0.16002)
		(layer "In4.Cu")
		(net "M_D_CPU1_SB_DQS_DN<9>")
	)
	(segment
		(start 55.082948 -274.703286)
		(end 55.359554 -274.703286)
		(width 0.16002)
		(layer "In4.Cu")
		(net "M_D_CPU1_SB_DQS_DN<9>")
	)
	(segment
		(start 55.555388 -275.917152)
		(end 55.92826 -276.290024)
		(width 0.16002)
		(layer "In4.Cu")
		(net "M_D_CPU1_SB_DQS_DN<9>")
	)
	(segment
		(start 76.757022 -270.328136)
		(end 77.384656 -270.328136)
		(width 0.09525)
		(layer "In4.Cu")
		(net "M_D_CPU1_SB_DQS_DN<9>")
	)
	(segment
		(start 55.555388 -274.89912)
		(end 55.555388 -275.917152)
		(width 0.16002)
		(layer "In4.Cu")
		(net "M_D_CPU1_SB_DQS_DN<9>")
	)
	(segment
		(start 80.301338 -271.326356)
		(end 80.30972 -271.331182)
		(width 0.09525)
		(layer "In4.Cu")
		(net "M_D_CPU1_SB_DQS_DN<9>")
	)
	(segment
		(start 50.305208 -275.477224)
		(end 50.988976 -275.477224)
		(width 0.16002)
		(layer "In4.Cu")
		(net "M_D_CPU1_SB_DQS_DN<9>")
	)
	(arc
		(start 82.189574 -271.331182)
		(mid 82.471006 -271.406937)
		(end 82.752438 -271.331182)
		(width 0.09525)
		(layer "In4.Cu")
		(net "M_D_CPU1_SB_DQS_DN<9>")
	)
	(arc
		(start 81.812384 -271.331182)
		(mid 81.996159 -271.28041)
		(end 82.181192 -271.326356)
		(width 0.09525)
		(layer "In4.Cu")
		(net "M_D_CPU1_SB_DQS_DN<9>")
	)
	(arc
		(start 87.829644 -271.331182)
		(mid 88.111076 -271.406937)
		(end 88.392508 -271.331182)
		(width 0.09525)
		(layer "In4.Cu")
		(net "M_D_CPU1_SB_DQS_DN<9>")
	)
	(arc
		(start 90.272362 -271.331182)
		(mid 90.456137 -271.28041)
		(end 90.64117 -271.326356)
		(width 0.09525)
		(layer "In4.Cu")
		(net "M_D_CPU1_SB_DQS_DN<9>")
	)
	(arc
		(start 80.30972 -271.331182)
		(mid 80.591152 -271.406937)
		(end 80.872584 -271.331182)
		(width 0.09525)
		(layer "In4.Cu")
		(net "M_D_CPU1_SB_DQS_DN<9>")
	)
	(arc
		(start 80.872584 -271.331182)
		(mid 81.061052 -271.280505)
		(end 81.24952 -271.331182)
		(width 0.09525)
		(layer "In4.Cu")
		(net "M_D_CPU1_SB_DQS_DN<9>")
	)
	(arc
		(start 83.129628 -271.331182)
		(mid 83.41106 -271.406937)
		(end 83.692492 -271.331182)
		(width 0.09525)
		(layer "In4.Cu")
		(net "M_D_CPU1_SB_DQS_DN<9>")
	)
	(arc
		(start 83.700874 -271.326356)
		(mid 83.885906 -271.280442)
		(end 84.069682 -271.331182)
		(width 0.09525)
		(layer "In4.Cu")
		(net "M_D_CPU1_SB_DQS_DN<9>")
	)
	(arc
		(start 89.709498 -271.331182)
		(mid 89.99093 -271.406937)
		(end 90.272362 -271.331182)
		(width 0.09525)
		(layer "In4.Cu")
		(net "M_D_CPU1_SB_DQS_DN<9>")
	)
	(arc
		(start 84.069682 -271.331182)
		(mid 84.351114 -271.406937)
		(end 84.632546 -271.331182)
		(width 0.09525)
		(layer "In4.Cu")
		(net "M_D_CPU1_SB_DQS_DN<9>")
	)
	(arc
		(start 85.572346 -271.331182)
		(mid 85.756121 -271.28041)
		(end 85.941154 -271.326356)
		(width 0.09525)
		(layer "In4.Cu")
		(net "M_D_CPU1_SB_DQS_DN<9>")
	)
	(arc
		(start 85.949536 -271.331182)
		(mid 86.230968 -271.406937)
		(end 86.5124 -271.331182)
		(width 0.09525)
		(layer "In4.Cu")
		(net "M_D_CPU1_SB_DQS_DN<9>")
	)
	(arc
		(start 88.40089 -271.326356)
		(mid 88.585922 -271.280442)
		(end 88.769698 -271.331182)
		(width 0.09525)
		(layer "In4.Cu")
		(net "M_D_CPU1_SB_DQS_DN<9>")
	)
	(arc
		(start 79.650336 -271.407128)
		(mid 79.796196 -271.387769)
		(end 79.932022 -271.331182)
		(width 0.09525)
		(layer "In4.Cu")
		(net "M_D_CPU1_SB_DQS_DN<9>")
	)
	(arc
		(start 91.125802 -271.37233)
		(mid 91.13613 -271.36837)
		(end 91.146376 -271.364202)
		(width 0.09525)
		(layer "In4.Cu")
		(net "M_D_CPU1_SB_DQS_DN<9>")
	)
	(arc
		(start 86.5124 -271.331182)
		(mid 86.696175 -271.28041)
		(end 86.881208 -271.326356)
		(width 0.09525)
		(layer "In4.Cu")
		(net "M_D_CPU1_SB_DQS_DN<9>")
	)
	(arc
		(start 90.649552 -271.331182)
		(mid 90.883066 -271.405025)
		(end 91.125802 -271.37233)
		(width 0.09525)
		(layer "In4.Cu")
		(net "M_D_CPU1_SB_DQS_DN<9>")
	)
	(arc
		(start 84.632546 -271.331182)
		(mid 84.821014 -271.280505)
		(end 85.009482 -271.331182)
		(width 0.09525)
		(layer "In4.Cu")
		(net "M_D_CPU1_SB_DQS_DN<9>")
	)
	(arc
		(start 85.009482 -271.331182)
		(mid 85.290914 -271.406937)
		(end 85.572346 -271.331182)
		(width 0.09525)
		(layer "In4.Cu")
		(net "M_D_CPU1_SB_DQS_DN<9>")
	)
	(arc
		(start 79.932022 -271.331182)
		(mid 80.116051 -271.280283)
		(end 80.301338 -271.326356)
		(width 0.09525)
		(layer "In4.Cu")
		(net "M_D_CPU1_SB_DQS_DN<9>")
	)
	(arc
		(start 86.88959 -271.331182)
		(mid 87.171022 -271.406937)
		(end 87.452454 -271.331182)
		(width 0.09525)
		(layer "In4.Cu")
		(net "M_D_CPU1_SB_DQS_DN<9>")
	)
	(arc
		(start 89.332562 -271.331182)
		(mid 89.52103 -271.280505)
		(end 89.709498 -271.331182)
		(width 0.09525)
		(layer "In4.Cu")
		(net "M_D_CPU1_SB_DQS_DN<9>")
	)
	(arc
		(start 81.24952 -271.331182)
		(mid 81.530952 -271.406937)
		(end 81.812384 -271.331182)
		(width 0.09525)
		(layer "In4.Cu")
		(net "M_D_CPU1_SB_DQS_DN<9>")
	)
	(arc
		(start 88.769698 -271.331182)
		(mid 89.05113 -271.406937)
		(end 89.332562 -271.331182)
		(width 0.09525)
		(layer "In4.Cu")
		(net "M_D_CPU1_SB_DQS_DN<9>")
	)
	(arc
		(start 82.76082 -271.326356)
		(mid 82.945852 -271.280442)
		(end 83.129628 -271.331182)
		(width 0.09525)
		(layer "In4.Cu")
		(net "M_D_CPU1_SB_DQS_DN<9>")
	)
	(arc
		(start 87.460836 -271.326356)
		(mid 87.645868 -271.280442)
		(end 87.829644 -271.331182)
		(width 0.09525)
		(layer "In4.Cu")
		(net "M_D_CPU1_SB_DQS_DN<9>")
	)
	(segment
		(start 92.80779 -290.830254)
		(end 92.340938 -291.096192)
		(width 0.12954)
		(layer "F.Cu")
		(net "M_D_CPU1_SB_DQS_DN<8>")
	)
	(segment
		(start 50.814986 -313.880246)
		(end 51.124104 -314.195206)
		(width 0.16002)
		(layer "In4.Cu")
		(net "M_D_CPU1_SB_DQS_DN<8>")
	)
	(segment
		(start 77.244448 -295.31437)
		(end 77.54239 -295.017444)
		(width 0.09525)
		(layer "In4.Cu")
		(net "M_D_CPU1_SB_DQS_DN<8>")
	)
	(segment
		(start 86.881208 -291.426138)
		(end 86.88959 -291.421312)
		(width 0.09525)
		(layer "In4.Cu")
		(net "M_D_CPU1_SB_DQS_DN<8>")
	)
	(segment
		(start 50.236374 -313.880246)
		(end 50.814986 -313.880246)
		(width 0.16002)
		(layer "In4.Cu")
		(net "M_D_CPU1_SB_DQS_DN<8>")
	)
	(segment
		(start 85.941154 -291.426138)
		(end 85.949536 -291.421312)
		(width 0.09525)
		(layer "In4.Cu")
		(net "M_D_CPU1_SB_DQS_DN<8>")
	)
	(segment
		(start 91.581224 -291.426138)
		(end 91.589606 -291.421312)
		(width 0.09525)
		(layer "In4.Cu")
		(net "M_D_CPU1_SB_DQS_DN<8>")
	)
	(segment
		(start 92.15247 -291.421312)
		(end 92.160852 -291.426138)
		(width 0.09525)
		(layer "In4.Cu")
		(net "M_D_CPU1_SB_DQS_DN<8>")
	)
	(segment
		(start 83.692492 -291.421312)
		(end 83.700874 -291.426138)
		(width 0.09525)
		(layer "In4.Cu")
		(net "M_D_CPU1_SB_DQS_DN<8>")
	)
	(segment
		(start 77.54239 -295.017444)
		(end 77.54239 -294.407844)
		(width 0.09525)
		(layer "In4.Cu")
		(net "M_D_CPU1_SB_DQS_DN<8>")
	)
	(segment
		(start 55.50408 -314.570364)
		(end 55.98414 -314.570364)
		(width 0.16002)
		(layer "In4.Cu")
		(net "M_D_CPU1_SB_DQS_DN<8>")
	)
	(segment
		(start 34.121852 -313.795664)
		(end 35.630358 -313.795664)
		(width 0.16002)
		(layer "In4.Cu")
		(net "M_D_CPU1_SB_DQS_DN<8>")
	)
	(segment
		(start 74.35215 -298.123102)
		(end 77.144372 -295.33088)
		(width 0.16002)
		(layer "In4.Cu")
		(net "M_D_CPU1_SB_DQS_DN<8>")
	)
	(segment
		(start 40.916098 -315.058298)
		(end 42.672508 -313.884564)
		(width 0.16002)
		(layer "In4.Cu")
		(net "M_D_CPU1_SB_DQS_DN<8>")
	)
	(segment
		(start 51.124104 -314.195206)
		(end 51.606704 -314.687204)
		(width 0.16002)
		(layer "In4.Cu")
		(net "M_D_CPU1_SB_DQS_DN<8>")
	)
	(segment
		(start 77.144372 -295.33088)
		(end 77.161136 -295.314116)
		(width 0.09525)
		(layer "In4.Cu")
		(net "M_D_CPU1_SB_DQS_DN<8>")
	)
	(segment
		(start 78.844394 -292.309042)
		(end 79.680816 -291.47262)
		(width 0.09525)
		(layer "In4.Cu")
		(net "M_D_CPU1_SB_DQS_DN<8>")
	)
	(segment
		(start 87.452454 -291.421312)
		(end 87.460836 -291.426138)
		(width 0.09525)
		(layer "In4.Cu")
		(net "M_D_CPU1_SB_DQS_DN<8>")
	)
	(segment
		(start 39.697152 -314.941458)
		(end 39.813992 -315.058298)
		(width 0.16002)
		(layer "In4.Cu")
		(net "M_D_CPU1_SB_DQS_DN<8>")
	)
	(segment
		(start 43.29303 -313.884564)
		(end 46.089824 -315.058298)
		(width 0.16002)
		(layer "In4.Cu")
		(net "M_D_CPU1_SB_DQS_DN<8>")
	)
	(segment
		(start 77.706474 -294.012112)
		(end 78.844394 -292.309042)
		(width 0.09525)
		(layer "In4.Cu")
		(net "M_D_CPU1_SB_DQS_DN<8>")
	)
	(segment
		(start 92.471494 -291.44849)
		(end 92.494862 -291.361622)
		(width 0.09525)
		(layer "In4.Cu")
		(net "M_D_CPU1_SB_DQS_DN<8>")
	)
	(segment
		(start 82.181192 -291.426138)
		(end 82.189574 -291.421312)
		(width 0.09525)
		(layer "In4.Cu")
		(net "M_D_CPU1_SB_DQS_DN<8>")
	)
	(segment
		(start 62.205108 -312.672476)
		(end 74.35215 -300.525434)
		(width 0.16002)
		(layer "In4.Cu")
		(net "M_D_CPU1_SB_DQS_DN<8>")
	)
	(segment
		(start 56.925718 -314.687204)
		(end 57.717436 -313.895486)
		(width 0.16002)
		(layer "In4.Cu")
		(net "M_D_CPU1_SB_DQS_DN<8>")
	)
	(segment
		(start 39.100252 -315.058298)
		(end 39.217092 -314.941458)
		(width 0.16002)
		(layer "In4.Cu")
		(net "M_D_CPU1_SB_DQS_DN<8>")
	)
	(segment
		(start 33.8582 -314.059316)
		(end 34.121852 -313.795664)
		(width 0.16002)
		(layer "In4.Cu")
		(net "M_D_CPU1_SB_DQS_DN<8>")
	)
	(segment
		(start 49.444402 -314.409582)
		(end 50.236374 -313.880246)
		(width 0.16002)
		(layer "In4.Cu")
		(net "M_D_CPU1_SB_DQS_DN<8>")
	)
	(segment
		(start 32.695896 -313.78525)
		(end 32.969962 -314.059316)
		(width 0.16002)
		(layer "In4.Cu")
		(net "M_D_CPU1_SB_DQS_DN<8>")
	)
	(segment
		(start 36.059364 -314.22467)
		(end 37.786564 -314.22467)
		(width 0.16002)
		(layer "In4.Cu")
		(net "M_D_CPU1_SB_DQS_DN<8>")
	)
	(segment
		(start 92.494862 -291.361622)
		(end 92.340938 -291.096192)
		(width 0.09525)
		(layer "In4.Cu")
		(net "M_D_CPU1_SB_DQS_DN<8>")
	)
	(segment
		(start 42.672508 -313.884564)
		(end 43.29303 -313.884564)
		(width 0.16002)
		(layer "In4.Cu")
		(net "M_D_CPU1_SB_DQS_DN<8>")
	)
	(segment
		(start 90.64117 -291.426138)
		(end 90.649552 -291.421312)
		(width 0.09525)
		(layer "In4.Cu")
		(net "M_D_CPU1_SB_DQS_DN<8>")
	)
	(segment
		(start 77.161136 -295.314116)
		(end 77.244448 -295.31437)
		(width 0.09525)
		(layer "In4.Cu")
		(net "M_D_CPU1_SB_DQS_DN<8>")
	)
	(segment
		(start 82.752438 -291.421312)
		(end 82.76082 -291.426138)
		(width 0.09525)
		(layer "In4.Cu")
		(net "M_D_CPU1_SB_DQS_DN<8>")
	)
	(segment
		(start 59.252866 -313.895486)
		(end 62.205108 -312.672476)
		(width 0.16002)
		(layer "In4.Cu")
		(net "M_D_CPU1_SB_DQS_DN<8>")
	)
	(segment
		(start 77.54239 -294.407844)
		(end 77.706474 -294.012112)
		(width 0.09525)
		(layer "In4.Cu")
		(net "M_D_CPU1_SB_DQS_DN<8>")
	)
	(segment
		(start 32.969962 -314.059316)
		(end 33.8582 -314.059316)
		(width 0.16002)
		(layer "In4.Cu")
		(net "M_D_CPU1_SB_DQS_DN<8>")
	)
	(segment
		(start 79.680816 -291.47262)
		(end 80.120998 -291.47262)
		(width 0.09525)
		(layer "In4.Cu")
		(net "M_D_CPU1_SB_DQS_DN<8>")
	)
	(segment
		(start 57.717436 -313.895486)
		(end 59.252866 -313.895486)
		(width 0.16002)
		(layer "In4.Cu")
		(net "M_D_CPU1_SB_DQS_DN<8>")
	)
	(segment
		(start 55.98414 -314.570364)
		(end 56.10098 -314.687204)
		(width 0.16002)
		(layer "In4.Cu")
		(net "M_D_CPU1_SB_DQS_DN<8>")
	)
	(segment
		(start 46.089824 -315.058298)
		(end 47.878746 -315.058298)
		(width 0.16002)
		(layer "In4.Cu")
		(net "M_D_CPU1_SB_DQS_DN<8>")
	)
	(segment
		(start 35.630358 -313.795664)
		(end 36.059364 -314.22467)
		(width 0.16002)
		(layer "In4.Cu")
		(net "M_D_CPU1_SB_DQS_DN<8>")
	)
	(segment
		(start 47.878746 -315.058298)
		(end 49.444402 -314.409582)
		(width 0.16002)
		(layer "In4.Cu")
		(net "M_D_CPU1_SB_DQS_DN<8>")
	)
	(segment
		(start 55.38724 -314.687204)
		(end 55.50408 -314.570364)
		(width 0.16002)
		(layer "In4.Cu")
		(net "M_D_CPU1_SB_DQS_DN<8>")
	)
	(segment
		(start 38.620192 -315.058298)
		(end 39.100252 -315.058298)
		(width 0.16002)
		(layer "In4.Cu")
		(net "M_D_CPU1_SB_DQS_DN<8>")
	)
	(segment
		(start 88.392508 -291.421312)
		(end 88.40089 -291.426138)
		(width 0.09525)
		(layer "In4.Cu")
		(net "M_D_CPU1_SB_DQS_DN<8>")
	)
	(segment
		(start 51.606704 -314.687204)
		(end 55.38724 -314.687204)
		(width 0.16002)
		(layer "In4.Cu")
		(net "M_D_CPU1_SB_DQS_DN<8>")
	)
	(segment
		(start 37.786564 -314.22467)
		(end 38.620192 -315.058298)
		(width 0.16002)
		(layer "In4.Cu")
		(net "M_D_CPU1_SB_DQS_DN<8>")
	)
	(segment
		(start 74.35215 -300.525434)
		(end 74.35215 -298.123102)
		(width 0.16002)
		(layer "In4.Cu")
		(net "M_D_CPU1_SB_DQS_DN<8>")
	)
	(segment
		(start 39.813992 -315.058298)
		(end 40.916098 -315.058298)
		(width 0.16002)
		(layer "In4.Cu")
		(net "M_D_CPU1_SB_DQS_DN<8>")
	)
	(segment
		(start 56.10098 -314.687204)
		(end 56.925718 -314.687204)
		(width 0.16002)
		(layer "In4.Cu")
		(net "M_D_CPU1_SB_DQS_DN<8>")
	)
	(segment
		(start 39.217092 -314.941458)
		(end 39.697152 -314.941458)
		(width 0.16002)
		(layer "In4.Cu")
		(net "M_D_CPU1_SB_DQS_DN<8>")
	)
	(arc
		(start 81.812384 -291.421312)
		(mid 81.996159 -291.472084)
		(end 82.181192 -291.426138)
		(width 0.09525)
		(layer "In4.Cu")
		(net "M_D_CPU1_SB_DQS_DN<8>")
	)
	(arc
		(start 80.872584 -291.421312)
		(mid 81.061052 -291.471989)
		(end 81.24952 -291.421312)
		(width 0.09525)
		(layer "In4.Cu")
		(net "M_D_CPU1_SB_DQS_DN<8>")
	)
	(arc
		(start 91.589606 -291.421312)
		(mid 91.871038 -291.345557)
		(end 92.15247 -291.421312)
		(width 0.09525)
		(layer "In4.Cu")
		(net "M_D_CPU1_SB_DQS_DN<8>")
	)
	(arc
		(start 81.24952 -291.421312)
		(mid 81.530952 -291.345557)
		(end 81.812384 -291.421312)
		(width 0.09525)
		(layer "In4.Cu")
		(net "M_D_CPU1_SB_DQS_DN<8>")
	)
	(arc
		(start 85.949536 -291.421312)
		(mid 86.230968 -291.345557)
		(end 86.5124 -291.421312)
		(width 0.09525)
		(layer "In4.Cu")
		(net "M_D_CPU1_SB_DQS_DN<8>")
	)
	(arc
		(start 85.572346 -291.421312)
		(mid 85.756121 -291.472084)
		(end 85.941154 -291.426138)
		(width 0.09525)
		(layer "In4.Cu")
		(net "M_D_CPU1_SB_DQS_DN<8>")
	)
	(arc
		(start 83.129628 -291.421312)
		(mid 83.41106 -291.345557)
		(end 83.692492 -291.421312)
		(width 0.09525)
		(layer "In4.Cu")
		(net "M_D_CPU1_SB_DQS_DN<8>")
	)
	(arc
		(start 88.40089 -291.426138)
		(mid 88.585922 -291.472052)
		(end 88.769698 -291.421312)
		(width 0.09525)
		(layer "In4.Cu")
		(net "M_D_CPU1_SB_DQS_DN<8>")
	)
	(arc
		(start 82.189574 -291.421312)
		(mid 82.471006 -291.345557)
		(end 82.752438 -291.421312)
		(width 0.09525)
		(layer "In4.Cu")
		(net "M_D_CPU1_SB_DQS_DN<8>")
	)
	(arc
		(start 86.5124 -291.421312)
		(mid 86.696175 -291.472084)
		(end 86.881208 -291.426138)
		(width 0.09525)
		(layer "In4.Cu")
		(net "M_D_CPU1_SB_DQS_DN<8>")
	)
	(arc
		(start 80.120998 -291.47262)
		(mid 80.218744 -291.459425)
		(end 80.30972 -291.421312)
		(width 0.09525)
		(layer "In4.Cu")
		(net "M_D_CPU1_SB_DQS_DN<8>")
	)
	(arc
		(start 90.272362 -291.421312)
		(mid 90.456137 -291.472084)
		(end 90.64117 -291.426138)
		(width 0.09525)
		(layer "In4.Cu")
		(net "M_D_CPU1_SB_DQS_DN<8>")
	)
	(arc
		(start 86.88959 -291.421312)
		(mid 87.171022 -291.345557)
		(end 87.452454 -291.421312)
		(width 0.09525)
		(layer "In4.Cu")
		(net "M_D_CPU1_SB_DQS_DN<8>")
	)
	(arc
		(start 89.709498 -291.421312)
		(mid 89.99093 -291.345557)
		(end 90.272362 -291.421312)
		(width 0.09525)
		(layer "In4.Cu")
		(net "M_D_CPU1_SB_DQS_DN<8>")
	)
	(arc
		(start 80.30972 -291.421312)
		(mid 80.591152 -291.345557)
		(end 80.872584 -291.421312)
		(width 0.09525)
		(layer "In4.Cu")
		(net "M_D_CPU1_SB_DQS_DN<8>")
	)
	(arc
		(start 89.332562 -291.421312)
		(mid 89.52103 -291.471989)
		(end 89.709498 -291.421312)
		(width 0.09525)
		(layer "In4.Cu")
		(net "M_D_CPU1_SB_DQS_DN<8>")
	)
	(arc
		(start 90.649552 -291.421312)
		(mid 90.930984 -291.345557)
		(end 91.212416 -291.421312)
		(width 0.09525)
		(layer "In4.Cu")
		(net "M_D_CPU1_SB_DQS_DN<8>")
	)
	(arc
		(start 83.700874 -291.426138)
		(mid 83.885906 -291.472052)
		(end 84.069682 -291.421312)
		(width 0.09525)
		(layer "In4.Cu")
		(net "M_D_CPU1_SB_DQS_DN<8>")
	)
	(arc
		(start 84.632546 -291.421312)
		(mid 84.821014 -291.471989)
		(end 85.009482 -291.421312)
		(width 0.09525)
		(layer "In4.Cu")
		(net "M_D_CPU1_SB_DQS_DN<8>")
	)
	(arc
		(start 82.76082 -291.426138)
		(mid 82.945852 -291.472052)
		(end 83.129628 -291.421312)
		(width 0.09525)
		(layer "In4.Cu")
		(net "M_D_CPU1_SB_DQS_DN<8>")
	)
	(arc
		(start 87.460836 -291.426138)
		(mid 87.645868 -291.472052)
		(end 87.829644 -291.421312)
		(width 0.09525)
		(layer "In4.Cu")
		(net "M_D_CPU1_SB_DQS_DN<8>")
	)
	(arc
		(start 91.212416 -291.421312)
		(mid 91.396191 -291.472084)
		(end 91.581224 -291.426138)
		(width 0.09525)
		(layer "In4.Cu")
		(net "M_D_CPU1_SB_DQS_DN<8>")
	)
	(arc
		(start 88.769698 -291.421312)
		(mid 89.05113 -291.345557)
		(end 89.332562 -291.421312)
		(width 0.09525)
		(layer "In4.Cu")
		(net "M_D_CPU1_SB_DQS_DN<8>")
	)
	(arc
		(start 84.069682 -291.421312)
		(mid 84.351114 -291.345557)
		(end 84.632546 -291.421312)
		(width 0.09525)
		(layer "In4.Cu")
		(net "M_D_CPU1_SB_DQS_DN<8>")
	)
	(arc
		(start 92.160852 -291.426138)
		(mid 92.313747 -291.470966)
		(end 92.471494 -291.44849)
		(width 0.09525)
		(layer "In4.Cu")
		(net "M_D_CPU1_SB_DQS_DN<8>")
	)
	(arc
		(start 87.829644 -291.421312)
		(mid 88.111076 -291.345557)
		(end 88.392508 -291.421312)
		(width 0.09525)
		(layer "In4.Cu")
		(net "M_D_CPU1_SB_DQS_DN<8>")
	)
	(arc
		(start 85.009482 -291.421312)
		(mid 85.290914 -291.345557)
		(end 85.572346 -291.421312)
		(width 0.09525)
		(layer "In4.Cu")
		(net "M_D_CPU1_SB_DQS_DN<8>")
	)
	(segment
		(start 92.80779 -285.970472)
		(end 92.340938 -286.23641)
		(width 0.12954)
		(layer "F.Cu")
		(net "M_D_CPU1_SB_DQS_DN<7>")
	)
	(segment
		(start 78.97622 -286.552132)
		(end 78.991968 -286.561276)
		(width 0.09525)
		(layer "In4.Cu")
		(net "M_D_CPU1_SB_DQS_DN<7>")
	)
	(segment
		(start 82.181192 -286.566356)
		(end 82.189574 -286.56153)
		(width 0.09525)
		(layer "In4.Cu")
		(net "M_D_CPU1_SB_DQS_DN<7>")
	)
	(segment
		(start 47.346108 -305.708304)
		(end 48.082962 -305.708304)
		(width 0.16002)
		(layer "In4.Cu")
		(net "M_D_CPU1_SB_DQS_DN<7>")
	)
	(segment
		(start 83.692492 -286.56153)
		(end 83.700874 -286.566356)
		(width 0.09525)
		(layer "In4.Cu")
		(net "M_D_CPU1_SB_DQS_DN<7>")
	)
	(segment
		(start 76.05649 -287.796732)
		(end 76.951586 -286.901636)
		(width 0.09525)
		(layer "In4.Cu")
		(net "M_D_CPU1_SB_DQS_DN<7>")
	)
	(segment
		(start 91.581224 -286.566356)
		(end 91.589606 -286.56153)
		(width 0.09525)
		(layer "In4.Cu")
		(net "M_D_CPU1_SB_DQS_DN<7>")
	)
	(segment
		(start 57.628536 -304.612802)
		(end 60.440316 -304.053494)
		(width 0.16002)
		(layer "In4.Cu")
		(net "M_D_CPU1_SB_DQS_DN<7>")
	)
	(segment
		(start 32.969962 -304.709322)
		(end 33.562544 -304.709322)
		(width 0.16002)
		(layer "In4.Cu")
		(net "M_D_CPU1_SB_DQS_DN<7>")
	)
	(segment
		(start 40.146732 -305.708304)
		(end 40.366696 -305.708304)
		(width 0.16002)
		(layer "In4.Cu")
		(net "M_D_CPU1_SB_DQS_DN<7>")
	)
	(segment
		(start 60.440316 -304.053494)
		(end 61.284612 -303.703736)
		(width 0.16002)
		(layer "In4.Cu")
		(net "M_D_CPU1_SB_DQS_DN<7>")
	)
	(segment
		(start 48.082962 -305.708304)
		(end 49.082452 -305.294284)
		(width 0.16002)
		(layer "In4.Cu")
		(net "M_D_CPU1_SB_DQS_DN<7>")
	)
	(segment
		(start 54.156356 -305.375564)
		(end 54.70398 -305.375564)
		(width 0.16002)
		(layer "In4.Cu")
		(net "M_D_CPU1_SB_DQS_DN<7>")
	)
	(segment
		(start 87.452454 -286.56153)
		(end 87.460836 -286.566356)
		(width 0.09525)
		(layer "In4.Cu")
		(net "M_D_CPU1_SB_DQS_DN<7>")
	)
	(segment
		(start 90.64117 -286.566356)
		(end 90.649552 -286.56153)
		(width 0.09525)
		(layer "In4.Cu")
		(net "M_D_CPU1_SB_DQS_DN<7>")
	)
	(segment
		(start 42.215816 -304.942494)
		(end 42.653458 -304.504852)
		(width 0.16002)
		(layer "In4.Cu")
		(net "M_D_CPU1_SB_DQS_DN<7>")
	)
	(segment
		(start 33.562544 -304.709322)
		(end 33.679384 -304.592482)
		(width 0.16002)
		(layer "In4.Cu")
		(net "M_D_CPU1_SB_DQS_DN<7>")
	)
	(segment
		(start 51.546252 -304.858166)
		(end 52.90693 -304.858166)
		(width 0.16002)
		(layer "In4.Cu")
		(net "M_D_CPU1_SB_DQS_DN<7>")
	)
	(segment
		(start 68.66255 -295.106344)
		(end 75.955906 -287.813496)
		(width 0.16002)
		(layer "In4.Cu")
		(net "M_D_CPU1_SB_DQS_DN<7>")
	)
	(segment
		(start 52.90693 -304.858166)
		(end 54.156356 -305.375564)
		(width 0.16002)
		(layer "In4.Cu")
		(net "M_D_CPU1_SB_DQS_DN<7>")
	)
	(segment
		(start 34.276284 -304.709322)
		(end 34.756344 -304.709322)
		(width 0.16002)
		(layer "In4.Cu")
		(net "M_D_CPU1_SB_DQS_DN<7>")
	)
	(segment
		(start 77.665072 -286.901636)
		(end 77.953616 -286.613092)
		(width 0.09525)
		(layer "In4.Cu")
		(net "M_D_CPU1_SB_DQS_DN<7>")
	)
	(segment
		(start 34.159444 -304.592482)
		(end 34.276284 -304.709322)
		(width 0.16002)
		(layer "In4.Cu")
		(net "M_D_CPU1_SB_DQS_DN<7>")
	)
	(segment
		(start 55.30088 -305.258724)
		(end 55.41772 -305.375564)
		(width 0.16002)
		(layer "In4.Cu")
		(net "M_D_CPU1_SB_DQS_DN<7>")
	)
	(segment
		(start 49.082452 -305.294284)
		(end 50.226214 -304.530252)
		(width 0.16002)
		(layer "In4.Cu")
		(net "M_D_CPU1_SB_DQS_DN<7>")
	)
	(segment
		(start 82.752438 -286.56153)
		(end 82.76082 -286.566356)
		(width 0.09525)
		(layer "In4.Cu")
		(net "M_D_CPU1_SB_DQS_DN<7>")
	)
	(segment
		(start 86.881208 -286.566356)
		(end 86.88959 -286.56153)
		(width 0.09525)
		(layer "In4.Cu")
		(net "M_D_CPU1_SB_DQS_DN<7>")
	)
	(segment
		(start 34.983928 -304.481738)
		(end 35.689032 -304.481738)
		(width 0.16002)
		(layer "In4.Cu")
		(net "M_D_CPU1_SB_DQS_DN<7>")
	)
	(segment
		(start 36.6649 -304.874676)
		(end 37.320474 -305.145948)
		(width 0.16002)
		(layer "In4.Cu")
		(net "M_D_CPU1_SB_DQS_DN<7>")
	)
	(segment
		(start 34.756344 -304.709322)
		(end 34.983928 -304.481738)
		(width 0.16002)
		(layer "In4.Cu")
		(net "M_D_CPU1_SB_DQS_DN<7>")
	)
	(segment
		(start 55.41772 -305.375564)
		(end 56.865774 -305.375564)
		(width 0.16002)
		(layer "In4.Cu")
		(net "M_D_CPU1_SB_DQS_DN<7>")
	)
	(segment
		(start 36.08197 -304.874676)
		(end 36.6649 -304.874676)
		(width 0.16002)
		(layer "In4.Cu")
		(net "M_D_CPU1_SB_DQS_DN<7>")
	)
	(segment
		(start 42.653458 -304.504852)
		(end 43.250358 -304.504852)
		(width 0.16002)
		(layer "In4.Cu")
		(net "M_D_CPU1_SB_DQS_DN<7>")
	)
	(segment
		(start 50.226214 -304.530252)
		(end 50.754534 -304.530252)
		(width 0.16002)
		(layer "In4.Cu")
		(net "M_D_CPU1_SB_DQS_DN<7>")
	)
	(segment
		(start 43.250358 -304.504852)
		(end 43.603672 -304.858166)
		(width 0.16002)
		(layer "In4.Cu")
		(net "M_D_CPU1_SB_DQS_DN<7>")
	)
	(segment
		(start 92.494862 -286.50184)
		(end 92.340938 -286.23641)
		(width 0.09525)
		(layer "In4.Cu")
		(net "M_D_CPU1_SB_DQS_DN<7>")
	)
	(segment
		(start 37.320474 -305.145948)
		(end 40.146732 -305.708304)
		(width 0.16002)
		(layer "In4.Cu")
		(net "M_D_CPU1_SB_DQS_DN<7>")
	)
	(segment
		(start 32.695896 -304.435256)
		(end 32.969962 -304.709322)
		(width 0.16002)
		(layer "In4.Cu")
		(net "M_D_CPU1_SB_DQS_DN<7>")
	)
	(segment
		(start 78.991968 -286.561276)
		(end 79.005938 -286.56915)
		(width 0.09525)
		(layer "In4.Cu")
		(net "M_D_CPU1_SB_DQS_DN<7>")
	)
	(segment
		(start 88.392508 -286.56153)
		(end 88.40089 -286.566356)
		(width 0.09525)
		(layer "In4.Cu")
		(net "M_D_CPU1_SB_DQS_DN<7>")
	)
	(segment
		(start 79.36865 -286.56153)
		(end 79.383382 -286.552894)
		(width 0.09525)
		(layer "In4.Cu")
		(net "M_D_CPU1_SB_DQS_DN<7>")
	)
	(segment
		(start 75.97267 -287.796732)
		(end 76.05649 -287.796732)
		(width 0.09525)
		(layer "In4.Cu")
		(net "M_D_CPU1_SB_DQS_DN<7>")
	)
	(segment
		(start 54.70398 -305.375564)
		(end 54.82082 -305.258724)
		(width 0.16002)
		(layer "In4.Cu")
		(net "M_D_CPU1_SB_DQS_DN<7>")
	)
	(segment
		(start 68.66255 -296.325798)
		(end 68.66255 -295.106344)
		(width 0.16002)
		(layer "In4.Cu")
		(net "M_D_CPU1_SB_DQS_DN<7>")
	)
	(segment
		(start 92.15247 -286.56153)
		(end 92.160852 -286.566356)
		(width 0.09525)
		(layer "In4.Cu")
		(net "M_D_CPU1_SB_DQS_DN<7>")
	)
	(segment
		(start 61.284612 -303.703736)
		(end 68.66255 -296.325798)
		(width 0.16002)
		(layer "In4.Cu")
		(net "M_D_CPU1_SB_DQS_DN<7>")
	)
	(segment
		(start 35.689032 -304.481738)
		(end 36.08197 -304.874676)
		(width 0.16002)
		(layer "In4.Cu")
		(net "M_D_CPU1_SB_DQS_DN<7>")
	)
	(segment
		(start 77.953616 -286.613092)
		(end 78.239874 -286.613092)
		(width 0.09525)
		(layer "In4.Cu")
		(net "M_D_CPU1_SB_DQS_DN<7>")
	)
	(segment
		(start 75.955906 -287.813496)
		(end 75.97267 -287.796732)
		(width 0.09525)
		(layer "In4.Cu")
		(net "M_D_CPU1_SB_DQS_DN<7>")
	)
	(segment
		(start 33.679384 -304.592482)
		(end 34.159444 -304.592482)
		(width 0.16002)
		(layer "In4.Cu")
		(net "M_D_CPU1_SB_DQS_DN<7>")
	)
	(segment
		(start 76.951586 -286.901636)
		(end 77.665072 -286.901636)
		(width 0.09525)
		(layer "In4.Cu")
		(net "M_D_CPU1_SB_DQS_DN<7>")
	)
	(segment
		(start 85.941154 -286.566356)
		(end 85.949536 -286.56153)
		(width 0.09525)
		(layer "In4.Cu")
		(net "M_D_CPU1_SB_DQS_DN<7>")
	)
	(segment
		(start 80.301338 -286.566356)
		(end 80.30972 -286.56153)
		(width 0.09525)
		(layer "In4.Cu")
		(net "M_D_CPU1_SB_DQS_DN<7>")
	)
	(segment
		(start 43.603672 -304.858166)
		(end 45.293534 -304.858166)
		(width 0.16002)
		(layer "In4.Cu")
		(net "M_D_CPU1_SB_DQS_DN<7>")
	)
	(segment
		(start 40.366696 -305.708304)
		(end 42.215816 -304.942494)
		(width 0.16002)
		(layer "In4.Cu")
		(net "M_D_CPU1_SB_DQS_DN<7>")
	)
	(segment
		(start 54.82082 -305.258724)
		(end 55.30088 -305.258724)
		(width 0.16002)
		(layer "In4.Cu")
		(net "M_D_CPU1_SB_DQS_DN<7>")
	)
	(segment
		(start 56.865774 -305.375564)
		(end 57.628536 -304.612802)
		(width 0.16002)
		(layer "In4.Cu")
		(net "M_D_CPU1_SB_DQS_DN<7>")
	)
	(segment
		(start 92.471494 -286.588708)
		(end 92.494862 -286.50184)
		(width 0.09525)
		(layer "In4.Cu")
		(net "M_D_CPU1_SB_DQS_DN<7>")
	)
	(segment
		(start 45.293534 -304.858166)
		(end 47.346108 -305.708304)
		(width 0.16002)
		(layer "In4.Cu")
		(net "M_D_CPU1_SB_DQS_DN<7>")
	)
	(segment
		(start 50.754534 -304.530252)
		(end 51.546252 -304.858166)
		(width 0.16002)
		(layer "In4.Cu")
		(net "M_D_CPU1_SB_DQS_DN<7>")
	)
	(arc
		(start 91.212416 -286.56153)
		(mid 91.396191 -286.612302)
		(end 91.581224 -286.566356)
		(width 0.09525)
		(layer "In4.Cu")
		(net "M_D_CPU1_SB_DQS_DN<7>")
	)
	(arc
		(start 85.572346 -286.56153)
		(mid 85.756121 -286.612302)
		(end 85.941154 -286.566356)
		(width 0.09525)
		(layer "In4.Cu")
		(net "M_D_CPU1_SB_DQS_DN<7>")
	)
	(arc
		(start 89.332562 -286.56153)
		(mid 89.52103 -286.612207)
		(end 89.709498 -286.56153)
		(width 0.09525)
		(layer "In4.Cu")
		(net "M_D_CPU1_SB_DQS_DN<7>")
	)
	(arc
		(start 84.632546 -286.56153)
		(mid 84.821014 -286.612207)
		(end 85.009482 -286.56153)
		(width 0.09525)
		(layer "In4.Cu")
		(net "M_D_CPU1_SB_DQS_DN<7>")
	)
	(arc
		(start 91.589606 -286.56153)
		(mid 91.871038 -286.485741)
		(end 92.15247 -286.56153)
		(width 0.09525)
		(layer "In4.Cu")
		(net "M_D_CPU1_SB_DQS_DN<7>")
	)
	(arc
		(start 90.272362 -286.56153)
		(mid 90.456137 -286.612302)
		(end 90.64117 -286.566356)
		(width 0.09525)
		(layer "In4.Cu")
		(net "M_D_CPU1_SB_DQS_DN<7>")
	)
	(arc
		(start 81.812384 -286.56153)
		(mid 81.996159 -286.612302)
		(end 82.181192 -286.566356)
		(width 0.09525)
		(layer "In4.Cu")
		(net "M_D_CPU1_SB_DQS_DN<7>")
	)
	(arc
		(start 87.829644 -286.56153)
		(mid 88.111076 -286.485741)
		(end 88.392508 -286.56153)
		(width 0.09525)
		(layer "In4.Cu")
		(net "M_D_CPU1_SB_DQS_DN<7>")
	)
	(arc
		(start 82.76082 -286.566356)
		(mid 82.945852 -286.61227)
		(end 83.129628 -286.56153)
		(width 0.09525)
		(layer "In4.Cu")
		(net "M_D_CPU1_SB_DQS_DN<7>")
	)
	(arc
		(start 81.24952 -286.56153)
		(mid 81.530952 -286.485741)
		(end 81.812384 -286.56153)
		(width 0.09525)
		(layer "In4.Cu")
		(net "M_D_CPU1_SB_DQS_DN<7>")
	)
	(arc
		(start 79.005938 -286.56915)
		(mid 79.188282 -286.612048)
		(end 79.36865 -286.56153)
		(width 0.09525)
		(layer "In4.Cu")
		(net "M_D_CPU1_SB_DQS_DN<7>")
	)
	(arc
		(start 79.383382 -286.552894)
		(mid 79.658841 -286.485479)
		(end 79.932022 -286.56153)
		(width 0.09525)
		(layer "In4.Cu")
		(net "M_D_CPU1_SB_DQS_DN<7>")
	)
	(arc
		(start 83.700874 -286.566356)
		(mid 83.885906 -286.61227)
		(end 84.069682 -286.56153)
		(width 0.09525)
		(layer "In4.Cu")
		(net "M_D_CPU1_SB_DQS_DN<7>")
	)
	(arc
		(start 83.129628 -286.56153)
		(mid 83.41106 -286.485741)
		(end 83.692492 -286.56153)
		(width 0.09525)
		(layer "In4.Cu")
		(net "M_D_CPU1_SB_DQS_DN<7>")
	)
	(arc
		(start 84.069682 -286.56153)
		(mid 84.351114 -286.485741)
		(end 84.632546 -286.56153)
		(width 0.09525)
		(layer "In4.Cu")
		(net "M_D_CPU1_SB_DQS_DN<7>")
	)
	(arc
		(start 90.649552 -286.56153)
		(mid 90.930984 -286.485741)
		(end 91.212416 -286.56153)
		(width 0.09525)
		(layer "In4.Cu")
		(net "M_D_CPU1_SB_DQS_DN<7>")
	)
	(arc
		(start 80.30972 -286.56153)
		(mid 80.591152 -286.485741)
		(end 80.872584 -286.56153)
		(width 0.09525)
		(layer "In4.Cu")
		(net "M_D_CPU1_SB_DQS_DN<7>")
	)
	(arc
		(start 89.709498 -286.56153)
		(mid 89.99093 -286.485741)
		(end 90.272362 -286.56153)
		(width 0.09525)
		(layer "In4.Cu")
		(net "M_D_CPU1_SB_DQS_DN<7>")
	)
	(arc
		(start 92.160852 -286.566356)
		(mid 92.313747 -286.611184)
		(end 92.471494 -286.588708)
		(width 0.09525)
		(layer "In4.Cu")
		(net "M_D_CPU1_SB_DQS_DN<7>")
	)
	(arc
		(start 86.5124 -286.56153)
		(mid 86.696175 -286.612302)
		(end 86.881208 -286.566356)
		(width 0.09525)
		(layer "In4.Cu")
		(net "M_D_CPU1_SB_DQS_DN<7>")
	)
	(arc
		(start 85.009482 -286.56153)
		(mid 85.290914 -286.485741)
		(end 85.572346 -286.56153)
		(width 0.09525)
		(layer "In4.Cu")
		(net "M_D_CPU1_SB_DQS_DN<7>")
	)
	(arc
		(start 79.932022 -286.56153)
		(mid 80.116051 -286.612429)
		(end 80.301338 -286.566356)
		(width 0.09525)
		(layer "In4.Cu")
		(net "M_D_CPU1_SB_DQS_DN<7>")
	)
	(arc
		(start 78.239874 -286.613092)
		(mid 78.337898 -286.599831)
		(end 78.429104 -286.56153)
		(width 0.09525)
		(layer "In4.Cu")
		(net "M_D_CPU1_SB_DQS_DN<7>")
	)
	(arc
		(start 78.429104 -286.56153)
		(mid 78.701435 -286.485568)
		(end 78.97622 -286.552132)
		(width 0.09525)
		(layer "In4.Cu")
		(net "M_D_CPU1_SB_DQS_DN<7>")
	)
	(arc
		(start 88.40089 -286.566356)
		(mid 88.585922 -286.61227)
		(end 88.769698 -286.56153)
		(width 0.09525)
		(layer "In4.Cu")
		(net "M_D_CPU1_SB_DQS_DN<7>")
	)
	(arc
		(start 80.872584 -286.56153)
		(mid 81.061052 -286.612207)
		(end 81.24952 -286.56153)
		(width 0.09525)
		(layer "In4.Cu")
		(net "M_D_CPU1_SB_DQS_DN<7>")
	)
	(arc
		(start 86.88959 -286.56153)
		(mid 87.171022 -286.485741)
		(end 87.452454 -286.56153)
		(width 0.09525)
		(layer "In4.Cu")
		(net "M_D_CPU1_SB_DQS_DN<7>")
	)
	(arc
		(start 88.769698 -286.56153)
		(mid 89.05113 -286.485741)
		(end 89.332562 -286.56153)
		(width 0.09525)
		(layer "In4.Cu")
		(net "M_D_CPU1_SB_DQS_DN<7>")
	)
	(arc
		(start 82.189574 -286.56153)
		(mid 82.471006 -286.485741)
		(end 82.752438 -286.56153)
		(width 0.09525)
		(layer "In4.Cu")
		(net "M_D_CPU1_SB_DQS_DN<7>")
	)
	(arc
		(start 85.949536 -286.56153)
		(mid 86.230968 -286.485741)
		(end 86.5124 -286.56153)
		(width 0.09525)
		(layer "In4.Cu")
		(net "M_D_CPU1_SB_DQS_DN<7>")
	)
	(arc
		(start 87.460836 -286.566356)
		(mid 87.645868 -286.61227)
		(end 87.829644 -286.56153)
		(width 0.09525)
		(layer "In4.Cu")
		(net "M_D_CPU1_SB_DQS_DN<7>")
	)
	(segment
		(start 92.80779 -281.110436)
		(end 92.340938 -281.376374)
		(width 0.12954)
		(layer "F.Cu")
		(net "M_D_CPU1_SB_DQS_DN<6>")
	)
	(segment
		(start 49.294034 -295.832022)
		(end 50.269902 -295.180258)
		(width 0.16002)
		(layer "In4.Cu")
		(net "M_D_CPU1_SB_DQS_DN<6>")
	)
	(segment
		(start 39.180008 -296.24147)
		(end 39.660068 -296.24147)
		(width 0.16002)
		(layer "In4.Cu")
		(net "M_D_CPU1_SB_DQS_DN<6>")
	)
	(segment
		(start 80.301338 -281.70632)
		(end 80.30972 -281.701494)
		(width 0.09525)
		(layer "In4.Cu")
		(net "M_D_CPU1_SB_DQS_DN<6>")
	)
	(segment
		(start 87.452454 -281.701494)
		(end 87.460836 -281.70632)
		(width 0.09525)
		(layer "In4.Cu")
		(net "M_D_CPU1_SB_DQS_DN<6>")
	)
	(segment
		(start 32.969962 -295.359328)
		(end 33.347152 -295.359328)
		(width 0.16002)
		(layer "In4.Cu")
		(net "M_D_CPU1_SB_DQS_DN<6>")
	)
	(segment
		(start 32.695896 -295.085262)
		(end 32.969962 -295.359328)
		(width 0.16002)
		(layer "In4.Cu")
		(net "M_D_CPU1_SB_DQS_DN<6>")
	)
	(segment
		(start 42.691304 -295.19245)
		(end 43.110658 -295.19245)
		(width 0.16002)
		(layer "In4.Cu")
		(net "M_D_CPU1_SB_DQS_DN<6>")
	)
	(segment
		(start 46.318932 -295.850056)
		(end 47.545752 -296.35831)
		(width 0.16002)
		(layer "In4.Cu")
		(net "M_D_CPU1_SB_DQS_DN<6>")
	)
	(segment
		(start 76.03871 -281.731466)
		(end 76.43749 -281.731466)
		(width 0.09525)
		(layer "In4.Cu")
		(net "M_D_CPU1_SB_DQS_DN<6>")
	)
	(segment
		(start 75.979528 -281.672284)
		(end 76.03871 -281.731466)
		(width 0.09525)
		(layer "In4.Cu")
		(net "M_D_CPU1_SB_DQS_DN<6>")
	)
	(segment
		(start 88.392508 -281.701494)
		(end 88.40089 -281.70632)
		(width 0.09525)
		(layer "In4.Cu")
		(net "M_D_CPU1_SB_DQS_DN<6>")
	)
	(segment
		(start 39.776908 -296.35831)
		(end 40.589962 -296.35831)
		(width 0.16002)
		(layer "In4.Cu")
		(net "M_D_CPU1_SB_DQS_DN<6>")
	)
	(segment
		(start 92.471494 -281.728672)
		(end 92.494862 -281.641804)
		(width 0.09525)
		(layer "In4.Cu")
		(net "M_D_CPU1_SB_DQS_DN<6>")
	)
	(segment
		(start 76.62545 -281.543506)
		(end 79.345536 -281.543506)
		(width 0.09525)
		(layer "In4.Cu")
		(net "M_D_CPU1_SB_DQS_DN<6>")
	)
	(segment
		(start 43.110658 -295.19245)
		(end 43.873674 -295.508172)
		(width 0.16002)
		(layer "In4.Cu")
		(net "M_D_CPU1_SB_DQS_DN<6>")
	)
	(segment
		(start 56.91378 -295.977564)
		(end 57.711086 -295.180258)
		(width 0.16002)
		(layer "In4.Cu")
		(net "M_D_CPU1_SB_DQS_DN<6>")
	)
	(segment
		(start 91.581224 -281.70632)
		(end 91.589606 -281.701494)
		(width 0.09525)
		(layer "In4.Cu")
		(net "M_D_CPU1_SB_DQS_DN<6>")
	)
	(segment
		(start 85.941154 -281.70632)
		(end 85.949536 -281.701494)
		(width 0.09525)
		(layer "In4.Cu")
		(net "M_D_CPU1_SB_DQS_DN<6>")
	)
	(segment
		(start 39.660068 -296.24147)
		(end 39.776908 -296.35831)
		(width 0.16002)
		(layer "In4.Cu")
		(net "M_D_CPU1_SB_DQS_DN<6>")
	)
	(segment
		(start 73.990454 -281.672284)
		(end 75.955906 -281.672284)
		(width 0.16002)
		(layer "In4.Cu")
		(net "M_D_CPU1_SB_DQS_DN<6>")
	)
	(segment
		(start 76.43749 -281.731466)
		(end 76.62545 -281.543506)
		(width 0.09525)
		(layer "In4.Cu")
		(net "M_D_CPU1_SB_DQS_DN<6>")
	)
	(segment
		(start 34.222182 -295.177464)
		(end 35.731958 -295.177464)
		(width 0.16002)
		(layer "In4.Cu")
		(net "M_D_CPU1_SB_DQS_DN<6>")
	)
	(segment
		(start 33.347152 -295.359328)
		(end 34.222182 -295.177464)
		(width 0.16002)
		(layer "In4.Cu")
		(net "M_D_CPU1_SB_DQS_DN<6>")
	)
	(segment
		(start 75.955906 -281.672284)
		(end 75.979528 -281.672284)
		(width 0.09525)
		(layer "In4.Cu")
		(net "M_D_CPU1_SB_DQS_DN<6>")
	)
	(segment
		(start 50.269902 -295.180258)
		(end 50.89017 -295.180258)
		(width 0.16002)
		(layer "In4.Cu")
		(net "M_D_CPU1_SB_DQS_DN<6>")
	)
	(segment
		(start 83.692492 -281.701494)
		(end 83.700874 -281.70632)
		(width 0.09525)
		(layer "In4.Cu")
		(net "M_D_CPU1_SB_DQS_DN<6>")
	)
	(segment
		(start 45.977048 -295.508172)
		(end 46.318932 -295.850056)
		(width 0.16002)
		(layer "In4.Cu")
		(net "M_D_CPU1_SB_DQS_DN<6>")
	)
	(segment
		(start 53.08092 -295.508172)
		(end 53.550312 -295.977564)
		(width 0.16002)
		(layer "In4.Cu")
		(net "M_D_CPU1_SB_DQS_DN<6>")
	)
	(segment
		(start 47.545752 -296.35831)
		(end 48.023526 -296.35831)
		(width 0.16002)
		(layer "In4.Cu")
		(net "M_D_CPU1_SB_DQS_DN<6>")
	)
	(segment
		(start 48.023526 -296.35831)
		(end 49.294034 -295.832022)
		(width 0.16002)
		(layer "In4.Cu")
		(net "M_D_CPU1_SB_DQS_DN<6>")
	)
	(segment
		(start 51.614578 -295.508172)
		(end 53.08092 -295.508172)
		(width 0.16002)
		(layer "In4.Cu")
		(net "M_D_CPU1_SB_DQS_DN<6>")
	)
	(segment
		(start 60.48248 -295.180258)
		(end 73.990454 -281.672284)
		(width 0.16002)
		(layer "In4.Cu")
		(net "M_D_CPU1_SB_DQS_DN<6>")
	)
	(segment
		(start 92.494862 -281.641804)
		(end 92.340938 -281.376374)
		(width 0.09525)
		(layer "In4.Cu")
		(net "M_D_CPU1_SB_DQS_DN<6>")
	)
	(segment
		(start 53.550312 -295.977564)
		(end 56.91378 -295.977564)
		(width 0.16002)
		(layer "In4.Cu")
		(net "M_D_CPU1_SB_DQS_DN<6>")
	)
	(segment
		(start 38.583108 -296.35831)
		(end 39.063168 -296.35831)
		(width 0.16002)
		(layer "In4.Cu")
		(net "M_D_CPU1_SB_DQS_DN<6>")
	)
	(segment
		(start 82.752438 -281.701494)
		(end 82.76082 -281.70632)
		(width 0.09525)
		(layer "In4.Cu")
		(net "M_D_CPU1_SB_DQS_DN<6>")
	)
	(segment
		(start 41.536366 -295.966388)
		(end 42.691304 -295.19245)
		(width 0.16002)
		(layer "In4.Cu")
		(net "M_D_CPU1_SB_DQS_DN<6>")
	)
	(segment
		(start 92.15247 -281.701494)
		(end 92.160852 -281.70632)
		(width 0.09525)
		(layer "In4.Cu")
		(net "M_D_CPU1_SB_DQS_DN<6>")
	)
	(segment
		(start 90.64117 -281.70632)
		(end 90.649552 -281.701494)
		(width 0.09525)
		(layer "In4.Cu")
		(net "M_D_CPU1_SB_DQS_DN<6>")
	)
	(segment
		(start 50.89017 -295.180258)
		(end 51.614578 -295.508172)
		(width 0.16002)
		(layer "In4.Cu")
		(net "M_D_CPU1_SB_DQS_DN<6>")
	)
	(segment
		(start 43.873674 -295.508172)
		(end 45.977048 -295.508172)
		(width 0.16002)
		(layer "In4.Cu")
		(net "M_D_CPU1_SB_DQS_DN<6>")
	)
	(segment
		(start 40.589962 -296.35831)
		(end 41.536366 -295.966388)
		(width 0.16002)
		(layer "In4.Cu")
		(net "M_D_CPU1_SB_DQS_DN<6>")
	)
	(segment
		(start 57.711086 -295.180258)
		(end 60.48248 -295.180258)
		(width 0.16002)
		(layer "In4.Cu")
		(net "M_D_CPU1_SB_DQS_DN<6>")
	)
	(segment
		(start 35.731958 -295.177464)
		(end 38.583108 -296.35831)
		(width 0.16002)
		(layer "In4.Cu")
		(net "M_D_CPU1_SB_DQS_DN<6>")
	)
	(segment
		(start 86.881208 -281.70632)
		(end 86.88959 -281.701494)
		(width 0.09525)
		(layer "In4.Cu")
		(net "M_D_CPU1_SB_DQS_DN<6>")
	)
	(segment
		(start 82.181192 -281.70632)
		(end 82.189574 -281.701494)
		(width 0.09525)
		(layer "In4.Cu")
		(net "M_D_CPU1_SB_DQS_DN<6>")
	)
	(segment
		(start 39.063168 -296.35831)
		(end 39.180008 -296.24147)
		(width 0.16002)
		(layer "In4.Cu")
		(net "M_D_CPU1_SB_DQS_DN<6>")
	)
	(arc
		(start 82.76082 -281.70632)
		(mid 82.945852 -281.752234)
		(end 83.129628 -281.701494)
		(width 0.09525)
		(layer "In4.Cu")
		(net "M_D_CPU1_SB_DQS_DN<6>")
	)
	(arc
		(start 79.345536 -281.543506)
		(mid 79.649233 -281.583693)
		(end 79.932022 -281.701494)
		(width 0.09525)
		(layer "In4.Cu")
		(net "M_D_CPU1_SB_DQS_DN<6>")
	)
	(arc
		(start 89.332562 -281.701494)
		(mid 89.52103 -281.752171)
		(end 89.709498 -281.701494)
		(width 0.09525)
		(layer "In4.Cu")
		(net "M_D_CPU1_SB_DQS_DN<6>")
	)
	(arc
		(start 84.632546 -281.701494)
		(mid 84.821014 -281.752171)
		(end 85.009482 -281.701494)
		(width 0.09525)
		(layer "In4.Cu")
		(net "M_D_CPU1_SB_DQS_DN<6>")
	)
	(arc
		(start 86.5124 -281.701494)
		(mid 86.696175 -281.752266)
		(end 86.881208 -281.70632)
		(width 0.09525)
		(layer "In4.Cu")
		(net "M_D_CPU1_SB_DQS_DN<6>")
	)
	(arc
		(start 91.589606 -281.701494)
		(mid 91.871038 -281.625739)
		(end 92.15247 -281.701494)
		(width 0.09525)
		(layer "In4.Cu")
		(net "M_D_CPU1_SB_DQS_DN<6>")
	)
	(arc
		(start 83.700874 -281.70632)
		(mid 83.885906 -281.752234)
		(end 84.069682 -281.701494)
		(width 0.09525)
		(layer "In4.Cu")
		(net "M_D_CPU1_SB_DQS_DN<6>")
	)
	(arc
		(start 86.88959 -281.701494)
		(mid 87.171022 -281.625739)
		(end 87.452454 -281.701494)
		(width 0.09525)
		(layer "In4.Cu")
		(net "M_D_CPU1_SB_DQS_DN<6>")
	)
	(arc
		(start 90.272362 -281.701494)
		(mid 90.456137 -281.752266)
		(end 90.64117 -281.70632)
		(width 0.09525)
		(layer "In4.Cu")
		(net "M_D_CPU1_SB_DQS_DN<6>")
	)
	(arc
		(start 81.812384 -281.701494)
		(mid 81.996159 -281.752266)
		(end 82.181192 -281.70632)
		(width 0.09525)
		(layer "In4.Cu")
		(net "M_D_CPU1_SB_DQS_DN<6>")
	)
	(arc
		(start 85.572346 -281.701494)
		(mid 85.756121 -281.752266)
		(end 85.941154 -281.70632)
		(width 0.09525)
		(layer "In4.Cu")
		(net "M_D_CPU1_SB_DQS_DN<6>")
	)
	(arc
		(start 85.009482 -281.701494)
		(mid 85.290914 -281.625739)
		(end 85.572346 -281.701494)
		(width 0.09525)
		(layer "In4.Cu")
		(net "M_D_CPU1_SB_DQS_DN<6>")
	)
	(arc
		(start 84.069682 -281.701494)
		(mid 84.351114 -281.625739)
		(end 84.632546 -281.701494)
		(width 0.09525)
		(layer "In4.Cu")
		(net "M_D_CPU1_SB_DQS_DN<6>")
	)
	(arc
		(start 88.40089 -281.70632)
		(mid 88.585922 -281.752234)
		(end 88.769698 -281.701494)
		(width 0.09525)
		(layer "In4.Cu")
		(net "M_D_CPU1_SB_DQS_DN<6>")
	)
	(arc
		(start 87.829644 -281.701494)
		(mid 88.111076 -281.625739)
		(end 88.392508 -281.701494)
		(width 0.09525)
		(layer "In4.Cu")
		(net "M_D_CPU1_SB_DQS_DN<6>")
	)
	(arc
		(start 89.709498 -281.701494)
		(mid 89.99093 -281.625739)
		(end 90.272362 -281.701494)
		(width 0.09525)
		(layer "In4.Cu")
		(net "M_D_CPU1_SB_DQS_DN<6>")
	)
	(arc
		(start 81.24952 -281.701494)
		(mid 81.530952 -281.625739)
		(end 81.812384 -281.701494)
		(width 0.09525)
		(layer "In4.Cu")
		(net "M_D_CPU1_SB_DQS_DN<6>")
	)
	(arc
		(start 85.949536 -281.701494)
		(mid 86.230968 -281.625739)
		(end 86.5124 -281.701494)
		(width 0.09525)
		(layer "In4.Cu")
		(net "M_D_CPU1_SB_DQS_DN<6>")
	)
	(arc
		(start 82.189574 -281.701494)
		(mid 82.471006 -281.625739)
		(end 82.752438 -281.701494)
		(width 0.09525)
		(layer "In4.Cu")
		(net "M_D_CPU1_SB_DQS_DN<6>")
	)
	(arc
		(start 79.932022 -281.701494)
		(mid 80.116051 -281.752393)
		(end 80.301338 -281.70632)
		(width 0.09525)
		(layer "In4.Cu")
		(net "M_D_CPU1_SB_DQS_DN<6>")
	)
	(arc
		(start 80.30972 -281.701494)
		(mid 80.591152 -281.625739)
		(end 80.872584 -281.701494)
		(width 0.09525)
		(layer "In4.Cu")
		(net "M_D_CPU1_SB_DQS_DN<6>")
	)
	(arc
		(start 88.769698 -281.701494)
		(mid 89.05113 -281.625739)
		(end 89.332562 -281.701494)
		(width 0.09525)
		(layer "In4.Cu")
		(net "M_D_CPU1_SB_DQS_DN<6>")
	)
	(arc
		(start 92.160852 -281.70632)
		(mid 92.313747 -281.751148)
		(end 92.471494 -281.728672)
		(width 0.09525)
		(layer "In4.Cu")
		(net "M_D_CPU1_SB_DQS_DN<6>")
	)
	(arc
		(start 90.649552 -281.701494)
		(mid 90.930984 -281.625739)
		(end 91.212416 -281.701494)
		(width 0.09525)
		(layer "In4.Cu")
		(net "M_D_CPU1_SB_DQS_DN<6>")
	)
	(arc
		(start 91.212416 -281.701494)
		(mid 91.396191 -281.752266)
		(end 91.581224 -281.70632)
		(width 0.09525)
		(layer "In4.Cu")
		(net "M_D_CPU1_SB_DQS_DN<6>")
	)
	(arc
		(start 80.872584 -281.701494)
		(mid 81.061052 -281.752171)
		(end 81.24952 -281.701494)
		(width 0.09525)
		(layer "In4.Cu")
		(net "M_D_CPU1_SB_DQS_DN<6>")
	)
	(arc
		(start 87.460836 -281.70632)
		(mid 87.645868 -281.752234)
		(end 87.829644 -281.701494)
		(width 0.09525)
		(layer "In4.Cu")
		(net "M_D_CPU1_SB_DQS_DN<6>")
	)
	(arc
		(start 83.129628 -281.701494)
		(mid 83.41106 -281.625739)
		(end 83.692492 -281.701494)
		(width 0.09525)
		(layer "In4.Cu")
		(net "M_D_CPU1_SB_DQS_DN<6>")
	)
	(segment
		(start 92.80779 -276.2504)
		(end 92.340938 -276.516338)
		(width 0.12954)
		(layer "F.Cu")
		(net "M_D_CPU1_SB_DQS_DN<5>")
	)
	(segment
		(start 40.51681 -287.008316)
		(end 42.102532 -286.351218)
		(width 0.16002)
		(layer "In4.Cu")
		(net "M_D_CPU1_SB_DQS_DN<5>")
	)
	(segment
		(start 88.392508 -276.841458)
		(end 88.40089 -276.846284)
		(width 0.09525)
		(layer "In4.Cu")
		(net "M_D_CPU1_SB_DQS_DN<5>")
	)
	(segment
		(start 86.881208 -276.846284)
		(end 86.88959 -276.841458)
		(width 0.09525)
		(layer "In4.Cu")
		(net "M_D_CPU1_SB_DQS_DN<5>")
	)
	(segment
		(start 42.648886 -285.804864)
		(end 43.302682 -285.804864)
		(width 0.16002)
		(layer "In4.Cu")
		(net "M_D_CPU1_SB_DQS_DN<5>")
	)
	(segment
		(start 51.147472 -286.158178)
		(end 53.103272 -286.158178)
		(width 0.16002)
		(layer "In4.Cu")
		(net "M_D_CPU1_SB_DQS_DN<5>")
	)
	(segment
		(start 82.752438 -276.841458)
		(end 82.76082 -276.846284)
		(width 0.09525)
		(layer "In4.Cu")
		(net "M_D_CPU1_SB_DQS_DN<5>")
	)
	(segment
		(start 75.955906 -276.048724)
		(end 75.979528 -276.048724)
		(width 0.09525)
		(layer "In4.Cu")
		(net "M_D_CPU1_SB_DQS_DN<5>")
	)
	(segment
		(start 76.968604 -276.699726)
		(end 79.405988 -276.699726)
		(width 0.09525)
		(layer "In4.Cu")
		(net "M_D_CPU1_SB_DQS_DN<5>")
	)
	(segment
		(start 42.102532 -286.351218)
		(end 42.648886 -285.804864)
		(width 0.16002)
		(layer "In4.Cu")
		(net "M_D_CPU1_SB_DQS_DN<5>")
	)
	(segment
		(start 76.376784 -276.107906)
		(end 76.968604 -276.699726)
		(width 0.09525)
		(layer "In4.Cu")
		(net "M_D_CPU1_SB_DQS_DN<5>")
	)
	(segment
		(start 80.301338 -276.846284)
		(end 80.30972 -276.841458)
		(width 0.09525)
		(layer "In4.Cu")
		(net "M_D_CPU1_SB_DQS_DN<5>")
	)
	(segment
		(start 91.581224 -276.846284)
		(end 91.589606 -276.841458)
		(width 0.09525)
		(layer "In4.Cu")
		(net "M_D_CPU1_SB_DQS_DN<5>")
	)
	(segment
		(start 75.979528 -276.048724)
		(end 76.03871 -276.107906)
		(width 0.09525)
		(layer "In4.Cu")
		(net "M_D_CPU1_SB_DQS_DN<5>")
	)
	(segment
		(start 45.307504 -286.158178)
		(end 47.360078 -287.008316)
		(width 0.16002)
		(layer "In4.Cu")
		(net "M_D_CPU1_SB_DQS_DN<5>")
	)
	(segment
		(start 90.64117 -276.846284)
		(end 90.649552 -276.841458)
		(width 0.09525)
		(layer "In4.Cu")
		(net "M_D_CPU1_SB_DQS_DN<5>")
	)
	(segment
		(start 60.193682 -285.830264)
		(end 69.975222 -276.048724)
		(width 0.16002)
		(layer "In4.Cu")
		(net "M_D_CPU1_SB_DQS_DN<5>")
	)
	(segment
		(start 33.8582 -286.009334)
		(end 34.97072 -285.779464)
		(width 0.16002)
		(layer "In4.Cu")
		(net "M_D_CPU1_SB_DQS_DN<5>")
	)
	(segment
		(start 76.03871 -276.107906)
		(end 76.376784 -276.107906)
		(width 0.09525)
		(layer "In4.Cu")
		(net "M_D_CPU1_SB_DQS_DN<5>")
	)
	(segment
		(start 38.42893 -286.629856)
		(end 39.939468 -287.008316)
		(width 0.16002)
		(layer "In4.Cu")
		(net "M_D_CPU1_SB_DQS_DN<5>")
	)
	(segment
		(start 49.705006 -286.300672)
		(end 50.175414 -285.830264)
		(width 0.16002)
		(layer "In4.Cu")
		(net "M_D_CPU1_SB_DQS_DN<5>")
	)
	(segment
		(start 53.103272 -286.158178)
		(end 53.575458 -286.630364)
		(width 0.16002)
		(layer "In4.Cu")
		(net "M_D_CPU1_SB_DQS_DN<5>")
	)
	(segment
		(start 69.975222 -276.048724)
		(end 75.955906 -276.048724)
		(width 0.16002)
		(layer "In4.Cu")
		(net "M_D_CPU1_SB_DQS_DN<5>")
	)
	(segment
		(start 47.360078 -287.008316)
		(end 47.996856 -287.008316)
		(width 0.16002)
		(layer "In4.Cu")
		(net "M_D_CPU1_SB_DQS_DN<5>")
	)
	(segment
		(start 82.181192 -276.846284)
		(end 82.189574 -276.841458)
		(width 0.09525)
		(layer "In4.Cu")
		(net "M_D_CPU1_SB_DQS_DN<5>")
	)
	(segment
		(start 83.692492 -276.841458)
		(end 83.700874 -276.846284)
		(width 0.09525)
		(layer "In4.Cu")
		(net "M_D_CPU1_SB_DQS_DN<5>")
	)
	(segment
		(start 92.494862 -276.781768)
		(end 92.340938 -276.516338)
		(width 0.09525)
		(layer "In4.Cu")
		(net "M_D_CPU1_SB_DQS_DN<5>")
	)
	(segment
		(start 47.996856 -287.008316)
		(end 49.705006 -286.300672)
		(width 0.16002)
		(layer "In4.Cu")
		(net "M_D_CPU1_SB_DQS_DN<5>")
	)
	(segment
		(start 87.452454 -276.841458)
		(end 87.460836 -276.846284)
		(width 0.09525)
		(layer "In4.Cu")
		(net "M_D_CPU1_SB_DQS_DN<5>")
	)
	(segment
		(start 92.15247 -276.841458)
		(end 92.160852 -276.846284)
		(width 0.09525)
		(layer "In4.Cu")
		(net "M_D_CPU1_SB_DQS_DN<5>")
	)
	(segment
		(start 32.969962 -286.009334)
		(end 33.8582 -286.009334)
		(width 0.16002)
		(layer "In4.Cu")
		(net "M_D_CPU1_SB_DQS_DN<5>")
	)
	(segment
		(start 38.34384 -286.48787)
		(end 38.42893 -286.629856)
		(width 0.16002)
		(layer "In4.Cu")
		(net "M_D_CPU1_SB_DQS_DN<5>")
	)
	(segment
		(start 92.471494 -276.868636)
		(end 92.494862 -276.781768)
		(width 0.09525)
		(layer "In4.Cu")
		(net "M_D_CPU1_SB_DQS_DN<5>")
	)
	(segment
		(start 53.575458 -286.630364)
		(end 56.910986 -286.630364)
		(width 0.16002)
		(layer "In4.Cu")
		(net "M_D_CPU1_SB_DQS_DN<5>")
	)
	(segment
		(start 35.681158 -285.779464)
		(end 36.672012 -286.189674)
		(width 0.16002)
		(layer "In4.Cu")
		(net "M_D_CPU1_SB_DQS_DN<5>")
	)
	(segment
		(start 34.97072 -285.779464)
		(end 35.681158 -285.779464)
		(width 0.16002)
		(layer "In4.Cu")
		(net "M_D_CPU1_SB_DQS_DN<5>")
	)
	(segment
		(start 50.175414 -285.830264)
		(end 50.819558 -285.830264)
		(width 0.16002)
		(layer "In4.Cu")
		(net "M_D_CPU1_SB_DQS_DN<5>")
	)
	(segment
		(start 43.302682 -285.804864)
		(end 44.10583 -286.158178)
		(width 0.16002)
		(layer "In4.Cu")
		(net "M_D_CPU1_SB_DQS_DN<5>")
	)
	(segment
		(start 50.819558 -285.830264)
		(end 51.147472 -286.158178)
		(width 0.16002)
		(layer "In4.Cu")
		(net "M_D_CPU1_SB_DQS_DN<5>")
	)
	(segment
		(start 37.878004 -286.371284)
		(end 38.34384 -286.48787)
		(width 0.16002)
		(layer "In4.Cu")
		(net "M_D_CPU1_SB_DQS_DN<5>")
	)
	(segment
		(start 57.711086 -285.830264)
		(end 60.193682 -285.830264)
		(width 0.16002)
		(layer "In4.Cu")
		(net "M_D_CPU1_SB_DQS_DN<5>")
	)
	(segment
		(start 32.695896 -285.735268)
		(end 32.969962 -286.009334)
		(width 0.16002)
		(layer "In4.Cu")
		(net "M_D_CPU1_SB_DQS_DN<5>")
	)
	(segment
		(start 56.910986 -286.630364)
		(end 57.711086 -285.830264)
		(width 0.16002)
		(layer "In4.Cu")
		(net "M_D_CPU1_SB_DQS_DN<5>")
	)
	(segment
		(start 39.939468 -287.008316)
		(end 40.51681 -287.008316)
		(width 0.16002)
		(layer "In4.Cu")
		(net "M_D_CPU1_SB_DQS_DN<5>")
	)
	(segment
		(start 44.10583 -286.158178)
		(end 45.307504 -286.158178)
		(width 0.16002)
		(layer "In4.Cu")
		(net "M_D_CPU1_SB_DQS_DN<5>")
	)
	(segment
		(start 85.941154 -276.846284)
		(end 85.949536 -276.841458)
		(width 0.09525)
		(layer "In4.Cu")
		(net "M_D_CPU1_SB_DQS_DN<5>")
	)
	(segment
		(start 36.672012 -286.189674)
		(end 37.736272 -286.45612)
		(width 0.16002)
		(layer "In4.Cu")
		(net "M_D_CPU1_SB_DQS_DN<5>")
	)
	(segment
		(start 37.736272 -286.45612)
		(end 37.878004 -286.371284)
		(width 0.16002)
		(layer "In4.Cu")
		(net "M_D_CPU1_SB_DQS_DN<5>")
	)
	(arc
		(start 84.069682 -276.841458)
		(mid 84.351114 -276.765703)
		(end 84.632546 -276.841458)
		(width 0.09525)
		(layer "In4.Cu")
		(net "M_D_CPU1_SB_DQS_DN<5>")
	)
	(arc
		(start 90.662506 -276.834346)
		(mid 90.938406 -276.765784)
		(end 91.212416 -276.841458)
		(width 0.09525)
		(layer "In4.Cu")
		(net "M_D_CPU1_SB_DQS_DN<5>")
	)
	(arc
		(start 88.40089 -276.846284)
		(mid 88.585922 -276.892198)
		(end 88.769698 -276.841458)
		(width 0.09525)
		(layer "In4.Cu")
		(net "M_D_CPU1_SB_DQS_DN<5>")
	)
	(arc
		(start 92.160852 -276.846284)
		(mid 92.313747 -276.891112)
		(end 92.471494 -276.868636)
		(width 0.09525)
		(layer "In4.Cu")
		(net "M_D_CPU1_SB_DQS_DN<5>")
	)
	(arc
		(start 79.932022 -276.841458)
		(mid 80.116051 -276.892357)
		(end 80.301338 -276.846284)
		(width 0.09525)
		(layer "In4.Cu")
		(net "M_D_CPU1_SB_DQS_DN<5>")
	)
	(arc
		(start 80.872584 -276.841458)
		(mid 81.061052 -276.892135)
		(end 81.24952 -276.841458)
		(width 0.09525)
		(layer "In4.Cu")
		(net "M_D_CPU1_SB_DQS_DN<5>")
	)
	(arc
		(start 90.272362 -276.841458)
		(mid 90.456137 -276.89223)
		(end 90.64117 -276.846284)
		(width 0.09525)
		(layer "In4.Cu")
		(net "M_D_CPU1_SB_DQS_DN<5>")
	)
	(arc
		(start 86.88959 -276.841458)
		(mid 87.171022 -276.765703)
		(end 87.452454 -276.841458)
		(width 0.09525)
		(layer "In4.Cu")
		(net "M_D_CPU1_SB_DQS_DN<5>")
	)
	(arc
		(start 86.5124 -276.841458)
		(mid 86.696175 -276.89223)
		(end 86.881208 -276.846284)
		(width 0.09525)
		(layer "In4.Cu")
		(net "M_D_CPU1_SB_DQS_DN<5>")
	)
	(arc
		(start 83.700874 -276.846284)
		(mid 83.885906 -276.892198)
		(end 84.069682 -276.841458)
		(width 0.09525)
		(layer "In4.Cu")
		(net "M_D_CPU1_SB_DQS_DN<5>")
	)
	(arc
		(start 81.262474 -276.834346)
		(mid 81.538374 -276.765784)
		(end 81.812384 -276.841458)
		(width 0.09525)
		(layer "In4.Cu")
		(net "M_D_CPU1_SB_DQS_DN<5>")
	)
	(arc
		(start 88.769698 -276.841458)
		(mid 89.05113 -276.765703)
		(end 89.332562 -276.841458)
		(width 0.09525)
		(layer "In4.Cu")
		(net "M_D_CPU1_SB_DQS_DN<5>")
	)
	(arc
		(start 91.589606 -276.841458)
		(mid 91.871038 -276.765703)
		(end 92.15247 -276.841458)
		(width 0.09525)
		(layer "In4.Cu")
		(net "M_D_CPU1_SB_DQS_DN<5>")
	)
	(arc
		(start 81.812384 -276.841458)
		(mid 81.996159 -276.89223)
		(end 82.181192 -276.846284)
		(width 0.09525)
		(layer "In4.Cu")
		(net "M_D_CPU1_SB_DQS_DN<5>")
	)
	(arc
		(start 80.30972 -276.841458)
		(mid 80.591152 -276.765703)
		(end 80.872584 -276.841458)
		(width 0.09525)
		(layer "In4.Cu")
		(net "M_D_CPU1_SB_DQS_DN<5>")
	)
	(arc
		(start 89.709498 -276.841458)
		(mid 89.715826 -276.837862)
		(end 89.722198 -276.834346)
		(width 0.09525)
		(layer "In4.Cu")
		(net "M_D_CPU1_SB_DQS_DN<5>")
	)
	(arc
		(start 82.76082 -276.846284)
		(mid 82.945852 -276.892198)
		(end 83.129628 -276.841458)
		(width 0.09525)
		(layer "In4.Cu")
		(net "M_D_CPU1_SB_DQS_DN<5>")
	)
	(arc
		(start 89.332562 -276.841458)
		(mid 89.52103 -276.892135)
		(end 89.709498 -276.841458)
		(width 0.09525)
		(layer "In4.Cu")
		(net "M_D_CPU1_SB_DQS_DN<5>")
	)
	(arc
		(start 89.722198 -276.834346)
		(mid 89.998208 -276.765785)
		(end 90.272362 -276.841458)
		(width 0.09525)
		(layer "In4.Cu")
		(net "M_D_CPU1_SB_DQS_DN<5>")
	)
	(arc
		(start 85.022182 -276.834346)
		(mid 85.298192 -276.765785)
		(end 85.572346 -276.841458)
		(width 0.09525)
		(layer "In4.Cu")
		(net "M_D_CPU1_SB_DQS_DN<5>")
	)
	(arc
		(start 87.829644 -276.841458)
		(mid 88.111076 -276.765703)
		(end 88.392508 -276.841458)
		(width 0.09525)
		(layer "In4.Cu")
		(net "M_D_CPU1_SB_DQS_DN<5>")
	)
	(arc
		(start 81.24952 -276.841458)
		(mid 81.255973 -276.837858)
		(end 81.262474 -276.834346)
		(width 0.09525)
		(layer "In4.Cu")
		(net "M_D_CPU1_SB_DQS_DN<5>")
	)
	(arc
		(start 85.572346 -276.841458)
		(mid 85.756121 -276.89223)
		(end 85.941154 -276.846284)
		(width 0.09525)
		(layer "In4.Cu")
		(net "M_D_CPU1_SB_DQS_DN<5>")
	)
	(arc
		(start 79.405988 -276.699726)
		(mid 79.678367 -276.735827)
		(end 79.932022 -276.841458)
		(width 0.09525)
		(layer "In4.Cu")
		(net "M_D_CPU1_SB_DQS_DN<5>")
	)
	(arc
		(start 87.460836 -276.846284)
		(mid 87.645868 -276.892198)
		(end 87.829644 -276.841458)
		(width 0.09525)
		(layer "In4.Cu")
		(net "M_D_CPU1_SB_DQS_DN<5>")
	)
	(arc
		(start 85.96249 -276.834346)
		(mid 86.23839 -276.765784)
		(end 86.5124 -276.841458)
		(width 0.09525)
		(layer "In4.Cu")
		(net "M_D_CPU1_SB_DQS_DN<5>")
	)
	(arc
		(start 91.212416 -276.841458)
		(mid 91.396191 -276.89223)
		(end 91.581224 -276.846284)
		(width 0.09525)
		(layer "In4.Cu")
		(net "M_D_CPU1_SB_DQS_DN<5>")
	)
	(arc
		(start 84.632546 -276.841458)
		(mid 84.821014 -276.892135)
		(end 85.009482 -276.841458)
		(width 0.09525)
		(layer "In4.Cu")
		(net "M_D_CPU1_SB_DQS_DN<5>")
	)
	(arc
		(start 83.129628 -276.841458)
		(mid 83.41106 -276.765703)
		(end 83.692492 -276.841458)
		(width 0.09525)
		(layer "In4.Cu")
		(net "M_D_CPU1_SB_DQS_DN<5>")
	)
	(arc
		(start 85.009482 -276.841458)
		(mid 85.01581 -276.837862)
		(end 85.022182 -276.834346)
		(width 0.09525)
		(layer "In4.Cu")
		(net "M_D_CPU1_SB_DQS_DN<5>")
	)
	(arc
		(start 90.649552 -276.841458)
		(mid 90.656005 -276.837858)
		(end 90.662506 -276.834346)
		(width 0.09525)
		(layer "In4.Cu")
		(net "M_D_CPU1_SB_DQS_DN<5>")
	)
	(arc
		(start 82.189574 -276.841458)
		(mid 82.471006 -276.765703)
		(end 82.752438 -276.841458)
		(width 0.09525)
		(layer "In4.Cu")
		(net "M_D_CPU1_SB_DQS_DN<5>")
	)
	(arc
		(start 85.949536 -276.841458)
		(mid 85.955989 -276.837858)
		(end 85.96249 -276.834346)
		(width 0.09525)
		(layer "In4.Cu")
		(net "M_D_CPU1_SB_DQS_DN<5>")
	)
	(segment
		(start 92.80779 -271.390364)
		(end 92.340938 -271.656302)
		(width 0.12954)
		(layer "F.Cu")
		(net "M_D_CPU1_SB_DQS_DN<4>")
	)
	(segment
		(start 82.181192 -271.986248)
		(end 82.189574 -271.981422)
		(width 0.09525)
		(layer "In4.Cu")
		(net "M_D_CPU1_SB_DQS_DN<4>")
	)
	(segment
		(start 51.127406 -276.808184)
		(end 53.464206 -276.808184)
		(width 0.16002)
		(layer "In4.Cu")
		(net "M_D_CPU1_SB_DQS_DN<4>")
	)
	(segment
		(start 33.8582 -276.65934)
		(end 34.073338 -276.444202)
		(width 0.16002)
		(layer "In4.Cu")
		(net "M_D_CPU1_SB_DQS_DN<4>")
	)
	(segment
		(start 39.55796 -277.658322)
		(end 40.991028 -277.658322)
		(width 0.16002)
		(layer "In4.Cu")
		(net "M_D_CPU1_SB_DQS_DN<4>")
	)
	(segment
		(start 50.738786 -276.419564)
		(end 51.127406 -276.808184)
		(width 0.16002)
		(layer "In4.Cu")
		(net "M_D_CPU1_SB_DQS_DN<4>")
	)
	(segment
		(start 41.793414 -277.321264)
		(end 42.631614 -276.483064)
		(width 0.16002)
		(layer "In4.Cu")
		(net "M_D_CPU1_SB_DQS_DN<4>")
	)
	(segment
		(start 76.50353 -270.695166)
		(end 77.37221 -270.695166)
		(width 0.09525)
		(layer "In4.Cu")
		(net "M_D_CPU1_SB_DQS_DN<4>")
	)
	(segment
		(start 77.37221 -270.695166)
		(end 78.58252 -271.905476)
		(width 0.09525)
		(layer "In4.Cu")
		(net "M_D_CPU1_SB_DQS_DN<4>")
	)
	(segment
		(start 38.086284 -277.658322)
		(end 38.84422 -277.658322)
		(width 0.16002)
		(layer "In4.Cu")
		(net "M_D_CPU1_SB_DQS_DN<4>")
	)
	(segment
		(start 50.213514 -276.419564)
		(end 50.738786 -276.419564)
		(width 0.16002)
		(layer "In4.Cu")
		(net "M_D_CPU1_SB_DQS_DN<4>")
	)
	(segment
		(start 43.275758 -276.483064)
		(end 43.600878 -276.808184)
		(width 0.16002)
		(layer "In4.Cu")
		(net "M_D_CPU1_SB_DQS_DN<4>")
	)
	(segment
		(start 82.752438 -271.981422)
		(end 82.76082 -271.986248)
		(width 0.09525)
		(layer "In4.Cu")
		(net "M_D_CPU1_SB_DQS_DN<4>")
	)
	(segment
		(start 75.955906 -270.425164)
		(end 75.979528 -270.425164)
		(width 0.09525)
		(layer "In4.Cu")
		(net "M_D_CPU1_SB_DQS_DN<4>")
	)
	(segment
		(start 48.539146 -277.658322)
		(end 49.121568 -277.0759)
		(width 0.16002)
		(layer "In4.Cu")
		(net "M_D_CPU1_SB_DQS_DN<4>")
	)
	(segment
		(start 41.328086 -277.321264)
		(end 41.793414 -277.321264)
		(width 0.16002)
		(layer "In4.Cu")
		(net "M_D_CPU1_SB_DQS_DN<4>")
	)
	(segment
		(start 39.44112 -277.541482)
		(end 39.55796 -277.658322)
		(width 0.16002)
		(layer "In4.Cu")
		(net "M_D_CPU1_SB_DQS_DN<4>")
	)
	(segment
		(start 83.692492 -271.981422)
		(end 83.700874 -271.986248)
		(width 0.09525)
		(layer "In4.Cu")
		(net "M_D_CPU1_SB_DQS_DN<4>")
	)
	(segment
		(start 92.494862 -271.921732)
		(end 92.340938 -271.656302)
		(width 0.09525)
		(layer "In4.Cu")
		(net "M_D_CPU1_SB_DQS_DN<4>")
	)
	(segment
		(start 92.471494 -272.0086)
		(end 92.494862 -271.921732)
		(width 0.09525)
		(layer "In4.Cu")
		(net "M_D_CPU1_SB_DQS_DN<4>")
	)
	(segment
		(start 85.941154 -271.986248)
		(end 85.949536 -271.981422)
		(width 0.09525)
		(layer "In4.Cu")
		(net "M_D_CPU1_SB_DQS_DN<4>")
	)
	(segment
		(start 53.464206 -276.808184)
		(end 53.939186 -277.283164)
		(width 0.16002)
		(layer "In4.Cu")
		(net "M_D_CPU1_SB_DQS_DN<4>")
	)
	(segment
		(start 53.939186 -277.283164)
		(end 56.919114 -277.283164)
		(width 0.16002)
		(layer "In4.Cu")
		(net "M_D_CPU1_SB_DQS_DN<4>")
	)
	(segment
		(start 91.581224 -271.986248)
		(end 91.589606 -271.981422)
		(width 0.09525)
		(layer "In4.Cu")
		(net "M_D_CPU1_SB_DQS_DN<4>")
	)
	(segment
		(start 76.29271 -270.484346)
		(end 76.50353 -270.695166)
		(width 0.09525)
		(layer "In4.Cu")
		(net "M_D_CPU1_SB_DQS_DN<4>")
	)
	(segment
		(start 34.073338 -276.444202)
		(end 35.693096 -276.444202)
		(width 0.16002)
		(layer "In4.Cu")
		(net "M_D_CPU1_SB_DQS_DN<4>")
	)
	(segment
		(start 78.58252 -271.905476)
		(end 79.650082 -271.905476)
		(width 0.09525)
		(layer "In4.Cu")
		(net "M_D_CPU1_SB_DQS_DN<4>")
	)
	(segment
		(start 38.96106 -277.541482)
		(end 39.44112 -277.541482)
		(width 0.16002)
		(layer "In4.Cu")
		(net "M_D_CPU1_SB_DQS_DN<4>")
	)
	(segment
		(start 32.695896 -276.385274)
		(end 32.969962 -276.65934)
		(width 0.16002)
		(layer "In4.Cu")
		(net "M_D_CPU1_SB_DQS_DN<4>")
	)
	(segment
		(start 80.301338 -271.986248)
		(end 80.30972 -271.981422)
		(width 0.09525)
		(layer "In4.Cu")
		(net "M_D_CPU1_SB_DQS_DN<4>")
	)
	(segment
		(start 45.710856 -276.808184)
		(end 46.560994 -277.658322)
		(width 0.16002)
		(layer "In4.Cu")
		(net "M_D_CPU1_SB_DQS_DN<4>")
	)
	(segment
		(start 87.452454 -271.981422)
		(end 87.460836 -271.986248)
		(width 0.09525)
		(layer "In4.Cu")
		(net "M_D_CPU1_SB_DQS_DN<4>")
	)
	(segment
		(start 49.557178 -277.0759)
		(end 50.213514 -276.419564)
		(width 0.16002)
		(layer "In4.Cu")
		(net "M_D_CPU1_SB_DQS_DN<4>")
	)
	(segment
		(start 40.991028 -277.658322)
		(end 41.328086 -277.321264)
		(width 0.16002)
		(layer "In4.Cu")
		(net "M_D_CPU1_SB_DQS_DN<4>")
	)
	(segment
		(start 65.709292 -270.425164)
		(end 75.955906 -270.425164)
		(width 0.16002)
		(layer "In4.Cu")
		(net "M_D_CPU1_SB_DQS_DN<4>")
	)
	(segment
		(start 57.731914 -276.470364)
		(end 59.664092 -276.470364)
		(width 0.16002)
		(layer "In4.Cu")
		(net "M_D_CPU1_SB_DQS_DN<4>")
	)
	(segment
		(start 86.881208 -271.986248)
		(end 86.88959 -271.981422)
		(width 0.09525)
		(layer "In4.Cu")
		(net "M_D_CPU1_SB_DQS_DN<4>")
	)
	(segment
		(start 35.693096 -276.444202)
		(end 36.073588 -276.824694)
		(width 0.16002)
		(layer "In4.Cu")
		(net "M_D_CPU1_SB_DQS_DN<4>")
	)
	(segment
		(start 38.84422 -277.658322)
		(end 38.96106 -277.541482)
		(width 0.16002)
		(layer "In4.Cu")
		(net "M_D_CPU1_SB_DQS_DN<4>")
	)
	(segment
		(start 49.121568 -277.0759)
		(end 49.557178 -277.0759)
		(width 0.16002)
		(layer "In4.Cu")
		(net "M_D_CPU1_SB_DQS_DN<4>")
	)
	(segment
		(start 42.631614 -276.483064)
		(end 43.275758 -276.483064)
		(width 0.16002)
		(layer "In4.Cu")
		(net "M_D_CPU1_SB_DQS_DN<4>")
	)
	(segment
		(start 90.64117 -271.986248)
		(end 90.649552 -271.981422)
		(width 0.09525)
		(layer "In4.Cu")
		(net "M_D_CPU1_SB_DQS_DN<4>")
	)
	(segment
		(start 92.15247 -271.981422)
		(end 92.160852 -271.986248)
		(width 0.09525)
		(layer "In4.Cu")
		(net "M_D_CPU1_SB_DQS_DN<4>")
	)
	(segment
		(start 43.600878 -276.808184)
		(end 45.710856 -276.808184)
		(width 0.16002)
		(layer "In4.Cu")
		(net "M_D_CPU1_SB_DQS_DN<4>")
	)
	(segment
		(start 46.560994 -277.658322)
		(end 48.539146 -277.658322)
		(width 0.16002)
		(layer "In4.Cu")
		(net "M_D_CPU1_SB_DQS_DN<4>")
	)
	(segment
		(start 59.664092 -276.470364)
		(end 65.709292 -270.425164)
		(width 0.16002)
		(layer "In4.Cu")
		(net "M_D_CPU1_SB_DQS_DN<4>")
	)
	(segment
		(start 75.979528 -270.425164)
		(end 76.03871 -270.484346)
		(width 0.09525)
		(layer "In4.Cu")
		(net "M_D_CPU1_SB_DQS_DN<4>")
	)
	(segment
		(start 32.969962 -276.65934)
		(end 33.8582 -276.65934)
		(width 0.16002)
		(layer "In4.Cu")
		(net "M_D_CPU1_SB_DQS_DN<4>")
	)
	(segment
		(start 88.392508 -271.981422)
		(end 88.40089 -271.986248)
		(width 0.09525)
		(layer "In4.Cu")
		(net "M_D_CPU1_SB_DQS_DN<4>")
	)
	(segment
		(start 76.03871 -270.484346)
		(end 76.29271 -270.484346)
		(width 0.09525)
		(layer "In4.Cu")
		(net "M_D_CPU1_SB_DQS_DN<4>")
	)
	(segment
		(start 36.073588 -276.824694)
		(end 38.086284 -277.658322)
		(width 0.16002)
		(layer "In4.Cu")
		(net "M_D_CPU1_SB_DQS_DN<4>")
	)
	(segment
		(start 56.919114 -277.283164)
		(end 57.731914 -276.470364)
		(width 0.16002)
		(layer "In4.Cu")
		(net "M_D_CPU1_SB_DQS_DN<4>")
	)
	(arc
		(start 81.812384 -271.981422)
		(mid 81.996159 -272.032194)
		(end 82.181192 -271.986248)
		(width 0.09525)
		(layer "In4.Cu")
		(net "M_D_CPU1_SB_DQS_DN<4>")
	)
	(arc
		(start 85.949536 -271.981422)
		(mid 86.230968 -271.905667)
		(end 86.5124 -271.981422)
		(width 0.09525)
		(layer "In4.Cu")
		(net "M_D_CPU1_SB_DQS_DN<4>")
	)
	(arc
		(start 92.160852 -271.986248)
		(mid 92.313747 -272.031076)
		(end 92.471494 -272.0086)
		(width 0.09525)
		(layer "In4.Cu")
		(net "M_D_CPU1_SB_DQS_DN<4>")
	)
	(arc
		(start 86.88959 -271.981422)
		(mid 87.171022 -271.905667)
		(end 87.452454 -271.981422)
		(width 0.09525)
		(layer "In4.Cu")
		(net "M_D_CPU1_SB_DQS_DN<4>")
	)
	(arc
		(start 90.272362 -271.981422)
		(mid 90.456137 -272.032194)
		(end 90.64117 -271.986248)
		(width 0.09525)
		(layer "In4.Cu")
		(net "M_D_CPU1_SB_DQS_DN<4>")
	)
	(arc
		(start 80.30972 -271.981422)
		(mid 80.591152 -271.905667)
		(end 80.872584 -271.981422)
		(width 0.09525)
		(layer "In4.Cu")
		(net "M_D_CPU1_SB_DQS_DN<4>")
	)
	(arc
		(start 81.24952 -271.981422)
		(mid 81.530952 -271.905667)
		(end 81.812384 -271.981422)
		(width 0.09525)
		(layer "In4.Cu")
		(net "M_D_CPU1_SB_DQS_DN<4>")
	)
	(arc
		(start 87.460836 -271.986248)
		(mid 87.645868 -272.032162)
		(end 87.829644 -271.981422)
		(width 0.09525)
		(layer "In4.Cu")
		(net "M_D_CPU1_SB_DQS_DN<4>")
	)
	(arc
		(start 85.572346 -271.981422)
		(mid 85.756121 -272.032194)
		(end 85.941154 -271.986248)
		(width 0.09525)
		(layer "In4.Cu")
		(net "M_D_CPU1_SB_DQS_DN<4>")
	)
	(arc
		(start 91.589606 -271.981422)
		(mid 91.871038 -271.905667)
		(end 92.15247 -271.981422)
		(width 0.09525)
		(layer "In4.Cu")
		(net "M_D_CPU1_SB_DQS_DN<4>")
	)
	(arc
		(start 82.76082 -271.986248)
		(mid 82.945852 -272.032162)
		(end 83.129628 -271.981422)
		(width 0.09525)
		(layer "In4.Cu")
		(net "M_D_CPU1_SB_DQS_DN<4>")
	)
	(arc
		(start 83.700874 -271.986248)
		(mid 83.885906 -272.032162)
		(end 84.069682 -271.981422)
		(width 0.09525)
		(layer "In4.Cu")
		(net "M_D_CPU1_SB_DQS_DN<4>")
	)
	(arc
		(start 85.009482 -271.981422)
		(mid 85.290914 -271.905667)
		(end 85.572346 -271.981422)
		(width 0.09525)
		(layer "In4.Cu")
		(net "M_D_CPU1_SB_DQS_DN<4>")
	)
	(arc
		(start 79.932022 -271.981422)
		(mid 80.116051 -272.032321)
		(end 80.301338 -271.986248)
		(width 0.09525)
		(layer "In4.Cu")
		(net "M_D_CPU1_SB_DQS_DN<4>")
	)
	(arc
		(start 86.5124 -271.981422)
		(mid 86.696175 -272.032194)
		(end 86.881208 -271.986248)
		(width 0.09525)
		(layer "In4.Cu")
		(net "M_D_CPU1_SB_DQS_DN<4>")
	)
	(arc
		(start 88.40089 -271.986248)
		(mid 88.585922 -272.032162)
		(end 88.769698 -271.981422)
		(width 0.09525)
		(layer "In4.Cu")
		(net "M_D_CPU1_SB_DQS_DN<4>")
	)
	(arc
		(start 80.872584 -271.981422)
		(mid 81.061052 -272.032099)
		(end 81.24952 -271.981422)
		(width 0.09525)
		(layer "In4.Cu")
		(net "M_D_CPU1_SB_DQS_DN<4>")
	)
	(arc
		(start 79.650082 -271.905476)
		(mid 79.796077 -271.924794)
		(end 79.932022 -271.981422)
		(width 0.09525)
		(layer "In4.Cu")
		(net "M_D_CPU1_SB_DQS_DN<4>")
	)
	(arc
		(start 83.129628 -271.981422)
		(mid 83.41106 -271.905667)
		(end 83.692492 -271.981422)
		(width 0.09525)
		(layer "In4.Cu")
		(net "M_D_CPU1_SB_DQS_DN<4>")
	)
	(arc
		(start 89.709498 -271.981422)
		(mid 89.99093 -271.905667)
		(end 90.272362 -271.981422)
		(width 0.09525)
		(layer "In4.Cu")
		(net "M_D_CPU1_SB_DQS_DN<4>")
	)
	(arc
		(start 84.069682 -271.981422)
		(mid 84.351114 -271.905667)
		(end 84.632546 -271.981422)
		(width 0.09525)
		(layer "In4.Cu")
		(net "M_D_CPU1_SB_DQS_DN<4>")
	)
	(arc
		(start 82.189574 -271.981422)
		(mid 82.471006 -271.905667)
		(end 82.752438 -271.981422)
		(width 0.09525)
		(layer "In4.Cu")
		(net "M_D_CPU1_SB_DQS_DN<4>")
	)
	(arc
		(start 84.632546 -271.981422)
		(mid 84.821014 -272.032099)
		(end 85.009482 -271.981422)
		(width 0.09525)
		(layer "In4.Cu")
		(net "M_D_CPU1_SB_DQS_DN<4>")
	)
	(arc
		(start 88.769698 -271.981422)
		(mid 89.05113 -271.905667)
		(end 89.332562 -271.981422)
		(width 0.09525)
		(layer "In4.Cu")
		(net "M_D_CPU1_SB_DQS_DN<4>")
	)
	(arc
		(start 91.212416 -271.981422)
		(mid 91.396191 -272.032194)
		(end 91.581224 -271.986248)
		(width 0.09525)
		(layer "In4.Cu")
		(net "M_D_CPU1_SB_DQS_DN<4>")
	)
	(arc
		(start 87.829644 -271.981422)
		(mid 88.111076 -271.905667)
		(end 88.392508 -271.981422)
		(width 0.09525)
		(layer "In4.Cu")
		(net "M_D_CPU1_SB_DQS_DN<4>")
	)
	(arc
		(start 90.649552 -271.981422)
		(mid 90.930984 -271.905667)
		(end 91.212416 -271.981422)
		(width 0.09525)
		(layer "In4.Cu")
		(net "M_D_CPU1_SB_DQS_DN<4>")
	)
	(arc
		(start 89.332562 -271.981422)
		(mid 89.52103 -272.032099)
		(end 89.709498 -271.981422)
		(width 0.09525)
		(layer "In4.Cu")
		(net "M_D_CPU1_SB_DQS_DN<4>")
	)
	(segment
		(start 91.86799 -290.830254)
		(end 91.401138 -291.096192)
		(width 0.12954)
		(layer "F.Cu")
		(net "M_D_CPU1_SB_DQS_DN<3>")
	)
	(segment
		(start 49.479708 -313.674506)
		(end 50.241708 -312.912506)
		(width 0.16002)
		(layer "In4.Cu")
		(net "M_D_CPU1_SB_DQS_DN<3>")
	)
	(segment
		(start 50.724308 -312.912506)
		(end 51.124358 -312.512456)
		(width 0.16002)
		(layer "In4.Cu")
		(net "M_D_CPU1_SB_DQS_DN<3>")
	)
	(segment
		(start 40.79748 -313.36234)
		(end 41.113964 -313.678824)
		(width 0.16002)
		(layer "In4.Cu")
		(net "M_D_CPU1_SB_DQS_DN<3>")
	)
	(segment
		(start 67.065144 -306.785264)
		(end 67.438778 -306.41163)
		(width 0.16002)
		(layer "In4.Cu")
		(net "M_D_CPU1_SB_DQS_DN<3>")
	)
	(segment
		(start 55.47995 -312.993024)
		(end 56.095138 -313.607958)
		(width 0.16002)
		(layer "In4.Cu")
		(net "M_D_CPU1_SB_DQS_DN<3>")
	)
	(segment
		(start 36.795964 -313.78525)
		(end 37.069776 -313.511438)
		(width 0.16002)
		(layer "In4.Cu")
		(net "M_D_CPU1_SB_DQS_DN<3>")
	)
	(segment
		(start 63.40729 -309.425848)
		(end 63.683896 -309.425848)
		(width 0.16002)
		(layer "In4.Cu")
		(net "M_D_CPU1_SB_DQS_DN<3>")
	)
	(segment
		(start 69.178424 -303.93132)
		(end 69.285104 -304.038)
		(width 0.16002)
		(layer "In4.Cu")
		(net "M_D_CPU1_SB_DQS_DN<3>")
	)
	(segment
		(start 76.363068 -295.195752)
		(end 76.62164 -294.936926)
		(width 0.09525)
		(layer "In4.Cu")
		(net "M_D_CPU1_SB_DQS_DN<3>")
	)
	(segment
		(start 60.660026 -312.173112)
		(end 60.936632 -312.173112)
		(width 0.16002)
		(layer "In4.Cu")
		(net "M_D_CPU1_SB_DQS_DN<3>")
	)
	(segment
		(start 52.105814 -312.512456)
		(end 53.280564 -313.687206)
		(width 0.16002)
		(layer "In4.Cu")
		(net "M_D_CPU1_SB_DQS_DN<3>")
	)
	(segment
		(start 87.452454 -290.771072)
		(end 87.460836 -290.766246)
		(width 0.09525)
		(layer "In4.Cu")
		(net "M_D_CPU1_SB_DQS_DN<3>")
	)
	(segment
		(start 76.821538 -293.822882)
		(end 77.274928 -293.369492)
		(width 0.09525)
		(layer "In4.Cu")
		(net "M_D_CPU1_SB_DQS_DN<3>")
	)
	(segment
		(start 91.247214 -290.830762)
		(end 91.401138 -291.096192)
		(width 0.09525)
		(layer "In4.Cu")
		(net "M_D_CPU1_SB_DQS_DN<3>")
	)
	(segment
		(start 65.057528 -308.052216)
		(end 65.164208 -308.158896)
		(width 0.16002)
		(layer "In4.Cu")
		(net "M_D_CPU1_SB_DQS_DN<3>")
	)
	(segment
		(start 57.010808 -313.687206)
		(end 57.874408 -312.823606)
		(width 0.16002)
		(layer "In4.Cu")
		(net "M_D_CPU1_SB_DQS_DN<3>")
	)
	(segment
		(start 62.033658 -310.79948)
		(end 62.310264 -310.79948)
		(width 0.16002)
		(layer "In4.Cu")
		(net "M_D_CPU1_SB_DQS_DN<3>")
	)
	(segment
		(start 65.164208 -308.158896)
		(end 65.691512 -308.158896)
		(width 0.16002)
		(layer "In4.Cu")
		(net "M_D_CPU1_SB_DQS_DN<3>")
	)
	(segment
		(start 68.438776 -305.411632)
		(end 68.81241 -305.037998)
		(width 0.16002)
		(layer "In4.Cu")
		(net "M_D_CPU1_SB_DQS_DN<3>")
	)
	(segment
		(start 37.069776 -313.511438)
		(end 39.319454 -313.511438)
		(width 0.16002)
		(layer "In4.Cu")
		(net "M_D_CPU1_SB_DQS_DN<3>")
	)
	(segment
		(start 63.211456 -309.898542)
		(end 63.211456 -309.621682)
		(width 0.16002)
		(layer "In4.Cu")
		(net "M_D_CPU1_SB_DQS_DN<3>")
	)
	(segment
		(start 67.439032 -305.884326)
		(end 67.332352 -305.777646)
		(width 0.16002)
		(layer "In4.Cu")
		(net "M_D_CPU1_SB_DQS_DN<3>")
	)
	(segment
		(start 64.691514 -309.158894)
		(end 64.691768 -308.63159)
		(width 0.16002)
		(layer "In4.Cu")
		(net "M_D_CPU1_SB_DQS_DN<3>")
	)
	(segment
		(start 82.752438 -290.771072)
		(end 82.76082 -290.766246)
		(width 0.09525)
		(layer "In4.Cu")
		(net "M_D_CPU1_SB_DQS_DN<3>")
	)
	(segment
		(start 42.761408 -312.840624)
		(end 43.244008 -312.840624)
		(width 0.16002)
		(layer "In4.Cu")
		(net "M_D_CPU1_SB_DQS_DN<3>")
	)
	(segment
		(start 67.911472 -305.411632)
		(end 68.438776 -305.411632)
		(width 0.16002)
		(layer "In4.Cu")
		(net "M_D_CPU1_SB_DQS_DN<3>")
	)
	(segment
		(start 90.64117 -290.766246)
		(end 90.649552 -290.771072)
		(width 0.09525)
		(layer "In4.Cu")
		(net "M_D_CPU1_SB_DQS_DN<3>")
	)
	(segment
		(start 67.332352 -305.777646)
		(end 67.332352 -305.500786)
		(width 0.16002)
		(layer "In4.Cu")
		(net "M_D_CPU1_SB_DQS_DN<3>")
	)
	(segment
		(start 60.936632 -312.173112)
		(end 61.043312 -312.279792)
		(width 0.16002)
		(layer "In4.Cu")
		(net "M_D_CPU1_SB_DQS_DN<3>")
	)
	(segment
		(start 61.94425 -311.906158)
		(end 61.944504 -311.378854)
		(width 0.16002)
		(layer "In4.Cu")
		(net "M_D_CPU1_SB_DQS_DN<3>")
	)
	(segment
		(start 39.468552 -313.36234)
		(end 40.79748 -313.36234)
		(width 0.16002)
		(layer "In4.Cu")
		(net "M_D_CPU1_SB_DQS_DN<3>")
	)
	(segment
		(start 64.585088 -308.24805)
		(end 64.780922 -308.052216)
		(width 0.16002)
		(layer "In4.Cu")
		(net "M_D_CPU1_SB_DQS_DN<3>")
	)
	(segment
		(start 61.837824 -311.272174)
		(end 61.837824 -310.995314)
		(width 0.16002)
		(layer "In4.Cu")
		(net "M_D_CPU1_SB_DQS_DN<3>")
	)
	(segment
		(start 60.009532 -312.823606)
		(end 60.660026 -312.173112)
		(width 0.16002)
		(layer "In4.Cu")
		(net "M_D_CPU1_SB_DQS_DN<3>")
	)
	(segment
		(start 68.81241 -305.037998)
		(end 68.812664 -304.510694)
		(width 0.16002)
		(layer "In4.Cu")
		(net "M_D_CPU1_SB_DQS_DN<3>")
	)
	(segment
		(start 67.332352 -305.500786)
		(end 67.528186 -305.304952)
		(width 0.16002)
		(layer "In4.Cu")
		(net "M_D_CPU1_SB_DQS_DN<3>")
	)
	(segment
		(start 67.438778 -306.194206)
		(end 67.439032 -305.884326)
		(width 0.16002)
		(layer "In4.Cu")
		(net "M_D_CPU1_SB_DQS_DN<3>")
	)
	(segment
		(start 86.881208 -290.766246)
		(end 86.88959 -290.771072)
		(width 0.09525)
		(layer "In4.Cu")
		(net "M_D_CPU1_SB_DQS_DN<3>")
	)
	(segment
		(start 62.310264 -310.79948)
		(end 62.416944 -310.90616)
		(width 0.16002)
		(layer "In4.Cu")
		(net "M_D_CPU1_SB_DQS_DN<3>")
	)
	(segment
		(start 85.941154 -290.766246)
		(end 85.949536 -290.771072)
		(width 0.09525)
		(layer "In4.Cu")
		(net "M_D_CPU1_SB_DQS_DN<3>")
	)
	(segment
		(start 54.49316 -313.687206)
		(end 55.187342 -312.993024)
		(width 0.16002)
		(layer "In4.Cu")
		(net "M_D_CPU1_SB_DQS_DN<3>")
	)
	(segment
		(start 73.74001 -297.901106)
		(end 76.346304 -295.29532)
		(width 0.16002)
		(layer "In4.Cu")
		(net "M_D_CPU1_SB_DQS_DN<3>")
	)
	(segment
		(start 83.692492 -290.771072)
		(end 83.700874 -290.766246)
		(width 0.09525)
		(layer "In4.Cu")
		(net "M_D_CPU1_SB_DQS_DN<3>")
	)
	(segment
		(start 51.124358 -312.512456)
		(end 52.105814 -312.512456)
		(width 0.16002)
		(layer "In4.Cu")
		(net "M_D_CPU1_SB_DQS_DN<3>")
	)
	(segment
		(start 63.790576 -309.532528)
		(end 64.31788 -309.532528)
		(width 0.16002)
		(layer "In4.Cu")
		(net "M_D_CPU1_SB_DQS_DN<3>")
	)
	(segment
		(start 70.186296 -303.137062)
		(end 70.079616 -303.030382)
		(width 0.16002)
		(layer "In4.Cu")
		(net "M_D_CPU1_SB_DQS_DN<3>")
	)
	(segment
		(start 70.079616 -303.030382)
		(end 70.079616 -302.753522)
		(width 0.16002)
		(layer "In4.Cu")
		(net "M_D_CPU1_SB_DQS_DN<3>")
	)
	(segment
		(start 64.780922 -308.052216)
		(end 65.057528 -308.052216)
		(width 0.16002)
		(layer "In4.Cu")
		(net "M_D_CPU1_SB_DQS_DN<3>")
	)
	(segment
		(start 65.95872 -306.874418)
		(end 66.154554 -306.678584)
		(width 0.16002)
		(layer "In4.Cu")
		(net "M_D_CPU1_SB_DQS_DN<3>")
	)
	(segment
		(start 64.691768 -308.63159)
		(end 64.585088 -308.52491)
		(width 0.16002)
		(layer "In4.Cu")
		(net "M_D_CPU1_SB_DQS_DN<3>")
	)
	(segment
		(start 76.62164 -294.936926)
		(end 76.62164 -294.305482)
		(width 0.09525)
		(layer "In4.Cu")
		(net "M_D_CPU1_SB_DQS_DN<3>")
	)
	(segment
		(start 55.187342 -312.993024)
		(end 55.47995 -312.993024)
		(width 0.16002)
		(layer "In4.Cu")
		(net "M_D_CPU1_SB_DQS_DN<3>")
	)
	(segment
		(start 53.280564 -313.687206)
		(end 54.49316 -313.687206)
		(width 0.16002)
		(layer "In4.Cu")
		(net "M_D_CPU1_SB_DQS_DN<3>")
	)
	(segment
		(start 76.363068 -295.278556)
		(end 76.363068 -295.195752)
		(width 0.09525)
		(layer "In4.Cu")
		(net "M_D_CPU1_SB_DQS_DN<3>")
	)
	(segment
		(start 66.0654 -307.257958)
		(end 65.95872 -307.151278)
		(width 0.16002)
		(layer "In4.Cu")
		(net "M_D_CPU1_SB_DQS_DN<3>")
	)
	(segment
		(start 68.705984 -304.404014)
		(end 68.705984 -304.127154)
		(width 0.16002)
		(layer "In4.Cu")
		(net "M_D_CPU1_SB_DQS_DN<3>")
	)
	(segment
		(start 88.392508 -290.771072)
		(end 88.40089 -290.766246)
		(width 0.09525)
		(layer "In4.Cu")
		(net "M_D_CPU1_SB_DQS_DN<3>")
	)
	(segment
		(start 82.181192 -290.766246)
		(end 82.189574 -290.771072)
		(width 0.09525)
		(layer "In4.Cu")
		(net "M_D_CPU1_SB_DQS_DN<3>")
	)
	(segment
		(start 63.211456 -309.621682)
		(end 63.40729 -309.425848)
		(width 0.16002)
		(layer "In4.Cu")
		(net "M_D_CPU1_SB_DQS_DN<3>")
	)
	(segment
		(start 66.154554 -306.678584)
		(end 66.43116 -306.678584)
		(width 0.16002)
		(layer "In4.Cu")
		(net "M_D_CPU1_SB_DQS_DN<3>")
	)
	(segment
		(start 64.585088 -308.52491)
		(end 64.585088 -308.24805)
		(width 0.16002)
		(layer "In4.Cu")
		(net "M_D_CPU1_SB_DQS_DN<3>")
	)
	(segment
		(start 63.683896 -309.425848)
		(end 63.790576 -309.532528)
		(width 0.16002)
		(layer "In4.Cu")
		(net "M_D_CPU1_SB_DQS_DN<3>")
	)
	(segment
		(start 91.146376 -290.804092)
		(end 91.247214 -290.830762)
		(width 0.09525)
		(layer "In4.Cu")
		(net "M_D_CPU1_SB_DQS_DN<3>")
	)
	(segment
		(start 57.874408 -312.823606)
		(end 60.009532 -312.823606)
		(width 0.16002)
		(layer "In4.Cu")
		(net "M_D_CPU1_SB_DQS_DN<3>")
	)
	(segment
		(start 39.319454 -313.511438)
		(end 39.468552 -313.36234)
		(width 0.16002)
		(layer "In4.Cu")
		(net "M_D_CPU1_SB_DQS_DN<3>")
	)
	(segment
		(start 56.174132 -313.687206)
		(end 57.010808 -313.687206)
		(width 0.16002)
		(layer "In4.Cu")
		(net "M_D_CPU1_SB_DQS_DN<3>")
	)
	(segment
		(start 66.065146 -307.785262)
		(end 66.0654 -307.257958)
		(width 0.16002)
		(layer "In4.Cu")
		(net "M_D_CPU1_SB_DQS_DN<3>")
	)
	(segment
		(start 67.528186 -305.304952)
		(end 67.804792 -305.304952)
		(width 0.16002)
		(layer "In4.Cu")
		(net "M_D_CPU1_SB_DQS_DN<3>")
	)
	(segment
		(start 67.438778 -306.41163)
		(end 67.438778 -306.194206)
		(width 0.16002)
		(layer "In4.Cu")
		(net "M_D_CPU1_SB_DQS_DN<3>")
	)
	(segment
		(start 68.705984 -304.127154)
		(end 68.901818 -303.93132)
		(width 0.16002)
		(layer "In4.Cu")
		(net "M_D_CPU1_SB_DQS_DN<3>")
	)
	(segment
		(start 78.435962 -291.631878)
		(end 79.800704 -290.719764)
		(width 0.09525)
		(layer "In4.Cu")
		(net "M_D_CPU1_SB_DQS_DN<3>")
	)
	(segment
		(start 76.62164 -294.305482)
		(end 76.821538 -293.822882)
		(width 0.09525)
		(layer "In4.Cu")
		(net "M_D_CPU1_SB_DQS_DN<3>")
	)
	(segment
		(start 70.079616 -302.753522)
		(end 73.74001 -299.093128)
		(width 0.16002)
		(layer "In4.Cu")
		(net "M_D_CPU1_SB_DQS_DN<3>")
	)
	(segment
		(start 56.095138 -313.607958)
		(end 56.174132 -313.687206)
		(width 0.16002)
		(layer "In4.Cu")
		(net "M_D_CPU1_SB_DQS_DN<3>")
	)
	(segment
		(start 65.95872 -307.151278)
		(end 65.95872 -306.874418)
		(width 0.16002)
		(layer "In4.Cu")
		(net "M_D_CPU1_SB_DQS_DN<3>")
	)
	(segment
		(start 69.812408 -304.038)
		(end 70.186042 -303.664366)
		(width 0.16002)
		(layer "In4.Cu")
		(net "M_D_CPU1_SB_DQS_DN<3>")
	)
	(segment
		(start 43.572176 -312.512456)
		(end 45.230796 -312.512456)
		(width 0.16002)
		(layer "In4.Cu")
		(net "M_D_CPU1_SB_DQS_DN<3>")
	)
	(segment
		(start 62.944248 -310.90616)
		(end 63.317882 -310.532526)
		(width 0.16002)
		(layer "In4.Cu")
		(net "M_D_CPU1_SB_DQS_DN<3>")
	)
	(segment
		(start 61.837824 -310.995314)
		(end 62.033658 -310.79948)
		(width 0.16002)
		(layer "In4.Cu")
		(net "M_D_CPU1_SB_DQS_DN<3>")
	)
	(segment
		(start 66.53784 -306.785264)
		(end 67.065144 -306.785264)
		(width 0.16002)
		(layer "In4.Cu")
		(net "M_D_CPU1_SB_DQS_DN<3>")
	)
	(segment
		(start 64.31788 -309.532528)
		(end 64.691514 -309.158894)
		(width 0.16002)
		(layer "In4.Cu")
		(net "M_D_CPU1_SB_DQS_DN<3>")
	)
	(segment
		(start 48.871124 -313.674506)
		(end 49.479708 -313.674506)
		(width 0.16002)
		(layer "In4.Cu")
		(net "M_D_CPU1_SB_DQS_DN<3>")
	)
	(segment
		(start 63.318136 -310.005222)
		(end 63.211456 -309.898542)
		(width 0.16002)
		(layer "In4.Cu")
		(net "M_D_CPU1_SB_DQS_DN<3>")
	)
	(segment
		(start 77.274928 -293.369492)
		(end 78.435962 -291.631878)
		(width 0.09525)
		(layer "In4.Cu")
		(net "M_D_CPU1_SB_DQS_DN<3>")
	)
	(segment
		(start 66.43116 -306.678584)
		(end 66.53784 -306.785264)
		(width 0.16002)
		(layer "In4.Cu")
		(net "M_D_CPU1_SB_DQS_DN<3>")
	)
	(segment
		(start 69.285104 -304.038)
		(end 69.812408 -304.038)
		(width 0.16002)
		(layer "In4.Cu")
		(net "M_D_CPU1_SB_DQS_DN<3>")
	)
	(segment
		(start 70.186042 -303.664366)
		(end 70.186296 -303.137062)
		(width 0.16002)
		(layer "In4.Cu")
		(net "M_D_CPU1_SB_DQS_DN<3>")
	)
	(segment
		(start 61.570616 -312.279792)
		(end 61.94425 -311.906158)
		(width 0.16002)
		(layer "In4.Cu")
		(net "M_D_CPU1_SB_DQS_DN<3>")
	)
	(segment
		(start 50.241708 -312.912506)
		(end 50.724308 -312.912506)
		(width 0.16002)
		(layer "In4.Cu")
		(net "M_D_CPU1_SB_DQS_DN<3>")
	)
	(segment
		(start 43.244008 -312.840624)
		(end 43.572176 -312.512456)
		(width 0.16002)
		(layer "In4.Cu")
		(net "M_D_CPU1_SB_DQS_DN<3>")
	)
	(segment
		(start 62.416944 -310.90616)
		(end 62.944248 -310.90616)
		(width 0.16002)
		(layer "In4.Cu")
		(net "M_D_CPU1_SB_DQS_DN<3>")
	)
	(segment
		(start 41.113964 -313.678824)
		(end 41.923208 -313.678824)
		(width 0.16002)
		(layer "In4.Cu")
		(net "M_D_CPU1_SB_DQS_DN<3>")
	)
	(segment
		(start 48.558958 -313.36234)
		(end 48.871124 -313.674506)
		(width 0.16002)
		(layer "In4.Cu")
		(net "M_D_CPU1_SB_DQS_DN<3>")
	)
	(segment
		(start 45.230796 -312.512456)
		(end 46.08068 -313.36234)
		(width 0.16002)
		(layer "In4.Cu")
		(net "M_D_CPU1_SB_DQS_DN<3>")
	)
	(segment
		(start 61.944504 -311.378854)
		(end 61.837824 -311.272174)
		(width 0.16002)
		(layer "In4.Cu")
		(net "M_D_CPU1_SB_DQS_DN<3>")
	)
	(segment
		(start 41.923208 -313.678824)
		(end 42.761408 -312.840624)
		(width 0.16002)
		(layer "In4.Cu")
		(net "M_D_CPU1_SB_DQS_DN<3>")
	)
	(segment
		(start 46.08068 -313.36234)
		(end 48.558958 -313.36234)
		(width 0.16002)
		(layer "In4.Cu")
		(net "M_D_CPU1_SB_DQS_DN<3>")
	)
	(segment
		(start 68.812664 -304.510694)
		(end 68.705984 -304.404014)
		(width 0.16002)
		(layer "In4.Cu")
		(net "M_D_CPU1_SB_DQS_DN<3>")
	)
	(segment
		(start 61.043312 -312.279792)
		(end 61.570616 -312.279792)
		(width 0.16002)
		(layer "In4.Cu")
		(net "M_D_CPU1_SB_DQS_DN<3>")
	)
	(segment
		(start 76.346304 -295.29532)
		(end 76.363068 -295.278556)
		(width 0.09525)
		(layer "In4.Cu")
		(net "M_D_CPU1_SB_DQS_DN<3>")
	)
	(segment
		(start 68.901818 -303.93132)
		(end 69.178424 -303.93132)
		(width 0.16002)
		(layer "In4.Cu")
		(net "M_D_CPU1_SB_DQS_DN<3>")
	)
	(segment
		(start 73.74001 -299.093128)
		(end 73.74001 -297.901106)
		(width 0.16002)
		(layer "In4.Cu")
		(net "M_D_CPU1_SB_DQS_DN<3>")
	)
	(segment
		(start 67.804792 -305.304952)
		(end 67.911472 -305.411632)
		(width 0.16002)
		(layer "In4.Cu")
		(net "M_D_CPU1_SB_DQS_DN<3>")
	)
	(segment
		(start 63.317882 -310.532526)
		(end 63.318136 -310.005222)
		(width 0.16002)
		(layer "In4.Cu")
		(net "M_D_CPU1_SB_DQS_DN<3>")
	)
	(segment
		(start 79.800704 -290.719764)
		(end 80.120998 -290.719764)
		(width 0.09525)
		(layer "In4.Cu")
		(net "M_D_CPU1_SB_DQS_DN<3>")
	)
	(segment
		(start 65.691512 -308.158896)
		(end 66.065146 -307.785262)
		(width 0.16002)
		(layer "In4.Cu")
		(net "M_D_CPU1_SB_DQS_DN<3>")
	)
	(arc
		(start 88.40089 -290.766246)
		(mid 88.585922 -290.720332)
		(end 88.769698 -290.771072)
		(width 0.09525)
		(layer "In4.Cu")
		(net "M_D_CPU1_SB_DQS_DN<3>")
	)
	(arc
		(start 86.88959 -290.771072)
		(mid 87.171022 -290.846827)
		(end 87.452454 -290.771072)
		(width 0.09525)
		(layer "In4.Cu")
		(net "M_D_CPU1_SB_DQS_DN<3>")
	)
	(arc
		(start 83.700874 -290.766246)
		(mid 83.885906 -290.720332)
		(end 84.069682 -290.771072)
		(width 0.09525)
		(layer "In4.Cu")
		(net "M_D_CPU1_SB_DQS_DN<3>")
	)
	(arc
		(start 85.949536 -290.771072)
		(mid 86.230968 -290.846827)
		(end 86.5124 -290.771072)
		(width 0.09525)
		(layer "In4.Cu")
		(net "M_D_CPU1_SB_DQS_DN<3>")
	)
	(arc
		(start 86.5124 -290.771072)
		(mid 86.696175 -290.7203)
		(end 86.881208 -290.766246)
		(width 0.09525)
		(layer "In4.Cu")
		(net "M_D_CPU1_SB_DQS_DN<3>")
	)
	(arc
		(start 81.812384 -290.771072)
		(mid 81.996159 -290.7203)
		(end 82.181192 -290.766246)
		(width 0.09525)
		(layer "In4.Cu")
		(net "M_D_CPU1_SB_DQS_DN<3>")
	)
	(arc
		(start 85.572346 -290.771072)
		(mid 85.756121 -290.7203)
		(end 85.941154 -290.766246)
		(width 0.09525)
		(layer "In4.Cu")
		(net "M_D_CPU1_SB_DQS_DN<3>")
	)
	(arc
		(start 90.272362 -290.771072)
		(mid 90.456137 -290.7203)
		(end 90.64117 -290.766246)
		(width 0.09525)
		(layer "In4.Cu")
		(net "M_D_CPU1_SB_DQS_DN<3>")
	)
	(arc
		(start 83.129628 -290.771072)
		(mid 83.41106 -290.846827)
		(end 83.692492 -290.771072)
		(width 0.09525)
		(layer "In4.Cu")
		(net "M_D_CPU1_SB_DQS_DN<3>")
	)
	(arc
		(start 89.332562 -290.771072)
		(mid 89.52103 -290.720395)
		(end 89.709498 -290.771072)
		(width 0.09525)
		(layer "In4.Cu")
		(net "M_D_CPU1_SB_DQS_DN<3>")
	)
	(arc
		(start 82.76082 -290.766246)
		(mid 82.945852 -290.720332)
		(end 83.129628 -290.771072)
		(width 0.09525)
		(layer "In4.Cu")
		(net "M_D_CPU1_SB_DQS_DN<3>")
	)
	(arc
		(start 90.649552 -290.771072)
		(mid 90.883066 -290.844915)
		(end 91.125802 -290.81222)
		(width 0.09525)
		(layer "In4.Cu")
		(net "M_D_CPU1_SB_DQS_DN<3>")
	)
	(arc
		(start 87.829644 -290.771072)
		(mid 88.111076 -290.846827)
		(end 88.392508 -290.771072)
		(width 0.09525)
		(layer "In4.Cu")
		(net "M_D_CPU1_SB_DQS_DN<3>")
	)
	(arc
		(start 81.24952 -290.771072)
		(mid 81.530952 -290.846827)
		(end 81.812384 -290.771072)
		(width 0.09525)
		(layer "In4.Cu")
		(net "M_D_CPU1_SB_DQS_DN<3>")
	)
	(arc
		(start 91.125802 -290.81222)
		(mid 91.13613 -290.80826)
		(end 91.146376 -290.804092)
		(width 0.09525)
		(layer "In4.Cu")
		(net "M_D_CPU1_SB_DQS_DN<3>")
	)
	(arc
		(start 84.069682 -290.771072)
		(mid 84.351114 -290.846827)
		(end 84.632546 -290.771072)
		(width 0.09525)
		(layer "In4.Cu")
		(net "M_D_CPU1_SB_DQS_DN<3>")
	)
	(arc
		(start 87.460836 -290.766246)
		(mid 87.645868 -290.720332)
		(end 87.829644 -290.771072)
		(width 0.09525)
		(layer "In4.Cu")
		(net "M_D_CPU1_SB_DQS_DN<3>")
	)
	(arc
		(start 80.30972 -290.771072)
		(mid 80.591152 -290.846827)
		(end 80.872584 -290.771072)
		(width 0.09525)
		(layer "In4.Cu")
		(net "M_D_CPU1_SB_DQS_DN<3>")
	)
	(arc
		(start 84.632546 -290.771072)
		(mid 84.821014 -290.720395)
		(end 85.009482 -290.771072)
		(width 0.09525)
		(layer "In4.Cu")
		(net "M_D_CPU1_SB_DQS_DN<3>")
	)
	(arc
		(start 82.189574 -290.771072)
		(mid 82.471006 -290.846827)
		(end 82.752438 -290.771072)
		(width 0.09525)
		(layer "In4.Cu")
		(net "M_D_CPU1_SB_DQS_DN<3>")
	)
	(arc
		(start 80.872584 -290.771072)
		(mid 81.061052 -290.720395)
		(end 81.24952 -290.771072)
		(width 0.09525)
		(layer "In4.Cu")
		(net "M_D_CPU1_SB_DQS_DN<3>")
	)
	(arc
		(start 89.709498 -290.771072)
		(mid 89.99093 -290.846827)
		(end 90.272362 -290.771072)
		(width 0.09525)
		(layer "In4.Cu")
		(net "M_D_CPU1_SB_DQS_DN<3>")
	)
	(arc
		(start 85.009482 -290.771072)
		(mid 85.290914 -290.846827)
		(end 85.572346 -290.771072)
		(width 0.09525)
		(layer "In4.Cu")
		(net "M_D_CPU1_SB_DQS_DN<3>")
	)
	(arc
		(start 80.120998 -290.719764)
		(mid 80.218744 -290.732959)
		(end 80.30972 -290.771072)
		(width 0.09525)
		(layer "In4.Cu")
		(net "M_D_CPU1_SB_DQS_DN<3>")
	)
	(arc
		(start 88.769698 -290.771072)
		(mid 89.05113 -290.846827)
		(end 89.332562 -290.771072)
		(width 0.09525)
		(layer "In4.Cu")
		(net "M_D_CPU1_SB_DQS_DN<3>")
	)
	(segment
		(start 91.86799 -285.970472)
		(end 91.401138 -286.23641)
		(width 0.12954)
		(layer "F.Cu")
		(net "M_D_CPU1_SB_DQS_DN<2>")
	)
	(segment
		(start 65.01003 -298.203112)
		(end 65.221358 -298.41444)
		(width 0.16002)
		(layer "In4.Cu")
		(net "M_D_CPU1_SB_DQS_DN<2>")
	)
	(segment
		(start 55.764684 -304.40122)
		(end 56.139588 -304.776124)
		(width 0.16002)
		(layer "In4.Cu")
		(net "M_D_CPU1_SB_DQS_DN<2>")
	)
	(segment
		(start 82.181192 -285.906464)
		(end 82.189574 -285.91129)
		(width 0.09525)
		(layer "In4.Cu")
		(net "M_D_CPU1_SB_DQS_DN<2>")
	)
	(segment
		(start 50.724308 -303.562512)
		(end 51.124358 -303.162462)
		(width 0.16002)
		(layer "In4.Cu")
		(net "M_D_CPU1_SB_DQS_DN<2>")
	)
	(segment
		(start 62.262766 -300.950376)
		(end 62.474094 -301.161704)
		(width 0.16002)
		(layer "In4.Cu")
		(net "M_D_CPU1_SB_DQS_DN<2>")
	)
	(segment
		(start 39.929308 -304.012346)
		(end 40.997886 -304.012346)
		(width 0.16002)
		(layer "In4.Cu")
		(net "M_D_CPU1_SB_DQS_DN<2>")
	)
	(segment
		(start 91.247214 -285.97098)
		(end 91.401138 -286.23641)
		(width 0.09525)
		(layer "In4.Cu")
		(net "M_D_CPU1_SB_DQS_DN<2>")
	)
	(segment
		(start 37.069776 -304.161444)
		(end 39.78021 -304.161444)
		(width 0.16002)
		(layer "In4.Cu")
		(net "M_D_CPU1_SB_DQS_DN<2>")
	)
	(segment
		(start 85.941154 -285.906464)
		(end 85.949536 -285.91129)
		(width 0.09525)
		(layer "In4.Cu")
		(net "M_D_CPU1_SB_DQS_DN<2>")
	)
	(segment
		(start 57.927748 -303.473612)
		(end 60.355226 -303.473612)
		(width 0.16002)
		(layer "In4.Cu")
		(net "M_D_CPU1_SB_DQS_DN<2>")
	)
	(segment
		(start 49.479708 -304.324512)
		(end 50.241708 -303.562512)
		(width 0.16002)
		(layer "In4.Cu")
		(net "M_D_CPU1_SB_DQS_DN<2>")
	)
	(segment
		(start 45.710602 -303.162462)
		(end 46.560486 -304.012346)
		(width 0.16002)
		(layer "In4.Cu")
		(net "M_D_CPU1_SB_DQS_DN<2>")
	)
	(segment
		(start 87.452454 -285.91129)
		(end 87.460836 -285.906464)
		(width 0.09525)
		(layer "In4.Cu")
		(net "M_D_CPU1_SB_DQS_DN<2>")
	)
	(segment
		(start 88.392508 -285.91129)
		(end 88.40089 -285.906464)
		(width 0.09525)
		(layer "In4.Cu")
		(net "M_D_CPU1_SB_DQS_DN<2>")
	)
	(segment
		(start 67.2846 -295.651682)
		(end 76.16952 -286.766762)
		(width 0.16002)
		(layer "In4.Cu")
		(net "M_D_CPU1_SB_DQS_DN<2>")
	)
	(segment
		(start 60.355226 -303.473612)
		(end 61.72073 -302.108108)
		(width 0.16002)
		(layer "In4.Cu")
		(net "M_D_CPU1_SB_DQS_DN<2>")
	)
	(segment
		(start 78.08214 -285.987236)
		(end 78.711044 -285.987236)
		(width 0.09525)
		(layer "In4.Cu")
		(net "M_D_CPU1_SB_DQS_DN<2>")
	)
	(segment
		(start 61.72073 -302.108108)
		(end 61.72073 -301.215552)
		(width 0.16002)
		(layer "In4.Cu")
		(net "M_D_CPU1_SB_DQS_DN<2>")
	)
	(segment
		(start 61.72073 -301.215552)
		(end 61.985906 -300.950376)
		(width 0.16002)
		(layer "In4.Cu")
		(net "M_D_CPU1_SB_DQS_DN<2>")
	)
	(segment
		(start 63.375032 -300.260766)
		(end 63.163704 -300.049438)
		(width 0.16002)
		(layer "In4.Cu")
		(net "M_D_CPU1_SB_DQS_DN<2>")
	)
	(segment
		(start 79.922116 -285.917386)
		(end 79.93253 -285.91129)
		(width 0.09525)
		(layer "In4.Cu")
		(net "M_D_CPU1_SB_DQS_DN<2>")
	)
	(segment
		(start 67.2846 -295.928542)
		(end 67.2846 -295.651682)
		(width 0.16002)
		(layer "In4.Cu")
		(net "M_D_CPU1_SB_DQS_DN<2>")
	)
	(segment
		(start 56.625236 -304.776124)
		(end 57.927748 -303.473612)
		(width 0.16002)
		(layer "In4.Cu")
		(net "M_D_CPU1_SB_DQS_DN<2>")
	)
	(segment
		(start 64.374522 -299.788326)
		(end 64.74841 -299.414438)
		(width 0.16002)
		(layer "In4.Cu")
		(net "M_D_CPU1_SB_DQS_DN<2>")
	)
	(segment
		(start 40.997886 -304.012346)
		(end 41.317164 -304.331624)
		(width 0.16002)
		(layer "In4.Cu")
		(net "M_D_CPU1_SB_DQS_DN<2>")
	)
	(segment
		(start 91.146376 -285.94431)
		(end 91.247214 -285.97098)
		(width 0.09525)
		(layer "In4.Cu")
		(net "M_D_CPU1_SB_DQS_DN<2>")
	)
	(segment
		(start 65.910968 -297.025314)
		(end 66.106802 -296.82948)
		(width 0.16002)
		(layer "In4.Cu")
		(net "M_D_CPU1_SB_DQS_DN<2>")
	)
	(segment
		(start 66.106802 -296.82948)
		(end 66.383662 -296.82948)
		(width 0.16002)
		(layer "In4.Cu")
		(net "M_D_CPU1_SB_DQS_DN<2>")
	)
	(segment
		(start 82.752438 -285.91129)
		(end 82.76082 -285.906464)
		(width 0.09525)
		(layer "In4.Cu")
		(net "M_D_CPU1_SB_DQS_DN<2>")
	)
	(segment
		(start 48.558958 -304.012346)
		(end 48.871124 -304.324512)
		(width 0.16002)
		(layer "In4.Cu")
		(net "M_D_CPU1_SB_DQS_DN<2>")
	)
	(segment
		(start 67.495674 -296.667174)
		(end 67.495928 -296.13987)
		(width 0.16002)
		(layer "In4.Cu")
		(net "M_D_CPU1_SB_DQS_DN<2>")
	)
	(segment
		(start 55.26532 -303.645824)
		(end 55.557928 -303.645824)
		(width 0.16002)
		(layer "In4.Cu")
		(net "M_D_CPU1_SB_DQS_DN<2>")
	)
	(segment
		(start 86.881208 -285.906464)
		(end 86.88959 -285.91129)
		(width 0.09525)
		(layer "In4.Cu")
		(net "M_D_CPU1_SB_DQS_DN<2>")
	)
	(segment
		(start 43.269408 -303.518824)
		(end 43.62577 -303.162462)
		(width 0.16002)
		(layer "In4.Cu")
		(net "M_D_CPU1_SB_DQS_DN<2>")
	)
	(segment
		(start 83.692492 -285.91129)
		(end 83.700874 -285.906464)
		(width 0.09525)
		(layer "In4.Cu")
		(net "M_D_CPU1_SB_DQS_DN<2>")
	)
	(segment
		(start 67.121786 -297.041062)
		(end 67.495674 -296.667174)
		(width 0.16002)
		(layer "In4.Cu")
		(net "M_D_CPU1_SB_DQS_DN<2>")
	)
	(segment
		(start 48.871124 -304.324512)
		(end 49.479708 -304.324512)
		(width 0.16002)
		(layer "In4.Cu")
		(net "M_D_CPU1_SB_DQS_DN<2>")
	)
	(segment
		(start 51.124358 -303.162462)
		(end 52.238656 -303.162462)
		(width 0.16002)
		(layer "In4.Cu")
		(net "M_D_CPU1_SB_DQS_DN<2>")
	)
	(segment
		(start 41.923208 -304.331624)
		(end 42.736008 -303.518824)
		(width 0.16002)
		(layer "In4.Cu")
		(net "M_D_CPU1_SB_DQS_DN<2>")
	)
	(segment
		(start 64.748664 -298.887134)
		(end 64.537336 -298.675806)
		(width 0.16002)
		(layer "In4.Cu")
		(net "M_D_CPU1_SB_DQS_DN<2>")
	)
	(segment
		(start 61.985906 -300.950376)
		(end 62.262766 -300.950376)
		(width 0.16002)
		(layer "In4.Cu")
		(net "M_D_CPU1_SB_DQS_DN<2>")
	)
	(segment
		(start 66.122042 -298.040806)
		(end 66.122296 -297.513502)
		(width 0.16002)
		(layer "In4.Cu")
		(net "M_D_CPU1_SB_DQS_DN<2>")
	)
	(segment
		(start 76.186284 -286.749998)
		(end 76.18603 -286.667194)
		(width 0.09525)
		(layer "In4.Cu")
		(net "M_D_CPU1_SB_DQS_DN<2>")
	)
	(segment
		(start 53.471318 -304.395124)
		(end 54.51602 -304.395124)
		(width 0.16002)
		(layer "In4.Cu")
		(net "M_D_CPU1_SB_DQS_DN<2>")
	)
	(segment
		(start 65.221358 -298.41444)
		(end 65.748154 -298.414694)
		(width 0.16002)
		(layer "In4.Cu")
		(net "M_D_CPU1_SB_DQS_DN<2>")
	)
	(segment
		(start 43.62577 -303.162462)
		(end 45.710602 -303.162462)
		(width 0.16002)
		(layer "In4.Cu")
		(net "M_D_CPU1_SB_DQS_DN<2>")
	)
	(segment
		(start 39.78021 -304.161444)
		(end 39.929308 -304.012346)
		(width 0.16002)
		(layer "In4.Cu")
		(net "M_D_CPU1_SB_DQS_DN<2>")
	)
	(segment
		(start 66.59499 -297.040808)
		(end 67.121786 -297.041062)
		(width 0.16002)
		(layer "In4.Cu")
		(net "M_D_CPU1_SB_DQS_DN<2>")
	)
	(segment
		(start 77.51953 -286.549846)
		(end 78.08214 -285.987236)
		(width 0.09525)
		(layer "In4.Cu")
		(net "M_D_CPU1_SB_DQS_DN<2>")
	)
	(segment
		(start 65.748154 -298.414694)
		(end 66.122042 -298.040806)
		(width 0.16002)
		(layer "In4.Cu")
		(net "M_D_CPU1_SB_DQS_DN<2>")
	)
	(segment
		(start 63.00089 -301.161958)
		(end 63.374778 -300.78807)
		(width 0.16002)
		(layer "In4.Cu")
		(net "M_D_CPU1_SB_DQS_DN<2>")
	)
	(segment
		(start 63.163704 -300.049438)
		(end 63.163704 -299.772578)
		(width 0.16002)
		(layer "In4.Cu")
		(net "M_D_CPU1_SB_DQS_DN<2>")
	)
	(segment
		(start 64.537336 -298.675806)
		(end 64.537336 -298.398946)
		(width 0.16002)
		(layer "In4.Cu")
		(net "M_D_CPU1_SB_DQS_DN<2>")
	)
	(segment
		(start 50.241708 -303.562512)
		(end 50.724308 -303.562512)
		(width 0.16002)
		(layer "In4.Cu")
		(net "M_D_CPU1_SB_DQS_DN<2>")
	)
	(segment
		(start 55.557928 -303.645824)
		(end 55.764684 -303.85258)
		(width 0.16002)
		(layer "In4.Cu")
		(net "M_D_CPU1_SB_DQS_DN<2>")
	)
	(segment
		(start 65.910968 -297.302174)
		(end 65.910968 -297.025314)
		(width 0.16002)
		(layer "In4.Cu")
		(net "M_D_CPU1_SB_DQS_DN<2>")
	)
	(segment
		(start 63.847726 -299.788072)
		(end 64.374522 -299.788326)
		(width 0.16002)
		(layer "In4.Cu")
		(net "M_D_CPU1_SB_DQS_DN<2>")
	)
	(segment
		(start 79.361538 -285.906464)
		(end 79.36992 -285.91129)
		(width 0.09525)
		(layer "In4.Cu")
		(net "M_D_CPU1_SB_DQS_DN<2>")
	)
	(segment
		(start 63.636398 -299.576744)
		(end 63.847726 -299.788072)
		(width 0.16002)
		(layer "In4.Cu")
		(net "M_D_CPU1_SB_DQS_DN<2>")
	)
	(segment
		(start 64.73317 -298.203112)
		(end 65.01003 -298.203112)
		(width 0.16002)
		(layer "In4.Cu")
		(net "M_D_CPU1_SB_DQS_DN<2>")
	)
	(segment
		(start 56.139588 -304.776124)
		(end 56.625236 -304.776124)
		(width 0.16002)
		(layer "In4.Cu")
		(net "M_D_CPU1_SB_DQS_DN<2>")
	)
	(segment
		(start 62.474094 -301.161704)
		(end 63.00089 -301.161958)
		(width 0.16002)
		(layer "In4.Cu")
		(net "M_D_CPU1_SB_DQS_DN<2>")
	)
	(segment
		(start 55.764684 -303.85258)
		(end 55.764684 -304.40122)
		(width 0.16002)
		(layer "In4.Cu")
		(net "M_D_CPU1_SB_DQS_DN<2>")
	)
	(segment
		(start 66.383662 -296.82948)
		(end 66.59499 -297.040808)
		(width 0.16002)
		(layer "In4.Cu")
		(net "M_D_CPU1_SB_DQS_DN<2>")
	)
	(segment
		(start 46.560486 -304.012346)
		(end 48.558958 -304.012346)
		(width 0.16002)
		(layer "In4.Cu")
		(net "M_D_CPU1_SB_DQS_DN<2>")
	)
	(segment
		(start 54.51602 -304.395124)
		(end 55.26532 -303.645824)
		(width 0.16002)
		(layer "In4.Cu")
		(net "M_D_CPU1_SB_DQS_DN<2>")
	)
	(segment
		(start 63.163704 -299.772578)
		(end 63.359538 -299.576744)
		(width 0.16002)
		(layer "In4.Cu")
		(net "M_D_CPU1_SB_DQS_DN<2>")
	)
	(segment
		(start 79.93253 -285.91129)
		(end 79.940912 -285.906464)
		(width 0.09525)
		(layer "In4.Cu")
		(net "M_D_CPU1_SB_DQS_DN<2>")
	)
	(segment
		(start 36.795964 -304.435256)
		(end 37.069776 -304.161444)
		(width 0.16002)
		(layer "In4.Cu")
		(net "M_D_CPU1_SB_DQS_DN<2>")
	)
	(segment
		(start 64.74841 -299.414438)
		(end 64.748664 -298.887134)
		(width 0.16002)
		(layer "In4.Cu")
		(net "M_D_CPU1_SB_DQS_DN<2>")
	)
	(segment
		(start 41.317164 -304.331624)
		(end 41.923208 -304.331624)
		(width 0.16002)
		(layer "In4.Cu")
		(net "M_D_CPU1_SB_DQS_DN<2>")
	)
	(segment
		(start 90.64117 -285.906464)
		(end 90.649552 -285.91129)
		(width 0.09525)
		(layer "In4.Cu")
		(net "M_D_CPU1_SB_DQS_DN<2>")
	)
	(segment
		(start 76.18603 -286.667194)
		(end 76.303378 -286.549846)
		(width 0.09525)
		(layer "In4.Cu")
		(net "M_D_CPU1_SB_DQS_DN<2>")
	)
	(segment
		(start 42.736008 -303.518824)
		(end 43.269408 -303.518824)
		(width 0.16002)
		(layer "In4.Cu")
		(net "M_D_CPU1_SB_DQS_DN<2>")
	)
	(segment
		(start 63.374778 -300.78807)
		(end 63.375032 -300.260766)
		(width 0.16002)
		(layer "In4.Cu")
		(net "M_D_CPU1_SB_DQS_DN<2>")
	)
	(segment
		(start 63.359538 -299.576744)
		(end 63.636398 -299.576744)
		(width 0.16002)
		(layer "In4.Cu")
		(net "M_D_CPU1_SB_DQS_DN<2>")
	)
	(segment
		(start 76.16952 -286.766762)
		(end 76.186284 -286.749998)
		(width 0.09525)
		(layer "In4.Cu")
		(net "M_D_CPU1_SB_DQS_DN<2>")
	)
	(segment
		(start 64.537336 -298.398946)
		(end 64.73317 -298.203112)
		(width 0.16002)
		(layer "In4.Cu")
		(net "M_D_CPU1_SB_DQS_DN<2>")
	)
	(segment
		(start 76.303378 -286.549846)
		(end 77.51953 -286.549846)
		(width 0.09525)
		(layer "In4.Cu")
		(net "M_D_CPU1_SB_DQS_DN<2>")
	)
	(segment
		(start 66.122296 -297.513502)
		(end 65.910968 -297.302174)
		(width 0.16002)
		(layer "In4.Cu")
		(net "M_D_CPU1_SB_DQS_DN<2>")
	)
	(segment
		(start 67.495928 -296.13987)
		(end 67.2846 -295.928542)
		(width 0.16002)
		(layer "In4.Cu")
		(net "M_D_CPU1_SB_DQS_DN<2>")
	)
	(segment
		(start 52.238656 -303.162462)
		(end 53.471318 -304.395124)
		(width 0.16002)
		(layer "In4.Cu")
		(net "M_D_CPU1_SB_DQS_DN<2>")
	)
	(arc
		(start 86.5124 -285.91129)
		(mid 86.696175 -285.860518)
		(end 86.881208 -285.906464)
		(width 0.09525)
		(layer "In4.Cu")
		(net "M_D_CPU1_SB_DQS_DN<2>")
	)
	(arc
		(start 81.24952 -285.91129)
		(mid 81.530952 -285.987045)
		(end 81.812384 -285.91129)
		(width 0.09525)
		(layer "In4.Cu")
		(net "M_D_CPU1_SB_DQS_DN<2>")
	)
	(arc
		(start 85.572346 -285.91129)
		(mid 85.756121 -285.860518)
		(end 85.941154 -285.906464)
		(width 0.09525)
		(layer "In4.Cu")
		(net "M_D_CPU1_SB_DQS_DN<2>")
	)
	(arc
		(start 83.700874 -285.906464)
		(mid 83.885906 -285.86055)
		(end 84.069682 -285.91129)
		(width 0.09525)
		(layer "In4.Cu")
		(net "M_D_CPU1_SB_DQS_DN<2>")
	)
	(arc
		(start 85.009482 -285.91129)
		(mid 85.290914 -285.987045)
		(end 85.572346 -285.91129)
		(width 0.09525)
		(layer "In4.Cu")
		(net "M_D_CPU1_SB_DQS_DN<2>")
	)
	(arc
		(start 90.272362 -285.91129)
		(mid 90.456137 -285.860518)
		(end 90.64117 -285.906464)
		(width 0.09525)
		(layer "In4.Cu")
		(net "M_D_CPU1_SB_DQS_DN<2>")
	)
	(arc
		(start 84.632546 -285.91129)
		(mid 84.821014 -285.860613)
		(end 85.009482 -285.91129)
		(width 0.09525)
		(layer "In4.Cu")
		(net "M_D_CPU1_SB_DQS_DN<2>")
	)
	(arc
		(start 79.36992 -285.91129)
		(mid 79.645209 -285.987011)
		(end 79.922116 -285.917386)
		(width 0.09525)
		(layer "In4.Cu")
		(net "M_D_CPU1_SB_DQS_DN<2>")
	)
	(arc
		(start 80.872584 -285.91129)
		(mid 81.061052 -285.860613)
		(end 81.24952 -285.91129)
		(width 0.09525)
		(layer "In4.Cu")
		(net "M_D_CPU1_SB_DQS_DN<2>")
	)
	(arc
		(start 81.812384 -285.91129)
		(mid 81.996159 -285.860518)
		(end 82.181192 -285.906464)
		(width 0.09525)
		(layer "In4.Cu")
		(net "M_D_CPU1_SB_DQS_DN<2>")
	)
	(arc
		(start 87.460836 -285.906464)
		(mid 87.645868 -285.86055)
		(end 87.829644 -285.91129)
		(width 0.09525)
		(layer "In4.Cu")
		(net "M_D_CPU1_SB_DQS_DN<2>")
	)
	(arc
		(start 89.709498 -285.91129)
		(mid 89.99093 -285.987045)
		(end 90.272362 -285.91129)
		(width 0.09525)
		(layer "In4.Cu")
		(net "M_D_CPU1_SB_DQS_DN<2>")
	)
	(arc
		(start 90.649552 -285.91129)
		(mid 90.883066 -285.985133)
		(end 91.125802 -285.952438)
		(width 0.09525)
		(layer "In4.Cu")
		(net "M_D_CPU1_SB_DQS_DN<2>")
	)
	(arc
		(start 88.40089 -285.906464)
		(mid 88.585922 -285.86055)
		(end 88.769698 -285.91129)
		(width 0.09525)
		(layer "In4.Cu")
		(net "M_D_CPU1_SB_DQS_DN<2>")
	)
	(arc
		(start 86.88959 -285.91129)
		(mid 87.171022 -285.987045)
		(end 87.452454 -285.91129)
		(width 0.09525)
		(layer "In4.Cu")
		(net "M_D_CPU1_SB_DQS_DN<2>")
	)
	(arc
		(start 91.125802 -285.952438)
		(mid 91.13613 -285.948478)
		(end 91.146376 -285.94431)
		(width 0.09525)
		(layer "In4.Cu")
		(net "M_D_CPU1_SB_DQS_DN<2>")
	)
	(arc
		(start 78.99273 -285.91129)
		(mid 79.176505 -285.860518)
		(end 79.361538 -285.906464)
		(width 0.09525)
		(layer "In4.Cu")
		(net "M_D_CPU1_SB_DQS_DN<2>")
	)
	(arc
		(start 85.949536 -285.91129)
		(mid 86.230968 -285.987045)
		(end 86.5124 -285.91129)
		(width 0.09525)
		(layer "In4.Cu")
		(net "M_D_CPU1_SB_DQS_DN<2>")
	)
	(arc
		(start 82.76082 -285.906464)
		(mid 82.945852 -285.86055)
		(end 83.129628 -285.91129)
		(width 0.09525)
		(layer "In4.Cu")
		(net "M_D_CPU1_SB_DQS_DN<2>")
	)
	(arc
		(start 87.829644 -285.91129)
		(mid 88.111076 -285.987045)
		(end 88.392508 -285.91129)
		(width 0.09525)
		(layer "In4.Cu")
		(net "M_D_CPU1_SB_DQS_DN<2>")
	)
	(arc
		(start 84.069682 -285.91129)
		(mid 84.351114 -285.987045)
		(end 84.632546 -285.91129)
		(width 0.09525)
		(layer "In4.Cu")
		(net "M_D_CPU1_SB_DQS_DN<2>")
	)
	(arc
		(start 83.129628 -285.91129)
		(mid 83.41106 -285.987045)
		(end 83.692492 -285.91129)
		(width 0.09525)
		(layer "In4.Cu")
		(net "M_D_CPU1_SB_DQS_DN<2>")
	)
	(arc
		(start 80.30972 -285.91129)
		(mid 80.591152 -285.987045)
		(end 80.872584 -285.91129)
		(width 0.09525)
		(layer "In4.Cu")
		(net "M_D_CPU1_SB_DQS_DN<2>")
	)
	(arc
		(start 78.711044 -285.987236)
		(mid 78.856924 -285.967931)
		(end 78.99273 -285.91129)
		(width 0.09525)
		(layer "In4.Cu")
		(net "M_D_CPU1_SB_DQS_DN<2>")
	)
	(arc
		(start 89.332562 -285.91129)
		(mid 89.52103 -285.860613)
		(end 89.709498 -285.91129)
		(width 0.09525)
		(layer "In4.Cu")
		(net "M_D_CPU1_SB_DQS_DN<2>")
	)
	(arc
		(start 79.940912 -285.906464)
		(mid 80.125944 -285.86055)
		(end 80.30972 -285.91129)
		(width 0.09525)
		(layer "In4.Cu")
		(net "M_D_CPU1_SB_DQS_DN<2>")
	)
	(arc
		(start 82.189574 -285.91129)
		(mid 82.471006 -285.987045)
		(end 82.752438 -285.91129)
		(width 0.09525)
		(layer "In4.Cu")
		(net "M_D_CPU1_SB_DQS_DN<2>")
	)
	(arc
		(start 88.769698 -285.91129)
		(mid 89.05113 -285.987045)
		(end 89.332562 -285.91129)
		(width 0.09525)
		(layer "In4.Cu")
		(net "M_D_CPU1_SB_DQS_DN<2>")
	)
	(segment
		(start 91.86799 -281.110436)
		(end 91.401138 -281.376374)
		(width 0.12954)
		(layer "F.Cu")
		(net "M_D_CPU1_SB_DQS_DN<1>")
	)
	(segment
		(start 79.93253 -281.051254)
		(end 79.940912 -281.046428)
		(width 0.09525)
		(layer "In4.Cu")
		(net "M_D_CPU1_SB_DQS_DN<1>")
	)
	(segment
		(start 76.858622 -280.720038)
		(end 78.072234 -280.720038)
		(width 0.09525)
		(layer "In4.Cu")
		(net "M_D_CPU1_SB_DQS_DN<1>")
	)
	(segment
		(start 43.320208 -294.171624)
		(end 43.679364 -293.812468)
		(width 0.16002)
		(layer "In4.Cu")
		(net "M_D_CPU1_SB_DQS_DN<1>")
	)
	(segment
		(start 45.098462 -293.812468)
		(end 45.948346 -294.662352)
		(width 0.16002)
		(layer "In4.Cu")
		(net "M_D_CPU1_SB_DQS_DN<1>")
	)
	(segment
		(start 90.64117 -281.046428)
		(end 90.649552 -281.051254)
		(width 0.09525)
		(layer "In4.Cu")
		(net "M_D_CPU1_SB_DQS_DN<1>")
	)
	(segment
		(start 76.155296 -281.082496)
		(end 76.214224 -281.023568)
		(width 0.09525)
		(layer "In4.Cu")
		(net "M_D_CPU1_SB_DQS_DN<1>")
	)
	(segment
		(start 60.738004 -294.123618)
		(end 66.449956 -288.411666)
		(width 0.16002)
		(layer "In4.Cu")
		(net "M_D_CPU1_SB_DQS_DN<1>")
	)
	(segment
		(start 36.795964 -295.085262)
		(end 37.069776 -294.81145)
		(width 0.16002)
		(layer "In4.Cu")
		(net "M_D_CPU1_SB_DQS_DN<1>")
	)
	(segment
		(start 69.491606 -284.484572)
		(end 69.670676 -284.663642)
		(width 0.16002)
		(layer "In4.Cu")
		(net "M_D_CPU1_SB_DQS_DN<1>")
	)
	(segment
		(start 72.41794 -281.916378)
		(end 72.945244 -281.916378)
		(width 0.16002)
		(layer "In4.Cu")
		(net "M_D_CPU1_SB_DQS_DN<1>")
	)
	(segment
		(start 67.823588 -287.038034)
		(end 67.823588 -286.51073)
		(width 0.16002)
		(layer "In4.Cu")
		(net "M_D_CPU1_SB_DQS_DN<1>")
	)
	(segment
		(start 87.452454 -281.051254)
		(end 87.460836 -281.046428)
		(width 0.09525)
		(layer "In4.Cu")
		(net "M_D_CPU1_SB_DQS_DN<1>")
	)
	(segment
		(start 66.744342 -287.231836)
		(end 66.923412 -287.410906)
		(width 0.16002)
		(layer "In4.Cu")
		(net "M_D_CPU1_SB_DQS_DN<1>")
	)
	(segment
		(start 42.736008 -294.171624)
		(end 43.320208 -294.171624)
		(width 0.16002)
		(layer "In4.Cu")
		(net "M_D_CPU1_SB_DQS_DN<1>")
	)
	(segment
		(start 71.765414 -281.933904)
		(end 71.96201 -281.737308)
		(width 0.16002)
		(layer "In4.Cu")
		(net "M_D_CPU1_SB_DQS_DN<1>")
	)
	(segment
		(start 66.270886 -287.428432)
		(end 66.467482 -287.231836)
		(width 0.16002)
		(layer "In4.Cu")
		(net "M_D_CPU1_SB_DQS_DN<1>")
	)
	(segment
		(start 39.419276 -294.81145)
		(end 39.568374 -294.662352)
		(width 0.16002)
		(layer "In4.Cu")
		(net "M_D_CPU1_SB_DQS_DN<1>")
	)
	(segment
		(start 76.555092 -281.023568)
		(end 76.858622 -280.720038)
		(width 0.09525)
		(layer "In4.Cu")
		(net "M_D_CPU1_SB_DQS_DN<1>")
	)
	(segment
		(start 67.841114 -285.858204)
		(end 68.117974 -285.858204)
		(width 0.16002)
		(layer "In4.Cu")
		(net "M_D_CPU1_SB_DQS_DN<1>")
	)
	(segment
		(start 86.881208 -281.046428)
		(end 86.88959 -281.051254)
		(width 0.09525)
		(layer "In4.Cu")
		(net "M_D_CPU1_SB_DQS_DN<1>")
	)
	(segment
		(start 45.948346 -294.662352)
		(end 48.52797 -294.662352)
		(width 0.16002)
		(layer "In4.Cu")
		(net "M_D_CPU1_SB_DQS_DN<1>")
	)
	(segment
		(start 69.19722 -285.137098)
		(end 69.01815 -284.958028)
		(width 0.16002)
		(layer "In4.Cu")
		(net "M_D_CPU1_SB_DQS_DN<1>")
	)
	(segment
		(start 48.840136 -294.974518)
		(end 49.479708 -294.974518)
		(width 0.16002)
		(layer "In4.Cu")
		(net "M_D_CPU1_SB_DQS_DN<1>")
	)
	(segment
		(start 66.449956 -288.411666)
		(end 66.449956 -287.884362)
		(width 0.16002)
		(layer "In4.Cu")
		(net "M_D_CPU1_SB_DQS_DN<1>")
	)
	(segment
		(start 68.297044 -286.037274)
		(end 68.824348 -286.037274)
		(width 0.16002)
		(layer "In4.Cu")
		(net "M_D_CPU1_SB_DQS_DN<1>")
	)
	(segment
		(start 66.467482 -287.231836)
		(end 66.744342 -287.231836)
		(width 0.16002)
		(layer "In4.Cu")
		(net "M_D_CPU1_SB_DQS_DN<1>")
	)
	(segment
		(start 78.429866 -281.051254)
		(end 78.444598 -281.05989)
		(width 0.09525)
		(layer "In4.Cu")
		(net "M_D_CPU1_SB_DQS_DN<1>")
	)
	(segment
		(start 52.227734 -293.812468)
		(end 53.402484 -294.987218)
		(width 0.16002)
		(layer "In4.Cu")
		(net "M_D_CPU1_SB_DQS_DN<1>")
	)
	(segment
		(start 79.922116 -281.05735)
		(end 79.93253 -281.051254)
		(width 0.09525)
		(layer "In4.Cu")
		(net "M_D_CPU1_SB_DQS_DN<1>")
	)
	(segment
		(start 71.944484 -282.917138)
		(end 71.944484 -282.389834)
		(width 0.16002)
		(layer "In4.Cu")
		(net "M_D_CPU1_SB_DQS_DN<1>")
	)
	(segment
		(start 57.874408 -294.123618)
		(end 60.738004 -294.123618)
		(width 0.16002)
		(layer "In4.Cu")
		(net "M_D_CPU1_SB_DQS_DN<1>")
	)
	(segment
		(start 71.96201 -281.737308)
		(end 72.23887 -281.737308)
		(width 0.16002)
		(layer "In4.Cu")
		(net "M_D_CPU1_SB_DQS_DN<1>")
	)
	(segment
		(start 39.568374 -294.662352)
		(end 40.969692 -294.662352)
		(width 0.16002)
		(layer "In4.Cu")
		(net "M_D_CPU1_SB_DQS_DN<1>")
	)
	(segment
		(start 66.923412 -287.410906)
		(end 67.450716 -287.410906)
		(width 0.16002)
		(layer "In4.Cu")
		(net "M_D_CPU1_SB_DQS_DN<1>")
	)
	(segment
		(start 69.19722 -285.664402)
		(end 69.19722 -285.137098)
		(width 0.16002)
		(layer "In4.Cu")
		(net "M_D_CPU1_SB_DQS_DN<1>")
	)
	(segment
		(start 68.117974 -285.858204)
		(end 68.297044 -286.037274)
		(width 0.16002)
		(layer "In4.Cu")
		(net "M_D_CPU1_SB_DQS_DN<1>")
	)
	(segment
		(start 50.724308 -294.212518)
		(end 51.124358 -293.812468)
		(width 0.16002)
		(layer "In4.Cu")
		(net "M_D_CPU1_SB_DQS_DN<1>")
	)
	(segment
		(start 69.670676 -284.663642)
		(end 70.19798 -284.663642)
		(width 0.16002)
		(layer "In4.Cu")
		(net "M_D_CPU1_SB_DQS_DN<1>")
	)
	(segment
		(start 53.402484 -294.987218)
		(end 57.010808 -294.987218)
		(width 0.16002)
		(layer "In4.Cu")
		(net "M_D_CPU1_SB_DQS_DN<1>")
	)
	(segment
		(start 70.865238 -283.11094)
		(end 71.044308 -283.29001)
		(width 0.16002)
		(layer "In4.Cu")
		(net "M_D_CPU1_SB_DQS_DN<1>")
	)
	(segment
		(start 71.765414 -282.210764)
		(end 71.765414 -281.933904)
		(width 0.16002)
		(layer "In4.Cu")
		(net "M_D_CPU1_SB_DQS_DN<1>")
	)
	(segment
		(start 91.247214 -281.110944)
		(end 91.401138 -281.376374)
		(width 0.09525)
		(layer "In4.Cu")
		(net "M_D_CPU1_SB_DQS_DN<1>")
	)
	(segment
		(start 71.044308 -283.29001)
		(end 71.571612 -283.29001)
		(width 0.16002)
		(layer "In4.Cu")
		(net "M_D_CPU1_SB_DQS_DN<1>")
	)
	(segment
		(start 67.450716 -287.410906)
		(end 67.823588 -287.038034)
		(width 0.16002)
		(layer "In4.Cu")
		(net "M_D_CPU1_SB_DQS_DN<1>")
	)
	(segment
		(start 57.010808 -294.987218)
		(end 57.874408 -294.123618)
		(width 0.16002)
		(layer "In4.Cu")
		(net "M_D_CPU1_SB_DQS_DN<1>")
	)
	(segment
		(start 41.32961 -295.02227)
		(end 41.885362 -295.02227)
		(width 0.16002)
		(layer "In4.Cu")
		(net "M_D_CPU1_SB_DQS_DN<1>")
	)
	(segment
		(start 70.19798 -284.663642)
		(end 70.570852 -284.29077)
		(width 0.16002)
		(layer "In4.Cu")
		(net "M_D_CPU1_SB_DQS_DN<1>")
	)
	(segment
		(start 66.449956 -287.884362)
		(end 66.270886 -287.705292)
		(width 0.16002)
		(layer "In4.Cu")
		(net "M_D_CPU1_SB_DQS_DN<1>")
	)
	(segment
		(start 66.270886 -287.705292)
		(end 66.270886 -287.428432)
		(width 0.16002)
		(layer "In4.Cu")
		(net "M_D_CPU1_SB_DQS_DN<1>")
	)
	(segment
		(start 67.823588 -286.51073)
		(end 67.644518 -286.33166)
		(width 0.16002)
		(layer "In4.Cu")
		(net "M_D_CPU1_SB_DQS_DN<1>")
	)
	(segment
		(start 67.644518 -286.33166)
		(end 67.644518 -286.0548)
		(width 0.16002)
		(layer "In4.Cu")
		(net "M_D_CPU1_SB_DQS_DN<1>")
	)
	(segment
		(start 85.941154 -281.046428)
		(end 85.949536 -281.051254)
		(width 0.09525)
		(layer "In4.Cu")
		(net "M_D_CPU1_SB_DQS_DN<1>")
	)
	(segment
		(start 82.752438 -281.051254)
		(end 82.76082 -281.046428)
		(width 0.09525)
		(layer "In4.Cu")
		(net "M_D_CPU1_SB_DQS_DN<1>")
	)
	(segment
		(start 41.885362 -295.02227)
		(end 42.736008 -294.171624)
		(width 0.16002)
		(layer "In4.Cu")
		(net "M_D_CPU1_SB_DQS_DN<1>")
	)
	(segment
		(start 70.588378 -283.11094)
		(end 70.865238 -283.11094)
		(width 0.16002)
		(layer "In4.Cu")
		(net "M_D_CPU1_SB_DQS_DN<1>")
	)
	(segment
		(start 40.969692 -294.662352)
		(end 41.32961 -295.02227)
		(width 0.16002)
		(layer "In4.Cu")
		(net "M_D_CPU1_SB_DQS_DN<1>")
	)
	(segment
		(start 70.391782 -283.307536)
		(end 70.588378 -283.11094)
		(width 0.16002)
		(layer "In4.Cu")
		(net "M_D_CPU1_SB_DQS_DN<1>")
	)
	(segment
		(start 69.01815 -284.958028)
		(end 69.01815 -284.681168)
		(width 0.16002)
		(layer "In4.Cu")
		(net "M_D_CPU1_SB_DQS_DN<1>")
	)
	(segment
		(start 72.23887 -281.737308)
		(end 72.41794 -281.916378)
		(width 0.16002)
		(layer "In4.Cu")
		(net "M_D_CPU1_SB_DQS_DN<1>")
	)
	(segment
		(start 68.824348 -286.037274)
		(end 69.19722 -285.664402)
		(width 0.16002)
		(layer "In4.Cu")
		(net "M_D_CPU1_SB_DQS_DN<1>")
	)
	(segment
		(start 91.146376 -281.084274)
		(end 91.247214 -281.110944)
		(width 0.09525)
		(layer "In4.Cu")
		(net "M_D_CPU1_SB_DQS_DN<1>")
	)
	(segment
		(start 72.945244 -281.916378)
		(end 73.779126 -281.082496)
		(width 0.16002)
		(layer "In4.Cu")
		(net "M_D_CPU1_SB_DQS_DN<1>")
	)
	(segment
		(start 71.571612 -283.29001)
		(end 71.944484 -282.917138)
		(width 0.16002)
		(layer "In4.Cu")
		(net "M_D_CPU1_SB_DQS_DN<1>")
	)
	(segment
		(start 79.361538 -281.046428)
		(end 79.36992 -281.051254)
		(width 0.09525)
		(layer "In4.Cu")
		(net "M_D_CPU1_SB_DQS_DN<1>")
	)
	(segment
		(start 78.072234 -280.720038)
		(end 78.314804 -280.962608)
		(width 0.09525)
		(layer "In4.Cu")
		(net "M_D_CPU1_SB_DQS_DN<1>")
	)
	(segment
		(start 70.391782 -283.584396)
		(end 70.391782 -283.307536)
		(width 0.16002)
		(layer "In4.Cu")
		(net "M_D_CPU1_SB_DQS_DN<1>")
	)
	(segment
		(start 67.644518 -286.0548)
		(end 67.841114 -285.858204)
		(width 0.16002)
		(layer "In4.Cu")
		(net "M_D_CPU1_SB_DQS_DN<1>")
	)
	(segment
		(start 71.944484 -282.389834)
		(end 71.765414 -282.210764)
		(width 0.16002)
		(layer "In4.Cu")
		(net "M_D_CPU1_SB_DQS_DN<1>")
	)
	(segment
		(start 70.570852 -283.763466)
		(end 70.391782 -283.584396)
		(width 0.16002)
		(layer "In4.Cu")
		(net "M_D_CPU1_SB_DQS_DN<1>")
	)
	(segment
		(start 76.214224 -281.023568)
		(end 76.555092 -281.023568)
		(width 0.09525)
		(layer "In4.Cu")
		(net "M_D_CPU1_SB_DQS_DN<1>")
	)
	(segment
		(start 49.479708 -294.974518)
		(end 50.241708 -294.212518)
		(width 0.16002)
		(layer "In4.Cu")
		(net "M_D_CPU1_SB_DQS_DN<1>")
	)
	(segment
		(start 50.241708 -294.212518)
		(end 50.724308 -294.212518)
		(width 0.16002)
		(layer "In4.Cu")
		(net "M_D_CPU1_SB_DQS_DN<1>")
	)
	(segment
		(start 88.392508 -281.051254)
		(end 88.40089 -281.046428)
		(width 0.09525)
		(layer "In4.Cu")
		(net "M_D_CPU1_SB_DQS_DN<1>")
	)
	(segment
		(start 76.131674 -281.082496)
		(end 76.155296 -281.082496)
		(width 0.09525)
		(layer "In4.Cu")
		(net "M_D_CPU1_SB_DQS_DN<1>")
	)
	(segment
		(start 43.679364 -293.812468)
		(end 45.098462 -293.812468)
		(width 0.16002)
		(layer "In4.Cu")
		(net "M_D_CPU1_SB_DQS_DN<1>")
	)
	(segment
		(start 69.214746 -284.484572)
		(end 69.491606 -284.484572)
		(width 0.16002)
		(layer "In4.Cu")
		(net "M_D_CPU1_SB_DQS_DN<1>")
	)
	(segment
		(start 48.52797 -294.662352)
		(end 48.840136 -294.974518)
		(width 0.16002)
		(layer "In4.Cu")
		(net "M_D_CPU1_SB_DQS_DN<1>")
	)
	(segment
		(start 73.779126 -281.082496)
		(end 76.131674 -281.082496)
		(width 0.16002)
		(layer "In4.Cu")
		(net "M_D_CPU1_SB_DQS_DN<1>")
	)
	(segment
		(start 82.181192 -281.046428)
		(end 82.189574 -281.051254)
		(width 0.09525)
		(layer "In4.Cu")
		(net "M_D_CPU1_SB_DQS_DN<1>")
	)
	(segment
		(start 69.01815 -284.681168)
		(end 69.214746 -284.484572)
		(width 0.16002)
		(layer "In4.Cu")
		(net "M_D_CPU1_SB_DQS_DN<1>")
	)
	(segment
		(start 83.692492 -281.051254)
		(end 83.700874 -281.046428)
		(width 0.09525)
		(layer "In4.Cu")
		(net "M_D_CPU1_SB_DQS_DN<1>")
	)
	(segment
		(start 51.124358 -293.812468)
		(end 52.227734 -293.812468)
		(width 0.16002)
		(layer "In4.Cu")
		(net "M_D_CPU1_SB_DQS_DN<1>")
	)
	(segment
		(start 37.069776 -294.81145)
		(end 39.419276 -294.81145)
		(width 0.16002)
		(layer "In4.Cu")
		(net "M_D_CPU1_SB_DQS_DN<1>")
	)
	(segment
		(start 70.570852 -284.29077)
		(end 70.570852 -283.763466)
		(width 0.16002)
		(layer "In4.Cu")
		(net "M_D_CPU1_SB_DQS_DN<1>")
	)
	(arc
		(start 80.30972 -281.051254)
		(mid 80.591152 -281.127009)
		(end 80.872584 -281.051254)
		(width 0.09525)
		(layer "In4.Cu")
		(net "M_D_CPU1_SB_DQS_DN<1>")
	)
	(arc
		(start 85.572346 -281.051254)
		(mid 85.756121 -281.000482)
		(end 85.941154 -281.046428)
		(width 0.09525)
		(layer "In4.Cu")
		(net "M_D_CPU1_SB_DQS_DN<1>")
	)
	(arc
		(start 91.125802 -281.092402)
		(mid 91.13613 -281.088442)
		(end 91.146376 -281.084274)
		(width 0.09525)
		(layer "In4.Cu")
		(net "M_D_CPU1_SB_DQS_DN<1>")
	)
	(arc
		(start 85.949536 -281.051254)
		(mid 86.230968 -281.127009)
		(end 86.5124 -281.051254)
		(width 0.09525)
		(layer "In4.Cu")
		(net "M_D_CPU1_SB_DQS_DN<1>")
	)
	(arc
		(start 79.36992 -281.051254)
		(mid 79.645209 -281.126975)
		(end 79.922116 -281.05735)
		(width 0.09525)
		(layer "In4.Cu")
		(net "M_D_CPU1_SB_DQS_DN<1>")
	)
	(arc
		(start 86.5124 -281.051254)
		(mid 86.696175 -281.000482)
		(end 86.881208 -281.046428)
		(width 0.09525)
		(layer "In4.Cu")
		(net "M_D_CPU1_SB_DQS_DN<1>")
	)
	(arc
		(start 78.444598 -281.05989)
		(mid 78.719803 -281.127154)
		(end 78.99273 -281.051254)
		(width 0.09525)
		(layer "In4.Cu")
		(net "M_D_CPU1_SB_DQS_DN<1>")
	)
	(arc
		(start 90.649552 -281.051254)
		(mid 90.883066 -281.125097)
		(end 91.125802 -281.092402)
		(width 0.09525)
		(layer "In4.Cu")
		(net "M_D_CPU1_SB_DQS_DN<1>")
	)
	(arc
		(start 82.76082 -281.046428)
		(mid 82.945852 -281.000514)
		(end 83.129628 -281.051254)
		(width 0.09525)
		(layer "In4.Cu")
		(net "M_D_CPU1_SB_DQS_DN<1>")
	)
	(arc
		(start 83.700874 -281.046428)
		(mid 83.885906 -281.000514)
		(end 84.069682 -281.051254)
		(width 0.09525)
		(layer "In4.Cu")
		(net "M_D_CPU1_SB_DQS_DN<1>")
	)
	(arc
		(start 79.940912 -281.046428)
		(mid 80.125944 -281.000514)
		(end 80.30972 -281.051254)
		(width 0.09525)
		(layer "In4.Cu")
		(net "M_D_CPU1_SB_DQS_DN<1>")
	)
	(arc
		(start 85.009482 -281.051254)
		(mid 85.290914 -281.127009)
		(end 85.572346 -281.051254)
		(width 0.09525)
		(layer "In4.Cu")
		(net "M_D_CPU1_SB_DQS_DN<1>")
	)
	(arc
		(start 89.709498 -281.051254)
		(mid 89.99093 -281.127009)
		(end 90.272362 -281.051254)
		(width 0.09525)
		(layer "In4.Cu")
		(net "M_D_CPU1_SB_DQS_DN<1>")
	)
	(arc
		(start 81.24952 -281.051254)
		(mid 81.530952 -281.127009)
		(end 81.812384 -281.051254)
		(width 0.09525)
		(layer "In4.Cu")
		(net "M_D_CPU1_SB_DQS_DN<1>")
	)
	(arc
		(start 88.769698 -281.051254)
		(mid 89.05113 -281.127009)
		(end 89.332562 -281.051254)
		(width 0.09525)
		(layer "In4.Cu")
		(net "M_D_CPU1_SB_DQS_DN<1>")
	)
	(arc
		(start 78.99273 -281.051254)
		(mid 79.176505 -281.000482)
		(end 79.361538 -281.046428)
		(width 0.09525)
		(layer "In4.Cu")
		(net "M_D_CPU1_SB_DQS_DN<1>")
	)
	(arc
		(start 82.189574 -281.051254)
		(mid 82.471006 -281.127009)
		(end 82.752438 -281.051254)
		(width 0.09525)
		(layer "In4.Cu")
		(net "M_D_CPU1_SB_DQS_DN<1>")
	)
	(arc
		(start 88.40089 -281.046428)
		(mid 88.585922 -281.000514)
		(end 88.769698 -281.051254)
		(width 0.09525)
		(layer "In4.Cu")
		(net "M_D_CPU1_SB_DQS_DN<1>")
	)
	(arc
		(start 84.069682 -281.051254)
		(mid 84.351114 -281.127009)
		(end 84.632546 -281.051254)
		(width 0.09525)
		(layer "In4.Cu")
		(net "M_D_CPU1_SB_DQS_DN<1>")
	)
	(arc
		(start 86.88959 -281.051254)
		(mid 87.171022 -281.127009)
		(end 87.452454 -281.051254)
		(width 0.09525)
		(layer "In4.Cu")
		(net "M_D_CPU1_SB_DQS_DN<1>")
	)
	(arc
		(start 78.314804 -280.962608)
		(mid 78.369452 -281.010673)
		(end 78.429866 -281.051254)
		(width 0.09525)
		(layer "In4.Cu")
		(net "M_D_CPU1_SB_DQS_DN<1>")
	)
	(arc
		(start 89.332562 -281.051254)
		(mid 89.52103 -281.000577)
		(end 89.709498 -281.051254)
		(width 0.09525)
		(layer "In4.Cu")
		(net "M_D_CPU1_SB_DQS_DN<1>")
	)
	(arc
		(start 87.829644 -281.051254)
		(mid 88.111076 -281.127009)
		(end 88.392508 -281.051254)
		(width 0.09525)
		(layer "In4.Cu")
		(net "M_D_CPU1_SB_DQS_DN<1>")
	)
	(arc
		(start 80.872584 -281.051254)
		(mid 81.061052 -281.000577)
		(end 81.24952 -281.051254)
		(width 0.09525)
		(layer "In4.Cu")
		(net "M_D_CPU1_SB_DQS_DN<1>")
	)
	(arc
		(start 84.632546 -281.051254)
		(mid 84.821014 -281.000577)
		(end 85.009482 -281.051254)
		(width 0.09525)
		(layer "In4.Cu")
		(net "M_D_CPU1_SB_DQS_DN<1>")
	)
	(arc
		(start 90.272362 -281.051254)
		(mid 90.456137 -281.000482)
		(end 90.64117 -281.046428)
		(width 0.09525)
		(layer "In4.Cu")
		(net "M_D_CPU1_SB_DQS_DN<1>")
	)
	(arc
		(start 87.460836 -281.046428)
		(mid 87.645868 -281.000514)
		(end 87.829644 -281.051254)
		(width 0.09525)
		(layer "In4.Cu")
		(net "M_D_CPU1_SB_DQS_DN<1>")
	)
	(arc
		(start 81.812384 -281.051254)
		(mid 81.996159 -281.000482)
		(end 82.181192 -281.046428)
		(width 0.09525)
		(layer "In4.Cu")
		(net "M_D_CPU1_SB_DQS_DN<1>")
	)
	(arc
		(start 83.129628 -281.051254)
		(mid 83.41106 -281.127009)
		(end 83.692492 -281.051254)
		(width 0.09525)
		(layer "In4.Cu")
		(net "M_D_CPU1_SB_DQS_DN<1>")
	)
	(segment
		(start 91.86799 -276.2504)
		(end 91.401138 -276.516338)
		(width 0.12954)
		(layer "F.Cu")
		(net "M_D_CPU1_SB_DQS_DN<0>")
	)
	(segment
		(start 62.448948 -281.756104)
		(end 62.725808 -281.756104)
		(width 0.16002)
		(layer "In4.Cu")
		(net "M_D_CPU1_SB_DQS_DN<0>")
	)
	(segment
		(start 62.359794 -282.862782)
		(end 62.359794 -282.335478)
		(width 0.16002)
		(layer "In4.Cu")
		(net "M_D_CPU1_SB_DQS_DN<0>")
	)
	(segment
		(start 63.359792 -281.862784)
		(end 63.733426 -281.48915)
		(width 0.16002)
		(layer "In4.Cu")
		(net "M_D_CPU1_SB_DQS_DN<0>")
	)
	(segment
		(start 65.196212 -279.00884)
		(end 65.473072 -279.00884)
		(width 0.16002)
		(layer "In4.Cu")
		(net "M_D_CPU1_SB_DQS_DN<0>")
	)
	(segment
		(start 82.181192 -276.186392)
		(end 82.189574 -276.191218)
		(width 0.09525)
		(layer "In4.Cu")
		(net "M_D_CPU1_SB_DQS_DN<0>")
	)
	(segment
		(start 61.458856 -283.236416)
		(end 61.98616 -283.236416)
		(width 0.16002)
		(layer "In4.Cu")
		(net "M_D_CPU1_SB_DQS_DN<0>")
	)
	(segment
		(start 50.724308 -284.862524)
		(end 51.124358 -284.462474)
		(width 0.16002)
		(layer "In4.Cu")
		(net "M_D_CPU1_SB_DQS_DN<0>")
	)
	(segment
		(start 77.192886 -275.400516)
		(end 78.059534 -276.267164)
		(width 0.09525)
		(layer "In4.Cu")
		(net "M_D_CPU1_SB_DQS_DN<0>")
	)
	(segment
		(start 55.38597 -285.637224)
		(end 55.77967 -286.030924)
		(width 0.16002)
		(layer "In4.Cu")
		(net "M_D_CPU1_SB_DQS_DN<0>")
	)
	(segment
		(start 66.569844 -277.635208)
		(end 66.846704 -277.635208)
		(width 0.16002)
		(layer "In4.Cu")
		(net "M_D_CPU1_SB_DQS_DN<0>")
	)
	(segment
		(start 87.452454 -276.191218)
		(end 87.460836 -276.186392)
		(width 0.09525)
		(layer "In4.Cu")
		(net "M_D_CPU1_SB_DQS_DN<0>")
	)
	(segment
		(start 62.253114 -281.951938)
		(end 62.448948 -281.756104)
		(width 0.16002)
		(layer "In4.Cu")
		(net "M_D_CPU1_SB_DQS_DN<0>")
	)
	(segment
		(start 67.747642 -276.73427)
		(end 67.747642 -276.45741)
		(width 0.16002)
		(layer "In4.Cu")
		(net "M_D_CPU1_SB_DQS_DN<0>")
	)
	(segment
		(start 52.224686 -284.462474)
		(end 53.399436 -285.637224)
		(width 0.16002)
		(layer "In4.Cu")
		(net "M_D_CPU1_SB_DQS_DN<0>")
	)
	(segment
		(start 91.146376 -276.224238)
		(end 91.247214 -276.250908)
		(width 0.09525)
		(layer "In4.Cu")
		(net "M_D_CPU1_SB_DQS_DN<0>")
	)
	(segment
		(start 56.617108 -286.030924)
		(end 57.785508 -284.862524)
		(width 0.16002)
		(layer "In4.Cu")
		(net "M_D_CPU1_SB_DQS_DN<0>")
	)
	(segment
		(start 90.64117 -276.186392)
		(end 90.649552 -276.191218)
		(width 0.09525)
		(layer "In4.Cu")
		(net "M_D_CPU1_SB_DQS_DN<0>")
	)
	(segment
		(start 82.752438 -276.191218)
		(end 82.76082 -276.186392)
		(width 0.09525)
		(layer "In4.Cu")
		(net "M_D_CPU1_SB_DQS_DN<0>")
	)
	(segment
		(start 59.978544 -284.503368)
		(end 60.085224 -284.610048)
		(width 0.16002)
		(layer "In4.Cu")
		(net "M_D_CPU1_SB_DQS_DN<0>")
	)
	(segment
		(start 75.979528 -275.459444)
		(end 76.038456 -275.400516)
		(width 0.09525)
		(layer "In4.Cu")
		(net "M_D_CPU1_SB_DQS_DN<0>")
	)
	(segment
		(start 40.98417 -285.312358)
		(end 41.321736 -285.649924)
		(width 0.16002)
		(layer "In4.Cu")
		(net "M_D_CPU1_SB_DQS_DN<0>")
	)
	(segment
		(start 41.321736 -285.649924)
		(end 41.918636 -285.649924)
		(width 0.16002)
		(layer "In4.Cu")
		(net "M_D_CPU1_SB_DQS_DN<0>")
	)
	(segment
		(start 36.795964 -285.735268)
		(end 37.069776 -285.461456)
		(width 0.16002)
		(layer "In4.Cu")
		(net "M_D_CPU1_SB_DQS_DN<0>")
	)
	(segment
		(start 63.82258 -280.382472)
		(end 64.09944 -280.382472)
		(width 0.16002)
		(layer "In4.Cu")
		(net "M_D_CPU1_SB_DQS_DN<0>")
	)
	(segment
		(start 50.241708 -284.862524)
		(end 50.724308 -284.862524)
		(width 0.16002)
		(layer "In4.Cu")
		(net "M_D_CPU1_SB_DQS_DN<0>")
	)
	(segment
		(start 60.879482 -283.32557)
		(end 61.075316 -283.129736)
		(width 0.16002)
		(layer "In4.Cu")
		(net "M_D_CPU1_SB_DQS_DN<0>")
	)
	(segment
		(start 64.20612 -280.489152)
		(end 64.733424 -280.489152)
		(width 0.16002)
		(layer "In4.Cu")
		(net "M_D_CPU1_SB_DQS_DN<0>")
	)
	(segment
		(start 65.107058 -279.588214)
		(end 65.000378 -279.481534)
		(width 0.16002)
		(layer "In4.Cu")
		(net "M_D_CPU1_SB_DQS_DN<0>")
	)
	(segment
		(start 91.247214 -276.250908)
		(end 91.401138 -276.516338)
		(width 0.09525)
		(layer "In4.Cu")
		(net "M_D_CPU1_SB_DQS_DN<0>")
	)
	(segment
		(start 60.085224 -284.610048)
		(end 60.612528 -284.610048)
		(width 0.16002)
		(layer "In4.Cu")
		(net "M_D_CPU1_SB_DQS_DN<0>")
	)
	(segment
		(start 67.854322 -277.368254)
		(end 67.854322 -276.84095)
		(width 0.16002)
		(layer "In4.Cu")
		(net "M_D_CPU1_SB_DQS_DN<0>")
	)
	(segment
		(start 66.953384 -277.741888)
		(end 67.480688 -277.741888)
		(width 0.16002)
		(layer "In4.Cu")
		(net "M_D_CPU1_SB_DQS_DN<0>")
	)
	(segment
		(start 65.000378 -279.204674)
		(end 65.196212 -279.00884)
		(width 0.16002)
		(layer "In4.Cu")
		(net "M_D_CPU1_SB_DQS_DN<0>")
	)
	(segment
		(start 65.107058 -280.115518)
		(end 65.107058 -279.588214)
		(width 0.16002)
		(layer "In4.Cu")
		(net "M_D_CPU1_SB_DQS_DN<0>")
	)
	(segment
		(start 68.745608 -275.459444)
		(end 75.955906 -275.459444)
		(width 0.16002)
		(layer "In4.Cu")
		(net "M_D_CPU1_SB_DQS_DN<0>")
	)
	(segment
		(start 41.918636 -285.649924)
		(end 42.706036 -284.862524)
		(width 0.16002)
		(layer "In4.Cu")
		(net "M_D_CPU1_SB_DQS_DN<0>")
	)
	(segment
		(start 45.42917 -285.312358)
		(end 48.07077 -285.312358)
		(width 0.16002)
		(layer "In4.Cu")
		(net "M_D_CPU1_SB_DQS_DN<0>")
	)
	(segment
		(start 66.48069 -278.741886)
		(end 66.48069 -278.214582)
		(width 0.16002)
		(layer "In4.Cu")
		(net "M_D_CPU1_SB_DQS_DN<0>")
	)
	(segment
		(start 48.593756 -285.835344)
		(end 49.268888 -285.835344)
		(width 0.16002)
		(layer "In4.Cu")
		(net "M_D_CPU1_SB_DQS_DN<0>")
	)
	(segment
		(start 76.038456 -275.400516)
		(end 77.192886 -275.400516)
		(width 0.09525)
		(layer "In4.Cu")
		(net "M_D_CPU1_SB_DQS_DN<0>")
	)
	(segment
		(start 62.725808 -281.756104)
		(end 62.832488 -281.862784)
		(width 0.16002)
		(layer "In4.Cu")
		(net "M_D_CPU1_SB_DQS_DN<0>")
	)
	(segment
		(start 80.301338 -276.186392)
		(end 80.30972 -276.191218)
		(width 0.09525)
		(layer "In4.Cu")
		(net "M_D_CPU1_SB_DQS_DN<0>")
	)
	(segment
		(start 67.747642 -276.45741)
		(end 68.745608 -275.459444)
		(width 0.16002)
		(layer "In4.Cu")
		(net "M_D_CPU1_SB_DQS_DN<0>")
	)
	(segment
		(start 78.059534 -276.267164)
		(end 79.650336 -276.267164)
		(width 0.09525)
		(layer "In4.Cu")
		(net "M_D_CPU1_SB_DQS_DN<0>")
	)
	(segment
		(start 63.733426 -281.48915)
		(end 63.733426 -280.961846)
		(width 0.16002)
		(layer "In4.Cu")
		(net "M_D_CPU1_SB_DQS_DN<0>")
	)
	(segment
		(start 85.941154 -276.186392)
		(end 85.949536 -276.191218)
		(width 0.09525)
		(layer "In4.Cu")
		(net "M_D_CPU1_SB_DQS_DN<0>")
	)
	(segment
		(start 55.77967 -286.030924)
		(end 56.617108 -286.030924)
		(width 0.16002)
		(layer "In4.Cu")
		(net "M_D_CPU1_SB_DQS_DN<0>")
	)
	(segment
		(start 83.692492 -276.191218)
		(end 83.700874 -276.186392)
		(width 0.09525)
		(layer "In4.Cu")
		(net "M_D_CPU1_SB_DQS_DN<0>")
	)
	(segment
		(start 62.359794 -282.335478)
		(end 62.253114 -282.228798)
		(width 0.16002)
		(layer "In4.Cu")
		(net "M_D_CPU1_SB_DQS_DN<0>")
	)
	(segment
		(start 66.846704 -277.635208)
		(end 66.953384 -277.741888)
		(width 0.16002)
		(layer "In4.Cu")
		(net "M_D_CPU1_SB_DQS_DN<0>")
	)
	(segment
		(start 66.37401 -278.107902)
		(end 66.37401 -277.831042)
		(width 0.16002)
		(layer "In4.Cu")
		(net "M_D_CPU1_SB_DQS_DN<0>")
	)
	(segment
		(start 59.701684 -284.503368)
		(end 59.978544 -284.503368)
		(width 0.16002)
		(layer "In4.Cu")
		(net "M_D_CPU1_SB_DQS_DN<0>")
	)
	(segment
		(start 64.733424 -280.489152)
		(end 65.107058 -280.115518)
		(width 0.16002)
		(layer "In4.Cu")
		(net "M_D_CPU1_SB_DQS_DN<0>")
	)
	(segment
		(start 63.733426 -280.961846)
		(end 63.626746 -280.855166)
		(width 0.16002)
		(layer "In4.Cu")
		(net "M_D_CPU1_SB_DQS_DN<0>")
	)
	(segment
		(start 39.254176 -285.461456)
		(end 39.403274 -285.312358)
		(width 0.16002)
		(layer "In4.Cu")
		(net "M_D_CPU1_SB_DQS_DN<0>")
	)
	(segment
		(start 86.881208 -276.186392)
		(end 86.88959 -276.191218)
		(width 0.09525)
		(layer "In4.Cu")
		(net "M_D_CPU1_SB_DQS_DN<0>")
	)
	(segment
		(start 75.955906 -275.459444)
		(end 75.979528 -275.459444)
		(width 0.09525)
		(layer "In4.Cu")
		(net "M_D_CPU1_SB_DQS_DN<0>")
	)
	(segment
		(start 59.342528 -284.862524)
		(end 59.701684 -284.503368)
		(width 0.16002)
		(layer "In4.Cu")
		(net "M_D_CPU1_SB_DQS_DN<0>")
	)
	(segment
		(start 65.473072 -279.00884)
		(end 65.579752 -279.11552)
		(width 0.16002)
		(layer "In4.Cu")
		(net "M_D_CPU1_SB_DQS_DN<0>")
	)
	(segment
		(start 63.626746 -280.855166)
		(end 63.626746 -280.578306)
		(width 0.16002)
		(layer "In4.Cu")
		(net "M_D_CPU1_SB_DQS_DN<0>")
	)
	(segment
		(start 62.832488 -281.862784)
		(end 63.359792 -281.862784)
		(width 0.16002)
		(layer "In4.Cu")
		(net "M_D_CPU1_SB_DQS_DN<0>")
	)
	(segment
		(start 88.392508 -276.191218)
		(end 88.40089 -276.186392)
		(width 0.09525)
		(layer "In4.Cu")
		(net "M_D_CPU1_SB_DQS_DN<0>")
	)
	(segment
		(start 60.612528 -284.610048)
		(end 60.986162 -284.236414)
		(width 0.16002)
		(layer "In4.Cu")
		(net "M_D_CPU1_SB_DQS_DN<0>")
	)
	(segment
		(start 61.075316 -283.129736)
		(end 61.352176 -283.129736)
		(width 0.16002)
		(layer "In4.Cu")
		(net "M_D_CPU1_SB_DQS_DN<0>")
	)
	(segment
		(start 49.268888 -285.835344)
		(end 50.241708 -284.862524)
		(width 0.16002)
		(layer "In4.Cu")
		(net "M_D_CPU1_SB_DQS_DN<0>")
	)
	(segment
		(start 67.854322 -276.84095)
		(end 67.747642 -276.73427)
		(width 0.16002)
		(layer "In4.Cu")
		(net "M_D_CPU1_SB_DQS_DN<0>")
	)
	(segment
		(start 61.98616 -283.236416)
		(end 62.359794 -282.862782)
		(width 0.16002)
		(layer "In4.Cu")
		(net "M_D_CPU1_SB_DQS_DN<0>")
	)
	(segment
		(start 43.614086 -284.462474)
		(end 44.579286 -284.462474)
		(width 0.16002)
		(layer "In4.Cu")
		(net "M_D_CPU1_SB_DQS_DN<0>")
	)
	(segment
		(start 65.000378 -279.481534)
		(end 65.000378 -279.204674)
		(width 0.16002)
		(layer "In4.Cu")
		(net "M_D_CPU1_SB_DQS_DN<0>")
	)
	(segment
		(start 57.785508 -284.862524)
		(end 59.342528 -284.862524)
		(width 0.16002)
		(layer "In4.Cu")
		(net "M_D_CPU1_SB_DQS_DN<0>")
	)
	(segment
		(start 48.07077 -285.312358)
		(end 48.593756 -285.835344)
		(width 0.16002)
		(layer "In4.Cu")
		(net "M_D_CPU1_SB_DQS_DN<0>")
	)
	(segment
		(start 63.626746 -280.578306)
		(end 63.82258 -280.382472)
		(width 0.16002)
		(layer "In4.Cu")
		(net "M_D_CPU1_SB_DQS_DN<0>")
	)
	(segment
		(start 53.399436 -285.637224)
		(end 55.38597 -285.637224)
		(width 0.16002)
		(layer "In4.Cu")
		(net "M_D_CPU1_SB_DQS_DN<0>")
	)
	(segment
		(start 60.879482 -283.60243)
		(end 60.879482 -283.32557)
		(width 0.16002)
		(layer "In4.Cu")
		(net "M_D_CPU1_SB_DQS_DN<0>")
	)
	(segment
		(start 64.09944 -280.382472)
		(end 64.20612 -280.489152)
		(width 0.16002)
		(layer "In4.Cu")
		(net "M_D_CPU1_SB_DQS_DN<0>")
	)
	(segment
		(start 51.124358 -284.462474)
		(end 52.224686 -284.462474)
		(width 0.16002)
		(layer "In4.Cu")
		(net "M_D_CPU1_SB_DQS_DN<0>")
	)
	(segment
		(start 66.37401 -277.831042)
		(end 66.569844 -277.635208)
		(width 0.16002)
		(layer "In4.Cu")
		(net "M_D_CPU1_SB_DQS_DN<0>")
	)
	(segment
		(start 37.069776 -285.461456)
		(end 39.254176 -285.461456)
		(width 0.16002)
		(layer "In4.Cu")
		(net "M_D_CPU1_SB_DQS_DN<0>")
	)
	(segment
		(start 44.579286 -284.462474)
		(end 45.42917 -285.312358)
		(width 0.16002)
		(layer "In4.Cu")
		(net "M_D_CPU1_SB_DQS_DN<0>")
	)
	(segment
		(start 60.986162 -284.236414)
		(end 60.986162 -283.70911)
		(width 0.16002)
		(layer "In4.Cu")
		(net "M_D_CPU1_SB_DQS_DN<0>")
	)
	(segment
		(start 39.403274 -285.312358)
		(end 40.98417 -285.312358)
		(width 0.16002)
		(layer "In4.Cu")
		(net "M_D_CPU1_SB_DQS_DN<0>")
	)
	(segment
		(start 65.579752 -279.11552)
		(end 66.107056 -279.11552)
		(width 0.16002)
		(layer "In4.Cu")
		(net "M_D_CPU1_SB_DQS_DN<0>")
	)
	(segment
		(start 62.253114 -282.228798)
		(end 62.253114 -281.951938)
		(width 0.16002)
		(layer "In4.Cu")
		(net "M_D_CPU1_SB_DQS_DN<0>")
	)
	(segment
		(start 66.107056 -279.11552)
		(end 66.48069 -278.741886)
		(width 0.16002)
		(layer "In4.Cu")
		(net "M_D_CPU1_SB_DQS_DN<0>")
	)
	(segment
		(start 61.352176 -283.129736)
		(end 61.458856 -283.236416)
		(width 0.16002)
		(layer "In4.Cu")
		(net "M_D_CPU1_SB_DQS_DN<0>")
	)
	(segment
		(start 60.986162 -283.70911)
		(end 60.879482 -283.60243)
		(width 0.16002)
		(layer "In4.Cu")
		(net "M_D_CPU1_SB_DQS_DN<0>")
	)
	(segment
		(start 66.48069 -278.214582)
		(end 66.37401 -278.107902)
		(width 0.16002)
		(layer "In4.Cu")
		(net "M_D_CPU1_SB_DQS_DN<0>")
	)
	(segment
		(start 43.214036 -284.862524)
		(end 43.614086 -284.462474)
		(width 0.16002)
		(layer "In4.Cu")
		(net "M_D_CPU1_SB_DQS_DN<0>")
	)
	(segment
		(start 67.480688 -277.741888)
		(end 67.854322 -277.368254)
		(width 0.16002)
		(layer "In4.Cu")
		(net "M_D_CPU1_SB_DQS_DN<0>")
	)
	(segment
		(start 42.706036 -284.862524)
		(end 43.214036 -284.862524)
		(width 0.16002)
		(layer "In4.Cu")
		(net "M_D_CPU1_SB_DQS_DN<0>")
	)
	(arc
		(start 80.872584 -276.191218)
		(mid 81.061052 -276.140541)
		(end 81.24952 -276.191218)
		(width 0.09525)
		(layer "In4.Cu")
		(net "M_D_CPU1_SB_DQS_DN<0>")
	)
	(arc
		(start 79.932022 -276.191218)
		(mid 80.116051 -276.140319)
		(end 80.301338 -276.186392)
		(width 0.09525)
		(layer "In4.Cu")
		(net "M_D_CPU1_SB_DQS_DN<0>")
	)
	(arc
		(start 90.649552 -276.191218)
		(mid 90.883066 -276.265061)
		(end 91.125802 -276.232366)
		(width 0.09525)
		(layer "In4.Cu")
		(net "M_D_CPU1_SB_DQS_DN<0>")
	)
	(arc
		(start 86.88959 -276.191218)
		(mid 87.171022 -276.266973)
		(end 87.452454 -276.191218)
		(width 0.09525)
		(layer "In4.Cu")
		(net "M_D_CPU1_SB_DQS_DN<0>")
	)
	(arc
		(start 89.709498 -276.191218)
		(mid 89.715826 -276.194814)
		(end 89.722198 -276.19833)
		(width 0.09525)
		(layer "In4.Cu")
		(net "M_D_CPU1_SB_DQS_DN<0>")
	)
	(arc
		(start 85.022182 -276.19833)
		(mid 85.298192 -276.266891)
		(end 85.572346 -276.191218)
		(width 0.09525)
		(layer "In4.Cu")
		(net "M_D_CPU1_SB_DQS_DN<0>")
	)
	(arc
		(start 89.722198 -276.19833)
		(mid 89.998208 -276.266891)
		(end 90.272362 -276.191218)
		(width 0.09525)
		(layer "In4.Cu")
		(net "M_D_CPU1_SB_DQS_DN<0>")
	)
	(arc
		(start 88.40089 -276.186392)
		(mid 88.585922 -276.140478)
		(end 88.769698 -276.191218)
		(width 0.09525)
		(layer "In4.Cu")
		(net "M_D_CPU1_SB_DQS_DN<0>")
	)
	(arc
		(start 90.272362 -276.191218)
		(mid 90.456137 -276.140446)
		(end 90.64117 -276.186392)
		(width 0.09525)
		(layer "In4.Cu")
		(net "M_D_CPU1_SB_DQS_DN<0>")
	)
	(arc
		(start 91.125802 -276.232366)
		(mid 91.13613 -276.228406)
		(end 91.146376 -276.224238)
		(width 0.09525)
		(layer "In4.Cu")
		(net "M_D_CPU1_SB_DQS_DN<0>")
	)
	(arc
		(start 86.5124 -276.191218)
		(mid 86.696175 -276.140446)
		(end 86.881208 -276.186392)
		(width 0.09525)
		(layer "In4.Cu")
		(net "M_D_CPU1_SB_DQS_DN<0>")
	)
	(arc
		(start 87.460836 -276.186392)
		(mid 87.645868 -276.140478)
		(end 87.829644 -276.191218)
		(width 0.09525)
		(layer "In4.Cu")
		(net "M_D_CPU1_SB_DQS_DN<0>")
	)
	(arc
		(start 85.572346 -276.191218)
		(mid 85.756121 -276.140446)
		(end 85.941154 -276.186392)
		(width 0.09525)
		(layer "In4.Cu")
		(net "M_D_CPU1_SB_DQS_DN<0>")
	)
	(arc
		(start 79.650336 -276.267164)
		(mid 79.796196 -276.247805)
		(end 79.932022 -276.191218)
		(width 0.09525)
		(layer "In4.Cu")
		(net "M_D_CPU1_SB_DQS_DN<0>")
	)
	(arc
		(start 83.129628 -276.191218)
		(mid 83.41106 -276.266973)
		(end 83.692492 -276.191218)
		(width 0.09525)
		(layer "In4.Cu")
		(net "M_D_CPU1_SB_DQS_DN<0>")
	)
	(arc
		(start 84.632546 -276.191218)
		(mid 84.821014 -276.140541)
		(end 85.009482 -276.191218)
		(width 0.09525)
		(layer "In4.Cu")
		(net "M_D_CPU1_SB_DQS_DN<0>")
	)
	(arc
		(start 80.30972 -276.191218)
		(mid 80.591152 -276.266973)
		(end 80.872584 -276.191218)
		(width 0.09525)
		(layer "In4.Cu")
		(net "M_D_CPU1_SB_DQS_DN<0>")
	)
	(arc
		(start 81.24952 -276.191218)
		(mid 81.255973 -276.194818)
		(end 81.262474 -276.19833)
		(width 0.09525)
		(layer "In4.Cu")
		(net "M_D_CPU1_SB_DQS_DN<0>")
	)
	(arc
		(start 84.069682 -276.191218)
		(mid 84.351114 -276.266973)
		(end 84.632546 -276.191218)
		(width 0.09525)
		(layer "In4.Cu")
		(net "M_D_CPU1_SB_DQS_DN<0>")
	)
	(arc
		(start 81.262474 -276.19833)
		(mid 81.538374 -276.266892)
		(end 81.812384 -276.191218)
		(width 0.09525)
		(layer "In4.Cu")
		(net "M_D_CPU1_SB_DQS_DN<0>")
	)
	(arc
		(start 88.769698 -276.191218)
		(mid 89.05113 -276.266973)
		(end 89.332562 -276.191218)
		(width 0.09525)
		(layer "In4.Cu")
		(net "M_D_CPU1_SB_DQS_DN<0>")
	)
	(arc
		(start 81.812384 -276.191218)
		(mid 81.996159 -276.140446)
		(end 82.181192 -276.186392)
		(width 0.09525)
		(layer "In4.Cu")
		(net "M_D_CPU1_SB_DQS_DN<0>")
	)
	(arc
		(start 85.949536 -276.191218)
		(mid 85.955989 -276.194818)
		(end 85.96249 -276.19833)
		(width 0.09525)
		(layer "In4.Cu")
		(net "M_D_CPU1_SB_DQS_DN<0>")
	)
	(arc
		(start 85.009482 -276.191218)
		(mid 85.01581 -276.194814)
		(end 85.022182 -276.19833)
		(width 0.09525)
		(layer "In4.Cu")
		(net "M_D_CPU1_SB_DQS_DN<0>")
	)
	(arc
		(start 82.189574 -276.191218)
		(mid 82.471006 -276.266973)
		(end 82.752438 -276.191218)
		(width 0.09525)
		(layer "In4.Cu")
		(net "M_D_CPU1_SB_DQS_DN<0>")
	)
	(arc
		(start 87.829644 -276.191218)
		(mid 88.111076 -276.266973)
		(end 88.392508 -276.191218)
		(width 0.09525)
		(layer "In4.Cu")
		(net "M_D_CPU1_SB_DQS_DN<0>")
	)
	(arc
		(start 85.96249 -276.19833)
		(mid 86.23839 -276.266892)
		(end 86.5124 -276.191218)
		(width 0.09525)
		(layer "In4.Cu")
		(net "M_D_CPU1_SB_DQS_DN<0>")
	)
	(arc
		(start 89.332562 -276.191218)
		(mid 89.52103 -276.140541)
		(end 89.709498 -276.191218)
		(width 0.09525)
		(layer "In4.Cu")
		(net "M_D_CPU1_SB_DQS_DN<0>")
	)
	(arc
		(start 82.76082 -276.186392)
		(mid 82.945852 -276.140478)
		(end 83.129628 -276.191218)
		(width 0.09525)
		(layer "In4.Cu")
		(net "M_D_CPU1_SB_DQS_DN<0>")
	)
	(arc
		(start 83.700874 -276.186392)
		(mid 83.885906 -276.140478)
		(end 84.069682 -276.191218)
		(width 0.09525)
		(layer "In4.Cu")
		(net "M_D_CPU1_SB_DQS_DN<0>")
	)
	(segment
		(start 92.80779 -279.490424)
		(end 92.340938 -279.756362)
		(width 0.10668)
		(layer "F.Cu")
		(net "M_D_CPU1_SB_DQ<9>")
	)
	(segment
		(start 38.232334 -292.584632)
		(end 38.462966 -292.584632)
		(width 0.14478)
		(layer "In4.Cu")
		(net "M_D_CPU1_SB_DQ<9>")
	)
	(segment
		(start 82.179668 -280.083768)
		(end 82.18805 -280.078942)
		(width 0.0889)
		(layer "In4.Cu")
		(net "M_D_CPU1_SB_DQ<9>")
	)
	(segment
		(start 76.327762 -279.753314)
		(end 76.481178 -279.753314)
		(width 0.0889)
		(layer "In4.Cu")
		(net "M_D_CPU1_SB_DQ<9>")
	)
	(segment
		(start 63.221108 -288.779204)
		(end 63.462662 -289.020758)
		(width 0.14478)
		(layer "In4.Cu")
		(net "M_D_CPU1_SB_DQ<9>")
	)
	(segment
		(start 46.915832 -293.097458)
		(end 46.915832 -292.823138)
		(width 0.14478)
		(layer "In4.Cu")
		(net "M_D_CPU1_SB_DQ<9>")
	)
	(segment
		(start 72.092058 -279.753314)
		(end 76.327762 -279.753314)
		(width 0.14478)
		(layer "In4.Cu")
		(net "M_D_CPU1_SB_DQ<9>")
	)
	(segment
		(start 52.115212 -292.11016)
		(end 52.438808 -292.433756)
		(width 0.14478)
		(layer "In4.Cu")
		(net "M_D_CPU1_SB_DQ<9>")
	)
	(segment
		(start 85.93963 -280.083768)
		(end 85.948012 -280.078942)
		(width 0.0889)
		(layer "In4.Cu")
		(net "M_D_CPU1_SB_DQ<9>")
	)
	(segment
		(start 83.694016 -280.078942)
		(end 83.702398 -280.083768)
		(width 0.0889)
		(layer "In4.Cu")
		(net "M_D_CPU1_SB_DQ<9>")
	)
	(segment
		(start 47.052738 -292.686232)
		(end 47.335186 -292.686232)
		(width 0.14478)
		(layer "In4.Cu")
		(net "M_D_CPU1_SB_DQ<9>")
	)
	(segment
		(start 37.596572 -293.335964)
		(end 37.906706 -293.335964)
		(width 0.14478)
		(layer "In4.Cu")
		(net "M_D_CPU1_SB_DQ<9>")
	)
	(segment
		(start 47.608998 -292.960298)
		(end 49.227994 -292.960298)
		(width 0.14478)
		(layer "In4.Cu")
		(net "M_D_CPU1_SB_DQ<9>")
	)
	(segment
		(start 54.401974 -292.960552)
		(end 54.402228 -292.960298)
		(width 0.14478)
		(layer "In4.Cu")
		(net "M_D_CPU1_SB_DQ<9>")
	)
	(segment
		(start 88.394032 -280.078942)
		(end 88.402414 -280.083768)
		(width 0.0889)
		(layer "In4.Cu")
		(net "M_D_CPU1_SB_DQ<9>")
	)
	(segment
		(start 80.299814 -280.083768)
		(end 80.308196 -280.078942)
		(width 0.0889)
		(layer "In4.Cu")
		(net "M_D_CPU1_SB_DQ<9>")
	)
	(segment
		(start 52.995068 -291.786564)
		(end 53.227732 -291.786564)
		(width 0.14478)
		(layer "In4.Cu")
		(net "M_D_CPU1_SB_DQ<9>")
	)
	(segment
		(start 52.83327 -291.948362)
		(end 52.995068 -291.786564)
		(width 0.14478)
		(layer "In4.Cu")
		(net "M_D_CPU1_SB_DQ<9>")
	)
	(segment
		(start 62.830964 -288.989516)
		(end 63.041276 -288.779204)
		(width 0.14478)
		(layer "In4.Cu")
		(net "M_D_CPU1_SB_DQ<9>")
	)
	(segment
		(start 46.359572 -293.097204)
		(end 46.359572 -293.097458)
		(width 0.14478)
		(layer "In4.Cu")
		(net "M_D_CPU1_SB_DQ<9>")
	)
	(segment
		(start 58.292238 -292.370764)
		(end 58.587894 -292.370764)
		(width 0.14478)
		(layer "In4.Cu")
		(net "M_D_CPU1_SB_DQ<9>")
	)
	(segment
		(start 50.401728 -291.786564)
		(end 50.634392 -291.786564)
		(width 0.14478)
		(layer "In4.Cu")
		(net "M_D_CPU1_SB_DQ<9>")
	)
	(segment
		(start 46.778926 -293.234364)
		(end 46.915832 -293.097458)
		(width 0.14478)
		(layer "In4.Cu")
		(net "M_D_CPU1_SB_DQ<9>")
	)
	(segment
		(start 62.830964 -289.169348)
		(end 62.830964 -288.989516)
		(width 0.14478)
		(layer "In4.Cu")
		(net "M_D_CPU1_SB_DQ<9>")
	)
	(segment
		(start 52.83327 -292.271958)
		(end 52.83327 -291.948362)
		(width 0.14478)
		(layer "In4.Cu")
		(net "M_D_CPU1_SB_DQ<9>")
	)
	(segment
		(start 46.915832 -292.823138)
		(end 47.052738 -292.686232)
		(width 0.14478)
		(layer "In4.Cu")
		(net "M_D_CPU1_SB_DQ<9>")
	)
	(segment
		(start 76.481178 -279.753314)
		(end 76.64831 -279.920446)
		(width 0.0889)
		(layer "In4.Cu")
		(net "M_D_CPU1_SB_DQ<9>")
	)
	(segment
		(start 58.587894 -292.370764)
		(end 58.848498 -292.11016)
		(width 0.14478)
		(layer "In4.Cu")
		(net "M_D_CPU1_SB_DQ<9>")
	)
	(segment
		(start 50.79619 -291.948362)
		(end 50.79619 -292.271958)
		(width 0.14478)
		(layer "In4.Cu")
		(net "M_D_CPU1_SB_DQ<9>")
	)
	(segment
		(start 58.031634 -292.11016)
		(end 58.292238 -292.370764)
		(width 0.14478)
		(layer "In4.Cu")
		(net "M_D_CPU1_SB_DQ<9>")
	)
	(segment
		(start 53.227732 -291.786564)
		(end 54.401974 -292.960552)
		(width 0.14478)
		(layer "In4.Cu")
		(net "M_D_CPU1_SB_DQ<9>")
	)
	(segment
		(start 92.495116 -280.021792)
		(end 92.340938 -279.756362)
		(width 0.0889)
		(layer "In4.Cu")
		(net "M_D_CPU1_SB_DQ<9>")
	)
	(segment
		(start 47.335186 -292.686232)
		(end 47.472092 -292.823138)
		(width 0.14478)
		(layer "In4.Cu")
		(net "M_D_CPU1_SB_DQ<9>")
	)
	(segment
		(start 38.06952 -293.17315)
		(end 38.06952 -292.747446)
		(width 0.14478)
		(layer "In4.Cu")
		(net "M_D_CPU1_SB_DQ<9>")
	)
	(segment
		(start 82.753962 -280.078942)
		(end 82.762344 -280.083768)
		(width 0.0889)
		(layer "In4.Cu")
		(net "M_D_CPU1_SB_DQ<9>")
	)
	(segment
		(start 56.745886 -292.960552)
		(end 57.596532 -292.11016)
		(width 0.14478)
		(layer "In4.Cu")
		(net "M_D_CPU1_SB_DQ<9>")
	)
	(segment
		(start 54.402228 -292.960298)
		(end 56.745632 -292.960298)
		(width 0.14478)
		(layer "In4.Cu")
		(net "M_D_CPU1_SB_DQ<9>")
	)
	(segment
		(start 60.60186 -292.11016)
		(end 63.072518 -289.639502)
		(width 0.14478)
		(layer "In4.Cu")
		(net "M_D_CPU1_SB_DQ<9>")
	)
	(segment
		(start 38.06952 -292.747446)
		(end 38.232334 -292.584632)
		(width 0.14478)
		(layer "In4.Cu")
		(net "M_D_CPU1_SB_DQ<9>")
	)
	(segment
		(start 47.472092 -292.823138)
		(end 47.472092 -292.823392)
		(width 0.14478)
		(layer "In4.Cu")
		(net "M_D_CPU1_SB_DQ<9>")
	)
	(segment
		(start 36.795964 -292.535356)
		(end 37.596572 -293.335964)
		(width 0.14478)
		(layer "In4.Cu")
		(net "M_D_CPU1_SB_DQ<9>")
	)
	(segment
		(start 51.190652 -292.433756)
		(end 51.514248 -292.11016)
		(width 0.14478)
		(layer "In4.Cu")
		(net "M_D_CPU1_SB_DQ<9>")
	)
	(segment
		(start 92.153994 -280.078942)
		(end 92.162376 -280.083768)
		(width 0.0889)
		(layer "In4.Cu")
		(net "M_D_CPU1_SB_DQ<9>")
	)
	(segment
		(start 58.848498 -292.11016)
		(end 60.60186 -292.11016)
		(width 0.14478)
		(layer "In4.Cu")
		(net "M_D_CPU1_SB_DQ<9>")
	)
	(segment
		(start 63.072518 -289.410902)
		(end 62.830964 -289.169348)
		(width 0.14478)
		(layer "In4.Cu")
		(net "M_D_CPU1_SB_DQ<9>")
	)
	(segment
		(start 86.879684 -280.083768)
		(end 86.888066 -280.078942)
		(width 0.0889)
		(layer "In4.Cu")
		(net "M_D_CPU1_SB_DQ<9>")
	)
	(segment
		(start 64.960246 -287.751774)
		(end 64.960246 -286.885126)
		(width 0.14478)
		(layer "In4.Cu")
		(net "M_D_CPU1_SB_DQ<9>")
	)
	(segment
		(start 45.372528 -292.11016)
		(end 46.359572 -293.097204)
		(width 0.14478)
		(layer "In4.Cu")
		(net "M_D_CPU1_SB_DQ<9>")
	)
	(segment
		(start 50.79619 -292.271958)
		(end 50.957988 -292.433756)
		(width 0.14478)
		(layer "In4.Cu")
		(net "M_D_CPU1_SB_DQ<9>")
	)
	(segment
		(start 63.462662 -289.020758)
		(end 63.691262 -289.020758)
		(width 0.14478)
		(layer "In4.Cu")
		(net "M_D_CPU1_SB_DQ<9>")
	)
	(segment
		(start 42.719244 -292.11016)
		(end 45.372528 -292.11016)
		(width 0.14478)
		(layer "In4.Cu")
		(net "M_D_CPU1_SB_DQ<9>")
	)
	(segment
		(start 76.64831 -279.920446)
		(end 79.34579 -279.920446)
		(width 0.0889)
		(layer "In4.Cu")
		(net "M_D_CPU1_SB_DQ<9>")
	)
	(segment
		(start 50.957988 -292.433756)
		(end 51.190652 -292.433756)
		(width 0.14478)
		(layer "In4.Cu")
		(net "M_D_CPU1_SB_DQ<9>")
	)
	(segment
		(start 57.596532 -292.11016)
		(end 58.031634 -292.11016)
		(width 0.14478)
		(layer "In4.Cu")
		(net "M_D_CPU1_SB_DQ<9>")
	)
	(segment
		(start 92.472764 -280.105104)
		(end 92.495116 -280.021792)
		(width 0.0889)
		(layer "In4.Cu")
		(net "M_D_CPU1_SB_DQ<9>")
	)
	(segment
		(start 91.5797 -280.083768)
		(end 91.588082 -280.078942)
		(width 0.0889)
		(layer "In4.Cu")
		(net "M_D_CPU1_SB_DQ<9>")
	)
	(segment
		(start 46.496478 -293.234364)
		(end 46.778926 -293.234364)
		(width 0.14478)
		(layer "In4.Cu")
		(net "M_D_CPU1_SB_DQ<9>")
	)
	(segment
		(start 37.906706 -293.335964)
		(end 38.06952 -293.17315)
		(width 0.14478)
		(layer "In4.Cu")
		(net "M_D_CPU1_SB_DQ<9>")
	)
	(segment
		(start 51.514248 -292.11016)
		(end 52.115212 -292.11016)
		(width 0.14478)
		(layer "In4.Cu")
		(net "M_D_CPU1_SB_DQ<9>")
	)
	(segment
		(start 52.671472 -292.433756)
		(end 52.83327 -292.271958)
		(width 0.14478)
		(layer "In4.Cu")
		(net "M_D_CPU1_SB_DQ<9>")
	)
	(segment
		(start 63.691262 -289.020758)
		(end 64.960246 -287.751774)
		(width 0.14478)
		(layer "In4.Cu")
		(net "M_D_CPU1_SB_DQ<9>")
	)
	(segment
		(start 87.453978 -280.078942)
		(end 87.46236 -280.083768)
		(width 0.0889)
		(layer "In4.Cu")
		(net "M_D_CPU1_SB_DQ<9>")
	)
	(segment
		(start 38.462966 -292.584632)
		(end 38.838632 -292.960298)
		(width 0.14478)
		(layer "In4.Cu")
		(net "M_D_CPU1_SB_DQ<9>")
	)
	(segment
		(start 49.227994 -292.960298)
		(end 50.401728 -291.786564)
		(width 0.14478)
		(layer "In4.Cu")
		(net "M_D_CPU1_SB_DQ<9>")
	)
	(segment
		(start 56.745632 -292.960298)
		(end 56.745886 -292.960552)
		(width 0.14478)
		(layer "In4.Cu")
		(net "M_D_CPU1_SB_DQ<9>")
	)
	(segment
		(start 46.359572 -293.097458)
		(end 46.496478 -293.234364)
		(width 0.14478)
		(layer "In4.Cu")
		(net "M_D_CPU1_SB_DQ<9>")
	)
	(segment
		(start 90.639646 -280.083768)
		(end 90.648028 -280.078942)
		(width 0.0889)
		(layer "In4.Cu")
		(net "M_D_CPU1_SB_DQ<9>")
	)
	(segment
		(start 50.634392 -291.786564)
		(end 50.79619 -291.948362)
		(width 0.14478)
		(layer "In4.Cu")
		(net "M_D_CPU1_SB_DQ<9>")
	)
	(segment
		(start 63.041276 -288.779204)
		(end 63.221108 -288.779204)
		(width 0.14478)
		(layer "In4.Cu")
		(net "M_D_CPU1_SB_DQ<9>")
	)
	(segment
		(start 47.472092 -292.823392)
		(end 47.608998 -292.960298)
		(width 0.14478)
		(layer "In4.Cu")
		(net "M_D_CPU1_SB_DQ<9>")
	)
	(segment
		(start 52.438808 -292.433756)
		(end 52.671472 -292.433756)
		(width 0.14478)
		(layer "In4.Cu")
		(net "M_D_CPU1_SB_DQ<9>")
	)
	(segment
		(start 64.960246 -286.885126)
		(end 72.092058 -279.753314)
		(width 0.14478)
		(layer "In4.Cu")
		(net "M_D_CPU1_SB_DQ<9>")
	)
	(segment
		(start 63.072518 -289.639502)
		(end 63.072518 -289.410902)
		(width 0.14478)
		(layer "In4.Cu")
		(net "M_D_CPU1_SB_DQ<9>")
	)
	(segment
		(start 41.869106 -292.960298)
		(end 42.719244 -292.11016)
		(width 0.14478)
		(layer "In4.Cu")
		(net "M_D_CPU1_SB_DQ<9>")
	)
	(segment
		(start 38.838632 -292.960298)
		(end 41.869106 -292.960298)
		(width 0.14478)
		(layer "In4.Cu")
		(net "M_D_CPU1_SB_DQ<9>")
	)
	(arc
		(start 88.402414 -280.083768)
		(mid 88.585922 -280.129262)
		(end 88.768174 -280.078942)
		(width 0.0889)
		(layer "In4.Cu")
		(net "M_D_CPU1_SB_DQ<9>")
	)
	(arc
		(start 85.57387 -280.078942)
		(mid 85.756121 -280.129292)
		(end 85.93963 -280.083768)
		(width 0.0889)
		(layer "In4.Cu")
		(net "M_D_CPU1_SB_DQ<9>")
	)
	(arc
		(start 83.128104 -280.078942)
		(mid 83.41106 -280.002765)
		(end 83.694016 -280.078942)
		(width 0.0889)
		(layer "In4.Cu")
		(net "M_D_CPU1_SB_DQ<9>")
	)
	(arc
		(start 84.068158 -280.078942)
		(mid 84.351114 -280.002765)
		(end 84.63407 -280.078942)
		(width 0.0889)
		(layer "In4.Cu")
		(net "M_D_CPU1_SB_DQ<9>")
	)
	(arc
		(start 89.334086 -280.078942)
		(mid 89.52103 -280.129197)
		(end 89.707974 -280.078942)
		(width 0.0889)
		(layer "In4.Cu")
		(net "M_D_CPU1_SB_DQ<9>")
	)
	(arc
		(start 85.948012 -280.078942)
		(mid 86.230968 -280.002765)
		(end 86.513924 -280.078942)
		(width 0.0889)
		(layer "In4.Cu")
		(net "M_D_CPU1_SB_DQ<9>")
	)
	(arc
		(start 87.82812 -280.078942)
		(mid 88.111076 -280.002765)
		(end 88.394032 -280.078942)
		(width 0.0889)
		(layer "In4.Cu")
		(net "M_D_CPU1_SB_DQ<9>")
	)
	(arc
		(start 91.588082 -280.078942)
		(mid 91.871038 -280.002765)
		(end 92.153994 -280.078942)
		(width 0.0889)
		(layer "In4.Cu")
		(net "M_D_CPU1_SB_DQ<9>")
	)
	(arc
		(start 91.21394 -280.078942)
		(mid 91.396191 -280.129292)
		(end 91.5797 -280.083768)
		(width 0.0889)
		(layer "In4.Cu")
		(net "M_D_CPU1_SB_DQ<9>")
	)
	(arc
		(start 79.34579 -279.920446)
		(mid 79.650168 -279.960762)
		(end 79.933546 -280.078942)
		(width 0.0889)
		(layer "In4.Cu")
		(net "M_D_CPU1_SB_DQ<9>")
	)
	(arc
		(start 83.702398 -280.083768)
		(mid 83.885906 -280.129262)
		(end 84.068158 -280.078942)
		(width 0.0889)
		(layer "In4.Cu")
		(net "M_D_CPU1_SB_DQ<9>")
	)
	(arc
		(start 85.007958 -280.078942)
		(mid 85.290914 -280.002765)
		(end 85.57387 -280.078942)
		(width 0.0889)
		(layer "In4.Cu")
		(net "M_D_CPU1_SB_DQ<9>")
	)
	(arc
		(start 89.707974 -280.078942)
		(mid 89.99093 -280.002765)
		(end 90.273886 -280.078942)
		(width 0.0889)
		(layer "In4.Cu")
		(net "M_D_CPU1_SB_DQ<9>")
	)
	(arc
		(start 87.46236 -280.083768)
		(mid 87.645868 -280.129262)
		(end 87.82812 -280.078942)
		(width 0.0889)
		(layer "In4.Cu")
		(net "M_D_CPU1_SB_DQ<9>")
	)
	(arc
		(start 79.933546 -280.078942)
		(mid 80.116051 -280.129419)
		(end 80.299814 -280.083768)
		(width 0.0889)
		(layer "In4.Cu")
		(net "M_D_CPU1_SB_DQ<9>")
	)
	(arc
		(start 88.768174 -280.078942)
		(mid 89.05113 -280.002765)
		(end 89.334086 -280.078942)
		(width 0.0889)
		(layer "In4.Cu")
		(net "M_D_CPU1_SB_DQ<9>")
	)
	(arc
		(start 84.63407 -280.078942)
		(mid 84.821014 -280.129197)
		(end 85.007958 -280.078942)
		(width 0.0889)
		(layer "In4.Cu")
		(net "M_D_CPU1_SB_DQ<9>")
	)
	(arc
		(start 81.247996 -280.078942)
		(mid 81.530952 -280.002765)
		(end 81.813908 -280.078942)
		(width 0.0889)
		(layer "In4.Cu")
		(net "M_D_CPU1_SB_DQ<9>")
	)
	(arc
		(start 82.762344 -280.083768)
		(mid 82.945852 -280.129262)
		(end 83.128104 -280.078942)
		(width 0.0889)
		(layer "In4.Cu")
		(net "M_D_CPU1_SB_DQ<9>")
	)
	(arc
		(start 86.888066 -280.078942)
		(mid 87.171022 -280.002765)
		(end 87.453978 -280.078942)
		(width 0.0889)
		(layer "In4.Cu")
		(net "M_D_CPU1_SB_DQ<9>")
	)
	(arc
		(start 90.273886 -280.078942)
		(mid 90.456137 -280.129292)
		(end 90.639646 -280.083768)
		(width 0.0889)
		(layer "In4.Cu")
		(net "M_D_CPU1_SB_DQ<9>")
	)
	(arc
		(start 80.308196 -280.078942)
		(mid 80.591152 -280.002765)
		(end 80.874108 -280.078942)
		(width 0.0889)
		(layer "In4.Cu")
		(net "M_D_CPU1_SB_DQ<9>")
	)
	(arc
		(start 90.648028 -280.078942)
		(mid 90.930984 -280.002765)
		(end 91.21394 -280.078942)
		(width 0.0889)
		(layer "In4.Cu")
		(net "M_D_CPU1_SB_DQ<9>")
	)
	(arc
		(start 82.18805 -280.078942)
		(mid 82.471006 -280.002765)
		(end 82.753962 -280.078942)
		(width 0.0889)
		(layer "In4.Cu")
		(net "M_D_CPU1_SB_DQ<9>")
	)
	(arc
		(start 86.513924 -280.078942)
		(mid 86.696175 -280.129292)
		(end 86.879684 -280.083768)
		(width 0.0889)
		(layer "In4.Cu")
		(net "M_D_CPU1_SB_DQ<9>")
	)
	(arc
		(start 80.874108 -280.078942)
		(mid 81.061052 -280.129197)
		(end 81.247996 -280.078942)
		(width 0.0889)
		(layer "In4.Cu")
		(net "M_D_CPU1_SB_DQ<9>")
	)
	(arc
		(start 92.162376 -280.083768)
		(mid 92.315246 -280.128409)
		(end 92.472764 -280.105104)
		(width 0.0889)
		(layer "In4.Cu")
		(net "M_D_CPU1_SB_DQ<9>")
	)
	(arc
		(start 81.813908 -280.078942)
		(mid 81.996159 -280.129292)
		(end 82.179668 -280.083768)
		(width 0.0889)
		(layer "In4.Cu")
		(net "M_D_CPU1_SB_DQ<9>")
	)
	(segment
		(start 91.397836 -278.680418)
		(end 90.930984 -278.946356)
		(width 0.10668)
		(layer "F.Cu")
		(net "M_D_CPU1_SB_DQ<8>")
	)
	(segment
		(start 51.073304 -290.719764)
		(end 51.320192 -290.719764)
		(width 0.14478)
		(layer "In4.Cu")
		(net "M_D_CPU1_SB_DQ<8>")
	)
	(segment
		(start 41.10482 -291.563806)
		(end 41.352978 -291.563806)
		(width 0.14478)
		(layer "In4.Cu")
		(net "M_D_CPU1_SB_DQ<8>")
	)
	(segment
		(start 48.825404 -291.127942)
		(end 48.825404 -291.422074)
		(width 0.14478)
		(layer "In4.Cu")
		(net "M_D_CPU1_SB_DQ<8>")
	)
	(segment
		(start 48.986694 -291.583364)
		(end 49.318672 -291.583364)
		(width 0.14478)
		(layer "In4.Cu")
		(net "M_D_CPU1_SB_DQ<8>")
	)
	(segment
		(start 38.769036 -290.966652)
		(end 39.062914 -291.26053)
		(width 0.14478)
		(layer "In4.Cu")
		(net "M_D_CPU1_SB_DQ<8>")
	)
	(segment
		(start 90.74404 -279.268936)
		(end 90.752422 -279.273762)
		(width 0.0889)
		(layer "In4.Cu")
		(net "M_D_CPU1_SB_DQ<8>")
	)
	(segment
		(start 60.386976 -290.21786)
		(end 60.605162 -290.436046)
		(width 0.14478)
		(layer "In4.Cu")
		(net "M_D_CPU1_SB_DQ<8>")
	)
	(segment
		(start 55.918354 -290.966652)
		(end 56.152034 -290.966652)
		(width 0.14478)
		(layer "In4.Cu")
		(net "M_D_CPU1_SB_DQ<8>")
	)
	(segment
		(start 60.159138 -290.21786)
		(end 60.386976 -290.21786)
		(width 0.14478)
		(layer "In4.Cu")
		(net "M_D_CPU1_SB_DQ<8>")
	)
	(segment
		(start 41.352978 -291.563806)
		(end 41.656254 -291.26053)
		(width 0.14478)
		(layer "In4.Cu")
		(net "M_D_CPU1_SB_DQ<8>")
	)
	(segment
		(start 50.763932 -290.410392)
		(end 51.073304 -290.719764)
		(width 0.14478)
		(layer "In4.Cu")
		(net "M_D_CPU1_SB_DQ<8>")
	)
	(segment
		(start 52.587906 -290.694364)
		(end 53.635656 -290.694364)
		(width 0.14478)
		(layer "In4.Cu")
		(net "M_D_CPU1_SB_DQ<8>")
	)
	(segment
		(start 88.289638 -279.273762)
		(end 88.29802 -279.268936)
		(width 0.0889)
		(layer "In4.Cu")
		(net "M_D_CPU1_SB_DQ<8>")
	)
	(segment
		(start 91.085162 -279.211786)
		(end 90.930984 -278.946356)
		(width 0.0889)
		(layer "In4.Cu")
		(net "M_D_CPU1_SB_DQ<8>")
	)
	(segment
		(start 71.634604 -278.742394)
		(end 76.62545 -278.742394)
		(width 0.14478)
		(layer "In4.Cu")
		(net "M_D_CPU1_SB_DQ<8>")
	)
	(segment
		(start 56.70804 -291.655754)
		(end 57.953402 -290.410392)
		(width 0.14478)
		(layer "In4.Cu")
		(net "M_D_CPU1_SB_DQ<8>")
	)
	(segment
		(start 49.318672 -291.583364)
		(end 50.491644 -290.410392)
		(width 0.14478)
		(layer "In4.Cu")
		(net "M_D_CPU1_SB_DQ<8>")
	)
	(segment
		(start 46.878748 -291.507164)
		(end 46.878748 -291.115242)
		(width 0.14478)
		(layer "In4.Cu")
		(net "M_D_CPU1_SB_DQ<8>")
	)
	(segment
		(start 37.22116 -291.26053)
		(end 37.594794 -291.26053)
		(width 0.14478)
		(layer "In4.Cu")
		(net "M_D_CPU1_SB_DQ<8>")
	)
	(segment
		(start 46.471332 -291.655754)
		(end 46.730158 -291.655754)
		(width 0.14478)
		(layer "In4.Cu")
		(net "M_D_CPU1_SB_DQ<8>")
	)
	(segment
		(start 38.374066 -291.127942)
		(end 38.535356 -290.966652)
		(width 0.14478)
		(layer "In4.Cu")
		(net "M_D_CPU1_SB_DQ<8>")
	)
	(segment
		(start 47.580296 -291.26053)
		(end 48.136556 -291.26053)
		(width 0.14478)
		(layer "In4.Cu")
		(net "M_D_CPU1_SB_DQ<8>")
	)
	(segment
		(start 38.535356 -290.966652)
		(end 38.769036 -290.966652)
		(width 0.14478)
		(layer "In4.Cu")
		(net "M_D_CPU1_SB_DQ<8>")
	)
	(segment
		(start 38.202108 -291.655754)
		(end 38.374066 -291.483796)
		(width 0.14478)
		(layer "In4.Cu")
		(net "M_D_CPU1_SB_DQ<8>")
	)
	(segment
		(start 80.39354 -279.26284)
		(end 80.403954 -279.268936)
		(width 0.0889)
		(layer "In4.Cu")
		(net "M_D_CPU1_SB_DQ<8>")
	)
	(segment
		(start 78.029308 -278.792686)
		(end 78.446884 -279.210262)
		(width 0.0889)
		(layer "In4.Cu")
		(net "M_D_CPU1_SB_DQ<8>")
	)
	(segment
		(start 46.730158 -291.655754)
		(end 46.878748 -291.507164)
		(width 0.14478)
		(layer "In4.Cu")
		(net "M_D_CPU1_SB_DQ<8>")
	)
	(segment
		(start 48.825404 -291.422074)
		(end 48.986694 -291.583364)
		(width 0.14478)
		(layer "In4.Cu")
		(net "M_D_CPU1_SB_DQ<8>")
	)
	(segment
		(start 85.10397 -279.268936)
		(end 85.112352 -279.273762)
		(width 0.0889)
		(layer "In4.Cu")
		(net "M_D_CPU1_SB_DQ<8>")
	)
	(segment
		(start 60.833762 -290.436046)
		(end 60.995814 -290.273994)
		(width 0.14478)
		(layer "In4.Cu")
		(net "M_D_CPU1_SB_DQ<8>")
	)
	(segment
		(start 60.777374 -289.827716)
		(end 60.777374 -289.599624)
		(width 0.14478)
		(layer "In4.Cu")
		(net "M_D_CPU1_SB_DQ<8>")
	)
	(segment
		(start 60.605162 -290.436046)
		(end 60.833762 -290.436046)
		(width 0.14478)
		(layer "In4.Cu")
		(net "M_D_CPU1_SB_DQ<8>")
	)
	(segment
		(start 58.32221 -290.410392)
		(end 58.631582 -290.719764)
		(width 0.14478)
		(layer "In4.Cu")
		(net "M_D_CPU1_SB_DQ<8>")
	)
	(segment
		(start 51.320192 -290.719764)
		(end 51.629564 -290.410392)
		(width 0.14478)
		(layer "In4.Cu")
		(net "M_D_CPU1_SB_DQ<8>")
	)
	(segment
		(start 91.06281 -279.295098)
		(end 91.085162 -279.211786)
		(width 0.0889)
		(layer "In4.Cu")
		(net "M_D_CPU1_SB_DQ<8>")
	)
	(segment
		(start 86.044024 -279.268936)
		(end 86.052406 -279.273762)
		(width 0.0889)
		(layer "In4.Cu")
		(net "M_D_CPU1_SB_DQ<8>")
	)
	(segment
		(start 61.77788 -289.495992)
		(end 61.77788 -289.267646)
		(width 0.14478)
		(layer "In4.Cu")
		(net "M_D_CPU1_SB_DQ<8>")
	)
	(segment
		(start 61.77788 -289.267646)
		(end 61.557662 -289.047428)
		(width 0.14478)
		(layer "In4.Cu")
		(net "M_D_CPU1_SB_DQ<8>")
	)
	(segment
		(start 45.22597 -290.410392)
		(end 46.471332 -291.655754)
		(width 0.14478)
		(layer "In4.Cu")
		(net "M_D_CPU1_SB_DQ<8>")
	)
	(segment
		(start 46.878748 -291.115242)
		(end 47.027338 -290.966652)
		(width 0.14478)
		(layer "In4.Cu")
		(net "M_D_CPU1_SB_DQ<8>")
	)
	(segment
		(start 42.168064 -291.26053)
		(end 42.991278 -290.437316)
		(width 0.14478)
		(layer "In4.Cu")
		(net "M_D_CPU1_SB_DQ<8>")
	)
	(segment
		(start 53.635656 -290.694364)
		(end 54.473856 -291.532564)
		(width 0.14478)
		(layer "In4.Cu")
		(net "M_D_CPU1_SB_DQ<8>")
	)
	(segment
		(start 78.897734 -279.268682)
		(end 78.903322 -279.26538)
		(width 0.0889)
		(layer "In4.Cu")
		(net "M_D_CPU1_SB_DQ<8>")
	)
	(segment
		(start 80.769714 -279.273762)
		(end 80.778096 -279.268936)
		(width 0.0889)
		(layer "In4.Cu")
		(net "M_D_CPU1_SB_DQ<8>")
	)
	(segment
		(start 47.027338 -290.966652)
		(end 47.286418 -290.966652)
		(width 0.14478)
		(layer "In4.Cu")
		(net "M_D_CPU1_SB_DQ<8>")
	)
	(segment
		(start 61.557662 -288.819336)
		(end 71.634604 -278.742394)
		(width 0.14478)
		(layer "In4.Cu")
		(net "M_D_CPU1_SB_DQ<8>")
	)
	(segment
		(start 79.463138 -279.268936)
		(end 79.47152 -279.273762)
		(width 0.0889)
		(layer "In4.Cu")
		(net "M_D_CPU1_SB_DQ<8>")
	)
	(segment
		(start 42.991278 -290.437316)
		(end 43.203622 -290.437316)
		(width 0.14478)
		(layer "In4.Cu")
		(net "M_D_CPU1_SB_DQ<8>")
	)
	(segment
		(start 41.656254 -291.26053)
		(end 42.168064 -291.26053)
		(width 0.14478)
		(layer "In4.Cu")
		(net "M_D_CPU1_SB_DQ<8>")
	)
	(segment
		(start 43.203622 -290.437316)
		(end 43.48607 -290.719764)
		(width 0.14478)
		(layer "In4.Cu")
		(net "M_D_CPU1_SB_DQ<8>")
	)
	(segment
		(start 43.732958 -290.719764)
		(end 44.04233 -290.410392)
		(width 0.14478)
		(layer "In4.Cu")
		(net "M_D_CPU1_SB_DQ<8>")
	)
	(segment
		(start 38.374066 -291.483796)
		(end 38.374066 -291.127942)
		(width 0.14478)
		(layer "In4.Cu")
		(net "M_D_CPU1_SB_DQ<8>")
	)
	(segment
		(start 51.629564 -290.410392)
		(end 52.303934 -290.410392)
		(width 0.14478)
		(layer "In4.Cu")
		(net "M_D_CPU1_SB_DQ<8>")
	)
	(segment
		(start 50.491644 -290.410392)
		(end 50.763932 -290.410392)
		(width 0.14478)
		(layer "In4.Cu")
		(net "M_D_CPU1_SB_DQ<8>")
	)
	(segment
		(start 89.229692 -279.273762)
		(end 89.238074 -279.268936)
		(width 0.0889)
		(layer "In4.Cu")
		(net "M_D_CPU1_SB_DQ<8>")
	)
	(segment
		(start 61.387736 -289.658044)
		(end 61.615828 -289.658044)
		(width 0.14478)
		(layer "In4.Cu")
		(net "M_D_CPU1_SB_DQ<8>")
	)
	(segment
		(start 78.879446 -279.279096)
		(end 78.897734 -279.268682)
		(width 0.0889)
		(layer "In4.Cu")
		(net "M_D_CPU1_SB_DQ<8>")
	)
	(segment
		(start 56.152034 -290.966652)
		(end 56.313324 -291.127942)
		(width 0.14478)
		(layer "In4.Cu")
		(net "M_D_CPU1_SB_DQ<8>")
	)
	(segment
		(start 56.313324 -291.494464)
		(end 56.474614 -291.655754)
		(width 0.14478)
		(layer "In4.Cu")
		(net "M_D_CPU1_SB_DQ<8>")
	)
	(segment
		(start 48.430434 -290.966652)
		(end 48.664114 -290.966652)
		(width 0.14478)
		(layer "In4.Cu")
		(net "M_D_CPU1_SB_DQ<8>")
	)
	(segment
		(start 47.286418 -290.966652)
		(end 47.580296 -291.26053)
		(width 0.14478)
		(layer "In4.Cu")
		(net "M_D_CPU1_SB_DQ<8>")
	)
	(segment
		(start 57.953402 -290.410392)
		(end 58.32221 -290.410392)
		(width 0.14478)
		(layer "In4.Cu")
		(net "M_D_CPU1_SB_DQ<8>")
	)
	(segment
		(start 48.664114 -290.966652)
		(end 48.825404 -291.127942)
		(width 0.14478)
		(layer "In4.Cu")
		(net "M_D_CPU1_SB_DQ<8>")
	)
	(segment
		(start 78.523338 -279.268936)
		(end 78.523592 -279.268936)
		(width 0.0889)
		(layer "In4.Cu")
		(net "M_D_CPU1_SB_DQ<8>")
	)
	(segment
		(start 81.344008 -279.268936)
		(end 81.35239 -279.273762)
		(width 0.0889)
		(layer "In4.Cu")
		(net "M_D_CPU1_SB_DQ<8>")
	)
	(segment
		(start 54.473856 -291.532564)
		(end 54.960774 -291.532564)
		(width 0.14478)
		(layer "In4.Cu")
		(net "M_D_CPU1_SB_DQ<8>")
	)
	(segment
		(start 55.232808 -291.26053)
		(end 55.624476 -291.26053)
		(width 0.14478)
		(layer "In4.Cu")
		(net "M_D_CPU1_SB_DQ<8>")
	)
	(segment
		(start 61.557662 -289.047428)
		(end 61.557662 -288.819336)
		(width 0.14478)
		(layer "In4.Cu")
		(net "M_D_CPU1_SB_DQ<8>")
	)
	(segment
		(start 60.939426 -289.437572)
		(end 61.167264 -289.437572)
		(width 0.14478)
		(layer "In4.Cu")
		(net "M_D_CPU1_SB_DQ<8>")
	)
	(segment
		(start 83.589622 -279.273762)
		(end 83.598004 -279.268936)
		(width 0.0889)
		(layer "In4.Cu")
		(net "M_D_CPU1_SB_DQ<8>")
	)
	(segment
		(start 37.594794 -291.26053)
		(end 37.990018 -291.655754)
		(width 0.14478)
		(layer "In4.Cu")
		(net "M_D_CPU1_SB_DQ<8>")
	)
	(segment
		(start 84.529676 -279.273762)
		(end 84.538058 -279.268936)
		(width 0.0889)
		(layer "In4.Cu")
		(net "M_D_CPU1_SB_DQ<8>")
	)
	(segment
		(start 55.624476 -291.26053)
		(end 55.918354 -290.966652)
		(width 0.14478)
		(layer "In4.Cu")
		(net "M_D_CPU1_SB_DQ<8>")
	)
	(segment
		(start 58.87847 -290.719764)
		(end 59.187842 -290.410392)
		(width 0.14478)
		(layer "In4.Cu")
		(net "M_D_CPU1_SB_DQ<8>")
	)
	(segment
		(start 39.062914 -291.26053)
		(end 40.801544 -291.26053)
		(width 0.14478)
		(layer "In4.Cu")
		(net "M_D_CPU1_SB_DQ<8>")
	)
	(segment
		(start 43.48607 -290.719764)
		(end 43.732958 -290.719764)
		(width 0.14478)
		(layer "In4.Cu")
		(net "M_D_CPU1_SB_DQ<8>")
	)
	(segment
		(start 44.04233 -290.410392)
		(end 45.22597 -290.410392)
		(width 0.14478)
		(layer "In4.Cu")
		(net "M_D_CPU1_SB_DQ<8>")
	)
	(segment
		(start 59.187842 -290.410392)
		(end 59.966606 -290.410392)
		(width 0.14478)
		(layer "In4.Cu")
		(net "M_D_CPU1_SB_DQ<8>")
	)
	(segment
		(start 36.795964 -290.835334)
		(end 37.22116 -291.26053)
		(width 0.14478)
		(layer "In4.Cu")
		(net "M_D_CPU1_SB_DQ<8>")
	)
	(segment
		(start 61.615828 -289.658044)
		(end 61.77788 -289.495992)
		(width 0.14478)
		(layer "In4.Cu")
		(net "M_D_CPU1_SB_DQ<8>")
	)
	(segment
		(start 40.801544 -291.26053)
		(end 41.10482 -291.563806)
		(width 0.14478)
		(layer "In4.Cu")
		(net "M_D_CPU1_SB_DQ<8>")
	)
	(segment
		(start 61.167264 -289.437572)
		(end 61.387736 -289.658044)
		(width 0.14478)
		(layer "In4.Cu")
		(net "M_D_CPU1_SB_DQ<8>")
	)
	(segment
		(start 54.960774 -291.532564)
		(end 55.232808 -291.26053)
		(width 0.14478)
		(layer "In4.Cu")
		(net "M_D_CPU1_SB_DQ<8>")
	)
	(segment
		(start 76.675742 -278.792686)
		(end 78.029308 -278.792686)
		(width 0.0889)
		(layer "In4.Cu")
		(net "M_D_CPU1_SB_DQ<8>")
	)
	(segment
		(start 37.990018 -291.655754)
		(end 38.202108 -291.655754)
		(width 0.14478)
		(layer "In4.Cu")
		(net "M_D_CPU1_SB_DQ<8>")
	)
	(segment
		(start 48.136556 -291.26053)
		(end 48.430434 -290.966652)
		(width 0.14478)
		(layer "In4.Cu")
		(net "M_D_CPU1_SB_DQ<8>")
	)
	(segment
		(start 60.777374 -289.599624)
		(end 60.939426 -289.437572)
		(width 0.14478)
		(layer "In4.Cu")
		(net "M_D_CPU1_SB_DQ<8>")
	)
	(segment
		(start 58.631582 -290.719764)
		(end 58.87847 -290.719764)
		(width 0.14478)
		(layer "In4.Cu")
		(net "M_D_CPU1_SB_DQ<8>")
	)
	(segment
		(start 89.803986 -279.268936)
		(end 89.812368 -279.273762)
		(width 0.0889)
		(layer "In4.Cu")
		(net "M_D_CPU1_SB_DQ<8>")
	)
	(segment
		(start 60.995814 -290.273994)
		(end 60.995814 -290.046156)
		(width 0.14478)
		(layer "In4.Cu")
		(net "M_D_CPU1_SB_DQ<8>")
	)
	(segment
		(start 52.303934 -290.410392)
		(end 52.587906 -290.694364)
		(width 0.14478)
		(layer "In4.Cu")
		(net "M_D_CPU1_SB_DQ<8>")
	)
	(segment
		(start 56.313324 -291.127942)
		(end 56.313324 -291.494464)
		(width 0.14478)
		(layer "In4.Cu")
		(net "M_D_CPU1_SB_DQ<8>")
	)
	(segment
		(start 59.966606 -290.410392)
		(end 60.159138 -290.21786)
		(width 0.14478)
		(layer "In4.Cu")
		(net "M_D_CPU1_SB_DQ<8>")
	)
	(segment
		(start 76.62545 -278.742394)
		(end 76.675742 -278.792686)
		(width 0.0889)
		(layer "In4.Cu")
		(net "M_D_CPU1_SB_DQ<8>")
	)
	(segment
		(start 60.995814 -290.046156)
		(end 60.777374 -289.827716)
		(width 0.14478)
		(layer "In4.Cu")
		(net "M_D_CPU1_SB_DQ<8>")
	)
	(segment
		(start 56.474614 -291.655754)
		(end 56.70804 -291.655754)
		(width 0.14478)
		(layer "In4.Cu")
		(net "M_D_CPU1_SB_DQ<8>")
	)
	(arc
		(start 84.163916 -279.268936)
		(mid 84.346167 -279.319286)
		(end 84.529676 -279.273762)
		(width 0.0889)
		(layer "In4.Cu")
		(net "M_D_CPU1_SB_DQ<8>")
	)
	(arc
		(start 85.478112 -279.268936)
		(mid 85.761068 -279.192759)
		(end 86.044024 -279.268936)
		(width 0.0889)
		(layer "In4.Cu")
		(net "M_D_CPU1_SB_DQ<8>")
	)
	(arc
		(start 80.403954 -279.268936)
		(mid 80.586205 -279.319286)
		(end 80.769714 -279.273762)
		(width 0.0889)
		(layer "In4.Cu")
		(net "M_D_CPU1_SB_DQ<8>")
	)
	(arc
		(start 78.523592 -279.268936)
		(mid 78.70022 -279.319169)
		(end 78.879446 -279.279096)
		(width 0.0889)
		(layer "In4.Cu")
		(net "M_D_CPU1_SB_DQ<8>")
	)
	(arc
		(start 78.446884 -279.210262)
		(mid 78.483211 -279.242075)
		(end 78.523338 -279.268936)
		(width 0.0889)
		(layer "In4.Cu")
		(net "M_D_CPU1_SB_DQ<8>")
	)
	(arc
		(start 82.65795 -279.268936)
		(mid 82.940906 -279.192759)
		(end 83.223862 -279.268936)
		(width 0.0889)
		(layer "In4.Cu")
		(net "M_D_CPU1_SB_DQ<8>")
	)
	(arc
		(start 82.284062 -279.268936)
		(mid 82.471006 -279.319191)
		(end 82.65795 -279.268936)
		(width 0.0889)
		(layer "In4.Cu")
		(net "M_D_CPU1_SB_DQ<8>")
	)
	(arc
		(start 89.812368 -279.273762)
		(mid 89.995876 -279.319256)
		(end 90.178128 -279.268936)
		(width 0.0889)
		(layer "In4.Cu")
		(net "M_D_CPU1_SB_DQ<8>")
	)
	(arc
		(start 84.538058 -279.268936)
		(mid 84.821014 -279.192759)
		(end 85.10397 -279.268936)
		(width 0.0889)
		(layer "In4.Cu")
		(net "M_D_CPU1_SB_DQ<8>")
	)
	(arc
		(start 79.837788 -279.268936)
		(mid 80.114855 -279.192665)
		(end 80.39354 -279.26284)
		(width 0.0889)
		(layer "In4.Cu")
		(net "M_D_CPU1_SB_DQ<8>")
	)
	(arc
		(start 87.357966 -279.268936)
		(mid 87.640922 -279.192759)
		(end 87.923878 -279.268936)
		(width 0.0889)
		(layer "In4.Cu")
		(net "M_D_CPU1_SB_DQ<8>")
	)
	(arc
		(start 85.112352 -279.273762)
		(mid 85.29586 -279.319256)
		(end 85.478112 -279.268936)
		(width 0.0889)
		(layer "In4.Cu")
		(net "M_D_CPU1_SB_DQ<8>")
	)
	(arc
		(start 90.752422 -279.273762)
		(mid 90.905292 -279.318403)
		(end 91.06281 -279.295098)
		(width 0.0889)
		(layer "In4.Cu")
		(net "M_D_CPU1_SB_DQ<8>")
	)
	(arc
		(start 83.598004 -279.268936)
		(mid 83.88096 -279.192759)
		(end 84.163916 -279.268936)
		(width 0.0889)
		(layer "In4.Cu")
		(net "M_D_CPU1_SB_DQ<8>")
	)
	(arc
		(start 89.238074 -279.268936)
		(mid 89.52103 -279.192759)
		(end 89.803986 -279.268936)
		(width 0.0889)
		(layer "In4.Cu")
		(net "M_D_CPU1_SB_DQ<8>")
	)
	(arc
		(start 88.29802 -279.268936)
		(mid 88.580976 -279.192759)
		(end 88.863932 -279.268936)
		(width 0.0889)
		(layer "In4.Cu")
		(net "M_D_CPU1_SB_DQ<8>")
	)
	(arc
		(start 80.778096 -279.268936)
		(mid 81.061052 -279.192759)
		(end 81.344008 -279.268936)
		(width 0.0889)
		(layer "In4.Cu")
		(net "M_D_CPU1_SB_DQ<8>")
	)
	(arc
		(start 78.903322 -279.26538)
		(mid 79.183711 -279.192711)
		(end 79.463138 -279.268936)
		(width 0.0889)
		(layer "In4.Cu")
		(net "M_D_CPU1_SB_DQ<8>")
	)
	(arc
		(start 81.35239 -279.273762)
		(mid 81.535898 -279.319256)
		(end 81.71815 -279.268936)
		(width 0.0889)
		(layer "In4.Cu")
		(net "M_D_CPU1_SB_DQ<8>")
	)
	(arc
		(start 81.71815 -279.268936)
		(mid 82.001106 -279.192759)
		(end 82.284062 -279.268936)
		(width 0.0889)
		(layer "In4.Cu")
		(net "M_D_CPU1_SB_DQ<8>")
	)
	(arc
		(start 87.923878 -279.268936)
		(mid 88.106129 -279.319286)
		(end 88.289638 -279.273762)
		(width 0.0889)
		(layer "In4.Cu")
		(net "M_D_CPU1_SB_DQ<8>")
	)
	(arc
		(start 86.984078 -279.268936)
		(mid 87.171022 -279.319191)
		(end 87.357966 -279.268936)
		(width 0.0889)
		(layer "In4.Cu")
		(net "M_D_CPU1_SB_DQ<8>")
	)
	(arc
		(start 83.223862 -279.268936)
		(mid 83.406113 -279.319286)
		(end 83.589622 -279.273762)
		(width 0.0889)
		(layer "In4.Cu")
		(net "M_D_CPU1_SB_DQ<8>")
	)
	(arc
		(start 79.47152 -279.273762)
		(mid 79.655282 -279.319378)
		(end 79.837788 -279.268936)
		(width 0.0889)
		(layer "In4.Cu")
		(net "M_D_CPU1_SB_DQ<8>")
	)
	(arc
		(start 88.863932 -279.268936)
		(mid 89.046183 -279.319286)
		(end 89.229692 -279.273762)
		(width 0.0889)
		(layer "In4.Cu")
		(net "M_D_CPU1_SB_DQ<8>")
	)
	(arc
		(start 86.052406 -279.273762)
		(mid 86.235914 -279.319256)
		(end 86.418166 -279.268936)
		(width 0.0889)
		(layer "In4.Cu")
		(net "M_D_CPU1_SB_DQ<8>")
	)
	(arc
		(start 86.418166 -279.268936)
		(mid 86.701122 -279.192759)
		(end 86.984078 -279.268936)
		(width 0.0889)
		(layer "In4.Cu")
		(net "M_D_CPU1_SB_DQ<8>")
	)
	(arc
		(start 90.178128 -279.268936)
		(mid 90.461084 -279.192759)
		(end 90.74404 -279.268936)
		(width 0.0889)
		(layer "In4.Cu")
		(net "M_D_CPU1_SB_DQ<8>")
	)
	(segment
		(start 93.277944 -278.680418)
		(end 92.811092 -278.946356)
		(width 0.10668)
		(layer "F.Cu")
		(net "M_D_CPU1_SB_DQ<7>")
	)
	(segment
		(start 80.769714 -278.61895)
		(end 80.778096 -278.623776)
		(width 0.0889)
		(layer "In4.Cu")
		(net "M_D_CPU1_SB_DQ<7>")
	)
	(segment
		(start 33.120838 -290.410392)
		(end 42.158158 -290.410392)
		(width 0.14478)
		(layer "In4.Cu")
		(net "M_D_CPU1_SB_DQ<7>")
	)
	(segment
		(start 50.554636 -289.560254)
		(end 52.34813 -289.560254)
		(width 0.14478)
		(layer "In4.Cu")
		(net "M_D_CPU1_SB_DQ<7>")
	)
	(segment
		(start 89.229692 -278.61895)
		(end 89.238074 -278.623776)
		(width 0.0889)
		(layer "In4.Cu")
		(net "M_D_CPU1_SB_DQ<7>")
	)
	(segment
		(start 80.39354 -278.629872)
		(end 80.403954 -278.623776)
		(width 0.0889)
		(layer "In4.Cu")
		(net "M_D_CPU1_SB_DQ<7>")
	)
	(segment
		(start 81.344008 -278.623776)
		(end 81.35239 -278.61895)
		(width 0.0889)
		(layer "In4.Cu")
		(net "M_D_CPU1_SB_DQ<7>")
	)
	(segment
		(start 57.33288 -290.033964)
		(end 58.476642 -289.560254)
		(width 0.14478)
		(layer "In4.Cu")
		(net "M_D_CPU1_SB_DQ<7>")
	)
	(segment
		(start 76.034392 -278.287734)
		(end 76.580238 -278.287734)
		(width 0.0889)
		(layer "In4.Cu")
		(net "M_D_CPU1_SB_DQ<7>")
	)
	(segment
		(start 86.044024 -278.623776)
		(end 86.052406 -278.61895)
		(width 0.0889)
		(layer "In4.Cu")
		(net "M_D_CPU1_SB_DQ<7>")
	)
	(segment
		(start 53.491892 -290.033964)
		(end 57.33288 -290.033964)
		(width 0.14478)
		(layer "In4.Cu")
		(net "M_D_CPU1_SB_DQ<7>")
	)
	(segment
		(start 52.34813 -289.560254)
		(end 53.491892 -290.033964)
		(width 0.14478)
		(layer "In4.Cu")
		(net "M_D_CPU1_SB_DQ<7>")
	)
	(segment
		(start 90.74404 -278.623776)
		(end 90.752422 -278.61895)
		(width 0.0889)
		(layer "In4.Cu")
		(net "M_D_CPU1_SB_DQ<7>")
	)
	(segment
		(start 92.560648 -278.655526)
		(end 92.656914 -278.680926)
		(width 0.0889)
		(layer "In4.Cu")
		(net "M_D_CPU1_SB_DQ<7>")
	)
	(segment
		(start 46.136814 -290.410392)
		(end 49.704498 -290.410392)
		(width 0.14478)
		(layer "In4.Cu")
		(net "M_D_CPU1_SB_DQ<7>")
	)
	(segment
		(start 45.286676 -289.560254)
		(end 46.136814 -290.410392)
		(width 0.14478)
		(layer "In4.Cu")
		(net "M_D_CPU1_SB_DQ<7>")
	)
	(segment
		(start 84.529676 -278.61895)
		(end 84.538058 -278.623776)
		(width 0.0889)
		(layer "In4.Cu")
		(net "M_D_CPU1_SB_DQ<7>")
	)
	(segment
		(start 60.037218 -289.560254)
		(end 71.309738 -278.287734)
		(width 0.14478)
		(layer "In4.Cu")
		(net "M_D_CPU1_SB_DQ<7>")
	)
	(segment
		(start 76.580238 -278.287734)
		(end 76.747116 -278.454612)
		(width 0.0889)
		(layer "In4.Cu")
		(net "M_D_CPU1_SB_DQ<7>")
	)
	(segment
		(start 88.289638 -278.61895)
		(end 88.29802 -278.623776)
		(width 0.0889)
		(layer "In4.Cu")
		(net "M_D_CPU1_SB_DQ<7>")
	)
	(segment
		(start 32.695896 -289.98545)
		(end 33.120838 -290.410392)
		(width 0.14478)
		(layer "In4.Cu")
		(net "M_D_CPU1_SB_DQ<7>")
	)
	(segment
		(start 89.803986 -278.623776)
		(end 89.812368 -278.61895)
		(width 0.0889)
		(layer "In4.Cu")
		(net "M_D_CPU1_SB_DQ<7>")
	)
	(segment
		(start 49.704498 -290.410392)
		(end 50.554636 -289.560254)
		(width 0.14478)
		(layer "In4.Cu")
		(net "M_D_CPU1_SB_DQ<7>")
	)
	(segment
		(start 43.008296 -289.560254)
		(end 45.286676 -289.560254)
		(width 0.14478)
		(layer "In4.Cu")
		(net "M_D_CPU1_SB_DQ<7>")
	)
	(segment
		(start 92.656914 -278.680926)
		(end 92.811092 -278.946356)
		(width 0.0889)
		(layer "In4.Cu")
		(net "M_D_CPU1_SB_DQ<7>")
	)
	(segment
		(start 85.10397 -278.623776)
		(end 85.112352 -278.61895)
		(width 0.0889)
		(layer "In4.Cu")
		(net "M_D_CPU1_SB_DQ<7>")
	)
	(segment
		(start 76.82738 -278.487886)
		(end 79.334868 -278.487886)
		(width 0.0889)
		(layer "In4.Cu")
		(net "M_D_CPU1_SB_DQ<7>")
	)
	(segment
		(start 83.589622 -278.61895)
		(end 83.598004 -278.623776)
		(width 0.0889)
		(layer "In4.Cu")
		(net "M_D_CPU1_SB_DQ<7>")
	)
	(segment
		(start 58.476642 -289.560254)
		(end 60.037218 -289.560254)
		(width 0.14478)
		(layer "In4.Cu")
		(net "M_D_CPU1_SB_DQ<7>")
	)
	(segment
		(start 71.309738 -278.287734)
		(end 76.034392 -278.287734)
		(width 0.14478)
		(layer "In4.Cu")
		(net "M_D_CPU1_SB_DQ<7>")
	)
	(segment
		(start 42.158158 -290.410392)
		(end 43.008296 -289.560254)
		(width 0.14478)
		(layer "In4.Cu")
		(net "M_D_CPU1_SB_DQ<7>")
	)
	(arc
		(start 79.334868 -278.487886)
		(mid 79.595344 -278.52246)
		(end 79.837788 -278.623776)
		(width 0.0889)
		(layer "In4.Cu")
		(net "M_D_CPU1_SB_DQ<7>")
	)
	(arc
		(start 83.598004 -278.623776)
		(mid 83.88096 -278.699953)
		(end 84.163916 -278.623776)
		(width 0.0889)
		(layer "In4.Cu")
		(net "M_D_CPU1_SB_DQ<7>")
	)
	(arc
		(start 86.984078 -278.623776)
		(mid 87.171022 -278.573521)
		(end 87.357966 -278.623776)
		(width 0.0889)
		(layer "In4.Cu")
		(net "M_D_CPU1_SB_DQ<7>")
	)
	(arc
		(start 80.403954 -278.623776)
		(mid 80.586205 -278.573426)
		(end 80.769714 -278.61895)
		(width 0.0889)
		(layer "In4.Cu")
		(net "M_D_CPU1_SB_DQ<7>")
	)
	(arc
		(start 88.29802 -278.623776)
		(mid 88.580976 -278.699953)
		(end 88.863932 -278.623776)
		(width 0.0889)
		(layer "In4.Cu")
		(net "M_D_CPU1_SB_DQ<7>")
	)
	(arc
		(start 82.284062 -278.623776)
		(mid 82.471006 -278.573521)
		(end 82.65795 -278.623776)
		(width 0.0889)
		(layer "In4.Cu")
		(net "M_D_CPU1_SB_DQ<7>")
	)
	(arc
		(start 79.837788 -278.623776)
		(mid 80.114855 -278.700047)
		(end 80.39354 -278.629872)
		(width 0.0889)
		(layer "In4.Cu")
		(net "M_D_CPU1_SB_DQ<7>")
	)
	(arc
		(start 87.357966 -278.623776)
		(mid 87.640922 -278.699953)
		(end 87.923878 -278.623776)
		(width 0.0889)
		(layer "In4.Cu")
		(net "M_D_CPU1_SB_DQ<7>")
	)
	(arc
		(start 91.118182 -278.623776)
		(mid 91.401138 -278.699953)
		(end 91.684094 -278.623776)
		(width 0.0889)
		(layer "In4.Cu")
		(net "M_D_CPU1_SB_DQ<7>")
	)
	(arc
		(start 84.538058 -278.623776)
		(mid 84.821014 -278.699953)
		(end 85.10397 -278.623776)
		(width 0.0889)
		(layer "In4.Cu")
		(net "M_D_CPU1_SB_DQ<7>")
	)
	(arc
		(start 84.163916 -278.623776)
		(mid 84.346167 -278.573426)
		(end 84.529676 -278.61895)
		(width 0.0889)
		(layer "In4.Cu")
		(net "M_D_CPU1_SB_DQ<7>")
	)
	(arc
		(start 80.778096 -278.623776)
		(mid 81.061052 -278.699953)
		(end 81.344008 -278.623776)
		(width 0.0889)
		(layer "In4.Cu")
		(net "M_D_CPU1_SB_DQ<7>")
	)
	(arc
		(start 90.178128 -278.623776)
		(mid 90.461084 -278.699953)
		(end 90.74404 -278.623776)
		(width 0.0889)
		(layer "In4.Cu")
		(net "M_D_CPU1_SB_DQ<7>")
	)
	(arc
		(start 85.112352 -278.61895)
		(mid 85.29586 -278.573456)
		(end 85.478112 -278.623776)
		(width 0.0889)
		(layer "In4.Cu")
		(net "M_D_CPU1_SB_DQ<7>")
	)
	(arc
		(start 90.752422 -278.61895)
		(mid 90.93593 -278.573456)
		(end 91.118182 -278.623776)
		(width 0.0889)
		(layer "In4.Cu")
		(net "M_D_CPU1_SB_DQ<7>")
	)
	(arc
		(start 91.684094 -278.623776)
		(mid 91.871038 -278.573521)
		(end 92.057982 -278.623776)
		(width 0.0889)
		(layer "In4.Cu")
		(net "M_D_CPU1_SB_DQ<7>")
	)
	(arc
		(start 81.71815 -278.623776)
		(mid 82.001106 -278.699953)
		(end 82.284062 -278.623776)
		(width 0.0889)
		(layer "In4.Cu")
		(net "M_D_CPU1_SB_DQ<7>")
	)
	(arc
		(start 81.35239 -278.61895)
		(mid 81.535898 -278.573456)
		(end 81.71815 -278.623776)
		(width 0.0889)
		(layer "In4.Cu")
		(net "M_D_CPU1_SB_DQ<7>")
	)
	(arc
		(start 76.747116 -278.454612)
		(mid 76.783927 -278.479272)
		(end 76.82738 -278.487886)
		(width 0.0889)
		(layer "In4.Cu")
		(net "M_D_CPU1_SB_DQ<7>")
	)
	(arc
		(start 87.923878 -278.623776)
		(mid 88.106129 -278.573426)
		(end 88.289638 -278.61895)
		(width 0.0889)
		(layer "In4.Cu")
		(net "M_D_CPU1_SB_DQ<7>")
	)
	(arc
		(start 88.863932 -278.623776)
		(mid 89.046183 -278.573426)
		(end 89.229692 -278.61895)
		(width 0.0889)
		(layer "In4.Cu")
		(net "M_D_CPU1_SB_DQ<7>")
	)
	(arc
		(start 86.418166 -278.623776)
		(mid 86.701122 -278.699953)
		(end 86.984078 -278.623776)
		(width 0.0889)
		(layer "In4.Cu")
		(net "M_D_CPU1_SB_DQ<7>")
	)
	(arc
		(start 82.65795 -278.623776)
		(mid 82.940906 -278.699953)
		(end 83.223862 -278.623776)
		(width 0.0889)
		(layer "In4.Cu")
		(net "M_D_CPU1_SB_DQ<7>")
	)
	(arc
		(start 86.052406 -278.61895)
		(mid 86.235914 -278.573456)
		(end 86.418166 -278.623776)
		(width 0.0889)
		(layer "In4.Cu")
		(net "M_D_CPU1_SB_DQ<7>")
	)
	(arc
		(start 89.812368 -278.61895)
		(mid 89.995876 -278.573456)
		(end 90.178128 -278.623776)
		(width 0.0889)
		(layer "In4.Cu")
		(net "M_D_CPU1_SB_DQ<7>")
	)
	(arc
		(start 92.057982 -278.623776)
		(mid 92.305578 -278.698954)
		(end 92.560648 -278.655526)
		(width 0.0889)
		(layer "In4.Cu")
		(net "M_D_CPU1_SB_DQ<7>")
	)
	(arc
		(start 83.223862 -278.623776)
		(mid 83.406113 -278.573426)
		(end 83.589622 -278.61895)
		(width 0.0889)
		(layer "In4.Cu")
		(net "M_D_CPU1_SB_DQ<7>")
	)
	(arc
		(start 89.238074 -278.623776)
		(mid 89.52103 -278.699953)
		(end 89.803986 -278.623776)
		(width 0.0889)
		(layer "In4.Cu")
		(net "M_D_CPU1_SB_DQ<7>")
	)
	(arc
		(start 85.478112 -278.623776)
		(mid 85.761068 -278.699953)
		(end 86.044024 -278.623776)
		(width 0.0889)
		(layer "In4.Cu")
		(net "M_D_CPU1_SB_DQ<7>")
	)
	(segment
		(start 91.86799 -277.870412)
		(end 91.401138 -278.13635)
		(width 0.10668)
		(layer "F.Cu")
		(net "M_D_CPU1_SB_DQ<6>")
	)
	(segment
		(start 45.935138 -288.71037)
		(end 50.11801 -288.71037)
		(width 0.14478)
		(layer "In4.Cu")
		(net "M_D_CPU1_SB_DQ<6>")
	)
	(segment
		(start 57.447434 -288.71037)
		(end 58.297572 -287.860232)
		(width 0.14478)
		(layer "In4.Cu")
		(net "M_D_CPU1_SB_DQ<6>")
	)
	(segment
		(start 34.832544 -288.548826)
		(end 34.832544 -288.22015)
		(width 0.14478)
		(layer "In4.Cu")
		(net "M_D_CPU1_SB_DQ<6>")
	)
	(segment
		(start 42.309034 -288.71037)
		(end 43.159172 -287.860232)
		(width 0.14478)
		(layer "In4.Cu")
		(net "M_D_CPU1_SB_DQ<6>")
	)
	(segment
		(start 82.753962 -277.81377)
		(end 82.762344 -277.808944)
		(width 0.0889)
		(layer "In4.Cu")
		(net "M_D_CPU1_SB_DQ<6>")
	)
	(segment
		(start 70.946772 -277.378414)
		(end 75.954636 -277.378414)
		(width 0.14478)
		(layer "In4.Cu")
		(net "M_D_CPU1_SB_DQ<6>")
	)
	(segment
		(start 34.671 -288.71037)
		(end 34.832544 -288.548826)
		(width 0.14478)
		(layer "In4.Cu")
		(net "M_D_CPU1_SB_DQ<6>")
	)
	(segment
		(start 90.639646 -277.808944)
		(end 90.648028 -277.81377)
		(width 0.0889)
		(layer "In4.Cu")
		(net "M_D_CPU1_SB_DQ<6>")
	)
	(segment
		(start 88.394032 -277.81377)
		(end 88.402414 -277.808944)
		(width 0.0889)
		(layer "In4.Cu")
		(net "M_D_CPU1_SB_DQ<6>")
	)
	(segment
		(start 58.297572 -287.860232)
		(end 60.464954 -287.860232)
		(width 0.14478)
		(layer "In4.Cu")
		(net "M_D_CPU1_SB_DQ<6>")
	)
	(segment
		(start 78.993492 -277.814024)
		(end 79.009748 -277.804626)
		(width 0.0889)
		(layer "In4.Cu")
		(net "M_D_CPU1_SB_DQ<6>")
	)
	(segment
		(start 82.179668 -277.808944)
		(end 82.18805 -277.81377)
		(width 0.0889)
		(layer "In4.Cu")
		(net "M_D_CPU1_SB_DQ<6>")
	)
	(segment
		(start 35.383978 -288.548826)
		(end 35.545522 -288.71037)
		(width 0.14478)
		(layer "In4.Cu")
		(net "M_D_CPU1_SB_DQ<6>")
	)
	(segment
		(start 77.969618 -277.378414)
		(end 78.481174 -277.88997)
		(width 0.0889)
		(layer "In4.Cu")
		(net "M_D_CPU1_SB_DQ<6>")
	)
	(segment
		(start 35.545522 -288.71037)
		(end 42.309034 -288.71037)
		(width 0.14478)
		(layer "In4.Cu")
		(net "M_D_CPU1_SB_DQ<6>")
	)
	(segment
		(start 32.695896 -288.285428)
		(end 33.120838 -288.71037)
		(width 0.14478)
		(layer "In4.Cu")
		(net "M_D_CPU1_SB_DQ<6>")
	)
	(segment
		(start 34.832544 -288.22015)
		(end 34.994088 -288.058606)
		(width 0.14478)
		(layer "In4.Cu")
		(net "M_D_CPU1_SB_DQ<6>")
	)
	(segment
		(start 50.11801 -288.71037)
		(end 50.968148 -287.860232)
		(width 0.14478)
		(layer "In4.Cu")
		(net "M_D_CPU1_SB_DQ<6>")
	)
	(segment
		(start 91.24696 -277.87092)
		(end 91.401138 -278.13635)
		(width 0.0889)
		(layer "In4.Cu")
		(net "M_D_CPU1_SB_DQ<6>")
	)
	(segment
		(start 75.954636 -277.378414)
		(end 77.969618 -277.378414)
		(width 0.0889)
		(layer "In4.Cu")
		(net "M_D_CPU1_SB_DQ<6>")
	)
	(segment
		(start 53.725318 -288.71037)
		(end 57.447434 -288.71037)
		(width 0.14478)
		(layer "In4.Cu")
		(net "M_D_CPU1_SB_DQ<6>")
	)
	(segment
		(start 87.453978 -277.81377)
		(end 87.46236 -277.808944)
		(width 0.0889)
		(layer "In4.Cu")
		(net "M_D_CPU1_SB_DQ<6>")
	)
	(segment
		(start 80.299814 -277.808944)
		(end 80.308196 -277.81377)
		(width 0.0889)
		(layer "In4.Cu")
		(net "M_D_CPU1_SB_DQ<6>")
	)
	(segment
		(start 33.120838 -288.71037)
		(end 34.671 -288.71037)
		(width 0.14478)
		(layer "In4.Cu")
		(net "M_D_CPU1_SB_DQ<6>")
	)
	(segment
		(start 91.150694 -277.84552)
		(end 91.24696 -277.87092)
		(width 0.0889)
		(layer "In4.Cu")
		(net "M_D_CPU1_SB_DQ<6>")
	)
	(segment
		(start 86.879684 -277.808944)
		(end 86.888066 -277.81377)
		(width 0.0889)
		(layer "In4.Cu")
		(net "M_D_CPU1_SB_DQ<6>")
	)
	(segment
		(start 34.994088 -288.058606)
		(end 35.222434 -288.058606)
		(width 0.14478)
		(layer "In4.Cu")
		(net "M_D_CPU1_SB_DQ<6>")
	)
	(segment
		(start 35.383978 -288.22015)
		(end 35.383978 -288.548826)
		(width 0.14478)
		(layer "In4.Cu")
		(net "M_D_CPU1_SB_DQ<6>")
	)
	(segment
		(start 79.36738 -277.81377)
		(end 79.377794 -277.819866)
		(width 0.0889)
		(layer "In4.Cu")
		(net "M_D_CPU1_SB_DQ<6>")
	)
	(segment
		(start 43.159172 -287.860232)
		(end 45.085 -287.860232)
		(width 0.14478)
		(layer "In4.Cu")
		(net "M_D_CPU1_SB_DQ<6>")
	)
	(segment
		(start 50.968148 -287.860232)
		(end 52.87518 -287.860232)
		(width 0.14478)
		(layer "In4.Cu")
		(net "M_D_CPU1_SB_DQ<6>")
	)
	(segment
		(start 83.694016 -277.81377)
		(end 83.702398 -277.808944)
		(width 0.0889)
		(layer "In4.Cu")
		(net "M_D_CPU1_SB_DQ<6>")
	)
	(segment
		(start 60.464954 -287.860232)
		(end 70.946772 -277.378414)
		(width 0.14478)
		(layer "In4.Cu")
		(net "M_D_CPU1_SB_DQ<6>")
	)
	(segment
		(start 78.481174 -277.88997)
		(end 78.711044 -277.88997)
		(width 0.0889)
		(layer "In4.Cu")
		(net "M_D_CPU1_SB_DQ<6>")
	)
	(segment
		(start 85.93963 -277.808944)
		(end 85.948012 -277.81377)
		(width 0.0889)
		(layer "In4.Cu")
		(net "M_D_CPU1_SB_DQ<6>")
	)
	(segment
		(start 52.87518 -287.860232)
		(end 53.725318 -288.71037)
		(width 0.14478)
		(layer "In4.Cu")
		(net "M_D_CPU1_SB_DQ<6>")
	)
	(segment
		(start 45.085 -287.860232)
		(end 45.935138 -288.71037)
		(width 0.14478)
		(layer "In4.Cu")
		(net "M_D_CPU1_SB_DQ<6>")
	)
	(segment
		(start 35.222434 -288.058606)
		(end 35.383978 -288.22015)
		(width 0.14478)
		(layer "In4.Cu")
		(net "M_D_CPU1_SB_DQ<6>")
	)
	(arc
		(start 81.813908 -277.81377)
		(mid 81.996159 -277.76342)
		(end 82.179668 -277.808944)
		(width 0.0889)
		(layer "In4.Cu")
		(net "M_D_CPU1_SB_DQ<6>")
	)
	(arc
		(start 80.308196 -277.81377)
		(mid 80.591152 -277.889947)
		(end 80.874108 -277.81377)
		(width 0.0889)
		(layer "In4.Cu")
		(net "M_D_CPU1_SB_DQ<6>")
	)
	(arc
		(start 81.247996 -277.81377)
		(mid 81.530952 -277.889947)
		(end 81.813908 -277.81377)
		(width 0.0889)
		(layer "In4.Cu")
		(net "M_D_CPU1_SB_DQ<6>")
	)
	(arc
		(start 79.009748 -277.804626)
		(mid 79.18973 -277.763526)
		(end 79.36738 -277.81377)
		(width 0.0889)
		(layer "In4.Cu")
		(net "M_D_CPU1_SB_DQ<6>")
	)
	(arc
		(start 85.007958 -277.81377)
		(mid 85.290914 -277.889947)
		(end 85.57387 -277.81377)
		(width 0.0889)
		(layer "In4.Cu")
		(net "M_D_CPU1_SB_DQ<6>")
	)
	(arc
		(start 78.711044 -277.88997)
		(mid 78.857292 -277.870665)
		(end 78.993492 -277.814024)
		(width 0.0889)
		(layer "In4.Cu")
		(net "M_D_CPU1_SB_DQ<6>")
	)
	(arc
		(start 90.648028 -277.81377)
		(mid 90.895624 -277.888948)
		(end 91.150694 -277.84552)
		(width 0.0889)
		(layer "In4.Cu")
		(net "M_D_CPU1_SB_DQ<6>")
	)
	(arc
		(start 89.707974 -277.81377)
		(mid 89.99093 -277.889947)
		(end 90.273886 -277.81377)
		(width 0.0889)
		(layer "In4.Cu")
		(net "M_D_CPU1_SB_DQ<6>")
	)
	(arc
		(start 80.874108 -277.81377)
		(mid 81.061052 -277.763515)
		(end 81.247996 -277.81377)
		(width 0.0889)
		(layer "In4.Cu")
		(net "M_D_CPU1_SB_DQ<6>")
	)
	(arc
		(start 86.513924 -277.81377)
		(mid 86.696175 -277.76342)
		(end 86.879684 -277.808944)
		(width 0.0889)
		(layer "In4.Cu")
		(net "M_D_CPU1_SB_DQ<6>")
	)
	(arc
		(start 87.82812 -277.81377)
		(mid 88.111076 -277.889947)
		(end 88.394032 -277.81377)
		(width 0.0889)
		(layer "In4.Cu")
		(net "M_D_CPU1_SB_DQ<6>")
	)
	(arc
		(start 89.334086 -277.81377)
		(mid 89.52103 -277.763515)
		(end 89.707974 -277.81377)
		(width 0.0889)
		(layer "In4.Cu")
		(net "M_D_CPU1_SB_DQ<6>")
	)
	(arc
		(start 84.63407 -277.81377)
		(mid 84.821014 -277.763515)
		(end 85.007958 -277.81377)
		(width 0.0889)
		(layer "In4.Cu")
		(net "M_D_CPU1_SB_DQ<6>")
	)
	(arc
		(start 79.377794 -277.819866)
		(mid 79.65648 -277.890086)
		(end 79.933546 -277.81377)
		(width 0.0889)
		(layer "In4.Cu")
		(net "M_D_CPU1_SB_DQ<6>")
	)
	(arc
		(start 90.273886 -277.81377)
		(mid 90.456137 -277.76342)
		(end 90.639646 -277.808944)
		(width 0.0889)
		(layer "In4.Cu")
		(net "M_D_CPU1_SB_DQ<6>")
	)
	(arc
		(start 84.068158 -277.81377)
		(mid 84.351114 -277.889947)
		(end 84.63407 -277.81377)
		(width 0.0889)
		(layer "In4.Cu")
		(net "M_D_CPU1_SB_DQ<6>")
	)
	(arc
		(start 79.933546 -277.81377)
		(mid 80.116051 -277.763293)
		(end 80.299814 -277.808944)
		(width 0.0889)
		(layer "In4.Cu")
		(net "M_D_CPU1_SB_DQ<6>")
	)
	(arc
		(start 87.46236 -277.808944)
		(mid 87.645868 -277.76345)
		(end 87.82812 -277.81377)
		(width 0.0889)
		(layer "In4.Cu")
		(net "M_D_CPU1_SB_DQ<6>")
	)
	(arc
		(start 86.888066 -277.81377)
		(mid 87.171022 -277.889947)
		(end 87.453978 -277.81377)
		(width 0.0889)
		(layer "In4.Cu")
		(net "M_D_CPU1_SB_DQ<6>")
	)
	(arc
		(start 88.402414 -277.808944)
		(mid 88.585922 -277.76345)
		(end 88.768174 -277.81377)
		(width 0.0889)
		(layer "In4.Cu")
		(net "M_D_CPU1_SB_DQ<6>")
	)
	(arc
		(start 85.948012 -277.81377)
		(mid 86.230968 -277.889947)
		(end 86.513924 -277.81377)
		(width 0.0889)
		(layer "In4.Cu")
		(net "M_D_CPU1_SB_DQ<6>")
	)
	(arc
		(start 82.18805 -277.81377)
		(mid 82.471006 -277.889947)
		(end 82.753962 -277.81377)
		(width 0.0889)
		(layer "In4.Cu")
		(net "M_D_CPU1_SB_DQ<6>")
	)
	(arc
		(start 85.57387 -277.81377)
		(mid 85.756121 -277.76342)
		(end 85.93963 -277.808944)
		(width 0.0889)
		(layer "In4.Cu")
		(net "M_D_CPU1_SB_DQ<6>")
	)
	(arc
		(start 83.702398 -277.808944)
		(mid 83.885906 -277.76345)
		(end 84.068158 -277.81377)
		(width 0.0889)
		(layer "In4.Cu")
		(net "M_D_CPU1_SB_DQ<6>")
	)
	(arc
		(start 88.768174 -277.81377)
		(mid 89.05113 -277.889947)
		(end 89.334086 -277.81377)
		(width 0.0889)
		(layer "In4.Cu")
		(net "M_D_CPU1_SB_DQ<6>")
	)
	(arc
		(start 82.762344 -277.808944)
		(mid 82.945852 -277.76345)
		(end 83.128104 -277.81377)
		(width 0.0889)
		(layer "In4.Cu")
		(net "M_D_CPU1_SB_DQ<6>")
	)
	(arc
		(start 83.128104 -277.81377)
		(mid 83.41106 -277.889947)
		(end 83.694016 -277.81377)
		(width 0.0889)
		(layer "In4.Cu")
		(net "M_D_CPU1_SB_DQ<6>")
	)
	(segment
		(start 92.80779 -277.870412)
		(end 92.340938 -278.13635)
		(width 0.10668)
		(layer "F.Cu")
		(net "M_D_CPU1_SB_DQ<5>")
	)
	(segment
		(start 46.960028 -289.239452)
		(end 47.195232 -289.239452)
		(width 0.14478)
		(layer "In4.Cu")
		(net "M_D_CPU1_SB_DQ<5>")
	)
	(segment
		(start 37.593016 -289.932364)
		(end 37.82187 -289.932364)
		(width 0.14478)
		(layer "In4.Cu")
		(net "M_D_CPU1_SB_DQ<5>")
	)
	(segment
		(start 45.127164 -288.71037)
		(end 46.350936 -289.934142)
		(width 0.14478)
		(layer "In4.Cu")
		(net "M_D_CPU1_SB_DQ<5>")
	)
	(segment
		(start 49.081182 -289.333178)
		(end 49.081182 -289.787838)
		(width 0.14478)
		(layer "In4.Cu")
		(net "M_D_CPU1_SB_DQ<5>")
	)
	(segment
		(start 38.93439 -289.932364)
		(end 39.306246 -289.560508)
		(width 0.14478)
		(layer "In4.Cu")
		(net "M_D_CPU1_SB_DQ<5>")
	)
	(segment
		(start 92.153994 -278.45893)
		(end 92.162376 -278.463756)
		(width 0.0889)
		(layer "In4.Cu")
		(net "M_D_CPU1_SB_DQ<5>")
	)
	(segment
		(start 39.306246 -289.560508)
		(end 42.19067 -289.560508)
		(width 0.14478)
		(layer "In4.Cu")
		(net "M_D_CPU1_SB_DQ<5>")
	)
	(segment
		(start 71.128382 -277.833074)
		(end 76.034392 -277.833074)
		(width 0.14478)
		(layer "In4.Cu")
		(net "M_D_CPU1_SB_DQ<5>")
	)
	(segment
		(start 92.495116 -278.40178)
		(end 92.340938 -278.13635)
		(width 0.0889)
		(layer "In4.Cu")
		(net "M_D_CPU1_SB_DQ<5>")
	)
	(segment
		(start 47.195232 -289.239452)
		(end 47.516288 -289.560508)
		(width 0.14478)
		(layer "In4.Cu")
		(net "M_D_CPU1_SB_DQ<5>")
	)
	(segment
		(start 37.984684 -289.76955)
		(end 37.984684 -289.351466)
		(width 0.14478)
		(layer "In4.Cu")
		(net "M_D_CPU1_SB_DQ<5>")
	)
	(segment
		(start 36.795964 -289.135312)
		(end 37.593016 -289.932364)
		(width 0.14478)
		(layer "In4.Cu")
		(net "M_D_CPU1_SB_DQ<5>")
	)
	(segment
		(start 38.37813 -289.188652)
		(end 38.540944 -289.351466)
		(width 0.14478)
		(layer "In4.Cu")
		(net "M_D_CPU1_SB_DQ<5>")
	)
	(segment
		(start 49.081182 -289.787838)
		(end 49.243996 -289.950652)
		(width 0.14478)
		(layer "In4.Cu")
		(net "M_D_CPU1_SB_DQ<5>")
	)
	(segment
		(start 50.761392 -288.71037)
		(end 53.072792 -288.71037)
		(width 0.14478)
		(layer "In4.Cu")
		(net "M_D_CPU1_SB_DQ<5>")
	)
	(segment
		(start 37.82187 -289.932364)
		(end 37.984684 -289.76955)
		(width 0.14478)
		(layer "In4.Cu")
		(net "M_D_CPU1_SB_DQ<5>")
	)
	(segment
		(start 38.540944 -289.76955)
		(end 38.703758 -289.932364)
		(width 0.14478)
		(layer "In4.Cu")
		(net "M_D_CPU1_SB_DQ<5>")
	)
	(segment
		(start 37.984684 -289.351466)
		(end 38.147498 -289.188652)
		(width 0.14478)
		(layer "In4.Cu")
		(net "M_D_CPU1_SB_DQ<5>")
	)
	(segment
		(start 47.516288 -289.560508)
		(end 48.297592 -289.560508)
		(width 0.14478)
		(layer "In4.Cu")
		(net "M_D_CPU1_SB_DQ<5>")
	)
	(segment
		(start 42.19067 -289.560508)
		(end 43.040808 -288.71037)
		(width 0.14478)
		(layer "In4.Cu")
		(net "M_D_CPU1_SB_DQ<5>")
	)
	(segment
		(start 60.251086 -288.71037)
		(end 71.128382 -277.833074)
		(width 0.14478)
		(layer "In4.Cu")
		(net "M_D_CPU1_SB_DQ<5>")
	)
	(segment
		(start 91.5797 -278.463756)
		(end 91.588082 -278.45893)
		(width 0.0889)
		(layer "In4.Cu")
		(net "M_D_CPU1_SB_DQ<5>")
	)
	(segment
		(start 38.147498 -289.188652)
		(end 38.37813 -289.188652)
		(width 0.14478)
		(layer "In4.Cu")
		(net "M_D_CPU1_SB_DQ<5>")
	)
	(segment
		(start 76.529438 -277.833074)
		(end 76.927456 -278.231092)
		(width 0.0889)
		(layer "In4.Cu")
		(net "M_D_CPU1_SB_DQ<5>")
	)
	(segment
		(start 38.703758 -289.932364)
		(end 38.93439 -289.932364)
		(width 0.14478)
		(layer "In4.Cu")
		(net "M_D_CPU1_SB_DQ<5>")
	)
	(segment
		(start 85.93963 -278.463756)
		(end 85.948012 -278.45893)
		(width 0.0889)
		(layer "In4.Cu")
		(net "M_D_CPU1_SB_DQ<5>")
	)
	(segment
		(start 76.034392 -277.833074)
		(end 76.529438 -277.833074)
		(width 0.0889)
		(layer "In4.Cu")
		(net "M_D_CPU1_SB_DQ<5>")
	)
	(segment
		(start 46.7995 -289.39998)
		(end 46.960028 -289.239452)
		(width 0.14478)
		(layer "In4.Cu")
		(net "M_D_CPU1_SB_DQ<5>")
	)
	(segment
		(start 88.394032 -278.45893)
		(end 88.402414 -278.463756)
		(width 0.0889)
		(layer "In4.Cu")
		(net "M_D_CPU1_SB_DQ<5>")
	)
	(segment
		(start 38.540944 -289.351466)
		(end 38.540944 -289.76955)
		(width 0.14478)
		(layer "In4.Cu")
		(net "M_D_CPU1_SB_DQ<5>")
	)
	(segment
		(start 49.243996 -289.950652)
		(end 49.52111 -289.950652)
		(width 0.14478)
		(layer "In4.Cu")
		(net "M_D_CPU1_SB_DQ<5>")
	)
	(segment
		(start 82.753962 -278.45893)
		(end 82.762344 -278.463756)
		(width 0.0889)
		(layer "In4.Cu")
		(net "M_D_CPU1_SB_DQ<5>")
	)
	(segment
		(start 48.687736 -289.170364)
		(end 48.918368 -289.170364)
		(width 0.14478)
		(layer "In4.Cu")
		(net "M_D_CPU1_SB_DQ<5>")
	)
	(segment
		(start 57.282842 -289.560508)
		(end 58.13298 -288.71037)
		(width 0.14478)
		(layer "In4.Cu")
		(net "M_D_CPU1_SB_DQ<5>")
	)
	(segment
		(start 48.297592 -289.560508)
		(end 48.687736 -289.170364)
		(width 0.14478)
		(layer "In4.Cu")
		(net "M_D_CPU1_SB_DQ<5>")
	)
	(segment
		(start 46.350936 -289.934142)
		(end 46.586394 -289.934142)
		(width 0.14478)
		(layer "In4.Cu")
		(net "M_D_CPU1_SB_DQ<5>")
	)
	(segment
		(start 58.13298 -288.71037)
		(end 60.251086 -288.71037)
		(width 0.14478)
		(layer "In4.Cu")
		(net "M_D_CPU1_SB_DQ<5>")
	)
	(segment
		(start 48.918368 -289.170364)
		(end 49.081182 -289.333178)
		(width 0.14478)
		(layer "In4.Cu")
		(net "M_D_CPU1_SB_DQ<5>")
	)
	(segment
		(start 49.52111 -289.950652)
		(end 50.761392 -288.71037)
		(width 0.14478)
		(layer "In4.Cu")
		(net "M_D_CPU1_SB_DQ<5>")
	)
	(segment
		(start 86.879684 -278.463756)
		(end 86.888066 -278.45893)
		(width 0.0889)
		(layer "In4.Cu")
		(net "M_D_CPU1_SB_DQ<5>")
	)
	(segment
		(start 46.7995 -289.721036)
		(end 46.7995 -289.39998)
		(width 0.14478)
		(layer "In4.Cu")
		(net "M_D_CPU1_SB_DQ<5>")
	)
	(segment
		(start 46.586394 -289.934142)
		(end 46.7995 -289.721036)
		(width 0.14478)
		(layer "In4.Cu")
		(net "M_D_CPU1_SB_DQ<5>")
	)
	(segment
		(start 82.179668 -278.463756)
		(end 82.18805 -278.45893)
		(width 0.0889)
		(layer "In4.Cu")
		(net "M_D_CPU1_SB_DQ<5>")
	)
	(segment
		(start 90.639646 -278.463756)
		(end 90.648028 -278.45893)
		(width 0.0889)
		(layer "In4.Cu")
		(net "M_D_CPU1_SB_DQ<5>")
	)
	(segment
		(start 77.00772 -278.264366)
		(end 79.21244 -278.264366)
		(width 0.0889)
		(layer "In4.Cu")
		(net "M_D_CPU1_SB_DQ<5>")
	)
	(segment
		(start 43.040808 -288.71037)
		(end 45.127164 -288.71037)
		(width 0.14478)
		(layer "In4.Cu")
		(net "M_D_CPU1_SB_DQ<5>")
	)
	(segment
		(start 83.694016 -278.45893)
		(end 83.702398 -278.463756)
		(width 0.0889)
		(layer "In4.Cu")
		(net "M_D_CPU1_SB_DQ<5>")
	)
	(segment
		(start 92.472764 -278.485092)
		(end 92.495116 -278.40178)
		(width 0.0889)
		(layer "In4.Cu")
		(net "M_D_CPU1_SB_DQ<5>")
	)
	(segment
		(start 53.072792 -288.71037)
		(end 53.92293 -289.560508)
		(width 0.14478)
		(layer "In4.Cu")
		(net "M_D_CPU1_SB_DQ<5>")
	)
	(segment
		(start 87.453978 -278.45893)
		(end 87.46236 -278.463756)
		(width 0.0889)
		(layer "In4.Cu")
		(net "M_D_CPU1_SB_DQ<5>")
	)
	(segment
		(start 53.92293 -289.560508)
		(end 57.282842 -289.560508)
		(width 0.14478)
		(layer "In4.Cu")
		(net "M_D_CPU1_SB_DQ<5>")
	)
	(arc
		(start 87.82812 -278.45893)
		(mid 88.111076 -278.382753)
		(end 88.394032 -278.45893)
		(width 0.0889)
		(layer "In4.Cu")
		(net "M_D_CPU1_SB_DQ<5>")
	)
	(arc
		(start 83.702398 -278.463756)
		(mid 83.885906 -278.50925)
		(end 84.068158 -278.45893)
		(width 0.0889)
		(layer "In4.Cu")
		(net "M_D_CPU1_SB_DQ<5>")
	)
	(arc
		(start 79.21244 -278.264366)
		(mid 79.586015 -278.313851)
		(end 79.9338 -278.45893)
		(width 0.0889)
		(layer "In4.Cu")
		(net "M_D_CPU1_SB_DQ<5>")
	)
	(arc
		(start 85.57387 -278.45893)
		(mid 85.756121 -278.50928)
		(end 85.93963 -278.463756)
		(width 0.0889)
		(layer "In4.Cu")
		(net "M_D_CPU1_SB_DQ<5>")
	)
	(arc
		(start 89.334086 -278.45893)
		(mid 89.52103 -278.509185)
		(end 89.707974 -278.45893)
		(width 0.0889)
		(layer "In4.Cu")
		(net "M_D_CPU1_SB_DQ<5>")
	)
	(arc
		(start 81.247996 -278.45893)
		(mid 81.530952 -278.382753)
		(end 81.813908 -278.45893)
		(width 0.0889)
		(layer "In4.Cu")
		(net "M_D_CPU1_SB_DQ<5>")
	)
	(arc
		(start 87.46236 -278.463756)
		(mid 87.645868 -278.50925)
		(end 87.82812 -278.45893)
		(width 0.0889)
		(layer "In4.Cu")
		(net "M_D_CPU1_SB_DQ<5>")
	)
	(arc
		(start 90.273886 -278.45893)
		(mid 90.456137 -278.50928)
		(end 90.639646 -278.463756)
		(width 0.0889)
		(layer "In4.Cu")
		(net "M_D_CPU1_SB_DQ<5>")
	)
	(arc
		(start 82.762344 -278.463756)
		(mid 82.945852 -278.50925)
		(end 83.128104 -278.45893)
		(width 0.0889)
		(layer "In4.Cu")
		(net "M_D_CPU1_SB_DQ<5>")
	)
	(arc
		(start 79.9338 -278.45893)
		(mid 80.120998 -278.509312)
		(end 80.308196 -278.45893)
		(width 0.0889)
		(layer "In4.Cu")
		(net "M_D_CPU1_SB_DQ<5>")
	)
	(arc
		(start 91.21394 -278.45893)
		(mid 91.396191 -278.50928)
		(end 91.5797 -278.463756)
		(width 0.0889)
		(layer "In4.Cu")
		(net "M_D_CPU1_SB_DQ<5>")
	)
	(arc
		(start 84.068158 -278.45893)
		(mid 84.351114 -278.382753)
		(end 84.63407 -278.45893)
		(width 0.0889)
		(layer "In4.Cu")
		(net "M_D_CPU1_SB_DQ<5>")
	)
	(arc
		(start 80.308196 -278.45893)
		(mid 80.591152 -278.382753)
		(end 80.874108 -278.45893)
		(width 0.0889)
		(layer "In4.Cu")
		(net "M_D_CPU1_SB_DQ<5>")
	)
	(arc
		(start 76.927456 -278.231092)
		(mid 76.964267 -278.255752)
		(end 77.00772 -278.264366)
		(width 0.0889)
		(layer "In4.Cu")
		(net "M_D_CPU1_SB_DQ<5>")
	)
	(arc
		(start 85.007958 -278.45893)
		(mid 85.290914 -278.382753)
		(end 85.57387 -278.45893)
		(width 0.0889)
		(layer "In4.Cu")
		(net "M_D_CPU1_SB_DQ<5>")
	)
	(arc
		(start 90.648028 -278.45893)
		(mid 90.930984 -278.382753)
		(end 91.21394 -278.45893)
		(width 0.0889)
		(layer "In4.Cu")
		(net "M_D_CPU1_SB_DQ<5>")
	)
	(arc
		(start 88.768174 -278.45893)
		(mid 89.05113 -278.382753)
		(end 89.334086 -278.45893)
		(width 0.0889)
		(layer "In4.Cu")
		(net "M_D_CPU1_SB_DQ<5>")
	)
	(arc
		(start 81.813908 -278.45893)
		(mid 81.996159 -278.50928)
		(end 82.179668 -278.463756)
		(width 0.0889)
		(layer "In4.Cu")
		(net "M_D_CPU1_SB_DQ<5>")
	)
	(arc
		(start 85.948012 -278.45893)
		(mid 86.230968 -278.382753)
		(end 86.513924 -278.45893)
		(width 0.0889)
		(layer "In4.Cu")
		(net "M_D_CPU1_SB_DQ<5>")
	)
	(arc
		(start 83.128104 -278.45893)
		(mid 83.41106 -278.382753)
		(end 83.694016 -278.45893)
		(width 0.0889)
		(layer "In4.Cu")
		(net "M_D_CPU1_SB_DQ<5>")
	)
	(arc
		(start 80.874108 -278.45893)
		(mid 81.061052 -278.509185)
		(end 81.247996 -278.45893)
		(width 0.0889)
		(layer "In4.Cu")
		(net "M_D_CPU1_SB_DQ<5>")
	)
	(arc
		(start 84.63407 -278.45893)
		(mid 84.821014 -278.509185)
		(end 85.007958 -278.45893)
		(width 0.0889)
		(layer "In4.Cu")
		(net "M_D_CPU1_SB_DQ<5>")
	)
	(arc
		(start 86.888066 -278.45893)
		(mid 87.171022 -278.382753)
		(end 87.453978 -278.45893)
		(width 0.0889)
		(layer "In4.Cu")
		(net "M_D_CPU1_SB_DQ<5>")
	)
	(arc
		(start 86.513924 -278.45893)
		(mid 86.696175 -278.50928)
		(end 86.879684 -278.463756)
		(width 0.0889)
		(layer "In4.Cu")
		(net "M_D_CPU1_SB_DQ<5>")
	)
	(arc
		(start 91.588082 -278.45893)
		(mid 91.871038 -278.382753)
		(end 92.153994 -278.45893)
		(width 0.0889)
		(layer "In4.Cu")
		(net "M_D_CPU1_SB_DQ<5>")
	)
	(arc
		(start 89.707974 -278.45893)
		(mid 89.99093 -278.382753)
		(end 90.273886 -278.45893)
		(width 0.0889)
		(layer "In4.Cu")
		(net "M_D_CPU1_SB_DQ<5>")
	)
	(arc
		(start 88.402414 -278.463756)
		(mid 88.585922 -278.50925)
		(end 88.768174 -278.45893)
		(width 0.0889)
		(layer "In4.Cu")
		(net "M_D_CPU1_SB_DQ<5>")
	)
	(arc
		(start 82.18805 -278.45893)
		(mid 82.471006 -278.382753)
		(end 82.753962 -278.45893)
		(width 0.0889)
		(layer "In4.Cu")
		(net "M_D_CPU1_SB_DQ<5>")
	)
	(arc
		(start 92.162376 -278.463756)
		(mid 92.315246 -278.508397)
		(end 92.472764 -278.485092)
		(width 0.0889)
		(layer "In4.Cu")
		(net "M_D_CPU1_SB_DQ<5>")
	)
	(segment
		(start 91.397836 -277.060406)
		(end 90.930984 -277.326344)
		(width 0.10668)
		(layer "F.Cu")
		(net "M_D_CPU1_SB_DQ<4>")
	)
	(segment
		(start 60.983368 -286.705548)
		(end 60.983368 -286.258508)
		(width 0.14478)
		(layer "In4.Cu")
		(net "M_D_CPU1_SB_DQ<4>")
	)
	(segment
		(start 67.059048 -280.629868)
		(end 67.225672 -280.463244)
		(width 0.14478)
		(layer "In4.Cu")
		(net "M_D_CPU1_SB_DQ<4>")
	)
	(segment
		(start 55.583582 -288.154364)
		(end 55.87746 -287.860486)
		(width 0.14478)
		(layer "In4.Cu")
		(net "M_D_CPU1_SB_DQ<4>")
	)
	(segment
		(start 59.250072 -287.23082)
		(end 59.411616 -287.392364)
		(width 0.14478)
		(layer "In4.Cu")
		(net "M_D_CPU1_SB_DQ<4>")
	)
	(segment
		(start 48.951388 -288.031682)
		(end 48.951388 -288.095182)
		(width 0.14478)
		(layer "In4.Cu")
		(net "M_D_CPU1_SB_DQ<4>")
	)
	(segment
		(start 45.908214 -287.870138)
		(end 48.789844 -287.870138)
		(width 0.14478)
		(layer "In4.Cu")
		(net "M_D_CPU1_SB_DQ<4>")
	)
	(segment
		(start 61.763656 -285.92526)
		(end 61.763656 -285.47822)
		(width 0.14478)
		(layer "In4.Cu")
		(net "M_D_CPU1_SB_DQ<4>")
	)
	(segment
		(start 77.979524 -277.118826)
		(end 78.560168 -277.69947)
		(width 0.0889)
		(layer "In4.Cu")
		(net "M_D_CPU1_SB_DQ<4>")
	)
	(segment
		(start 70.318122 -276.923754)
		(end 75.957176 -276.923754)
		(width 0.14478)
		(layer "In4.Cu")
		(net "M_D_CPU1_SB_DQ<4>")
	)
	(segment
		(start 65.665096 -281.57678)
		(end 65.83172 -281.410156)
		(width 0.14478)
		(layer "In4.Cu")
		(net "M_D_CPU1_SB_DQ<4>")
	)
	(segment
		(start 68.786248 -278.902668)
		(end 68.786248 -278.455628)
		(width 0.14478)
		(layer "In4.Cu")
		(net "M_D_CPU1_SB_DQ<4>")
	)
	(segment
		(start 62.543944 -284.697932)
		(end 62.710568 -284.531308)
		(width 0.14478)
		(layer "In4.Cu")
		(net "M_D_CPU1_SB_DQ<4>")
	)
	(segment
		(start 57.63641 -287.860486)
		(end 58.104532 -287.392364)
		(width 0.14478)
		(layer "In4.Cu")
		(net "M_D_CPU1_SB_DQ<4>")
	)
	(segment
		(start 63.157608 -284.531308)
		(end 63.324232 -284.364684)
		(width 0.14478)
		(layer "In4.Cu")
		(net "M_D_CPU1_SB_DQ<4>")
	)
	(segment
		(start 68.619624 -279.069292)
		(end 68.786248 -278.902668)
		(width 0.14478)
		(layer "In4.Cu")
		(net "M_D_CPU1_SB_DQ<4>")
	)
	(segment
		(start 65.051432 -282.190444)
		(end 65.498472 -282.190444)
		(width 0.14478)
		(layer "In4.Cu")
		(net "M_D_CPU1_SB_DQ<4>")
	)
	(segment
		(start 65.498472 -282.190444)
		(end 65.665096 -282.02382)
		(width 0.14478)
		(layer "In4.Cu")
		(net "M_D_CPU1_SB_DQ<4>")
	)
	(segment
		(start 56.43372 -288.154364)
		(end 56.696102 -288.154364)
		(width 0.14478)
		(layer "In4.Cu")
		(net "M_D_CPU1_SB_DQ<4>")
	)
	(segment
		(start 63.937896 -283.75102)
		(end 64.10452 -283.584396)
		(width 0.14478)
		(layer "In4.Cu")
		(net "M_D_CPU1_SB_DQ<4>")
	)
	(segment
		(start 63.324232 -283.917644)
		(end 63.490856 -283.75102)
		(width 0.14478)
		(layer "In4.Cu")
		(net "M_D_CPU1_SB_DQ<4>")
	)
	(segment
		(start 50.958496 -287.02)
		(end 52.678076 -287.02)
		(width 0.14478)
		(layer "In4.Cu")
		(net "M_D_CPU1_SB_DQ<4>")
	)
	(segment
		(start 63.324232 -284.364684)
		(end 63.324232 -283.917644)
		(width 0.14478)
		(layer "In4.Cu")
		(net "M_D_CPU1_SB_DQ<4>")
	)
	(segment
		(start 66.445384 -281.243532)
		(end 66.445384 -280.796492)
		(width 0.14478)
		(layer "In4.Cu")
		(net "M_D_CPU1_SB_DQ<4>")
	)
	(segment
		(start 53.914802 -287.860486)
		(end 54.20868 -288.154364)
		(width 0.14478)
		(layer "In4.Cu")
		(net "M_D_CPU1_SB_DQ<4>")
	)
	(segment
		(start 68.00596 -279.682956)
		(end 68.00596 -279.235916)
		(width 0.14478)
		(layer "In4.Cu")
		(net "M_D_CPU1_SB_DQ<4>")
	)
	(segment
		(start 88.289638 -277.65375)
		(end 88.29802 -277.648924)
		(width 0.0889)
		(layer "In4.Cu")
		(net "M_D_CPU1_SB_DQ<4>")
	)
	(segment
		(start 59.411616 -287.392364)
		(end 59.849512 -287.392364)
		(width 0.14478)
		(layer "In4.Cu")
		(net "M_D_CPU1_SB_DQ<4>")
	)
	(segment
		(start 68.786248 -278.455628)
		(end 68.952872 -278.289004)
		(width 0.14478)
		(layer "In4.Cu")
		(net "M_D_CPU1_SB_DQ<4>")
	)
	(segment
		(start 64.10452 -283.137356)
		(end 64.271144 -282.970732)
		(width 0.14478)
		(layer "In4.Cu")
		(net "M_D_CPU1_SB_DQ<4>")
	)
	(segment
		(start 86.044024 -277.648924)
		(end 86.052406 -277.65375)
		(width 0.0889)
		(layer "In4.Cu")
		(net "M_D_CPU1_SB_DQ<4>")
	)
	(segment
		(start 91.085162 -277.591774)
		(end 90.930984 -277.326344)
		(width 0.0889)
		(layer "In4.Cu")
		(net "M_D_CPU1_SB_DQ<4>")
	)
	(segment
		(start 67.392296 -279.84958)
		(end 67.839336 -279.84958)
		(width 0.14478)
		(layer "In4.Cu")
		(net "M_D_CPU1_SB_DQ<4>")
	)
	(segment
		(start 54.76494 -287.860486)
		(end 55.027322 -287.860486)
		(width 0.14478)
		(layer "In4.Cu")
		(net "M_D_CPU1_SB_DQ<4>")
	)
	(segment
		(start 58.860182 -286.707326)
		(end 59.088528 -286.707326)
		(width 0.14478)
		(layer "In4.Cu")
		(net "M_D_CPU1_SB_DQ<4>")
	)
	(segment
		(start 81.344008 -277.648924)
		(end 81.35239 -277.65375)
		(width 0.0889)
		(layer "In4.Cu")
		(net "M_D_CPU1_SB_DQ<4>")
	)
	(segment
		(start 50.108358 -287.870138)
		(end 50.958496 -287.02)
		(width 0.14478)
		(layer "In4.Cu")
		(net "M_D_CPU1_SB_DQ<4>")
	)
	(segment
		(start 62.543944 -285.144972)
		(end 62.543944 -284.697932)
		(width 0.14478)
		(layer "In4.Cu")
		(net "M_D_CPU1_SB_DQ<4>")
	)
	(segment
		(start 48.951388 -288.095182)
		(end 49.112932 -288.256726)
		(width 0.14478)
		(layer "In4.Cu")
		(net "M_D_CPU1_SB_DQ<4>")
	)
	(segment
		(start 66.612008 -280.629868)
		(end 67.059048 -280.629868)
		(width 0.14478)
		(layer "In4.Cu")
		(net "M_D_CPU1_SB_DQ<4>")
	)
	(segment
		(start 49.502822 -288.095182)
		(end 49.502822 -288.031682)
		(width 0.14478)
		(layer "In4.Cu")
		(net "M_D_CPU1_SB_DQ<4>")
	)
	(segment
		(start 76.374498 -276.923754)
		(end 76.56957 -277.118826)
		(width 0.0889)
		(layer "In4.Cu")
		(net "M_D_CPU1_SB_DQ<4>")
	)
	(segment
		(start 64.884808 -282.804108)
		(end 64.884808 -282.357068)
		(width 0.14478)
		(layer "In4.Cu")
		(net "M_D_CPU1_SB_DQ<4>")
	)
	(segment
		(start 65.665096 -282.02382)
		(end 65.665096 -281.57678)
		(width 0.14478)
		(layer "In4.Cu")
		(net "M_D_CPU1_SB_DQ<4>")
	)
	(segment
		(start 61.597032 -286.091884)
		(end 61.763656 -285.92526)
		(width 0.14478)
		(layer "In4.Cu")
		(net "M_D_CPU1_SB_DQ<4>")
	)
	(segment
		(start 67.225672 -280.463244)
		(end 67.225672 -280.016204)
		(width 0.14478)
		(layer "In4.Cu")
		(net "M_D_CPU1_SB_DQ<4>")
	)
	(segment
		(start 56.696102 -288.154364)
		(end 56.98998 -287.860486)
		(width 0.14478)
		(layer "In4.Cu")
		(net "M_D_CPU1_SB_DQ<4>")
	)
	(segment
		(start 89.229692 -277.65375)
		(end 89.238074 -277.648924)
		(width 0.0889)
		(layer "In4.Cu")
		(net "M_D_CPU1_SB_DQ<4>")
	)
	(segment
		(start 62.37732 -285.311596)
		(end 62.543944 -285.144972)
		(width 0.14478)
		(layer "In4.Cu")
		(net "M_D_CPU1_SB_DQ<4>")
	)
	(segment
		(start 37.230812 -287.870138)
		(end 42.386758 -287.870138)
		(width 0.14478)
		(layer "In4.Cu")
		(net "M_D_CPU1_SB_DQ<4>")
	)
	(segment
		(start 56.98998 -287.860486)
		(end 57.63641 -287.860486)
		(width 0.14478)
		(layer "In4.Cu")
		(net "M_D_CPU1_SB_DQ<4>")
	)
	(segment
		(start 45.058076 -287.02)
		(end 45.908214 -287.870138)
		(width 0.14478)
		(layer "In4.Cu")
		(net "M_D_CPU1_SB_DQ<4>")
	)
	(segment
		(start 53.518562 -287.860486)
		(end 53.914802 -287.860486)
		(width 0.14478)
		(layer "In4.Cu")
		(net "M_D_CPU1_SB_DQ<4>")
	)
	(segment
		(start 60.983368 -286.258508)
		(end 61.149992 -286.091884)
		(width 0.14478)
		(layer "In4.Cu")
		(net "M_D_CPU1_SB_DQ<4>")
	)
	(segment
		(start 63.490856 -283.75102)
		(end 63.937896 -283.75102)
		(width 0.14478)
		(layer "In4.Cu")
		(net "M_D_CPU1_SB_DQ<4>")
	)
	(segment
		(start 60.816744 -286.872172)
		(end 60.983368 -286.705548)
		(width 0.14478)
		(layer "In4.Cu")
		(net "M_D_CPU1_SB_DQ<4>")
	)
	(segment
		(start 42.386758 -287.870138)
		(end 43.236896 -287.02)
		(width 0.14478)
		(layer "In4.Cu")
		(net "M_D_CPU1_SB_DQ<4>")
	)
	(segment
		(start 62.710568 -284.531308)
		(end 63.157608 -284.531308)
		(width 0.14478)
		(layer "In4.Cu")
		(net "M_D_CPU1_SB_DQ<4>")
	)
	(segment
		(start 83.589622 -277.65375)
		(end 83.598004 -277.648924)
		(width 0.0889)
		(layer "In4.Cu")
		(net "M_D_CPU1_SB_DQ<4>")
	)
	(segment
		(start 49.341278 -288.256726)
		(end 49.502822 -288.095182)
		(width 0.14478)
		(layer "In4.Cu")
		(net "M_D_CPU1_SB_DQ<4>")
	)
	(segment
		(start 55.87746 -287.860486)
		(end 56.139842 -287.860486)
		(width 0.14478)
		(layer "In4.Cu")
		(net "M_D_CPU1_SB_DQ<4>")
	)
	(segment
		(start 55.3212 -288.154364)
		(end 55.583582 -288.154364)
		(width 0.14478)
		(layer "In4.Cu")
		(net "M_D_CPU1_SB_DQ<4>")
	)
	(segment
		(start 36.795964 -287.43529)
		(end 37.230812 -287.870138)
		(width 0.14478)
		(layer "In4.Cu")
		(net "M_D_CPU1_SB_DQ<4>")
	)
	(segment
		(start 64.884808 -282.357068)
		(end 65.051432 -282.190444)
		(width 0.14478)
		(layer "In4.Cu")
		(net "M_D_CPU1_SB_DQ<4>")
	)
	(segment
		(start 69.399912 -278.289004)
		(end 69.566536 -278.12238)
		(width 0.14478)
		(layer "In4.Cu")
		(net "M_D_CPU1_SB_DQ<4>")
	)
	(segment
		(start 54.20868 -288.154364)
		(end 54.471062 -288.154364)
		(width 0.14478)
		(layer "In4.Cu")
		(net "M_D_CPU1_SB_DQ<4>")
	)
	(segment
		(start 80.769714 -277.65375)
		(end 80.778096 -277.648924)
		(width 0.0889)
		(layer "In4.Cu")
		(net "M_D_CPU1_SB_DQ<4>")
	)
	(segment
		(start 78.560168 -277.69947)
		(end 78.71079 -277.69947)
		(width 0.0889)
		(layer "In4.Cu")
		(net "M_D_CPU1_SB_DQ<4>")
	)
	(segment
		(start 75.957176 -276.923754)
		(end 76.374498 -276.923754)
		(width 0.0889)
		(layer "In4.Cu")
		(net "M_D_CPU1_SB_DQ<4>")
	)
	(segment
		(start 66.445384 -280.796492)
		(end 66.612008 -280.629868)
		(width 0.14478)
		(layer "In4.Cu")
		(net "M_D_CPU1_SB_DQ<4>")
	)
	(segment
		(start 59.849512 -287.392364)
		(end 60.369704 -286.872172)
		(width 0.14478)
		(layer "In4.Cu")
		(net "M_D_CPU1_SB_DQ<4>")
	)
	(segment
		(start 64.10452 -283.584396)
		(end 64.10452 -283.137356)
		(width 0.14478)
		(layer "In4.Cu")
		(net "M_D_CPU1_SB_DQ<4>")
	)
	(segment
		(start 58.537094 -287.392364)
		(end 58.698638 -287.23082)
		(width 0.14478)
		(layer "In4.Cu")
		(net "M_D_CPU1_SB_DQ<4>")
	)
	(segment
		(start 65.83172 -281.410156)
		(end 66.27876 -281.410156)
		(width 0.14478)
		(layer "In4.Cu")
		(net "M_D_CPU1_SB_DQ<4>")
	)
	(segment
		(start 85.10397 -277.648924)
		(end 85.112352 -277.65375)
		(width 0.0889)
		(layer "In4.Cu")
		(net "M_D_CPU1_SB_DQ<4>")
	)
	(segment
		(start 59.250072 -286.86887)
		(end 59.250072 -287.23082)
		(width 0.14478)
		(layer "In4.Cu")
		(net "M_D_CPU1_SB_DQ<4>")
	)
	(segment
		(start 43.236896 -287.02)
		(end 45.058076 -287.02)
		(width 0.14478)
		(layer "In4.Cu")
		(net "M_D_CPU1_SB_DQ<4>")
	)
	(segment
		(start 49.112932 -288.256726)
		(end 49.341278 -288.256726)
		(width 0.14478)
		(layer "In4.Cu")
		(net "M_D_CPU1_SB_DQ<4>")
	)
	(segment
		(start 69.566536 -278.12238)
		(end 69.566536 -277.67534)
		(width 0.14478)
		(layer "In4.Cu")
		(net "M_D_CPU1_SB_DQ<4>")
	)
	(segment
		(start 68.00596 -279.235916)
		(end 68.172584 -279.069292)
		(width 0.14478)
		(layer "In4.Cu")
		(net "M_D_CPU1_SB_DQ<4>")
	)
	(segment
		(start 52.678076 -287.02)
		(end 53.518562 -287.860486)
		(width 0.14478)
		(layer "In4.Cu")
		(net "M_D_CPU1_SB_DQ<4>")
	)
	(segment
		(start 80.39354 -277.642828)
		(end 80.403954 -277.648924)
		(width 0.0889)
		(layer "In4.Cu")
		(net "M_D_CPU1_SB_DQ<4>")
	)
	(segment
		(start 78.897734 -277.64867)
		(end 78.903322 -277.645368)
		(width 0.0889)
		(layer "In4.Cu")
		(net "M_D_CPU1_SB_DQ<4>")
	)
	(segment
		(start 59.088528 -286.707326)
		(end 59.250072 -286.86887)
		(width 0.14478)
		(layer "In4.Cu")
		(net "M_D_CPU1_SB_DQ<4>")
	)
	(segment
		(start 64.718184 -282.970732)
		(end 64.884808 -282.804108)
		(width 0.14478)
		(layer "In4.Cu")
		(net "M_D_CPU1_SB_DQ<4>")
	)
	(segment
		(start 61.149992 -286.091884)
		(end 61.597032 -286.091884)
		(width 0.14478)
		(layer "In4.Cu")
		(net "M_D_CPU1_SB_DQ<4>")
	)
	(segment
		(start 48.789844 -287.870138)
		(end 48.951388 -288.031682)
		(width 0.14478)
		(layer "In4.Cu")
		(net "M_D_CPU1_SB_DQ<4>")
	)
	(segment
		(start 69.566536 -277.67534)
		(end 70.318122 -276.923754)
		(width 0.14478)
		(layer "In4.Cu")
		(net "M_D_CPU1_SB_DQ<4>")
	)
	(segment
		(start 49.664366 -287.870138)
		(end 50.108358 -287.870138)
		(width 0.14478)
		(layer "In4.Cu")
		(net "M_D_CPU1_SB_DQ<4>")
	)
	(segment
		(start 68.172584 -279.069292)
		(end 68.619624 -279.069292)
		(width 0.14478)
		(layer "In4.Cu")
		(net "M_D_CPU1_SB_DQ<4>")
	)
	(segment
		(start 60.369704 -286.872172)
		(end 60.816744 -286.872172)
		(width 0.14478)
		(layer "In4.Cu")
		(net "M_D_CPU1_SB_DQ<4>")
	)
	(segment
		(start 61.763656 -285.47822)
		(end 61.93028 -285.311596)
		(width 0.14478)
		(layer "In4.Cu")
		(net "M_D_CPU1_SB_DQ<4>")
	)
	(segment
		(start 56.139842 -287.860486)
		(end 56.43372 -288.154364)
		(width 0.14478)
		(layer "In4.Cu")
		(net "M_D_CPU1_SB_DQ<4>")
	)
	(segment
		(start 55.027322 -287.860486)
		(end 55.3212 -288.154364)
		(width 0.14478)
		(layer "In4.Cu")
		(net "M_D_CPU1_SB_DQ<4>")
	)
	(segment
		(start 58.698638 -286.86887)
		(end 58.860182 -286.707326)
		(width 0.14478)
		(layer "In4.Cu")
		(net "M_D_CPU1_SB_DQ<4>")
	)
	(segment
		(start 58.104532 -287.392364)
		(end 58.537094 -287.392364)
		(width 0.14478)
		(layer "In4.Cu")
		(net "M_D_CPU1_SB_DQ<4>")
	)
	(segment
		(start 58.698638 -287.23082)
		(end 58.698638 -286.86887)
		(width 0.14478)
		(layer "In4.Cu")
		(net "M_D_CPU1_SB_DQ<4>")
	)
	(segment
		(start 90.74404 -277.648924)
		(end 90.752422 -277.65375)
		(width 0.0889)
		(layer "In4.Cu")
		(net "M_D_CPU1_SB_DQ<4>")
	)
	(segment
		(start 49.502822 -288.031682)
		(end 49.664366 -287.870138)
		(width 0.14478)
		(layer "In4.Cu")
		(net "M_D_CPU1_SB_DQ<4>")
	)
	(segment
		(start 67.225672 -280.016204)
		(end 67.392296 -279.84958)
		(width 0.14478)
		(layer "In4.Cu")
		(net "M_D_CPU1_SB_DQ<4>")
	)
	(segment
		(start 76.56957 -277.118826)
		(end 77.979524 -277.118826)
		(width 0.0889)
		(layer "In4.Cu")
		(net "M_D_CPU1_SB_DQ<4>")
	)
	(segment
		(start 91.06281 -277.675086)
		(end 91.085162 -277.591774)
		(width 0.0889)
		(layer "In4.Cu")
		(net "M_D_CPU1_SB_DQ<4>")
	)
	(segment
		(start 64.271144 -282.970732)
		(end 64.718184 -282.970732)
		(width 0.14478)
		(layer "In4.Cu")
		(net "M_D_CPU1_SB_DQ<4>")
	)
	(segment
		(start 54.471062 -288.154364)
		(end 54.76494 -287.860486)
		(width 0.14478)
		(layer "In4.Cu")
		(net "M_D_CPU1_SB_DQ<4>")
	)
	(segment
		(start 66.27876 -281.410156)
		(end 66.445384 -281.243532)
		(width 0.14478)
		(layer "In4.Cu")
		(net "M_D_CPU1_SB_DQ<4>")
	)
	(segment
		(start 68.952872 -278.289004)
		(end 69.399912 -278.289004)
		(width 0.14478)
		(layer "In4.Cu")
		(net "M_D_CPU1_SB_DQ<4>")
	)
	(segment
		(start 79.463138 -277.648924)
		(end 79.47152 -277.65375)
		(width 0.0889)
		(layer "In4.Cu")
		(net "M_D_CPU1_SB_DQ<4>")
	)
	(segment
		(start 61.93028 -285.311596)
		(end 62.37732 -285.311596)
		(width 0.14478)
		(layer "In4.Cu")
		(net "M_D_CPU1_SB_DQ<4>")
	)
	(segment
		(start 84.529676 -277.65375)
		(end 84.538058 -277.648924)
		(width 0.0889)
		(layer "In4.Cu")
		(net "M_D_CPU1_SB_DQ<4>")
	)
	(segment
		(start 67.839336 -279.84958)
		(end 68.00596 -279.682956)
		(width 0.14478)
		(layer "In4.Cu")
		(net "M_D_CPU1_SB_DQ<4>")
	)
	(segment
		(start 89.803986 -277.648924)
		(end 89.812368 -277.65375)
		(width 0.0889)
		(layer "In4.Cu")
		(net "M_D_CPU1_SB_DQ<4>")
	)
	(arc
		(start 90.178128 -277.648924)
		(mid 90.461084 -277.572747)
		(end 90.74404 -277.648924)
		(width 0.0889)
		(layer "In4.Cu")
		(net "M_D_CPU1_SB_DQ<4>")
	)
	(arc
		(start 83.598004 -277.648924)
		(mid 83.88096 -277.572747)
		(end 84.163916 -277.648924)
		(width 0.0889)
		(layer "In4.Cu")
		(net "M_D_CPU1_SB_DQ<4>")
	)
	(arc
		(start 90.752422 -277.65375)
		(mid 90.905292 -277.698391)
		(end 91.06281 -277.675086)
		(width 0.0889)
		(layer "In4.Cu")
		(net "M_D_CPU1_SB_DQ<4>")
	)
	(arc
		(start 81.71815 -277.648924)
		(mid 82.001106 -277.572747)
		(end 82.284062 -277.648924)
		(width 0.0889)
		(layer "In4.Cu")
		(net "M_D_CPU1_SB_DQ<4>")
	)
	(arc
		(start 79.837788 -277.648924)
		(mid 80.114855 -277.572653)
		(end 80.39354 -277.642828)
		(width 0.0889)
		(layer "In4.Cu")
		(net "M_D_CPU1_SB_DQ<4>")
	)
	(arc
		(start 87.357966 -277.648924)
		(mid 87.640922 -277.572747)
		(end 87.923878 -277.648924)
		(width 0.0889)
		(layer "In4.Cu")
		(net "M_D_CPU1_SB_DQ<4>")
	)
	(arc
		(start 86.984078 -277.648924)
		(mid 87.171022 -277.699179)
		(end 87.357966 -277.648924)
		(width 0.0889)
		(layer "In4.Cu")
		(net "M_D_CPU1_SB_DQ<4>")
	)
	(arc
		(start 88.29802 -277.648924)
		(mid 88.580976 -277.572747)
		(end 88.863932 -277.648924)
		(width 0.0889)
		(layer "In4.Cu")
		(net "M_D_CPU1_SB_DQ<4>")
	)
	(arc
		(start 88.863932 -277.648924)
		(mid 89.046183 -277.699274)
		(end 89.229692 -277.65375)
		(width 0.0889)
		(layer "In4.Cu")
		(net "M_D_CPU1_SB_DQ<4>")
	)
	(arc
		(start 81.35239 -277.65375)
		(mid 81.535898 -277.699244)
		(end 81.71815 -277.648924)
		(width 0.0889)
		(layer "In4.Cu")
		(net "M_D_CPU1_SB_DQ<4>")
	)
	(arc
		(start 82.65795 -277.648924)
		(mid 82.940906 -277.572747)
		(end 83.223862 -277.648924)
		(width 0.0889)
		(layer "In4.Cu")
		(net "M_D_CPU1_SB_DQ<4>")
	)
	(arc
		(start 80.778096 -277.648924)
		(mid 81.061052 -277.572747)
		(end 81.344008 -277.648924)
		(width 0.0889)
		(layer "In4.Cu")
		(net "M_D_CPU1_SB_DQ<4>")
	)
	(arc
		(start 86.052406 -277.65375)
		(mid 86.235914 -277.699244)
		(end 86.418166 -277.648924)
		(width 0.0889)
		(layer "In4.Cu")
		(net "M_D_CPU1_SB_DQ<4>")
	)
	(arc
		(start 89.812368 -277.65375)
		(mid 89.995876 -277.699244)
		(end 90.178128 -277.648924)
		(width 0.0889)
		(layer "In4.Cu")
		(net "M_D_CPU1_SB_DQ<4>")
	)
	(arc
		(start 85.112352 -277.65375)
		(mid 85.29586 -277.699244)
		(end 85.478112 -277.648924)
		(width 0.0889)
		(layer "In4.Cu")
		(net "M_D_CPU1_SB_DQ<4>")
	)
	(arc
		(start 87.923878 -277.648924)
		(mid 88.106129 -277.699274)
		(end 88.289638 -277.65375)
		(width 0.0889)
		(layer "In4.Cu")
		(net "M_D_CPU1_SB_DQ<4>")
	)
	(arc
		(start 80.403954 -277.648924)
		(mid 80.586205 -277.699274)
		(end 80.769714 -277.65375)
		(width 0.0889)
		(layer "In4.Cu")
		(net "M_D_CPU1_SB_DQ<4>")
	)
	(arc
		(start 79.47152 -277.65375)
		(mid 79.655282 -277.699366)
		(end 79.837788 -277.648924)
		(width 0.0889)
		(layer "In4.Cu")
		(net "M_D_CPU1_SB_DQ<4>")
	)
	(arc
		(start 85.478112 -277.648924)
		(mid 85.761068 -277.572747)
		(end 86.044024 -277.648924)
		(width 0.0889)
		(layer "In4.Cu")
		(net "M_D_CPU1_SB_DQ<4>")
	)
	(arc
		(start 84.163916 -277.648924)
		(mid 84.346167 -277.699274)
		(end 84.529676 -277.65375)
		(width 0.0889)
		(layer "In4.Cu")
		(net "M_D_CPU1_SB_DQ<4>")
	)
	(arc
		(start 78.903322 -277.645368)
		(mid 79.183711 -277.572699)
		(end 79.463138 -277.648924)
		(width 0.0889)
		(layer "In4.Cu")
		(net "M_D_CPU1_SB_DQ<4>")
	)
	(arc
		(start 83.223862 -277.648924)
		(mid 83.406113 -277.699274)
		(end 83.589622 -277.65375)
		(width 0.0889)
		(layer "In4.Cu")
		(net "M_D_CPU1_SB_DQ<4>")
	)
	(arc
		(start 82.284062 -277.648924)
		(mid 82.471006 -277.699179)
		(end 82.65795 -277.648924)
		(width 0.0889)
		(layer "In4.Cu")
		(net "M_D_CPU1_SB_DQ<4>")
	)
	(arc
		(start 89.238074 -277.648924)
		(mid 89.52103 -277.572747)
		(end 89.803986 -277.648924)
		(width 0.0889)
		(layer "In4.Cu")
		(net "M_D_CPU1_SB_DQ<4>")
	)
	(arc
		(start 86.418166 -277.648924)
		(mid 86.701122 -277.572747)
		(end 86.984078 -277.648924)
		(width 0.0889)
		(layer "In4.Cu")
		(net "M_D_CPU1_SB_DQ<4>")
	)
	(arc
		(start 78.71079 -277.69947)
		(mid 78.807608 -277.686399)
		(end 78.897734 -277.64867)
		(width 0.0889)
		(layer "In4.Cu")
		(net "M_D_CPU1_SB_DQ<4>")
	)
	(arc
		(start 84.538058 -277.648924)
		(mid 84.821014 -277.572747)
		(end 85.10397 -277.648924)
		(width 0.0889)
		(layer "In4.Cu")
		(net "M_D_CPU1_SB_DQ<4>")
	)
	(segment
		(start 93.277944 -275.440394)
		(end 92.811092 -275.706332)
		(width 0.10668)
		(layer "F.Cu")
		(net "M_D_CPU1_SB_DQ<3>")
	)
	(segment
		(start 80.389222 -275.392388)
		(end 80.403954 -275.383752)
		(width 0.0889)
		(layer "In4.Cu")
		(net "M_D_CPU1_SB_DQ<3>")
	)
	(segment
		(start 57.34304 -284.064964)
		(end 57.7977 -283.610304)
		(width 0.14478)
		(layer "In4.Cu")
		(net "M_D_CPU1_SB_DQ<3>")
	)
	(segment
		(start 46.552104 -284.450536)
		(end 49.413668 -284.450536)
		(width 0.14478)
		(layer "In4.Cu")
		(net "M_D_CPU1_SB_DQ<3>")
	)
	(segment
		(start 53.520848 -284.064964)
		(end 57.34304 -284.064964)
		(width 0.14478)
		(layer "In4.Cu")
		(net "M_D_CPU1_SB_DQ<3>")
	)
	(segment
		(start 59.376818 -283.610304)
		(end 68.402708 -274.584414)
		(width 0.14478)
		(layer "In4.Cu")
		(net "M_D_CPU1_SB_DQ<3>")
	)
	(segment
		(start 33.111186 -284.450536)
		(end 41.793668 -284.450536)
		(width 0.14478)
		(layer "In4.Cu")
		(net "M_D_CPU1_SB_DQ<3>")
	)
	(segment
		(start 53.056536 -283.600652)
		(end 53.520848 -284.064964)
		(width 0.14478)
		(layer "In4.Cu")
		(net "M_D_CPU1_SB_DQ<3>")
	)
	(segment
		(start 76.485242 -274.584414)
		(end 76.82865 -274.241006)
		(width 0.0889)
		(layer "In4.Cu")
		(net "M_D_CPU1_SB_DQ<3>")
	)
	(segment
		(start 49.413668 -284.450536)
		(end 50.263552 -283.600652)
		(width 0.14478)
		(layer "In4.Cu")
		(net "M_D_CPU1_SB_DQ<3>")
	)
	(segment
		(start 81.344008 -275.383752)
		(end 81.35239 -275.378926)
		(width 0.0889)
		(layer "In4.Cu")
		(net "M_D_CPU1_SB_DQ<3>")
	)
	(segment
		(start 76.37145 -274.584414)
		(end 76.485242 -274.584414)
		(width 0.0889)
		(layer "In4.Cu")
		(net "M_D_CPU1_SB_DQ<3>")
	)
	(segment
		(start 85.10397 -275.383752)
		(end 85.112352 -275.378926)
		(width 0.0889)
		(layer "In4.Cu")
		(net "M_D_CPU1_SB_DQ<3>")
	)
	(segment
		(start 92.656914 -275.440902)
		(end 92.811092 -275.706332)
		(width 0.0889)
		(layer "In4.Cu")
		(net "M_D_CPU1_SB_DQ<3>")
	)
	(segment
		(start 90.74404 -275.383752)
		(end 90.752422 -275.378926)
		(width 0.0889)
		(layer "In4.Cu")
		(net "M_D_CPU1_SB_DQ<3>")
	)
	(segment
		(start 88.289638 -275.378926)
		(end 88.29802 -275.383752)
		(width 0.0889)
		(layer "In4.Cu")
		(net "M_D_CPU1_SB_DQ<3>")
	)
	(segment
		(start 78.400656 -275.332952)
		(end 79.649828 -275.332952)
		(width 0.0889)
		(layer "In4.Cu")
		(net "M_D_CPU1_SB_DQ<3>")
	)
	(segment
		(start 42.643552 -283.600652)
		(end 45.70222 -283.600652)
		(width 0.14478)
		(layer "In4.Cu")
		(net "M_D_CPU1_SB_DQ<3>")
	)
	(segment
		(start 84.529676 -275.378926)
		(end 84.538058 -275.383752)
		(width 0.0889)
		(layer "In4.Cu")
		(net "M_D_CPU1_SB_DQ<3>")
	)
	(segment
		(start 32.695896 -284.035246)
		(end 33.111186 -284.450536)
		(width 0.14478)
		(layer "In4.Cu")
		(net "M_D_CPU1_SB_DQ<3>")
	)
	(segment
		(start 57.7977 -283.610304)
		(end 59.376818 -283.610304)
		(width 0.14478)
		(layer "In4.Cu")
		(net "M_D_CPU1_SB_DQ<3>")
	)
	(segment
		(start 86.044024 -275.383752)
		(end 86.052406 -275.378926)
		(width 0.0889)
		(layer "In4.Cu")
		(net "M_D_CPU1_SB_DQ<3>")
	)
	(segment
		(start 89.803986 -275.383752)
		(end 89.812368 -275.378926)
		(width 0.0889)
		(layer "In4.Cu")
		(net "M_D_CPU1_SB_DQ<3>")
	)
	(segment
		(start 89.229692 -275.378926)
		(end 89.238074 -275.383752)
		(width 0.0889)
		(layer "In4.Cu")
		(net "M_D_CPU1_SB_DQ<3>")
	)
	(segment
		(start 68.402708 -274.584414)
		(end 76.37145 -274.584414)
		(width 0.14478)
		(layer "In4.Cu")
		(net "M_D_CPU1_SB_DQ<3>")
	)
	(segment
		(start 77.30871 -274.241006)
		(end 78.400656 -275.332952)
		(width 0.0889)
		(layer "In4.Cu")
		(net "M_D_CPU1_SB_DQ<3>")
	)
	(segment
		(start 45.70222 -283.600652)
		(end 46.552104 -284.450536)
		(width 0.14478)
		(layer "In4.Cu")
		(net "M_D_CPU1_SB_DQ<3>")
	)
	(segment
		(start 80.769714 -275.378926)
		(end 80.778096 -275.383752)
		(width 0.0889)
		(layer "In4.Cu")
		(net "M_D_CPU1_SB_DQ<3>")
	)
	(segment
		(start 41.793668 -284.450536)
		(end 42.643552 -283.600652)
		(width 0.14478)
		(layer "In4.Cu")
		(net "M_D_CPU1_SB_DQ<3>")
	)
	(segment
		(start 76.82865 -274.241006)
		(end 77.30871 -274.241006)
		(width 0.0889)
		(layer "In4.Cu")
		(net "M_D_CPU1_SB_DQ<3>")
	)
	(segment
		(start 50.263552 -283.600652)
		(end 53.056536 -283.600652)
		(width 0.14478)
		(layer "In4.Cu")
		(net "M_D_CPU1_SB_DQ<3>")
	)
	(segment
		(start 92.560648 -275.415502)
		(end 92.656914 -275.440902)
		(width 0.0889)
		(layer "In4.Cu")
		(net "M_D_CPU1_SB_DQ<3>")
	)
	(segment
		(start 83.589622 -275.378926)
		(end 83.598004 -275.383752)
		(width 0.0889)
		(layer "In4.Cu")
		(net "M_D_CPU1_SB_DQ<3>")
	)
	(arc
		(start 87.923878 -275.383752)
		(mid 88.106129 -275.333402)
		(end 88.289638 -275.378926)
		(width 0.0889)
		(layer "In4.Cu")
		(net "M_D_CPU1_SB_DQ<3>")
	)
	(arc
		(start 82.65795 -275.383752)
		(mid 82.940906 -275.459929)
		(end 83.223862 -275.383752)
		(width 0.0889)
		(layer "In4.Cu")
		(net "M_D_CPU1_SB_DQ<3>")
	)
	(arc
		(start 91.684094 -275.383752)
		(mid 91.871038 -275.333497)
		(end 92.057982 -275.383752)
		(width 0.0889)
		(layer "In4.Cu")
		(net "M_D_CPU1_SB_DQ<3>")
	)
	(arc
		(start 90.178128 -275.383752)
		(mid 90.461084 -275.459929)
		(end 90.74404 -275.383752)
		(width 0.0889)
		(layer "In4.Cu")
		(net "M_D_CPU1_SB_DQ<3>")
	)
	(arc
		(start 85.478112 -275.383752)
		(mid 85.761068 -275.459929)
		(end 86.044024 -275.383752)
		(width 0.0889)
		(layer "In4.Cu")
		(net "M_D_CPU1_SB_DQ<3>")
	)
	(arc
		(start 84.163916 -275.383752)
		(mid 84.346167 -275.333402)
		(end 84.529676 -275.378926)
		(width 0.0889)
		(layer "In4.Cu")
		(net "M_D_CPU1_SB_DQ<3>")
	)
	(arc
		(start 80.778096 -275.383752)
		(mid 81.061052 -275.459929)
		(end 81.344008 -275.383752)
		(width 0.0889)
		(layer "In4.Cu")
		(net "M_D_CPU1_SB_DQ<3>")
	)
	(arc
		(start 91.118182 -275.383752)
		(mid 91.401138 -275.459929)
		(end 91.684094 -275.383752)
		(width 0.0889)
		(layer "In4.Cu")
		(net "M_D_CPU1_SB_DQ<3>")
	)
	(arc
		(start 90.752422 -275.378926)
		(mid 90.93593 -275.333432)
		(end 91.118182 -275.383752)
		(width 0.0889)
		(layer "In4.Cu")
		(net "M_D_CPU1_SB_DQ<3>")
	)
	(arc
		(start 86.418166 -275.383752)
		(mid 86.701122 -275.459929)
		(end 86.984078 -275.383752)
		(width 0.0889)
		(layer "In4.Cu")
		(net "M_D_CPU1_SB_DQ<3>")
	)
	(arc
		(start 79.649828 -275.332952)
		(mid 79.747053 -275.345901)
		(end 79.837534 -275.383752)
		(width 0.0889)
		(layer "In4.Cu")
		(net "M_D_CPU1_SB_DQ<3>")
	)
	(arc
		(start 81.35239 -275.378926)
		(mid 81.535898 -275.333432)
		(end 81.71815 -275.383752)
		(width 0.0889)
		(layer "In4.Cu")
		(net "M_D_CPU1_SB_DQ<3>")
	)
	(arc
		(start 89.238074 -275.383752)
		(mid 89.52103 -275.459929)
		(end 89.803986 -275.383752)
		(width 0.0889)
		(layer "In4.Cu")
		(net "M_D_CPU1_SB_DQ<3>")
	)
	(arc
		(start 86.984078 -275.383752)
		(mid 87.171022 -275.333497)
		(end 87.357966 -275.383752)
		(width 0.0889)
		(layer "In4.Cu")
		(net "M_D_CPU1_SB_DQ<3>")
	)
	(arc
		(start 88.29802 -275.383752)
		(mid 88.580976 -275.459929)
		(end 88.863932 -275.383752)
		(width 0.0889)
		(layer "In4.Cu")
		(net "M_D_CPU1_SB_DQ<3>")
	)
	(arc
		(start 79.837534 -275.383752)
		(mid 80.11224 -275.460116)
		(end 80.389222 -275.392388)
		(width 0.0889)
		(layer "In4.Cu")
		(net "M_D_CPU1_SB_DQ<3>")
	)
	(arc
		(start 80.403954 -275.383752)
		(mid 80.586205 -275.333402)
		(end 80.769714 -275.378926)
		(width 0.0889)
		(layer "In4.Cu")
		(net "M_D_CPU1_SB_DQ<3>")
	)
	(arc
		(start 87.357966 -275.383752)
		(mid 87.640922 -275.459929)
		(end 87.923878 -275.383752)
		(width 0.0889)
		(layer "In4.Cu")
		(net "M_D_CPU1_SB_DQ<3>")
	)
	(arc
		(start 85.112352 -275.378926)
		(mid 85.29586 -275.333432)
		(end 85.478112 -275.383752)
		(width 0.0889)
		(layer "In4.Cu")
		(net "M_D_CPU1_SB_DQ<3>")
	)
	(arc
		(start 92.057982 -275.383752)
		(mid 92.305578 -275.45893)
		(end 92.560648 -275.415502)
		(width 0.0889)
		(layer "In4.Cu")
		(net "M_D_CPU1_SB_DQ<3>")
	)
	(arc
		(start 84.538058 -275.383752)
		(mid 84.821014 -275.459929)
		(end 85.10397 -275.383752)
		(width 0.0889)
		(layer "In4.Cu")
		(net "M_D_CPU1_SB_DQ<3>")
	)
	(arc
		(start 81.71815 -275.383752)
		(mid 82.001106 -275.459929)
		(end 82.284062 -275.383752)
		(width 0.0889)
		(layer "In4.Cu")
		(net "M_D_CPU1_SB_DQ<3>")
	)
	(arc
		(start 89.812368 -275.378926)
		(mid 89.995876 -275.333432)
		(end 90.178128 -275.383752)
		(width 0.0889)
		(layer "In4.Cu")
		(net "M_D_CPU1_SB_DQ<3>")
	)
	(arc
		(start 83.598004 -275.383752)
		(mid 83.88096 -275.459929)
		(end 84.163916 -275.383752)
		(width 0.0889)
		(layer "In4.Cu")
		(net "M_D_CPU1_SB_DQ<3>")
	)
	(arc
		(start 82.284062 -275.383752)
		(mid 82.471006 -275.333497)
		(end 82.65795 -275.383752)
		(width 0.0889)
		(layer "In4.Cu")
		(net "M_D_CPU1_SB_DQ<3>")
	)
	(arc
		(start 83.223862 -275.383752)
		(mid 83.406113 -275.333402)
		(end 83.589622 -275.378926)
		(width 0.0889)
		(layer "In4.Cu")
		(net "M_D_CPU1_SB_DQ<3>")
	)
	(arc
		(start 88.863932 -275.383752)
		(mid 89.046183 -275.333402)
		(end 89.229692 -275.378926)
		(width 0.0889)
		(layer "In4.Cu")
		(net "M_D_CPU1_SB_DQ<3>")
	)
	(arc
		(start 86.052406 -275.378926)
		(mid 86.235914 -275.333432)
		(end 86.418166 -275.383752)
		(width 0.0889)
		(layer "In4.Cu")
		(net "M_D_CPU1_SB_DQ<3>")
	)
	(segment
		(start 91.397836 -293.260272)
		(end 90.930984 -293.52621)
		(width 0.10668)
		(layer "F.Cu")
		(net "M_D_CPU1_SB_DQ<31>")
	)
	(segment
		(start 33.742884 -317.567564)
		(end 33.973516 -317.567564)
		(width 0.14478)
		(layer "In4.Cu")
		(net "M_D_CPU1_SB_DQ<31>")
	)
	(segment
		(start 79.912464 -296.458386)
		(end 80.349344 -296.458386)
		(width 0.0889)
		(layer "In4.Cu")
		(net "M_D_CPU1_SB_DQ<31>")
	)
	(segment
		(start 34.13633 -318.29756)
		(end 34.299144 -318.460374)
		(width 0.14478)
		(layer "In4.Cu")
		(net "M_D_CPU1_SB_DQ<31>")
	)
	(segment
		(start 81.344008 -294.823642)
		(end 81.383124 -294.800782)
		(width 0.0889)
		(layer "In4.Cu")
		(net "M_D_CPU1_SB_DQ<31>")
	)
	(segment
		(start 60.210446 -318.460374)
		(end 77.12202 -301.5488)
		(width 0.14478)
		(layer "In4.Cu")
		(net "M_D_CPU1_SB_DQ<31>")
	)
	(segment
		(start 34.529776 -318.460374)
		(end 34.69259 -318.29756)
		(width 0.14478)
		(layer "In4.Cu")
		(net "M_D_CPU1_SB_DQ<31>")
	)
	(segment
		(start 35.24885 -317.730378)
		(end 35.24885 -318.29756)
		(width 0.14478)
		(layer "In4.Cu")
		(net "M_D_CPU1_SB_DQ<31>")
	)
	(segment
		(start 34.299144 -318.460374)
		(end 34.529776 -318.460374)
		(width 0.14478)
		(layer "In4.Cu")
		(net "M_D_CPU1_SB_DQ<31>")
	)
	(segment
		(start 33.120838 -318.460374)
		(end 33.417256 -318.460374)
		(width 0.14478)
		(layer "In4.Cu")
		(net "M_D_CPU1_SB_DQ<31>")
	)
	(segment
		(start 34.69259 -318.29756)
		(end 34.69259 -317.730378)
		(width 0.14478)
		(layer "In4.Cu")
		(net "M_D_CPU1_SB_DQ<31>")
	)
	(segment
		(start 88.289638 -293.198804)
		(end 88.29802 -293.20363)
		(width 0.0889)
		(layer "In4.Cu")
		(net "M_D_CPU1_SB_DQ<31>")
	)
	(segment
		(start 81.783428 -294.031416)
		(end 81.813908 -294.013636)
		(width 0.0889)
		(layer "In4.Cu")
		(net "M_D_CPU1_SB_DQ<31>")
	)
	(segment
		(start 34.855404 -317.567564)
		(end 35.086036 -317.567564)
		(width 0.14478)
		(layer "In4.Cu")
		(net "M_D_CPU1_SB_DQ<31>")
	)
	(segment
		(start 35.086036 -317.567564)
		(end 35.24885 -317.730378)
		(width 0.14478)
		(layer "In4.Cu")
		(net "M_D_CPU1_SB_DQ<31>")
	)
	(segment
		(start 33.58007 -317.730378)
		(end 33.742884 -317.567564)
		(width 0.14478)
		(layer "In4.Cu")
		(net "M_D_CPU1_SB_DQ<31>")
	)
	(segment
		(start 34.69259 -317.730378)
		(end 34.855404 -317.567564)
		(width 0.14478)
		(layer "In4.Cu")
		(net "M_D_CPU1_SB_DQ<31>")
	)
	(segment
		(start 81.813908 -294.013636)
		(end 81.816448 -294.011858)
		(width 0.0889)
		(layer "In4.Cu")
		(net "M_D_CPU1_SB_DQ<31>")
	)
	(segment
		(start 33.58007 -318.29756)
		(end 33.58007 -317.730378)
		(width 0.14478)
		(layer "In4.Cu")
		(net "M_D_CPU1_SB_DQ<31>")
	)
	(segment
		(start 86.044024 -293.20363)
		(end 86.052406 -293.198804)
		(width 0.0889)
		(layer "In4.Cu")
		(net "M_D_CPU1_SB_DQ<31>")
	)
	(segment
		(start 83.589622 -293.198804)
		(end 83.598004 -293.20363)
		(width 0.0889)
		(layer "In4.Cu")
		(net "M_D_CPU1_SB_DQ<31>")
	)
	(segment
		(start 77.12202 -299.233082)
		(end 79.79918 -296.555922)
		(width 0.14478)
		(layer "In4.Cu")
		(net "M_D_CPU1_SB_DQ<31>")
	)
	(segment
		(start 90.77706 -293.26078)
		(end 90.930984 -293.52621)
		(width 0.0889)
		(layer "In4.Cu")
		(net "M_D_CPU1_SB_DQ<31>")
	)
	(segment
		(start 89.229692 -293.198804)
		(end 89.238074 -293.20363)
		(width 0.0889)
		(layer "In4.Cu")
		(net "M_D_CPU1_SB_DQ<31>")
	)
	(segment
		(start 79.79918 -296.555922)
		(end 79.88554 -296.469562)
		(width 0.0889)
		(layer "In4.Cu")
		(net "M_D_CPU1_SB_DQ<31>")
	)
	(segment
		(start 32.695896 -318.035432)
		(end 33.120838 -318.460374)
		(width 0.14478)
		(layer "In4.Cu")
		(net "M_D_CPU1_SB_DQ<31>")
	)
	(segment
		(start 80.843374 -295.651428)
		(end 80.873854 -295.633648)
		(width 0.0889)
		(layer "In4.Cu")
		(net "M_D_CPU1_SB_DQ<31>")
	)
	(segment
		(start 34.13633 -317.730378)
		(end 34.13633 -318.29756)
		(width 0.14478)
		(layer "In4.Cu")
		(net "M_D_CPU1_SB_DQ<31>")
	)
	(segment
		(start 89.803986 -293.20363)
		(end 89.812368 -293.198804)
		(width 0.0889)
		(layer "In4.Cu")
		(net "M_D_CPU1_SB_DQ<31>")
	)
	(segment
		(start 81.312258 -294.84193)
		(end 81.344008 -294.823642)
		(width 0.0889)
		(layer "In4.Cu")
		(net "M_D_CPU1_SB_DQ<31>")
	)
	(segment
		(start 84.529676 -293.198804)
		(end 84.538058 -293.20363)
		(width 0.0889)
		(layer "In4.Cu")
		(net "M_D_CPU1_SB_DQ<31>")
	)
	(segment
		(start 33.417256 -318.460374)
		(end 33.58007 -318.29756)
		(width 0.14478)
		(layer "In4.Cu")
		(net "M_D_CPU1_SB_DQ<31>")
	)
	(segment
		(start 90.681048 -293.23538)
		(end 90.77706 -293.26078)
		(width 0.0889)
		(layer "In4.Cu")
		(net "M_D_CPU1_SB_DQ<31>")
	)
	(segment
		(start 80.4037 -296.443654)
		(end 80.444086 -296.420032)
		(width 0.0889)
		(layer "In4.Cu")
		(net "M_D_CPU1_SB_DQ<31>")
	)
	(segment
		(start 35.411664 -318.460374)
		(end 60.210446 -318.460374)
		(width 0.14478)
		(layer "In4.Cu")
		(net "M_D_CPU1_SB_DQ<31>")
	)
	(segment
		(start 33.973516 -317.567564)
		(end 34.13633 -317.730378)
		(width 0.14478)
		(layer "In4.Cu")
		(net "M_D_CPU1_SB_DQ<31>")
	)
	(segment
		(start 85.10397 -293.20363)
		(end 85.112352 -293.198804)
		(width 0.0889)
		(layer "In4.Cu")
		(net "M_D_CPU1_SB_DQ<31>")
	)
	(segment
		(start 35.24885 -318.29756)
		(end 35.411664 -318.460374)
		(width 0.14478)
		(layer "In4.Cu")
		(net "M_D_CPU1_SB_DQ<31>")
	)
	(segment
		(start 82.281268 -293.205408)
		(end 82.284062 -293.20363)
		(width 0.0889)
		(layer "In4.Cu")
		(net "M_D_CPU1_SB_DQ<31>")
	)
	(segment
		(start 77.12202 -301.5488)
		(end 77.12202 -299.233082)
		(width 0.14478)
		(layer "In4.Cu")
		(net "M_D_CPU1_SB_DQ<31>")
	)
	(segment
		(start 80.873854 -295.633648)
		(end 80.91297 -295.610788)
		(width 0.0889)
		(layer "In4.Cu")
		(net "M_D_CPU1_SB_DQ<31>")
	)
	(arc
		(start 84.163916 -293.20363)
		(mid 84.346167 -293.15328)
		(end 84.529676 -293.198804)
		(width 0.0889)
		(layer "In4.Cu")
		(net "M_D_CPU1_SB_DQ<31>")
	)
	(arc
		(start 79.88554 -296.469562)
		(mid 79.897893 -296.461308)
		(end 79.912464 -296.458386)
		(width 0.0889)
		(layer "In4.Cu")
		(net "M_D_CPU1_SB_DQ<31>")
	)
	(arc
		(start 89.238074 -293.20363)
		(mid 89.52103 -293.279807)
		(end 89.803986 -293.20363)
		(width 0.0889)
		(layer "In4.Cu")
		(net "M_D_CPU1_SB_DQ<31>")
	)
	(arc
		(start 90.178128 -293.20363)
		(mid 90.425841 -293.27885)
		(end 90.681048 -293.23538)
		(width 0.0889)
		(layer "In4.Cu")
		(net "M_D_CPU1_SB_DQ<31>")
	)
	(arc
		(start 86.984078 -293.20363)
		(mid 87.171022 -293.153375)
		(end 87.357966 -293.20363)
		(width 0.0889)
		(layer "In4.Cu")
		(net "M_D_CPU1_SB_DQ<31>")
	)
	(arc
		(start 85.478112 -293.20363)
		(mid 85.761068 -293.279807)
		(end 86.044024 -293.20363)
		(width 0.0889)
		(layer "In4.Cu")
		(net "M_D_CPU1_SB_DQ<31>")
	)
	(arc
		(start 81.156302 -295.146222)
		(mid 81.197557 -294.975251)
		(end 81.312258 -294.84193)
		(width 0.0889)
		(layer "In4.Cu")
		(net "M_D_CPU1_SB_DQ<31>")
	)
	(arc
		(start 88.29802 -293.20363)
		(mid 88.580976 -293.279807)
		(end 88.863932 -293.20363)
		(width 0.0889)
		(layer "In4.Cu")
		(net "M_D_CPU1_SB_DQ<31>")
	)
	(arc
		(start 81.626456 -294.336216)
		(mid 81.668005 -294.164794)
		(end 81.783428 -294.031416)
		(width 0.0889)
		(layer "In4.Cu")
		(net "M_D_CPU1_SB_DQ<31>")
	)
	(arc
		(start 80.444086 -296.420032)
		(mid 80.622151 -296.217855)
		(end 80.686402 -295.956228)
		(width 0.0889)
		(layer "In4.Cu")
		(net "M_D_CPU1_SB_DQ<31>")
	)
	(arc
		(start 82.284062 -293.20363)
		(mid 82.471006 -293.153375)
		(end 82.65795 -293.20363)
		(width 0.0889)
		(layer "In4.Cu")
		(net "M_D_CPU1_SB_DQ<31>")
	)
	(arc
		(start 84.538058 -293.20363)
		(mid 84.821014 -293.279807)
		(end 85.10397 -293.20363)
		(width 0.0889)
		(layer "In4.Cu")
		(net "M_D_CPU1_SB_DQ<31>")
	)
	(arc
		(start 86.418166 -293.20363)
		(mid 86.701122 -293.279807)
		(end 86.984078 -293.20363)
		(width 0.0889)
		(layer "In4.Cu")
		(net "M_D_CPU1_SB_DQ<31>")
	)
	(arc
		(start 86.052406 -293.198804)
		(mid 86.235914 -293.15331)
		(end 86.418166 -293.20363)
		(width 0.0889)
		(layer "In4.Cu")
		(net "M_D_CPU1_SB_DQ<31>")
	)
	(arc
		(start 82.65795 -293.20363)
		(mid 82.940906 -293.279807)
		(end 83.223862 -293.20363)
		(width 0.0889)
		(layer "In4.Cu")
		(net "M_D_CPU1_SB_DQ<31>")
	)
	(arc
		(start 81.816448 -294.011858)
		(mid 82.021348 -293.806458)
		(end 82.096356 -293.52621)
		(width 0.0889)
		(layer "In4.Cu")
		(net "M_D_CPU1_SB_DQ<31>")
	)
	(arc
		(start 87.923878 -293.20363)
		(mid 88.106129 -293.15328)
		(end 88.289638 -293.198804)
		(width 0.0889)
		(layer "In4.Cu")
		(net "M_D_CPU1_SB_DQ<31>")
	)
	(arc
		(start 83.223862 -293.20363)
		(mid 83.406113 -293.15328)
		(end 83.589622 -293.198804)
		(width 0.0889)
		(layer "In4.Cu")
		(net "M_D_CPU1_SB_DQ<31>")
	)
	(arc
		(start 89.812368 -293.198804)
		(mid 89.995876 -293.15331)
		(end 90.178128 -293.20363)
		(width 0.0889)
		(layer "In4.Cu")
		(net "M_D_CPU1_SB_DQ<31>")
	)
	(arc
		(start 80.91297 -295.610788)
		(mid 81.091783 -295.408438)
		(end 81.156302 -295.146222)
		(width 0.0889)
		(layer "In4.Cu")
		(net "M_D_CPU1_SB_DQ<31>")
	)
	(arc
		(start 80.349344 -296.458386)
		(mid 80.377503 -296.454639)
		(end 80.4037 -296.443654)
		(width 0.0889)
		(layer "In4.Cu")
		(net "M_D_CPU1_SB_DQ<31>")
	)
	(arc
		(start 88.863932 -293.20363)
		(mid 89.046183 -293.15328)
		(end 89.229692 -293.198804)
		(width 0.0889)
		(layer "In4.Cu")
		(net "M_D_CPU1_SB_DQ<31>")
	)
	(arc
		(start 82.096356 -293.52621)
		(mid 82.145885 -293.341057)
		(end 82.281268 -293.205408)
		(width 0.0889)
		(layer "In4.Cu")
		(net "M_D_CPU1_SB_DQ<31>")
	)
	(arc
		(start 87.357966 -293.20363)
		(mid 87.640922 -293.279807)
		(end 87.923878 -293.20363)
		(width 0.0889)
		(layer "In4.Cu")
		(net "M_D_CPU1_SB_DQ<31>")
	)
	(arc
		(start 81.383124 -294.800782)
		(mid 81.561937 -294.598432)
		(end 81.626456 -294.336216)
		(width 0.0889)
		(layer "In4.Cu")
		(net "M_D_CPU1_SB_DQ<31>")
	)
	(arc
		(start 80.686402 -295.956228)
		(mid 80.727951 -295.784806)
		(end 80.843374 -295.651428)
		(width 0.0889)
		(layer "In4.Cu")
		(net "M_D_CPU1_SB_DQ<31>")
	)
	(arc
		(start 85.112352 -293.198804)
		(mid 85.29586 -293.15331)
		(end 85.478112 -293.20363)
		(width 0.0889)
		(layer "In4.Cu")
		(net "M_D_CPU1_SB_DQ<31>")
	)
	(arc
		(start 83.598004 -293.20363)
		(mid 83.88096 -293.279807)
		(end 84.163916 -293.20363)
		(width 0.0889)
		(layer "In4.Cu")
		(net "M_D_CPU1_SB_DQ<31>")
	)
	(segment
		(start 91.86799 -292.450266)
		(end 91.401138 -292.716204)
		(width 0.10668)
		(layer "F.Cu")
		(net "M_D_CPU1_SB_DQ<30>")
	)
	(segment
		(start 91.24696 -292.450774)
		(end 91.401138 -292.716204)
		(width 0.0889)
		(layer "In4.Cu")
		(net "M_D_CPU1_SB_DQ<30>")
	)
	(segment
		(start 33.493456 -316.597538)
		(end 33.493456 -316.028578)
		(width 0.14478)
		(layer "In4.Cu")
		(net "M_D_CPU1_SB_DQ<30>")
	)
	(segment
		(start 34.605976 -316.2173)
		(end 34.76879 -316.054486)
		(width 0.14478)
		(layer "In4.Cu")
		(net "M_D_CPU1_SB_DQ<30>")
	)
	(segment
		(start 33.493456 -316.028578)
		(end 33.65627 -315.865764)
		(width 0.14478)
		(layer "In4.Cu")
		(net "M_D_CPU1_SB_DQ<30>")
	)
	(segment
		(start 60.2107 -316.760352)
		(end 75.75931 -301.211742)
		(width 0.14478)
		(layer "In4.Cu")
		(net "M_D_CPU1_SB_DQ<30>")
	)
	(segment
		(start 75.75931 -301.211742)
		(end 75.75931 -298.66844)
		(width 0.14478)
		(layer "In4.Cu")
		(net "M_D_CPU1_SB_DQ<30>")
	)
	(segment
		(start 33.330642 -316.760352)
		(end 33.493456 -316.597538)
		(width 0.14478)
		(layer "In4.Cu")
		(net "M_D_CPU1_SB_DQ<30>")
	)
	(segment
		(start 78.310486 -296.117264)
		(end 78.562454 -295.865296)
		(width 0.0889)
		(layer "In4.Cu")
		(net "M_D_CPU1_SB_DQ<30>")
	)
	(segment
		(start 80.373474 -293.22141)
		(end 80.403954 -293.20363)
		(width 0.0889)
		(layer "In4.Cu")
		(net "M_D_CPU1_SB_DQ<30>")
	)
	(segment
		(start 34.21253 -316.760352)
		(end 34.443162 -316.760352)
		(width 0.14478)
		(layer "In4.Cu")
		(net "M_D_CPU1_SB_DQ<30>")
	)
	(segment
		(start 34.049716 -316.028578)
		(end 34.049716 -316.597538)
		(width 0.14478)
		(layer "In4.Cu")
		(net "M_D_CPU1_SB_DQ<30>")
	)
	(segment
		(start 88.394032 -292.393624)
		(end 88.402414 -292.388798)
		(width 0.0889)
		(layer "In4.Cu")
		(net "M_D_CPU1_SB_DQ<30>")
	)
	(segment
		(start 80.403954 -293.20363)
		(end 80.44307 -293.18077)
		(width 0.0889)
		(layer "In4.Cu")
		(net "M_D_CPU1_SB_DQ<30>")
	)
	(segment
		(start 33.120838 -316.760352)
		(end 33.330642 -316.760352)
		(width 0.14478)
		(layer "In4.Cu")
		(net "M_D_CPU1_SB_DQ<30>")
	)
	(segment
		(start 34.443162 -316.760352)
		(end 34.605976 -316.597538)
		(width 0.14478)
		(layer "In4.Cu")
		(net "M_D_CPU1_SB_DQ<30>")
	)
	(segment
		(start 34.049716 -316.597538)
		(end 34.21253 -316.760352)
		(width 0.14478)
		(layer "In4.Cu")
		(net "M_D_CPU1_SB_DQ<30>")
	)
	(segment
		(start 34.999422 -316.054486)
		(end 35.162236 -316.2173)
		(width 0.14478)
		(layer "In4.Cu")
		(net "M_D_CPU1_SB_DQ<30>")
	)
	(segment
		(start 79.432658 -294.84193)
		(end 79.464408 -294.823642)
		(width 0.0889)
		(layer "In4.Cu")
		(net "M_D_CPU1_SB_DQ<30>")
	)
	(segment
		(start 87.453978 -292.393624)
		(end 87.46236 -292.388798)
		(width 0.0889)
		(layer "In4.Cu")
		(net "M_D_CPU1_SB_DQ<30>")
	)
	(segment
		(start 79.934054 -294.013636)
		(end 79.97317 -293.990776)
		(width 0.0889)
		(layer "In4.Cu")
		(net "M_D_CPU1_SB_DQ<30>")
	)
	(segment
		(start 34.76879 -316.054486)
		(end 34.999422 -316.054486)
		(width 0.14478)
		(layer "In4.Cu")
		(net "M_D_CPU1_SB_DQ<30>")
	)
	(segment
		(start 83.694016 -292.393624)
		(end 83.702398 -292.388798)
		(width 0.0889)
		(layer "In4.Cu")
		(net "M_D_CPU1_SB_DQ<30>")
	)
	(segment
		(start 82.753962 -292.393624)
		(end 82.762344 -292.388798)
		(width 0.0889)
		(layer "In4.Cu")
		(net "M_D_CPU1_SB_DQ<30>")
	)
	(segment
		(start 82.179668 -292.388798)
		(end 82.18805 -292.393624)
		(width 0.0889)
		(layer "In4.Cu")
		(net "M_D_CPU1_SB_DQ<30>")
	)
	(segment
		(start 33.65627 -315.865764)
		(end 33.886902 -315.865764)
		(width 0.14478)
		(layer "In4.Cu")
		(net "M_D_CPU1_SB_DQ<30>")
	)
	(segment
		(start 91.150694 -292.425374)
		(end 91.24696 -292.450774)
		(width 0.0889)
		(layer "In4.Cu")
		(net "M_D_CPU1_SB_DQ<30>")
	)
	(segment
		(start 33.886902 -315.865764)
		(end 34.049716 -316.028578)
		(width 0.14478)
		(layer "In4.Cu")
		(net "M_D_CPU1_SB_DQ<30>")
	)
	(segment
		(start 34.605976 -316.597538)
		(end 34.605976 -316.2173)
		(width 0.14478)
		(layer "In4.Cu")
		(net "M_D_CPU1_SB_DQ<30>")
	)
	(segment
		(start 90.639646 -292.388798)
		(end 90.648028 -292.393624)
		(width 0.0889)
		(layer "In4.Cu")
		(net "M_D_CPU1_SB_DQ<30>")
	)
	(segment
		(start 78.947772 -295.66997)
		(end 79.0321 -295.611804)
		(width 0.0889)
		(layer "In4.Cu")
		(net "M_D_CPU1_SB_DQ<30>")
	)
	(segment
		(start 78.562454 -295.865296)
		(end 78.641702 -295.786302)
		(width 0.0889)
		(layer "In4.Cu")
		(net "M_D_CPU1_SB_DQ<30>")
	)
	(segment
		(start 32.695896 -316.33541)
		(end 33.120838 -316.760352)
		(width 0.14478)
		(layer "In4.Cu")
		(net "M_D_CPU1_SB_DQ<30>")
	)
	(segment
		(start 35.32505 -316.760352)
		(end 60.2107 -316.760352)
		(width 0.14478)
		(layer "In4.Cu")
		(net "M_D_CPU1_SB_DQ<30>")
	)
	(segment
		(start 35.162236 -316.2173)
		(end 35.162236 -316.597538)
		(width 0.14478)
		(layer "In4.Cu")
		(net "M_D_CPU1_SB_DQ<30>")
	)
	(segment
		(start 75.75931 -298.66844)
		(end 78.310486 -296.117264)
		(width 0.14478)
		(layer "In4.Cu")
		(net "M_D_CPU1_SB_DQ<30>")
	)
	(segment
		(start 86.879684 -292.388798)
		(end 86.888066 -292.393624)
		(width 0.0889)
		(layer "In4.Cu")
		(net "M_D_CPU1_SB_DQ<30>")
	)
	(segment
		(start 79.464408 -294.823642)
		(end 79.50073 -294.80256)
		(width 0.0889)
		(layer "In4.Cu")
		(net "M_D_CPU1_SB_DQ<30>")
	)
	(segment
		(start 80.842358 -292.411912)
		(end 80.874108 -292.393624)
		(width 0.0889)
		(layer "In4.Cu")
		(net "M_D_CPU1_SB_DQ<30>")
	)
	(segment
		(start 79.90459 -294.030654)
		(end 79.934054 -294.013636)
		(width 0.0889)
		(layer "In4.Cu")
		(net "M_D_CPU1_SB_DQ<30>")
	)
	(segment
		(start 35.162236 -316.597538)
		(end 35.32505 -316.760352)
		(width 0.14478)
		(layer "In4.Cu")
		(net "M_D_CPU1_SB_DQ<30>")
	)
	(segment
		(start 85.93963 -292.388798)
		(end 85.948012 -292.393624)
		(width 0.0889)
		(layer "In4.Cu")
		(net "M_D_CPU1_SB_DQ<30>")
	)
	(arc
		(start 88.768174 -292.393624)
		(mid 89.05113 -292.469801)
		(end 89.334086 -292.393624)
		(width 0.0889)
		(layer "In4.Cu")
		(net "M_D_CPU1_SB_DQ<30>")
	)
	(arc
		(start 81.813908 -292.393624)
		(mid 81.996159 -292.343274)
		(end 82.179668 -292.388798)
		(width 0.0889)
		(layer "In4.Cu")
		(net "M_D_CPU1_SB_DQ<30>")
	)
	(arc
		(start 81.247996 -292.393624)
		(mid 81.530952 -292.469801)
		(end 81.813908 -292.393624)
		(width 0.0889)
		(layer "In4.Cu")
		(net "M_D_CPU1_SB_DQ<30>")
	)
	(arc
		(start 80.874108 -292.393624)
		(mid 81.061052 -292.343369)
		(end 81.247996 -292.393624)
		(width 0.0889)
		(layer "In4.Cu")
		(net "M_D_CPU1_SB_DQ<30>")
	)
	(arc
		(start 88.402414 -292.388798)
		(mid 88.585922 -292.343304)
		(end 88.768174 -292.393624)
		(width 0.0889)
		(layer "In4.Cu")
		(net "M_D_CPU1_SB_DQ<30>")
	)
	(arc
		(start 84.63407 -292.393624)
		(mid 84.821014 -292.343369)
		(end 85.007958 -292.393624)
		(width 0.0889)
		(layer "In4.Cu")
		(net "M_D_CPU1_SB_DQ<30>")
	)
	(arc
		(start 86.513924 -292.393624)
		(mid 86.696175 -292.343274)
		(end 86.879684 -292.388798)
		(width 0.0889)
		(layer "In4.Cu")
		(net "M_D_CPU1_SB_DQ<30>")
	)
	(arc
		(start 87.46236 -292.388798)
		(mid 87.645868 -292.343304)
		(end 87.82812 -292.393624)
		(width 0.0889)
		(layer "In4.Cu")
		(net "M_D_CPU1_SB_DQ<30>")
	)
	(arc
		(start 83.702398 -292.388798)
		(mid 83.885906 -292.343304)
		(end 84.068158 -292.393624)
		(width 0.0889)
		(layer "In4.Cu")
		(net "M_D_CPU1_SB_DQ<30>")
	)
	(arc
		(start 85.007958 -292.393624)
		(mid 85.290914 -292.469801)
		(end 85.57387 -292.393624)
		(width 0.0889)
		(layer "In4.Cu")
		(net "M_D_CPU1_SB_DQ<30>")
	)
	(arc
		(start 84.068158 -292.393624)
		(mid 84.351114 -292.469801)
		(end 84.63407 -292.393624)
		(width 0.0889)
		(layer "In4.Cu")
		(net "M_D_CPU1_SB_DQ<30>")
	)
	(arc
		(start 80.686402 -292.716204)
		(mid 80.727657 -292.545233)
		(end 80.842358 -292.411912)
		(width 0.0889)
		(layer "In4.Cu")
		(net "M_D_CPU1_SB_DQ<30>")
	)
	(arc
		(start 90.648028 -292.393624)
		(mid 90.895624 -292.468802)
		(end 91.150694 -292.425374)
		(width 0.0889)
		(layer "In4.Cu")
		(net "M_D_CPU1_SB_DQ<30>")
	)
	(arc
		(start 78.641702 -295.786302)
		(mid 78.734916 -295.723925)
		(end 78.844902 -295.701974)
		(width 0.0889)
		(layer "In4.Cu")
		(net "M_D_CPU1_SB_DQ<30>")
	)
	(arc
		(start 85.57387 -292.393624)
		(mid 85.756121 -292.343274)
		(end 85.93963 -292.388798)
		(width 0.0889)
		(layer "In4.Cu")
		(net "M_D_CPU1_SB_DQ<30>")
	)
	(arc
		(start 79.276702 -295.146222)
		(mid 79.317957 -294.975251)
		(end 79.432658 -294.84193)
		(width 0.0889)
		(layer "In4.Cu")
		(net "M_D_CPU1_SB_DQ<30>")
	)
	(arc
		(start 80.44307 -293.18077)
		(mid 80.621883 -292.97842)
		(end 80.686402 -292.716204)
		(width 0.0889)
		(layer "In4.Cu")
		(net "M_D_CPU1_SB_DQ<30>")
	)
	(arc
		(start 87.82812 -292.393624)
		(mid 88.111076 -292.469801)
		(end 88.394032 -292.393624)
		(width 0.0889)
		(layer "In4.Cu")
		(net "M_D_CPU1_SB_DQ<30>")
	)
	(arc
		(start 78.844902 -295.701974)
		(mid 78.898763 -295.693779)
		(end 78.947772 -295.66997)
		(width 0.0889)
		(layer "In4.Cu")
		(net "M_D_CPU1_SB_DQ<30>")
	)
	(arc
		(start 80.216502 -293.52621)
		(mid 80.258051 -293.354788)
		(end 80.373474 -293.22141)
		(width 0.0889)
		(layer "In4.Cu")
		(net "M_D_CPU1_SB_DQ<30>")
	)
	(arc
		(start 83.128104 -292.393624)
		(mid 83.41106 -292.469801)
		(end 83.694016 -292.393624)
		(width 0.0889)
		(layer "In4.Cu")
		(net "M_D_CPU1_SB_DQ<30>")
	)
	(arc
		(start 89.334086 -292.393624)
		(mid 89.52103 -292.343369)
		(end 89.707974 -292.393624)
		(width 0.0889)
		(layer "In4.Cu")
		(net "M_D_CPU1_SB_DQ<30>")
	)
	(arc
		(start 82.762344 -292.388798)
		(mid 82.945852 -292.343304)
		(end 83.128104 -292.393624)
		(width 0.0889)
		(layer "In4.Cu")
		(net "M_D_CPU1_SB_DQ<30>")
	)
	(arc
		(start 90.273886 -292.393624)
		(mid 90.456137 -292.343274)
		(end 90.639646 -292.388798)
		(width 0.0889)
		(layer "In4.Cu")
		(net "M_D_CPU1_SB_DQ<30>")
	)
	(arc
		(start 85.948012 -292.393624)
		(mid 86.230968 -292.469801)
		(end 86.513924 -292.393624)
		(width 0.0889)
		(layer "In4.Cu")
		(net "M_D_CPU1_SB_DQ<30>")
	)
	(arc
		(start 79.0321 -295.611804)
		(mid 79.211829 -295.409184)
		(end 79.276702 -295.146222)
		(width 0.0889)
		(layer "In4.Cu")
		(net "M_D_CPU1_SB_DQ<30>")
	)
	(arc
		(start 82.18805 -292.393624)
		(mid 82.471006 -292.469801)
		(end 82.753962 -292.393624)
		(width 0.0889)
		(layer "In4.Cu")
		(net "M_D_CPU1_SB_DQ<30>")
	)
	(arc
		(start 89.707974 -292.393624)
		(mid 89.99093 -292.469801)
		(end 90.273886 -292.393624)
		(width 0.0889)
		(layer "In4.Cu")
		(net "M_D_CPU1_SB_DQ<30>")
	)
	(arc
		(start 79.97317 -293.990776)
		(mid 80.151983 -293.788426)
		(end 80.216502 -293.52621)
		(width 0.0889)
		(layer "In4.Cu")
		(net "M_D_CPU1_SB_DQ<30>")
	)
	(arc
		(start 79.746602 -294.336216)
		(mid 79.788442 -294.16423)
		(end 79.90459 -294.030654)
		(width 0.0889)
		(layer "In4.Cu")
		(net "M_D_CPU1_SB_DQ<30>")
	)
	(arc
		(start 79.50073 -294.80256)
		(mid 79.681382 -294.599815)
		(end 79.746602 -294.336216)
		(width 0.0889)
		(layer "In4.Cu")
		(net "M_D_CPU1_SB_DQ<30>")
	)
	(arc
		(start 86.888066 -292.393624)
		(mid 87.171022 -292.469801)
		(end 87.453978 -292.393624)
		(width 0.0889)
		(layer "In4.Cu")
		(net "M_D_CPU1_SB_DQ<30>")
	)
	(segment
		(start 91.86799 -274.630388)
		(end 91.401138 -274.896326)
		(width 0.10668)
		(layer "F.Cu")
		(net "M_D_CPU1_SB_DQ<2>")
	)
	(segment
		(start 80.299814 -274.56892)
		(end 80.308196 -274.573746)
		(width 0.0889)
		(layer "In4.Cu")
		(net "M_D_CPU1_SB_DQ<2>")
	)
	(segment
		(start 34.43097 -282.597606)
		(end 34.593784 -282.76042)
		(width 0.14478)
		(layer "In4.Cu")
		(net "M_D_CPU1_SB_DQ<2>")
	)
	(segment
		(start 34.43097 -281.78506)
		(end 34.43097 -282.597606)
		(width 0.14478)
		(layer "In4.Cu")
		(net "M_D_CPU1_SB_DQ<2>")
	)
	(segment
		(start 34.593784 -282.76042)
		(end 42.18813 -282.76042)
		(width 0.14478)
		(layer "In4.Cu")
		(net "M_D_CPU1_SB_DQ<2>")
	)
	(segment
		(start 91.24696 -274.630896)
		(end 91.401138 -274.896326)
		(width 0.0889)
		(layer "In4.Cu")
		(net "M_D_CPU1_SB_DQ<2>")
	)
	(segment
		(start 76.30795 -273.738086)
		(end 77.56525 -273.738086)
		(width 0.0889)
		(layer "In4.Cu")
		(net "M_D_CPU1_SB_DQ<2>")
	)
	(segment
		(start 78.977744 -274.583144)
		(end 78.993492 -274.574)
		(width 0.0889)
		(layer "In4.Cu")
		(net "M_D_CPU1_SB_DQ<2>")
	)
	(segment
		(start 33.87471 -281.78506)
		(end 34.037524 -281.622246)
		(width 0.14478)
		(layer "In4.Cu")
		(net "M_D_CPU1_SB_DQ<2>")
	)
	(segment
		(start 77.56525 -273.738086)
		(end 78.312264 -274.4851)
		(width 0.0889)
		(layer "In4.Cu")
		(net "M_D_CPU1_SB_DQ<2>")
	)
	(segment
		(start 78.993492 -274.574)
		(end 79.009748 -274.564602)
		(width 0.0889)
		(layer "In4.Cu")
		(net "M_D_CPU1_SB_DQ<2>")
	)
	(segment
		(start 75.985116 -273.675094)
		(end 76.244958 -273.675094)
		(width 0.0889)
		(layer "In4.Cu")
		(net "M_D_CPU1_SB_DQ<2>")
	)
	(segment
		(start 52.978304 -281.910282)
		(end 53.433218 -282.365196)
		(width 0.14478)
		(layer "In4.Cu")
		(net "M_D_CPU1_SB_DQ<2>")
	)
	(segment
		(start 50.123852 -281.910282)
		(end 52.978304 -281.910282)
		(width 0.14478)
		(layer "In4.Cu")
		(net "M_D_CPU1_SB_DQ<2>")
	)
	(segment
		(start 43.038268 -281.910282)
		(end 45.409104 -281.910282)
		(width 0.14478)
		(layer "In4.Cu")
		(net "M_D_CPU1_SB_DQ<2>")
	)
	(segment
		(start 76.244958 -273.675094)
		(end 76.30795 -273.738086)
		(width 0.0889)
		(layer "In4.Cu")
		(net "M_D_CPU1_SB_DQ<2>")
	)
	(segment
		(start 85.93963 -274.56892)
		(end 85.948012 -274.573746)
		(width 0.0889)
		(layer "In4.Cu")
		(net "M_D_CPU1_SB_DQ<2>")
	)
	(segment
		(start 88.394032 -274.573746)
		(end 88.402414 -274.56892)
		(width 0.0889)
		(layer "In4.Cu")
		(net "M_D_CPU1_SB_DQ<2>")
	)
	(segment
		(start 87.453978 -274.573746)
		(end 87.46236 -274.56892)
		(width 0.0889)
		(layer "In4.Cu")
		(net "M_D_CPU1_SB_DQ<2>")
	)
	(segment
		(start 45.409104 -281.910282)
		(end 46.259242 -282.76042)
		(width 0.14478)
		(layer "In4.Cu")
		(net "M_D_CPU1_SB_DQ<2>")
	)
	(segment
		(start 82.179668 -274.56892)
		(end 82.18805 -274.573746)
		(width 0.0889)
		(layer "In4.Cu")
		(net "M_D_CPU1_SB_DQ<2>")
	)
	(segment
		(start 46.259242 -282.76042)
		(end 49.273714 -282.76042)
		(width 0.14478)
		(layer "In4.Cu")
		(net "M_D_CPU1_SB_DQ<2>")
	)
	(segment
		(start 33.121092 -282.76042)
		(end 33.711896 -282.76042)
		(width 0.14478)
		(layer "In4.Cu")
		(net "M_D_CPU1_SB_DQ<2>")
	)
	(segment
		(start 34.268156 -281.622246)
		(end 34.43097 -281.78506)
		(width 0.14478)
		(layer "In4.Cu")
		(net "M_D_CPU1_SB_DQ<2>")
	)
	(segment
		(start 42.18813 -282.76042)
		(end 43.038268 -281.910282)
		(width 0.14478)
		(layer "In4.Cu")
		(net "M_D_CPU1_SB_DQ<2>")
	)
	(segment
		(start 57.846468 -281.910282)
		(end 59.804554 -281.910282)
		(width 0.14478)
		(layer "In4.Cu")
		(net "M_D_CPU1_SB_DQ<2>")
	)
	(segment
		(start 82.753962 -274.573746)
		(end 82.762344 -274.56892)
		(width 0.0889)
		(layer "In4.Cu")
		(net "M_D_CPU1_SB_DQ<2>")
	)
	(segment
		(start 79.36738 -274.573746)
		(end 79.377794 -274.579842)
		(width 0.0889)
		(layer "In4.Cu")
		(net "M_D_CPU1_SB_DQ<2>")
	)
	(segment
		(start 90.639646 -274.56892)
		(end 90.648028 -274.573746)
		(width 0.0889)
		(layer "In4.Cu")
		(net "M_D_CPU1_SB_DQ<2>")
	)
	(segment
		(start 32.695896 -282.335224)
		(end 33.121092 -282.76042)
		(width 0.14478)
		(layer "In4.Cu")
		(net "M_D_CPU1_SB_DQ<2>")
	)
	(segment
		(start 59.804554 -281.910282)
		(end 68.039742 -273.675094)
		(width 0.14478)
		(layer "In4.Cu")
		(net "M_D_CPU1_SB_DQ<2>")
	)
	(segment
		(start 33.711896 -282.76042)
		(end 33.87471 -282.597606)
		(width 0.14478)
		(layer "In4.Cu")
		(net "M_D_CPU1_SB_DQ<2>")
	)
	(segment
		(start 34.037524 -281.622246)
		(end 34.268156 -281.622246)
		(width 0.14478)
		(layer "In4.Cu")
		(net "M_D_CPU1_SB_DQ<2>")
	)
	(segment
		(start 49.273714 -282.76042)
		(end 50.123852 -281.910282)
		(width 0.14478)
		(layer "In4.Cu")
		(net "M_D_CPU1_SB_DQ<2>")
	)
	(segment
		(start 68.039742 -273.675094)
		(end 75.985116 -273.675094)
		(width 0.14478)
		(layer "In4.Cu")
		(net "M_D_CPU1_SB_DQ<2>")
	)
	(segment
		(start 53.433218 -282.365196)
		(end 57.391554 -282.365196)
		(width 0.14478)
		(layer "In4.Cu")
		(net "M_D_CPU1_SB_DQ<2>")
	)
	(segment
		(start 57.391554 -282.365196)
		(end 57.846468 -281.910282)
		(width 0.14478)
		(layer "In4.Cu")
		(net "M_D_CPU1_SB_DQ<2>")
	)
	(segment
		(start 91.150694 -274.605496)
		(end 91.24696 -274.630896)
		(width 0.0889)
		(layer "In4.Cu")
		(net "M_D_CPU1_SB_DQ<2>")
	)
	(segment
		(start 83.694016 -274.573746)
		(end 83.702398 -274.56892)
		(width 0.0889)
		(layer "In4.Cu")
		(net "M_D_CPU1_SB_DQ<2>")
	)
	(segment
		(start 33.87471 -282.597606)
		(end 33.87471 -281.78506)
		(width 0.14478)
		(layer "In4.Cu")
		(net "M_D_CPU1_SB_DQ<2>")
	)
	(segment
		(start 86.879684 -274.56892)
		(end 86.888066 -274.573746)
		(width 0.0889)
		(layer "In4.Cu")
		(net "M_D_CPU1_SB_DQ<2>")
	)
	(arc
		(start 79.933546 -274.573746)
		(mid 80.116051 -274.523269)
		(end 80.299814 -274.56892)
		(width 0.0889)
		(layer "In4.Cu")
		(net "M_D_CPU1_SB_DQ<2>")
	)
	(arc
		(start 84.63407 -274.573746)
		(mid 84.821014 -274.523491)
		(end 85.007958 -274.573746)
		(width 0.0889)
		(layer "In4.Cu")
		(net "M_D_CPU1_SB_DQ<2>")
	)
	(arc
		(start 84.068158 -274.573746)
		(mid 84.351114 -274.649923)
		(end 84.63407 -274.573746)
		(width 0.0889)
		(layer "In4.Cu")
		(net "M_D_CPU1_SB_DQ<2>")
	)
	(arc
		(start 81.247996 -274.573746)
		(mid 81.530952 -274.649923)
		(end 81.813908 -274.573746)
		(width 0.0889)
		(layer "In4.Cu")
		(net "M_D_CPU1_SB_DQ<2>")
	)
	(arc
		(start 83.702398 -274.56892)
		(mid 83.885906 -274.523426)
		(end 84.068158 -274.573746)
		(width 0.0889)
		(layer "In4.Cu")
		(net "M_D_CPU1_SB_DQ<2>")
	)
	(arc
		(start 78.42758 -274.573746)
		(mid 78.701435 -274.650096)
		(end 78.977744 -274.583144)
		(width 0.0889)
		(layer "In4.Cu")
		(net "M_D_CPU1_SB_DQ<2>")
	)
	(arc
		(start 82.762344 -274.56892)
		(mid 82.945852 -274.523426)
		(end 83.128104 -274.573746)
		(width 0.0889)
		(layer "In4.Cu")
		(net "M_D_CPU1_SB_DQ<2>")
	)
	(arc
		(start 88.402414 -274.56892)
		(mid 88.585922 -274.523426)
		(end 88.768174 -274.573746)
		(width 0.0889)
		(layer "In4.Cu")
		(net "M_D_CPU1_SB_DQ<2>")
	)
	(arc
		(start 80.308196 -274.573746)
		(mid 80.591152 -274.649923)
		(end 80.874108 -274.573746)
		(width 0.0889)
		(layer "In4.Cu")
		(net "M_D_CPU1_SB_DQ<2>")
	)
	(arc
		(start 79.009748 -274.564602)
		(mid 79.18973 -274.523502)
		(end 79.36738 -274.573746)
		(width 0.0889)
		(layer "In4.Cu")
		(net "M_D_CPU1_SB_DQ<2>")
	)
	(arc
		(start 85.007958 -274.573746)
		(mid 85.290914 -274.649923)
		(end 85.57387 -274.573746)
		(width 0.0889)
		(layer "In4.Cu")
		(net "M_D_CPU1_SB_DQ<2>")
	)
	(arc
		(start 78.312264 -274.4851)
		(mid 78.367049 -274.53316)
		(end 78.42758 -274.573746)
		(width 0.0889)
		(layer "In4.Cu")
		(net "M_D_CPU1_SB_DQ<2>")
	)
	(arc
		(start 86.888066 -274.573746)
		(mid 87.171022 -274.649923)
		(end 87.453978 -274.573746)
		(width 0.0889)
		(layer "In4.Cu")
		(net "M_D_CPU1_SB_DQ<2>")
	)
	(arc
		(start 89.334086 -274.573746)
		(mid 89.52103 -274.523491)
		(end 89.707974 -274.573746)
		(width 0.0889)
		(layer "In4.Cu")
		(net "M_D_CPU1_SB_DQ<2>")
	)
	(arc
		(start 85.948012 -274.573746)
		(mid 86.230968 -274.649923)
		(end 86.513924 -274.573746)
		(width 0.0889)
		(layer "In4.Cu")
		(net "M_D_CPU1_SB_DQ<2>")
	)
	(arc
		(start 87.82812 -274.573746)
		(mid 88.111076 -274.649923)
		(end 88.394032 -274.573746)
		(width 0.0889)
		(layer "In4.Cu")
		(net "M_D_CPU1_SB_DQ<2>")
	)
	(arc
		(start 80.874108 -274.573746)
		(mid 81.061052 -274.523491)
		(end 81.247996 -274.573746)
		(width 0.0889)
		(layer "In4.Cu")
		(net "M_D_CPU1_SB_DQ<2>")
	)
	(arc
		(start 89.707974 -274.573746)
		(mid 89.99093 -274.649923)
		(end 90.273886 -274.573746)
		(width 0.0889)
		(layer "In4.Cu")
		(net "M_D_CPU1_SB_DQ<2>")
	)
	(arc
		(start 85.57387 -274.573746)
		(mid 85.756121 -274.523396)
		(end 85.93963 -274.56892)
		(width 0.0889)
		(layer "In4.Cu")
		(net "M_D_CPU1_SB_DQ<2>")
	)
	(arc
		(start 90.273886 -274.573746)
		(mid 90.456137 -274.523396)
		(end 90.639646 -274.56892)
		(width 0.0889)
		(layer "In4.Cu")
		(net "M_D_CPU1_SB_DQ<2>")
	)
	(arc
		(start 83.128104 -274.573746)
		(mid 83.41106 -274.649923)
		(end 83.694016 -274.573746)
		(width 0.0889)
		(layer "In4.Cu")
		(net "M_D_CPU1_SB_DQ<2>")
	)
	(arc
		(start 81.813908 -274.573746)
		(mid 81.996159 -274.523396)
		(end 82.179668 -274.56892)
		(width 0.0889)
		(layer "In4.Cu")
		(net "M_D_CPU1_SB_DQ<2>")
	)
	(arc
		(start 88.768174 -274.573746)
		(mid 89.05113 -274.649923)
		(end 89.334086 -274.573746)
		(width 0.0889)
		(layer "In4.Cu")
		(net "M_D_CPU1_SB_DQ<2>")
	)
	(arc
		(start 86.513924 -274.573746)
		(mid 86.696175 -274.523396)
		(end 86.879684 -274.56892)
		(width 0.0889)
		(layer "In4.Cu")
		(net "M_D_CPU1_SB_DQ<2>")
	)
	(arc
		(start 79.377794 -274.579842)
		(mid 79.65648 -274.650062)
		(end 79.933546 -274.573746)
		(width 0.0889)
		(layer "In4.Cu")
		(net "M_D_CPU1_SB_DQ<2>")
	)
	(arc
		(start 82.18805 -274.573746)
		(mid 82.471006 -274.649923)
		(end 82.753962 -274.573746)
		(width 0.0889)
		(layer "In4.Cu")
		(net "M_D_CPU1_SB_DQ<2>")
	)
	(arc
		(start 90.648028 -274.573746)
		(mid 90.895624 -274.648924)
		(end 91.150694 -274.605496)
		(width 0.0889)
		(layer "In4.Cu")
		(net "M_D_CPU1_SB_DQ<2>")
	)
	(arc
		(start 87.46236 -274.56892)
		(mid 87.645868 -274.523426)
		(end 87.82812 -274.573746)
		(width 0.0889)
		(layer "In4.Cu")
		(net "M_D_CPU1_SB_DQ<2>")
	)
	(segment
		(start 92.80779 -292.450266)
		(end 92.340938 -292.716204)
		(width 0.10668)
		(layer "F.Cu")
		(net "M_D_CPU1_SB_DQ<29>")
	)
	(segment
		(start 39.110158 -317.830708)
		(end 39.110158 -317.378588)
		(width 0.14478)
		(layer "In4.Cu")
		(net "M_D_CPU1_SB_DQ<29>")
	)
	(segment
		(start 37.997638 -317.830708)
		(end 37.997638 -317.378588)
		(width 0.14478)
		(layer "In4.Cu")
		(net "M_D_CPU1_SB_DQ<29>")
	)
	(segment
		(start 42.82186 -317.441326)
		(end 43.052492 -317.441326)
		(width 0.14478)
		(layer "In4.Cu")
		(net "M_D_CPU1_SB_DQ<29>")
	)
	(segment
		(start 43.37812 -317.999364)
		(end 43.608752 -317.999364)
		(width 0.14478)
		(layer "In4.Cu")
		(net "M_D_CPU1_SB_DQ<29>")
	)
	(segment
		(start 42.102786 -317.38443)
		(end 42.102786 -317.83655)
		(width 0.14478)
		(layer "In4.Cu")
		(net "M_D_CPU1_SB_DQ<29>")
	)
	(segment
		(start 44.703238 -317.61049)
		(end 45.092112 -317.999364)
		(width 0.14478)
		(layer "In4.Cu")
		(net "M_D_CPU1_SB_DQ<29>")
	)
	(segment
		(start 76.244196 -298.869354)
		(end 78.625954 -296.487596)
		(width 0.14478)
		(layer "In4.Cu")
		(net "M_D_CPU1_SB_DQ<29>")
	)
	(segment
		(start 41.939972 -317.221616)
		(end 42.102786 -317.38443)
		(width 0.14478)
		(layer "In4.Cu")
		(net "M_D_CPU1_SB_DQ<29>")
	)
	(segment
		(start 81.211674 -293.059866)
		(end 81.247996 -293.038784)
		(width 0.0889)
		(layer "In4.Cu")
		(net "M_D_CPU1_SB_DQ<29>")
	)
	(segment
		(start 88.394032 -293.038784)
		(end 88.402414 -293.04361)
		(width 0.0889)
		(layer "In4.Cu")
		(net "M_D_CPU1_SB_DQ<29>")
	)
	(segment
		(start 38.947344 -317.993522)
		(end 39.110158 -317.830708)
		(width 0.14478)
		(layer "In4.Cu")
		(net "M_D_CPU1_SB_DQ<29>")
	)
	(segment
		(start 38.553898 -317.830708)
		(end 38.716712 -317.993522)
		(width 0.14478)
		(layer "In4.Cu")
		(net "M_D_CPU1_SB_DQ<29>")
	)
	(segment
		(start 39.503604 -317.215774)
		(end 39.89832 -317.61049)
		(width 0.14478)
		(layer "In4.Cu")
		(net "M_D_CPU1_SB_DQ<29>")
	)
	(segment
		(start 82.179668 -293.04361)
		(end 82.18805 -293.038784)
		(width 0.0889)
		(layer "In4.Cu")
		(net "M_D_CPU1_SB_DQ<29>")
	)
	(segment
		(start 40.764206 -317.61049)
		(end 41.15308 -317.999364)
		(width 0.14478)
		(layer "In4.Cu")
		(net "M_D_CPU1_SB_DQ<29>")
	)
	(segment
		(start 36.795964 -317.185294)
		(end 37.604192 -317.993522)
		(width 0.14478)
		(layer "In4.Cu")
		(net "M_D_CPU1_SB_DQ<29>")
	)
	(segment
		(start 45.092112 -317.999364)
		(end 45.322744 -317.999364)
		(width 0.14478)
		(layer "In4.Cu")
		(net "M_D_CPU1_SB_DQ<29>")
	)
	(segment
		(start 90.639646 -293.04361)
		(end 90.648028 -293.038784)
		(width 0.0889)
		(layer "In4.Cu")
		(net "M_D_CPU1_SB_DQ<29>")
	)
	(segment
		(start 43.997626 -317.61049)
		(end 44.703238 -317.61049)
		(width 0.14478)
		(layer "In4.Cu")
		(net "M_D_CPU1_SB_DQ<29>")
	)
	(segment
		(start 92.153994 -293.038784)
		(end 92.162376 -293.04361)
		(width 0.0889)
		(layer "In4.Cu")
		(net "M_D_CPU1_SB_DQ<29>")
	)
	(segment
		(start 91.5797 -293.04361)
		(end 91.588082 -293.038784)
		(width 0.0889)
		(layer "In4.Cu")
		(net "M_D_CPU1_SB_DQ<29>")
	)
	(segment
		(start 87.453978 -293.038784)
		(end 87.46236 -293.04361)
		(width 0.0889)
		(layer "In4.Cu")
		(net "M_D_CPU1_SB_DQ<29>")
	)
	(segment
		(start 41.15308 -317.999364)
		(end 41.383712 -317.999364)
		(width 0.14478)
		(layer "In4.Cu")
		(net "M_D_CPU1_SB_DQ<29>")
	)
	(segment
		(start 83.694016 -293.038784)
		(end 83.702398 -293.04361)
		(width 0.0889)
		(layer "In4.Cu")
		(net "M_D_CPU1_SB_DQ<29>")
	)
	(segment
		(start 39.272972 -317.215774)
		(end 39.503604 -317.215774)
		(width 0.14478)
		(layer "In4.Cu")
		(net "M_D_CPU1_SB_DQ<29>")
	)
	(segment
		(start 80.73898 -293.87165)
		(end 80.778096 -293.84879)
		(width 0.0889)
		(layer "In4.Cu")
		(net "M_D_CPU1_SB_DQ<29>")
	)
	(segment
		(start 38.716712 -317.993522)
		(end 38.947344 -317.993522)
		(width 0.14478)
		(layer "In4.Cu")
		(net "M_D_CPU1_SB_DQ<29>")
	)
	(segment
		(start 42.659046 -317.83655)
		(end 42.659046 -317.60414)
		(width 0.14478)
		(layer "In4.Cu")
		(net "M_D_CPU1_SB_DQ<29>")
	)
	(segment
		(start 92.472764 -293.064946)
		(end 92.495116 -292.981634)
		(width 0.0889)
		(layer "In4.Cu")
		(net "M_D_CPU1_SB_DQ<29>")
	)
	(segment
		(start 79.838296 -295.468802)
		(end 79.870046 -295.450514)
		(width 0.0889)
		(layer "In4.Cu")
		(net "M_D_CPU1_SB_DQ<29>")
	)
	(segment
		(start 37.997638 -317.378588)
		(end 38.160452 -317.215774)
		(width 0.14478)
		(layer "In4.Cu")
		(net "M_D_CPU1_SB_DQ<29>")
	)
	(segment
		(start 80.271874 -294.679878)
		(end 80.308196 -294.658796)
		(width 0.0889)
		(layer "In4.Cu")
		(net "M_D_CPU1_SB_DQ<29>")
	)
	(segment
		(start 39.110158 -317.378588)
		(end 39.272972 -317.215774)
		(width 0.14478)
		(layer "In4.Cu")
		(net "M_D_CPU1_SB_DQ<29>")
	)
	(segment
		(start 41.546526 -317.38443)
		(end 41.70934 -317.221616)
		(width 0.14478)
		(layer "In4.Cu")
		(net "M_D_CPU1_SB_DQ<29>")
	)
	(segment
		(start 37.604192 -317.993522)
		(end 37.834824 -317.993522)
		(width 0.14478)
		(layer "In4.Cu")
		(net "M_D_CPU1_SB_DQ<29>")
	)
	(segment
		(start 43.215306 -317.60414)
		(end 43.215306 -317.83655)
		(width 0.14478)
		(layer "In4.Cu")
		(net "M_D_CPU1_SB_DQ<29>")
	)
	(segment
		(start 42.659046 -317.60414)
		(end 42.82186 -317.441326)
		(width 0.14478)
		(layer "In4.Cu")
		(net "M_D_CPU1_SB_DQ<29>")
	)
	(segment
		(start 45.485558 -317.38443)
		(end 45.648372 -317.221616)
		(width 0.14478)
		(layer "In4.Cu")
		(net "M_D_CPU1_SB_DQ<29>")
	)
	(segment
		(start 79.238348 -296.354246)
		(end 79.400908 -296.259758)
		(width 0.0889)
		(layer "In4.Cu")
		(net "M_D_CPU1_SB_DQ<29>")
	)
	(segment
		(start 38.391084 -317.215774)
		(end 38.553898 -317.378588)
		(width 0.14478)
		(layer "In4.Cu")
		(net "M_D_CPU1_SB_DQ<29>")
	)
	(segment
		(start 82.753962 -293.038784)
		(end 82.762344 -293.04361)
		(width 0.0889)
		(layer "In4.Cu")
		(net "M_D_CPU1_SB_DQ<29>")
	)
	(segment
		(start 39.89832 -317.61049)
		(end 40.764206 -317.61049)
		(width 0.14478)
		(layer "In4.Cu")
		(net "M_D_CPU1_SB_DQ<29>")
	)
	(segment
		(start 41.546526 -317.83655)
		(end 41.546526 -317.38443)
		(width 0.14478)
		(layer "In4.Cu")
		(net "M_D_CPU1_SB_DQ<29>")
	)
	(segment
		(start 46.267878 -317.61049)
		(end 59.996578 -317.61049)
		(width 0.14478)
		(layer "In4.Cu")
		(net "M_D_CPU1_SB_DQ<29>")
	)
	(segment
		(start 38.553898 -317.378588)
		(end 38.553898 -317.830708)
		(width 0.14478)
		(layer "In4.Cu")
		(net "M_D_CPU1_SB_DQ<29>")
	)
	(segment
		(start 42.2656 -317.999364)
		(end 42.496232 -317.999364)
		(width 0.14478)
		(layer "In4.Cu")
		(net "M_D_CPU1_SB_DQ<29>")
	)
	(segment
		(start 43.608752 -317.999364)
		(end 43.997626 -317.61049)
		(width 0.14478)
		(layer "In4.Cu")
		(net "M_D_CPU1_SB_DQ<29>")
	)
	(segment
		(start 42.496232 -317.999364)
		(end 42.659046 -317.83655)
		(width 0.14478)
		(layer "In4.Cu")
		(net "M_D_CPU1_SB_DQ<29>")
	)
	(segment
		(start 45.879004 -317.221616)
		(end 46.267878 -317.61049)
		(width 0.14478)
		(layer "In4.Cu")
		(net "M_D_CPU1_SB_DQ<29>")
	)
	(segment
		(start 86.879684 -293.04361)
		(end 86.888066 -293.038784)
		(width 0.0889)
		(layer "In4.Cu")
		(net "M_D_CPU1_SB_DQ<29>")
	)
	(segment
		(start 76.244196 -301.362872)
		(end 76.244196 -298.869354)
		(width 0.14478)
		(layer "In4.Cu")
		(net "M_D_CPU1_SB_DQ<29>")
	)
	(segment
		(start 80.308196 -294.658796)
		(end 80.338676 -294.641016)
		(width 0.0889)
		(layer "In4.Cu")
		(net "M_D_CPU1_SB_DQ<29>")
	)
	(segment
		(start 59.996578 -317.61049)
		(end 76.244196 -301.362872)
		(width 0.14478)
		(layer "In4.Cu")
		(net "M_D_CPU1_SB_DQ<29>")
	)
	(segment
		(start 79.79918 -295.491662)
		(end 79.838296 -295.468802)
		(width 0.0889)
		(layer "In4.Cu")
		(net "M_D_CPU1_SB_DQ<29>")
	)
	(segment
		(start 43.215306 -317.83655)
		(end 43.37812 -317.999364)
		(width 0.14478)
		(layer "In4.Cu")
		(net "M_D_CPU1_SB_DQ<29>")
	)
	(segment
		(start 43.052492 -317.441326)
		(end 43.215306 -317.60414)
		(width 0.14478)
		(layer "In4.Cu")
		(net "M_D_CPU1_SB_DQ<29>")
	)
	(segment
		(start 38.160452 -317.215774)
		(end 38.391084 -317.215774)
		(width 0.14478)
		(layer "In4.Cu")
		(net "M_D_CPU1_SB_DQ<29>")
	)
	(segment
		(start 45.322744 -317.999364)
		(end 45.485558 -317.83655)
		(width 0.14478)
		(layer "In4.Cu")
		(net "M_D_CPU1_SB_DQ<29>")
	)
	(segment
		(start 92.495116 -292.981634)
		(end 92.340938 -292.716204)
		(width 0.0889)
		(layer "In4.Cu")
		(net "M_D_CPU1_SB_DQ<29>")
	)
	(segment
		(start 80.778096 -293.84879)
		(end 80.809846 -293.830502)
		(width 0.0889)
		(layer "In4.Cu")
		(net "M_D_CPU1_SB_DQ<29>")
	)
	(segment
		(start 41.383712 -317.999364)
		(end 41.546526 -317.83655)
		(width 0.14478)
		(layer "In4.Cu")
		(net "M_D_CPU1_SB_DQ<29>")
	)
	(segment
		(start 45.485558 -317.83655)
		(end 45.485558 -317.38443)
		(width 0.14478)
		(layer "In4.Cu")
		(net "M_D_CPU1_SB_DQ<29>")
	)
	(segment
		(start 85.93963 -293.04361)
		(end 85.948012 -293.038784)
		(width 0.0889)
		(layer "In4.Cu")
		(net "M_D_CPU1_SB_DQ<29>")
	)
	(segment
		(start 45.648372 -317.221616)
		(end 45.879004 -317.221616)
		(width 0.14478)
		(layer "In4.Cu")
		(net "M_D_CPU1_SB_DQ<29>")
	)
	(segment
		(start 41.70934 -317.221616)
		(end 41.939972 -317.221616)
		(width 0.14478)
		(layer "In4.Cu")
		(net "M_D_CPU1_SB_DQ<29>")
	)
	(segment
		(start 78.818994 -296.407586)
		(end 79.040482 -296.407586)
		(width 0.0889)
		(layer "In4.Cu")
		(net "M_D_CPU1_SB_DQ<29>")
	)
	(segment
		(start 37.834824 -317.993522)
		(end 37.997638 -317.830708)
		(width 0.14478)
		(layer "In4.Cu")
		(net "M_D_CPU1_SB_DQ<29>")
	)
	(segment
		(start 42.102786 -317.83655)
		(end 42.2656 -317.999364)
		(width 0.14478)
		(layer "In4.Cu")
		(net "M_D_CPU1_SB_DQ<29>")
	)
	(arc
		(start 81.813908 -293.038784)
		(mid 81.996159 -293.089134)
		(end 82.179668 -293.04361)
		(width 0.0889)
		(layer "In4.Cu")
		(net "M_D_CPU1_SB_DQ<29>")
	)
	(arc
		(start 81.247996 -293.038784)
		(mid 81.530952 -292.962607)
		(end 81.813908 -293.038784)
		(width 0.0889)
		(layer "In4.Cu")
		(net "M_D_CPU1_SB_DQ<29>")
	)
	(arc
		(start 86.513924 -293.038784)
		(mid 86.696175 -293.089134)
		(end 86.879684 -293.04361)
		(width 0.0889)
		(layer "In4.Cu")
		(net "M_D_CPU1_SB_DQ<29>")
	)
	(arc
		(start 86.888066 -293.038784)
		(mid 87.171022 -292.962607)
		(end 87.453978 -293.038784)
		(width 0.0889)
		(layer "In4.Cu")
		(net "M_D_CPU1_SB_DQ<29>")
	)
	(arc
		(start 82.762344 -293.04361)
		(mid 82.945852 -293.089104)
		(end 83.128104 -293.038784)
		(width 0.0889)
		(layer "In4.Cu")
		(net "M_D_CPU1_SB_DQ<29>")
	)
	(arc
		(start 79.400908 -296.259758)
		(mid 79.514837 -296.126611)
		(end 79.555848 -295.956228)
		(width 0.0889)
		(layer "In4.Cu")
		(net "M_D_CPU1_SB_DQ<29>")
	)
	(arc
		(start 89.707974 -293.038784)
		(mid 89.99093 -292.962607)
		(end 90.273886 -293.038784)
		(width 0.0889)
		(layer "In4.Cu")
		(net "M_D_CPU1_SB_DQ<29>")
	)
	(arc
		(start 91.588082 -293.038784)
		(mid 91.871038 -292.962607)
		(end 92.153994 -293.038784)
		(width 0.0889)
		(layer "In4.Cu")
		(net "M_D_CPU1_SB_DQ<29>")
	)
	(arc
		(start 83.128104 -293.038784)
		(mid 83.41106 -292.962607)
		(end 83.694016 -293.038784)
		(width 0.0889)
		(layer "In4.Cu")
		(net "M_D_CPU1_SB_DQ<29>")
	)
	(arc
		(start 79.870046 -295.450514)
		(mid 79.984722 -295.31718)
		(end 80.026002 -295.146222)
		(width 0.0889)
		(layer "In4.Cu")
		(net "M_D_CPU1_SB_DQ<29>")
	)
	(arc
		(start 83.702398 -293.04361)
		(mid 83.885906 -293.089104)
		(end 84.068158 -293.038784)
		(width 0.0889)
		(layer "In4.Cu")
		(net "M_D_CPU1_SB_DQ<29>")
	)
	(arc
		(start 85.948012 -293.038784)
		(mid 86.230968 -292.962607)
		(end 86.513924 -293.038784)
		(width 0.0889)
		(layer "In4.Cu")
		(net "M_D_CPU1_SB_DQ<29>")
	)
	(arc
		(start 80.809846 -293.830502)
		(mid 80.924522 -293.697168)
		(end 80.965802 -293.52621)
		(width 0.0889)
		(layer "In4.Cu")
		(net "M_D_CPU1_SB_DQ<29>")
	)
	(arc
		(start 87.46236 -293.04361)
		(mid 87.645868 -293.089104)
		(end 87.82812 -293.038784)
		(width 0.0889)
		(layer "In4.Cu")
		(net "M_D_CPU1_SB_DQ<29>")
	)
	(arc
		(start 78.625954 -296.487596)
		(mid 78.714522 -296.428417)
		(end 78.818994 -296.407586)
		(width 0.0889)
		(layer "In4.Cu")
		(net "M_D_CPU1_SB_DQ<29>")
	)
	(arc
		(start 92.162376 -293.04361)
		(mid 92.315246 -293.088251)
		(end 92.472764 -293.064946)
		(width 0.0889)
		(layer "In4.Cu")
		(net "M_D_CPU1_SB_DQ<29>")
	)
	(arc
		(start 89.334086 -293.038784)
		(mid 89.52103 -293.089039)
		(end 89.707974 -293.038784)
		(width 0.0889)
		(layer "In4.Cu")
		(net "M_D_CPU1_SB_DQ<29>")
	)
	(arc
		(start 90.273886 -293.038784)
		(mid 90.456137 -293.089134)
		(end 90.639646 -293.04361)
		(width 0.0889)
		(layer "In4.Cu")
		(net "M_D_CPU1_SB_DQ<29>")
	)
	(arc
		(start 88.402414 -293.04361)
		(mid 88.585922 -293.089104)
		(end 88.768174 -293.038784)
		(width 0.0889)
		(layer "In4.Cu")
		(net "M_D_CPU1_SB_DQ<29>")
	)
	(arc
		(start 84.068158 -293.038784)
		(mid 84.351114 -292.962607)
		(end 84.63407 -293.038784)
		(width 0.0889)
		(layer "In4.Cu")
		(net "M_D_CPU1_SB_DQ<29>")
	)
	(arc
		(start 80.495648 -294.336216)
		(mid 80.560163 -294.073997)
		(end 80.73898 -293.87165)
		(width 0.0889)
		(layer "In4.Cu")
		(net "M_D_CPU1_SB_DQ<29>")
	)
	(arc
		(start 85.57387 -293.038784)
		(mid 85.756121 -293.089134)
		(end 85.93963 -293.04361)
		(width 0.0889)
		(layer "In4.Cu")
		(net "M_D_CPU1_SB_DQ<29>")
	)
	(arc
		(start 91.21394 -293.038784)
		(mid 91.396191 -293.089134)
		(end 91.5797 -293.04361)
		(width 0.0889)
		(layer "In4.Cu")
		(net "M_D_CPU1_SB_DQ<29>")
	)
	(arc
		(start 80.026002 -295.146222)
		(mid 80.091238 -294.882631)
		(end 80.271874 -294.679878)
		(width 0.0889)
		(layer "In4.Cu")
		(net "M_D_CPU1_SB_DQ<29>")
	)
	(arc
		(start 82.18805 -293.038784)
		(mid 82.471006 -292.962607)
		(end 82.753962 -293.038784)
		(width 0.0889)
		(layer "In4.Cu")
		(net "M_D_CPU1_SB_DQ<29>")
	)
	(arc
		(start 88.768174 -293.038784)
		(mid 89.05113 -292.962607)
		(end 89.334086 -293.038784)
		(width 0.0889)
		(layer "In4.Cu")
		(net "M_D_CPU1_SB_DQ<29>")
	)
	(arc
		(start 84.63407 -293.038784)
		(mid 84.821014 -293.089039)
		(end 85.007958 -293.038784)
		(width 0.0889)
		(layer "In4.Cu")
		(net "M_D_CPU1_SB_DQ<29>")
	)
	(arc
		(start 80.965802 -293.52621)
		(mid 81.031038 -293.262619)
		(end 81.211674 -293.059866)
		(width 0.0889)
		(layer "In4.Cu")
		(net "M_D_CPU1_SB_DQ<29>")
	)
	(arc
		(start 79.040482 -296.407586)
		(mid 79.142947 -296.394018)
		(end 79.238348 -296.354246)
		(width 0.0889)
		(layer "In4.Cu")
		(net "M_D_CPU1_SB_DQ<29>")
	)
	(arc
		(start 90.648028 -293.038784)
		(mid 90.930984 -292.962607)
		(end 91.21394 -293.038784)
		(width 0.0889)
		(layer "In4.Cu")
		(net "M_D_CPU1_SB_DQ<29>")
	)
	(arc
		(start 79.555848 -295.956228)
		(mid 79.620363 -295.694009)
		(end 79.79918 -295.491662)
		(width 0.0889)
		(layer "In4.Cu")
		(net "M_D_CPU1_SB_DQ<29>")
	)
	(arc
		(start 80.338676 -294.641016)
		(mid 80.454103 -294.50764)
		(end 80.495648 -294.336216)
		(width 0.0889)
		(layer "In4.Cu")
		(net "M_D_CPU1_SB_DQ<29>")
	)
	(arc
		(start 87.82812 -293.038784)
		(mid 88.111076 -292.962607)
		(end 88.394032 -293.038784)
		(width 0.0889)
		(layer "In4.Cu")
		(net "M_D_CPU1_SB_DQ<29>")
	)
	(arc
		(start 85.007958 -293.038784)
		(mid 85.290914 -292.962607)
		(end 85.57387 -293.038784)
		(width 0.0889)
		(layer "In4.Cu")
		(net "M_D_CPU1_SB_DQ<29>")
	)
	(segment
		(start 91.397836 -291.64026)
		(end 90.930984 -291.906198)
		(width 0.10668)
		(layer "F.Cu")
		(net "M_D_CPU1_SB_DQ<28>")
	)
	(segment
		(start 43.299126 -315.129164)
		(end 43.529758 -315.129164)
		(width 0.14478)
		(layer "In4.Cu")
		(net "M_D_CPU1_SB_DQ<28>")
	)
	(segment
		(start 46.18101 -316.221364)
		(end 46.482254 -315.92012)
		(width 0.14478)
		(layer "In4.Cu")
		(net "M_D_CPU1_SB_DQ<28>")
	)
	(segment
		(start 85.10397 -292.228778)
		(end 85.112352 -292.233604)
		(width 0.0889)
		(layer "In4.Cu")
		(net "M_D_CPU1_SB_DQ<28>")
	)
	(segment
		(start 77.700886 -296.041064)
		(end 77.84211 -295.89984)
		(width 0.0889)
		(layer "In4.Cu")
		(net "M_D_CPU1_SB_DQ<28>")
	)
	(segment
		(start 55.091838 -316.097158)
		(end 55.254652 -316.259972)
		(width 0.14478)
		(layer "In4.Cu")
		(net "M_D_CPU1_SB_DQ<28>")
	)
	(segment
		(start 53.260244 -316.259972)
		(end 53.423058 -316.097158)
		(width 0.14478)
		(layer "In4.Cu")
		(net "M_D_CPU1_SB_DQ<28>")
	)
	(segment
		(start 53.979318 -316.097158)
		(end 54.142132 -316.259972)
		(width 0.14478)
		(layer "In4.Cu")
		(net "M_D_CPU1_SB_DQ<28>")
	)
	(segment
		(start 53.423058 -316.097158)
		(end 53.423058 -315.723778)
		(width 0.14478)
		(layer "In4.Cu")
		(net "M_D_CPU1_SB_DQ<28>")
	)
	(segment
		(start 45.935646 -316.221364)
		(end 46.18101 -316.221364)
		(width 0.14478)
		(layer "In4.Cu")
		(net "M_D_CPU1_SB_DQ<28>")
	)
	(segment
		(start 45.379386 -315.910468)
		(end 45.62475 -315.910468)
		(width 0.14478)
		(layer "In4.Cu")
		(net "M_D_CPU1_SB_DQ<28>")
	)
	(segment
		(start 53.979318 -315.723778)
		(end 53.979318 -316.097158)
		(width 0.14478)
		(layer "In4.Cu")
		(net "M_D_CPU1_SB_DQ<28>")
	)
	(segment
		(start 57.32018 -316.221364)
		(end 57.631076 -315.910468)
		(width 0.14478)
		(layer "In4.Cu")
		(net "M_D_CPU1_SB_DQ<28>")
	)
	(segment
		(start 53.423058 -315.723778)
		(end 53.585872 -315.560964)
		(width 0.14478)
		(layer "In4.Cu")
		(net "M_D_CPU1_SB_DQ<28>")
	)
	(segment
		(start 50.209958 -315.910468)
		(end 50.455322 -315.910468)
		(width 0.14478)
		(layer "In4.Cu")
		(net "M_D_CPU1_SB_DQ<28>")
	)
	(segment
		(start 78.139544 -295.181782)
		(end 78.139544 -295.146222)
		(width 0.0889)
		(layer "In4.Cu")
		(net "M_D_CPU1_SB_DQ<28>")
	)
	(segment
		(start 43.529758 -315.129164)
		(end 43.692572 -315.291978)
		(width 0.14478)
		(layer "In4.Cu")
		(net "M_D_CPU1_SB_DQ<28>")
	)
	(segment
		(start 47.048166 -316.221364)
		(end 47.29353 -316.221364)
		(width 0.14478)
		(layer "In4.Cu")
		(net "M_D_CPU1_SB_DQ<28>")
	)
	(segment
		(start 41.253918 -316.221364)
		(end 41.564814 -315.910468)
		(width 0.14478)
		(layer "In4.Cu")
		(net "M_D_CPU1_SB_DQ<28>")
	)
	(segment
		(start 43.855386 -315.910468)
		(end 44.51223 -315.910468)
		(width 0.14478)
		(layer "In4.Cu")
		(net "M_D_CPU1_SB_DQ<28>")
	)
	(segment
		(start 39.328852 -315.92012)
		(end 40.70731 -315.92012)
		(width 0.14478)
		(layer "In4.Cu")
		(net "M_D_CPU1_SB_DQ<28>")
	)
	(segment
		(start 46.482254 -315.92012)
		(end 46.746922 -315.92012)
		(width 0.14478)
		(layer "In4.Cu")
		(net "M_D_CPU1_SB_DQ<28>")
	)
	(segment
		(start 56.76392 -315.910468)
		(end 57.074816 -316.221364)
		(width 0.14478)
		(layer "In4.Cu")
		(net "M_D_CPU1_SB_DQ<28>")
	)
	(segment
		(start 54.698392 -315.560964)
		(end 54.929024 -315.560964)
		(width 0.14478)
		(layer "In4.Cu")
		(net "M_D_CPU1_SB_DQ<28>")
	)
	(segment
		(start 48.541178 -316.221364)
		(end 48.786542 -316.221364)
		(width 0.14478)
		(layer "In4.Cu")
		(net "M_D_CPU1_SB_DQ<28>")
	)
	(segment
		(start 54.929024 -315.560964)
		(end 55.091838 -315.723778)
		(width 0.14478)
		(layer "In4.Cu")
		(net "M_D_CPU1_SB_DQ<28>")
	)
	(segment
		(start 49.899062 -316.221364)
		(end 50.209958 -315.910468)
		(width 0.14478)
		(layer "In4.Cu")
		(net "M_D_CPU1_SB_DQ<28>")
	)
	(segment
		(start 58.4327 -316.221364)
		(end 58.743596 -315.910468)
		(width 0.14478)
		(layer "In4.Cu")
		(net "M_D_CPU1_SB_DQ<28>")
	)
	(segment
		(start 55.648098 -315.723778)
		(end 55.810912 -315.560964)
		(width 0.14478)
		(layer "In4.Cu")
		(net "M_D_CPU1_SB_DQ<28>")
	)
	(segment
		(start 44.51223 -315.910468)
		(end 44.823126 -316.221364)
		(width 0.14478)
		(layer "In4.Cu")
		(net "M_D_CPU1_SB_DQ<28>")
	)
	(segment
		(start 52.703984 -315.560964)
		(end 52.866798 -315.723778)
		(width 0.14478)
		(layer "In4.Cu")
		(net "M_D_CPU1_SB_DQ<28>")
	)
	(segment
		(start 49.097438 -315.910468)
		(end 49.342802 -315.910468)
		(width 0.14478)
		(layer "In4.Cu")
		(net "M_D_CPU1_SB_DQ<28>")
	)
	(segment
		(start 55.485284 -316.259972)
		(end 55.648098 -316.097158)
		(width 0.14478)
		(layer "In4.Cu")
		(net "M_D_CPU1_SB_DQ<28>")
	)
	(segment
		(start 52.866798 -316.097158)
		(end 53.029612 -316.259972)
		(width 0.14478)
		(layer "In4.Cu")
		(net "M_D_CPU1_SB_DQ<28>")
	)
	(segment
		(start 78.897988 -293.84879)
		(end 78.929738 -293.830502)
		(width 0.0889)
		(layer "In4.Cu")
		(net "M_D_CPU1_SB_DQ<28>")
	)
	(segment
		(start 79.368142 -293.038784)
		(end 79.398622 -293.021004)
		(width 0.0889)
		(layer "In4.Cu")
		(net "M_D_CPU1_SB_DQ<28>")
	)
	(segment
		(start 54.142132 -316.259972)
		(end 54.372764 -316.259972)
		(width 0.14478)
		(layer "In4.Cu")
		(net "M_D_CPU1_SB_DQ<28>")
	)
	(segment
		(start 45.62475 -315.910468)
		(end 45.935646 -316.221364)
		(width 0.14478)
		(layer "In4.Cu")
		(net "M_D_CPU1_SB_DQ<28>")
	)
	(segment
		(start 43.692572 -315.747654)
		(end 43.855386 -315.910468)
		(width 0.14478)
		(layer "In4.Cu")
		(net "M_D_CPU1_SB_DQ<28>")
	)
	(segment
		(start 55.091838 -315.723778)
		(end 55.091838 -316.097158)
		(width 0.14478)
		(layer "In4.Cu")
		(net "M_D_CPU1_SB_DQ<28>")
	)
	(segment
		(start 56.041544 -315.560964)
		(end 56.391048 -315.910468)
		(width 0.14478)
		(layer "In4.Cu")
		(net "M_D_CPU1_SB_DQ<28>")
	)
	(segment
		(start 38.782244 -316.221364)
		(end 39.027608 -316.221364)
		(width 0.14478)
		(layer "In4.Cu")
		(net "M_D_CPU1_SB_DQ<28>")
	)
	(segment
		(start 47.29353 -316.221364)
		(end 47.594774 -315.92012)
		(width 0.14478)
		(layer "In4.Cu")
		(net "M_D_CPU1_SB_DQ<28>")
	)
	(segment
		(start 57.074816 -316.221364)
		(end 57.32018 -316.221364)
		(width 0.14478)
		(layer "In4.Cu")
		(net "M_D_CPU1_SB_DQ<28>")
	)
	(segment
		(start 46.746922 -315.92012)
		(end 47.048166 -316.221364)
		(width 0.14478)
		(layer "In4.Cu")
		(net "M_D_CPU1_SB_DQ<28>")
	)
	(segment
		(start 44.823126 -316.221364)
		(end 45.06849 -316.221364)
		(width 0.14478)
		(layer "In4.Cu")
		(net "M_D_CPU1_SB_DQ<28>")
	)
	(segment
		(start 40.70731 -315.92012)
		(end 41.008554 -316.221364)
		(width 0.14478)
		(layer "In4.Cu")
		(net "M_D_CPU1_SB_DQ<28>")
	)
	(segment
		(start 53.029612 -316.259972)
		(end 53.260244 -316.259972)
		(width 0.14478)
		(layer "In4.Cu")
		(net "M_D_CPU1_SB_DQ<28>")
	)
	(segment
		(start 53.585872 -315.560964)
		(end 53.816504 -315.560964)
		(width 0.14478)
		(layer "In4.Cu")
		(net "M_D_CPU1_SB_DQ<28>")
	)
	(segment
		(start 58.187336 -316.221364)
		(end 58.4327 -316.221364)
		(width 0.14478)
		(layer "In4.Cu")
		(net "M_D_CPU1_SB_DQ<28>")
	)
	(segment
		(start 81.344008 -292.228778)
		(end 81.35239 -292.233604)
		(width 0.0889)
		(layer "In4.Cu")
		(net "M_D_CPU1_SB_DQ<28>")
	)
	(segment
		(start 41.008554 -316.221364)
		(end 41.253918 -316.221364)
		(width 0.14478)
		(layer "In4.Cu")
		(net "M_D_CPU1_SB_DQ<28>")
	)
	(segment
		(start 55.810912 -315.560964)
		(end 56.041544 -315.560964)
		(width 0.14478)
		(layer "In4.Cu")
		(net "M_D_CPU1_SB_DQ<28>")
	)
	(segment
		(start 51.322478 -315.910468)
		(end 52.123848 -315.910468)
		(width 0.14478)
		(layer "In4.Cu")
		(net "M_D_CPU1_SB_DQ<28>")
	)
	(segment
		(start 57.87644 -315.910468)
		(end 58.187336 -316.221364)
		(width 0.14478)
		(layer "In4.Cu")
		(net "M_D_CPU1_SB_DQ<28>")
	)
	(segment
		(start 79.798926 -292.251638)
		(end 79.838042 -292.228778)
		(width 0.0889)
		(layer "In4.Cu")
		(net "M_D_CPU1_SB_DQ<28>")
	)
	(segment
		(start 52.473352 -315.560964)
		(end 52.703984 -315.560964)
		(width 0.14478)
		(layer "In4.Cu")
		(net "M_D_CPU1_SB_DQ<28>")
	)
	(segment
		(start 43.136312 -315.291978)
		(end 43.299126 -315.129164)
		(width 0.14478)
		(layer "In4.Cu")
		(net "M_D_CPU1_SB_DQ<28>")
	)
	(segment
		(start 51.011582 -316.221364)
		(end 51.322478 -315.910468)
		(width 0.14478)
		(layer "In4.Cu")
		(net "M_D_CPU1_SB_DQ<28>")
	)
	(segment
		(start 86.044024 -292.228778)
		(end 86.052406 -292.233604)
		(width 0.0889)
		(layer "In4.Cu")
		(net "M_D_CPU1_SB_DQ<28>")
	)
	(segment
		(start 37.316156 -316.005464)
		(end 38.566344 -316.005464)
		(width 0.14478)
		(layer "In4.Cu")
		(net "M_D_CPU1_SB_DQ<28>")
	)
	(segment
		(start 48.786542 -316.221364)
		(end 49.097438 -315.910468)
		(width 0.14478)
		(layer "In4.Cu")
		(net "M_D_CPU1_SB_DQ<28>")
	)
	(segment
		(start 39.027608 -316.221364)
		(end 39.328852 -315.92012)
		(width 0.14478)
		(layer "In4.Cu")
		(net "M_D_CPU1_SB_DQ<28>")
	)
	(segment
		(start 89.803986 -292.228778)
		(end 89.812368 -292.233604)
		(width 0.0889)
		(layer "In4.Cu")
		(net "M_D_CPU1_SB_DQ<28>")
	)
	(segment
		(start 55.648098 -316.097158)
		(end 55.648098 -315.723778)
		(width 0.14478)
		(layer "In4.Cu")
		(net "M_D_CPU1_SB_DQ<28>")
	)
	(segment
		(start 83.589622 -292.233604)
		(end 83.598004 -292.228778)
		(width 0.0889)
		(layer "In4.Cu")
		(net "M_D_CPU1_SB_DQ<28>")
	)
	(segment
		(start 47.594774 -315.92012)
		(end 48.239934 -315.92012)
		(width 0.14478)
		(layer "In4.Cu")
		(net "M_D_CPU1_SB_DQ<28>")
	)
	(segment
		(start 42.836592 -315.910468)
		(end 43.136312 -315.610748)
		(width 0.14478)
		(layer "In4.Cu")
		(net "M_D_CPU1_SB_DQ<28>")
	)
	(segment
		(start 91.06281 -292.25494)
		(end 91.085162 -292.171628)
		(width 0.0889)
		(layer "In4.Cu")
		(net "M_D_CPU1_SB_DQ<28>")
	)
	(segment
		(start 91.085162 -292.171628)
		(end 90.930984 -291.906198)
		(width 0.0889)
		(layer "In4.Cu")
		(net "M_D_CPU1_SB_DQ<28>")
	)
	(segment
		(start 55.254652 -316.259972)
		(end 55.485284 -316.259972)
		(width 0.14478)
		(layer "In4.Cu")
		(net "M_D_CPU1_SB_DQ<28>")
	)
	(segment
		(start 84.529676 -292.233604)
		(end 84.538058 -292.228778)
		(width 0.0889)
		(layer "In4.Cu")
		(net "M_D_CPU1_SB_DQ<28>")
	)
	(segment
		(start 36.795964 -315.485272)
		(end 37.316156 -316.005464)
		(width 0.14478)
		(layer "In4.Cu")
		(net "M_D_CPU1_SB_DQ<28>")
	)
	(segment
		(start 41.564814 -315.910468)
		(end 42.836592 -315.910468)
		(width 0.14478)
		(layer "In4.Cu")
		(net "M_D_CPU1_SB_DQ<28>")
	)
	(segment
		(start 50.766218 -316.221364)
		(end 51.011582 -316.221364)
		(width 0.14478)
		(layer "In4.Cu")
		(net "M_D_CPU1_SB_DQ<28>")
	)
	(segment
		(start 80.777842 -292.228778)
		(end 80.778096 -292.228778)
		(width 0.0889)
		(layer "In4.Cu")
		(net "M_D_CPU1_SB_DQ<28>")
	)
	(segment
		(start 54.535578 -316.097158)
		(end 54.535578 -315.723778)
		(width 0.14478)
		(layer "In4.Cu")
		(net "M_D_CPU1_SB_DQ<28>")
	)
	(segment
		(start 60.1853 -315.910468)
		(end 75.274424 -300.821344)
		(width 0.14478)
		(layer "In4.Cu")
		(net "M_D_CPU1_SB_DQ<28>")
	)
	(segment
		(start 48.239934 -315.92012)
		(end 48.541178 -316.221364)
		(width 0.14478)
		(layer "In4.Cu")
		(net "M_D_CPU1_SB_DQ<28>")
	)
	(segment
		(start 38.566344 -316.005464)
		(end 38.782244 -316.221364)
		(width 0.14478)
		(layer "In4.Cu")
		(net "M_D_CPU1_SB_DQ<28>")
	)
	(segment
		(start 43.136312 -315.610748)
		(end 43.136312 -315.291978)
		(width 0.14478)
		(layer "In4.Cu")
		(net "M_D_CPU1_SB_DQ<28>")
	)
	(segment
		(start 49.342802 -315.910468)
		(end 49.653698 -316.221364)
		(width 0.14478)
		(layer "In4.Cu")
		(net "M_D_CPU1_SB_DQ<28>")
	)
	(segment
		(start 78.417166 -294.664892)
		(end 78.458568 -294.641016)
		(width 0.0889)
		(layer "In4.Cu")
		(net "M_D_CPU1_SB_DQ<28>")
	)
	(segment
		(start 54.535578 -315.723778)
		(end 54.698392 -315.560964)
		(width 0.14478)
		(layer "In4.Cu")
		(net "M_D_CPU1_SB_DQ<28>")
	)
	(segment
		(start 75.274424 -298.467526)
		(end 77.700886 -296.041064)
		(width 0.14478)
		(layer "In4.Cu")
		(net "M_D_CPU1_SB_DQ<28>")
	)
	(segment
		(start 90.74404 -292.228778)
		(end 90.752422 -292.233604)
		(width 0.0889)
		(layer "In4.Cu")
		(net "M_D_CPU1_SB_DQ<28>")
	)
	(segment
		(start 88.289638 -292.233604)
		(end 88.29802 -292.228778)
		(width 0.0889)
		(layer "In4.Cu")
		(net "M_D_CPU1_SB_DQ<28>")
	)
	(segment
		(start 58.743596 -315.910468)
		(end 60.1853 -315.910468)
		(width 0.14478)
		(layer "In4.Cu")
		(net "M_D_CPU1_SB_DQ<28>")
	)
	(segment
		(start 53.816504 -315.560964)
		(end 53.979318 -315.723778)
		(width 0.14478)
		(layer "In4.Cu")
		(net "M_D_CPU1_SB_DQ<28>")
	)
	(segment
		(start 49.653698 -316.221364)
		(end 49.899062 -316.221364)
		(width 0.14478)
		(layer "In4.Cu")
		(net "M_D_CPU1_SB_DQ<28>")
	)
	(segment
		(start 56.391048 -315.910468)
		(end 56.76392 -315.910468)
		(width 0.14478)
		(layer "In4.Cu")
		(net "M_D_CPU1_SB_DQ<28>")
	)
	(segment
		(start 43.692572 -315.291978)
		(end 43.692572 -315.747654)
		(width 0.14478)
		(layer "In4.Cu")
		(net "M_D_CPU1_SB_DQ<28>")
	)
	(segment
		(start 54.372764 -316.259972)
		(end 54.535578 -316.097158)
		(width 0.14478)
		(layer "In4.Cu")
		(net "M_D_CPU1_SB_DQ<28>")
	)
	(segment
		(start 50.455322 -315.910468)
		(end 50.766218 -316.221364)
		(width 0.14478)
		(layer "In4.Cu")
		(net "M_D_CPU1_SB_DQ<28>")
	)
	(segment
		(start 57.631076 -315.910468)
		(end 57.87644 -315.910468)
		(width 0.14478)
		(layer "In4.Cu")
		(net "M_D_CPU1_SB_DQ<28>")
	)
	(segment
		(start 75.274424 -300.821344)
		(end 75.274424 -298.467526)
		(width 0.14478)
		(layer "In4.Cu")
		(net "M_D_CPU1_SB_DQ<28>")
	)
	(segment
		(start 89.229692 -292.233604)
		(end 89.238074 -292.228778)
		(width 0.0889)
		(layer "In4.Cu")
		(net "M_D_CPU1_SB_DQ<28>")
	)
	(segment
		(start 45.06849 -316.221364)
		(end 45.379386 -315.910468)
		(width 0.14478)
		(layer "In4.Cu")
		(net "M_D_CPU1_SB_DQ<28>")
	)
	(segment
		(start 52.123848 -315.910468)
		(end 52.473352 -315.560964)
		(width 0.14478)
		(layer "In4.Cu")
		(net "M_D_CPU1_SB_DQ<28>")
	)
	(segment
		(start 52.866798 -315.723778)
		(end 52.866798 -316.097158)
		(width 0.14478)
		(layer "In4.Cu")
		(net "M_D_CPU1_SB_DQ<28>")
	)
	(segment
		(start 78.860142 -293.870634)
		(end 78.897988 -293.84879)
		(width 0.0889)
		(layer "In4.Cu")
		(net "M_D_CPU1_SB_DQ<28>")
	)
	(segment
		(start 79.329026 -293.061644)
		(end 79.368142 -293.038784)
		(width 0.0889)
		(layer "In4.Cu")
		(net "M_D_CPU1_SB_DQ<28>")
	)
	(arc
		(start 82.65795 -292.228778)
		(mid 82.940906 -292.152601)
		(end 83.223862 -292.228778)
		(width 0.0889)
		(layer "In4.Cu")
		(net "M_D_CPU1_SB_DQ<28>")
	)
	(arc
		(start 78.458568 -294.641016)
		(mid 78.573995 -294.50764)
		(end 78.61554 -294.336216)
		(width 0.0889)
		(layer "In4.Cu")
		(net "M_D_CPU1_SB_DQ<28>")
	)
	(arc
		(start 79.085694 -293.52621)
		(mid 79.150209 -293.263991)
		(end 79.329026 -293.061644)
		(width 0.0889)
		(layer "In4.Cu")
		(net "M_D_CPU1_SB_DQ<28>")
	)
	(arc
		(start 78.139544 -295.146222)
		(mid 78.213929 -294.868402)
		(end 78.417166 -294.664892)
		(width 0.0889)
		(layer "In4.Cu")
		(net "M_D_CPU1_SB_DQ<28>")
	)
	(arc
		(start 82.284062 -292.228778)
		(mid 82.471006 -292.279033)
		(end 82.65795 -292.228778)
		(width 0.0889)
		(layer "In4.Cu")
		(net "M_D_CPU1_SB_DQ<28>")
	)
	(arc
		(start 89.812368 -292.233604)
		(mid 89.995876 -292.279098)
		(end 90.178128 -292.228778)
		(width 0.0889)
		(layer "In4.Cu")
		(net "M_D_CPU1_SB_DQ<28>")
	)
	(arc
		(start 79.838042 -292.228778)
		(mid 80.120998 -292.152601)
		(end 80.403954 -292.228778)
		(width 0.0889)
		(layer "In4.Cu")
		(net "M_D_CPU1_SB_DQ<28>")
	)
	(arc
		(start 85.478112 -292.228778)
		(mid 85.761068 -292.152601)
		(end 86.044024 -292.228778)
		(width 0.0889)
		(layer "In4.Cu")
		(net "M_D_CPU1_SB_DQ<28>")
	)
	(arc
		(start 78.929738 -293.830502)
		(mid 79.044414 -293.697168)
		(end 79.085694 -293.52621)
		(width 0.0889)
		(layer "In4.Cu")
		(net "M_D_CPU1_SB_DQ<28>")
	)
	(arc
		(start 85.112352 -292.233604)
		(mid 85.29586 -292.279098)
		(end 85.478112 -292.228778)
		(width 0.0889)
		(layer "In4.Cu")
		(net "M_D_CPU1_SB_DQ<28>")
	)
	(arc
		(start 81.71815 -292.228778)
		(mid 82.001106 -292.152601)
		(end 82.284062 -292.228778)
		(width 0.0889)
		(layer "In4.Cu")
		(net "M_D_CPU1_SB_DQ<28>")
	)
	(arc
		(start 88.29802 -292.228778)
		(mid 88.580976 -292.152601)
		(end 88.863932 -292.228778)
		(width 0.0889)
		(layer "In4.Cu")
		(net "M_D_CPU1_SB_DQ<28>")
	)
	(arc
		(start 86.984078 -292.228778)
		(mid 87.171022 -292.279033)
		(end 87.357966 -292.228778)
		(width 0.0889)
		(layer "In4.Cu")
		(net "M_D_CPU1_SB_DQ<28>")
	)
	(arc
		(start 81.35239 -292.233604)
		(mid 81.535898 -292.279098)
		(end 81.71815 -292.228778)
		(width 0.0889)
		(layer "In4.Cu")
		(net "M_D_CPU1_SB_DQ<28>")
	)
	(arc
		(start 79.555594 -292.716204)
		(mid 79.620109 -292.453985)
		(end 79.798926 -292.251638)
		(width 0.0889)
		(layer "In4.Cu")
		(net "M_D_CPU1_SB_DQ<28>")
	)
	(arc
		(start 84.163916 -292.228778)
		(mid 84.346167 -292.279128)
		(end 84.529676 -292.233604)
		(width 0.0889)
		(layer "In4.Cu")
		(net "M_D_CPU1_SB_DQ<28>")
	)
	(arc
		(start 77.84211 -295.89984)
		(mid 78.06224 -295.570392)
		(end 78.139544 -295.181782)
		(width 0.0889)
		(layer "In4.Cu")
		(net "M_D_CPU1_SB_DQ<28>")
	)
	(arc
		(start 84.538058 -292.228778)
		(mid 84.821014 -292.152601)
		(end 85.10397 -292.228778)
		(width 0.0889)
		(layer "In4.Cu")
		(net "M_D_CPU1_SB_DQ<28>")
	)
	(arc
		(start 83.223862 -292.228778)
		(mid 83.406113 -292.279128)
		(end 83.589622 -292.233604)
		(width 0.0889)
		(layer "In4.Cu")
		(net "M_D_CPU1_SB_DQ<28>")
	)
	(arc
		(start 78.61554 -294.336216)
		(mid 78.680412 -294.073253)
		(end 78.860142 -293.870634)
		(width 0.0889)
		(layer "In4.Cu")
		(net "M_D_CPU1_SB_DQ<28>")
	)
	(arc
		(start 88.863932 -292.228778)
		(mid 89.046183 -292.279128)
		(end 89.229692 -292.233604)
		(width 0.0889)
		(layer "In4.Cu")
		(net "M_D_CPU1_SB_DQ<28>")
	)
	(arc
		(start 90.752422 -292.233604)
		(mid 90.905292 -292.278245)
		(end 91.06281 -292.25494)
		(width 0.0889)
		(layer "In4.Cu")
		(net "M_D_CPU1_SB_DQ<28>")
	)
	(arc
		(start 79.398622 -293.021004)
		(mid 79.514049 -292.887628)
		(end 79.555594 -292.716204)
		(width 0.0889)
		(layer "In4.Cu")
		(net "M_D_CPU1_SB_DQ<28>")
	)
	(arc
		(start 86.052406 -292.233604)
		(mid 86.235914 -292.279098)
		(end 86.418166 -292.228778)
		(width 0.0889)
		(layer "In4.Cu")
		(net "M_D_CPU1_SB_DQ<28>")
	)
	(arc
		(start 83.598004 -292.228778)
		(mid 83.88096 -292.152601)
		(end 84.163916 -292.228778)
		(width 0.0889)
		(layer "In4.Cu")
		(net "M_D_CPU1_SB_DQ<28>")
	)
	(arc
		(start 86.418166 -292.228778)
		(mid 86.701122 -292.152601)
		(end 86.984078 -292.228778)
		(width 0.0889)
		(layer "In4.Cu")
		(net "M_D_CPU1_SB_DQ<28>")
	)
	(arc
		(start 90.178128 -292.228778)
		(mid 90.461084 -292.152601)
		(end 90.74404 -292.228778)
		(width 0.0889)
		(layer "In4.Cu")
		(net "M_D_CPU1_SB_DQ<28>")
	)
	(arc
		(start 87.923878 -292.228778)
		(mid 88.106129 -292.279128)
		(end 88.289638 -292.233604)
		(width 0.0889)
		(layer "In4.Cu")
		(net "M_D_CPU1_SB_DQ<28>")
	)
	(arc
		(start 80.778096 -292.228778)
		(mid 81.061052 -292.152601)
		(end 81.344008 -292.228778)
		(width 0.0889)
		(layer "In4.Cu")
		(net "M_D_CPU1_SB_DQ<28>")
	)
	(arc
		(start 89.238074 -292.228778)
		(mid 89.52103 -292.152601)
		(end 89.803986 -292.228778)
		(width 0.0889)
		(layer "In4.Cu")
		(net "M_D_CPU1_SB_DQ<28>")
	)
	(arc
		(start 80.403954 -292.228778)
		(mid 80.590898 -292.279102)
		(end 80.777842 -292.228778)
		(width 0.0889)
		(layer "In4.Cu")
		(net "M_D_CPU1_SB_DQ<28>")
	)
	(arc
		(start 87.357966 -292.228778)
		(mid 87.640922 -292.152601)
		(end 87.923878 -292.228778)
		(width 0.0889)
		(layer "In4.Cu")
		(net "M_D_CPU1_SB_DQ<28>")
	)
	(segment
		(start 93.277944 -290.020248)
		(end 92.811092 -290.286186)
		(width 0.10668)
		(layer "F.Cu")
		(net "M_D_CPU1_SB_DQ<27>")
	)
	(segment
		(start 59.954922 -311.660286)
		(end 72.861678 -298.75353)
		(width 0.14478)
		(layer "In4.Cu")
		(net "M_D_CPU1_SB_DQ<27>")
	)
	(segment
		(start 76.968096 -292.026086)
		(end 77.283056 -292.026086)
		(width 0.0889)
		(layer "In4.Cu")
		(net "M_D_CPU1_SB_DQ<27>")
	)
	(segment
		(start 78.897734 -289.96386)
		(end 78.903322 -289.967162)
		(width 0.0889)
		(layer "In4.Cu")
		(net "M_D_CPU1_SB_DQ<27>")
	)
	(segment
		(start 83.589622 -289.95878)
		(end 83.598004 -289.963606)
		(width 0.0889)
		(layer "In4.Cu")
		(net "M_D_CPU1_SB_DQ<27>")
	)
	(segment
		(start 78.879446 -289.953446)
		(end 78.897734 -289.96386)
		(width 0.0889)
		(layer "In4.Cu")
		(net "M_D_CPU1_SB_DQ<27>")
	)
	(segment
		(start 85.10397 -289.963606)
		(end 85.112352 -289.95878)
		(width 0.0889)
		(layer "In4.Cu")
		(net "M_D_CPU1_SB_DQ<27>")
	)
	(segment
		(start 42.711116 -311.650634)
		(end 45.609256 -311.650634)
		(width 0.14478)
		(layer "In4.Cu")
		(net "M_D_CPU1_SB_DQ<27>")
	)
	(segment
		(start 79.463138 -289.963606)
		(end 79.474822 -289.956748)
		(width 0.0889)
		(layer "In4.Cu")
		(net "M_D_CPU1_SB_DQ<27>")
	)
	(segment
		(start 54.277768 -312.114946)
		(end 56.935116 -312.114946)
		(width 0.14478)
		(layer "In4.Cu")
		(net "M_D_CPU1_SB_DQ<27>")
	)
	(segment
		(start 88.289638 -289.95878)
		(end 88.29802 -289.963606)
		(width 0.0889)
		(layer "In4.Cu")
		(net "M_D_CPU1_SB_DQ<27>")
	)
	(segment
		(start 45.609256 -311.650634)
		(end 46.45914 -312.500518)
		(width 0.14478)
		(layer "In4.Cu")
		(net "M_D_CPU1_SB_DQ<27>")
	)
	(segment
		(start 53.813456 -311.650634)
		(end 54.277768 -312.114946)
		(width 0.14478)
		(layer "In4.Cu")
		(net "M_D_CPU1_SB_DQ<27>")
	)
	(segment
		(start 86.044024 -289.963606)
		(end 86.052406 -289.95878)
		(width 0.0889)
		(layer "In4.Cu")
		(net "M_D_CPU1_SB_DQ<27>")
	)
	(segment
		(start 76.72705 -292.267132)
		(end 76.968096 -292.026086)
		(width 0.0889)
		(layer "In4.Cu")
		(net "M_D_CPU1_SB_DQ<27>")
	)
	(segment
		(start 78.30439 -290.182808)
		(end 78.523592 -289.963606)
		(width 0.0889)
		(layer "In4.Cu")
		(net "M_D_CPU1_SB_DQ<27>")
	)
	(segment
		(start 49.881028 -311.650634)
		(end 53.813456 -311.650634)
		(width 0.14478)
		(layer "In4.Cu")
		(net "M_D_CPU1_SB_DQ<27>")
	)
	(segment
		(start 89.803986 -289.963606)
		(end 89.812368 -289.95878)
		(width 0.0889)
		(layer "In4.Cu")
		(net "M_D_CPU1_SB_DQ<27>")
	)
	(segment
		(start 78.30439 -291.004752)
		(end 78.30439 -290.182808)
		(width 0.0889)
		(layer "In4.Cu")
		(net "M_D_CPU1_SB_DQ<27>")
	)
	(segment
		(start 76.72705 -293.100506)
		(end 76.72705 -292.267132)
		(width 0.0889)
		(layer "In4.Cu")
		(net "M_D_CPU1_SB_DQ<27>")
	)
	(segment
		(start 92.560648 -289.995356)
		(end 92.656914 -290.020756)
		(width 0.0889)
		(layer "In4.Cu")
		(net "M_D_CPU1_SB_DQ<27>")
	)
	(segment
		(start 72.861678 -298.75353)
		(end 72.861678 -297.542712)
		(width 0.14478)
		(layer "In4.Cu")
		(net "M_D_CPU1_SB_DQ<27>")
	)
	(segment
		(start 32.695896 -312.085228)
		(end 33.111186 -312.500518)
		(width 0.14478)
		(layer "In4.Cu")
		(net "M_D_CPU1_SB_DQ<27>")
	)
	(segment
		(start 81.344008 -289.963606)
		(end 81.35239 -289.95878)
		(width 0.0889)
		(layer "In4.Cu")
		(net "M_D_CPU1_SB_DQ<27>")
	)
	(segment
		(start 80.389222 -289.972242)
		(end 80.403954 -289.963606)
		(width 0.0889)
		(layer "In4.Cu")
		(net "M_D_CPU1_SB_DQ<27>")
	)
	(segment
		(start 57.389776 -311.660286)
		(end 59.954922 -311.660286)
		(width 0.14478)
		(layer "In4.Cu")
		(net "M_D_CPU1_SB_DQ<27>")
	)
	(segment
		(start 33.111186 -312.500518)
		(end 41.861232 -312.500518)
		(width 0.14478)
		(layer "In4.Cu")
		(net "M_D_CPU1_SB_DQ<27>")
	)
	(segment
		(start 92.656914 -290.020756)
		(end 92.811092 -290.286186)
		(width 0.0889)
		(layer "In4.Cu")
		(net "M_D_CPU1_SB_DQ<27>")
	)
	(segment
		(start 80.769714 -289.95878)
		(end 80.778096 -289.963606)
		(width 0.0889)
		(layer "In4.Cu")
		(net "M_D_CPU1_SB_DQ<27>")
	)
	(segment
		(start 75.960986 -294.443404)
		(end 76.16825 -294.23614)
		(width 0.0889)
		(layer "In4.Cu")
		(net "M_D_CPU1_SB_DQ<27>")
	)
	(segment
		(start 89.229692 -289.95878)
		(end 89.238074 -289.963606)
		(width 0.0889)
		(layer "In4.Cu")
		(net "M_D_CPU1_SB_DQ<27>")
	)
	(segment
		(start 76.16825 -293.659306)
		(end 76.72705 -293.100506)
		(width 0.0889)
		(layer "In4.Cu")
		(net "M_D_CPU1_SB_DQ<27>")
	)
	(segment
		(start 41.861232 -312.500518)
		(end 42.711116 -311.650634)
		(width 0.14478)
		(layer "In4.Cu")
		(net "M_D_CPU1_SB_DQ<27>")
	)
	(segment
		(start 77.283056 -292.026086)
		(end 78.30439 -291.004752)
		(width 0.0889)
		(layer "In4.Cu")
		(net "M_D_CPU1_SB_DQ<27>")
	)
	(segment
		(start 84.529676 -289.95878)
		(end 84.538058 -289.963606)
		(width 0.0889)
		(layer "In4.Cu")
		(net "M_D_CPU1_SB_DQ<27>")
	)
	(segment
		(start 46.45914 -312.500518)
		(end 49.031144 -312.500518)
		(width 0.14478)
		(layer "In4.Cu")
		(net "M_D_CPU1_SB_DQ<27>")
	)
	(segment
		(start 90.74404 -289.963606)
		(end 90.752422 -289.95878)
		(width 0.0889)
		(layer "In4.Cu")
		(net "M_D_CPU1_SB_DQ<27>")
	)
	(segment
		(start 76.16825 -294.23614)
		(end 76.16825 -293.659306)
		(width 0.0889)
		(layer "In4.Cu")
		(net "M_D_CPU1_SB_DQ<27>")
	)
	(segment
		(start 72.861678 -297.542712)
		(end 75.960986 -294.443404)
		(width 0.14478)
		(layer "In4.Cu")
		(net "M_D_CPU1_SB_DQ<27>")
	)
	(segment
		(start 49.031144 -312.500518)
		(end 49.881028 -311.650634)
		(width 0.14478)
		(layer "In4.Cu")
		(net "M_D_CPU1_SB_DQ<27>")
	)
	(segment
		(start 56.935116 -312.114946)
		(end 57.389776 -311.660286)
		(width 0.14478)
		(layer "In4.Cu")
		(net "M_D_CPU1_SB_DQ<27>")
	)
	(arc
		(start 80.403954 -289.963606)
		(mid 80.586205 -289.913256)
		(end 80.769714 -289.95878)
		(width 0.0889)
		(layer "In4.Cu")
		(net "M_D_CPU1_SB_DQ<27>")
	)
	(arc
		(start 81.35239 -289.95878)
		(mid 81.535898 -289.913286)
		(end 81.71815 -289.963606)
		(width 0.0889)
		(layer "In4.Cu")
		(net "M_D_CPU1_SB_DQ<27>")
	)
	(arc
		(start 86.984078 -289.963606)
		(mid 87.171022 -289.913351)
		(end 87.357966 -289.963606)
		(width 0.0889)
		(layer "In4.Cu")
		(net "M_D_CPU1_SB_DQ<27>")
	)
	(arc
		(start 90.178128 -289.963606)
		(mid 90.461084 -290.039783)
		(end 90.74404 -289.963606)
		(width 0.0889)
		(layer "In4.Cu")
		(net "M_D_CPU1_SB_DQ<27>")
	)
	(arc
		(start 87.923878 -289.963606)
		(mid 88.106129 -289.913256)
		(end 88.289638 -289.95878)
		(width 0.0889)
		(layer "In4.Cu")
		(net "M_D_CPU1_SB_DQ<27>")
	)
	(arc
		(start 85.112352 -289.95878)
		(mid 85.29586 -289.913286)
		(end 85.478112 -289.963606)
		(width 0.0889)
		(layer "In4.Cu")
		(net "M_D_CPU1_SB_DQ<27>")
	)
	(arc
		(start 81.71815 -289.963606)
		(mid 82.001106 -290.039783)
		(end 82.284062 -289.963606)
		(width 0.0889)
		(layer "In4.Cu")
		(net "M_D_CPU1_SB_DQ<27>")
	)
	(arc
		(start 83.598004 -289.963606)
		(mid 83.88096 -290.039783)
		(end 84.163916 -289.963606)
		(width 0.0889)
		(layer "In4.Cu")
		(net "M_D_CPU1_SB_DQ<27>")
	)
	(arc
		(start 86.418166 -289.963606)
		(mid 86.701122 -290.039783)
		(end 86.984078 -289.963606)
		(width 0.0889)
		(layer "In4.Cu")
		(net "M_D_CPU1_SB_DQ<27>")
	)
	(arc
		(start 82.65795 -289.963606)
		(mid 82.940906 -290.039783)
		(end 83.223862 -289.963606)
		(width 0.0889)
		(layer "In4.Cu")
		(net "M_D_CPU1_SB_DQ<27>")
	)
	(arc
		(start 91.118182 -289.963606)
		(mid 91.401138 -290.039783)
		(end 91.684094 -289.963606)
		(width 0.0889)
		(layer "In4.Cu")
		(net "M_D_CPU1_SB_DQ<27>")
	)
	(arc
		(start 86.052406 -289.95878)
		(mid 86.235914 -289.913286)
		(end 86.418166 -289.963606)
		(width 0.0889)
		(layer "In4.Cu")
		(net "M_D_CPU1_SB_DQ<27>")
	)
	(arc
		(start 89.812368 -289.95878)
		(mid 89.995876 -289.913286)
		(end 90.178128 -289.963606)
		(width 0.0889)
		(layer "In4.Cu")
		(net "M_D_CPU1_SB_DQ<27>")
	)
	(arc
		(start 78.523592 -289.963606)
		(mid 78.70022 -289.913373)
		(end 78.879446 -289.953446)
		(width 0.0889)
		(layer "In4.Cu")
		(net "M_D_CPU1_SB_DQ<27>")
	)
	(arc
		(start 91.684094 -289.963606)
		(mid 91.871038 -289.913351)
		(end 92.057982 -289.963606)
		(width 0.0889)
		(layer "In4.Cu")
		(net "M_D_CPU1_SB_DQ<27>")
	)
	(arc
		(start 83.223862 -289.963606)
		(mid 83.406113 -289.913256)
		(end 83.589622 -289.95878)
		(width 0.0889)
		(layer "In4.Cu")
		(net "M_D_CPU1_SB_DQ<27>")
	)
	(arc
		(start 92.057982 -289.963606)
		(mid 92.305578 -290.038784)
		(end 92.560648 -289.995356)
		(width 0.0889)
		(layer "In4.Cu")
		(net "M_D_CPU1_SB_DQ<27>")
	)
	(arc
		(start 79.474822 -289.956748)
		(mid 79.657077 -289.913095)
		(end 79.837534 -289.963606)
		(width 0.0889)
		(layer "In4.Cu")
		(net "M_D_CPU1_SB_DQ<27>")
	)
	(arc
		(start 88.863932 -289.963606)
		(mid 89.046183 -289.913256)
		(end 89.229692 -289.95878)
		(width 0.0889)
		(layer "In4.Cu")
		(net "M_D_CPU1_SB_DQ<27>")
	)
	(arc
		(start 84.163916 -289.963606)
		(mid 84.346167 -289.913256)
		(end 84.529676 -289.95878)
		(width 0.0889)
		(layer "In4.Cu")
		(net "M_D_CPU1_SB_DQ<27>")
	)
	(arc
		(start 80.778096 -289.963606)
		(mid 81.061052 -290.039783)
		(end 81.344008 -289.963606)
		(width 0.0889)
		(layer "In4.Cu")
		(net "M_D_CPU1_SB_DQ<27>")
	)
	(arc
		(start 84.538058 -289.963606)
		(mid 84.821014 -290.039783)
		(end 85.10397 -289.963606)
		(width 0.0889)
		(layer "In4.Cu")
		(net "M_D_CPU1_SB_DQ<27>")
	)
	(arc
		(start 85.478112 -289.963606)
		(mid 85.761068 -290.039783)
		(end 86.044024 -289.963606)
		(width 0.0889)
		(layer "In4.Cu")
		(net "M_D_CPU1_SB_DQ<27>")
	)
	(arc
		(start 87.357966 -289.963606)
		(mid 87.640922 -290.039783)
		(end 87.923878 -289.963606)
		(width 0.0889)
		(layer "In4.Cu")
		(net "M_D_CPU1_SB_DQ<27>")
	)
	(arc
		(start 79.837534 -289.963606)
		(mid 80.11224 -290.03997)
		(end 80.389222 -289.972242)
		(width 0.0889)
		(layer "In4.Cu")
		(net "M_D_CPU1_SB_DQ<27>")
	)
	(arc
		(start 78.903322 -289.967162)
		(mid 79.183711 -290.039831)
		(end 79.463138 -289.963606)
		(width 0.0889)
		(layer "In4.Cu")
		(net "M_D_CPU1_SB_DQ<27>")
	)
	(arc
		(start 88.29802 -289.963606)
		(mid 88.580976 -290.039783)
		(end 88.863932 -289.963606)
		(width 0.0889)
		(layer "In4.Cu")
		(net "M_D_CPU1_SB_DQ<27>")
	)
	(arc
		(start 90.752422 -289.95878)
		(mid 90.93593 -289.913286)
		(end 91.118182 -289.963606)
		(width 0.0889)
		(layer "In4.Cu")
		(net "M_D_CPU1_SB_DQ<27>")
	)
	(arc
		(start 89.238074 -289.963606)
		(mid 89.52103 -290.039783)
		(end 89.803986 -289.963606)
		(width 0.0889)
		(layer "In4.Cu")
		(net "M_D_CPU1_SB_DQ<27>")
	)
	(arc
		(start 82.284062 -289.963606)
		(mid 82.471006 -289.913351)
		(end 82.65795 -289.963606)
		(width 0.0889)
		(layer "In4.Cu")
		(net "M_D_CPU1_SB_DQ<27>")
	)
	(segment
		(start 91.86799 -289.210242)
		(end 91.401138 -289.47618)
		(width 0.10668)
		(layer "F.Cu")
		(net "M_D_CPU1_SB_DQ<26>")
	)
	(segment
		(start 35.10026 -310.099964)
		(end 35.263074 -310.262778)
		(width 0.14478)
		(layer "In4.Cu")
		(net "M_D_CPU1_SB_DQ<26>")
	)
	(segment
		(start 34.313368 -310.810402)
		(end 34.544 -310.810402)
		(width 0.14478)
		(layer "In4.Cu")
		(net "M_D_CPU1_SB_DQ<26>")
	)
	(segment
		(start 33.594294 -310.262778)
		(end 33.757108 -310.099964)
		(width 0.14478)
		(layer "In4.Cu")
		(net "M_D_CPU1_SB_DQ<26>")
	)
	(segment
		(start 77.61859 -290.931346)
		(end 77.61859 -289.865054)
		(width 0.0889)
		(layer "In4.Cu")
		(net "M_D_CPU1_SB_DQ<26>")
	)
	(segment
		(start 90.639646 -289.148774)
		(end 90.648028 -289.1536)
		(width 0.0889)
		(layer "In4.Cu")
		(net "M_D_CPU1_SB_DQ<26>")
	)
	(segment
		(start 32.695896 -310.385206)
		(end 33.121092 -310.810402)
		(width 0.14478)
		(layer "In4.Cu")
		(net "M_D_CPU1_SB_DQ<26>")
	)
	(segment
		(start 78.993492 -289.153854)
		(end 79.01178 -289.14344)
		(width 0.0889)
		(layer "In4.Cu")
		(net "M_D_CPU1_SB_DQ<26>")
	)
	(segment
		(start 88.394032 -289.1536)
		(end 88.402414 -289.148774)
		(width 0.0889)
		(layer "In4.Cu")
		(net "M_D_CPU1_SB_DQ<26>")
	)
	(segment
		(start 56.95315 -310.810402)
		(end 57.803288 -309.960264)
		(width 0.14478)
		(layer "In4.Cu")
		(net "M_D_CPU1_SB_DQ<26>")
	)
	(segment
		(start 42.180002 -310.810402)
		(end 43.03014 -309.960264)
		(width 0.14478)
		(layer "In4.Cu")
		(net "M_D_CPU1_SB_DQ<26>")
	)
	(segment
		(start 71.962518 -296.742104)
		(end 75.931268 -292.773354)
		(width 0.14478)
		(layer "In4.Cu")
		(net "M_D_CPU1_SB_DQ<26>")
	)
	(segment
		(start 33.594294 -310.647588)
		(end 33.594294 -310.262778)
		(width 0.14478)
		(layer "In4.Cu")
		(net "M_D_CPU1_SB_DQ<26>")
	)
	(segment
		(start 34.706814 -310.262778)
		(end 34.869628 -310.099964)
		(width 0.14478)
		(layer "In4.Cu")
		(net "M_D_CPU1_SB_DQ<26>")
	)
	(segment
		(start 35.263074 -310.647588)
		(end 35.425888 -310.810402)
		(width 0.14478)
		(layer "In4.Cu")
		(net "M_D_CPU1_SB_DQ<26>")
	)
	(segment
		(start 83.694016 -289.1536)
		(end 83.702398 -289.148774)
		(width 0.0889)
		(layer "In4.Cu")
		(net "M_D_CPU1_SB_DQ<26>")
	)
	(segment
		(start 77.18171 -291.368226)
		(end 77.61859 -290.931346)
		(width 0.0889)
		(layer "In4.Cu")
		(net "M_D_CPU1_SB_DQ<26>")
	)
	(segment
		(start 79.919322 -289.162236)
		(end 79.934054 -289.1536)
		(width 0.0889)
		(layer "In4.Cu")
		(net "M_D_CPU1_SB_DQ<26>")
	)
	(segment
		(start 34.150554 -310.262778)
		(end 34.150554 -310.647588)
		(width 0.14478)
		(layer "In4.Cu")
		(net "M_D_CPU1_SB_DQ<26>")
	)
	(segment
		(start 82.753962 -289.1536)
		(end 82.762344 -289.148774)
		(width 0.0889)
		(layer "In4.Cu")
		(net "M_D_CPU1_SB_DQ<26>")
	)
	(segment
		(start 53.415692 -309.960264)
		(end 54.26583 -310.810402)
		(width 0.14478)
		(layer "In4.Cu")
		(net "M_D_CPU1_SB_DQ<26>")
	)
	(segment
		(start 60.382912 -309.960264)
		(end 71.962518 -298.380658)
		(width 0.14478)
		(layer "In4.Cu")
		(net "M_D_CPU1_SB_DQ<26>")
	)
	(segment
		(start 78.253844 -289.2298)
		(end 78.711044 -289.2298)
		(width 0.0889)
		(layer "In4.Cu")
		(net "M_D_CPU1_SB_DQ<26>")
	)
	(segment
		(start 49.43475 -310.810402)
		(end 50.284888 -309.960264)
		(width 0.14478)
		(layer "In4.Cu")
		(net "M_D_CPU1_SB_DQ<26>")
	)
	(segment
		(start 82.179668 -289.148774)
		(end 82.18805 -289.1536)
		(width 0.0889)
		(layer "In4.Cu")
		(net "M_D_CPU1_SB_DQ<26>")
	)
	(segment
		(start 33.121092 -310.810402)
		(end 33.43148 -310.810402)
		(width 0.14478)
		(layer "In4.Cu")
		(net "M_D_CPU1_SB_DQ<26>")
	)
	(segment
		(start 34.544 -310.810402)
		(end 34.706814 -310.647588)
		(width 0.14478)
		(layer "In4.Cu")
		(net "M_D_CPU1_SB_DQ<26>")
	)
	(segment
		(start 33.98774 -310.099964)
		(end 34.150554 -310.262778)
		(width 0.14478)
		(layer "In4.Cu")
		(net "M_D_CPU1_SB_DQ<26>")
	)
	(segment
		(start 50.284888 -309.960264)
		(end 53.415692 -309.960264)
		(width 0.14478)
		(layer "In4.Cu")
		(net "M_D_CPU1_SB_DQ<26>")
	)
	(segment
		(start 34.869628 -310.099964)
		(end 35.10026 -310.099964)
		(width 0.14478)
		(layer "In4.Cu")
		(net "M_D_CPU1_SB_DQ<26>")
	)
	(segment
		(start 46.34357 -310.810402)
		(end 49.43475 -310.810402)
		(width 0.14478)
		(layer "In4.Cu")
		(net "M_D_CPU1_SB_DQ<26>")
	)
	(segment
		(start 54.26583 -310.810402)
		(end 56.95315 -310.810402)
		(width 0.14478)
		(layer "In4.Cu")
		(net "M_D_CPU1_SB_DQ<26>")
	)
	(segment
		(start 35.263074 -310.262778)
		(end 35.263074 -310.647588)
		(width 0.14478)
		(layer "In4.Cu")
		(net "M_D_CPU1_SB_DQ<26>")
	)
	(segment
		(start 76.23175 -292.472872)
		(end 76.23175 -291.90442)
		(width 0.0889)
		(layer "In4.Cu")
		(net "M_D_CPU1_SB_DQ<26>")
	)
	(segment
		(start 43.03014 -309.960264)
		(end 45.493432 -309.960264)
		(width 0.14478)
		(layer "In4.Cu")
		(net "M_D_CPU1_SB_DQ<26>")
	)
	(segment
		(start 91.24696 -289.21075)
		(end 91.401138 -289.47618)
		(width 0.0889)
		(layer "In4.Cu")
		(net "M_D_CPU1_SB_DQ<26>")
	)
	(segment
		(start 91.150694 -289.18535)
		(end 91.24696 -289.21075)
		(width 0.0889)
		(layer "In4.Cu")
		(net "M_D_CPU1_SB_DQ<26>")
	)
	(segment
		(start 35.425888 -310.810402)
		(end 42.180002 -310.810402)
		(width 0.14478)
		(layer "In4.Cu")
		(net "M_D_CPU1_SB_DQ<26>")
	)
	(segment
		(start 79.934054 -289.1536)
		(end 79.942436 -289.148774)
		(width 0.0889)
		(layer "In4.Cu")
		(net "M_D_CPU1_SB_DQ<26>")
	)
	(segment
		(start 76.23175 -291.90442)
		(end 76.767944 -291.368226)
		(width 0.0889)
		(layer "In4.Cu")
		(net "M_D_CPU1_SB_DQ<26>")
	)
	(segment
		(start 33.43148 -310.810402)
		(end 33.594294 -310.647588)
		(width 0.14478)
		(layer "In4.Cu")
		(net "M_D_CPU1_SB_DQ<26>")
	)
	(segment
		(start 77.61859 -289.865054)
		(end 78.253844 -289.2298)
		(width 0.0889)
		(layer "In4.Cu")
		(net "M_D_CPU1_SB_DQ<26>")
	)
	(segment
		(start 85.93963 -289.148774)
		(end 85.948012 -289.1536)
		(width 0.0889)
		(layer "In4.Cu")
		(net "M_D_CPU1_SB_DQ<26>")
	)
	(segment
		(start 57.803288 -309.960264)
		(end 60.382912 -309.960264)
		(width 0.14478)
		(layer "In4.Cu")
		(net "M_D_CPU1_SB_DQ<26>")
	)
	(segment
		(start 33.757108 -310.099964)
		(end 33.98774 -310.099964)
		(width 0.14478)
		(layer "In4.Cu")
		(net "M_D_CPU1_SB_DQ<26>")
	)
	(segment
		(start 34.706814 -310.647588)
		(end 34.706814 -310.262778)
		(width 0.14478)
		(layer "In4.Cu")
		(net "M_D_CPU1_SB_DQ<26>")
	)
	(segment
		(start 45.493432 -309.960264)
		(end 46.34357 -310.810402)
		(width 0.14478)
		(layer "In4.Cu")
		(net "M_D_CPU1_SB_DQ<26>")
	)
	(segment
		(start 86.879684 -289.148774)
		(end 86.888066 -289.1536)
		(width 0.0889)
		(layer "In4.Cu")
		(net "M_D_CPU1_SB_DQ<26>")
	)
	(segment
		(start 71.962518 -298.380658)
		(end 71.962518 -296.742104)
		(width 0.14478)
		(layer "In4.Cu")
		(net "M_D_CPU1_SB_DQ<26>")
	)
	(segment
		(start 34.150554 -310.647588)
		(end 34.313368 -310.810402)
		(width 0.14478)
		(layer "In4.Cu")
		(net "M_D_CPU1_SB_DQ<26>")
	)
	(segment
		(start 75.931268 -292.773354)
		(end 76.23175 -292.472872)
		(width 0.0889)
		(layer "In4.Cu")
		(net "M_D_CPU1_SB_DQ<26>")
	)
	(segment
		(start 76.767944 -291.368226)
		(end 77.18171 -291.368226)
		(width 0.0889)
		(layer "In4.Cu")
		(net "M_D_CPU1_SB_DQ<26>")
	)
	(segment
		(start 87.453978 -289.1536)
		(end 87.46236 -289.148774)
		(width 0.0889)
		(layer "In4.Cu")
		(net "M_D_CPU1_SB_DQ<26>")
	)
	(arc
		(start 89.707974 -289.1536)
		(mid 89.99093 -289.229777)
		(end 90.273886 -289.1536)
		(width 0.0889)
		(layer "In4.Cu")
		(net "M_D_CPU1_SB_DQ<26>")
	)
	(arc
		(start 81.247996 -289.1536)
		(mid 81.530952 -289.229777)
		(end 81.813908 -289.1536)
		(width 0.0889)
		(layer "In4.Cu")
		(net "M_D_CPU1_SB_DQ<26>")
	)
	(arc
		(start 89.334086 -289.1536)
		(mid 89.52103 -289.103345)
		(end 89.707974 -289.1536)
		(width 0.0889)
		(layer "In4.Cu")
		(net "M_D_CPU1_SB_DQ<26>")
	)
	(arc
		(start 83.702398 -289.148774)
		(mid 83.885906 -289.10328)
		(end 84.068158 -289.1536)
		(width 0.0889)
		(layer "In4.Cu")
		(net "M_D_CPU1_SB_DQ<26>")
	)
	(arc
		(start 88.768174 -289.1536)
		(mid 89.05113 -289.229777)
		(end 89.334086 -289.1536)
		(width 0.0889)
		(layer "In4.Cu")
		(net "M_D_CPU1_SB_DQ<26>")
	)
	(arc
		(start 78.711044 -289.2298)
		(mid 78.857292 -289.210495)
		(end 78.993492 -289.153854)
		(width 0.0889)
		(layer "In4.Cu")
		(net "M_D_CPU1_SB_DQ<26>")
	)
	(arc
		(start 87.46236 -289.148774)
		(mid 87.645868 -289.10328)
		(end 87.82812 -289.1536)
		(width 0.0889)
		(layer "In4.Cu")
		(net "M_D_CPU1_SB_DQ<26>")
	)
	(arc
		(start 85.57387 -289.1536)
		(mid 85.756121 -289.10325)
		(end 85.93963 -289.148774)
		(width 0.0889)
		(layer "In4.Cu")
		(net "M_D_CPU1_SB_DQ<26>")
	)
	(arc
		(start 81.813908 -289.1536)
		(mid 81.996159 -289.10325)
		(end 82.179668 -289.148774)
		(width 0.0889)
		(layer "In4.Cu")
		(net "M_D_CPU1_SB_DQ<26>")
	)
	(arc
		(start 88.402414 -289.148774)
		(mid 88.585922 -289.10328)
		(end 88.768174 -289.1536)
		(width 0.0889)
		(layer "In4.Cu")
		(net "M_D_CPU1_SB_DQ<26>")
	)
	(arc
		(start 85.007958 -289.1536)
		(mid 85.290914 -289.229777)
		(end 85.57387 -289.1536)
		(width 0.0889)
		(layer "In4.Cu")
		(net "M_D_CPU1_SB_DQ<26>")
	)
	(arc
		(start 79.367634 -289.1536)
		(mid 79.64234 -289.229964)
		(end 79.919322 -289.162236)
		(width 0.0889)
		(layer "In4.Cu")
		(net "M_D_CPU1_SB_DQ<26>")
	)
	(arc
		(start 84.63407 -289.1536)
		(mid 84.821014 -289.103345)
		(end 85.007958 -289.1536)
		(width 0.0889)
		(layer "In4.Cu")
		(net "M_D_CPU1_SB_DQ<26>")
	)
	(arc
		(start 80.308196 -289.1536)
		(mid 80.591152 -289.229777)
		(end 80.874108 -289.1536)
		(width 0.0889)
		(layer "In4.Cu")
		(net "M_D_CPU1_SB_DQ<26>")
	)
	(arc
		(start 90.273886 -289.1536)
		(mid 90.456137 -289.10325)
		(end 90.639646 -289.148774)
		(width 0.0889)
		(layer "In4.Cu")
		(net "M_D_CPU1_SB_DQ<26>")
	)
	(arc
		(start 84.068158 -289.1536)
		(mid 84.351114 -289.229777)
		(end 84.63407 -289.1536)
		(width 0.0889)
		(layer "In4.Cu")
		(net "M_D_CPU1_SB_DQ<26>")
	)
	(arc
		(start 87.82812 -289.1536)
		(mid 88.111076 -289.229777)
		(end 88.394032 -289.1536)
		(width 0.0889)
		(layer "In4.Cu")
		(net "M_D_CPU1_SB_DQ<26>")
	)
	(arc
		(start 80.874108 -289.1536)
		(mid 81.061052 -289.103345)
		(end 81.247996 -289.1536)
		(width 0.0889)
		(layer "In4.Cu")
		(net "M_D_CPU1_SB_DQ<26>")
	)
	(arc
		(start 85.948012 -289.1536)
		(mid 86.230968 -289.229777)
		(end 86.513924 -289.1536)
		(width 0.0889)
		(layer "In4.Cu")
		(net "M_D_CPU1_SB_DQ<26>")
	)
	(arc
		(start 86.513924 -289.1536)
		(mid 86.696175 -289.10325)
		(end 86.879684 -289.148774)
		(width 0.0889)
		(layer "In4.Cu")
		(net "M_D_CPU1_SB_DQ<26>")
	)
	(arc
		(start 82.18805 -289.1536)
		(mid 82.471006 -289.229777)
		(end 82.753962 -289.1536)
		(width 0.0889)
		(layer "In4.Cu")
		(net "M_D_CPU1_SB_DQ<26>")
	)
	(arc
		(start 79.942436 -289.148774)
		(mid 80.125944 -289.10328)
		(end 80.308196 -289.1536)
		(width 0.0889)
		(layer "In4.Cu")
		(net "M_D_CPU1_SB_DQ<26>")
	)
	(arc
		(start 90.648028 -289.1536)
		(mid 90.895624 -289.228778)
		(end 91.150694 -289.18535)
		(width 0.0889)
		(layer "In4.Cu")
		(net "M_D_CPU1_SB_DQ<26>")
	)
	(arc
		(start 79.01178 -289.14344)
		(mid 79.191009 -289.103287)
		(end 79.367634 -289.1536)
		(width 0.0889)
		(layer "In4.Cu")
		(net "M_D_CPU1_SB_DQ<26>")
	)
	(arc
		(start 86.888066 -289.1536)
		(mid 87.171022 -289.229777)
		(end 87.453978 -289.1536)
		(width 0.0889)
		(layer "In4.Cu")
		(net "M_D_CPU1_SB_DQ<26>")
	)
	(arc
		(start 82.762344 -289.148774)
		(mid 82.945852 -289.10328)
		(end 83.128104 -289.1536)
		(width 0.0889)
		(layer "In4.Cu")
		(net "M_D_CPU1_SB_DQ<26>")
	)
	(arc
		(start 83.128104 -289.1536)
		(mid 83.41106 -289.229777)
		(end 83.694016 -289.1536)
		(width 0.0889)
		(layer "In4.Cu")
		(net "M_D_CPU1_SB_DQ<26>")
	)
	(segment
		(start 92.80779 -289.210242)
		(end 92.340938 -289.47618)
		(width 0.10668)
		(layer "F.Cu")
		(net "M_D_CPU1_SB_DQ<25>")
	)
	(segment
		(start 43.57624 -310.506364)
		(end 43.880024 -310.810148)
		(width 0.14478)
		(layer "In4.Cu")
		(net "M_D_CPU1_SB_DQ<25>")
	)
	(segment
		(start 36.795964 -311.235344)
		(end 37.601906 -312.041286)
		(width 0.14478)
		(layer "In4.Cu")
		(net "M_D_CPU1_SB_DQ<25>")
	)
	(segment
		(start 77.97165 -290.147756)
		(end 78.172056 -289.94735)
		(width 0.0889)
		(layer "In4.Cu")
		(net "M_D_CPU1_SB_DQ<25>")
	)
	(segment
		(start 90.639646 -289.803586)
		(end 90.648028 -289.79876)
		(width 0.0889)
		(layer "In4.Cu")
		(net "M_D_CPU1_SB_DQ<25>")
	)
	(segment
		(start 79.367126 -289.79876)
		(end 79.381858 -289.790124)
		(width 0.0889)
		(layer "In4.Cu")
		(net "M_D_CPU1_SB_DQ<25>")
	)
	(segment
		(start 38.169342 -311.312306)
		(end 38.399974 -311.312306)
		(width 0.14478)
		(layer "In4.Cu")
		(net "M_D_CPU1_SB_DQ<25>")
	)
	(segment
		(start 92.153994 -289.79876)
		(end 92.162376 -289.803586)
		(width 0.0889)
		(layer "In4.Cu")
		(net "M_D_CPU1_SB_DQ<25>")
	)
	(segment
		(start 83.694016 -289.79876)
		(end 83.702398 -289.803586)
		(width 0.0889)
		(layer "In4.Cu")
		(net "M_D_CPU1_SB_DQ<25>")
	)
	(segment
		(start 60.169044 -310.810148)
		(end 72.412098 -298.567094)
		(width 0.14478)
		(layer "In4.Cu")
		(net "M_D_CPU1_SB_DQ<25>")
	)
	(segment
		(start 91.5797 -289.803586)
		(end 91.588082 -289.79876)
		(width 0.0889)
		(layer "In4.Cu")
		(net "M_D_CPU1_SB_DQ<25>")
	)
	(segment
		(start 38.711886 -312.038746)
		(end 38.96995 -312.038746)
		(width 0.14478)
		(layer "In4.Cu")
		(net "M_D_CPU1_SB_DQ<25>")
	)
	(segment
		(start 52.838096 -311.02935)
		(end 52.838096 -310.590946)
		(width 0.14478)
		(layer "In4.Cu")
		(net "M_D_CPU1_SB_DQ<25>")
	)
	(segment
		(start 92.472764 -289.824922)
		(end 92.495116 -289.74161)
		(width 0.0889)
		(layer "In4.Cu")
		(net "M_D_CPU1_SB_DQ<25>")
	)
	(segment
		(start 44.91228 -310.506364)
		(end 45.30344 -310.506364)
		(width 0.14478)
		(layer "In4.Cu")
		(net "M_D_CPU1_SB_DQ<25>")
	)
	(segment
		(start 50.858166 -311.024778)
		(end 51.02098 -311.187592)
		(width 0.14478)
		(layer "In4.Cu")
		(net "M_D_CPU1_SB_DQ<25>")
	)
	(segment
		(start 86.879684 -289.803586)
		(end 86.888066 -289.79876)
		(width 0.0889)
		(layer "In4.Cu")
		(net "M_D_CPU1_SB_DQ<25>")
	)
	(segment
		(start 54.472586 -311.660286)
		(end 56.746394 -311.660286)
		(width 0.14478)
		(layer "In4.Cu")
		(net "M_D_CPU1_SB_DQ<25>")
	)
	(segment
		(start 75.93584 -293.412418)
		(end 76.42225 -292.926008)
		(width 0.0889)
		(layer "In4.Cu")
		(net "M_D_CPU1_SB_DQ<25>")
	)
	(segment
		(start 78.977744 -289.789362)
		(end 78.993492 -289.798506)
		(width 0.0889)
		(layer "In4.Cu")
		(net "M_D_CPU1_SB_DQ<25>")
	)
	(segment
		(start 80.299814 -289.803586)
		(end 80.308196 -289.79876)
		(width 0.0889)
		(layer "In4.Cu")
		(net "M_D_CPU1_SB_DQ<25>")
	)
	(segment
		(start 38.006528 -311.889648)
		(end 38.006528 -311.47512)
		(width 0.14478)
		(layer "In4.Cu")
		(net "M_D_CPU1_SB_DQ<25>")
	)
	(segment
		(start 78.172056 -289.94735)
		(end 78.42758 -289.79876)
		(width 0.0889)
		(layer "In4.Cu")
		(net "M_D_CPU1_SB_DQ<25>")
	)
	(segment
		(start 52.675282 -311.192164)
		(end 52.838096 -311.02935)
		(width 0.14478)
		(layer "In4.Cu")
		(net "M_D_CPU1_SB_DQ<25>")
	)
	(segment
		(start 47.013622 -311.979564)
		(end 47.3329 -311.660286)
		(width 0.14478)
		(layer "In4.Cu")
		(net "M_D_CPU1_SB_DQ<25>")
	)
	(segment
		(start 77.97165 -290.938966)
		(end 77.97165 -290.147756)
		(width 0.0889)
		(layer "In4.Cu")
		(net "M_D_CPU1_SB_DQ<25>")
	)
	(segment
		(start 39.860474 -311.660286)
		(end 41.063926 -311.660286)
		(width 0.14478)
		(layer "In4.Cu")
		(net "M_D_CPU1_SB_DQ<25>")
	)
	(segment
		(start 51.629056 -310.810148)
		(end 52.062634 -310.810148)
		(width 0.14478)
		(layer "In4.Cu")
		(net "M_D_CPU1_SB_DQ<25>")
	)
	(segment
		(start 52.44465 -311.192164)
		(end 52.675282 -311.192164)
		(width 0.14478)
		(layer "In4.Cu")
		(net "M_D_CPU1_SB_DQ<25>")
	)
	(segment
		(start 38.562788 -311.47512)
		(end 38.562788 -311.889648)
		(width 0.14478)
		(layer "In4.Cu")
		(net "M_D_CPU1_SB_DQ<25>")
	)
	(segment
		(start 50.695352 -310.42356)
		(end 50.858166 -310.586374)
		(width 0.14478)
		(layer "In4.Cu")
		(net "M_D_CPU1_SB_DQ<25>")
	)
	(segment
		(start 39.281862 -311.312306)
		(end 39.512494 -311.312306)
		(width 0.14478)
		(layer "In4.Cu")
		(net "M_D_CPU1_SB_DQ<25>")
	)
	(segment
		(start 52.838096 -310.590946)
		(end 53.00091 -310.428132)
		(width 0.14478)
		(layer "In4.Cu")
		(net "M_D_CPU1_SB_DQ<25>")
	)
	(segment
		(start 77.21981 -291.690806)
		(end 77.97165 -290.938966)
		(width 0.0889)
		(layer "In4.Cu")
		(net "M_D_CPU1_SB_DQ<25>")
	)
	(segment
		(start 53.00091 -310.428132)
		(end 53.240432 -310.428132)
		(width 0.14478)
		(layer "In4.Cu")
		(net "M_D_CPU1_SB_DQ<25>")
	)
	(segment
		(start 39.119048 -311.889648)
		(end 39.119048 -311.47512)
		(width 0.14478)
		(layer "In4.Cu")
		(net "M_D_CPU1_SB_DQ<25>")
	)
	(segment
		(start 50.46472 -310.42356)
		(end 50.695352 -310.42356)
		(width 0.14478)
		(layer "In4.Cu")
		(net "M_D_CPU1_SB_DQ<25>")
	)
	(segment
		(start 45.30344 -310.506364)
		(end 46.77664 -311.979564)
		(width 0.14478)
		(layer "In4.Cu")
		(net "M_D_CPU1_SB_DQ<25>")
	)
	(segment
		(start 48.908716 -311.979564)
		(end 50.46472 -310.42356)
		(width 0.14478)
		(layer "In4.Cu")
		(net "M_D_CPU1_SB_DQ<25>")
	)
	(segment
		(start 82.179668 -289.803586)
		(end 82.18805 -289.79876)
		(width 0.0889)
		(layer "In4.Cu")
		(net "M_D_CPU1_SB_DQ<25>")
	)
	(segment
		(start 92.495116 -289.74161)
		(end 92.340938 -289.47618)
		(width 0.0889)
		(layer "In4.Cu")
		(net "M_D_CPU1_SB_DQ<25>")
	)
	(segment
		(start 88.394032 -289.79876)
		(end 88.402414 -289.803586)
		(width 0.0889)
		(layer "In4.Cu")
		(net "M_D_CPU1_SB_DQ<25>")
	)
	(segment
		(start 47.3329 -311.660286)
		(end 48.352456 -311.660286)
		(width 0.14478)
		(layer "In4.Cu")
		(net "M_D_CPU1_SB_DQ<25>")
	)
	(segment
		(start 56.746394 -311.660286)
		(end 57.596532 -310.810148)
		(width 0.14478)
		(layer "In4.Cu")
		(net "M_D_CPU1_SB_DQ<25>")
	)
	(segment
		(start 38.399974 -311.312306)
		(end 38.562788 -311.47512)
		(width 0.14478)
		(layer "In4.Cu")
		(net "M_D_CPU1_SB_DQ<25>")
	)
	(segment
		(start 72.412098 -296.93616)
		(end 75.93584 -293.412418)
		(width 0.14478)
		(layer "In4.Cu")
		(net "M_D_CPU1_SB_DQ<25>")
	)
	(segment
		(start 37.601906 -312.041286)
		(end 37.85489 -312.041286)
		(width 0.14478)
		(layer "In4.Cu")
		(net "M_D_CPU1_SB_DQ<25>")
	)
	(segment
		(start 51.251612 -311.187592)
		(end 51.629056 -310.810148)
		(width 0.14478)
		(layer "In4.Cu")
		(net "M_D_CPU1_SB_DQ<25>")
	)
	(segment
		(start 78.993492 -289.798506)
		(end 79.007208 -289.80638)
		(width 0.0889)
		(layer "In4.Cu")
		(net "M_D_CPU1_SB_DQ<25>")
	)
	(segment
		(start 53.240432 -310.428132)
		(end 54.472586 -311.660286)
		(width 0.14478)
		(layer "In4.Cu")
		(net "M_D_CPU1_SB_DQ<25>")
	)
	(segment
		(start 39.119048 -311.47512)
		(end 39.281862 -311.312306)
		(width 0.14478)
		(layer "In4.Cu")
		(net "M_D_CPU1_SB_DQ<25>")
	)
	(segment
		(start 43.169332 -310.506364)
		(end 43.57624 -310.506364)
		(width 0.14478)
		(layer "In4.Cu")
		(net "M_D_CPU1_SB_DQ<25>")
	)
	(segment
		(start 48.352456 -311.660286)
		(end 48.671734 -311.979564)
		(width 0.14478)
		(layer "In4.Cu")
		(net "M_D_CPU1_SB_DQ<25>")
	)
	(segment
		(start 57.596532 -310.810148)
		(end 60.169044 -310.810148)
		(width 0.14478)
		(layer "In4.Cu")
		(net "M_D_CPU1_SB_DQ<25>")
	)
	(segment
		(start 38.96995 -312.038746)
		(end 39.119048 -311.889648)
		(width 0.14478)
		(layer "In4.Cu")
		(net "M_D_CPU1_SB_DQ<25>")
	)
	(segment
		(start 38.006528 -311.47512)
		(end 38.169342 -311.312306)
		(width 0.14478)
		(layer "In4.Cu")
		(net "M_D_CPU1_SB_DQ<25>")
	)
	(segment
		(start 85.93963 -289.803586)
		(end 85.948012 -289.79876)
		(width 0.0889)
		(layer "In4.Cu")
		(net "M_D_CPU1_SB_DQ<25>")
	)
	(segment
		(start 52.062634 -310.810148)
		(end 52.44465 -311.192164)
		(width 0.14478)
		(layer "In4.Cu")
		(net "M_D_CPU1_SB_DQ<25>")
	)
	(segment
		(start 51.02098 -311.187592)
		(end 51.251612 -311.187592)
		(width 0.14478)
		(layer "In4.Cu")
		(net "M_D_CPU1_SB_DQ<25>")
	)
	(segment
		(start 41.654984 -312.020712)
		(end 43.169332 -310.506364)
		(width 0.14478)
		(layer "In4.Cu")
		(net "M_D_CPU1_SB_DQ<25>")
	)
	(segment
		(start 43.880024 -310.810148)
		(end 44.608496 -310.810148)
		(width 0.14478)
		(layer "In4.Cu")
		(net "M_D_CPU1_SB_DQ<25>")
	)
	(segment
		(start 50.858166 -310.586374)
		(end 50.858166 -311.024778)
		(width 0.14478)
		(layer "In4.Cu")
		(net "M_D_CPU1_SB_DQ<25>")
	)
	(segment
		(start 76.42225 -292.926008)
		(end 76.42225 -292.135306)
		(width 0.0889)
		(layer "In4.Cu")
		(net "M_D_CPU1_SB_DQ<25>")
	)
	(segment
		(start 76.86675 -291.690806)
		(end 77.21981 -291.690806)
		(width 0.0889)
		(layer "In4.Cu")
		(net "M_D_CPU1_SB_DQ<25>")
	)
	(segment
		(start 48.671734 -311.979564)
		(end 48.908716 -311.979564)
		(width 0.14478)
		(layer "In4.Cu")
		(net "M_D_CPU1_SB_DQ<25>")
	)
	(segment
		(start 87.453978 -289.79876)
		(end 87.46236 -289.803586)
		(width 0.0889)
		(layer "In4.Cu")
		(net "M_D_CPU1_SB_DQ<25>")
	)
	(segment
		(start 41.424352 -312.020712)
		(end 41.654984 -312.020712)
		(width 0.14478)
		(layer "In4.Cu")
		(net "M_D_CPU1_SB_DQ<25>")
	)
	(segment
		(start 46.77664 -311.979564)
		(end 47.013622 -311.979564)
		(width 0.14478)
		(layer "In4.Cu")
		(net "M_D_CPU1_SB_DQ<25>")
	)
	(segment
		(start 82.753962 -289.79876)
		(end 82.762344 -289.803586)
		(width 0.0889)
		(layer "In4.Cu")
		(net "M_D_CPU1_SB_DQ<25>")
	)
	(segment
		(start 72.412098 -298.567094)
		(end 72.412098 -296.93616)
		(width 0.14478)
		(layer "In4.Cu")
		(net "M_D_CPU1_SB_DQ<25>")
	)
	(segment
		(start 41.063926 -311.660286)
		(end 41.424352 -312.020712)
		(width 0.14478)
		(layer "In4.Cu")
		(net "M_D_CPU1_SB_DQ<25>")
	)
	(segment
		(start 37.85489 -312.041286)
		(end 38.006528 -311.889648)
		(width 0.14478)
		(layer "In4.Cu")
		(net "M_D_CPU1_SB_DQ<25>")
	)
	(segment
		(start 76.42225 -292.135306)
		(end 76.86675 -291.690806)
		(width 0.0889)
		(layer "In4.Cu")
		(net "M_D_CPU1_SB_DQ<25>")
	)
	(segment
		(start 39.512494 -311.312306)
		(end 39.860474 -311.660286)
		(width 0.14478)
		(layer "In4.Cu")
		(net "M_D_CPU1_SB_DQ<25>")
	)
	(segment
		(start 38.562788 -311.889648)
		(end 38.711886 -312.038746)
		(width 0.14478)
		(layer "In4.Cu")
		(net "M_D_CPU1_SB_DQ<25>")
	)
	(segment
		(start 44.608496 -310.810148)
		(end 44.91228 -310.506364)
		(width 0.14478)
		(layer "In4.Cu")
		(net "M_D_CPU1_SB_DQ<25>")
	)
	(arc
		(start 89.707974 -289.79876)
		(mid 89.99093 -289.722583)
		(end 90.273886 -289.79876)
		(width 0.0889)
		(layer "In4.Cu")
		(net "M_D_CPU1_SB_DQ<25>")
	)
	(arc
		(start 82.18805 -289.79876)
		(mid 82.471006 -289.722583)
		(end 82.753962 -289.79876)
		(width 0.0889)
		(layer "In4.Cu")
		(net "M_D_CPU1_SB_DQ<25>")
	)
	(arc
		(start 84.068158 -289.79876)
		(mid 84.351114 -289.722583)
		(end 84.63407 -289.79876)
		(width 0.0889)
		(layer "In4.Cu")
		(net "M_D_CPU1_SB_DQ<25>")
	)
	(arc
		(start 85.007958 -289.79876)
		(mid 85.290914 -289.722583)
		(end 85.57387 -289.79876)
		(width 0.0889)
		(layer "In4.Cu")
		(net "M_D_CPU1_SB_DQ<25>")
	)
	(arc
		(start 92.162376 -289.803586)
		(mid 92.315246 -289.848227)
		(end 92.472764 -289.824922)
		(width 0.0889)
		(layer "In4.Cu")
		(net "M_D_CPU1_SB_DQ<25>")
	)
	(arc
		(start 88.402414 -289.803586)
		(mid 88.585922 -289.84908)
		(end 88.768174 -289.79876)
		(width 0.0889)
		(layer "In4.Cu")
		(net "M_D_CPU1_SB_DQ<25>")
	)
	(arc
		(start 83.702398 -289.803586)
		(mid 83.885906 -289.84908)
		(end 84.068158 -289.79876)
		(width 0.0889)
		(layer "In4.Cu")
		(net "M_D_CPU1_SB_DQ<25>")
	)
	(arc
		(start 89.334086 -289.79876)
		(mid 89.52103 -289.849015)
		(end 89.707974 -289.79876)
		(width 0.0889)
		(layer "In4.Cu")
		(net "M_D_CPU1_SB_DQ<25>")
	)
	(arc
		(start 81.813908 -289.79876)
		(mid 81.996159 -289.84911)
		(end 82.179668 -289.803586)
		(width 0.0889)
		(layer "In4.Cu")
		(net "M_D_CPU1_SB_DQ<25>")
	)
	(arc
		(start 82.762344 -289.803586)
		(mid 82.945852 -289.84908)
		(end 83.128104 -289.79876)
		(width 0.0889)
		(layer "In4.Cu")
		(net "M_D_CPU1_SB_DQ<25>")
	)
	(arc
		(start 84.63407 -289.79876)
		(mid 84.821014 -289.849015)
		(end 85.007958 -289.79876)
		(width 0.0889)
		(layer "In4.Cu")
		(net "M_D_CPU1_SB_DQ<25>")
	)
	(arc
		(start 91.21394 -289.79876)
		(mid 91.396191 -289.84911)
		(end 91.5797 -289.803586)
		(width 0.0889)
		(layer "In4.Cu")
		(net "M_D_CPU1_SB_DQ<25>")
	)
	(arc
		(start 88.768174 -289.79876)
		(mid 89.05113 -289.722583)
		(end 89.334086 -289.79876)
		(width 0.0889)
		(layer "In4.Cu")
		(net "M_D_CPU1_SB_DQ<25>")
	)
	(arc
		(start 78.42758 -289.79876)
		(mid 78.701435 -289.72241)
		(end 78.977744 -289.789362)
		(width 0.0889)
		(layer "In4.Cu")
		(net "M_D_CPU1_SB_DQ<25>")
	)
	(arc
		(start 91.588082 -289.79876)
		(mid 91.871038 -289.722583)
		(end 92.153994 -289.79876)
		(width 0.0889)
		(layer "In4.Cu")
		(net "M_D_CPU1_SB_DQ<25>")
	)
	(arc
		(start 83.128104 -289.79876)
		(mid 83.41106 -289.722583)
		(end 83.694016 -289.79876)
		(width 0.0889)
		(layer "In4.Cu")
		(net "M_D_CPU1_SB_DQ<25>")
	)
	(arc
		(start 86.513924 -289.79876)
		(mid 86.696175 -289.84911)
		(end 86.879684 -289.803586)
		(width 0.0889)
		(layer "In4.Cu")
		(net "M_D_CPU1_SB_DQ<25>")
	)
	(arc
		(start 90.273886 -289.79876)
		(mid 90.456137 -289.84911)
		(end 90.639646 -289.803586)
		(width 0.0889)
		(layer "In4.Cu")
		(net "M_D_CPU1_SB_DQ<25>")
	)
	(arc
		(start 79.381858 -289.790124)
		(mid 79.658841 -289.72232)
		(end 79.933546 -289.79876)
		(width 0.0889)
		(layer "In4.Cu")
		(net "M_D_CPU1_SB_DQ<25>")
	)
	(arc
		(start 79.933546 -289.79876)
		(mid 80.116051 -289.849237)
		(end 80.299814 -289.803586)
		(width 0.0889)
		(layer "In4.Cu")
		(net "M_D_CPU1_SB_DQ<25>")
	)
	(arc
		(start 87.82812 -289.79876)
		(mid 88.111076 -289.722583)
		(end 88.394032 -289.79876)
		(width 0.0889)
		(layer "In4.Cu")
		(net "M_D_CPU1_SB_DQ<25>")
	)
	(arc
		(start 87.46236 -289.803586)
		(mid 87.645868 -289.84908)
		(end 87.82812 -289.79876)
		(width 0.0889)
		(layer "In4.Cu")
		(net "M_D_CPU1_SB_DQ<25>")
	)
	(arc
		(start 81.247996 -289.79876)
		(mid 81.530952 -289.722583)
		(end 81.813908 -289.79876)
		(width 0.0889)
		(layer "In4.Cu")
		(net "M_D_CPU1_SB_DQ<25>")
	)
	(arc
		(start 85.948012 -289.79876)
		(mid 86.230968 -289.722583)
		(end 86.513924 -289.79876)
		(width 0.0889)
		(layer "In4.Cu")
		(net "M_D_CPU1_SB_DQ<25>")
	)
	(arc
		(start 86.888066 -289.79876)
		(mid 87.171022 -289.722583)
		(end 87.453978 -289.79876)
		(width 0.0889)
		(layer "In4.Cu")
		(net "M_D_CPU1_SB_DQ<25>")
	)
	(arc
		(start 79.007208 -289.80638)
		(mid 79.188138 -289.848858)
		(end 79.367126 -289.79876)
		(width 0.0889)
		(layer "In4.Cu")
		(net "M_D_CPU1_SB_DQ<25>")
	)
	(arc
		(start 90.648028 -289.79876)
		(mid 90.930984 -289.722583)
		(end 91.21394 -289.79876)
		(width 0.0889)
		(layer "In4.Cu")
		(net "M_D_CPU1_SB_DQ<25>")
	)
	(arc
		(start 80.874108 -289.79876)
		(mid 81.061052 -289.849015)
		(end 81.247996 -289.79876)
		(width 0.0889)
		(layer "In4.Cu")
		(net "M_D_CPU1_SB_DQ<25>")
	)
	(arc
		(start 85.57387 -289.79876)
		(mid 85.756121 -289.84911)
		(end 85.93963 -289.803586)
		(width 0.0889)
		(layer "In4.Cu")
		(net "M_D_CPU1_SB_DQ<25>")
	)
	(arc
		(start 80.308196 -289.79876)
		(mid 80.591152 -289.722583)
		(end 80.874108 -289.79876)
		(width 0.0889)
		(layer "In4.Cu")
		(net "M_D_CPU1_SB_DQ<25>")
	)
	(segment
		(start 91.397836 -288.400236)
		(end 90.930984 -288.666174)
		(width 0.10668)
		(layer "F.Cu")
		(net "M_D_CPU1_SB_DQ<24>")
	)
	(segment
		(start 53.717698 -309.476394)
		(end 53.947822 -309.476394)
		(width 0.14478)
		(layer "In4.Cu")
		(net "M_D_CPU1_SB_DQ<24>")
	)
	(segment
		(start 45.431456 -309.11038)
		(end 46.281594 -309.960518)
		(width 0.14478)
		(layer "In4.Cu")
		(net "M_D_CPU1_SB_DQ<24>")
	)
	(segment
		(start 70.923658 -298.269152)
		(end 71.512938 -297.679872)
		(width 0.14478)
		(layer "In4.Cu")
		(net "M_D_CPU1_SB_DQ<24>")
	)
	(segment
		(start 47.054516 -310.277764)
		(end 47.371762 -309.960518)
		(width 0.14478)
		(layer "In4.Cu")
		(net "M_D_CPU1_SB_DQ<24>")
	)
	(segment
		(start 38.94963 -310.345836)
		(end 39.112444 -310.183022)
		(width 0.14478)
		(layer "In4.Cu")
		(net "M_D_CPU1_SB_DQ<24>")
	)
	(segment
		(start 48.863758 -309.830978)
		(end 48.863758 -310.182006)
		(width 0.14478)
		(layer "In4.Cu")
		(net "M_D_CPU1_SB_DQ<24>")
	)
	(segment
		(start 69.550026 -299.642784)
		(end 69.956426 -299.642784)
		(width 0.14478)
		(layer "In4.Cu")
		(net "M_D_CPU1_SB_DQ<24>")
	)
	(segment
		(start 46.498256 -309.960518)
		(end 46.815502 -310.277764)
		(width 0.14478)
		(layer "In4.Cu")
		(net "M_D_CPU1_SB_DQ<24>")
	)
	(segment
		(start 68.582794 -301.016416)
		(end 68.582794 -300.610016)
		(width 0.14478)
		(layer "In4.Cu")
		(net "M_D_CPU1_SB_DQ<24>")
	)
	(segment
		(start 84.529676 -288.99358)
		(end 84.538058 -288.988754)
		(width 0.0889)
		(layer "In4.Cu")
		(net "M_D_CPU1_SB_DQ<24>")
	)
	(segment
		(start 39.275258 -309.685944)
		(end 39.50589 -309.685944)
		(width 0.14478)
		(layer "In4.Cu")
		(net "M_D_CPU1_SB_DQ<24>")
	)
	(segment
		(start 46.281594 -309.960518)
		(end 46.498256 -309.960518)
		(width 0.14478)
		(layer "In4.Cu")
		(net "M_D_CPU1_SB_DQ<24>")
	)
	(segment
		(start 37.83711 -310.345836)
		(end 37.999924 -310.183022)
		(width 0.14478)
		(layer "In4.Cu")
		(net "M_D_CPU1_SB_DQ<24>")
	)
	(segment
		(start 54.341268 -309.86984)
		(end 54.341268 -310.099964)
		(width 0.14478)
		(layer "In4.Cu")
		(net "M_D_CPU1_SB_DQ<24>")
	)
	(segment
		(start 56.97093 -309.456328)
		(end 57.134252 -309.293006)
		(width 0.14478)
		(layer "In4.Cu")
		(net "M_D_CPU1_SB_DQ<24>")
	)
	(segment
		(start 79.826358 -288.995612)
		(end 79.838042 -288.988754)
		(width 0.0889)
		(layer "In4.Cu")
		(net "M_D_CPU1_SB_DQ<24>")
	)
	(segment
		(start 68.769738 -300.423072)
		(end 69.176138 -300.423072)
		(width 0.14478)
		(layer "In4.Cu")
		(net "M_D_CPU1_SB_DQ<24>")
	)
	(segment
		(start 89.229692 -288.99358)
		(end 89.238074 -288.988754)
		(width 0.0889)
		(layer "In4.Cu")
		(net "M_D_CPU1_SB_DQ<24>")
	)
	(segment
		(start 55.863236 -310.144668)
		(end 55.863236 -309.734204)
		(width 0.14478)
		(layer "In4.Cu")
		(net "M_D_CPU1_SB_DQ<24>")
	)
	(segment
		(start 67.98945 -301.20336)
		(end 68.39585 -301.20336)
		(width 0.14478)
		(layer "In4.Cu")
		(net "M_D_CPU1_SB_DQ<24>")
	)
	(segment
		(start 71.512938 -296.353738)
		(end 75.783186 -292.08349)
		(width 0.14478)
		(layer "In4.Cu")
		(net "M_D_CPU1_SB_DQ<24>")
	)
	(segment
		(start 91.06281 -289.014916)
		(end 91.085162 -288.931604)
		(width 0.0889)
		(layer "In4.Cu")
		(net "M_D_CPU1_SB_DQ<24>")
	)
	(segment
		(start 68.582794 -300.610016)
		(end 68.769738 -300.423072)
		(width 0.14478)
		(layer "In4.Cu")
		(net "M_D_CPU1_SB_DQ<24>")
	)
	(segment
		(start 39.112444 -310.183022)
		(end 39.112444 -309.848758)
		(width 0.14478)
		(layer "In4.Cu")
		(net "M_D_CPU1_SB_DQ<24>")
	)
	(segment
		(start 70.14337 -299.04944)
		(end 70.330314 -298.862496)
		(width 0.14478)
		(layer "In4.Cu")
		(net "M_D_CPU1_SB_DQ<24>")
	)
	(segment
		(start 38.718998 -310.345836)
		(end 38.94963 -310.345836)
		(width 0.14478)
		(layer "In4.Cu")
		(net "M_D_CPU1_SB_DQ<24>")
	)
	(segment
		(start 37.999924 -309.848758)
		(end 38.162738 -309.685944)
		(width 0.14478)
		(layer "In4.Cu")
		(net "M_D_CPU1_SB_DQ<24>")
	)
	(segment
		(start 51.513486 -309.11038)
		(end 52.24145 -309.11038)
		(width 0.14478)
		(layer "In4.Cu")
		(net "M_D_CPU1_SB_DQ<24>")
	)
	(segment
		(start 76.70927 -291.157406)
		(end 76.70927 -290.50488)
		(width 0.0889)
		(layer "In4.Cu")
		(net "M_D_CPU1_SB_DQ<24>")
	)
	(segment
		(start 50.678842 -309.11038)
		(end 50.957226 -309.388764)
		(width 0.14478)
		(layer "In4.Cu")
		(net "M_D_CPU1_SB_DQ<24>")
	)
	(segment
		(start 37.999924 -310.183022)
		(end 37.999924 -309.848758)
		(width 0.14478)
		(layer "In4.Cu")
		(net "M_D_CPU1_SB_DQ<24>")
	)
	(segment
		(start 69.956426 -299.642784)
		(end 70.14337 -299.45584)
		(width 0.14478)
		(layer "In4.Cu")
		(net "M_D_CPU1_SB_DQ<24>")
	)
	(segment
		(start 70.330314 -298.862496)
		(end 70.736714 -298.862496)
		(width 0.14478)
		(layer "In4.Cu")
		(net "M_D_CPU1_SB_DQ<24>")
	)
	(segment
		(start 36.795964 -309.535322)
		(end 37.606478 -310.345836)
		(width 0.14478)
		(layer "In4.Cu")
		(net "M_D_CPU1_SB_DQ<24>")
	)
	(segment
		(start 80.769714 -288.99358)
		(end 80.778096 -288.988754)
		(width 0.0889)
		(layer "In4.Cu")
		(net "M_D_CPU1_SB_DQ<24>")
	)
	(segment
		(start 69.176138 -300.423072)
		(end 69.363082 -300.236128)
		(width 0.14478)
		(layer "In4.Cu")
		(net "M_D_CPU1_SB_DQ<24>")
	)
	(segment
		(start 56.02605 -309.57139)
		(end 56.256682 -309.57139)
		(width 0.14478)
		(layer "In4.Cu")
		(net "M_D_CPU1_SB_DQ<24>")
	)
	(segment
		(start 54.341268 -310.099964)
		(end 54.548786 -310.307482)
		(width 0.14478)
		(layer "In4.Cu")
		(net "M_D_CPU1_SB_DQ<24>")
	)
	(segment
		(start 52.24145 -309.11038)
		(end 52.519834 -309.388764)
		(width 0.14478)
		(layer "In4.Cu")
		(net "M_D_CPU1_SB_DQ<24>")
	)
	(segment
		(start 91.085162 -288.931604)
		(end 90.930984 -288.666174)
		(width 0.0889)
		(layer "In4.Cu")
		(net "M_D_CPU1_SB_DQ<24>")
	)
	(segment
		(start 54.532276 -309.678832)
		(end 54.341268 -309.86984)
		(width 0.14478)
		(layer "In4.Cu")
		(net "M_D_CPU1_SB_DQ<24>")
	)
	(segment
		(start 85.10397 -288.988754)
		(end 85.112352 -288.99358)
		(width 0.0889)
		(layer "In4.Cu")
		(net "M_D_CPU1_SB_DQ<24>")
	)
	(segment
		(start 57.087516 -310.032908)
		(end 57.087516 -309.802784)
		(width 0.14478)
		(layer "In4.Cu")
		(net "M_D_CPU1_SB_DQ<24>")
	)
	(segment
		(start 50.491644 -309.11038)
		(end 50.678842 -309.11038)
		(width 0.14478)
		(layer "In4.Cu")
		(net "M_D_CPU1_SB_DQ<24>")
	)
	(segment
		(start 76.70927 -290.50488)
		(end 78.17485 -289.0393)
		(width 0.0889)
		(layer "In4.Cu")
		(net "M_D_CPU1_SB_DQ<24>")
	)
	(segment
		(start 86.044024 -288.988754)
		(end 86.052406 -288.99358)
		(width 0.0889)
		(layer "In4.Cu")
		(net "M_D_CPU1_SB_DQ<24>")
	)
	(segment
		(start 53.076094 -309.11038)
		(end 53.351684 -309.11038)
		(width 0.14478)
		(layer "In4.Cu")
		(net "M_D_CPU1_SB_DQ<24>")
	)
	(segment
		(start 38.556184 -309.848758)
		(end 38.556184 -310.183022)
		(width 0.14478)
		(layer "In4.Cu")
		(net "M_D_CPU1_SB_DQ<24>")
	)
	(segment
		(start 90.74404 -288.988754)
		(end 90.752422 -288.99358)
		(width 0.0889)
		(layer "In4.Cu")
		(net "M_D_CPU1_SB_DQ<24>")
	)
	(segment
		(start 39.780464 -309.960518)
		(end 41.361614 -309.960518)
		(width 0.14478)
		(layer "In4.Cu")
		(net "M_D_CPU1_SB_DQ<24>")
	)
	(segment
		(start 59.065668 -309.11038)
		(end 60.08243 -309.11038)
		(width 0.14478)
		(layer "In4.Cu")
		(net "M_D_CPU1_SB_DQ<24>")
	)
	(segment
		(start 56.812942 -310.307482)
		(end 57.087516 -310.032908)
		(width 0.14478)
		(layer "In4.Cu")
		(net "M_D_CPU1_SB_DQ<24>")
	)
	(segment
		(start 56.256682 -309.57139)
		(end 56.419496 -309.734204)
		(width 0.14478)
		(layer "In4.Cu")
		(net "M_D_CPU1_SB_DQ<24>")
	)
	(segment
		(start 52.79771 -309.388764)
		(end 53.076094 -309.11038)
		(width 0.14478)
		(layer "In4.Cu")
		(net "M_D_CPU1_SB_DQ<24>")
	)
	(segment
		(start 83.589622 -288.99358)
		(end 83.598004 -288.988754)
		(width 0.0889)
		(layer "In4.Cu")
		(net "M_D_CPU1_SB_DQ<24>")
	)
	(segment
		(start 46.815502 -310.277764)
		(end 47.054516 -310.277764)
		(width 0.14478)
		(layer "In4.Cu")
		(net "M_D_CPU1_SB_DQ<24>")
	)
	(segment
		(start 69.363082 -300.236128)
		(end 69.363082 -299.829728)
		(width 0.14478)
		(layer "In4.Cu")
		(net "M_D_CPU1_SB_DQ<24>")
	)
	(segment
		(start 53.351684 -309.11038)
		(end 53.717698 -309.476394)
		(width 0.14478)
		(layer "In4.Cu")
		(net "M_D_CPU1_SB_DQ<24>")
	)
	(segment
		(start 41.980612 -310.348884)
		(end 43.219116 -309.11038)
		(width 0.14478)
		(layer "In4.Cu")
		(net "M_D_CPU1_SB_DQ<24>")
	)
	(segment
		(start 48.700944 -309.668164)
		(end 48.863758 -309.830978)
		(width 0.14478)
		(layer "In4.Cu")
		(net "M_D_CPU1_SB_DQ<24>")
	)
	(segment
		(start 48.177958 -309.960518)
		(end 48.470312 -309.668164)
		(width 0.14478)
		(layer "In4.Cu")
		(net "M_D_CPU1_SB_DQ<24>")
	)
	(segment
		(start 48.863758 -310.182006)
		(end 49.026572 -310.34482)
		(width 0.14478)
		(layer "In4.Cu")
		(net "M_D_CPU1_SB_DQ<24>")
	)
	(segment
		(start 56.97093 -309.686198)
		(end 56.97093 -309.456328)
		(width 0.14478)
		(layer "In4.Cu")
		(net "M_D_CPU1_SB_DQ<24>")
	)
	(segment
		(start 70.14337 -299.45584)
		(end 70.14337 -299.04944)
		(width 0.14478)
		(layer "In4.Cu")
		(net "M_D_CPU1_SB_DQ<24>")
	)
	(segment
		(start 89.803986 -288.988754)
		(end 89.812368 -288.99358)
		(width 0.0889)
		(layer "In4.Cu")
		(net "M_D_CPU1_SB_DQ<24>")
	)
	(segment
		(start 69.363082 -299.829728)
		(end 69.550026 -299.642784)
		(width 0.14478)
		(layer "In4.Cu")
		(net "M_D_CPU1_SB_DQ<24>")
	)
	(segment
		(start 54.13883 -309.285386)
		(end 54.368954 -309.285386)
		(width 0.14478)
		(layer "In4.Cu")
		(net "M_D_CPU1_SB_DQ<24>")
	)
	(segment
		(start 54.368954 -309.285386)
		(end 54.532276 -309.448708)
		(width 0.14478)
		(layer "In4.Cu")
		(net "M_D_CPU1_SB_DQ<24>")
	)
	(segment
		(start 58.071766 -309.293006)
		(end 58.509408 -308.855364)
		(width 0.14478)
		(layer "In4.Cu")
		(net "M_D_CPU1_SB_DQ<24>")
	)
	(segment
		(start 37.606478 -310.345836)
		(end 37.83711 -310.345836)
		(width 0.14478)
		(layer "In4.Cu")
		(net "M_D_CPU1_SB_DQ<24>")
	)
	(segment
		(start 41.74998 -310.348884)
		(end 41.980612 -310.348884)
		(width 0.14478)
		(layer "In4.Cu")
		(net "M_D_CPU1_SB_DQ<24>")
	)
	(segment
		(start 88.289638 -288.99358)
		(end 88.29802 -288.988754)
		(width 0.0889)
		(layer "In4.Cu")
		(net "M_D_CPU1_SB_DQ<24>")
	)
	(segment
		(start 43.219116 -309.11038)
		(end 45.431456 -309.11038)
		(width 0.14478)
		(layer "In4.Cu")
		(net "M_D_CPU1_SB_DQ<24>")
	)
	(segment
		(start 38.162738 -309.685944)
		(end 38.39337 -309.685944)
		(width 0.14478)
		(layer "In4.Cu")
		(net "M_D_CPU1_SB_DQ<24>")
	)
	(segment
		(start 70.923658 -298.675552)
		(end 70.923658 -298.269152)
		(width 0.14478)
		(layer "In4.Cu")
		(net "M_D_CPU1_SB_DQ<24>")
	)
	(segment
		(start 48.470312 -309.668164)
		(end 48.700944 -309.668164)
		(width 0.14478)
		(layer "In4.Cu")
		(net "M_D_CPU1_SB_DQ<24>")
	)
	(segment
		(start 58.810652 -308.855364)
		(end 59.065668 -309.11038)
		(width 0.14478)
		(layer "In4.Cu")
		(net "M_D_CPU1_SB_DQ<24>")
	)
	(segment
		(start 60.08243 -309.11038)
		(end 67.98945 -301.20336)
		(width 0.14478)
		(layer "In4.Cu")
		(net "M_D_CPU1_SB_DQ<24>")
	)
	(segment
		(start 41.361614 -309.960518)
		(end 41.74998 -310.348884)
		(width 0.14478)
		(layer "In4.Cu")
		(net "M_D_CPU1_SB_DQ<24>")
	)
	(segment
		(start 70.736714 -298.862496)
		(end 70.923658 -298.675552)
		(width 0.14478)
		(layer "In4.Cu")
		(net "M_D_CPU1_SB_DQ<24>")
	)
	(segment
		(start 81.344008 -288.988754)
		(end 81.35239 -288.99358)
		(width 0.0889)
		(layer "In4.Cu")
		(net "M_D_CPU1_SB_DQ<24>")
	)
	(segment
		(start 52.519834 -309.388764)
		(end 52.79771 -309.388764)
		(width 0.14478)
		(layer "In4.Cu")
		(net "M_D_CPU1_SB_DQ<24>")
	)
	(segment
		(start 50.957226 -309.388764)
		(end 51.235102 -309.388764)
		(width 0.14478)
		(layer "In4.Cu")
		(net "M_D_CPU1_SB_DQ<24>")
	)
	(segment
		(start 55.863236 -309.734204)
		(end 56.02605 -309.57139)
		(width 0.14478)
		(layer "In4.Cu")
		(net "M_D_CPU1_SB_DQ<24>")
	)
	(segment
		(start 71.512938 -297.679872)
		(end 71.512938 -296.353738)
		(width 0.14478)
		(layer "In4.Cu")
		(net "M_D_CPU1_SB_DQ<24>")
	)
	(segment
		(start 58.509408 -308.855364)
		(end 58.810652 -308.855364)
		(width 0.14478)
		(layer "In4.Cu")
		(net "M_D_CPU1_SB_DQ<24>")
	)
	(segment
		(start 68.39585 -301.20336)
		(end 68.582794 -301.016416)
		(width 0.14478)
		(layer "In4.Cu")
		(net "M_D_CPU1_SB_DQ<24>")
	)
	(segment
		(start 78.17485 -289.0393)
		(end 78.71079 -289.0393)
		(width 0.0889)
		(layer "In4.Cu")
		(net "M_D_CPU1_SB_DQ<24>")
	)
	(segment
		(start 55.700422 -310.307482)
		(end 55.863236 -310.144668)
		(width 0.14478)
		(layer "In4.Cu")
		(net "M_D_CPU1_SB_DQ<24>")
	)
	(segment
		(start 56.419496 -310.144668)
		(end 56.58231 -310.307482)
		(width 0.14478)
		(layer "In4.Cu")
		(net "M_D_CPU1_SB_DQ<24>")
	)
	(segment
		(start 56.58231 -310.307482)
		(end 56.812942 -310.307482)
		(width 0.14478)
		(layer "In4.Cu")
		(net "M_D_CPU1_SB_DQ<24>")
	)
	(segment
		(start 75.783186 -292.08349)
		(end 76.70927 -291.157406)
		(width 0.0889)
		(layer "In4.Cu")
		(net "M_D_CPU1_SB_DQ<24>")
	)
	(segment
		(start 54.548786 -310.307482)
		(end 55.700422 -310.307482)
		(width 0.14478)
		(layer "In4.Cu")
		(net "M_D_CPU1_SB_DQ<24>")
	)
	(segment
		(start 56.419496 -309.734204)
		(end 56.419496 -310.144668)
		(width 0.14478)
		(layer "In4.Cu")
		(net "M_D_CPU1_SB_DQ<24>")
	)
	(segment
		(start 49.257204 -310.34482)
		(end 50.491644 -309.11038)
		(width 0.14478)
		(layer "In4.Cu")
		(net "M_D_CPU1_SB_DQ<24>")
	)
	(segment
		(start 53.947822 -309.476394)
		(end 54.13883 -309.285386)
		(width 0.14478)
		(layer "In4.Cu")
		(net "M_D_CPU1_SB_DQ<24>")
	)
	(segment
		(start 39.112444 -309.848758)
		(end 39.275258 -309.685944)
		(width 0.14478)
		(layer "In4.Cu")
		(net "M_D_CPU1_SB_DQ<24>")
	)
	(segment
		(start 54.532276 -309.448708)
		(end 54.532276 -309.678832)
		(width 0.14478)
		(layer "In4.Cu")
		(net "M_D_CPU1_SB_DQ<24>")
	)
	(segment
		(start 57.087516 -309.802784)
		(end 56.97093 -309.686198)
		(width 0.14478)
		(layer "In4.Cu")
		(net "M_D_CPU1_SB_DQ<24>")
	)
	(segment
		(start 78.897734 -288.9885)
		(end 78.913482 -288.979356)
		(width 0.0889)
		(layer "In4.Cu")
		(net "M_D_CPU1_SB_DQ<24>")
	)
	(segment
		(start 38.556184 -310.183022)
		(end 38.718998 -310.345836)
		(width 0.14478)
		(layer "In4.Cu")
		(net "M_D_CPU1_SB_DQ<24>")
	)
	(segment
		(start 57.134252 -309.293006)
		(end 58.071766 -309.293006)
		(width 0.14478)
		(layer "In4.Cu")
		(net "M_D_CPU1_SB_DQ<24>")
	)
	(segment
		(start 47.371762 -309.960518)
		(end 48.177958 -309.960518)
		(width 0.14478)
		(layer "In4.Cu")
		(net "M_D_CPU1_SB_DQ<24>")
	)
	(segment
		(start 39.50589 -309.685944)
		(end 39.780464 -309.960518)
		(width 0.14478)
		(layer "In4.Cu")
		(net "M_D_CPU1_SB_DQ<24>")
	)
	(segment
		(start 51.235102 -309.388764)
		(end 51.513486 -309.11038)
		(width 0.14478)
		(layer "In4.Cu")
		(net "M_D_CPU1_SB_DQ<24>")
	)
	(segment
		(start 38.39337 -309.685944)
		(end 38.556184 -309.848758)
		(width 0.14478)
		(layer "In4.Cu")
		(net "M_D_CPU1_SB_DQ<24>")
	)
	(segment
		(start 49.026572 -310.34482)
		(end 49.257204 -310.34482)
		(width 0.14478)
		(layer "In4.Cu")
		(net "M_D_CPU1_SB_DQ<24>")
	)
	(arc
		(start 78.71079 -289.0393)
		(mid 78.807608 -289.026229)
		(end 78.897734 -288.9885)
		(width 0.0889)
		(layer "In4.Cu")
		(net "M_D_CPU1_SB_DQ<24>")
	)
	(arc
		(start 84.163916 -288.988754)
		(mid 84.346167 -289.039104)
		(end 84.529676 -288.99358)
		(width 0.0889)
		(layer "In4.Cu")
		(net "M_D_CPU1_SB_DQ<24>")
	)
	(arc
		(start 87.923878 -288.988754)
		(mid 88.106129 -289.039104)
		(end 88.289638 -288.99358)
		(width 0.0889)
		(layer "In4.Cu")
		(net "M_D_CPU1_SB_DQ<24>")
	)
	(arc
		(start 90.178128 -288.988754)
		(mid 90.461084 -288.912577)
		(end 90.74404 -288.988754)
		(width 0.0889)
		(layer "In4.Cu")
		(net "M_D_CPU1_SB_DQ<24>")
	)
	(arc
		(start 82.65795 -288.988754)
		(mid 82.940906 -288.912577)
		(end 83.223862 -288.988754)
		(width 0.0889)
		(layer "In4.Cu")
		(net "M_D_CPU1_SB_DQ<24>")
	)
	(arc
		(start 89.238074 -288.988754)
		(mid 89.52103 -288.912577)
		(end 89.803986 -288.988754)
		(width 0.0889)
		(layer "In4.Cu")
		(net "M_D_CPU1_SB_DQ<24>")
	)
	(arc
		(start 88.863932 -288.988754)
		(mid 89.046183 -289.039104)
		(end 89.229692 -288.99358)
		(width 0.0889)
		(layer "In4.Cu")
		(net "M_D_CPU1_SB_DQ<24>")
	)
	(arc
		(start 84.538058 -288.988754)
		(mid 84.821014 -288.912577)
		(end 85.10397 -288.988754)
		(width 0.0889)
		(layer "In4.Cu")
		(net "M_D_CPU1_SB_DQ<24>")
	)
	(arc
		(start 85.478112 -288.988754)
		(mid 85.761068 -288.912577)
		(end 86.044024 -288.988754)
		(width 0.0889)
		(layer "In4.Cu")
		(net "M_D_CPU1_SB_DQ<24>")
	)
	(arc
		(start 85.112352 -288.99358)
		(mid 85.29586 -289.039074)
		(end 85.478112 -288.988754)
		(width 0.0889)
		(layer "In4.Cu")
		(net "M_D_CPU1_SB_DQ<24>")
	)
	(arc
		(start 79.838042 -288.988754)
		(mid 80.120998 -288.912577)
		(end 80.403954 -288.988754)
		(width 0.0889)
		(layer "In4.Cu")
		(net "M_D_CPU1_SB_DQ<24>")
	)
	(arc
		(start 86.984078 -288.988754)
		(mid 87.171022 -289.039009)
		(end 87.357966 -288.988754)
		(width 0.0889)
		(layer "In4.Cu")
		(net "M_D_CPU1_SB_DQ<24>")
	)
	(arc
		(start 78.913482 -288.979356)
		(mid 79.189791 -288.91238)
		(end 79.463646 -288.988754)
		(width 0.0889)
		(layer "In4.Cu")
		(net "M_D_CPU1_SB_DQ<24>")
	)
	(arc
		(start 80.403954 -288.988754)
		(mid 80.586205 -289.039104)
		(end 80.769714 -288.99358)
		(width 0.0889)
		(layer "In4.Cu")
		(net "M_D_CPU1_SB_DQ<24>")
	)
	(arc
		(start 82.284062 -288.988754)
		(mid 82.471006 -289.039009)
		(end 82.65795 -288.988754)
		(width 0.0889)
		(layer "In4.Cu")
		(net "M_D_CPU1_SB_DQ<24>")
	)
	(arc
		(start 79.463646 -288.988754)
		(mid 79.644104 -289.039198)
		(end 79.826358 -288.995612)
		(width 0.0889)
		(layer "In4.Cu")
		(net "M_D_CPU1_SB_DQ<24>")
	)
	(arc
		(start 81.35239 -288.99358)
		(mid 81.535898 -289.039074)
		(end 81.71815 -288.988754)
		(width 0.0889)
		(layer "In4.Cu")
		(net "M_D_CPU1_SB_DQ<24>")
	)
	(arc
		(start 86.418166 -288.988754)
		(mid 86.701122 -288.912577)
		(end 86.984078 -288.988754)
		(width 0.0889)
		(layer "In4.Cu")
		(net "M_D_CPU1_SB_DQ<24>")
	)
	(arc
		(start 81.71815 -288.988754)
		(mid 82.001106 -288.912577)
		(end 82.284062 -288.988754)
		(width 0.0889)
		(layer "In4.Cu")
		(net "M_D_CPU1_SB_DQ<24>")
	)
	(arc
		(start 88.29802 -288.988754)
		(mid 88.580976 -288.912577)
		(end 88.863932 -288.988754)
		(width 0.0889)
		(layer "In4.Cu")
		(net "M_D_CPU1_SB_DQ<24>")
	)
	(arc
		(start 83.598004 -288.988754)
		(mid 83.88096 -288.912577)
		(end 84.163916 -288.988754)
		(width 0.0889)
		(layer "In4.Cu")
		(net "M_D_CPU1_SB_DQ<24>")
	)
	(arc
		(start 86.052406 -288.99358)
		(mid 86.235914 -289.039074)
		(end 86.418166 -288.988754)
		(width 0.0889)
		(layer "In4.Cu")
		(net "M_D_CPU1_SB_DQ<24>")
	)
	(arc
		(start 89.812368 -288.99358)
		(mid 89.995876 -289.039074)
		(end 90.178128 -288.988754)
		(width 0.0889)
		(layer "In4.Cu")
		(net "M_D_CPU1_SB_DQ<24>")
	)
	(arc
		(start 80.778096 -288.988754)
		(mid 81.061052 -288.912577)
		(end 81.344008 -288.988754)
		(width 0.0889)
		(layer "In4.Cu")
		(net "M_D_CPU1_SB_DQ<24>")
	)
	(arc
		(start 90.752422 -288.99358)
		(mid 90.905292 -289.038221)
		(end 91.06281 -289.014916)
		(width 0.0889)
		(layer "In4.Cu")
		(net "M_D_CPU1_SB_DQ<24>")
	)
	(arc
		(start 83.223862 -288.988754)
		(mid 83.406113 -289.039104)
		(end 83.589622 -288.99358)
		(width 0.0889)
		(layer "In4.Cu")
		(net "M_D_CPU1_SB_DQ<24>")
	)
	(arc
		(start 87.357966 -288.988754)
		(mid 87.640922 -288.912577)
		(end 87.923878 -288.988754)
		(width 0.0889)
		(layer "In4.Cu")
		(net "M_D_CPU1_SB_DQ<24>")
	)
	(segment
		(start 93.277944 -288.400236)
		(end 92.811092 -288.666174)
		(width 0.10668)
		(layer "F.Cu")
		(net "M_D_CPU1_SB_DQ<23>")
	)
	(segment
		(start 70.923658 -297.191176)
		(end 70.923658 -296.109898)
		(width 0.14478)
		(layer "In4.Cu")
		(net "M_D_CPU1_SB_DQ<23>")
	)
	(segment
		(start 89.803986 -288.343848)
		(end 89.812368 -288.339022)
		(width 0.0889)
		(layer "In4.Cu")
		(net "M_D_CPU1_SB_DQ<23>")
	)
	(segment
		(start 77.62875 -288.775902)
		(end 77.98435 -288.420302)
		(width 0.0889)
		(layer "In4.Cu")
		(net "M_D_CPU1_SB_DQ<23>")
	)
	(segment
		(start 57.618122 -308.715156)
		(end 57.99963 -308.333648)
		(width 0.14478)
		(layer "In4.Cu")
		(net "M_D_CPU1_SB_DQ<23>")
	)
	(segment
		(start 90.74404 -288.343848)
		(end 90.752422 -288.339022)
		(width 0.0889)
		(layer "In4.Cu")
		(net "M_D_CPU1_SB_DQ<23>")
	)
	(segment
		(start 49.704498 -309.11038)
		(end 50.554636 -308.260242)
		(width 0.14478)
		(layer "In4.Cu")
		(net "M_D_CPU1_SB_DQ<23>")
	)
	(segment
		(start 33.120838 -309.11038)
		(end 42.38117 -309.11038)
		(width 0.14478)
		(layer "In4.Cu")
		(net "M_D_CPU1_SB_DQ<23>")
	)
	(segment
		(start 75.865736 -291.16782)
		(end 76.411836 -290.62172)
		(width 0.0889)
		(layer "In4.Cu")
		(net "M_D_CPU1_SB_DQ<23>")
	)
	(segment
		(start 57.99963 -308.333648)
		(end 59.965082 -307.942742)
		(width 0.14478)
		(layer "In4.Cu")
		(net "M_D_CPU1_SB_DQ<23>")
	)
	(segment
		(start 76.411836 -290.62172)
		(end 76.411836 -290.53282)
		(width 0.0889)
		(layer "In4.Cu")
		(net "M_D_CPU1_SB_DQ<23>")
	)
	(segment
		(start 59.965082 -307.942742)
		(end 60.31865 -307.796184)
		(width 0.14478)
		(layer "In4.Cu")
		(net "M_D_CPU1_SB_DQ<23>")
	)
	(segment
		(start 86.044024 -288.343848)
		(end 86.052406 -288.339022)
		(width 0.0889)
		(layer "In4.Cu")
		(net "M_D_CPU1_SB_DQ<23>")
	)
	(segment
		(start 50.554636 -308.260242)
		(end 53.288692 -308.260242)
		(width 0.14478)
		(layer "In4.Cu")
		(net "M_D_CPU1_SB_DQ<23>")
	)
	(segment
		(start 88.289638 -288.339022)
		(end 88.29802 -288.343848)
		(width 0.0889)
		(layer "In4.Cu")
		(net "M_D_CPU1_SB_DQ<23>")
	)
	(segment
		(start 53.743606 -308.715156)
		(end 57.618122 -308.715156)
		(width 0.14478)
		(layer "In4.Cu")
		(net "M_D_CPU1_SB_DQ<23>")
	)
	(segment
		(start 92.561156 -288.375344)
		(end 92.656914 -288.400744)
		(width 0.0889)
		(layer "In4.Cu")
		(net "M_D_CPU1_SB_DQ<23>")
	)
	(segment
		(start 46.294802 -309.11038)
		(end 49.704498 -309.11038)
		(width 0.14478)
		(layer "In4.Cu")
		(net "M_D_CPU1_SB_DQ<23>")
	)
	(segment
		(start 78.886304 -288.33699)
		(end 78.897988 -288.343848)
		(width 0.0889)
		(layer "In4.Cu")
		(net "M_D_CPU1_SB_DQ<23>")
	)
	(segment
		(start 43.231308 -308.260242)
		(end 45.444664 -308.260242)
		(width 0.14478)
		(layer "In4.Cu")
		(net "M_D_CPU1_SB_DQ<23>")
	)
	(segment
		(start 77.98435 -288.420302)
		(end 78.239874 -288.420302)
		(width 0.0889)
		(layer "In4.Cu")
		(net "M_D_CPU1_SB_DQ<23>")
	)
	(segment
		(start 60.31865 -307.796184)
		(end 70.923658 -297.191176)
		(width 0.14478)
		(layer "In4.Cu")
		(net "M_D_CPU1_SB_DQ<23>")
	)
	(segment
		(start 53.288692 -308.260242)
		(end 53.743606 -308.715156)
		(width 0.14478)
		(layer "In4.Cu")
		(net "M_D_CPU1_SB_DQ<23>")
	)
	(segment
		(start 85.10397 -288.343848)
		(end 85.112352 -288.339022)
		(width 0.0889)
		(layer "In4.Cu")
		(net "M_D_CPU1_SB_DQ<23>")
	)
	(segment
		(start 89.229692 -288.339022)
		(end 89.238074 -288.343848)
		(width 0.0889)
		(layer "In4.Cu")
		(net "M_D_CPU1_SB_DQ<23>")
	)
	(segment
		(start 92.656914 -288.400744)
		(end 92.811092 -288.666174)
		(width 0.0889)
		(layer "In4.Cu")
		(net "M_D_CPU1_SB_DQ<23>")
	)
	(segment
		(start 42.38117 -309.11038)
		(end 43.231308 -308.260242)
		(width 0.14478)
		(layer "In4.Cu")
		(net "M_D_CPU1_SB_DQ<23>")
	)
	(segment
		(start 80.769714 -288.339022)
		(end 80.778096 -288.343848)
		(width 0.0889)
		(layer "In4.Cu")
		(net "M_D_CPU1_SB_DQ<23>")
	)
	(segment
		(start 83.589622 -288.339022)
		(end 83.598004 -288.343848)
		(width 0.0889)
		(layer "In4.Cu")
		(net "M_D_CPU1_SB_DQ<23>")
	)
	(segment
		(start 84.529676 -288.339022)
		(end 84.538058 -288.343848)
		(width 0.0889)
		(layer "In4.Cu")
		(net "M_D_CPU1_SB_DQ<23>")
	)
	(segment
		(start 77.62875 -289.315906)
		(end 77.62875 -288.775902)
		(width 0.0889)
		(layer "In4.Cu")
		(net "M_D_CPU1_SB_DQ<23>")
	)
	(segment
		(start 45.444664 -308.260242)
		(end 46.294802 -309.11038)
		(width 0.14478)
		(layer "In4.Cu")
		(net "M_D_CPU1_SB_DQ<23>")
	)
	(segment
		(start 81.344008 -288.343848)
		(end 81.35239 -288.339022)
		(width 0.0889)
		(layer "In4.Cu")
		(net "M_D_CPU1_SB_DQ<23>")
	)
	(segment
		(start 70.923658 -296.109898)
		(end 75.865736 -291.16782)
		(width 0.14478)
		(layer "In4.Cu")
		(net "M_D_CPU1_SB_DQ<23>")
	)
	(segment
		(start 32.695896 -308.685438)
		(end 33.120838 -309.11038)
		(width 0.14478)
		(layer "In4.Cu")
		(net "M_D_CPU1_SB_DQ<23>")
	)
	(segment
		(start 76.411836 -290.53282)
		(end 77.62875 -289.315906)
		(width 0.0889)
		(layer "In4.Cu")
		(net "M_D_CPU1_SB_DQ<23>")
	)
	(segment
		(start 79.82966 -288.339022)
		(end 79.838042 -288.343848)
		(width 0.0889)
		(layer "In4.Cu")
		(net "M_D_CPU1_SB_DQ<23>")
	)
	(arc
		(start 91.118182 -288.343848)
		(mid 91.401138 -288.420025)
		(end 91.684094 -288.343848)
		(width 0.0889)
		(layer "In4.Cu")
		(net "M_D_CPU1_SB_DQ<23>")
	)
	(arc
		(start 80.403954 -288.343848)
		(mid 80.586205 -288.293464)
		(end 80.769714 -288.339022)
		(width 0.0889)
		(layer "In4.Cu")
		(net "M_D_CPU1_SB_DQ<23>")
	)
	(arc
		(start 79.838042 -288.343848)
		(mid 80.120998 -288.420025)
		(end 80.403954 -288.343848)
		(width 0.0889)
		(layer "In4.Cu")
		(net "M_D_CPU1_SB_DQ<23>")
	)
	(arc
		(start 87.357966 -288.343848)
		(mid 87.640922 -288.420025)
		(end 87.923878 -288.343848)
		(width 0.0889)
		(layer "In4.Cu")
		(net "M_D_CPU1_SB_DQ<23>")
	)
	(arc
		(start 88.29802 -288.343848)
		(mid 88.580976 -288.420025)
		(end 88.863932 -288.343848)
		(width 0.0889)
		(layer "In4.Cu")
		(net "M_D_CPU1_SB_DQ<23>")
	)
	(arc
		(start 86.052406 -288.339022)
		(mid 86.235914 -288.293497)
		(end 86.418166 -288.343848)
		(width 0.0889)
		(layer "In4.Cu")
		(net "M_D_CPU1_SB_DQ<23>")
	)
	(arc
		(start 86.984078 -288.343848)
		(mid 87.171022 -288.293559)
		(end 87.357966 -288.343848)
		(width 0.0889)
		(layer "In4.Cu")
		(net "M_D_CPU1_SB_DQ<23>")
	)
	(arc
		(start 85.478112 -288.343848)
		(mid 85.761068 -288.420025)
		(end 86.044024 -288.343848)
		(width 0.0889)
		(layer "In4.Cu")
		(net "M_D_CPU1_SB_DQ<23>")
	)
	(arc
		(start 80.778096 -288.343848)
		(mid 81.061052 -288.420025)
		(end 81.344008 -288.343848)
		(width 0.0889)
		(layer "In4.Cu")
		(net "M_D_CPU1_SB_DQ<23>")
	)
	(arc
		(start 88.863932 -288.343848)
		(mid 89.046183 -288.293464)
		(end 89.229692 -288.339022)
		(width 0.0889)
		(layer "In4.Cu")
		(net "M_D_CPU1_SB_DQ<23>")
	)
	(arc
		(start 84.538058 -288.343848)
		(mid 84.821014 -288.420025)
		(end 85.10397 -288.343848)
		(width 0.0889)
		(layer "In4.Cu")
		(net "M_D_CPU1_SB_DQ<23>")
	)
	(arc
		(start 81.35239 -288.339022)
		(mid 81.535898 -288.293497)
		(end 81.71815 -288.343848)
		(width 0.0889)
		(layer "In4.Cu")
		(net "M_D_CPU1_SB_DQ<23>")
	)
	(arc
		(start 82.284062 -288.343848)
		(mid 82.471006 -288.293559)
		(end 82.65795 -288.343848)
		(width 0.0889)
		(layer "In4.Cu")
		(net "M_D_CPU1_SB_DQ<23>")
	)
	(arc
		(start 83.598004 -288.343848)
		(mid 83.88096 -288.420025)
		(end 84.163916 -288.343848)
		(width 0.0889)
		(layer "In4.Cu")
		(net "M_D_CPU1_SB_DQ<23>")
	)
	(arc
		(start 87.923878 -288.343848)
		(mid 88.106129 -288.293464)
		(end 88.289638 -288.339022)
		(width 0.0889)
		(layer "In4.Cu")
		(net "M_D_CPU1_SB_DQ<23>")
	)
	(arc
		(start 81.71815 -288.343848)
		(mid 82.001106 -288.420025)
		(end 82.284062 -288.343848)
		(width 0.0889)
		(layer "In4.Cu")
		(net "M_D_CPU1_SB_DQ<23>")
	)
	(arc
		(start 85.112352 -288.339022)
		(mid 85.29586 -288.293497)
		(end 85.478112 -288.343848)
		(width 0.0889)
		(layer "In4.Cu")
		(net "M_D_CPU1_SB_DQ<23>")
	)
	(arc
		(start 89.812368 -288.339022)
		(mid 89.995876 -288.293497)
		(end 90.178128 -288.343848)
		(width 0.0889)
		(layer "In4.Cu")
		(net "M_D_CPU1_SB_DQ<23>")
	)
	(arc
		(start 78.239874 -288.420302)
		(mid 78.386805 -288.400891)
		(end 78.523592 -288.343848)
		(width 0.0889)
		(layer "In4.Cu")
		(net "M_D_CPU1_SB_DQ<23>")
	)
	(arc
		(start 82.65795 -288.343848)
		(mid 82.940906 -288.420025)
		(end 83.223862 -288.343848)
		(width 0.0889)
		(layer "In4.Cu")
		(net "M_D_CPU1_SB_DQ<23>")
	)
	(arc
		(start 92.057982 -288.343848)
		(mid 92.305842 -288.418931)
		(end 92.561156 -288.375344)
		(width 0.0889)
		(layer "In4.Cu")
		(net "M_D_CPU1_SB_DQ<23>")
	)
	(arc
		(start 91.684094 -288.343848)
		(mid 91.871038 -288.293559)
		(end 92.057982 -288.343848)
		(width 0.0889)
		(layer "In4.Cu")
		(net "M_D_CPU1_SB_DQ<23>")
	)
	(arc
		(start 90.752422 -288.339022)
		(mid 90.93593 -288.293497)
		(end 91.118182 -288.343848)
		(width 0.0889)
		(layer "In4.Cu")
		(net "M_D_CPU1_SB_DQ<23>")
	)
	(arc
		(start 78.897988 -288.343848)
		(mid 79.180944 -288.420025)
		(end 79.4639 -288.343848)
		(width 0.0889)
		(layer "In4.Cu")
		(net "M_D_CPU1_SB_DQ<23>")
	)
	(arc
		(start 78.523592 -288.343848)
		(mid 78.70405 -288.293369)
		(end 78.886304 -288.33699)
		(width 0.0889)
		(layer "In4.Cu")
		(net "M_D_CPU1_SB_DQ<23>")
	)
	(arc
		(start 89.238074 -288.343848)
		(mid 89.52103 -288.420025)
		(end 89.803986 -288.343848)
		(width 0.0889)
		(layer "In4.Cu")
		(net "M_D_CPU1_SB_DQ<23>")
	)
	(arc
		(start 83.223862 -288.343848)
		(mid 83.406113 -288.293464)
		(end 83.589622 -288.339022)
		(width 0.0889)
		(layer "In4.Cu")
		(net "M_D_CPU1_SB_DQ<23>")
	)
	(arc
		(start 84.163916 -288.343848)
		(mid 84.346167 -288.293464)
		(end 84.529676 -288.339022)
		(width 0.0889)
		(layer "In4.Cu")
		(net "M_D_CPU1_SB_DQ<23>")
	)
	(arc
		(start 86.418166 -288.343848)
		(mid 86.701122 -288.420025)
		(end 86.984078 -288.343848)
		(width 0.0889)
		(layer "In4.Cu")
		(net "M_D_CPU1_SB_DQ<23>")
	)
	(arc
		(start 90.178128 -288.343848)
		(mid 90.461084 -288.420025)
		(end 90.74404 -288.343848)
		(width 0.0889)
		(layer "In4.Cu")
		(net "M_D_CPU1_SB_DQ<23>")
	)
	(arc
		(start 79.4639 -288.343848)
		(mid 79.646151 -288.293464)
		(end 79.82966 -288.339022)
		(width 0.0889)
		(layer "In4.Cu")
		(net "M_D_CPU1_SB_DQ<23>")
	)
	(segment
		(start 91.86799 -287.590484)
		(end 91.401138 -287.856422)
		(width 0.10668)
		(layer "F.Cu")
		(net "M_D_CPU1_SB_DQ<22>")
	)
	(segment
		(start 90.639646 -287.529016)
		(end 90.648028 -287.533842)
		(width 0.0889)
		(layer "In4.Cu")
		(net "M_D_CPU1_SB_DQ<22>")
	)
	(segment
		(start 80.299814 -287.529016)
		(end 80.308196 -287.533842)
		(width 0.0889)
		(layer "In4.Cu")
		(net "M_D_CPU1_SB_DQ<22>")
	)
	(segment
		(start 83.694016 -287.533842)
		(end 83.702398 -287.529016)
		(width 0.0889)
		(layer "In4.Cu")
		(net "M_D_CPU1_SB_DQ<22>")
	)
	(segment
		(start 60.282582 -306.56022)
		(end 70.024498 -296.818304)
		(width 0.14478)
		(layer "In4.Cu")
		(net "M_D_CPU1_SB_DQ<22>")
	)
	(segment
		(start 35.540442 -306.416964)
		(end 35.703256 -306.579778)
		(width 0.14478)
		(layer "In4.Cu")
		(net "M_D_CPU1_SB_DQ<22>")
	)
	(segment
		(start 85.93963 -287.529016)
		(end 85.948012 -287.533842)
		(width 0.0889)
		(layer "In4.Cu")
		(net "M_D_CPU1_SB_DQ<22>")
	)
	(segment
		(start 53.725318 -307.410358)
		(end 57.429654 -307.410358)
		(width 0.14478)
		(layer "In4.Cu")
		(net "M_D_CPU1_SB_DQ<22>")
	)
	(segment
		(start 76.42987 -289.220402)
		(end 76.42987 -288.962592)
		(width 0.0889)
		(layer "In4.Cu")
		(net "M_D_CPU1_SB_DQ<22>")
	)
	(segment
		(start 79.367888 -287.533842)
		(end 79.385922 -287.544256)
		(width 0.0889)
		(layer "In4.Cu")
		(net "M_D_CPU1_SB_DQ<22>")
	)
	(segment
		(start 35.30981 -306.416964)
		(end 35.540442 -306.416964)
		(width 0.14478)
		(layer "In4.Cu")
		(net "M_D_CPU1_SB_DQ<22>")
	)
	(segment
		(start 57.429654 -307.410358)
		(end 58.279792 -306.56022)
		(width 0.14478)
		(layer "In4.Cu")
		(net "M_D_CPU1_SB_DQ<22>")
	)
	(segment
		(start 50.968148 -306.56022)
		(end 52.87518 -306.56022)
		(width 0.14478)
		(layer "In4.Cu")
		(net "M_D_CPU1_SB_DQ<22>")
	)
	(segment
		(start 87.453978 -287.533842)
		(end 87.46236 -287.529016)
		(width 0.0889)
		(layer "In4.Cu")
		(net "M_D_CPU1_SB_DQ<22>")
	)
	(segment
		(start 35.146996 -307.247544)
		(end 35.146996 -306.579778)
		(width 0.14478)
		(layer "In4.Cu")
		(net "M_D_CPU1_SB_DQ<22>")
	)
	(segment
		(start 86.879684 -287.529016)
		(end 86.888066 -287.533842)
		(width 0.0889)
		(layer "In4.Cu")
		(net "M_D_CPU1_SB_DQ<22>")
	)
	(segment
		(start 70.024498 -295.625774)
		(end 75.950318 -289.699954)
		(width 0.14478)
		(layer "In4.Cu")
		(net "M_D_CPU1_SB_DQ<22>")
	)
	(segment
		(start 46.119034 -307.410358)
		(end 50.11801 -307.410358)
		(width 0.14478)
		(layer "In4.Cu")
		(net "M_D_CPU1_SB_DQ<22>")
	)
	(segment
		(start 52.87518 -306.56022)
		(end 53.725318 -307.410358)
		(width 0.14478)
		(layer "In4.Cu")
		(net "M_D_CPU1_SB_DQ<22>")
	)
	(segment
		(start 45.268896 -306.56022)
		(end 46.119034 -307.410358)
		(width 0.14478)
		(layer "In4.Cu")
		(net "M_D_CPU1_SB_DQ<22>")
	)
	(segment
		(start 82.753962 -287.533842)
		(end 82.762344 -287.529016)
		(width 0.0889)
		(layer "In4.Cu")
		(net "M_D_CPU1_SB_DQ<22>")
	)
	(segment
		(start 91.24696 -287.590992)
		(end 91.401138 -287.856422)
		(width 0.0889)
		(layer "In4.Cu")
		(net "M_D_CPU1_SB_DQ<22>")
	)
	(segment
		(start 35.703256 -307.247544)
		(end 35.86607 -307.410358)
		(width 0.14478)
		(layer "In4.Cu")
		(net "M_D_CPU1_SB_DQ<22>")
	)
	(segment
		(start 34.984182 -307.410358)
		(end 35.146996 -307.247544)
		(width 0.14478)
		(layer "In4.Cu")
		(net "M_D_CPU1_SB_DQ<22>")
	)
	(segment
		(start 35.86607 -307.410358)
		(end 42.709338 -307.410358)
		(width 0.14478)
		(layer "In4.Cu")
		(net "M_D_CPU1_SB_DQ<22>")
	)
	(segment
		(start 91.150694 -287.565592)
		(end 91.24696 -287.590992)
		(width 0.0889)
		(layer "In4.Cu")
		(net "M_D_CPU1_SB_DQ<22>")
	)
	(segment
		(start 58.279792 -306.56022)
		(end 60.282582 -306.56022)
		(width 0.14478)
		(layer "In4.Cu")
		(net "M_D_CPU1_SB_DQ<22>")
	)
	(segment
		(start 32.695896 -306.985416)
		(end 33.120838 -307.410358)
		(width 0.14478)
		(layer "In4.Cu")
		(net "M_D_CPU1_SB_DQ<22>")
	)
	(segment
		(start 33.120838 -307.410358)
		(end 34.984182 -307.410358)
		(width 0.14478)
		(layer "In4.Cu")
		(net "M_D_CPU1_SB_DQ<22>")
	)
	(segment
		(start 77.869288 -287.610042)
		(end 78.711044 -287.610042)
		(width 0.0889)
		(layer "In4.Cu")
		(net "M_D_CPU1_SB_DQ<22>")
	)
	(segment
		(start 35.146996 -306.579778)
		(end 35.30981 -306.416964)
		(width 0.14478)
		(layer "In4.Cu")
		(net "M_D_CPU1_SB_DQ<22>")
	)
	(segment
		(start 43.559476 -306.56022)
		(end 45.268896 -306.56022)
		(width 0.14478)
		(layer "In4.Cu")
		(net "M_D_CPU1_SB_DQ<22>")
	)
	(segment
		(start 75.950318 -289.699954)
		(end 76.42987 -289.220402)
		(width 0.0889)
		(layer "In4.Cu")
		(net "M_D_CPU1_SB_DQ<22>")
	)
	(segment
		(start 35.703256 -306.579778)
		(end 35.703256 -307.247544)
		(width 0.14478)
		(layer "In4.Cu")
		(net "M_D_CPU1_SB_DQ<22>")
	)
	(segment
		(start 77.329284 -288.150046)
		(end 77.869288 -287.610042)
		(width 0.0889)
		(layer "In4.Cu")
		(net "M_D_CPU1_SB_DQ<22>")
	)
	(segment
		(start 88.394032 -287.533842)
		(end 88.402414 -287.529016)
		(width 0.0889)
		(layer "In4.Cu")
		(net "M_D_CPU1_SB_DQ<22>")
	)
	(segment
		(start 82.179668 -287.529016)
		(end 82.18805 -287.533842)
		(width 0.0889)
		(layer "In4.Cu")
		(net "M_D_CPU1_SB_DQ<22>")
	)
	(segment
		(start 42.709338 -307.410358)
		(end 43.559476 -306.56022)
		(width 0.14478)
		(layer "In4.Cu")
		(net "M_D_CPU1_SB_DQ<22>")
	)
	(segment
		(start 50.11801 -307.410358)
		(end 50.968148 -306.56022)
		(width 0.14478)
		(layer "In4.Cu")
		(net "M_D_CPU1_SB_DQ<22>")
	)
	(segment
		(start 70.024498 -296.818304)
		(end 70.024498 -295.625774)
		(width 0.14478)
		(layer "In4.Cu")
		(net "M_D_CPU1_SB_DQ<22>")
	)
	(segment
		(start 77.242416 -288.150046)
		(end 77.329284 -288.150046)
		(width 0.0889)
		(layer "In4.Cu")
		(net "M_D_CPU1_SB_DQ<22>")
	)
	(segment
		(start 76.42987 -288.962592)
		(end 77.242416 -288.150046)
		(width 0.0889)
		(layer "In4.Cu")
		(net "M_D_CPU1_SB_DQ<22>")
	)
	(arc
		(start 90.648028 -287.533842)
		(mid 90.895625 -287.608986)
		(end 91.150694 -287.565592)
		(width 0.0889)
		(layer "In4.Cu")
		(net "M_D_CPU1_SB_DQ<22>")
	)
	(arc
		(start 84.63407 -287.533842)
		(mid 84.821014 -287.483587)
		(end 85.007958 -287.533842)
		(width 0.0889)
		(layer "In4.Cu")
		(net "M_D_CPU1_SB_DQ<22>")
	)
	(arc
		(start 81.247996 -287.533842)
		(mid 81.530952 -287.609985)
		(end 81.813908 -287.533842)
		(width 0.0889)
		(layer "In4.Cu")
		(net "M_D_CPU1_SB_DQ<22>")
	)
	(arc
		(start 80.308196 -287.533842)
		(mid 80.591152 -287.609985)
		(end 80.874108 -287.533842)
		(width 0.0889)
		(layer "In4.Cu")
		(net "M_D_CPU1_SB_DQ<22>")
	)
	(arc
		(start 79.385922 -287.544256)
		(mid 79.66108 -287.609986)
		(end 79.933546 -287.533842)
		(width 0.0889)
		(layer "In4.Cu")
		(net "M_D_CPU1_SB_DQ<22>")
	)
	(arc
		(start 82.18805 -287.533842)
		(mid 82.471006 -287.609985)
		(end 82.753962 -287.533842)
		(width 0.0889)
		(layer "In4.Cu")
		(net "M_D_CPU1_SB_DQ<22>")
	)
	(arc
		(start 83.702398 -287.529016)
		(mid 83.885906 -287.483522)
		(end 84.068158 -287.533842)
		(width 0.0889)
		(layer "In4.Cu")
		(net "M_D_CPU1_SB_DQ<22>")
	)
	(arc
		(start 84.068158 -287.533842)
		(mid 84.351114 -287.609985)
		(end 84.63407 -287.533842)
		(width 0.0889)
		(layer "In4.Cu")
		(net "M_D_CPU1_SB_DQ<22>")
	)
	(arc
		(start 83.128104 -287.533842)
		(mid 83.41106 -287.609985)
		(end 83.694016 -287.533842)
		(width 0.0889)
		(layer "In4.Cu")
		(net "M_D_CPU1_SB_DQ<22>")
	)
	(arc
		(start 87.82812 -287.533842)
		(mid 88.111076 -287.609985)
		(end 88.394032 -287.533842)
		(width 0.0889)
		(layer "In4.Cu")
		(net "M_D_CPU1_SB_DQ<22>")
	)
	(arc
		(start 85.57387 -287.533842)
		(mid 85.756121 -287.483492)
		(end 85.93963 -287.529016)
		(width 0.0889)
		(layer "In4.Cu")
		(net "M_D_CPU1_SB_DQ<22>")
	)
	(arc
		(start 80.874108 -287.533842)
		(mid 81.061052 -287.483587)
		(end 81.247996 -287.533842)
		(width 0.0889)
		(layer "In4.Cu")
		(net "M_D_CPU1_SB_DQ<22>")
	)
	(arc
		(start 79.933546 -287.533842)
		(mid 80.116051 -287.483365)
		(end 80.299814 -287.529016)
		(width 0.0889)
		(layer "In4.Cu")
		(net "M_D_CPU1_SB_DQ<22>")
	)
	(arc
		(start 81.813908 -287.533842)
		(mid 81.996159 -287.483492)
		(end 82.179668 -287.529016)
		(width 0.0889)
		(layer "In4.Cu")
		(net "M_D_CPU1_SB_DQ<22>")
	)
	(arc
		(start 90.273886 -287.533842)
		(mid 90.456137 -287.483492)
		(end 90.639646 -287.529016)
		(width 0.0889)
		(layer "In4.Cu")
		(net "M_D_CPU1_SB_DQ<22>")
	)
	(arc
		(start 78.711044 -287.610042)
		(mid 78.85757 -287.590672)
		(end 78.994 -287.533842)
		(width 0.0889)
		(layer "In4.Cu")
		(net "M_D_CPU1_SB_DQ<22>")
	)
	(arc
		(start 89.707974 -287.533842)
		(mid 89.99093 -287.609985)
		(end 90.273886 -287.533842)
		(width 0.0889)
		(layer "In4.Cu")
		(net "M_D_CPU1_SB_DQ<22>")
	)
	(arc
		(start 89.334086 -287.533842)
		(mid 89.52103 -287.483587)
		(end 89.707974 -287.533842)
		(width 0.0889)
		(layer "In4.Cu")
		(net "M_D_CPU1_SB_DQ<22>")
	)
	(arc
		(start 82.762344 -287.529016)
		(mid 82.945852 -287.483522)
		(end 83.128104 -287.533842)
		(width 0.0889)
		(layer "In4.Cu")
		(net "M_D_CPU1_SB_DQ<22>")
	)
	(arc
		(start 85.948012 -287.533842)
		(mid 86.230968 -287.609985)
		(end 86.513924 -287.533842)
		(width 0.0889)
		(layer "In4.Cu")
		(net "M_D_CPU1_SB_DQ<22>")
	)
	(arc
		(start 86.513924 -287.533842)
		(mid 86.696175 -287.483492)
		(end 86.879684 -287.529016)
		(width 0.0889)
		(layer "In4.Cu")
		(net "M_D_CPU1_SB_DQ<22>")
	)
	(arc
		(start 88.402414 -287.529016)
		(mid 88.585922 -287.483522)
		(end 88.768174 -287.533842)
		(width 0.0889)
		(layer "In4.Cu")
		(net "M_D_CPU1_SB_DQ<22>")
	)
	(arc
		(start 88.768174 -287.533842)
		(mid 89.05113 -287.609985)
		(end 89.334086 -287.533842)
		(width 0.0889)
		(layer "In4.Cu")
		(net "M_D_CPU1_SB_DQ<22>")
	)
	(arc
		(start 86.888066 -287.533842)
		(mid 87.171022 -287.609985)
		(end 87.453978 -287.533842)
		(width 0.0889)
		(layer "In4.Cu")
		(net "M_D_CPU1_SB_DQ<22>")
	)
	(arc
		(start 78.994 -287.533842)
		(mid 79.180944 -287.483587)
		(end 79.367888 -287.533842)
		(width 0.0889)
		(layer "In4.Cu")
		(net "M_D_CPU1_SB_DQ<22>")
	)
	(arc
		(start 85.007958 -287.533842)
		(mid 85.290914 -287.609985)
		(end 85.57387 -287.533842)
		(width 0.0889)
		(layer "In4.Cu")
		(net "M_D_CPU1_SB_DQ<22>")
	)
	(arc
		(start 87.46236 -287.529016)
		(mid 87.645868 -287.483522)
		(end 87.82812 -287.533842)
		(width 0.0889)
		(layer "In4.Cu")
		(net "M_D_CPU1_SB_DQ<22>")
	)
	(segment
		(start 92.80779 -287.590484)
		(end 92.340938 -287.856422)
		(width 0.10668)
		(layer "F.Cu")
		(net "M_D_CPU1_SB_DQ<21>")
	)
	(segment
		(start 43.398948 -307.410358)
		(end 45.45838 -307.410358)
		(width 0.14478)
		(layer "In4.Cu")
		(net "M_D_CPU1_SB_DQ<21>")
	)
	(segment
		(start 42.153586 -308.65572)
		(end 43.398948 -307.410358)
		(width 0.14478)
		(layer "In4.Cu")
		(net "M_D_CPU1_SB_DQ<21>")
	)
	(segment
		(start 76.71435 -289.57905)
		(end 76.71435 -289.026346)
		(width 0.0889)
		(layer "In4.Cu")
		(net "M_D_CPU1_SB_DQ<21>")
	)
	(segment
		(start 70.474078 -295.819322)
		(end 75.95108 -290.34232)
		(width 0.14478)
		(layer "In4.Cu")
		(net "M_D_CPU1_SB_DQ<21>")
	)
	(segment
		(start 48.644556 -308.260496)
		(end 49.040034 -307.865018)
		(width 0.14478)
		(layer "In4.Cu")
		(net "M_D_CPU1_SB_DQ<21>")
	)
	(segment
		(start 60.06846 -307.410358)
		(end 70.474078 -297.00474)
		(width 0.14478)
		(layer "In4.Cu")
		(net "M_D_CPU1_SB_DQ<21>")
	)
	(segment
		(start 82.179668 -288.183574)
		(end 82.18805 -288.178748)
		(width 0.0889)
		(layer "In4.Cu")
		(net "M_D_CPU1_SB_DQ<21>")
	)
	(segment
		(start 39.118794 -308.492906)
		(end 39.118794 -308.027832)
		(width 0.14478)
		(layer "In4.Cu")
		(net "M_D_CPU1_SB_DQ<21>")
	)
	(segment
		(start 90.639646 -288.183574)
		(end 90.648028 -288.178748)
		(width 0.0889)
		(layer "In4.Cu")
		(net "M_D_CPU1_SB_DQ<21>")
	)
	(segment
		(start 49.911254 -308.260496)
		(end 50.761392 -307.410358)
		(width 0.14478)
		(layer "In4.Cu")
		(net "M_D_CPU1_SB_DQ<21>")
	)
	(segment
		(start 38.006274 -308.031642)
		(end 38.169088 -307.868828)
		(width 0.14478)
		(layer "In4.Cu")
		(net "M_D_CPU1_SB_DQ<21>")
	)
	(segment
		(start 88.394032 -288.178748)
		(end 88.402414 -288.183574)
		(width 0.0889)
		(layer "In4.Cu")
		(net "M_D_CPU1_SB_DQ<21>")
	)
	(segment
		(start 37.84346 -308.652164)
		(end 38.006274 -308.48935)
		(width 0.14478)
		(layer "In4.Cu")
		(net "M_D_CPU1_SB_DQ<21>")
	)
	(segment
		(start 37.612828 -308.652164)
		(end 37.84346 -308.652164)
		(width 0.14478)
		(layer "In4.Cu")
		(net "M_D_CPU1_SB_DQ<21>")
	)
	(segment
		(start 41.76014 -308.492906)
		(end 41.922954 -308.65572)
		(width 0.14478)
		(layer "In4.Cu")
		(net "M_D_CPU1_SB_DQ<21>")
	)
	(segment
		(start 38.169088 -307.868828)
		(end 38.39972 -307.868828)
		(width 0.14478)
		(layer "In4.Cu")
		(net "M_D_CPU1_SB_DQ<21>")
	)
	(segment
		(start 38.562534 -308.031642)
		(end 38.562534 -308.492906)
		(width 0.14478)
		(layer "In4.Cu")
		(net "M_D_CPU1_SB_DQ<21>")
	)
	(segment
		(start 53.081936 -307.410358)
		(end 53.932074 -308.260496)
		(width 0.14478)
		(layer "In4.Cu")
		(net "M_D_CPU1_SB_DQ<21>")
	)
	(segment
		(start 40.41521 -308.260496)
		(end 40.810434 -308.65572)
		(width 0.14478)
		(layer "In4.Cu")
		(net "M_D_CPU1_SB_DQ<21>")
	)
	(segment
		(start 85.93963 -288.183574)
		(end 85.948012 -288.178748)
		(width 0.0889)
		(layer "In4.Cu")
		(net "M_D_CPU1_SB_DQ<21>")
	)
	(segment
		(start 92.153994 -288.178748)
		(end 92.162376 -288.183574)
		(width 0.0889)
		(layer "In4.Cu")
		(net "M_D_CPU1_SB_DQ<21>")
	)
	(segment
		(start 39.118794 -308.027832)
		(end 39.281608 -307.865018)
		(width 0.14478)
		(layer "In4.Cu")
		(net "M_D_CPU1_SB_DQ<21>")
	)
	(segment
		(start 79.934054 -288.178748)
		(end 79.942436 -288.183574)
		(width 0.0889)
		(layer "In4.Cu")
		(net "M_D_CPU1_SB_DQ<21>")
	)
	(segment
		(start 49.040034 -307.865018)
		(end 49.270666 -307.865018)
		(width 0.14478)
		(layer "In4.Cu")
		(net "M_D_CPU1_SB_DQ<21>")
	)
	(segment
		(start 86.879684 -288.183574)
		(end 86.888066 -288.178748)
		(width 0.0889)
		(layer "In4.Cu")
		(net "M_D_CPU1_SB_DQ<21>")
	)
	(segment
		(start 50.761392 -307.410358)
		(end 53.081936 -307.410358)
		(width 0.14478)
		(layer "In4.Cu")
		(net "M_D_CPU1_SB_DQ<21>")
	)
	(segment
		(start 38.006274 -308.48935)
		(end 38.006274 -308.031642)
		(width 0.14478)
		(layer "In4.Cu")
		(net "M_D_CPU1_SB_DQ<21>")
	)
	(segment
		(start 78.994 -288.178748)
		(end 79.002382 -288.183574)
		(width 0.0889)
		(layer "In4.Cu")
		(net "M_D_CPU1_SB_DQ<21>")
	)
	(segment
		(start 78.979268 -288.170112)
		(end 78.994 -288.178748)
		(width 0.0889)
		(layer "In4.Cu")
		(net "M_D_CPU1_SB_DQ<21>")
	)
	(segment
		(start 75.95108 -290.34232)
		(end 76.71435 -289.57905)
		(width 0.0889)
		(layer "In4.Cu")
		(net "M_D_CPU1_SB_DQ<21>")
	)
	(segment
		(start 58.279792 -307.410358)
		(end 60.06846 -307.410358)
		(width 0.14478)
		(layer "In4.Cu")
		(net "M_D_CPU1_SB_DQ<21>")
	)
	(segment
		(start 46.308518 -308.260496)
		(end 48.644556 -308.260496)
		(width 0.14478)
		(layer "In4.Cu")
		(net "M_D_CPU1_SB_DQ<21>")
	)
	(segment
		(start 87.453978 -288.178748)
		(end 87.46236 -288.183574)
		(width 0.0889)
		(layer "In4.Cu")
		(net "M_D_CPU1_SB_DQ<21>")
	)
	(segment
		(start 76.71435 -289.026346)
		(end 77.40015 -288.340546)
		(width 0.0889)
		(layer "In4.Cu")
		(net "M_D_CPU1_SB_DQ<21>")
	)
	(segment
		(start 41.20388 -308.027832)
		(end 41.366694 -307.865018)
		(width 0.14478)
		(layer "In4.Cu")
		(net "M_D_CPU1_SB_DQ<21>")
	)
	(segment
		(start 77.40015 -288.340546)
		(end 77.67193 -288.340546)
		(width 0.0889)
		(layer "In4.Cu")
		(net "M_D_CPU1_SB_DQ<21>")
	)
	(segment
		(start 38.725348 -308.65572)
		(end 38.95598 -308.65572)
		(width 0.14478)
		(layer "In4.Cu")
		(net "M_D_CPU1_SB_DQ<21>")
	)
	(segment
		(start 41.597326 -307.865018)
		(end 41.76014 -308.027832)
		(width 0.14478)
		(layer "In4.Cu")
		(net "M_D_CPU1_SB_DQ<21>")
	)
	(segment
		(start 91.5797 -288.183574)
		(end 91.588082 -288.178748)
		(width 0.0889)
		(layer "In4.Cu")
		(net "M_D_CPU1_SB_DQ<21>")
	)
	(segment
		(start 53.932074 -308.260496)
		(end 57.429654 -308.260496)
		(width 0.14478)
		(layer "In4.Cu")
		(net "M_D_CPU1_SB_DQ<21>")
	)
	(segment
		(start 39.907718 -308.260496)
		(end 40.41521 -308.260496)
		(width 0.14478)
		(layer "In4.Cu")
		(net "M_D_CPU1_SB_DQ<21>")
	)
	(segment
		(start 39.281608 -307.865018)
		(end 39.51224 -307.865018)
		(width 0.14478)
		(layer "In4.Cu")
		(net "M_D_CPU1_SB_DQ<21>")
	)
	(segment
		(start 83.694016 -288.178748)
		(end 83.702398 -288.183574)
		(width 0.0889)
		(layer "In4.Cu")
		(net "M_D_CPU1_SB_DQ<21>")
	)
	(segment
		(start 38.39972 -307.868828)
		(end 38.562534 -308.031642)
		(width 0.14478)
		(layer "In4.Cu")
		(net "M_D_CPU1_SB_DQ<21>")
	)
	(segment
		(start 36.795964 -307.8353)
		(end 37.612828 -308.652164)
		(width 0.14478)
		(layer "In4.Cu")
		(net "M_D_CPU1_SB_DQ<21>")
	)
	(segment
		(start 39.51224 -307.865018)
		(end 39.907718 -308.260496)
		(width 0.14478)
		(layer "In4.Cu")
		(net "M_D_CPU1_SB_DQ<21>")
	)
	(segment
		(start 70.474078 -297.00474)
		(end 70.474078 -295.819322)
		(width 0.14478)
		(layer "In4.Cu")
		(net "M_D_CPU1_SB_DQ<21>")
	)
	(segment
		(start 77.782674 -288.229802)
		(end 78.239874 -288.229802)
		(width 0.0889)
		(layer "In4.Cu")
		(net "M_D_CPU1_SB_DQ<21>")
	)
	(segment
		(start 38.95598 -308.65572)
		(end 39.118794 -308.492906)
		(width 0.14478)
		(layer "In4.Cu")
		(net "M_D_CPU1_SB_DQ<21>")
	)
	(segment
		(start 92.473018 -288.20491)
		(end 92.495116 -288.121852)
		(width 0.0889)
		(layer "In4.Cu")
		(net "M_D_CPU1_SB_DQ<21>")
	)
	(segment
		(start 82.753962 -288.178748)
		(end 82.762344 -288.183574)
		(width 0.0889)
		(layer "In4.Cu")
		(net "M_D_CPU1_SB_DQ<21>")
	)
	(segment
		(start 77.67193 -288.340546)
		(end 77.782674 -288.229802)
		(width 0.0889)
		(layer "In4.Cu")
		(net "M_D_CPU1_SB_DQ<21>")
	)
	(segment
		(start 92.495116 -288.121852)
		(end 92.340938 -287.856422)
		(width 0.0889)
		(layer "In4.Cu")
		(net "M_D_CPU1_SB_DQ<21>")
	)
	(segment
		(start 49.666144 -308.260496)
		(end 49.911254 -308.260496)
		(width 0.14478)
		(layer "In4.Cu")
		(net "M_D_CPU1_SB_DQ<21>")
	)
	(segment
		(start 41.366694 -307.865018)
		(end 41.597326 -307.865018)
		(width 0.14478)
		(layer "In4.Cu")
		(net "M_D_CPU1_SB_DQ<21>")
	)
	(segment
		(start 49.270666 -307.865018)
		(end 49.666144 -308.260496)
		(width 0.14478)
		(layer "In4.Cu")
		(net "M_D_CPU1_SB_DQ<21>")
	)
	(segment
		(start 45.45838 -307.410358)
		(end 46.308518 -308.260496)
		(width 0.14478)
		(layer "In4.Cu")
		(net "M_D_CPU1_SB_DQ<21>")
	)
	(segment
		(start 40.810434 -308.65572)
		(end 41.041066 -308.65572)
		(width 0.14478)
		(layer "In4.Cu")
		(net "M_D_CPU1_SB_DQ<21>")
	)
	(segment
		(start 57.429654 -308.260496)
		(end 58.279792 -307.410358)
		(width 0.14478)
		(layer "In4.Cu")
		(net "M_D_CPU1_SB_DQ<21>")
	)
	(segment
		(start 41.041066 -308.65572)
		(end 41.20388 -308.492906)
		(width 0.14478)
		(layer "In4.Cu")
		(net "M_D_CPU1_SB_DQ<21>")
	)
	(segment
		(start 41.76014 -308.027832)
		(end 41.76014 -308.492906)
		(width 0.14478)
		(layer "In4.Cu")
		(net "M_D_CPU1_SB_DQ<21>")
	)
	(segment
		(start 41.922954 -308.65572)
		(end 42.153586 -308.65572)
		(width 0.14478)
		(layer "In4.Cu")
		(net "M_D_CPU1_SB_DQ<21>")
	)
	(segment
		(start 41.20388 -308.492906)
		(end 41.20388 -308.027832)
		(width 0.14478)
		(layer "In4.Cu")
		(net "M_D_CPU1_SB_DQ<21>")
	)
	(segment
		(start 38.562534 -308.492906)
		(end 38.725348 -308.65572)
		(width 0.14478)
		(layer "In4.Cu")
		(net "M_D_CPU1_SB_DQ<21>")
	)
	(arc
		(start 78.239874 -288.229802)
		(mid 78.337105 -288.216705)
		(end 78.42758 -288.178748)
		(width 0.0889)
		(layer "In4.Cu")
		(net "M_D_CPU1_SB_DQ<21>")
	)
	(arc
		(start 88.402414 -288.183574)
		(mid 88.585922 -288.229099)
		(end 88.768174 -288.178748)
		(width 0.0889)
		(layer "In4.Cu")
		(net "M_D_CPU1_SB_DQ<21>")
	)
	(arc
		(start 90.648028 -288.178748)
		(mid 90.930984 -288.102571)
		(end 91.21394 -288.178748)
		(width 0.0889)
		(layer "In4.Cu")
		(net "M_D_CPU1_SB_DQ<21>")
	)
	(arc
		(start 85.007958 -288.178748)
		(mid 85.290914 -288.102571)
		(end 85.57387 -288.178748)
		(width 0.0889)
		(layer "In4.Cu")
		(net "M_D_CPU1_SB_DQ<21>")
	)
	(arc
		(start 81.247996 -288.178748)
		(mid 81.530952 -288.102571)
		(end 81.813908 -288.178748)
		(width 0.0889)
		(layer "In4.Cu")
		(net "M_D_CPU1_SB_DQ<21>")
	)
	(arc
		(start 80.874108 -288.178748)
		(mid 81.061052 -288.229037)
		(end 81.247996 -288.178748)
		(width 0.0889)
		(layer "In4.Cu")
		(net "M_D_CPU1_SB_DQ<21>")
	)
	(arc
		(start 86.888066 -288.178748)
		(mid 87.171022 -288.102571)
		(end 87.453978 -288.178748)
		(width 0.0889)
		(layer "In4.Cu")
		(net "M_D_CPU1_SB_DQ<21>")
	)
	(arc
		(start 83.702398 -288.183574)
		(mid 83.885906 -288.229099)
		(end 84.068158 -288.178748)
		(width 0.0889)
		(layer "In4.Cu")
		(net "M_D_CPU1_SB_DQ<21>")
	)
	(arc
		(start 89.707974 -288.178748)
		(mid 89.99093 -288.102571)
		(end 90.273886 -288.178748)
		(width 0.0889)
		(layer "In4.Cu")
		(net "M_D_CPU1_SB_DQ<21>")
	)
	(arc
		(start 92.162376 -288.183574)
		(mid 92.315364 -288.228254)
		(end 92.473018 -288.20491)
		(width 0.0889)
		(layer "In4.Cu")
		(net "M_D_CPU1_SB_DQ<21>")
	)
	(arc
		(start 78.42758 -288.178748)
		(mid 78.702286 -288.102384)
		(end 78.979268 -288.170112)
		(width 0.0889)
		(layer "In4.Cu")
		(net "M_D_CPU1_SB_DQ<21>")
	)
	(arc
		(start 85.948012 -288.178748)
		(mid 86.230968 -288.102571)
		(end 86.513924 -288.178748)
		(width 0.0889)
		(layer "In4.Cu")
		(net "M_D_CPU1_SB_DQ<21>")
	)
	(arc
		(start 80.308196 -288.178748)
		(mid 80.591152 -288.102571)
		(end 80.874108 -288.178748)
		(width 0.0889)
		(layer "In4.Cu")
		(net "M_D_CPU1_SB_DQ<21>")
	)
	(arc
		(start 91.21394 -288.178748)
		(mid 91.396191 -288.229132)
		(end 91.5797 -288.183574)
		(width 0.0889)
		(layer "In4.Cu")
		(net "M_D_CPU1_SB_DQ<21>")
	)
	(arc
		(start 79.368142 -288.178748)
		(mid 79.651098 -288.102571)
		(end 79.934054 -288.178748)
		(width 0.0889)
		(layer "In4.Cu")
		(net "M_D_CPU1_SB_DQ<21>")
	)
	(arc
		(start 86.513924 -288.178748)
		(mid 86.696175 -288.229132)
		(end 86.879684 -288.183574)
		(width 0.0889)
		(layer "In4.Cu")
		(net "M_D_CPU1_SB_DQ<21>")
	)
	(arc
		(start 87.82812 -288.178748)
		(mid 88.111076 -288.102571)
		(end 88.394032 -288.178748)
		(width 0.0889)
		(layer "In4.Cu")
		(net "M_D_CPU1_SB_DQ<21>")
	)
	(arc
		(start 83.128104 -288.178748)
		(mid 83.41106 -288.102571)
		(end 83.694016 -288.178748)
		(width 0.0889)
		(layer "In4.Cu")
		(net "M_D_CPU1_SB_DQ<21>")
	)
	(arc
		(start 84.068158 -288.178748)
		(mid 84.351114 -288.102571)
		(end 84.63407 -288.178748)
		(width 0.0889)
		(layer "In4.Cu")
		(net "M_D_CPU1_SB_DQ<21>")
	)
	(arc
		(start 84.63407 -288.178748)
		(mid 84.821014 -288.229037)
		(end 85.007958 -288.178748)
		(width 0.0889)
		(layer "In4.Cu")
		(net "M_D_CPU1_SB_DQ<21>")
	)
	(arc
		(start 79.942436 -288.183574)
		(mid 80.125944 -288.229099)
		(end 80.308196 -288.178748)
		(width 0.0889)
		(layer "In4.Cu")
		(net "M_D_CPU1_SB_DQ<21>")
	)
	(arc
		(start 90.273886 -288.178748)
		(mid 90.456137 -288.229132)
		(end 90.639646 -288.183574)
		(width 0.0889)
		(layer "In4.Cu")
		(net "M_D_CPU1_SB_DQ<21>")
	)
	(arc
		(start 87.46236 -288.183574)
		(mid 87.645868 -288.229099)
		(end 87.82812 -288.178748)
		(width 0.0889)
		(layer "In4.Cu")
		(net "M_D_CPU1_SB_DQ<21>")
	)
	(arc
		(start 82.762344 -288.183574)
		(mid 82.945852 -288.229099)
		(end 83.128104 -288.178748)
		(width 0.0889)
		(layer "In4.Cu")
		(net "M_D_CPU1_SB_DQ<21>")
	)
	(arc
		(start 88.768174 -288.178748)
		(mid 89.05113 -288.102571)
		(end 89.334086 -288.178748)
		(width 0.0889)
		(layer "In4.Cu")
		(net "M_D_CPU1_SB_DQ<21>")
	)
	(arc
		(start 79.002382 -288.183574)
		(mid 79.18589 -288.229099)
		(end 79.368142 -288.178748)
		(width 0.0889)
		(layer "In4.Cu")
		(net "M_D_CPU1_SB_DQ<21>")
	)
	(arc
		(start 89.334086 -288.178748)
		(mid 89.52103 -288.229037)
		(end 89.707974 -288.178748)
		(width 0.0889)
		(layer "In4.Cu")
		(net "M_D_CPU1_SB_DQ<21>")
	)
	(arc
		(start 85.57387 -288.178748)
		(mid 85.756121 -288.229132)
		(end 85.93963 -288.183574)
		(width 0.0889)
		(layer "In4.Cu")
		(net "M_D_CPU1_SB_DQ<21>")
	)
	(arc
		(start 82.18805 -288.178748)
		(mid 82.471006 -288.102571)
		(end 82.753962 -288.178748)
		(width 0.0889)
		(layer "In4.Cu")
		(net "M_D_CPU1_SB_DQ<21>")
	)
	(arc
		(start 91.588082 -288.178748)
		(mid 91.871038 -288.102571)
		(end 92.153994 -288.178748)
		(width 0.0889)
		(layer "In4.Cu")
		(net "M_D_CPU1_SB_DQ<21>")
	)
	(arc
		(start 81.813908 -288.178748)
		(mid 81.996159 -288.229132)
		(end 82.179668 -288.183574)
		(width 0.0889)
		(layer "In4.Cu")
		(net "M_D_CPU1_SB_DQ<21>")
	)
	(segment
		(start 91.397836 -286.780478)
		(end 90.930984 -287.046162)
		(width 0.10668)
		(layer "F.Cu")
		(net "M_D_CPU1_SB_DQ<20>")
	)
	(segment
		(start 80.769714 -287.373568)
		(end 80.778096 -287.368742)
		(width 0.0889)
		(layer "In4.Cu")
		(net "M_D_CPU1_SB_DQ<20>")
	)
	(segment
		(start 56.718962 -306.560474)
		(end 57.63641 -306.560474)
		(width 0.14478)
		(layer "In4.Cu")
		(net "M_D_CPU1_SB_DQ<20>")
	)
	(segment
		(start 59.789314 -306.10556)
		(end 60.101226 -306.10556)
		(width 0.14478)
		(layer "In4.Cu")
		(net "M_D_CPU1_SB_DQ<20>")
	)
	(segment
		(start 48.688498 -306.877466)
		(end 49.002188 -306.563776)
		(width 0.14478)
		(layer "In4.Cu")
		(net "M_D_CPU1_SB_DQ<20>")
	)
	(segment
		(start 38.090602 -306.789328)
		(end 38.090602 -306.55387)
		(width 0.14478)
		(layer "In4.Cu")
		(net "M_D_CPU1_SB_DQ<20>")
	)
	(segment
		(start 89.229692 -287.373568)
		(end 89.238074 -287.368742)
		(width 0.0889)
		(layer "In4.Cu")
		(net "M_D_CPU1_SB_DQ<20>")
	)
	(segment
		(start 41.72712 -306.558188)
		(end 42.122852 -306.95392)
		(width 0.14478)
		(layer "In4.Cu")
		(net "M_D_CPU1_SB_DQ<20>")
	)
	(segment
		(start 83.589622 -287.373568)
		(end 83.598004 -287.368742)
		(width 0.0889)
		(layer "In4.Cu")
		(net "M_D_CPU1_SB_DQ<20>")
	)
	(segment
		(start 54.798976 -306.81168)
		(end 54.942994 -306.955698)
		(width 0.14478)
		(layer "In4.Cu")
		(net "M_D_CPU1_SB_DQ<20>")
	)
	(segment
		(start 54.092856 -306.89169)
		(end 54.242716 -306.74183)
		(width 0.14478)
		(layer "In4.Cu")
		(net "M_D_CPU1_SB_DQ<20>")
	)
	(segment
		(start 54.654958 -306.258214)
		(end 54.798976 -306.402232)
		(width 0.14478)
		(layer "In4.Cu")
		(net "M_D_CPU1_SB_DQ<20>")
	)
	(segment
		(start 77.25029 -287.959546)
		(end 77.790294 -287.419542)
		(width 0.0889)
		(layer "In4.Cu")
		(net "M_D_CPU1_SB_DQ<20>")
	)
	(segment
		(start 38.642036 -306.789328)
		(end 38.80358 -306.950872)
		(width 0.14478)
		(layer "In4.Cu")
		(net "M_D_CPU1_SB_DQ<20>")
	)
	(segment
		(start 57.63641 -306.560474)
		(end 58.091324 -306.10556)
		(width 0.14478)
		(layer "In4.Cu")
		(net "M_D_CPU1_SB_DQ<20>")
	)
	(segment
		(start 54.942994 -306.955698)
		(end 55.211218 -306.955698)
		(width 0.14478)
		(layer "In4.Cu")
		(net "M_D_CPU1_SB_DQ<20>")
	)
	(segment
		(start 37.611558 -306.950872)
		(end 37.929058 -306.950872)
		(width 0.14478)
		(layer "In4.Cu")
		(net "M_D_CPU1_SB_DQ<20>")
	)
	(segment
		(start 48.138588 -306.570126)
		(end 48.445928 -306.877466)
		(width 0.14478)
		(layer "In4.Cu")
		(net "M_D_CPU1_SB_DQ<20>")
	)
	(segment
		(start 55.911496 -306.402232)
		(end 55.911496 -306.81168)
		(width 0.14478)
		(layer "In4.Cu")
		(net "M_D_CPU1_SB_DQ<20>")
	)
	(segment
		(start 81.344008 -287.368742)
		(end 81.35239 -287.373568)
		(width 0.0889)
		(layer "In4.Cu")
		(net "M_D_CPU1_SB_DQ<20>")
	)
	(segment
		(start 42.122852 -306.95392)
		(end 42.353484 -306.95392)
		(width 0.14478)
		(layer "In4.Cu")
		(net "M_D_CPU1_SB_DQ<20>")
	)
	(segment
		(start 59.62777 -305.35753)
		(end 59.62777 -305.944016)
		(width 0.14478)
		(layer "In4.Cu")
		(net "M_D_CPU1_SB_DQ<20>")
	)
	(segment
		(start 79.44866 -287.360106)
		(end 79.463392 -287.368742)
		(width 0.0889)
		(layer "In4.Cu")
		(net "M_D_CPU1_SB_DQ<20>")
	)
	(segment
		(start 56.323738 -306.955698)
		(end 56.718962 -306.560474)
		(width 0.14478)
		(layer "In4.Cu")
		(net "M_D_CPU1_SB_DQ<20>")
	)
	(segment
		(start 45.0977 -305.719988)
		(end 45.947838 -306.570126)
		(width 0.14478)
		(layer "In4.Cu")
		(net "M_D_CPU1_SB_DQ<20>")
	)
	(segment
		(start 38.252146 -306.392326)
		(end 38.480492 -306.392326)
		(width 0.14478)
		(layer "In4.Cu")
		(net "M_D_CPU1_SB_DQ<20>")
	)
	(segment
		(start 59.076336 -305.944016)
		(end 59.076336 -305.35753)
		(width 0.14478)
		(layer "In4.Cu")
		(net "M_D_CPU1_SB_DQ<20>")
	)
	(segment
		(start 59.076336 -305.35753)
		(end 59.23788 -305.195986)
		(width 0.14478)
		(layer "In4.Cu")
		(net "M_D_CPU1_SB_DQ<20>")
	)
	(segment
		(start 75.986386 -289.020758)
		(end 77.047598 -287.959546)
		(width 0.0889)
		(layer "In4.Cu")
		(net "M_D_CPU1_SB_DQ<20>")
	)
	(segment
		(start 54.242716 -306.402232)
		(end 54.386734 -306.258214)
		(width 0.14478)
		(layer "In4.Cu")
		(net "M_D_CPU1_SB_DQ<20>")
	)
	(segment
		(start 88.289638 -287.373568)
		(end 88.29802 -287.368742)
		(width 0.0889)
		(layer "In4.Cu")
		(net "M_D_CPU1_SB_DQ<20>")
	)
	(segment
		(start 69.574918 -296.631868)
		(end 69.574918 -295.432226)
		(width 0.14478)
		(layer "In4.Cu")
		(net "M_D_CPU1_SB_DQ<20>")
	)
	(segment
		(start 59.466226 -305.195986)
		(end 59.62777 -305.35753)
		(width 0.14478)
		(layer "In4.Cu")
		(net "M_D_CPU1_SB_DQ<20>")
	)
	(segment
		(start 50.114708 -306.563776)
		(end 50.958496 -305.719988)
		(width 0.14478)
		(layer "In4.Cu")
		(net "M_D_CPU1_SB_DQ<20>")
	)
	(segment
		(start 38.80358 -306.950872)
		(end 39.45509 -306.950872)
		(width 0.14478)
		(layer "In4.Cu")
		(net "M_D_CPU1_SB_DQ<20>")
	)
	(segment
		(start 58.914792 -306.10556)
		(end 59.076336 -305.944016)
		(width 0.14478)
		(layer "In4.Cu")
		(net "M_D_CPU1_SB_DQ<20>")
	)
	(segment
		(start 43.587416 -305.719988)
		(end 45.0977 -305.719988)
		(width 0.14478)
		(layer "In4.Cu")
		(net "M_D_CPU1_SB_DQ<20>")
	)
	(segment
		(start 50.958496 -305.719988)
		(end 52.70881 -305.719988)
		(width 0.14478)
		(layer "In4.Cu")
		(net "M_D_CPU1_SB_DQ<20>")
	)
	(segment
		(start 89.803986 -287.368742)
		(end 89.812368 -287.373568)
		(width 0.0889)
		(layer "In4.Cu")
		(net "M_D_CPU1_SB_DQ<20>")
	)
	(segment
		(start 90.74404 -287.368742)
		(end 90.752422 -287.373568)
		(width 0.0889)
		(layer "In4.Cu")
		(net "M_D_CPU1_SB_DQ<20>")
	)
	(segment
		(start 54.798976 -306.402232)
		(end 54.798976 -306.81168)
		(width 0.14478)
		(layer "In4.Cu")
		(net "M_D_CPU1_SB_DQ<20>")
	)
	(segment
		(start 77.790294 -287.419542)
		(end 78.71079 -287.419542)
		(width 0.0889)
		(layer "In4.Cu")
		(net "M_D_CPU1_SB_DQ<20>")
	)
	(segment
		(start 59.23788 -305.195986)
		(end 59.466226 -305.195986)
		(width 0.14478)
		(layer "In4.Cu")
		(net "M_D_CPU1_SB_DQ<20>")
	)
	(segment
		(start 84.529676 -287.373568)
		(end 84.538058 -287.368742)
		(width 0.0889)
		(layer "In4.Cu")
		(net "M_D_CPU1_SB_DQ<20>")
	)
	(segment
		(start 54.242716 -306.74183)
		(end 54.242716 -306.402232)
		(width 0.14478)
		(layer "In4.Cu")
		(net "M_D_CPU1_SB_DQ<20>")
	)
	(segment
		(start 41.496488 -306.558188)
		(end 41.72712 -306.558188)
		(width 0.14478)
		(layer "In4.Cu")
		(net "M_D_CPU1_SB_DQ<20>")
	)
	(segment
		(start 56.055514 -306.955698)
		(end 56.323738 -306.955698)
		(width 0.14478)
		(layer "In4.Cu")
		(net "M_D_CPU1_SB_DQ<20>")
	)
	(segment
		(start 91.085162 -287.311592)
		(end 90.930984 -287.046162)
		(width 0.0889)
		(layer "In4.Cu")
		(net "M_D_CPU1_SB_DQ<20>")
	)
	(segment
		(start 52.70881 -305.719988)
		(end 53.880512 -306.89169)
		(width 0.14478)
		(layer "In4.Cu")
		(net "M_D_CPU1_SB_DQ<20>")
	)
	(segment
		(start 54.386734 -306.258214)
		(end 54.654958 -306.258214)
		(width 0.14478)
		(layer "In4.Cu")
		(net "M_D_CPU1_SB_DQ<20>")
	)
	(segment
		(start 55.499254 -306.258214)
		(end 55.767478 -306.258214)
		(width 0.14478)
		(layer "In4.Cu")
		(net "M_D_CPU1_SB_DQ<20>")
	)
	(segment
		(start 91.06281 -287.394904)
		(end 91.085162 -287.311592)
		(width 0.0889)
		(layer "In4.Cu")
		(net "M_D_CPU1_SB_DQ<20>")
	)
	(segment
		(start 85.10397 -287.368742)
		(end 85.112352 -287.373568)
		(width 0.0889)
		(layer "In4.Cu")
		(net "M_D_CPU1_SB_DQ<20>")
	)
	(segment
		(start 38.642036 -306.55387)
		(end 38.642036 -306.789328)
		(width 0.14478)
		(layer "In4.Cu")
		(net "M_D_CPU1_SB_DQ<20>")
	)
	(segment
		(start 69.574918 -295.432226)
		(end 75.986386 -289.020758)
		(width 0.14478)
		(layer "In4.Cu")
		(net "M_D_CPU1_SB_DQ<20>")
	)
	(segment
		(start 79.463392 -287.368742)
		(end 79.475076 -287.3756)
		(width 0.0889)
		(layer "In4.Cu")
		(net "M_D_CPU1_SB_DQ<20>")
	)
	(segment
		(start 59.62777 -305.944016)
		(end 59.789314 -306.10556)
		(width 0.14478)
		(layer "In4.Cu")
		(net "M_D_CPU1_SB_DQ<20>")
	)
	(segment
		(start 77.047598 -287.959546)
		(end 77.25029 -287.959546)
		(width 0.0889)
		(layer "In4.Cu")
		(net "M_D_CPU1_SB_DQ<20>")
	)
	(segment
		(start 55.911496 -306.81168)
		(end 56.055514 -306.955698)
		(width 0.14478)
		(layer "In4.Cu")
		(net "M_D_CPU1_SB_DQ<20>")
	)
	(segment
		(start 55.767478 -306.258214)
		(end 55.911496 -306.402232)
		(width 0.14478)
		(layer "In4.Cu")
		(net "M_D_CPU1_SB_DQ<20>")
	)
	(segment
		(start 55.355236 -306.81168)
		(end 55.355236 -306.402232)
		(width 0.14478)
		(layer "In4.Cu")
		(net "M_D_CPU1_SB_DQ<20>")
	)
	(segment
		(start 39.45509 -306.950872)
		(end 39.835836 -306.570126)
		(width 0.14478)
		(layer "In4.Cu")
		(net "M_D_CPU1_SB_DQ<20>")
	)
	(segment
		(start 36.795964 -306.135278)
		(end 37.611558 -306.950872)
		(width 0.14478)
		(layer "In4.Cu")
		(net "M_D_CPU1_SB_DQ<20>")
	)
	(segment
		(start 45.947838 -306.570126)
		(end 48.138588 -306.570126)
		(width 0.14478)
		(layer "In4.Cu")
		(net "M_D_CPU1_SB_DQ<20>")
	)
	(segment
		(start 39.835836 -306.570126)
		(end 40.498014 -306.570126)
		(width 0.14478)
		(layer "In4.Cu")
		(net "M_D_CPU1_SB_DQ<20>")
	)
	(segment
		(start 49.002188 -306.563776)
		(end 50.114708 -306.563776)
		(width 0.14478)
		(layer "In4.Cu")
		(net "M_D_CPU1_SB_DQ<20>")
	)
	(segment
		(start 86.044024 -287.368742)
		(end 86.052406 -287.373568)
		(width 0.0889)
		(layer "In4.Cu")
		(net "M_D_CPU1_SB_DQ<20>")
	)
	(segment
		(start 55.211218 -306.955698)
		(end 55.355236 -306.81168)
		(width 0.14478)
		(layer "In4.Cu")
		(net "M_D_CPU1_SB_DQ<20>")
	)
	(segment
		(start 48.445928 -306.877466)
		(end 48.688498 -306.877466)
		(width 0.14478)
		(layer "In4.Cu")
		(net "M_D_CPU1_SB_DQ<20>")
	)
	(segment
		(start 38.090602 -306.55387)
		(end 38.252146 -306.392326)
		(width 0.14478)
		(layer "In4.Cu")
		(net "M_D_CPU1_SB_DQ<20>")
	)
	(segment
		(start 42.353484 -306.95392)
		(end 43.587416 -305.719988)
		(width 0.14478)
		(layer "In4.Cu")
		(net "M_D_CPU1_SB_DQ<20>")
	)
	(segment
		(start 38.480492 -306.392326)
		(end 38.642036 -306.55387)
		(width 0.14478)
		(layer "In4.Cu")
		(net "M_D_CPU1_SB_DQ<20>")
	)
	(segment
		(start 40.875966 -306.948078)
		(end 41.106598 -306.948078)
		(width 0.14478)
		(layer "In4.Cu")
		(net "M_D_CPU1_SB_DQ<20>")
	)
	(segment
		(start 53.880512 -306.89169)
		(end 54.092856 -306.89169)
		(width 0.14478)
		(layer "In4.Cu")
		(net "M_D_CPU1_SB_DQ<20>")
	)
	(segment
		(start 80.39354 -287.362646)
		(end 80.403954 -287.368742)
		(width 0.0889)
		(layer "In4.Cu")
		(net "M_D_CPU1_SB_DQ<20>")
	)
	(segment
		(start 55.355236 -306.402232)
		(end 55.499254 -306.258214)
		(width 0.14478)
		(layer "In4.Cu")
		(net "M_D_CPU1_SB_DQ<20>")
	)
	(segment
		(start 37.929058 -306.950872)
		(end 38.090602 -306.789328)
		(width 0.14478)
		(layer "In4.Cu")
		(net "M_D_CPU1_SB_DQ<20>")
	)
	(segment
		(start 58.091324 -306.10556)
		(end 58.914792 -306.10556)
		(width 0.14478)
		(layer "In4.Cu")
		(net "M_D_CPU1_SB_DQ<20>")
	)
	(segment
		(start 60.101226 -306.10556)
		(end 69.574918 -296.631868)
		(width 0.14478)
		(layer "In4.Cu")
		(net "M_D_CPU1_SB_DQ<20>")
	)
	(segment
		(start 40.498014 -306.570126)
		(end 40.875966 -306.948078)
		(width 0.14478)
		(layer "In4.Cu")
		(net "M_D_CPU1_SB_DQ<20>")
	)
	(segment
		(start 41.106598 -306.948078)
		(end 41.496488 -306.558188)
		(width 0.14478)
		(layer "In4.Cu")
		(net "M_D_CPU1_SB_DQ<20>")
	)
	(arc
		(start 85.478112 -287.368742)
		(mid 85.761068 -287.292599)
		(end 86.044024 -287.368742)
		(width 0.0889)
		(layer "In4.Cu")
		(net "M_D_CPU1_SB_DQ<20>")
	)
	(arc
		(start 84.538058 -287.368742)
		(mid 84.821014 -287.292599)
		(end 85.10397 -287.368742)
		(width 0.0889)
		(layer "In4.Cu")
		(net "M_D_CPU1_SB_DQ<20>")
	)
	(arc
		(start 86.418166 -287.368742)
		(mid 86.701122 -287.292599)
		(end 86.984078 -287.368742)
		(width 0.0889)
		(layer "In4.Cu")
		(net "M_D_CPU1_SB_DQ<20>")
	)
	(arc
		(start 79.475076 -287.3756)
		(mid 79.657331 -287.419253)
		(end 79.837788 -287.368742)
		(width 0.0889)
		(layer "In4.Cu")
		(net "M_D_CPU1_SB_DQ<20>")
	)
	(arc
		(start 83.598004 -287.368742)
		(mid 83.88096 -287.292599)
		(end 84.163916 -287.368742)
		(width 0.0889)
		(layer "In4.Cu")
		(net "M_D_CPU1_SB_DQ<20>")
	)
	(arc
		(start 81.35239 -287.373568)
		(mid 81.535898 -287.419062)
		(end 81.71815 -287.368742)
		(width 0.0889)
		(layer "In4.Cu")
		(net "M_D_CPU1_SB_DQ<20>")
	)
	(arc
		(start 89.238074 -287.368742)
		(mid 89.52103 -287.292599)
		(end 89.803986 -287.368742)
		(width 0.0889)
		(layer "In4.Cu")
		(net "M_D_CPU1_SB_DQ<20>")
	)
	(arc
		(start 88.29802 -287.368742)
		(mid 88.580976 -287.292599)
		(end 88.863932 -287.368742)
		(width 0.0889)
		(layer "In4.Cu")
		(net "M_D_CPU1_SB_DQ<20>")
	)
	(arc
		(start 78.897988 -287.368742)
		(mid 79.172186 -287.292667)
		(end 79.44866 -287.360106)
		(width 0.0889)
		(layer "In4.Cu")
		(net "M_D_CPU1_SB_DQ<20>")
	)
	(arc
		(start 90.752422 -287.373568)
		(mid 90.905292 -287.418209)
		(end 91.06281 -287.394904)
		(width 0.0889)
		(layer "In4.Cu")
		(net "M_D_CPU1_SB_DQ<20>")
	)
	(arc
		(start 85.112352 -287.373568)
		(mid 85.29586 -287.419062)
		(end 85.478112 -287.368742)
		(width 0.0889)
		(layer "In4.Cu")
		(net "M_D_CPU1_SB_DQ<20>")
	)
	(arc
		(start 87.923878 -287.368742)
		(mid 88.106129 -287.419092)
		(end 88.289638 -287.373568)
		(width 0.0889)
		(layer "In4.Cu")
		(net "M_D_CPU1_SB_DQ<20>")
	)
	(arc
		(start 89.812368 -287.373568)
		(mid 89.995876 -287.419062)
		(end 90.178128 -287.368742)
		(width 0.0889)
		(layer "In4.Cu")
		(net "M_D_CPU1_SB_DQ<20>")
	)
	(arc
		(start 79.837788 -287.368742)
		(mid 80.114855 -287.292505)
		(end 80.39354 -287.362646)
		(width 0.0889)
		(layer "In4.Cu")
		(net "M_D_CPU1_SB_DQ<20>")
	)
	(arc
		(start 83.223862 -287.368742)
		(mid 83.406113 -287.419092)
		(end 83.589622 -287.373568)
		(width 0.0889)
		(layer "In4.Cu")
		(net "M_D_CPU1_SB_DQ<20>")
	)
	(arc
		(start 82.65795 -287.368742)
		(mid 82.940906 -287.292599)
		(end 83.223862 -287.368742)
		(width 0.0889)
		(layer "In4.Cu")
		(net "M_D_CPU1_SB_DQ<20>")
	)
	(arc
		(start 86.984078 -287.368742)
		(mid 87.171022 -287.418997)
		(end 87.357966 -287.368742)
		(width 0.0889)
		(layer "In4.Cu")
		(net "M_D_CPU1_SB_DQ<20>")
	)
	(arc
		(start 84.163916 -287.368742)
		(mid 84.346167 -287.419092)
		(end 84.529676 -287.373568)
		(width 0.0889)
		(layer "In4.Cu")
		(net "M_D_CPU1_SB_DQ<20>")
	)
	(arc
		(start 81.71815 -287.368742)
		(mid 82.001106 -287.292599)
		(end 82.284062 -287.368742)
		(width 0.0889)
		(layer "In4.Cu")
		(net "M_D_CPU1_SB_DQ<20>")
	)
	(arc
		(start 90.178128 -287.368742)
		(mid 90.461084 -287.292599)
		(end 90.74404 -287.368742)
		(width 0.0889)
		(layer "In4.Cu")
		(net "M_D_CPU1_SB_DQ<20>")
	)
	(arc
		(start 87.357966 -287.368742)
		(mid 87.640922 -287.292599)
		(end 87.923878 -287.368742)
		(width 0.0889)
		(layer "In4.Cu")
		(net "M_D_CPU1_SB_DQ<20>")
	)
	(arc
		(start 80.778096 -287.368742)
		(mid 81.061052 -287.292599)
		(end 81.344008 -287.368742)
		(width 0.0889)
		(layer "In4.Cu")
		(net "M_D_CPU1_SB_DQ<20>")
	)
	(arc
		(start 88.863932 -287.368742)
		(mid 89.046183 -287.419092)
		(end 89.229692 -287.373568)
		(width 0.0889)
		(layer "In4.Cu")
		(net "M_D_CPU1_SB_DQ<20>")
	)
	(arc
		(start 82.284062 -287.368742)
		(mid 82.471006 -287.418997)
		(end 82.65795 -287.368742)
		(width 0.0889)
		(layer "In4.Cu")
		(net "M_D_CPU1_SB_DQ<20>")
	)
	(arc
		(start 86.052406 -287.373568)
		(mid 86.235914 -287.419062)
		(end 86.418166 -287.368742)
		(width 0.0889)
		(layer "In4.Cu")
		(net "M_D_CPU1_SB_DQ<20>")
	)
	(arc
		(start 80.403954 -287.368742)
		(mid 80.586205 -287.419092)
		(end 80.769714 -287.373568)
		(width 0.0889)
		(layer "In4.Cu")
		(net "M_D_CPU1_SB_DQ<20>")
	)
	(arc
		(start 78.71079 -287.419542)
		(mid 78.807748 -287.406519)
		(end 78.897988 -287.368742)
		(width 0.0889)
		(layer "In4.Cu")
		(net "M_D_CPU1_SB_DQ<20>")
	)
	(segment
		(start 92.80779 -274.630388)
		(end 92.340938 -274.896326)
		(width 0.10668)
		(layer "F.Cu")
		(net "M_D_CPU1_SB_DQ<1>")
	)
	(segment
		(start 54.634384 -282.991306)
		(end 54.795928 -283.15285)
		(width 0.14478)
		(layer "In4.Cu")
		(net "M_D_CPU1_SB_DQ<1>")
	)
	(segment
		(start 37.979604 -283.812742)
		(end 37.979604 -283.38145)
		(width 0.14478)
		(layer "In4.Cu")
		(net "M_D_CPU1_SB_DQ<1>")
	)
	(segment
		(start 88.394032 -275.218906)
		(end 88.402414 -275.223732)
		(width 0.0889)
		(layer "In4.Cu")
		(net "M_D_CPU1_SB_DQ<1>")
	)
	(segment
		(start 56.656986 -282.98521)
		(end 56.656986 -283.44876)
		(width 0.14478)
		(layer "In4.Cu")
		(net "M_D_CPU1_SB_DQ<1>")
	)
	(segment
		(start 86.879684 -275.223732)
		(end 86.888066 -275.218906)
		(width 0.0889)
		(layer "In4.Cu")
		(net "M_D_CPU1_SB_DQ<1>")
	)
	(segment
		(start 37.586158 -283.975556)
		(end 37.81679 -283.975556)
		(width 0.14478)
		(layer "In4.Cu")
		(net "M_D_CPU1_SB_DQ<1>")
	)
	(segment
		(start 54.244494 -283.15285)
		(end 54.406038 -282.991306)
		(width 0.14478)
		(layer "In4.Cu")
		(net "M_D_CPU1_SB_DQ<1>")
	)
	(segment
		(start 42.381678 -283.231844)
		(end 42.853356 -282.760166)
		(width 0.14478)
		(layer "In4.Cu")
		(net "M_D_CPU1_SB_DQ<1>")
	)
	(segment
		(start 56.105552 -283.44876)
		(end 56.105552 -282.98521)
		(width 0.14478)
		(layer "In4.Cu")
		(net "M_D_CPU1_SB_DQ<1>")
	)
	(segment
		(start 92.472764 -275.245068)
		(end 92.495116 -275.161756)
		(width 0.0889)
		(layer "In4.Cu")
		(net "M_D_CPU1_SB_DQ<1>")
	)
	(segment
		(start 54.795928 -283.15285)
		(end 54.795928 -283.44876)
		(width 0.14478)
		(layer "In4.Cu")
		(net "M_D_CPU1_SB_DQ<1>")
	)
	(segment
		(start 56.656986 -283.44876)
		(end 56.81853 -283.610304)
		(width 0.14478)
		(layer "In4.Cu")
		(net "M_D_CPU1_SB_DQ<1>")
	)
	(segment
		(start 56.81853 -283.610304)
		(end 56.984646 -283.610304)
		(width 0.14478)
		(layer "In4.Cu")
		(net "M_D_CPU1_SB_DQ<1>")
	)
	(segment
		(start 39.254938 -283.218636)
		(end 39.48557 -283.218636)
		(width 0.14478)
		(layer "In4.Cu")
		(net "M_D_CPU1_SB_DQ<1>")
	)
	(segment
		(start 83.694016 -275.218906)
		(end 83.702398 -275.223732)
		(width 0.0889)
		(layer "In4.Cu")
		(net "M_D_CPU1_SB_DQ<1>")
	)
	(segment
		(start 39.48557 -283.218636)
		(end 39.877238 -283.610304)
		(width 0.14478)
		(layer "In4.Cu")
		(net "M_D_CPU1_SB_DQ<1>")
	)
	(segment
		(start 76.47305 -274.047966)
		(end 77.385164 -274.047966)
		(width 0.0889)
		(layer "In4.Cu")
		(net "M_D_CPU1_SB_DQ<1>")
	)
	(segment
		(start 41.408096 -283.231844)
		(end 42.381678 -283.231844)
		(width 0.14478)
		(layer "In4.Cu")
		(net "M_D_CPU1_SB_DQ<1>")
	)
	(segment
		(start 38.92931 -283.975556)
		(end 39.092124 -283.812742)
		(width 0.14478)
		(layer "In4.Cu")
		(net "M_D_CPU1_SB_DQ<1>")
	)
	(segment
		(start 56.984646 -283.610304)
		(end 57.834784 -282.760166)
		(width 0.14478)
		(layer "In4.Cu")
		(net "M_D_CPU1_SB_DQ<1>")
	)
	(segment
		(start 91.5797 -275.223732)
		(end 91.588082 -275.218906)
		(width 0.0889)
		(layer "In4.Cu")
		(net "M_D_CPU1_SB_DQ<1>")
	)
	(segment
		(start 80.299814 -275.223732)
		(end 80.308196 -275.218906)
		(width 0.0889)
		(layer "In4.Cu")
		(net "M_D_CPU1_SB_DQ<1>")
	)
	(segment
		(start 76.391262 -274.129754)
		(end 76.47305 -274.047966)
		(width 0.0889)
		(layer "In4.Cu")
		(net "M_D_CPU1_SB_DQ<1>")
	)
	(segment
		(start 54.795928 -283.44876)
		(end 54.957472 -283.610304)
		(width 0.14478)
		(layer "In4.Cu")
		(net "M_D_CPU1_SB_DQ<1>")
	)
	(segment
		(start 37.81679 -283.975556)
		(end 37.979604 -283.812742)
		(width 0.14478)
		(layer "In4.Cu")
		(net "M_D_CPU1_SB_DQ<1>")
	)
	(segment
		(start 39.092124 -283.812742)
		(end 39.092124 -283.38145)
		(width 0.14478)
		(layer "In4.Cu")
		(net "M_D_CPU1_SB_DQ<1>")
	)
	(segment
		(start 38.535864 -283.812742)
		(end 38.698678 -283.975556)
		(width 0.14478)
		(layer "In4.Cu")
		(net "M_D_CPU1_SB_DQ<1>")
	)
	(segment
		(start 41.029636 -283.610304)
		(end 41.408096 -283.231844)
		(width 0.14478)
		(layer "In4.Cu")
		(net "M_D_CPU1_SB_DQ<1>")
	)
	(segment
		(start 45.573188 -282.760166)
		(end 46.423326 -283.610304)
		(width 0.14478)
		(layer "In4.Cu")
		(net "M_D_CPU1_SB_DQ<1>")
	)
	(segment
		(start 56.105552 -282.98521)
		(end 56.267096 -282.823666)
		(width 0.14478)
		(layer "In4.Cu")
		(net "M_D_CPU1_SB_DQ<1>")
	)
	(segment
		(start 39.877238 -283.610304)
		(end 41.029636 -283.610304)
		(width 0.14478)
		(layer "In4.Cu")
		(net "M_D_CPU1_SB_DQ<1>")
	)
	(segment
		(start 78.47965 -275.142452)
		(end 79.650082 -275.142452)
		(width 0.0889)
		(layer "In4.Cu")
		(net "M_D_CPU1_SB_DQ<1>")
	)
	(segment
		(start 57.834784 -282.760166)
		(end 58.221372 -282.760166)
		(width 0.14478)
		(layer "In4.Cu")
		(net "M_D_CPU1_SB_DQ<1>")
	)
	(segment
		(start 55.944008 -283.610304)
		(end 56.105552 -283.44876)
		(width 0.14478)
		(layer "In4.Cu")
		(net "M_D_CPU1_SB_DQ<1>")
	)
	(segment
		(start 38.535864 -283.38145)
		(end 38.535864 -283.812742)
		(width 0.14478)
		(layer "In4.Cu")
		(net "M_D_CPU1_SB_DQ<1>")
	)
	(segment
		(start 59.065922 -282.786074)
		(end 59.565032 -282.786074)
		(width 0.14478)
		(layer "In4.Cu")
		(net "M_D_CPU1_SB_DQ<1>")
	)
	(segment
		(start 76.201016 -274.129754)
		(end 76.391262 -274.129754)
		(width 0.0889)
		(layer "In4.Cu")
		(net "M_D_CPU1_SB_DQ<1>")
	)
	(segment
		(start 49.917096 -282.760166)
		(end 53.066188 -282.760166)
		(width 0.14478)
		(layer "In4.Cu")
		(net "M_D_CPU1_SB_DQ<1>")
	)
	(segment
		(start 54.957472 -283.610304)
		(end 55.944008 -283.610304)
		(width 0.14478)
		(layer "In4.Cu")
		(net "M_D_CPU1_SB_DQ<1>")
	)
	(segment
		(start 38.142418 -283.218636)
		(end 38.37305 -283.218636)
		(width 0.14478)
		(layer "In4.Cu")
		(net "M_D_CPU1_SB_DQ<1>")
	)
	(segment
		(start 42.853356 -282.760166)
		(end 45.573188 -282.760166)
		(width 0.14478)
		(layer "In4.Cu")
		(net "M_D_CPU1_SB_DQ<1>")
	)
	(segment
		(start 54.08295 -283.610304)
		(end 54.244494 -283.44876)
		(width 0.14478)
		(layer "In4.Cu")
		(net "M_D_CPU1_SB_DQ<1>")
	)
	(segment
		(start 56.267096 -282.823666)
		(end 56.495442 -282.823666)
		(width 0.14478)
		(layer "In4.Cu")
		(net "M_D_CPU1_SB_DQ<1>")
	)
	(segment
		(start 58.777632 -283.074364)
		(end 59.065922 -282.786074)
		(width 0.14478)
		(layer "In4.Cu")
		(net "M_D_CPU1_SB_DQ<1>")
	)
	(segment
		(start 49.066958 -283.610304)
		(end 49.917096 -282.760166)
		(width 0.14478)
		(layer "In4.Cu")
		(net "M_D_CPU1_SB_DQ<1>")
	)
	(segment
		(start 58.221372 -282.760166)
		(end 58.53557 -283.074364)
		(width 0.14478)
		(layer "In4.Cu")
		(net "M_D_CPU1_SB_DQ<1>")
	)
	(segment
		(start 77.385164 -274.047966)
		(end 78.47965 -275.142452)
		(width 0.0889)
		(layer "In4.Cu")
		(net "M_D_CPU1_SB_DQ<1>")
	)
	(segment
		(start 38.698678 -283.975556)
		(end 38.92931 -283.975556)
		(width 0.14478)
		(layer "In4.Cu")
		(net "M_D_CPU1_SB_DQ<1>")
	)
	(segment
		(start 46.423326 -283.610304)
		(end 49.066958 -283.610304)
		(width 0.14478)
		(layer "In4.Cu")
		(net "M_D_CPU1_SB_DQ<1>")
	)
	(segment
		(start 90.639646 -275.223732)
		(end 90.648028 -275.218906)
		(width 0.0889)
		(layer "In4.Cu")
		(net "M_D_CPU1_SB_DQ<1>")
	)
	(segment
		(start 82.753962 -275.218906)
		(end 82.762344 -275.223732)
		(width 0.0889)
		(layer "In4.Cu")
		(net "M_D_CPU1_SB_DQ<1>")
	)
	(segment
		(start 85.93963 -275.223732)
		(end 85.948012 -275.218906)
		(width 0.0889)
		(layer "In4.Cu")
		(net "M_D_CPU1_SB_DQ<1>")
	)
	(segment
		(start 58.53557 -283.074364)
		(end 58.777632 -283.074364)
		(width 0.14478)
		(layer "In4.Cu")
		(net "M_D_CPU1_SB_DQ<1>")
	)
	(segment
		(start 87.453978 -275.218906)
		(end 87.46236 -275.223732)
		(width 0.0889)
		(layer "In4.Cu")
		(net "M_D_CPU1_SB_DQ<1>")
	)
	(segment
		(start 53.916326 -283.610304)
		(end 54.08295 -283.610304)
		(width 0.14478)
		(layer "In4.Cu")
		(net "M_D_CPU1_SB_DQ<1>")
	)
	(segment
		(start 36.795964 -283.185362)
		(end 37.586158 -283.975556)
		(width 0.14478)
		(layer "In4.Cu")
		(net "M_D_CPU1_SB_DQ<1>")
	)
	(segment
		(start 39.092124 -283.38145)
		(end 39.254938 -283.218636)
		(width 0.14478)
		(layer "In4.Cu")
		(net "M_D_CPU1_SB_DQ<1>")
	)
	(segment
		(start 92.153994 -275.218906)
		(end 92.162376 -275.223732)
		(width 0.0889)
		(layer "In4.Cu")
		(net "M_D_CPU1_SB_DQ<1>")
	)
	(segment
		(start 38.37305 -283.218636)
		(end 38.535864 -283.38145)
		(width 0.14478)
		(layer "In4.Cu")
		(net "M_D_CPU1_SB_DQ<1>")
	)
	(segment
		(start 54.244494 -283.44876)
		(end 54.244494 -283.15285)
		(width 0.14478)
		(layer "In4.Cu")
		(net "M_D_CPU1_SB_DQ<1>")
	)
	(segment
		(start 68.221352 -274.129754)
		(end 76.201016 -274.129754)
		(width 0.14478)
		(layer "In4.Cu")
		(net "M_D_CPU1_SB_DQ<1>")
	)
	(segment
		(start 53.066188 -282.760166)
		(end 53.916326 -283.610304)
		(width 0.14478)
		(layer "In4.Cu")
		(net "M_D_CPU1_SB_DQ<1>")
	)
	(segment
		(start 37.979604 -283.38145)
		(end 38.142418 -283.218636)
		(width 0.14478)
		(layer "In4.Cu")
		(net "M_D_CPU1_SB_DQ<1>")
	)
	(segment
		(start 92.495116 -275.161756)
		(end 92.340938 -274.896326)
		(width 0.0889)
		(layer "In4.Cu")
		(net "M_D_CPU1_SB_DQ<1>")
	)
	(segment
		(start 82.179668 -275.223732)
		(end 82.18805 -275.218906)
		(width 0.0889)
		(layer "In4.Cu")
		(net "M_D_CPU1_SB_DQ<1>")
	)
	(segment
		(start 54.406038 -282.991306)
		(end 54.634384 -282.991306)
		(width 0.14478)
		(layer "In4.Cu")
		(net "M_D_CPU1_SB_DQ<1>")
	)
	(segment
		(start 56.495442 -282.823666)
		(end 56.656986 -282.98521)
		(width 0.14478)
		(layer "In4.Cu")
		(net "M_D_CPU1_SB_DQ<1>")
	)
	(segment
		(start 59.565032 -282.786074)
		(end 68.221352 -274.129754)
		(width 0.14478)
		(layer "In4.Cu")
		(net "M_D_CPU1_SB_DQ<1>")
	)
	(arc
		(start 83.128104 -275.218906)
		(mid 83.41106 -275.142729)
		(end 83.694016 -275.218906)
		(width 0.0889)
		(layer "In4.Cu")
		(net "M_D_CPU1_SB_DQ<1>")
	)
	(arc
		(start 80.874108 -275.218906)
		(mid 81.061052 -275.269161)
		(end 81.247996 -275.218906)
		(width 0.0889)
		(layer "In4.Cu")
		(net "M_D_CPU1_SB_DQ<1>")
	)
	(arc
		(start 88.768174 -275.218906)
		(mid 89.05113 -275.142729)
		(end 89.334086 -275.218906)
		(width 0.0889)
		(layer "In4.Cu")
		(net "M_D_CPU1_SB_DQ<1>")
	)
	(arc
		(start 85.948012 -275.218906)
		(mid 86.230968 -275.142729)
		(end 86.513924 -275.218906)
		(width 0.0889)
		(layer "In4.Cu")
		(net "M_D_CPU1_SB_DQ<1>")
	)
	(arc
		(start 86.888066 -275.218906)
		(mid 87.171022 -275.142729)
		(end 87.453978 -275.218906)
		(width 0.0889)
		(layer "In4.Cu")
		(net "M_D_CPU1_SB_DQ<1>")
	)
	(arc
		(start 81.247996 -275.218906)
		(mid 81.530952 -275.142729)
		(end 81.813908 -275.218906)
		(width 0.0889)
		(layer "In4.Cu")
		(net "M_D_CPU1_SB_DQ<1>")
	)
	(arc
		(start 91.21394 -275.218906)
		(mid 91.396191 -275.269256)
		(end 91.5797 -275.223732)
		(width 0.0889)
		(layer "In4.Cu")
		(net "M_D_CPU1_SB_DQ<1>")
	)
	(arc
		(start 91.588082 -275.218906)
		(mid 91.871038 -275.142729)
		(end 92.153994 -275.218906)
		(width 0.0889)
		(layer "In4.Cu")
		(net "M_D_CPU1_SB_DQ<1>")
	)
	(arc
		(start 90.273886 -275.218906)
		(mid 90.456137 -275.269256)
		(end 90.639646 -275.223732)
		(width 0.0889)
		(layer "In4.Cu")
		(net "M_D_CPU1_SB_DQ<1>")
	)
	(arc
		(start 90.648028 -275.218906)
		(mid 90.930984 -275.142729)
		(end 91.21394 -275.218906)
		(width 0.0889)
		(layer "In4.Cu")
		(net "M_D_CPU1_SB_DQ<1>")
	)
	(arc
		(start 84.068158 -275.218906)
		(mid 84.351114 -275.142729)
		(end 84.63407 -275.218906)
		(width 0.0889)
		(layer "In4.Cu")
		(net "M_D_CPU1_SB_DQ<1>")
	)
	(arc
		(start 89.334086 -275.218906)
		(mid 89.52103 -275.269161)
		(end 89.707974 -275.218906)
		(width 0.0889)
		(layer "In4.Cu")
		(net "M_D_CPU1_SB_DQ<1>")
	)
	(arc
		(start 82.18805 -275.218906)
		(mid 82.471006 -275.142729)
		(end 82.753962 -275.218906)
		(width 0.0889)
		(layer "In4.Cu")
		(net "M_D_CPU1_SB_DQ<1>")
	)
	(arc
		(start 84.63407 -275.218906)
		(mid 84.821014 -275.269161)
		(end 85.007958 -275.218906)
		(width 0.0889)
		(layer "In4.Cu")
		(net "M_D_CPU1_SB_DQ<1>")
	)
	(arc
		(start 87.46236 -275.223732)
		(mid 87.645868 -275.269226)
		(end 87.82812 -275.218906)
		(width 0.0889)
		(layer "In4.Cu")
		(net "M_D_CPU1_SB_DQ<1>")
	)
	(arc
		(start 83.702398 -275.223732)
		(mid 83.885906 -275.269226)
		(end 84.068158 -275.218906)
		(width 0.0889)
		(layer "In4.Cu")
		(net "M_D_CPU1_SB_DQ<1>")
	)
	(arc
		(start 88.402414 -275.223732)
		(mid 88.585922 -275.269226)
		(end 88.768174 -275.218906)
		(width 0.0889)
		(layer "In4.Cu")
		(net "M_D_CPU1_SB_DQ<1>")
	)
	(arc
		(start 92.162376 -275.223732)
		(mid 92.315246 -275.268373)
		(end 92.472764 -275.245068)
		(width 0.0889)
		(layer "In4.Cu")
		(net "M_D_CPU1_SB_DQ<1>")
	)
	(arc
		(start 79.650082 -275.142452)
		(mid 79.796882 -275.161896)
		(end 79.933546 -275.218906)
		(width 0.0889)
		(layer "In4.Cu")
		(net "M_D_CPU1_SB_DQ<1>")
	)
	(arc
		(start 85.57387 -275.218906)
		(mid 85.756121 -275.269256)
		(end 85.93963 -275.223732)
		(width 0.0889)
		(layer "In4.Cu")
		(net "M_D_CPU1_SB_DQ<1>")
	)
	(arc
		(start 85.007958 -275.218906)
		(mid 85.290914 -275.142729)
		(end 85.57387 -275.218906)
		(width 0.0889)
		(layer "In4.Cu")
		(net "M_D_CPU1_SB_DQ<1>")
	)
	(arc
		(start 81.813908 -275.218906)
		(mid 81.996159 -275.269256)
		(end 82.179668 -275.223732)
		(width 0.0889)
		(layer "In4.Cu")
		(net "M_D_CPU1_SB_DQ<1>")
	)
	(arc
		(start 82.762344 -275.223732)
		(mid 82.945852 -275.269226)
		(end 83.128104 -275.218906)
		(width 0.0889)
		(layer "In4.Cu")
		(net "M_D_CPU1_SB_DQ<1>")
	)
	(arc
		(start 87.82812 -275.218906)
		(mid 88.111076 -275.142729)
		(end 88.394032 -275.218906)
		(width 0.0889)
		(layer "In4.Cu")
		(net "M_D_CPU1_SB_DQ<1>")
	)
	(arc
		(start 89.707974 -275.218906)
		(mid 89.99093 -275.142729)
		(end 90.273886 -275.218906)
		(width 0.0889)
		(layer "In4.Cu")
		(net "M_D_CPU1_SB_DQ<1>")
	)
	(arc
		(start 79.933546 -275.218906)
		(mid 80.116051 -275.269383)
		(end 80.299814 -275.223732)
		(width 0.0889)
		(layer "In4.Cu")
		(net "M_D_CPU1_SB_DQ<1>")
	)
	(arc
		(start 80.308196 -275.218906)
		(mid 80.591152 -275.142729)
		(end 80.874108 -275.218906)
		(width 0.0889)
		(layer "In4.Cu")
		(net "M_D_CPU1_SB_DQ<1>")
	)
	(arc
		(start 86.513924 -275.218906)
		(mid 86.696175 -275.269256)
		(end 86.879684 -275.223732)
		(width 0.0889)
		(layer "In4.Cu")
		(net "M_D_CPU1_SB_DQ<1>")
	)
	(segment
		(start 93.277944 -285.160466)
		(end 92.811092 -285.426404)
		(width 0.10668)
		(layer "F.Cu")
		(net "M_D_CPU1_SB_DQ<19>")
	)
	(segment
		(start 34.233612 -302.302164)
		(end 34.396426 -302.464978)
		(width 0.14478)
		(layer "In4.Cu")
		(net "M_D_CPU1_SB_DQ<19>")
	)
	(segment
		(start 89.229692 -285.098998)
		(end 89.238074 -285.103824)
		(width 0.0889)
		(layer "In4.Cu")
		(net "M_D_CPU1_SB_DQ<19>")
	)
	(segment
		(start 80.389222 -285.11246)
		(end 80.403954 -285.103824)
		(width 0.0889)
		(layer "In4.Cu")
		(net "M_D_CPU1_SB_DQ<19>")
	)
	(segment
		(start 79.463138 -285.103824)
		(end 79.474822 -285.096966)
		(width 0.0889)
		(layer "In4.Cu")
		(net "M_D_CPU1_SB_DQ<19>")
	)
	(segment
		(start 49.031144 -303.150524)
		(end 49.881028 -302.30064)
		(width 0.14478)
		(layer "In4.Cu")
		(net "M_D_CPU1_SB_DQ<19>")
	)
	(segment
		(start 32.695896 -302.735234)
		(end 33.121092 -303.16043)
		(width 0.14478)
		(layer "In4.Cu")
		(net "M_D_CPU1_SB_DQ<19>")
	)
	(segment
		(start 92.560648 -285.135574)
		(end 92.656914 -285.160974)
		(width 0.0889)
		(layer "In4.Cu")
		(net "M_D_CPU1_SB_DQ<19>")
	)
	(segment
		(start 34.549334 -303.150524)
		(end 41.609772 -303.150524)
		(width 0.14478)
		(layer "In4.Cu")
		(net "M_D_CPU1_SB_DQ<19>")
	)
	(segment
		(start 60.292234 -302.225964)
		(end 60.767976 -301.750222)
		(width 0.14478)
		(layer "In4.Cu")
		(net "M_D_CPU1_SB_DQ<19>")
	)
	(segment
		(start 41.609772 -303.150524)
		(end 42.459656 -302.30064)
		(width 0.14478)
		(layer "In4.Cu")
		(net "M_D_CPU1_SB_DQ<19>")
	)
	(segment
		(start 34.00298 -302.302164)
		(end 34.233612 -302.302164)
		(width 0.14478)
		(layer "In4.Cu")
		(net "M_D_CPU1_SB_DQ<19>")
	)
	(segment
		(start 42.459656 -302.30064)
		(end 46.114716 -302.30064)
		(width 0.14478)
		(layer "In4.Cu")
		(net "M_D_CPU1_SB_DQ<19>")
	)
	(segment
		(start 83.589622 -285.098998)
		(end 83.598004 -285.103824)
		(width 0.0889)
		(layer "In4.Cu")
		(net "M_D_CPU1_SB_DQ<19>")
	)
	(segment
		(start 33.840166 -302.997616)
		(end 33.840166 -302.464978)
		(width 0.14478)
		(layer "In4.Cu")
		(net "M_D_CPU1_SB_DQ<19>")
	)
	(segment
		(start 81.344008 -285.103824)
		(end 81.35239 -285.098998)
		(width 0.0889)
		(layer "In4.Cu")
		(net "M_D_CPU1_SB_DQ<19>")
	)
	(segment
		(start 60.767976 -300.929802)
		(end 75.866244 -285.831534)
		(width 0.14478)
		(layer "In4.Cu")
		(net "M_D_CPU1_SB_DQ<19>")
	)
	(segment
		(start 33.677352 -303.16043)
		(end 33.840166 -302.997616)
		(width 0.14478)
		(layer "In4.Cu")
		(net "M_D_CPU1_SB_DQ<19>")
	)
	(segment
		(start 46.114716 -302.30064)
		(end 46.9646 -303.150524)
		(width 0.14478)
		(layer "In4.Cu")
		(net "M_D_CPU1_SB_DQ<19>")
	)
	(segment
		(start 78.879446 -285.093664)
		(end 78.897734 -285.104078)
		(width 0.0889)
		(layer "In4.Cu")
		(net "M_D_CPU1_SB_DQ<19>")
	)
	(segment
		(start 86.044024 -285.103824)
		(end 86.052406 -285.098998)
		(width 0.0889)
		(layer "In4.Cu")
		(net "M_D_CPU1_SB_DQ<19>")
	)
	(segment
		(start 85.10397 -285.103824)
		(end 85.112352 -285.098998)
		(width 0.0889)
		(layer "In4.Cu")
		(net "M_D_CPU1_SB_DQ<19>")
	)
	(segment
		(start 89.803986 -285.103824)
		(end 89.812368 -285.098998)
		(width 0.0889)
		(layer "In4.Cu")
		(net "M_D_CPU1_SB_DQ<19>")
	)
	(segment
		(start 46.9646 -303.150524)
		(end 49.031144 -303.150524)
		(width 0.14478)
		(layer "In4.Cu")
		(net "M_D_CPU1_SB_DQ<19>")
	)
	(segment
		(start 88.289638 -285.098998)
		(end 88.29802 -285.103824)
		(width 0.0889)
		(layer "In4.Cu")
		(net "M_D_CPU1_SB_DQ<19>")
	)
	(segment
		(start 34.396426 -302.997616)
		(end 34.549334 -303.150524)
		(width 0.14478)
		(layer "In4.Cu")
		(net "M_D_CPU1_SB_DQ<19>")
	)
	(segment
		(start 76.81214 -285.348426)
		(end 77.61478 -285.348426)
		(width 0.0889)
		(layer "In4.Cu")
		(net "M_D_CPU1_SB_DQ<19>")
	)
	(segment
		(start 49.881028 -302.30064)
		(end 53.658516 -302.30064)
		(width 0.14478)
		(layer "In4.Cu")
		(net "M_D_CPU1_SB_DQ<19>")
	)
	(segment
		(start 76.282042 -285.831534)
		(end 76.731876 -285.3817)
		(width 0.0889)
		(layer "In4.Cu")
		(net "M_D_CPU1_SB_DQ<19>")
	)
	(segment
		(start 57.474104 -302.225964)
		(end 60.292234 -302.225964)
		(width 0.14478)
		(layer "In4.Cu")
		(net "M_D_CPU1_SB_DQ<19>")
	)
	(segment
		(start 78.897734 -285.104078)
		(end 78.903322 -285.10738)
		(width 0.0889)
		(layer "In4.Cu")
		(net "M_D_CPU1_SB_DQ<19>")
	)
	(segment
		(start 34.396426 -302.464978)
		(end 34.396426 -302.997616)
		(width 0.14478)
		(layer "In4.Cu")
		(net "M_D_CPU1_SB_DQ<19>")
	)
	(segment
		(start 33.121092 -303.16043)
		(end 33.677352 -303.16043)
		(width 0.14478)
		(layer "In4.Cu")
		(net "M_D_CPU1_SB_DQ<19>")
	)
	(segment
		(start 80.769714 -285.098998)
		(end 80.778096 -285.103824)
		(width 0.0889)
		(layer "In4.Cu")
		(net "M_D_CPU1_SB_DQ<19>")
	)
	(segment
		(start 75.921616 -285.831534)
		(end 76.282042 -285.831534)
		(width 0.0889)
		(layer "In4.Cu")
		(net "M_D_CPU1_SB_DQ<19>")
	)
	(segment
		(start 60.767976 -301.750222)
		(end 60.767976 -300.929802)
		(width 0.14478)
		(layer "In4.Cu")
		(net "M_D_CPU1_SB_DQ<19>")
	)
	(segment
		(start 92.656914 -285.160974)
		(end 92.811092 -285.426404)
		(width 0.0889)
		(layer "In4.Cu")
		(net "M_D_CPU1_SB_DQ<19>")
	)
	(segment
		(start 84.529676 -285.098998)
		(end 84.538058 -285.103824)
		(width 0.0889)
		(layer "In4.Cu")
		(net "M_D_CPU1_SB_DQ<19>")
	)
	(segment
		(start 53.658516 -302.30064)
		(end 54.122828 -302.764952)
		(width 0.14478)
		(layer "In4.Cu")
		(net "M_D_CPU1_SB_DQ<19>")
	)
	(segment
		(start 75.866244 -285.831534)
		(end 75.921616 -285.831534)
		(width 0.14478)
		(layer "In4.Cu")
		(net "M_D_CPU1_SB_DQ<19>")
	)
	(segment
		(start 33.840166 -302.464978)
		(end 34.00298 -302.302164)
		(width 0.14478)
		(layer "In4.Cu")
		(net "M_D_CPU1_SB_DQ<19>")
	)
	(segment
		(start 54.122828 -302.764952)
		(end 56.935116 -302.764952)
		(width 0.14478)
		(layer "In4.Cu")
		(net "M_D_CPU1_SB_DQ<19>")
	)
	(segment
		(start 56.935116 -302.764952)
		(end 57.474104 -302.225964)
		(width 0.14478)
		(layer "In4.Cu")
		(net "M_D_CPU1_SB_DQ<19>")
	)
	(segment
		(start 90.74404 -285.103824)
		(end 90.752422 -285.098998)
		(width 0.0889)
		(layer "In4.Cu")
		(net "M_D_CPU1_SB_DQ<19>")
	)
	(arc
		(start 86.418166 -285.103824)
		(mid 86.701122 -285.180001)
		(end 86.984078 -285.103824)
		(width 0.0889)
		(layer "In4.Cu")
		(net "M_D_CPU1_SB_DQ<19>")
	)
	(arc
		(start 80.403954 -285.103824)
		(mid 80.586205 -285.053474)
		(end 80.769714 -285.098998)
		(width 0.0889)
		(layer "In4.Cu")
		(net "M_D_CPU1_SB_DQ<19>")
	)
	(arc
		(start 76.731876 -285.3817)
		(mid 76.768687 -285.35704)
		(end 76.81214 -285.348426)
		(width 0.0889)
		(layer "In4.Cu")
		(net "M_D_CPU1_SB_DQ<19>")
	)
	(arc
		(start 92.057982 -285.103824)
		(mid 92.305578 -285.179002)
		(end 92.560648 -285.135574)
		(width 0.0889)
		(layer "In4.Cu")
		(net "M_D_CPU1_SB_DQ<19>")
	)
	(arc
		(start 80.778096 -285.103824)
		(mid 81.061052 -285.180001)
		(end 81.344008 -285.103824)
		(width 0.0889)
		(layer "In4.Cu")
		(net "M_D_CPU1_SB_DQ<19>")
	)
	(arc
		(start 83.223862 -285.103824)
		(mid 83.406113 -285.053474)
		(end 83.589622 -285.098998)
		(width 0.0889)
		(layer "In4.Cu")
		(net "M_D_CPU1_SB_DQ<19>")
	)
	(arc
		(start 81.71815 -285.103824)
		(mid 82.001106 -285.180001)
		(end 82.284062 -285.103824)
		(width 0.0889)
		(layer "In4.Cu")
		(net "M_D_CPU1_SB_DQ<19>")
	)
	(arc
		(start 83.598004 -285.103824)
		(mid 83.88096 -285.180001)
		(end 84.163916 -285.103824)
		(width 0.0889)
		(layer "In4.Cu")
		(net "M_D_CPU1_SB_DQ<19>")
	)
	(arc
		(start 90.752422 -285.098998)
		(mid 90.93593 -285.053504)
		(end 91.118182 -285.103824)
		(width 0.0889)
		(layer "In4.Cu")
		(net "M_D_CPU1_SB_DQ<19>")
	)
	(arc
		(start 87.923878 -285.103824)
		(mid 88.106129 -285.053474)
		(end 88.289638 -285.098998)
		(width 0.0889)
		(layer "In4.Cu")
		(net "M_D_CPU1_SB_DQ<19>")
	)
	(arc
		(start 77.61478 -285.348426)
		(mid 78.08535 -285.286195)
		(end 78.523592 -285.103824)
		(width 0.0889)
		(layer "In4.Cu")
		(net "M_D_CPU1_SB_DQ<19>")
	)
	(arc
		(start 84.163916 -285.103824)
		(mid 84.346167 -285.053474)
		(end 84.529676 -285.098998)
		(width 0.0889)
		(layer "In4.Cu")
		(net "M_D_CPU1_SB_DQ<19>")
	)
	(arc
		(start 85.112352 -285.098998)
		(mid 85.29586 -285.053504)
		(end 85.478112 -285.103824)
		(width 0.0889)
		(layer "In4.Cu")
		(net "M_D_CPU1_SB_DQ<19>")
	)
	(arc
		(start 78.523592 -285.103824)
		(mid 78.70022 -285.053591)
		(end 78.879446 -285.093664)
		(width 0.0889)
		(layer "In4.Cu")
		(net "M_D_CPU1_SB_DQ<19>")
	)
	(arc
		(start 86.984078 -285.103824)
		(mid 87.171022 -285.053569)
		(end 87.357966 -285.103824)
		(width 0.0889)
		(layer "In4.Cu")
		(net "M_D_CPU1_SB_DQ<19>")
	)
	(arc
		(start 90.178128 -285.103824)
		(mid 90.461084 -285.180001)
		(end 90.74404 -285.103824)
		(width 0.0889)
		(layer "In4.Cu")
		(net "M_D_CPU1_SB_DQ<19>")
	)
	(arc
		(start 82.65795 -285.103824)
		(mid 82.940906 -285.180001)
		(end 83.223862 -285.103824)
		(width 0.0889)
		(layer "In4.Cu")
		(net "M_D_CPU1_SB_DQ<19>")
	)
	(arc
		(start 82.284062 -285.103824)
		(mid 82.471006 -285.053569)
		(end 82.65795 -285.103824)
		(width 0.0889)
		(layer "In4.Cu")
		(net "M_D_CPU1_SB_DQ<19>")
	)
	(arc
		(start 85.478112 -285.103824)
		(mid 85.761068 -285.180001)
		(end 86.044024 -285.103824)
		(width 0.0889)
		(layer "In4.Cu")
		(net "M_D_CPU1_SB_DQ<19>")
	)
	(arc
		(start 86.052406 -285.098998)
		(mid 86.235914 -285.053504)
		(end 86.418166 -285.103824)
		(width 0.0889)
		(layer "In4.Cu")
		(net "M_D_CPU1_SB_DQ<19>")
	)
	(arc
		(start 79.474822 -285.096966)
		(mid 79.657077 -285.053313)
		(end 79.837534 -285.103824)
		(width 0.0889)
		(layer "In4.Cu")
		(net "M_D_CPU1_SB_DQ<19>")
	)
	(arc
		(start 91.684094 -285.103824)
		(mid 91.871038 -285.053569)
		(end 92.057982 -285.103824)
		(width 0.0889)
		(layer "In4.Cu")
		(net "M_D_CPU1_SB_DQ<19>")
	)
	(arc
		(start 89.238074 -285.103824)
		(mid 89.52103 -285.180001)
		(end 89.803986 -285.103824)
		(width 0.0889)
		(layer "In4.Cu")
		(net "M_D_CPU1_SB_DQ<19>")
	)
	(arc
		(start 88.863932 -285.103824)
		(mid 89.046183 -285.053474)
		(end 89.229692 -285.098998)
		(width 0.0889)
		(layer "In4.Cu")
		(net "M_D_CPU1_SB_DQ<19>")
	)
	(arc
		(start 81.35239 -285.098998)
		(mid 81.535898 -285.053504)
		(end 81.71815 -285.103824)
		(width 0.0889)
		(layer "In4.Cu")
		(net "M_D_CPU1_SB_DQ<19>")
	)
	(arc
		(start 78.903322 -285.10738)
		(mid 79.183711 -285.180049)
		(end 79.463138 -285.103824)
		(width 0.0889)
		(layer "In4.Cu")
		(net "M_D_CPU1_SB_DQ<19>")
	)
	(arc
		(start 91.118182 -285.103824)
		(mid 91.401138 -285.180001)
		(end 91.684094 -285.103824)
		(width 0.0889)
		(layer "In4.Cu")
		(net "M_D_CPU1_SB_DQ<19>")
	)
	(arc
		(start 89.812368 -285.098998)
		(mid 89.995876 -285.053504)
		(end 90.178128 -285.103824)
		(width 0.0889)
		(layer "In4.Cu")
		(net "M_D_CPU1_SB_DQ<19>")
	)
	(arc
		(start 88.29802 -285.103824)
		(mid 88.580976 -285.180001)
		(end 88.863932 -285.103824)
		(width 0.0889)
		(layer "In4.Cu")
		(net "M_D_CPU1_SB_DQ<19>")
	)
	(arc
		(start 87.357966 -285.103824)
		(mid 87.640922 -285.180001)
		(end 87.923878 -285.103824)
		(width 0.0889)
		(layer "In4.Cu")
		(net "M_D_CPU1_SB_DQ<19>")
	)
	(arc
		(start 79.837534 -285.103824)
		(mid 80.11224 -285.180188)
		(end 80.389222 -285.11246)
		(width 0.0889)
		(layer "In4.Cu")
		(net "M_D_CPU1_SB_DQ<19>")
	)
	(arc
		(start 84.538058 -285.103824)
		(mid 84.821014 -285.180001)
		(end 85.10397 -285.103824)
		(width 0.0889)
		(layer "In4.Cu")
		(net "M_D_CPU1_SB_DQ<19>")
	)
	(segment
		(start 91.86799 -284.35046)
		(end 91.401138 -284.616398)
		(width 0.10668)
		(layer "F.Cu")
		(net "M_D_CPU1_SB_DQ<18>")
	)
	(segment
		(start 34.620962 -300.686978)
		(end 34.783776 -300.524164)
		(width 0.14478)
		(layer "In4.Cu")
		(net "M_D_CPU1_SB_DQ<18>")
	)
	(segment
		(start 83.694016 -284.293818)
		(end 83.702398 -284.288992)
		(width 0.0889)
		(layer "In4.Cu")
		(net "M_D_CPU1_SB_DQ<18>")
	)
	(segment
		(start 59.79668 -300.61027)
		(end 75.484736 -284.922214)
		(width 0.14478)
		(layer "In4.Cu")
		(net "M_D_CPU1_SB_DQ<18>")
	)
	(segment
		(start 53.415692 -300.61027)
		(end 54.26583 -301.460408)
		(width 0.14478)
		(layer "In4.Cu")
		(net "M_D_CPU1_SB_DQ<18>")
	)
	(segment
		(start 33.121092 -301.460408)
		(end 33.345628 -301.460408)
		(width 0.14478)
		(layer "In4.Cu")
		(net "M_D_CPU1_SB_DQ<18>")
	)
	(segment
		(start 42.52468 -300.61027)
		(end 46.151292 -300.61027)
		(width 0.14478)
		(layer "In4.Cu")
		(net "M_D_CPU1_SB_DQ<18>")
	)
	(segment
		(start 86.879684 -284.288992)
		(end 86.888066 -284.293818)
		(width 0.0889)
		(layer "In4.Cu")
		(net "M_D_CPU1_SB_DQ<18>")
	)
	(segment
		(start 78.993492 -284.294072)
		(end 79.009748 -284.284674)
		(width 0.0889)
		(layer "In4.Cu")
		(net "M_D_CPU1_SB_DQ<18>")
	)
	(segment
		(start 32.695896 -301.035212)
		(end 33.121092 -301.460408)
		(width 0.14478)
		(layer "In4.Cu")
		(net "M_D_CPU1_SB_DQ<18>")
	)
	(segment
		(start 79.36738 -284.293818)
		(end 79.377794 -284.299914)
		(width 0.0889)
		(layer "In4.Cu")
		(net "M_D_CPU1_SB_DQ<18>")
	)
	(segment
		(start 33.508442 -301.297594)
		(end 33.508442 -300.686978)
		(width 0.14478)
		(layer "In4.Cu")
		(net "M_D_CPU1_SB_DQ<18>")
	)
	(segment
		(start 33.345628 -301.460408)
		(end 33.508442 -301.297594)
		(width 0.14478)
		(layer "In4.Cu")
		(net "M_D_CPU1_SB_DQ<18>")
	)
	(segment
		(start 85.93963 -284.288992)
		(end 85.948012 -284.293818)
		(width 0.0889)
		(layer "In4.Cu")
		(net "M_D_CPU1_SB_DQ<18>")
	)
	(segment
		(start 34.064702 -300.686978)
		(end 34.064702 -301.297594)
		(width 0.14478)
		(layer "In4.Cu")
		(net "M_D_CPU1_SB_DQ<18>")
	)
	(segment
		(start 50.284888 -300.61027)
		(end 53.415692 -300.61027)
		(width 0.14478)
		(layer "In4.Cu")
		(net "M_D_CPU1_SB_DQ<18>")
	)
	(segment
		(start 90.639646 -284.288992)
		(end 90.648028 -284.293818)
		(width 0.0889)
		(layer "In4.Cu")
		(net "M_D_CPU1_SB_DQ<18>")
	)
	(segment
		(start 82.179668 -284.288992)
		(end 82.18805 -284.293818)
		(width 0.0889)
		(layer "In4.Cu")
		(net "M_D_CPU1_SB_DQ<18>")
	)
	(segment
		(start 87.453978 -284.293818)
		(end 87.46236 -284.288992)
		(width 0.0889)
		(layer "In4.Cu")
		(net "M_D_CPU1_SB_DQ<18>")
	)
	(segment
		(start 76.276962 -284.922214)
		(end 76.48321 -284.715966)
		(width 0.0889)
		(layer "In4.Cu")
		(net "M_D_CPU1_SB_DQ<18>")
	)
	(segment
		(start 54.26583 -301.460408)
		(end 56.95315 -301.460408)
		(width 0.14478)
		(layer "In4.Cu")
		(net "M_D_CPU1_SB_DQ<18>")
	)
	(segment
		(start 49.43475 -301.460408)
		(end 50.284888 -300.61027)
		(width 0.14478)
		(layer "In4.Cu")
		(net "M_D_CPU1_SB_DQ<18>")
	)
	(segment
		(start 88.394032 -284.293818)
		(end 88.402414 -284.288992)
		(width 0.0889)
		(layer "In4.Cu")
		(net "M_D_CPU1_SB_DQ<18>")
	)
	(segment
		(start 35.340036 -301.460408)
		(end 41.674542 -301.460408)
		(width 0.14478)
		(layer "In4.Cu")
		(net "M_D_CPU1_SB_DQ<18>")
	)
	(segment
		(start 77.53223 -284.715966)
		(end 77.878178 -284.370018)
		(width 0.0889)
		(layer "In4.Cu")
		(net "M_D_CPU1_SB_DQ<18>")
	)
	(segment
		(start 35.177222 -300.686978)
		(end 35.177222 -301.297594)
		(width 0.14478)
		(layer "In4.Cu")
		(net "M_D_CPU1_SB_DQ<18>")
	)
	(segment
		(start 35.177222 -301.297594)
		(end 35.340036 -301.460408)
		(width 0.14478)
		(layer "In4.Cu")
		(net "M_D_CPU1_SB_DQ<18>")
	)
	(segment
		(start 91.150694 -284.325568)
		(end 91.24696 -284.350968)
		(width 0.0889)
		(layer "In4.Cu")
		(net "M_D_CPU1_SB_DQ<18>")
	)
	(segment
		(start 77.878178 -284.370018)
		(end 78.711044 -284.370018)
		(width 0.0889)
		(layer "In4.Cu")
		(net "M_D_CPU1_SB_DQ<18>")
	)
	(segment
		(start 46.151292 -300.61027)
		(end 47.00143 -301.460408)
		(width 0.14478)
		(layer "In4.Cu")
		(net "M_D_CPU1_SB_DQ<18>")
	)
	(segment
		(start 82.753962 -284.293818)
		(end 82.762344 -284.288992)
		(width 0.0889)
		(layer "In4.Cu")
		(net "M_D_CPU1_SB_DQ<18>")
	)
	(segment
		(start 57.803288 -300.61027)
		(end 59.79668 -300.61027)
		(width 0.14478)
		(layer "In4.Cu")
		(net "M_D_CPU1_SB_DQ<18>")
	)
	(segment
		(start 75.973686 -284.922214)
		(end 76.276962 -284.922214)
		(width 0.0889)
		(layer "In4.Cu")
		(net "M_D_CPU1_SB_DQ<18>")
	)
	(segment
		(start 33.508442 -300.686978)
		(end 33.671256 -300.524164)
		(width 0.14478)
		(layer "In4.Cu")
		(net "M_D_CPU1_SB_DQ<18>")
	)
	(segment
		(start 34.458148 -301.460408)
		(end 34.620962 -301.297594)
		(width 0.14478)
		(layer "In4.Cu")
		(net "M_D_CPU1_SB_DQ<18>")
	)
	(segment
		(start 33.671256 -300.524164)
		(end 33.901888 -300.524164)
		(width 0.14478)
		(layer "In4.Cu")
		(net "M_D_CPU1_SB_DQ<18>")
	)
	(segment
		(start 56.95315 -301.460408)
		(end 57.803288 -300.61027)
		(width 0.14478)
		(layer "In4.Cu")
		(net "M_D_CPU1_SB_DQ<18>")
	)
	(segment
		(start 34.620962 -301.297594)
		(end 34.620962 -300.686978)
		(width 0.14478)
		(layer "In4.Cu")
		(net "M_D_CPU1_SB_DQ<18>")
	)
	(segment
		(start 76.48321 -284.715966)
		(end 77.53223 -284.715966)
		(width 0.0889)
		(layer "In4.Cu")
		(net "M_D_CPU1_SB_DQ<18>")
	)
	(segment
		(start 34.064702 -301.297594)
		(end 34.227516 -301.460408)
		(width 0.14478)
		(layer "In4.Cu")
		(net "M_D_CPU1_SB_DQ<18>")
	)
	(segment
		(start 33.901888 -300.524164)
		(end 34.064702 -300.686978)
		(width 0.14478)
		(layer "In4.Cu")
		(net "M_D_CPU1_SB_DQ<18>")
	)
	(segment
		(start 91.24696 -284.350968)
		(end 91.401138 -284.616398)
		(width 0.0889)
		(layer "In4.Cu")
		(net "M_D_CPU1_SB_DQ<18>")
	)
	(segment
		(start 41.674542 -301.460408)
		(end 42.52468 -300.61027)
		(width 0.14478)
		(layer "In4.Cu")
		(net "M_D_CPU1_SB_DQ<18>")
	)
	(segment
		(start 35.014408 -300.524164)
		(end 35.177222 -300.686978)
		(width 0.14478)
		(layer "In4.Cu")
		(net "M_D_CPU1_SB_DQ<18>")
	)
	(segment
		(start 34.227516 -301.460408)
		(end 34.458148 -301.460408)
		(width 0.14478)
		(layer "In4.Cu")
		(net "M_D_CPU1_SB_DQ<18>")
	)
	(segment
		(start 80.299814 -284.288992)
		(end 80.308196 -284.293818)
		(width 0.0889)
		(layer "In4.Cu")
		(net "M_D_CPU1_SB_DQ<18>")
	)
	(segment
		(start 47.00143 -301.460408)
		(end 49.43475 -301.460408)
		(width 0.14478)
		(layer "In4.Cu")
		(net "M_D_CPU1_SB_DQ<18>")
	)
	(segment
		(start 34.783776 -300.524164)
		(end 35.014408 -300.524164)
		(width 0.14478)
		(layer "In4.Cu")
		(net "M_D_CPU1_SB_DQ<18>")
	)
	(segment
		(start 75.484736 -284.922214)
		(end 75.973686 -284.922214)
		(width 0.14478)
		(layer "In4.Cu")
		(net "M_D_CPU1_SB_DQ<18>")
	)
	(arc
		(start 82.762344 -284.288992)
		(mid 82.945852 -284.243498)
		(end 83.128104 -284.293818)
		(width 0.0889)
		(layer "In4.Cu")
		(net "M_D_CPU1_SB_DQ<18>")
	)
	(arc
		(start 87.46236 -284.288992)
		(mid 87.645868 -284.243498)
		(end 87.82812 -284.293818)
		(width 0.0889)
		(layer "In4.Cu")
		(net "M_D_CPU1_SB_DQ<18>")
	)
	(arc
		(start 88.402414 -284.288992)
		(mid 88.585922 -284.243498)
		(end 88.768174 -284.293818)
		(width 0.0889)
		(layer "In4.Cu")
		(net "M_D_CPU1_SB_DQ<18>")
	)
	(arc
		(start 81.813908 -284.293818)
		(mid 81.996159 -284.243468)
		(end 82.179668 -284.288992)
		(width 0.0889)
		(layer "In4.Cu")
		(net "M_D_CPU1_SB_DQ<18>")
	)
	(arc
		(start 89.707974 -284.293818)
		(mid 89.99093 -284.369995)
		(end 90.273886 -284.293818)
		(width 0.0889)
		(layer "In4.Cu")
		(net "M_D_CPU1_SB_DQ<18>")
	)
	(arc
		(start 88.768174 -284.293818)
		(mid 89.05113 -284.369995)
		(end 89.334086 -284.293818)
		(width 0.0889)
		(layer "In4.Cu")
		(net "M_D_CPU1_SB_DQ<18>")
	)
	(arc
		(start 80.874108 -284.293818)
		(mid 81.061052 -284.243563)
		(end 81.247996 -284.293818)
		(width 0.0889)
		(layer "In4.Cu")
		(net "M_D_CPU1_SB_DQ<18>")
	)
	(arc
		(start 85.007958 -284.293818)
		(mid 85.290914 -284.369995)
		(end 85.57387 -284.293818)
		(width 0.0889)
		(layer "In4.Cu")
		(net "M_D_CPU1_SB_DQ<18>")
	)
	(arc
		(start 81.247996 -284.293818)
		(mid 81.530952 -284.369995)
		(end 81.813908 -284.293818)
		(width 0.0889)
		(layer "In4.Cu")
		(net "M_D_CPU1_SB_DQ<18>")
	)
	(arc
		(start 79.933546 -284.293818)
		(mid 80.116051 -284.243341)
		(end 80.299814 -284.288992)
		(width 0.0889)
		(layer "In4.Cu")
		(net "M_D_CPU1_SB_DQ<18>")
	)
	(arc
		(start 86.513924 -284.293818)
		(mid 86.696175 -284.243468)
		(end 86.879684 -284.288992)
		(width 0.0889)
		(layer "In4.Cu")
		(net "M_D_CPU1_SB_DQ<18>")
	)
	(arc
		(start 80.308196 -284.293818)
		(mid 80.591152 -284.369995)
		(end 80.874108 -284.293818)
		(width 0.0889)
		(layer "In4.Cu")
		(net "M_D_CPU1_SB_DQ<18>")
	)
	(arc
		(start 79.009748 -284.284674)
		(mid 79.18973 -284.243574)
		(end 79.36738 -284.293818)
		(width 0.0889)
		(layer "In4.Cu")
		(net "M_D_CPU1_SB_DQ<18>")
	)
	(arc
		(start 86.888066 -284.293818)
		(mid 87.171022 -284.369995)
		(end 87.453978 -284.293818)
		(width 0.0889)
		(layer "In4.Cu")
		(net "M_D_CPU1_SB_DQ<18>")
	)
	(arc
		(start 85.57387 -284.293818)
		(mid 85.756121 -284.243468)
		(end 85.93963 -284.288992)
		(width 0.0889)
		(layer "In4.Cu")
		(net "M_D_CPU1_SB_DQ<18>")
	)
	(arc
		(start 90.648028 -284.293818)
		(mid 90.895624 -284.368996)
		(end 91.150694 -284.325568)
		(width 0.0889)
		(layer "In4.Cu")
		(net "M_D_CPU1_SB_DQ<18>")
	)
	(arc
		(start 79.377794 -284.299914)
		(mid 79.65648 -284.370134)
		(end 79.933546 -284.293818)
		(width 0.0889)
		(layer "In4.Cu")
		(net "M_D_CPU1_SB_DQ<18>")
	)
	(arc
		(start 83.702398 -284.288992)
		(mid 83.885906 -284.243498)
		(end 84.068158 -284.293818)
		(width 0.0889)
		(layer "In4.Cu")
		(net "M_D_CPU1_SB_DQ<18>")
	)
	(arc
		(start 82.18805 -284.293818)
		(mid 82.471006 -284.369995)
		(end 82.753962 -284.293818)
		(width 0.0889)
		(layer "In4.Cu")
		(net "M_D_CPU1_SB_DQ<18>")
	)
	(arc
		(start 84.068158 -284.293818)
		(mid 84.351114 -284.369995)
		(end 84.63407 -284.293818)
		(width 0.0889)
		(layer "In4.Cu")
		(net "M_D_CPU1_SB_DQ<18>")
	)
	(arc
		(start 85.948012 -284.293818)
		(mid 86.230968 -284.369995)
		(end 86.513924 -284.293818)
		(width 0.0889)
		(layer "In4.Cu")
		(net "M_D_CPU1_SB_DQ<18>")
	)
	(arc
		(start 84.63407 -284.293818)
		(mid 84.821014 -284.243563)
		(end 85.007958 -284.293818)
		(width 0.0889)
		(layer "In4.Cu")
		(net "M_D_CPU1_SB_DQ<18>")
	)
	(arc
		(start 90.273886 -284.293818)
		(mid 90.456137 -284.243468)
		(end 90.639646 -284.288992)
		(width 0.0889)
		(layer "In4.Cu")
		(net "M_D_CPU1_SB_DQ<18>")
	)
	(arc
		(start 87.82812 -284.293818)
		(mid 88.111076 -284.369995)
		(end 88.394032 -284.293818)
		(width 0.0889)
		(layer "In4.Cu")
		(net "M_D_CPU1_SB_DQ<18>")
	)
	(arc
		(start 83.128104 -284.293818)
		(mid 83.41106 -284.369995)
		(end 83.694016 -284.293818)
		(width 0.0889)
		(layer "In4.Cu")
		(net "M_D_CPU1_SB_DQ<18>")
	)
	(arc
		(start 78.711044 -284.370018)
		(mid 78.857292 -284.350713)
		(end 78.993492 -284.294072)
		(width 0.0889)
		(layer "In4.Cu")
		(net "M_D_CPU1_SB_DQ<18>")
	)
	(arc
		(start 89.334086 -284.293818)
		(mid 89.52103 -284.243563)
		(end 89.707974 -284.293818)
		(width 0.0889)
		(layer "In4.Cu")
		(net "M_D_CPU1_SB_DQ<18>")
	)
	(segment
		(start 92.80779 -284.35046)
		(end 92.340938 -284.616398)
		(width 0.10668)
		(layer "F.Cu")
		(net "M_D_CPU1_SB_DQ<17>")
	)
	(segment
		(start 52.851304 -301.24527)
		(end 53.014118 -301.082456)
		(width 0.14478)
		(layer "In4.Cu")
		(net "M_D_CPU1_SB_DQ<17>")
	)
	(segment
		(start 36.795964 -301.88535)
		(end 37.593778 -302.683164)
		(width 0.14478)
		(layer "In4.Cu")
		(net "M_D_CPU1_SB_DQ<17>")
	)
	(segment
		(start 86.879684 -284.943804)
		(end 86.888066 -284.938978)
		(width 0.0889)
		(layer "In4.Cu")
		(net "M_D_CPU1_SB_DQ<17>")
	)
	(segment
		(start 60.164218 -301.717964)
		(end 60.318396 -301.563786)
		(width 0.14478)
		(layer "In4.Cu")
		(net "M_D_CPU1_SB_DQ<17>")
	)
	(segment
		(start 52.448968 -301.843186)
		(end 52.69738 -301.843186)
		(width 0.14478)
		(layer "In4.Cu")
		(net "M_D_CPU1_SB_DQ<17>")
	)
	(segment
		(start 39.167562 -302.100234)
		(end 39.330376 -301.93742)
		(width 0.14478)
		(layer "In4.Cu")
		(net "M_D_CPU1_SB_DQ<17>")
	)
	(segment
		(start 58.559954 -301.717964)
		(end 58.807858 -301.717964)
		(width 0.14478)
		(layer "In4.Cu")
		(net "M_D_CPU1_SB_DQ<17>")
	)
	(segment
		(start 78.427834 -284.938978)
		(end 78.42758 -284.938978)
		(width 0.0889)
		(layer "In4.Cu")
		(net "M_D_CPU1_SB_DQ<17>")
	)
	(segment
		(start 38.055042 -302.52035)
		(end 38.055042 -302.100234)
		(width 0.14478)
		(layer "In4.Cu")
		(net "M_D_CPU1_SB_DQ<17>")
	)
	(segment
		(start 39.561008 -301.93742)
		(end 39.93388 -302.310292)
		(width 0.14478)
		(layer "In4.Cu")
		(net "M_D_CPU1_SB_DQ<17>")
	)
	(segment
		(start 51.025552 -301.838614)
		(end 51.256184 -301.838614)
		(width 0.14478)
		(layer "In4.Cu")
		(net "M_D_CPU1_SB_DQ<17>")
	)
	(segment
		(start 52.851304 -301.689262)
		(end 52.851304 -301.24527)
		(width 0.14478)
		(layer "In4.Cu")
		(net "M_D_CPU1_SB_DQ<17>")
	)
	(segment
		(start 38.611302 -302.100234)
		(end 38.611302 -302.52035)
		(width 0.14478)
		(layer "In4.Cu")
		(net "M_D_CPU1_SB_DQ<17>")
	)
	(segment
		(start 58.239152 -301.151544)
		(end 58.39333 -301.305722)
		(width 0.14478)
		(layer "In4.Cu")
		(net "M_D_CPU1_SB_DQ<17>")
	)
	(segment
		(start 52.065936 -301.460154)
		(end 52.448968 -301.843186)
		(width 0.14478)
		(layer "In4.Cu")
		(net "M_D_CPU1_SB_DQ<17>")
	)
	(segment
		(start 80.299814 -284.943804)
		(end 80.308196 -284.938978)
		(width 0.0889)
		(layer "In4.Cu")
		(net "M_D_CPU1_SB_DQ<17>")
	)
	(segment
		(start 38.448488 -301.93742)
		(end 38.611302 -302.100234)
		(width 0.14478)
		(layer "In4.Cu")
		(net "M_D_CPU1_SB_DQ<17>")
	)
	(segment
		(start 51.256184 -301.838614)
		(end 51.634644 -301.460154)
		(width 0.14478)
		(layer "In4.Cu")
		(net "M_D_CPU1_SB_DQ<17>")
	)
	(segment
		(start 45.22851 -301.460408)
		(end 45.605954 -301.082964)
		(width 0.14478)
		(layer "In4.Cu")
		(net "M_D_CPU1_SB_DQ<17>")
	)
	(segment
		(start 54.472586 -302.310292)
		(end 56.746394 -302.310292)
		(width 0.14478)
		(layer "In4.Cu")
		(net "M_D_CPU1_SB_DQ<17>")
	)
	(segment
		(start 92.495116 -284.881828)
		(end 92.340938 -284.616398)
		(width 0.0889)
		(layer "In4.Cu")
		(net "M_D_CPU1_SB_DQ<17>")
	)
	(segment
		(start 92.472764 -284.96514)
		(end 92.495116 -284.881828)
		(width 0.0889)
		(layer "In4.Cu")
		(net "M_D_CPU1_SB_DQ<17>")
	)
	(segment
		(start 38.055042 -302.100234)
		(end 38.217856 -301.93742)
		(width 0.14478)
		(layer "In4.Cu")
		(net "M_D_CPU1_SB_DQ<17>")
	)
	(segment
		(start 76.67498 -285.056326)
		(end 77.992224 -285.056326)
		(width 0.0889)
		(layer "In4.Cu")
		(net "M_D_CPU1_SB_DQ<17>")
	)
	(segment
		(start 91.5797 -284.943804)
		(end 91.588082 -284.938978)
		(width 0.0889)
		(layer "In4.Cu")
		(net "M_D_CPU1_SB_DQ<17>")
	)
	(segment
		(start 79.367126 -284.938978)
		(end 79.381858 -284.930342)
		(width 0.0889)
		(layer "In4.Cu")
		(net "M_D_CPU1_SB_DQ<17>")
	)
	(segment
		(start 58.39333 -301.55134)
		(end 58.559954 -301.717964)
		(width 0.14478)
		(layer "In4.Cu")
		(net "M_D_CPU1_SB_DQ<17>")
	)
	(segment
		(start 39.93388 -302.310292)
		(end 41.637458 -302.310292)
		(width 0.14478)
		(layer "In4.Cu")
		(net "M_D_CPU1_SB_DQ<17>")
	)
	(segment
		(start 60.318396 -300.736254)
		(end 75.677776 -285.376874)
		(width 0.14478)
		(layer "In4.Cu")
		(net "M_D_CPU1_SB_DQ<17>")
	)
	(segment
		(start 38.774116 -302.683164)
		(end 39.004748 -302.683164)
		(width 0.14478)
		(layer "In4.Cu")
		(net "M_D_CPU1_SB_DQ<17>")
	)
	(segment
		(start 51.634644 -301.460154)
		(end 52.065936 -301.460154)
		(width 0.14478)
		(layer "In4.Cu")
		(net "M_D_CPU1_SB_DQ<17>")
	)
	(segment
		(start 41.637458 -302.310292)
		(end 42.487342 -301.460408)
		(width 0.14478)
		(layer "In4.Cu")
		(net "M_D_CPU1_SB_DQ<17>")
	)
	(segment
		(start 49.227994 -302.310292)
		(end 50.469292 -301.068994)
		(width 0.14478)
		(layer "In4.Cu")
		(net "M_D_CPU1_SB_DQ<17>")
	)
	(segment
		(start 59.065668 -301.460154)
		(end 59.658504 -301.460154)
		(width 0.14478)
		(layer "In4.Cu")
		(net "M_D_CPU1_SB_DQ<17>")
	)
	(segment
		(start 38.611302 -302.52035)
		(end 38.774116 -302.683164)
		(width 0.14478)
		(layer "In4.Cu")
		(net "M_D_CPU1_SB_DQ<17>")
	)
	(segment
		(start 52.69738 -301.843186)
		(end 52.851304 -301.689262)
		(width 0.14478)
		(layer "In4.Cu")
		(net "M_D_CPU1_SB_DQ<17>")
	)
	(segment
		(start 50.862738 -301.231808)
		(end 50.862738 -301.6758)
		(width 0.14478)
		(layer "In4.Cu")
		(net "M_D_CPU1_SB_DQ<17>")
	)
	(segment
		(start 83.694016 -284.938978)
		(end 83.702398 -284.943804)
		(width 0.0889)
		(layer "In4.Cu")
		(net "M_D_CPU1_SB_DQ<17>")
	)
	(segment
		(start 45.605954 -301.082964)
		(end 45.836586 -301.082964)
		(width 0.14478)
		(layer "In4.Cu")
		(net "M_D_CPU1_SB_DQ<17>")
	)
	(segment
		(start 58.807858 -301.717964)
		(end 59.065668 -301.460154)
		(width 0.14478)
		(layer "In4.Cu")
		(net "M_D_CPU1_SB_DQ<17>")
	)
	(segment
		(start 82.179668 -284.943804)
		(end 82.18805 -284.938978)
		(width 0.0889)
		(layer "In4.Cu")
		(net "M_D_CPU1_SB_DQ<17>")
	)
	(segment
		(start 56.746394 -302.310292)
		(end 57.905142 -301.151544)
		(width 0.14478)
		(layer "In4.Cu")
		(net "M_D_CPU1_SB_DQ<17>")
	)
	(segment
		(start 57.905142 -301.151544)
		(end 58.239152 -301.151544)
		(width 0.14478)
		(layer "In4.Cu")
		(net "M_D_CPU1_SB_DQ<17>")
	)
	(segment
		(start 59.916314 -301.717964)
		(end 60.164218 -301.717964)
		(width 0.14478)
		(layer "In4.Cu")
		(net "M_D_CPU1_SB_DQ<17>")
	)
	(segment
		(start 76.307442 -285.376874)
		(end 76.594716 -285.0896)
		(width 0.0889)
		(layer "In4.Cu")
		(net "M_D_CPU1_SB_DQ<17>")
	)
	(segment
		(start 75.958446 -285.376874)
		(end 76.307442 -285.376874)
		(width 0.0889)
		(layer "In4.Cu")
		(net "M_D_CPU1_SB_DQ<17>")
	)
	(segment
		(start 75.677776 -285.376874)
		(end 75.958446 -285.376874)
		(width 0.14478)
		(layer "In4.Cu")
		(net "M_D_CPU1_SB_DQ<17>")
	)
	(segment
		(start 87.453978 -284.938978)
		(end 87.46236 -284.943804)
		(width 0.0889)
		(layer "In4.Cu")
		(net "M_D_CPU1_SB_DQ<17>")
	)
	(segment
		(start 88.394032 -284.938978)
		(end 88.402414 -284.943804)
		(width 0.0889)
		(layer "In4.Cu")
		(net "M_D_CPU1_SB_DQ<17>")
	)
	(segment
		(start 78.977744 -284.92958)
		(end 78.993492 -284.938724)
		(width 0.0889)
		(layer "In4.Cu")
		(net "M_D_CPU1_SB_DQ<17>")
	)
	(segment
		(start 39.330376 -301.93742)
		(end 39.561008 -301.93742)
		(width 0.14478)
		(layer "In4.Cu")
		(net "M_D_CPU1_SB_DQ<17>")
	)
	(segment
		(start 39.167562 -302.52035)
		(end 39.167562 -302.100234)
		(width 0.14478)
		(layer "In4.Cu")
		(net "M_D_CPU1_SB_DQ<17>")
	)
	(segment
		(start 45.836586 -301.082964)
		(end 47.063914 -302.310292)
		(width 0.14478)
		(layer "In4.Cu")
		(net "M_D_CPU1_SB_DQ<17>")
	)
	(segment
		(start 47.063914 -302.310292)
		(end 49.227994 -302.310292)
		(width 0.14478)
		(layer "In4.Cu")
		(net "M_D_CPU1_SB_DQ<17>")
	)
	(segment
		(start 59.658504 -301.460154)
		(end 59.916314 -301.717964)
		(width 0.14478)
		(layer "In4.Cu")
		(net "M_D_CPU1_SB_DQ<17>")
	)
	(segment
		(start 82.753962 -284.938978)
		(end 82.762344 -284.943804)
		(width 0.0889)
		(layer "In4.Cu")
		(net "M_D_CPU1_SB_DQ<17>")
	)
	(segment
		(start 50.699924 -301.068994)
		(end 50.862738 -301.231808)
		(width 0.14478)
		(layer "In4.Cu")
		(net "M_D_CPU1_SB_DQ<17>")
	)
	(segment
		(start 50.469292 -301.068994)
		(end 50.699924 -301.068994)
		(width 0.14478)
		(layer "In4.Cu")
		(net "M_D_CPU1_SB_DQ<17>")
	)
	(segment
		(start 50.862738 -301.6758)
		(end 51.025552 -301.838614)
		(width 0.14478)
		(layer "In4.Cu")
		(net "M_D_CPU1_SB_DQ<17>")
	)
	(segment
		(start 38.217856 -301.93742)
		(end 38.448488 -301.93742)
		(width 0.14478)
		(layer "In4.Cu")
		(net "M_D_CPU1_SB_DQ<17>")
	)
	(segment
		(start 37.892228 -302.683164)
		(end 38.055042 -302.52035)
		(width 0.14478)
		(layer "In4.Cu")
		(net "M_D_CPU1_SB_DQ<17>")
	)
	(segment
		(start 53.24475 -301.082456)
		(end 54.472586 -302.310292)
		(width 0.14478)
		(layer "In4.Cu")
		(net "M_D_CPU1_SB_DQ<17>")
	)
	(segment
		(start 90.639646 -284.943804)
		(end 90.648028 -284.938978)
		(width 0.0889)
		(layer "In4.Cu")
		(net "M_D_CPU1_SB_DQ<17>")
	)
	(segment
		(start 85.93963 -284.943804)
		(end 85.948012 -284.938978)
		(width 0.0889)
		(layer "In4.Cu")
		(net "M_D_CPU1_SB_DQ<17>")
	)
	(segment
		(start 92.153994 -284.938978)
		(end 92.162376 -284.943804)
		(width 0.0889)
		(layer "In4.Cu")
		(net "M_D_CPU1_SB_DQ<17>")
	)
	(segment
		(start 60.318396 -301.563786)
		(end 60.318396 -300.736254)
		(width 0.14478)
		(layer "In4.Cu")
		(net "M_D_CPU1_SB_DQ<17>")
	)
	(segment
		(start 53.014118 -301.082456)
		(end 53.24475 -301.082456)
		(width 0.14478)
		(layer "In4.Cu")
		(net "M_D_CPU1_SB_DQ<17>")
	)
	(segment
		(start 78.993492 -284.938724)
		(end 79.007208 -284.946598)
		(width 0.0889)
		(layer "In4.Cu")
		(net "M_D_CPU1_SB_DQ<17>")
	)
	(segment
		(start 58.39333 -301.305722)
		(end 58.39333 -301.55134)
		(width 0.14478)
		(layer "In4.Cu")
		(net "M_D_CPU1_SB_DQ<17>")
	)
	(segment
		(start 39.004748 -302.683164)
		(end 39.167562 -302.52035)
		(width 0.14478)
		(layer "In4.Cu")
		(net "M_D_CPU1_SB_DQ<17>")
	)
	(segment
		(start 37.593778 -302.683164)
		(end 37.892228 -302.683164)
		(width 0.14478)
		(layer "In4.Cu")
		(net "M_D_CPU1_SB_DQ<17>")
	)
	(segment
		(start 42.487342 -301.460408)
		(end 45.22851 -301.460408)
		(width 0.14478)
		(layer "In4.Cu")
		(net "M_D_CPU1_SB_DQ<17>")
	)
	(arc
		(start 76.594716 -285.0896)
		(mid 76.631527 -285.06494)
		(end 76.67498 -285.056326)
		(width 0.0889)
		(layer "In4.Cu")
		(net "M_D_CPU1_SB_DQ<17>")
	)
	(arc
		(start 81.247996 -284.938978)
		(mid 81.530952 -284.862801)
		(end 81.813908 -284.938978)
		(width 0.0889)
		(layer "In4.Cu")
		(net "M_D_CPU1_SB_DQ<17>")
	)
	(arc
		(start 85.007958 -284.938978)
		(mid 85.290914 -284.862801)
		(end 85.57387 -284.938978)
		(width 0.0889)
		(layer "In4.Cu")
		(net "M_D_CPU1_SB_DQ<17>")
	)
	(arc
		(start 79.381858 -284.930342)
		(mid 79.658841 -284.862538)
		(end 79.933546 -284.938978)
		(width 0.0889)
		(layer "In4.Cu")
		(net "M_D_CPU1_SB_DQ<17>")
	)
	(arc
		(start 79.007208 -284.946598)
		(mid 79.188138 -284.989076)
		(end 79.367126 -284.938978)
		(width 0.0889)
		(layer "In4.Cu")
		(net "M_D_CPU1_SB_DQ<17>")
	)
	(arc
		(start 91.21394 -284.938978)
		(mid 91.396191 -284.989328)
		(end 91.5797 -284.943804)
		(width 0.0889)
		(layer "In4.Cu")
		(net "M_D_CPU1_SB_DQ<17>")
	)
	(arc
		(start 80.308196 -284.938978)
		(mid 80.591152 -284.862801)
		(end 80.874108 -284.938978)
		(width 0.0889)
		(layer "In4.Cu")
		(net "M_D_CPU1_SB_DQ<17>")
	)
	(arc
		(start 88.402414 -284.943804)
		(mid 88.585922 -284.989298)
		(end 88.768174 -284.938978)
		(width 0.0889)
		(layer "In4.Cu")
		(net "M_D_CPU1_SB_DQ<17>")
	)
	(arc
		(start 78.42758 -284.938978)
		(mid 78.701435 -284.862628)
		(end 78.977744 -284.92958)
		(width 0.0889)
		(layer "In4.Cu")
		(net "M_D_CPU1_SB_DQ<17>")
	)
	(arc
		(start 84.068158 -284.938978)
		(mid 84.351114 -284.862801)
		(end 84.63407 -284.938978)
		(width 0.0889)
		(layer "In4.Cu")
		(net "M_D_CPU1_SB_DQ<17>")
	)
	(arc
		(start 85.57387 -284.938978)
		(mid 85.756121 -284.989328)
		(end 85.93963 -284.943804)
		(width 0.0889)
		(layer "In4.Cu")
		(net "M_D_CPU1_SB_DQ<17>")
	)
	(arc
		(start 83.702398 -284.943804)
		(mid 83.885906 -284.989298)
		(end 84.068158 -284.938978)
		(width 0.0889)
		(layer "In4.Cu")
		(net "M_D_CPU1_SB_DQ<17>")
	)
	(arc
		(start 81.813908 -284.938978)
		(mid 81.996159 -284.989328)
		(end 82.179668 -284.943804)
		(width 0.0889)
		(layer "In4.Cu")
		(net "M_D_CPU1_SB_DQ<17>")
	)
	(arc
		(start 82.18805 -284.938978)
		(mid 82.471006 -284.862801)
		(end 82.753962 -284.938978)
		(width 0.0889)
		(layer "In4.Cu")
		(net "M_D_CPU1_SB_DQ<17>")
	)
	(arc
		(start 89.707974 -284.938978)
		(mid 89.99093 -284.862801)
		(end 90.273886 -284.938978)
		(width 0.0889)
		(layer "In4.Cu")
		(net "M_D_CPU1_SB_DQ<17>")
	)
	(arc
		(start 86.513924 -284.938978)
		(mid 86.696175 -284.989328)
		(end 86.879684 -284.943804)
		(width 0.0889)
		(layer "In4.Cu")
		(net "M_D_CPU1_SB_DQ<17>")
	)
	(arc
		(start 87.46236 -284.943804)
		(mid 87.645868 -284.989298)
		(end 87.82812 -284.938978)
		(width 0.0889)
		(layer "In4.Cu")
		(net "M_D_CPU1_SB_DQ<17>")
	)
	(arc
		(start 85.948012 -284.938978)
		(mid 86.230968 -284.862801)
		(end 86.513924 -284.938978)
		(width 0.0889)
		(layer "In4.Cu")
		(net "M_D_CPU1_SB_DQ<17>")
	)
	(arc
		(start 86.888066 -284.938978)
		(mid 87.171022 -284.862801)
		(end 87.453978 -284.938978)
		(width 0.0889)
		(layer "In4.Cu")
		(net "M_D_CPU1_SB_DQ<17>")
	)
	(arc
		(start 84.63407 -284.938978)
		(mid 84.821014 -284.989233)
		(end 85.007958 -284.938978)
		(width 0.0889)
		(layer "In4.Cu")
		(net "M_D_CPU1_SB_DQ<17>")
	)
	(arc
		(start 88.768174 -284.938978)
		(mid 89.05113 -284.862801)
		(end 89.334086 -284.938978)
		(width 0.0889)
		(layer "In4.Cu")
		(net "M_D_CPU1_SB_DQ<17>")
	)
	(arc
		(start 89.334086 -284.938978)
		(mid 89.52103 -284.989233)
		(end 89.707974 -284.938978)
		(width 0.0889)
		(layer "In4.Cu")
		(net "M_D_CPU1_SB_DQ<17>")
	)
	(arc
		(start 79.933546 -284.938978)
		(mid 80.116051 -284.989455)
		(end 80.299814 -284.943804)
		(width 0.0889)
		(layer "In4.Cu")
		(net "M_D_CPU1_SB_DQ<17>")
	)
	(arc
		(start 83.128104 -284.938978)
		(mid 83.41106 -284.862801)
		(end 83.694016 -284.938978)
		(width 0.0889)
		(layer "In4.Cu")
		(net "M_D_CPU1_SB_DQ<17>")
	)
	(arc
		(start 90.648028 -284.938978)
		(mid 90.930984 -284.862801)
		(end 91.21394 -284.938978)
		(width 0.0889)
		(layer "In4.Cu")
		(net "M_D_CPU1_SB_DQ<17>")
	)
	(arc
		(start 77.992224 -285.056326)
		(mid 78.217789 -285.026466)
		(end 78.427834 -284.938978)
		(width 0.0889)
		(layer "In4.Cu")
		(net "M_D_CPU1_SB_DQ<17>")
	)
	(arc
		(start 90.273886 -284.938978)
		(mid 90.456137 -284.989328)
		(end 90.639646 -284.943804)
		(width 0.0889)
		(layer "In4.Cu")
		(net "M_D_CPU1_SB_DQ<17>")
	)
	(arc
		(start 91.588082 -284.938978)
		(mid 91.871038 -284.862801)
		(end 92.153994 -284.938978)
		(width 0.0889)
		(layer "In4.Cu")
		(net "M_D_CPU1_SB_DQ<17>")
	)
	(arc
		(start 80.874108 -284.938978)
		(mid 81.061052 -284.989233)
		(end 81.247996 -284.938978)
		(width 0.0889)
		(layer "In4.Cu")
		(net "M_D_CPU1_SB_DQ<17>")
	)
	(arc
		(start 82.762344 -284.943804)
		(mid 82.945852 -284.989298)
		(end 83.128104 -284.938978)
		(width 0.0889)
		(layer "In4.Cu")
		(net "M_D_CPU1_SB_DQ<17>")
	)
	(arc
		(start 87.82812 -284.938978)
		(mid 88.111076 -284.862801)
		(end 88.394032 -284.938978)
		(width 0.0889)
		(layer "In4.Cu")
		(net "M_D_CPU1_SB_DQ<17>")
	)
	(arc
		(start 92.162376 -284.943804)
		(mid 92.315246 -284.988445)
		(end 92.472764 -284.96514)
		(width 0.0889)
		(layer "In4.Cu")
		(net "M_D_CPU1_SB_DQ<17>")
	)
	(segment
		(start 91.397836 -283.540454)
		(end 90.930984 -283.806392)
		(width 0.10668)
		(layer "F.Cu")
		(net "M_D_CPU1_SB_DQ<16>")
	)
	(segment
		(start 56.430926 -300.09973)
		(end 56.430926 -300.82236)
		(width 0.14478)
		(layer "In4.Cu")
		(net "M_D_CPU1_SB_DQ<16>")
	)
	(segment
		(start 76.78547 -283.946346)
		(end 77.967078 -283.946346)
		(width 0.0889)
		(layer "In4.Cu")
		(net "M_D_CPU1_SB_DQ<16>")
	)
	(segment
		(start 39.04996 -300.501304)
		(end 39.20998 -300.341284)
		(width 0.14478)
		(layer "In4.Cu")
		(net "M_D_CPU1_SB_DQ<16>")
	)
	(segment
		(start 52.233576 -299.760386)
		(end 52.39512 -299.92193)
		(width 0.14478)
		(layer "In4.Cu")
		(net "M_D_CPU1_SB_DQ<16>")
	)
	(segment
		(start 37.93744 -300.501304)
		(end 38.09746 -300.341284)
		(width 0.14478)
		(layer "In4.Cu")
		(net "M_D_CPU1_SB_DQ<16>")
	)
	(segment
		(start 49.07661 -300.8884)
		(end 49.36363 -300.8884)
		(width 0.14478)
		(layer "In4.Cu")
		(net "M_D_CPU1_SB_DQ<16>")
	)
	(segment
		(start 90.74404 -284.128972)
		(end 90.752422 -284.133798)
		(width 0.0889)
		(layer "In4.Cu")
		(net "M_D_CPU1_SB_DQ<16>")
	)
	(segment
		(start 53.351684 -299.760386)
		(end 53.732684 -300.141386)
		(width 0.14478)
		(layer "In4.Cu")
		(net "M_D_CPU1_SB_DQ<16>")
	)
	(segment
		(start 41.282366 -300.879764)
		(end 41.569386 -300.879764)
		(width 0.14478)
		(layer "In4.Cu")
		(net "M_D_CPU1_SB_DQ<16>")
	)
	(segment
		(start 54.82209 -300.134782)
		(end 54.82209 -300.705266)
		(width 0.14478)
		(layer "In4.Cu")
		(net "M_D_CPU1_SB_DQ<16>")
	)
	(segment
		(start 56.59247 -300.983904)
		(end 56.786526 -300.983904)
		(width 0.14478)
		(layer "In4.Cu")
		(net "M_D_CPU1_SB_DQ<16>")
	)
	(segment
		(start 56.786526 -300.983904)
		(end 58.010044 -299.760386)
		(width 0.14478)
		(layer "In4.Cu")
		(net "M_D_CPU1_SB_DQ<16>")
	)
	(segment
		(start 48.94199 -300.48454)
		(end 48.94199 -300.75378)
		(width 0.14478)
		(layer "In4.Cu")
		(net "M_D_CPU1_SB_DQ<16>")
	)
	(segment
		(start 56.430926 -300.82236)
		(end 56.59247 -300.983904)
		(width 0.14478)
		(layer "In4.Cu")
		(net "M_D_CPU1_SB_DQ<16>")
	)
	(segment
		(start 81.344008 -284.128972)
		(end 81.35239 -284.133798)
		(width 0.0889)
		(layer "In4.Cu")
		(net "M_D_CPU1_SB_DQ<16>")
	)
	(segment
		(start 41.569386 -300.879764)
		(end 42.689018 -299.760132)
		(width 0.14478)
		(layer "In4.Cu")
		(net "M_D_CPU1_SB_DQ<16>")
	)
	(segment
		(start 84.529676 -284.133798)
		(end 84.538058 -284.128972)
		(width 0.0889)
		(layer "In4.Cu")
		(net "M_D_CPU1_SB_DQ<16>")
	)
	(segment
		(start 38.88994 -300.930564)
		(end 39.04996 -300.770544)
		(width 0.14478)
		(layer "In4.Cu")
		(net "M_D_CPU1_SB_DQ<16>")
	)
	(segment
		(start 43.149774 -299.92193)
		(end 43.149774 -299.992542)
		(width 0.14478)
		(layer "In4.Cu")
		(net "M_D_CPU1_SB_DQ<16>")
	)
	(segment
		(start 43.701208 -299.992542)
		(end 43.701208 -299.92193)
		(width 0.14478)
		(layer "In4.Cu")
		(net "M_D_CPU1_SB_DQ<16>")
	)
	(segment
		(start 38.4937 -300.501304)
		(end 38.4937 -300.770544)
		(width 0.14478)
		(layer "In4.Cu")
		(net "M_D_CPU1_SB_DQ<16>")
	)
	(segment
		(start 48.259746 -300.610524)
		(end 48.52035 -300.34992)
		(width 0.14478)
		(layer "In4.Cu")
		(net "M_D_CPU1_SB_DQ<16>")
	)
	(segment
		(start 52.946554 -299.992542)
		(end 52.946554 -299.92193)
		(width 0.14478)
		(layer "In4.Cu")
		(net "M_D_CPU1_SB_DQ<16>")
	)
	(segment
		(start 52.78501 -300.154086)
		(end 52.946554 -299.992542)
		(width 0.14478)
		(layer "In4.Cu")
		(net "M_D_CPU1_SB_DQ<16>")
	)
	(segment
		(start 78.897734 -284.128718)
		(end 78.903322 -284.125416)
		(width 0.0889)
		(layer "In4.Cu")
		(net "M_D_CPU1_SB_DQ<16>")
	)
	(segment
		(start 76.264262 -284.467554)
		(end 76.78547 -283.946346)
		(width 0.0889)
		(layer "In4.Cu")
		(net "M_D_CPU1_SB_DQ<16>")
	)
	(segment
		(start 51.457606 -299.760386)
		(end 52.233576 -299.760386)
		(width 0.14478)
		(layer "In4.Cu")
		(net "M_D_CPU1_SB_DQ<16>")
	)
	(segment
		(start 40.726106 -300.341284)
		(end 41.013126 -300.341284)
		(width 0.14478)
		(layer "In4.Cu")
		(net "M_D_CPU1_SB_DQ<16>")
	)
	(segment
		(start 43.311318 -300.154086)
		(end 43.539664 -300.154086)
		(width 0.14478)
		(layer "In4.Cu")
		(net "M_D_CPU1_SB_DQ<16>")
	)
	(segment
		(start 43.862752 -299.760386)
		(end 44.777914 -299.760386)
		(width 0.14478)
		(layer "In4.Cu")
		(net "M_D_CPU1_SB_DQ<16>")
	)
	(segment
		(start 89.803986 -284.128972)
		(end 89.812368 -284.133798)
		(width 0.0889)
		(layer "In4.Cu")
		(net "M_D_CPU1_SB_DQ<16>")
	)
	(segment
		(start 54.106826 -300.141386)
		(end 54.33187 -299.916342)
		(width 0.14478)
		(layer "In4.Cu")
		(net "M_D_CPU1_SB_DQ<16>")
	)
	(segment
		(start 41.147746 -300.745144)
		(end 41.282366 -300.879764)
		(width 0.14478)
		(layer "In4.Cu")
		(net "M_D_CPU1_SB_DQ<16>")
	)
	(segment
		(start 51.134518 -300.149006)
		(end 51.296062 -299.987462)
		(width 0.14478)
		(layer "In4.Cu")
		(net "M_D_CPU1_SB_DQ<16>")
	)
	(segment
		(start 51.296062 -299.92193)
		(end 51.457606 -299.760386)
		(width 0.14478)
		(layer "In4.Cu")
		(net "M_D_CPU1_SB_DQ<16>")
	)
	(segment
		(start 41.013126 -300.341284)
		(end 41.147746 -300.475904)
		(width 0.14478)
		(layer "In4.Cu")
		(net "M_D_CPU1_SB_DQ<16>")
	)
	(segment
		(start 39.04996 -300.770544)
		(end 39.04996 -300.501304)
		(width 0.14478)
		(layer "In4.Cu")
		(net "M_D_CPU1_SB_DQ<16>")
	)
	(segment
		(start 40.456866 -300.610524)
		(end 40.726106 -300.341284)
		(width 0.14478)
		(layer "In4.Cu")
		(net "M_D_CPU1_SB_DQ<16>")
	)
	(segment
		(start 50.491644 -299.760386)
		(end 50.583084 -299.760386)
		(width 0.14478)
		(layer "In4.Cu")
		(net "M_D_CPU1_SB_DQ<16>")
	)
	(segment
		(start 38.65372 -300.930564)
		(end 38.88994 -300.930564)
		(width 0.14478)
		(layer "In4.Cu")
		(net "M_D_CPU1_SB_DQ<16>")
	)
	(segment
		(start 50.744628 -299.987462)
		(end 50.906172 -300.149006)
		(width 0.14478)
		(layer "In4.Cu")
		(net "M_D_CPU1_SB_DQ<16>")
	)
	(segment
		(start 50.744628 -299.92193)
		(end 50.744628 -299.987462)
		(width 0.14478)
		(layer "In4.Cu")
		(net "M_D_CPU1_SB_DQ<16>")
	)
	(segment
		(start 44.939458 -299.995082)
		(end 45.101002 -300.156626)
		(width 0.14478)
		(layer "In4.Cu")
		(net "M_D_CPU1_SB_DQ<16>")
	)
	(segment
		(start 88.289638 -284.133798)
		(end 88.29802 -284.128972)
		(width 0.0889)
		(layer "In4.Cu")
		(net "M_D_CPU1_SB_DQ<16>")
	)
	(segment
		(start 85.10397 -284.128972)
		(end 85.112352 -284.133798)
		(width 0.0889)
		(layer "In4.Cu")
		(net "M_D_CPU1_SB_DQ<16>")
	)
	(segment
		(start 46.811946 -300.610524)
		(end 48.259746 -300.610524)
		(width 0.14478)
		(layer "In4.Cu")
		(net "M_D_CPU1_SB_DQ<16>")
	)
	(segment
		(start 55.717948 -300.983904)
		(end 55.879492 -300.82236)
		(width 0.14478)
		(layer "In4.Cu")
		(net "M_D_CPU1_SB_DQ<16>")
	)
	(segment
		(start 77.967078 -283.946346)
		(end 78.20025 -284.179518)
		(width 0.0889)
		(layer "In4.Cu")
		(net "M_D_CPU1_SB_DQ<16>")
	)
	(segment
		(start 43.149774 -299.992542)
		(end 43.311318 -300.154086)
		(width 0.14478)
		(layer "In4.Cu")
		(net "M_D_CPU1_SB_DQ<16>")
	)
	(segment
		(start 43.701208 -299.92193)
		(end 43.862752 -299.760386)
		(width 0.14478)
		(layer "In4.Cu")
		(net "M_D_CPU1_SB_DQ<16>")
	)
	(segment
		(start 55.879492 -300.09973)
		(end 56.041036 -299.938186)
		(width 0.14478)
		(layer "In4.Cu")
		(net "M_D_CPU1_SB_DQ<16>")
	)
	(segment
		(start 58.010044 -299.760386)
		(end 58.387234 -299.760386)
		(width 0.14478)
		(layer "In4.Cu")
		(net "M_D_CPU1_SB_DQ<16>")
	)
	(segment
		(start 50.583084 -299.760386)
		(end 50.744628 -299.92193)
		(width 0.14478)
		(layer "In4.Cu")
		(net "M_D_CPU1_SB_DQ<16>")
	)
	(segment
		(start 41.147746 -300.475904)
		(end 41.147746 -300.745144)
		(width 0.14478)
		(layer "In4.Cu")
		(net "M_D_CPU1_SB_DQ<16>")
	)
	(segment
		(start 54.82209 -300.705266)
		(end 55.100728 -300.983904)
		(width 0.14478)
		(layer "In4.Cu")
		(net "M_D_CPU1_SB_DQ<16>")
	)
	(segment
		(start 42.689272 -299.760386)
		(end 42.98823 -299.760386)
		(width 0.14478)
		(layer "In4.Cu")
		(net "M_D_CPU1_SB_DQ<16>")
	)
	(segment
		(start 53.732684 -300.141386)
		(end 54.106826 -300.141386)
		(width 0.14478)
		(layer "In4.Cu")
		(net "M_D_CPU1_SB_DQ<16>")
	)
	(segment
		(start 36.795964 -300.185328)
		(end 37.5412 -300.930564)
		(width 0.14478)
		(layer "In4.Cu")
		(net "M_D_CPU1_SB_DQ<16>")
	)
	(segment
		(start 91.085162 -284.071822)
		(end 90.930984 -283.806392)
		(width 0.0889)
		(layer "In4.Cu")
		(net "M_D_CPU1_SB_DQ<16>")
	)
	(segment
		(start 43.539664 -300.154086)
		(end 43.701208 -299.992542)
		(width 0.14478)
		(layer "In4.Cu")
		(net "M_D_CPU1_SB_DQ<16>")
	)
	(segment
		(start 38.33368 -300.341284)
		(end 38.4937 -300.501304)
		(width 0.14478)
		(layer "In4.Cu")
		(net "M_D_CPU1_SB_DQ<16>")
	)
	(segment
		(start 37.93744 -300.770544)
		(end 37.93744 -300.501304)
		(width 0.14478)
		(layer "In4.Cu")
		(net "M_D_CPU1_SB_DQ<16>")
	)
	(segment
		(start 59.383422 -299.760386)
		(end 59.836812 -299.760386)
		(width 0.14478)
		(layer "In4.Cu")
		(net "M_D_CPU1_SB_DQ<16>")
	)
	(segment
		(start 54.60365 -299.916342)
		(end 54.82209 -300.134782)
		(width 0.14478)
		(layer "In4.Cu")
		(net "M_D_CPU1_SB_DQ<16>")
	)
	(segment
		(start 58.770012 -300.143164)
		(end 59.000644 -300.143164)
		(width 0.14478)
		(layer "In4.Cu")
		(net "M_D_CPU1_SB_DQ<16>")
	)
	(segment
		(start 44.777914 -299.760386)
		(end 44.939458 -299.92193)
		(width 0.14478)
		(layer "In4.Cu")
		(net "M_D_CPU1_SB_DQ<16>")
	)
	(segment
		(start 52.556664 -300.154086)
		(end 52.78501 -300.154086)
		(width 0.14478)
		(layer "In4.Cu")
		(net "M_D_CPU1_SB_DQ<16>")
	)
	(segment
		(start 91.06281 -284.155134)
		(end 91.085162 -284.071822)
		(width 0.0889)
		(layer "In4.Cu")
		(net "M_D_CPU1_SB_DQ<16>")
	)
	(segment
		(start 45.329348 -300.156626)
		(end 45.490892 -299.995082)
		(width 0.14478)
		(layer "In4.Cu")
		(net "M_D_CPU1_SB_DQ<16>")
	)
	(segment
		(start 42.689018 -299.760132)
		(end 42.689272 -299.760386)
		(width 0.14478)
		(layer "In4.Cu")
		(net "M_D_CPU1_SB_DQ<16>")
	)
	(segment
		(start 53.108098 -299.760386)
		(end 53.351684 -299.760386)
		(width 0.14478)
		(layer "In4.Cu")
		(net "M_D_CPU1_SB_DQ<16>")
	)
	(segment
		(start 45.961808 -299.760386)
		(end 46.811946 -300.610524)
		(width 0.14478)
		(layer "In4.Cu")
		(net "M_D_CPU1_SB_DQ<16>")
	)
	(segment
		(start 75.129644 -284.467554)
		(end 75.963526 -284.467554)
		(width 0.14478)
		(layer "In4.Cu")
		(net "M_D_CPU1_SB_DQ<16>")
	)
	(segment
		(start 50.906172 -300.149006)
		(end 51.134518 -300.149006)
		(width 0.14478)
		(layer "In4.Cu")
		(net "M_D_CPU1_SB_DQ<16>")
	)
	(segment
		(start 86.044024 -284.128972)
		(end 86.052406 -284.133798)
		(width 0.0889)
		(layer "In4.Cu")
		(net "M_D_CPU1_SB_DQ<16>")
	)
	(segment
		(start 52.39512 -299.92193)
		(end 52.39512 -299.992542)
		(width 0.14478)
		(layer "In4.Cu")
		(net "M_D_CPU1_SB_DQ<16>")
	)
	(segment
		(start 39.71544 -300.610524)
		(end 40.456866 -300.610524)
		(width 0.14478)
		(layer "In4.Cu")
		(net "M_D_CPU1_SB_DQ<16>")
	)
	(segment
		(start 39.20998 -300.341284)
		(end 39.4462 -300.341284)
		(width 0.14478)
		(layer "In4.Cu")
		(net "M_D_CPU1_SB_DQ<16>")
	)
	(segment
		(start 52.39512 -299.992542)
		(end 52.556664 -300.154086)
		(width 0.14478)
		(layer "In4.Cu")
		(net "M_D_CPU1_SB_DQ<16>")
	)
	(segment
		(start 80.39354 -284.122876)
		(end 80.403954 -284.128972)
		(width 0.0889)
		(layer "In4.Cu")
		(net "M_D_CPU1_SB_DQ<16>")
	)
	(segment
		(start 44.939458 -299.92193)
		(end 44.939458 -299.995082)
		(width 0.14478)
		(layer "In4.Cu")
		(net "M_D_CPU1_SB_DQ<16>")
	)
	(segment
		(start 78.20025 -284.179518)
		(end 78.71079 -284.179518)
		(width 0.0889)
		(layer "In4.Cu")
		(net "M_D_CPU1_SB_DQ<16>")
	)
	(segment
		(start 54.33187 -299.916342)
		(end 54.60365 -299.916342)
		(width 0.14478)
		(layer "In4.Cu")
		(net "M_D_CPU1_SB_DQ<16>")
	)
	(segment
		(start 45.101002 -300.156626)
		(end 45.329348 -300.156626)
		(width 0.14478)
		(layer "In4.Cu")
		(net "M_D_CPU1_SB_DQ<16>")
	)
	(segment
		(start 39.4462 -300.341284)
		(end 39.71544 -300.610524)
		(width 0.14478)
		(layer "In4.Cu")
		(net "M_D_CPU1_SB_DQ<16>")
	)
	(segment
		(start 79.463138 -284.128972)
		(end 79.47152 -284.133798)
		(width 0.0889)
		(layer "In4.Cu")
		(net "M_D_CPU1_SB_DQ<16>")
	)
	(segment
		(start 59.000644 -300.143164)
		(end 59.383422 -299.760386)
		(width 0.14478)
		(layer "In4.Cu")
		(net "M_D_CPU1_SB_DQ<16>")
	)
	(segment
		(start 55.879492 -300.82236)
		(end 55.879492 -300.09973)
		(width 0.14478)
		(layer "In4.Cu")
		(net "M_D_CPU1_SB_DQ<16>")
	)
	(segment
		(start 45.490892 -299.995082)
		(end 45.490892 -299.92193)
		(width 0.14478)
		(layer "In4.Cu")
		(net "M_D_CPU1_SB_DQ<16>")
	)
	(segment
		(start 75.963526 -284.467554)
		(end 76.264262 -284.467554)
		(width 0.0889)
		(layer "In4.Cu")
		(net "M_D_CPU1_SB_DQ<16>")
	)
	(segment
		(start 38.4937 -300.770544)
		(end 38.65372 -300.930564)
		(width 0.14478)
		(layer "In4.Cu")
		(net "M_D_CPU1_SB_DQ<16>")
	)
	(segment
		(start 45.652436 -299.760386)
		(end 45.961808 -299.760386)
		(width 0.14478)
		(layer "In4.Cu")
		(net "M_D_CPU1_SB_DQ<16>")
	)
	(segment
		(start 56.041036 -299.938186)
		(end 56.269382 -299.938186)
		(width 0.14478)
		(layer "In4.Cu")
		(net "M_D_CPU1_SB_DQ<16>")
	)
	(segment
		(start 83.589622 -284.133798)
		(end 83.598004 -284.128972)
		(width 0.0889)
		(layer "In4.Cu")
		(net "M_D_CPU1_SB_DQ<16>")
	)
	(segment
		(start 89.229692 -284.133798)
		(end 89.238074 -284.128972)
		(width 0.0889)
		(layer "In4.Cu")
		(net "M_D_CPU1_SB_DQ<16>")
	)
	(segment
		(start 48.94199 -300.75378)
		(end 49.07661 -300.8884)
		(width 0.14478)
		(layer "In4.Cu")
		(net "M_D_CPU1_SB_DQ<16>")
	)
	(segment
		(start 58.387234 -299.760386)
		(end 58.770012 -300.143164)
		(width 0.14478)
		(layer "In4.Cu")
		(net "M_D_CPU1_SB_DQ<16>")
	)
	(segment
		(start 55.100728 -300.983904)
		(end 55.717948 -300.983904)
		(width 0.14478)
		(layer "In4.Cu")
		(net "M_D_CPU1_SB_DQ<16>")
	)
	(segment
		(start 37.77742 -300.930564)
		(end 37.93744 -300.770544)
		(width 0.14478)
		(layer "In4.Cu")
		(net "M_D_CPU1_SB_DQ<16>")
	)
	(segment
		(start 37.5412 -300.930564)
		(end 37.77742 -300.930564)
		(width 0.14478)
		(layer "In4.Cu")
		(net "M_D_CPU1_SB_DQ<16>")
	)
	(segment
		(start 42.98823 -299.760386)
		(end 43.149774 -299.92193)
		(width 0.14478)
		(layer "In4.Cu")
		(net "M_D_CPU1_SB_DQ<16>")
	)
	(segment
		(start 56.269382 -299.938186)
		(end 56.430926 -300.09973)
		(width 0.14478)
		(layer "In4.Cu")
		(net "M_D_CPU1_SB_DQ<16>")
	)
	(segment
		(start 51.296062 -299.987462)
		(end 51.296062 -299.92193)
		(width 0.14478)
		(layer "In4.Cu")
		(net "M_D_CPU1_SB_DQ<16>")
	)
	(segment
		(start 48.52035 -300.34992)
		(end 48.80737 -300.34992)
		(width 0.14478)
		(layer "In4.Cu")
		(net "M_D_CPU1_SB_DQ<16>")
	)
	(segment
		(start 48.80737 -300.34992)
		(end 48.94199 -300.48454)
		(width 0.14478)
		(layer "In4.Cu")
		(net "M_D_CPU1_SB_DQ<16>")
	)
	(segment
		(start 52.946554 -299.92193)
		(end 53.108098 -299.760386)
		(width 0.14478)
		(layer "In4.Cu")
		(net "M_D_CPU1_SB_DQ<16>")
	)
	(segment
		(start 38.09746 -300.341284)
		(end 38.33368 -300.341284)
		(width 0.14478)
		(layer "In4.Cu")
		(net "M_D_CPU1_SB_DQ<16>")
	)
	(segment
		(start 49.36363 -300.8884)
		(end 50.491644 -299.760386)
		(width 0.14478)
		(layer "In4.Cu")
		(net "M_D_CPU1_SB_DQ<16>")
	)
	(segment
		(start 80.769714 -284.133798)
		(end 80.778096 -284.128972)
		(width 0.0889)
		(layer "In4.Cu")
		(net "M_D_CPU1_SB_DQ<16>")
	)
	(segment
		(start 45.490892 -299.92193)
		(end 45.652436 -299.760386)
		(width 0.14478)
		(layer "In4.Cu")
		(net "M_D_CPU1_SB_DQ<16>")
	)
	(segment
		(start 59.836812 -299.760386)
		(end 75.129644 -284.467554)
		(width 0.14478)
		(layer "In4.Cu")
		(net "M_D_CPU1_SB_DQ<16>")
	)
	(arc
		(start 84.538058 -284.128972)
		(mid 84.821014 -284.052795)
		(end 85.10397 -284.128972)
		(width 0.0889)
		(layer "In4.Cu")
		(net "M_D_CPU1_SB_DQ<16>")
	)
	(arc
		(start 87.357966 -284.128972)
		(mid 87.640922 -284.052795)
		(end 87.923878 -284.128972)
		(width 0.0889)
		(layer "In4.Cu")
		(net "M_D_CPU1_SB_DQ<16>")
	)
	(arc
		(start 89.812368 -284.133798)
		(mid 89.995876 -284.179292)
		(end 90.178128 -284.128972)
		(width 0.0889)
		(layer "In4.Cu")
		(net "M_D_CPU1_SB_DQ<16>")
	)
	(arc
		(start 82.284062 -284.128972)
		(mid 82.471006 -284.179227)
		(end 82.65795 -284.128972)
		(width 0.0889)
		(layer "In4.Cu")
		(net "M_D_CPU1_SB_DQ<16>")
	)
	(arc
		(start 86.052406 -284.133798)
		(mid 86.235914 -284.179292)
		(end 86.418166 -284.128972)
		(width 0.0889)
		(layer "In4.Cu")
		(net "M_D_CPU1_SB_DQ<16>")
	)
	(arc
		(start 85.478112 -284.128972)
		(mid 85.761068 -284.052795)
		(end 86.044024 -284.128972)
		(width 0.0889)
		(layer "In4.Cu")
		(net "M_D_CPU1_SB_DQ<16>")
	)
	(arc
		(start 86.418166 -284.128972)
		(mid 86.701122 -284.052795)
		(end 86.984078 -284.128972)
		(width 0.0889)
		(layer "In4.Cu")
		(net "M_D_CPU1_SB_DQ<16>")
	)
	(arc
		(start 78.71079 -284.179518)
		(mid 78.807608 -284.166447)
		(end 78.897734 -284.128718)
		(width 0.0889)
		(layer "In4.Cu")
		(net "M_D_CPU1_SB_DQ<16>")
	)
	(arc
		(start 80.403954 -284.128972)
		(mid 80.586205 -284.179322)
		(end 80.769714 -284.133798)
		(width 0.0889)
		(layer "In4.Cu")
		(net "M_D_CPU1_SB_DQ<16>")
	)
	(arc
		(start 88.29802 -284.128972)
		(mid 88.580976 -284.052795)
		(end 88.863932 -284.128972)
		(width 0.0889)
		(layer "In4.Cu")
		(net "M_D_CPU1_SB_DQ<16>")
	)
	(arc
		(start 88.863932 -284.128972)
		(mid 89.046183 -284.179322)
		(end 89.229692 -284.133798)
		(width 0.0889)
		(layer "In4.Cu")
		(net "M_D_CPU1_SB_DQ<16>")
	)
	(arc
		(start 85.112352 -284.133798)
		(mid 85.29586 -284.179292)
		(end 85.478112 -284.128972)
		(width 0.0889)
		(layer "In4.Cu")
		(net "M_D_CPU1_SB_DQ<16>")
	)
	(arc
		(start 84.163916 -284.128972)
		(mid 84.346167 -284.179322)
		(end 84.529676 -284.133798)
		(width 0.0889)
		(layer "In4.Cu")
		(net "M_D_CPU1_SB_DQ<16>")
	)
	(arc
		(start 90.178128 -284.128972)
		(mid 90.461084 -284.052795)
		(end 90.74404 -284.128972)
		(width 0.0889)
		(layer "In4.Cu")
		(net "M_D_CPU1_SB_DQ<16>")
	)
	(arc
		(start 87.923878 -284.128972)
		(mid 88.106129 -284.179322)
		(end 88.289638 -284.133798)
		(width 0.0889)
		(layer "In4.Cu")
		(net "M_D_CPU1_SB_DQ<16>")
	)
	(arc
		(start 79.837788 -284.128972)
		(mid 80.114855 -284.052701)
		(end 80.39354 -284.122876)
		(width 0.0889)
		(layer "In4.Cu")
		(net "M_D_CPU1_SB_DQ<16>")
	)
	(arc
		(start 81.35239 -284.133798)
		(mid 81.535898 -284.179292)
		(end 81.71815 -284.128972)
		(width 0.0889)
		(layer "In4.Cu")
		(net "M_D_CPU1_SB_DQ<16>")
	)
	(arc
		(start 83.223862 -284.128972)
		(mid 83.406113 -284.179322)
		(end 83.589622 -284.133798)
		(width 0.0889)
		(layer "In4.Cu")
		(net "M_D_CPU1_SB_DQ<16>")
	)
	(arc
		(start 79.47152 -284.133798)
		(mid 79.655282 -284.179414)
		(end 79.837788 -284.128972)
		(width 0.0889)
		(layer "In4.Cu")
		(net "M_D_CPU1_SB_DQ<16>")
	)
	(arc
		(start 89.238074 -284.128972)
		(mid 89.52103 -284.052795)
		(end 89.803986 -284.128972)
		(width 0.0889)
		(layer "In4.Cu")
		(net "M_D_CPU1_SB_DQ<16>")
	)
	(arc
		(start 81.71815 -284.128972)
		(mid 82.001106 -284.052795)
		(end 82.284062 -284.128972)
		(width 0.0889)
		(layer "In4.Cu")
		(net "M_D_CPU1_SB_DQ<16>")
	)
	(arc
		(start 90.752422 -284.133798)
		(mid 90.905292 -284.178439)
		(end 91.06281 -284.155134)
		(width 0.0889)
		(layer "In4.Cu")
		(net "M_D_CPU1_SB_DQ<16>")
	)
	(arc
		(start 78.903322 -284.125416)
		(mid 79.183711 -284.052747)
		(end 79.463138 -284.128972)
		(width 0.0889)
		(layer "In4.Cu")
		(net "M_D_CPU1_SB_DQ<16>")
	)
	(arc
		(start 82.65795 -284.128972)
		(mid 82.940906 -284.052795)
		(end 83.223862 -284.128972)
		(width 0.0889)
		(layer "In4.Cu")
		(net "M_D_CPU1_SB_DQ<16>")
	)
	(arc
		(start 80.778096 -284.128972)
		(mid 81.061052 -284.052795)
		(end 81.344008 -284.128972)
		(width 0.0889)
		(layer "In4.Cu")
		(net "M_D_CPU1_SB_DQ<16>")
	)
	(arc
		(start 83.598004 -284.128972)
		(mid 83.88096 -284.052795)
		(end 84.163916 -284.128972)
		(width 0.0889)
		(layer "In4.Cu")
		(net "M_D_CPU1_SB_DQ<16>")
	)
	(arc
		(start 86.984078 -284.128972)
		(mid 87.171022 -284.179227)
		(end 87.357966 -284.128972)
		(width 0.0889)
		(layer "In4.Cu")
		(net "M_D_CPU1_SB_DQ<16>")
	)
	(segment
		(start 93.277944 -283.540454)
		(end 92.811092 -283.806392)
		(width 0.10668)
		(layer "F.Cu")
		(net "M_D_CPU1_SB_DQ<15>")
	)
	(segment
		(start 46.799754 -299.760386)
		(end 49.704498 -299.760386)
		(width 0.14478)
		(layer "In4.Cu")
		(net "M_D_CPU1_SB_DQ<15>")
	)
	(segment
		(start 79.439262 -283.499814)
		(end 79.466948 -283.483812)
		(width 0.0889)
		(layer "In4.Cu")
		(net "M_D_CPU1_SB_DQ<15>")
	)
	(segment
		(start 49.704498 -299.760386)
		(end 50.554636 -298.910248)
		(width 0.14478)
		(layer "In4.Cu")
		(net "M_D_CPU1_SB_DQ<15>")
	)
	(segment
		(start 76.325222 -283.911294)
		(end 76.804012 -283.432504)
		(width 0.0889)
		(layer "In4.Cu")
		(net "M_D_CPU1_SB_DQ<15>")
	)
	(segment
		(start 80.769714 -283.478986)
		(end 80.778096 -283.483812)
		(width 0.0889)
		(layer "In4.Cu")
		(net "M_D_CPU1_SB_DQ<15>")
	)
	(segment
		(start 45.953426 -298.914058)
		(end 46.799754 -299.760386)
		(width 0.14478)
		(layer "In4.Cu")
		(net "M_D_CPU1_SB_DQ<15>")
	)
	(segment
		(start 85.10397 -283.483812)
		(end 85.112352 -283.478986)
		(width 0.0889)
		(layer "In4.Cu")
		(net "M_D_CPU1_SB_DQ<15>")
	)
	(segment
		(start 53.288692 -298.910248)
		(end 53.743606 -299.365162)
		(width 0.14478)
		(layer "In4.Cu")
		(net "M_D_CPU1_SB_DQ<15>")
	)
	(segment
		(start 81.344008 -283.483812)
		(end 81.35239 -283.478986)
		(width 0.0889)
		(layer "In4.Cu")
		(net "M_D_CPU1_SB_DQ<15>")
	)
	(segment
		(start 57.618122 -299.365162)
		(end 58.073036 -298.910248)
		(width 0.14478)
		(layer "In4.Cu")
		(net "M_D_CPU1_SB_DQ<15>")
	)
	(segment
		(start 79.83982 -283.484066)
		(end 79.863696 -283.498036)
		(width 0.0889)
		(layer "In4.Cu")
		(net "M_D_CPU1_SB_DQ<15>")
	)
	(segment
		(start 42.747946 -298.914058)
		(end 45.953426 -298.914058)
		(width 0.14478)
		(layer "In4.Cu")
		(net "M_D_CPU1_SB_DQ<15>")
	)
	(segment
		(start 58.073036 -298.910248)
		(end 59.900058 -298.910248)
		(width 0.14478)
		(layer "In4.Cu")
		(net "M_D_CPU1_SB_DQ<15>")
	)
	(segment
		(start 83.589622 -283.478986)
		(end 83.598004 -283.483812)
		(width 0.0889)
		(layer "In4.Cu")
		(net "M_D_CPU1_SB_DQ<15>")
	)
	(segment
		(start 41.901618 -299.760386)
		(end 42.747946 -298.914058)
		(width 0.14478)
		(layer "In4.Cu")
		(net "M_D_CPU1_SB_DQ<15>")
	)
	(segment
		(start 74.899012 -283.911294)
		(end 75.962256 -283.911294)
		(width 0.14478)
		(layer "In4.Cu")
		(net "M_D_CPU1_SB_DQ<15>")
	)
	(segment
		(start 88.289638 -283.478986)
		(end 88.29802 -283.483812)
		(width 0.0889)
		(layer "In4.Cu")
		(net "M_D_CPU1_SB_DQ<15>")
	)
	(segment
		(start 84.529676 -283.478986)
		(end 84.538058 -283.483812)
		(width 0.0889)
		(layer "In4.Cu")
		(net "M_D_CPU1_SB_DQ<15>")
	)
	(segment
		(start 75.962256 -283.911294)
		(end 76.325222 -283.911294)
		(width 0.0889)
		(layer "In4.Cu")
		(net "M_D_CPU1_SB_DQ<15>")
	)
	(segment
		(start 92.656914 -283.540962)
		(end 92.811092 -283.806392)
		(width 0.0889)
		(layer "In4.Cu")
		(net "M_D_CPU1_SB_DQ<15>")
	)
	(segment
		(start 59.900058 -298.910248)
		(end 74.899012 -283.911294)
		(width 0.14478)
		(layer "In4.Cu")
		(net "M_D_CPU1_SB_DQ<15>")
	)
	(segment
		(start 79.819754 -283.472636)
		(end 79.83982 -283.484066)
		(width 0.0889)
		(layer "In4.Cu")
		(net "M_D_CPU1_SB_DQ<15>")
	)
	(segment
		(start 32.695896 -299.335444)
		(end 33.120838 -299.760386)
		(width 0.14478)
		(layer "In4.Cu")
		(net "M_D_CPU1_SB_DQ<15>")
	)
	(segment
		(start 33.120838 -299.760386)
		(end 41.901618 -299.760386)
		(width 0.14478)
		(layer "In4.Cu")
		(net "M_D_CPU1_SB_DQ<15>")
	)
	(segment
		(start 50.554636 -298.910248)
		(end 53.288692 -298.910248)
		(width 0.14478)
		(layer "In4.Cu")
		(net "M_D_CPU1_SB_DQ<15>")
	)
	(segment
		(start 89.803986 -283.483812)
		(end 89.812368 -283.478986)
		(width 0.0889)
		(layer "In4.Cu")
		(net "M_D_CPU1_SB_DQ<15>")
	)
	(segment
		(start 53.743606 -299.365162)
		(end 57.618122 -299.365162)
		(width 0.14478)
		(layer "In4.Cu")
		(net "M_D_CPU1_SB_DQ<15>")
	)
	(segment
		(start 89.229692 -283.478986)
		(end 89.238074 -283.483812)
		(width 0.0889)
		(layer "In4.Cu")
		(net "M_D_CPU1_SB_DQ<15>")
	)
	(segment
		(start 92.560648 -283.515562)
		(end 92.656914 -283.540962)
		(width 0.0889)
		(layer "In4.Cu")
		(net "M_D_CPU1_SB_DQ<15>")
	)
	(segment
		(start 86.044024 -283.483812)
		(end 86.052406 -283.478986)
		(width 0.0889)
		(layer "In4.Cu")
		(net "M_D_CPU1_SB_DQ<15>")
	)
	(segment
		(start 90.74404 -283.483812)
		(end 90.752422 -283.478986)
		(width 0.0889)
		(layer "In4.Cu")
		(net "M_D_CPU1_SB_DQ<15>")
	)
	(segment
		(start 76.804012 -283.432504)
		(end 78.711044 -283.432504)
		(width 0.0889)
		(layer "In4.Cu")
		(net "M_D_CPU1_SB_DQ<15>")
	)
	(arc
		(start 87.357966 -283.483812)
		(mid 87.640922 -283.559989)
		(end 87.923878 -283.483812)
		(width 0.0889)
		(layer "In4.Cu")
		(net "M_D_CPU1_SB_DQ<15>")
	)
	(arc
		(start 84.163916 -283.483812)
		(mid 84.346167 -283.433462)
		(end 84.529676 -283.478986)
		(width 0.0889)
		(layer "In4.Cu")
		(net "M_D_CPU1_SB_DQ<15>")
	)
	(arc
		(start 86.984078 -283.483812)
		(mid 87.171022 -283.433557)
		(end 87.357966 -283.483812)
		(width 0.0889)
		(layer "In4.Cu")
		(net "M_D_CPU1_SB_DQ<15>")
	)
	(arc
		(start 85.112352 -283.478986)
		(mid 85.29586 -283.433492)
		(end 85.478112 -283.483812)
		(width 0.0889)
		(layer "In4.Cu")
		(net "M_D_CPU1_SB_DQ<15>")
	)
	(arc
		(start 86.052406 -283.478986)
		(mid 86.235914 -283.433492)
		(end 86.418166 -283.483812)
		(width 0.0889)
		(layer "In4.Cu")
		(net "M_D_CPU1_SB_DQ<15>")
	)
	(arc
		(start 88.29802 -283.483812)
		(mid 88.580976 -283.559989)
		(end 88.863932 -283.483812)
		(width 0.0889)
		(layer "In4.Cu")
		(net "M_D_CPU1_SB_DQ<15>")
	)
	(arc
		(start 87.923878 -283.483812)
		(mid 88.106129 -283.433462)
		(end 88.289638 -283.478986)
		(width 0.0889)
		(layer "In4.Cu")
		(net "M_D_CPU1_SB_DQ<15>")
	)
	(arc
		(start 82.65795 -283.483812)
		(mid 82.940906 -283.559989)
		(end 83.223862 -283.483812)
		(width 0.0889)
		(layer "In4.Cu")
		(net "M_D_CPU1_SB_DQ<15>")
	)
	(arc
		(start 90.178128 -283.483812)
		(mid 90.461084 -283.559989)
		(end 90.74404 -283.483812)
		(width 0.0889)
		(layer "In4.Cu")
		(net "M_D_CPU1_SB_DQ<15>")
	)
	(arc
		(start 79.466948 -283.483812)
		(mid 79.641933 -283.433868)
		(end 79.819754 -283.472636)
		(width 0.0889)
		(layer "In4.Cu")
		(net "M_D_CPU1_SB_DQ<15>")
	)
	(arc
		(start 78.899258 -283.483812)
		(mid 79.167227 -283.560635)
		(end 79.439262 -283.499814)
		(width 0.0889)
		(layer "In4.Cu")
		(net "M_D_CPU1_SB_DQ<15>")
	)
	(arc
		(start 85.478112 -283.483812)
		(mid 85.761068 -283.559989)
		(end 86.044024 -283.483812)
		(width 0.0889)
		(layer "In4.Cu")
		(net "M_D_CPU1_SB_DQ<15>")
	)
	(arc
		(start 80.403954 -283.483812)
		(mid 80.586205 -283.433462)
		(end 80.769714 -283.478986)
		(width 0.0889)
		(layer "In4.Cu")
		(net "M_D_CPU1_SB_DQ<15>")
	)
	(arc
		(start 92.057982 -283.483812)
		(mid 92.305578 -283.55899)
		(end 92.560648 -283.515562)
		(width 0.0889)
		(layer "In4.Cu")
		(net "M_D_CPU1_SB_DQ<15>")
	)
	(arc
		(start 78.711044 -283.432504)
		(mid 78.808558 -283.445659)
		(end 78.899258 -283.483812)
		(width 0.0889)
		(layer "In4.Cu")
		(net "M_D_CPU1_SB_DQ<15>")
	)
	(arc
		(start 81.35239 -283.478986)
		(mid 81.535898 -283.433492)
		(end 81.71815 -283.483812)
		(width 0.0889)
		(layer "In4.Cu")
		(net "M_D_CPU1_SB_DQ<15>")
	)
	(arc
		(start 84.538058 -283.483812)
		(mid 84.821014 -283.559989)
		(end 85.10397 -283.483812)
		(width 0.0889)
		(layer "In4.Cu")
		(net "M_D_CPU1_SB_DQ<15>")
	)
	(arc
		(start 83.223862 -283.483812)
		(mid 83.406113 -283.433462)
		(end 83.589622 -283.478986)
		(width 0.0889)
		(layer "In4.Cu")
		(net "M_D_CPU1_SB_DQ<15>")
	)
	(arc
		(start 81.71815 -283.483812)
		(mid 82.001106 -283.559989)
		(end 82.284062 -283.483812)
		(width 0.0889)
		(layer "In4.Cu")
		(net "M_D_CPU1_SB_DQ<15>")
	)
	(arc
		(start 90.752422 -283.478986)
		(mid 90.93593 -283.433492)
		(end 91.118182 -283.483812)
		(width 0.0889)
		(layer "In4.Cu")
		(net "M_D_CPU1_SB_DQ<15>")
	)
	(arc
		(start 91.118182 -283.483812)
		(mid 91.401138 -283.559989)
		(end 91.684094 -283.483812)
		(width 0.0889)
		(layer "In4.Cu")
		(net "M_D_CPU1_SB_DQ<15>")
	)
	(arc
		(start 88.863932 -283.483812)
		(mid 89.046183 -283.433462)
		(end 89.229692 -283.478986)
		(width 0.0889)
		(layer "In4.Cu")
		(net "M_D_CPU1_SB_DQ<15>")
	)
	(arc
		(start 82.284062 -283.483812)
		(mid 82.471006 -283.433557)
		(end 82.65795 -283.483812)
		(width 0.0889)
		(layer "In4.Cu")
		(net "M_D_CPU1_SB_DQ<15>")
	)
	(arc
		(start 83.598004 -283.483812)
		(mid 83.88096 -283.559989)
		(end 84.163916 -283.483812)
		(width 0.0889)
		(layer "In4.Cu")
		(net "M_D_CPU1_SB_DQ<15>")
	)
	(arc
		(start 86.418166 -283.483812)
		(mid 86.701122 -283.559989)
		(end 86.984078 -283.483812)
		(width 0.0889)
		(layer "In4.Cu")
		(net "M_D_CPU1_SB_DQ<15>")
	)
	(arc
		(start 91.684094 -283.483812)
		(mid 91.871038 -283.433557)
		(end 92.057982 -283.483812)
		(width 0.0889)
		(layer "In4.Cu")
		(net "M_D_CPU1_SB_DQ<15>")
	)
	(arc
		(start 89.238074 -283.483812)
		(mid 89.52103 -283.559989)
		(end 89.803986 -283.483812)
		(width 0.0889)
		(layer "In4.Cu")
		(net "M_D_CPU1_SB_DQ<15>")
	)
	(arc
		(start 80.778096 -283.483812)
		(mid 81.061052 -283.559989)
		(end 81.344008 -283.483812)
		(width 0.0889)
		(layer "In4.Cu")
		(net "M_D_CPU1_SB_DQ<15>")
	)
	(arc
		(start 79.863696 -283.498036)
		(mid 80.135633 -283.559862)
		(end 80.403954 -283.483812)
		(width 0.0889)
		(layer "In4.Cu")
		(net "M_D_CPU1_SB_DQ<15>")
	)
	(arc
		(start 89.812368 -283.478986)
		(mid 89.995876 -283.433492)
		(end 90.178128 -283.483812)
		(width 0.0889)
		(layer "In4.Cu")
		(net "M_D_CPU1_SB_DQ<15>")
	)
	(segment
		(start 91.86799 -282.730448)
		(end 91.401138 -282.996386)
		(width 0.10668)
		(layer "F.Cu")
		(net "M_D_CPU1_SB_DQ<14>")
	)
	(segment
		(start 82.179668 -282.66898)
		(end 82.18805 -282.673806)
		(width 0.0889)
		(layer "In4.Cu")
		(net "M_D_CPU1_SB_DQ<14>")
	)
	(segment
		(start 34.992056 -297.71467)
		(end 34.992056 -297.89882)
		(width 0.14478)
		(layer "In4.Cu")
		(net "M_D_CPU1_SB_DQ<14>")
	)
	(segment
		(start 35.1536 -298.060364)
		(end 42.178986 -298.060364)
		(width 0.14478)
		(layer "In4.Cu")
		(net "M_D_CPU1_SB_DQ<14>")
	)
	(segment
		(start 77.52207 -282.358846)
		(end 77.91323 -282.750006)
		(width 0.0889)
		(layer "In4.Cu")
		(net "M_D_CPU1_SB_DQ<14>")
	)
	(segment
		(start 91.150694 -282.705556)
		(end 91.24696 -282.730956)
		(width 0.0889)
		(layer "In4.Cu")
		(net "M_D_CPU1_SB_DQ<14>")
	)
	(segment
		(start 78.993492 -282.67406)
		(end 79.009748 -282.664662)
		(width 0.0889)
		(layer "In4.Cu")
		(net "M_D_CPU1_SB_DQ<14>")
	)
	(segment
		(start 76.203302 -283.001974)
		(end 76.84643 -282.358846)
		(width 0.0889)
		(layer "In4.Cu")
		(net "M_D_CPU1_SB_DQ<14>")
	)
	(segment
		(start 87.453978 -282.673806)
		(end 87.46236 -282.66898)
		(width 0.0889)
		(layer "In4.Cu")
		(net "M_D_CPU1_SB_DQ<14>")
	)
	(segment
		(start 50.11801 -298.060364)
		(end 50.968148 -297.210226)
		(width 0.14478)
		(layer "In4.Cu")
		(net "M_D_CPU1_SB_DQ<14>")
	)
	(segment
		(start 88.394032 -282.673806)
		(end 88.402414 -282.66898)
		(width 0.0889)
		(layer "In4.Cu")
		(net "M_D_CPU1_SB_DQ<14>")
	)
	(segment
		(start 77.91323 -282.750006)
		(end 78.711044 -282.750006)
		(width 0.0889)
		(layer "In4.Cu")
		(net "M_D_CPU1_SB_DQ<14>")
	)
	(segment
		(start 34.279078 -298.060364)
		(end 34.440622 -297.89882)
		(width 0.14478)
		(layer "In4.Cu")
		(net "M_D_CPU1_SB_DQ<14>")
	)
	(segment
		(start 52.87518 -297.210226)
		(end 53.725318 -298.060364)
		(width 0.14478)
		(layer "In4.Cu")
		(net "M_D_CPU1_SB_DQ<14>")
	)
	(segment
		(start 80.299814 -282.66898)
		(end 80.308196 -282.673806)
		(width 0.0889)
		(layer "In4.Cu")
		(net "M_D_CPU1_SB_DQ<14>")
	)
	(segment
		(start 85.93963 -282.66898)
		(end 85.948012 -282.673806)
		(width 0.0889)
		(layer "In4.Cu")
		(net "M_D_CPU1_SB_DQ<14>")
	)
	(segment
		(start 60.306458 -297.217592)
		(end 74.522076 -283.001974)
		(width 0.14478)
		(layer "In4.Cu")
		(net "M_D_CPU1_SB_DQ<14>")
	)
	(segment
		(start 45.646848 -297.210226)
		(end 46.496986 -298.060364)
		(width 0.14478)
		(layer "In4.Cu")
		(net "M_D_CPU1_SB_DQ<14>")
	)
	(segment
		(start 50.968148 -297.210226)
		(end 52.87518 -297.210226)
		(width 0.14478)
		(layer "In4.Cu")
		(net "M_D_CPU1_SB_DQ<14>")
	)
	(segment
		(start 42.178986 -298.060364)
		(end 43.029124 -297.210226)
		(width 0.14478)
		(layer "In4.Cu")
		(net "M_D_CPU1_SB_DQ<14>")
	)
	(segment
		(start 58.272426 -297.217592)
		(end 60.306458 -297.217592)
		(width 0.14478)
		(layer "In4.Cu")
		(net "M_D_CPU1_SB_DQ<14>")
	)
	(segment
		(start 90.639646 -282.66898)
		(end 90.648028 -282.673806)
		(width 0.0889)
		(layer "In4.Cu")
		(net "M_D_CPU1_SB_DQ<14>")
	)
	(segment
		(start 79.36738 -282.673806)
		(end 79.377794 -282.679902)
		(width 0.0889)
		(layer "In4.Cu")
		(net "M_D_CPU1_SB_DQ<14>")
	)
	(segment
		(start 76.84643 -282.358846)
		(end 77.52207 -282.358846)
		(width 0.0889)
		(layer "In4.Cu")
		(net "M_D_CPU1_SB_DQ<14>")
	)
	(segment
		(start 53.725318 -298.060364)
		(end 57.429654 -298.060364)
		(width 0.14478)
		(layer "In4.Cu")
		(net "M_D_CPU1_SB_DQ<14>")
	)
	(segment
		(start 46.496986 -298.060364)
		(end 50.11801 -298.060364)
		(width 0.14478)
		(layer "In4.Cu")
		(net "M_D_CPU1_SB_DQ<14>")
	)
	(segment
		(start 34.992056 -297.89882)
		(end 35.1536 -298.060364)
		(width 0.14478)
		(layer "In4.Cu")
		(net "M_D_CPU1_SB_DQ<14>")
	)
	(segment
		(start 74.522076 -283.001974)
		(end 75.968606 -283.001974)
		(width 0.14478)
		(layer "In4.Cu")
		(net "M_D_CPU1_SB_DQ<14>")
	)
	(segment
		(start 82.753962 -282.673806)
		(end 82.762344 -282.66898)
		(width 0.0889)
		(layer "In4.Cu")
		(net "M_D_CPU1_SB_DQ<14>")
	)
	(segment
		(start 34.440622 -297.89882)
		(end 34.440622 -297.71467)
		(width 0.14478)
		(layer "In4.Cu")
		(net "M_D_CPU1_SB_DQ<14>")
	)
	(segment
		(start 57.429654 -298.060364)
		(end 58.272426 -297.217592)
		(width 0.14478)
		(layer "In4.Cu")
		(net "M_D_CPU1_SB_DQ<14>")
	)
	(segment
		(start 32.695896 -297.635422)
		(end 33.120838 -298.060364)
		(width 0.14478)
		(layer "In4.Cu")
		(net "M_D_CPU1_SB_DQ<14>")
	)
	(segment
		(start 86.879684 -282.66898)
		(end 86.888066 -282.673806)
		(width 0.0889)
		(layer "In4.Cu")
		(net "M_D_CPU1_SB_DQ<14>")
	)
	(segment
		(start 43.029124 -297.210226)
		(end 45.646848 -297.210226)
		(width 0.14478)
		(layer "In4.Cu")
		(net "M_D_CPU1_SB_DQ<14>")
	)
	(segment
		(start 75.968606 -283.001974)
		(end 76.203302 -283.001974)
		(width 0.0889)
		(layer "In4.Cu")
		(net "M_D_CPU1_SB_DQ<14>")
	)
	(segment
		(start 34.830512 -297.553126)
		(end 34.992056 -297.71467)
		(width 0.14478)
		(layer "In4.Cu")
		(net "M_D_CPU1_SB_DQ<14>")
	)
	(segment
		(start 34.602166 -297.553126)
		(end 34.830512 -297.553126)
		(width 0.14478)
		(layer "In4.Cu")
		(net "M_D_CPU1_SB_DQ<14>")
	)
	(segment
		(start 34.440622 -297.71467)
		(end 34.602166 -297.553126)
		(width 0.14478)
		(layer "In4.Cu")
		(net "M_D_CPU1_SB_DQ<14>")
	)
	(segment
		(start 91.24696 -282.730956)
		(end 91.401138 -282.996386)
		(width 0.0889)
		(layer "In4.Cu")
		(net "M_D_CPU1_SB_DQ<14>")
	)
	(segment
		(start 83.694016 -282.673806)
		(end 83.702398 -282.66898)
		(width 0.0889)
		(layer "In4.Cu")
		(net "M_D_CPU1_SB_DQ<14>")
	)
	(segment
		(start 33.120838 -298.060364)
		(end 34.279078 -298.060364)
		(width 0.14478)
		(layer "In4.Cu")
		(net "M_D_CPU1_SB_DQ<14>")
	)
	(arc
		(start 87.82812 -282.673806)
		(mid 88.111076 -282.749983)
		(end 88.394032 -282.673806)
		(width 0.0889)
		(layer "In4.Cu")
		(net "M_D_CPU1_SB_DQ<14>")
	)
	(arc
		(start 80.308196 -282.673806)
		(mid 80.591152 -282.749983)
		(end 80.874108 -282.673806)
		(width 0.0889)
		(layer "In4.Cu")
		(net "M_D_CPU1_SB_DQ<14>")
	)
	(arc
		(start 85.007958 -282.673806)
		(mid 85.290914 -282.749983)
		(end 85.57387 -282.673806)
		(width 0.0889)
		(layer "In4.Cu")
		(net "M_D_CPU1_SB_DQ<14>")
	)
	(arc
		(start 88.402414 -282.66898)
		(mid 88.585922 -282.623486)
		(end 88.768174 -282.673806)
		(width 0.0889)
		(layer "In4.Cu")
		(net "M_D_CPU1_SB_DQ<14>")
	)
	(arc
		(start 80.874108 -282.673806)
		(mid 81.061052 -282.623551)
		(end 81.247996 -282.673806)
		(width 0.0889)
		(layer "In4.Cu")
		(net "M_D_CPU1_SB_DQ<14>")
	)
	(arc
		(start 81.813908 -282.673806)
		(mid 81.996159 -282.623456)
		(end 82.179668 -282.66898)
		(width 0.0889)
		(layer "In4.Cu")
		(net "M_D_CPU1_SB_DQ<14>")
	)
	(arc
		(start 79.933546 -282.673806)
		(mid 80.116051 -282.623329)
		(end 80.299814 -282.66898)
		(width 0.0889)
		(layer "In4.Cu")
		(net "M_D_CPU1_SB_DQ<14>")
	)
	(arc
		(start 85.948012 -282.673806)
		(mid 86.230968 -282.749983)
		(end 86.513924 -282.673806)
		(width 0.0889)
		(layer "In4.Cu")
		(net "M_D_CPU1_SB_DQ<14>")
	)
	(arc
		(start 78.711044 -282.750006)
		(mid 78.857292 -282.730701)
		(end 78.993492 -282.67406)
		(width 0.0889)
		(layer "In4.Cu")
		(net "M_D_CPU1_SB_DQ<14>")
	)
	(arc
		(start 82.762344 -282.66898)
		(mid 82.945852 -282.623486)
		(end 83.128104 -282.673806)
		(width 0.0889)
		(layer "In4.Cu")
		(net "M_D_CPU1_SB_DQ<14>")
	)
	(arc
		(start 79.009748 -282.664662)
		(mid 79.18973 -282.623562)
		(end 79.36738 -282.673806)
		(width 0.0889)
		(layer "In4.Cu")
		(net "M_D_CPU1_SB_DQ<14>")
	)
	(arc
		(start 83.128104 -282.673806)
		(mid 83.41106 -282.749983)
		(end 83.694016 -282.673806)
		(width 0.0889)
		(layer "In4.Cu")
		(net "M_D_CPU1_SB_DQ<14>")
	)
	(arc
		(start 86.888066 -282.673806)
		(mid 87.171022 -282.749983)
		(end 87.453978 -282.673806)
		(width 0.0889)
		(layer "In4.Cu")
		(net "M_D_CPU1_SB_DQ<14>")
	)
	(arc
		(start 84.63407 -282.673806)
		(mid 84.821014 -282.623551)
		(end 85.007958 -282.673806)
		(width 0.0889)
		(layer "In4.Cu")
		(net "M_D_CPU1_SB_DQ<14>")
	)
	(arc
		(start 90.648028 -282.673806)
		(mid 90.895624 -282.748984)
		(end 91.150694 -282.705556)
		(width 0.0889)
		(layer "In4.Cu")
		(net "M_D_CPU1_SB_DQ<14>")
	)
	(arc
		(start 79.377794 -282.679902)
		(mid 79.65648 -282.750122)
		(end 79.933546 -282.673806)
		(width 0.0889)
		(layer "In4.Cu")
		(net "M_D_CPU1_SB_DQ<14>")
	)
	(arc
		(start 90.273886 -282.673806)
		(mid 90.456137 -282.623456)
		(end 90.639646 -282.66898)
		(width 0.0889)
		(layer "In4.Cu")
		(net "M_D_CPU1_SB_DQ<14>")
	)
	(arc
		(start 84.068158 -282.673806)
		(mid 84.351114 -282.749983)
		(end 84.63407 -282.673806)
		(width 0.0889)
		(layer "In4.Cu")
		(net "M_D_CPU1_SB_DQ<14>")
	)
	(arc
		(start 83.702398 -282.66898)
		(mid 83.885906 -282.623486)
		(end 84.068158 -282.673806)
		(width 0.0889)
		(layer "In4.Cu")
		(net "M_D_CPU1_SB_DQ<14>")
	)
	(arc
		(start 89.334086 -282.673806)
		(mid 89.52103 -282.623551)
		(end 89.707974 -282.673806)
		(width 0.0889)
		(layer "In4.Cu")
		(net "M_D_CPU1_SB_DQ<14>")
	)
	(arc
		(start 81.247996 -282.673806)
		(mid 81.530952 -282.749983)
		(end 81.813908 -282.673806)
		(width 0.0889)
		(layer "In4.Cu")
		(net "M_D_CPU1_SB_DQ<14>")
	)
	(arc
		(start 86.513924 -282.673806)
		(mid 86.696175 -282.623456)
		(end 86.879684 -282.66898)
		(width 0.0889)
		(layer "In4.Cu")
		(net "M_D_CPU1_SB_DQ<14>")
	)
	(arc
		(start 85.57387 -282.673806)
		(mid 85.756121 -282.623456)
		(end 85.93963 -282.66898)
		(width 0.0889)
		(layer "In4.Cu")
		(net "M_D_CPU1_SB_DQ<14>")
	)
	(arc
		(start 82.18805 -282.673806)
		(mid 82.471006 -282.749983)
		(end 82.753962 -282.673806)
		(width 0.0889)
		(layer "In4.Cu")
		(net "M_D_CPU1_SB_DQ<14>")
	)
	(arc
		(start 87.46236 -282.66898)
		(mid 87.645868 -282.623486)
		(end 87.82812 -282.673806)
		(width 0.0889)
		(layer "In4.Cu")
		(net "M_D_CPU1_SB_DQ<14>")
	)
	(arc
		(start 88.768174 -282.673806)
		(mid 89.05113 -282.749983)
		(end 89.334086 -282.673806)
		(width 0.0889)
		(layer "In4.Cu")
		(net "M_D_CPU1_SB_DQ<14>")
	)
	(arc
		(start 89.707974 -282.673806)
		(mid 89.99093 -282.749983)
		(end 90.273886 -282.673806)
		(width 0.0889)
		(layer "In4.Cu")
		(net "M_D_CPU1_SB_DQ<14>")
	)
	(segment
		(start 92.80779 -282.730448)
		(end 92.340938 -282.996386)
		(width 0.10668)
		(layer "F.Cu")
		(net "M_D_CPU1_SB_DQ<13>")
	)
	(segment
		(start 38.171882 -298.51604)
		(end 38.402514 -298.51604)
		(width 0.14478)
		(layer "In4.Cu")
		(net "M_D_CPU1_SB_DQ<13>")
	)
	(segment
		(start 49.247806 -298.748958)
		(end 49.40935 -298.910502)
		(width 0.14478)
		(layer "In4.Cu")
		(net "M_D_CPU1_SB_DQ<13>")
	)
	(segment
		(start 39.284402 -298.51604)
		(end 39.515034 -298.51604)
		(width 0.14478)
		(layer "In4.Cu")
		(net "M_D_CPU1_SB_DQ<13>")
	)
	(segment
		(start 92.495116 -283.261816)
		(end 92.340938 -282.996386)
		(width 0.0889)
		(layer "In4.Cu")
		(net "M_D_CPU1_SB_DQ<13>")
	)
	(segment
		(start 48.857916 -298.520866)
		(end 49.086262 -298.520866)
		(width 0.14478)
		(layer "In4.Cu")
		(net "M_D_CPU1_SB_DQ<13>")
	)
	(segment
		(start 39.909496 -298.910502)
		(end 41.988994 -298.910502)
		(width 0.14478)
		(layer "In4.Cu")
		(net "M_D_CPU1_SB_DQ<13>")
	)
	(segment
		(start 90.639646 -283.323792)
		(end 90.648028 -283.318966)
		(width 0.0889)
		(layer "In4.Cu")
		(net "M_D_CPU1_SB_DQ<13>")
	)
	(segment
		(start 76.509372 -283.242004)
		(end 78.711044 -283.242004)
		(width 0.0889)
		(layer "In4.Cu")
		(net "M_D_CPU1_SB_DQ<13>")
	)
	(segment
		(start 43.126152 -298.060364)
		(end 43.430952 -298.365164)
		(width 0.14478)
		(layer "In4.Cu")
		(net "M_D_CPU1_SB_DQ<13>")
	)
	(segment
		(start 45.353224 -298.339764)
		(end 45.632624 -298.060364)
		(width 0.14478)
		(layer "In4.Cu")
		(net "M_D_CPU1_SB_DQ<13>")
	)
	(segment
		(start 56.261762 -298.520866)
		(end 56.490108 -298.520866)
		(width 0.14478)
		(layer "In4.Cu")
		(net "M_D_CPU1_SB_DQ<13>")
	)
	(segment
		(start 53.932074 -298.910502)
		(end 55.938674 -298.910502)
		(width 0.14478)
		(layer "In4.Cu")
		(net "M_D_CPU1_SB_DQ<13>")
	)
	(segment
		(start 56.100218 -298.748958)
		(end 56.100218 -298.68241)
		(width 0.14478)
		(layer "In4.Cu")
		(net "M_D_CPU1_SB_DQ<13>")
	)
	(segment
		(start 38.565328 -299.14215)
		(end 38.728142 -299.304964)
		(width 0.14478)
		(layer "In4.Cu")
		(net "M_D_CPU1_SB_DQ<13>")
	)
	(segment
		(start 56.100218 -298.68241)
		(end 56.261762 -298.520866)
		(width 0.14478)
		(layer "In4.Cu")
		(net "M_D_CPU1_SB_DQ<13>")
	)
	(segment
		(start 79.911194 -283.304742)
		(end 79.93507 -283.318712)
		(width 0.0889)
		(layer "In4.Cu")
		(net "M_D_CPU1_SB_DQ<13>")
	)
	(segment
		(start 83.694016 -283.318966)
		(end 83.702398 -283.323792)
		(width 0.0889)
		(layer "In4.Cu")
		(net "M_D_CPU1_SB_DQ<13>")
	)
	(segment
		(start 86.879684 -283.323792)
		(end 86.888066 -283.318966)
		(width 0.0889)
		(layer "In4.Cu")
		(net "M_D_CPU1_SB_DQ<13>")
	)
	(segment
		(start 45.076364 -298.339764)
		(end 45.353224 -298.339764)
		(width 0.14478)
		(layer "In4.Cu")
		(net "M_D_CPU1_SB_DQ<13>")
	)
	(segment
		(start 56.651652 -298.68241)
		(end 56.651652 -298.748958)
		(width 0.14478)
		(layer "In4.Cu")
		(net "M_D_CPU1_SB_DQ<13>")
	)
	(segment
		(start 56.490108 -298.520866)
		(end 56.651652 -298.68241)
		(width 0.14478)
		(layer "In4.Cu")
		(net "M_D_CPU1_SB_DQ<13>")
	)
	(segment
		(start 38.009068 -299.14215)
		(end 38.009068 -298.678854)
		(width 0.14478)
		(layer "In4.Cu")
		(net "M_D_CPU1_SB_DQ<13>")
	)
	(segment
		(start 49.247806 -298.68241)
		(end 49.247806 -298.748958)
		(width 0.14478)
		(layer "In4.Cu")
		(net "M_D_CPU1_SB_DQ<13>")
	)
	(segment
		(start 92.153994 -283.318966)
		(end 92.162376 -283.323792)
		(width 0.0889)
		(layer "In4.Cu")
		(net "M_D_CPU1_SB_DQ<13>")
	)
	(segment
		(start 38.958774 -299.304964)
		(end 39.121588 -299.14215)
		(width 0.14478)
		(layer "In4.Cu")
		(net "M_D_CPU1_SB_DQ<13>")
	)
	(segment
		(start 49.40935 -298.910502)
		(end 49.911254 -298.910502)
		(width 0.14478)
		(layer "In4.Cu")
		(net "M_D_CPU1_SB_DQ<13>")
	)
	(segment
		(start 38.402514 -298.51604)
		(end 38.565328 -298.678854)
		(width 0.14478)
		(layer "In4.Cu")
		(net "M_D_CPU1_SB_DQ<13>")
	)
	(segment
		(start 58.279792 -298.060364)
		(end 60.106814 -298.060364)
		(width 0.14478)
		(layer "In4.Cu")
		(net "M_D_CPU1_SB_DQ<13>")
	)
	(segment
		(start 37.846254 -299.304964)
		(end 38.009068 -299.14215)
		(width 0.14478)
		(layer "In4.Cu")
		(net "M_D_CPU1_SB_DQ<13>")
	)
	(segment
		(start 44.796964 -298.060364)
		(end 45.076364 -298.339764)
		(width 0.14478)
		(layer "In4.Cu")
		(net "M_D_CPU1_SB_DQ<13>")
	)
	(segment
		(start 48.696372 -298.748958)
		(end 48.696372 -298.68241)
		(width 0.14478)
		(layer "In4.Cu")
		(net "M_D_CPU1_SB_DQ<13>")
	)
	(segment
		(start 43.430952 -298.365164)
		(end 43.682412 -298.365164)
		(width 0.14478)
		(layer "In4.Cu")
		(net "M_D_CPU1_SB_DQ<13>")
	)
	(segment
		(start 48.696372 -298.68241)
		(end 48.857916 -298.520866)
		(width 0.14478)
		(layer "In4.Cu")
		(net "M_D_CPU1_SB_DQ<13>")
	)
	(segment
		(start 46.686978 -298.910502)
		(end 48.534828 -298.910502)
		(width 0.14478)
		(layer "In4.Cu")
		(net "M_D_CPU1_SB_DQ<13>")
	)
	(segment
		(start 43.987212 -298.060364)
		(end 44.796964 -298.060364)
		(width 0.14478)
		(layer "In4.Cu")
		(net "M_D_CPU1_SB_DQ<13>")
	)
	(segment
		(start 91.5797 -283.323792)
		(end 91.588082 -283.318966)
		(width 0.0889)
		(layer "In4.Cu")
		(net "M_D_CPU1_SB_DQ<13>")
	)
	(segment
		(start 74.710544 -283.456634)
		(end 75.963526 -283.456634)
		(width 0.14478)
		(layer "In4.Cu")
		(net "M_D_CPU1_SB_DQ<13>")
	)
	(segment
		(start 82.179668 -283.323792)
		(end 82.18805 -283.318966)
		(width 0.0889)
		(layer "In4.Cu")
		(net "M_D_CPU1_SB_DQ<13>")
	)
	(segment
		(start 43.682412 -298.365164)
		(end 43.987212 -298.060364)
		(width 0.14478)
		(layer "In4.Cu")
		(net "M_D_CPU1_SB_DQ<13>")
	)
	(segment
		(start 85.93963 -283.323792)
		(end 85.948012 -283.318966)
		(width 0.0889)
		(layer "In4.Cu")
		(net "M_D_CPU1_SB_DQ<13>")
	)
	(segment
		(start 39.515034 -298.51604)
		(end 39.909496 -298.910502)
		(width 0.14478)
		(layer "In4.Cu")
		(net "M_D_CPU1_SB_DQ<13>")
	)
	(segment
		(start 82.753962 -283.318966)
		(end 82.762344 -283.323792)
		(width 0.0889)
		(layer "In4.Cu")
		(net "M_D_CPU1_SB_DQ<13>")
	)
	(segment
		(start 39.121588 -299.14215)
		(end 39.121588 -298.678854)
		(width 0.14478)
		(layer "In4.Cu")
		(net "M_D_CPU1_SB_DQ<13>")
	)
	(segment
		(start 38.009068 -298.678854)
		(end 38.171882 -298.51604)
		(width 0.14478)
		(layer "In4.Cu")
		(net "M_D_CPU1_SB_DQ<13>")
	)
	(segment
		(start 75.963526 -283.456634)
		(end 76.294742 -283.456634)
		(width 0.0889)
		(layer "In4.Cu")
		(net "M_D_CPU1_SB_DQ<13>")
	)
	(segment
		(start 76.294742 -283.456634)
		(end 76.509372 -283.242004)
		(width 0.0889)
		(layer "In4.Cu")
		(net "M_D_CPU1_SB_DQ<13>")
	)
	(segment
		(start 45.83684 -298.060364)
		(end 46.686978 -298.910502)
		(width 0.14478)
		(layer "In4.Cu")
		(net "M_D_CPU1_SB_DQ<13>")
	)
	(segment
		(start 50.761392 -298.060364)
		(end 53.081936 -298.060364)
		(width 0.14478)
		(layer "In4.Cu")
		(net "M_D_CPU1_SB_DQ<13>")
	)
	(segment
		(start 92.472764 -283.345128)
		(end 92.495116 -283.261816)
		(width 0.0889)
		(layer "In4.Cu")
		(net "M_D_CPU1_SB_DQ<13>")
	)
	(segment
		(start 57.429654 -298.910502)
		(end 58.279792 -298.060364)
		(width 0.14478)
		(layer "In4.Cu")
		(net "M_D_CPU1_SB_DQ<13>")
	)
	(segment
		(start 36.795964 -298.485306)
		(end 37.615622 -299.304964)
		(width 0.14478)
		(layer "In4.Cu")
		(net "M_D_CPU1_SB_DQ<13>")
	)
	(segment
		(start 38.565328 -298.678854)
		(end 38.565328 -299.14215)
		(width 0.14478)
		(layer "In4.Cu")
		(net "M_D_CPU1_SB_DQ<13>")
	)
	(segment
		(start 88.394032 -283.318966)
		(end 88.402414 -283.323792)
		(width 0.0889)
		(layer "In4.Cu")
		(net "M_D_CPU1_SB_DQ<13>")
	)
	(segment
		(start 79.35214 -283.329888)
		(end 79.370936 -283.318966)
		(width 0.0889)
		(layer "In4.Cu")
		(net "M_D_CPU1_SB_DQ<13>")
	)
	(segment
		(start 45.632624 -298.060364)
		(end 45.83684 -298.060364)
		(width 0.14478)
		(layer "In4.Cu")
		(net "M_D_CPU1_SB_DQ<13>")
	)
	(segment
		(start 38.728142 -299.304964)
		(end 38.958774 -299.304964)
		(width 0.14478)
		(layer "In4.Cu")
		(net "M_D_CPU1_SB_DQ<13>")
	)
	(segment
		(start 42.839132 -298.060364)
		(end 43.126152 -298.060364)
		(width 0.14478)
		(layer "In4.Cu")
		(net "M_D_CPU1_SB_DQ<13>")
	)
	(segment
		(start 56.651652 -298.748958)
		(end 56.813196 -298.910502)
		(width 0.14478)
		(layer "In4.Cu")
		(net "M_D_CPU1_SB_DQ<13>")
	)
	(segment
		(start 79.93507 -283.318712)
		(end 79.956914 -283.331158)
		(width 0.0889)
		(layer "In4.Cu")
		(net "M_D_CPU1_SB_DQ<13>")
	)
	(segment
		(start 37.615622 -299.304964)
		(end 37.846254 -299.304964)
		(width 0.14478)
		(layer "In4.Cu")
		(net "M_D_CPU1_SB_DQ<13>")
	)
	(segment
		(start 60.106814 -298.060364)
		(end 74.710544 -283.456634)
		(width 0.14478)
		(layer "In4.Cu")
		(net "M_D_CPU1_SB_DQ<13>")
	)
	(segment
		(start 53.081936 -298.060364)
		(end 53.932074 -298.910502)
		(width 0.14478)
		(layer "In4.Cu")
		(net "M_D_CPU1_SB_DQ<13>")
	)
	(segment
		(start 39.121588 -298.678854)
		(end 39.284402 -298.51604)
		(width 0.14478)
		(layer "In4.Cu")
		(net "M_D_CPU1_SB_DQ<13>")
	)
	(segment
		(start 87.453978 -283.318966)
		(end 87.46236 -283.323792)
		(width 0.0889)
		(layer "In4.Cu")
		(net "M_D_CPU1_SB_DQ<13>")
	)
	(segment
		(start 56.813196 -298.910502)
		(end 57.429654 -298.910502)
		(width 0.14478)
		(layer "In4.Cu")
		(net "M_D_CPU1_SB_DQ<13>")
	)
	(segment
		(start 49.911254 -298.910502)
		(end 50.761392 -298.060364)
		(width 0.14478)
		(layer "In4.Cu")
		(net "M_D_CPU1_SB_DQ<13>")
	)
	(segment
		(start 48.534828 -298.910502)
		(end 48.696372 -298.748958)
		(width 0.14478)
		(layer "In4.Cu")
		(net "M_D_CPU1_SB_DQ<13>")
	)
	(segment
		(start 41.988994 -298.910502)
		(end 42.839132 -298.060364)
		(width 0.14478)
		(layer "In4.Cu")
		(net "M_D_CPU1_SB_DQ<13>")
	)
	(segment
		(start 49.086262 -298.520866)
		(end 49.247806 -298.68241)
		(width 0.14478)
		(layer "In4.Cu")
		(net "M_D_CPU1_SB_DQ<13>")
	)
	(segment
		(start 55.938674 -298.910502)
		(end 56.100218 -298.748958)
		(width 0.14478)
		(layer "In4.Cu")
		(net "M_D_CPU1_SB_DQ<13>")
	)
	(arc
		(start 87.82812 -283.318966)
		(mid 88.111076 -283.242789)
		(end 88.394032 -283.318966)
		(width 0.0889)
		(layer "In4.Cu")
		(net "M_D_CPU1_SB_DQ<13>")
	)
	(arc
		(start 78.711044 -283.242004)
		(mid 78.858531 -283.261547)
		(end 78.995778 -283.318966)
		(width 0.0889)
		(layer "In4.Cu")
		(net "M_D_CPU1_SB_DQ<13>")
	)
	(arc
		(start 80.874108 -283.318966)
		(mid 81.061052 -283.369221)
		(end 81.247996 -283.318966)
		(width 0.0889)
		(layer "In4.Cu")
		(net "M_D_CPU1_SB_DQ<13>")
	)
	(arc
		(start 84.63407 -283.318966)
		(mid 84.821014 -283.369221)
		(end 85.007958 -283.318966)
		(width 0.0889)
		(layer "In4.Cu")
		(net "M_D_CPU1_SB_DQ<13>")
	)
	(arc
		(start 81.247996 -283.318966)
		(mid 81.530952 -283.242789)
		(end 81.813908 -283.318966)
		(width 0.0889)
		(layer "In4.Cu")
		(net "M_D_CPU1_SB_DQ<13>")
	)
	(arc
		(start 78.995778 -283.318966)
		(mid 79.172569 -283.369685)
		(end 79.35214 -283.329888)
		(width 0.0889)
		(layer "In4.Cu")
		(net "M_D_CPU1_SB_DQ<13>")
	)
	(arc
		(start 85.948012 -283.318966)
		(mid 86.230968 -283.242789)
		(end 86.513924 -283.318966)
		(width 0.0889)
		(layer "In4.Cu")
		(net "M_D_CPU1_SB_DQ<13>")
	)
	(arc
		(start 88.768174 -283.318966)
		(mid 89.05113 -283.242789)
		(end 89.334086 -283.318966)
		(width 0.0889)
		(layer "In4.Cu")
		(net "M_D_CPU1_SB_DQ<13>")
	)
	(arc
		(start 89.707974 -283.318966)
		(mid 89.99093 -283.242789)
		(end 90.273886 -283.318966)
		(width 0.0889)
		(layer "In4.Cu")
		(net "M_D_CPU1_SB_DQ<13>")
	)
	(arc
		(start 79.956914 -283.331158)
		(mid 80.134096 -283.369098)
		(end 80.308196 -283.318966)
		(width 0.0889)
		(layer "In4.Cu")
		(net "M_D_CPU1_SB_DQ<13>")
	)
	(arc
		(start 86.513924 -283.318966)
		(mid 86.696175 -283.369316)
		(end 86.879684 -283.323792)
		(width 0.0889)
		(layer "In4.Cu")
		(net "M_D_CPU1_SB_DQ<13>")
	)
	(arc
		(start 81.813908 -283.318966)
		(mid 81.996159 -283.369316)
		(end 82.179668 -283.323792)
		(width 0.0889)
		(layer "In4.Cu")
		(net "M_D_CPU1_SB_DQ<13>")
	)
	(arc
		(start 82.762344 -283.323792)
		(mid 82.945852 -283.369286)
		(end 83.128104 -283.318966)
		(width 0.0889)
		(layer "In4.Cu")
		(net "M_D_CPU1_SB_DQ<13>")
	)
	(arc
		(start 90.648028 -283.318966)
		(mid 90.930984 -283.242789)
		(end 91.21394 -283.318966)
		(width 0.0889)
		(layer "In4.Cu")
		(net "M_D_CPU1_SB_DQ<13>")
	)
	(arc
		(start 80.308196 -283.318966)
		(mid 80.591152 -283.242789)
		(end 80.874108 -283.318966)
		(width 0.0889)
		(layer "In4.Cu")
		(net "M_D_CPU1_SB_DQ<13>")
	)
	(arc
		(start 87.46236 -283.323792)
		(mid 87.645868 -283.369286)
		(end 87.82812 -283.318966)
		(width 0.0889)
		(layer "In4.Cu")
		(net "M_D_CPU1_SB_DQ<13>")
	)
	(arc
		(start 91.588082 -283.318966)
		(mid 91.871038 -283.242789)
		(end 92.153994 -283.318966)
		(width 0.0889)
		(layer "In4.Cu")
		(net "M_D_CPU1_SB_DQ<13>")
	)
	(arc
		(start 88.402414 -283.323792)
		(mid 88.585922 -283.369286)
		(end 88.768174 -283.318966)
		(width 0.0889)
		(layer "In4.Cu")
		(net "M_D_CPU1_SB_DQ<13>")
	)
	(arc
		(start 82.18805 -283.318966)
		(mid 82.471006 -283.242789)
		(end 82.753962 -283.318966)
		(width 0.0889)
		(layer "In4.Cu")
		(net "M_D_CPU1_SB_DQ<13>")
	)
	(arc
		(start 83.128104 -283.318966)
		(mid 83.41106 -283.242789)
		(end 83.694016 -283.318966)
		(width 0.0889)
		(layer "In4.Cu")
		(net "M_D_CPU1_SB_DQ<13>")
	)
	(arc
		(start 91.21394 -283.318966)
		(mid 91.396191 -283.369316)
		(end 91.5797 -283.323792)
		(width 0.0889)
		(layer "In4.Cu")
		(net "M_D_CPU1_SB_DQ<13>")
	)
	(arc
		(start 85.007958 -283.318966)
		(mid 85.290914 -283.242789)
		(end 85.57387 -283.318966)
		(width 0.0889)
		(layer "In4.Cu")
		(net "M_D_CPU1_SB_DQ<13>")
	)
	(arc
		(start 89.334086 -283.318966)
		(mid 89.52103 -283.369221)
		(end 89.707974 -283.318966)
		(width 0.0889)
		(layer "In4.Cu")
		(net "M_D_CPU1_SB_DQ<13>")
	)
	(arc
		(start 92.162376 -283.323792)
		(mid 92.315246 -283.368433)
		(end 92.472764 -283.345128)
		(width 0.0889)
		(layer "In4.Cu")
		(net "M_D_CPU1_SB_DQ<13>")
	)
	(arc
		(start 85.57387 -283.318966)
		(mid 85.756121 -283.369316)
		(end 85.93963 -283.323792)
		(width 0.0889)
		(layer "In4.Cu")
		(net "M_D_CPU1_SB_DQ<13>")
	)
	(arc
		(start 84.068158 -283.318966)
		(mid 84.351114 -283.242789)
		(end 84.63407 -283.318966)
		(width 0.0889)
		(layer "In4.Cu")
		(net "M_D_CPU1_SB_DQ<13>")
	)
	(arc
		(start 86.888066 -283.318966)
		(mid 87.171022 -283.242789)
		(end 87.453978 -283.318966)
		(width 0.0889)
		(layer "In4.Cu")
		(net "M_D_CPU1_SB_DQ<13>")
	)
	(arc
		(start 90.273886 -283.318966)
		(mid 90.456137 -283.369316)
		(end 90.639646 -283.323792)
		(width 0.0889)
		(layer "In4.Cu")
		(net "M_D_CPU1_SB_DQ<13>")
	)
	(arc
		(start 83.702398 -283.323792)
		(mid 83.885906 -283.369286)
		(end 84.068158 -283.318966)
		(width 0.0889)
		(layer "In4.Cu")
		(net "M_D_CPU1_SB_DQ<13>")
	)
	(arc
		(start 79.370936 -283.318966)
		(mid 79.639256 -283.242858)
		(end 79.911194 -283.304742)
		(width 0.0889)
		(layer "In4.Cu")
		(net "M_D_CPU1_SB_DQ<13>")
	)
	(segment
		(start 91.397836 -281.920442)
		(end 90.930984 -282.18638)
		(width 0.10668)
		(layer "F.Cu")
		(net "M_D_CPU1_SB_DQ<12>")
	)
	(segment
		(start 42.358818 -297.220132)
		(end 43.208956 -296.369994)
		(width 0.14478)
		(layer "In4.Cu")
		(net "M_D_CPU1_SB_DQ<12>")
	)
	(segment
		(start 38.01618 -297.509946)
		(end 38.2778 -297.509946)
		(width 0.14478)
		(layer "In4.Cu")
		(net "M_D_CPU1_SB_DQ<12>")
	)
	(segment
		(start 55.496968 -297.610784)
		(end 55.65521 -297.452542)
		(width 0.14478)
		(layer "In4.Cu")
		(net "M_D_CPU1_SB_DQ<12>")
	)
	(segment
		(start 77.992224 -282.559506)
		(end 78.71079 -282.559506)
		(width 0.0889)
		(layer "In4.Cu")
		(net "M_D_CPU1_SB_DQ<12>")
	)
	(segment
		(start 89.803986 -282.50896)
		(end 89.812368 -282.513786)
		(width 0.0889)
		(layer "In4.Cu")
		(net "M_D_CPU1_SB_DQ<12>")
	)
	(segment
		(start 37.726366 -297.220132)
		(end 38.01618 -297.509946)
		(width 0.14478)
		(layer "In4.Cu")
		(net "M_D_CPU1_SB_DQ<12>")
	)
	(segment
		(start 78.897734 -282.508706)
		(end 78.903322 -282.505404)
		(width 0.0889)
		(layer "In4.Cu")
		(net "M_D_CPU1_SB_DQ<12>")
	)
	(segment
		(start 80.39354 -282.502864)
		(end 80.403954 -282.50896)
		(width 0.0889)
		(layer "In4.Cu")
		(net "M_D_CPU1_SB_DQ<12>")
	)
	(segment
		(start 49.19726 -297.220132)
		(end 49.358804 -297.381676)
		(width 0.14478)
		(layer "In4.Cu")
		(net "M_D_CPU1_SB_DQ<12>")
	)
	(segment
		(start 74.333608 -282.547314)
		(end 75.958446 -282.547314)
		(width 0.14478)
		(layer "In4.Cu")
		(net "M_D_CPU1_SB_DQ<12>")
	)
	(segment
		(start 88.289638 -282.513786)
		(end 88.29802 -282.50896)
		(width 0.0889)
		(layer "In4.Cu")
		(net "M_D_CPU1_SB_DQ<12>")
	)
	(segment
		(start 55.65521 -297.452542)
		(end 55.65521 -297.01744)
		(width 0.14478)
		(layer "In4.Cu")
		(net "M_D_CPU1_SB_DQ<12>")
	)
	(segment
		(start 40.764714 -297.220132)
		(end 40.926258 -297.381676)
		(width 0.14478)
		(layer "In4.Cu")
		(net "M_D_CPU1_SB_DQ<12>")
	)
	(segment
		(start 45.467016 -296.369994)
		(end 46.317154 -297.220132)
		(width 0.14478)
		(layer "In4.Cu")
		(net "M_D_CPU1_SB_DQ<12>")
	)
	(segment
		(start 79.463138 -282.50896)
		(end 79.47152 -282.513786)
		(width 0.0889)
		(layer "In4.Cu")
		(net "M_D_CPU1_SB_DQ<12>")
	)
	(segment
		(start 75.958446 -282.547314)
		(end 76.256642 -282.547314)
		(width 0.0889)
		(layer "In4.Cu")
		(net "M_D_CPU1_SB_DQ<12>")
	)
	(segment
		(start 55.09895 -297.018456)
		(end 55.09895 -297.452542)
		(width 0.14478)
		(layer "In4.Cu")
		(net "M_D_CPU1_SB_DQ<12>")
	)
	(segment
		(start 36.795964 -296.785284)
		(end 37.230812 -297.220132)
		(width 0.14478)
		(layer "In4.Cu")
		(net "M_D_CPU1_SB_DQ<12>")
	)
	(segment
		(start 48.41748 -297.601386)
		(end 48.645826 -297.601386)
		(width 0.14478)
		(layer "In4.Cu")
		(net "M_D_CPU1_SB_DQ<12>")
	)
	(segment
		(start 54.384448 -297.399964)
		(end 54.54269 -297.241722)
		(width 0.14478)
		(layer "In4.Cu")
		(net "M_D_CPU1_SB_DQ<12>")
	)
	(segment
		(start 40.926258 -297.381676)
		(end 40.926258 -297.444922)
		(width 0.14478)
		(layer "In4.Cu")
		(net "M_D_CPU1_SB_DQ<12>")
	)
	(segment
		(start 48.255936 -297.381676)
		(end 48.255936 -297.439842)
		(width 0.14478)
		(layer "In4.Cu")
		(net "M_D_CPU1_SB_DQ<12>")
	)
	(segment
		(start 59.60999 -296.601388)
		(end 59.771534 -296.762932)
		(width 0.14478)
		(layer "In4.Cu")
		(net "M_D_CPU1_SB_DQ<12>")
	)
	(segment
		(start 58.083958 -296.762932)
		(end 58.897012 -296.762932)
		(width 0.14478)
		(layer "In4.Cu")
		(net "M_D_CPU1_SB_DQ<12>")
	)
	(segment
		(start 53.710586 -297.399964)
		(end 54.384448 -297.399964)
		(width 0.14478)
		(layer "In4.Cu")
		(net "M_D_CPU1_SB_DQ<12>")
	)
	(segment
		(start 49.748694 -297.601386)
		(end 50.980086 -296.369994)
		(width 0.14478)
		(layer "In4.Cu")
		(net "M_D_CPU1_SB_DQ<12>")
	)
	(segment
		(start 54.54269 -297.018456)
		(end 54.700932 -296.860214)
		(width 0.14478)
		(layer "In4.Cu")
		(net "M_D_CPU1_SB_DQ<12>")
	)
	(segment
		(start 41.087802 -297.606466)
		(end 41.316148 -297.606466)
		(width 0.14478)
		(layer "In4.Cu")
		(net "M_D_CPU1_SB_DQ<12>")
	)
	(segment
		(start 38.2778 -297.509946)
		(end 38.567614 -297.220132)
		(width 0.14478)
		(layer "In4.Cu")
		(net "M_D_CPU1_SB_DQ<12>")
	)
	(segment
		(start 55.09895 -297.452542)
		(end 55.257192 -297.610784)
		(width 0.14478)
		(layer "In4.Cu")
		(net "M_D_CPU1_SB_DQ<12>")
	)
	(segment
		(start 56.101234 -296.860214)
		(end 56.844184 -297.603164)
		(width 0.14478)
		(layer "In4.Cu")
		(net "M_D_CPU1_SB_DQ<12>")
	)
	(segment
		(start 49.358804 -297.439842)
		(end 49.520348 -297.601386)
		(width 0.14478)
		(layer "In4.Cu")
		(net "M_D_CPU1_SB_DQ<12>")
	)
	(segment
		(start 47.405036 -297.220132)
		(end 48.094392 -297.220132)
		(width 0.14478)
		(layer "In4.Cu")
		(net "M_D_CPU1_SB_DQ<12>")
	)
	(segment
		(start 39.119048 -297.509946)
		(end 39.380668 -297.509946)
		(width 0.14478)
		(layer "In4.Cu")
		(net "M_D_CPU1_SB_DQ<12>")
	)
	(segment
		(start 60.11799 -296.762932)
		(end 74.333608 -282.547314)
		(width 0.14478)
		(layer "In4.Cu")
		(net "M_D_CPU1_SB_DQ<12>")
	)
	(segment
		(start 54.940708 -296.860214)
		(end 55.09895 -297.018456)
		(width 0.14478)
		(layer "In4.Cu")
		(net "M_D_CPU1_SB_DQ<12>")
	)
	(segment
		(start 47.243492 -297.381676)
		(end 47.405036 -297.220132)
		(width 0.14478)
		(layer "In4.Cu")
		(net "M_D_CPU1_SB_DQ<12>")
	)
	(segment
		(start 59.448446 -296.057066)
		(end 59.60999 -296.21861)
		(width 0.14478)
		(layer "In4.Cu")
		(net "M_D_CPU1_SB_DQ<12>")
	)
	(segment
		(start 37.230812 -297.220132)
		(end 37.726366 -297.220132)
		(width 0.14478)
		(layer "In4.Cu")
		(net "M_D_CPU1_SB_DQ<12>")
	)
	(segment
		(start 46.853602 -297.603926)
		(end 47.081948 -297.603926)
		(width 0.14478)
		(layer "In4.Cu")
		(net "M_D_CPU1_SB_DQ<12>")
	)
	(segment
		(start 41.316148 -297.606466)
		(end 41.477692 -297.444922)
		(width 0.14478)
		(layer "In4.Cu")
		(net "M_D_CPU1_SB_DQ<12>")
	)
	(segment
		(start 49.520348 -297.601386)
		(end 49.748694 -297.601386)
		(width 0.14478)
		(layer "In4.Cu")
		(net "M_D_CPU1_SB_DQ<12>")
	)
	(segment
		(start 59.058556 -296.601388)
		(end 59.058556 -296.21861)
		(width 0.14478)
		(layer "In4.Cu")
		(net "M_D_CPU1_SB_DQ<12>")
	)
	(segment
		(start 47.081948 -297.603926)
		(end 47.243492 -297.442382)
		(width 0.14478)
		(layer "In4.Cu")
		(net "M_D_CPU1_SB_DQ<12>")
	)
	(segment
		(start 48.645826 -297.601386)
		(end 48.80737 -297.439842)
		(width 0.14478)
		(layer "In4.Cu")
		(net "M_D_CPU1_SB_DQ<12>")
	)
	(segment
		(start 46.692058 -297.381676)
		(end 46.692058 -297.442382)
		(width 0.14478)
		(layer "In4.Cu")
		(net "M_D_CPU1_SB_DQ<12>")
	)
	(segment
		(start 48.094392 -297.220132)
		(end 48.255936 -297.381676)
		(width 0.14478)
		(layer "In4.Cu")
		(net "M_D_CPU1_SB_DQ<12>")
	)
	(segment
		(start 59.058556 -296.21861)
		(end 59.2201 -296.057066)
		(width 0.14478)
		(layer "In4.Cu")
		(net "M_D_CPU1_SB_DQ<12>")
	)
	(segment
		(start 43.208956 -296.369994)
		(end 45.467016 -296.369994)
		(width 0.14478)
		(layer "In4.Cu")
		(net "M_D_CPU1_SB_DQ<12>")
	)
	(segment
		(start 83.589622 -282.513786)
		(end 83.598004 -282.50896)
		(width 0.0889)
		(layer "In4.Cu")
		(net "M_D_CPU1_SB_DQ<12>")
	)
	(segment
		(start 49.358804 -297.381676)
		(end 49.358804 -297.439842)
		(width 0.14478)
		(layer "In4.Cu")
		(net "M_D_CPU1_SB_DQ<12>")
	)
	(segment
		(start 39.670482 -297.220132)
		(end 40.764714 -297.220132)
		(width 0.14478)
		(layer "In4.Cu")
		(net "M_D_CPU1_SB_DQ<12>")
	)
	(segment
		(start 59.2201 -296.057066)
		(end 59.448446 -296.057066)
		(width 0.14478)
		(layer "In4.Cu")
		(net "M_D_CPU1_SB_DQ<12>")
	)
	(segment
		(start 57.243726 -297.603164)
		(end 58.083958 -296.762932)
		(width 0.14478)
		(layer "In4.Cu")
		(net "M_D_CPU1_SB_DQ<12>")
	)
	(segment
		(start 59.60999 -296.21861)
		(end 59.60999 -296.601388)
		(width 0.14478)
		(layer "In4.Cu")
		(net "M_D_CPU1_SB_DQ<12>")
	)
	(segment
		(start 54.700932 -296.860214)
		(end 54.940708 -296.860214)
		(width 0.14478)
		(layer "In4.Cu")
		(net "M_D_CPU1_SB_DQ<12>")
	)
	(segment
		(start 59.771534 -296.762932)
		(end 60.11799 -296.762932)
		(width 0.14478)
		(layer "In4.Cu")
		(net "M_D_CPU1_SB_DQ<12>")
	)
	(segment
		(start 76.63561 -282.168346)
		(end 77.601064 -282.168346)
		(width 0.0889)
		(layer "In4.Cu")
		(net "M_D_CPU1_SB_DQ<12>")
	)
	(segment
		(start 50.980086 -296.369994)
		(end 52.680616 -296.369994)
		(width 0.14478)
		(layer "In4.Cu")
		(net "M_D_CPU1_SB_DQ<12>")
	)
	(segment
		(start 46.530514 -297.220132)
		(end 46.692058 -297.381676)
		(width 0.14478)
		(layer "In4.Cu")
		(net "M_D_CPU1_SB_DQ<12>")
	)
	(segment
		(start 46.317154 -297.220132)
		(end 46.530514 -297.220132)
		(width 0.14478)
		(layer "In4.Cu")
		(net "M_D_CPU1_SB_DQ<12>")
	)
	(segment
		(start 89.229692 -282.513786)
		(end 89.238074 -282.50896)
		(width 0.0889)
		(layer "In4.Cu")
		(net "M_D_CPU1_SB_DQ<12>")
	)
	(segment
		(start 52.680616 -296.369994)
		(end 53.710586 -297.399964)
		(width 0.14478)
		(layer "In4.Cu")
		(net "M_D_CPU1_SB_DQ<12>")
	)
	(segment
		(start 58.897012 -296.762932)
		(end 59.058556 -296.601388)
		(width 0.14478)
		(layer "In4.Cu")
		(net "M_D_CPU1_SB_DQ<12>")
	)
	(segment
		(start 76.256642 -282.547314)
		(end 76.63561 -282.168346)
		(width 0.0889)
		(layer "In4.Cu")
		(net "M_D_CPU1_SB_DQ<12>")
	)
	(segment
		(start 40.926258 -297.444922)
		(end 41.087802 -297.606466)
		(width 0.14478)
		(layer "In4.Cu")
		(net "M_D_CPU1_SB_DQ<12>")
	)
	(segment
		(start 39.380668 -297.509946)
		(end 39.670482 -297.220132)
		(width 0.14478)
		(layer "In4.Cu")
		(net "M_D_CPU1_SB_DQ<12>")
	)
	(segment
		(start 84.529676 -282.513786)
		(end 84.538058 -282.50896)
		(width 0.0889)
		(layer "In4.Cu")
		(net "M_D_CPU1_SB_DQ<12>")
	)
	(segment
		(start 46.692058 -297.442382)
		(end 46.853602 -297.603926)
		(width 0.14478)
		(layer "In4.Cu")
		(net "M_D_CPU1_SB_DQ<12>")
	)
	(segment
		(start 55.812436 -296.860214)
		(end 56.101234 -296.860214)
		(width 0.14478)
		(layer "In4.Cu")
		(net "M_D_CPU1_SB_DQ<12>")
	)
	(segment
		(start 41.639236 -297.220132)
		(end 42.358818 -297.220132)
		(width 0.14478)
		(layer "In4.Cu")
		(net "M_D_CPU1_SB_DQ<12>")
	)
	(segment
		(start 85.10397 -282.50896)
		(end 85.112352 -282.513786)
		(width 0.0889)
		(layer "In4.Cu")
		(net "M_D_CPU1_SB_DQ<12>")
	)
	(segment
		(start 47.243492 -297.442382)
		(end 47.243492 -297.381676)
		(width 0.14478)
		(layer "In4.Cu")
		(net "M_D_CPU1_SB_DQ<12>")
	)
	(segment
		(start 81.344008 -282.50896)
		(end 81.35239 -282.513786)
		(width 0.0889)
		(layer "In4.Cu")
		(net "M_D_CPU1_SB_DQ<12>")
	)
	(segment
		(start 77.601064 -282.168346)
		(end 77.992224 -282.559506)
		(width 0.0889)
		(layer "In4.Cu")
		(net "M_D_CPU1_SB_DQ<12>")
	)
	(segment
		(start 56.844184 -297.603164)
		(end 57.243726 -297.603164)
		(width 0.14478)
		(layer "In4.Cu")
		(net "M_D_CPU1_SB_DQ<12>")
	)
	(segment
		(start 38.567614 -297.220132)
		(end 38.829234 -297.220132)
		(width 0.14478)
		(layer "In4.Cu")
		(net "M_D_CPU1_SB_DQ<12>")
	)
	(segment
		(start 54.54269 -297.241722)
		(end 54.54269 -297.018456)
		(width 0.14478)
		(layer "In4.Cu")
		(net "M_D_CPU1_SB_DQ<12>")
	)
	(segment
		(start 91.06281 -282.535122)
		(end 91.085162 -282.45181)
		(width 0.0889)
		(layer "In4.Cu")
		(net "M_D_CPU1_SB_DQ<12>")
	)
	(segment
		(start 41.477692 -297.444922)
		(end 41.477692 -297.381676)
		(width 0.14478)
		(layer "In4.Cu")
		(net "M_D_CPU1_SB_DQ<12>")
	)
	(segment
		(start 90.74404 -282.50896)
		(end 90.752422 -282.513786)
		(width 0.0889)
		(layer "In4.Cu")
		(net "M_D_CPU1_SB_DQ<12>")
	)
	(segment
		(start 48.255936 -297.439842)
		(end 48.41748 -297.601386)
		(width 0.14478)
		(layer "In4.Cu")
		(net "M_D_CPU1_SB_DQ<12>")
	)
	(segment
		(start 55.257192 -297.610784)
		(end 55.496968 -297.610784)
		(width 0.14478)
		(layer "In4.Cu")
		(net "M_D_CPU1_SB_DQ<12>")
	)
	(segment
		(start 38.829234 -297.220132)
		(end 39.119048 -297.509946)
		(width 0.14478)
		(layer "In4.Cu")
		(net "M_D_CPU1_SB_DQ<12>")
	)
	(segment
		(start 48.968914 -297.220132)
		(end 49.19726 -297.220132)
		(width 0.14478)
		(layer "In4.Cu")
		(net "M_D_CPU1_SB_DQ<12>")
	)
	(segment
		(start 48.80737 -297.439842)
		(end 48.80737 -297.381676)
		(width 0.14478)
		(layer "In4.Cu")
		(net "M_D_CPU1_SB_DQ<12>")
	)
	(segment
		(start 86.044024 -282.50896)
		(end 86.052406 -282.513786)
		(width 0.0889)
		(layer "In4.Cu")
		(net "M_D_CPU1_SB_DQ<12>")
	)
	(segment
		(start 91.085162 -282.45181)
		(end 90.930984 -282.18638)
		(width 0.0889)
		(layer "In4.Cu")
		(net "M_D_CPU1_SB_DQ<12>")
	)
	(segment
		(start 80.769714 -282.513786)
		(end 80.778096 -282.50896)
		(width 0.0889)
		(layer "In4.Cu")
		(net "M_D_CPU1_SB_DQ<12>")
	)
	(segment
		(start 48.80737 -297.381676)
		(end 48.968914 -297.220132)
		(width 0.14478)
		(layer "In4.Cu")
		(net "M_D_CPU1_SB_DQ<12>")
	)
	(segment
		(start 41.477692 -297.381676)
		(end 41.639236 -297.220132)
		(width 0.14478)
		(layer "In4.Cu")
		(net "M_D_CPU1_SB_DQ<12>")
	)
	(segment
		(start 55.65521 -297.01744)
		(end 55.812436 -296.860214)
		(width 0.14478)
		(layer "In4.Cu")
		(net "M_D_CPU1_SB_DQ<12>")
	)
	(arc
		(start 90.178128 -282.50896)
		(mid 90.461084 -282.432783)
		(end 90.74404 -282.50896)
		(width 0.0889)
		(layer "In4.Cu")
		(net "M_D_CPU1_SB_DQ<12>")
	)
	(arc
		(start 86.984078 -282.50896)
		(mid 87.171022 -282.559215)
		(end 87.357966 -282.50896)
		(width 0.0889)
		(layer "In4.Cu")
		(net "M_D_CPU1_SB_DQ<12>")
	)
	(arc
		(start 80.403954 -282.50896)
		(mid 80.586205 -282.55931)
		(end 80.769714 -282.513786)
		(width 0.0889)
		(layer "In4.Cu")
		(net "M_D_CPU1_SB_DQ<12>")
	)
	(arc
		(start 86.052406 -282.513786)
		(mid 86.235914 -282.55928)
		(end 86.418166 -282.50896)
		(width 0.0889)
		(layer "In4.Cu")
		(net "M_D_CPU1_SB_DQ<12>")
	)
	(arc
		(start 89.238074 -282.50896)
		(mid 89.52103 -282.432783)
		(end 89.803986 -282.50896)
		(width 0.0889)
		(layer "In4.Cu")
		(net "M_D_CPU1_SB_DQ<12>")
	)
	(arc
		(start 88.863932 -282.50896)
		(mid 89.046183 -282.55931)
		(end 89.229692 -282.513786)
		(width 0.0889)
		(layer "In4.Cu")
		(net "M_D_CPU1_SB_DQ<12>")
	)
	(arc
		(start 83.223862 -282.50896)
		(mid 83.406113 -282.55931)
		(end 83.589622 -282.513786)
		(width 0.0889)
		(layer "In4.Cu")
		(net "M_D_CPU1_SB_DQ<12>")
	)
	(arc
		(start 78.71079 -282.559506)
		(mid 78.807608 -282.546435)
		(end 78.897734 -282.508706)
		(width 0.0889)
		(layer "In4.Cu")
		(net "M_D_CPU1_SB_DQ<12>")
	)
	(arc
		(start 87.923878 -282.50896)
		(mid 88.106129 -282.55931)
		(end 88.289638 -282.513786)
		(width 0.0889)
		(layer "In4.Cu")
		(net "M_D_CPU1_SB_DQ<12>")
	)
	(arc
		(start 82.284062 -282.50896)
		(mid 82.471006 -282.559215)
		(end 82.65795 -282.50896)
		(width 0.0889)
		(layer "In4.Cu")
		(net "M_D_CPU1_SB_DQ<12>")
	)
	(arc
		(start 88.29802 -282.50896)
		(mid 88.580976 -282.432783)
		(end 88.863932 -282.50896)
		(width 0.0889)
		(layer "In4.Cu")
		(net "M_D_CPU1_SB_DQ<12>")
	)
	(arc
		(start 84.538058 -282.50896)
		(mid 84.821014 -282.432783)
		(end 85.10397 -282.50896)
		(width 0.0889)
		(layer "In4.Cu")
		(net "M_D_CPU1_SB_DQ<12>")
	)
	(arc
		(start 89.812368 -282.513786)
		(mid 89.995876 -282.55928)
		(end 90.178128 -282.50896)
		(width 0.0889)
		(layer "In4.Cu")
		(net "M_D_CPU1_SB_DQ<12>")
	)
	(arc
		(start 85.112352 -282.513786)
		(mid 85.29586 -282.55928)
		(end 85.478112 -282.50896)
		(width 0.0889)
		(layer "In4.Cu")
		(net "M_D_CPU1_SB_DQ<12>")
	)
	(arc
		(start 85.478112 -282.50896)
		(mid 85.761068 -282.432783)
		(end 86.044024 -282.50896)
		(width 0.0889)
		(layer "In4.Cu")
		(net "M_D_CPU1_SB_DQ<12>")
	)
	(arc
		(start 83.598004 -282.50896)
		(mid 83.88096 -282.432783)
		(end 84.163916 -282.50896)
		(width 0.0889)
		(layer "In4.Cu")
		(net "M_D_CPU1_SB_DQ<12>")
	)
	(arc
		(start 79.837788 -282.50896)
		(mid 80.114855 -282.432689)
		(end 80.39354 -282.502864)
		(width 0.0889)
		(layer "In4.Cu")
		(net "M_D_CPU1_SB_DQ<12>")
	)
	(arc
		(start 90.752422 -282.513786)
		(mid 90.905292 -282.558427)
		(end 91.06281 -282.535122)
		(width 0.0889)
		(layer "In4.Cu")
		(net "M_D_CPU1_SB_DQ<12>")
	)
	(arc
		(start 78.903322 -282.505404)
		(mid 79.183711 -282.432735)
		(end 79.463138 -282.50896)
		(width 0.0889)
		(layer "In4.Cu")
		(net "M_D_CPU1_SB_DQ<12>")
	)
	(arc
		(start 82.65795 -282.50896)
		(mid 82.940906 -282.432783)
		(end 83.223862 -282.50896)
		(width 0.0889)
		(layer "In4.Cu")
		(net "M_D_CPU1_SB_DQ<12>")
	)
	(arc
		(start 87.357966 -282.50896)
		(mid 87.640922 -282.432783)
		(end 87.923878 -282.50896)
		(width 0.0889)
		(layer "In4.Cu")
		(net "M_D_CPU1_SB_DQ<12>")
	)
	(arc
		(start 81.71815 -282.50896)
		(mid 82.001106 -282.432783)
		(end 82.284062 -282.50896)
		(width 0.0889)
		(layer "In4.Cu")
		(net "M_D_CPU1_SB_DQ<12>")
	)
	(arc
		(start 86.418166 -282.50896)
		(mid 86.701122 -282.432783)
		(end 86.984078 -282.50896)
		(width 0.0889)
		(layer "In4.Cu")
		(net "M_D_CPU1_SB_DQ<12>")
	)
	(arc
		(start 79.47152 -282.513786)
		(mid 79.655282 -282.559402)
		(end 79.837788 -282.50896)
		(width 0.0889)
		(layer "In4.Cu")
		(net "M_D_CPU1_SB_DQ<12>")
	)
	(arc
		(start 84.163916 -282.50896)
		(mid 84.346167 -282.55931)
		(end 84.529676 -282.513786)
		(width 0.0889)
		(layer "In4.Cu")
		(net "M_D_CPU1_SB_DQ<12>")
	)
	(arc
		(start 81.35239 -282.513786)
		(mid 81.535898 -282.55928)
		(end 81.71815 -282.50896)
		(width 0.0889)
		(layer "In4.Cu")
		(net "M_D_CPU1_SB_DQ<12>")
	)
	(arc
		(start 80.778096 -282.50896)
		(mid 81.061052 -282.432783)
		(end 81.344008 -282.50896)
		(width 0.0889)
		(layer "In4.Cu")
		(net "M_D_CPU1_SB_DQ<12>")
	)
	(segment
		(start 93.277944 -280.30043)
		(end 92.811092 -280.566368)
		(width 0.10668)
		(layer "F.Cu")
		(net "M_D_CPU1_SB_DQ<11>")
	)
	(segment
		(start 76.316078 -280.207974)
		(end 76.604368 -280.207974)
		(width 0.0889)
		(layer "In4.Cu")
		(net "M_D_CPU1_SB_DQ<11>")
	)
	(segment
		(start 56.934862 -293.415212)
		(end 57.389776 -292.960298)
		(width 0.14478)
		(layer "In4.Cu")
		(net "M_D_CPU1_SB_DQ<11>")
	)
	(segment
		(start 92.560648 -280.275538)
		(end 92.656914 -280.300938)
		(width 0.0889)
		(layer "In4.Cu")
		(net "M_D_CPU1_SB_DQ<11>")
	)
	(segment
		(start 83.589622 -280.238962)
		(end 83.598004 -280.243788)
		(width 0.0889)
		(layer "In4.Cu")
		(net "M_D_CPU1_SB_DQ<11>")
	)
	(segment
		(start 86.044024 -280.243788)
		(end 86.052406 -280.238962)
		(width 0.0889)
		(layer "In4.Cu")
		(net "M_D_CPU1_SB_DQ<11>")
	)
	(segment
		(start 53.528468 -292.950646)
		(end 53.993034 -293.415212)
		(width 0.14478)
		(layer "In4.Cu")
		(net "M_D_CPU1_SB_DQ<11>")
	)
	(segment
		(start 49.031144 -293.80053)
		(end 49.881028 -292.950646)
		(width 0.14478)
		(layer "In4.Cu")
		(net "M_D_CPU1_SB_DQ<11>")
	)
	(segment
		(start 59.043316 -292.960298)
		(end 59.337448 -292.666166)
		(width 0.14478)
		(layer "In4.Cu")
		(net "M_D_CPU1_SB_DQ<11>")
	)
	(segment
		(start 53.993034 -293.415212)
		(end 56.934862 -293.415212)
		(width 0.14478)
		(layer "In4.Cu")
		(net "M_D_CPU1_SB_DQ<11>")
	)
	(segment
		(start 89.229692 -280.238962)
		(end 89.238074 -280.243788)
		(width 0.0889)
		(layer "In4.Cu")
		(net "M_D_CPU1_SB_DQ<11>")
	)
	(segment
		(start 85.10397 -280.243788)
		(end 85.112352 -280.238962)
		(width 0.0889)
		(layer "In4.Cu")
		(net "M_D_CPU1_SB_DQ<11>")
	)
	(segment
		(start 92.656914 -280.300938)
		(end 92.811092 -280.566368)
		(width 0.0889)
		(layer "In4.Cu")
		(net "M_D_CPU1_SB_DQ<11>")
	)
	(segment
		(start 32.695896 -293.38524)
		(end 33.111186 -293.80053)
		(width 0.14478)
		(layer "In4.Cu")
		(net "M_D_CPU1_SB_DQ<11>")
	)
	(segment
		(start 59.337448 -292.666166)
		(end 59.59475 -292.666166)
		(width 0.14478)
		(layer "In4.Cu")
		(net "M_D_CPU1_SB_DQ<11>")
	)
	(segment
		(start 41.76522 -293.80053)
		(end 42.615104 -292.950646)
		(width 0.14478)
		(layer "In4.Cu")
		(net "M_D_CPU1_SB_DQ<11>")
	)
	(segment
		(start 88.289638 -280.238962)
		(end 88.29802 -280.243788)
		(width 0.0889)
		(layer "In4.Cu")
		(net "M_D_CPU1_SB_DQ<11>")
	)
	(segment
		(start 49.881028 -292.950646)
		(end 53.528468 -292.950646)
		(width 0.14478)
		(layer "In4.Cu")
		(net "M_D_CPU1_SB_DQ<11>")
	)
	(segment
		(start 42.615104 -292.950646)
		(end 45.476668 -292.950646)
		(width 0.14478)
		(layer "In4.Cu")
		(net "M_D_CPU1_SB_DQ<11>")
	)
	(segment
		(start 45.476668 -292.950646)
		(end 46.326552 -293.80053)
		(width 0.14478)
		(layer "In4.Cu")
		(net "M_D_CPU1_SB_DQ<11>")
	)
	(segment
		(start 46.326552 -293.80053)
		(end 49.031144 -293.80053)
		(width 0.14478)
		(layer "In4.Cu")
		(net "M_D_CPU1_SB_DQ<11>")
	)
	(segment
		(start 60.387738 -292.960298)
		(end 65.409826 -287.93821)
		(width 0.14478)
		(layer "In4.Cu")
		(net "M_D_CPU1_SB_DQ<11>")
	)
	(segment
		(start 59.59475 -292.666166)
		(end 59.888882 -292.960298)
		(width 0.14478)
		(layer "In4.Cu")
		(net "M_D_CPU1_SB_DQ<11>")
	)
	(segment
		(start 65.409826 -287.071562)
		(end 72.273414 -280.207974)
		(width 0.14478)
		(layer "In4.Cu")
		(net "M_D_CPU1_SB_DQ<11>")
	)
	(segment
		(start 80.769714 -280.238962)
		(end 80.778096 -280.243788)
		(width 0.0889)
		(layer "In4.Cu")
		(net "M_D_CPU1_SB_DQ<11>")
	)
	(segment
		(start 89.803986 -280.243788)
		(end 89.812368 -280.238962)
		(width 0.0889)
		(layer "In4.Cu")
		(net "M_D_CPU1_SB_DQ<11>")
	)
	(segment
		(start 84.529676 -280.238962)
		(end 84.538058 -280.243788)
		(width 0.0889)
		(layer "In4.Cu")
		(net "M_D_CPU1_SB_DQ<11>")
	)
	(segment
		(start 76.650596 -280.161746)
		(end 79.534004 -280.161746)
		(width 0.0889)
		(layer "In4.Cu")
		(net "M_D_CPU1_SB_DQ<11>")
	)
	(segment
		(start 59.888882 -292.960298)
		(end 60.387738 -292.960298)
		(width 0.14478)
		(layer "In4.Cu")
		(net "M_D_CPU1_SB_DQ<11>")
	)
	(segment
		(start 33.111186 -293.80053)
		(end 41.76522 -293.80053)
		(width 0.14478)
		(layer "In4.Cu")
		(net "M_D_CPU1_SB_DQ<11>")
	)
	(segment
		(start 76.604368 -280.207974)
		(end 76.650596 -280.161746)
		(width 0.0889)
		(layer "In4.Cu")
		(net "M_D_CPU1_SB_DQ<11>")
	)
	(segment
		(start 80.389222 -280.252424)
		(end 80.403954 -280.243788)
		(width 0.0889)
		(layer "In4.Cu")
		(net "M_D_CPU1_SB_DQ<11>")
	)
	(segment
		(start 90.74404 -280.243788)
		(end 90.752422 -280.238962)
		(width 0.0889)
		(layer "In4.Cu")
		(net "M_D_CPU1_SB_DQ<11>")
	)
	(segment
		(start 65.409826 -287.93821)
		(end 65.409826 -287.071562)
		(width 0.14478)
		(layer "In4.Cu")
		(net "M_D_CPU1_SB_DQ<11>")
	)
	(segment
		(start 72.273414 -280.207974)
		(end 76.316078 -280.207974)
		(width 0.14478)
		(layer "In4.Cu")
		(net "M_D_CPU1_SB_DQ<11>")
	)
	(segment
		(start 57.389776 -292.960298)
		(end 59.043316 -292.960298)
		(width 0.14478)
		(layer "In4.Cu")
		(net "M_D_CPU1_SB_DQ<11>")
	)
	(segment
		(start 81.344008 -280.243788)
		(end 81.35239 -280.238962)
		(width 0.0889)
		(layer "In4.Cu")
		(net "M_D_CPU1_SB_DQ<11>")
	)
	(arc
		(start 79.837534 -280.243788)
		(mid 80.11224 -280.320152)
		(end 80.389222 -280.252424)
		(width 0.0889)
		(layer "In4.Cu")
		(net "M_D_CPU1_SB_DQ<11>")
	)
	(arc
		(start 80.403954 -280.243788)
		(mid 80.586205 -280.193438)
		(end 80.769714 -280.238962)
		(width 0.0889)
		(layer "In4.Cu")
		(net "M_D_CPU1_SB_DQ<11>")
	)
	(arc
		(start 89.238074 -280.243788)
		(mid 89.52103 -280.319965)
		(end 89.803986 -280.243788)
		(width 0.0889)
		(layer "In4.Cu")
		(net "M_D_CPU1_SB_DQ<11>")
	)
	(arc
		(start 86.052406 -280.238962)
		(mid 86.235914 -280.193468)
		(end 86.418166 -280.243788)
		(width 0.0889)
		(layer "In4.Cu")
		(net "M_D_CPU1_SB_DQ<11>")
	)
	(arc
		(start 84.538058 -280.243788)
		(mid 84.821014 -280.319965)
		(end 85.10397 -280.243788)
		(width 0.0889)
		(layer "In4.Cu")
		(net "M_D_CPU1_SB_DQ<11>")
	)
	(arc
		(start 89.812368 -280.238962)
		(mid 89.995876 -280.193468)
		(end 90.178128 -280.243788)
		(width 0.0889)
		(layer "In4.Cu")
		(net "M_D_CPU1_SB_DQ<11>")
	)
	(arc
		(start 81.35239 -280.238962)
		(mid 81.535898 -280.193468)
		(end 81.71815 -280.243788)
		(width 0.0889)
		(layer "In4.Cu")
		(net "M_D_CPU1_SB_DQ<11>")
	)
	(arc
		(start 87.357966 -280.243788)
		(mid 87.640922 -280.319965)
		(end 87.923878 -280.243788)
		(width 0.0889)
		(layer "In4.Cu")
		(net "M_D_CPU1_SB_DQ<11>")
	)
	(arc
		(start 91.118182 -280.243788)
		(mid 91.401138 -280.319965)
		(end 91.684094 -280.243788)
		(width 0.0889)
		(layer "In4.Cu")
		(net "M_D_CPU1_SB_DQ<11>")
	)
	(arc
		(start 90.752422 -280.238962)
		(mid 90.93593 -280.193468)
		(end 91.118182 -280.243788)
		(width 0.0889)
		(layer "In4.Cu")
		(net "M_D_CPU1_SB_DQ<11>")
	)
	(arc
		(start 85.478112 -280.243788)
		(mid 85.761068 -280.319965)
		(end 86.044024 -280.243788)
		(width 0.0889)
		(layer "In4.Cu")
		(net "M_D_CPU1_SB_DQ<11>")
	)
	(arc
		(start 83.598004 -280.243788)
		(mid 83.88096 -280.319965)
		(end 84.163916 -280.243788)
		(width 0.0889)
		(layer "In4.Cu")
		(net "M_D_CPU1_SB_DQ<11>")
	)
	(arc
		(start 80.778096 -280.243788)
		(mid 81.061052 -280.319965)
		(end 81.344008 -280.243788)
		(width 0.0889)
		(layer "In4.Cu")
		(net "M_D_CPU1_SB_DQ<11>")
	)
	(arc
		(start 91.684094 -280.243788)
		(mid 91.871038 -280.193533)
		(end 92.057982 -280.243788)
		(width 0.0889)
		(layer "In4.Cu")
		(net "M_D_CPU1_SB_DQ<11>")
	)
	(arc
		(start 87.923878 -280.243788)
		(mid 88.106129 -280.193438)
		(end 88.289638 -280.238962)
		(width 0.0889)
		(layer "In4.Cu")
		(net "M_D_CPU1_SB_DQ<11>")
	)
	(arc
		(start 92.057982 -280.243788)
		(mid 92.305578 -280.318966)
		(end 92.560648 -280.275538)
		(width 0.0889)
		(layer "In4.Cu")
		(net "M_D_CPU1_SB_DQ<11>")
	)
	(arc
		(start 88.29802 -280.243788)
		(mid 88.580976 -280.319965)
		(end 88.863932 -280.243788)
		(width 0.0889)
		(layer "In4.Cu")
		(net "M_D_CPU1_SB_DQ<11>")
	)
	(arc
		(start 83.223862 -280.243788)
		(mid 83.406113 -280.193438)
		(end 83.589622 -280.238962)
		(width 0.0889)
		(layer "In4.Cu")
		(net "M_D_CPU1_SB_DQ<11>")
	)
	(arc
		(start 84.163916 -280.243788)
		(mid 84.346167 -280.193438)
		(end 84.529676 -280.238962)
		(width 0.0889)
		(layer "In4.Cu")
		(net "M_D_CPU1_SB_DQ<11>")
	)
	(arc
		(start 82.65795 -280.243788)
		(mid 82.940906 -280.319965)
		(end 83.223862 -280.243788)
		(width 0.0889)
		(layer "In4.Cu")
		(net "M_D_CPU1_SB_DQ<11>")
	)
	(arc
		(start 82.284062 -280.243788)
		(mid 82.471006 -280.193533)
		(end 82.65795 -280.243788)
		(width 0.0889)
		(layer "In4.Cu")
		(net "M_D_CPU1_SB_DQ<11>")
	)
	(arc
		(start 85.112352 -280.238962)
		(mid 85.29586 -280.193468)
		(end 85.478112 -280.243788)
		(width 0.0889)
		(layer "In4.Cu")
		(net "M_D_CPU1_SB_DQ<11>")
	)
	(arc
		(start 86.984078 -280.243788)
		(mid 87.171022 -280.193533)
		(end 87.357966 -280.243788)
		(width 0.0889)
		(layer "In4.Cu")
		(net "M_D_CPU1_SB_DQ<11>")
	)
	(arc
		(start 86.418166 -280.243788)
		(mid 86.701122 -280.319965)
		(end 86.984078 -280.243788)
		(width 0.0889)
		(layer "In4.Cu")
		(net "M_D_CPU1_SB_DQ<11>")
	)
	(arc
		(start 90.178128 -280.243788)
		(mid 90.461084 -280.319965)
		(end 90.74404 -280.243788)
		(width 0.0889)
		(layer "In4.Cu")
		(net "M_D_CPU1_SB_DQ<11>")
	)
	(arc
		(start 79.534004 -280.161746)
		(mid 79.691224 -280.182603)
		(end 79.837534 -280.243788)
		(width 0.0889)
		(layer "In4.Cu")
		(net "M_D_CPU1_SB_DQ<11>")
	)
	(arc
		(start 88.863932 -280.243788)
		(mid 89.046183 -280.193438)
		(end 89.229692 -280.238962)
		(width 0.0889)
		(layer "In4.Cu")
		(net "M_D_CPU1_SB_DQ<11>")
	)
	(arc
		(start 81.71815 -280.243788)
		(mid 82.001106 -280.319965)
		(end 82.284062 -280.243788)
		(width 0.0889)
		(layer "In4.Cu")
		(net "M_D_CPU1_SB_DQ<11>")
	)
	(segment
		(start 91.86799 -279.490424)
		(end 91.401138 -279.756362)
		(width 0.10668)
		(layer "F.Cu")
		(net "M_D_CPU1_SB_DQ<10>")
	)
	(segment
		(start 82.179668 -279.428956)
		(end 82.18805 -279.433782)
		(width 0.0889)
		(layer "In4.Cu")
		(net "M_D_CPU1_SB_DQ<10>")
	)
	(segment
		(start 53.55844 -291.260276)
		(end 54.408578 -292.110414)
		(width 0.14478)
		(layer "In4.Cu")
		(net "M_D_CPU1_SB_DQ<10>")
	)
	(segment
		(start 83.694016 -279.433782)
		(end 83.702398 -279.428956)
		(width 0.0889)
		(layer "In4.Cu")
		(net "M_D_CPU1_SB_DQ<10>")
	)
	(segment
		(start 79.36738 -279.433782)
		(end 79.377794 -279.439878)
		(width 0.0889)
		(layer "In4.Cu")
		(net "M_D_CPU1_SB_DQ<10>")
	)
	(segment
		(start 60.815728 -291.260276)
		(end 62.310518 -289.765486)
		(width 0.14478)
		(layer "In4.Cu")
		(net "M_D_CPU1_SB_DQ<10>")
	)
	(segment
		(start 42.88282 -291.260276)
		(end 45.335952 -291.260276)
		(width 0.14478)
		(layer "In4.Cu")
		(net "M_D_CPU1_SB_DQ<10>")
	)
	(segment
		(start 56.95315 -292.110414)
		(end 57.803288 -291.260276)
		(width 0.14478)
		(layer "In4.Cu")
		(net "M_D_CPU1_SB_DQ<10>")
	)
	(segment
		(start 33.769046 -291.669978)
		(end 33.93186 -291.507164)
		(width 0.14478)
		(layer "In4.Cu")
		(net "M_D_CPU1_SB_DQ<10>")
	)
	(segment
		(start 59.643772 -290.97986)
		(end 59.932316 -290.97986)
		(width 0.14478)
		(layer "In4.Cu")
		(net "M_D_CPU1_SB_DQ<10>")
	)
	(segment
		(start 62.310518 -289.765486)
		(end 62.310518 -288.846768)
		(width 0.14478)
		(layer "In4.Cu")
		(net "M_D_CPU1_SB_DQ<10>")
	)
	(segment
		(start 60.212732 -291.260276)
		(end 60.815728 -291.260276)
		(width 0.14478)
		(layer "In4.Cu")
		(net "M_D_CPU1_SB_DQ<10>")
	)
	(segment
		(start 34.48812 -292.110414)
		(end 42.032682 -292.110414)
		(width 0.14478)
		(layer "In4.Cu")
		(net "M_D_CPU1_SB_DQ<10>")
	)
	(segment
		(start 76.345796 -279.298654)
		(end 76.505562 -279.298654)
		(width 0.0889)
		(layer "In4.Cu")
		(net "M_D_CPU1_SB_DQ<10>")
	)
	(segment
		(start 88.394032 -279.433782)
		(end 88.402414 -279.428956)
		(width 0.0889)
		(layer "In4.Cu")
		(net "M_D_CPU1_SB_DQ<10>")
	)
	(segment
		(start 59.363356 -291.260276)
		(end 59.643772 -290.97986)
		(width 0.14478)
		(layer "In4.Cu")
		(net "M_D_CPU1_SB_DQ<10>")
	)
	(segment
		(start 91.24696 -279.490932)
		(end 91.401138 -279.756362)
		(width 0.0889)
		(layer "In4.Cu")
		(net "M_D_CPU1_SB_DQ<10>")
	)
	(segment
		(start 62.310518 -288.846768)
		(end 71.858632 -279.298654)
		(width 0.14478)
		(layer "In4.Cu")
		(net "M_D_CPU1_SB_DQ<10>")
	)
	(segment
		(start 78.051914 -279.084786)
		(end 78.312264 -279.345136)
		(width 0.0889)
		(layer "In4.Cu")
		(net "M_D_CPU1_SB_DQ<10>")
	)
	(segment
		(start 34.162492 -291.507164)
		(end 34.325306 -291.669978)
		(width 0.14478)
		(layer "In4.Cu")
		(net "M_D_CPU1_SB_DQ<10>")
	)
	(segment
		(start 57.803288 -291.260276)
		(end 59.363356 -291.260276)
		(width 0.14478)
		(layer "In4.Cu")
		(net "M_D_CPU1_SB_DQ<10>")
	)
	(segment
		(start 45.335952 -291.260276)
		(end 46.18609 -292.110414)
		(width 0.14478)
		(layer "In4.Cu")
		(net "M_D_CPU1_SB_DQ<10>")
	)
	(segment
		(start 86.879684 -279.428956)
		(end 86.888066 -279.433782)
		(width 0.0889)
		(layer "In4.Cu")
		(net "M_D_CPU1_SB_DQ<10>")
	)
	(segment
		(start 76.505562 -279.298654)
		(end 76.71943 -279.084786)
		(width 0.0889)
		(layer "In4.Cu")
		(net "M_D_CPU1_SB_DQ<10>")
	)
	(segment
		(start 33.606232 -292.110414)
		(end 33.769046 -291.9476)
		(width 0.14478)
		(layer "In4.Cu")
		(net "M_D_CPU1_SB_DQ<10>")
	)
	(segment
		(start 90.639646 -279.428956)
		(end 90.648028 -279.433782)
		(width 0.0889)
		(layer "In4.Cu")
		(net "M_D_CPU1_SB_DQ<10>")
	)
	(segment
		(start 34.325306 -291.669978)
		(end 34.325306 -291.9476)
		(width 0.14478)
		(layer "In4.Cu")
		(net "M_D_CPU1_SB_DQ<10>")
	)
	(segment
		(start 33.769046 -291.9476)
		(end 33.769046 -291.669978)
		(width 0.14478)
		(layer "In4.Cu")
		(net "M_D_CPU1_SB_DQ<10>")
	)
	(segment
		(start 82.753962 -279.433782)
		(end 82.762344 -279.428956)
		(width 0.0889)
		(layer "In4.Cu")
		(net "M_D_CPU1_SB_DQ<10>")
	)
	(segment
		(start 46.18609 -292.110414)
		(end 49.43475 -292.110414)
		(width 0.14478)
		(layer "In4.Cu")
		(net "M_D_CPU1_SB_DQ<10>")
	)
	(segment
		(start 32.695896 -291.685218)
		(end 33.121092 -292.110414)
		(width 0.14478)
		(layer "In4.Cu")
		(net "M_D_CPU1_SB_DQ<10>")
	)
	(segment
		(start 87.453978 -279.433782)
		(end 87.46236 -279.428956)
		(width 0.0889)
		(layer "In4.Cu")
		(net "M_D_CPU1_SB_DQ<10>")
	)
	(segment
		(start 34.325306 -291.9476)
		(end 34.48812 -292.110414)
		(width 0.14478)
		(layer "In4.Cu")
		(net "M_D_CPU1_SB_DQ<10>")
	)
	(segment
		(start 80.299814 -279.428956)
		(end 80.308196 -279.433782)
		(width 0.0889)
		(layer "In4.Cu")
		(net "M_D_CPU1_SB_DQ<10>")
	)
	(segment
		(start 85.93963 -279.428956)
		(end 85.948012 -279.433782)
		(width 0.0889)
		(layer "In4.Cu")
		(net "M_D_CPU1_SB_DQ<10>")
	)
	(segment
		(start 33.93186 -291.507164)
		(end 34.162492 -291.507164)
		(width 0.14478)
		(layer "In4.Cu")
		(net "M_D_CPU1_SB_DQ<10>")
	)
	(segment
		(start 59.932316 -290.97986)
		(end 60.212732 -291.260276)
		(width 0.14478)
		(layer "In4.Cu")
		(net "M_D_CPU1_SB_DQ<10>")
	)
	(segment
		(start 76.71943 -279.084786)
		(end 78.051914 -279.084786)
		(width 0.0889)
		(layer "In4.Cu")
		(net "M_D_CPU1_SB_DQ<10>")
	)
	(segment
		(start 71.858632 -279.298654)
		(end 76.345796 -279.298654)
		(width 0.14478)
		(layer "In4.Cu")
		(net "M_D_CPU1_SB_DQ<10>")
	)
	(segment
		(start 91.150694 -279.465532)
		(end 91.24696 -279.490932)
		(width 0.0889)
		(layer "In4.Cu")
		(net "M_D_CPU1_SB_DQ<10>")
	)
	(segment
		(start 49.43475 -292.110414)
		(end 50.284888 -291.260276)
		(width 0.14478)
		(layer "In4.Cu")
		(net "M_D_CPU1_SB_DQ<10>")
	)
	(segment
		(start 54.408578 -292.110414)
		(end 56.95315 -292.110414)
		(width 0.14478)
		(layer "In4.Cu")
		(net "M_D_CPU1_SB_DQ<10>")
	)
	(segment
		(start 33.121092 -292.110414)
		(end 33.606232 -292.110414)
		(width 0.14478)
		(layer "In4.Cu")
		(net "M_D_CPU1_SB_DQ<10>")
	)
	(segment
		(start 42.032682 -292.110414)
		(end 42.88282 -291.260276)
		(width 0.14478)
		(layer "In4.Cu")
		(net "M_D_CPU1_SB_DQ<10>")
	)
	(segment
		(start 78.993492 -279.434036)
		(end 79.009748 -279.424638)
		(width 0.0889)
		(layer "In4.Cu")
		(net "M_D_CPU1_SB_DQ<10>")
	)
	(segment
		(start 50.284888 -291.260276)
		(end 53.55844 -291.260276)
		(width 0.14478)
		(layer "In4.Cu")
		(net "M_D_CPU1_SB_DQ<10>")
	)
	(segment
		(start 78.977744 -279.44318)
		(end 78.993492 -279.434036)
		(width 0.0889)
		(layer "In4.Cu")
		(net "M_D_CPU1_SB_DQ<10>")
	)
	(arc
		(start 88.768174 -279.433782)
		(mid 89.05113 -279.509959)
		(end 89.334086 -279.433782)
		(width 0.0889)
		(layer "In4.Cu")
		(net "M_D_CPU1_SB_DQ<10>")
	)
	(arc
		(start 80.308196 -279.433782)
		(mid 80.591152 -279.509959)
		(end 80.874108 -279.433782)
		(width 0.0889)
		(layer "In4.Cu")
		(net "M_D_CPU1_SB_DQ<10>")
	)
	(arc
		(start 84.63407 -279.433782)
		(mid 84.821014 -279.383527)
		(end 85.007958 -279.433782)
		(width 0.0889)
		(layer "In4.Cu")
		(net "M_D_CPU1_SB_DQ<10>")
	)
	(arc
		(start 81.247996 -279.433782)
		(mid 81.530952 -279.509959)
		(end 81.813908 -279.433782)
		(width 0.0889)
		(layer "In4.Cu")
		(net "M_D_CPU1_SB_DQ<10>")
	)
	(arc
		(start 82.18805 -279.433782)
		(mid 82.471006 -279.509959)
		(end 82.753962 -279.433782)
		(width 0.0889)
		(layer "In4.Cu")
		(net "M_D_CPU1_SB_DQ<10>")
	)
	(arc
		(start 79.009748 -279.424638)
		(mid 79.18973 -279.383538)
		(end 79.36738 -279.433782)
		(width 0.0889)
		(layer "In4.Cu")
		(net "M_D_CPU1_SB_DQ<10>")
	)
	(arc
		(start 78.312264 -279.345136)
		(mid 78.367049 -279.393196)
		(end 78.42758 -279.433782)
		(width 0.0889)
		(layer "In4.Cu")
		(net "M_D_CPU1_SB_DQ<10>")
	)
	(arc
		(start 88.402414 -279.428956)
		(mid 88.585922 -279.383462)
		(end 88.768174 -279.433782)
		(width 0.0889)
		(layer "In4.Cu")
		(net "M_D_CPU1_SB_DQ<10>")
	)
	(arc
		(start 90.273886 -279.433782)
		(mid 90.456137 -279.383432)
		(end 90.639646 -279.428956)
		(width 0.0889)
		(layer "In4.Cu")
		(net "M_D_CPU1_SB_DQ<10>")
	)
	(arc
		(start 87.46236 -279.428956)
		(mid 87.645868 -279.383462)
		(end 87.82812 -279.433782)
		(width 0.0889)
		(layer "In4.Cu")
		(net "M_D_CPU1_SB_DQ<10>")
	)
	(arc
		(start 83.702398 -279.428956)
		(mid 83.885906 -279.383462)
		(end 84.068158 -279.433782)
		(width 0.0889)
		(layer "In4.Cu")
		(net "M_D_CPU1_SB_DQ<10>")
	)
	(arc
		(start 86.513924 -279.433782)
		(mid 86.696175 -279.383432)
		(end 86.879684 -279.428956)
		(width 0.0889)
		(layer "In4.Cu")
		(net "M_D_CPU1_SB_DQ<10>")
	)
	(arc
		(start 80.874108 -279.433782)
		(mid 81.061052 -279.383527)
		(end 81.247996 -279.433782)
		(width 0.0889)
		(layer "In4.Cu")
		(net "M_D_CPU1_SB_DQ<10>")
	)
	(arc
		(start 85.948012 -279.433782)
		(mid 86.230968 -279.509959)
		(end 86.513924 -279.433782)
		(width 0.0889)
		(layer "In4.Cu")
		(net "M_D_CPU1_SB_DQ<10>")
	)
	(arc
		(start 90.648028 -279.433782)
		(mid 90.895624 -279.50896)
		(end 91.150694 -279.465532)
		(width 0.0889)
		(layer "In4.Cu")
		(net "M_D_CPU1_SB_DQ<10>")
	)
	(arc
		(start 79.933546 -279.433782)
		(mid 80.116051 -279.383305)
		(end 80.299814 -279.428956)
		(width 0.0889)
		(layer "In4.Cu")
		(net "M_D_CPU1_SB_DQ<10>")
	)
	(arc
		(start 82.762344 -279.428956)
		(mid 82.945852 -279.383462)
		(end 83.128104 -279.433782)
		(width 0.0889)
		(layer "In4.Cu")
		(net "M_D_CPU1_SB_DQ<10>")
	)
	(arc
		(start 83.128104 -279.433782)
		(mid 83.41106 -279.509959)
		(end 83.694016 -279.433782)
		(width 0.0889)
		(layer "In4.Cu")
		(net "M_D_CPU1_SB_DQ<10>")
	)
	(arc
		(start 89.334086 -279.433782)
		(mid 89.52103 -279.383527)
		(end 89.707974 -279.433782)
		(width 0.0889)
		(layer "In4.Cu")
		(net "M_D_CPU1_SB_DQ<10>")
	)
	(arc
		(start 81.813908 -279.433782)
		(mid 81.996159 -279.383432)
		(end 82.179668 -279.428956)
		(width 0.0889)
		(layer "In4.Cu")
		(net "M_D_CPU1_SB_DQ<10>")
	)
	(arc
		(start 84.068158 -279.433782)
		(mid 84.351114 -279.509959)
		(end 84.63407 -279.433782)
		(width 0.0889)
		(layer "In4.Cu")
		(net "M_D_CPU1_SB_DQ<10>")
	)
	(arc
		(start 78.42758 -279.433782)
		(mid 78.701435 -279.510132)
		(end 78.977744 -279.44318)
		(width 0.0889)
		(layer "In4.Cu")
		(net "M_D_CPU1_SB_DQ<10>")
	)
	(arc
		(start 79.377794 -279.439878)
		(mid 79.65648 -279.510098)
		(end 79.933546 -279.433782)
		(width 0.0889)
		(layer "In4.Cu")
		(net "M_D_CPU1_SB_DQ<10>")
	)
	(arc
		(start 85.007958 -279.433782)
		(mid 85.290914 -279.509959)
		(end 85.57387 -279.433782)
		(width 0.0889)
		(layer "In4.Cu")
		(net "M_D_CPU1_SB_DQ<10>")
	)
	(arc
		(start 86.888066 -279.433782)
		(mid 87.171022 -279.509959)
		(end 87.453978 -279.433782)
		(width 0.0889)
		(layer "In4.Cu")
		(net "M_D_CPU1_SB_DQ<10>")
	)
	(arc
		(start 87.82812 -279.433782)
		(mid 88.111076 -279.509959)
		(end 88.394032 -279.433782)
		(width 0.0889)
		(layer "In4.Cu")
		(net "M_D_CPU1_SB_DQ<10>")
	)
	(arc
		(start 89.707974 -279.433782)
		(mid 89.99093 -279.509959)
		(end 90.273886 -279.433782)
		(width 0.0889)
		(layer "In4.Cu")
		(net "M_D_CPU1_SB_DQ<10>")
	)
	(arc
		(start 85.57387 -279.433782)
		(mid 85.756121 -279.383432)
		(end 85.93963 -279.428956)
		(width 0.0889)
		(layer "In4.Cu")
		(net "M_D_CPU1_SB_DQ<10>")
	)
	(segment
		(start 91.397836 -273.820382)
		(end 90.930984 -274.08632)
		(width 0.10668)
		(layer "F.Cu")
		(net "M_D_CPU1_SB_DQ<0>")
	)
	(segment
		(start 59.133994 -281.221688)
		(end 59.295538 -281.060144)
		(width 0.14478)
		(layer "In4.Cu")
		(net "M_D_CPU1_SB_DQ<0>")
	)
	(segment
		(start 59.295538 -281.060144)
		(end 59.672474 -281.060144)
		(width 0.14478)
		(layer "In4.Cu")
		(net "M_D_CPU1_SB_DQ<0>")
	)
	(segment
		(start 62.733936 -277.998682)
		(end 63.065406 -277.998682)
		(width 0.14478)
		(layer "In4.Cu")
		(net "M_D_CPU1_SB_DQ<0>")
	)
	(segment
		(start 38.693344 -282.2702)
		(end 38.923976 -282.2702)
		(width 0.14478)
		(layer "In4.Cu")
		(net "M_D_CPU1_SB_DQ<0>")
	)
	(segment
		(start 91.085162 -274.35175)
		(end 90.930984 -274.08632)
		(width 0.0889)
		(layer "In4.Cu")
		(net "M_D_CPU1_SB_DQ<0>")
	)
	(segment
		(start 52.864512 -281.060144)
		(end 53.71465 -281.910282)
		(width 0.14478)
		(layer "In4.Cu")
		(net "M_D_CPU1_SB_DQ<0>")
	)
	(segment
		(start 38.367716 -281.616658)
		(end 38.53053 -281.779472)
		(width 0.14478)
		(layer "In4.Cu")
		(net "M_D_CPU1_SB_DQ<0>")
	)
	(segment
		(start 59.133994 -281.280362)
		(end 59.133994 -281.221688)
		(width 0.14478)
		(layer "In4.Cu")
		(net "M_D_CPU1_SB_DQ<0>")
	)
	(segment
		(start 54.705504 -281.748738)
		(end 54.867048 -281.910282)
		(width 0.14478)
		(layer "In4.Cu")
		(net "M_D_CPU1_SB_DQ<0>")
	)
	(segment
		(start 67.512184 -273.220434)
		(end 76.599796 -273.220434)
		(width 0.14478)
		(layer "In4.Cu")
		(net "M_D_CPU1_SB_DQ<0>")
	)
	(segment
		(start 48.223424 -281.910282)
		(end 48.600106 -282.286964)
		(width 0.14478)
		(layer "In4.Cu")
		(net "M_D_CPU1_SB_DQ<0>")
	)
	(segment
		(start 55.990744 -281.748738)
		(end 55.990744 -281.40279)
		(width 0.14478)
		(layer "In4.Cu")
		(net "M_D_CPU1_SB_DQ<0>")
	)
	(segment
		(start 64.850264 -275.882354)
		(end 65.0748 -275.657818)
		(width 0.14478)
		(layer "In4.Cu")
		(net "M_D_CPU1_SB_DQ<0>")
	)
	(segment
		(start 38.53053 -282.107386)
		(end 38.693344 -282.2702)
		(width 0.14478)
		(layer "In4.Cu")
		(net "M_D_CPU1_SB_DQ<0>")
	)
	(segment
		(start 39.283894 -281.910282)
		(end 42.301922 -281.910282)
		(width 0.14478)
		(layer "In4.Cu")
		(net "M_D_CPU1_SB_DQ<0>")
	)
	(segment
		(start 64.069976 -276.662642)
		(end 64.294512 -276.438106)
		(width 0.14478)
		(layer "In4.Cu")
		(net "M_D_CPU1_SB_DQ<0>")
	)
	(segment
		(start 63.289688 -277.671022)
		(end 63.289688 -277.44293)
		(width 0.14478)
		(layer "In4.Cu")
		(net "M_D_CPU1_SB_DQ<0>")
	)
	(segment
		(start 53.992526 -281.910282)
		(end 54.15407 -281.748738)
		(width 0.14478)
		(layer "In4.Cu")
		(net "M_D_CPU1_SB_DQ<0>")
	)
	(segment
		(start 54.15407 -281.748738)
		(end 54.15407 -281.38247)
		(width 0.14478)
		(layer "In4.Cu")
		(net "M_D_CPU1_SB_DQ<0>")
	)
	(segment
		(start 56.380634 -281.241246)
		(end 56.542178 -281.40279)
		(width 0.14478)
		(layer "In4.Cu")
		(net "M_D_CPU1_SB_DQ<0>")
	)
	(segment
		(start 76.599796 -273.220434)
		(end 76.817728 -273.438366)
		(width 0.0889)
		(layer "In4.Cu")
		(net "M_D_CPU1_SB_DQ<0>")
	)
	(segment
		(start 65.630552 -275.330158)
		(end 65.630552 -275.102066)
		(width 0.14478)
		(layer "In4.Cu")
		(net "M_D_CPU1_SB_DQ<0>")
	)
	(segment
		(start 67.191128 -273.769582)
		(end 67.191128 -273.54149)
		(width 0.14478)
		(layer "In4.Cu")
		(net "M_D_CPU1_SB_DQ<0>")
	)
	(segment
		(start 48.600106 -282.286964)
		(end 49.103788 -282.286964)
		(width 0.14478)
		(layer "In4.Cu")
		(net "M_D_CPU1_SB_DQ<0>")
	)
	(segment
		(start 64.625982 -276.438106)
		(end 64.850518 -276.21357)
		(width 0.14478)
		(layer "In4.Cu")
		(net "M_D_CPU1_SB_DQ<0>")
	)
	(segment
		(start 63.514224 -277.218394)
		(end 63.845694 -277.218394)
		(width 0.14478)
		(layer "In4.Cu")
		(net "M_D_CPU1_SB_DQ<0>")
	)
	(segment
		(start 66.635376 -274.097242)
		(end 66.966846 -274.097242)
		(width 0.14478)
		(layer "In4.Cu")
		(net "M_D_CPU1_SB_DQ<0>")
	)
	(segment
		(start 55.990744 -281.40279)
		(end 56.152288 -281.241246)
		(width 0.14478)
		(layer "In4.Cu")
		(net "M_D_CPU1_SB_DQ<0>")
	)
	(segment
		(start 67.191128 -273.54149)
		(end 67.512184 -273.220434)
		(width 0.14478)
		(layer "In4.Cu")
		(net "M_D_CPU1_SB_DQ<0>")
	)
	(segment
		(start 58.58256 -281.280362)
		(end 58.744104 -281.441906)
		(width 0.14478)
		(layer "In4.Cu")
		(net "M_D_CPU1_SB_DQ<0>")
	)
	(segment
		(start 56.703722 -281.910282)
		(end 56.863742 -281.910282)
		(width 0.14478)
		(layer "In4.Cu")
		(net "M_D_CPU1_SB_DQ<0>")
	)
	(segment
		(start 59.672474 -281.060144)
		(end 60.393072 -280.339546)
		(width 0.14478)
		(layer "In4.Cu")
		(net "M_D_CPU1_SB_DQ<0>")
	)
	(segment
		(start 58.58256 -281.221688)
		(end 58.58256 -281.280362)
		(width 0.14478)
		(layer "In4.Cu")
		(net "M_D_CPU1_SB_DQ<0>")
	)
	(segment
		(start 36.795964 -281.48534)
		(end 37.580824 -282.2702)
		(width 0.14478)
		(layer "In4.Cu")
		(net "M_D_CPU1_SB_DQ<0>")
	)
	(segment
		(start 63.289942 -277.774146)
		(end 63.289688 -277.671022)
		(width 0.14478)
		(layer "In4.Cu")
		(net "M_D_CPU1_SB_DQ<0>")
	)
	(segment
		(start 51.38801 -281.060144)
		(end 52.864512 -281.060144)
		(width 0.14478)
		(layer "In4.Cu")
		(net "M_D_CPU1_SB_DQ<0>")
	)
	(segment
		(start 38.53053 -281.779472)
		(end 38.53053 -282.107386)
		(width 0.14478)
		(layer "In4.Cu")
		(net "M_D_CPU1_SB_DQ<0>")
	)
	(segment
		(start 60.948824 -279.783794)
		(end 61.17336 -279.559258)
		(width 0.14478)
		(layer "In4.Cu")
		(net "M_D_CPU1_SB_DQ<0>")
	)
	(segment
		(start 58.744104 -281.441906)
		(end 58.97245 -281.441906)
		(width 0.14478)
		(layer "In4.Cu")
		(net "M_D_CPU1_SB_DQ<0>")
	)
	(segment
		(start 63.065406 -277.998682)
		(end 63.289942 -277.774146)
		(width 0.14478)
		(layer "In4.Cu")
		(net "M_D_CPU1_SB_DQ<0>")
	)
	(segment
		(start 46.070012 -281.910282)
		(end 46.424596 -281.910282)
		(width 0.14478)
		(layer "In4.Cu")
		(net "M_D_CPU1_SB_DQ<0>")
	)
	(segment
		(start 47.282354 -281.910282)
		(end 48.223424 -281.910282)
		(width 0.14478)
		(layer "In4.Cu")
		(net "M_D_CPU1_SB_DQ<0>")
	)
	(segment
		(start 46.424596 -281.910282)
		(end 46.73092 -282.216606)
		(width 0.14478)
		(layer "In4.Cu")
		(net "M_D_CPU1_SB_DQ<0>")
	)
	(segment
		(start 64.069976 -276.890734)
		(end 64.069976 -276.662642)
		(width 0.14478)
		(layer "In4.Cu")
		(net "M_D_CPU1_SB_DQ<0>")
	)
	(segment
		(start 38.923976 -282.2702)
		(end 39.283894 -281.910282)
		(width 0.14478)
		(layer "In4.Cu")
		(net "M_D_CPU1_SB_DQ<0>")
	)
	(segment
		(start 56.542178 -281.748738)
		(end 56.703722 -281.910282)
		(width 0.14478)
		(layer "In4.Cu")
		(net "M_D_CPU1_SB_DQ<0>")
	)
	(segment
		(start 66.966846 -274.097242)
		(end 67.191382 -273.872706)
		(width 0.14478)
		(layer "In4.Cu")
		(net "M_D_CPU1_SB_DQ<0>")
	)
	(segment
		(start 65.630552 -275.102066)
		(end 65.855088 -274.87753)
		(width 0.14478)
		(layer "In4.Cu")
		(net "M_D_CPU1_SB_DQ<0>")
	)
	(segment
		(start 46.069758 -281.910536)
		(end 46.070012 -281.910282)
		(width 0.14478)
		(layer "In4.Cu")
		(net "M_D_CPU1_SB_DQ<0>")
	)
	(segment
		(start 54.15407 -281.38247)
		(end 54.315614 -281.220926)
		(width 0.14478)
		(layer "In4.Cu")
		(net "M_D_CPU1_SB_DQ<0>")
	)
	(segment
		(start 37.97427 -281.779472)
		(end 38.137084 -281.616658)
		(width 0.14478)
		(layer "In4.Cu")
		(net "M_D_CPU1_SB_DQ<0>")
	)
	(segment
		(start 90.74404 -274.4089)
		(end 90.752422 -274.413726)
		(width 0.0889)
		(layer "In4.Cu")
		(net "M_D_CPU1_SB_DQ<0>")
	)
	(segment
		(start 50.330608 -281.060144)
		(end 50.566574 -281.060144)
		(width 0.14478)
		(layer "In4.Cu")
		(net "M_D_CPU1_SB_DQ<0>")
	)
	(segment
		(start 61.50483 -279.559258)
		(end 61.729366 -279.334722)
		(width 0.14478)
		(layer "In4.Cu")
		(net "M_D_CPU1_SB_DQ<0>")
	)
	(segment
		(start 46.97603 -282.216606)
		(end 47.282354 -281.910282)
		(width 0.14478)
		(layer "In4.Cu")
		(net "M_D_CPU1_SB_DQ<0>")
	)
	(segment
		(start 53.71465 -281.910282)
		(end 53.992526 -281.910282)
		(width 0.14478)
		(layer "In4.Cu")
		(net "M_D_CPU1_SB_DQ<0>")
	)
	(segment
		(start 50.836576 -281.330146)
		(end 51.118008 -281.330146)
		(width 0.14478)
		(layer "In4.Cu")
		(net "M_D_CPU1_SB_DQ<0>")
	)
	(segment
		(start 76.817728 -273.438366)
		(end 77.535024 -273.438366)
		(width 0.0889)
		(layer "In4.Cu")
		(net "M_D_CPU1_SB_DQ<0>")
	)
	(segment
		(start 81.344008 -274.4089)
		(end 81.35239 -274.413726)
		(width 0.0889)
		(layer "In4.Cu")
		(net "M_D_CPU1_SB_DQ<0>")
	)
	(segment
		(start 78.897734 -274.408646)
		(end 78.903322 -274.405344)
		(width 0.0889)
		(layer "In4.Cu")
		(net "M_D_CPU1_SB_DQ<0>")
	)
	(segment
		(start 61.729366 -279.334722)
		(end 61.729112 -279.231598)
		(width 0.14478)
		(layer "In4.Cu")
		(net "M_D_CPU1_SB_DQ<0>")
	)
	(segment
		(start 54.315614 -281.220926)
		(end 54.54396 -281.220926)
		(width 0.14478)
		(layer "In4.Cu")
		(net "M_D_CPU1_SB_DQ<0>")
	)
	(segment
		(start 66.41084 -274.54987)
		(end 66.41084 -274.321778)
		(width 0.14478)
		(layer "In4.Cu")
		(net "M_D_CPU1_SB_DQ<0>")
	)
	(segment
		(start 61.729112 -279.231598)
		(end 61.729112 -279.003506)
		(width 0.14478)
		(layer "In4.Cu")
		(net "M_D_CPU1_SB_DQ<0>")
	)
	(segment
		(start 54.705504 -281.38247)
		(end 54.705504 -281.748738)
		(width 0.14478)
		(layer "In4.Cu")
		(net "M_D_CPU1_SB_DQ<0>")
	)
	(segment
		(start 64.07023 -276.993858)
		(end 64.069976 -276.890734)
		(width 0.14478)
		(layer "In4.Cu")
		(net "M_D_CPU1_SB_DQ<0>")
	)
	(segment
		(start 66.411094 -274.652994)
		(end 66.41084 -274.54987)
		(width 0.14478)
		(layer "In4.Cu")
		(net "M_D_CPU1_SB_DQ<0>")
	)
	(segment
		(start 79.463138 -274.4089)
		(end 79.47152 -274.413726)
		(width 0.0889)
		(layer "In4.Cu")
		(net "M_D_CPU1_SB_DQ<0>")
	)
	(segment
		(start 60.393072 -280.339546)
		(end 60.724542 -280.339546)
		(width 0.14478)
		(layer "In4.Cu")
		(net "M_D_CPU1_SB_DQ<0>")
	)
	(segment
		(start 61.729112 -279.003506)
		(end 61.953648 -278.77897)
		(width 0.14478)
		(layer "In4.Cu")
		(net "M_D_CPU1_SB_DQ<0>")
	)
	(segment
		(start 62.509654 -278.554434)
		(end 62.5094 -278.45131)
		(width 0.14478)
		(layer "In4.Cu")
		(net "M_D_CPU1_SB_DQ<0>")
	)
	(segment
		(start 62.5094 -278.223218)
		(end 62.733936 -277.998682)
		(width 0.14478)
		(layer "In4.Cu")
		(net "M_D_CPU1_SB_DQ<0>")
	)
	(segment
		(start 60.724542 -280.339546)
		(end 60.949078 -280.11501)
		(width 0.14478)
		(layer "In4.Cu")
		(net "M_D_CPU1_SB_DQ<0>")
	)
	(segment
		(start 88.289638 -274.413726)
		(end 88.29802 -274.4089)
		(width 0.0889)
		(layer "In4.Cu")
		(net "M_D_CPU1_SB_DQ<0>")
	)
	(segment
		(start 80.39354 -274.402804)
		(end 80.403954 -274.4089)
		(width 0.0889)
		(layer "In4.Cu")
		(net "M_D_CPU1_SB_DQ<0>")
	)
	(segment
		(start 86.044024 -274.4089)
		(end 86.052406 -274.413726)
		(width 0.0889)
		(layer "In4.Cu")
		(net "M_D_CPU1_SB_DQ<0>")
	)
	(segment
		(start 65.0748 -275.657818)
		(end 65.40627 -275.657818)
		(width 0.14478)
		(layer "In4.Cu")
		(net "M_D_CPU1_SB_DQ<0>")
	)
	(segment
		(start 37.97427 -282.107386)
		(end 37.97427 -281.779472)
		(width 0.14478)
		(layer "In4.Cu")
		(net "M_D_CPU1_SB_DQ<0>")
	)
	(segment
		(start 46.73092 -282.216606)
		(end 46.97603 -282.216606)
		(width 0.14478)
		(layer "In4.Cu")
		(net "M_D_CPU1_SB_DQ<0>")
	)
	(segment
		(start 60.948824 -280.011886)
		(end 60.948824 -279.783794)
		(width 0.14478)
		(layer "In4.Cu")
		(net "M_D_CPU1_SB_DQ<0>")
	)
	(segment
		(start 37.580824 -282.2702)
		(end 37.811456 -282.2702)
		(width 0.14478)
		(layer "In4.Cu")
		(net "M_D_CPU1_SB_DQ<0>")
	)
	(segment
		(start 85.10397 -274.4089)
		(end 85.112352 -274.413726)
		(width 0.0889)
		(layer "In4.Cu")
		(net "M_D_CPU1_SB_DQ<0>")
	)
	(segment
		(start 64.294512 -276.438106)
		(end 64.625982 -276.438106)
		(width 0.14478)
		(layer "In4.Cu")
		(net "M_D_CPU1_SB_DQ<0>")
	)
	(segment
		(start 58.97245 -281.441906)
		(end 59.133994 -281.280362)
		(width 0.14478)
		(layer "In4.Cu")
		(net "M_D_CPU1_SB_DQ<0>")
	)
	(segment
		(start 63.845694 -277.218394)
		(end 64.07023 -276.993858)
		(width 0.14478)
		(layer "In4.Cu")
		(net "M_D_CPU1_SB_DQ<0>")
	)
	(segment
		(start 56.542178 -281.40279)
		(end 56.542178 -281.748738)
		(width 0.14478)
		(layer "In4.Cu")
		(net "M_D_CPU1_SB_DQ<0>")
	)
	(segment
		(start 65.855088 -274.87753)
		(end 66.186558 -274.87753)
		(width 0.14478)
		(layer "In4.Cu")
		(net "M_D_CPU1_SB_DQ<0>")
	)
	(segment
		(start 38.137084 -281.616658)
		(end 38.367716 -281.616658)
		(width 0.14478)
		(layer "In4.Cu")
		(net "M_D_CPU1_SB_DQ<0>")
	)
	(segment
		(start 42.301922 -281.910282)
		(end 43.15206 -281.060144)
		(width 0.14478)
		(layer "In4.Cu")
		(net "M_D_CPU1_SB_DQ<0>")
	)
	(segment
		(start 50.566574 -281.060144)
		(end 50.836576 -281.330146)
		(width 0.14478)
		(layer "In4.Cu")
		(net "M_D_CPU1_SB_DQ<0>")
	)
	(segment
		(start 37.811456 -282.2702)
		(end 37.97427 -282.107386)
		(width 0.14478)
		(layer "In4.Cu")
		(net "M_D_CPU1_SB_DQ<0>")
	)
	(segment
		(start 67.191382 -273.872706)
		(end 67.191128 -273.769582)
		(width 0.14478)
		(layer "In4.Cu")
		(net "M_D_CPU1_SB_DQ<0>")
	)
	(segment
		(start 54.867048 -281.910282)
		(end 55.8292 -281.910282)
		(width 0.14478)
		(layer "In4.Cu")
		(net "M_D_CPU1_SB_DQ<0>")
	)
	(segment
		(start 91.06281 -274.435062)
		(end 91.085162 -274.35175)
		(width 0.0889)
		(layer "In4.Cu")
		(net "M_D_CPU1_SB_DQ<0>")
	)
	(segment
		(start 80.769714 -274.413726)
		(end 80.778096 -274.4089)
		(width 0.0889)
		(layer "In4.Cu")
		(net "M_D_CPU1_SB_DQ<0>")
	)
	(segment
		(start 89.229692 -274.413726)
		(end 89.238074 -274.4089)
		(width 0.0889)
		(layer "In4.Cu")
		(net "M_D_CPU1_SB_DQ<0>")
	)
	(segment
		(start 66.41084 -274.321778)
		(end 66.635376 -274.097242)
		(width 0.14478)
		(layer "In4.Cu")
		(net "M_D_CPU1_SB_DQ<0>")
	)
	(segment
		(start 78.523338 -274.4089)
		(end 78.523592 -274.4089)
		(width 0.0889)
		(layer "In4.Cu")
		(net "M_D_CPU1_SB_DQ<0>")
	)
	(segment
		(start 63.289688 -277.44293)
		(end 63.514224 -277.218394)
		(width 0.14478)
		(layer "In4.Cu")
		(net "M_D_CPU1_SB_DQ<0>")
	)
	(segment
		(start 61.953648 -278.77897)
		(end 62.285118 -278.77897)
		(width 0.14478)
		(layer "In4.Cu")
		(net "M_D_CPU1_SB_DQ<0>")
	)
	(segment
		(start 65.40627 -275.657818)
		(end 65.630806 -275.433282)
		(width 0.14478)
		(layer "In4.Cu")
		(net "M_D_CPU1_SB_DQ<0>")
	)
	(segment
		(start 45.219112 -281.060144)
		(end 46.069758 -281.910536)
		(width 0.14478)
		(layer "In4.Cu")
		(net "M_D_CPU1_SB_DQ<0>")
	)
	(segment
		(start 58.421016 -281.060144)
		(end 58.58256 -281.221688)
		(width 0.14478)
		(layer "In4.Cu")
		(net "M_D_CPU1_SB_DQ<0>")
	)
	(segment
		(start 77.535024 -273.438366)
		(end 78.446884 -274.350226)
		(width 0.0889)
		(layer "In4.Cu")
		(net "M_D_CPU1_SB_DQ<0>")
	)
	(segment
		(start 60.949078 -280.11501)
		(end 60.948824 -280.011886)
		(width 0.14478)
		(layer "In4.Cu")
		(net "M_D_CPU1_SB_DQ<0>")
	)
	(segment
		(start 56.152288 -281.241246)
		(end 56.380634 -281.241246)
		(width 0.14478)
		(layer "In4.Cu")
		(net "M_D_CPU1_SB_DQ<0>")
	)
	(segment
		(start 56.863742 -281.910282)
		(end 57.71388 -281.060144)
		(width 0.14478)
		(layer "In4.Cu")
		(net "M_D_CPU1_SB_DQ<0>")
	)
	(segment
		(start 57.71388 -281.060144)
		(end 58.421016 -281.060144)
		(width 0.14478)
		(layer "In4.Cu")
		(net "M_D_CPU1_SB_DQ<0>")
	)
	(segment
		(start 64.850264 -276.110446)
		(end 64.850264 -275.882354)
		(width 0.14478)
		(layer "In4.Cu")
		(net "M_D_CPU1_SB_DQ<0>")
	)
	(segment
		(start 62.5094 -278.45131)
		(end 62.5094 -278.223218)
		(width 0.14478)
		(layer "In4.Cu")
		(net "M_D_CPU1_SB_DQ<0>")
	)
	(segment
		(start 43.15206 -281.060144)
		(end 45.219112 -281.060144)
		(width 0.14478)
		(layer "In4.Cu")
		(net "M_D_CPU1_SB_DQ<0>")
	)
	(segment
		(start 89.803986 -274.4089)
		(end 89.812368 -274.413726)
		(width 0.0889)
		(layer "In4.Cu")
		(net "M_D_CPU1_SB_DQ<0>")
	)
	(segment
		(start 61.17336 -279.559258)
		(end 61.50483 -279.559258)
		(width 0.14478)
		(layer "In4.Cu")
		(net "M_D_CPU1_SB_DQ<0>")
	)
	(segment
		(start 54.54396 -281.220926)
		(end 54.705504 -281.38247)
		(width 0.14478)
		(layer "In4.Cu")
		(net "M_D_CPU1_SB_DQ<0>")
	)
	(segment
		(start 83.589622 -274.413726)
		(end 83.598004 -274.4089)
		(width 0.0889)
		(layer "In4.Cu")
		(net "M_D_CPU1_SB_DQ<0>")
	)
	(segment
		(start 84.529676 -274.413726)
		(end 84.538058 -274.4089)
		(width 0.0889)
		(layer "In4.Cu")
		(net "M_D_CPU1_SB_DQ<0>")
	)
	(segment
		(start 55.8292 -281.910282)
		(end 55.990744 -281.748738)
		(width 0.14478)
		(layer "In4.Cu")
		(net "M_D_CPU1_SB_DQ<0>")
	)
	(segment
		(start 65.630806 -275.433282)
		(end 65.630552 -275.330158)
		(width 0.14478)
		(layer "In4.Cu")
		(net "M_D_CPU1_SB_DQ<0>")
	)
	(segment
		(start 62.285118 -278.77897)
		(end 62.509654 -278.554434)
		(width 0.14478)
		(layer "In4.Cu")
		(net "M_D_CPU1_SB_DQ<0>")
	)
	(segment
		(start 78.879446 -274.41906)
		(end 78.897734 -274.408646)
		(width 0.0889)
		(layer "In4.Cu")
		(net "M_D_CPU1_SB_DQ<0>")
	)
	(segment
		(start 66.186558 -274.87753)
		(end 66.411094 -274.652994)
		(width 0.14478)
		(layer "In4.Cu")
		(net "M_D_CPU1_SB_DQ<0>")
	)
	(segment
		(start 51.118008 -281.330146)
		(end 51.38801 -281.060144)
		(width 0.14478)
		(layer "In4.Cu")
		(net "M_D_CPU1_SB_DQ<0>")
	)
	(segment
		(start 64.850518 -276.21357)
		(end 64.850264 -276.110446)
		(width 0.14478)
		(layer "In4.Cu")
		(net "M_D_CPU1_SB_DQ<0>")
	)
	(segment
		(start 49.103788 -282.286964)
		(end 50.330608 -281.060144)
		(width 0.14478)
		(layer "In4.Cu")
		(net "M_D_CPU1_SB_DQ<0>")
	)
	(arc
		(start 85.478112 -274.4089)
		(mid 85.761068 -274.332723)
		(end 86.044024 -274.4089)
		(width 0.0889)
		(layer "In4.Cu")
		(net "M_D_CPU1_SB_DQ<0>")
	)
	(arc
		(start 81.35239 -274.413726)
		(mid 81.535898 -274.45922)
		(end 81.71815 -274.4089)
		(width 0.0889)
		(layer "In4.Cu")
		(net "M_D_CPU1_SB_DQ<0>")
	)
	(arc
		(start 82.284062 -274.4089)
		(mid 82.471006 -274.459155)
		(end 82.65795 -274.4089)
		(width 0.0889)
		(layer "In4.Cu")
		(net "M_D_CPU1_SB_DQ<0>")
	)
	(arc
		(start 89.812368 -274.413726)
		(mid 89.995876 -274.45922)
		(end 90.178128 -274.4089)
		(width 0.0889)
		(layer "In4.Cu")
		(net "M_D_CPU1_SB_DQ<0>")
	)
	(arc
		(start 78.523592 -274.4089)
		(mid 78.70022 -274.459133)
		(end 78.879446 -274.41906)
		(width 0.0889)
		(layer "In4.Cu")
		(net "M_D_CPU1_SB_DQ<0>")
	)
	(arc
		(start 84.163916 -274.4089)
		(mid 84.346167 -274.45925)
		(end 84.529676 -274.413726)
		(width 0.0889)
		(layer "In4.Cu")
		(net "M_D_CPU1_SB_DQ<0>")
	)
	(arc
		(start 79.47152 -274.413726)
		(mid 79.655282 -274.459342)
		(end 79.837788 -274.4089)
		(width 0.0889)
		(layer "In4.Cu")
		(net "M_D_CPU1_SB_DQ<0>")
	)
	(arc
		(start 88.863932 -274.4089)
		(mid 89.046183 -274.45925)
		(end 89.229692 -274.413726)
		(width 0.0889)
		(layer "In4.Cu")
		(net "M_D_CPU1_SB_DQ<0>")
	)
	(arc
		(start 86.418166 -274.4089)
		(mid 86.701122 -274.332723)
		(end 86.984078 -274.4089)
		(width 0.0889)
		(layer "In4.Cu")
		(net "M_D_CPU1_SB_DQ<0>")
	)
	(arc
		(start 84.538058 -274.4089)
		(mid 84.821014 -274.332723)
		(end 85.10397 -274.4089)
		(width 0.0889)
		(layer "In4.Cu")
		(net "M_D_CPU1_SB_DQ<0>")
	)
	(arc
		(start 78.903322 -274.405344)
		(mid 79.183711 -274.332675)
		(end 79.463138 -274.4089)
		(width 0.0889)
		(layer "In4.Cu")
		(net "M_D_CPU1_SB_DQ<0>")
	)
	(arc
		(start 86.984078 -274.4089)
		(mid 87.171022 -274.459155)
		(end 87.357966 -274.4089)
		(width 0.0889)
		(layer "In4.Cu")
		(net "M_D_CPU1_SB_DQ<0>")
	)
	(arc
		(start 90.752422 -274.413726)
		(mid 90.905292 -274.458367)
		(end 91.06281 -274.435062)
		(width 0.0889)
		(layer "In4.Cu")
		(net "M_D_CPU1_SB_DQ<0>")
	)
	(arc
		(start 87.357966 -274.4089)
		(mid 87.640922 -274.332723)
		(end 87.923878 -274.4089)
		(width 0.0889)
		(layer "In4.Cu")
		(net "M_D_CPU1_SB_DQ<0>")
	)
	(arc
		(start 89.238074 -274.4089)
		(mid 89.52103 -274.332723)
		(end 89.803986 -274.4089)
		(width 0.0889)
		(layer "In4.Cu")
		(net "M_D_CPU1_SB_DQ<0>")
	)
	(arc
		(start 88.29802 -274.4089)
		(mid 88.580976 -274.332723)
		(end 88.863932 -274.4089)
		(width 0.0889)
		(layer "In4.Cu")
		(net "M_D_CPU1_SB_DQ<0>")
	)
	(arc
		(start 81.71815 -274.4089)
		(mid 82.001106 -274.332723)
		(end 82.284062 -274.4089)
		(width 0.0889)
		(layer "In4.Cu")
		(net "M_D_CPU1_SB_DQ<0>")
	)
	(arc
		(start 85.112352 -274.413726)
		(mid 85.29586 -274.45922)
		(end 85.478112 -274.4089)
		(width 0.0889)
		(layer "In4.Cu")
		(net "M_D_CPU1_SB_DQ<0>")
	)
	(arc
		(start 83.223862 -274.4089)
		(mid 83.406113 -274.45925)
		(end 83.589622 -274.413726)
		(width 0.0889)
		(layer "In4.Cu")
		(net "M_D_CPU1_SB_DQ<0>")
	)
	(arc
		(start 90.178128 -274.4089)
		(mid 90.461084 -274.332723)
		(end 90.74404 -274.4089)
		(width 0.0889)
		(layer "In4.Cu")
		(net "M_D_CPU1_SB_DQ<0>")
	)
	(arc
		(start 79.837788 -274.4089)
		(mid 80.114855 -274.332629)
		(end 80.39354 -274.402804)
		(width 0.0889)
		(layer "In4.Cu")
		(net "M_D_CPU1_SB_DQ<0>")
	)
	(arc
		(start 83.598004 -274.4089)
		(mid 83.88096 -274.332723)
		(end 84.163916 -274.4089)
		(width 0.0889)
		(layer "In4.Cu")
		(net "M_D_CPU1_SB_DQ<0>")
	)
	(arc
		(start 82.65795 -274.4089)
		(mid 82.940906 -274.332723)
		(end 83.223862 -274.4089)
		(width 0.0889)
		(layer "In4.Cu")
		(net "M_D_CPU1_SB_DQ<0>")
	)
	(arc
		(start 80.403954 -274.4089)
		(mid 80.586205 -274.45925)
		(end 80.769714 -274.413726)
		(width 0.0889)
		(layer "In4.Cu")
		(net "M_D_CPU1_SB_DQ<0>")
	)
	(arc
		(start 78.446884 -274.350226)
		(mid 78.483211 -274.382039)
		(end 78.523338 -274.4089)
		(width 0.0889)
		(layer "In4.Cu")
		(net "M_D_CPU1_SB_DQ<0>")
	)
	(arc
		(start 86.052406 -274.413726)
		(mid 86.235914 -274.45922)
		(end 86.418166 -274.4089)
		(width 0.0889)
		(layer "In4.Cu")
		(net "M_D_CPU1_SB_DQ<0>")
	)
	(arc
		(start 80.778096 -274.4089)
		(mid 81.061052 -274.332723)
		(end 81.344008 -274.4089)
		(width 0.0889)
		(layer "In4.Cu")
		(net "M_D_CPU1_SB_DQ<0>")
	)
	(arc
		(start 87.923878 -274.4089)
		(mid 88.106129 -274.45925)
		(end 88.289638 -274.413726)
		(width 0.0889)
		(layer "In4.Cu")
		(net "M_D_CPU1_SB_DQ<0>")
	)
	(segment
		(start 91.86799 -266.530328)
		(end 91.401138 -266.796266)
		(width 0.10668)
		(layer "F.Cu")
		(net "M_D_CPU1_SB_CS_N<1>")
	)
	(segment
		(start 60.24499 -268.31036)
		(end 62.571376 -265.983974)
		(width 0.14478)
		(layer "In4.Cu")
		(net "M_D_CPU1_SB_CS_N<1>")
	)
	(segment
		(start 77.883258 -265.983974)
		(end 78.322424 -266.42314)
		(width 0.0889)
		(layer "In4.Cu")
		(net "M_D_CPU1_SB_CS_N<1>")
	)
	(segment
		(start 91.150694 -266.505436)
		(end 91.24696 -266.530836)
		(width 0.0889)
		(layer "In4.Cu")
		(net "M_D_CPU1_SB_CS_N<1>")
	)
	(segment
		(start 91.24696 -266.530836)
		(end 91.401138 -266.796266)
		(width 0.0889)
		(layer "In4.Cu")
		(net "M_D_CPU1_SB_CS_N<1>")
	)
	(segment
		(start 90.639646 -266.46886)
		(end 90.648028 -266.473686)
		(width 0.0889)
		(layer "In4.Cu")
		(net "M_D_CPU1_SB_CS_N<1>")
	)
	(segment
		(start 82.179668 -266.46886)
		(end 82.18805 -266.473686)
		(width 0.0889)
		(layer "In4.Cu")
		(net "M_D_CPU1_SB_CS_N<1>")
	)
	(segment
		(start 82.753962 -266.473686)
		(end 82.762344 -266.46886)
		(width 0.0889)
		(layer "In4.Cu")
		(net "M_D_CPU1_SB_CS_N<1>")
	)
	(segment
		(start 78.322424 -266.42314)
		(end 80.120998 -266.42314)
		(width 0.0889)
		(layer "In4.Cu")
		(net "M_D_CPU1_SB_CS_N<1>")
	)
	(segment
		(start 32.695896 -268.735302)
		(end 33.120838 -268.31036)
		(width 0.14478)
		(layer "In4.Cu")
		(net "M_D_CPU1_SB_CS_N<1>")
	)
	(segment
		(start 88.394032 -266.473686)
		(end 88.402414 -266.46886)
		(width 0.0889)
		(layer "In4.Cu")
		(net "M_D_CPU1_SB_CS_N<1>")
	)
	(segment
		(start 87.453978 -266.473686)
		(end 87.46236 -266.46886)
		(width 0.0889)
		(layer "In4.Cu")
		(net "M_D_CPU1_SB_CS_N<1>")
	)
	(segment
		(start 85.93963 -266.46886)
		(end 85.948012 -266.473686)
		(width 0.0889)
		(layer "In4.Cu")
		(net "M_D_CPU1_SB_CS_N<1>")
	)
	(segment
		(start 75.957176 -265.983974)
		(end 77.883258 -265.983974)
		(width 0.0889)
		(layer "In4.Cu")
		(net "M_D_CPU1_SB_CS_N<1>")
	)
	(segment
		(start 62.571376 -265.983974)
		(end 75.957176 -265.983974)
		(width 0.14478)
		(layer "In4.Cu")
		(net "M_D_CPU1_SB_CS_N<1>")
	)
	(segment
		(start 33.120838 -268.31036)
		(end 60.24499 -268.31036)
		(width 0.14478)
		(layer "In4.Cu")
		(net "M_D_CPU1_SB_CS_N<1>")
	)
	(segment
		(start 83.694016 -266.473686)
		(end 83.702398 -266.46886)
		(width 0.0889)
		(layer "In4.Cu")
		(net "M_D_CPU1_SB_CS_N<1>")
	)
	(segment
		(start 86.879684 -266.46886)
		(end 86.888066 -266.473686)
		(width 0.0889)
		(layer "In4.Cu")
		(net "M_D_CPU1_SB_CS_N<1>")
	)
	(arc
		(start 81.813908 -266.473686)
		(mid 81.996159 -266.423336)
		(end 82.179668 -266.46886)
		(width 0.0889)
		(layer "In4.Cu")
		(net "M_D_CPU1_SB_CS_N<1>")
	)
	(arc
		(start 80.874108 -266.473686)
		(mid 81.061052 -266.423431)
		(end 81.247996 -266.473686)
		(width 0.0889)
		(layer "In4.Cu")
		(net "M_D_CPU1_SB_CS_N<1>")
	)
	(arc
		(start 82.762344 -266.46886)
		(mid 82.945852 -266.423366)
		(end 83.128104 -266.473686)
		(width 0.0889)
		(layer "In4.Cu")
		(net "M_D_CPU1_SB_CS_N<1>")
	)
	(arc
		(start 86.888066 -266.473686)
		(mid 87.171022 -266.549863)
		(end 87.453978 -266.473686)
		(width 0.0889)
		(layer "In4.Cu")
		(net "M_D_CPU1_SB_CS_N<1>")
	)
	(arc
		(start 86.513924 -266.473686)
		(mid 86.696175 -266.423336)
		(end 86.879684 -266.46886)
		(width 0.0889)
		(layer "In4.Cu")
		(net "M_D_CPU1_SB_CS_N<1>")
	)
	(arc
		(start 80.308196 -266.473686)
		(mid 80.591152 -266.549863)
		(end 80.874108 -266.473686)
		(width 0.0889)
		(layer "In4.Cu")
		(net "M_D_CPU1_SB_CS_N<1>")
	)
	(arc
		(start 90.273886 -266.473686)
		(mid 90.456137 -266.423336)
		(end 90.639646 -266.46886)
		(width 0.0889)
		(layer "In4.Cu")
		(net "M_D_CPU1_SB_CS_N<1>")
	)
	(arc
		(start 85.57387 -266.473686)
		(mid 85.756121 -266.423336)
		(end 85.93963 -266.46886)
		(width 0.0889)
		(layer "In4.Cu")
		(net "M_D_CPU1_SB_CS_N<1>")
	)
	(arc
		(start 88.402414 -266.46886)
		(mid 88.585922 -266.423366)
		(end 88.768174 -266.473686)
		(width 0.0889)
		(layer "In4.Cu")
		(net "M_D_CPU1_SB_CS_N<1>")
	)
	(arc
		(start 83.128104 -266.473686)
		(mid 83.41106 -266.549863)
		(end 83.694016 -266.473686)
		(width 0.0889)
		(layer "In4.Cu")
		(net "M_D_CPU1_SB_CS_N<1>")
	)
	(arc
		(start 90.648028 -266.473686)
		(mid 90.895624 -266.548864)
		(end 91.150694 -266.505436)
		(width 0.0889)
		(layer "In4.Cu")
		(net "M_D_CPU1_SB_CS_N<1>")
	)
	(arc
		(start 82.18805 -266.473686)
		(mid 82.471006 -266.549863)
		(end 82.753962 -266.473686)
		(width 0.0889)
		(layer "In4.Cu")
		(net "M_D_CPU1_SB_CS_N<1>")
	)
	(arc
		(start 84.63407 -266.473686)
		(mid 84.821014 -266.423431)
		(end 85.007958 -266.473686)
		(width 0.0889)
		(layer "In4.Cu")
		(net "M_D_CPU1_SB_CS_N<1>")
	)
	(arc
		(start 89.334086 -266.473686)
		(mid 89.52103 -266.423431)
		(end 89.707974 -266.473686)
		(width 0.0889)
		(layer "In4.Cu")
		(net "M_D_CPU1_SB_CS_N<1>")
	)
	(arc
		(start 87.46236 -266.46886)
		(mid 87.645868 -266.423366)
		(end 87.82812 -266.473686)
		(width 0.0889)
		(layer "In4.Cu")
		(net "M_D_CPU1_SB_CS_N<1>")
	)
	(arc
		(start 89.707974 -266.473686)
		(mid 89.99093 -266.549863)
		(end 90.273886 -266.473686)
		(width 0.0889)
		(layer "In4.Cu")
		(net "M_D_CPU1_SB_CS_N<1>")
	)
	(arc
		(start 87.82812 -266.473686)
		(mid 88.111076 -266.549863)
		(end 88.394032 -266.473686)
		(width 0.0889)
		(layer "In4.Cu")
		(net "M_D_CPU1_SB_CS_N<1>")
	)
	(arc
		(start 81.247996 -266.473686)
		(mid 81.530952 -266.549863)
		(end 81.813908 -266.473686)
		(width 0.0889)
		(layer "In4.Cu")
		(net "M_D_CPU1_SB_CS_N<1>")
	)
	(arc
		(start 88.768174 -266.473686)
		(mid 89.05113 -266.549863)
		(end 89.334086 -266.473686)
		(width 0.0889)
		(layer "In4.Cu")
		(net "M_D_CPU1_SB_CS_N<1>")
	)
	(arc
		(start 83.702398 -266.46886)
		(mid 83.885906 -266.423366)
		(end 84.068158 -266.473686)
		(width 0.0889)
		(layer "In4.Cu")
		(net "M_D_CPU1_SB_CS_N<1>")
	)
	(arc
		(start 85.948012 -266.473686)
		(mid 86.230968 -266.549863)
		(end 86.513924 -266.473686)
		(width 0.0889)
		(layer "In4.Cu")
		(net "M_D_CPU1_SB_CS_N<1>")
	)
	(arc
		(start 84.068158 -266.473686)
		(mid 84.351114 -266.549863)
		(end 84.63407 -266.473686)
		(width 0.0889)
		(layer "In4.Cu")
		(net "M_D_CPU1_SB_CS_N<1>")
	)
	(arc
		(start 80.120998 -266.42314)
		(mid 80.217945 -266.436023)
		(end 80.308196 -266.473686)
		(width 0.0889)
		(layer "In4.Cu")
		(net "M_D_CPU1_SB_CS_N<1>")
	)
	(arc
		(start 85.007958 -266.473686)
		(mid 85.290914 -266.549863)
		(end 85.57387 -266.473686)
		(width 0.0889)
		(layer "In4.Cu")
		(net "M_D_CPU1_SB_CS_N<1>")
	)
	(segment
		(start 93.277944 -265.720322)
		(end 92.811092 -265.98626)
		(width 0.10668)
		(layer "F.Cu")
		(net "M_D_CPU1_SB_CS_N<0>")
	)
	(segment
		(start 56.77281 -267.460476)
		(end 57.084722 -267.148564)
		(width 0.14478)
		(layer "In4.Cu")
		(net "M_D_CPU1_SB_CS_N<0>")
	)
	(segment
		(start 57.084722 -267.148564)
		(end 57.32907 -267.148564)
		(width 0.14478)
		(layer "In4.Cu")
		(net "M_D_CPU1_SB_CS_N<0>")
	)
	(segment
		(start 38.620446 -267.460476)
		(end 38.890194 -267.460476)
		(width 0.14478)
		(layer "In4.Cu")
		(net "M_D_CPU1_SB_CS_N<0>")
	)
	(segment
		(start 45.375068 -267.148564)
		(end 45.68698 -267.460476)
		(width 0.14478)
		(layer "In4.Cu")
		(net "M_D_CPU1_SB_CS_N<0>")
	)
	(segment
		(start 53.43525 -267.460476)
		(end 53.747162 -267.148564)
		(width 0.14478)
		(layer "In4.Cu")
		(net "M_D_CPU1_SB_CS_N<0>")
	)
	(segment
		(start 37.777674 -267.460476)
		(end 38.064186 -267.173964)
		(width 0.14478)
		(layer "In4.Cu")
		(net "M_D_CPU1_SB_CS_N<0>")
	)
	(segment
		(start 81.344008 -265.66368)
		(end 81.35239 -265.658854)
		(width 0.0889)
		(layer "In4.Cu")
		(net "M_D_CPU1_SB_CS_N<0>")
	)
	(segment
		(start 43.856402 -267.460476)
		(end 44.818808 -267.460476)
		(width 0.14478)
		(layer "In4.Cu")
		(net "M_D_CPU1_SB_CS_N<0>")
	)
	(segment
		(start 53.747162 -267.148564)
		(end 53.99151 -267.148564)
		(width 0.14478)
		(layer "In4.Cu")
		(net "M_D_CPU1_SB_CS_N<0>")
	)
	(segment
		(start 57.640982 -267.460476)
		(end 57.88533 -267.460476)
		(width 0.14478)
		(layer "In4.Cu")
		(net "M_D_CPU1_SB_CS_N<0>")
	)
	(segment
		(start 58.197242 -267.148564)
		(end 58.44159 -267.148564)
		(width 0.14478)
		(layer "In4.Cu")
		(net "M_D_CPU1_SB_CS_N<0>")
	)
	(segment
		(start 55.972202 -267.148564)
		(end 56.21655 -267.148564)
		(width 0.14478)
		(layer "In4.Cu")
		(net "M_D_CPU1_SB_CS_N<0>")
	)
	(segment
		(start 49.379378 -267.460476)
		(end 49.69129 -267.148564)
		(width 0.14478)
		(layer "In4.Cu")
		(net "M_D_CPU1_SB_CS_N<0>")
	)
	(segment
		(start 76.119736 -265.529314)
		(end 79.340202 -265.529314)
		(width 0.0889)
		(layer "In4.Cu")
		(net "M_D_CPU1_SB_CS_N<0>")
	)
	(segment
		(start 56.528462 -267.460476)
		(end 56.77281 -267.460476)
		(width 0.14478)
		(layer "In4.Cu")
		(net "M_D_CPU1_SB_CS_N<0>")
	)
	(segment
		(start 60.492386 -267.173964)
		(end 62.137036 -265.529314)
		(width 0.14478)
		(layer "In4.Cu")
		(net "M_D_CPU1_SB_CS_N<0>")
	)
	(segment
		(start 42.743882 -267.460476)
		(end 42.98823 -267.460476)
		(width 0.14478)
		(layer "In4.Cu")
		(net "M_D_CPU1_SB_CS_N<0>")
	)
	(segment
		(start 41.075102 -267.148564)
		(end 41.31945 -267.148564)
		(width 0.14478)
		(layer "In4.Cu")
		(net "M_D_CPU1_SB_CS_N<0>")
	)
	(segment
		(start 59.997594 -267.460476)
		(end 60.284106 -267.173964)
		(width 0.14478)
		(layer "In4.Cu")
		(net "M_D_CPU1_SB_CS_N<0>")
	)
	(segment
		(start 45.13072 -267.148564)
		(end 45.375068 -267.148564)
		(width 0.14478)
		(layer "In4.Cu")
		(net "M_D_CPU1_SB_CS_N<0>")
	)
	(segment
		(start 41.631362 -267.460476)
		(end 41.87571 -267.460476)
		(width 0.14478)
		(layer "In4.Cu")
		(net "M_D_CPU1_SB_CS_N<0>")
	)
	(segment
		(start 46.24324 -267.148564)
		(end 46.487588 -267.148564)
		(width 0.14478)
		(layer "In4.Cu")
		(net "M_D_CPU1_SB_CS_N<0>")
	)
	(segment
		(start 82.284062 -265.66368)
		(end 82.292444 -265.658854)
		(width 0.0889)
		(layer "In4.Cu")
		(net "M_D_CPU1_SB_CS_N<0>")
	)
	(segment
		(start 36.795964 -267.885418)
		(end 37.220906 -267.460476)
		(width 0.14478)
		(layer "In4.Cu")
		(net "M_D_CPU1_SB_CS_N<0>")
	)
	(segment
		(start 86.044024 -265.66368)
		(end 86.052406 -265.658854)
		(width 0.0889)
		(layer "In4.Cu")
		(net "M_D_CPU1_SB_CS_N<0>")
	)
	(segment
		(start 48.266858 -267.460476)
		(end 48.57877 -267.148564)
		(width 0.14478)
		(layer "In4.Cu")
		(net "M_D_CPU1_SB_CS_N<0>")
	)
	(segment
		(start 39.446454 -267.173964)
		(end 39.732966 -267.460476)
		(width 0.14478)
		(layer "In4.Cu")
		(net "M_D_CPU1_SB_CS_N<0>")
	)
	(segment
		(start 58.753502 -267.460476)
		(end 59.997594 -267.460476)
		(width 0.14478)
		(layer "In4.Cu")
		(net "M_D_CPU1_SB_CS_N<0>")
	)
	(segment
		(start 45.931328 -267.460476)
		(end 46.24324 -267.148564)
		(width 0.14478)
		(layer "In4.Cu")
		(net "M_D_CPU1_SB_CS_N<0>")
	)
	(segment
		(start 48.57877 -267.148564)
		(end 48.823118 -267.148564)
		(width 0.14478)
		(layer "In4.Cu")
		(net "M_D_CPU1_SB_CS_N<0>")
	)
	(segment
		(start 42.98823 -267.460476)
		(end 43.300142 -267.148564)
		(width 0.14478)
		(layer "In4.Cu")
		(net "M_D_CPU1_SB_CS_N<0>")
	)
	(segment
		(start 58.44159 -267.148564)
		(end 58.753502 -267.460476)
		(width 0.14478)
		(layer "In4.Cu")
		(net "M_D_CPU1_SB_CS_N<0>")
	)
	(segment
		(start 52.32273 -267.460476)
		(end 52.634642 -267.148564)
		(width 0.14478)
		(layer "In4.Cu")
		(net "M_D_CPU1_SB_CS_N<0>")
	)
	(segment
		(start 37.220906 -267.460476)
		(end 37.777674 -267.460476)
		(width 0.14478)
		(layer "In4.Cu")
		(net "M_D_CPU1_SB_CS_N<0>")
	)
	(segment
		(start 50.24755 -267.460476)
		(end 50.491898 -267.460476)
		(width 0.14478)
		(layer "In4.Cu")
		(net "M_D_CPU1_SB_CS_N<0>")
	)
	(segment
		(start 42.43197 -267.148564)
		(end 42.743882 -267.460476)
		(width 0.14478)
		(layer "In4.Cu")
		(net "M_D_CPU1_SB_CS_N<0>")
	)
	(segment
		(start 54.54777 -267.460476)
		(end 54.859682 -267.148564)
		(width 0.14478)
		(layer "In4.Cu")
		(net "M_D_CPU1_SB_CS_N<0>")
	)
	(segment
		(start 53.190902 -267.460476)
		(end 53.43525 -267.460476)
		(width 0.14478)
		(layer "In4.Cu")
		(net "M_D_CPU1_SB_CS_N<0>")
	)
	(segment
		(start 80.769714 -265.658854)
		(end 80.778096 -265.66368)
		(width 0.0889)
		(layer "In4.Cu")
		(net "M_D_CPU1_SB_CS_N<0>")
	)
	(segment
		(start 38.333934 -267.173964)
		(end 38.620446 -267.460476)
		(width 0.14478)
		(layer "In4.Cu")
		(net "M_D_CPU1_SB_CS_N<0>")
	)
	(segment
		(start 51.048158 -267.148564)
		(end 51.36007 -267.460476)
		(width 0.14478)
		(layer "In4.Cu")
		(net "M_D_CPU1_SB_CS_N<0>")
	)
	(segment
		(start 54.303422 -267.460476)
		(end 54.54777 -267.460476)
		(width 0.14478)
		(layer "In4.Cu")
		(net "M_D_CPU1_SB_CS_N<0>")
	)
	(segment
		(start 43.300142 -267.148564)
		(end 43.54449 -267.148564)
		(width 0.14478)
		(layer "In4.Cu")
		(net "M_D_CPU1_SB_CS_N<0>")
	)
	(segment
		(start 44.818808 -267.460476)
		(end 45.13072 -267.148564)
		(width 0.14478)
		(layer "In4.Cu")
		(net "M_D_CPU1_SB_CS_N<0>")
	)
	(segment
		(start 92.560648 -265.69543)
		(end 92.656914 -265.72083)
		(width 0.0889)
		(layer "In4.Cu")
		(net "M_D_CPU1_SB_CS_N<0>")
	)
	(segment
		(start 92.656914 -265.72083)
		(end 92.811092 -265.98626)
		(width 0.0889)
		(layer "In4.Cu")
		(net "M_D_CPU1_SB_CS_N<0>")
	)
	(segment
		(start 50.491898 -267.460476)
		(end 50.80381 -267.148564)
		(width 0.14478)
		(layer "In4.Cu")
		(net "M_D_CPU1_SB_CS_N<0>")
	)
	(segment
		(start 80.389222 -265.672316)
		(end 80.403954 -265.66368)
		(width 0.0889)
		(layer "In4.Cu")
		(net "M_D_CPU1_SB_CS_N<0>")
	)
	(segment
		(start 48.823118 -267.148564)
		(end 49.13503 -267.460476)
		(width 0.14478)
		(layer "In4.Cu")
		(net "M_D_CPU1_SB_CS_N<0>")
	)
	(segment
		(start 90.74404 -265.66368)
		(end 90.752422 -265.658854)
		(width 0.0889)
		(layer "In4.Cu")
		(net "M_D_CPU1_SB_CS_N<0>")
	)
	(segment
		(start 54.859682 -267.148564)
		(end 55.10403 -267.148564)
		(width 0.14478)
		(layer "In4.Cu")
		(net "M_D_CPU1_SB_CS_N<0>")
	)
	(segment
		(start 53.99151 -267.148564)
		(end 54.303422 -267.460476)
		(width 0.14478)
		(layer "In4.Cu")
		(net "M_D_CPU1_SB_CS_N<0>")
	)
	(segment
		(start 39.732966 -267.460476)
		(end 40.76319 -267.460476)
		(width 0.14478)
		(layer "In4.Cu")
		(net "M_D_CPU1_SB_CS_N<0>")
	)
	(segment
		(start 43.54449 -267.148564)
		(end 43.856402 -267.460476)
		(width 0.14478)
		(layer "In4.Cu")
		(net "M_D_CPU1_SB_CS_N<0>")
	)
	(segment
		(start 46.487588 -267.148564)
		(end 46.7995 -267.460476)
		(width 0.14478)
		(layer "In4.Cu")
		(net "M_D_CPU1_SB_CS_N<0>")
	)
	(segment
		(start 49.935638 -267.148564)
		(end 50.24755 -267.460476)
		(width 0.14478)
		(layer "In4.Cu")
		(net "M_D_CPU1_SB_CS_N<0>")
	)
	(segment
		(start 52.87899 -267.148564)
		(end 53.190902 -267.460476)
		(width 0.14478)
		(layer "In4.Cu")
		(net "M_D_CPU1_SB_CS_N<0>")
	)
	(segment
		(start 41.87571 -267.460476)
		(end 42.187622 -267.148564)
		(width 0.14478)
		(layer "In4.Cu")
		(net "M_D_CPU1_SB_CS_N<0>")
	)
	(segment
		(start 45.68698 -267.460476)
		(end 45.931328 -267.460476)
		(width 0.14478)
		(layer "In4.Cu")
		(net "M_D_CPU1_SB_CS_N<0>")
	)
	(segment
		(start 60.284106 -267.173964)
		(end 60.492386 -267.173964)
		(width 0.14478)
		(layer "In4.Cu")
		(net "M_D_CPU1_SB_CS_N<0>")
	)
	(segment
		(start 49.13503 -267.460476)
		(end 49.379378 -267.460476)
		(width 0.14478)
		(layer "In4.Cu")
		(net "M_D_CPU1_SB_CS_N<0>")
	)
	(segment
		(start 51.36007 -267.460476)
		(end 52.32273 -267.460476)
		(width 0.14478)
		(layer "In4.Cu")
		(net "M_D_CPU1_SB_CS_N<0>")
	)
	(segment
		(start 55.10403 -267.148564)
		(end 55.415942 -267.460476)
		(width 0.14478)
		(layer "In4.Cu")
		(net "M_D_CPU1_SB_CS_N<0>")
	)
	(segment
		(start 38.064186 -267.173964)
		(end 38.333934 -267.173964)
		(width 0.14478)
		(layer "In4.Cu")
		(net "M_D_CPU1_SB_CS_N<0>")
	)
	(segment
		(start 84.529676 -265.658854)
		(end 84.538058 -265.66368)
		(width 0.0889)
		(layer "In4.Cu")
		(net "M_D_CPU1_SB_CS_N<0>")
	)
	(segment
		(start 85.10397 -265.66368)
		(end 85.112352 -265.658854)
		(width 0.0889)
		(layer "In4.Cu")
		(net "M_D_CPU1_SB_CS_N<0>")
	)
	(segment
		(start 52.634642 -267.148564)
		(end 52.87899 -267.148564)
		(width 0.14478)
		(layer "In4.Cu")
		(net "M_D_CPU1_SB_CS_N<0>")
	)
	(segment
		(start 42.187622 -267.148564)
		(end 42.43197 -267.148564)
		(width 0.14478)
		(layer "In4.Cu")
		(net "M_D_CPU1_SB_CS_N<0>")
	)
	(segment
		(start 57.32907 -267.148564)
		(end 57.640982 -267.460476)
		(width 0.14478)
		(layer "In4.Cu")
		(net "M_D_CPU1_SB_CS_N<0>")
	)
	(segment
		(start 49.69129 -267.148564)
		(end 49.935638 -267.148564)
		(width 0.14478)
		(layer "In4.Cu")
		(net "M_D_CPU1_SB_CS_N<0>")
	)
	(segment
		(start 40.76319 -267.460476)
		(end 41.075102 -267.148564)
		(width 0.14478)
		(layer "In4.Cu")
		(net "M_D_CPU1_SB_CS_N<0>")
	)
	(segment
		(start 56.21655 -267.148564)
		(end 56.528462 -267.460476)
		(width 0.14478)
		(layer "In4.Cu")
		(net "M_D_CPU1_SB_CS_N<0>")
	)
	(segment
		(start 89.229692 -265.658854)
		(end 89.238074 -265.66368)
		(width 0.0889)
		(layer "In4.Cu")
		(net "M_D_CPU1_SB_CS_N<0>")
	)
	(segment
		(start 89.803986 -265.66368)
		(end 89.812368 -265.658854)
		(width 0.0889)
		(layer "In4.Cu")
		(net "M_D_CPU1_SB_CS_N<0>")
	)
	(segment
		(start 55.66029 -267.460476)
		(end 55.972202 -267.148564)
		(width 0.14478)
		(layer "In4.Cu")
		(net "M_D_CPU1_SB_CS_N<0>")
	)
	(segment
		(start 88.289638 -265.658854)
		(end 88.29802 -265.66368)
		(width 0.0889)
		(layer "In4.Cu")
		(net "M_D_CPU1_SB_CS_N<0>")
	)
	(segment
		(start 39.176706 -267.173964)
		(end 39.446454 -267.173964)
		(width 0.14478)
		(layer "In4.Cu")
		(net "M_D_CPU1_SB_CS_N<0>")
	)
	(segment
		(start 38.890194 -267.460476)
		(end 39.176706 -267.173964)
		(width 0.14478)
		(layer "In4.Cu")
		(net "M_D_CPU1_SB_CS_N<0>")
	)
	(segment
		(start 46.7995 -267.460476)
		(end 48.266858 -267.460476)
		(width 0.14478)
		(layer "In4.Cu")
		(net "M_D_CPU1_SB_CS_N<0>")
	)
	(segment
		(start 57.88533 -267.460476)
		(end 58.197242 -267.148564)
		(width 0.14478)
		(layer "In4.Cu")
		(net "M_D_CPU1_SB_CS_N<0>")
	)
	(segment
		(start 55.415942 -267.460476)
		(end 55.66029 -267.460476)
		(width 0.14478)
		(layer "In4.Cu")
		(net "M_D_CPU1_SB_CS_N<0>")
	)
	(segment
		(start 41.31945 -267.148564)
		(end 41.631362 -267.460476)
		(width 0.14478)
		(layer "In4.Cu")
		(net "M_D_CPU1_SB_CS_N<0>")
	)
	(segment
		(start 62.137036 -265.529314)
		(end 76.119736 -265.529314)
		(width 0.14478)
		(layer "In4.Cu")
		(net "M_D_CPU1_SB_CS_N<0>")
	)
	(segment
		(start 50.80381 -267.148564)
		(end 51.048158 -267.148564)
		(width 0.14478)
		(layer "In4.Cu")
		(net "M_D_CPU1_SB_CS_N<0>")
	)
	(arc
		(start 86.984078 -265.66368)
		(mid 87.171022 -265.613425)
		(end 87.357966 -265.66368)
		(width 0.0889)
		(layer "In4.Cu")
		(net "M_D_CPU1_SB_CS_N<0>")
	)
	(arc
		(start 87.357966 -265.66368)
		(mid 87.640922 -265.739857)
		(end 87.923878 -265.66368)
		(width 0.0889)
		(layer "In4.Cu")
		(net "M_D_CPU1_SB_CS_N<0>")
	)
	(arc
		(start 79.837534 -265.66368)
		(mid 80.11224 -265.740044)
		(end 80.389222 -265.672316)
		(width 0.0889)
		(layer "In4.Cu")
		(net "M_D_CPU1_SB_CS_N<0>")
	)
	(arc
		(start 92.057982 -265.66368)
		(mid 92.305578 -265.738858)
		(end 92.560648 -265.69543)
		(width 0.0889)
		(layer "In4.Cu")
		(net "M_D_CPU1_SB_CS_N<0>")
	)
	(arc
		(start 89.812368 -265.658854)
		(mid 89.995876 -265.61336)
		(end 90.178128 -265.66368)
		(width 0.0889)
		(layer "In4.Cu")
		(net "M_D_CPU1_SB_CS_N<0>")
	)
	(arc
		(start 85.112352 -265.658854)
		(mid 85.29586 -265.61336)
		(end 85.478112 -265.66368)
		(width 0.0889)
		(layer "In4.Cu")
		(net "M_D_CPU1_SB_CS_N<0>")
	)
	(arc
		(start 80.403954 -265.66368)
		(mid 80.586205 -265.61333)
		(end 80.769714 -265.658854)
		(width 0.0889)
		(layer "In4.Cu")
		(net "M_D_CPU1_SB_CS_N<0>")
	)
	(arc
		(start 90.752422 -265.658854)
		(mid 90.93593 -265.61336)
		(end 91.118182 -265.66368)
		(width 0.0889)
		(layer "In4.Cu")
		(net "M_D_CPU1_SB_CS_N<0>")
	)
	(arc
		(start 84.163916 -265.66368)
		(mid 84.346167 -265.61333)
		(end 84.529676 -265.658854)
		(width 0.0889)
		(layer "In4.Cu")
		(net "M_D_CPU1_SB_CS_N<0>")
	)
	(arc
		(start 86.052406 -265.658854)
		(mid 86.235914 -265.61336)
		(end 86.418166 -265.66368)
		(width 0.0889)
		(layer "In4.Cu")
		(net "M_D_CPU1_SB_CS_N<0>")
	)
	(arc
		(start 89.238074 -265.66368)
		(mid 89.52103 -265.739857)
		(end 89.803986 -265.66368)
		(width 0.0889)
		(layer "In4.Cu")
		(net "M_D_CPU1_SB_CS_N<0>")
	)
	(arc
		(start 90.178128 -265.66368)
		(mid 90.461084 -265.739857)
		(end 90.74404 -265.66368)
		(width 0.0889)
		(layer "In4.Cu")
		(net "M_D_CPU1_SB_CS_N<0>")
	)
	(arc
		(start 86.418166 -265.66368)
		(mid 86.701122 -265.739857)
		(end 86.984078 -265.66368)
		(width 0.0889)
		(layer "In4.Cu")
		(net "M_D_CPU1_SB_CS_N<0>")
	)
	(arc
		(start 83.598004 -265.66368)
		(mid 83.88096 -265.739857)
		(end 84.163916 -265.66368)
		(width 0.0889)
		(layer "In4.Cu")
		(net "M_D_CPU1_SB_CS_N<0>")
	)
	(arc
		(start 87.923878 -265.66368)
		(mid 88.106129 -265.61333)
		(end 88.289638 -265.658854)
		(width 0.0889)
		(layer "In4.Cu")
		(net "M_D_CPU1_SB_CS_N<0>")
	)
	(arc
		(start 80.778096 -265.66368)
		(mid 81.061052 -265.739857)
		(end 81.344008 -265.66368)
		(width 0.0889)
		(layer "In4.Cu")
		(net "M_D_CPU1_SB_CS_N<0>")
	)
	(arc
		(start 83.224116 -265.66368)
		(mid 83.41106 -265.613425)
		(end 83.598004 -265.66368)
		(width 0.0889)
		(layer "In4.Cu")
		(net "M_D_CPU1_SB_CS_N<0>")
	)
	(arc
		(start 82.292444 -265.658854)
		(mid 82.475952 -265.61336)
		(end 82.658204 -265.66368)
		(width 0.0889)
		(layer "In4.Cu")
		(net "M_D_CPU1_SB_CS_N<0>")
	)
	(arc
		(start 85.478112 -265.66368)
		(mid 85.761068 -265.739857)
		(end 86.044024 -265.66368)
		(width 0.0889)
		(layer "In4.Cu")
		(net "M_D_CPU1_SB_CS_N<0>")
	)
	(arc
		(start 81.35239 -265.658854)
		(mid 81.535898 -265.61336)
		(end 81.71815 -265.66368)
		(width 0.0889)
		(layer "In4.Cu")
		(net "M_D_CPU1_SB_CS_N<0>")
	)
	(arc
		(start 88.863932 -265.66368)
		(mid 89.046183 -265.61333)
		(end 89.229692 -265.658854)
		(width 0.0889)
		(layer "In4.Cu")
		(net "M_D_CPU1_SB_CS_N<0>")
	)
	(arc
		(start 91.118182 -265.66368)
		(mid 91.401138 -265.739857)
		(end 91.684094 -265.66368)
		(width 0.0889)
		(layer "In4.Cu")
		(net "M_D_CPU1_SB_CS_N<0>")
	)
	(arc
		(start 82.658204 -265.66368)
		(mid 82.94116 -265.739857)
		(end 83.224116 -265.66368)
		(width 0.0889)
		(layer "In4.Cu")
		(net "M_D_CPU1_SB_CS_N<0>")
	)
	(arc
		(start 88.29802 -265.66368)
		(mid 88.580976 -265.739857)
		(end 88.863932 -265.66368)
		(width 0.0889)
		(layer "In4.Cu")
		(net "M_D_CPU1_SB_CS_N<0>")
	)
	(arc
		(start 79.340202 -265.529314)
		(mid 79.597779 -265.563506)
		(end 79.837534 -265.66368)
		(width 0.0889)
		(layer "In4.Cu")
		(net "M_D_CPU1_SB_CS_N<0>")
	)
	(arc
		(start 84.538058 -265.66368)
		(mid 84.821014 -265.739857)
		(end 85.10397 -265.66368)
		(width 0.0889)
		(layer "In4.Cu")
		(net "M_D_CPU1_SB_CS_N<0>")
	)
	(arc
		(start 91.684094 -265.66368)
		(mid 91.871038 -265.613425)
		(end 92.057982 -265.66368)
		(width 0.0889)
		(layer "In4.Cu")
		(net "M_D_CPU1_SB_CS_N<0>")
	)
	(arc
		(start 81.71815 -265.66368)
		(mid 82.001106 -265.739857)
		(end 82.284062 -265.66368)
		(width 0.0889)
		(layer "In4.Cu")
		(net "M_D_CPU1_SB_CS_N<0>")
	)
	(segment
		(start 93.277944 -270.580358)
		(end 92.811092 -270.846296)
		(width 0.10668)
		(layer "F.Cu")
		(net "M_D_CPU1_SB_CB<7>")
	)
	(segment
		(start 34.7599 -274.26031)
		(end 34.922714 -274.097496)
		(width 0.14478)
		(layer "In4.Cu")
		(net "M_D_CPU1_SB_CB<7>")
	)
	(segment
		(start 92.656914 -270.580866)
		(end 92.811092 -270.846296)
		(width 0.0889)
		(layer "In4.Cu")
		(net "M_D_CPU1_SB_CB<7>")
	)
	(segment
		(start 34.922714 -274.097496)
		(end 34.922714 -273.71802)
		(width 0.14478)
		(layer "In4.Cu")
		(net "M_D_CPU1_SB_CB<7>")
	)
	(segment
		(start 90.74404 -270.523716)
		(end 90.752422 -270.51889)
		(width 0.0889)
		(layer "In4.Cu")
		(net "M_D_CPU1_SB_CB<7>")
	)
	(segment
		(start 92.560648 -270.555466)
		(end 92.656914 -270.580866)
		(width 0.0889)
		(layer "In4.Cu")
		(net "M_D_CPU1_SB_CB<7>")
	)
	(segment
		(start 84.529676 -270.51889)
		(end 84.538058 -270.523716)
		(width 0.0889)
		(layer "In4.Cu")
		(net "M_D_CPU1_SB_CB<7>")
	)
	(segment
		(start 76.283058 -268.960854)
		(end 76.45019 -269.127986)
		(width 0.0889)
		(layer "In4.Cu")
		(net "M_D_CPU1_SB_CB<7>")
	)
	(segment
		(start 33.810194 -273.534378)
		(end 33.973008 -273.371564)
		(width 0.14478)
		(layer "In4.Cu")
		(net "M_D_CPU1_SB_CB<7>")
	)
	(segment
		(start 88.289638 -270.51889)
		(end 88.29802 -270.523716)
		(width 0.0889)
		(layer "In4.Cu")
		(net "M_D_CPU1_SB_CB<7>")
	)
	(segment
		(start 35.641788 -274.26031)
		(end 38.44544 -274.26031)
		(width 0.14478)
		(layer "In4.Cu")
		(net "M_D_CPU1_SB_CB<7>")
	)
	(segment
		(start 60.689236 -273.410426)
		(end 65.138808 -268.960854)
		(width 0.14478)
		(layer "In4.Cu")
		(net "M_D_CPU1_SB_CB<7>")
	)
	(segment
		(start 83.589622 -270.51889)
		(end 83.598004 -270.523716)
		(width 0.0889)
		(layer "In4.Cu")
		(net "M_D_CPU1_SB_CB<7>")
	)
	(segment
		(start 32.695896 -274.685252)
		(end 33.120838 -274.26031)
		(width 0.14478)
		(layer "In4.Cu")
		(net "M_D_CPU1_SB_CB<7>")
	)
	(segment
		(start 89.803986 -270.523716)
		(end 89.812368 -270.51889)
		(width 0.0889)
		(layer "In4.Cu")
		(net "M_D_CPU1_SB_CB<7>")
	)
	(segment
		(start 33.64738 -274.26031)
		(end 33.810194 -274.097496)
		(width 0.14478)
		(layer "In4.Cu")
		(net "M_D_CPU1_SB_CB<7>")
	)
	(segment
		(start 65.138808 -268.960854)
		(end 75.934824 -268.960854)
		(width 0.14478)
		(layer "In4.Cu")
		(net "M_D_CPU1_SB_CB<7>")
	)
	(segment
		(start 33.120838 -274.26031)
		(end 33.64738 -274.26031)
		(width 0.14478)
		(layer "In4.Cu")
		(net "M_D_CPU1_SB_CB<7>")
	)
	(segment
		(start 33.973008 -273.371564)
		(end 34.20364 -273.371564)
		(width 0.14478)
		(layer "In4.Cu")
		(net "M_D_CPU1_SB_CB<7>")
	)
	(segment
		(start 76.45019 -269.127986)
		(end 77.00391 -269.127986)
		(width 0.0889)
		(layer "In4.Cu")
		(net "M_D_CPU1_SB_CB<7>")
	)
	(segment
		(start 34.20364 -273.371564)
		(end 34.366454 -273.534378)
		(width 0.14478)
		(layer "In4.Cu")
		(net "M_D_CPU1_SB_CB<7>")
	)
	(segment
		(start 85.10397 -270.523716)
		(end 85.112352 -270.51889)
		(width 0.0889)
		(layer "In4.Cu")
		(net "M_D_CPU1_SB_CB<7>")
	)
	(segment
		(start 77.00391 -269.127986)
		(end 77.988668 -270.112744)
		(width 0.0889)
		(layer "In4.Cu")
		(net "M_D_CPU1_SB_CB<7>")
	)
	(segment
		(start 78.689708 -270.403066)
		(end 79.391002 -270.403066)
		(width 0.0889)
		(layer "In4.Cu")
		(net "M_D_CPU1_SB_CB<7>")
	)
	(segment
		(start 89.229692 -270.51889)
		(end 89.238074 -270.523716)
		(width 0.0889)
		(layer "In4.Cu")
		(net "M_D_CPU1_SB_CB<7>")
	)
	(segment
		(start 81.344008 -270.523716)
		(end 81.35239 -270.51889)
		(width 0.0889)
		(layer "In4.Cu")
		(net "M_D_CPU1_SB_CB<7>")
	)
	(segment
		(start 80.389222 -270.532352)
		(end 80.403954 -270.523716)
		(width 0.0889)
		(layer "In4.Cu")
		(net "M_D_CPU1_SB_CB<7>")
	)
	(segment
		(start 34.366454 -273.534378)
		(end 34.366454 -274.097496)
		(width 0.14478)
		(layer "In4.Cu")
		(net "M_D_CPU1_SB_CB<7>")
	)
	(segment
		(start 35.478974 -274.097496)
		(end 35.641788 -274.26031)
		(width 0.14478)
		(layer "In4.Cu")
		(net "M_D_CPU1_SB_CB<7>")
	)
	(segment
		(start 35.085528 -273.555206)
		(end 35.31616 -273.555206)
		(width 0.14478)
		(layer "In4.Cu")
		(net "M_D_CPU1_SB_CB<7>")
	)
	(segment
		(start 75.934824 -268.960854)
		(end 76.283058 -268.960854)
		(width 0.0889)
		(layer "In4.Cu")
		(net "M_D_CPU1_SB_CB<7>")
	)
	(segment
		(start 34.529268 -274.26031)
		(end 34.7599 -274.26031)
		(width 0.14478)
		(layer "In4.Cu")
		(net "M_D_CPU1_SB_CB<7>")
	)
	(segment
		(start 39.295324 -273.410426)
		(end 60.689236 -273.410426)
		(width 0.14478)
		(layer "In4.Cu")
		(net "M_D_CPU1_SB_CB<7>")
	)
	(segment
		(start 86.044024 -270.523716)
		(end 86.052406 -270.51889)
		(width 0.0889)
		(layer "In4.Cu")
		(net "M_D_CPU1_SB_CB<7>")
	)
	(segment
		(start 34.922714 -273.71802)
		(end 35.085528 -273.555206)
		(width 0.14478)
		(layer "In4.Cu")
		(net "M_D_CPU1_SB_CB<7>")
	)
	(segment
		(start 35.31616 -273.555206)
		(end 35.478974 -273.71802)
		(width 0.14478)
		(layer "In4.Cu")
		(net "M_D_CPU1_SB_CB<7>")
	)
	(segment
		(start 35.478974 -273.71802)
		(end 35.478974 -274.097496)
		(width 0.14478)
		(layer "In4.Cu")
		(net "M_D_CPU1_SB_CB<7>")
	)
	(segment
		(start 33.810194 -274.097496)
		(end 33.810194 -273.534378)
		(width 0.14478)
		(layer "In4.Cu")
		(net "M_D_CPU1_SB_CB<7>")
	)
	(segment
		(start 34.366454 -274.097496)
		(end 34.529268 -274.26031)
		(width 0.14478)
		(layer "In4.Cu")
		(net "M_D_CPU1_SB_CB<7>")
	)
	(segment
		(start 38.44544 -274.26031)
		(end 39.295324 -273.410426)
		(width 0.14478)
		(layer "In4.Cu")
		(net "M_D_CPU1_SB_CB<7>")
	)
	(segment
		(start 80.769714 -270.51889)
		(end 80.778096 -270.523716)
		(width 0.0889)
		(layer "In4.Cu")
		(net "M_D_CPU1_SB_CB<7>")
	)
	(arc
		(start 81.71815 -270.523716)
		(mid 82.001106 -270.599893)
		(end 82.284062 -270.523716)
		(width 0.0889)
		(layer "In4.Cu")
		(net "M_D_CPU1_SB_CB<7>")
	)
	(arc
		(start 90.178128 -270.523716)
		(mid 90.461084 -270.599893)
		(end 90.74404 -270.523716)
		(width 0.0889)
		(layer "In4.Cu")
		(net "M_D_CPU1_SB_CB<7>")
	)
	(arc
		(start 77.988668 -270.112744)
		(mid 78.310322 -270.327603)
		(end 78.689708 -270.403066)
		(width 0.0889)
		(layer "In4.Cu")
		(net "M_D_CPU1_SB_CB<7>")
	)
	(arc
		(start 86.984078 -270.523716)
		(mid 87.171022 -270.473461)
		(end 87.357966 -270.523716)
		(width 0.0889)
		(layer "In4.Cu")
		(net "M_D_CPU1_SB_CB<7>")
	)
	(arc
		(start 85.112352 -270.51889)
		(mid 85.29586 -270.473396)
		(end 85.478112 -270.523716)
		(width 0.0889)
		(layer "In4.Cu")
		(net "M_D_CPU1_SB_CB<7>")
	)
	(arc
		(start 83.598004 -270.523716)
		(mid 83.88096 -270.599893)
		(end 84.163916 -270.523716)
		(width 0.0889)
		(layer "In4.Cu")
		(net "M_D_CPU1_SB_CB<7>")
	)
	(arc
		(start 87.357966 -270.523716)
		(mid 87.640922 -270.599893)
		(end 87.923878 -270.523716)
		(width 0.0889)
		(layer "In4.Cu")
		(net "M_D_CPU1_SB_CB<7>")
	)
	(arc
		(start 88.863932 -270.523716)
		(mid 89.046183 -270.473366)
		(end 89.229692 -270.51889)
		(width 0.0889)
		(layer "In4.Cu")
		(net "M_D_CPU1_SB_CB<7>")
	)
	(arc
		(start 89.812368 -270.51889)
		(mid 89.995876 -270.473396)
		(end 90.178128 -270.523716)
		(width 0.0889)
		(layer "In4.Cu")
		(net "M_D_CPU1_SB_CB<7>")
	)
	(arc
		(start 87.923878 -270.523716)
		(mid 88.106129 -270.473366)
		(end 88.289638 -270.51889)
		(width 0.0889)
		(layer "In4.Cu")
		(net "M_D_CPU1_SB_CB<7>")
	)
	(arc
		(start 92.057982 -270.523716)
		(mid 92.305578 -270.598894)
		(end 92.560648 -270.555466)
		(width 0.0889)
		(layer "In4.Cu")
		(net "M_D_CPU1_SB_CB<7>")
	)
	(arc
		(start 86.052406 -270.51889)
		(mid 86.235914 -270.473396)
		(end 86.418166 -270.523716)
		(width 0.0889)
		(layer "In4.Cu")
		(net "M_D_CPU1_SB_CB<7>")
	)
	(arc
		(start 79.391002 -270.403066)
		(mid 79.622271 -270.433766)
		(end 79.837534 -270.523716)
		(width 0.0889)
		(layer "In4.Cu")
		(net "M_D_CPU1_SB_CB<7>")
	)
	(arc
		(start 82.284062 -270.523716)
		(mid 82.471006 -270.473461)
		(end 82.65795 -270.523716)
		(width 0.0889)
		(layer "In4.Cu")
		(net "M_D_CPU1_SB_CB<7>")
	)
	(arc
		(start 88.29802 -270.523716)
		(mid 88.580976 -270.599893)
		(end 88.863932 -270.523716)
		(width 0.0889)
		(layer "In4.Cu")
		(net "M_D_CPU1_SB_CB<7>")
	)
	(arc
		(start 85.478112 -270.523716)
		(mid 85.761068 -270.599893)
		(end 86.044024 -270.523716)
		(width 0.0889)
		(layer "In4.Cu")
		(net "M_D_CPU1_SB_CB<7>")
	)
	(arc
		(start 91.118182 -270.523716)
		(mid 91.401138 -270.599893)
		(end 91.684094 -270.523716)
		(width 0.0889)
		(layer "In4.Cu")
		(net "M_D_CPU1_SB_CB<7>")
	)
	(arc
		(start 91.684094 -270.523716)
		(mid 91.871038 -270.473461)
		(end 92.057982 -270.523716)
		(width 0.0889)
		(layer "In4.Cu")
		(net "M_D_CPU1_SB_CB<7>")
	)
	(arc
		(start 81.35239 -270.51889)
		(mid 81.535898 -270.473396)
		(end 81.71815 -270.523716)
		(width 0.0889)
		(layer "In4.Cu")
		(net "M_D_CPU1_SB_CB<7>")
	)
	(arc
		(start 84.163916 -270.523716)
		(mid 84.346167 -270.473366)
		(end 84.529676 -270.51889)
		(width 0.0889)
		(layer "In4.Cu")
		(net "M_D_CPU1_SB_CB<7>")
	)
	(arc
		(start 84.538058 -270.523716)
		(mid 84.821014 -270.599893)
		(end 85.10397 -270.523716)
		(width 0.0889)
		(layer "In4.Cu")
		(net "M_D_CPU1_SB_CB<7>")
	)
	(arc
		(start 90.752422 -270.51889)
		(mid 90.93593 -270.473396)
		(end 91.118182 -270.523716)
		(width 0.0889)
		(layer "In4.Cu")
		(net "M_D_CPU1_SB_CB<7>")
	)
	(arc
		(start 82.65795 -270.523716)
		(mid 82.940906 -270.599893)
		(end 83.223862 -270.523716)
		(width 0.0889)
		(layer "In4.Cu")
		(net "M_D_CPU1_SB_CB<7>")
	)
	(arc
		(start 89.238074 -270.523716)
		(mid 89.52103 -270.599893)
		(end 89.803986 -270.523716)
		(width 0.0889)
		(layer "In4.Cu")
		(net "M_D_CPU1_SB_CB<7>")
	)
	(arc
		(start 80.403954 -270.523716)
		(mid 80.586205 -270.473366)
		(end 80.769714 -270.51889)
		(width 0.0889)
		(layer "In4.Cu")
		(net "M_D_CPU1_SB_CB<7>")
	)
	(arc
		(start 86.418166 -270.523716)
		(mid 86.701122 -270.599893)
		(end 86.984078 -270.523716)
		(width 0.0889)
		(layer "In4.Cu")
		(net "M_D_CPU1_SB_CB<7>")
	)
	(arc
		(start 80.778096 -270.523716)
		(mid 81.061052 -270.599893)
		(end 81.344008 -270.523716)
		(width 0.0889)
		(layer "In4.Cu")
		(net "M_D_CPU1_SB_CB<7>")
	)
	(arc
		(start 83.223862 -270.523716)
		(mid 83.406113 -270.473366)
		(end 83.589622 -270.51889)
		(width 0.0889)
		(layer "In4.Cu")
		(net "M_D_CPU1_SB_CB<7>")
	)
	(arc
		(start 79.837534 -270.523716)
		(mid 80.11224 -270.60008)
		(end 80.389222 -270.532352)
		(width 0.0889)
		(layer "In4.Cu")
		(net "M_D_CPU1_SB_CB<7>")
	)
	(segment
		(start 91.86799 -269.770352)
		(end 91.401138 -270.03629)
		(width 0.10668)
		(layer "F.Cu")
		(net "M_D_CPU1_SB_CB<6>")
	)
	(segment
		(start 78.993492 -269.713964)
		(end 79.01178 -269.70355)
		(width 0.0889)
		(layer "In4.Cu")
		(net "M_D_CPU1_SB_CB<6>")
	)
	(segment
		(start 91.150694 -269.74546)
		(end 91.24696 -269.77086)
		(width 0.0889)
		(layer "In4.Cu")
		(net "M_D_CPU1_SB_CB<6>")
	)
	(segment
		(start 35.18789 -272.397474)
		(end 35.350704 -272.560288)
		(width 0.14478)
		(layer "In4.Cu")
		(net "M_D_CPU1_SB_CB<6>")
	)
	(segment
		(start 34.238184 -272.560288)
		(end 34.468816 -272.560288)
		(width 0.14478)
		(layer "In4.Cu")
		(net "M_D_CPU1_SB_CB<6>")
	)
	(segment
		(start 35.906964 -271.792446)
		(end 36.137596 -271.792446)
		(width 0.14478)
		(layer "In4.Cu")
		(net "M_D_CPU1_SB_CB<6>")
	)
	(segment
		(start 34.63163 -272.397474)
		(end 34.63163 -271.807178)
		(width 0.14478)
		(layer "In4.Cu")
		(net "M_D_CPU1_SB_CB<6>")
	)
	(segment
		(start 35.74415 -272.397474)
		(end 35.74415 -271.95526)
		(width 0.14478)
		(layer "In4.Cu")
		(net "M_D_CPU1_SB_CB<6>")
	)
	(segment
		(start 77.238606 -268.551406)
		(end 78.312264 -269.625064)
		(width 0.0889)
		(layer "In4.Cu")
		(net "M_D_CPU1_SB_CB<6>")
	)
	(segment
		(start 33.912556 -271.644364)
		(end 34.07537 -271.807178)
		(width 0.14478)
		(layer "In4.Cu")
		(net "M_D_CPU1_SB_CB<6>")
	)
	(segment
		(start 34.63163 -271.807178)
		(end 34.794444 -271.644364)
		(width 0.14478)
		(layer "In4.Cu")
		(net "M_D_CPU1_SB_CB<6>")
	)
	(segment
		(start 76.95057 -268.551406)
		(end 77.238606 -268.551406)
		(width 0.0889)
		(layer "In4.Cu")
		(net "M_D_CPU1_SB_CB<6>")
	)
	(segment
		(start 75.974956 -268.051534)
		(end 76.450698 -268.051534)
		(width 0.0889)
		(layer "In4.Cu")
		(net "M_D_CPU1_SB_CB<6>")
	)
	(segment
		(start 36.137596 -271.792446)
		(end 36.30041 -271.95526)
		(width 0.14478)
		(layer "In4.Cu")
		(net "M_D_CPU1_SB_CB<6>")
	)
	(segment
		(start 33.51911 -272.397474)
		(end 33.51911 -271.807178)
		(width 0.14478)
		(layer "In4.Cu")
		(net "M_D_CPU1_SB_CB<6>")
	)
	(segment
		(start 36.30041 -271.95526)
		(end 36.30041 -272.397474)
		(width 0.14478)
		(layer "In4.Cu")
		(net "M_D_CPU1_SB_CB<6>")
	)
	(segment
		(start 32.695896 -272.98523)
		(end 33.120838 -272.560288)
		(width 0.14478)
		(layer "In4.Cu")
		(net "M_D_CPU1_SB_CB<6>")
	)
	(segment
		(start 34.07537 -272.397474)
		(end 34.238184 -272.560288)
		(width 0.14478)
		(layer "In4.Cu")
		(net "M_D_CPU1_SB_CB<6>")
	)
	(segment
		(start 88.394032 -269.71371)
		(end 88.402414 -269.708884)
		(width 0.0889)
		(layer "In4.Cu")
		(net "M_D_CPU1_SB_CB<6>")
	)
	(segment
		(start 35.350704 -272.560288)
		(end 35.581336 -272.560288)
		(width 0.14478)
		(layer "In4.Cu")
		(net "M_D_CPU1_SB_CB<6>")
	)
	(segment
		(start 87.453978 -269.71371)
		(end 87.46236 -269.708884)
		(width 0.0889)
		(layer "In4.Cu")
		(net "M_D_CPU1_SB_CB<6>")
	)
	(segment
		(start 34.07537 -271.807178)
		(end 34.07537 -272.397474)
		(width 0.14478)
		(layer "In4.Cu")
		(net "M_D_CPU1_SB_CB<6>")
	)
	(segment
		(start 82.179668 -269.708884)
		(end 82.18805 -269.71371)
		(width 0.0889)
		(layer "In4.Cu")
		(net "M_D_CPU1_SB_CB<6>")
	)
	(segment
		(start 36.30041 -272.397474)
		(end 36.463224 -272.560288)
		(width 0.14478)
		(layer "In4.Cu")
		(net "M_D_CPU1_SB_CB<6>")
	)
	(segment
		(start 34.468816 -272.560288)
		(end 34.63163 -272.397474)
		(width 0.14478)
		(layer "In4.Cu")
		(net "M_D_CPU1_SB_CB<6>")
	)
	(segment
		(start 82.753962 -269.71371)
		(end 82.762344 -269.708884)
		(width 0.0889)
		(layer "In4.Cu")
		(net "M_D_CPU1_SB_CB<6>")
	)
	(segment
		(start 83.694016 -269.71371)
		(end 83.702398 -269.708884)
		(width 0.0889)
		(layer "In4.Cu")
		(net "M_D_CPU1_SB_CB<6>")
	)
	(segment
		(start 34.794444 -271.644364)
		(end 35.025076 -271.644364)
		(width 0.14478)
		(layer "In4.Cu")
		(net "M_D_CPU1_SB_CB<6>")
	)
	(segment
		(start 86.879684 -269.708884)
		(end 86.888066 -269.71371)
		(width 0.0889)
		(layer "In4.Cu")
		(net "M_D_CPU1_SB_CB<6>")
	)
	(segment
		(start 79.934054 -269.71371)
		(end 79.942436 -269.708884)
		(width 0.0889)
		(layer "In4.Cu")
		(net "M_D_CPU1_SB_CB<6>")
	)
	(segment
		(start 76.450698 -268.051534)
		(end 76.95057 -268.551406)
		(width 0.0889)
		(layer "In4.Cu")
		(net "M_D_CPU1_SB_CB<6>")
	)
	(segment
		(start 33.51911 -271.807178)
		(end 33.681924 -271.644364)
		(width 0.14478)
		(layer "In4.Cu")
		(net "M_D_CPU1_SB_CB<6>")
	)
	(segment
		(start 35.025076 -271.644364)
		(end 35.18789 -271.807178)
		(width 0.14478)
		(layer "In4.Cu")
		(net "M_D_CPU1_SB_CB<6>")
	)
	(segment
		(start 38.836346 -271.710404)
		(end 61.117226 -271.710404)
		(width 0.14478)
		(layer "In4.Cu")
		(net "M_D_CPU1_SB_CB<6>")
	)
	(segment
		(start 33.681924 -271.644364)
		(end 33.912556 -271.644364)
		(width 0.14478)
		(layer "In4.Cu")
		(net "M_D_CPU1_SB_CB<6>")
	)
	(segment
		(start 35.581336 -272.560288)
		(end 35.74415 -272.397474)
		(width 0.14478)
		(layer "In4.Cu")
		(net "M_D_CPU1_SB_CB<6>")
	)
	(segment
		(start 36.463224 -272.560288)
		(end 37.986462 -272.560288)
		(width 0.14478)
		(layer "In4.Cu")
		(net "M_D_CPU1_SB_CB<6>")
	)
	(segment
		(start 79.919322 -269.722346)
		(end 79.934054 -269.71371)
		(width 0.0889)
		(layer "In4.Cu")
		(net "M_D_CPU1_SB_CB<6>")
	)
	(segment
		(start 78.977744 -269.723108)
		(end 78.993492 -269.713964)
		(width 0.0889)
		(layer "In4.Cu")
		(net "M_D_CPU1_SB_CB<6>")
	)
	(segment
		(start 61.117226 -271.710404)
		(end 64.776096 -268.051534)
		(width 0.14478)
		(layer "In4.Cu")
		(net "M_D_CPU1_SB_CB<6>")
	)
	(segment
		(start 91.24696 -269.77086)
		(end 91.401138 -270.03629)
		(width 0.0889)
		(layer "In4.Cu")
		(net "M_D_CPU1_SB_CB<6>")
	)
	(segment
		(start 85.93963 -269.708884)
		(end 85.948012 -269.71371)
		(width 0.0889)
		(layer "In4.Cu")
		(net "M_D_CPU1_SB_CB<6>")
	)
	(segment
		(start 90.639646 -269.708884)
		(end 90.648028 -269.71371)
		(width 0.0889)
		(layer "In4.Cu")
		(net "M_D_CPU1_SB_CB<6>")
	)
	(segment
		(start 33.356296 -272.560288)
		(end 33.51911 -272.397474)
		(width 0.14478)
		(layer "In4.Cu")
		(net "M_D_CPU1_SB_CB<6>")
	)
	(segment
		(start 33.120838 -272.560288)
		(end 33.356296 -272.560288)
		(width 0.14478)
		(layer "In4.Cu")
		(net "M_D_CPU1_SB_CB<6>")
	)
	(segment
		(start 35.18789 -271.807178)
		(end 35.18789 -272.397474)
		(width 0.14478)
		(layer "In4.Cu")
		(net "M_D_CPU1_SB_CB<6>")
	)
	(segment
		(start 35.74415 -271.95526)
		(end 35.906964 -271.792446)
		(width 0.14478)
		(layer "In4.Cu")
		(net "M_D_CPU1_SB_CB<6>")
	)
	(segment
		(start 64.776096 -268.051534)
		(end 75.974956 -268.051534)
		(width 0.14478)
		(layer "In4.Cu")
		(net "M_D_CPU1_SB_CB<6>")
	)
	(segment
		(start 37.986462 -272.560288)
		(end 38.836346 -271.710404)
		(width 0.14478)
		(layer "In4.Cu")
		(net "M_D_CPU1_SB_CB<6>")
	)
	(arc
		(start 80.874108 -269.71371)
		(mid 81.061052 -269.663455)
		(end 81.247996 -269.71371)
		(width 0.0889)
		(layer "In4.Cu")
		(net "M_D_CPU1_SB_CB<6>")
	)
	(arc
		(start 78.42758 -269.71371)
		(mid 78.701435 -269.79006)
		(end 78.977744 -269.723108)
		(width 0.0889)
		(layer "In4.Cu")
		(net "M_D_CPU1_SB_CB<6>")
	)
	(arc
		(start 89.334086 -269.71371)
		(mid 89.52103 -269.663455)
		(end 89.707974 -269.71371)
		(width 0.0889)
		(layer "In4.Cu")
		(net "M_D_CPU1_SB_CB<6>")
	)
	(arc
		(start 87.82812 -269.71371)
		(mid 88.111076 -269.789887)
		(end 88.394032 -269.71371)
		(width 0.0889)
		(layer "In4.Cu")
		(net "M_D_CPU1_SB_CB<6>")
	)
	(arc
		(start 83.702398 -269.708884)
		(mid 83.885906 -269.66339)
		(end 84.068158 -269.71371)
		(width 0.0889)
		(layer "In4.Cu")
		(net "M_D_CPU1_SB_CB<6>")
	)
	(arc
		(start 90.648028 -269.71371)
		(mid 90.895624 -269.788888)
		(end 91.150694 -269.74546)
		(width 0.0889)
		(layer "In4.Cu")
		(net "M_D_CPU1_SB_CB<6>")
	)
	(arc
		(start 81.813908 -269.71371)
		(mid 81.996159 -269.66336)
		(end 82.179668 -269.708884)
		(width 0.0889)
		(layer "In4.Cu")
		(net "M_D_CPU1_SB_CB<6>")
	)
	(arc
		(start 86.513924 -269.71371)
		(mid 86.696175 -269.66336)
		(end 86.879684 -269.708884)
		(width 0.0889)
		(layer "In4.Cu")
		(net "M_D_CPU1_SB_CB<6>")
	)
	(arc
		(start 79.942436 -269.708884)
		(mid 80.125944 -269.66339)
		(end 80.308196 -269.71371)
		(width 0.0889)
		(layer "In4.Cu")
		(net "M_D_CPU1_SB_CB<6>")
	)
	(arc
		(start 84.63407 -269.71371)
		(mid 84.821014 -269.663455)
		(end 85.007958 -269.71371)
		(width 0.0889)
		(layer "In4.Cu")
		(net "M_D_CPU1_SB_CB<6>")
	)
	(arc
		(start 82.18805 -269.71371)
		(mid 82.471006 -269.789887)
		(end 82.753962 -269.71371)
		(width 0.0889)
		(layer "In4.Cu")
		(net "M_D_CPU1_SB_CB<6>")
	)
	(arc
		(start 85.57387 -269.71371)
		(mid 85.756121 -269.66336)
		(end 85.93963 -269.708884)
		(width 0.0889)
		(layer "In4.Cu")
		(net "M_D_CPU1_SB_CB<6>")
	)
	(arc
		(start 78.312264 -269.625064)
		(mid 78.367049 -269.673124)
		(end 78.42758 -269.71371)
		(width 0.0889)
		(layer "In4.Cu")
		(net "M_D_CPU1_SB_CB<6>")
	)
	(arc
		(start 79.01178 -269.70355)
		(mid 79.191009 -269.663397)
		(end 79.367634 -269.71371)
		(width 0.0889)
		(layer "In4.Cu")
		(net "M_D_CPU1_SB_CB<6>")
	)
	(arc
		(start 86.888066 -269.71371)
		(mid 87.171022 -269.789887)
		(end 87.453978 -269.71371)
		(width 0.0889)
		(layer "In4.Cu")
		(net "M_D_CPU1_SB_CB<6>")
	)
	(arc
		(start 84.068158 -269.71371)
		(mid 84.351114 -269.789887)
		(end 84.63407 -269.71371)
		(width 0.0889)
		(layer "In4.Cu")
		(net "M_D_CPU1_SB_CB<6>")
	)
	(arc
		(start 90.273886 -269.71371)
		(mid 90.456137 -269.66336)
		(end 90.639646 -269.708884)
		(width 0.0889)
		(layer "In4.Cu")
		(net "M_D_CPU1_SB_CB<6>")
	)
	(arc
		(start 85.948012 -269.71371)
		(mid 86.230968 -269.789887)
		(end 86.513924 -269.71371)
		(width 0.0889)
		(layer "In4.Cu")
		(net "M_D_CPU1_SB_CB<6>")
	)
	(arc
		(start 85.007958 -269.71371)
		(mid 85.290914 -269.789887)
		(end 85.57387 -269.71371)
		(width 0.0889)
		(layer "In4.Cu")
		(net "M_D_CPU1_SB_CB<6>")
	)
	(arc
		(start 83.128104 -269.71371)
		(mid 83.41106 -269.789887)
		(end 83.694016 -269.71371)
		(width 0.0889)
		(layer "In4.Cu")
		(net "M_D_CPU1_SB_CB<6>")
	)
	(arc
		(start 89.707974 -269.71371)
		(mid 89.99093 -269.789887)
		(end 90.273886 -269.71371)
		(width 0.0889)
		(layer "In4.Cu")
		(net "M_D_CPU1_SB_CB<6>")
	)
	(arc
		(start 80.308196 -269.71371)
		(mid 80.591152 -269.789887)
		(end 80.874108 -269.71371)
		(width 0.0889)
		(layer "In4.Cu")
		(net "M_D_CPU1_SB_CB<6>")
	)
	(arc
		(start 87.46236 -269.708884)
		(mid 87.645868 -269.66339)
		(end 87.82812 -269.71371)
		(width 0.0889)
		(layer "In4.Cu")
		(net "M_D_CPU1_SB_CB<6>")
	)
	(arc
		(start 88.402414 -269.708884)
		(mid 88.585922 -269.66339)
		(end 88.768174 -269.71371)
		(width 0.0889)
		(layer "In4.Cu")
		(net "M_D_CPU1_SB_CB<6>")
	)
	(arc
		(start 88.768174 -269.71371)
		(mid 89.05113 -269.789887)
		(end 89.334086 -269.71371)
		(width 0.0889)
		(layer "In4.Cu")
		(net "M_D_CPU1_SB_CB<6>")
	)
	(arc
		(start 82.762344 -269.708884)
		(mid 82.945852 -269.66339)
		(end 83.128104 -269.71371)
		(width 0.0889)
		(layer "In4.Cu")
		(net "M_D_CPU1_SB_CB<6>")
	)
	(arc
		(start 81.247996 -269.71371)
		(mid 81.530952 -269.789887)
		(end 81.813908 -269.71371)
		(width 0.0889)
		(layer "In4.Cu")
		(net "M_D_CPU1_SB_CB<6>")
	)
	(arc
		(start 79.367634 -269.71371)
		(mid 79.64234 -269.790074)
		(end 79.919322 -269.722346)
		(width 0.0889)
		(layer "In4.Cu")
		(net "M_D_CPU1_SB_CB<6>")
	)
	(segment
		(start 92.80779 -269.770352)
		(end 92.340938 -270.03629)
		(width 0.10668)
		(layer "F.Cu")
		(net "M_D_CPU1_SB_CB<5>")
	)
	(segment
		(start 45.40631 -272.77695)
		(end 45.40631 -272.343626)
		(width 0.14478)
		(layer "In4.Cu")
		(net "M_D_CPU1_SB_CB<5>")
	)
	(segment
		(start 92.472764 -270.385032)
		(end 92.495116 -270.30172)
		(width 0.0889)
		(layer "In4.Cu")
		(net "M_D_CPU1_SB_CB<5>")
	)
	(segment
		(start 64.957452 -268.506194)
		(end 75.947016 -268.506194)
		(width 0.14478)
		(layer "In4.Cu")
		(net "M_D_CPU1_SB_CB<5>")
	)
	(segment
		(start 49.66843 -272.939764)
		(end 49.899062 -272.939764)
		(width 0.14478)
		(layer "In4.Cu")
		(net "M_D_CPU1_SB_CB<5>")
	)
	(segment
		(start 45.569124 -272.180812)
		(end 45.799756 -272.180812)
		(width 0.14478)
		(layer "In4.Cu")
		(net "M_D_CPU1_SB_CB<5>")
	)
	(segment
		(start 45.012864 -272.939764)
		(end 45.243496 -272.939764)
		(width 0.14478)
		(layer "In4.Cu")
		(net "M_D_CPU1_SB_CB<5>")
	)
	(segment
		(start 41.53916 -272.4912)
		(end 41.701974 -272.328386)
		(width 0.14478)
		(layer "In4.Cu")
		(net "M_D_CPU1_SB_CB<5>")
	)
	(segment
		(start 77.02423 -268.807946)
		(end 78.114906 -269.898622)
		(width 0.0889)
		(layer "In4.Cu")
		(net "M_D_CPU1_SB_CB<5>")
	)
	(segment
		(start 86.879684 -270.363696)
		(end 86.888066 -270.35887)
		(width 0.0889)
		(layer "In4.Cu")
		(net "M_D_CPU1_SB_CB<5>")
	)
	(segment
		(start 46.51883 -272.77695)
		(end 46.51883 -272.343626)
		(width 0.14478)
		(layer "In4.Cu")
		(net "M_D_CPU1_SB_CB<5>")
	)
	(segment
		(start 85.93963 -270.363696)
		(end 85.948012 -270.35887)
		(width 0.0889)
		(layer "In4.Cu")
		(net "M_D_CPU1_SB_CB<5>")
	)
	(segment
		(start 50.455322 -272.180812)
		(end 50.618136 -272.343626)
		(width 0.14478)
		(layer "In4.Cu")
		(net "M_D_CPU1_SB_CB<5>")
	)
	(segment
		(start 45.243496 -272.939764)
		(end 45.40631 -272.77695)
		(width 0.14478)
		(layer "In4.Cu")
		(net "M_D_CPU1_SB_CB<5>")
	)
	(segment
		(start 46.912276 -272.180812)
		(end 47.291752 -272.560288)
		(width 0.14478)
		(layer "In4.Cu")
		(net "M_D_CPU1_SB_CB<5>")
	)
	(segment
		(start 46.681644 -272.180812)
		(end 46.912276 -272.180812)
		(width 0.14478)
		(layer "In4.Cu")
		(net "M_D_CPU1_SB_CB<5>")
	)
	(segment
		(start 92.495116 -270.30172)
		(end 92.340938 -270.03629)
		(width 0.0889)
		(layer "In4.Cu")
		(net "M_D_CPU1_SB_CB<5>")
	)
	(segment
		(start 92.153994 -270.35887)
		(end 92.162376 -270.363696)
		(width 0.0889)
		(layer "In4.Cu")
		(net "M_D_CPU1_SB_CB<5>")
	)
	(segment
		(start 51.011582 -272.939764)
		(end 51.391058 -272.560288)
		(width 0.14478)
		(layer "In4.Cu")
		(net "M_D_CPU1_SB_CB<5>")
	)
	(segment
		(start 41.376346 -272.939764)
		(end 41.53916 -272.77695)
		(width 0.14478)
		(layer "In4.Cu")
		(net "M_D_CPU1_SB_CB<5>")
	)
	(segment
		(start 76.60259 -268.807946)
		(end 77.02423 -268.807946)
		(width 0.0889)
		(layer "In4.Cu")
		(net "M_D_CPU1_SB_CB<5>")
	)
	(segment
		(start 50.061876 -272.77695)
		(end 50.061876 -272.343626)
		(width 0.14478)
		(layer "In4.Cu")
		(net "M_D_CPU1_SB_CB<5>")
	)
	(segment
		(start 50.618136 -272.343626)
		(end 50.618136 -272.77695)
		(width 0.14478)
		(layer "In4.Cu")
		(net "M_D_CPU1_SB_CB<5>")
	)
	(segment
		(start 42.258234 -272.939764)
		(end 42.488866 -272.939764)
		(width 0.14478)
		(layer "In4.Cu")
		(net "M_D_CPU1_SB_CB<5>")
	)
	(segment
		(start 41.932606 -272.328386)
		(end 42.09542 -272.4912)
		(width 0.14478)
		(layer "In4.Cu")
		(net "M_D_CPU1_SB_CB<5>")
	)
	(segment
		(start 75.947016 -268.506194)
		(end 76.300838 -268.506194)
		(width 0.0889)
		(layer "In4.Cu")
		(net "M_D_CPU1_SB_CB<5>")
	)
	(segment
		(start 43.045126 -272.384266)
		(end 43.20794 -272.54708)
		(width 0.14478)
		(layer "In4.Cu")
		(net "M_D_CPU1_SB_CB<5>")
	)
	(segment
		(start 83.694016 -270.35887)
		(end 83.702398 -270.363696)
		(width 0.0889)
		(layer "In4.Cu")
		(net "M_D_CPU1_SB_CB<5>")
	)
	(segment
		(start 80.299814 -270.363696)
		(end 80.308196 -270.35887)
		(width 0.0889)
		(layer "In4.Cu")
		(net "M_D_CPU1_SB_CB<5>")
	)
	(segment
		(start 76.300838 -268.506194)
		(end 76.60259 -268.807946)
		(width 0.0889)
		(layer "In4.Cu")
		(net "M_D_CPU1_SB_CB<5>")
	)
	(segment
		(start 44.633388 -272.560288)
		(end 45.012864 -272.939764)
		(width 0.14478)
		(layer "In4.Cu")
		(net "M_D_CPU1_SB_CB<5>")
	)
	(segment
		(start 50.78095 -272.939764)
		(end 51.011582 -272.939764)
		(width 0.14478)
		(layer "In4.Cu")
		(net "M_D_CPU1_SB_CB<5>")
	)
	(segment
		(start 50.618136 -272.77695)
		(end 50.78095 -272.939764)
		(width 0.14478)
		(layer "In4.Cu")
		(net "M_D_CPU1_SB_CB<5>")
	)
	(segment
		(start 43.601386 -272.939764)
		(end 43.980862 -272.560288)
		(width 0.14478)
		(layer "In4.Cu")
		(net "M_D_CPU1_SB_CB<5>")
	)
	(segment
		(start 40.766238 -272.560288)
		(end 41.145714 -272.939764)
		(width 0.14478)
		(layer "In4.Cu")
		(net "M_D_CPU1_SB_CB<5>")
	)
	(segment
		(start 36.795964 -273.835368)
		(end 37.220906 -273.410426)
		(width 0.14478)
		(layer "In4.Cu")
		(net "M_D_CPU1_SB_CB<5>")
	)
	(segment
		(start 42.814494 -272.384266)
		(end 43.045126 -272.384266)
		(width 0.14478)
		(layer "In4.Cu")
		(net "M_D_CPU1_SB_CB<5>")
	)
	(segment
		(start 82.179668 -270.363696)
		(end 82.18805 -270.35887)
		(width 0.0889)
		(layer "In4.Cu")
		(net "M_D_CPU1_SB_CB<5>")
	)
	(segment
		(start 49.505616 -272.77695)
		(end 49.66843 -272.939764)
		(width 0.14478)
		(layer "In4.Cu")
		(net "M_D_CPU1_SB_CB<5>")
	)
	(segment
		(start 46.51883 -272.343626)
		(end 46.681644 -272.180812)
		(width 0.14478)
		(layer "In4.Cu")
		(net "M_D_CPU1_SB_CB<5>")
	)
	(segment
		(start 48.949356 -272.77695)
		(end 48.949356 -272.343626)
		(width 0.14478)
		(layer "In4.Cu")
		(net "M_D_CPU1_SB_CB<5>")
	)
	(segment
		(start 43.20794 -272.54708)
		(end 43.20794 -272.77695)
		(width 0.14478)
		(layer "In4.Cu")
		(net "M_D_CPU1_SB_CB<5>")
	)
	(segment
		(start 45.40631 -272.343626)
		(end 45.569124 -272.180812)
		(width 0.14478)
		(layer "In4.Cu")
		(net "M_D_CPU1_SB_CB<5>")
	)
	(segment
		(start 49.342802 -272.180812)
		(end 49.505616 -272.343626)
		(width 0.14478)
		(layer "In4.Cu")
		(net "M_D_CPU1_SB_CB<5>")
	)
	(segment
		(start 45.96257 -272.343626)
		(end 45.96257 -272.77695)
		(width 0.14478)
		(layer "In4.Cu")
		(net "M_D_CPU1_SB_CB<5>")
	)
	(segment
		(start 41.53916 -272.77695)
		(end 41.53916 -272.4912)
		(width 0.14478)
		(layer "In4.Cu")
		(net "M_D_CPU1_SB_CB<5>")
	)
	(segment
		(start 51.391058 -272.560288)
		(end 60.903358 -272.560288)
		(width 0.14478)
		(layer "In4.Cu")
		(net "M_D_CPU1_SB_CB<5>")
	)
	(segment
		(start 42.488866 -272.939764)
		(end 42.65168 -272.77695)
		(width 0.14478)
		(layer "In4.Cu")
		(net "M_D_CPU1_SB_CB<5>")
	)
	(segment
		(start 45.799756 -272.180812)
		(end 45.96257 -272.343626)
		(width 0.14478)
		(layer "In4.Cu")
		(net "M_D_CPU1_SB_CB<5>")
	)
	(segment
		(start 42.65168 -272.54708)
		(end 42.814494 -272.384266)
		(width 0.14478)
		(layer "In4.Cu")
		(net "M_D_CPU1_SB_CB<5>")
	)
	(segment
		(start 48.786542 -272.939764)
		(end 48.949356 -272.77695)
		(width 0.14478)
		(layer "In4.Cu")
		(net "M_D_CPU1_SB_CB<5>")
	)
	(segment
		(start 43.980862 -272.560288)
		(end 44.633388 -272.560288)
		(width 0.14478)
		(layer "In4.Cu")
		(net "M_D_CPU1_SB_CB<5>")
	)
	(segment
		(start 48.949356 -272.343626)
		(end 49.11217 -272.180812)
		(width 0.14478)
		(layer "In4.Cu")
		(net "M_D_CPU1_SB_CB<5>")
	)
	(segment
		(start 42.65168 -272.77695)
		(end 42.65168 -272.54708)
		(width 0.14478)
		(layer "In4.Cu")
		(net "M_D_CPU1_SB_CB<5>")
	)
	(segment
		(start 60.903358 -272.560288)
		(end 64.957452 -268.506194)
		(width 0.14478)
		(layer "In4.Cu")
		(net "M_D_CPU1_SB_CB<5>")
	)
	(segment
		(start 91.5797 -270.363696)
		(end 91.588082 -270.35887)
		(width 0.0889)
		(layer "In4.Cu")
		(net "M_D_CPU1_SB_CB<5>")
	)
	(segment
		(start 48.55591 -272.939764)
		(end 48.786542 -272.939764)
		(width 0.14478)
		(layer "In4.Cu")
		(net "M_D_CPU1_SB_CB<5>")
	)
	(segment
		(start 87.453978 -270.35887)
		(end 87.46236 -270.363696)
		(width 0.0889)
		(layer "In4.Cu")
		(net "M_D_CPU1_SB_CB<5>")
	)
	(segment
		(start 37.220906 -273.410426)
		(end 38.406578 -273.410426)
		(width 0.14478)
		(layer "In4.Cu")
		(net "M_D_CPU1_SB_CB<5>")
	)
	(segment
		(start 50.061876 -272.343626)
		(end 50.22469 -272.180812)
		(width 0.14478)
		(layer "In4.Cu")
		(net "M_D_CPU1_SB_CB<5>")
	)
	(segment
		(start 49.899062 -272.939764)
		(end 50.061876 -272.77695)
		(width 0.14478)
		(layer "In4.Cu")
		(net "M_D_CPU1_SB_CB<5>")
	)
	(segment
		(start 38.406578 -273.410426)
		(end 39.256716 -272.560288)
		(width 0.14478)
		(layer "In4.Cu")
		(net "M_D_CPU1_SB_CB<5>")
	)
	(segment
		(start 43.20794 -272.77695)
		(end 43.370754 -272.939764)
		(width 0.14478)
		(layer "In4.Cu")
		(net "M_D_CPU1_SB_CB<5>")
	)
	(segment
		(start 43.370754 -272.939764)
		(end 43.601386 -272.939764)
		(width 0.14478)
		(layer "In4.Cu")
		(net "M_D_CPU1_SB_CB<5>")
	)
	(segment
		(start 88.394032 -270.35887)
		(end 88.402414 -270.363696)
		(width 0.0889)
		(layer "In4.Cu")
		(net "M_D_CPU1_SB_CB<5>")
	)
	(segment
		(start 78.737714 -270.156686)
		(end 79.183738 -270.156686)
		(width 0.0889)
		(layer "In4.Cu")
		(net "M_D_CPU1_SB_CB<5>")
	)
	(segment
		(start 41.701974 -272.328386)
		(end 41.932606 -272.328386)
		(width 0.14478)
		(layer "In4.Cu")
		(net "M_D_CPU1_SB_CB<5>")
	)
	(segment
		(start 42.09542 -272.77695)
		(end 42.258234 -272.939764)
		(width 0.14478)
		(layer "In4.Cu")
		(net "M_D_CPU1_SB_CB<5>")
	)
	(segment
		(start 46.125384 -272.939764)
		(end 46.356016 -272.939764)
		(width 0.14478)
		(layer "In4.Cu")
		(net "M_D_CPU1_SB_CB<5>")
	)
	(segment
		(start 41.145714 -272.939764)
		(end 41.376346 -272.939764)
		(width 0.14478)
		(layer "In4.Cu")
		(net "M_D_CPU1_SB_CB<5>")
	)
	(segment
		(start 45.96257 -272.77695)
		(end 46.125384 -272.939764)
		(width 0.14478)
		(layer "In4.Cu")
		(net "M_D_CPU1_SB_CB<5>")
	)
	(segment
		(start 39.256716 -272.560288)
		(end 40.766238 -272.560288)
		(width 0.14478)
		(layer "In4.Cu")
		(net "M_D_CPU1_SB_CB<5>")
	)
	(segment
		(start 42.09542 -272.4912)
		(end 42.09542 -272.77695)
		(width 0.14478)
		(layer "In4.Cu")
		(net "M_D_CPU1_SB_CB<5>")
	)
	(segment
		(start 49.505616 -272.343626)
		(end 49.505616 -272.77695)
		(width 0.14478)
		(layer "In4.Cu")
		(net "M_D_CPU1_SB_CB<5>")
	)
	(segment
		(start 46.356016 -272.939764)
		(end 46.51883 -272.77695)
		(width 0.14478)
		(layer "In4.Cu")
		(net "M_D_CPU1_SB_CB<5>")
	)
	(segment
		(start 90.639646 -270.363696)
		(end 90.648028 -270.35887)
		(width 0.0889)
		(layer "In4.Cu")
		(net "M_D_CPU1_SB_CB<5>")
	)
	(segment
		(start 82.753962 -270.35887)
		(end 82.762344 -270.363696)
		(width 0.0889)
		(layer "In4.Cu")
		(net "M_D_CPU1_SB_CB<5>")
	)
	(segment
		(start 48.176434 -272.560288)
		(end 48.55591 -272.939764)
		(width 0.14478)
		(layer "In4.Cu")
		(net "M_D_CPU1_SB_CB<5>")
	)
	(segment
		(start 47.291752 -272.560288)
		(end 48.176434 -272.560288)
		(width 0.14478)
		(layer "In4.Cu")
		(net "M_D_CPU1_SB_CB<5>")
	)
	(segment
		(start 49.11217 -272.180812)
		(end 49.342802 -272.180812)
		(width 0.14478)
		(layer "In4.Cu")
		(net "M_D_CPU1_SB_CB<5>")
	)
	(segment
		(start 50.22469 -272.180812)
		(end 50.455322 -272.180812)
		(width 0.14478)
		(layer "In4.Cu")
		(net "M_D_CPU1_SB_CB<5>")
	)
	(arc
		(start 90.648028 -270.35887)
		(mid 90.930984 -270.282693)
		(end 91.21394 -270.35887)
		(width 0.0889)
		(layer "In4.Cu")
		(net "M_D_CPU1_SB_CB<5>")
	)
	(arc
		(start 85.948012 -270.35887)
		(mid 86.230968 -270.282693)
		(end 86.513924 -270.35887)
		(width 0.0889)
		(layer "In4.Cu")
		(net "M_D_CPU1_SB_CB<5>")
	)
	(arc
		(start 81.813908 -270.35887)
		(mid 81.996159 -270.40922)
		(end 82.179668 -270.363696)
		(width 0.0889)
		(layer "In4.Cu")
		(net "M_D_CPU1_SB_CB<5>")
	)
	(arc
		(start 92.162376 -270.363696)
		(mid 92.315246 -270.408337)
		(end 92.472764 -270.385032)
		(width 0.0889)
		(layer "In4.Cu")
		(net "M_D_CPU1_SB_CB<5>")
	)
	(arc
		(start 83.702398 -270.363696)
		(mid 83.885906 -270.40919)
		(end 84.068158 -270.35887)
		(width 0.0889)
		(layer "In4.Cu")
		(net "M_D_CPU1_SB_CB<5>")
	)
	(arc
		(start 90.273886 -270.35887)
		(mid 90.456137 -270.40922)
		(end 90.639646 -270.363696)
		(width 0.0889)
		(layer "In4.Cu")
		(net "M_D_CPU1_SB_CB<5>")
	)
	(arc
		(start 87.82812 -270.35887)
		(mid 88.111076 -270.282693)
		(end 88.394032 -270.35887)
		(width 0.0889)
		(layer "In4.Cu")
		(net "M_D_CPU1_SB_CB<5>")
	)
	(arc
		(start 91.588082 -270.35887)
		(mid 91.871038 -270.282693)
		(end 92.153994 -270.35887)
		(width 0.0889)
		(layer "In4.Cu")
		(net "M_D_CPU1_SB_CB<5>")
	)
	(arc
		(start 80.308196 -270.35887)
		(mid 80.591152 -270.282693)
		(end 80.874108 -270.35887)
		(width 0.0889)
		(layer "In4.Cu")
		(net "M_D_CPU1_SB_CB<5>")
	)
	(arc
		(start 85.57387 -270.35887)
		(mid 85.756121 -270.40922)
		(end 85.93963 -270.363696)
		(width 0.0889)
		(layer "In4.Cu")
		(net "M_D_CPU1_SB_CB<5>")
	)
	(arc
		(start 88.402414 -270.363696)
		(mid 88.585922 -270.40919)
		(end 88.768174 -270.35887)
		(width 0.0889)
		(layer "In4.Cu")
		(net "M_D_CPU1_SB_CB<5>")
	)
	(arc
		(start 78.114906 -269.898622)
		(mid 78.400638 -270.089606)
		(end 78.737714 -270.156686)
		(width 0.0889)
		(layer "In4.Cu")
		(net "M_D_CPU1_SB_CB<5>")
	)
	(arc
		(start 87.46236 -270.363696)
		(mid 87.645868 -270.40919)
		(end 87.82812 -270.35887)
		(width 0.0889)
		(layer "In4.Cu")
		(net "M_D_CPU1_SB_CB<5>")
	)
	(arc
		(start 81.247996 -270.35887)
		(mid 81.530952 -270.282693)
		(end 81.813908 -270.35887)
		(width 0.0889)
		(layer "In4.Cu")
		(net "M_D_CPU1_SB_CB<5>")
	)
	(arc
		(start 84.068158 -270.35887)
		(mid 84.351114 -270.282693)
		(end 84.63407 -270.35887)
		(width 0.0889)
		(layer "In4.Cu")
		(net "M_D_CPU1_SB_CB<5>")
	)
	(arc
		(start 91.21394 -270.35887)
		(mid 91.396191 -270.40922)
		(end 91.5797 -270.363696)
		(width 0.0889)
		(layer "In4.Cu")
		(net "M_D_CPU1_SB_CB<5>")
	)
	(arc
		(start 79.183738 -270.156686)
		(mid 79.572029 -270.208125)
		(end 79.933546 -270.35887)
		(width 0.0889)
		(layer "In4.Cu")
		(net "M_D_CPU1_SB_CB<5>")
	)
	(arc
		(start 84.63407 -270.35887)
		(mid 84.821014 -270.409125)
		(end 85.007958 -270.35887)
		(width 0.0889)
		(layer "In4.Cu")
		(net "M_D_CPU1_SB_CB<5>")
	)
	(arc
		(start 80.874108 -270.35887)
		(mid 81.061052 -270.409125)
		(end 81.247996 -270.35887)
		(width 0.0889)
		(layer "In4.Cu")
		(net "M_D_CPU1_SB_CB<5>")
	)
	(arc
		(start 89.707974 -270.35887)
		(mid 89.99093 -270.282693)
		(end 90.273886 -270.35887)
		(width 0.0889)
		(layer "In4.Cu")
		(net "M_D_CPU1_SB_CB<5>")
	)
	(arc
		(start 89.334086 -270.35887)
		(mid 89.52103 -270.409125)
		(end 89.707974 -270.35887)
		(width 0.0889)
		(layer "In4.Cu")
		(net "M_D_CPU1_SB_CB<5>")
	)
	(arc
		(start 86.513924 -270.35887)
		(mid 86.696175 -270.40922)
		(end 86.879684 -270.363696)
		(width 0.0889)
		(layer "In4.Cu")
		(net "M_D_CPU1_SB_CB<5>")
	)
	(arc
		(start 85.007958 -270.35887)
		(mid 85.290914 -270.282693)
		(end 85.57387 -270.35887)
		(width 0.0889)
		(layer "In4.Cu")
		(net "M_D_CPU1_SB_CB<5>")
	)
	(arc
		(start 83.128104 -270.35887)
		(mid 83.41106 -270.282693)
		(end 83.694016 -270.35887)
		(width 0.0889)
		(layer "In4.Cu")
		(net "M_D_CPU1_SB_CB<5>")
	)
	(arc
		(start 82.762344 -270.363696)
		(mid 82.945852 -270.40919)
		(end 83.128104 -270.35887)
		(width 0.0889)
		(layer "In4.Cu")
		(net "M_D_CPU1_SB_CB<5>")
	)
	(arc
		(start 86.888066 -270.35887)
		(mid 87.171022 -270.282693)
		(end 87.453978 -270.35887)
		(width 0.0889)
		(layer "In4.Cu")
		(net "M_D_CPU1_SB_CB<5>")
	)
	(arc
		(start 88.768174 -270.35887)
		(mid 89.05113 -270.282693)
		(end 89.334086 -270.35887)
		(width 0.0889)
		(layer "In4.Cu")
		(net "M_D_CPU1_SB_CB<5>")
	)
	(arc
		(start 79.933546 -270.35887)
		(mid 80.116051 -270.409347)
		(end 80.299814 -270.363696)
		(width 0.0889)
		(layer "In4.Cu")
		(net "M_D_CPU1_SB_CB<5>")
	)
	(arc
		(start 82.18805 -270.35887)
		(mid 82.471006 -270.282693)
		(end 82.753962 -270.35887)
		(width 0.0889)
		(layer "In4.Cu")
		(net "M_D_CPU1_SB_CB<5>")
	)
	(segment
		(start 91.397836 -268.960346)
		(end 90.930984 -269.226284)
		(width 0.10668)
		(layer "F.Cu")
		(net "M_D_CPU1_SB_CB<4>")
	)
	(segment
		(start 37.120322 -271.810988)
		(end 37.567362 -271.810988)
		(width 0.14478)
		(layer "In4.Cu")
		(net "M_D_CPU1_SB_CB<4>")
	)
	(segment
		(start 78.897734 -269.54861)
		(end 78.913482 -269.539466)
		(width 0.0889)
		(layer "In4.Cu")
		(net "M_D_CPU1_SB_CB<4>")
	)
	(segment
		(start 78.879446 -269.559024)
		(end 78.897734 -269.54861)
		(width 0.0889)
		(layer "In4.Cu")
		(net "M_D_CPU1_SB_CB<4>")
	)
	(segment
		(start 37.567362 -271.810988)
		(end 37.737288 -271.641062)
		(width 0.14478)
		(layer "In4.Cu")
		(net "M_D_CPU1_SB_CB<4>")
	)
	(segment
		(start 56.450992 -270.860266)
		(end 56.705754 -270.860266)
		(width 0.14478)
		(layer "In4.Cu")
		(net "M_D_CPU1_SB_CB<4>")
	)
	(segment
		(start 55.593234 -270.860266)
		(end 55.894732 -271.161764)
		(width 0.14478)
		(layer "In4.Cu")
		(net "M_D_CPU1_SB_CB<4>")
	)
	(segment
		(start 53.368194 -270.860266)
		(end 53.669692 -271.161764)
		(width 0.14478)
		(layer "In4.Cu")
		(net "M_D_CPU1_SB_CB<4>")
	)
	(segment
		(start 57.262014 -271.161764)
		(end 57.563512 -270.860266)
		(width 0.14478)
		(layer "In4.Cu")
		(net "M_D_CPU1_SB_CB<4>")
	)
	(segment
		(start 61.968888 -269.564104)
		(end 61.968888 -269.335504)
		(width 0.14478)
		(layer "In4.Cu")
		(net "M_D_CPU1_SB_CB<4>")
	)
	(segment
		(start 61.402722 -270.558514)
		(end 61.1886 -270.344392)
		(width 0.14478)
		(layer "In4.Cu")
		(net "M_D_CPU1_SB_CB<4>")
	)
	(segment
		(start 86.044024 -269.548864)
		(end 86.052406 -269.55369)
		(width 0.0889)
		(layer "In4.Cu")
		(net "M_D_CPU1_SB_CB<4>")
	)
	(segment
		(start 62.801754 -269.388082)
		(end 62.963298 -269.226538)
		(width 0.14478)
		(layer "In4.Cu")
		(net "M_D_CPU1_SB_CB<4>")
	)
	(segment
		(start 53.669692 -271.161764)
		(end 53.924454 -271.161764)
		(width 0.14478)
		(layer "In4.Cu")
		(net "M_D_CPU1_SB_CB<4>")
	)
	(segment
		(start 62.749176 -268.783816)
		(end 62.749176 -268.555216)
		(width 0.14478)
		(layer "In4.Cu")
		(net "M_D_CPU1_SB_CB<4>")
	)
	(segment
		(start 41.870884 -270.860266)
		(end 42.172382 -271.161764)
		(width 0.14478)
		(layer "In4.Cu")
		(net "M_D_CPU1_SB_CB<4>")
	)
	(segment
		(start 90.74404 -269.548864)
		(end 90.752422 -269.55369)
		(width 0.0889)
		(layer "In4.Cu")
		(net "M_D_CPU1_SB_CB<4>")
	)
	(segment
		(start 41.616122 -270.860266)
		(end 41.870884 -270.860266)
		(width 0.14478)
		(layer "In4.Cu")
		(net "M_D_CPU1_SB_CB<4>")
	)
	(segment
		(start 48.194214 -270.860266)
		(end 48.495712 -271.161764)
		(width 0.14478)
		(layer "In4.Cu")
		(net "M_D_CPU1_SB_CB<4>")
	)
	(segment
		(start 62.021466 -270.16837)
		(end 62.18301 -270.006826)
		(width 0.14478)
		(layer "In4.Cu")
		(net "M_D_CPU1_SB_CB<4>")
	)
	(segment
		(start 60.444126 -270.860266)
		(end 60.569856 -270.734536)
		(width 0.14478)
		(layer "In4.Cu")
		(net "M_D_CPU1_SB_CB<4>")
	)
	(segment
		(start 46.952662 -270.860266)
		(end 48.194214 -270.860266)
		(width 0.14478)
		(layer "In4.Cu")
		(net "M_D_CPU1_SB_CB<4>")
	)
	(segment
		(start 61.241178 -270.948658)
		(end 61.402722 -270.787114)
		(width 0.14478)
		(layer "In4.Cu")
		(net "M_D_CPU1_SB_CB<4>")
	)
	(segment
		(start 58.374534 -271.161764)
		(end 58.676032 -270.860266)
		(width 0.14478)
		(layer "In4.Cu")
		(net "M_D_CPU1_SB_CB<4>")
	)
	(segment
		(start 81.344008 -269.548864)
		(end 81.35239 -269.55369)
		(width 0.0889)
		(layer "In4.Cu")
		(net "M_D_CPU1_SB_CB<4>")
	)
	(segment
		(start 91.06281 -269.575026)
		(end 91.085162 -269.491714)
		(width 0.0889)
		(layer "In4.Cu")
		(net "M_D_CPU1_SB_CB<4>")
	)
	(segment
		(start 39.057326 -271.161764)
		(end 39.358824 -270.860266)
		(width 0.14478)
		(layer "In4.Cu")
		(net "M_D_CPU1_SB_CB<4>")
	)
	(segment
		(start 45.840142 -270.860266)
		(end 46.094904 -270.860266)
		(width 0.14478)
		(layer "In4.Cu")
		(net "M_D_CPU1_SB_CB<4>")
	)
	(segment
		(start 36.795964 -272.135346)
		(end 37.120322 -271.810988)
		(width 0.14478)
		(layer "In4.Cu")
		(net "M_D_CPU1_SB_CB<4>")
	)
	(segment
		(start 50.419254 -270.860266)
		(end 50.720752 -271.161764)
		(width 0.14478)
		(layer "In4.Cu")
		(net "M_D_CPU1_SB_CB<4>")
	)
	(segment
		(start 52.811934 -271.161764)
		(end 53.113432 -270.860266)
		(width 0.14478)
		(layer "In4.Cu")
		(net "M_D_CPU1_SB_CB<4>")
	)
	(segment
		(start 63.529464 -268.003528)
		(end 63.529464 -267.774928)
		(width 0.14478)
		(layer "In4.Cu")
		(net "M_D_CPU1_SB_CB<4>")
	)
	(segment
		(start 52.557172 -271.161764)
		(end 52.811934 -271.161764)
		(width 0.14478)
		(layer "In4.Cu")
		(net "M_D_CPU1_SB_CB<4>")
	)
	(segment
		(start 62.359032 -269.17396)
		(end 62.573154 -269.388082)
		(width 0.14478)
		(layer "In4.Cu")
		(net "M_D_CPU1_SB_CB<4>")
	)
	(segment
		(start 41.314624 -271.161764)
		(end 41.616122 -270.860266)
		(width 0.14478)
		(layer "In4.Cu")
		(net "M_D_CPU1_SB_CB<4>")
	)
	(segment
		(start 89.229692 -269.55369)
		(end 89.238074 -269.548864)
		(width 0.0889)
		(layer "In4.Cu")
		(net "M_D_CPU1_SB_CB<4>")
	)
	(segment
		(start 57.563512 -270.860266)
		(end 57.818274 -270.860266)
		(width 0.14478)
		(layer "In4.Cu")
		(net "M_D_CPU1_SB_CB<4>")
	)
	(segment
		(start 46.396402 -271.161764)
		(end 46.651164 -271.161764)
		(width 0.14478)
		(layer "In4.Cu")
		(net "M_D_CPU1_SB_CB<4>")
	)
	(segment
		(start 61.1886 -270.344392)
		(end 61.1886 -270.115792)
		(width 0.14478)
		(layer "In4.Cu")
		(net "M_D_CPU1_SB_CB<4>")
	)
	(segment
		(start 55.036974 -271.161764)
		(end 55.338472 -270.860266)
		(width 0.14478)
		(layer "In4.Cu")
		(net "M_D_CPU1_SB_CB<4>")
	)
	(segment
		(start 54.225952 -270.860266)
		(end 54.480714 -270.860266)
		(width 0.14478)
		(layer "In4.Cu")
		(net "M_D_CPU1_SB_CB<4>")
	)
	(segment
		(start 88.289638 -269.55369)
		(end 88.29802 -269.548864)
		(width 0.0889)
		(layer "In4.Cu")
		(net "M_D_CPU1_SB_CB<4>")
	)
	(segment
		(start 56.149494 -271.161764)
		(end 56.450992 -270.860266)
		(width 0.14478)
		(layer "In4.Cu")
		(net "M_D_CPU1_SB_CB<4>")
	)
	(segment
		(start 89.803986 -269.548864)
		(end 89.812368 -269.55369)
		(width 0.0889)
		(layer "In4.Cu")
		(net "M_D_CPU1_SB_CB<4>")
	)
	(segment
		(start 48.495712 -271.161764)
		(end 48.750474 -271.161764)
		(width 0.14478)
		(layer "In4.Cu")
		(net "M_D_CPU1_SB_CB<4>")
	)
	(segment
		(start 62.130432 -269.17396)
		(end 62.359032 -269.17396)
		(width 0.14478)
		(layer "In4.Cu")
		(net "M_D_CPU1_SB_CB<4>")
	)
	(segment
		(start 43.284902 -271.161764)
		(end 43.539664 -271.161764)
		(width 0.14478)
		(layer "In4.Cu")
		(net "M_D_CPU1_SB_CB<4>")
	)
	(segment
		(start 39.358824 -270.860266)
		(end 40.758364 -270.860266)
		(width 0.14478)
		(layer "In4.Cu")
		(net "M_D_CPU1_SB_CB<4>")
	)
	(segment
		(start 61.350144 -269.954248)
		(end 61.578744 -269.954248)
		(width 0.14478)
		(layer "In4.Cu")
		(net "M_D_CPU1_SB_CB<4>")
	)
	(segment
		(start 83.589622 -269.55369)
		(end 83.598004 -269.548864)
		(width 0.0889)
		(layer "In4.Cu")
		(net "M_D_CPU1_SB_CB<4>")
	)
	(segment
		(start 63.707518 -267.596874)
		(end 75.969876 -267.596874)
		(width 0.14478)
		(layer "In4.Cu")
		(net "M_D_CPU1_SB_CB<4>")
	)
	(segment
		(start 53.113432 -270.860266)
		(end 53.368194 -270.860266)
		(width 0.14478)
		(layer "In4.Cu")
		(net "M_D_CPU1_SB_CB<4>")
	)
	(segment
		(start 78.05547 -268.162786)
		(end 78.05547 -269.098776)
		(width 0.0889)
		(layer "In4.Cu")
		(net "M_D_CPU1_SB_CB<4>")
	)
	(segment
		(start 78.523338 -269.548864)
		(end 78.523592 -269.548864)
		(width 0.0889)
		(layer "In4.Cu")
		(net "M_D_CPU1_SB_CB<4>")
	)
	(segment
		(start 58.676032 -270.860266)
		(end 60.444126 -270.860266)
		(width 0.14478)
		(layer "In4.Cu")
		(net "M_D_CPU1_SB_CB<4>")
	)
	(segment
		(start 63.582042 -268.607794)
		(end 63.743586 -268.44625)
		(width 0.14478)
		(layer "In4.Cu")
		(net "M_D_CPU1_SB_CB<4>")
	)
	(segment
		(start 61.012578 -270.948658)
		(end 61.241178 -270.948658)
		(width 0.14478)
		(layer "In4.Cu")
		(net "M_D_CPU1_SB_CB<4>")
	)
	(segment
		(start 63.743586 -268.44625)
		(end 63.743586 -268.21765)
		(width 0.14478)
		(layer "In4.Cu")
		(net "M_D_CPU1_SB_CB<4>")
	)
	(segment
		(start 44.982384 -270.860266)
		(end 45.283882 -271.161764)
		(width 0.14478)
		(layer "In4.Cu")
		(net "M_D_CPU1_SB_CB<4>")
	)
	(segment
		(start 51.277012 -270.860266)
		(end 52.255674 -270.860266)
		(width 0.14478)
		(layer "In4.Cu")
		(net "M_D_CPU1_SB_CB<4>")
	)
	(segment
		(start 62.963298 -269.226538)
		(end 62.963298 -268.997938)
		(width 0.14478)
		(layer "In4.Cu")
		(net "M_D_CPU1_SB_CB<4>")
	)
	(segment
		(start 40.758364 -270.860266)
		(end 41.059862 -271.161764)
		(width 0.14478)
		(layer "In4.Cu")
		(net "M_D_CPU1_SB_CB<4>")
	)
	(segment
		(start 55.338472 -270.860266)
		(end 55.593234 -270.860266)
		(width 0.14478)
		(layer "In4.Cu")
		(net "M_D_CPU1_SB_CB<4>")
	)
	(segment
		(start 61.968888 -269.335504)
		(end 62.130432 -269.17396)
		(width 0.14478)
		(layer "In4.Cu")
		(net "M_D_CPU1_SB_CB<4>")
	)
	(segment
		(start 42.728642 -270.860266)
		(end 42.983404 -270.860266)
		(width 0.14478)
		(layer "In4.Cu")
		(net "M_D_CPU1_SB_CB<4>")
	)
	(segment
		(start 58.119772 -271.161764)
		(end 58.374534 -271.161764)
		(width 0.14478)
		(layer "In4.Cu")
		(net "M_D_CPU1_SB_CB<4>")
	)
	(segment
		(start 45.283882 -271.161764)
		(end 45.538644 -271.161764)
		(width 0.14478)
		(layer "In4.Cu")
		(net "M_D_CPU1_SB_CB<4>")
	)
	(segment
		(start 48.750474 -271.161764)
		(end 49.051972 -270.860266)
		(width 0.14478)
		(layer "In4.Cu")
		(net "M_D_CPU1_SB_CB<4>")
	)
	(segment
		(start 37.737288 -271.194022)
		(end 38.071044 -270.860266)
		(width 0.14478)
		(layer "In4.Cu")
		(net "M_D_CPU1_SB_CB<4>")
	)
	(segment
		(start 42.427144 -271.161764)
		(end 42.728642 -270.860266)
		(width 0.14478)
		(layer "In4.Cu")
		(net "M_D_CPU1_SB_CB<4>")
	)
	(segment
		(start 60.798456 -270.734536)
		(end 61.012578 -270.948658)
		(width 0.14478)
		(layer "In4.Cu")
		(net "M_D_CPU1_SB_CB<4>")
	)
	(segment
		(start 50.975514 -271.161764)
		(end 51.277012 -270.860266)
		(width 0.14478)
		(layer "In4.Cu")
		(net "M_D_CPU1_SB_CB<4>")
	)
	(segment
		(start 80.769714 -269.55369)
		(end 80.778096 -269.548864)
		(width 0.0889)
		(layer "In4.Cu")
		(net "M_D_CPU1_SB_CB<4>")
	)
	(segment
		(start 63.13932 -268.393672)
		(end 63.353442 -268.607794)
		(width 0.14478)
		(layer "In4.Cu")
		(net "M_D_CPU1_SB_CB<4>")
	)
	(segment
		(start 42.983404 -270.860266)
		(end 43.284902 -271.161764)
		(width 0.14478)
		(layer "In4.Cu")
		(net "M_D_CPU1_SB_CB<4>")
	)
	(segment
		(start 49.306734 -270.860266)
		(end 49.608232 -271.161764)
		(width 0.14478)
		(layer "In4.Cu")
		(net "M_D_CPU1_SB_CB<4>")
	)
	(segment
		(start 52.255674 -270.860266)
		(end 52.557172 -271.161764)
		(width 0.14478)
		(layer "In4.Cu")
		(net "M_D_CPU1_SB_CB<4>")
	)
	(segment
		(start 41.059862 -271.161764)
		(end 41.314624 -271.161764)
		(width 0.14478)
		(layer "In4.Cu")
		(net "M_D_CPU1_SB_CB<4>")
	)
	(segment
		(start 78.05547 -269.098776)
		(end 78.446884 -269.49019)
		(width 0.0889)
		(layer "In4.Cu")
		(net "M_D_CPU1_SB_CB<4>")
	)
	(segment
		(start 54.480714 -270.860266)
		(end 54.782212 -271.161764)
		(width 0.14478)
		(layer "In4.Cu")
		(net "M_D_CPU1_SB_CB<4>")
	)
	(segment
		(start 60.569856 -270.734536)
		(end 60.798456 -270.734536)
		(width 0.14478)
		(layer "In4.Cu")
		(net "M_D_CPU1_SB_CB<4>")
	)
	(segment
		(start 62.91072 -268.393672)
		(end 63.13932 -268.393672)
		(width 0.14478)
		(layer "In4.Cu")
		(net "M_D_CPU1_SB_CB<4>")
	)
	(segment
		(start 91.085162 -269.491714)
		(end 90.930984 -269.226284)
		(width 0.0889)
		(layer "In4.Cu")
		(net "M_D_CPU1_SB_CB<4>")
	)
	(segment
		(start 42.172382 -271.161764)
		(end 42.427144 -271.161764)
		(width 0.14478)
		(layer "In4.Cu")
		(net "M_D_CPU1_SB_CB<4>")
	)
	(segment
		(start 54.782212 -271.161764)
		(end 55.036974 -271.161764)
		(width 0.14478)
		(layer "In4.Cu")
		(net "M_D_CPU1_SB_CB<4>")
	)
	(segment
		(start 61.792866 -270.16837)
		(end 62.021466 -270.16837)
		(width 0.14478)
		(layer "In4.Cu")
		(net "M_D_CPU1_SB_CB<4>")
	)
	(segment
		(start 37.737288 -271.641062)
		(end 37.737288 -271.194022)
		(width 0.14478)
		(layer "In4.Cu")
		(net "M_D_CPU1_SB_CB<4>")
	)
	(segment
		(start 57.007252 -271.161764)
		(end 57.262014 -271.161764)
		(width 0.14478)
		(layer "In4.Cu")
		(net "M_D_CPU1_SB_CB<4>")
	)
	(segment
		(start 62.18301 -269.778226)
		(end 61.968888 -269.564104)
		(width 0.14478)
		(layer "In4.Cu")
		(net "M_D_CPU1_SB_CB<4>")
	)
	(segment
		(start 46.651164 -271.161764)
		(end 46.952662 -270.860266)
		(width 0.14478)
		(layer "In4.Cu")
		(net "M_D_CPU1_SB_CB<4>")
	)
	(segment
		(start 84.529676 -269.55369)
		(end 84.538058 -269.548864)
		(width 0.0889)
		(layer "In4.Cu")
		(net "M_D_CPU1_SB_CB<4>")
	)
	(segment
		(start 63.353442 -268.607794)
		(end 63.582042 -268.607794)
		(width 0.14478)
		(layer "In4.Cu")
		(net "M_D_CPU1_SB_CB<4>")
	)
	(segment
		(start 46.094904 -270.860266)
		(end 46.396402 -271.161764)
		(width 0.14478)
		(layer "In4.Cu")
		(net "M_D_CPU1_SB_CB<4>")
	)
	(segment
		(start 62.18301 -270.006826)
		(end 62.18301 -269.778226)
		(width 0.14478)
		(layer "In4.Cu")
		(net "M_D_CPU1_SB_CB<4>")
	)
	(segment
		(start 38.802564 -271.161764)
		(end 39.057326 -271.161764)
		(width 0.14478)
		(layer "In4.Cu")
		(net "M_D_CPU1_SB_CB<4>")
	)
	(segment
		(start 50.720752 -271.161764)
		(end 50.975514 -271.161764)
		(width 0.14478)
		(layer "In4.Cu")
		(net "M_D_CPU1_SB_CB<4>")
	)
	(segment
		(start 56.705754 -270.860266)
		(end 57.007252 -271.161764)
		(width 0.14478)
		(layer "In4.Cu")
		(net "M_D_CPU1_SB_CB<4>")
	)
	(segment
		(start 55.894732 -271.161764)
		(end 56.149494 -271.161764)
		(width 0.14478)
		(layer "In4.Cu")
		(net "M_D_CPU1_SB_CB<4>")
	)
	(segment
		(start 38.071044 -270.860266)
		(end 38.501066 -270.860266)
		(width 0.14478)
		(layer "In4.Cu")
		(net "M_D_CPU1_SB_CB<4>")
	)
	(segment
		(start 49.051972 -270.860266)
		(end 49.306734 -270.860266)
		(width 0.14478)
		(layer "In4.Cu")
		(net "M_D_CPU1_SB_CB<4>")
	)
	(segment
		(start 63.529464 -267.774928)
		(end 63.707518 -267.596874)
		(width 0.14478)
		(layer "In4.Cu")
		(net "M_D_CPU1_SB_CB<4>")
	)
	(segment
		(start 61.402722 -270.787114)
		(end 61.402722 -270.558514)
		(width 0.14478)
		(layer "In4.Cu")
		(net "M_D_CPU1_SB_CB<4>")
	)
	(segment
		(start 63.743586 -268.21765)
		(end 63.529464 -268.003528)
		(width 0.14478)
		(layer "In4.Cu")
		(net "M_D_CPU1_SB_CB<4>")
	)
	(segment
		(start 43.841162 -270.860266)
		(end 44.982384 -270.860266)
		(width 0.14478)
		(layer "In4.Cu")
		(net "M_D_CPU1_SB_CB<4>")
	)
	(segment
		(start 61.1886 -270.115792)
		(end 61.350144 -269.954248)
		(width 0.14478)
		(layer "In4.Cu")
		(net "M_D_CPU1_SB_CB<4>")
	)
	(segment
		(start 75.969876 -267.596874)
		(end 77.489558 -267.596874)
		(width 0.0889)
		(layer "In4.Cu")
		(net "M_D_CPU1_SB_CB<4>")
	)
	(segment
		(start 79.826358 -269.555722)
		(end 79.838042 -269.548864)
		(width 0.0889)
		(layer "In4.Cu")
		(net "M_D_CPU1_SB_CB<4>")
	)
	(segment
		(start 50.164492 -270.860266)
		(end 50.419254 -270.860266)
		(width 0.14478)
		(layer "In4.Cu")
		(net "M_D_CPU1_SB_CB<4>")
	)
	(segment
		(start 77.489558 -267.596874)
		(end 78.05547 -268.162786)
		(width 0.0889)
		(layer "In4.Cu")
		(net "M_D_CPU1_SB_CB<4>")
	)
	(segment
		(start 61.578744 -269.954248)
		(end 61.792866 -270.16837)
		(width 0.14478)
		(layer "In4.Cu")
		(net "M_D_CPU1_SB_CB<4>")
	)
	(segment
		(start 53.924454 -271.161764)
		(end 54.225952 -270.860266)
		(width 0.14478)
		(layer "In4.Cu")
		(net "M_D_CPU1_SB_CB<4>")
	)
	(segment
		(start 62.963298 -268.997938)
		(end 62.749176 -268.783816)
		(width 0.14478)
		(layer "In4.Cu")
		(net "M_D_CPU1_SB_CB<4>")
	)
	(segment
		(start 43.539664 -271.161764)
		(end 43.841162 -270.860266)
		(width 0.14478)
		(layer "In4.Cu")
		(net "M_D_CPU1_SB_CB<4>")
	)
	(segment
		(start 38.501066 -270.860266)
		(end 38.802564 -271.161764)
		(width 0.14478)
		(layer "In4.Cu")
		(net "M_D_CPU1_SB_CB<4>")
	)
	(segment
		(start 85.10397 -269.548864)
		(end 85.112352 -269.55369)
		(width 0.0889)
		(layer "In4.Cu")
		(net "M_D_CPU1_SB_CB<4>")
	)
	(segment
		(start 49.608232 -271.161764)
		(end 49.862994 -271.161764)
		(width 0.14478)
		(layer "In4.Cu")
		(net "M_D_CPU1_SB_CB<4>")
	)
	(segment
		(start 49.862994 -271.161764)
		(end 50.164492 -270.860266)
		(width 0.14478)
		(layer "In4.Cu")
		(net "M_D_CPU1_SB_CB<4>")
	)
	(segment
		(start 57.818274 -270.860266)
		(end 58.119772 -271.161764)
		(width 0.14478)
		(layer "In4.Cu")
		(net "M_D_CPU1_SB_CB<4>")
	)
	(segment
		(start 62.749176 -268.555216)
		(end 62.91072 -268.393672)
		(width 0.14478)
		(layer "In4.Cu")
		(net "M_D_CPU1_SB_CB<4>")
	)
	(segment
		(start 62.573154 -269.388082)
		(end 62.801754 -269.388082)
		(width 0.14478)
		(layer "In4.Cu")
		(net "M_D_CPU1_SB_CB<4>")
	)
	(segment
		(start 45.538644 -271.161764)
		(end 45.840142 -270.860266)
		(width 0.14478)
		(layer "In4.Cu")
		(net "M_D_CPU1_SB_CB<4>")
	)
	(arc
		(start 78.446884 -269.49019)
		(mid 78.483211 -269.522003)
		(end 78.523338 -269.548864)
		(width 0.0889)
		(layer "In4.Cu")
		(net "M_D_CPU1_SB_CB<4>")
	)
	(arc
		(start 79.838042 -269.548864)
		(mid 80.120998 -269.472687)
		(end 80.403954 -269.548864)
		(width 0.0889)
		(layer "In4.Cu")
		(net "M_D_CPU1_SB_CB<4>")
	)
	(arc
		(start 86.052406 -269.55369)
		(mid 86.235914 -269.599184)
		(end 86.418166 -269.548864)
		(width 0.0889)
		(layer "In4.Cu")
		(net "M_D_CPU1_SB_CB<4>")
	)
	(arc
		(start 90.178128 -269.548864)
		(mid 90.461084 -269.472687)
		(end 90.74404 -269.548864)
		(width 0.0889)
		(layer "In4.Cu")
		(net "M_D_CPU1_SB_CB<4>")
	)
	(arc
		(start 86.418166 -269.548864)
		(mid 86.701122 -269.472687)
		(end 86.984078 -269.548864)
		(width 0.0889)
		(layer "In4.Cu")
		(net "M_D_CPU1_SB_CB<4>")
	)
	(arc
		(start 85.478112 -269.548864)
		(mid 85.761068 -269.472687)
		(end 86.044024 -269.548864)
		(width 0.0889)
		(layer "In4.Cu")
		(net "M_D_CPU1_SB_CB<4>")
	)
	(arc
		(start 78.523592 -269.548864)
		(mid 78.70022 -269.599097)
		(end 78.879446 -269.559024)
		(width 0.0889)
		(layer "In4.Cu")
		(net "M_D_CPU1_SB_CB<4>")
	)
	(arc
		(start 85.112352 -269.55369)
		(mid 85.29586 -269.599184)
		(end 85.478112 -269.548864)
		(width 0.0889)
		(layer "In4.Cu")
		(net "M_D_CPU1_SB_CB<4>")
	)
	(arc
		(start 87.357966 -269.548864)
		(mid 87.640922 -269.472687)
		(end 87.923878 -269.548864)
		(width 0.0889)
		(layer "In4.Cu")
		(net "M_D_CPU1_SB_CB<4>")
	)
	(arc
		(start 81.71815 -269.548864)
		(mid 82.001106 -269.472687)
		(end 82.284062 -269.548864)
		(width 0.0889)
		(layer "In4.Cu")
		(net "M_D_CPU1_SB_CB<4>")
	)
	(arc
		(start 84.538058 -269.548864)
		(mid 84.821014 -269.472687)
		(end 85.10397 -269.548864)
		(width 0.0889)
		(layer "In4.Cu")
		(net "M_D_CPU1_SB_CB<4>")
	)
	(arc
		(start 82.284062 -269.548864)
		(mid 82.471006 -269.599119)
		(end 82.65795 -269.548864)
		(width 0.0889)
		(layer "In4.Cu")
		(net "M_D_CPU1_SB_CB<4>")
	)
	(arc
		(start 88.863932 -269.548864)
		(mid 89.046183 -269.599214)
		(end 89.229692 -269.55369)
		(width 0.0889)
		(layer "In4.Cu")
		(net "M_D_CPU1_SB_CB<4>")
	)
	(arc
		(start 81.35239 -269.55369)
		(mid 81.535898 -269.599184)
		(end 81.71815 -269.548864)
		(width 0.0889)
		(layer "In4.Cu")
		(net "M_D_CPU1_SB_CB<4>")
	)
	(arc
		(start 86.984078 -269.548864)
		(mid 87.171022 -269.599119)
		(end 87.357966 -269.548864)
		(width 0.0889)
		(layer "In4.Cu")
		(net "M_D_CPU1_SB_CB<4>")
	)
	(arc
		(start 84.163916 -269.548864)
		(mid 84.346167 -269.599214)
		(end 84.529676 -269.55369)
		(width 0.0889)
		(layer "In4.Cu")
		(net "M_D_CPU1_SB_CB<4>")
	)
	(arc
		(start 89.238074 -269.548864)
		(mid 89.52103 -269.472687)
		(end 89.803986 -269.548864)
		(width 0.0889)
		(layer "In4.Cu")
		(net "M_D_CPU1_SB_CB<4>")
	)
	(arc
		(start 87.923878 -269.548864)
		(mid 88.106129 -269.599214)
		(end 88.289638 -269.55369)
		(width 0.0889)
		(layer "In4.Cu")
		(net "M_D_CPU1_SB_CB<4>")
	)
	(arc
		(start 88.29802 -269.548864)
		(mid 88.580976 -269.472687)
		(end 88.863932 -269.548864)
		(width 0.0889)
		(layer "In4.Cu")
		(net "M_D_CPU1_SB_CB<4>")
	)
	(arc
		(start 83.598004 -269.548864)
		(mid 83.88096 -269.472687)
		(end 84.163916 -269.548864)
		(width 0.0889)
		(layer "In4.Cu")
		(net "M_D_CPU1_SB_CB<4>")
	)
	(arc
		(start 80.778096 -269.548864)
		(mid 81.061052 -269.472687)
		(end 81.344008 -269.548864)
		(width 0.0889)
		(layer "In4.Cu")
		(net "M_D_CPU1_SB_CB<4>")
	)
	(arc
		(start 78.913482 -269.539466)
		(mid 79.189791 -269.47249)
		(end 79.463646 -269.548864)
		(width 0.0889)
		(layer "In4.Cu")
		(net "M_D_CPU1_SB_CB<4>")
	)
	(arc
		(start 80.403954 -269.548864)
		(mid 80.586205 -269.599214)
		(end 80.769714 -269.55369)
		(width 0.0889)
		(layer "In4.Cu")
		(net "M_D_CPU1_SB_CB<4>")
	)
	(arc
		(start 83.223862 -269.548864)
		(mid 83.406113 -269.599214)
		(end 83.589622 -269.55369)
		(width 0.0889)
		(layer "In4.Cu")
		(net "M_D_CPU1_SB_CB<4>")
	)
	(arc
		(start 90.752422 -269.55369)
		(mid 90.905292 -269.598331)
		(end 91.06281 -269.575026)
		(width 0.0889)
		(layer "In4.Cu")
		(net "M_D_CPU1_SB_CB<4>")
	)
	(arc
		(start 89.812368 -269.55369)
		(mid 89.995876 -269.599184)
		(end 90.178128 -269.548864)
		(width 0.0889)
		(layer "In4.Cu")
		(net "M_D_CPU1_SB_CB<4>")
	)
	(arc
		(start 82.65795 -269.548864)
		(mid 82.940906 -269.472687)
		(end 83.223862 -269.548864)
		(width 0.0889)
		(layer "In4.Cu")
		(net "M_D_CPU1_SB_CB<4>")
	)
	(arc
		(start 79.463646 -269.548864)
		(mid 79.644104 -269.599308)
		(end 79.826358 -269.555722)
		(width 0.0889)
		(layer "In4.Cu")
		(net "M_D_CPU1_SB_CB<4>")
	)
	(segment
		(start 93.277944 -273.820382)
		(end 92.811092 -274.08632)
		(width 0.10668)
		(layer "F.Cu")
		(net "M_D_CPU1_SB_CB<3>")
	)
	(segment
		(start 52.827936 -280.21026)
		(end 53.282596 -280.66492)
		(width 0.14478)
		(layer "In4.Cu")
		(net "M_D_CPU1_SB_CB<3>")
	)
	(segment
		(start 57.322212 -280.66492)
		(end 57.776872 -280.21026)
		(width 0.14478)
		(layer "In4.Cu")
		(net "M_D_CPU1_SB_CB<3>")
	)
	(segment
		(start 76.73213 -272.531586)
		(end 77.20711 -272.531586)
		(width 0.0889)
		(layer "In4.Cu")
		(net "M_D_CPU1_SB_CB<3>")
	)
	(segment
		(start 32.695896 -280.635202)
		(end 33.121092 -281.060398)
		(width 0.14478)
		(layer "In4.Cu")
		(net "M_D_CPU1_SB_CB<3>")
	)
	(segment
		(start 79.463138 -273.76374)
		(end 79.474822 -273.756882)
		(width 0.0889)
		(layer "In4.Cu")
		(net "M_D_CPU1_SB_CB<3>")
	)
	(segment
		(start 89.229692 -273.758914)
		(end 89.238074 -273.76374)
		(width 0.0889)
		(layer "In4.Cu")
		(net "M_D_CPU1_SB_CB<3>")
	)
	(segment
		(start 33.121092 -281.060398)
		(end 42.363898 -281.060398)
		(width 0.14478)
		(layer "In4.Cu")
		(net "M_D_CPU1_SB_CB<3>")
	)
	(segment
		(start 85.10397 -273.76374)
		(end 85.112352 -273.758914)
		(width 0.0889)
		(layer "In4.Cu")
		(net "M_D_CPU1_SB_CB<3>")
	)
	(segment
		(start 67.095878 -272.664174)
		(end 76.391516 -272.664174)
		(width 0.14478)
		(layer "In4.Cu")
		(net "M_D_CPU1_SB_CB<3>")
	)
	(segment
		(start 86.044024 -273.76374)
		(end 86.052406 -273.758914)
		(width 0.0889)
		(layer "In4.Cu")
		(net "M_D_CPU1_SB_CB<3>")
	)
	(segment
		(start 42.363898 -281.060398)
		(end 43.212258 -280.212038)
		(width 0.14478)
		(layer "In4.Cu")
		(net "M_D_CPU1_SB_CB<3>")
	)
	(segment
		(start 57.776872 -280.21026)
		(end 59.549792 -280.21026)
		(width 0.14478)
		(layer "In4.Cu")
		(net "M_D_CPU1_SB_CB<3>")
	)
	(segment
		(start 77.20711 -272.531586)
		(end 78.388718 -273.713194)
		(width 0.0889)
		(layer "In4.Cu")
		(net "M_D_CPU1_SB_CB<3>")
	)
	(segment
		(start 83.589622 -273.758914)
		(end 83.598004 -273.76374)
		(width 0.0889)
		(layer "In4.Cu")
		(net "M_D_CPU1_SB_CB<3>")
	)
	(segment
		(start 80.389222 -273.772376)
		(end 80.403954 -273.76374)
		(width 0.0889)
		(layer "In4.Cu")
		(net "M_D_CPU1_SB_CB<3>")
	)
	(segment
		(start 80.769714 -273.758914)
		(end 80.778096 -273.76374)
		(width 0.0889)
		(layer "In4.Cu")
		(net "M_D_CPU1_SB_CB<3>")
	)
	(segment
		(start 45.158914 -280.212038)
		(end 46.007274 -281.060398)
		(width 0.14478)
		(layer "In4.Cu")
		(net "M_D_CPU1_SB_CB<3>")
	)
	(segment
		(start 89.803986 -273.76374)
		(end 89.812368 -273.758914)
		(width 0.0889)
		(layer "In4.Cu")
		(net "M_D_CPU1_SB_CB<3>")
	)
	(segment
		(start 43.212258 -280.212038)
		(end 45.158914 -280.212038)
		(width 0.14478)
		(layer "In4.Cu")
		(net "M_D_CPU1_SB_CB<3>")
	)
	(segment
		(start 76.391516 -272.664174)
		(end 76.599542 -272.664174)
		(width 0.0889)
		(layer "In4.Cu")
		(net "M_D_CPU1_SB_CB<3>")
	)
	(segment
		(start 92.560648 -273.79549)
		(end 92.656914 -273.82089)
		(width 0.0889)
		(layer "In4.Cu")
		(net "M_D_CPU1_SB_CB<3>")
	)
	(segment
		(start 53.282596 -280.66492)
		(end 57.322212 -280.66492)
		(width 0.14478)
		(layer "In4.Cu")
		(net "M_D_CPU1_SB_CB<3>")
	)
	(segment
		(start 50.3936 -280.21026)
		(end 52.827936 -280.21026)
		(width 0.14478)
		(layer "In4.Cu")
		(net "M_D_CPU1_SB_CB<3>")
	)
	(segment
		(start 92.656914 -273.82089)
		(end 92.811092 -274.08632)
		(width 0.0889)
		(layer "In4.Cu")
		(net "M_D_CPU1_SB_CB<3>")
	)
	(segment
		(start 81.344008 -273.76374)
		(end 81.35239 -273.758914)
		(width 0.0889)
		(layer "In4.Cu")
		(net "M_D_CPU1_SB_CB<3>")
	)
	(segment
		(start 49.543462 -281.060398)
		(end 50.3936 -280.21026)
		(width 0.14478)
		(layer "In4.Cu")
		(net "M_D_CPU1_SB_CB<3>")
	)
	(segment
		(start 78.897734 -273.763994)
		(end 78.903322 -273.767296)
		(width 0.0889)
		(layer "In4.Cu")
		(net "M_D_CPU1_SB_CB<3>")
	)
	(segment
		(start 78.388718 -273.713194)
		(end 78.711044 -273.713194)
		(width 0.0889)
		(layer "In4.Cu")
		(net "M_D_CPU1_SB_CB<3>")
	)
	(segment
		(start 90.74404 -273.76374)
		(end 90.752422 -273.758914)
		(width 0.0889)
		(layer "In4.Cu")
		(net "M_D_CPU1_SB_CB<3>")
	)
	(segment
		(start 76.599542 -272.664174)
		(end 76.73213 -272.531586)
		(width 0.0889)
		(layer "In4.Cu")
		(net "M_D_CPU1_SB_CB<3>")
	)
	(segment
		(start 84.529676 -273.758914)
		(end 84.538058 -273.76374)
		(width 0.0889)
		(layer "In4.Cu")
		(net "M_D_CPU1_SB_CB<3>")
	)
	(segment
		(start 59.549792 -280.21026)
		(end 67.095878 -272.664174)
		(width 0.14478)
		(layer "In4.Cu")
		(net "M_D_CPU1_SB_CB<3>")
	)
	(segment
		(start 88.289638 -273.758914)
		(end 88.29802 -273.76374)
		(width 0.0889)
		(layer "In4.Cu")
		(net "M_D_CPU1_SB_CB<3>")
	)
	(segment
		(start 46.007274 -281.060398)
		(end 49.543462 -281.060398)
		(width 0.14478)
		(layer "In4.Cu")
		(net "M_D_CPU1_SB_CB<3>")
	)
	(arc
		(start 85.478112 -273.76374)
		(mid 85.761068 -273.839917)
		(end 86.044024 -273.76374)
		(width 0.0889)
		(layer "In4.Cu")
		(net "M_D_CPU1_SB_CB<3>")
	)
	(arc
		(start 88.863932 -273.76374)
		(mid 89.046183 -273.71339)
		(end 89.229692 -273.758914)
		(width 0.0889)
		(layer "In4.Cu")
		(net "M_D_CPU1_SB_CB<3>")
	)
	(arc
		(start 81.71815 -273.76374)
		(mid 82.001106 -273.839917)
		(end 82.284062 -273.76374)
		(width 0.0889)
		(layer "In4.Cu")
		(net "M_D_CPU1_SB_CB<3>")
	)
	(arc
		(start 86.418166 -273.76374)
		(mid 86.701122 -273.839917)
		(end 86.984078 -273.76374)
		(width 0.0889)
		(layer "In4.Cu")
		(net "M_D_CPU1_SB_CB<3>")
	)
	(arc
		(start 89.238074 -273.76374)
		(mid 89.52103 -273.839917)
		(end 89.803986 -273.76374)
		(width 0.0889)
		(layer "In4.Cu")
		(net "M_D_CPU1_SB_CB<3>")
	)
	(arc
		(start 91.684094 -273.76374)
		(mid 91.871038 -273.713485)
		(end 92.057982 -273.76374)
		(width 0.0889)
		(layer "In4.Cu")
		(net "M_D_CPU1_SB_CB<3>")
	)
	(arc
		(start 86.984078 -273.76374)
		(mid 87.171022 -273.713485)
		(end 87.357966 -273.76374)
		(width 0.0889)
		(layer "In4.Cu")
		(net "M_D_CPU1_SB_CB<3>")
	)
	(arc
		(start 78.711044 -273.713194)
		(mid 78.807735 -273.72629)
		(end 78.897734 -273.763994)
		(width 0.0889)
		(layer "In4.Cu")
		(net "M_D_CPU1_SB_CB<3>")
	)
	(arc
		(start 82.284062 -273.76374)
		(mid 82.471006 -273.713485)
		(end 82.65795 -273.76374)
		(width 0.0889)
		(layer "In4.Cu")
		(net "M_D_CPU1_SB_CB<3>")
	)
	(arc
		(start 88.29802 -273.76374)
		(mid 88.580976 -273.839917)
		(end 88.863932 -273.76374)
		(width 0.0889)
		(layer "In4.Cu")
		(net "M_D_CPU1_SB_CB<3>")
	)
	(arc
		(start 89.812368 -273.758914)
		(mid 89.995876 -273.71342)
		(end 90.178128 -273.76374)
		(width 0.0889)
		(layer "In4.Cu")
		(net "M_D_CPU1_SB_CB<3>")
	)
	(arc
		(start 90.178128 -273.76374)
		(mid 90.461084 -273.839917)
		(end 90.74404 -273.76374)
		(width 0.0889)
		(layer "In4.Cu")
		(net "M_D_CPU1_SB_CB<3>")
	)
	(arc
		(start 80.403954 -273.76374)
		(mid 80.586205 -273.71339)
		(end 80.769714 -273.758914)
		(width 0.0889)
		(layer "In4.Cu")
		(net "M_D_CPU1_SB_CB<3>")
	)
	(arc
		(start 87.357966 -273.76374)
		(mid 87.640922 -273.839917)
		(end 87.923878 -273.76374)
		(width 0.0889)
		(layer "In4.Cu")
		(net "M_D_CPU1_SB_CB<3>")
	)
	(arc
		(start 90.752422 -273.758914)
		(mid 90.93593 -273.71342)
		(end 91.118182 -273.76374)
		(width 0.0889)
		(layer "In4.Cu")
		(net "M_D_CPU1_SB_CB<3>")
	)
	(arc
		(start 84.538058 -273.76374)
		(mid 84.821014 -273.839917)
		(end 85.10397 -273.76374)
		(width 0.0889)
		(layer "In4.Cu")
		(net "M_D_CPU1_SB_CB<3>")
	)
	(arc
		(start 82.65795 -273.76374)
		(mid 82.940906 -273.839917)
		(end 83.223862 -273.76374)
		(width 0.0889)
		(layer "In4.Cu")
		(net "M_D_CPU1_SB_CB<3>")
	)
	(arc
		(start 83.223862 -273.76374)
		(mid 83.406113 -273.71339)
		(end 83.589622 -273.758914)
		(width 0.0889)
		(layer "In4.Cu")
		(net "M_D_CPU1_SB_CB<3>")
	)
	(arc
		(start 91.118182 -273.76374)
		(mid 91.401138 -273.839917)
		(end 91.684094 -273.76374)
		(width 0.0889)
		(layer "In4.Cu")
		(net "M_D_CPU1_SB_CB<3>")
	)
	(arc
		(start 87.923878 -273.76374)
		(mid 88.106129 -273.71339)
		(end 88.289638 -273.758914)
		(width 0.0889)
		(layer "In4.Cu")
		(net "M_D_CPU1_SB_CB<3>")
	)
	(arc
		(start 81.35239 -273.758914)
		(mid 81.535898 -273.71342)
		(end 81.71815 -273.76374)
		(width 0.0889)
		(layer "In4.Cu")
		(net "M_D_CPU1_SB_CB<3>")
	)
	(arc
		(start 85.112352 -273.758914)
		(mid 85.29586 -273.71342)
		(end 85.478112 -273.76374)
		(width 0.0889)
		(layer "In4.Cu")
		(net "M_D_CPU1_SB_CB<3>")
	)
	(arc
		(start 80.778096 -273.76374)
		(mid 81.061052 -273.839917)
		(end 81.344008 -273.76374)
		(width 0.0889)
		(layer "In4.Cu")
		(net "M_D_CPU1_SB_CB<3>")
	)
	(arc
		(start 92.057982 -273.76374)
		(mid 92.305578 -273.838918)
		(end 92.560648 -273.79549)
		(width 0.0889)
		(layer "In4.Cu")
		(net "M_D_CPU1_SB_CB<3>")
	)
	(arc
		(start 84.163916 -273.76374)
		(mid 84.346167 -273.71339)
		(end 84.529676 -273.758914)
		(width 0.0889)
		(layer "In4.Cu")
		(net "M_D_CPU1_SB_CB<3>")
	)
	(arc
		(start 83.598004 -273.76374)
		(mid 83.88096 -273.839917)
		(end 84.163916 -273.76374)
		(width 0.0889)
		(layer "In4.Cu")
		(net "M_D_CPU1_SB_CB<3>")
	)
	(arc
		(start 79.837534 -273.76374)
		(mid 80.11224 -273.840104)
		(end 80.389222 -273.772376)
		(width 0.0889)
		(layer "In4.Cu")
		(net "M_D_CPU1_SB_CB<3>")
	)
	(arc
		(start 78.903322 -273.767296)
		(mid 79.183711 -273.839965)
		(end 79.463138 -273.76374)
		(width 0.0889)
		(layer "In4.Cu")
		(net "M_D_CPU1_SB_CB<3>")
	)
	(arc
		(start 86.052406 -273.758914)
		(mid 86.235914 -273.71342)
		(end 86.418166 -273.76374)
		(width 0.0889)
		(layer "In4.Cu")
		(net "M_D_CPU1_SB_CB<3>")
	)
	(arc
		(start 79.474822 -273.756882)
		(mid 79.657077 -273.713229)
		(end 79.837534 -273.76374)
		(width 0.0889)
		(layer "In4.Cu")
		(net "M_D_CPU1_SB_CB<3>")
	)
	(segment
		(start 91.86799 -273.010376)
		(end 91.401138 -273.276314)
		(width 0.10668)
		(layer "F.Cu")
		(net "M_D_CPU1_SB_CB<2>")
	)
	(segment
		(start 42.667174 -279.360376)
		(end 43.517312 -278.510238)
		(width 0.14478)
		(layer "In4.Cu")
		(net "M_D_CPU1_SB_CB<2>")
	)
	(segment
		(start 34.461196 -279.360376)
		(end 42.667174 -279.360376)
		(width 0.14478)
		(layer "In4.Cu")
		(net "M_D_CPU1_SB_CB<2>")
	)
	(segment
		(start 47.016162 -279.658826)
		(end 47.314612 -279.360376)
		(width 0.14478)
		(layer "In4.Cu")
		(net "M_D_CPU1_SB_CB<2>")
	)
	(segment
		(start 91.24696 -273.010884)
		(end 91.401138 -273.276314)
		(width 0.0889)
		(layer "In4.Cu")
		(net "M_D_CPU1_SB_CB<2>")
	)
	(segment
		(start 88.394032 -272.953734)
		(end 88.402414 -272.948908)
		(width 0.0889)
		(layer "In4.Cu")
		(net "M_D_CPU1_SB_CB<2>")
	)
	(segment
		(start 91.150694 -272.985484)
		(end 91.24696 -273.010884)
		(width 0.0889)
		(layer "In4.Cu")
		(net "M_D_CPU1_SB_CB<2>")
	)
	(segment
		(start 87.453978 -272.953734)
		(end 87.46236 -272.948908)
		(width 0.0889)
		(layer "In4.Cu")
		(net "M_D_CPU1_SB_CB<2>")
	)
	(segment
		(start 80.299814 -272.948908)
		(end 80.308196 -272.953734)
		(width 0.0889)
		(layer "In4.Cu")
		(net "M_D_CPU1_SB_CB<2>")
	)
	(segment
		(start 57.410858 -279.289764)
		(end 58.190384 -278.510238)
		(width 0.14478)
		(layer "In4.Cu")
		(net "M_D_CPU1_SB_CB<2>")
	)
	(segment
		(start 45.20946 -278.510238)
		(end 46.059598 -279.360376)
		(width 0.14478)
		(layer "In4.Cu")
		(net "M_D_CPU1_SB_CB<2>")
	)
	(segment
		(start 77.468222 -272.021046)
		(end 78.312264 -272.865088)
		(width 0.0889)
		(layer "In4.Cu")
		(net "M_D_CPU1_SB_CB<2>")
	)
	(segment
		(start 78.977744 -272.963132)
		(end 78.993492 -272.953988)
		(width 0.0889)
		(layer "In4.Cu")
		(net "M_D_CPU1_SB_CB<2>")
	)
	(segment
		(start 47.314612 -279.360376)
		(end 49.956974 -279.360376)
		(width 0.14478)
		(layer "In4.Cu")
		(net "M_D_CPU1_SB_CB<2>")
	)
	(segment
		(start 50.807112 -278.510238)
		(end 52.82946 -278.510238)
		(width 0.14478)
		(layer "In4.Cu")
		(net "M_D_CPU1_SB_CB<2>")
	)
	(segment
		(start 49.956974 -279.360376)
		(end 50.807112 -278.510238)
		(width 0.14478)
		(layer "In4.Cu")
		(net "M_D_CPU1_SB_CB<2>")
	)
	(segment
		(start 33.742122 -278.792178)
		(end 33.904936 -278.629364)
		(width 0.14478)
		(layer "In4.Cu")
		(net "M_D_CPU1_SB_CB<2>")
	)
	(segment
		(start 32.695896 -278.935434)
		(end 33.120838 -279.360376)
		(width 0.14478)
		(layer "In4.Cu")
		(net "M_D_CPU1_SB_CB<2>")
	)
	(segment
		(start 82.179668 -272.948908)
		(end 82.18805 -272.953734)
		(width 0.0889)
		(layer "In4.Cu")
		(net "M_D_CPU1_SB_CB<2>")
	)
	(segment
		(start 75.960986 -271.754854)
		(end 76.501498 -271.754854)
		(width 0.0889)
		(layer "In4.Cu")
		(net "M_D_CPU1_SB_CB<2>")
	)
	(segment
		(start 43.517312 -278.510238)
		(end 45.20946 -278.510238)
		(width 0.14478)
		(layer "In4.Cu")
		(net "M_D_CPU1_SB_CB<2>")
	)
	(segment
		(start 90.639646 -272.948908)
		(end 90.648028 -272.953734)
		(width 0.0889)
		(layer "In4.Cu")
		(net "M_D_CPU1_SB_CB<2>")
	)
	(segment
		(start 78.993492 -272.953988)
		(end 79.009748 -272.94459)
		(width 0.0889)
		(layer "In4.Cu")
		(net "M_D_CPU1_SB_CB<2>")
	)
	(segment
		(start 86.879684 -272.948908)
		(end 86.888066 -272.953734)
		(width 0.0889)
		(layer "In4.Cu")
		(net "M_D_CPU1_SB_CB<2>")
	)
	(segment
		(start 83.694016 -272.953734)
		(end 83.702398 -272.948908)
		(width 0.0889)
		(layer "In4.Cu")
		(net "M_D_CPU1_SB_CB<2>")
	)
	(segment
		(start 34.135568 -278.629364)
		(end 34.298382 -278.792178)
		(width 0.14478)
		(layer "In4.Cu")
		(net "M_D_CPU1_SB_CB<2>")
	)
	(segment
		(start 46.059598 -279.360376)
		(end 46.464728 -279.360376)
		(width 0.14478)
		(layer "In4.Cu")
		(net "M_D_CPU1_SB_CB<2>")
	)
	(segment
		(start 33.120838 -279.360376)
		(end 33.579308 -279.360376)
		(width 0.14478)
		(layer "In4.Cu")
		(net "M_D_CPU1_SB_CB<2>")
	)
	(segment
		(start 53.608986 -279.289764)
		(end 57.410858 -279.289764)
		(width 0.14478)
		(layer "In4.Cu")
		(net "M_D_CPU1_SB_CB<2>")
	)
	(segment
		(start 33.904936 -278.629364)
		(end 34.135568 -278.629364)
		(width 0.14478)
		(layer "In4.Cu")
		(net "M_D_CPU1_SB_CB<2>")
	)
	(segment
		(start 66.733166 -271.754854)
		(end 75.960986 -271.754854)
		(width 0.14478)
		(layer "In4.Cu")
		(net "M_D_CPU1_SB_CB<2>")
	)
	(segment
		(start 34.298382 -279.197562)
		(end 34.461196 -279.360376)
		(width 0.14478)
		(layer "In4.Cu")
		(net "M_D_CPU1_SB_CB<2>")
	)
	(segment
		(start 85.93963 -272.948908)
		(end 85.948012 -272.953734)
		(width 0.0889)
		(layer "In4.Cu")
		(net "M_D_CPU1_SB_CB<2>")
	)
	(segment
		(start 33.742122 -279.197562)
		(end 33.742122 -278.792178)
		(width 0.14478)
		(layer "In4.Cu")
		(net "M_D_CPU1_SB_CB<2>")
	)
	(segment
		(start 33.579308 -279.360376)
		(end 33.742122 -279.197562)
		(width 0.14478)
		(layer "In4.Cu")
		(net "M_D_CPU1_SB_CB<2>")
	)
	(segment
		(start 34.298382 -278.792178)
		(end 34.298382 -279.197562)
		(width 0.14478)
		(layer "In4.Cu")
		(net "M_D_CPU1_SB_CB<2>")
	)
	(segment
		(start 82.753962 -272.953734)
		(end 82.762344 -272.948908)
		(width 0.0889)
		(layer "In4.Cu")
		(net "M_D_CPU1_SB_CB<2>")
	)
	(segment
		(start 76.501498 -271.754854)
		(end 76.76769 -272.021046)
		(width 0.0889)
		(layer "In4.Cu")
		(net "M_D_CPU1_SB_CB<2>")
	)
	(segment
		(start 76.76769 -272.021046)
		(end 77.468222 -272.021046)
		(width 0.0889)
		(layer "In4.Cu")
		(net "M_D_CPU1_SB_CB<2>")
	)
	(segment
		(start 79.36738 -272.953734)
		(end 79.377794 -272.95983)
		(width 0.0889)
		(layer "In4.Cu")
		(net "M_D_CPU1_SB_CB<2>")
	)
	(segment
		(start 46.763178 -279.658826)
		(end 47.016162 -279.658826)
		(width 0.14478)
		(layer "In4.Cu")
		(net "M_D_CPU1_SB_CB<2>")
	)
	(segment
		(start 52.82946 -278.510238)
		(end 53.608986 -279.289764)
		(width 0.14478)
		(layer "In4.Cu")
		(net "M_D_CPU1_SB_CB<2>")
	)
	(segment
		(start 46.464728 -279.360376)
		(end 46.763178 -279.658826)
		(width 0.14478)
		(layer "In4.Cu")
		(net "M_D_CPU1_SB_CB<2>")
	)
	(segment
		(start 58.190384 -278.510238)
		(end 59.977782 -278.510238)
		(width 0.14478)
		(layer "In4.Cu")
		(net "M_D_CPU1_SB_CB<2>")
	)
	(segment
		(start 59.977782 -278.510238)
		(end 66.733166 -271.754854)
		(width 0.14478)
		(layer "In4.Cu")
		(net "M_D_CPU1_SB_CB<2>")
	)
	(arc
		(start 85.57387 -272.953734)
		(mid 85.756121 -272.903384)
		(end 85.93963 -272.948908)
		(width 0.0889)
		(layer "In4.Cu")
		(net "M_D_CPU1_SB_CB<2>")
	)
	(arc
		(start 87.46236 -272.948908)
		(mid 87.645868 -272.903414)
		(end 87.82812 -272.953734)
		(width 0.0889)
		(layer "In4.Cu")
		(net "M_D_CPU1_SB_CB<2>")
	)
	(arc
		(start 86.888066 -272.953734)
		(mid 87.171022 -273.029911)
		(end 87.453978 -272.953734)
		(width 0.0889)
		(layer "In4.Cu")
		(net "M_D_CPU1_SB_CB<2>")
	)
	(arc
		(start 79.377794 -272.95983)
		(mid 79.65648 -273.03005)
		(end 79.933546 -272.953734)
		(width 0.0889)
		(layer "In4.Cu")
		(net "M_D_CPU1_SB_CB<2>")
	)
	(arc
		(start 89.334086 -272.953734)
		(mid 89.52103 -272.903479)
		(end 89.707974 -272.953734)
		(width 0.0889)
		(layer "In4.Cu")
		(net "M_D_CPU1_SB_CB<2>")
	)
	(arc
		(start 79.933546 -272.953734)
		(mid 80.116051 -272.903257)
		(end 80.299814 -272.948908)
		(width 0.0889)
		(layer "In4.Cu")
		(net "M_D_CPU1_SB_CB<2>")
	)
	(arc
		(start 80.874108 -272.953734)
		(mid 81.061052 -272.903479)
		(end 81.247996 -272.953734)
		(width 0.0889)
		(layer "In4.Cu")
		(net "M_D_CPU1_SB_CB<2>")
	)
	(arc
		(start 88.768174 -272.953734)
		(mid 89.05113 -273.029911)
		(end 89.334086 -272.953734)
		(width 0.0889)
		(layer "In4.Cu")
		(net "M_D_CPU1_SB_CB<2>")
	)
	(arc
		(start 85.007958 -272.953734)
		(mid 85.290914 -273.029911)
		(end 85.57387 -272.953734)
		(width 0.0889)
		(layer "In4.Cu")
		(net "M_D_CPU1_SB_CB<2>")
	)
	(arc
		(start 84.63407 -272.953734)
		(mid 84.821014 -272.903479)
		(end 85.007958 -272.953734)
		(width 0.0889)
		(layer "In4.Cu")
		(net "M_D_CPU1_SB_CB<2>")
	)
	(arc
		(start 85.948012 -272.953734)
		(mid 86.230968 -273.029911)
		(end 86.513924 -272.953734)
		(width 0.0889)
		(layer "In4.Cu")
		(net "M_D_CPU1_SB_CB<2>")
	)
	(arc
		(start 81.247996 -272.953734)
		(mid 81.530952 -273.029911)
		(end 81.813908 -272.953734)
		(width 0.0889)
		(layer "In4.Cu")
		(net "M_D_CPU1_SB_CB<2>")
	)
	(arc
		(start 90.648028 -272.953734)
		(mid 90.895624 -273.028912)
		(end 91.150694 -272.985484)
		(width 0.0889)
		(layer "In4.Cu")
		(net "M_D_CPU1_SB_CB<2>")
	)
	(arc
		(start 78.42758 -272.953734)
		(mid 78.701435 -273.030084)
		(end 78.977744 -272.963132)
		(width 0.0889)
		(layer "In4.Cu")
		(net "M_D_CPU1_SB_CB<2>")
	)
	(arc
		(start 80.308196 -272.953734)
		(mid 80.591152 -273.029911)
		(end 80.874108 -272.953734)
		(width 0.0889)
		(layer "In4.Cu")
		(net "M_D_CPU1_SB_CB<2>")
	)
	(arc
		(start 79.009748 -272.94459)
		(mid 79.18973 -272.90349)
		(end 79.36738 -272.953734)
		(width 0.0889)
		(layer "In4.Cu")
		(net "M_D_CPU1_SB_CB<2>")
	)
	(arc
		(start 86.513924 -272.953734)
		(mid 86.696175 -272.903384)
		(end 86.879684 -272.948908)
		(width 0.0889)
		(layer "In4.Cu")
		(net "M_D_CPU1_SB_CB<2>")
	)
	(arc
		(start 78.312264 -272.865088)
		(mid 78.367049 -272.913148)
		(end 78.42758 -272.953734)
		(width 0.0889)
		(layer "In4.Cu")
		(net "M_D_CPU1_SB_CB<2>")
	)
	(arc
		(start 83.702398 -272.948908)
		(mid 83.885906 -272.903414)
		(end 84.068158 -272.953734)
		(width 0.0889)
		(layer "In4.Cu")
		(net "M_D_CPU1_SB_CB<2>")
	)
	(arc
		(start 87.82812 -272.953734)
		(mid 88.111076 -273.029911)
		(end 88.394032 -272.953734)
		(width 0.0889)
		(layer "In4.Cu")
		(net "M_D_CPU1_SB_CB<2>")
	)
	(arc
		(start 90.273886 -272.953734)
		(mid 90.456137 -272.903384)
		(end 90.639646 -272.948908)
		(width 0.0889)
		(layer "In4.Cu")
		(net "M_D_CPU1_SB_CB<2>")
	)
	(arc
		(start 82.18805 -272.953734)
		(mid 82.471006 -273.029911)
		(end 82.753962 -272.953734)
		(width 0.0889)
		(layer "In4.Cu")
		(net "M_D_CPU1_SB_CB<2>")
	)
	(arc
		(start 83.128104 -272.953734)
		(mid 83.41106 -273.029911)
		(end 83.694016 -272.953734)
		(width 0.0889)
		(layer "In4.Cu")
		(net "M_D_CPU1_SB_CB<2>")
	)
	(arc
		(start 81.813908 -272.953734)
		(mid 81.996159 -272.903384)
		(end 82.179668 -272.948908)
		(width 0.0889)
		(layer "In4.Cu")
		(net "M_D_CPU1_SB_CB<2>")
	)
	(arc
		(start 88.402414 -272.948908)
		(mid 88.585922 -272.903414)
		(end 88.768174 -272.953734)
		(width 0.0889)
		(layer "In4.Cu")
		(net "M_D_CPU1_SB_CB<2>")
	)
	(arc
		(start 89.707974 -272.953734)
		(mid 89.99093 -273.029911)
		(end 90.273886 -272.953734)
		(width 0.0889)
		(layer "In4.Cu")
		(net "M_D_CPU1_SB_CB<2>")
	)
	(arc
		(start 82.762344 -272.948908)
		(mid 82.945852 -272.903414)
		(end 83.128104 -272.953734)
		(width 0.0889)
		(layer "In4.Cu")
		(net "M_D_CPU1_SB_CB<2>")
	)
	(arc
		(start 84.068158 -272.953734)
		(mid 84.351114 -273.029911)
		(end 84.63407 -272.953734)
		(width 0.0889)
		(layer "In4.Cu")
		(net "M_D_CPU1_SB_CB<2>")
	)
	(segment
		(start 92.80779 -273.010376)
		(end 92.340938 -273.276314)
		(width 0.10668)
		(layer "F.Cu")
		(net "M_D_CPU1_SB_CB<1>")
	)
	(segment
		(start 39.103046 -279.99944)
		(end 39.26586 -279.836626)
		(width 0.14478)
		(layer "In4.Cu")
		(net "M_D_CPU1_SB_CB<1>")
	)
	(segment
		(start 36.795964 -279.785318)
		(end 37.59708 -280.586434)
		(width 0.14478)
		(layer "In4.Cu")
		(net "M_D_CPU1_SB_CB<1>")
	)
	(segment
		(start 80.299814 -273.60372)
		(end 80.308196 -273.598894)
		(width 0.0889)
		(layer "In4.Cu")
		(net "M_D_CPU1_SB_CB<1>")
	)
	(segment
		(start 55.9943 -280.21026)
		(end 56.276494 -279.928066)
		(width 0.14478)
		(layer "In4.Cu")
		(net "M_D_CPU1_SB_CB<1>")
	)
	(segment
		(start 41.471596 -279.835356)
		(end 41.702228 -279.835356)
		(width 0.14478)
		(layer "In4.Cu")
		(net "M_D_CPU1_SB_CB<1>")
	)
	(segment
		(start 43.40225 -279.3619)
		(end 45.172122 -279.3619)
		(width 0.14478)
		(layer "In4.Cu")
		(net "M_D_CPU1_SB_CB<1>")
	)
	(segment
		(start 86.879684 -273.60372)
		(end 86.888066 -273.598894)
		(width 0.0889)
		(layer "In4.Cu")
		(net "M_D_CPU1_SB_CB<1>")
	)
	(segment
		(start 37.827712 -280.586434)
		(end 37.990526 -280.42362)
		(width 0.14478)
		(layer "In4.Cu")
		(net "M_D_CPU1_SB_CB<1>")
	)
	(segment
		(start 41.145968 -280.585164)
		(end 41.308782 -280.42235)
		(width 0.14478)
		(layer "In4.Cu")
		(net "M_D_CPU1_SB_CB<1>")
	)
	(segment
		(start 41.308782 -279.99817)
		(end 41.471596 -279.835356)
		(width 0.14478)
		(layer "In4.Cu")
		(net "M_D_CPU1_SB_CB<1>")
	)
	(segment
		(start 38.7096 -280.586434)
		(end 38.940232 -280.586434)
		(width 0.14478)
		(layer "In4.Cu")
		(net "M_D_CPU1_SB_CB<1>")
	)
	(segment
		(start 49.05629 -279.963626)
		(end 49.302924 -280.21026)
		(width 0.14478)
		(layer "In4.Cu")
		(net "M_D_CPU1_SB_CB<1>")
	)
	(segment
		(start 56.545734 -279.928066)
		(end 56.827928 -280.21026)
		(width 0.14478)
		(layer "In4.Cu")
		(net "M_D_CPU1_SB_CB<1>")
	)
	(segment
		(start 53.767482 -280.21026)
		(end 53.9877 -280.21026)
		(width 0.14478)
		(layer "In4.Cu")
		(net "M_D_CPU1_SB_CB<1>")
	)
	(segment
		(start 57.13349 -280.21026)
		(end 57.983628 -279.360122)
		(width 0.14478)
		(layer "In4.Cu")
		(net "M_D_CPU1_SB_CB<1>")
	)
	(segment
		(start 39.26586 -279.836626)
		(end 39.496492 -279.836626)
		(width 0.14478)
		(layer "In4.Cu")
		(net "M_D_CPU1_SB_CB<1>")
	)
	(segment
		(start 40.915336 -280.585164)
		(end 41.145968 -280.585164)
		(width 0.14478)
		(layer "In4.Cu")
		(net "M_D_CPU1_SB_CB<1>")
	)
	(segment
		(start 91.5797 -273.60372)
		(end 91.588082 -273.598894)
		(width 0.0889)
		(layer "In4.Cu")
		(net "M_D_CPU1_SB_CB<1>")
	)
	(segment
		(start 85.93963 -273.60372)
		(end 85.948012 -273.598894)
		(width 0.0889)
		(layer "In4.Cu")
		(net "M_D_CPU1_SB_CB<1>")
	)
	(segment
		(start 39.870126 -280.21026)
		(end 40.540432 -280.21026)
		(width 0.14478)
		(layer "In4.Cu")
		(net "M_D_CPU1_SB_CB<1>")
	)
	(segment
		(start 54.539134 -279.907746)
		(end 54.841648 -280.21026)
		(width 0.14478)
		(layer "In4.Cu")
		(net "M_D_CPU1_SB_CB<1>")
	)
	(segment
		(start 38.940232 -280.586434)
		(end 39.103046 -280.42362)
		(width 0.14478)
		(layer "In4.Cu")
		(net "M_D_CPU1_SB_CB<1>")
	)
	(segment
		(start 76.52639 -272.277586)
		(end 77.222604 -272.277586)
		(width 0.0889)
		(layer "In4.Cu")
		(net "M_D_CPU1_SB_CB<1>")
	)
	(segment
		(start 59.159902 -279.412192)
		(end 59.711844 -279.412192)
		(width 0.14478)
		(layer "In4.Cu")
		(net "M_D_CPU1_SB_CB<1>")
	)
	(segment
		(start 76.458318 -272.209514)
		(end 76.52639 -272.277586)
		(width 0.0889)
		(layer "In4.Cu")
		(net "M_D_CPU1_SB_CB<1>")
	)
	(segment
		(start 92.472764 -273.625056)
		(end 92.495116 -273.541744)
		(width 0.0889)
		(layer "In4.Cu")
		(net "M_D_CPU1_SB_CB<1>")
	)
	(segment
		(start 37.990526 -279.99944)
		(end 38.15334 -279.836626)
		(width 0.14478)
		(layer "In4.Cu")
		(net "M_D_CPU1_SB_CB<1>")
	)
	(segment
		(start 56.276494 -279.928066)
		(end 56.545734 -279.928066)
		(width 0.14478)
		(layer "In4.Cu")
		(net "M_D_CPU1_SB_CB<1>")
	)
	(segment
		(start 48.75149 -279.963626)
		(end 49.05629 -279.963626)
		(width 0.14478)
		(layer "In4.Cu")
		(net "M_D_CPU1_SB_CB<1>")
	)
	(segment
		(start 77.222604 -272.277586)
		(end 78.467712 -273.522694)
		(width 0.0889)
		(layer "In4.Cu")
		(net "M_D_CPU1_SB_CB<1>")
	)
	(segment
		(start 75.960986 -272.209514)
		(end 76.458318 -272.209514)
		(width 0.0889)
		(layer "In4.Cu")
		(net "M_D_CPU1_SB_CB<1>")
	)
	(segment
		(start 79.367126 -273.598894)
		(end 79.381858 -273.590258)
		(width 0.0889)
		(layer "In4.Cu")
		(net "M_D_CPU1_SB_CB<1>")
	)
	(segment
		(start 53.9877 -280.21026)
		(end 54.290214 -279.907746)
		(width 0.14478)
		(layer "In4.Cu")
		(net "M_D_CPU1_SB_CB<1>")
	)
	(segment
		(start 48.504856 -280.21026)
		(end 48.75149 -279.963626)
		(width 0.14478)
		(layer "In4.Cu")
		(net "M_D_CPU1_SB_CB<1>")
	)
	(segment
		(start 39.496492 -279.836626)
		(end 39.870126 -280.21026)
		(width 0.14478)
		(layer "In4.Cu")
		(net "M_D_CPU1_SB_CB<1>")
	)
	(segment
		(start 58.207656 -279.360122)
		(end 58.594498 -279.746964)
		(width 0.14478)
		(layer "In4.Cu")
		(net "M_D_CPU1_SB_CB<1>")
	)
	(segment
		(start 49.750218 -280.21026)
		(end 50.600356 -279.360122)
		(width 0.14478)
		(layer "In4.Cu")
		(net "M_D_CPU1_SB_CB<1>")
	)
	(segment
		(start 39.103046 -280.42362)
		(end 39.103046 -279.99944)
		(width 0.14478)
		(layer "In4.Cu")
		(net "M_D_CPU1_SB_CB<1>")
	)
	(segment
		(start 38.546786 -279.99944)
		(end 38.546786 -280.42362)
		(width 0.14478)
		(layer "In4.Cu")
		(net "M_D_CPU1_SB_CB<1>")
	)
	(segment
		(start 41.702228 -279.835356)
		(end 42.077132 -280.21026)
		(width 0.14478)
		(layer "In4.Cu")
		(net "M_D_CPU1_SB_CB<1>")
	)
	(segment
		(start 78.993492 -273.59864)
		(end 79.007208 -273.606514)
		(width 0.0889)
		(layer "In4.Cu")
		(net "M_D_CPU1_SB_CB<1>")
	)
	(segment
		(start 83.694016 -273.598894)
		(end 83.702398 -273.60372)
		(width 0.0889)
		(layer "In4.Cu")
		(net "M_D_CPU1_SB_CB<1>")
	)
	(segment
		(start 54.841648 -280.21026)
		(end 55.9943 -280.21026)
		(width 0.14478)
		(layer "In4.Cu")
		(net "M_D_CPU1_SB_CB<1>")
	)
	(segment
		(start 87.453978 -273.598894)
		(end 87.46236 -273.60372)
		(width 0.0889)
		(layer "In4.Cu")
		(net "M_D_CPU1_SB_CB<1>")
	)
	(segment
		(start 37.990526 -280.42362)
		(end 37.990526 -279.99944)
		(width 0.14478)
		(layer "In4.Cu")
		(net "M_D_CPU1_SB_CB<1>")
	)
	(segment
		(start 42.55389 -280.21026)
		(end 43.40225 -279.3619)
		(width 0.14478)
		(layer "In4.Cu")
		(net "M_D_CPU1_SB_CB<1>")
	)
	(segment
		(start 45.172122 -279.3619)
		(end 46.020482 -280.21026)
		(width 0.14478)
		(layer "In4.Cu")
		(net "M_D_CPU1_SB_CB<1>")
	)
	(segment
		(start 46.020482 -280.21026)
		(end 48.504856 -280.21026)
		(width 0.14478)
		(layer "In4.Cu")
		(net "M_D_CPU1_SB_CB<1>")
	)
	(segment
		(start 50.600356 -279.360122)
		(end 52.917344 -279.360122)
		(width 0.14478)
		(layer "In4.Cu")
		(net "M_D_CPU1_SB_CB<1>")
	)
	(segment
		(start 90.639646 -273.60372)
		(end 90.648028 -273.598894)
		(width 0.0889)
		(layer "In4.Cu")
		(net "M_D_CPU1_SB_CB<1>")
	)
	(segment
		(start 52.917344 -279.360122)
		(end 53.767482 -280.21026)
		(width 0.14478)
		(layer "In4.Cu")
		(net "M_D_CPU1_SB_CB<1>")
	)
	(segment
		(start 88.394032 -273.598894)
		(end 88.402414 -273.60372)
		(width 0.0889)
		(layer "In4.Cu")
		(net "M_D_CPU1_SB_CB<1>")
	)
	(segment
		(start 82.179668 -273.60372)
		(end 82.18805 -273.598894)
		(width 0.0889)
		(layer "In4.Cu")
		(net "M_D_CPU1_SB_CB<1>")
	)
	(segment
		(start 56.827928 -280.21026)
		(end 57.13349 -280.21026)
		(width 0.14478)
		(layer "In4.Cu")
		(net "M_D_CPU1_SB_CB<1>")
	)
	(segment
		(start 58.594498 -279.746964)
		(end 58.82513 -279.746964)
		(width 0.14478)
		(layer "In4.Cu")
		(net "M_D_CPU1_SB_CB<1>")
	)
	(segment
		(start 37.59708 -280.586434)
		(end 37.827712 -280.586434)
		(width 0.14478)
		(layer "In4.Cu")
		(net "M_D_CPU1_SB_CB<1>")
	)
	(segment
		(start 58.82513 -279.746964)
		(end 59.159902 -279.412192)
		(width 0.14478)
		(layer "In4.Cu")
		(net "M_D_CPU1_SB_CB<1>")
	)
	(segment
		(start 78.467712 -273.522694)
		(end 78.711552 -273.522694)
		(width 0.0889)
		(layer "In4.Cu")
		(net "M_D_CPU1_SB_CB<1>")
	)
	(segment
		(start 40.540432 -280.21026)
		(end 40.915336 -280.585164)
		(width 0.14478)
		(layer "In4.Cu")
		(net "M_D_CPU1_SB_CB<1>")
	)
	(segment
		(start 82.753962 -273.598894)
		(end 82.762344 -273.60372)
		(width 0.0889)
		(layer "In4.Cu")
		(net "M_D_CPU1_SB_CB<1>")
	)
	(segment
		(start 54.290214 -279.907746)
		(end 54.539134 -279.907746)
		(width 0.14478)
		(layer "In4.Cu")
		(net "M_D_CPU1_SB_CB<1>")
	)
	(segment
		(start 38.546786 -280.42362)
		(end 38.7096 -280.586434)
		(width 0.14478)
		(layer "In4.Cu")
		(net "M_D_CPU1_SB_CB<1>")
	)
	(segment
		(start 92.495116 -273.541744)
		(end 92.340938 -273.276314)
		(width 0.0889)
		(layer "In4.Cu")
		(net "M_D_CPU1_SB_CB<1>")
	)
	(segment
		(start 66.914522 -272.209514)
		(end 75.960986 -272.209514)
		(width 0.14478)
		(layer "In4.Cu")
		(net "M_D_CPU1_SB_CB<1>")
	)
	(segment
		(start 38.383972 -279.836626)
		(end 38.546786 -279.99944)
		(width 0.14478)
		(layer "In4.Cu")
		(net "M_D_CPU1_SB_CB<1>")
	)
	(segment
		(start 42.077132 -280.21026)
		(end 42.55389 -280.21026)
		(width 0.14478)
		(layer "In4.Cu")
		(net "M_D_CPU1_SB_CB<1>")
	)
	(segment
		(start 57.983628 -279.360122)
		(end 58.207656 -279.360122)
		(width 0.14478)
		(layer "In4.Cu")
		(net "M_D_CPU1_SB_CB<1>")
	)
	(segment
		(start 92.153994 -273.598894)
		(end 92.162376 -273.60372)
		(width 0.0889)
		(layer "In4.Cu")
		(net "M_D_CPU1_SB_CB<1>")
	)
	(segment
		(start 38.15334 -279.836626)
		(end 38.383972 -279.836626)
		(width 0.14478)
		(layer "In4.Cu")
		(net "M_D_CPU1_SB_CB<1>")
	)
	(segment
		(start 59.711844 -279.412192)
		(end 66.914522 -272.209514)
		(width 0.14478)
		(layer "In4.Cu")
		(net "M_D_CPU1_SB_CB<1>")
	)
	(segment
		(start 49.302924 -280.21026)
		(end 49.750218 -280.21026)
		(width 0.14478)
		(layer "In4.Cu")
		(net "M_D_CPU1_SB_CB<1>")
	)
	(segment
		(start 41.308782 -280.42235)
		(end 41.308782 -279.99817)
		(width 0.14478)
		(layer "In4.Cu")
		(net "M_D_CPU1_SB_CB<1>")
	)
	(arc
		(start 92.162376 -273.60372)
		(mid 92.315246 -273.648361)
		(end 92.472764 -273.625056)
		(width 0.0889)
		(layer "In4.Cu")
		(net "M_D_CPU1_SB_CB<1>")
	)
	(arc
		(start 86.513924 -273.598894)
		(mid 86.696175 -273.649244)
		(end 86.879684 -273.60372)
		(width 0.0889)
		(layer "In4.Cu")
		(net "M_D_CPU1_SB_CB<1>")
	)
	(arc
		(start 87.82812 -273.598894)
		(mid 88.111076 -273.522717)
		(end 88.394032 -273.598894)
		(width 0.0889)
		(layer "In4.Cu")
		(net "M_D_CPU1_SB_CB<1>")
	)
	(arc
		(start 90.273886 -273.598894)
		(mid 90.456137 -273.649244)
		(end 90.639646 -273.60372)
		(width 0.0889)
		(layer "In4.Cu")
		(net "M_D_CPU1_SB_CB<1>")
	)
	(arc
		(start 89.334086 -273.598894)
		(mid 89.52103 -273.649149)
		(end 89.707974 -273.598894)
		(width 0.0889)
		(layer "In4.Cu")
		(net "M_D_CPU1_SB_CB<1>")
	)
	(arc
		(start 82.18805 -273.598894)
		(mid 82.471006 -273.522717)
		(end 82.753962 -273.598894)
		(width 0.0889)
		(layer "In4.Cu")
		(net "M_D_CPU1_SB_CB<1>")
	)
	(arc
		(start 80.308196 -273.598894)
		(mid 80.591152 -273.522717)
		(end 80.874108 -273.598894)
		(width 0.0889)
		(layer "In4.Cu")
		(net "M_D_CPU1_SB_CB<1>")
	)
	(arc
		(start 79.933546 -273.598894)
		(mid 80.116051 -273.649371)
		(end 80.299814 -273.60372)
		(width 0.0889)
		(layer "In4.Cu")
		(net "M_D_CPU1_SB_CB<1>")
	)
	(arc
		(start 79.007208 -273.606514)
		(mid 79.188138 -273.648992)
		(end 79.367126 -273.598894)
		(width 0.0889)
		(layer "In4.Cu")
		(net "M_D_CPU1_SB_CB<1>")
	)
	(arc
		(start 87.46236 -273.60372)
		(mid 87.645868 -273.649214)
		(end 87.82812 -273.598894)
		(width 0.0889)
		(layer "In4.Cu")
		(net "M_D_CPU1_SB_CB<1>")
	)
	(arc
		(start 88.768174 -273.598894)
		(mid 89.05113 -273.522717)
		(end 89.334086 -273.598894)
		(width 0.0889)
		(layer "In4.Cu")
		(net "M_D_CPU1_SB_CB<1>")
	)
	(arc
		(start 89.707974 -273.598894)
		(mid 89.99093 -273.522717)
		(end 90.273886 -273.598894)
		(width 0.0889)
		(layer "In4.Cu")
		(net "M_D_CPU1_SB_CB<1>")
	)
	(arc
		(start 78.711552 -273.522694)
		(mid 78.727432 -273.522853)
		(end 78.743302 -273.523456)
		(width 0.0889)
		(layer "In4.Cu")
		(net "M_D_CPU1_SB_CB<1>")
	)
	(arc
		(start 79.381858 -273.590258)
		(mid 79.658841 -273.522454)
		(end 79.933546 -273.598894)
		(width 0.0889)
		(layer "In4.Cu")
		(net "M_D_CPU1_SB_CB<1>")
	)
	(arc
		(start 85.007958 -273.598894)
		(mid 85.290914 -273.522717)
		(end 85.57387 -273.598894)
		(width 0.0889)
		(layer "In4.Cu")
		(net "M_D_CPU1_SB_CB<1>")
	)
	(arc
		(start 83.702398 -273.60372)
		(mid 83.885906 -273.649214)
		(end 84.068158 -273.598894)
		(width 0.0889)
		(layer "In4.Cu")
		(net "M_D_CPU1_SB_CB<1>")
	)
	(arc
		(start 84.63407 -273.598894)
		(mid 84.821014 -273.649149)
		(end 85.007958 -273.598894)
		(width 0.0889)
		(layer "In4.Cu")
		(net "M_D_CPU1_SB_CB<1>")
	)
	(arc
		(start 88.402414 -273.60372)
		(mid 88.585922 -273.649214)
		(end 88.768174 -273.598894)
		(width 0.0889)
		(layer "In4.Cu")
		(net "M_D_CPU1_SB_CB<1>")
	)
	(arc
		(start 81.247996 -273.598894)
		(mid 81.530952 -273.522717)
		(end 81.813908 -273.598894)
		(width 0.0889)
		(layer "In4.Cu")
		(net "M_D_CPU1_SB_CB<1>")
	)
	(arc
		(start 82.762344 -273.60372)
		(mid 82.945852 -273.649214)
		(end 83.128104 -273.598894)
		(width 0.0889)
		(layer "In4.Cu")
		(net "M_D_CPU1_SB_CB<1>")
	)
	(arc
		(start 84.068158 -273.598894)
		(mid 84.351114 -273.522717)
		(end 84.63407 -273.598894)
		(width 0.0889)
		(layer "In4.Cu")
		(net "M_D_CPU1_SB_CB<1>")
	)
	(arc
		(start 78.743302 -273.523456)
		(mid 78.872806 -273.54637)
		(end 78.993492 -273.59864)
		(width 0.0889)
		(layer "In4.Cu")
		(net "M_D_CPU1_SB_CB<1>")
	)
	(arc
		(start 91.588082 -273.598894)
		(mid 91.871038 -273.522717)
		(end 92.153994 -273.598894)
		(width 0.0889)
		(layer "In4.Cu")
		(net "M_D_CPU1_SB_CB<1>")
	)
	(arc
		(start 81.813908 -273.598894)
		(mid 81.996159 -273.649244)
		(end 82.179668 -273.60372)
		(width 0.0889)
		(layer "In4.Cu")
		(net "M_D_CPU1_SB_CB<1>")
	)
	(arc
		(start 85.948012 -273.598894)
		(mid 86.230968 -273.522717)
		(end 86.513924 -273.598894)
		(width 0.0889)
		(layer "In4.Cu")
		(net "M_D_CPU1_SB_CB<1>")
	)
	(arc
		(start 85.57387 -273.598894)
		(mid 85.756121 -273.649244)
		(end 85.93963 -273.60372)
		(width 0.0889)
		(layer "In4.Cu")
		(net "M_D_CPU1_SB_CB<1>")
	)
	(arc
		(start 86.888066 -273.598894)
		(mid 87.171022 -273.522717)
		(end 87.453978 -273.598894)
		(width 0.0889)
		(layer "In4.Cu")
		(net "M_D_CPU1_SB_CB<1>")
	)
	(arc
		(start 90.648028 -273.598894)
		(mid 90.930984 -273.522717)
		(end 91.21394 -273.598894)
		(width 0.0889)
		(layer "In4.Cu")
		(net "M_D_CPU1_SB_CB<1>")
	)
	(arc
		(start 91.21394 -273.598894)
		(mid 91.396191 -273.649244)
		(end 91.5797 -273.60372)
		(width 0.0889)
		(layer "In4.Cu")
		(net "M_D_CPU1_SB_CB<1>")
	)
	(arc
		(start 83.128104 -273.598894)
		(mid 83.41106 -273.522717)
		(end 83.694016 -273.598894)
		(width 0.0889)
		(layer "In4.Cu")
		(net "M_D_CPU1_SB_CB<1>")
	)
	(arc
		(start 80.874108 -273.598894)
		(mid 81.061052 -273.649149)
		(end 81.247996 -273.598894)
		(width 0.0889)
		(layer "In4.Cu")
		(net "M_D_CPU1_SB_CB<1>")
	)
	(segment
		(start 91.397836 -272.20037)
		(end 90.930984 -272.466308)
		(width 0.10668)
		(layer "F.Cu")
		(net "M_D_CPU1_SB_CB<0>")
	)
	(segment
		(start 37.230812 -278.520144)
		(end 37.526722 -278.520144)
		(width 0.14478)
		(layer "In4.Cu")
		(net "M_D_CPU1_SB_CB<0>")
	)
	(segment
		(start 64.797178 -272.97507)
		(end 64.977518 -272.79473)
		(width 0.14478)
		(layer "In4.Cu")
		(net "M_D_CPU1_SB_CB<0>")
	)
	(segment
		(start 64.01689 -273.755358)
		(end 64.19723 -273.575018)
		(width 0.14478)
		(layer "In4.Cu")
		(net "M_D_CPU1_SB_CB<0>")
	)
	(segment
		(start 39.342568 -278.742902)
		(end 39.342568 -278.681688)
		(width 0.14478)
		(layer "In4.Cu")
		(net "M_D_CPU1_SB_CB<0>")
	)
	(segment
		(start 49.5935 -278.520144)
		(end 50.094134 -278.520144)
		(width 0.14478)
		(layer "In4.Cu")
		(net "M_D_CPU1_SB_CB<0>")
	)
	(segment
		(start 56.383682 -278.832564)
		(end 56.705754 -278.510492)
		(width 0.14478)
		(layer "In4.Cu")
		(net "M_D_CPU1_SB_CB<0>")
	)
	(segment
		(start 80.769714 -272.793714)
		(end 80.778096 -272.788888)
		(width 0.0889)
		(layer "In4.Cu")
		(net "M_D_CPU1_SB_CB<0>")
	)
	(segment
		(start 49.270412 -278.896826)
		(end 49.431956 -278.735282)
		(width 0.14478)
		(layer "In4.Cu")
		(net "M_D_CPU1_SB_CB<0>")
	)
	(segment
		(start 65.757806 -272.014442)
		(end 65.757552 -271.822926)
		(width 0.14478)
		(layer "In4.Cu")
		(net "M_D_CPU1_SB_CB<0>")
	)
	(segment
		(start 60.475876 -276.87651)
		(end 60.895738 -276.87651)
		(width 0.14478)
		(layer "In4.Cu")
		(net "M_D_CPU1_SB_CB<0>")
	)
	(segment
		(start 56.149494 -278.832564)
		(end 56.383682 -278.832564)
		(width 0.14478)
		(layer "In4.Cu")
		(net "M_D_CPU1_SB_CB<0>")
	)
	(segment
		(start 62.6364 -274.944078)
		(end 62.6364 -274.715986)
		(width 0.14478)
		(layer "In4.Cu")
		(net "M_D_CPU1_SB_CB<0>")
	)
	(segment
		(start 50.094134 -278.520144)
		(end 50.944272 -277.670006)
		(width 0.14478)
		(layer "In4.Cu")
		(net "M_D_CPU1_SB_CB<0>")
	)
	(segment
		(start 63.416688 -274.16379)
		(end 63.416688 -273.935698)
		(width 0.14478)
		(layer "In4.Cu")
		(net "M_D_CPU1_SB_CB<0>")
	)
	(segment
		(start 58.659268 -277.935944)
		(end 58.796936 -277.798276)
		(width 0.14478)
		(layer "In4.Cu")
		(net "M_D_CPU1_SB_CB<0>")
	)
	(segment
		(start 61.856112 -275.496274)
		(end 62.036452 -275.315934)
		(width 0.14478)
		(layer "In4.Cu")
		(net "M_D_CPU1_SB_CB<0>")
	)
	(segment
		(start 50.944272 -277.670006)
		(end 52.650136 -277.670006)
		(width 0.14478)
		(layer "In4.Cu")
		(net "M_D_CPU1_SB_CB<0>")
	)
	(segment
		(start 62.6364 -274.715986)
		(end 62.81674 -274.535646)
		(width 0.14478)
		(layer "In4.Cu")
		(net "M_D_CPU1_SB_CB<0>")
	)
	(segment
		(start 58.378344 -277.935944)
		(end 58.659268 -277.935944)
		(width 0.14478)
		(layer "In4.Cu")
		(net "M_D_CPU1_SB_CB<0>")
	)
	(segment
		(start 38.2397 -278.742902)
		(end 38.2397 -278.681688)
		(width 0.14478)
		(layer "In4.Cu")
		(net "M_D_CPU1_SB_CB<0>")
	)
	(segment
		(start 89.803986 -272.788888)
		(end 89.812368 -272.793714)
		(width 0.0889)
		(layer "In4.Cu")
		(net "M_D_CPU1_SB_CB<0>")
	)
	(segment
		(start 36.795964 -278.085296)
		(end 37.230812 -278.520144)
		(width 0.14478)
		(layer "In4.Cu")
		(net "M_D_CPU1_SB_CB<0>")
	)
	(segment
		(start 78.879446 -272.799048)
		(end 78.897734 -272.788634)
		(width 0.0889)
		(layer "In4.Cu")
		(net "M_D_CPU1_SB_CB<0>")
	)
	(segment
		(start 63.236602 -274.535646)
		(end 63.416942 -274.355306)
		(width 0.14478)
		(layer "In4.Cu")
		(net "M_D_CPU1_SB_CB<0>")
	)
	(segment
		(start 61.856366 -275.915882)
		(end 61.856112 -275.724366)
		(width 0.14478)
		(layer "In4.Cu")
		(net "M_D_CPU1_SB_CB<0>")
	)
	(segment
		(start 59.967622 -277.384764)
		(end 60.475876 -276.87651)
		(width 0.14478)
		(layer "In4.Cu")
		(net "M_D_CPU1_SB_CB<0>")
	)
	(segment
		(start 75.960986 -271.300194)
		(end 76.399898 -271.300194)
		(width 0.0889)
		(layer "In4.Cu")
		(net "M_D_CPU1_SB_CB<0>")
	)
	(segment
		(start 61.676026 -276.096222)
		(end 61.856366 -275.915882)
		(width 0.14478)
		(layer "In4.Cu")
		(net "M_D_CPU1_SB_CB<0>")
	)
	(segment
		(start 49.431956 -278.681688)
		(end 49.5935 -278.520144)
		(width 0.14478)
		(layer "In4.Cu")
		(net "M_D_CPU1_SB_CB<0>")
	)
	(segment
		(start 54.875938 -278.349456)
		(end 54.875938 -278.671528)
		(width 0.14478)
		(layer "In4.Cu")
		(net "M_D_CPU1_SB_CB<0>")
	)
	(segment
		(start 78.523338 -272.788888)
		(end 78.523592 -272.788888)
		(width 0.0889)
		(layer "In4.Cu")
		(net "M_D_CPU1_SB_CB<0>")
	)
	(segment
		(start 64.977518 -272.79473)
		(end 64.977264 -272.603214)
		(width 0.14478)
		(layer "In4.Cu")
		(net "M_D_CPU1_SB_CB<0>")
	)
	(segment
		(start 55.036974 -278.832564)
		(end 55.271162 -278.832564)
		(width 0.14478)
		(layer "In4.Cu")
		(net "M_D_CPU1_SB_CB<0>")
	)
	(segment
		(start 91.085162 -272.731738)
		(end 90.930984 -272.466308)
		(width 0.0889)
		(layer "In4.Cu")
		(net "M_D_CPU1_SB_CB<0>")
	)
	(segment
		(start 58.103008 -277.660354)
		(end 58.240676 -277.798022)
		(width 0.14478)
		(layer "In4.Cu")
		(net "M_D_CPU1_SB_CB<0>")
	)
	(segment
		(start 38.078156 -278.904446)
		(end 38.2397 -278.742902)
		(width 0.14478)
		(layer "In4.Cu")
		(net "M_D_CPU1_SB_CB<0>")
	)
	(segment
		(start 88.289638 -272.793714)
		(end 88.29802 -272.788888)
		(width 0.0889)
		(layer "In4.Cu")
		(net "M_D_CPU1_SB_CB<0>")
	)
	(segment
		(start 47.043594 -278.681688)
		(end 47.205138 -278.520144)
		(width 0.14478)
		(layer "In4.Cu")
		(net "M_D_CPU1_SB_CB<0>")
	)
	(segment
		(start 46.88205 -278.904446)
		(end 47.043594 -278.742902)
		(width 0.14478)
		(layer "In4.Cu")
		(net "M_D_CPU1_SB_CB<0>")
	)
	(segment
		(start 56.705754 -278.510492)
		(end 57.029858 -278.510492)
		(width 0.14478)
		(layer "In4.Cu")
		(net "M_D_CPU1_SB_CB<0>")
	)
	(segment
		(start 38.791134 -278.681688)
		(end 38.791134 -278.742902)
		(width 0.14478)
		(layer "In4.Cu")
		(net "M_D_CPU1_SB_CB<0>")
	)
	(segment
		(start 61.076078 -276.69617)
		(end 61.075824 -276.504654)
		(width 0.14478)
		(layer "In4.Cu")
		(net "M_D_CPU1_SB_CB<0>")
	)
	(segment
		(start 64.977264 -272.375122)
		(end 65.157604 -272.194782)
		(width 0.14478)
		(layer "In4.Cu")
		(net "M_D_CPU1_SB_CB<0>")
	)
	(segment
		(start 54.875938 -278.671528)
		(end 55.036974 -278.832564)
		(width 0.14478)
		(layer "In4.Cu")
		(net "M_D_CPU1_SB_CB<0>")
	)
	(segment
		(start 54.480714 -278.18842)
		(end 54.714902 -278.18842)
		(width 0.14478)
		(layer "In4.Cu")
		(net "M_D_CPU1_SB_CB<0>")
	)
	(segment
		(start 42.448226 -278.520144)
		(end 43.298364 -277.670006)
		(width 0.14478)
		(layer "In4.Cu")
		(net "M_D_CPU1_SB_CB<0>")
	)
	(segment
		(start 55.432198 -278.671528)
		(end 55.432198 -278.349456)
		(width 0.14478)
		(layer "In4.Cu")
		(net "M_D_CPU1_SB_CB<0>")
	)
	(segment
		(start 62.036452 -275.315934)
		(end 62.456314 -275.315934)
		(width 0.14478)
		(layer "In4.Cu")
		(net "M_D_CPU1_SB_CB<0>")
	)
	(segment
		(start 84.529676 -272.793714)
		(end 84.538058 -272.788888)
		(width 0.0889)
		(layer "In4.Cu")
		(net "M_D_CPU1_SB_CB<0>")
	)
	(segment
		(start 37.84981 -278.904446)
		(end 38.078156 -278.904446)
		(width 0.14478)
		(layer "In4.Cu")
		(net "M_D_CPU1_SB_CB<0>")
	)
	(segment
		(start 81.344008 -272.788888)
		(end 81.35239 -272.793714)
		(width 0.0889)
		(layer "In4.Cu")
		(net "M_D_CPU1_SB_CB<0>")
	)
	(segment
		(start 77.504036 -271.787366)
		(end 78.446884 -272.730214)
		(width 0.0889)
		(layer "In4.Cu")
		(net "M_D_CPU1_SB_CB<0>")
	)
	(segment
		(start 64.196976 -273.15541)
		(end 64.377316 -272.97507)
		(width 0.14478)
		(layer "In4.Cu")
		(net "M_D_CPU1_SB_CB<0>")
	)
	(segment
		(start 65.577466 -272.194782)
		(end 65.757806 -272.014442)
		(width 0.14478)
		(layer "In4.Cu")
		(net "M_D_CPU1_SB_CB<0>")
	)
	(segment
		(start 37.688266 -278.681688)
		(end 37.688266 -278.742902)
		(width 0.14478)
		(layer "In4.Cu")
		(net "M_D_CPU1_SB_CB<0>")
	)
	(segment
		(start 63.597028 -273.755358)
		(end 64.01689 -273.755358)
		(width 0.14478)
		(layer "In4.Cu")
		(net "M_D_CPU1_SB_CB<0>")
	)
	(segment
		(start 61.075824 -276.276562)
		(end 61.256164 -276.096222)
		(width 0.14478)
		(layer "In4.Cu")
		(net "M_D_CPU1_SB_CB<0>")
	)
	(segment
		(start 47.043594 -278.742902)
		(end 47.043594 -278.681688)
		(width 0.14478)
		(layer "In4.Cu")
		(net "M_D_CPU1_SB_CB<0>")
	)
	(segment
		(start 55.593234 -278.18842)
		(end 55.827422 -278.18842)
		(width 0.14478)
		(layer "In4.Cu")
		(net "M_D_CPU1_SB_CB<0>")
	)
	(segment
		(start 38.2397 -278.681688)
		(end 38.401244 -278.520144)
		(width 0.14478)
		(layer "In4.Cu")
		(net "M_D_CPU1_SB_CB<0>")
	)
	(segment
		(start 63.416942 -274.355306)
		(end 63.416688 -274.16379)
		(width 0.14478)
		(layer "In4.Cu")
		(net "M_D_CPU1_SB_CB<0>")
	)
	(segment
		(start 91.06281 -272.81505)
		(end 91.085162 -272.731738)
		(width 0.0889)
		(layer "In4.Cu")
		(net "M_D_CPU1_SB_CB<0>")
	)
	(segment
		(start 43.298364 -277.670006)
		(end 45.1231 -277.670006)
		(width 0.14478)
		(layer "In4.Cu")
		(net "M_D_CPU1_SB_CB<0>")
	)
	(segment
		(start 55.988458 -278.671528)
		(end 56.149494 -278.832564)
		(width 0.14478)
		(layer "In4.Cu")
		(net "M_D_CPU1_SB_CB<0>")
	)
	(segment
		(start 46.330616 -278.520144)
		(end 46.49216 -278.681688)
		(width 0.14478)
		(layer "In4.Cu")
		(net "M_D_CPU1_SB_CB<0>")
	)
	(segment
		(start 58.796936 -277.798276)
		(end 58.796936 -277.522432)
		(width 0.14478)
		(layer "In4.Cu")
		(net "M_D_CPU1_SB_CB<0>")
	)
	(segment
		(start 37.526722 -278.520144)
		(end 37.688266 -278.681688)
		(width 0.14478)
		(layer "In4.Cu")
		(net "M_D_CPU1_SB_CB<0>")
	)
	(segment
		(start 57.879996 -277.660354)
		(end 58.103008 -277.660354)
		(width 0.14478)
		(layer "In4.Cu")
		(net "M_D_CPU1_SB_CB<0>")
	)
	(segment
		(start 46.49216 -278.681688)
		(end 46.49216 -278.742902)
		(width 0.14478)
		(layer "In4.Cu")
		(net "M_D_CPU1_SB_CB<0>")
	)
	(segment
		(start 89.229692 -272.793714)
		(end 89.238074 -272.788888)
		(width 0.0889)
		(layer "In4.Cu")
		(net "M_D_CPU1_SB_CB<0>")
	)
	(segment
		(start 90.74404 -272.788888)
		(end 90.752422 -272.793714)
		(width 0.0889)
		(layer "In4.Cu")
		(net "M_D_CPU1_SB_CB<0>")
	)
	(segment
		(start 62.636654 -275.135594)
		(end 62.6364 -274.944078)
		(width 0.14478)
		(layer "In4.Cu")
		(net "M_D_CPU1_SB_CB<0>")
	)
	(segment
		(start 53.812694 -278.832564)
		(end 54.158642 -278.832564)
		(width 0.14478)
		(layer "In4.Cu")
		(net "M_D_CPU1_SB_CB<0>")
	)
	(segment
		(start 39.504112 -278.520144)
		(end 42.448226 -278.520144)
		(width 0.14478)
		(layer "In4.Cu")
		(net "M_D_CPU1_SB_CB<0>")
	)
	(segment
		(start 48.880522 -278.681688)
		(end 48.880522 -278.735282)
		(width 0.14478)
		(layer "In4.Cu")
		(net "M_D_CPU1_SB_CB<0>")
	)
	(segment
		(start 54.319678 -278.349456)
		(end 54.480714 -278.18842)
		(width 0.14478)
		(layer "In4.Cu")
		(net "M_D_CPU1_SB_CB<0>")
	)
	(segment
		(start 57.029858 -278.510492)
		(end 57.879996 -277.660354)
		(width 0.14478)
		(layer "In4.Cu")
		(net "M_D_CPU1_SB_CB<0>")
	)
	(segment
		(start 58.934604 -277.384764)
		(end 59.967622 -277.384764)
		(width 0.14478)
		(layer "In4.Cu")
		(net "M_D_CPU1_SB_CB<0>")
	)
	(segment
		(start 38.401244 -278.520144)
		(end 38.62959 -278.520144)
		(width 0.14478)
		(layer "In4.Cu")
		(net "M_D_CPU1_SB_CB<0>")
	)
	(segment
		(start 37.688266 -278.742902)
		(end 37.84981 -278.904446)
		(width 0.14478)
		(layer "In4.Cu")
		(net "M_D_CPU1_SB_CB<0>")
	)
	(segment
		(start 47.205138 -278.520144)
		(end 48.718978 -278.520144)
		(width 0.14478)
		(layer "In4.Cu")
		(net "M_D_CPU1_SB_CB<0>")
	)
	(segment
		(start 58.240676 -277.798022)
		(end 58.240676 -277.798276)
		(width 0.14478)
		(layer "In4.Cu")
		(net "M_D_CPU1_SB_CB<0>")
	)
	(segment
		(start 64.977264 -272.603214)
		(end 64.977264 -272.375122)
		(width 0.14478)
		(layer "In4.Cu")
		(net "M_D_CPU1_SB_CB<0>")
	)
	(segment
		(start 61.256164 -276.096222)
		(end 61.676026 -276.096222)
		(width 0.14478)
		(layer "In4.Cu")
		(net "M_D_CPU1_SB_CB<0>")
	)
	(segment
		(start 38.791134 -278.742902)
		(end 38.952678 -278.904446)
		(width 0.14478)
		(layer "In4.Cu")
		(net "M_D_CPU1_SB_CB<0>")
	)
	(segment
		(start 64.196976 -273.383502)
		(end 64.196976 -273.15541)
		(width 0.14478)
		(layer "In4.Cu")
		(net "M_D_CPU1_SB_CB<0>")
	)
	(segment
		(start 76.88707 -271.787366)
		(end 77.504036 -271.787366)
		(width 0.0889)
		(layer "In4.Cu")
		(net "M_D_CPU1_SB_CB<0>")
	)
	(segment
		(start 58.796936 -277.522432)
		(end 58.934604 -277.384764)
		(width 0.14478)
		(layer "In4.Cu")
		(net "M_D_CPU1_SB_CB<0>")
	)
	(segment
		(start 52.650136 -277.670006)
		(end 53.812694 -278.832564)
		(width 0.14478)
		(layer "In4.Cu")
		(net "M_D_CPU1_SB_CB<0>")
	)
	(segment
		(start 80.39354 -272.782792)
		(end 80.403954 -272.788888)
		(width 0.0889)
		(layer "In4.Cu")
		(net "M_D_CPU1_SB_CB<0>")
	)
	(segment
		(start 45.973238 -278.520144)
		(end 46.330616 -278.520144)
		(width 0.14478)
		(layer "In4.Cu")
		(net "M_D_CPU1_SB_CB<0>")
	)
	(segment
		(start 60.895738 -276.87651)
		(end 61.076078 -276.69617)
		(width 0.14478)
		(layer "In4.Cu")
		(net "M_D_CPU1_SB_CB<0>")
	)
	(segment
		(start 86.044024 -272.788888)
		(end 86.052406 -272.793714)
		(width 0.0889)
		(layer "In4.Cu")
		(net "M_D_CPU1_SB_CB<0>")
	)
	(segment
		(start 65.157604 -272.194782)
		(end 65.577466 -272.194782)
		(width 0.14478)
		(layer "In4.Cu")
		(net "M_D_CPU1_SB_CB<0>")
	)
	(segment
		(start 45.1231 -277.670006)
		(end 45.973238 -278.520144)
		(width 0.14478)
		(layer "In4.Cu")
		(net "M_D_CPU1_SB_CB<0>")
	)
	(segment
		(start 85.10397 -272.788888)
		(end 85.112352 -272.793714)
		(width 0.0889)
		(layer "In4.Cu")
		(net "M_D_CPU1_SB_CB<0>")
	)
	(segment
		(start 55.827422 -278.18842)
		(end 55.988458 -278.349456)
		(width 0.14478)
		(layer "In4.Cu")
		(net "M_D_CPU1_SB_CB<0>")
	)
	(segment
		(start 48.718978 -278.520144)
		(end 48.880522 -278.681688)
		(width 0.14478)
		(layer "In4.Cu")
		(net "M_D_CPU1_SB_CB<0>")
	)
	(segment
		(start 39.181024 -278.904446)
		(end 39.342568 -278.742902)
		(width 0.14478)
		(layer "In4.Cu")
		(net "M_D_CPU1_SB_CB<0>")
	)
	(segment
		(start 66.052192 -271.300194)
		(end 75.960986 -271.300194)
		(width 0.14478)
		(layer "In4.Cu")
		(net "M_D_CPU1_SB_CB<0>")
	)
	(segment
		(start 61.075824 -276.504654)
		(end 61.075824 -276.276562)
		(width 0.14478)
		(layer "In4.Cu")
		(net "M_D_CPU1_SB_CB<0>")
	)
	(segment
		(start 62.81674 -274.535646)
		(end 63.236602 -274.535646)
		(width 0.14478)
		(layer "In4.Cu")
		(net "M_D_CPU1_SB_CB<0>")
	)
	(segment
		(start 54.158642 -278.832564)
		(end 54.319678 -278.671528)
		(width 0.14478)
		(layer "In4.Cu")
		(net "M_D_CPU1_SB_CB<0>")
	)
	(segment
		(start 64.19723 -273.575018)
		(end 64.196976 -273.383502)
		(width 0.14478)
		(layer "In4.Cu")
		(net "M_D_CPU1_SB_CB<0>")
	)
	(segment
		(start 63.416688 -273.935698)
		(end 63.597028 -273.755358)
		(width 0.14478)
		(layer "In4.Cu")
		(net "M_D_CPU1_SB_CB<0>")
	)
	(segment
		(start 64.377316 -272.97507)
		(end 64.797178 -272.97507)
		(width 0.14478)
		(layer "In4.Cu")
		(net "M_D_CPU1_SB_CB<0>")
	)
	(segment
		(start 76.399898 -271.300194)
		(end 76.88707 -271.787366)
		(width 0.0889)
		(layer "In4.Cu")
		(net "M_D_CPU1_SB_CB<0>")
	)
	(segment
		(start 38.62959 -278.520144)
		(end 38.791134 -278.681688)
		(width 0.14478)
		(layer "In4.Cu")
		(net "M_D_CPU1_SB_CB<0>")
	)
	(segment
		(start 83.589622 -272.793714)
		(end 83.598004 -272.788888)
		(width 0.0889)
		(layer "In4.Cu")
		(net "M_D_CPU1_SB_CB<0>")
	)
	(segment
		(start 46.49216 -278.742902)
		(end 46.653704 -278.904446)
		(width 0.14478)
		(layer "In4.Cu")
		(net "M_D_CPU1_SB_CB<0>")
	)
	(segment
		(start 62.456314 -275.315934)
		(end 62.636654 -275.135594)
		(width 0.14478)
		(layer "In4.Cu")
		(net "M_D_CPU1_SB_CB<0>")
	)
	(segment
		(start 54.319678 -278.671528)
		(end 54.319678 -278.349456)
		(width 0.14478)
		(layer "In4.Cu")
		(net "M_D_CPU1_SB_CB<0>")
	)
	(segment
		(start 61.856112 -275.724366)
		(end 61.856112 -275.496274)
		(width 0.14478)
		(layer "In4.Cu")
		(net "M_D_CPU1_SB_CB<0>")
	)
	(segment
		(start 58.240676 -277.798276)
		(end 58.378344 -277.935944)
		(width 0.14478)
		(layer "In4.Cu")
		(net "M_D_CPU1_SB_CB<0>")
	)
	(segment
		(start 46.653704 -278.904446)
		(end 46.88205 -278.904446)
		(width 0.14478)
		(layer "In4.Cu")
		(net "M_D_CPU1_SB_CB<0>")
	)
	(segment
		(start 39.342568 -278.681688)
		(end 39.504112 -278.520144)
		(width 0.14478)
		(layer "In4.Cu")
		(net "M_D_CPU1_SB_CB<0>")
	)
	(segment
		(start 49.042066 -278.896826)
		(end 49.270412 -278.896826)
		(width 0.14478)
		(layer "In4.Cu")
		(net "M_D_CPU1_SB_CB<0>")
	)
	(segment
		(start 48.880522 -278.735282)
		(end 49.042066 -278.896826)
		(width 0.14478)
		(layer "In4.Cu")
		(net "M_D_CPU1_SB_CB<0>")
	)
	(segment
		(start 55.271162 -278.832564)
		(end 55.432198 -278.671528)
		(width 0.14478)
		(layer "In4.Cu")
		(net "M_D_CPU1_SB_CB<0>")
	)
	(segment
		(start 79.463138 -272.788888)
		(end 79.47152 -272.793714)
		(width 0.0889)
		(layer "In4.Cu")
		(net "M_D_CPU1_SB_CB<0>")
	)
	(segment
		(start 38.952678 -278.904446)
		(end 39.181024 -278.904446)
		(width 0.14478)
		(layer "In4.Cu")
		(net "M_D_CPU1_SB_CB<0>")
	)
	(segment
		(start 49.431956 -278.735282)
		(end 49.431956 -278.681688)
		(width 0.14478)
		(layer "In4.Cu")
		(net "M_D_CPU1_SB_CB<0>")
	)
	(segment
		(start 55.432198 -278.349456)
		(end 55.593234 -278.18842)
		(width 0.14478)
		(layer "In4.Cu")
		(net "M_D_CPU1_SB_CB<0>")
	)
	(segment
		(start 65.757552 -271.822926)
		(end 65.757552 -271.594834)
		(width 0.14478)
		(layer "In4.Cu")
		(net "M_D_CPU1_SB_CB<0>")
	)
	(segment
		(start 54.714902 -278.18842)
		(end 54.875938 -278.349456)
		(width 0.14478)
		(layer "In4.Cu")
		(net "M_D_CPU1_SB_CB<0>")
	)
	(segment
		(start 55.988458 -278.349456)
		(end 55.988458 -278.671528)
		(width 0.14478)
		(layer "In4.Cu")
		(net "M_D_CPU1_SB_CB<0>")
	)
	(segment
		(start 65.757552 -271.594834)
		(end 66.052192 -271.300194)
		(width 0.14478)
		(layer "In4.Cu")
		(net "M_D_CPU1_SB_CB<0>")
	)
	(segment
		(start 78.897734 -272.788634)
		(end 78.903322 -272.785332)
		(width 0.0889)
		(layer "In4.Cu")
		(net "M_D_CPU1_SB_CB<0>")
	)
	(arc
		(start 88.29802 -272.788888)
		(mid 88.580976 -272.712711)
		(end 88.863932 -272.788888)
		(width 0.0889)
		(layer "In4.Cu")
		(net "M_D_CPU1_SB_CB<0>")
	)
	(arc
		(start 81.35239 -272.793714)
		(mid 81.535898 -272.839208)
		(end 81.71815 -272.788888)
		(width 0.0889)
		(layer "In4.Cu")
		(net "M_D_CPU1_SB_CB<0>")
	)
	(arc
		(start 78.446884 -272.730214)
		(mid 78.483211 -272.762027)
		(end 78.523338 -272.788888)
		(width 0.0889)
		(layer "In4.Cu")
		(net "M_D_CPU1_SB_CB<0>")
	)
	(arc
		(start 87.357966 -272.788888)
		(mid 87.640922 -272.712711)
		(end 87.923878 -272.788888)
		(width 0.0889)
		(layer "In4.Cu")
		(net "M_D_CPU1_SB_CB<0>")
	)
	(arc
		(start 82.65795 -272.788888)
		(mid 82.940906 -272.712711)
		(end 83.223862 -272.788888)
		(width 0.0889)
		(layer "In4.Cu")
		(net "M_D_CPU1_SB_CB<0>")
	)
	(arc
		(start 78.523592 -272.788888)
		(mid 78.70022 -272.839121)
		(end 78.879446 -272.799048)
		(width 0.0889)
		(layer "In4.Cu")
		(net "M_D_CPU1_SB_CB<0>")
	)
	(arc
		(start 81.71815 -272.788888)
		(mid 82.001106 -272.712711)
		(end 82.284062 -272.788888)
		(width 0.0889)
		(layer "In4.Cu")
		(net "M_D_CPU1_SB_CB<0>")
	)
	(arc
		(start 83.598004 -272.788888)
		(mid 83.88096 -272.712711)
		(end 84.163916 -272.788888)
		(width 0.0889)
		(layer "In4.Cu")
		(net "M_D_CPU1_SB_CB<0>")
	)
	(arc
		(start 79.837788 -272.788888)
		(mid 80.114855 -272.712617)
		(end 80.39354 -272.782792)
		(width 0.0889)
		(layer "In4.Cu")
		(net "M_D_CPU1_SB_CB<0>")
	)
	(arc
		(start 88.863932 -272.788888)
		(mid 89.046183 -272.839238)
		(end 89.229692 -272.793714)
		(width 0.0889)
		(layer "In4.Cu")
		(net "M_D_CPU1_SB_CB<0>")
	)
	(arc
		(start 79.47152 -272.793714)
		(mid 79.655282 -272.83933)
		(end 79.837788 -272.788888)
		(width 0.0889)
		(layer "In4.Cu")
		(net "M_D_CPU1_SB_CB<0>")
	)
	(arc
		(start 90.178128 -272.788888)
		(mid 90.461084 -272.712711)
		(end 90.74404 -272.788888)
		(width 0.0889)
		(layer "In4.Cu")
		(net "M_D_CPU1_SB_CB<0>")
	)
	(arc
		(start 89.238074 -272.788888)
		(mid 89.52103 -272.712711)
		(end 89.803986 -272.788888)
		(width 0.0889)
		(layer "In4.Cu")
		(net "M_D_CPU1_SB_CB<0>")
	)
	(arc
		(start 87.923878 -272.788888)
		(mid 88.106129 -272.839238)
		(end 88.289638 -272.793714)
		(width 0.0889)
		(layer "In4.Cu")
		(net "M_D_CPU1_SB_CB<0>")
	)
	(arc
		(start 84.538058 -272.788888)
		(mid 84.821014 -272.712711)
		(end 85.10397 -272.788888)
		(width 0.0889)
		(layer "In4.Cu")
		(net "M_D_CPU1_SB_CB<0>")
	)
	(arc
		(start 86.052406 -272.793714)
		(mid 86.235914 -272.839208)
		(end 86.418166 -272.788888)
		(width 0.0889)
		(layer "In4.Cu")
		(net "M_D_CPU1_SB_CB<0>")
	)
	(arc
		(start 80.403954 -272.788888)
		(mid 80.586205 -272.839238)
		(end 80.769714 -272.793714)
		(width 0.0889)
		(layer "In4.Cu")
		(net "M_D_CPU1_SB_CB<0>")
	)
	(arc
		(start 82.284062 -272.788888)
		(mid 82.471006 -272.839143)
		(end 82.65795 -272.788888)
		(width 0.0889)
		(layer "In4.Cu")
		(net "M_D_CPU1_SB_CB<0>")
	)
	(arc
		(start 86.984078 -272.788888)
		(mid 87.171022 -272.839143)
		(end 87.357966 -272.788888)
		(width 0.0889)
		(layer "In4.Cu")
		(net "M_D_CPU1_SB_CB<0>")
	)
	(arc
		(start 90.752422 -272.793714)
		(mid 90.905292 -272.838355)
		(end 91.06281 -272.81505)
		(width 0.0889)
		(layer "In4.Cu")
		(net "M_D_CPU1_SB_CB<0>")
	)
	(arc
		(start 89.812368 -272.793714)
		(mid 89.995876 -272.839208)
		(end 90.178128 -272.788888)
		(width 0.0889)
		(layer "In4.Cu")
		(net "M_D_CPU1_SB_CB<0>")
	)
	(arc
		(start 85.478112 -272.788888)
		(mid 85.761068 -272.712711)
		(end 86.044024 -272.788888)
		(width 0.0889)
		(layer "In4.Cu")
		(net "M_D_CPU1_SB_CB<0>")
	)
	(arc
		(start 84.163916 -272.788888)
		(mid 84.346167 -272.839238)
		(end 84.529676 -272.793714)
		(width 0.0889)
		(layer "In4.Cu")
		(net "M_D_CPU1_SB_CB<0>")
	)
	(arc
		(start 80.778096 -272.788888)
		(mid 81.061052 -272.712711)
		(end 81.344008 -272.788888)
		(width 0.0889)
		(layer "In4.Cu")
		(net "M_D_CPU1_SB_CB<0>")
	)
	(arc
		(start 83.223862 -272.788888)
		(mid 83.406113 -272.839238)
		(end 83.589622 -272.793714)
		(width 0.0889)
		(layer "In4.Cu")
		(net "M_D_CPU1_SB_CB<0>")
	)
	(arc
		(start 78.903322 -272.785332)
		(mid 79.183711 -272.712663)
		(end 79.463138 -272.788888)
		(width 0.0889)
		(layer "In4.Cu")
		(net "M_D_CPU1_SB_CB<0>")
	)
	(arc
		(start 85.112352 -272.793714)
		(mid 85.29586 -272.839208)
		(end 85.478112 -272.788888)
		(width 0.0889)
		(layer "In4.Cu")
		(net "M_D_CPU1_SB_CB<0>")
	)
	(arc
		(start 86.418166 -272.788888)
		(mid 86.701122 -272.712711)
		(end 86.984078 -272.788888)
		(width 0.0889)
		(layer "In4.Cu")
		(net "M_D_CPU1_SB_CB<0>")
	)
	(segment
		(start 91.397836 -264.10031)
		(end 90.930984 -264.366248)
		(width 0.10668)
		(layer "F.Cu")
		(net "M_D_CPU1_SB_CA<6>")
	)
	(segment
		(start 50.976276 -266.081764)
		(end 51.297586 -265.760454)
		(width 0.14478)
		(layer "In4.Cu")
		(net "M_D_CPU1_SB_CA<6>")
	)
	(segment
		(start 76.261722 -264.619994)
		(end 76.54417 -264.337546)
		(width 0.0889)
		(layer "In4.Cu")
		(net "M_D_CPU1_SB_CA<6>")
	)
	(segment
		(start 89.229692 -264.693654)
		(end 89.238074 -264.688828)
		(width 0.0889)
		(layer "In4.Cu")
		(net "M_D_CPU1_SB_CA<6>")
	)
	(segment
		(start 58.024014 -265.760454)
		(end 58.345324 -266.081764)
		(width 0.14478)
		(layer "In4.Cu")
		(net "M_D_CPU1_SB_CA<6>")
	)
	(segment
		(start 57.789064 -265.760454)
		(end 58.024014 -265.760454)
		(width 0.14478)
		(layer "In4.Cu")
		(net "M_D_CPU1_SB_CA<6>")
	)
	(segment
		(start 56.120284 -266.081764)
		(end 56.355234 -266.081764)
		(width 0.14478)
		(layer "In4.Cu")
		(net "M_D_CPU1_SB_CA<6>")
	)
	(segment
		(start 54.376828 -265.760454)
		(end 55.798974 -265.760454)
		(width 0.14478)
		(layer "In4.Cu")
		(net "M_D_CPU1_SB_CA<6>")
	)
	(segment
		(start 84.529676 -264.693654)
		(end 84.538058 -264.688828)
		(width 0.0889)
		(layer "In4.Cu")
		(net "M_D_CPU1_SB_CA<6>")
	)
	(segment
		(start 41.79697 -265.760454)
		(end 42.11828 -266.081764)
		(width 0.14478)
		(layer "In4.Cu")
		(net "M_D_CPU1_SB_CA<6>")
	)
	(segment
		(start 45.104558 -266.081764)
		(end 45.339508 -266.081764)
		(width 0.14478)
		(layer "In4.Cu")
		(net "M_D_CPU1_SB_CA<6>")
	)
	(segment
		(start 38.136322 -266.081764)
		(end 38.457632 -265.760454)
		(width 0.14478)
		(layer "In4.Cu")
		(net "M_D_CPU1_SB_CA<6>")
	)
	(segment
		(start 49.072546 -265.760454)
		(end 49.307496 -265.760454)
		(width 0.14478)
		(layer "In4.Cu")
		(net "M_D_CPU1_SB_CA<6>")
	)
	(segment
		(start 85.10397 -264.688828)
		(end 85.112352 -264.693654)
		(width 0.0889)
		(layer "In4.Cu")
		(net "M_D_CPU1_SB_CA<6>")
	)
	(segment
		(start 80.769714 -264.693654)
		(end 80.778096 -264.688828)
		(width 0.0889)
		(layer "In4.Cu")
		(net "M_D_CPU1_SB_CA<6>")
	)
	(segment
		(start 44.783248 -265.760454)
		(end 45.104558 -266.081764)
		(width 0.14478)
		(layer "In4.Cu")
		(net "M_D_CPU1_SB_CA<6>")
	)
	(segment
		(start 49.863756 -266.081764)
		(end 50.185066 -265.760454)
		(width 0.14478)
		(layer "In4.Cu")
		(net "M_D_CPU1_SB_CA<6>")
	)
	(segment
		(start 42.90949 -265.760454)
		(end 43.2308 -266.081764)
		(width 0.14478)
		(layer "In4.Cu")
		(net "M_D_CPU1_SB_CA<6>")
	)
	(segment
		(start 75.960986 -264.619994)
		(end 76.261722 -264.619994)
		(width 0.0889)
		(layer "In4.Cu")
		(net "M_D_CPU1_SB_CA<6>")
	)
	(segment
		(start 79.463138 -264.688828)
		(end 79.47152 -264.693654)
		(width 0.0889)
		(layer "In4.Cu")
		(net "M_D_CPU1_SB_CA<6>")
	)
	(segment
		(start 52.386738 -265.760454)
		(end 52.708048 -266.081764)
		(width 0.14478)
		(layer "In4.Cu")
		(net "M_D_CPU1_SB_CA<6>")
	)
	(segment
		(start 37.901372 -266.081764)
		(end 38.136322 -266.081764)
		(width 0.14478)
		(layer "In4.Cu")
		(net "M_D_CPU1_SB_CA<6>")
	)
	(segment
		(start 43.2308 -266.081764)
		(end 43.46575 -266.081764)
		(width 0.14478)
		(layer "In4.Cu")
		(net "M_D_CPU1_SB_CA<6>")
	)
	(segment
		(start 86.044024 -264.688828)
		(end 86.052406 -264.693654)
		(width 0.0889)
		(layer "In4.Cu")
		(net "M_D_CPU1_SB_CA<6>")
	)
	(segment
		(start 80.39354 -264.682732)
		(end 80.403954 -264.688828)
		(width 0.0889)
		(layer "In4.Cu")
		(net "M_D_CPU1_SB_CA<6>")
	)
	(segment
		(start 43.78706 -265.760454)
		(end 44.783248 -265.760454)
		(width 0.14478)
		(layer "In4.Cu")
		(net "M_D_CPU1_SB_CA<6>")
	)
	(segment
		(start 50.185066 -265.760454)
		(end 50.420016 -265.760454)
		(width 0.14478)
		(layer "In4.Cu")
		(net "M_D_CPU1_SB_CA<6>")
	)
	(segment
		(start 59.457844 -266.081764)
		(end 59.692794 -266.081764)
		(width 0.14478)
		(layer "In4.Cu")
		(net "M_D_CPU1_SB_CA<6>")
	)
	(segment
		(start 78.879446 -264.698988)
		(end 78.897734 -264.688574)
		(width 0.0889)
		(layer "In4.Cu")
		(net "M_D_CPU1_SB_CA<6>")
	)
	(segment
		(start 41.24071 -266.081764)
		(end 41.56202 -265.760454)
		(width 0.14478)
		(layer "In4.Cu")
		(net "M_D_CPU1_SB_CA<6>")
	)
	(segment
		(start 78.523338 -264.688828)
		(end 78.523592 -264.688828)
		(width 0.0889)
		(layer "In4.Cu")
		(net "M_D_CPU1_SB_CA<6>")
	)
	(segment
		(start 56.355234 -266.081764)
		(end 56.676544 -265.760454)
		(width 0.14478)
		(layer "In4.Cu")
		(net "M_D_CPU1_SB_CA<6>")
	)
	(segment
		(start 38.457632 -265.760454)
		(end 38.692582 -265.760454)
		(width 0.14478)
		(layer "In4.Cu")
		(net "M_D_CPU1_SB_CA<6>")
	)
	(segment
		(start 78.154276 -264.337546)
		(end 78.446884 -264.630154)
		(width 0.0889)
		(layer "In4.Cu")
		(net "M_D_CPU1_SB_CA<6>")
	)
	(segment
		(start 59.692794 -266.081764)
		(end 61.154564 -264.619994)
		(width 0.14478)
		(layer "In4.Cu")
		(net "M_D_CPU1_SB_CA<6>")
	)
	(segment
		(start 39.013892 -266.081764)
		(end 39.248842 -266.081764)
		(width 0.14478)
		(layer "In4.Cu")
		(net "M_D_CPU1_SB_CA<6>")
	)
	(segment
		(start 49.307496 -265.760454)
		(end 49.628806 -266.081764)
		(width 0.14478)
		(layer "In4.Cu")
		(net "M_D_CPU1_SB_CA<6>")
	)
	(segment
		(start 53.820568 -266.081764)
		(end 54.055518 -266.081764)
		(width 0.14478)
		(layer "In4.Cu")
		(net "M_D_CPU1_SB_CA<6>")
	)
	(segment
		(start 45.895768 -265.760454)
		(end 46.217078 -266.081764)
		(width 0.14478)
		(layer "In4.Cu")
		(net "M_D_CPU1_SB_CA<6>")
	)
	(segment
		(start 52.942998 -266.081764)
		(end 53.264308 -265.760454)
		(width 0.14478)
		(layer "In4.Cu")
		(net "M_D_CPU1_SB_CA<6>")
	)
	(segment
		(start 53.499258 -265.760454)
		(end 53.820568 -266.081764)
		(width 0.14478)
		(layer "In4.Cu")
		(net "M_D_CPU1_SB_CA<6>")
	)
	(segment
		(start 56.676544 -265.760454)
		(end 56.911494 -265.760454)
		(width 0.14478)
		(layer "In4.Cu")
		(net "M_D_CPU1_SB_CA<6>")
	)
	(segment
		(start 45.660818 -265.760454)
		(end 45.895768 -265.760454)
		(width 0.14478)
		(layer "In4.Cu")
		(net "M_D_CPU1_SB_CA<6>")
	)
	(segment
		(start 39.570152 -265.760454)
		(end 40.68445 -265.760454)
		(width 0.14478)
		(layer "In4.Cu")
		(net "M_D_CPU1_SB_CA<6>")
	)
	(segment
		(start 89.803986 -264.688828)
		(end 89.812368 -264.693654)
		(width 0.0889)
		(layer "In4.Cu")
		(net "M_D_CPU1_SB_CA<6>")
	)
	(segment
		(start 39.248842 -266.081764)
		(end 39.570152 -265.760454)
		(width 0.14478)
		(layer "In4.Cu")
		(net "M_D_CPU1_SB_CA<6>")
	)
	(segment
		(start 50.420016 -265.760454)
		(end 50.741326 -266.081764)
		(width 0.14478)
		(layer "In4.Cu")
		(net "M_D_CPU1_SB_CA<6>")
	)
	(segment
		(start 82.284062 -264.688828)
		(end 82.292444 -264.693654)
		(width 0.0889)
		(layer "In4.Cu")
		(net "M_D_CPU1_SB_CA<6>")
	)
	(segment
		(start 42.11828 -266.081764)
		(end 42.35323 -266.081764)
		(width 0.14478)
		(layer "In4.Cu")
		(net "M_D_CPU1_SB_CA<6>")
	)
	(segment
		(start 46.773338 -265.760454)
		(end 48.194976 -265.760454)
		(width 0.14478)
		(layer "In4.Cu")
		(net "M_D_CPU1_SB_CA<6>")
	)
	(segment
		(start 51.297586 -265.760454)
		(end 52.386738 -265.760454)
		(width 0.14478)
		(layer "In4.Cu")
		(net "M_D_CPU1_SB_CA<6>")
	)
	(segment
		(start 37.220906 -265.760454)
		(end 37.580062 -265.760454)
		(width 0.14478)
		(layer "In4.Cu")
		(net "M_D_CPU1_SB_CA<6>")
	)
	(segment
		(start 54.055518 -266.081764)
		(end 54.376828 -265.760454)
		(width 0.14478)
		(layer "In4.Cu")
		(net "M_D_CPU1_SB_CA<6>")
	)
	(segment
		(start 56.911494 -265.760454)
		(end 57.232804 -266.081764)
		(width 0.14478)
		(layer "In4.Cu")
		(net "M_D_CPU1_SB_CA<6>")
	)
	(segment
		(start 57.467754 -266.081764)
		(end 57.789064 -265.760454)
		(width 0.14478)
		(layer "In4.Cu")
		(net "M_D_CPU1_SB_CA<6>")
	)
	(segment
		(start 52.708048 -266.081764)
		(end 52.942998 -266.081764)
		(width 0.14478)
		(layer "In4.Cu")
		(net "M_D_CPU1_SB_CA<6>")
	)
	(segment
		(start 36.795964 -266.185396)
		(end 37.220906 -265.760454)
		(width 0.14478)
		(layer "In4.Cu")
		(net "M_D_CPU1_SB_CA<6>")
	)
	(segment
		(start 42.67454 -265.760454)
		(end 42.90949 -265.760454)
		(width 0.14478)
		(layer "In4.Cu")
		(net "M_D_CPU1_SB_CA<6>")
	)
	(segment
		(start 81.344008 -264.688828)
		(end 81.35239 -264.693654)
		(width 0.0889)
		(layer "In4.Cu")
		(net "M_D_CPU1_SB_CA<6>")
	)
	(segment
		(start 57.232804 -266.081764)
		(end 57.467754 -266.081764)
		(width 0.14478)
		(layer "In4.Cu")
		(net "M_D_CPU1_SB_CA<6>")
	)
	(segment
		(start 49.628806 -266.081764)
		(end 49.863756 -266.081764)
		(width 0.14478)
		(layer "In4.Cu")
		(net "M_D_CPU1_SB_CA<6>")
	)
	(segment
		(start 42.35323 -266.081764)
		(end 42.67454 -265.760454)
		(width 0.14478)
		(layer "In4.Cu")
		(net "M_D_CPU1_SB_CA<6>")
	)
	(segment
		(start 55.798974 -265.760454)
		(end 56.120284 -266.081764)
		(width 0.14478)
		(layer "In4.Cu")
		(net "M_D_CPU1_SB_CA<6>")
	)
	(segment
		(start 50.741326 -266.081764)
		(end 50.976276 -266.081764)
		(width 0.14478)
		(layer "In4.Cu")
		(net "M_D_CPU1_SB_CA<6>")
	)
	(segment
		(start 58.580274 -266.081764)
		(end 58.901584 -265.760454)
		(width 0.14478)
		(layer "In4.Cu")
		(net "M_D_CPU1_SB_CA<6>")
	)
	(segment
		(start 76.54417 -264.337546)
		(end 78.154276 -264.337546)
		(width 0.0889)
		(layer "In4.Cu")
		(net "M_D_CPU1_SB_CA<6>")
	)
	(segment
		(start 46.452028 -266.081764)
		(end 46.773338 -265.760454)
		(width 0.14478)
		(layer "In4.Cu")
		(net "M_D_CPU1_SB_CA<6>")
	)
	(segment
		(start 78.897734 -264.688574)
		(end 78.903322 -264.685272)
		(width 0.0889)
		(layer "In4.Cu")
		(net "M_D_CPU1_SB_CA<6>")
	)
	(segment
		(start 58.901584 -265.760454)
		(end 59.136534 -265.760454)
		(width 0.14478)
		(layer "In4.Cu")
		(net "M_D_CPU1_SB_CA<6>")
	)
	(segment
		(start 41.56202 -265.760454)
		(end 41.79697 -265.760454)
		(width 0.14478)
		(layer "In4.Cu")
		(net "M_D_CPU1_SB_CA<6>")
	)
	(segment
		(start 59.136534 -265.760454)
		(end 59.457844 -266.081764)
		(width 0.14478)
		(layer "In4.Cu")
		(net "M_D_CPU1_SB_CA<6>")
	)
	(segment
		(start 61.154564 -264.619994)
		(end 75.960986 -264.619994)
		(width 0.14478)
		(layer "In4.Cu")
		(net "M_D_CPU1_SB_CA<6>")
	)
	(segment
		(start 41.00576 -266.081764)
		(end 41.24071 -266.081764)
		(width 0.14478)
		(layer "In4.Cu")
		(net "M_D_CPU1_SB_CA<6>")
	)
	(segment
		(start 48.516286 -266.081764)
		(end 48.751236 -266.081764)
		(width 0.14478)
		(layer "In4.Cu")
		(net "M_D_CPU1_SB_CA<6>")
	)
	(segment
		(start 91.06281 -264.71499)
		(end 91.085162 -264.631678)
		(width 0.0889)
		(layer "In4.Cu")
		(net "M_D_CPU1_SB_CA<6>")
	)
	(segment
		(start 46.217078 -266.081764)
		(end 46.452028 -266.081764)
		(width 0.14478)
		(layer "In4.Cu")
		(net "M_D_CPU1_SB_CA<6>")
	)
	(segment
		(start 43.46575 -266.081764)
		(end 43.78706 -265.760454)
		(width 0.14478)
		(layer "In4.Cu")
		(net "M_D_CPU1_SB_CA<6>")
	)
	(segment
		(start 48.194976 -265.760454)
		(end 48.516286 -266.081764)
		(width 0.14478)
		(layer "In4.Cu")
		(net "M_D_CPU1_SB_CA<6>")
	)
	(segment
		(start 48.751236 -266.081764)
		(end 49.072546 -265.760454)
		(width 0.14478)
		(layer "In4.Cu")
		(net "M_D_CPU1_SB_CA<6>")
	)
	(segment
		(start 90.74404 -264.688828)
		(end 90.752422 -264.693654)
		(width 0.0889)
		(layer "In4.Cu")
		(net "M_D_CPU1_SB_CA<6>")
	)
	(segment
		(start 91.085162 -264.631678)
		(end 90.930984 -264.366248)
		(width 0.0889)
		(layer "In4.Cu")
		(net "M_D_CPU1_SB_CA<6>")
	)
	(segment
		(start 53.264308 -265.760454)
		(end 53.499258 -265.760454)
		(width 0.14478)
		(layer "In4.Cu")
		(net "M_D_CPU1_SB_CA<6>")
	)
	(segment
		(start 40.68445 -265.760454)
		(end 41.00576 -266.081764)
		(width 0.14478)
		(layer "In4.Cu")
		(net "M_D_CPU1_SB_CA<6>")
	)
	(segment
		(start 45.339508 -266.081764)
		(end 45.660818 -265.760454)
		(width 0.14478)
		(layer "In4.Cu")
		(net "M_D_CPU1_SB_CA<6>")
	)
	(segment
		(start 88.289638 -264.693654)
		(end 88.29802 -264.688828)
		(width 0.0889)
		(layer "In4.Cu")
		(net "M_D_CPU1_SB_CA<6>")
	)
	(segment
		(start 58.345324 -266.081764)
		(end 58.580274 -266.081764)
		(width 0.14478)
		(layer "In4.Cu")
		(net "M_D_CPU1_SB_CA<6>")
	)
	(segment
		(start 37.580062 -265.760454)
		(end 37.901372 -266.081764)
		(width 0.14478)
		(layer "In4.Cu")
		(net "M_D_CPU1_SB_CA<6>")
	)
	(segment
		(start 38.692582 -265.760454)
		(end 39.013892 -266.081764)
		(width 0.14478)
		(layer "In4.Cu")
		(net "M_D_CPU1_SB_CA<6>")
	)
	(arc
		(start 85.112352 -264.693654)
		(mid 85.29586 -264.739148)
		(end 85.478112 -264.688828)
		(width 0.0889)
		(layer "In4.Cu")
		(net "M_D_CPU1_SB_CA<6>")
	)
	(arc
		(start 88.863932 -264.688828)
		(mid 89.046183 -264.739178)
		(end 89.229692 -264.693654)
		(width 0.0889)
		(layer "In4.Cu")
		(net "M_D_CPU1_SB_CA<6>")
	)
	(arc
		(start 78.523592 -264.688828)
		(mid 78.70022 -264.739061)
		(end 78.879446 -264.698988)
		(width 0.0889)
		(layer "In4.Cu")
		(net "M_D_CPU1_SB_CA<6>")
	)
	(arc
		(start 79.837788 -264.688828)
		(mid 80.114855 -264.612557)
		(end 80.39354 -264.682732)
		(width 0.0889)
		(layer "In4.Cu")
		(net "M_D_CPU1_SB_CA<6>")
	)
	(arc
		(start 78.903322 -264.685272)
		(mid 79.183711 -264.612603)
		(end 79.463138 -264.688828)
		(width 0.0889)
		(layer "In4.Cu")
		(net "M_D_CPU1_SB_CA<6>")
	)
	(arc
		(start 79.47152 -264.693654)
		(mid 79.655282 -264.73927)
		(end 79.837788 -264.688828)
		(width 0.0889)
		(layer "In4.Cu")
		(net "M_D_CPU1_SB_CA<6>")
	)
	(arc
		(start 90.752422 -264.693654)
		(mid 90.905292 -264.738295)
		(end 91.06281 -264.71499)
		(width 0.0889)
		(layer "In4.Cu")
		(net "M_D_CPU1_SB_CA<6>")
	)
	(arc
		(start 86.984078 -264.688828)
		(mid 87.171022 -264.739083)
		(end 87.357966 -264.688828)
		(width 0.0889)
		(layer "In4.Cu")
		(net "M_D_CPU1_SB_CA<6>")
	)
	(arc
		(start 86.418166 -264.688828)
		(mid 86.701122 -264.612651)
		(end 86.984078 -264.688828)
		(width 0.0889)
		(layer "In4.Cu")
		(net "M_D_CPU1_SB_CA<6>")
	)
	(arc
		(start 88.29802 -264.688828)
		(mid 88.580976 -264.612651)
		(end 88.863932 -264.688828)
		(width 0.0889)
		(layer "In4.Cu")
		(net "M_D_CPU1_SB_CA<6>")
	)
	(arc
		(start 80.403954 -264.688828)
		(mid 80.586205 -264.739178)
		(end 80.769714 -264.693654)
		(width 0.0889)
		(layer "In4.Cu")
		(net "M_D_CPU1_SB_CA<6>")
	)
	(arc
		(start 85.478112 -264.688828)
		(mid 85.761068 -264.612651)
		(end 86.044024 -264.688828)
		(width 0.0889)
		(layer "In4.Cu")
		(net "M_D_CPU1_SB_CA<6>")
	)
	(arc
		(start 89.812368 -264.693654)
		(mid 89.995876 -264.739148)
		(end 90.178128 -264.688828)
		(width 0.0889)
		(layer "In4.Cu")
		(net "M_D_CPU1_SB_CA<6>")
	)
	(arc
		(start 87.923878 -264.688828)
		(mid 88.106129 -264.739178)
		(end 88.289638 -264.693654)
		(width 0.0889)
		(layer "In4.Cu")
		(net "M_D_CPU1_SB_CA<6>")
	)
	(arc
		(start 78.446884 -264.630154)
		(mid 78.483211 -264.661967)
		(end 78.523338 -264.688828)
		(width 0.0889)
		(layer "In4.Cu")
		(net "M_D_CPU1_SB_CA<6>")
	)
	(arc
		(start 83.598004 -264.688828)
		(mid 83.88096 -264.612651)
		(end 84.163916 -264.688828)
		(width 0.0889)
		(layer "In4.Cu")
		(net "M_D_CPU1_SB_CA<6>")
	)
	(arc
		(start 80.778096 -264.688828)
		(mid 81.061052 -264.612651)
		(end 81.344008 -264.688828)
		(width 0.0889)
		(layer "In4.Cu")
		(net "M_D_CPU1_SB_CA<6>")
	)
	(arc
		(start 87.357966 -264.688828)
		(mid 87.640922 -264.612651)
		(end 87.923878 -264.688828)
		(width 0.0889)
		(layer "In4.Cu")
		(net "M_D_CPU1_SB_CA<6>")
	)
	(arc
		(start 82.292444 -264.693654)
		(mid 82.475952 -264.739148)
		(end 82.658204 -264.688828)
		(width 0.0889)
		(layer "In4.Cu")
		(net "M_D_CPU1_SB_CA<6>")
	)
	(arc
		(start 83.224116 -264.688828)
		(mid 83.41106 -264.739083)
		(end 83.598004 -264.688828)
		(width 0.0889)
		(layer "In4.Cu")
		(net "M_D_CPU1_SB_CA<6>")
	)
	(arc
		(start 81.71815 -264.688828)
		(mid 82.001106 -264.612651)
		(end 82.284062 -264.688828)
		(width 0.0889)
		(layer "In4.Cu")
		(net "M_D_CPU1_SB_CA<6>")
	)
	(arc
		(start 82.658204 -264.688828)
		(mid 82.94116 -264.612651)
		(end 83.224116 -264.688828)
		(width 0.0889)
		(layer "In4.Cu")
		(net "M_D_CPU1_SB_CA<6>")
	)
	(arc
		(start 90.178128 -264.688828)
		(mid 90.461084 -264.612651)
		(end 90.74404 -264.688828)
		(width 0.0889)
		(layer "In4.Cu")
		(net "M_D_CPU1_SB_CA<6>")
	)
	(arc
		(start 86.052406 -264.693654)
		(mid 86.235914 -264.739148)
		(end 86.418166 -264.688828)
		(width 0.0889)
		(layer "In4.Cu")
		(net "M_D_CPU1_SB_CA<6>")
	)
	(arc
		(start 84.538058 -264.688828)
		(mid 84.821014 -264.612651)
		(end 85.10397 -264.688828)
		(width 0.0889)
		(layer "In4.Cu")
		(net "M_D_CPU1_SB_CA<6>")
	)
	(arc
		(start 89.238074 -264.688828)
		(mid 89.52103 -264.612651)
		(end 89.803986 -264.688828)
		(width 0.0889)
		(layer "In4.Cu")
		(net "M_D_CPU1_SB_CA<6>")
	)
	(arc
		(start 81.35239 -264.693654)
		(mid 81.535898 -264.739148)
		(end 81.71815 -264.688828)
		(width 0.0889)
		(layer "In4.Cu")
		(net "M_D_CPU1_SB_CA<6>")
	)
	(arc
		(start 84.163916 -264.688828)
		(mid 84.346167 -264.739178)
		(end 84.529676 -264.693654)
		(width 0.0889)
		(layer "In4.Cu")
		(net "M_D_CPU1_SB_CA<6>")
	)
	(segment
		(start 93.277944 -264.10031)
		(end 92.811092 -264.366248)
		(width 0.10668)
		(layer "F.Cu")
		(net "M_D_CPU1_SB_CA<5>")
	)
	(segment
		(start 90.74404 -264.043668)
		(end 90.752422 -264.038842)
		(width 0.0889)
		(layer "In4.Cu")
		(net "M_D_CPU1_SB_CA<5>")
	)
	(segment
		(start 81.344008 -264.043668)
		(end 81.35239 -264.038842)
		(width 0.0889)
		(layer "In4.Cu")
		(net "M_D_CPU1_SB_CA<5>")
	)
	(segment
		(start 80.769714 -264.038842)
		(end 80.778096 -264.043668)
		(width 0.0889)
		(layer "In4.Cu")
		(net "M_D_CPU1_SB_CA<5>")
	)
	(segment
		(start 85.10397 -264.043668)
		(end 85.112352 -264.038842)
		(width 0.0889)
		(layer "In4.Cu")
		(net "M_D_CPU1_SB_CA<5>")
	)
	(segment
		(start 83.589622 -264.038842)
		(end 83.598004 -264.043668)
		(width 0.0889)
		(layer "In4.Cu")
		(net "M_D_CPU1_SB_CA<5>")
	)
	(segment
		(start 33.120838 -264.910316)
		(end 60.01512 -264.910316)
		(width 0.14478)
		(layer "In4.Cu")
		(net "M_D_CPU1_SB_CA<5>")
	)
	(segment
		(start 84.529676 -264.038842)
		(end 84.538058 -264.043668)
		(width 0.0889)
		(layer "In4.Cu")
		(net "M_D_CPU1_SB_CA<5>")
	)
	(segment
		(start 75.921616 -264.165334)
		(end 76.188062 -264.165334)
		(width 0.0889)
		(layer "In4.Cu")
		(net "M_D_CPU1_SB_CA<5>")
	)
	(segment
		(start 86.044024 -264.043668)
		(end 86.052406 -264.038842)
		(width 0.0889)
		(layer "In4.Cu")
		(net "M_D_CPU1_SB_CA<5>")
	)
	(segment
		(start 60.01512 -264.910316)
		(end 60.760102 -264.165334)
		(width 0.14478)
		(layer "In4.Cu")
		(net "M_D_CPU1_SB_CA<5>")
	)
	(segment
		(start 89.803986 -264.043668)
		(end 89.812368 -264.038842)
		(width 0.0889)
		(layer "In4.Cu")
		(net "M_D_CPU1_SB_CA<5>")
	)
	(segment
		(start 88.289638 -264.038842)
		(end 88.29802 -264.043668)
		(width 0.0889)
		(layer "In4.Cu")
		(net "M_D_CPU1_SB_CA<5>")
	)
	(segment
		(start 32.695896 -265.335258)
		(end 33.120838 -264.910316)
		(width 0.14478)
		(layer "In4.Cu")
		(net "M_D_CPU1_SB_CA<5>")
	)
	(segment
		(start 76.188062 -264.165334)
		(end 76.360528 -263.992868)
		(width 0.0889)
		(layer "In4.Cu")
		(net "M_D_CPU1_SB_CA<5>")
	)
	(segment
		(start 76.360528 -263.992868)
		(end 79.649828 -263.992868)
		(width 0.0889)
		(layer "In4.Cu")
		(net "M_D_CPU1_SB_CA<5>")
	)
	(segment
		(start 89.229692 -264.038842)
		(end 89.238074 -264.043668)
		(width 0.0889)
		(layer "In4.Cu")
		(net "M_D_CPU1_SB_CA<5>")
	)
	(segment
		(start 80.389222 -264.052304)
		(end 80.403954 -264.043668)
		(width 0.0889)
		(layer "In4.Cu")
		(net "M_D_CPU1_SB_CA<5>")
	)
	(segment
		(start 92.560648 -264.075418)
		(end 92.656914 -264.100818)
		(width 0.0889)
		(layer "In4.Cu")
		(net "M_D_CPU1_SB_CA<5>")
	)
	(segment
		(start 60.760102 -264.165334)
		(end 75.921616 -264.165334)
		(width 0.14478)
		(layer "In4.Cu")
		(net "M_D_CPU1_SB_CA<5>")
	)
	(segment
		(start 92.656914 -264.100818)
		(end 92.811092 -264.366248)
		(width 0.0889)
		(layer "In4.Cu")
		(net "M_D_CPU1_SB_CA<5>")
	)
	(arc
		(start 83.598004 -264.043668)
		(mid 83.88096 -264.119845)
		(end 84.163916 -264.043668)
		(width 0.0889)
		(layer "In4.Cu")
		(net "M_D_CPU1_SB_CA<5>")
	)
	(arc
		(start 87.357966 -264.043668)
		(mid 87.640922 -264.119845)
		(end 87.923878 -264.043668)
		(width 0.0889)
		(layer "In4.Cu")
		(net "M_D_CPU1_SB_CA<5>")
	)
	(arc
		(start 84.163916 -264.043668)
		(mid 84.346167 -263.993318)
		(end 84.529676 -264.038842)
		(width 0.0889)
		(layer "In4.Cu")
		(net "M_D_CPU1_SB_CA<5>")
	)
	(arc
		(start 80.778096 -264.043668)
		(mid 81.061052 -264.119845)
		(end 81.344008 -264.043668)
		(width 0.0889)
		(layer "In4.Cu")
		(net "M_D_CPU1_SB_CA<5>")
	)
	(arc
		(start 82.284062 -264.043668)
		(mid 82.471006 -263.993413)
		(end 82.65795 -264.043668)
		(width 0.0889)
		(layer "In4.Cu")
		(net "M_D_CPU1_SB_CA<5>")
	)
	(arc
		(start 80.403954 -264.043668)
		(mid 80.586205 -263.993318)
		(end 80.769714 -264.038842)
		(width 0.0889)
		(layer "In4.Cu")
		(net "M_D_CPU1_SB_CA<5>")
	)
	(arc
		(start 82.65795 -264.043668)
		(mid 82.940906 -264.119845)
		(end 83.223862 -264.043668)
		(width 0.0889)
		(layer "In4.Cu")
		(net "M_D_CPU1_SB_CA<5>")
	)
	(arc
		(start 89.238074 -264.043668)
		(mid 89.52103 -264.119845)
		(end 89.803986 -264.043668)
		(width 0.0889)
		(layer "In4.Cu")
		(net "M_D_CPU1_SB_CA<5>")
	)
	(arc
		(start 81.35239 -264.038842)
		(mid 81.535898 -263.993348)
		(end 81.71815 -264.043668)
		(width 0.0889)
		(layer "In4.Cu")
		(net "M_D_CPU1_SB_CA<5>")
	)
	(arc
		(start 85.478112 -264.043668)
		(mid 85.761068 -264.119845)
		(end 86.044024 -264.043668)
		(width 0.0889)
		(layer "In4.Cu")
		(net "M_D_CPU1_SB_CA<5>")
	)
	(arc
		(start 84.538058 -264.043668)
		(mid 84.821014 -264.119845)
		(end 85.10397 -264.043668)
		(width 0.0889)
		(layer "In4.Cu")
		(net "M_D_CPU1_SB_CA<5>")
	)
	(arc
		(start 91.684094 -264.043668)
		(mid 91.871038 -263.993413)
		(end 92.057982 -264.043668)
		(width 0.0889)
		(layer "In4.Cu")
		(net "M_D_CPU1_SB_CA<5>")
	)
	(arc
		(start 88.29802 -264.043668)
		(mid 88.580976 -264.119845)
		(end 88.863932 -264.043668)
		(width 0.0889)
		(layer "In4.Cu")
		(net "M_D_CPU1_SB_CA<5>")
	)
	(arc
		(start 86.418166 -264.043668)
		(mid 86.701122 -264.119845)
		(end 86.984078 -264.043668)
		(width 0.0889)
		(layer "In4.Cu")
		(net "M_D_CPU1_SB_CA<5>")
	)
	(arc
		(start 85.112352 -264.038842)
		(mid 85.29586 -263.993348)
		(end 85.478112 -264.043668)
		(width 0.0889)
		(layer "In4.Cu")
		(net "M_D_CPU1_SB_CA<5>")
	)
	(arc
		(start 90.178128 -264.043668)
		(mid 90.461084 -264.119845)
		(end 90.74404 -264.043668)
		(width 0.0889)
		(layer "In4.Cu")
		(net "M_D_CPU1_SB_CA<5>")
	)
	(arc
		(start 89.812368 -264.038842)
		(mid 89.995876 -263.993348)
		(end 90.178128 -264.043668)
		(width 0.0889)
		(layer "In4.Cu")
		(net "M_D_CPU1_SB_CA<5>")
	)
	(arc
		(start 83.223862 -264.043668)
		(mid 83.406113 -263.993318)
		(end 83.589622 -264.038842)
		(width 0.0889)
		(layer "In4.Cu")
		(net "M_D_CPU1_SB_CA<5>")
	)
	(arc
		(start 86.052406 -264.038842)
		(mid 86.235914 -263.993348)
		(end 86.418166 -264.043668)
		(width 0.0889)
		(layer "In4.Cu")
		(net "M_D_CPU1_SB_CA<5>")
	)
	(arc
		(start 90.752422 -264.038842)
		(mid 90.93593 -263.993348)
		(end 91.118182 -264.043668)
		(width 0.0889)
		(layer "In4.Cu")
		(net "M_D_CPU1_SB_CA<5>")
	)
	(arc
		(start 86.984078 -264.043668)
		(mid 87.171022 -263.993413)
		(end 87.357966 -264.043668)
		(width 0.0889)
		(layer "In4.Cu")
		(net "M_D_CPU1_SB_CA<5>")
	)
	(arc
		(start 92.057982 -264.043668)
		(mid 92.305578 -264.118846)
		(end 92.560648 -264.075418)
		(width 0.0889)
		(layer "In4.Cu")
		(net "M_D_CPU1_SB_CA<5>")
	)
	(arc
		(start 91.118182 -264.043668)
		(mid 91.401138 -264.119845)
		(end 91.684094 -264.043668)
		(width 0.0889)
		(layer "In4.Cu")
		(net "M_D_CPU1_SB_CA<5>")
	)
	(arc
		(start 79.649828 -263.992868)
		(mid 79.747053 -264.005817)
		(end 79.837534 -264.043668)
		(width 0.0889)
		(layer "In4.Cu")
		(net "M_D_CPU1_SB_CA<5>")
	)
	(arc
		(start 87.923878 -264.043668)
		(mid 88.106129 -263.993318)
		(end 88.289638 -264.038842)
		(width 0.0889)
		(layer "In4.Cu")
		(net "M_D_CPU1_SB_CA<5>")
	)
	(arc
		(start 81.71815 -264.043668)
		(mid 82.001106 -264.119845)
		(end 82.284062 -264.043668)
		(width 0.0889)
		(layer "In4.Cu")
		(net "M_D_CPU1_SB_CA<5>")
	)
	(arc
		(start 88.863932 -264.043668)
		(mid 89.046183 -263.993318)
		(end 89.229692 -264.038842)
		(width 0.0889)
		(layer "In4.Cu")
		(net "M_D_CPU1_SB_CA<5>")
	)
	(arc
		(start 79.837534 -264.043668)
		(mid 80.11224 -264.120032)
		(end 80.389222 -264.052304)
		(width 0.0889)
		(layer "In4.Cu")
		(net "M_D_CPU1_SB_CA<5>")
	)
	(segment
		(start 92.80779 -263.290304)
		(end 92.340938 -263.556242)
		(width 0.10668)
		(layer "F.Cu")
		(net "M_D_CPU1_SB_CA<4>")
	)
	(segment
		(start 44.683172 -264.060178)
		(end 45.002958 -264.379964)
		(width 0.14478)
		(layer "In4.Cu")
		(net "M_D_CPU1_SB_CA<4>")
	)
	(segment
		(start 46.671738 -264.060178)
		(end 48.316896 -264.060178)
		(width 0.14478)
		(layer "In4.Cu")
		(net "M_D_CPU1_SB_CA<4>")
	)
	(segment
		(start 57.851802 -264.060178)
		(end 58.088276 -264.060178)
		(width 0.14478)
		(layer "In4.Cu")
		(net "M_D_CPU1_SB_CA<4>")
	)
	(segment
		(start 38.556438 -264.060178)
		(end 38.792912 -264.060178)
		(width 0.14478)
		(layer "In4.Cu")
		(net "M_D_CPU1_SB_CA<4>")
	)
	(segment
		(start 56.975756 -264.060178)
		(end 57.295542 -264.379964)
		(width 0.14478)
		(layer "In4.Cu")
		(net "M_D_CPU1_SB_CA<4>")
	)
	(segment
		(start 85.93963 -263.883648)
		(end 85.948012 -263.878822)
		(width 0.0889)
		(layer "In4.Cu")
		(net "M_D_CPU1_SB_CA<4>")
	)
	(segment
		(start 76.912216 -263.710674)
		(end 77.00391 -263.802368)
		(width 0.0889)
		(layer "In4.Cu")
		(net "M_D_CPU1_SB_CA<4>")
	)
	(segment
		(start 92.153994 -263.878822)
		(end 92.162376 -263.883648)
		(width 0.0889)
		(layer "In4.Cu")
		(net "M_D_CPU1_SB_CA<4>")
	)
	(segment
		(start 40.670226 -264.060178)
		(end 40.990012 -264.379964)
		(width 0.14478)
		(layer "In4.Cu")
		(net "M_D_CPU1_SB_CA<4>")
	)
	(segment
		(start 42.658792 -264.060178)
		(end 42.895266 -264.060178)
		(width 0.14478)
		(layer "In4.Cu")
		(net "M_D_CPU1_SB_CA<4>")
	)
	(segment
		(start 49.749202 -264.379964)
		(end 49.985676 -264.379964)
		(width 0.14478)
		(layer "In4.Cu")
		(net "M_D_CPU1_SB_CA<4>")
	)
	(segment
		(start 77.00391 -263.802368)
		(end 79.650082 -263.802368)
		(width 0.0889)
		(layer "In4.Cu")
		(net "M_D_CPU1_SB_CA<4>")
	)
	(segment
		(start 52.351178 -264.060178)
		(end 52.670964 -264.379964)
		(width 0.14478)
		(layer "In4.Cu")
		(net "M_D_CPU1_SB_CA<4>")
	)
	(segment
		(start 59.200796 -264.060178)
		(end 59.520582 -264.379964)
		(width 0.14478)
		(layer "In4.Cu")
		(net "M_D_CPU1_SB_CA<4>")
	)
	(segment
		(start 56.183022 -264.379964)
		(end 56.419496 -264.379964)
		(width 0.14478)
		(layer "In4.Cu")
		(net "M_D_CPU1_SB_CA<4>")
	)
	(segment
		(start 48.316896 -264.060178)
		(end 48.636682 -264.379964)
		(width 0.14478)
		(layer "In4.Cu")
		(net "M_D_CPU1_SB_CA<4>")
	)
	(segment
		(start 59.757056 -264.379964)
		(end 60.426346 -263.710674)
		(width 0.14478)
		(layer "In4.Cu")
		(net "M_D_CPU1_SB_CA<4>")
	)
	(segment
		(start 48.636682 -264.379964)
		(end 48.873156 -264.379964)
		(width 0.14478)
		(layer "In4.Cu")
		(net "M_D_CPU1_SB_CA<4>")
	)
	(segment
		(start 90.639646 -263.883648)
		(end 90.648028 -263.878822)
		(width 0.0889)
		(layer "In4.Cu")
		(net "M_D_CPU1_SB_CA<4>")
	)
	(segment
		(start 42.895266 -264.060178)
		(end 43.215052 -264.379964)
		(width 0.14478)
		(layer "In4.Cu")
		(net "M_D_CPU1_SB_CA<4>")
	)
	(segment
		(start 92.495116 -263.821672)
		(end 92.340938 -263.556242)
		(width 0.0889)
		(layer "In4.Cu")
		(net "M_D_CPU1_SB_CA<4>")
	)
	(segment
		(start 42.102532 -264.379964)
		(end 42.339006 -264.379964)
		(width 0.14478)
		(layer "In4.Cu")
		(net "M_D_CPU1_SB_CA<4>")
	)
	(segment
		(start 38.792912 -264.060178)
		(end 39.112698 -264.379964)
		(width 0.14478)
		(layer "In4.Cu")
		(net "M_D_CPU1_SB_CA<4>")
	)
	(segment
		(start 48.873156 -264.379964)
		(end 49.192942 -264.060178)
		(width 0.14478)
		(layer "In4.Cu")
		(net "M_D_CPU1_SB_CA<4>")
	)
	(segment
		(start 86.879684 -263.883648)
		(end 86.888066 -263.878822)
		(width 0.0889)
		(layer "In4.Cu")
		(net "M_D_CPU1_SB_CA<4>")
	)
	(segment
		(start 88.394032 -263.878822)
		(end 88.402414 -263.883648)
		(width 0.0889)
		(layer "In4.Cu")
		(net "M_D_CPU1_SB_CA<4>")
	)
	(segment
		(start 87.453978 -263.878822)
		(end 87.46236 -263.883648)
		(width 0.0889)
		(layer "In4.Cu")
		(net "M_D_CPU1_SB_CA<4>")
	)
	(segment
		(start 53.783484 -264.379964)
		(end 54.019958 -264.379964)
		(width 0.14478)
		(layer "In4.Cu")
		(net "M_D_CPU1_SB_CA<4>")
	)
	(segment
		(start 41.546272 -264.060178)
		(end 41.782746 -264.060178)
		(width 0.14478)
		(layer "In4.Cu")
		(net "M_D_CPU1_SB_CA<4>")
	)
	(segment
		(start 75.952096 -263.710674)
		(end 76.912216 -263.710674)
		(width 0.0889)
		(layer "In4.Cu")
		(net "M_D_CPU1_SB_CA<4>")
	)
	(segment
		(start 49.429416 -264.060178)
		(end 49.749202 -264.379964)
		(width 0.14478)
		(layer "In4.Cu")
		(net "M_D_CPU1_SB_CA<4>")
	)
	(segment
		(start 53.463698 -264.060178)
		(end 53.783484 -264.379964)
		(width 0.14478)
		(layer "In4.Cu")
		(net "M_D_CPU1_SB_CA<4>")
	)
	(segment
		(start 49.985676 -264.379964)
		(end 50.305462 -264.060178)
		(width 0.14478)
		(layer "In4.Cu")
		(net "M_D_CPU1_SB_CA<4>")
	)
	(segment
		(start 43.215052 -264.379964)
		(end 43.451526 -264.379964)
		(width 0.14478)
		(layer "In4.Cu")
		(net "M_D_CPU1_SB_CA<4>")
	)
	(segment
		(start 56.419496 -264.379964)
		(end 56.739282 -264.060178)
		(width 0.14478)
		(layer "In4.Cu")
		(net "M_D_CPU1_SB_CA<4>")
	)
	(segment
		(start 82.753962 -263.878822)
		(end 82.762344 -263.883648)
		(width 0.0889)
		(layer "In4.Cu")
		(net "M_D_CPU1_SB_CA<4>")
	)
	(segment
		(start 41.782746 -264.060178)
		(end 42.102532 -264.379964)
		(width 0.14478)
		(layer "In4.Cu")
		(net "M_D_CPU1_SB_CA<4>")
	)
	(segment
		(start 58.408062 -264.379964)
		(end 58.644536 -264.379964)
		(width 0.14478)
		(layer "In4.Cu")
		(net "M_D_CPU1_SB_CA<4>")
	)
	(segment
		(start 53.227224 -264.060178)
		(end 53.463698 -264.060178)
		(width 0.14478)
		(layer "In4.Cu")
		(net "M_D_CPU1_SB_CA<4>")
	)
	(segment
		(start 80.299814 -263.883648)
		(end 80.308196 -263.878822)
		(width 0.0889)
		(layer "In4.Cu")
		(net "M_D_CPU1_SB_CA<4>")
	)
	(segment
		(start 49.192942 -264.060178)
		(end 49.429416 -264.060178)
		(width 0.14478)
		(layer "In4.Cu")
		(net "M_D_CPU1_SB_CA<4>")
	)
	(segment
		(start 51.417982 -264.060178)
		(end 52.351178 -264.060178)
		(width 0.14478)
		(layer "In4.Cu")
		(net "M_D_CPU1_SB_CA<4>")
	)
	(segment
		(start 50.541936 -264.060178)
		(end 50.861722 -264.379964)
		(width 0.14478)
		(layer "In4.Cu")
		(net "M_D_CPU1_SB_CA<4>")
	)
	(segment
		(start 45.795692 -264.060178)
		(end 46.115478 -264.379964)
		(width 0.14478)
		(layer "In4.Cu")
		(net "M_D_CPU1_SB_CA<4>")
	)
	(segment
		(start 54.339744 -264.060178)
		(end 55.863236 -264.060178)
		(width 0.14478)
		(layer "In4.Cu")
		(net "M_D_CPU1_SB_CA<4>")
	)
	(segment
		(start 43.771312 -264.060178)
		(end 44.683172 -264.060178)
		(width 0.14478)
		(layer "In4.Cu")
		(net "M_D_CPU1_SB_CA<4>")
	)
	(segment
		(start 55.863236 -264.060178)
		(end 56.183022 -264.379964)
		(width 0.14478)
		(layer "In4.Cu")
		(net "M_D_CPU1_SB_CA<4>")
	)
	(segment
		(start 57.532016 -264.379964)
		(end 57.851802 -264.060178)
		(width 0.14478)
		(layer "In4.Cu")
		(net "M_D_CPU1_SB_CA<4>")
	)
	(segment
		(start 58.644536 -264.379964)
		(end 58.964322 -264.060178)
		(width 0.14478)
		(layer "In4.Cu")
		(net "M_D_CPU1_SB_CA<4>")
	)
	(segment
		(start 46.115478 -264.379964)
		(end 46.351952 -264.379964)
		(width 0.14478)
		(layer "In4.Cu")
		(net "M_D_CPU1_SB_CA<4>")
	)
	(segment
		(start 41.226486 -264.379964)
		(end 41.546272 -264.060178)
		(width 0.14478)
		(layer "In4.Cu")
		(net "M_D_CPU1_SB_CA<4>")
	)
	(segment
		(start 82.179668 -263.883648)
		(end 82.18805 -263.878822)
		(width 0.0889)
		(layer "In4.Cu")
		(net "M_D_CPU1_SB_CA<4>")
	)
	(segment
		(start 52.670964 -264.379964)
		(end 52.907438 -264.379964)
		(width 0.14478)
		(layer "In4.Cu")
		(net "M_D_CPU1_SB_CA<4>")
	)
	(segment
		(start 83.694016 -263.878822)
		(end 83.702398 -263.883648)
		(width 0.0889)
		(layer "In4.Cu")
		(net "M_D_CPU1_SB_CA<4>")
	)
	(segment
		(start 50.305462 -264.060178)
		(end 50.541936 -264.060178)
		(width 0.14478)
		(layer "In4.Cu")
		(net "M_D_CPU1_SB_CA<4>")
	)
	(segment
		(start 38.236652 -264.379964)
		(end 38.556438 -264.060178)
		(width 0.14478)
		(layer "In4.Cu")
		(net "M_D_CPU1_SB_CA<4>")
	)
	(segment
		(start 39.668958 -264.060178)
		(end 40.670226 -264.060178)
		(width 0.14478)
		(layer "In4.Cu")
		(net "M_D_CPU1_SB_CA<4>")
	)
	(segment
		(start 57.295542 -264.379964)
		(end 57.532016 -264.379964)
		(width 0.14478)
		(layer "In4.Cu")
		(net "M_D_CPU1_SB_CA<4>")
	)
	(segment
		(start 58.088276 -264.060178)
		(end 58.408062 -264.379964)
		(width 0.14478)
		(layer "In4.Cu")
		(net "M_D_CPU1_SB_CA<4>")
	)
	(segment
		(start 40.990012 -264.379964)
		(end 41.226486 -264.379964)
		(width 0.14478)
		(layer "In4.Cu")
		(net "M_D_CPU1_SB_CA<4>")
	)
	(segment
		(start 60.426346 -263.710674)
		(end 75.952096 -263.710674)
		(width 0.14478)
		(layer "In4.Cu")
		(net "M_D_CPU1_SB_CA<4>")
	)
	(segment
		(start 45.239432 -264.379964)
		(end 45.559218 -264.060178)
		(width 0.14478)
		(layer "In4.Cu")
		(net "M_D_CPU1_SB_CA<4>")
	)
	(segment
		(start 45.559218 -264.060178)
		(end 45.795692 -264.060178)
		(width 0.14478)
		(layer "In4.Cu")
		(net "M_D_CPU1_SB_CA<4>")
	)
	(segment
		(start 39.112698 -264.379964)
		(end 39.349172 -264.379964)
		(width 0.14478)
		(layer "In4.Cu")
		(net "M_D_CPU1_SB_CA<4>")
	)
	(segment
		(start 92.472764 -263.904984)
		(end 92.495116 -263.821672)
		(width 0.0889)
		(layer "In4.Cu")
		(net "M_D_CPU1_SB_CA<4>")
	)
	(segment
		(start 54.019958 -264.379964)
		(end 54.339744 -264.060178)
		(width 0.14478)
		(layer "In4.Cu")
		(net "M_D_CPU1_SB_CA<4>")
	)
	(segment
		(start 38.000178 -264.379964)
		(end 38.236652 -264.379964)
		(width 0.14478)
		(layer "In4.Cu")
		(net "M_D_CPU1_SB_CA<4>")
	)
	(segment
		(start 51.098196 -264.379964)
		(end 51.417982 -264.060178)
		(width 0.14478)
		(layer "In4.Cu")
		(net "M_D_CPU1_SB_CA<4>")
	)
	(segment
		(start 45.002958 -264.379964)
		(end 45.239432 -264.379964)
		(width 0.14478)
		(layer "In4.Cu")
		(net "M_D_CPU1_SB_CA<4>")
	)
	(segment
		(start 56.739282 -264.060178)
		(end 56.975756 -264.060178)
		(width 0.14478)
		(layer "In4.Cu")
		(net "M_D_CPU1_SB_CA<4>")
	)
	(segment
		(start 37.680392 -264.060178)
		(end 38.000178 -264.379964)
		(width 0.14478)
		(layer "In4.Cu")
		(net "M_D_CPU1_SB_CA<4>")
	)
	(segment
		(start 36.795964 -264.485374)
		(end 37.22116 -264.060178)
		(width 0.14478)
		(layer "In4.Cu")
		(net "M_D_CPU1_SB_CA<4>")
	)
	(segment
		(start 58.964322 -264.060178)
		(end 59.200796 -264.060178)
		(width 0.14478)
		(layer "In4.Cu")
		(net "M_D_CPU1_SB_CA<4>")
	)
	(segment
		(start 37.22116 -264.060178)
		(end 37.680392 -264.060178)
		(width 0.14478)
		(layer "In4.Cu")
		(net "M_D_CPU1_SB_CA<4>")
	)
	(segment
		(start 91.5797 -263.883648)
		(end 91.588082 -263.878822)
		(width 0.0889)
		(layer "In4.Cu")
		(net "M_D_CPU1_SB_CA<4>")
	)
	(segment
		(start 52.907438 -264.379964)
		(end 53.227224 -264.060178)
		(width 0.14478)
		(layer "In4.Cu")
		(net "M_D_CPU1_SB_CA<4>")
	)
	(segment
		(start 43.451526 -264.379964)
		(end 43.771312 -264.060178)
		(width 0.14478)
		(layer "In4.Cu")
		(net "M_D_CPU1_SB_CA<4>")
	)
	(segment
		(start 46.351952 -264.379964)
		(end 46.671738 -264.060178)
		(width 0.14478)
		(layer "In4.Cu")
		(net "M_D_CPU1_SB_CA<4>")
	)
	(segment
		(start 59.520582 -264.379964)
		(end 59.757056 -264.379964)
		(width 0.14478)
		(layer "In4.Cu")
		(net "M_D_CPU1_SB_CA<4>")
	)
	(segment
		(start 50.861722 -264.379964)
		(end 51.098196 -264.379964)
		(width 0.14478)
		(layer "In4.Cu")
		(net "M_D_CPU1_SB_CA<4>")
	)
	(segment
		(start 39.349172 -264.379964)
		(end 39.668958 -264.060178)
		(width 0.14478)
		(layer "In4.Cu")
		(net "M_D_CPU1_SB_CA<4>")
	)
	(segment
		(start 42.339006 -264.379964)
		(end 42.658792 -264.060178)
		(width 0.14478)
		(layer "In4.Cu")
		(net "M_D_CPU1_SB_CA<4>")
	)
	(arc
		(start 91.21394 -263.878822)
		(mid 91.396191 -263.929172)
		(end 91.5797 -263.883648)
		(width 0.0889)
		(layer "In4.Cu")
		(net "M_D_CPU1_SB_CA<4>")
	)
	(arc
		(start 86.513924 -263.878822)
		(mid 86.696175 -263.929172)
		(end 86.879684 -263.883648)
		(width 0.0889)
		(layer "In4.Cu")
		(net "M_D_CPU1_SB_CA<4>")
	)
	(arc
		(start 88.402414 -263.883648)
		(mid 88.585922 -263.929142)
		(end 88.768174 -263.878822)
		(width 0.0889)
		(layer "In4.Cu")
		(net "M_D_CPU1_SB_CA<4>")
	)
	(arc
		(start 91.588082 -263.878822)
		(mid 91.871038 -263.802645)
		(end 92.153994 -263.878822)
		(width 0.0889)
		(layer "In4.Cu")
		(net "M_D_CPU1_SB_CA<4>")
	)
	(arc
		(start 82.762344 -263.883648)
		(mid 82.945852 -263.929142)
		(end 83.128104 -263.878822)
		(width 0.0889)
		(layer "In4.Cu")
		(net "M_D_CPU1_SB_CA<4>")
	)
	(arc
		(start 84.068158 -263.878822)
		(mid 84.351114 -263.802645)
		(end 84.63407 -263.878822)
		(width 0.0889)
		(layer "In4.Cu")
		(net "M_D_CPU1_SB_CA<4>")
	)
	(arc
		(start 90.648028 -263.878822)
		(mid 90.930984 -263.802645)
		(end 91.21394 -263.878822)
		(width 0.0889)
		(layer "In4.Cu")
		(net "M_D_CPU1_SB_CA<4>")
	)
	(arc
		(start 89.334086 -263.878822)
		(mid 89.52103 -263.929077)
		(end 89.707974 -263.878822)
		(width 0.0889)
		(layer "In4.Cu")
		(net "M_D_CPU1_SB_CA<4>")
	)
	(arc
		(start 81.813908 -263.878822)
		(mid 81.996159 -263.929172)
		(end 82.179668 -263.883648)
		(width 0.0889)
		(layer "In4.Cu")
		(net "M_D_CPU1_SB_CA<4>")
	)
	(arc
		(start 85.007958 -263.878822)
		(mid 85.290914 -263.802645)
		(end 85.57387 -263.878822)
		(width 0.0889)
		(layer "In4.Cu")
		(net "M_D_CPU1_SB_CA<4>")
	)
	(arc
		(start 79.650082 -263.802368)
		(mid 79.796882 -263.821812)
		(end 79.933546 -263.878822)
		(width 0.0889)
		(layer "In4.Cu")
		(net "M_D_CPU1_SB_CA<4>")
	)
	(arc
		(start 85.948012 -263.878822)
		(mid 86.230968 -263.802645)
		(end 86.513924 -263.878822)
		(width 0.0889)
		(layer "In4.Cu")
		(net "M_D_CPU1_SB_CA<4>")
	)
	(arc
		(start 80.874108 -263.878822)
		(mid 81.061052 -263.929077)
		(end 81.247996 -263.878822)
		(width 0.0889)
		(layer "In4.Cu")
		(net "M_D_CPU1_SB_CA<4>")
	)
	(arc
		(start 90.273886 -263.878822)
		(mid 90.456137 -263.929172)
		(end 90.639646 -263.883648)
		(width 0.0889)
		(layer "In4.Cu")
		(net "M_D_CPU1_SB_CA<4>")
	)
	(arc
		(start 87.82812 -263.878822)
		(mid 88.111076 -263.802645)
		(end 88.394032 -263.878822)
		(width 0.0889)
		(layer "In4.Cu")
		(net "M_D_CPU1_SB_CA<4>")
	)
	(arc
		(start 81.247996 -263.878822)
		(mid 81.530952 -263.802645)
		(end 81.813908 -263.878822)
		(width 0.0889)
		(layer "In4.Cu")
		(net "M_D_CPU1_SB_CA<4>")
	)
	(arc
		(start 87.46236 -263.883648)
		(mid 87.645868 -263.929142)
		(end 87.82812 -263.878822)
		(width 0.0889)
		(layer "In4.Cu")
		(net "M_D_CPU1_SB_CA<4>")
	)
	(arc
		(start 92.162376 -263.883648)
		(mid 92.315246 -263.928289)
		(end 92.472764 -263.904984)
		(width 0.0889)
		(layer "In4.Cu")
		(net "M_D_CPU1_SB_CA<4>")
	)
	(arc
		(start 80.308196 -263.878822)
		(mid 80.591152 -263.802645)
		(end 80.874108 -263.878822)
		(width 0.0889)
		(layer "In4.Cu")
		(net "M_D_CPU1_SB_CA<4>")
	)
	(arc
		(start 83.702398 -263.883648)
		(mid 83.885906 -263.929142)
		(end 84.068158 -263.878822)
		(width 0.0889)
		(layer "In4.Cu")
		(net "M_D_CPU1_SB_CA<4>")
	)
	(arc
		(start 89.707974 -263.878822)
		(mid 89.99093 -263.802645)
		(end 90.273886 -263.878822)
		(width 0.0889)
		(layer "In4.Cu")
		(net "M_D_CPU1_SB_CA<4>")
	)
	(arc
		(start 86.888066 -263.878822)
		(mid 87.171022 -263.802645)
		(end 87.453978 -263.878822)
		(width 0.0889)
		(layer "In4.Cu")
		(net "M_D_CPU1_SB_CA<4>")
	)
	(arc
		(start 83.128104 -263.878822)
		(mid 83.41106 -263.802645)
		(end 83.694016 -263.878822)
		(width 0.0889)
		(layer "In4.Cu")
		(net "M_D_CPU1_SB_CA<4>")
	)
	(arc
		(start 84.63407 -263.878822)
		(mid 84.821014 -263.929077)
		(end 85.007958 -263.878822)
		(width 0.0889)
		(layer "In4.Cu")
		(net "M_D_CPU1_SB_CA<4>")
	)
	(arc
		(start 85.57387 -263.878822)
		(mid 85.756121 -263.929172)
		(end 85.93963 -263.883648)
		(width 0.0889)
		(layer "In4.Cu")
		(net "M_D_CPU1_SB_CA<4>")
	)
	(arc
		(start 82.18805 -263.878822)
		(mid 82.471006 -263.802645)
		(end 82.753962 -263.878822)
		(width 0.0889)
		(layer "In4.Cu")
		(net "M_D_CPU1_SB_CA<4>")
	)
	(arc
		(start 79.933546 -263.878822)
		(mid 80.116051 -263.929299)
		(end 80.299814 -263.883648)
		(width 0.0889)
		(layer "In4.Cu")
		(net "M_D_CPU1_SB_CA<4>")
	)
	(arc
		(start 88.768174 -263.878822)
		(mid 89.05113 -263.802645)
		(end 89.334086 -263.878822)
		(width 0.0889)
		(layer "In4.Cu")
		(net "M_D_CPU1_SB_CA<4>")
	)
	(segment
		(start 91.86799 -263.290304)
		(end 91.401138 -263.556242)
		(width 0.10668)
		(layer "F.Cu")
		(net "M_D_CPU1_SB_CA<3>")
	)
	(segment
		(start 77.58303 -262.894826)
		(end 77.998066 -263.309862)
		(width 0.0889)
		(layer "In4.Cu")
		(net "M_D_CPU1_SB_CA<3>")
	)
	(segment
		(start 82.179668 -263.228836)
		(end 82.18805 -263.233662)
		(width 0.0889)
		(layer "In4.Cu")
		(net "M_D_CPU1_SB_CA<3>")
	)
	(segment
		(start 88.394032 -263.233662)
		(end 88.402414 -263.228836)
		(width 0.0889)
		(layer "In4.Cu")
		(net "M_D_CPU1_SB_CA<3>")
	)
	(segment
		(start 85.93963 -263.228836)
		(end 85.948012 -263.233662)
		(width 0.0889)
		(layer "In4.Cu")
		(net "M_D_CPU1_SB_CA<3>")
	)
	(segment
		(start 76.457302 -263.210294)
		(end 76.77277 -262.894826)
		(width 0.0889)
		(layer "In4.Cu")
		(net "M_D_CPU1_SB_CA<3>")
	)
	(segment
		(start 86.879684 -263.228836)
		(end 86.888066 -263.233662)
		(width 0.0889)
		(layer "In4.Cu")
		(net "M_D_CPU1_SB_CA<3>")
	)
	(segment
		(start 75.963526 -263.210294)
		(end 76.457302 -263.210294)
		(width 0.0889)
		(layer "In4.Cu")
		(net "M_D_CPU1_SB_CA<3>")
	)
	(segment
		(start 91.24696 -263.290812)
		(end 91.401138 -263.556242)
		(width 0.0889)
		(layer "In4.Cu")
		(net "M_D_CPU1_SB_CA<3>")
	)
	(segment
		(start 77.998066 -263.309862)
		(end 79.650336 -263.309862)
		(width 0.0889)
		(layer "In4.Cu")
		(net "M_D_CPU1_SB_CA<3>")
	)
	(segment
		(start 82.753962 -263.233662)
		(end 82.762344 -263.228836)
		(width 0.0889)
		(layer "In4.Cu")
		(net "M_D_CPU1_SB_CA<3>")
	)
	(segment
		(start 91.150694 -263.265412)
		(end 91.24696 -263.290812)
		(width 0.0889)
		(layer "In4.Cu")
		(net "M_D_CPU1_SB_CA<3>")
	)
	(segment
		(start 80.299814 -263.228836)
		(end 80.308196 -263.233662)
		(width 0.0889)
		(layer "In4.Cu")
		(net "M_D_CPU1_SB_CA<3>")
	)
	(segment
		(start 33.120838 -263.210294)
		(end 75.963526 -263.210294)
		(width 0.14478)
		(layer "In4.Cu")
		(net "M_D_CPU1_SB_CA<3>")
	)
	(segment
		(start 76.77277 -262.894826)
		(end 77.58303 -262.894826)
		(width 0.0889)
		(layer "In4.Cu")
		(net "M_D_CPU1_SB_CA<3>")
	)
	(segment
		(start 83.694016 -263.233662)
		(end 83.702398 -263.228836)
		(width 0.0889)
		(layer "In4.Cu")
		(net "M_D_CPU1_SB_CA<3>")
	)
	(segment
		(start 32.695896 -263.635236)
		(end 33.120838 -263.210294)
		(width 0.14478)
		(layer "In4.Cu")
		(net "M_D_CPU1_SB_CA<3>")
	)
	(segment
		(start 87.453978 -263.233662)
		(end 87.46236 -263.228836)
		(width 0.0889)
		(layer "In4.Cu")
		(net "M_D_CPU1_SB_CA<3>")
	)
	(segment
		(start 90.639646 -263.228836)
		(end 90.648028 -263.233662)
		(width 0.0889)
		(layer "In4.Cu")
		(net "M_D_CPU1_SB_CA<3>")
	)
	(arc
		(start 80.874108 -263.233662)
		(mid 81.061052 -263.183407)
		(end 81.247996 -263.233662)
		(width 0.0889)
		(layer "In4.Cu")
		(net "M_D_CPU1_SB_CA<3>")
	)
	(arc
		(start 89.334086 -263.233662)
		(mid 89.52103 -263.183407)
		(end 89.707974 -263.233662)
		(width 0.0889)
		(layer "In4.Cu")
		(net "M_D_CPU1_SB_CA<3>")
	)
	(arc
		(start 83.702398 -263.228836)
		(mid 83.885906 -263.183342)
		(end 84.068158 -263.233662)
		(width 0.0889)
		(layer "In4.Cu")
		(net "M_D_CPU1_SB_CA<3>")
	)
	(arc
		(start 83.128104 -263.233662)
		(mid 83.41106 -263.309839)
		(end 83.694016 -263.233662)
		(width 0.0889)
		(layer "In4.Cu")
		(net "M_D_CPU1_SB_CA<3>")
	)
	(arc
		(start 87.82812 -263.233662)
		(mid 88.111076 -263.309839)
		(end 88.394032 -263.233662)
		(width 0.0889)
		(layer "In4.Cu")
		(net "M_D_CPU1_SB_CA<3>")
	)
	(arc
		(start 81.813908 -263.233662)
		(mid 81.996159 -263.183312)
		(end 82.179668 -263.228836)
		(width 0.0889)
		(layer "In4.Cu")
		(net "M_D_CPU1_SB_CA<3>")
	)
	(arc
		(start 86.888066 -263.233662)
		(mid 87.171022 -263.309839)
		(end 87.453978 -263.233662)
		(width 0.0889)
		(layer "In4.Cu")
		(net "M_D_CPU1_SB_CA<3>")
	)
	(arc
		(start 89.707974 -263.233662)
		(mid 89.99093 -263.309839)
		(end 90.273886 -263.233662)
		(width 0.0889)
		(layer "In4.Cu")
		(net "M_D_CPU1_SB_CA<3>")
	)
	(arc
		(start 80.308196 -263.233662)
		(mid 80.591152 -263.309839)
		(end 80.874108 -263.233662)
		(width 0.0889)
		(layer "In4.Cu")
		(net "M_D_CPU1_SB_CA<3>")
	)
	(arc
		(start 79.650336 -263.309862)
		(mid 79.796993 -263.290525)
		(end 79.933546 -263.233662)
		(width 0.0889)
		(layer "In4.Cu")
		(net "M_D_CPU1_SB_CA<3>")
	)
	(arc
		(start 82.762344 -263.228836)
		(mid 82.945852 -263.183342)
		(end 83.128104 -263.233662)
		(width 0.0889)
		(layer "In4.Cu")
		(net "M_D_CPU1_SB_CA<3>")
	)
	(arc
		(start 85.57387 -263.233662)
		(mid 85.756121 -263.183312)
		(end 85.93963 -263.228836)
		(width 0.0889)
		(layer "In4.Cu")
		(net "M_D_CPU1_SB_CA<3>")
	)
	(arc
		(start 82.18805 -263.233662)
		(mid 82.471006 -263.309839)
		(end 82.753962 -263.233662)
		(width 0.0889)
		(layer "In4.Cu")
		(net "M_D_CPU1_SB_CA<3>")
	)
	(arc
		(start 85.948012 -263.233662)
		(mid 86.230968 -263.309839)
		(end 86.513924 -263.233662)
		(width 0.0889)
		(layer "In4.Cu")
		(net "M_D_CPU1_SB_CA<3>")
	)
	(arc
		(start 79.933546 -263.233662)
		(mid 80.116051 -263.183185)
		(end 80.299814 -263.228836)
		(width 0.0889)
		(layer "In4.Cu")
		(net "M_D_CPU1_SB_CA<3>")
	)
	(arc
		(start 81.247996 -263.233662)
		(mid 81.530952 -263.309839)
		(end 81.813908 -263.233662)
		(width 0.0889)
		(layer "In4.Cu")
		(net "M_D_CPU1_SB_CA<3>")
	)
	(arc
		(start 84.068158 -263.233662)
		(mid 84.351114 -263.309839)
		(end 84.63407 -263.233662)
		(width 0.0889)
		(layer "In4.Cu")
		(net "M_D_CPU1_SB_CA<3>")
	)
	(arc
		(start 90.273886 -263.233662)
		(mid 90.456137 -263.183312)
		(end 90.639646 -263.228836)
		(width 0.0889)
		(layer "In4.Cu")
		(net "M_D_CPU1_SB_CA<3>")
	)
	(arc
		(start 88.768174 -263.233662)
		(mid 89.05113 -263.309839)
		(end 89.334086 -263.233662)
		(width 0.0889)
		(layer "In4.Cu")
		(net "M_D_CPU1_SB_CA<3>")
	)
	(arc
		(start 87.46236 -263.228836)
		(mid 87.645868 -263.183342)
		(end 87.82812 -263.233662)
		(width 0.0889)
		(layer "In4.Cu")
		(net "M_D_CPU1_SB_CA<3>")
	)
	(arc
		(start 90.648028 -263.233662)
		(mid 90.895624 -263.30884)
		(end 91.150694 -263.265412)
		(width 0.0889)
		(layer "In4.Cu")
		(net "M_D_CPU1_SB_CA<3>")
	)
	(arc
		(start 85.007958 -263.233662)
		(mid 85.290914 -263.309839)
		(end 85.57387 -263.233662)
		(width 0.0889)
		(layer "In4.Cu")
		(net "M_D_CPU1_SB_CA<3>")
	)
	(arc
		(start 88.402414 -263.228836)
		(mid 88.585922 -263.183342)
		(end 88.768174 -263.233662)
		(width 0.0889)
		(layer "In4.Cu")
		(net "M_D_CPU1_SB_CA<3>")
	)
	(arc
		(start 86.513924 -263.233662)
		(mid 86.696175 -263.183312)
		(end 86.879684 -263.228836)
		(width 0.0889)
		(layer "In4.Cu")
		(net "M_D_CPU1_SB_CA<3>")
	)
	(arc
		(start 84.63407 -263.233662)
		(mid 84.821014 -263.183407)
		(end 85.007958 -263.233662)
		(width 0.0889)
		(layer "In4.Cu")
		(net "M_D_CPU1_SB_CA<3>")
	)
	(segment
		(start 91.397836 -262.480298)
		(end 90.930984 -262.746236)
		(width 0.10668)
		(layer "F.Cu")
		(net "M_D_CPU1_SB_CA<2>")
	)
	(segment
		(start 48.61306 -262.678164)
		(end 48.858678 -262.678164)
		(width 0.14478)
		(layer "In4.Cu")
		(net "M_D_CPU1_SB_CA<2>")
	)
	(segment
		(start 54.273196 -262.367522)
		(end 56.03494 -262.367522)
		(width 0.14478)
		(layer "In4.Cu")
		(net "M_D_CPU1_SB_CA<2>")
	)
	(segment
		(start 76.492608 -262.692388)
		(end 77.824838 -262.692388)
		(width 0.0889)
		(layer "In4.Cu")
		(net "M_D_CPU1_SB_CA<2>")
	)
	(segment
		(start 41.961562 -262.367522)
		(end 42.272204 -262.678164)
		(width 0.14478)
		(layer "In4.Cu")
		(net "M_D_CPU1_SB_CA<2>")
	)
	(segment
		(start 44.675806 -262.367522)
		(end 44.986448 -262.678164)
		(width 0.14478)
		(layer "In4.Cu")
		(net "M_D_CPU1_SB_CA<2>")
	)
	(segment
		(start 57.14746 -262.367522)
		(end 57.458102 -262.678164)
		(width 0.14478)
		(layer "In4.Cu")
		(net "M_D_CPU1_SB_CA<2>")
	)
	(segment
		(start 46.655228 -262.367522)
		(end 48.302418 -262.367522)
		(width 0.14478)
		(layer "In4.Cu")
		(net "M_D_CPU1_SB_CA<2>")
	)
	(segment
		(start 37.75075 -262.652764)
		(end 38.021768 -262.652764)
		(width 0.14478)
		(layer "In4.Cu")
		(net "M_D_CPU1_SB_CA<2>")
	)
	(segment
		(start 56.03494 -262.367522)
		(end 56.345582 -262.678164)
		(width 0.14478)
		(layer "In4.Cu")
		(net "M_D_CPU1_SB_CA<2>")
	)
	(segment
		(start 89.229692 -263.073642)
		(end 89.238074 -263.068816)
		(width 0.0889)
		(layer "In4.Cu")
		(net "M_D_CPU1_SB_CA<2>")
	)
	(segment
		(start 36.795964 -262.785352)
		(end 37.213794 -262.367522)
		(width 0.14478)
		(layer "In4.Cu")
		(net "M_D_CPU1_SB_CA<2>")
	)
	(segment
		(start 59.683142 -262.678164)
		(end 59.92876 -262.678164)
		(width 0.14478)
		(layer "In4.Cu")
		(net "M_D_CPU1_SB_CA<2>")
	)
	(segment
		(start 52.604416 -262.678164)
		(end 52.850034 -262.678164)
		(width 0.14478)
		(layer "In4.Cu")
		(net "M_D_CPU1_SB_CA<2>")
	)
	(segment
		(start 52.293774 -262.367522)
		(end 52.604416 -262.678164)
		(width 0.14478)
		(layer "In4.Cu")
		(net "M_D_CPU1_SB_CA<2>")
	)
	(segment
		(start 52.850034 -262.678164)
		(end 53.160676 -262.367522)
		(width 0.14478)
		(layer "In4.Cu")
		(net "M_D_CPU1_SB_CA<2>")
	)
	(segment
		(start 77.824838 -262.692388)
		(end 78.251812 -263.119362)
		(width 0.0889)
		(layer "In4.Cu")
		(net "M_D_CPU1_SB_CA<2>")
	)
	(segment
		(start 37.465508 -262.367522)
		(end 37.75075 -262.652764)
		(width 0.14478)
		(layer "In4.Cu")
		(net "M_D_CPU1_SB_CA<2>")
	)
	(segment
		(start 80.769714 -263.073642)
		(end 80.778096 -263.068816)
		(width 0.0889)
		(layer "In4.Cu")
		(net "M_D_CPU1_SB_CA<2>")
	)
	(segment
		(start 49.414938 -262.367522)
		(end 49.72558 -262.678164)
		(width 0.14478)
		(layer "In4.Cu")
		(net "M_D_CPU1_SB_CA<2>")
	)
	(segment
		(start 50.28184 -262.367522)
		(end 50.527458 -262.367522)
		(width 0.14478)
		(layer "In4.Cu")
		(net "M_D_CPU1_SB_CA<2>")
	)
	(segment
		(start 81.344008 -263.068816)
		(end 81.35239 -263.073642)
		(width 0.0889)
		(layer "In4.Cu")
		(net "M_D_CPU1_SB_CA<2>")
	)
	(segment
		(start 84.529676 -263.073642)
		(end 84.538058 -263.068816)
		(width 0.0889)
		(layer "In4.Cu")
		(net "M_D_CPU1_SB_CA<2>")
	)
	(segment
		(start 51.39436 -262.367522)
		(end 52.293774 -262.367522)
		(width 0.14478)
		(layer "In4.Cu")
		(net "M_D_CPU1_SB_CA<2>")
	)
	(segment
		(start 53.716936 -262.678164)
		(end 53.962554 -262.678164)
		(width 0.14478)
		(layer "In4.Cu")
		(net "M_D_CPU1_SB_CA<2>")
	)
	(segment
		(start 42.517822 -262.678164)
		(end 42.828464 -262.367522)
		(width 0.14478)
		(layer "In4.Cu")
		(net "M_D_CPU1_SB_CA<2>")
	)
	(segment
		(start 88.289638 -263.073642)
		(end 88.29802 -263.068816)
		(width 0.0889)
		(layer "In4.Cu")
		(net "M_D_CPU1_SB_CA<2>")
	)
	(segment
		(start 75.928982 -262.75538)
		(end 76.429616 -262.75538)
		(width 0.0889)
		(layer "In4.Cu")
		(net "M_D_CPU1_SB_CA<2>")
	)
	(segment
		(start 53.962554 -262.678164)
		(end 54.273196 -262.367522)
		(width 0.14478)
		(layer "In4.Cu")
		(net "M_D_CPU1_SB_CA<2>")
	)
	(segment
		(start 41.405302 -262.678164)
		(end 41.715944 -262.367522)
		(width 0.14478)
		(layer "In4.Cu")
		(net "M_D_CPU1_SB_CA<2>")
	)
	(segment
		(start 50.527458 -262.367522)
		(end 50.8381 -262.678164)
		(width 0.14478)
		(layer "In4.Cu")
		(net "M_D_CPU1_SB_CA<2>")
	)
	(segment
		(start 89.803986 -263.068816)
		(end 89.812368 -263.073642)
		(width 0.0889)
		(layer "In4.Cu")
		(net "M_D_CPU1_SB_CA<2>")
	)
	(segment
		(start 83.589622 -263.073642)
		(end 83.598004 -263.068816)
		(width 0.0889)
		(layer "In4.Cu")
		(net "M_D_CPU1_SB_CA<2>")
	)
	(segment
		(start 43.074082 -262.367522)
		(end 43.384724 -262.678164)
		(width 0.14478)
		(layer "In4.Cu")
		(net "M_D_CPU1_SB_CA<2>")
	)
	(segment
		(start 43.630342 -262.678164)
		(end 43.940984 -262.367522)
		(width 0.14478)
		(layer "In4.Cu")
		(net "M_D_CPU1_SB_CA<2>")
	)
	(segment
		(start 38.021768 -262.652764)
		(end 38.30701 -262.367522)
		(width 0.14478)
		(layer "In4.Cu")
		(net "M_D_CPU1_SB_CA<2>")
	)
	(segment
		(start 39.134288 -262.652764)
		(end 39.41953 -262.367522)
		(width 0.14478)
		(layer "In4.Cu")
		(net "M_D_CPU1_SB_CA<2>")
	)
	(segment
		(start 51.083718 -262.678164)
		(end 51.39436 -262.367522)
		(width 0.14478)
		(layer "In4.Cu")
		(net "M_D_CPU1_SB_CA<2>")
	)
	(segment
		(start 43.384724 -262.678164)
		(end 43.630342 -262.678164)
		(width 0.14478)
		(layer "In4.Cu")
		(net "M_D_CPU1_SB_CA<2>")
	)
	(segment
		(start 57.458102 -262.678164)
		(end 57.70372 -262.678164)
		(width 0.14478)
		(layer "In4.Cu")
		(net "M_D_CPU1_SB_CA<2>")
	)
	(segment
		(start 43.940984 -262.367522)
		(end 44.675806 -262.367522)
		(width 0.14478)
		(layer "In4.Cu")
		(net "M_D_CPU1_SB_CA<2>")
	)
	(segment
		(start 56.345582 -262.678164)
		(end 56.5912 -262.678164)
		(width 0.14478)
		(layer "In4.Cu")
		(net "M_D_CPU1_SB_CA<2>")
	)
	(segment
		(start 58.570622 -262.678164)
		(end 58.81624 -262.678164)
		(width 0.14478)
		(layer "In4.Cu")
		(net "M_D_CPU1_SB_CA<2>")
	)
	(segment
		(start 58.25998 -262.367522)
		(end 58.570622 -262.678164)
		(width 0.14478)
		(layer "In4.Cu")
		(net "M_D_CPU1_SB_CA<2>")
	)
	(segment
		(start 86.044024 -263.068816)
		(end 86.052406 -263.073642)
		(width 0.0889)
		(layer "In4.Cu")
		(net "M_D_CPU1_SB_CA<2>")
	)
	(segment
		(start 53.406294 -262.367522)
		(end 53.716936 -262.678164)
		(width 0.14478)
		(layer "In4.Cu")
		(net "M_D_CPU1_SB_CA<2>")
	)
	(segment
		(start 91.085162 -263.011666)
		(end 90.930984 -262.746236)
		(width 0.0889)
		(layer "In4.Cu")
		(net "M_D_CPU1_SB_CA<2>")
	)
	(segment
		(start 38.86327 -262.652764)
		(end 39.134288 -262.652764)
		(width 0.14478)
		(layer "In4.Cu")
		(net "M_D_CPU1_SB_CA<2>")
	)
	(segment
		(start 76.429616 -262.75538)
		(end 76.492608 -262.692388)
		(width 0.0889)
		(layer "In4.Cu")
		(net "M_D_CPU1_SB_CA<2>")
	)
	(segment
		(start 48.858678 -262.678164)
		(end 49.16932 -262.367522)
		(width 0.14478)
		(layer "In4.Cu")
		(net "M_D_CPU1_SB_CA<2>")
	)
	(segment
		(start 59.3725 -262.367522)
		(end 59.683142 -262.678164)
		(width 0.14478)
		(layer "In4.Cu")
		(net "M_D_CPU1_SB_CA<2>")
	)
	(segment
		(start 45.232066 -262.678164)
		(end 45.542708 -262.367522)
		(width 0.14478)
		(layer "In4.Cu")
		(net "M_D_CPU1_SB_CA<2>")
	)
	(segment
		(start 38.578028 -262.367522)
		(end 38.86327 -262.652764)
		(width 0.14478)
		(layer "In4.Cu")
		(net "M_D_CPU1_SB_CA<2>")
	)
	(segment
		(start 45.788326 -262.367522)
		(end 46.098968 -262.678164)
		(width 0.14478)
		(layer "In4.Cu")
		(net "M_D_CPU1_SB_CA<2>")
	)
	(segment
		(start 42.272204 -262.678164)
		(end 42.517822 -262.678164)
		(width 0.14478)
		(layer "In4.Cu")
		(net "M_D_CPU1_SB_CA<2>")
	)
	(segment
		(start 53.160676 -262.367522)
		(end 53.406294 -262.367522)
		(width 0.14478)
		(layer "In4.Cu")
		(net "M_D_CPU1_SB_CA<2>")
	)
	(segment
		(start 46.098968 -262.678164)
		(end 46.344586 -262.678164)
		(width 0.14478)
		(layer "In4.Cu")
		(net "M_D_CPU1_SB_CA<2>")
	)
	(segment
		(start 59.126882 -262.367522)
		(end 59.3725 -262.367522)
		(width 0.14478)
		(layer "In4.Cu")
		(net "M_D_CPU1_SB_CA<2>")
	)
	(segment
		(start 80.39354 -263.06272)
		(end 80.403954 -263.068816)
		(width 0.0889)
		(layer "In4.Cu")
		(net "M_D_CPU1_SB_CA<2>")
	)
	(segment
		(start 48.302418 -262.367522)
		(end 48.61306 -262.678164)
		(width 0.14478)
		(layer "In4.Cu")
		(net "M_D_CPU1_SB_CA<2>")
	)
	(segment
		(start 40.849042 -262.367522)
		(end 41.159684 -262.678164)
		(width 0.14478)
		(layer "In4.Cu")
		(net "M_D_CPU1_SB_CA<2>")
	)
	(segment
		(start 37.213794 -262.367522)
		(end 37.465508 -262.367522)
		(width 0.14478)
		(layer "In4.Cu")
		(net "M_D_CPU1_SB_CA<2>")
	)
	(segment
		(start 91.06281 -263.094978)
		(end 91.085162 -263.011666)
		(width 0.0889)
		(layer "In4.Cu")
		(net "M_D_CPU1_SB_CA<2>")
	)
	(segment
		(start 49.16932 -262.367522)
		(end 49.414938 -262.367522)
		(width 0.14478)
		(layer "In4.Cu")
		(net "M_D_CPU1_SB_CA<2>")
	)
	(segment
		(start 41.159684 -262.678164)
		(end 41.405302 -262.678164)
		(width 0.14478)
		(layer "In4.Cu")
		(net "M_D_CPU1_SB_CA<2>")
	)
	(segment
		(start 42.828464 -262.367522)
		(end 43.074082 -262.367522)
		(width 0.14478)
		(layer "In4.Cu")
		(net "M_D_CPU1_SB_CA<2>")
	)
	(segment
		(start 56.5912 -262.678164)
		(end 56.901842 -262.367522)
		(width 0.14478)
		(layer "In4.Cu")
		(net "M_D_CPU1_SB_CA<2>")
	)
	(segment
		(start 66.029332 -262.162544)
		(end 66.622168 -262.75538)
		(width 0.14478)
		(layer "In4.Cu")
		(net "M_D_CPU1_SB_CA<2>")
	)
	(segment
		(start 49.971198 -262.678164)
		(end 50.28184 -262.367522)
		(width 0.14478)
		(layer "In4.Cu")
		(net "M_D_CPU1_SB_CA<2>")
	)
	(segment
		(start 90.74404 -263.068816)
		(end 90.752422 -263.073642)
		(width 0.0889)
		(layer "In4.Cu")
		(net "M_D_CPU1_SB_CA<2>")
	)
	(segment
		(start 38.30701 -262.367522)
		(end 38.578028 -262.367522)
		(width 0.14478)
		(layer "In4.Cu")
		(net "M_D_CPU1_SB_CA<2>")
	)
	(segment
		(start 41.715944 -262.367522)
		(end 41.961562 -262.367522)
		(width 0.14478)
		(layer "In4.Cu")
		(net "M_D_CPU1_SB_CA<2>")
	)
	(segment
		(start 57.70372 -262.678164)
		(end 58.014362 -262.367522)
		(width 0.14478)
		(layer "In4.Cu")
		(net "M_D_CPU1_SB_CA<2>")
	)
	(segment
		(start 58.014362 -262.367522)
		(end 58.25998 -262.367522)
		(width 0.14478)
		(layer "In4.Cu")
		(net "M_D_CPU1_SB_CA<2>")
	)
	(segment
		(start 56.901842 -262.367522)
		(end 57.14746 -262.367522)
		(width 0.14478)
		(layer "In4.Cu")
		(net "M_D_CPU1_SB_CA<2>")
	)
	(segment
		(start 50.8381 -262.678164)
		(end 51.083718 -262.678164)
		(width 0.14478)
		(layer "In4.Cu")
		(net "M_D_CPU1_SB_CA<2>")
	)
	(segment
		(start 60.44438 -262.162544)
		(end 66.029332 -262.162544)
		(width 0.14478)
		(layer "In4.Cu")
		(net "M_D_CPU1_SB_CA<2>")
	)
	(segment
		(start 46.344586 -262.678164)
		(end 46.655228 -262.367522)
		(width 0.14478)
		(layer "In4.Cu")
		(net "M_D_CPU1_SB_CA<2>")
	)
	(segment
		(start 85.10397 -263.068816)
		(end 85.112352 -263.073642)
		(width 0.0889)
		(layer "In4.Cu")
		(net "M_D_CPU1_SB_CA<2>")
	)
	(segment
		(start 44.986448 -262.678164)
		(end 45.232066 -262.678164)
		(width 0.14478)
		(layer "In4.Cu")
		(net "M_D_CPU1_SB_CA<2>")
	)
	(segment
		(start 66.622168 -262.75538)
		(end 75.928982 -262.75538)
		(width 0.14478)
		(layer "In4.Cu")
		(net "M_D_CPU1_SB_CA<2>")
	)
	(segment
		(start 59.92876 -262.678164)
		(end 60.44438 -262.162544)
		(width 0.14478)
		(layer "In4.Cu")
		(net "M_D_CPU1_SB_CA<2>")
	)
	(segment
		(start 78.251812 -263.119362)
		(end 79.65059 -263.119362)
		(width 0.0889)
		(layer "In4.Cu")
		(net "M_D_CPU1_SB_CA<2>")
	)
	(segment
		(start 39.41953 -262.367522)
		(end 40.849042 -262.367522)
		(width 0.14478)
		(layer "In4.Cu")
		(net "M_D_CPU1_SB_CA<2>")
	)
	(segment
		(start 49.72558 -262.678164)
		(end 49.971198 -262.678164)
		(width 0.14478)
		(layer "In4.Cu")
		(net "M_D_CPU1_SB_CA<2>")
	)
	(segment
		(start 45.542708 -262.367522)
		(end 45.788326 -262.367522)
		(width 0.14478)
		(layer "In4.Cu")
		(net "M_D_CPU1_SB_CA<2>")
	)
	(segment
		(start 58.81624 -262.678164)
		(end 59.126882 -262.367522)
		(width 0.14478)
		(layer "In4.Cu")
		(net "M_D_CPU1_SB_CA<2>")
	)
	(arc
		(start 87.357966 -263.068816)
		(mid 87.640922 -262.992639)
		(end 87.923878 -263.068816)
		(width 0.0889)
		(layer "In4.Cu")
		(net "M_D_CPU1_SB_CA<2>")
	)
	(arc
		(start 85.478112 -263.068816)
		(mid 85.761068 -262.992639)
		(end 86.044024 -263.068816)
		(width 0.0889)
		(layer "In4.Cu")
		(net "M_D_CPU1_SB_CA<2>")
	)
	(arc
		(start 80.403954 -263.068816)
		(mid 80.586205 -263.119166)
		(end 80.769714 -263.073642)
		(width 0.0889)
		(layer "In4.Cu")
		(net "M_D_CPU1_SB_CA<2>")
	)
	(arc
		(start 81.71815 -263.068816)
		(mid 82.001106 -262.992639)
		(end 82.284062 -263.068816)
		(width 0.0889)
		(layer "In4.Cu")
		(net "M_D_CPU1_SB_CA<2>")
	)
	(arc
		(start 80.778096 -263.068816)
		(mid 81.061052 -262.992639)
		(end 81.344008 -263.068816)
		(width 0.0889)
		(layer "In4.Cu")
		(net "M_D_CPU1_SB_CA<2>")
	)
	(arc
		(start 81.35239 -263.073642)
		(mid 81.535898 -263.119136)
		(end 81.71815 -263.068816)
		(width 0.0889)
		(layer "In4.Cu")
		(net "M_D_CPU1_SB_CA<2>")
	)
	(arc
		(start 90.178128 -263.068816)
		(mid 90.461084 -262.992639)
		(end 90.74404 -263.068816)
		(width 0.0889)
		(layer "In4.Cu")
		(net "M_D_CPU1_SB_CA<2>")
	)
	(arc
		(start 89.812368 -263.073642)
		(mid 89.995876 -263.119136)
		(end 90.178128 -263.068816)
		(width 0.0889)
		(layer "In4.Cu")
		(net "M_D_CPU1_SB_CA<2>")
	)
	(arc
		(start 89.238074 -263.068816)
		(mid 89.52103 -262.992639)
		(end 89.803986 -263.068816)
		(width 0.0889)
		(layer "In4.Cu")
		(net "M_D_CPU1_SB_CA<2>")
	)
	(arc
		(start 83.223862 -263.068816)
		(mid 83.406113 -263.119166)
		(end 83.589622 -263.073642)
		(width 0.0889)
		(layer "In4.Cu")
		(net "M_D_CPU1_SB_CA<2>")
	)
	(arc
		(start 90.752422 -263.073642)
		(mid 90.905292 -263.118283)
		(end 91.06281 -263.094978)
		(width 0.0889)
		(layer "In4.Cu")
		(net "M_D_CPU1_SB_CA<2>")
	)
	(arc
		(start 87.923878 -263.068816)
		(mid 88.106129 -263.119166)
		(end 88.289638 -263.073642)
		(width 0.0889)
		(layer "In4.Cu")
		(net "M_D_CPU1_SB_CA<2>")
	)
	(arc
		(start 86.418166 -263.068816)
		(mid 86.701122 -262.992639)
		(end 86.984078 -263.068816)
		(width 0.0889)
		(layer "In4.Cu")
		(net "M_D_CPU1_SB_CA<2>")
	)
	(arc
		(start 84.538058 -263.068816)
		(mid 84.821014 -262.992639)
		(end 85.10397 -263.068816)
		(width 0.0889)
		(layer "In4.Cu")
		(net "M_D_CPU1_SB_CA<2>")
	)
	(arc
		(start 88.863932 -263.068816)
		(mid 89.046183 -263.119166)
		(end 89.229692 -263.073642)
		(width 0.0889)
		(layer "In4.Cu")
		(net "M_D_CPU1_SB_CA<2>")
	)
	(arc
		(start 82.65795 -263.068816)
		(mid 82.940906 -262.992639)
		(end 83.223862 -263.068816)
		(width 0.0889)
		(layer "In4.Cu")
		(net "M_D_CPU1_SB_CA<2>")
	)
	(arc
		(start 79.837788 -263.068816)
		(mid 80.114855 -262.992545)
		(end 80.39354 -263.06272)
		(width 0.0889)
		(layer "In4.Cu")
		(net "M_D_CPU1_SB_CA<2>")
	)
	(arc
		(start 86.052406 -263.073642)
		(mid 86.235914 -263.119136)
		(end 86.418166 -263.068816)
		(width 0.0889)
		(layer "In4.Cu")
		(net "M_D_CPU1_SB_CA<2>")
	)
	(arc
		(start 88.29802 -263.068816)
		(mid 88.580976 -262.992639)
		(end 88.863932 -263.068816)
		(width 0.0889)
		(layer "In4.Cu")
		(net "M_D_CPU1_SB_CA<2>")
	)
	(arc
		(start 83.598004 -263.068816)
		(mid 83.88096 -262.992639)
		(end 84.163916 -263.068816)
		(width 0.0889)
		(layer "In4.Cu")
		(net "M_D_CPU1_SB_CA<2>")
	)
	(arc
		(start 85.112352 -263.073642)
		(mid 85.29586 -263.119136)
		(end 85.478112 -263.068816)
		(width 0.0889)
		(layer "In4.Cu")
		(net "M_D_CPU1_SB_CA<2>")
	)
	(arc
		(start 84.163916 -263.068816)
		(mid 84.346167 -263.119166)
		(end 84.529676 -263.073642)
		(width 0.0889)
		(layer "In4.Cu")
		(net "M_D_CPU1_SB_CA<2>")
	)
	(arc
		(start 79.65059 -263.119362)
		(mid 79.747516 -263.106425)
		(end 79.837788 -263.068816)
		(width 0.0889)
		(layer "In4.Cu")
		(net "M_D_CPU1_SB_CA<2>")
	)
	(arc
		(start 82.284062 -263.068816)
		(mid 82.471006 -263.119071)
		(end 82.65795 -263.068816)
		(width 0.0889)
		(layer "In4.Cu")
		(net "M_D_CPU1_SB_CA<2>")
	)
	(arc
		(start 86.984078 -263.068816)
		(mid 87.171022 -263.119071)
		(end 87.357966 -263.068816)
		(width 0.0889)
		(layer "In4.Cu")
		(net "M_D_CPU1_SB_CA<2>")
	)
	(segment
		(start 93.277944 -262.480298)
		(end 92.811092 -262.746236)
		(width 0.10668)
		(layer "F.Cu")
		(net "M_D_CPU1_SB_CA<1>")
	)
	(segment
		(start 80.389222 -262.432292)
		(end 80.403954 -262.423656)
		(width 0.0889)
		(layer "In4.Cu")
		(net "M_D_CPU1_SB_CA<1>")
	)
	(segment
		(start 80.769714 -262.41883)
		(end 80.778096 -262.423656)
		(width 0.0889)
		(layer "In4.Cu")
		(net "M_D_CPU1_SB_CA<1>")
	)
	(segment
		(start 85.10397 -262.423656)
		(end 85.112352 -262.41883)
		(width 0.0889)
		(layer "In4.Cu")
		(net "M_D_CPU1_SB_CA<1>")
	)
	(segment
		(start 75.986386 -262.246364)
		(end 77.770228 -262.246364)
		(width 0.0889)
		(layer "In4.Cu")
		(net "M_D_CPU1_SB_CA<1>")
	)
	(segment
		(start 88.289638 -262.41883)
		(end 88.29802 -262.423656)
		(width 0.0889)
		(layer "In4.Cu")
		(net "M_D_CPU1_SB_CA<1>")
	)
	(segment
		(start 83.589622 -262.41883)
		(end 83.598004 -262.423656)
		(width 0.0889)
		(layer "In4.Cu")
		(net "M_D_CPU1_SB_CA<1>")
	)
	(segment
		(start 89.803986 -262.423656)
		(end 89.812368 -262.41883)
		(width 0.0889)
		(layer "In4.Cu")
		(net "M_D_CPU1_SB_CA<1>")
	)
	(segment
		(start 66.013076 -261.510272)
		(end 66.749168 -262.246364)
		(width 0.14478)
		(layer "In4.Cu")
		(net "M_D_CPU1_SB_CA<1>")
	)
	(segment
		(start 66.749168 -262.246364)
		(end 75.986386 -262.246364)
		(width 0.14478)
		(layer "In4.Cu")
		(net "M_D_CPU1_SB_CA<1>")
	)
	(segment
		(start 32.695896 -261.935214)
		(end 33.120838 -261.510272)
		(width 0.14478)
		(layer "In4.Cu")
		(net "M_D_CPU1_SB_CA<1>")
	)
	(segment
		(start 92.656914 -262.480806)
		(end 92.811092 -262.746236)
		(width 0.0889)
		(layer "In4.Cu")
		(net "M_D_CPU1_SB_CA<1>")
	)
	(segment
		(start 90.74404 -262.423656)
		(end 90.752422 -262.41883)
		(width 0.0889)
		(layer "In4.Cu")
		(net "M_D_CPU1_SB_CA<1>")
	)
	(segment
		(start 81.344008 -262.423656)
		(end 81.35239 -262.41883)
		(width 0.0889)
		(layer "In4.Cu")
		(net "M_D_CPU1_SB_CA<1>")
	)
	(segment
		(start 33.120838 -261.510272)
		(end 66.013076 -261.510272)
		(width 0.14478)
		(layer "In4.Cu")
		(net "M_D_CPU1_SB_CA<1>")
	)
	(segment
		(start 89.229692 -262.41883)
		(end 89.238074 -262.423656)
		(width 0.0889)
		(layer "In4.Cu")
		(net "M_D_CPU1_SB_CA<1>")
	)
	(segment
		(start 77.80909 -262.285226)
		(end 79.46644 -262.285226)
		(width 0.0889)
		(layer "In4.Cu")
		(net "M_D_CPU1_SB_CA<1>")
	)
	(segment
		(start 86.044024 -262.423656)
		(end 86.052406 -262.41883)
		(width 0.0889)
		(layer "In4.Cu")
		(net "M_D_CPU1_SB_CA<1>")
	)
	(segment
		(start 92.560648 -262.455406)
		(end 92.656914 -262.480806)
		(width 0.0889)
		(layer "In4.Cu")
		(net "M_D_CPU1_SB_CA<1>")
	)
	(segment
		(start 84.529676 -262.41883)
		(end 84.538058 -262.423656)
		(width 0.0889)
		(layer "In4.Cu")
		(net "M_D_CPU1_SB_CA<1>")
	)
	(segment
		(start 77.770228 -262.246364)
		(end 77.80909 -262.285226)
		(width 0.0889)
		(layer "In4.Cu")
		(net "M_D_CPU1_SB_CA<1>")
	)
	(arc
		(start 85.478112 -262.423656)
		(mid 85.761068 -262.499833)
		(end 86.044024 -262.423656)
		(width 0.0889)
		(layer "In4.Cu")
		(net "M_D_CPU1_SB_CA<1>")
	)
	(arc
		(start 79.837534 -262.423656)
		(mid 80.11224 -262.50002)
		(end 80.389222 -262.432292)
		(width 0.0889)
		(layer "In4.Cu")
		(net "M_D_CPU1_SB_CA<1>")
	)
	(arc
		(start 89.812368 -262.41883)
		(mid 89.995876 -262.373336)
		(end 90.178128 -262.423656)
		(width 0.0889)
		(layer "In4.Cu")
		(net "M_D_CPU1_SB_CA<1>")
	)
	(arc
		(start 90.178128 -262.423656)
		(mid 90.461084 -262.499833)
		(end 90.74404 -262.423656)
		(width 0.0889)
		(layer "In4.Cu")
		(net "M_D_CPU1_SB_CA<1>")
	)
	(arc
		(start 80.778096 -262.423656)
		(mid 81.061052 -262.499833)
		(end 81.344008 -262.423656)
		(width 0.0889)
		(layer "In4.Cu")
		(net "M_D_CPU1_SB_CA<1>")
	)
	(arc
		(start 82.65795 -262.423656)
		(mid 82.940906 -262.499833)
		(end 83.223862 -262.423656)
		(width 0.0889)
		(layer "In4.Cu")
		(net "M_D_CPU1_SB_CA<1>")
	)
	(arc
		(start 79.46644 -262.285226)
		(mid 79.51102 -262.2886)
		(end 79.554578 -262.298688)
		(width 0.0889)
		(layer "In4.Cu")
		(net "M_D_CPU1_SB_CA<1>")
	)
	(arc
		(start 91.684094 -262.423656)
		(mid 91.871038 -262.373401)
		(end 92.057982 -262.423656)
		(width 0.0889)
		(layer "In4.Cu")
		(net "M_D_CPU1_SB_CA<1>")
	)
	(arc
		(start 81.35239 -262.41883)
		(mid 81.535898 -262.373336)
		(end 81.71815 -262.423656)
		(width 0.0889)
		(layer "In4.Cu")
		(net "M_D_CPU1_SB_CA<1>")
	)
	(arc
		(start 87.357966 -262.423656)
		(mid 87.640922 -262.499833)
		(end 87.923878 -262.423656)
		(width 0.0889)
		(layer "In4.Cu")
		(net "M_D_CPU1_SB_CA<1>")
	)
	(arc
		(start 88.29802 -262.423656)
		(mid 88.580976 -262.499833)
		(end 88.863932 -262.423656)
		(width 0.0889)
		(layer "In4.Cu")
		(net "M_D_CPU1_SB_CA<1>")
	)
	(arc
		(start 83.598004 -262.423656)
		(mid 83.88096 -262.499833)
		(end 84.163916 -262.423656)
		(width 0.0889)
		(layer "In4.Cu")
		(net "M_D_CPU1_SB_CA<1>")
	)
	(arc
		(start 84.163916 -262.423656)
		(mid 84.346167 -262.373306)
		(end 84.529676 -262.41883)
		(width 0.0889)
		(layer "In4.Cu")
		(net "M_D_CPU1_SB_CA<1>")
	)
	(arc
		(start 90.752422 -262.41883)
		(mid 90.93593 -262.373336)
		(end 91.118182 -262.423656)
		(width 0.0889)
		(layer "In4.Cu")
		(net "M_D_CPU1_SB_CA<1>")
	)
	(arc
		(start 92.057982 -262.423656)
		(mid 92.305578 -262.498834)
		(end 92.560648 -262.455406)
		(width 0.0889)
		(layer "In4.Cu")
		(net "M_D_CPU1_SB_CA<1>")
	)
	(arc
		(start 88.863932 -262.423656)
		(mid 89.046183 -262.373306)
		(end 89.229692 -262.41883)
		(width 0.0889)
		(layer "In4.Cu")
		(net "M_D_CPU1_SB_CA<1>")
	)
	(arc
		(start 86.984078 -262.423656)
		(mid 87.171022 -262.373401)
		(end 87.357966 -262.423656)
		(width 0.0889)
		(layer "In4.Cu")
		(net "M_D_CPU1_SB_CA<1>")
	)
	(arc
		(start 83.223862 -262.423656)
		(mid 83.406113 -262.373306)
		(end 83.589622 -262.41883)
		(width 0.0889)
		(layer "In4.Cu")
		(net "M_D_CPU1_SB_CA<1>")
	)
	(arc
		(start 91.118182 -262.423656)
		(mid 91.401138 -262.499833)
		(end 91.684094 -262.423656)
		(width 0.0889)
		(layer "In4.Cu")
		(net "M_D_CPU1_SB_CA<1>")
	)
	(arc
		(start 79.554578 -262.298688)
		(mid 79.699527 -262.353313)
		(end 79.837534 -262.423656)
		(width 0.0889)
		(layer "In4.Cu")
		(net "M_D_CPU1_SB_CA<1>")
	)
	(arc
		(start 85.112352 -262.41883)
		(mid 85.29586 -262.373336)
		(end 85.478112 -262.423656)
		(width 0.0889)
		(layer "In4.Cu")
		(net "M_D_CPU1_SB_CA<1>")
	)
	(arc
		(start 86.418166 -262.423656)
		(mid 86.701122 -262.499833)
		(end 86.984078 -262.423656)
		(width 0.0889)
		(layer "In4.Cu")
		(net "M_D_CPU1_SB_CA<1>")
	)
	(arc
		(start 80.403954 -262.423656)
		(mid 80.586205 -262.373306)
		(end 80.769714 -262.41883)
		(width 0.0889)
		(layer "In4.Cu")
		(net "M_D_CPU1_SB_CA<1>")
	)
	(arc
		(start 87.923878 -262.423656)
		(mid 88.106129 -262.373306)
		(end 88.289638 -262.41883)
		(width 0.0889)
		(layer "In4.Cu")
		(net "M_D_CPU1_SB_CA<1>")
	)
	(arc
		(start 81.71815 -262.423656)
		(mid 82.001106 -262.499833)
		(end 82.284062 -262.423656)
		(width 0.0889)
		(layer "In4.Cu")
		(net "M_D_CPU1_SB_CA<1>")
	)
	(arc
		(start 82.284062 -262.423656)
		(mid 82.471006 -262.373401)
		(end 82.65795 -262.423656)
		(width 0.0889)
		(layer "In4.Cu")
		(net "M_D_CPU1_SB_CA<1>")
	)
	(arc
		(start 89.238074 -262.423656)
		(mid 89.52103 -262.499833)
		(end 89.803986 -262.423656)
		(width 0.0889)
		(layer "In4.Cu")
		(net "M_D_CPU1_SB_CA<1>")
	)
	(arc
		(start 84.538058 -262.423656)
		(mid 84.821014 -262.499833)
		(end 85.10397 -262.423656)
		(width 0.0889)
		(layer "In4.Cu")
		(net "M_D_CPU1_SB_CA<1>")
	)
	(arc
		(start 86.052406 -262.41883)
		(mid 86.235914 -262.373336)
		(end 86.418166 -262.423656)
		(width 0.0889)
		(layer "In4.Cu")
		(net "M_D_CPU1_SB_CA<1>")
	)
	(segment
		(start 92.80779 -261.670292)
		(end 92.340938 -261.93623)
		(width 0.10668)
		(layer "F.Cu")
		(net "M_D_CPU1_SB_CA<0>")
	)
	(segment
		(start 45.1993 -260.976364)
		(end 45.439584 -260.976364)
		(width 0.14478)
		(layer "In4.Cu")
		(net "M_D_CPU1_SB_CA<0>")
	)
	(segment
		(start 42.339006 -260.976364)
		(end 42.57929 -260.976364)
		(width 0.14478)
		(layer "In4.Cu")
		(net "M_D_CPU1_SB_CA<0>")
	)
	(segment
		(start 40.113966 -260.976364)
		(end 40.35425 -260.976364)
		(width 0.14478)
		(layer "In4.Cu")
		(net "M_D_CPU1_SB_CA<0>")
	)
	(segment
		(start 38.12921 -260.976364)
		(end 38.445186 -260.660388)
		(width 0.14478)
		(layer "In4.Cu")
		(net "M_D_CPU1_SB_CA<0>")
	)
	(segment
		(start 60.127388 -260.660388)
		(end 66.030348 -260.660388)
		(width 0.14478)
		(layer "In4.Cu")
		(net "M_D_CPU1_SB_CA<0>")
	)
	(segment
		(start 40.91051 -260.660388)
		(end 41.226486 -260.976364)
		(width 0.14478)
		(layer "In4.Cu")
		(net "M_D_CPU1_SB_CA<0>")
	)
	(segment
		(start 46.552104 -260.976364)
		(end 46.86808 -260.660388)
		(width 0.14478)
		(layer "In4.Cu")
		(net "M_D_CPU1_SB_CA<0>")
	)
	(segment
		(start 43.451526 -260.976364)
		(end 43.69181 -260.976364)
		(width 0.14478)
		(layer "In4.Cu")
		(net "M_D_CPU1_SB_CA<0>")
	)
	(segment
		(start 41.782746 -260.660388)
		(end 42.02303 -260.660388)
		(width 0.14478)
		(layer "In4.Cu")
		(net "M_D_CPU1_SB_CA<0>")
	)
	(segment
		(start 40.670226 -260.660388)
		(end 40.91051 -260.660388)
		(width 0.14478)
		(layer "In4.Cu")
		(net "M_D_CPU1_SB_CA<0>")
	)
	(segment
		(start 66.030348 -260.660388)
		(end 67.14617 -261.77621)
		(width 0.14478)
		(layer "In4.Cu")
		(net "M_D_CPU1_SB_CA<0>")
	)
	(segment
		(start 91.5797 -262.263636)
		(end 91.588082 -262.25881)
		(width 0.0889)
		(layer "In4.Cu")
		(net "M_D_CPU1_SB_CA<0>")
	)
	(segment
		(start 57.030112 -260.660388)
		(end 57.346088 -260.976364)
		(width 0.14478)
		(layer "In4.Cu")
		(net "M_D_CPU1_SB_CA<0>")
	)
	(segment
		(start 58.142632 -260.660388)
		(end 58.458608 -260.976364)
		(width 0.14478)
		(layer "In4.Cu")
		(net "M_D_CPU1_SB_CA<0>")
	)
	(segment
		(start 37.888926 -260.976364)
		(end 38.12921 -260.976364)
		(width 0.14478)
		(layer "In4.Cu")
		(net "M_D_CPU1_SB_CA<0>")
	)
	(segment
		(start 42.895266 -260.660388)
		(end 43.13555 -260.660388)
		(width 0.14478)
		(layer "In4.Cu")
		(net "M_D_CPU1_SB_CA<0>")
	)
	(segment
		(start 41.46677 -260.976364)
		(end 41.782746 -260.660388)
		(width 0.14478)
		(layer "In4.Cu")
		(net "M_D_CPU1_SB_CA<0>")
	)
	(segment
		(start 59.014868 -260.660388)
		(end 59.255152 -260.660388)
		(width 0.14478)
		(layer "In4.Cu")
		(net "M_D_CPU1_SB_CA<0>")
	)
	(segment
		(start 76.614274 -261.77621)
		(end 76.88199 -262.043926)
		(width 0.0889)
		(layer "In4.Cu")
		(net "M_D_CPU1_SB_CA<0>")
	)
	(segment
		(start 47.108364 -260.660388)
		(end 47.42434 -260.976364)
		(width 0.14478)
		(layer "In4.Cu")
		(net "M_D_CPU1_SB_CA<0>")
	)
	(segment
		(start 58.698892 -260.976364)
		(end 59.014868 -260.660388)
		(width 0.14478)
		(layer "In4.Cu")
		(net "M_D_CPU1_SB_CA<0>")
	)
	(segment
		(start 40.35425 -260.976364)
		(end 40.670226 -260.660388)
		(width 0.14478)
		(layer "In4.Cu")
		(net "M_D_CPU1_SB_CA<0>")
	)
	(segment
		(start 87.453978 -262.25881)
		(end 87.46236 -262.263636)
		(width 0.0889)
		(layer "In4.Cu")
		(net "M_D_CPU1_SB_CA<0>")
	)
	(segment
		(start 55.121048 -260.976364)
		(end 55.361332 -260.976364)
		(width 0.14478)
		(layer "In4.Cu")
		(net "M_D_CPU1_SB_CA<0>")
	)
	(segment
		(start 53.692552 -260.660388)
		(end 54.008528 -260.976364)
		(width 0.14478)
		(layer "In4.Cu")
		(net "M_D_CPU1_SB_CA<0>")
	)
	(segment
		(start 55.677308 -260.660388)
		(end 55.917592 -260.660388)
		(width 0.14478)
		(layer "In4.Cu")
		(net "M_D_CPU1_SB_CA<0>")
	)
	(segment
		(start 59.571128 -260.976364)
		(end 59.811412 -260.976364)
		(width 0.14478)
		(layer "In4.Cu")
		(net "M_D_CPU1_SB_CA<0>")
	)
	(segment
		(start 50.445924 -260.660388)
		(end 50.7619 -260.976364)
		(width 0.14478)
		(layer "In4.Cu")
		(net "M_D_CPU1_SB_CA<0>")
	)
	(segment
		(start 37.220906 -260.660388)
		(end 37.57295 -260.660388)
		(width 0.14478)
		(layer "In4.Cu")
		(net "M_D_CPU1_SB_CA<0>")
	)
	(segment
		(start 48.53686 -260.976364)
		(end 48.777144 -260.976364)
		(width 0.14478)
		(layer "In4.Cu")
		(net "M_D_CPU1_SB_CA<0>")
	)
	(segment
		(start 57.902348 -260.660388)
		(end 58.142632 -260.660388)
		(width 0.14478)
		(layer "In4.Cu")
		(net "M_D_CPU1_SB_CA<0>")
	)
	(segment
		(start 54.564788 -260.660388)
		(end 54.805072 -260.660388)
		(width 0.14478)
		(layer "In4.Cu")
		(net "M_D_CPU1_SB_CA<0>")
	)
	(segment
		(start 82.179668 -262.263636)
		(end 82.18805 -262.25881)
		(width 0.0889)
		(layer "In4.Cu")
		(net "M_D_CPU1_SB_CA<0>")
	)
	(segment
		(start 58.458608 -260.976364)
		(end 58.698892 -260.976364)
		(width 0.14478)
		(layer "In4.Cu")
		(net "M_D_CPU1_SB_CA<0>")
	)
	(segment
		(start 42.57929 -260.976364)
		(end 42.895266 -260.660388)
		(width 0.14478)
		(layer "In4.Cu")
		(net "M_D_CPU1_SB_CA<0>")
	)
	(segment
		(start 47.9806 -260.660388)
		(end 48.220884 -260.660388)
		(width 0.14478)
		(layer "In4.Cu")
		(net "M_D_CPU1_SB_CA<0>")
	)
	(segment
		(start 51.002184 -260.976364)
		(end 51.31816 -260.660388)
		(width 0.14478)
		(layer "In4.Cu")
		(net "M_D_CPU1_SB_CA<0>")
	)
	(segment
		(start 49.889664 -260.976364)
		(end 50.20564 -260.660388)
		(width 0.14478)
		(layer "In4.Cu")
		(net "M_D_CPU1_SB_CA<0>")
	)
	(segment
		(start 43.69181 -260.976364)
		(end 44.007786 -260.660388)
		(width 0.14478)
		(layer "In4.Cu")
		(net "M_D_CPU1_SB_CA<0>")
	)
	(segment
		(start 39.557706 -260.660388)
		(end 39.79799 -260.660388)
		(width 0.14478)
		(layer "In4.Cu")
		(net "M_D_CPU1_SB_CA<0>")
	)
	(segment
		(start 39.24173 -260.976364)
		(end 39.557706 -260.660388)
		(width 0.14478)
		(layer "In4.Cu")
		(net "M_D_CPU1_SB_CA<0>")
	)
	(segment
		(start 47.664624 -260.976364)
		(end 47.9806 -260.660388)
		(width 0.14478)
		(layer "In4.Cu")
		(net "M_D_CPU1_SB_CA<0>")
	)
	(segment
		(start 59.811412 -260.976364)
		(end 60.127388 -260.660388)
		(width 0.14478)
		(layer "In4.Cu")
		(net "M_D_CPU1_SB_CA<0>")
	)
	(segment
		(start 57.586372 -260.976364)
		(end 57.902348 -260.660388)
		(width 0.14478)
		(layer "In4.Cu")
		(net "M_D_CPU1_SB_CA<0>")
	)
	(segment
		(start 55.917592 -260.660388)
		(end 56.233568 -260.976364)
		(width 0.14478)
		(layer "In4.Cu")
		(net "M_D_CPU1_SB_CA<0>")
	)
	(segment
		(start 55.361332 -260.976364)
		(end 55.677308 -260.660388)
		(width 0.14478)
		(layer "In4.Cu")
		(net "M_D_CPU1_SB_CA<0>")
	)
	(segment
		(start 67.14617 -261.77621)
		(end 75.948032 -261.77621)
		(width 0.14478)
		(layer "In4.Cu")
		(net "M_D_CPU1_SB_CA<0>")
	)
	(segment
		(start 39.001446 -260.976364)
		(end 39.24173 -260.976364)
		(width 0.14478)
		(layer "In4.Cu")
		(net "M_D_CPU1_SB_CA<0>")
	)
	(segment
		(start 52.896008 -260.976364)
		(end 53.136292 -260.976364)
		(width 0.14478)
		(layer "In4.Cu")
		(net "M_D_CPU1_SB_CA<0>")
	)
	(segment
		(start 86.879684 -262.263636)
		(end 86.888066 -262.25881)
		(width 0.0889)
		(layer "In4.Cu")
		(net "M_D_CPU1_SB_CA<0>")
	)
	(segment
		(start 54.008528 -260.976364)
		(end 54.248812 -260.976364)
		(width 0.14478)
		(layer "In4.Cu")
		(net "M_D_CPU1_SB_CA<0>")
	)
	(segment
		(start 43.13555 -260.660388)
		(end 43.451526 -260.976364)
		(width 0.14478)
		(layer "In4.Cu")
		(net "M_D_CPU1_SB_CA<0>")
	)
	(segment
		(start 42.02303 -260.660388)
		(end 42.339006 -260.976364)
		(width 0.14478)
		(layer "In4.Cu")
		(net "M_D_CPU1_SB_CA<0>")
	)
	(segment
		(start 92.495116 -262.20166)
		(end 92.340938 -261.93623)
		(width 0.0889)
		(layer "In4.Cu")
		(net "M_D_CPU1_SB_CA<0>")
	)
	(segment
		(start 85.93963 -262.263636)
		(end 85.948012 -262.25881)
		(width 0.0889)
		(layer "In4.Cu")
		(net "M_D_CPU1_SB_CA<0>")
	)
	(segment
		(start 57.346088 -260.976364)
		(end 57.586372 -260.976364)
		(width 0.14478)
		(layer "In4.Cu")
		(net "M_D_CPU1_SB_CA<0>")
	)
	(segment
		(start 54.248812 -260.976364)
		(end 54.564788 -260.660388)
		(width 0.14478)
		(layer "In4.Cu")
		(net "M_D_CPU1_SB_CA<0>")
	)
	(segment
		(start 53.136292 -260.976364)
		(end 53.452268 -260.660388)
		(width 0.14478)
		(layer "In4.Cu")
		(net "M_D_CPU1_SB_CA<0>")
	)
	(segment
		(start 49.09312 -260.660388)
		(end 49.333404 -260.660388)
		(width 0.14478)
		(layer "In4.Cu")
		(net "M_D_CPU1_SB_CA<0>")
	)
	(segment
		(start 47.42434 -260.976364)
		(end 47.664624 -260.976364)
		(width 0.14478)
		(layer "In4.Cu")
		(net "M_D_CPU1_SB_CA<0>")
	)
	(segment
		(start 37.57295 -260.660388)
		(end 37.888926 -260.976364)
		(width 0.14478)
		(layer "In4.Cu")
		(net "M_D_CPU1_SB_CA<0>")
	)
	(segment
		(start 92.153994 -262.25881)
		(end 92.162376 -262.263636)
		(width 0.0889)
		(layer "In4.Cu")
		(net "M_D_CPU1_SB_CA<0>")
	)
	(segment
		(start 56.233568 -260.976364)
		(end 56.473852 -260.976364)
		(width 0.14478)
		(layer "In4.Cu")
		(net "M_D_CPU1_SB_CA<0>")
	)
	(segment
		(start 41.226486 -260.976364)
		(end 41.46677 -260.976364)
		(width 0.14478)
		(layer "In4.Cu")
		(net "M_D_CPU1_SB_CA<0>")
	)
	(segment
		(start 92.472764 -262.284972)
		(end 92.495116 -262.20166)
		(width 0.0889)
		(layer "In4.Cu")
		(net "M_D_CPU1_SB_CA<0>")
	)
	(segment
		(start 45.75556 -260.660388)
		(end 45.995844 -260.660388)
		(width 0.14478)
		(layer "In4.Cu")
		(net "M_D_CPU1_SB_CA<0>")
	)
	(segment
		(start 45.439584 -260.976364)
		(end 45.75556 -260.660388)
		(width 0.14478)
		(layer "In4.Cu")
		(net "M_D_CPU1_SB_CA<0>")
	)
	(segment
		(start 51.31816 -260.660388)
		(end 52.580032 -260.660388)
		(width 0.14478)
		(layer "In4.Cu")
		(net "M_D_CPU1_SB_CA<0>")
	)
	(segment
		(start 82.753962 -262.25881)
		(end 82.762344 -262.263636)
		(width 0.0889)
		(layer "In4.Cu")
		(net "M_D_CPU1_SB_CA<0>")
	)
	(segment
		(start 49.333404 -260.660388)
		(end 49.64938 -260.976364)
		(width 0.14478)
		(layer "In4.Cu")
		(net "M_D_CPU1_SB_CA<0>")
	)
	(segment
		(start 44.883324 -260.660388)
		(end 45.1993 -260.976364)
		(width 0.14478)
		(layer "In4.Cu")
		(net "M_D_CPU1_SB_CA<0>")
	)
	(segment
		(start 56.473852 -260.976364)
		(end 56.789828 -260.660388)
		(width 0.14478)
		(layer "In4.Cu")
		(net "M_D_CPU1_SB_CA<0>")
	)
	(segment
		(start 48.220884 -260.660388)
		(end 48.53686 -260.976364)
		(width 0.14478)
		(layer "In4.Cu")
		(net "M_D_CPU1_SB_CA<0>")
	)
	(segment
		(start 56.789828 -260.660388)
		(end 57.030112 -260.660388)
		(width 0.14478)
		(layer "In4.Cu")
		(net "M_D_CPU1_SB_CA<0>")
	)
	(segment
		(start 44.007786 -260.660388)
		(end 44.883324 -260.660388)
		(width 0.14478)
		(layer "In4.Cu")
		(net "M_D_CPU1_SB_CA<0>")
	)
	(segment
		(start 75.948032 -261.77621)
		(end 76.614274 -261.77621)
		(width 0.0889)
		(layer "In4.Cu")
		(net "M_D_CPU1_SB_CA<0>")
	)
	(segment
		(start 59.255152 -260.660388)
		(end 59.571128 -260.976364)
		(width 0.14478)
		(layer "In4.Cu")
		(net "M_D_CPU1_SB_CA<0>")
	)
	(segment
		(start 90.639646 -262.263636)
		(end 90.648028 -262.25881)
		(width 0.0889)
		(layer "In4.Cu")
		(net "M_D_CPU1_SB_CA<0>")
	)
	(segment
		(start 38.445186 -260.660388)
		(end 38.68547 -260.660388)
		(width 0.14478)
		(layer "In4.Cu")
		(net "M_D_CPU1_SB_CA<0>")
	)
	(segment
		(start 54.805072 -260.660388)
		(end 55.121048 -260.976364)
		(width 0.14478)
		(layer "In4.Cu")
		(net "M_D_CPU1_SB_CA<0>")
	)
	(segment
		(start 53.452268 -260.660388)
		(end 53.692552 -260.660388)
		(width 0.14478)
		(layer "In4.Cu")
		(net "M_D_CPU1_SB_CA<0>")
	)
	(segment
		(start 52.580032 -260.660388)
		(end 52.896008 -260.976364)
		(width 0.14478)
		(layer "In4.Cu")
		(net "M_D_CPU1_SB_CA<0>")
	)
	(segment
		(start 49.64938 -260.976364)
		(end 49.889664 -260.976364)
		(width 0.14478)
		(layer "In4.Cu")
		(net "M_D_CPU1_SB_CA<0>")
	)
	(segment
		(start 45.995844 -260.660388)
		(end 46.31182 -260.976364)
		(width 0.14478)
		(layer "In4.Cu")
		(net "M_D_CPU1_SB_CA<0>")
	)
	(segment
		(start 39.79799 -260.660388)
		(end 40.113966 -260.976364)
		(width 0.14478)
		(layer "In4.Cu")
		(net "M_D_CPU1_SB_CA<0>")
	)
	(segment
		(start 76.88199 -262.043926)
		(end 79.135986 -262.043926)
		(width 0.0889)
		(layer "In4.Cu")
		(net "M_D_CPU1_SB_CA<0>")
	)
	(segment
		(start 38.68547 -260.660388)
		(end 39.001446 -260.976364)
		(width 0.14478)
		(layer "In4.Cu")
		(net "M_D_CPU1_SB_CA<0>")
	)
	(segment
		(start 36.795964 -261.08533)
		(end 37.220906 -260.660388)
		(width 0.14478)
		(layer "In4.Cu")
		(net "M_D_CPU1_SB_CA<0>")
	)
	(segment
		(start 46.31182 -260.976364)
		(end 46.552104 -260.976364)
		(width 0.14478)
		(layer "In4.Cu")
		(net "M_D_CPU1_SB_CA<0>")
	)
	(segment
		(start 50.7619 -260.976364)
		(end 51.002184 -260.976364)
		(width 0.14478)
		(layer "In4.Cu")
		(net "M_D_CPU1_SB_CA<0>")
	)
	(segment
		(start 46.86808 -260.660388)
		(end 47.108364 -260.660388)
		(width 0.14478)
		(layer "In4.Cu")
		(net "M_D_CPU1_SB_CA<0>")
	)
	(segment
		(start 80.299814 -262.263636)
		(end 80.308196 -262.25881)
		(width 0.0889)
		(layer "In4.Cu")
		(net "M_D_CPU1_SB_CA<0>")
	)
	(segment
		(start 83.694016 -262.25881)
		(end 83.702398 -262.263636)
		(width 0.0889)
		(layer "In4.Cu")
		(net "M_D_CPU1_SB_CA<0>")
	)
	(segment
		(start 48.777144 -260.976364)
		(end 49.09312 -260.660388)
		(width 0.14478)
		(layer "In4.Cu")
		(net "M_D_CPU1_SB_CA<0>")
	)
	(segment
		(start 50.20564 -260.660388)
		(end 50.445924 -260.660388)
		(width 0.14478)
		(layer "In4.Cu")
		(net "M_D_CPU1_SB_CA<0>")
	)
	(segment
		(start 88.394032 -262.25881)
		(end 88.402414 -262.263636)
		(width 0.0889)
		(layer "In4.Cu")
		(net "M_D_CPU1_SB_CA<0>")
	)
	(arc
		(start 87.82812 -262.25881)
		(mid 88.111076 -262.182633)
		(end 88.394032 -262.25881)
		(width 0.0889)
		(layer "In4.Cu")
		(net "M_D_CPU1_SB_CA<0>")
	)
	(arc
		(start 88.402414 -262.263636)
		(mid 88.585922 -262.30913)
		(end 88.768174 -262.25881)
		(width 0.0889)
		(layer "In4.Cu")
		(net "M_D_CPU1_SB_CA<0>")
	)
	(arc
		(start 89.334086 -262.25881)
		(mid 89.52103 -262.309065)
		(end 89.707974 -262.25881)
		(width 0.0889)
		(layer "In4.Cu")
		(net "M_D_CPU1_SB_CA<0>")
	)
	(arc
		(start 86.888066 -262.25881)
		(mid 87.171022 -262.182633)
		(end 87.453978 -262.25881)
		(width 0.0889)
		(layer "In4.Cu")
		(net "M_D_CPU1_SB_CA<0>")
	)
	(arc
		(start 82.18805 -262.25881)
		(mid 82.471006 -262.182633)
		(end 82.753962 -262.25881)
		(width 0.0889)
		(layer "In4.Cu")
		(net "M_D_CPU1_SB_CA<0>")
	)
	(arc
		(start 84.068158 -262.25881)
		(mid 84.351114 -262.182633)
		(end 84.63407 -262.25881)
		(width 0.0889)
		(layer "In4.Cu")
		(net "M_D_CPU1_SB_CA<0>")
	)
	(arc
		(start 85.007958 -262.25881)
		(mid 85.290914 -262.182633)
		(end 85.57387 -262.25881)
		(width 0.0889)
		(layer "In4.Cu")
		(net "M_D_CPU1_SB_CA<0>")
	)
	(arc
		(start 92.162376 -262.263636)
		(mid 92.315246 -262.308277)
		(end 92.472764 -262.284972)
		(width 0.0889)
		(layer "In4.Cu")
		(net "M_D_CPU1_SB_CA<0>")
	)
	(arc
		(start 85.57387 -262.25881)
		(mid 85.756121 -262.30916)
		(end 85.93963 -262.263636)
		(width 0.0889)
		(layer "In4.Cu")
		(net "M_D_CPU1_SB_CA<0>")
	)
	(arc
		(start 88.768174 -262.25881)
		(mid 89.05113 -262.182633)
		(end 89.334086 -262.25881)
		(width 0.0889)
		(layer "In4.Cu")
		(net "M_D_CPU1_SB_CA<0>")
	)
	(arc
		(start 86.513924 -262.25881)
		(mid 86.696175 -262.30916)
		(end 86.879684 -262.263636)
		(width 0.0889)
		(layer "In4.Cu")
		(net "M_D_CPU1_SB_CA<0>")
	)
	(arc
		(start 79.135986 -262.043926)
		(mid 79.548981 -262.098597)
		(end 79.933546 -262.25881)
		(width 0.0889)
		(layer "In4.Cu")
		(net "M_D_CPU1_SB_CA<0>")
	)
	(arc
		(start 81.813908 -262.25881)
		(mid 81.996159 -262.30916)
		(end 82.179668 -262.263636)
		(width 0.0889)
		(layer "In4.Cu")
		(net "M_D_CPU1_SB_CA<0>")
	)
	(arc
		(start 85.948012 -262.25881)
		(mid 86.230968 -262.182633)
		(end 86.513924 -262.25881)
		(width 0.0889)
		(layer "In4.Cu")
		(net "M_D_CPU1_SB_CA<0>")
	)
	(arc
		(start 83.702398 -262.263636)
		(mid 83.885906 -262.30913)
		(end 84.068158 -262.25881)
		(width 0.0889)
		(layer "In4.Cu")
		(net "M_D_CPU1_SB_CA<0>")
	)
	(arc
		(start 90.273886 -262.25881)
		(mid 90.456137 -262.30916)
		(end 90.639646 -262.263636)
		(width 0.0889)
		(layer "In4.Cu")
		(net "M_D_CPU1_SB_CA<0>")
	)
	(arc
		(start 87.46236 -262.263636)
		(mid 87.645868 -262.30913)
		(end 87.82812 -262.25881)
		(width 0.0889)
		(layer "In4.Cu")
		(net "M_D_CPU1_SB_CA<0>")
	)
	(arc
		(start 91.21394 -262.25881)
		(mid 91.396191 -262.30916)
		(end 91.5797 -262.263636)
		(width 0.0889)
		(layer "In4.Cu")
		(net "M_D_CPU1_SB_CA<0>")
	)
	(arc
		(start 81.247996 -262.25881)
		(mid 81.530952 -262.182633)
		(end 81.813908 -262.25881)
		(width 0.0889)
		(layer "In4.Cu")
		(net "M_D_CPU1_SB_CA<0>")
	)
	(arc
		(start 82.762344 -262.263636)
		(mid 82.945852 -262.30913)
		(end 83.128104 -262.25881)
		(width 0.0889)
		(layer "In4.Cu")
		(net "M_D_CPU1_SB_CA<0>")
	)
	(arc
		(start 80.308196 -262.25881)
		(mid 80.591152 -262.182633)
		(end 80.874108 -262.25881)
		(width 0.0889)
		(layer "In4.Cu")
		(net "M_D_CPU1_SB_CA<0>")
	)
	(arc
		(start 89.707974 -262.25881)
		(mid 89.99093 -262.182633)
		(end 90.273886 -262.25881)
		(width 0.0889)
		(layer "In4.Cu")
		(net "M_D_CPU1_SB_CA<0>")
	)
	(arc
		(start 84.63407 -262.25881)
		(mid 84.821014 -262.309065)
		(end 85.007958 -262.25881)
		(width 0.0889)
		(layer "In4.Cu")
		(net "M_D_CPU1_SB_CA<0>")
	)
	(arc
		(start 91.588082 -262.25881)
		(mid 91.871038 -262.182633)
		(end 92.153994 -262.25881)
		(width 0.0889)
		(layer "In4.Cu")
		(net "M_D_CPU1_SB_CA<0>")
	)
	(arc
		(start 83.128104 -262.25881)
		(mid 83.41106 -262.182633)
		(end 83.694016 -262.25881)
		(width 0.0889)
		(layer "In4.Cu")
		(net "M_D_CPU1_SB_CA<0>")
	)
	(arc
		(start 80.874108 -262.25881)
		(mid 81.061052 -262.309065)
		(end 81.247996 -262.25881)
		(width 0.0889)
		(layer "In4.Cu")
		(net "M_D_CPU1_SB_CA<0>")
	)
	(arc
		(start 79.933546 -262.25881)
		(mid 80.116051 -262.309287)
		(end 80.299814 -262.263636)
		(width 0.0889)
		(layer "In4.Cu")
		(net "M_D_CPU1_SB_CA<0>")
	)
	(arc
		(start 90.648028 -262.25881)
		(mid 90.930984 -262.182633)
		(end 91.21394 -262.25881)
		(width 0.0889)
		(layer "In4.Cu")
		(net "M_D_CPU1_SB_CA<0>")
	)
	(segment
		(start 92.80779 -266.530328)
		(end 92.340938 -266.796266)
		(width 0.10668)
		(layer "F.Cu")
		(net "M_D_CPU1_SA_RSP<0>")
	)
	(segment
		(start 57.569862 -269.160244)
		(end 57.854342 -268.875764)
		(width 0.11684)
		(layer "In4.Cu")
		(net "M_D_CPU1_SA_RSP<0>")
	)
	(segment
		(start 45.873924 -268.875764)
		(end 46.117764 -268.875764)
		(width 0.11684)
		(layer "In4.Cu")
		(net "M_D_CPU1_SA_RSP<0>")
	)
	(segment
		(start 84.62645 -267.107162)
		(end 84.637118 -267.113258)
		(width 0.0889)
		(layer "In4.Cu")
		(net "M_D_CPU1_SA_RSP<0>")
	)
	(segment
		(start 92.489782 -267.052552)
		(end 92.340938 -266.796266)
		(width 0.0889)
		(layer "In4.Cu")
		(net "M_D_CPU1_SA_RSP<0>")
	)
	(segment
		(start 52.814982 -268.875764)
		(end 53.099462 -269.160244)
		(width 0.11684)
		(layer "In4.Cu")
		(net "M_D_CPU1_SA_RSP<0>")
	)
	(segment
		(start 42.283634 -268.875764)
		(end 42.568114 -269.160244)
		(width 0.11684)
		(layer "In4.Cu")
		(net "M_D_CPU1_SA_RSP<0>")
	)
	(segment
		(start 41.226994 -268.875764)
		(end 41.511474 -269.160244)
		(width 0.11684)
		(layer "In4.Cu")
		(net "M_D_CPU1_SA_RSP<0>")
	)
	(segment
		(start 88.386412 -267.107162)
		(end 88.39708 -267.113258)
		(width 0.0889)
		(layer "In4.Cu")
		(net "M_D_CPU1_SA_RSP<0>")
	)
	(segment
		(start 55.984902 -268.875764)
		(end 56.269382 -269.160244)
		(width 0.11684)
		(layer "In4.Cu")
		(net "M_D_CPU1_SA_RSP<0>")
	)
	(segment
		(start 54.684422 -268.875764)
		(end 54.928262 -268.875764)
		(width 0.11684)
		(layer "In4.Cu")
		(net "M_D_CPU1_SA_RSP<0>")
	)
	(segment
		(start 45.061124 -268.875764)
		(end 45.345604 -269.160244)
		(width 0.11684)
		(layer "In4.Cu")
		(net "M_D_CPU1_SA_RSP<0>")
	)
	(segment
		(start 81.244948 -267.113258)
		(end 81.255616 -267.107162)
		(width 0.0889)
		(layer "In4.Cu")
		(net "M_D_CPU1_SA_RSP<0>")
	)
	(segment
		(start 85.944964 -267.113258)
		(end 85.955632 -267.107162)
		(width 0.0889)
		(layer "In4.Cu")
		(net "M_D_CPU1_SA_RSP<0>")
	)
	(segment
		(start 78.259686 -267.035788)
		(end 79.650336 -267.035788)
		(width 0.0889)
		(layer "In4.Cu")
		(net "M_D_CPU1_SA_RSP<0>")
	)
	(segment
		(start 50.337212 -269.160244)
		(end 50.621692 -268.875764)
		(width 0.11684)
		(layer "In4.Cu")
		(net "M_D_CPU1_SA_RSP<0>")
	)
	(segment
		(start 54.156102 -269.160244)
		(end 54.399942 -269.160244)
		(width 0.11684)
		(layer "In4.Cu")
		(net "M_D_CPU1_SA_RSP<0>")
	)
	(segment
		(start 44.532804 -269.160244)
		(end 44.817284 -268.875764)
		(width 0.11684)
		(layer "In4.Cu")
		(net "M_D_CPU1_SA_RSP<0>")
	)
	(segment
		(start 42.811954 -269.160244)
		(end 43.096434 -268.875764)
		(width 0.11684)
		(layer "In4.Cu")
		(net "M_D_CPU1_SA_RSP<0>")
	)
	(segment
		(start 76.95057 -266.915646)
		(end 78.139544 -266.915646)
		(width 0.0889)
		(layer "In4.Cu")
		(net "M_D_CPU1_SA_RSP<0>")
	)
	(segment
		(start 43.096434 -268.875764)
		(end 43.340274 -268.875764)
		(width 0.11684)
		(layer "In4.Cu")
		(net "M_D_CPU1_SA_RSP<0>")
	)
	(segment
		(start 92.466414 -267.140436)
		(end 92.489782 -267.052552)
		(width 0.0889)
		(layer "In4.Cu")
		(net "M_D_CPU1_SA_RSP<0>")
	)
	(segment
		(start 46.646084 -269.160244)
		(end 46.930564 -268.875764)
		(width 0.11684)
		(layer "In4.Cu")
		(net "M_D_CPU1_SA_RSP<0>")
	)
	(segment
		(start 42.568114 -269.160244)
		(end 42.811954 -269.160244)
		(width 0.11684)
		(layer "In4.Cu")
		(net "M_D_CPU1_SA_RSP<0>")
	)
	(segment
		(start 53.871622 -268.875764)
		(end 54.156102 -269.160244)
		(width 0.11684)
		(layer "In4.Cu")
		(net "M_D_CPU1_SA_RSP<0>")
	)
	(segment
		(start 42.039794 -268.875764)
		(end 42.283634 -268.875764)
		(width 0.11684)
		(layer "In4.Cu")
		(net "M_D_CPU1_SA_RSP<0>")
	)
	(segment
		(start 47.458884 -269.160244)
		(end 48.223932 -269.160244)
		(width 0.11684)
		(layer "In4.Cu")
		(net "M_D_CPU1_SA_RSP<0>")
	)
	(segment
		(start 48.223932 -269.160244)
		(end 48.508412 -268.875764)
		(width 0.11684)
		(layer "In4.Cu")
		(net "M_D_CPU1_SA_RSP<0>")
	)
	(segment
		(start 50.865532 -268.875764)
		(end 51.150012 -269.160244)
		(width 0.11684)
		(layer "In4.Cu")
		(net "M_D_CPU1_SA_RSP<0>")
	)
	(segment
		(start 41.511474 -269.160244)
		(end 41.755314 -269.160244)
		(width 0.11684)
		(layer "In4.Cu")
		(net "M_D_CPU1_SA_RSP<0>")
	)
	(segment
		(start 53.343302 -269.160244)
		(end 53.627782 -268.875764)
		(width 0.11684)
		(layer "In4.Cu")
		(net "M_D_CPU1_SA_RSP<0>")
	)
	(segment
		(start 46.930564 -268.875764)
		(end 47.174404 -268.875764)
		(width 0.11684)
		(layer "In4.Cu")
		(net "M_D_CPU1_SA_RSP<0>")
	)
	(segment
		(start 60.543186 -268.875764)
		(end 62.994286 -266.424664)
		(width 0.11684)
		(layer "In4.Cu")
		(net "M_D_CPU1_SA_RSP<0>")
	)
	(segment
		(start 53.099462 -269.160244)
		(end 53.343302 -269.160244)
		(width 0.11684)
		(layer "In4.Cu")
		(net "M_D_CPU1_SA_RSP<0>")
	)
	(segment
		(start 89.326466 -267.107162)
		(end 89.337134 -267.113258)
		(width 0.0889)
		(layer "In4.Cu")
		(net "M_D_CPU1_SA_RSP<0>")
	)
	(segment
		(start 38.04793 -268.875764)
		(end 38.29177 -268.875764)
		(width 0.11684)
		(layer "In4.Cu")
		(net "M_D_CPU1_SA_RSP<0>")
	)
	(segment
		(start 55.456582 -269.160244)
		(end 55.741062 -268.875764)
		(width 0.11684)
		(layer "In4.Cu")
		(net "M_D_CPU1_SA_RSP<0>")
	)
	(segment
		(start 80.866488 -267.107162)
		(end 80.877156 -267.113258)
		(width 0.0889)
		(layer "In4.Cu")
		(net "M_D_CPU1_SA_RSP<0>")
	)
	(segment
		(start 38.57625 -269.160244)
		(end 38.82009 -269.160244)
		(width 0.11684)
		(layer "In4.Cu")
		(net "M_D_CPU1_SA_RSP<0>")
	)
	(segment
		(start 39.34841 -268.875764)
		(end 39.63289 -269.160244)
		(width 0.11684)
		(layer "In4.Cu")
		(net "M_D_CPU1_SA_RSP<0>")
	)
	(segment
		(start 51.150012 -269.160244)
		(end 52.286662 -269.160244)
		(width 0.11684)
		(layer "In4.Cu")
		(net "M_D_CPU1_SA_RSP<0>")
	)
	(segment
		(start 37.22116 -269.160244)
		(end 37.76345 -269.160244)
		(width 0.11684)
		(layer "In4.Cu")
		(net "M_D_CPU1_SA_RSP<0>")
	)
	(segment
		(start 48.752252 -268.875764)
		(end 49.036732 -269.160244)
		(width 0.11684)
		(layer "In4.Cu")
		(net "M_D_CPU1_SA_RSP<0>")
	)
	(segment
		(start 54.928262 -268.875764)
		(end 55.212742 -269.160244)
		(width 0.11684)
		(layer "In4.Cu")
		(net "M_D_CPU1_SA_RSP<0>")
	)
	(segment
		(start 49.565052 -268.875764)
		(end 49.808892 -268.875764)
		(width 0.11684)
		(layer "In4.Cu")
		(net "M_D_CPU1_SA_RSP<0>")
	)
	(segment
		(start 39.63289 -269.160244)
		(end 40.698674 -269.160244)
		(width 0.11684)
		(layer "In4.Cu")
		(net "M_D_CPU1_SA_RSP<0>")
	)
	(segment
		(start 57.854342 -268.875764)
		(end 58.098182 -268.875764)
		(width 0.11684)
		(layer "In4.Cu")
		(net "M_D_CPU1_SA_RSP<0>")
	)
	(segment
		(start 46.402244 -269.160244)
		(end 46.646084 -269.160244)
		(width 0.11684)
		(layer "In4.Cu")
		(net "M_D_CPU1_SA_RSP<0>")
	)
	(segment
		(start 49.036732 -269.160244)
		(end 49.280572 -269.160244)
		(width 0.11684)
		(layer "In4.Cu")
		(net "M_D_CPU1_SA_RSP<0>")
	)
	(segment
		(start 56.797702 -268.875764)
		(end 57.041542 -268.875764)
		(width 0.11684)
		(layer "In4.Cu")
		(net "M_D_CPU1_SA_RSP<0>")
	)
	(segment
		(start 58.098182 -268.875764)
		(end 58.382662 -269.160244)
		(width 0.11684)
		(layer "In4.Cu")
		(net "M_D_CPU1_SA_RSP<0>")
	)
	(segment
		(start 36.795964 -269.58544)
		(end 37.22116 -269.160244)
		(width 0.11684)
		(layer "In4.Cu")
		(net "M_D_CPU1_SA_RSP<0>")
	)
	(segment
		(start 49.280572 -269.160244)
		(end 49.565052 -268.875764)
		(width 0.11684)
		(layer "In4.Cu")
		(net "M_D_CPU1_SA_RSP<0>")
	)
	(segment
		(start 41.755314 -269.160244)
		(end 42.039794 -268.875764)
		(width 0.11684)
		(layer "In4.Cu")
		(net "M_D_CPU1_SA_RSP<0>")
	)
	(segment
		(start 50.621692 -268.875764)
		(end 50.865532 -268.875764)
		(width 0.11684)
		(layer "In4.Cu")
		(net "M_D_CPU1_SA_RSP<0>")
	)
	(segment
		(start 58.382662 -269.160244)
		(end 59.833256 -269.160244)
		(width 0.11684)
		(layer "In4.Cu")
		(net "M_D_CPU1_SA_RSP<0>")
	)
	(segment
		(start 62.994286 -266.424664)
		(end 76.049886 -266.424664)
		(width 0.11684)
		(layer "In4.Cu")
		(net "M_D_CPU1_SA_RSP<0>")
	)
	(segment
		(start 40.698674 -269.160244)
		(end 40.983154 -268.875764)
		(width 0.11684)
		(layer "In4.Cu")
		(net "M_D_CPU1_SA_RSP<0>")
	)
	(segment
		(start 90.64498 -267.113258)
		(end 90.655648 -267.107162)
		(width 0.0889)
		(layer "In4.Cu")
		(net "M_D_CPU1_SA_RSP<0>")
	)
	(segment
		(start 59.833256 -269.160244)
		(end 60.117736 -268.875764)
		(width 0.11684)
		(layer "In4.Cu")
		(net "M_D_CPU1_SA_RSP<0>")
	)
	(segment
		(start 56.513222 -269.160244)
		(end 56.797702 -268.875764)
		(width 0.11684)
		(layer "In4.Cu")
		(net "M_D_CPU1_SA_RSP<0>")
	)
	(segment
		(start 55.741062 -268.875764)
		(end 55.984902 -268.875764)
		(width 0.11684)
		(layer "In4.Cu")
		(net "M_D_CPU1_SA_RSP<0>")
	)
	(segment
		(start 55.212742 -269.160244)
		(end 55.456582 -269.160244)
		(width 0.11684)
		(layer "In4.Cu")
		(net "M_D_CPU1_SA_RSP<0>")
	)
	(segment
		(start 89.704926 -267.113258)
		(end 89.715594 -267.107162)
		(width 0.0889)
		(layer "In4.Cu")
		(net "M_D_CPU1_SA_RSP<0>")
	)
	(segment
		(start 85.00491 -267.113258)
		(end 85.015578 -267.107162)
		(width 0.0889)
		(layer "In4.Cu")
		(net "M_D_CPU1_SA_RSP<0>")
	)
	(segment
		(start 80.296766 -267.118084)
		(end 80.304894 -267.113258)
		(width 0.0889)
		(layer "In4.Cu")
		(net "M_D_CPU1_SA_RSP<0>")
	)
	(segment
		(start 83.686396 -267.107162)
		(end 83.697064 -267.113258)
		(width 0.0889)
		(layer "In4.Cu")
		(net "M_D_CPU1_SA_RSP<0>")
	)
	(segment
		(start 52.571142 -268.875764)
		(end 52.814982 -268.875764)
		(width 0.11684)
		(layer "In4.Cu")
		(net "M_D_CPU1_SA_RSP<0>")
	)
	(segment
		(start 76.049886 -266.424664)
		(end 76.459588 -266.424664)
		(width 0.0889)
		(layer "In4.Cu")
		(net "M_D_CPU1_SA_RSP<0>")
	)
	(segment
		(start 47.174404 -268.875764)
		(end 47.458884 -269.160244)
		(width 0.11684)
		(layer "In4.Cu")
		(net "M_D_CPU1_SA_RSP<0>")
	)
	(segment
		(start 46.117764 -268.875764)
		(end 46.402244 -269.160244)
		(width 0.11684)
		(layer "In4.Cu")
		(net "M_D_CPU1_SA_RSP<0>")
	)
	(segment
		(start 39.10457 -268.875764)
		(end 39.34841 -268.875764)
		(width 0.11684)
		(layer "In4.Cu")
		(net "M_D_CPU1_SA_RSP<0>")
	)
	(segment
		(start 48.508412 -268.875764)
		(end 48.752252 -268.875764)
		(width 0.11684)
		(layer "In4.Cu")
		(net "M_D_CPU1_SA_RSP<0>")
	)
	(segment
		(start 76.459588 -266.424664)
		(end 76.95057 -266.915646)
		(width 0.0889)
		(layer "In4.Cu")
		(net "M_D_CPU1_SA_RSP<0>")
	)
	(segment
		(start 57.041542 -268.875764)
		(end 57.326022 -269.160244)
		(width 0.11684)
		(layer "In4.Cu")
		(net "M_D_CPU1_SA_RSP<0>")
	)
	(segment
		(start 37.76345 -269.160244)
		(end 38.04793 -268.875764)
		(width 0.11684)
		(layer "In4.Cu")
		(net "M_D_CPU1_SA_RSP<0>")
	)
	(segment
		(start 49.808892 -268.875764)
		(end 50.093372 -269.160244)
		(width 0.11684)
		(layer "In4.Cu")
		(net "M_D_CPU1_SA_RSP<0>")
	)
	(segment
		(start 50.093372 -269.160244)
		(end 50.337212 -269.160244)
		(width 0.11684)
		(layer "In4.Cu")
		(net "M_D_CPU1_SA_RSP<0>")
	)
	(segment
		(start 43.340274 -268.875764)
		(end 43.624754 -269.160244)
		(width 0.11684)
		(layer "In4.Cu")
		(net "M_D_CPU1_SA_RSP<0>")
	)
	(segment
		(start 45.345604 -269.160244)
		(end 45.589444 -269.160244)
		(width 0.11684)
		(layer "In4.Cu")
		(net "M_D_CPU1_SA_RSP<0>")
	)
	(segment
		(start 57.326022 -269.160244)
		(end 57.569862 -269.160244)
		(width 0.11684)
		(layer "In4.Cu")
		(net "M_D_CPU1_SA_RSP<0>")
	)
	(segment
		(start 52.286662 -269.160244)
		(end 52.571142 -268.875764)
		(width 0.11684)
		(layer "In4.Cu")
		(net "M_D_CPU1_SA_RSP<0>")
	)
	(segment
		(start 43.624754 -269.160244)
		(end 44.532804 -269.160244)
		(width 0.11684)
		(layer "In4.Cu")
		(net "M_D_CPU1_SA_RSP<0>")
	)
	(segment
		(start 40.983154 -268.875764)
		(end 41.226994 -268.875764)
		(width 0.11684)
		(layer "In4.Cu")
		(net "M_D_CPU1_SA_RSP<0>")
	)
	(segment
		(start 56.269382 -269.160244)
		(end 56.513222 -269.160244)
		(width 0.11684)
		(layer "In4.Cu")
		(net "M_D_CPU1_SA_RSP<0>")
	)
	(segment
		(start 53.627782 -268.875764)
		(end 53.871622 -268.875764)
		(width 0.11684)
		(layer "In4.Cu")
		(net "M_D_CPU1_SA_RSP<0>")
	)
	(segment
		(start 60.117736 -268.875764)
		(end 60.543186 -268.875764)
		(width 0.11684)
		(layer "In4.Cu")
		(net "M_D_CPU1_SA_RSP<0>")
	)
	(segment
		(start 44.817284 -268.875764)
		(end 45.061124 -268.875764)
		(width 0.11684)
		(layer "In4.Cu")
		(net "M_D_CPU1_SA_RSP<0>")
	)
	(segment
		(start 78.139544 -266.915646)
		(end 78.259686 -267.035788)
		(width 0.0889)
		(layer "In4.Cu")
		(net "M_D_CPU1_SA_RSP<0>")
	)
	(segment
		(start 38.82009 -269.160244)
		(end 39.10457 -268.875764)
		(width 0.11684)
		(layer "In4.Cu")
		(net "M_D_CPU1_SA_RSP<0>")
	)
	(segment
		(start 38.29177 -268.875764)
		(end 38.57625 -269.160244)
		(width 0.11684)
		(layer "In4.Cu")
		(net "M_D_CPU1_SA_RSP<0>")
	)
	(segment
		(start 45.589444 -269.160244)
		(end 45.873924 -268.875764)
		(width 0.11684)
		(layer "In4.Cu")
		(net "M_D_CPU1_SA_RSP<0>")
	)
	(segment
		(start 54.399942 -269.160244)
		(end 54.684422 -268.875764)
		(width 0.11684)
		(layer "In4.Cu")
		(net "M_D_CPU1_SA_RSP<0>")
	)
	(arc
		(start 81.81721 -267.113258)
		(mid 82.001106 -267.162738)
		(end 82.185002 -267.113258)
		(width 0.0889)
		(layer "In4.Cu")
		(net "M_D_CPU1_SA_RSP<0>")
	)
	(arc
		(start 91.585034 -267.113258)
		(mid 91.871038 -267.036306)
		(end 92.157042 -267.113258)
		(width 0.0889)
		(layer "In4.Cu")
		(net "M_D_CPU1_SA_RSP<0>")
	)
	(arc
		(start 81.255616 -267.107162)
		(mid 81.537205 -267.036288)
		(end 81.81721 -267.113258)
		(width 0.0889)
		(layer "In4.Cu")
		(net "M_D_CPU1_SA_RSP<0>")
	)
	(arc
		(start 86.885018 -267.113258)
		(mid 87.171022 -267.036306)
		(end 87.457026 -267.113258)
		(width 0.0889)
		(layer "In4.Cu")
		(net "M_D_CPU1_SA_RSP<0>")
	)
	(arc
		(start 85.955632 -267.107162)
		(mid 86.237221 -267.036288)
		(end 86.517226 -267.113258)
		(width 0.0889)
		(layer "In4.Cu")
		(net "M_D_CPU1_SA_RSP<0>")
	)
	(arc
		(start 79.657194 -267.035788)
		(mid 79.80204 -267.056419)
		(end 79.936848 -267.113258)
		(width 0.0889)
		(layer "In4.Cu")
		(net "M_D_CPU1_SA_RSP<0>")
	)
	(arc
		(start 84.064856 -267.113258)
		(mid 84.34486 -267.036213)
		(end 84.62645 -267.107162)
		(width 0.0889)
		(layer "In4.Cu")
		(net "M_D_CPU1_SA_RSP<0>")
	)
	(arc
		(start 89.337134 -267.113258)
		(mid 89.52103 -267.162738)
		(end 89.704926 -267.113258)
		(width 0.0889)
		(layer "In4.Cu")
		(net "M_D_CPU1_SA_RSP<0>")
	)
	(arc
		(start 85.015578 -267.107162)
		(mid 85.297167 -267.036288)
		(end 85.577172 -267.113258)
		(width 0.0889)
		(layer "In4.Cu")
		(net "M_D_CPU1_SA_RSP<0>")
	)
	(arc
		(start 86.517226 -267.113258)
		(mid 86.701122 -267.162738)
		(end 86.885018 -267.113258)
		(width 0.0889)
		(layer "In4.Cu")
		(net "M_D_CPU1_SA_RSP<0>")
	)
	(arc
		(start 91.217242 -267.113258)
		(mid 91.401138 -267.162738)
		(end 91.585034 -267.113258)
		(width 0.0889)
		(layer "In4.Cu")
		(net "M_D_CPU1_SA_RSP<0>")
	)
	(arc
		(start 90.655648 -267.107162)
		(mid 90.937237 -267.036288)
		(end 91.217242 -267.113258)
		(width 0.0889)
		(layer "In4.Cu")
		(net "M_D_CPU1_SA_RSP<0>")
	)
	(arc
		(start 90.277188 -267.113258)
		(mid 90.461084 -267.162738)
		(end 90.64498 -267.113258)
		(width 0.0889)
		(layer "In4.Cu")
		(net "M_D_CPU1_SA_RSP<0>")
	)
	(arc
		(start 79.936848 -267.113258)
		(mid 80.116163 -267.162834)
		(end 80.296766 -267.118084)
		(width 0.0889)
		(layer "In4.Cu")
		(net "M_D_CPU1_SA_RSP<0>")
	)
	(arc
		(start 85.577172 -267.113258)
		(mid 85.761068 -267.162738)
		(end 85.944964 -267.113258)
		(width 0.0889)
		(layer "In4.Cu")
		(net "M_D_CPU1_SA_RSP<0>")
	)
	(arc
		(start 89.715594 -267.107162)
		(mid 89.997183 -267.036288)
		(end 90.277188 -267.113258)
		(width 0.0889)
		(layer "In4.Cu")
		(net "M_D_CPU1_SA_RSP<0>")
	)
	(arc
		(start 88.764872 -267.113258)
		(mid 89.044876 -267.036213)
		(end 89.326466 -267.107162)
		(width 0.0889)
		(layer "In4.Cu")
		(net "M_D_CPU1_SA_RSP<0>")
	)
	(arc
		(start 88.39708 -267.113258)
		(mid 88.580976 -267.162738)
		(end 88.764872 -267.113258)
		(width 0.0889)
		(layer "In4.Cu")
		(net "M_D_CPU1_SA_RSP<0>")
	)
	(arc
		(start 83.124802 -267.113258)
		(mid 83.404806 -267.036213)
		(end 83.686396 -267.107162)
		(width 0.0889)
		(layer "In4.Cu")
		(net "M_D_CPU1_SA_RSP<0>")
	)
	(arc
		(start 87.457026 -267.113258)
		(mid 87.640922 -267.162738)
		(end 87.824818 -267.113258)
		(width 0.0889)
		(layer "In4.Cu")
		(net "M_D_CPU1_SA_RSP<0>")
	)
	(arc
		(start 92.157042 -267.113258)
		(mid 92.308701 -267.161212)
		(end 92.466414 -267.140436)
		(width 0.0889)
		(layer "In4.Cu")
		(net "M_D_CPU1_SA_RSP<0>")
	)
	(arc
		(start 83.697064 -267.113258)
		(mid 83.88096 -267.162738)
		(end 84.064856 -267.113258)
		(width 0.0889)
		(layer "In4.Cu")
		(net "M_D_CPU1_SA_RSP<0>")
	)
	(arc
		(start 79.650336 -267.035788)
		(mid 79.653765 -267.035778)
		(end 79.657194 -267.035788)
		(width 0.0889)
		(layer "In4.Cu")
		(net "M_D_CPU1_SA_RSP<0>")
	)
	(arc
		(start 82.75701 -267.113258)
		(mid 82.940906 -267.162738)
		(end 83.124802 -267.113258)
		(width 0.0889)
		(layer "In4.Cu")
		(net "M_D_CPU1_SA_RSP<0>")
	)
	(arc
		(start 87.824818 -267.113258)
		(mid 88.104822 -267.036213)
		(end 88.386412 -267.107162)
		(width 0.0889)
		(layer "In4.Cu")
		(net "M_D_CPU1_SA_RSP<0>")
	)
	(arc
		(start 82.185002 -267.113258)
		(mid 82.471006 -267.036306)
		(end 82.75701 -267.113258)
		(width 0.0889)
		(layer "In4.Cu")
		(net "M_D_CPU1_SA_RSP<0>")
	)
	(arc
		(start 80.304894 -267.113258)
		(mid 80.584898 -267.036213)
		(end 80.866488 -267.107162)
		(width 0.0889)
		(layer "In4.Cu")
		(net "M_D_CPU1_SA_RSP<0>")
	)
	(arc
		(start 84.637118 -267.113258)
		(mid 84.821014 -267.162738)
		(end 85.00491 -267.113258)
		(width 0.0889)
		(layer "In4.Cu")
		(net "M_D_CPU1_SA_RSP<0>")
	)
	(arc
		(start 80.877156 -267.113258)
		(mid 81.061052 -267.162738)
		(end 81.244948 -267.113258)
		(width 0.0889)
		(layer "In4.Cu")
		(net "M_D_CPU1_SA_RSP<0>")
	)
	(segment
		(start 92.507816 -256.09042)
		(end 92.040964 -255.824482)
		(width 0.10668)
		(layer "F.Cu")
		(net "M_D_CPU1_SA_PAR")
	)
	(segment
		(start 42.44594 -255.368552)
		(end 42.609008 -255.205484)
		(width 0.14478)
		(layer "In4.Cu")
		(net "M_D_CPU1_SA_PAR")
	)
	(segment
		(start 38.254686 -255.743964)
		(end 41.169844 -255.743964)
		(width 0.14478)
		(layer "In4.Cu")
		(net "M_D_CPU1_SA_PAR")
	)
	(segment
		(start 90.913966 -255.501902)
		(end 90.922348 -255.497076)
		(width 0.0889)
		(layer "In4.Cu")
		(net "M_D_CPU1_SA_PAR")
	)
	(segment
		(start 36.795964 -254.285242)
		(end 38.254686 -255.743964)
		(width 0.14478)
		(layer "In4.Cu")
		(net "M_D_CPU1_SA_PAR")
	)
	(segment
		(start 92.195142 -255.559052)
		(end 92.040964 -255.824482)
		(width 0.0889)
		(layer "In4.Cu")
		(net "M_D_CPU1_SA_PAR")
	)
	(segment
		(start 76.560426 -256.610104)
		(end 76.819252 -256.610104)
		(width 0.0889)
		(layer "In4.Cu")
		(net "M_D_CPU1_SA_PAR")
	)
	(segment
		(start 73.027286 -256.610104)
		(end 76.560426 -256.610104)
		(width 0.14478)
		(layer "In4.Cu")
		(net "M_D_CPU1_SA_PAR")
	)
	(segment
		(start 81.879694 -255.497076)
		(end 81.888076 -255.501902)
		(width 0.0889)
		(layer "In4.Cu")
		(net "M_D_CPU1_SA_PAR")
	)
	(segment
		(start 91.85402 -255.501902)
		(end 91.862402 -255.497076)
		(width 0.0889)
		(layer "In4.Cu")
		(net "M_D_CPU1_SA_PAR")
	)
	(segment
		(start 83.394042 -255.501902)
		(end 83.402424 -255.497076)
		(width 0.0889)
		(layer "In4.Cu")
		(net "M_D_CPU1_SA_PAR")
	)
	(segment
		(start 42.44594 -255.580896)
		(end 42.44594 -255.368552)
		(width 0.14478)
		(layer "In4.Cu")
		(net "M_D_CPU1_SA_PAR")
	)
	(segment
		(start 41.49598 -255.205484)
		(end 41.726358 -255.205484)
		(width 0.14478)
		(layer "In4.Cu")
		(net "M_D_CPU1_SA_PAR")
	)
	(segment
		(start 85.639656 -255.497076)
		(end 85.648038 -255.501902)
		(width 0.0889)
		(layer "In4.Cu")
		(net "M_D_CPU1_SA_PAR")
	)
	(segment
		(start 79.067406 -255.501902)
		(end 79.07782 -255.507998)
		(width 0.0889)
		(layer "In4.Cu")
		(net "M_D_CPU1_SA_PAR")
	)
	(segment
		(start 41.332912 -255.580896)
		(end 41.332912 -255.368552)
		(width 0.14478)
		(layer "In4.Cu")
		(net "M_D_CPU1_SA_PAR")
	)
	(segment
		(start 76.819252 -256.610104)
		(end 77.851254 -255.578102)
		(width 0.0889)
		(layer "In4.Cu")
		(net "M_D_CPU1_SA_PAR")
	)
	(segment
		(start 42.839386 -255.205484)
		(end 43.002454 -255.368552)
		(width 0.14478)
		(layer "In4.Cu")
		(net "M_D_CPU1_SA_PAR")
	)
	(segment
		(start 82.453988 -255.501902)
		(end 82.46237 -255.497076)
		(width 0.0889)
		(layer "In4.Cu")
		(net "M_D_CPU1_SA_PAR")
	)
	(segment
		(start 71.512176 -255.094994)
		(end 73.027286 -256.610104)
		(width 0.14478)
		(layer "In4.Cu")
		(net "M_D_CPU1_SA_PAR")
	)
	(segment
		(start 90.339672 -255.497076)
		(end 90.348054 -255.501902)
		(width 0.0889)
		(layer "In4.Cu")
		(net "M_D_CPU1_SA_PAR")
	)
	(segment
		(start 43.165522 -255.743964)
		(end 64.988186 -255.743964)
		(width 0.14478)
		(layer "In4.Cu")
		(net "M_D_CPU1_SA_PAR")
	)
	(segment
		(start 88.094058 -255.501902)
		(end 88.10244 -255.497076)
		(width 0.0889)
		(layer "In4.Cu")
		(net "M_D_CPU1_SA_PAR")
	)
	(segment
		(start 41.169844 -255.743964)
		(end 41.332912 -255.580896)
		(width 0.14478)
		(layer "In4.Cu")
		(net "M_D_CPU1_SA_PAR")
	)
	(segment
		(start 86.57971 -255.497076)
		(end 86.588092 -255.501902)
		(width 0.0889)
		(layer "In4.Cu")
		(net "M_D_CPU1_SA_PAR")
	)
	(segment
		(start 78.693518 -255.502156)
		(end 78.709774 -255.492758)
		(width 0.0889)
		(layer "In4.Cu")
		(net "M_D_CPU1_SA_PAR")
	)
	(segment
		(start 43.002454 -255.580896)
		(end 43.165522 -255.743964)
		(width 0.14478)
		(layer "In4.Cu")
		(net "M_D_CPU1_SA_PAR")
	)
	(segment
		(start 64.988186 -255.743964)
		(end 65.637156 -255.094994)
		(width 0.14478)
		(layer "In4.Cu")
		(net "M_D_CPU1_SA_PAR")
	)
	(segment
		(start 41.889426 -255.368552)
		(end 41.889426 -255.580896)
		(width 0.14478)
		(layer "In4.Cu")
		(net "M_D_CPU1_SA_PAR")
	)
	(segment
		(start 43.002454 -255.368552)
		(end 43.002454 -255.580896)
		(width 0.14478)
		(layer "In4.Cu")
		(net "M_D_CPU1_SA_PAR")
	)
	(segment
		(start 41.332912 -255.368552)
		(end 41.49598 -255.205484)
		(width 0.14478)
		(layer "In4.Cu")
		(net "M_D_CPU1_SA_PAR")
	)
	(segment
		(start 41.726358 -255.205484)
		(end 41.889426 -255.368552)
		(width 0.14478)
		(layer "In4.Cu")
		(net "M_D_CPU1_SA_PAR")
	)
	(segment
		(start 65.637156 -255.094994)
		(end 71.512176 -255.094994)
		(width 0.14478)
		(layer "In4.Cu")
		(net "M_D_CPU1_SA_PAR")
	)
	(segment
		(start 42.282872 -255.743964)
		(end 42.44594 -255.580896)
		(width 0.14478)
		(layer "In4.Cu")
		(net "M_D_CPU1_SA_PAR")
	)
	(segment
		(start 79.99984 -255.497076)
		(end 80.008222 -255.501902)
		(width 0.0889)
		(layer "In4.Cu")
		(net "M_D_CPU1_SA_PAR")
	)
	(segment
		(start 77.851254 -255.578102)
		(end 78.41107 -255.578102)
		(width 0.0889)
		(layer "In4.Cu")
		(net "M_D_CPU1_SA_PAR")
	)
	(segment
		(start 42.609008 -255.205484)
		(end 42.839386 -255.205484)
		(width 0.14478)
		(layer "In4.Cu")
		(net "M_D_CPU1_SA_PAR")
	)
	(segment
		(start 42.052494 -255.743964)
		(end 42.282872 -255.743964)
		(width 0.14478)
		(layer "In4.Cu")
		(net "M_D_CPU1_SA_PAR")
	)
	(segment
		(start 92.17279 -255.47574)
		(end 92.195142 -255.559052)
		(width 0.0889)
		(layer "In4.Cu")
		(net "M_D_CPU1_SA_PAR")
	)
	(segment
		(start 87.154004 -255.501902)
		(end 87.162386 -255.497076)
		(width 0.0889)
		(layer "In4.Cu")
		(net "M_D_CPU1_SA_PAR")
	)
	(segment
		(start 41.889426 -255.580896)
		(end 42.052494 -255.743964)
		(width 0.14478)
		(layer "In4.Cu")
		(net "M_D_CPU1_SA_PAR")
	)
	(arc
		(start 86.21395 -255.501902)
		(mid 86.396201 -255.451552)
		(end 86.57971 -255.497076)
		(width 0.0889)
		(layer "In4.Cu")
		(net "M_D_CPU1_SA_PAR")
	)
	(arc
		(start 85.273896 -255.501902)
		(mid 85.456147 -255.451552)
		(end 85.639656 -255.497076)
		(width 0.0889)
		(layer "In4.Cu")
		(net "M_D_CPU1_SA_PAR")
	)
	(arc
		(start 88.10244 -255.497076)
		(mid 88.285948 -255.451582)
		(end 88.4682 -255.501902)
		(width 0.0889)
		(layer "In4.Cu")
		(net "M_D_CPU1_SA_PAR")
	)
	(arc
		(start 89.408 -255.501902)
		(mid 89.690956 -255.578079)
		(end 89.973912 -255.501902)
		(width 0.0889)
		(layer "In4.Cu")
		(net "M_D_CPU1_SA_PAR")
	)
	(arc
		(start 80.948022 -255.501902)
		(mid 81.230978 -255.578079)
		(end 81.513934 -255.501902)
		(width 0.0889)
		(layer "In4.Cu")
		(net "M_D_CPU1_SA_PAR")
	)
	(arc
		(start 82.82813 -255.501902)
		(mid 83.111086 -255.578079)
		(end 83.394042 -255.501902)
		(width 0.0889)
		(layer "In4.Cu")
		(net "M_D_CPU1_SA_PAR")
	)
	(arc
		(start 81.513934 -255.501902)
		(mid 81.696185 -255.451552)
		(end 81.879694 -255.497076)
		(width 0.0889)
		(layer "In4.Cu")
		(net "M_D_CPU1_SA_PAR")
	)
	(arc
		(start 87.528146 -255.501902)
		(mid 87.811102 -255.578079)
		(end 88.094058 -255.501902)
		(width 0.0889)
		(layer "In4.Cu")
		(net "M_D_CPU1_SA_PAR")
	)
	(arc
		(start 90.922348 -255.497076)
		(mid 91.105856 -255.451582)
		(end 91.288108 -255.501902)
		(width 0.0889)
		(layer "In4.Cu")
		(net "M_D_CPU1_SA_PAR")
	)
	(arc
		(start 82.46237 -255.497076)
		(mid 82.645878 -255.451582)
		(end 82.82813 -255.501902)
		(width 0.0889)
		(layer "In4.Cu")
		(net "M_D_CPU1_SA_PAR")
	)
	(arc
		(start 79.07782 -255.507998)
		(mid 79.356506 -255.578218)
		(end 79.633572 -255.501902)
		(width 0.0889)
		(layer "In4.Cu")
		(net "M_D_CPU1_SA_PAR")
	)
	(arc
		(start 87.162386 -255.497076)
		(mid 87.345894 -255.451582)
		(end 87.528146 -255.501902)
		(width 0.0889)
		(layer "In4.Cu")
		(net "M_D_CPU1_SA_PAR")
	)
	(arc
		(start 89.034112 -255.501902)
		(mid 89.221056 -255.451647)
		(end 89.408 -255.501902)
		(width 0.0889)
		(layer "In4.Cu")
		(net "M_D_CPU1_SA_PAR")
	)
	(arc
		(start 83.402424 -255.497076)
		(mid 83.585932 -255.451582)
		(end 83.768184 -255.501902)
		(width 0.0889)
		(layer "In4.Cu")
		(net "M_D_CPU1_SA_PAR")
	)
	(arc
		(start 79.633572 -255.501902)
		(mid 79.816077 -255.451425)
		(end 79.99984 -255.497076)
		(width 0.0889)
		(layer "In4.Cu")
		(net "M_D_CPU1_SA_PAR")
	)
	(arc
		(start 90.348054 -255.501902)
		(mid 90.63101 -255.578079)
		(end 90.913966 -255.501902)
		(width 0.0889)
		(layer "In4.Cu")
		(net "M_D_CPU1_SA_PAR")
	)
	(arc
		(start 91.288108 -255.501902)
		(mid 91.571064 -255.578079)
		(end 91.85402 -255.501902)
		(width 0.0889)
		(layer "In4.Cu")
		(net "M_D_CPU1_SA_PAR")
	)
	(arc
		(start 86.588092 -255.501902)
		(mid 86.871048 -255.578079)
		(end 87.154004 -255.501902)
		(width 0.0889)
		(layer "In4.Cu")
		(net "M_D_CPU1_SA_PAR")
	)
	(arc
		(start 80.574134 -255.501902)
		(mid 80.761078 -255.451647)
		(end 80.948022 -255.501902)
		(width 0.0889)
		(layer "In4.Cu")
		(net "M_D_CPU1_SA_PAR")
	)
	(arc
		(start 81.888076 -255.501902)
		(mid 82.171032 -255.578079)
		(end 82.453988 -255.501902)
		(width 0.0889)
		(layer "In4.Cu")
		(net "M_D_CPU1_SA_PAR")
	)
	(arc
		(start 84.707984 -255.501902)
		(mid 84.99094 -255.578079)
		(end 85.273896 -255.501902)
		(width 0.0889)
		(layer "In4.Cu")
		(net "M_D_CPU1_SA_PAR")
	)
	(arc
		(start 84.334096 -255.501902)
		(mid 84.52104 -255.451647)
		(end 84.707984 -255.501902)
		(width 0.0889)
		(layer "In4.Cu")
		(net "M_D_CPU1_SA_PAR")
	)
	(arc
		(start 85.648038 -255.501902)
		(mid 85.930994 -255.578079)
		(end 86.21395 -255.501902)
		(width 0.0889)
		(layer "In4.Cu")
		(net "M_D_CPU1_SA_PAR")
	)
	(arc
		(start 91.862402 -255.497076)
		(mid 92.015272 -255.452435)
		(end 92.17279 -255.47574)
		(width 0.0889)
		(layer "In4.Cu")
		(net "M_D_CPU1_SA_PAR")
	)
	(arc
		(start 88.4682 -255.501902)
		(mid 88.751156 -255.578079)
		(end 89.034112 -255.501902)
		(width 0.0889)
		(layer "In4.Cu")
		(net "M_D_CPU1_SA_PAR")
	)
	(arc
		(start 78.41107 -255.578102)
		(mid 78.557318 -255.558797)
		(end 78.693518 -255.502156)
		(width 0.0889)
		(layer "In4.Cu")
		(net "M_D_CPU1_SA_PAR")
	)
	(arc
		(start 78.709774 -255.492758)
		(mid 78.889756 -255.451658)
		(end 79.067406 -255.501902)
		(width 0.0889)
		(layer "In4.Cu")
		(net "M_D_CPU1_SA_PAR")
	)
	(arc
		(start 83.768184 -255.501902)
		(mid 84.05114 -255.578079)
		(end 84.334096 -255.501902)
		(width 0.0889)
		(layer "In4.Cu")
		(net "M_D_CPU1_SA_PAR")
	)
	(arc
		(start 89.973912 -255.501902)
		(mid 90.156163 -255.451552)
		(end 90.339672 -255.497076)
		(width 0.0889)
		(layer "In4.Cu")
		(net "M_D_CPU1_SA_PAR")
	)
	(arc
		(start 80.008222 -255.501902)
		(mid 80.291178 -255.578079)
		(end 80.574134 -255.501902)
		(width 0.0889)
		(layer "In4.Cu")
		(net "M_D_CPU1_SA_PAR")
	)
	(segment
		(start 92.507816 -247.99036)
		(end 92.040964 -247.724422)
		(width 0.12954)
		(layer "F.Cu")
		(net "M_D_CPU1_SA_DQS_DP<9>")
	)
	(segment
		(start 86.581234 -247.394476)
		(end 86.589616 -247.399302)
		(width 0.09525)
		(layer "In4.Cu")
		(net "M_D_CPU1_SA_DQS_DP<9>")
	)
	(segment
		(start 85.64118 -247.394476)
		(end 85.649562 -247.399302)
		(width 0.09525)
		(layer "In4.Cu")
		(net "M_D_CPU1_SA_DQS_DP<9>")
	)
	(segment
		(start 77.552804 -247.582436)
		(end 77.7875 -247.34774)
		(width 0.09525)
		(layer "In4.Cu")
		(net "M_D_CPU1_SA_DQS_DP<9>")
	)
	(segment
		(start 48.644048 -240.560606)
		(end 48.979074 -240.22558)
		(width 0.16002)
		(layer "In4.Cu")
		(net "M_D_CPU1_SA_DQS_DP<9>")
	)
	(segment
		(start 78.671166 -247.411494)
		(end 78.691994 -247.399302)
		(width 0.09525)
		(layer "In4.Cu")
		(net "M_D_CPU1_SA_DQS_DP<9>")
	)
	(segment
		(start 75.087988 -247.164606)
		(end 75.259438 -247.336056)
		(width 0.16002)
		(layer "In4.Cu")
		(net "M_D_CPU1_SA_DQS_DP<9>")
	)
	(segment
		(start 90.341196 -247.394476)
		(end 90.349578 -247.399302)
		(width 0.09525)
		(layer "In4.Cu")
		(net "M_D_CPU1_SA_DQS_DP<9>")
	)
	(segment
		(start 32.969708 -239.561624)
		(end 35.002978 -239.561624)
		(width 0.16002)
		(layer "In4.Cu")
		(net "M_D_CPU1_SA_DQS_DP<9>")
	)
	(segment
		(start 36.553648 -239.844072)
		(end 37.033708 -239.844072)
		(width 0.16002)
		(layer "In4.Cu")
		(net "M_D_CPU1_SA_DQS_DP<9>")
	)
	(segment
		(start 42.796968 -239.341406)
		(end 43.111674 -239.341406)
		(width 0.16002)
		(layer "In4.Cu")
		(net "M_D_CPU1_SA_DQS_DP<9>")
	)
	(segment
		(start 32.695896 -239.835436)
		(end 32.969708 -239.561624)
		(width 0.16002)
		(layer "In4.Cu")
		(net "M_D_CPU1_SA_DQS_DP<9>")
	)
	(segment
		(start 54.281832 -240.529872)
		(end 56.218836 -240.529872)
		(width 0.16002)
		(layer "In4.Cu")
		(net "M_D_CPU1_SA_DQS_DP<9>")
	)
	(segment
		(start 43.480736 -239.710468)
		(end 45.441616 -239.710468)
		(width 0.16002)
		(layer "In4.Cu")
		(net "M_D_CPU1_SA_DQS_DP<9>")
	)
	(segment
		(start 41.435274 -240.22558)
		(end 41.912794 -240.22558)
		(width 0.16002)
		(layer "In4.Cu")
		(net "M_D_CPU1_SA_DQS_DP<9>")
	)
	(segment
		(start 39.180262 -240.560606)
		(end 41.100248 -240.560606)
		(width 0.16002)
		(layer "In4.Cu")
		(net "M_D_CPU1_SA_DQS_DP<9>")
	)
	(segment
		(start 64.771524 -247.164606)
		(end 75.087988 -247.164606)
		(width 0.16002)
		(layer "In4.Cu")
		(net "M_D_CPU1_SA_DQS_DP<9>")
	)
	(segment
		(start 47.494698 -240.560606)
		(end 48.644048 -240.560606)
		(width 0.16002)
		(layer "In4.Cu")
		(net "M_D_CPU1_SA_DQS_DP<9>")
	)
	(segment
		(start 90.912442 -247.399302)
		(end 90.920824 -247.394476)
		(width 0.09525)
		(layer "In4.Cu")
		(net "M_D_CPU1_SA_DQS_DP<9>")
	)
	(segment
		(start 81.881218 -247.394476)
		(end 81.8896 -247.399302)
		(width 0.09525)
		(layer "In4.Cu")
		(net "M_D_CPU1_SA_DQS_DP<9>")
	)
	(segment
		(start 51.024536 -239.710468)
		(end 53.462428 -239.710468)
		(width 0.16002)
		(layer "In4.Cu")
		(net "M_D_CPU1_SA_DQS_DP<9>")
	)
	(segment
		(start 82.452464 -247.399302)
		(end 82.460846 -247.394476)
		(width 0.09525)
		(layer "In4.Cu")
		(net "M_D_CPU1_SA_DQS_DP<9>")
	)
	(segment
		(start 75.955906 -247.336056)
		(end 75.979528 -247.336056)
		(width 0.09525)
		(layer "In4.Cu")
		(net "M_D_CPU1_SA_DQS_DP<9>")
	)
	(segment
		(start 35.610292 -239.380776)
		(end 35.956748 -239.727232)
		(width 0.16002)
		(layer "In4.Cu")
		(net "M_D_CPU1_SA_DQS_DP<9>")
	)
	(segment
		(start 77.7875 -247.34774)
		(end 77.940154 -247.34774)
		(width 0.09525)
		(layer "In4.Cu")
		(net "M_D_CPU1_SA_DQS_DP<9>")
	)
	(segment
		(start 75.979528 -247.336056)
		(end 76.03871 -247.276874)
		(width 0.09525)
		(layer "In4.Cu")
		(net "M_D_CPU1_SA_DQS_DP<9>")
	)
	(segment
		(start 37.150548 -239.727232)
		(end 38.346888 -239.727232)
		(width 0.16002)
		(layer "In4.Cu")
		(net "M_D_CPU1_SA_DQS_DP<9>")
	)
	(segment
		(start 41.100248 -240.560606)
		(end 41.435274 -240.22558)
		(width 0.16002)
		(layer "In4.Cu")
		(net "M_D_CPU1_SA_DQS_DP<9>")
	)
	(segment
		(start 43.111674 -239.341406)
		(end 43.480736 -239.710468)
		(width 0.16002)
		(layer "In4.Cu")
		(net "M_D_CPU1_SA_DQS_DP<9>")
	)
	(segment
		(start 75.259438 -247.336056)
		(end 75.955906 -247.336056)
		(width 0.16002)
		(layer "In4.Cu")
		(net "M_D_CPU1_SA_DQS_DP<9>")
	)
	(segment
		(start 59.867292 -242.260374)
		(end 64.771524 -247.164606)
		(width 0.16002)
		(layer "In4.Cu")
		(net "M_D_CPU1_SA_DQS_DP<9>")
	)
	(segment
		(start 48.979074 -240.22558)
		(end 49.456594 -240.22558)
		(width 0.16002)
		(layer "In4.Cu")
		(net "M_D_CPU1_SA_DQS_DP<9>")
	)
	(segment
		(start 38.346888 -239.727232)
		(end 39.180262 -240.560606)
		(width 0.16002)
		(layer "In4.Cu")
		(net "M_D_CPU1_SA_DQS_DP<9>")
	)
	(segment
		(start 78.691994 -247.399302)
		(end 78.703932 -247.392444)
		(width 0.09525)
		(layer "In4.Cu")
		(net "M_D_CPU1_SA_DQS_DP<9>")
	)
	(segment
		(start 45.441616 -239.710468)
		(end 47.494698 -240.560606)
		(width 0.16002)
		(layer "In4.Cu")
		(net "M_D_CPU1_SA_DQS_DP<9>")
	)
	(segment
		(start 37.033708 -239.844072)
		(end 37.150548 -239.727232)
		(width 0.16002)
		(layer "In4.Cu")
		(net "M_D_CPU1_SA_DQS_DP<9>")
	)
	(segment
		(start 53.462428 -239.710468)
		(end 54.281832 -240.529872)
		(width 0.16002)
		(layer "In4.Cu")
		(net "M_D_CPU1_SA_DQS_DP<9>")
	)
	(segment
		(start 88.092534 -247.399302)
		(end 88.100916 -247.394476)
		(width 0.09525)
		(layer "In4.Cu")
		(net "M_D_CPU1_SA_DQS_DP<9>")
	)
	(segment
		(start 76.197968 -247.276874)
		(end 76.50353 -247.582436)
		(width 0.09525)
		(layer "In4.Cu")
		(net "M_D_CPU1_SA_DQS_DP<9>")
	)
	(segment
		(start 35.956748 -239.727232)
		(end 36.436808 -239.727232)
		(width 0.16002)
		(layer "In4.Cu")
		(net "M_D_CPU1_SA_DQS_DP<9>")
	)
	(segment
		(start 56.523128 -240.22558)
		(end 57.027572 -240.22558)
		(width 0.16002)
		(layer "In4.Cu")
		(net "M_D_CPU1_SA_DQS_DP<9>")
	)
	(segment
		(start 36.436808 -239.727232)
		(end 36.553648 -239.844072)
		(width 0.16002)
		(layer "In4.Cu")
		(net "M_D_CPU1_SA_DQS_DP<9>")
	)
	(segment
		(start 79.06893 -247.399302)
		(end 79.079344 -247.405398)
		(width 0.09525)
		(layer "In4.Cu")
		(net "M_D_CPU1_SA_DQS_DP<9>")
	)
	(segment
		(start 92.17152 -247.372124)
		(end 92.194888 -247.458992)
		(width 0.09525)
		(layer "In4.Cu")
		(net "M_D_CPU1_SA_DQS_DP<9>")
	)
	(segment
		(start 50.655474 -239.341406)
		(end 51.024536 -239.710468)
		(width 0.16002)
		(layer "In4.Cu")
		(net "M_D_CPU1_SA_DQS_DP<9>")
	)
	(segment
		(start 50.340768 -239.341406)
		(end 50.655474 -239.341406)
		(width 0.16002)
		(layer "In4.Cu")
		(net "M_D_CPU1_SA_DQS_DP<9>")
	)
	(segment
		(start 76.03871 -247.276874)
		(end 76.197968 -247.276874)
		(width 0.09525)
		(layer "In4.Cu")
		(net "M_D_CPU1_SA_DQS_DP<9>")
	)
	(segment
		(start 49.456594 -240.22558)
		(end 50.340768 -239.341406)
		(width 0.16002)
		(layer "In4.Cu")
		(net "M_D_CPU1_SA_DQS_DP<9>")
	)
	(segment
		(start 41.912794 -240.22558)
		(end 42.796968 -239.341406)
		(width 0.16002)
		(layer "In4.Cu")
		(net "M_D_CPU1_SA_DQS_DP<9>")
	)
	(segment
		(start 92.194888 -247.458992)
		(end 92.040964 -247.724422)
		(width 0.09525)
		(layer "In4.Cu")
		(net "M_D_CPU1_SA_DQS_DP<9>")
	)
	(segment
		(start 57.027572 -240.22558)
		(end 59.062366 -242.260374)
		(width 0.16002)
		(layer "In4.Cu")
		(net "M_D_CPU1_SA_DQS_DP<9>")
	)
	(segment
		(start 56.218836 -240.529872)
		(end 56.523128 -240.22558)
		(width 0.16002)
		(layer "In4.Cu")
		(net "M_D_CPU1_SA_DQS_DP<9>")
	)
	(segment
		(start 35.002978 -239.561624)
		(end 35.183826 -239.380776)
		(width 0.16002)
		(layer "In4.Cu")
		(net "M_D_CPU1_SA_DQS_DP<9>")
	)
	(segment
		(start 87.15248 -247.399302)
		(end 87.160862 -247.394476)
		(width 0.09525)
		(layer "In4.Cu")
		(net "M_D_CPU1_SA_DQS_DP<9>")
	)
	(segment
		(start 80.001364 -247.394476)
		(end 80.009746 -247.399302)
		(width 0.09525)
		(layer "In4.Cu")
		(net "M_D_CPU1_SA_DQS_DP<9>")
	)
	(segment
		(start 83.392518 -247.399302)
		(end 83.4009 -247.394476)
		(width 0.09525)
		(layer "In4.Cu")
		(net "M_D_CPU1_SA_DQS_DP<9>")
	)
	(segment
		(start 91.852496 -247.399302)
		(end 91.860878 -247.394476)
		(width 0.09525)
		(layer "In4.Cu")
		(net "M_D_CPU1_SA_DQS_DP<9>")
	)
	(segment
		(start 59.062366 -242.260374)
		(end 59.867292 -242.260374)
		(width 0.16002)
		(layer "In4.Cu")
		(net "M_D_CPU1_SA_DQS_DP<9>")
	)
	(segment
		(start 35.183826 -239.380776)
		(end 35.610292 -239.380776)
		(width 0.16002)
		(layer "In4.Cu")
		(net "M_D_CPU1_SA_DQS_DP<9>")
	)
	(segment
		(start 76.50353 -247.582436)
		(end 77.552804 -247.582436)
		(width 0.09525)
		(layer "In4.Cu")
		(net "M_D_CPU1_SA_DQS_DP<9>")
	)
	(arc
		(start 81.8896 -247.399302)
		(mid 82.171032 -247.475057)
		(end 82.452464 -247.399302)
		(width 0.09525)
		(layer "In4.Cu")
		(net "M_D_CPU1_SA_DQS_DP<9>")
	)
	(arc
		(start 80.009746 -247.399302)
		(mid 80.291178 -247.475057)
		(end 80.57261 -247.399302)
		(width 0.09525)
		(layer "In4.Cu")
		(net "M_D_CPU1_SA_DQS_DP<9>")
	)
	(arc
		(start 87.52967 -247.399302)
		(mid 87.811102 -247.475057)
		(end 88.092534 -247.399302)
		(width 0.09525)
		(layer "In4.Cu")
		(net "M_D_CPU1_SA_DQS_DP<9>")
	)
	(arc
		(start 83.4009 -247.394476)
		(mid 83.585932 -247.348562)
		(end 83.769708 -247.399302)
		(width 0.09525)
		(layer "In4.Cu")
		(net "M_D_CPU1_SA_DQS_DP<9>")
	)
	(arc
		(start 77.940154 -247.34774)
		(mid 78.038051 -247.361026)
		(end 78.12913 -247.399302)
		(width 0.09525)
		(layer "In4.Cu")
		(net "M_D_CPU1_SA_DQS_DP<9>")
	)
	(arc
		(start 89.409524 -247.399302)
		(mid 89.690956 -247.475057)
		(end 89.972388 -247.399302)
		(width 0.09525)
		(layer "In4.Cu")
		(net "M_D_CPU1_SA_DQS_DP<9>")
	)
	(arc
		(start 86.212426 -247.399302)
		(mid 86.396201 -247.34853)
		(end 86.581234 -247.394476)
		(width 0.09525)
		(layer "In4.Cu")
		(net "M_D_CPU1_SA_DQS_DP<9>")
	)
	(arc
		(start 83.769708 -247.399302)
		(mid 84.05114 -247.475057)
		(end 84.332572 -247.399302)
		(width 0.09525)
		(layer "In4.Cu")
		(net "M_D_CPU1_SA_DQS_DP<9>")
	)
	(arc
		(start 88.100916 -247.394476)
		(mid 88.285948 -247.348562)
		(end 88.469724 -247.399302)
		(width 0.09525)
		(layer "In4.Cu")
		(net "M_D_CPU1_SA_DQS_DP<9>")
	)
	(arc
		(start 90.920824 -247.394476)
		(mid 91.105856 -247.348562)
		(end 91.289632 -247.399302)
		(width 0.09525)
		(layer "In4.Cu")
		(net "M_D_CPU1_SA_DQS_DP<9>")
	)
	(arc
		(start 84.709508 -247.399302)
		(mid 84.99094 -247.475057)
		(end 85.272372 -247.399302)
		(width 0.09525)
		(layer "In4.Cu")
		(net "M_D_CPU1_SA_DQS_DP<9>")
	)
	(arc
		(start 91.289632 -247.399302)
		(mid 91.571064 -247.475057)
		(end 91.852496 -247.399302)
		(width 0.09525)
		(layer "In4.Cu")
		(net "M_D_CPU1_SA_DQS_DP<9>")
	)
	(arc
		(start 88.469724 -247.399302)
		(mid 88.751156 -247.475057)
		(end 89.032588 -247.399302)
		(width 0.09525)
		(layer "In4.Cu")
		(net "M_D_CPU1_SA_DQS_DP<9>")
	)
	(arc
		(start 90.349578 -247.399302)
		(mid 90.63101 -247.475057)
		(end 90.912442 -247.399302)
		(width 0.09525)
		(layer "In4.Cu")
		(net "M_D_CPU1_SA_DQS_DP<9>")
	)
	(arc
		(start 91.860878 -247.394476)
		(mid 92.013773 -247.349648)
		(end 92.17152 -247.372124)
		(width 0.09525)
		(layer "In4.Cu")
		(net "M_D_CPU1_SA_DQS_DP<9>")
	)
	(arc
		(start 81.51241 -247.399302)
		(mid 81.696185 -247.34853)
		(end 81.881218 -247.394476)
		(width 0.09525)
		(layer "In4.Cu")
		(net "M_D_CPU1_SA_DQS_DP<9>")
	)
	(arc
		(start 86.589616 -247.399302)
		(mid 86.871048 -247.475057)
		(end 87.15248 -247.399302)
		(width 0.09525)
		(layer "In4.Cu")
		(net "M_D_CPU1_SA_DQS_DP<9>")
	)
	(arc
		(start 85.272372 -247.399302)
		(mid 85.456147 -247.34853)
		(end 85.64118 -247.394476)
		(width 0.09525)
		(layer "In4.Cu")
		(net "M_D_CPU1_SA_DQS_DP<9>")
	)
	(arc
		(start 80.57261 -247.399302)
		(mid 80.761078 -247.348625)
		(end 80.949546 -247.399302)
		(width 0.09525)
		(layer "In4.Cu")
		(net "M_D_CPU1_SA_DQS_DP<9>")
	)
	(arc
		(start 84.332572 -247.399302)
		(mid 84.52104 -247.348625)
		(end 84.709508 -247.399302)
		(width 0.09525)
		(layer "In4.Cu")
		(net "M_D_CPU1_SA_DQS_DP<9>")
	)
	(arc
		(start 79.632048 -247.399302)
		(mid 79.816077 -247.348403)
		(end 80.001364 -247.394476)
		(width 0.09525)
		(layer "In4.Cu")
		(net "M_D_CPU1_SA_DQS_DP<9>")
	)
	(arc
		(start 82.460846 -247.394476)
		(mid 82.645878 -247.348562)
		(end 82.829654 -247.399302)
		(width 0.09525)
		(layer "In4.Cu")
		(net "M_D_CPU1_SA_DQS_DP<9>")
	)
	(arc
		(start 78.12913 -247.399302)
		(mid 78.398563 -247.475173)
		(end 78.671166 -247.411494)
		(width 0.09525)
		(layer "In4.Cu")
		(net "M_D_CPU1_SA_DQS_DP<9>")
	)
	(arc
		(start 79.079344 -247.405398)
		(mid 79.356506 -247.475198)
		(end 79.632048 -247.399302)
		(width 0.09525)
		(layer "In4.Cu")
		(net "M_D_CPU1_SA_DQS_DP<9>")
	)
	(arc
		(start 89.032588 -247.399302)
		(mid 89.221056 -247.348625)
		(end 89.409524 -247.399302)
		(width 0.09525)
		(layer "In4.Cu")
		(net "M_D_CPU1_SA_DQS_DP<9>")
	)
	(arc
		(start 85.649562 -247.399302)
		(mid 85.930994 -247.475057)
		(end 86.212426 -247.399302)
		(width 0.09525)
		(layer "In4.Cu")
		(net "M_D_CPU1_SA_DQS_DP<9>")
	)
	(arc
		(start 80.949546 -247.399302)
		(mid 81.230978 -247.475057)
		(end 81.51241 -247.399302)
		(width 0.09525)
		(layer "In4.Cu")
		(net "M_D_CPU1_SA_DQS_DP<9>")
	)
	(arc
		(start 82.829654 -247.399302)
		(mid 83.111086 -247.475057)
		(end 83.392518 -247.399302)
		(width 0.09525)
		(layer "In4.Cu")
		(net "M_D_CPU1_SA_DQS_DP<9>")
	)
	(arc
		(start 87.160862 -247.394476)
		(mid 87.345894 -247.348562)
		(end 87.52967 -247.399302)
		(width 0.09525)
		(layer "In4.Cu")
		(net "M_D_CPU1_SA_DQS_DP<9>")
	)
	(arc
		(start 78.703932 -247.392444)
		(mid 78.887313 -247.348613)
		(end 79.06893 -247.399302)
		(width 0.09525)
		(layer "In4.Cu")
		(net "M_D_CPU1_SA_DQS_DP<9>")
	)
	(arc
		(start 89.972388 -247.399302)
		(mid 90.156163 -247.34853)
		(end 90.341196 -247.394476)
		(width 0.09525)
		(layer "In4.Cu")
		(net "M_D_CPU1_SA_DQS_DP<9>")
	)
	(segment
		(start 92.507816 -243.130324)
		(end 92.040964 -242.864386)
		(width 0.12954)
		(layer "F.Cu")
		(net "M_D_CPU1_SA_DQS_DP<8>")
	)
	(segment
		(start 56.523128 -230.875586)
		(end 57.247028 -230.875586)
		(width 0.16002)
		(layer "In4.Cu")
		(net "M_D_CPU1_SA_DQS_DP<8>")
	)
	(segment
		(start 85.64118 -242.53444)
		(end 85.649562 -242.539266)
		(width 0.09525)
		(layer "In4.Cu")
		(net "M_D_CPU1_SA_DQS_DP<8>")
	)
	(segment
		(start 41.100248 -231.210612)
		(end 41.435274 -230.875586)
		(width 0.16002)
		(layer "In4.Cu")
		(net "M_D_CPU1_SA_DQS_DP<8>")
	)
	(segment
		(start 35.108896 -230.030782)
		(end 35.610292 -230.030782)
		(width 0.16002)
		(layer "In4.Cu")
		(net "M_D_CPU1_SA_DQS_DP<8>")
	)
	(segment
		(start 81.881218 -242.53444)
		(end 81.8896 -242.539266)
		(width 0.09525)
		(layer "In4.Cu")
		(net "M_D_CPU1_SA_DQS_DP<8>")
	)
	(segment
		(start 75.89774 -241.549428)
		(end 75.921362 -241.549428)
		(width 0.09525)
		(layer "In4.Cu")
		(net "M_D_CPU1_SA_DQS_DP<8>")
	)
	(segment
		(start 87.15248 -242.539266)
		(end 87.160862 -242.53444)
		(width 0.09525)
		(layer "In4.Cu")
		(net "M_D_CPU1_SA_DQS_DP<8>")
	)
	(segment
		(start 36.553648 -230.494078)
		(end 37.033708 -230.494078)
		(width 0.16002)
		(layer "In4.Cu")
		(net "M_D_CPU1_SA_DQS_DP<8>")
	)
	(segment
		(start 49.456594 -230.875586)
		(end 50.340768 -229.991412)
		(width 0.16002)
		(layer "In4.Cu")
		(net "M_D_CPU1_SA_DQS_DP<8>")
	)
	(segment
		(start 46.691042 -231.210612)
		(end 48.644048 -231.210612)
		(width 0.16002)
		(layer "In4.Cu")
		(net "M_D_CPU1_SA_DQS_DP<8>")
	)
	(segment
		(start 91.852496 -242.539266)
		(end 91.860878 -242.53444)
		(width 0.09525)
		(layer "In4.Cu")
		(net "M_D_CPU1_SA_DQS_DP<8>")
	)
	(segment
		(start 76.24191 -241.72418)
		(end 76.677266 -242.159536)
		(width 0.09525)
		(layer "In4.Cu")
		(net "M_D_CPU1_SA_DQS_DP<8>")
	)
	(segment
		(start 76.133706 -241.490246)
		(end 76.24191 -241.59845)
		(width 0.09525)
		(layer "In4.Cu")
		(net "M_D_CPU1_SA_DQS_DP<8>")
	)
	(segment
		(start 90.912442 -242.539266)
		(end 90.920824 -242.53444)
		(width 0.09525)
		(layer "In4.Cu")
		(net "M_D_CPU1_SA_DQS_DP<8>")
	)
	(segment
		(start 48.979074 -230.875586)
		(end 49.456594 -230.875586)
		(width 0.16002)
		(layer "In4.Cu")
		(net "M_D_CPU1_SA_DQS_DP<8>")
	)
	(segment
		(start 92.194888 -242.598956)
		(end 92.040964 -242.864386)
		(width 0.09525)
		(layer "In4.Cu")
		(net "M_D_CPU1_SA_DQS_DP<8>")
	)
	(segment
		(start 45.840904 -230.360474)
		(end 46.691042 -231.210612)
		(width 0.16002)
		(layer "In4.Cu")
		(net "M_D_CPU1_SA_DQS_DP<8>")
	)
	(segment
		(start 76.677266 -242.159536)
		(end 77.344016 -242.159536)
		(width 0.09525)
		(layer "In4.Cu")
		(net "M_D_CPU1_SA_DQS_DP<8>")
	)
	(segment
		(start 50.655474 -229.991412)
		(end 51.024536 -230.360474)
		(width 0.16002)
		(layer "In4.Cu")
		(net "M_D_CPU1_SA_DQS_DP<8>")
	)
	(segment
		(start 57.582054 -231.210612)
		(end 59.868562 -231.210612)
		(width 0.16002)
		(layer "In4.Cu")
		(net "M_D_CPU1_SA_DQS_DP<8>")
	)
	(segment
		(start 57.247028 -230.875586)
		(end 57.582054 -231.210612)
		(width 0.16002)
		(layer "In4.Cu")
		(net "M_D_CPU1_SA_DQS_DP<8>")
	)
	(segment
		(start 50.340768 -229.991412)
		(end 50.655474 -229.991412)
		(width 0.16002)
		(layer "In4.Cu")
		(net "M_D_CPU1_SA_DQS_DP<8>")
	)
	(segment
		(start 35.956748 -230.377238)
		(end 36.436808 -230.377238)
		(width 0.16002)
		(layer "In4.Cu")
		(net "M_D_CPU1_SA_DQS_DP<8>")
	)
	(segment
		(start 78.671166 -242.551458)
		(end 78.691994 -242.539266)
		(width 0.09525)
		(layer "In4.Cu")
		(net "M_D_CPU1_SA_DQS_DP<8>")
	)
	(segment
		(start 53.457348 -230.360474)
		(end 54.276752 -231.179878)
		(width 0.16002)
		(layer "In4.Cu")
		(net "M_D_CPU1_SA_DQS_DP<8>")
	)
	(segment
		(start 90.341196 -242.53444)
		(end 90.349578 -242.539266)
		(width 0.09525)
		(layer "In4.Cu")
		(net "M_D_CPU1_SA_DQS_DP<8>")
	)
	(segment
		(start 92.17152 -242.512088)
		(end 92.194888 -242.598956)
		(width 0.09525)
		(layer "In4.Cu")
		(net "M_D_CPU1_SA_DQS_DP<8>")
	)
	(segment
		(start 43.111674 -229.991412)
		(end 43.480736 -230.360474)
		(width 0.16002)
		(layer "In4.Cu")
		(net "M_D_CPU1_SA_DQS_DP<8>")
	)
	(segment
		(start 37.033708 -230.494078)
		(end 37.150548 -230.377238)
		(width 0.16002)
		(layer "In4.Cu")
		(net "M_D_CPU1_SA_DQS_DP<8>")
	)
	(segment
		(start 42.796968 -229.991412)
		(end 43.111674 -229.991412)
		(width 0.16002)
		(layer "In4.Cu")
		(net "M_D_CPU1_SA_DQS_DP<8>")
	)
	(segment
		(start 83.392518 -242.539266)
		(end 83.4009 -242.53444)
		(width 0.09525)
		(layer "In4.Cu")
		(net "M_D_CPU1_SA_DQS_DP<8>")
	)
	(segment
		(start 32.695896 -230.485442)
		(end 32.969962 -230.211376)
		(width 0.16002)
		(layer "In4.Cu")
		(net "M_D_CPU1_SA_DQS_DP<8>")
	)
	(segment
		(start 48.644048 -231.210612)
		(end 48.979074 -230.875586)
		(width 0.16002)
		(layer "In4.Cu")
		(net "M_D_CPU1_SA_DQS_DP<8>")
	)
	(segment
		(start 35.610292 -230.030782)
		(end 35.956748 -230.377238)
		(width 0.16002)
		(layer "In4.Cu")
		(net "M_D_CPU1_SA_DQS_DP<8>")
	)
	(segment
		(start 78.691994 -242.539266)
		(end 78.706472 -242.530884)
		(width 0.09525)
		(layer "In4.Cu")
		(net "M_D_CPU1_SA_DQS_DP<8>")
	)
	(segment
		(start 86.581234 -242.53444)
		(end 86.589616 -242.539266)
		(width 0.09525)
		(layer "In4.Cu")
		(net "M_D_CPU1_SA_DQS_DP<8>")
	)
	(segment
		(start 41.435274 -230.875586)
		(end 41.912794 -230.875586)
		(width 0.16002)
		(layer "In4.Cu")
		(net "M_D_CPU1_SA_DQS_DP<8>")
	)
	(segment
		(start 54.276752 -231.179878)
		(end 56.218836 -231.179878)
		(width 0.16002)
		(layer "In4.Cu")
		(net "M_D_CPU1_SA_DQS_DP<8>")
	)
	(segment
		(start 32.969962 -230.211376)
		(end 34.928302 -230.211376)
		(width 0.16002)
		(layer "In4.Cu")
		(net "M_D_CPU1_SA_DQS_DP<8>")
	)
	(segment
		(start 38.346888 -230.377238)
		(end 39.180262 -231.210612)
		(width 0.16002)
		(layer "In4.Cu")
		(net "M_D_CPU1_SA_DQS_DP<8>")
	)
	(segment
		(start 70.207378 -241.549428)
		(end 75.89774 -241.549428)
		(width 0.16002)
		(layer "In4.Cu")
		(net "M_D_CPU1_SA_DQS_DP<8>")
	)
	(segment
		(start 59.868562 -231.210612)
		(end 70.207378 -241.549428)
		(width 0.16002)
		(layer "In4.Cu")
		(net "M_D_CPU1_SA_DQS_DP<8>")
	)
	(segment
		(start 82.452464 -242.539266)
		(end 82.460846 -242.53444)
		(width 0.09525)
		(layer "In4.Cu")
		(net "M_D_CPU1_SA_DQS_DP<8>")
	)
	(segment
		(start 88.092534 -242.539266)
		(end 88.100916 -242.53444)
		(width 0.09525)
		(layer "In4.Cu")
		(net "M_D_CPU1_SA_DQS_DP<8>")
	)
	(segment
		(start 79.617824 -242.547902)
		(end 79.632556 -242.539266)
		(width 0.09525)
		(layer "In4.Cu")
		(net "M_D_CPU1_SA_DQS_DP<8>")
	)
	(segment
		(start 36.436808 -230.377238)
		(end 36.553648 -230.494078)
		(width 0.16002)
		(layer "In4.Cu")
		(net "M_D_CPU1_SA_DQS_DP<8>")
	)
	(segment
		(start 43.480736 -230.360474)
		(end 45.840904 -230.360474)
		(width 0.16002)
		(layer "In4.Cu")
		(net "M_D_CPU1_SA_DQS_DP<8>")
	)
	(segment
		(start 37.150548 -230.377238)
		(end 38.346888 -230.377238)
		(width 0.16002)
		(layer "In4.Cu")
		(net "M_D_CPU1_SA_DQS_DP<8>")
	)
	(segment
		(start 79.632556 -242.539266)
		(end 79.640938 -242.53444)
		(width 0.09525)
		(layer "In4.Cu")
		(net "M_D_CPU1_SA_DQS_DP<8>")
	)
	(segment
		(start 41.912794 -230.875586)
		(end 42.796968 -229.991412)
		(width 0.16002)
		(layer "In4.Cu")
		(net "M_D_CPU1_SA_DQS_DP<8>")
	)
	(segment
		(start 76.24191 -241.59845)
		(end 76.24191 -241.72418)
		(width 0.09525)
		(layer "In4.Cu")
		(net "M_D_CPU1_SA_DQS_DP<8>")
	)
	(segment
		(start 75.921362 -241.549428)
		(end 75.980544 -241.490246)
		(width 0.09525)
		(layer "In4.Cu")
		(net "M_D_CPU1_SA_DQS_DP<8>")
	)
	(segment
		(start 39.180262 -231.210612)
		(end 41.100248 -231.210612)
		(width 0.16002)
		(layer "In4.Cu")
		(net "M_D_CPU1_SA_DQS_DP<8>")
	)
	(segment
		(start 77.344016 -242.159536)
		(end 77.672184 -242.487704)
		(width 0.09525)
		(layer "In4.Cu")
		(net "M_D_CPU1_SA_DQS_DP<8>")
	)
	(segment
		(start 34.928302 -230.211376)
		(end 35.108896 -230.030782)
		(width 0.16002)
		(layer "In4.Cu")
		(net "M_D_CPU1_SA_DQS_DP<8>")
	)
	(segment
		(start 51.024536 -230.360474)
		(end 53.457348 -230.360474)
		(width 0.16002)
		(layer "In4.Cu")
		(net "M_D_CPU1_SA_DQS_DP<8>")
	)
	(segment
		(start 75.980544 -241.490246)
		(end 76.133706 -241.490246)
		(width 0.09525)
		(layer "In4.Cu")
		(net "M_D_CPU1_SA_DQS_DP<8>")
	)
	(segment
		(start 56.218836 -231.179878)
		(end 56.523128 -230.875586)
		(width 0.16002)
		(layer "In4.Cu")
		(net "M_D_CPU1_SA_DQS_DP<8>")
	)
	(segment
		(start 77.672184 -242.487704)
		(end 77.940154 -242.487704)
		(width 0.09525)
		(layer "In4.Cu")
		(net "M_D_CPU1_SA_DQS_DP<8>")
	)
	(arc
		(start 90.920824 -242.53444)
		(mid 91.105856 -242.488526)
		(end 91.289632 -242.539266)
		(width 0.09525)
		(layer "In4.Cu")
		(net "M_D_CPU1_SA_DQS_DP<8>")
	)
	(arc
		(start 80.009746 -242.539266)
		(mid 80.291178 -242.615021)
		(end 80.57261 -242.539266)
		(width 0.09525)
		(layer "In4.Cu")
		(net "M_D_CPU1_SA_DQS_DP<8>")
	)
	(arc
		(start 90.349578 -242.539266)
		(mid 90.63101 -242.615021)
		(end 90.912442 -242.539266)
		(width 0.09525)
		(layer "In4.Cu")
		(net "M_D_CPU1_SA_DQS_DP<8>")
	)
	(arc
		(start 84.332572 -242.539266)
		(mid 84.52104 -242.488589)
		(end 84.709508 -242.539266)
		(width 0.09525)
		(layer "In4.Cu")
		(net "M_D_CPU1_SA_DQS_DP<8>")
	)
	(arc
		(start 82.460846 -242.53444)
		(mid 82.645878 -242.488526)
		(end 82.829654 -242.539266)
		(width 0.09525)
		(layer "In4.Cu")
		(net "M_D_CPU1_SA_DQS_DP<8>")
	)
	(arc
		(start 84.709508 -242.539266)
		(mid 84.99094 -242.615021)
		(end 85.272372 -242.539266)
		(width 0.09525)
		(layer "In4.Cu")
		(net "M_D_CPU1_SA_DQS_DP<8>")
	)
	(arc
		(start 82.829654 -242.539266)
		(mid 83.111086 -242.615021)
		(end 83.392518 -242.539266)
		(width 0.09525)
		(layer "In4.Cu")
		(net "M_D_CPU1_SA_DQS_DP<8>")
	)
	(arc
		(start 87.160862 -242.53444)
		(mid 87.345894 -242.488526)
		(end 87.52967 -242.539266)
		(width 0.09525)
		(layer "In4.Cu")
		(net "M_D_CPU1_SA_DQS_DP<8>")
	)
	(arc
		(start 89.409524 -242.539266)
		(mid 89.690956 -242.615021)
		(end 89.972388 -242.539266)
		(width 0.09525)
		(layer "In4.Cu")
		(net "M_D_CPU1_SA_DQS_DP<8>")
	)
	(arc
		(start 86.589616 -242.539266)
		(mid 86.871048 -242.615021)
		(end 87.15248 -242.539266)
		(width 0.09525)
		(layer "In4.Cu")
		(net "M_D_CPU1_SA_DQS_DP<8>")
	)
	(arc
		(start 86.212426 -242.539266)
		(mid 86.396201 -242.488494)
		(end 86.581234 -242.53444)
		(width 0.09525)
		(layer "In4.Cu")
		(net "M_D_CPU1_SA_DQS_DP<8>")
	)
	(arc
		(start 91.289632 -242.539266)
		(mid 91.571064 -242.615021)
		(end 91.852496 -242.539266)
		(width 0.09525)
		(layer "In4.Cu")
		(net "M_D_CPU1_SA_DQS_DP<8>")
	)
	(arc
		(start 88.469724 -242.539266)
		(mid 88.751156 -242.615021)
		(end 89.032588 -242.539266)
		(width 0.09525)
		(layer "In4.Cu")
		(net "M_D_CPU1_SA_DQS_DP<8>")
	)
	(arc
		(start 85.649562 -242.539266)
		(mid 85.930994 -242.615021)
		(end 86.212426 -242.539266)
		(width 0.09525)
		(layer "In4.Cu")
		(net "M_D_CPU1_SA_DQS_DP<8>")
	)
	(arc
		(start 87.52967 -242.539266)
		(mid 87.811102 -242.615021)
		(end 88.092534 -242.539266)
		(width 0.09525)
		(layer "In4.Cu")
		(net "M_D_CPU1_SA_DQS_DP<8>")
	)
	(arc
		(start 85.272372 -242.539266)
		(mid 85.456147 -242.488494)
		(end 85.64118 -242.53444)
		(width 0.09525)
		(layer "In4.Cu")
		(net "M_D_CPU1_SA_DQS_DP<8>")
	)
	(arc
		(start 83.769708 -242.539266)
		(mid 84.05114 -242.615021)
		(end 84.332572 -242.539266)
		(width 0.09525)
		(layer "In4.Cu")
		(net "M_D_CPU1_SA_DQS_DP<8>")
	)
	(arc
		(start 78.12913 -242.539266)
		(mid 78.398563 -242.615137)
		(end 78.671166 -242.551458)
		(width 0.09525)
		(layer "In4.Cu")
		(net "M_D_CPU1_SA_DQS_DP<8>")
	)
	(arc
		(start 88.100916 -242.53444)
		(mid 88.285948 -242.488526)
		(end 88.469724 -242.539266)
		(width 0.09525)
		(layer "In4.Cu")
		(net "M_D_CPU1_SA_DQS_DP<8>")
	)
	(arc
		(start 79.640938 -242.53444)
		(mid 79.82597 -242.488526)
		(end 80.009746 -242.539266)
		(width 0.09525)
		(layer "In4.Cu")
		(net "M_D_CPU1_SA_DQS_DP<8>")
	)
	(arc
		(start 89.032588 -242.539266)
		(mid 89.221056 -242.488589)
		(end 89.409524 -242.539266)
		(width 0.09525)
		(layer "In4.Cu")
		(net "M_D_CPU1_SA_DQS_DP<8>")
	)
	(arc
		(start 83.4009 -242.53444)
		(mid 83.585932 -242.488526)
		(end 83.769708 -242.539266)
		(width 0.09525)
		(layer "In4.Cu")
		(net "M_D_CPU1_SA_DQS_DP<8>")
	)
	(arc
		(start 77.940154 -242.487704)
		(mid 78.038051 -242.50099)
		(end 78.12913 -242.539266)
		(width 0.09525)
		(layer "In4.Cu")
		(net "M_D_CPU1_SA_DQS_DP<8>")
	)
	(arc
		(start 79.069184 -242.539266)
		(mid 79.342366 -242.615208)
		(end 79.617824 -242.547902)
		(width 0.09525)
		(layer "In4.Cu")
		(net "M_D_CPU1_SA_DQS_DP<8>")
	)
	(arc
		(start 81.8896 -242.539266)
		(mid 82.171032 -242.615021)
		(end 82.452464 -242.539266)
		(width 0.09525)
		(layer "In4.Cu")
		(net "M_D_CPU1_SA_DQS_DP<8>")
	)
	(arc
		(start 91.860878 -242.53444)
		(mid 92.013773 -242.489612)
		(end 92.17152 -242.512088)
		(width 0.09525)
		(layer "In4.Cu")
		(net "M_D_CPU1_SA_DQS_DP<8>")
	)
	(arc
		(start 80.57261 -242.539266)
		(mid 80.761078 -242.488589)
		(end 80.949546 -242.539266)
		(width 0.09525)
		(layer "In4.Cu")
		(net "M_D_CPU1_SA_DQS_DP<8>")
	)
	(arc
		(start 78.706472 -242.530884)
		(mid 78.888904 -242.488444)
		(end 79.069184 -242.539266)
		(width 0.09525)
		(layer "In4.Cu")
		(net "M_D_CPU1_SA_DQS_DP<8>")
	)
	(arc
		(start 81.51241 -242.539266)
		(mid 81.696185 -242.488494)
		(end 81.881218 -242.53444)
		(width 0.09525)
		(layer "In4.Cu")
		(net "M_D_CPU1_SA_DQS_DP<8>")
	)
	(arc
		(start 80.949546 -242.539266)
		(mid 81.230978 -242.615021)
		(end 81.51241 -242.539266)
		(width 0.09525)
		(layer "In4.Cu")
		(net "M_D_CPU1_SA_DQS_DP<8>")
	)
	(arc
		(start 89.972388 -242.539266)
		(mid 90.156163 -242.488494)
		(end 90.341196 -242.53444)
		(width 0.09525)
		(layer "In4.Cu")
		(net "M_D_CPU1_SA_DQS_DP<8>")
	)
	(segment
		(start 92.507816 -238.270288)
		(end 92.040964 -238.00435)
		(width 0.12954)
		(layer "F.Cu")
		(net "M_D_CPU1_SA_DQS_DP<7>")
	)
	(segment
		(start 56.218836 -221.829884)
		(end 56.523128 -221.525592)
		(width 0.16002)
		(layer "In4.Cu")
		(net "M_D_CPU1_SA_DQS_DP<7>")
	)
	(segment
		(start 88.092534 -237.67923)
		(end 88.100916 -237.674404)
		(width 0.09525)
		(layer "In4.Cu")
		(net "M_D_CPU1_SA_DQS_DP<7>")
	)
	(segment
		(start 45.840904 -221.01048)
		(end 46.690788 -221.860364)
		(width 0.16002)
		(layer "In4.Cu")
		(net "M_D_CPU1_SA_DQS_DP<7>")
	)
	(segment
		(start 41.435274 -221.525592)
		(end 41.912794 -221.525592)
		(width 0.16002)
		(layer "In4.Cu")
		(net "M_D_CPU1_SA_DQS_DP<7>")
	)
	(segment
		(start 48.644302 -221.860364)
		(end 48.979074 -221.525592)
		(width 0.16002)
		(layer "In4.Cu")
		(net "M_D_CPU1_SA_DQS_DP<7>")
	)
	(segment
		(start 79.050642 -237.66653)
		(end 79.072486 -237.67923)
		(width 0.09525)
		(layer "In4.Cu")
		(net "M_D_CPU1_SA_DQS_DP<7>")
	)
	(segment
		(start 81.881218 -237.674404)
		(end 81.8896 -237.67923)
		(width 0.09525)
		(layer "In4.Cu")
		(net "M_D_CPU1_SA_DQS_DP<7>")
	)
	(segment
		(start 37.150548 -221.027244)
		(end 38.346888 -221.027244)
		(width 0.16002)
		(layer "In4.Cu")
		(net "M_D_CPU1_SA_DQS_DP<7>")
	)
	(segment
		(start 76.03871 -235.872274)
		(end 76.173584 -235.872274)
		(width 0.09525)
		(layer "In4.Cu")
		(net "M_D_CPU1_SA_DQS_DP<7>")
	)
	(segment
		(start 37.033708 -221.144084)
		(end 37.150548 -221.027244)
		(width 0.16002)
		(layer "In4.Cu")
		(net "M_D_CPU1_SA_DQS_DP<7>")
	)
	(segment
		(start 75.979528 -235.931456)
		(end 76.03871 -235.872274)
		(width 0.09525)
		(layer "In4.Cu")
		(net "M_D_CPU1_SA_DQS_DP<7>")
	)
	(segment
		(start 79.60614 -237.695232)
		(end 79.633572 -237.67923)
		(width 0.09525)
		(layer "In4.Cu")
		(net "M_D_CPU1_SA_DQS_DP<7>")
	)
	(segment
		(start 35.956748 -221.027244)
		(end 36.436808 -221.027244)
		(width 0.16002)
		(layer "In4.Cu")
		(net "M_D_CPU1_SA_DQS_DP<7>")
	)
	(segment
		(start 92.17152 -237.652052)
		(end 92.194888 -237.73892)
		(width 0.09525)
		(layer "In4.Cu")
		(net "M_D_CPU1_SA_DQS_DP<7>")
	)
	(segment
		(start 76.173584 -235.872274)
		(end 76.533756 -236.232446)
		(width 0.09525)
		(layer "In4.Cu")
		(net "M_D_CPU1_SA_DQS_DP<7>")
	)
	(segment
		(start 85.64118 -237.674404)
		(end 85.649562 -237.67923)
		(width 0.09525)
		(layer "In4.Cu")
		(net "M_D_CPU1_SA_DQS_DP<7>")
	)
	(segment
		(start 43.111674 -220.641418)
		(end 43.480736 -221.01048)
		(width 0.16002)
		(layer "In4.Cu")
		(net "M_D_CPU1_SA_DQS_DP<7>")
	)
	(segment
		(start 43.480736 -221.01048)
		(end 45.840904 -221.01048)
		(width 0.16002)
		(layer "In4.Cu")
		(net "M_D_CPU1_SA_DQS_DP<7>")
	)
	(segment
		(start 76.938632 -236.232446)
		(end 77.20838 -236.502194)
		(width 0.09525)
		(layer "In4.Cu")
		(net "M_D_CPU1_SA_DQS_DP<7>")
	)
	(segment
		(start 57.211976 -221.525592)
		(end 57.546748 -221.860364)
		(width 0.16002)
		(layer "In4.Cu")
		(net "M_D_CPU1_SA_DQS_DP<7>")
	)
	(segment
		(start 73.677018 -235.931456)
		(end 75.955906 -235.931456)
		(width 0.16002)
		(layer "In4.Cu")
		(net "M_D_CPU1_SA_DQS_DP<7>")
	)
	(segment
		(start 86.581234 -237.674404)
		(end 86.589616 -237.67923)
		(width 0.09525)
		(layer "In4.Cu")
		(net "M_D_CPU1_SA_DQS_DP<7>")
	)
	(segment
		(start 41.100502 -221.860364)
		(end 41.435274 -221.525592)
		(width 0.16002)
		(layer "In4.Cu")
		(net "M_D_CPU1_SA_DQS_DP<7>")
	)
	(segment
		(start 92.194888 -237.73892)
		(end 92.040964 -238.00435)
		(width 0.09525)
		(layer "In4.Cu")
		(net "M_D_CPU1_SA_DQS_DP<7>")
	)
	(segment
		(start 76.533756 -236.232446)
		(end 76.938632 -236.232446)
		(width 0.09525)
		(layer "In4.Cu")
		(net "M_D_CPU1_SA_DQS_DP<7>")
	)
	(segment
		(start 90.912442 -237.67923)
		(end 90.920824 -237.674404)
		(width 0.09525)
		(layer "In4.Cu")
		(net "M_D_CPU1_SA_DQS_DP<7>")
	)
	(segment
		(start 50.340768 -220.641418)
		(end 50.655474 -220.641418)
		(width 0.16002)
		(layer "In4.Cu")
		(net "M_D_CPU1_SA_DQS_DP<7>")
	)
	(segment
		(start 53.43652 -221.01048)
		(end 54.255924 -221.829884)
		(width 0.16002)
		(layer "In4.Cu")
		(net "M_D_CPU1_SA_DQS_DP<7>")
	)
	(segment
		(start 59.962288 -221.860364)
		(end 60.46597 -222.364046)
		(width 0.16002)
		(layer "In4.Cu")
		(net "M_D_CPU1_SA_DQS_DP<7>")
	)
	(segment
		(start 35.610292 -220.680788)
		(end 35.956748 -221.027244)
		(width 0.16002)
		(layer "In4.Cu")
		(net "M_D_CPU1_SA_DQS_DP<7>")
	)
	(segment
		(start 83.392518 -237.67923)
		(end 83.4009 -237.674404)
		(width 0.09525)
		(layer "In4.Cu")
		(net "M_D_CPU1_SA_DQS_DP<7>")
	)
	(segment
		(start 78.170024 -237.755684)
		(end 78.411324 -237.755684)
		(width 0.09525)
		(layer "In4.Cu")
		(net "M_D_CPU1_SA_DQS_DP<7>")
	)
	(segment
		(start 77.20838 -236.502194)
		(end 77.20838 -236.79404)
		(width 0.09525)
		(layer "In4.Cu")
		(net "M_D_CPU1_SA_DQS_DP<7>")
	)
	(segment
		(start 42.796968 -220.641418)
		(end 43.111674 -220.641418)
		(width 0.16002)
		(layer "In4.Cu")
		(net "M_D_CPU1_SA_DQS_DP<7>")
	)
	(segment
		(start 48.979074 -221.525592)
		(end 49.456594 -221.525592)
		(width 0.16002)
		(layer "In4.Cu")
		(net "M_D_CPU1_SA_DQS_DP<7>")
	)
	(segment
		(start 36.436808 -221.027244)
		(end 36.553648 -221.144084)
		(width 0.16002)
		(layer "In4.Cu")
		(net "M_D_CPU1_SA_DQS_DP<7>")
	)
	(segment
		(start 50.655474 -220.641418)
		(end 51.024536 -221.01048)
		(width 0.16002)
		(layer "In4.Cu")
		(net "M_D_CPU1_SA_DQS_DP<7>")
	)
	(segment
		(start 36.553648 -221.144084)
		(end 37.033708 -221.144084)
		(width 0.16002)
		(layer "In4.Cu")
		(net "M_D_CPU1_SA_DQS_DP<7>")
	)
	(segment
		(start 35.01009 -220.861382)
		(end 35.190684 -220.680788)
		(width 0.16002)
		(layer "In4.Cu")
		(net "M_D_CPU1_SA_DQS_DP<7>")
	)
	(segment
		(start 32.695896 -221.135194)
		(end 32.969708 -220.861382)
		(width 0.16002)
		(layer "In4.Cu")
		(net "M_D_CPU1_SA_DQS_DP<7>")
	)
	(segment
		(start 91.852496 -237.67923)
		(end 91.860878 -237.674404)
		(width 0.09525)
		(layer "In4.Cu")
		(net "M_D_CPU1_SA_DQS_DP<7>")
	)
	(segment
		(start 79.633572 -237.67923)
		(end 79.652368 -237.668562)
		(width 0.09525)
		(layer "In4.Cu")
		(net "M_D_CPU1_SA_DQS_DP<7>")
	)
	(segment
		(start 54.255924 -221.829884)
		(end 56.218836 -221.829884)
		(width 0.16002)
		(layer "In4.Cu")
		(net "M_D_CPU1_SA_DQS_DP<7>")
	)
	(segment
		(start 90.341196 -237.674404)
		(end 90.349578 -237.67923)
		(width 0.09525)
		(layer "In4.Cu")
		(net "M_D_CPU1_SA_DQS_DP<7>")
	)
	(segment
		(start 39.180008 -221.860364)
		(end 41.100502 -221.860364)
		(width 0.16002)
		(layer "In4.Cu")
		(net "M_D_CPU1_SA_DQS_DP<7>")
	)
	(segment
		(start 75.955906 -235.931456)
		(end 75.979528 -235.931456)
		(width 0.09525)
		(layer "In4.Cu")
		(net "M_D_CPU1_SA_DQS_DP<7>")
	)
	(segment
		(start 38.346888 -221.027244)
		(end 39.180008 -221.860364)
		(width 0.16002)
		(layer "In4.Cu")
		(net "M_D_CPU1_SA_DQS_DP<7>")
	)
	(segment
		(start 77.20838 -236.79404)
		(end 78.170024 -237.755684)
		(width 0.09525)
		(layer "In4.Cu")
		(net "M_D_CPU1_SA_DQS_DP<7>")
	)
	(segment
		(start 49.456594 -221.525592)
		(end 50.340768 -220.641418)
		(width 0.16002)
		(layer "In4.Cu")
		(net "M_D_CPU1_SA_DQS_DP<7>")
	)
	(segment
		(start 60.46597 -222.720408)
		(end 73.677018 -235.931456)
		(width 0.16002)
		(layer "In4.Cu")
		(net "M_D_CPU1_SA_DQS_DP<7>")
	)
	(segment
		(start 56.523128 -221.525592)
		(end 57.211976 -221.525592)
		(width 0.16002)
		(layer "In4.Cu")
		(net "M_D_CPU1_SA_DQS_DP<7>")
	)
	(segment
		(start 57.546748 -221.860364)
		(end 59.962288 -221.860364)
		(width 0.16002)
		(layer "In4.Cu")
		(net "M_D_CPU1_SA_DQS_DP<7>")
	)
	(segment
		(start 32.969708 -220.861382)
		(end 35.01009 -220.861382)
		(width 0.16002)
		(layer "In4.Cu")
		(net "M_D_CPU1_SA_DQS_DP<7>")
	)
	(segment
		(start 60.46597 -222.364046)
		(end 60.46597 -222.720408)
		(width 0.16002)
		(layer "In4.Cu")
		(net "M_D_CPU1_SA_DQS_DP<7>")
	)
	(segment
		(start 41.912794 -221.525592)
		(end 42.796968 -220.641418)
		(width 0.16002)
		(layer "In4.Cu")
		(net "M_D_CPU1_SA_DQS_DP<7>")
	)
	(segment
		(start 82.452464 -237.67923)
		(end 82.460846 -237.674404)
		(width 0.09525)
		(layer "In4.Cu")
		(net "M_D_CPU1_SA_DQS_DP<7>")
	)
	(segment
		(start 51.024536 -221.01048)
		(end 53.43652 -221.01048)
		(width 0.16002)
		(layer "In4.Cu")
		(net "M_D_CPU1_SA_DQS_DP<7>")
	)
	(segment
		(start 87.15248 -237.67923)
		(end 87.160862 -237.674404)
		(width 0.09525)
		(layer "In4.Cu")
		(net "M_D_CPU1_SA_DQS_DP<7>")
	)
	(segment
		(start 35.190684 -220.680788)
		(end 35.610292 -220.680788)
		(width 0.16002)
		(layer "In4.Cu")
		(net "M_D_CPU1_SA_DQS_DP<7>")
	)
	(segment
		(start 46.690788 -221.860364)
		(end 48.644302 -221.860364)
		(width 0.16002)
		(layer "In4.Cu")
		(net "M_D_CPU1_SA_DQS_DP<7>")
	)
	(arc
		(start 84.332572 -237.67923)
		(mid 84.52104 -237.628553)
		(end 84.709508 -237.67923)
		(width 0.09525)
		(layer "In4.Cu")
		(net "M_D_CPU1_SA_DQS_DP<7>")
	)
	(arc
		(start 87.52967 -237.67923)
		(mid 87.811102 -237.754985)
		(end 88.092534 -237.67923)
		(width 0.09525)
		(layer "In4.Cu")
		(net "M_D_CPU1_SA_DQS_DP<7>")
	)
	(arc
		(start 89.972388 -237.67923)
		(mid 90.156163 -237.628458)
		(end 90.341196 -237.674404)
		(width 0.09525)
		(layer "In4.Cu")
		(net "M_D_CPU1_SA_DQS_DP<7>")
	)
	(arc
		(start 87.160862 -237.674404)
		(mid 87.345894 -237.62849)
		(end 87.52967 -237.67923)
		(width 0.09525)
		(layer "In4.Cu")
		(net "M_D_CPU1_SA_DQS_DP<7>")
	)
	(arc
		(start 80.949546 -237.67923)
		(mid 81.230978 -237.754985)
		(end 81.51241 -237.67923)
		(width 0.09525)
		(layer "In4.Cu")
		(net "M_D_CPU1_SA_DQS_DP<7>")
	)
	(arc
		(start 81.51241 -237.67923)
		(mid 81.696185 -237.628458)
		(end 81.881218 -237.674404)
		(width 0.09525)
		(layer "In4.Cu")
		(net "M_D_CPU1_SA_DQS_DP<7>")
	)
	(arc
		(start 78.69428 -237.678976)
		(mid 78.870892 -237.627924)
		(end 79.050642 -237.66653)
		(width 0.09525)
		(layer "In4.Cu")
		(net "M_D_CPU1_SA_DQS_DP<7>")
	)
	(arc
		(start 86.589616 -237.67923)
		(mid 86.871048 -237.754985)
		(end 87.15248 -237.67923)
		(width 0.09525)
		(layer "In4.Cu")
		(net "M_D_CPU1_SA_DQS_DP<7>")
	)
	(arc
		(start 88.100916 -237.674404)
		(mid 88.285948 -237.62849)
		(end 88.469724 -237.67923)
		(width 0.09525)
		(layer "In4.Cu")
		(net "M_D_CPU1_SA_DQS_DP<7>")
	)
	(arc
		(start 79.072486 -237.67923)
		(mid 79.337295 -237.754859)
		(end 79.60614 -237.695232)
		(width 0.09525)
		(layer "In4.Cu")
		(net "M_D_CPU1_SA_DQS_DP<7>")
	)
	(arc
		(start 90.349578 -237.67923)
		(mid 90.63101 -237.754985)
		(end 90.912442 -237.67923)
		(width 0.09525)
		(layer "In4.Cu")
		(net "M_D_CPU1_SA_DQS_DP<7>")
	)
	(arc
		(start 89.409524 -237.67923)
		(mid 89.690956 -237.754985)
		(end 89.972388 -237.67923)
		(width 0.09525)
		(layer "In4.Cu")
		(net "M_D_CPU1_SA_DQS_DP<7>")
	)
	(arc
		(start 85.649562 -237.67923)
		(mid 85.930994 -237.754985)
		(end 86.212426 -237.67923)
		(width 0.09525)
		(layer "In4.Cu")
		(net "M_D_CPU1_SA_DQS_DP<7>")
	)
	(arc
		(start 89.032588 -237.67923)
		(mid 89.221056 -237.628553)
		(end 89.409524 -237.67923)
		(width 0.09525)
		(layer "In4.Cu")
		(net "M_D_CPU1_SA_DQS_DP<7>")
	)
	(arc
		(start 83.769708 -237.67923)
		(mid 84.05114 -237.754985)
		(end 84.332572 -237.67923)
		(width 0.09525)
		(layer "In4.Cu")
		(net "M_D_CPU1_SA_DQS_DP<7>")
	)
	(arc
		(start 82.829654 -237.67923)
		(mid 83.111086 -237.754985)
		(end 83.392518 -237.67923)
		(width 0.09525)
		(layer "In4.Cu")
		(net "M_D_CPU1_SA_DQS_DP<7>")
	)
	(arc
		(start 85.272372 -237.67923)
		(mid 85.456147 -237.628458)
		(end 85.64118 -237.674404)
		(width 0.09525)
		(layer "In4.Cu")
		(net "M_D_CPU1_SA_DQS_DP<7>")
	)
	(arc
		(start 84.709508 -237.67923)
		(mid 84.99094 -237.754985)
		(end 85.272372 -237.67923)
		(width 0.09525)
		(layer "In4.Cu")
		(net "M_D_CPU1_SA_DQS_DP<7>")
	)
	(arc
		(start 78.425802 -237.755684)
		(mid 78.56488 -237.734271)
		(end 78.69428 -237.678976)
		(width 0.09525)
		(layer "In4.Cu")
		(net "M_D_CPU1_SA_DQS_DP<7>")
	)
	(arc
		(start 90.920824 -237.674404)
		(mid 91.105856 -237.62849)
		(end 91.289632 -237.67923)
		(width 0.09525)
		(layer "In4.Cu")
		(net "M_D_CPU1_SA_DQS_DP<7>")
	)
	(arc
		(start 88.469724 -237.67923)
		(mid 88.751156 -237.754985)
		(end 89.032588 -237.67923)
		(width 0.09525)
		(layer "In4.Cu")
		(net "M_D_CPU1_SA_DQS_DP<7>")
	)
	(arc
		(start 81.8896 -237.67923)
		(mid 82.171032 -237.754985)
		(end 82.452464 -237.67923)
		(width 0.09525)
		(layer "In4.Cu")
		(net "M_D_CPU1_SA_DQS_DP<7>")
	)
	(arc
		(start 80.009746 -237.67923)
		(mid 80.291178 -237.754985)
		(end 80.57261 -237.67923)
		(width 0.09525)
		(layer "In4.Cu")
		(net "M_D_CPU1_SA_DQS_DP<7>")
	)
	(arc
		(start 83.4009 -237.674404)
		(mid 83.585932 -237.62849)
		(end 83.769708 -237.67923)
		(width 0.09525)
		(layer "In4.Cu")
		(net "M_D_CPU1_SA_DQS_DP<7>")
	)
	(arc
		(start 80.57261 -237.67923)
		(mid 80.761078 -237.628553)
		(end 80.949546 -237.67923)
		(width 0.09525)
		(layer "In4.Cu")
		(net "M_D_CPU1_SA_DQS_DP<7>")
	)
	(arc
		(start 91.860878 -237.674404)
		(mid 92.013773 -237.629576)
		(end 92.17152 -237.652052)
		(width 0.09525)
		(layer "In4.Cu")
		(net "M_D_CPU1_SA_DQS_DP<7>")
	)
	(arc
		(start 91.289632 -237.67923)
		(mid 91.571064 -237.754985)
		(end 91.852496 -237.67923)
		(width 0.09525)
		(layer "In4.Cu")
		(net "M_D_CPU1_SA_DQS_DP<7>")
	)
	(arc
		(start 79.652368 -237.668562)
		(mid 79.832418 -237.628637)
		(end 80.009746 -237.67923)
		(width 0.09525)
		(layer "In4.Cu")
		(net "M_D_CPU1_SA_DQS_DP<7>")
	)
	(arc
		(start 82.460846 -237.674404)
		(mid 82.645878 -237.62849)
		(end 82.829654 -237.67923)
		(width 0.09525)
		(layer "In4.Cu")
		(net "M_D_CPU1_SA_DQS_DP<7>")
	)
	(arc
		(start 78.411324 -237.755684)
		(mid 78.418563 -237.755732)
		(end 78.425802 -237.755684)
		(width 0.09525)
		(layer "In4.Cu")
		(net "M_D_CPU1_SA_DQS_DP<7>")
	)
	(arc
		(start 86.212426 -237.67923)
		(mid 86.396201 -237.628458)
		(end 86.581234 -237.674404)
		(width 0.09525)
		(layer "In4.Cu")
		(net "M_D_CPU1_SA_DQS_DP<7>")
	)
	(segment
		(start 92.507816 -233.410252)
		(end 92.040964 -233.144314)
		(width 0.12954)
		(layer "F.Cu")
		(net "M_D_CPU1_SA_DQS_DP<6>")
	)
	(segment
		(start 88.092534 -232.819194)
		(end 88.100916 -232.814368)
		(width 0.09525)
		(layer "In4.Cu")
		(net "M_D_CPU1_SA_DQS_DP<6>")
	)
	(segment
		(start 76.118974 -230.366316)
		(end 76.135738 -230.38308)
		(width 0.09525)
		(layer "In4.Cu")
		(net "M_D_CPU1_SA_DQS_DP<6>")
	)
	(segment
		(start 43.459146 -211.660486)
		(end 45.819314 -211.660486)
		(width 0.16002)
		(layer "In4.Cu")
		(net "M_D_CPU1_SA_DQS_DP<6>")
	)
	(segment
		(start 43.103546 -211.304886)
		(end 43.459146 -211.660486)
		(width 0.16002)
		(layer "In4.Cu")
		(net "M_D_CPU1_SA_DQS_DP<6>")
	)
	(segment
		(start 48.985424 -212.190838)
		(end 49.462944 -212.190838)
		(width 0.16002)
		(layer "In4.Cu")
		(net "M_D_CPU1_SA_DQS_DP<6>")
	)
	(segment
		(start 32.695896 -211.7852)
		(end 32.969708 -211.511388)
		(width 0.16002)
		(layer "In4.Cu")
		(net "M_D_CPU1_SA_DQS_DP<6>")
	)
	(segment
		(start 34.976308 -211.511388)
		(end 35.15487 -211.332826)
		(width 0.16002)
		(layer "In4.Cu")
		(net "M_D_CPU1_SA_DQS_DP<6>")
	)
	(segment
		(start 85.64118 -232.814368)
		(end 85.649562 -232.819194)
		(width 0.09525)
		(layer "In4.Cu")
		(net "M_D_CPU1_SA_DQS_DP<6>")
	)
	(segment
		(start 53.983382 -212.190838)
		(end 57.267602 -212.190838)
		(width 0.16002)
		(layer "In4.Cu")
		(net "M_D_CPU1_SA_DQS_DP<6>")
	)
	(segment
		(start 83.392518 -232.819194)
		(end 83.4009 -232.814368)
		(width 0.09525)
		(layer "In4.Cu")
		(net "M_D_CPU1_SA_DQS_DP<6>")
	)
	(segment
		(start 50.649124 -211.306664)
		(end 51.002946 -211.660486)
		(width 0.16002)
		(layer "In4.Cu")
		(net "M_D_CPU1_SA_DQS_DP<6>")
	)
	(segment
		(start 50.347118 -211.306664)
		(end 50.649124 -211.306664)
		(width 0.16002)
		(layer "In4.Cu")
		(net "M_D_CPU1_SA_DQS_DP<6>")
	)
	(segment
		(start 35.97275 -211.690966)
		(end 36.45281 -211.690966)
		(width 0.16002)
		(layer "In4.Cu")
		(net "M_D_CPU1_SA_DQS_DP<6>")
	)
	(segment
		(start 72.940418 -227.18776)
		(end 76.118974 -230.366316)
		(width 0.16002)
		(layer "In4.Cu")
		(net "M_D_CPU1_SA_DQS_DP<6>")
	)
	(segment
		(start 34.25698 -211.511388)
		(end 34.976308 -211.511388)
		(width 0.16002)
		(layer "In4.Cu")
		(net "M_D_CPU1_SA_DQS_DP<6>")
	)
	(segment
		(start 53.45303 -211.660486)
		(end 53.983382 -212.190838)
		(width 0.16002)
		(layer "In4.Cu")
		(net "M_D_CPU1_SA_DQS_DP<6>")
	)
	(segment
		(start 92.194888 -232.878884)
		(end 92.040964 -233.144314)
		(width 0.09525)
		(layer "In4.Cu")
		(net "M_D_CPU1_SA_DQS_DP<6>")
	)
	(segment
		(start 91.852496 -232.819194)
		(end 91.860878 -232.814368)
		(width 0.09525)
		(layer "In4.Cu")
		(net "M_D_CPU1_SA_DQS_DP<6>")
	)
	(segment
		(start 72.940418 -227.187506)
		(end 72.940418 -227.18776)
		(width 0.16002)
		(layer "In4.Cu")
		(net "M_D_CPU1_SA_DQS_DP<6>")
	)
	(segment
		(start 46.669198 -212.51037)
		(end 48.665892 -212.51037)
		(width 0.16002)
		(layer "In4.Cu")
		(net "M_D_CPU1_SA_DQS_DP<6>")
	)
	(segment
		(start 36.45281 -211.690966)
		(end 36.56965 -211.807806)
		(width 0.16002)
		(layer "In4.Cu")
		(net "M_D_CPU1_SA_DQS_DP<6>")
	)
	(segment
		(start 82.452464 -232.819194)
		(end 82.460846 -232.814368)
		(width 0.09525)
		(layer "In4.Cu")
		(net "M_D_CPU1_SA_DQS_DP<6>")
	)
	(segment
		(start 90.341196 -232.814368)
		(end 90.349578 -232.819194)
		(width 0.09525)
		(layer "In4.Cu")
		(net "M_D_CPU1_SA_DQS_DP<6>")
	)
	(segment
		(start 42.79519 -211.304886)
		(end 43.103546 -211.304886)
		(width 0.16002)
		(layer "In4.Cu")
		(net "M_D_CPU1_SA_DQS_DP<6>")
	)
	(segment
		(start 51.002946 -211.660486)
		(end 53.45303 -211.660486)
		(width 0.16002)
		(layer "In4.Cu")
		(net "M_D_CPU1_SA_DQS_DP<6>")
	)
	(segment
		(start 92.17152 -232.792016)
		(end 92.194888 -232.878884)
		(width 0.09525)
		(layer "In4.Cu")
		(net "M_D_CPU1_SA_DQS_DP<6>")
	)
	(segment
		(start 72.47001 -225.142806)
		(end 72.47001 -226.717098)
		(width 0.16002)
		(layer "In4.Cu")
		(net "M_D_CPU1_SA_DQS_DP<6>")
	)
	(segment
		(start 79.417926 -232.767886)
		(end 79.821024 -232.767886)
		(width 0.09525)
		(layer "In4.Cu")
		(net "M_D_CPU1_SA_DQS_DP<6>")
	)
	(segment
		(start 37.16655 -211.690966)
		(end 38.37813 -211.690966)
		(width 0.16002)
		(layer "In4.Cu")
		(net "M_D_CPU1_SA_DQS_DP<6>")
	)
	(segment
		(start 86.581234 -232.814368)
		(end 86.589616 -232.819194)
		(width 0.09525)
		(layer "In4.Cu")
		(net "M_D_CPU1_SA_DQS_DP<6>")
	)
	(segment
		(start 77.422756 -230.772716)
		(end 79.417926 -232.767886)
		(width 0.09525)
		(layer "In4.Cu")
		(net "M_D_CPU1_SA_DQS_DP<6>")
	)
	(segment
		(start 57.267602 -212.190838)
		(end 57.587134 -212.51037)
		(width 0.16002)
		(layer "In4.Cu")
		(net "M_D_CPU1_SA_DQS_DP<6>")
	)
	(segment
		(start 76.135738 -230.38308)
		(end 76.219558 -230.38308)
		(width 0.09525)
		(layer "In4.Cu")
		(net "M_D_CPU1_SA_DQS_DP<6>")
	)
	(segment
		(start 35.15487 -211.332826)
		(end 35.61461 -211.332826)
		(width 0.16002)
		(layer "In4.Cu")
		(net "M_D_CPU1_SA_DQS_DP<6>")
	)
	(segment
		(start 90.912442 -232.819194)
		(end 90.920824 -232.814368)
		(width 0.09525)
		(layer "In4.Cu")
		(net "M_D_CPU1_SA_DQS_DP<6>")
	)
	(segment
		(start 39.197534 -212.51037)
		(end 41.109646 -212.51037)
		(width 0.16002)
		(layer "In4.Cu")
		(net "M_D_CPU1_SA_DQS_DP<6>")
	)
	(segment
		(start 35.61461 -211.332826)
		(end 35.97275 -211.690966)
		(width 0.16002)
		(layer "In4.Cu")
		(net "M_D_CPU1_SA_DQS_DP<6>")
	)
	(segment
		(start 76.609194 -230.772716)
		(end 77.422756 -230.772716)
		(width 0.09525)
		(layer "In4.Cu")
		(net "M_D_CPU1_SA_DQS_DP<6>")
	)
	(segment
		(start 57.587134 -212.51037)
		(end 59.837574 -212.51037)
		(width 0.16002)
		(layer "In4.Cu")
		(net "M_D_CPU1_SA_DQS_DP<6>")
	)
	(segment
		(start 48.665892 -212.51037)
		(end 48.985424 -212.190838)
		(width 0.16002)
		(layer "In4.Cu")
		(net "M_D_CPU1_SA_DQS_DP<6>")
	)
	(segment
		(start 36.56965 -211.807806)
		(end 37.04971 -211.807806)
		(width 0.16002)
		(layer "In4.Cu")
		(net "M_D_CPU1_SA_DQS_DP<6>")
	)
	(segment
		(start 34.14014 -211.628228)
		(end 34.25698 -211.511388)
		(width 0.16002)
		(layer "In4.Cu")
		(net "M_D_CPU1_SA_DQS_DP<6>")
	)
	(segment
		(start 41.109646 -212.51037)
		(end 41.41343 -212.206586)
		(width 0.16002)
		(layer "In4.Cu")
		(net "M_D_CPU1_SA_DQS_DP<6>")
	)
	(segment
		(start 41.89349 -212.206586)
		(end 42.79519 -211.304886)
		(width 0.16002)
		(layer "In4.Cu")
		(net "M_D_CPU1_SA_DQS_DP<6>")
	)
	(segment
		(start 81.881218 -232.814368)
		(end 81.8896 -232.819194)
		(width 0.09525)
		(layer "In4.Cu")
		(net "M_D_CPU1_SA_DQS_DP<6>")
	)
	(segment
		(start 32.969708 -211.511388)
		(end 33.54324 -211.511388)
		(width 0.16002)
		(layer "In4.Cu")
		(net "M_D_CPU1_SA_DQS_DP<6>")
	)
	(segment
		(start 37.04971 -211.807806)
		(end 37.16655 -211.690966)
		(width 0.16002)
		(layer "In4.Cu")
		(net "M_D_CPU1_SA_DQS_DP<6>")
	)
	(segment
		(start 59.837574 -212.51037)
		(end 72.47001 -225.142806)
		(width 0.16002)
		(layer "In4.Cu")
		(net "M_D_CPU1_SA_DQS_DP<6>")
	)
	(segment
		(start 87.15248 -232.819194)
		(end 87.160862 -232.814368)
		(width 0.09525)
		(layer "In4.Cu")
		(net "M_D_CPU1_SA_DQS_DP<6>")
	)
	(segment
		(start 38.37813 -211.690966)
		(end 39.197534 -212.51037)
		(width 0.16002)
		(layer "In4.Cu")
		(net "M_D_CPU1_SA_DQS_DP<6>")
	)
	(segment
		(start 33.54324 -211.511388)
		(end 33.66008 -211.628228)
		(width 0.16002)
		(layer "In4.Cu")
		(net "M_D_CPU1_SA_DQS_DP<6>")
	)
	(segment
		(start 49.462944 -212.190838)
		(end 50.347118 -211.306664)
		(width 0.16002)
		(layer "In4.Cu")
		(net "M_D_CPU1_SA_DQS_DP<6>")
	)
	(segment
		(start 76.219558 -230.38308)
		(end 76.609194 -230.772716)
		(width 0.09525)
		(layer "In4.Cu")
		(net "M_D_CPU1_SA_DQS_DP<6>")
	)
	(segment
		(start 72.47001 -226.717098)
		(end 72.940418 -227.187506)
		(width 0.16002)
		(layer "In4.Cu")
		(net "M_D_CPU1_SA_DQS_DP<6>")
	)
	(segment
		(start 41.41343 -212.206586)
		(end 41.89349 -212.206586)
		(width 0.16002)
		(layer "In4.Cu")
		(net "M_D_CPU1_SA_DQS_DP<6>")
	)
	(segment
		(start 33.66008 -211.628228)
		(end 34.14014 -211.628228)
		(width 0.16002)
		(layer "In4.Cu")
		(net "M_D_CPU1_SA_DQS_DP<6>")
	)
	(segment
		(start 45.819314 -211.660486)
		(end 46.669198 -212.51037)
		(width 0.16002)
		(layer "In4.Cu")
		(net "M_D_CPU1_SA_DQS_DP<6>")
	)
	(arc
		(start 87.52967 -232.819194)
		(mid 87.811102 -232.894949)
		(end 88.092534 -232.819194)
		(width 0.09525)
		(layer "In4.Cu")
		(net "M_D_CPU1_SA_DQS_DP<6>")
	)
	(arc
		(start 85.649562 -232.819194)
		(mid 85.930994 -232.894949)
		(end 86.212426 -232.819194)
		(width 0.09525)
		(layer "In4.Cu")
		(net "M_D_CPU1_SA_DQS_DP<6>")
	)
	(arc
		(start 89.409524 -232.819194)
		(mid 89.690956 -232.894949)
		(end 89.972388 -232.819194)
		(width 0.09525)
		(layer "In4.Cu")
		(net "M_D_CPU1_SA_DQS_DP<6>")
	)
	(arc
		(start 91.289632 -232.819194)
		(mid 91.571064 -232.894949)
		(end 91.852496 -232.819194)
		(width 0.09525)
		(layer "In4.Cu")
		(net "M_D_CPU1_SA_DQS_DP<6>")
	)
	(arc
		(start 89.032588 -232.819194)
		(mid 89.221056 -232.768517)
		(end 89.409524 -232.819194)
		(width 0.09525)
		(layer "In4.Cu")
		(net "M_D_CPU1_SA_DQS_DP<6>")
	)
	(arc
		(start 80.57261 -232.819194)
		(mid 80.761078 -232.768517)
		(end 80.949546 -232.819194)
		(width 0.09525)
		(layer "In4.Cu")
		(net "M_D_CPU1_SA_DQS_DP<6>")
	)
	(arc
		(start 84.332572 -232.819194)
		(mid 84.52104 -232.768517)
		(end 84.709508 -232.819194)
		(width 0.09525)
		(layer "In4.Cu")
		(net "M_D_CPU1_SA_DQS_DP<6>")
	)
	(arc
		(start 86.589616 -232.819194)
		(mid 86.871048 -232.894949)
		(end 87.15248 -232.819194)
		(width 0.09525)
		(layer "In4.Cu")
		(net "M_D_CPU1_SA_DQS_DP<6>")
	)
	(arc
		(start 85.272372 -232.819194)
		(mid 85.456147 -232.768422)
		(end 85.64118 -232.814368)
		(width 0.09525)
		(layer "In4.Cu")
		(net "M_D_CPU1_SA_DQS_DP<6>")
	)
	(arc
		(start 81.51241 -232.819194)
		(mid 81.696185 -232.768422)
		(end 81.881218 -232.814368)
		(width 0.09525)
		(layer "In4.Cu")
		(net "M_D_CPU1_SA_DQS_DP<6>")
	)
	(arc
		(start 83.769708 -232.819194)
		(mid 84.05114 -232.894949)
		(end 84.332572 -232.819194)
		(width 0.09525)
		(layer "In4.Cu")
		(net "M_D_CPU1_SA_DQS_DP<6>")
	)
	(arc
		(start 89.972388 -232.819194)
		(mid 90.156163 -232.768422)
		(end 90.341196 -232.814368)
		(width 0.09525)
		(layer "In4.Cu")
		(net "M_D_CPU1_SA_DQS_DP<6>")
	)
	(arc
		(start 86.212426 -232.819194)
		(mid 86.396201 -232.768422)
		(end 86.581234 -232.814368)
		(width 0.09525)
		(layer "In4.Cu")
		(net "M_D_CPU1_SA_DQS_DP<6>")
	)
	(arc
		(start 88.100916 -232.814368)
		(mid 88.285948 -232.768454)
		(end 88.469724 -232.819194)
		(width 0.09525)
		(layer "In4.Cu")
		(net "M_D_CPU1_SA_DQS_DP<6>")
	)
	(arc
		(start 84.709508 -232.819194)
		(mid 84.99094 -232.894949)
		(end 85.272372 -232.819194)
		(width 0.09525)
		(layer "In4.Cu")
		(net "M_D_CPU1_SA_DQS_DP<6>")
	)
	(arc
		(start 83.4009 -232.814368)
		(mid 83.585932 -232.768454)
		(end 83.769708 -232.819194)
		(width 0.09525)
		(layer "In4.Cu")
		(net "M_D_CPU1_SA_DQS_DP<6>")
	)
	(arc
		(start 90.349578 -232.819194)
		(mid 90.63101 -232.894949)
		(end 90.912442 -232.819194)
		(width 0.09525)
		(layer "In4.Cu")
		(net "M_D_CPU1_SA_DQS_DP<6>")
	)
	(arc
		(start 81.8896 -232.819194)
		(mid 82.171032 -232.894949)
		(end 82.452464 -232.819194)
		(width 0.09525)
		(layer "In4.Cu")
		(net "M_D_CPU1_SA_DQS_DP<6>")
	)
	(arc
		(start 82.829654 -232.819194)
		(mid 83.111086 -232.894949)
		(end 83.392518 -232.819194)
		(width 0.09525)
		(layer "In4.Cu")
		(net "M_D_CPU1_SA_DQS_DP<6>")
	)
	(arc
		(start 80.949546 -232.819194)
		(mid 81.230978 -232.894949)
		(end 81.51241 -232.819194)
		(width 0.09525)
		(layer "In4.Cu")
		(net "M_D_CPU1_SA_DQS_DP<6>")
	)
	(arc
		(start 91.860878 -232.814368)
		(mid 92.013773 -232.76954)
		(end 92.17152 -232.792016)
		(width 0.09525)
		(layer "In4.Cu")
		(net "M_D_CPU1_SA_DQS_DP<6>")
	)
	(arc
		(start 90.920824 -232.814368)
		(mid 91.105856 -232.768454)
		(end 91.289632 -232.819194)
		(width 0.09525)
		(layer "In4.Cu")
		(net "M_D_CPU1_SA_DQS_DP<6>")
	)
	(arc
		(start 80.009746 -232.819194)
		(mid 80.291178 -232.894949)
		(end 80.57261 -232.819194)
		(width 0.09525)
		(layer "In4.Cu")
		(net "M_D_CPU1_SA_DQS_DP<6>")
	)
	(arc
		(start 79.821024 -232.767886)
		(mid 79.91877 -232.781081)
		(end 80.009746 -232.819194)
		(width 0.09525)
		(layer "In4.Cu")
		(net "M_D_CPU1_SA_DQS_DP<6>")
	)
	(arc
		(start 82.460846 -232.814368)
		(mid 82.645878 -232.768454)
		(end 82.829654 -232.819194)
		(width 0.09525)
		(layer "In4.Cu")
		(net "M_D_CPU1_SA_DQS_DP<6>")
	)
	(arc
		(start 88.469724 -232.819194)
		(mid 88.751156 -232.894949)
		(end 89.032588 -232.819194)
		(width 0.09525)
		(layer "In4.Cu")
		(net "M_D_CPU1_SA_DQS_DP<6>")
	)
	(arc
		(start 87.160862 -232.814368)
		(mid 87.345894 -232.768454)
		(end 87.52967 -232.819194)
		(width 0.09525)
		(layer "In4.Cu")
		(net "M_D_CPU1_SA_DQS_DP<6>")
	)
	(segment
		(start 92.507816 -228.55047)
		(end 92.040964 -228.284532)
		(width 0.12954)
		(layer "F.Cu")
		(net "M_D_CPU1_SA_DQS_DP<5>")
	)
	(segment
		(start 90.912442 -227.959412)
		(end 90.920824 -227.954586)
		(width 0.09525)
		(layer "In4.Cu")
		(net "M_D_CPU1_SA_DQS_DP<5>")
	)
	(segment
		(start 45.859954 -202.310492)
		(end 46.709838 -203.160376)
		(width 0.16002)
		(layer "In4.Cu")
		(net "M_D_CPU1_SA_DQS_DP<5>")
	)
	(segment
		(start 81.4197 -227.149406)
		(end 81.451196 -227.167694)
		(width 0.09525)
		(layer "In4.Cu")
		(net "M_D_CPU1_SA_DQS_DP<5>")
	)
	(segment
		(start 32.695896 -202.435206)
		(end 32.969708 -202.161394)
		(width 0.16002)
		(layer "In4.Cu")
		(net "M_D_CPU1_SA_DQS_DP<5>")
	)
	(segment
		(start 35.926268 -202.325986)
		(end 36.83508 -202.325986)
		(width 0.16002)
		(layer "In4.Cu")
		(net "M_D_CPU1_SA_DQS_DP<5>")
	)
	(segment
		(start 41.434512 -202.836526)
		(end 41.919652 -202.836526)
		(width 0.16002)
		(layer "In4.Cu")
		(net "M_D_CPU1_SA_DQS_DP<5>")
	)
	(segment
		(start 37.43198 -202.442826)
		(end 37.54882 -202.325986)
		(width 0.16002)
		(layer "In4.Cu")
		(net "M_D_CPU1_SA_DQS_DP<5>")
	)
	(segment
		(start 77.86497 -221.664784)
		(end 78.16469 -221.964504)
		(width 0.16002)
		(layer "In4.Cu")
		(net "M_D_CPU1_SA_DQS_DP<5>")
	)
	(segment
		(start 79.036164 -223.079818)
		(end 79.069692 -223.099376)
		(width 0.09525)
		(layer "In4.Cu")
		(net "M_D_CPU1_SA_DQS_DP<5>")
	)
	(segment
		(start 38.341808 -202.325986)
		(end 39.176198 -203.160376)
		(width 0.16002)
		(layer "In4.Cu")
		(net "M_D_CPU1_SA_DQS_DP<5>")
	)
	(segment
		(start 90.341196 -227.954586)
		(end 90.349578 -227.959412)
		(width 0.09525)
		(layer "In4.Cu")
		(net "M_D_CPU1_SA_DQS_DP<5>")
	)
	(segment
		(start 88.092534 -227.959412)
		(end 88.100916 -227.954586)
		(width 0.09525)
		(layer "In4.Cu")
		(net "M_D_CPU1_SA_DQS_DP<5>")
	)
	(segment
		(start 43.119548 -201.957686)
		(end 43.472354 -202.310492)
		(width 0.16002)
		(layer "In4.Cu")
		(net "M_D_CPU1_SA_DQS_DP<5>")
	)
	(segment
		(start 50.660808 -201.957686)
		(end 51.013614 -202.310492)
		(width 0.16002)
		(layer "In4.Cu")
		(net "M_D_CPU1_SA_DQS_DP<5>")
	)
	(segment
		(start 81.3816 -227.127308)
		(end 81.4197 -227.149406)
		(width 0.09525)
		(layer "In4.Cu")
		(net "M_D_CPU1_SA_DQS_DP<5>")
	)
	(segment
		(start 91.852496 -227.959412)
		(end 91.860878 -227.954586)
		(width 0.09525)
		(layer "In4.Cu")
		(net "M_D_CPU1_SA_DQS_DP<5>")
	)
	(segment
		(start 87.15248 -227.959412)
		(end 87.160862 -227.954586)
		(width 0.09525)
		(layer "In4.Cu")
		(net "M_D_CPU1_SA_DQS_DP<5>")
	)
	(segment
		(start 82.452464 -227.959412)
		(end 82.460846 -227.954586)
		(width 0.09525)
		(layer "In4.Cu")
		(net "M_D_CPU1_SA_DQS_DP<5>")
	)
	(segment
		(start 81.8515 -227.937314)
		(end 81.8896 -227.959412)
		(width 0.09525)
		(layer "In4.Cu")
		(net "M_D_CPU1_SA_DQS_DP<5>")
	)
	(segment
		(start 83.392518 -227.959412)
		(end 83.4009 -227.954586)
		(width 0.09525)
		(layer "In4.Cu")
		(net "M_D_CPU1_SA_DQS_DP<5>")
	)
	(segment
		(start 80.479646 -225.529394)
		(end 80.512158 -225.54819)
		(width 0.09525)
		(layer "In4.Cu")
		(net "M_D_CPU1_SA_DQS_DP<5>")
	)
	(segment
		(start 49.445672 -202.839066)
		(end 50.327052 -201.957686)
		(width 0.16002)
		(layer "In4.Cu")
		(net "M_D_CPU1_SA_DQS_DP<5>")
	)
	(segment
		(start 34.380424 -202.161394)
		(end 34.860484 -202.161394)
		(width 0.16002)
		(layer "In4.Cu")
		(net "M_D_CPU1_SA_DQS_DP<5>")
	)
	(segment
		(start 36.83508 -202.325986)
		(end 36.95192 -202.442826)
		(width 0.16002)
		(layer "In4.Cu")
		(net "M_D_CPU1_SA_DQS_DP<5>")
	)
	(segment
		(start 33.666684 -202.161394)
		(end 33.783524 -202.278234)
		(width 0.16002)
		(layer "In4.Cu")
		(net "M_D_CPU1_SA_DQS_DP<5>")
	)
	(segment
		(start 33.783524 -202.278234)
		(end 34.263584 -202.278234)
		(width 0.16002)
		(layer "In4.Cu")
		(net "M_D_CPU1_SA_DQS_DP<5>")
	)
	(segment
		(start 79.5401 -223.909382)
		(end 79.570326 -223.926908)
		(width 0.09525)
		(layer "In4.Cu")
		(net "M_D_CPU1_SA_DQS_DP<5>")
	)
	(segment
		(start 79.50073 -223.886522)
		(end 79.5401 -223.909382)
		(width 0.09525)
		(layer "In4.Cu")
		(net "M_D_CPU1_SA_DQS_DP<5>")
	)
	(segment
		(start 46.709838 -203.160376)
		(end 48.626522 -203.160376)
		(width 0.16002)
		(layer "In4.Cu")
		(net "M_D_CPU1_SA_DQS_DP<5>")
	)
	(segment
		(start 41.919652 -202.836526)
		(end 42.798492 -201.957686)
		(width 0.16002)
		(layer "In4.Cu")
		(net "M_D_CPU1_SA_DQS_DP<5>")
	)
	(segment
		(start 51.013614 -202.310492)
		(end 53.431694 -202.310492)
		(width 0.16002)
		(layer "In4.Cu")
		(net "M_D_CPU1_SA_DQS_DP<5>")
	)
	(segment
		(start 50.327052 -201.957686)
		(end 50.660808 -201.957686)
		(width 0.16002)
		(layer "In4.Cu")
		(net "M_D_CPU1_SA_DQS_DP<5>")
	)
	(segment
		(start 39.176198 -203.160376)
		(end 41.110662 -203.160376)
		(width 0.16002)
		(layer "In4.Cu")
		(net "M_D_CPU1_SA_DQS_DP<5>")
	)
	(segment
		(start 48.626522 -203.160376)
		(end 48.947832 -202.839066)
		(width 0.16002)
		(layer "In4.Cu")
		(net "M_D_CPU1_SA_DQS_DP<5>")
	)
	(segment
		(start 78.265274 -221.981268)
		(end 78.56347 -222.279464)
		(width 0.09525)
		(layer "In4.Cu")
		(net "M_D_CPU1_SA_DQS_DP<5>")
	)
	(segment
		(start 80.916526 -226.320096)
		(end 80.949546 -226.3394)
		(width 0.09525)
		(layer "In4.Cu")
		(net "M_D_CPU1_SA_DQS_DP<5>")
	)
	(segment
		(start 78.181454 -221.981268)
		(end 78.265274 -221.981268)
		(width 0.09525)
		(layer "In4.Cu")
		(net "M_D_CPU1_SA_DQS_DP<5>")
	)
	(segment
		(start 57.33923 -202.831446)
		(end 57.66816 -203.160376)
		(width 0.16002)
		(layer "In4.Cu")
		(net "M_D_CPU1_SA_DQS_DP<5>")
	)
	(segment
		(start 53.431694 -202.310492)
		(end 54.254908 -203.133706)
		(width 0.16002)
		(layer "In4.Cu")
		(net "M_D_CPU1_SA_DQS_DP<5>")
	)
	(segment
		(start 79.974694 -224.698814)
		(end 80.009746 -224.719388)
		(width 0.09525)
		(layer "In4.Cu")
		(net "M_D_CPU1_SA_DQS_DP<5>")
	)
	(segment
		(start 80.009746 -224.719388)
		(end 80.041242 -224.737676)
		(width 0.09525)
		(layer "In4.Cu")
		(net "M_D_CPU1_SA_DQS_DP<5>")
	)
	(segment
		(start 77.86497 -221.193614)
		(end 77.86497 -221.664784)
		(width 0.16002)
		(layer "In4.Cu")
		(net "M_D_CPU1_SA_DQS_DP<5>")
	)
	(segment
		(start 54.254908 -203.133706)
		(end 56.222392 -203.133706)
		(width 0.16002)
		(layer "In4.Cu")
		(net "M_D_CPU1_SA_DQS_DP<5>")
	)
	(segment
		(start 56.524652 -202.831446)
		(end 57.33923 -202.831446)
		(width 0.16002)
		(layer "In4.Cu")
		(net "M_D_CPU1_SA_DQS_DP<5>")
	)
	(segment
		(start 43.472354 -202.310492)
		(end 45.859954 -202.310492)
		(width 0.16002)
		(layer "In4.Cu")
		(net "M_D_CPU1_SA_DQS_DP<5>")
	)
	(segment
		(start 35.590988 -201.990706)
		(end 35.926268 -202.325986)
		(width 0.16002)
		(layer "In4.Cu")
		(net "M_D_CPU1_SA_DQS_DP<5>")
	)
	(segment
		(start 36.95192 -202.442826)
		(end 37.43198 -202.442826)
		(width 0.16002)
		(layer "In4.Cu")
		(net "M_D_CPU1_SA_DQS_DP<5>")
	)
	(segment
		(start 86.581234 -227.954586)
		(end 86.589616 -227.959412)
		(width 0.09525)
		(layer "In4.Cu")
		(net "M_D_CPU1_SA_DQS_DP<5>")
	)
	(segment
		(start 32.969708 -202.161394)
		(end 33.666684 -202.161394)
		(width 0.16002)
		(layer "In4.Cu")
		(net "M_D_CPU1_SA_DQS_DP<5>")
	)
	(segment
		(start 34.860484 -202.161394)
		(end 35.031172 -201.990706)
		(width 0.16002)
		(layer "In4.Cu")
		(net "M_D_CPU1_SA_DQS_DP<5>")
	)
	(segment
		(start 92.194888 -228.019102)
		(end 92.040964 -228.284532)
		(width 0.09525)
		(layer "In4.Cu")
		(net "M_D_CPU1_SA_DQS_DP<5>")
	)
	(segment
		(start 85.64118 -227.954586)
		(end 85.649562 -227.959412)
		(width 0.09525)
		(layer "In4.Cu")
		(net "M_D_CPU1_SA_DQS_DP<5>")
	)
	(segment
		(start 42.798492 -201.957686)
		(end 43.119548 -201.957686)
		(width 0.16002)
		(layer "In4.Cu")
		(net "M_D_CPU1_SA_DQS_DP<5>")
	)
	(segment
		(start 80.949546 -226.3394)
		(end 80.982058 -226.358196)
		(width 0.09525)
		(layer "In4.Cu")
		(net "M_D_CPU1_SA_DQS_DP<5>")
	)
	(segment
		(start 79.069692 -223.099376)
		(end 79.103474 -223.118934)
		(width 0.09525)
		(layer "In4.Cu")
		(net "M_D_CPU1_SA_DQS_DP<5>")
	)
	(segment
		(start 59.831732 -203.160376)
		(end 77.86497 -221.193614)
		(width 0.16002)
		(layer "In4.Cu")
		(net "M_D_CPU1_SA_DQS_DP<5>")
	)
	(segment
		(start 34.263584 -202.278234)
		(end 34.380424 -202.161394)
		(width 0.16002)
		(layer "In4.Cu")
		(net "M_D_CPU1_SA_DQS_DP<5>")
	)
	(segment
		(start 80.914494 -226.318826)
		(end 80.916526 -226.320096)
		(width 0.09525)
		(layer "In4.Cu")
		(net "M_D_CPU1_SA_DQS_DP<5>")
	)
	(segment
		(start 78.16469 -221.964504)
		(end 78.181454 -221.981268)
		(width 0.09525)
		(layer "In4.Cu")
		(net "M_D_CPU1_SA_DQS_DP<5>")
	)
	(segment
		(start 78.600046 -222.28937)
		(end 78.631542 -222.307658)
		(width 0.09525)
		(layer "In4.Cu")
		(net "M_D_CPU1_SA_DQS_DP<5>")
	)
	(segment
		(start 35.031172 -201.990706)
		(end 35.590988 -201.990706)
		(width 0.16002)
		(layer "In4.Cu")
		(net "M_D_CPU1_SA_DQS_DP<5>")
	)
	(segment
		(start 80.441546 -225.507296)
		(end 80.479646 -225.529394)
		(width 0.09525)
		(layer "In4.Cu")
		(net "M_D_CPU1_SA_DQS_DP<5>")
	)
	(segment
		(start 78.56347 -222.279464)
		(end 78.600046 -222.28937)
		(width 0.09525)
		(layer "In4.Cu")
		(net "M_D_CPU1_SA_DQS_DP<5>")
	)
	(segment
		(start 92.17152 -227.932234)
		(end 92.194888 -228.019102)
		(width 0.09525)
		(layer "In4.Cu")
		(net "M_D_CPU1_SA_DQS_DP<5>")
	)
	(segment
		(start 41.110662 -203.160376)
		(end 41.434512 -202.836526)
		(width 0.16002)
		(layer "In4.Cu")
		(net "M_D_CPU1_SA_DQS_DP<5>")
	)
	(segment
		(start 56.222392 -203.133706)
		(end 56.524652 -202.831446)
		(width 0.16002)
		(layer "In4.Cu")
		(net "M_D_CPU1_SA_DQS_DP<5>")
	)
	(segment
		(start 48.947832 -202.839066)
		(end 49.445672 -202.839066)
		(width 0.16002)
		(layer "In4.Cu")
		(net "M_D_CPU1_SA_DQS_DP<5>")
	)
	(segment
		(start 37.54882 -202.325986)
		(end 38.341808 -202.325986)
		(width 0.16002)
		(layer "In4.Cu")
		(net "M_D_CPU1_SA_DQS_DP<5>")
	)
	(segment
		(start 57.66816 -203.160376)
		(end 59.831732 -203.160376)
		(width 0.16002)
		(layer "In4.Cu")
		(net "M_D_CPU1_SA_DQS_DP<5>")
	)
	(arc
		(start 81.138776 -226.66452)
		(mid 81.203173 -226.925826)
		(end 81.3816 -227.127308)
		(width 0.09525)
		(layer "In4.Cu")
		(net "M_D_CPU1_SA_DQS_DP<5>")
	)
	(arc
		(start 80.512158 -225.54819)
		(mid 80.627432 -225.682468)
		(end 80.668876 -225.854514)
		(width 0.09525)
		(layer "In4.Cu")
		(net "M_D_CPU1_SA_DQS_DP<5>")
	)
	(arc
		(start 80.198722 -225.044508)
		(mid 80.263119 -225.305814)
		(end 80.441546 -225.507296)
		(width 0.09525)
		(layer "In4.Cu")
		(net "M_D_CPU1_SA_DQS_DP<5>")
	)
	(arc
		(start 83.4009 -227.954586)
		(mid 83.585932 -227.908672)
		(end 83.769708 -227.959412)
		(width 0.09525)
		(layer "In4.Cu")
		(net "M_D_CPU1_SA_DQS_DP<5>")
	)
	(arc
		(start 81.451196 -227.167694)
		(mid 81.566994 -227.302088)
		(end 81.608676 -227.474526)
		(width 0.09525)
		(layer "In4.Cu")
		(net "M_D_CPU1_SA_DQS_DP<5>")
	)
	(arc
		(start 91.860878 -227.954586)
		(mid 92.013773 -227.909758)
		(end 92.17152 -227.932234)
		(width 0.09525)
		(layer "In4.Cu")
		(net "M_D_CPU1_SA_DQS_DP<5>")
	)
	(arc
		(start 87.160862 -227.954586)
		(mid 87.345894 -227.908672)
		(end 87.52967 -227.959412)
		(width 0.09525)
		(layer "In4.Cu")
		(net "M_D_CPU1_SA_DQS_DP<5>")
	)
	(arc
		(start 88.469724 -227.959412)
		(mid 88.751156 -228.035167)
		(end 89.032588 -227.959412)
		(width 0.09525)
		(layer "In4.Cu")
		(net "M_D_CPU1_SA_DQS_DP<5>")
	)
	(arc
		(start 79.258922 -223.424496)
		(mid 79.323024 -223.68524)
		(end 79.50073 -223.886522)
		(width 0.09525)
		(layer "In4.Cu")
		(net "M_D_CPU1_SA_DQS_DP<5>")
	)
	(arc
		(start 85.272372 -227.959412)
		(mid 85.456147 -227.90864)
		(end 85.64118 -227.954586)
		(width 0.09525)
		(layer "In4.Cu")
		(net "M_D_CPU1_SA_DQS_DP<5>")
	)
	(arc
		(start 79.570326 -223.926908)
		(mid 79.687027 -224.061437)
		(end 79.729076 -224.234502)
		(width 0.09525)
		(layer "In4.Cu")
		(net "M_D_CPU1_SA_DQS_DP<5>")
	)
	(arc
		(start 91.289632 -227.959412)
		(mid 91.571064 -228.035167)
		(end 91.852496 -227.959412)
		(width 0.09525)
		(layer "In4.Cu")
		(net "M_D_CPU1_SA_DQS_DP<5>")
	)
	(arc
		(start 86.589616 -227.959412)
		(mid 86.871048 -228.035167)
		(end 87.15248 -227.959412)
		(width 0.09525)
		(layer "In4.Cu")
		(net "M_D_CPU1_SA_DQS_DP<5>")
	)
	(arc
		(start 80.668876 -225.854514)
		(mid 80.734069 -226.117143)
		(end 80.914494 -226.318826)
		(width 0.09525)
		(layer "In4.Cu")
		(net "M_D_CPU1_SA_DQS_DP<5>")
	)
	(arc
		(start 87.52967 -227.959412)
		(mid 87.811102 -228.035167)
		(end 88.092534 -227.959412)
		(width 0.09525)
		(layer "In4.Cu")
		(net "M_D_CPU1_SA_DQS_DP<5>")
	)
	(arc
		(start 89.032588 -227.959412)
		(mid 89.221056 -227.908735)
		(end 89.409524 -227.959412)
		(width 0.09525)
		(layer "In4.Cu")
		(net "M_D_CPU1_SA_DQS_DP<5>")
	)
	(arc
		(start 78.789276 -222.61449)
		(mid 78.854829 -222.877862)
		(end 79.036164 -223.079818)
		(width 0.09525)
		(layer "In4.Cu")
		(net "M_D_CPU1_SA_DQS_DP<5>")
	)
	(arc
		(start 79.729076 -224.234502)
		(mid 79.794269 -224.497131)
		(end 79.974694 -224.698814)
		(width 0.09525)
		(layer "In4.Cu")
		(net "M_D_CPU1_SA_DQS_DP<5>")
	)
	(arc
		(start 90.349578 -227.959412)
		(mid 90.63101 -228.035167)
		(end 90.912442 -227.959412)
		(width 0.09525)
		(layer "In4.Cu")
		(net "M_D_CPU1_SA_DQS_DP<5>")
	)
	(arc
		(start 84.709508 -227.959412)
		(mid 84.99094 -228.035167)
		(end 85.272372 -227.959412)
		(width 0.09525)
		(layer "In4.Cu")
		(net "M_D_CPU1_SA_DQS_DP<5>")
	)
	(arc
		(start 81.8896 -227.959412)
		(mid 82.171032 -228.035167)
		(end 82.452464 -227.959412)
		(width 0.09525)
		(layer "In4.Cu")
		(net "M_D_CPU1_SA_DQS_DP<5>")
	)
	(arc
		(start 84.332572 -227.959412)
		(mid 84.52104 -227.908735)
		(end 84.709508 -227.959412)
		(width 0.09525)
		(layer "In4.Cu")
		(net "M_D_CPU1_SA_DQS_DP<5>")
	)
	(arc
		(start 89.972388 -227.959412)
		(mid 90.156163 -227.90864)
		(end 90.341196 -227.954586)
		(width 0.09525)
		(layer "In4.Cu")
		(net "M_D_CPU1_SA_DQS_DP<5>")
	)
	(arc
		(start 78.631542 -222.307658)
		(mid 78.747566 -222.441979)
		(end 78.789276 -222.61449)
		(width 0.09525)
		(layer "In4.Cu")
		(net "M_D_CPU1_SA_DQS_DP<5>")
	)
	(arc
		(start 83.769708 -227.959412)
		(mid 84.05114 -228.035167)
		(end 84.332572 -227.959412)
		(width 0.09525)
		(layer "In4.Cu")
		(net "M_D_CPU1_SA_DQS_DP<5>")
	)
	(arc
		(start 90.920824 -227.954586)
		(mid 91.105856 -227.908672)
		(end 91.289632 -227.959412)
		(width 0.09525)
		(layer "In4.Cu")
		(net "M_D_CPU1_SA_DQS_DP<5>")
	)
	(arc
		(start 89.409524 -227.959412)
		(mid 89.690956 -228.035167)
		(end 89.972388 -227.959412)
		(width 0.09525)
		(layer "In4.Cu")
		(net "M_D_CPU1_SA_DQS_DP<5>")
	)
	(arc
		(start 85.649562 -227.959412)
		(mid 85.930994 -228.035167)
		(end 86.212426 -227.959412)
		(width 0.09525)
		(layer "In4.Cu")
		(net "M_D_CPU1_SA_DQS_DP<5>")
	)
	(arc
		(start 82.460846 -227.954586)
		(mid 82.645878 -227.908672)
		(end 82.829654 -227.959412)
		(width 0.09525)
		(layer "In4.Cu")
		(net "M_D_CPU1_SA_DQS_DP<5>")
	)
	(arc
		(start 86.212426 -227.959412)
		(mid 86.396201 -227.90864)
		(end 86.581234 -227.954586)
		(width 0.09525)
		(layer "In4.Cu")
		(net "M_D_CPU1_SA_DQS_DP<5>")
	)
	(arc
		(start 81.608676 -227.474526)
		(mid 81.673073 -227.735832)
		(end 81.8515 -227.937314)
		(width 0.09525)
		(layer "In4.Cu")
		(net "M_D_CPU1_SA_DQS_DP<5>")
	)
	(arc
		(start 80.041242 -224.737676)
		(mid 80.15704 -224.87207)
		(end 80.198722 -225.044508)
		(width 0.09525)
		(layer "In4.Cu")
		(net "M_D_CPU1_SA_DQS_DP<5>")
	)
	(arc
		(start 88.100916 -227.954586)
		(mid 88.285948 -227.908672)
		(end 88.469724 -227.959412)
		(width 0.09525)
		(layer "In4.Cu")
		(net "M_D_CPU1_SA_DQS_DP<5>")
	)
	(arc
		(start 80.982058 -226.358196)
		(mid 81.097332 -226.492474)
		(end 81.138776 -226.66452)
		(width 0.09525)
		(layer "In4.Cu")
		(net "M_D_CPU1_SA_DQS_DP<5>")
	)
	(arc
		(start 79.103474 -223.118934)
		(mid 79.217853 -223.253073)
		(end 79.258922 -223.424496)
		(width 0.09525)
		(layer "In4.Cu")
		(net "M_D_CPU1_SA_DQS_DP<5>")
	)
	(arc
		(start 82.829654 -227.959412)
		(mid 83.111086 -228.035167)
		(end 83.392518 -227.959412)
		(width 0.09525)
		(layer "In4.Cu")
		(net "M_D_CPU1_SA_DQS_DP<5>")
	)
	(segment
		(start 91.568016 -246.370348)
		(end 91.10091 -246.10441)
		(width 0.12954)
		(layer "F.Cu")
		(net "M_D_CPU1_SA_DQS_DP<4>")
	)
	(segment
		(start 64.015874 -244.412262)
		(end 64.298068 -244.130068)
		(width 0.16002)
		(layer "In4.Cu")
		(net "M_D_CPU1_SA_DQS_DP<4>")
	)
	(segment
		(start 59.894978 -240.291366)
		(end 60.074302 -240.112042)
		(width 0.16002)
		(layer "In4.Cu")
		(net "M_D_CPU1_SA_DQS_DP<4>")
	)
	(segment
		(start 61.550804 -241.382804)
		(end 62.078108 -241.382804)
		(width 0.16002)
		(layer "In4.Cu")
		(net "M_D_CPU1_SA_DQS_DP<4>")
	)
	(segment
		(start 75.903328 -245.991634)
		(end 75.962256 -246.050562)
		(width 0.09525)
		(layer "In4.Cu")
		(net "M_D_CPU1_SA_DQS_DP<4>")
	)
	(segment
		(start 60.074302 -240.112042)
		(end 60.601606 -240.112042)
		(width 0.16002)
		(layer "In4.Cu")
		(net "M_D_CPU1_SA_DQS_DP<4>")
	)
	(segment
		(start 62.924436 -242.756436)
		(end 63.45174 -242.756436)
		(width 0.16002)
		(layer "In4.Cu")
		(net "M_D_CPU1_SA_DQS_DP<4>")
	)
	(segment
		(start 77.32395 -246.763286)
		(end 77.606906 -246.48033)
		(width 0.09525)
		(layer "In4.Cu")
		(net "M_D_CPU1_SA_DQS_DP<4>")
	)
	(segment
		(start 76.677774 -246.763286)
		(end 77.32395 -246.763286)
		(width 0.09525)
		(layer "In4.Cu")
		(net "M_D_CPU1_SA_DQS_DP<4>")
	)
	(segment
		(start 83.392518 -246.42953)
		(end 83.4009 -246.434356)
		(width 0.09525)
		(layer "In4.Cu")
		(net "M_D_CPU1_SA_DQS_DP<4>")
	)
	(segment
		(start 75.879706 -245.991634)
		(end 75.903328 -245.991634)
		(width 0.09525)
		(layer "In4.Cu")
		(net "M_D_CPU1_SA_DQS_DP<4>")
	)
	(segment
		(start 62.365382 -243.03863)
		(end 62.642242 -243.03863)
		(width 0.16002)
		(layer "In4.Cu")
		(net "M_D_CPU1_SA_DQS_DP<4>")
	)
	(segment
		(start 65.318386 -245.991634)
		(end 75.879706 -245.991634)
		(width 0.16002)
		(layer "In4.Cu")
		(net "M_D_CPU1_SA_DQS_DP<4>")
	)
	(segment
		(start 41.444164 -238.589566)
		(end 41.830752 -238.589566)
		(width 0.16002)
		(layer "In4.Cu")
		(net "M_D_CPU1_SA_DQS_DP<4>")
	)
	(segment
		(start 88.092534 -246.42953)
		(end 88.100916 -246.434356)
		(width 0.09525)
		(layer "In4.Cu")
		(net "M_D_CPU1_SA_DQS_DP<4>")
	)
	(segment
		(start 58.378598 -239.051846)
		(end 59.618118 -240.291366)
		(width 0.16002)
		(layer "In4.Cu")
		(net "M_D_CPU1_SA_DQS_DP<4>")
	)
	(segment
		(start 79.633318 -246.42953)
		(end 79.650082 -246.439182)
		(width 0.09525)
		(layer "In4.Cu")
		(net "M_D_CPU1_SA_DQS_DP<4>")
	)
	(segment
		(start 37.069776 -238.409226)
		(end 39.072566 -238.409226)
		(width 0.16002)
		(layer "In4.Cu")
		(net "M_D_CPU1_SA_DQS_DP<4>")
	)
	(segment
		(start 49.403 -238.589566)
		(end 50.23358 -237.758986)
		(width 0.16002)
		(layer "In4.Cu")
		(net "M_D_CPU1_SA_DQS_DP<4>")
	)
	(segment
		(start 86.581234 -246.434356)
		(end 86.589616 -246.42953)
		(width 0.09525)
		(layer "In4.Cu")
		(net "M_D_CPU1_SA_DQS_DP<4>")
	)
	(segment
		(start 79.053182 -246.440452)
		(end 79.071978 -246.42953)
		(width 0.09525)
		(layer "In4.Cu")
		(net "M_D_CPU1_SA_DQS_DP<4>")
	)
	(segment
		(start 43.454828 -237.410244)
		(end 45.18914 -237.410244)
		(width 0.16002)
		(layer "In4.Cu")
		(net "M_D_CPU1_SA_DQS_DP<4>")
	)
	(segment
		(start 62.451742 -241.756438)
		(end 62.451742 -242.283742)
		(width 0.16002)
		(layer "In4.Cu")
		(net "M_D_CPU1_SA_DQS_DP<4>")
	)
	(segment
		(start 62.078108 -241.382804)
		(end 62.451742 -241.756438)
		(width 0.16002)
		(layer "In4.Cu")
		(net "M_D_CPU1_SA_DQS_DP<4>")
	)
	(segment
		(start 62.169548 -242.565936)
		(end 62.169548 -242.842796)
		(width 0.16002)
		(layer "In4.Cu")
		(net "M_D_CPU1_SA_DQS_DP<4>")
	)
	(segment
		(start 46.039024 -238.260128)
		(end 48.658526 -238.260128)
		(width 0.16002)
		(layer "In4.Cu")
		(net "M_D_CPU1_SA_DQS_DP<4>")
	)
	(segment
		(start 90.846148 -246.39651)
		(end 90.946986 -246.36984)
		(width 0.09525)
		(layer "In4.Cu")
		(net "M_D_CPU1_SA_DQS_DP<4>")
	)
	(segment
		(start 85.64118 -246.434356)
		(end 85.649562 -246.42953)
		(width 0.09525)
		(layer "In4.Cu")
		(net "M_D_CPU1_SA_DQS_DP<4>")
	)
	(segment
		(start 60.795916 -241.192304)
		(end 60.795916 -241.469164)
		(width 0.16002)
		(layer "In4.Cu")
		(net "M_D_CPU1_SA_DQS_DP<4>")
	)
	(segment
		(start 39.072566 -238.409226)
		(end 39.221664 -238.260128)
		(width 0.16002)
		(layer "In4.Cu")
		(net "M_D_CPU1_SA_DQS_DP<4>")
	)
	(segment
		(start 41.114726 -238.260128)
		(end 41.444164 -238.589566)
		(width 0.16002)
		(layer "In4.Cu")
		(net "M_D_CPU1_SA_DQS_DP<4>")
	)
	(segment
		(start 48.658526 -238.260128)
		(end 48.987964 -238.589566)
		(width 0.16002)
		(layer "In4.Cu")
		(net "M_D_CPU1_SA_DQS_DP<4>")
	)
	(segment
		(start 63.54318 -243.939568)
		(end 63.54318 -244.216428)
		(width 0.16002)
		(layer "In4.Cu")
		(net "M_D_CPU1_SA_DQS_DP<4>")
	)
	(segment
		(start 50.998628 -237.410244)
		(end 52.781708 -237.410244)
		(width 0.16002)
		(layer "In4.Cu")
		(net "M_D_CPU1_SA_DQS_DP<4>")
	)
	(segment
		(start 50.23358 -237.758986)
		(end 50.649886 -237.758986)
		(width 0.16002)
		(layer "In4.Cu")
		(net "M_D_CPU1_SA_DQS_DP<4>")
	)
	(segment
		(start 63.825374 -243.657374)
		(end 63.54318 -243.939568)
		(width 0.16002)
		(layer "In4.Cu")
		(net "M_D_CPU1_SA_DQS_DP<4>")
	)
	(segment
		(start 65.199006 -245.031006)
		(end 64.916812 -245.3132)
		(width 0.16002)
		(layer "In4.Cu")
		(net "M_D_CPU1_SA_DQS_DP<4>")
	)
	(segment
		(start 60.97524 -241.01298)
		(end 60.795916 -241.192304)
		(width 0.16002)
		(layer "In4.Cu")
		(net "M_D_CPU1_SA_DQS_DP<4>")
	)
	(segment
		(start 81.881218 -246.434356)
		(end 81.8896 -246.42953)
		(width 0.09525)
		(layer "In4.Cu")
		(net "M_D_CPU1_SA_DQS_DP<4>")
	)
	(segment
		(start 55.246016 -238.642144)
		(end 55.246016 -239.107218)
		(width 0.16002)
		(layer "In4.Cu")
		(net "M_D_CPU1_SA_DQS_DP<4>")
	)
	(segment
		(start 39.221664 -238.260128)
		(end 41.114726 -238.260128)
		(width 0.16002)
		(layer "In4.Cu")
		(net "M_D_CPU1_SA_DQS_DP<4>")
	)
	(segment
		(start 75.962256 -246.050562)
		(end 76.250038 -246.050562)
		(width 0.09525)
		(layer "In4.Cu")
		(net "M_D_CPU1_SA_DQS_DP<4>")
	)
	(segment
		(start 87.15248 -246.42953)
		(end 87.160862 -246.434356)
		(width 0.09525)
		(layer "In4.Cu")
		(net "M_D_CPU1_SA_DQS_DP<4>")
	)
	(segment
		(start 82.452464 -246.42953)
		(end 82.460846 -246.434356)
		(width 0.09525)
		(layer "In4.Cu")
		(net "M_D_CPU1_SA_DQS_DP<4>")
	)
	(segment
		(start 61.26861 -241.664998)
		(end 61.550804 -241.382804)
		(width 0.16002)
		(layer "In4.Cu")
		(net "M_D_CPU1_SA_DQS_DP<4>")
	)
	(segment
		(start 52.781708 -237.410244)
		(end 53.66004 -238.288576)
		(width 0.16002)
		(layer "In4.Cu")
		(net "M_D_CPU1_SA_DQS_DP<4>")
	)
	(segment
		(start 63.825374 -243.13007)
		(end 63.825374 -243.657374)
		(width 0.16002)
		(layer "In4.Cu")
		(net "M_D_CPU1_SA_DQS_DP<4>")
	)
	(segment
		(start 55.246016 -239.107218)
		(end 55.443882 -239.305084)
		(width 0.16002)
		(layer "In4.Cu")
		(net "M_D_CPU1_SA_DQS_DP<4>")
	)
	(segment
		(start 78.131162 -246.42953)
		(end 78.165706 -246.409464)
		(width 0.09525)
		(layer "In4.Cu")
		(net "M_D_CPU1_SA_DQS_DP<4>")
	)
	(segment
		(start 55.724044 -239.305084)
		(end 55.977282 -239.051846)
		(width 0.16002)
		(layer "In4.Cu")
		(net "M_D_CPU1_SA_DQS_DP<4>")
	)
	(segment
		(start 55.977282 -239.051846)
		(end 58.378598 -239.051846)
		(width 0.16002)
		(layer "In4.Cu")
		(net "M_D_CPU1_SA_DQS_DP<4>")
	)
	(segment
		(start 79.607918 -246.414798)
		(end 79.633318 -246.42953)
		(width 0.09525)
		(layer "In4.Cu")
		(net "M_D_CPU1_SA_DQS_DP<4>")
	)
	(segment
		(start 65.199006 -244.503702)
		(end 65.199006 -245.031006)
		(width 0.16002)
		(layer "In4.Cu")
		(net "M_D_CPU1_SA_DQS_DP<4>")
	)
	(segment
		(start 41.830752 -238.589566)
		(end 42.661332 -237.758986)
		(width 0.16002)
		(layer "In4.Cu")
		(net "M_D_CPU1_SA_DQS_DP<4>")
	)
	(segment
		(start 48.987964 -238.589566)
		(end 49.403 -238.589566)
		(width 0.16002)
		(layer "In4.Cu")
		(net "M_D_CPU1_SA_DQS_DP<4>")
	)
	(segment
		(start 59.618118 -240.291366)
		(end 59.894978 -240.291366)
		(width 0.16002)
		(layer "In4.Cu")
		(net "M_D_CPU1_SA_DQS_DP<4>")
	)
	(segment
		(start 76.452984 -246.253508)
		(end 76.452984 -246.538496)
		(width 0.09525)
		(layer "In4.Cu")
		(net "M_D_CPU1_SA_DQS_DP<4>")
	)
	(segment
		(start 60.795916 -241.469164)
		(end 60.99175 -241.664998)
		(width 0.16002)
		(layer "In4.Cu")
		(net "M_D_CPU1_SA_DQS_DP<4>")
	)
	(segment
		(start 76.452984 -246.538496)
		(end 76.677774 -246.763286)
		(width 0.09525)
		(layer "In4.Cu")
		(net "M_D_CPU1_SA_DQS_DP<4>")
	)
	(segment
		(start 90.341196 -246.434356)
		(end 90.349578 -246.42953)
		(width 0.09525)
		(layer "In4.Cu")
		(net "M_D_CPU1_SA_DQS_DP<4>")
	)
	(segment
		(start 50.649886 -237.758986)
		(end 50.998628 -237.410244)
		(width 0.16002)
		(layer "In4.Cu")
		(net "M_D_CPU1_SA_DQS_DP<4>")
	)
	(segment
		(start 55.443882 -239.305084)
		(end 55.724044 -239.305084)
		(width 0.16002)
		(layer "In4.Cu")
		(net "M_D_CPU1_SA_DQS_DP<4>")
	)
	(segment
		(start 62.451742 -242.283742)
		(end 62.169548 -242.565936)
		(width 0.16002)
		(layer "In4.Cu")
		(net "M_D_CPU1_SA_DQS_DP<4>")
	)
	(segment
		(start 54.892448 -238.288576)
		(end 55.246016 -238.642144)
		(width 0.16002)
		(layer "In4.Cu")
		(net "M_D_CPU1_SA_DQS_DP<4>")
	)
	(segment
		(start 60.97524 -240.485676)
		(end 60.97524 -241.01298)
		(width 0.16002)
		(layer "In4.Cu")
		(net "M_D_CPU1_SA_DQS_DP<4>")
	)
	(segment
		(start 64.825372 -244.130068)
		(end 65.199006 -244.503702)
		(width 0.16002)
		(layer "In4.Cu")
		(net "M_D_CPU1_SA_DQS_DP<4>")
	)
	(segment
		(start 63.45174 -242.756436)
		(end 63.825374 -243.13007)
		(width 0.16002)
		(layer "In4.Cu")
		(net "M_D_CPU1_SA_DQS_DP<4>")
	)
	(segment
		(start 45.18914 -237.410244)
		(end 46.039024 -238.260128)
		(width 0.16002)
		(layer "In4.Cu")
		(net "M_D_CPU1_SA_DQS_DP<4>")
	)
	(segment
		(start 77.606906 -246.48033)
		(end 77.943456 -246.48033)
		(width 0.09525)
		(layer "In4.Cu")
		(net "M_D_CPU1_SA_DQS_DP<4>")
	)
	(segment
		(start 63.739014 -244.412262)
		(end 64.015874 -244.412262)
		(width 0.16002)
		(layer "In4.Cu")
		(net "M_D_CPU1_SA_DQS_DP<4>")
	)
	(segment
		(start 36.795964 -238.135414)
		(end 37.069776 -238.409226)
		(width 0.16002)
		(layer "In4.Cu")
		(net "M_D_CPU1_SA_DQS_DP<4>")
	)
	(segment
		(start 64.298068 -244.130068)
		(end 64.825372 -244.130068)
		(width 0.16002)
		(layer "In4.Cu")
		(net "M_D_CPU1_SA_DQS_DP<4>")
	)
	(segment
		(start 60.601606 -240.112042)
		(end 60.97524 -240.485676)
		(width 0.16002)
		(layer "In4.Cu")
		(net "M_D_CPU1_SA_DQS_DP<4>")
	)
	(segment
		(start 76.250038 -246.050562)
		(end 76.452984 -246.253508)
		(width 0.09525)
		(layer "In4.Cu")
		(net "M_D_CPU1_SA_DQS_DP<4>")
	)
	(segment
		(start 42.661332 -237.758986)
		(end 43.106086 -237.758986)
		(width 0.16002)
		(layer "In4.Cu")
		(net "M_D_CPU1_SA_DQS_DP<4>")
	)
	(segment
		(start 62.169548 -242.842796)
		(end 62.365382 -243.03863)
		(width 0.16002)
		(layer "In4.Cu")
		(net "M_D_CPU1_SA_DQS_DP<4>")
	)
	(segment
		(start 62.642242 -243.03863)
		(end 62.924436 -242.756436)
		(width 0.16002)
		(layer "In4.Cu")
		(net "M_D_CPU1_SA_DQS_DP<4>")
	)
	(segment
		(start 53.66004 -238.288576)
		(end 54.892448 -238.288576)
		(width 0.16002)
		(layer "In4.Cu")
		(net "M_D_CPU1_SA_DQS_DP<4>")
	)
	(segment
		(start 64.916812 -245.59006)
		(end 65.318386 -245.991634)
		(width 0.16002)
		(layer "In4.Cu")
		(net "M_D_CPU1_SA_DQS_DP<4>")
	)
	(segment
		(start 63.54318 -244.216428)
		(end 63.739014 -244.412262)
		(width 0.16002)
		(layer "In4.Cu")
		(net "M_D_CPU1_SA_DQS_DP<4>")
	)
	(segment
		(start 90.946986 -246.36984)
		(end 91.10091 -246.10441)
		(width 0.09525)
		(layer "In4.Cu")
		(net "M_D_CPU1_SA_DQS_DP<4>")
	)
	(segment
		(start 60.99175 -241.664998)
		(end 61.26861 -241.664998)
		(width 0.16002)
		(layer "In4.Cu")
		(net "M_D_CPU1_SA_DQS_DP<4>")
	)
	(segment
		(start 64.916812 -245.3132)
		(end 64.916812 -245.59006)
		(width 0.16002)
		(layer "In4.Cu")
		(net "M_D_CPU1_SA_DQS_DP<4>")
	)
	(segment
		(start 43.106086 -237.758986)
		(end 43.454828 -237.410244)
		(width 0.16002)
		(layer "In4.Cu")
		(net "M_D_CPU1_SA_DQS_DP<4>")
	)
	(arc
		(start 90.826336 -246.388636)
		(mid 90.836279 -246.392479)
		(end 90.846148 -246.39651)
		(width 0.09525)
		(layer "In4.Cu")
		(net "M_D_CPU1_SA_DQS_DP<4>")
	)
	(arc
		(start 90.349578 -246.42953)
		(mid 90.583373 -246.355663)
		(end 90.826336 -246.388636)
		(width 0.09525)
		(layer "In4.Cu")
		(net "M_D_CPU1_SA_DQS_DP<4>")
	)
	(arc
		(start 81.8896 -246.42953)
		(mid 82.171032 -246.353775)
		(end 82.452464 -246.42953)
		(width 0.09525)
		(layer "In4.Cu")
		(net "M_D_CPU1_SA_DQS_DP<4>")
	)
	(arc
		(start 78.693772 -246.42953)
		(mid 78.872087 -246.480672)
		(end 79.053182 -246.440452)
		(width 0.09525)
		(layer "In4.Cu")
		(net "M_D_CPU1_SA_DQS_DP<4>")
	)
	(arc
		(start 78.024482 -246.471186)
		(mid 78.07941 -246.45443)
		(end 78.131162 -246.42953)
		(width 0.09525)
		(layer "In4.Cu")
		(net "M_D_CPU1_SA_DQS_DP<4>")
	)
	(arc
		(start 84.709508 -246.42953)
		(mid 84.99094 -246.353775)
		(end 85.272372 -246.42953)
		(width 0.09525)
		(layer "In4.Cu")
		(net "M_D_CPU1_SA_DQS_DP<4>")
	)
	(arc
		(start 88.469724 -246.42953)
		(mid 88.751156 -246.353775)
		(end 89.032588 -246.42953)
		(width 0.09525)
		(layer "In4.Cu")
		(net "M_D_CPU1_SA_DQS_DP<4>")
	)
	(arc
		(start 89.032588 -246.42953)
		(mid 89.221056 -246.480207)
		(end 89.409524 -246.42953)
		(width 0.09525)
		(layer "In4.Cu")
		(net "M_D_CPU1_SA_DQS_DP<4>")
	)
	(arc
		(start 85.649562 -246.42953)
		(mid 85.930994 -246.353775)
		(end 86.212426 -246.42953)
		(width 0.09525)
		(layer "In4.Cu")
		(net "M_D_CPU1_SA_DQS_DP<4>")
	)
	(arc
		(start 82.829654 -246.42953)
		(mid 83.111086 -246.353775)
		(end 83.392518 -246.42953)
		(width 0.09525)
		(layer "In4.Cu")
		(net "M_D_CPU1_SA_DQS_DP<4>")
	)
	(arc
		(start 87.52967 -246.42953)
		(mid 87.811102 -246.353775)
		(end 88.092534 -246.42953)
		(width 0.09525)
		(layer "In4.Cu")
		(net "M_D_CPU1_SA_DQS_DP<4>")
	)
	(arc
		(start 80.57261 -246.42953)
		(mid 80.761078 -246.480207)
		(end 80.949546 -246.42953)
		(width 0.09525)
		(layer "In4.Cu")
		(net "M_D_CPU1_SA_DQS_DP<4>")
	)
	(arc
		(start 84.332572 -246.42953)
		(mid 84.52104 -246.480207)
		(end 84.709508 -246.42953)
		(width 0.09525)
		(layer "In4.Cu")
		(net "M_D_CPU1_SA_DQS_DP<4>")
	)
	(arc
		(start 87.160862 -246.434356)
		(mid 87.345894 -246.48027)
		(end 87.52967 -246.42953)
		(width 0.09525)
		(layer "In4.Cu")
		(net "M_D_CPU1_SA_DQS_DP<4>")
	)
	(arc
		(start 82.460846 -246.434356)
		(mid 82.645878 -246.48027)
		(end 82.829654 -246.42953)
		(width 0.09525)
		(layer "In4.Cu")
		(net "M_D_CPU1_SA_DQS_DP<4>")
	)
	(arc
		(start 77.943456 -246.48033)
		(mid 77.98422 -246.477973)
		(end 78.024482 -246.471186)
		(width 0.09525)
		(layer "In4.Cu")
		(net "M_D_CPU1_SA_DQS_DP<4>")
	)
	(arc
		(start 89.409524 -246.42953)
		(mid 89.690956 -246.353775)
		(end 89.972388 -246.42953)
		(width 0.09525)
		(layer "In4.Cu")
		(net "M_D_CPU1_SA_DQS_DP<4>")
	)
	(arc
		(start 80.949546 -246.42953)
		(mid 81.230978 -246.353775)
		(end 81.51241 -246.42953)
		(width 0.09525)
		(layer "In4.Cu")
		(net "M_D_CPU1_SA_DQS_DP<4>")
	)
	(arc
		(start 88.100916 -246.434356)
		(mid 88.285948 -246.48027)
		(end 88.469724 -246.42953)
		(width 0.09525)
		(layer "In4.Cu")
		(net "M_D_CPU1_SA_DQS_DP<4>")
	)
	(arc
		(start 79.650082 -246.439182)
		(mid 79.831139 -246.480164)
		(end 80.009746 -246.42953)
		(width 0.09525)
		(layer "In4.Cu")
		(net "M_D_CPU1_SA_DQS_DP<4>")
	)
	(arc
		(start 83.769708 -246.42953)
		(mid 84.05114 -246.353775)
		(end 84.332572 -246.42953)
		(width 0.09525)
		(layer "In4.Cu")
		(net "M_D_CPU1_SA_DQS_DP<4>")
	)
	(arc
		(start 89.972388 -246.42953)
		(mid 90.156163 -246.480302)
		(end 90.341196 -246.434356)
		(width 0.09525)
		(layer "In4.Cu")
		(net "M_D_CPU1_SA_DQS_DP<4>")
	)
	(arc
		(start 81.51241 -246.42953)
		(mid 81.696185 -246.480302)
		(end 81.881218 -246.434356)
		(width 0.09525)
		(layer "In4.Cu")
		(net "M_D_CPU1_SA_DQS_DP<4>")
	)
	(arc
		(start 78.165706 -246.409464)
		(mid 78.432232 -246.353527)
		(end 78.693772 -246.42953)
		(width 0.09525)
		(layer "In4.Cu")
		(net "M_D_CPU1_SA_DQS_DP<4>")
	)
	(arc
		(start 79.071978 -246.42953)
		(mid 79.338065 -246.353985)
		(end 79.607918 -246.414798)
		(width 0.09525)
		(layer "In4.Cu")
		(net "M_D_CPU1_SA_DQS_DP<4>")
	)
	(arc
		(start 85.272372 -246.42953)
		(mid 85.456147 -246.480302)
		(end 85.64118 -246.434356)
		(width 0.09525)
		(layer "In4.Cu")
		(net "M_D_CPU1_SA_DQS_DP<4>")
	)
	(arc
		(start 86.212426 -246.42953)
		(mid 86.396201 -246.480302)
		(end 86.581234 -246.434356)
		(width 0.09525)
		(layer "In4.Cu")
		(net "M_D_CPU1_SA_DQS_DP<4>")
	)
	(arc
		(start 80.009746 -246.42953)
		(mid 80.291178 -246.353775)
		(end 80.57261 -246.42953)
		(width 0.09525)
		(layer "In4.Cu")
		(net "M_D_CPU1_SA_DQS_DP<4>")
	)
	(arc
		(start 86.589616 -246.42953)
		(mid 86.871048 -246.353775)
		(end 87.15248 -246.42953)
		(width 0.09525)
		(layer "In4.Cu")
		(net "M_D_CPU1_SA_DQS_DP<4>")
	)
	(arc
		(start 83.4009 -246.434356)
		(mid 83.585932 -246.48027)
		(end 83.769708 -246.42953)
		(width 0.09525)
		(layer "In4.Cu")
		(net "M_D_CPU1_SA_DQS_DP<4>")
	)
	(segment
		(start 91.568016 -241.510312)
		(end 91.10091 -241.244374)
		(width 0.12954)
		(layer "F.Cu")
		(net "M_D_CPU1_SA_DQS_DP<3>")
	)
	(segment
		(start 65.72885 -234.715304)
		(end 65.52057 -234.923584)
		(width 0.16002)
		(layer "In4.Cu")
		(net "M_D_CPU1_SA_DQS_DP<3>")
	)
	(segment
		(start 86.581234 -241.57432)
		(end 86.589616 -241.569494)
		(width 0.09525)
		(layer "In4.Cu")
		(net "M_D_CPU1_SA_DQS_DP<3>")
	)
	(segment
		(start 41.51884 -229.314248)
		(end 41.756076 -229.314248)
		(width 0.16002)
		(layer "In4.Cu")
		(net "M_D_CPU1_SA_DQS_DP<3>")
	)
	(segment
		(start 64.355218 -233.341672)
		(end 64.146938 -233.549952)
		(width 0.16002)
		(layer "In4.Cu")
		(net "M_D_CPU1_SA_DQS_DP<3>")
	)
	(segment
		(start 39.072566 -229.059232)
		(end 39.221664 -228.910134)
		(width 0.16002)
		(layer "In4.Cu")
		(net "M_D_CPU1_SA_DQS_DP<3>")
	)
	(segment
		(start 50.998628 -228.06025)
		(end 52.781708 -228.06025)
		(width 0.16002)
		(layer "In4.Cu")
		(net "M_D_CPU1_SA_DQS_DP<3>")
	)
	(segment
		(start 65.354708 -233.814112)
		(end 65.728596 -234.188)
		(width 0.16002)
		(layer "In4.Cu")
		(net "M_D_CPU1_SA_DQS_DP<3>")
	)
	(segment
		(start 64.146938 -233.549952)
		(end 64.146938 -233.826812)
		(width 0.16002)
		(layer "In4.Cu")
		(net "M_D_CPU1_SA_DQS_DP<3>")
	)
	(segment
		(start 41.114726 -228.910134)
		(end 41.51884 -229.314248)
		(width 0.16002)
		(layer "In4.Cu")
		(net "M_D_CPU1_SA_DQS_DP<3>")
	)
	(segment
		(start 59.880754 -228.919786)
		(end 60.253626 -229.292658)
		(width 0.16002)
		(layer "In4.Cu")
		(net "M_D_CPU1_SA_DQS_DP<3>")
	)
	(segment
		(start 90.846148 -241.536474)
		(end 90.946986 -241.509804)
		(width 0.09525)
		(layer "In4.Cu")
		(net "M_D_CPU1_SA_DQS_DP<3>")
	)
	(segment
		(start 39.221664 -228.910134)
		(end 41.114726 -228.910134)
		(width 0.16002)
		(layer "In4.Cu")
		(net "M_D_CPU1_SA_DQS_DP<3>")
	)
	(segment
		(start 64.146938 -233.826812)
		(end 64.342772 -234.022646)
		(width 0.16002)
		(layer "In4.Cu")
		(net "M_D_CPU1_SA_DQS_DP<3>")
	)
	(segment
		(start 49.3141 -229.328472)
		(end 50.23358 -228.408992)
		(width 0.16002)
		(layer "In4.Cu")
		(net "M_D_CPU1_SA_DQS_DP<3>")
	)
	(segment
		(start 76.787756 -240.903506)
		(end 77.22743 -240.903506)
		(width 0.09525)
		(layer "In4.Cu")
		(net "M_D_CPU1_SA_DQS_DP<3>")
	)
	(segment
		(start 61.233812 -229.69347)
		(end 61.6077 -230.067358)
		(width 0.16002)
		(layer "In4.Cu")
		(net "M_D_CPU1_SA_DQS_DP<3>")
	)
	(segment
		(start 45.934376 -228.910134)
		(end 48.658526 -228.910134)
		(width 0.16002)
		(layer "In4.Cu")
		(net "M_D_CPU1_SA_DQS_DP<3>")
	)
	(segment
		(start 75.955906 -240.357406)
		(end 75.979528 -240.357406)
		(width 0.09525)
		(layer "In4.Cu")
		(net "M_D_CPU1_SA_DQS_DP<3>")
	)
	(segment
		(start 56.799988 -229.277926)
		(end 57.5437 -229.277926)
		(width 0.16002)
		(layer "In4.Cu")
		(net "M_D_CPU1_SA_DQS_DP<3>")
	)
	(segment
		(start 41.756076 -229.314248)
		(end 42.661332 -228.408992)
		(width 0.16002)
		(layer "In4.Cu")
		(net "M_D_CPU1_SA_DQS_DP<3>")
	)
	(segment
		(start 60.253626 -229.292658)
		(end 60.253626 -229.45217)
		(width 0.16002)
		(layer "In4.Cu")
		(net "M_D_CPU1_SA_DQS_DP<3>")
	)
	(segment
		(start 55.574692 -229.249986)
		(end 55.96509 -229.640384)
		(width 0.16002)
		(layer "In4.Cu")
		(net "M_D_CPU1_SA_DQS_DP<3>")
	)
	(segment
		(start 79.632556 -241.569494)
		(end 79.640938 -241.57432)
		(width 0.09525)
		(layer "In4.Cu")
		(net "M_D_CPU1_SA_DQS_DP<3>")
	)
	(segment
		(start 62.96914 -232.649014)
		(end 63.246 -232.649014)
		(width 0.16002)
		(layer "In4.Cu")
		(net "M_D_CPU1_SA_DQS_DP<3>")
	)
	(segment
		(start 45.084492 -228.06025)
		(end 45.934376 -228.910134)
		(width 0.16002)
		(layer "In4.Cu")
		(net "M_D_CPU1_SA_DQS_DP<3>")
	)
	(segment
		(start 90.946986 -241.509804)
		(end 91.10091 -241.244374)
		(width 0.09525)
		(layer "In4.Cu")
		(net "M_D_CPU1_SA_DQS_DP<3>")
	)
	(segment
		(start 62.981332 -231.440736)
		(end 62.981586 -231.96804)
		(width 0.16002)
		(layer "In4.Cu")
		(net "M_D_CPU1_SA_DQS_DP<3>")
	)
	(segment
		(start 42.661332 -228.408992)
		(end 43.106086 -228.408992)
		(width 0.16002)
		(layer "In4.Cu")
		(net "M_D_CPU1_SA_DQS_DP<3>")
	)
	(segment
		(start 77.22743 -240.903506)
		(end 77.817726 -241.493802)
		(width 0.09525)
		(layer "In4.Cu")
		(net "M_D_CPU1_SA_DQS_DP<3>")
	)
	(segment
		(start 63.246 -232.649014)
		(end 63.45428 -232.440734)
		(width 0.16002)
		(layer "In4.Cu")
		(net "M_D_CPU1_SA_DQS_DP<3>")
	)
	(segment
		(start 61.6077 -230.067358)
		(end 61.607954 -230.594408)
		(width 0.16002)
		(layer "In4.Cu")
		(net "M_D_CPU1_SA_DQS_DP<3>")
	)
	(segment
		(start 50.649886 -228.408992)
		(end 50.998628 -228.06025)
		(width 0.16002)
		(layer "In4.Cu")
		(net "M_D_CPU1_SA_DQS_DP<3>")
	)
	(segment
		(start 48.658526 -228.910134)
		(end 49.076864 -229.328472)
		(width 0.16002)
		(layer "In4.Cu")
		(net "M_D_CPU1_SA_DQS_DP<3>")
	)
	(segment
		(start 76.300838 -240.416588)
		(end 76.787756 -240.903506)
		(width 0.09525)
		(layer "In4.Cu")
		(net "M_D_CPU1_SA_DQS_DP<3>")
	)
	(segment
		(start 58.792618 -229.640384)
		(end 58.980832 -229.45217)
		(width 0.16002)
		(layer "In4.Cu")
		(net "M_D_CPU1_SA_DQS_DP<3>")
	)
	(segment
		(start 52.781708 -228.06025)
		(end 53.971444 -229.249986)
		(width 0.16002)
		(layer "In4.Cu")
		(net "M_D_CPU1_SA_DQS_DP<3>")
	)
	(segment
		(start 36.795964 -228.78542)
		(end 37.069776 -229.059232)
		(width 0.16002)
		(layer "In4.Cu")
		(net "M_D_CPU1_SA_DQS_DP<3>")
	)
	(segment
		(start 62.981586 -231.96804)
		(end 62.773306 -232.17632)
		(width 0.16002)
		(layer "In4.Cu")
		(net "M_D_CPU1_SA_DQS_DP<3>")
	)
	(segment
		(start 57.906158 -229.640384)
		(end 58.792618 -229.640384)
		(width 0.16002)
		(layer "In4.Cu")
		(net "M_D_CPU1_SA_DQS_DP<3>")
	)
	(segment
		(start 75.979528 -240.357406)
		(end 76.03871 -240.416588)
		(width 0.09525)
		(layer "In4.Cu")
		(net "M_D_CPU1_SA_DQS_DP<3>")
	)
	(segment
		(start 78.692502 -241.569494)
		(end 78.700884 -241.57432)
		(width 0.09525)
		(layer "In4.Cu")
		(net "M_D_CPU1_SA_DQS_DP<3>")
	)
	(segment
		(start 50.23358 -228.408992)
		(end 50.649886 -228.408992)
		(width 0.16002)
		(layer "In4.Cu")
		(net "M_D_CPU1_SA_DQS_DP<3>")
	)
	(segment
		(start 64.619632 -234.022646)
		(end 64.827912 -233.814366)
		(width 0.16002)
		(layer "In4.Cu")
		(net "M_D_CPU1_SA_DQS_DP<3>")
	)
	(segment
		(start 49.076864 -229.328472)
		(end 49.3141 -229.328472)
		(width 0.16002)
		(layer "In4.Cu")
		(net "M_D_CPU1_SA_DQS_DP<3>")
	)
	(segment
		(start 37.069776 -229.059232)
		(end 39.072566 -229.059232)
		(width 0.16002)
		(layer "In4.Cu")
		(net "M_D_CPU1_SA_DQS_DP<3>")
	)
	(segment
		(start 58.980832 -229.292658)
		(end 59.353704 -228.919786)
		(width 0.16002)
		(layer "In4.Cu")
		(net "M_D_CPU1_SA_DQS_DP<3>")
	)
	(segment
		(start 81.881218 -241.57432)
		(end 81.8896 -241.569494)
		(width 0.09525)
		(layer "In4.Cu")
		(net "M_D_CPU1_SA_DQS_DP<3>")
	)
	(segment
		(start 83.392518 -241.569494)
		(end 83.4009 -241.57432)
		(width 0.09525)
		(layer "In4.Cu")
		(net "M_D_CPU1_SA_DQS_DP<3>")
	)
	(segment
		(start 56.43753 -229.640384)
		(end 56.799988 -229.277926)
		(width 0.16002)
		(layer "In4.Cu")
		(net "M_D_CPU1_SA_DQS_DP<3>")
	)
	(segment
		(start 64.354964 -232.814368)
		(end 64.355218 -233.341672)
		(width 0.16002)
		(layer "In4.Cu")
		(net "M_D_CPU1_SA_DQS_DP<3>")
	)
	(segment
		(start 90.341196 -241.57432)
		(end 90.349578 -241.569494)
		(width 0.09525)
		(layer "In4.Cu")
		(net "M_D_CPU1_SA_DQS_DP<3>")
	)
	(segment
		(start 70.677532 -240.357406)
		(end 75.955906 -240.357406)
		(width 0.16002)
		(layer "In4.Cu")
		(net "M_D_CPU1_SA_DQS_DP<3>")
	)
	(segment
		(start 76.03871 -240.416588)
		(end 76.300838 -240.416588)
		(width 0.09525)
		(layer "In4.Cu")
		(net "M_D_CPU1_SA_DQS_DP<3>")
	)
	(segment
		(start 58.980832 -229.45217)
		(end 58.980832 -229.292658)
		(width 0.16002)
		(layer "In4.Cu")
		(net "M_D_CPU1_SA_DQS_DP<3>")
	)
	(segment
		(start 61.872368 -231.275382)
		(end 62.080648 -231.067102)
		(width 0.16002)
		(layer "In4.Cu")
		(net "M_D_CPU1_SA_DQS_DP<3>")
	)
	(segment
		(start 43.454828 -228.06025)
		(end 45.084492 -228.06025)
		(width 0.16002)
		(layer "In4.Cu")
		(net "M_D_CPU1_SA_DQS_DP<3>")
	)
	(segment
		(start 53.971444 -229.249986)
		(end 55.574692 -229.249986)
		(width 0.16002)
		(layer "In4.Cu")
		(net "M_D_CPU1_SA_DQS_DP<3>")
	)
	(segment
		(start 55.96509 -229.640384)
		(end 56.43753 -229.640384)
		(width 0.16002)
		(layer "In4.Cu")
		(net "M_D_CPU1_SA_DQS_DP<3>")
	)
	(segment
		(start 77.817726 -241.493802)
		(end 78.41107 -241.493802)
		(width 0.09525)
		(layer "In4.Cu")
		(net "M_D_CPU1_SA_DQS_DP<3>")
	)
	(segment
		(start 60.494926 -229.69347)
		(end 61.233812 -229.69347)
		(width 0.16002)
		(layer "In4.Cu")
		(net "M_D_CPU1_SA_DQS_DP<3>")
	)
	(segment
		(start 64.342772 -234.022646)
		(end 64.619632 -234.022646)
		(width 0.16002)
		(layer "In4.Cu")
		(net "M_D_CPU1_SA_DQS_DP<3>")
	)
	(segment
		(start 62.773306 -232.17632)
		(end 62.773306 -232.45318)
		(width 0.16002)
		(layer "In4.Cu")
		(net "M_D_CPU1_SA_DQS_DP<3>")
	)
	(segment
		(start 43.106086 -228.408992)
		(end 43.454828 -228.06025)
		(width 0.16002)
		(layer "In4.Cu")
		(net "M_D_CPU1_SA_DQS_DP<3>")
	)
	(segment
		(start 64.827912 -233.814366)
		(end 65.354708 -233.814112)
		(width 0.16002)
		(layer "In4.Cu")
		(net "M_D_CPU1_SA_DQS_DP<3>")
	)
	(segment
		(start 61.399674 -231.079548)
		(end 61.595508 -231.275382)
		(width 0.16002)
		(layer "In4.Cu")
		(net "M_D_CPU1_SA_DQS_DP<3>")
	)
	(segment
		(start 61.399674 -230.802688)
		(end 61.399674 -231.079548)
		(width 0.16002)
		(layer "In4.Cu")
		(net "M_D_CPU1_SA_DQS_DP<3>")
	)
	(segment
		(start 65.728596 -234.188)
		(end 65.72885 -234.715304)
		(width 0.16002)
		(layer "In4.Cu")
		(net "M_D_CPU1_SA_DQS_DP<3>")
	)
	(segment
		(start 65.52057 -234.923584)
		(end 65.52057 -235.200444)
		(width 0.16002)
		(layer "In4.Cu")
		(net "M_D_CPU1_SA_DQS_DP<3>")
	)
	(segment
		(start 87.15248 -241.569494)
		(end 87.160862 -241.57432)
		(width 0.09525)
		(layer "In4.Cu")
		(net "M_D_CPU1_SA_DQS_DP<3>")
	)
	(segment
		(start 62.607444 -231.066848)
		(end 62.981332 -231.440736)
		(width 0.16002)
		(layer "In4.Cu")
		(net "M_D_CPU1_SA_DQS_DP<3>")
	)
	(segment
		(start 63.981076 -232.44048)
		(end 64.354964 -232.814368)
		(width 0.16002)
		(layer "In4.Cu")
		(net "M_D_CPU1_SA_DQS_DP<3>")
	)
	(segment
		(start 57.5437 -229.277926)
		(end 57.906158 -229.640384)
		(width 0.16002)
		(layer "In4.Cu")
		(net "M_D_CPU1_SA_DQS_DP<3>")
	)
	(segment
		(start 63.45428 -232.440734)
		(end 63.981076 -232.44048)
		(width 0.16002)
		(layer "In4.Cu")
		(net "M_D_CPU1_SA_DQS_DP<3>")
	)
	(segment
		(start 85.64118 -241.57432)
		(end 85.649562 -241.569494)
		(width 0.09525)
		(layer "In4.Cu")
		(net "M_D_CPU1_SA_DQS_DP<3>")
	)
	(segment
		(start 59.353704 -228.919786)
		(end 59.880754 -228.919786)
		(width 0.16002)
		(layer "In4.Cu")
		(net "M_D_CPU1_SA_DQS_DP<3>")
	)
	(segment
		(start 62.080648 -231.067102)
		(end 62.607444 -231.066848)
		(width 0.16002)
		(layer "In4.Cu")
		(net "M_D_CPU1_SA_DQS_DP<3>")
	)
	(segment
		(start 82.452464 -241.569494)
		(end 82.460846 -241.57432)
		(width 0.09525)
		(layer "In4.Cu")
		(net "M_D_CPU1_SA_DQS_DP<3>")
	)
	(segment
		(start 61.595508 -231.275382)
		(end 61.872368 -231.275382)
		(width 0.16002)
		(layer "In4.Cu")
		(net "M_D_CPU1_SA_DQS_DP<3>")
	)
	(segment
		(start 62.773306 -232.45318)
		(end 62.96914 -232.649014)
		(width 0.16002)
		(layer "In4.Cu")
		(net "M_D_CPU1_SA_DQS_DP<3>")
	)
	(segment
		(start 61.607954 -230.594408)
		(end 61.399674 -230.802688)
		(width 0.16002)
		(layer "In4.Cu")
		(net "M_D_CPU1_SA_DQS_DP<3>")
	)
	(segment
		(start 65.52057 -235.200444)
		(end 70.677532 -240.357406)
		(width 0.16002)
		(layer "In4.Cu")
		(net "M_D_CPU1_SA_DQS_DP<3>")
	)
	(segment
		(start 60.253626 -229.45217)
		(end 60.494926 -229.69347)
		(width 0.16002)
		(layer "In4.Cu")
		(net "M_D_CPU1_SA_DQS_DP<3>")
	)
	(segment
		(start 88.092534 -241.569494)
		(end 88.100916 -241.57432)
		(width 0.09525)
		(layer "In4.Cu")
		(net "M_D_CPU1_SA_DQS_DP<3>")
	)
	(arc
		(start 89.032588 -241.569494)
		(mid 89.221056 -241.620171)
		(end 89.409524 -241.569494)
		(width 0.09525)
		(layer "In4.Cu")
		(net "M_D_CPU1_SA_DQS_DP<3>")
	)
	(arc
		(start 78.700884 -241.57432)
		(mid 78.885916 -241.620234)
		(end 79.069692 -241.569494)
		(width 0.09525)
		(layer "In4.Cu")
		(net "M_D_CPU1_SA_DQS_DP<3>")
	)
	(arc
		(start 79.069692 -241.569494)
		(mid 79.351124 -241.493739)
		(end 79.632556 -241.569494)
		(width 0.09525)
		(layer "In4.Cu")
		(net "M_D_CPU1_SA_DQS_DP<3>")
	)
	(arc
		(start 87.52967 -241.569494)
		(mid 87.811102 -241.493739)
		(end 88.092534 -241.569494)
		(width 0.09525)
		(layer "In4.Cu")
		(net "M_D_CPU1_SA_DQS_DP<3>")
	)
	(arc
		(start 90.349578 -241.569494)
		(mid 90.583373 -241.495627)
		(end 90.826336 -241.5286)
		(width 0.09525)
		(layer "In4.Cu")
		(net "M_D_CPU1_SA_DQS_DP<3>")
	)
	(arc
		(start 89.972388 -241.569494)
		(mid 90.156163 -241.620266)
		(end 90.341196 -241.57432)
		(width 0.09525)
		(layer "In4.Cu")
		(net "M_D_CPU1_SA_DQS_DP<3>")
	)
	(arc
		(start 85.649562 -241.569494)
		(mid 85.930994 -241.493739)
		(end 86.212426 -241.569494)
		(width 0.09525)
		(layer "In4.Cu")
		(net "M_D_CPU1_SA_DQS_DP<3>")
	)
	(arc
		(start 87.160862 -241.57432)
		(mid 87.345894 -241.620234)
		(end 87.52967 -241.569494)
		(width 0.09525)
		(layer "In4.Cu")
		(net "M_D_CPU1_SA_DQS_DP<3>")
	)
	(arc
		(start 84.332572 -241.569494)
		(mid 84.52104 -241.620171)
		(end 84.709508 -241.569494)
		(width 0.09525)
		(layer "In4.Cu")
		(net "M_D_CPU1_SA_DQS_DP<3>")
	)
	(arc
		(start 82.460846 -241.57432)
		(mid 82.645878 -241.620234)
		(end 82.829654 -241.569494)
		(width 0.09525)
		(layer "In4.Cu")
		(net "M_D_CPU1_SA_DQS_DP<3>")
	)
	(arc
		(start 78.41107 -241.493802)
		(mid 78.556778 -241.51307)
		(end 78.692502 -241.569494)
		(width 0.09525)
		(layer "In4.Cu")
		(net "M_D_CPU1_SA_DQS_DP<3>")
	)
	(arc
		(start 79.640938 -241.57432)
		(mid 79.82597 -241.620234)
		(end 80.009746 -241.569494)
		(width 0.09525)
		(layer "In4.Cu")
		(net "M_D_CPU1_SA_DQS_DP<3>")
	)
	(arc
		(start 88.100916 -241.57432)
		(mid 88.285948 -241.620234)
		(end 88.469724 -241.569494)
		(width 0.09525)
		(layer "In4.Cu")
		(net "M_D_CPU1_SA_DQS_DP<3>")
	)
	(arc
		(start 85.272372 -241.569494)
		(mid 85.456147 -241.620266)
		(end 85.64118 -241.57432)
		(width 0.09525)
		(layer "In4.Cu")
		(net "M_D_CPU1_SA_DQS_DP<3>")
	)
	(arc
		(start 83.4009 -241.57432)
		(mid 83.585932 -241.620234)
		(end 83.769708 -241.569494)
		(width 0.09525)
		(layer "In4.Cu")
		(net "M_D_CPU1_SA_DQS_DP<3>")
	)
	(arc
		(start 80.57261 -241.569494)
		(mid 80.761078 -241.620171)
		(end 80.949546 -241.569494)
		(width 0.09525)
		(layer "In4.Cu")
		(net "M_D_CPU1_SA_DQS_DP<3>")
	)
	(arc
		(start 84.709508 -241.569494)
		(mid 84.99094 -241.493739)
		(end 85.272372 -241.569494)
		(width 0.09525)
		(layer "In4.Cu")
		(net "M_D_CPU1_SA_DQS_DP<3>")
	)
	(arc
		(start 82.829654 -241.569494)
		(mid 83.111086 -241.493739)
		(end 83.392518 -241.569494)
		(width 0.09525)
		(layer "In4.Cu")
		(net "M_D_CPU1_SA_DQS_DP<3>")
	)
	(arc
		(start 90.826336 -241.5286)
		(mid 90.836279 -241.532443)
		(end 90.846148 -241.536474)
		(width 0.09525)
		(layer "In4.Cu")
		(net "M_D_CPU1_SA_DQS_DP<3>")
	)
	(arc
		(start 83.769708 -241.569494)
		(mid 84.05114 -241.493739)
		(end 84.332572 -241.569494)
		(width 0.09525)
		(layer "In4.Cu")
		(net "M_D_CPU1_SA_DQS_DP<3>")
	)
	(arc
		(start 80.949546 -241.569494)
		(mid 81.230978 -241.493739)
		(end 81.51241 -241.569494)
		(width 0.09525)
		(layer "In4.Cu")
		(net "M_D_CPU1_SA_DQS_DP<3>")
	)
	(arc
		(start 89.409524 -241.569494)
		(mid 89.690956 -241.493739)
		(end 89.972388 -241.569494)
		(width 0.09525)
		(layer "In4.Cu")
		(net "M_D_CPU1_SA_DQS_DP<3>")
	)
	(arc
		(start 80.009746 -241.569494)
		(mid 80.291178 -241.493739)
		(end 80.57261 -241.569494)
		(width 0.09525)
		(layer "In4.Cu")
		(net "M_D_CPU1_SA_DQS_DP<3>")
	)
	(arc
		(start 81.51241 -241.569494)
		(mid 81.696185 -241.620266)
		(end 81.881218 -241.57432)
		(width 0.09525)
		(layer "In4.Cu")
		(net "M_D_CPU1_SA_DQS_DP<3>")
	)
	(arc
		(start 86.589616 -241.569494)
		(mid 86.871048 -241.493739)
		(end 87.15248 -241.569494)
		(width 0.09525)
		(layer "In4.Cu")
		(net "M_D_CPU1_SA_DQS_DP<3>")
	)
	(arc
		(start 81.8896 -241.569494)
		(mid 82.171032 -241.493739)
		(end 82.452464 -241.569494)
		(width 0.09525)
		(layer "In4.Cu")
		(net "M_D_CPU1_SA_DQS_DP<3>")
	)
	(arc
		(start 86.212426 -241.569494)
		(mid 86.396201 -241.620266)
		(end 86.581234 -241.57432)
		(width 0.09525)
		(layer "In4.Cu")
		(net "M_D_CPU1_SA_DQS_DP<3>")
	)
	(arc
		(start 88.469724 -241.569494)
		(mid 88.751156 -241.493739)
		(end 89.032588 -241.569494)
		(width 0.09525)
		(layer "In4.Cu")
		(net "M_D_CPU1_SA_DQS_DP<3>")
	)
	(segment
		(start 91.568016 -236.650276)
		(end 91.10091 -236.384338)
		(width 0.12954)
		(layer "F.Cu")
		(net "M_D_CPU1_SA_DQS_DP<2>")
	)
	(segment
		(start 49.3141 -219.978478)
		(end 50.23358 -219.058998)
		(width 0.16002)
		(layer "In4.Cu")
		(net "M_D_CPU1_SA_DQS_DP<2>")
	)
	(segment
		(start 79.607918 -236.694726)
		(end 79.633318 -236.709458)
		(width 0.09525)
		(layer "In4.Cu")
		(net "M_D_CPU1_SA_DQS_DP<2>")
	)
	(segment
		(start 64.862202 -224.354136)
		(end 64.450214 -224.766124)
		(width 0.16002)
		(layer "In4.Cu")
		(net "M_D_CPU1_SA_DQS_DP<2>")
	)
	(segment
		(start 67.197478 -227.790248)
		(end 74.14133 -234.7341)
		(width 0.16002)
		(layer "In4.Cu")
		(net "M_D_CPU1_SA_DQS_DP<2>")
	)
	(segment
		(start 49.076864 -219.978478)
		(end 49.3141 -219.978478)
		(width 0.16002)
		(layer "In4.Cu")
		(net "M_D_CPU1_SA_DQS_DP<2>")
	)
	(segment
		(start 43.454828 -218.710256)
		(end 45.076364 -218.710256)
		(width 0.16002)
		(layer "In4.Cu")
		(net "M_D_CPU1_SA_DQS_DP<2>")
	)
	(segment
		(start 74.14133 -234.7341)
		(end 75.955906 -234.7341)
		(width 0.16002)
		(layer "In4.Cu")
		(net "M_D_CPU1_SA_DQS_DP<2>")
	)
	(segment
		(start 52.781708 -218.710256)
		(end 53.821076 -219.749624)
		(width 0.16002)
		(layer "In4.Cu")
		(net "M_D_CPU1_SA_DQS_DP<2>")
	)
	(segment
		(start 77.129894 -235.526326)
		(end 78.236572 -236.633004)
		(width 0.09525)
		(layer "In4.Cu")
		(net "M_D_CPU1_SA_DQS_DP<2>")
	)
	(segment
		(start 90.946986 -236.649768)
		(end 91.10091 -236.384338)
		(width 0.09525)
		(layer "In4.Cu")
		(net "M_D_CPU1_SA_DQS_DP<2>")
	)
	(segment
		(start 76.250038 -234.793028)
		(end 76.452984 -234.995974)
		(width 0.09525)
		(layer "In4.Cu")
		(net "M_D_CPU1_SA_DQS_DP<2>")
	)
	(segment
		(start 90.846148 -236.676438)
		(end 90.946986 -236.649768)
		(width 0.09525)
		(layer "In4.Cu")
		(net "M_D_CPU1_SA_DQS_DP<2>")
	)
	(segment
		(start 83.392518 -236.709458)
		(end 83.4009 -236.714284)
		(width 0.09525)
		(layer "In4.Cu")
		(net "M_D_CPU1_SA_DQS_DP<2>")
	)
	(segment
		(start 48.658526 -219.56014)
		(end 49.076864 -219.978478)
		(width 0.16002)
		(layer "In4.Cu")
		(net "M_D_CPU1_SA_DQS_DP<2>")
	)
	(segment
		(start 88.092534 -236.709458)
		(end 88.100916 -236.714284)
		(width 0.09525)
		(layer "In4.Cu")
		(net "M_D_CPU1_SA_DQS_DP<2>")
	)
	(segment
		(start 63.961264 -223.453198)
		(end 64.488568 -223.453452)
		(width 0.16002)
		(layer "In4.Cu")
		(net "M_D_CPU1_SA_DQS_DP<2>")
	)
	(segment
		(start 87.15248 -236.709458)
		(end 87.160862 -236.714284)
		(width 0.09525)
		(layer "In4.Cu")
		(net "M_D_CPU1_SA_DQS_DP<2>")
	)
	(segment
		(start 41.114726 -219.56014)
		(end 41.51884 -219.964254)
		(width 0.16002)
		(layer "In4.Cu")
		(net "M_D_CPU1_SA_DQS_DP<2>")
	)
	(segment
		(start 61.898784 -222.491554)
		(end 62.175644 -222.491554)
		(width 0.16002)
		(layer "In4.Cu")
		(net "M_D_CPU1_SA_DQS_DP<2>")
	)
	(segment
		(start 76.774294 -235.526326)
		(end 77.129894 -235.526326)
		(width 0.09525)
		(layer "In4.Cu")
		(net "M_D_CPU1_SA_DQS_DP<2>")
	)
	(segment
		(start 67.197478 -227.162614)
		(end 67.197478 -227.790248)
		(width 0.16002)
		(layer "In4.Cu")
		(net "M_D_CPU1_SA_DQS_DP<2>")
	)
	(segment
		(start 64.488568 -223.453452)
		(end 64.862456 -223.82734)
		(width 0.16002)
		(layer "In4.Cu")
		(net "M_D_CPU1_SA_DQS_DP<2>")
	)
	(segment
		(start 45.076364 -218.710256)
		(end 45.926248 -219.56014)
		(width 0.16002)
		(layer "In4.Cu")
		(net "M_D_CPU1_SA_DQS_DP<2>")
	)
	(segment
		(start 39.229284 -219.56014)
		(end 41.114726 -219.56014)
		(width 0.16002)
		(layer "In4.Cu")
		(net "M_D_CPU1_SA_DQS_DP<2>")
	)
	(segment
		(start 90.341196 -236.714284)
		(end 90.349578 -236.709458)
		(width 0.09525)
		(layer "In4.Cu")
		(net "M_D_CPU1_SA_DQS_DP<2>")
	)
	(segment
		(start 63.076582 -223.392492)
		(end 63.076582 -223.669352)
		(width 0.16002)
		(layer "In4.Cu")
		(net "M_D_CPU1_SA_DQS_DP<2>")
	)
	(segment
		(start 60.09513 -220.318584)
		(end 61.63691 -221.860364)
		(width 0.16002)
		(layer "In4.Cu")
		(net "M_D_CPU1_SA_DQS_DP<2>")
	)
	(segment
		(start 78.236572 -236.633004)
		(end 78.411832 -236.633004)
		(width 0.09525)
		(layer "In4.Cu")
		(net "M_D_CPU1_SA_DQS_DP<2>")
	)
	(segment
		(start 66.647314 -226.61245)
		(end 67.197478 -227.162614)
		(width 0.16002)
		(layer "In4.Cu")
		(net "M_D_CPU1_SA_DQS_DP<2>")
	)
	(segment
		(start 75.955906 -234.7341)
		(end 75.979528 -234.7341)
		(width 0.09525)
		(layer "In4.Cu")
		(net "M_D_CPU1_SA_DQS_DP<2>")
	)
	(segment
		(start 37.069776 -219.709238)
		(end 39.080186 -219.709238)
		(width 0.16002)
		(layer "In4.Cu")
		(net "M_D_CPU1_SA_DQS_DP<2>")
	)
	(segment
		(start 50.23358 -219.058998)
		(end 50.649886 -219.058998)
		(width 0.16002)
		(layer "In4.Cu")
		(net "M_D_CPU1_SA_DQS_DP<2>")
	)
	(segment
		(start 86.581234 -236.714284)
		(end 86.589616 -236.709458)
		(width 0.09525)
		(layer "In4.Cu")
		(net "M_D_CPU1_SA_DQS_DP<2>")
	)
	(segment
		(start 63.488824 -222.453708)
		(end 63.48857 -222.980504)
		(width 0.16002)
		(layer "In4.Cu")
		(net "M_D_CPU1_SA_DQS_DP<2>")
	)
	(segment
		(start 39.080186 -219.709238)
		(end 39.229284 -219.56014)
		(width 0.16002)
		(layer "In4.Cu")
		(net "M_D_CPU1_SA_DQS_DP<2>")
	)
	(segment
		(start 41.756076 -219.964254)
		(end 42.661332 -219.058998)
		(width 0.16002)
		(layer "In4.Cu")
		(net "M_D_CPU1_SA_DQS_DP<2>")
	)
	(segment
		(start 76.038456 -234.793028)
		(end 76.250038 -234.793028)
		(width 0.09525)
		(layer "In4.Cu")
		(net "M_D_CPU1_SA_DQS_DP<2>")
	)
	(segment
		(start 66.236088 -225.200972)
		(end 66.235834 -225.727768)
		(width 0.16002)
		(layer "In4.Cu")
		(net "M_D_CPU1_SA_DQS_DP<2>")
	)
	(segment
		(start 41.51884 -219.964254)
		(end 41.756076 -219.964254)
		(width 0.16002)
		(layer "In4.Cu")
		(net "M_D_CPU1_SA_DQS_DP<2>")
	)
	(segment
		(start 61.63691 -221.860364)
		(end 61.63691 -222.22968)
		(width 0.16002)
		(layer "In4.Cu")
		(net "M_D_CPU1_SA_DQS_DP<2>")
	)
	(segment
		(start 63.48857 -222.980504)
		(end 63.076582 -223.392492)
		(width 0.16002)
		(layer "In4.Cu")
		(net "M_D_CPU1_SA_DQS_DP<2>")
	)
	(segment
		(start 75.979528 -234.7341)
		(end 76.038456 -234.793028)
		(width 0.09525)
		(layer "In4.Cu")
		(net "M_D_CPU1_SA_DQS_DP<2>")
	)
	(segment
		(start 81.881218 -236.714284)
		(end 81.8896 -236.709458)
		(width 0.09525)
		(layer "In4.Cu")
		(net "M_D_CPU1_SA_DQS_DP<2>")
	)
	(segment
		(start 43.106086 -219.058998)
		(end 43.454828 -218.710256)
		(width 0.16002)
		(layer "In4.Cu")
		(net "M_D_CPU1_SA_DQS_DP<2>")
	)
	(segment
		(start 66.235834 -225.727768)
		(end 65.823846 -226.139756)
		(width 0.16002)
		(layer "In4.Cu")
		(net "M_D_CPU1_SA_DQS_DP<2>")
	)
	(segment
		(start 64.922908 -225.238818)
		(end 65.334896 -224.82683)
		(width 0.16002)
		(layer "In4.Cu")
		(net "M_D_CPU1_SA_DQS_DP<2>")
	)
	(segment
		(start 64.862456 -223.82734)
		(end 64.862202 -224.354136)
		(width 0.16002)
		(layer "In4.Cu")
		(net "M_D_CPU1_SA_DQS_DP<2>")
	)
	(segment
		(start 65.823846 -226.416616)
		(end 66.01968 -226.61245)
		(width 0.16002)
		(layer "In4.Cu")
		(net "M_D_CPU1_SA_DQS_DP<2>")
	)
	(segment
		(start 85.64118 -236.714284)
		(end 85.649562 -236.709458)
		(width 0.09525)
		(layer "In4.Cu")
		(net "M_D_CPU1_SA_DQS_DP<2>")
	)
	(segment
		(start 53.821076 -219.749624)
		(end 54.700424 -219.749624)
		(width 0.16002)
		(layer "In4.Cu")
		(net "M_D_CPU1_SA_DQS_DP<2>")
	)
	(segment
		(start 76.452984 -235.205016)
		(end 76.774294 -235.526326)
		(width 0.09525)
		(layer "In4.Cu")
		(net "M_D_CPU1_SA_DQS_DP<2>")
	)
	(segment
		(start 54.700424 -219.749624)
		(end 55.269384 -220.318584)
		(width 0.16002)
		(layer "In4.Cu")
		(net "M_D_CPU1_SA_DQS_DP<2>")
	)
	(segment
		(start 64.450214 -225.042984)
		(end 64.646048 -225.238818)
		(width 0.16002)
		(layer "In4.Cu")
		(net "M_D_CPU1_SA_DQS_DP<2>")
	)
	(segment
		(start 50.998628 -218.710256)
		(end 52.781708 -218.710256)
		(width 0.16002)
		(layer "In4.Cu")
		(net "M_D_CPU1_SA_DQS_DP<2>")
	)
	(segment
		(start 82.452464 -236.709458)
		(end 82.460846 -236.714284)
		(width 0.09525)
		(layer "In4.Cu")
		(net "M_D_CPU1_SA_DQS_DP<2>")
	)
	(segment
		(start 63.076582 -223.669352)
		(end 63.272416 -223.865186)
		(width 0.16002)
		(layer "In4.Cu")
		(net "M_D_CPU1_SA_DQS_DP<2>")
	)
	(segment
		(start 65.823846 -226.139756)
		(end 65.823846 -226.416616)
		(width 0.16002)
		(layer "In4.Cu")
		(net "M_D_CPU1_SA_DQS_DP<2>")
	)
	(segment
		(start 61.63691 -222.22968)
		(end 61.898784 -222.491554)
		(width 0.16002)
		(layer "In4.Cu")
		(net "M_D_CPU1_SA_DQS_DP<2>")
	)
	(segment
		(start 42.661332 -219.058998)
		(end 43.106086 -219.058998)
		(width 0.16002)
		(layer "In4.Cu")
		(net "M_D_CPU1_SA_DQS_DP<2>")
	)
	(segment
		(start 65.334896 -224.82683)
		(end 65.8622 -224.827084)
		(width 0.16002)
		(layer "In4.Cu")
		(net "M_D_CPU1_SA_DQS_DP<2>")
	)
	(segment
		(start 55.269384 -220.318584)
		(end 60.09513 -220.318584)
		(width 0.16002)
		(layer "In4.Cu")
		(net "M_D_CPU1_SA_DQS_DP<2>")
	)
	(segment
		(start 50.649886 -219.058998)
		(end 50.998628 -218.710256)
		(width 0.16002)
		(layer "In4.Cu")
		(net "M_D_CPU1_SA_DQS_DP<2>")
	)
	(segment
		(start 65.8622 -224.827084)
		(end 66.236088 -225.200972)
		(width 0.16002)
		(layer "In4.Cu")
		(net "M_D_CPU1_SA_DQS_DP<2>")
	)
	(segment
		(start 62.587632 -222.079566)
		(end 63.114936 -222.07982)
		(width 0.16002)
		(layer "In4.Cu")
		(net "M_D_CPU1_SA_DQS_DP<2>")
	)
	(segment
		(start 76.452984 -234.995974)
		(end 76.452984 -235.205016)
		(width 0.09525)
		(layer "In4.Cu")
		(net "M_D_CPU1_SA_DQS_DP<2>")
	)
	(segment
		(start 79.633318 -236.709458)
		(end 79.650082 -236.71911)
		(width 0.09525)
		(layer "In4.Cu")
		(net "M_D_CPU1_SA_DQS_DP<2>")
	)
	(segment
		(start 45.926248 -219.56014)
		(end 48.658526 -219.56014)
		(width 0.16002)
		(layer "In4.Cu")
		(net "M_D_CPU1_SA_DQS_DP<2>")
	)
	(segment
		(start 63.549276 -223.865186)
		(end 63.961264 -223.453198)
		(width 0.16002)
		(layer "In4.Cu")
		(net "M_D_CPU1_SA_DQS_DP<2>")
	)
	(segment
		(start 64.646048 -225.238818)
		(end 64.922908 -225.238818)
		(width 0.16002)
		(layer "In4.Cu")
		(net "M_D_CPU1_SA_DQS_DP<2>")
	)
	(segment
		(start 66.01968 -226.61245)
		(end 66.647314 -226.61245)
		(width 0.16002)
		(layer "In4.Cu")
		(net "M_D_CPU1_SA_DQS_DP<2>")
	)
	(segment
		(start 63.272416 -223.865186)
		(end 63.549276 -223.865186)
		(width 0.16002)
		(layer "In4.Cu")
		(net "M_D_CPU1_SA_DQS_DP<2>")
	)
	(segment
		(start 63.114936 -222.07982)
		(end 63.488824 -222.453708)
		(width 0.16002)
		(layer "In4.Cu")
		(net "M_D_CPU1_SA_DQS_DP<2>")
	)
	(segment
		(start 79.053182 -236.72038)
		(end 79.071978 -236.709458)
		(width 0.09525)
		(layer "In4.Cu")
		(net "M_D_CPU1_SA_DQS_DP<2>")
	)
	(segment
		(start 62.175644 -222.491554)
		(end 62.587632 -222.079566)
		(width 0.16002)
		(layer "In4.Cu")
		(net "M_D_CPU1_SA_DQS_DP<2>")
	)
	(segment
		(start 64.450214 -224.766124)
		(end 64.450214 -225.042984)
		(width 0.16002)
		(layer "In4.Cu")
		(net "M_D_CPU1_SA_DQS_DP<2>")
	)
	(segment
		(start 36.795964 -219.435426)
		(end 37.069776 -219.709238)
		(width 0.16002)
		(layer "In4.Cu")
		(net "M_D_CPU1_SA_DQS_DP<2>")
	)
	(arc
		(start 78.693772 -236.709458)
		(mid 78.872087 -236.7606)
		(end 79.053182 -236.72038)
		(width 0.09525)
		(layer "In4.Cu")
		(net "M_D_CPU1_SA_DQS_DP<2>")
	)
	(arc
		(start 87.160862 -236.714284)
		(mid 87.345894 -236.760198)
		(end 87.52967 -236.709458)
		(width 0.09525)
		(layer "In4.Cu")
		(net "M_D_CPU1_SA_DQS_DP<2>")
	)
	(arc
		(start 88.469724 -236.709458)
		(mid 88.751156 -236.633703)
		(end 89.032588 -236.709458)
		(width 0.09525)
		(layer "In4.Cu")
		(net "M_D_CPU1_SA_DQS_DP<2>")
	)
	(arc
		(start 81.8896 -236.709458)
		(mid 82.171032 -236.633703)
		(end 82.452464 -236.709458)
		(width 0.09525)
		(layer "In4.Cu")
		(net "M_D_CPU1_SA_DQS_DP<2>")
	)
	(arc
		(start 78.411832 -236.633004)
		(mid 78.557875 -236.65254)
		(end 78.693772 -236.709458)
		(width 0.09525)
		(layer "In4.Cu")
		(net "M_D_CPU1_SA_DQS_DP<2>")
	)
	(arc
		(start 80.949546 -236.709458)
		(mid 81.230978 -236.633703)
		(end 81.51241 -236.709458)
		(width 0.09525)
		(layer "In4.Cu")
		(net "M_D_CPU1_SA_DQS_DP<2>")
	)
	(arc
		(start 90.349578 -236.709458)
		(mid 90.583373 -236.635591)
		(end 90.826336 -236.668564)
		(width 0.09525)
		(layer "In4.Cu")
		(net "M_D_CPU1_SA_DQS_DP<2>")
	)
	(arc
		(start 85.272372 -236.709458)
		(mid 85.456147 -236.76023)
		(end 85.64118 -236.714284)
		(width 0.09525)
		(layer "In4.Cu")
		(net "M_D_CPU1_SA_DQS_DP<2>")
	)
	(arc
		(start 84.709508 -236.709458)
		(mid 84.99094 -236.633703)
		(end 85.272372 -236.709458)
		(width 0.09525)
		(layer "In4.Cu")
		(net "M_D_CPU1_SA_DQS_DP<2>")
	)
	(arc
		(start 88.100916 -236.714284)
		(mid 88.285948 -236.760198)
		(end 88.469724 -236.709458)
		(width 0.09525)
		(layer "In4.Cu")
		(net "M_D_CPU1_SA_DQS_DP<2>")
	)
	(arc
		(start 86.589616 -236.709458)
		(mid 86.871048 -236.633703)
		(end 87.15248 -236.709458)
		(width 0.09525)
		(layer "In4.Cu")
		(net "M_D_CPU1_SA_DQS_DP<2>")
	)
	(arc
		(start 86.212426 -236.709458)
		(mid 86.396201 -236.76023)
		(end 86.581234 -236.714284)
		(width 0.09525)
		(layer "In4.Cu")
		(net "M_D_CPU1_SA_DQS_DP<2>")
	)
	(arc
		(start 82.829654 -236.709458)
		(mid 83.111086 -236.633703)
		(end 83.392518 -236.709458)
		(width 0.09525)
		(layer "In4.Cu")
		(net "M_D_CPU1_SA_DQS_DP<2>")
	)
	(arc
		(start 83.4009 -236.714284)
		(mid 83.585932 -236.760198)
		(end 83.769708 -236.709458)
		(width 0.09525)
		(layer "In4.Cu")
		(net "M_D_CPU1_SA_DQS_DP<2>")
	)
	(arc
		(start 87.52967 -236.709458)
		(mid 87.811102 -236.633703)
		(end 88.092534 -236.709458)
		(width 0.09525)
		(layer "In4.Cu")
		(net "M_D_CPU1_SA_DQS_DP<2>")
	)
	(arc
		(start 83.769708 -236.709458)
		(mid 84.05114 -236.633703)
		(end 84.332572 -236.709458)
		(width 0.09525)
		(layer "In4.Cu")
		(net "M_D_CPU1_SA_DQS_DP<2>")
	)
	(arc
		(start 89.409524 -236.709458)
		(mid 89.690956 -236.633703)
		(end 89.972388 -236.709458)
		(width 0.09525)
		(layer "In4.Cu")
		(net "M_D_CPU1_SA_DQS_DP<2>")
	)
	(arc
		(start 79.650082 -236.71911)
		(mid 79.831139 -236.760092)
		(end 80.009746 -236.709458)
		(width 0.09525)
		(layer "In4.Cu")
		(net "M_D_CPU1_SA_DQS_DP<2>")
	)
	(arc
		(start 85.649562 -236.709458)
		(mid 85.930994 -236.633703)
		(end 86.212426 -236.709458)
		(width 0.09525)
		(layer "In4.Cu")
		(net "M_D_CPU1_SA_DQS_DP<2>")
	)
	(arc
		(start 81.51241 -236.709458)
		(mid 81.696185 -236.76023)
		(end 81.881218 -236.714284)
		(width 0.09525)
		(layer "In4.Cu")
		(net "M_D_CPU1_SA_DQS_DP<2>")
	)
	(arc
		(start 90.826336 -236.668564)
		(mid 90.836279 -236.672407)
		(end 90.846148 -236.676438)
		(width 0.09525)
		(layer "In4.Cu")
		(net "M_D_CPU1_SA_DQS_DP<2>")
	)
	(arc
		(start 89.032588 -236.709458)
		(mid 89.221056 -236.760135)
		(end 89.409524 -236.709458)
		(width 0.09525)
		(layer "In4.Cu")
		(net "M_D_CPU1_SA_DQS_DP<2>")
	)
	(arc
		(start 80.57261 -236.709458)
		(mid 80.761078 -236.760135)
		(end 80.949546 -236.709458)
		(width 0.09525)
		(layer "In4.Cu")
		(net "M_D_CPU1_SA_DQS_DP<2>")
	)
	(arc
		(start 79.071978 -236.709458)
		(mid 79.338065 -236.633913)
		(end 79.607918 -236.694726)
		(width 0.09525)
		(layer "In4.Cu")
		(net "M_D_CPU1_SA_DQS_DP<2>")
	)
	(arc
		(start 82.460846 -236.714284)
		(mid 82.645878 -236.760198)
		(end 82.829654 -236.709458)
		(width 0.09525)
		(layer "In4.Cu")
		(net "M_D_CPU1_SA_DQS_DP<2>")
	)
	(arc
		(start 89.972388 -236.709458)
		(mid 90.156163 -236.76023)
		(end 90.341196 -236.714284)
		(width 0.09525)
		(layer "In4.Cu")
		(net "M_D_CPU1_SA_DQS_DP<2>")
	)
	(arc
		(start 80.009746 -236.709458)
		(mid 80.291178 -236.633703)
		(end 80.57261 -236.709458)
		(width 0.09525)
		(layer "In4.Cu")
		(net "M_D_CPU1_SA_DQS_DP<2>")
	)
	(arc
		(start 84.332572 -236.709458)
		(mid 84.52104 -236.760135)
		(end 84.709508 -236.709458)
		(width 0.09525)
		(layer "In4.Cu")
		(net "M_D_CPU1_SA_DQS_DP<2>")
	)
	(segment
		(start 91.568016 -231.79024)
		(end 91.10091 -231.524302)
		(width 0.12954)
		(layer "F.Cu")
		(net "M_D_CPU1_SA_DQS_DP<1>")
	)
	(segment
		(start 71.805546 -222.8088)
		(end 73.67651 -224.679764)
		(width 0.16002)
		(layer "In4.Cu")
		(net "M_D_CPU1_SA_DQS_DP<1>")
	)
	(segment
		(start 76.434188 -228.940868)
		(end 76.450952 -228.957632)
		(width 0.09525)
		(layer "In4.Cu")
		(net "M_D_CPU1_SA_DQS_DP<1>")
	)
	(segment
		(start 69.164962 -219.150692)
		(end 69.164962 -219.677996)
		(width 0.16002)
		(layer "In4.Cu")
		(net "M_D_CPU1_SA_DQS_DP<1>")
	)
	(segment
		(start 68.264024 -218.777058)
		(end 68.791328 -218.777058)
		(width 0.16002)
		(layer "In4.Cu")
		(net "M_D_CPU1_SA_DQS_DP<1>")
	)
	(segment
		(start 79.632556 -231.849422)
		(end 79.640938 -231.854248)
		(width 0.09525)
		(layer "In4.Cu")
		(net "M_D_CPU1_SA_DQS_DP<1>")
	)
	(segment
		(start 69.530976 -220.25737)
		(end 69.637656 -220.15069)
		(width 0.16002)
		(layer "In4.Cu")
		(net "M_D_CPU1_SA_DQS_DP<1>")
	)
	(segment
		(start 37.069776 -210.359244)
		(end 39.09949 -210.359244)
		(width 0.16002)
		(layer "In4.Cu")
		(net "M_D_CPU1_SA_DQS_DP<1>")
	)
	(segment
		(start 49.40935 -210.554824)
		(end 50.23993 -209.724244)
		(width 0.16002)
		(layer "In4.Cu")
		(net "M_D_CPU1_SA_DQS_DP<1>")
	)
	(segment
		(start 66.311018 -217.037412)
		(end 66.311018 -217.314272)
		(width 0.16002)
		(layer "In4.Cu")
		(net "M_D_CPU1_SA_DQS_DP<1>")
	)
	(segment
		(start 76.450952 -229.040436)
		(end 76.859638 -229.449376)
		(width 0.09525)
		(layer "In4.Cu")
		(net "M_D_CPU1_SA_DQS_DP<1>")
	)
	(segment
		(start 66.506852 -217.510106)
		(end 66.783712 -217.510106)
		(width 0.16002)
		(layer "In4.Cu")
		(net "M_D_CPU1_SA_DQS_DP<1>")
	)
	(segment
		(start 67.68465 -218.687904)
		(end 67.880484 -218.883738)
		(width 0.16002)
		(layer "In4.Cu")
		(net "M_D_CPU1_SA_DQS_DP<1>")
	)
	(segment
		(start 63.563754 -214.290148)
		(end 63.563754 -214.567008)
		(width 0.16002)
		(layer "In4.Cu")
		(net "M_D_CPU1_SA_DQS_DP<1>")
	)
	(segment
		(start 81.881218 -231.854248)
		(end 81.8896 -231.849422)
		(width 0.09525)
		(layer "In4.Cu")
		(net "M_D_CPU1_SA_DQS_DP<1>")
	)
	(segment
		(start 65.13322 -216.136474)
		(end 65.41008 -216.136474)
		(width 0.16002)
		(layer "In4.Cu")
		(net "M_D_CPU1_SA_DQS_DP<1>")
	)
	(segment
		(start 85.64118 -231.854248)
		(end 85.649562 -231.849422)
		(width 0.09525)
		(layer "In4.Cu")
		(net "M_D_CPU1_SA_DQS_DP<1>")
	)
	(segment
		(start 66.890392 -217.403426)
		(end 67.417696 -217.403426)
		(width 0.16002)
		(layer "In4.Cu")
		(net "M_D_CPU1_SA_DQS_DP<1>")
	)
	(segment
		(start 88.092534 -231.849422)
		(end 88.100916 -231.854248)
		(width 0.09525)
		(layer "In4.Cu")
		(net "M_D_CPU1_SA_DQS_DP<1>")
	)
	(segment
		(start 65.044066 -215.029796)
		(end 65.044066 -215.5571)
		(width 0.16002)
		(layer "In4.Cu")
		(net "M_D_CPU1_SA_DQS_DP<1>")
	)
	(segment
		(start 65.51676 -216.029794)
		(end 66.044064 -216.029794)
		(width 0.16002)
		(layer "In4.Cu")
		(net "M_D_CPU1_SA_DQS_DP<1>")
	)
	(segment
		(start 70.627748 -221.631002)
		(end 70.904608 -221.631002)
		(width 0.16002)
		(layer "In4.Cu")
		(net "M_D_CPU1_SA_DQS_DP<1>")
	)
	(segment
		(start 64.143128 -214.656162)
		(end 64.670432 -214.656162)
		(width 0.16002)
		(layer "In4.Cu")
		(net "M_D_CPU1_SA_DQS_DP<1>")
	)
	(segment
		(start 62.385956 -213.38921)
		(end 62.662816 -213.38921)
		(width 0.16002)
		(layer "In4.Cu")
		(net "M_D_CPU1_SA_DQS_DP<1>")
	)
	(segment
		(start 53.74386 -210.344004)
		(end 54.486048 -210.344004)
		(width 0.16002)
		(layer "In4.Cu")
		(net "M_D_CPU1_SA_DQS_DP<1>")
	)
	(segment
		(start 76.450952 -228.957632)
		(end 76.450952 -229.040436)
		(width 0.09525)
		(layer "In4.Cu")
		(net "M_D_CPU1_SA_DQS_DP<1>")
	)
	(segment
		(start 83.392518 -231.849422)
		(end 83.4009 -231.854248)
		(width 0.09525)
		(layer "In4.Cu")
		(net "M_D_CPU1_SA_DQS_DP<1>")
	)
	(segment
		(start 78.61173 -230.149146)
		(end 78.95209 -230.489506)
		(width 0.09525)
		(layer "In4.Cu")
		(net "M_D_CPU1_SA_DQS_DP<1>")
	)
	(segment
		(start 43.112436 -209.724244)
		(end 43.476418 -209.360262)
		(width 0.16002)
		(layer "In4.Cu")
		(net "M_D_CPU1_SA_DQS_DP<1>")
	)
	(segment
		(start 39.248588 -210.210146)
		(end 41.093136 -210.210146)
		(width 0.16002)
		(layer "In4.Cu")
		(net "M_D_CPU1_SA_DQS_DP<1>")
	)
	(segment
		(start 64.670432 -214.656162)
		(end 65.044066 -215.029796)
		(width 0.16002)
		(layer "In4.Cu")
		(net "M_D_CPU1_SA_DQS_DP<1>")
	)
	(segment
		(start 67.68465 -218.411044)
		(end 67.68465 -218.687904)
		(width 0.16002)
		(layer "In4.Cu")
		(net "M_D_CPU1_SA_DQS_DP<1>")
	)
	(segment
		(start 39.09949 -210.359244)
		(end 39.248588 -210.210146)
		(width 0.16002)
		(layer "In4.Cu")
		(net "M_D_CPU1_SA_DQS_DP<1>")
	)
	(segment
		(start 65.044066 -215.5571)
		(end 64.937386 -215.66378)
		(width 0.16002)
		(layer "In4.Cu")
		(net "M_D_CPU1_SA_DQS_DP<1>")
	)
	(segment
		(start 54.486048 -210.344004)
		(end 55.110888 -210.968844)
		(width 0.16002)
		(layer "In4.Cu")
		(net "M_D_CPU1_SA_DQS_DP<1>")
	)
	(segment
		(start 67.79133 -218.304364)
		(end 67.68465 -218.411044)
		(width 0.16002)
		(layer "In4.Cu")
		(net "M_D_CPU1_SA_DQS_DP<1>")
	)
	(segment
		(start 51.020218 -209.360262)
		(end 52.760118 -209.360262)
		(width 0.16002)
		(layer "In4.Cu")
		(net "M_D_CPU1_SA_DQS_DP<1>")
	)
	(segment
		(start 63.563754 -214.567008)
		(end 63.759588 -214.762842)
		(width 0.16002)
		(layer "In4.Cu")
		(net "M_D_CPU1_SA_DQS_DP<1>")
	)
	(segment
		(start 64.937386 -215.94064)
		(end 65.13322 -216.136474)
		(width 0.16002)
		(layer "In4.Cu")
		(net "M_D_CPU1_SA_DQS_DP<1>")
	)
	(segment
		(start 70.538594 -221.051628)
		(end 70.431914 -221.158308)
		(width 0.16002)
		(layer "In4.Cu")
		(net "M_D_CPU1_SA_DQS_DP<1>")
	)
	(segment
		(start 62.769496 -213.28253)
		(end 63.2968 -213.28253)
		(width 0.16002)
		(layer "In4.Cu")
		(net "M_D_CPU1_SA_DQS_DP<1>")
	)
	(segment
		(start 63.759588 -214.762842)
		(end 64.036448 -214.762842)
		(width 0.16002)
		(layer "In4.Cu")
		(net "M_D_CPU1_SA_DQS_DP<1>")
	)
	(segment
		(start 48.636936 -210.210146)
		(end 48.981614 -210.554824)
		(width 0.16002)
		(layer "In4.Cu")
		(net "M_D_CPU1_SA_DQS_DP<1>")
	)
	(segment
		(start 69.164962 -219.677996)
		(end 69.058282 -219.784676)
		(width 0.16002)
		(layer "In4.Cu")
		(net "M_D_CPU1_SA_DQS_DP<1>")
	)
	(segment
		(start 70.904608 -221.631002)
		(end 71.011288 -221.524322)
		(width 0.16002)
		(layer "In4.Cu")
		(net "M_D_CPU1_SA_DQS_DP<1>")
	)
	(segment
		(start 50.23993 -209.724244)
		(end 50.656236 -209.724244)
		(width 0.16002)
		(layer "In4.Cu")
		(net "M_D_CPU1_SA_DQS_DP<1>")
	)
	(segment
		(start 41.837102 -210.554824)
		(end 42.667682 -209.724244)
		(width 0.16002)
		(layer "In4.Cu")
		(net "M_D_CPU1_SA_DQS_DP<1>")
	)
	(segment
		(start 90.846148 -231.816402)
		(end 90.946986 -231.789732)
		(width 0.09525)
		(layer "In4.Cu")
		(net "M_D_CPU1_SA_DQS_DP<1>")
	)
	(segment
		(start 86.581234 -231.854248)
		(end 86.589616 -231.849422)
		(width 0.09525)
		(layer "In4.Cu")
		(net "M_D_CPU1_SA_DQS_DP<1>")
	)
	(segment
		(start 52.760118 -209.360262)
		(end 53.74386 -210.344004)
		(width 0.16002)
		(layer "In4.Cu")
		(net "M_D_CPU1_SA_DQS_DP<1>")
	)
	(segment
		(start 46.059598 -210.210146)
		(end 48.636936 -210.210146)
		(width 0.16002)
		(layer "In4.Cu")
		(net "M_D_CPU1_SA_DQS_DP<1>")
	)
	(segment
		(start 82.452464 -231.849422)
		(end 82.460846 -231.854248)
		(width 0.09525)
		(layer "In4.Cu")
		(net "M_D_CPU1_SA_DQS_DP<1>")
	)
	(segment
		(start 67.417696 -217.403426)
		(end 67.79133 -217.77706)
		(width 0.16002)
		(layer "In4.Cu")
		(net "M_D_CPU1_SA_DQS_DP<1>")
	)
	(segment
		(start 41.437814 -210.554824)
		(end 41.837102 -210.554824)
		(width 0.16002)
		(layer "In4.Cu")
		(net "M_D_CPU1_SA_DQS_DP<1>")
	)
	(segment
		(start 90.946986 -231.789732)
		(end 91.10091 -231.524302)
		(width 0.09525)
		(layer "In4.Cu")
		(net "M_D_CPU1_SA_DQS_DP<1>")
	)
	(segment
		(start 64.036448 -214.762842)
		(end 64.143128 -214.656162)
		(width 0.16002)
		(layer "In4.Cu")
		(net "M_D_CPU1_SA_DQS_DP<1>")
	)
	(segment
		(start 66.311018 -217.314272)
		(end 66.506852 -217.510106)
		(width 0.16002)
		(layer "In4.Cu")
		(net "M_D_CPU1_SA_DQS_DP<1>")
	)
	(segment
		(start 66.044064 -216.029794)
		(end 66.417698 -216.403428)
		(width 0.16002)
		(layer "In4.Cu")
		(net "M_D_CPU1_SA_DQS_DP<1>")
	)
	(segment
		(start 45.209714 -209.360262)
		(end 46.059598 -210.210146)
		(width 0.16002)
		(layer "In4.Cu")
		(net "M_D_CPU1_SA_DQS_DP<1>")
	)
	(segment
		(start 50.656236 -209.724244)
		(end 51.020218 -209.360262)
		(width 0.16002)
		(layer "In4.Cu")
		(net "M_D_CPU1_SA_DQS_DP<1>")
	)
	(segment
		(start 70.538594 -220.524324)
		(end 70.538594 -221.051628)
		(width 0.16002)
		(layer "In4.Cu")
		(net "M_D_CPU1_SA_DQS_DP<1>")
	)
	(segment
		(start 71.538592 -221.524322)
		(end 71.912226 -221.897956)
		(width 0.16002)
		(layer "In4.Cu")
		(net "M_D_CPU1_SA_DQS_DP<1>")
	)
	(segment
		(start 70.431914 -221.158308)
		(end 70.431914 -221.435168)
		(width 0.16002)
		(layer "In4.Cu")
		(net "M_D_CPU1_SA_DQS_DP<1>")
	)
	(segment
		(start 63.2968 -213.28253)
		(end 63.670434 -213.656164)
		(width 0.16002)
		(layer "In4.Cu")
		(net "M_D_CPU1_SA_DQS_DP<1>")
	)
	(segment
		(start 78.95209 -231.187752)
		(end 79.554832 -231.790494)
		(width 0.09525)
		(layer "In4.Cu")
		(net "M_D_CPU1_SA_DQS_DP<1>")
	)
	(segment
		(start 78.95209 -230.489506)
		(end 78.95209 -231.187752)
		(width 0.09525)
		(layer "In4.Cu")
		(net "M_D_CPU1_SA_DQS_DP<1>")
	)
	(segment
		(start 77.458824 -229.449376)
		(end 78.158594 -230.149146)
		(width 0.09525)
		(layer "In4.Cu")
		(net "M_D_CPU1_SA_DQS_DP<1>")
	)
	(segment
		(start 63.670434 -214.183468)
		(end 63.563754 -214.290148)
		(width 0.16002)
		(layer "In4.Cu")
		(net "M_D_CPU1_SA_DQS_DP<1>")
	)
	(segment
		(start 69.058282 -219.784676)
		(end 69.058282 -220.061536)
		(width 0.16002)
		(layer "In4.Cu")
		(net "M_D_CPU1_SA_DQS_DP<1>")
	)
	(segment
		(start 43.476418 -209.360262)
		(end 45.209714 -209.360262)
		(width 0.16002)
		(layer "In4.Cu")
		(net "M_D_CPU1_SA_DQS_DP<1>")
	)
	(segment
		(start 48.981614 -210.554824)
		(end 49.40935 -210.554824)
		(width 0.16002)
		(layer "In4.Cu")
		(net "M_D_CPU1_SA_DQS_DP<1>")
	)
	(segment
		(start 70.16496 -220.15069)
		(end 70.538594 -220.524324)
		(width 0.16002)
		(layer "In4.Cu")
		(net "M_D_CPU1_SA_DQS_DP<1>")
	)
	(segment
		(start 70.431914 -221.435168)
		(end 70.627748 -221.631002)
		(width 0.16002)
		(layer "In4.Cu")
		(net "M_D_CPU1_SA_DQS_DP<1>")
	)
	(segment
		(start 71.805546 -222.53194)
		(end 71.805546 -222.8088)
		(width 0.16002)
		(layer "In4.Cu")
		(net "M_D_CPU1_SA_DQS_DP<1>")
	)
	(segment
		(start 69.637656 -220.15069)
		(end 70.16496 -220.15069)
		(width 0.16002)
		(layer "In4.Cu")
		(net "M_D_CPU1_SA_DQS_DP<1>")
	)
	(segment
		(start 73.67651 -224.679764)
		(end 73.67651 -226.18319)
		(width 0.16002)
		(layer "In4.Cu")
		(net "M_D_CPU1_SA_DQS_DP<1>")
	)
	(segment
		(start 36.795964 -210.085432)
		(end 37.069776 -210.359244)
		(width 0.16002)
		(layer "In4.Cu")
		(net "M_D_CPU1_SA_DQS_DP<1>")
	)
	(segment
		(start 66.783712 -217.510106)
		(end 66.890392 -217.403426)
		(width 0.16002)
		(layer "In4.Cu")
		(net "M_D_CPU1_SA_DQS_DP<1>")
	)
	(segment
		(start 67.880484 -218.883738)
		(end 68.157344 -218.883738)
		(width 0.16002)
		(layer "In4.Cu")
		(net "M_D_CPU1_SA_DQS_DP<1>")
	)
	(segment
		(start 63.670434 -213.656164)
		(end 63.670434 -214.183468)
		(width 0.16002)
		(layer "In4.Cu")
		(net "M_D_CPU1_SA_DQS_DP<1>")
	)
	(segment
		(start 90.341196 -231.854248)
		(end 90.349578 -231.849422)
		(width 0.09525)
		(layer "In4.Cu")
		(net "M_D_CPU1_SA_DQS_DP<1>")
	)
	(segment
		(start 71.912226 -222.42526)
		(end 71.805546 -222.53194)
		(width 0.16002)
		(layer "In4.Cu")
		(net "M_D_CPU1_SA_DQS_DP<1>")
	)
	(segment
		(start 71.011288 -221.524322)
		(end 71.538592 -221.524322)
		(width 0.16002)
		(layer "In4.Cu")
		(net "M_D_CPU1_SA_DQS_DP<1>")
	)
	(segment
		(start 62.662816 -213.38921)
		(end 62.769496 -213.28253)
		(width 0.16002)
		(layer "In4.Cu")
		(net "M_D_CPU1_SA_DQS_DP<1>")
	)
	(segment
		(start 76.859638 -229.449376)
		(end 77.458824 -229.449376)
		(width 0.09525)
		(layer "In4.Cu")
		(net "M_D_CPU1_SA_DQS_DP<1>")
	)
	(segment
		(start 68.157344 -218.883738)
		(end 68.264024 -218.777058)
		(width 0.16002)
		(layer "In4.Cu")
		(net "M_D_CPU1_SA_DQS_DP<1>")
	)
	(segment
		(start 66.417698 -216.930732)
		(end 66.311018 -217.037412)
		(width 0.16002)
		(layer "In4.Cu")
		(net "M_D_CPU1_SA_DQS_DP<1>")
	)
	(segment
		(start 87.15248 -231.849422)
		(end 87.160862 -231.854248)
		(width 0.09525)
		(layer "In4.Cu")
		(net "M_D_CPU1_SA_DQS_DP<1>")
	)
	(segment
		(start 64.937386 -215.66378)
		(end 64.937386 -215.94064)
		(width 0.16002)
		(layer "In4.Cu")
		(net "M_D_CPU1_SA_DQS_DP<1>")
	)
	(segment
		(start 68.791328 -218.777058)
		(end 69.164962 -219.150692)
		(width 0.16002)
		(layer "In4.Cu")
		(net "M_D_CPU1_SA_DQS_DP<1>")
	)
	(segment
		(start 55.110888 -210.968844)
		(end 59.96559 -210.968844)
		(width 0.16002)
		(layer "In4.Cu")
		(net "M_D_CPU1_SA_DQS_DP<1>")
	)
	(segment
		(start 69.058282 -220.061536)
		(end 69.254116 -220.25737)
		(width 0.16002)
		(layer "In4.Cu")
		(net "M_D_CPU1_SA_DQS_DP<1>")
	)
	(segment
		(start 59.96559 -210.968844)
		(end 62.385956 -213.38921)
		(width 0.16002)
		(layer "In4.Cu")
		(net "M_D_CPU1_SA_DQS_DP<1>")
	)
	(segment
		(start 71.912226 -221.897956)
		(end 71.912226 -222.42526)
		(width 0.16002)
		(layer "In4.Cu")
		(net "M_D_CPU1_SA_DQS_DP<1>")
	)
	(segment
		(start 66.417698 -216.403428)
		(end 66.417698 -216.930732)
		(width 0.16002)
		(layer "In4.Cu")
		(net "M_D_CPU1_SA_DQS_DP<1>")
	)
	(segment
		(start 41.093136 -210.210146)
		(end 41.437814 -210.554824)
		(width 0.16002)
		(layer "In4.Cu")
		(net "M_D_CPU1_SA_DQS_DP<1>")
	)
	(segment
		(start 65.41008 -216.136474)
		(end 65.51676 -216.029794)
		(width 0.16002)
		(layer "In4.Cu")
		(net "M_D_CPU1_SA_DQS_DP<1>")
	)
	(segment
		(start 69.254116 -220.25737)
		(end 69.530976 -220.25737)
		(width 0.16002)
		(layer "In4.Cu")
		(net "M_D_CPU1_SA_DQS_DP<1>")
	)
	(segment
		(start 42.667682 -209.724244)
		(end 43.112436 -209.724244)
		(width 0.16002)
		(layer "In4.Cu")
		(net "M_D_CPU1_SA_DQS_DP<1>")
	)
	(segment
		(start 67.79133 -217.77706)
		(end 67.79133 -218.304364)
		(width 0.16002)
		(layer "In4.Cu")
		(net "M_D_CPU1_SA_DQS_DP<1>")
	)
	(segment
		(start 78.158594 -230.149146)
		(end 78.61173 -230.149146)
		(width 0.09525)
		(layer "In4.Cu")
		(net "M_D_CPU1_SA_DQS_DP<1>")
	)
	(segment
		(start 73.67651 -226.18319)
		(end 76.434188 -228.940868)
		(width 0.16002)
		(layer "In4.Cu")
		(net "M_D_CPU1_SA_DQS_DP<1>")
	)
	(arc
		(start 81.8896 -231.849422)
		(mid 82.171032 -231.773667)
		(end 82.452464 -231.849422)
		(width 0.09525)
		(layer "In4.Cu")
		(net "M_D_CPU1_SA_DQS_DP<1>")
	)
	(arc
		(start 88.100916 -231.854248)
		(mid 88.285948 -231.900162)
		(end 88.469724 -231.849422)
		(width 0.09525)
		(layer "In4.Cu")
		(net "M_D_CPU1_SA_DQS_DP<1>")
	)
	(arc
		(start 79.640938 -231.854248)
		(mid 79.82597 -231.900162)
		(end 80.009746 -231.849422)
		(width 0.09525)
		(layer "In4.Cu")
		(net "M_D_CPU1_SA_DQS_DP<1>")
	)
	(arc
		(start 80.57261 -231.849422)
		(mid 80.761078 -231.900099)
		(end 80.949546 -231.849422)
		(width 0.09525)
		(layer "In4.Cu")
		(net "M_D_CPU1_SA_DQS_DP<1>")
	)
	(arc
		(start 79.554832 -231.790494)
		(mid 79.591776 -231.822487)
		(end 79.632556 -231.849422)
		(width 0.09525)
		(layer "In4.Cu")
		(net "M_D_CPU1_SA_DQS_DP<1>")
	)
	(arc
		(start 87.160862 -231.854248)
		(mid 87.345894 -231.900162)
		(end 87.52967 -231.849422)
		(width 0.09525)
		(layer "In4.Cu")
		(net "M_D_CPU1_SA_DQS_DP<1>")
	)
	(arc
		(start 84.332572 -231.849422)
		(mid 84.52104 -231.900099)
		(end 84.709508 -231.849422)
		(width 0.09525)
		(layer "In4.Cu")
		(net "M_D_CPU1_SA_DQS_DP<1>")
	)
	(arc
		(start 90.349578 -231.849422)
		(mid 90.583373 -231.775555)
		(end 90.826336 -231.808528)
		(width 0.09525)
		(layer "In4.Cu")
		(net "M_D_CPU1_SA_DQS_DP<1>")
	)
	(arc
		(start 85.649562 -231.849422)
		(mid 85.930994 -231.773667)
		(end 86.212426 -231.849422)
		(width 0.09525)
		(layer "In4.Cu")
		(net "M_D_CPU1_SA_DQS_DP<1>")
	)
	(arc
		(start 89.972388 -231.849422)
		(mid 90.156163 -231.900194)
		(end 90.341196 -231.854248)
		(width 0.09525)
		(layer "In4.Cu")
		(net "M_D_CPU1_SA_DQS_DP<1>")
	)
	(arc
		(start 90.826336 -231.808528)
		(mid 90.836279 -231.812371)
		(end 90.846148 -231.816402)
		(width 0.09525)
		(layer "In4.Cu")
		(net "M_D_CPU1_SA_DQS_DP<1>")
	)
	(arc
		(start 80.009746 -231.849422)
		(mid 80.291178 -231.773667)
		(end 80.57261 -231.849422)
		(width 0.09525)
		(layer "In4.Cu")
		(net "M_D_CPU1_SA_DQS_DP<1>")
	)
	(arc
		(start 88.469724 -231.849422)
		(mid 88.751156 -231.773667)
		(end 89.032588 -231.849422)
		(width 0.09525)
		(layer "In4.Cu")
		(net "M_D_CPU1_SA_DQS_DP<1>")
	)
	(arc
		(start 85.272372 -231.849422)
		(mid 85.456147 -231.900194)
		(end 85.64118 -231.854248)
		(width 0.09525)
		(layer "In4.Cu")
		(net "M_D_CPU1_SA_DQS_DP<1>")
	)
	(arc
		(start 86.589616 -231.849422)
		(mid 86.871048 -231.773667)
		(end 87.15248 -231.849422)
		(width 0.09525)
		(layer "In4.Cu")
		(net "M_D_CPU1_SA_DQS_DP<1>")
	)
	(arc
		(start 84.709508 -231.849422)
		(mid 84.99094 -231.773667)
		(end 85.272372 -231.849422)
		(width 0.09525)
		(layer "In4.Cu")
		(net "M_D_CPU1_SA_DQS_DP<1>")
	)
	(arc
		(start 82.829654 -231.849422)
		(mid 83.111086 -231.773667)
		(end 83.392518 -231.849422)
		(width 0.09525)
		(layer "In4.Cu")
		(net "M_D_CPU1_SA_DQS_DP<1>")
	)
	(arc
		(start 82.460846 -231.854248)
		(mid 82.645878 -231.900162)
		(end 82.829654 -231.849422)
		(width 0.09525)
		(layer "In4.Cu")
		(net "M_D_CPU1_SA_DQS_DP<1>")
	)
	(arc
		(start 80.949546 -231.849422)
		(mid 81.230978 -231.773667)
		(end 81.51241 -231.849422)
		(width 0.09525)
		(layer "In4.Cu")
		(net "M_D_CPU1_SA_DQS_DP<1>")
	)
	(arc
		(start 87.52967 -231.849422)
		(mid 87.811102 -231.773667)
		(end 88.092534 -231.849422)
		(width 0.09525)
		(layer "In4.Cu")
		(net "M_D_CPU1_SA_DQS_DP<1>")
	)
	(arc
		(start 83.4009 -231.854248)
		(mid 83.585932 -231.900162)
		(end 83.769708 -231.849422)
		(width 0.09525)
		(layer "In4.Cu")
		(net "M_D_CPU1_SA_DQS_DP<1>")
	)
	(arc
		(start 89.409524 -231.849422)
		(mid 89.690956 -231.773667)
		(end 89.972388 -231.849422)
		(width 0.09525)
		(layer "In4.Cu")
		(net "M_D_CPU1_SA_DQS_DP<1>")
	)
	(arc
		(start 83.769708 -231.849422)
		(mid 84.05114 -231.773667)
		(end 84.332572 -231.849422)
		(width 0.09525)
		(layer "In4.Cu")
		(net "M_D_CPU1_SA_DQS_DP<1>")
	)
	(arc
		(start 86.212426 -231.849422)
		(mid 86.396201 -231.900194)
		(end 86.581234 -231.854248)
		(width 0.09525)
		(layer "In4.Cu")
		(net "M_D_CPU1_SA_DQS_DP<1>")
	)
	(arc
		(start 89.032588 -231.849422)
		(mid 89.221056 -231.900099)
		(end 89.409524 -231.849422)
		(width 0.09525)
		(layer "In4.Cu")
		(net "M_D_CPU1_SA_DQS_DP<1>")
	)
	(arc
		(start 81.51241 -231.849422)
		(mid 81.696185 -231.900194)
		(end 81.881218 -231.854248)
		(width 0.09525)
		(layer "In4.Cu")
		(net "M_D_CPU1_SA_DQS_DP<1>")
	)
	(segment
		(start 91.568016 -226.930458)
		(end 91.10091 -226.66452)
		(width 0.12954)
		(layer "F.Cu")
		(net "M_D_CPU1_SA_DQS_DP<0>")
	)
	(segment
		(start 81.480914 -225.35134)
		(end 81.51241 -225.369628)
		(width 0.09525)
		(layer "In4.Cu")
		(net "M_D_CPU1_SA_DQS_DP<0>")
	)
	(segment
		(start 82.419952 -226.970844)
		(end 82.452464 -226.98964)
		(width 0.09525)
		(layer "In4.Cu")
		(net "M_D_CPU1_SA_DQS_DP<0>")
	)
	(segment
		(start 79.442818 -221.399354)
		(end 79.442818 -221.804484)
		(width 0.09525)
		(layer "In4.Cu")
		(net "M_D_CPU1_SA_DQS_DP<0>")
	)
	(segment
		(start 62.159134 -202.938888)
		(end 62.159134 -203.688188)
		(width 0.16002)
		(layer "In4.Cu")
		(net "M_D_CPU1_SA_DQS_DP<0>")
	)
	(segment
		(start 41.83253 -201.203306)
		(end 42.67327 -200.362566)
		(width 0.16002)
		(layer "In4.Cu")
		(net "M_D_CPU1_SA_DQS_DP<0>")
	)
	(segment
		(start 37.069776 -201.00925)
		(end 39.072566 -201.00925)
		(width 0.16002)
		(layer "In4.Cu")
		(net "M_D_CPU1_SA_DQS_DP<0>")
	)
	(segment
		(start 74.74585 -216.274904)
		(end 75.49515 -216.274904)
		(width 0.16002)
		(layer "In4.Cu")
		(net "M_D_CPU1_SA_DQS_DP<0>")
	)
	(segment
		(start 77.269086 -218.04884)
		(end 77.269086 -218.79814)
		(width 0.16002)
		(layer "In4.Cu")
		(net "M_D_CPU1_SA_DQS_DP<0>")
	)
	(segment
		(start 80.10271 -222.93961)
		(end 80.137762 -222.960184)
		(width 0.09525)
		(layer "In4.Cu")
		(net "M_D_CPU1_SA_DQS_DP<0>")
	)
	(segment
		(start 70.400926 -211.92998)
		(end 70.624954 -212.154008)
		(width 0.16002)
		(layer "In4.Cu")
		(net "M_D_CPU1_SA_DQS_DP<0>")
	)
	(segment
		(start 62.383162 -203.912216)
		(end 63.132462 -203.912216)
		(width 0.16002)
		(layer "In4.Cu")
		(net "M_D_CPU1_SA_DQS_DP<0>")
	)
	(segment
		(start 74.521822 -215.301576)
		(end 74.521822 -216.050876)
		(width 0.16002)
		(layer "In4.Cu")
		(net "M_D_CPU1_SA_DQS_DP<0>")
	)
	(segment
		(start 68.62699 -209.406744)
		(end 69.027294 -209.807048)
		(width 0.16002)
		(layer "In4.Cu")
		(net "M_D_CPU1_SA_DQS_DP<0>")
	)
	(segment
		(start 71.774558 -213.303612)
		(end 71.998586 -213.52764)
		(width 0.16002)
		(layer "In4.Cu")
		(net "M_D_CPU1_SA_DQS_DP<0>")
	)
	(segment
		(start 73.14819 -214.677244)
		(end 73.372218 -214.901272)
		(width 0.16002)
		(layer "In4.Cu")
		(net "M_D_CPU1_SA_DQS_DP<0>")
	)
	(segment
		(start 50.24501 -200.357486)
		(end 50.68697 -200.357486)
		(width 0.16002)
		(layer "In4.Cu")
		(net "M_D_CPU1_SA_DQS_DP<0>")
	)
	(segment
		(start 81.009998 -224.540826)
		(end 81.04251 -224.559622)
		(width 0.09525)
		(layer "In4.Cu")
		(net "M_D_CPU1_SA_DQS_DP<0>")
	)
	(segment
		(start 83.392518 -226.98964)
		(end 83.4009 -226.994466)
		(width 0.09525)
		(layer "In4.Cu")
		(net "M_D_CPU1_SA_DQS_DP<0>")
	)
	(segment
		(start 80.540098 -223.73082)
		(end 80.57261 -223.749616)
		(width 0.09525)
		(layer "In4.Cu")
		(net "M_D_CPU1_SA_DQS_DP<0>")
	)
	(segment
		(start 64.906398 -205.686152)
		(end 64.906398 -206.435452)
		(width 0.16002)
		(layer "In4.Cu")
		(net "M_D_CPU1_SA_DQS_DP<0>")
	)
	(segment
		(start 90.946986 -226.92995)
		(end 91.10091 -226.66452)
		(width 0.09525)
		(layer "In4.Cu")
		(net "M_D_CPU1_SA_DQS_DP<0>")
	)
	(segment
		(start 73.14819 -213.927944)
		(end 73.14819 -214.677244)
		(width 0.16002)
		(layer "In4.Cu")
		(net "M_D_CPU1_SA_DQS_DP<0>")
	)
	(segment
		(start 64.906398 -206.435452)
		(end 65.130426 -206.65948)
		(width 0.16002)
		(layer "In4.Cu")
		(net "M_D_CPU1_SA_DQS_DP<0>")
	)
	(segment
		(start 79.501746 -220.2815)
		(end 79.501746 -221.316804)
		(width 0.16002)
		(layer "In4.Cu")
		(net "M_D_CPU1_SA_DQS_DP<0>")
	)
	(segment
		(start 42.67327 -200.362566)
		(end 43.13047 -200.362566)
		(width 0.16002)
		(layer "In4.Cu")
		(net "M_D_CPU1_SA_DQS_DP<0>")
	)
	(segment
		(start 67.653662 -209.182716)
		(end 67.87769 -209.406744)
		(width 0.16002)
		(layer "In4.Cu")
		(net "M_D_CPU1_SA_DQS_DP<0>")
	)
	(segment
		(start 90.341196 -226.994466)
		(end 90.349578 -226.98964)
		(width 0.09525)
		(layer "In4.Cu")
		(net "M_D_CPU1_SA_DQS_DP<0>")
	)
	(segment
		(start 63.756794 -205.285848)
		(end 64.506094 -205.285848)
		(width 0.16002)
		(layer "In4.Cu")
		(net "M_D_CPU1_SA_DQS_DP<0>")
	)
	(segment
		(start 36.795964 -200.735438)
		(end 37.069776 -201.00925)
		(width 0.16002)
		(layer "In4.Cu")
		(net "M_D_CPU1_SA_DQS_DP<0>")
	)
	(segment
		(start 71.374254 -212.154008)
		(end 71.774558 -212.554312)
		(width 0.16002)
		(layer "In4.Cu")
		(net "M_D_CPU1_SA_DQS_DP<0>")
	)
	(segment
		(start 50.68697 -200.357486)
		(end 51.034188 -200.010268)
		(width 0.16002)
		(layer "In4.Cu")
		(net "M_D_CPU1_SA_DQS_DP<0>")
	)
	(segment
		(start 76.119482 -217.648536)
		(end 76.868782 -217.648536)
		(width 0.16002)
		(layer "In4.Cu")
		(net "M_D_CPU1_SA_DQS_DP<0>")
	)
	(segment
		(start 65.130426 -206.65948)
		(end 65.879726 -206.65948)
		(width 0.16002)
		(layer "In4.Cu")
		(net "M_D_CPU1_SA_DQS_DP<0>")
	)
	(segment
		(start 90.846148 -226.95662)
		(end 90.946986 -226.92995)
		(width 0.09525)
		(layer "In4.Cu")
		(net "M_D_CPU1_SA_DQS_DP<0>")
	)
	(segment
		(start 46.002956 -200.860152)
		(end 48.606456 -200.860152)
		(width 0.16002)
		(layer "In4.Cu")
		(net "M_D_CPU1_SA_DQS_DP<0>")
	)
	(segment
		(start 75.49515 -216.274904)
		(end 75.895454 -216.675208)
		(width 0.16002)
		(layer "In4.Cu")
		(net "M_D_CPU1_SA_DQS_DP<0>")
	)
	(segment
		(start 88.092534 -226.98964)
		(end 88.100916 -226.994466)
		(width 0.09525)
		(layer "In4.Cu")
		(net "M_D_CPU1_SA_DQS_DP<0>")
	)
	(segment
		(start 49.40935 -201.193146)
		(end 50.24501 -200.357486)
		(width 0.16002)
		(layer "In4.Cu")
		(net "M_D_CPU1_SA_DQS_DP<0>")
	)
	(segment
		(start 70.624954 -212.154008)
		(end 71.374254 -212.154008)
		(width 0.16002)
		(layer "In4.Cu")
		(net "M_D_CPU1_SA_DQS_DP<0>")
	)
	(segment
		(start 74.121518 -214.901272)
		(end 74.521822 -215.301576)
		(width 0.16002)
		(layer "In4.Cu")
		(net "M_D_CPU1_SA_DQS_DP<0>")
	)
	(segment
		(start 51.034188 -200.010268)
		(end 52.781962 -200.010268)
		(width 0.16002)
		(layer "In4.Cu")
		(net "M_D_CPU1_SA_DQS_DP<0>")
	)
	(segment
		(start 75.895454 -217.424508)
		(end 76.119482 -217.648536)
		(width 0.16002)
		(layer "In4.Cu")
		(net "M_D_CPU1_SA_DQS_DP<0>")
	)
	(segment
		(start 65.879726 -206.65948)
		(end 66.28003 -207.059784)
		(width 0.16002)
		(layer "In4.Cu")
		(net "M_D_CPU1_SA_DQS_DP<0>")
	)
	(segment
		(start 43.48353 -200.009506)
		(end 45.15231 -200.009506)
		(width 0.16002)
		(layer "In4.Cu")
		(net "M_D_CPU1_SA_DQS_DP<0>")
	)
	(segment
		(start 43.13047 -200.362566)
		(end 43.48353 -200.009506)
		(width 0.16002)
		(layer "In4.Cu")
		(net "M_D_CPU1_SA_DQS_DP<0>")
	)
	(segment
		(start 69.027294 -209.807048)
		(end 69.027294 -210.556348)
		(width 0.16002)
		(layer "In4.Cu")
		(net "M_D_CPU1_SA_DQS_DP<0>")
	)
	(segment
		(start 79.501746 -221.316804)
		(end 79.501746 -221.340426)
		(width 0.09525)
		(layer "In4.Cu")
		(net "M_D_CPU1_SA_DQS_DP<0>")
	)
	(segment
		(start 72.747886 -213.52764)
		(end 73.14819 -213.927944)
		(width 0.16002)
		(layer "In4.Cu")
		(net "M_D_CPU1_SA_DQS_DP<0>")
	)
	(segment
		(start 80.071214 -222.921322)
		(end 80.10271 -222.93961)
		(width 0.09525)
		(layer "In4.Cu")
		(net "M_D_CPU1_SA_DQS_DP<0>")
	)
	(segment
		(start 78.242414 -219.022168)
		(end 79.501746 -220.2815)
		(width 0.16002)
		(layer "In4.Cu")
		(net "M_D_CPU1_SA_DQS_DP<0>")
	)
	(segment
		(start 75.895454 -216.675208)
		(end 75.895454 -217.424508)
		(width 0.16002)
		(layer "In4.Cu")
		(net "M_D_CPU1_SA_DQS_DP<0>")
	)
	(segment
		(start 71.774558 -212.554312)
		(end 71.774558 -213.303612)
		(width 0.16002)
		(layer "In4.Cu")
		(net "M_D_CPU1_SA_DQS_DP<0>")
	)
	(segment
		(start 63.132462 -203.912216)
		(end 63.532766 -204.31252)
		(width 0.16002)
		(layer "In4.Cu")
		(net "M_D_CPU1_SA_DQS_DP<0>")
	)
	(segment
		(start 86.581234 -226.994466)
		(end 86.589616 -226.98964)
		(width 0.09525)
		(layer "In4.Cu")
		(net "M_D_CPU1_SA_DQS_DP<0>")
	)
	(segment
		(start 41.100756 -200.860152)
		(end 41.44391 -201.203306)
		(width 0.16002)
		(layer "In4.Cu")
		(net "M_D_CPU1_SA_DQS_DP<0>")
	)
	(segment
		(start 39.221664 -200.860152)
		(end 41.100756 -200.860152)
		(width 0.16002)
		(layer "In4.Cu")
		(net "M_D_CPU1_SA_DQS_DP<0>")
	)
	(segment
		(start 56.231536 -200.910444)
		(end 56.951118 -201.630026)
		(width 0.16002)
		(layer "In4.Cu")
		(net "M_D_CPU1_SA_DQS_DP<0>")
	)
	(segment
		(start 67.87769 -209.406744)
		(end 68.62699 -209.406744)
		(width 0.16002)
		(layer "In4.Cu")
		(net "M_D_CPU1_SA_DQS_DP<0>")
	)
	(segment
		(start 71.998586 -213.52764)
		(end 72.747886 -213.52764)
		(width 0.16002)
		(layer "In4.Cu")
		(net "M_D_CPU1_SA_DQS_DP<0>")
	)
	(segment
		(start 70.400926 -211.18068)
		(end 70.400926 -211.92998)
		(width 0.16002)
		(layer "In4.Cu")
		(net "M_D_CPU1_SA_DQS_DP<0>")
	)
	(segment
		(start 77.269086 -218.79814)
		(end 77.493114 -219.022168)
		(width 0.16002)
		(layer "In4.Cu")
		(net "M_D_CPU1_SA_DQS_DP<0>")
	)
	(segment
		(start 63.532766 -204.31252)
		(end 63.532766 -205.06182)
		(width 0.16002)
		(layer "In4.Cu")
		(net "M_D_CPU1_SA_DQS_DP<0>")
	)
	(segment
		(start 80.57261 -223.749616)
		(end 80.607662 -223.77019)
		(width 0.09525)
		(layer "In4.Cu")
		(net "M_D_CPU1_SA_DQS_DP<0>")
	)
	(segment
		(start 66.28003 -207.809084)
		(end 66.504058 -208.033112)
		(width 0.16002)
		(layer "In4.Cu")
		(net "M_D_CPU1_SA_DQS_DP<0>")
	)
	(segment
		(start 77.493114 -219.022168)
		(end 78.242414 -219.022168)
		(width 0.16002)
		(layer "In4.Cu")
		(net "M_D_CPU1_SA_DQS_DP<0>")
	)
	(segment
		(start 66.28003 -207.059784)
		(end 66.28003 -207.809084)
		(width 0.16002)
		(layer "In4.Cu")
		(net "M_D_CPU1_SA_DQS_DP<0>")
	)
	(segment
		(start 52.781962 -200.010268)
		(end 53.682138 -200.910444)
		(width 0.16002)
		(layer "In4.Cu")
		(net "M_D_CPU1_SA_DQS_DP<0>")
	)
	(segment
		(start 66.504058 -208.033112)
		(end 67.253358 -208.033112)
		(width 0.16002)
		(layer "In4.Cu")
		(net "M_D_CPU1_SA_DQS_DP<0>")
	)
	(segment
		(start 56.951118 -201.630026)
		(end 60.850272 -201.630026)
		(width 0.16002)
		(layer "In4.Cu")
		(net "M_D_CPU1_SA_DQS_DP<0>")
	)
	(segment
		(start 81.950052 -226.160838)
		(end 81.982564 -226.179634)
		(width 0.09525)
		(layer "In4.Cu")
		(net "M_D_CPU1_SA_DQS_DP<0>")
	)
	(segment
		(start 48.606456 -200.860152)
		(end 48.93945 -201.193146)
		(width 0.16002)
		(layer "In4.Cu")
		(net "M_D_CPU1_SA_DQS_DP<0>")
	)
	(segment
		(start 48.93945 -201.193146)
		(end 49.40935 -201.193146)
		(width 0.16002)
		(layer "In4.Cu")
		(net "M_D_CPU1_SA_DQS_DP<0>")
	)
	(segment
		(start 69.027294 -210.556348)
		(end 69.251322 -210.780376)
		(width 0.16002)
		(layer "In4.Cu")
		(net "M_D_CPU1_SA_DQS_DP<0>")
	)
	(segment
		(start 53.682138 -200.910444)
		(end 56.231536 -200.910444)
		(width 0.16002)
		(layer "In4.Cu")
		(net "M_D_CPU1_SA_DQS_DP<0>")
	)
	(segment
		(start 74.521822 -216.050876)
		(end 74.74585 -216.274904)
		(width 0.16002)
		(layer "In4.Cu")
		(net "M_D_CPU1_SA_DQS_DP<0>")
	)
	(segment
		(start 73.372218 -214.901272)
		(end 74.121518 -214.901272)
		(width 0.16002)
		(layer "In4.Cu")
		(net "M_D_CPU1_SA_DQS_DP<0>")
	)
	(segment
		(start 45.15231 -200.009506)
		(end 46.002956 -200.860152)
		(width 0.16002)
		(layer "In4.Cu")
		(net "M_D_CPU1_SA_DQS_DP<0>")
	)
	(segment
		(start 79.501746 -221.340426)
		(end 79.442818 -221.399354)
		(width 0.09525)
		(layer "In4.Cu")
		(net "M_D_CPU1_SA_DQS_DP<0>")
	)
	(segment
		(start 62.159134 -203.688188)
		(end 62.383162 -203.912216)
		(width 0.16002)
		(layer "In4.Cu")
		(net "M_D_CPU1_SA_DQS_DP<0>")
	)
	(segment
		(start 60.850272 -201.630026)
		(end 62.159134 -202.938888)
		(width 0.16002)
		(layer "In4.Cu")
		(net "M_D_CPU1_SA_DQS_DP<0>")
	)
	(segment
		(start 69.251322 -210.780376)
		(end 70.000622 -210.780376)
		(width 0.16002)
		(layer "In4.Cu")
		(net "M_D_CPU1_SA_DQS_DP<0>")
	)
	(segment
		(start 63.532766 -205.06182)
		(end 63.756794 -205.285848)
		(width 0.16002)
		(layer "In4.Cu")
		(net "M_D_CPU1_SA_DQS_DP<0>")
	)
	(segment
		(start 39.072566 -201.00925)
		(end 39.221664 -200.860152)
		(width 0.16002)
		(layer "In4.Cu")
		(net "M_D_CPU1_SA_DQS_DP<0>")
	)
	(segment
		(start 70.000622 -210.780376)
		(end 70.400926 -211.18068)
		(width 0.16002)
		(layer "In4.Cu")
		(net "M_D_CPU1_SA_DQS_DP<0>")
	)
	(segment
		(start 64.506094 -205.285848)
		(end 64.906398 -205.686152)
		(width 0.16002)
		(layer "In4.Cu")
		(net "M_D_CPU1_SA_DQS_DP<0>")
	)
	(segment
		(start 81.982564 -226.179634)
		(end 82.017616 -226.200208)
		(width 0.09525)
		(layer "In4.Cu")
		(net "M_D_CPU1_SA_DQS_DP<0>")
	)
	(segment
		(start 81.51241 -225.369628)
		(end 81.55051 -225.391726)
		(width 0.09525)
		(layer "In4.Cu")
		(net "M_D_CPU1_SA_DQS_DP<0>")
	)
	(segment
		(start 79.600044 -222.111316)
		(end 79.600044 -222.110808)
		(width 0.09525)
		(layer "In4.Cu")
		(net "M_D_CPU1_SA_DQS_DP<0>")
	)
	(segment
		(start 82.452464 -226.98964)
		(end 82.460846 -226.994466)
		(width 0.09525)
		(layer "In4.Cu")
		(net "M_D_CPU1_SA_DQS_DP<0>")
	)
	(segment
		(start 81.04251 -224.559622)
		(end 81.08061 -224.58172)
		(width 0.09525)
		(layer "In4.Cu")
		(net "M_D_CPU1_SA_DQS_DP<0>")
	)
	(segment
		(start 87.15248 -226.98964)
		(end 87.160862 -226.994466)
		(width 0.09525)
		(layer "In4.Cu")
		(net "M_D_CPU1_SA_DQS_DP<0>")
	)
	(segment
		(start 67.653662 -208.433416)
		(end 67.653662 -209.182716)
		(width 0.16002)
		(layer "In4.Cu")
		(net "M_D_CPU1_SA_DQS_DP<0>")
	)
	(segment
		(start 76.868782 -217.648536)
		(end 77.269086 -218.04884)
		(width 0.16002)
		(layer "In4.Cu")
		(net "M_D_CPU1_SA_DQS_DP<0>")
	)
	(segment
		(start 67.253358 -208.033112)
		(end 67.653662 -208.433416)
		(width 0.16002)
		(layer "In4.Cu")
		(net "M_D_CPU1_SA_DQS_DP<0>")
	)
	(segment
		(start 79.600044 -222.110808)
		(end 79.671926 -222.152464)
		(width 0.09525)
		(layer "In4.Cu")
		(net "M_D_CPU1_SA_DQS_DP<0>")
	)
	(segment
		(start 85.64118 -226.994466)
		(end 85.649562 -226.98964)
		(width 0.09525)
		(layer "In4.Cu")
		(net "M_D_CPU1_SA_DQS_DP<0>")
	)
	(segment
		(start 41.44391 -201.203306)
		(end 41.83253 -201.203306)
		(width 0.16002)
		(layer "In4.Cu")
		(net "M_D_CPU1_SA_DQS_DP<0>")
	)
	(arc
		(start 80.607662 -223.77019)
		(mid 80.788117 -223.971856)
		(end 80.85328 -224.234502)
		(width 0.09525)
		(layer "In4.Cu")
		(net "M_D_CPU1_SA_DQS_DP<0>")
	)
	(arc
		(start 85.272372 -226.98964)
		(mid 85.456147 -227.040412)
		(end 85.64118 -226.994466)
		(width 0.09525)
		(layer "In4.Cu")
		(net "M_D_CPU1_SA_DQS_DP<0>")
	)
	(arc
		(start 80.85328 -224.234502)
		(mid 80.894737 -224.406542)
		(end 81.009998 -224.540826)
		(width 0.09525)
		(layer "In4.Cu")
		(net "M_D_CPU1_SA_DQS_DP<0>")
	)
	(arc
		(start 83.4009 -226.994466)
		(mid 83.585932 -227.04038)
		(end 83.769708 -226.98964)
		(width 0.09525)
		(layer "In4.Cu")
		(net "M_D_CPU1_SA_DQS_DP<0>")
	)
	(arc
		(start 89.972388 -226.98964)
		(mid 90.156163 -227.040412)
		(end 90.341196 -226.994466)
		(width 0.09525)
		(layer "In4.Cu")
		(net "M_D_CPU1_SA_DQS_DP<0>")
	)
	(arc
		(start 89.409524 -226.98964)
		(mid 89.690956 -226.913885)
		(end 89.972388 -226.98964)
		(width 0.09525)
		(layer "In4.Cu")
		(net "M_D_CPU1_SA_DQS_DP<0>")
	)
	(arc
		(start 85.649562 -226.98964)
		(mid 85.930994 -226.913885)
		(end 86.212426 -226.98964)
		(width 0.09525)
		(layer "In4.Cu")
		(net "M_D_CPU1_SA_DQS_DP<0>")
	)
	(arc
		(start 84.709508 -226.98964)
		(mid 84.99094 -226.913885)
		(end 85.272372 -226.98964)
		(width 0.09525)
		(layer "In4.Cu")
		(net "M_D_CPU1_SA_DQS_DP<0>")
	)
	(arc
		(start 80.38338 -223.424496)
		(mid 80.424837 -223.596536)
		(end 80.540098 -223.73082)
		(width 0.09525)
		(layer "In4.Cu")
		(net "M_D_CPU1_SA_DQS_DP<0>")
	)
	(arc
		(start 81.08061 -224.58172)
		(mid 81.25906 -224.78319)
		(end 81.323434 -225.044508)
		(width 0.09525)
		(layer "In4.Cu")
		(net "M_D_CPU1_SA_DQS_DP<0>")
	)
	(arc
		(start 79.671926 -222.152464)
		(mid 79.849612 -222.353756)
		(end 79.913734 -222.61449)
		(width 0.09525)
		(layer "In4.Cu")
		(net "M_D_CPU1_SA_DQS_DP<0>")
	)
	(arc
		(start 82.017616 -226.200208)
		(mid 82.198071 -226.401874)
		(end 82.263234 -226.66452)
		(width 0.09525)
		(layer "In4.Cu")
		(net "M_D_CPU1_SA_DQS_DP<0>")
	)
	(arc
		(start 90.349578 -226.98964)
		(mid 90.583373 -226.915773)
		(end 90.826336 -226.948746)
		(width 0.09525)
		(layer "In4.Cu")
		(net "M_D_CPU1_SA_DQS_DP<0>")
	)
	(arc
		(start 80.137762 -222.960184)
		(mid 80.318217 -223.16185)
		(end 80.38338 -223.424496)
		(width 0.09525)
		(layer "In4.Cu")
		(net "M_D_CPU1_SA_DQS_DP<0>")
	)
	(arc
		(start 86.589616 -226.98964)
		(mid 86.871048 -226.913885)
		(end 87.15248 -226.98964)
		(width 0.09525)
		(layer "In4.Cu")
		(net "M_D_CPU1_SA_DQS_DP<0>")
	)
	(arc
		(start 79.442818 -221.804484)
		(mid 79.484417 -221.976863)
		(end 79.600044 -222.111316)
		(width 0.09525)
		(layer "In4.Cu")
		(net "M_D_CPU1_SA_DQS_DP<0>")
	)
	(arc
		(start 90.826336 -226.948746)
		(mid 90.836279 -226.952589)
		(end 90.846148 -226.95662)
		(width 0.09525)
		(layer "In4.Cu")
		(net "M_D_CPU1_SA_DQS_DP<0>")
	)
	(arc
		(start 82.829654 -226.98964)
		(mid 83.111086 -226.913885)
		(end 83.392518 -226.98964)
		(width 0.09525)
		(layer "In4.Cu")
		(net "M_D_CPU1_SA_DQS_DP<0>")
	)
	(arc
		(start 82.460846 -226.994466)
		(mid 82.645878 -227.04038)
		(end 82.829654 -226.98964)
		(width 0.09525)
		(layer "In4.Cu")
		(net "M_D_CPU1_SA_DQS_DP<0>")
	)
	(arc
		(start 81.55051 -225.391726)
		(mid 81.72896 -225.593196)
		(end 81.793334 -225.854514)
		(width 0.09525)
		(layer "In4.Cu")
		(net "M_D_CPU1_SA_DQS_DP<0>")
	)
	(arc
		(start 87.52967 -226.98964)
		(mid 87.811102 -226.913885)
		(end 88.092534 -226.98964)
		(width 0.09525)
		(layer "In4.Cu")
		(net "M_D_CPU1_SA_DQS_DP<0>")
	)
	(arc
		(start 81.793334 -225.854514)
		(mid 81.834791 -226.026554)
		(end 81.950052 -226.160838)
		(width 0.09525)
		(layer "In4.Cu")
		(net "M_D_CPU1_SA_DQS_DP<0>")
	)
	(arc
		(start 79.913734 -222.61449)
		(mid 79.955399 -222.786937)
		(end 80.071214 -222.921322)
		(width 0.09525)
		(layer "In4.Cu")
		(net "M_D_CPU1_SA_DQS_DP<0>")
	)
	(arc
		(start 88.469724 -226.98964)
		(mid 88.751156 -226.913885)
		(end 89.032588 -226.98964)
		(width 0.09525)
		(layer "In4.Cu")
		(net "M_D_CPU1_SA_DQS_DP<0>")
	)
	(arc
		(start 87.160862 -226.994466)
		(mid 87.345894 -227.04038)
		(end 87.52967 -226.98964)
		(width 0.09525)
		(layer "In4.Cu")
		(net "M_D_CPU1_SA_DQS_DP<0>")
	)
	(arc
		(start 86.212426 -226.98964)
		(mid 86.396201 -227.040412)
		(end 86.581234 -226.994466)
		(width 0.09525)
		(layer "In4.Cu")
		(net "M_D_CPU1_SA_DQS_DP<0>")
	)
	(arc
		(start 81.323434 -225.044508)
		(mid 81.365099 -225.216955)
		(end 81.480914 -225.35134)
		(width 0.09525)
		(layer "In4.Cu")
		(net "M_D_CPU1_SA_DQS_DP<0>")
	)
	(arc
		(start 82.263234 -226.66452)
		(mid 82.304691 -226.83656)
		(end 82.419952 -226.970844)
		(width 0.09525)
		(layer "In4.Cu")
		(net "M_D_CPU1_SA_DQS_DP<0>")
	)
	(arc
		(start 84.332572 -226.98964)
		(mid 84.52104 -227.040317)
		(end 84.709508 -226.98964)
		(width 0.09525)
		(layer "In4.Cu")
		(net "M_D_CPU1_SA_DQS_DP<0>")
	)
	(arc
		(start 89.032588 -226.98964)
		(mid 89.221056 -227.040317)
		(end 89.409524 -226.98964)
		(width 0.09525)
		(layer "In4.Cu")
		(net "M_D_CPU1_SA_DQS_DP<0>")
	)
	(arc
		(start 83.769708 -226.98964)
		(mid 84.05114 -226.913885)
		(end 84.332572 -226.98964)
		(width 0.09525)
		(layer "In4.Cu")
		(net "M_D_CPU1_SA_DQS_DP<0>")
	)
	(arc
		(start 88.100916 -226.994466)
		(mid 88.285948 -227.04038)
		(end 88.469724 -226.98964)
		(width 0.09525)
		(layer "In4.Cu")
		(net "M_D_CPU1_SA_DQS_DP<0>")
	)
	(segment
		(start 92.97797 -247.180354)
		(end 92.511118 -246.914416)
		(width 0.12954)
		(layer "F.Cu")
		(net "M_D_CPU1_SA_DQS_DN<9>")
	)
	(segment
		(start 57.152794 -239.92332)
		(end 59.187588 -241.958114)
		(width 0.16002)
		(layer "In4.Cu")
		(net "M_D_CPU1_SA_DQS_DN<9>")
	)
	(segment
		(start 64.896746 -246.862346)
		(end 75.21321 -246.862346)
		(width 0.16002)
		(layer "In4.Cu")
		(net "M_D_CPU1_SA_DQS_DN<9>")
	)
	(segment
		(start 35.735514 -239.078516)
		(end 36.08197 -239.424972)
		(width 0.16002)
		(layer "In4.Cu")
		(net "M_D_CPU1_SA_DQS_DN<9>")
	)
	(segment
		(start 92.256356 -247.206516)
		(end 92.357194 -247.179846)
		(width 0.09525)
		(layer "In4.Cu")
		(net "M_D_CPU1_SA_DQS_DN<9>")
	)
	(segment
		(start 51.149758 -239.408208)
		(end 53.58765 -239.408208)
		(width 0.16002)
		(layer "In4.Cu")
		(net "M_D_CPU1_SA_DQS_DN<9>")
	)
	(segment
		(start 47.554896 -240.258346)
		(end 48.518826 -240.258346)
		(width 0.16002)
		(layer "In4.Cu")
		(net "M_D_CPU1_SA_DQS_DN<9>")
	)
	(segment
		(start 76.274422 -247.092724)
		(end 76.579984 -247.398286)
		(width 0.09525)
		(layer "In4.Cu")
		(net "M_D_CPU1_SA_DQS_DN<9>")
	)
	(segment
		(start 76.579984 -247.398286)
		(end 77.47635 -247.398286)
		(width 0.09525)
		(layer "In4.Cu")
		(net "M_D_CPU1_SA_DQS_DN<9>")
	)
	(segment
		(start 43.236896 -239.039146)
		(end 43.605958 -239.408208)
		(width 0.16002)
		(layer "In4.Cu")
		(net "M_D_CPU1_SA_DQS_DN<9>")
	)
	(segment
		(start 56.093614 -240.227612)
		(end 56.397906 -239.92332)
		(width 0.16002)
		(layer "In4.Cu")
		(net "M_D_CPU1_SA_DQS_DN<9>")
	)
	(segment
		(start 76.038456 -247.092724)
		(end 76.274422 -247.092724)
		(width 0.09525)
		(layer "In4.Cu")
		(net "M_D_CPU1_SA_DQS_DN<9>")
	)
	(segment
		(start 53.58765 -239.408208)
		(end 54.407054 -240.227612)
		(width 0.16002)
		(layer "In4.Cu")
		(net "M_D_CPU1_SA_DQS_DN<9>")
	)
	(segment
		(start 81.04251 -247.239536)
		(end 81.050892 -247.244362)
		(width 0.09525)
		(layer "In4.Cu")
		(net "M_D_CPU1_SA_DQS_DN<9>")
	)
	(segment
		(start 89.502488 -247.239536)
		(end 89.51087 -247.244362)
		(width 0.09525)
		(layer "In4.Cu")
		(net "M_D_CPU1_SA_DQS_DN<9>")
	)
	(segment
		(start 87.991188 -247.244362)
		(end 87.99957 -247.239536)
		(width 0.09525)
		(layer "In4.Cu")
		(net "M_D_CPU1_SA_DQS_DN<9>")
	)
	(segment
		(start 84.231226 -247.244362)
		(end 84.239608 -247.239536)
		(width 0.09525)
		(layer "In4.Cu")
		(net "M_D_CPU1_SA_DQS_DN<9>")
	)
	(segment
		(start 80.471264 -247.244362)
		(end 80.479646 -247.239536)
		(width 0.09525)
		(layer "In4.Cu")
		(net "M_D_CPU1_SA_DQS_DN<9>")
	)
	(segment
		(start 92.357194 -247.179846)
		(end 92.511118 -246.914416)
		(width 0.09525)
		(layer "In4.Cu")
		(net "M_D_CPU1_SA_DQS_DN<9>")
	)
	(segment
		(start 34.877756 -239.259364)
		(end 35.058604 -239.078516)
		(width 0.16002)
		(layer "In4.Cu")
		(net "M_D_CPU1_SA_DQS_DN<9>")
	)
	(segment
		(start 83.291172 -247.244362)
		(end 83.299554 -247.239536)
		(width 0.09525)
		(layer "In4.Cu")
		(net "M_D_CPU1_SA_DQS_DN<9>")
	)
	(segment
		(start 41.310052 -239.92332)
		(end 41.787572 -239.92332)
		(width 0.16002)
		(layer "In4.Cu")
		(net "M_D_CPU1_SA_DQS_DN<9>")
	)
	(segment
		(start 38.47211 -239.424972)
		(end 39.305484 -240.258346)
		(width 0.16002)
		(layer "In4.Cu")
		(net "M_D_CPU1_SA_DQS_DN<9>")
	)
	(segment
		(start 43.605958 -239.408208)
		(end 45.501814 -239.408208)
		(width 0.16002)
		(layer "In4.Cu")
		(net "M_D_CPU1_SA_DQS_DN<9>")
	)
	(segment
		(start 32.695896 -238.985298)
		(end 32.969962 -239.259364)
		(width 0.16002)
		(layer "In4.Cu")
		(net "M_D_CPU1_SA_DQS_DN<9>")
	)
	(segment
		(start 78.599284 -247.239536)
		(end 78.614016 -247.2309)
		(width 0.09525)
		(layer "In4.Cu")
		(net "M_D_CPU1_SA_DQS_DN<9>")
	)
	(segment
		(start 75.955906 -247.033796)
		(end 75.979528 -247.033796)
		(width 0.09525)
		(layer "In4.Cu")
		(net "M_D_CPU1_SA_DQS_DN<9>")
	)
	(segment
		(start 32.969962 -239.259364)
		(end 34.877756 -239.259364)
		(width 0.16002)
		(layer "In4.Cu")
		(net "M_D_CPU1_SA_DQS_DN<9>")
	)
	(segment
		(start 45.501814 -239.408208)
		(end 47.554896 -240.258346)
		(width 0.16002)
		(layer "In4.Cu")
		(net "M_D_CPU1_SA_DQS_DN<9>")
	)
	(segment
		(start 40.975026 -240.258346)
		(end 41.310052 -239.92332)
		(width 0.16002)
		(layer "In4.Cu")
		(net "M_D_CPU1_SA_DQS_DN<9>")
	)
	(segment
		(start 48.853852 -239.92332)
		(end 49.331372 -239.92332)
		(width 0.16002)
		(layer "In4.Cu")
		(net "M_D_CPU1_SA_DQS_DN<9>")
	)
	(segment
		(start 77.711046 -247.16359)
		(end 77.940154 -247.16359)
		(width 0.09525)
		(layer "In4.Cu")
		(net "M_D_CPU1_SA_DQS_DN<9>")
	)
	(segment
		(start 79.16164 -247.239536)
		(end 79.170022 -247.244362)
		(width 0.09525)
		(layer "In4.Cu")
		(net "M_D_CPU1_SA_DQS_DN<9>")
	)
	(segment
		(start 39.305484 -240.258346)
		(end 40.975026 -240.258346)
		(width 0.16002)
		(layer "In4.Cu")
		(net "M_D_CPU1_SA_DQS_DN<9>")
	)
	(segment
		(start 42.671746 -239.039146)
		(end 43.236896 -239.039146)
		(width 0.16002)
		(layer "In4.Cu")
		(net "M_D_CPU1_SA_DQS_DN<9>")
	)
	(segment
		(start 36.08197 -239.424972)
		(end 38.47211 -239.424972)
		(width 0.16002)
		(layer "In4.Cu")
		(net "M_D_CPU1_SA_DQS_DN<9>")
	)
	(segment
		(start 78.584806 -247.247918)
		(end 78.599284 -247.239536)
		(width 0.09525)
		(layer "In4.Cu")
		(net "M_D_CPU1_SA_DQS_DN<9>")
	)
	(segment
		(start 91.75115 -247.244362)
		(end 91.759532 -247.239536)
		(width 0.09525)
		(layer "In4.Cu")
		(net "M_D_CPU1_SA_DQS_DN<9>")
	)
	(segment
		(start 59.992514 -241.958114)
		(end 64.896746 -246.862346)
		(width 0.16002)
		(layer "In4.Cu")
		(net "M_D_CPU1_SA_DQS_DN<9>")
	)
	(segment
		(start 35.058604 -239.078516)
		(end 35.735514 -239.078516)
		(width 0.16002)
		(layer "In4.Cu")
		(net "M_D_CPU1_SA_DQS_DN<9>")
	)
	(segment
		(start 85.742526 -247.239536)
		(end 85.750908 -247.244362)
		(width 0.09525)
		(layer "In4.Cu")
		(net "M_D_CPU1_SA_DQS_DN<9>")
	)
	(segment
		(start 48.518826 -240.258346)
		(end 48.853852 -239.92332)
		(width 0.16002)
		(layer "In4.Cu")
		(net "M_D_CPU1_SA_DQS_DN<9>")
	)
	(segment
		(start 41.787572 -239.92332)
		(end 42.671746 -239.039146)
		(width 0.16002)
		(layer "In4.Cu")
		(net "M_D_CPU1_SA_DQS_DN<9>")
	)
	(segment
		(start 49.331372 -239.92332)
		(end 50.215546 -239.039146)
		(width 0.16002)
		(layer "In4.Cu")
		(net "M_D_CPU1_SA_DQS_DN<9>")
	)
	(segment
		(start 75.979528 -247.033796)
		(end 76.038456 -247.092724)
		(width 0.09525)
		(layer "In4.Cu")
		(net "M_D_CPU1_SA_DQS_DN<9>")
	)
	(segment
		(start 80.092042 -247.23344)
		(end 80.102456 -247.239536)
		(width 0.09525)
		(layer "In4.Cu")
		(net "M_D_CPU1_SA_DQS_DN<9>")
	)
	(segment
		(start 75.38466 -247.033796)
		(end 75.955906 -247.033796)
		(width 0.16002)
		(layer "In4.Cu")
		(net "M_D_CPU1_SA_DQS_DN<9>")
	)
	(segment
		(start 50.215546 -239.039146)
		(end 50.780696 -239.039146)
		(width 0.16002)
		(layer "In4.Cu")
		(net "M_D_CPU1_SA_DQS_DN<9>")
	)
	(segment
		(start 84.802472 -247.239536)
		(end 84.810854 -247.244362)
		(width 0.09525)
		(layer "In4.Cu")
		(net "M_D_CPU1_SA_DQS_DN<9>")
	)
	(segment
		(start 59.187588 -241.958114)
		(end 59.992514 -241.958114)
		(width 0.16002)
		(layer "In4.Cu")
		(net "M_D_CPU1_SA_DQS_DN<9>")
	)
	(segment
		(start 50.780696 -239.039146)
		(end 51.149758 -239.408208)
		(width 0.16002)
		(layer "In4.Cu")
		(net "M_D_CPU1_SA_DQS_DN<9>")
	)
	(segment
		(start 54.407054 -240.227612)
		(end 56.093614 -240.227612)
		(width 0.16002)
		(layer "In4.Cu")
		(net "M_D_CPU1_SA_DQS_DN<9>")
	)
	(segment
		(start 77.47635 -247.398286)
		(end 77.711046 -247.16359)
		(width 0.09525)
		(layer "In4.Cu")
		(net "M_D_CPU1_SA_DQS_DN<9>")
	)
	(segment
		(start 75.21321 -246.862346)
		(end 75.38466 -247.033796)
		(width 0.16002)
		(layer "In4.Cu")
		(net "M_D_CPU1_SA_DQS_DN<9>")
	)
	(segment
		(start 88.931242 -247.244362)
		(end 88.939624 -247.239536)
		(width 0.09525)
		(layer "In4.Cu")
		(net "M_D_CPU1_SA_DQS_DN<9>")
	)
	(segment
		(start 56.397906 -239.92332)
		(end 57.152794 -239.92332)
		(width 0.16002)
		(layer "In4.Cu")
		(net "M_D_CPU1_SA_DQS_DN<9>")
	)
	(arc
		(start 86.119716 -247.239536)
		(mid 86.401148 -247.163781)
		(end 86.68258 -247.239536)
		(width 0.09525)
		(layer "In4.Cu")
		(net "M_D_CPU1_SA_DQS_DN<9>")
	)
	(arc
		(start 85.750908 -247.244362)
		(mid 85.93594 -247.290276)
		(end 86.119716 -247.239536)
		(width 0.09525)
		(layer "In4.Cu")
		(net "M_D_CPU1_SA_DQS_DN<9>")
	)
	(arc
		(start 80.102456 -247.239536)
		(mid 80.286231 -247.290308)
		(end 80.471264 -247.244362)
		(width 0.09525)
		(layer "In4.Cu")
		(net "M_D_CPU1_SA_DQS_DN<9>")
	)
	(arc
		(start 81.4197 -247.239536)
		(mid 81.701132 -247.163781)
		(end 81.982564 -247.239536)
		(width 0.09525)
		(layer "In4.Cu")
		(net "M_D_CPU1_SA_DQS_DN<9>")
	)
	(arc
		(start 79.170022 -247.244362)
		(mid 79.355308 -247.290398)
		(end 79.539338 -247.239536)
		(width 0.09525)
		(layer "In4.Cu")
		(net "M_D_CPU1_SA_DQS_DN<9>")
	)
	(arc
		(start 79.539338 -247.239536)
		(mid 79.814881 -247.163687)
		(end 80.092042 -247.23344)
		(width 0.09525)
		(layer "In4.Cu")
		(net "M_D_CPU1_SA_DQS_DN<9>")
	)
	(arc
		(start 77.940154 -247.16359)
		(mid 78.086149 -247.182908)
		(end 78.222094 -247.239536)
		(width 0.09525)
		(layer "In4.Cu")
		(net "M_D_CPU1_SA_DQS_DN<9>")
	)
	(arc
		(start 88.562434 -247.239536)
		(mid 88.746209 -247.290308)
		(end 88.931242 -247.244362)
		(width 0.09525)
		(layer "In4.Cu")
		(net "M_D_CPU1_SA_DQS_DN<9>")
	)
	(arc
		(start 81.982564 -247.239536)
		(mid 82.171032 -247.290213)
		(end 82.3595 -247.239536)
		(width 0.09525)
		(layer "In4.Cu")
		(net "M_D_CPU1_SA_DQS_DN<9>")
	)
	(arc
		(start 85.179662 -247.239536)
		(mid 85.461094 -247.163781)
		(end 85.742526 -247.239536)
		(width 0.09525)
		(layer "In4.Cu")
		(net "M_D_CPU1_SA_DQS_DN<9>")
	)
	(arc
		(start 83.862418 -247.239536)
		(mid 84.046193 -247.290308)
		(end 84.231226 -247.244362)
		(width 0.09525)
		(layer "In4.Cu")
		(net "M_D_CPU1_SA_DQS_DN<9>")
	)
	(arc
		(start 89.51087 -247.244362)
		(mid 89.695902 -247.290276)
		(end 89.879678 -247.239536)
		(width 0.09525)
		(layer "In4.Cu")
		(net "M_D_CPU1_SA_DQS_DN<9>")
	)
	(arc
		(start 82.922364 -247.239536)
		(mid 83.106139 -247.290308)
		(end 83.291172 -247.244362)
		(width 0.09525)
		(layer "In4.Cu")
		(net "M_D_CPU1_SA_DQS_DN<9>")
	)
	(arc
		(start 84.810854 -247.244362)
		(mid 84.995886 -247.290276)
		(end 85.179662 -247.239536)
		(width 0.09525)
		(layer "In4.Cu")
		(net "M_D_CPU1_SA_DQS_DN<9>")
	)
	(arc
		(start 92.235782 -247.198388)
		(mid 92.24611 -247.202348)
		(end 92.256356 -247.206516)
		(width 0.09525)
		(layer "In4.Cu")
		(net "M_D_CPU1_SA_DQS_DN<9>")
	)
	(arc
		(start 89.879678 -247.239536)
		(mid 90.16111 -247.163781)
		(end 90.442542 -247.239536)
		(width 0.09525)
		(layer "In4.Cu")
		(net "M_D_CPU1_SA_DQS_DN<9>")
	)
	(arc
		(start 82.3595 -247.239536)
		(mid 82.640932 -247.163781)
		(end 82.922364 -247.239536)
		(width 0.09525)
		(layer "In4.Cu")
		(net "M_D_CPU1_SA_DQS_DN<9>")
	)
	(arc
		(start 91.382342 -247.239536)
		(mid 91.566117 -247.290308)
		(end 91.75115 -247.244362)
		(width 0.09525)
		(layer "In4.Cu")
		(net "M_D_CPU1_SA_DQS_DN<9>")
	)
	(arc
		(start 78.222094 -247.239536)
		(mid 78.402373 -247.290367)
		(end 78.584806 -247.247918)
		(width 0.09525)
		(layer "In4.Cu")
		(net "M_D_CPU1_SA_DQS_DN<9>")
	)
	(arc
		(start 84.239608 -247.239536)
		(mid 84.52104 -247.163781)
		(end 84.802472 -247.239536)
		(width 0.09525)
		(layer "In4.Cu")
		(net "M_D_CPU1_SA_DQS_DN<9>")
	)
	(arc
		(start 81.050892 -247.244362)
		(mid 81.235924 -247.290276)
		(end 81.4197 -247.239536)
		(width 0.09525)
		(layer "In4.Cu")
		(net "M_D_CPU1_SA_DQS_DN<9>")
	)
	(arc
		(start 91.759532 -247.239536)
		(mid 91.993046 -247.165693)
		(end 92.235782 -247.198388)
		(width 0.09525)
		(layer "In4.Cu")
		(net "M_D_CPU1_SA_DQS_DN<9>")
	)
	(arc
		(start 80.479646 -247.239536)
		(mid 80.761078 -247.163781)
		(end 81.04251 -247.239536)
		(width 0.09525)
		(layer "In4.Cu")
		(net "M_D_CPU1_SA_DQS_DN<9>")
	)
	(arc
		(start 90.442542 -247.239536)
		(mid 90.63101 -247.290213)
		(end 90.819478 -247.239536)
		(width 0.09525)
		(layer "In4.Cu")
		(net "M_D_CPU1_SA_DQS_DN<9>")
	)
	(arc
		(start 87.62238 -247.239536)
		(mid 87.806155 -247.290308)
		(end 87.991188 -247.244362)
		(width 0.09525)
		(layer "In4.Cu")
		(net "M_D_CPU1_SA_DQS_DN<9>")
	)
	(arc
		(start 87.99957 -247.239536)
		(mid 88.281002 -247.163781)
		(end 88.562434 -247.239536)
		(width 0.09525)
		(layer "In4.Cu")
		(net "M_D_CPU1_SA_DQS_DN<9>")
	)
	(arc
		(start 90.819478 -247.239536)
		(mid 91.10091 -247.163781)
		(end 91.382342 -247.239536)
		(width 0.09525)
		(layer "In4.Cu")
		(net "M_D_CPU1_SA_DQS_DN<9>")
	)
	(arc
		(start 88.939624 -247.239536)
		(mid 89.221056 -247.163781)
		(end 89.502488 -247.239536)
		(width 0.09525)
		(layer "In4.Cu")
		(net "M_D_CPU1_SA_DQS_DN<9>")
	)
	(arc
		(start 83.299554 -247.239536)
		(mid 83.580986 -247.163781)
		(end 83.862418 -247.239536)
		(width 0.09525)
		(layer "In4.Cu")
		(net "M_D_CPU1_SA_DQS_DN<9>")
	)
	(arc
		(start 78.614016 -247.2309)
		(mid 78.888967 -247.163757)
		(end 79.16164 -247.239536)
		(width 0.09525)
		(layer "In4.Cu")
		(net "M_D_CPU1_SA_DQS_DN<9>")
	)
	(arc
		(start 87.059516 -247.239536)
		(mid 87.340948 -247.163781)
		(end 87.62238 -247.239536)
		(width 0.09525)
		(layer "In4.Cu")
		(net "M_D_CPU1_SA_DQS_DN<9>")
	)
	(arc
		(start 86.68258 -247.239536)
		(mid 86.871048 -247.290213)
		(end 87.059516 -247.239536)
		(width 0.09525)
		(layer "In4.Cu")
		(net "M_D_CPU1_SA_DQS_DN<9>")
	)
	(segment
		(start 92.97797 -242.320318)
		(end 92.511118 -242.05438)
		(width 0.12954)
		(layer "F.Cu")
		(net "M_D_CPU1_SA_DQS_DN<8>")
	)
	(segment
		(start 50.215546 -229.689152)
		(end 50.780696 -229.689152)
		(width 0.16002)
		(layer "In4.Cu")
		(net "M_D_CPU1_SA_DQS_DN<8>")
	)
	(segment
		(start 77.42047 -241.975386)
		(end 77.748638 -242.303554)
		(width 0.09525)
		(layer "In4.Cu")
		(net "M_D_CPU1_SA_DQS_DN<8>")
	)
	(segment
		(start 84.231226 -242.384326)
		(end 84.239608 -242.3795)
		(width 0.09525)
		(layer "In4.Cu")
		(net "M_D_CPU1_SA_DQS_DN<8>")
	)
	(segment
		(start 50.780696 -229.689152)
		(end 51.149758 -230.058214)
		(width 0.16002)
		(layer "In4.Cu")
		(net "M_D_CPU1_SA_DQS_DN<8>")
	)
	(segment
		(start 34.983674 -229.728522)
		(end 35.735514 -229.728522)
		(width 0.16002)
		(layer "In4.Cu")
		(net "M_D_CPU1_SA_DQS_DN<8>")
	)
	(segment
		(start 46.816264 -230.908352)
		(end 48.518826 -230.908352)
		(width 0.16002)
		(layer "In4.Cu")
		(net "M_D_CPU1_SA_DQS_DN<8>")
	)
	(segment
		(start 75.89774 -241.247168)
		(end 75.921362 -241.247168)
		(width 0.09525)
		(layer "In4.Cu")
		(net "M_D_CPU1_SA_DQS_DN<8>")
	)
	(segment
		(start 76.42606 -241.521996)
		(end 76.42606 -241.647726)
		(width 0.09525)
		(layer "In4.Cu")
		(net "M_D_CPU1_SA_DQS_DN<8>")
	)
	(segment
		(start 48.518826 -230.908352)
		(end 48.853852 -230.573326)
		(width 0.16002)
		(layer "In4.Cu")
		(net "M_D_CPU1_SA_DQS_DN<8>")
	)
	(segment
		(start 41.310052 -230.573326)
		(end 41.787572 -230.573326)
		(width 0.16002)
		(layer "In4.Cu")
		(net "M_D_CPU1_SA_DQS_DN<8>")
	)
	(segment
		(start 49.331372 -230.573326)
		(end 50.215546 -229.689152)
		(width 0.16002)
		(layer "In4.Cu")
		(net "M_D_CPU1_SA_DQS_DN<8>")
	)
	(segment
		(start 56.397906 -230.573326)
		(end 57.37225 -230.573326)
		(width 0.16002)
		(layer "In4.Cu")
		(net "M_D_CPU1_SA_DQS_DN<8>")
	)
	(segment
		(start 78.599284 -242.3795)
		(end 78.620112 -242.367308)
		(width 0.09525)
		(layer "In4.Cu")
		(net "M_D_CPU1_SA_DQS_DN<8>")
	)
	(segment
		(start 42.671746 -229.689152)
		(end 43.236896 -229.689152)
		(width 0.16002)
		(layer "In4.Cu")
		(net "M_D_CPU1_SA_DQS_DN<8>")
	)
	(segment
		(start 53.58257 -230.058214)
		(end 54.401974 -230.877618)
		(width 0.16002)
		(layer "In4.Cu")
		(net "M_D_CPU1_SA_DQS_DN<8>")
	)
	(segment
		(start 88.931242 -242.384326)
		(end 88.939624 -242.3795)
		(width 0.09525)
		(layer "In4.Cu")
		(net "M_D_CPU1_SA_DQS_DN<8>")
	)
	(segment
		(start 57.37225 -230.573326)
		(end 57.707276 -230.908352)
		(width 0.16002)
		(layer "In4.Cu")
		(net "M_D_CPU1_SA_DQS_DN<8>")
	)
	(segment
		(start 75.921362 -241.247168)
		(end 75.98029 -241.306096)
		(width 0.09525)
		(layer "In4.Cu")
		(net "M_D_CPU1_SA_DQS_DN<8>")
	)
	(segment
		(start 39.305484 -230.908352)
		(end 40.975026 -230.908352)
		(width 0.16002)
		(layer "In4.Cu")
		(net "M_D_CPU1_SA_DQS_DN<8>")
	)
	(segment
		(start 43.236896 -229.689152)
		(end 43.605958 -230.058214)
		(width 0.16002)
		(layer "In4.Cu")
		(net "M_D_CPU1_SA_DQS_DN<8>")
	)
	(segment
		(start 80.471264 -242.384326)
		(end 80.479646 -242.3795)
		(width 0.09525)
		(layer "In4.Cu")
		(net "M_D_CPU1_SA_DQS_DN<8>")
	)
	(segment
		(start 78.584806 -242.387882)
		(end 78.599284 -242.3795)
		(width 0.09525)
		(layer "In4.Cu")
		(net "M_D_CPU1_SA_DQS_DN<8>")
	)
	(segment
		(start 77.748638 -242.303554)
		(end 77.940154 -242.303554)
		(width 0.09525)
		(layer "In4.Cu")
		(net "M_D_CPU1_SA_DQS_DN<8>")
	)
	(segment
		(start 51.149758 -230.058214)
		(end 53.58257 -230.058214)
		(width 0.16002)
		(layer "In4.Cu")
		(net "M_D_CPU1_SA_DQS_DN<8>")
	)
	(segment
		(start 54.401974 -230.877618)
		(end 56.093614 -230.877618)
		(width 0.16002)
		(layer "In4.Cu")
		(net "M_D_CPU1_SA_DQS_DN<8>")
	)
	(segment
		(start 91.75115 -242.384326)
		(end 91.759532 -242.3795)
		(width 0.09525)
		(layer "In4.Cu")
		(net "M_D_CPU1_SA_DQS_DN<8>")
	)
	(segment
		(start 76.21016 -241.306096)
		(end 76.42606 -241.521996)
		(width 0.09525)
		(layer "In4.Cu")
		(net "M_D_CPU1_SA_DQS_DN<8>")
	)
	(segment
		(start 83.291172 -242.384326)
		(end 83.299554 -242.3795)
		(width 0.09525)
		(layer "In4.Cu")
		(net "M_D_CPU1_SA_DQS_DN<8>")
	)
	(segment
		(start 89.502488 -242.3795)
		(end 89.51087 -242.384326)
		(width 0.09525)
		(layer "In4.Cu")
		(net "M_D_CPU1_SA_DQS_DN<8>")
	)
	(segment
		(start 70.3326 -241.247168)
		(end 75.89774 -241.247168)
		(width 0.16002)
		(layer "In4.Cu")
		(net "M_D_CPU1_SA_DQS_DN<8>")
	)
	(segment
		(start 59.993784 -230.908352)
		(end 70.3326 -241.247168)
		(width 0.16002)
		(layer "In4.Cu")
		(net "M_D_CPU1_SA_DQS_DN<8>")
	)
	(segment
		(start 81.04251 -242.3795)
		(end 81.050892 -242.384326)
		(width 0.09525)
		(layer "In4.Cu")
		(net "M_D_CPU1_SA_DQS_DN<8>")
	)
	(segment
		(start 32.695896 -229.635304)
		(end 32.969708 -229.909116)
		(width 0.16002)
		(layer "In4.Cu")
		(net "M_D_CPU1_SA_DQS_DN<8>")
	)
	(segment
		(start 36.08197 -230.074978)
		(end 38.47211 -230.074978)
		(width 0.16002)
		(layer "In4.Cu")
		(net "M_D_CPU1_SA_DQS_DN<8>")
	)
	(segment
		(start 41.787572 -230.573326)
		(end 42.671746 -229.689152)
		(width 0.16002)
		(layer "In4.Cu")
		(net "M_D_CPU1_SA_DQS_DN<8>")
	)
	(segment
		(start 32.969708 -229.909116)
		(end 34.80308 -229.909116)
		(width 0.16002)
		(layer "In4.Cu")
		(net "M_D_CPU1_SA_DQS_DN<8>")
	)
	(segment
		(start 45.966126 -230.058214)
		(end 46.816264 -230.908352)
		(width 0.16002)
		(layer "In4.Cu")
		(net "M_D_CPU1_SA_DQS_DN<8>")
	)
	(segment
		(start 84.802472 -242.3795)
		(end 84.810854 -242.384326)
		(width 0.09525)
		(layer "In4.Cu")
		(net "M_D_CPU1_SA_DQS_DN<8>")
	)
	(segment
		(start 48.853852 -230.573326)
		(end 49.331372 -230.573326)
		(width 0.16002)
		(layer "In4.Cu")
		(net "M_D_CPU1_SA_DQS_DN<8>")
	)
	(segment
		(start 85.742526 -242.3795)
		(end 85.750908 -242.384326)
		(width 0.09525)
		(layer "In4.Cu")
		(net "M_D_CPU1_SA_DQS_DN<8>")
	)
	(segment
		(start 75.98029 -241.306096)
		(end 76.21016 -241.306096)
		(width 0.09525)
		(layer "In4.Cu")
		(net "M_D_CPU1_SA_DQS_DN<8>")
	)
	(segment
		(start 38.47211 -230.074978)
		(end 39.305484 -230.908352)
		(width 0.16002)
		(layer "In4.Cu")
		(net "M_D_CPU1_SA_DQS_DN<8>")
	)
	(segment
		(start 57.707276 -230.908352)
		(end 59.993784 -230.908352)
		(width 0.16002)
		(layer "In4.Cu")
		(net "M_D_CPU1_SA_DQS_DN<8>")
	)
	(segment
		(start 35.735514 -229.728522)
		(end 36.08197 -230.074978)
		(width 0.16002)
		(layer "In4.Cu")
		(net "M_D_CPU1_SA_DQS_DN<8>")
	)
	(segment
		(start 56.093614 -230.877618)
		(end 56.397906 -230.573326)
		(width 0.16002)
		(layer "In4.Cu")
		(net "M_D_CPU1_SA_DQS_DN<8>")
	)
	(segment
		(start 87.991188 -242.384326)
		(end 87.99957 -242.3795)
		(width 0.09525)
		(layer "In4.Cu")
		(net "M_D_CPU1_SA_DQS_DN<8>")
	)
	(segment
		(start 79.527654 -242.386358)
		(end 79.539592 -242.3795)
		(width 0.09525)
		(layer "In4.Cu")
		(net "M_D_CPU1_SA_DQS_DN<8>")
	)
	(segment
		(start 34.80308 -229.909116)
		(end 34.983674 -229.728522)
		(width 0.16002)
		(layer "In4.Cu")
		(net "M_D_CPU1_SA_DQS_DN<8>")
	)
	(segment
		(start 92.256356 -242.34648)
		(end 92.357194 -242.31981)
		(width 0.09525)
		(layer "In4.Cu")
		(net "M_D_CPU1_SA_DQS_DN<8>")
	)
	(segment
		(start 43.605958 -230.058214)
		(end 45.966126 -230.058214)
		(width 0.16002)
		(layer "In4.Cu")
		(net "M_D_CPU1_SA_DQS_DN<8>")
	)
	(segment
		(start 92.357194 -242.31981)
		(end 92.511118 -242.05438)
		(width 0.09525)
		(layer "In4.Cu")
		(net "M_D_CPU1_SA_DQS_DN<8>")
	)
	(segment
		(start 76.75372 -241.975386)
		(end 77.42047 -241.975386)
		(width 0.09525)
		(layer "In4.Cu")
		(net "M_D_CPU1_SA_DQS_DN<8>")
	)
	(segment
		(start 40.975026 -230.908352)
		(end 41.310052 -230.573326)
		(width 0.16002)
		(layer "In4.Cu")
		(net "M_D_CPU1_SA_DQS_DN<8>")
	)
	(segment
		(start 76.42606 -241.647726)
		(end 76.75372 -241.975386)
		(width 0.09525)
		(layer "In4.Cu")
		(net "M_D_CPU1_SA_DQS_DN<8>")
	)
	(arc
		(start 84.810854 -242.384326)
		(mid 84.995886 -242.43024)
		(end 85.179662 -242.3795)
		(width 0.09525)
		(layer "In4.Cu")
		(net "M_D_CPU1_SA_DQS_DN<8>")
	)
	(arc
		(start 90.819478 -242.3795)
		(mid 91.10091 -242.303745)
		(end 91.382342 -242.3795)
		(width 0.09525)
		(layer "In4.Cu")
		(net "M_D_CPU1_SA_DQS_DN<8>")
	)
	(arc
		(start 80.479646 -242.3795)
		(mid 80.761078 -242.303745)
		(end 81.04251 -242.3795)
		(width 0.09525)
		(layer "In4.Cu")
		(net "M_D_CPU1_SA_DQS_DN<8>")
	)
	(arc
		(start 92.235782 -242.338352)
		(mid 92.24611 -242.342312)
		(end 92.256356 -242.34648)
		(width 0.09525)
		(layer "In4.Cu")
		(net "M_D_CPU1_SA_DQS_DN<8>")
	)
	(arc
		(start 89.51087 -242.384326)
		(mid 89.695902 -242.43024)
		(end 89.879678 -242.3795)
		(width 0.09525)
		(layer "In4.Cu")
		(net "M_D_CPU1_SA_DQS_DN<8>")
	)
	(arc
		(start 89.879678 -242.3795)
		(mid 90.16111 -242.303745)
		(end 90.442542 -242.3795)
		(width 0.09525)
		(layer "In4.Cu")
		(net "M_D_CPU1_SA_DQS_DN<8>")
	)
	(arc
		(start 91.759532 -242.3795)
		(mid 91.993046 -242.305657)
		(end 92.235782 -242.338352)
		(width 0.09525)
		(layer "In4.Cu")
		(net "M_D_CPU1_SA_DQS_DN<8>")
	)
	(arc
		(start 80.102456 -242.3795)
		(mid 80.286231 -242.430272)
		(end 80.471264 -242.384326)
		(width 0.09525)
		(layer "In4.Cu")
		(net "M_D_CPU1_SA_DQS_DN<8>")
	)
	(arc
		(start 88.939624 -242.3795)
		(mid 89.221056 -242.303745)
		(end 89.502488 -242.3795)
		(width 0.09525)
		(layer "In4.Cu")
		(net "M_D_CPU1_SA_DQS_DN<8>")
	)
	(arc
		(start 81.4197 -242.3795)
		(mid 81.701132 -242.303745)
		(end 81.982564 -242.3795)
		(width 0.09525)
		(layer "In4.Cu")
		(net "M_D_CPU1_SA_DQS_DN<8>")
	)
	(arc
		(start 81.050892 -242.384326)
		(mid 81.235924 -242.43024)
		(end 81.4197 -242.3795)
		(width 0.09525)
		(layer "In4.Cu")
		(net "M_D_CPU1_SA_DQS_DN<8>")
	)
	(arc
		(start 85.750908 -242.384326)
		(mid 85.93594 -242.43024)
		(end 86.119716 -242.3795)
		(width 0.09525)
		(layer "In4.Cu")
		(net "M_D_CPU1_SA_DQS_DN<8>")
	)
	(arc
		(start 88.562434 -242.3795)
		(mid 88.746209 -242.430272)
		(end 88.931242 -242.384326)
		(width 0.09525)
		(layer "In4.Cu")
		(net "M_D_CPU1_SA_DQS_DN<8>")
	)
	(arc
		(start 79.539592 -242.3795)
		(mid 79.821024 -242.303745)
		(end 80.102456 -242.3795)
		(width 0.09525)
		(layer "In4.Cu")
		(net "M_D_CPU1_SA_DQS_DN<8>")
	)
	(arc
		(start 83.299554 -242.3795)
		(mid 83.580986 -242.303745)
		(end 83.862418 -242.3795)
		(width 0.09525)
		(layer "In4.Cu")
		(net "M_D_CPU1_SA_DQS_DN<8>")
	)
	(arc
		(start 78.222094 -242.3795)
		(mid 78.402373 -242.430331)
		(end 78.584806 -242.387882)
		(width 0.09525)
		(layer "In4.Cu")
		(net "M_D_CPU1_SA_DQS_DN<8>")
	)
	(arc
		(start 86.68258 -242.3795)
		(mid 86.871048 -242.430177)
		(end 87.059516 -242.3795)
		(width 0.09525)
		(layer "In4.Cu")
		(net "M_D_CPU1_SA_DQS_DN<8>")
	)
	(arc
		(start 81.982564 -242.3795)
		(mid 82.171032 -242.430177)
		(end 82.3595 -242.3795)
		(width 0.09525)
		(layer "In4.Cu")
		(net "M_D_CPU1_SA_DQS_DN<8>")
	)
	(arc
		(start 87.059516 -242.3795)
		(mid 87.340948 -242.303745)
		(end 87.62238 -242.3795)
		(width 0.09525)
		(layer "In4.Cu")
		(net "M_D_CPU1_SA_DQS_DN<8>")
	)
	(arc
		(start 87.62238 -242.3795)
		(mid 87.806155 -242.430272)
		(end 87.991188 -242.384326)
		(width 0.09525)
		(layer "In4.Cu")
		(net "M_D_CPU1_SA_DQS_DN<8>")
	)
	(arc
		(start 78.620112 -242.367308)
		(mid 78.892717 -242.303512)
		(end 79.162148 -242.3795)
		(width 0.09525)
		(layer "In4.Cu")
		(net "M_D_CPU1_SA_DQS_DN<8>")
	)
	(arc
		(start 77.940154 -242.303554)
		(mid 78.086149 -242.322872)
		(end 78.222094 -242.3795)
		(width 0.09525)
		(layer "In4.Cu")
		(net "M_D_CPU1_SA_DQS_DN<8>")
	)
	(arc
		(start 82.3595 -242.3795)
		(mid 82.640932 -242.303745)
		(end 82.922364 -242.3795)
		(width 0.09525)
		(layer "In4.Cu")
		(net "M_D_CPU1_SA_DQS_DN<8>")
	)
	(arc
		(start 90.442542 -242.3795)
		(mid 90.63101 -242.430177)
		(end 90.819478 -242.3795)
		(width 0.09525)
		(layer "In4.Cu")
		(net "M_D_CPU1_SA_DQS_DN<8>")
	)
	(arc
		(start 82.922364 -242.3795)
		(mid 83.106139 -242.430272)
		(end 83.291172 -242.384326)
		(width 0.09525)
		(layer "In4.Cu")
		(net "M_D_CPU1_SA_DQS_DN<8>")
	)
	(arc
		(start 91.382342 -242.3795)
		(mid 91.566117 -242.430272)
		(end 91.75115 -242.384326)
		(width 0.09525)
		(layer "In4.Cu")
		(net "M_D_CPU1_SA_DQS_DN<8>")
	)
	(arc
		(start 87.99957 -242.3795)
		(mid 88.281002 -242.303745)
		(end 88.562434 -242.3795)
		(width 0.09525)
		(layer "In4.Cu")
		(net "M_D_CPU1_SA_DQS_DN<8>")
	)
	(arc
		(start 86.119716 -242.3795)
		(mid 86.401148 -242.303745)
		(end 86.68258 -242.3795)
		(width 0.09525)
		(layer "In4.Cu")
		(net "M_D_CPU1_SA_DQS_DN<8>")
	)
	(arc
		(start 83.862418 -242.3795)
		(mid 84.046193 -242.430272)
		(end 84.231226 -242.384326)
		(width 0.09525)
		(layer "In4.Cu")
		(net "M_D_CPU1_SA_DQS_DN<8>")
	)
	(arc
		(start 84.239608 -242.3795)
		(mid 84.52104 -242.303745)
		(end 84.802472 -242.3795)
		(width 0.09525)
		(layer "In4.Cu")
		(net "M_D_CPU1_SA_DQS_DN<8>")
	)
	(arc
		(start 79.162148 -242.3795)
		(mid 79.344018 -242.430365)
		(end 79.527654 -242.386358)
		(width 0.09525)
		(layer "In4.Cu")
		(net "M_D_CPU1_SA_DQS_DN<8>")
	)
	(arc
		(start 85.179662 -242.3795)
		(mid 85.461094 -242.303745)
		(end 85.742526 -242.3795)
		(width 0.09525)
		(layer "In4.Cu")
		(net "M_D_CPU1_SA_DQS_DN<8>")
	)
	(segment
		(start 92.97797 -237.460282)
		(end 92.511118 -237.194344)
		(width 0.12954)
		(layer "F.Cu")
		(net "M_D_CPU1_SA_DQS_DN<7>")
	)
	(segment
		(start 77.015086 -236.048296)
		(end 77.39253 -236.42574)
		(width 0.09525)
		(layer "In4.Cu")
		(net "M_D_CPU1_SA_DQS_DN<7>")
	)
	(segment
		(start 73.80224 -235.629196)
		(end 75.955906 -235.629196)
		(width 0.16002)
		(layer "In4.Cu")
		(net "M_D_CPU1_SA_DQS_DN<7>")
	)
	(segment
		(start 84.231226 -237.52429)
		(end 84.239608 -237.519464)
		(width 0.09525)
		(layer "In4.Cu")
		(net "M_D_CPU1_SA_DQS_DN<7>")
	)
	(segment
		(start 88.931242 -237.52429)
		(end 88.939624 -237.519464)
		(width 0.09525)
		(layer "In4.Cu")
		(net "M_D_CPU1_SA_DQS_DN<7>")
	)
	(segment
		(start 42.671746 -220.339158)
		(end 43.236896 -220.339158)
		(width 0.16002)
		(layer "In4.Cu")
		(net "M_D_CPU1_SA_DQS_DN<7>")
	)
	(segment
		(start 56.397906 -221.223332)
		(end 57.337198 -221.223332)
		(width 0.16002)
		(layer "In4.Cu")
		(net "M_D_CPU1_SA_DQS_DN<7>")
	)
	(segment
		(start 76.038456 -235.688124)
		(end 76.250038 -235.688124)
		(width 0.09525)
		(layer "In4.Cu")
		(net "M_D_CPU1_SA_DQS_DN<7>")
	)
	(segment
		(start 87.991188 -237.52429)
		(end 87.99957 -237.519464)
		(width 0.09525)
		(layer "In4.Cu")
		(net "M_D_CPU1_SA_DQS_DN<7>")
	)
	(segment
		(start 76.250038 -235.688124)
		(end 76.61021 -236.048296)
		(width 0.09525)
		(layer "In4.Cu")
		(net "M_D_CPU1_SA_DQS_DN<7>")
	)
	(segment
		(start 35.735514 -220.378528)
		(end 36.08197 -220.724984)
		(width 0.16002)
		(layer "In4.Cu")
		(net "M_D_CPU1_SA_DQS_DN<7>")
	)
	(segment
		(start 57.337198 -221.223332)
		(end 57.67197 -221.558104)
		(width 0.16002)
		(layer "In4.Cu")
		(net "M_D_CPU1_SA_DQS_DN<7>")
	)
	(segment
		(start 79.524606 -237.529116)
		(end 79.54137 -237.519464)
		(width 0.09525)
		(layer "In4.Cu")
		(net "M_D_CPU1_SA_DQS_DN<7>")
	)
	(segment
		(start 60.08751 -221.558104)
		(end 60.76823 -222.238824)
		(width 0.16002)
		(layer "In4.Cu")
		(net "M_D_CPU1_SA_DQS_DN<7>")
	)
	(segment
		(start 48.51908 -221.558104)
		(end 48.853852 -221.223332)
		(width 0.16002)
		(layer "In4.Cu")
		(net "M_D_CPU1_SA_DQS_DN<7>")
	)
	(segment
		(start 79.54137 -237.519464)
		(end 79.568802 -237.503462)
		(width 0.09525)
		(layer "In4.Cu")
		(net "M_D_CPU1_SA_DQS_DN<7>")
	)
	(segment
		(start 46.81601 -221.558104)
		(end 48.51908 -221.558104)
		(width 0.16002)
		(layer "In4.Cu")
		(net "M_D_CPU1_SA_DQS_DN<7>")
	)
	(segment
		(start 39.30523 -221.558104)
		(end 40.97528 -221.558104)
		(width 0.16002)
		(layer "In4.Cu")
		(net "M_D_CPU1_SA_DQS_DN<7>")
	)
	(segment
		(start 41.787572 -221.223332)
		(end 42.671746 -220.339158)
		(width 0.16002)
		(layer "In4.Cu")
		(net "M_D_CPU1_SA_DQS_DN<7>")
	)
	(segment
		(start 60.76823 -222.595186)
		(end 73.80224 -235.629196)
		(width 0.16002)
		(layer "In4.Cu")
		(net "M_D_CPU1_SA_DQS_DN<7>")
	)
	(segment
		(start 91.75115 -237.52429)
		(end 91.759532 -237.519464)
		(width 0.09525)
		(layer "In4.Cu")
		(net "M_D_CPU1_SA_DQS_DN<7>")
	)
	(segment
		(start 92.256356 -237.486444)
		(end 92.357194 -237.459774)
		(width 0.09525)
		(layer "In4.Cu")
		(net "M_D_CPU1_SA_DQS_DN<7>")
	)
	(segment
		(start 76.61021 -236.048296)
		(end 77.015086 -236.048296)
		(width 0.09525)
		(layer "In4.Cu")
		(net "M_D_CPU1_SA_DQS_DN<7>")
	)
	(segment
		(start 45.966126 -220.70822)
		(end 46.81601 -221.558104)
		(width 0.16002)
		(layer "In4.Cu")
		(net "M_D_CPU1_SA_DQS_DN<7>")
	)
	(segment
		(start 75.979528 -235.629196)
		(end 76.038456 -235.688124)
		(width 0.09525)
		(layer "In4.Cu")
		(net "M_D_CPU1_SA_DQS_DN<7>")
	)
	(segment
		(start 48.853852 -221.223332)
		(end 49.331372 -221.223332)
		(width 0.16002)
		(layer "In4.Cu")
		(net "M_D_CPU1_SA_DQS_DN<7>")
	)
	(segment
		(start 36.08197 -220.724984)
		(end 38.47211 -220.724984)
		(width 0.16002)
		(layer "In4.Cu")
		(net "M_D_CPU1_SA_DQS_DN<7>")
	)
	(segment
		(start 32.969708 -220.559122)
		(end 34.884868 -220.559122)
		(width 0.16002)
		(layer "In4.Cu")
		(net "M_D_CPU1_SA_DQS_DN<7>")
	)
	(segment
		(start 60.76823 -222.238824)
		(end 60.76823 -222.595186)
		(width 0.16002)
		(layer "In4.Cu")
		(net "M_D_CPU1_SA_DQS_DN<7>")
	)
	(segment
		(start 92.357194 -237.459774)
		(end 92.511118 -237.194344)
		(width 0.09525)
		(layer "In4.Cu")
		(net "M_D_CPU1_SA_DQS_DN<7>")
	)
	(segment
		(start 75.955906 -235.629196)
		(end 75.979528 -235.629196)
		(width 0.09525)
		(layer "In4.Cu")
		(net "M_D_CPU1_SA_DQS_DN<7>")
	)
	(segment
		(start 34.884868 -220.559122)
		(end 35.065462 -220.378528)
		(width 0.16002)
		(layer "In4.Cu")
		(net "M_D_CPU1_SA_DQS_DN<7>")
	)
	(segment
		(start 51.149758 -220.70822)
		(end 53.561742 -220.70822)
		(width 0.16002)
		(layer "In4.Cu")
		(net "M_D_CPU1_SA_DQS_DN<7>")
	)
	(segment
		(start 53.561742 -220.70822)
		(end 54.381146 -221.527624)
		(width 0.16002)
		(layer "In4.Cu")
		(net "M_D_CPU1_SA_DQS_DN<7>")
	)
	(segment
		(start 50.780696 -220.339158)
		(end 51.149758 -220.70822)
		(width 0.16002)
		(layer "In4.Cu")
		(net "M_D_CPU1_SA_DQS_DN<7>")
	)
	(segment
		(start 50.215546 -220.339158)
		(end 50.780696 -220.339158)
		(width 0.16002)
		(layer "In4.Cu")
		(net "M_D_CPU1_SA_DQS_DN<7>")
	)
	(segment
		(start 40.97528 -221.558104)
		(end 41.310052 -221.223332)
		(width 0.16002)
		(layer "In4.Cu")
		(net "M_D_CPU1_SA_DQS_DN<7>")
	)
	(segment
		(start 38.47211 -220.724984)
		(end 39.30523 -221.558104)
		(width 0.16002)
		(layer "In4.Cu")
		(net "M_D_CPU1_SA_DQS_DN<7>")
	)
	(segment
		(start 79.141574 -237.505494)
		(end 79.16545 -237.519464)
		(width 0.09525)
		(layer "In4.Cu")
		(net "M_D_CPU1_SA_DQS_DN<7>")
	)
	(segment
		(start 49.331372 -221.223332)
		(end 50.215546 -220.339158)
		(width 0.16002)
		(layer "In4.Cu")
		(net "M_D_CPU1_SA_DQS_DN<7>")
	)
	(segment
		(start 85.742526 -237.519464)
		(end 85.750908 -237.52429)
		(width 0.09525)
		(layer "In4.Cu")
		(net "M_D_CPU1_SA_DQS_DN<7>")
	)
	(segment
		(start 84.802472 -237.519464)
		(end 84.810854 -237.52429)
		(width 0.09525)
		(layer "In4.Cu")
		(net "M_D_CPU1_SA_DQS_DN<7>")
	)
	(segment
		(start 54.381146 -221.527624)
		(end 56.093614 -221.527624)
		(width 0.16002)
		(layer "In4.Cu")
		(net "M_D_CPU1_SA_DQS_DN<7>")
	)
	(segment
		(start 77.39253 -236.42574)
		(end 77.39253 -236.717586)
		(width 0.09525)
		(layer "In4.Cu")
		(net "M_D_CPU1_SA_DQS_DN<7>")
	)
	(segment
		(start 81.04251 -237.519464)
		(end 81.050892 -237.52429)
		(width 0.09525)
		(layer "In4.Cu")
		(net "M_D_CPU1_SA_DQS_DN<7>")
	)
	(segment
		(start 41.310052 -221.223332)
		(end 41.787572 -221.223332)
		(width 0.16002)
		(layer "In4.Cu")
		(net "M_D_CPU1_SA_DQS_DN<7>")
	)
	(segment
		(start 89.502488 -237.519464)
		(end 89.51087 -237.52429)
		(width 0.09525)
		(layer "In4.Cu")
		(net "M_D_CPU1_SA_DQS_DN<7>")
	)
	(segment
		(start 43.236896 -220.339158)
		(end 43.605958 -220.70822)
		(width 0.16002)
		(layer "In4.Cu")
		(net "M_D_CPU1_SA_DQS_DN<7>")
	)
	(segment
		(start 80.471264 -237.52429)
		(end 80.479646 -237.519464)
		(width 0.09525)
		(layer "In4.Cu")
		(net "M_D_CPU1_SA_DQS_DN<7>")
	)
	(segment
		(start 35.065462 -220.378528)
		(end 35.735514 -220.378528)
		(width 0.16002)
		(layer "In4.Cu")
		(net "M_D_CPU1_SA_DQS_DN<7>")
	)
	(segment
		(start 43.605958 -220.70822)
		(end 45.966126 -220.70822)
		(width 0.16002)
		(layer "In4.Cu")
		(net "M_D_CPU1_SA_DQS_DN<7>")
	)
	(segment
		(start 56.093614 -221.527624)
		(end 56.397906 -221.223332)
		(width 0.16002)
		(layer "In4.Cu")
		(net "M_D_CPU1_SA_DQS_DN<7>")
	)
	(segment
		(start 77.39253 -236.717586)
		(end 78.246478 -237.571534)
		(width 0.09525)
		(layer "In4.Cu")
		(net "M_D_CPU1_SA_DQS_DN<7>")
	)
	(segment
		(start 78.246478 -237.571534)
		(end 78.41107 -237.571534)
		(width 0.09525)
		(layer "In4.Cu")
		(net "M_D_CPU1_SA_DQS_DN<7>")
	)
	(segment
		(start 83.291172 -237.52429)
		(end 83.299554 -237.519464)
		(width 0.09525)
		(layer "In4.Cu")
		(net "M_D_CPU1_SA_DQS_DN<7>")
	)
	(segment
		(start 32.695896 -220.28531)
		(end 32.969708 -220.559122)
		(width 0.16002)
		(layer "In4.Cu")
		(net "M_D_CPU1_SA_DQS_DN<7>")
	)
	(segment
		(start 57.67197 -221.558104)
		(end 60.08751 -221.558104)
		(width 0.16002)
		(layer "In4.Cu")
		(net "M_D_CPU1_SA_DQS_DN<7>")
	)
	(arc
		(start 82.922364 -237.519464)
		(mid 83.106139 -237.570236)
		(end 83.291172 -237.52429)
		(width 0.09525)
		(layer "In4.Cu")
		(net "M_D_CPU1_SA_DQS_DN<7>")
	)
	(arc
		(start 78.600808 -237.519718)
		(mid 78.869353 -237.443225)
		(end 79.141574 -237.505494)
		(width 0.09525)
		(layer "In4.Cu")
		(net "M_D_CPU1_SA_DQS_DN<7>")
	)
	(arc
		(start 88.939624 -237.519464)
		(mid 89.221056 -237.443709)
		(end 89.502488 -237.519464)
		(width 0.09525)
		(layer "In4.Cu")
		(net "M_D_CPU1_SA_DQS_DN<7>")
	)
	(arc
		(start 91.382342 -237.519464)
		(mid 91.566117 -237.570236)
		(end 91.75115 -237.52429)
		(width 0.09525)
		(layer "In4.Cu")
		(net "M_D_CPU1_SA_DQS_DN<7>")
	)
	(arc
		(start 80.102456 -237.519464)
		(mid 80.286231 -237.570236)
		(end 80.471264 -237.52429)
		(width 0.09525)
		(layer "In4.Cu")
		(net "M_D_CPU1_SA_DQS_DN<7>")
	)
	(arc
		(start 88.562434 -237.519464)
		(mid 88.746209 -237.570236)
		(end 88.931242 -237.52429)
		(width 0.09525)
		(layer "In4.Cu")
		(net "M_D_CPU1_SA_DQS_DN<7>")
	)
	(arc
		(start 81.982564 -237.519464)
		(mid 82.171032 -237.570141)
		(end 82.3595 -237.519464)
		(width 0.09525)
		(layer "In4.Cu")
		(net "M_D_CPU1_SA_DQS_DN<7>")
	)
	(arc
		(start 81.050892 -237.52429)
		(mid 81.235924 -237.570204)
		(end 81.4197 -237.519464)
		(width 0.09525)
		(layer "In4.Cu")
		(net "M_D_CPU1_SA_DQS_DN<7>")
	)
	(arc
		(start 87.99957 -237.519464)
		(mid 88.281002 -237.443709)
		(end 88.562434 -237.519464)
		(width 0.09525)
		(layer "In4.Cu")
		(net "M_D_CPU1_SA_DQS_DN<7>")
	)
	(arc
		(start 89.879678 -237.519464)
		(mid 90.16111 -237.443709)
		(end 90.442542 -237.519464)
		(width 0.09525)
		(layer "In4.Cu")
		(net "M_D_CPU1_SA_DQS_DN<7>")
	)
	(arc
		(start 83.299554 -237.519464)
		(mid 83.580986 -237.443709)
		(end 83.862418 -237.519464)
		(width 0.09525)
		(layer "In4.Cu")
		(net "M_D_CPU1_SA_DQS_DN<7>")
	)
	(arc
		(start 87.62238 -237.519464)
		(mid 87.806155 -237.570236)
		(end 87.991188 -237.52429)
		(width 0.09525)
		(layer "In4.Cu")
		(net "M_D_CPU1_SA_DQS_DN<7>")
	)
	(arc
		(start 86.119716 -237.519464)
		(mid 86.401148 -237.443709)
		(end 86.68258 -237.519464)
		(width 0.09525)
		(layer "In4.Cu")
		(net "M_D_CPU1_SA_DQS_DN<7>")
	)
	(arc
		(start 87.059516 -237.519464)
		(mid 87.340948 -237.443709)
		(end 87.62238 -237.519464)
		(width 0.09525)
		(layer "In4.Cu")
		(net "M_D_CPU1_SA_DQS_DN<7>")
	)
	(arc
		(start 90.819478 -237.519464)
		(mid 91.10091 -237.443709)
		(end 91.382342 -237.519464)
		(width 0.09525)
		(layer "In4.Cu")
		(net "M_D_CPU1_SA_DQS_DN<7>")
	)
	(arc
		(start 78.41107 -237.571534)
		(mid 78.509376 -237.558214)
		(end 78.600808 -237.519718)
		(width 0.09525)
		(layer "In4.Cu")
		(net "M_D_CPU1_SA_DQS_DN<7>")
	)
	(arc
		(start 79.568802 -237.503462)
		(mid 79.837645 -237.443911)
		(end 80.102456 -237.519464)
		(width 0.09525)
		(layer "In4.Cu")
		(net "M_D_CPU1_SA_DQS_DN<7>")
	)
	(arc
		(start 89.51087 -237.52429)
		(mid 89.695902 -237.570204)
		(end 89.879678 -237.519464)
		(width 0.09525)
		(layer "In4.Cu")
		(net "M_D_CPU1_SA_DQS_DN<7>")
	)
	(arc
		(start 79.16545 -237.519464)
		(mid 79.343802 -237.570005)
		(end 79.524606 -237.529116)
		(width 0.09525)
		(layer "In4.Cu")
		(net "M_D_CPU1_SA_DQS_DN<7>")
	)
	(arc
		(start 84.810854 -237.52429)
		(mid 84.995886 -237.570204)
		(end 85.179662 -237.519464)
		(width 0.09525)
		(layer "In4.Cu")
		(net "M_D_CPU1_SA_DQS_DN<7>")
	)
	(arc
		(start 90.442542 -237.519464)
		(mid 90.63101 -237.570141)
		(end 90.819478 -237.519464)
		(width 0.09525)
		(layer "In4.Cu")
		(net "M_D_CPU1_SA_DQS_DN<7>")
	)
	(arc
		(start 85.179662 -237.519464)
		(mid 85.461094 -237.443709)
		(end 85.742526 -237.519464)
		(width 0.09525)
		(layer "In4.Cu")
		(net "M_D_CPU1_SA_DQS_DN<7>")
	)
	(arc
		(start 82.3595 -237.519464)
		(mid 82.640932 -237.443709)
		(end 82.922364 -237.519464)
		(width 0.09525)
		(layer "In4.Cu")
		(net "M_D_CPU1_SA_DQS_DN<7>")
	)
	(arc
		(start 81.4197 -237.519464)
		(mid 81.701132 -237.443709)
		(end 81.982564 -237.519464)
		(width 0.09525)
		(layer "In4.Cu")
		(net "M_D_CPU1_SA_DQS_DN<7>")
	)
	(arc
		(start 92.235782 -237.478316)
		(mid 92.24611 -237.482276)
		(end 92.256356 -237.486444)
		(width 0.09525)
		(layer "In4.Cu")
		(net "M_D_CPU1_SA_DQS_DN<7>")
	)
	(arc
		(start 83.862418 -237.519464)
		(mid 84.046193 -237.570236)
		(end 84.231226 -237.52429)
		(width 0.09525)
		(layer "In4.Cu")
		(net "M_D_CPU1_SA_DQS_DN<7>")
	)
	(arc
		(start 91.759532 -237.519464)
		(mid 91.993046 -237.445621)
		(end 92.235782 -237.478316)
		(width 0.09525)
		(layer "In4.Cu")
		(net "M_D_CPU1_SA_DQS_DN<7>")
	)
	(arc
		(start 84.239608 -237.519464)
		(mid 84.52104 -237.443709)
		(end 84.802472 -237.519464)
		(width 0.09525)
		(layer "In4.Cu")
		(net "M_D_CPU1_SA_DQS_DN<7>")
	)
	(arc
		(start 80.479646 -237.519464)
		(mid 80.761078 -237.443709)
		(end 81.04251 -237.519464)
		(width 0.09525)
		(layer "In4.Cu")
		(net "M_D_CPU1_SA_DQS_DN<7>")
	)
	(arc
		(start 86.68258 -237.519464)
		(mid 86.871048 -237.570141)
		(end 87.059516 -237.519464)
		(width 0.09525)
		(layer "In4.Cu")
		(net "M_D_CPU1_SA_DQS_DN<7>")
	)
	(arc
		(start 85.750908 -237.52429)
		(mid 85.93594 -237.570204)
		(end 86.119716 -237.519464)
		(width 0.09525)
		(layer "In4.Cu")
		(net "M_D_CPU1_SA_DQS_DN<7>")
	)
	(segment
		(start 92.97797 -232.600246)
		(end 92.511118 -232.334308)
		(width 0.12954)
		(layer "F.Cu")
		(net "M_D_CPU1_SA_DQS_DN<6>")
	)
	(segment
		(start 84.802472 -232.659428)
		(end 84.810854 -232.664254)
		(width 0.09525)
		(layer "In4.Cu")
		(net "M_D_CPU1_SA_DQS_DN<6>")
	)
	(segment
		(start 72.77227 -225.017584)
		(end 72.77227 -226.591876)
		(width 0.16002)
		(layer "In4.Cu")
		(net "M_D_CPU1_SA_DQS_DN<6>")
	)
	(segment
		(start 40.984424 -212.20811)
		(end 41.288208 -211.904326)
		(width 0.16002)
		(layer "In4.Cu")
		(net "M_D_CPU1_SA_DQS_DN<6>")
	)
	(segment
		(start 57.712356 -212.20811)
		(end 59.962796 -212.20811)
		(width 0.16002)
		(layer "In4.Cu")
		(net "M_D_CPU1_SA_DQS_DN<6>")
	)
	(segment
		(start 77.49921 -230.588566)
		(end 79.49438 -232.583736)
		(width 0.09525)
		(layer "In4.Cu")
		(net "M_D_CPU1_SA_DQS_DN<6>")
	)
	(segment
		(start 92.357194 -232.599738)
		(end 92.511118 -232.334308)
		(width 0.09525)
		(layer "In4.Cu")
		(net "M_D_CPU1_SA_DQS_DN<6>")
	)
	(segment
		(start 42.669968 -211.002626)
		(end 43.228768 -211.002626)
		(width 0.16002)
		(layer "In4.Cu")
		(net "M_D_CPU1_SA_DQS_DN<6>")
	)
	(segment
		(start 48.860202 -211.888578)
		(end 49.337722 -211.888578)
		(width 0.16002)
		(layer "In4.Cu")
		(net "M_D_CPU1_SA_DQS_DN<6>")
	)
	(segment
		(start 51.128168 -211.358226)
		(end 53.578252 -211.358226)
		(width 0.16002)
		(layer "In4.Cu")
		(net "M_D_CPU1_SA_DQS_DN<6>")
	)
	(segment
		(start 48.54067 -212.20811)
		(end 48.860202 -211.888578)
		(width 0.16002)
		(layer "In4.Cu")
		(net "M_D_CPU1_SA_DQS_DN<6>")
	)
	(segment
		(start 45.944536 -211.358226)
		(end 46.79442 -212.20811)
		(width 0.16002)
		(layer "In4.Cu")
		(net "M_D_CPU1_SA_DQS_DN<6>")
	)
	(segment
		(start 46.79442 -212.20811)
		(end 48.54067 -212.20811)
		(width 0.16002)
		(layer "In4.Cu")
		(net "M_D_CPU1_SA_DQS_DN<6>")
	)
	(segment
		(start 83.291172 -232.664254)
		(end 83.299554 -232.659428)
		(width 0.09525)
		(layer "In4.Cu")
		(net "M_D_CPU1_SA_DQS_DN<6>")
	)
	(segment
		(start 92.256356 -232.626408)
		(end 92.357194 -232.599738)
		(width 0.09525)
		(layer "In4.Cu")
		(net "M_D_CPU1_SA_DQS_DN<6>")
	)
	(segment
		(start 81.04251 -232.659428)
		(end 81.050892 -232.664254)
		(width 0.09525)
		(layer "In4.Cu")
		(net "M_D_CPU1_SA_DQS_DN<6>")
	)
	(segment
		(start 76.349606 -230.252524)
		(end 76.685648 -230.588566)
		(width 0.09525)
		(layer "In4.Cu")
		(net "M_D_CPU1_SA_DQS_DN<6>")
	)
	(segment
		(start 41.768268 -211.904326)
		(end 42.669968 -211.002626)
		(width 0.16002)
		(layer "In4.Cu")
		(net "M_D_CPU1_SA_DQS_DN<6>")
	)
	(segment
		(start 32.969708 -211.209128)
		(end 34.851086 -211.209128)
		(width 0.16002)
		(layer "In4.Cu")
		(net "M_D_CPU1_SA_DQS_DN<6>")
	)
	(segment
		(start 54.108604 -211.888578)
		(end 57.392824 -211.888578)
		(width 0.16002)
		(layer "In4.Cu")
		(net "M_D_CPU1_SA_DQS_DN<6>")
	)
	(segment
		(start 57.392824 -211.888578)
		(end 57.712356 -212.20811)
		(width 0.16002)
		(layer "In4.Cu")
		(net "M_D_CPU1_SA_DQS_DN<6>")
	)
	(segment
		(start 76.685648 -230.588566)
		(end 77.49921 -230.588566)
		(width 0.09525)
		(layer "In4.Cu")
		(net "M_D_CPU1_SA_DQS_DN<6>")
	)
	(segment
		(start 85.742526 -232.659428)
		(end 85.750908 -232.664254)
		(width 0.09525)
		(layer "In4.Cu")
		(net "M_D_CPU1_SA_DQS_DN<6>")
	)
	(segment
		(start 50.774346 -211.004404)
		(end 51.128168 -211.358226)
		(width 0.16002)
		(layer "In4.Cu")
		(net "M_D_CPU1_SA_DQS_DN<6>")
	)
	(segment
		(start 50.221896 -211.004404)
		(end 50.774346 -211.004404)
		(width 0.16002)
		(layer "In4.Cu")
		(net "M_D_CPU1_SA_DQS_DN<6>")
	)
	(segment
		(start 53.578252 -211.358226)
		(end 54.108604 -211.888578)
		(width 0.16002)
		(layer "In4.Cu")
		(net "M_D_CPU1_SA_DQS_DN<6>")
	)
	(segment
		(start 39.322756 -212.20811)
		(end 40.984424 -212.20811)
		(width 0.16002)
		(layer "In4.Cu")
		(net "M_D_CPU1_SA_DQS_DN<6>")
	)
	(segment
		(start 38.503352 -211.388706)
		(end 39.322756 -212.20811)
		(width 0.16002)
		(layer "In4.Cu")
		(net "M_D_CPU1_SA_DQS_DN<6>")
	)
	(segment
		(start 91.75115 -232.664254)
		(end 91.759532 -232.659428)
		(width 0.09525)
		(layer "In4.Cu")
		(net "M_D_CPU1_SA_DQS_DN<6>")
	)
	(segment
		(start 41.288208 -211.904326)
		(end 41.768268 -211.904326)
		(width 0.16002)
		(layer "In4.Cu")
		(net "M_D_CPU1_SA_DQS_DN<6>")
	)
	(segment
		(start 84.231226 -232.664254)
		(end 84.239608 -232.659428)
		(width 0.09525)
		(layer "In4.Cu")
		(net "M_D_CPU1_SA_DQS_DN<6>")
	)
	(segment
		(start 76.332842 -230.152448)
		(end 76.349606 -230.169212)
		(width 0.09525)
		(layer "In4.Cu")
		(net "M_D_CPU1_SA_DQS_DN<6>")
	)
	(segment
		(start 88.931242 -232.664254)
		(end 88.939624 -232.659428)
		(width 0.09525)
		(layer "In4.Cu")
		(net "M_D_CPU1_SA_DQS_DN<6>")
	)
	(segment
		(start 87.991188 -232.664254)
		(end 87.99957 -232.659428)
		(width 0.09525)
		(layer "In4.Cu")
		(net "M_D_CPU1_SA_DQS_DN<6>")
	)
	(segment
		(start 79.49438 -232.583736)
		(end 79.821024 -232.583736)
		(width 0.09525)
		(layer "In4.Cu")
		(net "M_D_CPU1_SA_DQS_DN<6>")
	)
	(segment
		(start 43.228768 -211.002626)
		(end 43.584368 -211.358226)
		(width 0.16002)
		(layer "In4.Cu")
		(net "M_D_CPU1_SA_DQS_DN<6>")
	)
	(segment
		(start 49.337722 -211.888578)
		(end 50.221896 -211.004404)
		(width 0.16002)
		(layer "In4.Cu")
		(net "M_D_CPU1_SA_DQS_DN<6>")
	)
	(segment
		(start 36.097972 -211.388706)
		(end 38.503352 -211.388706)
		(width 0.16002)
		(layer "In4.Cu")
		(net "M_D_CPU1_SA_DQS_DN<6>")
	)
	(segment
		(start 89.502488 -232.659428)
		(end 89.51087 -232.664254)
		(width 0.09525)
		(layer "In4.Cu")
		(net "M_D_CPU1_SA_DQS_DN<6>")
	)
	(segment
		(start 34.851086 -211.209128)
		(end 35.029648 -211.030566)
		(width 0.16002)
		(layer "In4.Cu")
		(net "M_D_CPU1_SA_DQS_DN<6>")
	)
	(segment
		(start 35.739832 -211.030566)
		(end 36.097972 -211.388706)
		(width 0.16002)
		(layer "In4.Cu")
		(net "M_D_CPU1_SA_DQS_DN<6>")
	)
	(segment
		(start 35.029648 -211.030566)
		(end 35.739832 -211.030566)
		(width 0.16002)
		(layer "In4.Cu")
		(net "M_D_CPU1_SA_DQS_DN<6>")
	)
	(segment
		(start 59.962796 -212.20811)
		(end 72.77227 -225.017584)
		(width 0.16002)
		(layer "In4.Cu")
		(net "M_D_CPU1_SA_DQS_DN<6>")
	)
	(segment
		(start 80.471264 -232.664254)
		(end 80.479646 -232.659428)
		(width 0.09525)
		(layer "In4.Cu")
		(net "M_D_CPU1_SA_DQS_DN<6>")
	)
	(segment
		(start 32.695896 -210.935316)
		(end 32.969708 -211.209128)
		(width 0.16002)
		(layer "In4.Cu")
		(net "M_D_CPU1_SA_DQS_DN<6>")
	)
	(segment
		(start 43.584368 -211.358226)
		(end 45.944536 -211.358226)
		(width 0.16002)
		(layer "In4.Cu")
		(net "M_D_CPU1_SA_DQS_DN<6>")
	)
	(segment
		(start 72.77227 -226.591876)
		(end 76.332842 -230.152448)
		(width 0.16002)
		(layer "In4.Cu")
		(net "M_D_CPU1_SA_DQS_DN<6>")
	)
	(segment
		(start 76.349606 -230.169212)
		(end 76.349606 -230.252524)
		(width 0.09525)
		(layer "In4.Cu")
		(net "M_D_CPU1_SA_DQS_DN<6>")
	)
	(arc
		(start 85.179662 -232.659428)
		(mid 85.461094 -232.583673)
		(end 85.742526 -232.659428)
		(width 0.09525)
		(layer "In4.Cu")
		(net "M_D_CPU1_SA_DQS_DN<6>")
	)
	(arc
		(start 91.382342 -232.659428)
		(mid 91.566117 -232.7102)
		(end 91.75115 -232.664254)
		(width 0.09525)
		(layer "In4.Cu")
		(net "M_D_CPU1_SA_DQS_DN<6>")
	)
	(arc
		(start 87.99957 -232.659428)
		(mid 88.281002 -232.583673)
		(end 88.562434 -232.659428)
		(width 0.09525)
		(layer "In4.Cu")
		(net "M_D_CPU1_SA_DQS_DN<6>")
	)
	(arc
		(start 79.821024 -232.583736)
		(mid 79.966732 -232.603004)
		(end 80.102456 -232.659428)
		(width 0.09525)
		(layer "In4.Cu")
		(net "M_D_CPU1_SA_DQS_DN<6>")
	)
	(arc
		(start 92.235782 -232.61828)
		(mid 92.24611 -232.62224)
		(end 92.256356 -232.626408)
		(width 0.09525)
		(layer "In4.Cu")
		(net "M_D_CPU1_SA_DQS_DN<6>")
	)
	(arc
		(start 80.102456 -232.659428)
		(mid 80.286231 -232.7102)
		(end 80.471264 -232.664254)
		(width 0.09525)
		(layer "In4.Cu")
		(net "M_D_CPU1_SA_DQS_DN<6>")
	)
	(arc
		(start 84.239608 -232.659428)
		(mid 84.52104 -232.583673)
		(end 84.802472 -232.659428)
		(width 0.09525)
		(layer "In4.Cu")
		(net "M_D_CPU1_SA_DQS_DN<6>")
	)
	(arc
		(start 81.4197 -232.659428)
		(mid 81.701132 -232.583673)
		(end 81.982564 -232.659428)
		(width 0.09525)
		(layer "In4.Cu")
		(net "M_D_CPU1_SA_DQS_DN<6>")
	)
	(arc
		(start 80.479646 -232.659428)
		(mid 80.761078 -232.583673)
		(end 81.04251 -232.659428)
		(width 0.09525)
		(layer "In4.Cu")
		(net "M_D_CPU1_SA_DQS_DN<6>")
	)
	(arc
		(start 90.819478 -232.659428)
		(mid 91.10091 -232.583673)
		(end 91.382342 -232.659428)
		(width 0.09525)
		(layer "In4.Cu")
		(net "M_D_CPU1_SA_DQS_DN<6>")
	)
	(arc
		(start 83.299554 -232.659428)
		(mid 83.580986 -232.583673)
		(end 83.862418 -232.659428)
		(width 0.09525)
		(layer "In4.Cu")
		(net "M_D_CPU1_SA_DQS_DN<6>")
	)
	(arc
		(start 84.810854 -232.664254)
		(mid 84.995886 -232.710168)
		(end 85.179662 -232.659428)
		(width 0.09525)
		(layer "In4.Cu")
		(net "M_D_CPU1_SA_DQS_DN<6>")
	)
	(arc
		(start 89.51087 -232.664254)
		(mid 89.695902 -232.710168)
		(end 89.879678 -232.659428)
		(width 0.09525)
		(layer "In4.Cu")
		(net "M_D_CPU1_SA_DQS_DN<6>")
	)
	(arc
		(start 81.982564 -232.659428)
		(mid 82.171032 -232.710105)
		(end 82.3595 -232.659428)
		(width 0.09525)
		(layer "In4.Cu")
		(net "M_D_CPU1_SA_DQS_DN<6>")
	)
	(arc
		(start 86.119716 -232.659428)
		(mid 86.401148 -232.583673)
		(end 86.68258 -232.659428)
		(width 0.09525)
		(layer "In4.Cu")
		(net "M_D_CPU1_SA_DQS_DN<6>")
	)
	(arc
		(start 88.562434 -232.659428)
		(mid 88.746209 -232.7102)
		(end 88.931242 -232.664254)
		(width 0.09525)
		(layer "In4.Cu")
		(net "M_D_CPU1_SA_DQS_DN<6>")
	)
	(arc
		(start 91.759532 -232.659428)
		(mid 91.993046 -232.585585)
		(end 92.235782 -232.61828)
		(width 0.09525)
		(layer "In4.Cu")
		(net "M_D_CPU1_SA_DQS_DN<6>")
	)
	(arc
		(start 88.939624 -232.659428)
		(mid 89.221056 -232.583673)
		(end 89.502488 -232.659428)
		(width 0.09525)
		(layer "In4.Cu")
		(net "M_D_CPU1_SA_DQS_DN<6>")
	)
	(arc
		(start 81.050892 -232.664254)
		(mid 81.235924 -232.710168)
		(end 81.4197 -232.659428)
		(width 0.09525)
		(layer "In4.Cu")
		(net "M_D_CPU1_SA_DQS_DN<6>")
	)
	(arc
		(start 82.3595 -232.659428)
		(mid 82.640932 -232.583673)
		(end 82.922364 -232.659428)
		(width 0.09525)
		(layer "In4.Cu")
		(net "M_D_CPU1_SA_DQS_DN<6>")
	)
	(arc
		(start 87.62238 -232.659428)
		(mid 87.806155 -232.7102)
		(end 87.991188 -232.664254)
		(width 0.09525)
		(layer "In4.Cu")
		(net "M_D_CPU1_SA_DQS_DN<6>")
	)
	(arc
		(start 90.442542 -232.659428)
		(mid 90.63101 -232.710105)
		(end 90.819478 -232.659428)
		(width 0.09525)
		(layer "In4.Cu")
		(net "M_D_CPU1_SA_DQS_DN<6>")
	)
	(arc
		(start 89.879678 -232.659428)
		(mid 90.16111 -232.583673)
		(end 90.442542 -232.659428)
		(width 0.09525)
		(layer "In4.Cu")
		(net "M_D_CPU1_SA_DQS_DN<6>")
	)
	(arc
		(start 82.922364 -232.659428)
		(mid 83.106139 -232.7102)
		(end 83.291172 -232.664254)
		(width 0.09525)
		(layer "In4.Cu")
		(net "M_D_CPU1_SA_DQS_DN<6>")
	)
	(arc
		(start 86.68258 -232.659428)
		(mid 86.871048 -232.710105)
		(end 87.059516 -232.659428)
		(width 0.09525)
		(layer "In4.Cu")
		(net "M_D_CPU1_SA_DQS_DN<6>")
	)
	(arc
		(start 83.862418 -232.659428)
		(mid 84.046193 -232.7102)
		(end 84.231226 -232.664254)
		(width 0.09525)
		(layer "In4.Cu")
		(net "M_D_CPU1_SA_DQS_DN<6>")
	)
	(arc
		(start 85.750908 -232.664254)
		(mid 85.93594 -232.710168)
		(end 86.119716 -232.659428)
		(width 0.09525)
		(layer "In4.Cu")
		(net "M_D_CPU1_SA_DQS_DN<6>")
	)
	(arc
		(start 87.059516 -232.659428)
		(mid 87.340948 -232.583673)
		(end 87.62238 -232.659428)
		(width 0.09525)
		(layer "In4.Cu")
		(net "M_D_CPU1_SA_DQS_DN<6>")
	)
	(segment
		(start 92.97797 -227.740464)
		(end 92.511118 -227.474526)
		(width 0.12954)
		(layer "F.Cu")
		(net "M_D_CPU1_SA_DQS_DN<5>")
	)
	(segment
		(start 34.735262 -201.859134)
		(end 34.90595 -201.688446)
		(width 0.16002)
		(layer "In4.Cu")
		(net "M_D_CPU1_SA_DQS_DN<5>")
	)
	(segment
		(start 50.20183 -201.655426)
		(end 50.78603 -201.655426)
		(width 0.16002)
		(layer "In4.Cu")
		(net "M_D_CPU1_SA_DQS_DN<5>")
	)
	(segment
		(start 82.360008 -227.7999)
		(end 82.360262 -227.7999)
		(width 0.09525)
		(layer "In4.Cu")
		(net "M_D_CPU1_SA_DQS_DN<5>")
	)
	(segment
		(start 78.16723 -221.539308)
		(end 78.378558 -221.750636)
		(width 0.16002)
		(layer "In4.Cu")
		(net "M_D_CPU1_SA_DQS_DN<5>")
	)
	(segment
		(start 86.671658 -227.793804)
		(end 86.681818 -227.7999)
		(width 0.09525)
		(layer "In4.Cu")
		(net "M_D_CPU1_SA_DQS_DN<5>")
	)
	(segment
		(start 43.597576 -202.008232)
		(end 45.985176 -202.008232)
		(width 0.16002)
		(layer "In4.Cu")
		(net "M_D_CPU1_SA_DQS_DN<5>")
	)
	(segment
		(start 92.256356 -227.766626)
		(end 92.357194 -227.739956)
		(width 0.09525)
		(layer "In4.Cu")
		(net "M_D_CPU1_SA_DQS_DN<5>")
	)
	(segment
		(start 91.760294 -227.7999)
		(end 91.770454 -227.793804)
		(width 0.09525)
		(layer "In4.Cu")
		(net "M_D_CPU1_SA_DQS_DN<5>")
	)
	(segment
		(start 46.83506 -202.858116)
		(end 48.5013 -202.858116)
		(width 0.16002)
		(layer "In4.Cu")
		(net "M_D_CPU1_SA_DQS_DN<5>")
	)
	(segment
		(start 78.378558 -221.750636)
		(end 78.395322 -221.7674)
		(width 0.09525)
		(layer "In4.Cu")
		(net "M_D_CPU1_SA_DQS_DN<5>")
	)
	(segment
		(start 45.985176 -202.008232)
		(end 46.83506 -202.858116)
		(width 0.16002)
		(layer "In4.Cu")
		(net "M_D_CPU1_SA_DQS_DN<5>")
	)
	(segment
		(start 83.300316 -227.7999)
		(end 83.310476 -227.793804)
		(width 0.09525)
		(layer "In4.Cu")
		(net "M_D_CPU1_SA_DQS_DN<5>")
	)
	(segment
		(start 87.060278 -227.7999)
		(end 87.070438 -227.793804)
		(width 0.09525)
		(layer "In4.Cu")
		(net "M_D_CPU1_SA_DQS_DN<5>")
	)
	(segment
		(start 56.09717 -202.831446)
		(end 56.39943 -202.529186)
		(width 0.16002)
		(layer "In4.Cu")
		(net "M_D_CPU1_SA_DQS_DN<5>")
	)
	(segment
		(start 78.48854 -221.94393)
		(end 78.615286 -222.070422)
		(width 0.09525)
		(layer "In4.Cu")
		(net "M_D_CPU1_SA_DQS_DN<5>")
	)
	(segment
		(start 42.67327 -201.655426)
		(end 43.24477 -201.655426)
		(width 0.16002)
		(layer "In4.Cu")
		(net "M_D_CPU1_SA_DQS_DN<5>")
	)
	(segment
		(start 32.695896 -201.585322)
		(end 32.969708 -201.859134)
		(width 0.16002)
		(layer "In4.Cu")
		(net "M_D_CPU1_SA_DQS_DN<5>")
	)
	(segment
		(start 34.90595 -201.688446)
		(end 35.71621 -201.688446)
		(width 0.16002)
		(layer "In4.Cu")
		(net "M_D_CPU1_SA_DQS_DN<5>")
	)
	(segment
		(start 92.357194 -227.739956)
		(end 92.511118 -227.474526)
		(width 0.09525)
		(layer "In4.Cu")
		(net "M_D_CPU1_SA_DQS_DN<5>")
	)
	(segment
		(start 50.78603 -201.655426)
		(end 51.138836 -202.008232)
		(width 0.16002)
		(layer "In4.Cu")
		(net "M_D_CPU1_SA_DQS_DN<5>")
	)
	(segment
		(start 57.793382 -202.858116)
		(end 59.956954 -202.858116)
		(width 0.16002)
		(layer "In4.Cu")
		(net "M_D_CPU1_SA_DQS_DN<5>")
	)
	(segment
		(start 86.681818 -227.7999)
		(end 86.682072 -227.7999)
		(width 0.09525)
		(layer "In4.Cu")
		(net "M_D_CPU1_SA_DQS_DN<5>")
	)
	(segment
		(start 40.98544 -202.858116)
		(end 41.30929 -202.534266)
		(width 0.16002)
		(layer "In4.Cu")
		(net "M_D_CPU1_SA_DQS_DN<5>")
	)
	(segment
		(start 36.05149 -202.023726)
		(end 38.46703 -202.023726)
		(width 0.16002)
		(layer "In4.Cu")
		(net "M_D_CPU1_SA_DQS_DN<5>")
	)
	(segment
		(start 79.600298 -223.731328)
		(end 79.632556 -223.74987)
		(width 0.09525)
		(layer "In4.Cu")
		(net "M_D_CPU1_SA_DQS_DN<5>")
	)
	(segment
		(start 92.256102 -227.767388)
		(end 92.256356 -227.766626)
		(width 0.09525)
		(layer "In4.Cu")
		(net "M_D_CPU1_SA_DQS_DN<5>")
	)
	(segment
		(start 85.741764 -227.7999)
		(end 85.742018 -227.7999)
		(width 0.09525)
		(layer "In4.Cu")
		(net "M_D_CPU1_SA_DQS_DN<5>")
	)
	(segment
		(start 78.16723 -221.068392)
		(end 78.16723 -221.539308)
		(width 0.16002)
		(layer "In4.Cu")
		(net "M_D_CPU1_SA_DQS_DN<5>")
	)
	(segment
		(start 88.000078 -227.7999)
		(end 88.000332 -227.7999)
		(width 0.09525)
		(layer "In4.Cu")
		(net "M_D_CPU1_SA_DQS_DN<5>")
	)
	(segment
		(start 32.969708 -201.859134)
		(end 34.735262 -201.859134)
		(width 0.16002)
		(layer "In4.Cu")
		(net "M_D_CPU1_SA_DQS_DN<5>")
	)
	(segment
		(start 38.46703 -202.023726)
		(end 39.30142 -202.858116)
		(width 0.16002)
		(layer "In4.Cu")
		(net "M_D_CPU1_SA_DQS_DN<5>")
	)
	(segment
		(start 90.43162 -227.793804)
		(end 90.44178 -227.7999)
		(width 0.09525)
		(layer "In4.Cu")
		(net "M_D_CPU1_SA_DQS_DN<5>")
	)
	(segment
		(start 41.30929 -202.534266)
		(end 41.79443 -202.534266)
		(width 0.16002)
		(layer "In4.Cu")
		(net "M_D_CPU1_SA_DQS_DN<5>")
	)
	(segment
		(start 51.138836 -202.008232)
		(end 53.556916 -202.008232)
		(width 0.16002)
		(layer "In4.Cu")
		(net "M_D_CPU1_SA_DQS_DN<5>")
	)
	(segment
		(start 81.042256 -226.179888)
		(end 81.081626 -226.202748)
		(width 0.09525)
		(layer "In4.Cu")
		(net "M_D_CPU1_SA_DQS_DN<5>")
	)
	(segment
		(start 56.39943 -202.529186)
		(end 57.464452 -202.529186)
		(width 0.16002)
		(layer "In4.Cu")
		(net "M_D_CPU1_SA_DQS_DN<5>")
	)
	(segment
		(start 78.692502 -222.129858)
		(end 78.730856 -222.15221)
		(width 0.09525)
		(layer "In4.Cu")
		(net "M_D_CPU1_SA_DQS_DN<5>")
	)
	(segment
		(start 80.10271 -224.560384)
		(end 80.14081 -224.582228)
		(width 0.09525)
		(layer "In4.Cu")
		(net "M_D_CPU1_SA_DQS_DN<5>")
	)
	(segment
		(start 43.24477 -201.655426)
		(end 43.597576 -202.008232)
		(width 0.16002)
		(layer "In4.Cu")
		(net "M_D_CPU1_SA_DQS_DN<5>")
	)
	(segment
		(start 81.481168 -226.97186)
		(end 81.512156 -226.989894)
		(width 0.09525)
		(layer "In4.Cu")
		(net "M_D_CPU1_SA_DQS_DN<5>")
	)
	(segment
		(start 80.073754 -224.543366)
		(end 80.10271 -224.560384)
		(width 0.09525)
		(layer "In4.Cu")
		(net "M_D_CPU1_SA_DQS_DN<5>")
	)
	(segment
		(start 80.541114 -225.351848)
		(end 80.572102 -225.369882)
		(width 0.09525)
		(layer "In4.Cu")
		(net "M_D_CPU1_SA_DQS_DN<5>")
	)
	(segment
		(start 35.71621 -201.688446)
		(end 36.05149 -202.023726)
		(width 0.16002)
		(layer "In4.Cu")
		(net "M_D_CPU1_SA_DQS_DN<5>")
	)
	(segment
		(start 41.79443 -202.534266)
		(end 42.67327 -201.655426)
		(width 0.16002)
		(layer "In4.Cu")
		(net "M_D_CPU1_SA_DQS_DN<5>")
	)
	(segment
		(start 85.731604 -227.793804)
		(end 85.741764 -227.7999)
		(width 0.09525)
		(layer "In4.Cu")
		(net "M_D_CPU1_SA_DQS_DN<5>")
	)
	(segment
		(start 79.632556 -223.74987)
		(end 79.669386 -223.77146)
		(width 0.09525)
		(layer "In4.Cu")
		(net "M_D_CPU1_SA_DQS_DN<5>")
	)
	(segment
		(start 48.5013 -202.858116)
		(end 48.82261 -202.536806)
		(width 0.16002)
		(layer "In4.Cu")
		(net "M_D_CPU1_SA_DQS_DN<5>")
	)
	(segment
		(start 78.395322 -221.7674)
		(end 78.395322 -221.850712)
		(width 0.09525)
		(layer "In4.Cu")
		(net "M_D_CPU1_SA_DQS_DN<5>")
	)
	(segment
		(start 53.556916 -202.008232)
		(end 54.38013 -202.831446)
		(width 0.16002)
		(layer "In4.Cu")
		(net "M_D_CPU1_SA_DQS_DN<5>")
	)
	(segment
		(start 88.000332 -227.7999)
		(end 88.010492 -227.793804)
		(width 0.09525)
		(layer "In4.Cu")
		(net "M_D_CPU1_SA_DQS_DN<5>")
	)
	(segment
		(start 81.951068 -227.781866)
		(end 81.982056 -227.7999)
		(width 0.09525)
		(layer "In4.Cu")
		(net "M_D_CPU1_SA_DQS_DN<5>")
	)
	(segment
		(start 79.13497 -222.924116)
		(end 79.162402 -222.939864)
		(width 0.09525)
		(layer "In4.Cu")
		(net "M_D_CPU1_SA_DQS_DN<5>")
	)
	(segment
		(start 49.32045 -202.536806)
		(end 50.20183 -201.655426)
		(width 0.16002)
		(layer "In4.Cu")
		(net "M_D_CPU1_SA_DQS_DN<5>")
	)
	(segment
		(start 39.30142 -202.858116)
		(end 40.98544 -202.858116)
		(width 0.16002)
		(layer "In4.Cu")
		(net "M_D_CPU1_SA_DQS_DN<5>")
	)
	(segment
		(start 90.44178 -227.7999)
		(end 90.442034 -227.7999)
		(width 0.09525)
		(layer "In4.Cu")
		(net "M_D_CPU1_SA_DQS_DN<5>")
	)
	(segment
		(start 81.512156 -226.989894)
		(end 81.550764 -227.012246)
		(width 0.09525)
		(layer "In4.Cu")
		(net "M_D_CPU1_SA_DQS_DN<5>")
	)
	(segment
		(start 91.76004 -227.7999)
		(end 91.760294 -227.7999)
		(width 0.09525)
		(layer "In4.Cu")
		(net "M_D_CPU1_SA_DQS_DN<5>")
	)
	(segment
		(start 83.300062 -227.7999)
		(end 83.300316 -227.7999)
		(width 0.09525)
		(layer "In4.Cu")
		(net "M_D_CPU1_SA_DQS_DN<5>")
	)
	(segment
		(start 59.956954 -202.858116)
		(end 78.16723 -221.068392)
		(width 0.16002)
		(layer "In4.Cu")
		(net "M_D_CPU1_SA_DQS_DN<5>")
	)
	(segment
		(start 81.014316 -226.163632)
		(end 81.042256 -226.179888)
		(width 0.09525)
		(layer "In4.Cu")
		(net "M_D_CPU1_SA_DQS_DN<5>")
	)
	(segment
		(start 57.464452 -202.529186)
		(end 57.793382 -202.858116)
		(width 0.16002)
		(layer "In4.Cu")
		(net "M_D_CPU1_SA_DQS_DN<5>")
	)
	(segment
		(start 78.395322 -221.850712)
		(end 78.48854 -221.94393)
		(width 0.09525)
		(layer "In4.Cu")
		(net "M_D_CPU1_SA_DQS_DN<5>")
	)
	(segment
		(start 79.162402 -222.939864)
		(end 79.203296 -222.96374)
		(width 0.09525)
		(layer "In4.Cu")
		(net "M_D_CPU1_SA_DQS_DN<5>")
	)
	(segment
		(start 48.82261 -202.536806)
		(end 49.32045 -202.536806)
		(width 0.16002)
		(layer "In4.Cu")
		(net "M_D_CPU1_SA_DQS_DN<5>")
	)
	(segment
		(start 82.360262 -227.7999)
		(end 82.370422 -227.793804)
		(width 0.09525)
		(layer "In4.Cu")
		(net "M_D_CPU1_SA_DQS_DN<5>")
	)
	(segment
		(start 80.572102 -225.369882)
		(end 80.611726 -225.392742)
		(width 0.09525)
		(layer "In4.Cu")
		(net "M_D_CPU1_SA_DQS_DN<5>")
	)
	(segment
		(start 90.82024 -227.7999)
		(end 90.8304 -227.793804)
		(width 0.09525)
		(layer "In4.Cu")
		(net "M_D_CPU1_SA_DQS_DN<5>")
	)
	(segment
		(start 54.38013 -202.831446)
		(end 56.09717 -202.831446)
		(width 0.16002)
		(layer "In4.Cu")
		(net "M_D_CPU1_SA_DQS_DN<5>")
	)
	(arc
		(start 87.622126 -227.7999)
		(mid 87.811102 -227.850797)
		(end 88.000078 -227.7999)
		(width 0.09525)
		(layer "In4.Cu")
		(net "M_D_CPU1_SA_DQS_DN<5>")
	)
	(arc
		(start 81.081626 -226.202748)
		(mid 81.258991 -226.403992)
		(end 81.322926 -226.66452)
		(width 0.09525)
		(layer "In4.Cu")
		(net "M_D_CPU1_SA_DQS_DN<5>")
	)
	(arc
		(start 88.940132 -227.7999)
		(mid 89.221056 -227.724366)
		(end 89.50198 -227.7999)
		(width 0.09525)
		(layer "In4.Cu")
		(net "M_D_CPU1_SA_DQS_DN<5>")
	)
	(arc
		(start 92.235782 -227.75926)
		(mid 92.245982 -227.763224)
		(end 92.256102 -227.767388)
		(width 0.09525)
		(layer "In4.Cu")
		(net "M_D_CPU1_SA_DQS_DN<5>")
	)
	(arc
		(start 89.879932 -227.7999)
		(mid 90.154967 -227.724272)
		(end 90.43162 -227.793804)
		(width 0.09525)
		(layer "In4.Cu")
		(net "M_D_CPU1_SA_DQS_DN<5>")
	)
	(arc
		(start 86.682072 -227.7999)
		(mid 86.871192 -227.850925)
		(end 87.060278 -227.7999)
		(width 0.09525)
		(layer "In4.Cu")
		(net "M_D_CPU1_SA_DQS_DN<5>")
	)
	(arc
		(start 83.862164 -227.7999)
		(mid 84.05114 -227.850797)
		(end 84.240116 -227.7999)
		(width 0.09525)
		(layer "In4.Cu")
		(net "M_D_CPU1_SA_DQS_DN<5>")
	)
	(arc
		(start 82.370422 -227.793804)
		(mid 82.647076 -227.724218)
		(end 82.92211 -227.7999)
		(width 0.09525)
		(layer "In4.Cu")
		(net "M_D_CPU1_SA_DQS_DN<5>")
	)
	(arc
		(start 86.11997 -227.7999)
		(mid 86.395005 -227.724272)
		(end 86.671658 -227.793804)
		(width 0.09525)
		(layer "In4.Cu")
		(net "M_D_CPU1_SA_DQS_DN<5>")
	)
	(arc
		(start 88.010492 -227.793804)
		(mid 88.287146 -227.724218)
		(end 88.56218 -227.7999)
		(width 0.09525)
		(layer "In4.Cu")
		(net "M_D_CPU1_SA_DQS_DN<5>")
	)
	(arc
		(start 85.179916 -227.7999)
		(mid 85.454951 -227.724272)
		(end 85.731604 -227.793804)
		(width 0.09525)
		(layer "In4.Cu")
		(net "M_D_CPU1_SA_DQS_DN<5>")
	)
	(arc
		(start 85.742018 -227.7999)
		(mid 85.930994 -227.850797)
		(end 86.11997 -227.7999)
		(width 0.09525)
		(layer "In4.Cu")
		(net "M_D_CPU1_SA_DQS_DN<5>")
	)
	(arc
		(start 90.8304 -227.793804)
		(mid 91.107054 -227.724218)
		(end 91.382088 -227.7999)
		(width 0.09525)
		(layer "In4.Cu")
		(net "M_D_CPU1_SA_DQS_DN<5>")
	)
	(arc
		(start 82.92211 -227.7999)
		(mid 83.111086 -227.850797)
		(end 83.300062 -227.7999)
		(width 0.09525)
		(layer "In4.Cu")
		(net "M_D_CPU1_SA_DQS_DN<5>")
	)
	(arc
		(start 79.443072 -223.424496)
		(mid 79.484671 -223.596875)
		(end 79.600298 -223.731328)
		(width 0.09525)
		(layer "In4.Cu")
		(net "M_D_CPU1_SA_DQS_DN<5>")
	)
	(arc
		(start 80.853026 -225.854514)
		(mid 80.895821 -226.028828)
		(end 81.014316 -226.163632)
		(width 0.09525)
		(layer "In4.Cu")
		(net "M_D_CPU1_SA_DQS_DN<5>")
	)
	(arc
		(start 90.442034 -227.7999)
		(mid 90.631154 -227.850925)
		(end 90.82024 -227.7999)
		(width 0.09525)
		(layer "In4.Cu")
		(net "M_D_CPU1_SA_DQS_DN<5>")
	)
	(arc
		(start 81.550764 -227.012246)
		(mid 81.728679 -227.213606)
		(end 81.792826 -227.474526)
		(width 0.09525)
		(layer "In4.Cu")
		(net "M_D_CPU1_SA_DQS_DN<5>")
	)
	(arc
		(start 81.982056 -227.7999)
		(mid 82.171032 -227.850797)
		(end 82.360008 -227.7999)
		(width 0.09525)
		(layer "In4.Cu")
		(net "M_D_CPU1_SA_DQS_DN<5>")
	)
	(arc
		(start 81.322926 -226.66452)
		(mid 81.364854 -226.837347)
		(end 81.481168 -226.97186)
		(width 0.09525)
		(layer "In4.Cu")
		(net "M_D_CPU1_SA_DQS_DN<5>")
	)
	(arc
		(start 80.14081 -224.582228)
		(mid 80.318725 -224.783588)
		(end 80.382872 -225.044508)
		(width 0.09525)
		(layer "In4.Cu")
		(net "M_D_CPU1_SA_DQS_DN<5>")
	)
	(arc
		(start 81.792826 -227.474526)
		(mid 81.834754 -227.647353)
		(end 81.951068 -227.781866)
		(width 0.09525)
		(layer "In4.Cu")
		(net "M_D_CPU1_SA_DQS_DN<5>")
	)
	(arc
		(start 78.973426 -222.61449)
		(mid 79.016244 -222.789102)
		(end 79.13497 -222.924116)
		(width 0.09525)
		(layer "In4.Cu")
		(net "M_D_CPU1_SA_DQS_DN<5>")
	)
	(arc
		(start 80.382872 -225.044508)
		(mid 80.4248 -225.217335)
		(end 80.541114 -225.351848)
		(width 0.09525)
		(layer "In4.Cu")
		(net "M_D_CPU1_SA_DQS_DN<5>")
	)
	(arc
		(start 79.913226 -224.234502)
		(mid 79.955751 -224.408551)
		(end 80.073754 -224.543366)
		(width 0.09525)
		(layer "In4.Cu")
		(net "M_D_CPU1_SA_DQS_DN<5>")
	)
	(arc
		(start 91.770454 -227.793804)
		(mid 91.999344 -227.725836)
		(end 92.235782 -227.75926)
		(width 0.09525)
		(layer "In4.Cu")
		(net "M_D_CPU1_SA_DQS_DN<5>")
	)
	(arc
		(start 87.070438 -227.793804)
		(mid 87.347092 -227.724218)
		(end 87.622126 -227.7999)
		(width 0.09525)
		(layer "In4.Cu")
		(net "M_D_CPU1_SA_DQS_DN<5>")
	)
	(arc
		(start 91.382088 -227.7999)
		(mid 91.571064 -227.850797)
		(end 91.76004 -227.7999)
		(width 0.09525)
		(layer "In4.Cu")
		(net "M_D_CPU1_SA_DQS_DN<5>")
	)
	(arc
		(start 78.730856 -222.15221)
		(mid 78.909081 -222.353468)
		(end 78.973426 -222.61449)
		(width 0.09525)
		(layer "In4.Cu")
		(net "M_D_CPU1_SA_DQS_DN<5>")
	)
	(arc
		(start 88.56218 -227.7999)
		(mid 88.751156 -227.850797)
		(end 88.940132 -227.7999)
		(width 0.09525)
		(layer "In4.Cu")
		(net "M_D_CPU1_SA_DQS_DN<5>")
	)
	(arc
		(start 83.310476 -227.793804)
		(mid 83.58713 -227.724218)
		(end 83.862164 -227.7999)
		(width 0.09525)
		(layer "In4.Cu")
		(net "M_D_CPU1_SA_DQS_DN<5>")
	)
	(arc
		(start 84.240116 -227.7999)
		(mid 84.52104 -227.724366)
		(end 84.801964 -227.7999)
		(width 0.09525)
		(layer "In4.Cu")
		(net "M_D_CPU1_SA_DQS_DN<5>")
	)
	(arc
		(start 78.615286 -222.070422)
		(mid 78.651963 -222.102648)
		(end 78.692502 -222.129858)
		(width 0.09525)
		(layer "In4.Cu")
		(net "M_D_CPU1_SA_DQS_DN<5>")
	)
	(arc
		(start 80.611726 -225.392742)
		(mid 80.789091 -225.593986)
		(end 80.853026 -225.854514)
		(width 0.09525)
		(layer "In4.Cu")
		(net "M_D_CPU1_SA_DQS_DN<5>")
	)
	(arc
		(start 84.801964 -227.7999)
		(mid 84.99094 -227.850797)
		(end 85.179916 -227.7999)
		(width 0.09525)
		(layer "In4.Cu")
		(net "M_D_CPU1_SA_DQS_DN<5>")
	)
	(arc
		(start 79.203296 -222.96374)
		(mid 79.379518 -223.164787)
		(end 79.443072 -223.424496)
		(width 0.09525)
		(layer "In4.Cu")
		(net "M_D_CPU1_SA_DQS_DN<5>")
	)
	(arc
		(start 89.50198 -227.7999)
		(mid 89.690956 -227.850797)
		(end 89.879932 -227.7999)
		(width 0.09525)
		(layer "In4.Cu")
		(net "M_D_CPU1_SA_DQS_DN<5>")
	)
	(arc
		(start 79.669386 -223.77146)
		(mid 79.848533 -223.972844)
		(end 79.913226 -224.234502)
		(width 0.09525)
		(layer "In4.Cu")
		(net "M_D_CPU1_SA_DQS_DN<5>")
	)
	(segment
		(start 91.097862 -247.180354)
		(end 90.63101 -246.914416)
		(width 0.12954)
		(layer "F.Cu")
		(net "M_D_CPU1_SA_DQS_DN<4>")
	)
	(segment
		(start 63.049658 -243.058696)
		(end 63.326518 -243.058696)
		(width 0.16002)
		(layer "In4.Cu")
		(net "M_D_CPU1_SA_DQS_DN<4>")
	)
	(segment
		(start 62.767464 -243.34089)
		(end 63.049658 -243.058696)
		(width 0.16002)
		(layer "In4.Cu")
		(net "M_D_CPU1_SA_DQS_DN<4>")
	)
	(segment
		(start 55.849266 -239.607344)
		(end 56.102504 -239.354106)
		(width 0.16002)
		(layer "In4.Cu")
		(net "M_D_CPU1_SA_DQS_DN<4>")
	)
	(segment
		(start 76.60132 -246.947436)
		(end 77.400404 -246.947436)
		(width 0.09525)
		(layer "In4.Cu")
		(net "M_D_CPU1_SA_DQS_DN<4>")
	)
	(segment
		(start 54.767226 -238.590836)
		(end 54.943756 -238.767366)
		(width 0.16002)
		(layer "In4.Cu")
		(net "M_D_CPU1_SA_DQS_DN<4>")
	)
	(segment
		(start 75.903328 -246.293894)
		(end 75.96251 -246.234712)
		(width 0.09525)
		(layer "In4.Cu")
		(net "M_D_CPU1_SA_DQS_DN<4>")
	)
	(segment
		(start 61.393832 -241.967258)
		(end 61.676026 -241.685064)
		(width 0.16002)
		(layer "In4.Cu")
		(net "M_D_CPU1_SA_DQS_DN<4>")
	)
	(segment
		(start 89.502488 -246.589296)
		(end 89.51087 -246.58447)
		(width 0.09525)
		(layer "In4.Cu")
		(net "M_D_CPU1_SA_DQS_DN<4>")
	)
	(segment
		(start 90.76182 -246.562372)
		(end 90.784934 -246.648986)
		(width 0.09525)
		(layer "In4.Cu")
		(net "M_D_CPU1_SA_DQS_DN<4>")
	)
	(segment
		(start 60.866528 -241.967258)
		(end 61.393832 -241.967258)
		(width 0.16002)
		(layer "In4.Cu")
		(net "M_D_CPU1_SA_DQS_DN<4>")
	)
	(segment
		(start 75.879706 -246.293894)
		(end 75.903328 -246.293894)
		(width 0.09525)
		(layer "In4.Cu")
		(net "M_D_CPU1_SA_DQS_DN<4>")
	)
	(segment
		(start 60.199524 -240.414302)
		(end 60.476384 -240.414302)
		(width 0.16002)
		(layer "In4.Cu")
		(net "M_D_CPU1_SA_DQS_DN<4>")
	)
	(segment
		(start 63.326518 -243.058696)
		(end 63.523114 -243.255292)
		(width 0.16002)
		(layer "In4.Cu")
		(net "M_D_CPU1_SA_DQS_DN<4>")
	)
	(segment
		(start 80.471264 -246.58447)
		(end 80.479646 -246.589296)
		(width 0.09525)
		(layer "In4.Cu")
		(net "M_D_CPU1_SA_DQS_DN<4>")
	)
	(segment
		(start 40.989504 -238.562388)
		(end 41.318942 -238.891826)
		(width 0.16002)
		(layer "In4.Cu")
		(net "M_D_CPU1_SA_DQS_DN<4>")
	)
	(segment
		(start 65.193164 -246.293894)
		(end 75.879706 -246.293894)
		(width 0.16002)
		(layer "In4.Cu")
		(net "M_D_CPU1_SA_DQS_DN<4>")
	)
	(segment
		(start 64.614552 -245.715282)
		(end 65.193164 -246.293894)
		(width 0.16002)
		(layer "In4.Cu")
		(net "M_D_CPU1_SA_DQS_DN<4>")
	)
	(segment
		(start 81.04251 -246.589296)
		(end 81.050892 -246.58447)
		(width 0.09525)
		(layer "In4.Cu")
		(net "M_D_CPU1_SA_DQS_DN<4>")
	)
	(segment
		(start 46.42612 -238.562388)
		(end 46.54296 -238.679228)
		(width 0.16002)
		(layer "In4.Cu")
		(net "M_D_CPU1_SA_DQS_DN<4>")
	)
	(segment
		(start 60.493656 -241.594386)
		(end 60.866528 -241.967258)
		(width 0.16002)
		(layer "In4.Cu")
		(net "M_D_CPU1_SA_DQS_DN<4>")
	)
	(segment
		(start 60.493656 -241.067082)
		(end 60.493656 -241.594386)
		(width 0.16002)
		(layer "In4.Cu")
		(net "M_D_CPU1_SA_DQS_DN<4>")
	)
	(segment
		(start 43.231308 -238.061246)
		(end 43.58005 -237.712504)
		(width 0.16002)
		(layer "In4.Cu")
		(net "M_D_CPU1_SA_DQS_DN<4>")
	)
	(segment
		(start 54.943756 -239.23244)
		(end 55.31866 -239.607344)
		(width 0.16002)
		(layer "In4.Cu")
		(net "M_D_CPU1_SA_DQS_DN<4>")
	)
	(segment
		(start 63.523114 -243.255292)
		(end 63.523114 -243.532152)
		(width 0.16002)
		(layer "In4.Cu")
		(net "M_D_CPU1_SA_DQS_DN<4>")
	)
	(segment
		(start 64.70015 -244.432328)
		(end 64.896746 -244.628924)
		(width 0.16002)
		(layer "In4.Cu")
		(net "M_D_CPU1_SA_DQS_DN<4>")
	)
	(segment
		(start 60.476384 -240.414302)
		(end 60.67298 -240.610898)
		(width 0.16002)
		(layer "In4.Cu")
		(net "M_D_CPU1_SA_DQS_DN<4>")
	)
	(segment
		(start 53.534818 -238.590836)
		(end 54.767226 -238.590836)
		(width 0.16002)
		(layer "In4.Cu")
		(net "M_D_CPU1_SA_DQS_DN<4>")
	)
	(segment
		(start 60.67298 -240.610898)
		(end 60.67298 -240.887758)
		(width 0.16002)
		(layer "In4.Cu")
		(net "M_D_CPU1_SA_DQS_DN<4>")
	)
	(segment
		(start 61.952886 -241.685064)
		(end 62.149482 -241.88166)
		(width 0.16002)
		(layer "In4.Cu")
		(net "M_D_CPU1_SA_DQS_DN<4>")
	)
	(segment
		(start 47.13986 -238.562388)
		(end 48.533304 -238.562388)
		(width 0.16002)
		(layer "In4.Cu")
		(net "M_D_CPU1_SA_DQS_DN<4>")
	)
	(segment
		(start 41.318942 -238.891826)
		(end 41.955974 -238.891826)
		(width 0.16002)
		(layer "In4.Cu")
		(net "M_D_CPU1_SA_DQS_DN<4>")
	)
	(segment
		(start 41.955974 -238.891826)
		(end 42.786554 -238.061246)
		(width 0.16002)
		(layer "In4.Cu")
		(net "M_D_CPU1_SA_DQS_DN<4>")
	)
	(segment
		(start 84.802472 -246.589296)
		(end 84.810854 -246.58447)
		(width 0.09525)
		(layer "In4.Cu")
		(net "M_D_CPU1_SA_DQS_DN<4>")
	)
	(segment
		(start 90.784934 -246.648986)
		(end 90.63101 -246.914416)
		(width 0.09525)
		(layer "In4.Cu")
		(net "M_D_CPU1_SA_DQS_DN<4>")
	)
	(segment
		(start 43.58005 -237.712504)
		(end 45.063918 -237.712504)
		(width 0.16002)
		(layer "In4.Cu")
		(net "M_D_CPU1_SA_DQS_DN<4>")
	)
	(segment
		(start 76.268834 -246.329962)
		(end 76.268834 -246.61495)
		(width 0.09525)
		(layer "In4.Cu")
		(net "M_D_CPU1_SA_DQS_DN<4>")
	)
	(segment
		(start 78.223618 -246.589296)
		(end 78.249018 -246.574818)
		(width 0.09525)
		(layer "In4.Cu")
		(net "M_D_CPU1_SA_DQS_DN<4>")
	)
	(segment
		(start 64.614552 -245.187978)
		(end 64.614552 -245.715282)
		(width 0.16002)
		(layer "In4.Cu")
		(net "M_D_CPU1_SA_DQS_DN<4>")
	)
	(segment
		(start 64.42329 -244.432328)
		(end 64.70015 -244.432328)
		(width 0.16002)
		(layer "In4.Cu")
		(net "M_D_CPU1_SA_DQS_DN<4>")
	)
	(segment
		(start 46.54296 -238.679228)
		(end 47.02302 -238.679228)
		(width 0.16002)
		(layer "In4.Cu")
		(net "M_D_CPU1_SA_DQS_DN<4>")
	)
	(segment
		(start 64.141096 -244.714522)
		(end 64.42329 -244.432328)
		(width 0.16002)
		(layer "In4.Cu")
		(net "M_D_CPU1_SA_DQS_DN<4>")
	)
	(segment
		(start 42.786554 -238.061246)
		(end 43.231308 -238.061246)
		(width 0.16002)
		(layer "In4.Cu")
		(net "M_D_CPU1_SA_DQS_DN<4>")
	)
	(segment
		(start 76.268834 -246.61495)
		(end 76.60132 -246.947436)
		(width 0.09525)
		(layer "In4.Cu")
		(net "M_D_CPU1_SA_DQS_DN<4>")
	)
	(segment
		(start 59.492896 -240.593626)
		(end 60.0202 -240.593626)
		(width 0.16002)
		(layer "In4.Cu")
		(net "M_D_CPU1_SA_DQS_DN<4>")
	)
	(segment
		(start 61.676026 -241.685064)
		(end 61.952886 -241.685064)
		(width 0.16002)
		(layer "In4.Cu")
		(net "M_D_CPU1_SA_DQS_DN<4>")
	)
	(segment
		(start 49.528222 -238.891826)
		(end 50.358802 -238.061246)
		(width 0.16002)
		(layer "In4.Cu")
		(net "M_D_CPU1_SA_DQS_DN<4>")
	)
	(segment
		(start 56.102504 -239.354106)
		(end 58.253376 -239.354106)
		(width 0.16002)
		(layer "In4.Cu")
		(net "M_D_CPU1_SA_DQS_DN<4>")
	)
	(segment
		(start 63.613792 -244.714522)
		(end 64.141096 -244.714522)
		(width 0.16002)
		(layer "In4.Cu")
		(net "M_D_CPU1_SA_DQS_DN<4>")
	)
	(segment
		(start 50.775108 -238.061246)
		(end 51.12385 -237.712504)
		(width 0.16002)
		(layer "In4.Cu")
		(net "M_D_CPU1_SA_DQS_DN<4>")
	)
	(segment
		(start 64.896746 -244.628924)
		(end 64.896746 -244.905784)
		(width 0.16002)
		(layer "In4.Cu")
		(net "M_D_CPU1_SA_DQS_DN<4>")
	)
	(segment
		(start 77.68336 -246.66448)
		(end 77.94371 -246.66448)
		(width 0.09525)
		(layer "In4.Cu")
		(net "M_D_CPU1_SA_DQS_DN<4>")
	)
	(segment
		(start 77.400404 -246.947436)
		(end 77.68336 -246.66448)
		(width 0.09525)
		(layer "In4.Cu")
		(net "M_D_CPU1_SA_DQS_DN<4>")
	)
	(segment
		(start 79.526638 -246.580914)
		(end 79.541116 -246.589296)
		(width 0.09525)
		(layer "In4.Cu")
		(net "M_D_CPU1_SA_DQS_DN<4>")
	)
	(segment
		(start 63.24092 -243.814346)
		(end 63.24092 -244.34165)
		(width 0.16002)
		(layer "In4.Cu")
		(net "M_D_CPU1_SA_DQS_DN<4>")
	)
	(segment
		(start 76.173584 -246.234712)
		(end 76.268834 -246.329962)
		(width 0.09525)
		(layer "In4.Cu")
		(net "M_D_CPU1_SA_DQS_DN<4>")
	)
	(segment
		(start 62.24016 -243.34089)
		(end 62.767464 -243.34089)
		(width 0.16002)
		(layer "In4.Cu")
		(net "M_D_CPU1_SA_DQS_DN<4>")
	)
	(segment
		(start 79.141574 -246.602758)
		(end 79.164942 -246.589296)
		(width 0.09525)
		(layer "In4.Cu")
		(net "M_D_CPU1_SA_DQS_DN<4>")
	)
	(segment
		(start 48.862742 -238.891826)
		(end 49.528222 -238.891826)
		(width 0.16002)
		(layer "In4.Cu")
		(net "M_D_CPU1_SA_DQS_DN<4>")
	)
	(segment
		(start 62.149482 -241.88166)
		(end 62.149482 -242.15852)
		(width 0.16002)
		(layer "In4.Cu")
		(net "M_D_CPU1_SA_DQS_DN<4>")
	)
	(segment
		(start 58.253376 -239.354106)
		(end 59.492896 -240.593626)
		(width 0.16002)
		(layer "In4.Cu")
		(net "M_D_CPU1_SA_DQS_DN<4>")
	)
	(segment
		(start 47.02302 -238.679228)
		(end 47.13986 -238.562388)
		(width 0.16002)
		(layer "In4.Cu")
		(net "M_D_CPU1_SA_DQS_DN<4>")
	)
	(segment
		(start 79.541116 -246.589296)
		(end 79.566516 -246.604028)
		(width 0.09525)
		(layer "In4.Cu")
		(net "M_D_CPU1_SA_DQS_DN<4>")
	)
	(segment
		(start 48.533304 -238.562388)
		(end 48.862742 -238.891826)
		(width 0.16002)
		(layer "In4.Cu")
		(net "M_D_CPU1_SA_DQS_DN<4>")
	)
	(segment
		(start 39.346886 -238.562388)
		(end 40.989504 -238.562388)
		(width 0.16002)
		(layer "In4.Cu")
		(net "M_D_CPU1_SA_DQS_DN<4>")
	)
	(segment
		(start 45.913802 -238.562388)
		(end 46.42612 -238.562388)
		(width 0.16002)
		(layer "In4.Cu")
		(net "M_D_CPU1_SA_DQS_DN<4>")
	)
	(segment
		(start 62.149482 -242.15852)
		(end 61.867288 -242.440714)
		(width 0.16002)
		(layer "In4.Cu")
		(net "M_D_CPU1_SA_DQS_DN<4>")
	)
	(segment
		(start 45.063918 -237.712504)
		(end 45.913802 -238.562388)
		(width 0.16002)
		(layer "In4.Cu")
		(net "M_D_CPU1_SA_DQS_DN<4>")
	)
	(segment
		(start 87.991188 -246.58447)
		(end 87.99957 -246.589296)
		(width 0.09525)
		(layer "In4.Cu")
		(net "M_D_CPU1_SA_DQS_DN<4>")
	)
	(segment
		(start 36.795964 -238.985298)
		(end 37.069776 -238.711486)
		(width 0.16002)
		(layer "In4.Cu")
		(net "M_D_CPU1_SA_DQS_DN<4>")
	)
	(segment
		(start 37.069776 -238.711486)
		(end 39.197788 -238.711486)
		(width 0.16002)
		(layer "In4.Cu")
		(net "M_D_CPU1_SA_DQS_DN<4>")
	)
	(segment
		(start 51.12385 -237.712504)
		(end 52.656486 -237.712504)
		(width 0.16002)
		(layer "In4.Cu")
		(net "M_D_CPU1_SA_DQS_DN<4>")
	)
	(segment
		(start 54.943756 -238.767366)
		(end 54.943756 -239.23244)
		(width 0.16002)
		(layer "In4.Cu")
		(net "M_D_CPU1_SA_DQS_DN<4>")
	)
	(segment
		(start 60.67298 -240.887758)
		(end 60.493656 -241.067082)
		(width 0.16002)
		(layer "In4.Cu")
		(net "M_D_CPU1_SA_DQS_DN<4>")
	)
	(segment
		(start 64.896746 -244.905784)
		(end 64.614552 -245.187978)
		(width 0.16002)
		(layer "In4.Cu")
		(net "M_D_CPU1_SA_DQS_DN<4>")
	)
	(segment
		(start 63.523114 -243.532152)
		(end 63.24092 -243.814346)
		(width 0.16002)
		(layer "In4.Cu")
		(net "M_D_CPU1_SA_DQS_DN<4>")
	)
	(segment
		(start 61.867288 -242.968018)
		(end 62.24016 -243.34089)
		(width 0.16002)
		(layer "In4.Cu")
		(net "M_D_CPU1_SA_DQS_DN<4>")
	)
	(segment
		(start 39.197788 -238.711486)
		(end 39.346886 -238.562388)
		(width 0.16002)
		(layer "In4.Cu")
		(net "M_D_CPU1_SA_DQS_DN<4>")
	)
	(segment
		(start 75.96251 -246.234712)
		(end 76.173584 -246.234712)
		(width 0.09525)
		(layer "In4.Cu")
		(net "M_D_CPU1_SA_DQS_DN<4>")
	)
	(segment
		(start 52.656486 -237.712504)
		(end 53.534818 -238.590836)
		(width 0.16002)
		(layer "In4.Cu")
		(net "M_D_CPU1_SA_DQS_DN<4>")
	)
	(segment
		(start 50.358802 -238.061246)
		(end 50.775108 -238.061246)
		(width 0.16002)
		(layer "In4.Cu")
		(net "M_D_CPU1_SA_DQS_DN<4>")
	)
	(segment
		(start 61.867288 -242.440714)
		(end 61.867288 -242.968018)
		(width 0.16002)
		(layer "In4.Cu")
		(net "M_D_CPU1_SA_DQS_DN<4>")
	)
	(segment
		(start 84.231226 -246.58447)
		(end 84.239608 -246.589296)
		(width 0.09525)
		(layer "In4.Cu")
		(net "M_D_CPU1_SA_DQS_DN<4>")
	)
	(segment
		(start 83.291172 -246.58447)
		(end 83.299554 -246.589296)
		(width 0.09525)
		(layer "In4.Cu")
		(net "M_D_CPU1_SA_DQS_DN<4>")
	)
	(segment
		(start 55.31866 -239.607344)
		(end 55.849266 -239.607344)
		(width 0.16002)
		(layer "In4.Cu")
		(net "M_D_CPU1_SA_DQS_DN<4>")
	)
	(segment
		(start 60.0202 -240.593626)
		(end 60.199524 -240.414302)
		(width 0.16002)
		(layer "In4.Cu")
		(net "M_D_CPU1_SA_DQS_DN<4>")
	)
	(segment
		(start 88.931242 -246.58447)
		(end 88.939624 -246.589296)
		(width 0.09525)
		(layer "In4.Cu")
		(net "M_D_CPU1_SA_DQS_DN<4>")
	)
	(segment
		(start 85.742526 -246.589296)
		(end 85.750908 -246.58447)
		(width 0.09525)
		(layer "In4.Cu")
		(net "M_D_CPU1_SA_DQS_DN<4>")
	)
	(segment
		(start 63.24092 -244.34165)
		(end 63.613792 -244.714522)
		(width 0.16002)
		(layer "In4.Cu")
		(net "M_D_CPU1_SA_DQS_DN<4>")
	)
	(arc
		(start 81.982564 -246.589296)
		(mid 82.171032 -246.538619)
		(end 82.3595 -246.589296)
		(width 0.09525)
		(layer "In4.Cu")
		(net "M_D_CPU1_SA_DQS_DN<4>")
	)
	(arc
		(start 87.99957 -246.589296)
		(mid 88.281002 -246.665051)
		(end 88.562434 -246.589296)
		(width 0.09525)
		(layer "In4.Cu")
		(net "M_D_CPU1_SA_DQS_DN<4>")
	)
	(arc
		(start 80.102456 -246.589296)
		(mid 80.286231 -246.538524)
		(end 80.471264 -246.58447)
		(width 0.09525)
		(layer "In4.Cu")
		(net "M_D_CPU1_SA_DQS_DN<4>")
	)
	(arc
		(start 86.68258 -246.589296)
		(mid 86.871048 -246.538619)
		(end 87.059516 -246.589296)
		(width 0.09525)
		(layer "In4.Cu")
		(net "M_D_CPU1_SA_DQS_DN<4>")
	)
	(arc
		(start 90.442542 -246.589296)
		(mid 90.599169 -246.54011)
		(end 90.76182 -246.562372)
		(width 0.09525)
		(layer "In4.Cu")
		(net "M_D_CPU1_SA_DQS_DN<4>")
	)
	(arc
		(start 88.562434 -246.589296)
		(mid 88.746209 -246.538524)
		(end 88.931242 -246.58447)
		(width 0.09525)
		(layer "In4.Cu")
		(net "M_D_CPU1_SA_DQS_DN<4>")
	)
	(arc
		(start 85.750908 -246.58447)
		(mid 85.93594 -246.538556)
		(end 86.119716 -246.589296)
		(width 0.09525)
		(layer "In4.Cu")
		(net "M_D_CPU1_SA_DQS_DN<4>")
	)
	(arc
		(start 82.3595 -246.589296)
		(mid 82.640932 -246.665051)
		(end 82.922364 -246.589296)
		(width 0.09525)
		(layer "In4.Cu")
		(net "M_D_CPU1_SA_DQS_DN<4>")
	)
	(arc
		(start 78.600808 -246.589296)
		(mid 78.869471 -246.665514)
		(end 79.141574 -246.602758)
		(width 0.09525)
		(layer "In4.Cu")
		(net "M_D_CPU1_SA_DQS_DN<4>")
	)
	(arc
		(start 83.299554 -246.589296)
		(mid 83.580986 -246.665051)
		(end 83.862418 -246.589296)
		(width 0.09525)
		(layer "In4.Cu")
		(net "M_D_CPU1_SA_DQS_DN<4>")
	)
	(arc
		(start 87.62238 -246.589296)
		(mid 87.806155 -246.538524)
		(end 87.991188 -246.58447)
		(width 0.09525)
		(layer "In4.Cu")
		(net "M_D_CPU1_SA_DQS_DN<4>")
	)
	(arc
		(start 84.810854 -246.58447)
		(mid 84.995886 -246.538556)
		(end 85.179662 -246.589296)
		(width 0.09525)
		(layer "In4.Cu")
		(net "M_D_CPU1_SA_DQS_DN<4>")
	)
	(arc
		(start 84.239608 -246.589296)
		(mid 84.52104 -246.665051)
		(end 84.802472 -246.589296)
		(width 0.09525)
		(layer "In4.Cu")
		(net "M_D_CPU1_SA_DQS_DN<4>")
	)
	(arc
		(start 81.4197 -246.589296)
		(mid 81.701132 -246.665051)
		(end 81.982564 -246.589296)
		(width 0.09525)
		(layer "In4.Cu")
		(net "M_D_CPU1_SA_DQS_DN<4>")
	)
	(arc
		(start 85.179662 -246.589296)
		(mid 85.461094 -246.665051)
		(end 85.742526 -246.589296)
		(width 0.09525)
		(layer "In4.Cu")
		(net "M_D_CPU1_SA_DQS_DN<4>")
	)
	(arc
		(start 82.922364 -246.589296)
		(mid 83.106139 -246.538524)
		(end 83.291172 -246.58447)
		(width 0.09525)
		(layer "In4.Cu")
		(net "M_D_CPU1_SA_DQS_DN<4>")
	)
	(arc
		(start 83.862418 -246.589296)
		(mid 84.046193 -246.538524)
		(end 84.231226 -246.58447)
		(width 0.09525)
		(layer "In4.Cu")
		(net "M_D_CPU1_SA_DQS_DN<4>")
	)
	(arc
		(start 80.479646 -246.589296)
		(mid 80.761078 -246.665051)
		(end 81.04251 -246.589296)
		(width 0.09525)
		(layer "In4.Cu")
		(net "M_D_CPU1_SA_DQS_DN<4>")
	)
	(arc
		(start 78.249018 -246.574818)
		(mid 78.426723 -246.53834)
		(end 78.600808 -246.589296)
		(width 0.09525)
		(layer "In4.Cu")
		(net "M_D_CPU1_SA_DQS_DN<4>")
	)
	(arc
		(start 89.51087 -246.58447)
		(mid 89.695902 -246.538556)
		(end 89.879678 -246.589296)
		(width 0.09525)
		(layer "In4.Cu")
		(net "M_D_CPU1_SA_DQS_DN<4>")
	)
	(arc
		(start 81.050892 -246.58447)
		(mid 81.235924 -246.538556)
		(end 81.4197 -246.589296)
		(width 0.09525)
		(layer "In4.Cu")
		(net "M_D_CPU1_SA_DQS_DN<4>")
	)
	(arc
		(start 77.94371 -246.66448)
		(mid 78.004522 -246.661169)
		(end 78.064614 -246.651272)
		(width 0.09525)
		(layer "In4.Cu")
		(net "M_D_CPU1_SA_DQS_DN<4>")
	)
	(arc
		(start 79.164942 -246.589296)
		(mid 79.344714 -246.53872)
		(end 79.526638 -246.580914)
		(width 0.09525)
		(layer "In4.Cu")
		(net "M_D_CPU1_SA_DQS_DN<4>")
	)
	(arc
		(start 78.064614 -246.651272)
		(mid 78.146495 -246.626385)
		(end 78.223618 -246.589296)
		(width 0.09525)
		(layer "In4.Cu")
		(net "M_D_CPU1_SA_DQS_DN<4>")
	)
	(arc
		(start 89.879678 -246.589296)
		(mid 90.16111 -246.665051)
		(end 90.442542 -246.589296)
		(width 0.09525)
		(layer "In4.Cu")
		(net "M_D_CPU1_SA_DQS_DN<4>")
	)
	(arc
		(start 87.059516 -246.589296)
		(mid 87.340948 -246.665051)
		(end 87.62238 -246.589296)
		(width 0.09525)
		(layer "In4.Cu")
		(net "M_D_CPU1_SA_DQS_DN<4>")
	)
	(arc
		(start 86.119716 -246.589296)
		(mid 86.401148 -246.665051)
		(end 86.68258 -246.589296)
		(width 0.09525)
		(layer "In4.Cu")
		(net "M_D_CPU1_SA_DQS_DN<4>")
	)
	(arc
		(start 88.939624 -246.589296)
		(mid 89.221056 -246.665051)
		(end 89.502488 -246.589296)
		(width 0.09525)
		(layer "In4.Cu")
		(net "M_D_CPU1_SA_DQS_DN<4>")
	)
	(arc
		(start 79.566516 -246.604028)
		(mid 79.83637 -246.664907)
		(end 80.102456 -246.589296)
		(width 0.09525)
		(layer "In4.Cu")
		(net "M_D_CPU1_SA_DQS_DN<4>")
	)
	(segment
		(start 91.097862 -242.320318)
		(end 90.63101 -242.05438)
		(width 0.12954)
		(layer "F.Cu")
		(net "M_D_CPU1_SA_DQS_DN<3>")
	)
	(segment
		(start 61.470286 -231.577642)
		(end 61.99759 -231.577642)
		(width 0.16002)
		(layer "In4.Cu")
		(net "M_D_CPU1_SA_DQS_DN<3>")
	)
	(segment
		(start 64.052704 -233.21645)
		(end 63.844678 -233.424476)
		(width 0.16002)
		(layer "In4.Cu")
		(net "M_D_CPU1_SA_DQS_DN<3>")
	)
	(segment
		(start 59.951366 -229.41788)
		(end 59.951366 -229.577392)
		(width 0.16002)
		(layer "In4.Cu")
		(net "M_D_CPU1_SA_DQS_DN<3>")
	)
	(segment
		(start 64.744854 -234.324906)
		(end 64.953134 -234.116626)
		(width 0.16002)
		(layer "In4.Cu")
		(net "M_D_CPU1_SA_DQS_DN<3>")
	)
	(segment
		(start 63.579502 -232.742994)
		(end 63.855854 -232.742994)
		(width 0.16002)
		(layer "In4.Cu")
		(net "M_D_CPU1_SA_DQS_DN<3>")
	)
	(segment
		(start 58.91784 -229.942644)
		(end 59.283092 -229.577392)
		(width 0.16002)
		(layer "In4.Cu")
		(net "M_D_CPU1_SA_DQS_DN<3>")
	)
	(segment
		(start 53.846222 -229.552246)
		(end 55.44947 -229.552246)
		(width 0.16002)
		(layer "In4.Cu")
		(net "M_D_CPU1_SA_DQS_DN<3>")
	)
	(segment
		(start 75.955906 -240.659666)
		(end 75.979528 -240.659666)
		(width 0.09525)
		(layer "In4.Cu")
		(net "M_D_CPU1_SA_DQS_DN<3>")
	)
	(segment
		(start 59.283092 -229.41788)
		(end 59.478926 -229.222046)
		(width 0.16002)
		(layer "In4.Cu")
		(net "M_D_CPU1_SA_DQS_DN<3>")
	)
	(segment
		(start 62.843918 -232.951274)
		(end 63.371222 -232.951274)
		(width 0.16002)
		(layer "In4.Cu")
		(net "M_D_CPU1_SA_DQS_DN<3>")
	)
	(segment
		(start 62.471046 -232.050844)
		(end 62.471046 -232.578402)
		(width 0.16002)
		(layer "In4.Cu")
		(net "M_D_CPU1_SA_DQS_DN<3>")
	)
	(segment
		(start 41.881298 -229.616508)
		(end 42.786554 -228.711252)
		(width 0.16002)
		(layer "In4.Cu")
		(net "M_D_CPU1_SA_DQS_DN<3>")
	)
	(segment
		(start 61.30544 -230.469186)
		(end 61.097414 -230.677466)
		(width 0.16002)
		(layer "In4.Cu")
		(net "M_D_CPU1_SA_DQS_DN<3>")
	)
	(segment
		(start 46.42358 -229.329234)
		(end 46.90364 -229.329234)
		(width 0.16002)
		(layer "In4.Cu")
		(net "M_D_CPU1_SA_DQS_DN<3>")
	)
	(segment
		(start 59.478926 -229.222046)
		(end 59.755532 -229.222046)
		(width 0.16002)
		(layer "In4.Cu")
		(net "M_D_CPU1_SA_DQS_DN<3>")
	)
	(segment
		(start 79.53121 -241.724434)
		(end 79.539592 -241.72926)
		(width 0.09525)
		(layer "In4.Cu")
		(net "M_D_CPU1_SA_DQS_DN<3>")
	)
	(segment
		(start 39.346886 -229.212394)
		(end 40.989504 -229.212394)
		(width 0.16002)
		(layer "In4.Cu")
		(net "M_D_CPU1_SA_DQS_DN<3>")
	)
	(segment
		(start 36.795964 -229.635304)
		(end 37.069776 -229.361492)
		(width 0.16002)
		(layer "In4.Cu")
		(net "M_D_CPU1_SA_DQS_DN<3>")
	)
	(segment
		(start 76.711302 -241.087656)
		(end 77.150976 -241.087656)
		(width 0.09525)
		(layer "In4.Cu")
		(net "M_D_CPU1_SA_DQS_DN<3>")
	)
	(segment
		(start 59.283092 -229.577392)
		(end 59.283092 -229.41788)
		(width 0.16002)
		(layer "In4.Cu")
		(net "M_D_CPU1_SA_DQS_DN<3>")
	)
	(segment
		(start 43.58005 -228.36251)
		(end 44.95927 -228.36251)
		(width 0.16002)
		(layer "In4.Cu")
		(net "M_D_CPU1_SA_DQS_DN<3>")
	)
	(segment
		(start 39.197788 -229.361492)
		(end 39.346886 -229.212394)
		(width 0.16002)
		(layer "In4.Cu")
		(net "M_D_CPU1_SA_DQS_DN<3>")
	)
	(segment
		(start 55.839868 -229.942644)
		(end 56.562752 -229.942644)
		(width 0.16002)
		(layer "In4.Cu")
		(net "M_D_CPU1_SA_DQS_DN<3>")
	)
	(segment
		(start 90.76182 -241.702336)
		(end 90.784934 -241.78895)
		(width 0.09525)
		(layer "In4.Cu")
		(net "M_D_CPU1_SA_DQS_DN<3>")
	)
	(segment
		(start 64.052704 -232.939844)
		(end 64.052704 -233.21645)
		(width 0.16002)
		(layer "In4.Cu")
		(net "M_D_CPU1_SA_DQS_DN<3>")
	)
	(segment
		(start 40.989504 -229.212394)
		(end 41.393618 -229.616508)
		(width 0.16002)
		(layer "In4.Cu")
		(net "M_D_CPU1_SA_DQS_DN<3>")
	)
	(segment
		(start 51.12385 -228.36251)
		(end 52.656486 -228.36251)
		(width 0.16002)
		(layer "In4.Cu")
		(net "M_D_CPU1_SA_DQS_DN<3>")
	)
	(segment
		(start 42.786554 -228.711252)
		(end 43.231308 -228.711252)
		(width 0.16002)
		(layer "In4.Cu")
		(net "M_D_CPU1_SA_DQS_DN<3>")
	)
	(segment
		(start 50.775108 -228.711252)
		(end 51.12385 -228.36251)
		(width 0.16002)
		(layer "In4.Cu")
		(net "M_D_CPU1_SA_DQS_DN<3>")
	)
	(segment
		(start 65.229486 -234.116626)
		(end 65.426336 -234.313476)
		(width 0.16002)
		(layer "In4.Cu")
		(net "M_D_CPU1_SA_DQS_DN<3>")
	)
	(segment
		(start 61.10859 -229.99573)
		(end 61.30544 -230.19258)
		(width 0.16002)
		(layer "In4.Cu")
		(net "M_D_CPU1_SA_DQS_DN<3>")
	)
	(segment
		(start 62.679072 -231.566212)
		(end 62.679072 -231.842818)
		(width 0.16002)
		(layer "In4.Cu")
		(net "M_D_CPU1_SA_DQS_DN<3>")
	)
	(segment
		(start 56.562752 -229.942644)
		(end 56.92521 -229.580186)
		(width 0.16002)
		(layer "In4.Cu")
		(net "M_D_CPU1_SA_DQS_DN<3>")
	)
	(segment
		(start 84.802472 -241.72926)
		(end 84.810854 -241.724434)
		(width 0.09525)
		(layer "In4.Cu")
		(net "M_D_CPU1_SA_DQS_DN<3>")
	)
	(segment
		(start 62.471046 -232.578402)
		(end 62.843918 -232.951274)
		(width 0.16002)
		(layer "In4.Cu")
		(net "M_D_CPU1_SA_DQS_DN<3>")
	)
	(segment
		(start 90.784934 -241.78895)
		(end 90.63101 -242.05438)
		(width 0.09525)
		(layer "In4.Cu")
		(net "M_D_CPU1_SA_DQS_DN<3>")
	)
	(segment
		(start 62.20587 -231.369362)
		(end 62.482222 -231.369362)
		(width 0.16002)
		(layer "In4.Cu")
		(net "M_D_CPU1_SA_DQS_DN<3>")
	)
	(segment
		(start 77.150976 -241.087656)
		(end 77.741272 -241.677952)
		(width 0.09525)
		(layer "In4.Cu")
		(net "M_D_CPU1_SA_DQS_DN<3>")
	)
	(segment
		(start 57.780936 -229.942644)
		(end 58.91784 -229.942644)
		(width 0.16002)
		(layer "In4.Cu")
		(net "M_D_CPU1_SA_DQS_DN<3>")
	)
	(segment
		(start 62.679072 -231.842818)
		(end 62.471046 -232.050844)
		(width 0.16002)
		(layer "In4.Cu")
		(net "M_D_CPU1_SA_DQS_DN<3>")
	)
	(segment
		(start 88.931242 -241.724434)
		(end 88.939624 -241.72926)
		(width 0.09525)
		(layer "In4.Cu")
		(net "M_D_CPU1_SA_DQS_DN<3>")
	)
	(segment
		(start 61.30544 -230.19258)
		(end 61.30544 -230.469186)
		(width 0.16002)
		(layer "In4.Cu")
		(net "M_D_CPU1_SA_DQS_DN<3>")
	)
	(segment
		(start 59.951366 -229.577392)
		(end 60.369704 -229.99573)
		(width 0.16002)
		(layer "In4.Cu")
		(net "M_D_CPU1_SA_DQS_DN<3>")
	)
	(segment
		(start 46.90364 -229.329234)
		(end 47.02048 -229.212394)
		(width 0.16002)
		(layer "In4.Cu")
		(net "M_D_CPU1_SA_DQS_DN<3>")
	)
	(segment
		(start 76.224384 -240.600738)
		(end 76.711302 -241.087656)
		(width 0.09525)
		(layer "In4.Cu")
		(net "M_D_CPU1_SA_DQS_DN<3>")
	)
	(segment
		(start 63.855854 -232.742994)
		(end 64.052704 -232.939844)
		(width 0.16002)
		(layer "In4.Cu")
		(net "M_D_CPU1_SA_DQS_DN<3>")
	)
	(segment
		(start 45.809154 -229.212394)
		(end 46.30674 -229.212394)
		(width 0.16002)
		(layer "In4.Cu")
		(net "M_D_CPU1_SA_DQS_DN<3>")
	)
	(segment
		(start 57.418478 -229.580186)
		(end 57.780936 -229.942644)
		(width 0.16002)
		(layer "In4.Cu")
		(net "M_D_CPU1_SA_DQS_DN<3>")
	)
	(segment
		(start 48.951642 -229.630732)
		(end 49.439322 -229.630732)
		(width 0.16002)
		(layer "In4.Cu")
		(net "M_D_CPU1_SA_DQS_DN<3>")
	)
	(segment
		(start 62.482222 -231.369362)
		(end 62.679072 -231.566212)
		(width 0.16002)
		(layer "In4.Cu")
		(net "M_D_CPU1_SA_DQS_DN<3>")
	)
	(segment
		(start 61.097414 -230.677466)
		(end 61.097414 -231.20477)
		(width 0.16002)
		(layer "In4.Cu")
		(net "M_D_CPU1_SA_DQS_DN<3>")
	)
	(segment
		(start 55.44947 -229.552246)
		(end 55.839868 -229.942644)
		(width 0.16002)
		(layer "In4.Cu")
		(net "M_D_CPU1_SA_DQS_DN<3>")
	)
	(segment
		(start 41.393618 -229.616508)
		(end 41.881298 -229.616508)
		(width 0.16002)
		(layer "In4.Cu")
		(net "M_D_CPU1_SA_DQS_DN<3>")
	)
	(segment
		(start 85.742526 -241.72926)
		(end 85.750908 -241.724434)
		(width 0.09525)
		(layer "In4.Cu")
		(net "M_D_CPU1_SA_DQS_DN<3>")
	)
	(segment
		(start 64.21755 -234.324906)
		(end 64.744854 -234.324906)
		(width 0.16002)
		(layer "In4.Cu")
		(net "M_D_CPU1_SA_DQS_DN<3>")
	)
	(segment
		(start 76.038456 -240.600738)
		(end 76.224384 -240.600738)
		(width 0.09525)
		(layer "In4.Cu")
		(net "M_D_CPU1_SA_DQS_DN<3>")
	)
	(segment
		(start 63.844678 -233.424476)
		(end 63.844678 -233.952034)
		(width 0.16002)
		(layer "In4.Cu")
		(net "M_D_CPU1_SA_DQS_DN<3>")
	)
	(segment
		(start 48.533304 -229.212394)
		(end 48.951642 -229.630732)
		(width 0.16002)
		(layer "In4.Cu")
		(net "M_D_CPU1_SA_DQS_DN<3>")
	)
	(segment
		(start 46.30674 -229.212394)
		(end 46.42358 -229.329234)
		(width 0.16002)
		(layer "In4.Cu")
		(net "M_D_CPU1_SA_DQS_DN<3>")
	)
	(segment
		(start 65.426336 -234.313476)
		(end 65.426336 -234.590082)
		(width 0.16002)
		(layer "In4.Cu")
		(net "M_D_CPU1_SA_DQS_DN<3>")
	)
	(segment
		(start 63.371222 -232.951274)
		(end 63.579502 -232.742994)
		(width 0.16002)
		(layer "In4.Cu")
		(net "M_D_CPU1_SA_DQS_DN<3>")
	)
	(segment
		(start 49.439322 -229.630732)
		(end 50.358802 -228.711252)
		(width 0.16002)
		(layer "In4.Cu")
		(net "M_D_CPU1_SA_DQS_DN<3>")
	)
	(segment
		(start 80.471264 -241.724434)
		(end 80.479646 -241.72926)
		(width 0.09525)
		(layer "In4.Cu")
		(net "M_D_CPU1_SA_DQS_DN<3>")
	)
	(segment
		(start 63.844678 -233.952034)
		(end 64.21755 -234.324906)
		(width 0.16002)
		(layer "In4.Cu")
		(net "M_D_CPU1_SA_DQS_DN<3>")
	)
	(segment
		(start 87.991188 -241.724434)
		(end 87.99957 -241.72926)
		(width 0.09525)
		(layer "In4.Cu")
		(net "M_D_CPU1_SA_DQS_DN<3>")
	)
	(segment
		(start 50.358802 -228.711252)
		(end 50.775108 -228.711252)
		(width 0.16002)
		(layer "In4.Cu")
		(net "M_D_CPU1_SA_DQS_DN<3>")
	)
	(segment
		(start 70.55231 -240.659666)
		(end 75.955906 -240.659666)
		(width 0.16002)
		(layer "In4.Cu")
		(net "M_D_CPU1_SA_DQS_DN<3>")
	)
	(segment
		(start 52.656486 -228.36251)
		(end 53.846222 -229.552246)
		(width 0.16002)
		(layer "In4.Cu")
		(net "M_D_CPU1_SA_DQS_DN<3>")
	)
	(segment
		(start 47.02048 -229.212394)
		(end 48.533304 -229.212394)
		(width 0.16002)
		(layer "In4.Cu")
		(net "M_D_CPU1_SA_DQS_DN<3>")
	)
	(segment
		(start 59.755532 -229.222046)
		(end 59.951366 -229.41788)
		(width 0.16002)
		(layer "In4.Cu")
		(net "M_D_CPU1_SA_DQS_DN<3>")
	)
	(segment
		(start 89.502488 -241.72926)
		(end 89.51087 -241.724434)
		(width 0.09525)
		(layer "In4.Cu")
		(net "M_D_CPU1_SA_DQS_DN<3>")
	)
	(segment
		(start 44.95927 -228.36251)
		(end 45.809154 -229.212394)
		(width 0.16002)
		(layer "In4.Cu")
		(net "M_D_CPU1_SA_DQS_DN<3>")
	)
	(segment
		(start 64.953134 -234.116626)
		(end 65.229486 -234.116626)
		(width 0.16002)
		(layer "In4.Cu")
		(net "M_D_CPU1_SA_DQS_DN<3>")
	)
	(segment
		(start 60.369704 -229.99573)
		(end 61.10859 -229.99573)
		(width 0.16002)
		(layer "In4.Cu")
		(net "M_D_CPU1_SA_DQS_DN<3>")
	)
	(segment
		(start 56.92521 -229.580186)
		(end 57.418478 -229.580186)
		(width 0.16002)
		(layer "In4.Cu")
		(net "M_D_CPU1_SA_DQS_DN<3>")
	)
	(segment
		(start 65.21831 -234.798108)
		(end 65.21831 -235.325666)
		(width 0.16002)
		(layer "In4.Cu")
		(net "M_D_CPU1_SA_DQS_DN<3>")
	)
	(segment
		(start 77.741272 -241.677952)
		(end 78.41107 -241.677952)
		(width 0.09525)
		(layer "In4.Cu")
		(net "M_D_CPU1_SA_DQS_DN<3>")
	)
	(segment
		(start 65.426336 -234.590082)
		(end 65.21831 -234.798108)
		(width 0.16002)
		(layer "In4.Cu")
		(net "M_D_CPU1_SA_DQS_DN<3>")
	)
	(segment
		(start 43.231308 -228.711252)
		(end 43.58005 -228.36251)
		(width 0.16002)
		(layer "In4.Cu")
		(net "M_D_CPU1_SA_DQS_DN<3>")
	)
	(segment
		(start 65.21831 -235.325666)
		(end 70.55231 -240.659666)
		(width 0.16002)
		(layer "In4.Cu")
		(net "M_D_CPU1_SA_DQS_DN<3>")
	)
	(segment
		(start 84.231226 -241.724434)
		(end 84.239608 -241.72926)
		(width 0.09525)
		(layer "In4.Cu")
		(net "M_D_CPU1_SA_DQS_DN<3>")
	)
	(segment
		(start 83.291172 -241.724434)
		(end 83.299554 -241.72926)
		(width 0.09525)
		(layer "In4.Cu")
		(net "M_D_CPU1_SA_DQS_DN<3>")
	)
	(segment
		(start 81.04251 -241.72926)
		(end 81.050892 -241.724434)
		(width 0.09525)
		(layer "In4.Cu")
		(net "M_D_CPU1_SA_DQS_DN<3>")
	)
	(segment
		(start 61.097414 -231.20477)
		(end 61.470286 -231.577642)
		(width 0.16002)
		(layer "In4.Cu")
		(net "M_D_CPU1_SA_DQS_DN<3>")
	)
	(segment
		(start 61.99759 -231.577642)
		(end 62.20587 -231.369362)
		(width 0.16002)
		(layer "In4.Cu")
		(net "M_D_CPU1_SA_DQS_DN<3>")
	)
	(segment
		(start 75.979528 -240.659666)
		(end 76.038456 -240.600738)
		(width 0.09525)
		(layer "In4.Cu")
		(net "M_D_CPU1_SA_DQS_DN<3>")
	)
	(segment
		(start 37.069776 -229.361492)
		(end 39.197788 -229.361492)
		(width 0.16002)
		(layer "In4.Cu")
		(net "M_D_CPU1_SA_DQS_DN<3>")
	)
	(arc
		(start 82.3595 -241.72926)
		(mid 82.640932 -241.805015)
		(end 82.922364 -241.72926)
		(width 0.09525)
		(layer "In4.Cu")
		(net "M_D_CPU1_SA_DQS_DN<3>")
	)
	(arc
		(start 81.050892 -241.724434)
		(mid 81.235924 -241.67852)
		(end 81.4197 -241.72926)
		(width 0.09525)
		(layer "In4.Cu")
		(net "M_D_CPU1_SA_DQS_DN<3>")
	)
	(arc
		(start 79.162402 -241.72926)
		(mid 79.346177 -241.678488)
		(end 79.53121 -241.724434)
		(width 0.09525)
		(layer "In4.Cu")
		(net "M_D_CPU1_SA_DQS_DN<3>")
	)
	(arc
		(start 83.299554 -241.72926)
		(mid 83.580986 -241.805015)
		(end 83.862418 -241.72926)
		(width 0.09525)
		(layer "In4.Cu")
		(net "M_D_CPU1_SA_DQS_DN<3>")
	)
	(arc
		(start 81.982564 -241.72926)
		(mid 82.171032 -241.678583)
		(end 82.3595 -241.72926)
		(width 0.09525)
		(layer "In4.Cu")
		(net "M_D_CPU1_SA_DQS_DN<3>")
	)
	(arc
		(start 79.539592 -241.72926)
		(mid 79.821024 -241.805015)
		(end 80.102456 -241.72926)
		(width 0.09525)
		(layer "In4.Cu")
		(net "M_D_CPU1_SA_DQS_DN<3>")
	)
	(arc
		(start 86.68258 -241.72926)
		(mid 86.871048 -241.678583)
		(end 87.059516 -241.72926)
		(width 0.09525)
		(layer "In4.Cu")
		(net "M_D_CPU1_SA_DQS_DN<3>")
	)
	(arc
		(start 87.059516 -241.72926)
		(mid 87.340948 -241.805015)
		(end 87.62238 -241.72926)
		(width 0.09525)
		(layer "In4.Cu")
		(net "M_D_CPU1_SA_DQS_DN<3>")
	)
	(arc
		(start 82.922364 -241.72926)
		(mid 83.106139 -241.678488)
		(end 83.291172 -241.724434)
		(width 0.09525)
		(layer "In4.Cu")
		(net "M_D_CPU1_SA_DQS_DN<3>")
	)
	(arc
		(start 80.479646 -241.72926)
		(mid 80.761078 -241.805015)
		(end 81.04251 -241.72926)
		(width 0.09525)
		(layer "In4.Cu")
		(net "M_D_CPU1_SA_DQS_DN<3>")
	)
	(arc
		(start 80.102456 -241.72926)
		(mid 80.286231 -241.678488)
		(end 80.471264 -241.724434)
		(width 0.09525)
		(layer "In4.Cu")
		(net "M_D_CPU1_SA_DQS_DN<3>")
	)
	(arc
		(start 84.239608 -241.72926)
		(mid 84.52104 -241.805015)
		(end 84.802472 -241.72926)
		(width 0.09525)
		(layer "In4.Cu")
		(net "M_D_CPU1_SA_DQS_DN<3>")
	)
	(arc
		(start 81.4197 -241.72926)
		(mid 81.701132 -241.805015)
		(end 81.982564 -241.72926)
		(width 0.09525)
		(layer "In4.Cu")
		(net "M_D_CPU1_SA_DQS_DN<3>")
	)
	(arc
		(start 85.179662 -241.72926)
		(mid 85.461094 -241.805015)
		(end 85.742526 -241.72926)
		(width 0.09525)
		(layer "In4.Cu")
		(net "M_D_CPU1_SA_DQS_DN<3>")
	)
	(arc
		(start 87.99957 -241.72926)
		(mid 88.281002 -241.805015)
		(end 88.562434 -241.72926)
		(width 0.09525)
		(layer "In4.Cu")
		(net "M_D_CPU1_SA_DQS_DN<3>")
	)
	(arc
		(start 89.879678 -241.72926)
		(mid 90.16111 -241.805015)
		(end 90.442542 -241.72926)
		(width 0.09525)
		(layer "In4.Cu")
		(net "M_D_CPU1_SA_DQS_DN<3>")
	)
	(arc
		(start 88.939624 -241.72926)
		(mid 89.221056 -241.805015)
		(end 89.502488 -241.72926)
		(width 0.09525)
		(layer "In4.Cu")
		(net "M_D_CPU1_SA_DQS_DN<3>")
	)
	(arc
		(start 89.51087 -241.724434)
		(mid 89.695902 -241.67852)
		(end 89.879678 -241.72926)
		(width 0.09525)
		(layer "In4.Cu")
		(net "M_D_CPU1_SA_DQS_DN<3>")
	)
	(arc
		(start 83.862418 -241.72926)
		(mid 84.046193 -241.678488)
		(end 84.231226 -241.724434)
		(width 0.09525)
		(layer "In4.Cu")
		(net "M_D_CPU1_SA_DQS_DN<3>")
	)
	(arc
		(start 90.442542 -241.72926)
		(mid 90.599169 -241.680074)
		(end 90.76182 -241.702336)
		(width 0.09525)
		(layer "In4.Cu")
		(net "M_D_CPU1_SA_DQS_DN<3>")
	)
	(arc
		(start 85.750908 -241.724434)
		(mid 85.93594 -241.67852)
		(end 86.119716 -241.72926)
		(width 0.09525)
		(layer "In4.Cu")
		(net "M_D_CPU1_SA_DQS_DN<3>")
	)
	(arc
		(start 84.810854 -241.724434)
		(mid 84.995886 -241.67852)
		(end 85.179662 -241.72926)
		(width 0.09525)
		(layer "In4.Cu")
		(net "M_D_CPU1_SA_DQS_DN<3>")
	)
	(arc
		(start 78.599538 -241.72926)
		(mid 78.88097 -241.805015)
		(end 79.162402 -241.72926)
		(width 0.09525)
		(layer "In4.Cu")
		(net "M_D_CPU1_SA_DQS_DN<3>")
	)
	(arc
		(start 78.41107 -241.677952)
		(mid 78.508684 -241.691179)
		(end 78.599538 -241.72926)
		(width 0.09525)
		(layer "In4.Cu")
		(net "M_D_CPU1_SA_DQS_DN<3>")
	)
	(arc
		(start 86.119716 -241.72926)
		(mid 86.401148 -241.805015)
		(end 86.68258 -241.72926)
		(width 0.09525)
		(layer "In4.Cu")
		(net "M_D_CPU1_SA_DQS_DN<3>")
	)
	(arc
		(start 88.562434 -241.72926)
		(mid 88.746209 -241.678488)
		(end 88.931242 -241.724434)
		(width 0.09525)
		(layer "In4.Cu")
		(net "M_D_CPU1_SA_DQS_DN<3>")
	)
	(arc
		(start 87.62238 -241.72926)
		(mid 87.806155 -241.678488)
		(end 87.991188 -241.724434)
		(width 0.09525)
		(layer "In4.Cu")
		(net "M_D_CPU1_SA_DQS_DN<3>")
	)
	(segment
		(start 91.097862 -237.460282)
		(end 90.63101 -237.194344)
		(width 0.12954)
		(layer "F.Cu")
		(net "M_D_CPU1_SA_DQS_DN<2>")
	)
	(segment
		(start 39.205408 -220.011498)
		(end 39.354506 -219.8624)
		(width 0.16002)
		(layer "In4.Cu")
		(net "M_D_CPU1_SA_DQS_DN<2>")
	)
	(segment
		(start 62.712854 -222.38208)
		(end 62.989714 -222.38208)
		(width 0.16002)
		(layer "In4.Cu")
		(net "M_D_CPU1_SA_DQS_DN<2>")
	)
	(segment
		(start 87.991188 -236.864398)
		(end 87.99957 -236.869224)
		(width 0.09525)
		(layer "In4.Cu")
		(net "M_D_CPU1_SA_DQS_DN<2>")
	)
	(segment
		(start 65.521586 -226.541838)
		(end 65.894458 -226.91471)
		(width 0.16002)
		(layer "In4.Cu")
		(net "M_D_CPU1_SA_DQS_DN<2>")
	)
	(segment
		(start 61.33465 -222.354902)
		(end 61.773562 -222.793814)
		(width 0.16002)
		(layer "In4.Cu")
		(net "M_D_CPU1_SA_DQS_DN<2>")
	)
	(segment
		(start 64.363346 -223.755712)
		(end 64.559942 -223.952308)
		(width 0.16002)
		(layer "In4.Cu")
		(net "M_D_CPU1_SA_DQS_DN<2>")
	)
	(segment
		(start 51.12385 -219.012516)
		(end 52.656486 -219.012516)
		(width 0.16002)
		(layer "In4.Cu")
		(net "M_D_CPU1_SA_DQS_DN<2>")
	)
	(segment
		(start 75.955906 -235.03636)
		(end 75.979528 -235.03636)
		(width 0.09525)
		(layer "In4.Cu")
		(net "M_D_CPU1_SA_DQS_DN<2>")
	)
	(segment
		(start 88.931242 -236.864398)
		(end 88.939624 -236.869224)
		(width 0.09525)
		(layer "In4.Cu")
		(net "M_D_CPU1_SA_DQS_DN<2>")
	)
	(segment
		(start 80.471264 -236.864398)
		(end 80.479646 -236.869224)
		(width 0.09525)
		(layer "In4.Cu")
		(net "M_D_CPU1_SA_DQS_DN<2>")
	)
	(segment
		(start 47.05604 -219.8624)
		(end 48.533304 -219.8624)
		(width 0.16002)
		(layer "In4.Cu")
		(net "M_D_CPU1_SA_DQS_DN<2>")
	)
	(segment
		(start 63.674752 -224.167446)
		(end 64.086486 -223.755712)
		(width 0.16002)
		(layer "In4.Cu")
		(net "M_D_CPU1_SA_DQS_DN<2>")
	)
	(segment
		(start 65.460118 -225.129344)
		(end 65.736978 -225.129344)
		(width 0.16002)
		(layer "In4.Cu")
		(net "M_D_CPU1_SA_DQS_DN<2>")
	)
	(segment
		(start 64.147954 -225.168206)
		(end 64.520826 -225.541078)
		(width 0.16002)
		(layer "In4.Cu")
		(net "M_D_CPU1_SA_DQS_DN<2>")
	)
	(segment
		(start 65.894458 -226.91471)
		(end 66.522092 -226.91471)
		(width 0.16002)
		(layer "In4.Cu")
		(net "M_D_CPU1_SA_DQS_DN<2>")
	)
	(segment
		(start 46.3423 -219.8624)
		(end 46.45914 -219.97924)
		(width 0.16002)
		(layer "In4.Cu")
		(net "M_D_CPU1_SA_DQS_DN<2>")
	)
	(segment
		(start 48.951642 -220.280738)
		(end 49.439322 -220.280738)
		(width 0.16002)
		(layer "In4.Cu")
		(net "M_D_CPU1_SA_DQS_DN<2>")
	)
	(segment
		(start 46.9392 -219.97924)
		(end 47.05604 -219.8624)
		(width 0.16002)
		(layer "In4.Cu")
		(net "M_D_CPU1_SA_DQS_DN<2>")
	)
	(segment
		(start 36.795964 -220.28531)
		(end 37.069776 -220.011498)
		(width 0.16002)
		(layer "In4.Cu")
		(net "M_D_CPU1_SA_DQS_DN<2>")
	)
	(segment
		(start 83.291172 -236.864398)
		(end 83.299554 -236.869224)
		(width 0.09525)
		(layer "In4.Cu")
		(net "M_D_CPU1_SA_DQS_DN<2>")
	)
	(segment
		(start 76.268834 -235.072428)
		(end 76.268834 -235.28147)
		(width 0.09525)
		(layer "In4.Cu")
		(net "M_D_CPU1_SA_DQS_DN<2>")
	)
	(segment
		(start 78.160118 -236.817154)
		(end 78.41107 -236.817154)
		(width 0.09525)
		(layer "In4.Cu")
		(net "M_D_CPU1_SA_DQS_DN<2>")
	)
	(segment
		(start 66.522092 -226.91471)
		(end 66.895218 -227.287836)
		(width 0.16002)
		(layer "In4.Cu")
		(net "M_D_CPU1_SA_DQS_DN<2>")
	)
	(segment
		(start 90.784934 -236.928914)
		(end 90.63101 -237.194344)
		(width 0.09525)
		(layer "In4.Cu")
		(net "M_D_CPU1_SA_DQS_DN<2>")
	)
	(segment
		(start 61.773562 -222.793814)
		(end 62.30112 -222.793814)
		(width 0.16002)
		(layer "In4.Cu")
		(net "M_D_CPU1_SA_DQS_DN<2>")
	)
	(segment
		(start 41.881298 -220.266514)
		(end 42.786554 -219.361258)
		(width 0.16002)
		(layer "In4.Cu")
		(net "M_D_CPU1_SA_DQS_DN<2>")
	)
	(segment
		(start 76.69784 -235.710476)
		(end 77.05344 -235.710476)
		(width 0.09525)
		(layer "In4.Cu")
		(net "M_D_CPU1_SA_DQS_DN<2>")
	)
	(segment
		(start 74.016108 -235.03636)
		(end 75.955906 -235.03636)
		(width 0.16002)
		(layer "In4.Cu")
		(net "M_D_CPU1_SA_DQS_DN<2>")
	)
	(segment
		(start 76.03871 -234.977178)
		(end 76.173584 -234.977178)
		(width 0.09525)
		(layer "In4.Cu")
		(net "M_D_CPU1_SA_DQS_DN<2>")
	)
	(segment
		(start 64.086486 -223.755712)
		(end 64.363346 -223.755712)
		(width 0.16002)
		(layer "In4.Cu")
		(net "M_D_CPU1_SA_DQS_DN<2>")
	)
	(segment
		(start 43.231308 -219.361258)
		(end 43.58005 -219.012516)
		(width 0.16002)
		(layer "In4.Cu")
		(net "M_D_CPU1_SA_DQS_DN<2>")
	)
	(segment
		(start 63.147194 -224.167446)
		(end 63.674752 -224.167446)
		(width 0.16002)
		(layer "In4.Cu")
		(net "M_D_CPU1_SA_DQS_DN<2>")
	)
	(segment
		(start 84.802472 -236.869224)
		(end 84.810854 -236.864398)
		(width 0.09525)
		(layer "In4.Cu")
		(net "M_D_CPU1_SA_DQS_DN<2>")
	)
	(segment
		(start 66.895218 -227.287836)
		(end 66.895218 -227.91547)
		(width 0.16002)
		(layer "In4.Cu")
		(net "M_D_CPU1_SA_DQS_DN<2>")
	)
	(segment
		(start 53.695854 -220.051884)
		(end 54.575202 -220.051884)
		(width 0.16002)
		(layer "In4.Cu")
		(net "M_D_CPU1_SA_DQS_DN<2>")
	)
	(segment
		(start 61.33465 -221.985586)
		(end 61.33465 -222.354902)
		(width 0.16002)
		(layer "In4.Cu")
		(net "M_D_CPU1_SA_DQS_DN<2>")
	)
	(segment
		(start 40.989504 -219.8624)
		(end 41.393618 -220.266514)
		(width 0.16002)
		(layer "In4.Cu")
		(net "M_D_CPU1_SA_DQS_DN<2>")
	)
	(segment
		(start 64.520826 -225.541078)
		(end 65.048384 -225.541078)
		(width 0.16002)
		(layer "In4.Cu")
		(net "M_D_CPU1_SA_DQS_DN<2>")
	)
	(segment
		(start 62.774322 -223.794574)
		(end 63.147194 -224.167446)
		(width 0.16002)
		(layer "In4.Cu")
		(net "M_D_CPU1_SA_DQS_DN<2>")
	)
	(segment
		(start 43.58005 -219.012516)
		(end 44.951142 -219.012516)
		(width 0.16002)
		(layer "In4.Cu")
		(net "M_D_CPU1_SA_DQS_DN<2>")
	)
	(segment
		(start 62.30112 -222.793814)
		(end 62.712854 -222.38208)
		(width 0.16002)
		(layer "In4.Cu")
		(net "M_D_CPU1_SA_DQS_DN<2>")
	)
	(segment
		(start 76.173584 -234.977178)
		(end 76.268834 -235.072428)
		(width 0.09525)
		(layer "In4.Cu")
		(net "M_D_CPU1_SA_DQS_DN<2>")
	)
	(segment
		(start 42.786554 -219.361258)
		(end 43.231308 -219.361258)
		(width 0.16002)
		(layer "In4.Cu")
		(net "M_D_CPU1_SA_DQS_DN<2>")
	)
	(segment
		(start 46.45914 -219.97924)
		(end 46.9392 -219.97924)
		(width 0.16002)
		(layer "In4.Cu")
		(net "M_D_CPU1_SA_DQS_DN<2>")
	)
	(segment
		(start 65.933574 -225.32594)
		(end 65.933574 -225.602546)
		(width 0.16002)
		(layer "In4.Cu")
		(net "M_D_CPU1_SA_DQS_DN<2>")
	)
	(segment
		(start 64.147954 -224.640902)
		(end 64.147954 -225.168206)
		(width 0.16002)
		(layer "In4.Cu")
		(net "M_D_CPU1_SA_DQS_DN<2>")
	)
	(segment
		(start 76.268834 -235.28147)
		(end 76.69784 -235.710476)
		(width 0.09525)
		(layer "In4.Cu")
		(net "M_D_CPU1_SA_DQS_DN<2>")
	)
	(segment
		(start 62.989714 -222.38208)
		(end 63.18631 -222.578676)
		(width 0.16002)
		(layer "In4.Cu")
		(net "M_D_CPU1_SA_DQS_DN<2>")
	)
	(segment
		(start 89.502488 -236.869224)
		(end 89.51087 -236.864398)
		(width 0.09525)
		(layer "In4.Cu")
		(net "M_D_CPU1_SA_DQS_DN<2>")
	)
	(segment
		(start 59.969908 -220.620844)
		(end 61.33465 -221.985586)
		(width 0.16002)
		(layer "In4.Cu")
		(net "M_D_CPU1_SA_DQS_DN<2>")
	)
	(segment
		(start 49.439322 -220.280738)
		(end 50.358802 -219.361258)
		(width 0.16002)
		(layer "In4.Cu")
		(net "M_D_CPU1_SA_DQS_DN<2>")
	)
	(segment
		(start 62.774322 -223.26727)
		(end 62.774322 -223.794574)
		(width 0.16002)
		(layer "In4.Cu")
		(net "M_D_CPU1_SA_DQS_DN<2>")
	)
	(segment
		(start 39.354506 -219.8624)
		(end 40.989504 -219.8624)
		(width 0.16002)
		(layer "In4.Cu")
		(net "M_D_CPU1_SA_DQS_DN<2>")
	)
	(segment
		(start 64.559942 -224.228914)
		(end 64.147954 -224.640902)
		(width 0.16002)
		(layer "In4.Cu")
		(net "M_D_CPU1_SA_DQS_DN<2>")
	)
	(segment
		(start 65.048384 -225.541078)
		(end 65.460118 -225.129344)
		(width 0.16002)
		(layer "In4.Cu")
		(net "M_D_CPU1_SA_DQS_DN<2>")
	)
	(segment
		(start 79.141574 -236.882686)
		(end 79.164942 -236.869224)
		(width 0.09525)
		(layer "In4.Cu")
		(net "M_D_CPU1_SA_DQS_DN<2>")
	)
	(segment
		(start 41.393618 -220.266514)
		(end 41.881298 -220.266514)
		(width 0.16002)
		(layer "In4.Cu")
		(net "M_D_CPU1_SA_DQS_DN<2>")
	)
	(segment
		(start 75.979528 -235.03636)
		(end 76.03871 -234.977178)
		(width 0.09525)
		(layer "In4.Cu")
		(net "M_D_CPU1_SA_DQS_DN<2>")
	)
	(segment
		(start 79.526638 -236.860842)
		(end 79.541116 -236.869224)
		(width 0.09525)
		(layer "In4.Cu")
		(net "M_D_CPU1_SA_DQS_DN<2>")
	)
	(segment
		(start 84.231226 -236.864398)
		(end 84.239608 -236.869224)
		(width 0.09525)
		(layer "In4.Cu")
		(net "M_D_CPU1_SA_DQS_DN<2>")
	)
	(segment
		(start 65.933574 -225.602546)
		(end 65.521586 -226.014534)
		(width 0.16002)
		(layer "In4.Cu")
		(net "M_D_CPU1_SA_DQS_DN<2>")
	)
	(segment
		(start 48.533304 -219.8624)
		(end 48.951642 -220.280738)
		(width 0.16002)
		(layer "In4.Cu")
		(net "M_D_CPU1_SA_DQS_DN<2>")
	)
	(segment
		(start 45.801026 -219.8624)
		(end 46.3423 -219.8624)
		(width 0.16002)
		(layer "In4.Cu")
		(net "M_D_CPU1_SA_DQS_DN<2>")
	)
	(segment
		(start 37.069776 -220.011498)
		(end 39.205408 -220.011498)
		(width 0.16002)
		(layer "In4.Cu")
		(net "M_D_CPU1_SA_DQS_DN<2>")
	)
	(segment
		(start 50.775108 -219.361258)
		(end 51.12385 -219.012516)
		(width 0.16002)
		(layer "In4.Cu")
		(net "M_D_CPU1_SA_DQS_DN<2>")
	)
	(segment
		(start 50.358802 -219.361258)
		(end 50.775108 -219.361258)
		(width 0.16002)
		(layer "In4.Cu")
		(net "M_D_CPU1_SA_DQS_DN<2>")
	)
	(segment
		(start 81.04251 -236.869224)
		(end 81.050892 -236.864398)
		(width 0.09525)
		(layer "In4.Cu")
		(net "M_D_CPU1_SA_DQS_DN<2>")
	)
	(segment
		(start 65.521586 -226.014534)
		(end 65.521586 -226.541838)
		(width 0.16002)
		(layer "In4.Cu")
		(net "M_D_CPU1_SA_DQS_DN<2>")
	)
	(segment
		(start 79.541116 -236.869224)
		(end 79.566516 -236.883956)
		(width 0.09525)
		(layer "In4.Cu")
		(net "M_D_CPU1_SA_DQS_DN<2>")
	)
	(segment
		(start 44.951142 -219.012516)
		(end 45.801026 -219.8624)
		(width 0.16002)
		(layer "In4.Cu")
		(net "M_D_CPU1_SA_DQS_DN<2>")
	)
	(segment
		(start 63.18631 -222.855282)
		(end 62.774322 -223.26727)
		(width 0.16002)
		(layer "In4.Cu")
		(net "M_D_CPU1_SA_DQS_DN<2>")
	)
	(segment
		(start 66.895218 -227.91547)
		(end 74.016108 -235.03636)
		(width 0.16002)
		(layer "In4.Cu")
		(net "M_D_CPU1_SA_DQS_DN<2>")
	)
	(segment
		(start 55.144162 -220.620844)
		(end 59.969908 -220.620844)
		(width 0.16002)
		(layer "In4.Cu")
		(net "M_D_CPU1_SA_DQS_DN<2>")
	)
	(segment
		(start 90.76182 -236.8423)
		(end 90.784934 -236.928914)
		(width 0.09525)
		(layer "In4.Cu")
		(net "M_D_CPU1_SA_DQS_DN<2>")
	)
	(segment
		(start 85.742526 -236.869224)
		(end 85.750908 -236.864398)
		(width 0.09525)
		(layer "In4.Cu")
		(net "M_D_CPU1_SA_DQS_DN<2>")
	)
	(segment
		(start 52.656486 -219.012516)
		(end 53.695854 -220.051884)
		(width 0.16002)
		(layer "In4.Cu")
		(net "M_D_CPU1_SA_DQS_DN<2>")
	)
	(segment
		(start 54.575202 -220.051884)
		(end 55.144162 -220.620844)
		(width 0.16002)
		(layer "In4.Cu")
		(net "M_D_CPU1_SA_DQS_DN<2>")
	)
	(segment
		(start 77.05344 -235.710476)
		(end 78.160118 -236.817154)
		(width 0.09525)
		(layer "In4.Cu")
		(net "M_D_CPU1_SA_DQS_DN<2>")
	)
	(segment
		(start 63.18631 -222.578676)
		(end 63.18631 -222.855282)
		(width 0.16002)
		(layer "In4.Cu")
		(net "M_D_CPU1_SA_DQS_DN<2>")
	)
	(segment
		(start 65.736978 -225.129344)
		(end 65.933574 -225.32594)
		(width 0.16002)
		(layer "In4.Cu")
		(net "M_D_CPU1_SA_DQS_DN<2>")
	)
	(segment
		(start 64.559942 -223.952308)
		(end 64.559942 -224.228914)
		(width 0.16002)
		(layer "In4.Cu")
		(net "M_D_CPU1_SA_DQS_DN<2>")
	)
	(arc
		(start 79.164942 -236.869224)
		(mid 79.344714 -236.818648)
		(end 79.526638 -236.860842)
		(width 0.09525)
		(layer "In4.Cu")
		(net "M_D_CPU1_SA_DQS_DN<2>")
	)
	(arc
		(start 84.239608 -236.869224)
		(mid 84.52104 -236.944979)
		(end 84.802472 -236.869224)
		(width 0.09525)
		(layer "In4.Cu")
		(net "M_D_CPU1_SA_DQS_DN<2>")
	)
	(arc
		(start 85.750908 -236.864398)
		(mid 85.93594 -236.818484)
		(end 86.119716 -236.869224)
		(width 0.09525)
		(layer "In4.Cu")
		(net "M_D_CPU1_SA_DQS_DN<2>")
	)
	(arc
		(start 78.41107 -236.817154)
		(mid 78.509408 -236.83056)
		(end 78.600808 -236.869224)
		(width 0.09525)
		(layer "In4.Cu")
		(net "M_D_CPU1_SA_DQS_DN<2>")
	)
	(arc
		(start 86.119716 -236.869224)
		(mid 86.401148 -236.944979)
		(end 86.68258 -236.869224)
		(width 0.09525)
		(layer "In4.Cu")
		(net "M_D_CPU1_SA_DQS_DN<2>")
	)
	(arc
		(start 87.99957 -236.869224)
		(mid 88.281002 -236.944979)
		(end 88.562434 -236.869224)
		(width 0.09525)
		(layer "In4.Cu")
		(net "M_D_CPU1_SA_DQS_DN<2>")
	)
	(arc
		(start 78.600808 -236.869224)
		(mid 78.869471 -236.945442)
		(end 79.141574 -236.882686)
		(width 0.09525)
		(layer "In4.Cu")
		(net "M_D_CPU1_SA_DQS_DN<2>")
	)
	(arc
		(start 83.862418 -236.869224)
		(mid 84.046193 -236.818452)
		(end 84.231226 -236.864398)
		(width 0.09525)
		(layer "In4.Cu")
		(net "M_D_CPU1_SA_DQS_DN<2>")
	)
	(arc
		(start 83.299554 -236.869224)
		(mid 83.580986 -236.944979)
		(end 83.862418 -236.869224)
		(width 0.09525)
		(layer "In4.Cu")
		(net "M_D_CPU1_SA_DQS_DN<2>")
	)
	(arc
		(start 82.922364 -236.869224)
		(mid 83.106139 -236.818452)
		(end 83.291172 -236.864398)
		(width 0.09525)
		(layer "In4.Cu")
		(net "M_D_CPU1_SA_DQS_DN<2>")
	)
	(arc
		(start 84.810854 -236.864398)
		(mid 84.995886 -236.818484)
		(end 85.179662 -236.869224)
		(width 0.09525)
		(layer "In4.Cu")
		(net "M_D_CPU1_SA_DQS_DN<2>")
	)
	(arc
		(start 89.51087 -236.864398)
		(mid 89.695902 -236.818484)
		(end 89.879678 -236.869224)
		(width 0.09525)
		(layer "In4.Cu")
		(net "M_D_CPU1_SA_DQS_DN<2>")
	)
	(arc
		(start 81.982564 -236.869224)
		(mid 82.171032 -236.818547)
		(end 82.3595 -236.869224)
		(width 0.09525)
		(layer "In4.Cu")
		(net "M_D_CPU1_SA_DQS_DN<2>")
	)
	(arc
		(start 86.68258 -236.869224)
		(mid 86.871048 -236.818547)
		(end 87.059516 -236.869224)
		(width 0.09525)
		(layer "In4.Cu")
		(net "M_D_CPU1_SA_DQS_DN<2>")
	)
	(arc
		(start 81.050892 -236.864398)
		(mid 81.235924 -236.818484)
		(end 81.4197 -236.869224)
		(width 0.09525)
		(layer "In4.Cu")
		(net "M_D_CPU1_SA_DQS_DN<2>")
	)
	(arc
		(start 81.4197 -236.869224)
		(mid 81.701132 -236.944979)
		(end 81.982564 -236.869224)
		(width 0.09525)
		(layer "In4.Cu")
		(net "M_D_CPU1_SA_DQS_DN<2>")
	)
	(arc
		(start 80.479646 -236.869224)
		(mid 80.761078 -236.944979)
		(end 81.04251 -236.869224)
		(width 0.09525)
		(layer "In4.Cu")
		(net "M_D_CPU1_SA_DQS_DN<2>")
	)
	(arc
		(start 80.102456 -236.869224)
		(mid 80.286231 -236.818452)
		(end 80.471264 -236.864398)
		(width 0.09525)
		(layer "In4.Cu")
		(net "M_D_CPU1_SA_DQS_DN<2>")
	)
	(arc
		(start 82.3595 -236.869224)
		(mid 82.640932 -236.944979)
		(end 82.922364 -236.869224)
		(width 0.09525)
		(layer "In4.Cu")
		(net "M_D_CPU1_SA_DQS_DN<2>")
	)
	(arc
		(start 87.62238 -236.869224)
		(mid 87.806155 -236.818452)
		(end 87.991188 -236.864398)
		(width 0.09525)
		(layer "In4.Cu")
		(net "M_D_CPU1_SA_DQS_DN<2>")
	)
	(arc
		(start 87.059516 -236.869224)
		(mid 87.340948 -236.944979)
		(end 87.62238 -236.869224)
		(width 0.09525)
		(layer "In4.Cu")
		(net "M_D_CPU1_SA_DQS_DN<2>")
	)
	(arc
		(start 85.179662 -236.869224)
		(mid 85.461094 -236.944979)
		(end 85.742526 -236.869224)
		(width 0.09525)
		(layer "In4.Cu")
		(net "M_D_CPU1_SA_DQS_DN<2>")
	)
	(arc
		(start 90.442542 -236.869224)
		(mid 90.599169 -236.820038)
		(end 90.76182 -236.8423)
		(width 0.09525)
		(layer "In4.Cu")
		(net "M_D_CPU1_SA_DQS_DN<2>")
	)
	(arc
		(start 88.562434 -236.869224)
		(mid 88.746209 -236.818452)
		(end 88.931242 -236.864398)
		(width 0.09525)
		(layer "In4.Cu")
		(net "M_D_CPU1_SA_DQS_DN<2>")
	)
	(arc
		(start 89.879678 -236.869224)
		(mid 90.16111 -236.944979)
		(end 90.442542 -236.869224)
		(width 0.09525)
		(layer "In4.Cu")
		(net "M_D_CPU1_SA_DQS_DN<2>")
	)
	(arc
		(start 88.939624 -236.869224)
		(mid 89.221056 -236.944979)
		(end 89.502488 -236.869224)
		(width 0.09525)
		(layer "In4.Cu")
		(net "M_D_CPU1_SA_DQS_DN<2>")
	)
	(arc
		(start 79.566516 -236.883956)
		(mid 79.83637 -236.944835)
		(end 80.102456 -236.869224)
		(width 0.09525)
		(layer "In4.Cu")
		(net "M_D_CPU1_SA_DQS_DN<2>")
	)
	(segment
		(start 91.097862 -232.600246)
		(end 90.63101 -232.334308)
		(width 0.12954)
		(layer "F.Cu")
		(net "M_D_CPU1_SA_DQS_DN<1>")
	)
	(segment
		(start 52.634896 -209.662522)
		(end 53.618638 -210.646264)
		(width 0.16002)
		(layer "In4.Cu")
		(net "M_D_CPU1_SA_DQS_DN<1>")
	)
	(segment
		(start 66.38163 -217.812366)
		(end 66.908934 -217.812366)
		(width 0.16002)
		(layer "In4.Cu")
		(net "M_D_CPU1_SA_DQS_DN<1>")
	)
	(segment
		(start 67.48907 -218.179142)
		(end 67.38239 -218.285822)
		(width 0.16002)
		(layer "In4.Cu")
		(net "M_D_CPU1_SA_DQS_DN<1>")
	)
	(segment
		(start 81.04251 -232.009188)
		(end 81.050892 -232.004362)
		(width 0.09525)
		(layer "In4.Cu")
		(net "M_D_CPU1_SA_DQS_DN<1>")
	)
	(segment
		(start 70.236334 -220.926406)
		(end 70.129654 -221.033086)
		(width 0.16002)
		(layer "In4.Cu")
		(net "M_D_CPU1_SA_DQS_DN<1>")
	)
	(segment
		(start 41.962324 -210.857084)
		(end 42.792904 -210.026504)
		(width 0.16002)
		(layer "In4.Cu")
		(net "M_D_CPU1_SA_DQS_DN<1>")
	)
	(segment
		(start 68.389246 -219.079318)
		(end 68.666106 -219.079318)
		(width 0.16002)
		(layer "In4.Cu")
		(net "M_D_CPU1_SA_DQS_DN<1>")
	)
	(segment
		(start 70.039738 -220.45295)
		(end 70.236334 -220.649546)
		(width 0.16002)
		(layer "In4.Cu")
		(net "M_D_CPU1_SA_DQS_DN<1>")
	)
	(segment
		(start 68.862702 -219.552774)
		(end 68.756022 -219.659454)
		(width 0.16002)
		(layer "In4.Cu")
		(net "M_D_CPU1_SA_DQS_DN<1>")
	)
	(segment
		(start 64.635126 -215.538558)
		(end 64.635126 -216.065862)
		(width 0.16002)
		(layer "In4.Cu")
		(net "M_D_CPU1_SA_DQS_DN<1>")
	)
	(segment
		(start 64.741806 -215.431878)
		(end 64.635126 -215.538558)
		(width 0.16002)
		(layer "In4.Cu")
		(net "M_D_CPU1_SA_DQS_DN<1>")
	)
	(segment
		(start 64.635126 -216.065862)
		(end 65.007998 -216.438734)
		(width 0.16002)
		(layer "In4.Cu")
		(net "M_D_CPU1_SA_DQS_DN<1>")
	)
	(segment
		(start 38.36416 -210.661504)
		(end 39.224712 -210.661504)
		(width 0.16002)
		(layer "In4.Cu")
		(net "M_D_CPU1_SA_DQS_DN<1>")
	)
	(segment
		(start 48.511714 -210.512406)
		(end 48.856392 -210.857084)
		(width 0.16002)
		(layer "In4.Cu")
		(net "M_D_CPU1_SA_DQS_DN<1>")
	)
	(segment
		(start 71.02983 -221.933262)
		(end 71.13651 -221.826582)
		(width 0.16002)
		(layer "In4.Cu")
		(net "M_D_CPU1_SA_DQS_DN<1>")
	)
	(segment
		(start 70.236334 -220.649546)
		(end 70.236334 -220.926406)
		(width 0.16002)
		(layer "In4.Cu")
		(net "M_D_CPU1_SA_DQS_DN<1>")
	)
	(segment
		(start 54.985666 -211.271104)
		(end 59.840368 -211.271104)
		(width 0.16002)
		(layer "In4.Cu")
		(net "M_D_CPU1_SA_DQS_DN<1>")
	)
	(segment
		(start 64.54521 -214.958422)
		(end 64.741806 -215.155018)
		(width 0.16002)
		(layer "In4.Cu")
		(net "M_D_CPU1_SA_DQS_DN<1>")
	)
	(segment
		(start 78.535276 -230.333296)
		(end 78.76794 -230.56596)
		(width 0.09525)
		(layer "In4.Cu")
		(net "M_D_CPU1_SA_DQS_DN<1>")
	)
	(segment
		(start 71.609966 -222.023178)
		(end 71.609966 -222.300038)
		(width 0.16002)
		(layer "In4.Cu")
		(net "M_D_CPU1_SA_DQS_DN<1>")
	)
	(segment
		(start 37.069776 -210.661504)
		(end 37.65042 -210.661504)
		(width 0.16002)
		(layer "In4.Cu")
		(net "M_D_CPU1_SA_DQS_DN<1>")
	)
	(segment
		(start 66.008758 -217.439494)
		(end 66.38163 -217.812366)
		(width 0.16002)
		(layer "In4.Cu")
		(net "M_D_CPU1_SA_DQS_DN<1>")
	)
	(segment
		(start 65.007998 -216.438734)
		(end 65.535302 -216.438734)
		(width 0.16002)
		(layer "In4.Cu")
		(net "M_D_CPU1_SA_DQS_DN<1>")
	)
	(segment
		(start 88.931242 -232.004362)
		(end 88.939624 -232.009188)
		(width 0.09525)
		(layer "In4.Cu")
		(net "M_D_CPU1_SA_DQS_DN<1>")
	)
	(segment
		(start 76.320904 -229.171246)
		(end 76.783184 -229.633526)
		(width 0.09525)
		(layer "In4.Cu")
		(net "M_D_CPU1_SA_DQS_DN<1>")
	)
	(segment
		(start 73.37425 -224.804986)
		(end 73.37425 -226.308412)
		(width 0.16002)
		(layer "In4.Cu")
		(net "M_D_CPU1_SA_DQS_DN<1>")
	)
	(segment
		(start 76.783184 -229.633526)
		(end 77.38237 -229.633526)
		(width 0.09525)
		(layer "In4.Cu")
		(net "M_D_CPU1_SA_DQS_DN<1>")
	)
	(segment
		(start 45.934376 -210.512406)
		(end 46.46676 -210.512406)
		(width 0.16002)
		(layer "In4.Cu")
		(net "M_D_CPU1_SA_DQS_DN<1>")
	)
	(segment
		(start 66.115438 -216.52865)
		(end 66.115438 -216.80551)
		(width 0.16002)
		(layer "In4.Cu")
		(net "M_D_CPU1_SA_DQS_DN<1>")
	)
	(segment
		(start 73.37425 -226.308412)
		(end 76.22032 -229.154482)
		(width 0.16002)
		(layer "In4.Cu")
		(net "M_D_CPU1_SA_DQS_DN<1>")
	)
	(segment
		(start 69.128894 -220.55963)
		(end 69.656198 -220.55963)
		(width 0.16002)
		(layer "In4.Cu")
		(net "M_D_CPU1_SA_DQS_DN<1>")
	)
	(segment
		(start 51.14544 -209.662522)
		(end 52.634896 -209.662522)
		(width 0.16002)
		(layer "In4.Cu")
		(net "M_D_CPU1_SA_DQS_DN<1>")
	)
	(segment
		(start 76.237084 -229.171246)
		(end 76.320904 -229.171246)
		(width 0.09525)
		(layer "In4.Cu")
		(net "M_D_CPU1_SA_DQS_DN<1>")
	)
	(segment
		(start 37.65042 -210.661504)
		(end 37.76726 -210.778344)
		(width 0.16002)
		(layer "In4.Cu")
		(net "M_D_CPU1_SA_DQS_DN<1>")
	)
	(segment
		(start 78.76794 -230.56596)
		(end 78.76794 -231.264206)
		(width 0.09525)
		(layer "In4.Cu")
		(net "M_D_CPU1_SA_DQS_DN<1>")
	)
	(segment
		(start 63.261494 -214.69223)
		(end 63.634366 -215.065102)
		(width 0.16002)
		(layer "In4.Cu")
		(net "M_D_CPU1_SA_DQS_DN<1>")
	)
	(segment
		(start 90.784934 -232.068878)
		(end 90.63101 -232.334308)
		(width 0.09525)
		(layer "In4.Cu")
		(net "M_D_CPU1_SA_DQS_DN<1>")
	)
	(segment
		(start 68.666106 -219.079318)
		(end 68.862702 -219.275914)
		(width 0.16002)
		(layer "In4.Cu")
		(net "M_D_CPU1_SA_DQS_DN<1>")
	)
	(segment
		(start 84.802472 -232.009188)
		(end 84.810854 -232.004362)
		(width 0.09525)
		(layer "In4.Cu")
		(net "M_D_CPU1_SA_DQS_DN<1>")
	)
	(segment
		(start 36.795964 -210.935316)
		(end 37.069776 -210.661504)
		(width 0.16002)
		(layer "In4.Cu")
		(net "M_D_CPU1_SA_DQS_DN<1>")
	)
	(segment
		(start 47.1805 -210.512406)
		(end 48.511714 -210.512406)
		(width 0.16002)
		(layer "In4.Cu")
		(net "M_D_CPU1_SA_DQS_DN<1>")
	)
	(segment
		(start 85.742526 -232.009188)
		(end 85.750908 -232.004362)
		(width 0.09525)
		(layer "In4.Cu")
		(net "M_D_CPU1_SA_DQS_DN<1>")
	)
	(segment
		(start 65.918842 -216.332054)
		(end 66.115438 -216.52865)
		(width 0.16002)
		(layer "In4.Cu")
		(net "M_D_CPU1_SA_DQS_DN<1>")
	)
	(segment
		(start 87.991188 -232.004362)
		(end 87.99957 -232.009188)
		(width 0.09525)
		(layer "In4.Cu")
		(net "M_D_CPU1_SA_DQS_DN<1>")
	)
	(segment
		(start 42.792904 -210.026504)
		(end 43.237658 -210.026504)
		(width 0.16002)
		(layer "In4.Cu")
		(net "M_D_CPU1_SA_DQS_DN<1>")
	)
	(segment
		(start 39.224712 -210.661504)
		(end 39.37381 -210.512406)
		(width 0.16002)
		(layer "In4.Cu")
		(net "M_D_CPU1_SA_DQS_DN<1>")
	)
	(segment
		(start 65.535302 -216.438734)
		(end 65.641982 -216.332054)
		(width 0.16002)
		(layer "In4.Cu")
		(net "M_D_CPU1_SA_DQS_DN<1>")
	)
	(segment
		(start 77.38237 -229.633526)
		(end 78.08214 -230.333296)
		(width 0.09525)
		(layer "In4.Cu")
		(net "M_D_CPU1_SA_DQS_DN<1>")
	)
	(segment
		(start 71.41337 -221.826582)
		(end 71.609966 -222.023178)
		(width 0.16002)
		(layer "In4.Cu")
		(net "M_D_CPU1_SA_DQS_DN<1>")
	)
	(segment
		(start 76.22032 -229.154482)
		(end 76.237084 -229.171246)
		(width 0.09525)
		(layer "In4.Cu")
		(net "M_D_CPU1_SA_DQS_DN<1>")
	)
	(segment
		(start 69.656198 -220.55963)
		(end 69.762878 -220.45295)
		(width 0.16002)
		(layer "In4.Cu")
		(net "M_D_CPU1_SA_DQS_DN<1>")
	)
	(segment
		(start 48.856392 -210.857084)
		(end 49.534572 -210.857084)
		(width 0.16002)
		(layer "In4.Cu")
		(net "M_D_CPU1_SA_DQS_DN<1>")
	)
	(segment
		(start 68.756022 -220.186758)
		(end 69.128894 -220.55963)
		(width 0.16002)
		(layer "In4.Cu")
		(net "M_D_CPU1_SA_DQS_DN<1>")
	)
	(segment
		(start 40.967914 -210.512406)
		(end 41.312592 -210.857084)
		(width 0.16002)
		(layer "In4.Cu")
		(net "M_D_CPU1_SA_DQS_DN<1>")
	)
	(segment
		(start 66.008758 -216.91219)
		(end 66.008758 -217.439494)
		(width 0.16002)
		(layer "In4.Cu")
		(net "M_D_CPU1_SA_DQS_DN<1>")
	)
	(segment
		(start 67.38239 -218.813126)
		(end 67.755262 -219.185998)
		(width 0.16002)
		(layer "In4.Cu")
		(net "M_D_CPU1_SA_DQS_DN<1>")
	)
	(segment
		(start 50.365152 -210.026504)
		(end 50.781458 -210.026504)
		(width 0.16002)
		(layer "In4.Cu")
		(net "M_D_CPU1_SA_DQS_DN<1>")
	)
	(segment
		(start 89.502488 -232.009188)
		(end 89.51087 -232.004362)
		(width 0.09525)
		(layer "In4.Cu")
		(net "M_D_CPU1_SA_DQS_DN<1>")
	)
	(segment
		(start 54.360826 -210.646264)
		(end 54.985666 -211.271104)
		(width 0.16002)
		(layer "In4.Cu")
		(net "M_D_CPU1_SA_DQS_DN<1>")
	)
	(segment
		(start 64.741806 -215.155018)
		(end 64.741806 -215.431878)
		(width 0.16002)
		(layer "In4.Cu")
		(net "M_D_CPU1_SA_DQS_DN<1>")
	)
	(segment
		(start 66.115438 -216.80551)
		(end 66.008758 -216.91219)
		(width 0.16002)
		(layer "In4.Cu")
		(net "M_D_CPU1_SA_DQS_DN<1>")
	)
	(segment
		(start 69.762878 -220.45295)
		(end 70.039738 -220.45295)
		(width 0.16002)
		(layer "In4.Cu")
		(net "M_D_CPU1_SA_DQS_DN<1>")
	)
	(segment
		(start 83.291172 -232.004362)
		(end 83.299554 -232.009188)
		(width 0.09525)
		(layer "In4.Cu")
		(net "M_D_CPU1_SA_DQS_DN<1>")
	)
	(segment
		(start 71.13651 -221.826582)
		(end 71.41337 -221.826582)
		(width 0.16002)
		(layer "In4.Cu")
		(net "M_D_CPU1_SA_DQS_DN<1>")
	)
	(segment
		(start 46.5836 -210.629246)
		(end 47.06366 -210.629246)
		(width 0.16002)
		(layer "In4.Cu")
		(net "M_D_CPU1_SA_DQS_DN<1>")
	)
	(segment
		(start 71.503286 -222.406718)
		(end 71.503286 -222.934022)
		(width 0.16002)
		(layer "In4.Cu")
		(net "M_D_CPU1_SA_DQS_DN<1>")
	)
	(segment
		(start 49.534572 -210.857084)
		(end 50.365152 -210.026504)
		(width 0.16002)
		(layer "In4.Cu")
		(net "M_D_CPU1_SA_DQS_DN<1>")
	)
	(segment
		(start 66.908934 -217.812366)
		(end 67.015614 -217.705686)
		(width 0.16002)
		(layer "In4.Cu")
		(net "M_D_CPU1_SA_DQS_DN<1>")
	)
	(segment
		(start 67.38239 -218.285822)
		(end 67.38239 -218.813126)
		(width 0.16002)
		(layer "In4.Cu")
		(net "M_D_CPU1_SA_DQS_DN<1>")
	)
	(segment
		(start 67.292474 -217.705686)
		(end 67.48907 -217.902282)
		(width 0.16002)
		(layer "In4.Cu")
		(net "M_D_CPU1_SA_DQS_DN<1>")
	)
	(segment
		(start 46.46676 -210.512406)
		(end 46.5836 -210.629246)
		(width 0.16002)
		(layer "In4.Cu")
		(net "M_D_CPU1_SA_DQS_DN<1>")
	)
	(segment
		(start 43.237658 -210.026504)
		(end 43.60164 -209.662522)
		(width 0.16002)
		(layer "In4.Cu")
		(net "M_D_CPU1_SA_DQS_DN<1>")
	)
	(segment
		(start 63.634366 -215.065102)
		(end 64.16167 -215.065102)
		(width 0.16002)
		(layer "In4.Cu")
		(net "M_D_CPU1_SA_DQS_DN<1>")
	)
	(segment
		(start 67.015614 -217.705686)
		(end 67.292474 -217.705686)
		(width 0.16002)
		(layer "In4.Cu")
		(net "M_D_CPU1_SA_DQS_DN<1>")
	)
	(segment
		(start 43.60164 -209.662522)
		(end 45.084492 -209.662522)
		(width 0.16002)
		(layer "In4.Cu")
		(net "M_D_CPU1_SA_DQS_DN<1>")
	)
	(segment
		(start 47.06366 -210.629246)
		(end 47.1805 -210.512406)
		(width 0.16002)
		(layer "In4.Cu")
		(net "M_D_CPU1_SA_DQS_DN<1>")
	)
	(segment
		(start 64.16167 -215.065102)
		(end 64.26835 -214.958422)
		(width 0.16002)
		(layer "In4.Cu")
		(net "M_D_CPU1_SA_DQS_DN<1>")
	)
	(segment
		(start 59.840368 -211.271104)
		(end 62.260734 -213.69147)
		(width 0.16002)
		(layer "In4.Cu")
		(net "M_D_CPU1_SA_DQS_DN<1>")
	)
	(segment
		(start 70.129654 -221.033086)
		(end 70.129654 -221.56039)
		(width 0.16002)
		(layer "In4.Cu")
		(net "M_D_CPU1_SA_DQS_DN<1>")
	)
	(segment
		(start 62.894718 -213.58479)
		(end 63.171578 -213.58479)
		(width 0.16002)
		(layer "In4.Cu")
		(net "M_D_CPU1_SA_DQS_DN<1>")
	)
	(segment
		(start 68.756022 -219.659454)
		(end 68.756022 -220.186758)
		(width 0.16002)
		(layer "In4.Cu")
		(net "M_D_CPU1_SA_DQS_DN<1>")
	)
	(segment
		(start 65.641982 -216.332054)
		(end 65.918842 -216.332054)
		(width 0.16002)
		(layer "In4.Cu")
		(net "M_D_CPU1_SA_DQS_DN<1>")
	)
	(segment
		(start 62.788038 -213.69147)
		(end 62.894718 -213.58479)
		(width 0.16002)
		(layer "In4.Cu")
		(net "M_D_CPU1_SA_DQS_DN<1>")
	)
	(segment
		(start 63.368174 -213.781386)
		(end 63.368174 -214.058246)
		(width 0.16002)
		(layer "In4.Cu")
		(net "M_D_CPU1_SA_DQS_DN<1>")
	)
	(segment
		(start 63.261494 -214.164926)
		(end 63.261494 -214.69223)
		(width 0.16002)
		(layer "In4.Cu")
		(net "M_D_CPU1_SA_DQS_DN<1>")
	)
	(segment
		(start 80.471264 -232.004362)
		(end 80.479646 -232.009188)
		(width 0.09525)
		(layer "In4.Cu")
		(net "M_D_CPU1_SA_DQS_DN<1>")
	)
	(segment
		(start 68.862702 -219.275914)
		(end 68.862702 -219.552774)
		(width 0.16002)
		(layer "In4.Cu")
		(net "M_D_CPU1_SA_DQS_DN<1>")
	)
	(segment
		(start 63.171578 -213.58479)
		(end 63.368174 -213.781386)
		(width 0.16002)
		(layer "In4.Cu")
		(net "M_D_CPU1_SA_DQS_DN<1>")
	)
	(segment
		(start 53.618638 -210.646264)
		(end 54.360826 -210.646264)
		(width 0.16002)
		(layer "In4.Cu")
		(net "M_D_CPU1_SA_DQS_DN<1>")
	)
	(segment
		(start 39.37381 -210.512406)
		(end 40.967914 -210.512406)
		(width 0.16002)
		(layer "In4.Cu")
		(net "M_D_CPU1_SA_DQS_DN<1>")
	)
	(segment
		(start 84.231226 -232.004362)
		(end 84.239608 -232.009188)
		(width 0.09525)
		(layer "In4.Cu")
		(net "M_D_CPU1_SA_DQS_DN<1>")
	)
	(segment
		(start 67.755262 -219.185998)
		(end 68.282566 -219.185998)
		(width 0.16002)
		(layer "In4.Cu")
		(net "M_D_CPU1_SA_DQS_DN<1>")
	)
	(segment
		(start 71.503286 -222.934022)
		(end 73.37425 -224.804986)
		(width 0.16002)
		(layer "In4.Cu")
		(net "M_D_CPU1_SA_DQS_DN<1>")
	)
	(segment
		(start 38.24732 -210.778344)
		(end 38.36416 -210.661504)
		(width 0.16002)
		(layer "In4.Cu")
		(net "M_D_CPU1_SA_DQS_DN<1>")
	)
	(segment
		(start 71.609966 -222.300038)
		(end 71.503286 -222.406718)
		(width 0.16002)
		(layer "In4.Cu")
		(net "M_D_CPU1_SA_DQS_DN<1>")
	)
	(segment
		(start 70.129654 -221.56039)
		(end 70.502526 -221.933262)
		(width 0.16002)
		(layer "In4.Cu")
		(net "M_D_CPU1_SA_DQS_DN<1>")
	)
	(segment
		(start 37.76726 -210.778344)
		(end 38.24732 -210.778344)
		(width 0.16002)
		(layer "In4.Cu")
		(net "M_D_CPU1_SA_DQS_DN<1>")
	)
	(segment
		(start 67.48907 -217.902282)
		(end 67.48907 -218.179142)
		(width 0.16002)
		(layer "In4.Cu")
		(net "M_D_CPU1_SA_DQS_DN<1>")
	)
	(segment
		(start 62.260734 -213.69147)
		(end 62.788038 -213.69147)
		(width 0.16002)
		(layer "In4.Cu")
		(net "M_D_CPU1_SA_DQS_DN<1>")
	)
	(segment
		(start 45.084492 -209.662522)
		(end 45.934376 -210.512406)
		(width 0.16002)
		(layer "In4.Cu")
		(net "M_D_CPU1_SA_DQS_DN<1>")
	)
	(segment
		(start 90.76182 -231.982264)
		(end 90.784934 -232.068878)
		(width 0.09525)
		(layer "In4.Cu")
		(net "M_D_CPU1_SA_DQS_DN<1>")
	)
	(segment
		(start 70.502526 -221.933262)
		(end 71.02983 -221.933262)
		(width 0.16002)
		(layer "In4.Cu")
		(net "M_D_CPU1_SA_DQS_DN<1>")
	)
	(segment
		(start 78.76794 -231.264206)
		(end 79.42453 -231.920796)
		(width 0.09525)
		(layer "In4.Cu")
		(net "M_D_CPU1_SA_DQS_DN<1>")
	)
	(segment
		(start 50.781458 -210.026504)
		(end 51.14544 -209.662522)
		(width 0.16002)
		(layer "In4.Cu")
		(net "M_D_CPU1_SA_DQS_DN<1>")
	)
	(segment
		(start 68.282566 -219.185998)
		(end 68.389246 -219.079318)
		(width 0.16002)
		(layer "In4.Cu")
		(net "M_D_CPU1_SA_DQS_DN<1>")
	)
	(segment
		(start 64.26835 -214.958422)
		(end 64.54521 -214.958422)
		(width 0.16002)
		(layer "In4.Cu")
		(net "M_D_CPU1_SA_DQS_DN<1>")
	)
	(segment
		(start 41.312592 -210.857084)
		(end 41.962324 -210.857084)
		(width 0.16002)
		(layer "In4.Cu")
		(net "M_D_CPU1_SA_DQS_DN<1>")
	)
	(segment
		(start 63.368174 -214.058246)
		(end 63.261494 -214.164926)
		(width 0.16002)
		(layer "In4.Cu")
		(net "M_D_CPU1_SA_DQS_DN<1>")
	)
	(segment
		(start 78.08214 -230.333296)
		(end 78.535276 -230.333296)
		(width 0.09525)
		(layer "In4.Cu")
		(net "M_D_CPU1_SA_DQS_DN<1>")
	)
	(arc
		(start 84.810854 -232.004362)
		(mid 84.995886 -231.958448)
		(end 85.179662 -232.009188)
		(width 0.09525)
		(layer "In4.Cu")
		(net "M_D_CPU1_SA_DQS_DN<1>")
	)
	(arc
		(start 89.51087 -232.004362)
		(mid 89.695902 -231.958448)
		(end 89.879678 -232.009188)
		(width 0.09525)
		(layer "In4.Cu")
		(net "M_D_CPU1_SA_DQS_DN<1>")
	)
	(arc
		(start 85.179662 -232.009188)
		(mid 85.461094 -232.084943)
		(end 85.742526 -232.009188)
		(width 0.09525)
		(layer "In4.Cu")
		(net "M_D_CPU1_SA_DQS_DN<1>")
	)
	(arc
		(start 81.050892 -232.004362)
		(mid 81.235924 -231.958448)
		(end 81.4197 -232.009188)
		(width 0.09525)
		(layer "In4.Cu")
		(net "M_D_CPU1_SA_DQS_DN<1>")
	)
	(arc
		(start 87.99957 -232.009188)
		(mid 88.281002 -232.084943)
		(end 88.562434 -232.009188)
		(width 0.09525)
		(layer "In4.Cu")
		(net "M_D_CPU1_SA_DQS_DN<1>")
	)
	(arc
		(start 83.299554 -232.009188)
		(mid 83.580986 -232.084943)
		(end 83.862418 -232.009188)
		(width 0.09525)
		(layer "In4.Cu")
		(net "M_D_CPU1_SA_DQS_DN<1>")
	)
	(arc
		(start 79.42453 -231.920796)
		(mid 79.479192 -231.968727)
		(end 79.539592 -232.009188)
		(width 0.09525)
		(layer "In4.Cu")
		(net "M_D_CPU1_SA_DQS_DN<1>")
	)
	(arc
		(start 87.059516 -232.009188)
		(mid 87.340948 -232.084943)
		(end 87.62238 -232.009188)
		(width 0.09525)
		(layer "In4.Cu")
		(net "M_D_CPU1_SA_DQS_DN<1>")
	)
	(arc
		(start 88.939624 -232.009188)
		(mid 89.221056 -232.084943)
		(end 89.502488 -232.009188)
		(width 0.09525)
		(layer "In4.Cu")
		(net "M_D_CPU1_SA_DQS_DN<1>")
	)
	(arc
		(start 86.119716 -232.009188)
		(mid 86.401148 -232.084943)
		(end 86.68258 -232.009188)
		(width 0.09525)
		(layer "In4.Cu")
		(net "M_D_CPU1_SA_DQS_DN<1>")
	)
	(arc
		(start 83.862418 -232.009188)
		(mid 84.046193 -231.958416)
		(end 84.231226 -232.004362)
		(width 0.09525)
		(layer "In4.Cu")
		(net "M_D_CPU1_SA_DQS_DN<1>")
	)
	(arc
		(start 90.442542 -232.009188)
		(mid 90.599169 -231.960002)
		(end 90.76182 -231.982264)
		(width 0.09525)
		(layer "In4.Cu")
		(net "M_D_CPU1_SA_DQS_DN<1>")
	)
	(arc
		(start 85.750908 -232.004362)
		(mid 85.93594 -231.958448)
		(end 86.119716 -232.009188)
		(width 0.09525)
		(layer "In4.Cu")
		(net "M_D_CPU1_SA_DQS_DN<1>")
	)
	(arc
		(start 87.62238 -232.009188)
		(mid 87.806155 -231.958416)
		(end 87.991188 -232.004362)
		(width 0.09525)
		(layer "In4.Cu")
		(net "M_D_CPU1_SA_DQS_DN<1>")
	)
	(arc
		(start 89.879678 -232.009188)
		(mid 90.16111 -232.084943)
		(end 90.442542 -232.009188)
		(width 0.09525)
		(layer "In4.Cu")
		(net "M_D_CPU1_SA_DQS_DN<1>")
	)
	(arc
		(start 88.562434 -232.009188)
		(mid 88.746209 -231.958416)
		(end 88.931242 -232.004362)
		(width 0.09525)
		(layer "In4.Cu")
		(net "M_D_CPU1_SA_DQS_DN<1>")
	)
	(arc
		(start 82.922364 -232.009188)
		(mid 83.106139 -231.958416)
		(end 83.291172 -232.004362)
		(width 0.09525)
		(layer "In4.Cu")
		(net "M_D_CPU1_SA_DQS_DN<1>")
	)
	(arc
		(start 86.68258 -232.009188)
		(mid 86.871048 -231.958511)
		(end 87.059516 -232.009188)
		(width 0.09525)
		(layer "In4.Cu")
		(net "M_D_CPU1_SA_DQS_DN<1>")
	)
	(arc
		(start 82.3595 -232.009188)
		(mid 82.640932 -232.084943)
		(end 82.922364 -232.009188)
		(width 0.09525)
		(layer "In4.Cu")
		(net "M_D_CPU1_SA_DQS_DN<1>")
	)
	(arc
		(start 81.4197 -232.009188)
		(mid 81.701132 -232.084943)
		(end 81.982564 -232.009188)
		(width 0.09525)
		(layer "In4.Cu")
		(net "M_D_CPU1_SA_DQS_DN<1>")
	)
	(arc
		(start 80.102456 -232.009188)
		(mid 80.286231 -231.958416)
		(end 80.471264 -232.004362)
		(width 0.09525)
		(layer "In4.Cu")
		(net "M_D_CPU1_SA_DQS_DN<1>")
	)
	(arc
		(start 79.539592 -232.009188)
		(mid 79.821024 -232.084943)
		(end 80.102456 -232.009188)
		(width 0.09525)
		(layer "In4.Cu")
		(net "M_D_CPU1_SA_DQS_DN<1>")
	)
	(arc
		(start 81.982564 -232.009188)
		(mid 82.171032 -231.958511)
		(end 82.3595 -232.009188)
		(width 0.09525)
		(layer "In4.Cu")
		(net "M_D_CPU1_SA_DQS_DN<1>")
	)
	(arc
		(start 84.239608 -232.009188)
		(mid 84.52104 -232.084943)
		(end 84.802472 -232.009188)
		(width 0.09525)
		(layer "In4.Cu")
		(net "M_D_CPU1_SA_DQS_DN<1>")
	)
	(arc
		(start 80.479646 -232.009188)
		(mid 80.761078 -232.084943)
		(end 81.04251 -232.009188)
		(width 0.09525)
		(layer "In4.Cu")
		(net "M_D_CPU1_SA_DQS_DN<1>")
	)
	(segment
		(start 91.097862 -227.740464)
		(end 90.63101 -227.474526)
		(width 0.12954)
		(layer "F.Cu")
		(net "M_D_CPU1_SA_DQS_DN<0>")
	)
	(segment
		(start 68.725034 -210.68157)
		(end 69.1261 -211.082636)
		(width 0.16002)
		(layer "In4.Cu")
		(net "M_D_CPU1_SA_DQS_DN<0>")
	)
	(segment
		(start 83.291172 -227.14458)
		(end 83.299554 -227.149406)
		(width 0.09525)
		(layer "In4.Cu")
		(net "M_D_CPU1_SA_DQS_DN<0>")
	)
	(segment
		(start 80.914494 -224.698814)
		(end 80.916526 -224.700084)
		(width 0.09525)
		(layer "In4.Cu")
		(net "M_D_CPU1_SA_DQS_DN<0>")
	)
	(segment
		(start 81.4197 -225.529394)
		(end 81.451196 -225.547682)
		(width 0.09525)
		(layer "In4.Cu")
		(net "M_D_CPU1_SA_DQS_DN<0>")
	)
	(segment
		(start 43.608752 -200.311766)
		(end 45.027088 -200.311766)
		(width 0.16002)
		(layer "In4.Cu")
		(net "M_D_CPU1_SA_DQS_DN<0>")
	)
	(segment
		(start 84.231226 -227.14458)
		(end 84.239608 -227.149406)
		(width 0.09525)
		(layer "In4.Cu")
		(net "M_D_CPU1_SA_DQS_DN<0>")
	)
	(segment
		(start 39.197788 -201.31151)
		(end 39.346886 -201.162412)
		(width 0.16002)
		(layer "In4.Cu")
		(net "M_D_CPU1_SA_DQS_DN<0>")
	)
	(segment
		(start 75.593194 -216.80043)
		(end 75.593194 -217.54973)
		(width 0.16002)
		(layer "In4.Cu")
		(net "M_D_CPU1_SA_DQS_DN<0>")
	)
	(segment
		(start 65.754504 -206.96174)
		(end 65.97777 -207.185006)
		(width 0.16002)
		(layer "In4.Cu")
		(net "M_D_CPU1_SA_DQS_DN<0>")
	)
	(segment
		(start 80.444594 -223.888808)
		(end 80.446626 -223.890078)
		(width 0.09525)
		(layer "In4.Cu")
		(net "M_D_CPU1_SA_DQS_DN<0>")
	)
	(segment
		(start 69.8754 -211.082636)
		(end 70.098666 -211.305902)
		(width 0.16002)
		(layer "In4.Cu")
		(net "M_D_CPU1_SA_DQS_DN<0>")
	)
	(segment
		(start 79.500476 -222.26651)
		(end 79.539846 -222.28937)
		(width 0.09525)
		(layer "In4.Cu")
		(net "M_D_CPU1_SA_DQS_DN<0>")
	)
	(segment
		(start 41.957752 -201.505566)
		(end 42.798492 -200.664826)
		(width 0.16002)
		(layer "In4.Cu")
		(net "M_D_CPU1_SA_DQS_DN<0>")
	)
	(segment
		(start 38.120828 -201.42835)
		(end 38.600888 -201.42835)
		(width 0.16002)
		(layer "In4.Cu")
		(net "M_D_CPU1_SA_DQS_DN<0>")
	)
	(segment
		(start 72.622664 -213.8299)
		(end 72.84593 -214.053166)
		(width 0.16002)
		(layer "In4.Cu")
		(net "M_D_CPU1_SA_DQS_DN<0>")
	)
	(segment
		(start 74.620628 -216.577164)
		(end 75.369928 -216.577164)
		(width 0.16002)
		(layer "In4.Cu")
		(net "M_D_CPU1_SA_DQS_DN<0>")
	)
	(segment
		(start 67.752468 -209.709004)
		(end 68.501768 -209.709004)
		(width 0.16002)
		(layer "In4.Cu")
		(net "M_D_CPU1_SA_DQS_DN<0>")
	)
	(segment
		(start 67.351402 -208.558638)
		(end 67.351402 -209.307938)
		(width 0.16002)
		(layer "In4.Cu")
		(net "M_D_CPU1_SA_DQS_DN<0>")
	)
	(segment
		(start 50.812192 -200.659746)
		(end 51.15941 -200.312528)
		(width 0.16002)
		(layer "In4.Cu")
		(net "M_D_CPU1_SA_DQS_DN<0>")
	)
	(segment
		(start 90.76182 -227.122482)
		(end 90.784934 -227.209096)
		(width 0.09525)
		(layer "In4.Cu")
		(net "M_D_CPU1_SA_DQS_DN<0>")
	)
	(segment
		(start 48.481234 -201.162412)
		(end 48.814228 -201.495406)
		(width 0.16002)
		(layer "In4.Cu")
		(net "M_D_CPU1_SA_DQS_DN<0>")
	)
	(segment
		(start 79.539846 -222.28937)
		(end 79.572358 -222.308166)
		(width 0.09525)
		(layer "In4.Cu")
		(net "M_D_CPU1_SA_DQS_DN<0>")
	)
	(segment
		(start 51.15941 -200.312528)
		(end 52.65674 -200.312528)
		(width 0.16002)
		(layer "In4.Cu")
		(net "M_D_CPU1_SA_DQS_DN<0>")
	)
	(segment
		(start 72.84593 -214.802466)
		(end 73.246996 -215.203532)
		(width 0.16002)
		(layer "In4.Cu")
		(net "M_D_CPU1_SA_DQS_DN<0>")
	)
	(segment
		(start 63.631572 -205.588108)
		(end 64.380872 -205.588108)
		(width 0.16002)
		(layer "In4.Cu")
		(net "M_D_CPU1_SA_DQS_DN<0>")
	)
	(segment
		(start 75.369928 -216.577164)
		(end 75.593194 -216.80043)
		(width 0.16002)
		(layer "In4.Cu")
		(net "M_D_CPU1_SA_DQS_DN<0>")
	)
	(segment
		(start 63.00724 -204.214476)
		(end 63.230506 -204.437742)
		(width 0.16002)
		(layer "In4.Cu")
		(net "M_D_CPU1_SA_DQS_DN<0>")
	)
	(segment
		(start 45.877734 -201.162412)
		(end 46.42612 -201.162412)
		(width 0.16002)
		(layer "In4.Cu")
		(net "M_D_CPU1_SA_DQS_DN<0>")
	)
	(segment
		(start 71.873364 -213.8299)
		(end 72.622664 -213.8299)
		(width 0.16002)
		(layer "In4.Cu")
		(net "M_D_CPU1_SA_DQS_DN<0>")
	)
	(segment
		(start 81.8896 -226.3394)
		(end 81.922112 -226.358196)
		(width 0.09525)
		(layer "In4.Cu")
		(net "M_D_CPU1_SA_DQS_DN<0>")
	)
	(segment
		(start 90.784934 -227.209096)
		(end 90.63101 -227.474526)
		(width 0.09525)
		(layer "In4.Cu")
		(net "M_D_CPU1_SA_DQS_DN<0>")
	)
	(segment
		(start 64.380872 -205.588108)
		(end 64.604138 -205.811374)
		(width 0.16002)
		(layer "In4.Cu")
		(net "M_D_CPU1_SA_DQS_DN<0>")
	)
	(segment
		(start 65.97777 -207.934306)
		(end 66.378836 -208.335372)
		(width 0.16002)
		(layer "In4.Cu")
		(net "M_D_CPU1_SA_DQS_DN<0>")
	)
	(segment
		(start 61.856874 -203.81341)
		(end 62.25794 -204.214476)
		(width 0.16002)
		(layer "In4.Cu")
		(net "M_D_CPU1_SA_DQS_DN<0>")
	)
	(segment
		(start 36.795964 -201.585322)
		(end 37.069776 -201.31151)
		(width 0.16002)
		(layer "In4.Cu")
		(net "M_D_CPU1_SA_DQS_DN<0>")
	)
	(segment
		(start 79.199486 -220.406722)
		(end 79.199486 -221.316804)
		(width 0.16002)
		(layer "In4.Cu")
		(net "M_D_CPU1_SA_DQS_DN<0>")
	)
	(segment
		(start 75.593194 -217.54973)
		(end 75.99426 -217.950796)
		(width 0.16002)
		(layer "In4.Cu")
		(net "M_D_CPU1_SA_DQS_DN<0>")
	)
	(segment
		(start 42.798492 -200.664826)
		(end 43.255692 -200.664826)
		(width 0.16002)
		(layer "In4.Cu")
		(net "M_D_CPU1_SA_DQS_DN<0>")
	)
	(segment
		(start 63.230506 -204.437742)
		(end 63.230506 -205.187042)
		(width 0.16002)
		(layer "In4.Cu")
		(net "M_D_CPU1_SA_DQS_DN<0>")
	)
	(segment
		(start 38.003988 -201.31151)
		(end 38.120828 -201.42835)
		(width 0.16002)
		(layer "In4.Cu")
		(net "M_D_CPU1_SA_DQS_DN<0>")
	)
	(segment
		(start 81.8515 -226.317302)
		(end 81.8896 -226.3394)
		(width 0.09525)
		(layer "In4.Cu")
		(net "M_D_CPU1_SA_DQS_DN<0>")
	)
	(segment
		(start 74.219562 -215.426798)
		(end 74.219562 -216.176098)
		(width 0.16002)
		(layer "In4.Cu")
		(net "M_D_CPU1_SA_DQS_DN<0>")
	)
	(segment
		(start 84.802472 -227.149406)
		(end 84.810854 -227.14458)
		(width 0.09525)
		(layer "In4.Cu")
		(net "M_D_CPU1_SA_DQS_DN<0>")
	)
	(segment
		(start 64.604138 -205.811374)
		(end 64.604138 -206.560674)
		(width 0.16002)
		(layer "In4.Cu")
		(net "M_D_CPU1_SA_DQS_DN<0>")
	)
	(segment
		(start 72.84593 -214.053166)
		(end 72.84593 -214.802466)
		(width 0.16002)
		(layer "In4.Cu")
		(net "M_D_CPU1_SA_DQS_DN<0>")
	)
	(segment
		(start 73.996296 -215.203532)
		(end 74.219562 -215.426798)
		(width 0.16002)
		(layer "In4.Cu")
		(net "M_D_CPU1_SA_DQS_DN<0>")
	)
	(segment
		(start 45.027088 -200.311766)
		(end 45.877734 -201.162412)
		(width 0.16002)
		(layer "In4.Cu")
		(net "M_D_CPU1_SA_DQS_DN<0>")
	)
	(segment
		(start 80.916526 -224.700084)
		(end 80.949546 -224.719388)
		(width 0.09525)
		(layer "In4.Cu")
		(net "M_D_CPU1_SA_DQS_DN<0>")
	)
	(segment
		(start 61.856874 -203.06411)
		(end 61.856874 -203.81341)
		(width 0.16002)
		(layer "In4.Cu")
		(net "M_D_CPU1_SA_DQS_DN<0>")
	)
	(segment
		(start 89.502488 -227.149406)
		(end 89.51087 -227.14458)
		(width 0.09525)
		(layer "In4.Cu")
		(net "M_D_CPU1_SA_DQS_DN<0>")
	)
	(segment
		(start 71.472298 -213.428834)
		(end 71.873364 -213.8299)
		(width 0.16002)
		(layer "In4.Cu")
		(net "M_D_CPU1_SA_DQS_DN<0>")
	)
	(segment
		(start 73.246996 -215.203532)
		(end 73.996296 -215.203532)
		(width 0.16002)
		(layer "In4.Cu")
		(net "M_D_CPU1_SA_DQS_DN<0>")
	)
	(segment
		(start 70.098666 -211.305902)
		(end 70.098666 -212.055202)
		(width 0.16002)
		(layer "In4.Cu")
		(net "M_D_CPU1_SA_DQS_DN<0>")
	)
	(segment
		(start 40.975534 -201.162412)
		(end 41.318688 -201.505566)
		(width 0.16002)
		(layer "In4.Cu")
		(net "M_D_CPU1_SA_DQS_DN<0>")
	)
	(segment
		(start 54.57444 -201.329544)
		(end 55.0545 -201.329544)
		(width 0.16002)
		(layer "In4.Cu")
		(net "M_D_CPU1_SA_DQS_DN<0>")
	)
	(segment
		(start 47.13986 -201.162412)
		(end 48.481234 -201.162412)
		(width 0.16002)
		(layer "In4.Cu")
		(net "M_D_CPU1_SA_DQS_DN<0>")
	)
	(segment
		(start 68.725034 -209.93227)
		(end 68.725034 -210.68157)
		(width 0.16002)
		(layer "In4.Cu")
		(net "M_D_CPU1_SA_DQS_DN<0>")
	)
	(segment
		(start 43.255692 -200.664826)
		(end 43.608752 -200.311766)
		(width 0.16002)
		(layer "In4.Cu")
		(net "M_D_CPU1_SA_DQS_DN<0>")
	)
	(segment
		(start 41.318688 -201.505566)
		(end 41.957752 -201.505566)
		(width 0.16002)
		(layer "In4.Cu")
		(net "M_D_CPU1_SA_DQS_DN<0>")
	)
	(segment
		(start 80.01 -223.099376)
		(end 80.041496 -223.117664)
		(width 0.09525)
		(layer "In4.Cu")
		(net "M_D_CPU1_SA_DQS_DN<0>")
	)
	(segment
		(start 46.54296 -201.279252)
		(end 47.02302 -201.279252)
		(width 0.16002)
		(layer "In4.Cu")
		(net "M_D_CPU1_SA_DQS_DN<0>")
	)
	(segment
		(start 39.346886 -201.162412)
		(end 40.975534 -201.162412)
		(width 0.16002)
		(layer "In4.Cu")
		(net "M_D_CPU1_SA_DQS_DN<0>")
	)
	(segment
		(start 71.249032 -212.456268)
		(end 71.472298 -212.679534)
		(width 0.16002)
		(layer "In4.Cu")
		(net "M_D_CPU1_SA_DQS_DN<0>")
	)
	(segment
		(start 76.966826 -218.923362)
		(end 77.367892 -219.324428)
		(width 0.16002)
		(layer "In4.Cu")
		(net "M_D_CPU1_SA_DQS_DN<0>")
	)
	(segment
		(start 87.991188 -227.14458)
		(end 87.99957 -227.149406)
		(width 0.09525)
		(layer "In4.Cu")
		(net "M_D_CPU1_SA_DQS_DN<0>")
	)
	(segment
		(start 76.74356 -217.950796)
		(end 76.966826 -218.174062)
		(width 0.16002)
		(layer "In4.Cu")
		(net "M_D_CPU1_SA_DQS_DN<0>")
	)
	(segment
		(start 38.717728 -201.31151)
		(end 39.197788 -201.31151)
		(width 0.16002)
		(layer "In4.Cu")
		(net "M_D_CPU1_SA_DQS_DN<0>")
	)
	(segment
		(start 80.949546 -224.719388)
		(end 80.982058 -224.738184)
		(width 0.09525)
		(layer "In4.Cu")
		(net "M_D_CPU1_SA_DQS_DN<0>")
	)
	(segment
		(start 48.814228 -201.495406)
		(end 49.534572 -201.495406)
		(width 0.16002)
		(layer "In4.Cu")
		(net "M_D_CPU1_SA_DQS_DN<0>")
	)
	(segment
		(start 78.117192 -219.324428)
		(end 79.199486 -220.406722)
		(width 0.16002)
		(layer "In4.Cu")
		(net "M_D_CPU1_SA_DQS_DN<0>")
	)
	(segment
		(start 47.02302 -201.279252)
		(end 47.13986 -201.162412)
		(width 0.16002)
		(layer "In4.Cu")
		(net "M_D_CPU1_SA_DQS_DN<0>")
	)
	(segment
		(start 46.42612 -201.162412)
		(end 46.54296 -201.279252)
		(width 0.16002)
		(layer "In4.Cu")
		(net "M_D_CPU1_SA_DQS_DN<0>")
	)
	(segment
		(start 55.17134 -201.212704)
		(end 56.106314 -201.212704)
		(width 0.16002)
		(layer "In4.Cu")
		(net "M_D_CPU1_SA_DQS_DN<0>")
	)
	(segment
		(start 74.219562 -216.176098)
		(end 74.620628 -216.577164)
		(width 0.16002)
		(layer "In4.Cu")
		(net "M_D_CPU1_SA_DQS_DN<0>")
	)
	(segment
		(start 37.069776 -201.31151)
		(end 38.003988 -201.31151)
		(width 0.16002)
		(layer "In4.Cu")
		(net "M_D_CPU1_SA_DQS_DN<0>")
	)
	(segment
		(start 64.604138 -206.560674)
		(end 65.005204 -206.96174)
		(width 0.16002)
		(layer "In4.Cu")
		(net "M_D_CPU1_SA_DQS_DN<0>")
	)
	(segment
		(start 63.230506 -205.187042)
		(end 63.631572 -205.588108)
		(width 0.16002)
		(layer "In4.Cu")
		(net "M_D_CPU1_SA_DQS_DN<0>")
	)
	(segment
		(start 65.005204 -206.96174)
		(end 65.754504 -206.96174)
		(width 0.16002)
		(layer "In4.Cu")
		(net "M_D_CPU1_SA_DQS_DN<0>")
	)
	(segment
		(start 54.4576 -201.212704)
		(end 54.57444 -201.329544)
		(width 0.16002)
		(layer "In4.Cu")
		(net "M_D_CPU1_SA_DQS_DN<0>")
	)
	(segment
		(start 60.72505 -201.932286)
		(end 61.856874 -203.06411)
		(width 0.16002)
		(layer "In4.Cu")
		(net "M_D_CPU1_SA_DQS_DN<0>")
	)
	(segment
		(start 55.0545 -201.329544)
		(end 55.17134 -201.212704)
		(width 0.16002)
		(layer "In4.Cu")
		(net "M_D_CPU1_SA_DQS_DN<0>")
	)
	(segment
		(start 50.370232 -200.659746)
		(end 50.812192 -200.659746)
		(width 0.16002)
		(layer "In4.Cu")
		(net "M_D_CPU1_SA_DQS_DN<0>")
	)
	(segment
		(start 82.324448 -227.128832)
		(end 82.32648 -227.130102)
		(width 0.09525)
		(layer "In4.Cu")
		(net "M_D_CPU1_SA_DQS_DN<0>")
	)
	(segment
		(start 85.742526 -227.149406)
		(end 85.750908 -227.14458)
		(width 0.09525)
		(layer "In4.Cu")
		(net "M_D_CPU1_SA_DQS_DN<0>")
	)
	(segment
		(start 52.65674 -200.312528)
		(end 53.556916 -201.212704)
		(width 0.16002)
		(layer "In4.Cu")
		(net "M_D_CPU1_SA_DQS_DN<0>")
	)
	(segment
		(start 56.106314 -201.212704)
		(end 56.825896 -201.932286)
		(width 0.16002)
		(layer "In4.Cu")
		(net "M_D_CPU1_SA_DQS_DN<0>")
	)
	(segment
		(start 82.32648 -227.130102)
		(end 82.3595 -227.149406)
		(width 0.09525)
		(layer "In4.Cu")
		(net "M_D_CPU1_SA_DQS_DN<0>")
	)
	(segment
		(start 65.97777 -207.185006)
		(end 65.97777 -207.934306)
		(width 0.16002)
		(layer "In4.Cu")
		(net "M_D_CPU1_SA_DQS_DN<0>")
	)
	(segment
		(start 71.472298 -212.679534)
		(end 71.472298 -213.428834)
		(width 0.16002)
		(layer "In4.Cu")
		(net "M_D_CPU1_SA_DQS_DN<0>")
	)
	(segment
		(start 38.600888 -201.42835)
		(end 38.717728 -201.31151)
		(width 0.16002)
		(layer "In4.Cu")
		(net "M_D_CPU1_SA_DQS_DN<0>")
	)
	(segment
		(start 80.446626 -223.890078)
		(end 80.479646 -223.909382)
		(width 0.09525)
		(layer "In4.Cu")
		(net "M_D_CPU1_SA_DQS_DN<0>")
	)
	(segment
		(start 79.199486 -221.340426)
		(end 79.258668 -221.399608)
		(width 0.09525)
		(layer "In4.Cu")
		(net "M_D_CPU1_SA_DQS_DN<0>")
	)
	(segment
		(start 53.556916 -201.212704)
		(end 54.4576 -201.212704)
		(width 0.16002)
		(layer "In4.Cu")
		(net "M_D_CPU1_SA_DQS_DN<0>")
	)
	(segment
		(start 49.534572 -201.495406)
		(end 50.370232 -200.659746)
		(width 0.16002)
		(layer "In4.Cu")
		(net "M_D_CPU1_SA_DQS_DN<0>")
	)
	(segment
		(start 70.098666 -212.055202)
		(end 70.499732 -212.456268)
		(width 0.16002)
		(layer "In4.Cu")
		(net "M_D_CPU1_SA_DQS_DN<0>")
	)
	(segment
		(start 79.9719 -223.077278)
		(end 80.01 -223.099376)
		(width 0.09525)
		(layer "In4.Cu")
		(net "M_D_CPU1_SA_DQS_DN<0>")
	)
	(segment
		(start 68.501768 -209.709004)
		(end 68.725034 -209.93227)
		(width 0.16002)
		(layer "In4.Cu")
		(net "M_D_CPU1_SA_DQS_DN<0>")
	)
	(segment
		(start 88.931242 -227.14458)
		(end 88.939624 -227.149406)
		(width 0.09525)
		(layer "In4.Cu")
		(net "M_D_CPU1_SA_DQS_DN<0>")
	)
	(segment
		(start 69.1261 -211.082636)
		(end 69.8754 -211.082636)
		(width 0.16002)
		(layer "In4.Cu")
		(net "M_D_CPU1_SA_DQS_DN<0>")
	)
	(segment
		(start 81.3816 -225.507296)
		(end 81.4197 -225.529394)
		(width 0.09525)
		(layer "In4.Cu")
		(net "M_D_CPU1_SA_DQS_DN<0>")
	)
	(segment
		(start 80.479646 -223.909382)
		(end 80.512158 -223.928178)
		(width 0.09525)
		(layer "In4.Cu")
		(net "M_D_CPU1_SA_DQS_DN<0>")
	)
	(segment
		(start 66.378836 -208.335372)
		(end 67.128136 -208.335372)
		(width 0.16002)
		(layer "In4.Cu")
		(net "M_D_CPU1_SA_DQS_DN<0>")
	)
	(segment
		(start 79.199486 -221.316804)
		(end 79.199486 -221.340426)
		(width 0.09525)
		(layer "In4.Cu")
		(net "M_D_CPU1_SA_DQS_DN<0>")
	)
	(segment
		(start 76.966826 -218.174062)
		(end 76.966826 -218.923362)
		(width 0.16002)
		(layer "In4.Cu")
		(net "M_D_CPU1_SA_DQS_DN<0>")
	)
	(segment
		(start 62.25794 -204.214476)
		(end 63.00724 -204.214476)
		(width 0.16002)
		(layer "In4.Cu")
		(net "M_D_CPU1_SA_DQS_DN<0>")
	)
	(segment
		(start 77.367892 -219.324428)
		(end 78.117192 -219.324428)
		(width 0.16002)
		(layer "In4.Cu")
		(net "M_D_CPU1_SA_DQS_DN<0>")
	)
	(segment
		(start 75.99426 -217.950796)
		(end 76.74356 -217.950796)
		(width 0.16002)
		(layer "In4.Cu")
		(net "M_D_CPU1_SA_DQS_DN<0>")
	)
	(segment
		(start 67.128136 -208.335372)
		(end 67.351402 -208.558638)
		(width 0.16002)
		(layer "In4.Cu")
		(net "M_D_CPU1_SA_DQS_DN<0>")
	)
	(segment
		(start 70.499732 -212.456268)
		(end 71.249032 -212.456268)
		(width 0.16002)
		(layer "In4.Cu")
		(net "M_D_CPU1_SA_DQS_DN<0>")
	)
	(segment
		(start 67.351402 -209.307938)
		(end 67.752468 -209.709004)
		(width 0.16002)
		(layer "In4.Cu")
		(net "M_D_CPU1_SA_DQS_DN<0>")
	)
	(segment
		(start 56.825896 -201.932286)
		(end 60.72505 -201.932286)
		(width 0.16002)
		(layer "In4.Cu")
		(net "M_D_CPU1_SA_DQS_DN<0>")
	)
	(segment
		(start 79.258668 -221.399608)
		(end 79.258668 -221.804484)
		(width 0.09525)
		(layer "In4.Cu")
		(net "M_D_CPU1_SA_DQS_DN<0>")
	)
	(arc
		(start 79.729076 -222.61449)
		(mid 79.793473 -222.875796)
		(end 79.9719 -223.077278)
		(width 0.09525)
		(layer "In4.Cu")
		(net "M_D_CPU1_SA_DQS_DN<0>")
	)
	(arc
		(start 87.62238 -227.149406)
		(mid 87.806155 -227.098634)
		(end 87.991188 -227.14458)
		(width 0.09525)
		(layer "In4.Cu")
		(net "M_D_CPU1_SA_DQS_DN<0>")
	)
	(arc
		(start 79.258668 -221.804484)
		(mid 79.32277 -222.065228)
		(end 79.500476 -222.26651)
		(width 0.09525)
		(layer "In4.Cu")
		(net "M_D_CPU1_SA_DQS_DN<0>")
	)
	(arc
		(start 90.442542 -227.149406)
		(mid 90.599169 -227.10022)
		(end 90.76182 -227.122482)
		(width 0.09525)
		(layer "In4.Cu")
		(net "M_D_CPU1_SA_DQS_DN<0>")
	)
	(arc
		(start 85.750908 -227.14458)
		(mid 85.93594 -227.098666)
		(end 86.119716 -227.149406)
		(width 0.09525)
		(layer "In4.Cu")
		(net "M_D_CPU1_SA_DQS_DN<0>")
	)
	(arc
		(start 88.939624 -227.149406)
		(mid 89.221056 -227.225161)
		(end 89.502488 -227.149406)
		(width 0.09525)
		(layer "In4.Cu")
		(net "M_D_CPU1_SA_DQS_DN<0>")
	)
	(arc
		(start 88.562434 -227.149406)
		(mid 88.746209 -227.098634)
		(end 88.931242 -227.14458)
		(width 0.09525)
		(layer "In4.Cu")
		(net "M_D_CPU1_SA_DQS_DN<0>")
	)
	(arc
		(start 80.198976 -223.424496)
		(mid 80.264169 -223.687125)
		(end 80.444594 -223.888808)
		(width 0.09525)
		(layer "In4.Cu")
		(net "M_D_CPU1_SA_DQS_DN<0>")
	)
	(arc
		(start 82.07883 -226.66452)
		(mid 82.144023 -226.927149)
		(end 82.324448 -227.128832)
		(width 0.09525)
		(layer "In4.Cu")
		(net "M_D_CPU1_SA_DQS_DN<0>")
	)
	(arc
		(start 80.041496 -223.117664)
		(mid 80.157294 -223.252058)
		(end 80.198976 -223.424496)
		(width 0.09525)
		(layer "In4.Cu")
		(net "M_D_CPU1_SA_DQS_DN<0>")
	)
	(arc
		(start 87.059516 -227.149406)
		(mid 87.340948 -227.225161)
		(end 87.62238 -227.149406)
		(width 0.09525)
		(layer "In4.Cu")
		(net "M_D_CPU1_SA_DQS_DN<0>")
	)
	(arc
		(start 84.810854 -227.14458)
		(mid 84.995886 -227.098666)
		(end 85.179662 -227.149406)
		(width 0.09525)
		(layer "In4.Cu")
		(net "M_D_CPU1_SA_DQS_DN<0>")
	)
	(arc
		(start 86.68258 -227.149406)
		(mid 86.871048 -227.098729)
		(end 87.059516 -227.149406)
		(width 0.09525)
		(layer "In4.Cu")
		(net "M_D_CPU1_SA_DQS_DN<0>")
	)
	(arc
		(start 84.239608 -227.149406)
		(mid 84.52104 -227.225161)
		(end 84.802472 -227.149406)
		(width 0.09525)
		(layer "In4.Cu")
		(net "M_D_CPU1_SA_DQS_DN<0>")
	)
	(arc
		(start 80.668876 -224.234502)
		(mid 80.734069 -224.497131)
		(end 80.914494 -224.698814)
		(width 0.09525)
		(layer "In4.Cu")
		(net "M_D_CPU1_SA_DQS_DN<0>")
	)
	(arc
		(start 81.451196 -225.547682)
		(mid 81.566994 -225.682076)
		(end 81.608676 -225.854514)
		(width 0.09525)
		(layer "In4.Cu")
		(net "M_D_CPU1_SA_DQS_DN<0>")
	)
	(arc
		(start 79.572358 -222.308166)
		(mid 79.687632 -222.442444)
		(end 79.729076 -222.61449)
		(width 0.09525)
		(layer "In4.Cu")
		(net "M_D_CPU1_SA_DQS_DN<0>")
	)
	(arc
		(start 81.922112 -226.358196)
		(mid 82.037386 -226.492474)
		(end 82.07883 -226.66452)
		(width 0.09525)
		(layer "In4.Cu")
		(net "M_D_CPU1_SA_DQS_DN<0>")
	)
	(arc
		(start 89.879678 -227.149406)
		(mid 90.16111 -227.225161)
		(end 90.442542 -227.149406)
		(width 0.09525)
		(layer "In4.Cu")
		(net "M_D_CPU1_SA_DQS_DN<0>")
	)
	(arc
		(start 86.119716 -227.149406)
		(mid 86.401148 -227.225161)
		(end 86.68258 -227.149406)
		(width 0.09525)
		(layer "In4.Cu")
		(net "M_D_CPU1_SA_DQS_DN<0>")
	)
	(arc
		(start 83.299554 -227.149406)
		(mid 83.580986 -227.225161)
		(end 83.862418 -227.149406)
		(width 0.09525)
		(layer "In4.Cu")
		(net "M_D_CPU1_SA_DQS_DN<0>")
	)
	(arc
		(start 83.862418 -227.149406)
		(mid 84.046193 -227.098634)
		(end 84.231226 -227.14458)
		(width 0.09525)
		(layer "In4.Cu")
		(net "M_D_CPU1_SA_DQS_DN<0>")
	)
	(arc
		(start 89.51087 -227.14458)
		(mid 89.695902 -227.098666)
		(end 89.879678 -227.149406)
		(width 0.09525)
		(layer "In4.Cu")
		(net "M_D_CPU1_SA_DQS_DN<0>")
	)
	(arc
		(start 82.922364 -227.149406)
		(mid 83.106139 -227.098634)
		(end 83.291172 -227.14458)
		(width 0.09525)
		(layer "In4.Cu")
		(net "M_D_CPU1_SA_DQS_DN<0>")
	)
	(arc
		(start 81.138776 -225.044508)
		(mid 81.203173 -225.305814)
		(end 81.3816 -225.507296)
		(width 0.09525)
		(layer "In4.Cu")
		(net "M_D_CPU1_SA_DQS_DN<0>")
	)
	(arc
		(start 87.99957 -227.149406)
		(mid 88.281002 -227.225161)
		(end 88.562434 -227.149406)
		(width 0.09525)
		(layer "In4.Cu")
		(net "M_D_CPU1_SA_DQS_DN<0>")
	)
	(arc
		(start 81.608676 -225.854514)
		(mid 81.673073 -226.11582)
		(end 81.8515 -226.317302)
		(width 0.09525)
		(layer "In4.Cu")
		(net "M_D_CPU1_SA_DQS_DN<0>")
	)
	(arc
		(start 82.3595 -227.149406)
		(mid 82.640932 -227.225161)
		(end 82.922364 -227.149406)
		(width 0.09525)
		(layer "In4.Cu")
		(net "M_D_CPU1_SA_DQS_DN<0>")
	)
	(arc
		(start 80.982058 -224.738184)
		(mid 81.097332 -224.872462)
		(end 81.138776 -225.044508)
		(width 0.09525)
		(layer "In4.Cu")
		(net "M_D_CPU1_SA_DQS_DN<0>")
	)
	(arc
		(start 85.179662 -227.149406)
		(mid 85.461094 -227.225161)
		(end 85.742526 -227.149406)
		(width 0.09525)
		(layer "In4.Cu")
		(net "M_D_CPU1_SA_DQS_DN<0>")
	)
	(arc
		(start 80.512158 -223.928178)
		(mid 80.627432 -224.062456)
		(end 80.668876 -224.234502)
		(width 0.09525)
		(layer "In4.Cu")
		(net "M_D_CPU1_SA_DQS_DN<0>")
	)
	(segment
		(start 92.97797 -230.980234)
		(end 92.511118 -230.71455)
		(width 0.10668)
		(layer "F.Cu")
		(net "M_D_CPU1_SA_DQ<9>")
	)
	(segment
		(start 55.47868 -208.810352)
		(end 55.641748 -208.97342)
		(width 0.14478)
		(layer "In4.Cu")
		(net "M_D_CPU1_SA_DQ<9>")
	)
	(segment
		(start 85.74405 -231.036876)
		(end 85.752432 -231.041702)
		(width 0.0889)
		(layer "In4.Cu")
		(net "M_D_CPU1_SA_DQ<9>")
	)
	(segment
		(start 41.88333 -208.810352)
		(end 42.733214 -207.960468)
		(width 0.14478)
		(layer "In4.Cu")
		(net "M_D_CPU1_SA_DQ<9>")
	)
	(segment
		(start 88.929718 -231.041702)
		(end 88.9381 -231.036876)
		(width 0.0889)
		(layer "In4.Cu")
		(net "M_D_CPU1_SA_DQ<9>")
	)
	(segment
		(start 49.40681 -208.810352)
		(end 50.256694 -207.960468)
		(width 0.14478)
		(layer "In4.Cu")
		(net "M_D_CPU1_SA_DQ<9>")
	)
	(segment
		(start 78.22565 -228.490526)
		(end 78.46695 -228.490526)
		(width 0.0889)
		(layer "In4.Cu")
		(net "M_D_CPU1_SA_DQ<9>")
	)
	(segment
		(start 41.473882 -208.97342)
		(end 41.63695 -208.810352)
		(width 0.14478)
		(layer "In4.Cu")
		(net "M_D_CPU1_SA_DQ<9>")
	)
	(segment
		(start 76.080366 -226.854004)
		(end 76.571348 -227.344986)
		(width 0.0889)
		(layer "In4.Cu")
		(net "M_D_CPU1_SA_DQ<9>")
	)
	(segment
		(start 45.55871 -207.960468)
		(end 46.408594 -208.810352)
		(width 0.14478)
		(layer "In4.Cu")
		(net "M_D_CPU1_SA_DQ<9>")
	)
	(segment
		(start 55.248302 -208.810352)
		(end 55.47868 -208.810352)
		(width 0.14478)
		(layer "In4.Cu")
		(net "M_D_CPU1_SA_DQ<9>")
	)
	(segment
		(start 54.52872 -209.030316)
		(end 54.691788 -209.193384)
		(width 0.14478)
		(layer "In4.Cu")
		(net "M_D_CPU1_SA_DQ<9>")
	)
	(segment
		(start 38.774116 -208.561686)
		(end 38.937184 -208.724754)
		(width 0.14478)
		(layer "In4.Cu")
		(net "M_D_CPU1_SA_DQ<9>")
	)
	(segment
		(start 54.922166 -209.193384)
		(end 55.085234 -209.030316)
		(width 0.14478)
		(layer "In4.Cu")
		(net "M_D_CPU1_SA_DQ<9>")
	)
	(segment
		(start 51.336956 -208.189576)
		(end 51.336956 -208.123536)
		(width 0.14478)
		(layer "In4.Cu")
		(net "M_D_CPU1_SA_DQ<9>")
	)
	(segment
		(start 80.071468 -231.01808)
		(end 80.10398 -231.036876)
		(width 0.0889)
		(layer "In4.Cu")
		(net "M_D_CPU1_SA_DQ<9>")
	)
	(segment
		(start 48.934878 -208.97342)
		(end 49.097946 -208.810352)
		(width 0.14478)
		(layer "In4.Cu")
		(net "M_D_CPU1_SA_DQ<9>")
	)
	(segment
		(start 38.38067 -208.724754)
		(end 38.543738 -208.561686)
		(width 0.14478)
		(layer "In4.Cu")
		(net "M_D_CPU1_SA_DQ<9>")
	)
	(segment
		(start 54.691788 -209.193384)
		(end 54.922166 -209.193384)
		(width 0.14478)
		(layer "In4.Cu")
		(net "M_D_CPU1_SA_DQ<9>")
	)
	(segment
		(start 54.365652 -208.810352)
		(end 54.52872 -208.97342)
		(width 0.14478)
		(layer "In4.Cu")
		(net "M_D_CPU1_SA_DQ<9>")
	)
	(segment
		(start 43.436286 -208.350866)
		(end 43.67022 -208.350866)
		(width 0.14478)
		(layer "In4.Cu")
		(net "M_D_CPU1_SA_DQ<9>")
	)
	(segment
		(start 51.178206 -208.348326)
		(end 51.336956 -208.189576)
		(width 0.14478)
		(layer "In4.Cu")
		(net "M_D_CPU1_SA_DQ<9>")
	)
	(segment
		(start 39.100252 -209.193384)
		(end 39.33063 -209.193384)
		(width 0.14478)
		(layer "In4.Cu")
		(net "M_D_CPU1_SA_DQ<9>")
	)
	(segment
		(start 89.504012 -231.036876)
		(end 89.512394 -231.041702)
		(width 0.0889)
		(layer "In4.Cu")
		(net "M_D_CPU1_SA_DQ<9>")
	)
	(segment
		(start 41.310814 -209.193384)
		(end 41.473882 -209.030316)
		(width 0.14478)
		(layer "In4.Cu")
		(net "M_D_CPU1_SA_DQ<9>")
	)
	(segment
		(start 56.035194 -209.193384)
		(end 56.198262 -209.030316)
		(width 0.14478)
		(layer "In4.Cu")
		(net "M_D_CPU1_SA_DQ<9>")
	)
	(segment
		(start 39.493698 -209.030316)
		(end 39.493698 -208.97342)
		(width 0.14478)
		(layer "In4.Cu")
		(net "M_D_CPU1_SA_DQ<9>")
	)
	(segment
		(start 50.780442 -208.189576)
		(end 50.939192 -208.348326)
		(width 0.14478)
		(layer "In4.Cu")
		(net "M_D_CPU1_SA_DQ<9>")
	)
	(segment
		(start 48.541432 -209.198464)
		(end 48.77181 -209.198464)
		(width 0.14478)
		(layer "In4.Cu")
		(net "M_D_CPU1_SA_DQ<9>")
	)
	(segment
		(start 79.60233 -230.208582)
		(end 79.63408 -230.22687)
		(width 0.0889)
		(layer "In4.Cu")
		(net "M_D_CPU1_SA_DQ<9>")
	)
	(segment
		(start 43.274996 -208.189576)
		(end 43.436286 -208.350866)
		(width 0.14478)
		(layer "In4.Cu")
		(net "M_D_CPU1_SA_DQ<9>")
	)
	(segment
		(start 55.085234 -208.97342)
		(end 55.248302 -208.810352)
		(width 0.14478)
		(layer "In4.Cu")
		(net "M_D_CPU1_SA_DQ<9>")
	)
	(segment
		(start 51.336956 -208.123536)
		(end 51.500024 -207.960468)
		(width 0.14478)
		(layer "In4.Cu")
		(net "M_D_CPU1_SA_DQ<9>")
	)
	(segment
		(start 41.080436 -209.193384)
		(end 41.310814 -209.193384)
		(width 0.14478)
		(layer "In4.Cu")
		(net "M_D_CPU1_SA_DQ<9>")
	)
	(segment
		(start 48.77181 -209.198464)
		(end 48.934878 -209.035396)
		(width 0.14478)
		(layer "In4.Cu")
		(net "M_D_CPU1_SA_DQ<9>")
	)
	(segment
		(start 37.824156 -208.97342)
		(end 37.824156 -209.030316)
		(width 0.14478)
		(layer "In4.Cu")
		(net "M_D_CPU1_SA_DQ<9>")
	)
	(segment
		(start 83.289648 -231.041702)
		(end 83.29803 -231.036876)
		(width 0.0889)
		(layer "In4.Cu")
		(net "M_D_CPU1_SA_DQ<9>")
	)
	(segment
		(start 42.733214 -207.960468)
		(end 43.111928 -207.960468)
		(width 0.14478)
		(layer "In4.Cu")
		(net "M_D_CPU1_SA_DQ<9>")
	)
	(segment
		(start 55.641748 -208.97342)
		(end 55.641748 -209.030316)
		(width 0.14478)
		(layer "In4.Cu")
		(net "M_D_CPU1_SA_DQ<9>")
	)
	(segment
		(start 54.084474 -208.810352)
		(end 54.365652 -208.810352)
		(width 0.14478)
		(layer "In4.Cu")
		(net "M_D_CPU1_SA_DQ<9>")
	)
	(segment
		(start 77.08011 -227.344986)
		(end 78.22565 -228.490526)
		(width 0.0889)
		(layer "In4.Cu")
		(net "M_D_CPU1_SA_DQ<9>")
	)
	(segment
		(start 38.543738 -208.561686)
		(end 38.774116 -208.561686)
		(width 0.14478)
		(layer "In4.Cu")
		(net "M_D_CPU1_SA_DQ<9>")
	)
	(segment
		(start 76.571348 -227.344986)
		(end 77.08011 -227.344986)
		(width 0.0889)
		(layer "In4.Cu")
		(net "M_D_CPU1_SA_DQ<9>")
	)
	(segment
		(start 40.7543 -208.810352)
		(end 40.917368 -208.97342)
		(width 0.14478)
		(layer "In4.Cu")
		(net "M_D_CPU1_SA_DQ<9>")
	)
	(segment
		(start 43.274996 -208.123536)
		(end 43.274996 -208.189576)
		(width 0.14478)
		(layer "In4.Cu")
		(net "M_D_CPU1_SA_DQ<9>")
	)
	(segment
		(start 37.987224 -209.193384)
		(end 38.217602 -209.193384)
		(width 0.14478)
		(layer "In4.Cu")
		(net "M_D_CPU1_SA_DQ<9>")
	)
	(segment
		(start 50.939192 -208.348326)
		(end 51.178206 -208.348326)
		(width 0.14478)
		(layer "In4.Cu")
		(net "M_D_CPU1_SA_DQ<9>")
	)
	(segment
		(start 80.46974 -231.041702)
		(end 80.478122 -231.036876)
		(width 0.0889)
		(layer "In4.Cu")
		(net "M_D_CPU1_SA_DQ<9>")
	)
	(segment
		(start 51.500024 -207.960468)
		(end 53.23459 -207.960468)
		(width 0.14478)
		(layer "In4.Cu")
		(net "M_D_CPU1_SA_DQ<9>")
	)
	(segment
		(start 78.46695 -228.490526)
		(end 79.04607 -229.069646)
		(width 0.0889)
		(layer "In4.Cu")
		(net "M_D_CPU1_SA_DQ<9>")
	)
	(segment
		(start 84.803996 -231.036876)
		(end 84.812378 -231.041702)
		(width 0.0889)
		(layer "In4.Cu")
		(net "M_D_CPU1_SA_DQ<9>")
	)
	(segment
		(start 43.83151 -208.189576)
		(end 43.83151 -208.123536)
		(width 0.14478)
		(layer "In4.Cu")
		(net "M_D_CPU1_SA_DQ<9>")
	)
	(segment
		(start 84.229702 -231.041702)
		(end 84.238084 -231.036876)
		(width 0.0889)
		(layer "In4.Cu")
		(net "M_D_CPU1_SA_DQ<9>")
	)
	(segment
		(start 49.097946 -208.810352)
		(end 49.40681 -208.810352)
		(width 0.14478)
		(layer "In4.Cu")
		(net "M_D_CPU1_SA_DQ<9>")
	)
	(segment
		(start 39.493698 -208.97342)
		(end 39.656766 -208.810352)
		(width 0.14478)
		(layer "In4.Cu")
		(net "M_D_CPU1_SA_DQ<9>")
	)
	(segment
		(start 72.99325 -222.381826)
		(end 74.91095 -224.299526)
		(width 0.14478)
		(layer "In4.Cu")
		(net "M_D_CPU1_SA_DQ<9>")
	)
	(segment
		(start 36.795964 -208.38541)
		(end 37.220906 -208.810352)
		(width 0.14478)
		(layer "In4.Cu")
		(net "M_D_CPU1_SA_DQ<9>")
	)
	(segment
		(start 37.824156 -209.030316)
		(end 37.987224 -209.193384)
		(width 0.14478)
		(layer "In4.Cu")
		(net "M_D_CPU1_SA_DQ<9>")
	)
	(segment
		(start 72.99325 -221.552262)
		(end 72.99325 -222.381826)
		(width 0.14478)
		(layer "In4.Cu")
		(net "M_D_CPU1_SA_DQ<9>")
	)
	(segment
		(start 38.217602 -209.193384)
		(end 38.38067 -209.030316)
		(width 0.14478)
		(layer "In4.Cu")
		(net "M_D_CPU1_SA_DQ<9>")
	)
	(segment
		(start 92.35694 -230.97998)
		(end 92.511118 -230.71455)
		(width 0.0889)
		(layer "In4.Cu")
		(net "M_D_CPU1_SA_DQ<9>")
	)
	(segment
		(start 81.044034 -231.036876)
		(end 81.052416 -231.041702)
		(width 0.0889)
		(layer "In4.Cu")
		(net "M_D_CPU1_SA_DQ<9>")
	)
	(segment
		(start 92.261182 -231.00538)
		(end 92.35694 -230.97998)
		(width 0.0889)
		(layer "In4.Cu")
		(net "M_D_CPU1_SA_DQ<9>")
	)
	(segment
		(start 43.67022 -208.350866)
		(end 43.83151 -208.189576)
		(width 0.14478)
		(layer "In4.Cu")
		(net "M_D_CPU1_SA_DQ<9>")
	)
	(segment
		(start 48.378364 -208.97342)
		(end 48.378364 -209.035396)
		(width 0.14478)
		(layer "In4.Cu")
		(net "M_D_CPU1_SA_DQ<9>")
	)
	(segment
		(start 43.111928 -207.960468)
		(end 43.274996 -208.123536)
		(width 0.14478)
		(layer "In4.Cu")
		(net "M_D_CPU1_SA_DQ<9>")
	)
	(segment
		(start 40.917368 -209.030316)
		(end 41.080436 -209.193384)
		(width 0.14478)
		(layer "In4.Cu")
		(net "M_D_CPU1_SA_DQ<9>")
	)
	(segment
		(start 48.378364 -209.035396)
		(end 48.541432 -209.198464)
		(width 0.14478)
		(layer "In4.Cu")
		(net "M_D_CPU1_SA_DQ<9>")
	)
	(segment
		(start 48.934878 -209.035396)
		(end 48.934878 -208.97342)
		(width 0.14478)
		(layer "In4.Cu")
		(net "M_D_CPU1_SA_DQ<9>")
	)
	(segment
		(start 55.085234 -209.030316)
		(end 55.085234 -208.97342)
		(width 0.14478)
		(layer "In4.Cu")
		(net "M_D_CPU1_SA_DQ<9>")
	)
	(segment
		(start 74.91095 -225.684588)
		(end 76.080366 -226.854004)
		(width 0.14478)
		(layer "In4.Cu")
		(net "M_D_CPU1_SA_DQ<9>")
	)
	(segment
		(start 54.52872 -208.97342)
		(end 54.52872 -209.030316)
		(width 0.14478)
		(layer "In4.Cu")
		(net "M_D_CPU1_SA_DQ<9>")
	)
	(segment
		(start 55.804816 -209.193384)
		(end 56.035194 -209.193384)
		(width 0.14478)
		(layer "In4.Cu")
		(net "M_D_CPU1_SA_DQ<9>")
	)
	(segment
		(start 37.661088 -208.810352)
		(end 37.824156 -208.97342)
		(width 0.14478)
		(layer "In4.Cu")
		(net "M_D_CPU1_SA_DQ<9>")
	)
	(segment
		(start 50.780442 -208.123536)
		(end 50.780442 -208.189576)
		(width 0.14478)
		(layer "In4.Cu")
		(net "M_D_CPU1_SA_DQ<9>")
	)
	(segment
		(start 41.63695 -208.810352)
		(end 41.88333 -208.810352)
		(width 0.14478)
		(layer "In4.Cu")
		(net "M_D_CPU1_SA_DQ<9>")
	)
	(segment
		(start 55.641748 -209.030316)
		(end 55.804816 -209.193384)
		(width 0.14478)
		(layer "In4.Cu")
		(net "M_D_CPU1_SA_DQ<9>")
	)
	(segment
		(start 87.989664 -231.041702)
		(end 87.998046 -231.036876)
		(width 0.0889)
		(layer "In4.Cu")
		(net "M_D_CPU1_SA_DQ<9>")
	)
	(segment
		(start 74.91095 -224.299526)
		(end 74.91095 -225.684588)
		(width 0.14478)
		(layer "In4.Cu")
		(net "M_D_CPU1_SA_DQ<9>")
	)
	(segment
		(start 56.198262 -208.97342)
		(end 56.36133 -208.810352)
		(width 0.14478)
		(layer "In4.Cu")
		(net "M_D_CPU1_SA_DQ<9>")
	)
	(segment
		(start 56.36133 -208.810352)
		(end 60.25134 -208.810352)
		(width 0.14478)
		(layer "In4.Cu")
		(net "M_D_CPU1_SA_DQ<9>")
	)
	(segment
		(start 41.473882 -209.030316)
		(end 41.473882 -208.97342)
		(width 0.14478)
		(layer "In4.Cu")
		(net "M_D_CPU1_SA_DQ<9>")
	)
	(segment
		(start 40.917368 -208.97342)
		(end 40.917368 -209.030316)
		(width 0.14478)
		(layer "In4.Cu")
		(net "M_D_CPU1_SA_DQ<9>")
	)
	(segment
		(start 79.04607 -229.280466)
		(end 79.338678 -229.573074)
		(width 0.0889)
		(layer "In4.Cu")
		(net "M_D_CPU1_SA_DQ<9>")
	)
	(segment
		(start 38.937184 -209.030316)
		(end 39.100252 -209.193384)
		(width 0.14478)
		(layer "In4.Cu")
		(net "M_D_CPU1_SA_DQ<9>")
	)
	(segment
		(start 50.617374 -207.960468)
		(end 50.780442 -208.123536)
		(width 0.14478)
		(layer "In4.Cu")
		(net "M_D_CPU1_SA_DQ<9>")
	)
	(segment
		(start 46.408594 -208.810352)
		(end 48.215296 -208.810352)
		(width 0.14478)
		(layer "In4.Cu")
		(net "M_D_CPU1_SA_DQ<9>")
	)
	(segment
		(start 38.937184 -208.724754)
		(end 38.937184 -209.030316)
		(width 0.14478)
		(layer "In4.Cu")
		(net "M_D_CPU1_SA_DQ<9>")
	)
	(segment
		(start 37.220906 -208.810352)
		(end 37.661088 -208.810352)
		(width 0.14478)
		(layer "In4.Cu")
		(net "M_D_CPU1_SA_DQ<9>")
	)
	(segment
		(start 56.198262 -209.030316)
		(end 56.198262 -208.97342)
		(width 0.14478)
		(layer "In4.Cu")
		(net "M_D_CPU1_SA_DQ<9>")
	)
	(segment
		(start 38.38067 -209.030316)
		(end 38.38067 -208.724754)
		(width 0.14478)
		(layer "In4.Cu")
		(net "M_D_CPU1_SA_DQ<9>")
	)
	(segment
		(start 48.215296 -208.810352)
		(end 48.378364 -208.97342)
		(width 0.14478)
		(layer "In4.Cu")
		(net "M_D_CPU1_SA_DQ<9>")
	)
	(segment
		(start 79.63408 -230.22687)
		(end 79.670656 -230.248206)
		(width 0.0889)
		(layer "In4.Cu")
		(net "M_D_CPU1_SA_DQ<9>")
	)
	(segment
		(start 43.994578 -207.960468)
		(end 45.55871 -207.960468)
		(width 0.14478)
		(layer "In4.Cu")
		(net "M_D_CPU1_SA_DQ<9>")
	)
	(segment
		(start 60.25134 -208.810352)
		(end 72.99325 -221.552262)
		(width 0.14478)
		(layer "In4.Cu")
		(net "M_D_CPU1_SA_DQ<9>")
	)
	(segment
		(start 39.33063 -209.193384)
		(end 39.493698 -209.030316)
		(width 0.14478)
		(layer "In4.Cu")
		(net "M_D_CPU1_SA_DQ<9>")
	)
	(segment
		(start 39.656766 -208.810352)
		(end 40.7543 -208.810352)
		(width 0.14478)
		(layer "In4.Cu")
		(net "M_D_CPU1_SA_DQ<9>")
	)
	(segment
		(start 43.83151 -208.123536)
		(end 43.994578 -207.960468)
		(width 0.14478)
		(layer "In4.Cu")
		(net "M_D_CPU1_SA_DQ<9>")
	)
	(segment
		(start 91.749626 -231.041702)
		(end 91.758008 -231.036876)
		(width 0.0889)
		(layer "In4.Cu")
		(net "M_D_CPU1_SA_DQ<9>")
	)
	(segment
		(start 50.256694 -207.960468)
		(end 50.617374 -207.960468)
		(width 0.14478)
		(layer "In4.Cu")
		(net "M_D_CPU1_SA_DQ<9>")
	)
	(segment
		(start 53.23459 -207.960468)
		(end 54.084474 -208.810352)
		(width 0.14478)
		(layer "In4.Cu")
		(net "M_D_CPU1_SA_DQ<9>")
	)
	(segment
		(start 79.04607 -229.069646)
		(end 79.04607 -229.280466)
		(width 0.0889)
		(layer "In4.Cu")
		(net "M_D_CPU1_SA_DQ<9>")
	)
	(arc
		(start 80.10398 -231.036876)
		(mid 80.286231 -231.08726)
		(end 80.46974 -231.041702)
		(width 0.0889)
		(layer "In4.Cu")
		(net "M_D_CPU1_SA_DQ<9>")
	)
	(arc
		(start 81.418176 -231.036876)
		(mid 81.701132 -230.960699)
		(end 81.984088 -231.036876)
		(width 0.0889)
		(layer "In4.Cu")
		(net "M_D_CPU1_SA_DQ<9>")
	)
	(arc
		(start 91.383866 -231.036876)
		(mid 91.566117 -231.08726)
		(end 91.749626 -231.041702)
		(width 0.0889)
		(layer "In4.Cu")
		(net "M_D_CPU1_SA_DQ<9>")
	)
	(arc
		(start 81.984088 -231.036876)
		(mid 82.171032 -231.087165)
		(end 82.357976 -231.036876)
		(width 0.0889)
		(layer "In4.Cu")
		(net "M_D_CPU1_SA_DQ<9>")
	)
	(arc
		(start 81.052416 -231.041702)
		(mid 81.235924 -231.087227)
		(end 81.418176 -231.036876)
		(width 0.0889)
		(layer "In4.Cu")
		(net "M_D_CPU1_SA_DQ<9>")
	)
	(arc
		(start 85.178138 -231.036876)
		(mid 85.461094 -230.960699)
		(end 85.74405 -231.036876)
		(width 0.0889)
		(layer "In4.Cu")
		(net "M_D_CPU1_SA_DQ<9>")
	)
	(arc
		(start 88.9381 -231.036876)
		(mid 89.221056 -230.960699)
		(end 89.504012 -231.036876)
		(width 0.0889)
		(layer "In4.Cu")
		(net "M_D_CPU1_SA_DQ<9>")
	)
	(arc
		(start 79.916528 -230.71455)
		(mid 79.957494 -230.884956)
		(end 80.071468 -231.01808)
		(width 0.0889)
		(layer "In4.Cu")
		(net "M_D_CPU1_SA_DQ<9>")
	)
	(arc
		(start 79.670656 -230.248206)
		(mid 79.851308 -230.450951)
		(end 79.916528 -230.71455)
		(width 0.0889)
		(layer "In4.Cu")
		(net "M_D_CPU1_SA_DQ<9>")
	)
	(arc
		(start 87.623904 -231.036876)
		(mid 87.806155 -231.08726)
		(end 87.989664 -231.041702)
		(width 0.0889)
		(layer "In4.Cu")
		(net "M_D_CPU1_SA_DQ<9>")
	)
	(arc
		(start 85.752432 -231.041702)
		(mid 85.93594 -231.087227)
		(end 86.118192 -231.036876)
		(width 0.0889)
		(layer "In4.Cu")
		(net "M_D_CPU1_SA_DQ<9>")
	)
	(arc
		(start 86.118192 -231.036876)
		(mid 86.401148 -230.960699)
		(end 86.684104 -231.036876)
		(width 0.0889)
		(layer "In4.Cu")
		(net "M_D_CPU1_SA_DQ<9>")
	)
	(arc
		(start 87.998046 -231.036876)
		(mid 88.281002 -230.960699)
		(end 88.563958 -231.036876)
		(width 0.0889)
		(layer "In4.Cu")
		(net "M_D_CPU1_SA_DQ<9>")
	)
	(arc
		(start 84.812378 -231.041702)
		(mid 84.995886 -231.087227)
		(end 85.178138 -231.036876)
		(width 0.0889)
		(layer "In4.Cu")
		(net "M_D_CPU1_SA_DQ<9>")
	)
	(arc
		(start 79.338678 -229.573074)
		(mid 79.41871 -229.730174)
		(end 79.446374 -229.90429)
		(width 0.0889)
		(layer "In4.Cu")
		(net "M_D_CPU1_SA_DQ<9>")
	)
	(arc
		(start 82.923888 -231.036876)
		(mid 83.106139 -231.08726)
		(end 83.289648 -231.041702)
		(width 0.0889)
		(layer "In4.Cu")
		(net "M_D_CPU1_SA_DQ<9>")
	)
	(arc
		(start 79.446374 -229.90429)
		(mid 79.487629 -230.075261)
		(end 79.60233 -230.208582)
		(width 0.0889)
		(layer "In4.Cu")
		(net "M_D_CPU1_SA_DQ<9>")
	)
	(arc
		(start 83.29803 -231.036876)
		(mid 83.580986 -230.960699)
		(end 83.863942 -231.036876)
		(width 0.0889)
		(layer "In4.Cu")
		(net "M_D_CPU1_SA_DQ<9>")
	)
	(arc
		(start 90.817954 -231.036876)
		(mid 91.10091 -230.960699)
		(end 91.383866 -231.036876)
		(width 0.0889)
		(layer "In4.Cu")
		(net "M_D_CPU1_SA_DQ<9>")
	)
	(arc
		(start 83.863942 -231.036876)
		(mid 84.046193 -231.08726)
		(end 84.229702 -231.041702)
		(width 0.0889)
		(layer "In4.Cu")
		(net "M_D_CPU1_SA_DQ<9>")
	)
	(arc
		(start 82.357976 -231.036876)
		(mid 82.640932 -230.960699)
		(end 82.923888 -231.036876)
		(width 0.0889)
		(layer "In4.Cu")
		(net "M_D_CPU1_SA_DQ<9>")
	)
	(arc
		(start 90.444066 -231.036876)
		(mid 90.63101 -231.087165)
		(end 90.817954 -231.036876)
		(width 0.0889)
		(layer "In4.Cu")
		(net "M_D_CPU1_SA_DQ<9>")
	)
	(arc
		(start 89.512394 -231.041702)
		(mid 89.695902 -231.087227)
		(end 89.878154 -231.036876)
		(width 0.0889)
		(layer "In4.Cu")
		(net "M_D_CPU1_SA_DQ<9>")
	)
	(arc
		(start 87.057992 -231.036876)
		(mid 87.340948 -230.960699)
		(end 87.623904 -231.036876)
		(width 0.0889)
		(layer "In4.Cu")
		(net "M_D_CPU1_SA_DQ<9>")
	)
	(arc
		(start 84.238084 -231.036876)
		(mid 84.52104 -230.960699)
		(end 84.803996 -231.036876)
		(width 0.0889)
		(layer "In4.Cu")
		(net "M_D_CPU1_SA_DQ<9>")
	)
	(arc
		(start 86.684104 -231.036876)
		(mid 86.871048 -231.087165)
		(end 87.057992 -231.036876)
		(width 0.0889)
		(layer "In4.Cu")
		(net "M_D_CPU1_SA_DQ<9>")
	)
	(arc
		(start 80.478122 -231.036876)
		(mid 80.761078 -230.960699)
		(end 81.044034 -231.036876)
		(width 0.0889)
		(layer "In4.Cu")
		(net "M_D_CPU1_SA_DQ<9>")
	)
	(arc
		(start 91.758008 -231.036876)
		(mid 92.005868 -230.961793)
		(end 92.261182 -231.00538)
		(width 0.0889)
		(layer "In4.Cu")
		(net "M_D_CPU1_SA_DQ<9>")
	)
	(arc
		(start 88.563958 -231.036876)
		(mid 88.746209 -231.08726)
		(end 88.929718 -231.041702)
		(width 0.0889)
		(layer "In4.Cu")
		(net "M_D_CPU1_SA_DQ<9>")
	)
	(arc
		(start 89.878154 -231.036876)
		(mid 90.16111 -230.960699)
		(end 90.444066 -231.036876)
		(width 0.0889)
		(layer "In4.Cu")
		(net "M_D_CPU1_SA_DQ<9>")
	)
	(segment
		(start 91.568016 -230.170228)
		(end 91.10091 -229.90429)
		(width 0.10668)
		(layer "F.Cu")
		(net "M_D_CPU1_SA_DQ<8>")
	)
	(segment
		(start 59.82335 -207.11033)
		(end 73.91019 -221.19717)
		(width 0.14478)
		(layer "In4.Cu")
		(net "M_D_CPU1_SA_DQ<8>")
	)
	(segment
		(start 54.949598 -207.484726)
		(end 55.177944 -207.484726)
		(width 0.14478)
		(layer "In4.Cu")
		(net "M_D_CPU1_SA_DQ<8>")
	)
	(segment
		(start 50.256694 -206.260446)
		(end 50.490628 -206.260446)
		(width 0.14478)
		(layer "In4.Cu")
		(net "M_D_CPU1_SA_DQ<8>")
	)
	(segment
		(start 50.652172 -206.42199)
		(end 50.652172 -206.490062)
		(width 0.14478)
		(layer "In4.Cu")
		(net "M_D_CPU1_SA_DQ<8>")
	)
	(segment
		(start 41.88333 -207.11033)
		(end 42.733214 -206.260446)
		(width 0.14478)
		(layer "In4.Cu")
		(net "M_D_CPU1_SA_DQ<8>")
	)
	(segment
		(start 79.446374 -227.86975)
		(end 79.446374 -228.284532)
		(width 0.0889)
		(layer "In4.Cu")
		(net "M_D_CPU1_SA_DQ<8>")
	)
	(segment
		(start 38.652958 -207.510126)
		(end 38.881304 -207.510126)
		(width 0.14478)
		(layer "In4.Cu")
		(net "M_D_CPU1_SA_DQ<8>")
	)
	(segment
		(start 50.813716 -206.651606)
		(end 51.042062 -206.651606)
		(width 0.14478)
		(layer "In4.Cu")
		(net "M_D_CPU1_SA_DQ<8>")
	)
	(segment
		(start 38.881304 -207.510126)
		(end 39.042848 -207.348582)
		(width 0.14478)
		(layer "In4.Cu")
		(net "M_D_CPU1_SA_DQ<8>")
	)
	(segment
		(start 58.648092 -207.271874)
		(end 58.809636 -207.11033)
		(width 0.14478)
		(layer "In4.Cu")
		(net "M_D_CPU1_SA_DQ<8>")
	)
	(segment
		(start 38.491414 -206.99095)
		(end 38.491414 -207.348582)
		(width 0.14478)
		(layer "In4.Cu")
		(net "M_D_CPU1_SA_DQ<8>")
	)
	(segment
		(start 87.154004 -230.22687)
		(end 87.162386 -230.231696)
		(width 0.0889)
		(layer "In4.Cu")
		(net "M_D_CPU1_SA_DQ<8>")
	)
	(segment
		(start 57.545224 -207.271874)
		(end 57.706768 -207.11033)
		(width 0.14478)
		(layer "In4.Cu")
		(net "M_D_CPU1_SA_DQ<8>")
	)
	(segment
		(start 56.832246 -206.900526)
		(end 56.99379 -207.06207)
		(width 0.14478)
		(layer "In4.Cu")
		(net "M_D_CPU1_SA_DQ<8>")
	)
	(segment
		(start 54.62651 -207.11033)
		(end 54.788054 -207.271874)
		(width 0.14478)
		(layer "In4.Cu")
		(net "M_D_CPU1_SA_DQ<8>")
	)
	(segment
		(start 50.490628 -206.260446)
		(end 50.652172 -206.42199)
		(width 0.14478)
		(layer "In4.Cu")
		(net "M_D_CPU1_SA_DQ<8>")
	)
	(segment
		(start 38.491414 -207.348582)
		(end 38.652958 -207.510126)
		(width 0.14478)
		(layer "In4.Cu")
		(net "M_D_CPU1_SA_DQ<8>")
	)
	(segment
		(start 80.542384 -230.208582)
		(end 80.574134 -230.22687)
		(width 0.0889)
		(layer "In4.Cu")
		(net "M_D_CPU1_SA_DQ<8>")
	)
	(segment
		(start 51.042062 -206.651606)
		(end 51.203606 -206.490062)
		(width 0.14478)
		(layer "In4.Cu")
		(net "M_D_CPU1_SA_DQ<8>")
	)
	(segment
		(start 55.339488 -207.271874)
		(end 55.501032 -207.11033)
		(width 0.14478)
		(layer "In4.Cu")
		(net "M_D_CPU1_SA_DQ<8>")
	)
	(segment
		(start 41.256458 -207.413606)
		(end 41.559734 -207.11033)
		(width 0.14478)
		(layer "In4.Cu")
		(net "M_D_CPU1_SA_DQ<8>")
	)
	(segment
		(start 48.405796 -207.348582)
		(end 48.56734 -207.510126)
		(width 0.14478)
		(layer "In4.Cu")
		(net "M_D_CPU1_SA_DQ<8>")
	)
	(segment
		(start 39.042848 -206.98079)
		(end 39.204392 -206.819246)
		(width 0.14478)
		(layer "In4.Cu")
		(net "M_D_CPU1_SA_DQ<8>")
	)
	(segment
		(start 43.008804 -206.260446)
		(end 43.290744 -206.542386)
		(width 0.14478)
		(layer "In4.Cu")
		(net "M_D_CPU1_SA_DQ<8>")
	)
	(segment
		(start 58.809636 -207.11033)
		(end 59.82335 -207.11033)
		(width 0.14478)
		(layer "In4.Cu")
		(net "M_D_CPU1_SA_DQ<8>")
	)
	(segment
		(start 90.946986 -230.16972)
		(end 91.10091 -229.90429)
		(width 0.0889)
		(layer "In4.Cu")
		(net "M_D_CPU1_SA_DQ<8>")
	)
	(segment
		(start 81.879694 -230.231696)
		(end 81.888076 -230.22687)
		(width 0.0889)
		(layer "In4.Cu")
		(net "M_D_CPU1_SA_DQ<8>")
	)
	(segment
		(start 37.220906 -207.11033)
		(end 37.8206 -207.11033)
		(width 0.14478)
		(layer "In4.Cu")
		(net "M_D_CPU1_SA_DQ<8>")
	)
	(segment
		(start 57.155334 -207.484726)
		(end 57.38368 -207.484726)
		(width 0.14478)
		(layer "In4.Cu")
		(net "M_D_CPU1_SA_DQ<8>")
	)
	(segment
		(start 38.101524 -206.829406)
		(end 38.32987 -206.829406)
		(width 0.14478)
		(layer "In4.Cu")
		(net "M_D_CPU1_SA_DQ<8>")
	)
	(segment
		(start 56.99379 -207.323182)
		(end 57.155334 -207.484726)
		(width 0.14478)
		(layer "In4.Cu")
		(net "M_D_CPU1_SA_DQ<8>")
	)
	(segment
		(start 75.88377 -223.971866)
		(end 75.88377 -224.968308)
		(width 0.14478)
		(layer "In4.Cu")
		(net "M_D_CPU1_SA_DQ<8>")
	)
	(segment
		(start 88.094058 -230.22687)
		(end 88.10244 -230.231696)
		(width 0.0889)
		(layer "In4.Cu")
		(net "M_D_CPU1_SA_DQ<8>")
	)
	(segment
		(start 73.91019 -221.19717)
		(end 73.91019 -221.998286)
		(width 0.14478)
		(layer "In4.Cu")
		(net "M_D_CPU1_SA_DQ<8>")
	)
	(segment
		(start 58.096658 -207.323182)
		(end 58.258202 -207.484726)
		(width 0.14478)
		(layer "In4.Cu")
		(net "M_D_CPU1_SA_DQ<8>")
	)
	(segment
		(start 57.545224 -207.323182)
		(end 57.545224 -207.271874)
		(width 0.14478)
		(layer "In4.Cu")
		(net "M_D_CPU1_SA_DQ<8>")
	)
	(segment
		(start 39.432738 -206.819246)
		(end 39.723822 -207.11033)
		(width 0.14478)
		(layer "In4.Cu")
		(net "M_D_CPU1_SA_DQ<8>")
	)
	(segment
		(start 54.788054 -207.323182)
		(end 54.949598 -207.484726)
		(width 0.14478)
		(layer "In4.Cu")
		(net "M_D_CPU1_SA_DQ<8>")
	)
	(segment
		(start 55.501032 -207.11033)
		(end 55.729378 -207.11033)
		(width 0.14478)
		(layer "In4.Cu")
		(net "M_D_CPU1_SA_DQ<8>")
	)
	(segment
		(start 48.244252 -207.11033)
		(end 48.405796 -207.271874)
		(width 0.14478)
		(layer "In4.Cu")
		(net "M_D_CPU1_SA_DQ<8>")
	)
	(segment
		(start 56.442356 -207.06207)
		(end 56.6039 -206.900526)
		(width 0.14478)
		(layer "In4.Cu")
		(net "M_D_CPU1_SA_DQ<8>")
	)
	(segment
		(start 43.842178 -206.260446)
		(end 45.55871 -206.260446)
		(width 0.14478)
		(layer "In4.Cu")
		(net "M_D_CPU1_SA_DQ<8>")
	)
	(segment
		(start 57.706768 -207.11033)
		(end 57.935114 -207.11033)
		(width 0.14478)
		(layer "In4.Cu")
		(net "M_D_CPU1_SA_DQ<8>")
	)
	(segment
		(start 53.23459 -206.260446)
		(end 54.084474 -207.11033)
		(width 0.14478)
		(layer "In4.Cu")
		(net "M_D_CPU1_SA_DQ<8>")
	)
	(segment
		(start 39.042848 -207.348582)
		(end 39.042848 -206.98079)
		(width 0.14478)
		(layer "In4.Cu")
		(net "M_D_CPU1_SA_DQ<8>")
	)
	(segment
		(start 76.922376 -226.006914)
		(end 77.909928 -226.994466)
		(width 0.0889)
		(layer "In4.Cu")
		(net "M_D_CPU1_SA_DQ<8>")
	)
	(segment
		(start 48.95723 -207.348582)
		(end 48.95723 -207.271874)
		(width 0.14478)
		(layer "In4.Cu")
		(net "M_D_CPU1_SA_DQ<8>")
	)
	(segment
		(start 80.10398 -229.416864)
		(end 80.141064 -229.4382)
		(width 0.0889)
		(layer "In4.Cu")
		(net "M_D_CPU1_SA_DQ<8>")
	)
	(segment
		(start 55.729378 -207.11033)
		(end 55.890922 -207.271874)
		(width 0.14478)
		(layer "In4.Cu")
		(net "M_D_CPU1_SA_DQ<8>")
	)
	(segment
		(start 39.204392 -206.819246)
		(end 39.432738 -206.819246)
		(width 0.14478)
		(layer "In4.Cu")
		(net "M_D_CPU1_SA_DQ<8>")
	)
	(segment
		(start 49.40681 -207.11033)
		(end 50.256694 -206.260446)
		(width 0.14478)
		(layer "In4.Cu")
		(net "M_D_CPU1_SA_DQ<8>")
	)
	(segment
		(start 46.408594 -207.11033)
		(end 48.244252 -207.11033)
		(width 0.14478)
		(layer "In4.Cu")
		(net "M_D_CPU1_SA_DQ<8>")
	)
	(segment
		(start 39.723822 -207.11033)
		(end 40.705024 -207.11033)
		(width 0.14478)
		(layer "In4.Cu")
		(net "M_D_CPU1_SA_DQ<8>")
	)
	(segment
		(start 36.795964 -206.685388)
		(end 37.220906 -207.11033)
		(width 0.14478)
		(layer "In4.Cu")
		(net "M_D_CPU1_SA_DQ<8>")
	)
	(segment
		(start 83.394042 -230.22687)
		(end 83.402424 -230.231696)
		(width 0.0889)
		(layer "In4.Cu")
		(net "M_D_CPU1_SA_DQ<8>")
	)
	(segment
		(start 54.084474 -207.11033)
		(end 54.62651 -207.11033)
		(width 0.14478)
		(layer "In4.Cu")
		(net "M_D_CPU1_SA_DQ<8>")
	)
	(segment
		(start 58.486548 -207.484726)
		(end 58.648092 -207.323182)
		(width 0.14478)
		(layer "In4.Cu")
		(net "M_D_CPU1_SA_DQ<8>")
	)
	(segment
		(start 51.36515 -206.260446)
		(end 53.23459 -206.260446)
		(width 0.14478)
		(layer "In4.Cu")
		(net "M_D_CPU1_SA_DQ<8>")
	)
	(segment
		(start 56.280812 -207.484726)
		(end 56.442356 -207.323182)
		(width 0.14478)
		(layer "In4.Cu")
		(net "M_D_CPU1_SA_DQ<8>")
	)
	(segment
		(start 51.203606 -206.490062)
		(end 51.203606 -206.42199)
		(width 0.14478)
		(layer "In4.Cu")
		(net "M_D_CPU1_SA_DQ<8>")
	)
	(segment
		(start 86.57971 -230.231696)
		(end 86.588092 -230.22687)
		(width 0.0889)
		(layer "In4.Cu")
		(net "M_D_CPU1_SA_DQ<8>")
	)
	(segment
		(start 41.559734 -207.11033)
		(end 41.88333 -207.11033)
		(width 0.14478)
		(layer "In4.Cu")
		(net "M_D_CPU1_SA_DQ<8>")
	)
	(segment
		(start 58.258202 -207.484726)
		(end 58.486548 -207.484726)
		(width 0.14478)
		(layer "In4.Cu")
		(net "M_D_CPU1_SA_DQ<8>")
	)
	(segment
		(start 42.733214 -206.260446)
		(end 43.008804 -206.260446)
		(width 0.14478)
		(layer "In4.Cu")
		(net "M_D_CPU1_SA_DQ<8>")
	)
	(segment
		(start 45.55871 -206.260446)
		(end 46.408594 -207.11033)
		(width 0.14478)
		(layer "In4.Cu")
		(net "M_D_CPU1_SA_DQ<8>")
	)
	(segment
		(start 80.141064 -229.4382)
		(end 80.143096 -229.439724)
		(width 0.0889)
		(layer "In4.Cu")
		(net "M_D_CPU1_SA_DQ<8>")
	)
	(segment
		(start 43.290744 -206.542386)
		(end 43.560238 -206.542386)
		(width 0.14478)
		(layer "In4.Cu")
		(net "M_D_CPU1_SA_DQ<8>")
	)
	(segment
		(start 56.052466 -207.484726)
		(end 56.280812 -207.484726)
		(width 0.14478)
		(layer "In4.Cu")
		(net "M_D_CPU1_SA_DQ<8>")
	)
	(segment
		(start 48.795686 -207.510126)
		(end 48.95723 -207.348582)
		(width 0.14478)
		(layer "In4.Cu")
		(net "M_D_CPU1_SA_DQ<8>")
	)
	(segment
		(start 50.652172 -206.490062)
		(end 50.813716 -206.651606)
		(width 0.14478)
		(layer "In4.Cu")
		(net "M_D_CPU1_SA_DQ<8>")
	)
	(segment
		(start 55.890922 -207.323182)
		(end 56.052466 -207.484726)
		(width 0.14478)
		(layer "In4.Cu")
		(net "M_D_CPU1_SA_DQ<8>")
	)
	(segment
		(start 77.909928 -226.994466)
		(end 78.57109 -226.994466)
		(width 0.0889)
		(layer "In4.Cu")
		(net "M_D_CPU1_SA_DQ<8>")
	)
	(segment
		(start 80.071468 -229.398068)
		(end 80.10398 -229.416864)
		(width 0.0889)
		(layer "In4.Cu")
		(net "M_D_CPU1_SA_DQ<8>")
	)
	(segment
		(start 85.639656 -230.231696)
		(end 85.648038 -230.22687)
		(width 0.0889)
		(layer "In4.Cu")
		(net "M_D_CPU1_SA_DQ<8>")
	)
	(segment
		(start 73.91019 -221.998286)
		(end 75.88377 -223.971866)
		(width 0.14478)
		(layer "In4.Cu")
		(net "M_D_CPU1_SA_DQ<8>")
	)
	(segment
		(start 54.788054 -207.271874)
		(end 54.788054 -207.323182)
		(width 0.14478)
		(layer "In4.Cu")
		(net "M_D_CPU1_SA_DQ<8>")
	)
	(segment
		(start 48.405796 -207.271874)
		(end 48.405796 -207.348582)
		(width 0.14478)
		(layer "In4.Cu")
		(net "M_D_CPU1_SA_DQ<8>")
	)
	(segment
		(start 75.88377 -224.968308)
		(end 76.922376 -226.006914)
		(width 0.14478)
		(layer "In4.Cu")
		(net "M_D_CPU1_SA_DQ<8>")
	)
	(segment
		(start 57.38368 -207.484726)
		(end 57.545224 -207.323182)
		(width 0.14478)
		(layer "In4.Cu")
		(net "M_D_CPU1_SA_DQ<8>")
	)
	(segment
		(start 43.560238 -206.542386)
		(end 43.842178 -206.260446)
		(width 0.14478)
		(layer "In4.Cu")
		(net "M_D_CPU1_SA_DQ<8>")
	)
	(segment
		(start 56.99379 -207.06207)
		(end 56.99379 -207.323182)
		(width 0.14478)
		(layer "In4.Cu")
		(net "M_D_CPU1_SA_DQ<8>")
	)
	(segment
		(start 82.453988 -230.22687)
		(end 82.46237 -230.231696)
		(width 0.0889)
		(layer "In4.Cu")
		(net "M_D_CPU1_SA_DQ<8>")
	)
	(segment
		(start 58.648092 -207.323182)
		(end 58.648092 -207.271874)
		(width 0.14478)
		(layer "In4.Cu")
		(net "M_D_CPU1_SA_DQ<8>")
	)
	(segment
		(start 40.705024 -207.11033)
		(end 41.0083 -207.413606)
		(width 0.14478)
		(layer "In4.Cu")
		(net "M_D_CPU1_SA_DQ<8>")
	)
	(segment
		(start 79.60233 -228.588824)
		(end 79.63408 -228.607112)
		(width 0.0889)
		(layer "In4.Cu")
		(net "M_D_CPU1_SA_DQ<8>")
	)
	(segment
		(start 79.63408 -228.607112)
		(end 79.673196 -228.629972)
		(width 0.0889)
		(layer "In4.Cu")
		(net "M_D_CPU1_SA_DQ<8>")
	)
	(segment
		(start 55.339488 -207.323182)
		(end 55.339488 -207.271874)
		(width 0.14478)
		(layer "In4.Cu")
		(net "M_D_CPU1_SA_DQ<8>")
	)
	(segment
		(start 41.0083 -207.413606)
		(end 41.256458 -207.413606)
		(width 0.14478)
		(layer "In4.Cu")
		(net "M_D_CPU1_SA_DQ<8>")
	)
	(segment
		(start 55.177944 -207.484726)
		(end 55.339488 -207.323182)
		(width 0.14478)
		(layer "In4.Cu")
		(net "M_D_CPU1_SA_DQ<8>")
	)
	(segment
		(start 90.850974 -230.19512)
		(end 90.946986 -230.16972)
		(width 0.0889)
		(layer "In4.Cu")
		(net "M_D_CPU1_SA_DQ<8>")
	)
	(segment
		(start 90.339672 -230.231696)
		(end 90.348054 -230.22687)
		(width 0.0889)
		(layer "In4.Cu")
		(net "M_D_CPU1_SA_DQ<8>")
	)
	(segment
		(start 48.95723 -207.271874)
		(end 49.118774 -207.11033)
		(width 0.14478)
		(layer "In4.Cu")
		(net "M_D_CPU1_SA_DQ<8>")
	)
	(segment
		(start 51.203606 -206.42199)
		(end 51.36515 -206.260446)
		(width 0.14478)
		(layer "In4.Cu")
		(net "M_D_CPU1_SA_DQ<8>")
	)
	(segment
		(start 38.32987 -206.829406)
		(end 38.491414 -206.99095)
		(width 0.14478)
		(layer "In4.Cu")
		(net "M_D_CPU1_SA_DQ<8>")
	)
	(segment
		(start 58.096658 -207.271874)
		(end 58.096658 -207.323182)
		(width 0.14478)
		(layer "In4.Cu")
		(net "M_D_CPU1_SA_DQ<8>")
	)
	(segment
		(start 56.442356 -207.323182)
		(end 56.442356 -207.06207)
		(width 0.14478)
		(layer "In4.Cu")
		(net "M_D_CPU1_SA_DQ<8>")
	)
	(segment
		(start 78.57109 -226.994466)
		(end 79.446374 -227.86975)
		(width 0.0889)
		(layer "In4.Cu")
		(net "M_D_CPU1_SA_DQ<8>")
	)
	(segment
		(start 57.935114 -207.11033)
		(end 58.096658 -207.271874)
		(width 0.14478)
		(layer "In4.Cu")
		(net "M_D_CPU1_SA_DQ<8>")
	)
	(segment
		(start 56.6039 -206.900526)
		(end 56.832246 -206.900526)
		(width 0.14478)
		(layer "In4.Cu")
		(net "M_D_CPU1_SA_DQ<8>")
	)
	(segment
		(start 55.890922 -207.271874)
		(end 55.890922 -207.323182)
		(width 0.14478)
		(layer "In4.Cu")
		(net "M_D_CPU1_SA_DQ<8>")
	)
	(segment
		(start 37.8206 -207.11033)
		(end 38.101524 -206.829406)
		(width 0.14478)
		(layer "In4.Cu")
		(net "M_D_CPU1_SA_DQ<8>")
	)
	(segment
		(start 49.118774 -207.11033)
		(end 49.40681 -207.11033)
		(width 0.14478)
		(layer "In4.Cu")
		(net "M_D_CPU1_SA_DQ<8>")
	)
	(segment
		(start 48.56734 -207.510126)
		(end 48.795686 -207.510126)
		(width 0.14478)
		(layer "In4.Cu")
		(net "M_D_CPU1_SA_DQ<8>")
	)
	(arc
		(start 90.348054 -230.22687)
		(mid 90.595767 -230.151684)
		(end 90.850974 -230.19512)
		(width 0.0889)
		(layer "In4.Cu")
		(net "M_D_CPU1_SA_DQ<8>")
	)
	(arc
		(start 87.162386 -230.231696)
		(mid 87.345894 -230.27719)
		(end 87.528146 -230.22687)
		(width 0.0889)
		(layer "In4.Cu")
		(net "M_D_CPU1_SA_DQ<8>")
	)
	(arc
		(start 88.10244 -230.231696)
		(mid 88.285948 -230.27719)
		(end 88.4682 -230.22687)
		(width 0.0889)
		(layer "In4.Cu")
		(net "M_D_CPU1_SA_DQ<8>")
	)
	(arc
		(start 80.143096 -229.439724)
		(mid 80.321909 -229.642074)
		(end 80.386428 -229.90429)
		(width 0.0889)
		(layer "In4.Cu")
		(net "M_D_CPU1_SA_DQ<8>")
	)
	(arc
		(start 87.528146 -230.22687)
		(mid 87.811102 -230.150727)
		(end 88.094058 -230.22687)
		(width 0.0889)
		(layer "In4.Cu")
		(net "M_D_CPU1_SA_DQ<8>")
	)
	(arc
		(start 88.4682 -230.22687)
		(mid 88.751156 -230.150727)
		(end 89.034112 -230.22687)
		(width 0.0889)
		(layer "In4.Cu")
		(net "M_D_CPU1_SA_DQ<8>")
	)
	(arc
		(start 85.273896 -230.22687)
		(mid 85.456147 -230.27722)
		(end 85.639656 -230.231696)
		(width 0.0889)
		(layer "In4.Cu")
		(net "M_D_CPU1_SA_DQ<8>")
	)
	(arc
		(start 80.574134 -230.22687)
		(mid 80.761078 -230.277125)
		(end 80.948022 -230.22687)
		(width 0.0889)
		(layer "In4.Cu")
		(net "M_D_CPU1_SA_DQ<8>")
	)
	(arc
		(start 79.673196 -228.629972)
		(mid 79.852009 -228.832322)
		(end 79.916528 -229.094538)
		(width 0.0889)
		(layer "In4.Cu")
		(net "M_D_CPU1_SA_DQ<8>")
	)
	(arc
		(start 79.916528 -229.094538)
		(mid 79.957494 -229.264944)
		(end 80.071468 -229.398068)
		(width 0.0889)
		(layer "In4.Cu")
		(net "M_D_CPU1_SA_DQ<8>")
	)
	(arc
		(start 85.648038 -230.22687)
		(mid 85.930994 -230.150727)
		(end 86.21395 -230.22687)
		(width 0.0889)
		(layer "In4.Cu")
		(net "M_D_CPU1_SA_DQ<8>")
	)
	(arc
		(start 80.386428 -229.90429)
		(mid 80.427683 -230.075261)
		(end 80.542384 -230.208582)
		(width 0.0889)
		(layer "In4.Cu")
		(net "M_D_CPU1_SA_DQ<8>")
	)
	(arc
		(start 82.82813 -230.22687)
		(mid 83.111086 -230.150727)
		(end 83.394042 -230.22687)
		(width 0.0889)
		(layer "In4.Cu")
		(net "M_D_CPU1_SA_DQ<8>")
	)
	(arc
		(start 84.707984 -230.22687)
		(mid 84.99094 -230.150727)
		(end 85.273896 -230.22687)
		(width 0.0889)
		(layer "In4.Cu")
		(net "M_D_CPU1_SA_DQ<8>")
	)
	(arc
		(start 89.408 -230.22687)
		(mid 89.690956 -230.150727)
		(end 89.973912 -230.22687)
		(width 0.0889)
		(layer "In4.Cu")
		(net "M_D_CPU1_SA_DQ<8>")
	)
	(arc
		(start 83.768184 -230.22687)
		(mid 84.05114 -230.150727)
		(end 84.334096 -230.22687)
		(width 0.0889)
		(layer "In4.Cu")
		(net "M_D_CPU1_SA_DQ<8>")
	)
	(arc
		(start 86.21395 -230.22687)
		(mid 86.396201 -230.27722)
		(end 86.57971 -230.231696)
		(width 0.0889)
		(layer "In4.Cu")
		(net "M_D_CPU1_SA_DQ<8>")
	)
	(arc
		(start 84.334096 -230.22687)
		(mid 84.52104 -230.277125)
		(end 84.707984 -230.22687)
		(width 0.0889)
		(layer "In4.Cu")
		(net "M_D_CPU1_SA_DQ<8>")
	)
	(arc
		(start 86.588092 -230.22687)
		(mid 86.871048 -230.150727)
		(end 87.154004 -230.22687)
		(width 0.0889)
		(layer "In4.Cu")
		(net "M_D_CPU1_SA_DQ<8>")
	)
	(arc
		(start 81.888076 -230.22687)
		(mid 82.171032 -230.150727)
		(end 82.453988 -230.22687)
		(width 0.0889)
		(layer "In4.Cu")
		(net "M_D_CPU1_SA_DQ<8>")
	)
	(arc
		(start 89.973912 -230.22687)
		(mid 90.156163 -230.27722)
		(end 90.339672 -230.231696)
		(width 0.0889)
		(layer "In4.Cu")
		(net "M_D_CPU1_SA_DQ<8>")
	)
	(arc
		(start 81.513934 -230.22687)
		(mid 81.696185 -230.27722)
		(end 81.879694 -230.231696)
		(width 0.0889)
		(layer "In4.Cu")
		(net "M_D_CPU1_SA_DQ<8>")
	)
	(arc
		(start 82.46237 -230.231696)
		(mid 82.645878 -230.27719)
		(end 82.82813 -230.22687)
		(width 0.0889)
		(layer "In4.Cu")
		(net "M_D_CPU1_SA_DQ<8>")
	)
	(arc
		(start 83.402424 -230.231696)
		(mid 83.585932 -230.27719)
		(end 83.768184 -230.22687)
		(width 0.0889)
		(layer "In4.Cu")
		(net "M_D_CPU1_SA_DQ<8>")
	)
	(arc
		(start 79.446374 -228.284532)
		(mid 79.487629 -228.455503)
		(end 79.60233 -228.588824)
		(width 0.0889)
		(layer "In4.Cu")
		(net "M_D_CPU1_SA_DQ<8>")
	)
	(arc
		(start 89.034112 -230.22687)
		(mid 89.221056 -230.277125)
		(end 89.408 -230.22687)
		(width 0.0889)
		(layer "In4.Cu")
		(net "M_D_CPU1_SA_DQ<8>")
	)
	(arc
		(start 80.948022 -230.22687)
		(mid 81.230978 -230.150727)
		(end 81.513934 -230.22687)
		(width 0.0889)
		(layer "In4.Cu")
		(net "M_D_CPU1_SA_DQ<8>")
	)
	(segment
		(start 92.507816 -230.170228)
		(end 92.040964 -229.90429)
		(width 0.10668)
		(layer "F.Cu")
		(net "M_D_CPU1_SA_DQ<7>")
	)
	(segment
		(start 42.73423 -205.410308)
		(end 45.5676 -205.410308)
		(width 0.14478)
		(layer "In4.Cu")
		(net "M_D_CPU1_SA_DQ<7>")
	)
	(segment
		(start 34.78911 -206.260446)
		(end 34.981896 -206.06766)
		(width 0.14478)
		(layer "In4.Cu")
		(net "M_D_CPU1_SA_DQ<7>")
	)
	(segment
		(start 41.884092 -206.260446)
		(end 42.73423 -205.410308)
		(width 0.14478)
		(layer "In4.Cu")
		(net "M_D_CPU1_SA_DQ<7>")
	)
	(segment
		(start 91.85402 -229.581964)
		(end 91.862402 -229.577138)
		(width 0.0889)
		(layer "In4.Cu")
		(net "M_D_CPU1_SA_DQ<7>")
	)
	(segment
		(start 53.256434 -205.410308)
		(end 54.106572 -206.260446)
		(width 0.14478)
		(layer "In4.Cu")
		(net "M_D_CPU1_SA_DQ<7>")
	)
	(segment
		(start 35.64001 -206.06766)
		(end 35.832796 -206.260446)
		(width 0.14478)
		(layer "In4.Cu")
		(net "M_D_CPU1_SA_DQ<7>")
	)
	(segment
		(start 88.094058 -229.581964)
		(end 88.10244 -229.577138)
		(width 0.0889)
		(layer "In4.Cu")
		(net "M_D_CPU1_SA_DQ<7>")
	)
	(segment
		(start 50.222404 -205.410308)
		(end 53.256434 -205.410308)
		(width 0.14478)
		(layer "In4.Cu")
		(net "M_D_CPU1_SA_DQ<7>")
	)
	(segment
		(start 86.57971 -229.577138)
		(end 86.588092 -229.581964)
		(width 0.0889)
		(layer "In4.Cu")
		(net "M_D_CPU1_SA_DQ<7>")
	)
	(segment
		(start 75.564746 -222.850964)
		(end 76.964286 -224.250504)
		(width 0.14478)
		(layer "In4.Cu")
		(net "M_D_CPU1_SA_DQ<7>")
	)
	(segment
		(start 83.394042 -229.581964)
		(end 83.402424 -229.577138)
		(width 0.0889)
		(layer "In4.Cu")
		(net "M_D_CPU1_SA_DQ<7>")
	)
	(segment
		(start 54.106572 -206.260446)
		(end 59.752992 -206.260446)
		(width 0.14478)
		(layer "In4.Cu")
		(net "M_D_CPU1_SA_DQ<7>")
	)
	(segment
		(start 92.195142 -229.63886)
		(end 92.040964 -229.90429)
		(width 0.0889)
		(layer "In4.Cu")
		(net "M_D_CPU1_SA_DQ<7>")
	)
	(segment
		(start 35.174682 -205.627986)
		(end 35.447224 -205.627986)
		(width 0.14478)
		(layer "In4.Cu")
		(net "M_D_CPU1_SA_DQ<7>")
	)
	(segment
		(start 35.832796 -206.260446)
		(end 41.884092 -206.260446)
		(width 0.14478)
		(layer "In4.Cu")
		(net "M_D_CPU1_SA_DQ<7>")
	)
	(segment
		(start 49.372266 -206.260446)
		(end 50.222404 -205.410308)
		(width 0.14478)
		(layer "In4.Cu")
		(net "M_D_CPU1_SA_DQ<7>")
	)
	(segment
		(start 92.173044 -229.555802)
		(end 92.195142 -229.63886)
		(width 0.0889)
		(layer "In4.Cu")
		(net "M_D_CPU1_SA_DQ<7>")
	)
	(segment
		(start 77.89037 -225.488754)
		(end 77.89037 -225.602546)
		(width 0.0889)
		(layer "In4.Cu")
		(net "M_D_CPU1_SA_DQ<7>")
	)
	(segment
		(start 90.339672 -229.577138)
		(end 90.348054 -229.581964)
		(width 0.0889)
		(layer "In4.Cu")
		(net "M_D_CPU1_SA_DQ<7>")
	)
	(segment
		(start 79.9719 -227.94087)
		(end 80.038702 -227.979732)
		(width 0.0889)
		(layer "In4.Cu")
		(net "M_D_CPU1_SA_DQ<7>")
	)
	(segment
		(start 34.981896 -205.820772)
		(end 35.174682 -205.627986)
		(width 0.14478)
		(layer "In4.Cu")
		(net "M_D_CPU1_SA_DQ<7>")
	)
	(segment
		(start 34.516568 -206.260446)
		(end 34.78911 -206.260446)
		(width 0.14478)
		(layer "In4.Cu")
		(net "M_D_CPU1_SA_DQ<7>")
	)
	(segment
		(start 46.417738 -206.260446)
		(end 49.372266 -206.260446)
		(width 0.14478)
		(layer "In4.Cu")
		(net "M_D_CPU1_SA_DQ<7>")
	)
	(segment
		(start 76.964286 -224.250504)
		(end 76.964286 -224.414842)
		(width 0.14478)
		(layer "In4.Cu")
		(net "M_D_CPU1_SA_DQ<7>")
	)
	(segment
		(start 35.447224 -205.627986)
		(end 35.64001 -205.820772)
		(width 0.14478)
		(layer "In4.Cu")
		(net "M_D_CPU1_SA_DQ<7>")
	)
	(segment
		(start 76.964286 -224.414842)
		(end 77.52715 -224.977706)
		(width 0.14478)
		(layer "In4.Cu")
		(net "M_D_CPU1_SA_DQ<7>")
	)
	(segment
		(start 33.121092 -206.260446)
		(end 33.472882 -206.260446)
		(width 0.14478)
		(layer "In4.Cu")
		(net "M_D_CPU1_SA_DQ<7>")
	)
	(segment
		(start 87.154004 -229.581964)
		(end 87.162386 -229.577138)
		(width 0.0889)
		(layer "In4.Cu")
		(net "M_D_CPU1_SA_DQ<7>")
	)
	(segment
		(start 34.323782 -205.60919)
		(end 34.323782 -206.06766)
		(width 0.14478)
		(layer "In4.Cu")
		(net "M_D_CPU1_SA_DQ<7>")
	)
	(segment
		(start 34.981896 -206.06766)
		(end 34.981896 -205.820772)
		(width 0.14478)
		(layer "In4.Cu")
		(net "M_D_CPU1_SA_DQ<7>")
	)
	(segment
		(start 33.858454 -205.416404)
		(end 34.130996 -205.416404)
		(width 0.14478)
		(layer "In4.Cu")
		(net "M_D_CPU1_SA_DQ<7>")
	)
	(segment
		(start 78.051914 -225.99269)
		(end 79.718916 -227.659692)
		(width 0.0889)
		(layer "In4.Cu")
		(net "M_D_CPU1_SA_DQ<7>")
	)
	(segment
		(start 33.472882 -206.260446)
		(end 33.665668 -206.06766)
		(width 0.14478)
		(layer "In4.Cu")
		(net "M_D_CPU1_SA_DQ<7>")
	)
	(segment
		(start 35.64001 -205.820772)
		(end 35.64001 -206.06766)
		(width 0.14478)
		(layer "In4.Cu")
		(net "M_D_CPU1_SA_DQ<7>")
	)
	(segment
		(start 82.453988 -229.581964)
		(end 82.46237 -229.577138)
		(width 0.0889)
		(layer "In4.Cu")
		(net "M_D_CPU1_SA_DQ<7>")
	)
	(segment
		(start 90.913966 -229.581964)
		(end 90.922348 -229.577138)
		(width 0.0889)
		(layer "In4.Cu")
		(net "M_D_CPU1_SA_DQ<7>")
	)
	(segment
		(start 85.639656 -229.577138)
		(end 85.648038 -229.581964)
		(width 0.0889)
		(layer "In4.Cu")
		(net "M_D_CPU1_SA_DQ<7>")
	)
	(segment
		(start 80.439006 -228.749098)
		(end 80.478122 -228.771958)
		(width 0.0889)
		(layer "In4.Cu")
		(net "M_D_CPU1_SA_DQ<7>")
	)
	(segment
		(start 33.665668 -205.60919)
		(end 33.858454 -205.416404)
		(width 0.14478)
		(layer "In4.Cu")
		(net "M_D_CPU1_SA_DQ<7>")
	)
	(segment
		(start 34.323782 -206.06766)
		(end 34.516568 -206.260446)
		(width 0.14478)
		(layer "In4.Cu")
		(net "M_D_CPU1_SA_DQ<7>")
	)
	(segment
		(start 34.130996 -205.416404)
		(end 34.323782 -205.60919)
		(width 0.14478)
		(layer "In4.Cu")
		(net "M_D_CPU1_SA_DQ<7>")
	)
	(segment
		(start 77.52715 -224.977706)
		(end 77.785722 -225.236278)
		(width 0.0889)
		(layer "In4.Cu")
		(net "M_D_CPU1_SA_DQ<7>")
	)
	(segment
		(start 80.9117 -229.560882)
		(end 80.948022 -229.581964)
		(width 0.0889)
		(layer "In4.Cu")
		(net "M_D_CPU1_SA_DQ<7>")
	)
	(segment
		(start 75.564746 -222.0722)
		(end 75.564746 -222.850964)
		(width 0.14478)
		(layer "In4.Cu")
		(net "M_D_CPU1_SA_DQ<7>")
	)
	(segment
		(start 33.665668 -206.06766)
		(end 33.665668 -205.60919)
		(width 0.14478)
		(layer "In4.Cu")
		(net "M_D_CPU1_SA_DQ<7>")
	)
	(segment
		(start 81.879694 -229.577138)
		(end 81.888076 -229.581964)
		(width 0.0889)
		(layer "In4.Cu")
		(net "M_D_CPU1_SA_DQ<7>")
	)
	(segment
		(start 80.478122 -228.771958)
		(end 80.509872 -228.790246)
		(width 0.0889)
		(layer "In4.Cu")
		(net "M_D_CPU1_SA_DQ<7>")
	)
	(segment
		(start 45.5676 -205.410308)
		(end 46.417738 -206.260446)
		(width 0.14478)
		(layer "In4.Cu")
		(net "M_D_CPU1_SA_DQ<7>")
	)
	(segment
		(start 59.752992 -206.260446)
		(end 75.564746 -222.0722)
		(width 0.14478)
		(layer "In4.Cu")
		(net "M_D_CPU1_SA_DQ<7>")
	)
	(segment
		(start 32.695896 -205.83525)
		(end 33.121092 -206.260446)
		(width 0.14478)
		(layer "In4.Cu")
		(net "M_D_CPU1_SA_DQ<7>")
	)
	(arc
		(start 82.82813 -229.581964)
		(mid 83.111086 -229.658141)
		(end 83.394042 -229.581964)
		(width 0.0889)
		(layer "In4.Cu")
		(net "M_D_CPU1_SA_DQ<7>")
	)
	(arc
		(start 83.402424 -229.577138)
		(mid 83.585932 -229.531613)
		(end 83.768184 -229.581964)
		(width 0.0889)
		(layer "In4.Cu")
		(net "M_D_CPU1_SA_DQ<7>")
	)
	(arc
		(start 80.665828 -229.094538)
		(mid 80.731064 -229.358129)
		(end 80.9117 -229.560882)
		(width 0.0889)
		(layer "In4.Cu")
		(net "M_D_CPU1_SA_DQ<7>")
	)
	(arc
		(start 87.528146 -229.581964)
		(mid 87.811102 -229.658141)
		(end 88.094058 -229.581964)
		(width 0.0889)
		(layer "In4.Cu")
		(net "M_D_CPU1_SA_DQ<7>")
	)
	(arc
		(start 84.334096 -229.581964)
		(mid 84.52104 -229.531675)
		(end 84.707984 -229.581964)
		(width 0.0889)
		(layer "In4.Cu")
		(net "M_D_CPU1_SA_DQ<7>")
	)
	(arc
		(start 88.10244 -229.577138)
		(mid 88.285948 -229.531613)
		(end 88.4682 -229.581964)
		(width 0.0889)
		(layer "In4.Cu")
		(net "M_D_CPU1_SA_DQ<7>")
	)
	(arc
		(start 90.922348 -229.577138)
		(mid 91.105856 -229.531613)
		(end 91.288108 -229.581964)
		(width 0.0889)
		(layer "In4.Cu")
		(net "M_D_CPU1_SA_DQ<7>")
	)
	(arc
		(start 77.785722 -225.236278)
		(mid 77.863176 -225.352101)
		(end 77.89037 -225.488754)
		(width 0.0889)
		(layer "In4.Cu")
		(net "M_D_CPU1_SA_DQ<7>")
	)
	(arc
		(start 80.038702 -227.979732)
		(mid 80.154129 -228.113108)
		(end 80.195674 -228.284532)
		(width 0.0889)
		(layer "In4.Cu")
		(net "M_D_CPU1_SA_DQ<7>")
	)
	(arc
		(start 80.195674 -228.284532)
		(mid 80.260189 -228.546751)
		(end 80.439006 -228.749098)
		(width 0.0889)
		(layer "In4.Cu")
		(net "M_D_CPU1_SA_DQ<7>")
	)
	(arc
		(start 89.034112 -229.581964)
		(mid 89.221056 -229.531675)
		(end 89.408 -229.581964)
		(width 0.0889)
		(layer "In4.Cu")
		(net "M_D_CPU1_SA_DQ<7>")
	)
	(arc
		(start 79.718916 -227.659692)
		(mid 79.770286 -227.716905)
		(end 79.815182 -227.779326)
		(width 0.0889)
		(layer "In4.Cu")
		(net "M_D_CPU1_SA_DQ<7>")
	)
	(arc
		(start 80.948022 -229.581964)
		(mid 81.230978 -229.658141)
		(end 81.513934 -229.581964)
		(width 0.0889)
		(layer "In4.Cu")
		(net "M_D_CPU1_SA_DQ<7>")
	)
	(arc
		(start 91.862402 -229.577138)
		(mid 92.01539 -229.532458)
		(end 92.173044 -229.555802)
		(width 0.0889)
		(layer "In4.Cu")
		(net "M_D_CPU1_SA_DQ<7>")
	)
	(arc
		(start 86.588092 -229.581964)
		(mid 86.871048 -229.658141)
		(end 87.154004 -229.581964)
		(width 0.0889)
		(layer "In4.Cu")
		(net "M_D_CPU1_SA_DQ<7>")
	)
	(arc
		(start 79.815182 -227.779326)
		(mid 79.885401 -227.867998)
		(end 79.9719 -227.94087)
		(width 0.0889)
		(layer "In4.Cu")
		(net "M_D_CPU1_SA_DQ<7>")
	)
	(arc
		(start 83.768184 -229.581964)
		(mid 84.05114 -229.658141)
		(end 84.334096 -229.581964)
		(width 0.0889)
		(layer "In4.Cu")
		(net "M_D_CPU1_SA_DQ<7>")
	)
	(arc
		(start 81.513934 -229.581964)
		(mid 81.696185 -229.53158)
		(end 81.879694 -229.577138)
		(width 0.0889)
		(layer "In4.Cu")
		(net "M_D_CPU1_SA_DQ<7>")
	)
	(arc
		(start 91.288108 -229.581964)
		(mid 91.571064 -229.658141)
		(end 91.85402 -229.581964)
		(width 0.0889)
		(layer "In4.Cu")
		(net "M_D_CPU1_SA_DQ<7>")
	)
	(arc
		(start 82.46237 -229.577138)
		(mid 82.645878 -229.531613)
		(end 82.82813 -229.581964)
		(width 0.0889)
		(layer "In4.Cu")
		(net "M_D_CPU1_SA_DQ<7>")
	)
	(arc
		(start 89.408 -229.581964)
		(mid 89.690956 -229.658141)
		(end 89.973912 -229.581964)
		(width 0.0889)
		(layer "In4.Cu")
		(net "M_D_CPU1_SA_DQ<7>")
	)
	(arc
		(start 80.509872 -228.790246)
		(mid 80.624548 -228.92358)
		(end 80.665828 -229.094538)
		(width 0.0889)
		(layer "In4.Cu")
		(net "M_D_CPU1_SA_DQ<7>")
	)
	(arc
		(start 90.348054 -229.581964)
		(mid 90.63101 -229.658141)
		(end 90.913966 -229.581964)
		(width 0.0889)
		(layer "In4.Cu")
		(net "M_D_CPU1_SA_DQ<7>")
	)
	(arc
		(start 88.4682 -229.581964)
		(mid 88.751156 -229.658141)
		(end 89.034112 -229.581964)
		(width 0.0889)
		(layer "In4.Cu")
		(net "M_D_CPU1_SA_DQ<7>")
	)
	(arc
		(start 85.273896 -229.581964)
		(mid 85.456147 -229.53158)
		(end 85.639656 -229.577138)
		(width 0.0889)
		(layer "In4.Cu")
		(net "M_D_CPU1_SA_DQ<7>")
	)
	(arc
		(start 84.707984 -229.581964)
		(mid 84.99094 -229.658141)
		(end 85.273896 -229.581964)
		(width 0.0889)
		(layer "In4.Cu")
		(net "M_D_CPU1_SA_DQ<7>")
	)
	(arc
		(start 86.21395 -229.581964)
		(mid 86.396201 -229.53158)
		(end 86.57971 -229.577138)
		(width 0.0889)
		(layer "In4.Cu")
		(net "M_D_CPU1_SA_DQ<7>")
	)
	(arc
		(start 81.888076 -229.581964)
		(mid 82.171032 -229.658141)
		(end 82.453988 -229.581964)
		(width 0.0889)
		(layer "In4.Cu")
		(net "M_D_CPU1_SA_DQ<7>")
	)
	(arc
		(start 77.89037 -225.602546)
		(mid 77.93235 -225.813682)
		(end 78.051914 -225.99269)
		(width 0.0889)
		(layer "In4.Cu")
		(net "M_D_CPU1_SA_DQ<7>")
	)
	(arc
		(start 89.973912 -229.581964)
		(mid 90.156163 -229.53158)
		(end 90.339672 -229.577138)
		(width 0.0889)
		(layer "In4.Cu")
		(net "M_D_CPU1_SA_DQ<7>")
	)
	(arc
		(start 87.162386 -229.577138)
		(mid 87.345894 -229.531613)
		(end 87.528146 -229.581964)
		(width 0.0889)
		(layer "In4.Cu")
		(net "M_D_CPU1_SA_DQ<7>")
	)
	(arc
		(start 85.648038 -229.581964)
		(mid 85.930994 -229.658141)
		(end 86.21395 -229.581964)
		(width 0.0889)
		(layer "In4.Cu")
		(net "M_D_CPU1_SA_DQ<7>")
	)
	(segment
		(start 91.097862 -229.360476)
		(end 90.63101 -229.094538)
		(width 0.10668)
		(layer "F.Cu")
		(net "M_D_CPU1_SA_DQ<6>")
	)
	(segment
		(start 45.5676 -203.710286)
		(end 46.417738 -204.560424)
		(width 0.14478)
		(layer "In4.Cu")
		(net "M_D_CPU1_SA_DQ<6>")
	)
	(segment
		(start 34.395156 -203.750672)
		(end 34.558224 -203.587604)
		(width 0.14478)
		(layer "In4.Cu")
		(net "M_D_CPU1_SA_DQ<6>")
	)
	(segment
		(start 80.9117 -227.94087)
		(end 80.948022 -227.961952)
		(width 0.0889)
		(layer "In4.Cu")
		(net "M_D_CPU1_SA_DQ<6>")
	)
	(segment
		(start 79.497936 -225.508312)
		(end 79.538322 -225.531934)
		(width 0.0889)
		(layer "In4.Cu")
		(net "M_D_CPU1_SA_DQ<6>")
	)
	(segment
		(start 84.803996 -228.771958)
		(end 84.812378 -228.767132)
		(width 0.0889)
		(layer "In4.Cu")
		(net "M_D_CPU1_SA_DQ<6>")
	)
	(segment
		(start 77.208126 -222.591884)
		(end 77.50683 -222.890588)
		(width 0.0889)
		(layer "In4.Cu")
		(net "M_D_CPU1_SA_DQ<6>")
	)
	(segment
		(start 76.507086 -221.690692)
		(end 76.507086 -222.447104)
		(width 0.14478)
		(layer "In4.Cu")
		(net "M_D_CPU1_SA_DQ<6>")
	)
	(segment
		(start 35.114738 -204.560424)
		(end 35.345116 -204.560424)
		(width 0.14478)
		(layer "In4.Cu")
		(net "M_D_CPU1_SA_DQ<6>")
	)
	(segment
		(start 81.37906 -228.749098)
		(end 81.418176 -228.771958)
		(width 0.0889)
		(layer "In4.Cu")
		(net "M_D_CPU1_SA_DQ<6>")
	)
	(segment
		(start 33.121092 -204.560424)
		(end 34.232088 -204.560424)
		(width 0.14478)
		(layer "In4.Cu")
		(net "M_D_CPU1_SA_DQ<6>")
	)
	(segment
		(start 35.508184 -204.397356)
		(end 35.508184 -203.855574)
		(width 0.14478)
		(layer "In4.Cu")
		(net "M_D_CPU1_SA_DQ<6>")
	)
	(segment
		(start 34.788602 -203.587604)
		(end 34.95167 -203.750672)
		(width 0.14478)
		(layer "In4.Cu")
		(net "M_D_CPU1_SA_DQ<6>")
	)
	(segment
		(start 35.508184 -203.855574)
		(end 35.671252 -203.692506)
		(width 0.14478)
		(layer "In4.Cu")
		(net "M_D_CPU1_SA_DQ<6>")
	)
	(segment
		(start 36.064698 -203.855574)
		(end 36.064698 -204.397356)
		(width 0.14478)
		(layer "In4.Cu")
		(net "M_D_CPU1_SA_DQ<6>")
	)
	(segment
		(start 35.90163 -203.692506)
		(end 36.064698 -203.855574)
		(width 0.14478)
		(layer "In4.Cu")
		(net "M_D_CPU1_SA_DQ<6>")
	)
	(segment
		(start 36.227766 -204.560424)
		(end 41.884092 -204.560424)
		(width 0.14478)
		(layer "In4.Cu")
		(net "M_D_CPU1_SA_DQ<6>")
	)
	(segment
		(start 34.232088 -204.560424)
		(end 34.395156 -204.397356)
		(width 0.14478)
		(layer "In4.Cu")
		(net "M_D_CPU1_SA_DQ<6>")
	)
	(segment
		(start 78.470252 -223.812862)
		(end 78.481428 -223.824038)
		(width 0.0889)
		(layer "In4.Cu")
		(net "M_D_CPU1_SA_DQ<6>")
	)
	(segment
		(start 79.9719 -226.320858)
		(end 80.008222 -226.34194)
		(width 0.0889)
		(layer "In4.Cu")
		(net "M_D_CPU1_SA_DQ<6>")
	)
	(segment
		(start 89.504012 -228.771958)
		(end 89.512394 -228.767132)
		(width 0.0889)
		(layer "In4.Cu")
		(net "M_D_CPU1_SA_DQ<6>")
	)
	(segment
		(start 42.73423 -203.710286)
		(end 45.5676 -203.710286)
		(width 0.14478)
		(layer "In4.Cu")
		(net "M_D_CPU1_SA_DQ<6>")
	)
	(segment
		(start 34.395156 -204.397356)
		(end 34.395156 -203.750672)
		(width 0.14478)
		(layer "In4.Cu")
		(net "M_D_CPU1_SA_DQ<6>")
	)
	(segment
		(start 80.008222 -226.34194)
		(end 80.038702 -226.35972)
		(width 0.0889)
		(layer "In4.Cu")
		(net "M_D_CPU1_SA_DQ<6>")
	)
	(segment
		(start 76.507086 -222.447104)
		(end 76.651866 -222.591884)
		(width 0.14478)
		(layer "In4.Cu")
		(net "M_D_CPU1_SA_DQ<6>")
	)
	(segment
		(start 80.439006 -227.129086)
		(end 80.478122 -227.151946)
		(width 0.0889)
		(layer "In4.Cu")
		(net "M_D_CPU1_SA_DQ<6>")
	)
	(segment
		(start 34.558224 -203.587604)
		(end 34.788602 -203.587604)
		(width 0.14478)
		(layer "In4.Cu")
		(net "M_D_CPU1_SA_DQ<6>")
	)
	(segment
		(start 50.222404 -203.710286)
		(end 53.256434 -203.710286)
		(width 0.14478)
		(layer "In4.Cu")
		(net "M_D_CPU1_SA_DQ<6>")
	)
	(segment
		(start 77.9526 -223.075246)
		(end 77.96022 -223.075246)
		(width 0.0889)
		(layer "In4.Cu")
		(net "M_D_CPU1_SA_DQ<6>")
	)
	(segment
		(start 80.948022 -227.961952)
		(end 80.979772 -227.98024)
		(width 0.0889)
		(layer "In4.Cu")
		(net "M_D_CPU1_SA_DQ<6>")
	)
	(segment
		(start 79.538322 -225.531934)
		(end 79.570072 -225.550222)
		(width 0.0889)
		(layer "In4.Cu")
		(net "M_D_CPU1_SA_DQ<6>")
	)
	(segment
		(start 53.256434 -203.710286)
		(end 54.106572 -204.560424)
		(width 0.14478)
		(layer "In4.Cu")
		(net "M_D_CPU1_SA_DQ<6>")
	)
	(segment
		(start 76.651866 -222.591884)
		(end 77.208126 -222.591884)
		(width 0.14478)
		(layer "In4.Cu")
		(net "M_D_CPU1_SA_DQ<6>")
	)
	(segment
		(start 85.74405 -228.771958)
		(end 85.752432 -228.767132)
		(width 0.0889)
		(layer "In4.Cu")
		(net "M_D_CPU1_SA_DQ<6>")
	)
	(segment
		(start 32.695896 -204.135228)
		(end 33.121092 -204.560424)
		(width 0.14478)
		(layer "In4.Cu")
		(net "M_D_CPU1_SA_DQ<6>")
	)
	(segment
		(start 80.478122 -227.151946)
		(end 80.509872 -227.170234)
		(width 0.0889)
		(layer "In4.Cu")
		(net "M_D_CPU1_SA_DQ<6>")
	)
	(segment
		(start 34.95167 -203.750672)
		(end 34.95167 -204.397356)
		(width 0.14478)
		(layer "In4.Cu")
		(net "M_D_CPU1_SA_DQ<6>")
	)
	(segment
		(start 90.762582 -228.745796)
		(end 90.784934 -228.829108)
		(width 0.0889)
		(layer "In4.Cu")
		(net "M_D_CPU1_SA_DQ<6>")
	)
	(segment
		(start 83.289648 -228.767132)
		(end 83.29803 -228.771958)
		(width 0.0889)
		(layer "In4.Cu")
		(net "M_D_CPU1_SA_DQ<6>")
	)
	(segment
		(start 49.372266 -204.560424)
		(end 50.222404 -203.710286)
		(width 0.14478)
		(layer "In4.Cu")
		(net "M_D_CPU1_SA_DQ<6>")
	)
	(segment
		(start 36.064698 -204.397356)
		(end 36.227766 -204.560424)
		(width 0.14478)
		(layer "In4.Cu")
		(net "M_D_CPU1_SA_DQ<6>")
	)
	(segment
		(start 35.671252 -203.692506)
		(end 35.90163 -203.692506)
		(width 0.14478)
		(layer "In4.Cu")
		(net "M_D_CPU1_SA_DQ<6>")
	)
	(segment
		(start 79.068422 -224.721928)
		(end 79.097886 -224.738946)
		(width 0.0889)
		(layer "In4.Cu")
		(net "M_D_CPU1_SA_DQ<6>")
	)
	(segment
		(start 84.229702 -228.767132)
		(end 84.238084 -228.771958)
		(width 0.0889)
		(layer "In4.Cu")
		(net "M_D_CPU1_SA_DQ<6>")
	)
	(segment
		(start 90.784934 -228.829108)
		(end 90.63101 -229.094538)
		(width 0.0889)
		(layer "In4.Cu")
		(net "M_D_CPU1_SA_DQ<6>")
	)
	(segment
		(start 79.028036 -224.698306)
		(end 79.068422 -224.721928)
		(width 0.0889)
		(layer "In4.Cu")
		(net "M_D_CPU1_SA_DQ<6>")
	)
	(segment
		(start 35.345116 -204.560424)
		(end 35.508184 -204.397356)
		(width 0.14478)
		(layer "In4.Cu")
		(net "M_D_CPU1_SA_DQ<6>")
	)
	(segment
		(start 88.929718 -228.767132)
		(end 88.9381 -228.771958)
		(width 0.0889)
		(layer "In4.Cu")
		(net "M_D_CPU1_SA_DQ<6>")
	)
	(segment
		(start 78.56474 -223.892618)
		(end 78.631796 -223.93148)
		(width 0.0889)
		(layer "In4.Cu")
		(net "M_D_CPU1_SA_DQ<6>")
	)
	(segment
		(start 59.376818 -204.560424)
		(end 76.507086 -221.690692)
		(width 0.14478)
		(layer "In4.Cu")
		(net "M_D_CPU1_SA_DQ<6>")
	)
	(segment
		(start 54.106572 -204.560424)
		(end 59.376818 -204.560424)
		(width 0.14478)
		(layer "In4.Cu")
		(net "M_D_CPU1_SA_DQ<6>")
	)
	(segment
		(start 46.417738 -204.560424)
		(end 49.372266 -204.560424)
		(width 0.14478)
		(layer "In4.Cu")
		(net "M_D_CPU1_SA_DQ<6>")
	)
	(segment
		(start 41.884092 -204.560424)
		(end 42.73423 -203.710286)
		(width 0.14478)
		(layer "In4.Cu")
		(net "M_D_CPU1_SA_DQ<6>")
	)
	(segment
		(start 34.95167 -204.397356)
		(end 35.114738 -204.560424)
		(width 0.14478)
		(layer "In4.Cu")
		(net "M_D_CPU1_SA_DQ<6>")
	)
	(segment
		(start 87.989664 -228.767132)
		(end 87.998046 -228.771958)
		(width 0.0889)
		(layer "In4.Cu")
		(net "M_D_CPU1_SA_DQ<6>")
	)
	(arc
		(start 80.195674 -226.66452)
		(mid 80.260189 -226.926739)
		(end 80.439006 -227.129086)
		(width 0.0889)
		(layer "In4.Cu")
		(net "M_D_CPU1_SA_DQ<6>")
	)
	(arc
		(start 90.444066 -228.771958)
		(mid 90.600385 -228.722963)
		(end 90.762582 -228.745796)
		(width 0.0889)
		(layer "In4.Cu")
		(net "M_D_CPU1_SA_DQ<6>")
	)
	(arc
		(start 89.512394 -228.767132)
		(mid 89.695902 -228.721638)
		(end 89.878154 -228.771958)
		(width 0.0889)
		(layer "In4.Cu")
		(net "M_D_CPU1_SA_DQ<6>")
	)
	(arc
		(start 87.057992 -228.771958)
		(mid 87.340948 -228.848135)
		(end 87.623904 -228.771958)
		(width 0.0889)
		(layer "In4.Cu")
		(net "M_D_CPU1_SA_DQ<6>")
	)
	(arc
		(start 78.631796 -223.93148)
		(mid 78.745203 -224.06451)
		(end 78.785974 -224.234502)
		(width 0.0889)
		(layer "In4.Cu")
		(net "M_D_CPU1_SA_DQ<6>")
	)
	(arc
		(start 78.481428 -223.824038)
		(mid 78.52144 -223.860325)
		(end 78.56474 -223.892618)
		(width 0.0889)
		(layer "In4.Cu")
		(net "M_D_CPU1_SA_DQ<6>")
	)
	(arc
		(start 87.998046 -228.771958)
		(mid 88.281002 -228.848135)
		(end 88.563958 -228.771958)
		(width 0.0889)
		(layer "In4.Cu")
		(net "M_D_CPU1_SA_DQ<6>")
	)
	(arc
		(start 86.684104 -228.771958)
		(mid 86.871048 -228.721703)
		(end 87.057992 -228.771958)
		(width 0.0889)
		(layer "In4.Cu")
		(net "M_D_CPU1_SA_DQ<6>")
	)
	(arc
		(start 81.135728 -228.284532)
		(mid 81.200243 -228.546751)
		(end 81.37906 -228.749098)
		(width 0.0889)
		(layer "In4.Cu")
		(net "M_D_CPU1_SA_DQ<6>")
	)
	(arc
		(start 83.29803 -228.771958)
		(mid 83.580986 -228.848135)
		(end 83.863942 -228.771958)
		(width 0.0889)
		(layer "In4.Cu")
		(net "M_D_CPU1_SA_DQ<6>")
	)
	(arc
		(start 86.118192 -228.771958)
		(mid 86.401148 -228.848135)
		(end 86.684104 -228.771958)
		(width 0.0889)
		(layer "In4.Cu")
		(net "M_D_CPU1_SA_DQ<6>")
	)
	(arc
		(start 81.418176 -228.771958)
		(mid 81.701132 -228.848135)
		(end 81.984088 -228.771958)
		(width 0.0889)
		(layer "In4.Cu")
		(net "M_D_CPU1_SA_DQ<6>")
	)
	(arc
		(start 85.752432 -228.767132)
		(mid 85.93594 -228.721638)
		(end 86.118192 -228.771958)
		(width 0.0889)
		(layer "In4.Cu")
		(net "M_D_CPU1_SA_DQ<6>")
	)
	(arc
		(start 78.785974 -224.234502)
		(mid 78.850127 -224.496091)
		(end 79.028036 -224.698306)
		(width 0.0889)
		(layer "In4.Cu")
		(net "M_D_CPU1_SA_DQ<6>")
	)
	(arc
		(start 89.878154 -228.771958)
		(mid 90.16111 -228.848135)
		(end 90.444066 -228.771958)
		(width 0.0889)
		(layer "In4.Cu")
		(net "M_D_CPU1_SA_DQ<6>")
	)
	(arc
		(start 77.96022 -223.075246)
		(mid 78.207177 -223.177539)
		(end 78.30947 -223.424496)
		(width 0.0889)
		(layer "In4.Cu")
		(net "M_D_CPU1_SA_DQ<6>")
	)
	(arc
		(start 80.979772 -227.98024)
		(mid 81.094448 -228.113574)
		(end 81.135728 -228.284532)
		(width 0.0889)
		(layer "In4.Cu")
		(net "M_D_CPU1_SA_DQ<6>")
	)
	(arc
		(start 88.563958 -228.771958)
		(mid 88.746209 -228.721608)
		(end 88.929718 -228.767132)
		(width 0.0889)
		(layer "In4.Cu")
		(net "M_D_CPU1_SA_DQ<6>")
	)
	(arc
		(start 84.812378 -228.767132)
		(mid 84.995886 -228.721638)
		(end 85.178138 -228.771958)
		(width 0.0889)
		(layer "In4.Cu")
		(net "M_D_CPU1_SA_DQ<6>")
	)
	(arc
		(start 82.357976 -228.771958)
		(mid 82.640932 -228.848135)
		(end 82.923888 -228.771958)
		(width 0.0889)
		(layer "In4.Cu")
		(net "M_D_CPU1_SA_DQ<6>")
	)
	(arc
		(start 79.570072 -225.550222)
		(mid 79.684748 -225.683556)
		(end 79.726028 -225.854514)
		(width 0.0889)
		(layer "In4.Cu")
		(net "M_D_CPU1_SA_DQ<6>")
	)
	(arc
		(start 83.863942 -228.771958)
		(mid 84.046193 -228.721608)
		(end 84.229702 -228.767132)
		(width 0.0889)
		(layer "In4.Cu")
		(net "M_D_CPU1_SA_DQ<6>")
	)
	(arc
		(start 85.178138 -228.771958)
		(mid 85.461094 -228.848135)
		(end 85.74405 -228.771958)
		(width 0.0889)
		(layer "In4.Cu")
		(net "M_D_CPU1_SA_DQ<6>")
	)
	(arc
		(start 77.50683 -222.890588)
		(mid 77.711351 -223.027245)
		(end 77.9526 -223.075246)
		(width 0.0889)
		(layer "In4.Cu")
		(net "M_D_CPU1_SA_DQ<6>")
	)
	(arc
		(start 80.509872 -227.170234)
		(mid 80.624548 -227.303568)
		(end 80.665828 -227.474526)
		(width 0.0889)
		(layer "In4.Cu")
		(net "M_D_CPU1_SA_DQ<6>")
	)
	(arc
		(start 87.623904 -228.771958)
		(mid 87.806155 -228.721608)
		(end 87.989664 -228.767132)
		(width 0.0889)
		(layer "In4.Cu")
		(net "M_D_CPU1_SA_DQ<6>")
	)
	(arc
		(start 88.9381 -228.771958)
		(mid 89.221056 -228.848135)
		(end 89.504012 -228.771958)
		(width 0.0889)
		(layer "In4.Cu")
		(net "M_D_CPU1_SA_DQ<6>")
	)
	(arc
		(start 79.726028 -225.854514)
		(mid 79.791264 -226.118105)
		(end 79.9719 -226.320858)
		(width 0.0889)
		(layer "In4.Cu")
		(net "M_D_CPU1_SA_DQ<6>")
	)
	(arc
		(start 79.25562 -225.044508)
		(mid 79.319913 -225.306113)
		(end 79.497936 -225.508312)
		(width 0.0889)
		(layer "In4.Cu")
		(net "M_D_CPU1_SA_DQ<6>")
	)
	(arc
		(start 79.097886 -224.738946)
		(mid 79.213839 -224.872579)
		(end 79.25562 -225.044508)
		(width 0.0889)
		(layer "In4.Cu")
		(net "M_D_CPU1_SA_DQ<6>")
	)
	(arc
		(start 84.238084 -228.771958)
		(mid 84.52104 -228.848135)
		(end 84.803996 -228.771958)
		(width 0.0889)
		(layer "In4.Cu")
		(net "M_D_CPU1_SA_DQ<6>")
	)
	(arc
		(start 80.665828 -227.474526)
		(mid 80.731064 -227.738117)
		(end 80.9117 -227.94087)
		(width 0.0889)
		(layer "In4.Cu")
		(net "M_D_CPU1_SA_DQ<6>")
	)
	(arc
		(start 81.984088 -228.771958)
		(mid 82.171032 -228.721703)
		(end 82.357976 -228.771958)
		(width 0.0889)
		(layer "In4.Cu")
		(net "M_D_CPU1_SA_DQ<6>")
	)
	(arc
		(start 80.038702 -226.35972)
		(mid 80.154129 -226.493096)
		(end 80.195674 -226.66452)
		(width 0.0889)
		(layer "In4.Cu")
		(net "M_D_CPU1_SA_DQ<6>")
	)
	(arc
		(start 78.30947 -223.424496)
		(mid 78.351256 -223.63466)
		(end 78.470252 -223.812862)
		(width 0.0889)
		(layer "In4.Cu")
		(net "M_D_CPU1_SA_DQ<6>")
	)
	(arc
		(start 82.923888 -228.771958)
		(mid 83.106139 -228.721608)
		(end 83.289648 -228.767132)
		(width 0.0889)
		(layer "In4.Cu")
		(net "M_D_CPU1_SA_DQ<6>")
	)
	(segment
		(start 92.97797 -229.360476)
		(end 92.511118 -229.094538)
		(width 0.10668)
		(layer "F.Cu")
		(net "M_D_CPU1_SA_DQ<5>")
	)
	(segment
		(start 88.929718 -229.42169)
		(end 88.9381 -229.416864)
		(width 0.0889)
		(layer "In4.Cu")
		(net "M_D_CPU1_SA_DQ<5>")
	)
	(segment
		(start 50.256694 -204.560424)
		(end 50.54727 -204.560424)
		(width 0.14478)
		(layer "In4.Cu")
		(net "M_D_CPU1_SA_DQ<5>")
	)
	(segment
		(start 43.52163 -204.943964)
		(end 43.684698 -204.780896)
		(width 0.14478)
		(layer "In4.Cu")
		(net "M_D_CPU1_SA_DQ<5>")
	)
	(segment
		(start 39.468552 -205.188312)
		(end 39.468552 -205.24724)
		(width 0.14478)
		(layer "In4.Cu")
		(net "M_D_CPU1_SA_DQ<5>")
	)
	(segment
		(start 80.0735 -227.779326)
		(end 80.10398 -227.797106)
		(width 0.0889)
		(layer "In4.Cu")
		(net "M_D_CPU1_SA_DQ<5>")
	)
	(segment
		(start 43.128184 -204.723492)
		(end 43.128184 -204.780896)
		(width 0.14478)
		(layer "In4.Cu")
		(net "M_D_CPU1_SA_DQ<5>")
	)
	(segment
		(start 50.873406 -204.949044)
		(end 51.103784 -204.949044)
		(width 0.14478)
		(layer "In4.Cu")
		(net "M_D_CPU1_SA_DQ<5>")
	)
	(segment
		(start 58.744866 -205.808326)
		(end 58.90641 -205.646782)
		(width 0.14478)
		(layer "In4.Cu")
		(net "M_D_CPU1_SA_DQ<5>")
	)
	(segment
		(start 41.486836 -205.573376)
		(end 41.649904 -205.410308)
		(width 0.14478)
		(layer "In4.Cu")
		(net "M_D_CPU1_SA_DQ<5>")
	)
	(segment
		(start 37.635942 -205.410308)
		(end 37.79901 -205.24724)
		(width 0.14478)
		(layer "In4.Cu")
		(net "M_D_CPU1_SA_DQ<5>")
	)
	(segment
		(start 48.461168 -205.573376)
		(end 48.461168 -205.639416)
		(width 0.14478)
		(layer "In4.Cu")
		(net "M_D_CPU1_SA_DQ<5>")
	)
	(segment
		(start 57.413652 -205.808326)
		(end 57.641998 -205.808326)
		(width 0.14478)
		(layer "In4.Cu")
		(net "M_D_CPU1_SA_DQ<5>")
	)
	(segment
		(start 38.912038 -205.188312)
		(end 39.075106 -205.025244)
		(width 0.14478)
		(layer "In4.Cu")
		(net "M_D_CPU1_SA_DQ<5>")
	)
	(segment
		(start 40.930322 -205.573376)
		(end 40.930322 -205.639416)
		(width 0.14478)
		(layer "In4.Cu")
		(net "M_D_CPU1_SA_DQ<5>")
	)
	(segment
		(start 92.35694 -229.359968)
		(end 92.511118 -229.094538)
		(width 0.0889)
		(layer "In4.Cu")
		(net "M_D_CPU1_SA_DQ<5>")
	)
	(segment
		(start 78.664562 -225.35007)
		(end 78.694026 -225.367088)
		(width 0.0889)
		(layer "In4.Cu")
		(net "M_D_CPU1_SA_DQ<5>")
	)
	(segment
		(start 57.252108 -205.571852)
		(end 57.252108 -205.646782)
		(width 0.14478)
		(layer "In4.Cu")
		(net "M_D_CPU1_SA_DQ<5>")
	)
	(segment
		(start 41.88333 -205.410308)
		(end 42.733214 -204.560424)
		(width 0.14478)
		(layer "In4.Cu")
		(net "M_D_CPU1_SA_DQ<5>")
	)
	(segment
		(start 80.542384 -228.588824)
		(end 80.574134 -228.607112)
		(width 0.0889)
		(layer "In4.Cu")
		(net "M_D_CPU1_SA_DQ<5>")
	)
	(segment
		(start 38.912038 -205.632304)
		(end 38.912038 -205.188312)
		(width 0.14478)
		(layer "In4.Cu")
		(net "M_D_CPU1_SA_DQ<5>")
	)
	(segment
		(start 50.54727 -204.560424)
		(end 50.710338 -204.723492)
		(width 0.14478)
		(layer "In4.Cu")
		(net "M_D_CPU1_SA_DQ<5>")
	)
	(segment
		(start 91.749626 -229.42169)
		(end 91.758008 -229.416864)
		(width 0.0889)
		(layer "In4.Cu")
		(net "M_D_CPU1_SA_DQ<5>")
	)
	(segment
		(start 39.63162 -205.410308)
		(end 40.767254 -205.410308)
		(width 0.14478)
		(layer "In4.Cu")
		(net "M_D_CPU1_SA_DQ<5>")
	)
	(segment
		(start 54.084474 -205.410308)
		(end 54.684422 -205.410308)
		(width 0.14478)
		(layer "In4.Cu")
		(net "M_D_CPU1_SA_DQ<5>")
	)
	(segment
		(start 41.09339 -205.802484)
		(end 41.323768 -205.802484)
		(width 0.14478)
		(layer "In4.Cu")
		(net "M_D_CPU1_SA_DQ<5>")
	)
	(segment
		(start 38.355524 -205.632304)
		(end 38.518592 -205.795372)
		(width 0.14478)
		(layer "In4.Cu")
		(net "M_D_CPU1_SA_DQ<5>")
	)
	(segment
		(start 39.468552 -205.24724)
		(end 39.63162 -205.410308)
		(width 0.14478)
		(layer "In4.Cu")
		(net "M_D_CPU1_SA_DQ<5>")
	)
	(segment
		(start 48.624236 -205.802484)
		(end 48.854614 -205.802484)
		(width 0.14478)
		(layer "In4.Cu")
		(net "M_D_CPU1_SA_DQ<5>")
	)
	(segment
		(start 49.017682 -205.573376)
		(end 49.18075 -205.410308)
		(width 0.14478)
		(layer "In4.Cu")
		(net "M_D_CPU1_SA_DQ<5>")
	)
	(segment
		(start 58.51652 -205.808326)
		(end 58.744866 -205.808326)
		(width 0.14478)
		(layer "In4.Cu")
		(net "M_D_CPU1_SA_DQ<5>")
	)
	(segment
		(start 42.965116 -204.560424)
		(end 43.128184 -204.723492)
		(width 0.14478)
		(layer "In4.Cu")
		(net "M_D_CPU1_SA_DQ<5>")
	)
	(segment
		(start 89.504012 -229.416864)
		(end 89.512394 -229.42169)
		(width 0.0889)
		(layer "In4.Cu")
		(net "M_D_CPU1_SA_DQ<5>")
	)
	(segment
		(start 77.477874 -223.487996)
		(end 77.714856 -223.724978)
		(width 0.0889)
		(layer "In4.Cu")
		(net "M_D_CPU1_SA_DQ<5>")
	)
	(segment
		(start 50.710338 -204.785976)
		(end 50.873406 -204.949044)
		(width 0.14478)
		(layer "In4.Cu")
		(net "M_D_CPU1_SA_DQ<5>")
	)
	(segment
		(start 80.10398 -227.797106)
		(end 80.143096 -227.819966)
		(width 0.0889)
		(layer "In4.Cu")
		(net "M_D_CPU1_SA_DQ<5>")
	)
	(segment
		(start 38.74897 -205.795372)
		(end 38.912038 -205.632304)
		(width 0.14478)
		(layer "In4.Cu")
		(net "M_D_CPU1_SA_DQ<5>")
	)
	(segment
		(start 55.960518 -205.629256)
		(end 56.123586 -205.792324)
		(width 0.14478)
		(layer "In4.Cu")
		(net "M_D_CPU1_SA_DQ<5>")
	)
	(segment
		(start 59.590686 -205.410308)
		(end 76.029566 -221.849188)
		(width 0.14478)
		(layer "In4.Cu")
		(net "M_D_CPU1_SA_DQ<5>")
	)
	(segment
		(start 76.425806 -223.046544)
		(end 76.964286 -223.046544)
		(width 0.14478)
		(layer "In4.Cu")
		(net "M_D_CPU1_SA_DQ<5>")
	)
	(segment
		(start 56.6801 -205.410308)
		(end 57.090564 -205.410308)
		(width 0.14478)
		(layer "In4.Cu")
		(net "M_D_CPU1_SA_DQ<5>")
	)
	(segment
		(start 84.803996 -229.416864)
		(end 84.812378 -229.42169)
		(width 0.0889)
		(layer "In4.Cu")
		(net "M_D_CPU1_SA_DQ<5>")
	)
	(segment
		(start 76.964286 -223.046544)
		(end 77.180948 -223.046544)
		(width 0.0889)
		(layer "In4.Cu")
		(net "M_D_CPU1_SA_DQ<5>")
	)
	(segment
		(start 85.74405 -229.416864)
		(end 85.752432 -229.42169)
		(width 0.0889)
		(layer "In4.Cu")
		(net "M_D_CPU1_SA_DQ<5>")
	)
	(segment
		(start 58.90641 -205.646782)
		(end 58.90641 -205.571852)
		(width 0.14478)
		(layer "In4.Cu")
		(net "M_D_CPU1_SA_DQ<5>")
	)
	(segment
		(start 77.714856 -223.724978)
		(end 77.75448 -223.747838)
		(width 0.0889)
		(layer "In4.Cu")
		(net "M_D_CPU1_SA_DQ<5>")
	)
	(segment
		(start 56.517032 -205.629256)
		(end 56.517032 -205.573376)
		(width 0.14478)
		(layer "In4.Cu")
		(net "M_D_CPU1_SA_DQ<5>")
	)
	(segment
		(start 79.63408 -226.987354)
		(end 79.669386 -227.007928)
		(width 0.0889)
		(layer "In4.Cu")
		(net "M_D_CPU1_SA_DQ<5>")
	)
	(segment
		(start 80.574134 -228.607112)
		(end 80.610456 -228.628194)
		(width 0.0889)
		(layer "In4.Cu")
		(net "M_D_CPU1_SA_DQ<5>")
	)
	(segment
		(start 45.55871 -204.560424)
		(end 46.408594 -205.410308)
		(width 0.14478)
		(layer "In4.Cu")
		(net "M_D_CPU1_SA_DQ<5>")
	)
	(segment
		(start 56.123586 -205.792324)
		(end 56.353964 -205.792324)
		(width 0.14478)
		(layer "In4.Cu")
		(net "M_D_CPU1_SA_DQ<5>")
	)
	(segment
		(start 48.854614 -205.802484)
		(end 49.017682 -205.639416)
		(width 0.14478)
		(layer "In4.Cu")
		(net "M_D_CPU1_SA_DQ<5>")
	)
	(segment
		(start 55.404004 -205.573376)
		(end 55.567072 -205.410308)
		(width 0.14478)
		(layer "In4.Cu")
		(net "M_D_CPU1_SA_DQ<5>")
	)
	(segment
		(start 40.767254 -205.410308)
		(end 40.930322 -205.573376)
		(width 0.14478)
		(layer "In4.Cu")
		(net "M_D_CPU1_SA_DQ<5>")
	)
	(segment
		(start 81.010506 -229.397306)
		(end 81.044034 -229.416864)
		(width 0.0889)
		(layer "In4.Cu")
		(net "M_D_CPU1_SA_DQ<5>")
	)
	(segment
		(start 78.19644 -224.541588)
		(end 78.224126 -224.55759)
		(width 0.0889)
		(layer "In4.Cu")
		(net "M_D_CPU1_SA_DQ<5>")
	)
	(segment
		(start 56.353964 -205.792324)
		(end 56.517032 -205.629256)
		(width 0.14478)
		(layer "In4.Cu")
		(net "M_D_CPU1_SA_DQ<5>")
	)
	(segment
		(start 57.803542 -205.36789)
		(end 57.965086 -205.206346)
		(width 0.14478)
		(layer "In4.Cu")
		(net "M_D_CPU1_SA_DQ<5>")
	)
	(segment
		(start 41.649904 -205.410308)
		(end 41.88333 -205.410308)
		(width 0.14478)
		(layer "In4.Cu")
		(net "M_D_CPU1_SA_DQ<5>")
	)
	(segment
		(start 50.710338 -204.723492)
		(end 50.710338 -204.785976)
		(width 0.14478)
		(layer "In4.Cu")
		(net "M_D_CPU1_SA_DQ<5>")
	)
	(segment
		(start 55.404004 -205.629256)
		(end 55.404004 -205.573376)
		(width 0.14478)
		(layer "In4.Cu")
		(net "M_D_CPU1_SA_DQ<5>")
	)
	(segment
		(start 38.355524 -205.188312)
		(end 38.355524 -205.632304)
		(width 0.14478)
		(layer "In4.Cu")
		(net "M_D_CPU1_SA_DQ<5>")
	)
	(segment
		(start 57.641998 -205.808326)
		(end 57.803542 -205.646782)
		(width 0.14478)
		(layer "In4.Cu")
		(net "M_D_CPU1_SA_DQ<5>")
	)
	(segment
		(start 76.029566 -222.650304)
		(end 76.425806 -223.046544)
		(width 0.14478)
		(layer "In4.Cu")
		(net "M_D_CPU1_SA_DQ<5>")
	)
	(segment
		(start 83.289648 -229.42169)
		(end 83.29803 -229.416864)
		(width 0.0889)
		(layer "In4.Cu")
		(net "M_D_CPU1_SA_DQ<5>")
	)
	(segment
		(start 79.606902 -226.971606)
		(end 79.63408 -226.987354)
		(width 0.0889)
		(layer "In4.Cu")
		(net "M_D_CPU1_SA_DQ<5>")
	)
	(segment
		(start 37.79901 -205.24724)
		(end 37.79901 -205.188312)
		(width 0.14478)
		(layer "In4.Cu")
		(net "M_D_CPU1_SA_DQ<5>")
	)
	(segment
		(start 38.518592 -205.795372)
		(end 38.74897 -205.795372)
		(width 0.14478)
		(layer "In4.Cu")
		(net "M_D_CPU1_SA_DQ<5>")
	)
	(segment
		(start 77.180948 -223.046544)
		(end 77.375766 -223.241362)
		(width 0.0889)
		(layer "In4.Cu")
		(net "M_D_CPU1_SA_DQ<5>")
	)
	(segment
		(start 78.224126 -224.55759)
		(end 78.251558 -224.573592)
		(width 0.0889)
		(layer "In4.Cu")
		(net "M_D_CPU1_SA_DQ<5>")
	)
	(segment
		(start 58.90641 -205.571852)
		(end 59.067954 -205.410308)
		(width 0.14478)
		(layer "In4.Cu")
		(net "M_D_CPU1_SA_DQ<5>")
	)
	(segment
		(start 57.252108 -205.646782)
		(end 57.413652 -205.808326)
		(width 0.14478)
		(layer "In4.Cu")
		(net "M_D_CPU1_SA_DQ<5>")
	)
	(segment
		(start 43.684698 -204.723492)
		(end 43.847766 -204.560424)
		(width 0.14478)
		(layer "In4.Cu")
		(net "M_D_CPU1_SA_DQ<5>")
	)
	(segment
		(start 41.323768 -205.802484)
		(end 41.486836 -205.639416)
		(width 0.14478)
		(layer "In4.Cu")
		(net "M_D_CPU1_SA_DQ<5>")
	)
	(segment
		(start 84.229702 -229.42169)
		(end 84.238084 -229.416864)
		(width 0.0889)
		(layer "In4.Cu")
		(net "M_D_CPU1_SA_DQ<5>")
	)
	(segment
		(start 41.486836 -205.639416)
		(end 41.486836 -205.573376)
		(width 0.14478)
		(layer "In4.Cu")
		(net "M_D_CPU1_SA_DQ<5>")
	)
	(segment
		(start 55.567072 -205.410308)
		(end 55.79745 -205.410308)
		(width 0.14478)
		(layer "In4.Cu")
		(net "M_D_CPU1_SA_DQ<5>")
	)
	(segment
		(start 39.075106 -205.025244)
		(end 39.305484 -205.025244)
		(width 0.14478)
		(layer "In4.Cu")
		(net "M_D_CPU1_SA_DQ<5>")
	)
	(segment
		(start 53.23459 -204.560424)
		(end 54.084474 -205.410308)
		(width 0.14478)
		(layer "In4.Cu")
		(net "M_D_CPU1_SA_DQ<5>")
	)
	(segment
		(start 49.18075 -205.410308)
		(end 49.40681 -205.410308)
		(width 0.14478)
		(layer "In4.Cu")
		(net "M_D_CPU1_SA_DQ<5>")
	)
	(segment
		(start 76.029566 -221.849188)
		(end 76.029566 -222.650304)
		(width 0.14478)
		(layer "In4.Cu")
		(net "M_D_CPU1_SA_DQ<5>")
	)
	(segment
		(start 49.40681 -205.410308)
		(end 50.256694 -204.560424)
		(width 0.14478)
		(layer "In4.Cu")
		(net "M_D_CPU1_SA_DQ<5>")
	)
	(segment
		(start 58.354976 -205.646782)
		(end 58.51652 -205.808326)
		(width 0.14478)
		(layer "In4.Cu")
		(net "M_D_CPU1_SA_DQ<5>")
	)
	(segment
		(start 37.962078 -205.025244)
		(end 38.192456 -205.025244)
		(width 0.14478)
		(layer "In4.Cu")
		(net "M_D_CPU1_SA_DQ<5>")
	)
	(segment
		(start 55.010558 -205.792324)
		(end 55.240936 -205.792324)
		(width 0.14478)
		(layer "In4.Cu")
		(net "M_D_CPU1_SA_DQ<5>")
	)
	(segment
		(start 37.220906 -205.410308)
		(end 37.635942 -205.410308)
		(width 0.14478)
		(layer "In4.Cu")
		(net "M_D_CPU1_SA_DQ<5>")
	)
	(segment
		(start 51.42992 -204.560424)
		(end 53.23459 -204.560424)
		(width 0.14478)
		(layer "In4.Cu")
		(net "M_D_CPU1_SA_DQ<5>")
	)
	(segment
		(start 43.128184 -204.780896)
		(end 43.291252 -204.943964)
		(width 0.14478)
		(layer "In4.Cu")
		(net "M_D_CPU1_SA_DQ<5>")
	)
	(segment
		(start 59.067954 -205.410308)
		(end 59.590686 -205.410308)
		(width 0.14478)
		(layer "In4.Cu")
		(net "M_D_CPU1_SA_DQ<5>")
	)
	(segment
		(start 48.2981 -205.410308)
		(end 48.461168 -205.573376)
		(width 0.14478)
		(layer "In4.Cu")
		(net "M_D_CPU1_SA_DQ<5>")
	)
	(segment
		(start 79.164434 -226.177856)
		(end 79.200756 -226.198938)
		(width 0.0889)
		(layer "In4.Cu")
		(net "M_D_CPU1_SA_DQ<5>")
	)
	(segment
		(start 51.266852 -204.723492)
		(end 51.42992 -204.560424)
		(width 0.14478)
		(layer "In4.Cu")
		(net "M_D_CPU1_SA_DQ<5>")
	)
	(segment
		(start 58.354976 -205.36789)
		(end 58.354976 -205.646782)
		(width 0.14478)
		(layer "In4.Cu")
		(net "M_D_CPU1_SA_DQ<5>")
	)
	(segment
		(start 38.192456 -205.025244)
		(end 38.355524 -205.188312)
		(width 0.14478)
		(layer "In4.Cu")
		(net "M_D_CPU1_SA_DQ<5>")
	)
	(segment
		(start 43.291252 -204.943964)
		(end 43.52163 -204.943964)
		(width 0.14478)
		(layer "In4.Cu")
		(net "M_D_CPU1_SA_DQ<5>")
	)
	(segment
		(start 51.103784 -204.949044)
		(end 51.266852 -204.785976)
		(width 0.14478)
		(layer "In4.Cu")
		(net "M_D_CPU1_SA_DQ<5>")
	)
	(segment
		(start 81.044034 -229.416864)
		(end 81.052416 -229.42169)
		(width 0.0889)
		(layer "In4.Cu")
		(net "M_D_CPU1_SA_DQ<5>")
	)
	(segment
		(start 57.090564 -205.410308)
		(end 57.252108 -205.571852)
		(width 0.14478)
		(layer "In4.Cu")
		(net "M_D_CPU1_SA_DQ<5>")
	)
	(segment
		(start 79.128874 -226.157282)
		(end 79.164434 -226.177856)
		(width 0.0889)
		(layer "In4.Cu")
		(net "M_D_CPU1_SA_DQ<5>")
	)
	(segment
		(start 87.989664 -229.42169)
		(end 87.998046 -229.416864)
		(width 0.0889)
		(layer "In4.Cu")
		(net "M_D_CPU1_SA_DQ<5>")
	)
	(segment
		(start 36.795964 -204.985366)
		(end 37.220906 -205.410308)
		(width 0.14478)
		(layer "In4.Cu")
		(net "M_D_CPU1_SA_DQ<5>")
	)
	(segment
		(start 54.84749 -205.573376)
		(end 54.84749 -205.629256)
		(width 0.14478)
		(layer "In4.Cu")
		(net "M_D_CPU1_SA_DQ<5>")
	)
	(segment
		(start 48.461168 -205.639416)
		(end 48.624236 -205.802484)
		(width 0.14478)
		(layer "In4.Cu")
		(net "M_D_CPU1_SA_DQ<5>")
	)
	(segment
		(start 58.193432 -205.206346)
		(end 58.354976 -205.36789)
		(width 0.14478)
		(layer "In4.Cu")
		(net "M_D_CPU1_SA_DQ<5>")
	)
	(segment
		(start 57.803542 -205.646782)
		(end 57.803542 -205.36789)
		(width 0.14478)
		(layer "In4.Cu")
		(net "M_D_CPU1_SA_DQ<5>")
	)
	(segment
		(start 56.517032 -205.573376)
		(end 56.6801 -205.410308)
		(width 0.14478)
		(layer "In4.Cu")
		(net "M_D_CPU1_SA_DQ<5>")
	)
	(segment
		(start 40.930322 -205.639416)
		(end 41.09339 -205.802484)
		(width 0.14478)
		(layer "In4.Cu")
		(net "M_D_CPU1_SA_DQ<5>")
	)
	(segment
		(start 92.261182 -229.385368)
		(end 92.35694 -229.359968)
		(width 0.0889)
		(layer "In4.Cu")
		(net "M_D_CPU1_SA_DQ<5>")
	)
	(segment
		(start 55.960518 -205.573376)
		(end 55.960518 -205.629256)
		(width 0.14478)
		(layer "In4.Cu")
		(net "M_D_CPU1_SA_DQ<5>")
	)
	(segment
		(start 55.240936 -205.792324)
		(end 55.404004 -205.629256)
		(width 0.14478)
		(layer "In4.Cu")
		(net "M_D_CPU1_SA_DQ<5>")
	)
	(segment
		(start 39.305484 -205.025244)
		(end 39.468552 -205.188312)
		(width 0.14478)
		(layer "In4.Cu")
		(net "M_D_CPU1_SA_DQ<5>")
	)
	(segment
		(start 43.847766 -204.560424)
		(end 45.55871 -204.560424)
		(width 0.14478)
		(layer "In4.Cu")
		(net "M_D_CPU1_SA_DQ<5>")
	)
	(segment
		(start 54.84749 -205.629256)
		(end 55.010558 -205.792324)
		(width 0.14478)
		(layer "In4.Cu")
		(net "M_D_CPU1_SA_DQ<5>")
	)
	(segment
		(start 77.75448 -223.747838)
		(end 77.79766 -223.772984)
		(width 0.0889)
		(layer "In4.Cu")
		(net "M_D_CPU1_SA_DQ<5>")
	)
	(segment
		(start 54.684422 -205.410308)
		(end 54.84749 -205.573376)
		(width 0.14478)
		(layer "In4.Cu")
		(net "M_D_CPU1_SA_DQ<5>")
	)
	(segment
		(start 43.684698 -204.780896)
		(end 43.684698 -204.723492)
		(width 0.14478)
		(layer "In4.Cu")
		(net "M_D_CPU1_SA_DQ<5>")
	)
	(segment
		(start 55.79745 -205.410308)
		(end 55.960518 -205.573376)
		(width 0.14478)
		(layer "In4.Cu")
		(net "M_D_CPU1_SA_DQ<5>")
	)
	(segment
		(start 51.266852 -204.785976)
		(end 51.266852 -204.723492)
		(width 0.14478)
		(layer "In4.Cu")
		(net "M_D_CPU1_SA_DQ<5>")
	)
	(segment
		(start 37.79901 -205.188312)
		(end 37.962078 -205.025244)
		(width 0.14478)
		(layer "In4.Cu")
		(net "M_D_CPU1_SA_DQ<5>")
	)
	(segment
		(start 49.017682 -205.639416)
		(end 49.017682 -205.573376)
		(width 0.14478)
		(layer "In4.Cu")
		(net "M_D_CPU1_SA_DQ<5>")
	)
	(segment
		(start 42.733214 -204.560424)
		(end 42.965116 -204.560424)
		(width 0.14478)
		(layer "In4.Cu")
		(net "M_D_CPU1_SA_DQ<5>")
	)
	(segment
		(start 46.408594 -205.410308)
		(end 48.2981 -205.410308)
		(width 0.14478)
		(layer "In4.Cu")
		(net "M_D_CPU1_SA_DQ<5>")
	)
	(segment
		(start 57.965086 -205.206346)
		(end 58.193432 -205.206346)
		(width 0.14478)
		(layer "In4.Cu")
		(net "M_D_CPU1_SA_DQ<5>")
	)
	(segment
		(start 78.694026 -225.367088)
		(end 78.733142 -225.389948)
		(width 0.0889)
		(layer "In4.Cu")
		(net "M_D_CPU1_SA_DQ<5>")
	)
	(arc
		(start 79.200756 -226.198938)
		(mid 79.38129 -226.401458)
		(end 79.446628 -226.664774)
		(width 0.0889)
		(layer "In4.Cu")
		(net "M_D_CPU1_SA_DQ<5>")
	)
	(arc
		(start 87.623904 -229.416864)
		(mid 87.806155 -229.467248)
		(end 87.989664 -229.42169)
		(width 0.0889)
		(layer "In4.Cu")
		(net "M_D_CPU1_SA_DQ<5>")
	)
	(arc
		(start 81.418176 -229.416864)
		(mid 81.701132 -229.340687)
		(end 81.984088 -229.416864)
		(width 0.0889)
		(layer "In4.Cu")
		(net "M_D_CPU1_SA_DQ<5>")
	)
	(arc
		(start 88.563958 -229.416864)
		(mid 88.746209 -229.467248)
		(end 88.929718 -229.42169)
		(width 0.0889)
		(layer "In4.Cu")
		(net "M_D_CPU1_SA_DQ<5>")
	)
	(arc
		(start 78.03642 -224.234502)
		(mid 78.078826 -224.407639)
		(end 78.19644 -224.541588)
		(width 0.0889)
		(layer "In4.Cu")
		(net "M_D_CPU1_SA_DQ<5>")
	)
	(arc
		(start 87.998046 -229.416864)
		(mid 88.281002 -229.340687)
		(end 88.563958 -229.416864)
		(width 0.0889)
		(layer "In4.Cu")
		(net "M_D_CPU1_SA_DQ<5>")
	)
	(arc
		(start 81.984088 -229.416864)
		(mid 82.171032 -229.467153)
		(end 82.357976 -229.416864)
		(width 0.0889)
		(layer "In4.Cu")
		(net "M_D_CPU1_SA_DQ<5>")
	)
	(arc
		(start 85.178138 -229.416864)
		(mid 85.461094 -229.340687)
		(end 85.74405 -229.416864)
		(width 0.0889)
		(layer "In4.Cu")
		(net "M_D_CPU1_SA_DQ<5>")
	)
	(arc
		(start 80.856328 -229.094538)
		(mid 80.89709 -229.264422)
		(end 81.010506 -229.397306)
		(width 0.0889)
		(layer "In4.Cu")
		(net "M_D_CPU1_SA_DQ<5>")
	)
	(arc
		(start 79.916528 -227.474526)
		(mid 79.958077 -227.645948)
		(end 80.0735 -227.779326)
		(width 0.0889)
		(layer "In4.Cu")
		(net "M_D_CPU1_SA_DQ<5>")
	)
	(arc
		(start 78.251558 -224.573592)
		(mid 78.438428 -224.777032)
		(end 78.506574 -225.044762)
		(width 0.0889)
		(layer "In4.Cu")
		(net "M_D_CPU1_SA_DQ<5>")
	)
	(arc
		(start 90.817954 -229.416864)
		(mid 91.10091 -229.340687)
		(end 91.383866 -229.416864)
		(width 0.0889)
		(layer "In4.Cu")
		(net "M_D_CPU1_SA_DQ<5>")
	)
	(arc
		(start 86.684104 -229.416864)
		(mid 86.871048 -229.467153)
		(end 87.057992 -229.416864)
		(width 0.0889)
		(layer "In4.Cu")
		(net "M_D_CPU1_SA_DQ<5>")
	)
	(arc
		(start 84.812378 -229.42169)
		(mid 84.995886 -229.467215)
		(end 85.178138 -229.416864)
		(width 0.0889)
		(layer "In4.Cu")
		(net "M_D_CPU1_SA_DQ<5>")
	)
	(arc
		(start 80.610456 -228.628194)
		(mid 80.791108 -228.830939)
		(end 80.856328 -229.094538)
		(width 0.0889)
		(layer "In4.Cu")
		(net "M_D_CPU1_SA_DQ<5>")
	)
	(arc
		(start 77.375766 -223.241362)
		(mid 77.440809 -223.3388)
		(end 77.46365 -223.453706)
		(width 0.0889)
		(layer "In4.Cu")
		(net "M_D_CPU1_SA_DQ<5>")
	)
	(arc
		(start 83.29803 -229.416864)
		(mid 83.580986 -229.340687)
		(end 83.863942 -229.416864)
		(width 0.0889)
		(layer "In4.Cu")
		(net "M_D_CPU1_SA_DQ<5>")
	)
	(arc
		(start 77.79766 -223.772984)
		(mid 77.973204 -223.974689)
		(end 78.03642 -224.234502)
		(width 0.0889)
		(layer "In4.Cu")
		(net "M_D_CPU1_SA_DQ<5>")
	)
	(arc
		(start 91.383866 -229.416864)
		(mid 91.566117 -229.467248)
		(end 91.749626 -229.42169)
		(width 0.0889)
		(layer "In4.Cu")
		(net "M_D_CPU1_SA_DQ<5>")
	)
	(arc
		(start 88.9381 -229.416864)
		(mid 89.221056 -229.340687)
		(end 89.504012 -229.416864)
		(width 0.0889)
		(layer "In4.Cu")
		(net "M_D_CPU1_SA_DQ<5>")
	)
	(arc
		(start 80.386428 -228.284532)
		(mid 80.427683 -228.455503)
		(end 80.542384 -228.588824)
		(width 0.0889)
		(layer "In4.Cu")
		(net "M_D_CPU1_SA_DQ<5>")
	)
	(arc
		(start 91.758008 -229.416864)
		(mid 92.005868 -229.341781)
		(end 92.261182 -229.385368)
		(width 0.0889)
		(layer "In4.Cu")
		(net "M_D_CPU1_SA_DQ<5>")
	)
	(arc
		(start 79.669386 -227.007928)
		(mid 79.850768 -227.210597)
		(end 79.916528 -227.474526)
		(width 0.0889)
		(layer "In4.Cu")
		(net "M_D_CPU1_SA_DQ<5>")
	)
	(arc
		(start 78.976474 -225.855276)
		(mid 79.016681 -226.024441)
		(end 79.128874 -226.157282)
		(width 0.0889)
		(layer "In4.Cu")
		(net "M_D_CPU1_SA_DQ<5>")
	)
	(arc
		(start 84.238084 -229.416864)
		(mid 84.52104 -229.340687)
		(end 84.803996 -229.416864)
		(width 0.0889)
		(layer "In4.Cu")
		(net "M_D_CPU1_SA_DQ<5>")
	)
	(arc
		(start 81.052416 -229.42169)
		(mid 81.235924 -229.467215)
		(end 81.418176 -229.416864)
		(width 0.0889)
		(layer "In4.Cu")
		(net "M_D_CPU1_SA_DQ<5>")
	)
	(arc
		(start 89.512394 -229.42169)
		(mid 89.695902 -229.467215)
		(end 89.878154 -229.416864)
		(width 0.0889)
		(layer "In4.Cu")
		(net "M_D_CPU1_SA_DQ<5>")
	)
	(arc
		(start 89.878154 -229.416864)
		(mid 90.16111 -229.340687)
		(end 90.444066 -229.416864)
		(width 0.0889)
		(layer "In4.Cu")
		(net "M_D_CPU1_SA_DQ<5>")
	)
	(arc
		(start 78.506574 -225.044762)
		(mid 78.548473 -225.216607)
		(end 78.664562 -225.35007)
		(width 0.0889)
		(layer "In4.Cu")
		(net "M_D_CPU1_SA_DQ<5>")
	)
	(arc
		(start 90.444066 -229.416864)
		(mid 90.63101 -229.467153)
		(end 90.817954 -229.416864)
		(width 0.0889)
		(layer "In4.Cu")
		(net "M_D_CPU1_SA_DQ<5>")
	)
	(arc
		(start 80.143096 -227.819966)
		(mid 80.321909 -228.022316)
		(end 80.386428 -228.284532)
		(width 0.0889)
		(layer "In4.Cu")
		(net "M_D_CPU1_SA_DQ<5>")
	)
	(arc
		(start 82.357976 -229.416864)
		(mid 82.640932 -229.340687)
		(end 82.923888 -229.416864)
		(width 0.0889)
		(layer "In4.Cu")
		(net "M_D_CPU1_SA_DQ<5>")
	)
	(arc
		(start 82.923888 -229.416864)
		(mid 83.106139 -229.467248)
		(end 83.289648 -229.42169)
		(width 0.0889)
		(layer "In4.Cu")
		(net "M_D_CPU1_SA_DQ<5>")
	)
	(arc
		(start 86.118192 -229.416864)
		(mid 86.401148 -229.340687)
		(end 86.684104 -229.416864)
		(width 0.0889)
		(layer "In4.Cu")
		(net "M_D_CPU1_SA_DQ<5>")
	)
	(arc
		(start 78.733142 -225.389948)
		(mid 78.912054 -225.592661)
		(end 78.976474 -225.855276)
		(width 0.0889)
		(layer "In4.Cu")
		(net "M_D_CPU1_SA_DQ<5>")
	)
	(arc
		(start 85.752432 -229.42169)
		(mid 85.93594 -229.467215)
		(end 86.118192 -229.416864)
		(width 0.0889)
		(layer "In4.Cu")
		(net "M_D_CPU1_SA_DQ<5>")
	)
	(arc
		(start 87.057992 -229.416864)
		(mid 87.340948 -229.340687)
		(end 87.623904 -229.416864)
		(width 0.0889)
		(layer "In4.Cu")
		(net "M_D_CPU1_SA_DQ<5>")
	)
	(arc
		(start 79.446628 -226.664774)
		(mid 79.48916 -226.837837)
		(end 79.606902 -226.971606)
		(width 0.0889)
		(layer "In4.Cu")
		(net "M_D_CPU1_SA_DQ<5>")
	)
	(arc
		(start 77.46365 -223.453706)
		(mid 77.467343 -223.472272)
		(end 77.477874 -223.487996)
		(width 0.0889)
		(layer "In4.Cu")
		(net "M_D_CPU1_SA_DQ<5>")
	)
	(arc
		(start 83.863942 -229.416864)
		(mid 84.046193 -229.467248)
		(end 84.229702 -229.42169)
		(width 0.0889)
		(layer "In4.Cu")
		(net "M_D_CPU1_SA_DQ<5>")
	)
	(segment
		(start 91.568016 -228.55047)
		(end 91.10091 -228.284532)
		(width 0.10668)
		(layer "F.Cu")
		(net "M_D_CPU1_SA_DQ<4>")
	)
	(segment
		(start 65.13449 -209.253836)
		(end 65.13449 -209.658458)
		(width 0.14478)
		(layer "In4.Cu")
		(net "M_D_CPU1_SA_DQ<4>")
	)
	(segment
		(start 46.418246 -203.719938)
		(end 48.160432 -203.719938)
		(width 0.14478)
		(layer "In4.Cu")
		(net "M_D_CPU1_SA_DQ<4>")
	)
	(segment
		(start 64.94653 -209.065876)
		(end 65.13449 -209.253836)
		(width 0.14478)
		(layer "In4.Cu")
		(net "M_D_CPU1_SA_DQ<4>")
	)
	(segment
		(start 50.247042 -202.870054)
		(end 50.568352 -202.870054)
		(width 0.14478)
		(layer "In4.Cu")
		(net "M_D_CPU1_SA_DQ<4>")
	)
	(segment
		(start 80.10398 -226.177094)
		(end 80.143096 -226.199954)
		(width 0.0889)
		(layer "In4.Cu")
		(net "M_D_CPU1_SA_DQ<4>")
	)
	(segment
		(start 75.466194 -219.990162)
		(end 75.694286 -219.990162)
		(width 0.14478)
		(layer "In4.Cu")
		(net "M_D_CPU1_SA_DQ<4>")
	)
	(segment
		(start 61.42101 -205.944978)
		(end 61.649102 -205.944978)
		(width 0.14478)
		(layer "In4.Cu")
		(net "M_D_CPU1_SA_DQ<4>")
	)
	(segment
		(start 67.287394 -211.40674)
		(end 67.475354 -211.5947)
		(width 0.14478)
		(layer "In4.Cu")
		(net "M_D_CPU1_SA_DQ<4>")
	)
	(segment
		(start 90.339672 -228.611938)
		(end 90.348054 -228.607112)
		(width 0.0889)
		(layer "In4.Cu")
		(net "M_D_CPU1_SA_DQ<4>")
	)
	(segment
		(start 72.345042 -216.86901)
		(end 72.573134 -216.86901)
		(width 0.14478)
		(layer "In4.Cu")
		(net "M_D_CPU1_SA_DQ<4>")
	)
	(segment
		(start 50.568352 -202.870054)
		(end 50.839624 -203.141326)
		(width 0.14478)
		(layer "In4.Cu")
		(net "M_D_CPU1_SA_DQ<4>")
	)
	(segment
		(start 66.33083 -210.626706)
		(end 66.507106 -210.626452)
		(width 0.14478)
		(layer "In4.Cu")
		(net "M_D_CPU1_SA_DQ<4>")
	)
	(segment
		(start 57.05221 -204.002386)
		(end 57.321196 -204.002386)
		(width 0.14478)
		(layer "In4.Cu")
		(net "M_D_CPU1_SA_DQ<4>")
	)
	(segment
		(start 61.04509 -205.164436)
		(end 61.23305 -205.352396)
		(width 0.14478)
		(layer "In4.Cu")
		(net "M_D_CPU1_SA_DQ<4>")
	)
	(segment
		(start 75.278234 -219.39758)
		(end 75.278234 -219.802202)
		(width 0.14478)
		(layer "In4.Cu")
		(net "M_D_CPU1_SA_DQ<4>")
	)
	(segment
		(start 68.067682 -212.187028)
		(end 68.255642 -212.374988)
		(width 0.14478)
		(layer "In4.Cu")
		(net "M_D_CPU1_SA_DQ<4>")
	)
	(segment
		(start 79.60233 -225.3488)
		(end 79.63408 -225.367088)
		(width 0.0889)
		(layer "In4.Cu")
		(net "M_D_CPU1_SA_DQ<4>")
	)
	(segment
		(start 68.671694 -212.96757)
		(end 68.84797 -212.967316)
		(width 0.14478)
		(layer "In4.Cu")
		(net "M_D_CPU1_SA_DQ<4>")
	)
	(segment
		(start 82.453988 -228.607112)
		(end 82.46237 -228.611938)
		(width 0.0889)
		(layer "In4.Cu")
		(net "M_D_CPU1_SA_DQ<4>")
	)
	(segment
		(start 65.914778 -210.438746)
		(end 66.102738 -210.626706)
		(width 0.14478)
		(layer "In4.Cu")
		(net "M_D_CPU1_SA_DQ<4>")
	)
	(segment
		(start 63.573914 -208.097882)
		(end 63.761874 -208.285842)
		(width 0.14478)
		(layer "In4.Cu")
		(net "M_D_CPU1_SA_DQ<4>")
	)
	(segment
		(start 87.154004 -228.607112)
		(end 87.162386 -228.611938)
		(width 0.0889)
		(layer "In4.Cu")
		(net "M_D_CPU1_SA_DQ<4>")
	)
	(segment
		(start 81.012284 -227.778818)
		(end 81.044034 -227.797106)
		(width 0.0889)
		(layer "In4.Cu")
		(net "M_D_CPU1_SA_DQ<4>")
	)
	(segment
		(start 71.188834 -215.30818)
		(end 71.376794 -215.49614)
		(width 0.14478)
		(layer "In4.Cu")
		(net "M_D_CPU1_SA_DQ<4>")
	)
	(segment
		(start 77.70241 -222.442786)
		(end 77.71765 -222.442786)
		(width 0.0889)
		(layer "In4.Cu")
		(net "M_D_CPU1_SA_DQ<4>")
	)
	(segment
		(start 45.568362 -202.870054)
		(end 46.418246 -203.719938)
		(width 0.14478)
		(layer "In4.Cu")
		(net "M_D_CPU1_SA_DQ<4>")
	)
	(segment
		(start 68.255642 -212.77961)
		(end 68.443602 -212.96757)
		(width 0.14478)
		(layer "In4.Cu")
		(net "M_D_CPU1_SA_DQ<4>")
	)
	(segment
		(start 60.640722 -205.16469)
		(end 60.868814 -205.16469)
		(width 0.14478)
		(layer "In4.Cu")
		(net "M_D_CPU1_SA_DQ<4>")
	)
	(segment
		(start 71.376794 -215.49614)
		(end 71.376794 -215.900762)
		(width 0.14478)
		(layer "In4.Cu")
		(net "M_D_CPU1_SA_DQ<4>")
	)
	(segment
		(start 72.93737 -217.461338)
		(end 73.12533 -217.649298)
		(width 0.14478)
		(layer "In4.Cu")
		(net "M_D_CPU1_SA_DQ<4>")
	)
	(segment
		(start 64.542162 -209.06613)
		(end 64.770254 -209.06613)
		(width 0.14478)
		(layer "In4.Cu")
		(net "M_D_CPU1_SA_DQ<4>")
	)
	(segment
		(start 65.13449 -209.658458)
		(end 65.32245 -209.846418)
		(width 0.14478)
		(layer "In4.Cu")
		(net "M_D_CPU1_SA_DQ<4>")
	)
	(segment
		(start 75.694286 -219.990162)
		(end 75.870562 -219.989908)
		(width 0.14478)
		(layer "In4.Cu")
		(net "M_D_CPU1_SA_DQ<4>")
	)
	(segment
		(start 70.596506 -214.715852)
		(end 70.596506 -215.120474)
		(width 0.14478)
		(layer "In4.Cu")
		(net "M_D_CPU1_SA_DQ<4>")
	)
	(segment
		(start 78.694026 -223.747076)
		(end 78.735936 -223.77146)
		(width 0.0889)
		(layer "In4.Cu")
		(net "M_D_CPU1_SA_DQ<4>")
	)
	(segment
		(start 83.394042 -228.607112)
		(end 83.402424 -228.611938)
		(width 0.0889)
		(layer "In4.Cu")
		(net "M_D_CPU1_SA_DQ<4>")
	)
	(segment
		(start 69.22389 -213.747858)
		(end 69.451982 -213.747858)
		(width 0.14478)
		(layer "In4.Cu")
		(net "M_D_CPU1_SA_DQ<4>")
	)
	(segment
		(start 69.03593 -213.559898)
		(end 69.22389 -213.747858)
		(width 0.14478)
		(layer "In4.Cu")
		(net "M_D_CPU1_SA_DQ<4>")
	)
	(segment
		(start 63.573914 -207.69326)
		(end 63.573914 -208.097882)
		(width 0.14478)
		(layer "In4.Cu")
		(net "M_D_CPU1_SA_DQ<4>")
	)
	(segment
		(start 69.816218 -213.935564)
		(end 69.816218 -214.340186)
		(width 0.14478)
		(layer "In4.Cu")
		(net "M_D_CPU1_SA_DQ<4>")
	)
	(segment
		(start 74.497946 -219.021914)
		(end 74.685906 -219.209874)
		(width 0.14478)
		(layer "In4.Cu")
		(net "M_D_CPU1_SA_DQ<4>")
	)
	(segment
		(start 58.706512 -203.719938)
		(end 59.600592 -203.719938)
		(width 0.14478)
		(layer "In4.Cu")
		(net "M_D_CPU1_SA_DQ<4>")
	)
	(segment
		(start 62.201298 -206.725266)
		(end 62.42939 -206.725266)
		(width 0.14478)
		(layer "In4.Cu")
		(net "M_D_CPU1_SA_DQ<4>")
	)
	(segment
		(start 81.879694 -228.611938)
		(end 81.888076 -228.607112)
		(width 0.0889)
		(layer "In4.Cu")
		(net "M_D_CPU1_SA_DQ<4>")
	)
	(segment
		(start 50.839624 -203.141326)
		(end 51.119786 -203.141326)
		(width 0.14478)
		(layer "In4.Cu")
		(net "M_D_CPU1_SA_DQ<4>")
	)
	(segment
		(start 69.03593 -213.155276)
		(end 69.03593 -213.559898)
		(width 0.14478)
		(layer "In4.Cu")
		(net "M_D_CPU1_SA_DQ<4>")
	)
	(segment
		(start 62.013338 -206.132684)
		(end 62.013338 -206.537306)
		(width 0.14478)
		(layer "In4.Cu")
		(net "M_D_CPU1_SA_DQ<4>")
	)
	(segment
		(start 78.224634 -222.93707)
		(end 78.257908 -222.956374)
		(width 0.0889)
		(layer "In4.Cu")
		(net "M_D_CPU1_SA_DQ<4>")
	)
	(segment
		(start 71.792846 -216.088722)
		(end 71.969122 -216.088468)
		(width 0.14478)
		(layer "In4.Cu")
		(net "M_D_CPU1_SA_DQ<4>")
	)
	(segment
		(start 65.550542 -209.846418)
		(end 65.726818 -209.846164)
		(width 0.14478)
		(layer "In4.Cu")
		(net "M_D_CPU1_SA_DQ<4>")
	)
	(segment
		(start 78.194154 -222.91929)
		(end 78.224634 -222.93707)
		(width 0.0889)
		(layer "In4.Cu")
		(net "M_D_CPU1_SA_DQ<4>")
	)
	(segment
		(start 53.112162 -202.870054)
		(end 53.962046 -203.719938)
		(width 0.14478)
		(layer "In4.Cu")
		(net "M_D_CPU1_SA_DQ<4>")
	)
	(segment
		(start 57.87263 -203.719938)
		(end 58.155078 -204.002386)
		(width 0.14478)
		(layer "In4.Cu")
		(net "M_D_CPU1_SA_DQ<4>")
	)
	(segment
		(start 61.23305 -205.352396)
		(end 61.23305 -205.757018)
		(width 0.14478)
		(layer "In4.Cu")
		(net "M_D_CPU1_SA_DQ<4>")
	)
	(segment
		(start 43.267884 -203.179426)
		(end 43.509946 -203.179426)
		(width 0.14478)
		(layer "In4.Cu")
		(net "M_D_CPU1_SA_DQ<4>")
	)
	(segment
		(start 81.044034 -227.797106)
		(end 81.08315 -227.819966)
		(width 0.0889)
		(layer "In4.Cu")
		(net "M_D_CPU1_SA_DQ<4>")
	)
	(segment
		(start 67.475354 -211.999322)
		(end 67.663314 -212.187282)
		(width 0.14478)
		(layer "In4.Cu")
		(net "M_D_CPU1_SA_DQ<4>")
	)
	(segment
		(start 57.321196 -204.002386)
		(end 57.603644 -203.719938)
		(width 0.14478)
		(layer "In4.Cu")
		(net "M_D_CPU1_SA_DQ<4>")
	)
	(segment
		(start 55.11546 -204.002386)
		(end 55.397908 -203.719938)
		(width 0.14478)
		(layer "In4.Cu")
		(net "M_D_CPU1_SA_DQ<4>")
	)
	(segment
		(start 36.795964 -203.285344)
		(end 37.230558 -203.719938)
		(width 0.14478)
		(layer "In4.Cu")
		(net "M_D_CPU1_SA_DQ<4>")
	)
	(segment
		(start 74.13371 -218.429586)
		(end 74.309986 -218.429332)
		(width 0.14478)
		(layer "In4.Cu")
		(net "M_D_CPU1_SA_DQ<4>")
	)
	(segment
		(start 74.685906 -219.209874)
		(end 74.913998 -219.209874)
		(width 0.14478)
		(layer "In4.Cu")
		(net "M_D_CPU1_SA_DQ<4>")
	)
	(segment
		(start 72.157082 -216.276428)
		(end 72.157082 -216.68105)
		(width 0.14478)
		(layer "In4.Cu")
		(net "M_D_CPU1_SA_DQ<4>")
	)
	(segment
		(start 60.452762 -204.572108)
		(end 60.452762 -204.97673)
		(width 0.14478)
		(layer "In4.Cu")
		(net "M_D_CPU1_SA_DQ<4>")
	)
	(segment
		(start 62.013338 -206.537306)
		(end 62.201298 -206.725266)
		(width 0.14478)
		(layer "In4.Cu")
		(net "M_D_CPU1_SA_DQ<4>")
	)
	(segment
		(start 72.93737 -217.056716)
		(end 72.93737 -217.461338)
		(width 0.14478)
		(layer "In4.Cu")
		(net "M_D_CPU1_SA_DQ<4>")
	)
	(segment
		(start 66.695066 -211.219034)
		(end 66.883026 -211.406994)
		(width 0.14478)
		(layer "In4.Cu")
		(net "M_D_CPU1_SA_DQ<4>")
	)
	(segment
		(start 68.443602 -212.96757)
		(end 68.671694 -212.96757)
		(width 0.14478)
		(layer "In4.Cu")
		(net "M_D_CPU1_SA_DQ<4>")
	)
	(segment
		(start 79.16418 -224.557082)
		(end 79.201772 -224.578926)
		(width 0.0889)
		(layer "In4.Cu")
		(net "M_D_CPU1_SA_DQ<4>")
	)
	(segment
		(start 65.726818 -209.846164)
		(end 65.914778 -210.034124)
		(width 0.14478)
		(layer "In4.Cu")
		(net "M_D_CPU1_SA_DQ<4>")
	)
	(segment
		(start 80.0735 -226.159314)
		(end 80.10398 -226.177094)
		(width 0.0889)
		(layer "In4.Cu")
		(net "M_D_CPU1_SA_DQ<4>")
	)
	(segment
		(start 75.870562 -219.989908)
		(end 76.058522 -220.177868)
		(width 0.14478)
		(layer "In4.Cu")
		(net "M_D_CPU1_SA_DQ<4>")
	)
	(segment
		(start 64.354202 -208.473548)
		(end 64.354202 -208.87817)
		(width 0.14478)
		(layer "In4.Cu")
		(net "M_D_CPU1_SA_DQ<4>")
	)
	(segment
		(start 51.391058 -202.870054)
		(end 53.112162 -202.870054)
		(width 0.14478)
		(layer "In4.Cu")
		(net "M_D_CPU1_SA_DQ<4>")
	)
	(segment
		(start 71.969122 -216.088468)
		(end 72.157082 -216.276428)
		(width 0.14478)
		(layer "In4.Cu")
		(net "M_D_CPU1_SA_DQ<4>")
	)
	(segment
		(start 77.22743 -221.346776)
		(end 77.22743 -221.967806)
		(width 0.14478)
		(layer "In4.Cu")
		(net "M_D_CPU1_SA_DQ<4>")
	)
	(segment
		(start 69.816218 -214.340186)
		(end 70.004178 -214.528146)
		(width 0.14478)
		(layer "In4.Cu")
		(net "M_D_CPU1_SA_DQ<4>")
	)
	(segment
		(start 43.509946 -203.179426)
		(end 43.819318 -202.870054)
		(width 0.14478)
		(layer "In4.Cu")
		(net "M_D_CPU1_SA_DQ<4>")
	)
	(segment
		(start 70.596506 -215.120474)
		(end 70.784466 -215.308434)
		(width 0.14478)
		(layer "In4.Cu")
		(net "M_D_CPU1_SA_DQ<4>")
	)
	(segment
		(start 70.004178 -214.528146)
		(end 70.23227 -214.528146)
		(width 0.14478)
		(layer "In4.Cu")
		(net "M_D_CPU1_SA_DQ<4>")
	)
	(segment
		(start 74.497946 -218.617292)
		(end 74.497946 -219.021914)
		(width 0.14478)
		(layer "In4.Cu")
		(net "M_D_CPU1_SA_DQ<4>")
	)
	(segment
		(start 58.155078 -204.002386)
		(end 58.424064 -204.002386)
		(width 0.14478)
		(layer "In4.Cu")
		(net "M_D_CPU1_SA_DQ<4>")
	)
	(segment
		(start 65.914778 -210.034124)
		(end 65.914778 -210.438746)
		(width 0.14478)
		(layer "In4.Cu")
		(net "M_D_CPU1_SA_DQ<4>")
	)
	(segment
		(start 75.278234 -219.802202)
		(end 75.466194 -219.990162)
		(width 0.14478)
		(layer "In4.Cu")
		(net "M_D_CPU1_SA_DQ<4>")
	)
	(segment
		(start 66.102738 -210.626706)
		(end 66.33083 -210.626706)
		(width 0.14478)
		(layer "In4.Cu")
		(net "M_D_CPU1_SA_DQ<4>")
	)
	(segment
		(start 79.13243 -224.538794)
		(end 79.16418 -224.557082)
		(width 0.0889)
		(layer "In4.Cu")
		(net "M_D_CPU1_SA_DQ<4>")
	)
	(segment
		(start 78.664562 -223.730058)
		(end 78.694026 -223.747076)
		(width 0.0889)
		(layer "In4.Cu")
		(net "M_D_CPU1_SA_DQ<4>")
	)
	(segment
		(start 43.819318 -202.870054)
		(end 45.568362 -202.870054)
		(width 0.14478)
		(layer "In4.Cu")
		(net "M_D_CPU1_SA_DQ<4>")
	)
	(segment
		(start 73.12533 -217.649298)
		(end 73.353422 -217.649298)
		(width 0.14478)
		(layer "In4.Cu")
		(net "M_D_CPU1_SA_DQ<4>")
	)
	(segment
		(start 69.451982 -213.747858)
		(end 69.628258 -213.747604)
		(width 0.14478)
		(layer "In4.Cu")
		(net "M_D_CPU1_SA_DQ<4>")
	)
	(segment
		(start 49.397158 -203.719938)
		(end 50.247042 -202.870054)
		(width 0.14478)
		(layer "In4.Cu")
		(net "M_D_CPU1_SA_DQ<4>")
	)
	(segment
		(start 69.628258 -213.747604)
		(end 69.816218 -213.935564)
		(width 0.14478)
		(layer "In4.Cu")
		(net "M_D_CPU1_SA_DQ<4>")
	)
	(segment
		(start 80.574134 -226.9871)
		(end 80.610456 -227.008182)
		(width 0.0889)
		(layer "In4.Cu")
		(net "M_D_CPU1_SA_DQ<4>")
	)
	(segment
		(start 42.958512 -202.870054)
		(end 43.267884 -203.179426)
		(width 0.14478)
		(layer "In4.Cu")
		(net "M_D_CPU1_SA_DQ<4>")
	)
	(segment
		(start 67.891406 -212.187282)
		(end 68.067682 -212.187028)
		(width 0.14478)
		(layer "In4.Cu")
		(net "M_D_CPU1_SA_DQ<4>")
	)
	(segment
		(start 63.385954 -207.5053)
		(end 63.573914 -207.69326)
		(width 0.14478)
		(layer "In4.Cu")
		(net "M_D_CPU1_SA_DQ<4>")
	)
	(segment
		(start 64.166242 -208.285588)
		(end 64.354202 -208.473548)
		(width 0.14478)
		(layer "In4.Cu")
		(net "M_D_CPU1_SA_DQ<4>")
	)
	(segment
		(start 71.376794 -215.900762)
		(end 71.564754 -216.088722)
		(width 0.14478)
		(layer "In4.Cu")
		(net "M_D_CPU1_SA_DQ<4>")
	)
	(segment
		(start 67.475354 -211.5947)
		(end 67.475354 -211.999322)
		(width 0.14478)
		(layer "In4.Cu")
		(net "M_D_CPU1_SA_DQ<4>")
	)
	(segment
		(start 72.573134 -216.86901)
		(end 72.74941 -216.868756)
		(width 0.14478)
		(layer "In4.Cu")
		(net "M_D_CPU1_SA_DQ<4>")
	)
	(segment
		(start 68.84797 -212.967316)
		(end 69.03593 -213.155276)
		(width 0.14478)
		(layer "In4.Cu")
		(net "M_D_CPU1_SA_DQ<4>")
	)
	(segment
		(start 51.119786 -203.141326)
		(end 51.391058 -202.870054)
		(width 0.14478)
		(layer "In4.Cu")
		(net "M_D_CPU1_SA_DQ<4>")
	)
	(segment
		(start 76.058522 -220.58249)
		(end 76.246482 -220.77045)
		(width 0.14478)
		(layer "In4.Cu")
		(net "M_D_CPU1_SA_DQ<4>")
	)
	(segment
		(start 37.230558 -203.719938)
		(end 41.873678 -203.719938)
		(width 0.14478)
		(layer "In4.Cu")
		(net "M_D_CPU1_SA_DQ<4>")
	)
	(segment
		(start 76.65085 -220.770196)
		(end 77.22743 -221.346776)
		(width 0.14478)
		(layer "In4.Cu")
		(net "M_D_CPU1_SA_DQ<4>")
	)
	(segment
		(start 75.090274 -219.20962)
		(end 75.278234 -219.39758)
		(width 0.14478)
		(layer "In4.Cu")
		(net "M_D_CPU1_SA_DQ<4>")
	)
	(segment
		(start 73.717658 -218.241626)
		(end 73.905618 -218.429586)
		(width 0.14478)
		(layer "In4.Cu")
		(net "M_D_CPU1_SA_DQ<4>")
	)
	(segment
		(start 68.255642 -212.374988)
		(end 68.255642 -212.77961)
		(width 0.14478)
		(layer "In4.Cu")
		(net "M_D_CPU1_SA_DQ<4>")
	)
	(segment
		(start 71.564754 -216.088722)
		(end 71.792846 -216.088722)
		(width 0.14478)
		(layer "In4.Cu")
		(net "M_D_CPU1_SA_DQ<4>")
	)
	(segment
		(start 55.949342 -204.002386)
		(end 56.218328 -204.002386)
		(width 0.14478)
		(layer "In4.Cu")
		(net "M_D_CPU1_SA_DQ<4>")
	)
	(segment
		(start 66.883026 -211.406994)
		(end 67.111118 -211.406994)
		(width 0.14478)
		(layer "In4.Cu")
		(net "M_D_CPU1_SA_DQ<4>")
	)
	(segment
		(start 60.452762 -204.97673)
		(end 60.640722 -205.16469)
		(width 0.14478)
		(layer "In4.Cu")
		(net "M_D_CPU1_SA_DQ<4>")
	)
	(segment
		(start 86.57971 -228.611938)
		(end 86.588092 -228.607112)
		(width 0.0889)
		(layer "In4.Cu")
		(net "M_D_CPU1_SA_DQ<4>")
	)
	(segment
		(start 77.22743 -221.967806)
		(end 77.70241 -222.442786)
		(width 0.14478)
		(layer "In4.Cu")
		(net "M_D_CPU1_SA_DQ<4>")
	)
	(segment
		(start 90.850974 -228.575362)
		(end 90.946986 -228.549962)
		(width 0.0889)
		(layer "In4.Cu")
		(net "M_D_CPU1_SA_DQ<4>")
	)
	(segment
		(start 54.564026 -203.719938)
		(end 54.846474 -204.002386)
		(width 0.14478)
		(layer "In4.Cu")
		(net "M_D_CPU1_SA_DQ<4>")
	)
	(segment
		(start 61.825378 -205.944724)
		(end 62.013338 -206.132684)
		(width 0.14478)
		(layer "In4.Cu")
		(net "M_D_CPU1_SA_DQ<4>")
	)
	(segment
		(start 41.873678 -203.719938)
		(end 42.723562 -202.870054)
		(width 0.14478)
		(layer "In4.Cu")
		(net "M_D_CPU1_SA_DQ<4>")
	)
	(segment
		(start 64.770254 -209.06613)
		(end 64.94653 -209.065876)
		(width 0.14478)
		(layer "In4.Cu")
		(net "M_D_CPU1_SA_DQ<4>")
	)
	(segment
		(start 72.157082 -216.68105)
		(end 72.345042 -216.86901)
		(width 0.14478)
		(layer "In4.Cu")
		(net "M_D_CPU1_SA_DQ<4>")
	)
	(segment
		(start 73.353422 -217.649298)
		(end 73.529698 -217.649044)
		(width 0.14478)
		(layer "In4.Cu")
		(net "M_D_CPU1_SA_DQ<4>")
	)
	(segment
		(start 48.160432 -203.719938)
		(end 48.4759 -204.035406)
		(width 0.14478)
		(layer "In4.Cu")
		(net "M_D_CPU1_SA_DQ<4>")
	)
	(segment
		(start 58.424064 -204.002386)
		(end 58.706512 -203.719938)
		(width 0.14478)
		(layer "In4.Cu")
		(net "M_D_CPU1_SA_DQ<4>")
	)
	(segment
		(start 74.913998 -219.209874)
		(end 75.090274 -219.20962)
		(width 0.14478)
		(layer "In4.Cu")
		(net "M_D_CPU1_SA_DQ<4>")
	)
	(segment
		(start 63.989966 -208.285842)
		(end 64.166242 -208.285588)
		(width 0.14478)
		(layer "In4.Cu")
		(net "M_D_CPU1_SA_DQ<4>")
	)
	(segment
		(start 76.474574 -220.77045)
		(end 76.65085 -220.770196)
		(width 0.14478)
		(layer "In4.Cu")
		(net "M_D_CPU1_SA_DQ<4>")
	)
	(segment
		(start 53.962046 -203.719938)
		(end 54.564026 -203.719938)
		(width 0.14478)
		(layer "In4.Cu")
		(net "M_D_CPU1_SA_DQ<4>")
	)
	(segment
		(start 55.666894 -203.719938)
		(end 55.949342 -204.002386)
		(width 0.14478)
		(layer "In4.Cu")
		(net "M_D_CPU1_SA_DQ<4>")
	)
	(segment
		(start 67.111118 -211.406994)
		(end 67.287394 -211.40674)
		(width 0.14478)
		(layer "In4.Cu")
		(net "M_D_CPU1_SA_DQ<4>")
	)
	(segment
		(start 62.605666 -206.725012)
		(end 62.793626 -206.912972)
		(width 0.14478)
		(layer "In4.Cu")
		(net "M_D_CPU1_SA_DQ<4>")
	)
	(segment
		(start 59.600592 -203.719938)
		(end 60.452762 -204.572108)
		(width 0.14478)
		(layer "In4.Cu")
		(net "M_D_CPU1_SA_DQ<4>")
	)
	(segment
		(start 56.218328 -204.002386)
		(end 56.500776 -203.719938)
		(width 0.14478)
		(layer "In4.Cu")
		(net "M_D_CPU1_SA_DQ<4>")
	)
	(segment
		(start 90.946986 -228.549962)
		(end 91.10091 -228.284532)
		(width 0.0889)
		(layer "In4.Cu")
		(net "M_D_CPU1_SA_DQ<4>")
	)
	(segment
		(start 73.905618 -218.429586)
		(end 74.13371 -218.429586)
		(width 0.14478)
		(layer "In4.Cu")
		(net "M_D_CPU1_SA_DQ<4>")
	)
	(segment
		(start 76.058522 -220.177868)
		(end 76.058522 -220.58249)
		(width 0.14478)
		(layer "In4.Cu")
		(net "M_D_CPU1_SA_DQ<4>")
	)
	(segment
		(start 66.507106 -210.626452)
		(end 66.695066 -210.814412)
		(width 0.14478)
		(layer "In4.Cu")
		(net "M_D_CPU1_SA_DQ<4>")
	)
	(segment
		(start 74.309986 -218.429332)
		(end 74.497946 -218.617292)
		(width 0.14478)
		(layer "In4.Cu")
		(net "M_D_CPU1_SA_DQ<4>")
	)
	(segment
		(start 60.868814 -205.16469)
		(end 61.04509 -205.164436)
		(width 0.14478)
		(layer "In4.Cu")
		(net "M_D_CPU1_SA_DQ<4>")
	)
	(segment
		(start 63.761874 -208.285842)
		(end 63.989966 -208.285842)
		(width 0.14478)
		(layer "In4.Cu")
		(net "M_D_CPU1_SA_DQ<4>")
	)
	(segment
		(start 81.483454 -228.589332)
		(end 81.513934 -228.607112)
		(width 0.0889)
		(layer "In4.Cu")
		(net "M_D_CPU1_SA_DQ<4>")
	)
	(segment
		(start 80.542384 -226.968812)
		(end 80.574134 -226.9871)
		(width 0.0889)
		(layer "In4.Cu")
		(net "M_D_CPU1_SA_DQ<4>")
	)
	(segment
		(start 67.663314 -212.187282)
		(end 67.891406 -212.187282)
		(width 0.14478)
		(layer "In4.Cu")
		(net "M_D_CPU1_SA_DQ<4>")
	)
	(segment
		(start 85.639656 -228.611938)
		(end 85.648038 -228.607112)
		(width 0.0889)
		(layer "In4.Cu")
		(net "M_D_CPU1_SA_DQ<4>")
	)
	(segment
		(start 55.397908 -203.719938)
		(end 55.666894 -203.719938)
		(width 0.14478)
		(layer "In4.Cu")
		(net "M_D_CPU1_SA_DQ<4>")
	)
	(segment
		(start 70.23227 -214.528146)
		(end 70.408546 -214.527892)
		(width 0.14478)
		(layer "In4.Cu")
		(net "M_D_CPU1_SA_DQ<4>")
	)
	(segment
		(start 73.717658 -217.837004)
		(end 73.717658 -218.241626)
		(width 0.14478)
		(layer "In4.Cu")
		(net "M_D_CPU1_SA_DQ<4>")
	)
	(segment
		(start 88.094058 -228.607112)
		(end 88.10244 -228.611938)
		(width 0.0889)
		(layer "In4.Cu")
		(net "M_D_CPU1_SA_DQ<4>")
	)
	(segment
		(start 42.723562 -202.870054)
		(end 42.958512 -202.870054)
		(width 0.14478)
		(layer "In4.Cu")
		(net "M_D_CPU1_SA_DQ<4>")
	)
	(segment
		(start 70.408546 -214.527892)
		(end 70.596506 -214.715852)
		(width 0.14478)
		(layer "In4.Cu")
		(net "M_D_CPU1_SA_DQ<4>")
	)
	(segment
		(start 62.981586 -207.505554)
		(end 63.209678 -207.505554)
		(width 0.14478)
		(layer "In4.Cu")
		(net "M_D_CPU1_SA_DQ<4>")
	)
	(segment
		(start 64.354202 -208.87817)
		(end 64.542162 -209.06613)
		(width 0.14478)
		(layer "In4.Cu")
		(net "M_D_CPU1_SA_DQ<4>")
	)
	(segment
		(start 66.695066 -210.814412)
		(end 66.695066 -211.219034)
		(width 0.14478)
		(layer "In4.Cu")
		(net "M_D_CPU1_SA_DQ<4>")
	)
	(segment
		(start 54.846474 -204.002386)
		(end 55.11546 -204.002386)
		(width 0.14478)
		(layer "In4.Cu")
		(net "M_D_CPU1_SA_DQ<4>")
	)
	(segment
		(start 65.32245 -209.846418)
		(end 65.550542 -209.846418)
		(width 0.14478)
		(layer "In4.Cu")
		(net "M_D_CPU1_SA_DQ<4>")
	)
	(segment
		(start 48.711866 -204.035406)
		(end 49.027334 -203.719938)
		(width 0.14478)
		(layer "In4.Cu")
		(net "M_D_CPU1_SA_DQ<4>")
	)
	(segment
		(start 76.246482 -220.77045)
		(end 76.474574 -220.77045)
		(width 0.14478)
		(layer "In4.Cu")
		(net "M_D_CPU1_SA_DQ<4>")
	)
	(segment
		(start 56.769762 -203.719938)
		(end 57.05221 -204.002386)
		(width 0.14478)
		(layer "In4.Cu")
		(net "M_D_CPU1_SA_DQ<4>")
	)
	(segment
		(start 49.027334 -203.719938)
		(end 49.397158 -203.719938)
		(width 0.14478)
		(layer "In4.Cu")
		(net "M_D_CPU1_SA_DQ<4>")
	)
	(segment
		(start 48.4759 -204.035406)
		(end 48.711866 -204.035406)
		(width 0.14478)
		(layer "In4.Cu")
		(net "M_D_CPU1_SA_DQ<4>")
	)
	(segment
		(start 71.012558 -215.308434)
		(end 71.188834 -215.30818)
		(width 0.14478)
		(layer "In4.Cu")
		(net "M_D_CPU1_SA_DQ<4>")
	)
	(segment
		(start 61.23305 -205.757018)
		(end 61.42101 -205.944978)
		(width 0.14478)
		(layer "In4.Cu")
		(net "M_D_CPU1_SA_DQ<4>")
	)
	(segment
		(start 56.500776 -203.719938)
		(end 56.769762 -203.719938)
		(width 0.14478)
		(layer "In4.Cu")
		(net "M_D_CPU1_SA_DQ<4>")
	)
	(segment
		(start 73.529698 -217.649044)
		(end 73.717658 -217.837004)
		(width 0.14478)
		(layer "In4.Cu")
		(net "M_D_CPU1_SA_DQ<4>")
	)
	(segment
		(start 62.42939 -206.725266)
		(end 62.605666 -206.725012)
		(width 0.14478)
		(layer "In4.Cu")
		(net "M_D_CPU1_SA_DQ<4>")
	)
	(segment
		(start 63.209678 -207.505554)
		(end 63.385954 -207.5053)
		(width 0.14478)
		(layer "In4.Cu")
		(net "M_D_CPU1_SA_DQ<4>")
	)
	(segment
		(start 72.74941 -216.868756)
		(end 72.93737 -217.056716)
		(width 0.14478)
		(layer "In4.Cu")
		(net "M_D_CPU1_SA_DQ<4>")
	)
	(segment
		(start 57.603644 -203.719938)
		(end 57.87263 -203.719938)
		(width 0.14478)
		(layer "In4.Cu")
		(net "M_D_CPU1_SA_DQ<4>")
	)
	(segment
		(start 70.784466 -215.308434)
		(end 71.012558 -215.308434)
		(width 0.14478)
		(layer "In4.Cu")
		(net "M_D_CPU1_SA_DQ<4>")
	)
	(segment
		(start 77.71765 -222.442786)
		(end 78.194154 -222.91929)
		(width 0.0889)
		(layer "In4.Cu")
		(net "M_D_CPU1_SA_DQ<4>")
	)
	(segment
		(start 62.793626 -206.912972)
		(end 62.793626 -207.317594)
		(width 0.14478)
		(layer "In4.Cu")
		(net "M_D_CPU1_SA_DQ<4>")
	)
	(segment
		(start 61.649102 -205.944978)
		(end 61.825378 -205.944724)
		(width 0.14478)
		(layer "In4.Cu")
		(net "M_D_CPU1_SA_DQ<4>")
	)
	(segment
		(start 62.793626 -207.317594)
		(end 62.981586 -207.505554)
		(width 0.14478)
		(layer "In4.Cu")
		(net "M_D_CPU1_SA_DQ<4>")
	)
	(segment
		(start 79.63408 -225.367088)
		(end 79.671926 -225.388932)
		(width 0.0889)
		(layer "In4.Cu")
		(net "M_D_CPU1_SA_DQ<4>")
	)
	(arc
		(start 86.21395 -228.607112)
		(mid 86.396201 -228.657462)
		(end 86.57971 -228.611938)
		(width 0.0889)
		(layer "In4.Cu")
		(net "M_D_CPU1_SA_DQ<4>")
	)
	(arc
		(start 82.46237 -228.611938)
		(mid 82.645878 -228.657432)
		(end 82.82813 -228.607112)
		(width 0.0889)
		(layer "In4.Cu")
		(net "M_D_CPU1_SA_DQ<4>")
	)
	(arc
		(start 85.273896 -228.607112)
		(mid 85.456147 -228.657462)
		(end 85.639656 -228.611938)
		(width 0.0889)
		(layer "In4.Cu")
		(net "M_D_CPU1_SA_DQ<4>")
	)
	(arc
		(start 84.334096 -228.607112)
		(mid 84.52104 -228.657367)
		(end 84.707984 -228.607112)
		(width 0.0889)
		(layer "In4.Cu")
		(net "M_D_CPU1_SA_DQ<4>")
	)
	(arc
		(start 90.348054 -228.607112)
		(mid 90.595767 -228.531892)
		(end 90.850974 -228.575362)
		(width 0.0889)
		(layer "In4.Cu")
		(net "M_D_CPU1_SA_DQ<4>")
	)
	(arc
		(start 78.506574 -223.424496)
		(mid 78.548414 -223.596482)
		(end 78.664562 -223.730058)
		(width 0.0889)
		(layer "In4.Cu")
		(net "M_D_CPU1_SA_DQ<4>")
	)
	(arc
		(start 80.856328 -227.474526)
		(mid 80.897583 -227.645497)
		(end 81.012284 -227.778818)
		(width 0.0889)
		(layer "In4.Cu")
		(net "M_D_CPU1_SA_DQ<4>")
	)
	(arc
		(start 88.10244 -228.611938)
		(mid 88.285948 -228.657432)
		(end 88.4682 -228.607112)
		(width 0.0889)
		(layer "In4.Cu")
		(net "M_D_CPU1_SA_DQ<4>")
	)
	(arc
		(start 89.408 -228.607112)
		(mid 89.690956 -228.530935)
		(end 89.973912 -228.607112)
		(width 0.0889)
		(layer "In4.Cu")
		(net "M_D_CPU1_SA_DQ<4>")
	)
	(arc
		(start 87.162386 -228.611938)
		(mid 87.345894 -228.657432)
		(end 87.528146 -228.607112)
		(width 0.0889)
		(layer "In4.Cu")
		(net "M_D_CPU1_SA_DQ<4>")
	)
	(arc
		(start 81.326482 -228.284532)
		(mid 81.368031 -228.455954)
		(end 81.483454 -228.589332)
		(width 0.0889)
		(layer "In4.Cu")
		(net "M_D_CPU1_SA_DQ<4>")
	)
	(arc
		(start 79.201772 -224.578926)
		(mid 79.381501 -224.781546)
		(end 79.446374 -225.044508)
		(width 0.0889)
		(layer "In4.Cu")
		(net "M_D_CPU1_SA_DQ<4>")
	)
	(arc
		(start 83.768184 -228.607112)
		(mid 84.05114 -228.530935)
		(end 84.334096 -228.607112)
		(width 0.0889)
		(layer "In4.Cu")
		(net "M_D_CPU1_SA_DQ<4>")
	)
	(arc
		(start 79.671926 -225.388932)
		(mid 79.851655 -225.591552)
		(end 79.916528 -225.854514)
		(width 0.0889)
		(layer "In4.Cu")
		(net "M_D_CPU1_SA_DQ<4>")
	)
	(arc
		(start 87.528146 -228.607112)
		(mid 87.811102 -228.530935)
		(end 88.094058 -228.607112)
		(width 0.0889)
		(layer "In4.Cu")
		(net "M_D_CPU1_SA_DQ<4>")
	)
	(arc
		(start 81.08315 -227.819966)
		(mid 81.261963 -228.022316)
		(end 81.326482 -228.284532)
		(width 0.0889)
		(layer "In4.Cu")
		(net "M_D_CPU1_SA_DQ<4>")
	)
	(arc
		(start 82.82813 -228.607112)
		(mid 83.111086 -228.530935)
		(end 83.394042 -228.607112)
		(width 0.0889)
		(layer "In4.Cu")
		(net "M_D_CPU1_SA_DQ<4>")
	)
	(arc
		(start 80.610456 -227.008182)
		(mid 80.791108 -227.210927)
		(end 80.856328 -227.474526)
		(width 0.0889)
		(layer "In4.Cu")
		(net "M_D_CPU1_SA_DQ<4>")
	)
	(arc
		(start 86.588092 -228.607112)
		(mid 86.871048 -228.530935)
		(end 87.154004 -228.607112)
		(width 0.0889)
		(layer "In4.Cu")
		(net "M_D_CPU1_SA_DQ<4>")
	)
	(arc
		(start 79.916528 -225.854514)
		(mid 79.958077 -226.025936)
		(end 80.0735 -226.159314)
		(width 0.0889)
		(layer "In4.Cu")
		(net "M_D_CPU1_SA_DQ<4>")
	)
	(arc
		(start 78.257908 -222.956374)
		(mid 78.44057 -223.159455)
		(end 78.506574 -223.424496)
		(width 0.0889)
		(layer "In4.Cu")
		(net "M_D_CPU1_SA_DQ<4>")
	)
	(arc
		(start 83.402424 -228.611938)
		(mid 83.585932 -228.657432)
		(end 83.768184 -228.607112)
		(width 0.0889)
		(layer "In4.Cu")
		(net "M_D_CPU1_SA_DQ<4>")
	)
	(arc
		(start 81.888076 -228.607112)
		(mid 82.171032 -228.530935)
		(end 82.453988 -228.607112)
		(width 0.0889)
		(layer "In4.Cu")
		(net "M_D_CPU1_SA_DQ<4>")
	)
	(arc
		(start 80.143096 -226.199954)
		(mid 80.321909 -226.402304)
		(end 80.386428 -226.66452)
		(width 0.0889)
		(layer "In4.Cu")
		(net "M_D_CPU1_SA_DQ<4>")
	)
	(arc
		(start 88.4682 -228.607112)
		(mid 88.751156 -228.530935)
		(end 89.034112 -228.607112)
		(width 0.0889)
		(layer "In4.Cu")
		(net "M_D_CPU1_SA_DQ<4>")
	)
	(arc
		(start 80.386428 -226.66452)
		(mid 80.427683 -226.835491)
		(end 80.542384 -226.968812)
		(width 0.0889)
		(layer "In4.Cu")
		(net "M_D_CPU1_SA_DQ<4>")
	)
	(arc
		(start 85.648038 -228.607112)
		(mid 85.930994 -228.530935)
		(end 86.21395 -228.607112)
		(width 0.0889)
		(layer "In4.Cu")
		(net "M_D_CPU1_SA_DQ<4>")
	)
	(arc
		(start 78.735936 -223.77146)
		(mid 78.912918 -223.973552)
		(end 78.976728 -224.234502)
		(width 0.0889)
		(layer "In4.Cu")
		(net "M_D_CPU1_SA_DQ<4>")
	)
	(arc
		(start 84.707984 -228.607112)
		(mid 84.99094 -228.530935)
		(end 85.273896 -228.607112)
		(width 0.0889)
		(layer "In4.Cu")
		(net "M_D_CPU1_SA_DQ<4>")
	)
	(arc
		(start 89.034112 -228.607112)
		(mid 89.221056 -228.657367)
		(end 89.408 -228.607112)
		(width 0.0889)
		(layer "In4.Cu")
		(net "M_D_CPU1_SA_DQ<4>")
	)
	(arc
		(start 78.976728 -224.234502)
		(mid 79.017917 -224.405406)
		(end 79.13243 -224.538794)
		(width 0.0889)
		(layer "In4.Cu")
		(net "M_D_CPU1_SA_DQ<4>")
	)
	(arc
		(start 89.973912 -228.607112)
		(mid 90.156163 -228.657462)
		(end 90.339672 -228.611938)
		(width 0.0889)
		(layer "In4.Cu")
		(net "M_D_CPU1_SA_DQ<4>")
	)
	(arc
		(start 79.446374 -225.044508)
		(mid 79.487629 -225.215479)
		(end 79.60233 -225.3488)
		(width 0.0889)
		(layer "In4.Cu")
		(net "M_D_CPU1_SA_DQ<4>")
	)
	(arc
		(start 81.513934 -228.607112)
		(mid 81.696185 -228.657462)
		(end 81.879694 -228.611938)
		(width 0.0889)
		(layer "In4.Cu")
		(net "M_D_CPU1_SA_DQ<4>")
	)
	(segment
		(start 92.507816 -226.930458)
		(end 92.040964 -226.66452)
		(width 0.10668)
		(layer "F.Cu")
		(net "M_D_CPU1_SA_DQ<3>")
	)
	(segment
		(start 91.85402 -226.34194)
		(end 91.862402 -226.337114)
		(width 0.0889)
		(layer "In4.Cu")
		(net "M_D_CPU1_SA_DQ<3>")
	)
	(segment
		(start 87.154004 -226.34194)
		(end 87.162386 -226.337114)
		(width 0.0889)
		(layer "In4.Cu")
		(net "M_D_CPU1_SA_DQ<3>")
	)
	(segment
		(start 80.075786 -221.235524)
		(end 80.075786 -221.404942)
		(width 0.0889)
		(layer "In4.Cu")
		(net "M_D_CPU1_SA_DQ<3>")
	)
	(segment
		(start 32.695896 -199.8853)
		(end 33.121092 -200.310496)
		(width 0.14478)
		(layer "In4.Cu")
		(net "M_D_CPU1_SA_DQ<3>")
	)
	(segment
		(start 92.195142 -226.39909)
		(end 92.040964 -226.66452)
		(width 0.0889)
		(layer "In4.Cu")
		(net "M_D_CPU1_SA_DQ<3>")
	)
	(segment
		(start 45.504608 -199.450706)
		(end 46.354492 -200.30059)
		(width 0.14478)
		(layer "In4.Cu")
		(net "M_D_CPU1_SA_DQ<3>")
	)
	(segment
		(start 41.893998 -200.30059)
		(end 42.743882 -199.450706)
		(width 0.14478)
		(layer "In4.Cu")
		(net "M_D_CPU1_SA_DQ<3>")
	)
	(segment
		(start 42.743882 -199.450706)
		(end 45.504608 -199.450706)
		(width 0.14478)
		(layer "In4.Cu")
		(net "M_D_CPU1_SA_DQ<3>")
	)
	(segment
		(start 80.43672 -222.267526)
		(end 80.47863 -222.29191)
		(width 0.0889)
		(layer "In4.Cu")
		(net "M_D_CPU1_SA_DQ<3>")
	)
	(segment
		(start 81.37906 -223.889062)
		(end 81.418176 -223.911922)
		(width 0.0889)
		(layer "In4.Cu")
		(net "M_D_CPU1_SA_DQ<3>")
	)
	(segment
		(start 33.865058 -199.877426)
		(end 34.095436 -199.877426)
		(width 0.14478)
		(layer "In4.Cu")
		(net "M_D_CPU1_SA_DQ<3>")
	)
	(segment
		(start 90.339672 -226.337114)
		(end 90.348054 -226.34194)
		(width 0.0889)
		(layer "In4.Cu")
		(net "M_D_CPU1_SA_DQ<3>")
	)
	(segment
		(start 80.47863 -222.29191)
		(end 80.506824 -222.308166)
		(width 0.0889)
		(layer "In4.Cu")
		(net "M_D_CPU1_SA_DQ<3>")
	)
	(segment
		(start 33.121092 -200.310496)
		(end 33.538922 -200.310496)
		(width 0.14478)
		(layer "In4.Cu")
		(net "M_D_CPU1_SA_DQ<3>")
	)
	(segment
		(start 82.789014 -226.31908)
		(end 82.82813 -226.34194)
		(width 0.0889)
		(layer "In4.Cu")
		(net "M_D_CPU1_SA_DQ<3>")
	)
	(segment
		(start 33.538922 -200.310496)
		(end 33.70199 -200.147428)
		(width 0.14478)
		(layer "In4.Cu")
		(net "M_D_CPU1_SA_DQ<3>")
	)
	(segment
		(start 34.095436 -199.877426)
		(end 34.258504 -200.040494)
		(width 0.14478)
		(layer "In4.Cu")
		(net "M_D_CPU1_SA_DQ<3>")
	)
	(segment
		(start 80.075786 -221.404942)
		(end 80.195928 -221.525084)
		(width 0.0889)
		(layer "In4.Cu")
		(net "M_D_CPU1_SA_DQ<3>")
	)
	(segment
		(start 49.382172 -200.30059)
		(end 50.232056 -199.450706)
		(width 0.14478)
		(layer "In4.Cu")
		(net "M_D_CPU1_SA_DQ<3>")
	)
	(segment
		(start 34.258504 -200.147428)
		(end 34.411666 -200.30059)
		(width 0.14478)
		(layer "In4.Cu")
		(net "M_D_CPU1_SA_DQ<3>")
	)
	(segment
		(start 90.913966 -226.34194)
		(end 90.922348 -226.337114)
		(width 0.0889)
		(layer "In4.Cu")
		(net "M_D_CPU1_SA_DQ<3>")
	)
	(segment
		(start 34.258504 -200.040494)
		(end 34.258504 -200.147428)
		(width 0.14478)
		(layer "In4.Cu")
		(net "M_D_CPU1_SA_DQ<3>")
	)
	(segment
		(start 46.354492 -200.30059)
		(end 49.382172 -200.30059)
		(width 0.14478)
		(layer "In4.Cu")
		(net "M_D_CPU1_SA_DQ<3>")
	)
	(segment
		(start 80.195928 -221.525084)
		(end 80.195928 -221.804484)
		(width 0.0889)
		(layer "In4.Cu")
		(net "M_D_CPU1_SA_DQ<3>")
	)
	(segment
		(start 82.321654 -225.510852)
		(end 82.357976 -225.531934)
		(width 0.0889)
		(layer "In4.Cu")
		(net "M_D_CPU1_SA_DQ<3>")
	)
	(segment
		(start 81.84896 -224.699068)
		(end 81.888076 -224.721928)
		(width 0.0889)
		(layer "In4.Cu")
		(net "M_D_CPU1_SA_DQ<3>")
	)
	(segment
		(start 34.411666 -200.30059)
		(end 41.893998 -200.30059)
		(width 0.14478)
		(layer "In4.Cu")
		(net "M_D_CPU1_SA_DQ<3>")
	)
	(segment
		(start 50.232056 -199.450706)
		(end 53.246782 -199.450706)
		(width 0.14478)
		(layer "In4.Cu")
		(net "M_D_CPU1_SA_DQ<3>")
	)
	(segment
		(start 86.57971 -226.337114)
		(end 86.588092 -226.34194)
		(width 0.0889)
		(layer "In4.Cu")
		(net "M_D_CPU1_SA_DQ<3>")
	)
	(segment
		(start 54.106572 -200.310496)
		(end 60.379102 -200.310496)
		(width 0.14478)
		(layer "In4.Cu")
		(net "M_D_CPU1_SA_DQ<3>")
	)
	(segment
		(start 33.70199 -200.040494)
		(end 33.865058 -199.877426)
		(width 0.14478)
		(layer "In4.Cu")
		(net "M_D_CPU1_SA_DQ<3>")
	)
	(segment
		(start 60.379102 -200.310496)
		(end 80.075786 -220.00718)
		(width 0.14478)
		(layer "In4.Cu")
		(net "M_D_CPU1_SA_DQ<3>")
	)
	(segment
		(start 81.888076 -224.721928)
		(end 81.919826 -224.740216)
		(width 0.0889)
		(layer "In4.Cu")
		(net "M_D_CPU1_SA_DQ<3>")
	)
	(segment
		(start 88.094058 -226.34194)
		(end 88.10244 -226.337114)
		(width 0.0889)
		(layer "In4.Cu")
		(net "M_D_CPU1_SA_DQ<3>")
	)
	(segment
		(start 80.9117 -223.080834)
		(end 80.948022 -223.101916)
		(width 0.0889)
		(layer "In4.Cu")
		(net "M_D_CPU1_SA_DQ<3>")
	)
	(segment
		(start 80.948022 -223.101916)
		(end 80.979772 -223.120204)
		(width 0.0889)
		(layer "In4.Cu")
		(net "M_D_CPU1_SA_DQ<3>")
	)
	(segment
		(start 80.075786 -220.00718)
		(end 80.075786 -221.235524)
		(width 0.14478)
		(layer "In4.Cu")
		(net "M_D_CPU1_SA_DQ<3>")
	)
	(segment
		(start 82.357976 -225.531934)
		(end 82.389726 -225.550222)
		(width 0.0889)
		(layer "In4.Cu")
		(net "M_D_CPU1_SA_DQ<3>")
	)
	(segment
		(start 85.639656 -226.337114)
		(end 85.648038 -226.34194)
		(width 0.0889)
		(layer "In4.Cu")
		(net "M_D_CPU1_SA_DQ<3>")
	)
	(segment
		(start 53.246782 -199.450706)
		(end 54.106572 -200.310496)
		(width 0.14478)
		(layer "In4.Cu")
		(net "M_D_CPU1_SA_DQ<3>")
	)
	(segment
		(start 81.418176 -223.911922)
		(end 81.448656 -223.929702)
		(width 0.0889)
		(layer "In4.Cu")
		(net "M_D_CPU1_SA_DQ<3>")
	)
	(segment
		(start 83.394042 -226.34194)
		(end 83.402424 -226.337114)
		(width 0.0889)
		(layer "In4.Cu")
		(net "M_D_CPU1_SA_DQ<3>")
	)
	(segment
		(start 33.70199 -200.147428)
		(end 33.70199 -200.040494)
		(width 0.14478)
		(layer "In4.Cu")
		(net "M_D_CPU1_SA_DQ<3>")
	)
	(segment
		(start 92.17279 -226.315778)
		(end 92.195142 -226.39909)
		(width 0.0889)
		(layer "In4.Cu")
		(net "M_D_CPU1_SA_DQ<3>")
	)
	(arc
		(start 88.4682 -226.34194)
		(mid 88.751156 -226.418117)
		(end 89.034112 -226.34194)
		(width 0.0889)
		(layer "In4.Cu")
		(net "M_D_CPU1_SA_DQ<3>")
	)
	(arc
		(start 85.648038 -226.34194)
		(mid 85.930994 -226.418117)
		(end 86.21395 -226.34194)
		(width 0.0889)
		(layer "In4.Cu")
		(net "M_D_CPU1_SA_DQ<3>")
	)
	(arc
		(start 90.348054 -226.34194)
		(mid 90.63101 -226.418117)
		(end 90.913966 -226.34194)
		(width 0.0889)
		(layer "In4.Cu")
		(net "M_D_CPU1_SA_DQ<3>")
	)
	(arc
		(start 84.707984 -226.34194)
		(mid 84.99094 -226.418117)
		(end 85.273896 -226.34194)
		(width 0.0889)
		(layer "In4.Cu")
		(net "M_D_CPU1_SA_DQ<3>")
	)
	(arc
		(start 82.545682 -225.854514)
		(mid 82.610197 -226.116733)
		(end 82.789014 -226.31908)
		(width 0.0889)
		(layer "In4.Cu")
		(net "M_D_CPU1_SA_DQ<3>")
	)
	(arc
		(start 91.288108 -226.34194)
		(mid 91.571064 -226.418117)
		(end 91.85402 -226.34194)
		(width 0.0889)
		(layer "In4.Cu")
		(net "M_D_CPU1_SA_DQ<3>")
	)
	(arc
		(start 80.665828 -222.61449)
		(mid 80.731064 -222.878081)
		(end 80.9117 -223.080834)
		(width 0.0889)
		(layer "In4.Cu")
		(net "M_D_CPU1_SA_DQ<3>")
	)
	(arc
		(start 83.402424 -226.337114)
		(mid 83.585932 -226.29162)
		(end 83.768184 -226.34194)
		(width 0.0889)
		(layer "In4.Cu")
		(net "M_D_CPU1_SA_DQ<3>")
	)
	(arc
		(start 83.768184 -226.34194)
		(mid 84.05114 -226.418117)
		(end 84.334096 -226.34194)
		(width 0.0889)
		(layer "In4.Cu")
		(net "M_D_CPU1_SA_DQ<3>")
	)
	(arc
		(start 87.162386 -226.337114)
		(mid 87.345894 -226.29162)
		(end 87.528146 -226.34194)
		(width 0.0889)
		(layer "In4.Cu")
		(net "M_D_CPU1_SA_DQ<3>")
	)
	(arc
		(start 85.273896 -226.34194)
		(mid 85.456147 -226.29159)
		(end 85.639656 -226.337114)
		(width 0.0889)
		(layer "In4.Cu")
		(net "M_D_CPU1_SA_DQ<3>")
	)
	(arc
		(start 88.10244 -226.337114)
		(mid 88.285948 -226.29162)
		(end 88.4682 -226.34194)
		(width 0.0889)
		(layer "In4.Cu")
		(net "M_D_CPU1_SA_DQ<3>")
	)
	(arc
		(start 81.448656 -223.929702)
		(mid 81.564083 -224.063078)
		(end 81.605628 -224.234502)
		(width 0.0889)
		(layer "In4.Cu")
		(net "M_D_CPU1_SA_DQ<3>")
	)
	(arc
		(start 80.195928 -221.804484)
		(mid 80.25972 -222.065443)
		(end 80.43672 -222.267526)
		(width 0.0889)
		(layer "In4.Cu")
		(net "M_D_CPU1_SA_DQ<3>")
	)
	(arc
		(start 91.862402 -226.337114)
		(mid 92.015272 -226.292473)
		(end 92.17279 -226.315778)
		(width 0.0889)
		(layer "In4.Cu")
		(net "M_D_CPU1_SA_DQ<3>")
	)
	(arc
		(start 84.334096 -226.34194)
		(mid 84.52104 -226.291685)
		(end 84.707984 -226.34194)
		(width 0.0889)
		(layer "In4.Cu")
		(net "M_D_CPU1_SA_DQ<3>")
	)
	(arc
		(start 90.922348 -226.337114)
		(mid 91.105856 -226.29162)
		(end 91.288108 -226.34194)
		(width 0.0889)
		(layer "In4.Cu")
		(net "M_D_CPU1_SA_DQ<3>")
	)
	(arc
		(start 81.135728 -223.424496)
		(mid 81.200243 -223.686715)
		(end 81.37906 -223.889062)
		(width 0.0889)
		(layer "In4.Cu")
		(net "M_D_CPU1_SA_DQ<3>")
	)
	(arc
		(start 86.21395 -226.34194)
		(mid 86.396201 -226.29159)
		(end 86.57971 -226.337114)
		(width 0.0889)
		(layer "In4.Cu")
		(net "M_D_CPU1_SA_DQ<3>")
	)
	(arc
		(start 89.973912 -226.34194)
		(mid 90.156163 -226.29159)
		(end 90.339672 -226.337114)
		(width 0.0889)
		(layer "In4.Cu")
		(net "M_D_CPU1_SA_DQ<3>")
	)
	(arc
		(start 89.034112 -226.34194)
		(mid 89.221056 -226.291685)
		(end 89.408 -226.34194)
		(width 0.0889)
		(layer "In4.Cu")
		(net "M_D_CPU1_SA_DQ<3>")
	)
	(arc
		(start 89.408 -226.34194)
		(mid 89.690956 -226.418117)
		(end 89.973912 -226.34194)
		(width 0.0889)
		(layer "In4.Cu")
		(net "M_D_CPU1_SA_DQ<3>")
	)
	(arc
		(start 82.075782 -225.044508)
		(mid 82.141018 -225.308099)
		(end 82.321654 -225.510852)
		(width 0.0889)
		(layer "In4.Cu")
		(net "M_D_CPU1_SA_DQ<3>")
	)
	(arc
		(start 86.588092 -226.34194)
		(mid 86.871048 -226.418117)
		(end 87.154004 -226.34194)
		(width 0.0889)
		(layer "In4.Cu")
		(net "M_D_CPU1_SA_DQ<3>")
	)
	(arc
		(start 81.605628 -224.234502)
		(mid 81.670143 -224.496721)
		(end 81.84896 -224.699068)
		(width 0.0889)
		(layer "In4.Cu")
		(net "M_D_CPU1_SA_DQ<3>")
	)
	(arc
		(start 80.979772 -223.120204)
		(mid 81.094448 -223.253538)
		(end 81.135728 -223.424496)
		(width 0.0889)
		(layer "In4.Cu")
		(net "M_D_CPU1_SA_DQ<3>")
	)
	(arc
		(start 87.528146 -226.34194)
		(mid 87.811102 -226.418117)
		(end 88.094058 -226.34194)
		(width 0.0889)
		(layer "In4.Cu")
		(net "M_D_CPU1_SA_DQ<3>")
	)
	(arc
		(start 82.82813 -226.34194)
		(mid 83.111086 -226.418117)
		(end 83.394042 -226.34194)
		(width 0.0889)
		(layer "In4.Cu")
		(net "M_D_CPU1_SA_DQ<3>")
	)
	(arc
		(start 82.389726 -225.550222)
		(mid 82.504402 -225.683556)
		(end 82.545682 -225.854514)
		(width 0.0889)
		(layer "In4.Cu")
		(net "M_D_CPU1_SA_DQ<3>")
	)
	(arc
		(start 80.506824 -222.308166)
		(mid 80.623685 -222.441931)
		(end 80.665828 -222.61449)
		(width 0.0889)
		(layer "In4.Cu")
		(net "M_D_CPU1_SA_DQ<3>")
	)
	(arc
		(start 81.919826 -224.740216)
		(mid 82.034502 -224.87355)
		(end 82.075782 -225.044508)
		(width 0.0889)
		(layer "In4.Cu")
		(net "M_D_CPU1_SA_DQ<3>")
	)
	(segment
		(start 92.507816 -244.750336)
		(end 92.040964 -244.484398)
		(width 0.10668)
		(layer "F.Cu")
		(net "M_D_CPU1_SA_DQ<31>")
	)
	(segment
		(start 90.339672 -244.156992)
		(end 90.348054 -244.161818)
		(width 0.0889)
		(layer "In4.Cu")
		(net "M_D_CPU1_SA_DQ<31>")
	)
	(segment
		(start 83.394042 -244.161818)
		(end 83.402424 -244.156992)
		(width 0.0889)
		(layer "In4.Cu")
		(net "M_D_CPU1_SA_DQ<31>")
	)
	(segment
		(start 32.695896 -233.885232)
		(end 33.121092 -234.310428)
		(width 0.14478)
		(layer "In4.Cu")
		(net "M_D_CPU1_SA_DQ<31>")
	)
	(segment
		(start 81.879694 -244.156992)
		(end 81.888076 -244.161818)
		(width 0.0889)
		(layer "In4.Cu")
		(net "M_D_CPU1_SA_DQ<31>")
	)
	(segment
		(start 76.204572 -243.510308)
		(end 76.50607 -243.811806)
		(width 0.0889)
		(layer "In4.Cu")
		(net "M_D_CPU1_SA_DQ<31>")
	)
	(segment
		(start 85.639656 -244.156992)
		(end 85.648038 -244.161818)
		(width 0.0889)
		(layer "In4.Cu")
		(net "M_D_CPU1_SA_DQ<31>")
	)
	(segment
		(start 33.91027 -233.39425)
		(end 34.103056 -233.201464)
		(width 0.14478)
		(layer "In4.Cu")
		(net "M_D_CPU1_SA_DQ<31>")
	)
	(segment
		(start 34.375598 -233.201464)
		(end 34.568384 -233.39425)
		(width 0.14478)
		(layer "In4.Cu")
		(net "M_D_CPU1_SA_DQ<31>")
	)
	(segment
		(start 86.57971 -244.156992)
		(end 86.588092 -244.161818)
		(width 0.0889)
		(layer "In4.Cu")
		(net "M_D_CPU1_SA_DQ<31>")
	)
	(segment
		(start 78.67777 -244.171216)
		(end 78.693518 -244.162072)
		(width 0.0889)
		(layer "In4.Cu")
		(net "M_D_CPU1_SA_DQ<31>")
	)
	(segment
		(start 92.195142 -244.218968)
		(end 92.040964 -244.484398)
		(width 0.0889)
		(layer "In4.Cu")
		(net "M_D_CPU1_SA_DQ<31>")
	)
	(segment
		(start 34.568384 -234.117642)
		(end 34.76117 -234.310428)
		(width 0.14478)
		(layer "In4.Cu")
		(net "M_D_CPU1_SA_DQ<31>")
	)
	(segment
		(start 59.588146 -234.310428)
		(end 68.788026 -243.510308)
		(width 0.14478)
		(layer "In4.Cu")
		(net "M_D_CPU1_SA_DQ<31>")
	)
	(segment
		(start 68.788026 -243.510308)
		(end 75.927966 -243.510308)
		(width 0.14478)
		(layer "In4.Cu")
		(net "M_D_CPU1_SA_DQ<31>")
	)
	(segment
		(start 88.094058 -244.161818)
		(end 88.10244 -244.156992)
		(width 0.0889)
		(layer "In4.Cu")
		(net "M_D_CPU1_SA_DQ<31>")
	)
	(segment
		(start 46.417738 -234.310428)
		(end 49.372266 -234.310428)
		(width 0.14478)
		(layer "In4.Cu")
		(net "M_D_CPU1_SA_DQ<31>")
	)
	(segment
		(start 77.458824 -244.111272)
		(end 77.940408 -244.111272)
		(width 0.0889)
		(layer "In4.Cu")
		(net "M_D_CPU1_SA_DQ<31>")
	)
	(segment
		(start 34.76117 -234.310428)
		(end 41.884092 -234.310428)
		(width 0.14478)
		(layer "In4.Cu")
		(net "M_D_CPU1_SA_DQ<31>")
	)
	(segment
		(start 34.568384 -233.39425)
		(end 34.568384 -234.117642)
		(width 0.14478)
		(layer "In4.Cu")
		(net "M_D_CPU1_SA_DQ<31>")
	)
	(segment
		(start 54.049676 -234.310428)
		(end 59.588146 -234.310428)
		(width 0.14478)
		(layer "In4.Cu")
		(net "M_D_CPU1_SA_DQ<31>")
	)
	(segment
		(start 79.067406 -244.161818)
		(end 79.07782 -244.167914)
		(width 0.0889)
		(layer "In4.Cu")
		(net "M_D_CPU1_SA_DQ<31>")
	)
	(segment
		(start 33.121092 -234.310428)
		(end 33.717484 -234.310428)
		(width 0.14478)
		(layer "In4.Cu")
		(net "M_D_CPU1_SA_DQ<31>")
	)
	(segment
		(start 42.73423 -233.46029)
		(end 45.5676 -233.46029)
		(width 0.14478)
		(layer "In4.Cu")
		(net "M_D_CPU1_SA_DQ<31>")
	)
	(segment
		(start 45.5676 -233.46029)
		(end 46.417738 -234.310428)
		(width 0.14478)
		(layer "In4.Cu")
		(net "M_D_CPU1_SA_DQ<31>")
	)
	(segment
		(start 87.154004 -244.161818)
		(end 87.162386 -244.156992)
		(width 0.0889)
		(layer "In4.Cu")
		(net "M_D_CPU1_SA_DQ<31>")
	)
	(segment
		(start 78.693518 -244.162072)
		(end 78.709774 -244.152674)
		(width 0.0889)
		(layer "In4.Cu")
		(net "M_D_CPU1_SA_DQ<31>")
	)
	(segment
		(start 76.50607 -243.811806)
		(end 77.159358 -243.811806)
		(width 0.0889)
		(layer "In4.Cu")
		(net "M_D_CPU1_SA_DQ<31>")
	)
	(segment
		(start 75.927966 -243.510308)
		(end 76.204572 -243.510308)
		(width 0.0889)
		(layer "In4.Cu")
		(net "M_D_CPU1_SA_DQ<31>")
	)
	(segment
		(start 50.222404 -233.46029)
		(end 53.199538 -233.46029)
		(width 0.14478)
		(layer "In4.Cu")
		(net "M_D_CPU1_SA_DQ<31>")
	)
	(segment
		(start 49.372266 -234.310428)
		(end 50.222404 -233.46029)
		(width 0.14478)
		(layer "In4.Cu")
		(net "M_D_CPU1_SA_DQ<31>")
	)
	(segment
		(start 33.91027 -234.117642)
		(end 33.91027 -233.39425)
		(width 0.14478)
		(layer "In4.Cu")
		(net "M_D_CPU1_SA_DQ<31>")
	)
	(segment
		(start 33.717484 -234.310428)
		(end 33.91027 -234.117642)
		(width 0.14478)
		(layer "In4.Cu")
		(net "M_D_CPU1_SA_DQ<31>")
	)
	(segment
		(start 53.199538 -233.46029)
		(end 54.049676 -234.310428)
		(width 0.14478)
		(layer "In4.Cu")
		(net "M_D_CPU1_SA_DQ<31>")
	)
	(segment
		(start 79.99984 -244.156992)
		(end 80.008222 -244.161818)
		(width 0.0889)
		(layer "In4.Cu")
		(net "M_D_CPU1_SA_DQ<31>")
	)
	(segment
		(start 82.453988 -244.161818)
		(end 82.46237 -244.156992)
		(width 0.0889)
		(layer "In4.Cu")
		(net "M_D_CPU1_SA_DQ<31>")
	)
	(segment
		(start 92.17279 -244.135656)
		(end 92.195142 -244.218968)
		(width 0.0889)
		(layer "In4.Cu")
		(net "M_D_CPU1_SA_DQ<31>")
	)
	(segment
		(start 90.913966 -244.161818)
		(end 90.922348 -244.156992)
		(width 0.0889)
		(layer "In4.Cu")
		(net "M_D_CPU1_SA_DQ<31>")
	)
	(segment
		(start 41.884092 -234.310428)
		(end 42.73423 -233.46029)
		(width 0.14478)
		(layer "In4.Cu")
		(net "M_D_CPU1_SA_DQ<31>")
	)
	(segment
		(start 91.85402 -244.161818)
		(end 91.862402 -244.156992)
		(width 0.0889)
		(layer "In4.Cu")
		(net "M_D_CPU1_SA_DQ<31>")
	)
	(segment
		(start 77.159358 -243.811806)
		(end 77.458824 -244.111272)
		(width 0.0889)
		(layer "In4.Cu")
		(net "M_D_CPU1_SA_DQ<31>")
	)
	(segment
		(start 34.103056 -233.201464)
		(end 34.375598 -233.201464)
		(width 0.14478)
		(layer "In4.Cu")
		(net "M_D_CPU1_SA_DQ<31>")
	)
	(arc
		(start 81.888076 -244.161818)
		(mid 82.171032 -244.237995)
		(end 82.453988 -244.161818)
		(width 0.0889)
		(layer "In4.Cu")
		(net "M_D_CPU1_SA_DQ<31>")
	)
	(arc
		(start 82.82813 -244.161818)
		(mid 83.111086 -244.237995)
		(end 83.394042 -244.161818)
		(width 0.0889)
		(layer "In4.Cu")
		(net "M_D_CPU1_SA_DQ<31>")
	)
	(arc
		(start 83.768184 -244.161818)
		(mid 84.05114 -244.237995)
		(end 84.334096 -244.161818)
		(width 0.0889)
		(layer "In4.Cu")
		(net "M_D_CPU1_SA_DQ<31>")
	)
	(arc
		(start 82.46237 -244.156992)
		(mid 82.645878 -244.111498)
		(end 82.82813 -244.161818)
		(width 0.0889)
		(layer "In4.Cu")
		(net "M_D_CPU1_SA_DQ<31>")
	)
	(arc
		(start 90.922348 -244.156992)
		(mid 91.105856 -244.111498)
		(end 91.288108 -244.161818)
		(width 0.0889)
		(layer "In4.Cu")
		(net "M_D_CPU1_SA_DQ<31>")
	)
	(arc
		(start 89.408 -244.161818)
		(mid 89.690956 -244.237995)
		(end 89.973912 -244.161818)
		(width 0.0889)
		(layer "In4.Cu")
		(net "M_D_CPU1_SA_DQ<31>")
	)
	(arc
		(start 80.574134 -244.161818)
		(mid 80.761078 -244.111563)
		(end 80.948022 -244.161818)
		(width 0.0889)
		(layer "In4.Cu")
		(net "M_D_CPU1_SA_DQ<31>")
	)
	(arc
		(start 78.709774 -244.152674)
		(mid 78.889756 -244.111574)
		(end 79.067406 -244.161818)
		(width 0.0889)
		(layer "In4.Cu")
		(net "M_D_CPU1_SA_DQ<31>")
	)
	(arc
		(start 84.334096 -244.161818)
		(mid 84.52104 -244.111563)
		(end 84.707984 -244.161818)
		(width 0.0889)
		(layer "In4.Cu")
		(net "M_D_CPU1_SA_DQ<31>")
	)
	(arc
		(start 86.588092 -244.161818)
		(mid 86.871048 -244.237995)
		(end 87.154004 -244.161818)
		(width 0.0889)
		(layer "In4.Cu")
		(net "M_D_CPU1_SA_DQ<31>")
	)
	(arc
		(start 91.862402 -244.156992)
		(mid 92.015272 -244.112351)
		(end 92.17279 -244.135656)
		(width 0.0889)
		(layer "In4.Cu")
		(net "M_D_CPU1_SA_DQ<31>")
	)
	(arc
		(start 85.648038 -244.161818)
		(mid 85.930994 -244.237995)
		(end 86.21395 -244.161818)
		(width 0.0889)
		(layer "In4.Cu")
		(net "M_D_CPU1_SA_DQ<31>")
	)
	(arc
		(start 89.973912 -244.161818)
		(mid 90.156163 -244.111468)
		(end 90.339672 -244.156992)
		(width 0.0889)
		(layer "In4.Cu")
		(net "M_D_CPU1_SA_DQ<31>")
	)
	(arc
		(start 78.127606 -244.161818)
		(mid 78.401461 -244.238168)
		(end 78.67777 -244.171216)
		(width 0.0889)
		(layer "In4.Cu")
		(net "M_D_CPU1_SA_DQ<31>")
	)
	(arc
		(start 83.402424 -244.156992)
		(mid 83.585932 -244.111498)
		(end 83.768184 -244.161818)
		(width 0.0889)
		(layer "In4.Cu")
		(net "M_D_CPU1_SA_DQ<31>")
	)
	(arc
		(start 80.008222 -244.161818)
		(mid 80.291178 -244.237995)
		(end 80.574134 -244.161818)
		(width 0.0889)
		(layer "In4.Cu")
		(net "M_D_CPU1_SA_DQ<31>")
	)
	(arc
		(start 91.288108 -244.161818)
		(mid 91.571064 -244.237995)
		(end 91.85402 -244.161818)
		(width 0.0889)
		(layer "In4.Cu")
		(net "M_D_CPU1_SA_DQ<31>")
	)
	(arc
		(start 77.940408 -244.111272)
		(mid 78.037359 -244.124147)
		(end 78.127606 -244.161818)
		(width 0.0889)
		(layer "In4.Cu")
		(net "M_D_CPU1_SA_DQ<31>")
	)
	(arc
		(start 85.273896 -244.161818)
		(mid 85.456147 -244.111468)
		(end 85.639656 -244.156992)
		(width 0.0889)
		(layer "In4.Cu")
		(net "M_D_CPU1_SA_DQ<31>")
	)
	(arc
		(start 79.07782 -244.167914)
		(mid 79.356506 -244.238134)
		(end 79.633572 -244.161818)
		(width 0.0889)
		(layer "In4.Cu")
		(net "M_D_CPU1_SA_DQ<31>")
	)
	(arc
		(start 88.4682 -244.161818)
		(mid 88.751156 -244.237995)
		(end 89.034112 -244.161818)
		(width 0.0889)
		(layer "In4.Cu")
		(net "M_D_CPU1_SA_DQ<31>")
	)
	(arc
		(start 90.348054 -244.161818)
		(mid 90.63101 -244.237995)
		(end 90.913966 -244.161818)
		(width 0.0889)
		(layer "In4.Cu")
		(net "M_D_CPU1_SA_DQ<31>")
	)
	(arc
		(start 81.513934 -244.161818)
		(mid 81.696185 -244.111468)
		(end 81.879694 -244.156992)
		(width 0.0889)
		(layer "In4.Cu")
		(net "M_D_CPU1_SA_DQ<31>")
	)
	(arc
		(start 79.633572 -244.161818)
		(mid 79.816077 -244.111341)
		(end 79.99984 -244.156992)
		(width 0.0889)
		(layer "In4.Cu")
		(net "M_D_CPU1_SA_DQ<31>")
	)
	(arc
		(start 84.707984 -244.161818)
		(mid 84.99094 -244.237995)
		(end 85.273896 -244.161818)
		(width 0.0889)
		(layer "In4.Cu")
		(net "M_D_CPU1_SA_DQ<31>")
	)
	(arc
		(start 89.034112 -244.161818)
		(mid 89.221056 -244.111563)
		(end 89.408 -244.161818)
		(width 0.0889)
		(layer "In4.Cu")
		(net "M_D_CPU1_SA_DQ<31>")
	)
	(arc
		(start 86.21395 -244.161818)
		(mid 86.396201 -244.111468)
		(end 86.57971 -244.156992)
		(width 0.0889)
		(layer "In4.Cu")
		(net "M_D_CPU1_SA_DQ<31>")
	)
	(arc
		(start 87.528146 -244.161818)
		(mid 87.811102 -244.237995)
		(end 88.094058 -244.161818)
		(width 0.0889)
		(layer "In4.Cu")
		(net "M_D_CPU1_SA_DQ<31>")
	)
	(arc
		(start 80.948022 -244.161818)
		(mid 81.230978 -244.237995)
		(end 81.513934 -244.161818)
		(width 0.0889)
		(layer "In4.Cu")
		(net "M_D_CPU1_SA_DQ<31>")
	)
	(arc
		(start 87.162386 -244.156992)
		(mid 87.345894 -244.111498)
		(end 87.528146 -244.161818)
		(width 0.0889)
		(layer "In4.Cu")
		(net "M_D_CPU1_SA_DQ<31>")
	)
	(arc
		(start 88.10244 -244.156992)
		(mid 88.285948 -244.111498)
		(end 88.4682 -244.161818)
		(width 0.0889)
		(layer "In4.Cu")
		(net "M_D_CPU1_SA_DQ<31>")
	)
	(segment
		(start 91.097862 -243.94033)
		(end 90.63101 -243.674392)
		(width 0.10668)
		(layer "F.Cu")
		(net "M_D_CPU1_SA_DQ<30>")
	)
	(segment
		(start 42.73423 -231.760268)
		(end 45.5676 -231.760268)
		(width 0.14478)
		(layer "In4.Cu")
		(net "M_D_CPU1_SA_DQ<30>")
	)
	(segment
		(start 75.95997 -242.595908)
		(end 76.308712 -242.595908)
		(width 0.0889)
		(layer "In4.Cu")
		(net "M_D_CPU1_SA_DQ<30>")
	)
	(segment
		(start 34.443416 -231.639364)
		(end 34.673794 -231.639364)
		(width 0.14478)
		(layer "In4.Cu")
		(net "M_D_CPU1_SA_DQ<30>")
	)
	(segment
		(start 53.256434 -231.760268)
		(end 54.106572 -232.610406)
		(width 0.14478)
		(layer "In4.Cu")
		(net "M_D_CPU1_SA_DQ<30>")
	)
	(segment
		(start 69.458586 -242.595908)
		(end 75.95997 -242.595908)
		(width 0.14478)
		(layer "In4.Cu")
		(net "M_D_CPU1_SA_DQ<30>")
	)
	(segment
		(start 45.5676 -231.760268)
		(end 46.417738 -232.610406)
		(width 0.14478)
		(layer "In4.Cu")
		(net "M_D_CPU1_SA_DQ<30>")
	)
	(segment
		(start 79.521304 -243.341652)
		(end 79.539592 -243.352066)
		(width 0.0889)
		(layer "In4.Cu")
		(net "M_D_CPU1_SA_DQ<30>")
	)
	(segment
		(start 35.393376 -231.950514)
		(end 35.556444 -231.787446)
		(width 0.14478)
		(layer "In4.Cu")
		(net "M_D_CPU1_SA_DQ<30>")
	)
	(segment
		(start 80.46974 -243.346986)
		(end 80.478122 -243.351812)
		(width 0.0889)
		(layer "In4.Cu")
		(net "M_D_CPU1_SA_DQ<30>")
	)
	(segment
		(start 35.393376 -232.447338)
		(end 35.393376 -231.950514)
		(width 0.14478)
		(layer "In4.Cu")
		(net "M_D_CPU1_SA_DQ<30>")
	)
	(segment
		(start 76.308712 -242.595908)
		(end 76.45019 -242.737386)
		(width 0.0889)
		(layer "In4.Cu")
		(net "M_D_CPU1_SA_DQ<30>")
	)
	(segment
		(start 79.539592 -243.352066)
		(end 79.561182 -243.364512)
		(width 0.0889)
		(layer "In4.Cu")
		(net "M_D_CPU1_SA_DQ<30>")
	)
	(segment
		(start 84.229702 -243.346986)
		(end 84.238084 -243.351812)
		(width 0.0889)
		(layer "In4.Cu")
		(net "M_D_CPU1_SA_DQ<30>")
	)
	(segment
		(start 88.929718 -243.346986)
		(end 88.9381 -243.351812)
		(width 0.0889)
		(layer "In4.Cu")
		(net "M_D_CPU1_SA_DQ<30>")
	)
	(segment
		(start 35.230308 -232.610406)
		(end 35.393376 -232.447338)
		(width 0.14478)
		(layer "In4.Cu")
		(net "M_D_CPU1_SA_DQ<30>")
	)
	(segment
		(start 85.74405 -243.351812)
		(end 85.752432 -243.346986)
		(width 0.0889)
		(layer "In4.Cu")
		(net "M_D_CPU1_SA_DQ<30>")
	)
	(segment
		(start 81.044034 -243.351812)
		(end 81.052416 -243.346986)
		(width 0.0889)
		(layer "In4.Cu")
		(net "M_D_CPU1_SA_DQ<30>")
	)
	(segment
		(start 77.618082 -243.300758)
		(end 78.41107 -243.300758)
		(width 0.0889)
		(layer "In4.Cu")
		(net "M_D_CPU1_SA_DQ<30>")
	)
	(segment
		(start 34.836862 -232.447338)
		(end 34.99993 -232.610406)
		(width 0.14478)
		(layer "In4.Cu")
		(net "M_D_CPU1_SA_DQ<30>")
	)
	(segment
		(start 35.556444 -231.787446)
		(end 35.786822 -231.787446)
		(width 0.14478)
		(layer "In4.Cu")
		(net "M_D_CPU1_SA_DQ<30>")
	)
	(segment
		(start 84.803996 -243.351812)
		(end 84.812378 -243.346986)
		(width 0.0889)
		(layer "In4.Cu")
		(net "M_D_CPU1_SA_DQ<30>")
	)
	(segment
		(start 34.280348 -232.447338)
		(end 34.280348 -231.802432)
		(width 0.14478)
		(layer "In4.Cu")
		(net "M_D_CPU1_SA_DQ<30>")
	)
	(segment
		(start 33.121092 -232.610406)
		(end 34.11728 -232.610406)
		(width 0.14478)
		(layer "In4.Cu")
		(net "M_D_CPU1_SA_DQ<30>")
	)
	(segment
		(start 46.417738 -232.610406)
		(end 49.372266 -232.610406)
		(width 0.14478)
		(layer "In4.Cu")
		(net "M_D_CPU1_SA_DQ<30>")
	)
	(segment
		(start 50.222404 -231.760268)
		(end 53.256434 -231.760268)
		(width 0.14478)
		(layer "In4.Cu")
		(net "M_D_CPU1_SA_DQ<30>")
	)
	(segment
		(start 90.784934 -243.408962)
		(end 90.63101 -243.674392)
		(width 0.0889)
		(layer "In4.Cu")
		(net "M_D_CPU1_SA_DQ<30>")
	)
	(segment
		(start 54.106572 -232.610406)
		(end 59.473084 -232.610406)
		(width 0.14478)
		(layer "In4.Cu")
		(net "M_D_CPU1_SA_DQ<30>")
	)
	(segment
		(start 34.673794 -231.639364)
		(end 34.836862 -231.802432)
		(width 0.14478)
		(layer "In4.Cu")
		(net "M_D_CPU1_SA_DQ<30>")
	)
	(segment
		(start 35.786822 -231.787446)
		(end 35.94989 -231.950514)
		(width 0.14478)
		(layer "In4.Cu")
		(net "M_D_CPU1_SA_DQ<30>")
	)
	(segment
		(start 34.836862 -231.802432)
		(end 34.836862 -232.447338)
		(width 0.14478)
		(layer "In4.Cu")
		(net "M_D_CPU1_SA_DQ<30>")
	)
	(segment
		(start 77.05471 -242.737386)
		(end 77.618082 -243.300758)
		(width 0.0889)
		(layer "In4.Cu")
		(net "M_D_CPU1_SA_DQ<30>")
	)
	(segment
		(start 76.45019 -242.737386)
		(end 77.05471 -242.737386)
		(width 0.0889)
		(layer "In4.Cu")
		(net "M_D_CPU1_SA_DQ<30>")
	)
	(segment
		(start 49.372266 -232.610406)
		(end 50.222404 -231.760268)
		(width 0.14478)
		(layer "In4.Cu")
		(net "M_D_CPU1_SA_DQ<30>")
	)
	(segment
		(start 34.280348 -231.802432)
		(end 34.443416 -231.639364)
		(width 0.14478)
		(layer "In4.Cu")
		(net "M_D_CPU1_SA_DQ<30>")
	)
	(segment
		(start 32.695896 -232.18521)
		(end 33.121092 -232.610406)
		(width 0.14478)
		(layer "In4.Cu")
		(net "M_D_CPU1_SA_DQ<30>")
	)
	(segment
		(start 90.762582 -243.32565)
		(end 90.784934 -243.408962)
		(width 0.0889)
		(layer "In4.Cu")
		(net "M_D_CPU1_SA_DQ<30>")
	)
	(segment
		(start 41.884092 -232.610406)
		(end 42.73423 -231.760268)
		(width 0.14478)
		(layer "In4.Cu")
		(net "M_D_CPU1_SA_DQ<30>")
	)
	(segment
		(start 34.99993 -232.610406)
		(end 35.230308 -232.610406)
		(width 0.14478)
		(layer "In4.Cu")
		(net "M_D_CPU1_SA_DQ<30>")
	)
	(segment
		(start 83.289648 -243.346986)
		(end 83.29803 -243.351812)
		(width 0.0889)
		(layer "In4.Cu")
		(net "M_D_CPU1_SA_DQ<30>")
	)
	(segment
		(start 34.11728 -232.610406)
		(end 34.280348 -232.447338)
		(width 0.14478)
		(layer "In4.Cu")
		(net "M_D_CPU1_SA_DQ<30>")
	)
	(segment
		(start 89.504012 -243.351812)
		(end 89.512394 -243.346986)
		(width 0.0889)
		(layer "In4.Cu")
		(net "M_D_CPU1_SA_DQ<30>")
	)
	(segment
		(start 79.143098 -243.365528)
		(end 79.166466 -243.351812)
		(width 0.0889)
		(layer "In4.Cu")
		(net "M_D_CPU1_SA_DQ<30>")
	)
	(segment
		(start 59.473084 -232.610406)
		(end 69.458586 -242.595908)
		(width 0.14478)
		(layer "In4.Cu")
		(net "M_D_CPU1_SA_DQ<30>")
	)
	(segment
		(start 36.112958 -232.610406)
		(end 41.884092 -232.610406)
		(width 0.14478)
		(layer "In4.Cu")
		(net "M_D_CPU1_SA_DQ<30>")
	)
	(segment
		(start 35.94989 -231.950514)
		(end 35.94989 -232.447338)
		(width 0.14478)
		(layer "In4.Cu")
		(net "M_D_CPU1_SA_DQ<30>")
	)
	(segment
		(start 87.989664 -243.346986)
		(end 87.998046 -243.351812)
		(width 0.0889)
		(layer "In4.Cu")
		(net "M_D_CPU1_SA_DQ<30>")
	)
	(segment
		(start 35.94989 -232.447338)
		(end 36.112958 -232.610406)
		(width 0.14478)
		(layer "In4.Cu")
		(net "M_D_CPU1_SA_DQ<30>")
	)
	(arc
		(start 80.478122 -243.351812)
		(mid 80.761078 -243.427989)
		(end 81.044034 -243.351812)
		(width 0.0889)
		(layer "In4.Cu")
		(net "M_D_CPU1_SA_DQ<30>")
	)
	(arc
		(start 88.9381 -243.351812)
		(mid 89.221056 -243.427989)
		(end 89.504012 -243.351812)
		(width 0.0889)
		(layer "In4.Cu")
		(net "M_D_CPU1_SA_DQ<30>")
	)
	(arc
		(start 79.561182 -243.364512)
		(mid 79.834211 -243.427831)
		(end 80.10398 -243.351812)
		(width 0.0889)
		(layer "In4.Cu")
		(net "M_D_CPU1_SA_DQ<30>")
	)
	(arc
		(start 83.863942 -243.351812)
		(mid 84.046193 -243.301462)
		(end 84.229702 -243.346986)
		(width 0.0889)
		(layer "In4.Cu")
		(net "M_D_CPU1_SA_DQ<30>")
	)
	(arc
		(start 89.512394 -243.346986)
		(mid 89.695902 -243.301492)
		(end 89.878154 -243.351812)
		(width 0.0889)
		(layer "In4.Cu")
		(net "M_D_CPU1_SA_DQ<30>")
	)
	(arc
		(start 90.444066 -243.351812)
		(mid 90.600385 -243.302817)
		(end 90.762582 -243.32565)
		(width 0.0889)
		(layer "In4.Cu")
		(net "M_D_CPU1_SA_DQ<30>")
	)
	(arc
		(start 80.10398 -243.351812)
		(mid 80.286231 -243.301462)
		(end 80.46974 -243.346986)
		(width 0.0889)
		(layer "In4.Cu")
		(net "M_D_CPU1_SA_DQ<30>")
	)
	(arc
		(start 86.118192 -243.351812)
		(mid 86.401148 -243.427989)
		(end 86.684104 -243.351812)
		(width 0.0889)
		(layer "In4.Cu")
		(net "M_D_CPU1_SA_DQ<30>")
	)
	(arc
		(start 78.599284 -243.351812)
		(mid 78.869441 -243.428574)
		(end 79.143098 -243.365528)
		(width 0.0889)
		(layer "In4.Cu")
		(net "M_D_CPU1_SA_DQ<30>")
	)
	(arc
		(start 82.923888 -243.351812)
		(mid 83.106139 -243.301462)
		(end 83.289648 -243.346986)
		(width 0.0889)
		(layer "In4.Cu")
		(net "M_D_CPU1_SA_DQ<30>")
	)
	(arc
		(start 81.418176 -243.351812)
		(mid 81.701132 -243.427989)
		(end 81.984088 -243.351812)
		(width 0.0889)
		(layer "In4.Cu")
		(net "M_D_CPU1_SA_DQ<30>")
	)
	(arc
		(start 85.752432 -243.346986)
		(mid 85.93594 -243.301492)
		(end 86.118192 -243.351812)
		(width 0.0889)
		(layer "In4.Cu")
		(net "M_D_CPU1_SA_DQ<30>")
	)
	(arc
		(start 86.684104 -243.351812)
		(mid 86.871048 -243.301557)
		(end 87.057992 -243.351812)
		(width 0.0889)
		(layer "In4.Cu")
		(net "M_D_CPU1_SA_DQ<30>")
	)
	(arc
		(start 85.178138 -243.351812)
		(mid 85.461094 -243.427989)
		(end 85.74405 -243.351812)
		(width 0.0889)
		(layer "In4.Cu")
		(net "M_D_CPU1_SA_DQ<30>")
	)
	(arc
		(start 83.29803 -243.351812)
		(mid 83.580986 -243.427989)
		(end 83.863942 -243.351812)
		(width 0.0889)
		(layer "In4.Cu")
		(net "M_D_CPU1_SA_DQ<30>")
	)
	(arc
		(start 89.878154 -243.351812)
		(mid 90.16111 -243.427989)
		(end 90.444066 -243.351812)
		(width 0.0889)
		(layer "In4.Cu")
		(net "M_D_CPU1_SA_DQ<30>")
	)
	(arc
		(start 81.052416 -243.346986)
		(mid 81.235924 -243.301492)
		(end 81.418176 -243.351812)
		(width 0.0889)
		(layer "In4.Cu")
		(net "M_D_CPU1_SA_DQ<30>")
	)
	(arc
		(start 88.563958 -243.351812)
		(mid 88.746209 -243.301462)
		(end 88.929718 -243.346986)
		(width 0.0889)
		(layer "In4.Cu")
		(net "M_D_CPU1_SA_DQ<30>")
	)
	(arc
		(start 87.998046 -243.351812)
		(mid 88.281002 -243.427989)
		(end 88.563958 -243.351812)
		(width 0.0889)
		(layer "In4.Cu")
		(net "M_D_CPU1_SA_DQ<30>")
	)
	(arc
		(start 79.166466 -243.351812)
		(mid 79.342586 -243.301834)
		(end 79.521304 -243.341652)
		(width 0.0889)
		(layer "In4.Cu")
		(net "M_D_CPU1_SA_DQ<30>")
	)
	(arc
		(start 84.812378 -243.346986)
		(mid 84.995886 -243.301492)
		(end 85.178138 -243.351812)
		(width 0.0889)
		(layer "In4.Cu")
		(net "M_D_CPU1_SA_DQ<30>")
	)
	(arc
		(start 84.238084 -243.351812)
		(mid 84.52104 -243.427989)
		(end 84.803996 -243.351812)
		(width 0.0889)
		(layer "In4.Cu")
		(net "M_D_CPU1_SA_DQ<30>")
	)
	(arc
		(start 81.984088 -243.351812)
		(mid 82.171032 -243.301557)
		(end 82.357976 -243.351812)
		(width 0.0889)
		(layer "In4.Cu")
		(net "M_D_CPU1_SA_DQ<30>")
	)
	(arc
		(start 78.41107 -243.300758)
		(mid 78.508573 -243.313773)
		(end 78.599284 -243.351812)
		(width 0.0889)
		(layer "In4.Cu")
		(net "M_D_CPU1_SA_DQ<30>")
	)
	(arc
		(start 82.357976 -243.351812)
		(mid 82.640932 -243.427989)
		(end 82.923888 -243.351812)
		(width 0.0889)
		(layer "In4.Cu")
		(net "M_D_CPU1_SA_DQ<30>")
	)
	(arc
		(start 87.623904 -243.351812)
		(mid 87.806155 -243.301462)
		(end 87.989664 -243.346986)
		(width 0.0889)
		(layer "In4.Cu")
		(net "M_D_CPU1_SA_DQ<30>")
	)
	(arc
		(start 87.057992 -243.351812)
		(mid 87.340948 -243.427989)
		(end 87.623904 -243.351812)
		(width 0.0889)
		(layer "In4.Cu")
		(net "M_D_CPU1_SA_DQ<30>")
	)
	(segment
		(start 91.097862 -226.120452)
		(end 90.63101 -225.854514)
		(width 0.10668)
		(layer "F.Cu")
		(net "M_D_CPU1_SA_DQ<2>")
	)
	(segment
		(start 35.550094 -198.447406)
		(end 35.713162 -198.610474)
		(width 0.14478)
		(layer "In4.Cu")
		(net "M_D_CPU1_SA_DQ<2>")
	)
	(segment
		(start 50.222404 -197.760336)
		(end 53.256434 -197.760336)
		(width 0.14478)
		(layer "In4.Cu")
		(net "M_D_CPU1_SA_DQ<2>")
	)
	(segment
		(start 33.121092 -198.610474)
		(end 33.717484 -198.610474)
		(width 0.14478)
		(layer "In4.Cu")
		(net "M_D_CPU1_SA_DQ<2>")
	)
	(segment
		(start 82.789014 -224.699068)
		(end 82.82813 -224.721928)
		(width 0.0889)
		(layer "In4.Cu")
		(net "M_D_CPU1_SA_DQ<2>")
	)
	(segment
		(start 35.387026 -198.015606)
		(end 35.550094 -198.178674)
		(width 0.14478)
		(layer "In4.Cu")
		(net "M_D_CPU1_SA_DQ<2>")
	)
	(segment
		(start 34.273998 -198.005446)
		(end 34.437066 -198.168514)
		(width 0.14478)
		(layer "In4.Cu")
		(net "M_D_CPU1_SA_DQ<2>")
	)
	(segment
		(start 88.929718 -225.527108)
		(end 88.9381 -225.531934)
		(width 0.0889)
		(layer "In4.Cu")
		(net "M_D_CPU1_SA_DQ<2>")
	)
	(segment
		(start 82.357976 -223.911922)
		(end 82.389726 -223.93021)
		(width 0.0889)
		(layer "In4.Cu")
		(net "M_D_CPU1_SA_DQ<2>")
	)
	(segment
		(start 34.04362 -198.005446)
		(end 34.273998 -198.005446)
		(width 0.14478)
		(layer "In4.Cu")
		(net "M_D_CPU1_SA_DQ<2>")
	)
	(segment
		(start 34.437066 -198.447406)
		(end 34.600134 -198.610474)
		(width 0.14478)
		(layer "In4.Cu")
		(net "M_D_CPU1_SA_DQ<2>")
	)
	(segment
		(start 84.803996 -225.531934)
		(end 84.812378 -225.527108)
		(width 0.0889)
		(layer "In4.Cu")
		(net "M_D_CPU1_SA_DQ<2>")
	)
	(segment
		(start 53.256434 -197.760336)
		(end 54.106572 -198.610474)
		(width 0.14478)
		(layer "In4.Cu")
		(net "M_D_CPU1_SA_DQ<2>")
	)
	(segment
		(start 41.884092 -198.610474)
		(end 42.73423 -197.760336)
		(width 0.14478)
		(layer "In4.Cu")
		(net "M_D_CPU1_SA_DQ<2>")
	)
	(segment
		(start 34.99358 -198.178674)
		(end 35.156648 -198.015606)
		(width 0.14478)
		(layer "In4.Cu")
		(net "M_D_CPU1_SA_DQ<2>")
	)
	(segment
		(start 54.106572 -198.610474)
		(end 59.965336 -198.610474)
		(width 0.14478)
		(layer "In4.Cu")
		(net "M_D_CPU1_SA_DQ<2>")
	)
	(segment
		(start 81.094326 -221.521782)
		(end 81.605628 -222.033084)
		(width 0.0889)
		(layer "In4.Cu")
		(net "M_D_CPU1_SA_DQ<2>")
	)
	(segment
		(start 81.888076 -223.101916)
		(end 81.919826 -223.120204)
		(width 0.0889)
		(layer "In4.Cu")
		(net "M_D_CPU1_SA_DQ<2>")
	)
	(segment
		(start 90.784934 -225.589084)
		(end 90.63101 -225.854514)
		(width 0.0889)
		(layer "In4.Cu")
		(net "M_D_CPU1_SA_DQ<2>")
	)
	(segment
		(start 82.321654 -223.89084)
		(end 82.357976 -223.911922)
		(width 0.0889)
		(layer "In4.Cu")
		(net "M_D_CPU1_SA_DQ<2>")
	)
	(segment
		(start 82.82813 -224.721928)
		(end 82.85861 -224.739708)
		(width 0.0889)
		(layer "In4.Cu")
		(net "M_D_CPU1_SA_DQ<2>")
	)
	(segment
		(start 33.880552 -198.168514)
		(end 34.04362 -198.005446)
		(width 0.14478)
		(layer "In4.Cu")
		(net "M_D_CPU1_SA_DQ<2>")
	)
	(segment
		(start 81.84896 -223.079056)
		(end 81.888076 -223.101916)
		(width 0.0889)
		(layer "In4.Cu")
		(net "M_D_CPU1_SA_DQ<2>")
	)
	(segment
		(start 49.372266 -198.610474)
		(end 50.222404 -197.760336)
		(width 0.14478)
		(layer "In4.Cu")
		(net "M_D_CPU1_SA_DQ<2>")
	)
	(segment
		(start 83.258914 -225.509074)
		(end 83.29803 -225.531934)
		(width 0.0889)
		(layer "In4.Cu")
		(net "M_D_CPU1_SA_DQ<2>")
	)
	(segment
		(start 35.156648 -198.015606)
		(end 35.387026 -198.015606)
		(width 0.14478)
		(layer "In4.Cu")
		(net "M_D_CPU1_SA_DQ<2>")
	)
	(segment
		(start 34.99358 -198.447406)
		(end 34.99358 -198.178674)
		(width 0.14478)
		(layer "In4.Cu")
		(net "M_D_CPU1_SA_DQ<2>")
	)
	(segment
		(start 32.695896 -198.185278)
		(end 33.121092 -198.610474)
		(width 0.14478)
		(layer "In4.Cu")
		(net "M_D_CPU1_SA_DQ<2>")
	)
	(segment
		(start 59.965336 -198.610474)
		(end 81.094326 -219.739464)
		(width 0.14478)
		(layer "In4.Cu")
		(net "M_D_CPU1_SA_DQ<2>")
	)
	(segment
		(start 87.989664 -225.527108)
		(end 87.998046 -225.531934)
		(width 0.0889)
		(layer "In4.Cu")
		(net "M_D_CPU1_SA_DQ<2>")
	)
	(segment
		(start 45.5676 -197.760336)
		(end 46.417738 -198.610474)
		(width 0.14478)
		(layer "In4.Cu")
		(net "M_D_CPU1_SA_DQ<2>")
	)
	(segment
		(start 90.762582 -225.505772)
		(end 90.784934 -225.589084)
		(width 0.0889)
		(layer "In4.Cu")
		(net "M_D_CPU1_SA_DQ<2>")
	)
	(segment
		(start 35.550094 -198.178674)
		(end 35.550094 -198.447406)
		(width 0.14478)
		(layer "In4.Cu")
		(net "M_D_CPU1_SA_DQ<2>")
	)
	(segment
		(start 85.74405 -225.531934)
		(end 85.752432 -225.527108)
		(width 0.0889)
		(layer "In4.Cu")
		(net "M_D_CPU1_SA_DQ<2>")
	)
	(segment
		(start 46.417738 -198.610474)
		(end 49.372266 -198.610474)
		(width 0.14478)
		(layer "In4.Cu")
		(net "M_D_CPU1_SA_DQ<2>")
	)
	(segment
		(start 89.504012 -225.531934)
		(end 89.512394 -225.527108)
		(width 0.0889)
		(layer "In4.Cu")
		(net "M_D_CPU1_SA_DQ<2>")
	)
	(segment
		(start 34.600134 -198.610474)
		(end 34.830512 -198.610474)
		(width 0.14478)
		(layer "In4.Cu")
		(net "M_D_CPU1_SA_DQ<2>")
	)
	(segment
		(start 81.605628 -222.033084)
		(end 81.605628 -222.61449)
		(width 0.0889)
		(layer "In4.Cu")
		(net "M_D_CPU1_SA_DQ<2>")
	)
	(segment
		(start 34.437066 -198.168514)
		(end 34.437066 -198.447406)
		(width 0.14478)
		(layer "In4.Cu")
		(net "M_D_CPU1_SA_DQ<2>")
	)
	(segment
		(start 33.880552 -198.447406)
		(end 33.880552 -198.168514)
		(width 0.14478)
		(layer "In4.Cu")
		(net "M_D_CPU1_SA_DQ<2>")
	)
	(segment
		(start 42.73423 -197.760336)
		(end 45.5676 -197.760336)
		(width 0.14478)
		(layer "In4.Cu")
		(net "M_D_CPU1_SA_DQ<2>")
	)
	(segment
		(start 81.094326 -221.304104)
		(end 81.094326 -221.521782)
		(width 0.0889)
		(layer "In4.Cu")
		(net "M_D_CPU1_SA_DQ<2>")
	)
	(segment
		(start 35.713162 -198.610474)
		(end 41.884092 -198.610474)
		(width 0.14478)
		(layer "In4.Cu")
		(net "M_D_CPU1_SA_DQ<2>")
	)
	(segment
		(start 33.717484 -198.610474)
		(end 33.880552 -198.447406)
		(width 0.14478)
		(layer "In4.Cu")
		(net "M_D_CPU1_SA_DQ<2>")
	)
	(segment
		(start 84.229702 -225.527108)
		(end 84.238084 -225.531934)
		(width 0.0889)
		(layer "In4.Cu")
		(net "M_D_CPU1_SA_DQ<2>")
	)
	(segment
		(start 34.830512 -198.610474)
		(end 34.99358 -198.447406)
		(width 0.14478)
		(layer "In4.Cu")
		(net "M_D_CPU1_SA_DQ<2>")
	)
	(segment
		(start 81.094326 -219.739464)
		(end 81.094326 -221.304104)
		(width 0.14478)
		(layer "In4.Cu")
		(net "M_D_CPU1_SA_DQ<2>")
	)
	(arc
		(start 88.9381 -225.531934)
		(mid 89.221056 -225.608111)
		(end 89.504012 -225.531934)
		(width 0.0889)
		(layer "In4.Cu")
		(net "M_D_CPU1_SA_DQ<2>")
	)
	(arc
		(start 83.015582 -225.044508)
		(mid 83.080097 -225.306727)
		(end 83.258914 -225.509074)
		(width 0.0889)
		(layer "In4.Cu")
		(net "M_D_CPU1_SA_DQ<2>")
	)
	(arc
		(start 84.812378 -225.527108)
		(mid 84.995886 -225.481614)
		(end 85.178138 -225.531934)
		(width 0.0889)
		(layer "In4.Cu")
		(net "M_D_CPU1_SA_DQ<2>")
	)
	(arc
		(start 85.752432 -225.527108)
		(mid 85.93594 -225.481614)
		(end 86.118192 -225.531934)
		(width 0.0889)
		(layer "In4.Cu")
		(net "M_D_CPU1_SA_DQ<2>")
	)
	(arc
		(start 89.878154 -225.531934)
		(mid 90.16111 -225.608111)
		(end 90.444066 -225.531934)
		(width 0.0889)
		(layer "In4.Cu")
		(net "M_D_CPU1_SA_DQ<2>")
	)
	(arc
		(start 84.238084 -225.531934)
		(mid 84.52104 -225.608111)
		(end 84.803996 -225.531934)
		(width 0.0889)
		(layer "In4.Cu")
		(net "M_D_CPU1_SA_DQ<2>")
	)
	(arc
		(start 82.389726 -223.93021)
		(mid 82.504402 -224.063544)
		(end 82.545682 -224.234502)
		(width 0.0889)
		(layer "In4.Cu")
		(net "M_D_CPU1_SA_DQ<2>")
	)
	(arc
		(start 81.919826 -223.120204)
		(mid 82.034502 -223.253538)
		(end 82.075782 -223.424496)
		(width 0.0889)
		(layer "In4.Cu")
		(net "M_D_CPU1_SA_DQ<2>")
	)
	(arc
		(start 83.29803 -225.531934)
		(mid 83.580986 -225.608111)
		(end 83.863942 -225.531934)
		(width 0.0889)
		(layer "In4.Cu")
		(net "M_D_CPU1_SA_DQ<2>")
	)
	(arc
		(start 83.863942 -225.531934)
		(mid 84.046193 -225.481584)
		(end 84.229702 -225.527108)
		(width 0.0889)
		(layer "In4.Cu")
		(net "M_D_CPU1_SA_DQ<2>")
	)
	(arc
		(start 86.684104 -225.531934)
		(mid 86.871048 -225.481679)
		(end 87.057992 -225.531934)
		(width 0.0889)
		(layer "In4.Cu")
		(net "M_D_CPU1_SA_DQ<2>")
	)
	(arc
		(start 82.545682 -224.234502)
		(mid 82.610197 -224.496721)
		(end 82.789014 -224.699068)
		(width 0.0889)
		(layer "In4.Cu")
		(net "M_D_CPU1_SA_DQ<2>")
	)
	(arc
		(start 86.118192 -225.531934)
		(mid 86.401148 -225.608111)
		(end 86.684104 -225.531934)
		(width 0.0889)
		(layer "In4.Cu")
		(net "M_D_CPU1_SA_DQ<2>")
	)
	(arc
		(start 90.444066 -225.531934)
		(mid 90.600385 -225.482939)
		(end 90.762582 -225.505772)
		(width 0.0889)
		(layer "In4.Cu")
		(net "M_D_CPU1_SA_DQ<2>")
	)
	(arc
		(start 89.512394 -225.527108)
		(mid 89.695902 -225.481614)
		(end 89.878154 -225.531934)
		(width 0.0889)
		(layer "In4.Cu")
		(net "M_D_CPU1_SA_DQ<2>")
	)
	(arc
		(start 87.998046 -225.531934)
		(mid 88.281002 -225.608111)
		(end 88.563958 -225.531934)
		(width 0.0889)
		(layer "In4.Cu")
		(net "M_D_CPU1_SA_DQ<2>")
	)
	(arc
		(start 87.057992 -225.531934)
		(mid 87.340948 -225.608111)
		(end 87.623904 -225.531934)
		(width 0.0889)
		(layer "In4.Cu")
		(net "M_D_CPU1_SA_DQ<2>")
	)
	(arc
		(start 82.85861 -224.739708)
		(mid 82.974037 -224.873084)
		(end 83.015582 -225.044508)
		(width 0.0889)
		(layer "In4.Cu")
		(net "M_D_CPU1_SA_DQ<2>")
	)
	(arc
		(start 87.623904 -225.531934)
		(mid 87.806155 -225.481584)
		(end 87.989664 -225.527108)
		(width 0.0889)
		(layer "In4.Cu")
		(net "M_D_CPU1_SA_DQ<2>")
	)
	(arc
		(start 81.605628 -222.61449)
		(mid 81.670143 -222.876709)
		(end 81.84896 -223.079056)
		(width 0.0889)
		(layer "In4.Cu")
		(net "M_D_CPU1_SA_DQ<2>")
	)
	(arc
		(start 82.075782 -223.424496)
		(mid 82.141018 -223.688087)
		(end 82.321654 -223.89084)
		(width 0.0889)
		(layer "In4.Cu")
		(net "M_D_CPU1_SA_DQ<2>")
	)
	(arc
		(start 85.178138 -225.531934)
		(mid 85.461094 -225.608111)
		(end 85.74405 -225.531934)
		(width 0.0889)
		(layer "In4.Cu")
		(net "M_D_CPU1_SA_DQ<2>")
	)
	(arc
		(start 88.563958 -225.531934)
		(mid 88.746209 -225.481584)
		(end 88.929718 -225.527108)
		(width 0.0889)
		(layer "In4.Cu")
		(net "M_D_CPU1_SA_DQ<2>")
	)
	(segment
		(start 92.97797 -243.94033)
		(end 92.511118 -243.674392)
		(width 0.10668)
		(layer "F.Cu")
		(net "M_D_CPU1_SA_DQ<29>")
	)
	(segment
		(start 38.85946 -233.244644)
		(end 38.85946 -233.675936)
		(width 0.14478)
		(layer "In4.Cu")
		(net "M_D_CPU1_SA_DQ<29>")
	)
	(segment
		(start 56.116982 -233.688382)
		(end 56.116982 -233.22407)
		(width 0.14478)
		(layer "In4.Cu")
		(net "M_D_CPU1_SA_DQ<29>")
	)
	(segment
		(start 78.59776 -243.996718)
		(end 78.603348 -243.993416)
		(width 0.0889)
		(layer "In4.Cu")
		(net "M_D_CPU1_SA_DQ<29>")
	)
	(segment
		(start 83.289648 -244.001798)
		(end 83.29803 -243.996972)
		(width 0.0889)
		(layer "In4.Cu")
		(net "M_D_CPU1_SA_DQ<29>")
	)
	(segment
		(start 54.434994 -233.074464)
		(end 54.665372 -233.074464)
		(width 0.14478)
		(layer "In4.Cu")
		(net "M_D_CPU1_SA_DQ<29>")
	)
	(segment
		(start 57.771284 -233.22407)
		(end 57.771284 -233.69651)
		(width 0.14478)
		(layer "In4.Cu")
		(net "M_D_CPU1_SA_DQ<29>")
	)
	(segment
		(start 39.415974 -233.623358)
		(end 39.579042 -233.46029)
		(width 0.14478)
		(layer "In4.Cu")
		(net "M_D_CPU1_SA_DQ<29>")
	)
	(segment
		(start 91.749626 -244.001798)
		(end 91.758008 -243.996972)
		(width 0.0889)
		(layer "In4.Cu")
		(net "M_D_CPU1_SA_DQ<29>")
	)
	(segment
		(start 37.746432 -233.623358)
		(end 37.746432 -233.675936)
		(width 0.14478)
		(layer "In4.Cu")
		(net "M_D_CPU1_SA_DQ<29>")
	)
	(segment
		(start 85.74405 -243.996972)
		(end 85.752432 -244.001798)
		(width 0.0889)
		(layer "In4.Cu")
		(net "M_D_CPU1_SA_DQ<29>")
	)
	(segment
		(start 56.506872 -233.062526)
		(end 56.668416 -233.22407)
		(width 0.14478)
		(layer "In4.Cu")
		(net "M_D_CPU1_SA_DQ<29>")
	)
	(segment
		(start 57.381394 -233.062526)
		(end 57.60974 -233.062526)
		(width 0.14478)
		(layer "In4.Cu")
		(net "M_D_CPU1_SA_DQ<29>")
	)
	(segment
		(start 57.058306 -233.858054)
		(end 57.21985 -233.69651)
		(width 0.14478)
		(layer "In4.Cu")
		(net "M_D_CPU1_SA_DQ<29>")
	)
	(segment
		(start 87.989664 -244.001798)
		(end 87.998046 -243.996972)
		(width 0.0889)
		(layer "In4.Cu")
		(net "M_D_CPU1_SA_DQ<29>")
	)
	(segment
		(start 39.022528 -233.839004)
		(end 39.252906 -233.839004)
		(width 0.14478)
		(layer "In4.Cu")
		(net "M_D_CPU1_SA_DQ<29>")
	)
	(segment
		(start 45.55871 -232.610406)
		(end 46.408594 -233.46029)
		(width 0.14478)
		(layer "In4.Cu")
		(net "M_D_CPU1_SA_DQ<29>")
	)
	(segment
		(start 92.260674 -243.965222)
		(end 92.35694 -243.939822)
		(width 0.0889)
		(layer "In4.Cu")
		(net "M_D_CPU1_SA_DQ<29>")
	)
	(segment
		(start 56.116982 -233.22407)
		(end 56.278526 -233.062526)
		(width 0.14478)
		(layer "In4.Cu")
		(net "M_D_CPU1_SA_DQ<29>")
	)
	(segment
		(start 56.668416 -233.69651)
		(end 56.82996 -233.858054)
		(width 0.14478)
		(layer "In4.Cu")
		(net "M_D_CPU1_SA_DQ<29>")
	)
	(segment
		(start 54.271926 -233.297222)
		(end 54.271926 -233.237532)
		(width 0.14478)
		(layer "In4.Cu")
		(net "M_D_CPU1_SA_DQ<29>")
	)
	(segment
		(start 37.583364 -233.46029)
		(end 37.746432 -233.623358)
		(width 0.14478)
		(layer "In4.Cu")
		(net "M_D_CPU1_SA_DQ<29>")
	)
	(segment
		(start 75.94219 -243.050568)
		(end 76.186792 -243.050568)
		(width 0.0889)
		(layer "In4.Cu")
		(net "M_D_CPU1_SA_DQ<29>")
	)
	(segment
		(start 54.271926 -233.237532)
		(end 54.434994 -233.074464)
		(width 0.14478)
		(layer "In4.Cu")
		(net "M_D_CPU1_SA_DQ<29>")
	)
	(segment
		(start 41.88333 -233.46029)
		(end 42.733214 -232.610406)
		(width 0.14478)
		(layer "In4.Cu")
		(net "M_D_CPU1_SA_DQ<29>")
	)
	(segment
		(start 80.093566 -243.990876)
		(end 80.10398 -243.996972)
		(width 0.0889)
		(layer "In4.Cu")
		(net "M_D_CPU1_SA_DQ<29>")
	)
	(segment
		(start 39.579042 -233.46029)
		(end 41.88333 -233.46029)
		(width 0.14478)
		(layer "In4.Cu")
		(net "M_D_CPU1_SA_DQ<29>")
	)
	(segment
		(start 76.186792 -243.050568)
		(end 76.65593 -243.519706)
		(width 0.0889)
		(layer "In4.Cu")
		(net "M_D_CPU1_SA_DQ<29>")
	)
	(segment
		(start 57.21985 -233.22407)
		(end 57.381394 -233.062526)
		(width 0.14478)
		(layer "In4.Cu")
		(net "M_D_CPU1_SA_DQ<29>")
	)
	(segment
		(start 89.504012 -243.996972)
		(end 89.512394 -244.001798)
		(width 0.0889)
		(layer "In4.Cu")
		(net "M_D_CPU1_SA_DQ<29>")
	)
	(segment
		(start 39.415974 -233.675936)
		(end 39.415974 -233.623358)
		(width 0.14478)
		(layer "In4.Cu")
		(net "M_D_CPU1_SA_DQ<29>")
	)
	(segment
		(start 38.302946 -233.675936)
		(end 38.302946 -233.244644)
		(width 0.14478)
		(layer "In4.Cu")
		(net "M_D_CPU1_SA_DQ<29>")
	)
	(segment
		(start 37.746432 -233.675936)
		(end 37.9095 -233.839004)
		(width 0.14478)
		(layer "In4.Cu")
		(net "M_D_CPU1_SA_DQ<29>")
	)
	(segment
		(start 78.579472 -244.007132)
		(end 78.59776 -243.996718)
		(width 0.0889)
		(layer "In4.Cu")
		(net "M_D_CPU1_SA_DQ<29>")
	)
	(segment
		(start 42.733214 -232.610406)
		(end 45.55871 -232.610406)
		(width 0.14478)
		(layer "In4.Cu")
		(net "M_D_CPU1_SA_DQ<29>")
	)
	(segment
		(start 77.68209 -243.920772)
		(end 77.940408 -243.920772)
		(width 0.0889)
		(layer "In4.Cu")
		(net "M_D_CPU1_SA_DQ<29>")
	)
	(segment
		(start 84.229702 -244.001798)
		(end 84.238084 -243.996972)
		(width 0.0889)
		(layer "In4.Cu")
		(net "M_D_CPU1_SA_DQ<29>")
	)
	(segment
		(start 57.771284 -233.69651)
		(end 57.932828 -233.858054)
		(width 0.14478)
		(layer "In4.Cu")
		(net "M_D_CPU1_SA_DQ<29>")
	)
	(segment
		(start 58.874152 -233.298746)
		(end 59.035696 -233.46029)
		(width 0.14478)
		(layer "In4.Cu")
		(net "M_D_CPU1_SA_DQ<29>")
	)
	(segment
		(start 58.712608 -233.062526)
		(end 58.874152 -233.22407)
		(width 0.14478)
		(layer "In4.Cu")
		(net "M_D_CPU1_SA_DQ<29>")
	)
	(segment
		(start 38.302946 -233.244644)
		(end 38.466014 -233.081576)
		(width 0.14478)
		(layer "In4.Cu")
		(net "M_D_CPU1_SA_DQ<29>")
	)
	(segment
		(start 81.044034 -243.996972)
		(end 81.052416 -244.001798)
		(width 0.0889)
		(layer "In4.Cu")
		(net "M_D_CPU1_SA_DQ<29>")
	)
	(segment
		(start 57.60974 -233.062526)
		(end 57.771284 -233.22407)
		(width 0.14478)
		(layer "In4.Cu")
		(net "M_D_CPU1_SA_DQ<29>")
	)
	(segment
		(start 84.803996 -243.996972)
		(end 84.812378 -244.001798)
		(width 0.0889)
		(layer "In4.Cu")
		(net "M_D_CPU1_SA_DQ<29>")
	)
	(segment
		(start 57.21985 -233.69651)
		(end 57.21985 -233.22407)
		(width 0.14478)
		(layer "In4.Cu")
		(net "M_D_CPU1_SA_DQ<29>")
	)
	(segment
		(start 56.668416 -233.22407)
		(end 56.668416 -233.69651)
		(width 0.14478)
		(layer "In4.Cu")
		(net "M_D_CPU1_SA_DQ<29>")
	)
	(segment
		(start 76.65593 -243.519706)
		(end 77.281024 -243.519706)
		(width 0.0889)
		(layer "In4.Cu")
		(net "M_D_CPU1_SA_DQ<29>")
	)
	(segment
		(start 54.991508 -233.849926)
		(end 55.955438 -233.849926)
		(width 0.14478)
		(layer "In4.Cu")
		(net "M_D_CPU1_SA_DQ<29>")
	)
	(segment
		(start 38.85946 -233.675936)
		(end 39.022528 -233.839004)
		(width 0.14478)
		(layer "In4.Cu")
		(net "M_D_CPU1_SA_DQ<29>")
	)
	(segment
		(start 56.278526 -233.062526)
		(end 56.506872 -233.062526)
		(width 0.14478)
		(layer "In4.Cu")
		(net "M_D_CPU1_SA_DQ<29>")
	)
	(segment
		(start 59.035696 -233.46029)
		(end 59.60364 -233.46029)
		(width 0.14478)
		(layer "In4.Cu")
		(net "M_D_CPU1_SA_DQ<29>")
	)
	(segment
		(start 58.322718 -233.69651)
		(end 58.322718 -233.22407)
		(width 0.14478)
		(layer "In4.Cu")
		(net "M_D_CPU1_SA_DQ<29>")
	)
	(segment
		(start 59.60364 -233.46029)
		(end 69.193918 -243.050568)
		(width 0.14478)
		(layer "In4.Cu")
		(net "M_D_CPU1_SA_DQ<29>")
	)
	(segment
		(start 58.161174 -233.858054)
		(end 58.322718 -233.69651)
		(width 0.14478)
		(layer "In4.Cu")
		(net "M_D_CPU1_SA_DQ<29>")
	)
	(segment
		(start 36.795964 -233.035348)
		(end 37.220906 -233.46029)
		(width 0.14478)
		(layer "In4.Cu")
		(net "M_D_CPU1_SA_DQ<29>")
	)
	(segment
		(start 50.256694 -232.610406)
		(end 52.997862 -232.610406)
		(width 0.14478)
		(layer "In4.Cu")
		(net "M_D_CPU1_SA_DQ<29>")
	)
	(segment
		(start 49.40681 -233.46029)
		(end 50.256694 -232.610406)
		(width 0.14478)
		(layer "In4.Cu")
		(net "M_D_CPU1_SA_DQ<29>")
	)
	(segment
		(start 80.46974 -244.001798)
		(end 80.478122 -243.996972)
		(width 0.0889)
		(layer "In4.Cu")
		(net "M_D_CPU1_SA_DQ<29>")
	)
	(segment
		(start 54.82844 -233.686858)
		(end 54.991508 -233.849926)
		(width 0.14478)
		(layer "In4.Cu")
		(net "M_D_CPU1_SA_DQ<29>")
	)
	(segment
		(start 57.932828 -233.858054)
		(end 58.161174 -233.858054)
		(width 0.14478)
		(layer "In4.Cu")
		(net "M_D_CPU1_SA_DQ<29>")
	)
	(segment
		(start 46.408594 -233.46029)
		(end 49.40681 -233.46029)
		(width 0.14478)
		(layer "In4.Cu")
		(net "M_D_CPU1_SA_DQ<29>")
	)
	(segment
		(start 77.281024 -243.519706)
		(end 77.68209 -243.920772)
		(width 0.0889)
		(layer "In4.Cu")
		(net "M_D_CPU1_SA_DQ<29>")
	)
	(segment
		(start 54.665372 -233.074464)
		(end 54.82844 -233.237532)
		(width 0.14478)
		(layer "In4.Cu")
		(net "M_D_CPU1_SA_DQ<29>")
	)
	(segment
		(start 52.997862 -232.610406)
		(end 53.847746 -233.46029)
		(width 0.14478)
		(layer "In4.Cu")
		(net "M_D_CPU1_SA_DQ<29>")
	)
	(segment
		(start 56.82996 -233.858054)
		(end 57.058306 -233.858054)
		(width 0.14478)
		(layer "In4.Cu")
		(net "M_D_CPU1_SA_DQ<29>")
	)
	(segment
		(start 38.466014 -233.081576)
		(end 38.696392 -233.081576)
		(width 0.14478)
		(layer "In4.Cu")
		(net "M_D_CPU1_SA_DQ<29>")
	)
	(segment
		(start 88.929718 -244.001798)
		(end 88.9381 -243.996972)
		(width 0.0889)
		(layer "In4.Cu")
		(net "M_D_CPU1_SA_DQ<29>")
	)
	(segment
		(start 54.82844 -233.237532)
		(end 54.82844 -233.686858)
		(width 0.14478)
		(layer "In4.Cu")
		(net "M_D_CPU1_SA_DQ<29>")
	)
	(segment
		(start 39.252906 -233.839004)
		(end 39.415974 -233.675936)
		(width 0.14478)
		(layer "In4.Cu")
		(net "M_D_CPU1_SA_DQ<29>")
	)
	(segment
		(start 55.955438 -233.849926)
		(end 56.116982 -233.688382)
		(width 0.14478)
		(layer "In4.Cu")
		(net "M_D_CPU1_SA_DQ<29>")
	)
	(segment
		(start 38.139878 -233.839004)
		(end 38.302946 -233.675936)
		(width 0.14478)
		(layer "In4.Cu")
		(net "M_D_CPU1_SA_DQ<29>")
	)
	(segment
		(start 58.874152 -233.22407)
		(end 58.874152 -233.298746)
		(width 0.14478)
		(layer "In4.Cu")
		(net "M_D_CPU1_SA_DQ<29>")
	)
	(segment
		(start 69.193918 -243.050568)
		(end 75.94219 -243.050568)
		(width 0.14478)
		(layer "In4.Cu")
		(net "M_D_CPU1_SA_DQ<29>")
	)
	(segment
		(start 54.108858 -233.46029)
		(end 54.271926 -233.297222)
		(width 0.14478)
		(layer "In4.Cu")
		(net "M_D_CPU1_SA_DQ<29>")
	)
	(segment
		(start 58.484262 -233.062526)
		(end 58.712608 -233.062526)
		(width 0.14478)
		(layer "In4.Cu")
		(net "M_D_CPU1_SA_DQ<29>")
	)
	(segment
		(start 37.9095 -233.839004)
		(end 38.139878 -233.839004)
		(width 0.14478)
		(layer "In4.Cu")
		(net "M_D_CPU1_SA_DQ<29>")
	)
	(segment
		(start 58.322718 -233.22407)
		(end 58.484262 -233.062526)
		(width 0.14478)
		(layer "In4.Cu")
		(net "M_D_CPU1_SA_DQ<29>")
	)
	(segment
		(start 92.35694 -243.939822)
		(end 92.511118 -243.674392)
		(width 0.0889)
		(layer "In4.Cu")
		(net "M_D_CPU1_SA_DQ<29>")
	)
	(segment
		(start 37.220906 -233.46029)
		(end 37.583364 -233.46029)
		(width 0.14478)
		(layer "In4.Cu")
		(net "M_D_CPU1_SA_DQ<29>")
	)
	(segment
		(start 38.696392 -233.081576)
		(end 38.85946 -233.244644)
		(width 0.14478)
		(layer "In4.Cu")
		(net "M_D_CPU1_SA_DQ<29>")
	)
	(segment
		(start 79.163164 -243.996972)
		(end 79.171546 -244.001798)
		(width 0.0889)
		(layer "In4.Cu")
		(net "M_D_CPU1_SA_DQ<29>")
	)
	(segment
		(start 53.847746 -233.46029)
		(end 54.108858 -233.46029)
		(width 0.14478)
		(layer "In4.Cu")
		(net "M_D_CPU1_SA_DQ<29>")
	)
	(arc
		(start 84.238084 -243.996972)
		(mid 84.52104 -243.920795)
		(end 84.803996 -243.996972)
		(width 0.0889)
		(layer "In4.Cu")
		(net "M_D_CPU1_SA_DQ<29>")
	)
	(arc
		(start 86.684104 -243.996972)
		(mid 86.871048 -244.047227)
		(end 87.057992 -243.996972)
		(width 0.0889)
		(layer "In4.Cu")
		(net "M_D_CPU1_SA_DQ<29>")
	)
	(arc
		(start 85.752432 -244.001798)
		(mid 85.93594 -244.047292)
		(end 86.118192 -243.996972)
		(width 0.0889)
		(layer "In4.Cu")
		(net "M_D_CPU1_SA_DQ<29>")
	)
	(arc
		(start 83.863942 -243.996972)
		(mid 84.046193 -244.047322)
		(end 84.229702 -244.001798)
		(width 0.0889)
		(layer "In4.Cu")
		(net "M_D_CPU1_SA_DQ<29>")
	)
	(arc
		(start 82.357976 -243.996972)
		(mid 82.640932 -243.920795)
		(end 82.923888 -243.996972)
		(width 0.0889)
		(layer "In4.Cu")
		(net "M_D_CPU1_SA_DQ<29>")
	)
	(arc
		(start 90.444066 -243.996972)
		(mid 90.63101 -244.047227)
		(end 90.817954 -243.996972)
		(width 0.0889)
		(layer "In4.Cu")
		(net "M_D_CPU1_SA_DQ<29>")
	)
	(arc
		(start 80.10398 -243.996972)
		(mid 80.286231 -244.047322)
		(end 80.46974 -244.001798)
		(width 0.0889)
		(layer "In4.Cu")
		(net "M_D_CPU1_SA_DQ<29>")
	)
	(arc
		(start 83.29803 -243.996972)
		(mid 83.580986 -243.920795)
		(end 83.863942 -243.996972)
		(width 0.0889)
		(layer "In4.Cu")
		(net "M_D_CPU1_SA_DQ<29>")
	)
	(arc
		(start 89.512394 -244.001798)
		(mid 89.695902 -244.047292)
		(end 89.878154 -243.996972)
		(width 0.0889)
		(layer "In4.Cu")
		(net "M_D_CPU1_SA_DQ<29>")
	)
	(arc
		(start 79.171546 -244.001798)
		(mid 79.355308 -244.047414)
		(end 79.537814 -243.996972)
		(width 0.0889)
		(layer "In4.Cu")
		(net "M_D_CPU1_SA_DQ<29>")
	)
	(arc
		(start 81.984088 -243.996972)
		(mid 82.171032 -244.047227)
		(end 82.357976 -243.996972)
		(width 0.0889)
		(layer "In4.Cu")
		(net "M_D_CPU1_SA_DQ<29>")
	)
	(arc
		(start 88.9381 -243.996972)
		(mid 89.221056 -243.920795)
		(end 89.504012 -243.996972)
		(width 0.0889)
		(layer "In4.Cu")
		(net "M_D_CPU1_SA_DQ<29>")
	)
	(arc
		(start 91.758008 -243.996972)
		(mid 92.005604 -243.921794)
		(end 92.260674 -243.965222)
		(width 0.0889)
		(layer "In4.Cu")
		(net "M_D_CPU1_SA_DQ<29>")
	)
	(arc
		(start 78.223618 -243.996972)
		(mid 78.400246 -244.047205)
		(end 78.579472 -244.007132)
		(width 0.0889)
		(layer "In4.Cu")
		(net "M_D_CPU1_SA_DQ<29>")
	)
	(arc
		(start 80.478122 -243.996972)
		(mid 80.761078 -243.920795)
		(end 81.044034 -243.996972)
		(width 0.0889)
		(layer "In4.Cu")
		(net "M_D_CPU1_SA_DQ<29>")
	)
	(arc
		(start 78.603348 -243.993416)
		(mid 78.883737 -243.920747)
		(end 79.163164 -243.996972)
		(width 0.0889)
		(layer "In4.Cu")
		(net "M_D_CPU1_SA_DQ<29>")
	)
	(arc
		(start 81.052416 -244.001798)
		(mid 81.235924 -244.047292)
		(end 81.418176 -243.996972)
		(width 0.0889)
		(layer "In4.Cu")
		(net "M_D_CPU1_SA_DQ<29>")
	)
	(arc
		(start 88.563958 -243.996972)
		(mid 88.746209 -244.047322)
		(end 88.929718 -244.001798)
		(width 0.0889)
		(layer "In4.Cu")
		(net "M_D_CPU1_SA_DQ<29>")
	)
	(arc
		(start 85.178138 -243.996972)
		(mid 85.461094 -243.920795)
		(end 85.74405 -243.996972)
		(width 0.0889)
		(layer "In4.Cu")
		(net "M_D_CPU1_SA_DQ<29>")
	)
	(arc
		(start 91.383866 -243.996972)
		(mid 91.566117 -244.047322)
		(end 91.749626 -244.001798)
		(width 0.0889)
		(layer "In4.Cu")
		(net "M_D_CPU1_SA_DQ<29>")
	)
	(arc
		(start 89.878154 -243.996972)
		(mid 90.16111 -243.920795)
		(end 90.444066 -243.996972)
		(width 0.0889)
		(layer "In4.Cu")
		(net "M_D_CPU1_SA_DQ<29>")
	)
	(arc
		(start 87.623904 -243.996972)
		(mid 87.806155 -244.047322)
		(end 87.989664 -244.001798)
		(width 0.0889)
		(layer "In4.Cu")
		(net "M_D_CPU1_SA_DQ<29>")
	)
	(arc
		(start 87.998046 -243.996972)
		(mid 88.281002 -243.920795)
		(end 88.563958 -243.996972)
		(width 0.0889)
		(layer "In4.Cu")
		(net "M_D_CPU1_SA_DQ<29>")
	)
	(arc
		(start 82.923888 -243.996972)
		(mid 83.106139 -244.047322)
		(end 83.289648 -244.001798)
		(width 0.0889)
		(layer "In4.Cu")
		(net "M_D_CPU1_SA_DQ<29>")
	)
	(arc
		(start 84.812378 -244.001798)
		(mid 84.995886 -244.047292)
		(end 85.178138 -243.996972)
		(width 0.0889)
		(layer "In4.Cu")
		(net "M_D_CPU1_SA_DQ<29>")
	)
	(arc
		(start 86.118192 -243.996972)
		(mid 86.401148 -243.920795)
		(end 86.684104 -243.996972)
		(width 0.0889)
		(layer "In4.Cu")
		(net "M_D_CPU1_SA_DQ<29>")
	)
	(arc
		(start 87.057992 -243.996972)
		(mid 87.340948 -243.920795)
		(end 87.623904 -243.996972)
		(width 0.0889)
		(layer "In4.Cu")
		(net "M_D_CPU1_SA_DQ<29>")
	)
	(arc
		(start 77.940408 -243.920772)
		(mid 78.087065 -243.940109)
		(end 78.223618 -243.996972)
		(width 0.0889)
		(layer "In4.Cu")
		(net "M_D_CPU1_SA_DQ<29>")
	)
	(arc
		(start 81.418176 -243.996972)
		(mid 81.701132 -243.920795)
		(end 81.984088 -243.996972)
		(width 0.0889)
		(layer "In4.Cu")
		(net "M_D_CPU1_SA_DQ<29>")
	)
	(arc
		(start 90.817954 -243.996972)
		(mid 91.10091 -243.920795)
		(end 91.383866 -243.996972)
		(width 0.0889)
		(layer "In4.Cu")
		(net "M_D_CPU1_SA_DQ<29>")
	)
	(arc
		(start 79.537814 -243.996972)
		(mid 79.814881 -243.920701)
		(end 80.093566 -243.990876)
		(width 0.0889)
		(layer "In4.Cu")
		(net "M_D_CPU1_SA_DQ<29>")
	)
	(segment
		(start 91.568016 -243.130324)
		(end 91.10091 -242.864386)
		(width 0.10668)
		(layer "F.Cu")
		(net "M_D_CPU1_SA_DQ<28>")
	)
	(segment
		(start 58.490866 -232.158286)
		(end 58.719212 -232.158286)
		(width 0.14478)
		(layer "In4.Cu")
		(net "M_D_CPU1_SA_DQ<28>")
	)
	(segment
		(start 65.824354 -238.03991)
		(end 65.894966 -238.039656)
		(width 0.14478)
		(layer "In4.Cu")
		(net "M_D_CPU1_SA_DQ<28>")
	)
	(segment
		(start 66.675254 -238.819944)
		(end 66.916046 -239.060736)
		(width 0.14478)
		(layer "In4.Cu")
		(net "M_D_CPU1_SA_DQ<28>")
	)
	(segment
		(start 65.35547 -237.799118)
		(end 65.596262 -238.03991)
		(width 0.14478)
		(layer "In4.Cu")
		(net "M_D_CPU1_SA_DQ<28>")
	)
	(segment
		(start 63.794894 -235.939584)
		(end 63.794894 -236.238542)
		(width 0.14478)
		(layer "In4.Cu")
		(net "M_D_CPU1_SA_DQ<28>")
	)
	(segment
		(start 49.397158 -231.76992)
		(end 50.247042 -230.920036)
		(width 0.14478)
		(layer "In4.Cu")
		(net "M_D_CPU1_SA_DQ<28>")
	)
	(segment
		(start 54.619398 -231.923336)
		(end 54.619398 -231.991916)
		(width 0.14478)
		(layer "In4.Cu")
		(net "M_D_CPU1_SA_DQ<28>")
	)
	(segment
		(start 37.569394 -231.121712)
		(end 37.732462 -230.958644)
		(width 0.14478)
		(layer "In4.Cu")
		(net "M_D_CPU1_SA_DQ<28>")
	)
	(segment
		(start 57.939432 -231.76992)
		(end 58.167778 -231.76992)
		(width 0.14478)
		(layer "In4.Cu")
		(net "M_D_CPU1_SA_DQ<28>")
	)
	(segment
		(start 61.694822 -234.13847)
		(end 61.922914 -234.13847)
		(width 0.14478)
		(layer "In4.Cu")
		(net "M_D_CPU1_SA_DQ<28>")
	)
	(segment
		(start 61.142626 -233.358182)
		(end 61.213238 -233.357928)
		(width 0.14478)
		(layer "In4.Cu")
		(net "M_D_CPU1_SA_DQ<28>")
	)
	(segment
		(start 51.267106 -231.133396)
		(end 51.267106 -231.073452)
		(width 0.14478)
		(layer "In4.Cu")
		(net "M_D_CPU1_SA_DQ<28>")
	)
	(segment
		(start 55.895494 -232.154984)
		(end 56.125872 -232.154984)
		(width 0.14478)
		(layer "In4.Cu")
		(net "M_D_CPU1_SA_DQ<28>")
	)
	(segment
		(start 60.673742 -233.11739)
		(end 60.914534 -233.358182)
		(width 0.14478)
		(layer "In4.Cu")
		(net "M_D_CPU1_SA_DQ<28>")
	)
	(segment
		(start 40.735504 -231.76992)
		(end 40.88892 -231.923336)
		(width 0.14478)
		(layer "In4.Cu")
		(net "M_D_CPU1_SA_DQ<28>")
	)
	(segment
		(start 64.33439 -236.47908)
		(end 64.575182 -236.719872)
		(width 0.14478)
		(layer "In4.Cu")
		(net "M_D_CPU1_SA_DQ<28>")
	)
	(segment
		(start 50.247042 -230.920036)
		(end 50.557176 -230.920036)
		(width 0.14478)
		(layer "In4.Cu")
		(net "M_D_CPU1_SA_DQ<28>")
	)
	(segment
		(start 55.175912 -231.991916)
		(end 55.175912 -231.923336)
		(width 0.14478)
		(layer "In4.Cu")
		(net "M_D_CPU1_SA_DQ<28>")
	)
	(segment
		(start 66.916046 -239.359694)
		(end 67.156838 -239.600486)
		(width 0.14478)
		(layer "In4.Cu")
		(net "M_D_CPU1_SA_DQ<28>")
	)
	(segment
		(start 54.782466 -232.154984)
		(end 55.012844 -232.154984)
		(width 0.14478)
		(layer "In4.Cu")
		(net "M_D_CPU1_SA_DQ<28>")
	)
	(segment
		(start 69.016118 -241.160808)
		(end 69.25691 -241.4016)
		(width 0.14478)
		(layer "In4.Cu")
		(net "M_D_CPU1_SA_DQ<28>")
	)
	(segment
		(start 61.45403 -233.897678)
		(end 61.694822 -234.13847)
		(width 0.14478)
		(layer "In4.Cu")
		(net "M_D_CPU1_SA_DQ<28>")
	)
	(segment
		(start 79.634842 -243.186712)
		(end 79.654908 -243.198142)
		(width 0.0889)
		(layer "In4.Cu")
		(net "M_D_CPU1_SA_DQ<28>")
	)
	(segment
		(start 64.815974 -237.259622)
		(end 65.044066 -237.259622)
		(width 0.14478)
		(layer "In4.Cu")
		(net "M_D_CPU1_SA_DQ<28>")
	)
	(segment
		(start 37.569394 -231.5972)
		(end 37.569394 -231.121712)
		(width 0.14478)
		(layer "In4.Cu")
		(net "M_D_CPU1_SA_DQ<28>")
	)
	(segment
		(start 50.557176 -230.920036)
		(end 50.710592 -231.073452)
		(width 0.14478)
		(layer "In4.Cu")
		(net "M_D_CPU1_SA_DQ<28>")
	)
	(segment
		(start 61.922914 -234.13847)
		(end 61.993526 -234.138216)
		(width 0.14478)
		(layer "In4.Cu")
		(net "M_D_CPU1_SA_DQ<28>")
	)
	(segment
		(start 58.880756 -231.931464)
		(end 59.0423 -231.76992)
		(width 0.14478)
		(layer "In4.Cu")
		(net "M_D_CPU1_SA_DQ<28>")
	)
	(segment
		(start 57.777888 -231.931464)
		(end 57.939432 -231.76992)
		(width 0.14478)
		(layer "In4.Cu")
		(net "M_D_CPU1_SA_DQ<28>")
	)
	(segment
		(start 62.234318 -234.677966)
		(end 62.47511 -234.918758)
		(width 0.14478)
		(layer "In4.Cu")
		(net "M_D_CPU1_SA_DQ<28>")
	)
	(segment
		(start 38.82771 -231.923336)
		(end 38.82771 -231.979216)
		(width 0.14478)
		(layer "In4.Cu")
		(net "M_D_CPU1_SA_DQ<28>")
	)
	(segment
		(start 63.255398 -235.699046)
		(end 63.48349 -235.699046)
		(width 0.14478)
		(layer "In4.Cu")
		(net "M_D_CPU1_SA_DQ<28>")
	)
	(segment
		(start 69.25691 -241.700558)
		(end 69.497702 -241.94135)
		(width 0.14478)
		(layer "In4.Cu")
		(net "M_D_CPU1_SA_DQ<28>")
	)
	(segment
		(start 62.703202 -234.918758)
		(end 62.773814 -234.918504)
		(width 0.14478)
		(layer "In4.Cu")
		(net "M_D_CPU1_SA_DQ<28>")
	)
	(segment
		(start 40.88892 -231.979216)
		(end 41.051988 -232.142284)
		(width 0.14478)
		(layer "In4.Cu")
		(net "M_D_CPU1_SA_DQ<28>")
	)
	(segment
		(start 37.220906 -231.760268)
		(end 37.406326 -231.760268)
		(width 0.14478)
		(layer "In4.Cu")
		(net "M_D_CPU1_SA_DQ<28>")
	)
	(segment
		(start 56.442356 -231.76992)
		(end 57.06491 -231.76992)
		(width 0.14478)
		(layer "In4.Cu")
		(net "M_D_CPU1_SA_DQ<28>")
	)
	(segment
		(start 67.156838 -239.600486)
		(end 67.38493 -239.600486)
		(width 0.14478)
		(layer "In4.Cu")
		(net "M_D_CPU1_SA_DQ<28>")
	)
	(segment
		(start 41.282366 -232.142284)
		(end 41.445434 -231.979216)
		(width 0.14478)
		(layer "In4.Cu")
		(net "M_D_CPU1_SA_DQ<28>")
	)
	(segment
		(start 54.45633 -231.760268)
		(end 54.619398 -231.923336)
		(width 0.14478)
		(layer "In4.Cu")
		(net "M_D_CPU1_SA_DQ<28>")
	)
	(segment
		(start 58.329322 -231.996742)
		(end 58.490866 -232.158286)
		(width 0.14478)
		(layer "In4.Cu")
		(net "M_D_CPU1_SA_DQ<28>")
	)
	(segment
		(start 88.094058 -243.186966)
		(end 88.10244 -243.191792)
		(width 0.0889)
		(layer "In4.Cu")
		(net "M_D_CPU1_SA_DQ<28>")
	)
	(segment
		(start 36.795964 -231.335326)
		(end 37.220906 -231.760268)
		(width 0.14478)
		(layer "In4.Cu")
		(net "M_D_CPU1_SA_DQ<28>")
	)
	(segment
		(start 66.604642 -238.820198)
		(end 66.675254 -238.819944)
		(width 0.14478)
		(layer "In4.Cu")
		(net "M_D_CPU1_SA_DQ<28>")
	)
	(segment
		(start 68.717414 -241.161062)
		(end 68.945506 -241.161062)
		(width 0.14478)
		(layer "In4.Cu")
		(net "M_D_CPU1_SA_DQ<28>")
	)
	(segment
		(start 63.554102 -235.698792)
		(end 63.794894 -235.939584)
		(width 0.14478)
		(layer "In4.Cu")
		(net "M_D_CPU1_SA_DQ<28>")
	)
	(segment
		(start 41.608502 -231.760268)
		(end 41.88333 -231.760268)
		(width 0.14478)
		(layer "In4.Cu")
		(net "M_D_CPU1_SA_DQ<28>")
	)
	(segment
		(start 63.48349 -235.699046)
		(end 63.554102 -235.698792)
		(width 0.14478)
		(layer "In4.Cu")
		(net "M_D_CPU1_SA_DQ<28>")
	)
	(segment
		(start 81.879694 -243.191792)
		(end 81.888076 -243.186966)
		(width 0.0889)
		(layer "In4.Cu")
		(net "M_D_CPU1_SA_DQ<28>")
	)
	(segment
		(start 43.591734 -231.301544)
		(end 43.754802 -231.138476)
		(width 0.14478)
		(layer "In4.Cu")
		(net "M_D_CPU1_SA_DQ<28>")
	)
	(segment
		(start 59.0423 -231.76992)
		(end 59.62523 -231.76992)
		(width 0.14478)
		(layer "In4.Cu")
		(net "M_D_CPU1_SA_DQ<28>")
	)
	(segment
		(start 57.06491 -231.76992)
		(end 57.226454 -231.931464)
		(width 0.14478)
		(layer "In4.Cu")
		(net "M_D_CPU1_SA_DQ<28>")
	)
	(segment
		(start 50.710592 -231.133396)
		(end 50.87366 -231.296464)
		(width 0.14478)
		(layer "In4.Cu")
		(net "M_D_CPU1_SA_DQ<28>")
	)
	(segment
		(start 66.37655 -238.820198)
		(end 66.604642 -238.820198)
		(width 0.14478)
		(layer "In4.Cu")
		(net "M_D_CPU1_SA_DQ<28>")
	)
	(segment
		(start 69.25691 -241.4016)
		(end 69.25691 -241.700558)
		(width 0.14478)
		(layer "In4.Cu")
		(net "M_D_CPU1_SA_DQ<28>")
	)
	(segment
		(start 50.710592 -231.073452)
		(end 50.710592 -231.133396)
		(width 0.14478)
		(layer "In4.Cu")
		(net "M_D_CPU1_SA_DQ<28>")
	)
	(segment
		(start 51.267106 -231.073452)
		(end 51.420522 -230.920036)
		(width 0.14478)
		(layer "In4.Cu")
		(net "M_D_CPU1_SA_DQ<28>")
	)
	(segment
		(start 38.82771 -231.979216)
		(end 38.990778 -232.142284)
		(width 0.14478)
		(layer "In4.Cu")
		(net "M_D_CPU1_SA_DQ<28>")
	)
	(segment
		(start 79.051658 -243.197888)
		(end 79.070454 -243.186966)
		(width 0.0889)
		(layer "In4.Cu")
		(net "M_D_CPU1_SA_DQ<28>")
	)
	(segment
		(start 90.850974 -243.155216)
		(end 90.946986 -243.129816)
		(width 0.0889)
		(layer "In4.Cu")
		(net "M_D_CPU1_SA_DQ<28>")
	)
	(segment
		(start 55.569358 -231.760268)
		(end 55.732426 -231.923336)
		(width 0.14478)
		(layer "In4.Cu")
		(net "M_D_CPU1_SA_DQ<28>")
	)
	(segment
		(start 76.61275 -242.480846)
		(end 77.267816 -242.480846)
		(width 0.0889)
		(layer "In4.Cu")
		(net "M_D_CPU1_SA_DQ<28>")
	)
	(segment
		(start 41.88333 -231.760268)
		(end 42.723562 -230.920036)
		(width 0.14478)
		(layer "In4.Cu")
		(net "M_D_CPU1_SA_DQ<28>")
	)
	(segment
		(start 63.014606 -235.458254)
		(end 63.255398 -235.699046)
		(width 0.14478)
		(layer "In4.Cu")
		(net "M_D_CPU1_SA_DQ<28>")
	)
	(segment
		(start 40.88892 -231.923336)
		(end 40.88892 -231.979216)
		(width 0.14478)
		(layer "In4.Cu")
		(net "M_D_CPU1_SA_DQ<28>")
	)
	(segment
		(start 57.226454 -231.931464)
		(end 57.226454 -231.996742)
		(width 0.14478)
		(layer "In4.Cu")
		(net "M_D_CPU1_SA_DQ<28>")
	)
	(segment
		(start 64.575182 -237.01883)
		(end 64.815974 -237.259622)
		(width 0.14478)
		(layer "In4.Cu")
		(net "M_D_CPU1_SA_DQ<28>")
	)
	(segment
		(start 60.673742 -232.818432)
		(end 60.673742 -233.11739)
		(width 0.14478)
		(layer "In4.Cu")
		(net "M_D_CPU1_SA_DQ<28>")
	)
	(segment
		(start 68.165218 -240.380774)
		(end 68.23583 -240.38052)
		(width 0.14478)
		(layer "In4.Cu")
		(net "M_D_CPU1_SA_DQ<28>")
	)
	(segment
		(start 83.394042 -243.186966)
		(end 83.402424 -243.191792)
		(width 0.0889)
		(layer "In4.Cu")
		(net "M_D_CPU1_SA_DQ<28>")
	)
	(segment
		(start 50.87366 -231.296464)
		(end 51.104038 -231.296464)
		(width 0.14478)
		(layer "In4.Cu")
		(net "M_D_CPU1_SA_DQ<28>")
	)
	(segment
		(start 76.273152 -242.141248)
		(end 76.61275 -242.480846)
		(width 0.0889)
		(layer "In4.Cu")
		(net "M_D_CPU1_SA_DQ<28>")
	)
	(segment
		(start 60.914534 -233.358182)
		(end 61.142626 -233.358182)
		(width 0.14478)
		(layer "In4.Cu")
		(net "M_D_CPU1_SA_DQ<28>")
	)
	(segment
		(start 68.476622 -240.621312)
		(end 68.476622 -240.92027)
		(width 0.14478)
		(layer "In4.Cu")
		(net "M_D_CPU1_SA_DQ<28>")
	)
	(segment
		(start 38.125908 -231.121712)
		(end 38.125908 -231.5972)
		(width 0.14478)
		(layer "In4.Cu")
		(net "M_D_CPU1_SA_DQ<28>")
	)
	(segment
		(start 58.719212 -232.158286)
		(end 58.880756 -231.996742)
		(width 0.14478)
		(layer "In4.Cu")
		(net "M_D_CPU1_SA_DQ<28>")
	)
	(segment
		(start 67.696334 -239.841024)
		(end 67.696334 -240.139982)
		(width 0.14478)
		(layer "In4.Cu")
		(net "M_D_CPU1_SA_DQ<28>")
	)
	(segment
		(start 69.796406 -241.941096)
		(end 69.996558 -242.141248)
		(width 0.14478)
		(layer "In4.Cu")
		(net "M_D_CPU1_SA_DQ<28>")
	)
	(segment
		(start 39.384224 -231.979216)
		(end 39.384224 -231.923336)
		(width 0.14478)
		(layer "In4.Cu")
		(net "M_D_CPU1_SA_DQ<28>")
	)
	(segment
		(start 66.135758 -238.280448)
		(end 66.135758 -238.579406)
		(width 0.14478)
		(layer "In4.Cu")
		(net "M_D_CPU1_SA_DQ<28>")
	)
	(segment
		(start 66.916046 -239.060736)
		(end 66.916046 -239.359694)
		(width 0.14478)
		(layer "In4.Cu")
		(net "M_D_CPU1_SA_DQ<28>")
	)
	(segment
		(start 69.725794 -241.94135)
		(end 69.796406 -241.941096)
		(width 0.14478)
		(layer "In4.Cu")
		(net "M_D_CPU1_SA_DQ<28>")
	)
	(segment
		(start 77.897228 -243.110258)
		(end 78.41107 -243.110258)
		(width 0.0889)
		(layer "In4.Cu")
		(net "M_D_CPU1_SA_DQ<28>")
	)
	(segment
		(start 56.125872 -232.154984)
		(end 56.28894 -231.991916)
		(width 0.14478)
		(layer "In4.Cu")
		(net "M_D_CPU1_SA_DQ<28>")
	)
	(segment
		(start 57.616344 -232.158286)
		(end 57.777888 -231.996742)
		(width 0.14478)
		(layer "In4.Cu")
		(net "M_D_CPU1_SA_DQ<28>")
	)
	(segment
		(start 43.908218 -230.920036)
		(end 45.568362 -230.920036)
		(width 0.14478)
		(layer "In4.Cu")
		(net "M_D_CPU1_SA_DQ<28>")
	)
	(segment
		(start 69.996558 -242.141248)
		(end 75.92949 -242.141248)
		(width 0.14478)
		(layer "In4.Cu")
		(net "M_D_CPU1_SA_DQ<28>")
	)
	(segment
		(start 86.57971 -243.191792)
		(end 86.588092 -243.186966)
		(width 0.0889)
		(layer "In4.Cu")
		(net "M_D_CPU1_SA_DQ<28>")
	)
	(segment
		(start 64.575182 -236.719872)
		(end 64.575182 -237.01883)
		(width 0.14478)
		(layer "In4.Cu")
		(net "M_D_CPU1_SA_DQ<28>")
	)
	(segment
		(start 65.114678 -237.259368)
		(end 65.35547 -237.50016)
		(width 0.14478)
		(layer "In4.Cu")
		(net "M_D_CPU1_SA_DQ<28>")
	)
	(segment
		(start 37.406326 -231.760268)
		(end 37.569394 -231.5972)
		(width 0.14478)
		(layer "In4.Cu")
		(net "M_D_CPU1_SA_DQ<28>")
	)
	(segment
		(start 67.937126 -240.380774)
		(end 68.165218 -240.380774)
		(width 0.14478)
		(layer "In4.Cu")
		(net "M_D_CPU1_SA_DQ<28>")
	)
	(segment
		(start 63.794894 -236.238542)
		(end 64.035686 -236.479334)
		(width 0.14478)
		(layer "In4.Cu")
		(net "M_D_CPU1_SA_DQ<28>")
	)
	(segment
		(start 57.387998 -232.158286)
		(end 57.616344 -232.158286)
		(width 0.14478)
		(layer "In4.Cu")
		(net "M_D_CPU1_SA_DQ<28>")
	)
	(segment
		(start 90.339672 -243.191792)
		(end 90.348054 -243.186966)
		(width 0.0889)
		(layer "In4.Cu")
		(net "M_D_CPU1_SA_DQ<28>")
	)
	(segment
		(start 57.777888 -231.996742)
		(end 57.777888 -231.931464)
		(width 0.14478)
		(layer "In4.Cu")
		(net "M_D_CPU1_SA_DQ<28>")
	)
	(segment
		(start 43.361356 -231.301544)
		(end 43.591734 -231.301544)
		(width 0.14478)
		(layer "In4.Cu")
		(net "M_D_CPU1_SA_DQ<28>")
	)
	(segment
		(start 43.198288 -231.073452)
		(end 43.198288 -231.138476)
		(width 0.14478)
		(layer "In4.Cu")
		(net "M_D_CPU1_SA_DQ<28>")
	)
	(segment
		(start 63.014606 -235.159296)
		(end 63.014606 -235.458254)
		(width 0.14478)
		(layer "In4.Cu")
		(net "M_D_CPU1_SA_DQ<28>")
	)
	(segment
		(start 54.619398 -231.991916)
		(end 54.782466 -232.154984)
		(width 0.14478)
		(layer "In4.Cu")
		(net "M_D_CPU1_SA_DQ<28>")
	)
	(segment
		(start 68.476622 -240.92027)
		(end 68.717414 -241.161062)
		(width 0.14478)
		(layer "In4.Cu")
		(net "M_D_CPU1_SA_DQ<28>")
	)
	(segment
		(start 51.104038 -231.296464)
		(end 51.267106 -231.133396)
		(width 0.14478)
		(layer "In4.Cu")
		(net "M_D_CPU1_SA_DQ<28>")
	)
	(segment
		(start 62.773814 -234.918504)
		(end 63.014606 -235.159296)
		(width 0.14478)
		(layer "In4.Cu")
		(net "M_D_CPU1_SA_DQ<28>")
	)
	(segment
		(start 82.453988 -243.186966)
		(end 82.46237 -243.191792)
		(width 0.0889)
		(layer "In4.Cu")
		(net "M_D_CPU1_SA_DQ<28>")
	)
	(segment
		(start 61.213238 -233.357928)
		(end 61.45403 -233.59872)
		(width 0.14478)
		(layer "In4.Cu")
		(net "M_D_CPU1_SA_DQ<28>")
	)
	(segment
		(start 53.94833 -231.760268)
		(end 54.45633 -231.760268)
		(width 0.14478)
		(layer "In4.Cu")
		(net "M_D_CPU1_SA_DQ<28>")
	)
	(segment
		(start 61.45403 -233.59872)
		(end 61.45403 -233.897678)
		(width 0.14478)
		(layer "In4.Cu")
		(net "M_D_CPU1_SA_DQ<28>")
	)
	(segment
		(start 55.012844 -232.154984)
		(end 55.175912 -231.991916)
		(width 0.14478)
		(layer "In4.Cu")
		(net "M_D_CPU1_SA_DQ<28>")
	)
	(segment
		(start 41.051988 -232.142284)
		(end 41.282366 -232.142284)
		(width 0.14478)
		(layer "In4.Cu")
		(net "M_D_CPU1_SA_DQ<28>")
	)
	(segment
		(start 43.754802 -231.138476)
		(end 43.754802 -231.073452)
		(width 0.14478)
		(layer "In4.Cu")
		(net "M_D_CPU1_SA_DQ<28>")
	)
	(segment
		(start 43.754802 -231.073452)
		(end 43.908218 -230.920036)
		(width 0.14478)
		(layer "In4.Cu")
		(net "M_D_CPU1_SA_DQ<28>")
	)
	(segment
		(start 45.568362 -230.920036)
		(end 46.418246 -231.76992)
		(width 0.14478)
		(layer "In4.Cu")
		(net "M_D_CPU1_SA_DQ<28>")
	)
	(segment
		(start 75.92949 -242.141248)
		(end 76.273152 -242.141248)
		(width 0.0889)
		(layer "In4.Cu")
		(net "M_D_CPU1_SA_DQ<28>")
	)
	(segment
		(start 69.497702 -241.94135)
		(end 69.725794 -241.94135)
		(width 0.14478)
		(layer "In4.Cu")
		(net "M_D_CPU1_SA_DQ<28>")
	)
	(segment
		(start 39.53764 -231.76992)
		(end 40.735504 -231.76992)
		(width 0.14478)
		(layer "In4.Cu")
		(net "M_D_CPU1_SA_DQ<28>")
	)
	(segment
		(start 39.384224 -231.923336)
		(end 39.53764 -231.76992)
		(width 0.14478)
		(layer "In4.Cu")
		(net "M_D_CPU1_SA_DQ<28>")
	)
	(segment
		(start 55.33898 -231.760268)
		(end 55.569358 -231.760268)
		(width 0.14478)
		(layer "In4.Cu")
		(net "M_D_CPU1_SA_DQ<28>")
	)
	(segment
		(start 67.455542 -239.600232)
		(end 67.696334 -239.841024)
		(width 0.14478)
		(layer "In4.Cu")
		(net "M_D_CPU1_SA_DQ<28>")
	)
	(segment
		(start 79.613252 -243.174266)
		(end 79.634842 -243.186712)
		(width 0.0889)
		(layer "In4.Cu")
		(net "M_D_CPU1_SA_DQ<28>")
	)
	(segment
		(start 43.198288 -231.138476)
		(end 43.361356 -231.301544)
		(width 0.14478)
		(layer "In4.Cu")
		(net "M_D_CPU1_SA_DQ<28>")
	)
	(segment
		(start 37.732462 -230.958644)
		(end 37.96284 -230.958644)
		(width 0.14478)
		(layer "In4.Cu")
		(net "M_D_CPU1_SA_DQ<28>")
	)
	(segment
		(start 56.28894 -231.923336)
		(end 56.442356 -231.76992)
		(width 0.14478)
		(layer "In4.Cu")
		(net "M_D_CPU1_SA_DQ<28>")
	)
	(segment
		(start 42.723562 -230.920036)
		(end 43.044872 -230.920036)
		(width 0.14478)
		(layer "In4.Cu")
		(net "M_D_CPU1_SA_DQ<28>")
	)
	(segment
		(start 55.732426 -231.991916)
		(end 55.895494 -232.154984)
		(width 0.14478)
		(layer "In4.Cu")
		(net "M_D_CPU1_SA_DQ<28>")
	)
	(segment
		(start 56.28894 -231.991916)
		(end 56.28894 -231.923336)
		(width 0.14478)
		(layer "In4.Cu")
		(net "M_D_CPU1_SA_DQ<28>")
	)
	(segment
		(start 90.946986 -243.129816)
		(end 91.10091 -242.864386)
		(width 0.0889)
		(layer "In4.Cu")
		(net "M_D_CPU1_SA_DQ<28>")
	)
	(segment
		(start 38.990778 -232.142284)
		(end 39.221156 -232.142284)
		(width 0.14478)
		(layer "In4.Cu")
		(net "M_D_CPU1_SA_DQ<28>")
	)
	(segment
		(start 65.596262 -238.03991)
		(end 65.824354 -238.03991)
		(width 0.14478)
		(layer "In4.Cu")
		(net "M_D_CPU1_SA_DQ<28>")
	)
	(segment
		(start 68.23583 -240.38052)
		(end 68.476622 -240.621312)
		(width 0.14478)
		(layer "In4.Cu")
		(net "M_D_CPU1_SA_DQ<28>")
	)
	(segment
		(start 55.175912 -231.923336)
		(end 55.33898 -231.760268)
		(width 0.14478)
		(layer "In4.Cu")
		(net "M_D_CPU1_SA_DQ<28>")
	)
	(segment
		(start 77.267816 -242.480846)
		(end 77.897228 -243.110258)
		(width 0.0889)
		(layer "In4.Cu")
		(net "M_D_CPU1_SA_DQ<28>")
	)
	(segment
		(start 41.445434 -231.979216)
		(end 41.445434 -231.923336)
		(width 0.14478)
		(layer "In4.Cu")
		(net "M_D_CPU1_SA_DQ<28>")
	)
	(segment
		(start 37.96284 -230.958644)
		(end 38.125908 -231.121712)
		(width 0.14478)
		(layer "In4.Cu")
		(net "M_D_CPU1_SA_DQ<28>")
	)
	(segment
		(start 53.108098 -230.920036)
		(end 53.94833 -231.760268)
		(width 0.14478)
		(layer "In4.Cu")
		(net "M_D_CPU1_SA_DQ<28>")
	)
	(segment
		(start 67.38493 -239.600486)
		(end 67.455542 -239.600232)
		(width 0.14478)
		(layer "In4.Cu")
		(net "M_D_CPU1_SA_DQ<28>")
	)
	(segment
		(start 62.47511 -234.918758)
		(end 62.703202 -234.918758)
		(width 0.14478)
		(layer "In4.Cu")
		(net "M_D_CPU1_SA_DQ<28>")
	)
	(segment
		(start 55.732426 -231.923336)
		(end 55.732426 -231.991916)
		(width 0.14478)
		(layer "In4.Cu")
		(net "M_D_CPU1_SA_DQ<28>")
	)
	(segment
		(start 61.993526 -234.138216)
		(end 62.234318 -234.379008)
		(width 0.14478)
		(layer "In4.Cu")
		(net "M_D_CPU1_SA_DQ<28>")
	)
	(segment
		(start 51.420522 -230.920036)
		(end 53.108098 -230.920036)
		(width 0.14478)
		(layer "In4.Cu")
		(net "M_D_CPU1_SA_DQ<28>")
	)
	(segment
		(start 46.418246 -231.76992)
		(end 49.397158 -231.76992)
		(width 0.14478)
		(layer "In4.Cu")
		(net "M_D_CPU1_SA_DQ<28>")
	)
	(segment
		(start 58.329322 -231.931464)
		(end 58.329322 -231.996742)
		(width 0.14478)
		(layer "In4.Cu")
		(net "M_D_CPU1_SA_DQ<28>")
	)
	(segment
		(start 59.62523 -231.76992)
		(end 60.673742 -232.818432)
		(width 0.14478)
		(layer "In4.Cu")
		(net "M_D_CPU1_SA_DQ<28>")
	)
	(segment
		(start 64.263778 -236.479334)
		(end 64.33439 -236.47908)
		(width 0.14478)
		(layer "In4.Cu")
		(net "M_D_CPU1_SA_DQ<28>")
	)
	(segment
		(start 68.945506 -241.161062)
		(end 69.016118 -241.160808)
		(width 0.14478)
		(layer "In4.Cu")
		(net "M_D_CPU1_SA_DQ<28>")
	)
	(segment
		(start 38.298628 -231.76992)
		(end 38.674294 -231.76992)
		(width 0.14478)
		(layer "In4.Cu")
		(net "M_D_CPU1_SA_DQ<28>")
	)
	(segment
		(start 65.044066 -237.259622)
		(end 65.114678 -237.259368)
		(width 0.14478)
		(layer "In4.Cu")
		(net "M_D_CPU1_SA_DQ<28>")
	)
	(segment
		(start 65.35547 -237.50016)
		(end 65.35547 -237.799118)
		(width 0.14478)
		(layer "In4.Cu")
		(net "M_D_CPU1_SA_DQ<28>")
	)
	(segment
		(start 43.044872 -230.920036)
		(end 43.198288 -231.073452)
		(width 0.14478)
		(layer "In4.Cu")
		(net "M_D_CPU1_SA_DQ<28>")
	)
	(segment
		(start 39.221156 -232.142284)
		(end 39.384224 -231.979216)
		(width 0.14478)
		(layer "In4.Cu")
		(net "M_D_CPU1_SA_DQ<28>")
	)
	(segment
		(start 85.639656 -243.191792)
		(end 85.648038 -243.186966)
		(width 0.0889)
		(layer "In4.Cu")
		(net "M_D_CPU1_SA_DQ<28>")
	)
	(segment
		(start 38.125908 -231.5972)
		(end 38.298628 -231.76992)
		(width 0.14478)
		(layer "In4.Cu")
		(net "M_D_CPU1_SA_DQ<28>")
	)
	(segment
		(start 62.234318 -234.379008)
		(end 62.234318 -234.677966)
		(width 0.14478)
		(layer "In4.Cu")
		(net "M_D_CPU1_SA_DQ<28>")
	)
	(segment
		(start 87.154004 -243.186966)
		(end 87.162386 -243.191792)
		(width 0.0889)
		(layer "In4.Cu")
		(net "M_D_CPU1_SA_DQ<28>")
	)
	(segment
		(start 64.035686 -236.479334)
		(end 64.263778 -236.479334)
		(width 0.14478)
		(layer "In4.Cu")
		(net "M_D_CPU1_SA_DQ<28>")
	)
	(segment
		(start 67.696334 -240.139982)
		(end 67.937126 -240.380774)
		(width 0.14478)
		(layer "In4.Cu")
		(net "M_D_CPU1_SA_DQ<28>")
	)
	(segment
		(start 58.880756 -231.996742)
		(end 58.880756 -231.931464)
		(width 0.14478)
		(layer "In4.Cu")
		(net "M_D_CPU1_SA_DQ<28>")
	)
	(segment
		(start 66.135758 -238.579406)
		(end 66.37655 -238.820198)
		(width 0.14478)
		(layer "In4.Cu")
		(net "M_D_CPU1_SA_DQ<28>")
	)
	(segment
		(start 65.894966 -238.039656)
		(end 66.135758 -238.280448)
		(width 0.14478)
		(layer "In4.Cu")
		(net "M_D_CPU1_SA_DQ<28>")
	)
	(segment
		(start 57.226454 -231.996742)
		(end 57.387998 -232.158286)
		(width 0.14478)
		(layer "In4.Cu")
		(net "M_D_CPU1_SA_DQ<28>")
	)
	(segment
		(start 38.674294 -231.76992)
		(end 38.82771 -231.923336)
		(width 0.14478)
		(layer "In4.Cu")
		(net "M_D_CPU1_SA_DQ<28>")
	)
	(segment
		(start 58.167778 -231.76992)
		(end 58.329322 -231.931464)
		(width 0.14478)
		(layer "In4.Cu")
		(net "M_D_CPU1_SA_DQ<28>")
	)
	(segment
		(start 41.445434 -231.923336)
		(end 41.608502 -231.760268)
		(width 0.14478)
		(layer "In4.Cu")
		(net "M_D_CPU1_SA_DQ<28>")
	)
	(arc
		(start 89.408 -243.186966)
		(mid 89.690956 -243.110789)
		(end 89.973912 -243.186966)
		(width 0.0889)
		(layer "In4.Cu")
		(net "M_D_CPU1_SA_DQ<28>")
	)
	(arc
		(start 87.162386 -243.191792)
		(mid 87.345894 -243.237286)
		(end 87.528146 -243.186966)
		(width 0.0889)
		(layer "In4.Cu")
		(net "M_D_CPU1_SA_DQ<28>")
	)
	(arc
		(start 82.46237 -243.191792)
		(mid 82.645878 -243.237286)
		(end 82.82813 -243.186966)
		(width 0.0889)
		(layer "In4.Cu")
		(net "M_D_CPU1_SA_DQ<28>")
	)
	(arc
		(start 80.008222 -243.186966)
		(mid 80.291178 -243.110789)
		(end 80.574134 -243.186966)
		(width 0.0889)
		(layer "In4.Cu")
		(net "M_D_CPU1_SA_DQ<28>")
	)
	(arc
		(start 89.973912 -243.186966)
		(mid 90.156163 -243.237316)
		(end 90.339672 -243.191792)
		(width 0.0889)
		(layer "In4.Cu")
		(net "M_D_CPU1_SA_DQ<28>")
	)
	(arc
		(start 84.334096 -243.186966)
		(mid 84.52104 -243.237221)
		(end 84.707984 -243.186966)
		(width 0.0889)
		(layer "In4.Cu")
		(net "M_D_CPU1_SA_DQ<28>")
	)
	(arc
		(start 83.768184 -243.186966)
		(mid 84.05114 -243.110789)
		(end 84.334096 -243.186966)
		(width 0.0889)
		(layer "In4.Cu")
		(net "M_D_CPU1_SA_DQ<28>")
	)
	(arc
		(start 89.034112 -243.186966)
		(mid 89.221056 -243.237221)
		(end 89.408 -243.186966)
		(width 0.0889)
		(layer "In4.Cu")
		(net "M_D_CPU1_SA_DQ<28>")
	)
	(arc
		(start 78.41107 -243.110258)
		(mid 78.558279 -243.129735)
		(end 78.695296 -243.186966)
		(width 0.0889)
		(layer "In4.Cu")
		(net "M_D_CPU1_SA_DQ<28>")
	)
	(arc
		(start 88.4682 -243.186966)
		(mid 88.751156 -243.110789)
		(end 89.034112 -243.186966)
		(width 0.0889)
		(layer "In4.Cu")
		(net "M_D_CPU1_SA_DQ<28>")
	)
	(arc
		(start 85.648038 -243.186966)
		(mid 85.930994 -243.110789)
		(end 86.21395 -243.186966)
		(width 0.0889)
		(layer "In4.Cu")
		(net "M_D_CPU1_SA_DQ<28>")
	)
	(arc
		(start 86.21395 -243.186966)
		(mid 86.396201 -243.237316)
		(end 86.57971 -243.191792)
		(width 0.0889)
		(layer "In4.Cu")
		(net "M_D_CPU1_SA_DQ<28>")
	)
	(arc
		(start 84.707984 -243.186966)
		(mid 84.99094 -243.110789)
		(end 85.273896 -243.186966)
		(width 0.0889)
		(layer "In4.Cu")
		(net "M_D_CPU1_SA_DQ<28>")
	)
	(arc
		(start 87.528146 -243.186966)
		(mid 87.811102 -243.110789)
		(end 88.094058 -243.186966)
		(width 0.0889)
		(layer "In4.Cu")
		(net "M_D_CPU1_SA_DQ<28>")
	)
	(arc
		(start 82.82813 -243.186966)
		(mid 83.111086 -243.110789)
		(end 83.394042 -243.186966)
		(width 0.0889)
		(layer "In4.Cu")
		(net "M_D_CPU1_SA_DQ<28>")
	)
	(arc
		(start 85.273896 -243.186966)
		(mid 85.456147 -243.237316)
		(end 85.639656 -243.191792)
		(width 0.0889)
		(layer "In4.Cu")
		(net "M_D_CPU1_SA_DQ<28>")
	)
	(arc
		(start 83.402424 -243.191792)
		(mid 83.585932 -243.237286)
		(end 83.768184 -243.186966)
		(width 0.0889)
		(layer "In4.Cu")
		(net "M_D_CPU1_SA_DQ<28>")
	)
	(arc
		(start 90.348054 -243.186966)
		(mid 90.595767 -243.111746)
		(end 90.850974 -243.155216)
		(width 0.0889)
		(layer "In4.Cu")
		(net "M_D_CPU1_SA_DQ<28>")
	)
	(arc
		(start 81.888076 -243.186966)
		(mid 82.171032 -243.110789)
		(end 82.453988 -243.186966)
		(width 0.0889)
		(layer "In4.Cu")
		(net "M_D_CPU1_SA_DQ<28>")
	)
	(arc
		(start 80.948022 -243.186966)
		(mid 81.230978 -243.110789)
		(end 81.513934 -243.186966)
		(width 0.0889)
		(layer "In4.Cu")
		(net "M_D_CPU1_SA_DQ<28>")
	)
	(arc
		(start 86.588092 -243.186966)
		(mid 86.871048 -243.110789)
		(end 87.154004 -243.186966)
		(width 0.0889)
		(layer "In4.Cu")
		(net "M_D_CPU1_SA_DQ<28>")
	)
	(arc
		(start 88.10244 -243.191792)
		(mid 88.285948 -243.237286)
		(end 88.4682 -243.186966)
		(width 0.0889)
		(layer "In4.Cu")
		(net "M_D_CPU1_SA_DQ<28>")
	)
	(arc
		(start 79.070454 -243.186966)
		(mid 79.340223 -243.110943)
		(end 79.613252 -243.174266)
		(width 0.0889)
		(layer "In4.Cu")
		(net "M_D_CPU1_SA_DQ<28>")
	)
	(arc
		(start 80.574134 -243.186966)
		(mid 80.761078 -243.237221)
		(end 80.948022 -243.186966)
		(width 0.0889)
		(layer "In4.Cu")
		(net "M_D_CPU1_SA_DQ<28>")
	)
	(arc
		(start 78.695296 -243.186966)
		(mid 78.872087 -243.237685)
		(end 79.051658 -243.197888)
		(width 0.0889)
		(layer "In4.Cu")
		(net "M_D_CPU1_SA_DQ<28>")
	)
	(arc
		(start 79.654908 -243.198142)
		(mid 79.832986 -243.237126)
		(end 80.008222 -243.186966)
		(width 0.0889)
		(layer "In4.Cu")
		(net "M_D_CPU1_SA_DQ<28>")
	)
	(arc
		(start 81.513934 -243.186966)
		(mid 81.696185 -243.237316)
		(end 81.879694 -243.191792)
		(width 0.0889)
		(layer "In4.Cu")
		(net "M_D_CPU1_SA_DQ<28>")
	)
	(segment
		(start 92.507816 -241.510312)
		(end 92.040964 -241.244374)
		(width 0.10668)
		(layer "F.Cu")
		(net "M_D_CPU1_SA_DQ<27>")
	)
	(segment
		(start 77.23505 -240.408206)
		(end 77.824838 -240.997994)
		(width 0.0889)
		(layer "In4.Cu")
		(net "M_D_CPU1_SA_DQ<27>")
	)
	(segment
		(start 77.824838 -240.997994)
		(end 78.41107 -240.997994)
		(width 0.0889)
		(layer "In4.Cu")
		(net "M_D_CPU1_SA_DQ<27>")
	)
	(segment
		(start 41.893236 -228.351334)
		(end 42.743882 -227.500688)
		(width 0.14478)
		(layer "In4.Cu")
		(net "M_D_CPU1_SA_DQ<27>")
	)
	(segment
		(start 79.06766 -240.921794)
		(end 79.082392 -240.93043)
		(width 0.0889)
		(layer "In4.Cu")
		(net "M_D_CPU1_SA_DQ<27>")
	)
	(segment
		(start 50.232056 -227.500688)
		(end 53.246782 -227.500688)
		(width 0.14478)
		(layer "In4.Cu")
		(net "M_D_CPU1_SA_DQ<27>")
	)
	(segment
		(start 88.094058 -240.921794)
		(end 88.10244 -240.916968)
		(width 0.0889)
		(layer "In4.Cu")
		(net "M_D_CPU1_SA_DQ<27>")
	)
	(segment
		(start 85.639656 -240.916968)
		(end 85.648038 -240.921794)
		(width 0.0889)
		(layer "In4.Cu")
		(net "M_D_CPU1_SA_DQ<27>")
	)
	(segment
		(start 33.111948 -228.351334)
		(end 41.893236 -228.351334)
		(width 0.14478)
		(layer "In4.Cu")
		(net "M_D_CPU1_SA_DQ<27>")
	)
	(segment
		(start 92.195142 -240.978944)
		(end 92.040964 -241.244374)
		(width 0.0889)
		(layer "In4.Cu")
		(net "M_D_CPU1_SA_DQ<27>")
	)
	(segment
		(start 86.57971 -240.916968)
		(end 86.588092 -240.921794)
		(width 0.0889)
		(layer "In4.Cu")
		(net "M_D_CPU1_SA_DQ<27>")
	)
	(segment
		(start 66.331846 -233.972608)
		(end 66.331846 -235.221272)
		(width 0.14478)
		(layer "In4.Cu")
		(net "M_D_CPU1_SA_DQ<27>")
	)
	(segment
		(start 92.17279 -240.895632)
		(end 92.195142 -240.978944)
		(width 0.0889)
		(layer "In4.Cu")
		(net "M_D_CPU1_SA_DQ<27>")
	)
	(segment
		(start 90.339672 -240.916968)
		(end 90.348054 -240.921794)
		(width 0.0889)
		(layer "In4.Cu")
		(net "M_D_CPU1_SA_DQ<27>")
	)
	(segment
		(start 42.743882 -227.500688)
		(end 45.557948 -227.500688)
		(width 0.14478)
		(layer "In4.Cu")
		(net "M_D_CPU1_SA_DQ<27>")
	)
	(segment
		(start 66.331846 -235.221272)
		(end 70.893432 -239.782858)
		(width 0.14478)
		(layer "In4.Cu")
		(net "M_D_CPU1_SA_DQ<27>")
	)
	(segment
		(start 76.086462 -239.782858)
		(end 76.71181 -240.408206)
		(width 0.0889)
		(layer "In4.Cu")
		(net "M_D_CPU1_SA_DQ<27>")
	)
	(segment
		(start 75.946 -239.782858)
		(end 76.086462 -239.782858)
		(width 0.0889)
		(layer "In4.Cu")
		(net "M_D_CPU1_SA_DQ<27>")
	)
	(segment
		(start 79.99984 -240.916968)
		(end 80.008222 -240.921794)
		(width 0.0889)
		(layer "In4.Cu")
		(net "M_D_CPU1_SA_DQ<27>")
	)
	(segment
		(start 70.893432 -239.782858)
		(end 75.946 -239.782858)
		(width 0.14478)
		(layer "In4.Cu")
		(net "M_D_CPU1_SA_DQ<27>")
	)
	(segment
		(start 81.879694 -240.916968)
		(end 81.888076 -240.921794)
		(width 0.0889)
		(layer "In4.Cu")
		(net "M_D_CPU1_SA_DQ<27>")
	)
	(segment
		(start 90.913966 -240.921794)
		(end 90.922348 -240.916968)
		(width 0.0889)
		(layer "In4.Cu")
		(net "M_D_CPU1_SA_DQ<27>")
	)
	(segment
		(start 82.453988 -240.921794)
		(end 82.46237 -240.916968)
		(width 0.0889)
		(layer "In4.Cu")
		(net "M_D_CPU1_SA_DQ<27>")
	)
	(segment
		(start 76.71181 -240.408206)
		(end 77.23505 -240.408206)
		(width 0.0889)
		(layer "In4.Cu")
		(net "M_D_CPU1_SA_DQ<27>")
	)
	(segment
		(start 87.154004 -240.921794)
		(end 87.162386 -240.916968)
		(width 0.0889)
		(layer "In4.Cu")
		(net "M_D_CPU1_SA_DQ<27>")
	)
	(segment
		(start 54.106572 -228.360478)
		(end 60.719716 -228.360478)
		(width 0.14478)
		(layer "In4.Cu")
		(net "M_D_CPU1_SA_DQ<27>")
	)
	(segment
		(start 46.407832 -228.350572)
		(end 49.382172 -228.350572)
		(width 0.14478)
		(layer "In4.Cu")
		(net "M_D_CPU1_SA_DQ<27>")
	)
	(segment
		(start 91.85402 -240.921794)
		(end 91.862402 -240.916968)
		(width 0.0889)
		(layer "In4.Cu")
		(net "M_D_CPU1_SA_DQ<27>")
	)
	(segment
		(start 79.059278 -240.916968)
		(end 79.06766 -240.921794)
		(width 0.0889)
		(layer "In4.Cu")
		(net "M_D_CPU1_SA_DQ<27>")
	)
	(segment
		(start 60.719716 -228.360478)
		(end 66.331846 -233.972608)
		(width 0.14478)
		(layer "In4.Cu")
		(net "M_D_CPU1_SA_DQ<27>")
	)
	(segment
		(start 32.695896 -227.935282)
		(end 33.111948 -228.351334)
		(width 0.14478)
		(layer "In4.Cu")
		(net "M_D_CPU1_SA_DQ<27>")
	)
	(segment
		(start 49.382172 -228.350572)
		(end 50.232056 -227.500688)
		(width 0.14478)
		(layer "In4.Cu")
		(net "M_D_CPU1_SA_DQ<27>")
	)
	(segment
		(start 45.557948 -227.500688)
		(end 46.407832 -228.350572)
		(width 0.14478)
		(layer "In4.Cu")
		(net "M_D_CPU1_SA_DQ<27>")
	)
	(segment
		(start 53.246782 -227.500688)
		(end 54.106572 -228.360478)
		(width 0.14478)
		(layer "In4.Cu")
		(net "M_D_CPU1_SA_DQ<27>")
	)
	(segment
		(start 83.394042 -240.921794)
		(end 83.402424 -240.916968)
		(width 0.0889)
		(layer "In4.Cu")
		(net "M_D_CPU1_SA_DQ<27>")
	)
	(arc
		(start 82.82813 -240.921794)
		(mid 83.111086 -240.997971)
		(end 83.394042 -240.921794)
		(width 0.0889)
		(layer "In4.Cu")
		(net "M_D_CPU1_SA_DQ<27>")
	)
	(arc
		(start 80.574134 -240.921794)
		(mid 80.761078 -240.871539)
		(end 80.948022 -240.921794)
		(width 0.0889)
		(layer "In4.Cu")
		(net "M_D_CPU1_SA_DQ<27>")
	)
	(arc
		(start 85.273896 -240.921794)
		(mid 85.456147 -240.871444)
		(end 85.639656 -240.916968)
		(width 0.0889)
		(layer "In4.Cu")
		(net "M_D_CPU1_SA_DQ<27>")
	)
	(arc
		(start 85.648038 -240.921794)
		(mid 85.930994 -240.997971)
		(end 86.21395 -240.921794)
		(width 0.0889)
		(layer "In4.Cu")
		(net "M_D_CPU1_SA_DQ<27>")
	)
	(arc
		(start 82.46237 -240.916968)
		(mid 82.645878 -240.871474)
		(end 82.82813 -240.921794)
		(width 0.0889)
		(layer "In4.Cu")
		(net "M_D_CPU1_SA_DQ<27>")
	)
	(arc
		(start 91.862402 -240.916968)
		(mid 92.015272 -240.872327)
		(end 92.17279 -240.895632)
		(width 0.0889)
		(layer "In4.Cu")
		(net "M_D_CPU1_SA_DQ<27>")
	)
	(arc
		(start 87.162386 -240.916968)
		(mid 87.345894 -240.871474)
		(end 87.528146 -240.921794)
		(width 0.0889)
		(layer "In4.Cu")
		(net "M_D_CPU1_SA_DQ<27>")
	)
	(arc
		(start 89.973912 -240.921794)
		(mid 90.156163 -240.871444)
		(end 90.339672 -240.916968)
		(width 0.0889)
		(layer "In4.Cu")
		(net "M_D_CPU1_SA_DQ<27>")
	)
	(arc
		(start 84.334096 -240.921794)
		(mid 84.52104 -240.871539)
		(end 84.707984 -240.921794)
		(width 0.0889)
		(layer "In4.Cu")
		(net "M_D_CPU1_SA_DQ<27>")
	)
	(arc
		(start 79.633572 -240.921794)
		(mid 79.816077 -240.871317)
		(end 79.99984 -240.916968)
		(width 0.0889)
		(layer "In4.Cu")
		(net "M_D_CPU1_SA_DQ<27>")
	)
	(arc
		(start 81.513934 -240.921794)
		(mid 81.696185 -240.871444)
		(end 81.879694 -240.916968)
		(width 0.0889)
		(layer "In4.Cu")
		(net "M_D_CPU1_SA_DQ<27>")
	)
	(arc
		(start 89.034112 -240.921794)
		(mid 89.221056 -240.871539)
		(end 89.408 -240.921794)
		(width 0.0889)
		(layer "In4.Cu")
		(net "M_D_CPU1_SA_DQ<27>")
	)
	(arc
		(start 86.588092 -240.921794)
		(mid 86.871048 -240.997971)
		(end 87.154004 -240.921794)
		(width 0.0889)
		(layer "In4.Cu")
		(net "M_D_CPU1_SA_DQ<27>")
	)
	(arc
		(start 88.4682 -240.921794)
		(mid 88.751156 -240.997971)
		(end 89.034112 -240.921794)
		(width 0.0889)
		(layer "In4.Cu")
		(net "M_D_CPU1_SA_DQ<27>")
	)
	(arc
		(start 89.408 -240.921794)
		(mid 89.690956 -240.997971)
		(end 89.973912 -240.921794)
		(width 0.0889)
		(layer "In4.Cu")
		(net "M_D_CPU1_SA_DQ<27>")
	)
	(arc
		(start 80.008222 -240.921794)
		(mid 80.291178 -240.997971)
		(end 80.574134 -240.921794)
		(width 0.0889)
		(layer "In4.Cu")
		(net "M_D_CPU1_SA_DQ<27>")
	)
	(arc
		(start 88.10244 -240.916968)
		(mid 88.285948 -240.871474)
		(end 88.4682 -240.921794)
		(width 0.0889)
		(layer "In4.Cu")
		(net "M_D_CPU1_SA_DQ<27>")
	)
	(arc
		(start 91.288108 -240.921794)
		(mid 91.571064 -240.997971)
		(end 91.85402 -240.921794)
		(width 0.0889)
		(layer "In4.Cu")
		(net "M_D_CPU1_SA_DQ<27>")
	)
	(arc
		(start 81.888076 -240.921794)
		(mid 82.171032 -240.997971)
		(end 82.453988 -240.921794)
		(width 0.0889)
		(layer "In4.Cu")
		(net "M_D_CPU1_SA_DQ<27>")
	)
	(arc
		(start 87.528146 -240.921794)
		(mid 87.811102 -240.997971)
		(end 88.094058 -240.921794)
		(width 0.0889)
		(layer "In4.Cu")
		(net "M_D_CPU1_SA_DQ<27>")
	)
	(arc
		(start 80.948022 -240.921794)
		(mid 81.230978 -240.997971)
		(end 81.513934 -240.921794)
		(width 0.0889)
		(layer "In4.Cu")
		(net "M_D_CPU1_SA_DQ<27>")
	)
	(arc
		(start 83.768184 -240.921794)
		(mid 84.05114 -240.997971)
		(end 84.334096 -240.921794)
		(width 0.0889)
		(layer "In4.Cu")
		(net "M_D_CPU1_SA_DQ<27>")
	)
	(arc
		(start 83.402424 -240.916968)
		(mid 83.585932 -240.871474)
		(end 83.768184 -240.921794)
		(width 0.0889)
		(layer "In4.Cu")
		(net "M_D_CPU1_SA_DQ<27>")
	)
	(arc
		(start 78.41107 -240.997994)
		(mid 78.557587 -240.978608)
		(end 78.694026 -240.921794)
		(width 0.0889)
		(layer "In4.Cu")
		(net "M_D_CPU1_SA_DQ<27>")
	)
	(arc
		(start 78.694026 -240.921794)
		(mid 78.876023 -240.871572)
		(end 79.059278 -240.916968)
		(width 0.0889)
		(layer "In4.Cu")
		(net "M_D_CPU1_SA_DQ<27>")
	)
	(arc
		(start 90.348054 -240.921794)
		(mid 90.63101 -240.997971)
		(end 90.913966 -240.921794)
		(width 0.0889)
		(layer "In4.Cu")
		(net "M_D_CPU1_SA_DQ<27>")
	)
	(arc
		(start 84.707984 -240.921794)
		(mid 84.99094 -240.997971)
		(end 85.273896 -240.921794)
		(width 0.0889)
		(layer "In4.Cu")
		(net "M_D_CPU1_SA_DQ<27>")
	)
	(arc
		(start 86.21395 -240.921794)
		(mid 86.396201 -240.871444)
		(end 86.57971 -240.916968)
		(width 0.0889)
		(layer "In4.Cu")
		(net "M_D_CPU1_SA_DQ<27>")
	)
	(arc
		(start 79.082392 -240.93043)
		(mid 79.359121 -240.998113)
		(end 79.633572 -240.921794)
		(width 0.0889)
		(layer "In4.Cu")
		(net "M_D_CPU1_SA_DQ<27>")
	)
	(arc
		(start 90.922348 -240.916968)
		(mid 91.105856 -240.871474)
		(end 91.288108 -240.921794)
		(width 0.0889)
		(layer "In4.Cu")
		(net "M_D_CPU1_SA_DQ<27>")
	)
	(segment
		(start 91.097862 -240.700306)
		(end 90.63101 -240.434368)
		(width 0.10668)
		(layer "F.Cu")
		(net "M_D_CPU1_SA_DQ<26>")
	)
	(segment
		(start 50.222404 -225.810318)
		(end 53.256434 -225.810318)
		(width 0.14478)
		(layer "In4.Cu")
		(net "M_D_CPU1_SA_DQ<26>")
	)
	(segment
		(start 35.099498 -227.19538)
		(end 35.262566 -227.358448)
		(width 0.14478)
		(layer "In4.Cu")
		(net "M_D_CPU1_SA_DQ<26>")
	)
	(segment
		(start 81.044034 -240.111788)
		(end 81.052416 -240.106962)
		(width 0.0889)
		(layer "In4.Cu")
		(net "M_D_CPU1_SA_DQ<26>")
	)
	(segment
		(start 75.92568 -238.873538)
		(end 76.233782 -238.873538)
		(width 0.0889)
		(layer "In4.Cu")
		(net "M_D_CPU1_SA_DQ<26>")
	)
	(segment
		(start 46.417738 -226.660456)
		(end 49.372266 -226.660456)
		(width 0.14478)
		(layer "In4.Cu")
		(net "M_D_CPU1_SA_DQ<26>")
	)
	(segment
		(start 35.492944 -227.358448)
		(end 35.656012 -227.19538)
		(width 0.14478)
		(layer "In4.Cu")
		(net "M_D_CPU1_SA_DQ<26>")
	)
	(segment
		(start 88.929718 -240.106962)
		(end 88.9381 -240.111788)
		(width 0.0889)
		(layer "In4.Cu")
		(net "M_D_CPU1_SA_DQ<26>")
	)
	(segment
		(start 34.954718 -226.660456)
		(end 35.099498 -226.805236)
		(width 0.14478)
		(layer "In4.Cu")
		(net "M_D_CPU1_SA_DQ<26>")
	)
	(segment
		(start 60.291726 -226.660456)
		(end 67.271646 -233.640376)
		(width 0.14478)
		(layer "In4.Cu")
		(net "M_D_CPU1_SA_DQ<26>")
	)
	(segment
		(start 87.989664 -240.106962)
		(end 87.998046 -240.111788)
		(width 0.0889)
		(layer "In4.Cu")
		(net "M_D_CPU1_SA_DQ<26>")
	)
	(segment
		(start 35.262566 -227.358448)
		(end 35.492944 -227.358448)
		(width 0.14478)
		(layer "In4.Cu")
		(net "M_D_CPU1_SA_DQ<26>")
	)
	(segment
		(start 33.121092 -226.660456)
		(end 34.954718 -226.660456)
		(width 0.14478)
		(layer "In4.Cu")
		(net "M_D_CPU1_SA_DQ<26>")
	)
	(segment
		(start 79.539592 -240.112042)
		(end 79.561182 -240.124488)
		(width 0.0889)
		(layer "In4.Cu")
		(net "M_D_CPU1_SA_DQ<26>")
	)
	(segment
		(start 90.784934 -240.168938)
		(end 90.63101 -240.434368)
		(width 0.0889)
		(layer "In4.Cu")
		(net "M_D_CPU1_SA_DQ<26>")
	)
	(segment
		(start 84.229702 -240.106962)
		(end 84.238084 -240.111788)
		(width 0.0889)
		(layer "In4.Cu")
		(net "M_D_CPU1_SA_DQ<26>")
	)
	(segment
		(start 76.233782 -238.873538)
		(end 76.41209 -239.051846)
		(width 0.0889)
		(layer "In4.Cu")
		(net "M_D_CPU1_SA_DQ<26>")
	)
	(segment
		(start 35.81908 -226.660456)
		(end 41.884092 -226.660456)
		(width 0.14478)
		(layer "In4.Cu")
		(net "M_D_CPU1_SA_DQ<26>")
	)
	(segment
		(start 77.11313 -239.051846)
		(end 78.122018 -240.060734)
		(width 0.0889)
		(layer "In4.Cu")
		(net "M_D_CPU1_SA_DQ<26>")
	)
	(segment
		(start 42.73423 -225.810318)
		(end 45.5676 -225.810318)
		(width 0.14478)
		(layer "In4.Cu")
		(net "M_D_CPU1_SA_DQ<26>")
	)
	(segment
		(start 45.5676 -225.810318)
		(end 46.417738 -226.660456)
		(width 0.14478)
		(layer "In4.Cu")
		(net "M_D_CPU1_SA_DQ<26>")
	)
	(segment
		(start 89.504012 -240.111788)
		(end 89.512394 -240.106962)
		(width 0.0889)
		(layer "In4.Cu")
		(net "M_D_CPU1_SA_DQ<26>")
	)
	(segment
		(start 78.122018 -240.060734)
		(end 78.41107 -240.060734)
		(width 0.0889)
		(layer "In4.Cu")
		(net "M_D_CPU1_SA_DQ<26>")
	)
	(segment
		(start 53.256434 -225.810318)
		(end 54.106572 -226.660456)
		(width 0.14478)
		(layer "In4.Cu")
		(net "M_D_CPU1_SA_DQ<26>")
	)
	(segment
		(start 79.521304 -240.101628)
		(end 79.539592 -240.112042)
		(width 0.0889)
		(layer "In4.Cu")
		(net "M_D_CPU1_SA_DQ<26>")
	)
	(segment
		(start 83.289648 -240.106962)
		(end 83.29803 -240.111788)
		(width 0.0889)
		(layer "In4.Cu")
		(net "M_D_CPU1_SA_DQ<26>")
	)
	(segment
		(start 85.74405 -240.111788)
		(end 85.752432 -240.106962)
		(width 0.0889)
		(layer "In4.Cu")
		(net "M_D_CPU1_SA_DQ<26>")
	)
	(segment
		(start 71.256144 -238.873538)
		(end 75.92568 -238.873538)
		(width 0.14478)
		(layer "In4.Cu")
		(net "M_D_CPU1_SA_DQ<26>")
	)
	(segment
		(start 84.803996 -240.111788)
		(end 84.812378 -240.106962)
		(width 0.0889)
		(layer "In4.Cu")
		(net "M_D_CPU1_SA_DQ<26>")
	)
	(segment
		(start 67.271646 -234.88904)
		(end 71.256144 -238.873538)
		(width 0.14478)
		(layer "In4.Cu")
		(net "M_D_CPU1_SA_DQ<26>")
	)
	(segment
		(start 80.46974 -240.106962)
		(end 80.478122 -240.111788)
		(width 0.0889)
		(layer "In4.Cu")
		(net "M_D_CPU1_SA_DQ<26>")
	)
	(segment
		(start 67.271646 -233.640376)
		(end 67.271646 -234.88904)
		(width 0.14478)
		(layer "In4.Cu")
		(net "M_D_CPU1_SA_DQ<26>")
	)
	(segment
		(start 32.695896 -226.23526)
		(end 33.121092 -226.660456)
		(width 0.14478)
		(layer "In4.Cu")
		(net "M_D_CPU1_SA_DQ<26>")
	)
	(segment
		(start 35.656012 -226.823524)
		(end 35.81908 -226.660456)
		(width 0.14478)
		(layer "In4.Cu")
		(net "M_D_CPU1_SA_DQ<26>")
	)
	(segment
		(start 90.762582 -240.085626)
		(end 90.784934 -240.168938)
		(width 0.0889)
		(layer "In4.Cu")
		(net "M_D_CPU1_SA_DQ<26>")
	)
	(segment
		(start 35.656012 -227.19538)
		(end 35.656012 -226.823524)
		(width 0.14478)
		(layer "In4.Cu")
		(net "M_D_CPU1_SA_DQ<26>")
	)
	(segment
		(start 54.106572 -226.660456)
		(end 60.291726 -226.660456)
		(width 0.14478)
		(layer "In4.Cu")
		(net "M_D_CPU1_SA_DQ<26>")
	)
	(segment
		(start 41.884092 -226.660456)
		(end 42.73423 -225.810318)
		(width 0.14478)
		(layer "In4.Cu")
		(net "M_D_CPU1_SA_DQ<26>")
	)
	(segment
		(start 76.41209 -239.051846)
		(end 77.11313 -239.051846)
		(width 0.0889)
		(layer "In4.Cu")
		(net "M_D_CPU1_SA_DQ<26>")
	)
	(segment
		(start 79.143098 -240.125504)
		(end 79.166466 -240.111788)
		(width 0.0889)
		(layer "In4.Cu")
		(net "M_D_CPU1_SA_DQ<26>")
	)
	(segment
		(start 49.372266 -226.660456)
		(end 50.222404 -225.810318)
		(width 0.14478)
		(layer "In4.Cu")
		(net "M_D_CPU1_SA_DQ<26>")
	)
	(segment
		(start 35.099498 -226.805236)
		(end 35.099498 -227.19538)
		(width 0.14478)
		(layer "In4.Cu")
		(net "M_D_CPU1_SA_DQ<26>")
	)
	(arc
		(start 84.238084 -240.111788)
		(mid 84.52104 -240.187965)
		(end 84.803996 -240.111788)
		(width 0.0889)
		(layer "In4.Cu")
		(net "M_D_CPU1_SA_DQ<26>")
	)
	(arc
		(start 82.923888 -240.111788)
		(mid 83.106139 -240.061438)
		(end 83.289648 -240.106962)
		(width 0.0889)
		(layer "In4.Cu")
		(net "M_D_CPU1_SA_DQ<26>")
	)
	(arc
		(start 81.984088 -240.111788)
		(mid 82.171032 -240.061533)
		(end 82.357976 -240.111788)
		(width 0.0889)
		(layer "In4.Cu")
		(net "M_D_CPU1_SA_DQ<26>")
	)
	(arc
		(start 86.118192 -240.111788)
		(mid 86.401148 -240.187965)
		(end 86.684104 -240.111788)
		(width 0.0889)
		(layer "In4.Cu")
		(net "M_D_CPU1_SA_DQ<26>")
	)
	(arc
		(start 85.178138 -240.111788)
		(mid 85.461094 -240.187965)
		(end 85.74405 -240.111788)
		(width 0.0889)
		(layer "In4.Cu")
		(net "M_D_CPU1_SA_DQ<26>")
	)
	(arc
		(start 85.752432 -240.106962)
		(mid 85.93594 -240.061468)
		(end 86.118192 -240.111788)
		(width 0.0889)
		(layer "In4.Cu")
		(net "M_D_CPU1_SA_DQ<26>")
	)
	(arc
		(start 83.29803 -240.111788)
		(mid 83.580986 -240.187965)
		(end 83.863942 -240.111788)
		(width 0.0889)
		(layer "In4.Cu")
		(net "M_D_CPU1_SA_DQ<26>")
	)
	(arc
		(start 82.357976 -240.111788)
		(mid 82.640932 -240.187965)
		(end 82.923888 -240.111788)
		(width 0.0889)
		(layer "In4.Cu")
		(net "M_D_CPU1_SA_DQ<26>")
	)
	(arc
		(start 79.561182 -240.124488)
		(mid 79.834211 -240.187807)
		(end 80.10398 -240.111788)
		(width 0.0889)
		(layer "In4.Cu")
		(net "M_D_CPU1_SA_DQ<26>")
	)
	(arc
		(start 78.41107 -240.060734)
		(mid 78.508573 -240.073749)
		(end 78.599284 -240.111788)
		(width 0.0889)
		(layer "In4.Cu")
		(net "M_D_CPU1_SA_DQ<26>")
	)
	(arc
		(start 86.684104 -240.111788)
		(mid 86.871048 -240.061533)
		(end 87.057992 -240.111788)
		(width 0.0889)
		(layer "In4.Cu")
		(net "M_D_CPU1_SA_DQ<26>")
	)
	(arc
		(start 84.812378 -240.106962)
		(mid 84.995886 -240.061468)
		(end 85.178138 -240.111788)
		(width 0.0889)
		(layer "In4.Cu")
		(net "M_D_CPU1_SA_DQ<26>")
	)
	(arc
		(start 81.052416 -240.106962)
		(mid 81.235924 -240.061468)
		(end 81.418176 -240.111788)
		(width 0.0889)
		(layer "In4.Cu")
		(net "M_D_CPU1_SA_DQ<26>")
	)
	(arc
		(start 80.478122 -240.111788)
		(mid 80.761078 -240.187965)
		(end 81.044034 -240.111788)
		(width 0.0889)
		(layer "In4.Cu")
		(net "M_D_CPU1_SA_DQ<26>")
	)
	(arc
		(start 79.166466 -240.111788)
		(mid 79.342586 -240.06181)
		(end 79.521304 -240.101628)
		(width 0.0889)
		(layer "In4.Cu")
		(net "M_D_CPU1_SA_DQ<26>")
	)
	(arc
		(start 88.9381 -240.111788)
		(mid 89.221056 -240.187965)
		(end 89.504012 -240.111788)
		(width 0.0889)
		(layer "In4.Cu")
		(net "M_D_CPU1_SA_DQ<26>")
	)
	(arc
		(start 88.563958 -240.111788)
		(mid 88.746209 -240.061438)
		(end 88.929718 -240.106962)
		(width 0.0889)
		(layer "In4.Cu")
		(net "M_D_CPU1_SA_DQ<26>")
	)
	(arc
		(start 87.057992 -240.111788)
		(mid 87.340948 -240.187965)
		(end 87.623904 -240.111788)
		(width 0.0889)
		(layer "In4.Cu")
		(net "M_D_CPU1_SA_DQ<26>")
	)
	(arc
		(start 89.512394 -240.106962)
		(mid 89.695902 -240.061468)
		(end 89.878154 -240.111788)
		(width 0.0889)
		(layer "In4.Cu")
		(net "M_D_CPU1_SA_DQ<26>")
	)
	(arc
		(start 87.998046 -240.111788)
		(mid 88.281002 -240.187965)
		(end 88.563958 -240.111788)
		(width 0.0889)
		(layer "In4.Cu")
		(net "M_D_CPU1_SA_DQ<26>")
	)
	(arc
		(start 83.863942 -240.111788)
		(mid 84.046193 -240.061438)
		(end 84.229702 -240.106962)
		(width 0.0889)
		(layer "In4.Cu")
		(net "M_D_CPU1_SA_DQ<26>")
	)
	(arc
		(start 90.444066 -240.111788)
		(mid 90.600385 -240.062793)
		(end 90.762582 -240.085626)
		(width 0.0889)
		(layer "In4.Cu")
		(net "M_D_CPU1_SA_DQ<26>")
	)
	(arc
		(start 80.10398 -240.111788)
		(mid 80.286231 -240.061438)
		(end 80.46974 -240.106962)
		(width 0.0889)
		(layer "In4.Cu")
		(net "M_D_CPU1_SA_DQ<26>")
	)
	(arc
		(start 78.599284 -240.111788)
		(mid 78.869441 -240.18855)
		(end 79.143098 -240.125504)
		(width 0.0889)
		(layer "In4.Cu")
		(net "M_D_CPU1_SA_DQ<26>")
	)
	(arc
		(start 87.623904 -240.111788)
		(mid 87.806155 -240.061438)
		(end 87.989664 -240.106962)
		(width 0.0889)
		(layer "In4.Cu")
		(net "M_D_CPU1_SA_DQ<26>")
	)
	(arc
		(start 89.878154 -240.111788)
		(mid 90.16111 -240.187965)
		(end 90.444066 -240.111788)
		(width 0.0889)
		(layer "In4.Cu")
		(net "M_D_CPU1_SA_DQ<26>")
	)
	(arc
		(start 81.418176 -240.111788)
		(mid 81.701132 -240.187965)
		(end 81.984088 -240.111788)
		(width 0.0889)
		(layer "In4.Cu")
		(net "M_D_CPU1_SA_DQ<26>")
	)
	(segment
		(start 92.97797 -240.700306)
		(end 92.511118 -240.434368)
		(width 0.10668)
		(layer "F.Cu")
		(net "M_D_CPU1_SA_DQ<25>")
	)
	(segment
		(start 42.733214 -226.660456)
		(end 43.016424 -226.660456)
		(width 0.14478)
		(layer "In4.Cu")
		(net "M_D_CPU1_SA_DQ<25>")
	)
	(segment
		(start 60.505594 -227.51034)
		(end 66.811906 -233.816652)
		(width 0.14478)
		(layer "In4.Cu")
		(net "M_D_CPU1_SA_DQ<25>")
	)
	(segment
		(start 43.736006 -226.889056)
		(end 43.736006 -226.823524)
		(width 0.14478)
		(layer "In4.Cu")
		(net "M_D_CPU1_SA_DQ<25>")
	)
	(segment
		(start 71.074788 -239.328198)
		(end 75.91933 -239.328198)
		(width 0.14478)
		(layer "In4.Cu")
		(net "M_D_CPU1_SA_DQ<25>")
	)
	(segment
		(start 39.379398 -227.673408)
		(end 39.542466 -227.51034)
		(width 0.14478)
		(layer "In4.Cu")
		(net "M_D_CPU1_SA_DQ<25>")
	)
	(segment
		(start 92.260674 -240.725198)
		(end 92.35694 -240.699798)
		(width 0.0889)
		(layer "In4.Cu")
		(net "M_D_CPU1_SA_DQ<25>")
	)
	(segment
		(start 48.2981 -227.51034)
		(end 48.461168 -227.673408)
		(width 0.14478)
		(layer "In4.Cu")
		(net "M_D_CPU1_SA_DQ<25>")
	)
	(segment
		(start 41.88333 -227.51034)
		(end 42.733214 -226.660456)
		(width 0.14478)
		(layer "In4.Cu")
		(net "M_D_CPU1_SA_DQ<25>")
	)
	(segment
		(start 37.709856 -227.673408)
		(end 37.709856 -227.742496)
		(width 0.14478)
		(layer "In4.Cu")
		(net "M_D_CPU1_SA_DQ<25>")
	)
	(segment
		(start 55.638192 -227.905564)
		(end 55.80126 -227.742496)
		(width 0.14478)
		(layer "In4.Cu")
		(net "M_D_CPU1_SA_DQ<25>")
	)
	(segment
		(start 38.26637 -227.742496)
		(end 38.26637 -227.278184)
		(width 0.14478)
		(layer "In4.Cu")
		(net "M_D_CPU1_SA_DQ<25>")
	)
	(segment
		(start 50.256694 -226.660456)
		(end 50.560224 -226.660456)
		(width 0.14478)
		(layer "In4.Cu")
		(net "M_D_CPU1_SA_DQ<25>")
	)
	(segment
		(start 39.542466 -227.51034)
		(end 41.88333 -227.51034)
		(width 0.14478)
		(layer "In4.Cu")
		(net "M_D_CPU1_SA_DQ<25>")
	)
	(segment
		(start 88.929718 -240.761774)
		(end 88.9381 -240.756948)
		(width 0.0889)
		(layer "In4.Cu")
		(net "M_D_CPU1_SA_DQ<25>")
	)
	(segment
		(start 43.179492 -226.823524)
		(end 43.179492 -226.889056)
		(width 0.14478)
		(layer "In4.Cu")
		(net "M_D_CPU1_SA_DQ<25>")
	)
	(segment
		(start 51.121056 -227.047806)
		(end 51.279806 -226.889056)
		(width 0.14478)
		(layer "In4.Cu")
		(net "M_D_CPU1_SA_DQ<25>")
	)
	(segment
		(start 48.461168 -227.673408)
		(end 48.461168 -227.742496)
		(width 0.14478)
		(layer "In4.Cu")
		(net "M_D_CPU1_SA_DQ<25>")
	)
	(segment
		(start 48.861472 -227.898706)
		(end 49.017682 -227.742496)
		(width 0.14478)
		(layer "In4.Cu")
		(net "M_D_CPU1_SA_DQ<25>")
	)
	(segment
		(start 55.01259 -227.51034)
		(end 55.407814 -227.905564)
		(width 0.14478)
		(layer "In4.Cu")
		(net "M_D_CPU1_SA_DQ<25>")
	)
	(segment
		(start 54.084474 -227.51034)
		(end 55.01259 -227.51034)
		(width 0.14478)
		(layer "In4.Cu")
		(net "M_D_CPU1_SA_DQ<25>")
	)
	(segment
		(start 51.279806 -226.823524)
		(end 51.442874 -226.660456)
		(width 0.14478)
		(layer "In4.Cu")
		(net "M_D_CPU1_SA_DQ<25>")
	)
	(segment
		(start 39.379398 -227.742496)
		(end 39.379398 -227.673408)
		(width 0.14478)
		(layer "In4.Cu")
		(net "M_D_CPU1_SA_DQ<25>")
	)
	(segment
		(start 89.504012 -240.756948)
		(end 89.512394 -240.761774)
		(width 0.0889)
		(layer "In4.Cu")
		(net "M_D_CPU1_SA_DQ<25>")
	)
	(segment
		(start 77.48905 -239.915446)
		(end 77.48905 -240.392712)
		(width 0.0889)
		(layer "In4.Cu")
		(net "M_D_CPU1_SA_DQ<25>")
	)
	(segment
		(start 85.74405 -240.756948)
		(end 85.752432 -240.761774)
		(width 0.0889)
		(layer "In4.Cu")
		(net "M_D_CPU1_SA_DQ<25>")
	)
	(segment
		(start 43.899074 -226.660456)
		(end 45.55871 -226.660456)
		(width 0.14478)
		(layer "In4.Cu")
		(net "M_D_CPU1_SA_DQ<25>")
	)
	(segment
		(start 81.044034 -240.756948)
		(end 81.052416 -240.761774)
		(width 0.0889)
		(layer "In4.Cu")
		(net "M_D_CPU1_SA_DQ<25>")
	)
	(segment
		(start 80.46974 -240.761774)
		(end 80.478122 -240.756948)
		(width 0.0889)
		(layer "In4.Cu")
		(net "M_D_CPU1_SA_DQ<25>")
	)
	(segment
		(start 43.179492 -226.889056)
		(end 43.338242 -227.047806)
		(width 0.14478)
		(layer "In4.Cu")
		(net "M_D_CPU1_SA_DQ<25>")
	)
	(segment
		(start 43.338242 -227.047806)
		(end 43.577256 -227.047806)
		(width 0.14478)
		(layer "In4.Cu")
		(net "M_D_CPU1_SA_DQ<25>")
	)
	(segment
		(start 77.903832 -240.807494)
		(end 78.41107 -240.807494)
		(width 0.0889)
		(layer "In4.Cu")
		(net "M_D_CPU1_SA_DQ<25>")
	)
	(segment
		(start 37.709856 -227.742496)
		(end 37.866066 -227.898706)
		(width 0.14478)
		(layer "In4.Cu")
		(net "M_D_CPU1_SA_DQ<25>")
	)
	(segment
		(start 50.723292 -226.889056)
		(end 50.882042 -227.047806)
		(width 0.14478)
		(layer "In4.Cu")
		(net "M_D_CPU1_SA_DQ<25>")
	)
	(segment
		(start 55.964328 -227.115624)
		(end 56.194706 -227.115624)
		(width 0.14478)
		(layer "In4.Cu")
		(net "M_D_CPU1_SA_DQ<25>")
	)
	(segment
		(start 56.194706 -227.115624)
		(end 56.357774 -227.278692)
		(width 0.14478)
		(layer "In4.Cu")
		(net "M_D_CPU1_SA_DQ<25>")
	)
	(segment
		(start 53.23459 -226.660456)
		(end 54.084474 -227.51034)
		(width 0.14478)
		(layer "In4.Cu")
		(net "M_D_CPU1_SA_DQ<25>")
	)
	(segment
		(start 56.357774 -227.347272)
		(end 56.520842 -227.51034)
		(width 0.14478)
		(layer "In4.Cu")
		(net "M_D_CPU1_SA_DQ<25>")
	)
	(segment
		(start 48.617378 -227.898706)
		(end 48.861472 -227.898706)
		(width 0.14478)
		(layer "In4.Cu")
		(net "M_D_CPU1_SA_DQ<25>")
	)
	(segment
		(start 38.822884 -227.742496)
		(end 38.979094 -227.898706)
		(width 0.14478)
		(layer "In4.Cu")
		(net "M_D_CPU1_SA_DQ<25>")
	)
	(segment
		(start 49.40681 -227.51034)
		(end 50.256694 -226.660456)
		(width 0.14478)
		(layer "In4.Cu")
		(net "M_D_CPU1_SA_DQ<25>")
	)
	(segment
		(start 38.822884 -227.278184)
		(end 38.822884 -227.742496)
		(width 0.14478)
		(layer "In4.Cu")
		(net "M_D_CPU1_SA_DQ<25>")
	)
	(segment
		(start 55.407814 -227.905564)
		(end 55.638192 -227.905564)
		(width 0.14478)
		(layer "In4.Cu")
		(net "M_D_CPU1_SA_DQ<25>")
	)
	(segment
		(start 87.989664 -240.761774)
		(end 87.998046 -240.756948)
		(width 0.0889)
		(layer "In4.Cu")
		(net "M_D_CPU1_SA_DQ<25>")
	)
	(segment
		(start 51.279806 -226.889056)
		(end 51.279806 -226.823524)
		(width 0.14478)
		(layer "In4.Cu")
		(net "M_D_CPU1_SA_DQ<25>")
	)
	(segment
		(start 49.017682 -227.742496)
		(end 49.017682 -227.673408)
		(width 0.14478)
		(layer "In4.Cu")
		(net "M_D_CPU1_SA_DQ<25>")
	)
	(segment
		(start 76.216002 -239.328198)
		(end 76.33843 -239.450626)
		(width 0.0889)
		(layer "In4.Cu")
		(net "M_D_CPU1_SA_DQ<25>")
	)
	(segment
		(start 79.153258 -240.750852)
		(end 79.163672 -240.756948)
		(width 0.0889)
		(layer "In4.Cu")
		(net "M_D_CPU1_SA_DQ<25>")
	)
	(segment
		(start 49.017682 -227.673408)
		(end 49.18075 -227.51034)
		(width 0.14478)
		(layer "In4.Cu")
		(net "M_D_CPU1_SA_DQ<25>")
	)
	(segment
		(start 77.48905 -240.392712)
		(end 77.903832 -240.807494)
		(width 0.0889)
		(layer "In4.Cu")
		(net "M_D_CPU1_SA_DQ<25>")
	)
	(segment
		(start 46.408594 -227.51034)
		(end 48.2981 -227.51034)
		(width 0.14478)
		(layer "In4.Cu")
		(net "M_D_CPU1_SA_DQ<25>")
	)
	(segment
		(start 50.723292 -226.823524)
		(end 50.723292 -226.889056)
		(width 0.14478)
		(layer "In4.Cu")
		(net "M_D_CPU1_SA_DQ<25>")
	)
	(segment
		(start 75.91933 -239.328198)
		(end 76.216002 -239.328198)
		(width 0.0889)
		(layer "In4.Cu")
		(net "M_D_CPU1_SA_DQ<25>")
	)
	(segment
		(start 66.811906 -235.065316)
		(end 71.074788 -239.328198)
		(width 0.14478)
		(layer "In4.Cu")
		(net "M_D_CPU1_SA_DQ<25>")
	)
	(segment
		(start 92.35694 -240.699798)
		(end 92.511118 -240.434368)
		(width 0.0889)
		(layer "In4.Cu")
		(net "M_D_CPU1_SA_DQ<25>")
	)
	(segment
		(start 55.80126 -227.278692)
		(end 55.964328 -227.115624)
		(width 0.14478)
		(layer "In4.Cu")
		(net "M_D_CPU1_SA_DQ<25>")
	)
	(segment
		(start 38.429438 -227.115116)
		(end 38.659816 -227.115116)
		(width 0.14478)
		(layer "In4.Cu")
		(net "M_D_CPU1_SA_DQ<25>")
	)
	(segment
		(start 38.11016 -227.898706)
		(end 38.26637 -227.742496)
		(width 0.14478)
		(layer "In4.Cu")
		(net "M_D_CPU1_SA_DQ<25>")
	)
	(segment
		(start 48.461168 -227.742496)
		(end 48.617378 -227.898706)
		(width 0.14478)
		(layer "In4.Cu")
		(net "M_D_CPU1_SA_DQ<25>")
	)
	(segment
		(start 84.803996 -240.756948)
		(end 84.812378 -240.761774)
		(width 0.0889)
		(layer "In4.Cu")
		(net "M_D_CPU1_SA_DQ<25>")
	)
	(segment
		(start 43.577256 -227.047806)
		(end 43.736006 -226.889056)
		(width 0.14478)
		(layer "In4.Cu")
		(net "M_D_CPU1_SA_DQ<25>")
	)
	(segment
		(start 45.55871 -226.660456)
		(end 46.408594 -227.51034)
		(width 0.14478)
		(layer "In4.Cu")
		(net "M_D_CPU1_SA_DQ<25>")
	)
	(segment
		(start 83.289648 -240.761774)
		(end 83.29803 -240.756948)
		(width 0.0889)
		(layer "In4.Cu")
		(net "M_D_CPU1_SA_DQ<25>")
	)
	(segment
		(start 50.882042 -227.047806)
		(end 51.121056 -227.047806)
		(width 0.14478)
		(layer "In4.Cu")
		(net "M_D_CPU1_SA_DQ<25>")
	)
	(segment
		(start 50.560224 -226.660456)
		(end 50.723292 -226.823524)
		(width 0.14478)
		(layer "In4.Cu")
		(net "M_D_CPU1_SA_DQ<25>")
	)
	(segment
		(start 79.163672 -240.756948)
		(end 79.17815 -240.76533)
		(width 0.0889)
		(layer "In4.Cu")
		(net "M_D_CPU1_SA_DQ<25>")
	)
	(segment
		(start 49.18075 -227.51034)
		(end 49.40681 -227.51034)
		(width 0.14478)
		(layer "In4.Cu")
		(net "M_D_CPU1_SA_DQ<25>")
	)
	(segment
		(start 76.33843 -239.450626)
		(end 77.02423 -239.450626)
		(width 0.0889)
		(layer "In4.Cu")
		(net "M_D_CPU1_SA_DQ<25>")
	)
	(segment
		(start 56.520842 -227.51034)
		(end 60.505594 -227.51034)
		(width 0.14478)
		(layer "In4.Cu")
		(net "M_D_CPU1_SA_DQ<25>")
	)
	(segment
		(start 43.016424 -226.660456)
		(end 43.179492 -226.823524)
		(width 0.14478)
		(layer "In4.Cu")
		(net "M_D_CPU1_SA_DQ<25>")
	)
	(segment
		(start 80.093566 -240.750852)
		(end 80.10398 -240.756948)
		(width 0.0889)
		(layer "In4.Cu")
		(net "M_D_CPU1_SA_DQ<25>")
	)
	(segment
		(start 91.749626 -240.761774)
		(end 91.758008 -240.756948)
		(width 0.0889)
		(layer "In4.Cu")
		(net "M_D_CPU1_SA_DQ<25>")
	)
	(segment
		(start 84.229702 -240.761774)
		(end 84.238084 -240.756948)
		(width 0.0889)
		(layer "In4.Cu")
		(net "M_D_CPU1_SA_DQ<25>")
	)
	(segment
		(start 66.811906 -233.816652)
		(end 66.811906 -235.065316)
		(width 0.14478)
		(layer "In4.Cu")
		(net "M_D_CPU1_SA_DQ<25>")
	)
	(segment
		(start 38.979094 -227.898706)
		(end 39.223188 -227.898706)
		(width 0.14478)
		(layer "In4.Cu")
		(net "M_D_CPU1_SA_DQ<25>")
	)
	(segment
		(start 77.02423 -239.450626)
		(end 77.48905 -239.915446)
		(width 0.0889)
		(layer "In4.Cu")
		(net "M_D_CPU1_SA_DQ<25>")
	)
	(segment
		(start 55.80126 -227.742496)
		(end 55.80126 -227.278692)
		(width 0.14478)
		(layer "In4.Cu")
		(net "M_D_CPU1_SA_DQ<25>")
	)
	(segment
		(start 43.736006 -226.823524)
		(end 43.899074 -226.660456)
		(width 0.14478)
		(layer "In4.Cu")
		(net "M_D_CPU1_SA_DQ<25>")
	)
	(segment
		(start 37.220906 -227.51034)
		(end 37.546788 -227.51034)
		(width 0.14478)
		(layer "In4.Cu")
		(net "M_D_CPU1_SA_DQ<25>")
	)
	(segment
		(start 38.659816 -227.115116)
		(end 38.822884 -227.278184)
		(width 0.14478)
		(layer "In4.Cu")
		(net "M_D_CPU1_SA_DQ<25>")
	)
	(segment
		(start 38.26637 -227.278184)
		(end 38.429438 -227.115116)
		(width 0.14478)
		(layer "In4.Cu")
		(net "M_D_CPU1_SA_DQ<25>")
	)
	(segment
		(start 56.357774 -227.278692)
		(end 56.357774 -227.347272)
		(width 0.14478)
		(layer "In4.Cu")
		(net "M_D_CPU1_SA_DQ<25>")
	)
	(segment
		(start 51.442874 -226.660456)
		(end 53.23459 -226.660456)
		(width 0.14478)
		(layer "In4.Cu")
		(net "M_D_CPU1_SA_DQ<25>")
	)
	(segment
		(start 36.795964 -227.085398)
		(end 37.220906 -227.51034)
		(width 0.14478)
		(layer "In4.Cu")
		(net "M_D_CPU1_SA_DQ<25>")
	)
	(segment
		(start 39.223188 -227.898706)
		(end 39.379398 -227.742496)
		(width 0.14478)
		(layer "In4.Cu")
		(net "M_D_CPU1_SA_DQ<25>")
	)
	(segment
		(start 37.546788 -227.51034)
		(end 37.709856 -227.673408)
		(width 0.14478)
		(layer "In4.Cu")
		(net "M_D_CPU1_SA_DQ<25>")
	)
	(segment
		(start 37.866066 -227.898706)
		(end 38.11016 -227.898706)
		(width 0.14478)
		(layer "In4.Cu")
		(net "M_D_CPU1_SA_DQ<25>")
	)
	(arc
		(start 89.878154 -240.756948)
		(mid 90.16111 -240.680771)
		(end 90.444066 -240.756948)
		(width 0.0889)
		(layer "In4.Cu")
		(net "M_D_CPU1_SA_DQ<25>")
	)
	(arc
		(start 86.684104 -240.756948)
		(mid 86.871048 -240.807203)
		(end 87.057992 -240.756948)
		(width 0.0889)
		(layer "In4.Cu")
		(net "M_D_CPU1_SA_DQ<25>")
	)
	(arc
		(start 81.984088 -240.756948)
		(mid 82.171032 -240.807203)
		(end 82.357976 -240.756948)
		(width 0.0889)
		(layer "In4.Cu")
		(net "M_D_CPU1_SA_DQ<25>")
	)
	(arc
		(start 84.238084 -240.756948)
		(mid 84.52104 -240.680771)
		(end 84.803996 -240.756948)
		(width 0.0889)
		(layer "In4.Cu")
		(net "M_D_CPU1_SA_DQ<25>")
	)
	(arc
		(start 84.812378 -240.761774)
		(mid 84.995886 -240.807268)
		(end 85.178138 -240.756948)
		(width 0.0889)
		(layer "In4.Cu")
		(net "M_D_CPU1_SA_DQ<25>")
	)
	(arc
		(start 80.478122 -240.756948)
		(mid 80.761078 -240.680771)
		(end 81.044034 -240.756948)
		(width 0.0889)
		(layer "In4.Cu")
		(net "M_D_CPU1_SA_DQ<25>")
	)
	(arc
		(start 87.623904 -240.756948)
		(mid 87.806155 -240.807298)
		(end 87.989664 -240.761774)
		(width 0.0889)
		(layer "In4.Cu")
		(net "M_D_CPU1_SA_DQ<25>")
	)
	(arc
		(start 88.9381 -240.756948)
		(mid 89.221056 -240.680771)
		(end 89.504012 -240.756948)
		(width 0.0889)
		(layer "In4.Cu")
		(net "M_D_CPU1_SA_DQ<25>")
	)
	(arc
		(start 82.923888 -240.756948)
		(mid 83.106139 -240.807298)
		(end 83.289648 -240.761774)
		(width 0.0889)
		(layer "In4.Cu")
		(net "M_D_CPU1_SA_DQ<25>")
	)
	(arc
		(start 85.752432 -240.761774)
		(mid 85.93594 -240.807268)
		(end 86.118192 -240.756948)
		(width 0.0889)
		(layer "In4.Cu")
		(net "M_D_CPU1_SA_DQ<25>")
	)
	(arc
		(start 79.537814 -240.756948)
		(mid 79.814881 -240.680677)
		(end 80.093566 -240.750852)
		(width 0.0889)
		(layer "In4.Cu")
		(net "M_D_CPU1_SA_DQ<25>")
	)
	(arc
		(start 82.357976 -240.756948)
		(mid 82.640932 -240.680771)
		(end 82.923888 -240.756948)
		(width 0.0889)
		(layer "In4.Cu")
		(net "M_D_CPU1_SA_DQ<25>")
	)
	(arc
		(start 83.863942 -240.756948)
		(mid 84.046193 -240.807298)
		(end 84.229702 -240.761774)
		(width 0.0889)
		(layer "In4.Cu")
		(net "M_D_CPU1_SA_DQ<25>")
	)
	(arc
		(start 90.817954 -240.756948)
		(mid 91.10091 -240.680771)
		(end 91.383866 -240.756948)
		(width 0.0889)
		(layer "In4.Cu")
		(net "M_D_CPU1_SA_DQ<25>")
	)
	(arc
		(start 89.512394 -240.761774)
		(mid 89.695902 -240.807268)
		(end 89.878154 -240.756948)
		(width 0.0889)
		(layer "In4.Cu")
		(net "M_D_CPU1_SA_DQ<25>")
	)
	(arc
		(start 79.17815 -240.76533)
		(mid 79.359058 -240.807352)
		(end 79.537814 -240.756948)
		(width 0.0889)
		(layer "In4.Cu")
		(net "M_D_CPU1_SA_DQ<25>")
	)
	(arc
		(start 88.563958 -240.756948)
		(mid 88.746209 -240.807298)
		(end 88.929718 -240.761774)
		(width 0.0889)
		(layer "In4.Cu")
		(net "M_D_CPU1_SA_DQ<25>")
	)
	(arc
		(start 87.998046 -240.756948)
		(mid 88.281002 -240.680771)
		(end 88.563958 -240.756948)
		(width 0.0889)
		(layer "In4.Cu")
		(net "M_D_CPU1_SA_DQ<25>")
	)
	(arc
		(start 90.444066 -240.756948)
		(mid 90.63101 -240.807203)
		(end 90.817954 -240.756948)
		(width 0.0889)
		(layer "In4.Cu")
		(net "M_D_CPU1_SA_DQ<25>")
	)
	(arc
		(start 91.383866 -240.756948)
		(mid 91.566117 -240.807298)
		(end 91.749626 -240.761774)
		(width 0.0889)
		(layer "In4.Cu")
		(net "M_D_CPU1_SA_DQ<25>")
	)
	(arc
		(start 78.41107 -240.807494)
		(mid 78.507881 -240.79457)
		(end 78.598014 -240.756948)
		(width 0.0889)
		(layer "In4.Cu")
		(net "M_D_CPU1_SA_DQ<25>")
	)
	(arc
		(start 83.29803 -240.756948)
		(mid 83.580986 -240.680771)
		(end 83.863942 -240.756948)
		(width 0.0889)
		(layer "In4.Cu")
		(net "M_D_CPU1_SA_DQ<25>")
	)
	(arc
		(start 85.178138 -240.756948)
		(mid 85.461094 -240.680771)
		(end 85.74405 -240.756948)
		(width 0.0889)
		(layer "In4.Cu")
		(net "M_D_CPU1_SA_DQ<25>")
	)
	(arc
		(start 78.598014 -240.756948)
		(mid 78.874827 -240.680805)
		(end 79.153258 -240.750852)
		(width 0.0889)
		(layer "In4.Cu")
		(net "M_D_CPU1_SA_DQ<25>")
	)
	(arc
		(start 81.052416 -240.761774)
		(mid 81.235924 -240.807268)
		(end 81.418176 -240.756948)
		(width 0.0889)
		(layer "In4.Cu")
		(net "M_D_CPU1_SA_DQ<25>")
	)
	(arc
		(start 80.10398 -240.756948)
		(mid 80.286231 -240.807298)
		(end 80.46974 -240.761774)
		(width 0.0889)
		(layer "In4.Cu")
		(net "M_D_CPU1_SA_DQ<25>")
	)
	(arc
		(start 91.758008 -240.756948)
		(mid 92.005604 -240.68177)
		(end 92.260674 -240.725198)
		(width 0.0889)
		(layer "In4.Cu")
		(net "M_D_CPU1_SA_DQ<25>")
	)
	(arc
		(start 81.418176 -240.756948)
		(mid 81.701132 -240.680771)
		(end 81.984088 -240.756948)
		(width 0.0889)
		(layer "In4.Cu")
		(net "M_D_CPU1_SA_DQ<25>")
	)
	(arc
		(start 87.057992 -240.756948)
		(mid 87.340948 -240.680771)
		(end 87.623904 -240.756948)
		(width 0.0889)
		(layer "In4.Cu")
		(net "M_D_CPU1_SA_DQ<25>")
	)
	(arc
		(start 86.118192 -240.756948)
		(mid 86.401148 -240.680771)
		(end 86.684104 -240.756948)
		(width 0.0889)
		(layer "In4.Cu")
		(net "M_D_CPU1_SA_DQ<25>")
	)
	(segment
		(start 91.568016 -239.8903)
		(end 91.10091 -239.624362)
		(width 0.10668)
		(layer "F.Cu")
		(net "M_D_CPU1_SA_DQ<24>")
	)
	(segment
		(start 58.803286 -225.810318)
		(end 60.077604 -225.810318)
		(width 0.14478)
		(layer "In4.Cu")
		(net "M_D_CPU1_SA_DQ<24>")
	)
	(segment
		(start 57.148984 -226.196906)
		(end 57.37733 -226.196906)
		(width 0.14478)
		(layer "In4.Cu")
		(net "M_D_CPU1_SA_DQ<24>")
	)
	(segment
		(start 86.57971 -239.951768)
		(end 86.588092 -239.946942)
		(width 0.0889)
		(layer "In4.Cu")
		(net "M_D_CPU1_SA_DQ<24>")
	)
	(segment
		(start 37.767006 -225.973386)
		(end 37.767006 -226.035616)
		(width 0.14478)
		(layer "In4.Cu")
		(net "M_D_CPU1_SA_DQ<24>")
	)
	(segment
		(start 79.634842 -239.946688)
		(end 79.654908 -239.958118)
		(width 0.0889)
		(layer "In4.Cu")
		(net "M_D_CPU1_SA_DQ<24>")
	)
	(segment
		(start 42.733214 -224.960434)
		(end 42.97807 -224.960434)
		(width 0.14478)
		(layer "In4.Cu")
		(net "M_D_CPU1_SA_DQ<24>")
	)
	(segment
		(start 53.23459 -224.960434)
		(end 54.084474 -225.810318)
		(width 0.14478)
		(layer "In4.Cu")
		(net "M_D_CPU1_SA_DQ<24>")
	)
	(segment
		(start 38.880034 -226.035616)
		(end 39.043102 -226.198684)
		(width 0.14478)
		(layer "In4.Cu")
		(net "M_D_CPU1_SA_DQ<24>")
	)
	(segment
		(start 37.220906 -225.810318)
		(end 37.603938 -225.810318)
		(width 0.14478)
		(layer "In4.Cu")
		(net "M_D_CPU1_SA_DQ<24>")
	)
	(segment
		(start 45.55871 -224.960434)
		(end 46.408594 -225.810318)
		(width 0.14478)
		(layer "In4.Cu")
		(net "M_D_CPU1_SA_DQ<24>")
	)
	(segment
		(start 56.825896 -225.810318)
		(end 56.98744 -225.971862)
		(width 0.14478)
		(layer "In4.Cu")
		(net "M_D_CPU1_SA_DQ<24>")
	)
	(segment
		(start 60.077604 -225.810318)
		(end 67.726306 -233.45902)
		(width 0.14478)
		(layer "In4.Cu")
		(net "M_D_CPU1_SA_DQ<24>")
	)
	(segment
		(start 58.090308 -226.035362)
		(end 58.251852 -226.196906)
		(width 0.14478)
		(layer "In4.Cu")
		(net "M_D_CPU1_SA_DQ<24>")
	)
	(segment
		(start 36.795964 -225.385376)
		(end 37.220906 -225.810318)
		(width 0.14478)
		(layer "In4.Cu")
		(net "M_D_CPU1_SA_DQ<24>")
	)
	(segment
		(start 77.072744 -238.741966)
		(end 78.201012 -239.870234)
		(width 0.0889)
		(layer "In4.Cu")
		(net "M_D_CPU1_SA_DQ<24>")
	)
	(segment
		(start 56.339994 -226.035616)
		(end 56.339994 -225.973386)
		(width 0.14478)
		(layer "In4.Cu")
		(net "M_D_CPU1_SA_DQ<24>")
	)
	(segment
		(start 43.534584 -225.345244)
		(end 43.697652 -225.182176)
		(width 0.14478)
		(layer "In4.Cu")
		(net "M_D_CPU1_SA_DQ<24>")
	)
	(segment
		(start 54.084474 -225.810318)
		(end 54.507384 -225.810318)
		(width 0.14478)
		(layer "In4.Cu")
		(net "M_D_CPU1_SA_DQ<24>")
	)
	(segment
		(start 87.154004 -239.946942)
		(end 87.162386 -239.951768)
		(width 0.0889)
		(layer "In4.Cu")
		(net "M_D_CPU1_SA_DQ<24>")
	)
	(segment
		(start 55.226966 -225.973386)
		(end 55.390034 -225.810318)
		(width 0.14478)
		(layer "In4.Cu")
		(net "M_D_CPU1_SA_DQ<24>")
	)
	(segment
		(start 38.32352 -225.698812)
		(end 38.486588 -225.535744)
		(width 0.14478)
		(layer "In4.Cu")
		(net "M_D_CPU1_SA_DQ<24>")
	)
	(segment
		(start 51.45532 -224.960434)
		(end 53.23459 -224.960434)
		(width 0.14478)
		(layer "In4.Cu")
		(net "M_D_CPU1_SA_DQ<24>")
	)
	(segment
		(start 38.716966 -225.535744)
		(end 38.880034 -225.698812)
		(width 0.14478)
		(layer "In4.Cu")
		(net "M_D_CPU1_SA_DQ<24>")
	)
	(segment
		(start 79.613252 -239.934242)
		(end 79.634842 -239.946688)
		(width 0.0889)
		(layer "In4.Cu")
		(net "M_D_CPU1_SA_DQ<24>")
	)
	(segment
		(start 54.670452 -226.035616)
		(end 54.83352 -226.198684)
		(width 0.14478)
		(layer "In4.Cu")
		(net "M_D_CPU1_SA_DQ<24>")
	)
	(segment
		(start 90.946986 -239.889792)
		(end 91.10091 -239.624362)
		(width 0.0889)
		(layer "In4.Cu")
		(net "M_D_CPU1_SA_DQ<24>")
	)
	(segment
		(start 49.063148 -225.810318)
		(end 49.40681 -225.810318)
		(width 0.14478)
		(layer "In4.Cu")
		(net "M_D_CPU1_SA_DQ<24>")
	)
	(segment
		(start 88.094058 -239.946942)
		(end 88.10244 -239.951768)
		(width 0.0889)
		(layer "In4.Cu")
		(net "M_D_CPU1_SA_DQ<24>")
	)
	(segment
		(start 58.641742 -225.971862)
		(end 58.803286 -225.810318)
		(width 0.14478)
		(layer "In4.Cu")
		(net "M_D_CPU1_SA_DQ<24>")
	)
	(segment
		(start 55.620412 -225.810318)
		(end 55.78348 -225.973386)
		(width 0.14478)
		(layer "In4.Cu")
		(net "M_D_CPU1_SA_DQ<24>")
	)
	(segment
		(start 83.394042 -239.946942)
		(end 83.402424 -239.951768)
		(width 0.0889)
		(layer "In4.Cu")
		(net "M_D_CPU1_SA_DQ<24>")
	)
	(segment
		(start 38.160452 -226.198684)
		(end 38.32352 -226.035616)
		(width 0.14478)
		(layer "In4.Cu")
		(net "M_D_CPU1_SA_DQ<24>")
	)
	(segment
		(start 82.453988 -239.946942)
		(end 82.46237 -239.951768)
		(width 0.0889)
		(layer "In4.Cu")
		(net "M_D_CPU1_SA_DQ<24>")
	)
	(segment
		(start 58.251852 -226.196906)
		(end 58.480198 -226.196906)
		(width 0.14478)
		(layer "In4.Cu")
		(net "M_D_CPU1_SA_DQ<24>")
	)
	(segment
		(start 48.506634 -226.198684)
		(end 48.737012 -226.198684)
		(width 0.14478)
		(layer "In4.Cu")
		(net "M_D_CPU1_SA_DQ<24>")
	)
	(segment
		(start 55.390034 -225.810318)
		(end 55.620412 -225.810318)
		(width 0.14478)
		(layer "In4.Cu")
		(net "M_D_CPU1_SA_DQ<24>")
	)
	(segment
		(start 48.90008 -226.035616)
		(end 48.90008 -225.973386)
		(width 0.14478)
		(layer "In4.Cu")
		(net "M_D_CPU1_SA_DQ<24>")
	)
	(segment
		(start 78.201012 -239.870234)
		(end 78.41107 -239.870234)
		(width 0.0889)
		(layer "In4.Cu")
		(net "M_D_CPU1_SA_DQ<24>")
	)
	(segment
		(start 58.480198 -226.196906)
		(end 58.641742 -226.035362)
		(width 0.14478)
		(layer "In4.Cu")
		(net "M_D_CPU1_SA_DQ<24>")
	)
	(segment
		(start 54.670452 -225.973386)
		(end 54.670452 -226.035616)
		(width 0.14478)
		(layer "In4.Cu")
		(net "M_D_CPU1_SA_DQ<24>")
	)
	(segment
		(start 50.898806 -225.350324)
		(end 51.129184 -225.350324)
		(width 0.14478)
		(layer "In4.Cu")
		(net "M_D_CPU1_SA_DQ<24>")
	)
	(segment
		(start 48.737012 -226.198684)
		(end 48.90008 -226.035616)
		(width 0.14478)
		(layer "In4.Cu")
		(net "M_D_CPU1_SA_DQ<24>")
	)
	(segment
		(start 40.901874 -225.973386)
		(end 40.901874 -226.030536)
		(width 0.14478)
		(layer "In4.Cu")
		(net "M_D_CPU1_SA_DQ<24>")
	)
	(segment
		(start 48.90008 -225.973386)
		(end 49.063148 -225.810318)
		(width 0.14478)
		(layer "In4.Cu")
		(net "M_D_CPU1_SA_DQ<24>")
	)
	(segment
		(start 48.343566 -226.035616)
		(end 48.506634 -226.198684)
		(width 0.14478)
		(layer "In4.Cu")
		(net "M_D_CPU1_SA_DQ<24>")
	)
	(segment
		(start 39.27348 -226.198684)
		(end 39.436548 -226.035616)
		(width 0.14478)
		(layer "In4.Cu")
		(net "M_D_CPU1_SA_DQ<24>")
	)
	(segment
		(start 57.928764 -225.810318)
		(end 58.090308 -225.971862)
		(width 0.14478)
		(layer "In4.Cu")
		(net "M_D_CPU1_SA_DQ<24>")
	)
	(segment
		(start 55.226966 -226.035616)
		(end 55.226966 -225.973386)
		(width 0.14478)
		(layer "In4.Cu")
		(net "M_D_CPU1_SA_DQ<24>")
	)
	(segment
		(start 39.599616 -225.810318)
		(end 40.738806 -225.810318)
		(width 0.14478)
		(layer "In4.Cu")
		(net "M_D_CPU1_SA_DQ<24>")
	)
	(segment
		(start 51.129184 -225.350324)
		(end 51.292252 -225.187256)
		(width 0.14478)
		(layer "In4.Cu")
		(net "M_D_CPU1_SA_DQ<24>")
	)
	(segment
		(start 56.98744 -225.971862)
		(end 56.98744 -226.035362)
		(width 0.14478)
		(layer "In4.Cu")
		(net "M_D_CPU1_SA_DQ<24>")
	)
	(segment
		(start 48.180498 -225.810318)
		(end 48.343566 -225.973386)
		(width 0.14478)
		(layer "In4.Cu")
		(net "M_D_CPU1_SA_DQ<24>")
	)
	(segment
		(start 75.94981 -238.418878)
		(end 76.335382 -238.418878)
		(width 0.0889)
		(layer "In4.Cu")
		(net "M_D_CPU1_SA_DQ<24>")
	)
	(segment
		(start 40.901874 -226.030536)
		(end 41.064942 -226.193604)
		(width 0.14478)
		(layer "In4.Cu")
		(net "M_D_CPU1_SA_DQ<24>")
	)
	(segment
		(start 50.256694 -224.960434)
		(end 50.57267 -224.960434)
		(width 0.14478)
		(layer "In4.Cu")
		(net "M_D_CPU1_SA_DQ<24>")
	)
	(segment
		(start 57.37733 -226.196906)
		(end 57.538874 -226.035362)
		(width 0.14478)
		(layer "In4.Cu")
		(net "M_D_CPU1_SA_DQ<24>")
	)
	(segment
		(start 56.503062 -225.810318)
		(end 56.825896 -225.810318)
		(width 0.14478)
		(layer "In4.Cu")
		(net "M_D_CPU1_SA_DQ<24>")
	)
	(segment
		(start 71.4375 -238.418878)
		(end 75.94981 -238.418878)
		(width 0.14478)
		(layer "In4.Cu")
		(net "M_D_CPU1_SA_DQ<24>")
	)
	(segment
		(start 51.292252 -225.123502)
		(end 51.45532 -224.960434)
		(width 0.14478)
		(layer "In4.Cu")
		(net "M_D_CPU1_SA_DQ<24>")
	)
	(segment
		(start 43.697652 -225.123502)
		(end 43.86072 -224.960434)
		(width 0.14478)
		(layer "In4.Cu")
		(net "M_D_CPU1_SA_DQ<24>")
	)
	(segment
		(start 43.141138 -225.123502)
		(end 43.141138 -225.182176)
		(width 0.14478)
		(layer "In4.Cu")
		(net "M_D_CPU1_SA_DQ<24>")
	)
	(segment
		(start 37.603938 -225.810318)
		(end 37.767006 -225.973386)
		(width 0.14478)
		(layer "In4.Cu")
		(net "M_D_CPU1_SA_DQ<24>")
	)
	(segment
		(start 38.486588 -225.535744)
		(end 38.716966 -225.535744)
		(width 0.14478)
		(layer "In4.Cu")
		(net "M_D_CPU1_SA_DQ<24>")
	)
	(segment
		(start 41.29532 -226.193604)
		(end 41.458388 -226.030536)
		(width 0.14478)
		(layer "In4.Cu")
		(net "M_D_CPU1_SA_DQ<24>")
	)
	(segment
		(start 43.697652 -225.182176)
		(end 43.697652 -225.123502)
		(width 0.14478)
		(layer "In4.Cu")
		(net "M_D_CPU1_SA_DQ<24>")
	)
	(segment
		(start 79.051658 -239.957864)
		(end 79.070454 -239.946942)
		(width 0.0889)
		(layer "In4.Cu")
		(net "M_D_CPU1_SA_DQ<24>")
	)
	(segment
		(start 56.98744 -226.035362)
		(end 57.148984 -226.196906)
		(width 0.14478)
		(layer "In4.Cu")
		(net "M_D_CPU1_SA_DQ<24>")
	)
	(segment
		(start 56.339994 -225.973386)
		(end 56.503062 -225.810318)
		(width 0.14478)
		(layer "In4.Cu")
		(net "M_D_CPU1_SA_DQ<24>")
	)
	(segment
		(start 37.930074 -226.198684)
		(end 38.160452 -226.198684)
		(width 0.14478)
		(layer "In4.Cu")
		(net "M_D_CPU1_SA_DQ<24>")
	)
	(segment
		(start 43.86072 -224.960434)
		(end 45.55871 -224.960434)
		(width 0.14478)
		(layer "In4.Cu")
		(net "M_D_CPU1_SA_DQ<24>")
	)
	(segment
		(start 41.621456 -225.810318)
		(end 41.88333 -225.810318)
		(width 0.14478)
		(layer "In4.Cu")
		(net "M_D_CPU1_SA_DQ<24>")
	)
	(segment
		(start 76.335382 -238.418878)
		(end 76.65847 -238.741966)
		(width 0.0889)
		(layer "In4.Cu")
		(net "M_D_CPU1_SA_DQ<24>")
	)
	(segment
		(start 85.639656 -239.951768)
		(end 85.648038 -239.946942)
		(width 0.0889)
		(layer "In4.Cu")
		(net "M_D_CPU1_SA_DQ<24>")
	)
	(segment
		(start 67.726306 -234.707684)
		(end 71.4375 -238.418878)
		(width 0.14478)
		(layer "In4.Cu")
		(net "M_D_CPU1_SA_DQ<24>")
	)
	(segment
		(start 41.458388 -225.973386)
		(end 41.621456 -225.810318)
		(width 0.14478)
		(layer "In4.Cu")
		(net "M_D_CPU1_SA_DQ<24>")
	)
	(segment
		(start 38.32352 -226.035616)
		(end 38.32352 -225.698812)
		(width 0.14478)
		(layer "In4.Cu")
		(net "M_D_CPU1_SA_DQ<24>")
	)
	(segment
		(start 43.141138 -225.182176)
		(end 43.304206 -225.345244)
		(width 0.14478)
		(layer "In4.Cu")
		(net "M_D_CPU1_SA_DQ<24>")
	)
	(segment
		(start 55.78348 -225.973386)
		(end 55.78348 -226.035616)
		(width 0.14478)
		(layer "In4.Cu")
		(net "M_D_CPU1_SA_DQ<24>")
	)
	(segment
		(start 55.78348 -226.035616)
		(end 55.946548 -226.198684)
		(width 0.14478)
		(layer "In4.Cu")
		(net "M_D_CPU1_SA_DQ<24>")
	)
	(segment
		(start 54.507384 -225.810318)
		(end 54.670452 -225.973386)
		(width 0.14478)
		(layer "In4.Cu")
		(net "M_D_CPU1_SA_DQ<24>")
	)
	(segment
		(start 39.043102 -226.198684)
		(end 39.27348 -226.198684)
		(width 0.14478)
		(layer "In4.Cu")
		(net "M_D_CPU1_SA_DQ<24>")
	)
	(segment
		(start 41.458388 -226.030536)
		(end 41.458388 -225.973386)
		(width 0.14478)
		(layer "In4.Cu")
		(net "M_D_CPU1_SA_DQ<24>")
	)
	(segment
		(start 54.83352 -226.198684)
		(end 55.063898 -226.198684)
		(width 0.14478)
		(layer "In4.Cu")
		(net "M_D_CPU1_SA_DQ<24>")
	)
	(segment
		(start 42.97807 -224.960434)
		(end 43.141138 -225.123502)
		(width 0.14478)
		(layer "In4.Cu")
		(net "M_D_CPU1_SA_DQ<24>")
	)
	(segment
		(start 51.292252 -225.187256)
		(end 51.292252 -225.123502)
		(width 0.14478)
		(layer "In4.Cu")
		(net "M_D_CPU1_SA_DQ<24>")
	)
	(segment
		(start 48.343566 -225.973386)
		(end 48.343566 -226.035616)
		(width 0.14478)
		(layer "In4.Cu")
		(net "M_D_CPU1_SA_DQ<24>")
	)
	(segment
		(start 43.304206 -225.345244)
		(end 43.534584 -225.345244)
		(width 0.14478)
		(layer "In4.Cu")
		(net "M_D_CPU1_SA_DQ<24>")
	)
	(segment
		(start 39.436548 -226.035616)
		(end 39.436548 -225.973386)
		(width 0.14478)
		(layer "In4.Cu")
		(net "M_D_CPU1_SA_DQ<24>")
	)
	(segment
		(start 57.538874 -225.971862)
		(end 57.700418 -225.810318)
		(width 0.14478)
		(layer "In4.Cu")
		(net "M_D_CPU1_SA_DQ<24>")
	)
	(segment
		(start 39.436548 -225.973386)
		(end 39.599616 -225.810318)
		(width 0.14478)
		(layer "In4.Cu")
		(net "M_D_CPU1_SA_DQ<24>")
	)
	(segment
		(start 46.408594 -225.810318)
		(end 48.180498 -225.810318)
		(width 0.14478)
		(layer "In4.Cu")
		(net "M_D_CPU1_SA_DQ<24>")
	)
	(segment
		(start 57.700418 -225.810318)
		(end 57.928764 -225.810318)
		(width 0.14478)
		(layer "In4.Cu")
		(net "M_D_CPU1_SA_DQ<24>")
	)
	(segment
		(start 37.767006 -226.035616)
		(end 37.930074 -226.198684)
		(width 0.14478)
		(layer "In4.Cu")
		(net "M_D_CPU1_SA_DQ<24>")
	)
	(segment
		(start 55.063898 -226.198684)
		(end 55.226966 -226.035616)
		(width 0.14478)
		(layer "In4.Cu")
		(net "M_D_CPU1_SA_DQ<24>")
	)
	(segment
		(start 76.65847 -238.741966)
		(end 77.072744 -238.741966)
		(width 0.0889)
		(layer "In4.Cu")
		(net "M_D_CPU1_SA_DQ<24>")
	)
	(segment
		(start 50.57267 -224.960434)
		(end 50.735738 -225.123502)
		(width 0.14478)
		(layer "In4.Cu")
		(net "M_D_CPU1_SA_DQ<24>")
	)
	(segment
		(start 58.090308 -225.971862)
		(end 58.090308 -226.035362)
		(width 0.14478)
		(layer "In4.Cu")
		(net "M_D_CPU1_SA_DQ<24>")
	)
	(segment
		(start 90.850974 -239.915192)
		(end 90.946986 -239.889792)
		(width 0.0889)
		(layer "In4.Cu")
		(net "M_D_CPU1_SA_DQ<24>")
	)
	(segment
		(start 58.641742 -226.035362)
		(end 58.641742 -225.971862)
		(width 0.14478)
		(layer "In4.Cu")
		(net "M_D_CPU1_SA_DQ<24>")
	)
	(segment
		(start 41.064942 -226.193604)
		(end 41.29532 -226.193604)
		(width 0.14478)
		(layer "In4.Cu")
		(net "M_D_CPU1_SA_DQ<24>")
	)
	(segment
		(start 50.735738 -225.187256)
		(end 50.898806 -225.350324)
		(width 0.14478)
		(layer "In4.Cu")
		(net "M_D_CPU1_SA_DQ<24>")
	)
	(segment
		(start 90.339672 -239.951768)
		(end 90.348054 -239.946942)
		(width 0.0889)
		(layer "In4.Cu")
		(net "M_D_CPU1_SA_DQ<24>")
	)
	(segment
		(start 41.88333 -225.810318)
		(end 42.733214 -224.960434)
		(width 0.14478)
		(layer "In4.Cu")
		(net "M_D_CPU1_SA_DQ<24>")
	)
	(segment
		(start 57.538874 -226.035362)
		(end 57.538874 -225.971862)
		(width 0.14478)
		(layer "In4.Cu")
		(net "M_D_CPU1_SA_DQ<24>")
	)
	(segment
		(start 56.176926 -226.198684)
		(end 56.339994 -226.035616)
		(width 0.14478)
		(layer "In4.Cu")
		(net "M_D_CPU1_SA_DQ<24>")
	)
	(segment
		(start 50.735738 -225.123502)
		(end 50.735738 -225.187256)
		(width 0.14478)
		(layer "In4.Cu")
		(net "M_D_CPU1_SA_DQ<24>")
	)
	(segment
		(start 81.879694 -239.951768)
		(end 81.888076 -239.946942)
		(width 0.0889)
		(layer "In4.Cu")
		(net "M_D_CPU1_SA_DQ<24>")
	)
	(segment
		(start 38.880034 -225.698812)
		(end 38.880034 -226.035616)
		(width 0.14478)
		(layer "In4.Cu")
		(net "M_D_CPU1_SA_DQ<24>")
	)
	(segment
		(start 55.946548 -226.198684)
		(end 56.176926 -226.198684)
		(width 0.14478)
		(layer "In4.Cu")
		(net "M_D_CPU1_SA_DQ<24>")
	)
	(segment
		(start 67.726306 -233.45902)
		(end 67.726306 -234.707684)
		(width 0.14478)
		(layer "In4.Cu")
		(net "M_D_CPU1_SA_DQ<24>")
	)
	(segment
		(start 49.40681 -225.810318)
		(end 50.256694 -224.960434)
		(width 0.14478)
		(layer "In4.Cu")
		(net "M_D_CPU1_SA_DQ<24>")
	)
	(segment
		(start 40.738806 -225.810318)
		(end 40.901874 -225.973386)
		(width 0.14478)
		(layer "In4.Cu")
		(net "M_D_CPU1_SA_DQ<24>")
	)
	(arc
		(start 80.008222 -239.946942)
		(mid 80.291178 -239.870765)
		(end 80.574134 -239.946942)
		(width 0.0889)
		(layer "In4.Cu")
		(net "M_D_CPU1_SA_DQ<24>")
	)
	(arc
		(start 78.41107 -239.870234)
		(mid 78.558279 -239.889711)
		(end 78.695296 -239.946942)
		(width 0.0889)
		(layer "In4.Cu")
		(net "M_D_CPU1_SA_DQ<24>")
	)
	(arc
		(start 79.070454 -239.946942)
		(mid 79.340223 -239.870919)
		(end 79.613252 -239.934242)
		(width 0.0889)
		(layer "In4.Cu")
		(net "M_D_CPU1_SA_DQ<24>")
	)
	(arc
		(start 78.695296 -239.946942)
		(mid 78.872087 -239.997661)
		(end 79.051658 -239.957864)
		(width 0.0889)
		(layer "In4.Cu")
		(net "M_D_CPU1_SA_DQ<24>")
	)
	(arc
		(start 83.768184 -239.946942)
		(mid 84.05114 -239.870765)
		(end 84.334096 -239.946942)
		(width 0.0889)
		(layer "In4.Cu")
		(net "M_D_CPU1_SA_DQ<24>")
	)
	(arc
		(start 83.402424 -239.951768)
		(mid 83.585932 -239.997262)
		(end 83.768184 -239.946942)
		(width 0.0889)
		(layer "In4.Cu")
		(net "M_D_CPU1_SA_DQ<24>")
	)
	(arc
		(start 85.648038 -239.946942)
		(mid 85.930994 -239.870765)
		(end 86.21395 -239.946942)
		(width 0.0889)
		(layer "In4.Cu")
		(net "M_D_CPU1_SA_DQ<24>")
	)
	(arc
		(start 85.273896 -239.946942)
		(mid 85.456147 -239.997292)
		(end 85.639656 -239.951768)
		(width 0.0889)
		(layer "In4.Cu")
		(net "M_D_CPU1_SA_DQ<24>")
	)
	(arc
		(start 89.973912 -239.946942)
		(mid 90.156163 -239.997292)
		(end 90.339672 -239.951768)
		(width 0.0889)
		(layer "In4.Cu")
		(net "M_D_CPU1_SA_DQ<24>")
	)
	(arc
		(start 89.408 -239.946942)
		(mid 89.690956 -239.870765)
		(end 89.973912 -239.946942)
		(width 0.0889)
		(layer "In4.Cu")
		(net "M_D_CPU1_SA_DQ<24>")
	)
	(arc
		(start 82.82813 -239.946942)
		(mid 83.111086 -239.870765)
		(end 83.394042 -239.946942)
		(width 0.0889)
		(layer "In4.Cu")
		(net "M_D_CPU1_SA_DQ<24>")
	)
	(arc
		(start 86.21395 -239.946942)
		(mid 86.396201 -239.997292)
		(end 86.57971 -239.951768)
		(width 0.0889)
		(layer "In4.Cu")
		(net "M_D_CPU1_SA_DQ<24>")
	)
	(arc
		(start 88.10244 -239.951768)
		(mid 88.285948 -239.997262)
		(end 88.4682 -239.946942)
		(width 0.0889)
		(layer "In4.Cu")
		(net "M_D_CPU1_SA_DQ<24>")
	)
	(arc
		(start 89.034112 -239.946942)
		(mid 89.221056 -239.997197)
		(end 89.408 -239.946942)
		(width 0.0889)
		(layer "In4.Cu")
		(net "M_D_CPU1_SA_DQ<24>")
	)
	(arc
		(start 88.4682 -239.946942)
		(mid 88.751156 -239.870765)
		(end 89.034112 -239.946942)
		(width 0.0889)
		(layer "In4.Cu")
		(net "M_D_CPU1_SA_DQ<24>")
	)
	(arc
		(start 90.348054 -239.946942)
		(mid 90.595767 -239.871722)
		(end 90.850974 -239.915192)
		(width 0.0889)
		(layer "In4.Cu")
		(net "M_D_CPU1_SA_DQ<24>")
	)
	(arc
		(start 86.588092 -239.946942)
		(mid 86.871048 -239.870765)
		(end 87.154004 -239.946942)
		(width 0.0889)
		(layer "In4.Cu")
		(net "M_D_CPU1_SA_DQ<24>")
	)
	(arc
		(start 84.707984 -239.946942)
		(mid 84.99094 -239.870765)
		(end 85.273896 -239.946942)
		(width 0.0889)
		(layer "In4.Cu")
		(net "M_D_CPU1_SA_DQ<24>")
	)
	(arc
		(start 79.654908 -239.958118)
		(mid 79.832986 -239.997102)
		(end 80.008222 -239.946942)
		(width 0.0889)
		(layer "In4.Cu")
		(net "M_D_CPU1_SA_DQ<24>")
	)
	(arc
		(start 87.528146 -239.946942)
		(mid 87.811102 -239.870765)
		(end 88.094058 -239.946942)
		(width 0.0889)
		(layer "In4.Cu")
		(net "M_D_CPU1_SA_DQ<24>")
	)
	(arc
		(start 81.513934 -239.946942)
		(mid 81.696185 -239.997292)
		(end 81.879694 -239.951768)
		(width 0.0889)
		(layer "In4.Cu")
		(net "M_D_CPU1_SA_DQ<24>")
	)
	(arc
		(start 80.574134 -239.946942)
		(mid 80.761078 -239.997197)
		(end 80.948022 -239.946942)
		(width 0.0889)
		(layer "In4.Cu")
		(net "M_D_CPU1_SA_DQ<24>")
	)
	(arc
		(start 84.334096 -239.946942)
		(mid 84.52104 -239.997197)
		(end 84.707984 -239.946942)
		(width 0.0889)
		(layer "In4.Cu")
		(net "M_D_CPU1_SA_DQ<24>")
	)
	(arc
		(start 80.948022 -239.946942)
		(mid 81.230978 -239.870765)
		(end 81.513934 -239.946942)
		(width 0.0889)
		(layer "In4.Cu")
		(net "M_D_CPU1_SA_DQ<24>")
	)
	(arc
		(start 81.888076 -239.946942)
		(mid 82.171032 -239.870765)
		(end 82.453988 -239.946942)
		(width 0.0889)
		(layer "In4.Cu")
		(net "M_D_CPU1_SA_DQ<24>")
	)
	(arc
		(start 87.162386 -239.951768)
		(mid 87.345894 -239.997262)
		(end 87.528146 -239.946942)
		(width 0.0889)
		(layer "In4.Cu")
		(net "M_D_CPU1_SA_DQ<24>")
	)
	(arc
		(start 82.46237 -239.951768)
		(mid 82.645878 -239.997262)
		(end 82.82813 -239.946942)
		(width 0.0889)
		(layer "In4.Cu")
		(net "M_D_CPU1_SA_DQ<24>")
	)
	(segment
		(start 92.507816 -239.8903)
		(end 92.040964 -239.624362)
		(width 0.10668)
		(layer "F.Cu")
		(net "M_D_CPU1_SA_DQ<23>")
	)
	(segment
		(start 83.402424 -239.296956)
		(end 83.394042 -239.301782)
		(width 0.0889)
		(layer "In4.Cu")
		(net "M_D_CPU1_SA_DQ<23>")
	)
	(segment
		(start 75.84948 -237.959138)
		(end 71.638922 -237.959138)
		(width 0.14478)
		(layer "In4.Cu")
		(net "M_D_CPU1_SA_DQ<23>")
	)
	(segment
		(start 53.256434 -224.110296)
		(end 50.222404 -224.110296)
		(width 0.14478)
		(layer "In4.Cu")
		(net "M_D_CPU1_SA_DQ<23>")
	)
	(segment
		(start 33.859216 -224.960434)
		(end 33.121092 -224.960434)
		(width 0.14478)
		(layer "In4.Cu")
		(net "M_D_CPU1_SA_DQ<23>")
	)
	(segment
		(start 50.222404 -224.110296)
		(end 49.372266 -224.960434)
		(width 0.14478)
		(layer "In4.Cu")
		(net "M_D_CPU1_SA_DQ<23>")
	)
	(segment
		(start 76.952094 -237.862618)
		(end 76.28001 -237.862618)
		(width 0.0889)
		(layer "In4.Cu")
		(net "M_D_CPU1_SA_DQ<23>")
	)
	(segment
		(start 59.849004 -224.960434)
		(end 54.106572 -224.960434)
		(width 0.14478)
		(layer "In4.Cu")
		(net "M_D_CPU1_SA_DQ<23>")
	)
	(segment
		(start 79.65694 -239.28959)
		(end 79.635096 -239.302036)
		(width 0.0889)
		(layer "In4.Cu")
		(net "M_D_CPU1_SA_DQ<23>")
	)
	(segment
		(start 54.106572 -224.960434)
		(end 53.256434 -224.110296)
		(width 0.14478)
		(layer "In4.Cu")
		(net "M_D_CPU1_SA_DQ<23>")
	)
	(segment
		(start 42.73423 -224.110296)
		(end 41.884092 -224.960434)
		(width 0.14478)
		(layer "In4.Cu")
		(net "M_D_CPU1_SA_DQ<23>")
	)
	(segment
		(start 34.022284 -224.314512)
		(end 34.022284 -224.797366)
		(width 0.14478)
		(layer "In4.Cu")
		(net "M_D_CPU1_SA_DQ<23>")
	)
	(segment
		(start 49.372266 -224.960434)
		(end 46.417738 -224.960434)
		(width 0.14478)
		(layer "In4.Cu")
		(net "M_D_CPU1_SA_DQ<23>")
	)
	(segment
		(start 86.588092 -239.301782)
		(end 86.57971 -239.296956)
		(width 0.0889)
		(layer "In4.Cu")
		(net "M_D_CPU1_SA_DQ<23>")
	)
	(segment
		(start 81.888076 -239.301782)
		(end 81.879694 -239.296956)
		(width 0.0889)
		(layer "In4.Cu")
		(net "M_D_CPU1_SA_DQ<23>")
	)
	(segment
		(start 34.578798 -224.314512)
		(end 34.41573 -224.151444)
		(width 0.14478)
		(layer "In4.Cu")
		(net "M_D_CPU1_SA_DQ<23>")
	)
	(segment
		(start 68.183506 -233.294936)
		(end 59.849004 -224.960434)
		(width 0.14478)
		(layer "In4.Cu")
		(net "M_D_CPU1_SA_DQ<23>")
	)
	(segment
		(start 45.5676 -224.110296)
		(end 42.73423 -224.110296)
		(width 0.14478)
		(layer "In4.Cu")
		(net "M_D_CPU1_SA_DQ<23>")
	)
	(segment
		(start 34.022284 -224.797366)
		(end 33.859216 -224.960434)
		(width 0.14478)
		(layer "In4.Cu")
		(net "M_D_CPU1_SA_DQ<23>")
	)
	(segment
		(start 33.121092 -224.960434)
		(end 32.695896 -224.535238)
		(width 0.14478)
		(layer "In4.Cu")
		(net "M_D_CPU1_SA_DQ<23>")
	)
	(segment
		(start 91.862402 -239.296956)
		(end 91.85402 -239.301782)
		(width 0.0889)
		(layer "In4.Cu")
		(net "M_D_CPU1_SA_DQ<23>")
	)
	(segment
		(start 88.10244 -239.296956)
		(end 88.094058 -239.301782)
		(width 0.0889)
		(layer "In4.Cu")
		(net "M_D_CPU1_SA_DQ<23>")
	)
	(segment
		(start 87.162386 -239.296956)
		(end 87.154004 -239.301782)
		(width 0.0889)
		(layer "In4.Cu")
		(net "M_D_CPU1_SA_DQ<23>")
	)
	(segment
		(start 34.185352 -224.151444)
		(end 34.022284 -224.314512)
		(width 0.14478)
		(layer "In4.Cu")
		(net "M_D_CPU1_SA_DQ<23>")
	)
	(segment
		(start 92.195142 -239.358932)
		(end 92.17279 -239.27562)
		(width 0.0889)
		(layer "In4.Cu")
		(net "M_D_CPU1_SA_DQ<23>")
	)
	(segment
		(start 71.638922 -237.959138)
		(end 68.183506 -234.503722)
		(width 0.14478)
		(layer "In4.Cu")
		(net "M_D_CPU1_SA_DQ<23>")
	)
	(segment
		(start 34.41573 -224.151444)
		(end 34.185352 -224.151444)
		(width 0.14478)
		(layer "In4.Cu")
		(net "M_D_CPU1_SA_DQ<23>")
	)
	(segment
		(start 85.648038 -239.301782)
		(end 85.639656 -239.296956)
		(width 0.0889)
		(layer "In4.Cu")
		(net "M_D_CPU1_SA_DQ<23>")
	)
	(segment
		(start 68.183506 -234.503722)
		(end 68.183506 -233.294936)
		(width 0.14478)
		(layer "In4.Cu")
		(net "M_D_CPU1_SA_DQ<23>")
	)
	(segment
		(start 76.18349 -237.959138)
		(end 75.84948 -237.959138)
		(width 0.0889)
		(layer "In4.Cu")
		(net "M_D_CPU1_SA_DQ<23>")
	)
	(segment
		(start 79.635096 -239.302036)
		(end 79.61122 -239.316006)
		(width 0.0889)
		(layer "In4.Cu")
		(net "M_D_CPU1_SA_DQ<23>")
	)
	(segment
		(start 77.76591 -238.747046)
		(end 77.76591 -238.676434)
		(width 0.0889)
		(layer "In4.Cu")
		(net "M_D_CPU1_SA_DQ<23>")
	)
	(segment
		(start 34.741866 -224.960434)
		(end 34.578798 -224.797366)
		(width 0.14478)
		(layer "In4.Cu")
		(net "M_D_CPU1_SA_DQ<23>")
	)
	(segment
		(start 77.76591 -238.676434)
		(end 76.952094 -237.862618)
		(width 0.0889)
		(layer "In4.Cu")
		(net "M_D_CPU1_SA_DQ<23>")
	)
	(segment
		(start 82.46237 -239.296956)
		(end 82.453988 -239.301782)
		(width 0.0889)
		(layer "In4.Cu")
		(net "M_D_CPU1_SA_DQ<23>")
	)
	(segment
		(start 78.41107 -239.378744)
		(end 78.397608 -239.378744)
		(width 0.0889)
		(layer "In4.Cu")
		(net "M_D_CPU1_SA_DQ<23>")
	)
	(segment
		(start 34.578798 -224.797366)
		(end 34.578798 -224.314512)
		(width 0.14478)
		(layer "In4.Cu")
		(net "M_D_CPU1_SA_DQ<23>")
	)
	(segment
		(start 41.884092 -224.960434)
		(end 34.741866 -224.960434)
		(width 0.14478)
		(layer "In4.Cu")
		(net "M_D_CPU1_SA_DQ<23>")
	)
	(segment
		(start 90.348054 -239.301782)
		(end 90.339672 -239.296956)
		(width 0.0889)
		(layer "In4.Cu")
		(net "M_D_CPU1_SA_DQ<23>")
	)
	(segment
		(start 92.040964 -239.624362)
		(end 92.195142 -239.358932)
		(width 0.0889)
		(layer "In4.Cu")
		(net "M_D_CPU1_SA_DQ<23>")
	)
	(segment
		(start 90.922348 -239.296956)
		(end 90.913966 -239.301782)
		(width 0.0889)
		(layer "In4.Cu")
		(net "M_D_CPU1_SA_DQ<23>")
	)
	(segment
		(start 79.070962 -239.301782)
		(end 79.052166 -239.29086)
		(width 0.0889)
		(layer "In4.Cu")
		(net "M_D_CPU1_SA_DQ<23>")
	)
	(segment
		(start 76.28001 -237.862618)
		(end 76.18349 -237.959138)
		(width 0.0889)
		(layer "In4.Cu")
		(net "M_D_CPU1_SA_DQ<23>")
	)
	(segment
		(start 46.417738 -224.960434)
		(end 45.5676 -224.110296)
		(width 0.14478)
		(layer "In4.Cu")
		(net "M_D_CPU1_SA_DQ<23>")
	)
	(arc
		(start 89.034112 -239.301782)
		(mid 88.751156 -239.377959)
		(end 88.4682 -239.301782)
		(width 0.0889)
		(layer "In4.Cu")
		(net "M_D_CPU1_SA_DQ<23>")
	)
	(arc
		(start 90.339672 -239.296956)
		(mid 90.156164 -239.251462)
		(end 89.973912 -239.301782)
		(width 0.0889)
		(layer "In4.Cu")
		(net "M_D_CPU1_SA_DQ<23>")
	)
	(arc
		(start 85.639656 -239.296956)
		(mid 85.456148 -239.251462)
		(end 85.273896 -239.301782)
		(width 0.0889)
		(layer "In4.Cu")
		(net "M_D_CPU1_SA_DQ<23>")
	)
	(arc
		(start 80.008222 -239.301782)
		(mid 79.834118 -239.251748)
		(end 79.65694 -239.28959)
		(width 0.0889)
		(layer "In4.Cu")
		(net "M_D_CPU1_SA_DQ<23>")
	)
	(arc
		(start 86.57971 -239.296956)
		(mid 86.396202 -239.251462)
		(end 86.21395 -239.301782)
		(width 0.0889)
		(layer "In4.Cu")
		(net "M_D_CPU1_SA_DQ<23>")
	)
	(arc
		(start 80.574134 -239.301782)
		(mid 80.291178 -239.377959)
		(end 80.008222 -239.301782)
		(width 0.0889)
		(layer "In4.Cu")
		(net "M_D_CPU1_SA_DQ<23>")
	)
	(arc
		(start 78.695804 -239.301782)
		(mid 78.558552 -239.359183)
		(end 78.41107 -239.378744)
		(width 0.0889)
		(layer "In4.Cu")
		(net "M_D_CPU1_SA_DQ<23>")
	)
	(arc
		(start 82.453988 -239.301782)
		(mid 82.171032 -239.377959)
		(end 81.888076 -239.301782)
		(width 0.0889)
		(layer "In4.Cu")
		(net "M_D_CPU1_SA_DQ<23>")
	)
	(arc
		(start 90.913966 -239.301782)
		(mid 90.63101 -239.377959)
		(end 90.348054 -239.301782)
		(width 0.0889)
		(layer "In4.Cu")
		(net "M_D_CPU1_SA_DQ<23>")
	)
	(arc
		(start 84.334096 -239.301782)
		(mid 84.05114 -239.377959)
		(end 83.768184 -239.301782)
		(width 0.0889)
		(layer "In4.Cu")
		(net "M_D_CPU1_SA_DQ<23>")
	)
	(arc
		(start 79.61122 -239.316006)
		(mid 79.339283 -239.377832)
		(end 79.070962 -239.301782)
		(width 0.0889)
		(layer "In4.Cu")
		(net "M_D_CPU1_SA_DQ<23>")
	)
	(arc
		(start 83.394042 -239.301782)
		(mid 83.111086 -239.377959)
		(end 82.82813 -239.301782)
		(width 0.0889)
		(layer "In4.Cu")
		(net "M_D_CPU1_SA_DQ<23>")
	)
	(arc
		(start 81.879694 -239.296956)
		(mid 81.696186 -239.251462)
		(end 81.513934 -239.301782)
		(width 0.0889)
		(layer "In4.Cu")
		(net "M_D_CPU1_SA_DQ<23>")
	)
	(arc
		(start 88.094058 -239.301782)
		(mid 87.811102 -239.377959)
		(end 87.528146 -239.301782)
		(width 0.0889)
		(layer "In4.Cu")
		(net "M_D_CPU1_SA_DQ<23>")
	)
	(arc
		(start 87.154004 -239.301782)
		(mid 86.871048 -239.377959)
		(end 86.588092 -239.301782)
		(width 0.0889)
		(layer "In4.Cu")
		(net "M_D_CPU1_SA_DQ<23>")
	)
	(arc
		(start 80.948022 -239.301782)
		(mid 80.761078 -239.251527)
		(end 80.574134 -239.301782)
		(width 0.0889)
		(layer "In4.Cu")
		(net "M_D_CPU1_SA_DQ<23>")
	)
	(arc
		(start 87.528146 -239.301782)
		(mid 87.345895 -239.251432)
		(end 87.162386 -239.296956)
		(width 0.0889)
		(layer "In4.Cu")
		(net "M_D_CPU1_SA_DQ<23>")
	)
	(arc
		(start 83.768184 -239.301782)
		(mid 83.585933 -239.251432)
		(end 83.402424 -239.296956)
		(width 0.0889)
		(layer "In4.Cu")
		(net "M_D_CPU1_SA_DQ<23>")
	)
	(arc
		(start 85.273896 -239.301782)
		(mid 84.99094 -239.377959)
		(end 84.707984 -239.301782)
		(width 0.0889)
		(layer "In4.Cu")
		(net "M_D_CPU1_SA_DQ<23>")
	)
	(arc
		(start 92.17279 -239.27562)
		(mid 92.01528 -239.252422)
		(end 91.862402 -239.296956)
		(width 0.0889)
		(layer "In4.Cu")
		(net "M_D_CPU1_SA_DQ<23>")
	)
	(arc
		(start 86.21395 -239.301782)
		(mid 85.930994 -239.377959)
		(end 85.648038 -239.301782)
		(width 0.0889)
		(layer "In4.Cu")
		(net "M_D_CPU1_SA_DQ<23>")
	)
	(arc
		(start 89.408 -239.301782)
		(mid 89.221056 -239.251527)
		(end 89.034112 -239.301782)
		(width 0.0889)
		(layer "In4.Cu")
		(net "M_D_CPU1_SA_DQ<23>")
	)
	(arc
		(start 78.397608 -239.378744)
		(mid 77.95093 -239.193724)
		(end 77.76591 -238.747046)
		(width 0.0889)
		(layer "In4.Cu")
		(net "M_D_CPU1_SA_DQ<23>")
	)
	(arc
		(start 84.707984 -239.301782)
		(mid 84.52104 -239.251527)
		(end 84.334096 -239.301782)
		(width 0.0889)
		(layer "In4.Cu")
		(net "M_D_CPU1_SA_DQ<23>")
	)
	(arc
		(start 81.513934 -239.301782)
		(mid 81.230978 -239.377959)
		(end 80.948022 -239.301782)
		(width 0.0889)
		(layer "In4.Cu")
		(net "M_D_CPU1_SA_DQ<23>")
	)
	(arc
		(start 79.052166 -239.29086)
		(mid 78.872595 -239.251043)
		(end 78.695804 -239.301782)
		(width 0.0889)
		(layer "In4.Cu")
		(net "M_D_CPU1_SA_DQ<23>")
	)
	(arc
		(start 91.288108 -239.301782)
		(mid 91.105857 -239.251432)
		(end 90.922348 -239.296956)
		(width 0.0889)
		(layer "In4.Cu")
		(net "M_D_CPU1_SA_DQ<23>")
	)
	(arc
		(start 91.85402 -239.301782)
		(mid 91.571064 -239.377959)
		(end 91.288108 -239.301782)
		(width 0.0889)
		(layer "In4.Cu")
		(net "M_D_CPU1_SA_DQ<23>")
	)
	(arc
		(start 88.4682 -239.301782)
		(mid 88.285949 -239.251432)
		(end 88.10244 -239.296956)
		(width 0.0889)
		(layer "In4.Cu")
		(net "M_D_CPU1_SA_DQ<23>")
	)
	(arc
		(start 89.973912 -239.301782)
		(mid 89.690956 -239.377959)
		(end 89.408 -239.301782)
		(width 0.0889)
		(layer "In4.Cu")
		(net "M_D_CPU1_SA_DQ<23>")
	)
	(arc
		(start 82.82813 -239.301782)
		(mid 82.645879 -239.251432)
		(end 82.46237 -239.296956)
		(width 0.0889)
		(layer "In4.Cu")
		(net "M_D_CPU1_SA_DQ<23>")
	)
	(segment
		(start 91.097862 -239.080294)
		(end 90.63101 -238.814356)
		(width 0.10668)
		(layer "F.Cu")
		(net "M_D_CPU1_SA_DQ<22>")
	)
	(segment
		(start 80.46974 -238.48695)
		(end 80.478122 -238.491776)
		(width 0.0889)
		(layer "In4.Cu")
		(net "M_D_CPU1_SA_DQ<22>")
	)
	(segment
		(start 33.121092 -223.260412)
		(end 34.200084 -223.260412)
		(width 0.14478)
		(layer "In4.Cu")
		(net "M_D_CPU1_SA_DQ<22>")
	)
	(segment
		(start 35.869626 -222.468186)
		(end 36.032694 -222.631254)
		(width 0.14478)
		(layer "In4.Cu")
		(net "M_D_CPU1_SA_DQ<22>")
	)
	(segment
		(start 46.417738 -223.260412)
		(end 49.372266 -223.260412)
		(width 0.14478)
		(layer "In4.Cu")
		(net "M_D_CPU1_SA_DQ<22>")
	)
	(segment
		(start 83.289648 -238.48695)
		(end 83.29803 -238.491776)
		(width 0.0889)
		(layer "In4.Cu")
		(net "M_D_CPU1_SA_DQ<22>")
	)
	(segment
		(start 42.73423 -222.410274)
		(end 45.5676 -222.410274)
		(width 0.14478)
		(layer "In4.Cu")
		(net "M_D_CPU1_SA_DQ<22>")
	)
	(segment
		(start 32.695896 -222.835216)
		(end 33.121092 -223.260412)
		(width 0.14478)
		(layer "In4.Cu")
		(net "M_D_CPU1_SA_DQ<22>")
	)
	(segment
		(start 79.143098 -238.505492)
		(end 79.166466 -238.491776)
		(width 0.0889)
		(layer "In4.Cu")
		(net "M_D_CPU1_SA_DQ<22>")
	)
	(segment
		(start 34.919666 -222.526352)
		(end 34.919666 -223.097344)
		(width 0.14478)
		(layer "In4.Cu")
		(net "M_D_CPU1_SA_DQ<22>")
	)
	(segment
		(start 36.032694 -222.631254)
		(end 36.032694 -223.097344)
		(width 0.14478)
		(layer "In4.Cu")
		(net "M_D_CPU1_SA_DQ<22>")
	)
	(segment
		(start 34.363152 -222.526352)
		(end 34.52622 -222.363284)
		(width 0.14478)
		(layer "In4.Cu")
		(net "M_D_CPU1_SA_DQ<22>")
	)
	(segment
		(start 49.372266 -223.260412)
		(end 50.222404 -222.410274)
		(width 0.14478)
		(layer "In4.Cu")
		(net "M_D_CPU1_SA_DQ<22>")
	)
	(segment
		(start 69.191886 -232.882948)
		(end 69.191886 -234.095036)
		(width 0.14478)
		(layer "In4.Cu")
		(net "M_D_CPU1_SA_DQ<22>")
	)
	(segment
		(start 59.56935 -223.260412)
		(end 69.191886 -232.882948)
		(width 0.14478)
		(layer "In4.Cu")
		(net "M_D_CPU1_SA_DQ<22>")
	)
	(segment
		(start 35.47618 -223.097344)
		(end 35.47618 -222.631254)
		(width 0.14478)
		(layer "In4.Cu")
		(net "M_D_CPU1_SA_DQ<22>")
	)
	(segment
		(start 89.504012 -238.491776)
		(end 89.512394 -238.48695)
		(width 0.0889)
		(layer "In4.Cu")
		(net "M_D_CPU1_SA_DQ<22>")
	)
	(segment
		(start 79.521304 -238.481616)
		(end 79.539592 -238.49203)
		(width 0.0889)
		(layer "In4.Cu")
		(net "M_D_CPU1_SA_DQ<22>")
	)
	(segment
		(start 35.639248 -222.468186)
		(end 35.869626 -222.468186)
		(width 0.14478)
		(layer "In4.Cu")
		(net "M_D_CPU1_SA_DQ<22>")
	)
	(segment
		(start 69.191886 -234.095036)
		(end 72.050148 -236.953298)
		(width 0.14478)
		(layer "In4.Cu")
		(net "M_D_CPU1_SA_DQ<22>")
	)
	(segment
		(start 75.96378 -236.953298)
		(end 76.139802 -236.953298)
		(width 0.0889)
		(layer "In4.Cu")
		(net "M_D_CPU1_SA_DQ<22>")
	)
	(segment
		(start 77.17409 -237.304326)
		(end 78.310486 -238.440722)
		(width 0.0889)
		(layer "In4.Cu")
		(net "M_D_CPU1_SA_DQ<22>")
	)
	(segment
		(start 34.52622 -222.363284)
		(end 34.756598 -222.363284)
		(width 0.14478)
		(layer "In4.Cu")
		(net "M_D_CPU1_SA_DQ<22>")
	)
	(segment
		(start 35.313112 -223.260412)
		(end 35.47618 -223.097344)
		(width 0.14478)
		(layer "In4.Cu")
		(net "M_D_CPU1_SA_DQ<22>")
	)
	(segment
		(start 90.784934 -238.548926)
		(end 90.63101 -238.814356)
		(width 0.0889)
		(layer "In4.Cu")
		(net "M_D_CPU1_SA_DQ<22>")
	)
	(segment
		(start 50.222404 -222.410274)
		(end 53.256434 -222.410274)
		(width 0.14478)
		(layer "In4.Cu")
		(net "M_D_CPU1_SA_DQ<22>")
	)
	(segment
		(start 84.229702 -238.48695)
		(end 84.238084 -238.491776)
		(width 0.0889)
		(layer "In4.Cu")
		(net "M_D_CPU1_SA_DQ<22>")
	)
	(segment
		(start 78.310486 -238.440722)
		(end 78.41107 -238.440722)
		(width 0.0889)
		(layer "In4.Cu")
		(net "M_D_CPU1_SA_DQ<22>")
	)
	(segment
		(start 85.74405 -238.491776)
		(end 85.752432 -238.48695)
		(width 0.0889)
		(layer "In4.Cu")
		(net "M_D_CPU1_SA_DQ<22>")
	)
	(segment
		(start 36.195762 -223.260412)
		(end 41.884092 -223.260412)
		(width 0.14478)
		(layer "In4.Cu")
		(net "M_D_CPU1_SA_DQ<22>")
	)
	(segment
		(start 53.256434 -222.410274)
		(end 54.106572 -223.260412)
		(width 0.14478)
		(layer "In4.Cu")
		(net "M_D_CPU1_SA_DQ<22>")
	)
	(segment
		(start 54.106572 -223.260412)
		(end 59.56935 -223.260412)
		(width 0.14478)
		(layer "In4.Cu")
		(net "M_D_CPU1_SA_DQ<22>")
	)
	(segment
		(start 36.032694 -223.097344)
		(end 36.195762 -223.260412)
		(width 0.14478)
		(layer "In4.Cu")
		(net "M_D_CPU1_SA_DQ<22>")
	)
	(segment
		(start 76.49083 -237.304326)
		(end 77.17409 -237.304326)
		(width 0.0889)
		(layer "In4.Cu")
		(net "M_D_CPU1_SA_DQ<22>")
	)
	(segment
		(start 84.803996 -238.491776)
		(end 84.812378 -238.48695)
		(width 0.0889)
		(layer "In4.Cu")
		(net "M_D_CPU1_SA_DQ<22>")
	)
	(segment
		(start 34.919666 -223.097344)
		(end 35.082734 -223.260412)
		(width 0.14478)
		(layer "In4.Cu")
		(net "M_D_CPU1_SA_DQ<22>")
	)
	(segment
		(start 35.47618 -222.631254)
		(end 35.639248 -222.468186)
		(width 0.14478)
		(layer "In4.Cu")
		(net "M_D_CPU1_SA_DQ<22>")
	)
	(segment
		(start 34.363152 -223.097344)
		(end 34.363152 -222.526352)
		(width 0.14478)
		(layer "In4.Cu")
		(net "M_D_CPU1_SA_DQ<22>")
	)
	(segment
		(start 34.756598 -222.363284)
		(end 34.919666 -222.526352)
		(width 0.14478)
		(layer "In4.Cu")
		(net "M_D_CPU1_SA_DQ<22>")
	)
	(segment
		(start 34.200084 -223.260412)
		(end 34.363152 -223.097344)
		(width 0.14478)
		(layer "In4.Cu")
		(net "M_D_CPU1_SA_DQ<22>")
	)
	(segment
		(start 88.929718 -238.48695)
		(end 88.9381 -238.491776)
		(width 0.0889)
		(layer "In4.Cu")
		(net "M_D_CPU1_SA_DQ<22>")
	)
	(segment
		(start 87.989664 -238.48695)
		(end 87.998046 -238.491776)
		(width 0.0889)
		(layer "In4.Cu")
		(net "M_D_CPU1_SA_DQ<22>")
	)
	(segment
		(start 81.044034 -238.491776)
		(end 81.052416 -238.48695)
		(width 0.0889)
		(layer "In4.Cu")
		(net "M_D_CPU1_SA_DQ<22>")
	)
	(segment
		(start 41.884092 -223.260412)
		(end 42.73423 -222.410274)
		(width 0.14478)
		(layer "In4.Cu")
		(net "M_D_CPU1_SA_DQ<22>")
	)
	(segment
		(start 79.539592 -238.49203)
		(end 79.561182 -238.504476)
		(width 0.0889)
		(layer "In4.Cu")
		(net "M_D_CPU1_SA_DQ<22>")
	)
	(segment
		(start 72.050148 -236.953298)
		(end 75.96378 -236.953298)
		(width 0.14478)
		(layer "In4.Cu")
		(net "M_D_CPU1_SA_DQ<22>")
	)
	(segment
		(start 76.139802 -236.953298)
		(end 76.49083 -237.304326)
		(width 0.0889)
		(layer "In4.Cu")
		(net "M_D_CPU1_SA_DQ<22>")
	)
	(segment
		(start 45.5676 -222.410274)
		(end 46.417738 -223.260412)
		(width 0.14478)
		(layer "In4.Cu")
		(net "M_D_CPU1_SA_DQ<22>")
	)
	(segment
		(start 35.082734 -223.260412)
		(end 35.313112 -223.260412)
		(width 0.14478)
		(layer "In4.Cu")
		(net "M_D_CPU1_SA_DQ<22>")
	)
	(segment
		(start 90.762582 -238.465614)
		(end 90.784934 -238.548926)
		(width 0.0889)
		(layer "In4.Cu")
		(net "M_D_CPU1_SA_DQ<22>")
	)
	(arc
		(start 85.752432 -238.48695)
		(mid 85.93594 -238.441456)
		(end 86.118192 -238.491776)
		(width 0.0889)
		(layer "In4.Cu")
		(net "M_D_CPU1_SA_DQ<22>")
	)
	(arc
		(start 83.29803 -238.491776)
		(mid 83.580986 -238.567953)
		(end 83.863942 -238.491776)
		(width 0.0889)
		(layer "In4.Cu")
		(net "M_D_CPU1_SA_DQ<22>")
	)
	(arc
		(start 80.10398 -238.491776)
		(mid 80.286231 -238.441426)
		(end 80.46974 -238.48695)
		(width 0.0889)
		(layer "In4.Cu")
		(net "M_D_CPU1_SA_DQ<22>")
	)
	(arc
		(start 86.684104 -238.491776)
		(mid 86.871048 -238.441521)
		(end 87.057992 -238.491776)
		(width 0.0889)
		(layer "In4.Cu")
		(net "M_D_CPU1_SA_DQ<22>")
	)
	(arc
		(start 79.561182 -238.504476)
		(mid 79.834211 -238.567795)
		(end 80.10398 -238.491776)
		(width 0.0889)
		(layer "In4.Cu")
		(net "M_D_CPU1_SA_DQ<22>")
	)
	(arc
		(start 84.238084 -238.491776)
		(mid 84.52104 -238.567953)
		(end 84.803996 -238.491776)
		(width 0.0889)
		(layer "In4.Cu")
		(net "M_D_CPU1_SA_DQ<22>")
	)
	(arc
		(start 90.444066 -238.491776)
		(mid 90.600385 -238.442781)
		(end 90.762582 -238.465614)
		(width 0.0889)
		(layer "In4.Cu")
		(net "M_D_CPU1_SA_DQ<22>")
	)
	(arc
		(start 81.418176 -238.491776)
		(mid 81.701132 -238.567953)
		(end 81.984088 -238.491776)
		(width 0.0889)
		(layer "In4.Cu")
		(net "M_D_CPU1_SA_DQ<22>")
	)
	(arc
		(start 78.41107 -238.440722)
		(mid 78.508573 -238.453737)
		(end 78.599284 -238.491776)
		(width 0.0889)
		(layer "In4.Cu")
		(net "M_D_CPU1_SA_DQ<22>")
	)
	(arc
		(start 81.052416 -238.48695)
		(mid 81.235924 -238.441456)
		(end 81.418176 -238.491776)
		(width 0.0889)
		(layer "In4.Cu")
		(net "M_D_CPU1_SA_DQ<22>")
	)
	(arc
		(start 80.478122 -238.491776)
		(mid 80.761078 -238.567953)
		(end 81.044034 -238.491776)
		(width 0.0889)
		(layer "In4.Cu")
		(net "M_D_CPU1_SA_DQ<22>")
	)
	(arc
		(start 88.563958 -238.491776)
		(mid 88.746209 -238.441426)
		(end 88.929718 -238.48695)
		(width 0.0889)
		(layer "In4.Cu")
		(net "M_D_CPU1_SA_DQ<22>")
	)
	(arc
		(start 87.623904 -238.491776)
		(mid 87.806155 -238.441426)
		(end 87.989664 -238.48695)
		(width 0.0889)
		(layer "In4.Cu")
		(net "M_D_CPU1_SA_DQ<22>")
	)
	(arc
		(start 87.057992 -238.491776)
		(mid 87.340948 -238.567953)
		(end 87.623904 -238.491776)
		(width 0.0889)
		(layer "In4.Cu")
		(net "M_D_CPU1_SA_DQ<22>")
	)
	(arc
		(start 83.863942 -238.491776)
		(mid 84.046193 -238.441426)
		(end 84.229702 -238.48695)
		(width 0.0889)
		(layer "In4.Cu")
		(net "M_D_CPU1_SA_DQ<22>")
	)
	(arc
		(start 79.166466 -238.491776)
		(mid 79.342586 -238.441798)
		(end 79.521304 -238.481616)
		(width 0.0889)
		(layer "In4.Cu")
		(net "M_D_CPU1_SA_DQ<22>")
	)
	(arc
		(start 78.599284 -238.491776)
		(mid 78.869441 -238.568538)
		(end 79.143098 -238.505492)
		(width 0.0889)
		(layer "In4.Cu")
		(net "M_D_CPU1_SA_DQ<22>")
	)
	(arc
		(start 82.923888 -238.491776)
		(mid 83.106139 -238.441426)
		(end 83.289648 -238.48695)
		(width 0.0889)
		(layer "In4.Cu")
		(net "M_D_CPU1_SA_DQ<22>")
	)
	(arc
		(start 89.878154 -238.491776)
		(mid 90.16111 -238.567953)
		(end 90.444066 -238.491776)
		(width 0.0889)
		(layer "In4.Cu")
		(net "M_D_CPU1_SA_DQ<22>")
	)
	(arc
		(start 86.118192 -238.491776)
		(mid 86.401148 -238.567953)
		(end 86.684104 -238.491776)
		(width 0.0889)
		(layer "In4.Cu")
		(net "M_D_CPU1_SA_DQ<22>")
	)
	(arc
		(start 88.9381 -238.491776)
		(mid 89.221056 -238.567953)
		(end 89.504012 -238.491776)
		(width 0.0889)
		(layer "In4.Cu")
		(net "M_D_CPU1_SA_DQ<22>")
	)
	(arc
		(start 84.812378 -238.48695)
		(mid 84.995886 -238.441456)
		(end 85.178138 -238.491776)
		(width 0.0889)
		(layer "In4.Cu")
		(net "M_D_CPU1_SA_DQ<22>")
	)
	(arc
		(start 89.512394 -238.48695)
		(mid 89.695902 -238.441456)
		(end 89.878154 -238.491776)
		(width 0.0889)
		(layer "In4.Cu")
		(net "M_D_CPU1_SA_DQ<22>")
	)
	(arc
		(start 82.357976 -238.491776)
		(mid 82.640932 -238.567953)
		(end 82.923888 -238.491776)
		(width 0.0889)
		(layer "In4.Cu")
		(net "M_D_CPU1_SA_DQ<22>")
	)
	(arc
		(start 87.998046 -238.491776)
		(mid 88.281002 -238.567953)
		(end 88.563958 -238.491776)
		(width 0.0889)
		(layer "In4.Cu")
		(net "M_D_CPU1_SA_DQ<22>")
	)
	(arc
		(start 81.984088 -238.491776)
		(mid 82.171032 -238.441521)
		(end 82.357976 -238.491776)
		(width 0.0889)
		(layer "In4.Cu")
		(net "M_D_CPU1_SA_DQ<22>")
	)
	(arc
		(start 85.178138 -238.491776)
		(mid 85.461094 -238.567953)
		(end 85.74405 -238.491776)
		(width 0.0889)
		(layer "In4.Cu")
		(net "M_D_CPU1_SA_DQ<22>")
	)
	(segment
		(start 92.97797 -239.080294)
		(end 92.511118 -238.814356)
		(width 0.10668)
		(layer "F.Cu")
		(net "M_D_CPU1_SA_DQ<21>")
	)
	(segment
		(start 92.35694 -239.079786)
		(end 92.511118 -238.814356)
		(width 0.0889)
		(layer "In4.Cu")
		(net "M_D_CPU1_SA_DQ<21>")
	)
	(segment
		(start 37.571934 -224.110296)
		(end 37.735002 -224.273364)
		(width 0.14478)
		(layer "In4.Cu")
		(net "M_D_CPU1_SA_DQ<21>")
	)
	(segment
		(start 38.684962 -223.738948)
		(end 38.84803 -223.902016)
		(width 0.14478)
		(layer "In4.Cu")
		(net "M_D_CPU1_SA_DQ<21>")
	)
	(segment
		(start 76.24953 -237.558326)
		(end 77.061568 -237.558326)
		(width 0.0889)
		(layer "In4.Cu")
		(net "M_D_CPU1_SA_DQ<21>")
	)
	(segment
		(start 49.017682 -224.333816)
		(end 49.017682 -224.273364)
		(width 0.14478)
		(layer "In4.Cu")
		(net "M_D_CPU1_SA_DQ<21>")
	)
	(segment
		(start 79.139288 -239.120934)
		(end 79.166974 -239.136936)
		(width 0.0889)
		(layer "In4.Cu")
		(net "M_D_CPU1_SA_DQ<21>")
	)
	(segment
		(start 42.733214 -223.260412)
		(end 42.99712 -223.260412)
		(width 0.14478)
		(layer "In4.Cu")
		(net "M_D_CPU1_SA_DQ<21>")
	)
	(segment
		(start 48.624236 -224.496884)
		(end 48.854614 -224.496884)
		(width 0.14478)
		(layer "In4.Cu")
		(net "M_D_CPU1_SA_DQ<21>")
	)
	(segment
		(start 43.716702 -223.42348)
		(end 43.87977 -223.260412)
		(width 0.14478)
		(layer "In4.Cu")
		(net "M_D_CPU1_SA_DQ<21>")
	)
	(segment
		(start 53.23459 -223.260412)
		(end 54.084474 -224.110296)
		(width 0.14478)
		(layer "In4.Cu")
		(net "M_D_CPU1_SA_DQ<21>")
	)
	(segment
		(start 39.011098 -224.481644)
		(end 39.241476 -224.481644)
		(width 0.14478)
		(layer "In4.Cu")
		(net "M_D_CPU1_SA_DQ<21>")
	)
	(segment
		(start 46.408594 -224.110296)
		(end 48.2981 -224.110296)
		(width 0.14478)
		(layer "In4.Cu")
		(net "M_D_CPU1_SA_DQ<21>")
	)
	(segment
		(start 57.14238 -224.338642)
		(end 57.14238 -223.88195)
		(width 0.14478)
		(layer "In4.Cu")
		(net "M_D_CPU1_SA_DQ<21>")
	)
	(segment
		(start 45.55871 -223.260412)
		(end 46.408594 -224.110296)
		(width 0.14478)
		(layer "In4.Cu")
		(net "M_D_CPU1_SA_DQ<21>")
	)
	(segment
		(start 92.260674 -239.105186)
		(end 92.35694 -239.079786)
		(width 0.0889)
		(layer "In4.Cu")
		(net "M_D_CPU1_SA_DQ<21>")
	)
	(segment
		(start 43.716702 -223.487996)
		(end 43.716702 -223.42348)
		(width 0.14478)
		(layer "In4.Cu")
		(net "M_D_CPU1_SA_DQ<21>")
	)
	(segment
		(start 49.40681 -224.110296)
		(end 50.256694 -223.260412)
		(width 0.14478)
		(layer "In4.Cu")
		(net "M_D_CPU1_SA_DQ<21>")
	)
	(segment
		(start 48.2981 -224.110296)
		(end 48.461168 -224.273364)
		(width 0.14478)
		(layer "In4.Cu")
		(net "M_D_CPU1_SA_DQ<21>")
	)
	(segment
		(start 43.553634 -223.651064)
		(end 43.716702 -223.487996)
		(width 0.14478)
		(layer "In4.Cu")
		(net "M_D_CPU1_SA_DQ<21>")
	)
	(segment
		(start 49.18075 -224.110296)
		(end 49.40681 -224.110296)
		(width 0.14478)
		(layer "In4.Cu")
		(net "M_D_CPU1_SA_DQ<21>")
	)
	(segment
		(start 41.88333 -224.110296)
		(end 42.733214 -223.260412)
		(width 0.14478)
		(layer "In4.Cu")
		(net "M_D_CPU1_SA_DQ<21>")
	)
	(segment
		(start 57.303924 -223.720406)
		(end 57.53227 -223.720406)
		(width 0.14478)
		(layer "In4.Cu")
		(net "M_D_CPU1_SA_DQ<21>")
	)
	(segment
		(start 56.75249 -224.500186)
		(end 56.980836 -224.500186)
		(width 0.14478)
		(layer "In4.Cu")
		(net "M_D_CPU1_SA_DQ<21>")
	)
	(segment
		(start 83.289648 -239.141762)
		(end 83.29803 -239.136936)
		(width 0.0889)
		(layer "In4.Cu")
		(net "M_D_CPU1_SA_DQ<21>")
	)
	(segment
		(start 50.886106 -223.651064)
		(end 51.116484 -223.651064)
		(width 0.14478)
		(layer "In4.Cu")
		(net "M_D_CPU1_SA_DQ<21>")
	)
	(segment
		(start 68.734686 -234.274106)
		(end 71.868538 -237.407958)
		(width 0.14478)
		(layer "In4.Cu")
		(net "M_D_CPU1_SA_DQ<21>")
	)
	(segment
		(start 77.061568 -237.558326)
		(end 77.95641 -238.453168)
		(width 0.0889)
		(layer "In4.Cu")
		(net "M_D_CPU1_SA_DQ<21>")
	)
	(segment
		(start 38.84803 -224.318576)
		(end 39.011098 -224.481644)
		(width 0.14478)
		(layer "In4.Cu")
		(net "M_D_CPU1_SA_DQ<21>")
	)
	(segment
		(start 38.291516 -223.902016)
		(end 38.454584 -223.738948)
		(width 0.14478)
		(layer "In4.Cu")
		(net "M_D_CPU1_SA_DQ<21>")
	)
	(segment
		(start 37.220906 -224.110296)
		(end 37.571934 -224.110296)
		(width 0.14478)
		(layer "In4.Cu")
		(net "M_D_CPU1_SA_DQ<21>")
	)
	(segment
		(start 89.504012 -239.136936)
		(end 89.512394 -239.141762)
		(width 0.0889)
		(layer "In4.Cu")
		(net "M_D_CPU1_SA_DQ<21>")
	)
	(segment
		(start 58.635138 -223.720406)
		(end 58.796682 -223.88195)
		(width 0.14478)
		(layer "In4.Cu")
		(net "M_D_CPU1_SA_DQ<21>")
	)
	(segment
		(start 43.160188 -223.42348)
		(end 43.160188 -223.487996)
		(width 0.14478)
		(layer "In4.Cu")
		(net "M_D_CPU1_SA_DQ<21>")
	)
	(segment
		(start 68.734686 -233.061764)
		(end 68.734686 -234.274106)
		(width 0.14478)
		(layer "In4.Cu")
		(net "M_D_CPU1_SA_DQ<21>")
	)
	(segment
		(start 79.539846 -239.136682)
		(end 79.563722 -239.122712)
		(width 0.0889)
		(layer "In4.Cu")
		(net "M_D_CPU1_SA_DQ<21>")
	)
	(segment
		(start 81.044034 -239.136936)
		(end 81.052416 -239.141762)
		(width 0.0889)
		(layer "In4.Cu")
		(net "M_D_CPU1_SA_DQ<21>")
	)
	(segment
		(start 58.958226 -224.110296)
		(end 59.783218 -224.110296)
		(width 0.14478)
		(layer "In4.Cu")
		(net "M_D_CPU1_SA_DQ<21>")
	)
	(segment
		(start 58.406792 -223.720406)
		(end 58.635138 -223.720406)
		(width 0.14478)
		(layer "In4.Cu")
		(net "M_D_CPU1_SA_DQ<21>")
	)
	(segment
		(start 56.590946 -224.338642)
		(end 56.75249 -224.500186)
		(width 0.14478)
		(layer "In4.Cu")
		(net "M_D_CPU1_SA_DQ<21>")
	)
	(segment
		(start 88.929718 -239.141762)
		(end 88.9381 -239.136936)
		(width 0.0889)
		(layer "In4.Cu")
		(net "M_D_CPU1_SA_DQ<21>")
	)
	(segment
		(start 51.279552 -223.42348)
		(end 51.44262 -223.260412)
		(width 0.14478)
		(layer "In4.Cu")
		(net "M_D_CPU1_SA_DQ<21>")
	)
	(segment
		(start 56.590946 -224.27184)
		(end 56.590946 -224.338642)
		(width 0.14478)
		(layer "In4.Cu")
		(net "M_D_CPU1_SA_DQ<21>")
	)
	(segment
		(start 40.997632 -224.501964)
		(end 41.22801 -224.501964)
		(width 0.14478)
		(layer "In4.Cu")
		(net "M_D_CPU1_SA_DQ<21>")
	)
	(segment
		(start 37.735002 -224.318576)
		(end 37.89807 -224.481644)
		(width 0.14478)
		(layer "In4.Cu")
		(net "M_D_CPU1_SA_DQ<21>")
	)
	(segment
		(start 48.854614 -224.496884)
		(end 49.017682 -224.333816)
		(width 0.14478)
		(layer "In4.Cu")
		(net "M_D_CPU1_SA_DQ<21>")
	)
	(segment
		(start 58.796682 -223.948752)
		(end 58.958226 -224.110296)
		(width 0.14478)
		(layer "In4.Cu")
		(net "M_D_CPU1_SA_DQ<21>")
	)
	(segment
		(start 78.397608 -239.188244)
		(end 78.41107 -239.188244)
		(width 0.0889)
		(layer "In4.Cu")
		(net "M_D_CPU1_SA_DQ<21>")
	)
	(segment
		(start 49.017682 -224.273364)
		(end 49.18075 -224.110296)
		(width 0.14478)
		(layer "In4.Cu")
		(net "M_D_CPU1_SA_DQ<21>")
	)
	(segment
		(start 40.834564 -224.273364)
		(end 40.834564 -224.338896)
		(width 0.14478)
		(layer "In4.Cu")
		(net "M_D_CPU1_SA_DQ<21>")
	)
	(segment
		(start 57.14238 -223.88195)
		(end 57.303924 -223.720406)
		(width 0.14478)
		(layer "In4.Cu")
		(net "M_D_CPU1_SA_DQ<21>")
	)
	(segment
		(start 51.116484 -223.651064)
		(end 51.279552 -223.487996)
		(width 0.14478)
		(layer "In4.Cu")
		(net "M_D_CPU1_SA_DQ<21>")
	)
	(segment
		(start 41.22801 -224.501964)
		(end 41.391078 -224.338896)
		(width 0.14478)
		(layer "In4.Cu")
		(net "M_D_CPU1_SA_DQ<21>")
	)
	(segment
		(start 50.55997 -223.260412)
		(end 50.723038 -223.42348)
		(width 0.14478)
		(layer "In4.Cu")
		(net "M_D_CPU1_SA_DQ<21>")
	)
	(segment
		(start 43.87977 -223.260412)
		(end 45.55871 -223.260412)
		(width 0.14478)
		(layer "In4.Cu")
		(net "M_D_CPU1_SA_DQ<21>")
	)
	(segment
		(start 58.245248 -224.338642)
		(end 58.245248 -223.88195)
		(width 0.14478)
		(layer "In4.Cu")
		(net "M_D_CPU1_SA_DQ<21>")
	)
	(segment
		(start 57.693814 -223.88195)
		(end 57.693814 -224.338642)
		(width 0.14478)
		(layer "In4.Cu")
		(net "M_D_CPU1_SA_DQ<21>")
	)
	(segment
		(start 80.46974 -239.141762)
		(end 80.478122 -239.136936)
		(width 0.0889)
		(layer "In4.Cu")
		(net "M_D_CPU1_SA_DQ<21>")
	)
	(segment
		(start 50.256694 -223.260412)
		(end 50.55997 -223.260412)
		(width 0.14478)
		(layer "In4.Cu")
		(net "M_D_CPU1_SA_DQ<21>")
	)
	(segment
		(start 41.391078 -224.338896)
		(end 41.391078 -224.273364)
		(width 0.14478)
		(layer "In4.Cu")
		(net "M_D_CPU1_SA_DQ<21>")
	)
	(segment
		(start 58.796682 -223.88195)
		(end 58.796682 -223.948752)
		(width 0.14478)
		(layer "In4.Cu")
		(net "M_D_CPU1_SA_DQ<21>")
	)
	(segment
		(start 56.429402 -224.110296)
		(end 56.590946 -224.27184)
		(width 0.14478)
		(layer "In4.Cu")
		(net "M_D_CPU1_SA_DQ<21>")
	)
	(segment
		(start 51.279552 -223.487996)
		(end 51.279552 -223.42348)
		(width 0.14478)
		(layer "In4.Cu")
		(net "M_D_CPU1_SA_DQ<21>")
	)
	(segment
		(start 39.404544 -224.318576)
		(end 39.404544 -224.273364)
		(width 0.14478)
		(layer "In4.Cu")
		(net "M_D_CPU1_SA_DQ<21>")
	)
	(segment
		(start 50.723038 -223.42348)
		(end 50.723038 -223.487996)
		(width 0.14478)
		(layer "In4.Cu")
		(net "M_D_CPU1_SA_DQ<21>")
	)
	(segment
		(start 85.74405 -239.136936)
		(end 85.752432 -239.141762)
		(width 0.0889)
		(layer "In4.Cu")
		(net "M_D_CPU1_SA_DQ<21>")
	)
	(segment
		(start 40.671496 -224.110296)
		(end 40.834564 -224.273364)
		(width 0.14478)
		(layer "In4.Cu")
		(net "M_D_CPU1_SA_DQ<21>")
	)
	(segment
		(start 38.291516 -224.318576)
		(end 38.291516 -223.902016)
		(width 0.14478)
		(layer "In4.Cu")
		(net "M_D_CPU1_SA_DQ<21>")
	)
	(segment
		(start 71.868538 -237.407958)
		(end 75.9333 -237.407958)
		(width 0.14478)
		(layer "In4.Cu")
		(net "M_D_CPU1_SA_DQ<21>")
	)
	(segment
		(start 40.834564 -224.338896)
		(end 40.997632 -224.501964)
		(width 0.14478)
		(layer "In4.Cu")
		(net "M_D_CPU1_SA_DQ<21>")
	)
	(segment
		(start 76.099162 -237.407958)
		(end 76.24953 -237.558326)
		(width 0.0889)
		(layer "In4.Cu")
		(net "M_D_CPU1_SA_DQ<21>")
	)
	(segment
		(start 56.980836 -224.500186)
		(end 57.14238 -224.338642)
		(width 0.14478)
		(layer "In4.Cu")
		(net "M_D_CPU1_SA_DQ<21>")
	)
	(segment
		(start 91.749626 -239.141762)
		(end 91.758008 -239.136936)
		(width 0.0889)
		(layer "In4.Cu")
		(net "M_D_CPU1_SA_DQ<21>")
	)
	(segment
		(start 48.461168 -224.273364)
		(end 48.461168 -224.333816)
		(width 0.14478)
		(layer "In4.Cu")
		(net "M_D_CPU1_SA_DQ<21>")
	)
	(segment
		(start 37.735002 -224.273364)
		(end 37.735002 -224.318576)
		(width 0.14478)
		(layer "In4.Cu")
		(net "M_D_CPU1_SA_DQ<21>")
	)
	(segment
		(start 38.128448 -224.481644)
		(end 38.291516 -224.318576)
		(width 0.14478)
		(layer "In4.Cu")
		(net "M_D_CPU1_SA_DQ<21>")
	)
	(segment
		(start 54.084474 -224.110296)
		(end 56.429402 -224.110296)
		(width 0.14478)
		(layer "In4.Cu")
		(net "M_D_CPU1_SA_DQ<21>")
	)
	(segment
		(start 50.723038 -223.487996)
		(end 50.886106 -223.651064)
		(width 0.14478)
		(layer "In4.Cu")
		(net "M_D_CPU1_SA_DQ<21>")
	)
	(segment
		(start 39.567612 -224.110296)
		(end 40.671496 -224.110296)
		(width 0.14478)
		(layer "In4.Cu")
		(net "M_D_CPU1_SA_DQ<21>")
	)
	(segment
		(start 43.323256 -223.651064)
		(end 43.553634 -223.651064)
		(width 0.14478)
		(layer "In4.Cu")
		(net "M_D_CPU1_SA_DQ<21>")
	)
	(segment
		(start 79.51978 -239.148112)
		(end 79.539846 -239.136682)
		(width 0.0889)
		(layer "In4.Cu")
		(net "M_D_CPU1_SA_DQ<21>")
	)
	(segment
		(start 84.229702 -239.141762)
		(end 84.238084 -239.136936)
		(width 0.0889)
		(layer "In4.Cu")
		(net "M_D_CPU1_SA_DQ<21>")
	)
	(segment
		(start 84.803996 -239.136936)
		(end 84.812378 -239.141762)
		(width 0.0889)
		(layer "In4.Cu")
		(net "M_D_CPU1_SA_DQ<21>")
	)
	(segment
		(start 77.95641 -238.453168)
		(end 77.95641 -238.747046)
		(width 0.0889)
		(layer "In4.Cu")
		(net "M_D_CPU1_SA_DQ<21>")
	)
	(segment
		(start 58.083704 -224.500186)
		(end 58.245248 -224.338642)
		(width 0.14478)
		(layer "In4.Cu")
		(net "M_D_CPU1_SA_DQ<21>")
	)
	(segment
		(start 39.404544 -224.273364)
		(end 39.567612 -224.110296)
		(width 0.14478)
		(layer "In4.Cu")
		(net "M_D_CPU1_SA_DQ<21>")
	)
	(segment
		(start 39.241476 -224.481644)
		(end 39.404544 -224.318576)
		(width 0.14478)
		(layer "In4.Cu")
		(net "M_D_CPU1_SA_DQ<21>")
	)
	(segment
		(start 37.89807 -224.481644)
		(end 38.128448 -224.481644)
		(width 0.14478)
		(layer "In4.Cu")
		(net "M_D_CPU1_SA_DQ<21>")
	)
	(segment
		(start 57.693814 -224.338642)
		(end 57.855358 -224.500186)
		(width 0.14478)
		(layer "In4.Cu")
		(net "M_D_CPU1_SA_DQ<21>")
	)
	(segment
		(start 48.461168 -224.333816)
		(end 48.624236 -224.496884)
		(width 0.14478)
		(layer "In4.Cu")
		(net "M_D_CPU1_SA_DQ<21>")
	)
	(segment
		(start 41.391078 -224.273364)
		(end 41.554146 -224.110296)
		(width 0.14478)
		(layer "In4.Cu")
		(net "M_D_CPU1_SA_DQ<21>")
	)
	(segment
		(start 43.160188 -223.487996)
		(end 43.323256 -223.651064)
		(width 0.14478)
		(layer "In4.Cu")
		(net "M_D_CPU1_SA_DQ<21>")
	)
	(segment
		(start 87.989664 -239.141762)
		(end 87.998046 -239.136936)
		(width 0.0889)
		(layer "In4.Cu")
		(net "M_D_CPU1_SA_DQ<21>")
	)
	(segment
		(start 36.795964 -223.685354)
		(end 37.220906 -224.110296)
		(width 0.14478)
		(layer "In4.Cu")
		(net "M_D_CPU1_SA_DQ<21>")
	)
	(segment
		(start 57.53227 -223.720406)
		(end 57.693814 -223.88195)
		(width 0.14478)
		(layer "In4.Cu")
		(net "M_D_CPU1_SA_DQ<21>")
	)
	(segment
		(start 59.783218 -224.110296)
		(end 68.734686 -233.061764)
		(width 0.14478)
		(layer "In4.Cu")
		(net "M_D_CPU1_SA_DQ<21>")
	)
	(segment
		(start 58.245248 -223.88195)
		(end 58.406792 -223.720406)
		(width 0.14478)
		(layer "In4.Cu")
		(net "M_D_CPU1_SA_DQ<21>")
	)
	(segment
		(start 38.84803 -223.902016)
		(end 38.84803 -224.318576)
		(width 0.14478)
		(layer "In4.Cu")
		(net "M_D_CPU1_SA_DQ<21>")
	)
	(segment
		(start 42.99712 -223.260412)
		(end 43.160188 -223.42348)
		(width 0.14478)
		(layer "In4.Cu")
		(net "M_D_CPU1_SA_DQ<21>")
	)
	(segment
		(start 75.9333 -237.407958)
		(end 76.099162 -237.407958)
		(width 0.0889)
		(layer "In4.Cu")
		(net "M_D_CPU1_SA_DQ<21>")
	)
	(segment
		(start 51.44262 -223.260412)
		(end 53.23459 -223.260412)
		(width 0.14478)
		(layer "In4.Cu")
		(net "M_D_CPU1_SA_DQ<21>")
	)
	(segment
		(start 41.554146 -224.110296)
		(end 41.88333 -224.110296)
		(width 0.14478)
		(layer "In4.Cu")
		(net "M_D_CPU1_SA_DQ<21>")
	)
	(segment
		(start 57.855358 -224.500186)
		(end 58.083704 -224.500186)
		(width 0.14478)
		(layer "In4.Cu")
		(net "M_D_CPU1_SA_DQ<21>")
	)
	(segment
		(start 38.454584 -223.738948)
		(end 38.684962 -223.738948)
		(width 0.14478)
		(layer "In4.Cu")
		(net "M_D_CPU1_SA_DQ<21>")
	)
	(arc
		(start 80.10398 -239.136936)
		(mid 80.286231 -239.187286)
		(end 80.46974 -239.141762)
		(width 0.0889)
		(layer "In4.Cu")
		(net "M_D_CPU1_SA_DQ<21>")
	)
	(arc
		(start 82.923888 -239.136936)
		(mid 83.106139 -239.187286)
		(end 83.289648 -239.141762)
		(width 0.0889)
		(layer "In4.Cu")
		(net "M_D_CPU1_SA_DQ<21>")
	)
	(arc
		(start 82.357976 -239.136936)
		(mid 82.640932 -239.060759)
		(end 82.923888 -239.136936)
		(width 0.0889)
		(layer "In4.Cu")
		(net "M_D_CPU1_SA_DQ<21>")
	)
	(arc
		(start 88.9381 -239.136936)
		(mid 89.221056 -239.060759)
		(end 89.504012 -239.136936)
		(width 0.0889)
		(layer "In4.Cu")
		(net "M_D_CPU1_SA_DQ<21>")
	)
	(arc
		(start 91.758008 -239.136936)
		(mid 92.005604 -239.061758)
		(end 92.260674 -239.105186)
		(width 0.0889)
		(layer "In4.Cu")
		(net "M_D_CPU1_SA_DQ<21>")
	)
	(arc
		(start 90.817954 -239.136936)
		(mid 91.10091 -239.060759)
		(end 91.383866 -239.136936)
		(width 0.0889)
		(layer "In4.Cu")
		(net "M_D_CPU1_SA_DQ<21>")
	)
	(arc
		(start 77.95641 -238.747046)
		(mid 78.085634 -239.05902)
		(end 78.397608 -239.188244)
		(width 0.0889)
		(layer "In4.Cu")
		(net "M_D_CPU1_SA_DQ<21>")
	)
	(arc
		(start 78.41107 -239.188244)
		(mid 78.508584 -239.175089)
		(end 78.599284 -239.136936)
		(width 0.0889)
		(layer "In4.Cu")
		(net "M_D_CPU1_SA_DQ<21>")
	)
	(arc
		(start 85.752432 -239.141762)
		(mid 85.93594 -239.187256)
		(end 86.118192 -239.136936)
		(width 0.0889)
		(layer "In4.Cu")
		(net "M_D_CPU1_SA_DQ<21>")
	)
	(arc
		(start 85.178138 -239.136936)
		(mid 85.461094 -239.060759)
		(end 85.74405 -239.136936)
		(width 0.0889)
		(layer "In4.Cu")
		(net "M_D_CPU1_SA_DQ<21>")
	)
	(arc
		(start 87.623904 -239.136936)
		(mid 87.806155 -239.187286)
		(end 87.989664 -239.141762)
		(width 0.0889)
		(layer "In4.Cu")
		(net "M_D_CPU1_SA_DQ<21>")
	)
	(arc
		(start 81.418176 -239.136936)
		(mid 81.701132 -239.060759)
		(end 81.984088 -239.136936)
		(width 0.0889)
		(layer "In4.Cu")
		(net "M_D_CPU1_SA_DQ<21>")
	)
	(arc
		(start 84.238084 -239.136936)
		(mid 84.52104 -239.060759)
		(end 84.803996 -239.136936)
		(width 0.0889)
		(layer "In4.Cu")
		(net "M_D_CPU1_SA_DQ<21>")
	)
	(arc
		(start 90.444066 -239.136936)
		(mid 90.63101 -239.187191)
		(end 90.817954 -239.136936)
		(width 0.0889)
		(layer "In4.Cu")
		(net "M_D_CPU1_SA_DQ<21>")
	)
	(arc
		(start 81.984088 -239.136936)
		(mid 82.171032 -239.187191)
		(end 82.357976 -239.136936)
		(width 0.0889)
		(layer "In4.Cu")
		(net "M_D_CPU1_SA_DQ<21>")
	)
	(arc
		(start 87.998046 -239.136936)
		(mid 88.281002 -239.060759)
		(end 88.563958 -239.136936)
		(width 0.0889)
		(layer "In4.Cu")
		(net "M_D_CPU1_SA_DQ<21>")
	)
	(arc
		(start 86.118192 -239.136936)
		(mid 86.401148 -239.060759)
		(end 86.684104 -239.136936)
		(width 0.0889)
		(layer "In4.Cu")
		(net "M_D_CPU1_SA_DQ<21>")
	)
	(arc
		(start 79.563722 -239.122712)
		(mid 79.835659 -239.060886)
		(end 80.10398 -239.136936)
		(width 0.0889)
		(layer "In4.Cu")
		(net "M_D_CPU1_SA_DQ<21>")
	)
	(arc
		(start 88.563958 -239.136936)
		(mid 88.746209 -239.187286)
		(end 88.929718 -239.141762)
		(width 0.0889)
		(layer "In4.Cu")
		(net "M_D_CPU1_SA_DQ<21>")
	)
	(arc
		(start 83.29803 -239.136936)
		(mid 83.580986 -239.060759)
		(end 83.863942 -239.136936)
		(width 0.0889)
		(layer "In4.Cu")
		(net "M_D_CPU1_SA_DQ<21>")
	)
	(arc
		(start 91.383866 -239.136936)
		(mid 91.566117 -239.187286)
		(end 91.749626 -239.141762)
		(width 0.0889)
		(layer "In4.Cu")
		(net "M_D_CPU1_SA_DQ<21>")
	)
	(arc
		(start 78.599284 -239.136936)
		(mid 78.867253 -239.060113)
		(end 79.139288 -239.120934)
		(width 0.0889)
		(layer "In4.Cu")
		(net "M_D_CPU1_SA_DQ<21>")
	)
	(arc
		(start 86.684104 -239.136936)
		(mid 86.871048 -239.187191)
		(end 87.057992 -239.136936)
		(width 0.0889)
		(layer "In4.Cu")
		(net "M_D_CPU1_SA_DQ<21>")
	)
	(arc
		(start 84.812378 -239.141762)
		(mid 84.995886 -239.187256)
		(end 85.178138 -239.136936)
		(width 0.0889)
		(layer "In4.Cu")
		(net "M_D_CPU1_SA_DQ<21>")
	)
	(arc
		(start 83.863942 -239.136936)
		(mid 84.046193 -239.187286)
		(end 84.229702 -239.141762)
		(width 0.0889)
		(layer "In4.Cu")
		(net "M_D_CPU1_SA_DQ<21>")
	)
	(arc
		(start 81.052416 -239.141762)
		(mid 81.235924 -239.187256)
		(end 81.418176 -239.136936)
		(width 0.0889)
		(layer "In4.Cu")
		(net "M_D_CPU1_SA_DQ<21>")
	)
	(arc
		(start 89.512394 -239.141762)
		(mid 89.695902 -239.187256)
		(end 89.878154 -239.136936)
		(width 0.0889)
		(layer "In4.Cu")
		(net "M_D_CPU1_SA_DQ<21>")
	)
	(arc
		(start 89.878154 -239.136936)
		(mid 90.16111 -239.060759)
		(end 90.444066 -239.136936)
		(width 0.0889)
		(layer "In4.Cu")
		(net "M_D_CPU1_SA_DQ<21>")
	)
	(arc
		(start 87.057992 -239.136936)
		(mid 87.340948 -239.060759)
		(end 87.623904 -239.136936)
		(width 0.0889)
		(layer "In4.Cu")
		(net "M_D_CPU1_SA_DQ<21>")
	)
	(arc
		(start 79.166974 -239.136936)
		(mid 79.341959 -239.18688)
		(end 79.51978 -239.148112)
		(width 0.0889)
		(layer "In4.Cu")
		(net "M_D_CPU1_SA_DQ<21>")
	)
	(arc
		(start 80.478122 -239.136936)
		(mid 80.761078 -239.060759)
		(end 81.044034 -239.136936)
		(width 0.0889)
		(layer "In4.Cu")
		(net "M_D_CPU1_SA_DQ<21>")
	)
	(segment
		(start 91.568016 -238.270288)
		(end 91.10091 -238.00435)
		(width 0.10668)
		(layer "F.Cu")
		(net "M_D_CPU1_SA_DQ<20>")
	)
	(segment
		(start 70.887082 -234.159806)
		(end 70.50405 -234.542838)
		(width 0.14478)
		(layer "In4.Cu")
		(net "M_D_CPU1_SA_DQ<20>")
	)
	(segment
		(start 72.837802 -236.11078)
		(end 73.065894 -236.11078)
		(width 0.14478)
		(layer "In4.Cu")
		(net "M_D_CPU1_SA_DQ<20>")
	)
	(segment
		(start 72.057514 -235.330492)
		(end 72.285606 -235.330492)
		(width 0.14478)
		(layer "In4.Cu")
		(net "M_D_CPU1_SA_DQ<20>")
	)
	(segment
		(start 38.170612 -221.871032)
		(end 38.170612 -222.247206)
		(width 0.14478)
		(layer "In4.Cu")
		(net "M_D_CPU1_SA_DQ<20>")
	)
	(segment
		(start 37.614098 -222.247206)
		(end 37.614098 -221.871032)
		(width 0.14478)
		(layer "In4.Cu")
		(net "M_D_CPU1_SA_DQ<20>")
	)
	(segment
		(start 70.894448 -234.932982)
		(end 71.277226 -234.550204)
		(width 0.14478)
		(layer "In4.Cu")
		(net "M_D_CPU1_SA_DQ<20>")
	)
	(segment
		(start 38.897814 -222.637096)
		(end 39.060882 -222.800164)
		(width 0.14478)
		(layer "In4.Cu")
		(net "M_D_CPU1_SA_DQ<20>")
	)
	(segment
		(start 90.339672 -238.331756)
		(end 90.348054 -238.32693)
		(width 0.0889)
		(layer "In4.Cu")
		(net "M_D_CPU1_SA_DQ<20>")
	)
	(segment
		(start 69.723762 -233.76255)
		(end 69.723762 -233.990642)
		(width 0.14478)
		(layer "In4.Cu")
		(net "M_D_CPU1_SA_DQ<20>")
	)
	(segment
		(start 49.397158 -222.419926)
		(end 50.247042 -221.570042)
		(width 0.14478)
		(layer "In4.Cu")
		(net "M_D_CPU1_SA_DQ<20>")
	)
	(segment
		(start 79.051658 -238.337852)
		(end 79.070454 -238.32693)
		(width 0.0889)
		(layer "In4.Cu")
		(net "M_D_CPU1_SA_DQ<20>")
	)
	(segment
		(start 79.613252 -238.31423)
		(end 79.634842 -238.326676)
		(width 0.0889)
		(layer "In4.Cu")
		(net "M_D_CPU1_SA_DQ<20>")
	)
	(segment
		(start 73.453752 -236.498638)
		(end 75.95743 -236.498638)
		(width 0.14478)
		(layer "In4.Cu")
		(net "M_D_CPU1_SA_DQ<20>")
	)
	(segment
		(start 85.639656 -238.331756)
		(end 85.648038 -238.32693)
		(width 0.0889)
		(layer "In4.Cu")
		(net "M_D_CPU1_SA_DQ<20>")
	)
	(segment
		(start 39.060882 -222.800164)
		(end 39.29126 -222.800164)
		(width 0.14478)
		(layer "In4.Cu")
		(net "M_D_CPU1_SA_DQ<20>")
	)
	(segment
		(start 69.885814 -234.152694)
		(end 70.11416 -234.152694)
		(width 0.14478)
		(layer "In4.Cu")
		(net "M_D_CPU1_SA_DQ<20>")
	)
	(segment
		(start 73.065894 -236.11078)
		(end 73.453752 -236.498638)
		(width 0.14478)
		(layer "In4.Cu")
		(net "M_D_CPU1_SA_DQ<20>")
	)
	(segment
		(start 38.897814 -222.573342)
		(end 38.897814 -222.637096)
		(width 0.14478)
		(layer "In4.Cu")
		(net "M_D_CPU1_SA_DQ<20>")
	)
	(segment
		(start 71.44639 -235.71327)
		(end 71.674736 -235.71327)
		(width 0.14478)
		(layer "In4.Cu")
		(net "M_D_CPU1_SA_DQ<20>")
	)
	(segment
		(start 72.064626 -236.103414)
		(end 72.064626 -236.331506)
		(width 0.14478)
		(layer "In4.Cu")
		(net "M_D_CPU1_SA_DQ<20>")
	)
	(segment
		(start 59.88431 -222.929196)
		(end 70.106794 -233.15168)
		(width 0.14478)
		(layer "In4.Cu")
		(net "M_D_CPU1_SA_DQ<20>")
	)
	(segment
		(start 70.50405 -234.542838)
		(end 70.50405 -234.77093)
		(width 0.14478)
		(layer "In4.Cu")
		(net "M_D_CPU1_SA_DQ<20>")
	)
	(segment
		(start 42.723562 -221.570042)
		(end 45.568362 -221.570042)
		(width 0.14478)
		(layer "In4.Cu")
		(net "M_D_CPU1_SA_DQ<20>")
	)
	(segment
		(start 39.454328 -222.573342)
		(end 39.607744 -222.419926)
		(width 0.14478)
		(layer "In4.Cu")
		(net "M_D_CPU1_SA_DQ<20>")
	)
	(segment
		(start 71.284338 -235.323126)
		(end 71.284338 -235.551218)
		(width 0.14478)
		(layer "In4.Cu")
		(net "M_D_CPU1_SA_DQ<20>")
	)
	(segment
		(start 37.45103 -222.410274)
		(end 37.614098 -222.247206)
		(width 0.14478)
		(layer "In4.Cu")
		(net "M_D_CPU1_SA_DQ<20>")
	)
	(segment
		(start 81.879694 -238.331756)
		(end 81.888076 -238.32693)
		(width 0.0889)
		(layer "In4.Cu")
		(net "M_D_CPU1_SA_DQ<20>")
	)
	(segment
		(start 77.161644 -237.022386)
		(end 78.38948 -238.250222)
		(width 0.0889)
		(layer "In4.Cu")
		(net "M_D_CPU1_SA_DQ<20>")
	)
	(segment
		(start 71.277226 -234.550204)
		(end 71.505318 -234.550204)
		(width 0.14478)
		(layer "In4.Cu")
		(net "M_D_CPU1_SA_DQ<20>")
	)
	(segment
		(start 39.454328 -222.637096)
		(end 39.454328 -222.573342)
		(width 0.14478)
		(layer "In4.Cu")
		(net "M_D_CPU1_SA_DQ<20>")
	)
	(segment
		(start 90.850974 -238.29518)
		(end 90.946986 -238.26978)
		(width 0.0889)
		(layer "In4.Cu")
		(net "M_D_CPU1_SA_DQ<20>")
	)
	(segment
		(start 41.873678 -222.419926)
		(end 42.723562 -221.570042)
		(width 0.14478)
		(layer "In4.Cu")
		(net "M_D_CPU1_SA_DQ<20>")
	)
	(segment
		(start 39.607744 -222.419926)
		(end 41.873678 -222.419926)
		(width 0.14478)
		(layer "In4.Cu")
		(net "M_D_CPU1_SA_DQ<20>")
	)
	(segment
		(start 54.015894 -222.419926)
		(end 59.70397 -222.419926)
		(width 0.14478)
		(layer "In4.Cu")
		(net "M_D_CPU1_SA_DQ<20>")
	)
	(segment
		(start 88.094058 -238.32693)
		(end 88.10244 -238.331756)
		(width 0.0889)
		(layer "In4.Cu")
		(net "M_D_CPU1_SA_DQ<20>")
	)
	(segment
		(start 70.496938 -233.769916)
		(end 70.72503 -233.769916)
		(width 0.14478)
		(layer "In4.Cu")
		(net "M_D_CPU1_SA_DQ<20>")
	)
	(segment
		(start 71.66737 -234.712256)
		(end 71.66737 -234.940094)
		(width 0.14478)
		(layer "In4.Cu")
		(net "M_D_CPU1_SA_DQ<20>")
	)
	(segment
		(start 38.170612 -222.247206)
		(end 38.343332 -222.419926)
		(width 0.14478)
		(layer "In4.Cu")
		(net "M_D_CPU1_SA_DQ<20>")
	)
	(segment
		(start 53.16601 -221.570042)
		(end 54.015894 -222.419926)
		(width 0.14478)
		(layer "In4.Cu")
		(net "M_D_CPU1_SA_DQ<20>")
	)
	(segment
		(start 59.88431 -222.600266)
		(end 59.88431 -222.929196)
		(width 0.14478)
		(layer "In4.Cu")
		(net "M_D_CPU1_SA_DQ<20>")
	)
	(segment
		(start 70.666102 -234.932982)
		(end 70.894448 -234.932982)
		(width 0.14478)
		(layer "In4.Cu")
		(net "M_D_CPU1_SA_DQ<20>")
	)
	(segment
		(start 69.723762 -233.990642)
		(end 69.885814 -234.152694)
		(width 0.14478)
		(layer "In4.Cu")
		(net "M_D_CPU1_SA_DQ<20>")
	)
	(segment
		(start 78.38948 -238.250222)
		(end 78.41107 -238.250222)
		(width 0.0889)
		(layer "In4.Cu")
		(net "M_D_CPU1_SA_DQ<20>")
	)
	(segment
		(start 83.394042 -238.32693)
		(end 83.402424 -238.331756)
		(width 0.0889)
		(layer "In4.Cu")
		(net "M_D_CPU1_SA_DQ<20>")
	)
	(segment
		(start 71.284338 -235.551218)
		(end 71.44639 -235.71327)
		(width 0.14478)
		(layer "In4.Cu")
		(net "M_D_CPU1_SA_DQ<20>")
	)
	(segment
		(start 38.007544 -221.707964)
		(end 38.170612 -221.871032)
		(width 0.14478)
		(layer "In4.Cu")
		(net "M_D_CPU1_SA_DQ<20>")
	)
	(segment
		(start 70.72503 -233.769916)
		(end 70.887082 -233.931968)
		(width 0.14478)
		(layer "In4.Cu")
		(net "M_D_CPU1_SA_DQ<20>")
	)
	(segment
		(start 36.795964 -221.985332)
		(end 37.220906 -222.410274)
		(width 0.14478)
		(layer "In4.Cu")
		(net "M_D_CPU1_SA_DQ<20>")
	)
	(segment
		(start 59.70397 -222.419926)
		(end 59.88431 -222.600266)
		(width 0.14478)
		(layer "In4.Cu")
		(net "M_D_CPU1_SA_DQ<20>")
	)
	(segment
		(start 76.66355 -237.022386)
		(end 77.161644 -237.022386)
		(width 0.0889)
		(layer "In4.Cu")
		(net "M_D_CPU1_SA_DQ<20>")
	)
	(segment
		(start 39.29126 -222.800164)
		(end 39.454328 -222.637096)
		(width 0.14478)
		(layer "In4.Cu")
		(net "M_D_CPU1_SA_DQ<20>")
	)
	(segment
		(start 75.95743 -236.498638)
		(end 76.139802 -236.498638)
		(width 0.0889)
		(layer "In4.Cu")
		(net "M_D_CPU1_SA_DQ<20>")
	)
	(segment
		(start 71.505318 -234.550204)
		(end 71.66737 -234.712256)
		(width 0.14478)
		(layer "In4.Cu")
		(net "M_D_CPU1_SA_DQ<20>")
	)
	(segment
		(start 86.57971 -238.331756)
		(end 86.588092 -238.32693)
		(width 0.0889)
		(layer "In4.Cu")
		(net "M_D_CPU1_SA_DQ<20>")
	)
	(segment
		(start 70.11416 -234.152694)
		(end 70.496938 -233.769916)
		(width 0.14478)
		(layer "In4.Cu")
		(net "M_D_CPU1_SA_DQ<20>")
	)
	(segment
		(start 72.447658 -235.492544)
		(end 72.447658 -235.720382)
		(width 0.14478)
		(layer "In4.Cu")
		(net "M_D_CPU1_SA_DQ<20>")
	)
	(segment
		(start 37.777166 -221.707964)
		(end 38.007544 -221.707964)
		(width 0.14478)
		(layer "In4.Cu")
		(net "M_D_CPU1_SA_DQ<20>")
	)
	(segment
		(start 38.744398 -222.419926)
		(end 38.897814 -222.573342)
		(width 0.14478)
		(layer "In4.Cu")
		(net "M_D_CPU1_SA_DQ<20>")
	)
	(segment
		(start 82.453988 -238.32693)
		(end 82.46237 -238.331756)
		(width 0.0889)
		(layer "In4.Cu")
		(net "M_D_CPU1_SA_DQ<20>")
	)
	(segment
		(start 79.634842 -238.326676)
		(end 79.654908 -238.338106)
		(width 0.0889)
		(layer "In4.Cu")
		(net "M_D_CPU1_SA_DQ<20>")
	)
	(segment
		(start 72.455024 -236.493558)
		(end 72.837802 -236.11078)
		(width 0.14478)
		(layer "In4.Cu")
		(net "M_D_CPU1_SA_DQ<20>")
	)
	(segment
		(start 72.226678 -236.493558)
		(end 72.455024 -236.493558)
		(width 0.14478)
		(layer "In4.Cu")
		(net "M_D_CPU1_SA_DQ<20>")
	)
	(segment
		(start 38.343332 -222.419926)
		(end 38.744398 -222.419926)
		(width 0.14478)
		(layer "In4.Cu")
		(net "M_D_CPU1_SA_DQ<20>")
	)
	(segment
		(start 71.674736 -235.71327)
		(end 72.057514 -235.330492)
		(width 0.14478)
		(layer "In4.Cu")
		(net "M_D_CPU1_SA_DQ<20>")
	)
	(segment
		(start 72.447658 -235.720382)
		(end 72.064626 -236.103414)
		(width 0.14478)
		(layer "In4.Cu")
		(net "M_D_CPU1_SA_DQ<20>")
	)
	(segment
		(start 90.946986 -238.26978)
		(end 91.10091 -238.00435)
		(width 0.0889)
		(layer "In4.Cu")
		(net "M_D_CPU1_SA_DQ<20>")
	)
	(segment
		(start 76.139802 -236.498638)
		(end 76.66355 -237.022386)
		(width 0.0889)
		(layer "In4.Cu")
		(net "M_D_CPU1_SA_DQ<20>")
	)
	(segment
		(start 50.247042 -221.570042)
		(end 53.16601 -221.570042)
		(width 0.14478)
		(layer "In4.Cu")
		(net "M_D_CPU1_SA_DQ<20>")
	)
	(segment
		(start 37.220906 -222.410274)
		(end 37.45103 -222.410274)
		(width 0.14478)
		(layer "In4.Cu")
		(net "M_D_CPU1_SA_DQ<20>")
	)
	(segment
		(start 72.285606 -235.330492)
		(end 72.447658 -235.492544)
		(width 0.14478)
		(layer "In4.Cu")
		(net "M_D_CPU1_SA_DQ<20>")
	)
	(segment
		(start 72.064626 -236.331506)
		(end 72.226678 -236.493558)
		(width 0.14478)
		(layer "In4.Cu")
		(net "M_D_CPU1_SA_DQ<20>")
	)
	(segment
		(start 70.106794 -233.15168)
		(end 70.106794 -233.379518)
		(width 0.14478)
		(layer "In4.Cu")
		(net "M_D_CPU1_SA_DQ<20>")
	)
	(segment
		(start 70.106794 -233.379518)
		(end 69.723762 -233.76255)
		(width 0.14478)
		(layer "In4.Cu")
		(net "M_D_CPU1_SA_DQ<20>")
	)
	(segment
		(start 45.568362 -221.570042)
		(end 46.418246 -222.419926)
		(width 0.14478)
		(layer "In4.Cu")
		(net "M_D_CPU1_SA_DQ<20>")
	)
	(segment
		(start 87.154004 -238.32693)
		(end 87.162386 -238.331756)
		(width 0.0889)
		(layer "In4.Cu")
		(net "M_D_CPU1_SA_DQ<20>")
	)
	(segment
		(start 37.614098 -221.871032)
		(end 37.777166 -221.707964)
		(width 0.14478)
		(layer "In4.Cu")
		(net "M_D_CPU1_SA_DQ<20>")
	)
	(segment
		(start 70.50405 -234.77093)
		(end 70.666102 -234.932982)
		(width 0.14478)
		(layer "In4.Cu")
		(net "M_D_CPU1_SA_DQ<20>")
	)
	(segment
		(start 71.66737 -234.940094)
		(end 71.284338 -235.323126)
		(width 0.14478)
		(layer "In4.Cu")
		(net "M_D_CPU1_SA_DQ<20>")
	)
	(segment
		(start 46.418246 -222.419926)
		(end 49.397158 -222.419926)
		(width 0.14478)
		(layer "In4.Cu")
		(net "M_D_CPU1_SA_DQ<20>")
	)
	(segment
		(start 70.887082 -233.931968)
		(end 70.887082 -234.159806)
		(width 0.14478)
		(layer "In4.Cu")
		(net "M_D_CPU1_SA_DQ<20>")
	)
	(arc
		(start 80.948022 -238.32693)
		(mid 81.230978 -238.250753)
		(end 81.513934 -238.32693)
		(width 0.0889)
		(layer "In4.Cu")
		(net "M_D_CPU1_SA_DQ<20>")
	)
	(arc
		(start 83.768184 -238.32693)
		(mid 84.05114 -238.250753)
		(end 84.334096 -238.32693)
		(width 0.0889)
		(layer "In4.Cu")
		(net "M_D_CPU1_SA_DQ<20>")
	)
	(arc
		(start 87.162386 -238.331756)
		(mid 87.345894 -238.37725)
		(end 87.528146 -238.32693)
		(width 0.0889)
		(layer "In4.Cu")
		(net "M_D_CPU1_SA_DQ<20>")
	)
	(arc
		(start 88.10244 -238.331756)
		(mid 88.285948 -238.37725)
		(end 88.4682 -238.32693)
		(width 0.0889)
		(layer "In4.Cu")
		(net "M_D_CPU1_SA_DQ<20>")
	)
	(arc
		(start 78.41107 -238.250222)
		(mid 78.558279 -238.269699)
		(end 78.695296 -238.32693)
		(width 0.0889)
		(layer "In4.Cu")
		(net "M_D_CPU1_SA_DQ<20>")
	)
	(arc
		(start 90.348054 -238.32693)
		(mid 90.595767 -238.25171)
		(end 90.850974 -238.29518)
		(width 0.0889)
		(layer "In4.Cu")
		(net "M_D_CPU1_SA_DQ<20>")
	)
	(arc
		(start 84.334096 -238.32693)
		(mid 84.52104 -238.377185)
		(end 84.707984 -238.32693)
		(width 0.0889)
		(layer "In4.Cu")
		(net "M_D_CPU1_SA_DQ<20>")
	)
	(arc
		(start 81.888076 -238.32693)
		(mid 82.171032 -238.250753)
		(end 82.453988 -238.32693)
		(width 0.0889)
		(layer "In4.Cu")
		(net "M_D_CPU1_SA_DQ<20>")
	)
	(arc
		(start 89.973912 -238.32693)
		(mid 90.156163 -238.37728)
		(end 90.339672 -238.331756)
		(width 0.0889)
		(layer "In4.Cu")
		(net "M_D_CPU1_SA_DQ<20>")
	)
	(arc
		(start 89.034112 -238.32693)
		(mid 89.221056 -238.377185)
		(end 89.408 -238.32693)
		(width 0.0889)
		(layer "In4.Cu")
		(net "M_D_CPU1_SA_DQ<20>")
	)
	(arc
		(start 80.008222 -238.32693)
		(mid 80.291178 -238.250753)
		(end 80.574134 -238.32693)
		(width 0.0889)
		(layer "In4.Cu")
		(net "M_D_CPU1_SA_DQ<20>")
	)
	(arc
		(start 85.273896 -238.32693)
		(mid 85.456147 -238.37728)
		(end 85.639656 -238.331756)
		(width 0.0889)
		(layer "In4.Cu")
		(net "M_D_CPU1_SA_DQ<20>")
	)
	(arc
		(start 80.574134 -238.32693)
		(mid 80.761078 -238.377185)
		(end 80.948022 -238.32693)
		(width 0.0889)
		(layer "In4.Cu")
		(net "M_D_CPU1_SA_DQ<20>")
	)
	(arc
		(start 89.408 -238.32693)
		(mid 89.690956 -238.250753)
		(end 89.973912 -238.32693)
		(width 0.0889)
		(layer "In4.Cu")
		(net "M_D_CPU1_SA_DQ<20>")
	)
	(arc
		(start 84.707984 -238.32693)
		(mid 84.99094 -238.250753)
		(end 85.273896 -238.32693)
		(width 0.0889)
		(layer "In4.Cu")
		(net "M_D_CPU1_SA_DQ<20>")
	)
	(arc
		(start 86.588092 -238.32693)
		(mid 86.871048 -238.250753)
		(end 87.154004 -238.32693)
		(width 0.0889)
		(layer "In4.Cu")
		(net "M_D_CPU1_SA_DQ<20>")
	)
	(arc
		(start 83.402424 -238.331756)
		(mid 83.585932 -238.37725)
		(end 83.768184 -238.32693)
		(width 0.0889)
		(layer "In4.Cu")
		(net "M_D_CPU1_SA_DQ<20>")
	)
	(arc
		(start 82.46237 -238.331756)
		(mid 82.645878 -238.37725)
		(end 82.82813 -238.32693)
		(width 0.0889)
		(layer "In4.Cu")
		(net "M_D_CPU1_SA_DQ<20>")
	)
	(arc
		(start 85.648038 -238.32693)
		(mid 85.930994 -238.250753)
		(end 86.21395 -238.32693)
		(width 0.0889)
		(layer "In4.Cu")
		(net "M_D_CPU1_SA_DQ<20>")
	)
	(arc
		(start 82.82813 -238.32693)
		(mid 83.111086 -238.250753)
		(end 83.394042 -238.32693)
		(width 0.0889)
		(layer "In4.Cu")
		(net "M_D_CPU1_SA_DQ<20>")
	)
	(arc
		(start 87.528146 -238.32693)
		(mid 87.811102 -238.250753)
		(end 88.094058 -238.32693)
		(width 0.0889)
		(layer "In4.Cu")
		(net "M_D_CPU1_SA_DQ<20>")
	)
	(arc
		(start 86.21395 -238.32693)
		(mid 86.396201 -238.37728)
		(end 86.57971 -238.331756)
		(width 0.0889)
		(layer "In4.Cu")
		(net "M_D_CPU1_SA_DQ<20>")
	)
	(arc
		(start 78.695296 -238.32693)
		(mid 78.872087 -238.377649)
		(end 79.051658 -238.337852)
		(width 0.0889)
		(layer "In4.Cu")
		(net "M_D_CPU1_SA_DQ<20>")
	)
	(arc
		(start 79.654908 -238.338106)
		(mid 79.832986 -238.37709)
		(end 80.008222 -238.32693)
		(width 0.0889)
		(layer "In4.Cu")
		(net "M_D_CPU1_SA_DQ<20>")
	)
	(arc
		(start 79.070454 -238.32693)
		(mid 79.340223 -238.250907)
		(end 79.613252 -238.31423)
		(width 0.0889)
		(layer "In4.Cu")
		(net "M_D_CPU1_SA_DQ<20>")
	)
	(arc
		(start 88.4682 -238.32693)
		(mid 88.751156 -238.250753)
		(end 89.034112 -238.32693)
		(width 0.0889)
		(layer "In4.Cu")
		(net "M_D_CPU1_SA_DQ<20>")
	)
	(arc
		(start 81.513934 -238.32693)
		(mid 81.696185 -238.37728)
		(end 81.879694 -238.331756)
		(width 0.0889)
		(layer "In4.Cu")
		(net "M_D_CPU1_SA_DQ<20>")
	)
	(segment
		(start 92.97797 -226.120452)
		(end 92.511118 -225.854514)
		(width 0.10668)
		(layer "F.Cu")
		(net "M_D_CPU1_SA_DQ<1>")
	)
	(segment
		(start 38.450774 -199.678036)
		(end 38.450774 -199.359774)
		(width 0.14478)
		(layer "In4.Cu")
		(net "M_D_CPU1_SA_DQ<1>")
	)
	(segment
		(start 39.563802 -199.623426)
		(end 39.72687 -199.460358)
		(width 0.14478)
		(layer "In4.Cu")
		(net "M_D_CPU1_SA_DQ<1>")
	)
	(segment
		(start 50.665634 -198.773542)
		(end 50.665634 -198.837296)
		(width 0.14478)
		(layer "In4.Cu")
		(net "M_D_CPU1_SA_DQ<1>")
	)
	(segment
		(start 80.532986 -221.189804)
		(end 80.532986 -222.000826)
		(width 0.0889)
		(layer "In4.Cu")
		(net "M_D_CPU1_SA_DQ<1>")
	)
	(segment
		(start 54.606698 -199.623426)
		(end 54.606698 -199.690736)
		(width 0.14478)
		(layer "In4.Cu")
		(net "M_D_CPU1_SA_DQ<1>")
	)
	(segment
		(start 38.450774 -199.359774)
		(end 38.613842 -199.196706)
		(width 0.14478)
		(layer "In4.Cu")
		(net "M_D_CPU1_SA_DQ<1>")
	)
	(segment
		(start 43.786806 -198.842376)
		(end 43.786806 -198.773542)
		(width 0.14478)
		(layer "In4.Cu")
		(net "M_D_CPU1_SA_DQ<1>")
	)
	(segment
		(start 45.55871 -198.610474)
		(end 46.408594 -199.460358)
		(width 0.14478)
		(layer "In4.Cu")
		(net "M_D_CPU1_SA_DQ<1>")
	)
	(segment
		(start 55.719726 -199.690736)
		(end 55.882794 -199.853804)
		(width 0.14478)
		(layer "In4.Cu")
		(net "M_D_CPU1_SA_DQ<1>")
	)
	(segment
		(start 41.88333 -199.460358)
		(end 42.733214 -198.610474)
		(width 0.14478)
		(layer "In4.Cu")
		(net "M_D_CPU1_SA_DQ<1>")
	)
	(segment
		(start 89.504012 -226.177094)
		(end 89.512394 -226.18192)
		(width 0.0889)
		(layer "In4.Cu")
		(net "M_D_CPU1_SA_DQ<1>")
	)
	(segment
		(start 41.566846 -199.460358)
		(end 41.88333 -199.460358)
		(width 0.14478)
		(layer "In4.Cu")
		(net "M_D_CPU1_SA_DQ<1>")
	)
	(segment
		(start 46.408594 -199.460358)
		(end 48.27905 -199.460358)
		(width 0.14478)
		(layer "In4.Cu")
		(net "M_D_CPU1_SA_DQ<1>")
	)
	(segment
		(start 81.984088 -224.557082)
		(end 82.02041 -224.578164)
		(width 0.0889)
		(layer "In4.Cu")
		(net "M_D_CPU1_SA_DQ<1>")
	)
	(segment
		(start 48.605186 -199.841104)
		(end 48.835564 -199.841104)
		(width 0.14478)
		(layer "In4.Cu")
		(net "M_D_CPU1_SA_DQ<1>")
	)
	(segment
		(start 48.835564 -199.841104)
		(end 48.998632 -199.678036)
		(width 0.14478)
		(layer "In4.Cu")
		(net "M_D_CPU1_SA_DQ<1>")
	)
	(segment
		(start 92.35694 -226.119944)
		(end 92.511118 -225.854514)
		(width 0.0889)
		(layer "In4.Cu")
		(net "M_D_CPU1_SA_DQ<1>")
	)
	(segment
		(start 40.847264 -199.690736)
		(end 41.000426 -199.843898)
		(width 0.14478)
		(layer "In4.Cu")
		(net "M_D_CPU1_SA_DQ<1>")
	)
	(segment
		(start 56.27624 -199.690736)
		(end 56.27624 -199.623426)
		(width 0.14478)
		(layer "In4.Cu")
		(net "M_D_CPU1_SA_DQ<1>")
	)
	(segment
		(start 48.998632 -199.623426)
		(end 49.1617 -199.460358)
		(width 0.14478)
		(layer "In4.Cu")
		(net "M_D_CPU1_SA_DQ<1>")
	)
	(segment
		(start 48.442118 -199.678036)
		(end 48.605186 -199.841104)
		(width 0.14478)
		(layer "In4.Cu")
		(net "M_D_CPU1_SA_DQ<1>")
	)
	(segment
		(start 81.952338 -224.538794)
		(end 81.984088 -224.557082)
		(width 0.0889)
		(layer "In4.Cu")
		(net "M_D_CPU1_SA_DQ<1>")
	)
	(segment
		(start 43.230292 -198.773542)
		(end 43.230292 -198.842376)
		(width 0.14478)
		(layer "In4.Cu")
		(net "M_D_CPU1_SA_DQ<1>")
	)
	(segment
		(start 81.044034 -222.93707)
		(end 81.08315 -222.95993)
		(width 0.0889)
		(layer "In4.Cu")
		(net "M_D_CPU1_SA_DQ<1>")
	)
	(segment
		(start 92.260674 -226.145344)
		(end 92.35694 -226.119944)
		(width 0.0889)
		(layer "In4.Cu")
		(net "M_D_CPU1_SA_DQ<1>")
	)
	(segment
		(start 51.385216 -198.610474)
		(end 53.23459 -198.610474)
		(width 0.14478)
		(layer "In4.Cu")
		(net "M_D_CPU1_SA_DQ<1>")
	)
	(segment
		(start 39.563802 -199.678036)
		(end 39.563802 -199.623426)
		(width 0.14478)
		(layer "In4.Cu")
		(net "M_D_CPU1_SA_DQ<1>")
	)
	(segment
		(start 54.606698 -199.690736)
		(end 54.769766 -199.853804)
		(width 0.14478)
		(layer "In4.Cu")
		(net "M_D_CPU1_SA_DQ<1>")
	)
	(segment
		(start 85.74405 -226.177094)
		(end 85.752432 -226.18192)
		(width 0.0889)
		(layer "In4.Cu")
		(net "M_D_CPU1_SA_DQ<1>")
	)
	(segment
		(start 48.27905 -199.460358)
		(end 48.442118 -199.623426)
		(width 0.14478)
		(layer "In4.Cu")
		(net "M_D_CPU1_SA_DQ<1>")
	)
	(segment
		(start 84.229702 -226.18192)
		(end 84.238084 -226.177094)
		(width 0.0889)
		(layer "In4.Cu")
		(net "M_D_CPU1_SA_DQ<1>")
	)
	(segment
		(start 54.769766 -199.853804)
		(end 55.000144 -199.853804)
		(width 0.14478)
		(layer "In4.Cu")
		(net "M_D_CPU1_SA_DQ<1>")
	)
	(segment
		(start 41.403778 -199.690736)
		(end 41.403778 -199.623426)
		(width 0.14478)
		(layer "In4.Cu")
		(net "M_D_CPU1_SA_DQ<1>")
	)
	(segment
		(start 43.067224 -198.610474)
		(end 43.230292 -198.773542)
		(width 0.14478)
		(layer "In4.Cu")
		(net "M_D_CPU1_SA_DQ<1>")
	)
	(segment
		(start 82.453988 -225.367088)
		(end 82.493104 -225.389948)
		(width 0.0889)
		(layer "In4.Cu")
		(net "M_D_CPU1_SA_DQ<1>")
	)
	(segment
		(start 50.665634 -198.837296)
		(end 50.828702 -199.000364)
		(width 0.14478)
		(layer "In4.Cu")
		(net "M_D_CPU1_SA_DQ<1>")
	)
	(segment
		(start 50.502566 -198.610474)
		(end 50.665634 -198.773542)
		(width 0.14478)
		(layer "In4.Cu")
		(net "M_D_CPU1_SA_DQ<1>")
	)
	(segment
		(start 54.084474 -199.460358)
		(end 54.44363 -199.460358)
		(width 0.14478)
		(layer "In4.Cu")
		(net "M_D_CPU1_SA_DQ<1>")
	)
	(segment
		(start 55.882794 -199.853804)
		(end 56.113172 -199.853804)
		(width 0.14478)
		(layer "In4.Cu")
		(net "M_D_CPU1_SA_DQ<1>")
	)
	(segment
		(start 55.719726 -199.623426)
		(end 55.719726 -199.690736)
		(width 0.14478)
		(layer "In4.Cu")
		(net "M_D_CPU1_SA_DQ<1>")
	)
	(segment
		(start 38.84422 -199.196706)
		(end 39.007288 -199.359774)
		(width 0.14478)
		(layer "In4.Cu")
		(net "M_D_CPU1_SA_DQ<1>")
	)
	(segment
		(start 84.803996 -226.177094)
		(end 84.812378 -226.18192)
		(width 0.0889)
		(layer "In4.Cu")
		(net "M_D_CPU1_SA_DQ<1>")
	)
	(segment
		(start 56.27624 -199.623426)
		(end 56.439308 -199.460358)
		(width 0.14478)
		(layer "In4.Cu")
		(net "M_D_CPU1_SA_DQ<1>")
	)
	(segment
		(start 41.403778 -199.623426)
		(end 41.566846 -199.460358)
		(width 0.14478)
		(layer "In4.Cu")
		(net "M_D_CPU1_SA_DQ<1>")
	)
	(segment
		(start 48.442118 -199.623426)
		(end 48.442118 -199.678036)
		(width 0.14478)
		(layer "In4.Cu")
		(net "M_D_CPU1_SA_DQ<1>")
	)
	(segment
		(start 88.929718 -226.18192)
		(end 88.9381 -226.177094)
		(width 0.0889)
		(layer "In4.Cu")
		(net "M_D_CPU1_SA_DQ<1>")
	)
	(segment
		(start 38.287706 -199.841104)
		(end 38.450774 -199.678036)
		(width 0.14478)
		(layer "In4.Cu")
		(net "M_D_CPU1_SA_DQ<1>")
	)
	(segment
		(start 60.172092 -199.460358)
		(end 80.532986 -219.821252)
		(width 0.14478)
		(layer "In4.Cu")
		(net "M_D_CPU1_SA_DQ<1>")
	)
	(segment
		(start 43.383708 -198.995792)
		(end 43.63339 -198.995792)
		(width 0.14478)
		(layer "In4.Cu")
		(net "M_D_CPU1_SA_DQ<1>")
	)
	(segment
		(start 53.23459 -198.610474)
		(end 54.084474 -199.460358)
		(width 0.14478)
		(layer "In4.Cu")
		(net "M_D_CPU1_SA_DQ<1>")
	)
	(segment
		(start 37.220906 -199.460358)
		(end 37.731192 -199.460358)
		(width 0.14478)
		(layer "In4.Cu")
		(net "M_D_CPU1_SA_DQ<1>")
	)
	(segment
		(start 51.05908 -199.000364)
		(end 51.222148 -198.837296)
		(width 0.14478)
		(layer "In4.Cu")
		(net "M_D_CPU1_SA_DQ<1>")
	)
	(segment
		(start 41.000426 -199.843898)
		(end 41.250616 -199.843898)
		(width 0.14478)
		(layer "In4.Cu")
		(net "M_D_CPU1_SA_DQ<1>")
	)
	(segment
		(start 49.1617 -199.460358)
		(end 49.40681 -199.460358)
		(width 0.14478)
		(layer "In4.Cu")
		(net "M_D_CPU1_SA_DQ<1>")
	)
	(segment
		(start 82.422238 -225.3488)
		(end 82.453988 -225.367088)
		(width 0.0889)
		(layer "In4.Cu")
		(net "M_D_CPU1_SA_DQ<1>")
	)
	(segment
		(start 49.40681 -199.460358)
		(end 50.256694 -198.610474)
		(width 0.14478)
		(layer "In4.Cu")
		(net "M_D_CPU1_SA_DQ<1>")
	)
	(segment
		(start 50.828702 -199.000364)
		(end 51.05908 -199.000364)
		(width 0.14478)
		(layer "In4.Cu")
		(net "M_D_CPU1_SA_DQ<1>")
	)
	(segment
		(start 43.786806 -198.773542)
		(end 43.949874 -198.610474)
		(width 0.14478)
		(layer "In4.Cu")
		(net "M_D_CPU1_SA_DQ<1>")
	)
	(segment
		(start 39.400734 -199.841104)
		(end 39.563802 -199.678036)
		(width 0.14478)
		(layer "In4.Cu")
		(net "M_D_CPU1_SA_DQ<1>")
	)
	(segment
		(start 41.250616 -199.843898)
		(end 41.403778 -199.690736)
		(width 0.14478)
		(layer "In4.Cu")
		(net "M_D_CPU1_SA_DQ<1>")
	)
	(segment
		(start 81.513934 -223.747076)
		(end 81.55305 -223.769936)
		(width 0.0889)
		(layer "In4.Cu")
		(net "M_D_CPU1_SA_DQ<1>")
	)
	(segment
		(start 40.847264 -199.623426)
		(end 40.847264 -199.690736)
		(width 0.14478)
		(layer "In4.Cu")
		(net "M_D_CPU1_SA_DQ<1>")
	)
	(segment
		(start 40.684196 -199.460358)
		(end 40.847264 -199.623426)
		(width 0.14478)
		(layer "In4.Cu")
		(net "M_D_CPU1_SA_DQ<1>")
	)
	(segment
		(start 54.44363 -199.460358)
		(end 54.606698 -199.623426)
		(width 0.14478)
		(layer "In4.Cu")
		(net "M_D_CPU1_SA_DQ<1>")
	)
	(segment
		(start 39.007288 -199.678036)
		(end 39.170356 -199.841104)
		(width 0.14478)
		(layer "In4.Cu")
		(net "M_D_CPU1_SA_DQ<1>")
	)
	(segment
		(start 55.556658 -199.460358)
		(end 55.719726 -199.623426)
		(width 0.14478)
		(layer "In4.Cu")
		(net "M_D_CPU1_SA_DQ<1>")
	)
	(segment
		(start 48.998632 -199.678036)
		(end 48.998632 -199.623426)
		(width 0.14478)
		(layer "In4.Cu")
		(net "M_D_CPU1_SA_DQ<1>")
	)
	(segment
		(start 56.113172 -199.853804)
		(end 56.27624 -199.690736)
		(width 0.14478)
		(layer "In4.Cu")
		(net "M_D_CPU1_SA_DQ<1>")
	)
	(segment
		(start 42.733214 -198.610474)
		(end 43.067224 -198.610474)
		(width 0.14478)
		(layer "In4.Cu")
		(net "M_D_CPU1_SA_DQ<1>")
	)
	(segment
		(start 51.222148 -198.837296)
		(end 51.222148 -198.773542)
		(width 0.14478)
		(layer "In4.Cu")
		(net "M_D_CPU1_SA_DQ<1>")
	)
	(segment
		(start 36.795964 -199.035416)
		(end 37.220906 -199.460358)
		(width 0.14478)
		(layer "In4.Cu")
		(net "M_D_CPU1_SA_DQ<1>")
	)
	(segment
		(start 81.483454 -223.729296)
		(end 81.513934 -223.747076)
		(width 0.0889)
		(layer "In4.Cu")
		(net "M_D_CPU1_SA_DQ<1>")
	)
	(segment
		(start 39.170356 -199.841104)
		(end 39.400734 -199.841104)
		(width 0.14478)
		(layer "In4.Cu")
		(net "M_D_CPU1_SA_DQ<1>")
	)
	(segment
		(start 91.749626 -226.18192)
		(end 91.758008 -226.177094)
		(width 0.0889)
		(layer "In4.Cu")
		(net "M_D_CPU1_SA_DQ<1>")
	)
	(segment
		(start 37.731192 -199.460358)
		(end 37.89426 -199.623426)
		(width 0.14478)
		(layer "In4.Cu")
		(net "M_D_CPU1_SA_DQ<1>")
	)
	(segment
		(start 39.72687 -199.460358)
		(end 40.684196 -199.460358)
		(width 0.14478)
		(layer "In4.Cu")
		(net "M_D_CPU1_SA_DQ<1>")
	)
	(segment
		(start 56.439308 -199.460358)
		(end 60.172092 -199.460358)
		(width 0.14478)
		(layer "In4.Cu")
		(net "M_D_CPU1_SA_DQ<1>")
	)
	(segment
		(start 43.63339 -198.995792)
		(end 43.786806 -198.842376)
		(width 0.14478)
		(layer "In4.Cu")
		(net "M_D_CPU1_SA_DQ<1>")
	)
	(segment
		(start 55.163212 -199.623426)
		(end 55.32628 -199.460358)
		(width 0.14478)
		(layer "In4.Cu")
		(net "M_D_CPU1_SA_DQ<1>")
	)
	(segment
		(start 38.613842 -199.196706)
		(end 38.84422 -199.196706)
		(width 0.14478)
		(layer "In4.Cu")
		(net "M_D_CPU1_SA_DQ<1>")
	)
	(segment
		(start 55.32628 -199.460358)
		(end 55.556658 -199.460358)
		(width 0.14478)
		(layer "In4.Cu")
		(net "M_D_CPU1_SA_DQ<1>")
	)
	(segment
		(start 83.289648 -226.18192)
		(end 83.29803 -226.177094)
		(width 0.0889)
		(layer "In4.Cu")
		(net "M_D_CPU1_SA_DQ<1>")
	)
	(segment
		(start 50.256694 -198.610474)
		(end 50.502566 -198.610474)
		(width 0.14478)
		(layer "In4.Cu")
		(net "M_D_CPU1_SA_DQ<1>")
	)
	(segment
		(start 37.89426 -199.623426)
		(end 37.89426 -199.678036)
		(width 0.14478)
		(layer "In4.Cu")
		(net "M_D_CPU1_SA_DQ<1>")
	)
	(segment
		(start 55.000144 -199.853804)
		(end 55.163212 -199.690736)
		(width 0.14478)
		(layer "In4.Cu")
		(net "M_D_CPU1_SA_DQ<1>")
	)
	(segment
		(start 37.89426 -199.678036)
		(end 38.057328 -199.841104)
		(width 0.14478)
		(layer "In4.Cu")
		(net "M_D_CPU1_SA_DQ<1>")
	)
	(segment
		(start 51.222148 -198.773542)
		(end 51.385216 -198.610474)
		(width 0.14478)
		(layer "In4.Cu")
		(net "M_D_CPU1_SA_DQ<1>")
	)
	(segment
		(start 39.007288 -199.359774)
		(end 39.007288 -199.678036)
		(width 0.14478)
		(layer "In4.Cu")
		(net "M_D_CPU1_SA_DQ<1>")
	)
	(segment
		(start 87.989664 -226.18192)
		(end 87.998046 -226.177094)
		(width 0.0889)
		(layer "In4.Cu")
		(net "M_D_CPU1_SA_DQ<1>")
	)
	(segment
		(start 55.163212 -199.690736)
		(end 55.163212 -199.623426)
		(width 0.14478)
		(layer "In4.Cu")
		(net "M_D_CPU1_SA_DQ<1>")
	)
	(segment
		(start 43.230292 -198.842376)
		(end 43.383708 -198.995792)
		(width 0.14478)
		(layer "In4.Cu")
		(net "M_D_CPU1_SA_DQ<1>")
	)
	(segment
		(start 82.893408 -226.159314)
		(end 82.923888 -226.177094)
		(width 0.0889)
		(layer "In4.Cu")
		(net "M_D_CPU1_SA_DQ<1>")
	)
	(segment
		(start 38.057328 -199.841104)
		(end 38.287706 -199.841104)
		(width 0.14478)
		(layer "In4.Cu")
		(net "M_D_CPU1_SA_DQ<1>")
	)
	(segment
		(start 43.949874 -198.610474)
		(end 45.55871 -198.610474)
		(width 0.14478)
		(layer "In4.Cu")
		(net "M_D_CPU1_SA_DQ<1>")
	)
	(segment
		(start 81.01457 -222.920052)
		(end 81.044034 -222.93707)
		(width 0.0889)
		(layer "In4.Cu")
		(net "M_D_CPU1_SA_DQ<1>")
	)
	(segment
		(start 80.532986 -219.821252)
		(end 80.532986 -221.189804)
		(width 0.14478)
		(layer "In4.Cu")
		(net "M_D_CPU1_SA_DQ<1>")
	)
	(arc
		(start 81.796382 -224.234502)
		(mid 81.837637 -224.405473)
		(end 81.952338 -224.538794)
		(width 0.0889)
		(layer "In4.Cu")
		(net "M_D_CPU1_SA_DQ<1>")
	)
	(arc
		(start 81.55305 -223.769936)
		(mid 81.731863 -223.972286)
		(end 81.796382 -224.234502)
		(width 0.0889)
		(layer "In4.Cu")
		(net "M_D_CPU1_SA_DQ<1>")
	)
	(arc
		(start 84.812378 -226.18192)
		(mid 84.995886 -226.227414)
		(end 85.178138 -226.177094)
		(width 0.0889)
		(layer "In4.Cu")
		(net "M_D_CPU1_SA_DQ<1>")
	)
	(arc
		(start 87.057992 -226.177094)
		(mid 87.340948 -226.100917)
		(end 87.623904 -226.177094)
		(width 0.0889)
		(layer "In4.Cu")
		(net "M_D_CPU1_SA_DQ<1>")
	)
	(arc
		(start 80.532986 -222.000826)
		(mid 80.553602 -222.084117)
		(end 80.61071 -222.148146)
		(width 0.0889)
		(layer "In4.Cu")
		(net "M_D_CPU1_SA_DQ<1>")
	)
	(arc
		(start 83.863942 -226.177094)
		(mid 84.046193 -226.227444)
		(end 84.229702 -226.18192)
		(width 0.0889)
		(layer "In4.Cu")
		(net "M_D_CPU1_SA_DQ<1>")
	)
	(arc
		(start 89.512394 -226.18192)
		(mid 89.695902 -226.227414)
		(end 89.878154 -226.177094)
		(width 0.0889)
		(layer "In4.Cu")
		(net "M_D_CPU1_SA_DQ<1>")
	)
	(arc
		(start 83.29803 -226.177094)
		(mid 83.580986 -226.100917)
		(end 83.863942 -226.177094)
		(width 0.0889)
		(layer "In4.Cu")
		(net "M_D_CPU1_SA_DQ<1>")
	)
	(arc
		(start 88.9381 -226.177094)
		(mid 89.221056 -226.100917)
		(end 89.504012 -226.177094)
		(width 0.0889)
		(layer "In4.Cu")
		(net "M_D_CPU1_SA_DQ<1>")
	)
	(arc
		(start 81.326482 -223.424496)
		(mid 81.368031 -223.595918)
		(end 81.483454 -223.729296)
		(width 0.0889)
		(layer "In4.Cu")
		(net "M_D_CPU1_SA_DQ<1>")
	)
	(arc
		(start 85.752432 -226.18192)
		(mid 85.93594 -226.227414)
		(end 86.118192 -226.177094)
		(width 0.0889)
		(layer "In4.Cu")
		(net "M_D_CPU1_SA_DQ<1>")
	)
	(arc
		(start 86.118192 -226.177094)
		(mid 86.401148 -226.100917)
		(end 86.684104 -226.177094)
		(width 0.0889)
		(layer "In4.Cu")
		(net "M_D_CPU1_SA_DQ<1>")
	)
	(arc
		(start 81.08315 -222.95993)
		(mid 81.261963 -223.16228)
		(end 81.326482 -223.424496)
		(width 0.0889)
		(layer "In4.Cu")
		(net "M_D_CPU1_SA_DQ<1>")
	)
	(arc
		(start 82.493104 -225.389948)
		(mid 82.671917 -225.592298)
		(end 82.736436 -225.854514)
		(width 0.0889)
		(layer "In4.Cu")
		(net "M_D_CPU1_SA_DQ<1>")
	)
	(arc
		(start 82.923888 -226.177094)
		(mid 83.106139 -226.227444)
		(end 83.289648 -226.18192)
		(width 0.0889)
		(layer "In4.Cu")
		(net "M_D_CPU1_SA_DQ<1>")
	)
	(arc
		(start 85.178138 -226.177094)
		(mid 85.461094 -226.100917)
		(end 85.74405 -226.177094)
		(width 0.0889)
		(layer "In4.Cu")
		(net "M_D_CPU1_SA_DQ<1>")
	)
	(arc
		(start 90.817954 -226.177094)
		(mid 91.10091 -226.100917)
		(end 91.383866 -226.177094)
		(width 0.0889)
		(layer "In4.Cu")
		(net "M_D_CPU1_SA_DQ<1>")
	)
	(arc
		(start 88.563958 -226.177094)
		(mid 88.746209 -226.227444)
		(end 88.929718 -226.18192)
		(width 0.0889)
		(layer "In4.Cu")
		(net "M_D_CPU1_SA_DQ<1>")
	)
	(arc
		(start 91.758008 -226.177094)
		(mid 92.005604 -226.101916)
		(end 92.260674 -226.145344)
		(width 0.0889)
		(layer "In4.Cu")
		(net "M_D_CPU1_SA_DQ<1>")
	)
	(arc
		(start 82.266282 -225.044508)
		(mid 82.307537 -225.215479)
		(end 82.422238 -225.3488)
		(width 0.0889)
		(layer "In4.Cu")
		(net "M_D_CPU1_SA_DQ<1>")
	)
	(arc
		(start 82.736436 -225.854514)
		(mid 82.777985 -226.025936)
		(end 82.893408 -226.159314)
		(width 0.0889)
		(layer "In4.Cu")
		(net "M_D_CPU1_SA_DQ<1>")
	)
	(arc
		(start 86.684104 -226.177094)
		(mid 86.871048 -226.227349)
		(end 87.057992 -226.177094)
		(width 0.0889)
		(layer "In4.Cu")
		(net "M_D_CPU1_SA_DQ<1>")
	)
	(arc
		(start 80.856582 -222.61449)
		(mid 80.898422 -222.786476)
		(end 81.01457 -222.920052)
		(width 0.0889)
		(layer "In4.Cu")
		(net "M_D_CPU1_SA_DQ<1>")
	)
	(arc
		(start 87.998046 -226.177094)
		(mid 88.281002 -226.100917)
		(end 88.563958 -226.177094)
		(width 0.0889)
		(layer "In4.Cu")
		(net "M_D_CPU1_SA_DQ<1>")
	)
	(arc
		(start 91.383866 -226.177094)
		(mid 91.566117 -226.227444)
		(end 91.749626 -226.18192)
		(width 0.0889)
		(layer "In4.Cu")
		(net "M_D_CPU1_SA_DQ<1>")
	)
	(arc
		(start 82.02041 -224.578164)
		(mid 82.201062 -224.780909)
		(end 82.266282 -225.044508)
		(width 0.0889)
		(layer "In4.Cu")
		(net "M_D_CPU1_SA_DQ<1>")
	)
	(arc
		(start 84.238084 -226.177094)
		(mid 84.52104 -226.100917)
		(end 84.803996 -226.177094)
		(width 0.0889)
		(layer "In4.Cu")
		(net "M_D_CPU1_SA_DQ<1>")
	)
	(arc
		(start 89.878154 -226.177094)
		(mid 90.16111 -226.100917)
		(end 90.444066 -226.177094)
		(width 0.0889)
		(layer "In4.Cu")
		(net "M_D_CPU1_SA_DQ<1>")
	)
	(arc
		(start 90.444066 -226.177094)
		(mid 90.63101 -226.227349)
		(end 90.817954 -226.177094)
		(width 0.0889)
		(layer "In4.Cu")
		(net "M_D_CPU1_SA_DQ<1>")
	)
	(arc
		(start 87.623904 -226.177094)
		(mid 87.806155 -226.227444)
		(end 87.989664 -226.18192)
		(width 0.0889)
		(layer "In4.Cu")
		(net "M_D_CPU1_SA_DQ<1>")
	)
	(arc
		(start 80.61071 -222.148146)
		(mid 80.791362 -222.350891)
		(end 80.856582 -222.61449)
		(width 0.0889)
		(layer "In4.Cu")
		(net "M_D_CPU1_SA_DQ<1>")
	)
	(segment
		(start 92.507816 -236.650276)
		(end 92.040964 -236.384338)
		(width 0.10668)
		(layer "F.Cu")
		(net "M_D_CPU1_SA_DQ<19>")
	)
	(segment
		(start 86.57971 -236.056932)
		(end 86.588092 -236.061758)
		(width 0.0889)
		(layer "In4.Cu")
		(net "M_D_CPU1_SA_DQ<19>")
	)
	(segment
		(start 90.913966 -236.061758)
		(end 90.922348 -236.056932)
		(width 0.0889)
		(layer "In4.Cu")
		(net "M_D_CPU1_SA_DQ<19>")
	)
	(segment
		(start 76.46797 -234.502706)
		(end 76.96073 -234.502706)
		(width 0.0889)
		(layer "In4.Cu")
		(net "M_D_CPU1_SA_DQ<19>")
	)
	(segment
		(start 92.195142 -236.118908)
		(end 92.040964 -236.384338)
		(width 0.0889)
		(layer "In4.Cu")
		(net "M_D_CPU1_SA_DQ<19>")
	)
	(segment
		(start 77.32649 -235.285026)
		(end 78.179676 -236.138212)
		(width 0.0889)
		(layer "In4.Cu")
		(net "M_D_CPU1_SA_DQ<19>")
	)
	(segment
		(start 45.557948 -218.150694)
		(end 46.407832 -219.000578)
		(width 0.14478)
		(layer "In4.Cu")
		(net "M_D_CPU1_SA_DQ<19>")
	)
	(segment
		(start 88.094058 -236.061758)
		(end 88.10244 -236.056932)
		(width 0.0889)
		(layer "In4.Cu")
		(net "M_D_CPU1_SA_DQ<19>")
	)
	(segment
		(start 60.836048 -219.010484)
		(end 67.80911 -225.983546)
		(width 0.14478)
		(layer "In4.Cu")
		(net "M_D_CPU1_SA_DQ<19>")
	)
	(segment
		(start 76.96073 -234.502706)
		(end 77.32649 -234.868466)
		(width 0.0889)
		(layer "In4.Cu")
		(net "M_D_CPU1_SA_DQ<19>")
	)
	(segment
		(start 32.695896 -218.585288)
		(end 33.111186 -219.000578)
		(width 0.14478)
		(layer "In4.Cu")
		(net "M_D_CPU1_SA_DQ<19>")
	)
	(segment
		(start 41.893998 -219.000578)
		(end 42.743882 -218.150694)
		(width 0.14478)
		(layer "In4.Cu")
		(net "M_D_CPU1_SA_DQ<19>")
	)
	(segment
		(start 78.179676 -236.138212)
		(end 79.350108 -236.138212)
		(width 0.0889)
		(layer "In4.Cu")
		(net "M_D_CPU1_SA_DQ<19>")
	)
	(segment
		(start 77.32649 -234.868466)
		(end 77.32649 -235.285026)
		(width 0.0889)
		(layer "In4.Cu")
		(net "M_D_CPU1_SA_DQ<19>")
	)
	(segment
		(start 74.402696 -234.159298)
		(end 75.93965 -234.159298)
		(width 0.14478)
		(layer "In4.Cu")
		(net "M_D_CPU1_SA_DQ<19>")
	)
	(segment
		(start 67.80911 -227.565712)
		(end 74.402696 -234.159298)
		(width 0.14478)
		(layer "In4.Cu")
		(net "M_D_CPU1_SA_DQ<19>")
	)
	(segment
		(start 75.93965 -234.159298)
		(end 76.124562 -234.159298)
		(width 0.0889)
		(layer "In4.Cu")
		(net "M_D_CPU1_SA_DQ<19>")
	)
	(segment
		(start 54.106572 -219.010484)
		(end 60.836048 -219.010484)
		(width 0.14478)
		(layer "In4.Cu")
		(net "M_D_CPU1_SA_DQ<19>")
	)
	(segment
		(start 46.407832 -219.000578)
		(end 49.382172 -219.000578)
		(width 0.14478)
		(layer "In4.Cu")
		(net "M_D_CPU1_SA_DQ<19>")
	)
	(segment
		(start 50.232056 -218.150694)
		(end 53.246782 -218.150694)
		(width 0.14478)
		(layer "In4.Cu")
		(net "M_D_CPU1_SA_DQ<19>")
	)
	(segment
		(start 33.111186 -219.000578)
		(end 41.893998 -219.000578)
		(width 0.14478)
		(layer "In4.Cu")
		(net "M_D_CPU1_SA_DQ<19>")
	)
	(segment
		(start 91.85402 -236.061758)
		(end 91.862402 -236.056932)
		(width 0.0889)
		(layer "In4.Cu")
		(net "M_D_CPU1_SA_DQ<19>")
	)
	(segment
		(start 49.382172 -219.000578)
		(end 50.232056 -218.150694)
		(width 0.14478)
		(layer "In4.Cu")
		(net "M_D_CPU1_SA_DQ<19>")
	)
	(segment
		(start 85.639656 -236.056932)
		(end 85.648038 -236.061758)
		(width 0.0889)
		(layer "In4.Cu")
		(net "M_D_CPU1_SA_DQ<19>")
	)
	(segment
		(start 90.339672 -236.056932)
		(end 90.348054 -236.061758)
		(width 0.0889)
		(layer "In4.Cu")
		(net "M_D_CPU1_SA_DQ<19>")
	)
	(segment
		(start 79.99984 -236.056932)
		(end 80.008222 -236.061758)
		(width 0.0889)
		(layer "In4.Cu")
		(net "M_D_CPU1_SA_DQ<19>")
	)
	(segment
		(start 82.453988 -236.061758)
		(end 82.46237 -236.056932)
		(width 0.0889)
		(layer "In4.Cu")
		(net "M_D_CPU1_SA_DQ<19>")
	)
	(segment
		(start 83.394042 -236.061758)
		(end 83.402424 -236.056932)
		(width 0.0889)
		(layer "In4.Cu")
		(net "M_D_CPU1_SA_DQ<19>")
	)
	(segment
		(start 87.154004 -236.061758)
		(end 87.162386 -236.056932)
		(width 0.0889)
		(layer "In4.Cu")
		(net "M_D_CPU1_SA_DQ<19>")
	)
	(segment
		(start 67.80911 -225.983546)
		(end 67.80911 -227.565712)
		(width 0.14478)
		(layer "In4.Cu")
		(net "M_D_CPU1_SA_DQ<19>")
	)
	(segment
		(start 81.879694 -236.056932)
		(end 81.888076 -236.061758)
		(width 0.0889)
		(layer "In4.Cu")
		(net "M_D_CPU1_SA_DQ<19>")
	)
	(segment
		(start 42.743882 -218.150694)
		(end 45.557948 -218.150694)
		(width 0.14478)
		(layer "In4.Cu")
		(net "M_D_CPU1_SA_DQ<19>")
	)
	(segment
		(start 92.17279 -236.035596)
		(end 92.195142 -236.118908)
		(width 0.0889)
		(layer "In4.Cu")
		(net "M_D_CPU1_SA_DQ<19>")
	)
	(segment
		(start 76.124562 -234.159298)
		(end 76.46797 -234.502706)
		(width 0.0889)
		(layer "In4.Cu")
		(net "M_D_CPU1_SA_DQ<19>")
	)
	(segment
		(start 53.246782 -218.150694)
		(end 54.106572 -219.010484)
		(width 0.14478)
		(layer "In4.Cu")
		(net "M_D_CPU1_SA_DQ<19>")
	)
	(arc
		(start 85.648038 -236.061758)
		(mid 85.930994 -236.137935)
		(end 86.21395 -236.061758)
		(width 0.0889)
		(layer "In4.Cu")
		(net "M_D_CPU1_SA_DQ<19>")
	)
	(arc
		(start 88.10244 -236.056932)
		(mid 88.285948 -236.011438)
		(end 88.4682 -236.061758)
		(width 0.0889)
		(layer "In4.Cu")
		(net "M_D_CPU1_SA_DQ<19>")
	)
	(arc
		(start 79.633572 -236.061758)
		(mid 79.816077 -236.011281)
		(end 79.99984 -236.056932)
		(width 0.0889)
		(layer "In4.Cu")
		(net "M_D_CPU1_SA_DQ<19>")
	)
	(arc
		(start 91.862402 -236.056932)
		(mid 92.015272 -236.012291)
		(end 92.17279 -236.035596)
		(width 0.0889)
		(layer "In4.Cu")
		(net "M_D_CPU1_SA_DQ<19>")
	)
	(arc
		(start 83.768184 -236.061758)
		(mid 84.05114 -236.137935)
		(end 84.334096 -236.061758)
		(width 0.0889)
		(layer "In4.Cu")
		(net "M_D_CPU1_SA_DQ<19>")
	)
	(arc
		(start 89.408 -236.061758)
		(mid 89.690956 -236.137935)
		(end 89.973912 -236.061758)
		(width 0.0889)
		(layer "In4.Cu")
		(net "M_D_CPU1_SA_DQ<19>")
	)
	(arc
		(start 84.707984 -236.061758)
		(mid 84.99094 -236.137935)
		(end 85.273896 -236.061758)
		(width 0.0889)
		(layer "In4.Cu")
		(net "M_D_CPU1_SA_DQ<19>")
	)
	(arc
		(start 88.4682 -236.061758)
		(mid 88.751156 -236.137935)
		(end 89.034112 -236.061758)
		(width 0.0889)
		(layer "In4.Cu")
		(net "M_D_CPU1_SA_DQ<19>")
	)
	(arc
		(start 84.334096 -236.061758)
		(mid 84.52104 -236.011503)
		(end 84.707984 -236.061758)
		(width 0.0889)
		(layer "In4.Cu")
		(net "M_D_CPU1_SA_DQ<19>")
	)
	(arc
		(start 82.82813 -236.061758)
		(mid 83.111086 -236.137935)
		(end 83.394042 -236.061758)
		(width 0.0889)
		(layer "In4.Cu")
		(net "M_D_CPU1_SA_DQ<19>")
	)
	(arc
		(start 87.162386 -236.056932)
		(mid 87.345894 -236.011438)
		(end 87.528146 -236.061758)
		(width 0.0889)
		(layer "In4.Cu")
		(net "M_D_CPU1_SA_DQ<19>")
	)
	(arc
		(start 86.21395 -236.061758)
		(mid 86.396201 -236.011408)
		(end 86.57971 -236.056932)
		(width 0.0889)
		(layer "In4.Cu")
		(net "M_D_CPU1_SA_DQ<19>")
	)
	(arc
		(start 81.513934 -236.061758)
		(mid 81.696185 -236.011408)
		(end 81.879694 -236.056932)
		(width 0.0889)
		(layer "In4.Cu")
		(net "M_D_CPU1_SA_DQ<19>")
	)
	(arc
		(start 90.922348 -236.056932)
		(mid 91.105856 -236.011438)
		(end 91.288108 -236.061758)
		(width 0.0889)
		(layer "In4.Cu")
		(net "M_D_CPU1_SA_DQ<19>")
	)
	(arc
		(start 82.46237 -236.056932)
		(mid 82.645878 -236.011438)
		(end 82.82813 -236.061758)
		(width 0.0889)
		(layer "In4.Cu")
		(net "M_D_CPU1_SA_DQ<19>")
	)
	(arc
		(start 83.402424 -236.056932)
		(mid 83.585932 -236.011438)
		(end 83.768184 -236.061758)
		(width 0.0889)
		(layer "In4.Cu")
		(net "M_D_CPU1_SA_DQ<19>")
	)
	(arc
		(start 86.588092 -236.061758)
		(mid 86.871048 -236.137935)
		(end 87.154004 -236.061758)
		(width 0.0889)
		(layer "In4.Cu")
		(net "M_D_CPU1_SA_DQ<19>")
	)
	(arc
		(start 91.288108 -236.061758)
		(mid 91.571064 -236.137935)
		(end 91.85402 -236.061758)
		(width 0.0889)
		(layer "In4.Cu")
		(net "M_D_CPU1_SA_DQ<19>")
	)
	(arc
		(start 87.528146 -236.061758)
		(mid 87.811102 -236.137935)
		(end 88.094058 -236.061758)
		(width 0.0889)
		(layer "In4.Cu")
		(net "M_D_CPU1_SA_DQ<19>")
	)
	(arc
		(start 89.973912 -236.061758)
		(mid 90.156163 -236.011408)
		(end 90.339672 -236.056932)
		(width 0.0889)
		(layer "In4.Cu")
		(net "M_D_CPU1_SA_DQ<19>")
	)
	(arc
		(start 80.574134 -236.061758)
		(mid 80.761078 -236.011503)
		(end 80.948022 -236.061758)
		(width 0.0889)
		(layer "In4.Cu")
		(net "M_D_CPU1_SA_DQ<19>")
	)
	(arc
		(start 90.348054 -236.061758)
		(mid 90.63101 -236.137935)
		(end 90.913966 -236.061758)
		(width 0.0889)
		(layer "In4.Cu")
		(net "M_D_CPU1_SA_DQ<19>")
	)
	(arc
		(start 80.948022 -236.061758)
		(mid 81.230978 -236.137935)
		(end 81.513934 -236.061758)
		(width 0.0889)
		(layer "In4.Cu")
		(net "M_D_CPU1_SA_DQ<19>")
	)
	(arc
		(start 80.008222 -236.061758)
		(mid 80.291178 -236.137935)
		(end 80.574134 -236.061758)
		(width 0.0889)
		(layer "In4.Cu")
		(net "M_D_CPU1_SA_DQ<19>")
	)
	(arc
		(start 85.273896 -236.061758)
		(mid 85.456147 -236.011408)
		(end 85.639656 -236.056932)
		(width 0.0889)
		(layer "In4.Cu")
		(net "M_D_CPU1_SA_DQ<19>")
	)
	(arc
		(start 89.034112 -236.061758)
		(mid 89.221056 -236.011503)
		(end 89.408 -236.061758)
		(width 0.0889)
		(layer "In4.Cu")
		(net "M_D_CPU1_SA_DQ<19>")
	)
	(arc
		(start 79.350108 -236.138212)
		(mid 79.496912 -236.118776)
		(end 79.633572 -236.061758)
		(width 0.0889)
		(layer "In4.Cu")
		(net "M_D_CPU1_SA_DQ<19>")
	)
	(arc
		(start 81.888076 -236.061758)
		(mid 82.171032 -236.137935)
		(end 82.453988 -236.061758)
		(width 0.0889)
		(layer "In4.Cu")
		(net "M_D_CPU1_SA_DQ<19>")
	)
	(segment
		(start 91.097862 -235.84027)
		(end 90.63101 -235.574332)
		(width 0.10668)
		(layer "F.Cu")
		(net "M_D_CPU1_SA_DQ<18>")
	)
	(segment
		(start 76.78293 -233.918506)
		(end 77.26299 -233.918506)
		(width 0.0889)
		(layer "In4.Cu")
		(net "M_D_CPU1_SA_DQ<18>")
	)
	(segment
		(start 53.256434 -216.460324)
		(end 54.106572 -217.310462)
		(width 0.14478)
		(layer "In4.Cu")
		(net "M_D_CPU1_SA_DQ<18>")
	)
	(segment
		(start 34.90468 -217.318336)
		(end 35.04946 -217.173556)
		(width 0.14478)
		(layer "In4.Cu")
		(net "M_D_CPU1_SA_DQ<18>")
	)
	(segment
		(start 78.35265 -234.614466)
		(end 78.954376 -235.216192)
		(width 0.0889)
		(layer "In4.Cu")
		(net "M_D_CPU1_SA_DQ<18>")
	)
	(segment
		(start 74.779632 -233.247438)
		(end 75.92695 -233.247438)
		(width 0.14478)
		(layer "In4.Cu")
		(net "M_D_CPU1_SA_DQ<18>")
	)
	(segment
		(start 84.229702 -235.246926)
		(end 84.238084 -235.251752)
		(width 0.0889)
		(layer "In4.Cu")
		(net "M_D_CPU1_SA_DQ<18>")
	)
	(segment
		(start 60.440824 -217.310462)
		(end 68.73621 -225.605848)
		(width 0.14478)
		(layer "In4.Cu")
		(net "M_D_CPU1_SA_DQ<18>")
	)
	(segment
		(start 35.605974 -216.562432)
		(end 35.605974 -217.147394)
		(width 0.14478)
		(layer "In4.Cu")
		(net "M_D_CPU1_SA_DQ<18>")
	)
	(segment
		(start 42.73423 -216.460324)
		(end 45.5676 -216.460324)
		(width 0.14478)
		(layer "In4.Cu")
		(net "M_D_CPU1_SA_DQ<18>")
	)
	(segment
		(start 77.95895 -234.614466)
		(end 78.35265 -234.614466)
		(width 0.0889)
		(layer "In4.Cu")
		(net "M_D_CPU1_SA_DQ<18>")
	)
	(segment
		(start 35.212528 -216.399364)
		(end 35.442906 -216.399364)
		(width 0.14478)
		(layer "In4.Cu")
		(net "M_D_CPU1_SA_DQ<18>")
	)
	(segment
		(start 83.289648 -235.246926)
		(end 83.29803 -235.251752)
		(width 0.0889)
		(layer "In4.Cu")
		(net "M_D_CPU1_SA_DQ<18>")
	)
	(segment
		(start 76.111862 -233.247438)
		(end 76.78293 -233.918506)
		(width 0.0889)
		(layer "In4.Cu")
		(net "M_D_CPU1_SA_DQ<18>")
	)
	(segment
		(start 80.46974 -235.246926)
		(end 80.478122 -235.251752)
		(width 0.0889)
		(layer "In4.Cu")
		(net "M_D_CPU1_SA_DQ<18>")
	)
	(segment
		(start 35.04946 -217.173556)
		(end 35.04946 -216.562432)
		(width 0.14478)
		(layer "In4.Cu")
		(net "M_D_CPU1_SA_DQ<18>")
	)
	(segment
		(start 90.762582 -235.22559)
		(end 90.784934 -235.308902)
		(width 0.0889)
		(layer "In4.Cu")
		(net "M_D_CPU1_SA_DQ<18>")
	)
	(segment
		(start 54.106572 -217.310462)
		(end 60.440824 -217.310462)
		(width 0.14478)
		(layer "In4.Cu")
		(net "M_D_CPU1_SA_DQ<18>")
	)
	(segment
		(start 45.5676 -216.460324)
		(end 46.417738 -217.310462)
		(width 0.14478)
		(layer "In4.Cu")
		(net "M_D_CPU1_SA_DQ<18>")
	)
	(segment
		(start 35.769042 -217.310462)
		(end 41.884092 -217.310462)
		(width 0.14478)
		(layer "In4.Cu")
		(net "M_D_CPU1_SA_DQ<18>")
	)
	(segment
		(start 32.695896 -216.885266)
		(end 33.128966 -217.318336)
		(width 0.14478)
		(layer "In4.Cu")
		(net "M_D_CPU1_SA_DQ<18>")
	)
	(segment
		(start 81.044034 -235.251752)
		(end 81.052416 -235.246926)
		(width 0.0889)
		(layer "In4.Cu")
		(net "M_D_CPU1_SA_DQ<18>")
	)
	(segment
		(start 90.784934 -235.308902)
		(end 90.63101 -235.574332)
		(width 0.0889)
		(layer "In4.Cu")
		(net "M_D_CPU1_SA_DQ<18>")
	)
	(segment
		(start 68.73621 -227.204016)
		(end 74.779632 -233.247438)
		(width 0.14478)
		(layer "In4.Cu")
		(net "M_D_CPU1_SA_DQ<18>")
	)
	(segment
		(start 77.26299 -233.918506)
		(end 77.95895 -234.614466)
		(width 0.0889)
		(layer "In4.Cu")
		(net "M_D_CPU1_SA_DQ<18>")
	)
	(segment
		(start 68.73621 -225.605848)
		(end 68.73621 -227.204016)
		(width 0.14478)
		(layer "In4.Cu")
		(net "M_D_CPU1_SA_DQ<18>")
	)
	(segment
		(start 35.605974 -217.147394)
		(end 35.769042 -217.310462)
		(width 0.14478)
		(layer "In4.Cu")
		(net "M_D_CPU1_SA_DQ<18>")
	)
	(segment
		(start 84.803996 -235.251752)
		(end 84.812378 -235.246926)
		(width 0.0889)
		(layer "In4.Cu")
		(net "M_D_CPU1_SA_DQ<18>")
	)
	(segment
		(start 88.929718 -235.246926)
		(end 88.9381 -235.251752)
		(width 0.0889)
		(layer "In4.Cu")
		(net "M_D_CPU1_SA_DQ<18>")
	)
	(segment
		(start 50.222404 -216.460324)
		(end 53.256434 -216.460324)
		(width 0.14478)
		(layer "In4.Cu")
		(net "M_D_CPU1_SA_DQ<18>")
	)
	(segment
		(start 35.442906 -216.399364)
		(end 35.605974 -216.562432)
		(width 0.14478)
		(layer "In4.Cu")
		(net "M_D_CPU1_SA_DQ<18>")
	)
	(segment
		(start 89.504012 -235.251752)
		(end 89.512394 -235.246926)
		(width 0.0889)
		(layer "In4.Cu")
		(net "M_D_CPU1_SA_DQ<18>")
	)
	(segment
		(start 41.884092 -217.310462)
		(end 42.73423 -216.460324)
		(width 0.14478)
		(layer "In4.Cu")
		(net "M_D_CPU1_SA_DQ<18>")
	)
	(segment
		(start 35.04946 -216.562432)
		(end 35.212528 -216.399364)
		(width 0.14478)
		(layer "In4.Cu")
		(net "M_D_CPU1_SA_DQ<18>")
	)
	(segment
		(start 75.92695 -233.247438)
		(end 76.111862 -233.247438)
		(width 0.0889)
		(layer "In4.Cu")
		(net "M_D_CPU1_SA_DQ<18>")
	)
	(segment
		(start 78.954376 -235.216192)
		(end 79.45501 -235.216192)
		(width 0.0889)
		(layer "In4.Cu")
		(net "M_D_CPU1_SA_DQ<18>")
	)
	(segment
		(start 85.74405 -235.251752)
		(end 85.752432 -235.246926)
		(width 0.0889)
		(layer "In4.Cu")
		(net "M_D_CPU1_SA_DQ<18>")
	)
	(segment
		(start 33.128966 -217.318336)
		(end 34.90468 -217.318336)
		(width 0.14478)
		(layer "In4.Cu")
		(net "M_D_CPU1_SA_DQ<18>")
	)
	(segment
		(start 87.989664 -235.246926)
		(end 87.998046 -235.251752)
		(width 0.0889)
		(layer "In4.Cu")
		(net "M_D_CPU1_SA_DQ<18>")
	)
	(segment
		(start 79.539592 -235.252006)
		(end 79.561182 -235.264452)
		(width 0.0889)
		(layer "In4.Cu")
		(net "M_D_CPU1_SA_DQ<18>")
	)
	(segment
		(start 46.417738 -217.310462)
		(end 49.372266 -217.310462)
		(width 0.14478)
		(layer "In4.Cu")
		(net "M_D_CPU1_SA_DQ<18>")
	)
	(segment
		(start 49.372266 -217.310462)
		(end 50.222404 -216.460324)
		(width 0.14478)
		(layer "In4.Cu")
		(net "M_D_CPU1_SA_DQ<18>")
	)
	(arc
		(start 81.984088 -235.251752)
		(mid 82.171032 -235.201497)
		(end 82.357976 -235.251752)
		(width 0.0889)
		(layer "In4.Cu")
		(net "M_D_CPU1_SA_DQ<18>")
	)
	(arc
		(start 85.178138 -235.251752)
		(mid 85.461094 -235.327929)
		(end 85.74405 -235.251752)
		(width 0.0889)
		(layer "In4.Cu")
		(net "M_D_CPU1_SA_DQ<18>")
	)
	(arc
		(start 88.563958 -235.251752)
		(mid 88.746209 -235.201402)
		(end 88.929718 -235.246926)
		(width 0.0889)
		(layer "In4.Cu")
		(net "M_D_CPU1_SA_DQ<18>")
	)
	(arc
		(start 79.45501 -235.216192)
		(mid 79.49841 -235.23148)
		(end 79.539592 -235.252006)
		(width 0.0889)
		(layer "In4.Cu")
		(net "M_D_CPU1_SA_DQ<18>")
	)
	(arc
		(start 89.512394 -235.246926)
		(mid 89.695902 -235.201432)
		(end 89.878154 -235.251752)
		(width 0.0889)
		(layer "In4.Cu")
		(net "M_D_CPU1_SA_DQ<18>")
	)
	(arc
		(start 89.878154 -235.251752)
		(mid 90.16111 -235.327929)
		(end 90.444066 -235.251752)
		(width 0.0889)
		(layer "In4.Cu")
		(net "M_D_CPU1_SA_DQ<18>")
	)
	(arc
		(start 83.863942 -235.251752)
		(mid 84.046193 -235.201402)
		(end 84.229702 -235.246926)
		(width 0.0889)
		(layer "In4.Cu")
		(net "M_D_CPU1_SA_DQ<18>")
	)
	(arc
		(start 79.561182 -235.264452)
		(mid 79.834211 -235.327771)
		(end 80.10398 -235.251752)
		(width 0.0889)
		(layer "In4.Cu")
		(net "M_D_CPU1_SA_DQ<18>")
	)
	(arc
		(start 87.998046 -235.251752)
		(mid 88.281002 -235.327929)
		(end 88.563958 -235.251752)
		(width 0.0889)
		(layer "In4.Cu")
		(net "M_D_CPU1_SA_DQ<18>")
	)
	(arc
		(start 84.812378 -235.246926)
		(mid 84.995886 -235.201432)
		(end 85.178138 -235.251752)
		(width 0.0889)
		(layer "In4.Cu")
		(net "M_D_CPU1_SA_DQ<18>")
	)
	(arc
		(start 81.052416 -235.246926)
		(mid 81.235924 -235.201432)
		(end 81.418176 -235.251752)
		(width 0.0889)
		(layer "In4.Cu")
		(net "M_D_CPU1_SA_DQ<18>")
	)
	(arc
		(start 84.238084 -235.251752)
		(mid 84.52104 -235.327929)
		(end 84.803996 -235.251752)
		(width 0.0889)
		(layer "In4.Cu")
		(net "M_D_CPU1_SA_DQ<18>")
	)
	(arc
		(start 80.478122 -235.251752)
		(mid 80.761078 -235.327929)
		(end 81.044034 -235.251752)
		(width 0.0889)
		(layer "In4.Cu")
		(net "M_D_CPU1_SA_DQ<18>")
	)
	(arc
		(start 85.752432 -235.246926)
		(mid 85.93594 -235.201432)
		(end 86.118192 -235.251752)
		(width 0.0889)
		(layer "In4.Cu")
		(net "M_D_CPU1_SA_DQ<18>")
	)
	(arc
		(start 87.623904 -235.251752)
		(mid 87.806155 -235.201402)
		(end 87.989664 -235.246926)
		(width 0.0889)
		(layer "In4.Cu")
		(net "M_D_CPU1_SA_DQ<18>")
	)
	(arc
		(start 86.118192 -235.251752)
		(mid 86.401148 -235.327929)
		(end 86.684104 -235.251752)
		(width 0.0889)
		(layer "In4.Cu")
		(net "M_D_CPU1_SA_DQ<18>")
	)
	(arc
		(start 83.29803 -235.251752)
		(mid 83.580986 -235.327929)
		(end 83.863942 -235.251752)
		(width 0.0889)
		(layer "In4.Cu")
		(net "M_D_CPU1_SA_DQ<18>")
	)
	(arc
		(start 86.684104 -235.251752)
		(mid 86.871048 -235.201497)
		(end 87.057992 -235.251752)
		(width 0.0889)
		(layer "In4.Cu")
		(net "M_D_CPU1_SA_DQ<18>")
	)
	(arc
		(start 88.9381 -235.251752)
		(mid 89.221056 -235.327929)
		(end 89.504012 -235.251752)
		(width 0.0889)
		(layer "In4.Cu")
		(net "M_D_CPU1_SA_DQ<18>")
	)
	(arc
		(start 81.418176 -235.251752)
		(mid 81.701132 -235.327929)
		(end 81.984088 -235.251752)
		(width 0.0889)
		(layer "In4.Cu")
		(net "M_D_CPU1_SA_DQ<18>")
	)
	(arc
		(start 82.357976 -235.251752)
		(mid 82.640932 -235.327929)
		(end 82.923888 -235.251752)
		(width 0.0889)
		(layer "In4.Cu")
		(net "M_D_CPU1_SA_DQ<18>")
	)
	(arc
		(start 80.10398 -235.251752)
		(mid 80.286231 -235.201402)
		(end 80.46974 -235.246926)
		(width 0.0889)
		(layer "In4.Cu")
		(net "M_D_CPU1_SA_DQ<18>")
	)
	(arc
		(start 87.057992 -235.251752)
		(mid 87.340948 -235.327929)
		(end 87.623904 -235.251752)
		(width 0.0889)
		(layer "In4.Cu")
		(net "M_D_CPU1_SA_DQ<18>")
	)
	(arc
		(start 90.444066 -235.251752)
		(mid 90.600385 -235.202757)
		(end 90.762582 -235.22559)
		(width 0.0889)
		(layer "In4.Cu")
		(net "M_D_CPU1_SA_DQ<18>")
	)
	(arc
		(start 82.923888 -235.251752)
		(mid 83.106139 -235.201402)
		(end 83.289648 -235.246926)
		(width 0.0889)
		(layer "In4.Cu")
		(net "M_D_CPU1_SA_DQ<18>")
	)
	(segment
		(start 92.97797 -235.84027)
		(end 92.511118 -235.574332)
		(width 0.10668)
		(layer "F.Cu")
		(net "M_D_CPU1_SA_DQ<17>")
	)
	(segment
		(start 50.256694 -217.310462)
		(end 50.585624 -217.310462)
		(width 0.14478)
		(layer "In4.Cu")
		(net "M_D_CPU1_SA_DQ<17>")
	)
	(segment
		(start 41.165272 -218.548966)
		(end 41.404286 -218.548966)
		(width 0.14478)
		(layer "In4.Cu")
		(net "M_D_CPU1_SA_DQ<17>")
	)
	(segment
		(start 43.217592 -217.47353)
		(end 43.217592 -217.536776)
		(width 0.14478)
		(layer "In4.Cu")
		(net "M_D_CPU1_SA_DQ<17>")
	)
	(segment
		(start 48.342804 -218.160346)
		(end 48.505872 -218.323414)
		(width 0.14478)
		(layer "In4.Cu")
		(net "M_D_CPU1_SA_DQ<17>")
	)
	(segment
		(start 75.93965 -233.702098)
		(end 76.205842 -233.702098)
		(width 0.0889)
		(layer "In4.Cu")
		(net "M_D_CPU1_SA_DQ<17>")
	)
	(segment
		(start 51.151536 -217.695526)
		(end 51.305206 -217.541856)
		(width 0.14478)
		(layer "In4.Cu")
		(net "M_D_CPU1_SA_DQ<17>")
	)
	(segment
		(start 55.056532 -218.553284)
		(end 55.28691 -218.553284)
		(width 0.14478)
		(layer "In4.Cu")
		(net "M_D_CPU1_SA_DQ<17>")
	)
	(segment
		(start 77.03693 -234.172506)
		(end 77.59573 -234.731306)
		(width 0.0889)
		(layer "In4.Cu")
		(net "M_D_CPU1_SA_DQ<17>")
	)
	(segment
		(start 41.726104 -218.160346)
		(end 41.88333 -218.160346)
		(width 0.14478)
		(layer "In4.Cu")
		(net "M_D_CPU1_SA_DQ<17>")
	)
	(segment
		(start 36.795964 -217.735404)
		(end 37.220906 -218.160346)
		(width 0.14478)
		(layer "In4.Cu")
		(net "M_D_CPU1_SA_DQ<17>")
	)
	(segment
		(start 92.35694 -235.839762)
		(end 92.511118 -235.574332)
		(width 0.0889)
		(layer "In4.Cu")
		(net "M_D_CPU1_SA_DQ<17>")
	)
	(segment
		(start 85.74405 -235.896912)
		(end 85.752432 -235.901738)
		(width 0.0889)
		(layer "In4.Cu")
		(net "M_D_CPU1_SA_DQ<17>")
	)
	(segment
		(start 83.289648 -235.901738)
		(end 83.29803 -235.896912)
		(width 0.0889)
		(layer "In4.Cu")
		(net "M_D_CPU1_SA_DQ<17>")
	)
	(segment
		(start 37.942774 -218.545664)
		(end 38.173152 -218.545664)
		(width 0.14478)
		(layer "In4.Cu")
		(net "M_D_CPU1_SA_DQ<17>")
	)
	(segment
		(start 55.449978 -218.323414)
		(end 55.613046 -218.160346)
		(width 0.14478)
		(layer "In4.Cu")
		(net "M_D_CPU1_SA_DQ<17>")
	)
	(segment
		(start 48.903636 -218.548966)
		(end 49.062386 -218.390216)
		(width 0.14478)
		(layer "In4.Cu")
		(net "M_D_CPU1_SA_DQ<17>")
	)
	(segment
		(start 91.749626 -235.901738)
		(end 91.758008 -235.896912)
		(width 0.0889)
		(layer "In4.Cu")
		(net "M_D_CPU1_SA_DQ<17>")
	)
	(segment
		(start 37.779706 -218.323414)
		(end 37.779706 -218.382596)
		(width 0.14478)
		(layer "In4.Cu")
		(net "M_D_CPU1_SA_DQ<17>")
	)
	(segment
		(start 39.449248 -218.323414)
		(end 39.612316 -218.160346)
		(width 0.14478)
		(layer "In4.Cu")
		(net "M_D_CPU1_SA_DQ<17>")
	)
	(segment
		(start 54.893464 -218.323414)
		(end 54.893464 -218.390216)
		(width 0.14478)
		(layer "In4.Cu")
		(net "M_D_CPU1_SA_DQ<17>")
	)
	(segment
		(start 56.16956 -218.553284)
		(end 56.399938 -218.553284)
		(width 0.14478)
		(layer "In4.Cu")
		(net "M_D_CPU1_SA_DQ<17>")
	)
	(segment
		(start 39.055802 -218.545664)
		(end 39.28618 -218.545664)
		(width 0.14478)
		(layer "In4.Cu")
		(net "M_D_CPU1_SA_DQ<17>")
	)
	(segment
		(start 54.084474 -218.160346)
		(end 54.730396 -218.160346)
		(width 0.14478)
		(layer "In4.Cu")
		(net "M_D_CPU1_SA_DQ<17>")
	)
	(segment
		(start 68.28155 -227.392484)
		(end 74.591164 -233.702098)
		(width 0.14478)
		(layer "In4.Cu")
		(net "M_D_CPU1_SA_DQ<17>")
	)
	(segment
		(start 50.902362 -217.695526)
		(end 51.151536 -217.695526)
		(width 0.14478)
		(layer "In4.Cu")
		(net "M_D_CPU1_SA_DQ<17>")
	)
	(segment
		(start 53.23459 -217.310462)
		(end 54.084474 -218.160346)
		(width 0.14478)
		(layer "In4.Cu")
		(net "M_D_CPU1_SA_DQ<17>")
	)
	(segment
		(start 39.612316 -218.160346)
		(end 40.843454 -218.160346)
		(width 0.14478)
		(layer "In4.Cu")
		(net "M_D_CPU1_SA_DQ<17>")
	)
	(segment
		(start 49.225454 -218.160346)
		(end 49.40681 -218.160346)
		(width 0.14478)
		(layer "In4.Cu")
		(net "M_D_CPU1_SA_DQ<17>")
	)
	(segment
		(start 55.449978 -218.390216)
		(end 55.449978 -218.323414)
		(width 0.14478)
		(layer "In4.Cu")
		(net "M_D_CPU1_SA_DQ<17>")
	)
	(segment
		(start 48.505872 -218.323414)
		(end 48.505872 -218.390216)
		(width 0.14478)
		(layer "In4.Cu")
		(net "M_D_CPU1_SA_DQ<17>")
	)
	(segment
		(start 68.28155 -225.81997)
		(end 68.28155 -227.392484)
		(width 0.14478)
		(layer "In4.Cu")
		(net "M_D_CPU1_SA_DQ<17>")
	)
	(segment
		(start 43.611038 -217.699844)
		(end 43.774106 -217.536776)
		(width 0.14478)
		(layer "In4.Cu")
		(net "M_D_CPU1_SA_DQ<17>")
	)
	(segment
		(start 51.468274 -217.310462)
		(end 53.23459 -217.310462)
		(width 0.14478)
		(layer "In4.Cu")
		(net "M_D_CPU1_SA_DQ<17>")
	)
	(segment
		(start 55.613046 -218.160346)
		(end 55.843424 -218.160346)
		(width 0.14478)
		(layer "In4.Cu")
		(net "M_D_CPU1_SA_DQ<17>")
	)
	(segment
		(start 88.929718 -235.901738)
		(end 88.9381 -235.896912)
		(width 0.0889)
		(layer "In4.Cu")
		(net "M_D_CPU1_SA_DQ<17>")
	)
	(segment
		(start 41.006522 -218.390216)
		(end 41.165272 -218.548966)
		(width 0.14478)
		(layer "In4.Cu")
		(net "M_D_CPU1_SA_DQ<17>")
	)
	(segment
		(start 39.449248 -218.382596)
		(end 39.449248 -218.323414)
		(width 0.14478)
		(layer "In4.Cu")
		(net "M_D_CPU1_SA_DQ<17>")
	)
	(segment
		(start 56.006492 -218.323414)
		(end 56.006492 -218.390216)
		(width 0.14478)
		(layer "In4.Cu")
		(net "M_D_CPU1_SA_DQ<17>")
	)
	(segment
		(start 89.504012 -235.896912)
		(end 89.512394 -235.901738)
		(width 0.0889)
		(layer "In4.Cu")
		(net "M_D_CPU1_SA_DQ<17>")
	)
	(segment
		(start 50.748692 -217.541856)
		(end 50.902362 -217.695526)
		(width 0.14478)
		(layer "In4.Cu")
		(net "M_D_CPU1_SA_DQ<17>")
	)
	(segment
		(start 50.585624 -217.310462)
		(end 50.748692 -217.47353)
		(width 0.14478)
		(layer "In4.Cu")
		(net "M_D_CPU1_SA_DQ<17>")
	)
	(segment
		(start 55.28691 -218.553284)
		(end 55.449978 -218.390216)
		(width 0.14478)
		(layer "In4.Cu")
		(net "M_D_CPU1_SA_DQ<17>")
	)
	(segment
		(start 51.305206 -217.541856)
		(end 51.305206 -217.47353)
		(width 0.14478)
		(layer "In4.Cu")
		(net "M_D_CPU1_SA_DQ<17>")
	)
	(segment
		(start 80.093566 -235.890816)
		(end 80.10398 -235.896912)
		(width 0.0889)
		(layer "In4.Cu")
		(net "M_D_CPU1_SA_DQ<17>")
	)
	(segment
		(start 49.40681 -218.160346)
		(end 50.256694 -217.310462)
		(width 0.14478)
		(layer "In4.Cu")
		(net "M_D_CPU1_SA_DQ<17>")
	)
	(segment
		(start 41.006522 -218.323414)
		(end 41.006522 -218.390216)
		(width 0.14478)
		(layer "In4.Cu")
		(net "M_D_CPU1_SA_DQ<17>")
	)
	(segment
		(start 43.38066 -217.699844)
		(end 43.611038 -217.699844)
		(width 0.14478)
		(layer "In4.Cu")
		(net "M_D_CPU1_SA_DQ<17>")
	)
	(segment
		(start 78.25867 -235.947712)
		(end 79.349854 -235.947712)
		(width 0.0889)
		(layer "In4.Cu")
		(net "M_D_CPU1_SA_DQ<17>")
	)
	(segment
		(start 56.726074 -218.160346)
		(end 60.621926 -218.160346)
		(width 0.14478)
		(layer "In4.Cu")
		(net "M_D_CPU1_SA_DQ<17>")
	)
	(segment
		(start 40.843454 -218.160346)
		(end 41.006522 -218.323414)
		(width 0.14478)
		(layer "In4.Cu")
		(net "M_D_CPU1_SA_DQ<17>")
	)
	(segment
		(start 56.563006 -218.390216)
		(end 56.563006 -218.323414)
		(width 0.14478)
		(layer "In4.Cu")
		(net "M_D_CPU1_SA_DQ<17>")
	)
	(segment
		(start 41.563036 -218.390216)
		(end 41.563036 -218.323414)
		(width 0.14478)
		(layer "In4.Cu")
		(net "M_D_CPU1_SA_DQ<17>")
	)
	(segment
		(start 41.404286 -218.548966)
		(end 41.563036 -218.390216)
		(width 0.14478)
		(layer "In4.Cu")
		(net "M_D_CPU1_SA_DQ<17>")
	)
	(segment
		(start 37.779706 -218.382596)
		(end 37.942774 -218.545664)
		(width 0.14478)
		(layer "In4.Cu")
		(net "M_D_CPU1_SA_DQ<17>")
	)
	(segment
		(start 84.803996 -235.896912)
		(end 84.812378 -235.901738)
		(width 0.0889)
		(layer "In4.Cu")
		(net "M_D_CPU1_SA_DQ<17>")
	)
	(segment
		(start 56.563006 -218.323414)
		(end 56.726074 -218.160346)
		(width 0.14478)
		(layer "In4.Cu")
		(net "M_D_CPU1_SA_DQ<17>")
	)
	(segment
		(start 38.892734 -218.079574)
		(end 38.892734 -218.382596)
		(width 0.14478)
		(layer "In4.Cu")
		(net "M_D_CPU1_SA_DQ<17>")
	)
	(segment
		(start 48.664622 -218.548966)
		(end 48.903636 -218.548966)
		(width 0.14478)
		(layer "In4.Cu")
		(net "M_D_CPU1_SA_DQ<17>")
	)
	(segment
		(start 43.774106 -217.536776)
		(end 43.774106 -217.47353)
		(width 0.14478)
		(layer "In4.Cu")
		(net "M_D_CPU1_SA_DQ<17>")
	)
	(segment
		(start 45.55871 -217.310462)
		(end 46.408594 -218.160346)
		(width 0.14478)
		(layer "In4.Cu")
		(net "M_D_CPU1_SA_DQ<17>")
	)
	(segment
		(start 42.733214 -217.310462)
		(end 43.054524 -217.310462)
		(width 0.14478)
		(layer "In4.Cu")
		(net "M_D_CPU1_SA_DQ<17>")
	)
	(segment
		(start 51.305206 -217.47353)
		(end 51.468274 -217.310462)
		(width 0.14478)
		(layer "In4.Cu")
		(net "M_D_CPU1_SA_DQ<17>")
	)
	(segment
		(start 84.229702 -235.901738)
		(end 84.238084 -235.896912)
		(width 0.0889)
		(layer "In4.Cu")
		(net "M_D_CPU1_SA_DQ<17>")
	)
	(segment
		(start 87.989664 -235.901738)
		(end 87.998046 -235.896912)
		(width 0.0889)
		(layer "In4.Cu")
		(net "M_D_CPU1_SA_DQ<17>")
	)
	(segment
		(start 74.591164 -233.702098)
		(end 75.93965 -233.702098)
		(width 0.14478)
		(layer "In4.Cu")
		(net "M_D_CPU1_SA_DQ<17>")
	)
	(segment
		(start 37.220906 -218.160346)
		(end 37.616638 -218.160346)
		(width 0.14478)
		(layer "In4.Cu")
		(net "M_D_CPU1_SA_DQ<17>")
	)
	(segment
		(start 38.729666 -217.916506)
		(end 38.892734 -218.079574)
		(width 0.14478)
		(layer "In4.Cu")
		(net "M_D_CPU1_SA_DQ<17>")
	)
	(segment
		(start 81.044034 -235.896912)
		(end 81.052416 -235.901738)
		(width 0.0889)
		(layer "In4.Cu")
		(net "M_D_CPU1_SA_DQ<17>")
	)
	(segment
		(start 48.505872 -218.390216)
		(end 48.664622 -218.548966)
		(width 0.14478)
		(layer "In4.Cu")
		(net "M_D_CPU1_SA_DQ<17>")
	)
	(segment
		(start 41.88333 -218.160346)
		(end 42.733214 -217.310462)
		(width 0.14478)
		(layer "In4.Cu")
		(net "M_D_CPU1_SA_DQ<17>")
	)
	(segment
		(start 55.843424 -218.160346)
		(end 56.006492 -218.323414)
		(width 0.14478)
		(layer "In4.Cu")
		(net "M_D_CPU1_SA_DQ<17>")
	)
	(segment
		(start 77.59573 -234.731306)
		(end 77.59573 -235.284772)
		(width 0.0889)
		(layer "In4.Cu")
		(net "M_D_CPU1_SA_DQ<17>")
	)
	(segment
		(start 56.006492 -218.390216)
		(end 56.16956 -218.553284)
		(width 0.14478)
		(layer "In4.Cu")
		(net "M_D_CPU1_SA_DQ<17>")
	)
	(segment
		(start 77.59573 -235.284772)
		(end 78.25867 -235.947712)
		(width 0.0889)
		(layer "In4.Cu")
		(net "M_D_CPU1_SA_DQ<17>")
	)
	(segment
		(start 54.730396 -218.160346)
		(end 54.893464 -218.323414)
		(width 0.14478)
		(layer "In4.Cu")
		(net "M_D_CPU1_SA_DQ<17>")
	)
	(segment
		(start 49.062386 -218.390216)
		(end 49.062386 -218.323414)
		(width 0.14478)
		(layer "In4.Cu")
		(net "M_D_CPU1_SA_DQ<17>")
	)
	(segment
		(start 43.217592 -217.536776)
		(end 43.38066 -217.699844)
		(width 0.14478)
		(layer "In4.Cu")
		(net "M_D_CPU1_SA_DQ<17>")
	)
	(segment
		(start 43.774106 -217.47353)
		(end 43.937174 -217.310462)
		(width 0.14478)
		(layer "In4.Cu")
		(net "M_D_CPU1_SA_DQ<17>")
	)
	(segment
		(start 38.499288 -217.916506)
		(end 38.729666 -217.916506)
		(width 0.14478)
		(layer "In4.Cu")
		(net "M_D_CPU1_SA_DQ<17>")
	)
	(segment
		(start 46.408594 -218.160346)
		(end 48.342804 -218.160346)
		(width 0.14478)
		(layer "In4.Cu")
		(net "M_D_CPU1_SA_DQ<17>")
	)
	(segment
		(start 76.205842 -233.702098)
		(end 76.67625 -234.172506)
		(width 0.0889)
		(layer "In4.Cu")
		(net "M_D_CPU1_SA_DQ<17>")
	)
	(segment
		(start 43.937174 -217.310462)
		(end 45.55871 -217.310462)
		(width 0.14478)
		(layer "In4.Cu")
		(net "M_D_CPU1_SA_DQ<17>")
	)
	(segment
		(start 76.67625 -234.172506)
		(end 77.03693 -234.172506)
		(width 0.0889)
		(layer "In4.Cu")
		(net "M_D_CPU1_SA_DQ<17>")
	)
	(segment
		(start 41.563036 -218.323414)
		(end 41.726104 -218.160346)
		(width 0.14478)
		(layer "In4.Cu")
		(net "M_D_CPU1_SA_DQ<17>")
	)
	(segment
		(start 38.33622 -218.382596)
		(end 38.33622 -218.079574)
		(width 0.14478)
		(layer "In4.Cu")
		(net "M_D_CPU1_SA_DQ<17>")
	)
	(segment
		(start 54.893464 -218.390216)
		(end 55.056532 -218.553284)
		(width 0.14478)
		(layer "In4.Cu")
		(net "M_D_CPU1_SA_DQ<17>")
	)
	(segment
		(start 56.399938 -218.553284)
		(end 56.563006 -218.390216)
		(width 0.14478)
		(layer "In4.Cu")
		(net "M_D_CPU1_SA_DQ<17>")
	)
	(segment
		(start 92.260674 -235.865162)
		(end 92.35694 -235.839762)
		(width 0.0889)
		(layer "In4.Cu")
		(net "M_D_CPU1_SA_DQ<17>")
	)
	(segment
		(start 50.748692 -217.47353)
		(end 50.748692 -217.541856)
		(width 0.14478)
		(layer "In4.Cu")
		(net "M_D_CPU1_SA_DQ<17>")
	)
	(segment
		(start 37.616638 -218.160346)
		(end 37.779706 -218.323414)
		(width 0.14478)
		(layer "In4.Cu")
		(net "M_D_CPU1_SA_DQ<17>")
	)
	(segment
		(start 60.621926 -218.160346)
		(end 68.28155 -225.81997)
		(width 0.14478)
		(layer "In4.Cu")
		(net "M_D_CPU1_SA_DQ<17>")
	)
	(segment
		(start 80.46974 -235.901738)
		(end 80.478122 -235.896912)
		(width 0.0889)
		(layer "In4.Cu")
		(net "M_D_CPU1_SA_DQ<17>")
	)
	(segment
		(start 49.062386 -218.323414)
		(end 49.225454 -218.160346)
		(width 0.14478)
		(layer "In4.Cu")
		(net "M_D_CPU1_SA_DQ<17>")
	)
	(segment
		(start 38.892734 -218.382596)
		(end 39.055802 -218.545664)
		(width 0.14478)
		(layer "In4.Cu")
		(net "M_D_CPU1_SA_DQ<17>")
	)
	(segment
		(start 39.28618 -218.545664)
		(end 39.449248 -218.382596)
		(width 0.14478)
		(layer "In4.Cu")
		(net "M_D_CPU1_SA_DQ<17>")
	)
	(segment
		(start 38.33622 -218.079574)
		(end 38.499288 -217.916506)
		(width 0.14478)
		(layer "In4.Cu")
		(net "M_D_CPU1_SA_DQ<17>")
	)
	(segment
		(start 38.173152 -218.545664)
		(end 38.33622 -218.382596)
		(width 0.14478)
		(layer "In4.Cu")
		(net "M_D_CPU1_SA_DQ<17>")
	)
	(segment
		(start 43.054524 -217.310462)
		(end 43.217592 -217.47353)
		(width 0.14478)
		(layer "In4.Cu")
		(net "M_D_CPU1_SA_DQ<17>")
	)
	(arc
		(start 82.357976 -235.896912)
		(mid 82.640932 -235.820735)
		(end 82.923888 -235.896912)
		(width 0.0889)
		(layer "In4.Cu")
		(net "M_D_CPU1_SA_DQ<17>")
	)
	(arc
		(start 83.29803 -235.896912)
		(mid 83.580986 -235.820735)
		(end 83.863942 -235.896912)
		(width 0.0889)
		(layer "In4.Cu")
		(net "M_D_CPU1_SA_DQ<17>")
	)
	(arc
		(start 80.478122 -235.896912)
		(mid 80.761078 -235.820735)
		(end 81.044034 -235.896912)
		(width 0.0889)
		(layer "In4.Cu")
		(net "M_D_CPU1_SA_DQ<17>")
	)
	(arc
		(start 81.984088 -235.896912)
		(mid 82.171032 -235.947167)
		(end 82.357976 -235.896912)
		(width 0.0889)
		(layer "In4.Cu")
		(net "M_D_CPU1_SA_DQ<17>")
	)
	(arc
		(start 90.444066 -235.896912)
		(mid 90.63101 -235.947167)
		(end 90.817954 -235.896912)
		(width 0.0889)
		(layer "In4.Cu")
		(net "M_D_CPU1_SA_DQ<17>")
	)
	(arc
		(start 90.817954 -235.896912)
		(mid 91.10091 -235.820735)
		(end 91.383866 -235.896912)
		(width 0.0889)
		(layer "In4.Cu")
		(net "M_D_CPU1_SA_DQ<17>")
	)
	(arc
		(start 85.752432 -235.901738)
		(mid 85.93594 -235.947232)
		(end 86.118192 -235.896912)
		(width 0.0889)
		(layer "In4.Cu")
		(net "M_D_CPU1_SA_DQ<17>")
	)
	(arc
		(start 80.10398 -235.896912)
		(mid 80.286231 -235.947262)
		(end 80.46974 -235.901738)
		(width 0.0889)
		(layer "In4.Cu")
		(net "M_D_CPU1_SA_DQ<17>")
	)
	(arc
		(start 88.9381 -235.896912)
		(mid 89.221056 -235.820735)
		(end 89.504012 -235.896912)
		(width 0.0889)
		(layer "In4.Cu")
		(net "M_D_CPU1_SA_DQ<17>")
	)
	(arc
		(start 89.512394 -235.901738)
		(mid 89.695902 -235.947232)
		(end 89.878154 -235.896912)
		(width 0.0889)
		(layer "In4.Cu")
		(net "M_D_CPU1_SA_DQ<17>")
	)
	(arc
		(start 81.418176 -235.896912)
		(mid 81.701132 -235.820735)
		(end 81.984088 -235.896912)
		(width 0.0889)
		(layer "In4.Cu")
		(net "M_D_CPU1_SA_DQ<17>")
	)
	(arc
		(start 87.998046 -235.896912)
		(mid 88.281002 -235.820735)
		(end 88.563958 -235.896912)
		(width 0.0889)
		(layer "In4.Cu")
		(net "M_D_CPU1_SA_DQ<17>")
	)
	(arc
		(start 83.863942 -235.896912)
		(mid 84.046193 -235.947262)
		(end 84.229702 -235.901738)
		(width 0.0889)
		(layer "In4.Cu")
		(net "M_D_CPU1_SA_DQ<17>")
	)
	(arc
		(start 86.118192 -235.896912)
		(mid 86.401148 -235.820735)
		(end 86.684104 -235.896912)
		(width 0.0889)
		(layer "In4.Cu")
		(net "M_D_CPU1_SA_DQ<17>")
	)
	(arc
		(start 91.758008 -235.896912)
		(mid 92.005604 -235.821734)
		(end 92.260674 -235.865162)
		(width 0.0889)
		(layer "In4.Cu")
		(net "M_D_CPU1_SA_DQ<17>")
	)
	(arc
		(start 79.349854 -235.947712)
		(mid 79.447215 -235.934804)
		(end 79.537814 -235.896912)
		(width 0.0889)
		(layer "In4.Cu")
		(net "M_D_CPU1_SA_DQ<17>")
	)
	(arc
		(start 86.684104 -235.896912)
		(mid 86.871048 -235.947167)
		(end 87.057992 -235.896912)
		(width 0.0889)
		(layer "In4.Cu")
		(net "M_D_CPU1_SA_DQ<17>")
	)
	(arc
		(start 87.057992 -235.896912)
		(mid 87.340948 -235.820735)
		(end 87.623904 -235.896912)
		(width 0.0889)
		(layer "In4.Cu")
		(net "M_D_CPU1_SA_DQ<17>")
	)
	(arc
		(start 81.052416 -235.901738)
		(mid 81.235924 -235.947232)
		(end 81.418176 -235.896912)
		(width 0.0889)
		(layer "In4.Cu")
		(net "M_D_CPU1_SA_DQ<17>")
	)
	(arc
		(start 84.238084 -235.896912)
		(mid 84.52104 -235.820735)
		(end 84.803996 -235.896912)
		(width 0.0889)
		(layer "In4.Cu")
		(net "M_D_CPU1_SA_DQ<17>")
	)
	(arc
		(start 91.383866 -235.896912)
		(mid 91.566117 -235.947262)
		(end 91.749626 -235.901738)
		(width 0.0889)
		(layer "In4.Cu")
		(net "M_D_CPU1_SA_DQ<17>")
	)
	(arc
		(start 79.537814 -235.896912)
		(mid 79.814881 -235.820641)
		(end 80.093566 -235.890816)
		(width 0.0889)
		(layer "In4.Cu")
		(net "M_D_CPU1_SA_DQ<17>")
	)
	(arc
		(start 85.178138 -235.896912)
		(mid 85.461094 -235.820735)
		(end 85.74405 -235.896912)
		(width 0.0889)
		(layer "In4.Cu")
		(net "M_D_CPU1_SA_DQ<17>")
	)
	(arc
		(start 87.623904 -235.896912)
		(mid 87.806155 -235.947262)
		(end 87.989664 -235.901738)
		(width 0.0889)
		(layer "In4.Cu")
		(net "M_D_CPU1_SA_DQ<17>")
	)
	(arc
		(start 89.878154 -235.896912)
		(mid 90.16111 -235.820735)
		(end 90.444066 -235.896912)
		(width 0.0889)
		(layer "In4.Cu")
		(net "M_D_CPU1_SA_DQ<17>")
	)
	(arc
		(start 82.923888 -235.896912)
		(mid 83.106139 -235.947262)
		(end 83.289648 -235.901738)
		(width 0.0889)
		(layer "In4.Cu")
		(net "M_D_CPU1_SA_DQ<17>")
	)
	(arc
		(start 84.812378 -235.901738)
		(mid 84.995886 -235.947232)
		(end 85.178138 -235.896912)
		(width 0.0889)
		(layer "In4.Cu")
		(net "M_D_CPU1_SA_DQ<17>")
	)
	(arc
		(start 88.563958 -235.896912)
		(mid 88.746209 -235.947262)
		(end 88.929718 -235.901738)
		(width 0.0889)
		(layer "In4.Cu")
		(net "M_D_CPU1_SA_DQ<17>")
	)
	(segment
		(start 91.568016 -235.030264)
		(end 91.10091 -234.764326)
		(width 0.10668)
		(layer "F.Cu")
		(net "M_D_CPU1_SA_DQ<16>")
	)
	(segment
		(start 75.94981 -232.792778)
		(end 76.746862 -232.792778)
		(width 0.0889)
		(layer "In4.Cu")
		(net "M_D_CPU1_SA_DQ<16>")
	)
	(segment
		(start 56.2229 -216.859866)
		(end 56.384444 -216.698322)
		(width 0.14478)
		(layer "In4.Cu")
		(net "M_D_CPU1_SA_DQ<16>")
	)
	(segment
		(start 43.541188 -215.922606)
		(end 43.853354 -215.61044)
		(width 0.14478)
		(layer "In4.Cu")
		(net "M_D_CPU1_SA_DQ<16>")
	)
	(segment
		(start 50.946304 -215.897206)
		(end 51.210972 -215.897206)
		(width 0.14478)
		(layer "In4.Cu")
		(net "M_D_CPU1_SA_DQ<16>")
	)
	(segment
		(start 37.220906 -216.460324)
		(end 37.6301 -216.460324)
		(width 0.14478)
		(layer "In4.Cu")
		(net "M_D_CPU1_SA_DQ<16>")
	)
	(segment
		(start 55.248302 -216.460324)
		(end 55.671466 -216.460324)
		(width 0.14478)
		(layer "In4.Cu")
		(net "M_D_CPU1_SA_DQ<16>")
	)
	(segment
		(start 53.23459 -215.61044)
		(end 54.084474 -216.460324)
		(width 0.14478)
		(layer "In4.Cu")
		(net "M_D_CPU1_SA_DQ<16>")
	)
	(segment
		(start 69.19087 -225.424492)
		(end 69.19087 -227.015548)
		(width 0.14478)
		(layer "In4.Cu")
		(net "M_D_CPU1_SA_DQ<16>")
	)
	(segment
		(start 39.056056 -216.857326)
		(end 39.284402 -216.857326)
		(width 0.14478)
		(layer "In4.Cu")
		(net "M_D_CPU1_SA_DQ<16>")
	)
	(segment
		(start 39.445946 -216.695782)
		(end 39.445946 -216.621868)
		(width 0.14478)
		(layer "In4.Cu")
		(net "M_D_CPU1_SA_DQ<16>")
	)
	(segment
		(start 90.850974 -235.055156)
		(end 90.946986 -235.029756)
		(width 0.0889)
		(layer "In4.Cu")
		(net "M_D_CPU1_SA_DQ<16>")
	)
	(segment
		(start 37.953188 -216.857326)
		(end 38.181534 -216.857326)
		(width 0.14478)
		(layer "In4.Cu")
		(net "M_D_CPU1_SA_DQ<16>")
	)
	(segment
		(start 37.791644 -216.621868)
		(end 37.791644 -216.695782)
		(width 0.14478)
		(layer "In4.Cu")
		(net "M_D_CPU1_SA_DQ<16>")
	)
	(segment
		(start 43.30192 -215.922606)
		(end 43.541188 -215.922606)
		(width 0.14478)
		(layer "In4.Cu")
		(net "M_D_CPU1_SA_DQ<16>")
	)
	(segment
		(start 77.41539 -233.613452)
		(end 78.225904 -234.423966)
		(width 0.0889)
		(layer "In4.Cu")
		(net "M_D_CPU1_SA_DQ<16>")
	)
	(segment
		(start 56.545988 -216.168986)
		(end 56.774334 -216.168986)
		(width 0.14478)
		(layer "In4.Cu")
		(net "M_D_CPU1_SA_DQ<16>")
	)
	(segment
		(start 56.935878 -216.33053)
		(end 56.935878 -216.698322)
		(width 0.14478)
		(layer "In4.Cu")
		(net "M_D_CPU1_SA_DQ<16>")
	)
	(segment
		(start 85.639656 -235.091732)
		(end 85.648038 -235.086906)
		(width 0.0889)
		(layer "In4.Cu")
		(net "M_D_CPU1_SA_DQ<16>")
	)
	(segment
		(start 50.659538 -215.61044)
		(end 50.946304 -215.897206)
		(width 0.14478)
		(layer "In4.Cu")
		(net "M_D_CPU1_SA_DQ<16>")
	)
	(segment
		(start 45.55871 -215.61044)
		(end 46.408594 -216.460324)
		(width 0.14478)
		(layer "In4.Cu")
		(net "M_D_CPU1_SA_DQ<16>")
	)
	(segment
		(start 54.409086 -216.460324)
		(end 54.696868 -216.748106)
		(width 0.14478)
		(layer "In4.Cu")
		(net "M_D_CPU1_SA_DQ<16>")
	)
	(segment
		(start 58.428636 -216.859866)
		(end 58.59018 -216.698322)
		(width 0.14478)
		(layer "In4.Cu")
		(net "M_D_CPU1_SA_DQ<16>")
	)
	(segment
		(start 57.325768 -216.859866)
		(end 57.487312 -216.698322)
		(width 0.14478)
		(layer "In4.Cu")
		(net "M_D_CPU1_SA_DQ<16>")
	)
	(segment
		(start 58.038746 -216.698322)
		(end 58.20029 -216.859866)
		(width 0.14478)
		(layer "In4.Cu")
		(net "M_D_CPU1_SA_DQ<16>")
	)
	(segment
		(start 81.879694 -235.091732)
		(end 81.888076 -235.086906)
		(width 0.0889)
		(layer "In4.Cu")
		(net "M_D_CPU1_SA_DQ<16>")
	)
	(segment
		(start 56.384444 -216.698322)
		(end 56.384444 -216.33053)
		(width 0.14478)
		(layer "In4.Cu")
		(net "M_D_CPU1_SA_DQ<16>")
	)
	(segment
		(start 56.384444 -216.33053)
		(end 56.545988 -216.168986)
		(width 0.14478)
		(layer "In4.Cu")
		(net "M_D_CPU1_SA_DQ<16>")
	)
	(segment
		(start 58.751724 -216.460324)
		(end 60.226702 -216.460324)
		(width 0.14478)
		(layer "In4.Cu")
		(net "M_D_CPU1_SA_DQ<16>")
	)
	(segment
		(start 79.634842 -235.086906)
		(end 79.634842 -235.086652)
		(width 0.0889)
		(layer "In4.Cu")
		(net "M_D_CPU1_SA_DQ<16>")
	)
	(segment
		(start 55.83301 -216.698322)
		(end 55.994554 -216.859866)
		(width 0.14478)
		(layer "In4.Cu")
		(net "M_D_CPU1_SA_DQ<16>")
	)
	(segment
		(start 78.225904 -234.423966)
		(end 78.601316 -234.423966)
		(width 0.0889)
		(layer "In4.Cu")
		(net "M_D_CPU1_SA_DQ<16>")
	)
	(segment
		(start 87.154004 -235.086906)
		(end 87.162386 -235.091732)
		(width 0.0889)
		(layer "In4.Cu")
		(net "M_D_CPU1_SA_DQ<16>")
	)
	(segment
		(start 58.20029 -216.859866)
		(end 58.428636 -216.859866)
		(width 0.14478)
		(layer "In4.Cu")
		(net "M_D_CPU1_SA_DQ<16>")
	)
	(segment
		(start 90.339672 -235.091732)
		(end 90.348054 -235.086906)
		(width 0.0889)
		(layer "In4.Cu")
		(net "M_D_CPU1_SA_DQ<16>")
	)
	(segment
		(start 38.732968 -216.174066)
		(end 38.894512 -216.33561)
		(width 0.14478)
		(layer "In4.Cu")
		(net "M_D_CPU1_SA_DQ<16>")
	)
	(segment
		(start 38.894512 -216.33561)
		(end 38.894512 -216.695782)
		(width 0.14478)
		(layer "In4.Cu")
		(net "M_D_CPU1_SA_DQ<16>")
	)
	(segment
		(start 78.601316 -234.423966)
		(end 79.203042 -235.025692)
		(width 0.0889)
		(layer "In4.Cu")
		(net "M_D_CPU1_SA_DQ<16>")
	)
	(segment
		(start 39.60749 -216.460324)
		(end 41.88333 -216.460324)
		(width 0.14478)
		(layer "In4.Cu")
		(net "M_D_CPU1_SA_DQ<16>")
	)
	(segment
		(start 79.634842 -235.086652)
		(end 79.654908 -235.098082)
		(width 0.0889)
		(layer "In4.Cu")
		(net "M_D_CPU1_SA_DQ<16>")
	)
	(segment
		(start 39.445946 -216.621868)
		(end 39.60749 -216.460324)
		(width 0.14478)
		(layer "In4.Cu")
		(net "M_D_CPU1_SA_DQ<16>")
	)
	(segment
		(start 54.696868 -216.748106)
		(end 54.96052 -216.748106)
		(width 0.14478)
		(layer "In4.Cu")
		(net "M_D_CPU1_SA_DQ<16>")
	)
	(segment
		(start 57.487312 -216.33053)
		(end 57.648856 -216.168986)
		(width 0.14478)
		(layer "In4.Cu")
		(net "M_D_CPU1_SA_DQ<16>")
	)
	(segment
		(start 82.453988 -235.086906)
		(end 82.46237 -235.091732)
		(width 0.0889)
		(layer "In4.Cu")
		(net "M_D_CPU1_SA_DQ<16>")
	)
	(segment
		(start 55.83301 -216.621868)
		(end 55.83301 -216.698322)
		(width 0.14478)
		(layer "In4.Cu")
		(net "M_D_CPU1_SA_DQ<16>")
	)
	(segment
		(start 51.497738 -215.61044)
		(end 53.23459 -215.61044)
		(width 0.14478)
		(layer "In4.Cu")
		(net "M_D_CPU1_SA_DQ<16>")
	)
	(segment
		(start 46.408594 -216.460324)
		(end 48.19904 -216.460324)
		(width 0.14478)
		(layer "In4.Cu")
		(net "M_D_CPU1_SA_DQ<16>")
	)
	(segment
		(start 57.877202 -216.168986)
		(end 58.038746 -216.33053)
		(width 0.14478)
		(layer "In4.Cu")
		(net "M_D_CPU1_SA_DQ<16>")
	)
	(segment
		(start 90.946986 -235.029756)
		(end 91.10091 -234.764326)
		(width 0.0889)
		(layer "In4.Cu")
		(net "M_D_CPU1_SA_DQ<16>")
	)
	(segment
		(start 54.084474 -216.460324)
		(end 54.409086 -216.460324)
		(width 0.14478)
		(layer "In4.Cu")
		(net "M_D_CPU1_SA_DQ<16>")
	)
	(segment
		(start 76.746862 -232.792778)
		(end 77.41539 -233.461306)
		(width 0.0889)
		(layer "In4.Cu")
		(net "M_D_CPU1_SA_DQ<16>")
	)
	(segment
		(start 58.59018 -216.621868)
		(end 58.751724 -216.460324)
		(width 0.14478)
		(layer "In4.Cu")
		(net "M_D_CPU1_SA_DQ<16>")
	)
	(segment
		(start 60.226702 -216.460324)
		(end 69.19087 -225.424492)
		(width 0.14478)
		(layer "In4.Cu")
		(net "M_D_CPU1_SA_DQ<16>")
	)
	(segment
		(start 48.750474 -216.735406)
		(end 49.025556 -216.460324)
		(width 0.14478)
		(layer "In4.Cu")
		(net "M_D_CPU1_SA_DQ<16>")
	)
	(segment
		(start 55.994554 -216.859866)
		(end 56.2229 -216.859866)
		(width 0.14478)
		(layer "In4.Cu")
		(net "M_D_CPU1_SA_DQ<16>")
	)
	(segment
		(start 50.256694 -215.61044)
		(end 50.659538 -215.61044)
		(width 0.14478)
		(layer "In4.Cu")
		(net "M_D_CPU1_SA_DQ<16>")
	)
	(segment
		(start 56.774334 -216.168986)
		(end 56.935878 -216.33053)
		(width 0.14478)
		(layer "In4.Cu")
		(net "M_D_CPU1_SA_DQ<16>")
	)
	(segment
		(start 38.894512 -216.695782)
		(end 39.056056 -216.857326)
		(width 0.14478)
		(layer "In4.Cu")
		(net "M_D_CPU1_SA_DQ<16>")
	)
	(segment
		(start 49.40681 -216.460324)
		(end 50.256694 -215.61044)
		(width 0.14478)
		(layer "In4.Cu")
		(net "M_D_CPU1_SA_DQ<16>")
	)
	(segment
		(start 54.96052 -216.748106)
		(end 55.248302 -216.460324)
		(width 0.14478)
		(layer "In4.Cu")
		(net "M_D_CPU1_SA_DQ<16>")
	)
	(segment
		(start 48.19904 -216.460324)
		(end 48.474122 -216.735406)
		(width 0.14478)
		(layer "In4.Cu")
		(net "M_D_CPU1_SA_DQ<16>")
	)
	(segment
		(start 38.504622 -216.174066)
		(end 38.732968 -216.174066)
		(width 0.14478)
		(layer "In4.Cu")
		(net "M_D_CPU1_SA_DQ<16>")
	)
	(segment
		(start 77.41539 -233.461306)
		(end 77.41539 -233.613452)
		(width 0.0889)
		(layer "In4.Cu")
		(net "M_D_CPU1_SA_DQ<16>")
	)
	(segment
		(start 42.989754 -215.61044)
		(end 43.30192 -215.922606)
		(width 0.14478)
		(layer "In4.Cu")
		(net "M_D_CPU1_SA_DQ<16>")
	)
	(segment
		(start 41.88333 -216.460324)
		(end 42.733214 -215.61044)
		(width 0.14478)
		(layer "In4.Cu")
		(net "M_D_CPU1_SA_DQ<16>")
	)
	(segment
		(start 38.343078 -216.33561)
		(end 38.504622 -216.174066)
		(width 0.14478)
		(layer "In4.Cu")
		(net "M_D_CPU1_SA_DQ<16>")
	)
	(segment
		(start 79.203042 -235.025692)
		(end 79.478886 -235.025692)
		(width 0.0889)
		(layer "In4.Cu")
		(net "M_D_CPU1_SA_DQ<16>")
	)
	(segment
		(start 86.57971 -235.091732)
		(end 86.588092 -235.086906)
		(width 0.0889)
		(layer "In4.Cu")
		(net "M_D_CPU1_SA_DQ<16>")
	)
	(segment
		(start 43.853354 -215.61044)
		(end 45.55871 -215.61044)
		(width 0.14478)
		(layer "In4.Cu")
		(net "M_D_CPU1_SA_DQ<16>")
	)
	(segment
		(start 57.097422 -216.859866)
		(end 57.325768 -216.859866)
		(width 0.14478)
		(layer "In4.Cu")
		(net "M_D_CPU1_SA_DQ<16>")
	)
	(segment
		(start 69.19087 -227.015548)
		(end 74.9681 -232.792778)
		(width 0.14478)
		(layer "In4.Cu")
		(net "M_D_CPU1_SA_DQ<16>")
	)
	(segment
		(start 51.210972 -215.897206)
		(end 51.497738 -215.61044)
		(width 0.14478)
		(layer "In4.Cu")
		(net "M_D_CPU1_SA_DQ<16>")
	)
	(segment
		(start 88.094058 -235.086906)
		(end 88.10244 -235.091732)
		(width 0.0889)
		(layer "In4.Cu")
		(net "M_D_CPU1_SA_DQ<16>")
	)
	(segment
		(start 57.487312 -216.698322)
		(end 57.487312 -216.33053)
		(width 0.14478)
		(layer "In4.Cu")
		(net "M_D_CPU1_SA_DQ<16>")
	)
	(segment
		(start 74.9681 -232.792778)
		(end 75.94981 -232.792778)
		(width 0.14478)
		(layer "In4.Cu")
		(net "M_D_CPU1_SA_DQ<16>")
	)
	(segment
		(start 83.394042 -235.086906)
		(end 83.402424 -235.091732)
		(width 0.0889)
		(layer "In4.Cu")
		(net "M_D_CPU1_SA_DQ<16>")
	)
	(segment
		(start 38.181534 -216.857326)
		(end 38.343078 -216.695782)
		(width 0.14478)
		(layer "In4.Cu")
		(net "M_D_CPU1_SA_DQ<16>")
	)
	(segment
		(start 38.343078 -216.695782)
		(end 38.343078 -216.33561)
		(width 0.14478)
		(layer "In4.Cu")
		(net "M_D_CPU1_SA_DQ<16>")
	)
	(segment
		(start 42.733214 -215.61044)
		(end 42.989754 -215.61044)
		(width 0.14478)
		(layer "In4.Cu")
		(net "M_D_CPU1_SA_DQ<16>")
	)
	(segment
		(start 37.6301 -216.460324)
		(end 37.791644 -216.621868)
		(width 0.14478)
		(layer "In4.Cu")
		(net "M_D_CPU1_SA_DQ<16>")
	)
	(segment
		(start 58.038746 -216.33053)
		(end 58.038746 -216.698322)
		(width 0.14478)
		(layer "In4.Cu")
		(net "M_D_CPU1_SA_DQ<16>")
	)
	(segment
		(start 48.474122 -216.735406)
		(end 48.750474 -216.735406)
		(width 0.14478)
		(layer "In4.Cu")
		(net "M_D_CPU1_SA_DQ<16>")
	)
	(segment
		(start 39.284402 -216.857326)
		(end 39.445946 -216.695782)
		(width 0.14478)
		(layer "In4.Cu")
		(net "M_D_CPU1_SA_DQ<16>")
	)
	(segment
		(start 37.791644 -216.695782)
		(end 37.953188 -216.857326)
		(width 0.14478)
		(layer "In4.Cu")
		(net "M_D_CPU1_SA_DQ<16>")
	)
	(segment
		(start 56.935878 -216.698322)
		(end 57.097422 -216.859866)
		(width 0.14478)
		(layer "In4.Cu")
		(net "M_D_CPU1_SA_DQ<16>")
	)
	(segment
		(start 58.59018 -216.698322)
		(end 58.59018 -216.621868)
		(width 0.14478)
		(layer "In4.Cu")
		(net "M_D_CPU1_SA_DQ<16>")
	)
	(segment
		(start 55.671466 -216.460324)
		(end 55.83301 -216.621868)
		(width 0.14478)
		(layer "In4.Cu")
		(net "M_D_CPU1_SA_DQ<16>")
	)
	(segment
		(start 57.648856 -216.168986)
		(end 57.877202 -216.168986)
		(width 0.14478)
		(layer "In4.Cu")
		(net "M_D_CPU1_SA_DQ<16>")
	)
	(segment
		(start 36.795964 -216.035382)
		(end 37.220906 -216.460324)
		(width 0.14478)
		(layer "In4.Cu")
		(net "M_D_CPU1_SA_DQ<16>")
	)
	(segment
		(start 49.025556 -216.460324)
		(end 49.40681 -216.460324)
		(width 0.14478)
		(layer "In4.Cu")
		(net "M_D_CPU1_SA_DQ<16>")
	)
	(arc
		(start 86.588092 -235.086906)
		(mid 86.871048 -235.010729)
		(end 87.154004 -235.086906)
		(width 0.0889)
		(layer "In4.Cu")
		(net "M_D_CPU1_SA_DQ<16>")
	)
	(arc
		(start 87.528146 -235.086906)
		(mid 87.811102 -235.010729)
		(end 88.094058 -235.086906)
		(width 0.0889)
		(layer "In4.Cu")
		(net "M_D_CPU1_SA_DQ<16>")
	)
	(arc
		(start 79.478886 -235.025692)
		(mid 79.559152 -235.050469)
		(end 79.634842 -235.086906)
		(width 0.0889)
		(layer "In4.Cu")
		(net "M_D_CPU1_SA_DQ<16>")
	)
	(arc
		(start 85.648038 -235.086906)
		(mid 85.930994 -235.010729)
		(end 86.21395 -235.086906)
		(width 0.0889)
		(layer "In4.Cu")
		(net "M_D_CPU1_SA_DQ<16>")
	)
	(arc
		(start 81.888076 -235.086906)
		(mid 82.171032 -235.010729)
		(end 82.453988 -235.086906)
		(width 0.0889)
		(layer "In4.Cu")
		(net "M_D_CPU1_SA_DQ<16>")
	)
	(arc
		(start 83.402424 -235.091732)
		(mid 83.585932 -235.137226)
		(end 83.768184 -235.086906)
		(width 0.0889)
		(layer "In4.Cu")
		(net "M_D_CPU1_SA_DQ<16>")
	)
	(arc
		(start 80.574134 -235.086906)
		(mid 80.761078 -235.137161)
		(end 80.948022 -235.086906)
		(width 0.0889)
		(layer "In4.Cu")
		(net "M_D_CPU1_SA_DQ<16>")
	)
	(arc
		(start 82.82813 -235.086906)
		(mid 83.111086 -235.010729)
		(end 83.394042 -235.086906)
		(width 0.0889)
		(layer "In4.Cu")
		(net "M_D_CPU1_SA_DQ<16>")
	)
	(arc
		(start 88.4682 -235.086906)
		(mid 88.751156 -235.010729)
		(end 89.034112 -235.086906)
		(width 0.0889)
		(layer "In4.Cu")
		(net "M_D_CPU1_SA_DQ<16>")
	)
	(arc
		(start 88.10244 -235.091732)
		(mid 88.285948 -235.137226)
		(end 88.4682 -235.086906)
		(width 0.0889)
		(layer "In4.Cu")
		(net "M_D_CPU1_SA_DQ<16>")
	)
	(arc
		(start 82.46237 -235.091732)
		(mid 82.645878 -235.137226)
		(end 82.82813 -235.086906)
		(width 0.0889)
		(layer "In4.Cu")
		(net "M_D_CPU1_SA_DQ<16>")
	)
	(arc
		(start 89.408 -235.086906)
		(mid 89.690956 -235.010729)
		(end 89.973912 -235.086906)
		(width 0.0889)
		(layer "In4.Cu")
		(net "M_D_CPU1_SA_DQ<16>")
	)
	(arc
		(start 83.768184 -235.086906)
		(mid 84.05114 -235.010729)
		(end 84.334096 -235.086906)
		(width 0.0889)
		(layer "In4.Cu")
		(net "M_D_CPU1_SA_DQ<16>")
	)
	(arc
		(start 81.513934 -235.086906)
		(mid 81.696185 -235.137256)
		(end 81.879694 -235.091732)
		(width 0.0889)
		(layer "In4.Cu")
		(net "M_D_CPU1_SA_DQ<16>")
	)
	(arc
		(start 86.21395 -235.086906)
		(mid 86.396201 -235.137256)
		(end 86.57971 -235.091732)
		(width 0.0889)
		(layer "In4.Cu")
		(net "M_D_CPU1_SA_DQ<16>")
	)
	(arc
		(start 87.162386 -235.091732)
		(mid 87.345894 -235.137226)
		(end 87.528146 -235.086906)
		(width 0.0889)
		(layer "In4.Cu")
		(net "M_D_CPU1_SA_DQ<16>")
	)
	(arc
		(start 90.348054 -235.086906)
		(mid 90.595767 -235.011686)
		(end 90.850974 -235.055156)
		(width 0.0889)
		(layer "In4.Cu")
		(net "M_D_CPU1_SA_DQ<16>")
	)
	(arc
		(start 89.034112 -235.086906)
		(mid 89.221056 -235.137161)
		(end 89.408 -235.086906)
		(width 0.0889)
		(layer "In4.Cu")
		(net "M_D_CPU1_SA_DQ<16>")
	)
	(arc
		(start 80.948022 -235.086906)
		(mid 81.230978 -235.010729)
		(end 81.513934 -235.086906)
		(width 0.0889)
		(layer "In4.Cu")
		(net "M_D_CPU1_SA_DQ<16>")
	)
	(arc
		(start 80.008222 -235.086906)
		(mid 80.291178 -235.010729)
		(end 80.574134 -235.086906)
		(width 0.0889)
		(layer "In4.Cu")
		(net "M_D_CPU1_SA_DQ<16>")
	)
	(arc
		(start 79.654908 -235.098082)
		(mid 79.832986 -235.137066)
		(end 80.008222 -235.086906)
		(width 0.0889)
		(layer "In4.Cu")
		(net "M_D_CPU1_SA_DQ<16>")
	)
	(arc
		(start 84.334096 -235.086906)
		(mid 84.52104 -235.137161)
		(end 84.707984 -235.086906)
		(width 0.0889)
		(layer "In4.Cu")
		(net "M_D_CPU1_SA_DQ<16>")
	)
	(arc
		(start 84.707984 -235.086906)
		(mid 84.99094 -235.010729)
		(end 85.273896 -235.086906)
		(width 0.0889)
		(layer "In4.Cu")
		(net "M_D_CPU1_SA_DQ<16>")
	)
	(arc
		(start 89.973912 -235.086906)
		(mid 90.156163 -235.137256)
		(end 90.339672 -235.091732)
		(width 0.0889)
		(layer "In4.Cu")
		(net "M_D_CPU1_SA_DQ<16>")
	)
	(arc
		(start 85.273896 -235.086906)
		(mid 85.456147 -235.137256)
		(end 85.639656 -235.091732)
		(width 0.0889)
		(layer "In4.Cu")
		(net "M_D_CPU1_SA_DQ<16>")
	)
	(segment
		(start 92.507816 -235.030264)
		(end 92.040964 -234.764326)
		(width 0.10668)
		(layer "F.Cu")
		(net "M_D_CPU1_SA_DQ<15>")
	)
	(segment
		(start 60.013088 -215.61044)
		(end 69.64045 -225.237802)
		(width 0.14478)
		(layer "In4.Cu")
		(net "M_D_CPU1_SA_DQ<15>")
	)
	(segment
		(start 75.182222 -232.338118)
		(end 76.256642 -232.338118)
		(width 0.14478)
		(layer "In4.Cu")
		(net "M_D_CPU1_SA_DQ<15>")
	)
	(segment
		(start 49.372266 -215.61044)
		(end 50.222404 -214.760302)
		(width 0.14478)
		(layer "In4.Cu")
		(net "M_D_CPU1_SA_DQ<15>")
	)
	(segment
		(start 33.9344 -215.447372)
		(end 33.9344 -215.162892)
		(width 0.14478)
		(layer "In4.Cu")
		(net "M_D_CPU1_SA_DQ<15>")
	)
	(segment
		(start 88.094058 -234.441746)
		(end 88.10244 -234.43692)
		(width 0.0889)
		(layer "In4.Cu")
		(net "M_D_CPU1_SA_DQ<15>")
	)
	(segment
		(start 91.85402 -234.441746)
		(end 91.862402 -234.43692)
		(width 0.0889)
		(layer "In4.Cu")
		(net "M_D_CPU1_SA_DQ<15>")
	)
	(segment
		(start 50.222404 -214.760302)
		(end 53.256434 -214.760302)
		(width 0.14478)
		(layer "In4.Cu")
		(net "M_D_CPU1_SA_DQ<15>")
	)
	(segment
		(start 69.64045 -225.237802)
		(end 69.64045 -226.796346)
		(width 0.14478)
		(layer "In4.Cu")
		(net "M_D_CPU1_SA_DQ<15>")
	)
	(segment
		(start 53.256434 -214.760302)
		(end 54.106572 -215.61044)
		(width 0.14478)
		(layer "In4.Cu")
		(net "M_D_CPU1_SA_DQ<15>")
	)
	(segment
		(start 90.913966 -234.441746)
		(end 90.922348 -234.43692)
		(width 0.0889)
		(layer "In4.Cu")
		(net "M_D_CPU1_SA_DQ<15>")
	)
	(segment
		(start 54.106572 -215.61044)
		(end 60.013088 -215.61044)
		(width 0.14478)
		(layer "In4.Cu")
		(net "M_D_CPU1_SA_DQ<15>")
	)
	(segment
		(start 76.46035 -232.541826)
		(end 76.84643 -232.541826)
		(width 0.0889)
		(layer "In4.Cu")
		(net "M_D_CPU1_SA_DQ<15>")
	)
	(segment
		(start 86.57971 -234.43692)
		(end 86.588092 -234.441746)
		(width 0.0889)
		(layer "In4.Cu")
		(net "M_D_CPU1_SA_DQ<15>")
	)
	(segment
		(start 81.879694 -234.43692)
		(end 81.888076 -234.441746)
		(width 0.0889)
		(layer "In4.Cu")
		(net "M_D_CPU1_SA_DQ<15>")
	)
	(segment
		(start 34.88436 -215.61044)
		(end 35.047428 -215.447372)
		(width 0.14478)
		(layer "In4.Cu")
		(net "M_D_CPU1_SA_DQ<15>")
	)
	(segment
		(start 45.5676 -214.760302)
		(end 46.417738 -215.61044)
		(width 0.14478)
		(layer "In4.Cu")
		(net "M_D_CPU1_SA_DQ<15>")
	)
	(segment
		(start 87.154004 -234.441746)
		(end 87.162386 -234.43692)
		(width 0.0889)
		(layer "In4.Cu")
		(net "M_D_CPU1_SA_DQ<15>")
	)
	(segment
		(start 77.90307 -233.598466)
		(end 78.59903 -233.598466)
		(width 0.0889)
		(layer "In4.Cu")
		(net "M_D_CPU1_SA_DQ<15>")
	)
	(segment
		(start 69.64045 -226.796346)
		(end 75.182222 -232.338118)
		(width 0.14478)
		(layer "In4.Cu")
		(net "M_D_CPU1_SA_DQ<15>")
	)
	(segment
		(start 35.210496 -214.999824)
		(end 35.440874 -214.999824)
		(width 0.14478)
		(layer "In4.Cu")
		(net "M_D_CPU1_SA_DQ<15>")
	)
	(segment
		(start 35.76701 -215.61044)
		(end 41.884092 -215.61044)
		(width 0.14478)
		(layer "In4.Cu")
		(net "M_D_CPU1_SA_DQ<15>")
	)
	(segment
		(start 90.339672 -234.43692)
		(end 90.348054 -234.441746)
		(width 0.0889)
		(layer "In4.Cu")
		(net "M_D_CPU1_SA_DQ<15>")
	)
	(segment
		(start 92.195142 -234.498896)
		(end 92.040964 -234.764326)
		(width 0.0889)
		(layer "In4.Cu")
		(net "M_D_CPU1_SA_DQ<15>")
	)
	(segment
		(start 34.490914 -215.162892)
		(end 34.490914 -215.447372)
		(width 0.14478)
		(layer "In4.Cu")
		(net "M_D_CPU1_SA_DQ<15>")
	)
	(segment
		(start 85.639656 -234.43692)
		(end 85.648038 -234.441746)
		(width 0.0889)
		(layer "In4.Cu")
		(net "M_D_CPU1_SA_DQ<15>")
	)
	(segment
		(start 34.097468 -214.999824)
		(end 34.327846 -214.999824)
		(width 0.14478)
		(layer "In4.Cu")
		(net "M_D_CPU1_SA_DQ<15>")
	)
	(segment
		(start 35.603942 -215.162892)
		(end 35.603942 -215.447372)
		(width 0.14478)
		(layer "In4.Cu")
		(net "M_D_CPU1_SA_DQ<15>")
	)
	(segment
		(start 78.59903 -233.598466)
		(end 79.391764 -234.3912)
		(width 0.0889)
		(layer "In4.Cu")
		(net "M_D_CPU1_SA_DQ<15>")
	)
	(segment
		(start 35.440874 -214.999824)
		(end 35.603942 -215.162892)
		(width 0.14478)
		(layer "In4.Cu")
		(net "M_D_CPU1_SA_DQ<15>")
	)
	(segment
		(start 46.417738 -215.61044)
		(end 49.372266 -215.61044)
		(width 0.14478)
		(layer "In4.Cu")
		(net "M_D_CPU1_SA_DQ<15>")
	)
	(segment
		(start 42.73423 -214.760302)
		(end 45.5676 -214.760302)
		(width 0.14478)
		(layer "In4.Cu")
		(net "M_D_CPU1_SA_DQ<15>")
	)
	(segment
		(start 76.256642 -232.338118)
		(end 76.46035 -232.541826)
		(width 0.0889)
		(layer "In4.Cu")
		(net "M_D_CPU1_SA_DQ<15>")
	)
	(segment
		(start 35.603942 -215.447372)
		(end 35.76701 -215.61044)
		(width 0.14478)
		(layer "In4.Cu")
		(net "M_D_CPU1_SA_DQ<15>")
	)
	(segment
		(start 79.391764 -234.3912)
		(end 79.821024 -234.3912)
		(width 0.0889)
		(layer "In4.Cu")
		(net "M_D_CPU1_SA_DQ<15>")
	)
	(segment
		(start 35.047428 -215.447372)
		(end 35.047428 -215.162892)
		(width 0.14478)
		(layer "In4.Cu")
		(net "M_D_CPU1_SA_DQ<15>")
	)
	(segment
		(start 33.771332 -215.61044)
		(end 33.9344 -215.447372)
		(width 0.14478)
		(layer "In4.Cu")
		(net "M_D_CPU1_SA_DQ<15>")
	)
	(segment
		(start 34.490914 -215.447372)
		(end 34.653982 -215.61044)
		(width 0.14478)
		(layer "In4.Cu")
		(net "M_D_CPU1_SA_DQ<15>")
	)
	(segment
		(start 33.9344 -215.162892)
		(end 34.097468 -214.999824)
		(width 0.14478)
		(layer "In4.Cu")
		(net "M_D_CPU1_SA_DQ<15>")
	)
	(segment
		(start 92.17279 -234.415584)
		(end 92.195142 -234.498896)
		(width 0.0889)
		(layer "In4.Cu")
		(net "M_D_CPU1_SA_DQ<15>")
	)
	(segment
		(start 35.047428 -215.162892)
		(end 35.210496 -214.999824)
		(width 0.14478)
		(layer "In4.Cu")
		(net "M_D_CPU1_SA_DQ<15>")
	)
	(segment
		(start 32.695896 -215.185244)
		(end 33.121092 -215.61044)
		(width 0.14478)
		(layer "In4.Cu")
		(net "M_D_CPU1_SA_DQ<15>")
	)
	(segment
		(start 83.394042 -234.441746)
		(end 83.402424 -234.43692)
		(width 0.0889)
		(layer "In4.Cu")
		(net "M_D_CPU1_SA_DQ<15>")
	)
	(segment
		(start 76.84643 -232.541826)
		(end 77.90307 -233.598466)
		(width 0.0889)
		(layer "In4.Cu")
		(net "M_D_CPU1_SA_DQ<15>")
	)
	(segment
		(start 41.884092 -215.61044)
		(end 42.73423 -214.760302)
		(width 0.14478)
		(layer "In4.Cu")
		(net "M_D_CPU1_SA_DQ<15>")
	)
	(segment
		(start 34.653982 -215.61044)
		(end 34.88436 -215.61044)
		(width 0.14478)
		(layer "In4.Cu")
		(net "M_D_CPU1_SA_DQ<15>")
	)
	(segment
		(start 33.121092 -215.61044)
		(end 33.771332 -215.61044)
		(width 0.14478)
		(layer "In4.Cu")
		(net "M_D_CPU1_SA_DQ<15>")
	)
	(segment
		(start 34.327846 -214.999824)
		(end 34.490914 -215.162892)
		(width 0.14478)
		(layer "In4.Cu")
		(net "M_D_CPU1_SA_DQ<15>")
	)
	(segment
		(start 82.453988 -234.441746)
		(end 82.46237 -234.43692)
		(width 0.0889)
		(layer "In4.Cu")
		(net "M_D_CPU1_SA_DQ<15>")
	)
	(arc
		(start 81.888076 -234.441746)
		(mid 82.171032 -234.517923)
		(end 82.453988 -234.441746)
		(width 0.0889)
		(layer "In4.Cu")
		(net "M_D_CPU1_SA_DQ<15>")
	)
	(arc
		(start 84.334096 -234.441746)
		(mid 84.52104 -234.391491)
		(end 84.707984 -234.441746)
		(width 0.0889)
		(layer "In4.Cu")
		(net "M_D_CPU1_SA_DQ<15>")
	)
	(arc
		(start 90.922348 -234.43692)
		(mid 91.105856 -234.391426)
		(end 91.288108 -234.441746)
		(width 0.0889)
		(layer "In4.Cu")
		(net "M_D_CPU1_SA_DQ<15>")
	)
	(arc
		(start 80.008222 -234.441746)
		(mid 80.291178 -234.517923)
		(end 80.574134 -234.441746)
		(width 0.0889)
		(layer "In4.Cu")
		(net "M_D_CPU1_SA_DQ<15>")
	)
	(arc
		(start 91.862402 -234.43692)
		(mid 92.015272 -234.392279)
		(end 92.17279 -234.415584)
		(width 0.0889)
		(layer "In4.Cu")
		(net "M_D_CPU1_SA_DQ<15>")
	)
	(arc
		(start 83.402424 -234.43692)
		(mid 83.585932 -234.391426)
		(end 83.768184 -234.441746)
		(width 0.0889)
		(layer "In4.Cu")
		(net "M_D_CPU1_SA_DQ<15>")
	)
	(arc
		(start 84.707984 -234.441746)
		(mid 84.99094 -234.517923)
		(end 85.273896 -234.441746)
		(width 0.0889)
		(layer "In4.Cu")
		(net "M_D_CPU1_SA_DQ<15>")
	)
	(arc
		(start 90.348054 -234.441746)
		(mid 90.63101 -234.517923)
		(end 90.913966 -234.441746)
		(width 0.0889)
		(layer "In4.Cu")
		(net "M_D_CPU1_SA_DQ<15>")
	)
	(arc
		(start 89.973912 -234.441746)
		(mid 90.156163 -234.391396)
		(end 90.339672 -234.43692)
		(width 0.0889)
		(layer "In4.Cu")
		(net "M_D_CPU1_SA_DQ<15>")
	)
	(arc
		(start 81.513934 -234.441746)
		(mid 81.696185 -234.391396)
		(end 81.879694 -234.43692)
		(width 0.0889)
		(layer "In4.Cu")
		(net "M_D_CPU1_SA_DQ<15>")
	)
	(arc
		(start 83.768184 -234.441746)
		(mid 84.05114 -234.517923)
		(end 84.334096 -234.441746)
		(width 0.0889)
		(layer "In4.Cu")
		(net "M_D_CPU1_SA_DQ<15>")
	)
	(arc
		(start 80.574134 -234.441746)
		(mid 80.761078 -234.391491)
		(end 80.948022 -234.441746)
		(width 0.0889)
		(layer "In4.Cu")
		(net "M_D_CPU1_SA_DQ<15>")
	)
	(arc
		(start 85.273896 -234.441746)
		(mid 85.456147 -234.391396)
		(end 85.639656 -234.43692)
		(width 0.0889)
		(layer "In4.Cu")
		(net "M_D_CPU1_SA_DQ<15>")
	)
	(arc
		(start 89.034112 -234.441746)
		(mid 89.221056 -234.391491)
		(end 89.408 -234.441746)
		(width 0.0889)
		(layer "In4.Cu")
		(net "M_D_CPU1_SA_DQ<15>")
	)
	(arc
		(start 91.288108 -234.441746)
		(mid 91.571064 -234.517923)
		(end 91.85402 -234.441746)
		(width 0.0889)
		(layer "In4.Cu")
		(net "M_D_CPU1_SA_DQ<15>")
	)
	(arc
		(start 87.162386 -234.43692)
		(mid 87.345894 -234.391426)
		(end 87.528146 -234.441746)
		(width 0.0889)
		(layer "In4.Cu")
		(net "M_D_CPU1_SA_DQ<15>")
	)
	(arc
		(start 79.821024 -234.3912)
		(mid 79.917971 -234.404083)
		(end 80.008222 -234.441746)
		(width 0.0889)
		(layer "In4.Cu")
		(net "M_D_CPU1_SA_DQ<15>")
	)
	(arc
		(start 80.948022 -234.441746)
		(mid 81.230978 -234.517923)
		(end 81.513934 -234.441746)
		(width 0.0889)
		(layer "In4.Cu")
		(net "M_D_CPU1_SA_DQ<15>")
	)
	(arc
		(start 86.21395 -234.441746)
		(mid 86.396201 -234.391396)
		(end 86.57971 -234.43692)
		(width 0.0889)
		(layer "In4.Cu")
		(net "M_D_CPU1_SA_DQ<15>")
	)
	(arc
		(start 82.82813 -234.441746)
		(mid 83.111086 -234.517923)
		(end 83.394042 -234.441746)
		(width 0.0889)
		(layer "In4.Cu")
		(net "M_D_CPU1_SA_DQ<15>")
	)
	(arc
		(start 86.588092 -234.441746)
		(mid 86.871048 -234.517923)
		(end 87.154004 -234.441746)
		(width 0.0889)
		(layer "In4.Cu")
		(net "M_D_CPU1_SA_DQ<15>")
	)
	(arc
		(start 89.408 -234.441746)
		(mid 89.690956 -234.517923)
		(end 89.973912 -234.441746)
		(width 0.0889)
		(layer "In4.Cu")
		(net "M_D_CPU1_SA_DQ<15>")
	)
	(arc
		(start 88.10244 -234.43692)
		(mid 88.285948 -234.391426)
		(end 88.4682 -234.441746)
		(width 0.0889)
		(layer "In4.Cu")
		(net "M_D_CPU1_SA_DQ<15>")
	)
	(arc
		(start 82.46237 -234.43692)
		(mid 82.645878 -234.391426)
		(end 82.82813 -234.441746)
		(width 0.0889)
		(layer "In4.Cu")
		(net "M_D_CPU1_SA_DQ<15>")
	)
	(arc
		(start 87.528146 -234.441746)
		(mid 87.811102 -234.517923)
		(end 88.094058 -234.441746)
		(width 0.0889)
		(layer "In4.Cu")
		(net "M_D_CPU1_SA_DQ<15>")
	)
	(arc
		(start 88.4682 -234.441746)
		(mid 88.751156 -234.517923)
		(end 89.034112 -234.441746)
		(width 0.0889)
		(layer "In4.Cu")
		(net "M_D_CPU1_SA_DQ<15>")
	)
	(arc
		(start 85.648038 -234.441746)
		(mid 85.930994 -234.517923)
		(end 86.21395 -234.441746)
		(width 0.0889)
		(layer "In4.Cu")
		(net "M_D_CPU1_SA_DQ<15>")
	)
	(segment
		(start 91.097862 -234.220258)
		(end 90.63101 -233.95432)
		(width 0.10668)
		(layer "F.Cu")
		(net "M_D_CPU1_SA_DQ<14>")
	)
	(segment
		(start 89.504012 -233.63174)
		(end 89.512394 -233.626914)
		(width 0.0889)
		(layer "In4.Cu")
		(net "M_D_CPU1_SA_DQ<14>")
	)
	(segment
		(start 77.21727 -231.642666)
		(end 77.21727 -231.957626)
		(width 0.0889)
		(layer "In4.Cu")
		(net "M_D_CPU1_SA_DQ<14>")
	)
	(segment
		(start 84.803996 -233.63174)
		(end 84.812378 -233.626914)
		(width 0.0889)
		(layer "In4.Cu")
		(net "M_D_CPU1_SA_DQ<14>")
	)
	(segment
		(start 88.929718 -233.626914)
		(end 88.9381 -233.63174)
		(width 0.0889)
		(layer "In4.Cu")
		(net "M_D_CPU1_SA_DQ<14>")
	)
	(segment
		(start 34.97453 -213.910418)
		(end 35.204908 -213.910418)
		(width 0.14478)
		(layer "In4.Cu")
		(net "M_D_CPU1_SA_DQ<14>")
	)
	(segment
		(start 85.74405 -233.63174)
		(end 85.752432 -233.626914)
		(width 0.0889)
		(layer "In4.Cu")
		(net "M_D_CPU1_SA_DQ<14>")
	)
	(segment
		(start 79.539592 -233.631994)
		(end 79.561182 -233.64444)
		(width 0.0889)
		(layer "In4.Cu")
		(net "M_D_CPU1_SA_DQ<14>")
	)
	(segment
		(start 35.92449 -213.74735)
		(end 36.087558 -213.910418)
		(width 0.14478)
		(layer "In4.Cu")
		(net "M_D_CPU1_SA_DQ<14>")
	)
	(segment
		(start 70.65772 -224.83953)
		(end 70.65772 -226.387406)
		(width 0.14478)
		(layer "In4.Cu")
		(net "M_D_CPU1_SA_DQ<14>")
	)
	(segment
		(start 90.762582 -233.605578)
		(end 90.784934 -233.68889)
		(width 0.0889)
		(layer "In4.Cu")
		(net "M_D_CPU1_SA_DQ<14>")
	)
	(segment
		(start 76.895452 -231.320848)
		(end 77.21727 -231.642666)
		(width 0.0889)
		(layer "In4.Cu")
		(net "M_D_CPU1_SA_DQ<14>")
	)
	(segment
		(start 34.254948 -213.74735)
		(end 34.254948 -213.288372)
		(width 0.14478)
		(layer "In4.Cu")
		(net "M_D_CPU1_SA_DQ<14>")
	)
	(segment
		(start 87.989664 -233.626914)
		(end 87.998046 -233.63174)
		(width 0.0889)
		(layer "In4.Cu")
		(net "M_D_CPU1_SA_DQ<14>")
	)
	(segment
		(start 54.106572 -213.910418)
		(end 59.728608 -213.910418)
		(width 0.14478)
		(layer "In4.Cu")
		(net "M_D_CPU1_SA_DQ<14>")
	)
	(segment
		(start 32.695896 -213.485222)
		(end 33.121092 -213.910418)
		(width 0.14478)
		(layer "In4.Cu")
		(net "M_D_CPU1_SA_DQ<14>")
	)
	(segment
		(start 41.884092 -213.910418)
		(end 42.73423 -213.06028)
		(width 0.14478)
		(layer "In4.Cu")
		(net "M_D_CPU1_SA_DQ<14>")
	)
	(segment
		(start 35.367976 -213.230714)
		(end 35.531044 -213.067646)
		(width 0.14478)
		(layer "In4.Cu")
		(net "M_D_CPU1_SA_DQ<14>")
	)
	(segment
		(start 42.73423 -213.06028)
		(end 45.5676 -213.06028)
		(width 0.14478)
		(layer "In4.Cu")
		(net "M_D_CPU1_SA_DQ<14>")
	)
	(segment
		(start 80.46974 -233.626914)
		(end 80.478122 -233.63174)
		(width 0.0889)
		(layer "In4.Cu")
		(net "M_D_CPU1_SA_DQ<14>")
	)
	(segment
		(start 46.417738 -213.910418)
		(end 49.372266 -213.910418)
		(width 0.14478)
		(layer "In4.Cu")
		(net "M_D_CPU1_SA_DQ<14>")
	)
	(segment
		(start 34.811462 -213.74735)
		(end 34.97453 -213.910418)
		(width 0.14478)
		(layer "In4.Cu")
		(net "M_D_CPU1_SA_DQ<14>")
	)
	(segment
		(start 34.648394 -213.125304)
		(end 34.811462 -213.288372)
		(width 0.14478)
		(layer "In4.Cu")
		(net "M_D_CPU1_SA_DQ<14>")
	)
	(segment
		(start 35.92449 -213.230714)
		(end 35.92449 -213.74735)
		(width 0.14478)
		(layer "In4.Cu")
		(net "M_D_CPU1_SA_DQ<14>")
	)
	(segment
		(start 50.222404 -213.06028)
		(end 53.256434 -213.06028)
		(width 0.14478)
		(layer "In4.Cu")
		(net "M_D_CPU1_SA_DQ<14>")
	)
	(segment
		(start 77.21727 -231.957626)
		(end 78.18247 -232.922826)
		(width 0.0889)
		(layer "In4.Cu")
		(net "M_D_CPU1_SA_DQ<14>")
	)
	(segment
		(start 35.761422 -213.067646)
		(end 35.92449 -213.230714)
		(width 0.14478)
		(layer "In4.Cu")
		(net "M_D_CPU1_SA_DQ<14>")
	)
	(segment
		(start 35.367976 -213.74735)
		(end 35.367976 -213.230714)
		(width 0.14478)
		(layer "In4.Cu")
		(net "M_D_CPU1_SA_DQ<14>")
	)
	(segment
		(start 35.531044 -213.067646)
		(end 35.761422 -213.067646)
		(width 0.14478)
		(layer "In4.Cu")
		(net "M_D_CPU1_SA_DQ<14>")
	)
	(segment
		(start 35.204908 -213.910418)
		(end 35.367976 -213.74735)
		(width 0.14478)
		(layer "In4.Cu")
		(net "M_D_CPU1_SA_DQ<14>")
	)
	(segment
		(start 36.087558 -213.910418)
		(end 41.884092 -213.910418)
		(width 0.14478)
		(layer "In4.Cu")
		(net "M_D_CPU1_SA_DQ<14>")
	)
	(segment
		(start 34.418016 -213.125304)
		(end 34.648394 -213.125304)
		(width 0.14478)
		(layer "In4.Cu")
		(net "M_D_CPU1_SA_DQ<14>")
	)
	(segment
		(start 75.591162 -231.320848)
		(end 75.91933 -231.320848)
		(width 0.14478)
		(layer "In4.Cu")
		(net "M_D_CPU1_SA_DQ<14>")
	)
	(segment
		(start 70.65772 -226.387406)
		(end 75.591162 -231.320848)
		(width 0.14478)
		(layer "In4.Cu")
		(net "M_D_CPU1_SA_DQ<14>")
	)
	(segment
		(start 45.5676 -213.06028)
		(end 46.417738 -213.910418)
		(width 0.14478)
		(layer "In4.Cu")
		(net "M_D_CPU1_SA_DQ<14>")
	)
	(segment
		(start 53.256434 -213.06028)
		(end 54.106572 -213.910418)
		(width 0.14478)
		(layer "In4.Cu")
		(net "M_D_CPU1_SA_DQ<14>")
	)
	(segment
		(start 90.784934 -233.68889)
		(end 90.63101 -233.95432)
		(width 0.0889)
		(layer "In4.Cu")
		(net "M_D_CPU1_SA_DQ<14>")
	)
	(segment
		(start 83.289648 -233.626914)
		(end 83.29803 -233.63174)
		(width 0.0889)
		(layer "In4.Cu")
		(net "M_D_CPU1_SA_DQ<14>")
	)
	(segment
		(start 75.91933 -231.320848)
		(end 76.895452 -231.320848)
		(width 0.0889)
		(layer "In4.Cu")
		(net "M_D_CPU1_SA_DQ<14>")
	)
	(segment
		(start 78.8035 -232.922826)
		(end 79.423006 -233.542332)
		(width 0.0889)
		(layer "In4.Cu")
		(net "M_D_CPU1_SA_DQ<14>")
	)
	(segment
		(start 33.121092 -213.910418)
		(end 34.09188 -213.910418)
		(width 0.14478)
		(layer "In4.Cu")
		(net "M_D_CPU1_SA_DQ<14>")
	)
	(segment
		(start 84.229702 -233.626914)
		(end 84.238084 -233.63174)
		(width 0.0889)
		(layer "In4.Cu")
		(net "M_D_CPU1_SA_DQ<14>")
	)
	(segment
		(start 34.09188 -213.910418)
		(end 34.254948 -213.74735)
		(width 0.14478)
		(layer "In4.Cu")
		(net "M_D_CPU1_SA_DQ<14>")
	)
	(segment
		(start 49.372266 -213.910418)
		(end 50.222404 -213.06028)
		(width 0.14478)
		(layer "In4.Cu")
		(net "M_D_CPU1_SA_DQ<14>")
	)
	(segment
		(start 59.728608 -213.910418)
		(end 70.65772 -224.83953)
		(width 0.14478)
		(layer "In4.Cu")
		(net "M_D_CPU1_SA_DQ<14>")
	)
	(segment
		(start 81.044034 -233.63174)
		(end 81.052416 -233.626914)
		(width 0.0889)
		(layer "In4.Cu")
		(net "M_D_CPU1_SA_DQ<14>")
	)
	(segment
		(start 34.254948 -213.288372)
		(end 34.418016 -213.125304)
		(width 0.14478)
		(layer "In4.Cu")
		(net "M_D_CPU1_SA_DQ<14>")
	)
	(segment
		(start 34.811462 -213.288372)
		(end 34.811462 -213.74735)
		(width 0.14478)
		(layer "In4.Cu")
		(net "M_D_CPU1_SA_DQ<14>")
	)
	(segment
		(start 78.18247 -232.922826)
		(end 78.8035 -232.922826)
		(width 0.0889)
		(layer "In4.Cu")
		(net "M_D_CPU1_SA_DQ<14>")
	)
	(arc
		(start 80.478122 -233.63174)
		(mid 80.761078 -233.707917)
		(end 81.044034 -233.63174)
		(width 0.0889)
		(layer "In4.Cu")
		(net "M_D_CPU1_SA_DQ<14>")
	)
	(arc
		(start 85.178138 -233.63174)
		(mid 85.461094 -233.707917)
		(end 85.74405 -233.63174)
		(width 0.0889)
		(layer "In4.Cu")
		(net "M_D_CPU1_SA_DQ<14>")
	)
	(arc
		(start 86.684104 -233.63174)
		(mid 86.871048 -233.581485)
		(end 87.057992 -233.63174)
		(width 0.0889)
		(layer "In4.Cu")
		(net "M_D_CPU1_SA_DQ<14>")
	)
	(arc
		(start 87.998046 -233.63174)
		(mid 88.281002 -233.707917)
		(end 88.563958 -233.63174)
		(width 0.0889)
		(layer "In4.Cu")
		(net "M_D_CPU1_SA_DQ<14>")
	)
	(arc
		(start 83.29803 -233.63174)
		(mid 83.580986 -233.707917)
		(end 83.863942 -233.63174)
		(width 0.0889)
		(layer "In4.Cu")
		(net "M_D_CPU1_SA_DQ<14>")
	)
	(arc
		(start 90.444066 -233.63174)
		(mid 90.600385 -233.582745)
		(end 90.762582 -233.605578)
		(width 0.0889)
		(layer "In4.Cu")
		(net "M_D_CPU1_SA_DQ<14>")
	)
	(arc
		(start 83.863942 -233.63174)
		(mid 84.046193 -233.58139)
		(end 84.229702 -233.626914)
		(width 0.0889)
		(layer "In4.Cu")
		(net "M_D_CPU1_SA_DQ<14>")
	)
	(arc
		(start 79.561182 -233.64444)
		(mid 79.834211 -233.707759)
		(end 80.10398 -233.63174)
		(width 0.0889)
		(layer "In4.Cu")
		(net "M_D_CPU1_SA_DQ<14>")
	)
	(arc
		(start 85.752432 -233.626914)
		(mid 85.93594 -233.58142)
		(end 86.118192 -233.63174)
		(width 0.0889)
		(layer "In4.Cu")
		(net "M_D_CPU1_SA_DQ<14>")
	)
	(arc
		(start 84.812378 -233.626914)
		(mid 84.995886 -233.58142)
		(end 85.178138 -233.63174)
		(width 0.0889)
		(layer "In4.Cu")
		(net "M_D_CPU1_SA_DQ<14>")
	)
	(arc
		(start 79.423006 -233.542332)
		(mid 79.478355 -233.590991)
		(end 79.539592 -233.631994)
		(width 0.0889)
		(layer "In4.Cu")
		(net "M_D_CPU1_SA_DQ<14>")
	)
	(arc
		(start 80.10398 -233.63174)
		(mid 80.286231 -233.58139)
		(end 80.46974 -233.626914)
		(width 0.0889)
		(layer "In4.Cu")
		(net "M_D_CPU1_SA_DQ<14>")
	)
	(arc
		(start 87.057992 -233.63174)
		(mid 87.340948 -233.707917)
		(end 87.623904 -233.63174)
		(width 0.0889)
		(layer "In4.Cu")
		(net "M_D_CPU1_SA_DQ<14>")
	)
	(arc
		(start 84.238084 -233.63174)
		(mid 84.52104 -233.707917)
		(end 84.803996 -233.63174)
		(width 0.0889)
		(layer "In4.Cu")
		(net "M_D_CPU1_SA_DQ<14>")
	)
	(arc
		(start 82.357976 -233.63174)
		(mid 82.640932 -233.707917)
		(end 82.923888 -233.63174)
		(width 0.0889)
		(layer "In4.Cu")
		(net "M_D_CPU1_SA_DQ<14>")
	)
	(arc
		(start 86.118192 -233.63174)
		(mid 86.401148 -233.707917)
		(end 86.684104 -233.63174)
		(width 0.0889)
		(layer "In4.Cu")
		(net "M_D_CPU1_SA_DQ<14>")
	)
	(arc
		(start 88.563958 -233.63174)
		(mid 88.746209 -233.58139)
		(end 88.929718 -233.626914)
		(width 0.0889)
		(layer "In4.Cu")
		(net "M_D_CPU1_SA_DQ<14>")
	)
	(arc
		(start 88.9381 -233.63174)
		(mid 89.221056 -233.707917)
		(end 89.504012 -233.63174)
		(width 0.0889)
		(layer "In4.Cu")
		(net "M_D_CPU1_SA_DQ<14>")
	)
	(arc
		(start 81.984088 -233.63174)
		(mid 82.171032 -233.581485)
		(end 82.357976 -233.63174)
		(width 0.0889)
		(layer "In4.Cu")
		(net "M_D_CPU1_SA_DQ<14>")
	)
	(arc
		(start 87.623904 -233.63174)
		(mid 87.806155 -233.58139)
		(end 87.989664 -233.626914)
		(width 0.0889)
		(layer "In4.Cu")
		(net "M_D_CPU1_SA_DQ<14>")
	)
	(arc
		(start 82.923888 -233.63174)
		(mid 83.106139 -233.58139)
		(end 83.289648 -233.626914)
		(width 0.0889)
		(layer "In4.Cu")
		(net "M_D_CPU1_SA_DQ<14>")
	)
	(arc
		(start 89.878154 -233.63174)
		(mid 90.16111 -233.707917)
		(end 90.444066 -233.63174)
		(width 0.0889)
		(layer "In4.Cu")
		(net "M_D_CPU1_SA_DQ<14>")
	)
	(arc
		(start 81.418176 -233.63174)
		(mid 81.701132 -233.707917)
		(end 81.984088 -233.63174)
		(width 0.0889)
		(layer "In4.Cu")
		(net "M_D_CPU1_SA_DQ<14>")
	)
	(arc
		(start 89.512394 -233.626914)
		(mid 89.695902 -233.58142)
		(end 89.878154 -233.63174)
		(width 0.0889)
		(layer "In4.Cu")
		(net "M_D_CPU1_SA_DQ<14>")
	)
	(arc
		(start 81.052416 -233.626914)
		(mid 81.235924 -233.58142)
		(end 81.418176 -233.63174)
		(width 0.0889)
		(layer "In4.Cu")
		(net "M_D_CPU1_SA_DQ<14>")
	)
	(segment
		(start 92.97797 -234.220258)
		(end 92.511118 -233.95432)
		(width 0.10668)
		(layer "F.Cu")
		(net "M_D_CPU1_SA_DQ<13>")
	)
	(segment
		(start 57.985914 -214.53475)
		(end 57.985914 -214.854282)
		(width 0.14478)
		(layer "In4.Cu")
		(net "M_D_CPU1_SA_DQ<13>")
	)
	(segment
		(start 57.43448 -214.53475)
		(end 57.596024 -214.373206)
		(width 0.14478)
		(layer "In4.Cu")
		(net "M_D_CPU1_SA_DQ<13>")
	)
	(segment
		(start 43.147488 -214.073486)
		(end 43.147488 -214.133176)
		(width 0.14478)
		(layer "In4.Cu")
		(net "M_D_CPU1_SA_DQ<13>")
	)
	(segment
		(start 53.23459 -213.910418)
		(end 54.084474 -214.760302)
		(width 0.14478)
		(layer "In4.Cu")
		(net "M_D_CPU1_SA_DQ<13>")
	)
	(segment
		(start 38.604444 -214.376)
		(end 38.834822 -214.376)
		(width 0.14478)
		(layer "In4.Cu")
		(net "M_D_CPU1_SA_DQ<13>")
	)
	(segment
		(start 48.973232 -214.92337)
		(end 49.1363 -214.760302)
		(width 0.14478)
		(layer "In4.Cu")
		(net "M_D_CPU1_SA_DQ<13>")
	)
	(segment
		(start 38.04793 -215.144604)
		(end 38.278308 -215.144604)
		(width 0.14478)
		(layer "In4.Cu")
		(net "M_D_CPU1_SA_DQ<13>")
	)
	(segment
		(start 49.40681 -214.760302)
		(end 50.256694 -213.910418)
		(width 0.14478)
		(layer "In4.Cu")
		(net "M_D_CPU1_SA_DQ<13>")
	)
	(segment
		(start 70.20306 -226.575874)
		(end 75.402694 -231.775508)
		(width 0.14478)
		(layer "In4.Cu")
		(net "M_D_CPU1_SA_DQ<13>")
	)
	(segment
		(start 40.77716 -214.92337)
		(end 40.77716 -214.986616)
		(width 0.14478)
		(layer "In4.Cu")
		(net "M_D_CPU1_SA_DQ<13>")
	)
	(segment
		(start 79.629254 -234.2007)
		(end 79.821278 -234.2007)
		(width 0.0889)
		(layer "In4.Cu")
		(net "M_D_CPU1_SA_DQ<13>")
	)
	(segment
		(start 43.86707 -213.910418)
		(end 45.55871 -213.910418)
		(width 0.14478)
		(layer "In4.Cu")
		(net "M_D_CPU1_SA_DQ<13>")
	)
	(segment
		(start 51.273202 -214.073486)
		(end 51.43627 -213.910418)
		(width 0.14478)
		(layer "In4.Cu")
		(net "M_D_CPU1_SA_DQ<13>")
	)
	(segment
		(start 91.749626 -234.281726)
		(end 91.758008 -234.2769)
		(width 0.0889)
		(layer "In4.Cu")
		(net "M_D_CPU1_SA_DQ<13>")
	)
	(segment
		(start 80.46974 -234.281726)
		(end 80.478122 -234.2769)
		(width 0.0889)
		(layer "In4.Cu")
		(net "M_D_CPU1_SA_DQ<13>")
	)
	(segment
		(start 92.35694 -234.21975)
		(end 92.511118 -233.95432)
		(width 0.0889)
		(layer "In4.Cu")
		(net "M_D_CPU1_SA_DQ<13>")
	)
	(segment
		(start 83.289648 -234.281726)
		(end 83.29803 -234.2769)
		(width 0.0889)
		(layer "In4.Cu")
		(net "M_D_CPU1_SA_DQ<13>")
	)
	(segment
		(start 48.810164 -215.149684)
		(end 48.973232 -214.986616)
		(width 0.14478)
		(layer "In4.Cu")
		(net "M_D_CPU1_SA_DQ<13>")
	)
	(segment
		(start 55.401464 -214.760302)
		(end 56.170068 -214.760302)
		(width 0.14478)
		(layer "In4.Cu")
		(net "M_D_CPU1_SA_DQ<13>")
	)
	(segment
		(start 57.596024 -214.373206)
		(end 57.82437 -214.373206)
		(width 0.14478)
		(layer "In4.Cu")
		(net "M_D_CPU1_SA_DQ<13>")
	)
	(segment
		(start 56.493156 -214.373206)
		(end 56.721502 -214.373206)
		(width 0.14478)
		(layer "In4.Cu")
		(net "M_D_CPU1_SA_DQ<13>")
	)
	(segment
		(start 41.170606 -215.149684)
		(end 41.333674 -214.986616)
		(width 0.14478)
		(layer "In4.Cu")
		(net "M_D_CPU1_SA_DQ<13>")
	)
	(segment
		(start 48.416718 -214.986616)
		(end 48.579786 -215.149684)
		(width 0.14478)
		(layer "In4.Cu")
		(net "M_D_CPU1_SA_DQ<13>")
	)
	(segment
		(start 36.795964 -214.33536)
		(end 37.220906 -214.760302)
		(width 0.14478)
		(layer "In4.Cu")
		(net "M_D_CPU1_SA_DQ<13>")
	)
	(segment
		(start 57.82437 -214.373206)
		(end 57.985914 -214.53475)
		(width 0.14478)
		(layer "In4.Cu")
		(net "M_D_CPU1_SA_DQ<13>")
	)
	(segment
		(start 48.579786 -215.149684)
		(end 48.810164 -215.149684)
		(width 0.14478)
		(layer "In4.Cu")
		(net "M_D_CPU1_SA_DQ<13>")
	)
	(segment
		(start 56.331612 -214.53475)
		(end 56.493156 -214.373206)
		(width 0.14478)
		(layer "In4.Cu")
		(net "M_D_CPU1_SA_DQ<13>")
	)
	(segment
		(start 58.375804 -215.015826)
		(end 58.537348 -214.854282)
		(width 0.14478)
		(layer "In4.Cu")
		(net "M_D_CPU1_SA_DQ<13>")
	)
	(segment
		(start 39.554404 -214.981536)
		(end 39.554404 -214.92337)
		(width 0.14478)
		(layer "In4.Cu")
		(net "M_D_CPU1_SA_DQ<13>")
	)
	(segment
		(start 54.518814 -214.760302)
		(end 54.681882 -214.92337)
		(width 0.14478)
		(layer "In4.Cu")
		(net "M_D_CPU1_SA_DQ<13>")
	)
	(segment
		(start 43.540934 -214.296244)
		(end 43.704002 -214.133176)
		(width 0.14478)
		(layer "In4.Cu")
		(net "M_D_CPU1_SA_DQ<13>")
	)
	(segment
		(start 56.331612 -214.598758)
		(end 56.331612 -214.53475)
		(width 0.14478)
		(layer "In4.Cu")
		(net "M_D_CPU1_SA_DQ<13>")
	)
	(segment
		(start 89.504012 -234.2769)
		(end 89.512394 -234.281726)
		(width 0.0889)
		(layer "In4.Cu")
		(net "M_D_CPU1_SA_DQ<13>")
	)
	(segment
		(start 42.98442 -213.910418)
		(end 43.147488 -214.073486)
		(width 0.14478)
		(layer "In4.Cu")
		(net "M_D_CPU1_SA_DQ<13>")
	)
	(segment
		(start 40.614092 -214.760302)
		(end 40.77716 -214.92337)
		(width 0.14478)
		(layer "In4.Cu")
		(net "M_D_CPU1_SA_DQ<13>")
	)
	(segment
		(start 57.272936 -214.934546)
		(end 57.43448 -214.773002)
		(width 0.14478)
		(layer "In4.Cu")
		(net "M_D_CPU1_SA_DQ<13>")
	)
	(segment
		(start 51.43627 -213.910418)
		(end 53.23459 -213.910418)
		(width 0.14478)
		(layer "In4.Cu")
		(net "M_D_CPU1_SA_DQ<13>")
	)
	(segment
		(start 37.884862 -214.981536)
		(end 38.04793 -215.144604)
		(width 0.14478)
		(layer "In4.Cu")
		(net "M_D_CPU1_SA_DQ<13>")
	)
	(segment
		(start 41.333674 -214.92337)
		(end 41.496742 -214.760302)
		(width 0.14478)
		(layer "In4.Cu")
		(net "M_D_CPU1_SA_DQ<13>")
	)
	(segment
		(start 42.733214 -213.910418)
		(end 42.98442 -213.910418)
		(width 0.14478)
		(layer "In4.Cu")
		(net "M_D_CPU1_SA_DQ<13>")
	)
	(segment
		(start 75.97013 -231.775508)
		(end 76.156312 -231.775508)
		(width 0.0889)
		(layer "In4.Cu")
		(net "M_D_CPU1_SA_DQ<13>")
	)
	(segment
		(start 39.554404 -214.92337)
		(end 39.717472 -214.760302)
		(width 0.14478)
		(layer "In4.Cu")
		(net "M_D_CPU1_SA_DQ<13>")
	)
	(segment
		(start 56.721502 -214.373206)
		(end 56.883046 -214.53475)
		(width 0.14478)
		(layer "In4.Cu")
		(net "M_D_CPU1_SA_DQ<13>")
	)
	(segment
		(start 78.024228 -233.306366)
		(end 78.73492 -233.306366)
		(width 0.0889)
		(layer "In4.Cu")
		(net "M_D_CPU1_SA_DQ<13>")
	)
	(segment
		(start 84.803996 -234.2769)
		(end 84.812378 -234.281726)
		(width 0.0889)
		(layer "In4.Cu")
		(net "M_D_CPU1_SA_DQ<13>")
	)
	(segment
		(start 49.1363 -214.760302)
		(end 49.40681 -214.760302)
		(width 0.14478)
		(layer "In4.Cu")
		(net "M_D_CPU1_SA_DQ<13>")
	)
	(segment
		(start 43.147488 -214.133176)
		(end 43.310556 -214.296244)
		(width 0.14478)
		(layer "In4.Cu")
		(net "M_D_CPU1_SA_DQ<13>")
	)
	(segment
		(start 58.537348 -214.854282)
		(end 58.537348 -214.53475)
		(width 0.14478)
		(layer "In4.Cu")
		(net "M_D_CPU1_SA_DQ<13>")
	)
	(segment
		(start 76.62037 -232.239566)
		(end 76.957428 -232.239566)
		(width 0.0889)
		(layer "In4.Cu")
		(net "M_D_CPU1_SA_DQ<13>")
	)
	(segment
		(start 84.229702 -234.281726)
		(end 84.238084 -234.2769)
		(width 0.0889)
		(layer "In4.Cu")
		(net "M_D_CPU1_SA_DQ<13>")
	)
	(segment
		(start 54.084474 -214.760302)
		(end 54.518814 -214.760302)
		(width 0.14478)
		(layer "In4.Cu")
		(net "M_D_CPU1_SA_DQ<13>")
	)
	(segment
		(start 38.441376 -214.539068)
		(end 38.604444 -214.376)
		(width 0.14478)
		(layer "In4.Cu")
		(net "M_D_CPU1_SA_DQ<13>")
	)
	(segment
		(start 38.99789 -214.981536)
		(end 39.160958 -215.144604)
		(width 0.14478)
		(layer "In4.Cu")
		(net "M_D_CPU1_SA_DQ<13>")
	)
	(segment
		(start 92.260674 -234.24515)
		(end 92.35694 -234.21975)
		(width 0.0889)
		(layer "In4.Cu")
		(net "M_D_CPU1_SA_DQ<13>")
	)
	(segment
		(start 55.238396 -214.986616)
		(end 55.238396 -214.92337)
		(width 0.14478)
		(layer "In4.Cu")
		(net "M_D_CPU1_SA_DQ<13>")
	)
	(segment
		(start 38.441376 -214.981536)
		(end 38.441376 -214.539068)
		(width 0.14478)
		(layer "In4.Cu")
		(net "M_D_CPU1_SA_DQ<13>")
	)
	(segment
		(start 54.84495 -215.149684)
		(end 55.075328 -215.149684)
		(width 0.14478)
		(layer "In4.Cu")
		(net "M_D_CPU1_SA_DQ<13>")
	)
	(segment
		(start 78.73492 -233.306366)
		(end 79.629254 -234.2007)
		(width 0.0889)
		(layer "In4.Cu")
		(net "M_D_CPU1_SA_DQ<13>")
	)
	(segment
		(start 37.220906 -214.760302)
		(end 37.721794 -214.760302)
		(width 0.14478)
		(layer "In4.Cu")
		(net "M_D_CPU1_SA_DQ<13>")
	)
	(segment
		(start 50.55362 -213.910418)
		(end 50.716688 -214.073486)
		(width 0.14478)
		(layer "In4.Cu")
		(net "M_D_CPU1_SA_DQ<13>")
	)
	(segment
		(start 59.088782 -214.598758)
		(end 59.250326 -214.760302)
		(width 0.14478)
		(layer "In4.Cu")
		(net "M_D_CPU1_SA_DQ<13>")
	)
	(segment
		(start 46.408594 -214.760302)
		(end 48.25365 -214.760302)
		(width 0.14478)
		(layer "In4.Cu")
		(net "M_D_CPU1_SA_DQ<13>")
	)
	(segment
		(start 41.333674 -214.986616)
		(end 41.333674 -214.92337)
		(width 0.14478)
		(layer "In4.Cu")
		(net "M_D_CPU1_SA_DQ<13>")
	)
	(segment
		(start 50.879756 -214.303864)
		(end 51.110134 -214.303864)
		(width 0.14478)
		(layer "In4.Cu")
		(net "M_D_CPU1_SA_DQ<13>")
	)
	(segment
		(start 51.273202 -214.140796)
		(end 51.273202 -214.073486)
		(width 0.14478)
		(layer "In4.Cu")
		(net "M_D_CPU1_SA_DQ<13>")
	)
	(segment
		(start 57.985914 -214.854282)
		(end 58.147458 -215.015826)
		(width 0.14478)
		(layer "In4.Cu")
		(net "M_D_CPU1_SA_DQ<13>")
	)
	(segment
		(start 41.496742 -214.760302)
		(end 41.88333 -214.760302)
		(width 0.14478)
		(layer "In4.Cu")
		(net "M_D_CPU1_SA_DQ<13>")
	)
	(segment
		(start 43.704002 -214.073486)
		(end 43.86707 -213.910418)
		(width 0.14478)
		(layer "In4.Cu")
		(net "M_D_CPU1_SA_DQ<13>")
	)
	(segment
		(start 39.717472 -214.760302)
		(end 40.614092 -214.760302)
		(width 0.14478)
		(layer "In4.Cu")
		(net "M_D_CPU1_SA_DQ<13>")
	)
	(segment
		(start 58.927238 -214.373206)
		(end 59.088782 -214.53475)
		(width 0.14478)
		(layer "In4.Cu")
		(net "M_D_CPU1_SA_DQ<13>")
	)
	(segment
		(start 37.721794 -214.760302)
		(end 37.884862 -214.92337)
		(width 0.14478)
		(layer "In4.Cu")
		(net "M_D_CPU1_SA_DQ<13>")
	)
	(segment
		(start 50.716688 -214.073486)
		(end 50.716688 -214.140796)
		(width 0.14478)
		(layer "In4.Cu")
		(net "M_D_CPU1_SA_DQ<13>")
	)
	(segment
		(start 56.883046 -214.773002)
		(end 57.04459 -214.934546)
		(width 0.14478)
		(layer "In4.Cu")
		(net "M_D_CPU1_SA_DQ<13>")
	)
	(segment
		(start 41.88333 -214.760302)
		(end 42.733214 -213.910418)
		(width 0.14478)
		(layer "In4.Cu")
		(net "M_D_CPU1_SA_DQ<13>")
	)
	(segment
		(start 87.989664 -234.281726)
		(end 87.998046 -234.2769)
		(width 0.0889)
		(layer "In4.Cu")
		(net "M_D_CPU1_SA_DQ<13>")
	)
	(segment
		(start 37.884862 -214.92337)
		(end 37.884862 -214.981536)
		(width 0.14478)
		(layer "In4.Cu")
		(net "M_D_CPU1_SA_DQ<13>")
	)
	(segment
		(start 58.147458 -215.015826)
		(end 58.375804 -215.015826)
		(width 0.14478)
		(layer "In4.Cu")
		(net "M_D_CPU1_SA_DQ<13>")
	)
	(segment
		(start 59.088782 -214.53475)
		(end 59.088782 -214.598758)
		(width 0.14478)
		(layer "In4.Cu")
		(net "M_D_CPU1_SA_DQ<13>")
	)
	(segment
		(start 43.310556 -214.296244)
		(end 43.540934 -214.296244)
		(width 0.14478)
		(layer "In4.Cu")
		(net "M_D_CPU1_SA_DQ<13>")
	)
	(segment
		(start 48.25365 -214.760302)
		(end 48.416718 -214.92337)
		(width 0.14478)
		(layer "In4.Cu")
		(net "M_D_CPU1_SA_DQ<13>")
	)
	(segment
		(start 57.04459 -214.934546)
		(end 57.272936 -214.934546)
		(width 0.14478)
		(layer "In4.Cu")
		(net "M_D_CPU1_SA_DQ<13>")
	)
	(segment
		(start 56.883046 -214.53475)
		(end 56.883046 -214.773002)
		(width 0.14478)
		(layer "In4.Cu")
		(net "M_D_CPU1_SA_DQ<13>")
	)
	(segment
		(start 70.20306 -225.020886)
		(end 70.20306 -226.575874)
		(width 0.14478)
		(layer "In4.Cu")
		(net "M_D_CPU1_SA_DQ<13>")
	)
	(segment
		(start 75.402694 -231.775508)
		(end 75.97013 -231.775508)
		(width 0.14478)
		(layer "In4.Cu")
		(net "M_D_CPU1_SA_DQ<13>")
	)
	(segment
		(start 40.940228 -215.149684)
		(end 41.170606 -215.149684)
		(width 0.14478)
		(layer "In4.Cu")
		(net "M_D_CPU1_SA_DQ<13>")
	)
	(segment
		(start 57.43448 -214.773002)
		(end 57.43448 -214.53475)
		(width 0.14478)
		(layer "In4.Cu")
		(net "M_D_CPU1_SA_DQ<13>")
	)
	(segment
		(start 40.77716 -214.986616)
		(end 40.940228 -215.149684)
		(width 0.14478)
		(layer "In4.Cu")
		(net "M_D_CPU1_SA_DQ<13>")
	)
	(segment
		(start 50.256694 -213.910418)
		(end 50.55362 -213.910418)
		(width 0.14478)
		(layer "In4.Cu")
		(net "M_D_CPU1_SA_DQ<13>")
	)
	(segment
		(start 59.942476 -214.760302)
		(end 70.20306 -225.020886)
		(width 0.14478)
		(layer "In4.Cu")
		(net "M_D_CPU1_SA_DQ<13>")
	)
	(segment
		(start 39.160958 -215.144604)
		(end 39.391336 -215.144604)
		(width 0.14478)
		(layer "In4.Cu")
		(net "M_D_CPU1_SA_DQ<13>")
	)
	(segment
		(start 88.929718 -234.281726)
		(end 88.9381 -234.2769)
		(width 0.0889)
		(layer "In4.Cu")
		(net "M_D_CPU1_SA_DQ<13>")
	)
	(segment
		(start 58.698892 -214.373206)
		(end 58.927238 -214.373206)
		(width 0.14478)
		(layer "In4.Cu")
		(net "M_D_CPU1_SA_DQ<13>")
	)
	(segment
		(start 48.416718 -214.92337)
		(end 48.416718 -214.986616)
		(width 0.14478)
		(layer "In4.Cu")
		(net "M_D_CPU1_SA_DQ<13>")
	)
	(segment
		(start 56.170068 -214.760302)
		(end 56.331612 -214.598758)
		(width 0.14478)
		(layer "In4.Cu")
		(net "M_D_CPU1_SA_DQ<13>")
	)
	(segment
		(start 54.681882 -214.92337)
		(end 54.681882 -214.986616)
		(width 0.14478)
		(layer "In4.Cu")
		(net "M_D_CPU1_SA_DQ<13>")
	)
	(segment
		(start 39.391336 -215.144604)
		(end 39.554404 -214.981536)
		(width 0.14478)
		(layer "In4.Cu")
		(net "M_D_CPU1_SA_DQ<13>")
	)
	(segment
		(start 50.716688 -214.140796)
		(end 50.879756 -214.303864)
		(width 0.14478)
		(layer "In4.Cu")
		(net "M_D_CPU1_SA_DQ<13>")
	)
	(segment
		(start 38.99789 -214.539068)
		(end 38.99789 -214.981536)
		(width 0.14478)
		(layer "In4.Cu")
		(net "M_D_CPU1_SA_DQ<13>")
	)
	(segment
		(start 48.973232 -214.986616)
		(end 48.973232 -214.92337)
		(width 0.14478)
		(layer "In4.Cu")
		(net "M_D_CPU1_SA_DQ<13>")
	)
	(segment
		(start 55.238396 -214.92337)
		(end 55.401464 -214.760302)
		(width 0.14478)
		(layer "In4.Cu")
		(net "M_D_CPU1_SA_DQ<13>")
	)
	(segment
		(start 85.74405 -234.2769)
		(end 85.752432 -234.281726)
		(width 0.0889)
		(layer "In4.Cu")
		(net "M_D_CPU1_SA_DQ<13>")
	)
	(segment
		(start 38.278308 -215.144604)
		(end 38.441376 -214.981536)
		(width 0.14478)
		(layer "In4.Cu")
		(net "M_D_CPU1_SA_DQ<13>")
	)
	(segment
		(start 76.957428 -232.239566)
		(end 78.024228 -233.306366)
		(width 0.0889)
		(layer "In4.Cu")
		(net "M_D_CPU1_SA_DQ<13>")
	)
	(segment
		(start 54.681882 -214.986616)
		(end 54.84495 -215.149684)
		(width 0.14478)
		(layer "In4.Cu")
		(net "M_D_CPU1_SA_DQ<13>")
	)
	(segment
		(start 58.537348 -214.53475)
		(end 58.698892 -214.373206)
		(width 0.14478)
		(layer "In4.Cu")
		(net "M_D_CPU1_SA_DQ<13>")
	)
	(segment
		(start 59.250326 -214.760302)
		(end 59.942476 -214.760302)
		(width 0.14478)
		(layer "In4.Cu")
		(net "M_D_CPU1_SA_DQ<13>")
	)
	(segment
		(start 38.834822 -214.376)
		(end 38.99789 -214.539068)
		(width 0.14478)
		(layer "In4.Cu")
		(net "M_D_CPU1_SA_DQ<13>")
	)
	(segment
		(start 51.110134 -214.303864)
		(end 51.273202 -214.140796)
		(width 0.14478)
		(layer "In4.Cu")
		(net "M_D_CPU1_SA_DQ<13>")
	)
	(segment
		(start 81.044034 -234.2769)
		(end 81.052416 -234.281726)
		(width 0.0889)
		(layer "In4.Cu")
		(net "M_D_CPU1_SA_DQ<13>")
	)
	(segment
		(start 43.704002 -214.133176)
		(end 43.704002 -214.073486)
		(width 0.14478)
		(layer "In4.Cu")
		(net "M_D_CPU1_SA_DQ<13>")
	)
	(segment
		(start 45.55871 -213.910418)
		(end 46.408594 -214.760302)
		(width 0.14478)
		(layer "In4.Cu")
		(net "M_D_CPU1_SA_DQ<13>")
	)
	(segment
		(start 55.075328 -215.149684)
		(end 55.238396 -214.986616)
		(width 0.14478)
		(layer "In4.Cu")
		(net "M_D_CPU1_SA_DQ<13>")
	)
	(segment
		(start 76.156312 -231.775508)
		(end 76.62037 -232.239566)
		(width 0.0889)
		(layer "In4.Cu")
		(net "M_D_CPU1_SA_DQ<13>")
	)
	(arc
		(start 86.684104 -234.2769)
		(mid 86.871048 -234.327155)
		(end 87.057992 -234.2769)
		(width 0.0889)
		(layer "In4.Cu")
		(net "M_D_CPU1_SA_DQ<13>")
	)
	(arc
		(start 80.10398 -234.2769)
		(mid 80.286231 -234.32725)
		(end 80.46974 -234.281726)
		(width 0.0889)
		(layer "In4.Cu")
		(net "M_D_CPU1_SA_DQ<13>")
	)
	(arc
		(start 85.752432 -234.281726)
		(mid 85.93594 -234.32722)
		(end 86.118192 -234.2769)
		(width 0.0889)
		(layer "In4.Cu")
		(net "M_D_CPU1_SA_DQ<13>")
	)
	(arc
		(start 87.057992 -234.2769)
		(mid 87.340948 -234.200723)
		(end 87.623904 -234.2769)
		(width 0.0889)
		(layer "In4.Cu")
		(net "M_D_CPU1_SA_DQ<13>")
	)
	(arc
		(start 79.821278 -234.2007)
		(mid 79.967668 -234.220111)
		(end 80.10398 -234.2769)
		(width 0.0889)
		(layer "In4.Cu")
		(net "M_D_CPU1_SA_DQ<13>")
	)
	(arc
		(start 87.623904 -234.2769)
		(mid 87.806155 -234.32725)
		(end 87.989664 -234.281726)
		(width 0.0889)
		(layer "In4.Cu")
		(net "M_D_CPU1_SA_DQ<13>")
	)
	(arc
		(start 89.512394 -234.281726)
		(mid 89.695902 -234.32722)
		(end 89.878154 -234.2769)
		(width 0.0889)
		(layer "In4.Cu")
		(net "M_D_CPU1_SA_DQ<13>")
	)
	(arc
		(start 81.052416 -234.281726)
		(mid 81.235924 -234.32722)
		(end 81.418176 -234.2769)
		(width 0.0889)
		(layer "In4.Cu")
		(net "M_D_CPU1_SA_DQ<13>")
	)
	(arc
		(start 91.383866 -234.2769)
		(mid 91.566117 -234.32725)
		(end 91.749626 -234.281726)
		(width 0.0889)
		(layer "In4.Cu")
		(net "M_D_CPU1_SA_DQ<13>")
	)
	(arc
		(start 88.563958 -234.2769)
		(mid 88.746209 -234.32725)
		(end 88.929718 -234.281726)
		(width 0.0889)
		(layer "In4.Cu")
		(net "M_D_CPU1_SA_DQ<13>")
	)
	(arc
		(start 81.418176 -234.2769)
		(mid 81.701132 -234.200723)
		(end 81.984088 -234.2769)
		(width 0.0889)
		(layer "In4.Cu")
		(net "M_D_CPU1_SA_DQ<13>")
	)
	(arc
		(start 89.878154 -234.2769)
		(mid 90.16111 -234.200723)
		(end 90.444066 -234.2769)
		(width 0.0889)
		(layer "In4.Cu")
		(net "M_D_CPU1_SA_DQ<13>")
	)
	(arc
		(start 81.984088 -234.2769)
		(mid 82.171032 -234.327155)
		(end 82.357976 -234.2769)
		(width 0.0889)
		(layer "In4.Cu")
		(net "M_D_CPU1_SA_DQ<13>")
	)
	(arc
		(start 86.118192 -234.2769)
		(mid 86.401148 -234.200723)
		(end 86.684104 -234.2769)
		(width 0.0889)
		(layer "In4.Cu")
		(net "M_D_CPU1_SA_DQ<13>")
	)
	(arc
		(start 83.863942 -234.2769)
		(mid 84.046193 -234.32725)
		(end 84.229702 -234.281726)
		(width 0.0889)
		(layer "In4.Cu")
		(net "M_D_CPU1_SA_DQ<13>")
	)
	(arc
		(start 90.444066 -234.2769)
		(mid 90.63101 -234.327155)
		(end 90.817954 -234.2769)
		(width 0.0889)
		(layer "In4.Cu")
		(net "M_D_CPU1_SA_DQ<13>")
	)
	(arc
		(start 80.478122 -234.2769)
		(mid 80.761078 -234.200723)
		(end 81.044034 -234.2769)
		(width 0.0889)
		(layer "In4.Cu")
		(net "M_D_CPU1_SA_DQ<13>")
	)
	(arc
		(start 87.998046 -234.2769)
		(mid 88.281002 -234.200723)
		(end 88.563958 -234.2769)
		(width 0.0889)
		(layer "In4.Cu")
		(net "M_D_CPU1_SA_DQ<13>")
	)
	(arc
		(start 90.817954 -234.2769)
		(mid 91.10091 -234.200723)
		(end 91.383866 -234.2769)
		(width 0.0889)
		(layer "In4.Cu")
		(net "M_D_CPU1_SA_DQ<13>")
	)
	(arc
		(start 82.357976 -234.2769)
		(mid 82.640932 -234.200723)
		(end 82.923888 -234.2769)
		(width 0.0889)
		(layer "In4.Cu")
		(net "M_D_CPU1_SA_DQ<13>")
	)
	(arc
		(start 91.758008 -234.2769)
		(mid 92.005604 -234.201722)
		(end 92.260674 -234.24515)
		(width 0.0889)
		(layer "In4.Cu")
		(net "M_D_CPU1_SA_DQ<13>")
	)
	(arc
		(start 85.178138 -234.2769)
		(mid 85.461094 -234.200723)
		(end 85.74405 -234.2769)
		(width 0.0889)
		(layer "In4.Cu")
		(net "M_D_CPU1_SA_DQ<13>")
	)
	(arc
		(start 84.238084 -234.2769)
		(mid 84.52104 -234.200723)
		(end 84.803996 -234.2769)
		(width 0.0889)
		(layer "In4.Cu")
		(net "M_D_CPU1_SA_DQ<13>")
	)
	(arc
		(start 82.923888 -234.2769)
		(mid 83.106139 -234.32725)
		(end 83.289648 -234.281726)
		(width 0.0889)
		(layer "In4.Cu")
		(net "M_D_CPU1_SA_DQ<13>")
	)
	(arc
		(start 83.29803 -234.2769)
		(mid 83.580986 -234.200723)
		(end 83.863942 -234.2769)
		(width 0.0889)
		(layer "In4.Cu")
		(net "M_D_CPU1_SA_DQ<13>")
	)
	(arc
		(start 88.9381 -234.2769)
		(mid 89.221056 -234.200723)
		(end 89.504012 -234.2769)
		(width 0.0889)
		(layer "In4.Cu")
		(net "M_D_CPU1_SA_DQ<13>")
	)
	(arc
		(start 84.812378 -234.281726)
		(mid 84.995886 -234.32722)
		(end 85.178138 -234.2769)
		(width 0.0889)
		(layer "In4.Cu")
		(net "M_D_CPU1_SA_DQ<13>")
	)
	(segment
		(start 91.568016 -233.410252)
		(end 91.10091 -233.144314)
		(width 0.10668)
		(layer "F.Cu")
		(net "M_D_CPU1_SA_DQ<12>")
	)
	(segment
		(start 57.857898 -213.069932)
		(end 58.019442 -213.231476)
		(width 0.14478)
		(layer "In4.Cu")
		(net "M_D_CPU1_SA_DQ<12>")
	)
	(segment
		(start 81.879694 -233.47172)
		(end 81.888076 -233.466894)
		(width 0.0889)
		(layer "In4.Cu")
		(net "M_D_CPU1_SA_DQ<12>")
	)
	(segment
		(start 58.019442 -213.231476)
		(end 58.019442 -213.294722)
		(width 0.14478)
		(layer "In4.Cu")
		(net "M_D_CPU1_SA_DQ<12>")
	)
	(segment
		(start 39.600886 -213.223348)
		(end 39.754302 -213.069932)
		(width 0.14478)
		(layer "In4.Cu")
		(net "M_D_CPU1_SA_DQ<12>")
	)
	(segment
		(start 59.600338 -213.069932)
		(end 71.23049 -224.700084)
		(width 0.14478)
		(layer "In4.Cu")
		(net "M_D_CPU1_SA_DQ<12>")
	)
	(segment
		(start 38.151562 -212.897212)
		(end 38.324282 -213.069932)
		(width 0.14478)
		(layer "In4.Cu")
		(net "M_D_CPU1_SA_DQ<12>")
	)
	(segment
		(start 42.909236 -212.220048)
		(end 43.07078 -212.381592)
		(width 0.14478)
		(layer "In4.Cu")
		(net "M_D_CPU1_SA_DQ<12>")
	)
	(segment
		(start 50.681382 -212.381592)
		(end 50.681382 -212.448902)
		(width 0.14478)
		(layer "In4.Cu")
		(net "M_D_CPU1_SA_DQ<12>")
	)
	(segment
		(start 57.468008 -213.231476)
		(end 57.629552 -213.069932)
		(width 0.14478)
		(layer "In4.Cu")
		(net "M_D_CPU1_SA_DQ<12>")
	)
	(segment
		(start 71.23049 -225.016822)
		(end 71.392034 -225.178366)
		(width 0.14478)
		(layer "In4.Cu")
		(net "M_D_CPU1_SA_DQ<12>")
	)
	(segment
		(start 55.652162 -212.773006)
		(end 55.813706 -212.93455)
		(width 0.14478)
		(layer "In4.Cu")
		(net "M_D_CPU1_SA_DQ<12>")
	)
	(segment
		(start 55.97525 -213.456266)
		(end 56.203596 -213.456266)
		(width 0.14478)
		(layer "In4.Cu")
		(net "M_D_CPU1_SA_DQ<12>")
	)
	(segment
		(start 58.73242 -213.069932)
		(end 59.600338 -213.069932)
		(width 0.14478)
		(layer "In4.Cu")
		(net "M_D_CPU1_SA_DQ<12>")
	)
	(segment
		(start 85.639656 -233.47172)
		(end 85.648038 -233.466894)
		(width 0.0889)
		(layer "In4.Cu")
		(net "M_D_CPU1_SA_DQ<12>")
	)
	(segment
		(start 55.262272 -212.93455)
		(end 55.423816 -212.773006)
		(width 0.14478)
		(layer "In4.Cu")
		(net "M_D_CPU1_SA_DQ<12>")
	)
	(segment
		(start 39.754302 -213.069932)
		(end 40.6908 -213.069932)
		(width 0.14478)
		(layer "In4.Cu")
		(net "M_D_CPU1_SA_DQ<12>")
	)
	(segment
		(start 58.570876 -213.294722)
		(end 58.570876 -213.231476)
		(width 0.14478)
		(layer "In4.Cu")
		(net "M_D_CPU1_SA_DQ<12>")
	)
	(segment
		(start 71.87311 -225.33991)
		(end 71.87311 -225.568256)
		(width 0.14478)
		(layer "In4.Cu")
		(net "M_D_CPU1_SA_DQ<12>")
	)
	(segment
		(start 48.750728 -213.448646)
		(end 48.912272 -213.287102)
		(width 0.14478)
		(layer "In4.Cu")
		(net "M_D_CPU1_SA_DQ<12>")
	)
	(segment
		(start 51.232816 -212.381592)
		(end 51.39436 -212.220048)
		(width 0.14478)
		(layer "In4.Cu")
		(net "M_D_CPU1_SA_DQ<12>")
	)
	(segment
		(start 43.232324 -212.602826)
		(end 43.46067 -212.602826)
		(width 0.14478)
		(layer "In4.Cu")
		(net "M_D_CPU1_SA_DQ<12>")
	)
	(segment
		(start 49.397158 -213.069932)
		(end 50.247042 -212.220048)
		(width 0.14478)
		(layer "In4.Cu")
		(net "M_D_CPU1_SA_DQ<12>")
	)
	(segment
		(start 55.262272 -213.294722)
		(end 55.262272 -212.93455)
		(width 0.14478)
		(layer "In4.Cu")
		(net "M_D_CPU1_SA_DQ<12>")
	)
	(segment
		(start 71.392034 -225.178366)
		(end 71.711566 -225.178366)
		(width 0.14478)
		(layer "In4.Cu")
		(net "M_D_CPU1_SA_DQ<12>")
	)
	(segment
		(start 46.418246 -213.069932)
		(end 48.199294 -213.069932)
		(width 0.14478)
		(layer "In4.Cu")
		(net "M_D_CPU1_SA_DQ<12>")
	)
	(segment
		(start 38.151562 -212.434932)
		(end 38.151562 -212.897212)
		(width 0.14478)
		(layer "In4.Cu")
		(net "M_D_CPU1_SA_DQ<12>")
	)
	(segment
		(start 55.423816 -212.773006)
		(end 55.652162 -212.773006)
		(width 0.14478)
		(layer "In4.Cu")
		(net "M_D_CPU1_SA_DQ<12>")
	)
	(segment
		(start 56.75503 -213.069932)
		(end 56.916574 -213.231476)
		(width 0.14478)
		(layer "In4.Cu")
		(net "M_D_CPU1_SA_DQ<12>")
	)
	(segment
		(start 56.526684 -213.069932)
		(end 56.75503 -213.069932)
		(width 0.14478)
		(layer "In4.Cu")
		(net "M_D_CPU1_SA_DQ<12>")
	)
	(segment
		(start 57.468008 -213.294722)
		(end 57.468008 -213.231476)
		(width 0.14478)
		(layer "In4.Cu")
		(net "M_D_CPU1_SA_DQ<12>")
	)
	(segment
		(start 39.437818 -213.450424)
		(end 39.600886 -213.287356)
		(width 0.14478)
		(layer "In4.Cu")
		(net "M_D_CPU1_SA_DQ<12>")
	)
	(segment
		(start 79.55788 -233.407712)
		(end 79.55788 -233.407458)
		(width 0.0889)
		(layer "In4.Cu")
		(net "M_D_CPU1_SA_DQ<12>")
	)
	(segment
		(start 54.710838 -213.294722)
		(end 54.872382 -213.456266)
		(width 0.14478)
		(layer "In4.Cu")
		(net "M_D_CPU1_SA_DQ<12>")
	)
	(segment
		(start 39.044372 -213.223348)
		(end 39.044372 -213.287356)
		(width 0.14478)
		(layer "In4.Cu")
		(net "M_D_CPU1_SA_DQ<12>")
	)
	(segment
		(start 49.073816 -213.069932)
		(end 49.397158 -213.069932)
		(width 0.14478)
		(layer "In4.Cu")
		(net "M_D_CPU1_SA_DQ<12>")
	)
	(segment
		(start 43.622214 -212.441282)
		(end 43.622214 -212.381592)
		(width 0.14478)
		(layer "In4.Cu")
		(net "M_D_CPU1_SA_DQ<12>")
	)
	(segment
		(start 56.916574 -213.231476)
		(end 56.916574 -213.294722)
		(width 0.14478)
		(layer "In4.Cu")
		(net "M_D_CPU1_SA_DQ<12>")
	)
	(segment
		(start 38.324282 -213.069932)
		(end 38.890956 -213.069932)
		(width 0.14478)
		(layer "In4.Cu")
		(net "M_D_CPU1_SA_DQ<12>")
	)
	(segment
		(start 39.600886 -213.287356)
		(end 39.600886 -213.223348)
		(width 0.14478)
		(layer "In4.Cu")
		(net "M_D_CPU1_SA_DQ<12>")
	)
	(segment
		(start 51.39436 -212.220048)
		(end 53.12029 -212.220048)
		(width 0.14478)
		(layer "In4.Cu")
		(net "M_D_CPU1_SA_DQ<12>")
	)
	(segment
		(start 50.247042 -212.220048)
		(end 50.519838 -212.220048)
		(width 0.14478)
		(layer "In4.Cu")
		(net "M_D_CPU1_SA_DQ<12>")
	)
	(segment
		(start 83.394042 -233.466894)
		(end 83.402424 -233.47172)
		(width 0.0889)
		(layer "In4.Cu")
		(net "M_D_CPU1_SA_DQ<12>")
	)
	(segment
		(start 45.568362 -212.220048)
		(end 46.418246 -213.069932)
		(width 0.14478)
		(layer "In4.Cu")
		(net "M_D_CPU1_SA_DQ<12>")
	)
	(segment
		(start 54.549294 -213.069932)
		(end 54.710838 -213.231476)
		(width 0.14478)
		(layer "In4.Cu")
		(net "M_D_CPU1_SA_DQ<12>")
	)
	(segment
		(start 38.890956 -213.069932)
		(end 39.044372 -213.223348)
		(width 0.14478)
		(layer "In4.Cu")
		(net "M_D_CPU1_SA_DQ<12>")
	)
	(segment
		(start 71.23049 -224.700084)
		(end 71.23049 -225.016822)
		(width 0.14478)
		(layer "In4.Cu")
		(net "M_D_CPU1_SA_DQ<12>")
	)
	(segment
		(start 51.071272 -212.610446)
		(end 51.232816 -212.448902)
		(width 0.14478)
		(layer "In4.Cu")
		(net "M_D_CPU1_SA_DQ<12>")
	)
	(segment
		(start 86.57971 -233.47172)
		(end 86.588092 -233.466894)
		(width 0.0889)
		(layer "In4.Cu")
		(net "M_D_CPU1_SA_DQ<12>")
	)
	(segment
		(start 37.220906 -213.06028)
		(end 37.43198 -213.06028)
		(width 0.14478)
		(layer "In4.Cu")
		(net "M_D_CPU1_SA_DQ<12>")
	)
	(segment
		(start 36.795964 -212.635338)
		(end 37.220906 -213.06028)
		(width 0.14478)
		(layer "In4.Cu")
		(net "M_D_CPU1_SA_DQ<12>")
	)
	(segment
		(start 56.916574 -213.294722)
		(end 57.078118 -213.456266)
		(width 0.14478)
		(layer "In4.Cu")
		(net "M_D_CPU1_SA_DQ<12>")
	)
	(segment
		(start 37.595048 -212.897212)
		(end 37.595048 -212.434932)
		(width 0.14478)
		(layer "In4.Cu")
		(net "M_D_CPU1_SA_DQ<12>")
	)
	(segment
		(start 43.622214 -212.381592)
		(end 43.783758 -212.220048)
		(width 0.14478)
		(layer "In4.Cu")
		(net "M_D_CPU1_SA_DQ<12>")
	)
	(segment
		(start 88.094058 -233.466894)
		(end 88.10244 -233.47172)
		(width 0.0889)
		(layer "In4.Cu")
		(net "M_D_CPU1_SA_DQ<12>")
	)
	(segment
		(start 55.100728 -213.456266)
		(end 55.262272 -213.294722)
		(width 0.14478)
		(layer "In4.Cu")
		(net "M_D_CPU1_SA_DQ<12>")
	)
	(segment
		(start 43.783758 -212.220048)
		(end 45.568362 -212.220048)
		(width 0.14478)
		(layer "In4.Cu")
		(net "M_D_CPU1_SA_DQ<12>")
	)
	(segment
		(start 48.360838 -213.287102)
		(end 48.522382 -213.448646)
		(width 0.14478)
		(layer "In4.Cu")
		(net "M_D_CPU1_SA_DQ<12>")
	)
	(segment
		(start 58.180986 -213.456266)
		(end 58.409332 -213.456266)
		(width 0.14478)
		(layer "In4.Cu")
		(net "M_D_CPU1_SA_DQ<12>")
	)
	(segment
		(start 58.409332 -213.456266)
		(end 58.570876 -213.294722)
		(width 0.14478)
		(layer "In4.Cu")
		(net "M_D_CPU1_SA_DQ<12>")
	)
	(segment
		(start 39.044372 -213.287356)
		(end 39.20744 -213.450424)
		(width 0.14478)
		(layer "In4.Cu")
		(net "M_D_CPU1_SA_DQ<12>")
	)
	(segment
		(start 50.681382 -212.448902)
		(end 50.842926 -212.610446)
		(width 0.14478)
		(layer "In4.Cu")
		(net "M_D_CPU1_SA_DQ<12>")
	)
	(segment
		(start 41.237662 -213.452964)
		(end 41.40073 -213.289896)
		(width 0.14478)
		(layer "In4.Cu")
		(net "M_D_CPU1_SA_DQ<12>")
	)
	(segment
		(start 71.711566 -225.178366)
		(end 71.87311 -225.33991)
		(width 0.14478)
		(layer "In4.Cu")
		(net "M_D_CPU1_SA_DQ<12>")
	)
	(segment
		(start 40.844216 -213.223348)
		(end 40.844216 -213.289896)
		(width 0.14478)
		(layer "In4.Cu")
		(net "M_D_CPU1_SA_DQ<12>")
	)
	(segment
		(start 48.199294 -213.069932)
		(end 48.360838 -213.231476)
		(width 0.14478)
		(layer "In4.Cu")
		(net "M_D_CPU1_SA_DQ<12>")
	)
	(segment
		(start 48.360838 -213.231476)
		(end 48.360838 -213.287102)
		(width 0.14478)
		(layer "In4.Cu")
		(net "M_D_CPU1_SA_DQ<12>")
	)
	(segment
		(start 51.232816 -212.448902)
		(end 51.232816 -212.381592)
		(width 0.14478)
		(layer "In4.Cu")
		(net "M_D_CPU1_SA_DQ<12>")
	)
	(segment
		(start 48.522382 -213.448646)
		(end 48.750728 -213.448646)
		(width 0.14478)
		(layer "In4.Cu")
		(net "M_D_CPU1_SA_DQ<12>")
	)
	(segment
		(start 41.88333 -213.06028)
		(end 42.723562 -212.220048)
		(width 0.14478)
		(layer "In4.Cu")
		(net "M_D_CPU1_SA_DQ<12>")
	)
	(segment
		(start 71.23049 -225.891344)
		(end 71.23049 -226.291648)
		(width 0.14478)
		(layer "In4.Cu")
		(net "M_D_CPU1_SA_DQ<12>")
	)
	(segment
		(start 77.52969 -231.561386)
		(end 77.52969 -232.000552)
		(width 0.0889)
		(layer "In4.Cu")
		(net "M_D_CPU1_SA_DQ<12>")
	)
	(segment
		(start 76.232512 -230.871268)
		(end 76.43241 -231.071166)
		(width 0.0889)
		(layer "In4.Cu")
		(net "M_D_CPU1_SA_DQ<12>")
	)
	(segment
		(start 43.46067 -212.602826)
		(end 43.622214 -212.441282)
		(width 0.14478)
		(layer "In4.Cu")
		(net "M_D_CPU1_SA_DQ<12>")
	)
	(segment
		(start 57.629552 -213.069932)
		(end 57.857898 -213.069932)
		(width 0.14478)
		(layer "In4.Cu")
		(net "M_D_CPU1_SA_DQ<12>")
	)
	(segment
		(start 76.43241 -231.071166)
		(end 77.03947 -231.071166)
		(width 0.0889)
		(layer "In4.Cu")
		(net "M_D_CPU1_SA_DQ<12>")
	)
	(segment
		(start 75.91933 -230.871268)
		(end 76.232512 -230.871268)
		(width 0.0889)
		(layer "In4.Cu")
		(net "M_D_CPU1_SA_DQ<12>")
	)
	(segment
		(start 78.882494 -232.732326)
		(end 79.55788 -233.407712)
		(width 0.0889)
		(layer "In4.Cu")
		(net "M_D_CPU1_SA_DQ<12>")
	)
	(segment
		(start 90.850974 -233.435144)
		(end 90.946986 -233.409744)
		(width 0.0889)
		(layer "In4.Cu")
		(net "M_D_CPU1_SA_DQ<12>")
	)
	(segment
		(start 50.519838 -212.220048)
		(end 50.681382 -212.381592)
		(width 0.14478)
		(layer "In4.Cu")
		(net "M_D_CPU1_SA_DQ<12>")
	)
	(segment
		(start 37.43198 -213.06028)
		(end 37.595048 -212.897212)
		(width 0.14478)
		(layer "In4.Cu")
		(net "M_D_CPU1_SA_DQ<12>")
	)
	(segment
		(start 48.912272 -213.287102)
		(end 48.912272 -213.231476)
		(width 0.14478)
		(layer "In4.Cu")
		(net "M_D_CPU1_SA_DQ<12>")
	)
	(segment
		(start 56.36514 -213.294722)
		(end 56.36514 -213.231476)
		(width 0.14478)
		(layer "In4.Cu")
		(net "M_D_CPU1_SA_DQ<12>")
	)
	(segment
		(start 56.36514 -213.231476)
		(end 56.526684 -213.069932)
		(width 0.14478)
		(layer "In4.Cu")
		(net "M_D_CPU1_SA_DQ<12>")
	)
	(segment
		(start 37.988494 -212.271864)
		(end 38.151562 -212.434932)
		(width 0.14478)
		(layer "In4.Cu")
		(net "M_D_CPU1_SA_DQ<12>")
	)
	(segment
		(start 43.07078 -212.381592)
		(end 43.07078 -212.441282)
		(width 0.14478)
		(layer "In4.Cu")
		(net "M_D_CPU1_SA_DQ<12>")
	)
	(segment
		(start 57.306464 -213.456266)
		(end 57.468008 -213.294722)
		(width 0.14478)
		(layer "In4.Cu")
		(net "M_D_CPU1_SA_DQ<12>")
	)
	(segment
		(start 90.339672 -233.47172)
		(end 90.348054 -233.466894)
		(width 0.0889)
		(layer "In4.Cu")
		(net "M_D_CPU1_SA_DQ<12>")
	)
	(segment
		(start 54.710838 -213.231476)
		(end 54.710838 -213.294722)
		(width 0.14478)
		(layer "In4.Cu")
		(net "M_D_CPU1_SA_DQ<12>")
	)
	(segment
		(start 58.019442 -213.294722)
		(end 58.180986 -213.456266)
		(width 0.14478)
		(layer "In4.Cu")
		(net "M_D_CPU1_SA_DQ<12>")
	)
	(segment
		(start 41.563798 -213.06028)
		(end 41.88333 -213.06028)
		(width 0.14478)
		(layer "In4.Cu")
		(net "M_D_CPU1_SA_DQ<12>")
	)
	(segment
		(start 42.723562 -212.220048)
		(end 42.909236 -212.220048)
		(width 0.14478)
		(layer "In4.Cu")
		(net "M_D_CPU1_SA_DQ<12>")
	)
	(segment
		(start 77.03947 -231.071166)
		(end 77.52969 -231.561386)
		(width 0.0889)
		(layer "In4.Cu")
		(net "M_D_CPU1_SA_DQ<12>")
	)
	(segment
		(start 54.872382 -213.456266)
		(end 55.100728 -213.456266)
		(width 0.14478)
		(layer "In4.Cu")
		(net "M_D_CPU1_SA_DQ<12>")
	)
	(segment
		(start 75.81011 -230.871268)
		(end 75.91933 -230.871268)
		(width 0.14478)
		(layer "In4.Cu")
		(net "M_D_CPU1_SA_DQ<12>")
	)
	(segment
		(start 90.946986 -233.409744)
		(end 91.10091 -233.144314)
		(width 0.0889)
		(layer "In4.Cu")
		(net "M_D_CPU1_SA_DQ<12>")
	)
	(segment
		(start 37.595048 -212.434932)
		(end 37.758116 -212.271864)
		(width 0.14478)
		(layer "In4.Cu")
		(net "M_D_CPU1_SA_DQ<12>")
	)
	(segment
		(start 87.154004 -233.466894)
		(end 87.162386 -233.47172)
		(width 0.0889)
		(layer "In4.Cu")
		(net "M_D_CPU1_SA_DQ<12>")
	)
	(segment
		(start 53.12029 -212.220048)
		(end 53.970174 -213.069932)
		(width 0.14478)
		(layer "In4.Cu")
		(net "M_D_CPU1_SA_DQ<12>")
	)
	(segment
		(start 79.634842 -233.46664)
		(end 79.654908 -233.47807)
		(width 0.0889)
		(layer "In4.Cu")
		(net "M_D_CPU1_SA_DQ<12>")
	)
	(segment
		(start 56.203596 -213.456266)
		(end 56.36514 -213.294722)
		(width 0.14478)
		(layer "In4.Cu")
		(net "M_D_CPU1_SA_DQ<12>")
	)
	(segment
		(start 57.078118 -213.456266)
		(end 57.306464 -213.456266)
		(width 0.14478)
		(layer "In4.Cu")
		(net "M_D_CPU1_SA_DQ<12>")
	)
	(segment
		(start 71.711566 -225.7298)
		(end 71.392034 -225.7298)
		(width 0.14478)
		(layer "In4.Cu")
		(net "M_D_CPU1_SA_DQ<12>")
	)
	(segment
		(start 41.007284 -213.452964)
		(end 41.237662 -213.452964)
		(width 0.14478)
		(layer "In4.Cu")
		(net "M_D_CPU1_SA_DQ<12>")
	)
	(segment
		(start 58.570876 -213.231476)
		(end 58.73242 -213.069932)
		(width 0.14478)
		(layer "In4.Cu")
		(net "M_D_CPU1_SA_DQ<12>")
	)
	(segment
		(start 37.758116 -212.271864)
		(end 37.988494 -212.271864)
		(width 0.14478)
		(layer "In4.Cu")
		(net "M_D_CPU1_SA_DQ<12>")
	)
	(segment
		(start 55.813706 -213.294722)
		(end 55.97525 -213.456266)
		(width 0.14478)
		(layer "In4.Cu")
		(net "M_D_CPU1_SA_DQ<12>")
	)
	(segment
		(start 82.453988 -233.466894)
		(end 82.46237 -233.47172)
		(width 0.0889)
		(layer "In4.Cu")
		(net "M_D_CPU1_SA_DQ<12>")
	)
	(segment
		(start 41.40073 -213.223348)
		(end 41.563798 -213.06028)
		(width 0.14478)
		(layer "In4.Cu")
		(net "M_D_CPU1_SA_DQ<12>")
	)
	(segment
		(start 48.912272 -213.231476)
		(end 49.073816 -213.069932)
		(width 0.14478)
		(layer "In4.Cu")
		(net "M_D_CPU1_SA_DQ<12>")
	)
	(segment
		(start 40.844216 -213.289896)
		(end 41.007284 -213.452964)
		(width 0.14478)
		(layer "In4.Cu")
		(net "M_D_CPU1_SA_DQ<12>")
	)
	(segment
		(start 39.20744 -213.450424)
		(end 39.437818 -213.450424)
		(width 0.14478)
		(layer "In4.Cu")
		(net "M_D_CPU1_SA_DQ<12>")
	)
	(segment
		(start 50.842926 -212.610446)
		(end 51.071272 -212.610446)
		(width 0.14478)
		(layer "In4.Cu")
		(net "M_D_CPU1_SA_DQ<12>")
	)
	(segment
		(start 53.970174 -213.069932)
		(end 54.549294 -213.069932)
		(width 0.14478)
		(layer "In4.Cu")
		(net "M_D_CPU1_SA_DQ<12>")
	)
	(segment
		(start 71.23049 -226.291648)
		(end 75.81011 -230.871268)
		(width 0.14478)
		(layer "In4.Cu")
		(net "M_D_CPU1_SA_DQ<12>")
	)
	(segment
		(start 71.87311 -225.568256)
		(end 71.711566 -225.7298)
		(width 0.14478)
		(layer "In4.Cu")
		(net "M_D_CPU1_SA_DQ<12>")
	)
	(segment
		(start 77.52969 -232.000552)
		(end 78.261464 -232.732326)
		(width 0.0889)
		(layer "In4.Cu")
		(net "M_D_CPU1_SA_DQ<12>")
	)
	(segment
		(start 40.6908 -213.069932)
		(end 40.844216 -213.223348)
		(width 0.14478)
		(layer "In4.Cu")
		(net "M_D_CPU1_SA_DQ<12>")
	)
	(segment
		(start 43.07078 -212.441282)
		(end 43.232324 -212.602826)
		(width 0.14478)
		(layer "In4.Cu")
		(net "M_D_CPU1_SA_DQ<12>")
	)
	(segment
		(start 71.392034 -225.7298)
		(end 71.23049 -225.891344)
		(width 0.14478)
		(layer "In4.Cu")
		(net "M_D_CPU1_SA_DQ<12>")
	)
	(segment
		(start 41.40073 -213.289896)
		(end 41.40073 -213.223348)
		(width 0.14478)
		(layer "In4.Cu")
		(net "M_D_CPU1_SA_DQ<12>")
	)
	(segment
		(start 78.261464 -232.732326)
		(end 78.882494 -232.732326)
		(width 0.0889)
		(layer "In4.Cu")
		(net "M_D_CPU1_SA_DQ<12>")
	)
	(segment
		(start 55.813706 -212.93455)
		(end 55.813706 -213.294722)
		(width 0.14478)
		(layer "In4.Cu")
		(net "M_D_CPU1_SA_DQ<12>")
	)
	(arc
		(start 87.528146 -233.466894)
		(mid 87.811102 -233.390717)
		(end 88.094058 -233.466894)
		(width 0.0889)
		(layer "In4.Cu")
		(net "M_D_CPU1_SA_DQ<12>")
	)
	(arc
		(start 86.588092 -233.466894)
		(mid 86.871048 -233.390717)
		(end 87.154004 -233.466894)
		(width 0.0889)
		(layer "In4.Cu")
		(net "M_D_CPU1_SA_DQ<12>")
	)
	(arc
		(start 84.707984 -233.466894)
		(mid 84.99094 -233.390717)
		(end 85.273896 -233.466894)
		(width 0.0889)
		(layer "In4.Cu")
		(net "M_D_CPU1_SA_DQ<12>")
	)
	(arc
		(start 89.034112 -233.466894)
		(mid 89.221056 -233.517149)
		(end 89.408 -233.466894)
		(width 0.0889)
		(layer "In4.Cu")
		(net "M_D_CPU1_SA_DQ<12>")
	)
	(arc
		(start 80.008222 -233.466894)
		(mid 80.291178 -233.390717)
		(end 80.574134 -233.466894)
		(width 0.0889)
		(layer "In4.Cu")
		(net "M_D_CPU1_SA_DQ<12>")
	)
	(arc
		(start 88.4682 -233.466894)
		(mid 88.751156 -233.390717)
		(end 89.034112 -233.466894)
		(width 0.0889)
		(layer "In4.Cu")
		(net "M_D_CPU1_SA_DQ<12>")
	)
	(arc
		(start 80.948022 -233.466894)
		(mid 81.230978 -233.390717)
		(end 81.513934 -233.466894)
		(width 0.0889)
		(layer "In4.Cu")
		(net "M_D_CPU1_SA_DQ<12>")
	)
	(arc
		(start 82.82813 -233.466894)
		(mid 83.111086 -233.390717)
		(end 83.394042 -233.466894)
		(width 0.0889)
		(layer "In4.Cu")
		(net "M_D_CPU1_SA_DQ<12>")
	)
	(arc
		(start 83.402424 -233.47172)
		(mid 83.585932 -233.517214)
		(end 83.768184 -233.466894)
		(width 0.0889)
		(layer "In4.Cu")
		(net "M_D_CPU1_SA_DQ<12>")
	)
	(arc
		(start 89.408 -233.466894)
		(mid 89.690956 -233.390717)
		(end 89.973912 -233.466894)
		(width 0.0889)
		(layer "In4.Cu")
		(net "M_D_CPU1_SA_DQ<12>")
	)
	(arc
		(start 83.768184 -233.466894)
		(mid 84.05114 -233.390717)
		(end 84.334096 -233.466894)
		(width 0.0889)
		(layer "In4.Cu")
		(net "M_D_CPU1_SA_DQ<12>")
	)
	(arc
		(start 81.888076 -233.466894)
		(mid 82.171032 -233.390717)
		(end 82.453988 -233.466894)
		(width 0.0889)
		(layer "In4.Cu")
		(net "M_D_CPU1_SA_DQ<12>")
	)
	(arc
		(start 79.55788 -233.407458)
		(mid 79.594422 -233.43957)
		(end 79.634842 -233.46664)
		(width 0.0889)
		(layer "In4.Cu")
		(net "M_D_CPU1_SA_DQ<12>")
	)
	(arc
		(start 86.21395 -233.466894)
		(mid 86.396201 -233.517244)
		(end 86.57971 -233.47172)
		(width 0.0889)
		(layer "In4.Cu")
		(net "M_D_CPU1_SA_DQ<12>")
	)
	(arc
		(start 87.162386 -233.47172)
		(mid 87.345894 -233.517214)
		(end 87.528146 -233.466894)
		(width 0.0889)
		(layer "In4.Cu")
		(net "M_D_CPU1_SA_DQ<12>")
	)
	(arc
		(start 84.334096 -233.466894)
		(mid 84.52104 -233.517149)
		(end 84.707984 -233.466894)
		(width 0.0889)
		(layer "In4.Cu")
		(net "M_D_CPU1_SA_DQ<12>")
	)
	(arc
		(start 82.46237 -233.47172)
		(mid 82.645878 -233.517214)
		(end 82.82813 -233.466894)
		(width 0.0889)
		(layer "In4.Cu")
		(net "M_D_CPU1_SA_DQ<12>")
	)
	(arc
		(start 80.574134 -233.466894)
		(mid 80.761078 -233.517149)
		(end 80.948022 -233.466894)
		(width 0.0889)
		(layer "In4.Cu")
		(net "M_D_CPU1_SA_DQ<12>")
	)
	(arc
		(start 79.654908 -233.47807)
		(mid 79.832986 -233.517054)
		(end 80.008222 -233.466894)
		(width 0.0889)
		(layer "In4.Cu")
		(net "M_D_CPU1_SA_DQ<12>")
	)
	(arc
		(start 85.648038 -233.466894)
		(mid 85.930994 -233.390717)
		(end 86.21395 -233.466894)
		(width 0.0889)
		(layer "In4.Cu")
		(net "M_D_CPU1_SA_DQ<12>")
	)
	(arc
		(start 85.273896 -233.466894)
		(mid 85.456147 -233.517244)
		(end 85.639656 -233.47172)
		(width 0.0889)
		(layer "In4.Cu")
		(net "M_D_CPU1_SA_DQ<12>")
	)
	(arc
		(start 81.513934 -233.466894)
		(mid 81.696185 -233.517244)
		(end 81.879694 -233.47172)
		(width 0.0889)
		(layer "In4.Cu")
		(net "M_D_CPU1_SA_DQ<12>")
	)
	(arc
		(start 90.348054 -233.466894)
		(mid 90.595767 -233.391674)
		(end 90.850974 -233.435144)
		(width 0.0889)
		(layer "In4.Cu")
		(net "M_D_CPU1_SA_DQ<12>")
	)
	(arc
		(start 88.10244 -233.47172)
		(mid 88.285948 -233.517214)
		(end 88.4682 -233.466894)
		(width 0.0889)
		(layer "In4.Cu")
		(net "M_D_CPU1_SA_DQ<12>")
	)
	(arc
		(start 89.973912 -233.466894)
		(mid 90.156163 -233.517244)
		(end 90.339672 -233.47172)
		(width 0.0889)
		(layer "In4.Cu")
		(net "M_D_CPU1_SA_DQ<12>")
	)
	(segment
		(start 92.507816 -231.79024)
		(end 92.040964 -231.524302)
		(width 0.10668)
		(layer "F.Cu")
		(net "M_D_CPU1_SA_DQ<11>")
	)
	(segment
		(start 49.382172 -209.650584)
		(end 50.232056 -208.8007)
		(width 0.14478)
		(layer "In4.Cu")
		(net "M_D_CPU1_SA_DQ<11>")
	)
	(segment
		(start 60.328048 -210.501738)
		(end 63.27775 -212.472778)
		(width 0.14478)
		(layer "In4.Cu")
		(net "M_D_CPU1_SA_DQ<11>")
	)
	(segment
		(start 76.200508 -227.822506)
		(end 77.11821 -227.822506)
		(width 0.0889)
		(layer "In4.Cu")
		(net "M_D_CPU1_SA_DQ<11>")
	)
	(segment
		(start 33.111186 -209.650584)
		(end 41.893998 -209.650584)
		(width 0.14478)
		(layer "In4.Cu")
		(net "M_D_CPU1_SA_DQ<11>")
	)
	(segment
		(start 77.76083 -228.465126)
		(end 77.76083 -229.163626)
		(width 0.0889)
		(layer "In4.Cu")
		(net "M_D_CPU1_SA_DQ<11>")
	)
	(segment
		(start 76.052426 -227.674424)
		(end 76.200508 -227.822506)
		(width 0.0889)
		(layer "In4.Cu")
		(net "M_D_CPU1_SA_DQ<11>")
	)
	(segment
		(start 78.74635 -229.793546)
		(end 79.205582 -230.252778)
		(width 0.0889)
		(layer "In4.Cu")
		(net "M_D_CPU1_SA_DQ<11>")
	)
	(segment
		(start 41.893998 -209.650584)
		(end 42.743882 -208.8007)
		(width 0.14478)
		(layer "In4.Cu")
		(net "M_D_CPU1_SA_DQ<11>")
	)
	(segment
		(start 81.879694 -231.19715)
		(end 81.888076 -231.201976)
		(width 0.0889)
		(layer "In4.Cu")
		(net "M_D_CPU1_SA_DQ<11>")
	)
	(segment
		(start 92.195142 -231.258872)
		(end 92.040964 -231.524302)
		(width 0.0889)
		(layer "In4.Cu")
		(net "M_D_CPU1_SA_DQ<11>")
	)
	(segment
		(start 59.698128 -210.24088)
		(end 60.328048 -210.501738)
		(width 0.14478)
		(layer "In4.Cu")
		(net "M_D_CPU1_SA_DQ<11>")
	)
	(segment
		(start 74.36739 -224.396046)
		(end 74.36739 -225.989388)
		(width 0.14478)
		(layer "In4.Cu")
		(net "M_D_CPU1_SA_DQ<11>")
	)
	(segment
		(start 74.36739 -225.989388)
		(end 76.052426 -227.674424)
		(width 0.14478)
		(layer "In4.Cu")
		(net "M_D_CPU1_SA_DQ<11>")
	)
	(segment
		(start 77.11821 -227.822506)
		(end 77.76083 -228.465126)
		(width 0.0889)
		(layer "In4.Cu")
		(net "M_D_CPU1_SA_DQ<11>")
	)
	(segment
		(start 50.232056 -208.8007)
		(end 53.246782 -208.8007)
		(width 0.14478)
		(layer "In4.Cu")
		(net "M_D_CPU1_SA_DQ<11>")
	)
	(segment
		(start 82.453988 -231.201976)
		(end 82.46237 -231.19715)
		(width 0.0889)
		(layer "In4.Cu")
		(net "M_D_CPU1_SA_DQ<11>")
	)
	(segment
		(start 72.51319 -222.541846)
		(end 74.36739 -224.396046)
		(width 0.14478)
		(layer "In4.Cu")
		(net "M_D_CPU1_SA_DQ<11>")
	)
	(segment
		(start 85.639656 -231.19715)
		(end 85.648038 -231.201976)
		(width 0.0889)
		(layer "In4.Cu")
		(net "M_D_CPU1_SA_DQ<11>")
	)
	(segment
		(start 53.246782 -208.8007)
		(end 54.106572 -209.66049)
		(width 0.14478)
		(layer "In4.Cu")
		(net "M_D_CPU1_SA_DQ<11>")
	)
	(segment
		(start 72.51319 -221.708218)
		(end 72.51319 -222.541846)
		(width 0.14478)
		(layer "In4.Cu")
		(net "M_D_CPU1_SA_DQ<11>")
	)
	(segment
		(start 56.779922 -209.66049)
		(end 59.698128 -210.24088)
		(width 0.14478)
		(layer "In4.Cu")
		(net "M_D_CPU1_SA_DQ<11>")
	)
	(segment
		(start 79.969106 -231.179116)
		(end 80.008222 -231.201976)
		(width 0.0889)
		(layer "In4.Cu")
		(net "M_D_CPU1_SA_DQ<11>")
	)
	(segment
		(start 42.743882 -208.8007)
		(end 45.557948 -208.8007)
		(width 0.14478)
		(layer "In4.Cu")
		(net "M_D_CPU1_SA_DQ<11>")
	)
	(segment
		(start 86.57971 -231.19715)
		(end 86.588092 -231.201976)
		(width 0.0889)
		(layer "In4.Cu")
		(net "M_D_CPU1_SA_DQ<11>")
	)
	(segment
		(start 88.094058 -231.201976)
		(end 88.10244 -231.19715)
		(width 0.0889)
		(layer "In4.Cu")
		(net "M_D_CPU1_SA_DQ<11>")
	)
	(segment
		(start 87.154004 -231.201976)
		(end 87.162386 -231.19715)
		(width 0.0889)
		(layer "In4.Cu")
		(net "M_D_CPU1_SA_DQ<11>")
	)
	(segment
		(start 63.27775 -212.472778)
		(end 72.51319 -221.708218)
		(width 0.14478)
		(layer "In4.Cu")
		(net "M_D_CPU1_SA_DQ<11>")
	)
	(segment
		(start 54.106572 -209.66049)
		(end 56.779922 -209.66049)
		(width 0.14478)
		(layer "In4.Cu")
		(net "M_D_CPU1_SA_DQ<11>")
	)
	(segment
		(start 90.339672 -231.19715)
		(end 90.348054 -231.201976)
		(width 0.0889)
		(layer "In4.Cu")
		(net "M_D_CPU1_SA_DQ<11>")
	)
	(segment
		(start 45.557948 -208.8007)
		(end 46.407832 -209.650584)
		(width 0.14478)
		(layer "In4.Cu")
		(net "M_D_CPU1_SA_DQ<11>")
	)
	(segment
		(start 78.39075 -229.793546)
		(end 78.74635 -229.793546)
		(width 0.0889)
		(layer "In4.Cu")
		(net "M_D_CPU1_SA_DQ<11>")
	)
	(segment
		(start 46.407832 -209.650584)
		(end 49.382172 -209.650584)
		(width 0.14478)
		(layer "In4.Cu")
		(net "M_D_CPU1_SA_DQ<11>")
	)
	(segment
		(start 92.173044 -231.175814)
		(end 92.195142 -231.258872)
		(width 0.0889)
		(layer "In4.Cu")
		(net "M_D_CPU1_SA_DQ<11>")
	)
	(segment
		(start 83.394042 -231.201976)
		(end 83.402424 -231.19715)
		(width 0.0889)
		(layer "In4.Cu")
		(net "M_D_CPU1_SA_DQ<11>")
	)
	(segment
		(start 91.85402 -231.201976)
		(end 91.862402 -231.19715)
		(width 0.0889)
		(layer "In4.Cu")
		(net "M_D_CPU1_SA_DQ<11>")
	)
	(segment
		(start 77.76083 -229.163626)
		(end 78.39075 -229.793546)
		(width 0.0889)
		(layer "In4.Cu")
		(net "M_D_CPU1_SA_DQ<11>")
	)
	(segment
		(start 90.913966 -231.201976)
		(end 90.922348 -231.19715)
		(width 0.0889)
		(layer "In4.Cu")
		(net "M_D_CPU1_SA_DQ<11>")
	)
	(segment
		(start 32.695896 -209.235294)
		(end 33.111186 -209.650584)
		(width 0.14478)
		(layer "In4.Cu")
		(net "M_D_CPU1_SA_DQ<11>")
	)
	(arc
		(start 89.408 -231.201976)
		(mid 89.690956 -231.278153)
		(end 89.973912 -231.201976)
		(width 0.0889)
		(layer "In4.Cu")
		(net "M_D_CPU1_SA_DQ<11>")
	)
	(arc
		(start 80.008222 -231.201976)
		(mid 80.291178 -231.278153)
		(end 80.574134 -231.201976)
		(width 0.0889)
		(layer "In4.Cu")
		(net "M_D_CPU1_SA_DQ<11>")
	)
	(arc
		(start 79.540608 -230.393494)
		(mid 79.676193 -230.529227)
		(end 79.725774 -230.71455)
		(width 0.0889)
		(layer "In4.Cu")
		(net "M_D_CPU1_SA_DQ<11>")
	)
	(arc
		(start 88.10244 -231.19715)
		(mid 88.285948 -231.151625)
		(end 88.4682 -231.201976)
		(width 0.0889)
		(layer "In4.Cu")
		(net "M_D_CPU1_SA_DQ<11>")
	)
	(arc
		(start 89.973912 -231.201976)
		(mid 90.156163 -231.151592)
		(end 90.339672 -231.19715)
		(width 0.0889)
		(layer "In4.Cu")
		(net "M_D_CPU1_SA_DQ<11>")
	)
	(arc
		(start 81.513934 -231.201976)
		(mid 81.696185 -231.151592)
		(end 81.879694 -231.19715)
		(width 0.0889)
		(layer "In4.Cu")
		(net "M_D_CPU1_SA_DQ<11>")
	)
	(arc
		(start 84.334096 -231.201976)
		(mid 84.52104 -231.151687)
		(end 84.707984 -231.201976)
		(width 0.0889)
		(layer "In4.Cu")
		(net "M_D_CPU1_SA_DQ<11>")
	)
	(arc
		(start 84.707984 -231.201976)
		(mid 84.99094 -231.278153)
		(end 85.273896 -231.201976)
		(width 0.0889)
		(layer "In4.Cu")
		(net "M_D_CPU1_SA_DQ<11>")
	)
	(arc
		(start 91.288108 -231.201976)
		(mid 91.571064 -231.278153)
		(end 91.85402 -231.201976)
		(width 0.0889)
		(layer "In4.Cu")
		(net "M_D_CPU1_SA_DQ<11>")
	)
	(arc
		(start 83.768184 -231.201976)
		(mid 84.05114 -231.278153)
		(end 84.334096 -231.201976)
		(width 0.0889)
		(layer "In4.Cu")
		(net "M_D_CPU1_SA_DQ<11>")
	)
	(arc
		(start 85.273896 -231.201976)
		(mid 85.456147 -231.151592)
		(end 85.639656 -231.19715)
		(width 0.0889)
		(layer "In4.Cu")
		(net "M_D_CPU1_SA_DQ<11>")
	)
	(arc
		(start 87.162386 -231.19715)
		(mid 87.345894 -231.151625)
		(end 87.528146 -231.201976)
		(width 0.0889)
		(layer "In4.Cu")
		(net "M_D_CPU1_SA_DQ<11>")
	)
	(arc
		(start 91.862402 -231.19715)
		(mid 92.01539 -231.15247)
		(end 92.173044 -231.175814)
		(width 0.0889)
		(layer "In4.Cu")
		(net "M_D_CPU1_SA_DQ<11>")
	)
	(arc
		(start 82.46237 -231.19715)
		(mid 82.645878 -231.151625)
		(end 82.82813 -231.201976)
		(width 0.0889)
		(layer "In4.Cu")
		(net "M_D_CPU1_SA_DQ<11>")
	)
	(arc
		(start 79.205582 -230.252778)
		(mid 79.29245 -230.314622)
		(end 79.394812 -230.344472)
		(width 0.0889)
		(layer "In4.Cu")
		(net "M_D_CPU1_SA_DQ<11>")
	)
	(arc
		(start 80.948022 -231.201976)
		(mid 81.230978 -231.278153)
		(end 81.513934 -231.201976)
		(width 0.0889)
		(layer "In4.Cu")
		(net "M_D_CPU1_SA_DQ<11>")
	)
	(arc
		(start 79.725774 -230.71455)
		(mid 79.790289 -230.976769)
		(end 79.969106 -231.179116)
		(width 0.0889)
		(layer "In4.Cu")
		(net "M_D_CPU1_SA_DQ<11>")
	)
	(arc
		(start 79.394812 -230.344472)
		(mid 79.470255 -230.361404)
		(end 79.540608 -230.393494)
		(width 0.0889)
		(layer "In4.Cu")
		(net "M_D_CPU1_SA_DQ<11>")
	)
	(arc
		(start 86.21395 -231.201976)
		(mid 86.396201 -231.151592)
		(end 86.57971 -231.19715)
		(width 0.0889)
		(layer "In4.Cu")
		(net "M_D_CPU1_SA_DQ<11>")
	)
	(arc
		(start 83.402424 -231.19715)
		(mid 83.585932 -231.151625)
		(end 83.768184 -231.201976)
		(width 0.0889)
		(layer "In4.Cu")
		(net "M_D_CPU1_SA_DQ<11>")
	)
	(arc
		(start 86.588092 -231.201976)
		(mid 86.871048 -231.278153)
		(end 87.154004 -231.201976)
		(width 0.0889)
		(layer "In4.Cu")
		(net "M_D_CPU1_SA_DQ<11>")
	)
	(arc
		(start 81.888076 -231.201976)
		(mid 82.171032 -231.278153)
		(end 82.453988 -231.201976)
		(width 0.0889)
		(layer "In4.Cu")
		(net "M_D_CPU1_SA_DQ<11>")
	)
	(arc
		(start 82.82813 -231.201976)
		(mid 83.111086 -231.278153)
		(end 83.394042 -231.201976)
		(width 0.0889)
		(layer "In4.Cu")
		(net "M_D_CPU1_SA_DQ<11>")
	)
	(arc
		(start 90.348054 -231.201976)
		(mid 90.63101 -231.278153)
		(end 90.913966 -231.201976)
		(width 0.0889)
		(layer "In4.Cu")
		(net "M_D_CPU1_SA_DQ<11>")
	)
	(arc
		(start 80.574134 -231.201976)
		(mid 80.761078 -231.151687)
		(end 80.948022 -231.201976)
		(width 0.0889)
		(layer "In4.Cu")
		(net "M_D_CPU1_SA_DQ<11>")
	)
	(arc
		(start 85.648038 -231.201976)
		(mid 85.930994 -231.278153)
		(end 86.21395 -231.201976)
		(width 0.0889)
		(layer "In4.Cu")
		(net "M_D_CPU1_SA_DQ<11>")
	)
	(arc
		(start 88.4682 -231.201976)
		(mid 88.751156 -231.278153)
		(end 89.034112 -231.201976)
		(width 0.0889)
		(layer "In4.Cu")
		(net "M_D_CPU1_SA_DQ<11>")
	)
	(arc
		(start 89.034112 -231.201976)
		(mid 89.221056 -231.151687)
		(end 89.408 -231.201976)
		(width 0.0889)
		(layer "In4.Cu")
		(net "M_D_CPU1_SA_DQ<11>")
	)
	(arc
		(start 87.528146 -231.201976)
		(mid 87.811102 -231.278153)
		(end 88.094058 -231.201976)
		(width 0.0889)
		(layer "In4.Cu")
		(net "M_D_CPU1_SA_DQ<11>")
	)
	(arc
		(start 90.922348 -231.19715)
		(mid 91.105856 -231.151625)
		(end 91.288108 -231.201976)
		(width 0.0889)
		(layer "In4.Cu")
		(net "M_D_CPU1_SA_DQ<11>")
	)
	(segment
		(start 91.097862 -230.980234)
		(end 90.63101 -230.71455)
		(width 0.10668)
		(layer "F.Cu")
		(net "M_D_CPU1_SA_DQ<10>")
	)
	(segment
		(start 79.969106 -229.559104)
		(end 80.040734 -229.60076)
		(width 0.0889)
		(layer "In4.Cu")
		(net "M_D_CPU1_SA_DQ<10>")
	)
	(segment
		(start 87.989664 -230.387144)
		(end 87.998046 -230.39197)
		(width 0.0889)
		(layer "In4.Cu")
		(net "M_D_CPU1_SA_DQ<10>")
	)
	(segment
		(start 33.121092 -207.960468)
		(end 34.631376 -207.960468)
		(width 0.14478)
		(layer "In4.Cu")
		(net "M_D_CPU1_SA_DQ<10>")
	)
	(segment
		(start 84.803996 -230.39197)
		(end 84.812378 -230.387144)
		(width 0.0889)
		(layer "In4.Cu")
		(net "M_D_CPU1_SA_DQ<10>")
	)
	(segment
		(start 35.514026 -207.960468)
		(end 41.884092 -207.960468)
		(width 0.14478)
		(layer "In4.Cu")
		(net "M_D_CPU1_SA_DQ<10>")
	)
	(segment
		(start 77.39253 -227.032566)
		(end 78.21803 -227.858066)
		(width 0.0889)
		(layer "In4.Cu")
		(net "M_D_CPU1_SA_DQ<10>")
	)
	(segment
		(start 73.45045 -222.201486)
		(end 75.371706 -224.122742)
		(width 0.14478)
		(layer "In4.Cu")
		(net "M_D_CPU1_SA_DQ<10>")
	)
	(segment
		(start 35.350958 -207.434434)
		(end 35.350958 -207.7974)
		(width 0.14478)
		(layer "In4.Cu")
		(net "M_D_CPU1_SA_DQ<10>")
	)
	(segment
		(start 75.371706 -224.122742)
		(end 75.371706 -225.337624)
		(width 0.14478)
		(layer "In4.Cu")
		(net "M_D_CPU1_SA_DQ<10>")
	)
	(segment
		(start 83.289648 -230.387144)
		(end 83.29803 -230.39197)
		(width 0.0889)
		(layer "In4.Cu")
		(net "M_D_CPU1_SA_DQ<10>")
	)
	(segment
		(start 42.73423 -207.11033)
		(end 45.5676 -207.11033)
		(width 0.14478)
		(layer "In4.Cu")
		(net "M_D_CPU1_SA_DQ<10>")
	)
	(segment
		(start 89.504012 -230.39197)
		(end 89.512394 -230.387144)
		(width 0.0889)
		(layer "In4.Cu")
		(net "M_D_CPU1_SA_DQ<10>")
	)
	(segment
		(start 73.45045 -221.373446)
		(end 73.45045 -222.201486)
		(width 0.14478)
		(layer "In4.Cu")
		(net "M_D_CPU1_SA_DQ<10>")
	)
	(segment
		(start 34.794444 -207.7974)
		(end 34.794444 -207.434434)
		(width 0.14478)
		(layer "In4.Cu")
		(net "M_D_CPU1_SA_DQ<10>")
	)
	(segment
		(start 90.762582 -230.365808)
		(end 90.784934 -230.44912)
		(width 0.0889)
		(layer "In4.Cu")
		(net "M_D_CPU1_SA_DQ<10>")
	)
	(segment
		(start 35.18789 -207.271366)
		(end 35.350958 -207.434434)
		(width 0.14478)
		(layer "In4.Cu")
		(net "M_D_CPU1_SA_DQ<10>")
	)
	(segment
		(start 41.884092 -207.960468)
		(end 42.73423 -207.11033)
		(width 0.14478)
		(layer "In4.Cu")
		(net "M_D_CPU1_SA_DQ<10>")
	)
	(segment
		(start 34.794444 -207.434434)
		(end 34.957512 -207.271366)
		(width 0.14478)
		(layer "In4.Cu")
		(net "M_D_CPU1_SA_DQ<10>")
	)
	(segment
		(start 85.74405 -230.39197)
		(end 85.752432 -230.387144)
		(width 0.0889)
		(layer "In4.Cu")
		(net "M_D_CPU1_SA_DQ<10>")
	)
	(segment
		(start 80.441546 -230.370634)
		(end 80.478122 -230.39197)
		(width 0.0889)
		(layer "In4.Cu")
		(net "M_D_CPU1_SA_DQ<10>")
	)
	(segment
		(start 78.21803 -227.858066)
		(end 78.36789 -227.858066)
		(width 0.0889)
		(layer "In4.Cu")
		(net "M_D_CPU1_SA_DQ<10>")
	)
	(segment
		(start 34.631376 -207.960468)
		(end 34.794444 -207.7974)
		(width 0.14478)
		(layer "In4.Cu")
		(net "M_D_CPU1_SA_DQ<10>")
	)
	(segment
		(start 32.695896 -207.535272)
		(end 33.121092 -207.960468)
		(width 0.14478)
		(layer "In4.Cu")
		(net "M_D_CPU1_SA_DQ<10>")
	)
	(segment
		(start 35.350958 -207.7974)
		(end 35.514026 -207.960468)
		(width 0.14478)
		(layer "In4.Cu")
		(net "M_D_CPU1_SA_DQ<10>")
	)
	(segment
		(start 88.929718 -230.387144)
		(end 88.9381 -230.39197)
		(width 0.0889)
		(layer "In4.Cu")
		(net "M_D_CPU1_SA_DQ<10>")
	)
	(segment
		(start 90.784934 -230.44912)
		(end 90.63101 -230.71455)
		(width 0.0889)
		(layer "In4.Cu")
		(net "M_D_CPU1_SA_DQ<10>")
	)
	(segment
		(start 81.044034 -230.39197)
		(end 81.052416 -230.387144)
		(width 0.0889)
		(layer "In4.Cu")
		(net "M_D_CPU1_SA_DQ<10>")
	)
	(segment
		(start 50.222404 -207.11033)
		(end 53.256434 -207.11033)
		(width 0.14478)
		(layer "In4.Cu")
		(net "M_D_CPU1_SA_DQ<10>")
	)
	(segment
		(start 76.378816 -226.344734)
		(end 76.54925 -226.515168)
		(width 0.0889)
		(layer "In4.Cu")
		(net "M_D_CPU1_SA_DQ<10>")
	)
	(segment
		(start 75.371706 -225.337624)
		(end 76.378816 -226.344734)
		(width 0.14478)
		(layer "In4.Cu")
		(net "M_D_CPU1_SA_DQ<10>")
	)
	(segment
		(start 78.36789 -227.858066)
		(end 79.632302 -229.122478)
		(width 0.0889)
		(layer "In4.Cu")
		(net "M_D_CPU1_SA_DQ<10>")
	)
	(segment
		(start 60.037472 -207.960468)
		(end 73.45045 -221.373446)
		(width 0.14478)
		(layer "In4.Cu")
		(net "M_D_CPU1_SA_DQ<10>")
	)
	(segment
		(start 76.54925 -226.743006)
		(end 76.83881 -227.032566)
		(width 0.0889)
		(layer "In4.Cu")
		(net "M_D_CPU1_SA_DQ<10>")
	)
	(segment
		(start 49.372266 -207.960468)
		(end 50.222404 -207.11033)
		(width 0.14478)
		(layer "In4.Cu")
		(net "M_D_CPU1_SA_DQ<10>")
	)
	(segment
		(start 54.106572 -207.960468)
		(end 60.037472 -207.960468)
		(width 0.14478)
		(layer "In4.Cu")
		(net "M_D_CPU1_SA_DQ<10>")
	)
	(segment
		(start 84.229702 -230.387144)
		(end 84.238084 -230.39197)
		(width 0.0889)
		(layer "In4.Cu")
		(net "M_D_CPU1_SA_DQ<10>")
	)
	(segment
		(start 76.54925 -226.515168)
		(end 76.54925 -226.743006)
		(width 0.0889)
		(layer "In4.Cu")
		(net "M_D_CPU1_SA_DQ<10>")
	)
	(segment
		(start 76.83881 -227.032566)
		(end 77.39253 -227.032566)
		(width 0.0889)
		(layer "In4.Cu")
		(net "M_D_CPU1_SA_DQ<10>")
	)
	(segment
		(start 46.417738 -207.960468)
		(end 49.372266 -207.960468)
		(width 0.14478)
		(layer "In4.Cu")
		(net "M_D_CPU1_SA_DQ<10>")
	)
	(segment
		(start 53.256434 -207.11033)
		(end 54.106572 -207.960468)
		(width 0.14478)
		(layer "In4.Cu")
		(net "M_D_CPU1_SA_DQ<10>")
	)
	(segment
		(start 45.5676 -207.11033)
		(end 46.417738 -207.960468)
		(width 0.14478)
		(layer "In4.Cu")
		(net "M_D_CPU1_SA_DQ<10>")
	)
	(segment
		(start 34.957512 -207.271366)
		(end 35.18789 -207.271366)
		(width 0.14478)
		(layer "In4.Cu")
		(net "M_D_CPU1_SA_DQ<10>")
	)
	(arc
		(start 86.118192 -230.39197)
		(mid 86.401148 -230.468113)
		(end 86.684104 -230.39197)
		(width 0.0889)
		(layer "In4.Cu")
		(net "M_D_CPU1_SA_DQ<10>")
	)
	(arc
		(start 86.684104 -230.39197)
		(mid 86.871048 -230.341715)
		(end 87.057992 -230.39197)
		(width 0.0889)
		(layer "In4.Cu")
		(net "M_D_CPU1_SA_DQ<10>")
	)
	(arc
		(start 90.444066 -230.39197)
		(mid 90.600385 -230.342975)
		(end 90.762582 -230.365808)
		(width 0.0889)
		(layer "In4.Cu")
		(net "M_D_CPU1_SA_DQ<10>")
	)
	(arc
		(start 88.563958 -230.39197)
		(mid 88.746209 -230.34162)
		(end 88.929718 -230.387144)
		(width 0.0889)
		(layer "In4.Cu")
		(net "M_D_CPU1_SA_DQ<10>")
	)
	(arc
		(start 79.77759 -229.331012)
		(mid 79.85804 -229.457915)
		(end 79.969106 -229.559104)
		(width 0.0889)
		(layer "In4.Cu")
		(net "M_D_CPU1_SA_DQ<10>")
	)
	(arc
		(start 81.984088 -230.39197)
		(mid 82.171032 -230.341715)
		(end 82.357976 -230.39197)
		(width 0.0889)
		(layer "In4.Cu")
		(net "M_D_CPU1_SA_DQ<10>")
	)
	(arc
		(start 82.357976 -230.39197)
		(mid 82.640932 -230.468113)
		(end 82.923888 -230.39197)
		(width 0.0889)
		(layer "In4.Cu")
		(net "M_D_CPU1_SA_DQ<10>")
	)
	(arc
		(start 87.057992 -230.39197)
		(mid 87.340948 -230.468113)
		(end 87.623904 -230.39197)
		(width 0.0889)
		(layer "In4.Cu")
		(net "M_D_CPU1_SA_DQ<10>")
	)
	(arc
		(start 88.9381 -230.39197)
		(mid 89.221056 -230.468113)
		(end 89.504012 -230.39197)
		(width 0.0889)
		(layer "In4.Cu")
		(net "M_D_CPU1_SA_DQ<10>")
	)
	(arc
		(start 89.512394 -230.387144)
		(mid 89.695902 -230.34165)
		(end 89.878154 -230.39197)
		(width 0.0889)
		(layer "In4.Cu")
		(net "M_D_CPU1_SA_DQ<10>")
	)
	(arc
		(start 84.238084 -230.39197)
		(mid 84.52104 -230.468113)
		(end 84.803996 -230.39197)
		(width 0.0889)
		(layer "In4.Cu")
		(net "M_D_CPU1_SA_DQ<10>")
	)
	(arc
		(start 82.923888 -230.39197)
		(mid 83.106139 -230.34162)
		(end 83.289648 -230.387144)
		(width 0.0889)
		(layer "In4.Cu")
		(net "M_D_CPU1_SA_DQ<10>")
	)
	(arc
		(start 85.178138 -230.39197)
		(mid 85.461094 -230.468113)
		(end 85.74405 -230.39197)
		(width 0.0889)
		(layer "In4.Cu")
		(net "M_D_CPU1_SA_DQ<10>")
	)
	(arc
		(start 81.418176 -230.39197)
		(mid 81.701132 -230.468113)
		(end 81.984088 -230.39197)
		(width 0.0889)
		(layer "In4.Cu")
		(net "M_D_CPU1_SA_DQ<10>")
	)
	(arc
		(start 84.812378 -230.387144)
		(mid 84.995886 -230.34165)
		(end 85.178138 -230.39197)
		(width 0.0889)
		(layer "In4.Cu")
		(net "M_D_CPU1_SA_DQ<10>")
	)
	(arc
		(start 79.632302 -229.122478)
		(mid 79.714194 -229.220302)
		(end 79.77759 -229.331012)
		(width 0.0889)
		(layer "In4.Cu")
		(net "M_D_CPU1_SA_DQ<10>")
	)
	(arc
		(start 87.623904 -230.39197)
		(mid 87.806155 -230.34162)
		(end 87.989664 -230.387144)
		(width 0.0889)
		(layer "In4.Cu")
		(net "M_D_CPU1_SA_DQ<10>")
	)
	(arc
		(start 83.863942 -230.39197)
		(mid 84.046193 -230.34162)
		(end 84.229702 -230.387144)
		(width 0.0889)
		(layer "In4.Cu")
		(net "M_D_CPU1_SA_DQ<10>")
	)
	(arc
		(start 87.998046 -230.39197)
		(mid 88.281002 -230.468113)
		(end 88.563958 -230.39197)
		(width 0.0889)
		(layer "In4.Cu")
		(net "M_D_CPU1_SA_DQ<10>")
	)
	(arc
		(start 85.752432 -230.387144)
		(mid 85.93594 -230.34165)
		(end 86.118192 -230.39197)
		(width 0.0889)
		(layer "In4.Cu")
		(net "M_D_CPU1_SA_DQ<10>")
	)
	(arc
		(start 80.195674 -229.90429)
		(mid 80.26091 -230.167881)
		(end 80.441546 -230.370634)
		(width 0.0889)
		(layer "In4.Cu")
		(net "M_D_CPU1_SA_DQ<10>")
	)
	(arc
		(start 80.478122 -230.39197)
		(mid 80.761078 -230.468113)
		(end 81.044034 -230.39197)
		(width 0.0889)
		(layer "In4.Cu")
		(net "M_D_CPU1_SA_DQ<10>")
	)
	(arc
		(start 89.878154 -230.39197)
		(mid 90.16111 -230.468113)
		(end 90.444066 -230.39197)
		(width 0.0889)
		(layer "In4.Cu")
		(net "M_D_CPU1_SA_DQ<10>")
	)
	(arc
		(start 80.040734 -229.60076)
		(mid 80.154663 -229.733907)
		(end 80.195674 -229.90429)
		(width 0.0889)
		(layer "In4.Cu")
		(net "M_D_CPU1_SA_DQ<10>")
	)
	(arc
		(start 83.29803 -230.39197)
		(mid 83.580986 -230.468113)
		(end 83.863942 -230.39197)
		(width 0.0889)
		(layer "In4.Cu")
		(net "M_D_CPU1_SA_DQ<10>")
	)
	(arc
		(start 81.052416 -230.387144)
		(mid 81.235924 -230.34165)
		(end 81.418176 -230.39197)
		(width 0.0889)
		(layer "In4.Cu")
		(net "M_D_CPU1_SA_DQ<10>")
	)
	(segment
		(start 91.568016 -225.310446)
		(end 91.10091 -225.044508)
		(width 0.10668)
		(layer "F.Cu")
		(net "M_D_CPU1_SA_DQ<0>")
	)
	(segment
		(start 42.733214 -196.910452)
		(end 45.55871 -196.910452)
		(width 0.14478)
		(layer "In4.Cu")
		(net "M_D_CPU1_SA_DQ<0>")
	)
	(segment
		(start 82.453988 -223.747076)
		(end 82.493104 -223.769936)
		(width 0.0889)
		(layer "In4.Cu")
		(net "M_D_CPU1_SA_DQ<0>")
	)
	(segment
		(start 40.643048 -197.760336)
		(end 40.806116 -197.597268)
		(width 0.14478)
		(layer "In4.Cu")
		(net "M_D_CPU1_SA_DQ<0>")
	)
	(segment
		(start 53.23459 -196.910452)
		(end 54.084474 -197.760336)
		(width 0.14478)
		(layer "In4.Cu")
		(net "M_D_CPU1_SA_DQ<0>")
	)
	(segment
		(start 41.36263 -196.491352)
		(end 41.36263 -197.597268)
		(width 0.14478)
		(layer "In4.Cu")
		(net "M_D_CPU1_SA_DQ<0>")
	)
	(segment
		(start 81.952338 -222.918782)
		(end 82.02041 -222.958152)
		(width 0.0889)
		(layer "In4.Cu")
		(net "M_D_CPU1_SA_DQ<0>")
	)
	(segment
		(start 41.88333 -197.760336)
		(end 42.733214 -196.910452)
		(width 0.14478)
		(layer "In4.Cu")
		(net "M_D_CPU1_SA_DQ<0>")
	)
	(segment
		(start 37.693092 -197.760336)
		(end 37.85616 -197.597268)
		(width 0.14478)
		(layer "In4.Cu")
		(net "M_D_CPU1_SA_DQ<0>")
	)
	(segment
		(start 37.220906 -197.760336)
		(end 37.693092 -197.760336)
		(width 0.14478)
		(layer "In4.Cu")
		(net "M_D_CPU1_SA_DQ<0>")
	)
	(segment
		(start 82.422238 -223.728788)
		(end 82.453988 -223.747076)
		(width 0.0889)
		(layer "In4.Cu")
		(net "M_D_CPU1_SA_DQ<0>")
	)
	(segment
		(start 85.639656 -225.371914)
		(end 85.648038 -225.367088)
		(width 0.0889)
		(layer "In4.Cu")
		(net "M_D_CPU1_SA_DQ<0>")
	)
	(segment
		(start 88.094058 -225.367088)
		(end 88.10244 -225.371914)
		(width 0.0889)
		(layer "In4.Cu")
		(net "M_D_CPU1_SA_DQ<0>")
	)
	(segment
		(start 90.946986 -225.309938)
		(end 91.10091 -225.044508)
		(width 0.0889)
		(layer "In4.Cu")
		(net "M_D_CPU1_SA_DQ<0>")
	)
	(segment
		(start 41.199562 -196.328284)
		(end 41.36263 -196.491352)
		(width 0.14478)
		(layer "In4.Cu")
		(net "M_D_CPU1_SA_DQ<0>")
	)
	(segment
		(start 40.969184 -196.328284)
		(end 41.199562 -196.328284)
		(width 0.14478)
		(layer "In4.Cu")
		(net "M_D_CPU1_SA_DQ<0>")
	)
	(segment
		(start 37.85616 -197.597268)
		(end 37.85616 -197.200774)
		(width 0.14478)
		(layer "In4.Cu")
		(net "M_D_CPU1_SA_DQ<0>")
	)
	(segment
		(start 39.362634 -196.661024)
		(end 39.525702 -196.824092)
		(width 0.14478)
		(layer "In4.Cu")
		(net "M_D_CPU1_SA_DQ<0>")
	)
	(segment
		(start 90.339672 -225.371914)
		(end 90.348054 -225.367088)
		(width 0.0889)
		(layer "In4.Cu")
		(net "M_D_CPU1_SA_DQ<0>")
	)
	(segment
		(start 41.525698 -197.760336)
		(end 41.88333 -197.760336)
		(width 0.14478)
		(layer "In4.Cu")
		(net "M_D_CPU1_SA_DQ<0>")
	)
	(segment
		(start 82.923888 -224.557082)
		(end 82.963004 -224.579942)
		(width 0.0889)
		(layer "In4.Cu")
		(net "M_D_CPU1_SA_DQ<0>")
	)
	(segment
		(start 54.084474 -197.760336)
		(end 59.758326 -197.760336)
		(width 0.14478)
		(layer "In4.Cu")
		(net "M_D_CPU1_SA_DQ<0>")
	)
	(segment
		(start 40.806116 -196.491352)
		(end 40.969184 -196.328284)
		(width 0.14478)
		(layer "In4.Cu")
		(net "M_D_CPU1_SA_DQ<0>")
	)
	(segment
		(start 38.80612 -197.760336)
		(end 38.969188 -197.597268)
		(width 0.14478)
		(layer "In4.Cu")
		(net "M_D_CPU1_SA_DQ<0>")
	)
	(segment
		(start 81.796382 -221.583758)
		(end 81.796382 -222.61449)
		(width 0.0889)
		(layer "In4.Cu")
		(net "M_D_CPU1_SA_DQ<0>")
	)
	(segment
		(start 50.256694 -196.910452)
		(end 53.23459 -196.910452)
		(width 0.14478)
		(layer "In4.Cu")
		(net "M_D_CPU1_SA_DQ<0>")
	)
	(segment
		(start 46.408594 -197.760336)
		(end 49.40681 -197.760336)
		(width 0.14478)
		(layer "In4.Cu")
		(net "M_D_CPU1_SA_DQ<0>")
	)
	(segment
		(start 38.575742 -197.760336)
		(end 38.80612 -197.760336)
		(width 0.14478)
		(layer "In4.Cu")
		(net "M_D_CPU1_SA_DQ<0>")
	)
	(segment
		(start 83.394042 -225.367088)
		(end 83.402424 -225.371914)
		(width 0.0889)
		(layer "In4.Cu")
		(net "M_D_CPU1_SA_DQ<0>")
	)
	(segment
		(start 45.55871 -196.910452)
		(end 46.408594 -197.760336)
		(width 0.14478)
		(layer "In4.Cu")
		(net "M_D_CPU1_SA_DQ<0>")
	)
	(segment
		(start 39.68877 -197.760336)
		(end 40.643048 -197.760336)
		(width 0.14478)
		(layer "In4.Cu")
		(net "M_D_CPU1_SA_DQ<0>")
	)
	(segment
		(start 87.154004 -225.367088)
		(end 87.162386 -225.371914)
		(width 0.0889)
		(layer "In4.Cu")
		(net "M_D_CPU1_SA_DQ<0>")
	)
	(segment
		(start 86.57971 -225.371914)
		(end 86.588092 -225.367088)
		(width 0.0889)
		(layer "In4.Cu")
		(net "M_D_CPU1_SA_DQ<0>")
	)
	(segment
		(start 36.795964 -197.335394)
		(end 37.220906 -197.760336)
		(width 0.14478)
		(layer "In4.Cu")
		(net "M_D_CPU1_SA_DQ<0>")
	)
	(segment
		(start 81.574386 -221.361762)
		(end 81.796382 -221.583758)
		(width 0.0889)
		(layer "In4.Cu")
		(net "M_D_CPU1_SA_DQ<0>")
	)
	(segment
		(start 81.574386 -219.576396)
		(end 81.574386 -221.253304)
		(width 0.14478)
		(layer "In4.Cu")
		(net "M_D_CPU1_SA_DQ<0>")
	)
	(segment
		(start 38.249606 -197.037706)
		(end 38.412674 -197.200774)
		(width 0.14478)
		(layer "In4.Cu")
		(net "M_D_CPU1_SA_DQ<0>")
	)
	(segment
		(start 41.36263 -197.597268)
		(end 41.525698 -197.760336)
		(width 0.14478)
		(layer "In4.Cu")
		(net "M_D_CPU1_SA_DQ<0>")
	)
	(segment
		(start 39.525702 -197.597268)
		(end 39.68877 -197.760336)
		(width 0.14478)
		(layer "In4.Cu")
		(net "M_D_CPU1_SA_DQ<0>")
	)
	(segment
		(start 38.969188 -197.597268)
		(end 38.969188 -196.824092)
		(width 0.14478)
		(layer "In4.Cu")
		(net "M_D_CPU1_SA_DQ<0>")
	)
	(segment
		(start 38.412674 -197.200774)
		(end 38.412674 -197.597268)
		(width 0.14478)
		(layer "In4.Cu")
		(net "M_D_CPU1_SA_DQ<0>")
	)
	(segment
		(start 38.019228 -197.037706)
		(end 38.249606 -197.037706)
		(width 0.14478)
		(layer "In4.Cu")
		(net "M_D_CPU1_SA_DQ<0>")
	)
	(segment
		(start 39.132256 -196.661024)
		(end 39.362634 -196.661024)
		(width 0.14478)
		(layer "In4.Cu")
		(net "M_D_CPU1_SA_DQ<0>")
	)
	(segment
		(start 82.893408 -224.539302)
		(end 82.923888 -224.557082)
		(width 0.0889)
		(layer "In4.Cu")
		(net "M_D_CPU1_SA_DQ<0>")
	)
	(segment
		(start 40.806116 -197.597268)
		(end 40.806116 -196.491352)
		(width 0.14478)
		(layer "In4.Cu")
		(net "M_D_CPU1_SA_DQ<0>")
	)
	(segment
		(start 81.574386 -221.253304)
		(end 81.574386 -221.361762)
		(width 0.0889)
		(layer "In4.Cu")
		(net "M_D_CPU1_SA_DQ<0>")
	)
	(segment
		(start 38.969188 -196.824092)
		(end 39.132256 -196.661024)
		(width 0.14478)
		(layer "In4.Cu")
		(net "M_D_CPU1_SA_DQ<0>")
	)
	(segment
		(start 38.412674 -197.597268)
		(end 38.575742 -197.760336)
		(width 0.14478)
		(layer "In4.Cu")
		(net "M_D_CPU1_SA_DQ<0>")
	)
	(segment
		(start 37.85616 -197.200774)
		(end 38.019228 -197.037706)
		(width 0.14478)
		(layer "In4.Cu")
		(net "M_D_CPU1_SA_DQ<0>")
	)
	(segment
		(start 39.525702 -196.824092)
		(end 39.525702 -197.597268)
		(width 0.14478)
		(layer "In4.Cu")
		(net "M_D_CPU1_SA_DQ<0>")
	)
	(segment
		(start 49.40681 -197.760336)
		(end 50.256694 -196.910452)
		(width 0.14478)
		(layer "In4.Cu")
		(net "M_D_CPU1_SA_DQ<0>")
	)
	(segment
		(start 83.362292 -225.3488)
		(end 83.394042 -225.367088)
		(width 0.0889)
		(layer "In4.Cu")
		(net "M_D_CPU1_SA_DQ<0>")
	)
	(segment
		(start 90.850974 -225.335338)
		(end 90.946986 -225.309938)
		(width 0.0889)
		(layer "In4.Cu")
		(net "M_D_CPU1_SA_DQ<0>")
	)
	(segment
		(start 59.758326 -197.760336)
		(end 81.574386 -219.576396)
		(width 0.14478)
		(layer "In4.Cu")
		(net "M_D_CPU1_SA_DQ<0>")
	)
	(arc
		(start 87.162386 -225.371914)
		(mid 87.345894 -225.417408)
		(end 87.528146 -225.367088)
		(width 0.0889)
		(layer "In4.Cu")
		(net "M_D_CPU1_SA_DQ<0>")
	)
	(arc
		(start 84.707984 -225.367088)
		(mid 84.99094 -225.290911)
		(end 85.273896 -225.367088)
		(width 0.0889)
		(layer "In4.Cu")
		(net "M_D_CPU1_SA_DQ<0>")
	)
	(arc
		(start 85.648038 -225.367088)
		(mid 85.930994 -225.290911)
		(end 86.21395 -225.367088)
		(width 0.0889)
		(layer "In4.Cu")
		(net "M_D_CPU1_SA_DQ<0>")
	)
	(arc
		(start 82.963004 -224.579942)
		(mid 83.141817 -224.782292)
		(end 83.206336 -225.044508)
		(width 0.0889)
		(layer "In4.Cu")
		(net "M_D_CPU1_SA_DQ<0>")
	)
	(arc
		(start 81.796382 -222.61449)
		(mid 81.837637 -222.785461)
		(end 81.952338 -222.918782)
		(width 0.0889)
		(layer "In4.Cu")
		(net "M_D_CPU1_SA_DQ<0>")
	)
	(arc
		(start 86.21395 -225.367088)
		(mid 86.396201 -225.417438)
		(end 86.57971 -225.371914)
		(width 0.0889)
		(layer "In4.Cu")
		(net "M_D_CPU1_SA_DQ<0>")
	)
	(arc
		(start 83.768184 -225.367088)
		(mid 84.05114 -225.290911)
		(end 84.334096 -225.367088)
		(width 0.0889)
		(layer "In4.Cu")
		(net "M_D_CPU1_SA_DQ<0>")
	)
	(arc
		(start 85.273896 -225.367088)
		(mid 85.456147 -225.417438)
		(end 85.639656 -225.371914)
		(width 0.0889)
		(layer "In4.Cu")
		(net "M_D_CPU1_SA_DQ<0>")
	)
	(arc
		(start 87.528146 -225.367088)
		(mid 87.811102 -225.290911)
		(end 88.094058 -225.367088)
		(width 0.0889)
		(layer "In4.Cu")
		(net "M_D_CPU1_SA_DQ<0>")
	)
	(arc
		(start 82.493104 -223.769936)
		(mid 82.671917 -223.972286)
		(end 82.736436 -224.234502)
		(width 0.0889)
		(layer "In4.Cu")
		(net "M_D_CPU1_SA_DQ<0>")
	)
	(arc
		(start 88.4682 -225.367088)
		(mid 88.751156 -225.290911)
		(end 89.034112 -225.367088)
		(width 0.0889)
		(layer "In4.Cu")
		(net "M_D_CPU1_SA_DQ<0>")
	)
	(arc
		(start 90.348054 -225.367088)
		(mid 90.595767 -225.291868)
		(end 90.850974 -225.335338)
		(width 0.0889)
		(layer "In4.Cu")
		(net "M_D_CPU1_SA_DQ<0>")
	)
	(arc
		(start 89.973912 -225.367088)
		(mid 90.156163 -225.417438)
		(end 90.339672 -225.371914)
		(width 0.0889)
		(layer "In4.Cu")
		(net "M_D_CPU1_SA_DQ<0>")
	)
	(arc
		(start 82.02041 -222.958152)
		(mid 82.201062 -223.160897)
		(end 82.266282 -223.424496)
		(width 0.0889)
		(layer "In4.Cu")
		(net "M_D_CPU1_SA_DQ<0>")
	)
	(arc
		(start 83.402424 -225.371914)
		(mid 83.585932 -225.417408)
		(end 83.768184 -225.367088)
		(width 0.0889)
		(layer "In4.Cu")
		(net "M_D_CPU1_SA_DQ<0>")
	)
	(arc
		(start 89.034112 -225.367088)
		(mid 89.221056 -225.417343)
		(end 89.408 -225.367088)
		(width 0.0889)
		(layer "In4.Cu")
		(net "M_D_CPU1_SA_DQ<0>")
	)
	(arc
		(start 82.266282 -223.424496)
		(mid 82.307537 -223.595467)
		(end 82.422238 -223.728788)
		(width 0.0889)
		(layer "In4.Cu")
		(net "M_D_CPU1_SA_DQ<0>")
	)
	(arc
		(start 82.736436 -224.234502)
		(mid 82.777985 -224.405924)
		(end 82.893408 -224.539302)
		(width 0.0889)
		(layer "In4.Cu")
		(net "M_D_CPU1_SA_DQ<0>")
	)
	(arc
		(start 89.408 -225.367088)
		(mid 89.690956 -225.290911)
		(end 89.973912 -225.367088)
		(width 0.0889)
		(layer "In4.Cu")
		(net "M_D_CPU1_SA_DQ<0>")
	)
	(arc
		(start 84.334096 -225.367088)
		(mid 84.52104 -225.417343)
		(end 84.707984 -225.367088)
		(width 0.0889)
		(layer "In4.Cu")
		(net "M_D_CPU1_SA_DQ<0>")
	)
	(arc
		(start 86.588092 -225.367088)
		(mid 86.871048 -225.290911)
		(end 87.154004 -225.367088)
		(width 0.0889)
		(layer "In4.Cu")
		(net "M_D_CPU1_SA_DQ<0>")
	)
	(arc
		(start 88.10244 -225.371914)
		(mid 88.285948 -225.417408)
		(end 88.4682 -225.367088)
		(width 0.0889)
		(layer "In4.Cu")
		(net "M_D_CPU1_SA_DQ<0>")
	)
	(arc
		(start 83.206336 -225.044508)
		(mid 83.247591 -225.215479)
		(end 83.362292 -225.3488)
		(width 0.0889)
		(layer "In4.Cu")
		(net "M_D_CPU1_SA_DQ<0>")
	)
	(segment
		(start 92.507816 -252.850396)
		(end 92.040964 -252.584458)
		(width 0.10668)
		(layer "F.Cu")
		(net "M_D_CPU1_SA_CS_N<1>")
	)
	(segment
		(start 92.195142 -252.319028)
		(end 92.040964 -252.584458)
		(width 0.0889)
		(layer "In4.Cu")
		(net "M_D_CPU1_SA_CS_N<1>")
	)
	(segment
		(start 83.394042 -252.261878)
		(end 83.402424 -252.257052)
		(width 0.0889)
		(layer "In4.Cu")
		(net "M_D_CPU1_SA_CS_N<1>")
	)
	(segment
		(start 82.453988 -252.261878)
		(end 82.46237 -252.257052)
		(width 0.0889)
		(layer "In4.Cu")
		(net "M_D_CPU1_SA_CS_N<1>")
	)
	(segment
		(start 37.156898 -247.060212)
		(end 38.85692 -248.760234)
		(width 0.14478)
		(layer "In4.Cu")
		(net "M_D_CPU1_SA_CS_N<1>")
	)
	(segment
		(start 86.57971 -252.257052)
		(end 86.588092 -252.261878)
		(width 0.0889)
		(layer "In4.Cu")
		(net "M_D_CPU1_SA_CS_N<1>")
	)
	(segment
		(start 76.067666 -252.137164)
		(end 77.46492 -252.137164)
		(width 0.0889)
		(layer "In4.Cu")
		(net "M_D_CPU1_SA_CS_N<1>")
	)
	(segment
		(start 73.226676 -251.498354)
		(end 73.865486 -252.137164)
		(width 0.14478)
		(layer "In4.Cu")
		(net "M_D_CPU1_SA_CS_N<1>")
	)
	(segment
		(start 77.540866 -252.21311)
		(end 77.975206 -252.21311)
		(width 0.0889)
		(layer "In4.Cu")
		(net "M_D_CPU1_SA_CS_N<1>")
	)
	(segment
		(start 90.913966 -252.261878)
		(end 90.922348 -252.257052)
		(width 0.0889)
		(layer "In4.Cu")
		(net "M_D_CPU1_SA_CS_N<1>")
	)
	(segment
		(start 81.879694 -252.257052)
		(end 81.888076 -252.261878)
		(width 0.0889)
		(layer "In4.Cu")
		(net "M_D_CPU1_SA_CS_N<1>")
	)
	(segment
		(start 87.154004 -252.261878)
		(end 87.162386 -252.257052)
		(width 0.0889)
		(layer "In4.Cu")
		(net "M_D_CPU1_SA_CS_N<1>")
	)
	(segment
		(start 73.865486 -252.137164)
		(end 76.067666 -252.137164)
		(width 0.14478)
		(layer "In4.Cu")
		(net "M_D_CPU1_SA_CS_N<1>")
	)
	(segment
		(start 90.339672 -252.257052)
		(end 90.348054 -252.261878)
		(width 0.0889)
		(layer "In4.Cu")
		(net "M_D_CPU1_SA_CS_N<1>")
	)
	(segment
		(start 92.17279 -252.235716)
		(end 92.195142 -252.319028)
		(width 0.0889)
		(layer "In4.Cu")
		(net "M_D_CPU1_SA_CS_N<1>")
	)
	(segment
		(start 88.094058 -252.261878)
		(end 88.10244 -252.257052)
		(width 0.0889)
		(layer "In4.Cu")
		(net "M_D_CPU1_SA_CS_N<1>")
	)
	(segment
		(start 85.639656 -252.257052)
		(end 85.648038 -252.261878)
		(width 0.0889)
		(layer "In4.Cu")
		(net "M_D_CPU1_SA_CS_N<1>")
	)
	(segment
		(start 32.695896 -246.63527)
		(end 33.120838 -247.060212)
		(width 0.14478)
		(layer "In4.Cu")
		(net "M_D_CPU1_SA_CS_N<1>")
	)
	(segment
		(start 38.85692 -248.760234)
		(end 59.856878 -248.760234)
		(width 0.14478)
		(layer "In4.Cu")
		(net "M_D_CPU1_SA_CS_N<1>")
	)
	(segment
		(start 78.693518 -252.262132)
		(end 78.709774 -252.252734)
		(width 0.0889)
		(layer "In4.Cu")
		(net "M_D_CPU1_SA_CS_N<1>")
	)
	(segment
		(start 77.46492 -252.137164)
		(end 77.540866 -252.21311)
		(width 0.0889)
		(layer "In4.Cu")
		(net "M_D_CPU1_SA_CS_N<1>")
	)
	(segment
		(start 79.99984 -252.257052)
		(end 80.008222 -252.261878)
		(width 0.0889)
		(layer "In4.Cu")
		(net "M_D_CPU1_SA_CS_N<1>")
	)
	(segment
		(start 33.120838 -247.060212)
		(end 37.156898 -247.060212)
		(width 0.14478)
		(layer "In4.Cu")
		(net "M_D_CPU1_SA_CS_N<1>")
	)
	(segment
		(start 79.067406 -252.261878)
		(end 79.07782 -252.267974)
		(width 0.0889)
		(layer "In4.Cu")
		(net "M_D_CPU1_SA_CS_N<1>")
	)
	(segment
		(start 78.67777 -252.271276)
		(end 78.693518 -252.262132)
		(width 0.0889)
		(layer "In4.Cu")
		(net "M_D_CPU1_SA_CS_N<1>")
	)
	(segment
		(start 62.594998 -251.498354)
		(end 73.226676 -251.498354)
		(width 0.14478)
		(layer "In4.Cu")
		(net "M_D_CPU1_SA_CS_N<1>")
	)
	(segment
		(start 91.85402 -252.261878)
		(end 91.862402 -252.257052)
		(width 0.0889)
		(layer "In4.Cu")
		(net "M_D_CPU1_SA_CS_N<1>")
	)
	(segment
		(start 59.856878 -248.760234)
		(end 62.594998 -251.498354)
		(width 0.14478)
		(layer "In4.Cu")
		(net "M_D_CPU1_SA_CS_N<1>")
	)
	(arc
		(start 80.574134 -252.261878)
		(mid 80.761078 -252.211623)
		(end 80.948022 -252.261878)
		(width 0.0889)
		(layer "In4.Cu")
		(net "M_D_CPU1_SA_CS_N<1>")
	)
	(arc
		(start 87.528146 -252.261878)
		(mid 87.811102 -252.338055)
		(end 88.094058 -252.261878)
		(width 0.0889)
		(layer "In4.Cu")
		(net "M_D_CPU1_SA_CS_N<1>")
	)
	(arc
		(start 83.768184 -252.261878)
		(mid 84.05114 -252.338055)
		(end 84.334096 -252.261878)
		(width 0.0889)
		(layer "In4.Cu")
		(net "M_D_CPU1_SA_CS_N<1>")
	)
	(arc
		(start 89.408 -252.261878)
		(mid 89.690956 -252.338055)
		(end 89.973912 -252.261878)
		(width 0.0889)
		(layer "In4.Cu")
		(net "M_D_CPU1_SA_CS_N<1>")
	)
	(arc
		(start 89.973912 -252.261878)
		(mid 90.156163 -252.211528)
		(end 90.339672 -252.257052)
		(width 0.0889)
		(layer "In4.Cu")
		(net "M_D_CPU1_SA_CS_N<1>")
	)
	(arc
		(start 81.513934 -252.261878)
		(mid 81.696185 -252.211528)
		(end 81.879694 -252.257052)
		(width 0.0889)
		(layer "In4.Cu")
		(net "M_D_CPU1_SA_CS_N<1>")
	)
	(arc
		(start 89.034112 -252.261878)
		(mid 89.221056 -252.211623)
		(end 89.408 -252.261878)
		(width 0.0889)
		(layer "In4.Cu")
		(net "M_D_CPU1_SA_CS_N<1>")
	)
	(arc
		(start 78.127606 -252.261878)
		(mid 78.401461 -252.338228)
		(end 78.67777 -252.271276)
		(width 0.0889)
		(layer "In4.Cu")
		(net "M_D_CPU1_SA_CS_N<1>")
	)
	(arc
		(start 84.334096 -252.261878)
		(mid 84.52104 -252.211623)
		(end 84.707984 -252.261878)
		(width 0.0889)
		(layer "In4.Cu")
		(net "M_D_CPU1_SA_CS_N<1>")
	)
	(arc
		(start 91.862402 -252.257052)
		(mid 92.015272 -252.212411)
		(end 92.17279 -252.235716)
		(width 0.0889)
		(layer "In4.Cu")
		(net "M_D_CPU1_SA_CS_N<1>")
	)
	(arc
		(start 82.82813 -252.261878)
		(mid 83.111086 -252.338055)
		(end 83.394042 -252.261878)
		(width 0.0889)
		(layer "In4.Cu")
		(net "M_D_CPU1_SA_CS_N<1>")
	)
	(arc
		(start 86.21395 -252.261878)
		(mid 86.396201 -252.211528)
		(end 86.57971 -252.257052)
		(width 0.0889)
		(layer "In4.Cu")
		(net "M_D_CPU1_SA_CS_N<1>")
	)
	(arc
		(start 85.273896 -252.261878)
		(mid 85.456147 -252.211528)
		(end 85.639656 -252.257052)
		(width 0.0889)
		(layer "In4.Cu")
		(net "M_D_CPU1_SA_CS_N<1>")
	)
	(arc
		(start 78.709774 -252.252734)
		(mid 78.889756 -252.211634)
		(end 79.067406 -252.261878)
		(width 0.0889)
		(layer "In4.Cu")
		(net "M_D_CPU1_SA_CS_N<1>")
	)
	(arc
		(start 77.975206 -252.21311)
		(mid 78.054055 -252.229219)
		(end 78.127606 -252.261878)
		(width 0.0889)
		(layer "In4.Cu")
		(net "M_D_CPU1_SA_CS_N<1>")
	)
	(arc
		(start 85.648038 -252.261878)
		(mid 85.930994 -252.338055)
		(end 86.21395 -252.261878)
		(width 0.0889)
		(layer "In4.Cu")
		(net "M_D_CPU1_SA_CS_N<1>")
	)
	(arc
		(start 90.922348 -252.257052)
		(mid 91.105856 -252.211558)
		(end 91.288108 -252.261878)
		(width 0.0889)
		(layer "In4.Cu")
		(net "M_D_CPU1_SA_CS_N<1>")
	)
	(arc
		(start 81.888076 -252.261878)
		(mid 82.171032 -252.338055)
		(end 82.453988 -252.261878)
		(width 0.0889)
		(layer "In4.Cu")
		(net "M_D_CPU1_SA_CS_N<1>")
	)
	(arc
		(start 88.4682 -252.261878)
		(mid 88.751156 -252.338055)
		(end 89.034112 -252.261878)
		(width 0.0889)
		(layer "In4.Cu")
		(net "M_D_CPU1_SA_CS_N<1>")
	)
	(arc
		(start 90.348054 -252.261878)
		(mid 90.63101 -252.338055)
		(end 90.913966 -252.261878)
		(width 0.0889)
		(layer "In4.Cu")
		(net "M_D_CPU1_SA_CS_N<1>")
	)
	(arc
		(start 80.948022 -252.261878)
		(mid 81.230978 -252.338055)
		(end 81.513934 -252.261878)
		(width 0.0889)
		(layer "In4.Cu")
		(net "M_D_CPU1_SA_CS_N<1>")
	)
	(arc
		(start 91.288108 -252.261878)
		(mid 91.571064 -252.338055)
		(end 91.85402 -252.261878)
		(width 0.0889)
		(layer "In4.Cu")
		(net "M_D_CPU1_SA_CS_N<1>")
	)
	(arc
		(start 84.707984 -252.261878)
		(mid 84.99094 -252.338055)
		(end 85.273896 -252.261878)
		(width 0.0889)
		(layer "In4.Cu")
		(net "M_D_CPU1_SA_CS_N<1>")
	)
	(arc
		(start 79.633572 -252.261878)
		(mid 79.816077 -252.211401)
		(end 79.99984 -252.257052)
		(width 0.0889)
		(layer "In4.Cu")
		(net "M_D_CPU1_SA_CS_N<1>")
	)
	(arc
		(start 88.10244 -252.257052)
		(mid 88.285948 -252.211558)
		(end 88.4682 -252.261878)
		(width 0.0889)
		(layer "In4.Cu")
		(net "M_D_CPU1_SA_CS_N<1>")
	)
	(arc
		(start 87.162386 -252.257052)
		(mid 87.345894 -252.211558)
		(end 87.528146 -252.261878)
		(width 0.0889)
		(layer "In4.Cu")
		(net "M_D_CPU1_SA_CS_N<1>")
	)
	(arc
		(start 79.07782 -252.267974)
		(mid 79.356506 -252.338194)
		(end 79.633572 -252.261878)
		(width 0.0889)
		(layer "In4.Cu")
		(net "M_D_CPU1_SA_CS_N<1>")
	)
	(arc
		(start 86.588092 -252.261878)
		(mid 86.871048 -252.338055)
		(end 87.154004 -252.261878)
		(width 0.0889)
		(layer "In4.Cu")
		(net "M_D_CPU1_SA_CS_N<1>")
	)
	(arc
		(start 82.46237 -252.257052)
		(mid 82.645878 -252.211558)
		(end 82.82813 -252.261878)
		(width 0.0889)
		(layer "In4.Cu")
		(net "M_D_CPU1_SA_CS_N<1>")
	)
	(arc
		(start 80.008222 -252.261878)
		(mid 80.291178 -252.338055)
		(end 80.574134 -252.261878)
		(width 0.0889)
		(layer "In4.Cu")
		(net "M_D_CPU1_SA_CS_N<1>")
	)
	(arc
		(start 83.402424 -252.257052)
		(mid 83.585932 -252.211558)
		(end 83.768184 -252.261878)
		(width 0.0889)
		(layer "In4.Cu")
		(net "M_D_CPU1_SA_CS_N<1>")
	)
	(segment
		(start 91.097862 -252.04039)
		(end 90.63101 -251.774452)
		(width 0.10668)
		(layer "F.Cu")
		(net "M_D_CPU1_SA_CS_N<0>")
	)
	(segment
		(start 43.053 -248.073418)
		(end 43.216068 -247.91035)
		(width 0.14478)
		(layer "In4.Cu")
		(net "M_D_CPU1_SA_CS_N<0>")
	)
	(segment
		(start 83.289648 -251.447046)
		(end 83.29803 -251.451872)
		(width 0.0889)
		(layer "In4.Cu")
		(net "M_D_CPU1_SA_CS_N<0>")
	)
	(segment
		(start 48.960024 -248.073418)
		(end 48.960024 -248.133616)
		(width 0.14478)
		(layer "In4.Cu")
		(net "M_D_CPU1_SA_CS_N<0>")
	)
	(segment
		(start 50.629566 -248.133616)
		(end 50.629566 -248.073418)
		(width 0.14478)
		(layer "In4.Cu")
		(net "M_D_CPU1_SA_CS_N<0>")
	)
	(segment
		(start 76.070206 -251.593604)
		(end 77.19695 -251.593604)
		(width 0.0889)
		(layer "In4.Cu")
		(net "M_D_CPU1_SA_CS_N<0>")
	)
	(segment
		(start 41.546526 -248.304304)
		(end 41.776904 -248.304304)
		(width 0.14478)
		(layer "In4.Cu")
		(net "M_D_CPU1_SA_CS_N<0>")
	)
	(segment
		(start 62.804802 -251.048774)
		(end 73.420224 -251.048774)
		(width 0.14478)
		(layer "In4.Cu")
		(net "M_D_CPU1_SA_CS_N<0>")
	)
	(segment
		(start 42.889932 -248.304304)
		(end 43.053 -248.141236)
		(width 0.14478)
		(layer "In4.Cu")
		(net "M_D_CPU1_SA_CS_N<0>")
	)
	(segment
		(start 80.093566 -251.457968)
		(end 80.10398 -251.451872)
		(width 0.0889)
		(layer "In4.Cu")
		(net "M_D_CPU1_SA_CS_N<0>")
	)
	(segment
		(start 85.74405 -251.451872)
		(end 85.752432 -251.447046)
		(width 0.0889)
		(layer "In4.Cu")
		(net "M_D_CPU1_SA_CS_N<0>")
	)
	(segment
		(start 53.216048 -248.304304)
		(end 53.446426 -248.304304)
		(width 0.14478)
		(layer "In4.Cu")
		(net "M_D_CPU1_SA_CS_N<0>")
	)
	(segment
		(start 77.19695 -251.593604)
		(end 77.262228 -251.528326)
		(width 0.0889)
		(layer "In4.Cu")
		(net "M_D_CPU1_SA_CS_N<0>")
	)
	(segment
		(start 81.044034 -251.451872)
		(end 81.052416 -251.447046)
		(width 0.0889)
		(layer "In4.Cu")
		(net "M_D_CPU1_SA_CS_N<0>")
	)
	(segment
		(start 46.604428 -247.91035)
		(end 48.796956 -247.91035)
		(width 0.14478)
		(layer "In4.Cu")
		(net "M_D_CPU1_SA_CS_N<0>")
	)
	(segment
		(start 53.609494 -248.073418)
		(end 53.772562 -247.91035)
		(width 0.14478)
		(layer "In4.Cu")
		(net "M_D_CPU1_SA_CS_N<0>")
	)
	(segment
		(start 41.776904 -248.304304)
		(end 41.939972 -248.141236)
		(width 0.14478)
		(layer "In4.Cu")
		(net "M_D_CPU1_SA_CS_N<0>")
	)
	(segment
		(start 49.123092 -248.296684)
		(end 49.35347 -248.296684)
		(width 0.14478)
		(layer "In4.Cu")
		(net "M_D_CPU1_SA_CS_N<0>")
	)
	(segment
		(start 50.23612 -248.296684)
		(end 50.466498 -248.296684)
		(width 0.14478)
		(layer "In4.Cu")
		(net "M_D_CPU1_SA_CS_N<0>")
	)
	(segment
		(start 45.721778 -247.91035)
		(end 45.884846 -248.073418)
		(width 0.14478)
		(layer "In4.Cu")
		(net "M_D_CPU1_SA_CS_N<0>")
	)
	(segment
		(start 84.803996 -251.451872)
		(end 84.812378 -251.447046)
		(width 0.0889)
		(layer "In4.Cu")
		(net "M_D_CPU1_SA_CS_N<0>")
	)
	(segment
		(start 49.516538 -248.073418)
		(end 49.679606 -247.91035)
		(width 0.14478)
		(layer "In4.Cu")
		(net "M_D_CPU1_SA_CS_N<0>")
	)
	(segment
		(start 43.216068 -247.91035)
		(end 45.721778 -247.91035)
		(width 0.14478)
		(layer "In4.Cu")
		(net "M_D_CPU1_SA_CS_N<0>")
	)
	(segment
		(start 42.333418 -247.91035)
		(end 42.496486 -248.073418)
		(width 0.14478)
		(layer "In4.Cu")
		(net "M_D_CPU1_SA_CS_N<0>")
	)
	(segment
		(start 50.073052 -248.133616)
		(end 50.23612 -248.296684)
		(width 0.14478)
		(layer "In4.Cu")
		(net "M_D_CPU1_SA_CS_N<0>")
	)
	(segment
		(start 87.989664 -251.447046)
		(end 87.998046 -251.451872)
		(width 0.0889)
		(layer "In4.Cu")
		(net "M_D_CPU1_SA_CS_N<0>")
	)
	(segment
		(start 73.420224 -251.048774)
		(end 73.965054 -251.593604)
		(width 0.14478)
		(layer "In4.Cu")
		(net "M_D_CPU1_SA_CS_N<0>")
	)
	(segment
		(start 36.795964 -245.785386)
		(end 38.920928 -247.91035)
		(width 0.14478)
		(layer "In4.Cu")
		(net "M_D_CPU1_SA_CS_N<0>")
	)
	(segment
		(start 49.679606 -247.91035)
		(end 49.909984 -247.91035)
		(width 0.14478)
		(layer "In4.Cu")
		(net "M_D_CPU1_SA_CS_N<0>")
	)
	(segment
		(start 41.939972 -248.073418)
		(end 42.10304 -247.91035)
		(width 0.14478)
		(layer "In4.Cu")
		(net "M_D_CPU1_SA_CS_N<0>")
	)
	(segment
		(start 73.965054 -251.593604)
		(end 76.070206 -251.593604)
		(width 0.14478)
		(layer "In4.Cu")
		(net "M_D_CPU1_SA_CS_N<0>")
	)
	(segment
		(start 53.772562 -247.91035)
		(end 59.666378 -247.91035)
		(width 0.14478)
		(layer "In4.Cu")
		(net "M_D_CPU1_SA_CS_N<0>")
	)
	(segment
		(start 42.496486 -248.141236)
		(end 42.659554 -248.304304)
		(width 0.14478)
		(layer "In4.Cu")
		(net "M_D_CPU1_SA_CS_N<0>")
	)
	(segment
		(start 46.44136 -248.073418)
		(end 46.604428 -247.91035)
		(width 0.14478)
		(layer "In4.Cu")
		(net "M_D_CPU1_SA_CS_N<0>")
	)
	(segment
		(start 59.666378 -247.91035)
		(end 62.804802 -251.048774)
		(width 0.14478)
		(layer "In4.Cu")
		(net "M_D_CPU1_SA_CS_N<0>")
	)
	(segment
		(start 46.047914 -248.304304)
		(end 46.278292 -248.304304)
		(width 0.14478)
		(layer "In4.Cu")
		(net "M_D_CPU1_SA_CS_N<0>")
	)
	(segment
		(start 46.278292 -248.304304)
		(end 46.44136 -248.141236)
		(width 0.14478)
		(layer "In4.Cu")
		(net "M_D_CPU1_SA_CS_N<0>")
	)
	(segment
		(start 45.884846 -248.073418)
		(end 45.884846 -248.141236)
		(width 0.14478)
		(layer "In4.Cu")
		(net "M_D_CPU1_SA_CS_N<0>")
	)
	(segment
		(start 42.659554 -248.304304)
		(end 42.889932 -248.304304)
		(width 0.14478)
		(layer "In4.Cu")
		(net "M_D_CPU1_SA_CS_N<0>")
	)
	(segment
		(start 79.163672 -251.451872)
		(end 79.17815 -251.44349)
		(width 0.0889)
		(layer "In4.Cu")
		(net "M_D_CPU1_SA_CS_N<0>")
	)
	(segment
		(start 77.262228 -251.528326)
		(end 77.940154 -251.528326)
		(width 0.0889)
		(layer "In4.Cu")
		(net "M_D_CPU1_SA_CS_N<0>")
	)
	(segment
		(start 80.46974 -251.447046)
		(end 80.478122 -251.451872)
		(width 0.0889)
		(layer "In4.Cu")
		(net "M_D_CPU1_SA_CS_N<0>")
	)
	(segment
		(start 78.58633 -251.445014)
		(end 78.598014 -251.451872)
		(width 0.0889)
		(layer "In4.Cu")
		(net "M_D_CPU1_SA_CS_N<0>")
	)
	(segment
		(start 45.884846 -248.141236)
		(end 46.047914 -248.304304)
		(width 0.14478)
		(layer "In4.Cu")
		(net "M_D_CPU1_SA_CS_N<0>")
	)
	(segment
		(start 48.960024 -248.133616)
		(end 49.123092 -248.296684)
		(width 0.14478)
		(layer "In4.Cu")
		(net "M_D_CPU1_SA_CS_N<0>")
	)
	(segment
		(start 41.939972 -248.141236)
		(end 41.939972 -248.073418)
		(width 0.14478)
		(layer "In4.Cu")
		(net "M_D_CPU1_SA_CS_N<0>")
	)
	(segment
		(start 49.909984 -247.91035)
		(end 50.073052 -248.073418)
		(width 0.14478)
		(layer "In4.Cu")
		(net "M_D_CPU1_SA_CS_N<0>")
	)
	(segment
		(start 48.796956 -247.91035)
		(end 48.960024 -248.073418)
		(width 0.14478)
		(layer "In4.Cu")
		(net "M_D_CPU1_SA_CS_N<0>")
	)
	(segment
		(start 52.889912 -247.91035)
		(end 53.05298 -248.073418)
		(width 0.14478)
		(layer "In4.Cu")
		(net "M_D_CPU1_SA_CS_N<0>")
	)
	(segment
		(start 53.05298 -248.073418)
		(end 53.05298 -248.141236)
		(width 0.14478)
		(layer "In4.Cu")
		(net "M_D_CPU1_SA_CS_N<0>")
	)
	(segment
		(start 50.629566 -248.073418)
		(end 50.792634 -247.91035)
		(width 0.14478)
		(layer "In4.Cu")
		(net "M_D_CPU1_SA_CS_N<0>")
	)
	(segment
		(start 50.466498 -248.296684)
		(end 50.629566 -248.133616)
		(width 0.14478)
		(layer "In4.Cu")
		(net "M_D_CPU1_SA_CS_N<0>")
	)
	(segment
		(start 49.35347 -248.296684)
		(end 49.516538 -248.133616)
		(width 0.14478)
		(layer "In4.Cu")
		(net "M_D_CPU1_SA_CS_N<0>")
	)
	(segment
		(start 38.920928 -247.91035)
		(end 41.22039 -247.91035)
		(width 0.14478)
		(layer "In4.Cu")
		(net "M_D_CPU1_SA_CS_N<0>")
	)
	(segment
		(start 42.496486 -248.073418)
		(end 42.496486 -248.141236)
		(width 0.14478)
		(layer "In4.Cu")
		(net "M_D_CPU1_SA_CS_N<0>")
	)
	(segment
		(start 41.383458 -248.141236)
		(end 41.546526 -248.304304)
		(width 0.14478)
		(layer "In4.Cu")
		(net "M_D_CPU1_SA_CS_N<0>")
	)
	(segment
		(start 43.053 -248.141236)
		(end 43.053 -248.073418)
		(width 0.14478)
		(layer "In4.Cu")
		(net "M_D_CPU1_SA_CS_N<0>")
	)
	(segment
		(start 46.44136 -248.141236)
		(end 46.44136 -248.073418)
		(width 0.14478)
		(layer "In4.Cu")
		(net "M_D_CPU1_SA_CS_N<0>")
	)
	(segment
		(start 50.073052 -248.073418)
		(end 50.073052 -248.133616)
		(width 0.14478)
		(layer "In4.Cu")
		(net "M_D_CPU1_SA_CS_N<0>")
	)
	(segment
		(start 53.609494 -248.141236)
		(end 53.609494 -248.073418)
		(width 0.14478)
		(layer "In4.Cu")
		(net "M_D_CPU1_SA_CS_N<0>")
	)
	(segment
		(start 53.05298 -248.141236)
		(end 53.216048 -248.304304)
		(width 0.14478)
		(layer "In4.Cu")
		(net "M_D_CPU1_SA_CS_N<0>")
	)
	(segment
		(start 90.785188 -251.509022)
		(end 90.63101 -251.774452)
		(width 0.0889)
		(layer "In4.Cu")
		(net "M_D_CPU1_SA_CS_N<0>")
	)
	(segment
		(start 84.229702 -251.447046)
		(end 84.238084 -251.451872)
		(width 0.0889)
		(layer "In4.Cu")
		(net "M_D_CPU1_SA_CS_N<0>")
	)
	(segment
		(start 50.792634 -247.91035)
		(end 52.889912 -247.91035)
		(width 0.14478)
		(layer "In4.Cu")
		(net "M_D_CPU1_SA_CS_N<0>")
	)
	(segment
		(start 41.383458 -248.073418)
		(end 41.383458 -248.141236)
		(width 0.14478)
		(layer "In4.Cu")
		(net "M_D_CPU1_SA_CS_N<0>")
	)
	(segment
		(start 42.10304 -247.91035)
		(end 42.333418 -247.91035)
		(width 0.14478)
		(layer "In4.Cu")
		(net "M_D_CPU1_SA_CS_N<0>")
	)
	(segment
		(start 41.22039 -247.91035)
		(end 41.383458 -248.073418)
		(width 0.14478)
		(layer "In4.Cu")
		(net "M_D_CPU1_SA_CS_N<0>")
	)
	(segment
		(start 53.446426 -248.304304)
		(end 53.609494 -248.141236)
		(width 0.14478)
		(layer "In4.Cu")
		(net "M_D_CPU1_SA_CS_N<0>")
	)
	(segment
		(start 88.929718 -251.447046)
		(end 88.9381 -251.451872)
		(width 0.0889)
		(layer "In4.Cu")
		(net "M_D_CPU1_SA_CS_N<0>")
	)
	(segment
		(start 89.504012 -251.451872)
		(end 89.512394 -251.447046)
		(width 0.0889)
		(layer "In4.Cu")
		(net "M_D_CPU1_SA_CS_N<0>")
	)
	(segment
		(start 90.762836 -251.42571)
		(end 90.785188 -251.509022)
		(width 0.0889)
		(layer "In4.Cu")
		(net "M_D_CPU1_SA_CS_N<0>")
	)
	(segment
		(start 79.153258 -251.457968)
		(end 79.163672 -251.451872)
		(width 0.0889)
		(layer "In4.Cu")
		(net "M_D_CPU1_SA_CS_N<0>")
	)
	(segment
		(start 49.516538 -248.133616)
		(end 49.516538 -248.073418)
		(width 0.14478)
		(layer "In4.Cu")
		(net "M_D_CPU1_SA_CS_N<0>")
	)
	(segment
		(start 90.444066 -251.451872)
		(end 90.452448 -251.447046)
		(width 0.0889)
		(layer "In4.Cu")
		(net "M_D_CPU1_SA_CS_N<0>")
	)
	(arc
		(start 80.10398 -251.451872)
		(mid 80.286231 -251.401522)
		(end 80.46974 -251.447046)
		(width 0.0889)
		(layer "In4.Cu")
		(net "M_D_CPU1_SA_CS_N<0>")
	)
	(arc
		(start 86.684104 -251.451872)
		(mid 86.871048 -251.401617)
		(end 87.057992 -251.451872)
		(width 0.0889)
		(layer "In4.Cu")
		(net "M_D_CPU1_SA_CS_N<0>")
	)
	(arc
		(start 81.052416 -251.447046)
		(mid 81.235924 -251.401552)
		(end 81.418176 -251.451872)
		(width 0.0889)
		(layer "In4.Cu")
		(net "M_D_CPU1_SA_CS_N<0>")
	)
	(arc
		(start 84.238084 -251.451872)
		(mid 84.52104 -251.528049)
		(end 84.803996 -251.451872)
		(width 0.0889)
		(layer "In4.Cu")
		(net "M_D_CPU1_SA_CS_N<0>")
	)
	(arc
		(start 77.940154 -251.528326)
		(mid 78.086958 -251.50889)
		(end 78.223618 -251.451872)
		(width 0.0889)
		(layer "In4.Cu")
		(net "M_D_CPU1_SA_CS_N<0>")
	)
	(arc
		(start 87.057992 -251.451872)
		(mid 87.340948 -251.528049)
		(end 87.623904 -251.451872)
		(width 0.0889)
		(layer "In4.Cu")
		(net "M_D_CPU1_SA_CS_N<0>")
	)
	(arc
		(start 78.223618 -251.451872)
		(mid 78.404076 -251.401428)
		(end 78.58633 -251.445014)
		(width 0.0889)
		(layer "In4.Cu")
		(net "M_D_CPU1_SA_CS_N<0>")
	)
	(arc
		(start 81.984088 -251.451872)
		(mid 82.171032 -251.401617)
		(end 82.357976 -251.451872)
		(width 0.0889)
		(layer "In4.Cu")
		(net "M_D_CPU1_SA_CS_N<0>")
	)
	(arc
		(start 88.9381 -251.451872)
		(mid 89.221056 -251.528049)
		(end 89.504012 -251.451872)
		(width 0.0889)
		(layer "In4.Cu")
		(net "M_D_CPU1_SA_CS_N<0>")
	)
	(arc
		(start 87.623904 -251.451872)
		(mid 87.806155 -251.401522)
		(end 87.989664 -251.447046)
		(width 0.0889)
		(layer "In4.Cu")
		(net "M_D_CPU1_SA_CS_N<0>")
	)
	(arc
		(start 83.863942 -251.451872)
		(mid 84.046193 -251.401522)
		(end 84.229702 -251.447046)
		(width 0.0889)
		(layer "In4.Cu")
		(net "M_D_CPU1_SA_CS_N<0>")
	)
	(arc
		(start 82.923888 -251.451872)
		(mid 83.106139 -251.401522)
		(end 83.289648 -251.447046)
		(width 0.0889)
		(layer "In4.Cu")
		(net "M_D_CPU1_SA_CS_N<0>")
	)
	(arc
		(start 79.17815 -251.44349)
		(mid 79.359058 -251.401468)
		(end 79.537814 -251.451872)
		(width 0.0889)
		(layer "In4.Cu")
		(net "M_D_CPU1_SA_CS_N<0>")
	)
	(arc
		(start 78.598014 -251.451872)
		(mid 78.874827 -251.528015)
		(end 79.153258 -251.457968)
		(width 0.0889)
		(layer "In4.Cu")
		(net "M_D_CPU1_SA_CS_N<0>")
	)
	(arc
		(start 83.29803 -251.451872)
		(mid 83.580986 -251.528049)
		(end 83.863942 -251.451872)
		(width 0.0889)
		(layer "In4.Cu")
		(net "M_D_CPU1_SA_CS_N<0>")
	)
	(arc
		(start 80.478122 -251.451872)
		(mid 80.761078 -251.528049)
		(end 81.044034 -251.451872)
		(width 0.0889)
		(layer "In4.Cu")
		(net "M_D_CPU1_SA_CS_N<0>")
	)
	(arc
		(start 82.357976 -251.451872)
		(mid 82.640932 -251.528049)
		(end 82.923888 -251.451872)
		(width 0.0889)
		(layer "In4.Cu")
		(net "M_D_CPU1_SA_CS_N<0>")
	)
	(arc
		(start 85.178138 -251.451872)
		(mid 85.461094 -251.528049)
		(end 85.74405 -251.451872)
		(width 0.0889)
		(layer "In4.Cu")
		(net "M_D_CPU1_SA_CS_N<0>")
	)
	(arc
		(start 89.512394 -251.447046)
		(mid 89.695902 -251.401552)
		(end 89.878154 -251.451872)
		(width 0.0889)
		(layer "In4.Cu")
		(net "M_D_CPU1_SA_CS_N<0>")
	)
	(arc
		(start 79.537814 -251.451872)
		(mid 79.814881 -251.528143)
		(end 80.093566 -251.457968)
		(width 0.0889)
		(layer "In4.Cu")
		(net "M_D_CPU1_SA_CS_N<0>")
	)
	(arc
		(start 89.878154 -251.451872)
		(mid 90.16111 -251.528049)
		(end 90.444066 -251.451872)
		(width 0.0889)
		(layer "In4.Cu")
		(net "M_D_CPU1_SA_CS_N<0>")
	)
	(arc
		(start 84.812378 -251.447046)
		(mid 84.995886 -251.401552)
		(end 85.178138 -251.451872)
		(width 0.0889)
		(layer "In4.Cu")
		(net "M_D_CPU1_SA_CS_N<0>")
	)
	(arc
		(start 81.418176 -251.451872)
		(mid 81.701132 -251.528049)
		(end 81.984088 -251.451872)
		(width 0.0889)
		(layer "In4.Cu")
		(net "M_D_CPU1_SA_CS_N<0>")
	)
	(arc
		(start 90.452448 -251.447046)
		(mid 90.605318 -251.402405)
		(end 90.762836 -251.42571)
		(width 0.0889)
		(layer "In4.Cu")
		(net "M_D_CPU1_SA_CS_N<0>")
	)
	(arc
		(start 88.563958 -251.451872)
		(mid 88.746209 -251.401522)
		(end 88.929718 -251.447046)
		(width 0.0889)
		(layer "In4.Cu")
		(net "M_D_CPU1_SA_CS_N<0>")
	)
	(arc
		(start 86.118192 -251.451872)
		(mid 86.401148 -251.528049)
		(end 86.684104 -251.451872)
		(width 0.0889)
		(layer "In4.Cu")
		(net "M_D_CPU1_SA_CS_N<0>")
	)
	(arc
		(start 87.998046 -251.451872)
		(mid 88.281002 -251.528049)
		(end 88.563958 -251.451872)
		(width 0.0889)
		(layer "In4.Cu")
		(net "M_D_CPU1_SA_CS_N<0>")
	)
	(arc
		(start 85.752432 -251.447046)
		(mid 85.93594 -251.401552)
		(end 86.118192 -251.451872)
		(width 0.0889)
		(layer "In4.Cu")
		(net "M_D_CPU1_SA_CS_N<0>")
	)
	(segment
		(start 92.507816 -249.610372)
		(end 92.040964 -249.344434)
		(width 0.10668)
		(layer "F.Cu")
		(net "M_D_CPU1_SA_CB<7>")
	)
	(segment
		(start 81.879694 -249.017028)
		(end 81.888076 -249.021854)
		(width 0.0889)
		(layer "In4.Cu")
		(net "M_D_CPU1_SA_CB<7>")
	)
	(segment
		(start 34.897568 -243.660422)
		(end 35.060636 -243.497354)
		(width 0.14478)
		(layer "In4.Cu")
		(net "M_D_CPU1_SA_CB<7>")
	)
	(segment
		(start 87.154004 -249.021854)
		(end 87.162386 -249.017028)
		(width 0.0889)
		(layer "In4.Cu")
		(net "M_D_CPU1_SA_CB<7>")
	)
	(segment
		(start 33.947608 -242.605052)
		(end 34.110676 -242.441984)
		(width 0.14478)
		(layer "In4.Cu")
		(net "M_D_CPU1_SA_CB<7>")
	)
	(segment
		(start 35.454082 -242.960906)
		(end 35.61715 -243.123974)
		(width 0.14478)
		(layer "In4.Cu")
		(net "M_D_CPU1_SA_CB<7>")
	)
	(segment
		(start 76.67879 -249.201686)
		(end 77.08519 -249.201686)
		(width 0.0889)
		(layer "In4.Cu")
		(net "M_D_CPU1_SA_CB<7>")
	)
	(segment
		(start 78.693518 -249.022108)
		(end 78.709774 -249.01271)
		(width 0.0889)
		(layer "In4.Cu")
		(net "M_D_CPU1_SA_CB<7>")
	)
	(segment
		(start 58.705242 -245.469918)
		(end 60.20816 -245.469918)
		(width 0.14478)
		(layer "In4.Cu")
		(net "M_D_CPU1_SA_CB<7>")
	)
	(segment
		(start 74.581766 -249.460004)
		(end 75.940666 -249.460004)
		(width 0.14478)
		(layer "In4.Cu")
		(net "M_D_CPU1_SA_CB<7>")
	)
	(segment
		(start 90.913966 -249.021854)
		(end 90.922348 -249.017028)
		(width 0.0889)
		(layer "In4.Cu")
		(net "M_D_CPU1_SA_CB<7>")
	)
	(segment
		(start 77.75321 -249.021854)
		(end 77.764894 -249.014996)
		(width 0.0889)
		(layer "In4.Cu")
		(net "M_D_CPU1_SA_CB<7>")
	)
	(segment
		(start 92.17279 -248.995692)
		(end 92.195142 -249.079004)
		(width 0.0889)
		(layer "In4.Cu")
		(net "M_D_CPU1_SA_CB<7>")
	)
	(segment
		(start 75.940666 -249.460004)
		(end 76.420472 -249.460004)
		(width 0.0889)
		(layer "In4.Cu")
		(net "M_D_CPU1_SA_CB<7>")
	)
	(segment
		(start 34.504122 -243.497354)
		(end 34.66719 -243.660422)
		(width 0.14478)
		(layer "In4.Cu")
		(net "M_D_CPU1_SA_CB<7>")
	)
	(segment
		(start 35.060636 -243.123974)
		(end 35.223704 -242.960906)
		(width 0.14478)
		(layer "In4.Cu")
		(net "M_D_CPU1_SA_CB<7>")
	)
	(segment
		(start 60.20816 -245.469918)
		(end 63.884556 -249.146314)
		(width 0.14478)
		(layer "In4.Cu")
		(net "M_D_CPU1_SA_CB<7>")
	)
	(segment
		(start 90.339672 -249.017028)
		(end 90.348054 -249.021854)
		(width 0.0889)
		(layer "In4.Cu")
		(net "M_D_CPU1_SA_CB<7>")
	)
	(segment
		(start 85.639656 -249.017028)
		(end 85.648038 -249.021854)
		(width 0.0889)
		(layer "In4.Cu")
		(net "M_D_CPU1_SA_CB<7>")
	)
	(segment
		(start 55.661306 -243.660422)
		(end 57.11571 -245.114826)
		(width 0.14478)
		(layer "In4.Cu")
		(net "M_D_CPU1_SA_CB<7>")
	)
	(segment
		(start 35.61715 -243.123974)
		(end 35.61715 -243.497354)
		(width 0.14478)
		(layer "In4.Cu")
		(net "M_D_CPU1_SA_CB<7>")
	)
	(segment
		(start 34.110676 -242.441984)
		(end 34.341054 -242.441984)
		(width 0.14478)
		(layer "In4.Cu")
		(net "M_D_CPU1_SA_CB<7>")
	)
	(segment
		(start 79.067406 -249.021854)
		(end 79.07782 -249.02795)
		(width 0.0889)
		(layer "In4.Cu")
		(net "M_D_CPU1_SA_CB<7>")
	)
	(segment
		(start 34.66719 -243.660422)
		(end 34.897568 -243.660422)
		(width 0.14478)
		(layer "In4.Cu")
		(net "M_D_CPU1_SA_CB<7>")
	)
	(segment
		(start 34.341054 -242.441984)
		(end 34.504122 -242.605052)
		(width 0.14478)
		(layer "In4.Cu")
		(net "M_D_CPU1_SA_CB<7>")
	)
	(segment
		(start 35.060636 -243.497354)
		(end 35.060636 -243.123974)
		(width 0.14478)
		(layer "In4.Cu")
		(net "M_D_CPU1_SA_CB<7>")
	)
	(segment
		(start 78.67777 -249.031252)
		(end 78.693518 -249.022108)
		(width 0.0889)
		(layer "In4.Cu")
		(net "M_D_CPU1_SA_CB<7>")
	)
	(segment
		(start 57.11571 -245.114826)
		(end 58.35015 -245.114826)
		(width 0.14478)
		(layer "In4.Cu")
		(net "M_D_CPU1_SA_CB<7>")
	)
	(segment
		(start 35.223704 -242.960906)
		(end 35.454082 -242.960906)
		(width 0.14478)
		(layer "In4.Cu")
		(net "M_D_CPU1_SA_CB<7>")
	)
	(segment
		(start 83.394042 -249.021854)
		(end 83.402424 -249.017028)
		(width 0.0889)
		(layer "In4.Cu")
		(net "M_D_CPU1_SA_CB<7>")
	)
	(segment
		(start 74.268076 -249.146314)
		(end 74.581766 -249.460004)
		(width 0.14478)
		(layer "In4.Cu")
		(net "M_D_CPU1_SA_CB<7>")
	)
	(segment
		(start 91.85402 -249.021854)
		(end 91.862402 -249.017028)
		(width 0.0889)
		(layer "In4.Cu")
		(net "M_D_CPU1_SA_CB<7>")
	)
	(segment
		(start 63.884556 -249.146314)
		(end 74.268076 -249.146314)
		(width 0.14478)
		(layer "In4.Cu")
		(net "M_D_CPU1_SA_CB<7>")
	)
	(segment
		(start 88.094058 -249.021854)
		(end 88.10244 -249.017028)
		(width 0.0889)
		(layer "In4.Cu")
		(net "M_D_CPU1_SA_CB<7>")
	)
	(segment
		(start 86.57971 -249.017028)
		(end 86.588092 -249.021854)
		(width 0.0889)
		(layer "In4.Cu")
		(net "M_D_CPU1_SA_CB<7>")
	)
	(segment
		(start 82.453988 -249.021854)
		(end 82.46237 -249.017028)
		(width 0.0889)
		(layer "In4.Cu")
		(net "M_D_CPU1_SA_CB<7>")
	)
	(segment
		(start 33.78454 -243.660422)
		(end 33.947608 -243.497354)
		(width 0.14478)
		(layer "In4.Cu")
		(net "M_D_CPU1_SA_CB<7>")
	)
	(segment
		(start 79.99984 -249.017028)
		(end 80.008222 -249.021854)
		(width 0.0889)
		(layer "In4.Cu")
		(net "M_D_CPU1_SA_CB<7>")
	)
	(segment
		(start 76.420472 -249.460004)
		(end 76.67879 -249.201686)
		(width 0.0889)
		(layer "In4.Cu")
		(net "M_D_CPU1_SA_CB<7>")
	)
	(segment
		(start 34.504122 -242.605052)
		(end 34.504122 -243.497354)
		(width 0.14478)
		(layer "In4.Cu")
		(net "M_D_CPU1_SA_CB<7>")
	)
	(segment
		(start 33.947608 -243.497354)
		(end 33.947608 -242.605052)
		(width 0.14478)
		(layer "In4.Cu")
		(net "M_D_CPU1_SA_CB<7>")
	)
	(segment
		(start 35.780218 -243.660422)
		(end 55.661306 -243.660422)
		(width 0.14478)
		(layer "In4.Cu")
		(net "M_D_CPU1_SA_CB<7>")
	)
	(segment
		(start 32.695896 -243.235226)
		(end 33.121092 -243.660422)
		(width 0.14478)
		(layer "In4.Cu")
		(net "M_D_CPU1_SA_CB<7>")
	)
	(segment
		(start 58.35015 -245.114826)
		(end 58.705242 -245.469918)
		(width 0.14478)
		(layer "In4.Cu")
		(net "M_D_CPU1_SA_CB<7>")
	)
	(segment
		(start 35.61715 -243.497354)
		(end 35.780218 -243.660422)
		(width 0.14478)
		(layer "In4.Cu")
		(net "M_D_CPU1_SA_CB<7>")
	)
	(segment
		(start 33.121092 -243.660422)
		(end 33.78454 -243.660422)
		(width 0.14478)
		(layer "In4.Cu")
		(net "M_D_CPU1_SA_CB<7>")
	)
	(segment
		(start 92.195142 -249.079004)
		(end 92.040964 -249.344434)
		(width 0.0889)
		(layer "In4.Cu")
		(net "M_D_CPU1_SA_CB<7>")
	)
	(arc
		(start 87.162386 -249.017028)
		(mid 87.345894 -248.971534)
		(end 87.528146 -249.021854)
		(width 0.0889)
		(layer "In4.Cu")
		(net "M_D_CPU1_SA_CB<7>")
	)
	(arc
		(start 78.709774 -249.01271)
		(mid 78.889756 -248.97161)
		(end 79.067406 -249.021854)
		(width 0.0889)
		(layer "In4.Cu")
		(net "M_D_CPU1_SA_CB<7>")
	)
	(arc
		(start 89.408 -249.021854)
		(mid 89.690956 -249.098031)
		(end 89.973912 -249.021854)
		(width 0.0889)
		(layer "In4.Cu")
		(net "M_D_CPU1_SA_CB<7>")
	)
	(arc
		(start 77.764894 -249.014996)
		(mid 77.947149 -248.971343)
		(end 78.127606 -249.021854)
		(width 0.0889)
		(layer "In4.Cu")
		(net "M_D_CPU1_SA_CB<7>")
	)
	(arc
		(start 79.633572 -249.021854)
		(mid 79.816077 -248.971377)
		(end 79.99984 -249.017028)
		(width 0.0889)
		(layer "In4.Cu")
		(net "M_D_CPU1_SA_CB<7>")
	)
	(arc
		(start 90.348054 -249.021854)
		(mid 90.63101 -249.098031)
		(end 90.913966 -249.021854)
		(width 0.0889)
		(layer "In4.Cu")
		(net "M_D_CPU1_SA_CB<7>")
	)
	(arc
		(start 87.528146 -249.021854)
		(mid 87.811102 -249.098031)
		(end 88.094058 -249.021854)
		(width 0.0889)
		(layer "In4.Cu")
		(net "M_D_CPU1_SA_CB<7>")
	)
	(arc
		(start 77.08519 -249.201686)
		(mid 77.431083 -249.155927)
		(end 77.75321 -249.021854)
		(width 0.0889)
		(layer "In4.Cu")
		(net "M_D_CPU1_SA_CB<7>")
	)
	(arc
		(start 91.288108 -249.021854)
		(mid 91.571064 -249.098031)
		(end 91.85402 -249.021854)
		(width 0.0889)
		(layer "In4.Cu")
		(net "M_D_CPU1_SA_CB<7>")
	)
	(arc
		(start 85.273896 -249.021854)
		(mid 85.456147 -248.971504)
		(end 85.639656 -249.017028)
		(width 0.0889)
		(layer "In4.Cu")
		(net "M_D_CPU1_SA_CB<7>")
	)
	(arc
		(start 83.768184 -249.021854)
		(mid 84.05114 -249.098031)
		(end 84.334096 -249.021854)
		(width 0.0889)
		(layer "In4.Cu")
		(net "M_D_CPU1_SA_CB<7>")
	)
	(arc
		(start 80.574134 -249.021854)
		(mid 80.761078 -248.971599)
		(end 80.948022 -249.021854)
		(width 0.0889)
		(layer "In4.Cu")
		(net "M_D_CPU1_SA_CB<7>")
	)
	(arc
		(start 88.4682 -249.021854)
		(mid 88.751156 -249.098031)
		(end 89.034112 -249.021854)
		(width 0.0889)
		(layer "In4.Cu")
		(net "M_D_CPU1_SA_CB<7>")
	)
	(arc
		(start 82.82813 -249.021854)
		(mid 83.111086 -249.098031)
		(end 83.394042 -249.021854)
		(width 0.0889)
		(layer "In4.Cu")
		(net "M_D_CPU1_SA_CB<7>")
	)
	(arc
		(start 90.922348 -249.017028)
		(mid 91.105856 -248.971534)
		(end 91.288108 -249.021854)
		(width 0.0889)
		(layer "In4.Cu")
		(net "M_D_CPU1_SA_CB<7>")
	)
	(arc
		(start 82.46237 -249.017028)
		(mid 82.645878 -248.971534)
		(end 82.82813 -249.021854)
		(width 0.0889)
		(layer "In4.Cu")
		(net "M_D_CPU1_SA_CB<7>")
	)
	(arc
		(start 78.127606 -249.021854)
		(mid 78.401461 -249.098204)
		(end 78.67777 -249.031252)
		(width 0.0889)
		(layer "In4.Cu")
		(net "M_D_CPU1_SA_CB<7>")
	)
	(arc
		(start 85.648038 -249.021854)
		(mid 85.930994 -249.098031)
		(end 86.21395 -249.021854)
		(width 0.0889)
		(layer "In4.Cu")
		(net "M_D_CPU1_SA_CB<7>")
	)
	(arc
		(start 86.21395 -249.021854)
		(mid 86.396201 -248.971504)
		(end 86.57971 -249.017028)
		(width 0.0889)
		(layer "In4.Cu")
		(net "M_D_CPU1_SA_CB<7>")
	)
	(arc
		(start 84.334096 -249.021854)
		(mid 84.52104 -248.971599)
		(end 84.707984 -249.021854)
		(width 0.0889)
		(layer "In4.Cu")
		(net "M_D_CPU1_SA_CB<7>")
	)
	(arc
		(start 80.008222 -249.021854)
		(mid 80.291178 -249.098031)
		(end 80.574134 -249.021854)
		(width 0.0889)
		(layer "In4.Cu")
		(net "M_D_CPU1_SA_CB<7>")
	)
	(arc
		(start 81.513934 -249.021854)
		(mid 81.696185 -248.971504)
		(end 81.879694 -249.017028)
		(width 0.0889)
		(layer "In4.Cu")
		(net "M_D_CPU1_SA_CB<7>")
	)
	(arc
		(start 83.402424 -249.017028)
		(mid 83.585932 -248.971534)
		(end 83.768184 -249.021854)
		(width 0.0889)
		(layer "In4.Cu")
		(net "M_D_CPU1_SA_CB<7>")
	)
	(arc
		(start 88.10244 -249.017028)
		(mid 88.285948 -248.971534)
		(end 88.4682 -249.021854)
		(width 0.0889)
		(layer "In4.Cu")
		(net "M_D_CPU1_SA_CB<7>")
	)
	(arc
		(start 89.973912 -249.021854)
		(mid 90.156163 -248.971504)
		(end 90.339672 -249.017028)
		(width 0.0889)
		(layer "In4.Cu")
		(net "M_D_CPU1_SA_CB<7>")
	)
	(arc
		(start 91.862402 -249.017028)
		(mid 92.015272 -248.972387)
		(end 92.17279 -248.995692)
		(width 0.0889)
		(layer "In4.Cu")
		(net "M_D_CPU1_SA_CB<7>")
	)
	(arc
		(start 89.034112 -249.021854)
		(mid 89.221056 -248.971599)
		(end 89.408 -249.021854)
		(width 0.0889)
		(layer "In4.Cu")
		(net "M_D_CPU1_SA_CB<7>")
	)
	(arc
		(start 79.07782 -249.02795)
		(mid 79.356506 -249.09817)
		(end 79.633572 -249.021854)
		(width 0.0889)
		(layer "In4.Cu")
		(net "M_D_CPU1_SA_CB<7>")
	)
	(arc
		(start 84.707984 -249.021854)
		(mid 84.99094 -249.098031)
		(end 85.273896 -249.021854)
		(width 0.0889)
		(layer "In4.Cu")
		(net "M_D_CPU1_SA_CB<7>")
	)
	(arc
		(start 86.588092 -249.021854)
		(mid 86.871048 -249.098031)
		(end 87.154004 -249.021854)
		(width 0.0889)
		(layer "In4.Cu")
		(net "M_D_CPU1_SA_CB<7>")
	)
	(arc
		(start 81.888076 -249.021854)
		(mid 82.171032 -249.098031)
		(end 82.453988 -249.021854)
		(width 0.0889)
		(layer "In4.Cu")
		(net "M_D_CPU1_SA_CB<7>")
	)
	(arc
		(start 80.948022 -249.021854)
		(mid 81.230978 -249.098031)
		(end 81.513934 -249.021854)
		(width 0.0889)
		(layer "In4.Cu")
		(net "M_D_CPU1_SA_CB<7>")
	)
	(segment
		(start 91.097862 -248.800366)
		(end 90.63101 -248.534428)
		(width 0.10668)
		(layer "F.Cu")
		(net "M_D_CPU1_SA_CB<6>")
	)
	(segment
		(start 35.491674 -241.9604)
		(end 35.654742 -241.797332)
		(width 0.14478)
		(layer "In4.Cu")
		(net "M_D_CPU1_SA_CB<6>")
	)
	(segment
		(start 35.81781 -240.648744)
		(end 36.048188 -240.648744)
		(width 0.14478)
		(layer "In4.Cu")
		(net "M_D_CPU1_SA_CB<6>")
	)
	(segment
		(start 84.803996 -248.211848)
		(end 84.812378 -248.207022)
		(width 0.0889)
		(layer "In4.Cu")
		(net "M_D_CPU1_SA_CB<6>")
	)
	(segment
		(start 77.43317 -248.635266)
		(end 77.52461 -248.543826)
		(width 0.0889)
		(layer "In4.Cu")
		(net "M_D_CPU1_SA_CB<6>")
	)
	(segment
		(start 59.743848 -243.667026)
		(end 64.313816 -248.236994)
		(width 0.14478)
		(layer "In4.Cu")
		(net "M_D_CPU1_SA_CB<6>")
	)
	(segment
		(start 36.211256 -240.811812)
		(end 36.211256 -241.797332)
		(width 0.14478)
		(layer "In4.Cu")
		(net "M_D_CPU1_SA_CB<6>")
	)
	(segment
		(start 76.35367 -248.635266)
		(end 77.43317 -248.635266)
		(width 0.0889)
		(layer "In4.Cu")
		(net "M_D_CPU1_SA_CB<6>")
	)
	(segment
		(start 79.521304 -248.201688)
		(end 79.539592 -248.212102)
		(width 0.0889)
		(layer "In4.Cu")
		(net "M_D_CPU1_SA_CB<6>")
	)
	(segment
		(start 84.229702 -248.207022)
		(end 84.238084 -248.211848)
		(width 0.0889)
		(layer "In4.Cu")
		(net "M_D_CPU1_SA_CB<6>")
	)
	(segment
		(start 80.46974 -248.207022)
		(end 80.478122 -248.211848)
		(width 0.0889)
		(layer "In4.Cu")
		(net "M_D_CPU1_SA_CB<6>")
	)
	(segment
		(start 64.313816 -248.236994)
		(end 74.666856 -248.236994)
		(width 0.14478)
		(layer "In4.Cu")
		(net "M_D_CPU1_SA_CB<6>")
	)
	(segment
		(start 90.762582 -248.185686)
		(end 90.784934 -248.268998)
		(width 0.0889)
		(layer "In4.Cu")
		(net "M_D_CPU1_SA_CB<6>")
	)
	(segment
		(start 34.93516 -240.819686)
		(end 35.098228 -240.982754)
		(width 0.14478)
		(layer "In4.Cu")
		(net "M_D_CPU1_SA_CB<6>")
	)
	(segment
		(start 34.541714 -241.797332)
		(end 34.541714 -240.982754)
		(width 0.14478)
		(layer "In4.Cu")
		(net "M_D_CPU1_SA_CB<6>")
	)
	(segment
		(start 34.378646 -241.9604)
		(end 34.541714 -241.797332)
		(width 0.14478)
		(layer "In4.Cu")
		(net "M_D_CPU1_SA_CB<6>")
	)
	(segment
		(start 89.504012 -248.211848)
		(end 89.512394 -248.207022)
		(width 0.0889)
		(layer "In4.Cu")
		(net "M_D_CPU1_SA_CB<6>")
	)
	(segment
		(start 77.875384 -248.543826)
		(end 78.147926 -248.271284)
		(width 0.0889)
		(layer "In4.Cu")
		(net "M_D_CPU1_SA_CB<6>")
	)
	(segment
		(start 79.539592 -248.212102)
		(end 79.561182 -248.224548)
		(width 0.0889)
		(layer "In4.Cu")
		(net "M_D_CPU1_SA_CB<6>")
	)
	(segment
		(start 90.784934 -248.268998)
		(end 90.63101 -248.534428)
		(width 0.0889)
		(layer "In4.Cu")
		(net "M_D_CPU1_SA_CB<6>")
	)
	(segment
		(start 85.74405 -248.211848)
		(end 85.752432 -248.207022)
		(width 0.0889)
		(layer "In4.Cu")
		(net "M_D_CPU1_SA_CB<6>")
	)
	(segment
		(start 76.261468 -248.543064)
		(end 76.35367 -248.635266)
		(width 0.0889)
		(layer "In4.Cu")
		(net "M_D_CPU1_SA_CB<6>")
	)
	(segment
		(start 81.044034 -248.211848)
		(end 81.052416 -248.207022)
		(width 0.0889)
		(layer "In4.Cu")
		(net "M_D_CPU1_SA_CB<6>")
	)
	(segment
		(start 35.261296 -241.9604)
		(end 35.491674 -241.9604)
		(width 0.14478)
		(layer "In4.Cu")
		(net "M_D_CPU1_SA_CB<6>")
	)
	(segment
		(start 36.374324 -241.9604)
		(end 56.798972 -241.9604)
		(width 0.14478)
		(layer "In4.Cu")
		(net "M_D_CPU1_SA_CB<6>")
	)
	(segment
		(start 78.225142 -248.212102)
		(end 78.252574 -248.196354)
		(width 0.0889)
		(layer "In4.Cu")
		(net "M_D_CPU1_SA_CB<6>")
	)
	(segment
		(start 87.989664 -248.207022)
		(end 87.998046 -248.211848)
		(width 0.0889)
		(layer "In4.Cu")
		(net "M_D_CPU1_SA_CB<6>")
	)
	(segment
		(start 79.143098 -248.225564)
		(end 79.166466 -248.211848)
		(width 0.0889)
		(layer "In4.Cu")
		(net "M_D_CPU1_SA_CB<6>")
	)
	(segment
		(start 58.505598 -243.667026)
		(end 59.743848 -243.667026)
		(width 0.14478)
		(layer "In4.Cu")
		(net "M_D_CPU1_SA_CB<6>")
	)
	(segment
		(start 56.798972 -241.9604)
		(end 58.505598 -243.667026)
		(width 0.14478)
		(layer "In4.Cu")
		(net "M_D_CPU1_SA_CB<6>")
	)
	(segment
		(start 35.098228 -240.982754)
		(end 35.098228 -241.797332)
		(width 0.14478)
		(layer "In4.Cu")
		(net "M_D_CPU1_SA_CB<6>")
	)
	(segment
		(start 34.541714 -240.982754)
		(end 34.704782 -240.819686)
		(width 0.14478)
		(layer "In4.Cu")
		(net "M_D_CPU1_SA_CB<6>")
	)
	(segment
		(start 36.048188 -240.648744)
		(end 36.211256 -240.811812)
		(width 0.14478)
		(layer "In4.Cu")
		(net "M_D_CPU1_SA_CB<6>")
	)
	(segment
		(start 74.666856 -248.236994)
		(end 74.972926 -248.543064)
		(width 0.14478)
		(layer "In4.Cu")
		(net "M_D_CPU1_SA_CB<6>")
	)
	(segment
		(start 36.211256 -241.797332)
		(end 36.374324 -241.9604)
		(width 0.14478)
		(layer "In4.Cu")
		(net "M_D_CPU1_SA_CB<6>")
	)
	(segment
		(start 32.695896 -241.535204)
		(end 33.121092 -241.9604)
		(width 0.14478)
		(layer "In4.Cu")
		(net "M_D_CPU1_SA_CB<6>")
	)
	(segment
		(start 74.972926 -248.543064)
		(end 75.927966 -248.543064)
		(width 0.14478)
		(layer "In4.Cu")
		(net "M_D_CPU1_SA_CB<6>")
	)
	(segment
		(start 75.927966 -248.543064)
		(end 76.261468 -248.543064)
		(width 0.0889)
		(layer "In4.Cu")
		(net "M_D_CPU1_SA_CB<6>")
	)
	(segment
		(start 34.704782 -240.819686)
		(end 34.93516 -240.819686)
		(width 0.14478)
		(layer "In4.Cu")
		(net "M_D_CPU1_SA_CB<6>")
	)
	(segment
		(start 35.654742 -241.797332)
		(end 35.654742 -240.811812)
		(width 0.14478)
		(layer "In4.Cu")
		(net "M_D_CPU1_SA_CB<6>")
	)
	(segment
		(start 35.654742 -240.811812)
		(end 35.81781 -240.648744)
		(width 0.14478)
		(layer "In4.Cu")
		(net "M_D_CPU1_SA_CB<6>")
	)
	(segment
		(start 33.121092 -241.9604)
		(end 34.378646 -241.9604)
		(width 0.14478)
		(layer "In4.Cu")
		(net "M_D_CPU1_SA_CB<6>")
	)
	(segment
		(start 83.289648 -248.207022)
		(end 83.29803 -248.211848)
		(width 0.0889)
		(layer "In4.Cu")
		(net "M_D_CPU1_SA_CB<6>")
	)
	(segment
		(start 35.098228 -241.797332)
		(end 35.261296 -241.9604)
		(width 0.14478)
		(layer "In4.Cu")
		(net "M_D_CPU1_SA_CB<6>")
	)
	(segment
		(start 88.929718 -248.207022)
		(end 88.9381 -248.211848)
		(width 0.0889)
		(layer "In4.Cu")
		(net "M_D_CPU1_SA_CB<6>")
	)
	(segment
		(start 77.52461 -248.543826)
		(end 77.875384 -248.543826)
		(width 0.0889)
		(layer "In4.Cu")
		(net "M_D_CPU1_SA_CB<6>")
	)
	(arc
		(start 78.599284 -248.211848)
		(mid 78.869441 -248.28861)
		(end 79.143098 -248.225564)
		(width 0.0889)
		(layer "In4.Cu")
		(net "M_D_CPU1_SA_CB<6>")
	)
	(arc
		(start 81.052416 -248.207022)
		(mid 81.235924 -248.161528)
		(end 81.418176 -248.211848)
		(width 0.0889)
		(layer "In4.Cu")
		(net "M_D_CPU1_SA_CB<6>")
	)
	(arc
		(start 87.623904 -248.211848)
		(mid 87.806155 -248.161498)
		(end 87.989664 -248.207022)
		(width 0.0889)
		(layer "In4.Cu")
		(net "M_D_CPU1_SA_CB<6>")
	)
	(arc
		(start 80.478122 -248.211848)
		(mid 80.761078 -248.288025)
		(end 81.044034 -248.211848)
		(width 0.0889)
		(layer "In4.Cu")
		(net "M_D_CPU1_SA_CB<6>")
	)
	(arc
		(start 84.812378 -248.207022)
		(mid 84.995886 -248.161528)
		(end 85.178138 -248.211848)
		(width 0.0889)
		(layer "In4.Cu")
		(net "M_D_CPU1_SA_CB<6>")
	)
	(arc
		(start 89.512394 -248.207022)
		(mid 89.695902 -248.161528)
		(end 89.878154 -248.211848)
		(width 0.0889)
		(layer "In4.Cu")
		(net "M_D_CPU1_SA_CB<6>")
	)
	(arc
		(start 82.357976 -248.211848)
		(mid 82.640932 -248.288025)
		(end 82.923888 -248.211848)
		(width 0.0889)
		(layer "In4.Cu")
		(net "M_D_CPU1_SA_CB<6>")
	)
	(arc
		(start 78.252574 -248.196354)
		(mid 78.427825 -248.161421)
		(end 78.599284 -248.211848)
		(width 0.0889)
		(layer "In4.Cu")
		(net "M_D_CPU1_SA_CB<6>")
	)
	(arc
		(start 88.563958 -248.211848)
		(mid 88.746209 -248.161498)
		(end 88.929718 -248.207022)
		(width 0.0889)
		(layer "In4.Cu")
		(net "M_D_CPU1_SA_CB<6>")
	)
	(arc
		(start 80.10398 -248.211848)
		(mid 80.286231 -248.161498)
		(end 80.46974 -248.207022)
		(width 0.0889)
		(layer "In4.Cu")
		(net "M_D_CPU1_SA_CB<6>")
	)
	(arc
		(start 79.561182 -248.224548)
		(mid 79.834211 -248.287867)
		(end 80.10398 -248.211848)
		(width 0.0889)
		(layer "In4.Cu")
		(net "M_D_CPU1_SA_CB<6>")
	)
	(arc
		(start 79.166466 -248.211848)
		(mid 79.342586 -248.16187)
		(end 79.521304 -248.201688)
		(width 0.0889)
		(layer "In4.Cu")
		(net "M_D_CPU1_SA_CB<6>")
	)
	(arc
		(start 84.238084 -248.211848)
		(mid 84.52104 -248.288025)
		(end 84.803996 -248.211848)
		(width 0.0889)
		(layer "In4.Cu")
		(net "M_D_CPU1_SA_CB<6>")
	)
	(arc
		(start 87.057992 -248.211848)
		(mid 87.340948 -248.288025)
		(end 87.623904 -248.211848)
		(width 0.0889)
		(layer "In4.Cu")
		(net "M_D_CPU1_SA_CB<6>")
	)
	(arc
		(start 83.29803 -248.211848)
		(mid 83.580986 -248.288025)
		(end 83.863942 -248.211848)
		(width 0.0889)
		(layer "In4.Cu")
		(net "M_D_CPU1_SA_CB<6>")
	)
	(arc
		(start 82.923888 -248.211848)
		(mid 83.106139 -248.161498)
		(end 83.289648 -248.207022)
		(width 0.0889)
		(layer "In4.Cu")
		(net "M_D_CPU1_SA_CB<6>")
	)
	(arc
		(start 88.9381 -248.211848)
		(mid 89.221056 -248.288025)
		(end 89.504012 -248.211848)
		(width 0.0889)
		(layer "In4.Cu")
		(net "M_D_CPU1_SA_CB<6>")
	)
	(arc
		(start 86.118192 -248.211848)
		(mid 86.401148 -248.288025)
		(end 86.684104 -248.211848)
		(width 0.0889)
		(layer "In4.Cu")
		(net "M_D_CPU1_SA_CB<6>")
	)
	(arc
		(start 89.878154 -248.211848)
		(mid 90.16111 -248.288025)
		(end 90.444066 -248.211848)
		(width 0.0889)
		(layer "In4.Cu")
		(net "M_D_CPU1_SA_CB<6>")
	)
	(arc
		(start 87.998046 -248.211848)
		(mid 88.281002 -248.288025)
		(end 88.563958 -248.211848)
		(width 0.0889)
		(layer "In4.Cu")
		(net "M_D_CPU1_SA_CB<6>")
	)
	(arc
		(start 83.863942 -248.211848)
		(mid 84.046193 -248.161498)
		(end 84.229702 -248.207022)
		(width 0.0889)
		(layer "In4.Cu")
		(net "M_D_CPU1_SA_CB<6>")
	)
	(arc
		(start 90.444066 -248.211848)
		(mid 90.600385 -248.162853)
		(end 90.762582 -248.185686)
		(width 0.0889)
		(layer "In4.Cu")
		(net "M_D_CPU1_SA_CB<6>")
	)
	(arc
		(start 81.984088 -248.211848)
		(mid 82.171032 -248.161593)
		(end 82.357976 -248.211848)
		(width 0.0889)
		(layer "In4.Cu")
		(net "M_D_CPU1_SA_CB<6>")
	)
	(arc
		(start 85.178138 -248.211848)
		(mid 85.461094 -248.288025)
		(end 85.74405 -248.211848)
		(width 0.0889)
		(layer "In4.Cu")
		(net "M_D_CPU1_SA_CB<6>")
	)
	(arc
		(start 81.418176 -248.211848)
		(mid 81.701132 -248.288025)
		(end 81.984088 -248.211848)
		(width 0.0889)
		(layer "In4.Cu")
		(net "M_D_CPU1_SA_CB<6>")
	)
	(arc
		(start 78.147926 -248.271284)
		(mid 78.184582 -248.239144)
		(end 78.225142 -248.212102)
		(width 0.0889)
		(layer "In4.Cu")
		(net "M_D_CPU1_SA_CB<6>")
	)
	(arc
		(start 85.752432 -248.207022)
		(mid 85.93594 -248.161528)
		(end 86.118192 -248.211848)
		(width 0.0889)
		(layer "In4.Cu")
		(net "M_D_CPU1_SA_CB<6>")
	)
	(arc
		(start 86.684104 -248.211848)
		(mid 86.871048 -248.161593)
		(end 87.057992 -248.211848)
		(width 0.0889)
		(layer "In4.Cu")
		(net "M_D_CPU1_SA_CB<6>")
	)
	(segment
		(start 92.97797 -248.800366)
		(end 92.511118 -248.534428)
		(width 0.10668)
		(layer "F.Cu")
		(net "M_D_CPU1_SA_CB<5>")
	)
	(segment
		(start 84.229702 -248.861834)
		(end 84.238084 -248.857008)
		(width 0.0889)
		(layer "In4.Cu")
		(net "M_D_CPU1_SA_CB<5>")
	)
	(segment
		(start 46.440344 -243.044218)
		(end 46.440344 -242.57635)
		(width 0.14478)
		(layer "In4.Cu")
		(net "M_D_CPU1_SA_CB<5>")
	)
	(segment
		(start 78.579472 -248.867168)
		(end 78.59776 -248.856754)
		(width 0.0889)
		(layer "In4.Cu")
		(net "M_D_CPU1_SA_CB<5>")
	)
	(segment
		(start 47.153322 -242.810284)
		(end 48.443388 -242.810284)
		(width 0.14478)
		(layer "In4.Cu")
		(net "M_D_CPU1_SA_CB<5>")
	)
	(segment
		(start 81.044034 -248.857008)
		(end 81.052416 -248.861834)
		(width 0.0889)
		(layer "In4.Cu")
		(net "M_D_CPU1_SA_CB<5>")
	)
	(segment
		(start 44.947586 -243.205762)
		(end 45.175932 -243.205762)
		(width 0.14478)
		(layer "In4.Cu")
		(net "M_D_CPU1_SA_CB<5>")
	)
	(segment
		(start 50.259234 -242.71605)
		(end 50.259234 -243.046758)
		(width 0.14478)
		(layer "In4.Cu")
		(net "M_D_CPU1_SA_CB<5>")
	)
	(segment
		(start 77.469746 -248.907554)
		(end 77.47 -248.9073)
		(width 0.0889)
		(layer "In4.Cu")
		(net "M_D_CPU1_SA_CB<5>")
	)
	(segment
		(start 53.59019 -243.047266)
		(end 53.818536 -243.047266)
		(width 0.14478)
		(layer "In4.Cu")
		(net "M_D_CPU1_SA_CB<5>")
	)
	(segment
		(start 50.649124 -243.208302)
		(end 50.810668 -243.046758)
		(width 0.14478)
		(layer "In4.Cu")
		(net "M_D_CPU1_SA_CB<5>")
	)
	(segment
		(start 50.972212 -242.412266)
		(end 51.200558 -242.412266)
		(width 0.14478)
		(layer "In4.Cu")
		(net "M_D_CPU1_SA_CB<5>")
	)
	(segment
		(start 45.88891 -243.044218)
		(end 46.050454 -243.205762)
		(width 0.14478)
		(layer "In4.Cu")
		(net "M_D_CPU1_SA_CB<5>")
	)
	(segment
		(start 49.156366 -243.046758)
		(end 49.31791 -243.208302)
		(width 0.14478)
		(layer "In4.Cu")
		(net "M_D_CPU1_SA_CB<5>")
	)
	(segment
		(start 54.531514 -242.57381)
		(end 54.531514 -242.64874)
		(width 0.14478)
		(layer "In4.Cu")
		(net "M_D_CPU1_SA_CB<5>")
	)
	(segment
		(start 56.93156 -242.78209)
		(end 57.093104 -242.943634)
		(width 0.14478)
		(layer "In4.Cu")
		(net "M_D_CPU1_SA_CB<5>")
	)
	(segment
		(start 76.151232 -249.002804)
		(end 76.24953 -248.904506)
		(width 0.0889)
		(layer "In4.Cu")
		(net "M_D_CPU1_SA_CB<5>")
	)
	(segment
		(start 83.289648 -248.861834)
		(end 83.29803 -248.857008)
		(width 0.0889)
		(layer "In4.Cu")
		(net "M_D_CPU1_SA_CB<5>")
	)
	(segment
		(start 48.443388 -242.810284)
		(end 48.604932 -242.64874)
		(width 0.14478)
		(layer "In4.Cu")
		(net "M_D_CPU1_SA_CB<5>")
	)
	(segment
		(start 79.163164 -248.857008)
		(end 79.171546 -248.861834)
		(width 0.0889)
		(layer "In4.Cu")
		(net "M_D_CPU1_SA_CB<5>")
	)
	(segment
		(start 56.722772 -243.542566)
		(end 56.722772 -243.771166)
		(width 0.14478)
		(layer "In4.Cu")
		(net "M_D_CPU1_SA_CB<5>")
	)
	(segment
		(start 54.693058 -242.810284)
		(end 55.76189 -242.810284)
		(width 0.14478)
		(layer "In4.Cu")
		(net "M_D_CPU1_SA_CB<5>")
	)
	(segment
		(start 49.7078 -242.71605)
		(end 49.869344 -242.554506)
		(width 0.14478)
		(layer "In4.Cu")
		(net "M_D_CPU1_SA_CB<5>")
	)
	(segment
		(start 56.104028 -243.152422)
		(end 56.332628 -243.152422)
		(width 0.14478)
		(layer "In4.Cu")
		(net "M_D_CPU1_SA_CB<5>")
	)
	(segment
		(start 53.428646 -242.885722)
		(end 53.59019 -243.047266)
		(width 0.14478)
		(layer "In4.Cu")
		(net "M_D_CPU1_SA_CB<5>")
	)
	(segment
		(start 50.810668 -242.57381)
		(end 50.972212 -242.412266)
		(width 0.14478)
		(layer "In4.Cu")
		(net "M_D_CPU1_SA_CB<5>")
	)
	(segment
		(start 75.950826 -249.002804)
		(end 76.151232 -249.002804)
		(width 0.0889)
		(layer "In4.Cu")
		(net "M_D_CPU1_SA_CB<5>")
	)
	(segment
		(start 50.259234 -243.046758)
		(end 50.420778 -243.208302)
		(width 0.14478)
		(layer "In4.Cu")
		(net "M_D_CPU1_SA_CB<5>")
	)
	(segment
		(start 57.093104 -243.172234)
		(end 56.722772 -243.542566)
		(width 0.14478)
		(layer "In4.Cu")
		(net "M_D_CPU1_SA_CB<5>")
	)
	(segment
		(start 56.332628 -243.152422)
		(end 56.70296 -242.78209)
		(width 0.14478)
		(layer "In4.Cu")
		(net "M_D_CPU1_SA_CB<5>")
	)
	(segment
		(start 92.260674 -248.825258)
		(end 92.35694 -248.799858)
		(width 0.0889)
		(layer "In4.Cu")
		(net "M_D_CPU1_SA_CB<5>")
	)
	(segment
		(start 49.546256 -243.208302)
		(end 49.7078 -243.046758)
		(width 0.14478)
		(layer "In4.Cu")
		(net "M_D_CPU1_SA_CB<5>")
	)
	(segment
		(start 52.715668 -242.810284)
		(end 52.877212 -242.64874)
		(width 0.14478)
		(layer "In4.Cu")
		(net "M_D_CPU1_SA_CB<5>")
	)
	(segment
		(start 45.727366 -242.582446)
		(end 45.88891 -242.74399)
		(width 0.14478)
		(layer "In4.Cu")
		(net "M_D_CPU1_SA_CB<5>")
	)
	(segment
		(start 49.869344 -242.554506)
		(end 50.09769 -242.554506)
		(width 0.14478)
		(layer "In4.Cu")
		(net "M_D_CPU1_SA_CB<5>")
	)
	(segment
		(start 37.220906 -242.810284)
		(end 44.624498 -242.810284)
		(width 0.14478)
		(layer "In4.Cu")
		(net "M_D_CPU1_SA_CB<5>")
	)
	(segment
		(start 51.523646 -242.810284)
		(end 52.715668 -242.810284)
		(width 0.14478)
		(layer "In4.Cu")
		(net "M_D_CPU1_SA_CB<5>")
	)
	(segment
		(start 48.766476 -242.412266)
		(end 48.994822 -242.412266)
		(width 0.14478)
		(layer "In4.Cu")
		(net "M_D_CPU1_SA_CB<5>")
	)
	(segment
		(start 44.624498 -242.810284)
		(end 44.786042 -242.971828)
		(width 0.14478)
		(layer "In4.Cu")
		(net "M_D_CPU1_SA_CB<5>")
	)
	(segment
		(start 48.994822 -242.412266)
		(end 49.156366 -242.57381)
		(width 0.14478)
		(layer "In4.Cu")
		(net "M_D_CPU1_SA_CB<5>")
	)
	(segment
		(start 76.480162 -248.904506)
		(end 76.48321 -248.907554)
		(width 0.0889)
		(layer "In4.Cu")
		(net "M_D_CPU1_SA_CB<5>")
	)
	(segment
		(start 74.774806 -249.002804)
		(end 75.950826 -249.002804)
		(width 0.14478)
		(layer "In4.Cu")
		(net "M_D_CPU1_SA_CB<5>")
	)
	(segment
		(start 46.601888 -242.414806)
		(end 46.830234 -242.414806)
		(width 0.14478)
		(layer "In4.Cu")
		(net "M_D_CPU1_SA_CB<5>")
	)
	(segment
		(start 50.420778 -243.208302)
		(end 50.649124 -243.208302)
		(width 0.14478)
		(layer "In4.Cu")
		(net "M_D_CPU1_SA_CB<5>")
	)
	(segment
		(start 53.98008 -242.885722)
		(end 53.98008 -242.57381)
		(width 0.14478)
		(layer "In4.Cu")
		(net "M_D_CPU1_SA_CB<5>")
	)
	(segment
		(start 54.141624 -242.412266)
		(end 54.36997 -242.412266)
		(width 0.14478)
		(layer "In4.Cu")
		(net "M_D_CPU1_SA_CB<5>")
	)
	(segment
		(start 48.604932 -242.64874)
		(end 48.604932 -242.57381)
		(width 0.14478)
		(layer "In4.Cu")
		(net "M_D_CPU1_SA_CB<5>")
	)
	(segment
		(start 46.830234 -242.414806)
		(end 46.991778 -242.57635)
		(width 0.14478)
		(layer "In4.Cu")
		(net "M_D_CPU1_SA_CB<5>")
	)
	(segment
		(start 89.504012 -248.857008)
		(end 89.512394 -248.861834)
		(width 0.0889)
		(layer "In4.Cu")
		(net "M_D_CPU1_SA_CB<5>")
	)
	(segment
		(start 91.749626 -248.861834)
		(end 91.758008 -248.857008)
		(width 0.0889)
		(layer "In4.Cu")
		(net "M_D_CPU1_SA_CB<5>")
	)
	(segment
		(start 74.463656 -248.691654)
		(end 74.774806 -249.002804)
		(width 0.14478)
		(layer "In4.Cu")
		(net "M_D_CPU1_SA_CB<5>")
	)
	(segment
		(start 46.991778 -242.64874)
		(end 47.153322 -242.810284)
		(width 0.14478)
		(layer "In4.Cu")
		(net "M_D_CPU1_SA_CB<5>")
	)
	(segment
		(start 53.038756 -242.412266)
		(end 53.267102 -242.412266)
		(width 0.14478)
		(layer "In4.Cu")
		(net "M_D_CPU1_SA_CB<5>")
	)
	(segment
		(start 51.362102 -242.57381)
		(end 51.362102 -242.64874)
		(width 0.14478)
		(layer "In4.Cu")
		(net "M_D_CPU1_SA_CB<5>")
	)
	(segment
		(start 64.102996 -248.691654)
		(end 74.463656 -248.691654)
		(width 0.14478)
		(layer "In4.Cu")
		(net "M_D_CPU1_SA_CB<5>")
	)
	(segment
		(start 44.786042 -243.044218)
		(end 44.947586 -243.205762)
		(width 0.14478)
		(layer "In4.Cu")
		(net "M_D_CPU1_SA_CB<5>")
	)
	(segment
		(start 85.74405 -248.857008)
		(end 85.752432 -248.861834)
		(width 0.0889)
		(layer "In4.Cu")
		(net "M_D_CPU1_SA_CB<5>")
	)
	(segment
		(start 76.24953 -248.904506)
		(end 76.480162 -248.904506)
		(width 0.0889)
		(layer "In4.Cu")
		(net "M_D_CPU1_SA_CB<5>")
	)
	(segment
		(start 59.926728 -244.515386)
		(end 64.102996 -248.691654)
		(width 0.14478)
		(layer "In4.Cu")
		(net "M_D_CPU1_SA_CB<5>")
	)
	(segment
		(start 50.810668 -243.046758)
		(end 50.810668 -242.57381)
		(width 0.14478)
		(layer "In4.Cu")
		(net "M_D_CPU1_SA_CB<5>")
	)
	(segment
		(start 78.59776 -248.856754)
		(end 78.603348 -248.853452)
		(width 0.0889)
		(layer "In4.Cu")
		(net "M_D_CPU1_SA_CB<5>")
	)
	(segment
		(start 51.200558 -242.412266)
		(end 51.362102 -242.57381)
		(width 0.14478)
		(layer "In4.Cu")
		(net "M_D_CPU1_SA_CB<5>")
	)
	(segment
		(start 87.989664 -248.861834)
		(end 87.998046 -248.857008)
		(width 0.0889)
		(layer "In4.Cu")
		(net "M_D_CPU1_SA_CB<5>")
	)
	(segment
		(start 45.337476 -242.74399)
		(end 45.49902 -242.582446)
		(width 0.14478)
		(layer "In4.Cu")
		(net "M_D_CPU1_SA_CB<5>")
	)
	(segment
		(start 48.604932 -242.57381)
		(end 48.766476 -242.412266)
		(width 0.14478)
		(layer "In4.Cu")
		(net "M_D_CPU1_SA_CB<5>")
	)
	(segment
		(start 45.88891 -242.74399)
		(end 45.88891 -243.044218)
		(width 0.14478)
		(layer "In4.Cu")
		(net "M_D_CPU1_SA_CB<5>")
	)
	(segment
		(start 52.877212 -242.57381)
		(end 53.038756 -242.412266)
		(width 0.14478)
		(layer "In4.Cu")
		(net "M_D_CPU1_SA_CB<5>")
	)
	(segment
		(start 36.795964 -242.385342)
		(end 37.220906 -242.810284)
		(width 0.14478)
		(layer "In4.Cu")
		(net "M_D_CPU1_SA_CB<5>")
	)
	(segment
		(start 56.70296 -242.78209)
		(end 56.93156 -242.78209)
		(width 0.14478)
		(layer "In4.Cu")
		(net "M_D_CPU1_SA_CB<5>")
	)
	(segment
		(start 56.722772 -243.771166)
		(end 57.466992 -244.515386)
		(width 0.14478)
		(layer "In4.Cu")
		(net "M_D_CPU1_SA_CB<5>")
	)
	(segment
		(start 46.2788 -243.205762)
		(end 46.440344 -243.044218)
		(width 0.14478)
		(layer "In4.Cu")
		(net "M_D_CPU1_SA_CB<5>")
	)
	(segment
		(start 92.35694 -248.799858)
		(end 92.511118 -248.534428)
		(width 0.0889)
		(layer "In4.Cu")
		(net "M_D_CPU1_SA_CB<5>")
	)
	(segment
		(start 52.877212 -242.64874)
		(end 52.877212 -242.57381)
		(width 0.14478)
		(layer "In4.Cu")
		(net "M_D_CPU1_SA_CB<5>")
	)
	(segment
		(start 51.362102 -242.64874)
		(end 51.523646 -242.810284)
		(width 0.14478)
		(layer "In4.Cu")
		(net "M_D_CPU1_SA_CB<5>")
	)
	(segment
		(start 49.156366 -242.57381)
		(end 49.156366 -243.046758)
		(width 0.14478)
		(layer "In4.Cu")
		(net "M_D_CPU1_SA_CB<5>")
	)
	(segment
		(start 49.7078 -243.046758)
		(end 49.7078 -242.71605)
		(width 0.14478)
		(layer "In4.Cu")
		(net "M_D_CPU1_SA_CB<5>")
	)
	(segment
		(start 57.093104 -242.943634)
		(end 57.093104 -243.172234)
		(width 0.14478)
		(layer "In4.Cu")
		(net "M_D_CPU1_SA_CB<5>")
	)
	(segment
		(start 55.76189 -242.810284)
		(end 56.104028 -243.152422)
		(width 0.14478)
		(layer "In4.Cu")
		(net "M_D_CPU1_SA_CB<5>")
	)
	(segment
		(start 45.175932 -243.205762)
		(end 45.337476 -243.044218)
		(width 0.14478)
		(layer "In4.Cu")
		(net "M_D_CPU1_SA_CB<5>")
	)
	(segment
		(start 50.09769 -242.554506)
		(end 50.259234 -242.71605)
		(width 0.14478)
		(layer "In4.Cu")
		(net "M_D_CPU1_SA_CB<5>")
	)
	(segment
		(start 45.337476 -243.044218)
		(end 45.337476 -242.74399)
		(width 0.14478)
		(layer "In4.Cu")
		(net "M_D_CPU1_SA_CB<5>")
	)
	(segment
		(start 46.440344 -242.57635)
		(end 46.601888 -242.414806)
		(width 0.14478)
		(layer "In4.Cu")
		(net "M_D_CPU1_SA_CB<5>")
	)
	(segment
		(start 46.991778 -242.57635)
		(end 46.991778 -242.64874)
		(width 0.14478)
		(layer "In4.Cu")
		(net "M_D_CPU1_SA_CB<5>")
	)
	(segment
		(start 53.98008 -242.57381)
		(end 54.141624 -242.412266)
		(width 0.14478)
		(layer "In4.Cu")
		(net "M_D_CPU1_SA_CB<5>")
	)
	(segment
		(start 45.49902 -242.582446)
		(end 45.727366 -242.582446)
		(width 0.14478)
		(layer "In4.Cu")
		(net "M_D_CPU1_SA_CB<5>")
	)
	(segment
		(start 49.31791 -243.208302)
		(end 49.546256 -243.208302)
		(width 0.14478)
		(layer "In4.Cu")
		(net "M_D_CPU1_SA_CB<5>")
	)
	(segment
		(start 84.803996 -248.857008)
		(end 84.812378 -248.861834)
		(width 0.0889)
		(layer "In4.Cu")
		(net "M_D_CPU1_SA_CB<5>")
	)
	(segment
		(start 54.36997 -242.412266)
		(end 54.531514 -242.57381)
		(width 0.14478)
		(layer "In4.Cu")
		(net "M_D_CPU1_SA_CB<5>")
	)
	(segment
		(start 80.093566 -248.850912)
		(end 80.10398 -248.857008)
		(width 0.0889)
		(layer "In4.Cu")
		(net "M_D_CPU1_SA_CB<5>")
	)
	(segment
		(start 44.786042 -242.971828)
		(end 44.786042 -243.044218)
		(width 0.14478)
		(layer "In4.Cu")
		(net "M_D_CPU1_SA_CB<5>")
	)
	(segment
		(start 57.466992 -244.515386)
		(end 59.926728 -244.515386)
		(width 0.14478)
		(layer "In4.Cu")
		(net "M_D_CPU1_SA_CB<5>")
	)
	(segment
		(start 53.428646 -242.57381)
		(end 53.428646 -242.885722)
		(width 0.14478)
		(layer "In4.Cu")
		(net "M_D_CPU1_SA_CB<5>")
	)
	(segment
		(start 54.531514 -242.64874)
		(end 54.693058 -242.810284)
		(width 0.14478)
		(layer "In4.Cu")
		(net "M_D_CPU1_SA_CB<5>")
	)
	(segment
		(start 53.267102 -242.412266)
		(end 53.428646 -242.57381)
		(width 0.14478)
		(layer "In4.Cu")
		(net "M_D_CPU1_SA_CB<5>")
	)
	(segment
		(start 46.050454 -243.205762)
		(end 46.2788 -243.205762)
		(width 0.14478)
		(layer "In4.Cu")
		(net "M_D_CPU1_SA_CB<5>")
	)
	(segment
		(start 76.48321 -248.907554)
		(end 77.469746 -248.907554)
		(width 0.0889)
		(layer "In4.Cu")
		(net "M_D_CPU1_SA_CB<5>")
	)
	(segment
		(start 53.818536 -243.047266)
		(end 53.98008 -242.885722)
		(width 0.14478)
		(layer "In4.Cu")
		(net "M_D_CPU1_SA_CB<5>")
	)
	(segment
		(start 88.929718 -248.861834)
		(end 88.9381 -248.857008)
		(width 0.0889)
		(layer "In4.Cu")
		(net "M_D_CPU1_SA_CB<5>")
	)
	(segment
		(start 77.657198 -248.857008)
		(end 77.67193 -248.848372)
		(width 0.0889)
		(layer "In4.Cu")
		(net "M_D_CPU1_SA_CB<5>")
	)
	(segment
		(start 80.46974 -248.861834)
		(end 80.478122 -248.857008)
		(width 0.0889)
		(layer "In4.Cu")
		(net "M_D_CPU1_SA_CB<5>")
	)
	(arc
		(start 91.758008 -248.857008)
		(mid 92.005604 -248.78183)
		(end 92.260674 -248.825258)
		(width 0.0889)
		(layer "In4.Cu")
		(net "M_D_CPU1_SA_CB<5>")
	)
	(arc
		(start 85.752432 -248.861834)
		(mid 85.93594 -248.907328)
		(end 86.118192 -248.857008)
		(width 0.0889)
		(layer "In4.Cu")
		(net "M_D_CPU1_SA_CB<5>")
	)
	(arc
		(start 77.47 -248.9073)
		(mid 77.566932 -248.894549)
		(end 77.657198 -248.857008)
		(width 0.0889)
		(layer "In4.Cu")
		(net "M_D_CPU1_SA_CB<5>")
	)
	(arc
		(start 89.878154 -248.857008)
		(mid 90.16111 -248.780831)
		(end 90.444066 -248.857008)
		(width 0.0889)
		(layer "In4.Cu")
		(net "M_D_CPU1_SA_CB<5>")
	)
	(arc
		(start 79.537814 -248.857008)
		(mid 79.814881 -248.780737)
		(end 80.093566 -248.850912)
		(width 0.0889)
		(layer "In4.Cu")
		(net "M_D_CPU1_SA_CB<5>")
	)
	(arc
		(start 85.178138 -248.857008)
		(mid 85.461094 -248.780831)
		(end 85.74405 -248.857008)
		(width 0.0889)
		(layer "In4.Cu")
		(net "M_D_CPU1_SA_CB<5>")
	)
	(arc
		(start 81.418176 -248.857008)
		(mid 81.701132 -248.780831)
		(end 81.984088 -248.857008)
		(width 0.0889)
		(layer "In4.Cu")
		(net "M_D_CPU1_SA_CB<5>")
	)
	(arc
		(start 86.118192 -248.857008)
		(mid 86.401148 -248.780831)
		(end 86.684104 -248.857008)
		(width 0.0889)
		(layer "In4.Cu")
		(net "M_D_CPU1_SA_CB<5>")
	)
	(arc
		(start 88.9381 -248.857008)
		(mid 89.221056 -248.780831)
		(end 89.504012 -248.857008)
		(width 0.0889)
		(layer "In4.Cu")
		(net "M_D_CPU1_SA_CB<5>")
	)
	(arc
		(start 79.171546 -248.861834)
		(mid 79.355308 -248.90745)
		(end 79.537814 -248.857008)
		(width 0.0889)
		(layer "In4.Cu")
		(net "M_D_CPU1_SA_CB<5>")
	)
	(arc
		(start 80.10398 -248.857008)
		(mid 80.286231 -248.907358)
		(end 80.46974 -248.861834)
		(width 0.0889)
		(layer "In4.Cu")
		(net "M_D_CPU1_SA_CB<5>")
	)
	(arc
		(start 89.512394 -248.861834)
		(mid 89.695902 -248.907328)
		(end 89.878154 -248.857008)
		(width 0.0889)
		(layer "In4.Cu")
		(net "M_D_CPU1_SA_CB<5>")
	)
	(arc
		(start 87.623904 -248.857008)
		(mid 87.806155 -248.907358)
		(end 87.989664 -248.861834)
		(width 0.0889)
		(layer "In4.Cu")
		(net "M_D_CPU1_SA_CB<5>")
	)
	(arc
		(start 81.984088 -248.857008)
		(mid 82.171032 -248.907263)
		(end 82.357976 -248.857008)
		(width 0.0889)
		(layer "In4.Cu")
		(net "M_D_CPU1_SA_CB<5>")
	)
	(arc
		(start 91.383866 -248.857008)
		(mid 91.566117 -248.907358)
		(end 91.749626 -248.861834)
		(width 0.0889)
		(layer "In4.Cu")
		(net "M_D_CPU1_SA_CB<5>")
	)
	(arc
		(start 87.057992 -248.857008)
		(mid 87.340948 -248.780831)
		(end 87.623904 -248.857008)
		(width 0.0889)
		(layer "In4.Cu")
		(net "M_D_CPU1_SA_CB<5>")
	)
	(arc
		(start 81.052416 -248.861834)
		(mid 81.235924 -248.907328)
		(end 81.418176 -248.857008)
		(width 0.0889)
		(layer "In4.Cu")
		(net "M_D_CPU1_SA_CB<5>")
	)
	(arc
		(start 86.684104 -248.857008)
		(mid 86.871048 -248.907263)
		(end 87.057992 -248.857008)
		(width 0.0889)
		(layer "In4.Cu")
		(net "M_D_CPU1_SA_CB<5>")
	)
	(arc
		(start 80.478122 -248.857008)
		(mid 80.761078 -248.780831)
		(end 81.044034 -248.857008)
		(width 0.0889)
		(layer "In4.Cu")
		(net "M_D_CPU1_SA_CB<5>")
	)
	(arc
		(start 84.238084 -248.857008)
		(mid 84.52104 -248.780831)
		(end 84.803996 -248.857008)
		(width 0.0889)
		(layer "In4.Cu")
		(net "M_D_CPU1_SA_CB<5>")
	)
	(arc
		(start 83.863942 -248.857008)
		(mid 84.046193 -248.907358)
		(end 84.229702 -248.861834)
		(width 0.0889)
		(layer "In4.Cu")
		(net "M_D_CPU1_SA_CB<5>")
	)
	(arc
		(start 90.817954 -248.857008)
		(mid 91.10091 -248.780831)
		(end 91.383866 -248.857008)
		(width 0.0889)
		(layer "In4.Cu")
		(net "M_D_CPU1_SA_CB<5>")
	)
	(arc
		(start 90.444066 -248.857008)
		(mid 90.63101 -248.907263)
		(end 90.817954 -248.857008)
		(width 0.0889)
		(layer "In4.Cu")
		(net "M_D_CPU1_SA_CB<5>")
	)
	(arc
		(start 87.998046 -248.857008)
		(mid 88.281002 -248.780831)
		(end 88.563958 -248.857008)
		(width 0.0889)
		(layer "In4.Cu")
		(net "M_D_CPU1_SA_CB<5>")
	)
	(arc
		(start 78.223618 -248.857008)
		(mid 78.400246 -248.907241)
		(end 78.579472 -248.867168)
		(width 0.0889)
		(layer "In4.Cu")
		(net "M_D_CPU1_SA_CB<5>")
	)
	(arc
		(start 82.357976 -248.857008)
		(mid 82.640932 -248.780831)
		(end 82.923888 -248.857008)
		(width 0.0889)
		(layer "In4.Cu")
		(net "M_D_CPU1_SA_CB<5>")
	)
	(arc
		(start 82.923888 -248.857008)
		(mid 83.106139 -248.907358)
		(end 83.289648 -248.861834)
		(width 0.0889)
		(layer "In4.Cu")
		(net "M_D_CPU1_SA_CB<5>")
	)
	(arc
		(start 88.563958 -248.857008)
		(mid 88.746209 -248.907358)
		(end 88.929718 -248.861834)
		(width 0.0889)
		(layer "In4.Cu")
		(net "M_D_CPU1_SA_CB<5>")
	)
	(arc
		(start 83.29803 -248.857008)
		(mid 83.580986 -248.780831)
		(end 83.863942 -248.857008)
		(width 0.0889)
		(layer "In4.Cu")
		(net "M_D_CPU1_SA_CB<5>")
	)
	(arc
		(start 77.67193 -248.848372)
		(mid 77.948913 -248.780568)
		(end 78.223618 -248.857008)
		(width 0.0889)
		(layer "In4.Cu")
		(net "M_D_CPU1_SA_CB<5>")
	)
	(arc
		(start 78.603348 -248.853452)
		(mid 78.883737 -248.780783)
		(end 79.163164 -248.857008)
		(width 0.0889)
		(layer "In4.Cu")
		(net "M_D_CPU1_SA_CB<5>")
	)
	(arc
		(start 84.812378 -248.861834)
		(mid 84.995886 -248.907328)
		(end 85.178138 -248.857008)
		(width 0.0889)
		(layer "In4.Cu")
		(net "M_D_CPU1_SA_CB<5>")
	)
	(segment
		(start 91.568016 -247.99036)
		(end 91.10091 -247.724422)
		(width 0.10668)
		(layer "F.Cu")
		(net "M_D_CPU1_SA_CB<4>")
	)
	(segment
		(start 75.955906 -248.083324)
		(end 76.345288 -248.083324)
		(width 0.0889)
		(layer "In4.Cu")
		(net "M_D_CPU1_SA_CB<4>")
	)
	(segment
		(start 90.946986 -247.989852)
		(end 91.10091 -247.724422)
		(width 0.0889)
		(layer "In4.Cu")
		(net "M_D_CPU1_SA_CB<4>")
	)
	(segment
		(start 50.247042 -240.27003)
		(end 50.614326 -240.27003)
		(width 0.14478)
		(layer "In4.Cu")
		(net "M_D_CPU1_SA_CB<4>")
	)
	(segment
		(start 45.363892 -241.326416)
		(end 45.363892 -240.669064)
		(width 0.14478)
		(layer "In4.Cu")
		(net "M_D_CPU1_SA_CB<4>")
	)
	(segment
		(start 74.867516 -247.782334)
		(end 75.168506 -248.083324)
		(width 0.14478)
		(layer "In4.Cu")
		(net "M_D_CPU1_SA_CB<4>")
	)
	(segment
		(start 53.075586 -240.27003)
		(end 53.915818 -241.110262)
		(width 0.14478)
		(layer "In4.Cu")
		(net "M_D_CPU1_SA_CB<4>")
	)
	(segment
		(start 36.795964 -240.68532)
		(end 37.220906 -241.110262)
		(width 0.14478)
		(layer "In4.Cu")
		(net "M_D_CPU1_SA_CB<4>")
	)
	(segment
		(start 45.771816 -240.473484)
		(end 46.418246 -241.119914)
		(width 0.14478)
		(layer "In4.Cu")
		(net "M_D_CPU1_SA_CB<4>")
	)
	(segment
		(start 53.915818 -241.110262)
		(end 56.94045 -241.110262)
		(width 0.14478)
		(layer "In4.Cu")
		(net "M_D_CPU1_SA_CB<4>")
	)
	(segment
		(start 45.200824 -241.489484)
		(end 45.363892 -241.326416)
		(width 0.14478)
		(layer "In4.Cu")
		(net "M_D_CPU1_SA_CB<4>")
	)
	(segment
		(start 50.93081 -241.362484)
		(end 51.161188 -241.362484)
		(width 0.14478)
		(layer "In4.Cu")
		(net "M_D_CPU1_SA_CB<4>")
	)
	(segment
		(start 37.931598 -240.403126)
		(end 38.094666 -240.566194)
		(width 0.14478)
		(layer "In4.Cu")
		(net "M_D_CPU1_SA_CB<4>")
	)
	(segment
		(start 44.970446 -241.489484)
		(end 45.200824 -241.489484)
		(width 0.14478)
		(layer "In4.Cu")
		(net "M_D_CPU1_SA_CB<4>")
	)
	(segment
		(start 51.324256 -241.199416)
		(end 51.324256 -240.423446)
		(width 0.14478)
		(layer "In4.Cu")
		(net "M_D_CPU1_SA_CB<4>")
	)
	(segment
		(start 56.94045 -241.110262)
		(end 58.650124 -242.819936)
		(width 0.14478)
		(layer "In4.Cu")
		(net "M_D_CPU1_SA_CB<4>")
	)
	(segment
		(start 50.614326 -240.27003)
		(end 50.767742 -240.423446)
		(width 0.14478)
		(layer "In4.Cu")
		(net "M_D_CPU1_SA_CB<4>")
	)
	(segment
		(start 45.363892 -240.669064)
		(end 45.559472 -240.473484)
		(width 0.14478)
		(layer "In4.Cu")
		(net "M_D_CPU1_SA_CB<4>")
	)
	(segment
		(start 64.576452 -247.782334)
		(end 74.867516 -247.782334)
		(width 0.14478)
		(layer "In4.Cu")
		(net "M_D_CPU1_SA_CB<4>")
	)
	(segment
		(start 43.49623 -241.476784)
		(end 43.659298 -241.313716)
		(width 0.14478)
		(layer "In4.Cu")
		(net "M_D_CPU1_SA_CB<4>")
	)
	(segment
		(start 43.102784 -240.423446)
		(end 43.102784 -241.313716)
		(width 0.14478)
		(layer "In4.Cu")
		(net "M_D_CPU1_SA_CB<4>")
	)
	(segment
		(start 88.094058 -248.047002)
		(end 88.10244 -248.051828)
		(width 0.0889)
		(layer "In4.Cu")
		(net "M_D_CPU1_SA_CB<4>")
	)
	(segment
		(start 37.538152 -240.566194)
		(end 37.70122 -240.403126)
		(width 0.14478)
		(layer "In4.Cu")
		(net "M_D_CPU1_SA_CB<4>")
	)
	(segment
		(start 42.939716 -240.260378)
		(end 43.102784 -240.423446)
		(width 0.14478)
		(layer "In4.Cu")
		(net "M_D_CPU1_SA_CB<4>")
	)
	(segment
		(start 42.733214 -240.260378)
		(end 42.939716 -240.260378)
		(width 0.14478)
		(layer "In4.Cu")
		(net "M_D_CPU1_SA_CB<4>")
	)
	(segment
		(start 51.324256 -240.423446)
		(end 51.477672 -240.27003)
		(width 0.14478)
		(layer "In4.Cu")
		(net "M_D_CPU1_SA_CB<4>")
	)
	(segment
		(start 44.807378 -240.423446)
		(end 44.807378 -241.326416)
		(width 0.14478)
		(layer "In4.Cu")
		(net "M_D_CPU1_SA_CB<4>")
	)
	(segment
		(start 86.57971 -248.051828)
		(end 86.588092 -248.047002)
		(width 0.0889)
		(layer "In4.Cu")
		(net "M_D_CPU1_SA_CB<4>")
	)
	(segment
		(start 82.453988 -248.047002)
		(end 82.46237 -248.051828)
		(width 0.0889)
		(layer "In4.Cu")
		(net "M_D_CPU1_SA_CB<4>")
	)
	(segment
		(start 77.79639 -248.353326)
		(end 78.013052 -248.13641)
		(width 0.0889)
		(layer "In4.Cu")
		(net "M_D_CPU1_SA_CB<4>")
	)
	(segment
		(start 85.639656 -248.051828)
		(end 85.648038 -248.047002)
		(width 0.0889)
		(layer "In4.Cu")
		(net "M_D_CPU1_SA_CB<4>")
	)
	(segment
		(start 45.559472 -240.473484)
		(end 45.771816 -240.473484)
		(width 0.14478)
		(layer "In4.Cu")
		(net "M_D_CPU1_SA_CB<4>")
	)
	(segment
		(start 37.538152 -240.947194)
		(end 37.538152 -240.566194)
		(width 0.14478)
		(layer "In4.Cu")
		(net "M_D_CPU1_SA_CB<4>")
	)
	(segment
		(start 81.879694 -248.051828)
		(end 81.888076 -248.047002)
		(width 0.0889)
		(layer "In4.Cu")
		(net "M_D_CPU1_SA_CB<4>")
	)
	(segment
		(start 38.267386 -241.119914)
		(end 41.873678 -241.119914)
		(width 0.14478)
		(layer "In4.Cu")
		(net "M_D_CPU1_SA_CB<4>")
	)
	(segment
		(start 38.094666 -240.566194)
		(end 38.094666 -240.947194)
		(width 0.14478)
		(layer "In4.Cu")
		(net "M_D_CPU1_SA_CB<4>")
	)
	(segment
		(start 90.850974 -248.015252)
		(end 90.946986 -247.989852)
		(width 0.0889)
		(layer "In4.Cu")
		(net "M_D_CPU1_SA_CB<4>")
	)
	(segment
		(start 75.168506 -248.083324)
		(end 75.955906 -248.083324)
		(width 0.14478)
		(layer "In4.Cu")
		(net "M_D_CPU1_SA_CB<4>")
	)
	(segment
		(start 58.650124 -242.819936)
		(end 59.614054 -242.819936)
		(width 0.14478)
		(layer "In4.Cu")
		(net "M_D_CPU1_SA_CB<4>")
	)
	(segment
		(start 51.477672 -240.27003)
		(end 53.075586 -240.27003)
		(width 0.14478)
		(layer "In4.Cu")
		(net "M_D_CPU1_SA_CB<4>")
	)
	(segment
		(start 90.339672 -248.051828)
		(end 90.348054 -248.047002)
		(width 0.0889)
		(layer "In4.Cu")
		(net "M_D_CPU1_SA_CB<4>")
	)
	(segment
		(start 37.70122 -240.403126)
		(end 37.931598 -240.403126)
		(width 0.14478)
		(layer "In4.Cu")
		(net "M_D_CPU1_SA_CB<4>")
	)
	(segment
		(start 76.61529 -248.353326)
		(end 77.79639 -248.353326)
		(width 0.0889)
		(layer "In4.Cu")
		(net "M_D_CPU1_SA_CB<4>")
	)
	(segment
		(start 38.094666 -240.947194)
		(end 38.267386 -241.119914)
		(width 0.14478)
		(layer "In4.Cu")
		(net "M_D_CPU1_SA_CB<4>")
	)
	(segment
		(start 76.345288 -248.083324)
		(end 76.61529 -248.353326)
		(width 0.0889)
		(layer "In4.Cu")
		(net "M_D_CPU1_SA_CB<4>")
	)
	(segment
		(start 44.653962 -240.27003)
		(end 44.807378 -240.423446)
		(width 0.14478)
		(layer "In4.Cu")
		(net "M_D_CPU1_SA_CB<4>")
	)
	(segment
		(start 79.051658 -248.057924)
		(end 79.070454 -248.047002)
		(width 0.0889)
		(layer "In4.Cu")
		(net "M_D_CPU1_SA_CB<4>")
	)
	(segment
		(start 51.161188 -241.362484)
		(end 51.324256 -241.199416)
		(width 0.14478)
		(layer "In4.Cu")
		(net "M_D_CPU1_SA_CB<4>")
	)
	(segment
		(start 44.807378 -241.326416)
		(end 44.970446 -241.489484)
		(width 0.14478)
		(layer "In4.Cu")
		(net "M_D_CPU1_SA_CB<4>")
	)
	(segment
		(start 79.634842 -248.046748)
		(end 79.654908 -248.058178)
		(width 0.0889)
		(layer "In4.Cu")
		(net "M_D_CPU1_SA_CB<4>")
	)
	(segment
		(start 43.812714 -240.27003)
		(end 44.653962 -240.27003)
		(width 0.14478)
		(layer "In4.Cu")
		(net "M_D_CPU1_SA_CB<4>")
	)
	(segment
		(start 87.154004 -248.047002)
		(end 87.162386 -248.051828)
		(width 0.0889)
		(layer "In4.Cu")
		(net "M_D_CPU1_SA_CB<4>")
	)
	(segment
		(start 43.265852 -241.476784)
		(end 43.49623 -241.476784)
		(width 0.14478)
		(layer "In4.Cu")
		(net "M_D_CPU1_SA_CB<4>")
	)
	(segment
		(start 43.659298 -241.313716)
		(end 43.659298 -240.423446)
		(width 0.14478)
		(layer "In4.Cu")
		(net "M_D_CPU1_SA_CB<4>")
	)
	(segment
		(start 83.394042 -248.047002)
		(end 83.402424 -248.051828)
		(width 0.0889)
		(layer "In4.Cu")
		(net "M_D_CPU1_SA_CB<4>")
	)
	(segment
		(start 46.418246 -241.119914)
		(end 49.397158 -241.119914)
		(width 0.14478)
		(layer "In4.Cu")
		(net "M_D_CPU1_SA_CB<4>")
	)
	(segment
		(start 49.397158 -241.119914)
		(end 50.247042 -240.27003)
		(width 0.14478)
		(layer "In4.Cu")
		(net "M_D_CPU1_SA_CB<4>")
	)
	(segment
		(start 37.375084 -241.110262)
		(end 37.538152 -240.947194)
		(width 0.14478)
		(layer "In4.Cu")
		(net "M_D_CPU1_SA_CB<4>")
	)
	(segment
		(start 78.129638 -248.046748)
		(end 78.161388 -248.02846)
		(width 0.0889)
		(layer "In4.Cu")
		(net "M_D_CPU1_SA_CB<4>")
	)
	(segment
		(start 43.102784 -241.313716)
		(end 43.265852 -241.476784)
		(width 0.14478)
		(layer "In4.Cu")
		(net "M_D_CPU1_SA_CB<4>")
	)
	(segment
		(start 79.613252 -248.034302)
		(end 79.634842 -248.046748)
		(width 0.0889)
		(layer "In4.Cu")
		(net "M_D_CPU1_SA_CB<4>")
	)
	(segment
		(start 37.220906 -241.110262)
		(end 37.375084 -241.110262)
		(width 0.14478)
		(layer "In4.Cu")
		(net "M_D_CPU1_SA_CB<4>")
	)
	(segment
		(start 50.767742 -241.199416)
		(end 50.93081 -241.362484)
		(width 0.14478)
		(layer "In4.Cu")
		(net "M_D_CPU1_SA_CB<4>")
	)
	(segment
		(start 43.659298 -240.423446)
		(end 43.812714 -240.27003)
		(width 0.14478)
		(layer "In4.Cu")
		(net "M_D_CPU1_SA_CB<4>")
	)
	(segment
		(start 59.614054 -242.819936)
		(end 64.576452 -247.782334)
		(width 0.14478)
		(layer "In4.Cu")
		(net "M_D_CPU1_SA_CB<4>")
	)
	(segment
		(start 41.873678 -241.119914)
		(end 42.733214 -240.260378)
		(width 0.14478)
		(layer "In4.Cu")
		(net "M_D_CPU1_SA_CB<4>")
	)
	(segment
		(start 50.767742 -240.423446)
		(end 50.767742 -241.199416)
		(width 0.14478)
		(layer "In4.Cu")
		(net "M_D_CPU1_SA_CB<4>")
	)
	(arc
		(start 78.013052 -248.13641)
		(mid 78.068401 -248.087751)
		(end 78.129638 -248.046748)
		(width 0.0889)
		(layer "In4.Cu")
		(net "M_D_CPU1_SA_CB<4>")
	)
	(arc
		(start 84.334096 -248.047002)
		(mid 84.52104 -248.097257)
		(end 84.707984 -248.047002)
		(width 0.0889)
		(layer "In4.Cu")
		(net "M_D_CPU1_SA_CB<4>")
	)
	(arc
		(start 84.707984 -248.047002)
		(mid 84.99094 -247.970825)
		(end 85.273896 -248.047002)
		(width 0.0889)
		(layer "In4.Cu")
		(net "M_D_CPU1_SA_CB<4>")
	)
	(arc
		(start 88.4682 -248.047002)
		(mid 88.751156 -247.970825)
		(end 89.034112 -248.047002)
		(width 0.0889)
		(layer "In4.Cu")
		(net "M_D_CPU1_SA_CB<4>")
	)
	(arc
		(start 89.034112 -248.047002)
		(mid 89.221056 -248.097257)
		(end 89.408 -248.047002)
		(width 0.0889)
		(layer "In4.Cu")
		(net "M_D_CPU1_SA_CB<4>")
	)
	(arc
		(start 81.513934 -248.047002)
		(mid 81.696185 -248.097352)
		(end 81.879694 -248.051828)
		(width 0.0889)
		(layer "In4.Cu")
		(net "M_D_CPU1_SA_CB<4>")
	)
	(arc
		(start 80.574134 -248.047002)
		(mid 80.761078 -248.097257)
		(end 80.948022 -248.047002)
		(width 0.0889)
		(layer "In4.Cu")
		(net "M_D_CPU1_SA_CB<4>")
	)
	(arc
		(start 87.162386 -248.051828)
		(mid 87.345894 -248.097322)
		(end 87.528146 -248.047002)
		(width 0.0889)
		(layer "In4.Cu")
		(net "M_D_CPU1_SA_CB<4>")
	)
	(arc
		(start 85.648038 -248.047002)
		(mid 85.930994 -247.970825)
		(end 86.21395 -248.047002)
		(width 0.0889)
		(layer "In4.Cu")
		(net "M_D_CPU1_SA_CB<4>")
	)
	(arc
		(start 78.161388 -248.02846)
		(mid 78.430673 -247.970548)
		(end 78.695296 -248.047002)
		(width 0.0889)
		(layer "In4.Cu")
		(net "M_D_CPU1_SA_CB<4>")
	)
	(arc
		(start 86.21395 -248.047002)
		(mid 86.396201 -248.097352)
		(end 86.57971 -248.051828)
		(width 0.0889)
		(layer "In4.Cu")
		(net "M_D_CPU1_SA_CB<4>")
	)
	(arc
		(start 88.10244 -248.051828)
		(mid 88.285948 -248.097322)
		(end 88.4682 -248.047002)
		(width 0.0889)
		(layer "In4.Cu")
		(net "M_D_CPU1_SA_CB<4>")
	)
	(arc
		(start 82.82813 -248.047002)
		(mid 83.111086 -247.970825)
		(end 83.394042 -248.047002)
		(width 0.0889)
		(layer "In4.Cu")
		(net "M_D_CPU1_SA_CB<4>")
	)
	(arc
		(start 79.070454 -248.047002)
		(mid 79.340223 -247.970979)
		(end 79.613252 -248.034302)
		(width 0.0889)
		(layer "In4.Cu")
		(net "M_D_CPU1_SA_CB<4>")
	)
	(arc
		(start 83.402424 -248.051828)
		(mid 83.585932 -248.097322)
		(end 83.768184 -248.047002)
		(width 0.0889)
		(layer "In4.Cu")
		(net "M_D_CPU1_SA_CB<4>")
	)
	(arc
		(start 83.768184 -248.047002)
		(mid 84.05114 -247.970825)
		(end 84.334096 -248.047002)
		(width 0.0889)
		(layer "In4.Cu")
		(net "M_D_CPU1_SA_CB<4>")
	)
	(arc
		(start 80.948022 -248.047002)
		(mid 81.230978 -247.970825)
		(end 81.513934 -248.047002)
		(width 0.0889)
		(layer "In4.Cu")
		(net "M_D_CPU1_SA_CB<4>")
	)
	(arc
		(start 87.528146 -248.047002)
		(mid 87.811102 -247.970825)
		(end 88.094058 -248.047002)
		(width 0.0889)
		(layer "In4.Cu")
		(net "M_D_CPU1_SA_CB<4>")
	)
	(arc
		(start 78.695296 -248.047002)
		(mid 78.872087 -248.097721)
		(end 79.051658 -248.057924)
		(width 0.0889)
		(layer "In4.Cu")
		(net "M_D_CPU1_SA_CB<4>")
	)
	(arc
		(start 86.588092 -248.047002)
		(mid 86.871048 -247.970825)
		(end 87.154004 -248.047002)
		(width 0.0889)
		(layer "In4.Cu")
		(net "M_D_CPU1_SA_CB<4>")
	)
	(arc
		(start 85.273896 -248.047002)
		(mid 85.456147 -248.097352)
		(end 85.639656 -248.051828)
		(width 0.0889)
		(layer "In4.Cu")
		(net "M_D_CPU1_SA_CB<4>")
	)
	(arc
		(start 81.888076 -248.047002)
		(mid 82.171032 -247.970825)
		(end 82.453988 -248.047002)
		(width 0.0889)
		(layer "In4.Cu")
		(net "M_D_CPU1_SA_CB<4>")
	)
	(arc
		(start 80.008222 -248.047002)
		(mid 80.291178 -247.970825)
		(end 80.574134 -248.047002)
		(width 0.0889)
		(layer "In4.Cu")
		(net "M_D_CPU1_SA_CB<4>")
	)
	(arc
		(start 89.973912 -248.047002)
		(mid 90.156163 -248.097352)
		(end 90.339672 -248.051828)
		(width 0.0889)
		(layer "In4.Cu")
		(net "M_D_CPU1_SA_CB<4>")
	)
	(arc
		(start 79.654908 -248.058178)
		(mid 79.832986 -248.097162)
		(end 80.008222 -248.047002)
		(width 0.0889)
		(layer "In4.Cu")
		(net "M_D_CPU1_SA_CB<4>")
	)
	(arc
		(start 82.46237 -248.051828)
		(mid 82.645878 -248.097322)
		(end 82.82813 -248.047002)
		(width 0.0889)
		(layer "In4.Cu")
		(net "M_D_CPU1_SA_CB<4>")
	)
	(arc
		(start 89.408 -248.047002)
		(mid 89.690956 -247.970825)
		(end 89.973912 -248.047002)
		(width 0.0889)
		(layer "In4.Cu")
		(net "M_D_CPU1_SA_CB<4>")
	)
	(arc
		(start 90.348054 -248.047002)
		(mid 90.595767 -247.971782)
		(end 90.850974 -248.015252)
		(width 0.0889)
		(layer "In4.Cu")
		(net "M_D_CPU1_SA_CB<4>")
	)
	(segment
		(start 92.507816 -246.370348)
		(end 92.040964 -246.10441)
		(width 0.10668)
		(layer "F.Cu")
		(net "M_D_CPU1_SA_CB<3>")
	)
	(segment
		(start 59.420506 -238.730536)
		(end 59.58205 -238.89208)
		(width 0.14478)
		(layer "In4.Cu")
		(net "M_D_CPU1_SA_CB<3>")
	)
	(segment
		(start 92.17279 -245.755668)
		(end 92.195142 -245.83898)
		(width 0.0889)
		(layer "In4.Cu")
		(net "M_D_CPU1_SA_CB<3>")
	)
	(segment
		(start 59.58205 -238.89208)
		(end 59.81065 -238.89208)
		(width 0.14478)
		(layer "In4.Cu")
		(net "M_D_CPU1_SA_CB<3>")
	)
	(segment
		(start 78.693518 -245.782084)
		(end 78.709774 -245.772686)
		(width 0.0889)
		(layer "In4.Cu")
		(net "M_D_CPU1_SA_CB<3>")
	)
	(segment
		(start 53.246782 -236.850682)
		(end 54.106572 -237.710472)
		(width 0.14478)
		(layer "In4.Cu")
		(net "M_D_CPU1_SA_CB<3>")
	)
	(segment
		(start 79.067406 -245.78183)
		(end 79.07782 -245.787926)
		(width 0.0889)
		(layer "In4.Cu")
		(net "M_D_CPU1_SA_CB<3>")
	)
	(segment
		(start 46.407832 -237.700566)
		(end 49.382172 -237.700566)
		(width 0.14478)
		(layer "In4.Cu")
		(net "M_D_CPU1_SA_CB<3>")
	)
	(segment
		(start 45.557948 -236.850682)
		(end 46.407832 -237.700566)
		(width 0.14478)
		(layer "In4.Cu")
		(net "M_D_CPU1_SA_CB<3>")
	)
	(segment
		(start 33.121092 -237.710472)
		(end 33.834832 -237.710472)
		(width 0.14478)
		(layer "In4.Cu")
		(net "M_D_CPU1_SA_CB<3>")
	)
	(segment
		(start 59.20867 -237.710472)
		(end 59.59602 -238.097822)
		(width 0.14478)
		(layer "In4.Cu")
		(net "M_D_CPU1_SA_CB<3>")
	)
	(segment
		(start 90.339672 -245.777004)
		(end 90.348054 -245.78183)
		(width 0.0889)
		(layer "In4.Cu")
		(net "M_D_CPU1_SA_CB<3>")
	)
	(segment
		(start 59.420506 -238.501936)
		(end 59.420506 -238.730536)
		(width 0.14478)
		(layer "In4.Cu")
		(net "M_D_CPU1_SA_CB<3>")
	)
	(segment
		(start 41.893998 -237.700566)
		(end 42.743882 -236.850682)
		(width 0.14478)
		(layer "In4.Cu")
		(net "M_D_CPU1_SA_CB<3>")
	)
	(segment
		(start 34.065718 -237.479586)
		(end 34.486596 -237.479586)
		(width 0.14478)
		(layer "In4.Cu")
		(net "M_D_CPU1_SA_CB<3>")
	)
	(segment
		(start 76.23683 -245.432834)
		(end 76.53528 -245.731284)
		(width 0.0889)
		(layer "In4.Cu")
		(net "M_D_CPU1_SA_CB<3>")
	)
	(segment
		(start 83.394042 -245.78183)
		(end 83.402424 -245.777004)
		(width 0.0889)
		(layer "In4.Cu")
		(net "M_D_CPU1_SA_CB<3>")
	)
	(segment
		(start 59.59602 -238.097822)
		(end 59.59602 -238.326422)
		(width 0.14478)
		(layer "In4.Cu")
		(net "M_D_CPU1_SA_CB<3>")
	)
	(segment
		(start 54.106572 -237.710472)
		(end 59.20867 -237.710472)
		(width 0.14478)
		(layer "In4.Cu")
		(net "M_D_CPU1_SA_CB<3>")
	)
	(segment
		(start 79.99984 -245.777004)
		(end 80.008222 -245.78183)
		(width 0.0889)
		(layer "In4.Cu")
		(net "M_D_CPU1_SA_CB<3>")
	)
	(segment
		(start 49.382172 -237.700566)
		(end 50.232056 -236.850682)
		(width 0.14478)
		(layer "In4.Cu")
		(net "M_D_CPU1_SA_CB<3>")
	)
	(segment
		(start 90.913966 -245.78183)
		(end 90.922348 -245.777004)
		(width 0.0889)
		(layer "In4.Cu")
		(net "M_D_CPU1_SA_CB<3>")
	)
	(segment
		(start 78.67777 -245.791228)
		(end 78.693518 -245.782084)
		(width 0.0889)
		(layer "In4.Cu")
		(net "M_D_CPU1_SA_CB<3>")
	)
	(segment
		(start 86.57971 -245.777004)
		(end 86.588092 -245.78183)
		(width 0.0889)
		(layer "In4.Cu")
		(net "M_D_CPU1_SA_CB<3>")
	)
	(segment
		(start 76.53528 -245.731284)
		(end 77.940408 -245.731284)
		(width 0.0889)
		(layer "In4.Cu")
		(net "M_D_CPU1_SA_CB<3>")
	)
	(segment
		(start 50.232056 -236.850682)
		(end 53.246782 -236.850682)
		(width 0.14478)
		(layer "In4.Cu")
		(net "M_D_CPU1_SA_CB<3>")
	)
	(segment
		(start 59.986164 -238.716566)
		(end 60.214764 -238.716566)
		(width 0.14478)
		(layer "In4.Cu")
		(net "M_D_CPU1_SA_CB<3>")
	)
	(segment
		(start 92.195142 -245.83898)
		(end 92.040964 -246.10441)
		(width 0.0889)
		(layer "In4.Cu")
		(net "M_D_CPU1_SA_CB<3>")
	)
	(segment
		(start 59.81065 -238.89208)
		(end 59.986164 -238.716566)
		(width 0.14478)
		(layer "In4.Cu")
		(net "M_D_CPU1_SA_CB<3>")
	)
	(segment
		(start 34.707576 -237.700566)
		(end 41.893998 -237.700566)
		(width 0.14478)
		(layer "In4.Cu")
		(net "M_D_CPU1_SA_CB<3>")
	)
	(segment
		(start 42.743882 -236.850682)
		(end 45.557948 -236.850682)
		(width 0.14478)
		(layer "In4.Cu")
		(net "M_D_CPU1_SA_CB<3>")
	)
	(segment
		(start 60.214764 -238.716566)
		(end 66.931032 -245.432834)
		(width 0.14478)
		(layer "In4.Cu")
		(net "M_D_CPU1_SA_CB<3>")
	)
	(segment
		(start 87.154004 -245.78183)
		(end 87.162386 -245.777004)
		(width 0.0889)
		(layer "In4.Cu")
		(net "M_D_CPU1_SA_CB<3>")
	)
	(segment
		(start 81.879694 -245.777004)
		(end 81.888076 -245.78183)
		(width 0.0889)
		(layer "In4.Cu")
		(net "M_D_CPU1_SA_CB<3>")
	)
	(segment
		(start 59.59602 -238.326422)
		(end 59.420506 -238.501936)
		(width 0.14478)
		(layer "In4.Cu")
		(net "M_D_CPU1_SA_CB<3>")
	)
	(segment
		(start 91.85402 -245.78183)
		(end 91.862402 -245.777004)
		(width 0.0889)
		(layer "In4.Cu")
		(net "M_D_CPU1_SA_CB<3>")
	)
	(segment
		(start 66.931032 -245.432834)
		(end 75.870816 -245.432834)
		(width 0.14478)
		(layer "In4.Cu")
		(net "M_D_CPU1_SA_CB<3>")
	)
	(segment
		(start 75.870816 -245.432834)
		(end 76.23683 -245.432834)
		(width 0.0889)
		(layer "In4.Cu")
		(net "M_D_CPU1_SA_CB<3>")
	)
	(segment
		(start 33.834832 -237.710472)
		(end 34.065718 -237.479586)
		(width 0.14478)
		(layer "In4.Cu")
		(net "M_D_CPU1_SA_CB<3>")
	)
	(segment
		(start 34.486596 -237.479586)
		(end 34.707576 -237.700566)
		(width 0.14478)
		(layer "In4.Cu")
		(net "M_D_CPU1_SA_CB<3>")
	)
	(segment
		(start 85.639656 -245.777004)
		(end 85.648038 -245.78183)
		(width 0.0889)
		(layer "In4.Cu")
		(net "M_D_CPU1_SA_CB<3>")
	)
	(segment
		(start 32.695896 -237.285276)
		(end 33.121092 -237.710472)
		(width 0.14478)
		(layer "In4.Cu")
		(net "M_D_CPU1_SA_CB<3>")
	)
	(segment
		(start 82.453988 -245.78183)
		(end 82.46237 -245.777004)
		(width 0.0889)
		(layer "In4.Cu")
		(net "M_D_CPU1_SA_CB<3>")
	)
	(segment
		(start 88.094058 -245.78183)
		(end 88.10244 -245.777004)
		(width 0.0889)
		(layer "In4.Cu")
		(net "M_D_CPU1_SA_CB<3>")
	)
	(arc
		(start 83.402424 -245.777004)
		(mid 83.585932 -245.73151)
		(end 83.768184 -245.78183)
		(width 0.0889)
		(layer "In4.Cu")
		(net "M_D_CPU1_SA_CB<3>")
	)
	(arc
		(start 88.10244 -245.777004)
		(mid 88.285948 -245.73151)
		(end 88.4682 -245.78183)
		(width 0.0889)
		(layer "In4.Cu")
		(net "M_D_CPU1_SA_CB<3>")
	)
	(arc
		(start 86.21395 -245.78183)
		(mid 86.396201 -245.73148)
		(end 86.57971 -245.777004)
		(width 0.0889)
		(layer "In4.Cu")
		(net "M_D_CPU1_SA_CB<3>")
	)
	(arc
		(start 89.408 -245.78183)
		(mid 89.690956 -245.858007)
		(end 89.973912 -245.78183)
		(width 0.0889)
		(layer "In4.Cu")
		(net "M_D_CPU1_SA_CB<3>")
	)
	(arc
		(start 80.948022 -245.78183)
		(mid 81.230978 -245.858007)
		(end 81.513934 -245.78183)
		(width 0.0889)
		(layer "In4.Cu")
		(net "M_D_CPU1_SA_CB<3>")
	)
	(arc
		(start 77.940408 -245.731284)
		(mid 78.037359 -245.744159)
		(end 78.127606 -245.78183)
		(width 0.0889)
		(layer "In4.Cu")
		(net "M_D_CPU1_SA_CB<3>")
	)
	(arc
		(start 82.46237 -245.777004)
		(mid 82.645878 -245.73151)
		(end 82.82813 -245.78183)
		(width 0.0889)
		(layer "In4.Cu")
		(net "M_D_CPU1_SA_CB<3>")
	)
	(arc
		(start 87.162386 -245.777004)
		(mid 87.345894 -245.73151)
		(end 87.528146 -245.78183)
		(width 0.0889)
		(layer "In4.Cu")
		(net "M_D_CPU1_SA_CB<3>")
	)
	(arc
		(start 90.922348 -245.777004)
		(mid 91.105856 -245.73151)
		(end 91.288108 -245.78183)
		(width 0.0889)
		(layer "In4.Cu")
		(net "M_D_CPU1_SA_CB<3>")
	)
	(arc
		(start 89.034112 -245.78183)
		(mid 89.221056 -245.731575)
		(end 89.408 -245.78183)
		(width 0.0889)
		(layer "In4.Cu")
		(net "M_D_CPU1_SA_CB<3>")
	)
	(arc
		(start 86.588092 -245.78183)
		(mid 86.871048 -245.858007)
		(end 87.154004 -245.78183)
		(width 0.0889)
		(layer "In4.Cu")
		(net "M_D_CPU1_SA_CB<3>")
	)
	(arc
		(start 84.707984 -245.78183)
		(mid 84.99094 -245.858007)
		(end 85.273896 -245.78183)
		(width 0.0889)
		(layer "In4.Cu")
		(net "M_D_CPU1_SA_CB<3>")
	)
	(arc
		(start 79.633572 -245.78183)
		(mid 79.816077 -245.731353)
		(end 79.99984 -245.777004)
		(width 0.0889)
		(layer "In4.Cu")
		(net "M_D_CPU1_SA_CB<3>")
	)
	(arc
		(start 88.4682 -245.78183)
		(mid 88.751156 -245.858007)
		(end 89.034112 -245.78183)
		(width 0.0889)
		(layer "In4.Cu")
		(net "M_D_CPU1_SA_CB<3>")
	)
	(arc
		(start 89.973912 -245.78183)
		(mid 90.156163 -245.73148)
		(end 90.339672 -245.777004)
		(width 0.0889)
		(layer "In4.Cu")
		(net "M_D_CPU1_SA_CB<3>")
	)
	(arc
		(start 91.862402 -245.777004)
		(mid 92.015272 -245.732363)
		(end 92.17279 -245.755668)
		(width 0.0889)
		(layer "In4.Cu")
		(net "M_D_CPU1_SA_CB<3>")
	)
	(arc
		(start 83.768184 -245.78183)
		(mid 84.05114 -245.858007)
		(end 84.334096 -245.78183)
		(width 0.0889)
		(layer "In4.Cu")
		(net "M_D_CPU1_SA_CB<3>")
	)
	(arc
		(start 82.82813 -245.78183)
		(mid 83.111086 -245.858007)
		(end 83.394042 -245.78183)
		(width 0.0889)
		(layer "In4.Cu")
		(net "M_D_CPU1_SA_CB<3>")
	)
	(arc
		(start 81.888076 -245.78183)
		(mid 82.171032 -245.858007)
		(end 82.453988 -245.78183)
		(width 0.0889)
		(layer "In4.Cu")
		(net "M_D_CPU1_SA_CB<3>")
	)
	(arc
		(start 80.008222 -245.78183)
		(mid 80.291178 -245.858007)
		(end 80.574134 -245.78183)
		(width 0.0889)
		(layer "In4.Cu")
		(net "M_D_CPU1_SA_CB<3>")
	)
	(arc
		(start 80.574134 -245.78183)
		(mid 80.761078 -245.731575)
		(end 80.948022 -245.78183)
		(width 0.0889)
		(layer "In4.Cu")
		(net "M_D_CPU1_SA_CB<3>")
	)
	(arc
		(start 78.709774 -245.772686)
		(mid 78.889756 -245.731586)
		(end 79.067406 -245.78183)
		(width 0.0889)
		(layer "In4.Cu")
		(net "M_D_CPU1_SA_CB<3>")
	)
	(arc
		(start 90.348054 -245.78183)
		(mid 90.63101 -245.858007)
		(end 90.913966 -245.78183)
		(width 0.0889)
		(layer "In4.Cu")
		(net "M_D_CPU1_SA_CB<3>")
	)
	(arc
		(start 79.07782 -245.787926)
		(mid 79.356506 -245.858146)
		(end 79.633572 -245.78183)
		(width 0.0889)
		(layer "In4.Cu")
		(net "M_D_CPU1_SA_CB<3>")
	)
	(arc
		(start 84.334096 -245.78183)
		(mid 84.52104 -245.731575)
		(end 84.707984 -245.78183)
		(width 0.0889)
		(layer "In4.Cu")
		(net "M_D_CPU1_SA_CB<3>")
	)
	(arc
		(start 85.648038 -245.78183)
		(mid 85.930994 -245.858007)
		(end 86.21395 -245.78183)
		(width 0.0889)
		(layer "In4.Cu")
		(net "M_D_CPU1_SA_CB<3>")
	)
	(arc
		(start 87.528146 -245.78183)
		(mid 87.811102 -245.858007)
		(end 88.094058 -245.78183)
		(width 0.0889)
		(layer "In4.Cu")
		(net "M_D_CPU1_SA_CB<3>")
	)
	(arc
		(start 85.273896 -245.78183)
		(mid 85.456147 -245.73148)
		(end 85.639656 -245.777004)
		(width 0.0889)
		(layer "In4.Cu")
		(net "M_D_CPU1_SA_CB<3>")
	)
	(arc
		(start 81.513934 -245.78183)
		(mid 81.696185 -245.73148)
		(end 81.879694 -245.777004)
		(width 0.0889)
		(layer "In4.Cu")
		(net "M_D_CPU1_SA_CB<3>")
	)
	(arc
		(start 78.127606 -245.78183)
		(mid 78.401461 -245.85818)
		(end 78.67777 -245.791228)
		(width 0.0889)
		(layer "In4.Cu")
		(net "M_D_CPU1_SA_CB<3>")
	)
	(arc
		(start 91.288108 -245.78183)
		(mid 91.571064 -245.858007)
		(end 91.85402 -245.78183)
		(width 0.0889)
		(layer "In4.Cu")
		(net "M_D_CPU1_SA_CB<3>")
	)
	(segment
		(start 91.097862 -245.560342)
		(end 90.63101 -245.294404)
		(width 0.10668)
		(layer "F.Cu")
		(net "M_D_CPU1_SA_CB<2>")
	)
	(segment
		(start 54.106572 -236.01045)
		(end 58.8645 -236.01045)
		(width 0.14478)
		(layer "In4.Cu")
		(net "M_D_CPU1_SA_CB<2>")
	)
	(segment
		(start 77.02169 -244.378226)
		(end 77.564234 -244.92077)
		(width 0.0889)
		(layer "In4.Cu")
		(net "M_D_CPU1_SA_CB<2>")
	)
	(segment
		(start 34.864294 -235.847382)
		(end 35.027362 -236.01045)
		(width 0.14478)
		(layer "In4.Cu")
		(net "M_D_CPU1_SA_CB<2>")
	)
	(segment
		(start 59.878976 -236.277658)
		(end 60.04052 -236.439202)
		(width 0.14478)
		(layer "In4.Cu")
		(net "M_D_CPU1_SA_CB<2>")
	)
	(segment
		(start 84.229702 -244.966998)
		(end 84.238084 -244.971824)
		(width 0.0889)
		(layer "In4.Cu")
		(net "M_D_CPU1_SA_CB<2>")
	)
	(segment
		(start 59.895486 -237.041436)
		(end 67.387724 -244.533674)
		(width 0.14478)
		(layer "In4.Cu")
		(net "M_D_CPU1_SA_CB<2>")
	)
	(segment
		(start 79.143098 -244.98554)
		(end 79.166466 -244.971824)
		(width 0.0889)
		(layer "In4.Cu")
		(net "M_D_CPU1_SA_CB<2>")
	)
	(segment
		(start 53.256434 -235.160312)
		(end 54.106572 -236.01045)
		(width 0.14478)
		(layer "In4.Cu")
		(net "M_D_CPU1_SA_CB<2>")
	)
	(segment
		(start 79.521304 -244.961664)
		(end 79.539592 -244.972078)
		(width 0.0889)
		(layer "In4.Cu")
		(net "M_D_CPU1_SA_CB<2>")
	)
	(segment
		(start 85.74405 -244.971824)
		(end 85.752432 -244.966998)
		(width 0.0889)
		(layer "In4.Cu")
		(net "M_D_CPU1_SA_CB<2>")
	)
	(segment
		(start 34.30778 -235.396532)
		(end 34.470848 -235.233464)
		(width 0.14478)
		(layer "In4.Cu")
		(net "M_D_CPU1_SA_CB<2>")
	)
	(segment
		(start 76.353924 -244.378226)
		(end 77.02169 -244.378226)
		(width 0.0889)
		(layer "In4.Cu")
		(net "M_D_CPU1_SA_CB<2>")
	)
	(segment
		(start 87.989664 -244.966998)
		(end 87.998046 -244.971824)
		(width 0.0889)
		(layer "In4.Cu")
		(net "M_D_CPU1_SA_CB<2>")
	)
	(segment
		(start 41.884092 -236.01045)
		(end 42.73423 -235.160312)
		(width 0.14478)
		(layer "In4.Cu")
		(net "M_D_CPU1_SA_CB<2>")
	)
	(segment
		(start 34.470848 -235.233464)
		(end 34.701226 -235.233464)
		(width 0.14478)
		(layer "In4.Cu")
		(net "M_D_CPU1_SA_CB<2>")
	)
	(segment
		(start 34.144712 -236.01045)
		(end 34.30778 -235.847382)
		(width 0.14478)
		(layer "In4.Cu")
		(net "M_D_CPU1_SA_CB<2>")
	)
	(segment
		(start 60.04052 -236.439202)
		(end 60.04052 -236.667802)
		(width 0.14478)
		(layer "In4.Cu")
		(net "M_D_CPU1_SA_CB<2>")
	)
	(segment
		(start 67.387724 -244.533674)
		(end 76.198476 -244.533674)
		(width 0.14478)
		(layer "In4.Cu")
		(net "M_D_CPU1_SA_CB<2>")
	)
	(segment
		(start 34.30778 -235.847382)
		(end 34.30778 -235.396532)
		(width 0.14478)
		(layer "In4.Cu")
		(net "M_D_CPU1_SA_CB<2>")
	)
	(segment
		(start 90.784934 -245.028974)
		(end 90.63101 -245.294404)
		(width 0.0889)
		(layer "In4.Cu")
		(net "M_D_CPU1_SA_CB<2>")
	)
	(segment
		(start 59.276742 -236.422692)
		(end 59.505342 -236.422692)
		(width 0.14478)
		(layer "In4.Cu")
		(net "M_D_CPU1_SA_CB<2>")
	)
	(segment
		(start 58.8645 -236.01045)
		(end 59.276742 -236.422692)
		(width 0.14478)
		(layer "In4.Cu")
		(net "M_D_CPU1_SA_CB<2>")
	)
	(segment
		(start 45.5676 -235.160312)
		(end 46.417738 -236.01045)
		(width 0.14478)
		(layer "In4.Cu")
		(net "M_D_CPU1_SA_CB<2>")
	)
	(segment
		(start 50.222404 -235.160312)
		(end 53.256434 -235.160312)
		(width 0.14478)
		(layer "In4.Cu")
		(net "M_D_CPU1_SA_CB<2>")
	)
	(segment
		(start 46.417738 -236.01045)
		(end 49.372266 -236.01045)
		(width 0.14478)
		(layer "In4.Cu")
		(net "M_D_CPU1_SA_CB<2>")
	)
	(segment
		(start 49.372266 -236.01045)
		(end 50.222404 -235.160312)
		(width 0.14478)
		(layer "In4.Cu")
		(net "M_D_CPU1_SA_CB<2>")
	)
	(segment
		(start 84.803996 -244.971824)
		(end 84.812378 -244.966998)
		(width 0.0889)
		(layer "In4.Cu")
		(net "M_D_CPU1_SA_CB<2>")
	)
	(segment
		(start 88.929718 -244.966998)
		(end 88.9381 -244.971824)
		(width 0.0889)
		(layer "In4.Cu")
		(net "M_D_CPU1_SA_CB<2>")
	)
	(segment
		(start 79.539592 -244.972078)
		(end 79.561182 -244.984524)
		(width 0.0889)
		(layer "In4.Cu")
		(net "M_D_CPU1_SA_CB<2>")
	)
	(segment
		(start 83.289648 -244.966998)
		(end 83.29803 -244.971824)
		(width 0.0889)
		(layer "In4.Cu")
		(net "M_D_CPU1_SA_CB<2>")
	)
	(segment
		(start 81.044034 -244.971824)
		(end 81.052416 -244.966998)
		(width 0.0889)
		(layer "In4.Cu")
		(net "M_D_CPU1_SA_CB<2>")
	)
	(segment
		(start 59.505342 -236.422692)
		(end 59.650376 -236.277658)
		(width 0.14478)
		(layer "In4.Cu")
		(net "M_D_CPU1_SA_CB<2>")
	)
	(segment
		(start 77.564234 -244.92077)
		(end 78.41107 -244.92077)
		(width 0.0889)
		(layer "In4.Cu")
		(net "M_D_CPU1_SA_CB<2>")
	)
	(segment
		(start 59.895486 -236.812836)
		(end 59.895486 -237.041436)
		(width 0.14478)
		(layer "In4.Cu")
		(net "M_D_CPU1_SA_CB<2>")
	)
	(segment
		(start 35.027362 -236.01045)
		(end 41.884092 -236.01045)
		(width 0.14478)
		(layer "In4.Cu")
		(net "M_D_CPU1_SA_CB<2>")
	)
	(segment
		(start 59.650376 -236.277658)
		(end 59.878976 -236.277658)
		(width 0.14478)
		(layer "In4.Cu")
		(net "M_D_CPU1_SA_CB<2>")
	)
	(segment
		(start 34.864294 -235.396532)
		(end 34.864294 -235.847382)
		(width 0.14478)
		(layer "In4.Cu")
		(net "M_D_CPU1_SA_CB<2>")
	)
	(segment
		(start 76.198476 -244.533674)
		(end 76.353924 -244.378226)
		(width 0.0889)
		(layer "In4.Cu")
		(net "M_D_CPU1_SA_CB<2>")
	)
	(segment
		(start 42.73423 -235.160312)
		(end 45.5676 -235.160312)
		(width 0.14478)
		(layer "In4.Cu")
		(net "M_D_CPU1_SA_CB<2>")
	)
	(segment
		(start 32.695896 -235.585254)
		(end 33.121092 -236.01045)
		(width 0.14478)
		(layer "In4.Cu")
		(net "M_D_CPU1_SA_CB<2>")
	)
	(segment
		(start 80.46974 -244.966998)
		(end 80.478122 -244.971824)
		(width 0.0889)
		(layer "In4.Cu")
		(net "M_D_CPU1_SA_CB<2>")
	)
	(segment
		(start 89.504012 -244.971824)
		(end 89.512394 -244.966998)
		(width 0.0889)
		(layer "In4.Cu")
		(net "M_D_CPU1_SA_CB<2>")
	)
	(segment
		(start 34.701226 -235.233464)
		(end 34.864294 -235.396532)
		(width 0.14478)
		(layer "In4.Cu")
		(net "M_D_CPU1_SA_CB<2>")
	)
	(segment
		(start 33.121092 -236.01045)
		(end 34.144712 -236.01045)
		(width 0.14478)
		(layer "In4.Cu")
		(net "M_D_CPU1_SA_CB<2>")
	)
	(segment
		(start 60.04052 -236.667802)
		(end 59.895486 -236.812836)
		(width 0.14478)
		(layer "In4.Cu")
		(net "M_D_CPU1_SA_CB<2>")
	)
	(segment
		(start 90.762582 -244.945662)
		(end 90.784934 -245.028974)
		(width 0.0889)
		(layer "In4.Cu")
		(net "M_D_CPU1_SA_CB<2>")
	)
	(arc
		(start 80.10398 -244.971824)
		(mid 80.286231 -244.921474)
		(end 80.46974 -244.966998)
		(width 0.0889)
		(layer "In4.Cu")
		(net "M_D_CPU1_SA_CB<2>")
	)
	(arc
		(start 87.623904 -244.971824)
		(mid 87.806155 -244.921474)
		(end 87.989664 -244.966998)
		(width 0.0889)
		(layer "In4.Cu")
		(net "M_D_CPU1_SA_CB<2>")
	)
	(arc
		(start 87.998046 -244.971824)
		(mid 88.281002 -245.048001)
		(end 88.563958 -244.971824)
		(width 0.0889)
		(layer "In4.Cu")
		(net "M_D_CPU1_SA_CB<2>")
	)
	(arc
		(start 85.752432 -244.966998)
		(mid 85.93594 -244.921504)
		(end 86.118192 -244.971824)
		(width 0.0889)
		(layer "In4.Cu")
		(net "M_D_CPU1_SA_CB<2>")
	)
	(arc
		(start 83.863942 -244.971824)
		(mid 84.046193 -244.921474)
		(end 84.229702 -244.966998)
		(width 0.0889)
		(layer "In4.Cu")
		(net "M_D_CPU1_SA_CB<2>")
	)
	(arc
		(start 81.984088 -244.971824)
		(mid 82.171032 -244.921569)
		(end 82.357976 -244.971824)
		(width 0.0889)
		(layer "In4.Cu")
		(net "M_D_CPU1_SA_CB<2>")
	)
	(arc
		(start 78.41107 -244.92077)
		(mid 78.508573 -244.933785)
		(end 78.599284 -244.971824)
		(width 0.0889)
		(layer "In4.Cu")
		(net "M_D_CPU1_SA_CB<2>")
	)
	(arc
		(start 78.599284 -244.971824)
		(mid 78.869441 -245.048586)
		(end 79.143098 -244.98554)
		(width 0.0889)
		(layer "In4.Cu")
		(net "M_D_CPU1_SA_CB<2>")
	)
	(arc
		(start 89.512394 -244.966998)
		(mid 89.695902 -244.921504)
		(end 89.878154 -244.971824)
		(width 0.0889)
		(layer "In4.Cu")
		(net "M_D_CPU1_SA_CB<2>")
	)
	(arc
		(start 88.9381 -244.971824)
		(mid 89.221056 -245.048001)
		(end 89.504012 -244.971824)
		(width 0.0889)
		(layer "In4.Cu")
		(net "M_D_CPU1_SA_CB<2>")
	)
	(arc
		(start 84.812378 -244.966998)
		(mid 84.995886 -244.921504)
		(end 85.178138 -244.971824)
		(width 0.0889)
		(layer "In4.Cu")
		(net "M_D_CPU1_SA_CB<2>")
	)
	(arc
		(start 90.444066 -244.971824)
		(mid 90.600385 -244.922829)
		(end 90.762582 -244.945662)
		(width 0.0889)
		(layer "In4.Cu")
		(net "M_D_CPU1_SA_CB<2>")
	)
	(arc
		(start 80.478122 -244.971824)
		(mid 80.761078 -245.048001)
		(end 81.044034 -244.971824)
		(width 0.0889)
		(layer "In4.Cu")
		(net "M_D_CPU1_SA_CB<2>")
	)
	(arc
		(start 79.561182 -244.984524)
		(mid 79.834211 -245.047843)
		(end 80.10398 -244.971824)
		(width 0.0889)
		(layer "In4.Cu")
		(net "M_D_CPU1_SA_CB<2>")
	)
	(arc
		(start 82.357976 -244.971824)
		(mid 82.640932 -245.048001)
		(end 82.923888 -244.971824)
		(width 0.0889)
		(layer "In4.Cu")
		(net "M_D_CPU1_SA_CB<2>")
	)
	(arc
		(start 81.052416 -244.966998)
		(mid 81.235924 -244.921504)
		(end 81.418176 -244.971824)
		(width 0.0889)
		(layer "In4.Cu")
		(net "M_D_CPU1_SA_CB<2>")
	)
	(arc
		(start 88.563958 -244.971824)
		(mid 88.746209 -244.921474)
		(end 88.929718 -244.966998)
		(width 0.0889)
		(layer "In4.Cu")
		(net "M_D_CPU1_SA_CB<2>")
	)
	(arc
		(start 87.057992 -244.971824)
		(mid 87.340948 -245.048001)
		(end 87.623904 -244.971824)
		(width 0.0889)
		(layer "In4.Cu")
		(net "M_D_CPU1_SA_CB<2>")
	)
	(arc
		(start 86.684104 -244.971824)
		(mid 86.871048 -244.921569)
		(end 87.057992 -244.971824)
		(width 0.0889)
		(layer "In4.Cu")
		(net "M_D_CPU1_SA_CB<2>")
	)
	(arc
		(start 89.878154 -244.971824)
		(mid 90.16111 -245.048001)
		(end 90.444066 -244.971824)
		(width 0.0889)
		(layer "In4.Cu")
		(net "M_D_CPU1_SA_CB<2>")
	)
	(arc
		(start 81.418176 -244.971824)
		(mid 81.701132 -245.048001)
		(end 81.984088 -244.971824)
		(width 0.0889)
		(layer "In4.Cu")
		(net "M_D_CPU1_SA_CB<2>")
	)
	(arc
		(start 86.118192 -244.971824)
		(mid 86.401148 -245.048001)
		(end 86.684104 -244.971824)
		(width 0.0889)
		(layer "In4.Cu")
		(net "M_D_CPU1_SA_CB<2>")
	)
	(arc
		(start 85.178138 -244.971824)
		(mid 85.461094 -245.048001)
		(end 85.74405 -244.971824)
		(width 0.0889)
		(layer "In4.Cu")
		(net "M_D_CPU1_SA_CB<2>")
	)
	(arc
		(start 82.923888 -244.971824)
		(mid 83.106139 -244.921474)
		(end 83.289648 -244.966998)
		(width 0.0889)
		(layer "In4.Cu")
		(net "M_D_CPU1_SA_CB<2>")
	)
	(arc
		(start 84.238084 -244.971824)
		(mid 84.52104 -245.048001)
		(end 84.803996 -244.971824)
		(width 0.0889)
		(layer "In4.Cu")
		(net "M_D_CPU1_SA_CB<2>")
	)
	(arc
		(start 79.166466 -244.971824)
		(mid 79.342586 -244.921846)
		(end 79.521304 -244.961664)
		(width 0.0889)
		(layer "In4.Cu")
		(net "M_D_CPU1_SA_CB<2>")
	)
	(arc
		(start 83.29803 -244.971824)
		(mid 83.580986 -245.048001)
		(end 83.863942 -244.971824)
		(width 0.0889)
		(layer "In4.Cu")
		(net "M_D_CPU1_SA_CB<2>")
	)
	(segment
		(start 92.97797 -245.560342)
		(end 92.511118 -245.294404)
		(width 0.10668)
		(layer "F.Cu")
		(net "M_D_CPU1_SA_CB<1>")
	)
	(segment
		(start 36.795964 -236.435392)
		(end 37.220906 -236.860334)
		(width 0.14478)
		(layer "In4.Cu")
		(net "M_D_CPU1_SA_CB<1>")
	)
	(segment
		(start 55.099458 -237.023402)
		(end 55.262526 -236.860334)
		(width 0.14478)
		(layer "In4.Cu")
		(net "M_D_CPU1_SA_CB<1>")
	)
	(segment
		(start 48.992282 -236.633512)
		(end 48.992282 -236.697266)
		(width 0.14478)
		(layer "In4.Cu")
		(net "M_D_CPU1_SA_CB<1>")
	)
	(segment
		(start 53.23459 -236.01045)
		(end 54.084474 -236.860334)
		(width 0.14478)
		(layer "In4.Cu")
		(net "M_D_CPU1_SA_CB<1>")
	)
	(segment
		(start 54.542944 -237.023402)
		(end 54.542944 -237.089696)
		(width 0.14478)
		(layer "In4.Cu")
		(net "M_D_CPU1_SA_CB<1>")
	)
	(segment
		(start 76.629768 -245.373906)
		(end 77.538326 -245.373906)
		(width 0.0889)
		(layer "In4.Cu")
		(net "M_D_CPU1_SA_CB<1>")
	)
	(segment
		(start 55.655972 -237.089696)
		(end 55.81904 -237.252764)
		(width 0.14478)
		(layer "In4.Cu")
		(net "M_D_CPU1_SA_CB<1>")
	)
	(segment
		(start 85.74405 -245.616984)
		(end 85.752432 -245.62181)
		(width 0.0889)
		(layer "In4.Cu")
		(net "M_D_CPU1_SA_CB<1>")
	)
	(segment
		(start 92.260674 -245.585234)
		(end 92.35694 -245.559834)
		(width 0.0889)
		(layer "In4.Cu")
		(net "M_D_CPU1_SA_CB<1>")
	)
	(segment
		(start 59.000644 -236.860334)
		(end 67.123564 -244.983254)
		(width 0.14478)
		(layer "In4.Cu")
		(net "M_D_CPU1_SA_CB<1>")
	)
	(segment
		(start 54.084474 -236.860334)
		(end 54.379876 -236.860334)
		(width 0.14478)
		(layer "In4.Cu")
		(net "M_D_CPU1_SA_CB<1>")
	)
	(segment
		(start 41.88333 -236.860334)
		(end 42.733214 -236.01045)
		(width 0.14478)
		(layer "In4.Cu")
		(net "M_D_CPU1_SA_CB<1>")
	)
	(segment
		(start 43.217592 -236.173518)
		(end 43.217592 -236.236256)
		(width 0.14478)
		(layer "In4.Cu")
		(net "M_D_CPU1_SA_CB<1>")
	)
	(segment
		(start 47.141384 -236.615986)
		(end 47.385732 -236.860334)
		(width 0.14478)
		(layer "In4.Cu")
		(net "M_D_CPU1_SA_CB<1>")
	)
	(segment
		(start 51.43627 -236.01045)
		(end 52.291742 -236.01045)
		(width 0.14478)
		(layer "In4.Cu")
		(net "M_D_CPU1_SA_CB<1>")
	)
	(segment
		(start 46.408594 -236.860334)
		(end 46.58995 -236.860334)
		(width 0.14478)
		(layer "In4.Cu")
		(net "M_D_CPU1_SA_CB<1>")
	)
	(segment
		(start 77.538326 -245.373906)
		(end 77.705204 -245.540784)
		(width 0.0889)
		(layer "In4.Cu")
		(net "M_D_CPU1_SA_CB<1>")
	)
	(segment
		(start 38.297358 -237.248446)
		(end 38.456108 -237.089696)
		(width 0.14478)
		(layer "In4.Cu")
		(net "M_D_CPU1_SA_CB<1>")
	)
	(segment
		(start 81.044034 -245.616984)
		(end 81.052416 -245.62181)
		(width 0.0889)
		(layer "In4.Cu")
		(net "M_D_CPU1_SA_CB<1>")
	)
	(segment
		(start 52.291742 -236.01045)
		(end 52.532026 -235.770166)
		(width 0.14478)
		(layer "In4.Cu")
		(net "M_D_CPU1_SA_CB<1>")
	)
	(segment
		(start 39.012622 -237.089696)
		(end 39.171372 -237.248446)
		(width 0.14478)
		(layer "In4.Cu")
		(net "M_D_CPU1_SA_CB<1>")
	)
	(segment
		(start 43.611038 -236.399324)
		(end 43.774106 -236.236256)
		(width 0.14478)
		(layer "In4.Cu")
		(net "M_D_CPU1_SA_CB<1>")
	)
	(segment
		(start 57.097168 -236.565186)
		(end 57.392316 -236.860334)
		(width 0.14478)
		(layer "In4.Cu")
		(net "M_D_CPU1_SA_CB<1>")
	)
	(segment
		(start 56.840882 -236.565186)
		(end 57.097168 -236.565186)
		(width 0.14478)
		(layer "In4.Cu")
		(net "M_D_CPU1_SA_CB<1>")
	)
	(segment
		(start 38.058344 -237.248446)
		(end 38.297358 -237.248446)
		(width 0.14478)
		(layer "In4.Cu")
		(net "M_D_CPU1_SA_CB<1>")
	)
	(segment
		(start 57.392316 -236.860334)
		(end 57.648602 -236.860334)
		(width 0.14478)
		(layer "In4.Cu")
		(net "M_D_CPU1_SA_CB<1>")
	)
	(segment
		(start 43.217592 -236.236256)
		(end 43.38066 -236.399324)
		(width 0.14478)
		(layer "In4.Cu")
		(net "M_D_CPU1_SA_CB<1>")
	)
	(segment
		(start 80.093566 -245.610888)
		(end 80.10398 -245.616984)
		(width 0.0889)
		(layer "In4.Cu")
		(net "M_D_CPU1_SA_CB<1>")
	)
	(segment
		(start 37.220906 -236.860334)
		(end 37.736526 -236.860334)
		(width 0.14478)
		(layer "In4.Cu")
		(net "M_D_CPU1_SA_CB<1>")
	)
	(segment
		(start 37.899594 -237.023402)
		(end 37.899594 -237.089696)
		(width 0.14478)
		(layer "In4.Cu")
		(net "M_D_CPU1_SA_CB<1>")
	)
	(segment
		(start 50.879756 -236.399324)
		(end 51.110134 -236.399324)
		(width 0.14478)
		(layer "In4.Cu")
		(net "M_D_CPU1_SA_CB<1>")
	)
	(segment
		(start 55.81904 -237.252764)
		(end 56.049418 -237.252764)
		(width 0.14478)
		(layer "In4.Cu")
		(net "M_D_CPU1_SA_CB<1>")
	)
	(segment
		(start 79.163164 -245.616984)
		(end 79.171546 -245.62181)
		(width 0.0889)
		(layer "In4.Cu")
		(net "M_D_CPU1_SA_CB<1>")
	)
	(segment
		(start 67.123564 -244.983254)
		(end 76.239116 -244.983254)
		(width 0.14478)
		(layer "In4.Cu")
		(net "M_D_CPU1_SA_CB<1>")
	)
	(segment
		(start 54.706012 -237.252764)
		(end 54.93639 -237.252764)
		(width 0.14478)
		(layer "In4.Cu")
		(net "M_D_CPU1_SA_CB<1>")
	)
	(segment
		(start 43.054524 -236.01045)
		(end 43.217592 -236.173518)
		(width 0.14478)
		(layer "In4.Cu")
		(net "M_D_CPU1_SA_CB<1>")
	)
	(segment
		(start 47.385732 -236.860334)
		(end 48.2727 -236.860334)
		(width 0.14478)
		(layer "In4.Cu")
		(net "M_D_CPU1_SA_CB<1>")
	)
	(segment
		(start 37.736526 -236.860334)
		(end 37.899594 -237.023402)
		(width 0.14478)
		(layer "In4.Cu")
		(net "M_D_CPU1_SA_CB<1>")
	)
	(segment
		(start 56.375554 -236.860334)
		(end 56.545734 -236.860334)
		(width 0.14478)
		(layer "In4.Cu")
		(net "M_D_CPU1_SA_CB<1>")
	)
	(segment
		(start 84.229702 -245.62181)
		(end 84.238084 -245.616984)
		(width 0.0889)
		(layer "In4.Cu")
		(net "M_D_CPU1_SA_CB<1>")
	)
	(segment
		(start 56.212486 -237.089696)
		(end 56.212486 -237.023402)
		(width 0.14478)
		(layer "In4.Cu")
		(net "M_D_CPU1_SA_CB<1>")
	)
	(segment
		(start 48.435768 -236.697266)
		(end 48.435768 -236.633512)
		(width 0.14478)
		(layer "In4.Cu")
		(net "M_D_CPU1_SA_CB<1>")
	)
	(segment
		(start 78.59776 -245.61673)
		(end 78.603348 -245.613428)
		(width 0.0889)
		(layer "In4.Cu")
		(net "M_D_CPU1_SA_CB<1>")
	)
	(segment
		(start 49.40681 -236.860334)
		(end 50.256694 -236.01045)
		(width 0.14478)
		(layer "In4.Cu")
		(net "M_D_CPU1_SA_CB<1>")
	)
	(segment
		(start 55.492904 -236.860334)
		(end 55.655972 -237.023402)
		(width 0.14478)
		(layer "In4.Cu")
		(net "M_D_CPU1_SA_CB<1>")
	)
	(segment
		(start 39.410386 -237.248446)
		(end 39.569136 -237.089696)
		(width 0.14478)
		(layer "In4.Cu")
		(net "M_D_CPU1_SA_CB<1>")
	)
	(segment
		(start 57.94375 -236.565186)
		(end 58.200036 -236.565186)
		(width 0.14478)
		(layer "In4.Cu")
		(net "M_D_CPU1_SA_CB<1>")
	)
	(segment
		(start 38.456108 -236.658912)
		(end 38.619176 -236.495844)
		(width 0.14478)
		(layer "In4.Cu")
		(net "M_D_CPU1_SA_CB<1>")
	)
	(segment
		(start 52.843176 -235.770166)
		(end 53.08346 -236.01045)
		(width 0.14478)
		(layer "In4.Cu")
		(net "M_D_CPU1_SA_CB<1>")
	)
	(segment
		(start 89.504012 -245.616984)
		(end 89.512394 -245.62181)
		(width 0.0889)
		(layer "In4.Cu")
		(net "M_D_CPU1_SA_CB<1>")
	)
	(segment
		(start 39.012622 -236.658912)
		(end 39.012622 -237.089696)
		(width 0.14478)
		(layer "In4.Cu")
		(net "M_D_CPU1_SA_CB<1>")
	)
	(segment
		(start 48.2727 -236.860334)
		(end 48.435768 -236.697266)
		(width 0.14478)
		(layer "In4.Cu")
		(net "M_D_CPU1_SA_CB<1>")
	)
	(segment
		(start 43.774106 -236.173518)
		(end 43.937174 -236.01045)
		(width 0.14478)
		(layer "In4.Cu")
		(net "M_D_CPU1_SA_CB<1>")
	)
	(segment
		(start 80.46974 -245.62181)
		(end 80.478122 -245.616984)
		(width 0.0889)
		(layer "In4.Cu")
		(net "M_D_CPU1_SA_CB<1>")
	)
	(segment
		(start 45.55871 -236.01045)
		(end 46.408594 -236.860334)
		(width 0.14478)
		(layer "In4.Cu")
		(net "M_D_CPU1_SA_CB<1>")
	)
	(segment
		(start 49.15535 -236.860334)
		(end 49.40681 -236.860334)
		(width 0.14478)
		(layer "In4.Cu")
		(net "M_D_CPU1_SA_CB<1>")
	)
	(segment
		(start 43.38066 -236.399324)
		(end 43.611038 -236.399324)
		(width 0.14478)
		(layer "In4.Cu")
		(net "M_D_CPU1_SA_CB<1>")
	)
	(segment
		(start 43.774106 -236.236256)
		(end 43.774106 -236.173518)
		(width 0.14478)
		(layer "In4.Cu")
		(net "M_D_CPU1_SA_CB<1>")
	)
	(segment
		(start 46.58995 -236.860334)
		(end 46.834298 -236.615986)
		(width 0.14478)
		(layer "In4.Cu")
		(net "M_D_CPU1_SA_CB<1>")
	)
	(segment
		(start 55.099458 -237.089696)
		(end 55.099458 -237.023402)
		(width 0.14478)
		(layer "In4.Cu")
		(net "M_D_CPU1_SA_CB<1>")
	)
	(segment
		(start 58.200036 -236.565186)
		(end 58.495184 -236.860334)
		(width 0.14478)
		(layer "In4.Cu")
		(net "M_D_CPU1_SA_CB<1>")
	)
	(segment
		(start 88.929718 -245.62181)
		(end 88.9381 -245.616984)
		(width 0.0889)
		(layer "In4.Cu")
		(net "M_D_CPU1_SA_CB<1>")
	)
	(segment
		(start 55.262526 -236.860334)
		(end 55.492904 -236.860334)
		(width 0.14478)
		(layer "In4.Cu")
		(net "M_D_CPU1_SA_CB<1>")
	)
	(segment
		(start 87.989664 -245.62181)
		(end 87.998046 -245.616984)
		(width 0.0889)
		(layer "In4.Cu")
		(net "M_D_CPU1_SA_CB<1>")
	)
	(segment
		(start 55.655972 -237.023402)
		(end 55.655972 -237.089696)
		(width 0.14478)
		(layer "In4.Cu")
		(net "M_D_CPU1_SA_CB<1>")
	)
	(segment
		(start 48.829214 -236.470444)
		(end 48.992282 -236.633512)
		(width 0.14478)
		(layer "In4.Cu")
		(net "M_D_CPU1_SA_CB<1>")
	)
	(segment
		(start 38.456108 -237.089696)
		(end 38.456108 -236.658912)
		(width 0.14478)
		(layer "In4.Cu")
		(net "M_D_CPU1_SA_CB<1>")
	)
	(segment
		(start 54.93639 -237.252764)
		(end 55.099458 -237.089696)
		(width 0.14478)
		(layer "In4.Cu")
		(net "M_D_CPU1_SA_CB<1>")
	)
	(segment
		(start 38.849554 -236.495844)
		(end 39.012622 -236.658912)
		(width 0.14478)
		(layer "In4.Cu")
		(net "M_D_CPU1_SA_CB<1>")
	)
	(segment
		(start 37.899594 -237.089696)
		(end 38.058344 -237.248446)
		(width 0.14478)
		(layer "In4.Cu")
		(net "M_D_CPU1_SA_CB<1>")
	)
	(segment
		(start 48.435768 -236.633512)
		(end 48.598836 -236.470444)
		(width 0.14478)
		(layer "In4.Cu")
		(net "M_D_CPU1_SA_CB<1>")
	)
	(segment
		(start 41.104312 -236.557566)
		(end 41.352978 -236.557566)
		(width 0.14478)
		(layer "In4.Cu")
		(net "M_D_CPU1_SA_CB<1>")
	)
	(segment
		(start 83.289648 -245.62181)
		(end 83.29803 -245.616984)
		(width 0.0889)
		(layer "In4.Cu")
		(net "M_D_CPU1_SA_CB<1>")
	)
	(segment
		(start 48.598836 -236.470444)
		(end 48.829214 -236.470444)
		(width 0.14478)
		(layer "In4.Cu")
		(net "M_D_CPU1_SA_CB<1>")
	)
	(segment
		(start 53.08346 -236.01045)
		(end 53.23459 -236.01045)
		(width 0.14478)
		(layer "In4.Cu")
		(net "M_D_CPU1_SA_CB<1>")
	)
	(segment
		(start 46.834298 -236.615986)
		(end 47.141384 -236.615986)
		(width 0.14478)
		(layer "In4.Cu")
		(net "M_D_CPU1_SA_CB<1>")
	)
	(segment
		(start 42.733214 -236.01045)
		(end 43.054524 -236.01045)
		(width 0.14478)
		(layer "In4.Cu")
		(net "M_D_CPU1_SA_CB<1>")
	)
	(segment
		(start 56.049418 -237.252764)
		(end 56.212486 -237.089696)
		(width 0.14478)
		(layer "In4.Cu")
		(net "M_D_CPU1_SA_CB<1>")
	)
	(segment
		(start 39.732204 -236.860334)
		(end 40.801544 -236.860334)
		(width 0.14478)
		(layer "In4.Cu")
		(net "M_D_CPU1_SA_CB<1>")
	)
	(segment
		(start 57.648602 -236.860334)
		(end 57.94375 -236.565186)
		(width 0.14478)
		(layer "In4.Cu")
		(net "M_D_CPU1_SA_CB<1>")
	)
	(segment
		(start 58.495184 -236.860334)
		(end 59.000644 -236.860334)
		(width 0.14478)
		(layer "In4.Cu")
		(net "M_D_CPU1_SA_CB<1>")
	)
	(segment
		(start 51.273202 -236.236256)
		(end 51.273202 -236.173518)
		(width 0.14478)
		(layer "In4.Cu")
		(net "M_D_CPU1_SA_CB<1>")
	)
	(segment
		(start 56.212486 -237.023402)
		(end 56.375554 -236.860334)
		(width 0.14478)
		(layer "In4.Cu")
		(net "M_D_CPU1_SA_CB<1>")
	)
	(segment
		(start 52.532026 -235.770166)
		(end 52.843176 -235.770166)
		(width 0.14478)
		(layer "In4.Cu")
		(net "M_D_CPU1_SA_CB<1>")
	)
	(segment
		(start 84.803996 -245.616984)
		(end 84.812378 -245.62181)
		(width 0.0889)
		(layer "In4.Cu")
		(net "M_D_CPU1_SA_CB<1>")
	)
	(segment
		(start 39.569136 -237.089696)
		(end 39.569136 -237.023402)
		(width 0.14478)
		(layer "In4.Cu")
		(net "M_D_CPU1_SA_CB<1>")
	)
	(segment
		(start 56.545734 -236.860334)
		(end 56.840882 -236.565186)
		(width 0.14478)
		(layer "In4.Cu")
		(net "M_D_CPU1_SA_CB<1>")
	)
	(segment
		(start 40.801544 -236.860334)
		(end 41.104312 -236.557566)
		(width 0.14478)
		(layer "In4.Cu")
		(net "M_D_CPU1_SA_CB<1>")
	)
	(segment
		(start 50.716688 -236.236256)
		(end 50.879756 -236.399324)
		(width 0.14478)
		(layer "In4.Cu")
		(net "M_D_CPU1_SA_CB<1>")
	)
	(segment
		(start 41.655746 -236.860334)
		(end 41.88333 -236.860334)
		(width 0.14478)
		(layer "In4.Cu")
		(net "M_D_CPU1_SA_CB<1>")
	)
	(segment
		(start 41.352978 -236.557566)
		(end 41.655746 -236.860334)
		(width 0.14478)
		(layer "In4.Cu")
		(net "M_D_CPU1_SA_CB<1>")
	)
	(segment
		(start 78.579472 -245.627144)
		(end 78.59776 -245.61673)
		(width 0.0889)
		(layer "In4.Cu")
		(net "M_D_CPU1_SA_CB<1>")
	)
	(segment
		(start 43.937174 -236.01045)
		(end 45.55871 -236.01045)
		(width 0.14478)
		(layer "In4.Cu")
		(net "M_D_CPU1_SA_CB<1>")
	)
	(segment
		(start 50.716688 -236.173518)
		(end 50.716688 -236.236256)
		(width 0.14478)
		(layer "In4.Cu")
		(net "M_D_CPU1_SA_CB<1>")
	)
	(segment
		(start 48.992282 -236.697266)
		(end 49.15535 -236.860334)
		(width 0.14478)
		(layer "In4.Cu")
		(net "M_D_CPU1_SA_CB<1>")
	)
	(segment
		(start 51.273202 -236.173518)
		(end 51.43627 -236.01045)
		(width 0.14478)
		(layer "In4.Cu")
		(net "M_D_CPU1_SA_CB<1>")
	)
	(segment
		(start 76.239116 -244.983254)
		(end 76.629768 -245.373906)
		(width 0.0889)
		(layer "In4.Cu")
		(net "M_D_CPU1_SA_CB<1>")
	)
	(segment
		(start 92.35694 -245.559834)
		(end 92.511118 -245.294404)
		(width 0.0889)
		(layer "In4.Cu")
		(net "M_D_CPU1_SA_CB<1>")
	)
	(segment
		(start 39.171372 -237.248446)
		(end 39.410386 -237.248446)
		(width 0.14478)
		(layer "In4.Cu")
		(net "M_D_CPU1_SA_CB<1>")
	)
	(segment
		(start 54.379876 -236.860334)
		(end 54.542944 -237.023402)
		(width 0.14478)
		(layer "In4.Cu")
		(net "M_D_CPU1_SA_CB<1>")
	)
	(segment
		(start 39.569136 -237.023402)
		(end 39.732204 -236.860334)
		(width 0.14478)
		(layer "In4.Cu")
		(net "M_D_CPU1_SA_CB<1>")
	)
	(segment
		(start 50.256694 -236.01045)
		(end 50.55362 -236.01045)
		(width 0.14478)
		(layer "In4.Cu")
		(net "M_D_CPU1_SA_CB<1>")
	)
	(segment
		(start 54.542944 -237.089696)
		(end 54.706012 -237.252764)
		(width 0.14478)
		(layer "In4.Cu")
		(net "M_D_CPU1_SA_CB<1>")
	)
	(segment
		(start 91.749626 -245.62181)
		(end 91.758008 -245.616984)
		(width 0.0889)
		(layer "In4.Cu")
		(net "M_D_CPU1_SA_CB<1>")
	)
	(segment
		(start 50.55362 -236.01045)
		(end 50.716688 -236.173518)
		(width 0.14478)
		(layer "In4.Cu")
		(net "M_D_CPU1_SA_CB<1>")
	)
	(segment
		(start 77.705204 -245.540784)
		(end 77.940408 -245.540784)
		(width 0.0889)
		(layer "In4.Cu")
		(net "M_D_CPU1_SA_CB<1>")
	)
	(segment
		(start 38.619176 -236.495844)
		(end 38.849554 -236.495844)
		(width 0.14478)
		(layer "In4.Cu")
		(net "M_D_CPU1_SA_CB<1>")
	)
	(segment
		(start 51.110134 -236.399324)
		(end 51.273202 -236.236256)
		(width 0.14478)
		(layer "In4.Cu")
		(net "M_D_CPU1_SA_CB<1>")
	)
	(arc
		(start 90.444066 -245.616984)
		(mid 90.63101 -245.667239)
		(end 90.817954 -245.616984)
		(width 0.0889)
		(layer "In4.Cu")
		(net "M_D_CPU1_SA_CB<1>")
	)
	(arc
		(start 81.984088 -245.616984)
		(mid 82.171032 -245.667239)
		(end 82.357976 -245.616984)
		(width 0.0889)
		(layer "In4.Cu")
		(net "M_D_CPU1_SA_CB<1>")
	)
	(arc
		(start 87.623904 -245.616984)
		(mid 87.806155 -245.667334)
		(end 87.989664 -245.62181)
		(width 0.0889)
		(layer "In4.Cu")
		(net "M_D_CPU1_SA_CB<1>")
	)
	(arc
		(start 86.118192 -245.616984)
		(mid 86.401148 -245.540807)
		(end 86.684104 -245.616984)
		(width 0.0889)
		(layer "In4.Cu")
		(net "M_D_CPU1_SA_CB<1>")
	)
	(arc
		(start 80.478122 -245.616984)
		(mid 80.761078 -245.540807)
		(end 81.044034 -245.616984)
		(width 0.0889)
		(layer "In4.Cu")
		(net "M_D_CPU1_SA_CB<1>")
	)
	(arc
		(start 91.383866 -245.616984)
		(mid 91.566117 -245.667334)
		(end 91.749626 -245.62181)
		(width 0.0889)
		(layer "In4.Cu")
		(net "M_D_CPU1_SA_CB<1>")
	)
	(arc
		(start 90.817954 -245.616984)
		(mid 91.10091 -245.540807)
		(end 91.383866 -245.616984)
		(width 0.0889)
		(layer "In4.Cu")
		(net "M_D_CPU1_SA_CB<1>")
	)
	(arc
		(start 89.512394 -245.62181)
		(mid 89.695902 -245.667304)
		(end 89.878154 -245.616984)
		(width 0.0889)
		(layer "In4.Cu")
		(net "M_D_CPU1_SA_CB<1>")
	)
	(arc
		(start 80.10398 -245.616984)
		(mid 80.286231 -245.667334)
		(end 80.46974 -245.62181)
		(width 0.0889)
		(layer "In4.Cu")
		(net "M_D_CPU1_SA_CB<1>")
	)
	(arc
		(start 87.057992 -245.616984)
		(mid 87.340948 -245.540807)
		(end 87.623904 -245.616984)
		(width 0.0889)
		(layer "In4.Cu")
		(net "M_D_CPU1_SA_CB<1>")
	)
	(arc
		(start 79.171546 -245.62181)
		(mid 79.355308 -245.667426)
		(end 79.537814 -245.616984)
		(width 0.0889)
		(layer "In4.Cu")
		(net "M_D_CPU1_SA_CB<1>")
	)
	(arc
		(start 89.878154 -245.616984)
		(mid 90.16111 -245.540807)
		(end 90.444066 -245.616984)
		(width 0.0889)
		(layer "In4.Cu")
		(net "M_D_CPU1_SA_CB<1>")
	)
	(arc
		(start 82.923888 -245.616984)
		(mid 83.106139 -245.667334)
		(end 83.289648 -245.62181)
		(width 0.0889)
		(layer "In4.Cu")
		(net "M_D_CPU1_SA_CB<1>")
	)
	(arc
		(start 83.29803 -245.616984)
		(mid 83.580986 -245.540807)
		(end 83.863942 -245.616984)
		(width 0.0889)
		(layer "In4.Cu")
		(net "M_D_CPU1_SA_CB<1>")
	)
	(arc
		(start 81.418176 -245.616984)
		(mid 81.701132 -245.540807)
		(end 81.984088 -245.616984)
		(width 0.0889)
		(layer "In4.Cu")
		(net "M_D_CPU1_SA_CB<1>")
	)
	(arc
		(start 82.357976 -245.616984)
		(mid 82.640932 -245.540807)
		(end 82.923888 -245.616984)
		(width 0.0889)
		(layer "In4.Cu")
		(net "M_D_CPU1_SA_CB<1>")
	)
	(arc
		(start 78.223618 -245.616984)
		(mid 78.400246 -245.667217)
		(end 78.579472 -245.627144)
		(width 0.0889)
		(layer "In4.Cu")
		(net "M_D_CPU1_SA_CB<1>")
	)
	(arc
		(start 77.940408 -245.540784)
		(mid 78.087065 -245.560121)
		(end 78.223618 -245.616984)
		(width 0.0889)
		(layer "In4.Cu")
		(net "M_D_CPU1_SA_CB<1>")
	)
	(arc
		(start 81.052416 -245.62181)
		(mid 81.235924 -245.667304)
		(end 81.418176 -245.616984)
		(width 0.0889)
		(layer "In4.Cu")
		(net "M_D_CPU1_SA_CB<1>")
	)
	(arc
		(start 85.752432 -245.62181)
		(mid 85.93594 -245.667304)
		(end 86.118192 -245.616984)
		(width 0.0889)
		(layer "In4.Cu")
		(net "M_D_CPU1_SA_CB<1>")
	)
	(arc
		(start 79.537814 -245.616984)
		(mid 79.814881 -245.540713)
		(end 80.093566 -245.610888)
		(width 0.0889)
		(layer "In4.Cu")
		(net "M_D_CPU1_SA_CB<1>")
	)
	(arc
		(start 91.758008 -245.616984)
		(mid 92.005604 -245.541806)
		(end 92.260674 -245.585234)
		(width 0.0889)
		(layer "In4.Cu")
		(net "M_D_CPU1_SA_CB<1>")
	)
	(arc
		(start 87.998046 -245.616984)
		(mid 88.281002 -245.540807)
		(end 88.563958 -245.616984)
		(width 0.0889)
		(layer "In4.Cu")
		(net "M_D_CPU1_SA_CB<1>")
	)
	(arc
		(start 78.603348 -245.613428)
		(mid 78.883737 -245.540759)
		(end 79.163164 -245.616984)
		(width 0.0889)
		(layer "In4.Cu")
		(net "M_D_CPU1_SA_CB<1>")
	)
	(arc
		(start 86.684104 -245.616984)
		(mid 86.871048 -245.667239)
		(end 87.057992 -245.616984)
		(width 0.0889)
		(layer "In4.Cu")
		(net "M_D_CPU1_SA_CB<1>")
	)
	(arc
		(start 84.238084 -245.616984)
		(mid 84.52104 -245.540807)
		(end 84.803996 -245.616984)
		(width 0.0889)
		(layer "In4.Cu")
		(net "M_D_CPU1_SA_CB<1>")
	)
	(arc
		(start 83.863942 -245.616984)
		(mid 84.046193 -245.667334)
		(end 84.229702 -245.62181)
		(width 0.0889)
		(layer "In4.Cu")
		(net "M_D_CPU1_SA_CB<1>")
	)
	(arc
		(start 88.563958 -245.616984)
		(mid 88.746209 -245.667334)
		(end 88.929718 -245.62181)
		(width 0.0889)
		(layer "In4.Cu")
		(net "M_D_CPU1_SA_CB<1>")
	)
	(arc
		(start 88.9381 -245.616984)
		(mid 89.221056 -245.540807)
		(end 89.504012 -245.616984)
		(width 0.0889)
		(layer "In4.Cu")
		(net "M_D_CPU1_SA_CB<1>")
	)
	(arc
		(start 85.178138 -245.616984)
		(mid 85.461094 -245.540807)
		(end 85.74405 -245.616984)
		(width 0.0889)
		(layer "In4.Cu")
		(net "M_D_CPU1_SA_CB<1>")
	)
	(arc
		(start 84.812378 -245.62181)
		(mid 84.995886 -245.667304)
		(end 85.178138 -245.616984)
		(width 0.0889)
		(layer "In4.Cu")
		(net "M_D_CPU1_SA_CB<1>")
	)
	(segment
		(start 91.568016 -244.750336)
		(end 91.10091 -244.484398)
		(width 0.10668)
		(layer "F.Cu")
		(net "M_D_CPU1_SA_CB<0>")
	)
	(segment
		(start 56.16321 -235.550964)
		(end 56.393588 -235.550964)
		(width 0.14478)
		(layer "In4.Cu")
		(net "M_D_CPU1_SA_CB<0>")
	)
	(segment
		(start 43.236642 -234.539536)
		(end 43.39971 -234.702604)
		(width 0.14478)
		(layer "In4.Cu")
		(net "M_D_CPU1_SA_CB<0>")
	)
	(segment
		(start 48.218852 -235.160312)
		(end 48.38192 -235.32338)
		(width 0.14478)
		(layer "In4.Cu")
		(net "M_D_CPU1_SA_CB<0>")
	)
	(segment
		(start 61.200284 -236.961426)
		(end 61.056774 -237.104936)
		(width 0.14478)
		(layer "In4.Cu")
		(net "M_D_CPU1_SA_CB<0>")
	)
	(segment
		(start 43.956224 -234.310428)
		(end 45.55871 -234.310428)
		(width 0.14478)
		(layer "In4.Cu")
		(net "M_D_CPU1_SA_CB<0>")
	)
	(segment
		(start 55.443628 -235.387896)
		(end 55.443628 -235.32338)
		(width 0.14478)
		(layer "In4.Cu")
		(net "M_D_CPU1_SA_CB<0>")
	)
	(segment
		(start 83.394042 -244.806978)
		(end 83.402424 -244.811804)
		(width 0.0889)
		(layer "In4.Cu")
		(net "M_D_CPU1_SA_CB<0>")
	)
	(segment
		(start 55.050182 -235.550964)
		(end 55.28056 -235.550964)
		(width 0.14478)
		(layer "In4.Cu")
		(net "M_D_CPU1_SA_CB<0>")
	)
	(segment
		(start 79.613252 -244.794278)
		(end 79.634842 -244.806724)
		(width 0.0889)
		(layer "In4.Cu")
		(net "M_D_CPU1_SA_CB<0>")
	)
	(segment
		(start 62.76086 -238.522002)
		(end 62.61735 -238.665512)
		(width 0.14478)
		(layer "In4.Cu")
		(net "M_D_CPU1_SA_CB<0>")
	)
	(segment
		(start 52.341526 -234.473496)
		(end 52.341526 -234.542076)
		(width 0.14478)
		(layer "In4.Cu")
		(net "M_D_CPU1_SA_CB<0>")
	)
	(segment
		(start 55.606696 -235.160312)
		(end 55.837074 -235.160312)
		(width 0.14478)
		(layer "In4.Cu")
		(net "M_D_CPU1_SA_CB<0>")
	)
	(segment
		(start 49.40681 -235.160312)
		(end 50.256694 -234.310428)
		(width 0.14478)
		(layer "In4.Cu")
		(net "M_D_CPU1_SA_CB<0>")
	)
	(segment
		(start 79.634842 -244.806724)
		(end 79.654908 -244.818154)
		(width 0.0889)
		(layer "In4.Cu")
		(net "M_D_CPU1_SA_CB<0>")
	)
	(segment
		(start 46.872144 -235.545884)
		(end 47.102522 -235.545884)
		(width 0.14478)
		(layer "In4.Cu")
		(net "M_D_CPU1_SA_CB<0>")
	)
	(segment
		(start 37.81552 -235.550964)
		(end 38.045898 -235.550964)
		(width 0.14478)
		(layer "In4.Cu")
		(net "M_D_CPU1_SA_CB<0>")
	)
	(segment
		(start 56.556656 -235.387896)
		(end 56.556656 -235.32338)
		(width 0.14478)
		(layer "In4.Cu")
		(net "M_D_CPU1_SA_CB<0>")
	)
	(segment
		(start 48.775366 -235.550964)
		(end 48.938434 -235.387896)
		(width 0.14478)
		(layer "In4.Cu")
		(net "M_D_CPU1_SA_CB<0>")
	)
	(segment
		(start 43.236642 -234.473496)
		(end 43.236642 -234.539536)
		(width 0.14478)
		(layer "In4.Cu")
		(net "M_D_CPU1_SA_CB<0>")
	)
	(segment
		(start 63.151004 -238.912146)
		(end 63.379096 -238.912146)
		(width 0.14478)
		(layer "In4.Cu")
		(net "M_D_CPU1_SA_CB<0>")
	)
	(segment
		(start 51.378866 -234.310428)
		(end 52.178458 -234.310428)
		(width 0.14478)
		(layer "In4.Cu")
		(net "M_D_CPU1_SA_CB<0>")
	)
	(segment
		(start 53.061108 -234.310428)
		(end 53.23459 -234.310428)
		(width 0.14478)
		(layer "In4.Cu")
		(net "M_D_CPU1_SA_CB<0>")
	)
	(segment
		(start 46.709076 -235.382816)
		(end 46.872144 -235.545884)
		(width 0.14478)
		(layer "In4.Cu")
		(net "M_D_CPU1_SA_CB<0>")
	)
	(segment
		(start 61.980572 -237.513622)
		(end 61.980572 -237.741714)
		(width 0.14478)
		(layer "In4.Cu")
		(net "M_D_CPU1_SA_CB<0>")
	)
	(segment
		(start 49.101502 -235.160312)
		(end 49.40681 -235.160312)
		(width 0.14478)
		(layer "In4.Cu")
		(net "M_D_CPU1_SA_CB<0>")
	)
	(segment
		(start 48.544988 -235.550964)
		(end 48.775366 -235.550964)
		(width 0.14478)
		(layer "In4.Cu")
		(net "M_D_CPU1_SA_CB<0>")
	)
	(segment
		(start 37.489384 -235.160312)
		(end 37.652452 -235.32338)
		(width 0.14478)
		(layer "In4.Cu")
		(net "M_D_CPU1_SA_CB<0>")
	)
	(segment
		(start 50.659284 -234.534456)
		(end 50.822352 -234.697524)
		(width 0.14478)
		(layer "In4.Cu")
		(net "M_D_CPU1_SA_CB<0>")
	)
	(segment
		(start 43.39971 -234.702604)
		(end 43.630088 -234.702604)
		(width 0.14478)
		(layer "In4.Cu")
		(net "M_D_CPU1_SA_CB<0>")
	)
	(segment
		(start 39.321994 -235.32338)
		(end 39.485062 -235.160312)
		(width 0.14478)
		(layer "In4.Cu")
		(net "M_D_CPU1_SA_CB<0>")
	)
	(segment
		(start 41.88333 -235.160312)
		(end 42.733214 -234.310428)
		(width 0.14478)
		(layer "In4.Cu")
		(net "M_D_CPU1_SA_CB<0>")
	)
	(segment
		(start 38.928548 -235.550964)
		(end 39.158926 -235.550964)
		(width 0.14478)
		(layer "In4.Cu")
		(net "M_D_CPU1_SA_CB<0>")
	)
	(segment
		(start 68.533518 -244.066568)
		(end 75.92441 -244.066568)
		(width 0.14478)
		(layer "In4.Cu")
		(net "M_D_CPU1_SA_CB<0>")
	)
	(segment
		(start 62.227206 -238.275622)
		(end 62.370716 -238.131858)
		(width 0.14478)
		(layer "In4.Cu")
		(net "M_D_CPU1_SA_CB<0>")
	)
	(segment
		(start 75.92441 -244.066568)
		(end 76.979526 -244.066568)
		(width 0.0889)
		(layer "In4.Cu")
		(net "M_D_CPU1_SA_CB<0>")
	)
	(segment
		(start 54.084474 -235.160312)
		(end 54.724046 -235.160312)
		(width 0.14478)
		(layer "In4.Cu")
		(net "M_D_CPU1_SA_CB<0>")
	)
	(segment
		(start 39.321994 -235.387896)
		(end 39.321994 -235.32338)
		(width 0.14478)
		(layer "In4.Cu")
		(net "M_D_CPU1_SA_CB<0>")
	)
	(segment
		(start 77.643228 -244.73027)
		(end 78.41107 -244.73027)
		(width 0.0889)
		(layer "In4.Cu")
		(net "M_D_CPU1_SA_CB<0>")
	)
	(segment
		(start 56.719724 -235.160312)
		(end 59.627262 -235.160312)
		(width 0.14478)
		(layer "In4.Cu")
		(net "M_D_CPU1_SA_CB<0>")
	)
	(segment
		(start 38.045898 -235.550964)
		(end 38.208966 -235.387896)
		(width 0.14478)
		(layer "In4.Cu")
		(net "M_D_CPU1_SA_CB<0>")
	)
	(segment
		(start 48.38192 -235.32338)
		(end 48.38192 -235.387896)
		(width 0.14478)
		(layer "In4.Cu")
		(net "M_D_CPU1_SA_CB<0>")
	)
	(segment
		(start 43.073574 -234.310428)
		(end 43.236642 -234.473496)
		(width 0.14478)
		(layer "In4.Cu")
		(net "M_D_CPU1_SA_CB<0>")
	)
	(segment
		(start 52.89804 -234.542076)
		(end 52.89804 -234.473496)
		(width 0.14478)
		(layer "In4.Cu")
		(net "M_D_CPU1_SA_CB<0>")
	)
	(segment
		(start 38.208966 -235.387896)
		(end 38.208966 -235.275374)
		(width 0.14478)
		(layer "In4.Cu")
		(net "M_D_CPU1_SA_CB<0>")
	)
	(segment
		(start 87.154004 -244.806978)
		(end 87.162386 -244.811804)
		(width 0.0889)
		(layer "In4.Cu")
		(net "M_D_CPU1_SA_CB<0>")
	)
	(segment
		(start 48.938434 -235.32338)
		(end 49.101502 -235.160312)
		(width 0.14478)
		(layer "In4.Cu")
		(net "M_D_CPU1_SA_CB<0>")
	)
	(segment
		(start 61.056774 -237.104936)
		(end 61.056774 -237.333282)
		(width 0.14478)
		(layer "In4.Cu")
		(net "M_D_CPU1_SA_CB<0>")
	)
	(segment
		(start 54.887114 -235.32338)
		(end 54.887114 -235.387896)
		(width 0.14478)
		(layer "In4.Cu")
		(net "M_D_CPU1_SA_CB<0>")
	)
	(segment
		(start 63.007494 -239.05591)
		(end 63.151004 -238.912146)
		(width 0.14478)
		(layer "In4.Cu")
		(net "M_D_CPU1_SA_CB<0>")
	)
	(segment
		(start 43.630088 -234.702604)
		(end 43.793156 -234.539536)
		(width 0.14478)
		(layer "In4.Cu")
		(net "M_D_CPU1_SA_CB<0>")
	)
	(segment
		(start 52.504594 -234.705144)
		(end 52.734972 -234.705144)
		(width 0.14478)
		(layer "In4.Cu")
		(net "M_D_CPU1_SA_CB<0>")
	)
	(segment
		(start 61.837062 -238.11357)
		(end 61.999114 -238.275622)
		(width 0.14478)
		(layer "In4.Cu")
		(net "M_D_CPU1_SA_CB<0>")
	)
	(segment
		(start 38.76548 -235.275374)
		(end 38.76548 -235.387896)
		(width 0.14478)
		(layer "In4.Cu")
		(net "M_D_CPU1_SA_CB<0>")
	)
	(segment
		(start 62.598808 -238.131858)
		(end 62.76086 -238.29391)
		(width 0.14478)
		(layer "In4.Cu")
		(net "M_D_CPU1_SA_CB<0>")
	)
	(segment
		(start 50.822352 -234.697524)
		(end 51.05273 -234.697524)
		(width 0.14478)
		(layer "In4.Cu")
		(net "M_D_CPU1_SA_CB<0>")
	)
	(segment
		(start 79.051658 -244.8179)
		(end 79.070454 -244.806978)
		(width 0.0889)
		(layer "In4.Cu")
		(net "M_D_CPU1_SA_CB<0>")
	)
	(segment
		(start 50.496216 -234.310428)
		(end 50.659284 -234.473496)
		(width 0.14478)
		(layer "In4.Cu")
		(net "M_D_CPU1_SA_CB<0>")
	)
	(segment
		(start 56.556656 -235.32338)
		(end 56.719724 -235.160312)
		(width 0.14478)
		(layer "In4.Cu")
		(net "M_D_CPU1_SA_CB<0>")
	)
	(segment
		(start 55.837074 -235.160312)
		(end 56.000142 -235.32338)
		(width 0.14478)
		(layer "In4.Cu")
		(net "M_D_CPU1_SA_CB<0>")
	)
	(segment
		(start 37.652452 -235.387896)
		(end 37.81552 -235.550964)
		(width 0.14478)
		(layer "In4.Cu")
		(net "M_D_CPU1_SA_CB<0>")
	)
	(segment
		(start 61.590428 -237.35157)
		(end 61.81852 -237.35157)
		(width 0.14478)
		(layer "In4.Cu")
		(net "M_D_CPU1_SA_CB<0>")
	)
	(segment
		(start 62.61735 -238.665512)
		(end 62.61735 -238.893858)
		(width 0.14478)
		(layer "In4.Cu")
		(net "M_D_CPU1_SA_CB<0>")
	)
	(segment
		(start 52.178458 -234.310428)
		(end 52.341526 -234.473496)
		(width 0.14478)
		(layer "In4.Cu")
		(net "M_D_CPU1_SA_CB<0>")
	)
	(segment
		(start 86.57971 -244.811804)
		(end 86.588092 -244.806978)
		(width 0.0889)
		(layer "In4.Cu")
		(net "M_D_CPU1_SA_CB<0>")
	)
	(segment
		(start 61.200284 -236.733334)
		(end 61.200284 -236.961426)
		(width 0.14478)
		(layer "In4.Cu")
		(net "M_D_CPU1_SA_CB<0>")
	)
	(segment
		(start 61.218826 -237.495334)
		(end 61.446918 -237.495334)
		(width 0.14478)
		(layer "In4.Cu")
		(net "M_D_CPU1_SA_CB<0>")
	)
	(segment
		(start 38.372034 -235.112306)
		(end 38.602412 -235.112306)
		(width 0.14478)
		(layer "In4.Cu")
		(net "M_D_CPU1_SA_CB<0>")
	)
	(segment
		(start 37.220906 -235.160312)
		(end 37.489384 -235.160312)
		(width 0.14478)
		(layer "In4.Cu")
		(net "M_D_CPU1_SA_CB<0>")
	)
	(segment
		(start 62.370716 -238.131858)
		(end 62.598808 -238.131858)
		(width 0.14478)
		(layer "In4.Cu")
		(net "M_D_CPU1_SA_CB<0>")
	)
	(segment
		(start 48.38192 -235.387896)
		(end 48.544988 -235.550964)
		(width 0.14478)
		(layer "In4.Cu")
		(net "M_D_CPU1_SA_CB<0>")
	)
	(segment
		(start 61.81852 -237.35157)
		(end 61.980572 -237.513622)
		(width 0.14478)
		(layer "In4.Cu")
		(net "M_D_CPU1_SA_CB<0>")
	)
	(segment
		(start 56.000142 -235.387896)
		(end 56.16321 -235.550964)
		(width 0.14478)
		(layer "In4.Cu")
		(net "M_D_CPU1_SA_CB<0>")
	)
	(segment
		(start 43.793156 -234.473496)
		(end 43.956224 -234.310428)
		(width 0.14478)
		(layer "In4.Cu")
		(net "M_D_CPU1_SA_CB<0>")
	)
	(segment
		(start 42.733214 -234.310428)
		(end 43.073574 -234.310428)
		(width 0.14478)
		(layer "In4.Cu")
		(net "M_D_CPU1_SA_CB<0>")
	)
	(segment
		(start 61.056774 -237.333282)
		(end 61.218826 -237.495334)
		(width 0.14478)
		(layer "In4.Cu")
		(net "M_D_CPU1_SA_CB<0>")
	)
	(segment
		(start 52.734972 -234.705144)
		(end 52.89804 -234.542076)
		(width 0.14478)
		(layer "In4.Cu")
		(net "M_D_CPU1_SA_CB<0>")
	)
	(segment
		(start 51.215798 -234.534456)
		(end 51.215798 -234.473496)
		(width 0.14478)
		(layer "In4.Cu")
		(net "M_D_CPU1_SA_CB<0>")
	)
	(segment
		(start 61.980572 -237.741714)
		(end 61.837062 -237.885224)
		(width 0.14478)
		(layer "In4.Cu")
		(net "M_D_CPU1_SA_CB<0>")
	)
	(segment
		(start 55.28056 -235.550964)
		(end 55.443628 -235.387896)
		(width 0.14478)
		(layer "In4.Cu")
		(net "M_D_CPU1_SA_CB<0>")
	)
	(segment
		(start 82.453988 -244.806978)
		(end 82.46237 -244.811804)
		(width 0.0889)
		(layer "In4.Cu")
		(net "M_D_CPU1_SA_CB<0>")
	)
	(segment
		(start 53.23459 -234.310428)
		(end 54.084474 -235.160312)
		(width 0.14478)
		(layer "In4.Cu")
		(net "M_D_CPU1_SA_CB<0>")
	)
	(segment
		(start 81.879694 -244.811804)
		(end 81.888076 -244.806978)
		(width 0.0889)
		(layer "In4.Cu")
		(net "M_D_CPU1_SA_CB<0>")
	)
	(segment
		(start 45.55871 -234.310428)
		(end 46.408594 -235.160312)
		(width 0.14478)
		(layer "In4.Cu")
		(net "M_D_CPU1_SA_CB<0>")
	)
	(segment
		(start 47.26559 -235.32338)
		(end 47.428658 -235.160312)
		(width 0.14478)
		(layer "In4.Cu")
		(net "M_D_CPU1_SA_CB<0>")
	)
	(segment
		(start 62.76086 -238.29391)
		(end 62.76086 -238.522002)
		(width 0.14478)
		(layer "In4.Cu")
		(net "M_D_CPU1_SA_CB<0>")
	)
	(segment
		(start 88.094058 -244.806978)
		(end 88.10244 -244.811804)
		(width 0.0889)
		(layer "In4.Cu")
		(net "M_D_CPU1_SA_CB<0>")
	)
	(segment
		(start 62.779402 -239.05591)
		(end 63.007494 -239.05591)
		(width 0.14478)
		(layer "In4.Cu")
		(net "M_D_CPU1_SA_CB<0>")
	)
	(segment
		(start 38.76548 -235.387896)
		(end 38.928548 -235.550964)
		(width 0.14478)
		(layer "In4.Cu")
		(net "M_D_CPU1_SA_CB<0>")
	)
	(segment
		(start 63.379096 -238.912146)
		(end 68.533518 -244.066568)
		(width 0.14478)
		(layer "In4.Cu")
		(net "M_D_CPU1_SA_CB<0>")
	)
	(segment
		(start 43.793156 -234.539536)
		(end 43.793156 -234.473496)
		(width 0.14478)
		(layer "In4.Cu")
		(net "M_D_CPU1_SA_CB<0>")
	)
	(segment
		(start 50.256694 -234.310428)
		(end 50.496216 -234.310428)
		(width 0.14478)
		(layer "In4.Cu")
		(net "M_D_CPU1_SA_CB<0>")
	)
	(segment
		(start 48.938434 -235.387896)
		(end 48.938434 -235.32338)
		(width 0.14478)
		(layer "In4.Cu")
		(net "M_D_CPU1_SA_CB<0>")
	)
	(segment
		(start 52.341526 -234.542076)
		(end 52.504594 -234.705144)
		(width 0.14478)
		(layer "In4.Cu")
		(net "M_D_CPU1_SA_CB<0>")
	)
	(segment
		(start 56.393588 -235.550964)
		(end 56.556656 -235.387896)
		(width 0.14478)
		(layer "In4.Cu")
		(net "M_D_CPU1_SA_CB<0>")
	)
	(segment
		(start 47.102522 -235.545884)
		(end 47.26559 -235.382816)
		(width 0.14478)
		(layer "In4.Cu")
		(net "M_D_CPU1_SA_CB<0>")
	)
	(segment
		(start 37.652452 -235.32338)
		(end 37.652452 -235.387896)
		(width 0.14478)
		(layer "In4.Cu")
		(net "M_D_CPU1_SA_CB<0>")
	)
	(segment
		(start 55.443628 -235.32338)
		(end 55.606696 -235.160312)
		(width 0.14478)
		(layer "In4.Cu")
		(net "M_D_CPU1_SA_CB<0>")
	)
	(segment
		(start 59.627262 -235.160312)
		(end 61.200284 -236.733334)
		(width 0.14478)
		(layer "In4.Cu")
		(net "M_D_CPU1_SA_CB<0>")
	)
	(segment
		(start 39.158926 -235.550964)
		(end 39.321994 -235.387896)
		(width 0.14478)
		(layer "In4.Cu")
		(net "M_D_CPU1_SA_CB<0>")
	)
	(segment
		(start 61.999114 -238.275622)
		(end 62.227206 -238.275622)
		(width 0.14478)
		(layer "In4.Cu")
		(net "M_D_CPU1_SA_CB<0>")
	)
	(segment
		(start 39.485062 -235.160312)
		(end 41.88333 -235.160312)
		(width 0.14478)
		(layer "In4.Cu")
		(net "M_D_CPU1_SA_CB<0>")
	)
	(segment
		(start 46.546008 -235.160312)
		(end 46.709076 -235.32338)
		(width 0.14478)
		(layer "In4.Cu")
		(net "M_D_CPU1_SA_CB<0>")
	)
	(segment
		(start 61.446918 -237.495334)
		(end 61.590428 -237.35157)
		(width 0.14478)
		(layer "In4.Cu")
		(net "M_D_CPU1_SA_CB<0>")
	)
	(segment
		(start 46.408594 -235.160312)
		(end 46.546008 -235.160312)
		(width 0.14478)
		(layer "In4.Cu")
		(net "M_D_CPU1_SA_CB<0>")
	)
	(segment
		(start 46.709076 -235.32338)
		(end 46.709076 -235.382816)
		(width 0.14478)
		(layer "In4.Cu")
		(net "M_D_CPU1_SA_CB<0>")
	)
	(segment
		(start 54.887114 -235.387896)
		(end 55.050182 -235.550964)
		(width 0.14478)
		(layer "In4.Cu")
		(net "M_D_CPU1_SA_CB<0>")
	)
	(segment
		(start 36.795964 -234.73537)
		(end 37.220906 -235.160312)
		(width 0.14478)
		(layer "In4.Cu")
		(net "M_D_CPU1_SA_CB<0>")
	)
	(segment
		(start 76.979526 -244.066568)
		(end 77.643228 -244.73027)
		(width 0.0889)
		(layer "In4.Cu")
		(net "M_D_CPU1_SA_CB<0>")
	)
	(segment
		(start 51.05273 -234.697524)
		(end 51.215798 -234.534456)
		(width 0.14478)
		(layer "In4.Cu")
		(net "M_D_CPU1_SA_CB<0>")
	)
	(segment
		(start 50.659284 -234.473496)
		(end 50.659284 -234.534456)
		(width 0.14478)
		(layer "In4.Cu")
		(net "M_D_CPU1_SA_CB<0>")
	)
	(segment
		(start 90.339672 -244.811804)
		(end 90.348054 -244.806978)
		(width 0.0889)
		(layer "In4.Cu")
		(net "M_D_CPU1_SA_CB<0>")
	)
	(segment
		(start 85.639656 -244.811804)
		(end 85.648038 -244.806978)
		(width 0.0889)
		(layer "In4.Cu")
		(net "M_D_CPU1_SA_CB<0>")
	)
	(segment
		(start 51.215798 -234.473496)
		(end 51.378866 -234.310428)
		(width 0.14478)
		(layer "In4.Cu")
		(net "M_D_CPU1_SA_CB<0>")
	)
	(segment
		(start 62.61735 -238.893858)
		(end 62.779402 -239.05591)
		(width 0.14478)
		(layer "In4.Cu")
		(net "M_D_CPU1_SA_CB<0>")
	)
	(segment
		(start 38.208966 -235.275374)
		(end 38.372034 -235.112306)
		(width 0.14478)
		(layer "In4.Cu")
		(net "M_D_CPU1_SA_CB<0>")
	)
	(segment
		(start 56.000142 -235.32338)
		(end 56.000142 -235.387896)
		(width 0.14478)
		(layer "In4.Cu")
		(net "M_D_CPU1_SA_CB<0>")
	)
	(segment
		(start 54.724046 -235.160312)
		(end 54.887114 -235.32338)
		(width 0.14478)
		(layer "In4.Cu")
		(net "M_D_CPU1_SA_CB<0>")
	)
	(segment
		(start 52.89804 -234.473496)
		(end 53.061108 -234.310428)
		(width 0.14478)
		(layer "In4.Cu")
		(net "M_D_CPU1_SA_CB<0>")
	)
	(segment
		(start 47.26559 -235.382816)
		(end 47.26559 -235.32338)
		(width 0.14478)
		(layer "In4.Cu")
		(net "M_D_CPU1_SA_CB<0>")
	)
	(segment
		(start 38.602412 -235.112306)
		(end 38.76548 -235.275374)
		(width 0.14478)
		(layer "In4.Cu")
		(net "M_D_CPU1_SA_CB<0>")
	)
	(segment
		(start 90.946986 -244.749828)
		(end 91.10091 -244.484398)
		(width 0.0889)
		(layer "In4.Cu")
		(net "M_D_CPU1_SA_CB<0>")
	)
	(segment
		(start 90.850974 -244.775228)
		(end 90.946986 -244.749828)
		(width 0.0889)
		(layer "In4.Cu")
		(net "M_D_CPU1_SA_CB<0>")
	)
	(segment
		(start 47.428658 -235.160312)
		(end 48.218852 -235.160312)
		(width 0.14478)
		(layer "In4.Cu")
		(net "M_D_CPU1_SA_CB<0>")
	)
	(segment
		(start 61.837062 -237.885224)
		(end 61.837062 -238.11357)
		(width 0.14478)
		(layer "In4.Cu")
		(net "M_D_CPU1_SA_CB<0>")
	)
	(arc
		(start 83.768184 -244.806978)
		(mid 84.05114 -244.730801)
		(end 84.334096 -244.806978)
		(width 0.0889)
		(layer "In4.Cu")
		(net "M_D_CPU1_SA_CB<0>")
	)
	(arc
		(start 81.888076 -244.806978)
		(mid 82.171032 -244.730801)
		(end 82.453988 -244.806978)
		(width 0.0889)
		(layer "In4.Cu")
		(net "M_D_CPU1_SA_CB<0>")
	)
	(arc
		(start 81.513934 -244.806978)
		(mid 81.696185 -244.857328)
		(end 81.879694 -244.811804)
		(width 0.0889)
		(layer "In4.Cu")
		(net "M_D_CPU1_SA_CB<0>")
	)
	(arc
		(start 79.070454 -244.806978)
		(mid 79.340223 -244.730955)
		(end 79.613252 -244.794278)
		(width 0.0889)
		(layer "In4.Cu")
		(net "M_D_CPU1_SA_CB<0>")
	)
	(arc
		(start 84.707984 -244.806978)
		(mid 84.99094 -244.730801)
		(end 85.273896 -244.806978)
		(width 0.0889)
		(layer "In4.Cu")
		(net "M_D_CPU1_SA_CB<0>")
	)
	(arc
		(start 88.10244 -244.811804)
		(mid 88.285948 -244.857298)
		(end 88.4682 -244.806978)
		(width 0.0889)
		(layer "In4.Cu")
		(net "M_D_CPU1_SA_CB<0>")
	)
	(arc
		(start 89.408 -244.806978)
		(mid 89.690956 -244.730801)
		(end 89.973912 -244.806978)
		(width 0.0889)
		(layer "In4.Cu")
		(net "M_D_CPU1_SA_CB<0>")
	)
	(arc
		(start 86.21395 -244.806978)
		(mid 86.396201 -244.857328)
		(end 86.57971 -244.811804)
		(width 0.0889)
		(layer "In4.Cu")
		(net "M_D_CPU1_SA_CB<0>")
	)
	(arc
		(start 85.273896 -244.806978)
		(mid 85.456147 -244.857328)
		(end 85.639656 -244.811804)
		(width 0.0889)
		(layer "In4.Cu")
		(net "M_D_CPU1_SA_CB<0>")
	)
	(arc
		(start 78.41107 -244.73027)
		(mid 78.558279 -244.749747)
		(end 78.695296 -244.806978)
		(width 0.0889)
		(layer "In4.Cu")
		(net "M_D_CPU1_SA_CB<0>")
	)
	(arc
		(start 82.46237 -244.811804)
		(mid 82.645878 -244.857298)
		(end 82.82813 -244.806978)
		(width 0.0889)
		(layer "In4.Cu")
		(net "M_D_CPU1_SA_CB<0>")
	)
	(arc
		(start 83.402424 -244.811804)
		(mid 83.585932 -244.857298)
		(end 83.768184 -244.806978)
		(width 0.0889)
		(layer "In4.Cu")
		(net "M_D_CPU1_SA_CB<0>")
	)
	(arc
		(start 79.654908 -244.818154)
		(mid 79.832986 -244.857138)
		(end 80.008222 -244.806978)
		(width 0.0889)
		(layer "In4.Cu")
		(net "M_D_CPU1_SA_CB<0>")
	)
	(arc
		(start 82.82813 -244.806978)
		(mid 83.111086 -244.730801)
		(end 83.394042 -244.806978)
		(width 0.0889)
		(layer "In4.Cu")
		(net "M_D_CPU1_SA_CB<0>")
	)
	(arc
		(start 80.008222 -244.806978)
		(mid 80.291178 -244.730801)
		(end 80.574134 -244.806978)
		(width 0.0889)
		(layer "In4.Cu")
		(net "M_D_CPU1_SA_CB<0>")
	)
	(arc
		(start 86.588092 -244.806978)
		(mid 86.871048 -244.730801)
		(end 87.154004 -244.806978)
		(width 0.0889)
		(layer "In4.Cu")
		(net "M_D_CPU1_SA_CB<0>")
	)
	(arc
		(start 84.334096 -244.806978)
		(mid 84.52104 -244.857233)
		(end 84.707984 -244.806978)
		(width 0.0889)
		(layer "In4.Cu")
		(net "M_D_CPU1_SA_CB<0>")
	)
	(arc
		(start 88.4682 -244.806978)
		(mid 88.751156 -244.730801)
		(end 89.034112 -244.806978)
		(width 0.0889)
		(layer "In4.Cu")
		(net "M_D_CPU1_SA_CB<0>")
	)
	(arc
		(start 90.348054 -244.806978)
		(mid 90.595767 -244.731758)
		(end 90.850974 -244.775228)
		(width 0.0889)
		(layer "In4.Cu")
		(net "M_D_CPU1_SA_CB<0>")
	)
	(arc
		(start 87.528146 -244.806978)
		(mid 87.811102 -244.730801)
		(end 88.094058 -244.806978)
		(width 0.0889)
		(layer "In4.Cu")
		(net "M_D_CPU1_SA_CB<0>")
	)
	(arc
		(start 85.648038 -244.806978)
		(mid 85.930994 -244.730801)
		(end 86.21395 -244.806978)
		(width 0.0889)
		(layer "In4.Cu")
		(net "M_D_CPU1_SA_CB<0>")
	)
	(arc
		(start 87.162386 -244.811804)
		(mid 87.345894 -244.857298)
		(end 87.528146 -244.806978)
		(width 0.0889)
		(layer "In4.Cu")
		(net "M_D_CPU1_SA_CB<0>")
	)
	(arc
		(start 89.973912 -244.806978)
		(mid 90.156163 -244.857328)
		(end 90.339672 -244.811804)
		(width 0.0889)
		(layer "In4.Cu")
		(net "M_D_CPU1_SA_CB<0>")
	)
	(arc
		(start 78.695296 -244.806978)
		(mid 78.872087 -244.857697)
		(end 79.051658 -244.8179)
		(width 0.0889)
		(layer "In4.Cu")
		(net "M_D_CPU1_SA_CB<0>")
	)
	(arc
		(start 80.574134 -244.806978)
		(mid 80.761078 -244.857233)
		(end 80.948022 -244.806978)
		(width 0.0889)
		(layer "In4.Cu")
		(net "M_D_CPU1_SA_CB<0>")
	)
	(arc
		(start 80.948022 -244.806978)
		(mid 81.230978 -244.730801)
		(end 81.513934 -244.806978)
		(width 0.0889)
		(layer "In4.Cu")
		(net "M_D_CPU1_SA_CB<0>")
	)
	(arc
		(start 89.034112 -244.806978)
		(mid 89.221056 -244.857233)
		(end 89.408 -244.806978)
		(width 0.0889)
		(layer "In4.Cu")
		(net "M_D_CPU1_SA_CB<0>")
	)
	(segment
		(start 92.97797 -255.280414)
		(end 92.511118 -255.014476)
		(width 0.10668)
		(layer "F.Cu")
		(net "M_D_CPU1_SA_CA<6>")
	)
	(segment
		(start 92.260674 -255.305306)
		(end 92.35694 -255.279906)
		(width 0.0889)
		(layer "In4.Cu")
		(net "M_D_CPU1_SA_CA<6>")
	)
	(segment
		(start 37.418264 -254.172974)
		(end 37.648896 -254.173228)
		(width 0.14478)
		(layer "In4.Cu")
		(net "M_D_CPU1_SA_CA<6>")
	)
	(segment
		(start 84.803996 -255.337056)
		(end 84.812378 -255.341882)
		(width 0.0889)
		(layer "In4.Cu")
		(net "M_D_CPU1_SA_CA<6>")
	)
	(segment
		(start 85.74405 -255.337056)
		(end 85.752432 -255.341882)
		(width 0.0889)
		(layer "In4.Cu")
		(net "M_D_CPU1_SA_CA<6>")
	)
	(segment
		(start 91.749626 -255.341882)
		(end 91.758008 -255.337056)
		(width 0.0889)
		(layer "In4.Cu")
		(net "M_D_CPU1_SA_CA<6>")
	)
	(segment
		(start 37.648896 -254.173228)
		(end 37.901118 -253.921006)
		(width 0.14478)
		(layer "In4.Cu")
		(net "M_D_CPU1_SA_CA<6>")
	)
	(segment
		(start 71.828152 -254.645414)
		(end 72.865742 -255.683004)
		(width 0.14478)
		(layer "In4.Cu")
		(net "M_D_CPU1_SA_CA<6>")
	)
	(segment
		(start 37.901118 -253.921006)
		(end 38.13175 -253.921006)
		(width 0.14478)
		(layer "In4.Cu")
		(net "M_D_CPU1_SA_CA<6>")
	)
	(segment
		(start 92.35694 -255.279906)
		(end 92.511118 -255.014476)
		(width 0.0889)
		(layer "In4.Cu")
		(net "M_D_CPU1_SA_CA<6>")
	)
	(segment
		(start 60.66917 -254.645414)
		(end 71.828152 -254.645414)
		(width 0.14478)
		(layer "In4.Cu")
		(net "M_D_CPU1_SA_CA<6>")
	)
	(segment
		(start 36.795964 -252.58522)
		(end 37.507672 -253.296928)
		(width 0.14478)
		(layer "In4.Cu")
		(net "M_D_CPU1_SA_CA<6>")
	)
	(segment
		(start 81.044034 -255.337056)
		(end 81.052416 -255.341882)
		(width 0.0889)
		(layer "In4.Cu")
		(net "M_D_CPU1_SA_CA<6>")
	)
	(segment
		(start 38.042596 -254.797306)
		(end 38.205664 -254.960374)
		(width 0.14478)
		(layer "In4.Cu")
		(net "M_D_CPU1_SA_CA<6>")
	)
	(segment
		(start 76.001626 -255.683004)
		(end 77.157072 -255.683004)
		(width 0.0889)
		(layer "In4.Cu")
		(net "M_D_CPU1_SA_CA<6>")
	)
	(segment
		(start 37.507418 -253.527052)
		(end 37.255196 -253.779274)
		(width 0.14478)
		(layer "In4.Cu")
		(net "M_D_CPU1_SA_CA<6>")
	)
	(segment
		(start 38.686486 -254.710438)
		(end 60.604146 -254.710438)
		(width 0.14478)
		(layer "In4.Cu")
		(net "M_D_CPU1_SA_CA<6>")
	)
	(segment
		(start 88.929718 -255.341882)
		(end 88.9381 -255.337056)
		(width 0.0889)
		(layer "In4.Cu")
		(net "M_D_CPU1_SA_CA<6>")
	)
	(segment
		(start 38.13175 -253.921006)
		(end 38.295072 -254.084328)
		(width 0.14478)
		(layer "In4.Cu")
		(net "M_D_CPU1_SA_CA<6>")
	)
	(segment
		(start 72.865742 -255.683004)
		(end 76.001626 -255.683004)
		(width 0.14478)
		(layer "In4.Cu")
		(net "M_D_CPU1_SA_CA<6>")
	)
	(segment
		(start 89.504012 -255.337056)
		(end 89.512394 -255.341882)
		(width 0.0889)
		(layer "In4.Cu")
		(net "M_D_CPU1_SA_CA<6>")
	)
	(segment
		(start 78.59776 -255.336802)
		(end 78.603348 -255.3335)
		(width 0.0889)
		(layer "In4.Cu")
		(net "M_D_CPU1_SA_CA<6>")
	)
	(segment
		(start 38.436296 -254.960628)
		(end 38.686486 -254.710438)
		(width 0.14478)
		(layer "In4.Cu")
		(net "M_D_CPU1_SA_CA<6>")
	)
	(segment
		(start 37.255196 -253.779274)
		(end 37.255196 -254.009906)
		(width 0.14478)
		(layer "In4.Cu")
		(net "M_D_CPU1_SA_CA<6>")
	)
	(segment
		(start 38.205664 -254.960374)
		(end 38.436296 -254.960628)
		(width 0.14478)
		(layer "In4.Cu")
		(net "M_D_CPU1_SA_CA<6>")
	)
	(segment
		(start 37.507672 -253.296928)
		(end 37.507418 -253.527052)
		(width 0.14478)
		(layer "In4.Cu")
		(net "M_D_CPU1_SA_CA<6>")
	)
	(segment
		(start 38.295072 -254.084328)
		(end 38.294818 -254.314452)
		(width 0.14478)
		(layer "In4.Cu")
		(net "M_D_CPU1_SA_CA<6>")
	)
	(segment
		(start 38.294818 -254.314452)
		(end 38.042596 -254.566674)
		(width 0.14478)
		(layer "In4.Cu")
		(net "M_D_CPU1_SA_CA<6>")
	)
	(segment
		(start 80.093566 -255.33096)
		(end 80.10398 -255.337056)
		(width 0.0889)
		(layer "In4.Cu")
		(net "M_D_CPU1_SA_CA<6>")
	)
	(segment
		(start 38.042596 -254.566674)
		(end 38.042596 -254.797306)
		(width 0.14478)
		(layer "In4.Cu")
		(net "M_D_CPU1_SA_CA<6>")
	)
	(segment
		(start 83.289648 -255.341882)
		(end 83.29803 -255.337056)
		(width 0.0889)
		(layer "In4.Cu")
		(net "M_D_CPU1_SA_CA<6>")
	)
	(segment
		(start 77.452474 -255.387602)
		(end 78.410816 -255.387602)
		(width 0.0889)
		(layer "In4.Cu")
		(net "M_D_CPU1_SA_CA<6>")
	)
	(segment
		(start 79.163164 -255.337056)
		(end 79.171546 -255.341882)
		(width 0.0889)
		(layer "In4.Cu")
		(net "M_D_CPU1_SA_CA<6>")
	)
	(segment
		(start 77.157072 -255.683004)
		(end 77.452474 -255.387602)
		(width 0.0889)
		(layer "In4.Cu")
		(net "M_D_CPU1_SA_CA<6>")
	)
	(segment
		(start 80.46974 -255.341882)
		(end 80.478122 -255.337056)
		(width 0.0889)
		(layer "In4.Cu")
		(net "M_D_CPU1_SA_CA<6>")
	)
	(segment
		(start 84.229702 -255.341882)
		(end 84.238084 -255.337056)
		(width 0.0889)
		(layer "In4.Cu")
		(net "M_D_CPU1_SA_CA<6>")
	)
	(segment
		(start 37.255196 -254.009906)
		(end 37.418264 -254.172974)
		(width 0.14478)
		(layer "In4.Cu")
		(net "M_D_CPU1_SA_CA<6>")
	)
	(segment
		(start 87.989664 -255.341882)
		(end 87.998046 -255.337056)
		(width 0.0889)
		(layer "In4.Cu")
		(net "M_D_CPU1_SA_CA<6>")
	)
	(segment
		(start 60.604146 -254.710438)
		(end 60.66917 -254.645414)
		(width 0.14478)
		(layer "In4.Cu")
		(net "M_D_CPU1_SA_CA<6>")
	)
	(arc
		(start 84.238084 -255.337056)
		(mid 84.52104 -255.260879)
		(end 84.803996 -255.337056)
		(width 0.0889)
		(layer "In4.Cu")
		(net "M_D_CPU1_SA_CA<6>")
	)
	(arc
		(start 91.383866 -255.337056)
		(mid 91.566117 -255.387406)
		(end 91.749626 -255.341882)
		(width 0.0889)
		(layer "In4.Cu")
		(net "M_D_CPU1_SA_CA<6>")
	)
	(arc
		(start 88.563958 -255.337056)
		(mid 88.746209 -255.387406)
		(end 88.929718 -255.341882)
		(width 0.0889)
		(layer "In4.Cu")
		(net "M_D_CPU1_SA_CA<6>")
	)
	(arc
		(start 86.684104 -255.337056)
		(mid 86.871048 -255.387311)
		(end 87.057992 -255.337056)
		(width 0.0889)
		(layer "In4.Cu")
		(net "M_D_CPU1_SA_CA<6>")
	)
	(arc
		(start 90.817954 -255.337056)
		(mid 91.10091 -255.260879)
		(end 91.383866 -255.337056)
		(width 0.0889)
		(layer "In4.Cu")
		(net "M_D_CPU1_SA_CA<6>")
	)
	(arc
		(start 90.444066 -255.337056)
		(mid 90.63101 -255.387311)
		(end 90.817954 -255.337056)
		(width 0.0889)
		(layer "In4.Cu")
		(net "M_D_CPU1_SA_CA<6>")
	)
	(arc
		(start 88.9381 -255.337056)
		(mid 89.221056 -255.260879)
		(end 89.504012 -255.337056)
		(width 0.0889)
		(layer "In4.Cu")
		(net "M_D_CPU1_SA_CA<6>")
	)
	(arc
		(start 80.10398 -255.337056)
		(mid 80.286231 -255.387406)
		(end 80.46974 -255.341882)
		(width 0.0889)
		(layer "In4.Cu")
		(net "M_D_CPU1_SA_CA<6>")
	)
	(arc
		(start 81.984088 -255.337056)
		(mid 82.171032 -255.387311)
		(end 82.357976 -255.337056)
		(width 0.0889)
		(layer "In4.Cu")
		(net "M_D_CPU1_SA_CA<6>")
	)
	(arc
		(start 87.998046 -255.337056)
		(mid 88.281002 -255.260879)
		(end 88.563958 -255.337056)
		(width 0.0889)
		(layer "In4.Cu")
		(net "M_D_CPU1_SA_CA<6>")
	)
	(arc
		(start 81.052416 -255.341882)
		(mid 81.235924 -255.387376)
		(end 81.418176 -255.337056)
		(width 0.0889)
		(layer "In4.Cu")
		(net "M_D_CPU1_SA_CA<6>")
	)
	(arc
		(start 81.418176 -255.337056)
		(mid 81.701132 -255.260879)
		(end 81.984088 -255.337056)
		(width 0.0889)
		(layer "In4.Cu")
		(net "M_D_CPU1_SA_CA<6>")
	)
	(arc
		(start 80.478122 -255.337056)
		(mid 80.761078 -255.260879)
		(end 81.044034 -255.337056)
		(width 0.0889)
		(layer "In4.Cu")
		(net "M_D_CPU1_SA_CA<6>")
	)
	(arc
		(start 83.29803 -255.337056)
		(mid 83.580986 -255.260879)
		(end 83.863942 -255.337056)
		(width 0.0889)
		(layer "In4.Cu")
		(net "M_D_CPU1_SA_CA<6>")
	)
	(arc
		(start 87.623904 -255.337056)
		(mid 87.806155 -255.387406)
		(end 87.989664 -255.341882)
		(width 0.0889)
		(layer "In4.Cu")
		(net "M_D_CPU1_SA_CA<6>")
	)
	(arc
		(start 83.863942 -255.337056)
		(mid 84.046193 -255.387406)
		(end 84.229702 -255.341882)
		(width 0.0889)
		(layer "In4.Cu")
		(net "M_D_CPU1_SA_CA<6>")
	)
	(arc
		(start 78.603348 -255.3335)
		(mid 78.883737 -255.260831)
		(end 79.163164 -255.337056)
		(width 0.0889)
		(layer "In4.Cu")
		(net "M_D_CPU1_SA_CA<6>")
	)
	(arc
		(start 91.758008 -255.337056)
		(mid 92.005604 -255.261878)
		(end 92.260674 -255.305306)
		(width 0.0889)
		(layer "In4.Cu")
		(net "M_D_CPU1_SA_CA<6>")
	)
	(arc
		(start 86.118192 -255.337056)
		(mid 86.401148 -255.260879)
		(end 86.684104 -255.337056)
		(width 0.0889)
		(layer "In4.Cu")
		(net "M_D_CPU1_SA_CA<6>")
	)
	(arc
		(start 89.878154 -255.337056)
		(mid 90.16111 -255.260879)
		(end 90.444066 -255.337056)
		(width 0.0889)
		(layer "In4.Cu")
		(net "M_D_CPU1_SA_CA<6>")
	)
	(arc
		(start 85.178138 -255.337056)
		(mid 85.461094 -255.260879)
		(end 85.74405 -255.337056)
		(width 0.0889)
		(layer "In4.Cu")
		(net "M_D_CPU1_SA_CA<6>")
	)
	(arc
		(start 78.410816 -255.387602)
		(mid 78.507634 -255.374531)
		(end 78.59776 -255.336802)
		(width 0.0889)
		(layer "In4.Cu")
		(net "M_D_CPU1_SA_CA<6>")
	)
	(arc
		(start 82.357976 -255.337056)
		(mid 82.640932 -255.260879)
		(end 82.923888 -255.337056)
		(width 0.0889)
		(layer "In4.Cu")
		(net "M_D_CPU1_SA_CA<6>")
	)
	(arc
		(start 85.752432 -255.341882)
		(mid 85.93594 -255.387376)
		(end 86.118192 -255.337056)
		(width 0.0889)
		(layer "In4.Cu")
		(net "M_D_CPU1_SA_CA<6>")
	)
	(arc
		(start 84.812378 -255.341882)
		(mid 84.995886 -255.387376)
		(end 85.178138 -255.337056)
		(width 0.0889)
		(layer "In4.Cu")
		(net "M_D_CPU1_SA_CA<6>")
	)
	(arc
		(start 79.537814 -255.337056)
		(mid 79.814881 -255.260785)
		(end 80.093566 -255.33096)
		(width 0.0889)
		(layer "In4.Cu")
		(net "M_D_CPU1_SA_CA<6>")
	)
	(arc
		(start 87.057992 -255.337056)
		(mid 87.340948 -255.260879)
		(end 87.623904 -255.337056)
		(width 0.0889)
		(layer "In4.Cu")
		(net "M_D_CPU1_SA_CA<6>")
	)
	(arc
		(start 79.171546 -255.341882)
		(mid 79.355308 -255.387498)
		(end 79.537814 -255.337056)
		(width 0.0889)
		(layer "In4.Cu")
		(net "M_D_CPU1_SA_CA<6>")
	)
	(arc
		(start 89.512394 -255.341882)
		(mid 89.695902 -255.387376)
		(end 89.878154 -255.337056)
		(width 0.0889)
		(layer "In4.Cu")
		(net "M_D_CPU1_SA_CA<6>")
	)
	(arc
		(start 82.923888 -255.337056)
		(mid 83.106139 -255.387406)
		(end 83.289648 -255.341882)
		(width 0.0889)
		(layer "In4.Cu")
		(net "M_D_CPU1_SA_CA<6>")
	)
	(segment
		(start 91.097862 -255.280414)
		(end 90.63101 -255.014476)
		(width 0.10668)
		(layer "F.Cu")
		(net "M_D_CPU1_SA_CA<5>")
	)
	(segment
		(start 84.803996 -254.691896)
		(end 84.812378 -254.68707)
		(width 0.0889)
		(layer "In4.Cu")
		(net "M_D_CPU1_SA_CA<5>")
	)
	(segment
		(start 37.156898 -252.160278)
		(end 38.85692 -253.8603)
		(width 0.14478)
		(layer "In4.Cu")
		(net "M_D_CPU1_SA_CA<5>")
	)
	(segment
		(start 83.289648 -254.68707)
		(end 83.29803 -254.691896)
		(width 0.0889)
		(layer "In4.Cu")
		(net "M_D_CPU1_SA_CA<5>")
	)
	(segment
		(start 90.762582 -254.665734)
		(end 90.784934 -254.749046)
		(width 0.0889)
		(layer "In4.Cu")
		(net "M_D_CPU1_SA_CA<5>")
	)
	(segment
		(start 58.655712 -254.195834)
		(end 72.0217 -254.195834)
		(width 0.14478)
		(layer "In4.Cu")
		(net "M_D_CPU1_SA_CA<5>")
	)
	(segment
		(start 81.044034 -254.691896)
		(end 81.052416 -254.68707)
		(width 0.0889)
		(layer "In4.Cu")
		(net "M_D_CPU1_SA_CA<5>")
	)
	(segment
		(start 58.320178 -253.8603)
		(end 58.655712 -254.195834)
		(width 0.14478)
		(layer "In4.Cu")
		(net "M_D_CPU1_SA_CA<5>")
	)
	(segment
		(start 73.05167 -255.225804)
		(end 75.973686 -255.225804)
		(width 0.14478)
		(layer "In4.Cu")
		(net "M_D_CPU1_SA_CA<5>")
	)
	(segment
		(start 33.120838 -252.160278)
		(end 37.156898 -252.160278)
		(width 0.14478)
		(layer "In4.Cu")
		(net "M_D_CPU1_SA_CA<5>")
	)
	(segment
		(start 87.989664 -254.68707)
		(end 87.998046 -254.691896)
		(width 0.0889)
		(layer "In4.Cu")
		(net "M_D_CPU1_SA_CA<5>")
	)
	(segment
		(start 89.504012 -254.691896)
		(end 89.512394 -254.68707)
		(width 0.0889)
		(layer "In4.Cu")
		(net "M_D_CPU1_SA_CA<5>")
	)
	(segment
		(start 77.103732 -255.225804)
		(end 77.35697 -254.972566)
		(width 0.0889)
		(layer "In4.Cu")
		(net "M_D_CPU1_SA_CA<5>")
	)
	(segment
		(start 84.229702 -254.68707)
		(end 84.238084 -254.691896)
		(width 0.0889)
		(layer "In4.Cu")
		(net "M_D_CPU1_SA_CA<5>")
	)
	(segment
		(start 38.85692 -253.8603)
		(end 58.320178 -253.8603)
		(width 0.14478)
		(layer "In4.Cu")
		(net "M_D_CPU1_SA_CA<5>")
	)
	(segment
		(start 72.0217 -254.195834)
		(end 73.05167 -255.225804)
		(width 0.14478)
		(layer "In4.Cu")
		(net "M_D_CPU1_SA_CA<5>")
	)
	(segment
		(start 85.74405 -254.691896)
		(end 85.752432 -254.68707)
		(width 0.0889)
		(layer "In4.Cu")
		(net "M_D_CPU1_SA_CA<5>")
	)
	(segment
		(start 90.784934 -254.749046)
		(end 90.63101 -255.014476)
		(width 0.0889)
		(layer "In4.Cu")
		(net "M_D_CPU1_SA_CA<5>")
	)
	(segment
		(start 79.539592 -254.69215)
		(end 79.561182 -254.704596)
		(width 0.0889)
		(layer "In4.Cu")
		(net "M_D_CPU1_SA_CA<5>")
	)
	(segment
		(start 75.973686 -255.225804)
		(end 77.103732 -255.225804)
		(width 0.0889)
		(layer "In4.Cu")
		(net "M_D_CPU1_SA_CA<5>")
	)
	(segment
		(start 77.35697 -254.972566)
		(end 77.926692 -254.972566)
		(width 0.0889)
		(layer "In4.Cu")
		(net "M_D_CPU1_SA_CA<5>")
	)
	(segment
		(start 80.46974 -254.68707)
		(end 80.478122 -254.691896)
		(width 0.0889)
		(layer "In4.Cu")
		(net "M_D_CPU1_SA_CA<5>")
	)
	(segment
		(start 77.926692 -254.972566)
		(end 78.147926 -254.751332)
		(width 0.0889)
		(layer "In4.Cu")
		(net "M_D_CPU1_SA_CA<5>")
	)
	(segment
		(start 88.929718 -254.68707)
		(end 88.9381 -254.691896)
		(width 0.0889)
		(layer "In4.Cu")
		(net "M_D_CPU1_SA_CA<5>")
	)
	(segment
		(start 79.521304 -254.681736)
		(end 79.539592 -254.69215)
		(width 0.0889)
		(layer "In4.Cu")
		(net "M_D_CPU1_SA_CA<5>")
	)
	(segment
		(start 32.695896 -251.735336)
		(end 33.120838 -252.160278)
		(width 0.14478)
		(layer "In4.Cu")
		(net "M_D_CPU1_SA_CA<5>")
	)
	(segment
		(start 79.143098 -254.705612)
		(end 79.166466 -254.691896)
		(width 0.0889)
		(layer "In4.Cu")
		(net "M_D_CPU1_SA_CA<5>")
	)
	(segment
		(start 78.225142 -254.69215)
		(end 78.252574 -254.676402)
		(width 0.0889)
		(layer "In4.Cu")
		(net "M_D_CPU1_SA_CA<5>")
	)
	(arc
		(start 78.252574 -254.676402)
		(mid 78.427825 -254.641469)
		(end 78.599284 -254.691896)
		(width 0.0889)
		(layer "In4.Cu")
		(net "M_D_CPU1_SA_CA<5>")
	)
	(arc
		(start 81.052416 -254.68707)
		(mid 81.235924 -254.641576)
		(end 81.418176 -254.691896)
		(width 0.0889)
		(layer "In4.Cu")
		(net "M_D_CPU1_SA_CA<5>")
	)
	(arc
		(start 85.178138 -254.691896)
		(mid 85.461094 -254.768073)
		(end 85.74405 -254.691896)
		(width 0.0889)
		(layer "In4.Cu")
		(net "M_D_CPU1_SA_CA<5>")
	)
	(arc
		(start 84.812378 -254.68707)
		(mid 84.995886 -254.641576)
		(end 85.178138 -254.691896)
		(width 0.0889)
		(layer "In4.Cu")
		(net "M_D_CPU1_SA_CA<5>")
	)
	(arc
		(start 82.357976 -254.691896)
		(mid 82.640932 -254.768073)
		(end 82.923888 -254.691896)
		(width 0.0889)
		(layer "In4.Cu")
		(net "M_D_CPU1_SA_CA<5>")
	)
	(arc
		(start 80.478122 -254.691896)
		(mid 80.761078 -254.768073)
		(end 81.044034 -254.691896)
		(width 0.0889)
		(layer "In4.Cu")
		(net "M_D_CPU1_SA_CA<5>")
	)
	(arc
		(start 87.623904 -254.691896)
		(mid 87.806155 -254.641546)
		(end 87.989664 -254.68707)
		(width 0.0889)
		(layer "In4.Cu")
		(net "M_D_CPU1_SA_CA<5>")
	)
	(arc
		(start 89.512394 -254.68707)
		(mid 89.695902 -254.641576)
		(end 89.878154 -254.691896)
		(width 0.0889)
		(layer "In4.Cu")
		(net "M_D_CPU1_SA_CA<5>")
	)
	(arc
		(start 81.418176 -254.691896)
		(mid 81.701132 -254.768073)
		(end 81.984088 -254.691896)
		(width 0.0889)
		(layer "In4.Cu")
		(net "M_D_CPU1_SA_CA<5>")
	)
	(arc
		(start 85.752432 -254.68707)
		(mid 85.93594 -254.641576)
		(end 86.118192 -254.691896)
		(width 0.0889)
		(layer "In4.Cu")
		(net "M_D_CPU1_SA_CA<5>")
	)
	(arc
		(start 87.998046 -254.691896)
		(mid 88.281002 -254.768073)
		(end 88.563958 -254.691896)
		(width 0.0889)
		(layer "In4.Cu")
		(net "M_D_CPU1_SA_CA<5>")
	)
	(arc
		(start 82.923888 -254.691896)
		(mid 83.106139 -254.641546)
		(end 83.289648 -254.68707)
		(width 0.0889)
		(layer "In4.Cu")
		(net "M_D_CPU1_SA_CA<5>")
	)
	(arc
		(start 88.563958 -254.691896)
		(mid 88.746209 -254.641546)
		(end 88.929718 -254.68707)
		(width 0.0889)
		(layer "In4.Cu")
		(net "M_D_CPU1_SA_CA<5>")
	)
	(arc
		(start 84.238084 -254.691896)
		(mid 84.52104 -254.768073)
		(end 84.803996 -254.691896)
		(width 0.0889)
		(layer "In4.Cu")
		(net "M_D_CPU1_SA_CA<5>")
	)
	(arc
		(start 88.9381 -254.691896)
		(mid 89.221056 -254.768073)
		(end 89.504012 -254.691896)
		(width 0.0889)
		(layer "In4.Cu")
		(net "M_D_CPU1_SA_CA<5>")
	)
	(arc
		(start 87.057992 -254.691896)
		(mid 87.340948 -254.768073)
		(end 87.623904 -254.691896)
		(width 0.0889)
		(layer "In4.Cu")
		(net "M_D_CPU1_SA_CA<5>")
	)
	(arc
		(start 83.29803 -254.691896)
		(mid 83.580986 -254.768073)
		(end 83.863942 -254.691896)
		(width 0.0889)
		(layer "In4.Cu")
		(net "M_D_CPU1_SA_CA<5>")
	)
	(arc
		(start 86.118192 -254.691896)
		(mid 86.401148 -254.768073)
		(end 86.684104 -254.691896)
		(width 0.0889)
		(layer "In4.Cu")
		(net "M_D_CPU1_SA_CA<5>")
	)
	(arc
		(start 79.561182 -254.704596)
		(mid 79.834211 -254.767915)
		(end 80.10398 -254.691896)
		(width 0.0889)
		(layer "In4.Cu")
		(net "M_D_CPU1_SA_CA<5>")
	)
	(arc
		(start 79.166466 -254.691896)
		(mid 79.342586 -254.641918)
		(end 79.521304 -254.681736)
		(width 0.0889)
		(layer "In4.Cu")
		(net "M_D_CPU1_SA_CA<5>")
	)
	(arc
		(start 90.444066 -254.691896)
		(mid 90.600385 -254.642901)
		(end 90.762582 -254.665734)
		(width 0.0889)
		(layer "In4.Cu")
		(net "M_D_CPU1_SA_CA<5>")
	)
	(arc
		(start 81.984088 -254.691896)
		(mid 82.171032 -254.641641)
		(end 82.357976 -254.691896)
		(width 0.0889)
		(layer "In4.Cu")
		(net "M_D_CPU1_SA_CA<5>")
	)
	(arc
		(start 78.147926 -254.751332)
		(mid 78.184582 -254.719192)
		(end 78.225142 -254.69215)
		(width 0.0889)
		(layer "In4.Cu")
		(net "M_D_CPU1_SA_CA<5>")
	)
	(arc
		(start 78.599284 -254.691896)
		(mid 78.869441 -254.768658)
		(end 79.143098 -254.705612)
		(width 0.0889)
		(layer "In4.Cu")
		(net "M_D_CPU1_SA_CA<5>")
	)
	(arc
		(start 89.878154 -254.691896)
		(mid 90.16111 -254.768073)
		(end 90.444066 -254.691896)
		(width 0.0889)
		(layer "In4.Cu")
		(net "M_D_CPU1_SA_CA<5>")
	)
	(arc
		(start 86.684104 -254.691896)
		(mid 86.871048 -254.641641)
		(end 87.057992 -254.691896)
		(width 0.0889)
		(layer "In4.Cu")
		(net "M_D_CPU1_SA_CA<5>")
	)
	(arc
		(start 80.10398 -254.691896)
		(mid 80.286231 -254.641546)
		(end 80.46974 -254.68707)
		(width 0.0889)
		(layer "In4.Cu")
		(net "M_D_CPU1_SA_CA<5>")
	)
	(arc
		(start 83.863942 -254.691896)
		(mid 84.046193 -254.641546)
		(end 84.229702 -254.68707)
		(width 0.0889)
		(layer "In4.Cu")
		(net "M_D_CPU1_SA_CA<5>")
	)
	(segment
		(start 91.568016 -254.470408)
		(end 91.10091 -254.20447)
		(width 0.10668)
		(layer "F.Cu")
		(net "M_D_CPU1_SA_CA<4>")
	)
	(segment
		(start 76.451968 -254.839724)
		(end 77.088238 -254.839724)
		(width 0.0889)
		(layer "In4.Cu")
		(net "M_D_CPU1_SA_CA<4>")
	)
	(segment
		(start 83.394042 -254.52705)
		(end 83.402424 -254.531876)
		(width 0.0889)
		(layer "In4.Cu")
		(net "M_D_CPU1_SA_CA<4>")
	)
	(segment
		(start 40.912288 -253.010162)
		(end 41.075356 -253.17323)
		(width 0.14478)
		(layer "In4.Cu")
		(net "M_D_CPU1_SA_CA<4>")
	)
	(segment
		(start 86.57971 -254.531876)
		(end 86.588092 -254.52705)
		(width 0.0889)
		(layer "In4.Cu")
		(net "M_D_CPU1_SA_CA<4>")
	)
	(segment
		(start 49.648872 -253.010162)
		(end 49.87925 -253.010162)
		(width 0.14478)
		(layer "In4.Cu")
		(net "M_D_CPU1_SA_CA<4>")
	)
	(segment
		(start 52.928266 -253.010162)
		(end 53.091334 -253.17323)
		(width 0.14478)
		(layer "In4.Cu")
		(net "M_D_CPU1_SA_CA<4>")
	)
	(segment
		(start 46.473618 -253.17323)
		(end 46.473618 -253.239016)
		(width 0.14478)
		(layer "In4.Cu")
		(net "M_D_CPU1_SA_CA<4>")
	)
	(segment
		(start 42.907966 -253.010162)
		(end 45.197522 -253.010162)
		(width 0.14478)
		(layer "In4.Cu")
		(net "M_D_CPU1_SA_CA<4>")
	)
	(segment
		(start 42.744898 -253.239016)
		(end 42.744898 -253.17323)
		(width 0.14478)
		(layer "In4.Cu")
		(net "M_D_CPU1_SA_CA<4>")
	)
	(segment
		(start 46.080172 -253.010162)
		(end 46.31055 -253.010162)
		(width 0.14478)
		(layer "In4.Cu")
		(net "M_D_CPU1_SA_CA<4>")
	)
	(segment
		(start 60.556902 -253.746254)
		(end 72.255888 -253.746254)
		(width 0.14478)
		(layer "In4.Cu")
		(net "M_D_CPU1_SA_CA<4>")
	)
	(segment
		(start 85.639656 -254.531876)
		(end 85.648038 -254.52705)
		(width 0.0889)
		(layer "In4.Cu")
		(net "M_D_CPU1_SA_CA<4>")
	)
	(segment
		(start 53.48478 -253.399544)
		(end 53.647848 -253.236476)
		(width 0.14478)
		(layer "In4.Cu")
		(net "M_D_CPU1_SA_CA<4>")
	)
	(segment
		(start 73.270618 -254.760984)
		(end 76.263246 -254.760984)
		(width 0.14478)
		(layer "In4.Cu")
		(net "M_D_CPU1_SA_CA<4>")
	)
	(segment
		(start 50.7619 -253.010162)
		(end 52.928266 -253.010162)
		(width 0.14478)
		(layer "In4.Cu")
		(net "M_D_CPU1_SA_CA<4>")
	)
	(segment
		(start 90.946986 -254.4699)
		(end 91.10091 -254.20447)
		(width 0.0889)
		(layer "In4.Cu")
		(net "M_D_CPU1_SA_CA<4>")
	)
	(segment
		(start 88.094058 -254.52705)
		(end 88.10244 -254.531876)
		(width 0.0889)
		(layer "In4.Cu")
		(net "M_D_CPU1_SA_CA<4>")
	)
	(segment
		(start 41.075356 -253.239016)
		(end 41.238424 -253.402084)
		(width 0.14478)
		(layer "In4.Cu")
		(net "M_D_CPU1_SA_CA<4>")
	)
	(segment
		(start 45.197522 -253.010162)
		(end 45.36059 -253.17323)
		(width 0.14478)
		(layer "In4.Cu")
		(net "M_D_CPU1_SA_CA<4>")
	)
	(segment
		(start 53.254402 -253.399544)
		(end 53.48478 -253.399544)
		(width 0.14478)
		(layer "In4.Cu")
		(net "M_D_CPU1_SA_CA<4>")
	)
	(segment
		(start 53.647848 -253.17323)
		(end 53.810916 -253.010162)
		(width 0.14478)
		(layer "In4.Cu")
		(net "M_D_CPU1_SA_CA<4>")
	)
	(segment
		(start 53.647848 -253.236476)
		(end 53.647848 -253.17323)
		(width 0.14478)
		(layer "In4.Cu")
		(net "M_D_CPU1_SA_CA<4>")
	)
	(segment
		(start 50.205386 -253.402084)
		(end 50.435764 -253.402084)
		(width 0.14478)
		(layer "In4.Cu")
		(net "M_D_CPU1_SA_CA<4>")
	)
	(segment
		(start 49.87925 -253.010162)
		(end 50.042318 -253.17323)
		(width 0.14478)
		(layer "In4.Cu")
		(net "M_D_CPU1_SA_CA<4>")
	)
	(segment
		(start 46.31055 -253.010162)
		(end 46.473618 -253.17323)
		(width 0.14478)
		(layer "In4.Cu")
		(net "M_D_CPU1_SA_CA<4>")
	)
	(segment
		(start 45.523658 -253.402084)
		(end 45.754036 -253.402084)
		(width 0.14478)
		(layer "In4.Cu")
		(net "M_D_CPU1_SA_CA<4>")
	)
	(segment
		(start 76.263246 -254.760984)
		(end 76.373228 -254.760984)
		(width 0.0889)
		(layer "In4.Cu")
		(net "M_D_CPU1_SA_CA<4>")
	)
	(segment
		(start 79.634842 -254.526796)
		(end 79.654908 -254.538226)
		(width 0.0889)
		(layer "In4.Cu")
		(net "M_D_CPU1_SA_CA<4>")
	)
	(segment
		(start 42.58183 -253.402084)
		(end 42.744898 -253.239016)
		(width 0.14478)
		(layer "In4.Cu")
		(net "M_D_CPU1_SA_CA<4>")
	)
	(segment
		(start 81.879694 -254.531876)
		(end 81.888076 -254.52705)
		(width 0.0889)
		(layer "In4.Cu")
		(net "M_D_CPU1_SA_CA<4>")
	)
	(segment
		(start 41.238424 -253.402084)
		(end 41.468802 -253.402084)
		(width 0.14478)
		(layer "In4.Cu")
		(net "M_D_CPU1_SA_CA<4>")
	)
	(segment
		(start 90.339672 -254.531876)
		(end 90.348054 -254.52705)
		(width 0.0889)
		(layer "In4.Cu")
		(net "M_D_CPU1_SA_CA<4>")
	)
	(segment
		(start 49.092358 -253.402084)
		(end 49.322736 -253.402084)
		(width 0.14478)
		(layer "In4.Cu")
		(net "M_D_CPU1_SA_CA<4>")
	)
	(segment
		(start 50.042318 -253.17323)
		(end 50.042318 -253.239016)
		(width 0.14478)
		(layer "In4.Cu")
		(net "M_D_CPU1_SA_CA<4>")
	)
	(segment
		(start 49.485804 -253.239016)
		(end 49.485804 -253.17323)
		(width 0.14478)
		(layer "In4.Cu")
		(net "M_D_CPU1_SA_CA<4>")
	)
	(segment
		(start 45.36059 -253.239016)
		(end 45.523658 -253.402084)
		(width 0.14478)
		(layer "In4.Cu")
		(net "M_D_CPU1_SA_CA<4>")
	)
	(segment
		(start 45.754036 -253.402084)
		(end 45.917104 -253.239016)
		(width 0.14478)
		(layer "In4.Cu")
		(net "M_D_CPU1_SA_CA<4>")
	)
	(segment
		(start 46.473618 -253.239016)
		(end 46.636686 -253.402084)
		(width 0.14478)
		(layer "In4.Cu")
		(net "M_D_CPU1_SA_CA<4>")
	)
	(segment
		(start 78.129638 -254.526796)
		(end 78.161388 -254.508508)
		(width 0.0889)
		(layer "In4.Cu")
		(net "M_D_CPU1_SA_CA<4>")
	)
	(segment
		(start 47.1932 -253.010162)
		(end 48.766222 -253.010162)
		(width 0.14478)
		(layer "In4.Cu")
		(net "M_D_CPU1_SA_CA<4>")
	)
	(segment
		(start 45.917104 -253.17323)
		(end 46.080172 -253.010162)
		(width 0.14478)
		(layer "In4.Cu")
		(net "M_D_CPU1_SA_CA<4>")
	)
	(segment
		(start 77.217016 -254.710946)
		(end 77.918564 -254.710946)
		(width 0.0889)
		(layer "In4.Cu")
		(net "M_D_CPU1_SA_CA<4>")
	)
	(segment
		(start 87.154004 -254.52705)
		(end 87.162386 -254.531876)
		(width 0.0889)
		(layer "In4.Cu")
		(net "M_D_CPU1_SA_CA<4>")
	)
	(segment
		(start 59.82081 -253.010162)
		(end 60.556902 -253.746254)
		(width 0.14478)
		(layer "In4.Cu")
		(net "M_D_CPU1_SA_CA<4>")
	)
	(segment
		(start 50.435764 -253.402084)
		(end 50.598832 -253.239016)
		(width 0.14478)
		(layer "In4.Cu")
		(net "M_D_CPU1_SA_CA<4>")
	)
	(segment
		(start 46.867064 -253.402084)
		(end 47.030132 -253.239016)
		(width 0.14478)
		(layer "In4.Cu")
		(net "M_D_CPU1_SA_CA<4>")
	)
	(segment
		(start 76.373228 -254.760984)
		(end 76.451968 -254.839724)
		(width 0.0889)
		(layer "In4.Cu")
		(net "M_D_CPU1_SA_CA<4>")
	)
	(segment
		(start 48.92929 -253.17323)
		(end 48.92929 -253.239016)
		(width 0.14478)
		(layer "In4.Cu")
		(net "M_D_CPU1_SA_CA<4>")
	)
	(segment
		(start 42.188384 -253.17323)
		(end 42.188384 -253.239016)
		(width 0.14478)
		(layer "In4.Cu")
		(net "M_D_CPU1_SA_CA<4>")
	)
	(segment
		(start 41.468802 -253.402084)
		(end 41.63187 -253.239016)
		(width 0.14478)
		(layer "In4.Cu")
		(net "M_D_CPU1_SA_CA<4>")
	)
	(segment
		(start 49.322736 -253.402084)
		(end 49.485804 -253.239016)
		(width 0.14478)
		(layer "In4.Cu")
		(net "M_D_CPU1_SA_CA<4>")
	)
	(segment
		(start 50.598832 -253.17323)
		(end 50.7619 -253.010162)
		(width 0.14478)
		(layer "In4.Cu")
		(net "M_D_CPU1_SA_CA<4>")
	)
	(segment
		(start 41.63187 -253.239016)
		(end 41.63187 -253.17323)
		(width 0.14478)
		(layer "In4.Cu")
		(net "M_D_CPU1_SA_CA<4>")
	)
	(segment
		(start 90.850974 -254.4953)
		(end 90.946986 -254.4699)
		(width 0.0889)
		(layer "In4.Cu")
		(net "M_D_CPU1_SA_CA<4>")
	)
	(segment
		(start 46.636686 -253.402084)
		(end 46.867064 -253.402084)
		(width 0.14478)
		(layer "In4.Cu")
		(net "M_D_CPU1_SA_CA<4>")
	)
	(segment
		(start 41.63187 -253.17323)
		(end 41.794938 -253.010162)
		(width 0.14478)
		(layer "In4.Cu")
		(net "M_D_CPU1_SA_CA<4>")
	)
	(segment
		(start 50.042318 -253.239016)
		(end 50.205386 -253.402084)
		(width 0.14478)
		(layer "In4.Cu")
		(net "M_D_CPU1_SA_CA<4>")
	)
	(segment
		(start 48.92929 -253.239016)
		(end 49.092358 -253.402084)
		(width 0.14478)
		(layer "In4.Cu")
		(net "M_D_CPU1_SA_CA<4>")
	)
	(segment
		(start 41.075356 -253.17323)
		(end 41.075356 -253.239016)
		(width 0.14478)
		(layer "In4.Cu")
		(net "M_D_CPU1_SA_CA<4>")
	)
	(segment
		(start 49.485804 -253.17323)
		(end 49.648872 -253.010162)
		(width 0.14478)
		(layer "In4.Cu")
		(net "M_D_CPU1_SA_CA<4>")
	)
	(segment
		(start 36.795964 -250.885198)
		(end 38.920928 -253.010162)
		(width 0.14478)
		(layer "In4.Cu")
		(net "M_D_CPU1_SA_CA<4>")
	)
	(segment
		(start 41.794938 -253.010162)
		(end 42.025316 -253.010162)
		(width 0.14478)
		(layer "In4.Cu")
		(net "M_D_CPU1_SA_CA<4>")
	)
	(segment
		(start 42.744898 -253.17323)
		(end 42.907966 -253.010162)
		(width 0.14478)
		(layer "In4.Cu")
		(net "M_D_CPU1_SA_CA<4>")
	)
	(segment
		(start 42.188384 -253.239016)
		(end 42.351452 -253.402084)
		(width 0.14478)
		(layer "In4.Cu")
		(net "M_D_CPU1_SA_CA<4>")
	)
	(segment
		(start 45.917104 -253.239016)
		(end 45.917104 -253.17323)
		(width 0.14478)
		(layer "In4.Cu")
		(net "M_D_CPU1_SA_CA<4>")
	)
	(segment
		(start 72.255888 -253.746254)
		(end 73.270618 -254.760984)
		(width 0.14478)
		(layer "In4.Cu")
		(net "M_D_CPU1_SA_CA<4>")
	)
	(segment
		(start 38.920928 -253.010162)
		(end 40.912288 -253.010162)
		(width 0.14478)
		(layer "In4.Cu")
		(net "M_D_CPU1_SA_CA<4>")
	)
	(segment
		(start 79.613252 -254.51435)
		(end 79.634842 -254.526796)
		(width 0.0889)
		(layer "In4.Cu")
		(net "M_D_CPU1_SA_CA<4>")
	)
	(segment
		(start 77.918564 -254.710946)
		(end 78.013052 -254.616458)
		(width 0.0889)
		(layer "In4.Cu")
		(net "M_D_CPU1_SA_CA<4>")
	)
	(segment
		(start 82.453988 -254.52705)
		(end 82.46237 -254.531876)
		(width 0.0889)
		(layer "In4.Cu")
		(net "M_D_CPU1_SA_CA<4>")
	)
	(segment
		(start 53.810916 -253.010162)
		(end 59.82081 -253.010162)
		(width 0.14478)
		(layer "In4.Cu")
		(net "M_D_CPU1_SA_CA<4>")
	)
	(segment
		(start 42.025316 -253.010162)
		(end 42.188384 -253.17323)
		(width 0.14478)
		(layer "In4.Cu")
		(net "M_D_CPU1_SA_CA<4>")
	)
	(segment
		(start 42.351452 -253.402084)
		(end 42.58183 -253.402084)
		(width 0.14478)
		(layer "In4.Cu")
		(net "M_D_CPU1_SA_CA<4>")
	)
	(segment
		(start 47.030132 -253.239016)
		(end 47.030132 -253.17323)
		(width 0.14478)
		(layer "In4.Cu")
		(net "M_D_CPU1_SA_CA<4>")
	)
	(segment
		(start 47.030132 -253.17323)
		(end 47.1932 -253.010162)
		(width 0.14478)
		(layer "In4.Cu")
		(net "M_D_CPU1_SA_CA<4>")
	)
	(segment
		(start 45.36059 -253.17323)
		(end 45.36059 -253.239016)
		(width 0.14478)
		(layer "In4.Cu")
		(net "M_D_CPU1_SA_CA<4>")
	)
	(segment
		(start 79.051658 -254.537972)
		(end 79.070454 -254.52705)
		(width 0.0889)
		(layer "In4.Cu")
		(net "M_D_CPU1_SA_CA<4>")
	)
	(segment
		(start 53.091334 -253.236476)
		(end 53.254402 -253.399544)
		(width 0.14478)
		(layer "In4.Cu")
		(net "M_D_CPU1_SA_CA<4>")
	)
	(segment
		(start 53.091334 -253.17323)
		(end 53.091334 -253.236476)
		(width 0.14478)
		(layer "In4.Cu")
		(net "M_D_CPU1_SA_CA<4>")
	)
	(segment
		(start 50.598832 -253.239016)
		(end 50.598832 -253.17323)
		(width 0.14478)
		(layer "In4.Cu")
		(net "M_D_CPU1_SA_CA<4>")
	)
	(segment
		(start 77.088238 -254.839724)
		(end 77.217016 -254.710946)
		(width 0.0889)
		(layer "In4.Cu")
		(net "M_D_CPU1_SA_CA<4>")
	)
	(segment
		(start 48.766222 -253.010162)
		(end 48.92929 -253.17323)
		(width 0.14478)
		(layer "In4.Cu")
		(net "M_D_CPU1_SA_CA<4>")
	)
	(arc
		(start 85.648038 -254.52705)
		(mid 85.930994 -254.450873)
		(end 86.21395 -254.52705)
		(width 0.0889)
		(layer "In4.Cu")
		(net "M_D_CPU1_SA_CA<4>")
	)
	(arc
		(start 89.408 -254.52705)
		(mid 89.690956 -254.450873)
		(end 89.973912 -254.52705)
		(width 0.0889)
		(layer "In4.Cu")
		(net "M_D_CPU1_SA_CA<4>")
	)
	(arc
		(start 82.46237 -254.531876)
		(mid 82.645878 -254.57737)
		(end 82.82813 -254.52705)
		(width 0.0889)
		(layer "In4.Cu")
		(net "M_D_CPU1_SA_CA<4>")
	)
	(arc
		(start 87.162386 -254.531876)
		(mid 87.345894 -254.57737)
		(end 87.528146 -254.52705)
		(width 0.0889)
		(layer "In4.Cu")
		(net "M_D_CPU1_SA_CA<4>")
	)
	(arc
		(start 86.21395 -254.52705)
		(mid 86.396201 -254.5774)
		(end 86.57971 -254.531876)
		(width 0.0889)
		(layer "In4.Cu")
		(net "M_D_CPU1_SA_CA<4>")
	)
	(arc
		(start 83.402424 -254.531876)
		(mid 83.585932 -254.57737)
		(end 83.768184 -254.52705)
		(width 0.0889)
		(layer "In4.Cu")
		(net "M_D_CPU1_SA_CA<4>")
	)
	(arc
		(start 89.973912 -254.52705)
		(mid 90.156163 -254.5774)
		(end 90.339672 -254.531876)
		(width 0.0889)
		(layer "In4.Cu")
		(net "M_D_CPU1_SA_CA<4>")
	)
	(arc
		(start 80.008222 -254.52705)
		(mid 80.291178 -254.450873)
		(end 80.574134 -254.52705)
		(width 0.0889)
		(layer "In4.Cu")
		(net "M_D_CPU1_SA_CA<4>")
	)
	(arc
		(start 78.695296 -254.52705)
		(mid 78.872087 -254.577769)
		(end 79.051658 -254.537972)
		(width 0.0889)
		(layer "In4.Cu")
		(net "M_D_CPU1_SA_CA<4>")
	)
	(arc
		(start 79.070454 -254.52705)
		(mid 79.340223 -254.451027)
		(end 79.613252 -254.51435)
		(width 0.0889)
		(layer "In4.Cu")
		(net "M_D_CPU1_SA_CA<4>")
	)
	(arc
		(start 78.013052 -254.616458)
		(mid 78.068401 -254.567799)
		(end 78.129638 -254.526796)
		(width 0.0889)
		(layer "In4.Cu")
		(net "M_D_CPU1_SA_CA<4>")
	)
	(arc
		(start 89.034112 -254.52705)
		(mid 89.221056 -254.577305)
		(end 89.408 -254.52705)
		(width 0.0889)
		(layer "In4.Cu")
		(net "M_D_CPU1_SA_CA<4>")
	)
	(arc
		(start 82.82813 -254.52705)
		(mid 83.111086 -254.450873)
		(end 83.394042 -254.52705)
		(width 0.0889)
		(layer "In4.Cu")
		(net "M_D_CPU1_SA_CA<4>")
	)
	(arc
		(start 80.574134 -254.52705)
		(mid 80.761078 -254.577305)
		(end 80.948022 -254.52705)
		(width 0.0889)
		(layer "In4.Cu")
		(net "M_D_CPU1_SA_CA<4>")
	)
	(arc
		(start 80.948022 -254.52705)
		(mid 81.230978 -254.450873)
		(end 81.513934 -254.52705)
		(width 0.0889)
		(layer "In4.Cu")
		(net "M_D_CPU1_SA_CA<4>")
	)
	(arc
		(start 79.654908 -254.538226)
		(mid 79.832986 -254.57721)
		(end 80.008222 -254.52705)
		(width 0.0889)
		(layer "In4.Cu")
		(net "M_D_CPU1_SA_CA<4>")
	)
	(arc
		(start 85.273896 -254.52705)
		(mid 85.456147 -254.5774)
		(end 85.639656 -254.531876)
		(width 0.0889)
		(layer "In4.Cu")
		(net "M_D_CPU1_SA_CA<4>")
	)
	(arc
		(start 83.768184 -254.52705)
		(mid 84.05114 -254.450873)
		(end 84.334096 -254.52705)
		(width 0.0889)
		(layer "In4.Cu")
		(net "M_D_CPU1_SA_CA<4>")
	)
	(arc
		(start 78.161388 -254.508508)
		(mid 78.430673 -254.450596)
		(end 78.695296 -254.52705)
		(width 0.0889)
		(layer "In4.Cu")
		(net "M_D_CPU1_SA_CA<4>")
	)
	(arc
		(start 86.588092 -254.52705)
		(mid 86.871048 -254.450873)
		(end 87.154004 -254.52705)
		(width 0.0889)
		(layer "In4.Cu")
		(net "M_D_CPU1_SA_CA<4>")
	)
	(arc
		(start 84.334096 -254.52705)
		(mid 84.52104 -254.577305)
		(end 84.707984 -254.52705)
		(width 0.0889)
		(layer "In4.Cu")
		(net "M_D_CPU1_SA_CA<4>")
	)
	(arc
		(start 90.348054 -254.52705)
		(mid 90.595767 -254.45183)
		(end 90.850974 -254.4953)
		(width 0.0889)
		(layer "In4.Cu")
		(net "M_D_CPU1_SA_CA<4>")
	)
	(arc
		(start 88.10244 -254.531876)
		(mid 88.285948 -254.57737)
		(end 88.4682 -254.52705)
		(width 0.0889)
		(layer "In4.Cu")
		(net "M_D_CPU1_SA_CA<4>")
	)
	(arc
		(start 88.4682 -254.52705)
		(mid 88.751156 -254.450873)
		(end 89.034112 -254.52705)
		(width 0.0889)
		(layer "In4.Cu")
		(net "M_D_CPU1_SA_CA<4>")
	)
	(arc
		(start 84.707984 -254.52705)
		(mid 84.99094 -254.450873)
		(end 85.273896 -254.52705)
		(width 0.0889)
		(layer "In4.Cu")
		(net "M_D_CPU1_SA_CA<4>")
	)
	(arc
		(start 87.528146 -254.52705)
		(mid 87.811102 -254.450873)
		(end 88.094058 -254.52705)
		(width 0.0889)
		(layer "In4.Cu")
		(net "M_D_CPU1_SA_CA<4>")
	)
	(arc
		(start 81.888076 -254.52705)
		(mid 82.171032 -254.450873)
		(end 82.453988 -254.52705)
		(width 0.0889)
		(layer "In4.Cu")
		(net "M_D_CPU1_SA_CA<4>")
	)
	(arc
		(start 81.513934 -254.52705)
		(mid 81.696185 -254.5774)
		(end 81.879694 -254.531876)
		(width 0.0889)
		(layer "In4.Cu")
		(net "M_D_CPU1_SA_CA<4>")
	)
	(segment
		(start 92.507816 -254.470408)
		(end 92.040964 -254.20447)
		(width 0.10668)
		(layer "F.Cu")
		(net "M_D_CPU1_SA_CA<3>")
	)
	(segment
		(start 78.67777 -253.891288)
		(end 78.693518 -253.882144)
		(width 0.0889)
		(layer "In4.Cu")
		(net "M_D_CPU1_SA_CA<3>")
	)
	(segment
		(start 83.394042 -253.88189)
		(end 83.402424 -253.877064)
		(width 0.0889)
		(layer "In4.Cu")
		(net "M_D_CPU1_SA_CA<3>")
	)
	(segment
		(start 33.120838 -250.460256)
		(end 37.156898 -250.460256)
		(width 0.14478)
		(layer "In4.Cu")
		(net "M_D_CPU1_SA_CA<3>")
	)
	(segment
		(start 78.693518 -253.882144)
		(end 78.709774 -253.872746)
		(width 0.0889)
		(layer "In4.Cu")
		(net "M_D_CPU1_SA_CA<3>")
	)
	(segment
		(start 75.955906 -254.301244)
		(end 76.275692 -254.301244)
		(width 0.0889)
		(layer "In4.Cu")
		(net "M_D_CPU1_SA_CA<3>")
	)
	(segment
		(start 92.195142 -253.93904)
		(end 92.040964 -254.20447)
		(width 0.0889)
		(layer "In4.Cu")
		(net "M_D_CPU1_SA_CA<3>")
	)
	(segment
		(start 86.57971 -253.877064)
		(end 86.588092 -253.88189)
		(width 0.0889)
		(layer "In4.Cu")
		(net "M_D_CPU1_SA_CA<3>")
	)
	(segment
		(start 82.453988 -253.88189)
		(end 82.46237 -253.877064)
		(width 0.0889)
		(layer "In4.Cu")
		(net "M_D_CPU1_SA_CA<3>")
	)
	(segment
		(start 37.156898 -250.460256)
		(end 38.85692 -252.160278)
		(width 0.14478)
		(layer "In4.Cu")
		(net "M_D_CPU1_SA_CA<3>")
	)
	(segment
		(start 76.49591 -254.081026)
		(end 77.013562 -254.081026)
		(width 0.0889)
		(layer "In4.Cu")
		(net "M_D_CPU1_SA_CA<3>")
	)
	(segment
		(start 87.154004 -253.88189)
		(end 87.162386 -253.877064)
		(width 0.0889)
		(layer "In4.Cu")
		(net "M_D_CPU1_SA_CA<3>")
	)
	(segment
		(start 88.094058 -253.88189)
		(end 88.10244 -253.877064)
		(width 0.0889)
		(layer "In4.Cu")
		(net "M_D_CPU1_SA_CA<3>")
	)
	(segment
		(start 73.454006 -254.301244)
		(end 75.955906 -254.301244)
		(width 0.14478)
		(layer "In4.Cu")
		(net "M_D_CPU1_SA_CA<3>")
	)
	(segment
		(start 60.743338 -253.296674)
		(end 72.449436 -253.296674)
		(width 0.14478)
		(layer "In4.Cu")
		(net "M_D_CPU1_SA_CA<3>")
	)
	(segment
		(start 72.449436 -253.296674)
		(end 73.454006 -254.301244)
		(width 0.14478)
		(layer "In4.Cu")
		(net "M_D_CPU1_SA_CA<3>")
	)
	(segment
		(start 59.606942 -252.160278)
		(end 60.743338 -253.296674)
		(width 0.14478)
		(layer "In4.Cu")
		(net "M_D_CPU1_SA_CA<3>")
	)
	(segment
		(start 79.067406 -253.88189)
		(end 79.07782 -253.887986)
		(width 0.0889)
		(layer "In4.Cu")
		(net "M_D_CPU1_SA_CA<3>")
	)
	(segment
		(start 90.339672 -253.877064)
		(end 90.348054 -253.88189)
		(width 0.0889)
		(layer "In4.Cu")
		(net "M_D_CPU1_SA_CA<3>")
	)
	(segment
		(start 77.75321 -253.88189)
		(end 77.764894 -253.875032)
		(width 0.0889)
		(layer "In4.Cu")
		(net "M_D_CPU1_SA_CA<3>")
	)
	(segment
		(start 85.639656 -253.877064)
		(end 85.648038 -253.88189)
		(width 0.0889)
		(layer "In4.Cu")
		(net "M_D_CPU1_SA_CA<3>")
	)
	(segment
		(start 91.85402 -253.88189)
		(end 91.862402 -253.877064)
		(width 0.0889)
		(layer "In4.Cu")
		(net "M_D_CPU1_SA_CA<3>")
	)
	(segment
		(start 79.99984 -253.877064)
		(end 80.008222 -253.88189)
		(width 0.0889)
		(layer "In4.Cu")
		(net "M_D_CPU1_SA_CA<3>")
	)
	(segment
		(start 92.17279 -253.855728)
		(end 92.195142 -253.93904)
		(width 0.0889)
		(layer "In4.Cu")
		(net "M_D_CPU1_SA_CA<3>")
	)
	(segment
		(start 90.913966 -253.88189)
		(end 90.922348 -253.877064)
		(width 0.0889)
		(layer "In4.Cu")
		(net "M_D_CPU1_SA_CA<3>")
	)
	(segment
		(start 32.695896 -250.035314)
		(end 33.120838 -250.460256)
		(width 0.14478)
		(layer "In4.Cu")
		(net "M_D_CPU1_SA_CA<3>")
	)
	(segment
		(start 81.879694 -253.877064)
		(end 81.888076 -253.88189)
		(width 0.0889)
		(layer "In4.Cu")
		(net "M_D_CPU1_SA_CA<3>")
	)
	(segment
		(start 76.275692 -254.301244)
		(end 76.49591 -254.081026)
		(width 0.0889)
		(layer "In4.Cu")
		(net "M_D_CPU1_SA_CA<3>")
	)
	(segment
		(start 38.85692 -252.160278)
		(end 59.606942 -252.160278)
		(width 0.14478)
		(layer "In4.Cu")
		(net "M_D_CPU1_SA_CA<3>")
	)
	(arc
		(start 90.348054 -253.88189)
		(mid 90.63101 -253.958067)
		(end 90.913966 -253.88189)
		(width 0.0889)
		(layer "In4.Cu")
		(net "M_D_CPU1_SA_CA<3>")
	)
	(arc
		(start 84.334096 -253.88189)
		(mid 84.52104 -253.831635)
		(end 84.707984 -253.88189)
		(width 0.0889)
		(layer "In4.Cu")
		(net "M_D_CPU1_SA_CA<3>")
	)
	(arc
		(start 78.127606 -253.88189)
		(mid 78.401461 -253.95824)
		(end 78.67777 -253.891288)
		(width 0.0889)
		(layer "In4.Cu")
		(net "M_D_CPU1_SA_CA<3>")
	)
	(arc
		(start 87.162386 -253.877064)
		(mid 87.345894 -253.83157)
		(end 87.528146 -253.88189)
		(width 0.0889)
		(layer "In4.Cu")
		(net "M_D_CPU1_SA_CA<3>")
	)
	(arc
		(start 77.013562 -254.081026)
		(mid 77.396555 -254.030371)
		(end 77.75321 -253.88189)
		(width 0.0889)
		(layer "In4.Cu")
		(net "M_D_CPU1_SA_CA<3>")
	)
	(arc
		(start 91.862402 -253.877064)
		(mid 92.015272 -253.832423)
		(end 92.17279 -253.855728)
		(width 0.0889)
		(layer "In4.Cu")
		(net "M_D_CPU1_SA_CA<3>")
	)
	(arc
		(start 79.633572 -253.88189)
		(mid 79.816077 -253.831413)
		(end 79.99984 -253.877064)
		(width 0.0889)
		(layer "In4.Cu")
		(net "M_D_CPU1_SA_CA<3>")
	)
	(arc
		(start 86.21395 -253.88189)
		(mid 86.396201 -253.83154)
		(end 86.57971 -253.877064)
		(width 0.0889)
		(layer "In4.Cu")
		(net "M_D_CPU1_SA_CA<3>")
	)
	(arc
		(start 80.008222 -253.88189)
		(mid 80.291178 -253.958067)
		(end 80.574134 -253.88189)
		(width 0.0889)
		(layer "In4.Cu")
		(net "M_D_CPU1_SA_CA<3>")
	)
	(arc
		(start 83.402424 -253.877064)
		(mid 83.585932 -253.83157)
		(end 83.768184 -253.88189)
		(width 0.0889)
		(layer "In4.Cu")
		(net "M_D_CPU1_SA_CA<3>")
	)
	(arc
		(start 84.707984 -253.88189)
		(mid 84.99094 -253.958067)
		(end 85.273896 -253.88189)
		(width 0.0889)
		(layer "In4.Cu")
		(net "M_D_CPU1_SA_CA<3>")
	)
	(arc
		(start 89.973912 -253.88189)
		(mid 90.156163 -253.83154)
		(end 90.339672 -253.877064)
		(width 0.0889)
		(layer "In4.Cu")
		(net "M_D_CPU1_SA_CA<3>")
	)
	(arc
		(start 87.528146 -253.88189)
		(mid 87.811102 -253.958067)
		(end 88.094058 -253.88189)
		(width 0.0889)
		(layer "In4.Cu")
		(net "M_D_CPU1_SA_CA<3>")
	)
	(arc
		(start 77.764894 -253.875032)
		(mid 77.947149 -253.831379)
		(end 78.127606 -253.88189)
		(width 0.0889)
		(layer "In4.Cu")
		(net "M_D_CPU1_SA_CA<3>")
	)
	(arc
		(start 89.408 -253.88189)
		(mid 89.690956 -253.958067)
		(end 89.973912 -253.88189)
		(width 0.0889)
		(layer "In4.Cu")
		(net "M_D_CPU1_SA_CA<3>")
	)
	(arc
		(start 85.648038 -253.88189)
		(mid 85.930994 -253.958067)
		(end 86.21395 -253.88189)
		(width 0.0889)
		(layer "In4.Cu")
		(net "M_D_CPU1_SA_CA<3>")
	)
	(arc
		(start 90.922348 -253.877064)
		(mid 91.105856 -253.83157)
		(end 91.288108 -253.88189)
		(width 0.0889)
		(layer "In4.Cu")
		(net "M_D_CPU1_SA_CA<3>")
	)
	(arc
		(start 91.288108 -253.88189)
		(mid 91.571064 -253.958067)
		(end 91.85402 -253.88189)
		(width 0.0889)
		(layer "In4.Cu")
		(net "M_D_CPU1_SA_CA<3>")
	)
	(arc
		(start 80.948022 -253.88189)
		(mid 81.230978 -253.958067)
		(end 81.513934 -253.88189)
		(width 0.0889)
		(layer "In4.Cu")
		(net "M_D_CPU1_SA_CA<3>")
	)
	(arc
		(start 82.46237 -253.877064)
		(mid 82.645878 -253.83157)
		(end 82.82813 -253.88189)
		(width 0.0889)
		(layer "In4.Cu")
		(net "M_D_CPU1_SA_CA<3>")
	)
	(arc
		(start 78.709774 -253.872746)
		(mid 78.889756 -253.831646)
		(end 79.067406 -253.88189)
		(width 0.0889)
		(layer "In4.Cu")
		(net "M_D_CPU1_SA_CA<3>")
	)
	(arc
		(start 81.888076 -253.88189)
		(mid 82.171032 -253.958067)
		(end 82.453988 -253.88189)
		(width 0.0889)
		(layer "In4.Cu")
		(net "M_D_CPU1_SA_CA<3>")
	)
	(arc
		(start 85.273896 -253.88189)
		(mid 85.456147 -253.83154)
		(end 85.639656 -253.877064)
		(width 0.0889)
		(layer "In4.Cu")
		(net "M_D_CPU1_SA_CA<3>")
	)
	(arc
		(start 89.034112 -253.88189)
		(mid 89.221056 -253.831635)
		(end 89.408 -253.88189)
		(width 0.0889)
		(layer "In4.Cu")
		(net "M_D_CPU1_SA_CA<3>")
	)
	(arc
		(start 79.07782 -253.887986)
		(mid 79.356506 -253.958206)
		(end 79.633572 -253.88189)
		(width 0.0889)
		(layer "In4.Cu")
		(net "M_D_CPU1_SA_CA<3>")
	)
	(arc
		(start 86.588092 -253.88189)
		(mid 86.871048 -253.958067)
		(end 87.154004 -253.88189)
		(width 0.0889)
		(layer "In4.Cu")
		(net "M_D_CPU1_SA_CA<3>")
	)
	(arc
		(start 82.82813 -253.88189)
		(mid 83.111086 -253.958067)
		(end 83.394042 -253.88189)
		(width 0.0889)
		(layer "In4.Cu")
		(net "M_D_CPU1_SA_CA<3>")
	)
	(arc
		(start 80.574134 -253.88189)
		(mid 80.761078 -253.831635)
		(end 80.948022 -253.88189)
		(width 0.0889)
		(layer "In4.Cu")
		(net "M_D_CPU1_SA_CA<3>")
	)
	(arc
		(start 88.4682 -253.88189)
		(mid 88.751156 -253.958067)
		(end 89.034112 -253.88189)
		(width 0.0889)
		(layer "In4.Cu")
		(net "M_D_CPU1_SA_CA<3>")
	)
	(arc
		(start 83.768184 -253.88189)
		(mid 84.05114 -253.958067)
		(end 84.334096 -253.88189)
		(width 0.0889)
		(layer "In4.Cu")
		(net "M_D_CPU1_SA_CA<3>")
	)
	(arc
		(start 88.10244 -253.877064)
		(mid 88.285948 -253.83157)
		(end 88.4682 -253.88189)
		(width 0.0889)
		(layer "In4.Cu")
		(net "M_D_CPU1_SA_CA<3>")
	)
	(arc
		(start 81.513934 -253.88189)
		(mid 81.696185 -253.83154)
		(end 81.879694 -253.877064)
		(width 0.0889)
		(layer "In4.Cu")
		(net "M_D_CPU1_SA_CA<3>")
	)
	(segment
		(start 92.97797 -253.660402)
		(end 92.511118 -253.394464)
		(width 0.10668)
		(layer "F.Cu")
		(net "M_D_CPU1_SA_CA<2>")
	)
	(segment
		(start 92.35694 -253.659894)
		(end 92.511118 -253.394464)
		(width 0.0889)
		(layer "In4.Cu")
		(net "M_D_CPU1_SA_CA<2>")
	)
	(segment
		(start 77.469746 -253.76759)
		(end 77.47 -253.767336)
		(width 0.0889)
		(layer "In4.Cu")
		(net "M_D_CPU1_SA_CA<2>")
	)
	(segment
		(start 45.92066 -251.702824)
		(end 46.151038 -251.702824)
		(width 0.14478)
		(layer "In4.Cu")
		(net "M_D_CPU1_SA_CA<2>")
	)
	(segment
		(start 45.757592 -251.539756)
		(end 45.92066 -251.702824)
		(width 0.14478)
		(layer "In4.Cu")
		(net "M_D_CPU1_SA_CA<2>")
	)
	(segment
		(start 73.639934 -253.844044)
		(end 75.960986 -253.844044)
		(width 0.14478)
		(layer "In4.Cu")
		(net "M_D_CPU1_SA_CA<2>")
	)
	(segment
		(start 38.920674 -251.31014)
		(end 41.019984 -251.31014)
		(width 0.14478)
		(layer "In4.Cu")
		(net "M_D_CPU1_SA_CA<2>")
	)
	(segment
		(start 59.61253 -251.31014)
		(end 61.149484 -252.847094)
		(width 0.14478)
		(layer "In4.Cu")
		(net "M_D_CPU1_SA_CA<2>")
	)
	(segment
		(start 46.477174 -251.31014)
		(end 59.61253 -251.31014)
		(width 0.14478)
		(layer "In4.Cu")
		(net "M_D_CPU1_SA_CA<2>")
	)
	(segment
		(start 45.594524 -251.31014)
		(end 45.757592 -251.473208)
		(width 0.14478)
		(layer "In4.Cu")
		(net "M_D_CPU1_SA_CA<2>")
	)
	(segment
		(start 88.929718 -253.72187)
		(end 88.9381 -253.717044)
		(width 0.0889)
		(layer "In4.Cu")
		(net "M_D_CPU1_SA_CA<2>")
	)
	(segment
		(start 79.163164 -253.717044)
		(end 79.171546 -253.72187)
		(width 0.0889)
		(layer "In4.Cu")
		(net "M_D_CPU1_SA_CA<2>")
	)
	(segment
		(start 42.459148 -251.702824)
		(end 42.689526 -251.702824)
		(width 0.14478)
		(layer "In4.Cu")
		(net "M_D_CPU1_SA_CA<2>")
	)
	(segment
		(start 42.29608 -251.539756)
		(end 42.459148 -251.702824)
		(width 0.14478)
		(layer "In4.Cu")
		(net "M_D_CPU1_SA_CA<2>")
	)
	(segment
		(start 45.757592 -251.473208)
		(end 45.757592 -251.539756)
		(width 0.14478)
		(layer "In4.Cu")
		(net "M_D_CPU1_SA_CA<2>")
	)
	(segment
		(start 41.739566 -251.473208)
		(end 41.902634 -251.31014)
		(width 0.14478)
		(layer "In4.Cu")
		(net "M_D_CPU1_SA_CA<2>")
	)
	(segment
		(start 78.579472 -253.727204)
		(end 78.59776 -253.71679)
		(width 0.0889)
		(layer "In4.Cu")
		(net "M_D_CPU1_SA_CA<2>")
	)
	(segment
		(start 84.229702 -253.72187)
		(end 84.238084 -253.717044)
		(width 0.0889)
		(layer "In4.Cu")
		(net "M_D_CPU1_SA_CA<2>")
	)
	(segment
		(start 76.321666 -253.76759)
		(end 77.469746 -253.76759)
		(width 0.0889)
		(layer "In4.Cu")
		(net "M_D_CPU1_SA_CA<2>")
	)
	(segment
		(start 41.576498 -251.702824)
		(end 41.739566 -251.539756)
		(width 0.14478)
		(layer "In4.Cu")
		(net "M_D_CPU1_SA_CA<2>")
	)
	(segment
		(start 46.151038 -251.702824)
		(end 46.314106 -251.539756)
		(width 0.14478)
		(layer "In4.Cu")
		(net "M_D_CPU1_SA_CA<2>")
	)
	(segment
		(start 41.739566 -251.539756)
		(end 41.739566 -251.473208)
		(width 0.14478)
		(layer "In4.Cu")
		(net "M_D_CPU1_SA_CA<2>")
	)
	(segment
		(start 41.34612 -251.702824)
		(end 41.576498 -251.702824)
		(width 0.14478)
		(layer "In4.Cu")
		(net "M_D_CPU1_SA_CA<2>")
	)
	(segment
		(start 84.803996 -253.717044)
		(end 84.812378 -253.72187)
		(width 0.0889)
		(layer "In4.Cu")
		(net "M_D_CPU1_SA_CA<2>")
	)
	(segment
		(start 36.795964 -249.18543)
		(end 38.920674 -251.31014)
		(width 0.14478)
		(layer "In4.Cu")
		(net "M_D_CPU1_SA_CA<2>")
	)
	(segment
		(start 42.29608 -251.473208)
		(end 42.29608 -251.539756)
		(width 0.14478)
		(layer "In4.Cu")
		(net "M_D_CPU1_SA_CA<2>")
	)
	(segment
		(start 92.260674 -253.685294)
		(end 92.35694 -253.659894)
		(width 0.0889)
		(layer "In4.Cu")
		(net "M_D_CPU1_SA_CA<2>")
	)
	(segment
		(start 87.989664 -253.72187)
		(end 87.998046 -253.717044)
		(width 0.0889)
		(layer "In4.Cu")
		(net "M_D_CPU1_SA_CA<2>")
	)
	(segment
		(start 42.133012 -251.31014)
		(end 42.29608 -251.473208)
		(width 0.14478)
		(layer "In4.Cu")
		(net "M_D_CPU1_SA_CA<2>")
	)
	(segment
		(start 76.245212 -253.844044)
		(end 76.321666 -253.76759)
		(width 0.0889)
		(layer "In4.Cu")
		(net "M_D_CPU1_SA_CA<2>")
	)
	(segment
		(start 81.044034 -253.717044)
		(end 81.052416 -253.72187)
		(width 0.0889)
		(layer "In4.Cu")
		(net "M_D_CPU1_SA_CA<2>")
	)
	(segment
		(start 41.183052 -251.539756)
		(end 41.34612 -251.702824)
		(width 0.14478)
		(layer "In4.Cu")
		(net "M_D_CPU1_SA_CA<2>")
	)
	(segment
		(start 80.46974 -253.72187)
		(end 80.478122 -253.717044)
		(width 0.0889)
		(layer "In4.Cu")
		(net "M_D_CPU1_SA_CA<2>")
	)
	(segment
		(start 72.642984 -252.847094)
		(end 73.639934 -253.844044)
		(width 0.14478)
		(layer "In4.Cu")
		(net "M_D_CPU1_SA_CA<2>")
	)
	(segment
		(start 75.960986 -253.844044)
		(end 76.245212 -253.844044)
		(width 0.0889)
		(layer "In4.Cu")
		(net "M_D_CPU1_SA_CA<2>")
	)
	(segment
		(start 42.852594 -251.473208)
		(end 43.015662 -251.31014)
		(width 0.14478)
		(layer "In4.Cu")
		(net "M_D_CPU1_SA_CA<2>")
	)
	(segment
		(start 78.59776 -253.71679)
		(end 78.603348 -253.713488)
		(width 0.0889)
		(layer "In4.Cu")
		(net "M_D_CPU1_SA_CA<2>")
	)
	(segment
		(start 61.149484 -252.847094)
		(end 72.642984 -252.847094)
		(width 0.14478)
		(layer "In4.Cu")
		(net "M_D_CPU1_SA_CA<2>")
	)
	(segment
		(start 41.183052 -251.473208)
		(end 41.183052 -251.539756)
		(width 0.14478)
		(layer "In4.Cu")
		(net "M_D_CPU1_SA_CA<2>")
	)
	(segment
		(start 83.289648 -253.72187)
		(end 83.29803 -253.717044)
		(width 0.0889)
		(layer "In4.Cu")
		(net "M_D_CPU1_SA_CA<2>")
	)
	(segment
		(start 91.749626 -253.72187)
		(end 91.758008 -253.717044)
		(width 0.0889)
		(layer "In4.Cu")
		(net "M_D_CPU1_SA_CA<2>")
	)
	(segment
		(start 89.504012 -253.717044)
		(end 89.512394 -253.72187)
		(width 0.0889)
		(layer "In4.Cu")
		(net "M_D_CPU1_SA_CA<2>")
	)
	(segment
		(start 80.093566 -253.710948)
		(end 80.10398 -253.717044)
		(width 0.0889)
		(layer "In4.Cu")
		(net "M_D_CPU1_SA_CA<2>")
	)
	(segment
		(start 85.74405 -253.717044)
		(end 85.752432 -253.72187)
		(width 0.0889)
		(layer "In4.Cu")
		(net "M_D_CPU1_SA_CA<2>")
	)
	(segment
		(start 46.314106 -251.473208)
		(end 46.477174 -251.31014)
		(width 0.14478)
		(layer "In4.Cu")
		(net "M_D_CPU1_SA_CA<2>")
	)
	(segment
		(start 46.314106 -251.539756)
		(end 46.314106 -251.473208)
		(width 0.14478)
		(layer "In4.Cu")
		(net "M_D_CPU1_SA_CA<2>")
	)
	(segment
		(start 41.019984 -251.31014)
		(end 41.183052 -251.473208)
		(width 0.14478)
		(layer "In4.Cu")
		(net "M_D_CPU1_SA_CA<2>")
	)
	(segment
		(start 42.852594 -251.539756)
		(end 42.852594 -251.473208)
		(width 0.14478)
		(layer "In4.Cu")
		(net "M_D_CPU1_SA_CA<2>")
	)
	(segment
		(start 42.689526 -251.702824)
		(end 42.852594 -251.539756)
		(width 0.14478)
		(layer "In4.Cu")
		(net "M_D_CPU1_SA_CA<2>")
	)
	(segment
		(start 43.015662 -251.31014)
		(end 45.594524 -251.31014)
		(width 0.14478)
		(layer "In4.Cu")
		(net "M_D_CPU1_SA_CA<2>")
	)
	(segment
		(start 77.657198 -253.717044)
		(end 77.67193 -253.708408)
		(width 0.0889)
		(layer "In4.Cu")
		(net "M_D_CPU1_SA_CA<2>")
	)
	(segment
		(start 41.902634 -251.31014)
		(end 42.133012 -251.31014)
		(width 0.14478)
		(layer "In4.Cu")
		(net "M_D_CPU1_SA_CA<2>")
	)
	(arc
		(start 77.47 -253.767336)
		(mid 77.566932 -253.754585)
		(end 77.657198 -253.717044)
		(width 0.0889)
		(layer "In4.Cu")
		(net "M_D_CPU1_SA_CA<2>")
	)
	(arc
		(start 80.478122 -253.717044)
		(mid 80.761078 -253.640867)
		(end 81.044034 -253.717044)
		(width 0.0889)
		(layer "In4.Cu")
		(net "M_D_CPU1_SA_CA<2>")
	)
	(arc
		(start 78.223618 -253.717044)
		(mid 78.400246 -253.767277)
		(end 78.579472 -253.727204)
		(width 0.0889)
		(layer "In4.Cu")
		(net "M_D_CPU1_SA_CA<2>")
	)
	(arc
		(start 81.418176 -253.717044)
		(mid 81.701132 -253.640867)
		(end 81.984088 -253.717044)
		(width 0.0889)
		(layer "In4.Cu")
		(net "M_D_CPU1_SA_CA<2>")
	)
	(arc
		(start 79.171546 -253.72187)
		(mid 79.355308 -253.767486)
		(end 79.537814 -253.717044)
		(width 0.0889)
		(layer "In4.Cu")
		(net "M_D_CPU1_SA_CA<2>")
	)
	(arc
		(start 83.863942 -253.717044)
		(mid 84.046193 -253.767394)
		(end 84.229702 -253.72187)
		(width 0.0889)
		(layer "In4.Cu")
		(net "M_D_CPU1_SA_CA<2>")
	)
	(arc
		(start 81.984088 -253.717044)
		(mid 82.171032 -253.767299)
		(end 82.357976 -253.717044)
		(width 0.0889)
		(layer "In4.Cu")
		(net "M_D_CPU1_SA_CA<2>")
	)
	(arc
		(start 80.10398 -253.717044)
		(mid 80.286231 -253.767394)
		(end 80.46974 -253.72187)
		(width 0.0889)
		(layer "In4.Cu")
		(net "M_D_CPU1_SA_CA<2>")
	)
	(arc
		(start 87.623904 -253.717044)
		(mid 87.806155 -253.767394)
		(end 87.989664 -253.72187)
		(width 0.0889)
		(layer "In4.Cu")
		(net "M_D_CPU1_SA_CA<2>")
	)
	(arc
		(start 82.923888 -253.717044)
		(mid 83.106139 -253.767394)
		(end 83.289648 -253.72187)
		(width 0.0889)
		(layer "In4.Cu")
		(net "M_D_CPU1_SA_CA<2>")
	)
	(arc
		(start 88.563958 -253.717044)
		(mid 88.746209 -253.767394)
		(end 88.929718 -253.72187)
		(width 0.0889)
		(layer "In4.Cu")
		(net "M_D_CPU1_SA_CA<2>")
	)
	(arc
		(start 85.752432 -253.72187)
		(mid 85.93594 -253.767364)
		(end 86.118192 -253.717044)
		(width 0.0889)
		(layer "In4.Cu")
		(net "M_D_CPU1_SA_CA<2>")
	)
	(arc
		(start 78.603348 -253.713488)
		(mid 78.883737 -253.640819)
		(end 79.163164 -253.717044)
		(width 0.0889)
		(layer "In4.Cu")
		(net "M_D_CPU1_SA_CA<2>")
	)
	(arc
		(start 83.29803 -253.717044)
		(mid 83.580986 -253.640867)
		(end 83.863942 -253.717044)
		(width 0.0889)
		(layer "In4.Cu")
		(net "M_D_CPU1_SA_CA<2>")
	)
	(arc
		(start 88.9381 -253.717044)
		(mid 89.221056 -253.640867)
		(end 89.504012 -253.717044)
		(width 0.0889)
		(layer "In4.Cu")
		(net "M_D_CPU1_SA_CA<2>")
	)
	(arc
		(start 89.512394 -253.72187)
		(mid 89.695902 -253.767364)
		(end 89.878154 -253.717044)
		(width 0.0889)
		(layer "In4.Cu")
		(net "M_D_CPU1_SA_CA<2>")
	)
	(arc
		(start 86.684104 -253.717044)
		(mid 86.871048 -253.767299)
		(end 87.057992 -253.717044)
		(width 0.0889)
		(layer "In4.Cu")
		(net "M_D_CPU1_SA_CA<2>")
	)
	(arc
		(start 87.998046 -253.717044)
		(mid 88.281002 -253.640867)
		(end 88.563958 -253.717044)
		(width 0.0889)
		(layer "In4.Cu")
		(net "M_D_CPU1_SA_CA<2>")
	)
	(arc
		(start 77.67193 -253.708408)
		(mid 77.948913 -253.640604)
		(end 78.223618 -253.717044)
		(width 0.0889)
		(layer "In4.Cu")
		(net "M_D_CPU1_SA_CA<2>")
	)
	(arc
		(start 79.537814 -253.717044)
		(mid 79.814881 -253.640773)
		(end 80.093566 -253.710948)
		(width 0.0889)
		(layer "In4.Cu")
		(net "M_D_CPU1_SA_CA<2>")
	)
	(arc
		(start 90.817954 -253.717044)
		(mid 91.10091 -253.640867)
		(end 91.383866 -253.717044)
		(width 0.0889)
		(layer "In4.Cu")
		(net "M_D_CPU1_SA_CA<2>")
	)
	(arc
		(start 81.052416 -253.72187)
		(mid 81.235924 -253.767364)
		(end 81.418176 -253.717044)
		(width 0.0889)
		(layer "In4.Cu")
		(net "M_D_CPU1_SA_CA<2>")
	)
	(arc
		(start 89.878154 -253.717044)
		(mid 90.16111 -253.640867)
		(end 90.444066 -253.717044)
		(width 0.0889)
		(layer "In4.Cu")
		(net "M_D_CPU1_SA_CA<2>")
	)
	(arc
		(start 91.383866 -253.717044)
		(mid 91.566117 -253.767394)
		(end 91.749626 -253.72187)
		(width 0.0889)
		(layer "In4.Cu")
		(net "M_D_CPU1_SA_CA<2>")
	)
	(arc
		(start 84.812378 -253.72187)
		(mid 84.995886 -253.767364)
		(end 85.178138 -253.717044)
		(width 0.0889)
		(layer "In4.Cu")
		(net "M_D_CPU1_SA_CA<2>")
	)
	(arc
		(start 82.357976 -253.717044)
		(mid 82.640932 -253.640867)
		(end 82.923888 -253.717044)
		(width 0.0889)
		(layer "In4.Cu")
		(net "M_D_CPU1_SA_CA<2>")
	)
	(arc
		(start 90.444066 -253.717044)
		(mid 90.63101 -253.767299)
		(end 90.817954 -253.717044)
		(width 0.0889)
		(layer "In4.Cu")
		(net "M_D_CPU1_SA_CA<2>")
	)
	(arc
		(start 84.238084 -253.717044)
		(mid 84.52104 -253.640867)
		(end 84.803996 -253.717044)
		(width 0.0889)
		(layer "In4.Cu")
		(net "M_D_CPU1_SA_CA<2>")
	)
	(arc
		(start 85.178138 -253.717044)
		(mid 85.461094 -253.640867)
		(end 85.74405 -253.717044)
		(width 0.0889)
		(layer "In4.Cu")
		(net "M_D_CPU1_SA_CA<2>")
	)
	(arc
		(start 91.758008 -253.717044)
		(mid 92.005604 -253.641866)
		(end 92.260674 -253.685294)
		(width 0.0889)
		(layer "In4.Cu")
		(net "M_D_CPU1_SA_CA<2>")
	)
	(arc
		(start 86.118192 -253.717044)
		(mid 86.401148 -253.640867)
		(end 86.684104 -253.717044)
		(width 0.0889)
		(layer "In4.Cu")
		(net "M_D_CPU1_SA_CA<2>")
	)
	(arc
		(start 87.057992 -253.717044)
		(mid 87.340948 -253.640867)
		(end 87.623904 -253.717044)
		(width 0.0889)
		(layer "In4.Cu")
		(net "M_D_CPU1_SA_CA<2>")
	)
	(segment
		(start 91.097862 -253.660402)
		(end 90.63101 -253.394464)
		(width 0.10668)
		(layer "F.Cu")
		(net "M_D_CPU1_SA_CA<1>")
	)
	(segment
		(start 79.539592 -253.072138)
		(end 79.561182 -253.084584)
		(width 0.0889)
		(layer "In4.Cu")
		(net "M_D_CPU1_SA_CA<1>")
	)
	(segment
		(start 72.83958 -252.397514)
		(end 73.82383 -253.381764)
		(width 0.14478)
		(layer "In4.Cu")
		(net "M_D_CPU1_SA_CA<1>")
	)
	(segment
		(start 79.521304 -253.061724)
		(end 79.539592 -253.072138)
		(width 0.0889)
		(layer "In4.Cu")
		(net "M_D_CPU1_SA_CA<1>")
	)
	(segment
		(start 38.85692 -250.460256)
		(end 59.398662 -250.460256)
		(width 0.14478)
		(layer "In4.Cu")
		(net "M_D_CPU1_SA_CA<1>")
	)
	(segment
		(start 77.29474 -253.147576)
		(end 77.943456 -253.147576)
		(width 0.0889)
		(layer "In4.Cu")
		(net "M_D_CPU1_SA_CA<1>")
	)
	(segment
		(start 77.060552 -253.381764)
		(end 77.29474 -253.147576)
		(width 0.0889)
		(layer "In4.Cu")
		(net "M_D_CPU1_SA_CA<1>")
	)
	(segment
		(start 90.784934 -253.129034)
		(end 90.63101 -253.394464)
		(width 0.0889)
		(layer "In4.Cu")
		(net "M_D_CPU1_SA_CA<1>")
	)
	(segment
		(start 90.762582 -253.045722)
		(end 90.784934 -253.129034)
		(width 0.0889)
		(layer "In4.Cu")
		(net "M_D_CPU1_SA_CA<1>")
	)
	(segment
		(start 81.044034 -253.071884)
		(end 81.052416 -253.067058)
		(width 0.0889)
		(layer "In4.Cu")
		(net "M_D_CPU1_SA_CA<1>")
	)
	(segment
		(start 83.289648 -253.067058)
		(end 83.29803 -253.071884)
		(width 0.0889)
		(layer "In4.Cu")
		(net "M_D_CPU1_SA_CA<1>")
	)
	(segment
		(start 79.143098 -253.0856)
		(end 79.166466 -253.071884)
		(width 0.0889)
		(layer "In4.Cu")
		(net "M_D_CPU1_SA_CA<1>")
	)
	(segment
		(start 84.803996 -253.071884)
		(end 84.812378 -253.067058)
		(width 0.0889)
		(layer "In4.Cu")
		(net "M_D_CPU1_SA_CA<1>")
	)
	(segment
		(start 87.989664 -253.067058)
		(end 87.998046 -253.071884)
		(width 0.0889)
		(layer "In4.Cu")
		(net "M_D_CPU1_SA_CA<1>")
	)
	(segment
		(start 78.225142 -253.072138)
		(end 78.252574 -253.05639)
		(width 0.0889)
		(layer "In4.Cu")
		(net "M_D_CPU1_SA_CA<1>")
	)
	(segment
		(start 88.929718 -253.067058)
		(end 88.9381 -253.071884)
		(width 0.0889)
		(layer "In4.Cu")
		(net "M_D_CPU1_SA_CA<1>")
	)
	(segment
		(start 80.46974 -253.067058)
		(end 80.478122 -253.071884)
		(width 0.0889)
		(layer "In4.Cu")
		(net "M_D_CPU1_SA_CA<1>")
	)
	(segment
		(start 84.229702 -253.067058)
		(end 84.238084 -253.071884)
		(width 0.0889)
		(layer "In4.Cu")
		(net "M_D_CPU1_SA_CA<1>")
	)
	(segment
		(start 85.74405 -253.071884)
		(end 85.752432 -253.067058)
		(width 0.0889)
		(layer "In4.Cu")
		(net "M_D_CPU1_SA_CA<1>")
	)
	(segment
		(start 73.82383 -253.381764)
		(end 75.968606 -253.381764)
		(width 0.14478)
		(layer "In4.Cu")
		(net "M_D_CPU1_SA_CA<1>")
	)
	(segment
		(start 33.120838 -248.760234)
		(end 37.156898 -248.760234)
		(width 0.14478)
		(layer "In4.Cu")
		(net "M_D_CPU1_SA_CA<1>")
	)
	(segment
		(start 61.33592 -252.397514)
		(end 72.83958 -252.397514)
		(width 0.14478)
		(layer "In4.Cu")
		(net "M_D_CPU1_SA_CA<1>")
	)
	(segment
		(start 75.968606 -253.381764)
		(end 77.060552 -253.381764)
		(width 0.0889)
		(layer "In4.Cu")
		(net "M_D_CPU1_SA_CA<1>")
	)
	(segment
		(start 89.504012 -253.071884)
		(end 89.512394 -253.067058)
		(width 0.0889)
		(layer "In4.Cu")
		(net "M_D_CPU1_SA_CA<1>")
	)
	(segment
		(start 32.695896 -248.335292)
		(end 33.120838 -248.760234)
		(width 0.14478)
		(layer "In4.Cu")
		(net "M_D_CPU1_SA_CA<1>")
	)
	(segment
		(start 37.156898 -248.760234)
		(end 38.85692 -250.460256)
		(width 0.14478)
		(layer "In4.Cu")
		(net "M_D_CPU1_SA_CA<1>")
	)
	(segment
		(start 59.398662 -250.460256)
		(end 61.33592 -252.397514)
		(width 0.14478)
		(layer "In4.Cu")
		(net "M_D_CPU1_SA_CA<1>")
	)
	(arc
		(start 82.357976 -253.071884)
		(mid 82.640932 -253.148061)
		(end 82.923888 -253.071884)
		(width 0.0889)
		(layer "In4.Cu")
		(net "M_D_CPU1_SA_CA<1>")
	)
	(arc
		(start 81.418176 -253.071884)
		(mid 81.701132 -253.148061)
		(end 81.984088 -253.071884)
		(width 0.0889)
		(layer "In4.Cu")
		(net "M_D_CPU1_SA_CA<1>")
	)
	(arc
		(start 90.444066 -253.071884)
		(mid 90.600385 -253.022889)
		(end 90.762582 -253.045722)
		(width 0.0889)
		(layer "In4.Cu")
		(net "M_D_CPU1_SA_CA<1>")
	)
	(arc
		(start 80.10398 -253.071884)
		(mid 80.286231 -253.021534)
		(end 80.46974 -253.067058)
		(width 0.0889)
		(layer "In4.Cu")
		(net "M_D_CPU1_SA_CA<1>")
	)
	(arc
		(start 83.863942 -253.071884)
		(mid 84.046193 -253.021534)
		(end 84.229702 -253.067058)
		(width 0.0889)
		(layer "In4.Cu")
		(net "M_D_CPU1_SA_CA<1>")
	)
	(arc
		(start 86.684104 -253.071884)
		(mid 86.871048 -253.021629)
		(end 87.057992 -253.071884)
		(width 0.0889)
		(layer "In4.Cu")
		(net "M_D_CPU1_SA_CA<1>")
	)
	(arc
		(start 78.599284 -253.071884)
		(mid 78.869441 -253.148646)
		(end 79.143098 -253.0856)
		(width 0.0889)
		(layer "In4.Cu")
		(net "M_D_CPU1_SA_CA<1>")
	)
	(arc
		(start 85.752432 -253.067058)
		(mid 85.93594 -253.021564)
		(end 86.118192 -253.071884)
		(width 0.0889)
		(layer "In4.Cu")
		(net "M_D_CPU1_SA_CA<1>")
	)
	(arc
		(start 87.998046 -253.071884)
		(mid 88.281002 -253.148061)
		(end 88.563958 -253.071884)
		(width 0.0889)
		(layer "In4.Cu")
		(net "M_D_CPU1_SA_CA<1>")
	)
	(arc
		(start 86.118192 -253.071884)
		(mid 86.401148 -253.148061)
		(end 86.684104 -253.071884)
		(width 0.0889)
		(layer "In4.Cu")
		(net "M_D_CPU1_SA_CA<1>")
	)
	(arc
		(start 81.984088 -253.071884)
		(mid 82.171032 -253.021629)
		(end 82.357976 -253.071884)
		(width 0.0889)
		(layer "In4.Cu")
		(net "M_D_CPU1_SA_CA<1>")
	)
	(arc
		(start 85.178138 -253.071884)
		(mid 85.461094 -253.148061)
		(end 85.74405 -253.071884)
		(width 0.0889)
		(layer "In4.Cu")
		(net "M_D_CPU1_SA_CA<1>")
	)
	(arc
		(start 82.923888 -253.071884)
		(mid 83.106139 -253.021534)
		(end 83.289648 -253.067058)
		(width 0.0889)
		(layer "In4.Cu")
		(net "M_D_CPU1_SA_CA<1>")
	)
	(arc
		(start 77.943456 -253.147576)
		(mid 78.089279 -253.128436)
		(end 78.225142 -253.072138)
		(width 0.0889)
		(layer "In4.Cu")
		(net "M_D_CPU1_SA_CA<1>")
	)
	(arc
		(start 89.878154 -253.071884)
		(mid 90.16111 -253.148061)
		(end 90.444066 -253.071884)
		(width 0.0889)
		(layer "In4.Cu")
		(net "M_D_CPU1_SA_CA<1>")
	)
	(arc
		(start 87.057992 -253.071884)
		(mid 87.340948 -253.148061)
		(end 87.623904 -253.071884)
		(width 0.0889)
		(layer "In4.Cu")
		(net "M_D_CPU1_SA_CA<1>")
	)
	(arc
		(start 84.238084 -253.071884)
		(mid 84.52104 -253.148061)
		(end 84.803996 -253.071884)
		(width 0.0889)
		(layer "In4.Cu")
		(net "M_D_CPU1_SA_CA<1>")
	)
	(arc
		(start 88.9381 -253.071884)
		(mid 89.221056 -253.148061)
		(end 89.504012 -253.071884)
		(width 0.0889)
		(layer "In4.Cu")
		(net "M_D_CPU1_SA_CA<1>")
	)
	(arc
		(start 88.563958 -253.071884)
		(mid 88.746209 -253.021534)
		(end 88.929718 -253.067058)
		(width 0.0889)
		(layer "In4.Cu")
		(net "M_D_CPU1_SA_CA<1>")
	)
	(arc
		(start 79.166466 -253.071884)
		(mid 79.342586 -253.021906)
		(end 79.521304 -253.061724)
		(width 0.0889)
		(layer "In4.Cu")
		(net "M_D_CPU1_SA_CA<1>")
	)
	(arc
		(start 81.052416 -253.067058)
		(mid 81.235924 -253.021564)
		(end 81.418176 -253.071884)
		(width 0.0889)
		(layer "In4.Cu")
		(net "M_D_CPU1_SA_CA<1>")
	)
	(arc
		(start 87.623904 -253.071884)
		(mid 87.806155 -253.021534)
		(end 87.989664 -253.067058)
		(width 0.0889)
		(layer "In4.Cu")
		(net "M_D_CPU1_SA_CA<1>")
	)
	(arc
		(start 78.252574 -253.05639)
		(mid 78.427825 -253.021457)
		(end 78.599284 -253.071884)
		(width 0.0889)
		(layer "In4.Cu")
		(net "M_D_CPU1_SA_CA<1>")
	)
	(arc
		(start 79.561182 -253.084584)
		(mid 79.834211 -253.147903)
		(end 80.10398 -253.071884)
		(width 0.0889)
		(layer "In4.Cu")
		(net "M_D_CPU1_SA_CA<1>")
	)
	(arc
		(start 83.29803 -253.071884)
		(mid 83.580986 -253.148061)
		(end 83.863942 -253.071884)
		(width 0.0889)
		(layer "In4.Cu")
		(net "M_D_CPU1_SA_CA<1>")
	)
	(arc
		(start 80.478122 -253.071884)
		(mid 80.761078 -253.148061)
		(end 81.044034 -253.071884)
		(width 0.0889)
		(layer "In4.Cu")
		(net "M_D_CPU1_SA_CA<1>")
	)
	(arc
		(start 84.812378 -253.067058)
		(mid 84.995886 -253.021564)
		(end 85.178138 -253.071884)
		(width 0.0889)
		(layer "In4.Cu")
		(net "M_D_CPU1_SA_CA<1>")
	)
	(arc
		(start 89.512394 -253.067058)
		(mid 89.695902 -253.021564)
		(end 89.878154 -253.071884)
		(width 0.0889)
		(layer "In4.Cu")
		(net "M_D_CPU1_SA_CA<1>")
	)
	(segment
		(start 91.568016 -252.850396)
		(end 91.10091 -252.584458)
		(width 0.10668)
		(layer "F.Cu")
		(net "M_D_CPU1_SA_CA<0>")
	)
	(segment
		(start 62.376812 -251.947934)
		(end 73.033128 -251.947934)
		(width 0.14478)
		(layer "In4.Cu")
		(net "M_D_CPU1_SA_CA<0>")
	)
	(segment
		(start 77.52207 -252.957076)
		(end 77.94371 -252.957076)
		(width 0.0889)
		(layer "In4.Cu")
		(net "M_D_CPU1_SA_CA<0>")
	)
	(segment
		(start 50.722022 -249.77344)
		(end 50.88509 -249.610372)
		(width 0.14478)
		(layer "In4.Cu")
		(net "M_D_CPU1_SA_CA<0>")
	)
	(segment
		(start 46.094142 -250.001024)
		(end 46.32452 -250.001024)
		(width 0.14478)
		(layer "In4.Cu")
		(net "M_D_CPU1_SA_CA<0>")
	)
	(segment
		(start 50.165508 -249.77344)
		(end 50.165508 -249.840496)
		(width 0.14478)
		(layer "In4.Cu")
		(net "M_D_CPU1_SA_CA<0>")
	)
	(segment
		(start 42.497756 -250.001024)
		(end 42.728134 -250.001024)
		(width 0.14478)
		(layer "In4.Cu")
		(net "M_D_CPU1_SA_CA<0>")
	)
	(segment
		(start 49.05248 -249.840496)
		(end 49.215548 -250.003564)
		(width 0.14478)
		(layer "In4.Cu")
		(net "M_D_CPU1_SA_CA<0>")
	)
	(segment
		(start 42.334688 -249.77344)
		(end 42.334688 -249.837956)
		(width 0.14478)
		(layer "In4.Cu")
		(net "M_D_CPU1_SA_CA<0>")
	)
	(segment
		(start 53.07965 -249.77344)
		(end 53.07965 -249.840496)
		(width 0.14478)
		(layer "In4.Cu")
		(net "M_D_CPU1_SA_CA<0>")
	)
	(segment
		(start 46.487588 -249.77344)
		(end 46.650656 -249.610372)
		(width 0.14478)
		(layer "In4.Cu")
		(net "M_D_CPU1_SA_CA<0>")
	)
	(segment
		(start 79.634842 -252.906784)
		(end 79.654908 -252.918214)
		(width 0.0889)
		(layer "In4.Cu")
		(net "M_D_CPU1_SA_CA<0>")
	)
	(segment
		(start 78.129892 -252.907038)
		(end 78.129892 -252.906784)
		(width 0.0889)
		(layer "In4.Cu")
		(net "M_D_CPU1_SA_CA<0>")
	)
	(segment
		(start 42.891202 -249.837956)
		(end 42.891202 -249.77344)
		(width 0.14478)
		(layer "In4.Cu")
		(net "M_D_CPU1_SA_CA<0>")
	)
	(segment
		(start 49.445926 -250.003564)
		(end 49.608994 -249.840496)
		(width 0.14478)
		(layer "In4.Cu")
		(net "M_D_CPU1_SA_CA<0>")
	)
	(segment
		(start 46.650656 -249.610372)
		(end 48.889412 -249.610372)
		(width 0.14478)
		(layer "In4.Cu")
		(net "M_D_CPU1_SA_CA<0>")
	)
	(segment
		(start 45.931074 -249.837956)
		(end 46.094142 -250.001024)
		(width 0.14478)
		(layer "In4.Cu")
		(net "M_D_CPU1_SA_CA<0>")
	)
	(segment
		(start 79.613252 -252.894338)
		(end 79.634842 -252.906784)
		(width 0.0889)
		(layer "In4.Cu")
		(net "M_D_CPU1_SA_CA<0>")
	)
	(segment
		(start 49.05248 -249.77344)
		(end 49.05248 -249.840496)
		(width 0.14478)
		(layer "In4.Cu")
		(net "M_D_CPU1_SA_CA<0>")
	)
	(segment
		(start 41.615106 -250.001024)
		(end 41.778174 -249.837956)
		(width 0.14478)
		(layer "In4.Cu")
		(net "M_D_CPU1_SA_CA<0>")
	)
	(segment
		(start 38.920928 -249.610372)
		(end 41.058592 -249.610372)
		(width 0.14478)
		(layer "In4.Cu")
		(net "M_D_CPU1_SA_CA<0>")
	)
	(segment
		(start 42.334688 -249.837956)
		(end 42.497756 -250.001024)
		(width 0.14478)
		(layer "In4.Cu")
		(net "M_D_CPU1_SA_CA<0>")
	)
	(segment
		(start 41.22166 -249.77344)
		(end 41.22166 -249.837956)
		(width 0.14478)
		(layer "In4.Cu")
		(net "M_D_CPU1_SA_CA<0>")
	)
	(segment
		(start 48.889412 -249.610372)
		(end 49.05248 -249.77344)
		(width 0.14478)
		(layer "In4.Cu")
		(net "M_D_CPU1_SA_CA<0>")
	)
	(segment
		(start 79.051658 -252.91796)
		(end 79.070454 -252.907038)
		(width 0.0889)
		(layer "In4.Cu")
		(net "M_D_CPU1_SA_CA<0>")
	)
	(segment
		(start 77.03312 -252.468126)
		(end 77.52207 -252.957076)
		(width 0.0889)
		(layer "In4.Cu")
		(net "M_D_CPU1_SA_CA<0>")
	)
	(segment
		(start 49.608994 -249.840496)
		(end 49.608994 -249.77344)
		(width 0.14478)
		(layer "In4.Cu")
		(net "M_D_CPU1_SA_CA<0>")
	)
	(segment
		(start 88.094058 -252.907038)
		(end 88.10244 -252.911864)
		(width 0.0889)
		(layer "In4.Cu")
		(net "M_D_CPU1_SA_CA<0>")
	)
	(segment
		(start 53.636164 -249.77344)
		(end 53.799232 -249.610372)
		(width 0.14478)
		(layer "In4.Cu")
		(net "M_D_CPU1_SA_CA<0>")
	)
	(segment
		(start 49.608994 -249.77344)
		(end 49.772062 -249.610372)
		(width 0.14478)
		(layer "In4.Cu")
		(net "M_D_CPU1_SA_CA<0>")
	)
	(segment
		(start 50.328576 -250.003564)
		(end 50.558954 -250.003564)
		(width 0.14478)
		(layer "In4.Cu")
		(net "M_D_CPU1_SA_CA<0>")
	)
	(segment
		(start 41.941242 -249.610372)
		(end 42.17162 -249.610372)
		(width 0.14478)
		(layer "In4.Cu")
		(net "M_D_CPU1_SA_CA<0>")
	)
	(segment
		(start 42.17162 -249.610372)
		(end 42.334688 -249.77344)
		(width 0.14478)
		(layer "In4.Cu")
		(net "M_D_CPU1_SA_CA<0>")
	)
	(segment
		(start 41.22166 -249.837956)
		(end 41.384728 -250.001024)
		(width 0.14478)
		(layer "In4.Cu")
		(net "M_D_CPU1_SA_CA<0>")
	)
	(segment
		(start 53.242718 -250.003564)
		(end 53.473096 -250.003564)
		(width 0.14478)
		(layer "In4.Cu")
		(net "M_D_CPU1_SA_CA<0>")
	)
	(segment
		(start 50.722022 -249.840496)
		(end 50.722022 -249.77344)
		(width 0.14478)
		(layer "In4.Cu")
		(net "M_D_CPU1_SA_CA<0>")
	)
	(segment
		(start 53.07965 -249.840496)
		(end 53.242718 -250.003564)
		(width 0.14478)
		(layer "In4.Cu")
		(net "M_D_CPU1_SA_CA<0>")
	)
	(segment
		(start 42.891202 -249.77344)
		(end 43.05427 -249.610372)
		(width 0.14478)
		(layer "In4.Cu")
		(net "M_D_CPU1_SA_CA<0>")
	)
	(segment
		(start 83.394042 -252.907038)
		(end 83.402424 -252.911864)
		(width 0.0889)
		(layer "In4.Cu")
		(net "M_D_CPU1_SA_CA<0>")
	)
	(segment
		(start 76.123546 -252.723904)
		(end 76.293472 -252.723904)
		(width 0.0889)
		(layer "In4.Cu")
		(net "M_D_CPU1_SA_CA<0>")
	)
	(segment
		(start 49.215548 -250.003564)
		(end 49.445926 -250.003564)
		(width 0.14478)
		(layer "In4.Cu")
		(net "M_D_CPU1_SA_CA<0>")
	)
	(segment
		(start 41.778174 -249.837956)
		(end 41.778174 -249.77344)
		(width 0.14478)
		(layer "In4.Cu")
		(net "M_D_CPU1_SA_CA<0>")
	)
	(segment
		(start 90.339672 -252.911864)
		(end 90.348054 -252.907038)
		(width 0.0889)
		(layer "In4.Cu")
		(net "M_D_CPU1_SA_CA<0>")
	)
	(segment
		(start 52.916582 -249.610372)
		(end 53.07965 -249.77344)
		(width 0.14478)
		(layer "In4.Cu")
		(net "M_D_CPU1_SA_CA<0>")
	)
	(segment
		(start 50.88509 -249.610372)
		(end 52.916582 -249.610372)
		(width 0.14478)
		(layer "In4.Cu")
		(net "M_D_CPU1_SA_CA<0>")
	)
	(segment
		(start 90.850974 -252.875288)
		(end 90.946986 -252.849888)
		(width 0.0889)
		(layer "In4.Cu")
		(net "M_D_CPU1_SA_CA<0>")
	)
	(segment
		(start 53.473096 -250.003564)
		(end 53.636164 -249.840496)
		(width 0.14478)
		(layer "In4.Cu")
		(net "M_D_CPU1_SA_CA<0>")
	)
	(segment
		(start 42.728134 -250.001024)
		(end 42.891202 -249.837956)
		(width 0.14478)
		(layer "In4.Cu")
		(net "M_D_CPU1_SA_CA<0>")
	)
	(segment
		(start 41.778174 -249.77344)
		(end 41.941242 -249.610372)
		(width 0.14478)
		(layer "In4.Cu")
		(net "M_D_CPU1_SA_CA<0>")
	)
	(segment
		(start 90.946986 -252.849888)
		(end 91.10091 -252.584458)
		(width 0.0889)
		(layer "In4.Cu")
		(net "M_D_CPU1_SA_CA<0>")
	)
	(segment
		(start 36.795964 -247.485408)
		(end 38.920928 -249.610372)
		(width 0.14478)
		(layer "In4.Cu")
		(net "M_D_CPU1_SA_CA<0>")
	)
	(segment
		(start 78.129892 -252.906784)
		(end 78.129638 -252.906784)
		(width 0.0889)
		(layer "In4.Cu")
		(net "M_D_CPU1_SA_CA<0>")
	)
	(segment
		(start 41.384728 -250.001024)
		(end 41.615106 -250.001024)
		(width 0.14478)
		(layer "In4.Cu")
		(net "M_D_CPU1_SA_CA<0>")
	)
	(segment
		(start 50.558954 -250.003564)
		(end 50.722022 -249.840496)
		(width 0.14478)
		(layer "In4.Cu")
		(net "M_D_CPU1_SA_CA<0>")
	)
	(segment
		(start 45.931074 -249.77344)
		(end 45.931074 -249.837956)
		(width 0.14478)
		(layer "In4.Cu")
		(net "M_D_CPU1_SA_CA<0>")
	)
	(segment
		(start 49.772062 -249.610372)
		(end 50.00244 -249.610372)
		(width 0.14478)
		(layer "In4.Cu")
		(net "M_D_CPU1_SA_CA<0>")
	)
	(segment
		(start 86.57971 -252.911864)
		(end 86.588092 -252.907038)
		(width 0.0889)
		(layer "In4.Cu")
		(net "M_D_CPU1_SA_CA<0>")
	)
	(segment
		(start 50.165508 -249.840496)
		(end 50.328576 -250.003564)
		(width 0.14478)
		(layer "In4.Cu")
		(net "M_D_CPU1_SA_CA<0>")
	)
	(segment
		(start 41.058592 -249.610372)
		(end 41.22166 -249.77344)
		(width 0.14478)
		(layer "In4.Cu")
		(net "M_D_CPU1_SA_CA<0>")
	)
	(segment
		(start 76.54925 -252.468126)
		(end 77.03312 -252.468126)
		(width 0.0889)
		(layer "In4.Cu")
		(net "M_D_CPU1_SA_CA<0>")
	)
	(segment
		(start 76.293472 -252.723904)
		(end 76.54925 -252.468126)
		(width 0.0889)
		(layer "In4.Cu")
		(net "M_D_CPU1_SA_CA<0>")
	)
	(segment
		(start 46.32452 -250.001024)
		(end 46.487588 -249.837956)
		(width 0.14478)
		(layer "In4.Cu")
		(net "M_D_CPU1_SA_CA<0>")
	)
	(segment
		(start 87.154004 -252.907038)
		(end 87.162386 -252.911864)
		(width 0.0889)
		(layer "In4.Cu")
		(net "M_D_CPU1_SA_CA<0>")
	)
	(segment
		(start 45.768006 -249.610372)
		(end 45.931074 -249.77344)
		(width 0.14478)
		(layer "In4.Cu")
		(net "M_D_CPU1_SA_CA<0>")
	)
	(segment
		(start 73.033128 -251.947934)
		(end 73.809098 -252.723904)
		(width 0.14478)
		(layer "In4.Cu")
		(net "M_D_CPU1_SA_CA<0>")
	)
	(segment
		(start 78.129638 -252.906784)
		(end 78.161388 -252.888496)
		(width 0.0889)
		(layer "In4.Cu")
		(net "M_D_CPU1_SA_CA<0>")
	)
	(segment
		(start 73.809098 -252.723904)
		(end 76.123546 -252.723904)
		(width 0.14478)
		(layer "In4.Cu")
		(net "M_D_CPU1_SA_CA<0>")
	)
	(segment
		(start 43.05427 -249.610372)
		(end 45.768006 -249.610372)
		(width 0.14478)
		(layer "In4.Cu")
		(net "M_D_CPU1_SA_CA<0>")
	)
	(segment
		(start 53.799232 -249.610372)
		(end 60.03925 -249.610372)
		(width 0.14478)
		(layer "In4.Cu")
		(net "M_D_CPU1_SA_CA<0>")
	)
	(segment
		(start 46.487588 -249.837956)
		(end 46.487588 -249.77344)
		(width 0.14478)
		(layer "In4.Cu")
		(net "M_D_CPU1_SA_CA<0>")
	)
	(segment
		(start 85.639656 -252.911864)
		(end 85.648038 -252.907038)
		(width 0.0889)
		(layer "In4.Cu")
		(net "M_D_CPU1_SA_CA<0>")
	)
	(segment
		(start 82.453988 -252.907038)
		(end 82.46237 -252.911864)
		(width 0.0889)
		(layer "In4.Cu")
		(net "M_D_CPU1_SA_CA<0>")
	)
	(segment
		(start 60.03925 -249.610372)
		(end 62.376812 -251.947934)
		(width 0.14478)
		(layer "In4.Cu")
		(net "M_D_CPU1_SA_CA<0>")
	)
	(segment
		(start 50.00244 -249.610372)
		(end 50.165508 -249.77344)
		(width 0.14478)
		(layer "In4.Cu")
		(net "M_D_CPU1_SA_CA<0>")
	)
	(segment
		(start 53.636164 -249.840496)
		(end 53.636164 -249.77344)
		(width 0.14478)
		(layer "In4.Cu")
		(net "M_D_CPU1_SA_CA<0>")
	)
	(segment
		(start 81.879694 -252.911864)
		(end 81.888076 -252.907038)
		(width 0.0889)
		(layer "In4.Cu")
		(net "M_D_CPU1_SA_CA<0>")
	)
	(arc
		(start 86.588092 -252.907038)
		(mid 86.871048 -252.830861)
		(end 87.154004 -252.907038)
		(width 0.0889)
		(layer "In4.Cu")
		(net "M_D_CPU1_SA_CA<0>")
	)
	(arc
		(start 84.334096 -252.907038)
		(mid 84.52104 -252.957293)
		(end 84.707984 -252.907038)
		(width 0.0889)
		(layer "In4.Cu")
		(net "M_D_CPU1_SA_CA<0>")
	)
	(arc
		(start 89.034112 -252.907038)
		(mid 89.221056 -252.957293)
		(end 89.408 -252.907038)
		(width 0.0889)
		(layer "In4.Cu")
		(net "M_D_CPU1_SA_CA<0>")
	)
	(arc
		(start 77.94371 -252.957076)
		(mid 78.040101 -252.944325)
		(end 78.129892 -252.907038)
		(width 0.0889)
		(layer "In4.Cu")
		(net "M_D_CPU1_SA_CA<0>")
	)
	(arc
		(start 86.21395 -252.907038)
		(mid 86.396201 -252.957388)
		(end 86.57971 -252.911864)
		(width 0.0889)
		(layer "In4.Cu")
		(net "M_D_CPU1_SA_CA<0>")
	)
	(arc
		(start 87.528146 -252.907038)
		(mid 87.811102 -252.830861)
		(end 88.094058 -252.907038)
		(width 0.0889)
		(layer "In4.Cu")
		(net "M_D_CPU1_SA_CA<0>")
	)
	(arc
		(start 85.273896 -252.907038)
		(mid 85.456147 -252.957388)
		(end 85.639656 -252.911864)
		(width 0.0889)
		(layer "In4.Cu")
		(net "M_D_CPU1_SA_CA<0>")
	)
	(arc
		(start 81.888076 -252.907038)
		(mid 82.171032 -252.830861)
		(end 82.453988 -252.907038)
		(width 0.0889)
		(layer "In4.Cu")
		(net "M_D_CPU1_SA_CA<0>")
	)
	(arc
		(start 88.10244 -252.911864)
		(mid 88.285948 -252.957358)
		(end 88.4682 -252.907038)
		(width 0.0889)
		(layer "In4.Cu")
		(net "M_D_CPU1_SA_CA<0>")
	)
	(arc
		(start 79.070454 -252.907038)
		(mid 79.340223 -252.831015)
		(end 79.613252 -252.894338)
		(width 0.0889)
		(layer "In4.Cu")
		(net "M_D_CPU1_SA_CA<0>")
	)
	(arc
		(start 82.46237 -252.911864)
		(mid 82.645878 -252.957358)
		(end 82.82813 -252.907038)
		(width 0.0889)
		(layer "In4.Cu")
		(net "M_D_CPU1_SA_CA<0>")
	)
	(arc
		(start 80.948022 -252.907038)
		(mid 81.230978 -252.830861)
		(end 81.513934 -252.907038)
		(width 0.0889)
		(layer "In4.Cu")
		(net "M_D_CPU1_SA_CA<0>")
	)
	(arc
		(start 80.008222 -252.907038)
		(mid 80.291178 -252.830861)
		(end 80.574134 -252.907038)
		(width 0.0889)
		(layer "In4.Cu")
		(net "M_D_CPU1_SA_CA<0>")
	)
	(arc
		(start 89.408 -252.907038)
		(mid 89.690956 -252.830861)
		(end 89.973912 -252.907038)
		(width 0.0889)
		(layer "In4.Cu")
		(net "M_D_CPU1_SA_CA<0>")
	)
	(arc
		(start 89.973912 -252.907038)
		(mid 90.156163 -252.957388)
		(end 90.339672 -252.911864)
		(width 0.0889)
		(layer "In4.Cu")
		(net "M_D_CPU1_SA_CA<0>")
	)
	(arc
		(start 85.648038 -252.907038)
		(mid 85.930994 -252.830861)
		(end 86.21395 -252.907038)
		(width 0.0889)
		(layer "In4.Cu")
		(net "M_D_CPU1_SA_CA<0>")
	)
	(arc
		(start 80.574134 -252.907038)
		(mid 80.761078 -252.957293)
		(end 80.948022 -252.907038)
		(width 0.0889)
		(layer "In4.Cu")
		(net "M_D_CPU1_SA_CA<0>")
	)
	(arc
		(start 88.4682 -252.907038)
		(mid 88.751156 -252.830861)
		(end 89.034112 -252.907038)
		(width 0.0889)
		(layer "In4.Cu")
		(net "M_D_CPU1_SA_CA<0>")
	)
	(arc
		(start 87.162386 -252.911864)
		(mid 87.345894 -252.957358)
		(end 87.528146 -252.907038)
		(width 0.0889)
		(layer "In4.Cu")
		(net "M_D_CPU1_SA_CA<0>")
	)
	(arc
		(start 78.161388 -252.888496)
		(mid 78.430673 -252.830584)
		(end 78.695296 -252.907038)
		(width 0.0889)
		(layer "In4.Cu")
		(net "M_D_CPU1_SA_CA<0>")
	)
	(arc
		(start 84.707984 -252.907038)
		(mid 84.99094 -252.830861)
		(end 85.273896 -252.907038)
		(width 0.0889)
		(layer "In4.Cu")
		(net "M_D_CPU1_SA_CA<0>")
	)
	(arc
		(start 82.82813 -252.907038)
		(mid 83.111086 -252.830861)
		(end 83.394042 -252.907038)
		(width 0.0889)
		(layer "In4.Cu")
		(net "M_D_CPU1_SA_CA<0>")
	)
	(arc
		(start 81.513934 -252.907038)
		(mid 81.696185 -252.957388)
		(end 81.879694 -252.911864)
		(width 0.0889)
		(layer "In4.Cu")
		(net "M_D_CPU1_SA_CA<0>")
	)
	(arc
		(start 78.695296 -252.907038)
		(mid 78.872087 -252.957757)
		(end 79.051658 -252.91796)
		(width 0.0889)
		(layer "In4.Cu")
		(net "M_D_CPU1_SA_CA<0>")
	)
	(arc
		(start 83.402424 -252.911864)
		(mid 83.585932 -252.957358)
		(end 83.768184 -252.907038)
		(width 0.0889)
		(layer "In4.Cu")
		(net "M_D_CPU1_SA_CA<0>")
	)
	(arc
		(start 83.768184 -252.907038)
		(mid 84.05114 -252.830861)
		(end 84.334096 -252.907038)
		(width 0.0889)
		(layer "In4.Cu")
		(net "M_D_CPU1_SA_CA<0>")
	)
	(arc
		(start 79.654908 -252.918214)
		(mid 79.832986 -252.957198)
		(end 80.008222 -252.907038)
		(width 0.0889)
		(layer "In4.Cu")
		(net "M_D_CPU1_SA_CA<0>")
	)
	(arc
		(start 90.348054 -252.907038)
		(mid 90.595767 -252.831818)
		(end 90.850974 -252.875288)
		(width 0.0889)
		(layer "In4.Cu")
		(net "M_D_CPU1_SA_CA<0>")
	)
	(segment
		(start 92.507816 -251.230384)
		(end 92.040964 -250.964446)
		(width 0.10668)
		(layer "F.Cu")
		(net "M_D_CPU1_RESET_N")
	)
	(segment
		(start 32.695896 -244.935248)
		(end 33.120838 -245.36019)
		(width 0.11684)
		(layer "In4.Cu")
		(net "M_D_CPU1_RESET_N")
	)
	(segment
		(start 76.313792 -250.834144)
		(end 76.37653 -250.771406)
		(width 0.0889)
		(layer "In4.Cu")
		(net "M_D_CPU1_RESET_N")
	)
	(segment
		(start 76.014326 -250.834144)
		(end 76.313792 -250.834144)
		(width 0.0889)
		(layer "In4.Cu")
		(net "M_D_CPU1_RESET_N")
	)
	(segment
		(start 91.85402 -250.641866)
		(end 91.862402 -250.63704)
		(width 0.0889)
		(layer "In4.Cu")
		(net "M_D_CPU1_RESET_N")
	)
	(segment
		(start 92.195142 -250.699016)
		(end 92.040964 -250.964446)
		(width 0.0889)
		(layer "In4.Cu")
		(net "M_D_CPU1_RESET_N")
	)
	(segment
		(start 76.37653 -250.771406)
		(end 78.5114 -250.771406)
		(width 0.0889)
		(layer "In4.Cu")
		(net "M_D_CPU1_RESET_N")
	)
	(segment
		(start 79.63408 -250.641866)
		(end 79.642462 -250.63704)
		(width 0.0889)
		(layer "In4.Cu")
		(net "M_D_CPU1_RESET_N")
	)
	(segment
		(start 86.57971 -250.63704)
		(end 86.588092 -250.641866)
		(width 0.0889)
		(layer "In4.Cu")
		(net "M_D_CPU1_RESET_N")
	)
	(segment
		(start 73.734422 -250.308364)
		(end 74.260202 -250.834144)
		(width 0.11684)
		(layer "In4.Cu")
		(net "M_D_CPU1_RESET_N")
	)
	(segment
		(start 74.260202 -250.834144)
		(end 76.014326 -250.834144)
		(width 0.11684)
		(layer "In4.Cu")
		(net "M_D_CPU1_RESET_N")
	)
	(segment
		(start 85.639656 -250.63704)
		(end 85.648038 -250.641866)
		(width 0.0889)
		(layer "In4.Cu")
		(net "M_D_CPU1_RESET_N")
	)
	(segment
		(start 63.138558 -250.308364)
		(end 73.734422 -250.308364)
		(width 0.11684)
		(layer "In4.Cu")
		(net "M_D_CPU1_RESET_N")
	)
	(segment
		(start 92.17279 -250.615704)
		(end 92.195142 -250.699016)
		(width 0.0889)
		(layer "In4.Cu")
		(net "M_D_CPU1_RESET_N")
	)
	(segment
		(start 82.453988 -250.641866)
		(end 82.46237 -250.63704)
		(width 0.0889)
		(layer "In4.Cu")
		(net "M_D_CPU1_RESET_N")
	)
	(segment
		(start 33.120838 -245.36019)
		(end 37.680138 -245.36019)
		(width 0.11684)
		(layer "In4.Cu")
		(net "M_D_CPU1_RESET_N")
	)
	(segment
		(start 91.279726 -250.63704)
		(end 91.288108 -250.641866)
		(width 0.0889)
		(layer "In4.Cu")
		(net "M_D_CPU1_RESET_N")
	)
	(segment
		(start 83.394042 -250.641866)
		(end 83.402424 -250.63704)
		(width 0.0889)
		(layer "In4.Cu")
		(net "M_D_CPU1_RESET_N")
	)
	(segment
		(start 90.339672 -250.63704)
		(end 90.348054 -250.641866)
		(width 0.0889)
		(layer "In4.Cu")
		(net "M_D_CPU1_RESET_N")
	)
	(segment
		(start 87.154004 -250.641866)
		(end 87.162386 -250.63704)
		(width 0.0889)
		(layer "In4.Cu")
		(net "M_D_CPU1_RESET_N")
	)
	(segment
		(start 88.094058 -250.641866)
		(end 88.10244 -250.63704)
		(width 0.0889)
		(layer "In4.Cu")
		(net "M_D_CPU1_RESET_N")
	)
	(segment
		(start 81.879694 -250.63704)
		(end 81.888076 -250.641866)
		(width 0.0889)
		(layer "In4.Cu")
		(net "M_D_CPU1_RESET_N")
	)
	(segment
		(start 78.591664 -250.738132)
		(end 78.655164 -250.674632)
		(width 0.0889)
		(layer "In4.Cu")
		(net "M_D_CPU1_RESET_N")
	)
	(segment
		(start 59.890406 -247.060212)
		(end 63.138558 -250.308364)
		(width 0.11684)
		(layer "In4.Cu")
		(net "M_D_CPU1_RESET_N")
	)
	(segment
		(start 37.680138 -245.36019)
		(end 39.38016 -247.060212)
		(width 0.11684)
		(layer "In4.Cu")
		(net "M_D_CPU1_RESET_N")
	)
	(segment
		(start 39.38016 -247.060212)
		(end 59.890406 -247.060212)
		(width 0.11684)
		(layer "In4.Cu")
		(net "M_D_CPU1_RESET_N")
	)
	(arc
		(start 84.707984 -250.641866)
		(mid 84.99094 -250.718043)
		(end 85.273896 -250.641866)
		(width 0.0889)
		(layer "In4.Cu")
		(net "M_D_CPU1_RESET_N")
	)
	(arc
		(start 88.10244 -250.63704)
		(mid 88.285948 -250.591546)
		(end 88.4682 -250.641866)
		(width 0.0889)
		(layer "In4.Cu")
		(net "M_D_CPU1_RESET_N")
	)
	(arc
		(start 87.528146 -250.641866)
		(mid 87.811102 -250.718043)
		(end 88.094058 -250.641866)
		(width 0.0889)
		(layer "In4.Cu")
		(net "M_D_CPU1_RESET_N")
	)
	(arc
		(start 80.008222 -250.641866)
		(mid 80.291178 -250.718043)
		(end 80.574134 -250.641866)
		(width 0.0889)
		(layer "In4.Cu")
		(net "M_D_CPU1_RESET_N")
	)
	(arc
		(start 83.402424 -250.63704)
		(mid 83.585932 -250.591546)
		(end 83.768184 -250.641866)
		(width 0.0889)
		(layer "In4.Cu")
		(net "M_D_CPU1_RESET_N")
	)
	(arc
		(start 91.288108 -250.641866)
		(mid 91.571064 -250.718043)
		(end 91.85402 -250.641866)
		(width 0.0889)
		(layer "In4.Cu")
		(net "M_D_CPU1_RESET_N")
	)
	(arc
		(start 82.46237 -250.63704)
		(mid 82.645878 -250.591546)
		(end 82.82813 -250.641866)
		(width 0.0889)
		(layer "In4.Cu")
		(net "M_D_CPU1_RESET_N")
	)
	(arc
		(start 81.513934 -250.641866)
		(mid 81.696185 -250.591516)
		(end 81.879694 -250.63704)
		(width 0.0889)
		(layer "In4.Cu")
		(net "M_D_CPU1_RESET_N")
	)
	(arc
		(start 86.21395 -250.641866)
		(mid 86.396201 -250.591516)
		(end 86.57971 -250.63704)
		(width 0.0889)
		(layer "In4.Cu")
		(net "M_D_CPU1_RESET_N")
	)
	(arc
		(start 90.913966 -250.641866)
		(mid 91.096217 -250.591516)
		(end 91.279726 -250.63704)
		(width 0.0889)
		(layer "In4.Cu")
		(net "M_D_CPU1_RESET_N")
	)
	(arc
		(start 79.642462 -250.63704)
		(mid 79.82597 -250.591546)
		(end 80.008222 -250.641866)
		(width 0.0889)
		(layer "In4.Cu")
		(net "M_D_CPU1_RESET_N")
	)
	(arc
		(start 78.5114 -250.771406)
		(mid 78.554835 -250.762748)
		(end 78.591664 -250.738132)
		(width 0.0889)
		(layer "In4.Cu")
		(net "M_D_CPU1_RESET_N")
	)
	(arc
		(start 80.948022 -250.641866)
		(mid 81.230978 -250.718043)
		(end 81.513934 -250.641866)
		(width 0.0889)
		(layer "In4.Cu")
		(net "M_D_CPU1_RESET_N")
	)
	(arc
		(start 89.973912 -250.641866)
		(mid 90.156163 -250.591516)
		(end 90.339672 -250.63704)
		(width 0.0889)
		(layer "In4.Cu")
		(net "M_D_CPU1_RESET_N")
	)
	(arc
		(start 80.574134 -250.641866)
		(mid 80.761078 -250.591611)
		(end 80.948022 -250.641866)
		(width 0.0889)
		(layer "In4.Cu")
		(net "M_D_CPU1_RESET_N")
	)
	(arc
		(start 83.768184 -250.641866)
		(mid 84.05114 -250.718043)
		(end 84.334096 -250.641866)
		(width 0.0889)
		(layer "In4.Cu")
		(net "M_D_CPU1_RESET_N")
	)
	(arc
		(start 78.728316 -250.624086)
		(mid 78.900397 -250.591927)
		(end 79.068168 -250.641866)
		(width 0.0889)
		(layer "In4.Cu")
		(net "M_D_CPU1_RESET_N")
	)
	(arc
		(start 84.334096 -250.641866)
		(mid 84.52104 -250.591611)
		(end 84.707984 -250.641866)
		(width 0.0889)
		(layer "In4.Cu")
		(net "M_D_CPU1_RESET_N")
	)
	(arc
		(start 90.348054 -250.641866)
		(mid 90.63101 -250.718043)
		(end 90.913966 -250.641866)
		(width 0.0889)
		(layer "In4.Cu")
		(net "M_D_CPU1_RESET_N")
	)
	(arc
		(start 86.588092 -250.641866)
		(mid 86.871048 -250.718043)
		(end 87.154004 -250.641866)
		(width 0.0889)
		(layer "In4.Cu")
		(net "M_D_CPU1_RESET_N")
	)
	(arc
		(start 85.273896 -250.641866)
		(mid 85.456147 -250.591516)
		(end 85.639656 -250.63704)
		(width 0.0889)
		(layer "In4.Cu")
		(net "M_D_CPU1_RESET_N")
	)
	(arc
		(start 88.4682 -250.641866)
		(mid 88.751156 -250.718043)
		(end 89.034112 -250.641866)
		(width 0.0889)
		(layer "In4.Cu")
		(net "M_D_CPU1_RESET_N")
	)
	(arc
		(start 78.655164 -250.674632)
		(mid 78.689428 -250.646012)
		(end 78.728316 -250.624086)
		(width 0.0889)
		(layer "In4.Cu")
		(net "M_D_CPU1_RESET_N")
	)
	(arc
		(start 79.068168 -250.641866)
		(mid 79.351124 -250.718043)
		(end 79.63408 -250.641866)
		(width 0.0889)
		(layer "In4.Cu")
		(net "M_D_CPU1_RESET_N")
	)
	(arc
		(start 85.648038 -250.641866)
		(mid 85.930994 -250.718043)
		(end 86.21395 -250.641866)
		(width 0.0889)
		(layer "In4.Cu")
		(net "M_D_CPU1_RESET_N")
	)
	(arc
		(start 82.82813 -250.641866)
		(mid 83.111086 -250.718043)
		(end 83.394042 -250.641866)
		(width 0.0889)
		(layer "In4.Cu")
		(net "M_D_CPU1_RESET_N")
	)
	(arc
		(start 91.862402 -250.63704)
		(mid 92.015272 -250.592399)
		(end 92.17279 -250.615704)
		(width 0.0889)
		(layer "In4.Cu")
		(net "M_D_CPU1_RESET_N")
	)
	(arc
		(start 87.162386 -250.63704)
		(mid 87.345894 -250.591546)
		(end 87.528146 -250.641866)
		(width 0.0889)
		(layer "In4.Cu")
		(net "M_D_CPU1_RESET_N")
	)
	(arc
		(start 89.408 -250.641866)
		(mid 89.690956 -250.718043)
		(end 89.973912 -250.641866)
		(width 0.0889)
		(layer "In4.Cu")
		(net "M_D_CPU1_RESET_N")
	)
	(arc
		(start 81.888076 -250.641866)
		(mid 82.171032 -250.718043)
		(end 82.453988 -250.641866)
		(width 0.0889)
		(layer "In4.Cu")
		(net "M_D_CPU1_RESET_N")
	)
	(arc
		(start 89.034112 -250.641866)
		(mid 89.221056 -250.591611)
		(end 89.408 -250.641866)
		(width 0.0889)
		(layer "In4.Cu")
		(net "M_D_CPU1_RESET_N")
	)
	(segment
		(start 91.568016 -256.09042)
		(end 91.10091 -255.824482)
		(width 0.14732)
		(layer "F.Cu")
		(net "M_D_CPU1_CLK_DP<0>")
	)
	(segment
		(start 76.225908 -257.290824)
		(end 76.202286 -257.290824)
		(width 0.09525)
		(layer "In4.Cu")
		(net "M_D_CPU1_CLK_DP<0>")
	)
	(segment
		(start 78.165706 -256.129536)
		(end 78.131162 -256.149602)
		(width 0.09525)
		(layer "In4.Cu")
		(net "M_D_CPU1_CLK_DP<0>")
	)
	(segment
		(start 33.857692 -253.70917)
		(end 32.969708 -253.70917)
		(width 0.16002)
		(layer "In4.Cu")
		(net "M_D_CPU1_CLK_DP<0>")
	)
	(segment
		(start 32.969708 -253.70917)
		(end 32.695896 -253.435358)
		(width 0.16002)
		(layer "In4.Cu")
		(net "M_D_CPU1_CLK_DP<0>")
	)
	(segment
		(start 90.946986 -256.089912)
		(end 90.846148 -256.116582)
		(width 0.09525)
		(layer "In4.Cu")
		(net "M_D_CPU1_CLK_DP<0>")
	)
	(segment
		(start 90.349578 -256.149602)
		(end 90.341196 -256.154428)
		(width 0.09525)
		(layer "In4.Cu")
		(net "M_D_CPU1_CLK_DP<0>")
	)
	(segment
		(start 81.8896 -256.149602)
		(end 81.881218 -256.154428)
		(width 0.09525)
		(layer "In4.Cu")
		(net "M_D_CPU1_CLK_DP<0>")
	)
	(segment
		(start 83.4009 -256.154428)
		(end 83.392518 -256.149602)
		(width 0.09525)
		(layer "In4.Cu")
		(net "M_D_CPU1_CLK_DP<0>")
	)
	(segment
		(start 87.160862 -256.154428)
		(end 87.15248 -256.149602)
		(width 0.09525)
		(layer "In4.Cu")
		(net "M_D_CPU1_CLK_DP<0>")
	)
	(segment
		(start 91.10091 -255.824482)
		(end 90.946986 -256.089912)
		(width 0.09525)
		(layer "In4.Cu")
		(net "M_D_CPU1_CLK_DP<0>")
	)
	(segment
		(start 65.397126 -256.432304)
		(end 36.580826 -256.432304)
		(width 0.16002)
		(layer "In4.Cu")
		(net "M_D_CPU1_CLK_DP<0>")
	)
	(segment
		(start 78.015338 -256.238248)
		(end 76.90358 -257.350006)
		(width 0.09525)
		(layer "In4.Cu")
		(net "M_D_CPU1_CLK_DP<0>")
	)
	(segment
		(start 76.28509 -257.350006)
		(end 76.225908 -257.290824)
		(width 0.09525)
		(layer "In4.Cu")
		(net "M_D_CPU1_CLK_DP<0>")
	)
	(segment
		(start 79.071216 -256.149602)
		(end 79.04734 -256.163318)
		(width 0.09525)
		(layer "In4.Cu")
		(net "M_D_CPU1_CLK_DP<0>")
	)
	(segment
		(start 88.100916 -256.154428)
		(end 88.092534 -256.149602)
		(width 0.09525)
		(layer "In4.Cu")
		(net "M_D_CPU1_CLK_DP<0>")
	)
	(segment
		(start 71.238364 -255.755394)
		(end 66.074036 -255.755394)
		(width 0.16002)
		(layer "In4.Cu")
		(net "M_D_CPU1_CLK_DP<0>")
	)
	(segment
		(start 72.773794 -257.290824)
		(end 71.238364 -255.755394)
		(width 0.16002)
		(layer "In4.Cu")
		(net "M_D_CPU1_CLK_DP<0>")
	)
	(segment
		(start 86.589616 -256.149602)
		(end 86.581234 -256.154428)
		(width 0.09525)
		(layer "In4.Cu")
		(net "M_D_CPU1_CLK_DP<0>")
	)
	(segment
		(start 82.460846 -256.154428)
		(end 82.452464 -256.149602)
		(width 0.09525)
		(layer "In4.Cu")
		(net "M_D_CPU1_CLK_DP<0>")
	)
	(segment
		(start 79.096616 -256.13487)
		(end 79.071216 -256.149602)
		(width 0.09525)
		(layer "In4.Cu")
		(net "M_D_CPU1_CLK_DP<0>")
	)
	(segment
		(start 36.580826 -256.432304)
		(end 33.857692 -253.70917)
		(width 0.16002)
		(layer "In4.Cu")
		(net "M_D_CPU1_CLK_DP<0>")
	)
	(segment
		(start 76.202286 -257.290824)
		(end 72.773794 -257.290824)
		(width 0.16002)
		(layer "In4.Cu")
		(net "M_D_CPU1_CLK_DP<0>")
	)
	(segment
		(start 66.074036 -255.755394)
		(end 65.397126 -256.432304)
		(width 0.16002)
		(layer "In4.Cu")
		(net "M_D_CPU1_CLK_DP<0>")
	)
	(segment
		(start 79.640938 -256.154428)
		(end 79.632556 -256.149602)
		(width 0.09525)
		(layer "In4.Cu")
		(net "M_D_CPU1_CLK_DP<0>")
	)
	(segment
		(start 76.90358 -257.350006)
		(end 76.28509 -257.350006)
		(width 0.09525)
		(layer "In4.Cu")
		(net "M_D_CPU1_CLK_DP<0>")
	)
	(segment
		(start 85.649562 -256.149602)
		(end 85.64118 -256.154428)
		(width 0.09525)
		(layer "In4.Cu")
		(net "M_D_CPU1_CLK_DP<0>")
	)
	(arc
		(start 88.469724 -256.149602)
		(mid 88.285949 -256.200374)
		(end 88.100916 -256.154428)
		(width 0.09525)
		(layer "In4.Cu")
		(net "M_D_CPU1_CLK_DP<0>")
	)
	(arc
		(start 83.769708 -256.149602)
		(mid 83.585933 -256.200374)
		(end 83.4009 -256.154428)
		(width 0.09525)
		(layer "In4.Cu")
		(net "M_D_CPU1_CLK_DP<0>")
	)
	(arc
		(start 79.632556 -256.149602)
		(mid 79.366469 -256.074057)
		(end 79.096616 -256.13487)
		(width 0.09525)
		(layer "In4.Cu")
		(net "M_D_CPU1_CLK_DP<0>")
	)
	(arc
		(start 90.341196 -256.154428)
		(mid 90.156164 -256.200342)
		(end 89.972388 -256.149602)
		(width 0.09525)
		(layer "In4.Cu")
		(net "M_D_CPU1_CLK_DP<0>")
	)
	(arc
		(start 78.0415 -256.213864)
		(mid 78.028224 -256.225847)
		(end 78.015338 -256.238248)
		(width 0.09525)
		(layer "In4.Cu")
		(net "M_D_CPU1_CLK_DP<0>")
	)
	(arc
		(start 79.04734 -256.163318)
		(mid 78.868854 -256.200561)
		(end 78.693772 -256.149602)
		(width 0.09525)
		(layer "In4.Cu")
		(net "M_D_CPU1_CLK_DP<0>")
	)
	(arc
		(start 88.092534 -256.149602)
		(mid 87.811102 -256.073847)
		(end 87.52967 -256.149602)
		(width 0.09525)
		(layer "In4.Cu")
		(net "M_D_CPU1_CLK_DP<0>")
	)
	(arc
		(start 84.709508 -256.149602)
		(mid 84.52104 -256.200279)
		(end 84.332572 -256.149602)
		(width 0.09525)
		(layer "In4.Cu")
		(net "M_D_CPU1_CLK_DP<0>")
	)
	(arc
		(start 85.272372 -256.149602)
		(mid 84.99094 -256.073847)
		(end 84.709508 -256.149602)
		(width 0.09525)
		(layer "In4.Cu")
		(net "M_D_CPU1_CLK_DP<0>")
	)
	(arc
		(start 86.581234 -256.154428)
		(mid 86.396202 -256.200342)
		(end 86.212426 -256.149602)
		(width 0.09525)
		(layer "In4.Cu")
		(net "M_D_CPU1_CLK_DP<0>")
	)
	(arc
		(start 89.032588 -256.149602)
		(mid 88.751156 -256.073847)
		(end 88.469724 -256.149602)
		(width 0.09525)
		(layer "In4.Cu")
		(net "M_D_CPU1_CLK_DP<0>")
	)
	(arc
		(start 89.409524 -256.149602)
		(mid 89.221056 -256.200279)
		(end 89.032588 -256.149602)
		(width 0.09525)
		(layer "In4.Cu")
		(net "M_D_CPU1_CLK_DP<0>")
	)
	(arc
		(start 84.332572 -256.149602)
		(mid 84.05114 -256.073847)
		(end 83.769708 -256.149602)
		(width 0.09525)
		(layer "In4.Cu")
		(net "M_D_CPU1_CLK_DP<0>")
	)
	(arc
		(start 80.009746 -256.149602)
		(mid 79.825971 -256.200374)
		(end 79.640938 -256.154428)
		(width 0.09525)
		(layer "In4.Cu")
		(net "M_D_CPU1_CLK_DP<0>")
	)
	(arc
		(start 86.212426 -256.149602)
		(mid 85.930994 -256.073847)
		(end 85.649562 -256.149602)
		(width 0.09525)
		(layer "In4.Cu")
		(net "M_D_CPU1_CLK_DP<0>")
	)
	(arc
		(start 87.15248 -256.149602)
		(mid 86.871048 -256.073847)
		(end 86.589616 -256.149602)
		(width 0.09525)
		(layer "In4.Cu")
		(net "M_D_CPU1_CLK_DP<0>")
	)
	(arc
		(start 82.829654 -256.149602)
		(mid 82.645879 -256.200374)
		(end 82.460846 -256.154428)
		(width 0.09525)
		(layer "In4.Cu")
		(net "M_D_CPU1_CLK_DP<0>")
	)
	(arc
		(start 80.57261 -256.149602)
		(mid 80.291178 -256.073847)
		(end 80.009746 -256.149602)
		(width 0.09525)
		(layer "In4.Cu")
		(net "M_D_CPU1_CLK_DP<0>")
	)
	(arc
		(start 81.881218 -256.154428)
		(mid 81.696186 -256.200342)
		(end 81.51241 -256.149602)
		(width 0.09525)
		(layer "In4.Cu")
		(net "M_D_CPU1_CLK_DP<0>")
	)
	(arc
		(start 78.131162 -256.149602)
		(mid 78.084744 -256.179518)
		(end 78.0415 -256.213864)
		(width 0.09525)
		(layer "In4.Cu")
		(net "M_D_CPU1_CLK_DP<0>")
	)
	(arc
		(start 85.64118 -256.154428)
		(mid 85.456148 -256.200342)
		(end 85.272372 -256.149602)
		(width 0.09525)
		(layer "In4.Cu")
		(net "M_D_CPU1_CLK_DP<0>")
	)
	(arc
		(start 90.846148 -256.116582)
		(mid 90.594007 -256.075012)
		(end 90.349578 -256.149602)
		(width 0.09525)
		(layer "In4.Cu")
		(net "M_D_CPU1_CLK_DP<0>")
	)
	(arc
		(start 82.452464 -256.149602)
		(mid 82.171032 -256.073847)
		(end 81.8896 -256.149602)
		(width 0.09525)
		(layer "In4.Cu")
		(net "M_D_CPU1_CLK_DP<0>")
	)
	(arc
		(start 83.392518 -256.149602)
		(mid 83.111086 -256.073847)
		(end 82.829654 -256.149602)
		(width 0.09525)
		(layer "In4.Cu")
		(net "M_D_CPU1_CLK_DP<0>")
	)
	(arc
		(start 89.972388 -256.149602)
		(mid 89.690956 -256.073847)
		(end 89.409524 -256.149602)
		(width 0.09525)
		(layer "In4.Cu")
		(net "M_D_CPU1_CLK_DP<0>")
	)
	(arc
		(start 78.693772 -256.149602)
		(mid 78.432236 -256.073489)
		(end 78.165706 -256.129536)
		(width 0.09525)
		(layer "In4.Cu")
		(net "M_D_CPU1_CLK_DP<0>")
	)
	(arc
		(start 80.949546 -256.149602)
		(mid 80.761078 -256.200279)
		(end 80.57261 -256.149602)
		(width 0.09525)
		(layer "In4.Cu")
		(net "M_D_CPU1_CLK_DP<0>")
	)
	(arc
		(start 87.52967 -256.149602)
		(mid 87.345895 -256.200374)
		(end 87.160862 -256.154428)
		(width 0.09525)
		(layer "In4.Cu")
		(net "M_D_CPU1_CLK_DP<0>")
	)
	(arc
		(start 81.51241 -256.149602)
		(mid 81.230978 -256.073847)
		(end 80.949546 -256.149602)
		(width 0.09525)
		(layer "In4.Cu")
		(net "M_D_CPU1_CLK_DP<0>")
	)
	(segment
		(start 91.097862 -256.900426)
		(end 90.63101 -256.634488)
		(width 0.14732)
		(layer "F.Cu")
		(net "M_D_CPU1_CLK_DN<0>")
	)
	(segment
		(start 32.969708 -254.01143)
		(end 32.695896 -254.285242)
		(width 0.16002)
		(layer "In4.Cu")
		(net "M_D_CPU1_CLK_DN<0>")
	)
	(segment
		(start 81.050892 -256.304542)
		(end 81.04251 -256.309368)
		(width 0.09525)
		(layer "In4.Cu")
		(net "M_D_CPU1_CLK_DN<0>")
	)
	(segment
		(start 78.249018 -256.29489)
		(end 78.223618 -256.309368)
		(width 0.09525)
		(layer "In4.Cu")
		(net "M_D_CPU1_CLK_DN<0>")
	)
	(segment
		(start 76.284836 -257.534156)
		(end 76.225908 -257.593084)
		(width 0.09525)
		(layer "In4.Cu")
		(net "M_D_CPU1_CLK_DN<0>")
	)
	(segment
		(start 90.63101 -256.634488)
		(end 90.784934 -256.369058)
		(width 0.09525)
		(layer "In4.Cu")
		(net "M_D_CPU1_CLK_DN<0>")
	)
	(segment
		(start 76.225908 -257.593084)
		(end 76.202286 -257.593084)
		(width 0.09525)
		(layer "In4.Cu")
		(net "M_D_CPU1_CLK_DN<0>")
	)
	(segment
		(start 72.648572 -257.593084)
		(end 71.113142 -256.057654)
		(width 0.16002)
		(layer "In4.Cu")
		(net "M_D_CPU1_CLK_DN<0>")
	)
	(segment
		(start 76.202286 -257.593084)
		(end 72.648572 -257.593084)
		(width 0.16002)
		(layer "In4.Cu")
		(net "M_D_CPU1_CLK_DN<0>")
	)
	(segment
		(start 34.401252 -254.680212)
		(end 33.73247 -254.01143)
		(width 0.16002)
		(layer "In4.Cu")
		(net "M_D_CPU1_CLK_DN<0>")
	)
	(segment
		(start 34.74085 -255.185164)
		(end 34.401252 -254.845566)
		(width 0.16002)
		(layer "In4.Cu")
		(net "M_D_CPU1_CLK_DN<0>")
	)
	(segment
		(start 89.51087 -256.304542)
		(end 89.502488 -256.309368)
		(width 0.09525)
		(layer "In4.Cu")
		(net "M_D_CPU1_CLK_DN<0>")
	)
	(segment
		(start 65.522348 -256.734564)
		(end 36.455604 -256.734564)
		(width 0.16002)
		(layer "In4.Cu")
		(net "M_D_CPU1_CLK_DN<0>")
	)
	(segment
		(start 88.939624 -256.309368)
		(end 88.931242 -256.304542)
		(width 0.09525)
		(layer "In4.Cu")
		(net "M_D_CPU1_CLK_DN<0>")
	)
	(segment
		(start 90.784934 -256.369058)
		(end 90.76182 -256.282444)
		(width 0.09525)
		(layer "In4.Cu")
		(net "M_D_CPU1_CLK_DN<0>")
	)
	(segment
		(start 79.177896 -256.300986)
		(end 79.163418 -256.309368)
		(width 0.09525)
		(layer "In4.Cu")
		(net "M_D_CPU1_CLK_DN<0>")
	)
	(segment
		(start 78.145386 -256.368804)
		(end 76.980034 -257.534156)
		(width 0.09525)
		(layer "In4.Cu")
		(net "M_D_CPU1_CLK_DN<0>")
	)
	(segment
		(start 36.455604 -256.734564)
		(end 34.906204 -255.185164)
		(width 0.16002)
		(layer "In4.Cu")
		(net "M_D_CPU1_CLK_DN<0>")
	)
	(segment
		(start 84.239608 -256.309368)
		(end 84.231226 -256.304542)
		(width 0.09525)
		(layer "In4.Cu")
		(net "M_D_CPU1_CLK_DN<0>")
	)
	(segment
		(start 83.299554 -256.309368)
		(end 83.291172 -256.304542)
		(width 0.09525)
		(layer "In4.Cu")
		(net "M_D_CPU1_CLK_DN<0>")
	)
	(segment
		(start 79.163418 -256.309368)
		(end 79.128874 -256.329434)
		(width 0.09525)
		(layer "In4.Cu")
		(net "M_D_CPU1_CLK_DN<0>")
	)
	(segment
		(start 34.906204 -255.185164)
		(end 34.74085 -255.185164)
		(width 0.16002)
		(layer "In4.Cu")
		(net "M_D_CPU1_CLK_DN<0>")
	)
	(segment
		(start 84.810854 -256.304542)
		(end 84.802472 -256.309368)
		(width 0.09525)
		(layer "In4.Cu")
		(net "M_D_CPU1_CLK_DN<0>")
	)
	(segment
		(start 33.73247 -254.01143)
		(end 32.969708 -254.01143)
		(width 0.16002)
		(layer "In4.Cu")
		(net "M_D_CPU1_CLK_DN<0>")
	)
	(segment
		(start 34.401252 -254.845566)
		(end 34.401252 -254.680212)
		(width 0.16002)
		(layer "In4.Cu")
		(net "M_D_CPU1_CLK_DN<0>")
	)
	(segment
		(start 85.750908 -256.304542)
		(end 85.742526 -256.309368)
		(width 0.09525)
		(layer "In4.Cu")
		(net "M_D_CPU1_CLK_DN<0>")
	)
	(segment
		(start 66.199258 -256.057654)
		(end 65.522348 -256.734564)
		(width 0.16002)
		(layer "In4.Cu")
		(net "M_D_CPU1_CLK_DN<0>")
	)
	(segment
		(start 71.113142 -256.057654)
		(end 66.199258 -256.057654)
		(width 0.16002)
		(layer "In4.Cu")
		(net "M_D_CPU1_CLK_DN<0>")
	)
	(segment
		(start 87.99957 -256.309368)
		(end 87.991188 -256.304542)
		(width 0.09525)
		(layer "In4.Cu")
		(net "M_D_CPU1_CLK_DN<0>")
	)
	(segment
		(start 76.980034 -257.534156)
		(end 76.284836 -257.534156)
		(width 0.09525)
		(layer "In4.Cu")
		(net "M_D_CPU1_CLK_DN<0>")
	)
	(segment
		(start 80.479646 -256.309368)
		(end 80.471264 -256.304542)
		(width 0.09525)
		(layer "In4.Cu")
		(net "M_D_CPU1_CLK_DN<0>")
	)
	(arc
		(start 86.68258 -256.309368)
		(mid 86.401148 -256.385123)
		(end 86.119716 -256.309368)
		(width 0.09525)
		(layer "In4.Cu")
		(net "M_D_CPU1_CLK_DN<0>")
	)
	(arc
		(start 85.179662 -256.309368)
		(mid 84.995887 -256.258596)
		(end 84.810854 -256.304542)
		(width 0.09525)
		(layer "In4.Cu")
		(net "M_D_CPU1_CLK_DN<0>")
	)
	(arc
		(start 86.119716 -256.309368)
		(mid 85.935941 -256.258596)
		(end 85.750908 -256.304542)
		(width 0.09525)
		(layer "In4.Cu")
		(net "M_D_CPU1_CLK_DN<0>")
	)
	(arc
		(start 78.600808 -256.309368)
		(mid 78.426719 -256.258496)
		(end 78.249018 -256.29489)
		(width 0.09525)
		(layer "In4.Cu")
		(net "M_D_CPU1_CLK_DN<0>")
	)
	(arc
		(start 80.471264 -256.304542)
		(mid 80.286232 -256.258628)
		(end 80.102456 -256.309368)
		(width 0.09525)
		(layer "In4.Cu")
		(net "M_D_CPU1_CLK_DN<0>")
	)
	(arc
		(start 87.059516 -256.309368)
		(mid 86.871048 -256.258691)
		(end 86.68258 -256.309368)
		(width 0.09525)
		(layer "In4.Cu")
		(net "M_D_CPU1_CLK_DN<0>")
	)
	(arc
		(start 78.223618 -256.309368)
		(mid 78.192063 -256.329575)
		(end 78.162658 -256.352802)
		(width 0.09525)
		(layer "In4.Cu")
		(net "M_D_CPU1_CLK_DN<0>")
	)
	(arc
		(start 84.231226 -256.304542)
		(mid 84.046194 -256.258628)
		(end 83.862418 -256.309368)
		(width 0.09525)
		(layer "In4.Cu")
		(net "M_D_CPU1_CLK_DN<0>")
	)
	(arc
		(start 81.04251 -256.309368)
		(mid 80.761078 -256.385123)
		(end 80.479646 -256.309368)
		(width 0.09525)
		(layer "In4.Cu")
		(net "M_D_CPU1_CLK_DN<0>")
	)
	(arc
		(start 88.931242 -256.304542)
		(mid 88.74621 -256.258628)
		(end 88.562434 -256.309368)
		(width 0.09525)
		(layer "In4.Cu")
		(net "M_D_CPU1_CLK_DN<0>")
	)
	(arc
		(start 85.742526 -256.309368)
		(mid 85.461094 -256.385123)
		(end 85.179662 -256.309368)
		(width 0.09525)
		(layer "In4.Cu")
		(net "M_D_CPU1_CLK_DN<0>")
	)
	(arc
		(start 88.562434 -256.309368)
		(mid 88.281002 -256.385123)
		(end 87.99957 -256.309368)
		(width 0.09525)
		(layer "In4.Cu")
		(net "M_D_CPU1_CLK_DN<0>")
	)
	(arc
		(start 84.802472 -256.309368)
		(mid 84.52104 -256.385123)
		(end 84.239608 -256.309368)
		(width 0.09525)
		(layer "In4.Cu")
		(net "M_D_CPU1_CLK_DN<0>")
	)
	(arc
		(start 81.4197 -256.309368)
		(mid 81.235925 -256.258596)
		(end 81.050892 -256.304542)
		(width 0.09525)
		(layer "In4.Cu")
		(net "M_D_CPU1_CLK_DN<0>")
	)
	(arc
		(start 78.162658 -256.352802)
		(mid 78.153897 -256.360668)
		(end 78.145386 -256.368804)
		(width 0.09525)
		(layer "In4.Cu")
		(net "M_D_CPU1_CLK_DN<0>")
	)
	(arc
		(start 82.3595 -256.309368)
		(mid 82.171032 -256.258691)
		(end 81.982564 -256.309368)
		(width 0.09525)
		(layer "In4.Cu")
		(net "M_D_CPU1_CLK_DN<0>")
	)
	(arc
		(start 79.128874 -256.329434)
		(mid 78.862348 -256.385371)
		(end 78.600808 -256.309368)
		(width 0.09525)
		(layer "In4.Cu")
		(net "M_D_CPU1_CLK_DN<0>")
	)
	(arc
		(start 89.502488 -256.309368)
		(mid 89.221056 -256.385123)
		(end 88.939624 -256.309368)
		(width 0.09525)
		(layer "In4.Cu")
		(net "M_D_CPU1_CLK_DN<0>")
	)
	(arc
		(start 83.291172 -256.304542)
		(mid 83.10614 -256.258628)
		(end 82.922364 -256.309368)
		(width 0.09525)
		(layer "In4.Cu")
		(net "M_D_CPU1_CLK_DN<0>")
	)
	(arc
		(start 82.922364 -256.309368)
		(mid 82.640932 -256.385123)
		(end 82.3595 -256.309368)
		(width 0.09525)
		(layer "In4.Cu")
		(net "M_D_CPU1_CLK_DN<0>")
	)
	(arc
		(start 89.879678 -256.309368)
		(mid 89.695903 -256.258596)
		(end 89.51087 -256.304542)
		(width 0.09525)
		(layer "In4.Cu")
		(net "M_D_CPU1_CLK_DN<0>")
	)
	(arc
		(start 83.862418 -256.309368)
		(mid 83.580986 -256.385123)
		(end 83.299554 -256.309368)
		(width 0.09525)
		(layer "In4.Cu")
		(net "M_D_CPU1_CLK_DN<0>")
	)
	(arc
		(start 90.442542 -256.309368)
		(mid 90.16111 -256.385123)
		(end 89.879678 -256.309368)
		(width 0.09525)
		(layer "In4.Cu")
		(net "M_D_CPU1_CLK_DN<0>")
	)
	(arc
		(start 90.76182 -256.282444)
		(mid 90.599169 -256.260184)
		(end 90.442542 -256.309368)
		(width 0.09525)
		(layer "In4.Cu")
		(net "M_D_CPU1_CLK_DN<0>")
	)
	(arc
		(start 81.982564 -256.309368)
		(mid 81.701132 -256.385123)
		(end 81.4197 -256.309368)
		(width 0.09525)
		(layer "In4.Cu")
		(net "M_D_CPU1_CLK_DN<0>")
	)
	(arc
		(start 87.62238 -256.309368)
		(mid 87.340948 -256.385123)
		(end 87.059516 -256.309368)
		(width 0.09525)
		(layer "In4.Cu")
		(net "M_D_CPU1_CLK_DN<0>")
	)
	(arc
		(start 87.991188 -256.304542)
		(mid 87.806156 -256.258628)
		(end 87.62238 -256.309368)
		(width 0.09525)
		(layer "In4.Cu")
		(net "M_D_CPU1_CLK_DN<0>")
	)
	(arc
		(start 79.539592 -256.309368)
		(mid 79.35982 -256.258792)
		(end 79.177896 -256.300986)
		(width 0.09525)
		(layer "In4.Cu")
		(net "M_D_CPU1_CLK_DN<0>")
	)
	(arc
		(start 80.102456 -256.309368)
		(mid 79.821024 -256.385123)
		(end 79.539592 -256.309368)
		(width 0.09525)
		(layer "In4.Cu")
		(net "M_D_CPU1_CLK_DN<0>")
	)
	(segment
		(start 92.97797 -250.420378)
		(end 92.511118 -250.15444)
		(width 0.10668)
		(layer "F.Cu")
		(net "M_D_CPU1_ALERT_R_N")
	)
	(segment
		(start 76.306934 -250.339098)
		(end 76.960222 -250.339098)
		(width 0.0889)
		(layer "In4.Cu")
		(net "M_D_CPU1_ALERT_R_N")
	)
	(segment
		(start 84.229702 -250.481846)
		(end 84.238084 -250.47702)
		(width 0.0889)
		(layer "In4.Cu")
		(net "M_D_CPU1_ALERT_R_N")
	)
	(segment
		(start 74.36866 -250.339098)
		(end 76.306934 -250.339098)
		(width 0.11684)
		(layer "In4.Cu")
		(net "M_D_CPU1_ALERT_R_N")
	)
	(segment
		(start 92.260674 -250.44527)
		(end 92.35694 -250.41987)
		(width 0.0889)
		(layer "In4.Cu")
		(net "M_D_CPU1_ALERT_R_N")
	)
	(segment
		(start 88.929718 -250.481846)
		(end 88.9381 -250.47702)
		(width 0.0889)
		(layer "In4.Cu")
		(net "M_D_CPU1_ALERT_R_N")
	)
	(segment
		(start 80.46974 -250.481846)
		(end 80.478122 -250.47702)
		(width 0.0889)
		(layer "In4.Cu")
		(net "M_D_CPU1_ALERT_R_N")
	)
	(segment
		(start 63.548006 -249.886724)
		(end 73.916286 -249.886724)
		(width 0.11684)
		(layer "In4.Cu")
		(net "M_D_CPU1_ALERT_R_N")
	)
	(segment
		(start 73.916286 -249.886724)
		(end 74.36866 -250.339098)
		(width 0.11684)
		(layer "In4.Cu")
		(net "M_D_CPU1_ALERT_R_N")
	)
	(segment
		(start 38.192964 -244.085364)
		(end 38.192964 -244.821202)
		(width 0.11684)
		(layer "In4.Cu")
		(net "M_D_CPU1_ALERT_R_N")
	)
	(segment
		(start 85.74405 -250.47702)
		(end 85.752432 -250.481846)
		(width 0.0889)
		(layer "In4.Cu")
		(net "M_D_CPU1_ALERT_R_N")
	)
	(segment
		(start 81.044034 -250.47702)
		(end 81.052416 -250.481846)
		(width 0.0889)
		(layer "In4.Cu")
		(net "M_D_CPU1_ALERT_R_N")
	)
	(segment
		(start 90.444066 -250.47702)
		(end 90.452448 -250.481846)
		(width 0.0889)
		(layer "In4.Cu")
		(net "M_D_CPU1_ALERT_R_N")
	)
	(segment
		(start 76.960222 -250.339098)
		(end 77.02169 -250.400566)
		(width 0.0889)
		(layer "In4.Cu")
		(net "M_D_CPU1_ALERT_R_N")
	)
	(segment
		(start 77.02169 -250.400566)
		(end 77.940154 -250.400566)
		(width 0.0889)
		(layer "In4.Cu")
		(net "M_D_CPU1_ALERT_R_N")
	)
	(segment
		(start 84.803996 -250.47702)
		(end 84.812378 -250.481846)
		(width 0.0889)
		(layer "In4.Cu")
		(net "M_D_CPU1_ALERT_R_N")
	)
	(segment
		(start 38.192964 -244.821202)
		(end 39.58209 -246.210328)
		(width 0.11684)
		(layer "In4.Cu")
		(net "M_D_CPU1_ALERT_R_N")
	)
	(segment
		(start 79.529686 -250.481846)
		(end 79.538068 -250.47702)
		(width 0.0889)
		(layer "In4.Cu")
		(net "M_D_CPU1_ALERT_R_N")
	)
	(segment
		(start 58.23839 -246.466106)
		(end 58.494168 -246.210328)
		(width 0.11684)
		(layer "In4.Cu")
		(net "M_D_CPU1_ALERT_R_N")
	)
	(segment
		(start 56.85155 -246.210328)
		(end 57.107328 -246.466106)
		(width 0.11684)
		(layer "In4.Cu")
		(net "M_D_CPU1_ALERT_R_N")
	)
	(segment
		(start 78.58633 -250.483878)
		(end 78.598014 -250.47702)
		(width 0.0889)
		(layer "In4.Cu")
		(net "M_D_CPU1_ALERT_R_N")
	)
	(segment
		(start 87.989664 -250.481846)
		(end 87.998046 -250.47702)
		(width 0.0889)
		(layer "In4.Cu")
		(net "M_D_CPU1_ALERT_R_N")
	)
	(segment
		(start 58.494168 -246.210328)
		(end 59.87161 -246.210328)
		(width 0.11684)
		(layer "In4.Cu")
		(net "M_D_CPU1_ALERT_R_N")
	)
	(segment
		(start 39.58209 -246.210328)
		(end 56.85155 -246.210328)
		(width 0.11684)
		(layer "In4.Cu")
		(net "M_D_CPU1_ALERT_R_N")
	)
	(segment
		(start 83.289648 -250.481846)
		(end 83.29803 -250.47702)
		(width 0.0889)
		(layer "In4.Cu")
		(net "M_D_CPU1_ALERT_R_N")
	)
	(segment
		(start 89.504012 -250.47702)
		(end 89.512394 -250.481846)
		(width 0.0889)
		(layer "In4.Cu")
		(net "M_D_CPU1_ALERT_R_N")
	)
	(segment
		(start 92.35694 -250.41987)
		(end 92.511118 -250.15444)
		(width 0.0889)
		(layer "In4.Cu")
		(net "M_D_CPU1_ALERT_R_N")
	)
	(segment
		(start 57.107328 -246.466106)
		(end 58.23839 -246.466106)
		(width 0.11684)
		(layer "In4.Cu")
		(net "M_D_CPU1_ALERT_R_N")
	)
	(segment
		(start 59.87161 -246.210328)
		(end 63.548006 -249.886724)
		(width 0.11684)
		(layer "In4.Cu")
		(net "M_D_CPU1_ALERT_R_N")
	)
	(arc
		(start 80.10398 -250.47702)
		(mid 80.286231 -250.52737)
		(end 80.46974 -250.481846)
		(width 0.0889)
		(layer "In4.Cu")
		(net "M_D_CPU1_ALERT_R_N")
	)
	(arc
		(start 78.07198 -250.41606)
		(mid 78.150021 -250.441013)
		(end 78.223618 -250.47702)
		(width 0.0889)
		(layer "In4.Cu")
		(net "M_D_CPU1_ALERT_R_N")
	)
	(arc
		(start 81.418176 -250.47702)
		(mid 81.701132 -250.400843)
		(end 81.984088 -250.47702)
		(width 0.0889)
		(layer "In4.Cu")
		(net "M_D_CPU1_ALERT_R_N")
	)
	(arc
		(start 89.512394 -250.481846)
		(mid 89.695902 -250.52734)
		(end 89.878154 -250.47702)
		(width 0.0889)
		(layer "In4.Cu")
		(net "M_D_CPU1_ALERT_R_N")
	)
	(arc
		(start 80.478122 -250.47702)
		(mid 80.761078 -250.400843)
		(end 81.044034 -250.47702)
		(width 0.0889)
		(layer "In4.Cu")
		(net "M_D_CPU1_ALERT_R_N")
	)
	(arc
		(start 85.178138 -250.47702)
		(mid 85.461094 -250.400843)
		(end 85.74405 -250.47702)
		(width 0.0889)
		(layer "In4.Cu")
		(net "M_D_CPU1_ALERT_R_N")
	)
	(arc
		(start 87.623904 -250.47702)
		(mid 87.806155 -250.52737)
		(end 87.989664 -250.481846)
		(width 0.0889)
		(layer "In4.Cu")
		(net "M_D_CPU1_ALERT_R_N")
	)
	(arc
		(start 90.452448 -250.481846)
		(mid 90.635956 -250.52734)
		(end 90.818208 -250.47702)
		(width 0.0889)
		(layer "In4.Cu")
		(net "M_D_CPU1_ALERT_R_N")
	)
	(arc
		(start 91.758008 -250.47702)
		(mid 92.005604 -250.401842)
		(end 92.260674 -250.44527)
		(width 0.0889)
		(layer "In4.Cu")
		(net "M_D_CPU1_ALERT_R_N")
	)
	(arc
		(start 84.238084 -250.47702)
		(mid 84.52104 -250.400843)
		(end 84.803996 -250.47702)
		(width 0.0889)
		(layer "In4.Cu")
		(net "M_D_CPU1_ALERT_R_N")
	)
	(arc
		(start 88.563958 -250.47702)
		(mid 88.746209 -250.52737)
		(end 88.929718 -250.481846)
		(width 0.0889)
		(layer "In4.Cu")
		(net "M_D_CPU1_ALERT_R_N")
	)
	(arc
		(start 79.538068 -250.47702)
		(mid 79.821024 -250.400843)
		(end 80.10398 -250.47702)
		(width 0.0889)
		(layer "In4.Cu")
		(net "M_D_CPU1_ALERT_R_N")
	)
	(arc
		(start 77.940154 -250.400566)
		(mid 78.006526 -250.404408)
		(end 78.07198 -250.41606)
		(width 0.0889)
		(layer "In4.Cu")
		(net "M_D_CPU1_ALERT_R_N")
	)
	(arc
		(start 86.118192 -250.47702)
		(mid 86.401148 -250.400843)
		(end 86.684104 -250.47702)
		(width 0.0889)
		(layer "In4.Cu")
		(net "M_D_CPU1_ALERT_R_N")
	)
	(arc
		(start 91.38412 -250.47702)
		(mid 91.571064 -250.527275)
		(end 91.758008 -250.47702)
		(width 0.0889)
		(layer "In4.Cu")
		(net "M_D_CPU1_ALERT_R_N")
	)
	(arc
		(start 78.598014 -250.47702)
		(mid 78.88097 -250.400843)
		(end 79.163926 -250.47702)
		(width 0.0889)
		(layer "In4.Cu")
		(net "M_D_CPU1_ALERT_R_N")
	)
	(arc
		(start 78.223618 -250.47702)
		(mid 78.404076 -250.527464)
		(end 78.58633 -250.483878)
		(width 0.0889)
		(layer "In4.Cu")
		(net "M_D_CPU1_ALERT_R_N")
	)
	(arc
		(start 86.684104 -250.47702)
		(mid 86.871048 -250.527275)
		(end 87.057992 -250.47702)
		(width 0.0889)
		(layer "In4.Cu")
		(net "M_D_CPU1_ALERT_R_N")
	)
	(arc
		(start 85.752432 -250.481846)
		(mid 85.93594 -250.52734)
		(end 86.118192 -250.47702)
		(width 0.0889)
		(layer "In4.Cu")
		(net "M_D_CPU1_ALERT_R_N")
	)
	(arc
		(start 81.984088 -250.47702)
		(mid 82.171032 -250.527275)
		(end 82.357976 -250.47702)
		(width 0.0889)
		(layer "In4.Cu")
		(net "M_D_CPU1_ALERT_R_N")
	)
	(arc
		(start 79.163926 -250.47702)
		(mid 79.346177 -250.52737)
		(end 79.529686 -250.481846)
		(width 0.0889)
		(layer "In4.Cu")
		(net "M_D_CPU1_ALERT_R_N")
	)
	(arc
		(start 84.812378 -250.481846)
		(mid 84.995886 -250.52734)
		(end 85.178138 -250.47702)
		(width 0.0889)
		(layer "In4.Cu")
		(net "M_D_CPU1_ALERT_R_N")
	)
	(arc
		(start 83.863942 -250.47702)
		(mid 84.046193 -250.52737)
		(end 84.229702 -250.481846)
		(width 0.0889)
		(layer "In4.Cu")
		(net "M_D_CPU1_ALERT_R_N")
	)
	(arc
		(start 82.357976 -250.47702)
		(mid 82.640932 -250.400843)
		(end 82.923888 -250.47702)
		(width 0.0889)
		(layer "In4.Cu")
		(net "M_D_CPU1_ALERT_R_N")
	)
	(arc
		(start 81.052416 -250.481846)
		(mid 81.235924 -250.52734)
		(end 81.418176 -250.47702)
		(width 0.0889)
		(layer "In4.Cu")
		(net "M_D_CPU1_ALERT_R_N")
	)
	(arc
		(start 88.9381 -250.47702)
		(mid 89.221056 -250.400843)
		(end 89.504012 -250.47702)
		(width 0.0889)
		(layer "In4.Cu")
		(net "M_D_CPU1_ALERT_R_N")
	)
	(arc
		(start 89.878154 -250.47702)
		(mid 90.16111 -250.400843)
		(end 90.444066 -250.47702)
		(width 0.0889)
		(layer "In4.Cu")
		(net "M_D_CPU1_ALERT_R_N")
	)
	(arc
		(start 87.057992 -250.47702)
		(mid 87.340948 -250.400843)
		(end 87.623904 -250.47702)
		(width 0.0889)
		(layer "In4.Cu")
		(net "M_D_CPU1_ALERT_R_N")
	)
	(arc
		(start 87.998046 -250.47702)
		(mid 88.281002 -250.400843)
		(end 88.563958 -250.47702)
		(width 0.0889)
		(layer "In4.Cu")
		(net "M_D_CPU1_ALERT_R_N")
	)
	(arc
		(start 90.818208 -250.47702)
		(mid 91.101164 -250.400843)
		(end 91.38412 -250.47702)
		(width 0.0889)
		(layer "In4.Cu")
		(net "M_D_CPU1_ALERT_R_N")
	)
	(arc
		(start 83.29803 -250.47702)
		(mid 83.580986 -250.400843)
		(end 83.863942 -250.47702)
		(width 0.0889)
		(layer "In4.Cu")
		(net "M_D_CPU1_ALERT_R_N")
	)
	(arc
		(start 82.923888 -250.47702)
		(mid 83.106139 -250.52737)
		(end 83.289648 -250.481846)
		(width 0.0889)
		(layer "In4.Cu")
		(net "M_D_CPU1_ALERT_R_N")
	)
	(via
		(at 36.795964 -244.085364)
		(size 0.4826)
		(drill 0.254)
		(layers "F.Cu" "B.Cu")
		(net "M_D_CPU1_ALERT_N")
	)
	(segment
		(start 37.392864 -244.085364)
		(end 36.795964 -244.085364)
		(width 0.10668)
		(layer "B.Cu")
		(net "M_D_CPU1_ALERT_N")
	)
	(segment
		(start 339.337904 -267.34008)
		(end 338.871052 -267.606018)
		(width 0.10668)
		(layer "F.Cu")
		(net "M_D_CPU0_SB_RSP<0>")
	)
	(segment
		(start 327.752456 -267.936472)
		(end 327.776078 -267.92301)
		(width 0.0889)
		(layer "In4.Cu")
		(net "M_D_CPU0_SB_RSP<0>")
	)
	(segment
		(start 323.908674 -266.85113)
		(end 324.392036 -266.85113)
		(width 0.0889)
		(layer "In4.Cu")
		(net "M_D_CPU0_SB_RSP<0>")
	)
	(segment
		(start 331.535024 -267.92301)
		(end 331.545692 -267.916914)
		(width 0.0889)
		(layer "In4.Cu")
		(net "M_D_CPU0_SB_RSP<0>")
	)
	(segment
		(start 307.590444 -270.010128)
		(end 307.822346 -270.010128)
		(width 0.11684)
		(layer "In4.Cu")
		(net "M_D_CPU0_SB_RSP<0>")
	)
	(segment
		(start 291.062918 -269.71371)
		(end 291.29482 -269.71371)
		(width 0.11684)
		(layer "In4.Cu")
		(net "M_D_CPU0_SB_RSP<0>")
	)
	(segment
		(start 286.523684 -270.010128)
		(end 286.780986 -270.010128)
		(width 0.11684)
		(layer "In4.Cu")
		(net "M_D_CPU0_SB_RSP<0>")
	)
	(segment
		(start 306.237386 -269.71371)
		(end 306.533804 -270.010128)
		(width 0.11684)
		(layer "In4.Cu")
		(net "M_D_CPU0_SB_RSP<0>")
	)
	(segment
		(start 306.533804 -270.010128)
		(end 306.765706 -270.010128)
		(width 0.11684)
		(layer "In4.Cu")
		(net "M_D_CPU0_SB_RSP<0>")
	)
	(segment
		(start 297.330876 -269.71371)
		(end 297.562778 -269.71371)
		(width 0.11684)
		(layer "In4.Cu")
		(net "M_D_CPU0_SB_RSP<0>")
	)
	(segment
		(start 285.724346 -270.010128)
		(end 285.995364 -269.73911)
		(width 0.11684)
		(layer "In4.Cu")
		(net "M_D_CPU0_SB_RSP<0>")
	)
	(segment
		(start 301.161958 -270.010128)
		(end 301.458376 -269.71371)
		(width 0.11684)
		(layer "In4.Cu")
		(net "M_D_CPU0_SB_RSP<0>")
	)
	(segment
		(start 302.515016 -269.71371)
		(end 302.746918 -269.71371)
		(width 0.11684)
		(layer "In4.Cu")
		(net "M_D_CPU0_SB_RSP<0>")
	)
	(segment
		(start 298.619418 -269.71371)
		(end 298.915836 -270.010128)
		(width 0.11684)
		(layer "In4.Cu")
		(net "M_D_CPU0_SB_RSP<0>")
	)
	(segment
		(start 338.676488 -267.916914)
		(end 338.687156 -267.92301)
		(width 0.0889)
		(layer "In4.Cu")
		(net "M_D_CPU0_SB_RSP<0>")
	)
	(segment
		(start 289.18154 -269.71371)
		(end 289.477958 -270.010128)
		(width 0.11684)
		(layer "In4.Cu")
		(net "M_D_CPU0_SB_RSP<0>")
	)
	(segment
		(start 333.976472 -267.916914)
		(end 333.98714 -267.92301)
		(width 0.0889)
		(layer "In4.Cu")
		(net "M_D_CPU0_SB_RSP<0>")
	)
	(segment
		(start 287.580324 -270.010128)
		(end 288.65322 -270.010128)
		(width 0.11684)
		(layer "In4.Cu")
		(net "M_D_CPU0_SB_RSP<0>")
	)
	(segment
		(start 324.392036 -266.85113)
		(end 324.771258 -267.230352)
		(width 0.0889)
		(layer "In4.Cu")
		(net "M_D_CPU0_SB_RSP<0>")
	)
	(segment
		(start 290.7665 -270.010128)
		(end 291.062918 -269.71371)
		(width 0.11684)
		(layer "In4.Cu")
		(net "M_D_CPU0_SB_RSP<0>")
	)
	(segment
		(start 294.391842 -270.010128)
		(end 294.623744 -270.010128)
		(width 0.11684)
		(layer "In4.Cu")
		(net "M_D_CPU0_SB_RSP<0>")
	)
	(segment
		(start 308.118764 -269.71371)
		(end 308.483254 -269.71371)
		(width 0.11684)
		(layer "In4.Cu")
		(net "M_D_CPU0_SB_RSP<0>")
	)
	(segment
		(start 303.043336 -270.010128)
		(end 303.595786 -270.010128)
		(width 0.11684)
		(layer "In4.Cu")
		(net "M_D_CPU0_SB_RSP<0>")
	)
	(segment
		(start 295.448482 -270.010128)
		(end 295.977818 -270.010128)
		(width 0.11684)
		(layer "In4.Cu")
		(net "M_D_CPU0_SB_RSP<0>")
	)
	(segment
		(start 294.920162 -269.71371)
		(end 295.152064 -269.71371)
		(width 0.11684)
		(layer "In4.Cu")
		(net "M_D_CPU0_SB_RSP<0>")
	)
	(segment
		(start 293.335202 -270.010128)
		(end 293.567104 -270.010128)
		(width 0.11684)
		(layer "In4.Cu")
		(net "M_D_CPU0_SB_RSP<0>")
	)
	(segment
		(start 290.23818 -269.71371)
		(end 290.534598 -270.010128)
		(width 0.11684)
		(layer "In4.Cu")
		(net "M_D_CPU0_SB_RSP<0>")
	)
	(segment
		(start 304.948844 -269.71371)
		(end 305.180746 -269.71371)
		(width 0.11684)
		(layer "In4.Cu")
		(net "M_D_CPU0_SB_RSP<0>")
	)
	(segment
		(start 289.477958 -270.010128)
		(end 289.70986 -270.010128)
		(width 0.11684)
		(layer "In4.Cu")
		(net "M_D_CPU0_SB_RSP<0>")
	)
	(segment
		(start 300.401736 -269.71371)
		(end 300.633638 -269.71371)
		(width 0.11684)
		(layer "In4.Cu")
		(net "M_D_CPU0_SB_RSP<0>")
	)
	(segment
		(start 301.986696 -270.010128)
		(end 302.218598 -270.010128)
		(width 0.11684)
		(layer "In4.Cu")
		(net "M_D_CPU0_SB_RSP<0>")
	)
	(segment
		(start 326.835008 -267.92301)
		(end 326.858376 -267.909294)
		(width 0.0889)
		(layer "In4.Cu")
		(net "M_D_CPU0_SB_RSP<0>")
	)
	(segment
		(start 286.780986 -270.010128)
		(end 287.052004 -269.73911)
		(width 0.11684)
		(layer "In4.Cu")
		(net "M_D_CPU0_SB_RSP<0>")
	)
	(segment
		(start 294.095424 -269.71371)
		(end 294.391842 -270.010128)
		(width 0.11684)
		(layer "In4.Cu")
		(net "M_D_CPU0_SB_RSP<0>")
	)
	(segment
		(start 290.006278 -269.71371)
		(end 290.23818 -269.71371)
		(width 0.11684)
		(layer "In4.Cu")
		(net "M_D_CPU0_SB_RSP<0>")
	)
	(segment
		(start 287.052004 -269.73911)
		(end 287.309306 -269.73911)
		(width 0.11684)
		(layer "In4.Cu")
		(net "M_D_CPU0_SB_RSP<0>")
	)
	(segment
		(start 289.70986 -270.010128)
		(end 290.006278 -269.71371)
		(width 0.11684)
		(layer "In4.Cu")
		(net "M_D_CPU0_SB_RSP<0>")
	)
	(segment
		(start 302.218598 -270.010128)
		(end 302.515016 -269.71371)
		(width 0.11684)
		(layer "In4.Cu")
		(net "M_D_CPU0_SB_RSP<0>")
	)
	(segment
		(start 305.709066 -270.010128)
		(end 306.005484 -269.71371)
		(width 0.11684)
		(layer "In4.Cu")
		(net "M_D_CPU0_SB_RSP<0>")
	)
	(segment
		(start 284.736032 -270.43507)
		(end 285.160974 -270.010128)
		(width 0.11684)
		(layer "In4.Cu")
		(net "M_D_CPU0_SB_RSP<0>")
	)
	(segment
		(start 304.420524 -270.010128)
		(end 304.652426 -270.010128)
		(width 0.11684)
		(layer "In4.Cu")
		(net "M_D_CPU0_SB_RSP<0>")
	)
	(segment
		(start 336.23504 -267.92301)
		(end 336.245708 -267.916914)
		(width 0.0889)
		(layer "In4.Cu")
		(net "M_D_CPU0_SB_RSP<0>")
	)
	(segment
		(start 296.506138 -269.71371)
		(end 296.802556 -270.010128)
		(width 0.11684)
		(layer "In4.Cu")
		(net "M_D_CPU0_SB_RSP<0>")
	)
	(segment
		(start 288.949638 -269.71371)
		(end 289.18154 -269.71371)
		(width 0.11684)
		(layer "In4.Cu")
		(net "M_D_CPU0_SB_RSP<0>")
	)
	(segment
		(start 285.995364 -269.73911)
		(end 286.252666 -269.73911)
		(width 0.11684)
		(layer "In4.Cu")
		(net "M_D_CPU0_SB_RSP<0>")
	)
	(segment
		(start 305.477164 -270.010128)
		(end 305.709066 -270.010128)
		(width 0.11684)
		(layer "In4.Cu")
		(net "M_D_CPU0_SB_RSP<0>")
	)
	(segment
		(start 295.152064 -269.71371)
		(end 295.448482 -270.010128)
		(width 0.11684)
		(layer "In4.Cu")
		(net "M_D_CPU0_SB_RSP<0>")
	)
	(segment
		(start 324.771258 -267.230352)
		(end 325.757794 -267.230352)
		(width 0.0889)
		(layer "In4.Cu")
		(net "M_D_CPU0_SB_RSP<0>")
	)
	(segment
		(start 334.916526 -267.916914)
		(end 334.927194 -267.92301)
		(width 0.0889)
		(layer "In4.Cu")
		(net "M_D_CPU0_SB_RSP<0>")
	)
	(segment
		(start 300.105318 -270.010128)
		(end 300.401736 -269.71371)
		(width 0.11684)
		(layer "In4.Cu")
		(net "M_D_CPU0_SB_RSP<0>")
	)
	(segment
		(start 294.623744 -270.010128)
		(end 294.920162 -269.71371)
		(width 0.11684)
		(layer "In4.Cu")
		(net "M_D_CPU0_SB_RSP<0>")
	)
	(segment
		(start 293.567104 -270.010128)
		(end 293.863522 -269.71371)
		(width 0.11684)
		(layer "In4.Cu")
		(net "M_D_CPU0_SB_RSP<0>")
	)
	(segment
		(start 296.802556 -270.010128)
		(end 297.034458 -270.010128)
		(width 0.11684)
		(layer "In4.Cu")
		(net "M_D_CPU0_SB_RSP<0>")
	)
	(segment
		(start 338.996528 -267.950188)
		(end 339.019896 -267.862304)
		(width 0.0889)
		(layer "In4.Cu")
		(net "M_D_CPU0_SB_RSP<0>")
	)
	(segment
		(start 304.652426 -270.010128)
		(end 304.948844 -269.71371)
		(width 0.11684)
		(layer "In4.Cu")
		(net "M_D_CPU0_SB_RSP<0>")
	)
	(segment
		(start 303.892204 -269.71371)
		(end 304.124106 -269.71371)
		(width 0.11684)
		(layer "In4.Cu")
		(net "M_D_CPU0_SB_RSP<0>")
	)
	(segment
		(start 293.863522 -269.71371)
		(end 294.095424 -269.71371)
		(width 0.11684)
		(layer "In4.Cu")
		(net "M_D_CPU0_SB_RSP<0>")
	)
	(segment
		(start 335.294986 -267.92301)
		(end 335.305654 -267.916914)
		(width 0.0889)
		(layer "In4.Cu")
		(net "M_D_CPU0_SB_RSP<0>")
	)
	(segment
		(start 288.65322 -270.010128)
		(end 288.949638 -269.71371)
		(width 0.11684)
		(layer "In4.Cu")
		(net "M_D_CPU0_SB_RSP<0>")
	)
	(segment
		(start 326.468232 -267.92301)
		(end 326.484742 -267.932408)
		(width 0.0889)
		(layer "In4.Cu")
		(net "M_D_CPU0_SB_RSP<0>")
	)
	(segment
		(start 296.274236 -269.71371)
		(end 296.506138 -269.71371)
		(width 0.11684)
		(layer "In4.Cu")
		(net "M_D_CPU0_SB_RSP<0>")
	)
	(segment
		(start 302.746918 -269.71371)
		(end 303.043336 -270.010128)
		(width 0.11684)
		(layer "In4.Cu")
		(net "M_D_CPU0_SB_RSP<0>")
	)
	(segment
		(start 301.458376 -269.71371)
		(end 301.690278 -269.71371)
		(width 0.11684)
		(layer "In4.Cu")
		(net "M_D_CPU0_SB_RSP<0>")
	)
	(segment
		(start 308.483254 -269.71371)
		(end 311.345834 -266.85113)
		(width 0.11684)
		(layer "In4.Cu")
		(net "M_D_CPU0_SB_RSP<0>")
	)
	(segment
		(start 330.21651 -267.916914)
		(end 330.227178 -267.92301)
		(width 0.0889)
		(layer "In4.Cu")
		(net "M_D_CPU0_SB_RSP<0>")
	)
	(segment
		(start 293.038784 -269.71371)
		(end 293.335202 -270.010128)
		(width 0.11684)
		(layer "In4.Cu")
		(net "M_D_CPU0_SB_RSP<0>")
	)
	(segment
		(start 306.005484 -269.71371)
		(end 306.237386 -269.71371)
		(width 0.11684)
		(layer "In4.Cu")
		(net "M_D_CPU0_SB_RSP<0>")
	)
	(segment
		(start 307.822346 -270.010128)
		(end 308.118764 -269.71371)
		(width 0.11684)
		(layer "In4.Cu")
		(net "M_D_CPU0_SB_RSP<0>")
	)
	(segment
		(start 297.562778 -269.71371)
		(end 297.859196 -270.010128)
		(width 0.11684)
		(layer "In4.Cu")
		(net "M_D_CPU0_SB_RSP<0>")
	)
	(segment
		(start 295.977818 -270.010128)
		(end 296.274236 -269.71371)
		(width 0.11684)
		(layer "In4.Cu")
		(net "M_D_CPU0_SB_RSP<0>")
	)
	(segment
		(start 286.252666 -269.73911)
		(end 286.523684 -270.010128)
		(width 0.11684)
		(layer "In4.Cu")
		(net "M_D_CPU0_SB_RSP<0>")
	)
	(segment
		(start 327.776078 -267.92301)
		(end 327.799446 -267.909294)
		(width 0.0889)
		(layer "In4.Cu")
		(net "M_D_CPU0_SB_RSP<0>")
	)
	(segment
		(start 306.765706 -270.010128)
		(end 307.062124 -269.71371)
		(width 0.11684)
		(layer "In4.Cu")
		(net "M_D_CPU0_SB_RSP<0>")
	)
	(segment
		(start 291.591238 -270.010128)
		(end 292.510464 -270.010128)
		(width 0.11684)
		(layer "In4.Cu")
		(net "M_D_CPU0_SB_RSP<0>")
	)
	(segment
		(start 298.091098 -270.010128)
		(end 298.387516 -269.71371)
		(width 0.11684)
		(layer "In4.Cu")
		(net "M_D_CPU0_SB_RSP<0>")
	)
	(segment
		(start 300.633638 -269.71371)
		(end 300.930056 -270.010128)
		(width 0.11684)
		(layer "In4.Cu")
		(net "M_D_CPU0_SB_RSP<0>")
	)
	(segment
		(start 297.859196 -270.010128)
		(end 298.091098 -270.010128)
		(width 0.11684)
		(layer "In4.Cu")
		(net "M_D_CPU0_SB_RSP<0>")
	)
	(segment
		(start 292.806882 -269.71371)
		(end 293.038784 -269.71371)
		(width 0.11684)
		(layer "In4.Cu")
		(net "M_D_CPU0_SB_RSP<0>")
	)
	(segment
		(start 330.59497 -267.92301)
		(end 330.605638 -267.916914)
		(width 0.0889)
		(layer "In4.Cu")
		(net "M_D_CPU0_SB_RSP<0>")
	)
	(segment
		(start 290.534598 -270.010128)
		(end 290.7665 -270.010128)
		(width 0.11684)
		(layer "In4.Cu")
		(net "M_D_CPU0_SB_RSP<0>")
	)
	(segment
		(start 307.294026 -269.71371)
		(end 307.590444 -270.010128)
		(width 0.11684)
		(layer "In4.Cu")
		(net "M_D_CPU0_SB_RSP<0>")
	)
	(segment
		(start 304.124106 -269.71371)
		(end 304.420524 -270.010128)
		(width 0.11684)
		(layer "In4.Cu")
		(net "M_D_CPU0_SB_RSP<0>")
	)
	(segment
		(start 287.309306 -269.73911)
		(end 287.580324 -270.010128)
		(width 0.11684)
		(layer "In4.Cu")
		(net "M_D_CPU0_SB_RSP<0>")
	)
	(segment
		(start 303.595786 -270.010128)
		(end 303.892204 -269.71371)
		(width 0.11684)
		(layer "In4.Cu")
		(net "M_D_CPU0_SB_RSP<0>")
	)
	(segment
		(start 339.019896 -267.862304)
		(end 338.871052 -267.606018)
		(width 0.0889)
		(layer "In4.Cu")
		(net "M_D_CPU0_SB_RSP<0>")
	)
	(segment
		(start 301.690278 -269.71371)
		(end 301.986696 -270.010128)
		(width 0.11684)
		(layer "In4.Cu")
		(net "M_D_CPU0_SB_RSP<0>")
	)
	(segment
		(start 298.387516 -269.71371)
		(end 298.619418 -269.71371)
		(width 0.11684)
		(layer "In4.Cu")
		(net "M_D_CPU0_SB_RSP<0>")
	)
	(segment
		(start 298.915836 -270.010128)
		(end 300.105318 -270.010128)
		(width 0.11684)
		(layer "In4.Cu")
		(net "M_D_CPU0_SB_RSP<0>")
	)
	(segment
		(start 305.180746 -269.71371)
		(end 305.477164 -270.010128)
		(width 0.11684)
		(layer "In4.Cu")
		(net "M_D_CPU0_SB_RSP<0>")
	)
	(segment
		(start 325.757794 -267.230352)
		(end 326.392286 -267.864844)
		(width 0.0889)
		(layer "In4.Cu")
		(net "M_D_CPU0_SB_RSP<0>")
	)
	(segment
		(start 307.062124 -269.71371)
		(end 307.294026 -269.71371)
		(width 0.11684)
		(layer "In4.Cu")
		(net "M_D_CPU0_SB_RSP<0>")
	)
	(segment
		(start 292.510464 -270.010128)
		(end 292.806882 -269.71371)
		(width 0.11684)
		(layer "In4.Cu")
		(net "M_D_CPU0_SB_RSP<0>")
	)
	(segment
		(start 300.930056 -270.010128)
		(end 301.161958 -270.010128)
		(width 0.11684)
		(layer "In4.Cu")
		(net "M_D_CPU0_SB_RSP<0>")
	)
	(segment
		(start 311.345834 -266.85113)
		(end 323.908674 -266.85113)
		(width 0.11684)
		(layer "In4.Cu")
		(net "M_D_CPU0_SB_RSP<0>")
	)
	(segment
		(start 291.29482 -269.71371)
		(end 291.591238 -270.010128)
		(width 0.11684)
		(layer "In4.Cu")
		(net "M_D_CPU0_SB_RSP<0>")
	)
	(segment
		(start 285.160974 -270.010128)
		(end 285.724346 -270.010128)
		(width 0.11684)
		(layer "In4.Cu")
		(net "M_D_CPU0_SB_RSP<0>")
	)
	(segment
		(start 297.034458 -270.010128)
		(end 297.330876 -269.71371)
		(width 0.11684)
		(layer "In4.Cu")
		(net "M_D_CPU0_SB_RSP<0>")
	)
	(arc
		(start 336.807302 -267.92301)
		(mid 336.991198 -267.97249)
		(end 337.175094 -267.92301)
		(width 0.0889)
		(layer "In4.Cu")
		(net "M_D_CPU0_SB_RSP<0>")
	)
	(arc
		(start 330.605638 -267.916914)
		(mid 330.887227 -267.84604)
		(end 331.167232 -267.92301)
		(width 0.0889)
		(layer "In4.Cu")
		(net "M_D_CPU0_SB_RSP<0>")
	)
	(arc
		(start 330.227178 -267.92301)
		(mid 330.411074 -267.97249)
		(end 330.59497 -267.92301)
		(width 0.0889)
		(layer "In4.Cu")
		(net "M_D_CPU0_SB_RSP<0>")
	)
	(arc
		(start 326.392286 -267.864844)
		(mid 326.428357 -267.89641)
		(end 326.468232 -267.92301)
		(width 0.0889)
		(layer "In4.Cu")
		(net "M_D_CPU0_SB_RSP<0>")
	)
	(arc
		(start 326.858376 -267.909294)
		(mid 327.135078 -267.845573)
		(end 327.408286 -267.92301)
		(width 0.0889)
		(layer "In4.Cu")
		(net "M_D_CPU0_SB_RSP<0>")
	)
	(arc
		(start 327.799446 -267.909294)
		(mid 328.075133 -267.846039)
		(end 328.347324 -267.92301)
		(width 0.0889)
		(layer "In4.Cu")
		(net "M_D_CPU0_SB_RSP<0>")
	)
	(arc
		(start 335.305654 -267.916914)
		(mid 335.587243 -267.84604)
		(end 335.867248 -267.92301)
		(width 0.0889)
		(layer "In4.Cu")
		(net "M_D_CPU0_SB_RSP<0>")
	)
	(arc
		(start 333.414878 -267.92301)
		(mid 333.694882 -267.845965)
		(end 333.976472 -267.916914)
		(width 0.0889)
		(layer "In4.Cu")
		(net "M_D_CPU0_SB_RSP<0>")
	)
	(arc
		(start 333.98714 -267.92301)
		(mid 334.171036 -267.97249)
		(end 334.354932 -267.92301)
		(width 0.0889)
		(layer "In4.Cu")
		(net "M_D_CPU0_SB_RSP<0>")
	)
	(arc
		(start 335.867248 -267.92301)
		(mid 336.051144 -267.97249)
		(end 336.23504 -267.92301)
		(width 0.0889)
		(layer "In4.Cu")
		(net "M_D_CPU0_SB_RSP<0>")
	)
	(arc
		(start 332.107286 -267.92301)
		(mid 332.291182 -267.97249)
		(end 332.475078 -267.92301)
		(width 0.0889)
		(layer "In4.Cu")
		(net "M_D_CPU0_SB_RSP<0>")
	)
	(arc
		(start 327.408286 -267.92301)
		(mid 327.578684 -267.972596)
		(end 327.752456 -267.936472)
		(width 0.0889)
		(layer "In4.Cu")
		(net "M_D_CPU0_SB_RSP<0>")
	)
	(arc
		(start 338.687156 -267.92301)
		(mid 338.838815 -267.970964)
		(end 338.996528 -267.950188)
		(width 0.0889)
		(layer "In4.Cu")
		(net "M_D_CPU0_SB_RSP<0>")
	)
	(arc
		(start 337.175094 -267.92301)
		(mid 337.461098 -267.846058)
		(end 337.747102 -267.92301)
		(width 0.0889)
		(layer "In4.Cu")
		(net "M_D_CPU0_SB_RSP<0>")
	)
	(arc
		(start 337.747102 -267.92301)
		(mid 337.930998 -267.97249)
		(end 338.114894 -267.92301)
		(width 0.0889)
		(layer "In4.Cu")
		(net "M_D_CPU0_SB_RSP<0>")
	)
	(arc
		(start 331.545692 -267.916914)
		(mid 331.827281 -267.84604)
		(end 332.107286 -267.92301)
		(width 0.0889)
		(layer "In4.Cu")
		(net "M_D_CPU0_SB_RSP<0>")
	)
	(arc
		(start 328.715116 -267.92301)
		(mid 329.00112 -267.846058)
		(end 329.287124 -267.92301)
		(width 0.0889)
		(layer "In4.Cu")
		(net "M_D_CPU0_SB_RSP<0>")
	)
	(arc
		(start 326.484742 -267.932408)
		(mid 326.661088 -267.97235)
		(end 326.835008 -267.92301)
		(width 0.0889)
		(layer "In4.Cu")
		(net "M_D_CPU0_SB_RSP<0>")
	)
	(arc
		(start 329.654916 -267.92301)
		(mid 329.93492 -267.845965)
		(end 330.21651 -267.916914)
		(width 0.0889)
		(layer "In4.Cu")
		(net "M_D_CPU0_SB_RSP<0>")
	)
	(arc
		(start 338.114894 -267.92301)
		(mid 338.394898 -267.845965)
		(end 338.676488 -267.916914)
		(width 0.0889)
		(layer "In4.Cu")
		(net "M_D_CPU0_SB_RSP<0>")
	)
	(arc
		(start 331.167232 -267.92301)
		(mid 331.351128 -267.97249)
		(end 331.535024 -267.92301)
		(width 0.0889)
		(layer "In4.Cu")
		(net "M_D_CPU0_SB_RSP<0>")
	)
	(arc
		(start 336.245708 -267.916914)
		(mid 336.527297 -267.84604)
		(end 336.807302 -267.92301)
		(width 0.0889)
		(layer "In4.Cu")
		(net "M_D_CPU0_SB_RSP<0>")
	)
	(arc
		(start 334.927194 -267.92301)
		(mid 335.11109 -267.97249)
		(end 335.294986 -267.92301)
		(width 0.0889)
		(layer "In4.Cu")
		(net "M_D_CPU0_SB_RSP<0>")
	)
	(arc
		(start 334.354932 -267.92301)
		(mid 334.634936 -267.845965)
		(end 334.916526 -267.916914)
		(width 0.0889)
		(layer "In4.Cu")
		(net "M_D_CPU0_SB_RSP<0>")
	)
	(arc
		(start 333.047086 -267.92301)
		(mid 333.230982 -267.97249)
		(end 333.414878 -267.92301)
		(width 0.0889)
		(layer "In4.Cu")
		(net "M_D_CPU0_SB_RSP<0>")
	)
	(arc
		(start 328.347324 -267.92301)
		(mid 328.53122 -267.97249)
		(end 328.715116 -267.92301)
		(width 0.0889)
		(layer "In4.Cu")
		(net "M_D_CPU0_SB_RSP<0>")
	)
	(arc
		(start 329.287124 -267.92301)
		(mid 329.47102 -267.97249)
		(end 329.654916 -267.92301)
		(width 0.0889)
		(layer "In4.Cu")
		(net "M_D_CPU0_SB_RSP<0>")
	)
	(arc
		(start 332.475078 -267.92301)
		(mid 332.761082 -267.846058)
		(end 333.047086 -267.92301)
		(width 0.0889)
		(layer "In4.Cu")
		(net "M_D_CPU0_SB_RSP<0>")
	)
	(segment
		(start 339.808058 -264.910062)
		(end 339.341206 -265.176)
		(width 0.10668)
		(layer "F.Cu")
		(net "M_D_CPU0_SB_PAR")
	)
	(segment
		(start 327.307448 -264.85342)
		(end 327.317862 -264.859516)
		(width 0.0889)
		(layer "In4.Cu")
		(net "M_D_CPU0_SB_PAR")
	)
	(segment
		(start 323.906134 -265.0744)
		(end 324.24497 -265.0744)
		(width 0.0889)
		(layer "In4.Cu")
		(net "M_D_CPU0_SB_PAR")
	)
	(segment
		(start 335.394046 -264.85342)
		(end 335.402428 -264.848594)
		(width 0.0889)
		(layer "In4.Cu")
		(net "M_D_CPU0_SB_PAR")
	)
	(segment
		(start 331.634084 -264.85342)
		(end 331.642466 -264.848594)
		(width 0.0889)
		(layer "In4.Cu")
		(net "M_D_CPU0_SB_PAR")
	)
	(segment
		(start 324.24497 -265.0744)
		(end 324.791578 -264.527792)
		(width 0.0889)
		(layer "In4.Cu")
		(net "M_D_CPU0_SB_PAR")
	)
	(segment
		(start 336.3341 -264.85342)
		(end 336.342482 -264.848594)
		(width 0.0889)
		(layer "In4.Cu")
		(net "M_D_CPU0_SB_PAR")
	)
	(segment
		(start 326.917812 -264.862818)
		(end 326.93356 -264.853674)
		(width 0.0889)
		(layer "In4.Cu")
		(net "M_D_CPU0_SB_PAR")
	)
	(segment
		(start 330.119736 -264.848594)
		(end 330.128118 -264.85342)
		(width 0.0889)
		(layer "In4.Cu")
		(net "M_D_CPU0_SB_PAR")
	)
	(segment
		(start 308.23408 -266.610084)
		(end 309.769764 -265.0744)
		(width 0.14478)
		(layer "In4.Cu")
		(net "M_D_CPU0_SB_PAR")
	)
	(segment
		(start 339.187028 -264.91057)
		(end 339.341206 -265.176)
		(width 0.0889)
		(layer "In4.Cu")
		(net "M_D_CPU0_SB_PAR")
	)
	(segment
		(start 326.01535 -264.527792)
		(end 326.252332 -264.764774)
		(width 0.0889)
		(layer "In4.Cu")
		(net "M_D_CPU0_SB_PAR")
	)
	(segment
		(start 331.05979 -264.848594)
		(end 331.068172 -264.85342)
		(width 0.0889)
		(layer "In4.Cu")
		(net "M_D_CPU0_SB_PAR")
	)
	(segment
		(start 309.769764 -265.0744)
		(end 323.906134 -265.0744)
		(width 0.14478)
		(layer "In4.Cu")
		(net "M_D_CPU0_SB_PAR")
	)
	(segment
		(start 338.579714 -264.848594)
		(end 338.588096 -264.85342)
		(width 0.0889)
		(layer "In4.Cu")
		(net "M_D_CPU0_SB_PAR")
	)
	(segment
		(start 333.879698 -264.848594)
		(end 333.88808 -264.85342)
		(width 0.0889)
		(layer "In4.Cu")
		(net "M_D_CPU0_SB_PAR")
	)
	(segment
		(start 328.239882 -264.848594)
		(end 328.248264 -264.85342)
		(width 0.0889)
		(layer "In4.Cu")
		(net "M_D_CPU0_SB_PAR")
	)
	(segment
		(start 280.635964 -267.035026)
		(end 281.060906 -266.610084)
		(width 0.14478)
		(layer "In4.Cu")
		(net "M_D_CPU0_SB_PAR")
	)
	(segment
		(start 339.090762 -264.88517)
		(end 339.187028 -264.91057)
		(width 0.0889)
		(layer "In4.Cu")
		(net "M_D_CPU0_SB_PAR")
	)
	(segment
		(start 326.93356 -264.853674)
		(end 326.949816 -264.844276)
		(width 0.0889)
		(layer "In4.Cu")
		(net "M_D_CPU0_SB_PAR")
	)
	(segment
		(start 281.060906 -266.610084)
		(end 308.23408 -266.610084)
		(width 0.14478)
		(layer "In4.Cu")
		(net "M_D_CPU0_SB_PAR")
	)
	(segment
		(start 324.791578 -264.527792)
		(end 326.01535 -264.527792)
		(width 0.0889)
		(layer "In4.Cu")
		(net "M_D_CPU0_SB_PAR")
	)
	(segment
		(start 334.819752 -264.848594)
		(end 334.828134 -264.85342)
		(width 0.0889)
		(layer "In4.Cu")
		(net "M_D_CPU0_SB_PAR")
	)
	(arc
		(start 333.88808 -264.85342)
		(mid 334.171036 -264.929597)
		(end 334.453992 -264.85342)
		(width 0.0889)
		(layer "In4.Cu")
		(net "M_D_CPU0_SB_PAR")
	)
	(arc
		(start 338.588096 -264.85342)
		(mid 338.835692 -264.928598)
		(end 339.090762 -264.88517)
		(width 0.0889)
		(layer "In4.Cu")
		(net "M_D_CPU0_SB_PAR")
	)
	(arc
		(start 334.828134 -264.85342)
		(mid 335.11109 -264.929597)
		(end 335.394046 -264.85342)
		(width 0.0889)
		(layer "In4.Cu")
		(net "M_D_CPU0_SB_PAR")
	)
	(arc
		(start 336.342482 -264.848594)
		(mid 336.52599 -264.8031)
		(end 336.708242 -264.85342)
		(width 0.0889)
		(layer "In4.Cu")
		(net "M_D_CPU0_SB_PAR")
	)
	(arc
		(start 329.188064 -264.85342)
		(mid 329.47102 -264.929597)
		(end 329.753976 -264.85342)
		(width 0.0889)
		(layer "In4.Cu")
		(net "M_D_CPU0_SB_PAR")
	)
	(arc
		(start 326.949816 -264.844276)
		(mid 327.129798 -264.803176)
		(end 327.307448 -264.85342)
		(width 0.0889)
		(layer "In4.Cu")
		(net "M_D_CPU0_SB_PAR")
	)
	(arc
		(start 331.642466 -264.848594)
		(mid 331.825974 -264.8031)
		(end 332.008226 -264.85342)
		(width 0.0889)
		(layer "In4.Cu")
		(net "M_D_CPU0_SB_PAR")
	)
	(arc
		(start 333.513938 -264.85342)
		(mid 333.696189 -264.80307)
		(end 333.879698 -264.848594)
		(width 0.0889)
		(layer "In4.Cu")
		(net "M_D_CPU0_SB_PAR")
	)
	(arc
		(start 327.873614 -264.85342)
		(mid 328.056119 -264.802943)
		(end 328.239882 -264.848594)
		(width 0.0889)
		(layer "In4.Cu")
		(net "M_D_CPU0_SB_PAR")
	)
	(arc
		(start 326.367648 -264.85342)
		(mid 326.641503 -264.92977)
		(end 326.917812 -264.862818)
		(width 0.0889)
		(layer "In4.Cu")
		(net "M_D_CPU0_SB_PAR")
	)
	(arc
		(start 330.128118 -264.85342)
		(mid 330.411074 -264.929597)
		(end 330.69403 -264.85342)
		(width 0.0889)
		(layer "In4.Cu")
		(net "M_D_CPU0_SB_PAR")
	)
	(arc
		(start 332.948026 -264.85342)
		(mid 333.230982 -264.929597)
		(end 333.513938 -264.85342)
		(width 0.0889)
		(layer "In4.Cu")
		(net "M_D_CPU0_SB_PAR")
	)
	(arc
		(start 327.317862 -264.859516)
		(mid 327.596548 -264.929736)
		(end 327.873614 -264.85342)
		(width 0.0889)
		(layer "In4.Cu")
		(net "M_D_CPU0_SB_PAR")
	)
	(arc
		(start 329.753976 -264.85342)
		(mid 329.936227 -264.80307)
		(end 330.119736 -264.848594)
		(width 0.0889)
		(layer "In4.Cu")
		(net "M_D_CPU0_SB_PAR")
	)
	(arc
		(start 328.248264 -264.85342)
		(mid 328.53122 -264.929597)
		(end 328.814176 -264.85342)
		(width 0.0889)
		(layer "In4.Cu")
		(net "M_D_CPU0_SB_PAR")
	)
	(arc
		(start 335.402428 -264.848594)
		(mid 335.585936 -264.8031)
		(end 335.768188 -264.85342)
		(width 0.0889)
		(layer "In4.Cu")
		(net "M_D_CPU0_SB_PAR")
	)
	(arc
		(start 332.574138 -264.85342)
		(mid 332.761082 -264.803165)
		(end 332.948026 -264.85342)
		(width 0.0889)
		(layer "In4.Cu")
		(net "M_D_CPU0_SB_PAR")
	)
	(arc
		(start 336.708242 -264.85342)
		(mid 336.991198 -264.929597)
		(end 337.274154 -264.85342)
		(width 0.0889)
		(layer "In4.Cu")
		(net "M_D_CPU0_SB_PAR")
	)
	(arc
		(start 326.252332 -264.764774)
		(mid 326.307117 -264.812834)
		(end 326.367648 -264.85342)
		(width 0.0889)
		(layer "In4.Cu")
		(net "M_D_CPU0_SB_PAR")
	)
	(arc
		(start 335.768188 -264.85342)
		(mid 336.051144 -264.929597)
		(end 336.3341 -264.85342)
		(width 0.0889)
		(layer "In4.Cu")
		(net "M_D_CPU0_SB_PAR")
	)
	(arc
		(start 328.814176 -264.85342)
		(mid 329.00112 -264.803165)
		(end 329.188064 -264.85342)
		(width 0.0889)
		(layer "In4.Cu")
		(net "M_D_CPU0_SB_PAR")
	)
	(arc
		(start 331.068172 -264.85342)
		(mid 331.351128 -264.929597)
		(end 331.634084 -264.85342)
		(width 0.0889)
		(layer "In4.Cu")
		(net "M_D_CPU0_SB_PAR")
	)
	(arc
		(start 334.453992 -264.85342)
		(mid 334.636243 -264.80307)
		(end 334.819752 -264.848594)
		(width 0.0889)
		(layer "In4.Cu")
		(net "M_D_CPU0_SB_PAR")
	)
	(arc
		(start 338.213954 -264.85342)
		(mid 338.396205 -264.80307)
		(end 338.579714 -264.848594)
		(width 0.0889)
		(layer "In4.Cu")
		(net "M_D_CPU0_SB_PAR")
	)
	(arc
		(start 337.274154 -264.85342)
		(mid 337.461098 -264.803165)
		(end 337.648042 -264.85342)
		(width 0.0889)
		(layer "In4.Cu")
		(net "M_D_CPU0_SB_PAR")
	)
	(arc
		(start 330.69403 -264.85342)
		(mid 330.876281 -264.80307)
		(end 331.05979 -264.848594)
		(width 0.0889)
		(layer "In4.Cu")
		(net "M_D_CPU0_SB_PAR")
	)
	(arc
		(start 332.008226 -264.85342)
		(mid 332.291182 -264.929597)
		(end 332.574138 -264.85342)
		(width 0.0889)
		(layer "In4.Cu")
		(net "M_D_CPU0_SB_PAR")
	)
	(arc
		(start 337.648042 -264.85342)
		(mid 337.930998 -264.929597)
		(end 338.213954 -264.85342)
		(width 0.0889)
		(layer "In4.Cu")
		(net "M_D_CPU0_SB_PAR")
	)
	(segment
		(start 339.337904 -270.580104)
		(end 338.871052 -270.846042)
		(width 0.12954)
		(layer "F.Cu")
		(net "M_D_CPU0_SB_DQS_DP<9>")
	)
	(segment
		(start 293.558976 -274.618196)
		(end 293.558976 -274.405344)
		(width 0.16002)
		(layer "In4.Cu")
		(net "M_D_CPU0_SB_DQS_DP<9>")
	)
	(segment
		(start 303.797716 -274.773644)
		(end 303.797716 -275.791676)
		(width 0.16002)
		(layer "In4.Cu")
		(net "M_D_CPU0_SB_DQS_DP<9>")
	)
	(segment
		(start 337.74253 -271.171162)
		(end 337.750912 -271.175988)
		(width 0.09525)
		(layer "In4.Cu")
		(net "M_D_CPU0_SB_DQS_DP<9>")
	)
	(segment
		(start 298.803822 -275.17471)
		(end 299.293534 -274.684998)
		(width 0.16002)
		(layer "In4.Cu")
		(net "M_D_CPU0_SB_DQS_DP<9>")
	)
	(segment
		(start 301.410878 -273.986752)
		(end 301.78375 -274.359624)
		(width 0.16002)
		(layer "In4.Cu")
		(net "M_D_CPU0_SB_DQS_DP<9>")
	)
	(segment
		(start 336.23123 -271.175988)
		(end 336.239612 -271.171162)
		(width 0.09525)
		(layer "In4.Cu")
		(net "M_D_CPU0_SB_DQS_DP<9>")
	)
	(segment
		(start 328.711306 -271.175988)
		(end 328.719688 -271.171162)
		(width 0.09525)
		(layer "In4.Cu")
		(net "M_D_CPU0_SB_DQS_DP<9>")
	)
	(segment
		(start 324.773544 -270.143732)
		(end 325.401178 -270.143732)
		(width 0.09525)
		(layer "In4.Cu")
		(net "M_D_CPU0_SB_DQS_DP<9>")
	)
	(segment
		(start 287.477708 -275.63572)
		(end 289.056064 -275.63572)
		(width 0.16002)
		(layer "In4.Cu")
		(net "M_D_CPU0_SB_DQS_DP<9>")
	)
	(segment
		(start 300.552358 -273.986752)
		(end 301.410878 -273.986752)
		(width 0.16002)
		(layer "In4.Cu")
		(net "M_D_CPU0_SB_DQS_DP<9>")
	)
	(segment
		(start 302.524922 -274.773644)
		(end 302.897794 -274.400772)
		(width 0.16002)
		(layer "In4.Cu")
		(net "M_D_CPU0_SB_DQS_DP<9>")
	)
	(segment
		(start 313.305952 -269.53337)
		(end 323.912992 -269.53337)
		(width 0.16002)
		(layer "In4.Cu")
		(net "M_D_CPU0_SB_DQS_DP<9>")
	)
	(segment
		(start 291.429948 -274.778216)
		(end 293.398956 -274.778216)
		(width 0.16002)
		(layer "In4.Cu")
		(net "M_D_CPU0_SB_DQS_DP<9>")
	)
	(segment
		(start 289.056064 -275.63572)
		(end 289.395154 -275.97481)
		(width 0.16002)
		(layer "In4.Cu")
		(net "M_D_CPU0_SB_DQS_DP<9>")
	)
	(segment
		(start 286.066992 -275.63572)
		(end 286.763968 -275.63572)
		(width 0.16002)
		(layer "In4.Cu")
		(net "M_D_CPU0_SB_DQS_DP<9>")
	)
	(segment
		(start 294.458898 -274.032472)
		(end 294.83177 -274.405344)
		(width 0.16002)
		(layer "In4.Cu")
		(net "M_D_CPU0_SB_DQS_DP<9>")
	)
	(segment
		(start 285.009844 -275.808948)
		(end 285.893764 -275.808948)
		(width 0.16002)
		(layer "In4.Cu")
		(net "M_D_CPU0_SB_DQS_DP<9>")
	)
	(segment
		(start 301.979584 -275.98751)
		(end 302.329088 -275.98751)
		(width 0.16002)
		(layer "In4.Cu")
		(net "M_D_CPU0_SB_DQS_DP<9>")
	)
	(segment
		(start 325.401178 -270.143732)
		(end 326.48017 -271.222724)
		(width 0.09525)
		(layer "In4.Cu")
		(net "M_D_CPU0_SB_DQS_DP<9>")
	)
	(segment
		(start 296.913554 -275.97481)
		(end 297.319954 -275.97481)
		(width 0.16002)
		(layer "In4.Cu")
		(net "M_D_CPU0_SB_DQS_DP<9>")
	)
	(segment
		(start 289.750754 -275.97481)
		(end 290.576254 -275.14931)
		(width 0.16002)
		(layer "In4.Cu")
		(net "M_D_CPU0_SB_DQS_DP<9>")
	)
	(segment
		(start 323.912992 -269.53337)
		(end 323.936614 -269.53337)
		(width 0.09525)
		(layer "In4.Cu")
		(net "M_D_CPU0_SB_DQS_DP<9>")
	)
	(segment
		(start 302.524922 -275.791676)
		(end 302.524922 -274.773644)
		(width 0.16002)
		(layer "In4.Cu")
		(net "M_D_CPU0_SB_DQS_DP<9>")
	)
	(segment
		(start 302.897794 -274.400772)
		(end 303.424844 -274.400772)
		(width 0.16002)
		(layer "In4.Cu")
		(net "M_D_CPU0_SB_DQS_DP<9>")
	)
	(segment
		(start 299.293534 -274.684998)
		(end 299.854112 -274.684998)
		(width 0.16002)
		(layer "In4.Cu")
		(net "M_D_CPU0_SB_DQS_DP<9>")
	)
	(segment
		(start 301.78375 -274.359624)
		(end 301.78375 -275.791676)
		(width 0.16002)
		(layer "In4.Cu")
		(net "M_D_CPU0_SB_DQS_DP<9>")
	)
	(segment
		(start 303.424844 -274.400772)
		(end 303.797716 -274.773644)
		(width 0.16002)
		(layer "In4.Cu")
		(net "M_D_CPU0_SB_DQS_DP<9>")
	)
	(segment
		(start 296.566844 -275.6281)
		(end 296.913554 -275.97481)
		(width 0.16002)
		(layer "In4.Cu")
		(net "M_D_CPU0_SB_DQS_DP<9>")
	)
	(segment
		(start 324.222364 -269.592552)
		(end 324.773544 -270.143732)
		(width 0.09525)
		(layer "In4.Cu")
		(net "M_D_CPU0_SB_DQS_DP<9>")
	)
	(segment
		(start 298.120054 -275.17471)
		(end 298.803822 -275.17471)
		(width 0.16002)
		(layer "In4.Cu")
		(net "M_D_CPU0_SB_DQS_DP<9>")
	)
	(segment
		(start 328.332084 -271.165066)
		(end 328.342498 -271.171162)
		(width 0.09525)
		(layer "In4.Cu")
		(net "M_D_CPU0_SB_DQS_DP<9>")
	)
	(segment
		(start 293.398956 -274.778216)
		(end 293.558976 -274.618196)
		(width 0.16002)
		(layer "In4.Cu")
		(net "M_D_CPU0_SB_DQS_DP<9>")
	)
	(segment
		(start 293.931848 -274.032472)
		(end 294.458898 -274.032472)
		(width 0.16002)
		(layer "In4.Cu")
		(net "M_D_CPU0_SB_DQS_DP<9>")
	)
	(segment
		(start 303.797716 -275.791676)
		(end 303.99355 -275.98751)
		(width 0.16002)
		(layer "In4.Cu")
		(net "M_D_CPU0_SB_DQS_DP<9>")
	)
	(segment
		(start 333.042514 -271.171162)
		(end 333.050896 -271.175988)
		(width 0.09525)
		(layer "In4.Cu")
		(net "M_D_CPU0_SB_DQS_DP<9>")
	)
	(segment
		(start 339.024976 -271.111472)
		(end 338.871052 -270.846042)
		(width 0.09525)
		(layer "In4.Cu")
		(net "M_D_CPU0_SB_DQS_DP<9>")
	)
	(segment
		(start 302.329088 -275.98751)
		(end 302.524922 -275.791676)
		(width 0.16002)
		(layer "In4.Cu")
		(net "M_D_CPU0_SB_DQS_DP<9>")
	)
	(segment
		(start 284.736032 -275.535136)
		(end 285.009844 -275.808948)
		(width 0.16002)
		(layer "In4.Cu")
		(net "M_D_CPU0_SB_DQS_DP<9>")
	)
	(segment
		(start 297.319954 -275.97481)
		(end 298.120054 -275.17471)
		(width 0.16002)
		(layer "In4.Cu")
		(net "M_D_CPU0_SB_DQS_DP<9>")
	)
	(segment
		(start 323.936614 -269.53337)
		(end 323.995796 -269.592552)
		(width 0.09525)
		(layer "In4.Cu")
		(net "M_D_CPU0_SB_DQS_DP<9>")
	)
	(segment
		(start 290.576254 -275.14931)
		(end 291.058854 -275.14931)
		(width 0.16002)
		(layer "In4.Cu")
		(net "M_D_CPU0_SB_DQS_DP<9>")
	)
	(segment
		(start 287.360868 -275.51888)
		(end 287.477708 -275.63572)
		(width 0.16002)
		(layer "In4.Cu")
		(net "M_D_CPU0_SB_DQS_DP<9>")
	)
	(segment
		(start 285.893764 -275.808948)
		(end 286.066992 -275.63572)
		(width 0.16002)
		(layer "In4.Cu")
		(net "M_D_CPU0_SB_DQS_DP<9>")
	)
	(segment
		(start 326.48017 -271.222724)
		(end 327.590404 -271.222724)
		(width 0.09525)
		(layer "In4.Cu")
		(net "M_D_CPU0_SB_DQS_DP<9>")
	)
	(segment
		(start 305.714654 -275.14931)
		(end 307.690012 -275.14931)
		(width 0.16002)
		(layer "In4.Cu")
		(net "M_D_CPU0_SB_DQS_DP<9>")
	)
	(segment
		(start 299.854112 -274.684998)
		(end 300.552358 -273.986752)
		(width 0.16002)
		(layer "In4.Cu")
		(net "M_D_CPU0_SB_DQS_DP<9>")
	)
	(segment
		(start 323.995796 -269.592552)
		(end 324.222364 -269.592552)
		(width 0.09525)
		(layer "In4.Cu")
		(net "M_D_CPU0_SB_DQS_DP<9>")
	)
	(segment
		(start 294.83177 -274.405344)
		(end 294.83177 -275.432266)
		(width 0.16002)
		(layer "In4.Cu")
		(net "M_D_CPU0_SB_DQS_DP<9>")
	)
	(segment
		(start 286.880808 -275.51888)
		(end 287.360868 -275.51888)
		(width 0.16002)
		(layer "In4.Cu")
		(net "M_D_CPU0_SB_DQS_DP<9>")
	)
	(segment
		(start 332.471268 -271.175988)
		(end 332.47965 -271.171162)
		(width 0.09525)
		(layer "In4.Cu")
		(net "M_D_CPU0_SB_DQS_DP<9>")
	)
	(segment
		(start 295.027604 -275.6281)
		(end 296.566844 -275.6281)
		(width 0.16002)
		(layer "In4.Cu")
		(net "M_D_CPU0_SB_DQS_DP<9>")
	)
	(segment
		(start 304.876454 -275.98751)
		(end 305.714654 -275.14931)
		(width 0.16002)
		(layer "In4.Cu")
		(net "M_D_CPU0_SB_DQS_DP<9>")
	)
	(segment
		(start 333.982568 -271.171162)
		(end 333.99095 -271.175988)
		(width 0.09525)
		(layer "In4.Cu")
		(net "M_D_CPU0_SB_DQS_DP<9>")
	)
	(segment
		(start 338.682584 -271.171162)
		(end 338.690966 -271.175988)
		(width 0.09525)
		(layer "In4.Cu")
		(net "M_D_CPU0_SB_DQS_DP<9>")
	)
	(segment
		(start 331.531214 -271.175988)
		(end 331.539596 -271.171162)
		(width 0.09525)
		(layer "In4.Cu")
		(net "M_D_CPU0_SB_DQS_DP<9>")
	)
	(segment
		(start 289.395154 -275.97481)
		(end 289.750754 -275.97481)
		(width 0.16002)
		(layer "In4.Cu")
		(net "M_D_CPU0_SB_DQS_DP<9>")
	)
	(segment
		(start 301.78375 -275.791676)
		(end 301.979584 -275.98751)
		(width 0.16002)
		(layer "In4.Cu")
		(net "M_D_CPU0_SB_DQS_DP<9>")
	)
	(segment
		(start 286.763968 -275.63572)
		(end 286.880808 -275.51888)
		(width 0.16002)
		(layer "In4.Cu")
		(net "M_D_CPU0_SB_DQS_DP<9>")
	)
	(segment
		(start 291.058854 -275.14931)
		(end 291.429948 -274.778216)
		(width 0.16002)
		(layer "In4.Cu")
		(net "M_D_CPU0_SB_DQS_DP<9>")
	)
	(segment
		(start 329.282552 -271.171162)
		(end 329.290934 -271.175988)
		(width 0.09525)
		(layer "In4.Cu")
		(net "M_D_CPU0_SB_DQS_DP<9>")
	)
	(segment
		(start 303.99355 -275.98751)
		(end 304.876454 -275.98751)
		(width 0.16002)
		(layer "In4.Cu")
		(net "M_D_CPU0_SB_DQS_DP<9>")
	)
	(segment
		(start 337.171284 -271.175988)
		(end 337.179666 -271.171162)
		(width 0.09525)
		(layer "In4.Cu")
		(net "M_D_CPU0_SB_DQS_DP<9>")
	)
	(segment
		(start 307.690012 -275.14931)
		(end 313.305952 -269.53337)
		(width 0.16002)
		(layer "In4.Cu")
		(net "M_D_CPU0_SB_DQS_DP<9>")
	)
	(segment
		(start 339.001608 -271.19834)
		(end 339.024976 -271.111472)
		(width 0.09525)
		(layer "In4.Cu")
		(net "M_D_CPU0_SB_DQS_DP<9>")
	)
	(segment
		(start 293.558976 -274.405344)
		(end 293.931848 -274.032472)
		(width 0.16002)
		(layer "In4.Cu")
		(net "M_D_CPU0_SB_DQS_DP<9>")
	)
	(segment
		(start 294.83177 -275.432266)
		(end 295.027604 -275.6281)
		(width 0.16002)
		(layer "In4.Cu")
		(net "M_D_CPU0_SB_DQS_DP<9>")
	)
	(arc
		(start 335.862422 -271.171162)
		(mid 336.046197 -271.221934)
		(end 336.23123 -271.175988)
		(width 0.09525)
		(layer "In4.Cu")
		(net "M_D_CPU0_SB_DQS_DP<9>")
	)
	(arc
		(start 335.299558 -271.171162)
		(mid 335.58099 -271.095407)
		(end 335.862422 -271.171162)
		(width 0.09525)
		(layer "In4.Cu")
		(net "M_D_CPU0_SB_DQS_DP<9>")
	)
	(arc
		(start 333.050896 -271.175988)
		(mid 333.235928 -271.221902)
		(end 333.419704 -271.171162)
		(width 0.09525)
		(layer "In4.Cu")
		(net "M_D_CPU0_SB_DQS_DP<9>")
	)
	(arc
		(start 337.750912 -271.175988)
		(mid 337.935944 -271.221902)
		(end 338.11972 -271.171162)
		(width 0.09525)
		(layer "In4.Cu")
		(net "M_D_CPU0_SB_DQS_DP<9>")
	)
	(arc
		(start 331.162406 -271.171162)
		(mid 331.346181 -271.221934)
		(end 331.531214 -271.175988)
		(width 0.09525)
		(layer "In4.Cu")
		(net "M_D_CPU0_SB_DQS_DP<9>")
	)
	(arc
		(start 327.77938 -271.171162)
		(mid 328.054923 -271.095313)
		(end 328.332084 -271.165066)
		(width 0.09525)
		(layer "In4.Cu")
		(net "M_D_CPU0_SB_DQS_DP<9>")
	)
	(arc
		(start 333.419704 -271.171162)
		(mid 333.701136 -271.095407)
		(end 333.982568 -271.171162)
		(width 0.09525)
		(layer "In4.Cu")
		(net "M_D_CPU0_SB_DQS_DP<9>")
	)
	(arc
		(start 328.342498 -271.171162)
		(mid 328.526273 -271.221934)
		(end 328.711306 -271.175988)
		(width 0.09525)
		(layer "In4.Cu")
		(net "M_D_CPU0_SB_DQS_DP<9>")
	)
	(arc
		(start 330.222606 -271.171162)
		(mid 330.411074 -271.221839)
		(end 330.599542 -271.171162)
		(width 0.09525)
		(layer "In4.Cu")
		(net "M_D_CPU0_SB_DQS_DP<9>")
	)
	(arc
		(start 336.802476 -271.171162)
		(mid 336.986251 -271.221934)
		(end 337.171284 -271.175988)
		(width 0.09525)
		(layer "In4.Cu")
		(net "M_D_CPU0_SB_DQS_DP<9>")
	)
	(arc
		(start 334.359758 -271.171162)
		(mid 334.64119 -271.095407)
		(end 334.922622 -271.171162)
		(width 0.09525)
		(layer "In4.Cu")
		(net "M_D_CPU0_SB_DQS_DP<9>")
	)
	(arc
		(start 332.10246 -271.171162)
		(mid 332.286235 -271.221934)
		(end 332.471268 -271.175988)
		(width 0.09525)
		(layer "In4.Cu")
		(net "M_D_CPU0_SB_DQS_DP<9>")
	)
	(arc
		(start 332.47965 -271.171162)
		(mid 332.761082 -271.095407)
		(end 333.042514 -271.171162)
		(width 0.09525)
		(layer "In4.Cu")
		(net "M_D_CPU0_SB_DQS_DP<9>")
	)
	(arc
		(start 338.11972 -271.171162)
		(mid 338.401152 -271.095407)
		(end 338.682584 -271.171162)
		(width 0.09525)
		(layer "In4.Cu")
		(net "M_D_CPU0_SB_DQS_DP<9>")
	)
	(arc
		(start 338.690966 -271.175988)
		(mid 338.843861 -271.220816)
		(end 339.001608 -271.19834)
		(width 0.09525)
		(layer "In4.Cu")
		(net "M_D_CPU0_SB_DQS_DP<9>")
	)
	(arc
		(start 329.290934 -271.175988)
		(mid 329.475966 -271.221902)
		(end 329.659742 -271.171162)
		(width 0.09525)
		(layer "In4.Cu")
		(net "M_D_CPU0_SB_DQS_DP<9>")
	)
	(arc
		(start 329.659742 -271.171162)
		(mid 329.941174 -271.095407)
		(end 330.222606 -271.171162)
		(width 0.09525)
		(layer "In4.Cu")
		(net "M_D_CPU0_SB_DQS_DP<9>")
	)
	(arc
		(start 336.239612 -271.171162)
		(mid 336.521044 -271.095407)
		(end 336.802476 -271.171162)
		(width 0.09525)
		(layer "In4.Cu")
		(net "M_D_CPU0_SB_DQS_DP<9>")
	)
	(arc
		(start 334.922622 -271.171162)
		(mid 335.11109 -271.221839)
		(end 335.299558 -271.171162)
		(width 0.09525)
		(layer "In4.Cu")
		(net "M_D_CPU0_SB_DQS_DP<9>")
	)
	(arc
		(start 331.539596 -271.171162)
		(mid 331.821028 -271.095407)
		(end 332.10246 -271.171162)
		(width 0.09525)
		(layer "In4.Cu")
		(net "M_D_CPU0_SB_DQS_DP<9>")
	)
	(arc
		(start 328.719688 -271.171162)
		(mid 329.00112 -271.095407)
		(end 329.282552 -271.171162)
		(width 0.09525)
		(layer "In4.Cu")
		(net "M_D_CPU0_SB_DQS_DP<9>")
	)
	(arc
		(start 327.590404 -271.222724)
		(mid 327.688301 -271.209438)
		(end 327.77938 -271.171162)
		(width 0.09525)
		(layer "In4.Cu")
		(net "M_D_CPU0_SB_DQS_DP<9>")
	)
	(arc
		(start 333.99095 -271.175988)
		(mid 334.175982 -271.221902)
		(end 334.359758 -271.171162)
		(width 0.09525)
		(layer "In4.Cu")
		(net "M_D_CPU0_SB_DQS_DP<9>")
	)
	(arc
		(start 337.179666 -271.171162)
		(mid 337.461098 -271.095407)
		(end 337.74253 -271.171162)
		(width 0.09525)
		(layer "In4.Cu")
		(net "M_D_CPU0_SB_DQS_DP<9>")
	)
	(arc
		(start 330.599542 -271.171162)
		(mid 330.880974 -271.095407)
		(end 331.162406 -271.171162)
		(width 0.09525)
		(layer "In4.Cu")
		(net "M_D_CPU0_SB_DQS_DP<9>")
	)
	(segment
		(start 341.218012 -291.640006)
		(end 340.75116 -291.905944)
		(width 0.12954)
		(layer "F.Cu")
		(net "M_D_CPU0_SB_DQS_DP<8>")
	)
	(segment
		(start 337.171284 -291.575998)
		(end 337.179666 -291.580824)
		(width 0.09525)
		(layer "In4.Cu")
		(net "M_D_CPU0_SB_DQS_DP<8>")
	)
	(segment
		(start 310.316372 -312.928508)
		(end 322.594478 -300.650402)
		(width 0.16002)
		(layer "In4.Cu")
		(net "M_D_CPU0_SB_DQS_DP<8>")
	)
	(segment
		(start 340.597236 -291.640514)
		(end 340.75116 -291.905944)
		(width 0.09525)
		(layer "In4.Cu")
		(net "M_D_CPU0_SB_DQS_DP<8>")
	)
	(segment
		(start 288.948114 -315.360304)
		(end 290.691824 -314.194952)
		(width 0.16002)
		(layer "In4.Cu")
		(net "M_D_CPU0_SB_DQS_DP<8>")
	)
	(segment
		(start 329.282552 -291.580824)
		(end 329.290934 -291.575998)
		(width 0.09525)
		(layer "In4.Cu")
		(net "M_D_CPU0_SB_DQS_DP<8>")
	)
	(segment
		(start 322.594478 -298.24807)
		(end 325.297546 -295.545002)
		(width 0.16002)
		(layer "In4.Cu")
		(net "M_D_CPU0_SB_DQS_DP<8>")
	)
	(segment
		(start 325.315072 -295.444926)
		(end 325.314564 -295.444672)
		(width 0.09525)
		(layer "In4.Cu")
		(net "M_D_CPU0_SB_DQS_DP<8>")
	)
	(segment
		(start 297.527726 -314.677298)
		(end 298.24934 -314.194952)
		(width 0.16002)
		(layer "In4.Cu")
		(net "M_D_CPU0_SB_DQS_DP<8>")
	)
	(segment
		(start 305.782726 -314.197492)
		(end 307.253132 -314.197492)
		(width 0.16002)
		(layer "In4.Cu")
		(net "M_D_CPU0_SB_DQS_DP<8>")
	)
	(segment
		(start 283.87421 -314.526676)
		(end 285.60141 -314.526676)
		(width 0.16002)
		(layer "In4.Cu")
		(net "M_D_CPU0_SB_DQS_DP<8>")
	)
	(segment
		(start 325.31431 -295.528238)
		(end 325.31431 -295.445434)
		(width 0.09525)
		(layer "In4.Cu")
		(net "M_D_CPU0_SB_DQS_DP<8>")
	)
	(segment
		(start 325.297546 -295.545002)
		(end 325.31431 -295.528238)
		(width 0.09525)
		(layer "In4.Cu")
		(net "M_D_CPU0_SB_DQS_DP<8>")
	)
	(segment
		(start 337.74253 -291.580824)
		(end 337.750912 -291.575998)
		(width 0.09525)
		(layer "In4.Cu")
		(net "M_D_CPU0_SB_DQS_DP<8>")
	)
	(segment
		(start 326.927718 -292.42639)
		(end 327.697338 -291.656516)
		(width 0.09525)
		(layer "In4.Cu")
		(net "M_D_CPU0_SB_DQS_DP<8>")
	)
	(segment
		(start 283.445204 -314.09767)
		(end 283.87421 -314.526676)
		(width 0.16002)
		(layer "In4.Cu")
		(net "M_D_CPU0_SB_DQS_DP<8>")
	)
	(segment
		(start 307.253132 -314.197492)
		(end 310.316372 -312.928508)
		(width 0.16002)
		(layer "In4.Cu")
		(net "M_D_CPU0_SB_DQS_DP<8>")
	)
	(segment
		(start 331.531214 -291.575998)
		(end 331.539596 -291.580824)
		(width 0.09525)
		(layer "In4.Cu")
		(net "M_D_CPU0_SB_DQS_DP<8>")
	)
	(segment
		(start 325.31431 -295.445434)
		(end 325.315072 -295.444926)
		(width 0.09525)
		(layer "In4.Cu")
		(net "M_D_CPU0_SB_DQS_DP<8>")
	)
	(segment
		(start 332.471268 -291.575998)
		(end 332.47965 -291.580824)
		(width 0.09525)
		(layer "In4.Cu")
		(net "M_D_CPU0_SB_DQS_DP<8>")
	)
	(segment
		(start 295.879012 -315.360304)
		(end 297.527726 -314.677298)
		(width 0.16002)
		(layer "In4.Cu")
		(net "M_D_CPU0_SB_DQS_DP<8>")
	)
	(segment
		(start 286.435038 -315.360304)
		(end 288.948114 -315.360304)
		(width 0.16002)
		(layer "In4.Cu")
		(net "M_D_CPU0_SB_DQS_DP<8>")
	)
	(segment
		(start 298.24934 -314.194952)
		(end 298.26839 -314.182252)
		(width 0.16002)
		(layer "In4.Cu")
		(net "M_D_CPU0_SB_DQS_DP<8>")
	)
	(segment
		(start 322.594478 -300.650402)
		(end 322.594478 -298.24807)
		(width 0.16002)
		(layer "In4.Cu")
		(net "M_D_CPU0_SB_DQS_DP<8>")
	)
	(segment
		(start 298.628054 -314.182252)
		(end 299.419772 -314.98921)
		(width 0.16002)
		(layer "In4.Cu")
		(net "M_D_CPU0_SB_DQS_DP<8>")
	)
	(segment
		(start 325.314564 -295.444672)
		(end 325.666608 -295.093898)
		(width 0.09525)
		(layer "In4.Cu")
		(net "M_D_CPU0_SB_DQS_DP<8>")
	)
	(segment
		(start 299.419772 -314.98921)
		(end 304.991008 -314.98921)
		(width 0.16002)
		(layer "In4.Cu")
		(net "M_D_CPU0_SB_DQS_DP<8>")
	)
	(segment
		(start 325.666608 -295.093898)
		(end 325.666608 -294.44442)
		(width 0.09525)
		(layer "In4.Cu")
		(net "M_D_CPU0_SB_DQS_DP<8>")
	)
	(segment
		(start 281.92349 -314.361322)
		(end 282.187142 -314.09767)
		(width 0.16002)
		(layer "In4.Cu")
		(net "M_D_CPU0_SB_DQS_DP<8>")
	)
	(segment
		(start 338.682584 -291.580824)
		(end 338.690966 -291.575998)
		(width 0.09525)
		(layer "In4.Cu")
		(net "M_D_CPU0_SB_DQS_DP<8>")
	)
	(segment
		(start 333.982568 -291.580824)
		(end 333.99095 -291.575998)
		(width 0.09525)
		(layer "In4.Cu")
		(net "M_D_CPU0_SB_DQS_DP<8>")
	)
	(segment
		(start 328.711306 -291.575998)
		(end 328.719688 -291.580824)
		(width 0.09525)
		(layer "In4.Cu")
		(net "M_D_CPU0_SB_DQS_DP<8>")
	)
	(segment
		(start 282.187142 -314.09767)
		(end 283.445204 -314.09767)
		(width 0.16002)
		(layer "In4.Cu")
		(net "M_D_CPU0_SB_DQS_DP<8>")
	)
	(segment
		(start 325.809864 -294.099234)
		(end 326.927718 -292.42639)
		(width 0.09525)
		(layer "In4.Cu")
		(net "M_D_CPU0_SB_DQS_DP<8>")
	)
	(segment
		(start 285.60141 -314.526676)
		(end 286.435038 -315.360304)
		(width 0.16002)
		(layer "In4.Cu")
		(net "M_D_CPU0_SB_DQS_DP<8>")
	)
	(segment
		(start 298.26839 -314.182252)
		(end 298.628054 -314.182252)
		(width 0.16002)
		(layer "In4.Cu")
		(net "M_D_CPU0_SB_DQS_DP<8>")
	)
	(segment
		(start 340.496398 -291.613844)
		(end 340.597236 -291.640514)
		(width 0.09525)
		(layer "In4.Cu")
		(net "M_D_CPU0_SB_DQS_DP<8>")
	)
	(segment
		(start 290.691824 -314.194952)
		(end 290.70427 -314.18657)
		(width 0.16002)
		(layer "In4.Cu")
		(net "M_D_CPU0_SB_DQS_DP<8>")
	)
	(segment
		(start 336.23123 -291.575998)
		(end 336.239612 -291.580824)
		(width 0.09525)
		(layer "In4.Cu")
		(net "M_D_CPU0_SB_DQS_DP<8>")
	)
	(segment
		(start 280.909776 -314.361322)
		(end 281.92349 -314.361322)
		(width 0.16002)
		(layer "In4.Cu")
		(net "M_D_CPU0_SB_DQS_DP<8>")
	)
	(segment
		(start 291.192204 -314.194952)
		(end 293.968932 -315.360304)
		(width 0.16002)
		(layer "In4.Cu")
		(net "M_D_CPU0_SB_DQS_DP<8>")
	)
	(segment
		(start 291.172138 -314.18657)
		(end 291.192204 -314.194952)
		(width 0.16002)
		(layer "In4.Cu")
		(net "M_D_CPU0_SB_DQS_DP<8>")
	)
	(segment
		(start 290.70427 -314.18657)
		(end 291.172138 -314.18657)
		(width 0.16002)
		(layer "In4.Cu")
		(net "M_D_CPU0_SB_DQS_DP<8>")
	)
	(segment
		(start 325.666608 -294.44442)
		(end 325.809864 -294.099234)
		(width 0.09525)
		(layer "In4.Cu")
		(net "M_D_CPU0_SB_DQS_DP<8>")
	)
	(segment
		(start 293.968932 -315.360304)
		(end 295.879012 -315.360304)
		(width 0.16002)
		(layer "In4.Cu")
		(net "M_D_CPU0_SB_DQS_DP<8>")
	)
	(segment
		(start 280.635964 -314.635134)
		(end 280.909776 -314.361322)
		(width 0.16002)
		(layer "In4.Cu")
		(net "M_D_CPU0_SB_DQS_DP<8>")
	)
	(segment
		(start 327.697338 -291.656516)
		(end 328.061066 -291.656516)
		(width 0.09525)
		(layer "In4.Cu")
		(net "M_D_CPU0_SB_DQS_DP<8>")
	)
	(segment
		(start 304.991008 -314.98921)
		(end 305.782726 -314.197492)
		(width 0.16002)
		(layer "In4.Cu")
		(net "M_D_CPU0_SB_DQS_DP<8>")
	)
	(segment
		(start 333.042514 -291.580824)
		(end 333.050896 -291.575998)
		(width 0.09525)
		(layer "In4.Cu")
		(net "M_D_CPU0_SB_DQS_DP<8>")
	)
	(arc
		(start 328.342498 -291.580824)
		(mid 328.526273 -291.530052)
		(end 328.711306 -291.575998)
		(width 0.09525)
		(layer "In4.Cu")
		(net "M_D_CPU0_SB_DQS_DP<8>")
	)
	(arc
		(start 336.239612 -291.580824)
		(mid 336.521044 -291.656579)
		(end 336.802476 -291.580824)
		(width 0.09525)
		(layer "In4.Cu")
		(net "M_D_CPU0_SB_DQS_DP<8>")
	)
	(arc
		(start 338.690966 -291.575998)
		(mid 338.875998 -291.530084)
		(end 339.059774 -291.580824)
		(width 0.09525)
		(layer "In4.Cu")
		(net "M_D_CPU0_SB_DQS_DP<8>")
	)
	(arc
		(start 328.061066 -291.656516)
		(mid 328.206774 -291.637248)
		(end 328.342498 -291.580824)
		(width 0.09525)
		(layer "In4.Cu")
		(net "M_D_CPU0_SB_DQS_DP<8>")
	)
	(arc
		(start 335.299558 -291.580824)
		(mid 335.58099 -291.656579)
		(end 335.862422 -291.580824)
		(width 0.09525)
		(layer "In4.Cu")
		(net "M_D_CPU0_SB_DQS_DP<8>")
	)
	(arc
		(start 339.622638 -291.580824)
		(mid 339.811106 -291.530147)
		(end 339.999574 -291.580824)
		(width 0.09525)
		(layer "In4.Cu")
		(net "M_D_CPU0_SB_DQS_DP<8>")
	)
	(arc
		(start 330.222606 -291.580824)
		(mid 330.411074 -291.530147)
		(end 330.599542 -291.580824)
		(width 0.09525)
		(layer "In4.Cu")
		(net "M_D_CPU0_SB_DQS_DP<8>")
	)
	(arc
		(start 329.290934 -291.575998)
		(mid 329.475966 -291.530084)
		(end 329.659742 -291.580824)
		(width 0.09525)
		(layer "In4.Cu")
		(net "M_D_CPU0_SB_DQS_DP<8>")
	)
	(arc
		(start 333.419704 -291.580824)
		(mid 333.701136 -291.656579)
		(end 333.982568 -291.580824)
		(width 0.09525)
		(layer "In4.Cu")
		(net "M_D_CPU0_SB_DQS_DP<8>")
	)
	(arc
		(start 337.750912 -291.575998)
		(mid 337.935944 -291.530084)
		(end 338.11972 -291.580824)
		(width 0.09525)
		(layer "In4.Cu")
		(net "M_D_CPU0_SB_DQS_DP<8>")
	)
	(arc
		(start 332.10246 -291.580824)
		(mid 332.286235 -291.530052)
		(end 332.471268 -291.575998)
		(width 0.09525)
		(layer "In4.Cu")
		(net "M_D_CPU0_SB_DQS_DP<8>")
	)
	(arc
		(start 337.179666 -291.580824)
		(mid 337.461098 -291.656579)
		(end 337.74253 -291.580824)
		(width 0.09525)
		(layer "In4.Cu")
		(net "M_D_CPU0_SB_DQS_DP<8>")
	)
	(arc
		(start 334.922622 -291.580824)
		(mid 335.11109 -291.530147)
		(end 335.299558 -291.580824)
		(width 0.09525)
		(layer "In4.Cu")
		(net "M_D_CPU0_SB_DQS_DP<8>")
	)
	(arc
		(start 339.999574 -291.580824)
		(mid 340.233088 -291.654667)
		(end 340.475824 -291.621972)
		(width 0.09525)
		(layer "In4.Cu")
		(net "M_D_CPU0_SB_DQS_DP<8>")
	)
	(arc
		(start 332.47965 -291.580824)
		(mid 332.761082 -291.656579)
		(end 333.042514 -291.580824)
		(width 0.09525)
		(layer "In4.Cu")
		(net "M_D_CPU0_SB_DQS_DP<8>")
	)
	(arc
		(start 333.050896 -291.575998)
		(mid 333.235928 -291.530084)
		(end 333.419704 -291.580824)
		(width 0.09525)
		(layer "In4.Cu")
		(net "M_D_CPU0_SB_DQS_DP<8>")
	)
	(arc
		(start 330.599542 -291.580824)
		(mid 330.880974 -291.656579)
		(end 331.162406 -291.580824)
		(width 0.09525)
		(layer "In4.Cu")
		(net "M_D_CPU0_SB_DQS_DP<8>")
	)
	(arc
		(start 339.059774 -291.580824)
		(mid 339.341206 -291.656579)
		(end 339.622638 -291.580824)
		(width 0.09525)
		(layer "In4.Cu")
		(net "M_D_CPU0_SB_DQS_DP<8>")
	)
	(arc
		(start 329.659742 -291.580824)
		(mid 329.941174 -291.656579)
		(end 330.222606 -291.580824)
		(width 0.09525)
		(layer "In4.Cu")
		(net "M_D_CPU0_SB_DQS_DP<8>")
	)
	(arc
		(start 331.162406 -291.580824)
		(mid 331.346181 -291.530052)
		(end 331.531214 -291.575998)
		(width 0.09525)
		(layer "In4.Cu")
		(net "M_D_CPU0_SB_DQS_DP<8>")
	)
	(arc
		(start 328.719688 -291.580824)
		(mid 329.00112 -291.656579)
		(end 329.282552 -291.580824)
		(width 0.09525)
		(layer "In4.Cu")
		(net "M_D_CPU0_SB_DQS_DP<8>")
	)
	(arc
		(start 340.475824 -291.621972)
		(mid 340.486152 -291.618012)
		(end 340.496398 -291.613844)
		(width 0.09525)
		(layer "In4.Cu")
		(net "M_D_CPU0_SB_DQS_DP<8>")
	)
	(arc
		(start 331.539596 -291.580824)
		(mid 331.821028 -291.656579)
		(end 332.10246 -291.580824)
		(width 0.09525)
		(layer "In4.Cu")
		(net "M_D_CPU0_SB_DQS_DP<8>")
	)
	(arc
		(start 338.11972 -291.580824)
		(mid 338.401152 -291.656579)
		(end 338.682584 -291.580824)
		(width 0.09525)
		(layer "In4.Cu")
		(net "M_D_CPU0_SB_DQS_DP<8>")
	)
	(arc
		(start 334.359758 -291.580824)
		(mid 334.64119 -291.656579)
		(end 334.922622 -291.580824)
		(width 0.09525)
		(layer "In4.Cu")
		(net "M_D_CPU0_SB_DQS_DP<8>")
	)
	(arc
		(start 333.99095 -291.575998)
		(mid 334.175982 -291.530084)
		(end 334.359758 -291.580824)
		(width 0.09525)
		(layer "In4.Cu")
		(net "M_D_CPU0_SB_DQS_DP<8>")
	)
	(arc
		(start 335.862422 -291.580824)
		(mid 336.046197 -291.530052)
		(end 336.23123 -291.575998)
		(width 0.09525)
		(layer "In4.Cu")
		(net "M_D_CPU0_SB_DQS_DP<8>")
	)
	(arc
		(start 336.802476 -291.580824)
		(mid 336.986251 -291.530052)
		(end 337.171284 -291.575998)
		(width 0.09525)
		(layer "In4.Cu")
		(net "M_D_CPU0_SB_DQS_DP<8>")
	)
	(segment
		(start 341.218012 -286.780224)
		(end 340.75116 -287.045908)
		(width 0.12954)
		(layer "F.Cu")
		(net "M_D_CPU0_SB_DQS_DP<7>")
	)
	(segment
		(start 325.970138 -286.796988)
		(end 326.180196 -286.796988)
		(width 0.09525)
		(layer "In4.Cu")
		(net "M_D_CPU0_SB_DQS_DP<7>")
	)
	(segment
		(start 337.171284 -286.715962)
		(end 337.179666 -286.720788)
		(width 0.09525)
		(layer "In4.Cu")
		(net "M_D_CPU0_SB_DQS_DP<7>")
	)
	(segment
		(start 333.982568 -286.720788)
		(end 333.99095 -286.715962)
		(width 0.09525)
		(layer "In4.Cu")
		(net "M_D_CPU0_SB_DQS_DP<7>")
	)
	(segment
		(start 328.711306 -286.715962)
		(end 328.719688 -286.720788)
		(width 0.09525)
		(layer "In4.Cu")
		(net "M_D_CPU0_SB_DQS_DP<7>")
	)
	(segment
		(start 288.366962 -306.01031)
		(end 290.32708 -305.198526)
		(width 0.16002)
		(layer "In4.Cu")
		(net "M_D_CPU0_SB_DQS_DP<7>")
	)
	(segment
		(start 324.109842 -288.026856)
		(end 324.126606 -288.010092)
		(width 0.09525)
		(layer "In4.Cu")
		(net "M_D_CPU0_SB_DQS_DP<7>")
	)
	(segment
		(start 285.172404 -305.436524)
		(end 288.056828 -306.01031)
		(width 0.16002)
		(layer "In4.Cu")
		(net "M_D_CPU0_SB_DQS_DP<7>")
	)
	(segment
		(start 324.968108 -287.085532)
		(end 325.681594 -287.085532)
		(width 0.09525)
		(layer "In4.Cu")
		(net "M_D_CPU0_SB_DQS_DP<7>")
	)
	(segment
		(start 295.225978 -306.01031)
		(end 296.083228 -306.01031)
		(width 0.16002)
		(layer "In4.Cu")
		(net "M_D_CPU0_SB_DQS_DP<7>")
	)
	(segment
		(start 283.896816 -305.176682)
		(end 284.54477 -305.176682)
		(width 0.16002)
		(layer "In4.Cu")
		(net "M_D_CPU0_SB_DQS_DP<7>")
	)
	(segment
		(start 336.23123 -286.715962)
		(end 336.239612 -286.720788)
		(width 0.09525)
		(layer "In4.Cu")
		(net "M_D_CPU0_SB_DQS_DP<7>")
	)
	(segment
		(start 337.74253 -286.720788)
		(end 337.750912 -286.715962)
		(width 0.09525)
		(layer "In4.Cu")
		(net "M_D_CPU0_SB_DQS_DP<7>")
	)
	(segment
		(start 329.282552 -286.720788)
		(end 329.290934 -286.715962)
		(width 0.09525)
		(layer "In4.Cu")
		(net "M_D_CPU0_SB_DQS_DP<7>")
	)
	(segment
		(start 283.503878 -304.783744)
		(end 283.896816 -305.176682)
		(width 0.16002)
		(layer "In4.Cu")
		(net "M_D_CPU0_SB_DQS_DP<7>")
	)
	(segment
		(start 324.126606 -288.010092)
		(end 324.126606 -287.927288)
		(width 0.09525)
		(layer "In4.Cu")
		(net "M_D_CPU0_SB_DQS_DP<7>")
	)
	(segment
		(start 309.395876 -303.959768)
		(end 316.904878 -296.450766)
		(width 0.16002)
		(layer "In4.Cu")
		(net "M_D_CPU0_SB_DQS_DP<7>")
	)
	(segment
		(start 325.681594 -287.085532)
		(end 325.970138 -286.796988)
		(width 0.09525)
		(layer "In4.Cu")
		(net "M_D_CPU0_SB_DQS_DP<7>")
	)
	(segment
		(start 300.7868 -305.160172)
		(end 302.036226 -305.67757)
		(width 0.16002)
		(layer "In4.Cu")
		(net "M_D_CPU0_SB_DQS_DP<7>")
	)
	(segment
		(start 304.931064 -305.67757)
		(end 305.717448 -304.891186)
		(width 0.16002)
		(layer "In4.Cu")
		(net "M_D_CPU0_SB_DQS_DP<7>")
	)
	(segment
		(start 291.418518 -305.160172)
		(end 293.173404 -305.160172)
		(width 0.16002)
		(layer "In4.Cu")
		(net "M_D_CPU0_SB_DQS_DP<7>")
	)
	(segment
		(start 327.401682 -286.720788)
		(end 327.41362 -286.71393)
		(width 0.09525)
		(layer "In4.Cu")
		(net "M_D_CPU0_SB_DQS_DP<7>")
	)
	(segment
		(start 280.909776 -305.011328)
		(end 282.821634 -305.011328)
		(width 0.16002)
		(layer "In4.Cu")
		(net "M_D_CPU0_SB_DQS_DP<7>")
	)
	(segment
		(start 326.821038 -286.710628)
		(end 326.839326 -286.721042)
		(width 0.09525)
		(layer "In4.Cu")
		(net "M_D_CPU0_SB_DQS_DP<7>")
	)
	(segment
		(start 324.126606 -287.927288)
		(end 324.968108 -287.085532)
		(width 0.09525)
		(layer "In4.Cu")
		(net "M_D_CPU0_SB_DQS_DP<7>")
	)
	(segment
		(start 316.904878 -295.231312)
		(end 324.109842 -288.026856)
		(width 0.16002)
		(layer "In4.Cu")
		(net "M_D_CPU0_SB_DQS_DP<7>")
	)
	(segment
		(start 333.042514 -286.720788)
		(end 333.050896 -286.715962)
		(width 0.09525)
		(layer "In4.Cu")
		(net "M_D_CPU0_SB_DQS_DP<7>")
	)
	(segment
		(start 316.904878 -296.450766)
		(end 316.904878 -295.231312)
		(width 0.16002)
		(layer "In4.Cu")
		(net "M_D_CPU0_SB_DQS_DP<7>")
	)
	(segment
		(start 302.036226 -305.67757)
		(end 304.931064 -305.67757)
		(width 0.16002)
		(layer "In4.Cu")
		(net "M_D_CPU0_SB_DQS_DP<7>")
	)
	(segment
		(start 296.083228 -306.01031)
		(end 297.165776 -305.562)
		(width 0.16002)
		(layer "In4.Cu")
		(net "M_D_CPU0_SB_DQS_DP<7>")
	)
	(segment
		(start 298.634404 -304.832258)
		(end 299.426122 -305.160172)
		(width 0.16002)
		(layer "In4.Cu")
		(net "M_D_CPU0_SB_DQS_DP<7>")
	)
	(segment
		(start 338.682584 -286.720788)
		(end 338.690966 -286.715962)
		(width 0.09525)
		(layer "In4.Cu")
		(net "M_D_CPU0_SB_DQS_DP<7>")
	)
	(segment
		(start 293.173404 -305.160172)
		(end 295.225978 -306.01031)
		(width 0.16002)
		(layer "In4.Cu")
		(net "M_D_CPU0_SB_DQS_DP<7>")
	)
	(segment
		(start 291.065204 -304.806858)
		(end 291.418518 -305.160172)
		(width 0.16002)
		(layer "In4.Cu")
		(net "M_D_CPU0_SB_DQS_DP<7>")
	)
	(segment
		(start 282.821634 -305.011328)
		(end 283.049218 -304.783744)
		(width 0.16002)
		(layer "In4.Cu")
		(net "M_D_CPU0_SB_DQS_DP<7>")
	)
	(segment
		(start 288.056828 -306.01031)
		(end 288.366962 -306.01031)
		(width 0.16002)
		(layer "In4.Cu")
		(net "M_D_CPU0_SB_DQS_DP<7>")
	)
	(segment
		(start 331.531214 -286.715962)
		(end 331.539596 -286.720788)
		(width 0.09525)
		(layer "In4.Cu")
		(net "M_D_CPU0_SB_DQS_DP<7>")
	)
	(segment
		(start 328.327766 -286.729424)
		(end 328.342498 -286.720788)
		(width 0.09525)
		(layer "In4.Cu")
		(net "M_D_CPU0_SB_DQS_DP<7>")
	)
	(segment
		(start 297.165776 -305.562)
		(end 298.257976 -304.832258)
		(width 0.16002)
		(layer "In4.Cu")
		(net "M_D_CPU0_SB_DQS_DP<7>")
	)
	(segment
		(start 290.32708 -305.198526)
		(end 290.718748 -304.806858)
		(width 0.16002)
		(layer "In4.Cu")
		(net "M_D_CPU0_SB_DQS_DP<7>")
	)
	(segment
		(start 332.471268 -286.715962)
		(end 332.47965 -286.720788)
		(width 0.09525)
		(layer "In4.Cu")
		(net "M_D_CPU0_SB_DQS_DP<7>")
	)
	(segment
		(start 326.839326 -286.721042)
		(end 326.844914 -286.724344)
		(width 0.09525)
		(layer "In4.Cu")
		(net "M_D_CPU0_SB_DQS_DP<7>")
	)
	(segment
		(start 290.718748 -304.806858)
		(end 291.065204 -304.806858)
		(width 0.16002)
		(layer "In4.Cu")
		(net "M_D_CPU0_SB_DQS_DP<7>")
	)
	(segment
		(start 340.496398 -286.753808)
		(end 340.597236 -286.780478)
		(width 0.09525)
		(layer "In4.Cu")
		(net "M_D_CPU0_SB_DQS_DP<7>")
	)
	(segment
		(start 298.257976 -304.832258)
		(end 298.634404 -304.832258)
		(width 0.16002)
		(layer "In4.Cu")
		(net "M_D_CPU0_SB_DQS_DP<7>")
	)
	(segment
		(start 308.468522 -304.34407)
		(end 309.395876 -303.959768)
		(width 0.16002)
		(layer "In4.Cu")
		(net "M_D_CPU0_SB_DQS_DP<7>")
	)
	(segment
		(start 283.049218 -304.783744)
		(end 283.503878 -304.783744)
		(width 0.16002)
		(layer "In4.Cu")
		(net "M_D_CPU0_SB_DQS_DP<7>")
	)
	(segment
		(start 305.717448 -304.891186)
		(end 308.468522 -304.34407)
		(width 0.16002)
		(layer "In4.Cu")
		(net "M_D_CPU0_SB_DQS_DP<7>")
	)
	(segment
		(start 340.597236 -286.780478)
		(end 340.75116 -287.045908)
		(width 0.09525)
		(layer "In4.Cu")
		(net "M_D_CPU0_SB_DQS_DP<7>")
	)
	(segment
		(start 280.635964 -305.28514)
		(end 280.909776 -305.011328)
		(width 0.16002)
		(layer "In4.Cu")
		(net "M_D_CPU0_SB_DQS_DP<7>")
	)
	(segment
		(start 284.54477 -305.176682)
		(end 285.172404 -305.436524)
		(width 0.16002)
		(layer "In4.Cu")
		(net "M_D_CPU0_SB_DQS_DP<7>")
	)
	(segment
		(start 299.426122 -305.160172)
		(end 300.7868 -305.160172)
		(width 0.16002)
		(layer "In4.Cu")
		(net "M_D_CPU0_SB_DQS_DP<7>")
	)
	(arc
		(start 335.299558 -286.720788)
		(mid 335.58099 -286.796577)
		(end 335.862422 -286.720788)
		(width 0.09525)
		(layer "In4.Cu")
		(net "M_D_CPU0_SB_DQS_DP<7>")
	)
	(arc
		(start 332.47965 -286.720788)
		(mid 332.761082 -286.796577)
		(end 333.042514 -286.720788)
		(width 0.09525)
		(layer "In4.Cu")
		(net "M_D_CPU0_SB_DQS_DP<7>")
	)
	(arc
		(start 336.802476 -286.720788)
		(mid 336.986251 -286.670016)
		(end 337.171284 -286.715962)
		(width 0.09525)
		(layer "In4.Cu")
		(net "M_D_CPU0_SB_DQS_DP<7>")
	)
	(arc
		(start 339.059774 -286.720788)
		(mid 339.341206 -286.796577)
		(end 339.622638 -286.720788)
		(width 0.09525)
		(layer "In4.Cu")
		(net "M_D_CPU0_SB_DQS_DP<7>")
	)
	(arc
		(start 331.162406 -286.720788)
		(mid 331.346181 -286.670016)
		(end 331.531214 -286.715962)
		(width 0.09525)
		(layer "In4.Cu")
		(net "M_D_CPU0_SB_DQS_DP<7>")
	)
	(arc
		(start 329.659742 -286.720788)
		(mid 329.941174 -286.796577)
		(end 330.222606 -286.720788)
		(width 0.09525)
		(layer "In4.Cu")
		(net "M_D_CPU0_SB_DQS_DP<7>")
	)
	(arc
		(start 328.342498 -286.720788)
		(mid 328.526273 -286.670016)
		(end 328.711306 -286.715962)
		(width 0.09525)
		(layer "In4.Cu")
		(net "M_D_CPU0_SB_DQS_DP<7>")
	)
	(arc
		(start 334.359758 -286.720788)
		(mid 334.64119 -286.796577)
		(end 334.922622 -286.720788)
		(width 0.09525)
		(layer "In4.Cu")
		(net "M_D_CPU0_SB_DQS_DP<7>")
	)
	(arc
		(start 333.99095 -286.715962)
		(mid 334.175982 -286.670048)
		(end 334.359758 -286.720788)
		(width 0.09525)
		(layer "In4.Cu")
		(net "M_D_CPU0_SB_DQS_DP<7>")
	)
	(arc
		(start 330.599542 -286.720788)
		(mid 330.880974 -286.796577)
		(end 331.162406 -286.720788)
		(width 0.09525)
		(layer "In4.Cu")
		(net "M_D_CPU0_SB_DQS_DP<7>")
	)
	(arc
		(start 327.41362 -286.71393)
		(mid 327.597255 -286.66998)
		(end 327.779126 -286.720788)
		(width 0.09525)
		(layer "In4.Cu")
		(net "M_D_CPU0_SB_DQS_DP<7>")
	)
	(arc
		(start 327.779126 -286.720788)
		(mid 328.052308 -286.796764)
		(end 328.327766 -286.729424)
		(width 0.09525)
		(layer "In4.Cu")
		(net "M_D_CPU0_SB_DQS_DP<7>")
	)
	(arc
		(start 332.10246 -286.720788)
		(mid 332.286235 -286.670016)
		(end 332.471268 -286.715962)
		(width 0.09525)
		(layer "In4.Cu")
		(net "M_D_CPU0_SB_DQS_DP<7>")
	)
	(arc
		(start 328.719688 -286.720788)
		(mid 329.00112 -286.796577)
		(end 329.282552 -286.720788)
		(width 0.09525)
		(layer "In4.Cu")
		(net "M_D_CPU0_SB_DQS_DP<7>")
	)
	(arc
		(start 340.475824 -286.761936)
		(mid 340.486151 -286.757974)
		(end 340.496398 -286.753808)
		(width 0.09525)
		(layer "In4.Cu")
		(net "M_D_CPU0_SB_DQS_DP<7>")
	)
	(arc
		(start 337.179666 -286.720788)
		(mid 337.461098 -286.796577)
		(end 337.74253 -286.720788)
		(width 0.09525)
		(layer "In4.Cu")
		(net "M_D_CPU0_SB_DQS_DP<7>")
	)
	(arc
		(start 331.539596 -286.720788)
		(mid 331.821028 -286.796577)
		(end 332.10246 -286.720788)
		(width 0.09525)
		(layer "In4.Cu")
		(net "M_D_CPU0_SB_DQS_DP<7>")
	)
	(arc
		(start 326.180196 -286.796988)
		(mid 326.326219 -286.777576)
		(end 326.462136 -286.720788)
		(width 0.09525)
		(layer "In4.Cu")
		(net "M_D_CPU0_SB_DQS_DP<7>")
	)
	(arc
		(start 337.750912 -286.715962)
		(mid 337.935944 -286.670048)
		(end 338.11972 -286.720788)
		(width 0.09525)
		(layer "In4.Cu")
		(net "M_D_CPU0_SB_DQS_DP<7>")
	)
	(arc
		(start 326.462136 -286.720788)
		(mid 326.640288 -286.670132)
		(end 326.821038 -286.710628)
		(width 0.09525)
		(layer "In4.Cu")
		(net "M_D_CPU0_SB_DQS_DP<7>")
	)
	(arc
		(start 329.290934 -286.715962)
		(mid 329.475966 -286.670048)
		(end 329.659742 -286.720788)
		(width 0.09525)
		(layer "In4.Cu")
		(net "M_D_CPU0_SB_DQS_DP<7>")
	)
	(arc
		(start 335.862422 -286.720788)
		(mid 336.046197 -286.670016)
		(end 336.23123 -286.715962)
		(width 0.09525)
		(layer "In4.Cu")
		(net "M_D_CPU0_SB_DQS_DP<7>")
	)
	(arc
		(start 330.222606 -286.720788)
		(mid 330.411074 -286.670111)
		(end 330.599542 -286.720788)
		(width 0.09525)
		(layer "In4.Cu")
		(net "M_D_CPU0_SB_DQS_DP<7>")
	)
	(arc
		(start 338.690966 -286.715962)
		(mid 338.875998 -286.670048)
		(end 339.059774 -286.720788)
		(width 0.09525)
		(layer "In4.Cu")
		(net "M_D_CPU0_SB_DQS_DP<7>")
	)
	(arc
		(start 334.922622 -286.720788)
		(mid 335.11109 -286.670111)
		(end 335.299558 -286.720788)
		(width 0.09525)
		(layer "In4.Cu")
		(net "M_D_CPU0_SB_DQS_DP<7>")
	)
	(arc
		(start 333.050896 -286.715962)
		(mid 333.235928 -286.670048)
		(end 333.419704 -286.720788)
		(width 0.09525)
		(layer "In4.Cu")
		(net "M_D_CPU0_SB_DQS_DP<7>")
	)
	(arc
		(start 336.239612 -286.720788)
		(mid 336.521044 -286.796577)
		(end 336.802476 -286.720788)
		(width 0.09525)
		(layer "In4.Cu")
		(net "M_D_CPU0_SB_DQS_DP<7>")
	)
	(arc
		(start 339.622638 -286.720788)
		(mid 339.811106 -286.670111)
		(end 339.999574 -286.720788)
		(width 0.09525)
		(layer "In4.Cu")
		(net "M_D_CPU0_SB_DQS_DP<7>")
	)
	(arc
		(start 339.999574 -286.720788)
		(mid 340.233087 -286.794665)
		(end 340.475824 -286.761936)
		(width 0.09525)
		(layer "In4.Cu")
		(net "M_D_CPU0_SB_DQS_DP<7>")
	)
	(arc
		(start 326.844914 -286.724344)
		(mid 327.123779 -286.796625)
		(end 327.401682 -286.720788)
		(width 0.09525)
		(layer "In4.Cu")
		(net "M_D_CPU0_SB_DQS_DP<7>")
	)
	(arc
		(start 338.11972 -286.720788)
		(mid 338.401152 -286.796577)
		(end 338.682584 -286.720788)
		(width 0.09525)
		(layer "In4.Cu")
		(net "M_D_CPU0_SB_DQS_DP<7>")
	)
	(arc
		(start 333.419704 -286.720788)
		(mid 333.701136 -286.796577)
		(end 333.982568 -286.720788)
		(width 0.09525)
		(layer "In4.Cu")
		(net "M_D_CPU0_SB_DQS_DP<7>")
	)
	(segment
		(start 341.218012 -281.920188)
		(end 340.75116 -282.186126)
		(width 0.12954)
		(layer "F.Cu")
		(net "M_D_CPU0_SB_DQS_DP<6>")
	)
	(segment
		(start 304.97907 -296.27957)
		(end 305.776376 -295.482264)
		(width 0.16002)
		(layer "In4.Cu")
		(net "M_D_CPU0_SB_DQS_DP<6>")
	)
	(segment
		(start 336.23123 -281.85618)
		(end 336.239612 -281.861006)
		(width 0.09525)
		(layer "In4.Cu")
		(net "M_D_CPU0_SB_DQS_DP<6>")
	)
	(segment
		(start 328.711306 -281.85618)
		(end 328.719688 -281.861006)
		(width 0.09525)
		(layer "In4.Cu")
		(net "M_D_CPU0_SB_DQS_DP<6>")
	)
	(segment
		(start 324.454012 -281.915362)
		(end 324.641972 -281.727402)
		(width 0.09525)
		(layer "In4.Cu")
		(net "M_D_CPU0_SB_DQS_DP<6>")
	)
	(segment
		(start 293.791894 -295.810178)
		(end 294.087804 -296.106088)
		(width 0.16002)
		(layer "In4.Cu")
		(net "M_D_CPU0_SB_DQS_DP<6>")
	)
	(segment
		(start 328.335894 -281.864308)
		(end 328.342498 -281.861006)
		(width 0.09525)
		(layer "In4.Cu")
		(net "M_D_CPU0_SB_DQS_DP<6>")
	)
	(segment
		(start 283.611828 -295.47947)
		(end 286.462978 -296.660316)
		(width 0.16002)
		(layer "In4.Cu")
		(net "M_D_CPU0_SB_DQS_DP<6>")
	)
	(segment
		(start 298.301664 -295.482264)
		(end 298.76496 -295.482264)
		(width 0.16002)
		(layer "In4.Cu")
		(net "M_D_CPU0_SB_DQS_DP<6>")
	)
	(segment
		(start 324.641972 -281.727402)
		(end 327.28535 -281.727402)
		(width 0.09525)
		(layer "In4.Cu")
		(net "M_D_CPU0_SB_DQS_DP<6>")
	)
	(segment
		(start 288.590228 -296.660316)
		(end 289.619944 -296.234104)
		(width 0.16002)
		(layer "In4.Cu")
		(net "M_D_CPU0_SB_DQS_DP<6>")
	)
	(segment
		(start 295.425622 -296.660316)
		(end 296.023792 -296.660316)
		(width 0.16002)
		(layer "In4.Cu")
		(net "M_D_CPU0_SB_DQS_DP<6>")
	)
	(segment
		(start 323.919596 -281.97429)
		(end 323.978524 -281.915362)
		(width 0.09525)
		(layer "In4.Cu")
		(net "M_D_CPU0_SB_DQS_DP<6>")
	)
	(segment
		(start 281.318462 -295.661334)
		(end 282.193492 -295.47947)
		(width 0.16002)
		(layer "In4.Cu")
		(net "M_D_CPU0_SB_DQS_DP<6>")
	)
	(segment
		(start 305.776376 -295.482264)
		(end 308.54777 -295.482264)
		(width 0.16002)
		(layer "In4.Cu")
		(net "M_D_CPU0_SB_DQS_DP<6>")
	)
	(segment
		(start 308.54777 -295.482264)
		(end 322.055744 -281.97429)
		(width 0.16002)
		(layer "In4.Cu")
		(net "M_D_CPU0_SB_DQS_DP<6>")
	)
	(segment
		(start 301.365158 -296.27957)
		(end 304.97907 -296.27957)
		(width 0.16002)
		(layer "In4.Cu")
		(net "M_D_CPU0_SB_DQS_DP<6>")
	)
	(segment
		(start 294.087804 -296.106088)
		(end 295.425622 -296.660316)
		(width 0.16002)
		(layer "In4.Cu")
		(net "M_D_CPU0_SB_DQS_DP<6>")
	)
	(segment
		(start 286.462978 -296.660316)
		(end 288.590228 -296.660316)
		(width 0.16002)
		(layer "In4.Cu")
		(net "M_D_CPU0_SB_DQS_DP<6>")
	)
	(segment
		(start 291.753544 -295.810178)
		(end 293.791894 -295.810178)
		(width 0.16002)
		(layer "In4.Cu")
		(net "M_D_CPU0_SB_DQS_DP<6>")
	)
	(segment
		(start 323.978524 -281.915362)
		(end 324.454012 -281.915362)
		(width 0.09525)
		(layer "In4.Cu")
		(net "M_D_CPU0_SB_DQS_DP<6>")
	)
	(segment
		(start 282.193492 -295.47947)
		(end 283.611828 -295.47947)
		(width 0.16002)
		(layer "In4.Cu")
		(net "M_D_CPU0_SB_DQS_DP<6>")
	)
	(segment
		(start 299.489368 -295.810178)
		(end 300.895766 -295.810178)
		(width 0.16002)
		(layer "In4.Cu")
		(net "M_D_CPU0_SB_DQS_DP<6>")
	)
	(segment
		(start 300.895766 -295.810178)
		(end 301.365158 -296.27957)
		(width 0.16002)
		(layer "In4.Cu")
		(net "M_D_CPU0_SB_DQS_DP<6>")
	)
	(segment
		(start 333.042514 -281.861006)
		(end 333.050896 -281.85618)
		(width 0.09525)
		(layer "In4.Cu")
		(net "M_D_CPU0_SB_DQS_DP<6>")
	)
	(segment
		(start 297.377358 -296.099738)
		(end 298.301664 -295.482264)
		(width 0.16002)
		(layer "In4.Cu")
		(net "M_D_CPU0_SB_DQS_DP<6>")
	)
	(segment
		(start 290.990528 -295.494456)
		(end 291.753544 -295.810178)
		(width 0.16002)
		(layer "In4.Cu")
		(net "M_D_CPU0_SB_DQS_DP<6>")
	)
	(segment
		(start 322.055744 -281.97429)
		(end 323.895974 -281.97429)
		(width 0.16002)
		(layer "In4.Cu")
		(net "M_D_CPU0_SB_DQS_DP<6>")
	)
	(segment
		(start 337.74253 -281.861006)
		(end 337.750912 -281.85618)
		(width 0.09525)
		(layer "In4.Cu")
		(net "M_D_CPU0_SB_DQS_DP<6>")
	)
	(segment
		(start 296.023792 -296.660316)
		(end 297.377358 -296.099738)
		(width 0.16002)
		(layer "In4.Cu")
		(net "M_D_CPU0_SB_DQS_DP<6>")
	)
	(segment
		(start 328.330814 -281.867102)
		(end 328.335894 -281.864308)
		(width 0.09525)
		(layer "In4.Cu")
		(net "M_D_CPU0_SB_DQS_DP<6>")
	)
	(segment
		(start 280.909776 -295.661334)
		(end 281.318462 -295.661334)
		(width 0.16002)
		(layer "In4.Cu")
		(net "M_D_CPU0_SB_DQS_DP<6>")
	)
	(segment
		(start 290.72332 -295.494456)
		(end 290.990528 -295.494456)
		(width 0.16002)
		(layer "In4.Cu")
		(net "M_D_CPU0_SB_DQS_DP<6>")
	)
	(segment
		(start 337.171284 -281.85618)
		(end 337.179666 -281.861006)
		(width 0.09525)
		(layer "In4.Cu")
		(net "M_D_CPU0_SB_DQS_DP<6>")
	)
	(segment
		(start 331.531214 -281.85618)
		(end 331.539596 -281.861006)
		(width 0.09525)
		(layer "In4.Cu")
		(net "M_D_CPU0_SB_DQS_DP<6>")
	)
	(segment
		(start 298.76496 -295.482264)
		(end 299.489368 -295.810178)
		(width 0.16002)
		(layer "In4.Cu")
		(net "M_D_CPU0_SB_DQS_DP<6>")
	)
	(segment
		(start 338.682584 -281.861006)
		(end 338.690966 -281.85618)
		(width 0.09525)
		(layer "In4.Cu")
		(net "M_D_CPU0_SB_DQS_DP<6>")
	)
	(segment
		(start 332.471268 -281.85618)
		(end 332.47965 -281.861006)
		(width 0.09525)
		(layer "In4.Cu")
		(net "M_D_CPU0_SB_DQS_DP<6>")
	)
	(segment
		(start 333.982568 -281.861006)
		(end 333.99095 -281.85618)
		(width 0.09525)
		(layer "In4.Cu")
		(net "M_D_CPU0_SB_DQS_DP<6>")
	)
	(segment
		(start 323.895974 -281.97429)
		(end 323.919596 -281.97429)
		(width 0.09525)
		(layer "In4.Cu")
		(net "M_D_CPU0_SB_DQS_DP<6>")
	)
	(segment
		(start 329.282552 -281.861006)
		(end 329.290934 -281.85618)
		(width 0.09525)
		(layer "In4.Cu")
		(net "M_D_CPU0_SB_DQS_DP<6>")
	)
	(segment
		(start 280.635964 -295.935146)
		(end 280.909776 -295.661334)
		(width 0.16002)
		(layer "In4.Cu")
		(net "M_D_CPU0_SB_DQS_DP<6>")
	)
	(segment
		(start 340.597236 -281.920696)
		(end 340.75116 -282.186126)
		(width 0.09525)
		(layer "In4.Cu")
		(net "M_D_CPU0_SB_DQS_DP<6>")
	)
	(segment
		(start 289.619944 -296.234104)
		(end 290.72332 -295.494456)
		(width 0.16002)
		(layer "In4.Cu")
		(net "M_D_CPU0_SB_DQS_DP<6>")
	)
	(segment
		(start 340.496398 -281.894026)
		(end 340.597236 -281.920696)
		(width 0.09525)
		(layer "In4.Cu")
		(net "M_D_CPU0_SB_DQS_DP<6>")
	)
	(arc
		(start 340.475824 -281.902154)
		(mid 340.486152 -281.898194)
		(end 340.496398 -281.894026)
		(width 0.09525)
		(layer "In4.Cu")
		(net "M_D_CPU0_SB_DQS_DP<6>")
	)
	(arc
		(start 337.179666 -281.861006)
		(mid 337.461098 -281.936761)
		(end 337.74253 -281.861006)
		(width 0.09525)
		(layer "In4.Cu")
		(net "M_D_CPU0_SB_DQS_DP<6>")
	)
	(arc
		(start 336.802476 -281.861006)
		(mid 336.986251 -281.810234)
		(end 337.171284 -281.85618)
		(width 0.09525)
		(layer "In4.Cu")
		(net "M_D_CPU0_SB_DQS_DP<6>")
	)
	(arc
		(start 330.599542 -281.861006)
		(mid 330.880974 -281.936761)
		(end 331.162406 -281.861006)
		(width 0.09525)
		(layer "In4.Cu")
		(net "M_D_CPU0_SB_DQS_DP<6>")
	)
	(arc
		(start 335.862422 -281.861006)
		(mid 336.046197 -281.810234)
		(end 336.23123 -281.85618)
		(width 0.09525)
		(layer "In4.Cu")
		(net "M_D_CPU0_SB_DQS_DP<6>")
	)
	(arc
		(start 338.690966 -281.85618)
		(mid 338.875998 -281.810266)
		(end 339.059774 -281.861006)
		(width 0.09525)
		(layer "In4.Cu")
		(net "M_D_CPU0_SB_DQS_DP<6>")
	)
	(arc
		(start 334.359758 -281.861006)
		(mid 334.64119 -281.936761)
		(end 334.922622 -281.861006)
		(width 0.09525)
		(layer "In4.Cu")
		(net "M_D_CPU0_SB_DQS_DP<6>")
	)
	(arc
		(start 333.050896 -281.85618)
		(mid 333.235928 -281.810266)
		(end 333.419704 -281.861006)
		(width 0.09525)
		(layer "In4.Cu")
		(net "M_D_CPU0_SB_DQS_DP<6>")
	)
	(arc
		(start 339.999574 -281.861006)
		(mid 340.233088 -281.934849)
		(end 340.475824 -281.902154)
		(width 0.09525)
		(layer "In4.Cu")
		(net "M_D_CPU0_SB_DQS_DP<6>")
	)
	(arc
		(start 336.239612 -281.861006)
		(mid 336.521044 -281.936761)
		(end 336.802476 -281.861006)
		(width 0.09525)
		(layer "In4.Cu")
		(net "M_D_CPU0_SB_DQS_DP<6>")
	)
	(arc
		(start 338.11972 -281.861006)
		(mid 338.401152 -281.936761)
		(end 338.682584 -281.861006)
		(width 0.09525)
		(layer "In4.Cu")
		(net "M_D_CPU0_SB_DQS_DP<6>")
	)
	(arc
		(start 330.222606 -281.861006)
		(mid 330.411074 -281.810329)
		(end 330.599542 -281.861006)
		(width 0.09525)
		(layer "In4.Cu")
		(net "M_D_CPU0_SB_DQS_DP<6>")
	)
	(arc
		(start 333.419704 -281.861006)
		(mid 333.701136 -281.936761)
		(end 333.982568 -281.861006)
		(width 0.09525)
		(layer "In4.Cu")
		(net "M_D_CPU0_SB_DQS_DP<6>")
	)
	(arc
		(start 333.99095 -281.85618)
		(mid 334.175982 -281.810266)
		(end 334.359758 -281.861006)
		(width 0.09525)
		(layer "In4.Cu")
		(net "M_D_CPU0_SB_DQS_DP<6>")
	)
	(arc
		(start 339.622638 -281.861006)
		(mid 339.811106 -281.810329)
		(end 339.999574 -281.861006)
		(width 0.09525)
		(layer "In4.Cu")
		(net "M_D_CPU0_SB_DQS_DP<6>")
	)
	(arc
		(start 331.162406 -281.861006)
		(mid 331.346181 -281.810234)
		(end 331.531214 -281.85618)
		(width 0.09525)
		(layer "In4.Cu")
		(net "M_D_CPU0_SB_DQS_DP<6>")
	)
	(arc
		(start 337.750912 -281.85618)
		(mid 337.935944 -281.810266)
		(end 338.11972 -281.861006)
		(width 0.09525)
		(layer "In4.Cu")
		(net "M_D_CPU0_SB_DQS_DP<6>")
	)
	(arc
		(start 334.922622 -281.861006)
		(mid 335.11109 -281.810329)
		(end 335.299558 -281.861006)
		(width 0.09525)
		(layer "In4.Cu")
		(net "M_D_CPU0_SB_DQS_DP<6>")
	)
	(arc
		(start 331.539596 -281.861006)
		(mid 331.821028 -281.936761)
		(end 332.10246 -281.861006)
		(width 0.09525)
		(layer "In4.Cu")
		(net "M_D_CPU0_SB_DQS_DP<6>")
	)
	(arc
		(start 335.299558 -281.861006)
		(mid 335.58099 -281.936761)
		(end 335.862422 -281.861006)
		(width 0.09525)
		(layer "In4.Cu")
		(net "M_D_CPU0_SB_DQS_DP<6>")
	)
	(arc
		(start 327.28535 -281.727402)
		(mid 327.54118 -281.761405)
		(end 327.77938 -281.860752)
		(width 0.09525)
		(layer "In4.Cu")
		(net "M_D_CPU0_SB_DQS_DP<6>")
	)
	(arc
		(start 329.659742 -281.861006)
		(mid 329.941174 -281.936761)
		(end 330.222606 -281.861006)
		(width 0.09525)
		(layer "In4.Cu")
		(net "M_D_CPU0_SB_DQS_DP<6>")
	)
	(arc
		(start 329.290934 -281.85618)
		(mid 329.475966 -281.810266)
		(end 329.659742 -281.861006)
		(width 0.09525)
		(layer "In4.Cu")
		(net "M_D_CPU0_SB_DQS_DP<6>")
	)
	(arc
		(start 328.342498 -281.861006)
		(mid 328.526273 -281.810234)
		(end 328.711306 -281.85618)
		(width 0.09525)
		(layer "In4.Cu")
		(net "M_D_CPU0_SB_DQS_DP<6>")
	)
	(arc
		(start 328.719688 -281.861006)
		(mid 329.00112 -281.936761)
		(end 329.282552 -281.861006)
		(width 0.09525)
		(layer "In4.Cu")
		(net "M_D_CPU0_SB_DQS_DP<6>")
	)
	(arc
		(start 332.47965 -281.861006)
		(mid 332.761082 -281.936761)
		(end 333.042514 -281.861006)
		(width 0.09525)
		(layer "In4.Cu")
		(net "M_D_CPU0_SB_DQS_DP<6>")
	)
	(arc
		(start 332.10246 -281.861006)
		(mid 332.286235 -281.810234)
		(end 332.471268 -281.85618)
		(width 0.09525)
		(layer "In4.Cu")
		(net "M_D_CPU0_SB_DQS_DP<6>")
	)
	(arc
		(start 339.059774 -281.861006)
		(mid 339.341206 -281.936761)
		(end 339.622638 -281.861006)
		(width 0.09525)
		(layer "In4.Cu")
		(net "M_D_CPU0_SB_DQS_DP<6>")
	)
	(arc
		(start 327.77938 -281.860752)
		(mid 328.054274 -281.936503)
		(end 328.330814 -281.867102)
		(width 0.09525)
		(layer "In4.Cu")
		(net "M_D_CPU0_SB_DQS_DP<6>")
	)
	(segment
		(start 341.218012 -277.060152)
		(end 340.75116 -277.32609)
		(width 0.12954)
		(layer "F.Cu")
		(net "M_D_CPU0_SB_DQS_DP<5>")
	)
	(segment
		(start 329.282552 -277.00097)
		(end 329.290934 -276.996144)
		(width 0.09525)
		(layer "In4.Cu")
		(net "M_D_CPU0_SB_DQS_DP<5>")
	)
	(segment
		(start 332.471268 -276.996144)
		(end 332.47965 -277.00097)
		(width 0.09525)
		(layer "In4.Cu")
		(net "M_D_CPU0_SB_DQS_DP<5>")
	)
	(segment
		(start 287.842198 -287.310322)
		(end 288.517076 -287.310322)
		(width 0.16002)
		(layer "In4.Cu")
		(net "M_D_CPU0_SB_DQS_DP<5>")
	)
	(segment
		(start 301.390304 -286.93237)
		(end 304.976276 -286.93237)
		(width 0.16002)
		(layer "In4.Cu")
		(net "M_D_CPU0_SB_DQS_DP<5>")
	)
	(segment
		(start 328.327766 -277.009606)
		(end 328.342498 -277.00097)
		(width 0.09525)
		(layer "In4.Cu")
		(net "M_D_CPU0_SB_DQS_DP<5>")
	)
	(segment
		(start 288.517076 -287.310322)
		(end 290.213796 -286.60725)
		(width 0.16002)
		(layer "In4.Cu")
		(net "M_D_CPU0_SB_DQS_DP<5>")
	)
	(segment
		(start 340.597236 -277.06066)
		(end 340.75116 -277.32609)
		(width 0.09525)
		(layer "In4.Cu")
		(net "M_D_CPU0_SB_DQS_DP<5>")
	)
	(segment
		(start 281.829256 -286.31134)
		(end 282.941776 -286.08147)
		(width 0.16002)
		(layer "In4.Cu")
		(net "M_D_CPU0_SB_DQS_DP<5>")
	)
	(segment
		(start 305.776376 -286.13227)
		(end 308.258972 -286.13227)
		(width 0.16002)
		(layer "In4.Cu")
		(net "M_D_CPU0_SB_DQS_DP<5>")
	)
	(segment
		(start 290.213796 -286.60725)
		(end 290.714176 -286.10687)
		(width 0.16002)
		(layer "In4.Cu")
		(net "M_D_CPU0_SB_DQS_DP<5>")
	)
	(segment
		(start 280.909776 -286.31134)
		(end 281.829256 -286.31134)
		(width 0.16002)
		(layer "In4.Cu")
		(net "M_D_CPU0_SB_DQS_DP<5>")
	)
	(segment
		(start 323.919596 -276.35073)
		(end 323.978524 -276.291802)
		(width 0.09525)
		(layer "In4.Cu")
		(net "M_D_CPU0_SB_DQS_DP<5>")
	)
	(segment
		(start 284.51683 -286.477456)
		(end 287.842198 -287.310322)
		(width 0.16002)
		(layer "In4.Cu")
		(net "M_D_CPU0_SB_DQS_DP<5>")
	)
	(segment
		(start 291.982144 -286.460184)
		(end 293.187374 -286.460184)
		(width 0.16002)
		(layer "In4.Cu")
		(net "M_D_CPU0_SB_DQS_DP<5>")
	)
	(segment
		(start 304.976276 -286.93237)
		(end 305.776376 -286.13227)
		(width 0.16002)
		(layer "In4.Cu")
		(net "M_D_CPU0_SB_DQS_DP<5>")
	)
	(segment
		(start 293.187374 -286.460184)
		(end 295.239948 -287.310322)
		(width 0.16002)
		(layer "In4.Cu")
		(net "M_D_CPU0_SB_DQS_DP<5>")
	)
	(segment
		(start 297.81627 -286.556704)
		(end 298.240704 -286.13227)
		(width 0.16002)
		(layer "In4.Cu")
		(net "M_D_CPU0_SB_DQS_DP<5>")
	)
	(segment
		(start 327.777602 -276.999446)
		(end 327.777348 -276.999954)
		(width 0.09525)
		(layer "In4.Cu")
		(net "M_D_CPU0_SB_DQS_DP<5>")
	)
	(segment
		(start 308.258972 -286.13227)
		(end 318.040512 -276.35073)
		(width 0.16002)
		(layer "In4.Cu")
		(net "M_D_CPU0_SB_DQS_DP<5>")
	)
	(segment
		(start 298.634404 -286.13227)
		(end 298.962318 -286.460184)
		(width 0.16002)
		(layer "In4.Cu")
		(net "M_D_CPU0_SB_DQS_DP<5>")
	)
	(segment
		(start 290.714176 -286.10687)
		(end 291.178996 -286.10687)
		(width 0.16002)
		(layer "In4.Cu")
		(net "M_D_CPU0_SB_DQS_DP<5>")
	)
	(segment
		(start 333.042514 -277.00097)
		(end 333.050896 -276.996144)
		(width 0.09525)
		(layer "In4.Cu")
		(net "M_D_CPU0_SB_DQS_DP<5>")
	)
	(segment
		(start 323.895974 -276.35073)
		(end 323.919596 -276.35073)
		(width 0.09525)
		(layer "In4.Cu")
		(net "M_D_CPU0_SB_DQS_DP<5>")
	)
	(segment
		(start 323.978524 -276.291802)
		(end 324.240398 -276.291802)
		(width 0.09525)
		(layer "In4.Cu")
		(net "M_D_CPU0_SB_DQS_DP<5>")
	)
	(segment
		(start 291.178996 -286.10687)
		(end 291.982144 -286.460184)
		(width 0.16002)
		(layer "In4.Cu")
		(net "M_D_CPU0_SB_DQS_DP<5>")
	)
	(segment
		(start 337.171284 -276.996144)
		(end 337.179666 -277.00097)
		(width 0.09525)
		(layer "In4.Cu")
		(net "M_D_CPU0_SB_DQS_DP<5>")
	)
	(segment
		(start 337.74253 -277.00097)
		(end 337.750912 -276.996144)
		(width 0.09525)
		(layer "In4.Cu")
		(net "M_D_CPU0_SB_DQS_DP<5>")
	)
	(segment
		(start 300.918118 -286.460184)
		(end 301.390304 -286.93237)
		(width 0.16002)
		(layer "In4.Cu")
		(net "M_D_CPU0_SB_DQS_DP<5>")
	)
	(segment
		(start 283.561028 -286.08147)
		(end 284.51683 -286.477456)
		(width 0.16002)
		(layer "In4.Cu")
		(net "M_D_CPU0_SB_DQS_DP<5>")
	)
	(segment
		(start 280.635964 -286.585152)
		(end 280.909776 -286.31134)
		(width 0.16002)
		(layer "In4.Cu")
		(net "M_D_CPU0_SB_DQS_DP<5>")
	)
	(segment
		(start 295.239948 -287.310322)
		(end 295.997122 -287.310322)
		(width 0.16002)
		(layer "In4.Cu")
		(net "M_D_CPU0_SB_DQS_DP<5>")
	)
	(segment
		(start 324.832218 -276.883622)
		(end 327.346056 -276.883622)
		(width 0.09525)
		(layer "In4.Cu")
		(net "M_D_CPU0_SB_DQS_DP<5>")
	)
	(segment
		(start 336.23123 -276.996144)
		(end 336.239612 -277.00097)
		(width 0.09525)
		(layer "In4.Cu")
		(net "M_D_CPU0_SB_DQS_DP<5>")
	)
	(segment
		(start 338.682584 -277.00097)
		(end 338.690966 -276.996144)
		(width 0.09525)
		(layer "In4.Cu")
		(net "M_D_CPU0_SB_DQS_DP<5>")
	)
	(segment
		(start 298.962318 -286.460184)
		(end 300.918118 -286.460184)
		(width 0.16002)
		(layer "In4.Cu")
		(net "M_D_CPU0_SB_DQS_DP<5>")
	)
	(segment
		(start 333.982568 -277.00097)
		(end 333.99095 -276.996144)
		(width 0.09525)
		(layer "In4.Cu")
		(net "M_D_CPU0_SB_DQS_DP<5>")
	)
	(segment
		(start 318.040512 -276.35073)
		(end 323.895974 -276.35073)
		(width 0.16002)
		(layer "In4.Cu")
		(net "M_D_CPU0_SB_DQS_DP<5>")
	)
	(segment
		(start 295.997122 -287.310322)
		(end 297.81627 -286.556704)
		(width 0.16002)
		(layer "In4.Cu")
		(net "M_D_CPU0_SB_DQS_DP<5>")
	)
	(segment
		(start 282.941776 -286.08147)
		(end 283.561028 -286.08147)
		(width 0.16002)
		(layer "In4.Cu")
		(net "M_D_CPU0_SB_DQS_DP<5>")
	)
	(segment
		(start 324.240398 -276.291802)
		(end 324.832218 -276.883622)
		(width 0.09525)
		(layer "In4.Cu")
		(net "M_D_CPU0_SB_DQS_DP<5>")
	)
	(segment
		(start 331.531214 -276.996144)
		(end 331.539596 -277.00097)
		(width 0.09525)
		(layer "In4.Cu")
		(net "M_D_CPU0_SB_DQS_DP<5>")
	)
	(segment
		(start 328.711306 -276.996144)
		(end 328.719688 -277.00097)
		(width 0.09525)
		(layer "In4.Cu")
		(net "M_D_CPU0_SB_DQS_DP<5>")
	)
	(segment
		(start 340.496398 -277.03399)
		(end 340.597236 -277.06066)
		(width 0.09525)
		(layer "In4.Cu")
		(net "M_D_CPU0_SB_DQS_DP<5>")
	)
	(segment
		(start 298.240704 -286.13227)
		(end 298.634404 -286.13227)
		(width 0.16002)
		(layer "In4.Cu")
		(net "M_D_CPU0_SB_DQS_DP<5>")
	)
	(arc
		(start 333.050896 -276.996144)
		(mid 333.235928 -276.95023)
		(end 333.419704 -277.00097)
		(width 0.09525)
		(layer "In4.Cu")
		(net "M_D_CPU0_SB_DQS_DP<5>")
	)
	(arc
		(start 334.922622 -277.00097)
		(mid 335.11109 -276.950293)
		(end 335.299558 -277.00097)
		(width 0.09525)
		(layer "In4.Cu")
		(net "M_D_CPU0_SB_DQS_DP<5>")
	)
	(arc
		(start 332.10246 -277.00097)
		(mid 332.286235 -276.950198)
		(end 332.471268 -276.996144)
		(width 0.09525)
		(layer "In4.Cu")
		(net "M_D_CPU0_SB_DQS_DP<5>")
	)
	(arc
		(start 335.312258 -277.008082)
		(mid 335.588268 -277.076643)
		(end 335.862422 -277.00097)
		(width 0.09525)
		(layer "In4.Cu")
		(net "M_D_CPU0_SB_DQS_DP<5>")
	)
	(arc
		(start 333.99095 -276.996144)
		(mid 334.175982 -276.95023)
		(end 334.359758 -277.00097)
		(width 0.09525)
		(layer "In4.Cu")
		(net "M_D_CPU0_SB_DQS_DP<5>")
	)
	(arc
		(start 334.359758 -277.00097)
		(mid 334.64119 -277.076725)
		(end 334.922622 -277.00097)
		(width 0.09525)
		(layer "In4.Cu")
		(net "M_D_CPU0_SB_DQS_DP<5>")
	)
	(arc
		(start 337.750912 -276.996144)
		(mid 337.935944 -276.95023)
		(end 338.11972 -277.00097)
		(width 0.09525)
		(layer "In4.Cu")
		(net "M_D_CPU0_SB_DQS_DP<5>")
	)
	(arc
		(start 337.179666 -277.00097)
		(mid 337.461098 -277.076725)
		(end 337.74253 -277.00097)
		(width 0.09525)
		(layer "In4.Cu")
		(net "M_D_CPU0_SB_DQS_DP<5>")
	)
	(arc
		(start 335.862422 -277.00097)
		(mid 336.046197 -276.950198)
		(end 336.23123 -276.996144)
		(width 0.09525)
		(layer "In4.Cu")
		(net "M_D_CPU0_SB_DQS_DP<5>")
	)
	(arc
		(start 338.11972 -277.00097)
		(mid 338.401152 -277.076725)
		(end 338.682584 -277.00097)
		(width 0.09525)
		(layer "In4.Cu")
		(net "M_D_CPU0_SB_DQS_DP<5>")
	)
	(arc
		(start 332.47965 -277.00097)
		(mid 332.761082 -277.076725)
		(end 333.042514 -277.00097)
		(width 0.09525)
		(layer "In4.Cu")
		(net "M_D_CPU0_SB_DQS_DP<5>")
	)
	(arc
		(start 331.55255 -277.008082)
		(mid 331.82845 -277.076644)
		(end 332.10246 -277.00097)
		(width 0.09525)
		(layer "In4.Cu")
		(net "M_D_CPU0_SB_DQS_DP<5>")
	)
	(arc
		(start 333.419704 -277.00097)
		(mid 333.701136 -277.076725)
		(end 333.982568 -277.00097)
		(width 0.09525)
		(layer "In4.Cu")
		(net "M_D_CPU0_SB_DQS_DP<5>")
	)
	(arc
		(start 331.162406 -277.00097)
		(mid 331.346181 -276.950198)
		(end 331.531214 -276.996144)
		(width 0.09525)
		(layer "In4.Cu")
		(net "M_D_CPU0_SB_DQS_DP<5>")
	)
	(arc
		(start 327.346056 -276.883622)
		(mid 327.569441 -276.913158)
		(end 327.777602 -276.999446)
		(width 0.09525)
		(layer "In4.Cu")
		(net "M_D_CPU0_SB_DQS_DP<5>")
	)
	(arc
		(start 339.622638 -277.00097)
		(mid 339.811106 -276.950293)
		(end 339.999574 -277.00097)
		(width 0.09525)
		(layer "In4.Cu")
		(net "M_D_CPU0_SB_DQS_DP<5>")
	)
	(arc
		(start 330.612242 -277.008082)
		(mid 330.888252 -277.076643)
		(end 331.162406 -277.00097)
		(width 0.09525)
		(layer "In4.Cu")
		(net "M_D_CPU0_SB_DQS_DP<5>")
	)
	(arc
		(start 331.539596 -277.00097)
		(mid 331.546049 -277.00457)
		(end 331.55255 -277.008082)
		(width 0.09525)
		(layer "In4.Cu")
		(net "M_D_CPU0_SB_DQS_DP<5>")
	)
	(arc
		(start 329.290934 -276.996144)
		(mid 329.475966 -276.95023)
		(end 329.659742 -277.00097)
		(width 0.09525)
		(layer "In4.Cu")
		(net "M_D_CPU0_SB_DQS_DP<5>")
	)
	(arc
		(start 328.719688 -277.00097)
		(mid 329.00112 -277.076725)
		(end 329.282552 -277.00097)
		(width 0.09525)
		(layer "In4.Cu")
		(net "M_D_CPU0_SB_DQS_DP<5>")
	)
	(arc
		(start 328.342498 -277.00097)
		(mid 328.526273 -276.950198)
		(end 328.711306 -276.996144)
		(width 0.09525)
		(layer "In4.Cu")
		(net "M_D_CPU0_SB_DQS_DP<5>")
	)
	(arc
		(start 339.059774 -277.00097)
		(mid 339.341206 -277.076725)
		(end 339.622638 -277.00097)
		(width 0.09525)
		(layer "In4.Cu")
		(net "M_D_CPU0_SB_DQS_DP<5>")
	)
	(arc
		(start 336.252566 -277.008082)
		(mid 336.528466 -277.076644)
		(end 336.802476 -277.00097)
		(width 0.09525)
		(layer "In4.Cu")
		(net "M_D_CPU0_SB_DQS_DP<5>")
	)
	(arc
		(start 336.802476 -277.00097)
		(mid 336.986251 -276.950198)
		(end 337.171284 -276.996144)
		(width 0.09525)
		(layer "In4.Cu")
		(net "M_D_CPU0_SB_DQS_DP<5>")
	)
	(arc
		(start 330.222606 -277.00097)
		(mid 330.411074 -276.950293)
		(end 330.599542 -277.00097)
		(width 0.09525)
		(layer "In4.Cu")
		(net "M_D_CPU0_SB_DQS_DP<5>")
	)
	(arc
		(start 339.999574 -277.00097)
		(mid 340.233088 -277.074813)
		(end 340.475824 -277.042118)
		(width 0.09525)
		(layer "In4.Cu")
		(net "M_D_CPU0_SB_DQS_DP<5>")
	)
	(arc
		(start 327.779126 -277.00097)
		(mid 328.052308 -277.076912)
		(end 328.327766 -277.009606)
		(width 0.09525)
		(layer "In4.Cu")
		(net "M_D_CPU0_SB_DQS_DP<5>")
	)
	(arc
		(start 335.299558 -277.00097)
		(mid 335.305886 -277.004566)
		(end 335.312258 -277.008082)
		(width 0.09525)
		(layer "In4.Cu")
		(net "M_D_CPU0_SB_DQS_DP<5>")
	)
	(arc
		(start 338.690966 -276.996144)
		(mid 338.875998 -276.95023)
		(end 339.059774 -277.00097)
		(width 0.09525)
		(layer "In4.Cu")
		(net "M_D_CPU0_SB_DQS_DP<5>")
	)
	(arc
		(start 340.475824 -277.042118)
		(mid 340.486152 -277.038158)
		(end 340.496398 -277.03399)
		(width 0.09525)
		(layer "In4.Cu")
		(net "M_D_CPU0_SB_DQS_DP<5>")
	)
	(arc
		(start 327.777348 -276.999954)
		(mid 327.778238 -277.000461)
		(end 327.779126 -277.00097)
		(width 0.09525)
		(layer "In4.Cu")
		(net "M_D_CPU0_SB_DQS_DP<5>")
	)
	(arc
		(start 329.659742 -277.00097)
		(mid 329.941174 -277.076725)
		(end 330.222606 -277.00097)
		(width 0.09525)
		(layer "In4.Cu")
		(net "M_D_CPU0_SB_DQS_DP<5>")
	)
	(arc
		(start 330.599542 -277.00097)
		(mid 330.60587 -277.004566)
		(end 330.612242 -277.008082)
		(width 0.09525)
		(layer "In4.Cu")
		(net "M_D_CPU0_SB_DQS_DP<5>")
	)
	(arc
		(start 336.239612 -277.00097)
		(mid 336.246065 -277.00457)
		(end 336.252566 -277.008082)
		(width 0.09525)
		(layer "In4.Cu")
		(net "M_D_CPU0_SB_DQS_DP<5>")
	)
	(segment
		(start 341.218012 -272.200116)
		(end 340.75116 -272.466054)
		(width 0.12954)
		(layer "F.Cu")
		(net "M_D_CPU0_SB_DQS_DP<4>")
	)
	(segment
		(start 325.235824 -270.879062)
		(end 326.446134 -272.089372)
		(width 0.09525)
		(layer "In4.Cu")
		(net "M_D_CPU0_SB_DQS_DP<4>")
	)
	(segment
		(start 328.711306 -272.136108)
		(end 328.719688 -272.140934)
		(width 0.09525)
		(layer "In4.Cu")
		(net "M_D_CPU0_SB_DQS_DP<4>")
	)
	(segment
		(start 293.525702 -277.11019)
		(end 294.37584 -277.960328)
		(width 0.16002)
		(layer "In4.Cu")
		(net "M_D_CPU0_SB_DQS_DP<4>")
	)
	(segment
		(start 282.138628 -276.746208)
		(end 283.507942 -276.746208)
		(width 0.16002)
		(layer "In4.Cu")
		(net "M_D_CPU0_SB_DQS_DP<4>")
	)
	(segment
		(start 301.754032 -277.58517)
		(end 304.984404 -277.58517)
		(width 0.16002)
		(layer "In4.Cu")
		(net "M_D_CPU0_SB_DQS_DP<4>")
	)
	(segment
		(start 338.682584 -272.140934)
		(end 338.690966 -272.136108)
		(width 0.09525)
		(layer "In4.Cu")
		(net "M_D_CPU0_SB_DQS_DP<4>")
	)
	(segment
		(start 283.507942 -276.746208)
		(end 283.84246 -277.080726)
		(width 0.16002)
		(layer "In4.Cu")
		(net "M_D_CPU0_SB_DQS_DP<4>")
	)
	(segment
		(start 323.895974 -270.72717)
		(end 323.919596 -270.72717)
		(width 0.09525)
		(layer "In4.Cu")
		(net "M_D_CPU0_SB_DQS_DP<4>")
	)
	(segment
		(start 324.156324 -270.668242)
		(end 324.367144 -270.879062)
		(width 0.09525)
		(layer "In4.Cu")
		(net "M_D_CPU0_SB_DQS_DP<4>")
	)
	(segment
		(start 328.327766 -272.14957)
		(end 328.342498 -272.140934)
		(width 0.09525)
		(layer "In4.Cu")
		(net "M_D_CPU0_SB_DQS_DP<4>")
	)
	(segment
		(start 289.393376 -277.62327)
		(end 289.858704 -277.62327)
		(width 0.16002)
		(layer "In4.Cu")
		(net "M_D_CPU0_SB_DQS_DP<4>")
	)
	(segment
		(start 340.597236 -272.200624)
		(end 340.75116 -272.466054)
		(width 0.09525)
		(layer "In4.Cu")
		(net "M_D_CPU0_SB_DQS_DP<4>")
	)
	(segment
		(start 323.978524 -270.668242)
		(end 324.156324 -270.668242)
		(width 0.09525)
		(layer "In4.Cu")
		(net "M_D_CPU0_SB_DQS_DP<4>")
	)
	(segment
		(start 329.282552 -272.140934)
		(end 329.290934 -272.136108)
		(width 0.09525)
		(layer "In4.Cu")
		(net "M_D_CPU0_SB_DQS_DP<4>")
	)
	(segment
		(start 281.92349 -276.961346)
		(end 282.138628 -276.746208)
		(width 0.16002)
		(layer "In4.Cu")
		(net "M_D_CPU0_SB_DQS_DP<4>")
	)
	(segment
		(start 333.042514 -272.140934)
		(end 333.050896 -272.136108)
		(width 0.09525)
		(layer "In4.Cu")
		(net "M_D_CPU0_SB_DQS_DP<4>")
	)
	(segment
		(start 297.186858 -277.377906)
		(end 297.622468 -277.377906)
		(width 0.16002)
		(layer "In4.Cu")
		(net "M_D_CPU0_SB_DQS_DP<4>")
	)
	(segment
		(start 285.966154 -277.960328)
		(end 289.056318 -277.960328)
		(width 0.16002)
		(layer "In4.Cu")
		(net "M_D_CPU0_SB_DQS_DP<4>")
	)
	(segment
		(start 333.982568 -272.140934)
		(end 333.99095 -272.136108)
		(width 0.09525)
		(layer "In4.Cu")
		(net "M_D_CPU0_SB_DQS_DP<4>")
	)
	(segment
		(start 301.279052 -277.11019)
		(end 301.754032 -277.58517)
		(width 0.16002)
		(layer "In4.Cu")
		(net "M_D_CPU0_SB_DQS_DP<4>")
	)
	(segment
		(start 294.37584 -277.960328)
		(end 296.604436 -277.960328)
		(width 0.16002)
		(layer "In4.Cu")
		(net "M_D_CPU0_SB_DQS_DP<4>")
	)
	(segment
		(start 305.797204 -276.77237)
		(end 307.729382 -276.77237)
		(width 0.16002)
		(layer "In4.Cu")
		(net "M_D_CPU0_SB_DQS_DP<4>")
	)
	(segment
		(start 337.74253 -272.140934)
		(end 337.750912 -272.136108)
		(width 0.09525)
		(layer "In4.Cu")
		(net "M_D_CPU0_SB_DQS_DP<4>")
	)
	(segment
		(start 291.415724 -277.11019)
		(end 293.525702 -277.11019)
		(width 0.16002)
		(layer "In4.Cu")
		(net "M_D_CPU0_SB_DQS_DP<4>")
	)
	(segment
		(start 336.23123 -272.136108)
		(end 336.239612 -272.140934)
		(width 0.09525)
		(layer "In4.Cu")
		(net "M_D_CPU0_SB_DQS_DP<4>")
	)
	(segment
		(start 283.84246 -277.080726)
		(end 285.966154 -277.960328)
		(width 0.16002)
		(layer "In4.Cu")
		(net "M_D_CPU0_SB_DQS_DP<4>")
	)
	(segment
		(start 331.531214 -272.136108)
		(end 331.539596 -272.140934)
		(width 0.09525)
		(layer "In4.Cu")
		(net "M_D_CPU0_SB_DQS_DP<4>")
	)
	(segment
		(start 298.278804 -276.72157)
		(end 298.553632 -276.72157)
		(width 0.16002)
		(layer "In4.Cu")
		(net "M_D_CPU0_SB_DQS_DP<4>")
	)
	(segment
		(start 340.496398 -272.173954)
		(end 340.597236 -272.200624)
		(width 0.09525)
		(layer "In4.Cu")
		(net "M_D_CPU0_SB_DQS_DP<4>")
	)
	(segment
		(start 290.696904 -276.78507)
		(end 291.090604 -276.78507)
		(width 0.16002)
		(layer "In4.Cu")
		(net "M_D_CPU0_SB_DQS_DP<4>")
	)
	(segment
		(start 291.090604 -276.78507)
		(end 291.415724 -277.11019)
		(width 0.16002)
		(layer "In4.Cu")
		(net "M_D_CPU0_SB_DQS_DP<4>")
	)
	(segment
		(start 296.604436 -277.960328)
		(end 297.186858 -277.377906)
		(width 0.16002)
		(layer "In4.Cu")
		(net "M_D_CPU0_SB_DQS_DP<4>")
	)
	(segment
		(start 289.858704 -277.62327)
		(end 290.696904 -276.78507)
		(width 0.16002)
		(layer "In4.Cu")
		(net "M_D_CPU0_SB_DQS_DP<4>")
	)
	(segment
		(start 280.909776 -276.961346)
		(end 281.92349 -276.961346)
		(width 0.16002)
		(layer "In4.Cu")
		(net "M_D_CPU0_SB_DQS_DP<4>")
	)
	(segment
		(start 323.919596 -270.72717)
		(end 323.978524 -270.668242)
		(width 0.09525)
		(layer "In4.Cu")
		(net "M_D_CPU0_SB_DQS_DP<4>")
	)
	(segment
		(start 324.367144 -270.879062)
		(end 325.235824 -270.879062)
		(width 0.09525)
		(layer "In4.Cu")
		(net "M_D_CPU0_SB_DQS_DP<4>")
	)
	(segment
		(start 304.984404 -277.58517)
		(end 305.797204 -276.77237)
		(width 0.16002)
		(layer "In4.Cu")
		(net "M_D_CPU0_SB_DQS_DP<4>")
	)
	(segment
		(start 298.942252 -277.11019)
		(end 301.279052 -277.11019)
		(width 0.16002)
		(layer "In4.Cu")
		(net "M_D_CPU0_SB_DQS_DP<4>")
	)
	(segment
		(start 337.171284 -272.136108)
		(end 337.179666 -272.140934)
		(width 0.09525)
		(layer "In4.Cu")
		(net "M_D_CPU0_SB_DQS_DP<4>")
	)
	(segment
		(start 280.635964 -277.235158)
		(end 280.909776 -276.961346)
		(width 0.16002)
		(layer "In4.Cu")
		(net "M_D_CPU0_SB_DQS_DP<4>")
	)
	(segment
		(start 313.774582 -270.72717)
		(end 323.895974 -270.72717)
		(width 0.16002)
		(layer "In4.Cu")
		(net "M_D_CPU0_SB_DQS_DP<4>")
	)
	(segment
		(start 326.446134 -272.089372)
		(end 327.59015 -272.089372)
		(width 0.09525)
		(layer "In4.Cu")
		(net "M_D_CPU0_SB_DQS_DP<4>")
	)
	(segment
		(start 297.622468 -277.377906)
		(end 298.278804 -276.72157)
		(width 0.16002)
		(layer "In4.Cu")
		(net "M_D_CPU0_SB_DQS_DP<4>")
	)
	(segment
		(start 298.553632 -276.72157)
		(end 298.942252 -277.11019)
		(width 0.16002)
		(layer "In4.Cu")
		(net "M_D_CPU0_SB_DQS_DP<4>")
	)
	(segment
		(start 307.729382 -276.77237)
		(end 313.774582 -270.72717)
		(width 0.16002)
		(layer "In4.Cu")
		(net "M_D_CPU0_SB_DQS_DP<4>")
	)
	(segment
		(start 289.056318 -277.960328)
		(end 289.393376 -277.62327)
		(width 0.16002)
		(layer "In4.Cu")
		(net "M_D_CPU0_SB_DQS_DP<4>")
	)
	(segment
		(start 332.471268 -272.136108)
		(end 332.47965 -272.140934)
		(width 0.09525)
		(layer "In4.Cu")
		(net "M_D_CPU0_SB_DQS_DP<4>")
	)
	(arc
		(start 329.659742 -272.140934)
		(mid 329.941174 -272.216689)
		(end 330.222606 -272.140934)
		(width 0.09525)
		(layer "In4.Cu")
		(net "M_D_CPU0_SB_DQS_DP<4>")
	)
	(arc
		(start 332.47965 -272.140934)
		(mid 332.761082 -272.216689)
		(end 333.042514 -272.140934)
		(width 0.09525)
		(layer "In4.Cu")
		(net "M_D_CPU0_SB_DQS_DP<4>")
	)
	(arc
		(start 336.802476 -272.140934)
		(mid 336.986251 -272.090162)
		(end 337.171284 -272.136108)
		(width 0.09525)
		(layer "In4.Cu")
		(net "M_D_CPU0_SB_DQS_DP<4>")
	)
	(arc
		(start 337.750912 -272.136108)
		(mid 337.935944 -272.090194)
		(end 338.11972 -272.140934)
		(width 0.09525)
		(layer "In4.Cu")
		(net "M_D_CPU0_SB_DQS_DP<4>")
	)
	(arc
		(start 336.239612 -272.140934)
		(mid 336.521044 -272.216689)
		(end 336.802476 -272.140934)
		(width 0.09525)
		(layer "In4.Cu")
		(net "M_D_CPU0_SB_DQS_DP<4>")
	)
	(arc
		(start 339.999574 -272.140934)
		(mid 340.233088 -272.214777)
		(end 340.475824 -272.182082)
		(width 0.09525)
		(layer "In4.Cu")
		(net "M_D_CPU0_SB_DQS_DP<4>")
	)
	(arc
		(start 330.222606 -272.140934)
		(mid 330.411074 -272.090257)
		(end 330.599542 -272.140934)
		(width 0.09525)
		(layer "In4.Cu")
		(net "M_D_CPU0_SB_DQS_DP<4>")
	)
	(arc
		(start 334.359758 -272.140934)
		(mid 334.64119 -272.216689)
		(end 334.922622 -272.140934)
		(width 0.09525)
		(layer "In4.Cu")
		(net "M_D_CPU0_SB_DQS_DP<4>")
	)
	(arc
		(start 327.779126 -272.140934)
		(mid 328.052308 -272.216876)
		(end 328.327766 -272.14957)
		(width 0.09525)
		(layer "In4.Cu")
		(net "M_D_CPU0_SB_DQS_DP<4>")
	)
	(arc
		(start 334.922622 -272.140934)
		(mid 335.11109 -272.090257)
		(end 335.299558 -272.140934)
		(width 0.09525)
		(layer "In4.Cu")
		(net "M_D_CPU0_SB_DQS_DP<4>")
	)
	(arc
		(start 339.059774 -272.140934)
		(mid 339.341206 -272.216689)
		(end 339.622638 -272.140934)
		(width 0.09525)
		(layer "In4.Cu")
		(net "M_D_CPU0_SB_DQS_DP<4>")
	)
	(arc
		(start 329.290934 -272.136108)
		(mid 329.475966 -272.090194)
		(end 329.659742 -272.140934)
		(width 0.09525)
		(layer "In4.Cu")
		(net "M_D_CPU0_SB_DQS_DP<4>")
	)
	(arc
		(start 330.599542 -272.140934)
		(mid 330.880974 -272.216689)
		(end 331.162406 -272.140934)
		(width 0.09525)
		(layer "In4.Cu")
		(net "M_D_CPU0_SB_DQS_DP<4>")
	)
	(arc
		(start 327.59015 -272.089372)
		(mid 327.688047 -272.102658)
		(end 327.779126 -272.140934)
		(width 0.09525)
		(layer "In4.Cu")
		(net "M_D_CPU0_SB_DQS_DP<4>")
	)
	(arc
		(start 332.10246 -272.140934)
		(mid 332.286235 -272.090162)
		(end 332.471268 -272.136108)
		(width 0.09525)
		(layer "In4.Cu")
		(net "M_D_CPU0_SB_DQS_DP<4>")
	)
	(arc
		(start 337.179666 -272.140934)
		(mid 337.461098 -272.216689)
		(end 337.74253 -272.140934)
		(width 0.09525)
		(layer "In4.Cu")
		(net "M_D_CPU0_SB_DQS_DP<4>")
	)
	(arc
		(start 339.622638 -272.140934)
		(mid 339.811106 -272.090257)
		(end 339.999574 -272.140934)
		(width 0.09525)
		(layer "In4.Cu")
		(net "M_D_CPU0_SB_DQS_DP<4>")
	)
	(arc
		(start 333.419704 -272.140934)
		(mid 333.701136 -272.216689)
		(end 333.982568 -272.140934)
		(width 0.09525)
		(layer "In4.Cu")
		(net "M_D_CPU0_SB_DQS_DP<4>")
	)
	(arc
		(start 333.050896 -272.136108)
		(mid 333.235928 -272.090194)
		(end 333.419704 -272.140934)
		(width 0.09525)
		(layer "In4.Cu")
		(net "M_D_CPU0_SB_DQS_DP<4>")
	)
	(arc
		(start 331.539596 -272.140934)
		(mid 331.821028 -272.216689)
		(end 332.10246 -272.140934)
		(width 0.09525)
		(layer "In4.Cu")
		(net "M_D_CPU0_SB_DQS_DP<4>")
	)
	(arc
		(start 338.11972 -272.140934)
		(mid 338.401152 -272.216689)
		(end 338.682584 -272.140934)
		(width 0.09525)
		(layer "In4.Cu")
		(net "M_D_CPU0_SB_DQS_DP<4>")
	)
	(arc
		(start 338.690966 -272.136108)
		(mid 338.875998 -272.090194)
		(end 339.059774 -272.140934)
		(width 0.09525)
		(layer "In4.Cu")
		(net "M_D_CPU0_SB_DQS_DP<4>")
	)
	(arc
		(start 328.719688 -272.140934)
		(mid 329.00112 -272.216689)
		(end 329.282552 -272.140934)
		(width 0.09525)
		(layer "In4.Cu")
		(net "M_D_CPU0_SB_DQS_DP<4>")
	)
	(arc
		(start 335.862422 -272.140934)
		(mid 336.046197 -272.090162)
		(end 336.23123 -272.136108)
		(width 0.09525)
		(layer "In4.Cu")
		(net "M_D_CPU0_SB_DQS_DP<4>")
	)
	(arc
		(start 331.162406 -272.140934)
		(mid 331.346181 -272.090162)
		(end 331.531214 -272.136108)
		(width 0.09525)
		(layer "In4.Cu")
		(net "M_D_CPU0_SB_DQS_DP<4>")
	)
	(arc
		(start 333.99095 -272.136108)
		(mid 334.175982 -272.090194)
		(end 334.359758 -272.140934)
		(width 0.09525)
		(layer "In4.Cu")
		(net "M_D_CPU0_SB_DQS_DP<4>")
	)
	(arc
		(start 340.475824 -272.182082)
		(mid 340.486152 -272.178122)
		(end 340.496398 -272.173954)
		(width 0.09525)
		(layer "In4.Cu")
		(net "M_D_CPU0_SB_DQS_DP<4>")
	)
	(arc
		(start 335.299558 -272.140934)
		(mid 335.58099 -272.216689)
		(end 335.862422 -272.140934)
		(width 0.09525)
		(layer "In4.Cu")
		(net "M_D_CPU0_SB_DQS_DP<4>")
	)
	(arc
		(start 328.342498 -272.140934)
		(mid 328.526273 -272.090162)
		(end 328.711306 -272.136108)
		(width 0.09525)
		(layer "In4.Cu")
		(net "M_D_CPU0_SB_DQS_DP<4>")
	)
	(segment
		(start 339.337904 -290.019994)
		(end 338.871052 -290.285932)
		(width 0.12954)
		(layer "F.Cu")
		(net "M_D_CPU0_SB_DQS_DP<3>")
	)
	(segment
		(start 310.482234 -310.603646)
		(end 310.759094 -310.603646)
		(width 0.16002)
		(layer "In4.Cu")
		(net "M_D_CPU0_SB_DQS_DP<3>")
	)
	(segment
		(start 312.595768 -307.749702)
		(end 313.122818 -307.749702)
		(width 0.16002)
		(layer "In4.Cu")
		(net "M_D_CPU0_SB_DQS_DP<3>")
	)
	(segment
		(start 328.711306 -290.615878)
		(end 328.719688 -290.611052)
		(width 0.09525)
		(layer "In4.Cu")
		(net "M_D_CPU0_SB_DQS_DP<3>")
	)
	(segment
		(start 303.54524 -312.69051)
		(end 304.239422 -313.384692)
		(width 0.16002)
		(layer "In4.Cu")
		(net "M_D_CPU0_SB_DQS_DP<3>")
	)
	(segment
		(start 333.982568 -290.611052)
		(end 333.99095 -290.615878)
		(width 0.09525)
		(layer "In4.Cu")
		(net "M_D_CPU0_SB_DQS_DP<3>")
	)
	(segment
		(start 327.684892 -290.53536)
		(end 328.06132 -290.53536)
		(width 0.09525)
		(layer "In4.Cu")
		(net "M_D_CPU0_SB_DQS_DP<3>")
	)
	(segment
		(start 314.87999 -306.48275)
		(end 315.076586 -306.286154)
		(width 0.16002)
		(layer "In4.Cu")
		(net "M_D_CPU0_SB_DQS_DP<3>")
	)
	(segment
		(start 296.936414 -313.371992)
		(end 297.294554 -313.371992)
		(width 0.16002)
		(layer "In4.Cu")
		(net "M_D_CPU0_SB_DQS_DP<3>")
	)
	(segment
		(start 309.475632 -310.869838)
		(end 309.848504 -310.496966)
		(width 0.16002)
		(layer "In4.Cu")
		(net "M_D_CPU0_SB_DQS_DP<3>")
	)
	(segment
		(start 329.282552 -290.611052)
		(end 329.290934 -290.615878)
		(width 0.09525)
		(layer "In4.Cu")
		(net "M_D_CPU0_SB_DQS_DP<3>")
	)
	(segment
		(start 306.489608 -312.521092)
		(end 306.606448 -312.404252)
		(width 0.16002)
		(layer "In4.Cu")
		(net "M_D_CPU0_SB_DQS_DP<3>")
	)
	(segment
		(start 291.387022 -312.209942)
		(end 293.296086 -312.209942)
		(width 0.16002)
		(layer "In4.Cu")
		(net "M_D_CPU0_SB_DQS_DP<3>")
	)
	(segment
		(start 288.86277 -313.059826)
		(end 289.179254 -313.37631)
		(width 0.16002)
		(layer "In4.Cu")
		(net "M_D_CPU0_SB_DQS_DP<3>")
	)
	(segment
		(start 315.976762 -305.109118)
		(end 316.253622 -305.109118)
		(width 0.16002)
		(layer "In4.Cu")
		(net "M_D_CPU0_SB_DQS_DP<3>")
	)
	(segment
		(start 326.243188 -291.498782)
		(end 327.684892 -290.53536)
		(width 0.09525)
		(layer "In4.Cu")
		(net "M_D_CPU0_SB_DQS_DP<3>")
	)
	(segment
		(start 314.49645 -306.37607)
		(end 314.60313 -306.48275)
		(width 0.16002)
		(layer "In4.Cu")
		(net "M_D_CPU0_SB_DQS_DP<3>")
	)
	(segment
		(start 336.23123 -290.615878)
		(end 336.239612 -290.611052)
		(width 0.09525)
		(layer "In4.Cu")
		(net "M_D_CPU0_SB_DQS_DP<3>")
	)
	(segment
		(start 316.343792 -304.001678)
		(end 316.716664 -303.628806)
		(width 0.16002)
		(layer "In4.Cu")
		(net "M_D_CPU0_SB_DQS_DP<3>")
	)
	(segment
		(start 311.749186 -309.123334)
		(end 311.855866 -309.230014)
		(width 0.16002)
		(layer "In4.Cu")
		(net "M_D_CPU0_SB_DQS_DP<3>")
	)
	(segment
		(start 321.377818 -298.967652)
		(end 321.377818 -297.77563)
		(width 0.16002)
		(layer "In4.Cu")
		(net "M_D_CPU0_SB_DQS_DP<3>")
	)
	(segment
		(start 317.243714 -303.628806)
		(end 317.350394 -303.735486)
		(width 0.16002)
		(layer "In4.Cu")
		(net "M_D_CPU0_SB_DQS_DP<3>")
	)
	(segment
		(start 305.689254 -312.521092)
		(end 306.489608 -312.521092)
		(width 0.16002)
		(layer "In4.Cu")
		(net "M_D_CPU0_SB_DQS_DP<3>")
	)
	(segment
		(start 312.222896 -308.650132)
		(end 312.222896 -308.122574)
		(width 0.16002)
		(layer "In4.Cu")
		(net "M_D_CPU0_SB_DQS_DP<3>")
	)
	(segment
		(start 309.108602 -311.977278)
		(end 309.385462 -311.977278)
		(width 0.16002)
		(layer "In4.Cu")
		(net "M_D_CPU0_SB_DQS_DP<3>")
	)
	(segment
		(start 313.122818 -307.749702)
		(end 313.229498 -307.856382)
		(width 0.16002)
		(layer "In4.Cu")
		(net "M_D_CPU0_SB_DQS_DP<3>")
	)
	(segment
		(start 303.002188 -312.69051)
		(end 303.54524 -312.69051)
		(width 0.16002)
		(layer "In4.Cu")
		(net "M_D_CPU0_SB_DQS_DP<3>")
	)
	(segment
		(start 316.253622 -305.109118)
		(end 316.450218 -304.912522)
		(width 0.16002)
		(layer "In4.Cu")
		(net "M_D_CPU0_SB_DQS_DP<3>")
	)
	(segment
		(start 284.736032 -312.935112)
		(end 285.009844 -313.208924)
		(width 0.16002)
		(layer "In4.Cu")
		(net "M_D_CPU0_SB_DQS_DP<3>")
	)
	(segment
		(start 325.07174 -293.251636)
		(end 326.243188 -291.498782)
		(width 0.09525)
		(layer "In4.Cu")
		(net "M_D_CPU0_SB_DQS_DP<3>")
	)
	(segment
		(start 298.539154 -312.609992)
		(end 298.939204 -312.209942)
		(width 0.16002)
		(layer "In4.Cu")
		(net "M_D_CPU0_SB_DQS_DP<3>")
	)
	(segment
		(start 331.531214 -290.615878)
		(end 331.539596 -290.611052)
		(width 0.09525)
		(layer "In4.Cu")
		(net "M_D_CPU0_SB_DQS_DP<3>")
	)
	(segment
		(start 316.343792 -304.529236)
		(end 316.343792 -304.001678)
		(width 0.16002)
		(layer "In4.Cu")
		(net "M_D_CPU0_SB_DQS_DP<3>")
	)
	(segment
		(start 293.296086 -312.209942)
		(end 294.14597 -313.059826)
		(width 0.16002)
		(layer "In4.Cu")
		(net "M_D_CPU0_SB_DQS_DP<3>")
	)
	(segment
		(start 287.1343 -313.208924)
		(end 287.283398 -313.059826)
		(width 0.16002)
		(layer "In4.Cu")
		(net "M_D_CPU0_SB_DQS_DP<3>")
	)
	(segment
		(start 313.596528 -306.748942)
		(end 313.9694 -306.37607)
		(width 0.16002)
		(layer "In4.Cu")
		(net "M_D_CPU0_SB_DQS_DP<3>")
	)
	(segment
		(start 291.058854 -312.53811)
		(end 291.387022 -312.209942)
		(width 0.16002)
		(layer "In4.Cu")
		(net "M_D_CPU0_SB_DQS_DP<3>")
	)
	(segment
		(start 314.97016 -305.902868)
		(end 314.97016 -305.37531)
		(width 0.16002)
		(layer "In4.Cu")
		(net "M_D_CPU0_SB_DQS_DP<3>")
	)
	(segment
		(start 317.627254 -303.735486)
		(end 317.82385 -303.53889)
		(width 0.16002)
		(layer "In4.Cu")
		(net "M_D_CPU0_SB_DQS_DP<3>")
	)
	(segment
		(start 313.229498 -307.856382)
		(end 313.506358 -307.856382)
		(width 0.16002)
		(layer "In4.Cu")
		(net "M_D_CPU0_SB_DQS_DP<3>")
	)
	(segment
		(start 296.624248 -313.059826)
		(end 296.936414 -313.371992)
		(width 0.16002)
		(layer "In4.Cu")
		(net "M_D_CPU0_SB_DQS_DP<3>")
	)
	(segment
		(start 309.475632 -311.397396)
		(end 309.475632 -310.869838)
		(width 0.16002)
		(layer "In4.Cu")
		(net "M_D_CPU0_SB_DQS_DP<3>")
	)
	(segment
		(start 310.375554 -310.496966)
		(end 310.482234 -310.603646)
		(width 0.16002)
		(layer "In4.Cu")
		(net "M_D_CPU0_SB_DQS_DP<3>")
	)
	(segment
		(start 315.343032 -305.002438)
		(end 315.870082 -305.002438)
		(width 0.16002)
		(layer "In4.Cu")
		(net "M_D_CPU0_SB_DQS_DP<3>")
	)
	(segment
		(start 310.95569 -310.13019)
		(end 310.849264 -310.023764)
		(width 0.16002)
		(layer "In4.Cu")
		(net "M_D_CPU0_SB_DQS_DP<3>")
	)
	(segment
		(start 324.377558 -294.860218)
		(end 324.377558 -294.268398)
		(width 0.09525)
		(layer "In4.Cu")
		(net "M_D_CPU0_SB_DQS_DP<3>")
	)
	(segment
		(start 297.294554 -313.371992)
		(end 298.056554 -312.609992)
		(width 0.16002)
		(layer "In4.Cu")
		(net "M_D_CPU0_SB_DQS_DP<3>")
	)
	(segment
		(start 289.738054 -313.37631)
		(end 290.576254 -312.53811)
		(width 0.16002)
		(layer "In4.Cu")
		(net "M_D_CPU0_SB_DQS_DP<3>")
	)
	(segment
		(start 337.74253 -290.611052)
		(end 337.750912 -290.615878)
		(width 0.09525)
		(layer "In4.Cu")
		(net "M_D_CPU0_SB_DQS_DP<3>")
	)
	(segment
		(start 304.239422 -313.384692)
		(end 304.825654 -313.384692)
		(width 0.16002)
		(layer "In4.Cu")
		(net "M_D_CPU0_SB_DQS_DP<3>")
	)
	(segment
		(start 286.586168 -313.208924)
		(end 287.1343 -313.208924)
		(width 0.16002)
		(layer "In4.Cu")
		(net "M_D_CPU0_SB_DQS_DP<3>")
	)
	(segment
		(start 324.173088 -295.064688)
		(end 324.377558 -294.860218)
		(width 0.09525)
		(layer "In4.Cu")
		(net "M_D_CPU0_SB_DQS_DP<3>")
	)
	(segment
		(start 313.702954 -307.659786)
		(end 313.702954 -307.382926)
		(width 0.16002)
		(layer "In4.Cu")
		(net "M_D_CPU0_SB_DQS_DP<3>")
	)
	(segment
		(start 315.076586 -306.009294)
		(end 314.97016 -305.902868)
		(width 0.16002)
		(layer "In4.Cu")
		(net "M_D_CPU0_SB_DQS_DP<3>")
	)
	(segment
		(start 310.759094 -310.603646)
		(end 310.95569 -310.40705)
		(width 0.16002)
		(layer "In4.Cu")
		(net "M_D_CPU0_SB_DQS_DP<3>")
	)
	(segment
		(start 304.825654 -313.384692)
		(end 305.689254 -312.521092)
		(width 0.16002)
		(layer "In4.Cu")
		(net "M_D_CPU0_SB_DQS_DP<3>")
	)
	(segment
		(start 285.009844 -313.208924)
		(end 285.872428 -313.208924)
		(width 0.16002)
		(layer "In4.Cu")
		(net "M_D_CPU0_SB_DQS_DP<3>")
	)
	(segment
		(start 317.82385 -303.26203)
		(end 317.717424 -303.155604)
		(width 0.16002)
		(layer "In4.Cu")
		(net "M_D_CPU0_SB_DQS_DP<3>")
	)
	(segment
		(start 332.471268 -290.615878)
		(end 332.47965 -290.611052)
		(width 0.09525)
		(layer "In4.Cu")
		(net "M_D_CPU0_SB_DQS_DP<3>")
	)
	(segment
		(start 314.60313 -306.48275)
		(end 314.87999 -306.48275)
		(width 0.16002)
		(layer "In4.Cu")
		(net "M_D_CPU0_SB_DQS_DP<3>")
	)
	(segment
		(start 312.132726 -309.230014)
		(end 312.329322 -309.033418)
		(width 0.16002)
		(layer "In4.Cu")
		(net "M_D_CPU0_SB_DQS_DP<3>")
	)
	(segment
		(start 311.855866 -309.230014)
		(end 312.132726 -309.230014)
		(width 0.16002)
		(layer "In4.Cu")
		(net "M_D_CPU0_SB_DQS_DP<3>")
	)
	(segment
		(start 309.582058 -311.503822)
		(end 309.475632 -311.397396)
		(width 0.16002)
		(layer "In4.Cu")
		(net "M_D_CPU0_SB_DQS_DP<3>")
	)
	(segment
		(start 300.171104 -312.209942)
		(end 301.345854 -313.384692)
		(width 0.16002)
		(layer "In4.Cu")
		(net "M_D_CPU0_SB_DQS_DP<3>")
	)
	(segment
		(start 339.001608 -290.63823)
		(end 339.024976 -290.551362)
		(width 0.09525)
		(layer "In4.Cu")
		(net "M_D_CPU0_SB_DQS_DP<3>")
	)
	(segment
		(start 333.042514 -290.611052)
		(end 333.050896 -290.615878)
		(width 0.09525)
		(layer "In4.Cu")
		(net "M_D_CPU0_SB_DQS_DP<3>")
	)
	(segment
		(start 337.171284 -290.615878)
		(end 337.179666 -290.611052)
		(width 0.09525)
		(layer "In4.Cu")
		(net "M_D_CPU0_SB_DQS_DP<3>")
	)
	(segment
		(start 313.506358 -307.856382)
		(end 313.702954 -307.659786)
		(width 0.16002)
		(layer "In4.Cu")
		(net "M_D_CPU0_SB_DQS_DP<3>")
	)
	(segment
		(start 294.14597 -313.059826)
		(end 296.624248 -313.059826)
		(width 0.16002)
		(layer "In4.Cu")
		(net "M_D_CPU0_SB_DQS_DP<3>")
	)
	(segment
		(start 317.717424 -302.628046)
		(end 321.377818 -298.967652)
		(width 0.16002)
		(layer "In4.Cu")
		(net "M_D_CPU0_SB_DQS_DP<3>")
	)
	(segment
		(start 317.350394 -303.735486)
		(end 317.627254 -303.735486)
		(width 0.16002)
		(layer "In4.Cu")
		(net "M_D_CPU0_SB_DQS_DP<3>")
	)
	(segment
		(start 310.849264 -310.023764)
		(end 310.849264 -309.496206)
		(width 0.16002)
		(layer "In4.Cu")
		(net "M_D_CPU0_SB_DQS_DP<3>")
	)
	(segment
		(start 286.469328 -313.092084)
		(end 286.586168 -313.208924)
		(width 0.16002)
		(layer "In4.Cu")
		(net "M_D_CPU0_SB_DQS_DP<3>")
	)
	(segment
		(start 324.605396 -293.718234)
		(end 325.07174 -293.251636)
		(width 0.09525)
		(layer "In4.Cu")
		(net "M_D_CPU0_SB_DQS_DP<3>")
	)
	(segment
		(start 307.203348 -312.521092)
		(end 307.824378 -312.521092)
		(width 0.16002)
		(layer "In4.Cu")
		(net "M_D_CPU0_SB_DQS_DP<3>")
	)
	(segment
		(start 317.82385 -303.53889)
		(end 317.82385 -303.26203)
		(width 0.16002)
		(layer "In4.Cu")
		(net "M_D_CPU0_SB_DQS_DP<3>")
	)
	(segment
		(start 316.450218 -304.912522)
		(end 316.450218 -304.635662)
		(width 0.16002)
		(layer "In4.Cu")
		(net "M_D_CPU0_SB_DQS_DP<3>")
	)
	(segment
		(start 307.086508 -312.404252)
		(end 307.203348 -312.521092)
		(width 0.16002)
		(layer "In4.Cu")
		(net "M_D_CPU0_SB_DQS_DP<3>")
	)
	(segment
		(start 314.97016 -305.37531)
		(end 315.343032 -305.002438)
		(width 0.16002)
		(layer "In4.Cu")
		(net "M_D_CPU0_SB_DQS_DP<3>")
	)
	(segment
		(start 310.95569 -310.40705)
		(end 310.95569 -310.13019)
		(width 0.16002)
		(layer "In4.Cu")
		(net "M_D_CPU0_SB_DQS_DP<3>")
	)
	(segment
		(start 324.377558 -294.268398)
		(end 324.605396 -293.718234)
		(width 0.09525)
		(layer "In4.Cu")
		(net "M_D_CPU0_SB_DQS_DP<3>")
	)
	(segment
		(start 312.329322 -308.756558)
		(end 312.222896 -308.650132)
		(width 0.16002)
		(layer "In4.Cu")
		(net "M_D_CPU0_SB_DQS_DP<3>")
	)
	(segment
		(start 298.939204 -312.209942)
		(end 300.171104 -312.209942)
		(width 0.16002)
		(layer "In4.Cu")
		(net "M_D_CPU0_SB_DQS_DP<3>")
	)
	(segment
		(start 306.606448 -312.404252)
		(end 307.086508 -312.404252)
		(width 0.16002)
		(layer "In4.Cu")
		(net "M_D_CPU0_SB_DQS_DP<3>")
	)
	(segment
		(start 290.576254 -312.53811)
		(end 291.058854 -312.53811)
		(width 0.16002)
		(layer "In4.Cu")
		(net "M_D_CPU0_SB_DQS_DP<3>")
	)
	(segment
		(start 309.385462 -311.977278)
		(end 309.582058 -311.780682)
		(width 0.16002)
		(layer "In4.Cu")
		(net "M_D_CPU0_SB_DQS_DP<3>")
	)
	(segment
		(start 317.717424 -303.155604)
		(end 317.717424 -302.628046)
		(width 0.16002)
		(layer "In4.Cu")
		(net "M_D_CPU0_SB_DQS_DP<3>")
	)
	(segment
		(start 308.474872 -311.870598)
		(end 309.001922 -311.870598)
		(width 0.16002)
		(layer "In4.Cu")
		(net "M_D_CPU0_SB_DQS_DP<3>")
	)
	(segment
		(start 287.283398 -313.059826)
		(end 288.86277 -313.059826)
		(width 0.16002)
		(layer "In4.Cu")
		(net "M_D_CPU0_SB_DQS_DP<3>")
	)
	(segment
		(start 285.872428 -313.208924)
		(end 285.989268 -313.092084)
		(width 0.16002)
		(layer "In4.Cu")
		(net "M_D_CPU0_SB_DQS_DP<3>")
	)
	(segment
		(start 309.848504 -310.496966)
		(end 310.375554 -310.496966)
		(width 0.16002)
		(layer "In4.Cu")
		(net "M_D_CPU0_SB_DQS_DP<3>")
	)
	(segment
		(start 312.222896 -308.122574)
		(end 312.595768 -307.749702)
		(width 0.16002)
		(layer "In4.Cu")
		(net "M_D_CPU0_SB_DQS_DP<3>")
	)
	(segment
		(start 321.377818 -297.77563)
		(end 324.072504 -295.081452)
		(width 0.16002)
		(layer "In4.Cu")
		(net "M_D_CPU0_SB_DQS_DP<3>")
	)
	(segment
		(start 298.056554 -312.609992)
		(end 298.539154 -312.609992)
		(width 0.16002)
		(layer "In4.Cu")
		(net "M_D_CPU0_SB_DQS_DP<3>")
	)
	(segment
		(start 312.329322 -309.033418)
		(end 312.329322 -308.756558)
		(width 0.16002)
		(layer "In4.Cu")
		(net "M_D_CPU0_SB_DQS_DP<3>")
	)
	(segment
		(start 285.989268 -313.092084)
		(end 286.469328 -313.092084)
		(width 0.16002)
		(layer "In4.Cu")
		(net "M_D_CPU0_SB_DQS_DP<3>")
	)
	(segment
		(start 302.308006 -313.384692)
		(end 303.002188 -312.69051)
		(width 0.16002)
		(layer "In4.Cu")
		(net "M_D_CPU0_SB_DQS_DP<3>")
	)
	(segment
		(start 309.582058 -311.780682)
		(end 309.582058 -311.503822)
		(width 0.16002)
		(layer "In4.Cu")
		(net "M_D_CPU0_SB_DQS_DP<3>")
	)
	(segment
		(start 324.072504 -295.081452)
		(end 324.089268 -295.064688)
		(width 0.09525)
		(layer "In4.Cu")
		(net "M_D_CPU0_SB_DQS_DP<3>")
	)
	(segment
		(start 313.9694 -306.37607)
		(end 314.49645 -306.37607)
		(width 0.16002)
		(layer "In4.Cu")
		(net "M_D_CPU0_SB_DQS_DP<3>")
	)
	(segment
		(start 316.716664 -303.628806)
		(end 317.243714 -303.628806)
		(width 0.16002)
		(layer "In4.Cu")
		(net "M_D_CPU0_SB_DQS_DP<3>")
	)
	(segment
		(start 316.450218 -304.635662)
		(end 316.343792 -304.529236)
		(width 0.16002)
		(layer "In4.Cu")
		(net "M_D_CPU0_SB_DQS_DP<3>")
	)
	(segment
		(start 313.596528 -307.2765)
		(end 313.596528 -306.748942)
		(width 0.16002)
		(layer "In4.Cu")
		(net "M_D_CPU0_SB_DQS_DP<3>")
	)
	(segment
		(start 338.682584 -290.611052)
		(end 338.690966 -290.615878)
		(width 0.09525)
		(layer "In4.Cu")
		(net "M_D_CPU0_SB_DQS_DP<3>")
	)
	(segment
		(start 289.179254 -313.37631)
		(end 289.738054 -313.37631)
		(width 0.16002)
		(layer "In4.Cu")
		(net "M_D_CPU0_SB_DQS_DP<3>")
	)
	(segment
		(start 309.001922 -311.870598)
		(end 309.108602 -311.977278)
		(width 0.16002)
		(layer "In4.Cu")
		(net "M_D_CPU0_SB_DQS_DP<3>")
	)
	(segment
		(start 307.824378 -312.521092)
		(end 308.474872 -311.870598)
		(width 0.16002)
		(layer "In4.Cu")
		(net "M_D_CPU0_SB_DQS_DP<3>")
	)
	(segment
		(start 313.702954 -307.382926)
		(end 313.596528 -307.2765)
		(width 0.16002)
		(layer "In4.Cu")
		(net "M_D_CPU0_SB_DQS_DP<3>")
	)
	(segment
		(start 339.024976 -290.551362)
		(end 338.871052 -290.285932)
		(width 0.09525)
		(layer "In4.Cu")
		(net "M_D_CPU0_SB_DQS_DP<3>")
	)
	(segment
		(start 311.222136 -309.123334)
		(end 311.749186 -309.123334)
		(width 0.16002)
		(layer "In4.Cu")
		(net "M_D_CPU0_SB_DQS_DP<3>")
	)
	(segment
		(start 315.870082 -305.002438)
		(end 315.976762 -305.109118)
		(width 0.16002)
		(layer "In4.Cu")
		(net "M_D_CPU0_SB_DQS_DP<3>")
	)
	(segment
		(start 324.089268 -295.064688)
		(end 324.173088 -295.064688)
		(width 0.09525)
		(layer "In4.Cu")
		(net "M_D_CPU0_SB_DQS_DP<3>")
	)
	(segment
		(start 301.345854 -313.384692)
		(end 302.308006 -313.384692)
		(width 0.16002)
		(layer "In4.Cu")
		(net "M_D_CPU0_SB_DQS_DP<3>")
	)
	(segment
		(start 310.849264 -309.496206)
		(end 311.222136 -309.123334)
		(width 0.16002)
		(layer "In4.Cu")
		(net "M_D_CPU0_SB_DQS_DP<3>")
	)
	(segment
		(start 315.076586 -306.286154)
		(end 315.076586 -306.009294)
		(width 0.16002)
		(layer "In4.Cu")
		(net "M_D_CPU0_SB_DQS_DP<3>")
	)
	(arc
		(start 331.162406 -290.611052)
		(mid 331.346181 -290.661824)
		(end 331.531214 -290.615878)
		(width 0.09525)
		(layer "In4.Cu")
		(net "M_D_CPU0_SB_DQS_DP<3>")
	)
	(arc
		(start 338.690966 -290.615878)
		(mid 338.843861 -290.660706)
		(end 339.001608 -290.63823)
		(width 0.09525)
		(layer "In4.Cu")
		(net "M_D_CPU0_SB_DQS_DP<3>")
	)
	(arc
		(start 336.802476 -290.611052)
		(mid 336.986251 -290.661824)
		(end 337.171284 -290.615878)
		(width 0.09525)
		(layer "In4.Cu")
		(net "M_D_CPU0_SB_DQS_DP<3>")
	)
	(arc
		(start 333.419704 -290.611052)
		(mid 333.701136 -290.535297)
		(end 333.982568 -290.611052)
		(width 0.09525)
		(layer "In4.Cu")
		(net "M_D_CPU0_SB_DQS_DP<3>")
	)
	(arc
		(start 329.290934 -290.615878)
		(mid 329.475966 -290.661792)
		(end 329.659742 -290.611052)
		(width 0.09525)
		(layer "In4.Cu")
		(net "M_D_CPU0_SB_DQS_DP<3>")
	)
	(arc
		(start 332.10246 -290.611052)
		(mid 332.286235 -290.661824)
		(end 332.471268 -290.615878)
		(width 0.09525)
		(layer "In4.Cu")
		(net "M_D_CPU0_SB_DQS_DP<3>")
	)
	(arc
		(start 328.06132 -290.53536)
		(mid 328.206897 -290.554661)
		(end 328.342498 -290.611052)
		(width 0.09525)
		(layer "In4.Cu")
		(net "M_D_CPU0_SB_DQS_DP<3>")
	)
	(arc
		(start 332.47965 -290.611052)
		(mid 332.761082 -290.535297)
		(end 333.042514 -290.611052)
		(width 0.09525)
		(layer "In4.Cu")
		(net "M_D_CPU0_SB_DQS_DP<3>")
	)
	(arc
		(start 335.299558 -290.611052)
		(mid 335.58099 -290.535297)
		(end 335.862422 -290.611052)
		(width 0.09525)
		(layer "In4.Cu")
		(net "M_D_CPU0_SB_DQS_DP<3>")
	)
	(arc
		(start 329.659742 -290.611052)
		(mid 329.941174 -290.535297)
		(end 330.222606 -290.611052)
		(width 0.09525)
		(layer "In4.Cu")
		(net "M_D_CPU0_SB_DQS_DP<3>")
	)
	(arc
		(start 337.179666 -290.611052)
		(mid 337.461098 -290.535297)
		(end 337.74253 -290.611052)
		(width 0.09525)
		(layer "In4.Cu")
		(net "M_D_CPU0_SB_DQS_DP<3>")
	)
	(arc
		(start 337.750912 -290.615878)
		(mid 337.935944 -290.661792)
		(end 338.11972 -290.611052)
		(width 0.09525)
		(layer "In4.Cu")
		(net "M_D_CPU0_SB_DQS_DP<3>")
	)
	(arc
		(start 333.050896 -290.615878)
		(mid 333.235928 -290.661792)
		(end 333.419704 -290.611052)
		(width 0.09525)
		(layer "In4.Cu")
		(net "M_D_CPU0_SB_DQS_DP<3>")
	)
	(arc
		(start 330.222606 -290.611052)
		(mid 330.411074 -290.661729)
		(end 330.599542 -290.611052)
		(width 0.09525)
		(layer "In4.Cu")
		(net "M_D_CPU0_SB_DQS_DP<3>")
	)
	(arc
		(start 333.99095 -290.615878)
		(mid 334.175982 -290.661792)
		(end 334.359758 -290.611052)
		(width 0.09525)
		(layer "In4.Cu")
		(net "M_D_CPU0_SB_DQS_DP<3>")
	)
	(arc
		(start 334.359758 -290.611052)
		(mid 334.64119 -290.535297)
		(end 334.922622 -290.611052)
		(width 0.09525)
		(layer "In4.Cu")
		(net "M_D_CPU0_SB_DQS_DP<3>")
	)
	(arc
		(start 328.342498 -290.611052)
		(mid 328.526273 -290.661824)
		(end 328.711306 -290.615878)
		(width 0.09525)
		(layer "In4.Cu")
		(net "M_D_CPU0_SB_DQS_DP<3>")
	)
	(arc
		(start 335.862422 -290.611052)
		(mid 336.046197 -290.661824)
		(end 336.23123 -290.615878)
		(width 0.09525)
		(layer "In4.Cu")
		(net "M_D_CPU0_SB_DQS_DP<3>")
	)
	(arc
		(start 338.11972 -290.611052)
		(mid 338.401152 -290.535297)
		(end 338.682584 -290.611052)
		(width 0.09525)
		(layer "In4.Cu")
		(net "M_D_CPU0_SB_DQS_DP<3>")
	)
	(arc
		(start 336.239612 -290.611052)
		(mid 336.521044 -290.535297)
		(end 336.802476 -290.611052)
		(width 0.09525)
		(layer "In4.Cu")
		(net "M_D_CPU0_SB_DQS_DP<3>")
	)
	(arc
		(start 328.719688 -290.611052)
		(mid 329.00112 -290.535297)
		(end 329.282552 -290.611052)
		(width 0.09525)
		(layer "In4.Cu")
		(net "M_D_CPU0_SB_DQS_DP<3>")
	)
	(arc
		(start 334.922622 -290.611052)
		(mid 335.11109 -290.661729)
		(end 335.299558 -290.611052)
		(width 0.09525)
		(layer "In4.Cu")
		(net "M_D_CPU0_SB_DQS_DP<3>")
	)
	(arc
		(start 331.539596 -290.611052)
		(mid 331.821028 -290.535297)
		(end 332.10246 -290.611052)
		(width 0.09525)
		(layer "In4.Cu")
		(net "M_D_CPU0_SB_DQS_DP<3>")
	)
	(arc
		(start 330.599542 -290.611052)
		(mid 330.880974 -290.535297)
		(end 331.162406 -290.611052)
		(width 0.09525)
		(layer "In4.Cu")
		(net "M_D_CPU0_SB_DQS_DP<3>")
	)
	(segment
		(start 339.337904 -285.160212)
		(end 338.871052 -285.42615)
		(width 0.12954)
		(layer "F.Cu")
		(net "M_D_CPU0_SB_DQS_DP<2>")
	)
	(segment
		(start 310.539384 -300.85919)
		(end 310.815736 -300.85919)
		(width 0.16002)
		(layer "In4.Cu")
		(net "M_D_CPU0_SB_DQS_DP<2>")
	)
	(segment
		(start 313.563 -298.111926)
		(end 313.75985 -297.915076)
		(width 0.16002)
		(layer "In4.Cu")
		(net "M_D_CPU0_SB_DQS_DP<2>")
	)
	(segment
		(start 313.548776 -297.427396)
		(end 313.548776 -296.899838)
		(width 0.16002)
		(layer "In4.Cu")
		(net "M_D_CPU0_SB_DQS_DP<2>")
	)
	(segment
		(start 287.595056 -303.85893)
		(end 287.744154 -303.709832)
		(width 0.16002)
		(layer "In4.Cu")
		(net "M_D_CPU0_SB_DQS_DP<2>")
	)
	(segment
		(start 309.358538 -301.982632)
		(end 309.358538 -301.090076)
		(width 0.16002)
		(layer "In4.Cu")
		(net "M_D_CPU0_SB_DQS_DP<2>")
	)
	(segment
		(start 304.007012 -303.727104)
		(end 304.007012 -304.275744)
		(width 0.16002)
		(layer "In4.Cu")
		(net "M_D_CPU0_SB_DQS_DP<2>")
	)
	(segment
		(start 289.382454 -304.02911)
		(end 289.738054 -304.02911)
		(width 0.16002)
		(layer "In4.Cu")
		(net "M_D_CPU0_SB_DQS_DP<2>")
	)
	(segment
		(start 303.080166 -303.34331)
		(end 303.623218 -303.34331)
		(width 0.16002)
		(layer "In4.Cu")
		(net "M_D_CPU0_SB_DQS_DP<2>")
	)
	(segment
		(start 314.66028 -296.738294)
		(end 314.936632 -296.738294)
		(width 0.16002)
		(layer "In4.Cu")
		(net "M_D_CPU0_SB_DQS_DP<2>")
	)
	(segment
		(start 311.012586 -300.385734)
		(end 310.801512 -300.17466)
		(width 0.16002)
		(layer "In4.Cu")
		(net "M_D_CPU0_SB_DQS_DP<2>")
	)
	(segment
		(start 297.294554 -304.021998)
		(end 298.056554 -303.259998)
		(width 0.16002)
		(layer "In4.Cu")
		(net "M_D_CPU0_SB_DQS_DP<2>")
	)
	(segment
		(start 303.623218 -303.34331)
		(end 304.007012 -303.727104)
		(width 0.16002)
		(layer "In4.Cu")
		(net "M_D_CPU0_SB_DQS_DP<2>")
	)
	(segment
		(start 337.171284 -285.756096)
		(end 337.179666 -285.75127)
		(width 0.09525)
		(layer "In4.Cu")
		(net "M_D_CPU0_SB_DQS_DP<2>")
	)
	(segment
		(start 291.084254 -303.21631)
		(end 291.440616 -302.859948)
		(width 0.16002)
		(layer "In4.Cu")
		(net "M_D_CPU0_SB_DQS_DP<2>")
	)
	(segment
		(start 309.800752 -300.647862)
		(end 310.328056 -300.647862)
		(width 0.16002)
		(layer "In4.Cu")
		(net "M_D_CPU0_SB_DQS_DP<2>")
	)
	(segment
		(start 313.548776 -296.899838)
		(end 313.921648 -296.526966)
		(width 0.16002)
		(layer "In4.Cu")
		(net "M_D_CPU0_SB_DQS_DP<2>")
	)
	(segment
		(start 286.319468 -303.74209)
		(end 286.436308 -303.85893)
		(width 0.16002)
		(layer "In4.Cu")
		(net "M_D_CPU0_SB_DQS_DP<2>")
	)
	(segment
		(start 307.571648 -303.171098)
		(end 308.170072 -303.171098)
		(width 0.16002)
		(layer "In4.Cu")
		(net "M_D_CPU0_SB_DQS_DP<2>")
	)
	(segment
		(start 300.303946 -302.859948)
		(end 301.536608 -304.09261)
		(width 0.16002)
		(layer "In4.Cu")
		(net "M_D_CPU0_SB_DQS_DP<2>")
	)
	(segment
		(start 302.330866 -304.09261)
		(end 303.080166 -303.34331)
		(width 0.16002)
		(layer "In4.Cu")
		(net "M_D_CPU0_SB_DQS_DP<2>")
	)
	(segment
		(start 310.801512 -300.17466)
		(end 310.801512 -299.647102)
		(width 0.16002)
		(layer "In4.Cu")
		(net "M_D_CPU0_SB_DQS_DP<2>")
	)
	(segment
		(start 301.536608 -304.09261)
		(end 302.330866 -304.09261)
		(width 0.16002)
		(layer "In4.Cu")
		(net "M_D_CPU0_SB_DQS_DP<2>")
	)
	(segment
		(start 285.009844 -303.85893)
		(end 285.722568 -303.85893)
		(width 0.16002)
		(layer "In4.Cu")
		(net "M_D_CPU0_SB_DQS_DP<2>")
	)
	(segment
		(start 291.440616 -302.859948)
		(end 293.775892 -302.859948)
		(width 0.16002)
		(layer "In4.Cu")
		(net "M_D_CPU0_SB_DQS_DP<2>")
	)
	(segment
		(start 294.625776 -303.709832)
		(end 296.624248 -303.709832)
		(width 0.16002)
		(layer "In4.Cu")
		(net "M_D_CPU0_SB_DQS_DP<2>")
	)
	(segment
		(start 308.170072 -303.171098)
		(end 309.358538 -301.982632)
		(width 0.16002)
		(layer "In4.Cu")
		(net "M_D_CPU0_SB_DQS_DP<2>")
	)
	(segment
		(start 336.23123 -285.756096)
		(end 336.239612 -285.75127)
		(width 0.09525)
		(layer "In4.Cu")
		(net "M_D_CPU0_SB_DQS_DP<2>")
	)
	(segment
		(start 313.921648 -296.526966)
		(end 314.448952 -296.526966)
		(width 0.16002)
		(layer "In4.Cu")
		(net "M_D_CPU0_SB_DQS_DP<2>")
	)
	(segment
		(start 331.531214 -285.756096)
		(end 331.539596 -285.75127)
		(width 0.09525)
		(layer "In4.Cu")
		(net "M_D_CPU0_SB_DQS_DP<2>")
	)
	(segment
		(start 325.383144 -286.365442)
		(end 325.945754 -285.802832)
		(width 0.09525)
		(layer "In4.Cu")
		(net "M_D_CPU0_SB_DQS_DP<2>")
	)
	(segment
		(start 325.945754 -285.802832)
		(end 326.651112 -285.802832)
		(width 0.09525)
		(layer "In4.Cu")
		(net "M_D_CPU0_SB_DQS_DP<2>")
	)
	(segment
		(start 284.736032 -303.585118)
		(end 285.009844 -303.85893)
		(width 0.16002)
		(layer "In4.Cu")
		(net "M_D_CPU0_SB_DQS_DP<2>")
	)
	(segment
		(start 313.286648 -298.111926)
		(end 313.563 -298.111926)
		(width 0.16002)
		(layer "In4.Cu")
		(net "M_D_CPU0_SB_DQS_DP<2>")
	)
	(segment
		(start 298.939204 -302.859948)
		(end 300.303946 -302.859948)
		(width 0.16002)
		(layer "In4.Cu")
		(net "M_D_CPU0_SB_DQS_DP<2>")
	)
	(segment
		(start 310.801512 -299.647102)
		(end 311.174384 -299.27423)
		(width 0.16002)
		(layer "In4.Cu")
		(net "M_D_CPU0_SB_DQS_DP<2>")
	)
	(segment
		(start 327.392538 -285.745174)
		(end 327.402952 -285.75127)
		(width 0.09525)
		(layer "In4.Cu")
		(net "M_D_CPU0_SB_DQS_DP<2>")
	)
	(segment
		(start 306.974748 -303.054258)
		(end 307.454808 -303.054258)
		(width 0.16002)
		(layer "In4.Cu")
		(net "M_D_CPU0_SB_DQS_DP<2>")
	)
	(segment
		(start 306.857908 -303.171098)
		(end 306.974748 -303.054258)
		(width 0.16002)
		(layer "In4.Cu")
		(net "M_D_CPU0_SB_DQS_DP<2>")
	)
	(segment
		(start 312.386218 -299.012102)
		(end 312.175144 -298.801028)
		(width 0.16002)
		(layer "In4.Cu")
		(net "M_D_CPU0_SB_DQS_DP<2>")
	)
	(segment
		(start 313.07532 -297.900598)
		(end 313.286648 -298.111926)
		(width 0.16002)
		(layer "In4.Cu")
		(net "M_D_CPU0_SB_DQS_DP<2>")
	)
	(segment
		(start 313.75985 -297.915076)
		(end 313.75985 -297.63847)
		(width 0.16002)
		(layer "In4.Cu")
		(net "M_D_CPU0_SB_DQS_DP<2>")
	)
	(segment
		(start 298.539154 -303.259998)
		(end 298.939204 -302.859948)
		(width 0.16002)
		(layer "In4.Cu")
		(net "M_D_CPU0_SB_DQS_DP<2>")
	)
	(segment
		(start 323.996558 -286.535876)
		(end 324.166992 -286.365442)
		(width 0.09525)
		(layer "In4.Cu")
		(net "M_D_CPU0_SB_DQS_DP<2>")
	)
	(segment
		(start 328.711306 -285.756096)
		(end 328.719688 -285.75127)
		(width 0.09525)
		(layer "In4.Cu")
		(net "M_D_CPU0_SB_DQS_DP<2>")
	)
	(segment
		(start 313.75985 -297.63847)
		(end 313.548776 -297.427396)
		(width 0.16002)
		(layer "In4.Cu")
		(net "M_D_CPU0_SB_DQS_DP<2>")
	)
	(segment
		(start 310.328056 -300.647862)
		(end 310.539384 -300.85919)
		(width 0.16002)
		(layer "In4.Cu")
		(net "M_D_CPU0_SB_DQS_DP<2>")
	)
	(segment
		(start 289.063176 -303.709832)
		(end 289.382454 -304.02911)
		(width 0.16002)
		(layer "In4.Cu")
		(net "M_D_CPU0_SB_DQS_DP<2>")
	)
	(segment
		(start 307.454808 -303.054258)
		(end 307.571648 -303.171098)
		(width 0.16002)
		(layer "In4.Cu")
		(net "M_D_CPU0_SB_DQS_DP<2>")
	)
	(segment
		(start 339.001608 -285.778448)
		(end 339.024976 -285.69158)
		(width 0.09525)
		(layer "In4.Cu")
		(net "M_D_CPU0_SB_DQS_DP<2>")
	)
	(segment
		(start 315.133482 -296.264838)
		(end 314.922408 -296.053764)
		(width 0.16002)
		(layer "In4.Cu")
		(net "M_D_CPU0_SB_DQS_DP<2>")
	)
	(segment
		(start 324.166992 -286.365442)
		(end 325.383144 -286.365442)
		(width 0.09525)
		(layer "In4.Cu")
		(net "M_D_CPU0_SB_DQS_DP<2>")
	)
	(segment
		(start 333.982568 -285.75127)
		(end 333.99095 -285.756096)
		(width 0.09525)
		(layer "In4.Cu")
		(net "M_D_CPU0_SB_DQS_DP<2>")
	)
	(segment
		(start 323.895974 -286.55264)
		(end 323.912738 -286.535876)
		(width 0.09525)
		(layer "In4.Cu")
		(net "M_D_CPU0_SB_DQS_DP<2>")
	)
	(segment
		(start 309.358538 -301.090076)
		(end 309.800752 -300.647862)
		(width 0.16002)
		(layer "In4.Cu")
		(net "M_D_CPU0_SB_DQS_DP<2>")
	)
	(segment
		(start 329.282552 -285.75127)
		(end 329.290934 -285.756096)
		(width 0.09525)
		(layer "In4.Cu")
		(net "M_D_CPU0_SB_DQS_DP<2>")
	)
	(segment
		(start 311.913016 -299.485558)
		(end 312.189368 -299.485558)
		(width 0.16002)
		(layer "In4.Cu")
		(net "M_D_CPU0_SB_DQS_DP<2>")
	)
	(segment
		(start 315.133482 -296.541444)
		(end 315.133482 -296.264838)
		(width 0.16002)
		(layer "In4.Cu")
		(net "M_D_CPU0_SB_DQS_DP<2>")
	)
	(segment
		(start 298.056554 -303.259998)
		(end 298.539154 -303.259998)
		(width 0.16002)
		(layer "In4.Cu")
		(net "M_D_CPU0_SB_DQS_DP<2>")
	)
	(segment
		(start 314.922408 -296.053764)
		(end 314.922408 -295.526206)
		(width 0.16002)
		(layer "In4.Cu")
		(net "M_D_CPU0_SB_DQS_DP<2>")
	)
	(segment
		(start 311.701688 -299.27423)
		(end 311.913016 -299.485558)
		(width 0.16002)
		(layer "In4.Cu")
		(net "M_D_CPU0_SB_DQS_DP<2>")
	)
	(segment
		(start 311.012586 -300.66234)
		(end 311.012586 -300.385734)
		(width 0.16002)
		(layer "In4.Cu")
		(net "M_D_CPU0_SB_DQS_DP<2>")
	)
	(segment
		(start 337.74253 -285.75127)
		(end 337.750912 -285.756096)
		(width 0.09525)
		(layer "In4.Cu")
		(net "M_D_CPU0_SB_DQS_DP<2>")
	)
	(segment
		(start 293.775892 -302.859948)
		(end 294.625776 -303.709832)
		(width 0.16002)
		(layer "In4.Cu")
		(net "M_D_CPU0_SB_DQS_DP<2>")
	)
	(segment
		(start 327.779888 -285.75127)
		(end 327.790302 -285.745174)
		(width 0.09525)
		(layer "In4.Cu")
		(net "M_D_CPU0_SB_DQS_DP<2>")
	)
	(segment
		(start 289.738054 -304.02911)
		(end 290.550854 -303.21631)
		(width 0.16002)
		(layer "In4.Cu")
		(net "M_D_CPU0_SB_DQS_DP<2>")
	)
	(segment
		(start 323.912738 -286.535876)
		(end 323.996558 -286.535876)
		(width 0.09525)
		(layer "In4.Cu")
		(net "M_D_CPU0_SB_DQS_DP<2>")
	)
	(segment
		(start 296.624248 -303.709832)
		(end 296.936414 -304.021998)
		(width 0.16002)
		(layer "In4.Cu")
		(net "M_D_CPU0_SB_DQS_DP<2>")
	)
	(segment
		(start 312.189368 -299.485558)
		(end 312.386218 -299.288708)
		(width 0.16002)
		(layer "In4.Cu")
		(net "M_D_CPU0_SB_DQS_DP<2>")
	)
	(segment
		(start 333.042514 -285.75127)
		(end 333.050896 -285.756096)
		(width 0.09525)
		(layer "In4.Cu")
		(net "M_D_CPU0_SB_DQS_DP<2>")
	)
	(segment
		(start 304.007012 -304.275744)
		(end 304.204878 -304.47361)
		(width 0.16002)
		(layer "In4.Cu")
		(net "M_D_CPU0_SB_DQS_DP<2>")
	)
	(segment
		(start 311.174384 -299.27423)
		(end 311.701688 -299.27423)
		(width 0.16002)
		(layer "In4.Cu")
		(net "M_D_CPU0_SB_DQS_DP<2>")
	)
	(segment
		(start 304.204878 -304.47361)
		(end 304.440082 -304.47361)
		(width 0.16002)
		(layer "In4.Cu")
		(net "M_D_CPU0_SB_DQS_DP<2>")
	)
	(segment
		(start 286.436308 -303.85893)
		(end 287.595056 -303.85893)
		(width 0.16002)
		(layer "In4.Cu")
		(net "M_D_CPU0_SB_DQS_DP<2>")
	)
	(segment
		(start 314.922408 -295.526206)
		(end 323.895974 -286.55264)
		(width 0.16002)
		(layer "In4.Cu")
		(net "M_D_CPU0_SB_DQS_DP<2>")
	)
	(segment
		(start 338.682584 -285.75127)
		(end 338.690966 -285.756096)
		(width 0.09525)
		(layer "In4.Cu")
		(net "M_D_CPU0_SB_DQS_DP<2>")
	)
	(segment
		(start 314.448952 -296.526966)
		(end 314.66028 -296.738294)
		(width 0.16002)
		(layer "In4.Cu")
		(net "M_D_CPU0_SB_DQS_DP<2>")
	)
	(segment
		(start 339.024976 -285.69158)
		(end 338.871052 -285.42615)
		(width 0.09525)
		(layer "In4.Cu")
		(net "M_D_CPU0_SB_DQS_DP<2>")
	)
	(segment
		(start 332.471268 -285.756096)
		(end 332.47965 -285.75127)
		(width 0.09525)
		(layer "In4.Cu")
		(net "M_D_CPU0_SB_DQS_DP<2>")
	)
	(segment
		(start 312.548016 -297.900598)
		(end 313.07532 -297.900598)
		(width 0.16002)
		(layer "In4.Cu")
		(net "M_D_CPU0_SB_DQS_DP<2>")
	)
	(segment
		(start 296.936414 -304.021998)
		(end 297.294554 -304.021998)
		(width 0.16002)
		(layer "In4.Cu")
		(net "M_D_CPU0_SB_DQS_DP<2>")
	)
	(segment
		(start 287.744154 -303.709832)
		(end 289.063176 -303.709832)
		(width 0.16002)
		(layer "In4.Cu")
		(net "M_D_CPU0_SB_DQS_DP<2>")
	)
	(segment
		(start 312.386218 -299.288708)
		(end 312.386218 -299.012102)
		(width 0.16002)
		(layer "In4.Cu")
		(net "M_D_CPU0_SB_DQS_DP<2>")
	)
	(segment
		(start 310.815736 -300.85919)
		(end 311.012586 -300.66234)
		(width 0.16002)
		(layer "In4.Cu")
		(net "M_D_CPU0_SB_DQS_DP<2>")
	)
	(segment
		(start 312.175144 -298.27347)
		(end 312.548016 -297.900598)
		(width 0.16002)
		(layer "In4.Cu")
		(net "M_D_CPU0_SB_DQS_DP<2>")
	)
	(segment
		(start 285.839408 -303.74209)
		(end 286.319468 -303.74209)
		(width 0.16002)
		(layer "In4.Cu")
		(net "M_D_CPU0_SB_DQS_DP<2>")
	)
	(segment
		(start 314.936632 -296.738294)
		(end 315.133482 -296.541444)
		(width 0.16002)
		(layer "In4.Cu")
		(net "M_D_CPU0_SB_DQS_DP<2>")
	)
	(segment
		(start 305.742594 -303.171098)
		(end 306.857908 -303.171098)
		(width 0.16002)
		(layer "In4.Cu")
		(net "M_D_CPU0_SB_DQS_DP<2>")
	)
	(segment
		(start 312.175144 -298.801028)
		(end 312.175144 -298.27347)
		(width 0.16002)
		(layer "In4.Cu")
		(net "M_D_CPU0_SB_DQS_DP<2>")
	)
	(segment
		(start 285.722568 -303.85893)
		(end 285.839408 -303.74209)
		(width 0.16002)
		(layer "In4.Cu")
		(net "M_D_CPU0_SB_DQS_DP<2>")
	)
	(segment
		(start 304.440082 -304.47361)
		(end 305.742594 -303.171098)
		(width 0.16002)
		(layer "In4.Cu")
		(net "M_D_CPU0_SB_DQS_DP<2>")
	)
	(segment
		(start 290.550854 -303.21631)
		(end 291.084254 -303.21631)
		(width 0.16002)
		(layer "In4.Cu")
		(net "M_D_CPU0_SB_DQS_DP<2>")
	)
	(arc
		(start 330.222606 -285.75127)
		(mid 330.411074 -285.801947)
		(end 330.599542 -285.75127)
		(width 0.09525)
		(layer "In4.Cu")
		(net "M_D_CPU0_SB_DQS_DP<2>")
	)
	(arc
		(start 334.922622 -285.75127)
		(mid 335.11109 -285.801947)
		(end 335.299558 -285.75127)
		(width 0.09525)
		(layer "In4.Cu")
		(net "M_D_CPU0_SB_DQS_DP<2>")
	)
	(arc
		(start 336.239612 -285.75127)
		(mid 336.521044 -285.675515)
		(end 336.802476 -285.75127)
		(width 0.09525)
		(layer "In4.Cu")
		(net "M_D_CPU0_SB_DQS_DP<2>")
	)
	(arc
		(start 331.539596 -285.75127)
		(mid 331.821028 -285.675515)
		(end 332.10246 -285.75127)
		(width 0.09525)
		(layer "In4.Cu")
		(net "M_D_CPU0_SB_DQS_DP<2>")
	)
	(arc
		(start 337.750912 -285.756096)
		(mid 337.935944 -285.80201)
		(end 338.11972 -285.75127)
		(width 0.09525)
		(layer "In4.Cu")
		(net "M_D_CPU0_SB_DQS_DP<2>")
	)
	(arc
		(start 333.419704 -285.75127)
		(mid 333.701136 -285.675515)
		(end 333.982568 -285.75127)
		(width 0.09525)
		(layer "In4.Cu")
		(net "M_D_CPU0_SB_DQS_DP<2>")
	)
	(arc
		(start 326.651112 -285.802832)
		(mid 326.748868 -285.789498)
		(end 326.839834 -285.75127)
		(width 0.09525)
		(layer "In4.Cu")
		(net "M_D_CPU0_SB_DQS_DP<2>")
	)
	(arc
		(start 326.839834 -285.75127)
		(mid 327.115377 -285.675421)
		(end 327.392538 -285.745174)
		(width 0.09525)
		(layer "In4.Cu")
		(net "M_D_CPU0_SB_DQS_DP<2>")
	)
	(arc
		(start 338.11972 -285.75127)
		(mid 338.401152 -285.675515)
		(end 338.682584 -285.75127)
		(width 0.09525)
		(layer "In4.Cu")
		(net "M_D_CPU0_SB_DQS_DP<2>")
	)
	(arc
		(start 329.290934 -285.756096)
		(mid 329.475966 -285.80201)
		(end 329.659742 -285.75127)
		(width 0.09525)
		(layer "In4.Cu")
		(net "M_D_CPU0_SB_DQS_DP<2>")
	)
	(arc
		(start 329.659742 -285.75127)
		(mid 329.941174 -285.675515)
		(end 330.222606 -285.75127)
		(width 0.09525)
		(layer "In4.Cu")
		(net "M_D_CPU0_SB_DQS_DP<2>")
	)
	(arc
		(start 330.599542 -285.75127)
		(mid 330.880974 -285.675515)
		(end 331.162406 -285.75127)
		(width 0.09525)
		(layer "In4.Cu")
		(net "M_D_CPU0_SB_DQS_DP<2>")
	)
	(arc
		(start 327.402952 -285.75127)
		(mid 327.59142 -285.801947)
		(end 327.779888 -285.75127)
		(width 0.09525)
		(layer "In4.Cu")
		(net "M_D_CPU0_SB_DQS_DP<2>")
	)
	(arc
		(start 332.47965 -285.75127)
		(mid 332.761082 -285.675515)
		(end 333.042514 -285.75127)
		(width 0.09525)
		(layer "In4.Cu")
		(net "M_D_CPU0_SB_DQS_DP<2>")
	)
	(arc
		(start 328.342498 -285.75127)
		(mid 328.526273 -285.802042)
		(end 328.711306 -285.756096)
		(width 0.09525)
		(layer "In4.Cu")
		(net "M_D_CPU0_SB_DQS_DP<2>")
	)
	(arc
		(start 328.719688 -285.75127)
		(mid 329.00112 -285.675515)
		(end 329.282552 -285.75127)
		(width 0.09525)
		(layer "In4.Cu")
		(net "M_D_CPU0_SB_DQS_DP<2>")
	)
	(arc
		(start 331.162406 -285.75127)
		(mid 331.346181 -285.802042)
		(end 331.531214 -285.756096)
		(width 0.09525)
		(layer "In4.Cu")
		(net "M_D_CPU0_SB_DQS_DP<2>")
	)
	(arc
		(start 335.862422 -285.75127)
		(mid 336.046197 -285.802042)
		(end 336.23123 -285.756096)
		(width 0.09525)
		(layer "In4.Cu")
		(net "M_D_CPU0_SB_DQS_DP<2>")
	)
	(arc
		(start 332.10246 -285.75127)
		(mid 332.286235 -285.802042)
		(end 332.471268 -285.756096)
		(width 0.09525)
		(layer "In4.Cu")
		(net "M_D_CPU0_SB_DQS_DP<2>")
	)
	(arc
		(start 336.802476 -285.75127)
		(mid 336.986251 -285.802042)
		(end 337.171284 -285.756096)
		(width 0.09525)
		(layer "In4.Cu")
		(net "M_D_CPU0_SB_DQS_DP<2>")
	)
	(arc
		(start 335.299558 -285.75127)
		(mid 335.58099 -285.675515)
		(end 335.862422 -285.75127)
		(width 0.09525)
		(layer "In4.Cu")
		(net "M_D_CPU0_SB_DQS_DP<2>")
	)
	(arc
		(start 337.179666 -285.75127)
		(mid 337.461098 -285.675515)
		(end 337.74253 -285.75127)
		(width 0.09525)
		(layer "In4.Cu")
		(net "M_D_CPU0_SB_DQS_DP<2>")
	)
	(arc
		(start 333.99095 -285.756096)
		(mid 334.175982 -285.80201)
		(end 334.359758 -285.75127)
		(width 0.09525)
		(layer "In4.Cu")
		(net "M_D_CPU0_SB_DQS_DP<2>")
	)
	(arc
		(start 338.690966 -285.756096)
		(mid 338.843861 -285.800924)
		(end 339.001608 -285.778448)
		(width 0.09525)
		(layer "In4.Cu")
		(net "M_D_CPU0_SB_DQS_DP<2>")
	)
	(arc
		(start 327.790302 -285.745174)
		(mid 328.06721 -285.675497)
		(end 328.342498 -285.75127)
		(width 0.09525)
		(layer "In4.Cu")
		(net "M_D_CPU0_SB_DQS_DP<2>")
	)
	(arc
		(start 333.050896 -285.756096)
		(mid 333.235928 -285.80201)
		(end 333.419704 -285.75127)
		(width 0.09525)
		(layer "In4.Cu")
		(net "M_D_CPU0_SB_DQS_DP<2>")
	)
	(arc
		(start 334.359758 -285.75127)
		(mid 334.64119 -285.675515)
		(end 334.922622 -285.75127)
		(width 0.09525)
		(layer "In4.Cu")
		(net "M_D_CPU0_SB_DQS_DP<2>")
	)
	(segment
		(start 339.337904 -280.300176)
		(end 338.871052 -280.566114)
		(width 0.12954)
		(layer "F.Cu")
		(net "M_D_CPU0_SB_DQS_DP<1>")
	)
	(segment
		(start 317.029592 -284.182058)
		(end 317.556896 -284.182058)
		(width 0.16002)
		(layer "In4.Cu")
		(net "M_D_CPU0_SB_DQS_DP<1>")
	)
	(segment
		(start 329.282552 -280.891234)
		(end 329.290934 -280.89606)
		(width 0.09525)
		(layer "In4.Cu")
		(net "M_D_CPU0_SB_DQS_DP<1>")
	)
	(segment
		(start 293.163752 -293.509954)
		(end 294.013636 -294.359838)
		(width 0.16002)
		(layer "In4.Cu")
		(net "M_D_CPU0_SB_DQS_DP<1>")
	)
	(segment
		(start 286.261048 -294.392096)
		(end 286.377888 -294.508936)
		(width 0.16002)
		(layer "In4.Cu")
		(net "M_D_CPU0_SB_DQS_DP<1>")
	)
	(segment
		(start 317.556896 -284.182058)
		(end 317.735966 -284.361128)
		(width 0.16002)
		(layer "In4.Cu")
		(net "M_D_CPU0_SB_DQS_DP<1>")
	)
	(segment
		(start 289.034982 -294.359838)
		(end 289.3949 -294.719756)
		(width 0.16002)
		(layer "In4.Cu")
		(net "M_D_CPU0_SB_DQS_DP<1>")
	)
	(segment
		(start 284.736032 -294.235124)
		(end 285.009844 -294.508936)
		(width 0.16002)
		(layer "In4.Cu")
		(net "M_D_CPU0_SB_DQS_DP<1>")
	)
	(segment
		(start 297.294554 -294.672004)
		(end 298.056554 -293.910004)
		(width 0.16002)
		(layer "In4.Cu")
		(net "M_D_CPU0_SB_DQS_DP<1>")
	)
	(segment
		(start 319.403222 -281.808428)
		(end 319.776856 -281.434794)
		(width 0.16002)
		(layer "In4.Cu")
		(net "M_D_CPU0_SB_DQS_DP<1>")
	)
	(segment
		(start 318.012826 -284.361128)
		(end 318.20866 -284.165294)
		(width 0.16002)
		(layer "In4.Cu")
		(net "M_D_CPU0_SB_DQS_DP<1>")
	)
	(segment
		(start 327.392538 -280.885138)
		(end 327.402952 -280.891234)
		(width 0.09525)
		(layer "In4.Cu")
		(net "M_D_CPU0_SB_DQS_DP<1>")
	)
	(segment
		(start 291.49421 -293.509954)
		(end 293.163752 -293.509954)
		(width 0.16002)
		(layer "In4.Cu")
		(net "M_D_CPU0_SB_DQS_DP<1>")
	)
	(segment
		(start 328.711306 -280.89606)
		(end 328.719688 -280.891234)
		(width 0.09525)
		(layer "In4.Cu")
		(net "M_D_CPU0_SB_DQS_DP<1>")
	)
	(segment
		(start 318.403224 -282.808426)
		(end 318.930528 -282.808426)
		(width 0.16002)
		(layer "In4.Cu")
		(net "M_D_CPU0_SB_DQS_DP<1>")
	)
	(segment
		(start 298.056554 -293.910004)
		(end 298.539154 -293.910004)
		(width 0.16002)
		(layer "In4.Cu")
		(net "M_D_CPU0_SB_DQS_DP<1>")
	)
	(segment
		(start 333.982568 -280.891234)
		(end 333.99095 -280.89606)
		(width 0.09525)
		(layer "In4.Cu")
		(net "M_D_CPU0_SB_DQS_DP<1>")
	)
	(segment
		(start 324.722236 -280.535634)
		(end 326.088756 -280.535634)
		(width 0.09525)
		(layer "In4.Cu")
		(net "M_D_CPU0_SB_DQS_DP<1>")
	)
	(segment
		(start 324.154546 -280.839164)
		(end 324.418706 -280.839164)
		(width 0.09525)
		(layer "In4.Cu")
		(net "M_D_CPU0_SB_DQS_DP<1>")
	)
	(segment
		(start 316.655958 -285.082996)
		(end 316.655958 -284.555692)
		(width 0.16002)
		(layer "In4.Cu")
		(net "M_D_CPU0_SB_DQS_DP<1>")
	)
	(segment
		(start 315.282326 -285.929324)
		(end 315.65596 -285.55569)
		(width 0.16002)
		(layer "In4.Cu")
		(net "M_D_CPU0_SB_DQS_DP<1>")
	)
	(segment
		(start 287.38322 -294.359838)
		(end 289.034982 -294.359838)
		(width 0.16002)
		(layer "In4.Cu")
		(net "M_D_CPU0_SB_DQS_DP<1>")
	)
	(segment
		(start 289.700208 -294.719756)
		(end 290.550854 -293.86911)
		(width 0.16002)
		(layer "In4.Cu")
		(net "M_D_CPU0_SB_DQS_DP<1>")
	)
	(segment
		(start 298.539154 -293.910004)
		(end 298.939204 -293.509954)
		(width 0.16002)
		(layer "In4.Cu")
		(net "M_D_CPU0_SB_DQS_DP<1>")
	)
	(segment
		(start 315.265562 -287.108392)
		(end 315.461396 -286.912558)
		(width 0.16002)
		(layer "In4.Cu")
		(net "M_D_CPU0_SB_DQS_DP<1>")
	)
	(segment
		(start 313.908694 -287.302956)
		(end 314.282328 -286.929322)
		(width 0.16002)
		(layer "In4.Cu")
		(net "M_D_CPU0_SB_DQS_DP<1>")
	)
	(segment
		(start 319.582292 -282.791662)
		(end 319.582292 -282.514802)
		(width 0.16002)
		(layer "In4.Cu")
		(net "M_D_CPU0_SB_DQS_DP<1>")
	)
	(segment
		(start 326.462898 -280.891234)
		(end 326.474836 -280.898092)
		(width 0.09525)
		(layer "In4.Cu")
		(net "M_D_CPU0_SB_DQS_DP<1>")
	)
	(segment
		(start 338.682584 -280.891234)
		(end 338.690966 -280.89606)
		(width 0.09525)
		(layer "In4.Cu")
		(net "M_D_CPU0_SB_DQS_DP<1>")
	)
	(segment
		(start 318.02959 -283.709364)
		(end 318.02959 -283.18206)
		(width 0.16002)
		(layer "In4.Cu")
		(net "M_D_CPU0_SB_DQS_DP<1>")
	)
	(segment
		(start 326.088756 -280.535634)
		(end 326.385174 -280.832052)
		(width 0.09525)
		(layer "In4.Cu")
		(net "M_D_CPU0_SB_DQS_DP<1>")
	)
	(segment
		(start 314.282328 -286.929322)
		(end 314.809632 -286.929322)
		(width 0.16002)
		(layer "In4.Cu")
		(net "M_D_CPU0_SB_DQS_DP<1>")
	)
	(segment
		(start 339.024976 -280.831544)
		(end 338.871052 -280.566114)
		(width 0.09525)
		(layer "In4.Cu")
		(net "M_D_CPU0_SB_DQS_DP<1>")
	)
	(segment
		(start 315.65596 -285.55569)
		(end 316.183264 -285.55569)
		(width 0.16002)
		(layer "In4.Cu")
		(net "M_D_CPU0_SB_DQS_DP<1>")
	)
	(segment
		(start 327.779888 -280.891234)
		(end 327.790302 -280.885138)
		(width 0.09525)
		(layer "In4.Cu")
		(net "M_D_CPU0_SB_DQS_DP<1>")
	)
	(segment
		(start 285.664148 -294.508936)
		(end 285.780988 -294.392096)
		(width 0.16002)
		(layer "In4.Cu")
		(net "M_D_CPU0_SB_DQS_DP<1>")
	)
	(segment
		(start 336.23123 -280.89606)
		(end 336.239612 -280.891234)
		(width 0.09525)
		(layer "In4.Cu")
		(net "M_D_CPU0_SB_DQS_DP<1>")
	)
	(segment
		(start 290.550854 -293.86911)
		(end 291.135054 -293.86911)
		(width 0.16002)
		(layer "In4.Cu")
		(net "M_D_CPU0_SB_DQS_DP<1>")
	)
	(segment
		(start 314.087764 -288.28619)
		(end 314.087764 -288.00933)
		(width 0.16002)
		(layer "In4.Cu")
		(net "M_D_CPU0_SB_DQS_DP<1>")
	)
	(segment
		(start 313.908694 -287.83026)
		(end 313.908694 -287.302956)
		(width 0.16002)
		(layer "In4.Cu")
		(net "M_D_CPU0_SB_DQS_DP<1>")
	)
	(segment
		(start 316.835028 -285.538926)
		(end 316.835028 -285.262066)
		(width 0.16002)
		(layer "In4.Cu")
		(net "M_D_CPU0_SB_DQS_DP<1>")
	)
	(segment
		(start 320.48323 -281.613864)
		(end 320.76009 -281.613864)
		(width 0.16002)
		(layer "In4.Cu")
		(net "M_D_CPU0_SB_DQS_DP<1>")
	)
	(segment
		(start 304.825654 -294.684704)
		(end 305.689254 -293.821104)
		(width 0.16002)
		(layer "In4.Cu")
		(net "M_D_CPU0_SB_DQS_DP<1>")
	)
	(segment
		(start 321.593972 -280.779982)
		(end 324.071742 -280.779982)
		(width 0.16002)
		(layer "In4.Cu")
		(net "M_D_CPU0_SB_DQS_DP<1>")
	)
	(segment
		(start 317.735966 -284.361128)
		(end 318.012826 -284.361128)
		(width 0.16002)
		(layer "In4.Cu")
		(net "M_D_CPU0_SB_DQS_DP<1>")
	)
	(segment
		(start 315.282326 -286.456628)
		(end 315.282326 -285.929324)
		(width 0.16002)
		(layer "In4.Cu")
		(net "M_D_CPU0_SB_DQS_DP<1>")
	)
	(segment
		(start 318.02959 -283.18206)
		(end 318.403224 -282.808426)
		(width 0.16002)
		(layer "In4.Cu")
		(net "M_D_CPU0_SB_DQS_DP<1>")
	)
	(segment
		(start 287.234122 -294.508936)
		(end 287.38322 -294.359838)
		(width 0.16002)
		(layer "In4.Cu")
		(net "M_D_CPU0_SB_DQS_DP<1>")
	)
	(segment
		(start 320.30416 -281.434794)
		(end 320.48323 -281.613864)
		(width 0.16002)
		(layer "In4.Cu")
		(net "M_D_CPU0_SB_DQS_DP<1>")
	)
	(segment
		(start 294.013636 -294.359838)
		(end 296.59326 -294.359838)
		(width 0.16002)
		(layer "In4.Cu")
		(net "M_D_CPU0_SB_DQS_DP<1>")
	)
	(segment
		(start 314.809632 -286.929322)
		(end 314.988702 -287.108392)
		(width 0.16002)
		(layer "In4.Cu")
		(net "M_D_CPU0_SB_DQS_DP<1>")
	)
	(segment
		(start 316.639194 -285.73476)
		(end 316.835028 -285.538926)
		(width 0.16002)
		(layer "In4.Cu")
		(net "M_D_CPU0_SB_DQS_DP<1>")
	)
	(segment
		(start 319.776856 -281.434794)
		(end 320.30416 -281.434794)
		(width 0.16002)
		(layer "In4.Cu")
		(net "M_D_CPU0_SB_DQS_DP<1>")
	)
	(segment
		(start 318.930528 -282.808426)
		(end 319.109598 -282.987496)
		(width 0.16002)
		(layer "In4.Cu")
		(net "M_D_CPU0_SB_DQS_DP<1>")
	)
	(segment
		(start 319.403222 -282.335732)
		(end 319.403222 -281.808428)
		(width 0.16002)
		(layer "In4.Cu")
		(net "M_D_CPU0_SB_DQS_DP<1>")
	)
	(segment
		(start 316.362334 -285.73476)
		(end 316.639194 -285.73476)
		(width 0.16002)
		(layer "In4.Cu")
		(net "M_D_CPU0_SB_DQS_DP<1>")
	)
	(segment
		(start 286.377888 -294.508936)
		(end 287.234122 -294.508936)
		(width 0.16002)
		(layer "In4.Cu")
		(net "M_D_CPU0_SB_DQS_DP<1>")
	)
	(segment
		(start 291.135054 -293.86911)
		(end 291.49421 -293.509954)
		(width 0.16002)
		(layer "In4.Cu")
		(net "M_D_CPU0_SB_DQS_DP<1>")
	)
	(segment
		(start 319.582292 -282.514802)
		(end 319.403222 -282.335732)
		(width 0.16002)
		(layer "In4.Cu")
		(net "M_D_CPU0_SB_DQS_DP<1>")
	)
	(segment
		(start 285.009844 -294.508936)
		(end 285.664148 -294.508936)
		(width 0.16002)
		(layer "In4.Cu")
		(net "M_D_CPU0_SB_DQS_DP<1>")
	)
	(segment
		(start 316.183264 -285.55569)
		(end 316.362334 -285.73476)
		(width 0.16002)
		(layer "In4.Cu")
		(net "M_D_CPU0_SB_DQS_DP<1>")
	)
	(segment
		(start 296.905426 -294.672004)
		(end 297.294554 -294.672004)
		(width 0.16002)
		(layer "In4.Cu")
		(net "M_D_CPU0_SB_DQS_DP<1>")
	)
	(segment
		(start 314.988702 -287.108392)
		(end 315.265562 -287.108392)
		(width 0.16002)
		(layer "In4.Cu")
		(net "M_D_CPU0_SB_DQS_DP<1>")
	)
	(segment
		(start 298.939204 -293.509954)
		(end 300.293024 -293.509954)
		(width 0.16002)
		(layer "In4.Cu")
		(net "M_D_CPU0_SB_DQS_DP<1>")
	)
	(segment
		(start 337.74253 -280.891234)
		(end 337.750912 -280.89606)
		(width 0.09525)
		(layer "In4.Cu")
		(net "M_D_CPU0_SB_DQS_DP<1>")
	)
	(segment
		(start 300.293024 -293.509954)
		(end 301.467774 -294.684704)
		(width 0.16002)
		(layer "In4.Cu")
		(net "M_D_CPU0_SB_DQS_DP<1>")
	)
	(segment
		(start 289.3949 -294.719756)
		(end 289.700208 -294.719756)
		(width 0.16002)
		(layer "In4.Cu")
		(net "M_D_CPU0_SB_DQS_DP<1>")
	)
	(segment
		(start 319.109598 -282.987496)
		(end 319.386458 -282.987496)
		(width 0.16002)
		(layer "In4.Cu")
		(net "M_D_CPU0_SB_DQS_DP<1>")
	)
	(segment
		(start 315.461396 -286.912558)
		(end 315.461396 -286.635698)
		(width 0.16002)
		(layer "In4.Cu")
		(net "M_D_CPU0_SB_DQS_DP<1>")
	)
	(segment
		(start 319.386458 -282.987496)
		(end 319.582292 -282.791662)
		(width 0.16002)
		(layer "In4.Cu")
		(net "M_D_CPU0_SB_DQS_DP<1>")
	)
	(segment
		(start 333.042514 -280.891234)
		(end 333.050896 -280.89606)
		(width 0.09525)
		(layer "In4.Cu")
		(net "M_D_CPU0_SB_DQS_DP<1>")
	)
	(segment
		(start 316.655958 -284.555692)
		(end 317.029592 -284.182058)
		(width 0.16002)
		(layer "In4.Cu")
		(net "M_D_CPU0_SB_DQS_DP<1>")
	)
	(segment
		(start 308.55285 -293.821104)
		(end 314.087764 -288.28619)
		(width 0.16002)
		(layer "In4.Cu")
		(net "M_D_CPU0_SB_DQS_DP<1>")
	)
	(segment
		(start 337.171284 -280.89606)
		(end 337.179666 -280.891234)
		(width 0.09525)
		(layer "In4.Cu")
		(net "M_D_CPU0_SB_DQS_DP<1>")
	)
	(segment
		(start 301.467774 -294.684704)
		(end 304.825654 -294.684704)
		(width 0.16002)
		(layer "In4.Cu")
		(net "M_D_CPU0_SB_DQS_DP<1>")
	)
	(segment
		(start 305.689254 -293.821104)
		(end 308.55285 -293.821104)
		(width 0.16002)
		(layer "In4.Cu")
		(net "M_D_CPU0_SB_DQS_DP<1>")
	)
	(segment
		(start 318.20866 -284.165294)
		(end 318.20866 -283.888434)
		(width 0.16002)
		(layer "In4.Cu")
		(net "M_D_CPU0_SB_DQS_DP<1>")
	)
	(segment
		(start 318.20866 -283.888434)
		(end 318.02959 -283.709364)
		(width 0.16002)
		(layer "In4.Cu")
		(net "M_D_CPU0_SB_DQS_DP<1>")
	)
	(segment
		(start 285.780988 -294.392096)
		(end 286.261048 -294.392096)
		(width 0.16002)
		(layer "In4.Cu")
		(net "M_D_CPU0_SB_DQS_DP<1>")
	)
	(segment
		(start 339.001608 -280.918412)
		(end 339.024976 -280.831544)
		(width 0.09525)
		(layer "In4.Cu")
		(net "M_D_CPU0_SB_DQS_DP<1>")
	)
	(segment
		(start 324.418706 -280.839164)
		(end 324.722236 -280.535634)
		(width 0.09525)
		(layer "In4.Cu")
		(net "M_D_CPU0_SB_DQS_DP<1>")
	)
	(segment
		(start 331.531214 -280.89606)
		(end 331.539596 -280.891234)
		(width 0.09525)
		(layer "In4.Cu")
		(net "M_D_CPU0_SB_DQS_DP<1>")
	)
	(segment
		(start 315.461396 -286.635698)
		(end 315.282326 -286.456628)
		(width 0.16002)
		(layer "In4.Cu")
		(net "M_D_CPU0_SB_DQS_DP<1>")
	)
	(segment
		(start 332.471268 -280.89606)
		(end 332.47965 -280.891234)
		(width 0.09525)
		(layer "In4.Cu")
		(net "M_D_CPU0_SB_DQS_DP<1>")
	)
	(segment
		(start 324.071742 -280.779982)
		(end 324.095364 -280.779982)
		(width 0.09525)
		(layer "In4.Cu")
		(net "M_D_CPU0_SB_DQS_DP<1>")
	)
	(segment
		(start 296.59326 -294.359838)
		(end 296.905426 -294.672004)
		(width 0.16002)
		(layer "In4.Cu")
		(net "M_D_CPU0_SB_DQS_DP<1>")
	)
	(segment
		(start 320.76009 -281.613864)
		(end 321.593972 -280.779982)
		(width 0.16002)
		(layer "In4.Cu")
		(net "M_D_CPU0_SB_DQS_DP<1>")
	)
	(segment
		(start 316.835028 -285.262066)
		(end 316.655958 -285.082996)
		(width 0.16002)
		(layer "In4.Cu")
		(net "M_D_CPU0_SB_DQS_DP<1>")
	)
	(segment
		(start 324.095364 -280.779982)
		(end 324.154546 -280.839164)
		(width 0.09525)
		(layer "In4.Cu")
		(net "M_D_CPU0_SB_DQS_DP<1>")
	)
	(segment
		(start 314.087764 -288.00933)
		(end 313.908694 -287.83026)
		(width 0.16002)
		(layer "In4.Cu")
		(net "M_D_CPU0_SB_DQS_DP<1>")
	)
	(arc
		(start 336.802476 -280.891234)
		(mid 336.986251 -280.942006)
		(end 337.171284 -280.89606)
		(width 0.09525)
		(layer "In4.Cu")
		(net "M_D_CPU0_SB_DQS_DP<1>")
	)
	(arc
		(start 338.11972 -280.891234)
		(mid 338.401152 -280.815479)
		(end 338.682584 -280.891234)
		(width 0.09525)
		(layer "In4.Cu")
		(net "M_D_CPU0_SB_DQS_DP<1>")
	)
	(arc
		(start 330.222606 -280.891234)
		(mid 330.411074 -280.941911)
		(end 330.599542 -280.891234)
		(width 0.09525)
		(layer "In4.Cu")
		(net "M_D_CPU0_SB_DQS_DP<1>")
	)
	(arc
		(start 326.385174 -280.832052)
		(mid 326.422105 -280.864179)
		(end 326.462898 -280.891234)
		(width 0.09525)
		(layer "In4.Cu")
		(net "M_D_CPU0_SB_DQS_DP<1>")
	)
	(arc
		(start 337.179666 -280.891234)
		(mid 337.461098 -280.815479)
		(end 337.74253 -280.891234)
		(width 0.09525)
		(layer "In4.Cu")
		(net "M_D_CPU0_SB_DQS_DP<1>")
	)
	(arc
		(start 331.162406 -280.891234)
		(mid 331.346181 -280.942006)
		(end 331.531214 -280.89606)
		(width 0.09525)
		(layer "In4.Cu")
		(net "M_D_CPU0_SB_DQS_DP<1>")
	)
	(arc
		(start 330.599542 -280.891234)
		(mid 330.880974 -280.815479)
		(end 331.162406 -280.891234)
		(width 0.09525)
		(layer "In4.Cu")
		(net "M_D_CPU0_SB_DQS_DP<1>")
	)
	(arc
		(start 337.750912 -280.89606)
		(mid 337.935944 -280.941974)
		(end 338.11972 -280.891234)
		(width 0.09525)
		(layer "In4.Cu")
		(net "M_D_CPU0_SB_DQS_DP<1>")
	)
	(arc
		(start 335.862422 -280.891234)
		(mid 336.046197 -280.942006)
		(end 336.23123 -280.89606)
		(width 0.09525)
		(layer "In4.Cu")
		(net "M_D_CPU0_SB_DQS_DP<1>")
	)
	(arc
		(start 327.402952 -280.891234)
		(mid 327.59142 -280.941911)
		(end 327.779888 -280.891234)
		(width 0.09525)
		(layer "In4.Cu")
		(net "M_D_CPU0_SB_DQS_DP<1>")
	)
	(arc
		(start 328.719688 -280.891234)
		(mid 329.00112 -280.815479)
		(end 329.282552 -280.891234)
		(width 0.09525)
		(layer "In4.Cu")
		(net "M_D_CPU0_SB_DQS_DP<1>")
	)
	(arc
		(start 338.690966 -280.89606)
		(mid 338.843861 -280.940888)
		(end 339.001608 -280.918412)
		(width 0.09525)
		(layer "In4.Cu")
		(net "M_D_CPU0_SB_DQS_DP<1>")
	)
	(arc
		(start 334.922622 -280.891234)
		(mid 335.11109 -280.941911)
		(end 335.299558 -280.891234)
		(width 0.09525)
		(layer "In4.Cu")
		(net "M_D_CPU0_SB_DQS_DP<1>")
	)
	(arc
		(start 335.299558 -280.891234)
		(mid 335.58099 -280.815479)
		(end 335.862422 -280.891234)
		(width 0.09525)
		(layer "In4.Cu")
		(net "M_D_CPU0_SB_DQS_DP<1>")
	)
	(arc
		(start 332.47965 -280.891234)
		(mid 332.761082 -280.815479)
		(end 333.042514 -280.891234)
		(width 0.09525)
		(layer "In4.Cu")
		(net "M_D_CPU0_SB_DQS_DP<1>")
	)
	(arc
		(start 333.99095 -280.89606)
		(mid 334.175982 -280.941974)
		(end 334.359758 -280.891234)
		(width 0.09525)
		(layer "In4.Cu")
		(net "M_D_CPU0_SB_DQS_DP<1>")
	)
	(arc
		(start 332.10246 -280.891234)
		(mid 332.286235 -280.942006)
		(end 332.471268 -280.89606)
		(width 0.09525)
		(layer "In4.Cu")
		(net "M_D_CPU0_SB_DQS_DP<1>")
	)
	(arc
		(start 333.050896 -280.89606)
		(mid 333.235928 -280.941974)
		(end 333.419704 -280.891234)
		(width 0.09525)
		(layer "In4.Cu")
		(net "M_D_CPU0_SB_DQS_DP<1>")
	)
	(arc
		(start 329.659742 -280.891234)
		(mid 329.941174 -280.815479)
		(end 330.222606 -280.891234)
		(width 0.09525)
		(layer "In4.Cu")
		(net "M_D_CPU0_SB_DQS_DP<1>")
	)
	(arc
		(start 326.474836 -280.898092)
		(mid 326.658217 -280.941923)
		(end 326.839834 -280.891234)
		(width 0.09525)
		(layer "In4.Cu")
		(net "M_D_CPU0_SB_DQS_DP<1>")
	)
	(arc
		(start 331.539596 -280.891234)
		(mid 331.821028 -280.815479)
		(end 332.10246 -280.891234)
		(width 0.09525)
		(layer "In4.Cu")
		(net "M_D_CPU0_SB_DQS_DP<1>")
	)
	(arc
		(start 329.290934 -280.89606)
		(mid 329.475966 -280.941974)
		(end 329.659742 -280.891234)
		(width 0.09525)
		(layer "In4.Cu")
		(net "M_D_CPU0_SB_DQS_DP<1>")
	)
	(arc
		(start 336.239612 -280.891234)
		(mid 336.521044 -280.815479)
		(end 336.802476 -280.891234)
		(width 0.09525)
		(layer "In4.Cu")
		(net "M_D_CPU0_SB_DQS_DP<1>")
	)
	(arc
		(start 326.839834 -280.891234)
		(mid 327.115377 -280.815385)
		(end 327.392538 -280.885138)
		(width 0.09525)
		(layer "In4.Cu")
		(net "M_D_CPU0_SB_DQS_DP<1>")
	)
	(arc
		(start 333.419704 -280.891234)
		(mid 333.701136 -280.815479)
		(end 333.982568 -280.891234)
		(width 0.09525)
		(layer "In4.Cu")
		(net "M_D_CPU0_SB_DQS_DP<1>")
	)
	(arc
		(start 328.342498 -280.891234)
		(mid 328.526273 -280.942006)
		(end 328.711306 -280.89606)
		(width 0.09525)
		(layer "In4.Cu")
		(net "M_D_CPU0_SB_DQS_DP<1>")
	)
	(arc
		(start 334.359758 -280.891234)
		(mid 334.64119 -280.815479)
		(end 334.922622 -280.891234)
		(width 0.09525)
		(layer "In4.Cu")
		(net "M_D_CPU0_SB_DQS_DP<1>")
	)
	(arc
		(start 327.790302 -280.885138)
		(mid 328.06721 -280.815461)
		(end 328.342498 -280.891234)
		(width 0.09525)
		(layer "In4.Cu")
		(net "M_D_CPU0_SB_DQS_DP<1>")
	)
	(segment
		(start 339.337904 -275.44014)
		(end 338.871052 -275.706078)
		(width 0.12954)
		(layer "F.Cu")
		(net "M_D_CPU0_SB_DQS_DP<0>")
	)
	(segment
		(start 315.295534 -277.439374)
		(end 315.49213 -277.242778)
		(width 0.16002)
		(layer "In4.Cu")
		(net "M_D_CPU0_SB_DQS_DP<0>")
	)
	(segment
		(start 284.736032 -284.88513)
		(end 285.009844 -285.158942)
		(width 0.16002)
		(layer "In4.Cu")
		(net "M_D_CPU0_SB_DQS_DP<0>")
	)
	(segment
		(start 289.733482 -285.34741)
		(end 290.520882 -284.56001)
		(width 0.16002)
		(layer "In4.Cu")
		(net "M_D_CPU0_SB_DQS_DP<0>")
	)
	(segment
		(start 293.49446 -285.009844)
		(end 296.13606 -285.009844)
		(width 0.16002)
		(layer "In4.Cu")
		(net "M_D_CPU0_SB_DQS_DP<0>")
	)
	(segment
		(start 309.997602 -282.460446)
		(end 309.890922 -282.353766)
		(width 0.16002)
		(layer "In4.Cu")
		(net "M_D_CPU0_SB_DQS_DP<0>")
	)
	(segment
		(start 291.428932 -284.15996)
		(end 292.644576 -284.15996)
		(width 0.16002)
		(layer "In4.Cu")
		(net "M_D_CPU0_SB_DQS_DP<0>")
	)
	(segment
		(start 285.009844 -285.158942)
		(end 285.758128 -285.158942)
		(width 0.16002)
		(layer "In4.Cu")
		(net "M_D_CPU0_SB_DQS_DP<0>")
	)
	(segment
		(start 312.638186 -279.079198)
		(end 313.011058 -278.706326)
		(width 0.16002)
		(layer "In4.Cu")
		(net "M_D_CPU0_SB_DQS_DP<0>")
	)
	(segment
		(start 309.524146 -282.933902)
		(end 309.801006 -282.933902)
		(width 0.16002)
		(layer "In4.Cu")
		(net "M_D_CPU0_SB_DQS_DP<0>")
	)
	(segment
		(start 308.51729 -283.200094)
		(end 308.890162 -282.827222)
		(width 0.16002)
		(layer "In4.Cu")
		(net "M_D_CPU0_SB_DQS_DP<0>")
	)
	(segment
		(start 326.076056 -276.08276)
		(end 327.590404 -276.08276)
		(width 0.09525)
		(layer "In4.Cu")
		(net "M_D_CPU0_SB_DQS_DP<0>")
	)
	(segment
		(start 311.264554 -280.45283)
		(end 311.637426 -280.079958)
		(width 0.16002)
		(layer "In4.Cu")
		(net "M_D_CPU0_SB_DQS_DP<0>")
	)
	(segment
		(start 286.471868 -285.158942)
		(end 287.069022 -285.158942)
		(width 0.16002)
		(layer "In4.Cu")
		(net "M_D_CPU0_SB_DQS_DP<0>")
	)
	(segment
		(start 312.16473 -280.079958)
		(end 312.27141 -280.186638)
		(width 0.16002)
		(layer "In4.Cu")
		(net "M_D_CPU0_SB_DQS_DP<0>")
	)
	(segment
		(start 311.264554 -280.980134)
		(end 311.264554 -280.45283)
		(width 0.16002)
		(layer "In4.Cu")
		(net "M_D_CPU0_SB_DQS_DP<0>")
	)
	(segment
		(start 314.911994 -277.332694)
		(end 315.018674 -277.439374)
		(width 0.16002)
		(layer "In4.Cu")
		(net "M_D_CPU0_SB_DQS_DP<0>")
	)
	(segment
		(start 329.282552 -276.031198)
		(end 329.290934 -276.036024)
		(width 0.09525)
		(layer "In4.Cu")
		(net "M_D_CPU0_SB_DQS_DP<0>")
	)
	(segment
		(start 304.431954 -285.72841)
		(end 305.600354 -284.56001)
		(width 0.16002)
		(layer "In4.Cu")
		(net "M_D_CPU0_SB_DQS_DP<0>")
	)
	(segment
		(start 296.13606 -285.009844)
		(end 296.659046 -285.53283)
		(width 0.16002)
		(layer "In4.Cu")
		(net "M_D_CPU0_SB_DQS_DP<0>")
	)
	(segment
		(start 303.45126 -285.33471)
		(end 303.84496 -285.72841)
		(width 0.16002)
		(layer "In4.Cu")
		(net "M_D_CPU0_SB_DQS_DP<0>")
	)
	(segment
		(start 289.387026 -285.34741)
		(end 289.733482 -285.34741)
		(width 0.16002)
		(layer "In4.Cu")
		(net "M_D_CPU0_SB_DQS_DP<0>")
	)
	(segment
		(start 298.939204 -284.15996)
		(end 300.289976 -284.15996)
		(width 0.16002)
		(layer "In4.Cu")
		(net "M_D_CPU0_SB_DQS_DP<0>")
	)
	(segment
		(start 315.018674 -277.439374)
		(end 315.295534 -277.439374)
		(width 0.16002)
		(layer "In4.Cu")
		(net "M_D_CPU0_SB_DQS_DP<0>")
	)
	(segment
		(start 332.471268 -276.036024)
		(end 332.47965 -276.031198)
		(width 0.09525)
		(layer "In4.Cu")
		(net "M_D_CPU0_SB_DQS_DP<0>")
	)
	(segment
		(start 308.62397 -283.834078)
		(end 308.51729 -283.727398)
		(width 0.16002)
		(layer "In4.Cu")
		(net "M_D_CPU0_SB_DQS_DP<0>")
	)
	(segment
		(start 312.638186 -279.606502)
		(end 312.638186 -279.079198)
		(width 0.16002)
		(layer "In4.Cu")
		(net "M_D_CPU0_SB_DQS_DP<0>")
	)
	(segment
		(start 333.042514 -276.031198)
		(end 333.050896 -276.036024)
		(width 0.09525)
		(layer "In4.Cu")
		(net "M_D_CPU0_SB_DQS_DP<0>")
	)
	(segment
		(start 323.919596 -275.15693)
		(end 323.978778 -275.216112)
		(width 0.09525)
		(layer "In4.Cu")
		(net "M_D_CPU0_SB_DQS_DP<0>")
	)
	(segment
		(start 311.371234 -281.363674)
		(end 311.371234 -281.086814)
		(width 0.16002)
		(layer "In4.Cu")
		(net "M_D_CPU0_SB_DQS_DP<0>")
	)
	(segment
		(start 286.355028 -285.042102)
		(end 286.471868 -285.158942)
		(width 0.16002)
		(layer "In4.Cu")
		(net "M_D_CPU0_SB_DQS_DP<0>")
	)
	(segment
		(start 336.23123 -276.036024)
		(end 336.239612 -276.031198)
		(width 0.09525)
		(layer "In4.Cu")
		(net "M_D_CPU0_SB_DQS_DP<0>")
	)
	(segment
		(start 309.801006 -282.933902)
		(end 309.997602 -282.737306)
		(width 0.16002)
		(layer "In4.Cu")
		(net "M_D_CPU0_SB_DQS_DP<0>")
	)
	(segment
		(start 337.171284 -276.036024)
		(end 337.179666 -276.031198)
		(width 0.09525)
		(layer "In4.Cu")
		(net "M_D_CPU0_SB_DQS_DP<0>")
	)
	(segment
		(start 310.897778 -281.56027)
		(end 311.174638 -281.56027)
		(width 0.16002)
		(layer "In4.Cu")
		(net "M_D_CPU0_SB_DQS_DP<0>")
	)
	(segment
		(start 315.49213 -277.242778)
		(end 315.49213 -276.965918)
		(width 0.16002)
		(layer "In4.Cu")
		(net "M_D_CPU0_SB_DQS_DP<0>")
	)
	(segment
		(start 339.001608 -276.058376)
		(end 339.024976 -275.971508)
		(width 0.09525)
		(layer "In4.Cu")
		(net "M_D_CPU0_SB_DQS_DP<0>")
	)
	(segment
		(start 315.38545 -276.331934)
		(end 316.560454 -275.15693)
		(width 0.16002)
		(layer "In4.Cu")
		(net "M_D_CPU0_SB_DQS_DP<0>")
	)
	(segment
		(start 289.04946 -285.009844)
		(end 289.387026 -285.34741)
		(width 0.16002)
		(layer "In4.Cu")
		(net "M_D_CPU0_SB_DQS_DP<0>")
	)
	(segment
		(start 303.84496 -285.72841)
		(end 304.431954 -285.72841)
		(width 0.16002)
		(layer "In4.Cu")
		(net "M_D_CPU0_SB_DQS_DP<0>")
	)
	(segment
		(start 298.539154 -284.56001)
		(end 298.939204 -284.15996)
		(width 0.16002)
		(layer "In4.Cu")
		(net "M_D_CPU0_SB_DQS_DP<0>")
	)
	(segment
		(start 291.028882 -284.56001)
		(end 291.428932 -284.15996)
		(width 0.16002)
		(layer "In4.Cu")
		(net "M_D_CPU0_SB_DQS_DP<0>")
	)
	(segment
		(start 314.011818 -278.23287)
		(end 314.011818 -277.705566)
		(width 0.16002)
		(layer "In4.Cu")
		(net "M_D_CPU0_SB_DQS_DP<0>")
	)
	(segment
		(start 285.874968 -285.042102)
		(end 286.355028 -285.042102)
		(width 0.16002)
		(layer "In4.Cu")
		(net "M_D_CPU0_SB_DQS_DP<0>")
	)
	(segment
		(start 311.371234 -281.086814)
		(end 311.264554 -280.980134)
		(width 0.16002)
		(layer "In4.Cu")
		(net "M_D_CPU0_SB_DQS_DP<0>")
	)
	(segment
		(start 328.332084 -276.025102)
		(end 328.342498 -276.031198)
		(width 0.09525)
		(layer "In4.Cu")
		(net "M_D_CPU0_SB_DQS_DP<0>")
	)
	(segment
		(start 312.744866 -279.713182)
		(end 312.638186 -279.606502)
		(width 0.16002)
		(layer "In4.Cu")
		(net "M_D_CPU0_SB_DQS_DP<0>")
	)
	(segment
		(start 287.21812 -285.009844)
		(end 289.04946 -285.009844)
		(width 0.16002)
		(layer "In4.Cu")
		(net "M_D_CPU0_SB_DQS_DP<0>")
	)
	(segment
		(start 308.043834 -284.200854)
		(end 308.150514 -284.307534)
		(width 0.16002)
		(layer "In4.Cu")
		(net "M_D_CPU0_SB_DQS_DP<0>")
	)
	(segment
		(start 310.263794 -281.45359)
		(end 310.791098 -281.45359)
		(width 0.16002)
		(layer "In4.Cu")
		(net "M_D_CPU0_SB_DQS_DP<0>")
	)
	(segment
		(start 296.659046 -285.53283)
		(end 297.083734 -285.53283)
		(width 0.16002)
		(layer "In4.Cu")
		(net "M_D_CPU0_SB_DQS_DP<0>")
	)
	(segment
		(start 305.600354 -284.56001)
		(end 307.157374 -284.56001)
		(width 0.16002)
		(layer "In4.Cu")
		(net "M_D_CPU0_SB_DQS_DP<0>")
	)
	(segment
		(start 307.51653 -284.200854)
		(end 308.043834 -284.200854)
		(width 0.16002)
		(layer "In4.Cu")
		(net "M_D_CPU0_SB_DQS_DP<0>")
	)
	(segment
		(start 333.982568 -276.031198)
		(end 333.99095 -276.036024)
		(width 0.09525)
		(layer "In4.Cu")
		(net "M_D_CPU0_SB_DQS_DP<0>")
	)
	(segment
		(start 313.921902 -278.813006)
		(end 314.118498 -278.61641)
		(width 0.16002)
		(layer "In4.Cu")
		(net "M_D_CPU0_SB_DQS_DP<0>")
	)
	(segment
		(start 323.895974 -275.15693)
		(end 323.919596 -275.15693)
		(width 0.09525)
		(layer "In4.Cu")
		(net "M_D_CPU0_SB_DQS_DP<0>")
	)
	(segment
		(start 328.711306 -276.036024)
		(end 328.719688 -276.031198)
		(width 0.09525)
		(layer "In4.Cu")
		(net "M_D_CPU0_SB_DQS_DP<0>")
	)
	(segment
		(start 308.62397 -284.110938)
		(end 308.62397 -283.834078)
		(width 0.16002)
		(layer "In4.Cu")
		(net "M_D_CPU0_SB_DQS_DP<0>")
	)
	(segment
		(start 314.011818 -277.705566)
		(end 314.38469 -277.332694)
		(width 0.16002)
		(layer "In4.Cu")
		(net "M_D_CPU0_SB_DQS_DP<0>")
	)
	(segment
		(start 331.531214 -276.036024)
		(end 331.539596 -276.031198)
		(width 0.09525)
		(layer "In4.Cu")
		(net "M_D_CPU0_SB_DQS_DP<0>")
	)
	(segment
		(start 287.069022 -285.158942)
		(end 287.21812 -285.009844)
		(width 0.16002)
		(layer "In4.Cu")
		(net "M_D_CPU0_SB_DQS_DP<0>")
	)
	(segment
		(start 338.682584 -276.031198)
		(end 338.690966 -276.036024)
		(width 0.09525)
		(layer "In4.Cu")
		(net "M_D_CPU0_SB_DQS_DP<0>")
	)
	(segment
		(start 311.637426 -280.079958)
		(end 312.16473 -280.079958)
		(width 0.16002)
		(layer "In4.Cu")
		(net "M_D_CPU0_SB_DQS_DP<0>")
	)
	(segment
		(start 337.74253 -276.031198)
		(end 337.750912 -276.036024)
		(width 0.09525)
		(layer "In4.Cu")
		(net "M_D_CPU0_SB_DQS_DP<0>")
	)
	(segment
		(start 314.38469 -277.332694)
		(end 314.911994 -277.332694)
		(width 0.16002)
		(layer "In4.Cu")
		(net "M_D_CPU0_SB_DQS_DP<0>")
	)
	(segment
		(start 339.024976 -275.971508)
		(end 338.871052 -275.706078)
		(width 0.09525)
		(layer "In4.Cu")
		(net "M_D_CPU0_SB_DQS_DP<0>")
	)
	(segment
		(start 292.644576 -284.15996)
		(end 293.49446 -285.009844)
		(width 0.16002)
		(layer "In4.Cu")
		(net "M_D_CPU0_SB_DQS_DP<0>")
	)
	(segment
		(start 309.417466 -282.827222)
		(end 309.524146 -282.933902)
		(width 0.16002)
		(layer "In4.Cu")
		(net "M_D_CPU0_SB_DQS_DP<0>")
	)
	(segment
		(start 323.978778 -275.216112)
		(end 325.209408 -275.216112)
		(width 0.09525)
		(layer "In4.Cu")
		(net "M_D_CPU0_SB_DQS_DP<0>")
	)
	(segment
		(start 297.083734 -285.53283)
		(end 298.056554 -284.56001)
		(width 0.16002)
		(layer "In4.Cu")
		(net "M_D_CPU0_SB_DQS_DP<0>")
	)
	(segment
		(start 309.997602 -282.737306)
		(end 309.997602 -282.460446)
		(width 0.16002)
		(layer "In4.Cu")
		(net "M_D_CPU0_SB_DQS_DP<0>")
	)
	(segment
		(start 316.560454 -275.15693)
		(end 323.895974 -275.15693)
		(width 0.16002)
		(layer "In4.Cu")
		(net "M_D_CPU0_SB_DQS_DP<0>")
	)
	(segment
		(start 315.49213 -276.965918)
		(end 315.38545 -276.859238)
		(width 0.16002)
		(layer "In4.Cu")
		(net "M_D_CPU0_SB_DQS_DP<0>")
	)
	(segment
		(start 290.520882 -284.56001)
		(end 291.028882 -284.56001)
		(width 0.16002)
		(layer "In4.Cu")
		(net "M_D_CPU0_SB_DQS_DP<0>")
	)
	(segment
		(start 310.791098 -281.45359)
		(end 310.897778 -281.56027)
		(width 0.16002)
		(layer "In4.Cu")
		(net "M_D_CPU0_SB_DQS_DP<0>")
	)
	(segment
		(start 298.056554 -284.56001)
		(end 298.539154 -284.56001)
		(width 0.16002)
		(layer "In4.Cu")
		(net "M_D_CPU0_SB_DQS_DP<0>")
	)
	(segment
		(start 301.464726 -285.33471)
		(end 303.45126 -285.33471)
		(width 0.16002)
		(layer "In4.Cu")
		(net "M_D_CPU0_SB_DQS_DP<0>")
	)
	(segment
		(start 307.157374 -284.56001)
		(end 307.51653 -284.200854)
		(width 0.16002)
		(layer "In4.Cu")
		(net "M_D_CPU0_SB_DQS_DP<0>")
	)
	(segment
		(start 315.38545 -276.859238)
		(end 315.38545 -276.331934)
		(width 0.16002)
		(layer "In4.Cu")
		(net "M_D_CPU0_SB_DQS_DP<0>")
	)
	(segment
		(start 311.174638 -281.56027)
		(end 311.371234 -281.363674)
		(width 0.16002)
		(layer "In4.Cu")
		(net "M_D_CPU0_SB_DQS_DP<0>")
	)
	(segment
		(start 309.890922 -281.826462)
		(end 310.263794 -281.45359)
		(width 0.16002)
		(layer "In4.Cu")
		(net "M_D_CPU0_SB_DQS_DP<0>")
	)
	(segment
		(start 314.118498 -278.33955)
		(end 314.011818 -278.23287)
		(width 0.16002)
		(layer "In4.Cu")
		(net "M_D_CPU0_SB_DQS_DP<0>")
	)
	(segment
		(start 308.51729 -283.727398)
		(end 308.51729 -283.200094)
		(width 0.16002)
		(layer "In4.Cu")
		(net "M_D_CPU0_SB_DQS_DP<0>")
	)
	(segment
		(start 308.427374 -284.307534)
		(end 308.62397 -284.110938)
		(width 0.16002)
		(layer "In4.Cu")
		(net "M_D_CPU0_SB_DQS_DP<0>")
	)
	(segment
		(start 312.54827 -280.186638)
		(end 312.744866 -279.990042)
		(width 0.16002)
		(layer "In4.Cu")
		(net "M_D_CPU0_SB_DQS_DP<0>")
	)
	(segment
		(start 313.538362 -278.706326)
		(end 313.645042 -278.813006)
		(width 0.16002)
		(layer "In4.Cu")
		(net "M_D_CPU0_SB_DQS_DP<0>")
	)
	(segment
		(start 314.118498 -278.61641)
		(end 314.118498 -278.33955)
		(width 0.16002)
		(layer "In4.Cu")
		(net "M_D_CPU0_SB_DQS_DP<0>")
	)
	(segment
		(start 308.890162 -282.827222)
		(end 309.417466 -282.827222)
		(width 0.16002)
		(layer "In4.Cu")
		(net "M_D_CPU0_SB_DQS_DP<0>")
	)
	(segment
		(start 312.27141 -280.186638)
		(end 312.54827 -280.186638)
		(width 0.16002)
		(layer "In4.Cu")
		(net "M_D_CPU0_SB_DQS_DP<0>")
	)
	(segment
		(start 312.744866 -279.990042)
		(end 312.744866 -279.713182)
		(width 0.16002)
		(layer "In4.Cu")
		(net "M_D_CPU0_SB_DQS_DP<0>")
	)
	(segment
		(start 325.209408 -275.216112)
		(end 326.076056 -276.08276)
		(width 0.09525)
		(layer "In4.Cu")
		(net "M_D_CPU0_SB_DQS_DP<0>")
	)
	(segment
		(start 308.150514 -284.307534)
		(end 308.427374 -284.307534)
		(width 0.16002)
		(layer "In4.Cu")
		(net "M_D_CPU0_SB_DQS_DP<0>")
	)
	(segment
		(start 285.758128 -285.158942)
		(end 285.874968 -285.042102)
		(width 0.16002)
		(layer "In4.Cu")
		(net "M_D_CPU0_SB_DQS_DP<0>")
	)
	(segment
		(start 313.011058 -278.706326)
		(end 313.538362 -278.706326)
		(width 0.16002)
		(layer "In4.Cu")
		(net "M_D_CPU0_SB_DQS_DP<0>")
	)
	(segment
		(start 309.890922 -282.353766)
		(end 309.890922 -281.826462)
		(width 0.16002)
		(layer "In4.Cu")
		(net "M_D_CPU0_SB_DQS_DP<0>")
	)
	(segment
		(start 313.645042 -278.813006)
		(end 313.921902 -278.813006)
		(width 0.16002)
		(layer "In4.Cu")
		(net "M_D_CPU0_SB_DQS_DP<0>")
	)
	(segment
		(start 300.289976 -284.15996)
		(end 301.464726 -285.33471)
		(width 0.16002)
		(layer "In4.Cu")
		(net "M_D_CPU0_SB_DQS_DP<0>")
	)
	(arc
		(start 336.239612 -276.031198)
		(mid 336.246065 -276.027598)
		(end 336.252566 -276.024086)
		(width 0.09525)
		(layer "In4.Cu")
		(net "M_D_CPU0_SB_DQS_DP<0>")
	)
	(arc
		(start 332.10246 -276.031198)
		(mid 332.286235 -276.08197)
		(end 332.471268 -276.036024)
		(width 0.09525)
		(layer "In4.Cu")
		(net "M_D_CPU0_SB_DQS_DP<0>")
	)
	(arc
		(start 327.77938 -276.031198)
		(mid 328.054923 -275.955349)
		(end 328.332084 -276.025102)
		(width 0.09525)
		(layer "In4.Cu")
		(net "M_D_CPU0_SB_DQS_DP<0>")
	)
	(arc
		(start 334.359758 -276.031198)
		(mid 334.64119 -275.955443)
		(end 334.922622 -276.031198)
		(width 0.09525)
		(layer "In4.Cu")
		(net "M_D_CPU0_SB_DQS_DP<0>")
	)
	(arc
		(start 335.862422 -276.031198)
		(mid 336.046197 -276.08197)
		(end 336.23123 -276.036024)
		(width 0.09525)
		(layer "In4.Cu")
		(net "M_D_CPU0_SB_DQS_DP<0>")
	)
	(arc
		(start 337.750912 -276.036024)
		(mid 337.935944 -276.081938)
		(end 338.11972 -276.031198)
		(width 0.09525)
		(layer "In4.Cu")
		(net "M_D_CPU0_SB_DQS_DP<0>")
	)
	(arc
		(start 328.719688 -276.031198)
		(mid 329.00112 -275.955443)
		(end 329.282552 -276.031198)
		(width 0.09525)
		(layer "In4.Cu")
		(net "M_D_CPU0_SB_DQS_DP<0>")
	)
	(arc
		(start 329.659742 -276.031198)
		(mid 329.941174 -275.955443)
		(end 330.222606 -276.031198)
		(width 0.09525)
		(layer "In4.Cu")
		(net "M_D_CPU0_SB_DQS_DP<0>")
	)
	(arc
		(start 331.162406 -276.031198)
		(mid 331.346181 -276.08197)
		(end 331.531214 -276.036024)
		(width 0.09525)
		(layer "In4.Cu")
		(net "M_D_CPU0_SB_DQS_DP<0>")
	)
	(arc
		(start 333.99095 -276.036024)
		(mid 334.175982 -276.081938)
		(end 334.359758 -276.031198)
		(width 0.09525)
		(layer "In4.Cu")
		(net "M_D_CPU0_SB_DQS_DP<0>")
	)
	(arc
		(start 332.47965 -276.031198)
		(mid 332.761082 -275.955443)
		(end 333.042514 -276.031198)
		(width 0.09525)
		(layer "In4.Cu")
		(net "M_D_CPU0_SB_DQS_DP<0>")
	)
	(arc
		(start 329.290934 -276.036024)
		(mid 329.475966 -276.081938)
		(end 329.659742 -276.031198)
		(width 0.09525)
		(layer "In4.Cu")
		(net "M_D_CPU0_SB_DQS_DP<0>")
	)
	(arc
		(start 338.690966 -276.036024)
		(mid 338.843861 -276.080852)
		(end 339.001608 -276.058376)
		(width 0.09525)
		(layer "In4.Cu")
		(net "M_D_CPU0_SB_DQS_DP<0>")
	)
	(arc
		(start 330.612242 -276.024086)
		(mid 330.888252 -275.955525)
		(end 331.162406 -276.031198)
		(width 0.09525)
		(layer "In4.Cu")
		(net "M_D_CPU0_SB_DQS_DP<0>")
	)
	(arc
		(start 328.342498 -276.031198)
		(mid 328.526273 -276.08197)
		(end 328.711306 -276.036024)
		(width 0.09525)
		(layer "In4.Cu")
		(net "M_D_CPU0_SB_DQS_DP<0>")
	)
	(arc
		(start 335.299558 -276.031198)
		(mid 335.305886 -276.027602)
		(end 335.312258 -276.024086)
		(width 0.09525)
		(layer "In4.Cu")
		(net "M_D_CPU0_SB_DQS_DP<0>")
	)
	(arc
		(start 330.599542 -276.031198)
		(mid 330.60587 -276.027602)
		(end 330.612242 -276.024086)
		(width 0.09525)
		(layer "In4.Cu")
		(net "M_D_CPU0_SB_DQS_DP<0>")
	)
	(arc
		(start 335.312258 -276.024086)
		(mid 335.588268 -275.955525)
		(end 335.862422 -276.031198)
		(width 0.09525)
		(layer "In4.Cu")
		(net "M_D_CPU0_SB_DQS_DP<0>")
	)
	(arc
		(start 336.802476 -276.031198)
		(mid 336.986251 -276.08197)
		(end 337.171284 -276.036024)
		(width 0.09525)
		(layer "In4.Cu")
		(net "M_D_CPU0_SB_DQS_DP<0>")
	)
	(arc
		(start 331.55255 -276.024086)
		(mid 331.82845 -275.955524)
		(end 332.10246 -276.031198)
		(width 0.09525)
		(layer "In4.Cu")
		(net "M_D_CPU0_SB_DQS_DP<0>")
	)
	(arc
		(start 338.11972 -276.031198)
		(mid 338.401152 -275.955443)
		(end 338.682584 -276.031198)
		(width 0.09525)
		(layer "In4.Cu")
		(net "M_D_CPU0_SB_DQS_DP<0>")
	)
	(arc
		(start 327.590404 -276.08276)
		(mid 327.688301 -276.069474)
		(end 327.77938 -276.031198)
		(width 0.09525)
		(layer "In4.Cu")
		(net "M_D_CPU0_SB_DQS_DP<0>")
	)
	(arc
		(start 336.252566 -276.024086)
		(mid 336.528466 -275.955524)
		(end 336.802476 -276.031198)
		(width 0.09525)
		(layer "In4.Cu")
		(net "M_D_CPU0_SB_DQS_DP<0>")
	)
	(arc
		(start 333.419704 -276.031198)
		(mid 333.701136 -275.955443)
		(end 333.982568 -276.031198)
		(width 0.09525)
		(layer "In4.Cu")
		(net "M_D_CPU0_SB_DQS_DP<0>")
	)
	(arc
		(start 331.539596 -276.031198)
		(mid 331.546049 -276.027598)
		(end 331.55255 -276.024086)
		(width 0.09525)
		(layer "In4.Cu")
		(net "M_D_CPU0_SB_DQS_DP<0>")
	)
	(arc
		(start 337.179666 -276.031198)
		(mid 337.461098 -275.955443)
		(end 337.74253 -276.031198)
		(width 0.09525)
		(layer "In4.Cu")
		(net "M_D_CPU0_SB_DQS_DP<0>")
	)
	(arc
		(start 330.222606 -276.031198)
		(mid 330.411074 -276.081875)
		(end 330.599542 -276.031198)
		(width 0.09525)
		(layer "In4.Cu")
		(net "M_D_CPU0_SB_DQS_DP<0>")
	)
	(arc
		(start 333.050896 -276.036024)
		(mid 333.235928 -276.081938)
		(end 333.419704 -276.031198)
		(width 0.09525)
		(layer "In4.Cu")
		(net "M_D_CPU0_SB_DQS_DP<0>")
	)
	(arc
		(start 334.922622 -276.031198)
		(mid 335.11109 -276.081875)
		(end 335.299558 -276.031198)
		(width 0.09525)
		(layer "In4.Cu")
		(net "M_D_CPU0_SB_DQS_DP<0>")
	)
	(segment
		(start 339.808058 -271.39011)
		(end 339.341206 -271.656048)
		(width 0.12954)
		(layer "F.Cu")
		(net "M_D_CPU0_SB_DQS_DN<9>")
	)
	(segment
		(start 300.67758 -274.289012)
		(end 301.285656 -274.289012)
		(width 0.16002)
		(layer "In4.Cu")
		(net "M_D_CPU0_SB_DQS_DN<9>")
	)
	(segment
		(start 302.45431 -276.28977)
		(end 302.827182 -275.916898)
		(width 0.16002)
		(layer "In4.Cu")
		(net "M_D_CPU0_SB_DQS_DN<9>")
	)
	(segment
		(start 339.086444 -271.363948)
		(end 339.187282 -271.390618)
		(width 0.09525)
		(layer "In4.Cu")
		(net "M_D_CPU0_SB_DQS_DN<9>")
	)
	(segment
		(start 313.431174 -269.83563)
		(end 323.912992 -269.83563)
		(width 0.16002)
		(layer "In4.Cu")
		(net "M_D_CPU0_SB_DQS_DN<9>")
	)
	(segment
		(start 293.861236 -274.743418)
		(end 293.861236 -274.530566)
		(width 0.16002)
		(layer "In4.Cu")
		(net "M_D_CPU0_SB_DQS_DN<9>")
	)
	(segment
		(start 296.441622 -275.93036)
		(end 296.788332 -276.27707)
		(width 0.16002)
		(layer "In4.Cu")
		(net "M_D_CPU0_SB_DQS_DN<9>")
	)
	(segment
		(start 303.868328 -276.28977)
		(end 305.001676 -276.28977)
		(width 0.16002)
		(layer "In4.Cu")
		(net "M_D_CPU0_SB_DQS_DN<9>")
	)
	(segment
		(start 301.285656 -274.289012)
		(end 301.48149 -274.484846)
		(width 0.16002)
		(layer "In4.Cu")
		(net "M_D_CPU0_SB_DQS_DN<9>")
	)
	(segment
		(start 331.63256 -271.330928)
		(end 331.640942 -271.326102)
		(width 0.09525)
		(layer "In4.Cu")
		(net "M_D_CPU0_SB_DQS_DN<9>")
	)
	(segment
		(start 302.827182 -274.898866)
		(end 303.023016 -274.703032)
		(width 0.16002)
		(layer "In4.Cu")
		(net "M_D_CPU0_SB_DQS_DN<9>")
	)
	(segment
		(start 289.269932 -276.27707)
		(end 289.875976 -276.27707)
		(width 0.16002)
		(layer "In4.Cu")
		(net "M_D_CPU0_SB_DQS_DN<9>")
	)
	(segment
		(start 324.14591 -269.776702)
		(end 324.69709 -270.327882)
		(width 0.09525)
		(layer "In4.Cu")
		(net "M_D_CPU0_SB_DQS_DN<9>")
	)
	(segment
		(start 335.392522 -271.330928)
		(end 335.400904 -271.326102)
		(width 0.09525)
		(layer "In4.Cu")
		(net "M_D_CPU0_SB_DQS_DN<9>")
	)
	(segment
		(start 303.495456 -275.916898)
		(end 303.868328 -276.28977)
		(width 0.16002)
		(layer "In4.Cu")
		(net "M_D_CPU0_SB_DQS_DN<9>")
	)
	(segment
		(start 299.418756 -274.987258)
		(end 299.979334 -274.987258)
		(width 0.16002)
		(layer "In4.Cu")
		(net "M_D_CPU0_SB_DQS_DN<9>")
	)
	(segment
		(start 302.827182 -275.916898)
		(end 302.827182 -274.898866)
		(width 0.16002)
		(layer "In4.Cu")
		(net "M_D_CPU0_SB_DQS_DN<9>")
	)
	(segment
		(start 339.187282 -271.390618)
		(end 339.341206 -271.656048)
		(width 0.09525)
		(layer "In4.Cu")
		(net "M_D_CPU0_SB_DQS_DN<9>")
	)
	(segment
		(start 297.445176 -276.27707)
		(end 298.245276 -275.47697)
		(width 0.16002)
		(layer "In4.Cu")
		(net "M_D_CPU0_SB_DQS_DN<9>")
	)
	(segment
		(start 294.52951 -275.557488)
		(end 294.902382 -275.93036)
		(width 0.16002)
		(layer "In4.Cu")
		(net "M_D_CPU0_SB_DQS_DN<9>")
	)
	(segment
		(start 323.995542 -269.776702)
		(end 324.14591 -269.776702)
		(width 0.09525)
		(layer "In4.Cu")
		(net "M_D_CPU0_SB_DQS_DN<9>")
	)
	(segment
		(start 301.854362 -276.28977)
		(end 302.45431 -276.28977)
		(width 0.16002)
		(layer "In4.Cu")
		(net "M_D_CPU0_SB_DQS_DN<9>")
	)
	(segment
		(start 330.12126 -271.326102)
		(end 330.129642 -271.330928)
		(width 0.09525)
		(layer "In4.Cu")
		(net "M_D_CPU0_SB_DQS_DN<9>")
	)
	(segment
		(start 293.861236 -274.530566)
		(end 294.05707 -274.334732)
		(width 0.16002)
		(layer "In4.Cu")
		(net "M_D_CPU0_SB_DQS_DN<9>")
	)
	(segment
		(start 294.52951 -274.530566)
		(end 294.52951 -275.557488)
		(width 0.16002)
		(layer "In4.Cu")
		(net "M_D_CPU0_SB_DQS_DN<9>")
	)
	(segment
		(start 299.979334 -274.987258)
		(end 300.67758 -274.289012)
		(width 0.16002)
		(layer "In4.Cu")
		(net "M_D_CPU0_SB_DQS_DN<9>")
	)
	(segment
		(start 307.815234 -275.45157)
		(end 313.431174 -269.83563)
		(width 0.16002)
		(layer "In4.Cu")
		(net "M_D_CPU0_SB_DQS_DN<9>")
	)
	(segment
		(start 291.55517 -275.080476)
		(end 293.524178 -275.080476)
		(width 0.16002)
		(layer "In4.Cu")
		(net "M_D_CPU0_SB_DQS_DN<9>")
	)
	(segment
		(start 301.48149 -274.484846)
		(end 301.48149 -275.916898)
		(width 0.16002)
		(layer "In4.Cu")
		(net "M_D_CPU0_SB_DQS_DN<9>")
	)
	(segment
		(start 288.930842 -275.93798)
		(end 289.269932 -276.27707)
		(width 0.16002)
		(layer "In4.Cu")
		(net "M_D_CPU0_SB_DQS_DN<9>")
	)
	(segment
		(start 286.018986 -276.111208)
		(end 286.192214 -275.93798)
		(width 0.16002)
		(layer "In4.Cu")
		(net "M_D_CPU0_SB_DQS_DN<9>")
	)
	(segment
		(start 334.821276 -271.326102)
		(end 334.829658 -271.330928)
		(width 0.09525)
		(layer "In4.Cu")
		(net "M_D_CPU0_SB_DQS_DN<9>")
	)
	(segment
		(start 330.692506 -271.330928)
		(end 330.700888 -271.326102)
		(width 0.09525)
		(layer "In4.Cu")
		(net "M_D_CPU0_SB_DQS_DN<9>")
	)
	(segment
		(start 323.912992 -269.83563)
		(end 323.936614 -269.83563)
		(width 0.09525)
		(layer "In4.Cu")
		(net "M_D_CPU0_SB_DQS_DN<9>")
	)
	(segment
		(start 286.192214 -275.93798)
		(end 288.930842 -275.93798)
		(width 0.16002)
		(layer "In4.Cu")
		(net "M_D_CPU0_SB_DQS_DN<9>")
	)
	(segment
		(start 336.332576 -271.330928)
		(end 336.340958 -271.326102)
		(width 0.09525)
		(layer "In4.Cu")
		(net "M_D_CPU0_SB_DQS_DN<9>")
	)
	(segment
		(start 298.929044 -275.47697)
		(end 299.418756 -274.987258)
		(width 0.16002)
		(layer "In4.Cu")
		(net "M_D_CPU0_SB_DQS_DN<9>")
	)
	(segment
		(start 291.184076 -275.45157)
		(end 291.55517 -275.080476)
		(width 0.16002)
		(layer "In4.Cu")
		(net "M_D_CPU0_SB_DQS_DN<9>")
	)
	(segment
		(start 305.001676 -276.28977)
		(end 305.839876 -275.45157)
		(width 0.16002)
		(layer "In4.Cu")
		(net "M_D_CPU0_SB_DQS_DN<9>")
	)
	(segment
		(start 305.839876 -275.45157)
		(end 307.815234 -275.45157)
		(width 0.16002)
		(layer "In4.Cu")
		(net "M_D_CPU0_SB_DQS_DN<9>")
	)
	(segment
		(start 303.023016 -274.703032)
		(end 303.299622 -274.703032)
		(width 0.16002)
		(layer "In4.Cu")
		(net "M_D_CPU0_SB_DQS_DN<9>")
	)
	(segment
		(start 294.05707 -274.334732)
		(end 294.333676 -274.334732)
		(width 0.16002)
		(layer "In4.Cu")
		(net "M_D_CPU0_SB_DQS_DN<9>")
	)
	(segment
		(start 285.009844 -276.111208)
		(end 286.018986 -276.111208)
		(width 0.16002)
		(layer "In4.Cu")
		(net "M_D_CPU0_SB_DQS_DN<9>")
	)
	(segment
		(start 325.324724 -270.327882)
		(end 326.403716 -271.406874)
		(width 0.09525)
		(layer "In4.Cu")
		(net "M_D_CPU0_SB_DQS_DN<9>")
	)
	(segment
		(start 298.245276 -275.47697)
		(end 298.929044 -275.47697)
		(width 0.16002)
		(layer "In4.Cu")
		(net "M_D_CPU0_SB_DQS_DN<9>")
	)
	(segment
		(start 303.495456 -274.898866)
		(end 303.495456 -275.916898)
		(width 0.16002)
		(layer "In4.Cu")
		(net "M_D_CPU0_SB_DQS_DN<9>")
	)
	(segment
		(start 324.69709 -270.327882)
		(end 325.324724 -270.327882)
		(width 0.09525)
		(layer "In4.Cu")
		(net "M_D_CPU0_SB_DQS_DN<9>")
	)
	(segment
		(start 290.701476 -275.45157)
		(end 291.184076 -275.45157)
		(width 0.16002)
		(layer "In4.Cu")
		(net "M_D_CPU0_SB_DQS_DN<9>")
	)
	(segment
		(start 296.788332 -276.27707)
		(end 297.445176 -276.27707)
		(width 0.16002)
		(layer "In4.Cu")
		(net "M_D_CPU0_SB_DQS_DN<9>")
	)
	(segment
		(start 294.902382 -275.93036)
		(end 296.441622 -275.93036)
		(width 0.16002)
		(layer "In4.Cu")
		(net "M_D_CPU0_SB_DQS_DN<9>")
	)
	(segment
		(start 303.299622 -274.703032)
		(end 303.495456 -274.898866)
		(width 0.16002)
		(layer "In4.Cu")
		(net "M_D_CPU0_SB_DQS_DN<9>")
	)
	(segment
		(start 338.581238 -271.326102)
		(end 338.58962 -271.330928)
		(width 0.09525)
		(layer "In4.Cu")
		(net "M_D_CPU0_SB_DQS_DN<9>")
	)
	(segment
		(start 328.241406 -271.326102)
		(end 328.249788 -271.330928)
		(width 0.09525)
		(layer "In4.Cu")
		(net "M_D_CPU0_SB_DQS_DN<9>")
	)
	(segment
		(start 294.333676 -274.334732)
		(end 294.52951 -274.530566)
		(width 0.16002)
		(layer "In4.Cu")
		(net "M_D_CPU0_SB_DQS_DN<9>")
	)
	(segment
		(start 326.403716 -271.406874)
		(end 327.590404 -271.406874)
		(width 0.09525)
		(layer "In4.Cu")
		(net "M_D_CPU0_SB_DQS_DN<9>")
	)
	(segment
		(start 333.881222 -271.326102)
		(end 333.889604 -271.330928)
		(width 0.09525)
		(layer "In4.Cu")
		(net "M_D_CPU0_SB_DQS_DN<9>")
	)
	(segment
		(start 301.48149 -275.916898)
		(end 301.854362 -276.28977)
		(width 0.16002)
		(layer "In4.Cu")
		(net "M_D_CPU0_SB_DQS_DN<9>")
	)
	(segment
		(start 289.875976 -276.27707)
		(end 290.701476 -275.45157)
		(width 0.16002)
		(layer "In4.Cu")
		(net "M_D_CPU0_SB_DQS_DN<9>")
	)
	(segment
		(start 323.936614 -269.83563)
		(end 323.995542 -269.776702)
		(width 0.09525)
		(layer "In4.Cu")
		(net "M_D_CPU0_SB_DQS_DN<9>")
	)
	(segment
		(start 284.736032 -276.38502)
		(end 285.009844 -276.111208)
		(width 0.16002)
		(layer "In4.Cu")
		(net "M_D_CPU0_SB_DQS_DN<9>")
	)
	(segment
		(start 293.524178 -275.080476)
		(end 293.861236 -274.743418)
		(width 0.16002)
		(layer "In4.Cu")
		(net "M_D_CPU0_SB_DQS_DN<9>")
	)
	(arc
		(start 337.27263 -271.330928)
		(mid 337.461098 -271.280251)
		(end 337.649566 -271.330928)
		(width 0.09525)
		(layer "In4.Cu")
		(net "M_D_CPU0_SB_DQS_DN<9>")
	)
	(arc
		(start 328.812652 -271.330928)
		(mid 329.00112 -271.280251)
		(end 329.189588 -271.330928)
		(width 0.09525)
		(layer "In4.Cu")
		(net "M_D_CPU0_SB_DQS_DN<9>")
	)
	(arc
		(start 338.58962 -271.330928)
		(mid 338.823134 -271.404771)
		(end 339.06587 -271.372076)
		(width 0.09525)
		(layer "In4.Cu")
		(net "M_D_CPU0_SB_DQS_DN<9>")
	)
	(arc
		(start 329.752452 -271.330928)
		(mid 329.936227 -271.280156)
		(end 330.12126 -271.326102)
		(width 0.09525)
		(layer "In4.Cu")
		(net "M_D_CPU0_SB_DQS_DN<9>")
	)
	(arc
		(start 335.400904 -271.326102)
		(mid 335.585936 -271.280188)
		(end 335.769712 -271.330928)
		(width 0.09525)
		(layer "In4.Cu")
		(net "M_D_CPU0_SB_DQS_DN<9>")
	)
	(arc
		(start 335.769712 -271.330928)
		(mid 336.051144 -271.406683)
		(end 336.332576 -271.330928)
		(width 0.09525)
		(layer "In4.Cu")
		(net "M_D_CPU0_SB_DQS_DN<9>")
	)
	(arc
		(start 330.129642 -271.330928)
		(mid 330.411074 -271.406683)
		(end 330.692506 -271.330928)
		(width 0.09525)
		(layer "In4.Cu")
		(net "M_D_CPU0_SB_DQS_DN<9>")
	)
	(arc
		(start 327.590404 -271.406874)
		(mid 327.736264 -271.387515)
		(end 327.87209 -271.330928)
		(width 0.09525)
		(layer "In4.Cu")
		(net "M_D_CPU0_SB_DQS_DN<9>")
	)
	(arc
		(start 332.572614 -271.330928)
		(mid 332.761082 -271.280251)
		(end 332.94955 -271.330928)
		(width 0.09525)
		(layer "In4.Cu")
		(net "M_D_CPU0_SB_DQS_DN<9>")
	)
	(arc
		(start 333.512414 -271.330928)
		(mid 333.696189 -271.280156)
		(end 333.881222 -271.326102)
		(width 0.09525)
		(layer "In4.Cu")
		(net "M_D_CPU0_SB_DQS_DN<9>")
	)
	(arc
		(start 332.94955 -271.330928)
		(mid 333.230982 -271.406683)
		(end 333.512414 -271.330928)
		(width 0.09525)
		(layer "In4.Cu")
		(net "M_D_CPU0_SB_DQS_DN<9>")
	)
	(arc
		(start 337.649566 -271.330928)
		(mid 337.930998 -271.406683)
		(end 338.21243 -271.330928)
		(width 0.09525)
		(layer "In4.Cu")
		(net "M_D_CPU0_SB_DQS_DN<9>")
	)
	(arc
		(start 338.21243 -271.330928)
		(mid 338.396205 -271.280156)
		(end 338.581238 -271.326102)
		(width 0.09525)
		(layer "In4.Cu")
		(net "M_D_CPU0_SB_DQS_DN<9>")
	)
	(arc
		(start 327.87209 -271.330928)
		(mid 328.056119 -271.280029)
		(end 328.241406 -271.326102)
		(width 0.09525)
		(layer "In4.Cu")
		(net "M_D_CPU0_SB_DQS_DN<9>")
	)
	(arc
		(start 336.709766 -271.330928)
		(mid 336.991198 -271.406683)
		(end 337.27263 -271.330928)
		(width 0.09525)
		(layer "In4.Cu")
		(net "M_D_CPU0_SB_DQS_DN<9>")
	)
	(arc
		(start 331.069696 -271.330928)
		(mid 331.351128 -271.406683)
		(end 331.63256 -271.330928)
		(width 0.09525)
		(layer "In4.Cu")
		(net "M_D_CPU0_SB_DQS_DN<9>")
	)
	(arc
		(start 331.640942 -271.326102)
		(mid 331.825974 -271.280188)
		(end 332.00975 -271.330928)
		(width 0.09525)
		(layer "In4.Cu")
		(net "M_D_CPU0_SB_DQS_DN<9>")
	)
	(arc
		(start 329.189588 -271.330928)
		(mid 329.47102 -271.406683)
		(end 329.752452 -271.330928)
		(width 0.09525)
		(layer "In4.Cu")
		(net "M_D_CPU0_SB_DQS_DN<9>")
	)
	(arc
		(start 334.829658 -271.330928)
		(mid 335.11109 -271.406683)
		(end 335.392522 -271.330928)
		(width 0.09525)
		(layer "In4.Cu")
		(net "M_D_CPU0_SB_DQS_DN<9>")
	)
	(arc
		(start 339.06587 -271.372076)
		(mid 339.076198 -271.368116)
		(end 339.086444 -271.363948)
		(width 0.09525)
		(layer "In4.Cu")
		(net "M_D_CPU0_SB_DQS_DN<9>")
	)
	(arc
		(start 332.00975 -271.330928)
		(mid 332.291182 -271.406683)
		(end 332.572614 -271.330928)
		(width 0.09525)
		(layer "In4.Cu")
		(net "M_D_CPU0_SB_DQS_DN<9>")
	)
	(arc
		(start 333.889604 -271.330928)
		(mid 334.171036 -271.406683)
		(end 334.452468 -271.330928)
		(width 0.09525)
		(layer "In4.Cu")
		(net "M_D_CPU0_SB_DQS_DN<9>")
	)
	(arc
		(start 328.249788 -271.330928)
		(mid 328.53122 -271.406683)
		(end 328.812652 -271.330928)
		(width 0.09525)
		(layer "In4.Cu")
		(net "M_D_CPU0_SB_DQS_DN<9>")
	)
	(arc
		(start 336.340958 -271.326102)
		(mid 336.52599 -271.280188)
		(end 336.709766 -271.330928)
		(width 0.09525)
		(layer "In4.Cu")
		(net "M_D_CPU0_SB_DQS_DN<9>")
	)
	(arc
		(start 330.700888 -271.326102)
		(mid 330.88592 -271.280188)
		(end 331.069696 -271.330928)
		(width 0.09525)
		(layer "In4.Cu")
		(net "M_D_CPU0_SB_DQS_DN<9>")
	)
	(arc
		(start 334.452468 -271.330928)
		(mid 334.636243 -271.280156)
		(end 334.821276 -271.326102)
		(width 0.09525)
		(layer "In4.Cu")
		(net "M_D_CPU0_SB_DQS_DN<9>")
	)
	(segment
		(start 340.747858 -290.83)
		(end 340.281006 -291.095938)
		(width 0.12954)
		(layer "F.Cu")
		(net "M_D_CPU0_SB_DQS_DN<8>")
	)
	(segment
		(start 283.999432 -314.224416)
		(end 285.726632 -314.224416)
		(width 0.16002)
		(layer "In4.Cu")
		(net "M_D_CPU0_SB_DQS_DN<8>")
	)
	(segment
		(start 287.15716 -314.941204)
		(end 287.63722 -314.941204)
		(width 0.16002)
		(layer "In4.Cu")
		(net "M_D_CPU0_SB_DQS_DN<8>")
	)
	(segment
		(start 298.755054 -313.879992)
		(end 299.064172 -314.194952)
		(width 0.16002)
		(layer "In4.Cu")
		(net "M_D_CPU0_SB_DQS_DN<8>")
	)
	(segment
		(start 295.818814 -315.058044)
		(end 297.38447 -314.409328)
		(width 0.16002)
		(layer "In4.Cu")
		(net "M_D_CPU0_SB_DQS_DN<8>")
	)
	(segment
		(start 338.581238 -291.425884)
		(end 338.58962 -291.421058)
		(width 0.09525)
		(layer "In4.Cu")
		(net "M_D_CPU0_SB_DQS_DN<8>")
	)
	(segment
		(start 322.292218 -298.122848)
		(end 325.08444 -295.330626)
		(width 0.16002)
		(layer "In4.Cu")
		(net "M_D_CPU0_SB_DQS_DN<8>")
	)
	(segment
		(start 334.821276 -291.425884)
		(end 334.829658 -291.421058)
		(width 0.09525)
		(layer "In4.Cu")
		(net "M_D_CPU0_SB_DQS_DN<8>")
	)
	(segment
		(start 325.184516 -295.314116)
		(end 325.482458 -295.01719)
		(width 0.09525)
		(layer "In4.Cu")
		(net "M_D_CPU0_SB_DQS_DN<8>")
	)
	(segment
		(start 325.482458 -295.01719)
		(end 325.482458 -294.40759)
		(width 0.09525)
		(layer "In4.Cu")
		(net "M_D_CPU0_SB_DQS_DN<8>")
	)
	(segment
		(start 286.56026 -315.058044)
		(end 287.04032 -315.058044)
		(width 0.16002)
		(layer "In4.Cu")
		(net "M_D_CPU0_SB_DQS_DN<8>")
	)
	(segment
		(start 325.646542 -294.011858)
		(end 326.784462 -292.308788)
		(width 0.09525)
		(layer "In4.Cu")
		(net "M_D_CPU0_SB_DQS_DN<8>")
	)
	(segment
		(start 303.327308 -314.68695)
		(end 303.444148 -314.57011)
		(width 0.16002)
		(layer "In4.Cu")
		(net "M_D_CPU0_SB_DQS_DN<8>")
	)
	(segment
		(start 288.856166 -315.058044)
		(end 290.612576 -313.88431)
		(width 0.16002)
		(layer "In4.Cu")
		(net "M_D_CPU0_SB_DQS_DN<8>")
	)
	(segment
		(start 287.75406 -315.058044)
		(end 288.856166 -315.058044)
		(width 0.16002)
		(layer "In4.Cu")
		(net "M_D_CPU0_SB_DQS_DN<8>")
	)
	(segment
		(start 280.91003 -314.059062)
		(end 281.798268 -314.059062)
		(width 0.16002)
		(layer "In4.Cu")
		(net "M_D_CPU0_SB_DQS_DN<8>")
	)
	(segment
		(start 336.332576 -291.421058)
		(end 336.340958 -291.425884)
		(width 0.09525)
		(layer "In4.Cu")
		(net "M_D_CPU0_SB_DQS_DN<8>")
	)
	(segment
		(start 340.43493 -291.361368)
		(end 340.281006 -291.095938)
		(width 0.09525)
		(layer "In4.Cu")
		(net "M_D_CPU0_SB_DQS_DN<8>")
	)
	(segment
		(start 304.041048 -314.68695)
		(end 304.865786 -314.68695)
		(width 0.16002)
		(layer "In4.Cu")
		(net "M_D_CPU0_SB_DQS_DN<8>")
	)
	(segment
		(start 326.784462 -292.308788)
		(end 327.620884 -291.472366)
		(width 0.09525)
		(layer "In4.Cu")
		(net "M_D_CPU0_SB_DQS_DN<8>")
	)
	(segment
		(start 281.798268 -314.059062)
		(end 282.06192 -313.79541)
		(width 0.16002)
		(layer "In4.Cu")
		(net "M_D_CPU0_SB_DQS_DN<8>")
	)
	(segment
		(start 339.521292 -291.425884)
		(end 339.529674 -291.421058)
		(width 0.09525)
		(layer "In4.Cu")
		(net "M_D_CPU0_SB_DQS_DN<8>")
	)
	(segment
		(start 335.392522 -291.421058)
		(end 335.400904 -291.425884)
		(width 0.09525)
		(layer "In4.Cu")
		(net "M_D_CPU0_SB_DQS_DN<8>")
	)
	(segment
		(start 333.881222 -291.425884)
		(end 333.889604 -291.421058)
		(width 0.09525)
		(layer "In4.Cu")
		(net "M_D_CPU0_SB_DQS_DN<8>")
	)
	(segment
		(start 330.12126 -291.425884)
		(end 330.129642 -291.421058)
		(width 0.09525)
		(layer "In4.Cu")
		(net "M_D_CPU0_SB_DQS_DN<8>")
	)
	(segment
		(start 325.101204 -295.313862)
		(end 325.184516 -295.314116)
		(width 0.09525)
		(layer "In4.Cu")
		(net "M_D_CPU0_SB_DQS_DN<8>")
	)
	(segment
		(start 303.924208 -314.57011)
		(end 304.041048 -314.68695)
		(width 0.16002)
		(layer "In4.Cu")
		(net "M_D_CPU0_SB_DQS_DN<8>")
	)
	(segment
		(start 283.570426 -313.79541)
		(end 283.999432 -314.224416)
		(width 0.16002)
		(layer "In4.Cu")
		(net "M_D_CPU0_SB_DQS_DN<8>")
	)
	(segment
		(start 298.176442 -313.879992)
		(end 298.755054 -313.879992)
		(width 0.16002)
		(layer "In4.Cu")
		(net "M_D_CPU0_SB_DQS_DN<8>")
	)
	(segment
		(start 304.865786 -314.68695)
		(end 305.657504 -313.895232)
		(width 0.16002)
		(layer "In4.Cu")
		(net "M_D_CPU0_SB_DQS_DN<8>")
	)
	(segment
		(start 340.411562 -291.448236)
		(end 340.43493 -291.361368)
		(width 0.09525)
		(layer "In4.Cu")
		(net "M_D_CPU0_SB_DQS_DN<8>")
	)
	(segment
		(start 285.726632 -314.224416)
		(end 286.56026 -315.058044)
		(width 0.16002)
		(layer "In4.Cu")
		(net "M_D_CPU0_SB_DQS_DN<8>")
	)
	(segment
		(start 307.192934 -313.895232)
		(end 310.145176 -312.672222)
		(width 0.16002)
		(layer "In4.Cu")
		(net "M_D_CPU0_SB_DQS_DN<8>")
	)
	(segment
		(start 325.08444 -295.330626)
		(end 325.101204 -295.313862)
		(width 0.09525)
		(layer "In4.Cu")
		(net "M_D_CPU0_SB_DQS_DN<8>")
	)
	(segment
		(start 310.145176 -312.672222)
		(end 322.292218 -300.52518)
		(width 0.16002)
		(layer "In4.Cu")
		(net "M_D_CPU0_SB_DQS_DN<8>")
	)
	(segment
		(start 340.092538 -291.421058)
		(end 340.10092 -291.425884)
		(width 0.09525)
		(layer "In4.Cu")
		(net "M_D_CPU0_SB_DQS_DN<8>")
	)
	(segment
		(start 287.04032 -315.058044)
		(end 287.15716 -314.941204)
		(width 0.16002)
		(layer "In4.Cu")
		(net "M_D_CPU0_SB_DQS_DN<8>")
	)
	(segment
		(start 280.635964 -313.784996)
		(end 280.91003 -314.059062)
		(width 0.16002)
		(layer "In4.Cu")
		(net "M_D_CPU0_SB_DQS_DN<8>")
	)
	(segment
		(start 322.292218 -300.52518)
		(end 322.292218 -298.122848)
		(width 0.16002)
		(layer "In4.Cu")
		(net "M_D_CPU0_SB_DQS_DN<8>")
	)
	(segment
		(start 305.657504 -313.895232)
		(end 307.192934 -313.895232)
		(width 0.16002)
		(layer "In4.Cu")
		(net "M_D_CPU0_SB_DQS_DN<8>")
	)
	(segment
		(start 282.06192 -313.79541)
		(end 283.570426 -313.79541)
		(width 0.16002)
		(layer "In4.Cu")
		(net "M_D_CPU0_SB_DQS_DN<8>")
	)
	(segment
		(start 291.233098 -313.88431)
		(end 294.029892 -315.058044)
		(width 0.16002)
		(layer "In4.Cu")
		(net "M_D_CPU0_SB_DQS_DN<8>")
	)
	(segment
		(start 294.029892 -315.058044)
		(end 295.818814 -315.058044)
		(width 0.16002)
		(layer "In4.Cu")
		(net "M_D_CPU0_SB_DQS_DN<8>")
	)
	(segment
		(start 290.612576 -313.88431)
		(end 291.233098 -313.88431)
		(width 0.16002)
		(layer "In4.Cu")
		(net "M_D_CPU0_SB_DQS_DN<8>")
	)
	(segment
		(start 299.064172 -314.194952)
		(end 299.546772 -314.68695)
		(width 0.16002)
		(layer "In4.Cu")
		(net "M_D_CPU0_SB_DQS_DN<8>")
	)
	(segment
		(start 327.620884 -291.472366)
		(end 328.061066 -291.472366)
		(width 0.09525)
		(layer "In4.Cu")
		(net "M_D_CPU0_SB_DQS_DN<8>")
	)
	(segment
		(start 287.63722 -314.941204)
		(end 287.75406 -315.058044)
		(width 0.16002)
		(layer "In4.Cu")
		(net "M_D_CPU0_SB_DQS_DN<8>")
	)
	(segment
		(start 331.63256 -291.421058)
		(end 331.640942 -291.425884)
		(width 0.09525)
		(layer "In4.Cu")
		(net "M_D_CPU0_SB_DQS_DN<8>")
	)
	(segment
		(start 299.546772 -314.68695)
		(end 303.327308 -314.68695)
		(width 0.16002)
		(layer "In4.Cu")
		(net "M_D_CPU0_SB_DQS_DN<8>")
	)
	(segment
		(start 303.444148 -314.57011)
		(end 303.924208 -314.57011)
		(width 0.16002)
		(layer "In4.Cu")
		(net "M_D_CPU0_SB_DQS_DN<8>")
	)
	(segment
		(start 297.38447 -314.409328)
		(end 298.176442 -313.879992)
		(width 0.16002)
		(layer "In4.Cu")
		(net "M_D_CPU0_SB_DQS_DN<8>")
	)
	(segment
		(start 325.482458 -294.40759)
		(end 325.646542 -294.011858)
		(width 0.09525)
		(layer "In4.Cu")
		(net "M_D_CPU0_SB_DQS_DN<8>")
	)
	(segment
		(start 330.692506 -291.421058)
		(end 330.700888 -291.425884)
		(width 0.09525)
		(layer "In4.Cu")
		(net "M_D_CPU0_SB_DQS_DN<8>")
	)
	(arc
		(start 338.58962 -291.421058)
		(mid 338.871052 -291.345303)
		(end 339.152484 -291.421058)
		(width 0.09525)
		(layer "In4.Cu")
		(net "M_D_CPU0_SB_DQS_DN<8>")
	)
	(arc
		(start 334.452468 -291.421058)
		(mid 334.636243 -291.47183)
		(end 334.821276 -291.425884)
		(width 0.09525)
		(layer "In4.Cu")
		(net "M_D_CPU0_SB_DQS_DN<8>")
	)
	(arc
		(start 331.069696 -291.421058)
		(mid 331.351128 -291.345303)
		(end 331.63256 -291.421058)
		(width 0.09525)
		(layer "In4.Cu")
		(net "M_D_CPU0_SB_DQS_DN<8>")
	)
	(arc
		(start 333.889604 -291.421058)
		(mid 334.171036 -291.345303)
		(end 334.452468 -291.421058)
		(width 0.09525)
		(layer "In4.Cu")
		(net "M_D_CPU0_SB_DQS_DN<8>")
	)
	(arc
		(start 333.512414 -291.421058)
		(mid 333.696189 -291.47183)
		(end 333.881222 -291.425884)
		(width 0.09525)
		(layer "In4.Cu")
		(net "M_D_CPU0_SB_DQS_DN<8>")
	)
	(arc
		(start 328.061066 -291.472366)
		(mid 328.158812 -291.459171)
		(end 328.249788 -291.421058)
		(width 0.09525)
		(layer "In4.Cu")
		(net "M_D_CPU0_SB_DQS_DN<8>")
	)
	(arc
		(start 332.572614 -291.421058)
		(mid 332.761082 -291.471735)
		(end 332.94955 -291.421058)
		(width 0.09525)
		(layer "In4.Cu")
		(net "M_D_CPU0_SB_DQS_DN<8>")
	)
	(arc
		(start 335.400904 -291.425884)
		(mid 335.585936 -291.471798)
		(end 335.769712 -291.421058)
		(width 0.09525)
		(layer "In4.Cu")
		(net "M_D_CPU0_SB_DQS_DN<8>")
	)
	(arc
		(start 339.152484 -291.421058)
		(mid 339.336259 -291.47183)
		(end 339.521292 -291.425884)
		(width 0.09525)
		(layer "In4.Cu")
		(net "M_D_CPU0_SB_DQS_DN<8>")
	)
	(arc
		(start 328.812652 -291.421058)
		(mid 329.00112 -291.471735)
		(end 329.189588 -291.421058)
		(width 0.09525)
		(layer "In4.Cu")
		(net "M_D_CPU0_SB_DQS_DN<8>")
	)
	(arc
		(start 332.00975 -291.421058)
		(mid 332.291182 -291.345303)
		(end 332.572614 -291.421058)
		(width 0.09525)
		(layer "In4.Cu")
		(net "M_D_CPU0_SB_DQS_DN<8>")
	)
	(arc
		(start 328.249788 -291.421058)
		(mid 328.53122 -291.345303)
		(end 328.812652 -291.421058)
		(width 0.09525)
		(layer "In4.Cu")
		(net "M_D_CPU0_SB_DQS_DN<8>")
	)
	(arc
		(start 329.752452 -291.421058)
		(mid 329.936227 -291.47183)
		(end 330.12126 -291.425884)
		(width 0.09525)
		(layer "In4.Cu")
		(net "M_D_CPU0_SB_DQS_DN<8>")
	)
	(arc
		(start 329.189588 -291.421058)
		(mid 329.47102 -291.345303)
		(end 329.752452 -291.421058)
		(width 0.09525)
		(layer "In4.Cu")
		(net "M_D_CPU0_SB_DQS_DN<8>")
	)
	(arc
		(start 331.640942 -291.425884)
		(mid 331.825974 -291.471798)
		(end 332.00975 -291.421058)
		(width 0.09525)
		(layer "In4.Cu")
		(net "M_D_CPU0_SB_DQS_DN<8>")
	)
	(arc
		(start 335.769712 -291.421058)
		(mid 336.051144 -291.345303)
		(end 336.332576 -291.421058)
		(width 0.09525)
		(layer "In4.Cu")
		(net "M_D_CPU0_SB_DQS_DN<8>")
	)
	(arc
		(start 336.709766 -291.421058)
		(mid 336.991198 -291.345303)
		(end 337.27263 -291.421058)
		(width 0.09525)
		(layer "In4.Cu")
		(net "M_D_CPU0_SB_DQS_DN<8>")
	)
	(arc
		(start 330.700888 -291.425884)
		(mid 330.88592 -291.471798)
		(end 331.069696 -291.421058)
		(width 0.09525)
		(layer "In4.Cu")
		(net "M_D_CPU0_SB_DQS_DN<8>")
	)
	(arc
		(start 340.10092 -291.425884)
		(mid 340.253815 -291.470712)
		(end 340.411562 -291.448236)
		(width 0.09525)
		(layer "In4.Cu")
		(net "M_D_CPU0_SB_DQS_DN<8>")
	)
	(arc
		(start 336.340958 -291.425884)
		(mid 336.52599 -291.471798)
		(end 336.709766 -291.421058)
		(width 0.09525)
		(layer "In4.Cu")
		(net "M_D_CPU0_SB_DQS_DN<8>")
	)
	(arc
		(start 334.829658 -291.421058)
		(mid 335.11109 -291.345303)
		(end 335.392522 -291.421058)
		(width 0.09525)
		(layer "In4.Cu")
		(net "M_D_CPU0_SB_DQS_DN<8>")
	)
	(arc
		(start 339.529674 -291.421058)
		(mid 339.811106 -291.345303)
		(end 340.092538 -291.421058)
		(width 0.09525)
		(layer "In4.Cu")
		(net "M_D_CPU0_SB_DQS_DN<8>")
	)
	(arc
		(start 337.27263 -291.421058)
		(mid 337.461098 -291.471735)
		(end 337.649566 -291.421058)
		(width 0.09525)
		(layer "In4.Cu")
		(net "M_D_CPU0_SB_DQS_DN<8>")
	)
	(arc
		(start 332.94955 -291.421058)
		(mid 333.230982 -291.345303)
		(end 333.512414 -291.421058)
		(width 0.09525)
		(layer "In4.Cu")
		(net "M_D_CPU0_SB_DQS_DN<8>")
	)
	(arc
		(start 330.129642 -291.421058)
		(mid 330.411074 -291.345303)
		(end 330.692506 -291.421058)
		(width 0.09525)
		(layer "In4.Cu")
		(net "M_D_CPU0_SB_DQS_DN<8>")
	)
	(arc
		(start 338.21243 -291.421058)
		(mid 338.396205 -291.47183)
		(end 338.581238 -291.425884)
		(width 0.09525)
		(layer "In4.Cu")
		(net "M_D_CPU0_SB_DQS_DN<8>")
	)
	(arc
		(start 337.649566 -291.421058)
		(mid 337.930998 -291.345303)
		(end 338.21243 -291.421058)
		(width 0.09525)
		(layer "In4.Cu")
		(net "M_D_CPU0_SB_DQS_DN<8>")
	)
	(segment
		(start 340.747858 -285.970218)
		(end 340.281006 -286.236156)
		(width 0.12954)
		(layer "F.Cu")
		(net "M_D_CPU0_SB_DQS_DN<7>")
	)
	(segment
		(start 325.893684 -286.612838)
		(end 326.179942 -286.612838)
		(width 0.09525)
		(layer "In4.Cu")
		(net "M_D_CPU0_SB_DQS_DN<7>")
	)
	(segment
		(start 340.411562 -286.588454)
		(end 340.43493 -286.501586)
		(width 0.09525)
		(layer "In4.Cu")
		(net "M_D_CPU0_SB_DQS_DN<7>")
	)
	(segment
		(start 284.604968 -304.874422)
		(end 285.260542 -305.145694)
		(width 0.16002)
		(layer "In4.Cu")
		(net "M_D_CPU0_SB_DQS_DN<7>")
	)
	(segment
		(start 327.308718 -286.561276)
		(end 327.32345 -286.55264)
		(width 0.09525)
		(layer "In4.Cu")
		(net "M_D_CPU0_SB_DQS_DN<7>")
	)
	(segment
		(start 316.602618 -296.325544)
		(end 316.602618 -295.10609)
		(width 0.16002)
		(layer "In4.Cu")
		(net "M_D_CPU0_SB_DQS_DN<7>")
	)
	(segment
		(start 334.821276 -286.566102)
		(end 334.829658 -286.561276)
		(width 0.09525)
		(layer "In4.Cu")
		(net "M_D_CPU0_SB_DQS_DN<7>")
	)
	(segment
		(start 295.286176 -305.70805)
		(end 296.02303 -305.70805)
		(width 0.16002)
		(layer "In4.Cu")
		(net "M_D_CPU0_SB_DQS_DN<7>")
	)
	(segment
		(start 291.54374 -304.857912)
		(end 293.233602 -304.857912)
		(width 0.16002)
		(layer "In4.Cu")
		(net "M_D_CPU0_SB_DQS_DN<7>")
	)
	(segment
		(start 291.190426 -304.504598)
		(end 291.54374 -304.857912)
		(width 0.16002)
		(layer "In4.Cu")
		(net "M_D_CPU0_SB_DQS_DN<7>")
	)
	(segment
		(start 297.02252 -305.29403)
		(end 298.166282 -304.529998)
		(width 0.16002)
		(layer "In4.Cu")
		(net "M_D_CPU0_SB_DQS_DN<7>")
	)
	(segment
		(start 282.923996 -304.481484)
		(end 283.6291 -304.481484)
		(width 0.16002)
		(layer "In4.Cu")
		(net "M_D_CPU0_SB_DQS_DN<7>")
	)
	(segment
		(start 340.43493 -286.501586)
		(end 340.281006 -286.236156)
		(width 0.09525)
		(layer "In4.Cu")
		(net "M_D_CPU0_SB_DQS_DN<7>")
	)
	(segment
		(start 296.02303 -305.70805)
		(end 297.02252 -305.29403)
		(width 0.16002)
		(layer "In4.Cu")
		(net "M_D_CPU0_SB_DQS_DN<7>")
	)
	(segment
		(start 300.846998 -304.857912)
		(end 302.096424 -305.37531)
		(width 0.16002)
		(layer "In4.Cu")
		(net "M_D_CPU0_SB_DQS_DN<7>")
	)
	(segment
		(start 303.357788 -305.37531)
		(end 304.805842 -305.37531)
		(width 0.16002)
		(layer "In4.Cu")
		(net "M_D_CPU0_SB_DQS_DN<7>")
	)
	(segment
		(start 302.096424 -305.37531)
		(end 302.644048 -305.37531)
		(width 0.16002)
		(layer "In4.Cu")
		(net "M_D_CPU0_SB_DQS_DN<7>")
	)
	(segment
		(start 339.521292 -286.566102)
		(end 339.529674 -286.561276)
		(width 0.09525)
		(layer "In4.Cu")
		(net "M_D_CPU0_SB_DQS_DN<7>")
	)
	(segment
		(start 302.760888 -305.25847)
		(end 303.240948 -305.25847)
		(width 0.16002)
		(layer "In4.Cu")
		(net "M_D_CPU0_SB_DQS_DN<7>")
	)
	(segment
		(start 309.22468 -303.703482)
		(end 316.602618 -296.325544)
		(width 0.16002)
		(layer "In4.Cu")
		(net "M_D_CPU0_SB_DQS_DN<7>")
	)
	(segment
		(start 316.602618 -295.10609)
		(end 323.895974 -287.813242)
		(width 0.16002)
		(layer "In4.Cu")
		(net "M_D_CPU0_SB_DQS_DN<7>")
	)
	(segment
		(start 324.891654 -286.901382)
		(end 325.60514 -286.901382)
		(width 0.09525)
		(layer "In4.Cu")
		(net "M_D_CPU0_SB_DQS_DN<7>")
	)
	(segment
		(start 338.581238 -286.566102)
		(end 338.58962 -286.561276)
		(width 0.09525)
		(layer "In4.Cu")
		(net "M_D_CPU0_SB_DQS_DN<7>")
	)
	(segment
		(start 323.996558 -287.796478)
		(end 324.891654 -286.901382)
		(width 0.09525)
		(layer "In4.Cu")
		(net "M_D_CPU0_SB_DQS_DN<7>")
	)
	(segment
		(start 340.092538 -286.561276)
		(end 340.10092 -286.566102)
		(width 0.09525)
		(layer "In4.Cu")
		(net "M_D_CPU0_SB_DQS_DN<7>")
	)
	(segment
		(start 298.694602 -304.529998)
		(end 299.48632 -304.857912)
		(width 0.16002)
		(layer "In4.Cu")
		(net "M_D_CPU0_SB_DQS_DN<7>")
	)
	(segment
		(start 323.912738 -287.796478)
		(end 323.996558 -287.796478)
		(width 0.09525)
		(layer "In4.Cu")
		(net "M_D_CPU0_SB_DQS_DN<7>")
	)
	(segment
		(start 335.392522 -286.561276)
		(end 335.400904 -286.566102)
		(width 0.09525)
		(layer "In4.Cu")
		(net "M_D_CPU0_SB_DQS_DN<7>")
	)
	(segment
		(start 280.91003 -304.709068)
		(end 281.502612 -304.709068)
		(width 0.16002)
		(layer "In4.Cu")
		(net "M_D_CPU0_SB_DQS_DN<7>")
	)
	(segment
		(start 328.241406 -286.566102)
		(end 328.249788 -286.561276)
		(width 0.09525)
		(layer "In4.Cu")
		(net "M_D_CPU0_SB_DQS_DN<7>")
	)
	(segment
		(start 336.332576 -286.561276)
		(end 336.340958 -286.566102)
		(width 0.09525)
		(layer "In4.Cu")
		(net "M_D_CPU0_SB_DQS_DN<7>")
	)
	(segment
		(start 326.916288 -286.551878)
		(end 326.932036 -286.561022)
		(width 0.09525)
		(layer "In4.Cu")
		(net "M_D_CPU0_SB_DQS_DN<7>")
	)
	(segment
		(start 325.60514 -286.901382)
		(end 325.893684 -286.612838)
		(width 0.09525)
		(layer "In4.Cu")
		(net "M_D_CPU0_SB_DQS_DN<7>")
	)
	(segment
		(start 281.502612 -304.709068)
		(end 281.619452 -304.592228)
		(width 0.16002)
		(layer "In4.Cu")
		(net "M_D_CPU0_SB_DQS_DN<7>")
	)
	(segment
		(start 304.805842 -305.37531)
		(end 305.568604 -304.612548)
		(width 0.16002)
		(layer "In4.Cu")
		(net "M_D_CPU0_SB_DQS_DN<7>")
	)
	(segment
		(start 293.233602 -304.857912)
		(end 295.286176 -305.70805)
		(width 0.16002)
		(layer "In4.Cu")
		(net "M_D_CPU0_SB_DQS_DN<7>")
	)
	(segment
		(start 308.380384 -304.05324)
		(end 309.22468 -303.703482)
		(width 0.16002)
		(layer "In4.Cu")
		(net "M_D_CPU0_SB_DQS_DN<7>")
	)
	(segment
		(start 290.155884 -304.94224)
		(end 290.593526 -304.504598)
		(width 0.16002)
		(layer "In4.Cu")
		(net "M_D_CPU0_SB_DQS_DN<7>")
	)
	(segment
		(start 326.932036 -286.561022)
		(end 326.946006 -286.568896)
		(width 0.09525)
		(layer "In4.Cu")
		(net "M_D_CPU0_SB_DQS_DN<7>")
	)
	(segment
		(start 288.0868 -305.70805)
		(end 288.306764 -305.70805)
		(width 0.16002)
		(layer "In4.Cu")
		(net "M_D_CPU0_SB_DQS_DN<7>")
	)
	(segment
		(start 299.48632 -304.857912)
		(end 300.846998 -304.857912)
		(width 0.16002)
		(layer "In4.Cu")
		(net "M_D_CPU0_SB_DQS_DN<7>")
	)
	(segment
		(start 283.6291 -304.481484)
		(end 284.022038 -304.874422)
		(width 0.16002)
		(layer "In4.Cu")
		(net "M_D_CPU0_SB_DQS_DN<7>")
	)
	(segment
		(start 282.099512 -304.592228)
		(end 282.216352 -304.709068)
		(width 0.16002)
		(layer "In4.Cu")
		(net "M_D_CPU0_SB_DQS_DN<7>")
	)
	(segment
		(start 288.306764 -305.70805)
		(end 290.155884 -304.94224)
		(width 0.16002)
		(layer "In4.Cu")
		(net "M_D_CPU0_SB_DQS_DN<7>")
	)
	(segment
		(start 330.12126 -286.566102)
		(end 330.129642 -286.561276)
		(width 0.09525)
		(layer "In4.Cu")
		(net "M_D_CPU0_SB_DQS_DN<7>")
	)
	(segment
		(start 280.635964 -304.435002)
		(end 280.91003 -304.709068)
		(width 0.16002)
		(layer "In4.Cu")
		(net "M_D_CPU0_SB_DQS_DN<7>")
	)
	(segment
		(start 333.881222 -286.566102)
		(end 333.889604 -286.561276)
		(width 0.09525)
		(layer "In4.Cu")
		(net "M_D_CPU0_SB_DQS_DN<7>")
	)
	(segment
		(start 282.216352 -304.709068)
		(end 282.696412 -304.709068)
		(width 0.16002)
		(layer "In4.Cu")
		(net "M_D_CPU0_SB_DQS_DN<7>")
	)
	(segment
		(start 323.895974 -287.813242)
		(end 323.912738 -287.796478)
		(width 0.09525)
		(layer "In4.Cu")
		(net "M_D_CPU0_SB_DQS_DN<7>")
	)
	(segment
		(start 298.166282 -304.529998)
		(end 298.694602 -304.529998)
		(width 0.16002)
		(layer "In4.Cu")
		(net "M_D_CPU0_SB_DQS_DN<7>")
	)
	(segment
		(start 281.619452 -304.592228)
		(end 282.099512 -304.592228)
		(width 0.16002)
		(layer "In4.Cu")
		(net "M_D_CPU0_SB_DQS_DN<7>")
	)
	(segment
		(start 305.568604 -304.612548)
		(end 308.380384 -304.05324)
		(width 0.16002)
		(layer "In4.Cu")
		(net "M_D_CPU0_SB_DQS_DN<7>")
	)
	(segment
		(start 330.692506 -286.561276)
		(end 330.700888 -286.566102)
		(width 0.09525)
		(layer "In4.Cu")
		(net "M_D_CPU0_SB_DQS_DN<7>")
	)
	(segment
		(start 302.644048 -305.37531)
		(end 302.760888 -305.25847)
		(width 0.16002)
		(layer "In4.Cu")
		(net "M_D_CPU0_SB_DQS_DN<7>")
	)
	(segment
		(start 284.022038 -304.874422)
		(end 284.604968 -304.874422)
		(width 0.16002)
		(layer "In4.Cu")
		(net "M_D_CPU0_SB_DQS_DN<7>")
	)
	(segment
		(start 331.63256 -286.561276)
		(end 331.640942 -286.566102)
		(width 0.09525)
		(layer "In4.Cu")
		(net "M_D_CPU0_SB_DQS_DN<7>")
	)
	(segment
		(start 290.593526 -304.504598)
		(end 291.190426 -304.504598)
		(width 0.16002)
		(layer "In4.Cu")
		(net "M_D_CPU0_SB_DQS_DN<7>")
	)
	(segment
		(start 303.240948 -305.25847)
		(end 303.357788 -305.37531)
		(width 0.16002)
		(layer "In4.Cu")
		(net "M_D_CPU0_SB_DQS_DN<7>")
	)
	(segment
		(start 282.696412 -304.709068)
		(end 282.923996 -304.481484)
		(width 0.16002)
		(layer "In4.Cu")
		(net "M_D_CPU0_SB_DQS_DN<7>")
	)
	(segment
		(start 285.260542 -305.145694)
		(end 288.0868 -305.70805)
		(width 0.16002)
		(layer "In4.Cu")
		(net "M_D_CPU0_SB_DQS_DN<7>")
	)
	(arc
		(start 330.700888 -286.566102)
		(mid 330.88592 -286.612016)
		(end 331.069696 -286.561276)
		(width 0.09525)
		(layer "In4.Cu")
		(net "M_D_CPU0_SB_DQS_DN<7>")
	)
	(arc
		(start 326.179942 -286.612838)
		(mid 326.277966 -286.599577)
		(end 326.369172 -286.561276)
		(width 0.09525)
		(layer "In4.Cu")
		(net "M_D_CPU0_SB_DQS_DN<7>")
	)
	(arc
		(start 326.946006 -286.568896)
		(mid 327.12835 -286.611794)
		(end 327.308718 -286.561276)
		(width 0.09525)
		(layer "In4.Cu")
		(net "M_D_CPU0_SB_DQS_DN<7>")
	)
	(arc
		(start 337.649566 -286.561276)
		(mid 337.930998 -286.485487)
		(end 338.21243 -286.561276)
		(width 0.09525)
		(layer "In4.Cu")
		(net "M_D_CPU0_SB_DQS_DN<7>")
	)
	(arc
		(start 332.94955 -286.561276)
		(mid 333.230982 -286.485487)
		(end 333.512414 -286.561276)
		(width 0.09525)
		(layer "In4.Cu")
		(net "M_D_CPU0_SB_DQS_DN<7>")
	)
	(arc
		(start 338.58962 -286.561276)
		(mid 338.871052 -286.485487)
		(end 339.152484 -286.561276)
		(width 0.09525)
		(layer "In4.Cu")
		(net "M_D_CPU0_SB_DQS_DN<7>")
	)
	(arc
		(start 334.829658 -286.561276)
		(mid 335.11109 -286.485487)
		(end 335.392522 -286.561276)
		(width 0.09525)
		(layer "In4.Cu")
		(net "M_D_CPU0_SB_DQS_DN<7>")
	)
	(arc
		(start 326.369172 -286.561276)
		(mid 326.641503 -286.485314)
		(end 326.916288 -286.551878)
		(width 0.09525)
		(layer "In4.Cu")
		(net "M_D_CPU0_SB_DQS_DN<7>")
	)
	(arc
		(start 327.87209 -286.561276)
		(mid 328.056119 -286.612175)
		(end 328.241406 -286.566102)
		(width 0.09525)
		(layer "In4.Cu")
		(net "M_D_CPU0_SB_DQS_DN<7>")
	)
	(arc
		(start 327.32345 -286.55264)
		(mid 327.598909 -286.485225)
		(end 327.87209 -286.561276)
		(width 0.09525)
		(layer "In4.Cu")
		(net "M_D_CPU0_SB_DQS_DN<7>")
	)
	(arc
		(start 328.249788 -286.561276)
		(mid 328.53122 -286.485487)
		(end 328.812652 -286.561276)
		(width 0.09525)
		(layer "In4.Cu")
		(net "M_D_CPU0_SB_DQS_DN<7>")
	)
	(arc
		(start 332.00975 -286.561276)
		(mid 332.291182 -286.485487)
		(end 332.572614 -286.561276)
		(width 0.09525)
		(layer "In4.Cu")
		(net "M_D_CPU0_SB_DQS_DN<7>")
	)
	(arc
		(start 339.529674 -286.561276)
		(mid 339.811106 -286.485487)
		(end 340.092538 -286.561276)
		(width 0.09525)
		(layer "In4.Cu")
		(net "M_D_CPU0_SB_DQS_DN<7>")
	)
	(arc
		(start 334.452468 -286.561276)
		(mid 334.636243 -286.612048)
		(end 334.821276 -286.566102)
		(width 0.09525)
		(layer "In4.Cu")
		(net "M_D_CPU0_SB_DQS_DN<7>")
	)
	(arc
		(start 332.572614 -286.561276)
		(mid 332.761082 -286.611953)
		(end 332.94955 -286.561276)
		(width 0.09525)
		(layer "In4.Cu")
		(net "M_D_CPU0_SB_DQS_DN<7>")
	)
	(arc
		(start 336.709766 -286.561276)
		(mid 336.991198 -286.485487)
		(end 337.27263 -286.561276)
		(width 0.09525)
		(layer "In4.Cu")
		(net "M_D_CPU0_SB_DQS_DN<7>")
	)
	(arc
		(start 331.640942 -286.566102)
		(mid 331.825974 -286.612016)
		(end 332.00975 -286.561276)
		(width 0.09525)
		(layer "In4.Cu")
		(net "M_D_CPU0_SB_DQS_DN<7>")
	)
	(arc
		(start 330.129642 -286.561276)
		(mid 330.411074 -286.485487)
		(end 330.692506 -286.561276)
		(width 0.09525)
		(layer "In4.Cu")
		(net "M_D_CPU0_SB_DQS_DN<7>")
	)
	(arc
		(start 328.812652 -286.561276)
		(mid 329.00112 -286.611953)
		(end 329.189588 -286.561276)
		(width 0.09525)
		(layer "In4.Cu")
		(net "M_D_CPU0_SB_DQS_DN<7>")
	)
	(arc
		(start 333.889604 -286.561276)
		(mid 334.171036 -286.485487)
		(end 334.452468 -286.561276)
		(width 0.09525)
		(layer "In4.Cu")
		(net "M_D_CPU0_SB_DQS_DN<7>")
	)
	(arc
		(start 337.27263 -286.561276)
		(mid 337.461098 -286.611953)
		(end 337.649566 -286.561276)
		(width 0.09525)
		(layer "In4.Cu")
		(net "M_D_CPU0_SB_DQS_DN<7>")
	)
	(arc
		(start 335.769712 -286.561276)
		(mid 336.051144 -286.485487)
		(end 336.332576 -286.561276)
		(width 0.09525)
		(layer "In4.Cu")
		(net "M_D_CPU0_SB_DQS_DN<7>")
	)
	(arc
		(start 329.752452 -286.561276)
		(mid 329.936227 -286.612048)
		(end 330.12126 -286.566102)
		(width 0.09525)
		(layer "In4.Cu")
		(net "M_D_CPU0_SB_DQS_DN<7>")
	)
	(arc
		(start 340.10092 -286.566102)
		(mid 340.253815 -286.61093)
		(end 340.411562 -286.588454)
		(width 0.09525)
		(layer "In4.Cu")
		(net "M_D_CPU0_SB_DQS_DN<7>")
	)
	(arc
		(start 329.189588 -286.561276)
		(mid 329.47102 -286.485487)
		(end 329.752452 -286.561276)
		(width 0.09525)
		(layer "In4.Cu")
		(net "M_D_CPU0_SB_DQS_DN<7>")
	)
	(arc
		(start 338.21243 -286.561276)
		(mid 338.396205 -286.612048)
		(end 338.581238 -286.566102)
		(width 0.09525)
		(layer "In4.Cu")
		(net "M_D_CPU0_SB_DQS_DN<7>")
	)
	(arc
		(start 339.152484 -286.561276)
		(mid 339.336259 -286.612048)
		(end 339.521292 -286.566102)
		(width 0.09525)
		(layer "In4.Cu")
		(net "M_D_CPU0_SB_DQS_DN<7>")
	)
	(arc
		(start 333.512414 -286.561276)
		(mid 333.696189 -286.612048)
		(end 333.881222 -286.566102)
		(width 0.09525)
		(layer "In4.Cu")
		(net "M_D_CPU0_SB_DQS_DN<7>")
	)
	(arc
		(start 331.069696 -286.561276)
		(mid 331.351128 -286.485487)
		(end 331.63256 -286.561276)
		(width 0.09525)
		(layer "In4.Cu")
		(net "M_D_CPU0_SB_DQS_DN<7>")
	)
	(arc
		(start 335.400904 -286.566102)
		(mid 335.585936 -286.612016)
		(end 335.769712 -286.561276)
		(width 0.09525)
		(layer "In4.Cu")
		(net "M_D_CPU0_SB_DQS_DN<7>")
	)
	(arc
		(start 336.340958 -286.566102)
		(mid 336.52599 -286.612016)
		(end 336.709766 -286.561276)
		(width 0.09525)
		(layer "In4.Cu")
		(net "M_D_CPU0_SB_DQS_DN<7>")
	)
	(segment
		(start 340.747858 -281.110182)
		(end 340.281006 -281.37612)
		(width 0.12954)
		(layer "F.Cu")
		(net "M_D_CPU0_SB_DQS_DN<6>")
	)
	(segment
		(start 281.28722 -295.359074)
		(end 282.16225 -295.17721)
		(width 0.16002)
		(layer "In4.Cu")
		(net "M_D_CPU0_SB_DQS_DN<6>")
	)
	(segment
		(start 298.20997 -295.180004)
		(end 298.830238 -295.180004)
		(width 0.16002)
		(layer "In4.Cu")
		(net "M_D_CPU0_SB_DQS_DN<6>")
	)
	(segment
		(start 290.631372 -295.192196)
		(end 291.050726 -295.192196)
		(width 0.16002)
		(layer "In4.Cu")
		(net "M_D_CPU0_SB_DQS_DN<6>")
	)
	(segment
		(start 295.48582 -296.358056)
		(end 295.963594 -296.358056)
		(width 0.16002)
		(layer "In4.Cu")
		(net "M_D_CPU0_SB_DQS_DN<6>")
	)
	(segment
		(start 291.813742 -295.507918)
		(end 293.917116 -295.507918)
		(width 0.16002)
		(layer "In4.Cu")
		(net "M_D_CPU0_SB_DQS_DN<6>")
	)
	(segment
		(start 338.581238 -281.706066)
		(end 338.58962 -281.70124)
		(width 0.09525)
		(layer "In4.Cu")
		(net "M_D_CPU0_SB_DQS_DN<6>")
	)
	(segment
		(start 336.332576 -281.70124)
		(end 336.340958 -281.706066)
		(width 0.09525)
		(layer "In4.Cu")
		(net "M_D_CPU0_SB_DQS_DN<6>")
	)
	(segment
		(start 288.53003 -296.358056)
		(end 289.476434 -295.966134)
		(width 0.16002)
		(layer "In4.Cu")
		(net "M_D_CPU0_SB_DQS_DN<6>")
	)
	(segment
		(start 289.476434 -295.966134)
		(end 290.631372 -295.192196)
		(width 0.16002)
		(layer "In4.Cu")
		(net "M_D_CPU0_SB_DQS_DN<6>")
	)
	(segment
		(start 335.392522 -281.70124)
		(end 335.400904 -281.706066)
		(width 0.09525)
		(layer "In4.Cu")
		(net "M_D_CPU0_SB_DQS_DN<6>")
	)
	(segment
		(start 287.600136 -296.241216)
		(end 287.716976 -296.358056)
		(width 0.16002)
		(layer "In4.Cu")
		(net "M_D_CPU0_SB_DQS_DN<6>")
	)
	(segment
		(start 287.003236 -296.358056)
		(end 287.120076 -296.241216)
		(width 0.16002)
		(layer "In4.Cu")
		(net "M_D_CPU0_SB_DQS_DN<6>")
	)
	(segment
		(start 299.554646 -295.507918)
		(end 301.020988 -295.507918)
		(width 0.16002)
		(layer "In4.Cu")
		(net "M_D_CPU0_SB_DQS_DN<6>")
	)
	(segment
		(start 340.092538 -281.70124)
		(end 340.10092 -281.706066)
		(width 0.09525)
		(layer "In4.Cu")
		(net "M_D_CPU0_SB_DQS_DN<6>")
	)
	(segment
		(start 330.12126 -281.706066)
		(end 330.129642 -281.70124)
		(width 0.09525)
		(layer "In4.Cu")
		(net "M_D_CPU0_SB_DQS_DN<6>")
	)
	(segment
		(start 301.020988 -295.507918)
		(end 301.49038 -295.97731)
		(width 0.16002)
		(layer "In4.Cu")
		(net "M_D_CPU0_SB_DQS_DN<6>")
	)
	(segment
		(start 324.377558 -281.731212)
		(end 324.565518 -281.543252)
		(width 0.09525)
		(layer "In4.Cu")
		(net "M_D_CPU0_SB_DQS_DN<6>")
	)
	(segment
		(start 283.672026 -295.17721)
		(end 286.523176 -296.358056)
		(width 0.16002)
		(layer "In4.Cu")
		(net "M_D_CPU0_SB_DQS_DN<6>")
	)
	(segment
		(start 298.830238 -295.180004)
		(end 299.554646 -295.507918)
		(width 0.16002)
		(layer "In4.Cu")
		(net "M_D_CPU0_SB_DQS_DN<6>")
	)
	(segment
		(start 280.91003 -295.359074)
		(end 281.28722 -295.359074)
		(width 0.16002)
		(layer "In4.Cu")
		(net "M_D_CPU0_SB_DQS_DN<6>")
	)
	(segment
		(start 308.422548 -295.180004)
		(end 321.930522 -281.67203)
		(width 0.16002)
		(layer "In4.Cu")
		(net "M_D_CPU0_SB_DQS_DN<6>")
	)
	(segment
		(start 297.234102 -295.831768)
		(end 298.20997 -295.180004)
		(width 0.16002)
		(layer "In4.Cu")
		(net "M_D_CPU0_SB_DQS_DN<6>")
	)
	(segment
		(start 323.895974 -281.67203)
		(end 323.919596 -281.67203)
		(width 0.09525)
		(layer "In4.Cu")
		(net "M_D_CPU0_SB_DQS_DN<6>")
	)
	(segment
		(start 286.523176 -296.358056)
		(end 287.003236 -296.358056)
		(width 0.16002)
		(layer "In4.Cu")
		(net "M_D_CPU0_SB_DQS_DN<6>")
	)
	(segment
		(start 295.963594 -296.358056)
		(end 297.234102 -295.831768)
		(width 0.16002)
		(layer "In4.Cu")
		(net "M_D_CPU0_SB_DQS_DN<6>")
	)
	(segment
		(start 340.411562 -281.728418)
		(end 340.43493 -281.64155)
		(width 0.09525)
		(layer "In4.Cu")
		(net "M_D_CPU0_SB_DQS_DN<6>")
	)
	(segment
		(start 291.050726 -295.192196)
		(end 291.813742 -295.507918)
		(width 0.16002)
		(layer "In4.Cu")
		(net "M_D_CPU0_SB_DQS_DN<6>")
	)
	(segment
		(start 333.881222 -281.706066)
		(end 333.889604 -281.70124)
		(width 0.09525)
		(layer "In4.Cu")
		(net "M_D_CPU0_SB_DQS_DN<6>")
	)
	(segment
		(start 323.978778 -281.731212)
		(end 324.377558 -281.731212)
		(width 0.09525)
		(layer "In4.Cu")
		(net "M_D_CPU0_SB_DQS_DN<6>")
	)
	(segment
		(start 294.259 -295.849802)
		(end 295.48582 -296.358056)
		(width 0.16002)
		(layer "In4.Cu")
		(net "M_D_CPU0_SB_DQS_DN<6>")
	)
	(segment
		(start 334.821276 -281.706066)
		(end 334.829658 -281.70124)
		(width 0.09525)
		(layer "In4.Cu")
		(net "M_D_CPU0_SB_DQS_DN<6>")
	)
	(segment
		(start 328.241406 -281.706066)
		(end 328.249788 -281.70124)
		(width 0.09525)
		(layer "In4.Cu")
		(net "M_D_CPU0_SB_DQS_DN<6>")
	)
	(segment
		(start 340.43493 -281.64155)
		(end 340.281006 -281.37612)
		(width 0.09525)
		(layer "In4.Cu")
		(net "M_D_CPU0_SB_DQS_DN<6>")
	)
	(segment
		(start 330.692506 -281.70124)
		(end 330.700888 -281.706066)
		(width 0.09525)
		(layer "In4.Cu")
		(net "M_D_CPU0_SB_DQS_DN<6>")
	)
	(segment
		(start 301.49038 -295.97731)
		(end 304.853848 -295.97731)
		(width 0.16002)
		(layer "In4.Cu")
		(net "M_D_CPU0_SB_DQS_DN<6>")
	)
	(segment
		(start 324.565518 -281.543252)
		(end 327.285604 -281.543252)
		(width 0.09525)
		(layer "In4.Cu")
		(net "M_D_CPU0_SB_DQS_DN<6>")
	)
	(segment
		(start 280.635964 -295.085008)
		(end 280.91003 -295.359074)
		(width 0.16002)
		(layer "In4.Cu")
		(net "M_D_CPU0_SB_DQS_DN<6>")
	)
	(segment
		(start 304.853848 -295.97731)
		(end 305.651154 -295.180004)
		(width 0.16002)
		(layer "In4.Cu")
		(net "M_D_CPU0_SB_DQS_DN<6>")
	)
	(segment
		(start 293.917116 -295.507918)
		(end 294.259 -295.849802)
		(width 0.16002)
		(layer "In4.Cu")
		(net "M_D_CPU0_SB_DQS_DN<6>")
	)
	(segment
		(start 321.930522 -281.67203)
		(end 323.895974 -281.67203)
		(width 0.16002)
		(layer "In4.Cu")
		(net "M_D_CPU0_SB_DQS_DN<6>")
	)
	(segment
		(start 287.716976 -296.358056)
		(end 288.53003 -296.358056)
		(width 0.16002)
		(layer "In4.Cu")
		(net "M_D_CPU0_SB_DQS_DN<6>")
	)
	(segment
		(start 287.120076 -296.241216)
		(end 287.600136 -296.241216)
		(width 0.16002)
		(layer "In4.Cu")
		(net "M_D_CPU0_SB_DQS_DN<6>")
	)
	(segment
		(start 339.521292 -281.706066)
		(end 339.529674 -281.70124)
		(width 0.09525)
		(layer "In4.Cu")
		(net "M_D_CPU0_SB_DQS_DN<6>")
	)
	(segment
		(start 305.651154 -295.180004)
		(end 308.422548 -295.180004)
		(width 0.16002)
		(layer "In4.Cu")
		(net "M_D_CPU0_SB_DQS_DN<6>")
	)
	(segment
		(start 331.63256 -281.70124)
		(end 331.640942 -281.706066)
		(width 0.09525)
		(layer "In4.Cu")
		(net "M_D_CPU0_SB_DQS_DN<6>")
	)
	(segment
		(start 323.919596 -281.67203)
		(end 323.978778 -281.731212)
		(width 0.09525)
		(layer "In4.Cu")
		(net "M_D_CPU0_SB_DQS_DN<6>")
	)
	(segment
		(start 282.16225 -295.17721)
		(end 283.672026 -295.17721)
		(width 0.16002)
		(layer "In4.Cu")
		(net "M_D_CPU0_SB_DQS_DN<6>")
	)
	(arc
		(start 332.94955 -281.70124)
		(mid 333.230982 -281.625485)
		(end 333.512414 -281.70124)
		(width 0.09525)
		(layer "In4.Cu")
		(net "M_D_CPU0_SB_DQS_DN<6>")
	)
	(arc
		(start 338.21243 -281.70124)
		(mid 338.396205 -281.752012)
		(end 338.581238 -281.706066)
		(width 0.09525)
		(layer "In4.Cu")
		(net "M_D_CPU0_SB_DQS_DN<6>")
	)
	(arc
		(start 334.829658 -281.70124)
		(mid 335.11109 -281.625485)
		(end 335.392522 -281.70124)
		(width 0.09525)
		(layer "In4.Cu")
		(net "M_D_CPU0_SB_DQS_DN<6>")
	)
	(arc
		(start 339.152484 -281.70124)
		(mid 339.336259 -281.752012)
		(end 339.521292 -281.706066)
		(width 0.09525)
		(layer "In4.Cu")
		(net "M_D_CPU0_SB_DQS_DN<6>")
	)
	(arc
		(start 327.87209 -281.70124)
		(mid 328.056119 -281.752139)
		(end 328.241406 -281.706066)
		(width 0.09525)
		(layer "In4.Cu")
		(net "M_D_CPU0_SB_DQS_DN<6>")
	)
	(arc
		(start 337.27263 -281.70124)
		(mid 337.461098 -281.751917)
		(end 337.649566 -281.70124)
		(width 0.09525)
		(layer "In4.Cu")
		(net "M_D_CPU0_SB_DQS_DN<6>")
	)
	(arc
		(start 329.189588 -281.70124)
		(mid 329.47102 -281.625485)
		(end 329.752452 -281.70124)
		(width 0.09525)
		(layer "In4.Cu")
		(net "M_D_CPU0_SB_DQS_DN<6>")
	)
	(arc
		(start 336.709766 -281.70124)
		(mid 336.991198 -281.625485)
		(end 337.27263 -281.70124)
		(width 0.09525)
		(layer "In4.Cu")
		(net "M_D_CPU0_SB_DQS_DN<6>")
	)
	(arc
		(start 339.529674 -281.70124)
		(mid 339.811106 -281.625485)
		(end 340.092538 -281.70124)
		(width 0.09525)
		(layer "In4.Cu")
		(net "M_D_CPU0_SB_DQS_DN<6>")
	)
	(arc
		(start 335.400904 -281.706066)
		(mid 335.585936 -281.75198)
		(end 335.769712 -281.70124)
		(width 0.09525)
		(layer "In4.Cu")
		(net "M_D_CPU0_SB_DQS_DN<6>")
	)
	(arc
		(start 340.10092 -281.706066)
		(mid 340.253815 -281.750894)
		(end 340.411562 -281.728418)
		(width 0.09525)
		(layer "In4.Cu")
		(net "M_D_CPU0_SB_DQS_DN<6>")
	)
	(arc
		(start 329.752452 -281.70124)
		(mid 329.936227 -281.752012)
		(end 330.12126 -281.706066)
		(width 0.09525)
		(layer "In4.Cu")
		(net "M_D_CPU0_SB_DQS_DN<6>")
	)
	(arc
		(start 330.700888 -281.706066)
		(mid 330.88592 -281.75198)
		(end 331.069696 -281.70124)
		(width 0.09525)
		(layer "In4.Cu")
		(net "M_D_CPU0_SB_DQS_DN<6>")
	)
	(arc
		(start 336.340958 -281.706066)
		(mid 336.52599 -281.75198)
		(end 336.709766 -281.70124)
		(width 0.09525)
		(layer "In4.Cu")
		(net "M_D_CPU0_SB_DQS_DN<6>")
	)
	(arc
		(start 332.00975 -281.70124)
		(mid 332.291182 -281.625485)
		(end 332.572614 -281.70124)
		(width 0.09525)
		(layer "In4.Cu")
		(net "M_D_CPU0_SB_DQS_DN<6>")
	)
	(arc
		(start 333.889604 -281.70124)
		(mid 334.171036 -281.625485)
		(end 334.452468 -281.70124)
		(width 0.09525)
		(layer "In4.Cu")
		(net "M_D_CPU0_SB_DQS_DN<6>")
	)
	(arc
		(start 328.249788 -281.70124)
		(mid 328.53122 -281.625485)
		(end 328.812652 -281.70124)
		(width 0.09525)
		(layer "In4.Cu")
		(net "M_D_CPU0_SB_DQS_DN<6>")
	)
	(arc
		(start 334.452468 -281.70124)
		(mid 334.636243 -281.752012)
		(end 334.821276 -281.706066)
		(width 0.09525)
		(layer "In4.Cu")
		(net "M_D_CPU0_SB_DQS_DN<6>")
	)
	(arc
		(start 337.649566 -281.70124)
		(mid 337.930998 -281.625485)
		(end 338.21243 -281.70124)
		(width 0.09525)
		(layer "In4.Cu")
		(net "M_D_CPU0_SB_DQS_DN<6>")
	)
	(arc
		(start 331.640942 -281.706066)
		(mid 331.825974 -281.75198)
		(end 332.00975 -281.70124)
		(width 0.09525)
		(layer "In4.Cu")
		(net "M_D_CPU0_SB_DQS_DN<6>")
	)
	(arc
		(start 333.512414 -281.70124)
		(mid 333.696189 -281.752012)
		(end 333.881222 -281.706066)
		(width 0.09525)
		(layer "In4.Cu")
		(net "M_D_CPU0_SB_DQS_DN<6>")
	)
	(arc
		(start 328.812652 -281.70124)
		(mid 329.00112 -281.751917)
		(end 329.189588 -281.70124)
		(width 0.09525)
		(layer "In4.Cu")
		(net "M_D_CPU0_SB_DQS_DN<6>")
	)
	(arc
		(start 327.285604 -281.543252)
		(mid 327.589301 -281.583439)
		(end 327.87209 -281.70124)
		(width 0.09525)
		(layer "In4.Cu")
		(net "M_D_CPU0_SB_DQS_DN<6>")
	)
	(arc
		(start 332.572614 -281.70124)
		(mid 332.761082 -281.751917)
		(end 332.94955 -281.70124)
		(width 0.09525)
		(layer "In4.Cu")
		(net "M_D_CPU0_SB_DQS_DN<6>")
	)
	(arc
		(start 335.769712 -281.70124)
		(mid 336.051144 -281.625485)
		(end 336.332576 -281.70124)
		(width 0.09525)
		(layer "In4.Cu")
		(net "M_D_CPU0_SB_DQS_DN<6>")
	)
	(arc
		(start 330.129642 -281.70124)
		(mid 330.411074 -281.625485)
		(end 330.692506 -281.70124)
		(width 0.09525)
		(layer "In4.Cu")
		(net "M_D_CPU0_SB_DQS_DN<6>")
	)
	(arc
		(start 331.069696 -281.70124)
		(mid 331.351128 -281.625485)
		(end 331.63256 -281.70124)
		(width 0.09525)
		(layer "In4.Cu")
		(net "M_D_CPU0_SB_DQS_DN<6>")
	)
	(arc
		(start 338.58962 -281.70124)
		(mid 338.871052 -281.625485)
		(end 339.152484 -281.70124)
		(width 0.09525)
		(layer "In4.Cu")
		(net "M_D_CPU0_SB_DQS_DN<6>")
	)
	(segment
		(start 340.747858 -276.250146)
		(end 340.281006 -276.516084)
		(width 0.12954)
		(layer "F.Cu")
		(net "M_D_CPU0_SB_DQS_DN<5>")
	)
	(segment
		(start 340.092538 -276.841204)
		(end 340.10092 -276.84603)
		(width 0.09525)
		(layer "In4.Cu")
		(net "M_D_CPU0_SB_DQS_DN<5>")
	)
	(segment
		(start 283.621226 -285.77921)
		(end 284.61208 -286.18942)
		(width 0.16002)
		(layer "In4.Cu")
		(net "M_D_CPU0_SB_DQS_DN<5>")
	)
	(segment
		(start 301.04334 -286.157924)
		(end 301.515526 -286.63011)
		(width 0.16002)
		(layer "In4.Cu")
		(net "M_D_CPU0_SB_DQS_DN<5>")
	)
	(segment
		(start 324.908672 -276.699472)
		(end 327.346056 -276.699472)
		(width 0.09525)
		(layer "In4.Cu")
		(net "M_D_CPU0_SB_DQS_DN<5>")
	)
	(segment
		(start 301.515526 -286.63011)
		(end 304.851054 -286.63011)
		(width 0.16002)
		(layer "In4.Cu")
		(net "M_D_CPU0_SB_DQS_DN<5>")
	)
	(segment
		(start 295.936924 -287.008062)
		(end 297.645074 -286.300418)
		(width 0.16002)
		(layer "In4.Cu")
		(net "M_D_CPU0_SB_DQS_DN<5>")
	)
	(segment
		(start 282.910788 -285.77921)
		(end 283.621226 -285.77921)
		(width 0.16002)
		(layer "In4.Cu")
		(net "M_D_CPU0_SB_DQS_DN<5>")
	)
	(segment
		(start 295.300146 -287.008062)
		(end 295.936924 -287.008062)
		(width 0.16002)
		(layer "In4.Cu")
		(net "M_D_CPU0_SB_DQS_DN<5>")
	)
	(segment
		(start 280.91003 -286.00908)
		(end 281.798268 -286.00908)
		(width 0.16002)
		(layer "In4.Cu")
		(net "M_D_CPU0_SB_DQS_DN<5>")
	)
	(segment
		(start 290.0426 -286.350964)
		(end 290.588954 -285.80461)
		(width 0.16002)
		(layer "In4.Cu")
		(net "M_D_CPU0_SB_DQS_DN<5>")
	)
	(segment
		(start 323.895974 -276.04847)
		(end 323.919596 -276.04847)
		(width 0.09525)
		(layer "In4.Cu")
		(net "M_D_CPU0_SB_DQS_DN<5>")
	)
	(segment
		(start 340.43493 -276.781514)
		(end 340.281006 -276.516084)
		(width 0.09525)
		(layer "In4.Cu")
		(net "M_D_CPU0_SB_DQS_DN<5>")
	)
	(segment
		(start 339.521292 -276.84603)
		(end 339.529674 -276.841204)
		(width 0.09525)
		(layer "In4.Cu")
		(net "M_D_CPU0_SB_DQS_DN<5>")
	)
	(segment
		(start 297.645074 -286.300418)
		(end 298.115482 -285.83001)
		(width 0.16002)
		(layer "In4.Cu")
		(net "M_D_CPU0_SB_DQS_DN<5>")
	)
	(segment
		(start 280.635964 -285.735014)
		(end 280.91003 -286.00908)
		(width 0.16002)
		(layer "In4.Cu")
		(net "M_D_CPU0_SB_DQS_DN<5>")
	)
	(segment
		(start 286.283908 -286.487616)
		(end 286.368998 -286.629602)
		(width 0.16002)
		(layer "In4.Cu")
		(net "M_D_CPU0_SB_DQS_DN<5>")
	)
	(segment
		(start 286.368998 -286.629602)
		(end 287.879536 -287.008062)
		(width 0.16002)
		(layer "In4.Cu")
		(net "M_D_CPU0_SB_DQS_DN<5>")
	)
	(segment
		(start 335.392522 -276.841204)
		(end 335.400904 -276.84603)
		(width 0.09525)
		(layer "In4.Cu")
		(net "M_D_CPU0_SB_DQS_DN<5>")
	)
	(segment
		(start 330.692506 -276.841204)
		(end 330.700888 -276.84603)
		(width 0.09525)
		(layer "In4.Cu")
		(net "M_D_CPU0_SB_DQS_DN<5>")
	)
	(segment
		(start 299.08754 -286.157924)
		(end 301.04334 -286.157924)
		(width 0.16002)
		(layer "In4.Cu")
		(net "M_D_CPU0_SB_DQS_DN<5>")
	)
	(segment
		(start 330.12126 -276.84603)
		(end 330.129642 -276.841204)
		(width 0.09525)
		(layer "In4.Cu")
		(net "M_D_CPU0_SB_DQS_DN<5>")
	)
	(segment
		(start 317.91529 -276.04847)
		(end 323.895974 -276.04847)
		(width 0.16002)
		(layer "In4.Cu")
		(net "M_D_CPU0_SB_DQS_DN<5>")
	)
	(segment
		(start 333.881222 -276.84603)
		(end 333.889604 -276.841204)
		(width 0.09525)
		(layer "In4.Cu")
		(net "M_D_CPU0_SB_DQS_DN<5>")
	)
	(segment
		(start 285.818072 -286.37103)
		(end 286.283908 -286.487616)
		(width 0.16002)
		(layer "In4.Cu")
		(net "M_D_CPU0_SB_DQS_DN<5>")
	)
	(segment
		(start 336.332576 -276.841204)
		(end 336.340958 -276.84603)
		(width 0.09525)
		(layer "In4.Cu")
		(net "M_D_CPU0_SB_DQS_DN<5>")
	)
	(segment
		(start 308.13375 -285.83001)
		(end 317.91529 -276.04847)
		(width 0.16002)
		(layer "In4.Cu")
		(net "M_D_CPU0_SB_DQS_DN<5>")
	)
	(segment
		(start 293.247572 -286.157924)
		(end 295.300146 -287.008062)
		(width 0.16002)
		(layer "In4.Cu")
		(net "M_D_CPU0_SB_DQS_DN<5>")
	)
	(segment
		(start 340.411562 -276.868382)
		(end 340.43493 -276.781514)
		(width 0.09525)
		(layer "In4.Cu")
		(net "M_D_CPU0_SB_DQS_DN<5>")
	)
	(segment
		(start 284.61208 -286.18942)
		(end 285.67634 -286.455866)
		(width 0.16002)
		(layer "In4.Cu")
		(net "M_D_CPU0_SB_DQS_DN<5>")
	)
	(segment
		(start 323.978778 -276.107652)
		(end 324.316852 -276.107652)
		(width 0.09525)
		(layer "In4.Cu")
		(net "M_D_CPU0_SB_DQS_DN<5>")
	)
	(segment
		(start 305.651154 -285.83001)
		(end 308.13375 -285.83001)
		(width 0.16002)
		(layer "In4.Cu")
		(net "M_D_CPU0_SB_DQS_DN<5>")
	)
	(segment
		(start 331.63256 -276.841204)
		(end 331.640942 -276.84603)
		(width 0.09525)
		(layer "In4.Cu")
		(net "M_D_CPU0_SB_DQS_DN<5>")
	)
	(segment
		(start 290.588954 -285.80461)
		(end 291.24275 -285.80461)
		(width 0.16002)
		(layer "In4.Cu")
		(net "M_D_CPU0_SB_DQS_DN<5>")
	)
	(segment
		(start 304.851054 -286.63011)
		(end 305.651154 -285.83001)
		(width 0.16002)
		(layer "In4.Cu")
		(net "M_D_CPU0_SB_DQS_DN<5>")
	)
	(segment
		(start 298.759626 -285.83001)
		(end 299.08754 -286.157924)
		(width 0.16002)
		(layer "In4.Cu")
		(net "M_D_CPU0_SB_DQS_DN<5>")
	)
	(segment
		(start 324.316852 -276.107652)
		(end 324.908672 -276.699472)
		(width 0.09525)
		(layer "In4.Cu")
		(net "M_D_CPU0_SB_DQS_DN<5>")
	)
	(segment
		(start 292.045898 -286.157924)
		(end 293.247572 -286.157924)
		(width 0.16002)
		(layer "In4.Cu")
		(net "M_D_CPU0_SB_DQS_DN<5>")
	)
	(segment
		(start 298.115482 -285.83001)
		(end 298.759626 -285.83001)
		(width 0.16002)
		(layer "In4.Cu")
		(net "M_D_CPU0_SB_DQS_DN<5>")
	)
	(segment
		(start 281.798268 -286.00908)
		(end 282.910788 -285.77921)
		(width 0.16002)
		(layer "In4.Cu")
		(net "M_D_CPU0_SB_DQS_DN<5>")
	)
	(segment
		(start 291.24275 -285.80461)
		(end 292.045898 -286.157924)
		(width 0.16002)
		(layer "In4.Cu")
		(net "M_D_CPU0_SB_DQS_DN<5>")
	)
	(segment
		(start 323.919596 -276.04847)
		(end 323.978778 -276.107652)
		(width 0.09525)
		(layer "In4.Cu")
		(net "M_D_CPU0_SB_DQS_DN<5>")
	)
	(segment
		(start 328.241406 -276.84603)
		(end 328.249788 -276.841204)
		(width 0.09525)
		(layer "In4.Cu")
		(net "M_D_CPU0_SB_DQS_DN<5>")
	)
	(segment
		(start 288.456878 -287.008062)
		(end 290.0426 -286.350964)
		(width 0.16002)
		(layer "In4.Cu")
		(net "M_D_CPU0_SB_DQS_DN<5>")
	)
	(segment
		(start 285.67634 -286.455866)
		(end 285.818072 -286.37103)
		(width 0.16002)
		(layer "In4.Cu")
		(net "M_D_CPU0_SB_DQS_DN<5>")
	)
	(segment
		(start 338.581238 -276.84603)
		(end 338.58962 -276.841204)
		(width 0.09525)
		(layer "In4.Cu")
		(net "M_D_CPU0_SB_DQS_DN<5>")
	)
	(segment
		(start 287.879536 -287.008062)
		(end 288.456878 -287.008062)
		(width 0.16002)
		(layer "In4.Cu")
		(net "M_D_CPU0_SB_DQS_DN<5>")
	)
	(segment
		(start 334.821276 -276.84603)
		(end 334.829658 -276.841204)
		(width 0.09525)
		(layer "In4.Cu")
		(net "M_D_CPU0_SB_DQS_DN<5>")
	)
	(arc
		(start 329.189588 -276.841204)
		(mid 329.196041 -276.837604)
		(end 329.202542 -276.834092)
		(width 0.09525)
		(layer "In4.Cu")
		(net "M_D_CPU0_SB_DQS_DN<5>")
	)
	(arc
		(start 332.00975 -276.841204)
		(mid 332.291182 -276.765449)
		(end 332.572614 -276.841204)
		(width 0.09525)
		(layer "In4.Cu")
		(net "M_D_CPU0_SB_DQS_DN<5>")
	)
	(arc
		(start 333.512414 -276.841204)
		(mid 333.696189 -276.891976)
		(end 333.881222 -276.84603)
		(width 0.09525)
		(layer "In4.Cu")
		(net "M_D_CPU0_SB_DQS_DN<5>")
	)
	(arc
		(start 329.202542 -276.834092)
		(mid 329.478442 -276.76553)
		(end 329.752452 -276.841204)
		(width 0.09525)
		(layer "In4.Cu")
		(net "M_D_CPU0_SB_DQS_DN<5>")
	)
	(arc
		(start 333.889604 -276.841204)
		(mid 333.896057 -276.837604)
		(end 333.902558 -276.834092)
		(width 0.09525)
		(layer "In4.Cu")
		(net "M_D_CPU0_SB_DQS_DN<5>")
	)
	(arc
		(start 335.400904 -276.84603)
		(mid 335.585936 -276.891944)
		(end 335.769712 -276.841204)
		(width 0.09525)
		(layer "In4.Cu")
		(net "M_D_CPU0_SB_DQS_DN<5>")
	)
	(arc
		(start 334.829658 -276.841204)
		(mid 335.11109 -276.765449)
		(end 335.392522 -276.841204)
		(width 0.09525)
		(layer "In4.Cu")
		(net "M_D_CPU0_SB_DQS_DN<5>")
	)
	(arc
		(start 336.709766 -276.841204)
		(mid 336.991198 -276.765449)
		(end 337.27263 -276.841204)
		(width 0.09525)
		(layer "In4.Cu")
		(net "M_D_CPU0_SB_DQS_DN<5>")
	)
	(arc
		(start 338.21243 -276.841204)
		(mid 338.396205 -276.891976)
		(end 338.581238 -276.84603)
		(width 0.09525)
		(layer "In4.Cu")
		(net "M_D_CPU0_SB_DQS_DN<5>")
	)
	(arc
		(start 332.572614 -276.841204)
		(mid 332.761082 -276.891881)
		(end 332.94955 -276.841204)
		(width 0.09525)
		(layer "In4.Cu")
		(net "M_D_CPU0_SB_DQS_DN<5>")
	)
	(arc
		(start 338.602574 -276.834092)
		(mid 338.878474 -276.76553)
		(end 339.152484 -276.841204)
		(width 0.09525)
		(layer "In4.Cu")
		(net "M_D_CPU0_SB_DQS_DN<5>")
	)
	(arc
		(start 339.152484 -276.841204)
		(mid 339.336259 -276.891976)
		(end 339.521292 -276.84603)
		(width 0.09525)
		(layer "In4.Cu")
		(net "M_D_CPU0_SB_DQS_DN<5>")
	)
	(arc
		(start 331.640942 -276.84603)
		(mid 331.825974 -276.891944)
		(end 332.00975 -276.841204)
		(width 0.09525)
		(layer "In4.Cu")
		(net "M_D_CPU0_SB_DQS_DN<5>")
	)
	(arc
		(start 330.700888 -276.84603)
		(mid 330.88592 -276.891944)
		(end 331.069696 -276.841204)
		(width 0.09525)
		(layer "In4.Cu")
		(net "M_D_CPU0_SB_DQS_DN<5>")
	)
	(arc
		(start 327.87209 -276.841204)
		(mid 328.056119 -276.892103)
		(end 328.241406 -276.84603)
		(width 0.09525)
		(layer "In4.Cu")
		(net "M_D_CPU0_SB_DQS_DN<5>")
	)
	(arc
		(start 337.27263 -276.841204)
		(mid 337.461098 -276.891881)
		(end 337.649566 -276.841204)
		(width 0.09525)
		(layer "In4.Cu")
		(net "M_D_CPU0_SB_DQS_DN<5>")
	)
	(arc
		(start 335.769712 -276.841204)
		(mid 336.051144 -276.765449)
		(end 336.332576 -276.841204)
		(width 0.09525)
		(layer "In4.Cu")
		(net "M_D_CPU0_SB_DQS_DN<5>")
	)
	(arc
		(start 330.129642 -276.841204)
		(mid 330.411074 -276.765449)
		(end 330.692506 -276.841204)
		(width 0.09525)
		(layer "In4.Cu")
		(net "M_D_CPU0_SB_DQS_DN<5>")
	)
	(arc
		(start 332.96225 -276.834092)
		(mid 333.23826 -276.765531)
		(end 333.512414 -276.841204)
		(width 0.09525)
		(layer "In4.Cu")
		(net "M_D_CPU0_SB_DQS_DN<5>")
	)
	(arc
		(start 337.649566 -276.841204)
		(mid 337.655894 -276.837608)
		(end 337.662266 -276.834092)
		(width 0.09525)
		(layer "In4.Cu")
		(net "M_D_CPU0_SB_DQS_DN<5>")
	)
	(arc
		(start 329.752452 -276.841204)
		(mid 329.936227 -276.891976)
		(end 330.12126 -276.84603)
		(width 0.09525)
		(layer "In4.Cu")
		(net "M_D_CPU0_SB_DQS_DN<5>")
	)
	(arc
		(start 340.10092 -276.84603)
		(mid 340.253815 -276.890858)
		(end 340.411562 -276.868382)
		(width 0.09525)
		(layer "In4.Cu")
		(net "M_D_CPU0_SB_DQS_DN<5>")
	)
	(arc
		(start 338.58962 -276.841204)
		(mid 338.596073 -276.837604)
		(end 338.602574 -276.834092)
		(width 0.09525)
		(layer "In4.Cu")
		(net "M_D_CPU0_SB_DQS_DN<5>")
	)
	(arc
		(start 328.249788 -276.841204)
		(mid 328.53122 -276.765449)
		(end 328.812652 -276.841204)
		(width 0.09525)
		(layer "In4.Cu")
		(net "M_D_CPU0_SB_DQS_DN<5>")
	)
	(arc
		(start 327.346056 -276.699472)
		(mid 327.618435 -276.735573)
		(end 327.87209 -276.841204)
		(width 0.09525)
		(layer "In4.Cu")
		(net "M_D_CPU0_SB_DQS_DN<5>")
	)
	(arc
		(start 337.662266 -276.834092)
		(mid 337.938276 -276.765531)
		(end 338.21243 -276.841204)
		(width 0.09525)
		(layer "In4.Cu")
		(net "M_D_CPU0_SB_DQS_DN<5>")
	)
	(arc
		(start 331.069696 -276.841204)
		(mid 331.351128 -276.765449)
		(end 331.63256 -276.841204)
		(width 0.09525)
		(layer "In4.Cu")
		(net "M_D_CPU0_SB_DQS_DN<5>")
	)
	(arc
		(start 332.94955 -276.841204)
		(mid 332.955878 -276.837608)
		(end 332.96225 -276.834092)
		(width 0.09525)
		(layer "In4.Cu")
		(net "M_D_CPU0_SB_DQS_DN<5>")
	)
	(arc
		(start 328.812652 -276.841204)
		(mid 329.00112 -276.891881)
		(end 329.189588 -276.841204)
		(width 0.09525)
		(layer "In4.Cu")
		(net "M_D_CPU0_SB_DQS_DN<5>")
	)
	(arc
		(start 336.340958 -276.84603)
		(mid 336.52599 -276.891944)
		(end 336.709766 -276.841204)
		(width 0.09525)
		(layer "In4.Cu")
		(net "M_D_CPU0_SB_DQS_DN<5>")
	)
	(arc
		(start 333.902558 -276.834092)
		(mid 334.178458 -276.76553)
		(end 334.452468 -276.841204)
		(width 0.09525)
		(layer "In4.Cu")
		(net "M_D_CPU0_SB_DQS_DN<5>")
	)
	(arc
		(start 339.529674 -276.841204)
		(mid 339.811106 -276.765449)
		(end 340.092538 -276.841204)
		(width 0.09525)
		(layer "In4.Cu")
		(net "M_D_CPU0_SB_DQS_DN<5>")
	)
	(arc
		(start 334.452468 -276.841204)
		(mid 334.636243 -276.891976)
		(end 334.821276 -276.84603)
		(width 0.09525)
		(layer "In4.Cu")
		(net "M_D_CPU0_SB_DQS_DN<5>")
	)
	(segment
		(start 340.747858 -271.39011)
		(end 340.281006 -271.656048)
		(width 0.12954)
		(layer "F.Cu")
		(net "M_D_CPU0_SB_DQS_DN<4>")
	)
	(segment
		(start 307.60416 -276.47011)
		(end 313.64936 -270.42491)
		(width 0.16002)
		(layer "In4.Cu")
		(net "M_D_CPU0_SB_DQS_DN<4>")
	)
	(segment
		(start 339.521292 -271.985994)
		(end 339.529674 -271.981168)
		(width 0.09525)
		(layer "In4.Cu")
		(net "M_D_CPU0_SB_DQS_DN<4>")
	)
	(segment
		(start 301.879254 -277.28291)
		(end 304.859182 -277.28291)
		(width 0.16002)
		(layer "In4.Cu")
		(net "M_D_CPU0_SB_DQS_DN<4>")
	)
	(segment
		(start 289.268154 -277.32101)
		(end 289.733482 -277.32101)
		(width 0.16002)
		(layer "In4.Cu")
		(net "M_D_CPU0_SB_DQS_DN<4>")
	)
	(segment
		(start 294.501062 -277.658068)
		(end 296.479214 -277.658068)
		(width 0.16002)
		(layer "In4.Cu")
		(net "M_D_CPU0_SB_DQS_DN<4>")
	)
	(segment
		(start 304.859182 -277.28291)
		(end 305.671982 -276.47011)
		(width 0.16002)
		(layer "In4.Cu")
		(net "M_D_CPU0_SB_DQS_DN<4>")
	)
	(segment
		(start 330.692506 -271.981168)
		(end 330.700888 -271.985994)
		(width 0.09525)
		(layer "In4.Cu")
		(net "M_D_CPU0_SB_DQS_DN<4>")
	)
	(segment
		(start 287.498028 -277.658068)
		(end 288.931096 -277.658068)
		(width 0.16002)
		(layer "In4.Cu")
		(net "M_D_CPU0_SB_DQS_DN<4>")
	)
	(segment
		(start 324.232778 -270.484092)
		(end 324.443598 -270.694912)
		(width 0.09525)
		(layer "In4.Cu")
		(net "M_D_CPU0_SB_DQS_DN<4>")
	)
	(segment
		(start 340.411562 -272.008346)
		(end 340.43493 -271.921478)
		(width 0.09525)
		(layer "In4.Cu")
		(net "M_D_CPU0_SB_DQS_DN<4>")
	)
	(segment
		(start 326.522588 -271.905222)
		(end 327.59015 -271.905222)
		(width 0.09525)
		(layer "In4.Cu")
		(net "M_D_CPU0_SB_DQS_DN<4>")
	)
	(segment
		(start 328.241406 -271.985994)
		(end 328.249788 -271.981168)
		(width 0.09525)
		(layer "In4.Cu")
		(net "M_D_CPU0_SB_DQS_DN<4>")
	)
	(segment
		(start 293.650924 -276.80793)
		(end 294.501062 -277.658068)
		(width 0.16002)
		(layer "In4.Cu")
		(net "M_D_CPU0_SB_DQS_DN<4>")
	)
	(segment
		(start 296.479214 -277.658068)
		(end 297.061636 -277.075646)
		(width 0.16002)
		(layer "In4.Cu")
		(net "M_D_CPU0_SB_DQS_DN<4>")
	)
	(segment
		(start 297.497246 -277.075646)
		(end 298.153582 -276.41931)
		(width 0.16002)
		(layer "In4.Cu")
		(net "M_D_CPU0_SB_DQS_DN<4>")
	)
	(segment
		(start 286.784288 -277.658068)
		(end 286.901128 -277.541228)
		(width 0.16002)
		(layer "In4.Cu")
		(net "M_D_CPU0_SB_DQS_DN<4>")
	)
	(segment
		(start 324.443598 -270.694912)
		(end 325.312278 -270.694912)
		(width 0.09525)
		(layer "In4.Cu")
		(net "M_D_CPU0_SB_DQS_DN<4>")
	)
	(segment
		(start 280.91003 -276.659086)
		(end 281.798268 -276.659086)
		(width 0.16002)
		(layer "In4.Cu")
		(net "M_D_CPU0_SB_DQS_DN<4>")
	)
	(segment
		(start 334.821276 -271.985994)
		(end 334.829658 -271.981168)
		(width 0.09525)
		(layer "In4.Cu")
		(net "M_D_CPU0_SB_DQS_DN<4>")
	)
	(segment
		(start 323.895974 -270.42491)
		(end 323.919596 -270.42491)
		(width 0.09525)
		(layer "In4.Cu")
		(net "M_D_CPU0_SB_DQS_DN<4>")
	)
	(segment
		(start 291.215826 -276.48281)
		(end 291.540946 -276.80793)
		(width 0.16002)
		(layer "In4.Cu")
		(net "M_D_CPU0_SB_DQS_DN<4>")
	)
	(segment
		(start 280.635964 -276.38502)
		(end 280.91003 -276.659086)
		(width 0.16002)
		(layer "In4.Cu")
		(net "M_D_CPU0_SB_DQS_DN<4>")
	)
	(segment
		(start 323.978778 -270.484092)
		(end 324.232778 -270.484092)
		(width 0.09525)
		(layer "In4.Cu")
		(net "M_D_CPU0_SB_DQS_DN<4>")
	)
	(segment
		(start 290.571682 -276.48281)
		(end 291.215826 -276.48281)
		(width 0.16002)
		(layer "In4.Cu")
		(net "M_D_CPU0_SB_DQS_DN<4>")
	)
	(segment
		(start 340.43493 -271.921478)
		(end 340.281006 -271.656048)
		(width 0.09525)
		(layer "In4.Cu")
		(net "M_D_CPU0_SB_DQS_DN<4>")
	)
	(segment
		(start 286.901128 -277.541228)
		(end 287.381188 -277.541228)
		(width 0.16002)
		(layer "In4.Cu")
		(net "M_D_CPU0_SB_DQS_DN<4>")
	)
	(segment
		(start 291.540946 -276.80793)
		(end 293.650924 -276.80793)
		(width 0.16002)
		(layer "In4.Cu")
		(net "M_D_CPU0_SB_DQS_DN<4>")
	)
	(segment
		(start 297.061636 -277.075646)
		(end 297.497246 -277.075646)
		(width 0.16002)
		(layer "In4.Cu")
		(net "M_D_CPU0_SB_DQS_DN<4>")
	)
	(segment
		(start 325.312278 -270.694912)
		(end 326.522588 -271.905222)
		(width 0.09525)
		(layer "In4.Cu")
		(net "M_D_CPU0_SB_DQS_DN<4>")
	)
	(segment
		(start 281.798268 -276.659086)
		(end 282.013406 -276.443948)
		(width 0.16002)
		(layer "In4.Cu")
		(net "M_D_CPU0_SB_DQS_DN<4>")
	)
	(segment
		(start 305.671982 -276.47011)
		(end 307.60416 -276.47011)
		(width 0.16002)
		(layer "In4.Cu")
		(net "M_D_CPU0_SB_DQS_DN<4>")
	)
	(segment
		(start 288.931096 -277.658068)
		(end 289.268154 -277.32101)
		(width 0.16002)
		(layer "In4.Cu")
		(net "M_D_CPU0_SB_DQS_DN<4>")
	)
	(segment
		(start 287.381188 -277.541228)
		(end 287.498028 -277.658068)
		(width 0.16002)
		(layer "In4.Cu")
		(net "M_D_CPU0_SB_DQS_DN<4>")
	)
	(segment
		(start 286.026352 -277.658068)
		(end 286.784288 -277.658068)
		(width 0.16002)
		(layer "In4.Cu")
		(net "M_D_CPU0_SB_DQS_DN<4>")
	)
	(segment
		(start 299.067474 -276.80793)
		(end 301.404274 -276.80793)
		(width 0.16002)
		(layer "In4.Cu")
		(net "M_D_CPU0_SB_DQS_DN<4>")
	)
	(segment
		(start 298.678854 -276.41931)
		(end 299.067474 -276.80793)
		(width 0.16002)
		(layer "In4.Cu")
		(net "M_D_CPU0_SB_DQS_DN<4>")
	)
	(segment
		(start 282.013406 -276.443948)
		(end 283.633164 -276.443948)
		(width 0.16002)
		(layer "In4.Cu")
		(net "M_D_CPU0_SB_DQS_DN<4>")
	)
	(segment
		(start 340.092538 -271.981168)
		(end 340.10092 -271.985994)
		(width 0.09525)
		(layer "In4.Cu")
		(net "M_D_CPU0_SB_DQS_DN<4>")
	)
	(segment
		(start 289.733482 -277.32101)
		(end 290.571682 -276.48281)
		(width 0.16002)
		(layer "In4.Cu")
		(net "M_D_CPU0_SB_DQS_DN<4>")
	)
	(segment
		(start 298.153582 -276.41931)
		(end 298.678854 -276.41931)
		(width 0.16002)
		(layer "In4.Cu")
		(net "M_D_CPU0_SB_DQS_DN<4>")
	)
	(segment
		(start 283.633164 -276.443948)
		(end 284.013656 -276.82444)
		(width 0.16002)
		(layer "In4.Cu")
		(net "M_D_CPU0_SB_DQS_DN<4>")
	)
	(segment
		(start 335.392522 -271.981168)
		(end 335.400904 -271.985994)
		(width 0.09525)
		(layer "In4.Cu")
		(net "M_D_CPU0_SB_DQS_DN<4>")
	)
	(segment
		(start 331.63256 -271.981168)
		(end 331.640942 -271.985994)
		(width 0.09525)
		(layer "In4.Cu")
		(net "M_D_CPU0_SB_DQS_DN<4>")
	)
	(segment
		(start 323.919596 -270.42491)
		(end 323.978778 -270.484092)
		(width 0.09525)
		(layer "In4.Cu")
		(net "M_D_CPU0_SB_DQS_DN<4>")
	)
	(segment
		(start 338.581238 -271.985994)
		(end 338.58962 -271.981168)
		(width 0.09525)
		(layer "In4.Cu")
		(net "M_D_CPU0_SB_DQS_DN<4>")
	)
	(segment
		(start 284.013656 -276.82444)
		(end 286.026352 -277.658068)
		(width 0.16002)
		(layer "In4.Cu")
		(net "M_D_CPU0_SB_DQS_DN<4>")
	)
	(segment
		(start 330.12126 -271.985994)
		(end 330.129642 -271.981168)
		(width 0.09525)
		(layer "In4.Cu")
		(net "M_D_CPU0_SB_DQS_DN<4>")
	)
	(segment
		(start 301.404274 -276.80793)
		(end 301.879254 -277.28291)
		(width 0.16002)
		(layer "In4.Cu")
		(net "M_D_CPU0_SB_DQS_DN<4>")
	)
	(segment
		(start 336.332576 -271.981168)
		(end 336.340958 -271.985994)
		(width 0.09525)
		(layer "In4.Cu")
		(net "M_D_CPU0_SB_DQS_DN<4>")
	)
	(segment
		(start 333.881222 -271.985994)
		(end 333.889604 -271.981168)
		(width 0.09525)
		(layer "In4.Cu")
		(net "M_D_CPU0_SB_DQS_DN<4>")
	)
	(segment
		(start 313.64936 -270.42491)
		(end 323.895974 -270.42491)
		(width 0.16002)
		(layer "In4.Cu")
		(net "M_D_CPU0_SB_DQS_DN<4>")
	)
	(arc
		(start 328.812652 -271.981168)
		(mid 329.00112 -272.031845)
		(end 329.189588 -271.981168)
		(width 0.09525)
		(layer "In4.Cu")
		(net "M_D_CPU0_SB_DQS_DN<4>")
	)
	(arc
		(start 332.572614 -271.981168)
		(mid 332.761082 -272.031845)
		(end 332.94955 -271.981168)
		(width 0.09525)
		(layer "In4.Cu")
		(net "M_D_CPU0_SB_DQS_DN<4>")
	)
	(arc
		(start 336.709766 -271.981168)
		(mid 336.991198 -271.905413)
		(end 337.27263 -271.981168)
		(width 0.09525)
		(layer "In4.Cu")
		(net "M_D_CPU0_SB_DQS_DN<4>")
	)
	(arc
		(start 327.59015 -271.905222)
		(mid 327.736145 -271.92454)
		(end 327.87209 -271.981168)
		(width 0.09525)
		(layer "In4.Cu")
		(net "M_D_CPU0_SB_DQS_DN<4>")
	)
	(arc
		(start 339.529674 -271.981168)
		(mid 339.811106 -271.905413)
		(end 340.092538 -271.981168)
		(width 0.09525)
		(layer "In4.Cu")
		(net "M_D_CPU0_SB_DQS_DN<4>")
	)
	(arc
		(start 338.58962 -271.981168)
		(mid 338.871052 -271.905413)
		(end 339.152484 -271.981168)
		(width 0.09525)
		(layer "In4.Cu")
		(net "M_D_CPU0_SB_DQS_DN<4>")
	)
	(arc
		(start 335.769712 -271.981168)
		(mid 336.051144 -271.905413)
		(end 336.332576 -271.981168)
		(width 0.09525)
		(layer "In4.Cu")
		(net "M_D_CPU0_SB_DQS_DN<4>")
	)
	(arc
		(start 330.700888 -271.985994)
		(mid 330.88592 -272.031908)
		(end 331.069696 -271.981168)
		(width 0.09525)
		(layer "In4.Cu")
		(net "M_D_CPU0_SB_DQS_DN<4>")
	)
	(arc
		(start 340.10092 -271.985994)
		(mid 340.253815 -272.030822)
		(end 340.411562 -272.008346)
		(width 0.09525)
		(layer "In4.Cu")
		(net "M_D_CPU0_SB_DQS_DN<4>")
	)
	(arc
		(start 335.400904 -271.985994)
		(mid 335.585936 -272.031908)
		(end 335.769712 -271.981168)
		(width 0.09525)
		(layer "In4.Cu")
		(net "M_D_CPU0_SB_DQS_DN<4>")
	)
	(arc
		(start 333.512414 -271.981168)
		(mid 333.696189 -272.03194)
		(end 333.881222 -271.985994)
		(width 0.09525)
		(layer "In4.Cu")
		(net "M_D_CPU0_SB_DQS_DN<4>")
	)
	(arc
		(start 334.452468 -271.981168)
		(mid 334.636243 -272.03194)
		(end 334.821276 -271.985994)
		(width 0.09525)
		(layer "In4.Cu")
		(net "M_D_CPU0_SB_DQS_DN<4>")
	)
	(arc
		(start 339.152484 -271.981168)
		(mid 339.336259 -272.03194)
		(end 339.521292 -271.985994)
		(width 0.09525)
		(layer "In4.Cu")
		(net "M_D_CPU0_SB_DQS_DN<4>")
	)
	(arc
		(start 329.189588 -271.981168)
		(mid 329.47102 -271.905413)
		(end 329.752452 -271.981168)
		(width 0.09525)
		(layer "In4.Cu")
		(net "M_D_CPU0_SB_DQS_DN<4>")
	)
	(arc
		(start 328.249788 -271.981168)
		(mid 328.53122 -271.905413)
		(end 328.812652 -271.981168)
		(width 0.09525)
		(layer "In4.Cu")
		(net "M_D_CPU0_SB_DQS_DN<4>")
	)
	(arc
		(start 332.94955 -271.981168)
		(mid 333.230982 -271.905413)
		(end 333.512414 -271.981168)
		(width 0.09525)
		(layer "In4.Cu")
		(net "M_D_CPU0_SB_DQS_DN<4>")
	)
	(arc
		(start 336.340958 -271.985994)
		(mid 336.52599 -272.031908)
		(end 336.709766 -271.981168)
		(width 0.09525)
		(layer "In4.Cu")
		(net "M_D_CPU0_SB_DQS_DN<4>")
	)
	(arc
		(start 332.00975 -271.981168)
		(mid 332.291182 -271.905413)
		(end 332.572614 -271.981168)
		(width 0.09525)
		(layer "In4.Cu")
		(net "M_D_CPU0_SB_DQS_DN<4>")
	)
	(arc
		(start 337.649566 -271.981168)
		(mid 337.930998 -271.905413)
		(end 338.21243 -271.981168)
		(width 0.09525)
		(layer "In4.Cu")
		(net "M_D_CPU0_SB_DQS_DN<4>")
	)
	(arc
		(start 338.21243 -271.981168)
		(mid 338.396205 -272.03194)
		(end 338.581238 -271.985994)
		(width 0.09525)
		(layer "In4.Cu")
		(net "M_D_CPU0_SB_DQS_DN<4>")
	)
	(arc
		(start 331.640942 -271.985994)
		(mid 331.825974 -272.031908)
		(end 332.00975 -271.981168)
		(width 0.09525)
		(layer "In4.Cu")
		(net "M_D_CPU0_SB_DQS_DN<4>")
	)
	(arc
		(start 330.129642 -271.981168)
		(mid 330.411074 -271.905413)
		(end 330.692506 -271.981168)
		(width 0.09525)
		(layer "In4.Cu")
		(net "M_D_CPU0_SB_DQS_DN<4>")
	)
	(arc
		(start 337.27263 -271.981168)
		(mid 337.461098 -272.031845)
		(end 337.649566 -271.981168)
		(width 0.09525)
		(layer "In4.Cu")
		(net "M_D_CPU0_SB_DQS_DN<4>")
	)
	(arc
		(start 331.069696 -271.981168)
		(mid 331.351128 -271.905413)
		(end 331.63256 -271.981168)
		(width 0.09525)
		(layer "In4.Cu")
		(net "M_D_CPU0_SB_DQS_DN<4>")
	)
	(arc
		(start 333.889604 -271.981168)
		(mid 334.171036 -271.905413)
		(end 334.452468 -271.981168)
		(width 0.09525)
		(layer "In4.Cu")
		(net "M_D_CPU0_SB_DQS_DN<4>")
	)
	(arc
		(start 329.752452 -271.981168)
		(mid 329.936227 -272.03194)
		(end 330.12126 -271.985994)
		(width 0.09525)
		(layer "In4.Cu")
		(net "M_D_CPU0_SB_DQS_DN<4>")
	)
	(arc
		(start 334.829658 -271.981168)
		(mid 335.11109 -271.905413)
		(end 335.392522 -271.981168)
		(width 0.09525)
		(layer "In4.Cu")
		(net "M_D_CPU0_SB_DQS_DN<4>")
	)
	(arc
		(start 327.87209 -271.981168)
		(mid 328.056119 -272.032067)
		(end 328.241406 -271.985994)
		(width 0.09525)
		(layer "In4.Cu")
		(net "M_D_CPU0_SB_DQS_DN<4>")
	)
	(segment
		(start 339.808058 -290.83)
		(end 339.341206 -291.095938)
		(width 0.12954)
		(layer "F.Cu")
		(net "M_D_CPU0_SB_DQS_DN<3>")
	)
	(segment
		(start 310.357012 -310.905906)
		(end 310.884316 -310.905906)
		(width 0.16002)
		(layer "In4.Cu")
		(net "M_D_CPU0_SB_DQS_DN<3>")
	)
	(segment
		(start 316.378844 -305.411378)
		(end 316.752478 -305.037744)
		(width 0.16002)
		(layer "In4.Cu")
		(net "M_D_CPU0_SB_DQS_DN<3>")
	)
	(segment
		(start 312.631582 -309.15864)
		(end 312.631836 -308.631336)
		(width 0.16002)
		(layer "In4.Cu")
		(net "M_D_CPU0_SB_DQS_DN<3>")
	)
	(segment
		(start 325.214996 -293.369238)
		(end 326.37603 -291.631624)
		(width 0.09525)
		(layer "In4.Cu")
		(net "M_D_CPU0_SB_DQS_DN<3>")
	)
	(segment
		(start 324.303136 -295.278302)
		(end 324.303136 -295.195498)
		(width 0.09525)
		(layer "In4.Cu")
		(net "M_D_CPU0_SB_DQS_DN<3>")
	)
	(segment
		(start 318.019684 -303.030128)
		(end 318.019684 -302.753268)
		(width 0.16002)
		(layer "In4.Cu")
		(net "M_D_CPU0_SB_DQS_DN<3>")
	)
	(segment
		(start 294.020748 -313.362086)
		(end 296.499026 -313.362086)
		(width 0.16002)
		(layer "In4.Cu")
		(net "M_D_CPU0_SB_DQS_DN<3>")
	)
	(segment
		(start 314.477908 -306.78501)
		(end 315.005212 -306.78501)
		(width 0.16002)
		(layer "In4.Cu")
		(net "M_D_CPU0_SB_DQS_DN<3>")
	)
	(segment
		(start 310.250332 -310.799226)
		(end 310.357012 -310.905906)
		(width 0.16002)
		(layer "In4.Cu")
		(net "M_D_CPU0_SB_DQS_DN<3>")
	)
	(segment
		(start 311.623964 -309.425594)
		(end 311.730644 -309.532274)
		(width 0.16002)
		(layer "In4.Cu")
		(net "M_D_CPU0_SB_DQS_DN<3>")
	)
	(segment
		(start 324.286372 -295.295066)
		(end 324.303136 -295.278302)
		(width 0.09525)
		(layer "In4.Cu")
		(net "M_D_CPU0_SB_DQS_DN<3>")
	)
	(segment
		(start 304.950876 -313.686952)
		(end 305.814476 -312.823352)
		(width 0.16002)
		(layer "In4.Cu")
		(net "M_D_CPU0_SB_DQS_DN<3>")
	)
	(segment
		(start 287.259522 -313.511184)
		(end 287.40862 -313.362086)
		(width 0.16002)
		(layer "In4.Cu")
		(net "M_D_CPU0_SB_DQS_DN<3>")
	)
	(segment
		(start 309.777892 -311.27192)
		(end 309.777892 -310.99506)
		(width 0.16002)
		(layer "In4.Cu")
		(net "M_D_CPU0_SB_DQS_DN<3>")
	)
	(segment
		(start 326.37603 -291.631624)
		(end 327.740772 -290.71951)
		(width 0.09525)
		(layer "In4.Cu")
		(net "M_D_CPU0_SB_DQS_DN<3>")
	)
	(segment
		(start 324.761606 -293.822628)
		(end 325.214996 -293.369238)
		(width 0.09525)
		(layer "In4.Cu")
		(net "M_D_CPU0_SB_DQS_DN<3>")
	)
	(segment
		(start 317.118492 -303.931066)
		(end 317.225172 -304.037746)
		(width 0.16002)
		(layer "In4.Cu")
		(net "M_D_CPU0_SB_DQS_DN<3>")
	)
	(segment
		(start 339.187282 -290.830508)
		(end 339.341206 -291.095938)
		(width 0.09525)
		(layer "In4.Cu")
		(net "M_D_CPU0_SB_DQS_DN<3>")
	)
	(segment
		(start 316.646052 -304.40376)
		(end 316.646052 -304.1269)
		(width 0.16002)
		(layer "In4.Cu")
		(net "M_D_CPU0_SB_DQS_DN<3>")
	)
	(segment
		(start 324.561708 -294.305228)
		(end 324.761606 -293.822628)
		(width 0.09525)
		(layer "In4.Cu")
		(net "M_D_CPU0_SB_DQS_DN<3>")
	)
	(segment
		(start 314.005468 -307.257704)
		(end 313.898788 -307.151024)
		(width 0.16002)
		(layer "In4.Cu")
		(net "M_D_CPU0_SB_DQS_DN<3>")
	)
	(segment
		(start 318.126364 -303.136808)
		(end 318.019684 -303.030128)
		(width 0.16002)
		(layer "In4.Cu")
		(net "M_D_CPU0_SB_DQS_DN<3>")
	)
	(segment
		(start 314.005214 -307.785008)
		(end 314.005468 -307.257704)
		(width 0.16002)
		(layer "In4.Cu")
		(net "M_D_CPU0_SB_DQS_DN<3>")
	)
	(segment
		(start 308.8767 -312.172858)
		(end 308.98338 -312.279538)
		(width 0.16002)
		(layer "In4.Cu")
		(net "M_D_CPU0_SB_DQS_DN<3>")
	)
	(segment
		(start 305.814476 -312.823352)
		(end 307.9496 -312.823352)
		(width 0.16002)
		(layer "In4.Cu")
		(net "M_D_CPU0_SB_DQS_DN<3>")
	)
	(segment
		(start 331.63256 -290.770818)
		(end 331.640942 -290.765992)
		(width 0.09525)
		(layer "In4.Cu")
		(net "M_D_CPU0_SB_DQS_DN<3>")
	)
	(segment
		(start 309.777892 -310.99506)
		(end 309.973726 -310.799226)
		(width 0.16002)
		(layer "In4.Cu")
		(net "M_D_CPU0_SB_DQS_DN<3>")
	)
	(segment
		(start 309.973726 -310.799226)
		(end 310.250332 -310.799226)
		(width 0.16002)
		(layer "In4.Cu")
		(net "M_D_CPU0_SB_DQS_DN<3>")
	)
	(segment
		(start 321.680078 -299.092874)
		(end 321.680078 -297.900852)
		(width 0.16002)
		(layer "In4.Cu")
		(net "M_D_CPU0_SB_DQS_DN<3>")
	)
	(segment
		(start 311.730644 -309.532274)
		(end 312.257948 -309.532274)
		(width 0.16002)
		(layer "In4.Cu")
		(net "M_D_CPU0_SB_DQS_DN<3>")
	)
	(segment
		(start 314.094622 -306.67833)
		(end 314.371228 -306.67833)
		(width 0.16002)
		(layer "In4.Cu")
		(net "M_D_CPU0_SB_DQS_DN<3>")
	)
	(segment
		(start 309.884318 -311.905904)
		(end 309.884572 -311.3786)
		(width 0.16002)
		(layer "In4.Cu")
		(net "M_D_CPU0_SB_DQS_DN<3>")
	)
	(segment
		(start 311.25795 -310.532272)
		(end 311.258204 -310.004968)
		(width 0.16002)
		(layer "In4.Cu")
		(net "M_D_CPU0_SB_DQS_DN<3>")
	)
	(segment
		(start 303.420018 -312.99277)
		(end 304.035206 -313.607704)
		(width 0.16002)
		(layer "In4.Cu")
		(net "M_D_CPU0_SB_DQS_DN<3>")
	)
	(segment
		(start 317.225172 -304.037746)
		(end 317.752476 -304.037746)
		(width 0.16002)
		(layer "In4.Cu")
		(net "M_D_CPU0_SB_DQS_DN<3>")
	)
	(segment
		(start 310.884316 -310.905906)
		(end 311.25795 -310.532272)
		(width 0.16002)
		(layer "In4.Cu")
		(net "M_D_CPU0_SB_DQS_DN<3>")
	)
	(segment
		(start 338.581238 -290.765992)
		(end 338.58962 -290.770818)
		(width 0.09525)
		(layer "In4.Cu")
		(net "M_D_CPU0_SB_DQS_DN<3>")
	)
	(segment
		(start 314.371228 -306.67833)
		(end 314.477908 -306.78501)
		(width 0.16002)
		(layer "In4.Cu")
		(net "M_D_CPU0_SB_DQS_DN<3>")
	)
	(segment
		(start 315.378846 -306.411376)
		(end 315.378846 -306.193952)
		(width 0.16002)
		(layer "In4.Cu")
		(net "M_D_CPU0_SB_DQS_DN<3>")
	)
	(segment
		(start 293.170864 -312.512202)
		(end 294.020748 -313.362086)
		(width 0.16002)
		(layer "In4.Cu")
		(net "M_D_CPU0_SB_DQS_DN<3>")
	)
	(segment
		(start 313.898788 -307.151024)
		(end 313.898788 -306.874164)
		(width 0.16002)
		(layer "In4.Cu")
		(net "M_D_CPU0_SB_DQS_DN<3>")
	)
	(segment
		(start 289.054032 -313.67857)
		(end 289.863276 -313.67857)
		(width 0.16002)
		(layer "In4.Cu")
		(net "M_D_CPU0_SB_DQS_DN<3>")
	)
	(segment
		(start 324.561708 -294.936672)
		(end 324.561708 -294.305228)
		(width 0.09525)
		(layer "In4.Cu")
		(net "M_D_CPU0_SB_DQS_DN<3>")
	)
	(segment
		(start 300.045882 -312.512202)
		(end 301.220632 -313.686952)
		(width 0.16002)
		(layer "In4.Cu")
		(net "M_D_CPU0_SB_DQS_DN<3>")
	)
	(segment
		(start 335.392522 -290.770818)
		(end 335.400904 -290.765992)
		(width 0.09525)
		(layer "In4.Cu")
		(net "M_D_CPU0_SB_DQS_DN<3>")
	)
	(segment
		(start 321.680078 -297.900852)
		(end 324.286372 -295.295066)
		(width 0.16002)
		(layer "In4.Cu")
		(net "M_D_CPU0_SB_DQS_DN<3>")
	)
	(segment
		(start 333.881222 -290.765992)
		(end 333.889604 -290.770818)
		(width 0.09525)
		(layer "In4.Cu")
		(net "M_D_CPU0_SB_DQS_DN<3>")
	)
	(segment
		(start 285.009844 -313.511184)
		(end 287.259522 -313.511184)
		(width 0.16002)
		(layer "In4.Cu")
		(net "M_D_CPU0_SB_DQS_DN<3>")
	)
	(segment
		(start 334.821276 -290.765992)
		(end 334.829658 -290.770818)
		(width 0.09525)
		(layer "In4.Cu")
		(net "M_D_CPU0_SB_DQS_DN<3>")
	)
	(segment
		(start 312.631836 -308.631336)
		(end 312.525156 -308.524656)
		(width 0.16002)
		(layer "In4.Cu")
		(net "M_D_CPU0_SB_DQS_DN<3>")
	)
	(segment
		(start 316.646052 -304.1269)
		(end 316.841886 -303.931066)
		(width 0.16002)
		(layer "In4.Cu")
		(net "M_D_CPU0_SB_DQS_DN<3>")
	)
	(segment
		(start 312.72099 -308.051962)
		(end 312.997596 -308.051962)
		(width 0.16002)
		(layer "In4.Cu")
		(net "M_D_CPU0_SB_DQS_DN<3>")
	)
	(segment
		(start 336.332576 -290.770818)
		(end 336.340958 -290.765992)
		(width 0.09525)
		(layer "In4.Cu")
		(net "M_D_CPU0_SB_DQS_DN<3>")
	)
	(segment
		(start 299.064426 -312.512202)
		(end 300.045882 -312.512202)
		(width 0.16002)
		(layer "In4.Cu")
		(net "M_D_CPU0_SB_DQS_DN<3>")
	)
	(segment
		(start 284.736032 -313.784996)
		(end 285.009844 -313.511184)
		(width 0.16002)
		(layer "In4.Cu")
		(net "M_D_CPU0_SB_DQS_DN<3>")
	)
	(segment
		(start 296.499026 -313.362086)
		(end 296.811192 -313.674252)
		(width 0.16002)
		(layer "In4.Cu")
		(net "M_D_CPU0_SB_DQS_DN<3>")
	)
	(segment
		(start 313.898788 -306.874164)
		(end 314.094622 -306.67833)
		(width 0.16002)
		(layer "In4.Cu")
		(net "M_D_CPU0_SB_DQS_DN<3>")
	)
	(segment
		(start 316.752478 -305.037744)
		(end 316.752732 -304.51044)
		(width 0.16002)
		(layer "In4.Cu")
		(net "M_D_CPU0_SB_DQS_DN<3>")
	)
	(segment
		(start 308.98338 -312.279538)
		(end 309.510684 -312.279538)
		(width 0.16002)
		(layer "In4.Cu")
		(net "M_D_CPU0_SB_DQS_DN<3>")
	)
	(segment
		(start 304.035206 -313.607704)
		(end 304.1142 -313.686952)
		(width 0.16002)
		(layer "In4.Cu")
		(net "M_D_CPU0_SB_DQS_DN<3>")
	)
	(segment
		(start 311.347358 -309.425594)
		(end 311.623964 -309.425594)
		(width 0.16002)
		(layer "In4.Cu")
		(net "M_D_CPU0_SB_DQS_DN<3>")
	)
	(segment
		(start 312.525156 -308.524656)
		(end 312.525156 -308.247796)
		(width 0.16002)
		(layer "In4.Cu")
		(net "M_D_CPU0_SB_DQS_DN<3>")
	)
	(segment
		(start 339.086444 -290.803838)
		(end 339.187282 -290.830508)
		(width 0.09525)
		(layer "In4.Cu")
		(net "M_D_CPU0_SB_DQS_DN<3>")
	)
	(segment
		(start 304.1142 -313.686952)
		(end 304.950876 -313.686952)
		(width 0.16002)
		(layer "In4.Cu")
		(net "M_D_CPU0_SB_DQS_DN<3>")
	)
	(segment
		(start 291.512244 -312.512202)
		(end 293.170864 -312.512202)
		(width 0.16002)
		(layer "In4.Cu")
		(net "M_D_CPU0_SB_DQS_DN<3>")
	)
	(segment
		(start 312.997596 -308.051962)
		(end 313.104276 -308.158642)
		(width 0.16002)
		(layer "In4.Cu")
		(net "M_D_CPU0_SB_DQS_DN<3>")
	)
	(segment
		(start 318.019684 -302.753268)
		(end 321.680078 -299.092874)
		(width 0.16002)
		(layer "In4.Cu")
		(net "M_D_CPU0_SB_DQS_DN<3>")
	)
	(segment
		(start 316.841886 -303.931066)
		(end 317.118492 -303.931066)
		(width 0.16002)
		(layer "In4.Cu")
		(net "M_D_CPU0_SB_DQS_DN<3>")
	)
	(segment
		(start 303.12741 -312.99277)
		(end 303.420018 -312.99277)
		(width 0.16002)
		(layer "In4.Cu")
		(net "M_D_CPU0_SB_DQS_DN<3>")
	)
	(segment
		(start 315.27242 -305.500532)
		(end 315.468254 -305.304698)
		(width 0.16002)
		(layer "In4.Cu")
		(net "M_D_CPU0_SB_DQS_DN<3>")
	)
	(segment
		(start 307.9496 -312.823352)
		(end 308.600094 -312.172858)
		(width 0.16002)
		(layer "In4.Cu")
		(net "M_D_CPU0_SB_DQS_DN<3>")
	)
	(segment
		(start 311.151524 -309.621428)
		(end 311.347358 -309.425594)
		(width 0.16002)
		(layer "In4.Cu")
		(net "M_D_CPU0_SB_DQS_DN<3>")
	)
	(segment
		(start 330.12126 -290.765992)
		(end 330.129642 -290.770818)
		(width 0.09525)
		(layer "In4.Cu")
		(net "M_D_CPU0_SB_DQS_DN<3>")
	)
	(segment
		(start 330.692506 -290.770818)
		(end 330.700888 -290.765992)
		(width 0.09525)
		(layer "In4.Cu")
		(net "M_D_CPU0_SB_DQS_DN<3>")
	)
	(segment
		(start 302.433228 -313.686952)
		(end 303.12741 -312.99277)
		(width 0.16002)
		(layer "In4.Cu")
		(net "M_D_CPU0_SB_DQS_DN<3>")
	)
	(segment
		(start 288.737548 -313.362086)
		(end 289.054032 -313.67857)
		(width 0.16002)
		(layer "In4.Cu")
		(net "M_D_CPU0_SB_DQS_DN<3>")
	)
	(segment
		(start 315.85154 -305.411378)
		(end 316.378844 -305.411378)
		(width 0.16002)
		(layer "In4.Cu")
		(net "M_D_CPU0_SB_DQS_DN<3>")
	)
	(segment
		(start 315.74486 -305.304698)
		(end 315.85154 -305.411378)
		(width 0.16002)
		(layer "In4.Cu")
		(net "M_D_CPU0_SB_DQS_DN<3>")
	)
	(segment
		(start 312.257948 -309.532274)
		(end 312.631582 -309.15864)
		(width 0.16002)
		(layer "In4.Cu")
		(net "M_D_CPU0_SB_DQS_DN<3>")
	)
	(segment
		(start 311.151524 -309.898288)
		(end 311.151524 -309.621428)
		(width 0.16002)
		(layer "In4.Cu")
		(net "M_D_CPU0_SB_DQS_DN<3>")
	)
	(segment
		(start 301.220632 -313.686952)
		(end 302.433228 -313.686952)
		(width 0.16002)
		(layer "In4.Cu")
		(net "M_D_CPU0_SB_DQS_DN<3>")
	)
	(segment
		(start 298.181776 -312.912252)
		(end 298.664376 -312.912252)
		(width 0.16002)
		(layer "In4.Cu")
		(net "M_D_CPU0_SB_DQS_DN<3>")
	)
	(segment
		(start 315.378846 -306.193952)
		(end 315.3791 -305.884072)
		(width 0.16002)
		(layer "In4.Cu")
		(net "M_D_CPU0_SB_DQS_DN<3>")
	)
	(segment
		(start 308.600094 -312.172858)
		(end 308.8767 -312.172858)
		(width 0.16002)
		(layer "In4.Cu")
		(net "M_D_CPU0_SB_DQS_DN<3>")
	)
	(segment
		(start 312.525156 -308.247796)
		(end 312.72099 -308.051962)
		(width 0.16002)
		(layer "In4.Cu")
		(net "M_D_CPU0_SB_DQS_DN<3>")
	)
	(segment
		(start 311.258204 -310.004968)
		(end 311.151524 -309.898288)
		(width 0.16002)
		(layer "In4.Cu")
		(net "M_D_CPU0_SB_DQS_DN<3>")
	)
	(segment
		(start 298.664376 -312.912252)
		(end 299.064426 -312.512202)
		(width 0.16002)
		(layer "In4.Cu")
		(net "M_D_CPU0_SB_DQS_DN<3>")
	)
	(segment
		(start 290.701476 -312.84037)
		(end 291.184076 -312.84037)
		(width 0.16002)
		(layer "In4.Cu")
		(net "M_D_CPU0_SB_DQS_DN<3>")
	)
	(segment
		(start 289.863276 -313.67857)
		(end 290.701476 -312.84037)
		(width 0.16002)
		(layer "In4.Cu")
		(net "M_D_CPU0_SB_DQS_DN<3>")
	)
	(segment
		(start 315.3791 -305.884072)
		(end 315.27242 -305.777392)
		(width 0.16002)
		(layer "In4.Cu")
		(net "M_D_CPU0_SB_DQS_DN<3>")
	)
	(segment
		(start 315.468254 -305.304698)
		(end 315.74486 -305.304698)
		(width 0.16002)
		(layer "In4.Cu")
		(net "M_D_CPU0_SB_DQS_DN<3>")
	)
	(segment
		(start 324.303136 -295.195498)
		(end 324.561708 -294.936672)
		(width 0.09525)
		(layer "In4.Cu")
		(net "M_D_CPU0_SB_DQS_DN<3>")
	)
	(segment
		(start 318.12611 -303.664112)
		(end 318.126364 -303.136808)
		(width 0.16002)
		(layer "In4.Cu")
		(net "M_D_CPU0_SB_DQS_DN<3>")
	)
	(segment
		(start 327.740772 -290.71951)
		(end 328.061066 -290.71951)
		(width 0.09525)
		(layer "In4.Cu")
		(net "M_D_CPU0_SB_DQS_DN<3>")
	)
	(segment
		(start 315.27242 -305.777392)
		(end 315.27242 -305.500532)
		(width 0.16002)
		(layer "In4.Cu")
		(net "M_D_CPU0_SB_DQS_DN<3>")
	)
	(segment
		(start 296.811192 -313.674252)
		(end 297.419776 -313.674252)
		(width 0.16002)
		(layer "In4.Cu")
		(net "M_D_CPU0_SB_DQS_DN<3>")
	)
	(segment
		(start 309.884572 -311.3786)
		(end 309.777892 -311.27192)
		(width 0.16002)
		(layer "In4.Cu")
		(net "M_D_CPU0_SB_DQS_DN<3>")
	)
	(segment
		(start 309.510684 -312.279538)
		(end 309.884318 -311.905904)
		(width 0.16002)
		(layer "In4.Cu")
		(net "M_D_CPU0_SB_DQS_DN<3>")
	)
	(segment
		(start 287.40862 -313.362086)
		(end 288.737548 -313.362086)
		(width 0.16002)
		(layer "In4.Cu")
		(net "M_D_CPU0_SB_DQS_DN<3>")
	)
	(segment
		(start 317.752476 -304.037746)
		(end 318.12611 -303.664112)
		(width 0.16002)
		(layer "In4.Cu")
		(net "M_D_CPU0_SB_DQS_DN<3>")
	)
	(segment
		(start 315.005212 -306.78501)
		(end 315.378846 -306.411376)
		(width 0.16002)
		(layer "In4.Cu")
		(net "M_D_CPU0_SB_DQS_DN<3>")
	)
	(segment
		(start 297.419776 -313.674252)
		(end 298.181776 -312.912252)
		(width 0.16002)
		(layer "In4.Cu")
		(net "M_D_CPU0_SB_DQS_DN<3>")
	)
	(segment
		(start 316.752732 -304.51044)
		(end 316.646052 -304.40376)
		(width 0.16002)
		(layer "In4.Cu")
		(net "M_D_CPU0_SB_DQS_DN<3>")
	)
	(segment
		(start 313.104276 -308.158642)
		(end 313.63158 -308.158642)
		(width 0.16002)
		(layer "In4.Cu")
		(net "M_D_CPU0_SB_DQS_DN<3>")
	)
	(segment
		(start 313.63158 -308.158642)
		(end 314.005214 -307.785008)
		(width 0.16002)
		(layer "In4.Cu")
		(net "M_D_CPU0_SB_DQS_DN<3>")
	)
	(segment
		(start 291.184076 -312.84037)
		(end 291.512244 -312.512202)
		(width 0.16002)
		(layer "In4.Cu")
		(net "M_D_CPU0_SB_DQS_DN<3>")
	)
	(arc
		(start 333.512414 -290.770818)
		(mid 333.696189 -290.720046)
		(end 333.881222 -290.765992)
		(width 0.09525)
		(layer "In4.Cu")
		(net "M_D_CPU0_SB_DQS_DN<3>")
	)
	(arc
		(start 335.769712 -290.770818)
		(mid 336.051144 -290.846573)
		(end 336.332576 -290.770818)
		(width 0.09525)
		(layer "In4.Cu")
		(net "M_D_CPU0_SB_DQS_DN<3>")
	)
	(arc
		(start 328.249788 -290.770818)
		(mid 328.53122 -290.846573)
		(end 328.812652 -290.770818)
		(width 0.09525)
		(layer "In4.Cu")
		(net "M_D_CPU0_SB_DQS_DN<3>")
	)
	(arc
		(start 329.189588 -290.770818)
		(mid 329.47102 -290.846573)
		(end 329.752452 -290.770818)
		(width 0.09525)
		(layer "In4.Cu")
		(net "M_D_CPU0_SB_DQS_DN<3>")
	)
	(arc
		(start 338.58962 -290.770818)
		(mid 338.823134 -290.844661)
		(end 339.06587 -290.811966)
		(width 0.09525)
		(layer "In4.Cu")
		(net "M_D_CPU0_SB_DQS_DN<3>")
	)
	(arc
		(start 330.700888 -290.765992)
		(mid 330.88592 -290.720078)
		(end 331.069696 -290.770818)
		(width 0.09525)
		(layer "In4.Cu")
		(net "M_D_CPU0_SB_DQS_DN<3>")
	)
	(arc
		(start 328.061066 -290.71951)
		(mid 328.158812 -290.732705)
		(end 328.249788 -290.770818)
		(width 0.09525)
		(layer "In4.Cu")
		(net "M_D_CPU0_SB_DQS_DN<3>")
	)
	(arc
		(start 336.709766 -290.770818)
		(mid 336.991198 -290.846573)
		(end 337.27263 -290.770818)
		(width 0.09525)
		(layer "In4.Cu")
		(net "M_D_CPU0_SB_DQS_DN<3>")
	)
	(arc
		(start 337.27263 -290.770818)
		(mid 337.461098 -290.720141)
		(end 337.649566 -290.770818)
		(width 0.09525)
		(layer "In4.Cu")
		(net "M_D_CPU0_SB_DQS_DN<3>")
	)
	(arc
		(start 335.400904 -290.765992)
		(mid 335.585936 -290.720078)
		(end 335.769712 -290.770818)
		(width 0.09525)
		(layer "In4.Cu")
		(net "M_D_CPU0_SB_DQS_DN<3>")
	)
	(arc
		(start 328.812652 -290.770818)
		(mid 329.00112 -290.720141)
		(end 329.189588 -290.770818)
		(width 0.09525)
		(layer "In4.Cu")
		(net "M_D_CPU0_SB_DQS_DN<3>")
	)
	(arc
		(start 331.069696 -290.770818)
		(mid 331.351128 -290.846573)
		(end 331.63256 -290.770818)
		(width 0.09525)
		(layer "In4.Cu")
		(net "M_D_CPU0_SB_DQS_DN<3>")
	)
	(arc
		(start 332.00975 -290.770818)
		(mid 332.291182 -290.846573)
		(end 332.572614 -290.770818)
		(width 0.09525)
		(layer "In4.Cu")
		(net "M_D_CPU0_SB_DQS_DN<3>")
	)
	(arc
		(start 339.06587 -290.811966)
		(mid 339.076198 -290.808006)
		(end 339.086444 -290.803838)
		(width 0.09525)
		(layer "In4.Cu")
		(net "M_D_CPU0_SB_DQS_DN<3>")
	)
	(arc
		(start 333.889604 -290.770818)
		(mid 334.171036 -290.846573)
		(end 334.452468 -290.770818)
		(width 0.09525)
		(layer "In4.Cu")
		(net "M_D_CPU0_SB_DQS_DN<3>")
	)
	(arc
		(start 332.94955 -290.770818)
		(mid 333.230982 -290.846573)
		(end 333.512414 -290.770818)
		(width 0.09525)
		(layer "In4.Cu")
		(net "M_D_CPU0_SB_DQS_DN<3>")
	)
	(arc
		(start 337.649566 -290.770818)
		(mid 337.930998 -290.846573)
		(end 338.21243 -290.770818)
		(width 0.09525)
		(layer "In4.Cu")
		(net "M_D_CPU0_SB_DQS_DN<3>")
	)
	(arc
		(start 329.752452 -290.770818)
		(mid 329.936227 -290.720046)
		(end 330.12126 -290.765992)
		(width 0.09525)
		(layer "In4.Cu")
		(net "M_D_CPU0_SB_DQS_DN<3>")
	)
	(arc
		(start 331.640942 -290.765992)
		(mid 331.825974 -290.720078)
		(end 332.00975 -290.770818)
		(width 0.09525)
		(layer "In4.Cu")
		(net "M_D_CPU0_SB_DQS_DN<3>")
	)
	(arc
		(start 338.21243 -290.770818)
		(mid 338.396205 -290.720046)
		(end 338.581238 -290.765992)
		(width 0.09525)
		(layer "In4.Cu")
		(net "M_D_CPU0_SB_DQS_DN<3>")
	)
	(arc
		(start 334.829658 -290.770818)
		(mid 335.11109 -290.846573)
		(end 335.392522 -290.770818)
		(width 0.09525)
		(layer "In4.Cu")
		(net "M_D_CPU0_SB_DQS_DN<3>")
	)
	(arc
		(start 330.129642 -290.770818)
		(mid 330.411074 -290.846573)
		(end 330.692506 -290.770818)
		(width 0.09525)
		(layer "In4.Cu")
		(net "M_D_CPU0_SB_DQS_DN<3>")
	)
	(arc
		(start 334.452468 -290.770818)
		(mid 334.636243 -290.720046)
		(end 334.821276 -290.765992)
		(width 0.09525)
		(layer "In4.Cu")
		(net "M_D_CPU0_SB_DQS_DN<3>")
	)
	(arc
		(start 336.340958 -290.765992)
		(mid 336.52599 -290.720078)
		(end 336.709766 -290.770818)
		(width 0.09525)
		(layer "In4.Cu")
		(net "M_D_CPU0_SB_DQS_DN<3>")
	)
	(arc
		(start 332.572614 -290.770818)
		(mid 332.761082 -290.720141)
		(end 332.94955 -290.770818)
		(width 0.09525)
		(layer "In4.Cu")
		(net "M_D_CPU0_SB_DQS_DN<3>")
	)
	(segment
		(start 339.808058 -285.970218)
		(end 339.341206 -286.236156)
		(width 0.12954)
		(layer "F.Cu")
		(net "M_D_CPU0_SB_DQS_DN<2>")
	)
	(segment
		(start 311.576466 -299.57649)
		(end 311.787794 -299.787818)
		(width 0.16002)
		(layer "In4.Cu")
		(net "M_D_CPU0_SB_DQS_DN<2>")
	)
	(segment
		(start 312.688732 -298.88688)
		(end 312.477404 -298.675552)
		(width 0.16002)
		(layer "In4.Cu")
		(net "M_D_CPU0_SB_DQS_DN<2>")
	)
	(segment
		(start 298.181776 -303.562258)
		(end 298.664376 -303.562258)
		(width 0.16002)
		(layer "In4.Cu")
		(net "M_D_CPU0_SB_DQS_DN<2>")
	)
	(segment
		(start 339.187282 -285.970726)
		(end 339.341206 -286.236156)
		(width 0.09525)
		(layer "In4.Cu")
		(net "M_D_CPU0_SB_DQS_DN<2>")
	)
	(segment
		(start 324.243446 -286.549592)
		(end 325.459598 -286.549592)
		(width 0.09525)
		(layer "In4.Cu")
		(net "M_D_CPU0_SB_DQS_DN<2>")
	)
	(segment
		(start 313.161426 -298.414186)
		(end 313.688222 -298.41444)
		(width 0.16002)
		(layer "In4.Cu")
		(net "M_D_CPU0_SB_DQS_DN<2>")
	)
	(segment
		(start 315.224668 -295.651428)
		(end 324.109588 -286.766508)
		(width 0.16002)
		(layer "In4.Cu")
		(net "M_D_CPU0_SB_DQS_DN<2>")
	)
	(segment
		(start 335.392522 -285.911036)
		(end 335.400904 -285.90621)
		(width 0.09525)
		(layer "In4.Cu")
		(net "M_D_CPU0_SB_DQS_DN<2>")
	)
	(segment
		(start 314.535058 -297.040554)
		(end 315.061854 -297.040808)
		(width 0.16002)
		(layer "In4.Cu")
		(net "M_D_CPU0_SB_DQS_DN<2>")
	)
	(segment
		(start 296.811192 -304.324258)
		(end 297.419776 -304.324258)
		(width 0.16002)
		(layer "In4.Cu")
		(net "M_D_CPU0_SB_DQS_DN<2>")
	)
	(segment
		(start 311.299606 -299.57649)
		(end 311.576466 -299.57649)
		(width 0.16002)
		(layer "In4.Cu")
		(net "M_D_CPU0_SB_DQS_DN<2>")
	)
	(segment
		(start 312.477404 -298.675552)
		(end 312.477404 -298.398692)
		(width 0.16002)
		(layer "In4.Cu")
		(net "M_D_CPU0_SB_DQS_DN<2>")
	)
	(segment
		(start 315.435742 -296.66692)
		(end 315.435996 -296.139616)
		(width 0.16002)
		(layer "In4.Cu")
		(net "M_D_CPU0_SB_DQS_DN<2>")
	)
	(segment
		(start 334.821276 -285.90621)
		(end 334.829658 -285.911036)
		(width 0.09525)
		(layer "In4.Cu")
		(net "M_D_CPU0_SB_DQS_DN<2>")
	)
	(segment
		(start 314.04687 -296.829226)
		(end 314.32373 -296.829226)
		(width 0.16002)
		(layer "In4.Cu")
		(net "M_D_CPU0_SB_DQS_DN<2>")
	)
	(segment
		(start 288.937954 -304.012092)
		(end 289.257232 -304.33137)
		(width 0.16002)
		(layer "In4.Cu")
		(net "M_D_CPU0_SB_DQS_DN<2>")
	)
	(segment
		(start 300.178724 -303.162208)
		(end 301.411386 -304.39487)
		(width 0.16002)
		(layer "In4.Cu")
		(net "M_D_CPU0_SB_DQS_DN<2>")
	)
	(segment
		(start 315.435996 -296.139616)
		(end 315.224668 -295.928288)
		(width 0.16002)
		(layer "In4.Cu")
		(net "M_D_CPU0_SB_DQS_DN<2>")
	)
	(segment
		(start 303.704752 -303.852326)
		(end 303.704752 -304.400966)
		(width 0.16002)
		(layer "In4.Cu")
		(net "M_D_CPU0_SB_DQS_DN<2>")
	)
	(segment
		(start 314.062364 -297.513248)
		(end 313.851036 -297.30192)
		(width 0.16002)
		(layer "In4.Cu")
		(net "M_D_CPU0_SB_DQS_DN<2>")
	)
	(segment
		(start 324.126352 -286.749744)
		(end 324.126098 -286.66694)
		(width 0.09525)
		(layer "In4.Cu")
		(net "M_D_CPU0_SB_DQS_DN<2>")
	)
	(segment
		(start 301.411386 -304.39487)
		(end 302.456088 -304.39487)
		(width 0.16002)
		(layer "In4.Cu")
		(net "M_D_CPU0_SB_DQS_DN<2>")
	)
	(segment
		(start 312.673238 -298.202858)
		(end 312.950098 -298.202858)
		(width 0.16002)
		(layer "In4.Cu")
		(net "M_D_CPU0_SB_DQS_DN<2>")
	)
	(segment
		(start 289.863276 -304.33137)
		(end 290.676076 -303.51857)
		(width 0.16002)
		(layer "In4.Cu")
		(net "M_D_CPU0_SB_DQS_DN<2>")
	)
	(segment
		(start 311.103772 -299.772324)
		(end 311.299606 -299.57649)
		(width 0.16002)
		(layer "In4.Cu")
		(net "M_D_CPU0_SB_DQS_DN<2>")
	)
	(segment
		(start 309.660798 -302.107854)
		(end 309.660798 -301.215298)
		(width 0.16002)
		(layer "In4.Cu")
		(net "M_D_CPU0_SB_DQS_DN<2>")
	)
	(segment
		(start 291.209476 -303.51857)
		(end 291.565838 -303.162208)
		(width 0.16002)
		(layer "In4.Cu")
		(net "M_D_CPU0_SB_DQS_DN<2>")
	)
	(segment
		(start 327.862184 -285.917132)
		(end 327.872598 -285.911036)
		(width 0.09525)
		(layer "In4.Cu")
		(net "M_D_CPU0_SB_DQS_DN<2>")
	)
	(segment
		(start 327.301606 -285.90621)
		(end 327.309988 -285.911036)
		(width 0.09525)
		(layer "In4.Cu")
		(net "M_D_CPU0_SB_DQS_DN<2>")
	)
	(segment
		(start 324.126098 -286.66694)
		(end 324.243446 -286.549592)
		(width 0.09525)
		(layer "In4.Cu")
		(net "M_D_CPU0_SB_DQS_DN<2>")
	)
	(segment
		(start 309.660798 -301.215298)
		(end 309.925974 -300.950122)
		(width 0.16002)
		(layer "In4.Cu")
		(net "M_D_CPU0_SB_DQS_DN<2>")
	)
	(segment
		(start 311.787794 -299.787818)
		(end 312.31459 -299.788072)
		(width 0.16002)
		(layer "In4.Cu")
		(net "M_D_CPU0_SB_DQS_DN<2>")
	)
	(segment
		(start 312.950098 -298.202858)
		(end 313.161426 -298.414186)
		(width 0.16002)
		(layer "In4.Cu")
		(net "M_D_CPU0_SB_DQS_DN<2>")
	)
	(segment
		(start 290.676076 -303.51857)
		(end 291.209476 -303.51857)
		(width 0.16002)
		(layer "In4.Cu")
		(net "M_D_CPU0_SB_DQS_DN<2>")
	)
	(segment
		(start 304.565304 -304.77587)
		(end 305.867816 -303.473358)
		(width 0.16002)
		(layer "In4.Cu")
		(net "M_D_CPU0_SB_DQS_DN<2>")
	)
	(segment
		(start 299.064426 -303.162208)
		(end 300.178724 -303.162208)
		(width 0.16002)
		(layer "In4.Cu")
		(net "M_D_CPU0_SB_DQS_DN<2>")
	)
	(segment
		(start 285.009844 -304.16119)
		(end 287.720278 -304.16119)
		(width 0.16002)
		(layer "In4.Cu")
		(net "M_D_CPU0_SB_DQS_DN<2>")
	)
	(segment
		(start 324.109588 -286.766508)
		(end 324.126352 -286.749744)
		(width 0.09525)
		(layer "In4.Cu")
		(net "M_D_CPU0_SB_DQS_DN<2>")
	)
	(segment
		(start 327.872598 -285.911036)
		(end 327.88098 -285.90621)
		(width 0.09525)
		(layer "In4.Cu")
		(net "M_D_CPU0_SB_DQS_DN<2>")
	)
	(segment
		(start 314.32373 -296.829226)
		(end 314.535058 -297.040554)
		(width 0.16002)
		(layer "In4.Cu")
		(net "M_D_CPU0_SB_DQS_DN<2>")
	)
	(segment
		(start 293.65067 -303.162208)
		(end 294.500554 -304.012092)
		(width 0.16002)
		(layer "In4.Cu")
		(net "M_D_CPU0_SB_DQS_DN<2>")
	)
	(segment
		(start 304.079656 -304.77587)
		(end 304.565304 -304.77587)
		(width 0.16002)
		(layer "In4.Cu")
		(net "M_D_CPU0_SB_DQS_DN<2>")
	)
	(segment
		(start 339.086444 -285.944056)
		(end 339.187282 -285.970726)
		(width 0.09525)
		(layer "In4.Cu")
		(net "M_D_CPU0_SB_DQS_DN<2>")
	)
	(segment
		(start 312.477404 -298.398692)
		(end 312.673238 -298.202858)
		(width 0.16002)
		(layer "In4.Cu")
		(net "M_D_CPU0_SB_DQS_DN<2>")
	)
	(segment
		(start 330.692506 -285.911036)
		(end 330.700888 -285.90621)
		(width 0.09525)
		(layer "In4.Cu")
		(net "M_D_CPU0_SB_DQS_DN<2>")
	)
	(segment
		(start 297.419776 -304.324258)
		(end 298.181776 -303.562258)
		(width 0.16002)
		(layer "In4.Cu")
		(net "M_D_CPU0_SB_DQS_DN<2>")
	)
	(segment
		(start 311.314846 -300.787816)
		(end 311.3151 -300.260512)
		(width 0.16002)
		(layer "In4.Cu")
		(net "M_D_CPU0_SB_DQS_DN<2>")
	)
	(segment
		(start 311.3151 -300.260512)
		(end 311.103772 -300.049184)
		(width 0.16002)
		(layer "In4.Cu")
		(net "M_D_CPU0_SB_DQS_DN<2>")
	)
	(segment
		(start 326.022208 -285.986982)
		(end 326.651112 -285.986982)
		(width 0.09525)
		(layer "In4.Cu")
		(net "M_D_CPU0_SB_DQS_DN<2>")
	)
	(segment
		(start 333.881222 -285.90621)
		(end 333.889604 -285.911036)
		(width 0.09525)
		(layer "In4.Cu")
		(net "M_D_CPU0_SB_DQS_DN<2>")
	)
	(segment
		(start 294.500554 -304.012092)
		(end 296.499026 -304.012092)
		(width 0.16002)
		(layer "In4.Cu")
		(net "M_D_CPU0_SB_DQS_DN<2>")
	)
	(segment
		(start 313.851036 -297.02506)
		(end 314.04687 -296.829226)
		(width 0.16002)
		(layer "In4.Cu")
		(net "M_D_CPU0_SB_DQS_DN<2>")
	)
	(segment
		(start 309.925974 -300.950122)
		(end 310.202834 -300.950122)
		(width 0.16002)
		(layer "In4.Cu")
		(net "M_D_CPU0_SB_DQS_DN<2>")
	)
	(segment
		(start 315.061854 -297.040808)
		(end 315.435742 -296.66692)
		(width 0.16002)
		(layer "In4.Cu")
		(net "M_D_CPU0_SB_DQS_DN<2>")
	)
	(segment
		(start 308.295294 -303.473358)
		(end 309.660798 -302.107854)
		(width 0.16002)
		(layer "In4.Cu")
		(net "M_D_CPU0_SB_DQS_DN<2>")
	)
	(segment
		(start 311.103772 -300.049184)
		(end 311.103772 -299.772324)
		(width 0.16002)
		(layer "In4.Cu")
		(net "M_D_CPU0_SB_DQS_DN<2>")
	)
	(segment
		(start 284.736032 -304.435002)
		(end 285.009844 -304.16119)
		(width 0.16002)
		(layer "In4.Cu")
		(net "M_D_CPU0_SB_DQS_DN<2>")
	)
	(segment
		(start 303.205388 -303.64557)
		(end 303.497996 -303.64557)
		(width 0.16002)
		(layer "In4.Cu")
		(net "M_D_CPU0_SB_DQS_DN<2>")
	)
	(segment
		(start 287.869376 -304.012092)
		(end 288.937954 -304.012092)
		(width 0.16002)
		(layer "In4.Cu")
		(net "M_D_CPU0_SB_DQS_DN<2>")
	)
	(segment
		(start 313.851036 -297.30192)
		(end 313.851036 -297.02506)
		(width 0.16002)
		(layer "In4.Cu")
		(net "M_D_CPU0_SB_DQS_DN<2>")
	)
	(segment
		(start 325.459598 -286.549592)
		(end 326.022208 -285.986982)
		(width 0.09525)
		(layer "In4.Cu")
		(net "M_D_CPU0_SB_DQS_DN<2>")
	)
	(segment
		(start 296.499026 -304.012092)
		(end 296.811192 -304.324258)
		(width 0.16002)
		(layer "In4.Cu")
		(net "M_D_CPU0_SB_DQS_DN<2>")
	)
	(segment
		(start 305.867816 -303.473358)
		(end 308.295294 -303.473358)
		(width 0.16002)
		(layer "In4.Cu")
		(net "M_D_CPU0_SB_DQS_DN<2>")
	)
	(segment
		(start 287.720278 -304.16119)
		(end 287.869376 -304.012092)
		(width 0.16002)
		(layer "In4.Cu")
		(net "M_D_CPU0_SB_DQS_DN<2>")
	)
	(segment
		(start 315.224668 -295.928288)
		(end 315.224668 -295.651428)
		(width 0.16002)
		(layer "In4.Cu")
		(net "M_D_CPU0_SB_DQS_DN<2>")
	)
	(segment
		(start 298.664376 -303.562258)
		(end 299.064426 -303.162208)
		(width 0.16002)
		(layer "In4.Cu")
		(net "M_D_CPU0_SB_DQS_DN<2>")
	)
	(segment
		(start 312.31459 -299.788072)
		(end 312.688478 -299.414184)
		(width 0.16002)
		(layer "In4.Cu")
		(net "M_D_CPU0_SB_DQS_DN<2>")
	)
	(segment
		(start 303.704752 -304.400966)
		(end 304.079656 -304.77587)
		(width 0.16002)
		(layer "In4.Cu")
		(net "M_D_CPU0_SB_DQS_DN<2>")
	)
	(segment
		(start 310.414162 -301.16145)
		(end 310.940958 -301.161704)
		(width 0.16002)
		(layer "In4.Cu")
		(net "M_D_CPU0_SB_DQS_DN<2>")
	)
	(segment
		(start 314.06211 -298.040552)
		(end 314.062364 -297.513248)
		(width 0.16002)
		(layer "In4.Cu")
		(net "M_D_CPU0_SB_DQS_DN<2>")
	)
	(segment
		(start 331.63256 -285.911036)
		(end 331.640942 -285.90621)
		(width 0.09525)
		(layer "In4.Cu")
		(net "M_D_CPU0_SB_DQS_DN<2>")
	)
	(segment
		(start 303.497996 -303.64557)
		(end 303.704752 -303.852326)
		(width 0.16002)
		(layer "In4.Cu")
		(net "M_D_CPU0_SB_DQS_DN<2>")
	)
	(segment
		(start 289.257232 -304.33137)
		(end 289.863276 -304.33137)
		(width 0.16002)
		(layer "In4.Cu")
		(net "M_D_CPU0_SB_DQS_DN<2>")
	)
	(segment
		(start 313.688222 -298.41444)
		(end 314.06211 -298.040552)
		(width 0.16002)
		(layer "In4.Cu")
		(net "M_D_CPU0_SB_DQS_DN<2>")
	)
	(segment
		(start 312.688478 -299.414184)
		(end 312.688732 -298.88688)
		(width 0.16002)
		(layer "In4.Cu")
		(net "M_D_CPU0_SB_DQS_DN<2>")
	)
	(segment
		(start 310.940958 -301.161704)
		(end 311.314846 -300.787816)
		(width 0.16002)
		(layer "In4.Cu")
		(net "M_D_CPU0_SB_DQS_DN<2>")
	)
	(segment
		(start 330.12126 -285.90621)
		(end 330.129642 -285.911036)
		(width 0.09525)
		(layer "In4.Cu")
		(net "M_D_CPU0_SB_DQS_DN<2>")
	)
	(segment
		(start 291.565838 -303.162208)
		(end 293.65067 -303.162208)
		(width 0.16002)
		(layer "In4.Cu")
		(net "M_D_CPU0_SB_DQS_DN<2>")
	)
	(segment
		(start 310.202834 -300.950122)
		(end 310.414162 -301.16145)
		(width 0.16002)
		(layer "In4.Cu")
		(net "M_D_CPU0_SB_DQS_DN<2>")
	)
	(segment
		(start 302.456088 -304.39487)
		(end 303.205388 -303.64557)
		(width 0.16002)
		(layer "In4.Cu")
		(net "M_D_CPU0_SB_DQS_DN<2>")
	)
	(segment
		(start 336.332576 -285.911036)
		(end 336.340958 -285.90621)
		(width 0.09525)
		(layer "In4.Cu")
		(net "M_D_CPU0_SB_DQS_DN<2>")
	)
	(segment
		(start 338.581238 -285.90621)
		(end 338.58962 -285.911036)
		(width 0.09525)
		(layer "In4.Cu")
		(net "M_D_CPU0_SB_DQS_DN<2>")
	)
	(arc
		(start 326.932798 -285.911036)
		(mid 327.116573 -285.860264)
		(end 327.301606 -285.90621)
		(width 0.09525)
		(layer "In4.Cu")
		(net "M_D_CPU0_SB_DQS_DN<2>")
	)
	(arc
		(start 327.88098 -285.90621)
		(mid 328.066012 -285.860296)
		(end 328.249788 -285.911036)
		(width 0.09525)
		(layer "In4.Cu")
		(net "M_D_CPU0_SB_DQS_DN<2>")
	)
	(arc
		(start 330.700888 -285.90621)
		(mid 330.88592 -285.860296)
		(end 331.069696 -285.911036)
		(width 0.09525)
		(layer "In4.Cu")
		(net "M_D_CPU0_SB_DQS_DN<2>")
	)
	(arc
		(start 337.649566 -285.911036)
		(mid 337.930998 -285.986791)
		(end 338.21243 -285.911036)
		(width 0.09525)
		(layer "In4.Cu")
		(net "M_D_CPU0_SB_DQS_DN<2>")
	)
	(arc
		(start 333.512414 -285.911036)
		(mid 333.696189 -285.860264)
		(end 333.881222 -285.90621)
		(width 0.09525)
		(layer "In4.Cu")
		(net "M_D_CPU0_SB_DQS_DN<2>")
	)
	(arc
		(start 332.94955 -285.911036)
		(mid 333.230982 -285.986791)
		(end 333.512414 -285.911036)
		(width 0.09525)
		(layer "In4.Cu")
		(net "M_D_CPU0_SB_DQS_DN<2>")
	)
	(arc
		(start 330.129642 -285.911036)
		(mid 330.411074 -285.986791)
		(end 330.692506 -285.911036)
		(width 0.09525)
		(layer "In4.Cu")
		(net "M_D_CPU0_SB_DQS_DN<2>")
	)
	(arc
		(start 336.340958 -285.90621)
		(mid 336.52599 -285.860296)
		(end 336.709766 -285.911036)
		(width 0.09525)
		(layer "In4.Cu")
		(net "M_D_CPU0_SB_DQS_DN<2>")
	)
	(arc
		(start 335.400904 -285.90621)
		(mid 335.585936 -285.860296)
		(end 335.769712 -285.911036)
		(width 0.09525)
		(layer "In4.Cu")
		(net "M_D_CPU0_SB_DQS_DN<2>")
	)
	(arc
		(start 336.709766 -285.911036)
		(mid 336.991198 -285.986791)
		(end 337.27263 -285.911036)
		(width 0.09525)
		(layer "In4.Cu")
		(net "M_D_CPU0_SB_DQS_DN<2>")
	)
	(arc
		(start 328.249788 -285.911036)
		(mid 328.53122 -285.986791)
		(end 328.812652 -285.911036)
		(width 0.09525)
		(layer "In4.Cu")
		(net "M_D_CPU0_SB_DQS_DN<2>")
	)
	(arc
		(start 328.812652 -285.911036)
		(mid 329.00112 -285.860359)
		(end 329.189588 -285.911036)
		(width 0.09525)
		(layer "In4.Cu")
		(net "M_D_CPU0_SB_DQS_DN<2>")
	)
	(arc
		(start 329.189588 -285.911036)
		(mid 329.47102 -285.986791)
		(end 329.752452 -285.911036)
		(width 0.09525)
		(layer "In4.Cu")
		(net "M_D_CPU0_SB_DQS_DN<2>")
	)
	(arc
		(start 338.21243 -285.911036)
		(mid 338.396205 -285.860264)
		(end 338.581238 -285.90621)
		(width 0.09525)
		(layer "In4.Cu")
		(net "M_D_CPU0_SB_DQS_DN<2>")
	)
	(arc
		(start 333.889604 -285.911036)
		(mid 334.171036 -285.986791)
		(end 334.452468 -285.911036)
		(width 0.09525)
		(layer "In4.Cu")
		(net "M_D_CPU0_SB_DQS_DN<2>")
	)
	(arc
		(start 329.752452 -285.911036)
		(mid 329.936227 -285.860264)
		(end 330.12126 -285.90621)
		(width 0.09525)
		(layer "In4.Cu")
		(net "M_D_CPU0_SB_DQS_DN<2>")
	)
	(arc
		(start 339.06587 -285.952184)
		(mid 339.076198 -285.948224)
		(end 339.086444 -285.944056)
		(width 0.09525)
		(layer "In4.Cu")
		(net "M_D_CPU0_SB_DQS_DN<2>")
	)
	(arc
		(start 326.651112 -285.986982)
		(mid 326.796992 -285.967677)
		(end 326.932798 -285.911036)
		(width 0.09525)
		(layer "In4.Cu")
		(net "M_D_CPU0_SB_DQS_DN<2>")
	)
	(arc
		(start 331.069696 -285.911036)
		(mid 331.351128 -285.986791)
		(end 331.63256 -285.911036)
		(width 0.09525)
		(layer "In4.Cu")
		(net "M_D_CPU0_SB_DQS_DN<2>")
	)
	(arc
		(start 335.769712 -285.911036)
		(mid 336.051144 -285.986791)
		(end 336.332576 -285.911036)
		(width 0.09525)
		(layer "In4.Cu")
		(net "M_D_CPU0_SB_DQS_DN<2>")
	)
	(arc
		(start 334.452468 -285.911036)
		(mid 334.636243 -285.860264)
		(end 334.821276 -285.90621)
		(width 0.09525)
		(layer "In4.Cu")
		(net "M_D_CPU0_SB_DQS_DN<2>")
	)
	(arc
		(start 331.640942 -285.90621)
		(mid 331.825974 -285.860296)
		(end 332.00975 -285.911036)
		(width 0.09525)
		(layer "In4.Cu")
		(net "M_D_CPU0_SB_DQS_DN<2>")
	)
	(arc
		(start 337.27263 -285.911036)
		(mid 337.461098 -285.860359)
		(end 337.649566 -285.911036)
		(width 0.09525)
		(layer "In4.Cu")
		(net "M_D_CPU0_SB_DQS_DN<2>")
	)
	(arc
		(start 327.309988 -285.911036)
		(mid 327.585277 -285.986757)
		(end 327.862184 -285.917132)
		(width 0.09525)
		(layer "In4.Cu")
		(net "M_D_CPU0_SB_DQS_DN<2>")
	)
	(arc
		(start 332.572614 -285.911036)
		(mid 332.761082 -285.860359)
		(end 332.94955 -285.911036)
		(width 0.09525)
		(layer "In4.Cu")
		(net "M_D_CPU0_SB_DQS_DN<2>")
	)
	(arc
		(start 332.00975 -285.911036)
		(mid 332.291182 -285.986791)
		(end 332.572614 -285.911036)
		(width 0.09525)
		(layer "In4.Cu")
		(net "M_D_CPU0_SB_DQS_DN<2>")
	)
	(arc
		(start 334.829658 -285.911036)
		(mid 335.11109 -285.986791)
		(end 335.392522 -285.911036)
		(width 0.09525)
		(layer "In4.Cu")
		(net "M_D_CPU0_SB_DQS_DN<2>")
	)
	(arc
		(start 338.58962 -285.911036)
		(mid 338.823134 -285.984879)
		(end 339.06587 -285.952184)
		(width 0.09525)
		(layer "In4.Cu")
		(net "M_D_CPU0_SB_DQS_DN<2>")
	)
	(segment
		(start 339.808058 -281.110182)
		(end 339.341206 -281.37612)
		(width 0.12954)
		(layer "F.Cu")
		(net "M_D_CPU0_SB_DQS_DN<1>")
	)
	(segment
		(start 336.332576 -281.051)
		(end 336.340958 -281.046174)
		(width 0.09525)
		(layer "In4.Cu")
		(net "M_D_CPU0_SB_DQS_DN<1>")
	)
	(segment
		(start 315.763656 -287.03778)
		(end 315.763656 -286.510476)
		(width 0.16002)
		(layer "In4.Cu")
		(net "M_D_CPU0_SB_DQS_DN<1>")
	)
	(segment
		(start 330.12126 -281.046174)
		(end 330.129642 -281.051)
		(width 0.09525)
		(layer "In4.Cu")
		(net "M_D_CPU0_SB_DQS_DN<1>")
	)
	(segment
		(start 339.187282 -281.11069)
		(end 339.341206 -281.37612)
		(width 0.09525)
		(layer "In4.Cu")
		(net "M_D_CPU0_SB_DQS_DN<1>")
	)
	(segment
		(start 316.958218 -284.680914)
		(end 317.154814 -284.484318)
		(width 0.16002)
		(layer "In4.Cu")
		(net "M_D_CPU0_SB_DQS_DN<1>")
	)
	(segment
		(start 291.619432 -293.812214)
		(end 293.03853 -293.812214)
		(width 0.16002)
		(layer "In4.Cu")
		(net "M_D_CPU0_SB_DQS_DN<1>")
	)
	(segment
		(start 317.610744 -284.663388)
		(end 318.138048 -284.663388)
		(width 0.16002)
		(layer "In4.Cu")
		(net "M_D_CPU0_SB_DQS_DN<1>")
	)
	(segment
		(start 297.419776 -294.974264)
		(end 298.181776 -294.212264)
		(width 0.16002)
		(layer "In4.Cu")
		(net "M_D_CPU0_SB_DQS_DN<1>")
	)
	(segment
		(start 333.881222 -281.046174)
		(end 333.889604 -281.051)
		(width 0.09525)
		(layer "In4.Cu")
		(net "M_D_CPU0_SB_DQS_DN<1>")
	)
	(segment
		(start 320.178938 -281.737054)
		(end 320.358008 -281.916124)
		(width 0.16002)
		(layer "In4.Cu")
		(net "M_D_CPU0_SB_DQS_DN<1>")
	)
	(segment
		(start 314.86348 -287.410652)
		(end 315.390784 -287.410652)
		(width 0.16002)
		(layer "In4.Cu")
		(net "M_D_CPU0_SB_DQS_DN<1>")
	)
	(segment
		(start 296.468038 -294.662098)
		(end 296.780204 -294.974264)
		(width 0.16002)
		(layer "In4.Cu")
		(net "M_D_CPU0_SB_DQS_DN<1>")
	)
	(segment
		(start 298.181776 -294.212264)
		(end 298.664376 -294.212264)
		(width 0.16002)
		(layer "In4.Cu")
		(net "M_D_CPU0_SB_DQS_DN<1>")
	)
	(segment
		(start 289.82543 -295.022016)
		(end 290.676076 -294.17137)
		(width 0.16002)
		(layer "In4.Cu")
		(net "M_D_CPU0_SB_DQS_DN<1>")
	)
	(segment
		(start 314.210954 -287.705038)
		(end 314.210954 -287.428178)
		(width 0.16002)
		(layer "In4.Cu")
		(net "M_D_CPU0_SB_DQS_DN<1>")
	)
	(segment
		(start 327.301606 -281.046174)
		(end 327.309988 -281.051)
		(width 0.09525)
		(layer "In4.Cu")
		(net "M_D_CPU0_SB_DQS_DN<1>")
	)
	(segment
		(start 284.736032 -295.085008)
		(end 285.009844 -294.811196)
		(width 0.16002)
		(layer "In4.Cu")
		(net "M_D_CPU0_SB_DQS_DN<1>")
	)
	(segment
		(start 287.359344 -294.811196)
		(end 287.508442 -294.662098)
		(width 0.16002)
		(layer "In4.Cu")
		(net "M_D_CPU0_SB_DQS_DN<1>")
	)
	(segment
		(start 318.33185 -283.307282)
		(end 318.528446 -283.110686)
		(width 0.16002)
		(layer "In4.Cu")
		(net "M_D_CPU0_SB_DQS_DN<1>")
	)
	(segment
		(start 331.63256 -281.051)
		(end 331.640942 -281.046174)
		(width 0.09525)
		(layer "In4.Cu")
		(net "M_D_CPU0_SB_DQS_DN<1>")
	)
	(segment
		(start 317.137288 -285.136844)
		(end 316.958218 -284.957774)
		(width 0.16002)
		(layer "In4.Cu")
		(net "M_D_CPU0_SB_DQS_DN<1>")
	)
	(segment
		(start 324.095364 -281.082242)
		(end 324.154292 -281.023314)
		(width 0.09525)
		(layer "In4.Cu")
		(net "M_D_CPU0_SB_DQS_DN<1>")
	)
	(segment
		(start 288.90976 -294.662098)
		(end 289.269678 -295.022016)
		(width 0.16002)
		(layer "In4.Cu")
		(net "M_D_CPU0_SB_DQS_DN<1>")
	)
	(segment
		(start 318.805306 -283.110686)
		(end 318.984376 -283.289756)
		(width 0.16002)
		(layer "In4.Cu")
		(net "M_D_CPU0_SB_DQS_DN<1>")
	)
	(segment
		(start 324.071742 -281.082242)
		(end 324.095364 -281.082242)
		(width 0.09525)
		(layer "In4.Cu")
		(net "M_D_CPU0_SB_DQS_DN<1>")
	)
	(segment
		(start 299.064426 -293.812214)
		(end 300.167802 -293.812214)
		(width 0.16002)
		(layer "In4.Cu")
		(net "M_D_CPU0_SB_DQS_DN<1>")
	)
	(segment
		(start 317.154814 -284.484318)
		(end 317.431674 -284.484318)
		(width 0.16002)
		(layer "In4.Cu")
		(net "M_D_CPU0_SB_DQS_DN<1>")
	)
	(segment
		(start 317.137288 -285.664148)
		(end 317.137288 -285.136844)
		(width 0.16002)
		(layer "In4.Cu")
		(net "M_D_CPU0_SB_DQS_DN<1>")
	)
	(segment
		(start 316.764416 -286.03702)
		(end 317.137288 -285.664148)
		(width 0.16002)
		(layer "In4.Cu")
		(net "M_D_CPU0_SB_DQS_DN<1>")
	)
	(segment
		(start 318.51092 -284.290516)
		(end 318.51092 -283.763212)
		(width 0.16002)
		(layer "In4.Cu")
		(net "M_D_CPU0_SB_DQS_DN<1>")
	)
	(segment
		(start 304.950876 -294.986964)
		(end 305.814476 -294.123364)
		(width 0.16002)
		(layer "In4.Cu")
		(net "M_D_CPU0_SB_DQS_DN<1>")
	)
	(segment
		(start 315.584586 -286.054546)
		(end 315.781182 -285.85795)
		(width 0.16002)
		(layer "In4.Cu")
		(net "M_D_CPU0_SB_DQS_DN<1>")
	)
	(segment
		(start 315.781182 -285.85795)
		(end 316.058042 -285.85795)
		(width 0.16002)
		(layer "In4.Cu")
		(net "M_D_CPU0_SB_DQS_DN<1>")
	)
	(segment
		(start 320.358008 -281.916124)
		(end 320.885312 -281.916124)
		(width 0.16002)
		(layer "In4.Cu")
		(net "M_D_CPU0_SB_DQS_DN<1>")
	)
	(segment
		(start 314.40755 -287.231582)
		(end 314.68441 -287.231582)
		(width 0.16002)
		(layer "In4.Cu")
		(net "M_D_CPU0_SB_DQS_DN<1>")
	)
	(segment
		(start 315.584586 -286.331406)
		(end 315.584586 -286.054546)
		(width 0.16002)
		(layer "In4.Cu")
		(net "M_D_CPU0_SB_DQS_DN<1>")
	)
	(segment
		(start 287.508442 -294.662098)
		(end 288.90976 -294.662098)
		(width 0.16002)
		(layer "In4.Cu")
		(net "M_D_CPU0_SB_DQS_DN<1>")
	)
	(segment
		(start 339.086444 -281.08402)
		(end 339.187282 -281.11069)
		(width 0.09525)
		(layer "In4.Cu")
		(net "M_D_CPU0_SB_DQS_DN<1>")
	)
	(segment
		(start 316.958218 -284.957774)
		(end 316.958218 -284.680914)
		(width 0.16002)
		(layer "In4.Cu")
		(net "M_D_CPU0_SB_DQS_DN<1>")
	)
	(segment
		(start 285.009844 -294.811196)
		(end 287.359344 -294.811196)
		(width 0.16002)
		(layer "In4.Cu")
		(net "M_D_CPU0_SB_DQS_DN<1>")
	)
	(segment
		(start 318.33185 -283.584142)
		(end 318.33185 -283.307282)
		(width 0.16002)
		(layer "In4.Cu")
		(net "M_D_CPU0_SB_DQS_DN<1>")
	)
	(segment
		(start 314.210954 -287.428178)
		(end 314.40755 -287.231582)
		(width 0.16002)
		(layer "In4.Cu")
		(net "M_D_CPU0_SB_DQS_DN<1>")
	)
	(segment
		(start 300.167802 -293.812214)
		(end 301.342552 -294.986964)
		(width 0.16002)
		(layer "In4.Cu")
		(net "M_D_CPU0_SB_DQS_DN<1>")
	)
	(segment
		(start 305.814476 -294.123364)
		(end 308.678072 -294.123364)
		(width 0.16002)
		(layer "In4.Cu")
		(net "M_D_CPU0_SB_DQS_DN<1>")
	)
	(segment
		(start 338.581238 -281.046174)
		(end 338.58962 -281.051)
		(width 0.09525)
		(layer "In4.Cu")
		(net "M_D_CPU0_SB_DQS_DN<1>")
	)
	(segment
		(start 335.392522 -281.051)
		(end 335.400904 -281.046174)
		(width 0.09525)
		(layer "In4.Cu")
		(net "M_D_CPU0_SB_DQS_DN<1>")
	)
	(segment
		(start 316.237112 -286.03702)
		(end 316.764416 -286.03702)
		(width 0.16002)
		(layer "In4.Cu")
		(net "M_D_CPU0_SB_DQS_DN<1>")
	)
	(segment
		(start 319.705482 -281.93365)
		(end 319.902078 -281.737054)
		(width 0.16002)
		(layer "In4.Cu")
		(net "M_D_CPU0_SB_DQS_DN<1>")
	)
	(segment
		(start 326.369934 -281.051)
		(end 326.384666 -281.059636)
		(width 0.09525)
		(layer "In4.Cu")
		(net "M_D_CPU0_SB_DQS_DN<1>")
	)
	(segment
		(start 291.260276 -294.17137)
		(end 291.619432 -293.812214)
		(width 0.16002)
		(layer "In4.Cu")
		(net "M_D_CPU0_SB_DQS_DN<1>")
	)
	(segment
		(start 327.872598 -281.051)
		(end 327.88098 -281.046174)
		(width 0.09525)
		(layer "In4.Cu")
		(net "M_D_CPU0_SB_DQS_DN<1>")
	)
	(segment
		(start 319.51168 -283.289756)
		(end 319.884552 -282.916884)
		(width 0.16002)
		(layer "In4.Cu")
		(net "M_D_CPU0_SB_DQS_DN<1>")
	)
	(segment
		(start 324.49516 -281.023314)
		(end 324.79869 -280.719784)
		(width 0.09525)
		(layer "In4.Cu")
		(net "M_D_CPU0_SB_DQS_DN<1>")
	)
	(segment
		(start 317.431674 -284.484318)
		(end 317.610744 -284.663388)
		(width 0.16002)
		(layer "In4.Cu")
		(net "M_D_CPU0_SB_DQS_DN<1>")
	)
	(segment
		(start 301.342552 -294.986964)
		(end 304.950876 -294.986964)
		(width 0.16002)
		(layer "In4.Cu")
		(net "M_D_CPU0_SB_DQS_DN<1>")
	)
	(segment
		(start 308.678072 -294.123364)
		(end 314.390024 -288.411412)
		(width 0.16002)
		(layer "In4.Cu")
		(net "M_D_CPU0_SB_DQS_DN<1>")
	)
	(segment
		(start 319.705482 -282.21051)
		(end 319.705482 -281.93365)
		(width 0.16002)
		(layer "In4.Cu")
		(net "M_D_CPU0_SB_DQS_DN<1>")
	)
	(segment
		(start 293.03853 -293.812214)
		(end 293.888414 -294.662098)
		(width 0.16002)
		(layer "In4.Cu")
		(net "M_D_CPU0_SB_DQS_DN<1>")
	)
	(segment
		(start 316.058042 -285.85795)
		(end 316.237112 -286.03702)
		(width 0.16002)
		(layer "In4.Cu")
		(net "M_D_CPU0_SB_DQS_DN<1>")
	)
	(segment
		(start 327.862184 -281.057096)
		(end 327.872598 -281.051)
		(width 0.09525)
		(layer "In4.Cu")
		(net "M_D_CPU0_SB_DQS_DN<1>")
	)
	(segment
		(start 324.79869 -280.719784)
		(end 326.012302 -280.719784)
		(width 0.09525)
		(layer "In4.Cu")
		(net "M_D_CPU0_SB_DQS_DN<1>")
	)
	(segment
		(start 319.884552 -282.916884)
		(end 319.884552 -282.38958)
		(width 0.16002)
		(layer "In4.Cu")
		(net "M_D_CPU0_SB_DQS_DN<1>")
	)
	(segment
		(start 314.68441 -287.231582)
		(end 314.86348 -287.410652)
		(width 0.16002)
		(layer "In4.Cu")
		(net "M_D_CPU0_SB_DQS_DN<1>")
	)
	(segment
		(start 324.154292 -281.023314)
		(end 324.49516 -281.023314)
		(width 0.09525)
		(layer "In4.Cu")
		(net "M_D_CPU0_SB_DQS_DN<1>")
	)
	(segment
		(start 318.51092 -283.763212)
		(end 318.33185 -283.584142)
		(width 0.16002)
		(layer "In4.Cu")
		(net "M_D_CPU0_SB_DQS_DN<1>")
	)
	(segment
		(start 319.902078 -281.737054)
		(end 320.178938 -281.737054)
		(width 0.16002)
		(layer "In4.Cu")
		(net "M_D_CPU0_SB_DQS_DN<1>")
	)
	(segment
		(start 318.528446 -283.110686)
		(end 318.805306 -283.110686)
		(width 0.16002)
		(layer "In4.Cu")
		(net "M_D_CPU0_SB_DQS_DN<1>")
	)
	(segment
		(start 320.885312 -281.916124)
		(end 321.719194 -281.082242)
		(width 0.16002)
		(layer "In4.Cu")
		(net "M_D_CPU0_SB_DQS_DN<1>")
	)
	(segment
		(start 314.390024 -288.411412)
		(end 314.390024 -287.884108)
		(width 0.16002)
		(layer "In4.Cu")
		(net "M_D_CPU0_SB_DQS_DN<1>")
	)
	(segment
		(start 315.390784 -287.410652)
		(end 315.763656 -287.03778)
		(width 0.16002)
		(layer "In4.Cu")
		(net "M_D_CPU0_SB_DQS_DN<1>")
	)
	(segment
		(start 318.138048 -284.663388)
		(end 318.51092 -284.290516)
		(width 0.16002)
		(layer "In4.Cu")
		(net "M_D_CPU0_SB_DQS_DN<1>")
	)
	(segment
		(start 296.780204 -294.974264)
		(end 297.419776 -294.974264)
		(width 0.16002)
		(layer "In4.Cu")
		(net "M_D_CPU0_SB_DQS_DN<1>")
	)
	(segment
		(start 334.821276 -281.046174)
		(end 334.829658 -281.051)
		(width 0.09525)
		(layer "In4.Cu")
		(net "M_D_CPU0_SB_DQS_DN<1>")
	)
	(segment
		(start 289.269678 -295.022016)
		(end 289.82543 -295.022016)
		(width 0.16002)
		(layer "In4.Cu")
		(net "M_D_CPU0_SB_DQS_DN<1>")
	)
	(segment
		(start 330.692506 -281.051)
		(end 330.700888 -281.046174)
		(width 0.09525)
		(layer "In4.Cu")
		(net "M_D_CPU0_SB_DQS_DN<1>")
	)
	(segment
		(start 298.664376 -294.212264)
		(end 299.064426 -293.812214)
		(width 0.16002)
		(layer "In4.Cu")
		(net "M_D_CPU0_SB_DQS_DN<1>")
	)
	(segment
		(start 293.888414 -294.662098)
		(end 296.468038 -294.662098)
		(width 0.16002)
		(layer "In4.Cu")
		(net "M_D_CPU0_SB_DQS_DN<1>")
	)
	(segment
		(start 315.763656 -286.510476)
		(end 315.584586 -286.331406)
		(width 0.16002)
		(layer "In4.Cu")
		(net "M_D_CPU0_SB_DQS_DN<1>")
	)
	(segment
		(start 314.390024 -287.884108)
		(end 314.210954 -287.705038)
		(width 0.16002)
		(layer "In4.Cu")
		(net "M_D_CPU0_SB_DQS_DN<1>")
	)
	(segment
		(start 319.884552 -282.38958)
		(end 319.705482 -282.21051)
		(width 0.16002)
		(layer "In4.Cu")
		(net "M_D_CPU0_SB_DQS_DN<1>")
	)
	(segment
		(start 326.012302 -280.719784)
		(end 326.254872 -280.962354)
		(width 0.09525)
		(layer "In4.Cu")
		(net "M_D_CPU0_SB_DQS_DN<1>")
	)
	(segment
		(start 318.984376 -283.289756)
		(end 319.51168 -283.289756)
		(width 0.16002)
		(layer "In4.Cu")
		(net "M_D_CPU0_SB_DQS_DN<1>")
	)
	(segment
		(start 321.719194 -281.082242)
		(end 324.071742 -281.082242)
		(width 0.16002)
		(layer "In4.Cu")
		(net "M_D_CPU0_SB_DQS_DN<1>")
	)
	(segment
		(start 290.676076 -294.17137)
		(end 291.260276 -294.17137)
		(width 0.16002)
		(layer "In4.Cu")
		(net "M_D_CPU0_SB_DQS_DN<1>")
	)
	(arc
		(start 336.709766 -281.051)
		(mid 336.991198 -281.126755)
		(end 337.27263 -281.051)
		(width 0.09525)
		(layer "In4.Cu")
		(net "M_D_CPU0_SB_DQS_DN<1>")
	)
	(arc
		(start 335.400904 -281.046174)
		(mid 335.585936 -281.00026)
		(end 335.769712 -281.051)
		(width 0.09525)
		(layer "In4.Cu")
		(net "M_D_CPU0_SB_DQS_DN<1>")
	)
	(arc
		(start 329.752452 -281.051)
		(mid 329.936227 -281.000228)
		(end 330.12126 -281.046174)
		(width 0.09525)
		(layer "In4.Cu")
		(net "M_D_CPU0_SB_DQS_DN<1>")
	)
	(arc
		(start 329.189588 -281.051)
		(mid 329.47102 -281.126755)
		(end 329.752452 -281.051)
		(width 0.09525)
		(layer "In4.Cu")
		(net "M_D_CPU0_SB_DQS_DN<1>")
	)
	(arc
		(start 339.06587 -281.092148)
		(mid 339.076198 -281.088188)
		(end 339.086444 -281.08402)
		(width 0.09525)
		(layer "In4.Cu")
		(net "M_D_CPU0_SB_DQS_DN<1>")
	)
	(arc
		(start 328.249788 -281.051)
		(mid 328.53122 -281.126755)
		(end 328.812652 -281.051)
		(width 0.09525)
		(layer "In4.Cu")
		(net "M_D_CPU0_SB_DQS_DN<1>")
	)
	(arc
		(start 327.88098 -281.046174)
		(mid 328.066012 -281.00026)
		(end 328.249788 -281.051)
		(width 0.09525)
		(layer "In4.Cu")
		(net "M_D_CPU0_SB_DQS_DN<1>")
	)
	(arc
		(start 326.384666 -281.059636)
		(mid 326.659871 -281.1269)
		(end 326.932798 -281.051)
		(width 0.09525)
		(layer "In4.Cu")
		(net "M_D_CPU0_SB_DQS_DN<1>")
	)
	(arc
		(start 336.340958 -281.046174)
		(mid 336.52599 -281.00026)
		(end 336.709766 -281.051)
		(width 0.09525)
		(layer "In4.Cu")
		(net "M_D_CPU0_SB_DQS_DN<1>")
	)
	(arc
		(start 333.512414 -281.051)
		(mid 333.696189 -281.000228)
		(end 333.881222 -281.046174)
		(width 0.09525)
		(layer "In4.Cu")
		(net "M_D_CPU0_SB_DQS_DN<1>")
	)
	(arc
		(start 337.649566 -281.051)
		(mid 337.930998 -281.126755)
		(end 338.21243 -281.051)
		(width 0.09525)
		(layer "In4.Cu")
		(net "M_D_CPU0_SB_DQS_DN<1>")
	)
	(arc
		(start 330.129642 -281.051)
		(mid 330.411074 -281.126755)
		(end 330.692506 -281.051)
		(width 0.09525)
		(layer "In4.Cu")
		(net "M_D_CPU0_SB_DQS_DN<1>")
	)
	(arc
		(start 337.27263 -281.051)
		(mid 337.461098 -281.000323)
		(end 337.649566 -281.051)
		(width 0.09525)
		(layer "In4.Cu")
		(net "M_D_CPU0_SB_DQS_DN<1>")
	)
	(arc
		(start 338.58962 -281.051)
		(mid 338.823134 -281.124843)
		(end 339.06587 -281.092148)
		(width 0.09525)
		(layer "In4.Cu")
		(net "M_D_CPU0_SB_DQS_DN<1>")
	)
	(arc
		(start 330.700888 -281.046174)
		(mid 330.88592 -281.00026)
		(end 331.069696 -281.051)
		(width 0.09525)
		(layer "In4.Cu")
		(net "M_D_CPU0_SB_DQS_DN<1>")
	)
	(arc
		(start 333.889604 -281.051)
		(mid 334.171036 -281.126755)
		(end 334.452468 -281.051)
		(width 0.09525)
		(layer "In4.Cu")
		(net "M_D_CPU0_SB_DQS_DN<1>")
	)
	(arc
		(start 334.452468 -281.051)
		(mid 334.636243 -281.000228)
		(end 334.821276 -281.046174)
		(width 0.09525)
		(layer "In4.Cu")
		(net "M_D_CPU0_SB_DQS_DN<1>")
	)
	(arc
		(start 332.94955 -281.051)
		(mid 333.230982 -281.126755)
		(end 333.512414 -281.051)
		(width 0.09525)
		(layer "In4.Cu")
		(net "M_D_CPU0_SB_DQS_DN<1>")
	)
	(arc
		(start 334.829658 -281.051)
		(mid 335.11109 -281.126755)
		(end 335.392522 -281.051)
		(width 0.09525)
		(layer "In4.Cu")
		(net "M_D_CPU0_SB_DQS_DN<1>")
	)
	(arc
		(start 331.640942 -281.046174)
		(mid 331.825974 -281.00026)
		(end 332.00975 -281.051)
		(width 0.09525)
		(layer "In4.Cu")
		(net "M_D_CPU0_SB_DQS_DN<1>")
	)
	(arc
		(start 326.254872 -280.962354)
		(mid 326.30952 -281.010419)
		(end 326.369934 -281.051)
		(width 0.09525)
		(layer "In4.Cu")
		(net "M_D_CPU0_SB_DQS_DN<1>")
	)
	(arc
		(start 335.769712 -281.051)
		(mid 336.051144 -281.126755)
		(end 336.332576 -281.051)
		(width 0.09525)
		(layer "In4.Cu")
		(net "M_D_CPU0_SB_DQS_DN<1>")
	)
	(arc
		(start 331.069696 -281.051)
		(mid 331.351128 -281.126755)
		(end 331.63256 -281.051)
		(width 0.09525)
		(layer "In4.Cu")
		(net "M_D_CPU0_SB_DQS_DN<1>")
	)
	(arc
		(start 338.21243 -281.051)
		(mid 338.396205 -281.000228)
		(end 338.581238 -281.046174)
		(width 0.09525)
		(layer "In4.Cu")
		(net "M_D_CPU0_SB_DQS_DN<1>")
	)
	(arc
		(start 332.00975 -281.051)
		(mid 332.291182 -281.126755)
		(end 332.572614 -281.051)
		(width 0.09525)
		(layer "In4.Cu")
		(net "M_D_CPU0_SB_DQS_DN<1>")
	)
	(arc
		(start 332.572614 -281.051)
		(mid 332.761082 -281.000323)
		(end 332.94955 -281.051)
		(width 0.09525)
		(layer "In4.Cu")
		(net "M_D_CPU0_SB_DQS_DN<1>")
	)
	(arc
		(start 326.932798 -281.051)
		(mid 327.116573 -281.000228)
		(end 327.301606 -281.046174)
		(width 0.09525)
		(layer "In4.Cu")
		(net "M_D_CPU0_SB_DQS_DN<1>")
	)
	(arc
		(start 327.309988 -281.051)
		(mid 327.585277 -281.126721)
		(end 327.862184 -281.057096)
		(width 0.09525)
		(layer "In4.Cu")
		(net "M_D_CPU0_SB_DQS_DN<1>")
	)
	(arc
		(start 328.812652 -281.051)
		(mid 329.00112 -281.000323)
		(end 329.189588 -281.051)
		(width 0.09525)
		(layer "In4.Cu")
		(net "M_D_CPU0_SB_DQS_DN<1>")
	)
	(segment
		(start 339.808058 -276.250146)
		(end 339.341206 -276.516084)
		(width 0.12954)
		(layer "F.Cu")
		(net "M_D_CPU0_SB_DQS_DN<0>")
	)
	(segment
		(start 309.292244 -283.129482)
		(end 309.398924 -283.236162)
		(width 0.16002)
		(layer "In4.Cu")
		(net "M_D_CPU0_SB_DQS_DN<0>")
	)
	(segment
		(start 310.772556 -281.86253)
		(end 311.29986 -281.86253)
		(width 0.16002)
		(layer "In4.Cu")
		(net "M_D_CPU0_SB_DQS_DN<0>")
	)
	(segment
		(start 307.282596 -284.86227)
		(end 307.641752 -284.503114)
		(width 0.16002)
		(layer "In4.Cu")
		(net "M_D_CPU0_SB_DQS_DN<0>")
	)
	(segment
		(start 323.919596 -275.45919)
		(end 323.978524 -275.400262)
		(width 0.09525)
		(layer "In4.Cu")
		(net "M_D_CPU0_SB_DQS_DN<0>")
	)
	(segment
		(start 316.685676 -275.45919)
		(end 323.895974 -275.45919)
		(width 0.16002)
		(layer "In4.Cu")
		(net "M_D_CPU0_SB_DQS_DN<0>")
	)
	(segment
		(start 311.29986 -281.86253)
		(end 311.673494 -281.488896)
		(width 0.16002)
		(layer "In4.Cu")
		(net "M_D_CPU0_SB_DQS_DN<0>")
	)
	(segment
		(start 288.924238 -285.312104)
		(end 289.261804 -285.64967)
		(width 0.16002)
		(layer "In4.Cu")
		(net "M_D_CPU0_SB_DQS_DN<0>")
	)
	(segment
		(start 291.154104 -284.86227)
		(end 291.554154 -284.46222)
		(width 0.16002)
		(layer "In4.Cu")
		(net "M_D_CPU0_SB_DQS_DN<0>")
	)
	(segment
		(start 335.392522 -276.190964)
		(end 335.400904 -276.186138)
		(width 0.09525)
		(layer "In4.Cu")
		(net "M_D_CPU0_SB_DQS_DN<0>")
	)
	(segment
		(start 315.68771 -276.457156)
		(end 316.685676 -275.45919)
		(width 0.16002)
		(layer "In4.Cu")
		(net "M_D_CPU0_SB_DQS_DN<0>")
	)
	(segment
		(start 297.208956 -285.83509)
		(end 298.181776 -284.86227)
		(width 0.16002)
		(layer "In4.Cu")
		(net "M_D_CPU0_SB_DQS_DN<0>")
	)
	(segment
		(start 339.187282 -276.250654)
		(end 339.341206 -276.516084)
		(width 0.09525)
		(layer "In4.Cu")
		(net "M_D_CPU0_SB_DQS_DN<0>")
	)
	(segment
		(start 303.326038 -285.63697)
		(end 303.719738 -286.03067)
		(width 0.16002)
		(layer "In4.Cu")
		(net "M_D_CPU0_SB_DQS_DN<0>")
	)
	(segment
		(start 314.420758 -278.214328)
		(end 314.314078 -278.107648)
		(width 0.16002)
		(layer "In4.Cu")
		(net "M_D_CPU0_SB_DQS_DN<0>")
	)
	(segment
		(start 311.566814 -280.578052)
		(end 311.762648 -280.382218)
		(width 0.16002)
		(layer "In4.Cu")
		(net "M_D_CPU0_SB_DQS_DN<0>")
	)
	(segment
		(start 314.314078 -277.830788)
		(end 314.509912 -277.634954)
		(width 0.16002)
		(layer "In4.Cu")
		(net "M_D_CPU0_SB_DQS_DN<0>")
	)
	(segment
		(start 312.940446 -279.48128)
		(end 312.940446 -279.20442)
		(width 0.16002)
		(layer "In4.Cu")
		(net "M_D_CPU0_SB_DQS_DN<0>")
	)
	(segment
		(start 310.193182 -281.951684)
		(end 310.389016 -281.75585)
		(width 0.16002)
		(layer "In4.Cu")
		(net "M_D_CPU0_SB_DQS_DN<0>")
	)
	(segment
		(start 314.047124 -279.115266)
		(end 314.420758 -278.741632)
		(width 0.16002)
		(layer "In4.Cu")
		(net "M_D_CPU0_SB_DQS_DN<0>")
	)
	(segment
		(start 289.858704 -285.64967)
		(end 290.646104 -284.86227)
		(width 0.16002)
		(layer "In4.Cu")
		(net "M_D_CPU0_SB_DQS_DN<0>")
	)
	(segment
		(start 310.193182 -282.228544)
		(end 310.193182 -281.951684)
		(width 0.16002)
		(layer "In4.Cu")
		(net "M_D_CPU0_SB_DQS_DN<0>")
	)
	(segment
		(start 287.343342 -285.312104)
		(end 288.924238 -285.312104)
		(width 0.16002)
		(layer "In4.Cu")
		(net "M_D_CPU0_SB_DQS_DN<0>")
	)
	(segment
		(start 334.821276 -276.186138)
		(end 334.829658 -276.190964)
		(width 0.09525)
		(layer "In4.Cu")
		(net "M_D_CPU0_SB_DQS_DN<0>")
	)
	(segment
		(start 284.736032 -285.735014)
		(end 285.009844 -285.461202)
		(width 0.16002)
		(layer "In4.Cu")
		(net "M_D_CPU0_SB_DQS_DN<0>")
	)
	(segment
		(start 310.389016 -281.75585)
		(end 310.665876 -281.75585)
		(width 0.16002)
		(layer "In4.Cu")
		(net "M_D_CPU0_SB_DQS_DN<0>")
	)
	(segment
		(start 308.025292 -284.609794)
		(end 308.552596 -284.609794)
		(width 0.16002)
		(layer "In4.Cu")
		(net "M_D_CPU0_SB_DQS_DN<0>")
	)
	(segment
		(start 309.398924 -283.236162)
		(end 309.926228 -283.236162)
		(width 0.16002)
		(layer "In4.Cu")
		(net "M_D_CPU0_SB_DQS_DN<0>")
	)
	(segment
		(start 338.581238 -276.186138)
		(end 338.58962 -276.190964)
		(width 0.09525)
		(layer "In4.Cu")
		(net "M_D_CPU0_SB_DQS_DN<0>")
	)
	(segment
		(start 291.554154 -284.46222)
		(end 292.519354 -284.46222)
		(width 0.16002)
		(layer "In4.Cu")
		(net "M_D_CPU0_SB_DQS_DN<0>")
	)
	(segment
		(start 325.132954 -275.400262)
		(end 325.999602 -276.26691)
		(width 0.09525)
		(layer "In4.Cu")
		(net "M_D_CPU0_SB_DQS_DN<0>")
	)
	(segment
		(start 323.895974 -275.45919)
		(end 323.919596 -275.45919)
		(width 0.09525)
		(layer "In4.Cu")
		(net "M_D_CPU0_SB_DQS_DN<0>")
	)
	(segment
		(start 314.420758 -278.741632)
		(end 314.420758 -278.214328)
		(width 0.16002)
		(layer "In4.Cu")
		(net "M_D_CPU0_SB_DQS_DN<0>")
	)
	(segment
		(start 299.064426 -284.46222)
		(end 300.164754 -284.46222)
		(width 0.16002)
		(layer "In4.Cu")
		(net "M_D_CPU0_SB_DQS_DN<0>")
	)
	(segment
		(start 311.673494 -280.961592)
		(end 311.566814 -280.854912)
		(width 0.16002)
		(layer "In4.Cu")
		(net "M_D_CPU0_SB_DQS_DN<0>")
	)
	(segment
		(start 315.79439 -277.368)
		(end 315.79439 -276.840696)
		(width 0.16002)
		(layer "In4.Cu")
		(net "M_D_CPU0_SB_DQS_DN<0>")
	)
	(segment
		(start 289.261804 -285.64967)
		(end 289.858704 -285.64967)
		(width 0.16002)
		(layer "In4.Cu")
		(net "M_D_CPU0_SB_DQS_DN<0>")
	)
	(segment
		(start 287.194244 -285.461202)
		(end 287.343342 -285.312104)
		(width 0.16002)
		(layer "In4.Cu")
		(net "M_D_CPU0_SB_DQS_DN<0>")
	)
	(segment
		(start 313.13628 -279.008586)
		(end 313.41314 -279.008586)
		(width 0.16002)
		(layer "In4.Cu")
		(net "M_D_CPU0_SB_DQS_DN<0>")
	)
	(segment
		(start 323.978524 -275.400262)
		(end 325.132954 -275.400262)
		(width 0.09525)
		(layer "In4.Cu")
		(net "M_D_CPU0_SB_DQS_DN<0>")
	)
	(segment
		(start 298.664376 -284.86227)
		(end 299.064426 -284.46222)
		(width 0.16002)
		(layer "In4.Cu")
		(net "M_D_CPU0_SB_DQS_DN<0>")
	)
	(segment
		(start 307.918612 -284.503114)
		(end 308.025292 -284.609794)
		(width 0.16002)
		(layer "In4.Cu")
		(net "M_D_CPU0_SB_DQS_DN<0>")
	)
	(segment
		(start 339.086444 -276.223984)
		(end 339.187282 -276.250654)
		(width 0.09525)
		(layer "In4.Cu")
		(net "M_D_CPU0_SB_DQS_DN<0>")
	)
	(segment
		(start 296.533824 -285.83509)
		(end 297.208956 -285.83509)
		(width 0.16002)
		(layer "In4.Cu")
		(net "M_D_CPU0_SB_DQS_DN<0>")
	)
	(segment
		(start 310.299862 -282.335224)
		(end 310.193182 -282.228544)
		(width 0.16002)
		(layer "In4.Cu")
		(net "M_D_CPU0_SB_DQS_DN<0>")
	)
	(segment
		(start 311.762648 -280.382218)
		(end 312.039508 -280.382218)
		(width 0.16002)
		(layer "In4.Cu")
		(net "M_D_CPU0_SB_DQS_DN<0>")
	)
	(segment
		(start 315.68771 -276.734016)
		(end 315.68771 -276.457156)
		(width 0.16002)
		(layer "In4.Cu")
		(net "M_D_CPU0_SB_DQS_DN<0>")
	)
	(segment
		(start 311.673494 -281.488896)
		(end 311.673494 -280.961592)
		(width 0.16002)
		(layer "In4.Cu")
		(net "M_D_CPU0_SB_DQS_DN<0>")
	)
	(segment
		(start 308.81955 -283.602176)
		(end 308.81955 -283.325316)
		(width 0.16002)
		(layer "In4.Cu")
		(net "M_D_CPU0_SB_DQS_DN<0>")
	)
	(segment
		(start 314.314078 -278.107648)
		(end 314.314078 -277.830788)
		(width 0.16002)
		(layer "In4.Cu")
		(net "M_D_CPU0_SB_DQS_DN<0>")
	)
	(segment
		(start 314.786772 -277.634954)
		(end 314.893452 -277.741634)
		(width 0.16002)
		(layer "In4.Cu")
		(net "M_D_CPU0_SB_DQS_DN<0>")
	)
	(segment
		(start 328.241406 -276.186138)
		(end 328.249788 -276.190964)
		(width 0.09525)
		(layer "In4.Cu")
		(net "M_D_CPU0_SB_DQS_DN<0>")
	)
	(segment
		(start 333.881222 -276.186138)
		(end 333.889604 -276.190964)
		(width 0.09525)
		(layer "In4.Cu")
		(net "M_D_CPU0_SB_DQS_DN<0>")
	)
	(segment
		(start 293.369238 -285.312104)
		(end 296.010838 -285.312104)
		(width 0.16002)
		(layer "In4.Cu")
		(net "M_D_CPU0_SB_DQS_DN<0>")
	)
	(segment
		(start 304.557176 -286.03067)
		(end 305.725576 -284.86227)
		(width 0.16002)
		(layer "In4.Cu")
		(net "M_D_CPU0_SB_DQS_DN<0>")
	)
	(segment
		(start 309.926228 -283.236162)
		(end 310.299862 -282.862528)
		(width 0.16002)
		(layer "In4.Cu")
		(net "M_D_CPU0_SB_DQS_DN<0>")
	)
	(segment
		(start 312.673492 -280.488898)
		(end 313.047126 -280.115264)
		(width 0.16002)
		(layer "In4.Cu")
		(net "M_D_CPU0_SB_DQS_DN<0>")
	)
	(segment
		(start 315.420756 -277.741634)
		(end 315.79439 -277.368)
		(width 0.16002)
		(layer "In4.Cu")
		(net "M_D_CPU0_SB_DQS_DN<0>")
	)
	(segment
		(start 312.146188 -280.488898)
		(end 312.673492 -280.488898)
		(width 0.16002)
		(layer "In4.Cu")
		(net "M_D_CPU0_SB_DQS_DN<0>")
	)
	(segment
		(start 313.51982 -279.115266)
		(end 314.047124 -279.115266)
		(width 0.16002)
		(layer "In4.Cu")
		(net "M_D_CPU0_SB_DQS_DN<0>")
	)
	(segment
		(start 312.940446 -279.20442)
		(end 313.13628 -279.008586)
		(width 0.16002)
		(layer "In4.Cu")
		(net "M_D_CPU0_SB_DQS_DN<0>")
	)
	(segment
		(start 310.665876 -281.75585)
		(end 310.772556 -281.86253)
		(width 0.16002)
		(layer "In4.Cu")
		(net "M_D_CPU0_SB_DQS_DN<0>")
	)
	(segment
		(start 331.63256 -276.190964)
		(end 331.640942 -276.186138)
		(width 0.09525)
		(layer "In4.Cu")
		(net "M_D_CPU0_SB_DQS_DN<0>")
	)
	(segment
		(start 300.164754 -284.46222)
		(end 301.339504 -285.63697)
		(width 0.16002)
		(layer "In4.Cu")
		(net "M_D_CPU0_SB_DQS_DN<0>")
	)
	(segment
		(start 301.339504 -285.63697)
		(end 303.326038 -285.63697)
		(width 0.16002)
		(layer "In4.Cu")
		(net "M_D_CPU0_SB_DQS_DN<0>")
	)
	(segment
		(start 307.641752 -284.503114)
		(end 307.918612 -284.503114)
		(width 0.16002)
		(layer "In4.Cu")
		(net "M_D_CPU0_SB_DQS_DN<0>")
	)
	(segment
		(start 308.92623 -284.23616)
		(end 308.92623 -283.708856)
		(width 0.16002)
		(layer "In4.Cu")
		(net "M_D_CPU0_SB_DQS_DN<0>")
	)
	(segment
		(start 308.552596 -284.609794)
		(end 308.92623 -284.23616)
		(width 0.16002)
		(layer "In4.Cu")
		(net "M_D_CPU0_SB_DQS_DN<0>")
	)
	(segment
		(start 311.566814 -280.854912)
		(end 311.566814 -280.578052)
		(width 0.16002)
		(layer "In4.Cu")
		(net "M_D_CPU0_SB_DQS_DN<0>")
	)
	(segment
		(start 313.047126 -279.58796)
		(end 312.940446 -279.48128)
		(width 0.16002)
		(layer "In4.Cu")
		(net "M_D_CPU0_SB_DQS_DN<0>")
	)
	(segment
		(start 310.299862 -282.862528)
		(end 310.299862 -282.335224)
		(width 0.16002)
		(layer "In4.Cu")
		(net "M_D_CPU0_SB_DQS_DN<0>")
	)
	(segment
		(start 330.12126 -276.186138)
		(end 330.129642 -276.190964)
		(width 0.09525)
		(layer "In4.Cu")
		(net "M_D_CPU0_SB_DQS_DN<0>")
	)
	(segment
		(start 308.81955 -283.325316)
		(end 309.015384 -283.129482)
		(width 0.16002)
		(layer "In4.Cu")
		(net "M_D_CPU0_SB_DQS_DN<0>")
	)
	(segment
		(start 308.92623 -283.708856)
		(end 308.81955 -283.602176)
		(width 0.16002)
		(layer "In4.Cu")
		(net "M_D_CPU0_SB_DQS_DN<0>")
	)
	(segment
		(start 314.509912 -277.634954)
		(end 314.786772 -277.634954)
		(width 0.16002)
		(layer "In4.Cu")
		(net "M_D_CPU0_SB_DQS_DN<0>")
	)
	(segment
		(start 309.015384 -283.129482)
		(end 309.292244 -283.129482)
		(width 0.16002)
		(layer "In4.Cu")
		(net "M_D_CPU0_SB_DQS_DN<0>")
	)
	(segment
		(start 325.999602 -276.26691)
		(end 327.590404 -276.26691)
		(width 0.09525)
		(layer "In4.Cu")
		(net "M_D_CPU0_SB_DQS_DN<0>")
	)
	(segment
		(start 313.41314 -279.008586)
		(end 313.51982 -279.115266)
		(width 0.16002)
		(layer "In4.Cu")
		(net "M_D_CPU0_SB_DQS_DN<0>")
	)
	(segment
		(start 303.719738 -286.03067)
		(end 304.557176 -286.03067)
		(width 0.16002)
		(layer "In4.Cu")
		(net "M_D_CPU0_SB_DQS_DN<0>")
	)
	(segment
		(start 314.893452 -277.741634)
		(end 315.420756 -277.741634)
		(width 0.16002)
		(layer "In4.Cu")
		(net "M_D_CPU0_SB_DQS_DN<0>")
	)
	(segment
		(start 296.010838 -285.312104)
		(end 296.533824 -285.83509)
		(width 0.16002)
		(layer "In4.Cu")
		(net "M_D_CPU0_SB_DQS_DN<0>")
	)
	(segment
		(start 313.047126 -280.115264)
		(end 313.047126 -279.58796)
		(width 0.16002)
		(layer "In4.Cu")
		(net "M_D_CPU0_SB_DQS_DN<0>")
	)
	(segment
		(start 336.332576 -276.190964)
		(end 336.340958 -276.186138)
		(width 0.09525)
		(layer "In4.Cu")
		(net "M_D_CPU0_SB_DQS_DN<0>")
	)
	(segment
		(start 330.692506 -276.190964)
		(end 330.700888 -276.186138)
		(width 0.09525)
		(layer "In4.Cu")
		(net "M_D_CPU0_SB_DQS_DN<0>")
	)
	(segment
		(start 312.039508 -280.382218)
		(end 312.146188 -280.488898)
		(width 0.16002)
		(layer "In4.Cu")
		(net "M_D_CPU0_SB_DQS_DN<0>")
	)
	(segment
		(start 298.181776 -284.86227)
		(end 298.664376 -284.86227)
		(width 0.16002)
		(layer "In4.Cu")
		(net "M_D_CPU0_SB_DQS_DN<0>")
	)
	(segment
		(start 292.519354 -284.46222)
		(end 293.369238 -285.312104)
		(width 0.16002)
		(layer "In4.Cu")
		(net "M_D_CPU0_SB_DQS_DN<0>")
	)
	(segment
		(start 290.646104 -284.86227)
		(end 291.154104 -284.86227)
		(width 0.16002)
		(layer "In4.Cu")
		(net "M_D_CPU0_SB_DQS_DN<0>")
	)
	(segment
		(start 315.79439 -276.840696)
		(end 315.68771 -276.734016)
		(width 0.16002)
		(layer "In4.Cu")
		(net "M_D_CPU0_SB_DQS_DN<0>")
	)
	(segment
		(start 285.009844 -285.461202)
		(end 287.194244 -285.461202)
		(width 0.16002)
		(layer "In4.Cu")
		(net "M_D_CPU0_SB_DQS_DN<0>")
	)
	(segment
		(start 305.725576 -284.86227)
		(end 307.282596 -284.86227)
		(width 0.16002)
		(layer "In4.Cu")
		(net "M_D_CPU0_SB_DQS_DN<0>")
	)
	(arc
		(start 332.94955 -276.190964)
		(mid 332.955878 -276.19456)
		(end 332.96225 -276.198076)
		(width 0.09525)
		(layer "In4.Cu")
		(net "M_D_CPU0_SB_DQS_DN<0>")
	)
	(arc
		(start 332.00975 -276.190964)
		(mid 332.291182 -276.266719)
		(end 332.572614 -276.190964)
		(width 0.09525)
		(layer "In4.Cu")
		(net "M_D_CPU0_SB_DQS_DN<0>")
	)
	(arc
		(start 332.96225 -276.198076)
		(mid 333.23826 -276.266637)
		(end 333.512414 -276.190964)
		(width 0.09525)
		(layer "In4.Cu")
		(net "M_D_CPU0_SB_DQS_DN<0>")
	)
	(arc
		(start 330.700888 -276.186138)
		(mid 330.88592 -276.140224)
		(end 331.069696 -276.190964)
		(width 0.09525)
		(layer "In4.Cu")
		(net "M_D_CPU0_SB_DQS_DN<0>")
	)
	(arc
		(start 335.769712 -276.190964)
		(mid 336.051144 -276.266719)
		(end 336.332576 -276.190964)
		(width 0.09525)
		(layer "In4.Cu")
		(net "M_D_CPU0_SB_DQS_DN<0>")
	)
	(arc
		(start 337.649566 -276.190964)
		(mid 337.655894 -276.19456)
		(end 337.662266 -276.198076)
		(width 0.09525)
		(layer "In4.Cu")
		(net "M_D_CPU0_SB_DQS_DN<0>")
	)
	(arc
		(start 336.340958 -276.186138)
		(mid 336.52599 -276.140224)
		(end 336.709766 -276.190964)
		(width 0.09525)
		(layer "In4.Cu")
		(net "M_D_CPU0_SB_DQS_DN<0>")
	)
	(arc
		(start 329.189588 -276.190964)
		(mid 329.196041 -276.194564)
		(end 329.202542 -276.198076)
		(width 0.09525)
		(layer "In4.Cu")
		(net "M_D_CPU0_SB_DQS_DN<0>")
	)
	(arc
		(start 333.512414 -276.190964)
		(mid 333.696189 -276.140192)
		(end 333.881222 -276.186138)
		(width 0.09525)
		(layer "In4.Cu")
		(net "M_D_CPU0_SB_DQS_DN<0>")
	)
	(arc
		(start 336.709766 -276.190964)
		(mid 336.991198 -276.266719)
		(end 337.27263 -276.190964)
		(width 0.09525)
		(layer "In4.Cu")
		(net "M_D_CPU0_SB_DQS_DN<0>")
	)
	(arc
		(start 327.87209 -276.190964)
		(mid 328.056119 -276.140065)
		(end 328.241406 -276.186138)
		(width 0.09525)
		(layer "In4.Cu")
		(net "M_D_CPU0_SB_DQS_DN<0>")
	)
	(arc
		(start 338.58962 -276.190964)
		(mid 338.823134 -276.264807)
		(end 339.06587 -276.232112)
		(width 0.09525)
		(layer "In4.Cu")
		(net "M_D_CPU0_SB_DQS_DN<0>")
	)
	(arc
		(start 338.21243 -276.190964)
		(mid 338.396205 -276.140192)
		(end 338.581238 -276.186138)
		(width 0.09525)
		(layer "In4.Cu")
		(net "M_D_CPU0_SB_DQS_DN<0>")
	)
	(arc
		(start 331.069696 -276.190964)
		(mid 331.351128 -276.266719)
		(end 331.63256 -276.190964)
		(width 0.09525)
		(layer "In4.Cu")
		(net "M_D_CPU0_SB_DQS_DN<0>")
	)
	(arc
		(start 329.752452 -276.190964)
		(mid 329.936227 -276.140192)
		(end 330.12126 -276.186138)
		(width 0.09525)
		(layer "In4.Cu")
		(net "M_D_CPU0_SB_DQS_DN<0>")
	)
	(arc
		(start 328.249788 -276.190964)
		(mid 328.53122 -276.266719)
		(end 328.812652 -276.190964)
		(width 0.09525)
		(layer "In4.Cu")
		(net "M_D_CPU0_SB_DQS_DN<0>")
	)
	(arc
		(start 334.452468 -276.190964)
		(mid 334.636243 -276.140192)
		(end 334.821276 -276.186138)
		(width 0.09525)
		(layer "In4.Cu")
		(net "M_D_CPU0_SB_DQS_DN<0>")
	)
	(arc
		(start 333.889604 -276.190964)
		(mid 333.896057 -276.194564)
		(end 333.902558 -276.198076)
		(width 0.09525)
		(layer "In4.Cu")
		(net "M_D_CPU0_SB_DQS_DN<0>")
	)
	(arc
		(start 339.06587 -276.232112)
		(mid 339.076198 -276.228152)
		(end 339.086444 -276.223984)
		(width 0.09525)
		(layer "In4.Cu")
		(net "M_D_CPU0_SB_DQS_DN<0>")
	)
	(arc
		(start 328.812652 -276.190964)
		(mid 329.00112 -276.140287)
		(end 329.189588 -276.190964)
		(width 0.09525)
		(layer "In4.Cu")
		(net "M_D_CPU0_SB_DQS_DN<0>")
	)
	(arc
		(start 337.662266 -276.198076)
		(mid 337.938276 -276.266637)
		(end 338.21243 -276.190964)
		(width 0.09525)
		(layer "In4.Cu")
		(net "M_D_CPU0_SB_DQS_DN<0>")
	)
	(arc
		(start 334.829658 -276.190964)
		(mid 335.11109 -276.266719)
		(end 335.392522 -276.190964)
		(width 0.09525)
		(layer "In4.Cu")
		(net "M_D_CPU0_SB_DQS_DN<0>")
	)
	(arc
		(start 330.129642 -276.190964)
		(mid 330.411074 -276.266719)
		(end 330.692506 -276.190964)
		(width 0.09525)
		(layer "In4.Cu")
		(net "M_D_CPU0_SB_DQS_DN<0>")
	)
	(arc
		(start 331.640942 -276.186138)
		(mid 331.825974 -276.140224)
		(end 332.00975 -276.190964)
		(width 0.09525)
		(layer "In4.Cu")
		(net "M_D_CPU0_SB_DQS_DN<0>")
	)
	(arc
		(start 329.202542 -276.198076)
		(mid 329.478442 -276.266638)
		(end 329.752452 -276.190964)
		(width 0.09525)
		(layer "In4.Cu")
		(net "M_D_CPU0_SB_DQS_DN<0>")
	)
	(arc
		(start 335.400904 -276.186138)
		(mid 335.585936 -276.140224)
		(end 335.769712 -276.190964)
		(width 0.09525)
		(layer "In4.Cu")
		(net "M_D_CPU0_SB_DQS_DN<0>")
	)
	(arc
		(start 332.572614 -276.190964)
		(mid 332.761082 -276.140287)
		(end 332.94955 -276.190964)
		(width 0.09525)
		(layer "In4.Cu")
		(net "M_D_CPU0_SB_DQS_DN<0>")
	)
	(arc
		(start 327.590404 -276.26691)
		(mid 327.736264 -276.247551)
		(end 327.87209 -276.190964)
		(width 0.09525)
		(layer "In4.Cu")
		(net "M_D_CPU0_SB_DQS_DN<0>")
	)
	(arc
		(start 337.27263 -276.190964)
		(mid 337.461098 -276.140287)
		(end 337.649566 -276.190964)
		(width 0.09525)
		(layer "In4.Cu")
		(net "M_D_CPU0_SB_DQS_DN<0>")
	)
	(arc
		(start 333.902558 -276.198076)
		(mid 334.178458 -276.266638)
		(end 334.452468 -276.190964)
		(width 0.09525)
		(layer "In4.Cu")
		(net "M_D_CPU0_SB_DQS_DN<0>")
	)
	(segment
		(start 340.747858 -279.49017)
		(end 340.281006 -279.756108)
		(width 0.10668)
		(layer "F.Cu")
		(net "M_D_CPU0_SB_DQ<9>")
	)
	(segment
		(start 294.29964 -293.097204)
		(end 294.436546 -293.23411)
		(width 0.14478)
		(layer "In4.Cu")
		(net "M_D_CPU0_SB_DQ<9>")
	)
	(segment
		(start 298.736258 -291.948108)
		(end 298.736258 -292.271704)
		(width 0.14478)
		(layer "In4.Cu")
		(net "M_D_CPU0_SB_DQ<9>")
	)
	(segment
		(start 299.454316 -292.109906)
		(end 300.05528 -292.109906)
		(width 0.14478)
		(layer "In4.Cu")
		(net "M_D_CPU0_SB_DQ<9>")
	)
	(segment
		(start 311.40273 -289.020504)
		(end 311.63133 -289.020504)
		(width 0.14478)
		(layer "In4.Cu")
		(net "M_D_CPU0_SB_DQ<9>")
	)
	(segment
		(start 286.009588 -293.172896)
		(end 286.009588 -292.747192)
		(width 0.14478)
		(layer "In4.Cu")
		(net "M_D_CPU0_SB_DQ<9>")
	)
	(segment
		(start 302.342296 -292.960044)
		(end 304.6857 -292.960044)
		(width 0.14478)
		(layer "In4.Cu")
		(net "M_D_CPU0_SB_DQ<9>")
	)
	(segment
		(start 306.788566 -292.109906)
		(end 308.541928 -292.109906)
		(width 0.14478)
		(layer "In4.Cu")
		(net "M_D_CPU0_SB_DQ<9>")
	)
	(segment
		(start 289.809174 -292.960044)
		(end 290.659312 -292.109906)
		(width 0.14478)
		(layer "In4.Cu")
		(net "M_D_CPU0_SB_DQ<9>")
	)
	(segment
		(start 300.05528 -292.109906)
		(end 300.378876 -292.433502)
		(width 0.14478)
		(layer "In4.Cu")
		(net "M_D_CPU0_SB_DQ<9>")
	)
	(segment
		(start 310.771032 -289.169094)
		(end 310.771032 -288.989262)
		(width 0.14478)
		(layer "In4.Cu")
		(net "M_D_CPU0_SB_DQ<9>")
	)
	(segment
		(start 298.898056 -292.433502)
		(end 299.13072 -292.433502)
		(width 0.14478)
		(layer "In4.Cu")
		(net "M_D_CPU0_SB_DQ<9>")
	)
	(segment
		(start 300.773338 -292.271704)
		(end 300.773338 -291.948108)
		(width 0.14478)
		(layer "In4.Cu")
		(net "M_D_CPU0_SB_DQ<9>")
	)
	(segment
		(start 293.312596 -292.109906)
		(end 294.29964 -293.09695)
		(width 0.14478)
		(layer "In4.Cu")
		(net "M_D_CPU0_SB_DQ<9>")
	)
	(segment
		(start 312.900314 -286.884872)
		(end 320.032126 -279.75306)
		(width 0.14478)
		(layer "In4.Cu")
		(net "M_D_CPU0_SB_DQ<9>")
	)
	(segment
		(start 340.435184 -280.021538)
		(end 340.281006 -279.756108)
		(width 0.0889)
		(layer "In4.Cu")
		(net "M_D_CPU0_SB_DQ<9>")
	)
	(segment
		(start 295.41216 -292.823138)
		(end 295.549066 -292.960044)
		(width 0.14478)
		(layer "In4.Cu")
		(net "M_D_CPU0_SB_DQ<9>")
	)
	(segment
		(start 286.172402 -292.584378)
		(end 286.403034 -292.584378)
		(width 0.14478)
		(layer "In4.Cu")
		(net "M_D_CPU0_SB_DQ<9>")
	)
	(segment
		(start 285.53664 -293.33571)
		(end 285.846774 -293.33571)
		(width 0.14478)
		(layer "In4.Cu")
		(net "M_D_CPU0_SB_DQ<9>")
	)
	(segment
		(start 305.971702 -292.109906)
		(end 306.232306 -292.37051)
		(width 0.14478)
		(layer "In4.Cu")
		(net "M_D_CPU0_SB_DQ<9>")
	)
	(segment
		(start 294.8559 -293.097204)
		(end 294.8559 -292.822884)
		(width 0.14478)
		(layer "In4.Cu")
		(net "M_D_CPU0_SB_DQ<9>")
	)
	(segment
		(start 300.935136 -291.78631)
		(end 301.1678 -291.78631)
		(width 0.14478)
		(layer "In4.Cu")
		(net "M_D_CPU0_SB_DQ<9>")
	)
	(segment
		(start 311.161176 -288.77895)
		(end 311.40273 -289.020504)
		(width 0.14478)
		(layer "In4.Cu")
		(net "M_D_CPU0_SB_DQ<9>")
	)
	(segment
		(start 335.394046 -280.078688)
		(end 335.402428 -280.083514)
		(width 0.0889)
		(layer "In4.Cu")
		(net "M_D_CPU0_SB_DQ<9>")
	)
	(segment
		(start 336.3341 -280.078688)
		(end 336.342482 -280.083514)
		(width 0.0889)
		(layer "In4.Cu")
		(net "M_D_CPU0_SB_DQ<9>")
	)
	(segment
		(start 324.588378 -279.920192)
		(end 327.285858 -279.920192)
		(width 0.0889)
		(layer "In4.Cu")
		(net "M_D_CPU0_SB_DQ<9>")
	)
	(segment
		(start 294.992806 -292.685978)
		(end 295.275254 -292.685978)
		(width 0.14478)
		(layer "In4.Cu")
		(net "M_D_CPU0_SB_DQ<9>")
	)
	(segment
		(start 286.7787 -292.960044)
		(end 289.809174 -292.960044)
		(width 0.14478)
		(layer "In4.Cu")
		(net "M_D_CPU0_SB_DQ<9>")
	)
	(segment
		(start 328.239882 -280.083514)
		(end 328.248264 -280.078688)
		(width 0.0889)
		(layer "In4.Cu")
		(net "M_D_CPU0_SB_DQ<9>")
	)
	(segment
		(start 311.012586 -289.410648)
		(end 310.771032 -289.169094)
		(width 0.14478)
		(layer "In4.Cu")
		(net "M_D_CPU0_SB_DQ<9>")
	)
	(segment
		(start 324.421246 -279.75306)
		(end 324.588378 -279.920192)
		(width 0.0889)
		(layer "In4.Cu")
		(net "M_D_CPU0_SB_DQ<9>")
	)
	(segment
		(start 300.773338 -291.948108)
		(end 300.935136 -291.78631)
		(width 0.14478)
		(layer "In4.Cu")
		(net "M_D_CPU0_SB_DQ<9>")
	)
	(segment
		(start 301.1678 -291.78631)
		(end 302.342042 -292.960298)
		(width 0.14478)
		(layer "In4.Cu")
		(net "M_D_CPU0_SB_DQ<9>")
	)
	(segment
		(start 286.009588 -292.747192)
		(end 286.172402 -292.584378)
		(width 0.14478)
		(layer "In4.Cu")
		(net "M_D_CPU0_SB_DQ<9>")
	)
	(segment
		(start 333.879698 -280.083514)
		(end 333.88808 -280.078688)
		(width 0.0889)
		(layer "In4.Cu")
		(net "M_D_CPU0_SB_DQ<9>")
	)
	(segment
		(start 311.012586 -289.639248)
		(end 311.012586 -289.410648)
		(width 0.14478)
		(layer "In4.Cu")
		(net "M_D_CPU0_SB_DQ<9>")
	)
	(segment
		(start 331.634084 -280.078688)
		(end 331.642466 -280.083514)
		(width 0.0889)
		(layer "In4.Cu")
		(net "M_D_CPU0_SB_DQ<9>")
	)
	(segment
		(start 294.29964 -293.09695)
		(end 294.29964 -293.097204)
		(width 0.14478)
		(layer "In4.Cu")
		(net "M_D_CPU0_SB_DQ<9>")
	)
	(segment
		(start 308.541928 -292.109906)
		(end 311.012586 -289.639248)
		(width 0.14478)
		(layer "In4.Cu")
		(net "M_D_CPU0_SB_DQ<9>")
	)
	(segment
		(start 306.527962 -292.37051)
		(end 306.788566 -292.109906)
		(width 0.14478)
		(layer "In4.Cu")
		(net "M_D_CPU0_SB_DQ<9>")
	)
	(segment
		(start 339.519768 -280.083514)
		(end 339.52815 -280.078688)
		(width 0.0889)
		(layer "In4.Cu")
		(net "M_D_CPU0_SB_DQ<9>")
	)
	(segment
		(start 310.981344 -288.77895)
		(end 311.161176 -288.77895)
		(width 0.14478)
		(layer "In4.Cu")
		(net "M_D_CPU0_SB_DQ<9>")
	)
	(segment
		(start 295.549066 -292.960044)
		(end 297.168062 -292.960044)
		(width 0.14478)
		(layer "In4.Cu")
		(net "M_D_CPU0_SB_DQ<9>")
	)
	(segment
		(start 330.119736 -280.083514)
		(end 330.128118 -280.078688)
		(width 0.0889)
		(layer "In4.Cu")
		(net "M_D_CPU0_SB_DQ<9>")
	)
	(segment
		(start 295.275254 -292.685978)
		(end 295.41216 -292.822884)
		(width 0.14478)
		(layer "In4.Cu")
		(net "M_D_CPU0_SB_DQ<9>")
	)
	(segment
		(start 286.403034 -292.584378)
		(end 286.7787 -292.960044)
		(width 0.14478)
		(layer "In4.Cu")
		(net "M_D_CPU0_SB_DQ<9>")
	)
	(segment
		(start 304.6857 -292.960044)
		(end 304.685954 -292.960298)
		(width 0.14478)
		(layer "In4.Cu")
		(net "M_D_CPU0_SB_DQ<9>")
	)
	(segment
		(start 340.094062 -280.078688)
		(end 340.102444 -280.083514)
		(width 0.0889)
		(layer "In4.Cu")
		(net "M_D_CPU0_SB_DQ<9>")
	)
	(segment
		(start 320.032126 -279.75306)
		(end 324.26783 -279.75306)
		(width 0.14478)
		(layer "In4.Cu")
		(net "M_D_CPU0_SB_DQ<9>")
	)
	(segment
		(start 338.579714 -280.083514)
		(end 338.588096 -280.078688)
		(width 0.0889)
		(layer "In4.Cu")
		(net "M_D_CPU0_SB_DQ<9>")
	)
	(segment
		(start 294.436546 -293.23411)
		(end 294.718994 -293.23411)
		(width 0.14478)
		(layer "In4.Cu")
		(net "M_D_CPU0_SB_DQ<9>")
	)
	(segment
		(start 294.718994 -293.23411)
		(end 294.8559 -293.097204)
		(width 0.14478)
		(layer "In4.Cu")
		(net "M_D_CPU0_SB_DQ<9>")
	)
	(segment
		(start 334.819752 -280.083514)
		(end 334.828134 -280.078688)
		(width 0.0889)
		(layer "In4.Cu")
		(net "M_D_CPU0_SB_DQ<9>")
	)
	(segment
		(start 312.900314 -287.75152)
		(end 312.900314 -286.884872)
		(width 0.14478)
		(layer "In4.Cu")
		(net "M_D_CPU0_SB_DQ<9>")
	)
	(segment
		(start 300.61154 -292.433502)
		(end 300.773338 -292.271704)
		(width 0.14478)
		(layer "In4.Cu")
		(net "M_D_CPU0_SB_DQ<9>")
	)
	(segment
		(start 324.26783 -279.75306)
		(end 324.421246 -279.75306)
		(width 0.0889)
		(layer "In4.Cu")
		(net "M_D_CPU0_SB_DQ<9>")
	)
	(segment
		(start 340.412832 -280.10485)
		(end 340.435184 -280.021538)
		(width 0.0889)
		(layer "In4.Cu")
		(net "M_D_CPU0_SB_DQ<9>")
	)
	(segment
		(start 294.8559 -292.822884)
		(end 294.992806 -292.685978)
		(width 0.14478)
		(layer "In4.Cu")
		(net "M_D_CPU0_SB_DQ<9>")
	)
	(segment
		(start 290.659312 -292.109906)
		(end 293.312596 -292.109906)
		(width 0.14478)
		(layer "In4.Cu")
		(net "M_D_CPU0_SB_DQ<9>")
	)
	(segment
		(start 299.13072 -292.433502)
		(end 299.454316 -292.109906)
		(width 0.14478)
		(layer "In4.Cu")
		(net "M_D_CPU0_SB_DQ<9>")
	)
	(segment
		(start 298.736258 -292.271704)
		(end 298.898056 -292.433502)
		(width 0.14478)
		(layer "In4.Cu")
		(net "M_D_CPU0_SB_DQ<9>")
	)
	(segment
		(start 311.63133 -289.020504)
		(end 312.900314 -287.75152)
		(width 0.14478)
		(layer "In4.Cu")
		(net "M_D_CPU0_SB_DQ<9>")
	)
	(segment
		(start 284.736032 -292.535102)
		(end 285.53664 -293.33571)
		(width 0.14478)
		(layer "In4.Cu")
		(net "M_D_CPU0_SB_DQ<9>")
	)
	(segment
		(start 297.168062 -292.960044)
		(end 298.341796 -291.78631)
		(width 0.14478)
		(layer "In4.Cu")
		(net "M_D_CPU0_SB_DQ<9>")
	)
	(segment
		(start 330.69403 -280.078688)
		(end 330.702412 -280.083514)
		(width 0.0889)
		(layer "In4.Cu")
		(net "M_D_CPU0_SB_DQ<9>")
	)
	(segment
		(start 304.685954 -292.960298)
		(end 305.5366 -292.109906)
		(width 0.14478)
		(layer "In4.Cu")
		(net "M_D_CPU0_SB_DQ<9>")
	)
	(segment
		(start 300.378876 -292.433502)
		(end 300.61154 -292.433502)
		(width 0.14478)
		(layer "In4.Cu")
		(net "M_D_CPU0_SB_DQ<9>")
	)
	(segment
		(start 305.5366 -292.109906)
		(end 305.971702 -292.109906)
		(width 0.14478)
		(layer "In4.Cu")
		(net "M_D_CPU0_SB_DQ<9>")
	)
	(segment
		(start 298.341796 -291.78631)
		(end 298.57446 -291.78631)
		(width 0.14478)
		(layer "In4.Cu")
		(net "M_D_CPU0_SB_DQ<9>")
	)
	(segment
		(start 306.232306 -292.37051)
		(end 306.527962 -292.37051)
		(width 0.14478)
		(layer "In4.Cu")
		(net "M_D_CPU0_SB_DQ<9>")
	)
	(segment
		(start 302.342042 -292.960298)
		(end 302.342296 -292.960044)
		(width 0.14478)
		(layer "In4.Cu")
		(net "M_D_CPU0_SB_DQ<9>")
	)
	(segment
		(start 298.57446 -291.78631)
		(end 298.736258 -291.948108)
		(width 0.14478)
		(layer "In4.Cu")
		(net "M_D_CPU0_SB_DQ<9>")
	)
	(segment
		(start 295.41216 -292.822884)
		(end 295.41216 -292.823138)
		(width 0.14478)
		(layer "In4.Cu")
		(net "M_D_CPU0_SB_DQ<9>")
	)
	(segment
		(start 310.771032 -288.989262)
		(end 310.981344 -288.77895)
		(width 0.14478)
		(layer "In4.Cu")
		(net "M_D_CPU0_SB_DQ<9>")
	)
	(segment
		(start 285.846774 -293.33571)
		(end 286.009588 -293.172896)
		(width 0.14478)
		(layer "In4.Cu")
		(net "M_D_CPU0_SB_DQ<9>")
	)
	(arc
		(start 329.188064 -280.078688)
		(mid 329.47102 -280.002511)
		(end 329.753976 -280.078688)
		(width 0.0889)
		(layer "In4.Cu")
		(net "M_D_CPU0_SB_DQ<9>")
	)
	(arc
		(start 328.248264 -280.078688)
		(mid 328.53122 -280.002511)
		(end 328.814176 -280.078688)
		(width 0.0889)
		(layer "In4.Cu")
		(net "M_D_CPU0_SB_DQ<9>")
	)
	(arc
		(start 338.213954 -280.078688)
		(mid 338.396205 -280.129038)
		(end 338.579714 -280.083514)
		(width 0.0889)
		(layer "In4.Cu")
		(net "M_D_CPU0_SB_DQ<9>")
	)
	(arc
		(start 333.513938 -280.078688)
		(mid 333.696189 -280.129038)
		(end 333.879698 -280.083514)
		(width 0.0889)
		(layer "In4.Cu")
		(net "M_D_CPU0_SB_DQ<9>")
	)
	(arc
		(start 334.453992 -280.078688)
		(mid 334.636243 -280.129038)
		(end 334.819752 -280.083514)
		(width 0.0889)
		(layer "In4.Cu")
		(net "M_D_CPU0_SB_DQ<9>")
	)
	(arc
		(start 336.708242 -280.078688)
		(mid 336.991198 -280.002511)
		(end 337.274154 -280.078688)
		(width 0.0889)
		(layer "In4.Cu")
		(net "M_D_CPU0_SB_DQ<9>")
	)
	(arc
		(start 333.88808 -280.078688)
		(mid 334.171036 -280.002511)
		(end 334.453992 -280.078688)
		(width 0.0889)
		(layer "In4.Cu")
		(net "M_D_CPU0_SB_DQ<9>")
	)
	(arc
		(start 335.402428 -280.083514)
		(mid 335.585936 -280.129008)
		(end 335.768188 -280.078688)
		(width 0.0889)
		(layer "In4.Cu")
		(net "M_D_CPU0_SB_DQ<9>")
	)
	(arc
		(start 328.814176 -280.078688)
		(mid 329.00112 -280.128943)
		(end 329.188064 -280.078688)
		(width 0.0889)
		(layer "In4.Cu")
		(net "M_D_CPU0_SB_DQ<9>")
	)
	(arc
		(start 332.948026 -280.078688)
		(mid 333.230982 -280.002511)
		(end 333.513938 -280.078688)
		(width 0.0889)
		(layer "In4.Cu")
		(net "M_D_CPU0_SB_DQ<9>")
	)
	(arc
		(start 338.588096 -280.078688)
		(mid 338.871052 -280.002511)
		(end 339.154008 -280.078688)
		(width 0.0889)
		(layer "In4.Cu")
		(net "M_D_CPU0_SB_DQ<9>")
	)
	(arc
		(start 327.285858 -279.920192)
		(mid 327.590236 -279.960508)
		(end 327.873614 -280.078688)
		(width 0.0889)
		(layer "In4.Cu")
		(net "M_D_CPU0_SB_DQ<9>")
	)
	(arc
		(start 339.52815 -280.078688)
		(mid 339.811106 -280.002511)
		(end 340.094062 -280.078688)
		(width 0.0889)
		(layer "In4.Cu")
		(net "M_D_CPU0_SB_DQ<9>")
	)
	(arc
		(start 332.008226 -280.078688)
		(mid 332.291182 -280.002511)
		(end 332.574138 -280.078688)
		(width 0.0889)
		(layer "In4.Cu")
		(net "M_D_CPU0_SB_DQ<9>")
	)
	(arc
		(start 334.828134 -280.078688)
		(mid 335.11109 -280.002511)
		(end 335.394046 -280.078688)
		(width 0.0889)
		(layer "In4.Cu")
		(net "M_D_CPU0_SB_DQ<9>")
	)
	(arc
		(start 339.154008 -280.078688)
		(mid 339.336259 -280.129038)
		(end 339.519768 -280.083514)
		(width 0.0889)
		(layer "In4.Cu")
		(net "M_D_CPU0_SB_DQ<9>")
	)
	(arc
		(start 340.102444 -280.083514)
		(mid 340.255314 -280.128155)
		(end 340.412832 -280.10485)
		(width 0.0889)
		(layer "In4.Cu")
		(net "M_D_CPU0_SB_DQ<9>")
	)
	(arc
		(start 331.642466 -280.083514)
		(mid 331.825974 -280.129008)
		(end 332.008226 -280.078688)
		(width 0.0889)
		(layer "In4.Cu")
		(net "M_D_CPU0_SB_DQ<9>")
	)
	(arc
		(start 336.342482 -280.083514)
		(mid 336.52599 -280.129008)
		(end 336.708242 -280.078688)
		(width 0.0889)
		(layer "In4.Cu")
		(net "M_D_CPU0_SB_DQ<9>")
	)
	(arc
		(start 330.702412 -280.083514)
		(mid 330.88592 -280.129008)
		(end 331.068172 -280.078688)
		(width 0.0889)
		(layer "In4.Cu")
		(net "M_D_CPU0_SB_DQ<9>")
	)
	(arc
		(start 332.574138 -280.078688)
		(mid 332.761082 -280.128943)
		(end 332.948026 -280.078688)
		(width 0.0889)
		(layer "In4.Cu")
		(net "M_D_CPU0_SB_DQ<9>")
	)
	(arc
		(start 337.648042 -280.078688)
		(mid 337.930998 -280.002511)
		(end 338.213954 -280.078688)
		(width 0.0889)
		(layer "In4.Cu")
		(net "M_D_CPU0_SB_DQ<9>")
	)
	(arc
		(start 337.274154 -280.078688)
		(mid 337.461098 -280.128943)
		(end 337.648042 -280.078688)
		(width 0.0889)
		(layer "In4.Cu")
		(net "M_D_CPU0_SB_DQ<9>")
	)
	(arc
		(start 327.873614 -280.078688)
		(mid 328.056119 -280.129165)
		(end 328.239882 -280.083514)
		(width 0.0889)
		(layer "In4.Cu")
		(net "M_D_CPU0_SB_DQ<9>")
	)
	(arc
		(start 330.128118 -280.078688)
		(mid 330.411074 -280.002511)
		(end 330.69403 -280.078688)
		(width 0.0889)
		(layer "In4.Cu")
		(net "M_D_CPU0_SB_DQ<9>")
	)
	(arc
		(start 335.768188 -280.078688)
		(mid 336.051144 -280.002511)
		(end 336.3341 -280.078688)
		(width 0.0889)
		(layer "In4.Cu")
		(net "M_D_CPU0_SB_DQ<9>")
	)
	(arc
		(start 331.068172 -280.078688)
		(mid 331.351128 -280.002511)
		(end 331.634084 -280.078688)
		(width 0.0889)
		(layer "In4.Cu")
		(net "M_D_CPU0_SB_DQ<9>")
	)
	(arc
		(start 329.753976 -280.078688)
		(mid 329.936227 -280.129038)
		(end 330.119736 -280.083514)
		(width 0.0889)
		(layer "In4.Cu")
		(net "M_D_CPU0_SB_DQ<9>")
	)
	(segment
		(start 339.337904 -278.680164)
		(end 338.871052 -278.946102)
		(width 0.10668)
		(layer "F.Cu")
		(net "M_D_CPU0_SB_DQ<8>")
	)
	(segment
		(start 285.161228 -291.260276)
		(end 285.534862 -291.260276)
		(width 0.14478)
		(layer "In4.Cu")
		(net "M_D_CPU0_SB_DQ<8>")
	)
	(segment
		(start 326.463406 -279.268682)
		(end 326.46366 -279.268682)
		(width 0.0889)
		(layer "In4.Cu")
		(net "M_D_CPU0_SB_DQ<8>")
	)
	(segment
		(start 303.172876 -291.260276)
		(end 303.564544 -291.260276)
		(width 0.14478)
		(layer "In4.Cu")
		(net "M_D_CPU0_SB_DQ<8>")
	)
	(segment
		(start 285.930086 -291.6555)
		(end 286.142176 -291.6555)
		(width 0.14478)
		(layer "In4.Cu")
		(net "M_D_CPU0_SB_DQ<8>")
	)
	(segment
		(start 289.044888 -291.563552)
		(end 289.293046 -291.563552)
		(width 0.14478)
		(layer "In4.Cu")
		(net "M_D_CPU0_SB_DQ<8>")
	)
	(segment
		(start 297.25874 -291.58311)
		(end 298.431712 -290.410138)
		(width 0.14478)
		(layer "In4.Cu")
		(net "M_D_CPU0_SB_DQ<8>")
	)
	(segment
		(start 302.900842 -291.53231)
		(end 303.172876 -291.260276)
		(width 0.14478)
		(layer "In4.Cu")
		(net "M_D_CPU0_SB_DQ<8>")
	)
	(segment
		(start 289.596322 -291.260276)
		(end 290.108132 -291.260276)
		(width 0.14478)
		(layer "In4.Cu")
		(net "M_D_CPU0_SB_DQ<8>")
	)
	(segment
		(start 308.935882 -290.045902)
		(end 308.717442 -289.827462)
		(width 0.14478)
		(layer "In4.Cu")
		(net "M_D_CPU0_SB_DQ<8>")
	)
	(segment
		(start 305.89347 -290.410138)
		(end 306.262278 -290.410138)
		(width 0.14478)
		(layer "In4.Cu")
		(net "M_D_CPU0_SB_DQ<8>")
	)
	(segment
		(start 289.293046 -291.563552)
		(end 289.596322 -291.260276)
		(width 0.14478)
		(layer "In4.Cu")
		(net "M_D_CPU0_SB_DQ<8>")
	)
	(segment
		(start 300.244002 -290.410138)
		(end 300.527974 -290.69411)
		(width 0.14478)
		(layer "In4.Cu")
		(net "M_D_CPU0_SB_DQ<8>")
	)
	(segment
		(start 299.26026 -290.71951)
		(end 299.569632 -290.410138)
		(width 0.14478)
		(layer "In4.Cu")
		(net "M_D_CPU0_SB_DQ<8>")
	)
	(segment
		(start 308.717442 -289.827462)
		(end 308.717442 -289.59937)
		(width 0.14478)
		(layer "In4.Cu")
		(net "M_D_CPU0_SB_DQ<8>")
	)
	(segment
		(start 308.879494 -289.437318)
		(end 309.107332 -289.437318)
		(width 0.14478)
		(layer "In4.Cu")
		(net "M_D_CPU0_SB_DQ<8>")
	)
	(segment
		(start 304.253392 -291.49421)
		(end 304.414682 -291.6555)
		(width 0.14478)
		(layer "In4.Cu")
		(net "M_D_CPU0_SB_DQ<8>")
	)
	(segment
		(start 309.555896 -289.65779)
		(end 309.717948 -289.495738)
		(width 0.14478)
		(layer "In4.Cu")
		(net "M_D_CPU0_SB_DQ<8>")
	)
	(segment
		(start 337.744054 -279.268682)
		(end 337.752436 -279.273508)
		(width 0.0889)
		(layer "In4.Cu")
		(net "M_D_CPU0_SB_DQ<8>")
	)
	(segment
		(start 337.16976 -279.273508)
		(end 337.178142 -279.268682)
		(width 0.0889)
		(layer "In4.Cu")
		(net "M_D_CPU0_SB_DQ<8>")
	)
	(segment
		(start 326.837802 -279.268428)
		(end 326.84339 -279.265126)
		(width 0.0889)
		(layer "In4.Cu")
		(net "M_D_CPU0_SB_DQ<8>")
	)
	(segment
		(start 294.818816 -291.50691)
		(end 294.818816 -291.114988)
		(width 0.14478)
		(layer "In4.Cu")
		(net "M_D_CPU0_SB_DQ<8>")
	)
	(segment
		(start 286.142176 -291.6555)
		(end 286.314134 -291.483542)
		(width 0.14478)
		(layer "In4.Cu")
		(net "M_D_CPU0_SB_DQ<8>")
	)
	(segment
		(start 331.52969 -279.273508)
		(end 331.538072 -279.268682)
		(width 0.0889)
		(layer "In4.Cu")
		(net "M_D_CPU0_SB_DQ<8>")
	)
	(segment
		(start 303.858422 -290.966398)
		(end 304.092102 -290.966398)
		(width 0.14478)
		(layer "In4.Cu")
		(net "M_D_CPU0_SB_DQ<8>")
	)
	(segment
		(start 291.982398 -290.410138)
		(end 293.166038 -290.410138)
		(width 0.14478)
		(layer "In4.Cu")
		(net "M_D_CPU0_SB_DQ<8>")
	)
	(segment
		(start 329.284076 -279.268682)
		(end 329.292458 -279.273508)
		(width 0.0889)
		(layer "In4.Cu")
		(net "M_D_CPU0_SB_DQ<8>")
	)
	(segment
		(start 328.333608 -279.262586)
		(end 328.344022 -279.268682)
		(width 0.0889)
		(layer "In4.Cu")
		(net "M_D_CPU0_SB_DQ<8>")
	)
	(segment
		(start 306.57165 -290.71951)
		(end 306.818538 -290.71951)
		(width 0.14478)
		(layer "In4.Cu")
		(net "M_D_CPU0_SB_DQ<8>")
	)
	(segment
		(start 333.984092 -279.268682)
		(end 333.992474 -279.273508)
		(width 0.0889)
		(layer "In4.Cu")
		(net "M_D_CPU0_SB_DQ<8>")
	)
	(segment
		(start 296.076624 -291.260276)
		(end 296.370502 -290.966398)
		(width 0.14478)
		(layer "In4.Cu")
		(net "M_D_CPU0_SB_DQ<8>")
	)
	(segment
		(start 304.414682 -291.6555)
		(end 304.648108 -291.6555)
		(width 0.14478)
		(layer "In4.Cu")
		(net "M_D_CPU0_SB_DQ<8>")
	)
	(segment
		(start 309.49773 -289.047174)
		(end 309.49773 -288.819082)
		(width 0.14478)
		(layer "In4.Cu")
		(net "M_D_CPU0_SB_DQ<8>")
	)
	(segment
		(start 294.4114 -291.6555)
		(end 294.670226 -291.6555)
		(width 0.14478)
		(layer "In4.Cu")
		(net "M_D_CPU0_SB_DQ<8>")
	)
	(segment
		(start 294.818816 -291.114988)
		(end 294.967406 -290.966398)
		(width 0.14478)
		(layer "In4.Cu")
		(net "M_D_CPU0_SB_DQ<8>")
	)
	(segment
		(start 295.226486 -290.966398)
		(end 295.520364 -291.260276)
		(width 0.14478)
		(layer "In4.Cu")
		(net "M_D_CPU0_SB_DQ<8>")
	)
	(segment
		(start 324.565518 -278.74214)
		(end 324.61581 -278.792432)
		(width 0.0889)
		(layer "In4.Cu")
		(net "M_D_CPU0_SB_DQ<8>")
	)
	(segment
		(start 336.229706 -279.273508)
		(end 336.238088 -279.268682)
		(width 0.0889)
		(layer "In4.Cu")
		(net "M_D_CPU0_SB_DQ<8>")
	)
	(segment
		(start 296.370502 -290.966398)
		(end 296.604182 -290.966398)
		(width 0.14478)
		(layer "In4.Cu")
		(net "M_D_CPU0_SB_DQ<8>")
	)
	(segment
		(start 304.648108 -291.6555)
		(end 305.89347 -290.410138)
		(width 0.14478)
		(layer "In4.Cu")
		(net "M_D_CPU0_SB_DQ<8>")
	)
	(segment
		(start 290.931346 -290.437062)
		(end 291.14369 -290.437062)
		(width 0.14478)
		(layer "In4.Cu")
		(net "M_D_CPU0_SB_DQ<8>")
	)
	(segment
		(start 309.327804 -289.65779)
		(end 309.555896 -289.65779)
		(width 0.14478)
		(layer "In4.Cu")
		(net "M_D_CPU0_SB_DQ<8>")
	)
	(segment
		(start 295.520364 -291.260276)
		(end 296.076624 -291.260276)
		(width 0.14478)
		(layer "In4.Cu")
		(net "M_D_CPU0_SB_DQ<8>")
	)
	(segment
		(start 298.431712 -290.410138)
		(end 298.704 -290.410138)
		(width 0.14478)
		(layer "In4.Cu")
		(net "M_D_CPU0_SB_DQ<8>")
	)
	(segment
		(start 304.253392 -291.127688)
		(end 304.253392 -291.49421)
		(width 0.14478)
		(layer "In4.Cu")
		(net "M_D_CPU0_SB_DQ<8>")
	)
	(segment
		(start 326.819514 -279.278842)
		(end 326.837802 -279.268428)
		(width 0.0889)
		(layer "In4.Cu")
		(net "M_D_CPU0_SB_DQ<8>")
	)
	(segment
		(start 308.099206 -290.217606)
		(end 308.327044 -290.217606)
		(width 0.14478)
		(layer "In4.Cu")
		(net "M_D_CPU0_SB_DQ<8>")
	)
	(segment
		(start 308.54523 -290.435792)
		(end 308.77383 -290.435792)
		(width 0.14478)
		(layer "In4.Cu")
		(net "M_D_CPU0_SB_DQ<8>")
	)
	(segment
		(start 290.108132 -291.260276)
		(end 290.931346 -290.437062)
		(width 0.14478)
		(layer "In4.Cu")
		(net "M_D_CPU0_SB_DQ<8>")
	)
	(segment
		(start 298.704 -290.410138)
		(end 299.013372 -290.71951)
		(width 0.14478)
		(layer "In4.Cu")
		(net "M_D_CPU0_SB_DQ<8>")
	)
	(segment
		(start 287.002982 -291.260276)
		(end 288.741612 -291.260276)
		(width 0.14478)
		(layer "In4.Cu")
		(net "M_D_CPU0_SB_DQ<8>")
	)
	(segment
		(start 300.527974 -290.69411)
		(end 301.575724 -290.69411)
		(width 0.14478)
		(layer "In4.Cu")
		(net "M_D_CPU0_SB_DQ<8>")
	)
	(segment
		(start 308.717442 -289.59937)
		(end 308.879494 -289.437318)
		(width 0.14478)
		(layer "In4.Cu")
		(net "M_D_CPU0_SB_DQ<8>")
	)
	(segment
		(start 299.013372 -290.71951)
		(end 299.26026 -290.71951)
		(width 0.14478)
		(layer "In4.Cu")
		(net "M_D_CPU0_SB_DQ<8>")
	)
	(segment
		(start 296.604182 -290.966398)
		(end 296.765472 -291.127688)
		(width 0.14478)
		(layer "In4.Cu")
		(net "M_D_CPU0_SB_DQ<8>")
	)
	(segment
		(start 285.534862 -291.260276)
		(end 285.930086 -291.6555)
		(width 0.14478)
		(layer "In4.Cu")
		(net "M_D_CPU0_SB_DQ<8>")
	)
	(segment
		(start 308.935882 -290.27374)
		(end 308.935882 -290.045902)
		(width 0.14478)
		(layer "In4.Cu")
		(net "M_D_CPU0_SB_DQ<8>")
	)
	(segment
		(start 319.574672 -278.74214)
		(end 324.565518 -278.74214)
		(width 0.14478)
		(layer "In4.Cu")
		(net "M_D_CPU0_SB_DQ<8>")
	)
	(segment
		(start 309.107332 -289.437318)
		(end 309.327804 -289.65779)
		(width 0.14478)
		(layer "In4.Cu")
		(net "M_D_CPU0_SB_DQ<8>")
	)
	(segment
		(start 339.002878 -279.294844)
		(end 339.02523 -279.211532)
		(width 0.0889)
		(layer "In4.Cu")
		(net "M_D_CPU0_SB_DQ<8>")
	)
	(segment
		(start 332.469744 -279.273508)
		(end 332.478126 -279.268682)
		(width 0.0889)
		(layer "In4.Cu")
		(net "M_D_CPU0_SB_DQ<8>")
	)
	(segment
		(start 306.262278 -290.410138)
		(end 306.57165 -290.71951)
		(width 0.14478)
		(layer "In4.Cu")
		(net "M_D_CPU0_SB_DQ<8>")
	)
	(segment
		(start 286.709104 -290.966398)
		(end 287.002982 -291.260276)
		(width 0.14478)
		(layer "In4.Cu")
		(net "M_D_CPU0_SB_DQ<8>")
	)
	(segment
		(start 294.670226 -291.6555)
		(end 294.818816 -291.50691)
		(width 0.14478)
		(layer "In4.Cu")
		(net "M_D_CPU0_SB_DQ<8>")
	)
	(segment
		(start 296.765472 -291.127688)
		(end 296.765472 -291.42182)
		(width 0.14478)
		(layer "In4.Cu")
		(net "M_D_CPU0_SB_DQ<8>")
	)
	(segment
		(start 284.736032 -290.83508)
		(end 285.161228 -291.260276)
		(width 0.14478)
		(layer "In4.Cu")
		(net "M_D_CPU0_SB_DQ<8>")
	)
	(segment
		(start 291.426138 -290.71951)
		(end 291.673026 -290.71951)
		(width 0.14478)
		(layer "In4.Cu")
		(net "M_D_CPU0_SB_DQ<8>")
	)
	(segment
		(start 291.673026 -290.71951)
		(end 291.982398 -290.410138)
		(width 0.14478)
		(layer "In4.Cu")
		(net "M_D_CPU0_SB_DQ<8>")
	)
	(segment
		(start 303.564544 -291.260276)
		(end 303.858422 -290.966398)
		(width 0.14478)
		(layer "In4.Cu")
		(net "M_D_CPU0_SB_DQ<8>")
	)
	(segment
		(start 325.969376 -278.792432)
		(end 326.386952 -279.210008)
		(width 0.0889)
		(layer "In4.Cu")
		(net "M_D_CPU0_SB_DQ<8>")
	)
	(segment
		(start 299.569632 -290.410138)
		(end 300.244002 -290.410138)
		(width 0.14478)
		(layer "In4.Cu")
		(net "M_D_CPU0_SB_DQ<8>")
	)
	(segment
		(start 291.14369 -290.437062)
		(end 291.426138 -290.71951)
		(width 0.14478)
		(layer "In4.Cu")
		(net "M_D_CPU0_SB_DQ<8>")
	)
	(segment
		(start 294.967406 -290.966398)
		(end 295.226486 -290.966398)
		(width 0.14478)
		(layer "In4.Cu")
		(net "M_D_CPU0_SB_DQ<8>")
	)
	(segment
		(start 327.403206 -279.268682)
		(end 327.411588 -279.273508)
		(width 0.0889)
		(layer "In4.Cu")
		(net "M_D_CPU0_SB_DQ<8>")
	)
	(segment
		(start 288.741612 -291.260276)
		(end 289.044888 -291.563552)
		(width 0.14478)
		(layer "In4.Cu")
		(net "M_D_CPU0_SB_DQ<8>")
	)
	(segment
		(start 333.044038 -279.268682)
		(end 333.05242 -279.273508)
		(width 0.0889)
		(layer "In4.Cu")
		(net "M_D_CPU0_SB_DQ<8>")
	)
	(segment
		(start 286.314134 -291.127688)
		(end 286.475424 -290.966398)
		(width 0.14478)
		(layer "In4.Cu")
		(net "M_D_CPU0_SB_DQ<8>")
	)
	(segment
		(start 304.092102 -290.966398)
		(end 304.253392 -291.127688)
		(width 0.14478)
		(layer "In4.Cu")
		(net "M_D_CPU0_SB_DQ<8>")
	)
	(segment
		(start 324.61581 -278.792432)
		(end 325.969376 -278.792432)
		(width 0.0889)
		(layer "In4.Cu")
		(net "M_D_CPU0_SB_DQ<8>")
	)
	(segment
		(start 293.166038 -290.410138)
		(end 294.4114 -291.6555)
		(width 0.14478)
		(layer "In4.Cu")
		(net "M_D_CPU0_SB_DQ<8>")
	)
	(segment
		(start 339.02523 -279.211532)
		(end 338.871052 -278.946102)
		(width 0.0889)
		(layer "In4.Cu")
		(net "M_D_CPU0_SB_DQ<8>")
	)
	(segment
		(start 308.327044 -290.217606)
		(end 308.54523 -290.435792)
		(width 0.14478)
		(layer "In4.Cu")
		(net "M_D_CPU0_SB_DQ<8>")
	)
	(segment
		(start 296.926762 -291.58311)
		(end 297.25874 -291.58311)
		(width 0.14478)
		(layer "In4.Cu")
		(net "M_D_CPU0_SB_DQ<8>")
	)
	(segment
		(start 338.684108 -279.268682)
		(end 338.69249 -279.273508)
		(width 0.0889)
		(layer "In4.Cu")
		(net "M_D_CPU0_SB_DQ<8>")
	)
	(segment
		(start 307.12791 -290.410138)
		(end 307.906674 -290.410138)
		(width 0.14478)
		(layer "In4.Cu")
		(net "M_D_CPU0_SB_DQ<8>")
	)
	(segment
		(start 309.49773 -288.819082)
		(end 319.574672 -278.74214)
		(width 0.14478)
		(layer "In4.Cu")
		(net "M_D_CPU0_SB_DQ<8>")
	)
	(segment
		(start 306.818538 -290.71951)
		(end 307.12791 -290.410138)
		(width 0.14478)
		(layer "In4.Cu")
		(net "M_D_CPU0_SB_DQ<8>")
	)
	(segment
		(start 328.709782 -279.273508)
		(end 328.718164 -279.268682)
		(width 0.0889)
		(layer "In4.Cu")
		(net "M_D_CPU0_SB_DQ<8>")
	)
	(segment
		(start 307.906674 -290.410138)
		(end 308.099206 -290.217606)
		(width 0.14478)
		(layer "In4.Cu")
		(net "M_D_CPU0_SB_DQ<8>")
	)
	(segment
		(start 286.475424 -290.966398)
		(end 286.709104 -290.966398)
		(width 0.14478)
		(layer "In4.Cu")
		(net "M_D_CPU0_SB_DQ<8>")
	)
	(segment
		(start 286.314134 -291.483542)
		(end 286.314134 -291.127688)
		(width 0.14478)
		(layer "In4.Cu")
		(net "M_D_CPU0_SB_DQ<8>")
	)
	(segment
		(start 302.413924 -291.53231)
		(end 302.900842 -291.53231)
		(width 0.14478)
		(layer "In4.Cu")
		(net "M_D_CPU0_SB_DQ<8>")
	)
	(segment
		(start 301.575724 -290.69411)
		(end 302.413924 -291.53231)
		(width 0.14478)
		(layer "In4.Cu")
		(net "M_D_CPU0_SB_DQ<8>")
	)
	(segment
		(start 308.77383 -290.435792)
		(end 308.935882 -290.27374)
		(width 0.14478)
		(layer "In4.Cu")
		(net "M_D_CPU0_SB_DQ<8>")
	)
	(segment
		(start 309.717948 -289.495738)
		(end 309.717948 -289.267392)
		(width 0.14478)
		(layer "In4.Cu")
		(net "M_D_CPU0_SB_DQ<8>")
	)
	(segment
		(start 309.717948 -289.267392)
		(end 309.49773 -289.047174)
		(width 0.14478)
		(layer "In4.Cu")
		(net "M_D_CPU0_SB_DQ<8>")
	)
	(segment
		(start 296.765472 -291.42182)
		(end 296.926762 -291.58311)
		(width 0.14478)
		(layer "In4.Cu")
		(net "M_D_CPU0_SB_DQ<8>")
	)
	(arc
		(start 334.358234 -279.268682)
		(mid 334.64119 -279.192505)
		(end 334.924146 -279.268682)
		(width 0.0889)
		(layer "In4.Cu")
		(net "M_D_CPU0_SB_DQ<8>")
	)
	(arc
		(start 326.84339 -279.265126)
		(mid 327.123779 -279.192457)
		(end 327.403206 -279.268682)
		(width 0.0889)
		(layer "In4.Cu")
		(net "M_D_CPU0_SB_DQ<8>")
	)
	(arc
		(start 331.16393 -279.268682)
		(mid 331.346181 -279.319032)
		(end 331.52969 -279.273508)
		(width 0.0889)
		(layer "In4.Cu")
		(net "M_D_CPU0_SB_DQ<8>")
	)
	(arc
		(start 335.863946 -279.268682)
		(mid 336.046197 -279.319032)
		(end 336.229706 -279.273508)
		(width 0.0889)
		(layer "In4.Cu")
		(net "M_D_CPU0_SB_DQ<8>")
	)
	(arc
		(start 338.69249 -279.273508)
		(mid 338.84536 -279.318149)
		(end 339.002878 -279.294844)
		(width 0.0889)
		(layer "In4.Cu")
		(net "M_D_CPU0_SB_DQ<8>")
	)
	(arc
		(start 336.238088 -279.268682)
		(mid 336.521044 -279.192505)
		(end 336.804 -279.268682)
		(width 0.0889)
		(layer "In4.Cu")
		(net "M_D_CPU0_SB_DQ<8>")
	)
	(arc
		(start 333.05242 -279.273508)
		(mid 333.235928 -279.319002)
		(end 333.41818 -279.268682)
		(width 0.0889)
		(layer "In4.Cu")
		(net "M_D_CPU0_SB_DQ<8>")
	)
	(arc
		(start 337.178142 -279.268682)
		(mid 337.461098 -279.192505)
		(end 337.744054 -279.268682)
		(width 0.0889)
		(layer "In4.Cu")
		(net "M_D_CPU0_SB_DQ<8>")
	)
	(arc
		(start 332.103984 -279.268682)
		(mid 332.286235 -279.319032)
		(end 332.469744 -279.273508)
		(width 0.0889)
		(layer "In4.Cu")
		(net "M_D_CPU0_SB_DQ<8>")
	)
	(arc
		(start 335.298034 -279.268682)
		(mid 335.58099 -279.192505)
		(end 335.863946 -279.268682)
		(width 0.0889)
		(layer "In4.Cu")
		(net "M_D_CPU0_SB_DQ<8>")
	)
	(arc
		(start 333.41818 -279.268682)
		(mid 333.701136 -279.192505)
		(end 333.984092 -279.268682)
		(width 0.0889)
		(layer "In4.Cu")
		(net "M_D_CPU0_SB_DQ<8>")
	)
	(arc
		(start 330.22413 -279.268682)
		(mid 330.411074 -279.318937)
		(end 330.598018 -279.268682)
		(width 0.0889)
		(layer "In4.Cu")
		(net "M_D_CPU0_SB_DQ<8>")
	)
	(arc
		(start 336.804 -279.268682)
		(mid 336.986251 -279.319032)
		(end 337.16976 -279.273508)
		(width 0.0889)
		(layer "In4.Cu")
		(net "M_D_CPU0_SB_DQ<8>")
	)
	(arc
		(start 337.752436 -279.273508)
		(mid 337.935944 -279.319002)
		(end 338.118196 -279.268682)
		(width 0.0889)
		(layer "In4.Cu")
		(net "M_D_CPU0_SB_DQ<8>")
	)
	(arc
		(start 327.777856 -279.268682)
		(mid 328.054923 -279.192411)
		(end 328.333608 -279.262586)
		(width 0.0889)
		(layer "In4.Cu")
		(net "M_D_CPU0_SB_DQ<8>")
	)
	(arc
		(start 331.538072 -279.268682)
		(mid 331.821028 -279.192505)
		(end 332.103984 -279.268682)
		(width 0.0889)
		(layer "In4.Cu")
		(net "M_D_CPU0_SB_DQ<8>")
	)
	(arc
		(start 326.46366 -279.268682)
		(mid 326.640288 -279.318915)
		(end 326.819514 -279.278842)
		(width 0.0889)
		(layer "In4.Cu")
		(net "M_D_CPU0_SB_DQ<8>")
	)
	(arc
		(start 328.718164 -279.268682)
		(mid 329.00112 -279.192505)
		(end 329.284076 -279.268682)
		(width 0.0889)
		(layer "In4.Cu")
		(net "M_D_CPU0_SB_DQ<8>")
	)
	(arc
		(start 329.658218 -279.268682)
		(mid 329.941174 -279.192505)
		(end 330.22413 -279.268682)
		(width 0.0889)
		(layer "In4.Cu")
		(net "M_D_CPU0_SB_DQ<8>")
	)
	(arc
		(start 333.992474 -279.273508)
		(mid 334.175982 -279.319002)
		(end 334.358234 -279.268682)
		(width 0.0889)
		(layer "In4.Cu")
		(net "M_D_CPU0_SB_DQ<8>")
	)
	(arc
		(start 332.478126 -279.268682)
		(mid 332.761082 -279.192505)
		(end 333.044038 -279.268682)
		(width 0.0889)
		(layer "In4.Cu")
		(net "M_D_CPU0_SB_DQ<8>")
	)
	(arc
		(start 327.411588 -279.273508)
		(mid 327.59535 -279.319124)
		(end 327.777856 -279.268682)
		(width 0.0889)
		(layer "In4.Cu")
		(net "M_D_CPU0_SB_DQ<8>")
	)
	(arc
		(start 328.344022 -279.268682)
		(mid 328.526273 -279.319032)
		(end 328.709782 -279.273508)
		(width 0.0889)
		(layer "In4.Cu")
		(net "M_D_CPU0_SB_DQ<8>")
	)
	(arc
		(start 326.386952 -279.210008)
		(mid 326.423279 -279.241821)
		(end 326.463406 -279.268682)
		(width 0.0889)
		(layer "In4.Cu")
		(net "M_D_CPU0_SB_DQ<8>")
	)
	(arc
		(start 329.292458 -279.273508)
		(mid 329.475966 -279.319002)
		(end 329.658218 -279.268682)
		(width 0.0889)
		(layer "In4.Cu")
		(net "M_D_CPU0_SB_DQ<8>")
	)
	(arc
		(start 330.598018 -279.268682)
		(mid 330.880974 -279.192505)
		(end 331.16393 -279.268682)
		(width 0.0889)
		(layer "In4.Cu")
		(net "M_D_CPU0_SB_DQ<8>")
	)
	(arc
		(start 338.118196 -279.268682)
		(mid 338.401152 -279.192505)
		(end 338.684108 -279.268682)
		(width 0.0889)
		(layer "In4.Cu")
		(net "M_D_CPU0_SB_DQ<8>")
	)
	(arc
		(start 334.924146 -279.268682)
		(mid 335.11109 -279.318937)
		(end 335.298034 -279.268682)
		(width 0.0889)
		(layer "In4.Cu")
		(net "M_D_CPU0_SB_DQ<8>")
	)
	(segment
		(start 341.218012 -278.680164)
		(end 340.75116 -278.946102)
		(width 0.10668)
		(layer "F.Cu")
		(net "M_D_CPU0_SB_DQ<7>")
	)
	(segment
		(start 340.596982 -278.680672)
		(end 340.75116 -278.946102)
		(width 0.0889)
		(layer "In4.Cu")
		(net "M_D_CPU0_SB_DQ<7>")
	)
	(segment
		(start 328.333608 -278.629618)
		(end 328.344022 -278.623522)
		(width 0.0889)
		(layer "In4.Cu")
		(net "M_D_CPU0_SB_DQ<7>")
	)
	(segment
		(start 281.060906 -290.410138)
		(end 290.098226 -290.410138)
		(width 0.14478)
		(layer "In4.Cu")
		(net "M_D_CPU0_SB_DQ<7>")
	)
	(segment
		(start 293.226744 -289.56)
		(end 294.076882 -290.410138)
		(width 0.14478)
		(layer "In4.Cu")
		(net "M_D_CPU0_SB_DQ<7>")
	)
	(segment
		(start 338.684108 -278.623522)
		(end 338.69249 -278.618696)
		(width 0.0889)
		(layer "In4.Cu")
		(net "M_D_CPU0_SB_DQ<7>")
	)
	(segment
		(start 306.41671 -289.56)
		(end 307.977286 -289.56)
		(width 0.14478)
		(layer "In4.Cu")
		(net "M_D_CPU0_SB_DQ<7>")
	)
	(segment
		(start 324.767448 -278.487632)
		(end 327.274936 -278.487632)
		(width 0.0889)
		(layer "In4.Cu")
		(net "M_D_CPU0_SB_DQ<7>")
	)
	(segment
		(start 305.272948 -290.03371)
		(end 306.41671 -289.56)
		(width 0.14478)
		(layer "In4.Cu")
		(net "M_D_CPU0_SB_DQ<7>")
	)
	(segment
		(start 298.494704 -289.56)
		(end 300.288198 -289.56)
		(width 0.14478)
		(layer "In4.Cu")
		(net "M_D_CPU0_SB_DQ<7>")
	)
	(segment
		(start 331.52969 -278.618696)
		(end 331.538072 -278.623522)
		(width 0.0889)
		(layer "In4.Cu")
		(net "M_D_CPU0_SB_DQ<7>")
	)
	(segment
		(start 290.098226 -290.410138)
		(end 290.948364 -289.56)
		(width 0.14478)
		(layer "In4.Cu")
		(net "M_D_CPU0_SB_DQ<7>")
	)
	(segment
		(start 329.284076 -278.623522)
		(end 329.292458 -278.618696)
		(width 0.0889)
		(layer "In4.Cu")
		(net "M_D_CPU0_SB_DQ<7>")
	)
	(segment
		(start 337.16976 -278.618696)
		(end 337.178142 -278.623522)
		(width 0.0889)
		(layer "In4.Cu")
		(net "M_D_CPU0_SB_DQ<7>")
	)
	(segment
		(start 328.709782 -278.618696)
		(end 328.718164 -278.623522)
		(width 0.0889)
		(layer "In4.Cu")
		(net "M_D_CPU0_SB_DQ<7>")
	)
	(segment
		(start 280.635964 -289.985196)
		(end 281.060906 -290.410138)
		(width 0.14478)
		(layer "In4.Cu")
		(net "M_D_CPU0_SB_DQ<7>")
	)
	(segment
		(start 340.500716 -278.655272)
		(end 340.596982 -278.680672)
		(width 0.0889)
		(layer "In4.Cu")
		(net "M_D_CPU0_SB_DQ<7>")
	)
	(segment
		(start 300.288198 -289.56)
		(end 301.43196 -290.03371)
		(width 0.14478)
		(layer "In4.Cu")
		(net "M_D_CPU0_SB_DQ<7>")
	)
	(segment
		(start 337.744054 -278.623522)
		(end 337.752436 -278.618696)
		(width 0.0889)
		(layer "In4.Cu")
		(net "M_D_CPU0_SB_DQ<7>")
	)
	(segment
		(start 332.469744 -278.618696)
		(end 332.478126 -278.623522)
		(width 0.0889)
		(layer "In4.Cu")
		(net "M_D_CPU0_SB_DQ<7>")
	)
	(segment
		(start 301.43196 -290.03371)
		(end 305.272948 -290.03371)
		(width 0.14478)
		(layer "In4.Cu")
		(net "M_D_CPU0_SB_DQ<7>")
	)
	(segment
		(start 290.948364 -289.56)
		(end 293.226744 -289.56)
		(width 0.14478)
		(layer "In4.Cu")
		(net "M_D_CPU0_SB_DQ<7>")
	)
	(segment
		(start 319.249806 -278.28748)
		(end 323.97446 -278.28748)
		(width 0.14478)
		(layer "In4.Cu")
		(net "M_D_CPU0_SB_DQ<7>")
	)
	(segment
		(start 333.984092 -278.623522)
		(end 333.992474 -278.618696)
		(width 0.0889)
		(layer "In4.Cu")
		(net "M_D_CPU0_SB_DQ<7>")
	)
	(segment
		(start 294.076882 -290.410138)
		(end 297.644566 -290.410138)
		(width 0.14478)
		(layer "In4.Cu")
		(net "M_D_CPU0_SB_DQ<7>")
	)
	(segment
		(start 324.520306 -278.28748)
		(end 324.687184 -278.454358)
		(width 0.0889)
		(layer "In4.Cu")
		(net "M_D_CPU0_SB_DQ<7>")
	)
	(segment
		(start 323.97446 -278.28748)
		(end 324.520306 -278.28748)
		(width 0.0889)
		(layer "In4.Cu")
		(net "M_D_CPU0_SB_DQ<7>")
	)
	(segment
		(start 333.044038 -278.623522)
		(end 333.05242 -278.618696)
		(width 0.0889)
		(layer "In4.Cu")
		(net "M_D_CPU0_SB_DQ<7>")
	)
	(segment
		(start 336.229706 -278.618696)
		(end 336.238088 -278.623522)
		(width 0.0889)
		(layer "In4.Cu")
		(net "M_D_CPU0_SB_DQ<7>")
	)
	(segment
		(start 297.644566 -290.410138)
		(end 298.494704 -289.56)
		(width 0.14478)
		(layer "In4.Cu")
		(net "M_D_CPU0_SB_DQ<7>")
	)
	(segment
		(start 307.977286 -289.56)
		(end 319.249806 -278.28748)
		(width 0.14478)
		(layer "In4.Cu")
		(net "M_D_CPU0_SB_DQ<7>")
	)
	(arc
		(start 333.992474 -278.618696)
		(mid 334.175982 -278.573202)
		(end 334.358234 -278.623522)
		(width 0.0889)
		(layer "In4.Cu")
		(net "M_D_CPU0_SB_DQ<7>")
	)
	(arc
		(start 338.118196 -278.623522)
		(mid 338.401152 -278.699699)
		(end 338.684108 -278.623522)
		(width 0.0889)
		(layer "In4.Cu")
		(net "M_D_CPU0_SB_DQ<7>")
	)
	(arc
		(start 333.05242 -278.618696)
		(mid 333.235928 -278.573202)
		(end 333.41818 -278.623522)
		(width 0.0889)
		(layer "In4.Cu")
		(net "M_D_CPU0_SB_DQ<7>")
	)
	(arc
		(start 332.478126 -278.623522)
		(mid 332.761082 -278.699699)
		(end 333.044038 -278.623522)
		(width 0.0889)
		(layer "In4.Cu")
		(net "M_D_CPU0_SB_DQ<7>")
	)
	(arc
		(start 327.777856 -278.623522)
		(mid 328.054923 -278.699793)
		(end 328.333608 -278.629618)
		(width 0.0889)
		(layer "In4.Cu")
		(net "M_D_CPU0_SB_DQ<7>")
	)
	(arc
		(start 338.69249 -278.618696)
		(mid 338.875998 -278.573202)
		(end 339.05825 -278.623522)
		(width 0.0889)
		(layer "In4.Cu")
		(net "M_D_CPU0_SB_DQ<7>")
	)
	(arc
		(start 324.687184 -278.454358)
		(mid 324.723995 -278.479018)
		(end 324.767448 -278.487632)
		(width 0.0889)
		(layer "In4.Cu")
		(net "M_D_CPU0_SB_DQ<7>")
	)
	(arc
		(start 331.538072 -278.623522)
		(mid 331.821028 -278.699699)
		(end 332.103984 -278.623522)
		(width 0.0889)
		(layer "In4.Cu")
		(net "M_D_CPU0_SB_DQ<7>")
	)
	(arc
		(start 328.718164 -278.623522)
		(mid 329.00112 -278.699699)
		(end 329.284076 -278.623522)
		(width 0.0889)
		(layer "In4.Cu")
		(net "M_D_CPU0_SB_DQ<7>")
	)
	(arc
		(start 329.292458 -278.618696)
		(mid 329.475966 -278.573202)
		(end 329.658218 -278.623522)
		(width 0.0889)
		(layer "In4.Cu")
		(net "M_D_CPU0_SB_DQ<7>")
	)
	(arc
		(start 334.358234 -278.623522)
		(mid 334.64119 -278.699699)
		(end 334.924146 -278.623522)
		(width 0.0889)
		(layer "In4.Cu")
		(net "M_D_CPU0_SB_DQ<7>")
	)
	(arc
		(start 332.103984 -278.623522)
		(mid 332.286235 -278.573172)
		(end 332.469744 -278.618696)
		(width 0.0889)
		(layer "In4.Cu")
		(net "M_D_CPU0_SB_DQ<7>")
	)
	(arc
		(start 335.298034 -278.623522)
		(mid 335.58099 -278.699699)
		(end 335.863946 -278.623522)
		(width 0.0889)
		(layer "In4.Cu")
		(net "M_D_CPU0_SB_DQ<7>")
	)
	(arc
		(start 337.752436 -278.618696)
		(mid 337.935944 -278.573202)
		(end 338.118196 -278.623522)
		(width 0.0889)
		(layer "In4.Cu")
		(net "M_D_CPU0_SB_DQ<7>")
	)
	(arc
		(start 328.344022 -278.623522)
		(mid 328.526273 -278.573172)
		(end 328.709782 -278.618696)
		(width 0.0889)
		(layer "In4.Cu")
		(net "M_D_CPU0_SB_DQ<7>")
	)
	(arc
		(start 337.178142 -278.623522)
		(mid 337.461098 -278.699699)
		(end 337.744054 -278.623522)
		(width 0.0889)
		(layer "In4.Cu")
		(net "M_D_CPU0_SB_DQ<7>")
	)
	(arc
		(start 339.99805 -278.623522)
		(mid 340.245646 -278.6987)
		(end 340.500716 -278.655272)
		(width 0.0889)
		(layer "In4.Cu")
		(net "M_D_CPU0_SB_DQ<7>")
	)
	(arc
		(start 339.05825 -278.623522)
		(mid 339.341206 -278.699699)
		(end 339.624162 -278.623522)
		(width 0.0889)
		(layer "In4.Cu")
		(net "M_D_CPU0_SB_DQ<7>")
	)
	(arc
		(start 330.598018 -278.623522)
		(mid 330.880974 -278.699699)
		(end 331.16393 -278.623522)
		(width 0.0889)
		(layer "In4.Cu")
		(net "M_D_CPU0_SB_DQ<7>")
	)
	(arc
		(start 331.16393 -278.623522)
		(mid 331.346181 -278.573172)
		(end 331.52969 -278.618696)
		(width 0.0889)
		(layer "In4.Cu")
		(net "M_D_CPU0_SB_DQ<7>")
	)
	(arc
		(start 334.924146 -278.623522)
		(mid 335.11109 -278.573267)
		(end 335.298034 -278.623522)
		(width 0.0889)
		(layer "In4.Cu")
		(net "M_D_CPU0_SB_DQ<7>")
	)
	(arc
		(start 333.41818 -278.623522)
		(mid 333.701136 -278.699699)
		(end 333.984092 -278.623522)
		(width 0.0889)
		(layer "In4.Cu")
		(net "M_D_CPU0_SB_DQ<7>")
	)
	(arc
		(start 330.22413 -278.623522)
		(mid 330.411074 -278.573267)
		(end 330.598018 -278.623522)
		(width 0.0889)
		(layer "In4.Cu")
		(net "M_D_CPU0_SB_DQ<7>")
	)
	(arc
		(start 339.624162 -278.623522)
		(mid 339.811106 -278.573267)
		(end 339.99805 -278.623522)
		(width 0.0889)
		(layer "In4.Cu")
		(net "M_D_CPU0_SB_DQ<7>")
	)
	(arc
		(start 329.658218 -278.623522)
		(mid 329.941174 -278.699699)
		(end 330.22413 -278.623522)
		(width 0.0889)
		(layer "In4.Cu")
		(net "M_D_CPU0_SB_DQ<7>")
	)
	(arc
		(start 335.863946 -278.623522)
		(mid 336.046197 -278.573172)
		(end 336.229706 -278.618696)
		(width 0.0889)
		(layer "In4.Cu")
		(net "M_D_CPU0_SB_DQ<7>")
	)
	(arc
		(start 336.238088 -278.623522)
		(mid 336.521044 -278.699699)
		(end 336.804 -278.623522)
		(width 0.0889)
		(layer "In4.Cu")
		(net "M_D_CPU0_SB_DQ<7>")
	)
	(arc
		(start 327.274936 -278.487632)
		(mid 327.535412 -278.522206)
		(end 327.777856 -278.623522)
		(width 0.0889)
		(layer "In4.Cu")
		(net "M_D_CPU0_SB_DQ<7>")
	)
	(arc
		(start 336.804 -278.623522)
		(mid 336.986251 -278.573172)
		(end 337.16976 -278.618696)
		(width 0.0889)
		(layer "In4.Cu")
		(net "M_D_CPU0_SB_DQ<7>")
	)
	(segment
		(start 339.808058 -277.870158)
		(end 339.341206 -278.136096)
		(width 0.10668)
		(layer "F.Cu")
		(net "M_D_CPU0_SB_DQ<6>")
	)
	(segment
		(start 330.119736 -277.80869)
		(end 330.128118 -277.813516)
		(width 0.0889)
		(layer "In4.Cu")
		(net "M_D_CPU0_SB_DQ<6>")
	)
	(segment
		(start 326.93356 -277.81377)
		(end 326.949816 -277.804372)
		(width 0.0889)
		(layer "In4.Cu")
		(net "M_D_CPU0_SB_DQ<6>")
	)
	(segment
		(start 308.405022 -287.859978)
		(end 318.88684 -277.37816)
		(width 0.14478)
		(layer "In4.Cu")
		(net "M_D_CPU0_SB_DQ<6>")
	)
	(segment
		(start 318.88684 -277.37816)
		(end 323.894704 -277.37816)
		(width 0.14478)
		(layer "In4.Cu")
		(net "M_D_CPU0_SB_DQ<6>")
	)
	(segment
		(start 336.3341 -277.813516)
		(end 336.342482 -277.80869)
		(width 0.0889)
		(layer "In4.Cu")
		(net "M_D_CPU0_SB_DQ<6>")
	)
	(segment
		(start 290.249102 -288.710116)
		(end 291.09924 -287.859978)
		(width 0.14478)
		(layer "In4.Cu")
		(net "M_D_CPU0_SB_DQ<6>")
	)
	(segment
		(start 334.819752 -277.80869)
		(end 334.828134 -277.813516)
		(width 0.0889)
		(layer "In4.Cu")
		(net "M_D_CPU0_SB_DQ<6>")
	)
	(segment
		(start 338.579714 -277.80869)
		(end 338.588096 -277.813516)
		(width 0.0889)
		(layer "In4.Cu")
		(net "M_D_CPU0_SB_DQ<6>")
	)
	(segment
		(start 281.060906 -288.710116)
		(end 282.611068 -288.710116)
		(width 0.14478)
		(layer "In4.Cu")
		(net "M_D_CPU0_SB_DQ<6>")
	)
	(segment
		(start 298.058078 -288.710116)
		(end 298.908216 -287.859978)
		(width 0.14478)
		(layer "In4.Cu")
		(net "M_D_CPU0_SB_DQ<6>")
	)
	(segment
		(start 293.025068 -287.859978)
		(end 293.875206 -288.710116)
		(width 0.14478)
		(layer "In4.Cu")
		(net "M_D_CPU0_SB_DQ<6>")
	)
	(segment
		(start 325.909686 -277.37816)
		(end 326.421242 -277.889716)
		(width 0.0889)
		(layer "In4.Cu")
		(net "M_D_CPU0_SB_DQ<6>")
	)
	(segment
		(start 301.665386 -288.710116)
		(end 305.387502 -288.710116)
		(width 0.14478)
		(layer "In4.Cu")
		(net "M_D_CPU0_SB_DQ<6>")
	)
	(segment
		(start 300.815248 -287.859978)
		(end 301.665386 -288.710116)
		(width 0.14478)
		(layer "In4.Cu")
		(net "M_D_CPU0_SB_DQ<6>")
	)
	(segment
		(start 293.875206 -288.710116)
		(end 298.058078 -288.710116)
		(width 0.14478)
		(layer "In4.Cu")
		(net "M_D_CPU0_SB_DQ<6>")
	)
	(segment
		(start 339.187028 -277.870666)
		(end 339.341206 -278.136096)
		(width 0.0889)
		(layer "In4.Cu")
		(net "M_D_CPU0_SB_DQ<6>")
	)
	(segment
		(start 282.772612 -288.219896)
		(end 282.934156 -288.058352)
		(width 0.14478)
		(layer "In4.Cu")
		(net "M_D_CPU0_SB_DQ<6>")
	)
	(segment
		(start 305.387502 -288.710116)
		(end 306.23764 -287.859978)
		(width 0.14478)
		(layer "In4.Cu")
		(net "M_D_CPU0_SB_DQ<6>")
	)
	(segment
		(start 306.23764 -287.859978)
		(end 308.405022 -287.859978)
		(width 0.14478)
		(layer "In4.Cu")
		(net "M_D_CPU0_SB_DQ<6>")
	)
	(segment
		(start 282.934156 -288.058352)
		(end 283.162502 -288.058352)
		(width 0.14478)
		(layer "In4.Cu")
		(net "M_D_CPU0_SB_DQ<6>")
	)
	(segment
		(start 331.634084 -277.813516)
		(end 331.642466 -277.80869)
		(width 0.0889)
		(layer "In4.Cu")
		(net "M_D_CPU0_SB_DQ<6>")
	)
	(segment
		(start 283.48559 -288.710116)
		(end 290.249102 -288.710116)
		(width 0.14478)
		(layer "In4.Cu")
		(net "M_D_CPU0_SB_DQ<6>")
	)
	(segment
		(start 327.307448 -277.813516)
		(end 327.317862 -277.819612)
		(width 0.0889)
		(layer "In4.Cu")
		(net "M_D_CPU0_SB_DQ<6>")
	)
	(segment
		(start 323.894704 -277.37816)
		(end 325.909686 -277.37816)
		(width 0.0889)
		(layer "In4.Cu")
		(net "M_D_CPU0_SB_DQ<6>")
	)
	(segment
		(start 283.324046 -288.548572)
		(end 283.48559 -288.710116)
		(width 0.14478)
		(layer "In4.Cu")
		(net "M_D_CPU0_SB_DQ<6>")
	)
	(segment
		(start 339.090762 -277.845266)
		(end 339.187028 -277.870666)
		(width 0.0889)
		(layer "In4.Cu")
		(net "M_D_CPU0_SB_DQ<6>")
	)
	(segment
		(start 283.324046 -288.219896)
		(end 283.324046 -288.548572)
		(width 0.14478)
		(layer "In4.Cu")
		(net "M_D_CPU0_SB_DQ<6>")
	)
	(segment
		(start 280.635964 -288.285174)
		(end 281.060906 -288.710116)
		(width 0.14478)
		(layer "In4.Cu")
		(net "M_D_CPU0_SB_DQ<6>")
	)
	(segment
		(start 282.772612 -288.548572)
		(end 282.772612 -288.219896)
		(width 0.14478)
		(layer "In4.Cu")
		(net "M_D_CPU0_SB_DQ<6>")
	)
	(segment
		(start 330.69403 -277.813516)
		(end 330.702412 -277.80869)
		(width 0.0889)
		(layer "In4.Cu")
		(net "M_D_CPU0_SB_DQ<6>")
	)
	(segment
		(start 283.162502 -288.058352)
		(end 283.324046 -288.219896)
		(width 0.14478)
		(layer "In4.Cu")
		(net "M_D_CPU0_SB_DQ<6>")
	)
	(segment
		(start 326.421242 -277.889716)
		(end 326.651112 -277.889716)
		(width 0.0889)
		(layer "In4.Cu")
		(net "M_D_CPU0_SB_DQ<6>")
	)
	(segment
		(start 282.611068 -288.710116)
		(end 282.772612 -288.548572)
		(width 0.14478)
		(layer "In4.Cu")
		(net "M_D_CPU0_SB_DQ<6>")
	)
	(segment
		(start 335.394046 -277.813516)
		(end 335.402428 -277.80869)
		(width 0.0889)
		(layer "In4.Cu")
		(net "M_D_CPU0_SB_DQ<6>")
	)
	(segment
		(start 298.908216 -287.859978)
		(end 300.815248 -287.859978)
		(width 0.14478)
		(layer "In4.Cu")
		(net "M_D_CPU0_SB_DQ<6>")
	)
	(segment
		(start 328.239882 -277.80869)
		(end 328.248264 -277.813516)
		(width 0.0889)
		(layer "In4.Cu")
		(net "M_D_CPU0_SB_DQ<6>")
	)
	(segment
		(start 291.09924 -287.859978)
		(end 293.025068 -287.859978)
		(width 0.14478)
		(layer "In4.Cu")
		(net "M_D_CPU0_SB_DQ<6>")
	)
	(segment
		(start 333.879698 -277.80869)
		(end 333.88808 -277.813516)
		(width 0.0889)
		(layer "In4.Cu")
		(net "M_D_CPU0_SB_DQ<6>")
	)
	(arc
		(start 333.88808 -277.813516)
		(mid 334.171036 -277.889693)
		(end 334.453992 -277.813516)
		(width 0.0889)
		(layer "In4.Cu")
		(net "M_D_CPU0_SB_DQ<6>")
	)
	(arc
		(start 326.949816 -277.804372)
		(mid 327.129798 -277.763272)
		(end 327.307448 -277.813516)
		(width 0.0889)
		(layer "In4.Cu")
		(net "M_D_CPU0_SB_DQ<6>")
	)
	(arc
		(start 334.828134 -277.813516)
		(mid 335.11109 -277.889693)
		(end 335.394046 -277.813516)
		(width 0.0889)
		(layer "In4.Cu")
		(net "M_D_CPU0_SB_DQ<6>")
	)
	(arc
		(start 338.588096 -277.813516)
		(mid 338.835692 -277.888694)
		(end 339.090762 -277.845266)
		(width 0.0889)
		(layer "In4.Cu")
		(net "M_D_CPU0_SB_DQ<6>")
	)
	(arc
		(start 326.651112 -277.889716)
		(mid 326.79736 -277.870411)
		(end 326.93356 -277.81377)
		(width 0.0889)
		(layer "In4.Cu")
		(net "M_D_CPU0_SB_DQ<6>")
	)
	(arc
		(start 330.702412 -277.80869)
		(mid 330.88592 -277.763196)
		(end 331.068172 -277.813516)
		(width 0.0889)
		(layer "In4.Cu")
		(net "M_D_CPU0_SB_DQ<6>")
	)
	(arc
		(start 330.128118 -277.813516)
		(mid 330.411074 -277.889693)
		(end 330.69403 -277.813516)
		(width 0.0889)
		(layer "In4.Cu")
		(net "M_D_CPU0_SB_DQ<6>")
	)
	(arc
		(start 333.513938 -277.813516)
		(mid 333.696189 -277.763166)
		(end 333.879698 -277.80869)
		(width 0.0889)
		(layer "In4.Cu")
		(net "M_D_CPU0_SB_DQ<6>")
	)
	(arc
		(start 329.753976 -277.813516)
		(mid 329.936227 -277.763166)
		(end 330.119736 -277.80869)
		(width 0.0889)
		(layer "In4.Cu")
		(net "M_D_CPU0_SB_DQ<6>")
	)
	(arc
		(start 336.342482 -277.80869)
		(mid 336.52599 -277.763196)
		(end 336.708242 -277.813516)
		(width 0.0889)
		(layer "In4.Cu")
		(net "M_D_CPU0_SB_DQ<6>")
	)
	(arc
		(start 335.768188 -277.813516)
		(mid 336.051144 -277.889693)
		(end 336.3341 -277.813516)
		(width 0.0889)
		(layer "In4.Cu")
		(net "M_D_CPU0_SB_DQ<6>")
	)
	(arc
		(start 331.068172 -277.813516)
		(mid 331.351128 -277.889693)
		(end 331.634084 -277.813516)
		(width 0.0889)
		(layer "In4.Cu")
		(net "M_D_CPU0_SB_DQ<6>")
	)
	(arc
		(start 329.188064 -277.813516)
		(mid 329.47102 -277.889693)
		(end 329.753976 -277.813516)
		(width 0.0889)
		(layer "In4.Cu")
		(net "M_D_CPU0_SB_DQ<6>")
	)
	(arc
		(start 327.873614 -277.813516)
		(mid 328.056119 -277.763039)
		(end 328.239882 -277.80869)
		(width 0.0889)
		(layer "In4.Cu")
		(net "M_D_CPU0_SB_DQ<6>")
	)
	(arc
		(start 335.402428 -277.80869)
		(mid 335.585936 -277.763196)
		(end 335.768188 -277.813516)
		(width 0.0889)
		(layer "In4.Cu")
		(net "M_D_CPU0_SB_DQ<6>")
	)
	(arc
		(start 336.708242 -277.813516)
		(mid 336.991198 -277.889693)
		(end 337.274154 -277.813516)
		(width 0.0889)
		(layer "In4.Cu")
		(net "M_D_CPU0_SB_DQ<6>")
	)
	(arc
		(start 338.213954 -277.813516)
		(mid 338.396205 -277.763166)
		(end 338.579714 -277.80869)
		(width 0.0889)
		(layer "In4.Cu")
		(net "M_D_CPU0_SB_DQ<6>")
	)
	(arc
		(start 331.642466 -277.80869)
		(mid 331.825974 -277.763196)
		(end 332.008226 -277.813516)
		(width 0.0889)
		(layer "In4.Cu")
		(net "M_D_CPU0_SB_DQ<6>")
	)
	(arc
		(start 332.574138 -277.813516)
		(mid 332.761082 -277.763261)
		(end 332.948026 -277.813516)
		(width 0.0889)
		(layer "In4.Cu")
		(net "M_D_CPU0_SB_DQ<6>")
	)
	(arc
		(start 332.008226 -277.813516)
		(mid 332.291182 -277.889693)
		(end 332.574138 -277.813516)
		(width 0.0889)
		(layer "In4.Cu")
		(net "M_D_CPU0_SB_DQ<6>")
	)
	(arc
		(start 327.317862 -277.819612)
		(mid 327.596548 -277.889832)
		(end 327.873614 -277.813516)
		(width 0.0889)
		(layer "In4.Cu")
		(net "M_D_CPU0_SB_DQ<6>")
	)
	(arc
		(start 328.814176 -277.813516)
		(mid 329.00112 -277.763261)
		(end 329.188064 -277.813516)
		(width 0.0889)
		(layer "In4.Cu")
		(net "M_D_CPU0_SB_DQ<6>")
	)
	(arc
		(start 328.248264 -277.813516)
		(mid 328.53122 -277.889693)
		(end 328.814176 -277.813516)
		(width 0.0889)
		(layer "In4.Cu")
		(net "M_D_CPU0_SB_DQ<6>")
	)
	(arc
		(start 337.648042 -277.813516)
		(mid 337.930998 -277.889693)
		(end 338.213954 -277.813516)
		(width 0.0889)
		(layer "In4.Cu")
		(net "M_D_CPU0_SB_DQ<6>")
	)
	(arc
		(start 337.274154 -277.813516)
		(mid 337.461098 -277.763261)
		(end 337.648042 -277.813516)
		(width 0.0889)
		(layer "In4.Cu")
		(net "M_D_CPU0_SB_DQ<6>")
	)
	(arc
		(start 332.948026 -277.813516)
		(mid 333.230982 -277.889693)
		(end 333.513938 -277.813516)
		(width 0.0889)
		(layer "In4.Cu")
		(net "M_D_CPU0_SB_DQ<6>")
	)
	(arc
		(start 334.453992 -277.813516)
		(mid 334.636243 -277.763166)
		(end 334.819752 -277.80869)
		(width 0.0889)
		(layer "In4.Cu")
		(net "M_D_CPU0_SB_DQ<6>")
	)
	(segment
		(start 340.747858 -277.870158)
		(end 340.281006 -278.136096)
		(width 0.10668)
		(layer "F.Cu")
		(net "M_D_CPU0_SB_DQ<5>")
	)
	(segment
		(start 338.579714 -278.463502)
		(end 338.588096 -278.458676)
		(width 0.0889)
		(layer "In4.Cu")
		(net "M_D_CPU0_SB_DQ<5>")
	)
	(segment
		(start 297.184064 -289.950398)
		(end 297.461178 -289.950398)
		(width 0.14478)
		(layer "In4.Cu")
		(net "M_D_CPU0_SB_DQ<5>")
	)
	(segment
		(start 297.02125 -289.787584)
		(end 297.184064 -289.950398)
		(width 0.14478)
		(layer "In4.Cu")
		(net "M_D_CPU0_SB_DQ<5>")
	)
	(segment
		(start 297.461178 -289.950398)
		(end 298.70146 -288.710116)
		(width 0.14478)
		(layer "In4.Cu")
		(net "M_D_CPU0_SB_DQ<5>")
	)
	(segment
		(start 290.130738 -289.560254)
		(end 290.980876 -288.710116)
		(width 0.14478)
		(layer "In4.Cu")
		(net "M_D_CPU0_SB_DQ<5>")
	)
	(segment
		(start 305.22291 -289.560254)
		(end 306.073048 -288.710116)
		(width 0.14478)
		(layer "In4.Cu")
		(net "M_D_CPU0_SB_DQ<5>")
	)
	(segment
		(start 340.435184 -278.401526)
		(end 340.281006 -278.136096)
		(width 0.0889)
		(layer "In4.Cu")
		(net "M_D_CPU0_SB_DQ<5>")
	)
	(segment
		(start 297.02125 -289.332924)
		(end 297.02125 -289.787584)
		(width 0.14478)
		(layer "In4.Cu")
		(net "M_D_CPU0_SB_DQ<5>")
	)
	(segment
		(start 294.291004 -289.933888)
		(end 294.526462 -289.933888)
		(width 0.14478)
		(layer "In4.Cu")
		(net "M_D_CPU0_SB_DQ<5>")
	)
	(segment
		(start 296.627804 -289.17011)
		(end 296.858436 -289.17011)
		(width 0.14478)
		(layer "In4.Cu")
		(net "M_D_CPU0_SB_DQ<5>")
	)
	(segment
		(start 293.067232 -288.710116)
		(end 294.291004 -289.933888)
		(width 0.14478)
		(layer "In4.Cu")
		(net "M_D_CPU0_SB_DQ<5>")
	)
	(segment
		(start 284.736032 -289.135058)
		(end 285.533084 -289.93211)
		(width 0.14478)
		(layer "In4.Cu")
		(net "M_D_CPU0_SB_DQ<5>")
	)
	(segment
		(start 340.412832 -278.484838)
		(end 340.435184 -278.401526)
		(width 0.0889)
		(layer "In4.Cu")
		(net "M_D_CPU0_SB_DQ<5>")
	)
	(segment
		(start 301.862998 -289.560254)
		(end 305.22291 -289.560254)
		(width 0.14478)
		(layer "In4.Cu")
		(net "M_D_CPU0_SB_DQ<5>")
	)
	(segment
		(start 285.924752 -289.769296)
		(end 285.924752 -289.351212)
		(width 0.14478)
		(layer "In4.Cu")
		(net "M_D_CPU0_SB_DQ<5>")
	)
	(segment
		(start 295.456356 -289.560254)
		(end 296.23766 -289.560254)
		(width 0.14478)
		(layer "In4.Cu")
		(net "M_D_CPU0_SB_DQ<5>")
	)
	(segment
		(start 340.094062 -278.458676)
		(end 340.102444 -278.463502)
		(width 0.0889)
		(layer "In4.Cu")
		(net "M_D_CPU0_SB_DQ<5>")
	)
	(segment
		(start 295.1353 -289.239198)
		(end 295.456356 -289.560254)
		(width 0.14478)
		(layer "In4.Cu")
		(net "M_D_CPU0_SB_DQ<5>")
	)
	(segment
		(start 285.761938 -289.93211)
		(end 285.924752 -289.769296)
		(width 0.14478)
		(layer "In4.Cu")
		(net "M_D_CPU0_SB_DQ<5>")
	)
	(segment
		(start 319.06845 -277.83282)
		(end 323.97446 -277.83282)
		(width 0.14478)
		(layer "In4.Cu")
		(net "M_D_CPU0_SB_DQ<5>")
	)
	(segment
		(start 286.087566 -289.188398)
		(end 286.318198 -289.188398)
		(width 0.14478)
		(layer "In4.Cu")
		(net "M_D_CPU0_SB_DQ<5>")
	)
	(segment
		(start 339.519768 -278.463502)
		(end 339.52815 -278.458676)
		(width 0.0889)
		(layer "In4.Cu")
		(net "M_D_CPU0_SB_DQ<5>")
	)
	(segment
		(start 331.634084 -278.458676)
		(end 331.642466 -278.463502)
		(width 0.0889)
		(layer "In4.Cu")
		(net "M_D_CPU0_SB_DQ<5>")
	)
	(segment
		(start 286.874458 -289.93211)
		(end 287.246314 -289.560254)
		(width 0.14478)
		(layer "In4.Cu")
		(net "M_D_CPU0_SB_DQ<5>")
	)
	(segment
		(start 285.924752 -289.351212)
		(end 286.087566 -289.188398)
		(width 0.14478)
		(layer "In4.Cu")
		(net "M_D_CPU0_SB_DQ<5>")
	)
	(segment
		(start 286.318198 -289.188398)
		(end 286.481012 -289.351212)
		(width 0.14478)
		(layer "In4.Cu")
		(net "M_D_CPU0_SB_DQ<5>")
	)
	(segment
		(start 330.69403 -278.458676)
		(end 330.702412 -278.463502)
		(width 0.0889)
		(layer "In4.Cu")
		(net "M_D_CPU0_SB_DQ<5>")
	)
	(segment
		(start 294.900096 -289.239198)
		(end 295.1353 -289.239198)
		(width 0.14478)
		(layer "In4.Cu")
		(net "M_D_CPU0_SB_DQ<5>")
	)
	(segment
		(start 294.739568 -289.720782)
		(end 294.739568 -289.399726)
		(width 0.14478)
		(layer "In4.Cu")
		(net "M_D_CPU0_SB_DQ<5>")
	)
	(segment
		(start 323.97446 -277.83282)
		(end 324.469506 -277.83282)
		(width 0.0889)
		(layer "In4.Cu")
		(net "M_D_CPU0_SB_DQ<5>")
	)
	(segment
		(start 334.819752 -278.463502)
		(end 334.828134 -278.458676)
		(width 0.0889)
		(layer "In4.Cu")
		(net "M_D_CPU0_SB_DQ<5>")
	)
	(segment
		(start 286.481012 -289.351212)
		(end 286.481012 -289.769296)
		(width 0.14478)
		(layer "In4.Cu")
		(net "M_D_CPU0_SB_DQ<5>")
	)
	(segment
		(start 287.246314 -289.560254)
		(end 290.130738 -289.560254)
		(width 0.14478)
		(layer "In4.Cu")
		(net "M_D_CPU0_SB_DQ<5>")
	)
	(segment
		(start 296.858436 -289.17011)
		(end 297.02125 -289.332924)
		(width 0.14478)
		(layer "In4.Cu")
		(net "M_D_CPU0_SB_DQ<5>")
	)
	(segment
		(start 324.947788 -278.264112)
		(end 327.152508 -278.264112)
		(width 0.0889)
		(layer "In4.Cu")
		(net "M_D_CPU0_SB_DQ<5>")
	)
	(segment
		(start 296.23766 -289.560254)
		(end 296.627804 -289.17011)
		(width 0.14478)
		(layer "In4.Cu")
		(net "M_D_CPU0_SB_DQ<5>")
	)
	(segment
		(start 308.191154 -288.710116)
		(end 319.06845 -277.83282)
		(width 0.14478)
		(layer "In4.Cu")
		(net "M_D_CPU0_SB_DQ<5>")
	)
	(segment
		(start 294.526462 -289.933888)
		(end 294.739568 -289.720782)
		(width 0.14478)
		(layer "In4.Cu")
		(net "M_D_CPU0_SB_DQ<5>")
	)
	(segment
		(start 306.073048 -288.710116)
		(end 308.191154 -288.710116)
		(width 0.14478)
		(layer "In4.Cu")
		(net "M_D_CPU0_SB_DQ<5>")
	)
	(segment
		(start 301.01286 -288.710116)
		(end 301.862998 -289.560254)
		(width 0.14478)
		(layer "In4.Cu")
		(net "M_D_CPU0_SB_DQ<5>")
	)
	(segment
		(start 335.394046 -278.458676)
		(end 335.402428 -278.463502)
		(width 0.0889)
		(layer "In4.Cu")
		(net "M_D_CPU0_SB_DQ<5>")
	)
	(segment
		(start 286.643826 -289.93211)
		(end 286.874458 -289.93211)
		(width 0.14478)
		(layer "In4.Cu")
		(net "M_D_CPU0_SB_DQ<5>")
	)
	(segment
		(start 290.980876 -288.710116)
		(end 293.067232 -288.710116)
		(width 0.14478)
		(layer "In4.Cu")
		(net "M_D_CPU0_SB_DQ<5>")
	)
	(segment
		(start 286.481012 -289.769296)
		(end 286.643826 -289.93211)
		(width 0.14478)
		(layer "In4.Cu")
		(net "M_D_CPU0_SB_DQ<5>")
	)
	(segment
		(start 336.3341 -278.458676)
		(end 336.342482 -278.463502)
		(width 0.0889)
		(layer "In4.Cu")
		(net "M_D_CPU0_SB_DQ<5>")
	)
	(segment
		(start 294.739568 -289.399726)
		(end 294.900096 -289.239198)
		(width 0.14478)
		(layer "In4.Cu")
		(net "M_D_CPU0_SB_DQ<5>")
	)
	(segment
		(start 333.879698 -278.463502)
		(end 333.88808 -278.458676)
		(width 0.0889)
		(layer "In4.Cu")
		(net "M_D_CPU0_SB_DQ<5>")
	)
	(segment
		(start 324.469506 -277.83282)
		(end 324.867524 -278.230838)
		(width 0.0889)
		(layer "In4.Cu")
		(net "M_D_CPU0_SB_DQ<5>")
	)
	(segment
		(start 298.70146 -288.710116)
		(end 301.01286 -288.710116)
		(width 0.14478)
		(layer "In4.Cu")
		(net "M_D_CPU0_SB_DQ<5>")
	)
	(segment
		(start 330.119736 -278.463502)
		(end 330.128118 -278.458676)
		(width 0.0889)
		(layer "In4.Cu")
		(net "M_D_CPU0_SB_DQ<5>")
	)
	(segment
		(start 285.533084 -289.93211)
		(end 285.761938 -289.93211)
		(width 0.14478)
		(layer "In4.Cu")
		(net "M_D_CPU0_SB_DQ<5>")
	)
	(arc
		(start 338.588096 -278.458676)
		(mid 338.871052 -278.382499)
		(end 339.154008 -278.458676)
		(width 0.0889)
		(layer "In4.Cu")
		(net "M_D_CPU0_SB_DQ<5>")
	)
	(arc
		(start 335.768188 -278.458676)
		(mid 336.051144 -278.382499)
		(end 336.3341 -278.458676)
		(width 0.0889)
		(layer "In4.Cu")
		(net "M_D_CPU0_SB_DQ<5>")
	)
	(arc
		(start 340.102444 -278.463502)
		(mid 340.255314 -278.508143)
		(end 340.412832 -278.484838)
		(width 0.0889)
		(layer "In4.Cu")
		(net "M_D_CPU0_SB_DQ<5>")
	)
	(arc
		(start 336.708242 -278.458676)
		(mid 336.991198 -278.382499)
		(end 337.274154 -278.458676)
		(width 0.0889)
		(layer "In4.Cu")
		(net "M_D_CPU0_SB_DQ<5>")
	)
	(arc
		(start 339.52815 -278.458676)
		(mid 339.811106 -278.382499)
		(end 340.094062 -278.458676)
		(width 0.0889)
		(layer "In4.Cu")
		(net "M_D_CPU0_SB_DQ<5>")
	)
	(arc
		(start 330.702412 -278.463502)
		(mid 330.88592 -278.508996)
		(end 331.068172 -278.458676)
		(width 0.0889)
		(layer "In4.Cu")
		(net "M_D_CPU0_SB_DQ<5>")
	)
	(arc
		(start 334.828134 -278.458676)
		(mid 335.11109 -278.382499)
		(end 335.394046 -278.458676)
		(width 0.0889)
		(layer "In4.Cu")
		(net "M_D_CPU0_SB_DQ<5>")
	)
	(arc
		(start 333.88808 -278.458676)
		(mid 334.171036 -278.382499)
		(end 334.453992 -278.458676)
		(width 0.0889)
		(layer "In4.Cu")
		(net "M_D_CPU0_SB_DQ<5>")
	)
	(arc
		(start 332.008226 -278.458676)
		(mid 332.291182 -278.382499)
		(end 332.574138 -278.458676)
		(width 0.0889)
		(layer "In4.Cu")
		(net "M_D_CPU0_SB_DQ<5>")
	)
	(arc
		(start 337.274154 -278.458676)
		(mid 337.461098 -278.508931)
		(end 337.648042 -278.458676)
		(width 0.0889)
		(layer "In4.Cu")
		(net "M_D_CPU0_SB_DQ<5>")
	)
	(arc
		(start 324.867524 -278.230838)
		(mid 324.904335 -278.255498)
		(end 324.947788 -278.264112)
		(width 0.0889)
		(layer "In4.Cu")
		(net "M_D_CPU0_SB_DQ<5>")
	)
	(arc
		(start 327.152508 -278.264112)
		(mid 327.526083 -278.313597)
		(end 327.873868 -278.458676)
		(width 0.0889)
		(layer "In4.Cu")
		(net "M_D_CPU0_SB_DQ<5>")
	)
	(arc
		(start 329.188064 -278.458676)
		(mid 329.47102 -278.382499)
		(end 329.753976 -278.458676)
		(width 0.0889)
		(layer "In4.Cu")
		(net "M_D_CPU0_SB_DQ<5>")
	)
	(arc
		(start 338.213954 -278.458676)
		(mid 338.396205 -278.509026)
		(end 338.579714 -278.463502)
		(width 0.0889)
		(layer "In4.Cu")
		(net "M_D_CPU0_SB_DQ<5>")
	)
	(arc
		(start 336.342482 -278.463502)
		(mid 336.52599 -278.508996)
		(end 336.708242 -278.458676)
		(width 0.0889)
		(layer "In4.Cu")
		(net "M_D_CPU0_SB_DQ<5>")
	)
	(arc
		(start 337.648042 -278.458676)
		(mid 337.930998 -278.382499)
		(end 338.213954 -278.458676)
		(width 0.0889)
		(layer "In4.Cu")
		(net "M_D_CPU0_SB_DQ<5>")
	)
	(arc
		(start 335.402428 -278.463502)
		(mid 335.585936 -278.508996)
		(end 335.768188 -278.458676)
		(width 0.0889)
		(layer "In4.Cu")
		(net "M_D_CPU0_SB_DQ<5>")
	)
	(arc
		(start 327.873868 -278.458676)
		(mid 328.061066 -278.509058)
		(end 328.248264 -278.458676)
		(width 0.0889)
		(layer "In4.Cu")
		(net "M_D_CPU0_SB_DQ<5>")
	)
	(arc
		(start 332.574138 -278.458676)
		(mid 332.761082 -278.508931)
		(end 332.948026 -278.458676)
		(width 0.0889)
		(layer "In4.Cu")
		(net "M_D_CPU0_SB_DQ<5>")
	)
	(arc
		(start 339.154008 -278.458676)
		(mid 339.336259 -278.509026)
		(end 339.519768 -278.463502)
		(width 0.0889)
		(layer "In4.Cu")
		(net "M_D_CPU0_SB_DQ<5>")
	)
	(arc
		(start 331.642466 -278.463502)
		(mid 331.825974 -278.508996)
		(end 332.008226 -278.458676)
		(width 0.0889)
		(layer "In4.Cu")
		(net "M_D_CPU0_SB_DQ<5>")
	)
	(arc
		(start 332.948026 -278.458676)
		(mid 333.230982 -278.382499)
		(end 333.513938 -278.458676)
		(width 0.0889)
		(layer "In4.Cu")
		(net "M_D_CPU0_SB_DQ<5>")
	)
	(arc
		(start 331.068172 -278.458676)
		(mid 331.351128 -278.382499)
		(end 331.634084 -278.458676)
		(width 0.0889)
		(layer "In4.Cu")
		(net "M_D_CPU0_SB_DQ<5>")
	)
	(arc
		(start 329.753976 -278.458676)
		(mid 329.936227 -278.509026)
		(end 330.119736 -278.463502)
		(width 0.0889)
		(layer "In4.Cu")
		(net "M_D_CPU0_SB_DQ<5>")
	)
	(arc
		(start 328.814176 -278.458676)
		(mid 329.00112 -278.508931)
		(end 329.188064 -278.458676)
		(width 0.0889)
		(layer "In4.Cu")
		(net "M_D_CPU0_SB_DQ<5>")
	)
	(arc
		(start 334.453992 -278.458676)
		(mid 334.636243 -278.509026)
		(end 334.819752 -278.463502)
		(width 0.0889)
		(layer "In4.Cu")
		(net "M_D_CPU0_SB_DQ<5>")
	)
	(arc
		(start 328.248264 -278.458676)
		(mid 328.53122 -278.382499)
		(end 328.814176 -278.458676)
		(width 0.0889)
		(layer "In4.Cu")
		(net "M_D_CPU0_SB_DQ<5>")
	)
	(arc
		(start 330.128118 -278.458676)
		(mid 330.411074 -278.382499)
		(end 330.69403 -278.458676)
		(width 0.0889)
		(layer "In4.Cu")
		(net "M_D_CPU0_SB_DQ<5>")
	)
	(arc
		(start 333.513938 -278.458676)
		(mid 333.696189 -278.509026)
		(end 333.879698 -278.463502)
		(width 0.0889)
		(layer "In4.Cu")
		(net "M_D_CPU0_SB_DQ<5>")
	)
	(segment
		(start 339.337904 -277.060152)
		(end 338.871052 -277.32609)
		(width 0.10668)
		(layer "F.Cu")
		(net "M_D_CPU0_SB_DQ<4>")
	)
	(segment
		(start 304.07991 -287.860232)
		(end 304.373788 -288.15411)
		(width 0.14478)
		(layer "In4.Cu")
		(net "M_D_CPU0_SB_DQ<4>")
	)
	(segment
		(start 296.891456 -288.094928)
		(end 297.053 -288.256472)
		(width 0.14478)
		(layer "In4.Cu")
		(net "M_D_CPU0_SB_DQ<4>")
	)
	(segment
		(start 302.96739 -287.860232)
		(end 303.261268 -288.15411)
		(width 0.14478)
		(layer "In4.Cu")
		(net "M_D_CPU0_SB_DQ<4>")
	)
	(segment
		(start 303.261268 -288.15411)
		(end 303.52365 -288.15411)
		(width 0.14478)
		(layer "In4.Cu")
		(net "M_D_CPU0_SB_DQ<4>")
	)
	(segment
		(start 308.756812 -286.871918)
		(end 308.923436 -286.705294)
		(width 0.14478)
		(layer "In4.Cu")
		(net "M_D_CPU0_SB_DQ<4>")
	)
	(segment
		(start 303.817528 -287.860232)
		(end 304.07991 -287.860232)
		(width 0.14478)
		(layer "In4.Cu")
		(net "M_D_CPU0_SB_DQ<4>")
	)
	(segment
		(start 306.638706 -286.868616)
		(end 306.80025 -286.707072)
		(width 0.14478)
		(layer "In4.Cu")
		(net "M_D_CPU0_SB_DQ<4>")
	)
	(segment
		(start 300.618144 -287.019746)
		(end 301.45863 -287.860232)
		(width 0.14478)
		(layer "In4.Cu")
		(net "M_D_CPU0_SB_DQ<4>")
	)
	(segment
		(start 285.17088 -287.869884)
		(end 290.326826 -287.869884)
		(width 0.14478)
		(layer "In4.Cu")
		(net "M_D_CPU0_SB_DQ<4>")
	)
	(segment
		(start 326.500236 -277.699216)
		(end 326.650858 -277.699216)
		(width 0.0889)
		(layer "In4.Cu")
		(net "M_D_CPU0_SB_DQ<4>")
	)
	(segment
		(start 318.25819 -276.9235)
		(end 323.897244 -276.9235)
		(width 0.14478)
		(layer "In4.Cu")
		(net "M_D_CPU0_SB_DQ<4>")
	)
	(segment
		(start 310.484012 -285.144718)
		(end 310.484012 -284.697678)
		(width 0.14478)
		(layer "In4.Cu")
		(net "M_D_CPU0_SB_DQ<4>")
	)
	(segment
		(start 307.19014 -286.868616)
		(end 307.19014 -287.230566)
		(width 0.14478)
		(layer "In4.Cu")
		(net "M_D_CPU0_SB_DQ<4>")
	)
	(segment
		(start 312.9915 -282.19019)
		(end 313.43854 -282.19019)
		(width 0.14478)
		(layer "In4.Cu")
		(net "M_D_CPU0_SB_DQ<4>")
	)
	(segment
		(start 314.385452 -280.796238)
		(end 314.552076 -280.629614)
		(width 0.14478)
		(layer "In4.Cu")
		(net "M_D_CPU0_SB_DQ<4>")
	)
	(segment
		(start 324.314566 -276.9235)
		(end 324.509638 -277.118572)
		(width 0.0889)
		(layer "In4.Cu")
		(net "M_D_CPU0_SB_DQ<4>")
	)
	(segment
		(start 328.333608 -277.642574)
		(end 328.344022 -277.64867)
		(width 0.0889)
		(layer "In4.Cu")
		(net "M_D_CPU0_SB_DQ<4>")
	)
	(segment
		(start 314.218828 -281.409902)
		(end 314.385452 -281.243278)
		(width 0.14478)
		(layer "In4.Cu")
		(net "M_D_CPU0_SB_DQ<4>")
	)
	(segment
		(start 324.509638 -277.118572)
		(end 325.919592 -277.118572)
		(width 0.0889)
		(layer "In4.Cu")
		(net "M_D_CPU0_SB_DQ<4>")
	)
	(segment
		(start 310.317388 -285.311342)
		(end 310.484012 -285.144718)
		(width 0.14478)
		(layer "In4.Cu")
		(net "M_D_CPU0_SB_DQ<4>")
	)
	(segment
		(start 317.506604 -278.122126)
		(end 317.506604 -277.675086)
		(width 0.14478)
		(layer "In4.Cu")
		(net "M_D_CPU0_SB_DQ<4>")
	)
	(segment
		(start 302.148748 -288.15411)
		(end 302.41113 -288.15411)
		(width 0.14478)
		(layer "In4.Cu")
		(net "M_D_CPU0_SB_DQ<4>")
	)
	(segment
		(start 339.02523 -277.59152)
		(end 338.871052 -277.32609)
		(width 0.0889)
		(layer "In4.Cu")
		(net "M_D_CPU0_SB_DQ<4>")
	)
	(segment
		(start 315.16574 -280.46299)
		(end 315.16574 -280.01595)
		(width 0.14478)
		(layer "In4.Cu")
		(net "M_D_CPU0_SB_DQ<4>")
	)
	(segment
		(start 309.09006 -286.09163)
		(end 309.5371 -286.09163)
		(width 0.14478)
		(layer "In4.Cu")
		(net "M_D_CPU0_SB_DQ<4>")
	)
	(segment
		(start 301.85487 -287.860232)
		(end 302.148748 -288.15411)
		(width 0.14478)
		(layer "In4.Cu")
		(net "M_D_CPU0_SB_DQ<4>")
	)
	(segment
		(start 312.658252 -282.970478)
		(end 312.824876 -282.803854)
		(width 0.14478)
		(layer "In4.Cu")
		(net "M_D_CPU0_SB_DQ<4>")
	)
	(segment
		(start 311.430924 -283.750766)
		(end 311.877964 -283.750766)
		(width 0.14478)
		(layer "In4.Cu")
		(net "M_D_CPU0_SB_DQ<4>")
	)
	(segment
		(start 328.709782 -277.653496)
		(end 328.718164 -277.64867)
		(width 0.0889)
		(layer "In4.Cu")
		(net "M_D_CPU0_SB_DQ<4>")
	)
	(segment
		(start 306.477162 -287.39211)
		(end 306.638706 -287.230566)
		(width 0.14478)
		(layer "In4.Cu")
		(net "M_D_CPU0_SB_DQ<4>")
	)
	(segment
		(start 302.41113 -288.15411)
		(end 302.705008 -287.860232)
		(width 0.14478)
		(layer "In4.Cu")
		(net "M_D_CPU0_SB_DQ<4>")
	)
	(segment
		(start 307.351684 -287.39211)
		(end 307.78958 -287.39211)
		(width 0.14478)
		(layer "In4.Cu")
		(net "M_D_CPU0_SB_DQ<4>")
	)
	(segment
		(start 298.048426 -287.869884)
		(end 298.898564 -287.019746)
		(width 0.14478)
		(layer "In4.Cu")
		(net "M_D_CPU0_SB_DQ<4>")
	)
	(segment
		(start 306.638706 -287.230566)
		(end 306.638706 -286.868616)
		(width 0.14478)
		(layer "In4.Cu")
		(net "M_D_CPU0_SB_DQ<4>")
	)
	(segment
		(start 315.332364 -279.849326)
		(end 315.779404 -279.849326)
		(width 0.14478)
		(layer "In4.Cu")
		(net "M_D_CPU0_SB_DQ<4>")
	)
	(segment
		(start 312.824876 -282.803854)
		(end 312.824876 -282.356814)
		(width 0.14478)
		(layer "In4.Cu")
		(net "M_D_CPU0_SB_DQ<4>")
	)
	(segment
		(start 297.281346 -288.256472)
		(end 297.44289 -288.094928)
		(width 0.14478)
		(layer "In4.Cu")
		(net "M_D_CPU0_SB_DQ<4>")
	)
	(segment
		(start 302.705008 -287.860232)
		(end 302.96739 -287.860232)
		(width 0.14478)
		(layer "In4.Cu")
		(net "M_D_CPU0_SB_DQ<4>")
	)
	(segment
		(start 316.112652 -279.069038)
		(end 316.559692 -279.069038)
		(width 0.14478)
		(layer "In4.Cu")
		(net "M_D_CPU0_SB_DQ<4>")
	)
	(segment
		(start 315.946028 -279.235662)
		(end 316.112652 -279.069038)
		(width 0.14478)
		(layer "In4.Cu")
		(net "M_D_CPU0_SB_DQ<4>")
	)
	(segment
		(start 313.605164 -282.023566)
		(end 313.605164 -281.576526)
		(width 0.14478)
		(layer "In4.Cu")
		(net "M_D_CPU0_SB_DQ<4>")
	)
	(segment
		(start 312.044588 -283.584142)
		(end 312.044588 -283.137102)
		(width 0.14478)
		(layer "In4.Cu")
		(net "M_D_CPU0_SB_DQ<4>")
	)
	(segment
		(start 297.604434 -287.869884)
		(end 298.048426 -287.869884)
		(width 0.14478)
		(layer "In4.Cu")
		(net "M_D_CPU0_SB_DQ<4>")
	)
	(segment
		(start 333.044038 -277.64867)
		(end 333.05242 -277.653496)
		(width 0.0889)
		(layer "In4.Cu")
		(net "M_D_CPU0_SB_DQ<4>")
	)
	(segment
		(start 333.984092 -277.64867)
		(end 333.992474 -277.653496)
		(width 0.0889)
		(layer "In4.Cu")
		(net "M_D_CPU0_SB_DQ<4>")
	)
	(segment
		(start 305.576478 -287.860232)
		(end 306.0446 -287.39211)
		(width 0.14478)
		(layer "In4.Cu")
		(net "M_D_CPU0_SB_DQ<4>")
	)
	(segment
		(start 310.484012 -284.697678)
		(end 310.650636 -284.531054)
		(width 0.14478)
		(layer "In4.Cu")
		(net "M_D_CPU0_SB_DQ<4>")
	)
	(segment
		(start 308.923436 -286.258254)
		(end 309.09006 -286.09163)
		(width 0.14478)
		(layer "In4.Cu")
		(net "M_D_CPU0_SB_DQ<4>")
	)
	(segment
		(start 339.002878 -277.674832)
		(end 339.02523 -277.59152)
		(width 0.0889)
		(layer "In4.Cu")
		(net "M_D_CPU0_SB_DQ<4>")
	)
	(segment
		(start 313.605164 -281.576526)
		(end 313.771788 -281.409902)
		(width 0.14478)
		(layer "In4.Cu")
		(net "M_D_CPU0_SB_DQ<4>")
	)
	(segment
		(start 311.877964 -283.750766)
		(end 312.044588 -283.584142)
		(width 0.14478)
		(layer "In4.Cu")
		(net "M_D_CPU0_SB_DQ<4>")
	)
	(segment
		(start 332.469744 -277.653496)
		(end 332.478126 -277.64867)
		(width 0.0889)
		(layer "In4.Cu")
		(net "M_D_CPU0_SB_DQ<4>")
	)
	(segment
		(start 326.837802 -277.648416)
		(end 326.84339 -277.645114)
		(width 0.0889)
		(layer "In4.Cu")
		(net "M_D_CPU0_SB_DQ<4>")
	)
	(segment
		(start 304.930048 -287.860232)
		(end 305.576478 -287.860232)
		(width 0.14478)
		(layer "In4.Cu")
		(net "M_D_CPU0_SB_DQ<4>")
	)
	(segment
		(start 297.053 -288.256472)
		(end 297.281346 -288.256472)
		(width 0.14478)
		(layer "In4.Cu")
		(net "M_D_CPU0_SB_DQ<4>")
	)
	(segment
		(start 293.848282 -287.869884)
		(end 296.729912 -287.869884)
		(width 0.14478)
		(layer "In4.Cu")
		(net "M_D_CPU0_SB_DQ<4>")
	)
	(segment
		(start 290.326826 -287.869884)
		(end 291.176964 -287.019746)
		(width 0.14478)
		(layer "In4.Cu")
		(net "M_D_CPU0_SB_DQ<4>")
	)
	(segment
		(start 296.729912 -287.869884)
		(end 296.891456 -288.031428)
		(width 0.14478)
		(layer "In4.Cu")
		(net "M_D_CPU0_SB_DQ<4>")
	)
	(segment
		(start 316.89294 -278.28875)
		(end 317.33998 -278.28875)
		(width 0.14478)
		(layer "In4.Cu")
		(net "M_D_CPU0_SB_DQ<4>")
	)
	(segment
		(start 311.097676 -284.531054)
		(end 311.2643 -284.36443)
		(width 0.14478)
		(layer "In4.Cu")
		(net "M_D_CPU0_SB_DQ<4>")
	)
	(segment
		(start 314.552076 -280.629614)
		(end 314.999116 -280.629614)
		(width 0.14478)
		(layer "In4.Cu")
		(net "M_D_CPU0_SB_DQ<4>")
	)
	(segment
		(start 292.998144 -287.019746)
		(end 293.848282 -287.869884)
		(width 0.14478)
		(layer "In4.Cu")
		(net "M_D_CPU0_SB_DQ<4>")
	)
	(segment
		(start 311.2643 -284.36443)
		(end 311.2643 -283.91739)
		(width 0.14478)
		(layer "In4.Cu")
		(net "M_D_CPU0_SB_DQ<4>")
	)
	(segment
		(start 314.999116 -280.629614)
		(end 315.16574 -280.46299)
		(width 0.14478)
		(layer "In4.Cu")
		(net "M_D_CPU0_SB_DQ<4>")
	)
	(segment
		(start 310.650636 -284.531054)
		(end 311.097676 -284.531054)
		(width 0.14478)
		(layer "In4.Cu")
		(net "M_D_CPU0_SB_DQ<4>")
	)
	(segment
		(start 327.403206 -277.64867)
		(end 327.411588 -277.653496)
		(width 0.0889)
		(layer "In4.Cu")
		(net "M_D_CPU0_SB_DQ<4>")
	)
	(segment
		(start 301.45863 -287.860232)
		(end 301.85487 -287.860232)
		(width 0.14478)
		(layer "In4.Cu")
		(net "M_D_CPU0_SB_DQ<4>")
	)
	(segment
		(start 297.44289 -288.094928)
		(end 297.44289 -288.031428)
		(width 0.14478)
		(layer "In4.Cu")
		(net "M_D_CPU0_SB_DQ<4>")
	)
	(segment
		(start 298.898564 -287.019746)
		(end 300.618144 -287.019746)
		(width 0.14478)
		(layer "In4.Cu")
		(net "M_D_CPU0_SB_DQ<4>")
	)
	(segment
		(start 306.80025 -286.707072)
		(end 307.028596 -286.707072)
		(width 0.14478)
		(layer "In4.Cu")
		(net "M_D_CPU0_SB_DQ<4>")
	)
	(segment
		(start 304.63617 -288.15411)
		(end 304.930048 -287.860232)
		(width 0.14478)
		(layer "In4.Cu")
		(net "M_D_CPU0_SB_DQ<4>")
	)
	(segment
		(start 309.5371 -286.09163)
		(end 309.703724 -285.925006)
		(width 0.14478)
		(layer "In4.Cu")
		(net "M_D_CPU0_SB_DQ<4>")
	)
	(segment
		(start 307.028596 -286.707072)
		(end 307.19014 -286.868616)
		(width 0.14478)
		(layer "In4.Cu")
		(net "M_D_CPU0_SB_DQ<4>")
	)
	(segment
		(start 337.16976 -277.653496)
		(end 337.178142 -277.64867)
		(width 0.0889)
		(layer "In4.Cu")
		(net "M_D_CPU0_SB_DQ<4>")
	)
	(segment
		(start 315.946028 -279.682702)
		(end 315.946028 -279.235662)
		(width 0.14478)
		(layer "In4.Cu")
		(net "M_D_CPU0_SB_DQ<4>")
	)
	(segment
		(start 307.78958 -287.39211)
		(end 308.309772 -286.871918)
		(width 0.14478)
		(layer "In4.Cu")
		(net "M_D_CPU0_SB_DQ<4>")
	)
	(segment
		(start 304.373788 -288.15411)
		(end 304.63617 -288.15411)
		(width 0.14478)
		(layer "In4.Cu")
		(net "M_D_CPU0_SB_DQ<4>")
	)
	(segment
		(start 329.284076 -277.64867)
		(end 329.292458 -277.653496)
		(width 0.0889)
		(layer "In4.Cu")
		(net "M_D_CPU0_SB_DQ<4>")
	)
	(segment
		(start 309.703724 -285.477966)
		(end 309.870348 -285.311342)
		(width 0.14478)
		(layer "In4.Cu")
		(net "M_D_CPU0_SB_DQ<4>")
	)
	(segment
		(start 291.176964 -287.019746)
		(end 292.998144 -287.019746)
		(width 0.14478)
		(layer "In4.Cu")
		(net "M_D_CPU0_SB_DQ<4>")
	)
	(segment
		(start 313.771788 -281.409902)
		(end 314.218828 -281.409902)
		(width 0.14478)
		(layer "In4.Cu")
		(net "M_D_CPU0_SB_DQ<4>")
	)
	(segment
		(start 296.891456 -288.031428)
		(end 296.891456 -288.094928)
		(width 0.14478)
		(layer "In4.Cu")
		(net "M_D_CPU0_SB_DQ<4>")
	)
	(segment
		(start 309.870348 -285.311342)
		(end 310.317388 -285.311342)
		(width 0.14478)
		(layer "In4.Cu")
		(net "M_D_CPU0_SB_DQ<4>")
	)
	(segment
		(start 317.506604 -277.675086)
		(end 318.25819 -276.9235)
		(width 0.14478)
		(layer "In4.Cu")
		(net "M_D_CPU0_SB_DQ<4>")
	)
	(segment
		(start 307.19014 -287.230566)
		(end 307.351684 -287.39211)
		(width 0.14478)
		(layer "In4.Cu")
		(net "M_D_CPU0_SB_DQ<4>")
	)
	(segment
		(start 312.211212 -282.970478)
		(end 312.658252 -282.970478)
		(width 0.14478)
		(layer "In4.Cu")
		(net "M_D_CPU0_SB_DQ<4>")
	)
	(segment
		(start 314.385452 -281.243278)
		(end 314.385452 -280.796238)
		(width 0.14478)
		(layer "In4.Cu")
		(net "M_D_CPU0_SB_DQ<4>")
	)
	(segment
		(start 315.779404 -279.849326)
		(end 315.946028 -279.682702)
		(width 0.14478)
		(layer "In4.Cu")
		(net "M_D_CPU0_SB_DQ<4>")
	)
	(segment
		(start 308.309772 -286.871918)
		(end 308.756812 -286.871918)
		(width 0.14478)
		(layer "In4.Cu")
		(net "M_D_CPU0_SB_DQ<4>")
	)
	(segment
		(start 313.43854 -282.19019)
		(end 313.605164 -282.023566)
		(width 0.14478)
		(layer "In4.Cu")
		(net "M_D_CPU0_SB_DQ<4>")
	)
	(segment
		(start 331.52969 -277.653496)
		(end 331.538072 -277.64867)
		(width 0.0889)
		(layer "In4.Cu")
		(net "M_D_CPU0_SB_DQ<4>")
	)
	(segment
		(start 338.684108 -277.64867)
		(end 338.69249 -277.653496)
		(width 0.0889)
		(layer "In4.Cu")
		(net "M_D_CPU0_SB_DQ<4>")
	)
	(segment
		(start 312.044588 -283.137102)
		(end 312.211212 -282.970478)
		(width 0.14478)
		(layer "In4.Cu")
		(net "M_D_CPU0_SB_DQ<4>")
	)
	(segment
		(start 315.16574 -280.01595)
		(end 315.332364 -279.849326)
		(width 0.14478)
		(layer "In4.Cu")
		(net "M_D_CPU0_SB_DQ<4>")
	)
	(segment
		(start 303.52365 -288.15411)
		(end 303.817528 -287.860232)
		(width 0.14478)
		(layer "In4.Cu")
		(net "M_D_CPU0_SB_DQ<4>")
	)
	(segment
		(start 323.897244 -276.9235)
		(end 324.314566 -276.9235)
		(width 0.0889)
		(layer "In4.Cu")
		(net "M_D_CPU0_SB_DQ<4>")
	)
	(segment
		(start 316.559692 -279.069038)
		(end 316.726316 -278.902414)
		(width 0.14478)
		(layer "In4.Cu")
		(net "M_D_CPU0_SB_DQ<4>")
	)
	(segment
		(start 308.923436 -286.705294)
		(end 308.923436 -286.258254)
		(width 0.14478)
		(layer "In4.Cu")
		(net "M_D_CPU0_SB_DQ<4>")
	)
	(segment
		(start 316.726316 -278.455374)
		(end 316.89294 -278.28875)
		(width 0.14478)
		(layer "In4.Cu")
		(net "M_D_CPU0_SB_DQ<4>")
	)
	(segment
		(start 306.0446 -287.39211)
		(end 306.477162 -287.39211)
		(width 0.14478)
		(layer "In4.Cu")
		(net "M_D_CPU0_SB_DQ<4>")
	)
	(segment
		(start 337.744054 -277.64867)
		(end 337.752436 -277.653496)
		(width 0.0889)
		(layer "In4.Cu")
		(net "M_D_CPU0_SB_DQ<4>")
	)
	(segment
		(start 317.33998 -278.28875)
		(end 317.506604 -278.122126)
		(width 0.14478)
		(layer "In4.Cu")
		(net "M_D_CPU0_SB_DQ<4>")
	)
	(segment
		(start 309.703724 -285.925006)
		(end 309.703724 -285.477966)
		(width 0.14478)
		(layer "In4.Cu")
		(net "M_D_CPU0_SB_DQ<4>")
	)
	(segment
		(start 284.736032 -287.435036)
		(end 285.17088 -287.869884)
		(width 0.14478)
		(layer "In4.Cu")
		(net "M_D_CPU0_SB_DQ<4>")
	)
	(segment
		(start 325.919592 -277.118572)
		(end 326.500236 -277.699216)
		(width 0.0889)
		(layer "In4.Cu")
		(net "M_D_CPU0_SB_DQ<4>")
	)
	(segment
		(start 312.824876 -282.356814)
		(end 312.9915 -282.19019)
		(width 0.14478)
		(layer "In4.Cu")
		(net "M_D_CPU0_SB_DQ<4>")
	)
	(segment
		(start 311.2643 -283.91739)
		(end 311.430924 -283.750766)
		(width 0.14478)
		(layer "In4.Cu")
		(net "M_D_CPU0_SB_DQ<4>")
	)
	(segment
		(start 297.44289 -288.031428)
		(end 297.604434 -287.869884)
		(width 0.14478)
		(layer "In4.Cu")
		(net "M_D_CPU0_SB_DQ<4>")
	)
	(segment
		(start 316.726316 -278.902414)
		(end 316.726316 -278.455374)
		(width 0.14478)
		(layer "In4.Cu")
		(net "M_D_CPU0_SB_DQ<4>")
	)
	(segment
		(start 336.229706 -277.653496)
		(end 336.238088 -277.64867)
		(width 0.0889)
		(layer "In4.Cu")
		(net "M_D_CPU0_SB_DQ<4>")
	)
	(arc
		(start 334.358234 -277.64867)
		(mid 334.64119 -277.572493)
		(end 334.924146 -277.64867)
		(width 0.0889)
		(layer "In4.Cu")
		(net "M_D_CPU0_SB_DQ<4>")
	)
	(arc
		(start 336.804 -277.64867)
		(mid 336.986251 -277.69902)
		(end 337.16976 -277.653496)
		(width 0.0889)
		(layer "In4.Cu")
		(net "M_D_CPU0_SB_DQ<4>")
	)
	(arc
		(start 334.924146 -277.64867)
		(mid 335.11109 -277.698925)
		(end 335.298034 -277.64867)
		(width 0.0889)
		(layer "In4.Cu")
		(net "M_D_CPU0_SB_DQ<4>")
	)
	(arc
		(start 329.292458 -277.653496)
		(mid 329.475966 -277.69899)
		(end 329.658218 -277.64867)
		(width 0.0889)
		(layer "In4.Cu")
		(net "M_D_CPU0_SB_DQ<4>")
	)
	(arc
		(start 331.538072 -277.64867)
		(mid 331.821028 -277.572493)
		(end 332.103984 -277.64867)
		(width 0.0889)
		(layer "In4.Cu")
		(net "M_D_CPU0_SB_DQ<4>")
	)
	(arc
		(start 330.22413 -277.64867)
		(mid 330.411074 -277.698925)
		(end 330.598018 -277.64867)
		(width 0.0889)
		(layer "In4.Cu")
		(net "M_D_CPU0_SB_DQ<4>")
	)
	(arc
		(start 333.05242 -277.653496)
		(mid 333.235928 -277.69899)
		(end 333.41818 -277.64867)
		(width 0.0889)
		(layer "In4.Cu")
		(net "M_D_CPU0_SB_DQ<4>")
	)
	(arc
		(start 335.863946 -277.64867)
		(mid 336.046197 -277.69902)
		(end 336.229706 -277.653496)
		(width 0.0889)
		(layer "In4.Cu")
		(net "M_D_CPU0_SB_DQ<4>")
	)
	(arc
		(start 333.41818 -277.64867)
		(mid 333.701136 -277.572493)
		(end 333.984092 -277.64867)
		(width 0.0889)
		(layer "In4.Cu")
		(net "M_D_CPU0_SB_DQ<4>")
	)
	(arc
		(start 337.178142 -277.64867)
		(mid 337.461098 -277.572493)
		(end 337.744054 -277.64867)
		(width 0.0889)
		(layer "In4.Cu")
		(net "M_D_CPU0_SB_DQ<4>")
	)
	(arc
		(start 333.992474 -277.653496)
		(mid 334.175982 -277.69899)
		(end 334.358234 -277.64867)
		(width 0.0889)
		(layer "In4.Cu")
		(net "M_D_CPU0_SB_DQ<4>")
	)
	(arc
		(start 338.69249 -277.653496)
		(mid 338.84536 -277.698137)
		(end 339.002878 -277.674832)
		(width 0.0889)
		(layer "In4.Cu")
		(net "M_D_CPU0_SB_DQ<4>")
	)
	(arc
		(start 338.118196 -277.64867)
		(mid 338.401152 -277.572493)
		(end 338.684108 -277.64867)
		(width 0.0889)
		(layer "In4.Cu")
		(net "M_D_CPU0_SB_DQ<4>")
	)
	(arc
		(start 327.777856 -277.64867)
		(mid 328.054923 -277.572399)
		(end 328.333608 -277.642574)
		(width 0.0889)
		(layer "In4.Cu")
		(net "M_D_CPU0_SB_DQ<4>")
	)
	(arc
		(start 335.298034 -277.64867)
		(mid 335.58099 -277.572493)
		(end 335.863946 -277.64867)
		(width 0.0889)
		(layer "In4.Cu")
		(net "M_D_CPU0_SB_DQ<4>")
	)
	(arc
		(start 328.718164 -277.64867)
		(mid 329.00112 -277.572493)
		(end 329.284076 -277.64867)
		(width 0.0889)
		(layer "In4.Cu")
		(net "M_D_CPU0_SB_DQ<4>")
	)
	(arc
		(start 327.411588 -277.653496)
		(mid 327.59535 -277.699112)
		(end 327.777856 -277.64867)
		(width 0.0889)
		(layer "In4.Cu")
		(net "M_D_CPU0_SB_DQ<4>")
	)
	(arc
		(start 331.16393 -277.64867)
		(mid 331.346181 -277.69902)
		(end 331.52969 -277.653496)
		(width 0.0889)
		(layer "In4.Cu")
		(net "M_D_CPU0_SB_DQ<4>")
	)
	(arc
		(start 337.752436 -277.653496)
		(mid 337.935944 -277.69899)
		(end 338.118196 -277.64867)
		(width 0.0889)
		(layer "In4.Cu")
		(net "M_D_CPU0_SB_DQ<4>")
	)
	(arc
		(start 329.658218 -277.64867)
		(mid 329.941174 -277.572493)
		(end 330.22413 -277.64867)
		(width 0.0889)
		(layer "In4.Cu")
		(net "M_D_CPU0_SB_DQ<4>")
	)
	(arc
		(start 336.238088 -277.64867)
		(mid 336.521044 -277.572493)
		(end 336.804 -277.64867)
		(width 0.0889)
		(layer "In4.Cu")
		(net "M_D_CPU0_SB_DQ<4>")
	)
	(arc
		(start 332.478126 -277.64867)
		(mid 332.761082 -277.572493)
		(end 333.044038 -277.64867)
		(width 0.0889)
		(layer "In4.Cu")
		(net "M_D_CPU0_SB_DQ<4>")
	)
	(arc
		(start 332.103984 -277.64867)
		(mid 332.286235 -277.69902)
		(end 332.469744 -277.653496)
		(width 0.0889)
		(layer "In4.Cu")
		(net "M_D_CPU0_SB_DQ<4>")
	)
	(arc
		(start 326.84339 -277.645114)
		(mid 327.123779 -277.572445)
		(end 327.403206 -277.64867)
		(width 0.0889)
		(layer "In4.Cu")
		(net "M_D_CPU0_SB_DQ<4>")
	)
	(arc
		(start 330.598018 -277.64867)
		(mid 330.880974 -277.572493)
		(end 331.16393 -277.64867)
		(width 0.0889)
		(layer "In4.Cu")
		(net "M_D_CPU0_SB_DQ<4>")
	)
	(arc
		(start 326.650858 -277.699216)
		(mid 326.747676 -277.686145)
		(end 326.837802 -277.648416)
		(width 0.0889)
		(layer "In4.Cu")
		(net "M_D_CPU0_SB_DQ<4>")
	)
	(arc
		(start 328.344022 -277.64867)
		(mid 328.526273 -277.69902)
		(end 328.709782 -277.653496)
		(width 0.0889)
		(layer "In4.Cu")
		(net "M_D_CPU0_SB_DQ<4>")
	)
	(segment
		(start 341.218012 -275.44014)
		(end 340.75116 -275.706078)
		(width 0.10668)
		(layer "F.Cu")
		(net "M_D_CPU0_SB_DQ<3>")
	)
	(segment
		(start 294.492172 -284.450282)
		(end 297.353736 -284.450282)
		(width 0.14478)
		(layer "In4.Cu")
		(net "M_D_CPU0_SB_DQ<3>")
	)
	(segment
		(start 340.596982 -275.440648)
		(end 340.75116 -275.706078)
		(width 0.0889)
		(layer "In4.Cu")
		(net "M_D_CPU0_SB_DQ<3>")
	)
	(segment
		(start 293.642288 -283.600398)
		(end 294.492172 -284.450282)
		(width 0.14478)
		(layer "In4.Cu")
		(net "M_D_CPU0_SB_DQ<3>")
	)
	(segment
		(start 328.709782 -275.378672)
		(end 328.718164 -275.383498)
		(width 0.0889)
		(layer "In4.Cu")
		(net "M_D_CPU0_SB_DQ<3>")
	)
	(segment
		(start 324.311518 -274.58416)
		(end 324.42531 -274.58416)
		(width 0.0889)
		(layer "In4.Cu")
		(net "M_D_CPU0_SB_DQ<3>")
	)
	(segment
		(start 298.20362 -283.600398)
		(end 300.996604 -283.600398)
		(width 0.14478)
		(layer "In4.Cu")
		(net "M_D_CPU0_SB_DQ<3>")
	)
	(segment
		(start 301.460916 -284.06471)
		(end 305.283108 -284.06471)
		(width 0.14478)
		(layer "In4.Cu")
		(net "M_D_CPU0_SB_DQ<3>")
	)
	(segment
		(start 280.635964 -284.034992)
		(end 281.051254 -284.450282)
		(width 0.14478)
		(layer "In4.Cu")
		(net "M_D_CPU0_SB_DQ<3>")
	)
	(segment
		(start 324.768718 -274.240752)
		(end 325.248778 -274.240752)
		(width 0.0889)
		(layer "In4.Cu")
		(net "M_D_CPU0_SB_DQ<3>")
	)
	(segment
		(start 328.32929 -275.392134)
		(end 328.344022 -275.383498)
		(width 0.0889)
		(layer "In4.Cu")
		(net "M_D_CPU0_SB_DQ<3>")
	)
	(segment
		(start 340.500716 -275.415248)
		(end 340.596982 -275.440648)
		(width 0.0889)
		(layer "In4.Cu")
		(net "M_D_CPU0_SB_DQ<3>")
	)
	(segment
		(start 333.984092 -275.383498)
		(end 333.992474 -275.378672)
		(width 0.0889)
		(layer "In4.Cu")
		(net "M_D_CPU0_SB_DQ<3>")
	)
	(segment
		(start 289.733736 -284.450282)
		(end 290.58362 -283.600398)
		(width 0.14478)
		(layer "In4.Cu")
		(net "M_D_CPU0_SB_DQ<3>")
	)
	(segment
		(start 307.316886 -283.61005)
		(end 316.342776 -274.58416)
		(width 0.14478)
		(layer "In4.Cu")
		(net "M_D_CPU0_SB_DQ<3>")
	)
	(segment
		(start 332.469744 -275.378672)
		(end 332.478126 -275.383498)
		(width 0.0889)
		(layer "In4.Cu")
		(net "M_D_CPU0_SB_DQ<3>")
	)
	(segment
		(start 337.744054 -275.383498)
		(end 337.752436 -275.378672)
		(width 0.0889)
		(layer "In4.Cu")
		(net "M_D_CPU0_SB_DQ<3>")
	)
	(segment
		(start 325.248778 -274.240752)
		(end 326.340724 -275.332698)
		(width 0.0889)
		(layer "In4.Cu")
		(net "M_D_CPU0_SB_DQ<3>")
	)
	(segment
		(start 333.044038 -275.383498)
		(end 333.05242 -275.378672)
		(width 0.0889)
		(layer "In4.Cu")
		(net "M_D_CPU0_SB_DQ<3>")
	)
	(segment
		(start 300.996604 -283.600398)
		(end 301.460916 -284.06471)
		(width 0.14478)
		(layer "In4.Cu")
		(net "M_D_CPU0_SB_DQ<3>")
	)
	(segment
		(start 336.229706 -275.378672)
		(end 336.238088 -275.383498)
		(width 0.0889)
		(layer "In4.Cu")
		(net "M_D_CPU0_SB_DQ<3>")
	)
	(segment
		(start 331.52969 -275.378672)
		(end 331.538072 -275.383498)
		(width 0.0889)
		(layer "In4.Cu")
		(net "M_D_CPU0_SB_DQ<3>")
	)
	(segment
		(start 281.051254 -284.450282)
		(end 289.733736 -284.450282)
		(width 0.14478)
		(layer "In4.Cu")
		(net "M_D_CPU0_SB_DQ<3>")
	)
	(segment
		(start 329.284076 -275.383498)
		(end 329.292458 -275.378672)
		(width 0.0889)
		(layer "In4.Cu")
		(net "M_D_CPU0_SB_DQ<3>")
	)
	(segment
		(start 324.42531 -274.58416)
		(end 324.768718 -274.240752)
		(width 0.0889)
		(layer "In4.Cu")
		(net "M_D_CPU0_SB_DQ<3>")
	)
	(segment
		(start 305.737768 -283.61005)
		(end 307.316886 -283.61005)
		(width 0.14478)
		(layer "In4.Cu")
		(net "M_D_CPU0_SB_DQ<3>")
	)
	(segment
		(start 290.58362 -283.600398)
		(end 293.642288 -283.600398)
		(width 0.14478)
		(layer "In4.Cu")
		(net "M_D_CPU0_SB_DQ<3>")
	)
	(segment
		(start 326.340724 -275.332698)
		(end 327.589896 -275.332698)
		(width 0.0889)
		(layer "In4.Cu")
		(net "M_D_CPU0_SB_DQ<3>")
	)
	(segment
		(start 297.353736 -284.450282)
		(end 298.20362 -283.600398)
		(width 0.14478)
		(layer "In4.Cu")
		(net "M_D_CPU0_SB_DQ<3>")
	)
	(segment
		(start 338.684108 -275.383498)
		(end 338.69249 -275.378672)
		(width 0.0889)
		(layer "In4.Cu")
		(net "M_D_CPU0_SB_DQ<3>")
	)
	(segment
		(start 316.342776 -274.58416)
		(end 324.311518 -274.58416)
		(width 0.14478)
		(layer "In4.Cu")
		(net "M_D_CPU0_SB_DQ<3>")
	)
	(segment
		(start 337.16976 -275.378672)
		(end 337.178142 -275.383498)
		(width 0.0889)
		(layer "In4.Cu")
		(net "M_D_CPU0_SB_DQ<3>")
	)
	(segment
		(start 305.283108 -284.06471)
		(end 305.737768 -283.61005)
		(width 0.14478)
		(layer "In4.Cu")
		(net "M_D_CPU0_SB_DQ<3>")
	)
	(arc
		(start 337.178142 -275.383498)
		(mid 337.461098 -275.459675)
		(end 337.744054 -275.383498)
		(width 0.0889)
		(layer "In4.Cu")
		(net "M_D_CPU0_SB_DQ<3>")
	)
	(arc
		(start 329.292458 -275.378672)
		(mid 329.475966 -275.333178)
		(end 329.658218 -275.383498)
		(width 0.0889)
		(layer "In4.Cu")
		(net "M_D_CPU0_SB_DQ<3>")
	)
	(arc
		(start 333.992474 -275.378672)
		(mid 334.175982 -275.333178)
		(end 334.358234 -275.383498)
		(width 0.0889)
		(layer "In4.Cu")
		(net "M_D_CPU0_SB_DQ<3>")
	)
	(arc
		(start 336.238088 -275.383498)
		(mid 336.521044 -275.459675)
		(end 336.804 -275.383498)
		(width 0.0889)
		(layer "In4.Cu")
		(net "M_D_CPU0_SB_DQ<3>")
	)
	(arc
		(start 327.589896 -275.332698)
		(mid 327.687121 -275.345647)
		(end 327.777602 -275.383498)
		(width 0.0889)
		(layer "In4.Cu")
		(net "M_D_CPU0_SB_DQ<3>")
	)
	(arc
		(start 334.924146 -275.383498)
		(mid 335.11109 -275.333243)
		(end 335.298034 -275.383498)
		(width 0.0889)
		(layer "In4.Cu")
		(net "M_D_CPU0_SB_DQ<3>")
	)
	(arc
		(start 334.358234 -275.383498)
		(mid 334.64119 -275.459675)
		(end 334.924146 -275.383498)
		(width 0.0889)
		(layer "In4.Cu")
		(net "M_D_CPU0_SB_DQ<3>")
	)
	(arc
		(start 333.41818 -275.383498)
		(mid 333.701136 -275.459675)
		(end 333.984092 -275.383498)
		(width 0.0889)
		(layer "In4.Cu")
		(net "M_D_CPU0_SB_DQ<3>")
	)
	(arc
		(start 336.804 -275.383498)
		(mid 336.986251 -275.333148)
		(end 337.16976 -275.378672)
		(width 0.0889)
		(layer "In4.Cu")
		(net "M_D_CPU0_SB_DQ<3>")
	)
	(arc
		(start 339.05825 -275.383498)
		(mid 339.341206 -275.459675)
		(end 339.624162 -275.383498)
		(width 0.0889)
		(layer "In4.Cu")
		(net "M_D_CPU0_SB_DQ<3>")
	)
	(arc
		(start 330.22413 -275.383498)
		(mid 330.411074 -275.333243)
		(end 330.598018 -275.383498)
		(width 0.0889)
		(layer "In4.Cu")
		(net "M_D_CPU0_SB_DQ<3>")
	)
	(arc
		(start 335.863946 -275.383498)
		(mid 336.046197 -275.333148)
		(end 336.229706 -275.378672)
		(width 0.0889)
		(layer "In4.Cu")
		(net "M_D_CPU0_SB_DQ<3>")
	)
	(arc
		(start 332.478126 -275.383498)
		(mid 332.761082 -275.459675)
		(end 333.044038 -275.383498)
		(width 0.0889)
		(layer "In4.Cu")
		(net "M_D_CPU0_SB_DQ<3>")
	)
	(arc
		(start 328.344022 -275.383498)
		(mid 328.526273 -275.333148)
		(end 328.709782 -275.378672)
		(width 0.0889)
		(layer "In4.Cu")
		(net "M_D_CPU0_SB_DQ<3>")
	)
	(arc
		(start 328.718164 -275.383498)
		(mid 329.00112 -275.459675)
		(end 329.284076 -275.383498)
		(width 0.0889)
		(layer "In4.Cu")
		(net "M_D_CPU0_SB_DQ<3>")
	)
	(arc
		(start 338.69249 -275.378672)
		(mid 338.875998 -275.333178)
		(end 339.05825 -275.383498)
		(width 0.0889)
		(layer "In4.Cu")
		(net "M_D_CPU0_SB_DQ<3>")
	)
	(arc
		(start 327.777602 -275.383498)
		(mid 328.052308 -275.459862)
		(end 328.32929 -275.392134)
		(width 0.0889)
		(layer "In4.Cu")
		(net "M_D_CPU0_SB_DQ<3>")
	)
	(arc
		(start 332.103984 -275.383498)
		(mid 332.286235 -275.333148)
		(end 332.469744 -275.378672)
		(width 0.0889)
		(layer "In4.Cu")
		(net "M_D_CPU0_SB_DQ<3>")
	)
	(arc
		(start 339.624162 -275.383498)
		(mid 339.811106 -275.333243)
		(end 339.99805 -275.383498)
		(width 0.0889)
		(layer "In4.Cu")
		(net "M_D_CPU0_SB_DQ<3>")
	)
	(arc
		(start 330.598018 -275.383498)
		(mid 330.880974 -275.459675)
		(end 331.16393 -275.383498)
		(width 0.0889)
		(layer "In4.Cu")
		(net "M_D_CPU0_SB_DQ<3>")
	)
	(arc
		(start 331.16393 -275.383498)
		(mid 331.346181 -275.333148)
		(end 331.52969 -275.378672)
		(width 0.0889)
		(layer "In4.Cu")
		(net "M_D_CPU0_SB_DQ<3>")
	)
	(arc
		(start 339.99805 -275.383498)
		(mid 340.245646 -275.458676)
		(end 340.500716 -275.415248)
		(width 0.0889)
		(layer "In4.Cu")
		(net "M_D_CPU0_SB_DQ<3>")
	)
	(arc
		(start 331.538072 -275.383498)
		(mid 331.821028 -275.459675)
		(end 332.103984 -275.383498)
		(width 0.0889)
		(layer "In4.Cu")
		(net "M_D_CPU0_SB_DQ<3>")
	)
	(arc
		(start 338.118196 -275.383498)
		(mid 338.401152 -275.459675)
		(end 338.684108 -275.383498)
		(width 0.0889)
		(layer "In4.Cu")
		(net "M_D_CPU0_SB_DQ<3>")
	)
	(arc
		(start 335.298034 -275.383498)
		(mid 335.58099 -275.459675)
		(end 335.863946 -275.383498)
		(width 0.0889)
		(layer "In4.Cu")
		(net "M_D_CPU0_SB_DQ<3>")
	)
	(arc
		(start 337.752436 -275.378672)
		(mid 337.935944 -275.333178)
		(end 338.118196 -275.383498)
		(width 0.0889)
		(layer "In4.Cu")
		(net "M_D_CPU0_SB_DQ<3>")
	)
	(arc
		(start 329.658218 -275.383498)
		(mid 329.941174 -275.459675)
		(end 330.22413 -275.383498)
		(width 0.0889)
		(layer "In4.Cu")
		(net "M_D_CPU0_SB_DQ<3>")
	)
	(arc
		(start 333.05242 -275.378672)
		(mid 333.235928 -275.333178)
		(end 333.41818 -275.383498)
		(width 0.0889)
		(layer "In4.Cu")
		(net "M_D_CPU0_SB_DQ<3>")
	)
	(segment
		(start 339.337904 -293.260018)
		(end 338.871052 -293.525956)
		(width 0.10668)
		(layer "F.Cu")
		(net "M_D_CPU0_SB_DQ<31>")
	)
	(segment
		(start 329.753976 -294.013382)
		(end 329.756516 -294.011604)
		(width 0.0889)
		(layer "In4.Cu")
		(net "M_D_CPU0_SB_DQ<31>")
	)
	(segment
		(start 282.632658 -318.297306)
		(end 282.632658 -317.730124)
		(width 0.14478)
		(layer "In4.Cu")
		(net "M_D_CPU0_SB_DQ<31>")
	)
	(segment
		(start 338.621116 -293.235126)
		(end 338.717128 -293.260526)
		(width 0.0889)
		(layer "In4.Cu")
		(net "M_D_CPU0_SB_DQ<31>")
	)
	(segment
		(start 282.469844 -318.46012)
		(end 282.632658 -318.297306)
		(width 0.14478)
		(layer "In4.Cu")
		(net "M_D_CPU0_SB_DQ<31>")
	)
	(segment
		(start 333.044038 -293.203376)
		(end 333.05242 -293.19855)
		(width 0.0889)
		(layer "In4.Cu")
		(net "M_D_CPU0_SB_DQ<31>")
	)
	(segment
		(start 283.188918 -318.297306)
		(end 283.351732 -318.46012)
		(width 0.14478)
		(layer "In4.Cu")
		(net "M_D_CPU0_SB_DQ<31>")
	)
	(segment
		(start 327.739248 -296.555668)
		(end 327.825608 -296.469308)
		(width 0.0889)
		(layer "In4.Cu")
		(net "M_D_CPU0_SB_DQ<31>")
	)
	(segment
		(start 328.343768 -296.4434)
		(end 328.384154 -296.419778)
		(width 0.0889)
		(layer "In4.Cu")
		(net "M_D_CPU0_SB_DQ<31>")
	)
	(segment
		(start 327.852532 -296.458132)
		(end 328.289412 -296.458132)
		(width 0.0889)
		(layer "In4.Cu")
		(net "M_D_CPU0_SB_DQ<31>")
	)
	(segment
		(start 329.284076 -294.823388)
		(end 329.323192 -294.800528)
		(width 0.0889)
		(layer "In4.Cu")
		(net "M_D_CPU0_SB_DQ<31>")
	)
	(segment
		(start 281.060906 -318.46012)
		(end 281.357324 -318.46012)
		(width 0.14478)
		(layer "In4.Cu")
		(net "M_D_CPU0_SB_DQ<31>")
	)
	(segment
		(start 281.357324 -318.46012)
		(end 281.520138 -318.297306)
		(width 0.14478)
		(layer "In4.Cu")
		(net "M_D_CPU0_SB_DQ<31>")
	)
	(segment
		(start 281.520138 -318.297306)
		(end 281.520138 -317.730124)
		(width 0.14478)
		(layer "In4.Cu")
		(net "M_D_CPU0_SB_DQ<31>")
	)
	(segment
		(start 283.026104 -317.56731)
		(end 283.188918 -317.730124)
		(width 0.14478)
		(layer "In4.Cu")
		(net "M_D_CPU0_SB_DQ<31>")
	)
	(segment
		(start 282.076398 -317.730124)
		(end 282.076398 -318.297306)
		(width 0.14478)
		(layer "In4.Cu")
		(net "M_D_CPU0_SB_DQ<31>")
	)
	(segment
		(start 283.351732 -318.46012)
		(end 308.150514 -318.46012)
		(width 0.14478)
		(layer "In4.Cu")
		(net "M_D_CPU0_SB_DQ<31>")
	)
	(segment
		(start 338.717128 -293.260526)
		(end 338.871052 -293.525956)
		(width 0.0889)
		(layer "In4.Cu")
		(net "M_D_CPU0_SB_DQ<31>")
	)
	(segment
		(start 328.783442 -295.651174)
		(end 328.813922 -295.633394)
		(width 0.0889)
		(layer "In4.Cu")
		(net "M_D_CPU0_SB_DQ<31>")
	)
	(segment
		(start 332.469744 -293.19855)
		(end 332.478126 -293.203376)
		(width 0.0889)
		(layer "In4.Cu")
		(net "M_D_CPU0_SB_DQ<31>")
	)
	(segment
		(start 328.813922 -295.633394)
		(end 328.853038 -295.610534)
		(width 0.0889)
		(layer "In4.Cu")
		(net "M_D_CPU0_SB_DQ<31>")
	)
	(segment
		(start 308.150514 -318.46012)
		(end 325.062088 -301.548546)
		(width 0.14478)
		(layer "In4.Cu")
		(net "M_D_CPU0_SB_DQ<31>")
	)
	(segment
		(start 337.16976 -293.19855)
		(end 337.178142 -293.203376)
		(width 0.0889)
		(layer "In4.Cu")
		(net "M_D_CPU0_SB_DQ<31>")
	)
	(segment
		(start 281.520138 -317.730124)
		(end 281.682952 -317.56731)
		(width 0.14478)
		(layer "In4.Cu")
		(net "M_D_CPU0_SB_DQ<31>")
	)
	(segment
		(start 282.795472 -317.56731)
		(end 283.026104 -317.56731)
		(width 0.14478)
		(layer "In4.Cu")
		(net "M_D_CPU0_SB_DQ<31>")
	)
	(segment
		(start 330.221336 -293.205154)
		(end 330.22413 -293.203376)
		(width 0.0889)
		(layer "In4.Cu")
		(net "M_D_CPU0_SB_DQ<31>")
	)
	(segment
		(start 281.913584 -317.56731)
		(end 282.076398 -317.730124)
		(width 0.14478)
		(layer "In4.Cu")
		(net "M_D_CPU0_SB_DQ<31>")
	)
	(segment
		(start 333.984092 -293.203376)
		(end 333.992474 -293.19855)
		(width 0.0889)
		(layer "In4.Cu")
		(net "M_D_CPU0_SB_DQ<31>")
	)
	(segment
		(start 329.252326 -294.841676)
		(end 329.284076 -294.823388)
		(width 0.0889)
		(layer "In4.Cu")
		(net "M_D_CPU0_SB_DQ<31>")
	)
	(segment
		(start 337.744054 -293.203376)
		(end 337.752436 -293.19855)
		(width 0.0889)
		(layer "In4.Cu")
		(net "M_D_CPU0_SB_DQ<31>")
	)
	(segment
		(start 281.682952 -317.56731)
		(end 281.913584 -317.56731)
		(width 0.14478)
		(layer "In4.Cu")
		(net "M_D_CPU0_SB_DQ<31>")
	)
	(segment
		(start 325.062088 -301.548546)
		(end 325.062088 -299.232828)
		(width 0.14478)
		(layer "In4.Cu")
		(net "M_D_CPU0_SB_DQ<31>")
	)
	(segment
		(start 282.632658 -317.730124)
		(end 282.795472 -317.56731)
		(width 0.14478)
		(layer "In4.Cu")
		(net "M_D_CPU0_SB_DQ<31>")
	)
	(segment
		(start 336.229706 -293.19855)
		(end 336.238088 -293.203376)
		(width 0.0889)
		(layer "In4.Cu")
		(net "M_D_CPU0_SB_DQ<31>")
	)
	(segment
		(start 331.52969 -293.19855)
		(end 331.538072 -293.203376)
		(width 0.0889)
		(layer "In4.Cu")
		(net "M_D_CPU0_SB_DQ<31>")
	)
	(segment
		(start 282.239212 -318.46012)
		(end 282.469844 -318.46012)
		(width 0.14478)
		(layer "In4.Cu")
		(net "M_D_CPU0_SB_DQ<31>")
	)
	(segment
		(start 325.062088 -299.232828)
		(end 327.739248 -296.555668)
		(width 0.14478)
		(layer "In4.Cu")
		(net "M_D_CPU0_SB_DQ<31>")
	)
	(segment
		(start 282.076398 -318.297306)
		(end 282.239212 -318.46012)
		(width 0.14478)
		(layer "In4.Cu")
		(net "M_D_CPU0_SB_DQ<31>")
	)
	(segment
		(start 329.723496 -294.031162)
		(end 329.753976 -294.013382)
		(width 0.0889)
		(layer "In4.Cu")
		(net "M_D_CPU0_SB_DQ<31>")
	)
	(segment
		(start 283.188918 -317.730124)
		(end 283.188918 -318.297306)
		(width 0.14478)
		(layer "In4.Cu")
		(net "M_D_CPU0_SB_DQ<31>")
	)
	(segment
		(start 280.635964 -318.035178)
		(end 281.060906 -318.46012)
		(width 0.14478)
		(layer "In4.Cu")
		(net "M_D_CPU0_SB_DQ<31>")
	)
	(arc
		(start 330.598018 -293.203376)
		(mid 330.880974 -293.279553)
		(end 331.16393 -293.203376)
		(width 0.0889)
		(layer "In4.Cu")
		(net "M_D_CPU0_SB_DQ<31>")
	)
	(arc
		(start 338.118196 -293.203376)
		(mid 338.365909 -293.278596)
		(end 338.621116 -293.235126)
		(width 0.0889)
		(layer "In4.Cu")
		(net "M_D_CPU0_SB_DQ<31>")
	)
	(arc
		(start 331.538072 -293.203376)
		(mid 331.821028 -293.279553)
		(end 332.103984 -293.203376)
		(width 0.0889)
		(layer "In4.Cu")
		(net "M_D_CPU0_SB_DQ<31>")
	)
	(arc
		(start 333.41818 -293.203376)
		(mid 333.701136 -293.279553)
		(end 333.984092 -293.203376)
		(width 0.0889)
		(layer "In4.Cu")
		(net "M_D_CPU0_SB_DQ<31>")
	)
	(arc
		(start 336.804 -293.203376)
		(mid 336.986251 -293.153026)
		(end 337.16976 -293.19855)
		(width 0.0889)
		(layer "In4.Cu")
		(net "M_D_CPU0_SB_DQ<31>")
	)
	(arc
		(start 329.09637 -295.145968)
		(mid 329.137625 -294.974997)
		(end 329.252326 -294.841676)
		(width 0.0889)
		(layer "In4.Cu")
		(net "M_D_CPU0_SB_DQ<31>")
	)
	(arc
		(start 330.22413 -293.203376)
		(mid 330.411074 -293.153121)
		(end 330.598018 -293.203376)
		(width 0.0889)
		(layer "In4.Cu")
		(net "M_D_CPU0_SB_DQ<31>")
	)
	(arc
		(start 332.103984 -293.203376)
		(mid 332.286235 -293.153026)
		(end 332.469744 -293.19855)
		(width 0.0889)
		(layer "In4.Cu")
		(net "M_D_CPU0_SB_DQ<31>")
	)
	(arc
		(start 337.178142 -293.203376)
		(mid 337.461098 -293.279553)
		(end 337.744054 -293.203376)
		(width 0.0889)
		(layer "In4.Cu")
		(net "M_D_CPU0_SB_DQ<31>")
	)
	(arc
		(start 333.992474 -293.19855)
		(mid 334.175982 -293.153056)
		(end 334.358234 -293.203376)
		(width 0.0889)
		(layer "In4.Cu")
		(net "M_D_CPU0_SB_DQ<31>")
	)
	(arc
		(start 334.358234 -293.203376)
		(mid 334.64119 -293.279553)
		(end 334.924146 -293.203376)
		(width 0.0889)
		(layer "In4.Cu")
		(net "M_D_CPU0_SB_DQ<31>")
	)
	(arc
		(start 335.298034 -293.203376)
		(mid 335.58099 -293.279553)
		(end 335.863946 -293.203376)
		(width 0.0889)
		(layer "In4.Cu")
		(net "M_D_CPU0_SB_DQ<31>")
	)
	(arc
		(start 337.752436 -293.19855)
		(mid 337.935944 -293.153056)
		(end 338.118196 -293.203376)
		(width 0.0889)
		(layer "In4.Cu")
		(net "M_D_CPU0_SB_DQ<31>")
	)
	(arc
		(start 328.289412 -296.458132)
		(mid 328.317571 -296.454385)
		(end 328.343768 -296.4434)
		(width 0.0889)
		(layer "In4.Cu")
		(net "M_D_CPU0_SB_DQ<31>")
	)
	(arc
		(start 335.863946 -293.203376)
		(mid 336.046197 -293.153026)
		(end 336.229706 -293.19855)
		(width 0.0889)
		(layer "In4.Cu")
		(net "M_D_CPU0_SB_DQ<31>")
	)
	(arc
		(start 330.036424 -293.525956)
		(mid 330.085953 -293.340803)
		(end 330.221336 -293.205154)
		(width 0.0889)
		(layer "In4.Cu")
		(net "M_D_CPU0_SB_DQ<31>")
	)
	(arc
		(start 331.16393 -293.203376)
		(mid 331.346181 -293.153026)
		(end 331.52969 -293.19855)
		(width 0.0889)
		(layer "In4.Cu")
		(net "M_D_CPU0_SB_DQ<31>")
	)
	(arc
		(start 334.924146 -293.203376)
		(mid 335.11109 -293.153121)
		(end 335.298034 -293.203376)
		(width 0.0889)
		(layer "In4.Cu")
		(net "M_D_CPU0_SB_DQ<31>")
	)
	(arc
		(start 329.756516 -294.011604)
		(mid 329.961416 -293.806204)
		(end 330.036424 -293.525956)
		(width 0.0889)
		(layer "In4.Cu")
		(net "M_D_CPU0_SB_DQ<31>")
	)
	(arc
		(start 328.384154 -296.419778)
		(mid 328.562219 -296.217601)
		(end 328.62647 -295.955974)
		(width 0.0889)
		(layer "In4.Cu")
		(net "M_D_CPU0_SB_DQ<31>")
	)
	(arc
		(start 329.323192 -294.800528)
		(mid 329.502005 -294.598178)
		(end 329.566524 -294.335962)
		(width 0.0889)
		(layer "In4.Cu")
		(net "M_D_CPU0_SB_DQ<31>")
	)
	(arc
		(start 336.238088 -293.203376)
		(mid 336.521044 -293.279553)
		(end 336.804 -293.203376)
		(width 0.0889)
		(layer "In4.Cu")
		(net "M_D_CPU0_SB_DQ<31>")
	)
	(arc
		(start 327.825608 -296.469308)
		(mid 327.837961 -296.461054)
		(end 327.852532 -296.458132)
		(width 0.0889)
		(layer "In4.Cu")
		(net "M_D_CPU0_SB_DQ<31>")
	)
	(arc
		(start 332.478126 -293.203376)
		(mid 332.761082 -293.279553)
		(end 333.044038 -293.203376)
		(width 0.0889)
		(layer "In4.Cu")
		(net "M_D_CPU0_SB_DQ<31>")
	)
	(arc
		(start 329.566524 -294.335962)
		(mid 329.608073 -294.16454)
		(end 329.723496 -294.031162)
		(width 0.0889)
		(layer "In4.Cu")
		(net "M_D_CPU0_SB_DQ<31>")
	)
	(arc
		(start 328.62647 -295.955974)
		(mid 328.668019 -295.784552)
		(end 328.783442 -295.651174)
		(width 0.0889)
		(layer "In4.Cu")
		(net "M_D_CPU0_SB_DQ<31>")
	)
	(arc
		(start 328.853038 -295.610534)
		(mid 329.031851 -295.408184)
		(end 329.09637 -295.145968)
		(width 0.0889)
		(layer "In4.Cu")
		(net "M_D_CPU0_SB_DQ<31>")
	)
	(arc
		(start 333.05242 -293.19855)
		(mid 333.235928 -293.153056)
		(end 333.41818 -293.203376)
		(width 0.0889)
		(layer "In4.Cu")
		(net "M_D_CPU0_SB_DQ<31>")
	)
	(segment
		(start 339.808058 -292.450012)
		(end 339.341206 -292.71595)
		(width 0.10668)
		(layer "F.Cu")
		(net "M_D_CPU0_SB_DQ<30>")
	)
	(segment
		(start 323.699378 -301.211488)
		(end 323.699378 -298.668186)
		(width 0.14478)
		(layer "In4.Cu")
		(net "M_D_CPU0_SB_DQ<30>")
	)
	(segment
		(start 283.102304 -316.217046)
		(end 283.102304 -316.597284)
		(width 0.14478)
		(layer "In4.Cu")
		(net "M_D_CPU0_SB_DQ<30>")
	)
	(segment
		(start 282.708858 -316.054232)
		(end 282.93949 -316.054232)
		(width 0.14478)
		(layer "In4.Cu")
		(net "M_D_CPU0_SB_DQ<30>")
	)
	(segment
		(start 330.119736 -292.388544)
		(end 330.128118 -292.39337)
		(width 0.0889)
		(layer "In4.Cu")
		(net "M_D_CPU0_SB_DQ<30>")
	)
	(segment
		(start 331.634084 -292.39337)
		(end 331.642466 -292.388544)
		(width 0.0889)
		(layer "In4.Cu")
		(net "M_D_CPU0_SB_DQ<30>")
	)
	(segment
		(start 326.250554 -296.11701)
		(end 326.502522 -295.865042)
		(width 0.0889)
		(layer "In4.Cu")
		(net "M_D_CPU0_SB_DQ<30>")
	)
	(segment
		(start 327.372726 -294.841676)
		(end 327.404476 -294.823388)
		(width 0.0889)
		(layer "In4.Cu")
		(net "M_D_CPU0_SB_DQ<30>")
	)
	(segment
		(start 330.69403 -292.39337)
		(end 330.702412 -292.388544)
		(width 0.0889)
		(layer "In4.Cu")
		(net "M_D_CPU0_SB_DQ<30>")
	)
	(segment
		(start 336.3341 -292.39337)
		(end 336.342482 -292.388544)
		(width 0.0889)
		(layer "In4.Cu")
		(net "M_D_CPU0_SB_DQ<30>")
	)
	(segment
		(start 323.699378 -298.668186)
		(end 326.250554 -296.11701)
		(width 0.14478)
		(layer "In4.Cu")
		(net "M_D_CPU0_SB_DQ<30>")
	)
	(segment
		(start 281.433524 -316.028324)
		(end 281.596338 -315.86551)
		(width 0.14478)
		(layer "In4.Cu")
		(net "M_D_CPU0_SB_DQ<30>")
	)
	(segment
		(start 328.313542 -293.221156)
		(end 328.344022 -293.203376)
		(width 0.0889)
		(layer "In4.Cu")
		(net "M_D_CPU0_SB_DQ<30>")
	)
	(segment
		(start 283.102304 -316.597284)
		(end 283.265118 -316.760098)
		(width 0.14478)
		(layer "In4.Cu")
		(net "M_D_CPU0_SB_DQ<30>")
	)
	(segment
		(start 281.27071 -316.760098)
		(end 281.433524 -316.597284)
		(width 0.14478)
		(layer "In4.Cu")
		(net "M_D_CPU0_SB_DQ<30>")
	)
	(segment
		(start 280.635964 -316.335156)
		(end 281.060906 -316.760098)
		(width 0.14478)
		(layer "In4.Cu")
		(net "M_D_CPU0_SB_DQ<30>")
	)
	(segment
		(start 326.502522 -295.865042)
		(end 326.58177 -295.786048)
		(width 0.0889)
		(layer "In4.Cu")
		(net "M_D_CPU0_SB_DQ<30>")
	)
	(segment
		(start 338.579714 -292.388544)
		(end 338.588096 -292.39337)
		(width 0.0889)
		(layer "In4.Cu")
		(net "M_D_CPU0_SB_DQ<30>")
	)
	(segment
		(start 328.344022 -293.203376)
		(end 328.383138 -293.180516)
		(width 0.0889)
		(layer "In4.Cu")
		(net "M_D_CPU0_SB_DQ<30>")
	)
	(segment
		(start 281.060906 -316.760098)
		(end 281.27071 -316.760098)
		(width 0.14478)
		(layer "In4.Cu")
		(net "M_D_CPU0_SB_DQ<30>")
	)
	(segment
		(start 333.879698 -292.388544)
		(end 333.88808 -292.39337)
		(width 0.0889)
		(layer "In4.Cu")
		(net "M_D_CPU0_SB_DQ<30>")
	)
	(segment
		(start 281.433524 -316.597284)
		(end 281.433524 -316.028324)
		(width 0.14478)
		(layer "In4.Cu")
		(net "M_D_CPU0_SB_DQ<30>")
	)
	(segment
		(start 281.82697 -315.86551)
		(end 281.989784 -316.028324)
		(width 0.14478)
		(layer "In4.Cu")
		(net "M_D_CPU0_SB_DQ<30>")
	)
	(segment
		(start 282.152598 -316.760098)
		(end 282.38323 -316.760098)
		(width 0.14478)
		(layer "In4.Cu")
		(net "M_D_CPU0_SB_DQ<30>")
	)
	(segment
		(start 281.596338 -315.86551)
		(end 281.82697 -315.86551)
		(width 0.14478)
		(layer "In4.Cu")
		(net "M_D_CPU0_SB_DQ<30>")
	)
	(segment
		(start 282.38323 -316.760098)
		(end 282.546044 -316.597284)
		(width 0.14478)
		(layer "In4.Cu")
		(net "M_D_CPU0_SB_DQ<30>")
	)
	(segment
		(start 283.265118 -316.760098)
		(end 308.150768 -316.760098)
		(width 0.14478)
		(layer "In4.Cu")
		(net "M_D_CPU0_SB_DQ<30>")
	)
	(segment
		(start 281.989784 -316.028324)
		(end 281.989784 -316.597284)
		(width 0.14478)
		(layer "In4.Cu")
		(net "M_D_CPU0_SB_DQ<30>")
	)
	(segment
		(start 335.394046 -292.39337)
		(end 335.402428 -292.388544)
		(width 0.0889)
		(layer "In4.Cu")
		(net "M_D_CPU0_SB_DQ<30>")
	)
	(segment
		(start 282.546044 -316.217046)
		(end 282.708858 -316.054232)
		(width 0.14478)
		(layer "In4.Cu")
		(net "M_D_CPU0_SB_DQ<30>")
	)
	(segment
		(start 281.989784 -316.597284)
		(end 282.152598 -316.760098)
		(width 0.14478)
		(layer "In4.Cu")
		(net "M_D_CPU0_SB_DQ<30>")
	)
	(segment
		(start 327.404476 -294.823388)
		(end 327.440798 -294.802306)
		(width 0.0889)
		(layer "In4.Cu")
		(net "M_D_CPU0_SB_DQ<30>")
	)
	(segment
		(start 339.090762 -292.42512)
		(end 339.187028 -292.45052)
		(width 0.0889)
		(layer "In4.Cu")
		(net "M_D_CPU0_SB_DQ<30>")
	)
	(segment
		(start 327.844658 -294.0304)
		(end 327.874122 -294.013382)
		(width 0.0889)
		(layer "In4.Cu")
		(net "M_D_CPU0_SB_DQ<30>")
	)
	(segment
		(start 326.88784 -295.669716)
		(end 326.972168 -295.61155)
		(width 0.0889)
		(layer "In4.Cu")
		(net "M_D_CPU0_SB_DQ<30>")
	)
	(segment
		(start 308.150768 -316.760098)
		(end 323.699378 -301.211488)
		(width 0.14478)
		(layer "In4.Cu")
		(net "M_D_CPU0_SB_DQ<30>")
	)
	(segment
		(start 282.93949 -316.054232)
		(end 283.102304 -316.217046)
		(width 0.14478)
		(layer "In4.Cu")
		(net "M_D_CPU0_SB_DQ<30>")
	)
	(segment
		(start 282.546044 -316.597284)
		(end 282.546044 -316.217046)
		(width 0.14478)
		(layer "In4.Cu")
		(net "M_D_CPU0_SB_DQ<30>")
	)
	(segment
		(start 327.874122 -294.013382)
		(end 327.913238 -293.990522)
		(width 0.0889)
		(layer "In4.Cu")
		(net "M_D_CPU0_SB_DQ<30>")
	)
	(segment
		(start 328.782426 -292.411658)
		(end 328.814176 -292.39337)
		(width 0.0889)
		(layer "In4.Cu")
		(net "M_D_CPU0_SB_DQ<30>")
	)
	(segment
		(start 334.819752 -292.388544)
		(end 334.828134 -292.39337)
		(width 0.0889)
		(layer "In4.Cu")
		(net "M_D_CPU0_SB_DQ<30>")
	)
	(segment
		(start 339.187028 -292.45052)
		(end 339.341206 -292.71595)
		(width 0.0889)
		(layer "In4.Cu")
		(net "M_D_CPU0_SB_DQ<30>")
	)
	(arc
		(start 330.128118 -292.39337)
		(mid 330.411074 -292.469547)
		(end 330.69403 -292.39337)
		(width 0.0889)
		(layer "In4.Cu")
		(net "M_D_CPU0_SB_DQ<30>")
	)
	(arc
		(start 332.948026 -292.39337)
		(mid 333.230982 -292.469547)
		(end 333.513938 -292.39337)
		(width 0.0889)
		(layer "In4.Cu")
		(net "M_D_CPU0_SB_DQ<30>")
	)
	(arc
		(start 332.008226 -292.39337)
		(mid 332.291182 -292.469547)
		(end 332.574138 -292.39337)
		(width 0.0889)
		(layer "In4.Cu")
		(net "M_D_CPU0_SB_DQ<30>")
	)
	(arc
		(start 334.828134 -292.39337)
		(mid 335.11109 -292.469547)
		(end 335.394046 -292.39337)
		(width 0.0889)
		(layer "In4.Cu")
		(net "M_D_CPU0_SB_DQ<30>")
	)
	(arc
		(start 330.702412 -292.388544)
		(mid 330.88592 -292.34305)
		(end 331.068172 -292.39337)
		(width 0.0889)
		(layer "In4.Cu")
		(net "M_D_CPU0_SB_DQ<30>")
	)
	(arc
		(start 331.068172 -292.39337)
		(mid 331.351128 -292.469547)
		(end 331.634084 -292.39337)
		(width 0.0889)
		(layer "In4.Cu")
		(net "M_D_CPU0_SB_DQ<30>")
	)
	(arc
		(start 327.68667 -294.335962)
		(mid 327.72851 -294.163976)
		(end 327.844658 -294.0304)
		(width 0.0889)
		(layer "In4.Cu")
		(net "M_D_CPU0_SB_DQ<30>")
	)
	(arc
		(start 332.574138 -292.39337)
		(mid 332.761082 -292.343115)
		(end 332.948026 -292.39337)
		(width 0.0889)
		(layer "In4.Cu")
		(net "M_D_CPU0_SB_DQ<30>")
	)
	(arc
		(start 335.768188 -292.39337)
		(mid 336.051144 -292.469547)
		(end 336.3341 -292.39337)
		(width 0.0889)
		(layer "In4.Cu")
		(net "M_D_CPU0_SB_DQ<30>")
	)
	(arc
		(start 327.21677 -295.145968)
		(mid 327.258025 -294.974997)
		(end 327.372726 -294.841676)
		(width 0.0889)
		(layer "In4.Cu")
		(net "M_D_CPU0_SB_DQ<30>")
	)
	(arc
		(start 336.708242 -292.39337)
		(mid 336.991198 -292.469547)
		(end 337.274154 -292.39337)
		(width 0.0889)
		(layer "In4.Cu")
		(net "M_D_CPU0_SB_DQ<30>")
	)
	(arc
		(start 328.15657 -293.525956)
		(mid 328.198119 -293.354534)
		(end 328.313542 -293.221156)
		(width 0.0889)
		(layer "In4.Cu")
		(net "M_D_CPU0_SB_DQ<30>")
	)
	(arc
		(start 331.642466 -292.388544)
		(mid 331.825974 -292.34305)
		(end 332.008226 -292.39337)
		(width 0.0889)
		(layer "In4.Cu")
		(net "M_D_CPU0_SB_DQ<30>")
	)
	(arc
		(start 329.753976 -292.39337)
		(mid 329.936227 -292.34302)
		(end 330.119736 -292.388544)
		(width 0.0889)
		(layer "In4.Cu")
		(net "M_D_CPU0_SB_DQ<30>")
	)
	(arc
		(start 334.453992 -292.39337)
		(mid 334.636243 -292.34302)
		(end 334.819752 -292.388544)
		(width 0.0889)
		(layer "In4.Cu")
		(net "M_D_CPU0_SB_DQ<30>")
	)
	(arc
		(start 337.648042 -292.39337)
		(mid 337.930998 -292.469547)
		(end 338.213954 -292.39337)
		(width 0.0889)
		(layer "In4.Cu")
		(net "M_D_CPU0_SB_DQ<30>")
	)
	(arc
		(start 333.513938 -292.39337)
		(mid 333.696189 -292.34302)
		(end 333.879698 -292.388544)
		(width 0.0889)
		(layer "In4.Cu")
		(net "M_D_CPU0_SB_DQ<30>")
	)
	(arc
		(start 336.342482 -292.388544)
		(mid 336.52599 -292.34305)
		(end 336.708242 -292.39337)
		(width 0.0889)
		(layer "In4.Cu")
		(net "M_D_CPU0_SB_DQ<30>")
	)
	(arc
		(start 326.78497 -295.70172)
		(mid 326.838831 -295.693525)
		(end 326.88784 -295.669716)
		(width 0.0889)
		(layer "In4.Cu")
		(net "M_D_CPU0_SB_DQ<30>")
	)
	(arc
		(start 328.814176 -292.39337)
		(mid 329.00112 -292.343115)
		(end 329.188064 -292.39337)
		(width 0.0889)
		(layer "In4.Cu")
		(net "M_D_CPU0_SB_DQ<30>")
	)
	(arc
		(start 328.62647 -292.71595)
		(mid 328.667725 -292.544979)
		(end 328.782426 -292.411658)
		(width 0.0889)
		(layer "In4.Cu")
		(net "M_D_CPU0_SB_DQ<30>")
	)
	(arc
		(start 328.383138 -293.180516)
		(mid 328.561951 -292.978166)
		(end 328.62647 -292.71595)
		(width 0.0889)
		(layer "In4.Cu")
		(net "M_D_CPU0_SB_DQ<30>")
	)
	(arc
		(start 327.440798 -294.802306)
		(mid 327.62145 -294.599561)
		(end 327.68667 -294.335962)
		(width 0.0889)
		(layer "In4.Cu")
		(net "M_D_CPU0_SB_DQ<30>")
	)
	(arc
		(start 326.972168 -295.61155)
		(mid 327.151897 -295.40893)
		(end 327.21677 -295.145968)
		(width 0.0889)
		(layer "In4.Cu")
		(net "M_D_CPU0_SB_DQ<30>")
	)
	(arc
		(start 335.402428 -292.388544)
		(mid 335.585936 -292.34305)
		(end 335.768188 -292.39337)
		(width 0.0889)
		(layer "In4.Cu")
		(net "M_D_CPU0_SB_DQ<30>")
	)
	(arc
		(start 326.58177 -295.786048)
		(mid 326.674984 -295.723671)
		(end 326.78497 -295.70172)
		(width 0.0889)
		(layer "In4.Cu")
		(net "M_D_CPU0_SB_DQ<30>")
	)
	(arc
		(start 337.274154 -292.39337)
		(mid 337.461098 -292.343115)
		(end 337.648042 -292.39337)
		(width 0.0889)
		(layer "In4.Cu")
		(net "M_D_CPU0_SB_DQ<30>")
	)
	(arc
		(start 338.213954 -292.39337)
		(mid 338.396205 -292.34302)
		(end 338.579714 -292.388544)
		(width 0.0889)
		(layer "In4.Cu")
		(net "M_D_CPU0_SB_DQ<30>")
	)
	(arc
		(start 327.913238 -293.990522)
		(mid 328.092051 -293.788172)
		(end 328.15657 -293.525956)
		(width 0.0889)
		(layer "In4.Cu")
		(net "M_D_CPU0_SB_DQ<30>")
	)
	(arc
		(start 333.88808 -292.39337)
		(mid 334.171036 -292.469547)
		(end 334.453992 -292.39337)
		(width 0.0889)
		(layer "In4.Cu")
		(net "M_D_CPU0_SB_DQ<30>")
	)
	(arc
		(start 329.188064 -292.39337)
		(mid 329.47102 -292.469547)
		(end 329.753976 -292.39337)
		(width 0.0889)
		(layer "In4.Cu")
		(net "M_D_CPU0_SB_DQ<30>")
	)
	(arc
		(start 338.588096 -292.39337)
		(mid 338.835692 -292.468548)
		(end 339.090762 -292.42512)
		(width 0.0889)
		(layer "In4.Cu")
		(net "M_D_CPU0_SB_DQ<30>")
	)
	(segment
		(start 339.808058 -274.630134)
		(end 339.341206 -274.896072)
		(width 0.10668)
		(layer "F.Cu")
		(net "M_D_CPU0_SB_DQ<2>")
	)
	(segment
		(start 301.373286 -282.364942)
		(end 305.331622 -282.364942)
		(width 0.14478)
		(layer "In4.Cu")
		(net "M_D_CPU0_SB_DQ<2>")
	)
	(segment
		(start 339.187028 -274.630642)
		(end 339.341206 -274.896072)
		(width 0.0889)
		(layer "In4.Cu")
		(net "M_D_CPU0_SB_DQ<2>")
	)
	(segment
		(start 282.371038 -282.597352)
		(end 282.533852 -282.760166)
		(width 0.14478)
		(layer "In4.Cu")
		(net "M_D_CPU0_SB_DQ<2>")
	)
	(segment
		(start 305.331622 -282.364942)
		(end 305.786536 -281.910028)
		(width 0.14478)
		(layer "In4.Cu")
		(net "M_D_CPU0_SB_DQ<2>")
	)
	(segment
		(start 335.394046 -274.573492)
		(end 335.402428 -274.568666)
		(width 0.0889)
		(layer "In4.Cu")
		(net "M_D_CPU0_SB_DQ<2>")
	)
	(segment
		(start 336.3341 -274.573492)
		(end 336.342482 -274.568666)
		(width 0.0889)
		(layer "In4.Cu")
		(net "M_D_CPU0_SB_DQ<2>")
	)
	(segment
		(start 307.744622 -281.910028)
		(end 315.97981 -273.67484)
		(width 0.14478)
		(layer "In4.Cu")
		(net "M_D_CPU0_SB_DQ<2>")
	)
	(segment
		(start 330.119736 -274.568666)
		(end 330.128118 -274.573492)
		(width 0.0889)
		(layer "In4.Cu")
		(net "M_D_CPU0_SB_DQ<2>")
	)
	(segment
		(start 315.97981 -273.67484)
		(end 323.925184 -273.67484)
		(width 0.14478)
		(layer "In4.Cu")
		(net "M_D_CPU0_SB_DQ<2>")
	)
	(segment
		(start 281.814778 -281.784806)
		(end 281.977592 -281.621992)
		(width 0.14478)
		(layer "In4.Cu")
		(net "M_D_CPU0_SB_DQ<2>")
	)
	(segment
		(start 280.635964 -282.33497)
		(end 281.06116 -282.760166)
		(width 0.14478)
		(layer "In4.Cu")
		(net "M_D_CPU0_SB_DQ<2>")
	)
	(segment
		(start 294.19931 -282.760166)
		(end 297.213782 -282.760166)
		(width 0.14478)
		(layer "In4.Cu")
		(net "M_D_CPU0_SB_DQ<2>")
	)
	(segment
		(start 293.349172 -281.910028)
		(end 294.19931 -282.760166)
		(width 0.14478)
		(layer "In4.Cu")
		(net "M_D_CPU0_SB_DQ<2>")
	)
	(segment
		(start 339.090762 -274.605242)
		(end 339.187028 -274.630642)
		(width 0.0889)
		(layer "In4.Cu")
		(net "M_D_CPU0_SB_DQ<2>")
	)
	(segment
		(start 281.977592 -281.621992)
		(end 282.208224 -281.621992)
		(width 0.14478)
		(layer "In4.Cu")
		(net "M_D_CPU0_SB_DQ<2>")
	)
	(segment
		(start 338.579714 -274.568666)
		(end 338.588096 -274.573492)
		(width 0.0889)
		(layer "In4.Cu")
		(net "M_D_CPU0_SB_DQ<2>")
	)
	(segment
		(start 305.786536 -281.910028)
		(end 307.744622 -281.910028)
		(width 0.14478)
		(layer "In4.Cu")
		(net "M_D_CPU0_SB_DQ<2>")
	)
	(segment
		(start 334.819752 -274.568666)
		(end 334.828134 -274.573492)
		(width 0.0889)
		(layer "In4.Cu")
		(net "M_D_CPU0_SB_DQ<2>")
	)
	(segment
		(start 281.651964 -282.760166)
		(end 281.814778 -282.597352)
		(width 0.14478)
		(layer "In4.Cu")
		(net "M_D_CPU0_SB_DQ<2>")
	)
	(segment
		(start 325.505318 -273.737832)
		(end 326.252332 -274.484846)
		(width 0.0889)
		(layer "In4.Cu")
		(net "M_D_CPU0_SB_DQ<2>")
	)
	(segment
		(start 282.371038 -281.784806)
		(end 282.371038 -282.597352)
		(width 0.14478)
		(layer "In4.Cu")
		(net "M_D_CPU0_SB_DQ<2>")
	)
	(segment
		(start 281.814778 -282.597352)
		(end 281.814778 -281.784806)
		(width 0.14478)
		(layer "In4.Cu")
		(net "M_D_CPU0_SB_DQ<2>")
	)
	(segment
		(start 330.69403 -274.573492)
		(end 330.702412 -274.568666)
		(width 0.0889)
		(layer "In4.Cu")
		(net "M_D_CPU0_SB_DQ<2>")
	)
	(segment
		(start 326.93356 -274.573746)
		(end 326.949816 -274.564348)
		(width 0.0889)
		(layer "In4.Cu")
		(net "M_D_CPU0_SB_DQ<2>")
	)
	(segment
		(start 282.208224 -281.621992)
		(end 282.371038 -281.784806)
		(width 0.14478)
		(layer "In4.Cu")
		(net "M_D_CPU0_SB_DQ<2>")
	)
	(segment
		(start 327.307448 -274.573492)
		(end 327.317862 -274.579588)
		(width 0.0889)
		(layer "In4.Cu")
		(net "M_D_CPU0_SB_DQ<2>")
	)
	(segment
		(start 331.634084 -274.573492)
		(end 331.642466 -274.568666)
		(width 0.0889)
		(layer "In4.Cu")
		(net "M_D_CPU0_SB_DQ<2>")
	)
	(segment
		(start 297.213782 -282.760166)
		(end 298.06392 -281.910028)
		(width 0.14478)
		(layer "In4.Cu")
		(net "M_D_CPU0_SB_DQ<2>")
	)
	(segment
		(start 324.248018 -273.737832)
		(end 325.505318 -273.737832)
		(width 0.0889)
		(layer "In4.Cu")
		(net "M_D_CPU0_SB_DQ<2>")
	)
	(segment
		(start 328.239882 -274.568666)
		(end 328.248264 -274.573492)
		(width 0.0889)
		(layer "In4.Cu")
		(net "M_D_CPU0_SB_DQ<2>")
	)
	(segment
		(start 298.06392 -281.910028)
		(end 300.918372 -281.910028)
		(width 0.14478)
		(layer "In4.Cu")
		(net "M_D_CPU0_SB_DQ<2>")
	)
	(segment
		(start 290.978336 -281.910028)
		(end 293.349172 -281.910028)
		(width 0.14478)
		(layer "In4.Cu")
		(net "M_D_CPU0_SB_DQ<2>")
	)
	(segment
		(start 300.918372 -281.910028)
		(end 301.373286 -282.364942)
		(width 0.14478)
		(layer "In4.Cu")
		(net "M_D_CPU0_SB_DQ<2>")
	)
	(segment
		(start 323.925184 -273.67484)
		(end 324.185026 -273.67484)
		(width 0.0889)
		(layer "In4.Cu")
		(net "M_D_CPU0_SB_DQ<2>")
	)
	(segment
		(start 282.533852 -282.760166)
		(end 290.128198 -282.760166)
		(width 0.14478)
		(layer "In4.Cu")
		(net "M_D_CPU0_SB_DQ<2>")
	)
	(segment
		(start 333.879698 -274.568666)
		(end 333.88808 -274.573492)
		(width 0.0889)
		(layer "In4.Cu")
		(net "M_D_CPU0_SB_DQ<2>")
	)
	(segment
		(start 281.06116 -282.760166)
		(end 281.651964 -282.760166)
		(width 0.14478)
		(layer "In4.Cu")
		(net "M_D_CPU0_SB_DQ<2>")
	)
	(segment
		(start 326.917812 -274.58289)
		(end 326.93356 -274.573746)
		(width 0.0889)
		(layer "In4.Cu")
		(net "M_D_CPU0_SB_DQ<2>")
	)
	(segment
		(start 324.185026 -273.67484)
		(end 324.248018 -273.737832)
		(width 0.0889)
		(layer "In4.Cu")
		(net "M_D_CPU0_SB_DQ<2>")
	)
	(segment
		(start 290.128198 -282.760166)
		(end 290.978336 -281.910028)
		(width 0.14478)
		(layer "In4.Cu")
		(net "M_D_CPU0_SB_DQ<2>")
	)
	(arc
		(start 332.574138 -274.573492)
		(mid 332.761082 -274.523237)
		(end 332.948026 -274.573492)
		(width 0.0889)
		(layer "In4.Cu")
		(net "M_D_CPU0_SB_DQ<2>")
	)
	(arc
		(start 337.274154 -274.573492)
		(mid 337.461098 -274.523237)
		(end 337.648042 -274.573492)
		(width 0.0889)
		(layer "In4.Cu")
		(net "M_D_CPU0_SB_DQ<2>")
	)
	(arc
		(start 327.873614 -274.573492)
		(mid 328.056119 -274.523015)
		(end 328.239882 -274.568666)
		(width 0.0889)
		(layer "In4.Cu")
		(net "M_D_CPU0_SB_DQ<2>")
	)
	(arc
		(start 327.317862 -274.579588)
		(mid 327.596548 -274.649808)
		(end 327.873614 -274.573492)
		(width 0.0889)
		(layer "In4.Cu")
		(net "M_D_CPU0_SB_DQ<2>")
	)
	(arc
		(start 329.753976 -274.573492)
		(mid 329.936227 -274.523142)
		(end 330.119736 -274.568666)
		(width 0.0889)
		(layer "In4.Cu")
		(net "M_D_CPU0_SB_DQ<2>")
	)
	(arc
		(start 330.702412 -274.568666)
		(mid 330.88592 -274.523172)
		(end 331.068172 -274.573492)
		(width 0.0889)
		(layer "In4.Cu")
		(net "M_D_CPU0_SB_DQ<2>")
	)
	(arc
		(start 329.188064 -274.573492)
		(mid 329.47102 -274.649669)
		(end 329.753976 -274.573492)
		(width 0.0889)
		(layer "In4.Cu")
		(net "M_D_CPU0_SB_DQ<2>")
	)
	(arc
		(start 326.367648 -274.573492)
		(mid 326.641503 -274.649842)
		(end 326.917812 -274.58289)
		(width 0.0889)
		(layer "In4.Cu")
		(net "M_D_CPU0_SB_DQ<2>")
	)
	(arc
		(start 334.453992 -274.573492)
		(mid 334.636243 -274.523142)
		(end 334.819752 -274.568666)
		(width 0.0889)
		(layer "In4.Cu")
		(net "M_D_CPU0_SB_DQ<2>")
	)
	(arc
		(start 332.008226 -274.573492)
		(mid 332.291182 -274.649669)
		(end 332.574138 -274.573492)
		(width 0.0889)
		(layer "In4.Cu")
		(net "M_D_CPU0_SB_DQ<2>")
	)
	(arc
		(start 331.068172 -274.573492)
		(mid 331.351128 -274.649669)
		(end 331.634084 -274.573492)
		(width 0.0889)
		(layer "In4.Cu")
		(net "M_D_CPU0_SB_DQ<2>")
	)
	(arc
		(start 334.828134 -274.573492)
		(mid 335.11109 -274.649669)
		(end 335.394046 -274.573492)
		(width 0.0889)
		(layer "In4.Cu")
		(net "M_D_CPU0_SB_DQ<2>")
	)
	(arc
		(start 333.88808 -274.573492)
		(mid 334.171036 -274.649669)
		(end 334.453992 -274.573492)
		(width 0.0889)
		(layer "In4.Cu")
		(net "M_D_CPU0_SB_DQ<2>")
	)
	(arc
		(start 336.342482 -274.568666)
		(mid 336.52599 -274.523172)
		(end 336.708242 -274.573492)
		(width 0.0889)
		(layer "In4.Cu")
		(net "M_D_CPU0_SB_DQ<2>")
	)
	(arc
		(start 326.949816 -274.564348)
		(mid 327.129798 -274.523248)
		(end 327.307448 -274.573492)
		(width 0.0889)
		(layer "In4.Cu")
		(net "M_D_CPU0_SB_DQ<2>")
	)
	(arc
		(start 331.642466 -274.568666)
		(mid 331.825974 -274.523172)
		(end 332.008226 -274.573492)
		(width 0.0889)
		(layer "In4.Cu")
		(net "M_D_CPU0_SB_DQ<2>")
	)
	(arc
		(start 335.768188 -274.573492)
		(mid 336.051144 -274.649669)
		(end 336.3341 -274.573492)
		(width 0.0889)
		(layer "In4.Cu")
		(net "M_D_CPU0_SB_DQ<2>")
	)
	(arc
		(start 332.948026 -274.573492)
		(mid 333.230982 -274.649669)
		(end 333.513938 -274.573492)
		(width 0.0889)
		(layer "In4.Cu")
		(net "M_D_CPU0_SB_DQ<2>")
	)
	(arc
		(start 333.513938 -274.573492)
		(mid 333.696189 -274.523142)
		(end 333.879698 -274.568666)
		(width 0.0889)
		(layer "In4.Cu")
		(net "M_D_CPU0_SB_DQ<2>")
	)
	(arc
		(start 338.213954 -274.573492)
		(mid 338.396205 -274.523142)
		(end 338.579714 -274.568666)
		(width 0.0889)
		(layer "In4.Cu")
		(net "M_D_CPU0_SB_DQ<2>")
	)
	(arc
		(start 328.814176 -274.573492)
		(mid 329.00112 -274.523237)
		(end 329.188064 -274.573492)
		(width 0.0889)
		(layer "In4.Cu")
		(net "M_D_CPU0_SB_DQ<2>")
	)
	(arc
		(start 328.248264 -274.573492)
		(mid 328.53122 -274.649669)
		(end 328.814176 -274.573492)
		(width 0.0889)
		(layer "In4.Cu")
		(net "M_D_CPU0_SB_DQ<2>")
	)
	(arc
		(start 336.708242 -274.573492)
		(mid 336.991198 -274.649669)
		(end 337.274154 -274.573492)
		(width 0.0889)
		(layer "In4.Cu")
		(net "M_D_CPU0_SB_DQ<2>")
	)
	(arc
		(start 337.648042 -274.573492)
		(mid 337.930998 -274.649669)
		(end 338.213954 -274.573492)
		(width 0.0889)
		(layer "In4.Cu")
		(net "M_D_CPU0_SB_DQ<2>")
	)
	(arc
		(start 338.588096 -274.573492)
		(mid 338.835692 -274.64867)
		(end 339.090762 -274.605242)
		(width 0.0889)
		(layer "In4.Cu")
		(net "M_D_CPU0_SB_DQ<2>")
	)
	(arc
		(start 326.252332 -274.484846)
		(mid 326.307117 -274.532906)
		(end 326.367648 -274.573492)
		(width 0.0889)
		(layer "In4.Cu")
		(net "M_D_CPU0_SB_DQ<2>")
	)
	(arc
		(start 330.128118 -274.573492)
		(mid 330.411074 -274.649669)
		(end 330.69403 -274.573492)
		(width 0.0889)
		(layer "In4.Cu")
		(net "M_D_CPU0_SB_DQ<2>")
	)
	(arc
		(start 335.402428 -274.568666)
		(mid 335.585936 -274.523172)
		(end 335.768188 -274.573492)
		(width 0.0889)
		(layer "In4.Cu")
		(net "M_D_CPU0_SB_DQ<2>")
	)
	(segment
		(start 340.747858 -292.450012)
		(end 340.281006 -292.71595)
		(width 0.10668)
		(layer "F.Cu")
		(net "M_D_CPU0_SB_DQ<29>")
	)
	(segment
		(start 286.493966 -317.378334)
		(end 286.493966 -317.830454)
		(width 0.14478)
		(layer "In4.Cu")
		(net "M_D_CPU0_SB_DQ<29>")
	)
	(segment
		(start 307.936646 -317.610236)
		(end 324.184264 -301.362618)
		(width 0.14478)
		(layer "In4.Cu")
		(net "M_D_CPU0_SB_DQ<29>")
	)
	(segment
		(start 289.486594 -317.836296)
		(end 289.486594 -317.384176)
		(width 0.14478)
		(layer "In4.Cu")
		(net "M_D_CPU0_SB_DQ<29>")
	)
	(segment
		(start 340.412832 -293.064692)
		(end 340.435184 -292.98138)
		(width 0.0889)
		(layer "In4.Cu")
		(net "M_D_CPU0_SB_DQ<29>")
	)
	(segment
		(start 293.819072 -317.221362)
		(end 294.207946 -317.610236)
		(width 0.14478)
		(layer "In4.Cu")
		(net "M_D_CPU0_SB_DQ<29>")
	)
	(segment
		(start 328.248264 -294.658542)
		(end 328.278744 -294.640762)
		(width 0.0889)
		(layer "In4.Cu")
		(net "M_D_CPU0_SB_DQ<29>")
	)
	(segment
		(start 335.394046 -293.03853)
		(end 335.402428 -293.043356)
		(width 0.0889)
		(layer "In4.Cu")
		(net "M_D_CPU0_SB_DQ<29>")
	)
	(segment
		(start 329.151742 -293.059612)
		(end 329.188064 -293.03853)
		(width 0.0889)
		(layer "In4.Cu")
		(net "M_D_CPU0_SB_DQ<29>")
	)
	(segment
		(start 290.042854 -317.384176)
		(end 290.042854 -317.836296)
		(width 0.14478)
		(layer "In4.Cu")
		(net "M_D_CPU0_SB_DQ<29>")
	)
	(segment
		(start 286.493966 -317.830454)
		(end 286.65678 -317.993268)
		(width 0.14478)
		(layer "In4.Cu")
		(net "M_D_CPU0_SB_DQ<29>")
	)
	(segment
		(start 285.937706 -317.378334)
		(end 286.10052 -317.21552)
		(width 0.14478)
		(layer "In4.Cu")
		(net "M_D_CPU0_SB_DQ<29>")
	)
	(segment
		(start 291.155374 -317.836296)
		(end 291.318188 -317.99911)
		(width 0.14478)
		(layer "In4.Cu")
		(net "M_D_CPU0_SB_DQ<29>")
	)
	(segment
		(start 324.184264 -301.362618)
		(end 324.184264 -298.8691)
		(width 0.14478)
		(layer "In4.Cu")
		(net "M_D_CPU0_SB_DQ<29>")
	)
	(segment
		(start 286.10052 -317.21552)
		(end 286.331152 -317.21552)
		(width 0.14478)
		(layer "In4.Cu")
		(net "M_D_CPU0_SB_DQ<29>")
	)
	(segment
		(start 328.679048 -293.871396)
		(end 328.718164 -293.848536)
		(width 0.0889)
		(layer "In4.Cu")
		(net "M_D_CPU0_SB_DQ<29>")
	)
	(segment
		(start 330.69403 -293.03853)
		(end 330.702412 -293.043356)
		(width 0.0889)
		(layer "In4.Cu")
		(net "M_D_CPU0_SB_DQ<29>")
	)
	(segment
		(start 327.178416 -296.353992)
		(end 327.340976 -296.259504)
		(width 0.0889)
		(layer "In4.Cu")
		(net "M_D_CPU0_SB_DQ<29>")
	)
	(segment
		(start 293.03218 -317.99911)
		(end 293.262812 -317.99911)
		(width 0.14478)
		(layer "In4.Cu")
		(net "M_D_CPU0_SB_DQ<29>")
	)
	(segment
		(start 286.887412 -317.993268)
		(end 287.050226 -317.830454)
		(width 0.14478)
		(layer "In4.Cu")
		(net "M_D_CPU0_SB_DQ<29>")
	)
	(segment
		(start 328.718164 -293.848536)
		(end 328.749914 -293.830248)
		(width 0.0889)
		(layer "In4.Cu")
		(net "M_D_CPU0_SB_DQ<29>")
	)
	(segment
		(start 292.643306 -317.610236)
		(end 293.03218 -317.99911)
		(width 0.14478)
		(layer "In4.Cu")
		(net "M_D_CPU0_SB_DQ<29>")
	)
	(segment
		(start 290.4363 -317.99911)
		(end 290.599114 -317.836296)
		(width 0.14478)
		(layer "In4.Cu")
		(net "M_D_CPU0_SB_DQ<29>")
	)
	(segment
		(start 291.54882 -317.99911)
		(end 291.937694 -317.610236)
		(width 0.14478)
		(layer "In4.Cu")
		(net "M_D_CPU0_SB_DQ<29>")
	)
	(segment
		(start 338.579714 -293.043356)
		(end 338.588096 -293.03853)
		(width 0.0889)
		(layer "In4.Cu")
		(net "M_D_CPU0_SB_DQ<29>")
	)
	(segment
		(start 324.184264 -298.8691)
		(end 326.566022 -296.487342)
		(width 0.14478)
		(layer "In4.Cu")
		(net "M_D_CPU0_SB_DQ<29>")
	)
	(segment
		(start 334.819752 -293.043356)
		(end 334.828134 -293.03853)
		(width 0.0889)
		(layer "In4.Cu")
		(net "M_D_CPU0_SB_DQ<29>")
	)
	(segment
		(start 340.435184 -292.98138)
		(end 340.281006 -292.71595)
		(width 0.0889)
		(layer "In4.Cu")
		(net "M_D_CPU0_SB_DQ<29>")
	)
	(segment
		(start 330.119736 -293.043356)
		(end 330.128118 -293.03853)
		(width 0.0889)
		(layer "In4.Cu")
		(net "M_D_CPU0_SB_DQ<29>")
	)
	(segment
		(start 284.736032 -317.18504)
		(end 285.54426 -317.993268)
		(width 0.14478)
		(layer "In4.Cu")
		(net "M_D_CPU0_SB_DQ<29>")
	)
	(segment
		(start 290.599114 -317.836296)
		(end 290.599114 -317.603886)
		(width 0.14478)
		(layer "In4.Cu")
		(net "M_D_CPU0_SB_DQ<29>")
	)
	(segment
		(start 290.599114 -317.603886)
		(end 290.761928 -317.441072)
		(width 0.14478)
		(layer "In4.Cu")
		(net "M_D_CPU0_SB_DQ<29>")
	)
	(segment
		(start 328.211942 -294.679624)
		(end 328.248264 -294.658542)
		(width 0.0889)
		(layer "In4.Cu")
		(net "M_D_CPU0_SB_DQ<29>")
	)
	(segment
		(start 326.759062 -296.407332)
		(end 326.98055 -296.407332)
		(width 0.0889)
		(layer "In4.Cu")
		(net "M_D_CPU0_SB_DQ<29>")
	)
	(segment
		(start 331.634084 -293.03853)
		(end 331.642466 -293.043356)
		(width 0.0889)
		(layer "In4.Cu")
		(net "M_D_CPU0_SB_DQ<29>")
	)
	(segment
		(start 290.761928 -317.441072)
		(end 290.99256 -317.441072)
		(width 0.14478)
		(layer "In4.Cu")
		(net "M_D_CPU0_SB_DQ<29>")
	)
	(segment
		(start 327.739248 -295.491408)
		(end 327.778364 -295.468548)
		(width 0.0889)
		(layer "In4.Cu")
		(net "M_D_CPU0_SB_DQ<29>")
	)
	(segment
		(start 336.3341 -293.03853)
		(end 336.342482 -293.043356)
		(width 0.0889)
		(layer "In4.Cu")
		(net "M_D_CPU0_SB_DQ<29>")
	)
	(segment
		(start 291.937694 -317.610236)
		(end 292.643306 -317.610236)
		(width 0.14478)
		(layer "In4.Cu")
		(net "M_D_CPU0_SB_DQ<29>")
	)
	(segment
		(start 289.093148 -317.99911)
		(end 289.32378 -317.99911)
		(width 0.14478)
		(layer "In4.Cu")
		(net "M_D_CPU0_SB_DQ<29>")
	)
	(segment
		(start 333.879698 -293.043356)
		(end 333.88808 -293.03853)
		(width 0.0889)
		(layer "In4.Cu")
		(net "M_D_CPU0_SB_DQ<29>")
	)
	(segment
		(start 285.54426 -317.993268)
		(end 285.774892 -317.993268)
		(width 0.14478)
		(layer "In4.Cu")
		(net "M_D_CPU0_SB_DQ<29>")
	)
	(segment
		(start 286.65678 -317.993268)
		(end 286.887412 -317.993268)
		(width 0.14478)
		(layer "In4.Cu")
		(net "M_D_CPU0_SB_DQ<29>")
	)
	(segment
		(start 291.155374 -317.603886)
		(end 291.155374 -317.836296)
		(width 0.14478)
		(layer "In4.Cu")
		(net "M_D_CPU0_SB_DQ<29>")
	)
	(segment
		(start 287.050226 -317.830454)
		(end 287.050226 -317.378334)
		(width 0.14478)
		(layer "In4.Cu")
		(net "M_D_CPU0_SB_DQ<29>")
	)
	(segment
		(start 287.838388 -317.610236)
		(end 288.704274 -317.610236)
		(width 0.14478)
		(layer "In4.Cu")
		(net "M_D_CPU0_SB_DQ<29>")
	)
	(segment
		(start 288.704274 -317.610236)
		(end 289.093148 -317.99911)
		(width 0.14478)
		(layer "In4.Cu")
		(net "M_D_CPU0_SB_DQ<29>")
	)
	(segment
		(start 287.443672 -317.21552)
		(end 287.838388 -317.610236)
		(width 0.14478)
		(layer "In4.Cu")
		(net "M_D_CPU0_SB_DQ<29>")
	)
	(segment
		(start 287.21304 -317.21552)
		(end 287.443672 -317.21552)
		(width 0.14478)
		(layer "In4.Cu")
		(net "M_D_CPU0_SB_DQ<29>")
	)
	(segment
		(start 293.262812 -317.99911)
		(end 293.425626 -317.836296)
		(width 0.14478)
		(layer "In4.Cu")
		(net "M_D_CPU0_SB_DQ<29>")
	)
	(segment
		(start 290.205668 -317.99911)
		(end 290.4363 -317.99911)
		(width 0.14478)
		(layer "In4.Cu")
		(net "M_D_CPU0_SB_DQ<29>")
	)
	(segment
		(start 339.519768 -293.043356)
		(end 339.52815 -293.03853)
		(width 0.0889)
		(layer "In4.Cu")
		(net "M_D_CPU0_SB_DQ<29>")
	)
	(segment
		(start 340.094062 -293.03853)
		(end 340.102444 -293.043356)
		(width 0.0889)
		(layer "In4.Cu")
		(net "M_D_CPU0_SB_DQ<29>")
	)
	(segment
		(start 289.649408 -317.221362)
		(end 289.88004 -317.221362)
		(width 0.14478)
		(layer "In4.Cu")
		(net "M_D_CPU0_SB_DQ<29>")
	)
	(segment
		(start 286.331152 -317.21552)
		(end 286.493966 -317.378334)
		(width 0.14478)
		(layer "In4.Cu")
		(net "M_D_CPU0_SB_DQ<29>")
	)
	(segment
		(start 289.88004 -317.221362)
		(end 290.042854 -317.384176)
		(width 0.14478)
		(layer "In4.Cu")
		(net "M_D_CPU0_SB_DQ<29>")
	)
	(segment
		(start 293.425626 -317.836296)
		(end 293.425626 -317.384176)
		(width 0.14478)
		(layer "In4.Cu")
		(net "M_D_CPU0_SB_DQ<29>")
	)
	(segment
		(start 290.99256 -317.441072)
		(end 291.155374 -317.603886)
		(width 0.14478)
		(layer "In4.Cu")
		(net "M_D_CPU0_SB_DQ<29>")
	)
	(segment
		(start 285.774892 -317.993268)
		(end 285.937706 -317.830454)
		(width 0.14478)
		(layer "In4.Cu")
		(net "M_D_CPU0_SB_DQ<29>")
	)
	(segment
		(start 285.937706 -317.830454)
		(end 285.937706 -317.378334)
		(width 0.14478)
		(layer "In4.Cu")
		(net "M_D_CPU0_SB_DQ<29>")
	)
	(segment
		(start 293.425626 -317.384176)
		(end 293.58844 -317.221362)
		(width 0.14478)
		(layer "In4.Cu")
		(net "M_D_CPU0_SB_DQ<29>")
	)
	(segment
		(start 289.32378 -317.99911)
		(end 289.486594 -317.836296)
		(width 0.14478)
		(layer "In4.Cu")
		(net "M_D_CPU0_SB_DQ<29>")
	)
	(segment
		(start 289.486594 -317.384176)
		(end 289.649408 -317.221362)
		(width 0.14478)
		(layer "In4.Cu")
		(net "M_D_CPU0_SB_DQ<29>")
	)
	(segment
		(start 293.58844 -317.221362)
		(end 293.819072 -317.221362)
		(width 0.14478)
		(layer "In4.Cu")
		(net "M_D_CPU0_SB_DQ<29>")
	)
	(segment
		(start 291.318188 -317.99911)
		(end 291.54882 -317.99911)
		(width 0.14478)
		(layer "In4.Cu")
		(net "M_D_CPU0_SB_DQ<29>")
	)
	(segment
		(start 327.778364 -295.468548)
		(end 327.810114 -295.45026)
		(width 0.0889)
		(layer "In4.Cu")
		(net "M_D_CPU0_SB_DQ<29>")
	)
	(segment
		(start 290.042854 -317.836296)
		(end 290.205668 -317.99911)
		(width 0.14478)
		(layer "In4.Cu")
		(net "M_D_CPU0_SB_DQ<29>")
	)
	(segment
		(start 287.050226 -317.378334)
		(end 287.21304 -317.21552)
		(width 0.14478)
		(layer "In4.Cu")
		(net "M_D_CPU0_SB_DQ<29>")
	)
	(segment
		(start 294.207946 -317.610236)
		(end 307.936646 -317.610236)
		(width 0.14478)
		(layer "In4.Cu")
		(net "M_D_CPU0_SB_DQ<29>")
	)
	(arc
		(start 329.188064 -293.03853)
		(mid 329.47102 -292.962353)
		(end 329.753976 -293.03853)
		(width 0.0889)
		(layer "In4.Cu")
		(net "M_D_CPU0_SB_DQ<29>")
	)
	(arc
		(start 332.008226 -293.03853)
		(mid 332.291182 -292.962353)
		(end 332.574138 -293.03853)
		(width 0.0889)
		(layer "In4.Cu")
		(net "M_D_CPU0_SB_DQ<29>")
	)
	(arc
		(start 327.340976 -296.259504)
		(mid 327.454905 -296.126357)
		(end 327.495916 -295.955974)
		(width 0.0889)
		(layer "In4.Cu")
		(net "M_D_CPU0_SB_DQ<29>")
	)
	(arc
		(start 340.102444 -293.043356)
		(mid 340.255314 -293.087997)
		(end 340.412832 -293.064692)
		(width 0.0889)
		(layer "In4.Cu")
		(net "M_D_CPU0_SB_DQ<29>")
	)
	(arc
		(start 334.453992 -293.03853)
		(mid 334.636243 -293.08888)
		(end 334.819752 -293.043356)
		(width 0.0889)
		(layer "In4.Cu")
		(net "M_D_CPU0_SB_DQ<29>")
	)
	(arc
		(start 326.98055 -296.407332)
		(mid 327.083015 -296.393764)
		(end 327.178416 -296.353992)
		(width 0.0889)
		(layer "In4.Cu")
		(net "M_D_CPU0_SB_DQ<29>")
	)
	(arc
		(start 328.435716 -294.335962)
		(mid 328.500231 -294.073743)
		(end 328.679048 -293.871396)
		(width 0.0889)
		(layer "In4.Cu")
		(net "M_D_CPU0_SB_DQ<29>")
	)
	(arc
		(start 332.574138 -293.03853)
		(mid 332.761082 -293.088785)
		(end 332.948026 -293.03853)
		(width 0.0889)
		(layer "In4.Cu")
		(net "M_D_CPU0_SB_DQ<29>")
	)
	(arc
		(start 336.342482 -293.043356)
		(mid 336.52599 -293.08885)
		(end 336.708242 -293.03853)
		(width 0.0889)
		(layer "In4.Cu")
		(net "M_D_CPU0_SB_DQ<29>")
	)
	(arc
		(start 334.828134 -293.03853)
		(mid 335.11109 -292.962353)
		(end 335.394046 -293.03853)
		(width 0.0889)
		(layer "In4.Cu")
		(net "M_D_CPU0_SB_DQ<29>")
	)
	(arc
		(start 337.648042 -293.03853)
		(mid 337.930998 -292.962353)
		(end 338.213954 -293.03853)
		(width 0.0889)
		(layer "In4.Cu")
		(net "M_D_CPU0_SB_DQ<29>")
	)
	(arc
		(start 327.810114 -295.45026)
		(mid 327.92479 -295.316926)
		(end 327.96607 -295.145968)
		(width 0.0889)
		(layer "In4.Cu")
		(net "M_D_CPU0_SB_DQ<29>")
	)
	(arc
		(start 330.128118 -293.03853)
		(mid 330.411074 -292.962353)
		(end 330.69403 -293.03853)
		(width 0.0889)
		(layer "In4.Cu")
		(net "M_D_CPU0_SB_DQ<29>")
	)
	(arc
		(start 339.52815 -293.03853)
		(mid 339.811106 -292.962353)
		(end 340.094062 -293.03853)
		(width 0.0889)
		(layer "In4.Cu")
		(net "M_D_CPU0_SB_DQ<29>")
	)
	(arc
		(start 336.708242 -293.03853)
		(mid 336.991198 -292.962353)
		(end 337.274154 -293.03853)
		(width 0.0889)
		(layer "In4.Cu")
		(net "M_D_CPU0_SB_DQ<29>")
	)
	(arc
		(start 333.513938 -293.03853)
		(mid 333.696189 -293.08888)
		(end 333.879698 -293.043356)
		(width 0.0889)
		(layer "In4.Cu")
		(net "M_D_CPU0_SB_DQ<29>")
	)
	(arc
		(start 332.948026 -293.03853)
		(mid 333.230982 -292.962353)
		(end 333.513938 -293.03853)
		(width 0.0889)
		(layer "In4.Cu")
		(net "M_D_CPU0_SB_DQ<29>")
	)
	(arc
		(start 326.566022 -296.487342)
		(mid 326.65459 -296.428163)
		(end 326.759062 -296.407332)
		(width 0.0889)
		(layer "In4.Cu")
		(net "M_D_CPU0_SB_DQ<29>")
	)
	(arc
		(start 337.274154 -293.03853)
		(mid 337.461098 -293.088785)
		(end 337.648042 -293.03853)
		(width 0.0889)
		(layer "In4.Cu")
		(net "M_D_CPU0_SB_DQ<29>")
	)
	(arc
		(start 331.642466 -293.043356)
		(mid 331.825974 -293.08885)
		(end 332.008226 -293.03853)
		(width 0.0889)
		(layer "In4.Cu")
		(net "M_D_CPU0_SB_DQ<29>")
	)
	(arc
		(start 329.753976 -293.03853)
		(mid 329.936227 -293.08888)
		(end 330.119736 -293.043356)
		(width 0.0889)
		(layer "In4.Cu")
		(net "M_D_CPU0_SB_DQ<29>")
	)
	(arc
		(start 328.90587 -293.525956)
		(mid 328.971106 -293.262365)
		(end 329.151742 -293.059612)
		(width 0.0889)
		(layer "In4.Cu")
		(net "M_D_CPU0_SB_DQ<29>")
	)
	(arc
		(start 335.768188 -293.03853)
		(mid 336.051144 -292.962353)
		(end 336.3341 -293.03853)
		(width 0.0889)
		(layer "In4.Cu")
		(net "M_D_CPU0_SB_DQ<29>")
	)
	(arc
		(start 333.88808 -293.03853)
		(mid 334.171036 -292.962353)
		(end 334.453992 -293.03853)
		(width 0.0889)
		(layer "In4.Cu")
		(net "M_D_CPU0_SB_DQ<29>")
	)
	(arc
		(start 335.402428 -293.043356)
		(mid 335.585936 -293.08885)
		(end 335.768188 -293.03853)
		(width 0.0889)
		(layer "In4.Cu")
		(net "M_D_CPU0_SB_DQ<29>")
	)
	(arc
		(start 328.749914 -293.830248)
		(mid 328.86459 -293.696914)
		(end 328.90587 -293.525956)
		(width 0.0889)
		(layer "In4.Cu")
		(net "M_D_CPU0_SB_DQ<29>")
	)
	(arc
		(start 331.068172 -293.03853)
		(mid 331.351128 -292.962353)
		(end 331.634084 -293.03853)
		(width 0.0889)
		(layer "In4.Cu")
		(net "M_D_CPU0_SB_DQ<29>")
	)
	(arc
		(start 328.278744 -294.640762)
		(mid 328.394171 -294.507386)
		(end 328.435716 -294.335962)
		(width 0.0889)
		(layer "In4.Cu")
		(net "M_D_CPU0_SB_DQ<29>")
	)
	(arc
		(start 327.495916 -295.955974)
		(mid 327.560431 -295.693755)
		(end 327.739248 -295.491408)
		(width 0.0889)
		(layer "In4.Cu")
		(net "M_D_CPU0_SB_DQ<29>")
	)
	(arc
		(start 338.588096 -293.03853)
		(mid 338.871052 -292.962353)
		(end 339.154008 -293.03853)
		(width 0.0889)
		(layer "In4.Cu")
		(net "M_D_CPU0_SB_DQ<29>")
	)
	(arc
		(start 339.154008 -293.03853)
		(mid 339.336259 -293.08888)
		(end 339.519768 -293.043356)
		(width 0.0889)
		(layer "In4.Cu")
		(net "M_D_CPU0_SB_DQ<29>")
	)
	(arc
		(start 330.702412 -293.043356)
		(mid 330.88592 -293.08885)
		(end 331.068172 -293.03853)
		(width 0.0889)
		(layer "In4.Cu")
		(net "M_D_CPU0_SB_DQ<29>")
	)
	(arc
		(start 338.213954 -293.03853)
		(mid 338.396205 -293.08888)
		(end 338.579714 -293.043356)
		(width 0.0889)
		(layer "In4.Cu")
		(net "M_D_CPU0_SB_DQ<29>")
	)
	(arc
		(start 327.96607 -295.145968)
		(mid 328.031306 -294.882377)
		(end 328.211942 -294.679624)
		(width 0.0889)
		(layer "In4.Cu")
		(net "M_D_CPU0_SB_DQ<29>")
	)
	(segment
		(start 339.337904 -291.640006)
		(end 338.871052 -291.905944)
		(width 0.10668)
		(layer "F.Cu")
		(net "M_D_CPU0_SB_DQ<28>")
	)
	(segment
		(start 301.52594 -315.56071)
		(end 301.756572 -315.56071)
		(width 0.14478)
		(layer "In4.Cu")
		(net "M_D_CPU0_SB_DQ<28>")
	)
	(segment
		(start 291.63264 -315.7474)
		(end 291.795454 -315.910214)
		(width 0.14478)
		(layer "In4.Cu")
		(net "M_D_CPU0_SB_DQ<28>")
	)
	(segment
		(start 301.200312 -316.259718)
		(end 301.363126 -316.096904)
		(width 0.14478)
		(layer "In4.Cu")
		(net "M_D_CPU0_SB_DQ<28>")
	)
	(segment
		(start 301.756572 -315.56071)
		(end 301.919386 -315.723524)
		(width 0.14478)
		(layer "In4.Cu")
		(net "M_D_CPU0_SB_DQ<28>")
	)
	(segment
		(start 300.063916 -315.910214)
		(end 300.41342 -315.56071)
		(width 0.14478)
		(layer "In4.Cu")
		(net "M_D_CPU0_SB_DQ<28>")
	)
	(segment
		(start 300.806866 -315.723524)
		(end 300.806866 -316.096904)
		(width 0.14478)
		(layer "In4.Cu")
		(net "M_D_CPU0_SB_DQ<28>")
	)
	(segment
		(start 303.031906 -316.096904)
		(end 303.19472 -316.259718)
		(width 0.14478)
		(layer "In4.Cu")
		(net "M_D_CPU0_SB_DQ<28>")
	)
	(segment
		(start 287.26892 -315.919866)
		(end 288.647378 -315.919866)
		(width 0.14478)
		(layer "In4.Cu")
		(net "M_D_CPU0_SB_DQ<28>")
	)
	(segment
		(start 302.63846 -315.56071)
		(end 302.869092 -315.56071)
		(width 0.14478)
		(layer "In4.Cu")
		(net "M_D_CPU0_SB_DQ<28>")
	)
	(segment
		(start 300.806866 -316.096904)
		(end 300.96968 -316.259718)
		(width 0.14478)
		(layer "In4.Cu")
		(net "M_D_CPU0_SB_DQ<28>")
	)
	(segment
		(start 290.77666 -315.910214)
		(end 291.07638 -315.610494)
		(width 0.14478)
		(layer "In4.Cu")
		(net "M_D_CPU0_SB_DQ<28>")
	)
	(segment
		(start 329.284076 -292.228524)
		(end 329.292458 -292.23335)
		(width 0.0889)
		(layer "In4.Cu")
		(net "M_D_CPU0_SB_DQ<28>")
	)
	(segment
		(start 297.037506 -315.910214)
		(end 297.28287 -315.910214)
		(width 0.14478)
		(layer "In4.Cu")
		(net "M_D_CPU0_SB_DQ<28>")
	)
	(segment
		(start 292.763194 -316.22111)
		(end 293.008558 -316.22111)
		(width 0.14478)
		(layer "In4.Cu")
		(net "M_D_CPU0_SB_DQ<28>")
	)
	(segment
		(start 295.534842 -315.919866)
		(end 296.180002 -315.919866)
		(width 0.14478)
		(layer "In4.Cu")
		(net "M_D_CPU0_SB_DQ<28>")
	)
	(segment
		(start 289.193986 -316.22111)
		(end 289.504882 -315.910214)
		(width 0.14478)
		(layer "In4.Cu")
		(net "M_D_CPU0_SB_DQ<28>")
	)
	(segment
		(start 298.706286 -316.22111)
		(end 298.95165 -316.22111)
		(width 0.14478)
		(layer "In4.Cu")
		(net "M_D_CPU0_SB_DQ<28>")
	)
	(segment
		(start 303.588166 -315.723524)
		(end 303.75098 -315.56071)
		(width 0.14478)
		(layer "In4.Cu")
		(net "M_D_CPU0_SB_DQ<28>")
	)
	(segment
		(start 327.269094 -293.06139)
		(end 327.30821 -293.03853)
		(width 0.0889)
		(layer "In4.Cu")
		(net "M_D_CPU0_SB_DQ<28>")
	)
	(segment
		(start 337.16976 -292.23335)
		(end 337.178142 -292.228524)
		(width 0.0889)
		(layer "In4.Cu")
		(net "M_D_CPU0_SB_DQ<28>")
	)
	(segment
		(start 286.722312 -316.22111)
		(end 286.967676 -316.22111)
		(width 0.14478)
		(layer "In4.Cu")
		(net "M_D_CPU0_SB_DQ<28>")
	)
	(segment
		(start 285.256224 -316.00521)
		(end 286.506412 -316.00521)
		(width 0.14478)
		(layer "In4.Cu")
		(net "M_D_CPU0_SB_DQ<28>")
	)
	(segment
		(start 294.121078 -316.22111)
		(end 294.422322 -315.919866)
		(width 0.14478)
		(layer "In4.Cu")
		(net "M_D_CPU0_SB_DQ<28>")
	)
	(segment
		(start 303.19472 -316.259718)
		(end 303.425352 -316.259718)
		(width 0.14478)
		(layer "In4.Cu")
		(net "M_D_CPU0_SB_DQ<28>")
	)
	(segment
		(start 284.736032 -315.485018)
		(end 285.256224 -316.00521)
		(width 0.14478)
		(layer "In4.Cu")
		(net "M_D_CPU0_SB_DQ<28>")
	)
	(segment
		(start 298.95165 -316.22111)
		(end 299.262546 -315.910214)
		(width 0.14478)
		(layer "In4.Cu")
		(net "M_D_CPU0_SB_DQ<28>")
	)
	(segment
		(start 296.481246 -316.22111)
		(end 296.72661 -316.22111)
		(width 0.14478)
		(layer "In4.Cu")
		(net "M_D_CPU0_SB_DQ<28>")
	)
	(segment
		(start 303.031906 -315.723524)
		(end 303.031906 -316.096904)
		(width 0.14478)
		(layer "In4.Cu")
		(net "M_D_CPU0_SB_DQ<28>")
	)
	(segment
		(start 292.452298 -315.910214)
		(end 292.763194 -316.22111)
		(width 0.14478)
		(layer "In4.Cu")
		(net "M_D_CPU0_SB_DQ<28>")
	)
	(segment
		(start 293.008558 -316.22111)
		(end 293.319454 -315.910214)
		(width 0.14478)
		(layer "In4.Cu")
		(net "M_D_CPU0_SB_DQ<28>")
	)
	(segment
		(start 328.71791 -292.228524)
		(end 328.718164 -292.228524)
		(width 0.0889)
		(layer "In4.Cu")
		(net "M_D_CPU0_SB_DQ<28>")
	)
	(segment
		(start 302.869092 -315.56071)
		(end 303.031906 -315.723524)
		(width 0.14478)
		(layer "In4.Cu")
		(net "M_D_CPU0_SB_DQ<28>")
	)
	(segment
		(start 305.571144 -315.910214)
		(end 305.816508 -315.910214)
		(width 0.14478)
		(layer "In4.Cu")
		(net "M_D_CPU0_SB_DQ<28>")
	)
	(segment
		(start 288.647378 -315.919866)
		(end 288.948622 -316.22111)
		(width 0.14478)
		(layer "In4.Cu")
		(net "M_D_CPU0_SB_DQ<28>")
	)
	(segment
		(start 304.331116 -315.910214)
		(end 304.703988 -315.910214)
		(width 0.14478)
		(layer "In4.Cu")
		(net "M_D_CPU0_SB_DQ<28>")
	)
	(segment
		(start 293.564818 -315.910214)
		(end 293.875714 -316.22111)
		(width 0.14478)
		(layer "In4.Cu")
		(net "M_D_CPU0_SB_DQ<28>")
	)
	(segment
		(start 306.372768 -316.22111)
		(end 306.683664 -315.910214)
		(width 0.14478)
		(layer "In4.Cu")
		(net "M_D_CPU0_SB_DQ<28>")
	)
	(segment
		(start 289.504882 -315.910214)
		(end 290.77666 -315.910214)
		(width 0.14478)
		(layer "In4.Cu")
		(net "M_D_CPU0_SB_DQ<28>")
	)
	(segment
		(start 305.014884 -316.22111)
		(end 305.260248 -316.22111)
		(width 0.14478)
		(layer "In4.Cu")
		(net "M_D_CPU0_SB_DQ<28>")
	)
	(segment
		(start 291.239194 -315.12891)
		(end 291.469826 -315.12891)
		(width 0.14478)
		(layer "In4.Cu")
		(net "M_D_CPU0_SB_DQ<28>")
	)
	(segment
		(start 291.07638 -315.610494)
		(end 291.07638 -315.291724)
		(width 0.14478)
		(layer "In4.Cu")
		(net "M_D_CPU0_SB_DQ<28>")
	)
	(segment
		(start 332.469744 -292.23335)
		(end 332.478126 -292.228524)
		(width 0.0889)
		(layer "In4.Cu")
		(net "M_D_CPU0_SB_DQ<28>")
	)
	(segment
		(start 304.703988 -315.910214)
		(end 305.014884 -316.22111)
		(width 0.14478)
		(layer "In4.Cu")
		(net "M_D_CPU0_SB_DQ<28>")
	)
	(segment
		(start 288.948622 -316.22111)
		(end 289.193986 -316.22111)
		(width 0.14478)
		(layer "In4.Cu")
		(net "M_D_CPU0_SB_DQ<28>")
	)
	(segment
		(start 305.816508 -315.910214)
		(end 306.127404 -316.22111)
		(width 0.14478)
		(layer "In4.Cu")
		(net "M_D_CPU0_SB_DQ<28>")
	)
	(segment
		(start 300.96968 -316.259718)
		(end 301.200312 -316.259718)
		(width 0.14478)
		(layer "In4.Cu")
		(net "M_D_CPU0_SB_DQ<28>")
	)
	(segment
		(start 303.588166 -316.096904)
		(end 303.588166 -315.723524)
		(width 0.14478)
		(layer "In4.Cu")
		(net "M_D_CPU0_SB_DQ<28>")
	)
	(segment
		(start 297.593766 -316.22111)
		(end 297.83913 -316.22111)
		(width 0.14478)
		(layer "In4.Cu")
		(net "M_D_CPU0_SB_DQ<28>")
	)
	(segment
		(start 303.75098 -315.56071)
		(end 303.981612 -315.56071)
		(width 0.14478)
		(layer "In4.Cu")
		(net "M_D_CPU0_SB_DQ<28>")
	)
	(segment
		(start 302.0822 -316.259718)
		(end 302.312832 -316.259718)
		(width 0.14478)
		(layer "In4.Cu")
		(net "M_D_CPU0_SB_DQ<28>")
	)
	(segment
		(start 300.41342 -315.56071)
		(end 300.644052 -315.56071)
		(width 0.14478)
		(layer "In4.Cu")
		(net "M_D_CPU0_SB_DQ<28>")
	)
	(segment
		(start 297.83913 -316.22111)
		(end 298.150026 -315.910214)
		(width 0.14478)
		(layer "In4.Cu")
		(net "M_D_CPU0_SB_DQ<28>")
	)
	(segment
		(start 327.30821 -293.03853)
		(end 327.33869 -293.02075)
		(width 0.0889)
		(layer "In4.Cu")
		(net "M_D_CPU0_SB_DQ<28>")
	)
	(segment
		(start 296.72661 -316.22111)
		(end 297.037506 -315.910214)
		(width 0.14478)
		(layer "In4.Cu")
		(net "M_D_CPU0_SB_DQ<28>")
	)
	(segment
		(start 326.838056 -293.848536)
		(end 326.869806 -293.830248)
		(width 0.0889)
		(layer "In4.Cu")
		(net "M_D_CPU0_SB_DQ<28>")
	)
	(segment
		(start 326.80021 -293.87038)
		(end 326.838056 -293.848536)
		(width 0.0889)
		(layer "In4.Cu")
		(net "M_D_CPU0_SB_DQ<28>")
	)
	(segment
		(start 323.214492 -300.82109)
		(end 323.214492 -298.467272)
		(width 0.14478)
		(layer "In4.Cu")
		(net "M_D_CPU0_SB_DQ<28>")
	)
	(segment
		(start 306.127404 -316.22111)
		(end 306.372768 -316.22111)
		(width 0.14478)
		(layer "In4.Cu")
		(net "M_D_CPU0_SB_DQ<28>")
	)
	(segment
		(start 301.919386 -315.723524)
		(end 301.919386 -316.096904)
		(width 0.14478)
		(layer "In4.Cu")
		(net "M_D_CPU0_SB_DQ<28>")
	)
	(segment
		(start 291.07638 -315.291724)
		(end 291.239194 -315.12891)
		(width 0.14478)
		(layer "In4.Cu")
		(net "M_D_CPU0_SB_DQ<28>")
	)
	(segment
		(start 301.919386 -316.096904)
		(end 302.0822 -316.259718)
		(width 0.14478)
		(layer "In4.Cu")
		(net "M_D_CPU0_SB_DQ<28>")
	)
	(segment
		(start 303.425352 -316.259718)
		(end 303.588166 -316.096904)
		(width 0.14478)
		(layer "In4.Cu")
		(net "M_D_CPU0_SB_DQ<28>")
	)
	(segment
		(start 302.475646 -316.096904)
		(end 302.475646 -315.723524)
		(width 0.14478)
		(layer "In4.Cu")
		(net "M_D_CPU0_SB_DQ<28>")
	)
	(segment
		(start 336.229706 -292.23335)
		(end 336.238088 -292.228524)
		(width 0.0889)
		(layer "In4.Cu")
		(net "M_D_CPU0_SB_DQ<28>")
	)
	(segment
		(start 291.795454 -315.910214)
		(end 292.452298 -315.910214)
		(width 0.14478)
		(layer "In4.Cu")
		(net "M_D_CPU0_SB_DQ<28>")
	)
	(segment
		(start 331.52969 -292.23335)
		(end 331.538072 -292.228524)
		(width 0.0889)
		(layer "In4.Cu")
		(net "M_D_CPU0_SB_DQ<28>")
	)
	(segment
		(start 302.475646 -315.723524)
		(end 302.63846 -315.56071)
		(width 0.14478)
		(layer "In4.Cu")
		(net "M_D_CPU0_SB_DQ<28>")
	)
	(segment
		(start 301.363126 -315.723524)
		(end 301.52594 -315.56071)
		(width 0.14478)
		(layer "In4.Cu")
		(net "M_D_CPU0_SB_DQ<28>")
	)
	(segment
		(start 333.044038 -292.228524)
		(end 333.05242 -292.23335)
		(width 0.0889)
		(layer "In4.Cu")
		(net "M_D_CPU0_SB_DQ<28>")
	)
	(segment
		(start 295.233598 -316.22111)
		(end 295.534842 -315.919866)
		(width 0.14478)
		(layer "In4.Cu")
		(net "M_D_CPU0_SB_DQ<28>")
	)
	(segment
		(start 325.640954 -296.04081)
		(end 325.782178 -295.899586)
		(width 0.0889)
		(layer "In4.Cu")
		(net "M_D_CPU0_SB_DQ<28>")
	)
	(segment
		(start 293.875714 -316.22111)
		(end 294.121078 -316.22111)
		(width 0.14478)
		(layer "In4.Cu")
		(net "M_D_CPU0_SB_DQ<28>")
	)
	(segment
		(start 303.981612 -315.56071)
		(end 304.331116 -315.910214)
		(width 0.14478)
		(layer "In4.Cu")
		(net "M_D_CPU0_SB_DQ<28>")
	)
	(segment
		(start 338.684108 -292.228524)
		(end 338.69249 -292.23335)
		(width 0.0889)
		(layer "In4.Cu")
		(net "M_D_CPU0_SB_DQ<28>")
	)
	(segment
		(start 305.260248 -316.22111)
		(end 305.571144 -315.910214)
		(width 0.14478)
		(layer "In4.Cu")
		(net "M_D_CPU0_SB_DQ<28>")
	)
	(segment
		(start 323.214492 -298.467272)
		(end 325.640954 -296.04081)
		(width 0.14478)
		(layer "In4.Cu")
		(net "M_D_CPU0_SB_DQ<28>")
	)
	(segment
		(start 299.262546 -315.910214)
		(end 300.063916 -315.910214)
		(width 0.14478)
		(layer "In4.Cu")
		(net "M_D_CPU0_SB_DQ<28>")
	)
	(segment
		(start 339.002878 -292.254686)
		(end 339.02523 -292.171374)
		(width 0.0889)
		(layer "In4.Cu")
		(net "M_D_CPU0_SB_DQ<28>")
	)
	(segment
		(start 339.02523 -292.171374)
		(end 338.871052 -291.905944)
		(width 0.0889)
		(layer "In4.Cu")
		(net "M_D_CPU0_SB_DQ<28>")
	)
	(segment
		(start 296.180002 -315.919866)
		(end 296.481246 -316.22111)
		(width 0.14478)
		(layer "In4.Cu")
		(net "M_D_CPU0_SB_DQ<28>")
	)
	(segment
		(start 293.319454 -315.910214)
		(end 293.564818 -315.910214)
		(width 0.14478)
		(layer "In4.Cu")
		(net "M_D_CPU0_SB_DQ<28>")
	)
	(segment
		(start 298.39539 -315.910214)
		(end 298.706286 -316.22111)
		(width 0.14478)
		(layer "In4.Cu")
		(net "M_D_CPU0_SB_DQ<28>")
	)
	(segment
		(start 297.28287 -315.910214)
		(end 297.593766 -316.22111)
		(width 0.14478)
		(layer "In4.Cu")
		(net "M_D_CPU0_SB_DQ<28>")
	)
	(segment
		(start 291.469826 -315.12891)
		(end 291.63264 -315.291724)
		(width 0.14478)
		(layer "In4.Cu")
		(net "M_D_CPU0_SB_DQ<28>")
	)
	(segment
		(start 286.967676 -316.22111)
		(end 287.26892 -315.919866)
		(width 0.14478)
		(layer "In4.Cu")
		(net "M_D_CPU0_SB_DQ<28>")
	)
	(segment
		(start 291.63264 -315.291724)
		(end 291.63264 -315.7474)
		(width 0.14478)
		(layer "In4.Cu")
		(net "M_D_CPU0_SB_DQ<28>")
	)
	(segment
		(start 294.68699 -315.919866)
		(end 294.988234 -316.22111)
		(width 0.14478)
		(layer "In4.Cu")
		(net "M_D_CPU0_SB_DQ<28>")
	)
	(segment
		(start 294.988234 -316.22111)
		(end 295.233598 -316.22111)
		(width 0.14478)
		(layer "In4.Cu")
		(net "M_D_CPU0_SB_DQ<28>")
	)
	(segment
		(start 301.363126 -316.096904)
		(end 301.363126 -315.723524)
		(width 0.14478)
		(layer "In4.Cu")
		(net "M_D_CPU0_SB_DQ<28>")
	)
	(segment
		(start 326.079612 -295.181528)
		(end 326.079612 -295.145968)
		(width 0.0889)
		(layer "In4.Cu")
		(net "M_D_CPU0_SB_DQ<28>")
	)
	(segment
		(start 300.644052 -315.56071)
		(end 300.806866 -315.723524)
		(width 0.14478)
		(layer "In4.Cu")
		(net "M_D_CPU0_SB_DQ<28>")
	)
	(segment
		(start 302.312832 -316.259718)
		(end 302.475646 -316.096904)
		(width 0.14478)
		(layer "In4.Cu")
		(net "M_D_CPU0_SB_DQ<28>")
	)
	(segment
		(start 327.738994 -292.251384)
		(end 327.77811 -292.228524)
		(width 0.0889)
		(layer "In4.Cu")
		(net "M_D_CPU0_SB_DQ<28>")
	)
	(segment
		(start 298.150026 -315.910214)
		(end 298.39539 -315.910214)
		(width 0.14478)
		(layer "In4.Cu")
		(net "M_D_CPU0_SB_DQ<28>")
	)
	(segment
		(start 326.357234 -294.664638)
		(end 326.398636 -294.640762)
		(width 0.0889)
		(layer "In4.Cu")
		(net "M_D_CPU0_SB_DQ<28>")
	)
	(segment
		(start 294.422322 -315.919866)
		(end 294.68699 -315.919866)
		(width 0.14478)
		(layer "In4.Cu")
		(net "M_D_CPU0_SB_DQ<28>")
	)
	(segment
		(start 337.744054 -292.228524)
		(end 337.752436 -292.23335)
		(width 0.0889)
		(layer "In4.Cu")
		(net "M_D_CPU0_SB_DQ<28>")
	)
	(segment
		(start 286.506412 -316.00521)
		(end 286.722312 -316.22111)
		(width 0.14478)
		(layer "In4.Cu")
		(net "M_D_CPU0_SB_DQ<28>")
	)
	(segment
		(start 306.683664 -315.910214)
		(end 308.125368 -315.910214)
		(width 0.14478)
		(layer "In4.Cu")
		(net "M_D_CPU0_SB_DQ<28>")
	)
	(segment
		(start 333.984092 -292.228524)
		(end 333.992474 -292.23335)
		(width 0.0889)
		(layer "In4.Cu")
		(net "M_D_CPU0_SB_DQ<28>")
	)
	(segment
		(start 308.125368 -315.910214)
		(end 323.214492 -300.82109)
		(width 0.14478)
		(layer "In4.Cu")
		(net "M_D_CPU0_SB_DQ<28>")
	)
	(arc
		(start 326.869806 -293.830248)
		(mid 326.984482 -293.696914)
		(end 327.025762 -293.525956)
		(width 0.0889)
		(layer "In4.Cu")
		(net "M_D_CPU0_SB_DQ<28>")
	)
	(arc
		(start 326.398636 -294.640762)
		(mid 326.514063 -294.507386)
		(end 326.555608 -294.335962)
		(width 0.0889)
		(layer "In4.Cu")
		(net "M_D_CPU0_SB_DQ<28>")
	)
	(arc
		(start 337.178142 -292.228524)
		(mid 337.461098 -292.152347)
		(end 337.744054 -292.228524)
		(width 0.0889)
		(layer "In4.Cu")
		(net "M_D_CPU0_SB_DQ<28>")
	)
	(arc
		(start 330.598018 -292.228524)
		(mid 330.880974 -292.152347)
		(end 331.16393 -292.228524)
		(width 0.0889)
		(layer "In4.Cu")
		(net "M_D_CPU0_SB_DQ<28>")
	)
	(arc
		(start 330.22413 -292.228524)
		(mid 330.411074 -292.278779)
		(end 330.598018 -292.228524)
		(width 0.0889)
		(layer "In4.Cu")
		(net "M_D_CPU0_SB_DQ<28>")
	)
	(arc
		(start 326.555608 -294.335962)
		(mid 326.62048 -294.072999)
		(end 326.80021 -293.87038)
		(width 0.0889)
		(layer "In4.Cu")
		(net "M_D_CPU0_SB_DQ<28>")
	)
	(arc
		(start 325.782178 -295.899586)
		(mid 326.002308 -295.570138)
		(end 326.079612 -295.181528)
		(width 0.0889)
		(layer "In4.Cu")
		(net "M_D_CPU0_SB_DQ<28>")
	)
	(arc
		(start 338.118196 -292.228524)
		(mid 338.401152 -292.152347)
		(end 338.684108 -292.228524)
		(width 0.0889)
		(layer "In4.Cu")
		(net "M_D_CPU0_SB_DQ<28>")
	)
	(arc
		(start 334.924146 -292.228524)
		(mid 335.11109 -292.278779)
		(end 335.298034 -292.228524)
		(width 0.0889)
		(layer "In4.Cu")
		(net "M_D_CPU0_SB_DQ<28>")
	)
	(arc
		(start 333.05242 -292.23335)
		(mid 333.235928 -292.278844)
		(end 333.41818 -292.228524)
		(width 0.0889)
		(layer "In4.Cu")
		(net "M_D_CPU0_SB_DQ<28>")
	)
	(arc
		(start 328.344022 -292.228524)
		(mid 328.530966 -292.278848)
		(end 328.71791 -292.228524)
		(width 0.0889)
		(layer "In4.Cu")
		(net "M_D_CPU0_SB_DQ<28>")
	)
	(arc
		(start 336.804 -292.228524)
		(mid 336.986251 -292.278874)
		(end 337.16976 -292.23335)
		(width 0.0889)
		(layer "In4.Cu")
		(net "M_D_CPU0_SB_DQ<28>")
	)
	(arc
		(start 331.16393 -292.228524)
		(mid 331.346181 -292.278874)
		(end 331.52969 -292.23335)
		(width 0.0889)
		(layer "In4.Cu")
		(net "M_D_CPU0_SB_DQ<28>")
	)
	(arc
		(start 335.298034 -292.228524)
		(mid 335.58099 -292.152347)
		(end 335.863946 -292.228524)
		(width 0.0889)
		(layer "In4.Cu")
		(net "M_D_CPU0_SB_DQ<28>")
	)
	(arc
		(start 329.292458 -292.23335)
		(mid 329.475966 -292.278844)
		(end 329.658218 -292.228524)
		(width 0.0889)
		(layer "In4.Cu")
		(net "M_D_CPU0_SB_DQ<28>")
	)
	(arc
		(start 329.658218 -292.228524)
		(mid 329.941174 -292.152347)
		(end 330.22413 -292.228524)
		(width 0.0889)
		(layer "In4.Cu")
		(net "M_D_CPU0_SB_DQ<28>")
	)
	(arc
		(start 331.538072 -292.228524)
		(mid 331.821028 -292.152347)
		(end 332.103984 -292.228524)
		(width 0.0889)
		(layer "In4.Cu")
		(net "M_D_CPU0_SB_DQ<28>")
	)
	(arc
		(start 328.718164 -292.228524)
		(mid 329.00112 -292.152347)
		(end 329.284076 -292.228524)
		(width 0.0889)
		(layer "In4.Cu")
		(net "M_D_CPU0_SB_DQ<28>")
	)
	(arc
		(start 332.103984 -292.228524)
		(mid 332.286235 -292.278874)
		(end 332.469744 -292.23335)
		(width 0.0889)
		(layer "In4.Cu")
		(net "M_D_CPU0_SB_DQ<28>")
	)
	(arc
		(start 327.495662 -292.71595)
		(mid 327.560177 -292.453731)
		(end 327.738994 -292.251384)
		(width 0.0889)
		(layer "In4.Cu")
		(net "M_D_CPU0_SB_DQ<28>")
	)
	(arc
		(start 333.41818 -292.228524)
		(mid 333.701136 -292.152347)
		(end 333.984092 -292.228524)
		(width 0.0889)
		(layer "In4.Cu")
		(net "M_D_CPU0_SB_DQ<28>")
	)
	(arc
		(start 335.863946 -292.228524)
		(mid 336.046197 -292.278874)
		(end 336.229706 -292.23335)
		(width 0.0889)
		(layer "In4.Cu")
		(net "M_D_CPU0_SB_DQ<28>")
	)
	(arc
		(start 338.69249 -292.23335)
		(mid 338.84536 -292.277991)
		(end 339.002878 -292.254686)
		(width 0.0889)
		(layer "In4.Cu")
		(net "M_D_CPU0_SB_DQ<28>")
	)
	(arc
		(start 333.992474 -292.23335)
		(mid 334.175982 -292.278844)
		(end 334.358234 -292.228524)
		(width 0.0889)
		(layer "In4.Cu")
		(net "M_D_CPU0_SB_DQ<28>")
	)
	(arc
		(start 337.752436 -292.23335)
		(mid 337.935944 -292.278844)
		(end 338.118196 -292.228524)
		(width 0.0889)
		(layer "In4.Cu")
		(net "M_D_CPU0_SB_DQ<28>")
	)
	(arc
		(start 327.77811 -292.228524)
		(mid 328.061066 -292.152347)
		(end 328.344022 -292.228524)
		(width 0.0889)
		(layer "In4.Cu")
		(net "M_D_CPU0_SB_DQ<28>")
	)
	(arc
		(start 332.478126 -292.228524)
		(mid 332.761082 -292.152347)
		(end 333.044038 -292.228524)
		(width 0.0889)
		(layer "In4.Cu")
		(net "M_D_CPU0_SB_DQ<28>")
	)
	(arc
		(start 334.358234 -292.228524)
		(mid 334.64119 -292.152347)
		(end 334.924146 -292.228524)
		(width 0.0889)
		(layer "In4.Cu")
		(net "M_D_CPU0_SB_DQ<28>")
	)
	(arc
		(start 327.33869 -293.02075)
		(mid 327.454117 -292.887374)
		(end 327.495662 -292.71595)
		(width 0.0889)
		(layer "In4.Cu")
		(net "M_D_CPU0_SB_DQ<28>")
	)
	(arc
		(start 336.238088 -292.228524)
		(mid 336.521044 -292.152347)
		(end 336.804 -292.228524)
		(width 0.0889)
		(layer "In4.Cu")
		(net "M_D_CPU0_SB_DQ<28>")
	)
	(arc
		(start 327.025762 -293.525956)
		(mid 327.090277 -293.263737)
		(end 327.269094 -293.06139)
		(width 0.0889)
		(layer "In4.Cu")
		(net "M_D_CPU0_SB_DQ<28>")
	)
	(arc
		(start 326.079612 -295.145968)
		(mid 326.153997 -294.868148)
		(end 326.357234 -294.664638)
		(width 0.0889)
		(layer "In4.Cu")
		(net "M_D_CPU0_SB_DQ<28>")
	)
	(segment
		(start 341.218012 -290.019994)
		(end 340.75116 -290.285932)
		(width 0.10668)
		(layer "F.Cu")
		(net "M_D_CPU0_SB_DQ<27>")
	)
	(segment
		(start 328.709782 -289.958526)
		(end 328.718164 -289.963352)
		(width 0.0889)
		(layer "In4.Cu")
		(net "M_D_CPU0_SB_DQ<27>")
	)
	(segment
		(start 331.52969 -289.958526)
		(end 331.538072 -289.963352)
		(width 0.0889)
		(layer "In4.Cu")
		(net "M_D_CPU0_SB_DQ<27>")
	)
	(segment
		(start 326.819514 -289.953192)
		(end 326.837802 -289.963606)
		(width 0.0889)
		(layer "In4.Cu")
		(net "M_D_CPU0_SB_DQ<27>")
	)
	(segment
		(start 307.89499 -311.660032)
		(end 320.801746 -298.753276)
		(width 0.14478)
		(layer "In4.Cu")
		(net "M_D_CPU0_SB_DQ<27>")
	)
	(segment
		(start 326.244458 -290.182554)
		(end 326.46366 -289.963352)
		(width 0.0889)
		(layer "In4.Cu")
		(net "M_D_CPU0_SB_DQ<27>")
	)
	(segment
		(start 324.667118 -293.100252)
		(end 324.667118 -292.266878)
		(width 0.0889)
		(layer "In4.Cu")
		(net "M_D_CPU0_SB_DQ<27>")
	)
	(segment
		(start 301.753524 -311.65038)
		(end 302.217836 -312.114692)
		(width 0.14478)
		(layer "In4.Cu")
		(net "M_D_CPU0_SB_DQ<27>")
	)
	(segment
		(start 327.403206 -289.963352)
		(end 327.41489 -289.956494)
		(width 0.0889)
		(layer "In4.Cu")
		(net "M_D_CPU0_SB_DQ<27>")
	)
	(segment
		(start 320.801746 -297.542458)
		(end 323.901054 -294.44315)
		(width 0.14478)
		(layer "In4.Cu")
		(net "M_D_CPU0_SB_DQ<27>")
	)
	(segment
		(start 333.984092 -289.963352)
		(end 333.992474 -289.958526)
		(width 0.0889)
		(layer "In4.Cu")
		(net "M_D_CPU0_SB_DQ<27>")
	)
	(segment
		(start 302.217836 -312.114692)
		(end 304.875184 -312.114692)
		(width 0.14478)
		(layer "In4.Cu")
		(net "M_D_CPU0_SB_DQ<27>")
	)
	(segment
		(start 326.244458 -291.004498)
		(end 326.244458 -290.182554)
		(width 0.0889)
		(layer "In4.Cu")
		(net "M_D_CPU0_SB_DQ<27>")
	)
	(segment
		(start 293.549324 -311.65038)
		(end 294.399208 -312.500264)
		(width 0.14478)
		(layer "In4.Cu")
		(net "M_D_CPU0_SB_DQ<27>")
	)
	(segment
		(start 340.500716 -289.995102)
		(end 340.596982 -290.020502)
		(width 0.0889)
		(layer "In4.Cu")
		(net "M_D_CPU0_SB_DQ<27>")
	)
	(segment
		(start 336.229706 -289.958526)
		(end 336.238088 -289.963352)
		(width 0.0889)
		(layer "In4.Cu")
		(net "M_D_CPU0_SB_DQ<27>")
	)
	(segment
		(start 297.821096 -311.65038)
		(end 301.753524 -311.65038)
		(width 0.14478)
		(layer "In4.Cu")
		(net "M_D_CPU0_SB_DQ<27>")
	)
	(segment
		(start 340.596982 -290.020502)
		(end 340.75116 -290.285932)
		(width 0.0889)
		(layer "In4.Cu")
		(net "M_D_CPU0_SB_DQ<27>")
	)
	(segment
		(start 324.108318 -293.659052)
		(end 324.667118 -293.100252)
		(width 0.0889)
		(layer "In4.Cu")
		(net "M_D_CPU0_SB_DQ<27>")
	)
	(segment
		(start 304.875184 -312.114692)
		(end 305.329844 -311.660032)
		(width 0.14478)
		(layer "In4.Cu")
		(net "M_D_CPU0_SB_DQ<27>")
	)
	(segment
		(start 281.051254 -312.500264)
		(end 289.8013 -312.500264)
		(width 0.14478)
		(layer "In4.Cu")
		(net "M_D_CPU0_SB_DQ<27>")
	)
	(segment
		(start 329.284076 -289.963352)
		(end 329.292458 -289.958526)
		(width 0.0889)
		(layer "In4.Cu")
		(net "M_D_CPU0_SB_DQ<27>")
	)
	(segment
		(start 324.108318 -294.235886)
		(end 324.108318 -293.659052)
		(width 0.0889)
		(layer "In4.Cu")
		(net "M_D_CPU0_SB_DQ<27>")
	)
	(segment
		(start 337.16976 -289.958526)
		(end 337.178142 -289.963352)
		(width 0.0889)
		(layer "In4.Cu")
		(net "M_D_CPU0_SB_DQ<27>")
	)
	(segment
		(start 324.667118 -292.266878)
		(end 324.908164 -292.025832)
		(width 0.0889)
		(layer "In4.Cu")
		(net "M_D_CPU0_SB_DQ<27>")
	)
	(segment
		(start 290.651184 -311.65038)
		(end 293.549324 -311.65038)
		(width 0.14478)
		(layer "In4.Cu")
		(net "M_D_CPU0_SB_DQ<27>")
	)
	(segment
		(start 325.223124 -292.025832)
		(end 326.244458 -291.004498)
		(width 0.0889)
		(layer "In4.Cu")
		(net "M_D_CPU0_SB_DQ<27>")
	)
	(segment
		(start 337.744054 -289.963352)
		(end 337.752436 -289.958526)
		(width 0.0889)
		(layer "In4.Cu")
		(net "M_D_CPU0_SB_DQ<27>")
	)
	(segment
		(start 294.399208 -312.500264)
		(end 296.971212 -312.500264)
		(width 0.14478)
		(layer "In4.Cu")
		(net "M_D_CPU0_SB_DQ<27>")
	)
	(segment
		(start 328.32929 -289.971988)
		(end 328.344022 -289.963352)
		(width 0.0889)
		(layer "In4.Cu")
		(net "M_D_CPU0_SB_DQ<27>")
	)
	(segment
		(start 326.837802 -289.963606)
		(end 326.84339 -289.966908)
		(width 0.0889)
		(layer "In4.Cu")
		(net "M_D_CPU0_SB_DQ<27>")
	)
	(segment
		(start 324.908164 -292.025832)
		(end 325.223124 -292.025832)
		(width 0.0889)
		(layer "In4.Cu")
		(net "M_D_CPU0_SB_DQ<27>")
	)
	(segment
		(start 338.684108 -289.963352)
		(end 338.69249 -289.958526)
		(width 0.0889)
		(layer "In4.Cu")
		(net "M_D_CPU0_SB_DQ<27>")
	)
	(segment
		(start 333.044038 -289.963352)
		(end 333.05242 -289.958526)
		(width 0.0889)
		(layer "In4.Cu")
		(net "M_D_CPU0_SB_DQ<27>")
	)
	(segment
		(start 323.901054 -294.44315)
		(end 324.108318 -294.235886)
		(width 0.0889)
		(layer "In4.Cu")
		(net "M_D_CPU0_SB_DQ<27>")
	)
	(segment
		(start 289.8013 -312.500264)
		(end 290.651184 -311.65038)
		(width 0.14478)
		(layer "In4.Cu")
		(net "M_D_CPU0_SB_DQ<27>")
	)
	(segment
		(start 280.635964 -312.084974)
		(end 281.051254 -312.500264)
		(width 0.14478)
		(layer "In4.Cu")
		(net "M_D_CPU0_SB_DQ<27>")
	)
	(segment
		(start 332.469744 -289.958526)
		(end 332.478126 -289.963352)
		(width 0.0889)
		(layer "In4.Cu")
		(net "M_D_CPU0_SB_DQ<27>")
	)
	(segment
		(start 320.801746 -298.753276)
		(end 320.801746 -297.542458)
		(width 0.14478)
		(layer "In4.Cu")
		(net "M_D_CPU0_SB_DQ<27>")
	)
	(segment
		(start 305.329844 -311.660032)
		(end 307.89499 -311.660032)
		(width 0.14478)
		(layer "In4.Cu")
		(net "M_D_CPU0_SB_DQ<27>")
	)
	(segment
		(start 296.971212 -312.500264)
		(end 297.821096 -311.65038)
		(width 0.14478)
		(layer "In4.Cu")
		(net "M_D_CPU0_SB_DQ<27>")
	)
	(arc
		(start 326.46366 -289.963352)
		(mid 326.640288 -289.913119)
		(end 326.819514 -289.953192)
		(width 0.0889)
		(layer "In4.Cu")
		(net "M_D_CPU0_SB_DQ<27>")
	)
	(arc
		(start 338.69249 -289.958526)
		(mid 338.875998 -289.913032)
		(end 339.05825 -289.963352)
		(width 0.0889)
		(layer "In4.Cu")
		(net "M_D_CPU0_SB_DQ<27>")
	)
	(arc
		(start 339.99805 -289.963352)
		(mid 340.245646 -290.03853)
		(end 340.500716 -289.995102)
		(width 0.0889)
		(layer "In4.Cu")
		(net "M_D_CPU0_SB_DQ<27>")
	)
	(arc
		(start 327.777602 -289.963352)
		(mid 328.052308 -290.039716)
		(end 328.32929 -289.971988)
		(width 0.0889)
		(layer "In4.Cu")
		(net "M_D_CPU0_SB_DQ<27>")
	)
	(arc
		(start 331.16393 -289.963352)
		(mid 331.346181 -289.913002)
		(end 331.52969 -289.958526)
		(width 0.0889)
		(layer "In4.Cu")
		(net "M_D_CPU0_SB_DQ<27>")
	)
	(arc
		(start 337.178142 -289.963352)
		(mid 337.461098 -290.039529)
		(end 337.744054 -289.963352)
		(width 0.0889)
		(layer "In4.Cu")
		(net "M_D_CPU0_SB_DQ<27>")
	)
	(arc
		(start 332.478126 -289.963352)
		(mid 332.761082 -290.039529)
		(end 333.044038 -289.963352)
		(width 0.0889)
		(layer "In4.Cu")
		(net "M_D_CPU0_SB_DQ<27>")
	)
	(arc
		(start 333.992474 -289.958526)
		(mid 334.175982 -289.913032)
		(end 334.358234 -289.963352)
		(width 0.0889)
		(layer "In4.Cu")
		(net "M_D_CPU0_SB_DQ<27>")
	)
	(arc
		(start 336.238088 -289.963352)
		(mid 336.521044 -290.039529)
		(end 336.804 -289.963352)
		(width 0.0889)
		(layer "In4.Cu")
		(net "M_D_CPU0_SB_DQ<27>")
	)
	(arc
		(start 338.118196 -289.963352)
		(mid 338.401152 -290.039529)
		(end 338.684108 -289.963352)
		(width 0.0889)
		(layer "In4.Cu")
		(net "M_D_CPU0_SB_DQ<27>")
	)
	(arc
		(start 329.292458 -289.958526)
		(mid 329.475966 -289.913032)
		(end 329.658218 -289.963352)
		(width 0.0889)
		(layer "In4.Cu")
		(net "M_D_CPU0_SB_DQ<27>")
	)
	(arc
		(start 328.344022 -289.963352)
		(mid 328.526273 -289.913002)
		(end 328.709782 -289.958526)
		(width 0.0889)
		(layer "In4.Cu")
		(net "M_D_CPU0_SB_DQ<27>")
	)
	(arc
		(start 326.84339 -289.966908)
		(mid 327.123779 -290.039577)
		(end 327.403206 -289.963352)
		(width 0.0889)
		(layer "In4.Cu")
		(net "M_D_CPU0_SB_DQ<27>")
	)
	(arc
		(start 333.41818 -289.963352)
		(mid 333.701136 -290.039529)
		(end 333.984092 -289.963352)
		(width 0.0889)
		(layer "In4.Cu")
		(net "M_D_CPU0_SB_DQ<27>")
	)
	(arc
		(start 334.924146 -289.963352)
		(mid 335.11109 -289.913097)
		(end 335.298034 -289.963352)
		(width 0.0889)
		(layer "In4.Cu")
		(net "M_D_CPU0_SB_DQ<27>")
	)
	(arc
		(start 329.658218 -289.963352)
		(mid 329.941174 -290.039529)
		(end 330.22413 -289.963352)
		(width 0.0889)
		(layer "In4.Cu")
		(net "M_D_CPU0_SB_DQ<27>")
	)
	(arc
		(start 331.538072 -289.963352)
		(mid 331.821028 -290.039529)
		(end 332.103984 -289.963352)
		(width 0.0889)
		(layer "In4.Cu")
		(net "M_D_CPU0_SB_DQ<27>")
	)
	(arc
		(start 337.752436 -289.958526)
		(mid 337.935944 -289.913032)
		(end 338.118196 -289.963352)
		(width 0.0889)
		(layer "In4.Cu")
		(net "M_D_CPU0_SB_DQ<27>")
	)
	(arc
		(start 334.358234 -289.963352)
		(mid 334.64119 -290.039529)
		(end 334.924146 -289.963352)
		(width 0.0889)
		(layer "In4.Cu")
		(net "M_D_CPU0_SB_DQ<27>")
	)
	(arc
		(start 339.624162 -289.963352)
		(mid 339.811106 -289.913097)
		(end 339.99805 -289.963352)
		(width 0.0889)
		(layer "In4.Cu")
		(net "M_D_CPU0_SB_DQ<27>")
	)
	(arc
		(start 328.718164 -289.963352)
		(mid 329.00112 -290.039529)
		(end 329.284076 -289.963352)
		(width 0.0889)
		(layer "In4.Cu")
		(net "M_D_CPU0_SB_DQ<27>")
	)
	(arc
		(start 327.41489 -289.956494)
		(mid 327.597145 -289.912841)
		(end 327.777602 -289.963352)
		(width 0.0889)
		(layer "In4.Cu")
		(net "M_D_CPU0_SB_DQ<27>")
	)
	(arc
		(start 330.598018 -289.963352)
		(mid 330.880974 -290.039529)
		(end 331.16393 -289.963352)
		(width 0.0889)
		(layer "In4.Cu")
		(net "M_D_CPU0_SB_DQ<27>")
	)
	(arc
		(start 332.103984 -289.963352)
		(mid 332.286235 -289.913002)
		(end 332.469744 -289.958526)
		(width 0.0889)
		(layer "In4.Cu")
		(net "M_D_CPU0_SB_DQ<27>")
	)
	(arc
		(start 335.298034 -289.963352)
		(mid 335.58099 -290.039529)
		(end 335.863946 -289.963352)
		(width 0.0889)
		(layer "In4.Cu")
		(net "M_D_CPU0_SB_DQ<27>")
	)
	(arc
		(start 330.22413 -289.963352)
		(mid 330.411074 -289.913097)
		(end 330.598018 -289.963352)
		(width 0.0889)
		(layer "In4.Cu")
		(net "M_D_CPU0_SB_DQ<27>")
	)
	(arc
		(start 336.804 -289.963352)
		(mid 336.986251 -289.913002)
		(end 337.16976 -289.958526)
		(width 0.0889)
		(layer "In4.Cu")
		(net "M_D_CPU0_SB_DQ<27>")
	)
	(arc
		(start 339.05825 -289.963352)
		(mid 339.341206 -290.039529)
		(end 339.624162 -289.963352)
		(width 0.0889)
		(layer "In4.Cu")
		(net "M_D_CPU0_SB_DQ<27>")
	)
	(arc
		(start 333.05242 -289.958526)
		(mid 333.235928 -289.913032)
		(end 333.41818 -289.963352)
		(width 0.0889)
		(layer "In4.Cu")
		(net "M_D_CPU0_SB_DQ<27>")
	)
	(arc
		(start 335.863946 -289.963352)
		(mid 336.046197 -289.913002)
		(end 336.229706 -289.958526)
		(width 0.0889)
		(layer "In4.Cu")
		(net "M_D_CPU0_SB_DQ<27>")
	)
	(segment
		(start 339.808058 -289.209988)
		(end 339.341206 -289.475926)
		(width 0.10668)
		(layer "F.Cu")
		(net "M_D_CPU0_SB_DQ<26>")
	)
	(segment
		(start 325.121778 -291.367972)
		(end 325.558658 -290.931092)
		(width 0.0889)
		(layer "In4.Cu")
		(net "M_D_CPU0_SB_DQ<26>")
	)
	(segment
		(start 293.4335 -309.96001)
		(end 294.283638 -310.810148)
		(width 0.14478)
		(layer "In4.Cu")
		(net "M_D_CPU0_SB_DQ<26>")
	)
	(segment
		(start 339.187028 -289.210496)
		(end 339.341206 -289.475926)
		(width 0.0889)
		(layer "In4.Cu")
		(net "M_D_CPU0_SB_DQ<26>")
	)
	(segment
		(start 339.090762 -289.185096)
		(end 339.187028 -289.210496)
		(width 0.0889)
		(layer "In4.Cu")
		(net "M_D_CPU0_SB_DQ<26>")
	)
	(segment
		(start 305.743356 -309.96001)
		(end 308.32298 -309.96001)
		(width 0.14478)
		(layer "In4.Cu")
		(net "M_D_CPU0_SB_DQ<26>")
	)
	(segment
		(start 325.558658 -290.931092)
		(end 325.558658 -289.8648)
		(width 0.0889)
		(layer "In4.Cu")
		(net "M_D_CPU0_SB_DQ<26>")
	)
	(segment
		(start 290.970208 -309.96001)
		(end 293.4335 -309.96001)
		(width 0.14478)
		(layer "In4.Cu")
		(net "M_D_CPU0_SB_DQ<26>")
	)
	(segment
		(start 326.93356 -289.1536)
		(end 326.951848 -289.143186)
		(width 0.0889)
		(layer "In4.Cu")
		(net "M_D_CPU0_SB_DQ<26>")
	)
	(segment
		(start 324.708012 -291.367972)
		(end 325.121778 -291.367972)
		(width 0.0889)
		(layer "In4.Cu")
		(net "M_D_CPU0_SB_DQ<26>")
	)
	(segment
		(start 283.040328 -310.09971)
		(end 283.203142 -310.262524)
		(width 0.14478)
		(layer "In4.Cu")
		(net "M_D_CPU0_SB_DQ<26>")
	)
	(segment
		(start 290.12007 -310.810148)
		(end 290.970208 -309.96001)
		(width 0.14478)
		(layer "In4.Cu")
		(net "M_D_CPU0_SB_DQ<26>")
	)
	(segment
		(start 335.394046 -289.153346)
		(end 335.402428 -289.14852)
		(width 0.0889)
		(layer "In4.Cu")
		(net "M_D_CPU0_SB_DQ<26>")
	)
	(segment
		(start 336.3341 -289.153346)
		(end 336.342482 -289.14852)
		(width 0.0889)
		(layer "In4.Cu")
		(net "M_D_CPU0_SB_DQ<26>")
	)
	(segment
		(start 302.205898 -310.810148)
		(end 304.893218 -310.810148)
		(width 0.14478)
		(layer "In4.Cu")
		(net "M_D_CPU0_SB_DQ<26>")
	)
	(segment
		(start 281.697176 -310.09971)
		(end 281.927808 -310.09971)
		(width 0.14478)
		(layer "In4.Cu")
		(net "M_D_CPU0_SB_DQ<26>")
	)
	(segment
		(start 280.635964 -310.384952)
		(end 281.06116 -310.810148)
		(width 0.14478)
		(layer "In4.Cu")
		(net "M_D_CPU0_SB_DQ<26>")
	)
	(segment
		(start 281.534362 -310.262524)
		(end 281.697176 -310.09971)
		(width 0.14478)
		(layer "In4.Cu")
		(net "M_D_CPU0_SB_DQ<26>")
	)
	(segment
		(start 282.090622 -310.262524)
		(end 282.090622 -310.647334)
		(width 0.14478)
		(layer "In4.Cu")
		(net "M_D_CPU0_SB_DQ<26>")
	)
	(segment
		(start 330.69403 -289.153346)
		(end 330.702412 -289.14852)
		(width 0.0889)
		(layer "In4.Cu")
		(net "M_D_CPU0_SB_DQ<26>")
	)
	(segment
		(start 304.893218 -310.810148)
		(end 305.743356 -309.96001)
		(width 0.14478)
		(layer "In4.Cu")
		(net "M_D_CPU0_SB_DQ<26>")
	)
	(segment
		(start 301.35576 -309.96001)
		(end 302.205898 -310.810148)
		(width 0.14478)
		(layer "In4.Cu")
		(net "M_D_CPU0_SB_DQ<26>")
	)
	(segment
		(start 330.119736 -289.14852)
		(end 330.128118 -289.153346)
		(width 0.0889)
		(layer "In4.Cu")
		(net "M_D_CPU0_SB_DQ<26>")
	)
	(segment
		(start 297.374818 -310.810148)
		(end 298.224956 -309.96001)
		(width 0.14478)
		(layer "In4.Cu")
		(net "M_D_CPU0_SB_DQ<26>")
	)
	(segment
		(start 282.809696 -310.09971)
		(end 283.040328 -310.09971)
		(width 0.14478)
		(layer "In4.Cu")
		(net "M_D_CPU0_SB_DQ<26>")
	)
	(segment
		(start 281.06116 -310.810148)
		(end 281.371548 -310.810148)
		(width 0.14478)
		(layer "In4.Cu")
		(net "M_D_CPU0_SB_DQ<26>")
	)
	(segment
		(start 282.253436 -310.810148)
		(end 282.484068 -310.810148)
		(width 0.14478)
		(layer "In4.Cu")
		(net "M_D_CPU0_SB_DQ<26>")
	)
	(segment
		(start 281.927808 -310.09971)
		(end 282.090622 -310.262524)
		(width 0.14478)
		(layer "In4.Cu")
		(net "M_D_CPU0_SB_DQ<26>")
	)
	(segment
		(start 323.871336 -292.7731)
		(end 324.171818 -292.472618)
		(width 0.0889)
		(layer "In4.Cu")
		(net "M_D_CPU0_SB_DQ<26>")
	)
	(segment
		(start 319.902586 -298.380404)
		(end 319.902586 -296.74185)
		(width 0.14478)
		(layer "In4.Cu")
		(net "M_D_CPU0_SB_DQ<26>")
	)
	(segment
		(start 333.879698 -289.14852)
		(end 333.88808 -289.153346)
		(width 0.0889)
		(layer "In4.Cu")
		(net "M_D_CPU0_SB_DQ<26>")
	)
	(segment
		(start 281.534362 -310.647334)
		(end 281.534362 -310.262524)
		(width 0.14478)
		(layer "In4.Cu")
		(net "M_D_CPU0_SB_DQ<26>")
	)
	(segment
		(start 282.090622 -310.647334)
		(end 282.253436 -310.810148)
		(width 0.14478)
		(layer "In4.Cu")
		(net "M_D_CPU0_SB_DQ<26>")
	)
	(segment
		(start 282.484068 -310.810148)
		(end 282.646882 -310.647334)
		(width 0.14478)
		(layer "In4.Cu")
		(net "M_D_CPU0_SB_DQ<26>")
	)
	(segment
		(start 327.874122 -289.153346)
		(end 327.882504 -289.14852)
		(width 0.0889)
		(layer "In4.Cu")
		(net "M_D_CPU0_SB_DQ<26>")
	)
	(segment
		(start 283.203142 -310.262524)
		(end 283.203142 -310.647334)
		(width 0.14478)
		(layer "In4.Cu")
		(net "M_D_CPU0_SB_DQ<26>")
	)
	(segment
		(start 327.85939 -289.161982)
		(end 327.874122 -289.153346)
		(width 0.0889)
		(layer "In4.Cu")
		(net "M_D_CPU0_SB_DQ<26>")
	)
	(segment
		(start 281.371548 -310.810148)
		(end 281.534362 -310.647334)
		(width 0.14478)
		(layer "In4.Cu")
		(net "M_D_CPU0_SB_DQ<26>")
	)
	(segment
		(start 308.32298 -309.96001)
		(end 319.902586 -298.380404)
		(width 0.14478)
		(layer "In4.Cu")
		(net "M_D_CPU0_SB_DQ<26>")
	)
	(segment
		(start 326.193912 -289.229546)
		(end 326.651112 -289.229546)
		(width 0.0889)
		(layer "In4.Cu")
		(net "M_D_CPU0_SB_DQ<26>")
	)
	(segment
		(start 282.646882 -310.262524)
		(end 282.809696 -310.09971)
		(width 0.14478)
		(layer "In4.Cu")
		(net "M_D_CPU0_SB_DQ<26>")
	)
	(segment
		(start 283.365956 -310.810148)
		(end 290.12007 -310.810148)
		(width 0.14478)
		(layer "In4.Cu")
		(net "M_D_CPU0_SB_DQ<26>")
	)
	(segment
		(start 298.224956 -309.96001)
		(end 301.35576 -309.96001)
		(width 0.14478)
		(layer "In4.Cu")
		(net "M_D_CPU0_SB_DQ<26>")
	)
	(segment
		(start 319.902586 -296.74185)
		(end 323.871336 -292.7731)
		(width 0.14478)
		(layer "In4.Cu")
		(net "M_D_CPU0_SB_DQ<26>")
	)
	(segment
		(start 325.558658 -289.8648)
		(end 326.193912 -289.229546)
		(width 0.0889)
		(layer "In4.Cu")
		(net "M_D_CPU0_SB_DQ<26>")
	)
	(segment
		(start 324.171818 -291.904166)
		(end 324.708012 -291.367972)
		(width 0.0889)
		(layer "In4.Cu")
		(net "M_D_CPU0_SB_DQ<26>")
	)
	(segment
		(start 294.283638 -310.810148)
		(end 297.374818 -310.810148)
		(width 0.14478)
		(layer "In4.Cu")
		(net "M_D_CPU0_SB_DQ<26>")
	)
	(segment
		(start 324.171818 -292.472618)
		(end 324.171818 -291.904166)
		(width 0.0889)
		(layer "In4.Cu")
		(net "M_D_CPU0_SB_DQ<26>")
	)
	(segment
		(start 331.634084 -289.153346)
		(end 331.642466 -289.14852)
		(width 0.0889)
		(layer "In4.Cu")
		(net "M_D_CPU0_SB_DQ<26>")
	)
	(segment
		(start 283.203142 -310.647334)
		(end 283.365956 -310.810148)
		(width 0.14478)
		(layer "In4.Cu")
		(net "M_D_CPU0_SB_DQ<26>")
	)
	(segment
		(start 338.579714 -289.14852)
		(end 338.588096 -289.153346)
		(width 0.0889)
		(layer "In4.Cu")
		(net "M_D_CPU0_SB_DQ<26>")
	)
	(segment
		(start 334.819752 -289.14852)
		(end 334.828134 -289.153346)
		(width 0.0889)
		(layer "In4.Cu")
		(net "M_D_CPU0_SB_DQ<26>")
	)
	(segment
		(start 282.646882 -310.647334)
		(end 282.646882 -310.262524)
		(width 0.14478)
		(layer "In4.Cu")
		(net "M_D_CPU0_SB_DQ<26>")
	)
	(arc
		(start 329.753976 -289.153346)
		(mid 329.936227 -289.102996)
		(end 330.119736 -289.14852)
		(width 0.0889)
		(layer "In4.Cu")
		(net "M_D_CPU0_SB_DQ<26>")
	)
	(arc
		(start 330.128118 -289.153346)
		(mid 330.411074 -289.229523)
		(end 330.69403 -289.153346)
		(width 0.0889)
		(layer "In4.Cu")
		(net "M_D_CPU0_SB_DQ<26>")
	)
	(arc
		(start 337.274154 -289.153346)
		(mid 337.461098 -289.103091)
		(end 337.648042 -289.153346)
		(width 0.0889)
		(layer "In4.Cu")
		(net "M_D_CPU0_SB_DQ<26>")
	)
	(arc
		(start 326.951848 -289.143186)
		(mid 327.131077 -289.103033)
		(end 327.307702 -289.153346)
		(width 0.0889)
		(layer "In4.Cu")
		(net "M_D_CPU0_SB_DQ<26>")
	)
	(arc
		(start 333.513938 -289.153346)
		(mid 333.696189 -289.102996)
		(end 333.879698 -289.14852)
		(width 0.0889)
		(layer "In4.Cu")
		(net "M_D_CPU0_SB_DQ<26>")
	)
	(arc
		(start 338.213954 -289.153346)
		(mid 338.396205 -289.102996)
		(end 338.579714 -289.14852)
		(width 0.0889)
		(layer "In4.Cu")
		(net "M_D_CPU0_SB_DQ<26>")
	)
	(arc
		(start 328.248264 -289.153346)
		(mid 328.53122 -289.229523)
		(end 328.814176 -289.153346)
		(width 0.0889)
		(layer "In4.Cu")
		(net "M_D_CPU0_SB_DQ<26>")
	)
	(arc
		(start 329.188064 -289.153346)
		(mid 329.47102 -289.229523)
		(end 329.753976 -289.153346)
		(width 0.0889)
		(layer "In4.Cu")
		(net "M_D_CPU0_SB_DQ<26>")
	)
	(arc
		(start 331.068172 -289.153346)
		(mid 331.351128 -289.229523)
		(end 331.634084 -289.153346)
		(width 0.0889)
		(layer "In4.Cu")
		(net "M_D_CPU0_SB_DQ<26>")
	)
	(arc
		(start 335.768188 -289.153346)
		(mid 336.051144 -289.229523)
		(end 336.3341 -289.153346)
		(width 0.0889)
		(layer "In4.Cu")
		(net "M_D_CPU0_SB_DQ<26>")
	)
	(arc
		(start 332.948026 -289.153346)
		(mid 333.230982 -289.229523)
		(end 333.513938 -289.153346)
		(width 0.0889)
		(layer "In4.Cu")
		(net "M_D_CPU0_SB_DQ<26>")
	)
	(arc
		(start 331.642466 -289.14852)
		(mid 331.825974 -289.103026)
		(end 332.008226 -289.153346)
		(width 0.0889)
		(layer "In4.Cu")
		(net "M_D_CPU0_SB_DQ<26>")
	)
	(arc
		(start 335.402428 -289.14852)
		(mid 335.585936 -289.103026)
		(end 335.768188 -289.153346)
		(width 0.0889)
		(layer "In4.Cu")
		(net "M_D_CPU0_SB_DQ<26>")
	)
	(arc
		(start 327.882504 -289.14852)
		(mid 328.066012 -289.103026)
		(end 328.248264 -289.153346)
		(width 0.0889)
		(layer "In4.Cu")
		(net "M_D_CPU0_SB_DQ<26>")
	)
	(arc
		(start 330.702412 -289.14852)
		(mid 330.88592 -289.103026)
		(end 331.068172 -289.153346)
		(width 0.0889)
		(layer "In4.Cu")
		(net "M_D_CPU0_SB_DQ<26>")
	)
	(arc
		(start 336.342482 -289.14852)
		(mid 336.52599 -289.103026)
		(end 336.708242 -289.153346)
		(width 0.0889)
		(layer "In4.Cu")
		(net "M_D_CPU0_SB_DQ<26>")
	)
	(arc
		(start 337.648042 -289.153346)
		(mid 337.930998 -289.229523)
		(end 338.213954 -289.153346)
		(width 0.0889)
		(layer "In4.Cu")
		(net "M_D_CPU0_SB_DQ<26>")
	)
	(arc
		(start 333.88808 -289.153346)
		(mid 334.171036 -289.229523)
		(end 334.453992 -289.153346)
		(width 0.0889)
		(layer "In4.Cu")
		(net "M_D_CPU0_SB_DQ<26>")
	)
	(arc
		(start 327.307702 -289.153346)
		(mid 327.582408 -289.22971)
		(end 327.85939 -289.161982)
		(width 0.0889)
		(layer "In4.Cu")
		(net "M_D_CPU0_SB_DQ<26>")
	)
	(arc
		(start 334.828134 -289.153346)
		(mid 335.11109 -289.229523)
		(end 335.394046 -289.153346)
		(width 0.0889)
		(layer "In4.Cu")
		(net "M_D_CPU0_SB_DQ<26>")
	)
	(arc
		(start 332.574138 -289.153346)
		(mid 332.761082 -289.103091)
		(end 332.948026 -289.153346)
		(width 0.0889)
		(layer "In4.Cu")
		(net "M_D_CPU0_SB_DQ<26>")
	)
	(arc
		(start 326.651112 -289.229546)
		(mid 326.79736 -289.210241)
		(end 326.93356 -289.1536)
		(width 0.0889)
		(layer "In4.Cu")
		(net "M_D_CPU0_SB_DQ<26>")
	)
	(arc
		(start 332.008226 -289.153346)
		(mid 332.291182 -289.229523)
		(end 332.574138 -289.153346)
		(width 0.0889)
		(layer "In4.Cu")
		(net "M_D_CPU0_SB_DQ<26>")
	)
	(arc
		(start 328.814176 -289.153346)
		(mid 329.00112 -289.103091)
		(end 329.188064 -289.153346)
		(width 0.0889)
		(layer "In4.Cu")
		(net "M_D_CPU0_SB_DQ<26>")
	)
	(arc
		(start 338.588096 -289.153346)
		(mid 338.835692 -289.228524)
		(end 339.090762 -289.185096)
		(width 0.0889)
		(layer "In4.Cu")
		(net "M_D_CPU0_SB_DQ<26>")
	)
	(arc
		(start 336.708242 -289.153346)
		(mid 336.991198 -289.229523)
		(end 337.274154 -289.153346)
		(width 0.0889)
		(layer "In4.Cu")
		(net "M_D_CPU0_SB_DQ<26>")
	)
	(arc
		(start 334.453992 -289.153346)
		(mid 334.636243 -289.102996)
		(end 334.819752 -289.14852)
		(width 0.0889)
		(layer "In4.Cu")
		(net "M_D_CPU0_SB_DQ<26>")
	)
	(segment
		(start 340.747858 -289.209988)
		(end 340.281006 -289.475926)
		(width 0.10668)
		(layer "F.Cu")
		(net "M_D_CPU0_SB_DQ<25>")
	)
	(segment
		(start 296.848784 -311.97931)
		(end 298.404788 -310.423306)
		(width 0.14478)
		(layer "In4.Cu")
		(net "M_D_CPU0_SB_DQ<25>")
	)
	(segment
		(start 300.002702 -310.809894)
		(end 300.384718 -311.19191)
		(width 0.14478)
		(layer "In4.Cu")
		(net "M_D_CPU0_SB_DQ<25>")
	)
	(segment
		(start 340.412832 -289.824668)
		(end 340.435184 -289.741356)
		(width 0.0889)
		(layer "In4.Cu")
		(net "M_D_CPU0_SB_DQ<25>")
	)
	(segment
		(start 334.819752 -289.803332)
		(end 334.828134 -289.798506)
		(width 0.0889)
		(layer "In4.Cu")
		(net "M_D_CPU0_SB_DQ<25>")
	)
	(segment
		(start 292.548564 -310.809894)
		(end 292.852348 -310.50611)
		(width 0.14478)
		(layer "In4.Cu")
		(net "M_D_CPU0_SB_DQ<25>")
	)
	(segment
		(start 289.36442 -312.020458)
		(end 289.595052 -312.020458)
		(width 0.14478)
		(layer "In4.Cu")
		(net "M_D_CPU0_SB_DQ<25>")
	)
	(segment
		(start 287.059116 -311.474866)
		(end 287.22193 -311.312052)
		(width 0.14478)
		(layer "In4.Cu")
		(net "M_D_CPU0_SB_DQ<25>")
	)
	(segment
		(start 287.452562 -311.312052)
		(end 287.800542 -311.660032)
		(width 0.14478)
		(layer "In4.Cu")
		(net "M_D_CPU0_SB_DQ<25>")
	)
	(segment
		(start 284.736032 -311.23509)
		(end 285.541974 -312.041032)
		(width 0.14478)
		(layer "In4.Cu")
		(net "M_D_CPU0_SB_DQ<25>")
	)
	(segment
		(start 291.820092 -310.809894)
		(end 292.548564 -310.809894)
		(width 0.14478)
		(layer "In4.Cu")
		(net "M_D_CPU0_SB_DQ<25>")
	)
	(segment
		(start 289.595052 -312.020458)
		(end 291.1094 -310.50611)
		(width 0.14478)
		(layer "In4.Cu")
		(net "M_D_CPU0_SB_DQ<25>")
	)
	(segment
		(start 286.910018 -312.038492)
		(end 287.059116 -311.889394)
		(width 0.14478)
		(layer "In4.Cu")
		(net "M_D_CPU0_SB_DQ<25>")
	)
	(segment
		(start 286.502856 -311.889394)
		(end 286.651954 -312.038492)
		(width 0.14478)
		(layer "In4.Cu")
		(net "M_D_CPU0_SB_DQ<25>")
	)
	(segment
		(start 289.003994 -311.660032)
		(end 289.36442 -312.020458)
		(width 0.14478)
		(layer "In4.Cu")
		(net "M_D_CPU0_SB_DQ<25>")
	)
	(segment
		(start 298.798234 -311.024524)
		(end 298.961048 -311.187338)
		(width 0.14478)
		(layer "In4.Cu")
		(net "M_D_CPU0_SB_DQ<25>")
	)
	(segment
		(start 323.875908 -293.412164)
		(end 324.362318 -292.925754)
		(width 0.0889)
		(layer "In4.Cu")
		(net "M_D_CPU0_SB_DQ<25>")
	)
	(segment
		(start 336.3341 -289.798506)
		(end 336.342482 -289.803332)
		(width 0.0889)
		(layer "In4.Cu")
		(net "M_D_CPU0_SB_DQ<25>")
	)
	(segment
		(start 291.1094 -310.50611)
		(end 291.516308 -310.50611)
		(width 0.14478)
		(layer "In4.Cu")
		(net "M_D_CPU0_SB_DQ<25>")
	)
	(segment
		(start 338.579714 -289.803332)
		(end 338.588096 -289.798506)
		(width 0.0889)
		(layer "In4.Cu")
		(net "M_D_CPU0_SB_DQ<25>")
	)
	(segment
		(start 326.917812 -289.789108)
		(end 326.93356 -289.798252)
		(width 0.0889)
		(layer "In4.Cu")
		(net "M_D_CPU0_SB_DQ<25>")
	)
	(segment
		(start 324.806818 -291.690552)
		(end 325.159878 -291.690552)
		(width 0.0889)
		(layer "In4.Cu")
		(net "M_D_CPU0_SB_DQ<25>")
	)
	(segment
		(start 335.394046 -289.798506)
		(end 335.402428 -289.803332)
		(width 0.0889)
		(layer "In4.Cu")
		(net "M_D_CPU0_SB_DQ<25>")
	)
	(segment
		(start 285.794958 -312.041032)
		(end 285.946596 -311.889394)
		(width 0.14478)
		(layer "In4.Cu")
		(net "M_D_CPU0_SB_DQ<25>")
	)
	(segment
		(start 328.239882 -289.803332)
		(end 328.248264 -289.798506)
		(width 0.0889)
		(layer "In4.Cu")
		(net "M_D_CPU0_SB_DQ<25>")
	)
	(segment
		(start 327.307194 -289.798506)
		(end 327.321926 -289.78987)
		(width 0.0889)
		(layer "In4.Cu")
		(net "M_D_CPU0_SB_DQ<25>")
	)
	(segment
		(start 325.911718 -290.938712)
		(end 325.911718 -290.147502)
		(width 0.0889)
		(layer "In4.Cu")
		(net "M_D_CPU0_SB_DQ<25>")
	)
	(segment
		(start 305.5366 -310.809894)
		(end 308.109112 -310.809894)
		(width 0.14478)
		(layer "In4.Cu")
		(net "M_D_CPU0_SB_DQ<25>")
	)
	(segment
		(start 285.946596 -311.889394)
		(end 285.946596 -311.474866)
		(width 0.14478)
		(layer "In4.Cu")
		(net "M_D_CPU0_SB_DQ<25>")
	)
	(segment
		(start 293.243508 -310.50611)
		(end 294.716708 -311.97931)
		(width 0.14478)
		(layer "In4.Cu")
		(net "M_D_CPU0_SB_DQ<25>")
	)
	(segment
		(start 291.516308 -310.50611)
		(end 291.820092 -310.809894)
		(width 0.14478)
		(layer "In4.Cu")
		(net "M_D_CPU0_SB_DQ<25>")
	)
	(segment
		(start 295.272968 -311.660032)
		(end 296.292524 -311.660032)
		(width 0.14478)
		(layer "In4.Cu")
		(net "M_D_CPU0_SB_DQ<25>")
	)
	(segment
		(start 300.778164 -310.590692)
		(end 300.940978 -310.427878)
		(width 0.14478)
		(layer "In4.Cu")
		(net "M_D_CPU0_SB_DQ<25>")
	)
	(segment
		(start 330.69403 -289.798506)
		(end 330.702412 -289.803332)
		(width 0.0889)
		(layer "In4.Cu")
		(net "M_D_CPU0_SB_DQ<25>")
	)
	(segment
		(start 302.412654 -311.660032)
		(end 304.686462 -311.660032)
		(width 0.14478)
		(layer "In4.Cu")
		(net "M_D_CPU0_SB_DQ<25>")
	)
	(segment
		(start 298.798234 -310.58612)
		(end 298.798234 -311.024524)
		(width 0.14478)
		(layer "In4.Cu")
		(net "M_D_CPU0_SB_DQ<25>")
	)
	(segment
		(start 300.384718 -311.19191)
		(end 300.61535 -311.19191)
		(width 0.14478)
		(layer "In4.Cu")
		(net "M_D_CPU0_SB_DQ<25>")
	)
	(segment
		(start 320.352166 -298.56684)
		(end 320.352166 -296.935906)
		(width 0.14478)
		(layer "In4.Cu")
		(net "M_D_CPU0_SB_DQ<25>")
	)
	(segment
		(start 320.352166 -296.935906)
		(end 323.875908 -293.412164)
		(width 0.14478)
		(layer "In4.Cu")
		(net "M_D_CPU0_SB_DQ<25>")
	)
	(segment
		(start 292.852348 -310.50611)
		(end 293.243508 -310.50611)
		(width 0.14478)
		(layer "In4.Cu")
		(net "M_D_CPU0_SB_DQ<25>")
	)
	(segment
		(start 331.634084 -289.798506)
		(end 331.642466 -289.803332)
		(width 0.0889)
		(layer "In4.Cu")
		(net "M_D_CPU0_SB_DQ<25>")
	)
	(segment
		(start 286.10941 -311.312052)
		(end 286.340042 -311.312052)
		(width 0.14478)
		(layer "In4.Cu")
		(net "M_D_CPU0_SB_DQ<25>")
	)
	(segment
		(start 298.961048 -311.187338)
		(end 299.19168 -311.187338)
		(width 0.14478)
		(layer "In4.Cu")
		(net "M_D_CPU0_SB_DQ<25>")
	)
	(segment
		(start 298.63542 -310.423306)
		(end 298.798234 -310.58612)
		(width 0.14478)
		(layer "In4.Cu")
		(net "M_D_CPU0_SB_DQ<25>")
	)
	(segment
		(start 285.946596 -311.474866)
		(end 286.10941 -311.312052)
		(width 0.14478)
		(layer "In4.Cu")
		(net "M_D_CPU0_SB_DQ<25>")
	)
	(segment
		(start 326.93356 -289.798252)
		(end 326.947276 -289.806126)
		(width 0.0889)
		(layer "In4.Cu")
		(net "M_D_CPU0_SB_DQ<25>")
	)
	(segment
		(start 299.19168 -311.187338)
		(end 299.569124 -310.809894)
		(width 0.14478)
		(layer "In4.Cu")
		(net "M_D_CPU0_SB_DQ<25>")
	)
	(segment
		(start 333.879698 -289.803332)
		(end 333.88808 -289.798506)
		(width 0.0889)
		(layer "In4.Cu")
		(net "M_D_CPU0_SB_DQ<25>")
	)
	(segment
		(start 294.95369 -311.97931)
		(end 295.272968 -311.660032)
		(width 0.14478)
		(layer "In4.Cu")
		(net "M_D_CPU0_SB_DQ<25>")
	)
	(segment
		(start 325.159878 -291.690552)
		(end 325.911718 -290.938712)
		(width 0.0889)
		(layer "In4.Cu")
		(net "M_D_CPU0_SB_DQ<25>")
	)
	(segment
		(start 285.541974 -312.041032)
		(end 285.794958 -312.041032)
		(width 0.14478)
		(layer "In4.Cu")
		(net "M_D_CPU0_SB_DQ<25>")
	)
	(segment
		(start 324.362318 -292.135052)
		(end 324.806818 -291.690552)
		(width 0.0889)
		(layer "In4.Cu")
		(net "M_D_CPU0_SB_DQ<25>")
	)
	(segment
		(start 308.109112 -310.809894)
		(end 320.352166 -298.56684)
		(width 0.14478)
		(layer "In4.Cu")
		(net "M_D_CPU0_SB_DQ<25>")
	)
	(segment
		(start 326.112124 -289.947096)
		(end 326.367648 -289.798506)
		(width 0.0889)
		(layer "In4.Cu")
		(net "M_D_CPU0_SB_DQ<25>")
	)
	(segment
		(start 300.61535 -311.19191)
		(end 300.778164 -311.029096)
		(width 0.14478)
		(layer "In4.Cu")
		(net "M_D_CPU0_SB_DQ<25>")
	)
	(segment
		(start 287.800542 -311.660032)
		(end 289.003994 -311.660032)
		(width 0.14478)
		(layer "In4.Cu")
		(net "M_D_CPU0_SB_DQ<25>")
	)
	(segment
		(start 298.404788 -310.423306)
		(end 298.63542 -310.423306)
		(width 0.14478)
		(layer "In4.Cu")
		(net "M_D_CPU0_SB_DQ<25>")
	)
	(segment
		(start 340.094062 -289.798506)
		(end 340.102444 -289.803332)
		(width 0.0889)
		(layer "In4.Cu")
		(net "M_D_CPU0_SB_DQ<25>")
	)
	(segment
		(start 286.651954 -312.038492)
		(end 286.910018 -312.038492)
		(width 0.14478)
		(layer "In4.Cu")
		(net "M_D_CPU0_SB_DQ<25>")
	)
	(segment
		(start 286.340042 -311.312052)
		(end 286.502856 -311.474866)
		(width 0.14478)
		(layer "In4.Cu")
		(net "M_D_CPU0_SB_DQ<25>")
	)
	(segment
		(start 325.911718 -290.147502)
		(end 326.112124 -289.947096)
		(width 0.0889)
		(layer "In4.Cu")
		(net "M_D_CPU0_SB_DQ<25>")
	)
	(segment
		(start 300.940978 -310.427878)
		(end 301.1805 -310.427878)
		(width 0.14478)
		(layer "In4.Cu")
		(net "M_D_CPU0_SB_DQ<25>")
	)
	(segment
		(start 294.716708 -311.97931)
		(end 294.95369 -311.97931)
		(width 0.14478)
		(layer "In4.Cu")
		(net "M_D_CPU0_SB_DQ<25>")
	)
	(segment
		(start 286.502856 -311.474866)
		(end 286.502856 -311.889394)
		(width 0.14478)
		(layer "In4.Cu")
		(net "M_D_CPU0_SB_DQ<25>")
	)
	(segment
		(start 324.362318 -292.925754)
		(end 324.362318 -292.135052)
		(width 0.0889)
		(layer "In4.Cu")
		(net "M_D_CPU0_SB_DQ<25>")
	)
	(segment
		(start 339.519768 -289.803332)
		(end 339.52815 -289.798506)
		(width 0.0889)
		(layer "In4.Cu")
		(net "M_D_CPU0_SB_DQ<25>")
	)
	(segment
		(start 301.1805 -310.427878)
		(end 302.412654 -311.660032)
		(width 0.14478)
		(layer "In4.Cu")
		(net "M_D_CPU0_SB_DQ<25>")
	)
	(segment
		(start 300.778164 -311.029096)
		(end 300.778164 -310.590692)
		(width 0.14478)
		(layer "In4.Cu")
		(net "M_D_CPU0_SB_DQ<25>")
	)
	(segment
		(start 296.292524 -311.660032)
		(end 296.611802 -311.97931)
		(width 0.14478)
		(layer "In4.Cu")
		(net "M_D_CPU0_SB_DQ<25>")
	)
	(segment
		(start 340.435184 -289.741356)
		(end 340.281006 -289.475926)
		(width 0.0889)
		(layer "In4.Cu")
		(net "M_D_CPU0_SB_DQ<25>")
	)
	(segment
		(start 287.22193 -311.312052)
		(end 287.452562 -311.312052)
		(width 0.14478)
		(layer "In4.Cu")
		(net "M_D_CPU0_SB_DQ<25>")
	)
	(segment
		(start 330.119736 -289.803332)
		(end 330.128118 -289.798506)
		(width 0.0889)
		(layer "In4.Cu")
		(net "M_D_CPU0_SB_DQ<25>")
	)
	(segment
		(start 304.686462 -311.660032)
		(end 305.5366 -310.809894)
		(width 0.14478)
		(layer "In4.Cu")
		(net "M_D_CPU0_SB_DQ<25>")
	)
	(segment
		(start 299.569124 -310.809894)
		(end 300.002702 -310.809894)
		(width 0.14478)
		(layer "In4.Cu")
		(net "M_D_CPU0_SB_DQ<25>")
	)
	(segment
		(start 296.611802 -311.97931)
		(end 296.848784 -311.97931)
		(width 0.14478)
		(layer "In4.Cu")
		(net "M_D_CPU0_SB_DQ<25>")
	)
	(segment
		(start 287.059116 -311.889394)
		(end 287.059116 -311.474866)
		(width 0.14478)
		(layer "In4.Cu")
		(net "M_D_CPU0_SB_DQ<25>")
	)
	(arc
		(start 335.768188 -289.798506)
		(mid 336.051144 -289.722329)
		(end 336.3341 -289.798506)
		(width 0.0889)
		(layer "In4.Cu")
		(net "M_D_CPU0_SB_DQ<25>")
	)
	(arc
		(start 332.008226 -289.798506)
		(mid 332.291182 -289.722329)
		(end 332.574138 -289.798506)
		(width 0.0889)
		(layer "In4.Cu")
		(net "M_D_CPU0_SB_DQ<25>")
	)
	(arc
		(start 332.948026 -289.798506)
		(mid 333.230982 -289.722329)
		(end 333.513938 -289.798506)
		(width 0.0889)
		(layer "In4.Cu")
		(net "M_D_CPU0_SB_DQ<25>")
	)
	(arc
		(start 336.708242 -289.798506)
		(mid 336.991198 -289.722329)
		(end 337.274154 -289.798506)
		(width 0.0889)
		(layer "In4.Cu")
		(net "M_D_CPU0_SB_DQ<25>")
	)
	(arc
		(start 334.828134 -289.798506)
		(mid 335.11109 -289.722329)
		(end 335.394046 -289.798506)
		(width 0.0889)
		(layer "In4.Cu")
		(net "M_D_CPU0_SB_DQ<25>")
	)
	(arc
		(start 329.188064 -289.798506)
		(mid 329.47102 -289.722329)
		(end 329.753976 -289.798506)
		(width 0.0889)
		(layer "In4.Cu")
		(net "M_D_CPU0_SB_DQ<25>")
	)
	(arc
		(start 338.213954 -289.798506)
		(mid 338.396205 -289.848856)
		(end 338.579714 -289.803332)
		(width 0.0889)
		(layer "In4.Cu")
		(net "M_D_CPU0_SB_DQ<25>")
	)
	(arc
		(start 333.88808 -289.798506)
		(mid 334.171036 -289.722329)
		(end 334.453992 -289.798506)
		(width 0.0889)
		(layer "In4.Cu")
		(net "M_D_CPU0_SB_DQ<25>")
	)
	(arc
		(start 335.402428 -289.803332)
		(mid 335.585936 -289.848826)
		(end 335.768188 -289.798506)
		(width 0.0889)
		(layer "In4.Cu")
		(net "M_D_CPU0_SB_DQ<25>")
	)
	(arc
		(start 330.702412 -289.803332)
		(mid 330.88592 -289.848826)
		(end 331.068172 -289.798506)
		(width 0.0889)
		(layer "In4.Cu")
		(net "M_D_CPU0_SB_DQ<25>")
	)
	(arc
		(start 329.753976 -289.798506)
		(mid 329.936227 -289.848856)
		(end 330.119736 -289.803332)
		(width 0.0889)
		(layer "In4.Cu")
		(net "M_D_CPU0_SB_DQ<25>")
	)
	(arc
		(start 339.154008 -289.798506)
		(mid 339.336259 -289.848856)
		(end 339.519768 -289.803332)
		(width 0.0889)
		(layer "In4.Cu")
		(net "M_D_CPU0_SB_DQ<25>")
	)
	(arc
		(start 340.102444 -289.803332)
		(mid 340.255314 -289.847973)
		(end 340.412832 -289.824668)
		(width 0.0889)
		(layer "In4.Cu")
		(net "M_D_CPU0_SB_DQ<25>")
	)
	(arc
		(start 331.068172 -289.798506)
		(mid 331.351128 -289.722329)
		(end 331.634084 -289.798506)
		(width 0.0889)
		(layer "In4.Cu")
		(net "M_D_CPU0_SB_DQ<25>")
	)
	(arc
		(start 327.873614 -289.798506)
		(mid 328.056119 -289.848983)
		(end 328.239882 -289.803332)
		(width 0.0889)
		(layer "In4.Cu")
		(net "M_D_CPU0_SB_DQ<25>")
	)
	(arc
		(start 339.52815 -289.798506)
		(mid 339.811106 -289.722329)
		(end 340.094062 -289.798506)
		(width 0.0889)
		(layer "In4.Cu")
		(net "M_D_CPU0_SB_DQ<25>")
	)
	(arc
		(start 331.642466 -289.803332)
		(mid 331.825974 -289.848826)
		(end 332.008226 -289.798506)
		(width 0.0889)
		(layer "In4.Cu")
		(net "M_D_CPU0_SB_DQ<25>")
	)
	(arc
		(start 337.648042 -289.798506)
		(mid 337.930998 -289.722329)
		(end 338.213954 -289.798506)
		(width 0.0889)
		(layer "In4.Cu")
		(net "M_D_CPU0_SB_DQ<25>")
	)
	(arc
		(start 330.128118 -289.798506)
		(mid 330.411074 -289.722329)
		(end 330.69403 -289.798506)
		(width 0.0889)
		(layer "In4.Cu")
		(net "M_D_CPU0_SB_DQ<25>")
	)
	(arc
		(start 328.814176 -289.798506)
		(mid 329.00112 -289.848761)
		(end 329.188064 -289.798506)
		(width 0.0889)
		(layer "In4.Cu")
		(net "M_D_CPU0_SB_DQ<25>")
	)
	(arc
		(start 326.367648 -289.798506)
		(mid 326.641503 -289.722156)
		(end 326.917812 -289.789108)
		(width 0.0889)
		(layer "In4.Cu")
		(net "M_D_CPU0_SB_DQ<25>")
	)
	(arc
		(start 328.248264 -289.798506)
		(mid 328.53122 -289.722329)
		(end 328.814176 -289.798506)
		(width 0.0889)
		(layer "In4.Cu")
		(net "M_D_CPU0_SB_DQ<25>")
	)
	(arc
		(start 334.453992 -289.798506)
		(mid 334.636243 -289.848856)
		(end 334.819752 -289.803332)
		(width 0.0889)
		(layer "In4.Cu")
		(net "M_D_CPU0_SB_DQ<25>")
	)
	(arc
		(start 332.574138 -289.798506)
		(mid 332.761082 -289.848761)
		(end 332.948026 -289.798506)
		(width 0.0889)
		(layer "In4.Cu")
		(net "M_D_CPU0_SB_DQ<25>")
	)
	(arc
		(start 327.321926 -289.78987)
		(mid 327.598909 -289.722066)
		(end 327.873614 -289.798506)
		(width 0.0889)
		(layer "In4.Cu")
		(net "M_D_CPU0_SB_DQ<25>")
	)
	(arc
		(start 337.274154 -289.798506)
		(mid 337.461098 -289.848761)
		(end 337.648042 -289.798506)
		(width 0.0889)
		(layer "In4.Cu")
		(net "M_D_CPU0_SB_DQ<25>")
	)
	(arc
		(start 333.513938 -289.798506)
		(mid 333.696189 -289.848856)
		(end 333.879698 -289.803332)
		(width 0.0889)
		(layer "In4.Cu")
		(net "M_D_CPU0_SB_DQ<25>")
	)
	(arc
		(start 336.342482 -289.803332)
		(mid 336.52599 -289.848826)
		(end 336.708242 -289.798506)
		(width 0.0889)
		(layer "In4.Cu")
		(net "M_D_CPU0_SB_DQ<25>")
	)
	(arc
		(start 326.947276 -289.806126)
		(mid 327.128206 -289.848604)
		(end 327.307194 -289.798506)
		(width 0.0889)
		(layer "In4.Cu")
		(net "M_D_CPU0_SB_DQ<25>")
	)
	(arc
		(start 338.588096 -289.798506)
		(mid 338.871052 -289.722329)
		(end 339.154008 -289.798506)
		(width 0.0889)
		(layer "In4.Cu")
		(net "M_D_CPU0_SB_DQ<25>")
	)
	(segment
		(start 339.337904 -288.399982)
		(end 338.871052 -288.66592)
		(width 0.10668)
		(layer "F.Cu")
		(net "M_D_CPU0_SB_DQ<24>")
	)
	(segment
		(start 318.083438 -299.455586)
		(end 318.083438 -299.049186)
		(width 0.14478)
		(layer "In4.Cu")
		(net "M_D_CPU0_SB_DQ<24>")
	)
	(segment
		(start 301.291752 -309.110126)
		(end 301.657766 -309.47614)
		(width 0.14478)
		(layer "In4.Cu")
		(net "M_D_CPU0_SB_DQ<24>")
	)
	(segment
		(start 319.453006 -297.679618)
		(end 319.453006 -296.353484)
		(width 0.14478)
		(layer "In4.Cu")
		(net "M_D_CPU0_SB_DQ<24>")
	)
	(segment
		(start 287.445958 -309.68569)
		(end 287.720532 -309.960264)
		(width 0.14478)
		(layer "In4.Cu")
		(net "M_D_CPU0_SB_DQ<24>")
	)
	(segment
		(start 304.19675 -309.571136)
		(end 304.359564 -309.73395)
		(width 0.14478)
		(layer "In4.Cu")
		(net "M_D_CPU0_SB_DQ<24>")
	)
	(segment
		(start 305.07432 -309.292752)
		(end 306.011834 -309.292752)
		(width 0.14478)
		(layer "In4.Cu")
		(net "M_D_CPU0_SB_DQ<24>")
	)
	(segment
		(start 303.966118 -309.571136)
		(end 304.19675 -309.571136)
		(width 0.14478)
		(layer "In4.Cu")
		(net "M_D_CPU0_SB_DQ<24>")
	)
	(segment
		(start 296.118026 -309.960264)
		(end 296.41038 -309.66791)
		(width 0.14478)
		(layer "In4.Cu")
		(net "M_D_CPU0_SB_DQ<24>")
	)
	(segment
		(start 326.114918 -289.039046)
		(end 326.650858 -289.039046)
		(width 0.0889)
		(layer "In4.Cu")
		(net "M_D_CPU0_SB_DQ<24>")
	)
	(segment
		(start 324.649338 -290.504626)
		(end 326.114918 -289.039046)
		(width 0.0889)
		(layer "In4.Cu")
		(net "M_D_CPU0_SB_DQ<24>")
	)
	(segment
		(start 304.359564 -310.144414)
		(end 304.522378 -310.307228)
		(width 0.14478)
		(layer "In4.Cu")
		(net "M_D_CPU0_SB_DQ<24>")
	)
	(segment
		(start 291.159184 -309.110126)
		(end 293.371524 -309.110126)
		(width 0.14478)
		(layer "In4.Cu")
		(net "M_D_CPU0_SB_DQ<24>")
	)
	(segment
		(start 316.522862 -301.016162)
		(end 316.522862 -300.609762)
		(width 0.14478)
		(layer "In4.Cu")
		(net "M_D_CPU0_SB_DQ<24>")
	)
	(segment
		(start 301.657766 -309.47614)
		(end 301.88789 -309.47614)
		(width 0.14478)
		(layer "In4.Cu")
		(net "M_D_CPU0_SB_DQ<24>")
	)
	(segment
		(start 289.92068 -310.34863)
		(end 291.159184 -309.110126)
		(width 0.14478)
		(layer "In4.Cu")
		(net "M_D_CPU0_SB_DQ<24>")
	)
	(segment
		(start 308.022498 -309.110126)
		(end 315.929518 -301.203106)
		(width 0.14478)
		(layer "In4.Cu")
		(net "M_D_CPU0_SB_DQ<24>")
	)
	(segment
		(start 328.709782 -288.993326)
		(end 328.718164 -288.9885)
		(width 0.0889)
		(layer "In4.Cu")
		(net "M_D_CPU0_SB_DQ<24>")
	)
	(segment
		(start 304.522378 -310.307228)
		(end 304.75301 -310.307228)
		(width 0.14478)
		(layer "In4.Cu")
		(net "M_D_CPU0_SB_DQ<24>")
	)
	(segment
		(start 302.309022 -309.285132)
		(end 302.472344 -309.448454)
		(width 0.14478)
		(layer "In4.Cu")
		(net "M_D_CPU0_SB_DQ<24>")
	)
	(segment
		(start 304.910998 -309.685944)
		(end 304.910998 -309.456074)
		(width 0.14478)
		(layer "In4.Cu")
		(net "M_D_CPU0_SB_DQ<24>")
	)
	(segment
		(start 303.64049 -310.307228)
		(end 303.803304 -310.144414)
		(width 0.14478)
		(layer "In4.Cu")
		(net "M_D_CPU0_SB_DQ<24>")
	)
	(segment
		(start 316.522862 -300.609762)
		(end 316.709806 -300.422818)
		(width 0.14478)
		(layer "In4.Cu")
		(net "M_D_CPU0_SB_DQ<24>")
	)
	(segment
		(start 304.910998 -309.456074)
		(end 305.07432 -309.292752)
		(width 0.14478)
		(layer "In4.Cu")
		(net "M_D_CPU0_SB_DQ<24>")
	)
	(segment
		(start 336.229706 -288.993326)
		(end 336.238088 -288.9885)
		(width 0.0889)
		(layer "In4.Cu")
		(net "M_D_CPU0_SB_DQ<24>")
	)
	(segment
		(start 305.027584 -310.032654)
		(end 305.027584 -309.80253)
		(width 0.14478)
		(layer "In4.Cu")
		(net "M_D_CPU0_SB_DQ<24>")
	)
	(segment
		(start 333.044038 -288.9885)
		(end 333.05242 -288.993326)
		(width 0.0889)
		(layer "In4.Cu")
		(net "M_D_CPU0_SB_DQ<24>")
	)
	(segment
		(start 302.281336 -309.869586)
		(end 302.281336 -310.09971)
		(width 0.14478)
		(layer "In4.Cu")
		(net "M_D_CPU0_SB_DQ<24>")
	)
	(segment
		(start 296.41038 -309.66791)
		(end 296.641012 -309.66791)
		(width 0.14478)
		(layer "In4.Cu")
		(net "M_D_CPU0_SB_DQ<24>")
	)
	(segment
		(start 285.939992 -310.182768)
		(end 285.939992 -309.848504)
		(width 0.14478)
		(layer "In4.Cu")
		(net "M_D_CPU0_SB_DQ<24>")
	)
	(segment
		(start 337.744054 -288.9885)
		(end 337.752436 -288.993326)
		(width 0.0889)
		(layer "In4.Cu")
		(net "M_D_CPU0_SB_DQ<24>")
	)
	(segment
		(start 294.75557 -310.27751)
		(end 294.994584 -310.27751)
		(width 0.14478)
		(layer "In4.Cu")
		(net "M_D_CPU0_SB_DQ<24>")
	)
	(segment
		(start 318.270382 -298.862242)
		(end 318.676782 -298.862242)
		(width 0.14478)
		(layer "In4.Cu")
		(net "M_D_CPU0_SB_DQ<24>")
	)
	(segment
		(start 287.052512 -310.182768)
		(end 287.052512 -309.848504)
		(width 0.14478)
		(layer "In4.Cu")
		(net "M_D_CPU0_SB_DQ<24>")
	)
	(segment
		(start 302.472344 -309.678578)
		(end 302.281336 -309.869586)
		(width 0.14478)
		(layer "In4.Cu")
		(net "M_D_CPU0_SB_DQ<24>")
	)
	(segment
		(start 333.984092 -288.9885)
		(end 333.992474 -288.993326)
		(width 0.0889)
		(layer "In4.Cu")
		(net "M_D_CPU0_SB_DQ<24>")
	)
	(segment
		(start 339.02523 -288.93135)
		(end 338.871052 -288.66592)
		(width 0.0889)
		(layer "In4.Cu")
		(net "M_D_CPU0_SB_DQ<24>")
	)
	(segment
		(start 317.490094 -299.64253)
		(end 317.896494 -299.64253)
		(width 0.14478)
		(layer "In4.Cu")
		(net "M_D_CPU0_SB_DQ<24>")
	)
	(segment
		(start 295.31183 -309.960264)
		(end 296.118026 -309.960264)
		(width 0.14478)
		(layer "In4.Cu")
		(net "M_D_CPU0_SB_DQ<24>")
	)
	(segment
		(start 294.438324 -309.960264)
		(end 294.75557 -310.27751)
		(width 0.14478)
		(layer "In4.Cu")
		(net "M_D_CPU0_SB_DQ<24>")
	)
	(segment
		(start 285.939992 -309.848504)
		(end 286.102806 -309.68569)
		(width 0.14478)
		(layer "In4.Cu")
		(net "M_D_CPU0_SB_DQ<24>")
	)
	(segment
		(start 285.777178 -310.345582)
		(end 285.939992 -310.182768)
		(width 0.14478)
		(layer "In4.Cu")
		(net "M_D_CPU0_SB_DQ<24>")
	)
	(segment
		(start 293.371524 -309.110126)
		(end 294.221662 -309.960264)
		(width 0.14478)
		(layer "In4.Cu")
		(net "M_D_CPU0_SB_DQ<24>")
	)
	(segment
		(start 300.737778 -309.38851)
		(end 301.016162 -309.110126)
		(width 0.14478)
		(layer "In4.Cu")
		(net "M_D_CPU0_SB_DQ<24>")
	)
	(segment
		(start 286.333438 -309.68569)
		(end 286.496252 -309.848504)
		(width 0.14478)
		(layer "In4.Cu")
		(net "M_D_CPU0_SB_DQ<24>")
	)
	(segment
		(start 324.649338 -291.157152)
		(end 324.649338 -290.504626)
		(width 0.0889)
		(layer "In4.Cu")
		(net "M_D_CPU0_SB_DQ<24>")
	)
	(segment
		(start 305.027584 -309.80253)
		(end 304.910998 -309.685944)
		(width 0.14478)
		(layer "In4.Cu")
		(net "M_D_CPU0_SB_DQ<24>")
	)
	(segment
		(start 296.803826 -310.181752)
		(end 296.96664 -310.344566)
		(width 0.14478)
		(layer "In4.Cu")
		(net "M_D_CPU0_SB_DQ<24>")
	)
	(segment
		(start 286.496252 -310.182768)
		(end 286.659066 -310.345582)
		(width 0.14478)
		(layer "In4.Cu")
		(net "M_D_CPU0_SB_DQ<24>")
	)
	(segment
		(start 326.837802 -288.988246)
		(end 326.85355 -288.979102)
		(width 0.0889)
		(layer "In4.Cu")
		(net "M_D_CPU0_SB_DQ<24>")
	)
	(segment
		(start 327.766426 -288.995358)
		(end 327.77811 -288.9885)
		(width 0.0889)
		(layer "In4.Cu")
		(net "M_D_CPU0_SB_DQ<24>")
	)
	(segment
		(start 339.002878 -289.014662)
		(end 339.02523 -288.93135)
		(width 0.0889)
		(layer "In4.Cu")
		(net "M_D_CPU0_SB_DQ<24>")
	)
	(segment
		(start 318.676782 -298.862242)
		(end 318.863726 -298.675298)
		(width 0.14478)
		(layer "In4.Cu")
		(net "M_D_CPU0_SB_DQ<24>")
	)
	(segment
		(start 304.359564 -309.73395)
		(end 304.359564 -310.144414)
		(width 0.14478)
		(layer "In4.Cu")
		(net "M_D_CPU0_SB_DQ<24>")
	)
	(segment
		(start 298.61891 -309.110126)
		(end 298.897294 -309.38851)
		(width 0.14478)
		(layer "In4.Cu")
		(net "M_D_CPU0_SB_DQ<24>")
	)
	(segment
		(start 319.453006 -296.353484)
		(end 323.723254 -292.083236)
		(width 0.14478)
		(layer "In4.Cu")
		(net "M_D_CPU0_SB_DQ<24>")
	)
	(segment
		(start 297.197272 -310.344566)
		(end 298.431712 -309.110126)
		(width 0.14478)
		(layer "In4.Cu")
		(net "M_D_CPU0_SB_DQ<24>")
	)
	(segment
		(start 286.889698 -310.345582)
		(end 287.052512 -310.182768)
		(width 0.14478)
		(layer "In4.Cu")
		(net "M_D_CPU0_SB_DQ<24>")
	)
	(segment
		(start 301.88789 -309.47614)
		(end 302.078898 -309.285132)
		(width 0.14478)
		(layer "In4.Cu")
		(net "M_D_CPU0_SB_DQ<24>")
	)
	(segment
		(start 301.016162 -309.110126)
		(end 301.291752 -309.110126)
		(width 0.14478)
		(layer "In4.Cu")
		(net "M_D_CPU0_SB_DQ<24>")
	)
	(segment
		(start 302.281336 -310.09971)
		(end 302.488854 -310.307228)
		(width 0.14478)
		(layer "In4.Cu")
		(net "M_D_CPU0_SB_DQ<24>")
	)
	(segment
		(start 287.052512 -309.848504)
		(end 287.215326 -309.68569)
		(width 0.14478)
		(layer "In4.Cu")
		(net "M_D_CPU0_SB_DQ<24>")
	)
	(segment
		(start 302.078898 -309.285132)
		(end 302.309022 -309.285132)
		(width 0.14478)
		(layer "In4.Cu")
		(net "M_D_CPU0_SB_DQ<24>")
	)
	(segment
		(start 315.929518 -301.203106)
		(end 316.335918 -301.203106)
		(width 0.14478)
		(layer "In4.Cu")
		(net "M_D_CPU0_SB_DQ<24>")
	)
	(segment
		(start 300.459902 -309.38851)
		(end 300.737778 -309.38851)
		(width 0.14478)
		(layer "In4.Cu")
		(net "M_D_CPU0_SB_DQ<24>")
	)
	(segment
		(start 303.803304 -309.73395)
		(end 303.966118 -309.571136)
		(width 0.14478)
		(layer "In4.Cu")
		(net "M_D_CPU0_SB_DQ<24>")
	)
	(segment
		(start 338.684108 -288.9885)
		(end 338.69249 -288.993326)
		(width 0.0889)
		(layer "In4.Cu")
		(net "M_D_CPU0_SB_DQ<24>")
	)
	(segment
		(start 298.431712 -309.110126)
		(end 298.61891 -309.110126)
		(width 0.14478)
		(layer "In4.Cu")
		(net "M_D_CPU0_SB_DQ<24>")
	)
	(segment
		(start 294.221662 -309.960264)
		(end 294.438324 -309.960264)
		(width 0.14478)
		(layer "In4.Cu")
		(net "M_D_CPU0_SB_DQ<24>")
	)
	(segment
		(start 294.994584 -310.27751)
		(end 295.31183 -309.960264)
		(width 0.14478)
		(layer "In4.Cu")
		(net "M_D_CPU0_SB_DQ<24>")
	)
	(segment
		(start 289.690048 -310.34863)
		(end 289.92068 -310.34863)
		(width 0.14478)
		(layer "In4.Cu")
		(net "M_D_CPU0_SB_DQ<24>")
	)
	(segment
		(start 317.896494 -299.64253)
		(end 318.083438 -299.455586)
		(width 0.14478)
		(layer "In4.Cu")
		(net "M_D_CPU0_SB_DQ<24>")
	)
	(segment
		(start 287.720532 -309.960264)
		(end 289.301682 -309.960264)
		(width 0.14478)
		(layer "In4.Cu")
		(net "M_D_CPU0_SB_DQ<24>")
	)
	(segment
		(start 307.005736 -309.110126)
		(end 308.022498 -309.110126)
		(width 0.14478)
		(layer "In4.Cu")
		(net "M_D_CPU0_SB_DQ<24>")
	)
	(segment
		(start 284.736032 -309.535068)
		(end 285.546546 -310.345582)
		(width 0.14478)
		(layer "In4.Cu")
		(net "M_D_CPU0_SB_DQ<24>")
	)
	(segment
		(start 286.659066 -310.345582)
		(end 286.889698 -310.345582)
		(width 0.14478)
		(layer "In4.Cu")
		(net "M_D_CPU0_SB_DQ<24>")
	)
	(segment
		(start 299.453554 -309.110126)
		(end 300.181518 -309.110126)
		(width 0.14478)
		(layer "In4.Cu")
		(net "M_D_CPU0_SB_DQ<24>")
	)
	(segment
		(start 296.96664 -310.344566)
		(end 297.197272 -310.344566)
		(width 0.14478)
		(layer "In4.Cu")
		(net "M_D_CPU0_SB_DQ<24>")
	)
	(segment
		(start 286.496252 -309.848504)
		(end 286.496252 -310.182768)
		(width 0.14478)
		(layer "In4.Cu")
		(net "M_D_CPU0_SB_DQ<24>")
	)
	(segment
		(start 317.116206 -300.422818)
		(end 317.30315 -300.235874)
		(width 0.14478)
		(layer "In4.Cu")
		(net "M_D_CPU0_SB_DQ<24>")
	)
	(segment
		(start 317.30315 -299.829474)
		(end 317.490094 -299.64253)
		(width 0.14478)
		(layer "In4.Cu")
		(net "M_D_CPU0_SB_DQ<24>")
	)
	(segment
		(start 306.449476 -308.85511)
		(end 306.75072 -308.85511)
		(width 0.14478)
		(layer "In4.Cu")
		(net "M_D_CPU0_SB_DQ<24>")
	)
	(segment
		(start 316.335918 -301.203106)
		(end 316.522862 -301.016162)
		(width 0.14478)
		(layer "In4.Cu")
		(net "M_D_CPU0_SB_DQ<24>")
	)
	(segment
		(start 299.17517 -309.38851)
		(end 299.453554 -309.110126)
		(width 0.14478)
		(layer "In4.Cu")
		(net "M_D_CPU0_SB_DQ<24>")
	)
	(segment
		(start 306.75072 -308.85511)
		(end 307.005736 -309.110126)
		(width 0.14478)
		(layer "In4.Cu")
		(net "M_D_CPU0_SB_DQ<24>")
	)
	(segment
		(start 316.709806 -300.422818)
		(end 317.116206 -300.422818)
		(width 0.14478)
		(layer "In4.Cu")
		(net "M_D_CPU0_SB_DQ<24>")
	)
	(segment
		(start 306.011834 -309.292752)
		(end 306.449476 -308.85511)
		(width 0.14478)
		(layer "In4.Cu")
		(net "M_D_CPU0_SB_DQ<24>")
	)
	(segment
		(start 304.75301 -310.307228)
		(end 305.027584 -310.032654)
		(width 0.14478)
		(layer "In4.Cu")
		(net "M_D_CPU0_SB_DQ<24>")
	)
	(segment
		(start 298.897294 -309.38851)
		(end 299.17517 -309.38851)
		(width 0.14478)
		(layer "In4.Cu")
		(net "M_D_CPU0_SB_DQ<24>")
	)
	(segment
		(start 329.284076 -288.9885)
		(end 329.292458 -288.993326)
		(width 0.0889)
		(layer "In4.Cu")
		(net "M_D_CPU0_SB_DQ<24>")
	)
	(segment
		(start 318.083438 -299.049186)
		(end 318.270382 -298.862242)
		(width 0.14478)
		(layer "In4.Cu")
		(net "M_D_CPU0_SB_DQ<24>")
	)
	(segment
		(start 296.803826 -309.830724)
		(end 296.803826 -310.181752)
		(width 0.14478)
		(layer "In4.Cu")
		(net "M_D_CPU0_SB_DQ<24>")
	)
	(segment
		(start 296.641012 -309.66791)
		(end 296.803826 -309.830724)
		(width 0.14478)
		(layer "In4.Cu")
		(net "M_D_CPU0_SB_DQ<24>")
	)
	(segment
		(start 302.472344 -309.448454)
		(end 302.472344 -309.678578)
		(width 0.14478)
		(layer "In4.Cu")
		(net "M_D_CPU0_SB_DQ<24>")
	)
	(segment
		(start 331.52969 -288.993326)
		(end 331.538072 -288.9885)
		(width 0.0889)
		(layer "In4.Cu")
		(net "M_D_CPU0_SB_DQ<24>")
	)
	(segment
		(start 318.863726 -298.268898)
		(end 319.453006 -297.679618)
		(width 0.14478)
		(layer "In4.Cu")
		(net "M_D_CPU0_SB_DQ<24>")
	)
	(segment
		(start 300.181518 -309.110126)
		(end 300.459902 -309.38851)
		(width 0.14478)
		(layer "In4.Cu")
		(net "M_D_CPU0_SB_DQ<24>")
	)
	(segment
		(start 303.803304 -310.144414)
		(end 303.803304 -309.73395)
		(width 0.14478)
		(layer "In4.Cu")
		(net "M_D_CPU0_SB_DQ<24>")
	)
	(segment
		(start 286.102806 -309.68569)
		(end 286.333438 -309.68569)
		(width 0.14478)
		(layer "In4.Cu")
		(net "M_D_CPU0_SB_DQ<24>")
	)
	(segment
		(start 285.546546 -310.345582)
		(end 285.777178 -310.345582)
		(width 0.14478)
		(layer "In4.Cu")
		(net "M_D_CPU0_SB_DQ<24>")
	)
	(segment
		(start 317.30315 -300.235874)
		(end 317.30315 -299.829474)
		(width 0.14478)
		(layer "In4.Cu")
		(net "M_D_CPU0_SB_DQ<24>")
	)
	(segment
		(start 337.16976 -288.993326)
		(end 337.178142 -288.9885)
		(width 0.0889)
		(layer "In4.Cu")
		(net "M_D_CPU0_SB_DQ<24>")
	)
	(segment
		(start 302.488854 -310.307228)
		(end 303.64049 -310.307228)
		(width 0.14478)
		(layer "In4.Cu")
		(net "M_D_CPU0_SB_DQ<24>")
	)
	(segment
		(start 289.301682 -309.960264)
		(end 289.690048 -310.34863)
		(width 0.14478)
		(layer "In4.Cu")
		(net "M_D_CPU0_SB_DQ<24>")
	)
	(segment
		(start 323.723254 -292.083236)
		(end 324.649338 -291.157152)
		(width 0.0889)
		(layer "In4.Cu")
		(net "M_D_CPU0_SB_DQ<24>")
	)
	(segment
		(start 332.469744 -288.993326)
		(end 332.478126 -288.9885)
		(width 0.0889)
		(layer "In4.Cu")
		(net "M_D_CPU0_SB_DQ<24>")
	)
	(segment
		(start 287.215326 -309.68569)
		(end 287.445958 -309.68569)
		(width 0.14478)
		(layer "In4.Cu")
		(net "M_D_CPU0_SB_DQ<24>")
	)
	(segment
		(start 318.863726 -298.675298)
		(end 318.863726 -298.268898)
		(width 0.14478)
		(layer "In4.Cu")
		(net "M_D_CPU0_SB_DQ<24>")
	)
	(arc
		(start 332.103984 -288.9885)
		(mid 332.286235 -289.03885)
		(end 332.469744 -288.993326)
		(width 0.0889)
		(layer "In4.Cu")
		(net "M_D_CPU0_SB_DQ<24>")
	)
	(arc
		(start 332.478126 -288.9885)
		(mid 332.761082 -288.912323)
		(end 333.044038 -288.9885)
		(width 0.0889)
		(layer "In4.Cu")
		(net "M_D_CPU0_SB_DQ<24>")
	)
	(arc
		(start 331.16393 -288.9885)
		(mid 331.346181 -289.03885)
		(end 331.52969 -288.993326)
		(width 0.0889)
		(layer "In4.Cu")
		(net "M_D_CPU0_SB_DQ<24>")
	)
	(arc
		(start 329.658218 -288.9885)
		(mid 329.941174 -288.912323)
		(end 330.22413 -288.9885)
		(width 0.0889)
		(layer "In4.Cu")
		(net "M_D_CPU0_SB_DQ<24>")
	)
	(arc
		(start 336.238088 -288.9885)
		(mid 336.521044 -288.912323)
		(end 336.804 -288.9885)
		(width 0.0889)
		(layer "In4.Cu")
		(net "M_D_CPU0_SB_DQ<24>")
	)
	(arc
		(start 330.22413 -288.9885)
		(mid 330.411074 -289.038755)
		(end 330.598018 -288.9885)
		(width 0.0889)
		(layer "In4.Cu")
		(net "M_D_CPU0_SB_DQ<24>")
	)
	(arc
		(start 334.358234 -288.9885)
		(mid 334.64119 -288.912323)
		(end 334.924146 -288.9885)
		(width 0.0889)
		(layer "In4.Cu")
		(net "M_D_CPU0_SB_DQ<24>")
	)
	(arc
		(start 327.77811 -288.9885)
		(mid 328.061066 -288.912323)
		(end 328.344022 -288.9885)
		(width 0.0889)
		(layer "In4.Cu")
		(net "M_D_CPU0_SB_DQ<24>")
	)
	(arc
		(start 337.752436 -288.993326)
		(mid 337.935944 -289.03882)
		(end 338.118196 -288.9885)
		(width 0.0889)
		(layer "In4.Cu")
		(net "M_D_CPU0_SB_DQ<24>")
	)
	(arc
		(start 331.538072 -288.9885)
		(mid 331.821028 -288.912323)
		(end 332.103984 -288.9885)
		(width 0.0889)
		(layer "In4.Cu")
		(net "M_D_CPU0_SB_DQ<24>")
	)
	(arc
		(start 326.85355 -288.979102)
		(mid 327.129859 -288.912126)
		(end 327.403714 -288.9885)
		(width 0.0889)
		(layer "In4.Cu")
		(net "M_D_CPU0_SB_DQ<24>")
	)
	(arc
		(start 335.863946 -288.9885)
		(mid 336.046197 -289.03885)
		(end 336.229706 -288.993326)
		(width 0.0889)
		(layer "In4.Cu")
		(net "M_D_CPU0_SB_DQ<24>")
	)
	(arc
		(start 327.403714 -288.9885)
		(mid 327.584172 -289.038944)
		(end 327.766426 -288.995358)
		(width 0.0889)
		(layer "In4.Cu")
		(net "M_D_CPU0_SB_DQ<24>")
	)
	(arc
		(start 328.718164 -288.9885)
		(mid 329.00112 -288.912323)
		(end 329.284076 -288.9885)
		(width 0.0889)
		(layer "In4.Cu")
		(net "M_D_CPU0_SB_DQ<24>")
	)
	(arc
		(start 330.598018 -288.9885)
		(mid 330.880974 -288.912323)
		(end 331.16393 -288.9885)
		(width 0.0889)
		(layer "In4.Cu")
		(net "M_D_CPU0_SB_DQ<24>")
	)
	(arc
		(start 338.118196 -288.9885)
		(mid 338.401152 -288.912323)
		(end 338.684108 -288.9885)
		(width 0.0889)
		(layer "In4.Cu")
		(net "M_D_CPU0_SB_DQ<24>")
	)
	(arc
		(start 337.178142 -288.9885)
		(mid 337.461098 -288.912323)
		(end 337.744054 -288.9885)
		(width 0.0889)
		(layer "In4.Cu")
		(net "M_D_CPU0_SB_DQ<24>")
	)
	(arc
		(start 335.298034 -288.9885)
		(mid 335.58099 -288.912323)
		(end 335.863946 -288.9885)
		(width 0.0889)
		(layer "In4.Cu")
		(net "M_D_CPU0_SB_DQ<24>")
	)
	(arc
		(start 336.804 -288.9885)
		(mid 336.986251 -289.03885)
		(end 337.16976 -288.993326)
		(width 0.0889)
		(layer "In4.Cu")
		(net "M_D_CPU0_SB_DQ<24>")
	)
	(arc
		(start 333.41818 -288.9885)
		(mid 333.701136 -288.912323)
		(end 333.984092 -288.9885)
		(width 0.0889)
		(layer "In4.Cu")
		(net "M_D_CPU0_SB_DQ<24>")
	)
	(arc
		(start 333.992474 -288.993326)
		(mid 334.175982 -289.03882)
		(end 334.358234 -288.9885)
		(width 0.0889)
		(layer "In4.Cu")
		(net "M_D_CPU0_SB_DQ<24>")
	)
	(arc
		(start 329.292458 -288.993326)
		(mid 329.475966 -289.03882)
		(end 329.658218 -288.9885)
		(width 0.0889)
		(layer "In4.Cu")
		(net "M_D_CPU0_SB_DQ<24>")
	)
	(arc
		(start 334.924146 -288.9885)
		(mid 335.11109 -289.038755)
		(end 335.298034 -288.9885)
		(width 0.0889)
		(layer "In4.Cu")
		(net "M_D_CPU0_SB_DQ<24>")
	)
	(arc
		(start 338.69249 -288.993326)
		(mid 338.84536 -289.037967)
		(end 339.002878 -289.014662)
		(width 0.0889)
		(layer "In4.Cu")
		(net "M_D_CPU0_SB_DQ<24>")
	)
	(arc
		(start 333.05242 -288.993326)
		(mid 333.235928 -289.03882)
		(end 333.41818 -288.9885)
		(width 0.0889)
		(layer "In4.Cu")
		(net "M_D_CPU0_SB_DQ<24>")
	)
	(arc
		(start 328.344022 -288.9885)
		(mid 328.526273 -289.03885)
		(end 328.709782 -288.993326)
		(width 0.0889)
		(layer "In4.Cu")
		(net "M_D_CPU0_SB_DQ<24>")
	)
	(arc
		(start 326.650858 -289.039046)
		(mid 326.747676 -289.025975)
		(end 326.837802 -288.988246)
		(width 0.0889)
		(layer "In4.Cu")
		(net "M_D_CPU0_SB_DQ<24>")
	)
	(segment
		(start 341.218012 -288.399982)
		(end 340.75116 -288.66592)
		(width 0.10668)
		(layer "F.Cu")
		(net "M_D_CPU0_SB_DQ<23>")
	)
	(segment
		(start 318.863726 -297.190922)
		(end 318.863726 -296.109644)
		(width 0.14478)
		(layer "In4.Cu")
		(net "M_D_CPU0_SB_DQ<23>")
	)
	(segment
		(start 328.709782 -288.338768)
		(end 328.718164 -288.343594)
		(width 0.0889)
		(layer "In4.Cu")
		(net "M_D_CPU0_SB_DQ<23>")
	)
	(segment
		(start 305.939698 -308.333394)
		(end 307.90515 -307.942488)
		(width 0.14478)
		(layer "In4.Cu")
		(net "M_D_CPU0_SB_DQ<23>")
	)
	(segment
		(start 297.644566 -309.110126)
		(end 298.494704 -308.259988)
		(width 0.14478)
		(layer "In4.Cu")
		(net "M_D_CPU0_SB_DQ<23>")
	)
	(segment
		(start 327.769728 -288.338768)
		(end 327.77811 -288.343594)
		(width 0.0889)
		(layer "In4.Cu")
		(net "M_D_CPU0_SB_DQ<23>")
	)
	(segment
		(start 340.501224 -288.37509)
		(end 340.596982 -288.40049)
		(width 0.0889)
		(layer "In4.Cu")
		(net "M_D_CPU0_SB_DQ<23>")
	)
	(segment
		(start 324.351904 -290.621466)
		(end 324.351904 -290.532566)
		(width 0.0889)
		(layer "In4.Cu")
		(net "M_D_CPU0_SB_DQ<23>")
	)
	(segment
		(start 308.258718 -307.79593)
		(end 318.863726 -297.190922)
		(width 0.14478)
		(layer "In4.Cu")
		(net "M_D_CPU0_SB_DQ<23>")
	)
	(segment
		(start 337.16976 -288.338768)
		(end 337.178142 -288.343594)
		(width 0.0889)
		(layer "In4.Cu")
		(net "M_D_CPU0_SB_DQ<23>")
	)
	(segment
		(start 281.060906 -309.110126)
		(end 290.321238 -309.110126)
		(width 0.14478)
		(layer "In4.Cu")
		(net "M_D_CPU0_SB_DQ<23>")
	)
	(segment
		(start 326.826372 -288.336736)
		(end 326.838056 -288.343594)
		(width 0.0889)
		(layer "In4.Cu")
		(net "M_D_CPU0_SB_DQ<23>")
	)
	(segment
		(start 301.683674 -308.714902)
		(end 305.55819 -308.714902)
		(width 0.14478)
		(layer "In4.Cu")
		(net "M_D_CPU0_SB_DQ<23>")
	)
	(segment
		(start 337.744054 -288.343594)
		(end 337.752436 -288.338768)
		(width 0.0889)
		(layer "In4.Cu")
		(net "M_D_CPU0_SB_DQ<23>")
	)
	(segment
		(start 290.321238 -309.110126)
		(end 291.171376 -308.259988)
		(width 0.14478)
		(layer "In4.Cu")
		(net "M_D_CPU0_SB_DQ<23>")
	)
	(segment
		(start 333.984092 -288.343594)
		(end 333.992474 -288.338768)
		(width 0.0889)
		(layer "In4.Cu")
		(net "M_D_CPU0_SB_DQ<23>")
	)
	(segment
		(start 293.384732 -308.259988)
		(end 294.23487 -309.110126)
		(width 0.14478)
		(layer "In4.Cu")
		(net "M_D_CPU0_SB_DQ<23>")
	)
	(segment
		(start 318.863726 -296.109644)
		(end 323.805804 -291.167566)
		(width 0.14478)
		(layer "In4.Cu")
		(net "M_D_CPU0_SB_DQ<23>")
	)
	(segment
		(start 325.924418 -288.420048)
		(end 326.179942 -288.420048)
		(width 0.0889)
		(layer "In4.Cu")
		(net "M_D_CPU0_SB_DQ<23>")
	)
	(segment
		(start 324.351904 -290.532566)
		(end 325.568818 -289.315652)
		(width 0.0889)
		(layer "In4.Cu")
		(net "M_D_CPU0_SB_DQ<23>")
	)
	(segment
		(start 340.596982 -288.40049)
		(end 340.75116 -288.66592)
		(width 0.0889)
		(layer "In4.Cu")
		(net "M_D_CPU0_SB_DQ<23>")
	)
	(segment
		(start 336.229706 -288.338768)
		(end 336.238088 -288.343594)
		(width 0.0889)
		(layer "In4.Cu")
		(net "M_D_CPU0_SB_DQ<23>")
	)
	(segment
		(start 280.635964 -308.685184)
		(end 281.060906 -309.110126)
		(width 0.14478)
		(layer "In4.Cu")
		(net "M_D_CPU0_SB_DQ<23>")
	)
	(segment
		(start 333.044038 -288.343594)
		(end 333.05242 -288.338768)
		(width 0.0889)
		(layer "In4.Cu")
		(net "M_D_CPU0_SB_DQ<23>")
	)
	(segment
		(start 338.684108 -288.343594)
		(end 338.69249 -288.338768)
		(width 0.0889)
		(layer "In4.Cu")
		(net "M_D_CPU0_SB_DQ<23>")
	)
	(segment
		(start 332.469744 -288.338768)
		(end 332.478126 -288.343594)
		(width 0.0889)
		(layer "In4.Cu")
		(net "M_D_CPU0_SB_DQ<23>")
	)
	(segment
		(start 294.23487 -309.110126)
		(end 297.644566 -309.110126)
		(width 0.14478)
		(layer "In4.Cu")
		(net "M_D_CPU0_SB_DQ<23>")
	)
	(segment
		(start 291.171376 -308.259988)
		(end 293.384732 -308.259988)
		(width 0.14478)
		(layer "In4.Cu")
		(net "M_D_CPU0_SB_DQ<23>")
	)
	(segment
		(start 323.805804 -291.167566)
		(end 324.351904 -290.621466)
		(width 0.0889)
		(layer "In4.Cu")
		(net "M_D_CPU0_SB_DQ<23>")
	)
	(segment
		(start 301.22876 -308.259988)
		(end 301.683674 -308.714902)
		(width 0.14478)
		(layer "In4.Cu")
		(net "M_D_CPU0_SB_DQ<23>")
	)
	(segment
		(start 329.284076 -288.343594)
		(end 329.292458 -288.338768)
		(width 0.0889)
		(layer "In4.Cu")
		(net "M_D_CPU0_SB_DQ<23>")
	)
	(segment
		(start 298.494704 -308.259988)
		(end 301.22876 -308.259988)
		(width 0.14478)
		(layer "In4.Cu")
		(net "M_D_CPU0_SB_DQ<23>")
	)
	(segment
		(start 325.568818 -289.315652)
		(end 325.568818 -288.775648)
		(width 0.0889)
		(layer "In4.Cu")
		(net "M_D_CPU0_SB_DQ<23>")
	)
	(segment
		(start 307.90515 -307.942488)
		(end 308.258718 -307.79593)
		(width 0.14478)
		(layer "In4.Cu")
		(net "M_D_CPU0_SB_DQ<23>")
	)
	(segment
		(start 305.55819 -308.714902)
		(end 305.939698 -308.333394)
		(width 0.14478)
		(layer "In4.Cu")
		(net "M_D_CPU0_SB_DQ<23>")
	)
	(segment
		(start 325.568818 -288.775648)
		(end 325.924418 -288.420048)
		(width 0.0889)
		(layer "In4.Cu")
		(net "M_D_CPU0_SB_DQ<23>")
	)
	(segment
		(start 331.52969 -288.338768)
		(end 331.538072 -288.343594)
		(width 0.0889)
		(layer "In4.Cu")
		(net "M_D_CPU0_SB_DQ<23>")
	)
	(arc
		(start 326.46366 -288.343594)
		(mid 326.644118 -288.293115)
		(end 326.826372 -288.336736)
		(width 0.0889)
		(layer "In4.Cu")
		(net "M_D_CPU0_SB_DQ<23>")
	)
	(arc
		(start 339.624162 -288.343594)
		(mid 339.811106 -288.293305)
		(end 339.99805 -288.343594)
		(width 0.0889)
		(layer "In4.Cu")
		(net "M_D_CPU0_SB_DQ<23>")
	)
	(arc
		(start 328.718164 -288.343594)
		(mid 329.00112 -288.419771)
		(end 329.284076 -288.343594)
		(width 0.0889)
		(layer "In4.Cu")
		(net "M_D_CPU0_SB_DQ<23>")
	)
	(arc
		(start 333.41818 -288.343594)
		(mid 333.701136 -288.419771)
		(end 333.984092 -288.343594)
		(width 0.0889)
		(layer "In4.Cu")
		(net "M_D_CPU0_SB_DQ<23>")
	)
	(arc
		(start 332.478126 -288.343594)
		(mid 332.761082 -288.419771)
		(end 333.044038 -288.343594)
		(width 0.0889)
		(layer "In4.Cu")
		(net "M_D_CPU0_SB_DQ<23>")
	)
	(arc
		(start 326.838056 -288.343594)
		(mid 327.121012 -288.419771)
		(end 327.403968 -288.343594)
		(width 0.0889)
		(layer "In4.Cu")
		(net "M_D_CPU0_SB_DQ<23>")
	)
	(arc
		(start 335.298034 -288.343594)
		(mid 335.58099 -288.419771)
		(end 335.863946 -288.343594)
		(width 0.0889)
		(layer "In4.Cu")
		(net "M_D_CPU0_SB_DQ<23>")
	)
	(arc
		(start 328.344022 -288.343594)
		(mid 328.526273 -288.29321)
		(end 328.709782 -288.338768)
		(width 0.0889)
		(layer "In4.Cu")
		(net "M_D_CPU0_SB_DQ<23>")
	)
	(arc
		(start 335.863946 -288.343594)
		(mid 336.046197 -288.29321)
		(end 336.229706 -288.338768)
		(width 0.0889)
		(layer "In4.Cu")
		(net "M_D_CPU0_SB_DQ<23>")
	)
	(arc
		(start 337.752436 -288.338768)
		(mid 337.935944 -288.293243)
		(end 338.118196 -288.343594)
		(width 0.0889)
		(layer "In4.Cu")
		(net "M_D_CPU0_SB_DQ<23>")
	)
	(arc
		(start 333.05242 -288.338768)
		(mid 333.235928 -288.293243)
		(end 333.41818 -288.343594)
		(width 0.0889)
		(layer "In4.Cu")
		(net "M_D_CPU0_SB_DQ<23>")
	)
	(arc
		(start 329.658218 -288.343594)
		(mid 329.941174 -288.419771)
		(end 330.22413 -288.343594)
		(width 0.0889)
		(layer "In4.Cu")
		(net "M_D_CPU0_SB_DQ<23>")
	)
	(arc
		(start 333.992474 -288.338768)
		(mid 334.175982 -288.293243)
		(end 334.358234 -288.343594)
		(width 0.0889)
		(layer "In4.Cu")
		(net "M_D_CPU0_SB_DQ<23>")
	)
	(arc
		(start 334.358234 -288.343594)
		(mid 334.64119 -288.419771)
		(end 334.924146 -288.343594)
		(width 0.0889)
		(layer "In4.Cu")
		(net "M_D_CPU0_SB_DQ<23>")
	)
	(arc
		(start 326.179942 -288.420048)
		(mid 326.326873 -288.400637)
		(end 326.46366 -288.343594)
		(width 0.0889)
		(layer "In4.Cu")
		(net "M_D_CPU0_SB_DQ<23>")
	)
	(arc
		(start 338.118196 -288.343594)
		(mid 338.401152 -288.419771)
		(end 338.684108 -288.343594)
		(width 0.0889)
		(layer "In4.Cu")
		(net "M_D_CPU0_SB_DQ<23>")
	)
	(arc
		(start 339.05825 -288.343594)
		(mid 339.341206 -288.419771)
		(end 339.624162 -288.343594)
		(width 0.0889)
		(layer "In4.Cu")
		(net "M_D_CPU0_SB_DQ<23>")
	)
	(arc
		(start 337.178142 -288.343594)
		(mid 337.461098 -288.419771)
		(end 337.744054 -288.343594)
		(width 0.0889)
		(layer "In4.Cu")
		(net "M_D_CPU0_SB_DQ<23>")
	)
	(arc
		(start 330.22413 -288.343594)
		(mid 330.411074 -288.293305)
		(end 330.598018 -288.343594)
		(width 0.0889)
		(layer "In4.Cu")
		(net "M_D_CPU0_SB_DQ<23>")
	)
	(arc
		(start 330.598018 -288.343594)
		(mid 330.880974 -288.419771)
		(end 331.16393 -288.343594)
		(width 0.0889)
		(layer "In4.Cu")
		(net "M_D_CPU0_SB_DQ<23>")
	)
	(arc
		(start 334.924146 -288.343594)
		(mid 335.11109 -288.293305)
		(end 335.298034 -288.343594)
		(width 0.0889)
		(layer "In4.Cu")
		(net "M_D_CPU0_SB_DQ<23>")
	)
	(arc
		(start 327.403968 -288.343594)
		(mid 327.586219 -288.29321)
		(end 327.769728 -288.338768)
		(width 0.0889)
		(layer "In4.Cu")
		(net "M_D_CPU0_SB_DQ<23>")
	)
	(arc
		(start 331.538072 -288.343594)
		(mid 331.821028 -288.419771)
		(end 332.103984 -288.343594)
		(width 0.0889)
		(layer "In4.Cu")
		(net "M_D_CPU0_SB_DQ<23>")
	)
	(arc
		(start 331.16393 -288.343594)
		(mid 331.346181 -288.29321)
		(end 331.52969 -288.338768)
		(width 0.0889)
		(layer "In4.Cu")
		(net "M_D_CPU0_SB_DQ<23>")
	)
	(arc
		(start 329.292458 -288.338768)
		(mid 329.475966 -288.293243)
		(end 329.658218 -288.343594)
		(width 0.0889)
		(layer "In4.Cu")
		(net "M_D_CPU0_SB_DQ<23>")
	)
	(arc
		(start 339.99805 -288.343594)
		(mid 340.24591 -288.418677)
		(end 340.501224 -288.37509)
		(width 0.0889)
		(layer "In4.Cu")
		(net "M_D_CPU0_SB_DQ<23>")
	)
	(arc
		(start 327.77811 -288.343594)
		(mid 328.061066 -288.419771)
		(end 328.344022 -288.343594)
		(width 0.0889)
		(layer "In4.Cu")
		(net "M_D_CPU0_SB_DQ<23>")
	)
	(arc
		(start 336.804 -288.343594)
		(mid 336.986251 -288.29321)
		(end 337.16976 -288.338768)
		(width 0.0889)
		(layer "In4.Cu")
		(net "M_D_CPU0_SB_DQ<23>")
	)
	(arc
		(start 338.69249 -288.338768)
		(mid 338.875998 -288.293243)
		(end 339.05825 -288.343594)
		(width 0.0889)
		(layer "In4.Cu")
		(net "M_D_CPU0_SB_DQ<23>")
	)
	(arc
		(start 336.238088 -288.343594)
		(mid 336.521044 -288.419771)
		(end 336.804 -288.343594)
		(width 0.0889)
		(layer "In4.Cu")
		(net "M_D_CPU0_SB_DQ<23>")
	)
	(arc
		(start 332.103984 -288.343594)
		(mid 332.286235 -288.29321)
		(end 332.469744 -288.338768)
		(width 0.0889)
		(layer "In4.Cu")
		(net "M_D_CPU0_SB_DQ<23>")
	)
	(segment
		(start 339.808058 -287.59023)
		(end 339.341206 -287.856168)
		(width 0.10668)
		(layer "F.Cu")
		(net "M_D_CPU0_SB_DQ<22>")
	)
	(segment
		(start 328.239882 -287.528762)
		(end 328.248264 -287.533588)
		(width 0.0889)
		(layer "In4.Cu")
		(net "M_D_CPU0_SB_DQ<22>")
	)
	(segment
		(start 283.249878 -306.41671)
		(end 283.48051 -306.41671)
		(width 0.14478)
		(layer "In4.Cu")
		(net "M_D_CPU0_SB_DQ<22>")
	)
	(segment
		(start 327.307956 -287.533588)
		(end 327.32599 -287.544002)
		(width 0.0889)
		(layer "In4.Cu")
		(net "M_D_CPU0_SB_DQ<22>")
	)
	(segment
		(start 335.394046 -287.533588)
		(end 335.402428 -287.528762)
		(width 0.0889)
		(layer "In4.Cu")
		(net "M_D_CPU0_SB_DQ<22>")
	)
	(segment
		(start 324.369938 -289.220148)
		(end 324.369938 -288.962338)
		(width 0.0889)
		(layer "In4.Cu")
		(net "M_D_CPU0_SB_DQ<22>")
	)
	(segment
		(start 290.649406 -307.410104)
		(end 291.499544 -306.559966)
		(width 0.14478)
		(layer "In4.Cu")
		(net "M_D_CPU0_SB_DQ<22>")
	)
	(segment
		(start 334.819752 -287.528762)
		(end 334.828134 -287.533588)
		(width 0.0889)
		(layer "In4.Cu")
		(net "M_D_CPU0_SB_DQ<22>")
	)
	(segment
		(start 330.69403 -287.533588)
		(end 330.702412 -287.528762)
		(width 0.0889)
		(layer "In4.Cu")
		(net "M_D_CPU0_SB_DQ<22>")
	)
	(segment
		(start 280.635964 -306.985162)
		(end 281.060906 -307.410104)
		(width 0.14478)
		(layer "In4.Cu")
		(net "M_D_CPU0_SB_DQ<22>")
	)
	(segment
		(start 317.964566 -296.81805)
		(end 317.964566 -295.62552)
		(width 0.14478)
		(layer "In4.Cu")
		(net "M_D_CPU0_SB_DQ<22>")
	)
	(segment
		(start 294.059102 -307.410104)
		(end 298.058078 -307.410104)
		(width 0.14478)
		(layer "In4.Cu")
		(net "M_D_CPU0_SB_DQ<22>")
	)
	(segment
		(start 301.665386 -307.410104)
		(end 305.369722 -307.410104)
		(width 0.14478)
		(layer "In4.Cu")
		(net "M_D_CPU0_SB_DQ<22>")
	)
	(segment
		(start 323.890386 -289.6997)
		(end 324.369938 -289.220148)
		(width 0.0889)
		(layer "In4.Cu")
		(net "M_D_CPU0_SB_DQ<22>")
	)
	(segment
		(start 298.908216 -306.559966)
		(end 300.815248 -306.559966)
		(width 0.14478)
		(layer "In4.Cu")
		(net "M_D_CPU0_SB_DQ<22>")
	)
	(segment
		(start 306.21986 -306.559966)
		(end 308.22265 -306.559966)
		(width 0.14478)
		(layer "In4.Cu")
		(net "M_D_CPU0_SB_DQ<22>")
	)
	(segment
		(start 291.499544 -306.559966)
		(end 293.208964 -306.559966)
		(width 0.14478)
		(layer "In4.Cu")
		(net "M_D_CPU0_SB_DQ<22>")
	)
	(segment
		(start 325.269352 -288.149792)
		(end 325.809356 -287.609788)
		(width 0.0889)
		(layer "In4.Cu")
		(net "M_D_CPU0_SB_DQ<22>")
	)
	(segment
		(start 283.806138 -307.410104)
		(end 290.649406 -307.410104)
		(width 0.14478)
		(layer "In4.Cu")
		(net "M_D_CPU0_SB_DQ<22>")
	)
	(segment
		(start 330.119736 -287.528762)
		(end 330.128118 -287.533588)
		(width 0.0889)
		(layer "In4.Cu")
		(net "M_D_CPU0_SB_DQ<22>")
	)
	(segment
		(start 339.187028 -287.590738)
		(end 339.341206 -287.856168)
		(width 0.0889)
		(layer "In4.Cu")
		(net "M_D_CPU0_SB_DQ<22>")
	)
	(segment
		(start 283.087064 -306.579524)
		(end 283.249878 -306.41671)
		(width 0.14478)
		(layer "In4.Cu")
		(net "M_D_CPU0_SB_DQ<22>")
	)
	(segment
		(start 282.92425 -307.410104)
		(end 283.087064 -307.24729)
		(width 0.14478)
		(layer "In4.Cu")
		(net "M_D_CPU0_SB_DQ<22>")
	)
	(segment
		(start 281.060906 -307.410104)
		(end 282.92425 -307.410104)
		(width 0.14478)
		(layer "In4.Cu")
		(net "M_D_CPU0_SB_DQ<22>")
	)
	(segment
		(start 325.182484 -288.149792)
		(end 325.269352 -288.149792)
		(width 0.0889)
		(layer "In4.Cu")
		(net "M_D_CPU0_SB_DQ<22>")
	)
	(segment
		(start 293.208964 -306.559966)
		(end 294.059102 -307.410104)
		(width 0.14478)
		(layer "In4.Cu")
		(net "M_D_CPU0_SB_DQ<22>")
	)
	(segment
		(start 338.579714 -287.528762)
		(end 338.588096 -287.533588)
		(width 0.0889)
		(layer "In4.Cu")
		(net "M_D_CPU0_SB_DQ<22>")
	)
	(segment
		(start 325.809356 -287.609788)
		(end 326.651112 -287.609788)
		(width 0.0889)
		(layer "In4.Cu")
		(net "M_D_CPU0_SB_DQ<22>")
	)
	(segment
		(start 283.087064 -307.24729)
		(end 283.087064 -306.579524)
		(width 0.14478)
		(layer "In4.Cu")
		(net "M_D_CPU0_SB_DQ<22>")
	)
	(segment
		(start 298.058078 -307.410104)
		(end 298.908216 -306.559966)
		(width 0.14478)
		(layer "In4.Cu")
		(net "M_D_CPU0_SB_DQ<22>")
	)
	(segment
		(start 336.3341 -287.533588)
		(end 336.342482 -287.528762)
		(width 0.0889)
		(layer "In4.Cu")
		(net "M_D_CPU0_SB_DQ<22>")
	)
	(segment
		(start 305.369722 -307.410104)
		(end 306.21986 -306.559966)
		(width 0.14478)
		(layer "In4.Cu")
		(net "M_D_CPU0_SB_DQ<22>")
	)
	(segment
		(start 283.643324 -307.24729)
		(end 283.806138 -307.410104)
		(width 0.14478)
		(layer "In4.Cu")
		(net "M_D_CPU0_SB_DQ<22>")
	)
	(segment
		(start 324.369938 -288.962338)
		(end 325.182484 -288.149792)
		(width 0.0889)
		(layer "In4.Cu")
		(net "M_D_CPU0_SB_DQ<22>")
	)
	(segment
		(start 283.643324 -306.579524)
		(end 283.643324 -307.24729)
		(width 0.14478)
		(layer "In4.Cu")
		(net "M_D_CPU0_SB_DQ<22>")
	)
	(segment
		(start 308.22265 -306.559966)
		(end 317.964566 -296.81805)
		(width 0.14478)
		(layer "In4.Cu")
		(net "M_D_CPU0_SB_DQ<22>")
	)
	(segment
		(start 317.964566 -295.62552)
		(end 323.890386 -289.6997)
		(width 0.14478)
		(layer "In4.Cu")
		(net "M_D_CPU0_SB_DQ<22>")
	)
	(segment
		(start 339.090762 -287.565338)
		(end 339.187028 -287.590738)
		(width 0.0889)
		(layer "In4.Cu")
		(net "M_D_CPU0_SB_DQ<22>")
	)
	(segment
		(start 300.815248 -306.559966)
		(end 301.665386 -307.410104)
		(width 0.14478)
		(layer "In4.Cu")
		(net "M_D_CPU0_SB_DQ<22>")
	)
	(segment
		(start 331.634084 -287.533588)
		(end 331.642466 -287.528762)
		(width 0.0889)
		(layer "In4.Cu")
		(net "M_D_CPU0_SB_DQ<22>")
	)
	(segment
		(start 283.48051 -306.41671)
		(end 283.643324 -306.579524)
		(width 0.14478)
		(layer "In4.Cu")
		(net "M_D_CPU0_SB_DQ<22>")
	)
	(segment
		(start 333.879698 -287.528762)
		(end 333.88808 -287.533588)
		(width 0.0889)
		(layer "In4.Cu")
		(net "M_D_CPU0_SB_DQ<22>")
	)
	(arc
		(start 329.188064 -287.533588)
		(mid 329.47102 -287.609731)
		(end 329.753976 -287.533588)
		(width 0.0889)
		(layer "In4.Cu")
		(net "M_D_CPU0_SB_DQ<22>")
	)
	(arc
		(start 334.828134 -287.533588)
		(mid 335.11109 -287.609731)
		(end 335.394046 -287.533588)
		(width 0.0889)
		(layer "In4.Cu")
		(net "M_D_CPU0_SB_DQ<22>")
	)
	(arc
		(start 331.068172 -287.533588)
		(mid 331.351128 -287.609731)
		(end 331.634084 -287.533588)
		(width 0.0889)
		(layer "In4.Cu")
		(net "M_D_CPU0_SB_DQ<22>")
	)
	(arc
		(start 328.814176 -287.533588)
		(mid 329.00112 -287.483333)
		(end 329.188064 -287.533588)
		(width 0.0889)
		(layer "In4.Cu")
		(net "M_D_CPU0_SB_DQ<22>")
	)
	(arc
		(start 330.128118 -287.533588)
		(mid 330.411074 -287.609731)
		(end 330.69403 -287.533588)
		(width 0.0889)
		(layer "In4.Cu")
		(net "M_D_CPU0_SB_DQ<22>")
	)
	(arc
		(start 333.513938 -287.533588)
		(mid 333.696189 -287.483238)
		(end 333.879698 -287.528762)
		(width 0.0889)
		(layer "In4.Cu")
		(net "M_D_CPU0_SB_DQ<22>")
	)
	(arc
		(start 333.88808 -287.533588)
		(mid 334.171036 -287.609731)
		(end 334.453992 -287.533588)
		(width 0.0889)
		(layer "In4.Cu")
		(net "M_D_CPU0_SB_DQ<22>")
	)
	(arc
		(start 327.873614 -287.533588)
		(mid 328.056119 -287.483111)
		(end 328.239882 -287.528762)
		(width 0.0889)
		(layer "In4.Cu")
		(net "M_D_CPU0_SB_DQ<22>")
	)
	(arc
		(start 337.274154 -287.533588)
		(mid 337.461098 -287.483333)
		(end 337.648042 -287.533588)
		(width 0.0889)
		(layer "In4.Cu")
		(net "M_D_CPU0_SB_DQ<22>")
	)
	(arc
		(start 336.342482 -287.528762)
		(mid 336.52599 -287.483268)
		(end 336.708242 -287.533588)
		(width 0.0889)
		(layer "In4.Cu")
		(net "M_D_CPU0_SB_DQ<22>")
	)
	(arc
		(start 335.768188 -287.533588)
		(mid 336.051144 -287.609731)
		(end 336.3341 -287.533588)
		(width 0.0889)
		(layer "In4.Cu")
		(net "M_D_CPU0_SB_DQ<22>")
	)
	(arc
		(start 326.651112 -287.609788)
		(mid 326.797638 -287.590418)
		(end 326.934068 -287.533588)
		(width 0.0889)
		(layer "In4.Cu")
		(net "M_D_CPU0_SB_DQ<22>")
	)
	(arc
		(start 338.213954 -287.533588)
		(mid 338.396205 -287.483238)
		(end 338.579714 -287.528762)
		(width 0.0889)
		(layer "In4.Cu")
		(net "M_D_CPU0_SB_DQ<22>")
	)
	(arc
		(start 331.642466 -287.528762)
		(mid 331.825974 -287.483268)
		(end 332.008226 -287.533588)
		(width 0.0889)
		(layer "In4.Cu")
		(net "M_D_CPU0_SB_DQ<22>")
	)
	(arc
		(start 338.588096 -287.533588)
		(mid 338.835693 -287.608732)
		(end 339.090762 -287.565338)
		(width 0.0889)
		(layer "In4.Cu")
		(net "M_D_CPU0_SB_DQ<22>")
	)
	(arc
		(start 329.753976 -287.533588)
		(mid 329.936227 -287.483238)
		(end 330.119736 -287.528762)
		(width 0.0889)
		(layer "In4.Cu")
		(net "M_D_CPU0_SB_DQ<22>")
	)
	(arc
		(start 335.402428 -287.528762)
		(mid 335.585936 -287.483268)
		(end 335.768188 -287.533588)
		(width 0.0889)
		(layer "In4.Cu")
		(net "M_D_CPU0_SB_DQ<22>")
	)
	(arc
		(start 332.948026 -287.533588)
		(mid 333.230982 -287.609731)
		(end 333.513938 -287.533588)
		(width 0.0889)
		(layer "In4.Cu")
		(net "M_D_CPU0_SB_DQ<22>")
	)
	(arc
		(start 326.934068 -287.533588)
		(mid 327.121012 -287.483333)
		(end 327.307956 -287.533588)
		(width 0.0889)
		(layer "In4.Cu")
		(net "M_D_CPU0_SB_DQ<22>")
	)
	(arc
		(start 328.248264 -287.533588)
		(mid 328.53122 -287.609731)
		(end 328.814176 -287.533588)
		(width 0.0889)
		(layer "In4.Cu")
		(net "M_D_CPU0_SB_DQ<22>")
	)
	(arc
		(start 330.702412 -287.528762)
		(mid 330.88592 -287.483268)
		(end 331.068172 -287.533588)
		(width 0.0889)
		(layer "In4.Cu")
		(net "M_D_CPU0_SB_DQ<22>")
	)
	(arc
		(start 332.574138 -287.533588)
		(mid 332.761082 -287.483333)
		(end 332.948026 -287.533588)
		(width 0.0889)
		(layer "In4.Cu")
		(net "M_D_CPU0_SB_DQ<22>")
	)
	(arc
		(start 332.008226 -287.533588)
		(mid 332.291182 -287.609731)
		(end 332.574138 -287.533588)
		(width 0.0889)
		(layer "In4.Cu")
		(net "M_D_CPU0_SB_DQ<22>")
	)
	(arc
		(start 334.453992 -287.533588)
		(mid 334.636243 -287.483238)
		(end 334.819752 -287.528762)
		(width 0.0889)
		(layer "In4.Cu")
		(net "M_D_CPU0_SB_DQ<22>")
	)
	(arc
		(start 337.648042 -287.533588)
		(mid 337.930998 -287.609731)
		(end 338.213954 -287.533588)
		(width 0.0889)
		(layer "In4.Cu")
		(net "M_D_CPU0_SB_DQ<22>")
	)
	(arc
		(start 327.32599 -287.544002)
		(mid 327.601148 -287.609732)
		(end 327.873614 -287.533588)
		(width 0.0889)
		(layer "In4.Cu")
		(net "M_D_CPU0_SB_DQ<22>")
	)
	(arc
		(start 336.708242 -287.533588)
		(mid 336.991198 -287.609731)
		(end 337.274154 -287.533588)
		(width 0.0889)
		(layer "In4.Cu")
		(net "M_D_CPU0_SB_DQ<22>")
	)
	(segment
		(start 340.747858 -287.59023)
		(end 340.281006 -287.856168)
		(width 0.10668)
		(layer "F.Cu")
		(net "M_D_CPU0_SB_DQ<21>")
	)
	(segment
		(start 289.700208 -308.492652)
		(end 289.863022 -308.655466)
		(width 0.14478)
		(layer "In4.Cu")
		(net "M_D_CPU0_SB_DQ<21>")
	)
	(segment
		(start 334.819752 -288.18332)
		(end 334.828134 -288.178494)
		(width 0.0889)
		(layer "In4.Cu")
		(net "M_D_CPU0_SB_DQ<21>")
	)
	(segment
		(start 325.611998 -288.340292)
		(end 325.722742 -288.229548)
		(width 0.0889)
		(layer "In4.Cu")
		(net "M_D_CPU0_SB_DQ<21>")
	)
	(segment
		(start 323.891148 -290.342066)
		(end 324.654418 -289.578796)
		(width 0.0889)
		(layer "In4.Cu")
		(net "M_D_CPU0_SB_DQ<21>")
	)
	(segment
		(start 285.783528 -308.65191)
		(end 285.946342 -308.489096)
		(width 0.14478)
		(layer "In4.Cu")
		(net "M_D_CPU0_SB_DQ<21>")
	)
	(segment
		(start 284.736032 -307.835046)
		(end 285.552896 -308.65191)
		(width 0.14478)
		(layer "In4.Cu")
		(net "M_D_CPU0_SB_DQ<21>")
	)
	(segment
		(start 288.750502 -308.655466)
		(end 288.981134 -308.655466)
		(width 0.14478)
		(layer "In4.Cu")
		(net "M_D_CPU0_SB_DQ<21>")
	)
	(segment
		(start 297.606212 -308.260242)
		(end 297.851322 -308.260242)
		(width 0.14478)
		(layer "In4.Cu")
		(net "M_D_CPU0_SB_DQ<21>")
	)
	(segment
		(start 324.654418 -289.026092)
		(end 325.340218 -288.340292)
		(width 0.0889)
		(layer "In4.Cu")
		(net "M_D_CPU0_SB_DQ<21>")
	)
	(segment
		(start 340.094062 -288.178494)
		(end 340.102444 -288.18332)
		(width 0.0889)
		(layer "In4.Cu")
		(net "M_D_CPU0_SB_DQ<21>")
	)
	(segment
		(start 296.584624 -308.260242)
		(end 296.980102 -307.864764)
		(width 0.14478)
		(layer "In4.Cu")
		(net "M_D_CPU0_SB_DQ<21>")
	)
	(segment
		(start 301.872142 -308.260242)
		(end 305.369722 -308.260242)
		(width 0.14478)
		(layer "In4.Cu")
		(net "M_D_CPU0_SB_DQ<21>")
	)
	(segment
		(start 330.69403 -288.178494)
		(end 330.702412 -288.18332)
		(width 0.0889)
		(layer "In4.Cu")
		(net "M_D_CPU0_SB_DQ<21>")
	)
	(segment
		(start 288.355278 -308.260242)
		(end 288.750502 -308.655466)
		(width 0.14478)
		(layer "In4.Cu")
		(net "M_D_CPU0_SB_DQ<21>")
	)
	(segment
		(start 286.339788 -307.868574)
		(end 286.502602 -308.031388)
		(width 0.14478)
		(layer "In4.Cu")
		(net "M_D_CPU0_SB_DQ<21>")
	)
	(segment
		(start 318.414146 -297.004486)
		(end 318.414146 -295.819068)
		(width 0.14478)
		(layer "In4.Cu")
		(net "M_D_CPU0_SB_DQ<21>")
	)
	(segment
		(start 287.847786 -308.260242)
		(end 288.355278 -308.260242)
		(width 0.14478)
		(layer "In4.Cu")
		(net "M_D_CPU0_SB_DQ<21>")
	)
	(segment
		(start 297.851322 -308.260242)
		(end 298.70146 -307.410104)
		(width 0.14478)
		(layer "In4.Cu")
		(net "M_D_CPU0_SB_DQ<21>")
	)
	(segment
		(start 340.413086 -288.204656)
		(end 340.435184 -288.121598)
		(width 0.0889)
		(layer "In4.Cu")
		(net "M_D_CPU0_SB_DQ<21>")
	)
	(segment
		(start 339.519768 -288.18332)
		(end 339.52815 -288.178494)
		(width 0.0889)
		(layer "In4.Cu")
		(net "M_D_CPU0_SB_DQ<21>")
	)
	(segment
		(start 286.502602 -308.031388)
		(end 286.502602 -308.492652)
		(width 0.14478)
		(layer "In4.Cu")
		(net "M_D_CPU0_SB_DQ<21>")
	)
	(segment
		(start 287.058862 -308.492652)
		(end 287.058862 -308.027578)
		(width 0.14478)
		(layer "In4.Cu")
		(net "M_D_CPU0_SB_DQ<21>")
	)
	(segment
		(start 287.221676 -307.864764)
		(end 287.452308 -307.864764)
		(width 0.14478)
		(layer "In4.Cu")
		(net "M_D_CPU0_SB_DQ<21>")
	)
	(segment
		(start 286.109156 -307.868574)
		(end 286.339788 -307.868574)
		(width 0.14478)
		(layer "In4.Cu")
		(net "M_D_CPU0_SB_DQ<21>")
	)
	(segment
		(start 338.579714 -288.18332)
		(end 338.588096 -288.178494)
		(width 0.0889)
		(layer "In4.Cu")
		(net "M_D_CPU0_SB_DQ<21>")
	)
	(segment
		(start 301.022004 -307.410104)
		(end 301.872142 -308.260242)
		(width 0.14478)
		(layer "In4.Cu")
		(net "M_D_CPU0_SB_DQ<21>")
	)
	(segment
		(start 297.210734 -307.864764)
		(end 297.606212 -308.260242)
		(width 0.14478)
		(layer "In4.Cu")
		(net "M_D_CPU0_SB_DQ<21>")
	)
	(segment
		(start 336.3341 -288.178494)
		(end 336.342482 -288.18332)
		(width 0.0889)
		(layer "In4.Cu")
		(net "M_D_CPU0_SB_DQ<21>")
	)
	(segment
		(start 340.435184 -288.121598)
		(end 340.281006 -287.856168)
		(width 0.0889)
		(layer "In4.Cu")
		(net "M_D_CPU0_SB_DQ<21>")
	)
	(segment
		(start 286.665416 -308.655466)
		(end 286.896048 -308.655466)
		(width 0.14478)
		(layer "In4.Cu")
		(net "M_D_CPU0_SB_DQ<21>")
	)
	(segment
		(start 305.369722 -308.260242)
		(end 306.21986 -307.410104)
		(width 0.14478)
		(layer "In4.Cu")
		(net "M_D_CPU0_SB_DQ<21>")
	)
	(segment
		(start 289.306762 -307.864764)
		(end 289.537394 -307.864764)
		(width 0.14478)
		(layer "In4.Cu")
		(net "M_D_CPU0_SB_DQ<21>")
	)
	(segment
		(start 288.981134 -308.655466)
		(end 289.143948 -308.492652)
		(width 0.14478)
		(layer "In4.Cu")
		(net "M_D_CPU0_SB_DQ<21>")
	)
	(segment
		(start 326.919336 -288.169858)
		(end 326.934068 -288.178494)
		(width 0.0889)
		(layer "In4.Cu")
		(net "M_D_CPU0_SB_DQ<21>")
	)
	(segment
		(start 324.654418 -289.578796)
		(end 324.654418 -289.026092)
		(width 0.0889)
		(layer "In4.Cu")
		(net "M_D_CPU0_SB_DQ<21>")
	)
	(segment
		(start 286.896048 -308.655466)
		(end 287.058862 -308.492652)
		(width 0.14478)
		(layer "In4.Cu")
		(net "M_D_CPU0_SB_DQ<21>")
	)
	(segment
		(start 335.394046 -288.178494)
		(end 335.402428 -288.18332)
		(width 0.0889)
		(layer "In4.Cu")
		(net "M_D_CPU0_SB_DQ<21>")
	)
	(segment
		(start 333.879698 -288.18332)
		(end 333.88808 -288.178494)
		(width 0.0889)
		(layer "In4.Cu")
		(net "M_D_CPU0_SB_DQ<21>")
	)
	(segment
		(start 325.722742 -288.229548)
		(end 326.179942 -288.229548)
		(width 0.0889)
		(layer "In4.Cu")
		(net "M_D_CPU0_SB_DQ<21>")
	)
	(segment
		(start 308.008528 -307.410104)
		(end 318.414146 -297.004486)
		(width 0.14478)
		(layer "In4.Cu")
		(net "M_D_CPU0_SB_DQ<21>")
	)
	(segment
		(start 289.143948 -308.027578)
		(end 289.306762 -307.864764)
		(width 0.14478)
		(layer "In4.Cu")
		(net "M_D_CPU0_SB_DQ<21>")
	)
	(segment
		(start 293.398448 -307.410104)
		(end 294.248586 -308.260242)
		(width 0.14478)
		(layer "In4.Cu")
		(net "M_D_CPU0_SB_DQ<21>")
	)
	(segment
		(start 285.552896 -308.65191)
		(end 285.783528 -308.65191)
		(width 0.14478)
		(layer "In4.Cu")
		(net "M_D_CPU0_SB_DQ<21>")
	)
	(segment
		(start 287.058862 -308.027578)
		(end 287.221676 -307.864764)
		(width 0.14478)
		(layer "In4.Cu")
		(net "M_D_CPU0_SB_DQ<21>")
	)
	(segment
		(start 285.946342 -308.489096)
		(end 285.946342 -308.031388)
		(width 0.14478)
		(layer "In4.Cu")
		(net "M_D_CPU0_SB_DQ<21>")
	)
	(segment
		(start 289.143948 -308.492652)
		(end 289.143948 -308.027578)
		(width 0.14478)
		(layer "In4.Cu")
		(net "M_D_CPU0_SB_DQ<21>")
	)
	(segment
		(start 306.21986 -307.410104)
		(end 308.008528 -307.410104)
		(width 0.14478)
		(layer "In4.Cu")
		(net "M_D_CPU0_SB_DQ<21>")
	)
	(segment
		(start 298.70146 -307.410104)
		(end 301.022004 -307.410104)
		(width 0.14478)
		(layer "In4.Cu")
		(net "M_D_CPU0_SB_DQ<21>")
	)
	(segment
		(start 289.700208 -308.027578)
		(end 289.700208 -308.492652)
		(width 0.14478)
		(layer "In4.Cu")
		(net "M_D_CPU0_SB_DQ<21>")
	)
	(segment
		(start 331.634084 -288.178494)
		(end 331.642466 -288.18332)
		(width 0.0889)
		(layer "In4.Cu")
		(net "M_D_CPU0_SB_DQ<21>")
	)
	(segment
		(start 318.414146 -295.819068)
		(end 323.891148 -290.342066)
		(width 0.14478)
		(layer "In4.Cu")
		(net "M_D_CPU0_SB_DQ<21>")
	)
	(segment
		(start 287.452308 -307.864764)
		(end 287.847786 -308.260242)
		(width 0.14478)
		(layer "In4.Cu")
		(net "M_D_CPU0_SB_DQ<21>")
	)
	(segment
		(start 290.093654 -308.655466)
		(end 291.339016 -307.410104)
		(width 0.14478)
		(layer "In4.Cu")
		(net "M_D_CPU0_SB_DQ<21>")
	)
	(segment
		(start 289.537394 -307.864764)
		(end 289.700208 -308.027578)
		(width 0.14478)
		(layer "In4.Cu")
		(net "M_D_CPU0_SB_DQ<21>")
	)
	(segment
		(start 330.119736 -288.18332)
		(end 330.128118 -288.178494)
		(width 0.0889)
		(layer "In4.Cu")
		(net "M_D_CPU0_SB_DQ<21>")
	)
	(segment
		(start 285.946342 -308.031388)
		(end 286.109156 -307.868574)
		(width 0.14478)
		(layer "In4.Cu")
		(net "M_D_CPU0_SB_DQ<21>")
	)
	(segment
		(start 291.339016 -307.410104)
		(end 293.398448 -307.410104)
		(width 0.14478)
		(layer "In4.Cu")
		(net "M_D_CPU0_SB_DQ<21>")
	)
	(segment
		(start 296.980102 -307.864764)
		(end 297.210734 -307.864764)
		(width 0.14478)
		(layer "In4.Cu")
		(net "M_D_CPU0_SB_DQ<21>")
	)
	(segment
		(start 289.863022 -308.655466)
		(end 290.093654 -308.655466)
		(width 0.14478)
		(layer "In4.Cu")
		(net "M_D_CPU0_SB_DQ<21>")
	)
	(segment
		(start 286.502602 -308.492652)
		(end 286.665416 -308.655466)
		(width 0.14478)
		(layer "In4.Cu")
		(net "M_D_CPU0_SB_DQ<21>")
	)
	(segment
		(start 327.874122 -288.178494)
		(end 327.882504 -288.18332)
		(width 0.0889)
		(layer "In4.Cu")
		(net "M_D_CPU0_SB_DQ<21>")
	)
	(segment
		(start 325.340218 -288.340292)
		(end 325.611998 -288.340292)
		(width 0.0889)
		(layer "In4.Cu")
		(net "M_D_CPU0_SB_DQ<21>")
	)
	(segment
		(start 326.934068 -288.178494)
		(end 326.94245 -288.18332)
		(width 0.0889)
		(layer "In4.Cu")
		(net "M_D_CPU0_SB_DQ<21>")
	)
	(segment
		(start 294.248586 -308.260242)
		(end 296.584624 -308.260242)
		(width 0.14478)
		(layer "In4.Cu")
		(net "M_D_CPU0_SB_DQ<21>")
	)
	(arc
		(start 337.648042 -288.178494)
		(mid 337.930998 -288.102317)
		(end 338.213954 -288.178494)
		(width 0.0889)
		(layer "In4.Cu")
		(net "M_D_CPU0_SB_DQ<21>")
	)
	(arc
		(start 326.94245 -288.18332)
		(mid 327.125958 -288.228845)
		(end 327.30821 -288.178494)
		(width 0.0889)
		(layer "In4.Cu")
		(net "M_D_CPU0_SB_DQ<21>")
	)
	(arc
		(start 332.574138 -288.178494)
		(mid 332.761082 -288.228783)
		(end 332.948026 -288.178494)
		(width 0.0889)
		(layer "In4.Cu")
		(net "M_D_CPU0_SB_DQ<21>")
	)
	(arc
		(start 338.213954 -288.178494)
		(mid 338.396205 -288.228878)
		(end 338.579714 -288.18332)
		(width 0.0889)
		(layer "In4.Cu")
		(net "M_D_CPU0_SB_DQ<21>")
	)
	(arc
		(start 339.52815 -288.178494)
		(mid 339.811106 -288.102317)
		(end 340.094062 -288.178494)
		(width 0.0889)
		(layer "In4.Cu")
		(net "M_D_CPU0_SB_DQ<21>")
	)
	(arc
		(start 331.642466 -288.18332)
		(mid 331.825974 -288.228845)
		(end 332.008226 -288.178494)
		(width 0.0889)
		(layer "In4.Cu")
		(net "M_D_CPU0_SB_DQ<21>")
	)
	(arc
		(start 334.453992 -288.178494)
		(mid 334.636243 -288.228878)
		(end 334.819752 -288.18332)
		(width 0.0889)
		(layer "In4.Cu")
		(net "M_D_CPU0_SB_DQ<21>")
	)
	(arc
		(start 331.068172 -288.178494)
		(mid 331.351128 -288.102317)
		(end 331.634084 -288.178494)
		(width 0.0889)
		(layer "In4.Cu")
		(net "M_D_CPU0_SB_DQ<21>")
	)
	(arc
		(start 332.008226 -288.178494)
		(mid 332.291182 -288.102317)
		(end 332.574138 -288.178494)
		(width 0.0889)
		(layer "In4.Cu")
		(net "M_D_CPU0_SB_DQ<21>")
	)
	(arc
		(start 338.588096 -288.178494)
		(mid 338.871052 -288.102317)
		(end 339.154008 -288.178494)
		(width 0.0889)
		(layer "In4.Cu")
		(net "M_D_CPU0_SB_DQ<21>")
	)
	(arc
		(start 327.882504 -288.18332)
		(mid 328.066012 -288.228845)
		(end 328.248264 -288.178494)
		(width 0.0889)
		(layer "In4.Cu")
		(net "M_D_CPU0_SB_DQ<21>")
	)
	(arc
		(start 339.154008 -288.178494)
		(mid 339.336259 -288.228878)
		(end 339.519768 -288.18332)
		(width 0.0889)
		(layer "In4.Cu")
		(net "M_D_CPU0_SB_DQ<21>")
	)
	(arc
		(start 336.342482 -288.18332)
		(mid 336.52599 -288.228845)
		(end 336.708242 -288.178494)
		(width 0.0889)
		(layer "In4.Cu")
		(net "M_D_CPU0_SB_DQ<21>")
	)
	(arc
		(start 329.753976 -288.178494)
		(mid 329.936227 -288.228878)
		(end 330.119736 -288.18332)
		(width 0.0889)
		(layer "In4.Cu")
		(net "M_D_CPU0_SB_DQ<21>")
	)
	(arc
		(start 335.768188 -288.178494)
		(mid 336.051144 -288.102317)
		(end 336.3341 -288.178494)
		(width 0.0889)
		(layer "In4.Cu")
		(net "M_D_CPU0_SB_DQ<21>")
	)
	(arc
		(start 337.274154 -288.178494)
		(mid 337.461098 -288.228783)
		(end 337.648042 -288.178494)
		(width 0.0889)
		(layer "In4.Cu")
		(net "M_D_CPU0_SB_DQ<21>")
	)
	(arc
		(start 333.88808 -288.178494)
		(mid 334.171036 -288.102317)
		(end 334.453992 -288.178494)
		(width 0.0889)
		(layer "In4.Cu")
		(net "M_D_CPU0_SB_DQ<21>")
	)
	(arc
		(start 328.248264 -288.178494)
		(mid 328.53122 -288.102317)
		(end 328.814176 -288.178494)
		(width 0.0889)
		(layer "In4.Cu")
		(net "M_D_CPU0_SB_DQ<21>")
	)
	(arc
		(start 327.30821 -288.178494)
		(mid 327.591166 -288.102317)
		(end 327.874122 -288.178494)
		(width 0.0889)
		(layer "In4.Cu")
		(net "M_D_CPU0_SB_DQ<21>")
	)
	(arc
		(start 336.708242 -288.178494)
		(mid 336.991198 -288.102317)
		(end 337.274154 -288.178494)
		(width 0.0889)
		(layer "In4.Cu")
		(net "M_D_CPU0_SB_DQ<21>")
	)
	(arc
		(start 329.188064 -288.178494)
		(mid 329.47102 -288.102317)
		(end 329.753976 -288.178494)
		(width 0.0889)
		(layer "In4.Cu")
		(net "M_D_CPU0_SB_DQ<21>")
	)
	(arc
		(start 335.402428 -288.18332)
		(mid 335.585936 -288.228845)
		(end 335.768188 -288.178494)
		(width 0.0889)
		(layer "In4.Cu")
		(net "M_D_CPU0_SB_DQ<21>")
	)
	(arc
		(start 330.702412 -288.18332)
		(mid 330.88592 -288.228845)
		(end 331.068172 -288.178494)
		(width 0.0889)
		(layer "In4.Cu")
		(net "M_D_CPU0_SB_DQ<21>")
	)
	(arc
		(start 330.128118 -288.178494)
		(mid 330.411074 -288.102317)
		(end 330.69403 -288.178494)
		(width 0.0889)
		(layer "In4.Cu")
		(net "M_D_CPU0_SB_DQ<21>")
	)
	(arc
		(start 328.814176 -288.178494)
		(mid 329.00112 -288.228783)
		(end 329.188064 -288.178494)
		(width 0.0889)
		(layer "In4.Cu")
		(net "M_D_CPU0_SB_DQ<21>")
	)
	(arc
		(start 326.367648 -288.178494)
		(mid 326.642354 -288.10213)
		(end 326.919336 -288.169858)
		(width 0.0889)
		(layer "In4.Cu")
		(net "M_D_CPU0_SB_DQ<21>")
	)
	(arc
		(start 332.948026 -288.178494)
		(mid 333.230982 -288.102317)
		(end 333.513938 -288.178494)
		(width 0.0889)
		(layer "In4.Cu")
		(net "M_D_CPU0_SB_DQ<21>")
	)
	(arc
		(start 334.828134 -288.178494)
		(mid 335.11109 -288.102317)
		(end 335.394046 -288.178494)
		(width 0.0889)
		(layer "In4.Cu")
		(net "M_D_CPU0_SB_DQ<21>")
	)
	(arc
		(start 326.179942 -288.229548)
		(mid 326.277173 -288.216451)
		(end 326.367648 -288.178494)
		(width 0.0889)
		(layer "In4.Cu")
		(net "M_D_CPU0_SB_DQ<21>")
	)
	(arc
		(start 340.102444 -288.18332)
		(mid 340.255432 -288.228)
		(end 340.413086 -288.204656)
		(width 0.0889)
		(layer "In4.Cu")
		(net "M_D_CPU0_SB_DQ<21>")
	)
	(arc
		(start 333.513938 -288.178494)
		(mid 333.696189 -288.228878)
		(end 333.879698 -288.18332)
		(width 0.0889)
		(layer "In4.Cu")
		(net "M_D_CPU0_SB_DQ<21>")
	)
	(segment
		(start 339.337904 -286.780224)
		(end 338.871052 -287.045908)
		(width 0.10668)
		(layer "F.Cu")
		(net "M_D_CPU0_SB_DQ<20>")
	)
	(segment
		(start 305.576478 -306.56022)
		(end 306.031392 -306.105306)
		(width 0.14478)
		(layer "In4.Cu")
		(net "M_D_CPU0_SB_DQ<20>")
	)
	(segment
		(start 303.851564 -306.811426)
		(end 303.995582 -306.955444)
		(width 0.14478)
		(layer "In4.Cu")
		(net "M_D_CPU0_SB_DQ<20>")
	)
	(segment
		(start 338.684108 -287.368488)
		(end 338.69249 -287.373314)
		(width 0.0889)
		(layer "In4.Cu")
		(net "M_D_CPU0_SB_DQ<20>")
	)
	(segment
		(start 337.16976 -287.373314)
		(end 337.178142 -287.368488)
		(width 0.0889)
		(layer "In4.Cu")
		(net "M_D_CPU0_SB_DQ<20>")
	)
	(segment
		(start 307.729382 -306.105306)
		(end 308.041294 -306.105306)
		(width 0.14478)
		(layer "In4.Cu")
		(net "M_D_CPU0_SB_DQ<20>")
	)
	(segment
		(start 302.595026 -306.25796)
		(end 302.739044 -306.401978)
		(width 0.14478)
		(layer "In4.Cu")
		(net "M_D_CPU0_SB_DQ<20>")
	)
	(segment
		(start 307.016404 -305.943762)
		(end 307.016404 -305.357276)
		(width 0.14478)
		(layer "In4.Cu")
		(net "M_D_CPU0_SB_DQ<20>")
	)
	(segment
		(start 339.002878 -287.39465)
		(end 339.02523 -287.311338)
		(width 0.0889)
		(layer "In4.Cu")
		(net "M_D_CPU0_SB_DQ<20>")
	)
	(segment
		(start 307.567838 -305.943762)
		(end 307.729382 -306.105306)
		(width 0.14478)
		(layer "In4.Cu")
		(net "M_D_CPU0_SB_DQ<20>")
	)
	(segment
		(start 303.295304 -306.401978)
		(end 303.439322 -306.25796)
		(width 0.14478)
		(layer "In4.Cu")
		(net "M_D_CPU0_SB_DQ<20>")
	)
	(segment
		(start 333.984092 -287.368488)
		(end 333.992474 -287.373314)
		(width 0.0889)
		(layer "In4.Cu")
		(net "M_D_CPU0_SB_DQ<20>")
	)
	(segment
		(start 317.514986 -296.631614)
		(end 317.514986 -295.431972)
		(width 0.14478)
		(layer "In4.Cu")
		(net "M_D_CPU0_SB_DQ<20>")
	)
	(segment
		(start 327.388728 -287.359852)
		(end 327.40346 -287.368488)
		(width 0.0889)
		(layer "In4.Cu")
		(net "M_D_CPU0_SB_DQ<20>")
	)
	(segment
		(start 302.182784 -306.401978)
		(end 302.326802 -306.25796)
		(width 0.14478)
		(layer "In4.Cu")
		(net "M_D_CPU0_SB_DQ<20>")
	)
	(segment
		(start 339.02523 -287.311338)
		(end 338.871052 -287.045908)
		(width 0.0889)
		(layer "In4.Cu")
		(net "M_D_CPU0_SB_DQ<20>")
	)
	(segment
		(start 306.031392 -306.105306)
		(end 306.85486 -306.105306)
		(width 0.14478)
		(layer "In4.Cu")
		(net "M_D_CPU0_SB_DQ<20>")
	)
	(segment
		(start 323.926454 -289.020504)
		(end 324.987666 -287.959292)
		(width 0.0889)
		(layer "In4.Cu")
		(net "M_D_CPU0_SB_DQ<20>")
	)
	(segment
		(start 284.736032 -306.135024)
		(end 285.551626 -306.950618)
		(width 0.14478)
		(layer "In4.Cu")
		(net "M_D_CPU0_SB_DQ<20>")
	)
	(segment
		(start 289.667188 -306.557934)
		(end 290.06292 -306.953666)
		(width 0.14478)
		(layer "In4.Cu")
		(net "M_D_CPU0_SB_DQ<20>")
	)
	(segment
		(start 286.03067 -306.553616)
		(end 286.192214 -306.392072)
		(width 0.14478)
		(layer "In4.Cu")
		(net "M_D_CPU0_SB_DQ<20>")
	)
	(segment
		(start 329.284076 -287.368488)
		(end 329.292458 -287.373314)
		(width 0.0889)
		(layer "In4.Cu")
		(net "M_D_CPU0_SB_DQ<20>")
	)
	(segment
		(start 301.82058 -306.891436)
		(end 302.032924 -306.891436)
		(width 0.14478)
		(layer "In4.Cu")
		(net "M_D_CPU0_SB_DQ<20>")
	)
	(segment
		(start 303.439322 -306.25796)
		(end 303.707546 -306.25796)
		(width 0.14478)
		(layer "In4.Cu")
		(net "M_D_CPU0_SB_DQ<20>")
	)
	(segment
		(start 325.730362 -287.419288)
		(end 326.650858 -287.419288)
		(width 0.0889)
		(layer "In4.Cu")
		(net "M_D_CPU0_SB_DQ<20>")
	)
	(segment
		(start 307.177948 -305.195732)
		(end 307.406294 -305.195732)
		(width 0.14478)
		(layer "In4.Cu")
		(net "M_D_CPU0_SB_DQ<20>")
	)
	(segment
		(start 328.709782 -287.373314)
		(end 328.718164 -287.368488)
		(width 0.0889)
		(layer "In4.Cu")
		(net "M_D_CPU0_SB_DQ<20>")
	)
	(segment
		(start 293.887906 -306.569872)
		(end 296.078656 -306.569872)
		(width 0.14478)
		(layer "In4.Cu")
		(net "M_D_CPU0_SB_DQ<20>")
	)
	(segment
		(start 296.078656 -306.569872)
		(end 296.385996 -306.877212)
		(width 0.14478)
		(layer "In4.Cu")
		(net "M_D_CPU0_SB_DQ<20>")
	)
	(segment
		(start 302.883062 -306.955444)
		(end 303.151286 -306.955444)
		(width 0.14478)
		(layer "In4.Cu")
		(net "M_D_CPU0_SB_DQ<20>")
	)
	(segment
		(start 302.182784 -306.741576)
		(end 302.182784 -306.401978)
		(width 0.14478)
		(layer "In4.Cu")
		(net "M_D_CPU0_SB_DQ<20>")
	)
	(segment
		(start 302.326802 -306.25796)
		(end 302.595026 -306.25796)
		(width 0.14478)
		(layer "In4.Cu")
		(net "M_D_CPU0_SB_DQ<20>")
	)
	(segment
		(start 286.743648 -306.950618)
		(end 287.395158 -306.950618)
		(width 0.14478)
		(layer "In4.Cu")
		(net "M_D_CPU0_SB_DQ<20>")
	)
	(segment
		(start 302.739044 -306.811426)
		(end 302.883062 -306.955444)
		(width 0.14478)
		(layer "In4.Cu")
		(net "M_D_CPU0_SB_DQ<20>")
	)
	(segment
		(start 287.775904 -306.569872)
		(end 288.438082 -306.569872)
		(width 0.14478)
		(layer "In4.Cu")
		(net "M_D_CPU0_SB_DQ<20>")
	)
	(segment
		(start 290.293552 -306.953666)
		(end 291.527484 -305.719734)
		(width 0.14478)
		(layer "In4.Cu")
		(net "M_D_CPU0_SB_DQ<20>")
	)
	(segment
		(start 289.436556 -306.557934)
		(end 289.667188 -306.557934)
		(width 0.14478)
		(layer "In4.Cu")
		(net "M_D_CPU0_SB_DQ<20>")
	)
	(segment
		(start 331.52969 -287.373314)
		(end 331.538072 -287.368488)
		(width 0.0889)
		(layer "In4.Cu")
		(net "M_D_CPU0_SB_DQ<20>")
	)
	(segment
		(start 289.046666 -306.947824)
		(end 289.436556 -306.557934)
		(width 0.14478)
		(layer "In4.Cu")
		(net "M_D_CPU0_SB_DQ<20>")
	)
	(segment
		(start 293.037768 -305.719734)
		(end 293.887906 -306.569872)
		(width 0.14478)
		(layer "In4.Cu")
		(net "M_D_CPU0_SB_DQ<20>")
	)
	(segment
		(start 296.942256 -306.563522)
		(end 298.054776 -306.563522)
		(width 0.14478)
		(layer "In4.Cu")
		(net "M_D_CPU0_SB_DQ<20>")
	)
	(segment
		(start 286.582104 -306.789074)
		(end 286.743648 -306.950618)
		(width 0.14478)
		(layer "In4.Cu")
		(net "M_D_CPU0_SB_DQ<20>")
	)
	(segment
		(start 325.190358 -287.959292)
		(end 325.730362 -287.419288)
		(width 0.0889)
		(layer "In4.Cu")
		(net "M_D_CPU0_SB_DQ<20>")
	)
	(segment
		(start 303.995582 -306.955444)
		(end 304.263806 -306.955444)
		(width 0.14478)
		(layer "In4.Cu")
		(net "M_D_CPU0_SB_DQ<20>")
	)
	(segment
		(start 298.898564 -305.719734)
		(end 300.648878 -305.719734)
		(width 0.14478)
		(layer "In4.Cu")
		(net "M_D_CPU0_SB_DQ<20>")
	)
	(segment
		(start 328.333608 -287.362392)
		(end 328.344022 -287.368488)
		(width 0.0889)
		(layer "In4.Cu")
		(net "M_D_CPU0_SB_DQ<20>")
	)
	(segment
		(start 303.151286 -306.955444)
		(end 303.295304 -306.811426)
		(width 0.14478)
		(layer "In4.Cu")
		(net "M_D_CPU0_SB_DQ<20>")
	)
	(segment
		(start 286.42056 -306.392072)
		(end 286.582104 -306.553616)
		(width 0.14478)
		(layer "In4.Cu")
		(net "M_D_CPU0_SB_DQ<20>")
	)
	(segment
		(start 307.016404 -305.357276)
		(end 307.177948 -305.195732)
		(width 0.14478)
		(layer "In4.Cu")
		(net "M_D_CPU0_SB_DQ<20>")
	)
	(segment
		(start 307.567838 -305.357276)
		(end 307.567838 -305.943762)
		(width 0.14478)
		(layer "In4.Cu")
		(net "M_D_CPU0_SB_DQ<20>")
	)
	(segment
		(start 285.551626 -306.950618)
		(end 285.869126 -306.950618)
		(width 0.14478)
		(layer "In4.Cu")
		(net "M_D_CPU0_SB_DQ<20>")
	)
	(segment
		(start 317.514986 -295.431972)
		(end 323.926454 -289.020504)
		(width 0.14478)
		(layer "In4.Cu")
		(net "M_D_CPU0_SB_DQ<20>")
	)
	(segment
		(start 285.869126 -306.950618)
		(end 286.03067 -306.789074)
		(width 0.14478)
		(layer "In4.Cu")
		(net "M_D_CPU0_SB_DQ<20>")
	)
	(segment
		(start 298.054776 -306.563522)
		(end 298.898564 -305.719734)
		(width 0.14478)
		(layer "In4.Cu")
		(net "M_D_CPU0_SB_DQ<20>")
	)
	(segment
		(start 290.06292 -306.953666)
		(end 290.293552 -306.953666)
		(width 0.14478)
		(layer "In4.Cu")
		(net "M_D_CPU0_SB_DQ<20>")
	)
	(segment
		(start 307.406294 -305.195732)
		(end 307.567838 -305.357276)
		(width 0.14478)
		(layer "In4.Cu")
		(net "M_D_CPU0_SB_DQ<20>")
	)
	(segment
		(start 304.65903 -306.56022)
		(end 305.576478 -306.56022)
		(width 0.14478)
		(layer "In4.Cu")
		(net "M_D_CPU0_SB_DQ<20>")
	)
	(segment
		(start 333.044038 -287.368488)
		(end 333.05242 -287.373314)
		(width 0.0889)
		(layer "In4.Cu")
		(net "M_D_CPU0_SB_DQ<20>")
	)
	(segment
		(start 303.707546 -306.25796)
		(end 303.851564 -306.401978)
		(width 0.14478)
		(layer "In4.Cu")
		(net "M_D_CPU0_SB_DQ<20>")
	)
	(segment
		(start 288.816034 -306.947824)
		(end 289.046666 -306.947824)
		(width 0.14478)
		(layer "In4.Cu")
		(net "M_D_CPU0_SB_DQ<20>")
	)
	(segment
		(start 327.40346 -287.368488)
		(end 327.415144 -287.375346)
		(width 0.0889)
		(layer "In4.Cu")
		(net "M_D_CPU0_SB_DQ<20>")
	)
	(segment
		(start 332.469744 -287.373314)
		(end 332.478126 -287.368488)
		(width 0.0889)
		(layer "In4.Cu")
		(net "M_D_CPU0_SB_DQ<20>")
	)
	(segment
		(start 286.192214 -306.392072)
		(end 286.42056 -306.392072)
		(width 0.14478)
		(layer "In4.Cu")
		(net "M_D_CPU0_SB_DQ<20>")
	)
	(segment
		(start 286.582104 -306.553616)
		(end 286.582104 -306.789074)
		(width 0.14478)
		(layer "In4.Cu")
		(net "M_D_CPU0_SB_DQ<20>")
	)
	(segment
		(start 336.229706 -287.373314)
		(end 336.238088 -287.368488)
		(width 0.0889)
		(layer "In4.Cu")
		(net "M_D_CPU0_SB_DQ<20>")
	)
	(segment
		(start 286.03067 -306.789074)
		(end 286.03067 -306.553616)
		(width 0.14478)
		(layer "In4.Cu")
		(net "M_D_CPU0_SB_DQ<20>")
	)
	(segment
		(start 300.648878 -305.719734)
		(end 301.82058 -306.891436)
		(width 0.14478)
		(layer "In4.Cu")
		(net "M_D_CPU0_SB_DQ<20>")
	)
	(segment
		(start 306.85486 -306.105306)
		(end 307.016404 -305.943762)
		(width 0.14478)
		(layer "In4.Cu")
		(net "M_D_CPU0_SB_DQ<20>")
	)
	(segment
		(start 302.739044 -306.401978)
		(end 302.739044 -306.811426)
		(width 0.14478)
		(layer "In4.Cu")
		(net "M_D_CPU0_SB_DQ<20>")
	)
	(segment
		(start 296.385996 -306.877212)
		(end 296.628566 -306.877212)
		(width 0.14478)
		(layer "In4.Cu")
		(net "M_D_CPU0_SB_DQ<20>")
	)
	(segment
		(start 288.438082 -306.569872)
		(end 288.816034 -306.947824)
		(width 0.14478)
		(layer "In4.Cu")
		(net "M_D_CPU0_SB_DQ<20>")
	)
	(segment
		(start 308.041294 -306.105306)
		(end 317.514986 -296.631614)
		(width 0.14478)
		(layer "In4.Cu")
		(net "M_D_CPU0_SB_DQ<20>")
	)
	(segment
		(start 291.527484 -305.719734)
		(end 293.037768 -305.719734)
		(width 0.14478)
		(layer "In4.Cu")
		(net "M_D_CPU0_SB_DQ<20>")
	)
	(segment
		(start 337.744054 -287.368488)
		(end 337.752436 -287.373314)
		(width 0.0889)
		(layer "In4.Cu")
		(net "M_D_CPU0_SB_DQ<20>")
	)
	(segment
		(start 304.263806 -306.955444)
		(end 304.65903 -306.56022)
		(width 0.14478)
		(layer "In4.Cu")
		(net "M_D_CPU0_SB_DQ<20>")
	)
	(segment
		(start 303.851564 -306.401978)
		(end 303.851564 -306.811426)
		(width 0.14478)
		(layer "In4.Cu")
		(net "M_D_CPU0_SB_DQ<20>")
	)
	(segment
		(start 287.395158 -306.950618)
		(end 287.775904 -306.569872)
		(width 0.14478)
		(layer "In4.Cu")
		(net "M_D_CPU0_SB_DQ<20>")
	)
	(segment
		(start 324.987666 -287.959292)
		(end 325.190358 -287.959292)
		(width 0.0889)
		(layer "In4.Cu")
		(net "M_D_CPU0_SB_DQ<20>")
	)
	(segment
		(start 302.032924 -306.891436)
		(end 302.182784 -306.741576)
		(width 0.14478)
		(layer "In4.Cu")
		(net "M_D_CPU0_SB_DQ<20>")
	)
	(segment
		(start 296.628566 -306.877212)
		(end 296.942256 -306.563522)
		(width 0.14478)
		(layer "In4.Cu")
		(net "M_D_CPU0_SB_DQ<20>")
	)
	(segment
		(start 303.295304 -306.811426)
		(end 303.295304 -306.401978)
		(width 0.14478)
		(layer "In4.Cu")
		(net "M_D_CPU0_SB_DQ<20>")
	)
	(arc
		(start 330.598018 -287.368488)
		(mid 330.880974 -287.292345)
		(end 331.16393 -287.368488)
		(width 0.0889)
		(layer "In4.Cu")
		(net "M_D_CPU0_SB_DQ<20>")
	)
	(arc
		(start 335.298034 -287.368488)
		(mid 335.58099 -287.292345)
		(end 335.863946 -287.368488)
		(width 0.0889)
		(layer "In4.Cu")
		(net "M_D_CPU0_SB_DQ<20>")
	)
	(arc
		(start 332.103984 -287.368488)
		(mid 332.286235 -287.418838)
		(end 332.469744 -287.373314)
		(width 0.0889)
		(layer "In4.Cu")
		(net "M_D_CPU0_SB_DQ<20>")
	)
	(arc
		(start 329.658218 -287.368488)
		(mid 329.941174 -287.292345)
		(end 330.22413 -287.368488)
		(width 0.0889)
		(layer "In4.Cu")
		(net "M_D_CPU0_SB_DQ<20>")
	)
	(arc
		(start 333.41818 -287.368488)
		(mid 333.701136 -287.292345)
		(end 333.984092 -287.368488)
		(width 0.0889)
		(layer "In4.Cu")
		(net "M_D_CPU0_SB_DQ<20>")
	)
	(arc
		(start 338.69249 -287.373314)
		(mid 338.84536 -287.417955)
		(end 339.002878 -287.39465)
		(width 0.0889)
		(layer "In4.Cu")
		(net "M_D_CPU0_SB_DQ<20>")
	)
	(arc
		(start 331.16393 -287.368488)
		(mid 331.346181 -287.418838)
		(end 331.52969 -287.373314)
		(width 0.0889)
		(layer "In4.Cu")
		(net "M_D_CPU0_SB_DQ<20>")
	)
	(arc
		(start 336.238088 -287.368488)
		(mid 336.521044 -287.292345)
		(end 336.804 -287.368488)
		(width 0.0889)
		(layer "In4.Cu")
		(net "M_D_CPU0_SB_DQ<20>")
	)
	(arc
		(start 327.777856 -287.368488)
		(mid 328.054923 -287.292251)
		(end 328.333608 -287.362392)
		(width 0.0889)
		(layer "In4.Cu")
		(net "M_D_CPU0_SB_DQ<20>")
	)
	(arc
		(start 328.718164 -287.368488)
		(mid 329.00112 -287.292345)
		(end 329.284076 -287.368488)
		(width 0.0889)
		(layer "In4.Cu")
		(net "M_D_CPU0_SB_DQ<20>")
	)
	(arc
		(start 338.118196 -287.368488)
		(mid 338.401152 -287.292345)
		(end 338.684108 -287.368488)
		(width 0.0889)
		(layer "In4.Cu")
		(net "M_D_CPU0_SB_DQ<20>")
	)
	(arc
		(start 331.538072 -287.368488)
		(mid 331.821028 -287.292345)
		(end 332.103984 -287.368488)
		(width 0.0889)
		(layer "In4.Cu")
		(net "M_D_CPU0_SB_DQ<20>")
	)
	(arc
		(start 337.178142 -287.368488)
		(mid 337.461098 -287.292345)
		(end 337.744054 -287.368488)
		(width 0.0889)
		(layer "In4.Cu")
		(net "M_D_CPU0_SB_DQ<20>")
	)
	(arc
		(start 328.344022 -287.368488)
		(mid 328.526273 -287.418838)
		(end 328.709782 -287.373314)
		(width 0.0889)
		(layer "In4.Cu")
		(net "M_D_CPU0_SB_DQ<20>")
	)
	(arc
		(start 330.22413 -287.368488)
		(mid 330.411074 -287.418743)
		(end 330.598018 -287.368488)
		(width 0.0889)
		(layer "In4.Cu")
		(net "M_D_CPU0_SB_DQ<20>")
	)
	(arc
		(start 334.924146 -287.368488)
		(mid 335.11109 -287.418743)
		(end 335.298034 -287.368488)
		(width 0.0889)
		(layer "In4.Cu")
		(net "M_D_CPU0_SB_DQ<20>")
	)
	(arc
		(start 326.650858 -287.419288)
		(mid 326.747816 -287.406265)
		(end 326.838056 -287.368488)
		(width 0.0889)
		(layer "In4.Cu")
		(net "M_D_CPU0_SB_DQ<20>")
	)
	(arc
		(start 332.478126 -287.368488)
		(mid 332.761082 -287.292345)
		(end 333.044038 -287.368488)
		(width 0.0889)
		(layer "In4.Cu")
		(net "M_D_CPU0_SB_DQ<20>")
	)
	(arc
		(start 336.804 -287.368488)
		(mid 336.986251 -287.418838)
		(end 337.16976 -287.373314)
		(width 0.0889)
		(layer "In4.Cu")
		(net "M_D_CPU0_SB_DQ<20>")
	)
	(arc
		(start 329.292458 -287.373314)
		(mid 329.475966 -287.418808)
		(end 329.658218 -287.368488)
		(width 0.0889)
		(layer "In4.Cu")
		(net "M_D_CPU0_SB_DQ<20>")
	)
	(arc
		(start 334.358234 -287.368488)
		(mid 334.64119 -287.292345)
		(end 334.924146 -287.368488)
		(width 0.0889)
		(layer "In4.Cu")
		(net "M_D_CPU0_SB_DQ<20>")
	)
	(arc
		(start 326.838056 -287.368488)
		(mid 327.112254 -287.292413)
		(end 327.388728 -287.359852)
		(width 0.0889)
		(layer "In4.Cu")
		(net "M_D_CPU0_SB_DQ<20>")
	)
	(arc
		(start 337.752436 -287.373314)
		(mid 337.935944 -287.418808)
		(end 338.118196 -287.368488)
		(width 0.0889)
		(layer "In4.Cu")
		(net "M_D_CPU0_SB_DQ<20>")
	)
	(arc
		(start 327.415144 -287.375346)
		(mid 327.597399 -287.418999)
		(end 327.777856 -287.368488)
		(width 0.0889)
		(layer "In4.Cu")
		(net "M_D_CPU0_SB_DQ<20>")
	)
	(arc
		(start 333.992474 -287.373314)
		(mid 334.175982 -287.418808)
		(end 334.358234 -287.368488)
		(width 0.0889)
		(layer "In4.Cu")
		(net "M_D_CPU0_SB_DQ<20>")
	)
	(arc
		(start 335.863946 -287.368488)
		(mid 336.046197 -287.418838)
		(end 336.229706 -287.373314)
		(width 0.0889)
		(layer "In4.Cu")
		(net "M_D_CPU0_SB_DQ<20>")
	)
	(arc
		(start 333.05242 -287.373314)
		(mid 333.235928 -287.418808)
		(end 333.41818 -287.368488)
		(width 0.0889)
		(layer "In4.Cu")
		(net "M_D_CPU0_SB_DQ<20>")
	)
	(segment
		(start 340.747858 -274.630134)
		(end 340.281006 -274.896072)
		(width 0.10668)
		(layer "F.Cu")
		(net "M_D_CPU0_SB_DQ<1>")
	)
	(segment
		(start 285.526226 -283.975302)
		(end 285.756858 -283.975302)
		(width 0.14478)
		(layer "In4.Cu")
		(net "M_D_CPU0_SB_DQ<1>")
	)
	(segment
		(start 326.419718 -275.142198)
		(end 327.59015 -275.142198)
		(width 0.0889)
		(layer "In4.Cu")
		(net "M_D_CPU0_SB_DQ<1>")
	)
	(segment
		(start 339.519768 -275.223478)
		(end 339.52815 -275.218652)
		(width 0.0889)
		(layer "In4.Cu")
		(net "M_D_CPU0_SB_DQ<1>")
	)
	(segment
		(start 333.879698 -275.223478)
		(end 333.88808 -275.218652)
		(width 0.0889)
		(layer "In4.Cu")
		(net "M_D_CPU0_SB_DQ<1>")
	)
	(segment
		(start 325.325232 -274.047712)
		(end 326.419718 -275.142198)
		(width 0.0889)
		(layer "In4.Cu")
		(net "M_D_CPU0_SB_DQ<1>")
	)
	(segment
		(start 288.969704 -283.61005)
		(end 289.348164 -283.23159)
		(width 0.14478)
		(layer "In4.Cu")
		(net "M_D_CPU0_SB_DQ<1>")
	)
	(segment
		(start 286.082486 -283.218382)
		(end 286.313118 -283.218382)
		(width 0.14478)
		(layer "In4.Cu")
		(net "M_D_CPU0_SB_DQ<1>")
	)
	(segment
		(start 302.023018 -283.61005)
		(end 302.184562 -283.448506)
		(width 0.14478)
		(layer "In4.Cu")
		(net "M_D_CPU0_SB_DQ<1>")
	)
	(segment
		(start 316.16142 -274.1295)
		(end 324.141084 -274.1295)
		(width 0.14478)
		(layer "In4.Cu")
		(net "M_D_CPU0_SB_DQ<1>")
	)
	(segment
		(start 302.735996 -283.152596)
		(end 302.735996 -283.448506)
		(width 0.14478)
		(layer "In4.Cu")
		(net "M_D_CPU0_SB_DQ<1>")
	)
	(segment
		(start 336.3341 -275.218652)
		(end 336.342482 -275.223478)
		(width 0.0889)
		(layer "In4.Cu")
		(net "M_D_CPU0_SB_DQ<1>")
	)
	(segment
		(start 304.924714 -283.61005)
		(end 305.774852 -282.759912)
		(width 0.14478)
		(layer "In4.Cu")
		(net "M_D_CPU0_SB_DQ<1>")
	)
	(segment
		(start 286.475932 -283.381196)
		(end 286.475932 -283.812488)
		(width 0.14478)
		(layer "In4.Cu")
		(net "M_D_CPU0_SB_DQ<1>")
	)
	(segment
		(start 285.756858 -283.975302)
		(end 285.919672 -283.812488)
		(width 0.14478)
		(layer "In4.Cu")
		(net "M_D_CPU0_SB_DQ<1>")
	)
	(segment
		(start 302.184562 -283.152596)
		(end 302.346106 -282.991052)
		(width 0.14478)
		(layer "In4.Cu")
		(net "M_D_CPU0_SB_DQ<1>")
	)
	(segment
		(start 335.394046 -275.218652)
		(end 335.402428 -275.223478)
		(width 0.0889)
		(layer "In4.Cu")
		(net "M_D_CPU0_SB_DQ<1>")
	)
	(segment
		(start 334.819752 -275.223478)
		(end 334.828134 -275.218652)
		(width 0.0889)
		(layer "In4.Cu")
		(net "M_D_CPU0_SB_DQ<1>")
	)
	(segment
		(start 340.094062 -275.218652)
		(end 340.102444 -275.223478)
		(width 0.0889)
		(layer "In4.Cu")
		(net "M_D_CPU0_SB_DQ<1>")
	)
	(segment
		(start 324.33133 -274.1295)
		(end 324.413118 -274.047712)
		(width 0.0889)
		(layer "In4.Cu")
		(net "M_D_CPU0_SB_DQ<1>")
	)
	(segment
		(start 306.16144 -282.759912)
		(end 306.475638 -283.07411)
		(width 0.14478)
		(layer "In4.Cu")
		(net "M_D_CPU0_SB_DQ<1>")
	)
	(segment
		(start 285.919672 -283.381196)
		(end 286.082486 -283.218382)
		(width 0.14478)
		(layer "In4.Cu")
		(net "M_D_CPU0_SB_DQ<1>")
	)
	(segment
		(start 330.69403 -275.218652)
		(end 330.702412 -275.223478)
		(width 0.0889)
		(layer "In4.Cu")
		(net "M_D_CPU0_SB_DQ<1>")
	)
	(segment
		(start 294.363394 -283.61005)
		(end 297.007026 -283.61005)
		(width 0.14478)
		(layer "In4.Cu")
		(net "M_D_CPU0_SB_DQ<1>")
	)
	(segment
		(start 297.857164 -282.759912)
		(end 301.006256 -282.759912)
		(width 0.14478)
		(layer "In4.Cu")
		(net "M_D_CPU0_SB_DQ<1>")
	)
	(segment
		(start 302.89754 -283.61005)
		(end 303.884076 -283.61005)
		(width 0.14478)
		(layer "In4.Cu")
		(net "M_D_CPU0_SB_DQ<1>")
	)
	(segment
		(start 330.119736 -275.223478)
		(end 330.128118 -275.218652)
		(width 0.0889)
		(layer "In4.Cu")
		(net "M_D_CPU0_SB_DQ<1>")
	)
	(segment
		(start 304.43551 -282.823412)
		(end 304.597054 -282.984956)
		(width 0.14478)
		(layer "In4.Cu")
		(net "M_D_CPU0_SB_DQ<1>")
	)
	(segment
		(start 284.736032 -283.185108)
		(end 285.526226 -283.975302)
		(width 0.14478)
		(layer "In4.Cu")
		(net "M_D_CPU0_SB_DQ<1>")
	)
	(segment
		(start 328.239882 -275.223478)
		(end 328.248264 -275.218652)
		(width 0.0889)
		(layer "In4.Cu")
		(net "M_D_CPU0_SB_DQ<1>")
	)
	(segment
		(start 286.475932 -283.812488)
		(end 286.638746 -283.975302)
		(width 0.14478)
		(layer "In4.Cu")
		(net "M_D_CPU0_SB_DQ<1>")
	)
	(segment
		(start 290.321746 -283.23159)
		(end 290.793424 -282.759912)
		(width 0.14478)
		(layer "In4.Cu")
		(net "M_D_CPU0_SB_DQ<1>")
	)
	(segment
		(start 286.638746 -283.975302)
		(end 286.869378 -283.975302)
		(width 0.14478)
		(layer "In4.Cu")
		(net "M_D_CPU0_SB_DQ<1>")
	)
	(segment
		(start 302.735996 -283.448506)
		(end 302.89754 -283.61005)
		(width 0.14478)
		(layer "In4.Cu")
		(net "M_D_CPU0_SB_DQ<1>")
	)
	(segment
		(start 340.412832 -275.244814)
		(end 340.435184 -275.161502)
		(width 0.0889)
		(layer "In4.Cu")
		(net "M_D_CPU0_SB_DQ<1>")
	)
	(segment
		(start 306.475638 -283.07411)
		(end 306.7177 -283.07411)
		(width 0.14478)
		(layer "In4.Cu")
		(net "M_D_CPU0_SB_DQ<1>")
	)
	(segment
		(start 290.793424 -282.759912)
		(end 293.513256 -282.759912)
		(width 0.14478)
		(layer "In4.Cu")
		(net "M_D_CPU0_SB_DQ<1>")
	)
	(segment
		(start 305.774852 -282.759912)
		(end 306.16144 -282.759912)
		(width 0.14478)
		(layer "In4.Cu")
		(net "M_D_CPU0_SB_DQ<1>")
	)
	(segment
		(start 287.817306 -283.61005)
		(end 288.969704 -283.61005)
		(width 0.14478)
		(layer "In4.Cu")
		(net "M_D_CPU0_SB_DQ<1>")
	)
	(segment
		(start 286.869378 -283.975302)
		(end 287.032192 -283.812488)
		(width 0.14478)
		(layer "In4.Cu")
		(net "M_D_CPU0_SB_DQ<1>")
	)
	(segment
		(start 304.04562 -283.448506)
		(end 304.04562 -282.984956)
		(width 0.14478)
		(layer "In4.Cu")
		(net "M_D_CPU0_SB_DQ<1>")
	)
	(segment
		(start 289.348164 -283.23159)
		(end 290.321746 -283.23159)
		(width 0.14478)
		(layer "In4.Cu")
		(net "M_D_CPU0_SB_DQ<1>")
	)
	(segment
		(start 293.513256 -282.759912)
		(end 294.363394 -283.61005)
		(width 0.14478)
		(layer "In4.Cu")
		(net "M_D_CPU0_SB_DQ<1>")
	)
	(segment
		(start 304.04562 -282.984956)
		(end 304.207164 -282.823412)
		(width 0.14478)
		(layer "In4.Cu")
		(net "M_D_CPU0_SB_DQ<1>")
	)
	(segment
		(start 302.184562 -283.448506)
		(end 302.184562 -283.152596)
		(width 0.14478)
		(layer "In4.Cu")
		(net "M_D_CPU0_SB_DQ<1>")
	)
	(segment
		(start 287.032192 -283.381196)
		(end 287.195006 -283.218382)
		(width 0.14478)
		(layer "In4.Cu")
		(net "M_D_CPU0_SB_DQ<1>")
	)
	(segment
		(start 287.195006 -283.218382)
		(end 287.425638 -283.218382)
		(width 0.14478)
		(layer "In4.Cu")
		(net "M_D_CPU0_SB_DQ<1>")
	)
	(segment
		(start 297.007026 -283.61005)
		(end 297.857164 -282.759912)
		(width 0.14478)
		(layer "In4.Cu")
		(net "M_D_CPU0_SB_DQ<1>")
	)
	(segment
		(start 307.00599 -282.78582)
		(end 307.5051 -282.78582)
		(width 0.14478)
		(layer "In4.Cu")
		(net "M_D_CPU0_SB_DQ<1>")
	)
	(segment
		(start 306.7177 -283.07411)
		(end 307.00599 -282.78582)
		(width 0.14478)
		(layer "In4.Cu")
		(net "M_D_CPU0_SB_DQ<1>")
	)
	(segment
		(start 286.313118 -283.218382)
		(end 286.475932 -283.381196)
		(width 0.14478)
		(layer "In4.Cu")
		(net "M_D_CPU0_SB_DQ<1>")
	)
	(segment
		(start 324.413118 -274.047712)
		(end 325.325232 -274.047712)
		(width 0.0889)
		(layer "In4.Cu")
		(net "M_D_CPU0_SB_DQ<1>")
	)
	(segment
		(start 340.435184 -275.161502)
		(end 340.281006 -274.896072)
		(width 0.0889)
		(layer "In4.Cu")
		(net "M_D_CPU0_SB_DQ<1>")
	)
	(segment
		(start 324.141084 -274.1295)
		(end 324.33133 -274.1295)
		(width 0.0889)
		(layer "In4.Cu")
		(net "M_D_CPU0_SB_DQ<1>")
	)
	(segment
		(start 304.758598 -283.61005)
		(end 304.924714 -283.61005)
		(width 0.14478)
		(layer "In4.Cu")
		(net "M_D_CPU0_SB_DQ<1>")
	)
	(segment
		(start 302.574452 -282.991052)
		(end 302.735996 -283.152596)
		(width 0.14478)
		(layer "In4.Cu")
		(net "M_D_CPU0_SB_DQ<1>")
	)
	(segment
		(start 304.597054 -282.984956)
		(end 304.597054 -283.448506)
		(width 0.14478)
		(layer "In4.Cu")
		(net "M_D_CPU0_SB_DQ<1>")
	)
	(segment
		(start 338.579714 -275.223478)
		(end 338.588096 -275.218652)
		(width 0.0889)
		(layer "In4.Cu")
		(net "M_D_CPU0_SB_DQ<1>")
	)
	(segment
		(start 301.856394 -283.61005)
		(end 302.023018 -283.61005)
		(width 0.14478)
		(layer "In4.Cu")
		(net "M_D_CPU0_SB_DQ<1>")
	)
	(segment
		(start 331.634084 -275.218652)
		(end 331.642466 -275.223478)
		(width 0.0889)
		(layer "In4.Cu")
		(net "M_D_CPU0_SB_DQ<1>")
	)
	(segment
		(start 307.5051 -282.78582)
		(end 316.16142 -274.1295)
		(width 0.14478)
		(layer "In4.Cu")
		(net "M_D_CPU0_SB_DQ<1>")
	)
	(segment
		(start 287.032192 -283.812488)
		(end 287.032192 -283.381196)
		(width 0.14478)
		(layer "In4.Cu")
		(net "M_D_CPU0_SB_DQ<1>")
	)
	(segment
		(start 304.597054 -283.448506)
		(end 304.758598 -283.61005)
		(width 0.14478)
		(layer "In4.Cu")
		(net "M_D_CPU0_SB_DQ<1>")
	)
	(segment
		(start 302.346106 -282.991052)
		(end 302.574452 -282.991052)
		(width 0.14478)
		(layer "In4.Cu")
		(net "M_D_CPU0_SB_DQ<1>")
	)
	(segment
		(start 287.425638 -283.218382)
		(end 287.817306 -283.61005)
		(width 0.14478)
		(layer "In4.Cu")
		(net "M_D_CPU0_SB_DQ<1>")
	)
	(segment
		(start 301.006256 -282.759912)
		(end 301.856394 -283.61005)
		(width 0.14478)
		(layer "In4.Cu")
		(net "M_D_CPU0_SB_DQ<1>")
	)
	(segment
		(start 285.919672 -283.812488)
		(end 285.919672 -283.381196)
		(width 0.14478)
		(layer "In4.Cu")
		(net "M_D_CPU0_SB_DQ<1>")
	)
	(segment
		(start 304.207164 -282.823412)
		(end 304.43551 -282.823412)
		(width 0.14478)
		(layer "In4.Cu")
		(net "M_D_CPU0_SB_DQ<1>")
	)
	(segment
		(start 303.884076 -283.61005)
		(end 304.04562 -283.448506)
		(width 0.14478)
		(layer "In4.Cu")
		(net "M_D_CPU0_SB_DQ<1>")
	)
	(arc
		(start 332.948026 -275.218652)
		(mid 333.230982 -275.142475)
		(end 333.513938 -275.218652)
		(width 0.0889)
		(layer "In4.Cu")
		(net "M_D_CPU0_SB_DQ<1>")
	)
	(arc
		(start 333.513938 -275.218652)
		(mid 333.696189 -275.269002)
		(end 333.879698 -275.223478)
		(width 0.0889)
		(layer "In4.Cu")
		(net "M_D_CPU0_SB_DQ<1>")
	)
	(arc
		(start 339.52815 -275.218652)
		(mid 339.811106 -275.142475)
		(end 340.094062 -275.218652)
		(width 0.0889)
		(layer "In4.Cu")
		(net "M_D_CPU0_SB_DQ<1>")
	)
	(arc
		(start 331.642466 -275.223478)
		(mid 331.825974 -275.268972)
		(end 332.008226 -275.218652)
		(width 0.0889)
		(layer "In4.Cu")
		(net "M_D_CPU0_SB_DQ<1>")
	)
	(arc
		(start 329.188064 -275.218652)
		(mid 329.47102 -275.142475)
		(end 329.753976 -275.218652)
		(width 0.0889)
		(layer "In4.Cu")
		(net "M_D_CPU0_SB_DQ<1>")
	)
	(arc
		(start 327.59015 -275.142198)
		(mid 327.73695 -275.161642)
		(end 327.873614 -275.218652)
		(width 0.0889)
		(layer "In4.Cu")
		(net "M_D_CPU0_SB_DQ<1>")
	)
	(arc
		(start 339.154008 -275.218652)
		(mid 339.336259 -275.269002)
		(end 339.519768 -275.223478)
		(width 0.0889)
		(layer "In4.Cu")
		(net "M_D_CPU0_SB_DQ<1>")
	)
	(arc
		(start 333.88808 -275.218652)
		(mid 334.171036 -275.142475)
		(end 334.453992 -275.218652)
		(width 0.0889)
		(layer "In4.Cu")
		(net "M_D_CPU0_SB_DQ<1>")
	)
	(arc
		(start 334.453992 -275.218652)
		(mid 334.636243 -275.269002)
		(end 334.819752 -275.223478)
		(width 0.0889)
		(layer "In4.Cu")
		(net "M_D_CPU0_SB_DQ<1>")
	)
	(arc
		(start 338.213954 -275.218652)
		(mid 338.396205 -275.269002)
		(end 338.579714 -275.223478)
		(width 0.0889)
		(layer "In4.Cu")
		(net "M_D_CPU0_SB_DQ<1>")
	)
	(arc
		(start 337.274154 -275.218652)
		(mid 337.461098 -275.268907)
		(end 337.648042 -275.218652)
		(width 0.0889)
		(layer "In4.Cu")
		(net "M_D_CPU0_SB_DQ<1>")
	)
	(arc
		(start 328.814176 -275.218652)
		(mid 329.00112 -275.268907)
		(end 329.188064 -275.218652)
		(width 0.0889)
		(layer "In4.Cu")
		(net "M_D_CPU0_SB_DQ<1>")
	)
	(arc
		(start 331.068172 -275.218652)
		(mid 331.351128 -275.142475)
		(end 331.634084 -275.218652)
		(width 0.0889)
		(layer "In4.Cu")
		(net "M_D_CPU0_SB_DQ<1>")
	)
	(arc
		(start 337.648042 -275.218652)
		(mid 337.930998 -275.142475)
		(end 338.213954 -275.218652)
		(width 0.0889)
		(layer "In4.Cu")
		(net "M_D_CPU0_SB_DQ<1>")
	)
	(arc
		(start 335.402428 -275.223478)
		(mid 335.585936 -275.268972)
		(end 335.768188 -275.218652)
		(width 0.0889)
		(layer "In4.Cu")
		(net "M_D_CPU0_SB_DQ<1>")
	)
	(arc
		(start 329.753976 -275.218652)
		(mid 329.936227 -275.269002)
		(end 330.119736 -275.223478)
		(width 0.0889)
		(layer "In4.Cu")
		(net "M_D_CPU0_SB_DQ<1>")
	)
	(arc
		(start 334.828134 -275.218652)
		(mid 335.11109 -275.142475)
		(end 335.394046 -275.218652)
		(width 0.0889)
		(layer "In4.Cu")
		(net "M_D_CPU0_SB_DQ<1>")
	)
	(arc
		(start 336.342482 -275.223478)
		(mid 336.52599 -275.268972)
		(end 336.708242 -275.218652)
		(width 0.0889)
		(layer "In4.Cu")
		(net "M_D_CPU0_SB_DQ<1>")
	)
	(arc
		(start 335.768188 -275.218652)
		(mid 336.051144 -275.142475)
		(end 336.3341 -275.218652)
		(width 0.0889)
		(layer "In4.Cu")
		(net "M_D_CPU0_SB_DQ<1>")
	)
	(arc
		(start 338.588096 -275.218652)
		(mid 338.871052 -275.142475)
		(end 339.154008 -275.218652)
		(width 0.0889)
		(layer "In4.Cu")
		(net "M_D_CPU0_SB_DQ<1>")
	)
	(arc
		(start 332.574138 -275.218652)
		(mid 332.761082 -275.268907)
		(end 332.948026 -275.218652)
		(width 0.0889)
		(layer "In4.Cu")
		(net "M_D_CPU0_SB_DQ<1>")
	)
	(arc
		(start 327.873614 -275.218652)
		(mid 328.056119 -275.269129)
		(end 328.239882 -275.223478)
		(width 0.0889)
		(layer "In4.Cu")
		(net "M_D_CPU0_SB_DQ<1>")
	)
	(arc
		(start 330.128118 -275.218652)
		(mid 330.411074 -275.142475)
		(end 330.69403 -275.218652)
		(width 0.0889)
		(layer "In4.Cu")
		(net "M_D_CPU0_SB_DQ<1>")
	)
	(arc
		(start 340.102444 -275.223478)
		(mid 340.255314 -275.268119)
		(end 340.412832 -275.244814)
		(width 0.0889)
		(layer "In4.Cu")
		(net "M_D_CPU0_SB_DQ<1>")
	)
	(arc
		(start 332.008226 -275.218652)
		(mid 332.291182 -275.142475)
		(end 332.574138 -275.218652)
		(width 0.0889)
		(layer "In4.Cu")
		(net "M_D_CPU0_SB_DQ<1>")
	)
	(arc
		(start 330.702412 -275.223478)
		(mid 330.88592 -275.268972)
		(end 331.068172 -275.218652)
		(width 0.0889)
		(layer "In4.Cu")
		(net "M_D_CPU0_SB_DQ<1>")
	)
	(arc
		(start 328.248264 -275.218652)
		(mid 328.53122 -275.142475)
		(end 328.814176 -275.218652)
		(width 0.0889)
		(layer "In4.Cu")
		(net "M_D_CPU0_SB_DQ<1>")
	)
	(arc
		(start 336.708242 -275.218652)
		(mid 336.991198 -275.142475)
		(end 337.274154 -275.218652)
		(width 0.0889)
		(layer "In4.Cu")
		(net "M_D_CPU0_SB_DQ<1>")
	)
	(segment
		(start 341.218012 -285.160212)
		(end 340.75116 -285.42615)
		(width 0.10668)
		(layer "F.Cu")
		(net "M_D_CPU0_SB_DQ<19>")
	)
	(segment
		(start 333.984092 -285.10357)
		(end 333.992474 -285.098744)
		(width 0.0889)
		(layer "In4.Cu")
		(net "M_D_CPU0_SB_DQ<19>")
	)
	(segment
		(start 337.16976 -285.098744)
		(end 337.178142 -285.10357)
		(width 0.0889)
		(layer "In4.Cu")
		(net "M_D_CPU0_SB_DQ<19>")
	)
	(segment
		(start 301.598584 -302.300386)
		(end 302.062896 -302.764698)
		(width 0.14478)
		(layer "In4.Cu")
		(net "M_D_CPU0_SB_DQ<19>")
	)
	(segment
		(start 281.780234 -302.997362)
		(end 281.780234 -302.464724)
		(width 0.14478)
		(layer "In4.Cu")
		(net "M_D_CPU0_SB_DQ<19>")
	)
	(segment
		(start 282.336494 -302.997362)
		(end 282.489402 -303.15027)
		(width 0.14478)
		(layer "In4.Cu")
		(net "M_D_CPU0_SB_DQ<19>")
	)
	(segment
		(start 326.837802 -285.103824)
		(end 326.84339 -285.107126)
		(width 0.0889)
		(layer "In4.Cu")
		(net "M_D_CPU0_SB_DQ<19>")
	)
	(segment
		(start 282.17368 -302.30191)
		(end 282.336494 -302.464724)
		(width 0.14478)
		(layer "In4.Cu")
		(net "M_D_CPU0_SB_DQ<19>")
	)
	(segment
		(start 332.469744 -285.098744)
		(end 332.478126 -285.10357)
		(width 0.0889)
		(layer "In4.Cu")
		(net "M_D_CPU0_SB_DQ<19>")
	)
	(segment
		(start 308.708044 -301.749968)
		(end 308.708044 -300.929548)
		(width 0.14478)
		(layer "In4.Cu")
		(net "M_D_CPU0_SB_DQ<19>")
	)
	(segment
		(start 323.806312 -285.83128)
		(end 323.861684 -285.83128)
		(width 0.14478)
		(layer "In4.Cu")
		(net "M_D_CPU0_SB_DQ<19>")
	)
	(segment
		(start 328.709782 -285.098744)
		(end 328.718164 -285.10357)
		(width 0.0889)
		(layer "In4.Cu")
		(net "M_D_CPU0_SB_DQ<19>")
	)
	(segment
		(start 338.684108 -285.10357)
		(end 338.69249 -285.098744)
		(width 0.0889)
		(layer "In4.Cu")
		(net "M_D_CPU0_SB_DQ<19>")
	)
	(segment
		(start 302.062896 -302.764698)
		(end 304.875184 -302.764698)
		(width 0.14478)
		(layer "In4.Cu")
		(net "M_D_CPU0_SB_DQ<19>")
	)
	(segment
		(start 294.054784 -302.300386)
		(end 294.904668 -303.15027)
		(width 0.14478)
		(layer "In4.Cu")
		(net "M_D_CPU0_SB_DQ<19>")
	)
	(segment
		(start 308.232302 -302.22571)
		(end 308.708044 -301.749968)
		(width 0.14478)
		(layer "In4.Cu")
		(net "M_D_CPU0_SB_DQ<19>")
	)
	(segment
		(start 324.22211 -285.83128)
		(end 324.671944 -285.381446)
		(width 0.0889)
		(layer "In4.Cu")
		(net "M_D_CPU0_SB_DQ<19>")
	)
	(segment
		(start 336.229706 -285.098744)
		(end 336.238088 -285.10357)
		(width 0.0889)
		(layer "In4.Cu")
		(net "M_D_CPU0_SB_DQ<19>")
	)
	(segment
		(start 281.61742 -303.160176)
		(end 281.780234 -302.997362)
		(width 0.14478)
		(layer "In4.Cu")
		(net "M_D_CPU0_SB_DQ<19>")
	)
	(segment
		(start 294.904668 -303.15027)
		(end 296.971212 -303.15027)
		(width 0.14478)
		(layer "In4.Cu")
		(net "M_D_CPU0_SB_DQ<19>")
	)
	(segment
		(start 326.819514 -285.09341)
		(end 326.837802 -285.103824)
		(width 0.0889)
		(layer "In4.Cu")
		(net "M_D_CPU0_SB_DQ<19>")
	)
	(segment
		(start 333.044038 -285.10357)
		(end 333.05242 -285.098744)
		(width 0.0889)
		(layer "In4.Cu")
		(net "M_D_CPU0_SB_DQ<19>")
	)
	(segment
		(start 340.500716 -285.13532)
		(end 340.596982 -285.16072)
		(width 0.0889)
		(layer "In4.Cu")
		(net "M_D_CPU0_SB_DQ<19>")
	)
	(segment
		(start 304.875184 -302.764698)
		(end 305.414172 -302.22571)
		(width 0.14478)
		(layer "In4.Cu")
		(net "M_D_CPU0_SB_DQ<19>")
	)
	(segment
		(start 281.780234 -302.464724)
		(end 281.943048 -302.30191)
		(width 0.14478)
		(layer "In4.Cu")
		(net "M_D_CPU0_SB_DQ<19>")
	)
	(segment
		(start 290.399724 -302.300386)
		(end 294.054784 -302.300386)
		(width 0.14478)
		(layer "In4.Cu")
		(net "M_D_CPU0_SB_DQ<19>")
	)
	(segment
		(start 282.489402 -303.15027)
		(end 289.54984 -303.15027)
		(width 0.14478)
		(layer "In4.Cu")
		(net "M_D_CPU0_SB_DQ<19>")
	)
	(segment
		(start 323.861684 -285.83128)
		(end 324.22211 -285.83128)
		(width 0.0889)
		(layer "In4.Cu")
		(net "M_D_CPU0_SB_DQ<19>")
	)
	(segment
		(start 296.971212 -303.15027)
		(end 297.821096 -302.300386)
		(width 0.14478)
		(layer "In4.Cu")
		(net "M_D_CPU0_SB_DQ<19>")
	)
	(segment
		(start 280.635964 -302.73498)
		(end 281.06116 -303.160176)
		(width 0.14478)
		(layer "In4.Cu")
		(net "M_D_CPU0_SB_DQ<19>")
	)
	(segment
		(start 281.943048 -302.30191)
		(end 282.17368 -302.30191)
		(width 0.14478)
		(layer "In4.Cu")
		(net "M_D_CPU0_SB_DQ<19>")
	)
	(segment
		(start 281.06116 -303.160176)
		(end 281.61742 -303.160176)
		(width 0.14478)
		(layer "In4.Cu")
		(net "M_D_CPU0_SB_DQ<19>")
	)
	(segment
		(start 340.596982 -285.16072)
		(end 340.75116 -285.42615)
		(width 0.0889)
		(layer "In4.Cu")
		(net "M_D_CPU0_SB_DQ<19>")
	)
	(segment
		(start 337.744054 -285.10357)
		(end 337.752436 -285.098744)
		(width 0.0889)
		(layer "In4.Cu")
		(net "M_D_CPU0_SB_DQ<19>")
	)
	(segment
		(start 297.821096 -302.300386)
		(end 301.598584 -302.300386)
		(width 0.14478)
		(layer "In4.Cu")
		(net "M_D_CPU0_SB_DQ<19>")
	)
	(segment
		(start 282.336494 -302.464724)
		(end 282.336494 -302.997362)
		(width 0.14478)
		(layer "In4.Cu")
		(net "M_D_CPU0_SB_DQ<19>")
	)
	(segment
		(start 329.284076 -285.10357)
		(end 329.292458 -285.098744)
		(width 0.0889)
		(layer "In4.Cu")
		(net "M_D_CPU0_SB_DQ<19>")
	)
	(segment
		(start 327.403206 -285.10357)
		(end 327.41489 -285.096712)
		(width 0.0889)
		(layer "In4.Cu")
		(net "M_D_CPU0_SB_DQ<19>")
	)
	(segment
		(start 331.52969 -285.098744)
		(end 331.538072 -285.10357)
		(width 0.0889)
		(layer "In4.Cu")
		(net "M_D_CPU0_SB_DQ<19>")
	)
	(segment
		(start 305.414172 -302.22571)
		(end 308.232302 -302.22571)
		(width 0.14478)
		(layer "In4.Cu")
		(net "M_D_CPU0_SB_DQ<19>")
	)
	(segment
		(start 324.752208 -285.348172)
		(end 325.554848 -285.348172)
		(width 0.0889)
		(layer "In4.Cu")
		(net "M_D_CPU0_SB_DQ<19>")
	)
	(segment
		(start 308.708044 -300.929548)
		(end 323.806312 -285.83128)
		(width 0.14478)
		(layer "In4.Cu")
		(net "M_D_CPU0_SB_DQ<19>")
	)
	(segment
		(start 328.32929 -285.112206)
		(end 328.344022 -285.10357)
		(width 0.0889)
		(layer "In4.Cu")
		(net "M_D_CPU0_SB_DQ<19>")
	)
	(segment
		(start 289.54984 -303.15027)
		(end 290.399724 -302.300386)
		(width 0.14478)
		(layer "In4.Cu")
		(net "M_D_CPU0_SB_DQ<19>")
	)
	(arc
		(start 333.992474 -285.098744)
		(mid 334.175982 -285.05325)
		(end 334.358234 -285.10357)
		(width 0.0889)
		(layer "In4.Cu")
		(net "M_D_CPU0_SB_DQ<19>")
	)
	(arc
		(start 330.22413 -285.10357)
		(mid 330.411074 -285.053315)
		(end 330.598018 -285.10357)
		(width 0.0889)
		(layer "In4.Cu")
		(net "M_D_CPU0_SB_DQ<19>")
	)
	(arc
		(start 325.554848 -285.348172)
		(mid 326.025418 -285.285941)
		(end 326.46366 -285.10357)
		(width 0.0889)
		(layer "In4.Cu")
		(net "M_D_CPU0_SB_DQ<19>")
	)
	(arc
		(start 339.05825 -285.10357)
		(mid 339.341206 -285.179747)
		(end 339.624162 -285.10357)
		(width 0.0889)
		(layer "In4.Cu")
		(net "M_D_CPU0_SB_DQ<19>")
	)
	(arc
		(start 339.99805 -285.10357)
		(mid 340.245646 -285.178748)
		(end 340.500716 -285.13532)
		(width 0.0889)
		(layer "In4.Cu")
		(net "M_D_CPU0_SB_DQ<19>")
	)
	(arc
		(start 331.16393 -285.10357)
		(mid 331.346181 -285.05322)
		(end 331.52969 -285.098744)
		(width 0.0889)
		(layer "In4.Cu")
		(net "M_D_CPU0_SB_DQ<19>")
	)
	(arc
		(start 332.103984 -285.10357)
		(mid 332.286235 -285.05322)
		(end 332.469744 -285.098744)
		(width 0.0889)
		(layer "In4.Cu")
		(net "M_D_CPU0_SB_DQ<19>")
	)
	(arc
		(start 331.538072 -285.10357)
		(mid 331.821028 -285.179747)
		(end 332.103984 -285.10357)
		(width 0.0889)
		(layer "In4.Cu")
		(net "M_D_CPU0_SB_DQ<19>")
	)
	(arc
		(start 335.863946 -285.10357)
		(mid 336.046197 -285.05322)
		(end 336.229706 -285.098744)
		(width 0.0889)
		(layer "In4.Cu")
		(net "M_D_CPU0_SB_DQ<19>")
	)
	(arc
		(start 329.292458 -285.098744)
		(mid 329.475966 -285.05325)
		(end 329.658218 -285.10357)
		(width 0.0889)
		(layer "In4.Cu")
		(net "M_D_CPU0_SB_DQ<19>")
	)
	(arc
		(start 338.69249 -285.098744)
		(mid 338.875998 -285.05325)
		(end 339.05825 -285.10357)
		(width 0.0889)
		(layer "In4.Cu")
		(net "M_D_CPU0_SB_DQ<19>")
	)
	(arc
		(start 334.924146 -285.10357)
		(mid 335.11109 -285.053315)
		(end 335.298034 -285.10357)
		(width 0.0889)
		(layer "In4.Cu")
		(net "M_D_CPU0_SB_DQ<19>")
	)
	(arc
		(start 326.46366 -285.10357)
		(mid 326.640288 -285.053337)
		(end 326.819514 -285.09341)
		(width 0.0889)
		(layer "In4.Cu")
		(net "M_D_CPU0_SB_DQ<19>")
	)
	(arc
		(start 327.777602 -285.10357)
		(mid 328.052308 -285.179934)
		(end 328.32929 -285.112206)
		(width 0.0889)
		(layer "In4.Cu")
		(net "M_D_CPU0_SB_DQ<19>")
	)
	(arc
		(start 328.718164 -285.10357)
		(mid 329.00112 -285.179747)
		(end 329.284076 -285.10357)
		(width 0.0889)
		(layer "In4.Cu")
		(net "M_D_CPU0_SB_DQ<19>")
	)
	(arc
		(start 333.05242 -285.098744)
		(mid 333.235928 -285.05325)
		(end 333.41818 -285.10357)
		(width 0.0889)
		(layer "In4.Cu")
		(net "M_D_CPU0_SB_DQ<19>")
	)
	(arc
		(start 334.358234 -285.10357)
		(mid 334.64119 -285.179747)
		(end 334.924146 -285.10357)
		(width 0.0889)
		(layer "In4.Cu")
		(net "M_D_CPU0_SB_DQ<19>")
	)
	(arc
		(start 330.598018 -285.10357)
		(mid 330.880974 -285.179747)
		(end 331.16393 -285.10357)
		(width 0.0889)
		(layer "In4.Cu")
		(net "M_D_CPU0_SB_DQ<19>")
	)
	(arc
		(start 336.804 -285.10357)
		(mid 336.986251 -285.05322)
		(end 337.16976 -285.098744)
		(width 0.0889)
		(layer "In4.Cu")
		(net "M_D_CPU0_SB_DQ<19>")
	)
	(arc
		(start 333.41818 -285.10357)
		(mid 333.701136 -285.179747)
		(end 333.984092 -285.10357)
		(width 0.0889)
		(layer "In4.Cu")
		(net "M_D_CPU0_SB_DQ<19>")
	)
	(arc
		(start 329.658218 -285.10357)
		(mid 329.941174 -285.179747)
		(end 330.22413 -285.10357)
		(width 0.0889)
		(layer "In4.Cu")
		(net "M_D_CPU0_SB_DQ<19>")
	)
	(arc
		(start 335.298034 -285.10357)
		(mid 335.58099 -285.179747)
		(end 335.863946 -285.10357)
		(width 0.0889)
		(layer "In4.Cu")
		(net "M_D_CPU0_SB_DQ<19>")
	)
	(arc
		(start 327.41489 -285.096712)
		(mid 327.597145 -285.053059)
		(end 327.777602 -285.10357)
		(width 0.0889)
		(layer "In4.Cu")
		(net "M_D_CPU0_SB_DQ<19>")
	)
	(arc
		(start 339.624162 -285.10357)
		(mid 339.811106 -285.053315)
		(end 339.99805 -285.10357)
		(width 0.0889)
		(layer "In4.Cu")
		(net "M_D_CPU0_SB_DQ<19>")
	)
	(arc
		(start 337.178142 -285.10357)
		(mid 337.461098 -285.179747)
		(end 337.744054 -285.10357)
		(width 0.0889)
		(layer "In4.Cu")
		(net "M_D_CPU0_SB_DQ<19>")
	)
	(arc
		(start 338.118196 -285.10357)
		(mid 338.401152 -285.179747)
		(end 338.684108 -285.10357)
		(width 0.0889)
		(layer "In4.Cu")
		(net "M_D_CPU0_SB_DQ<19>")
	)
	(arc
		(start 324.671944 -285.381446)
		(mid 324.708755 -285.356786)
		(end 324.752208 -285.348172)
		(width 0.0889)
		(layer "In4.Cu")
		(net "M_D_CPU0_SB_DQ<19>")
	)
	(arc
		(start 336.238088 -285.10357)
		(mid 336.521044 -285.179747)
		(end 336.804 -285.10357)
		(width 0.0889)
		(layer "In4.Cu")
		(net "M_D_CPU0_SB_DQ<19>")
	)
	(arc
		(start 337.752436 -285.098744)
		(mid 337.935944 -285.05325)
		(end 338.118196 -285.10357)
		(width 0.0889)
		(layer "In4.Cu")
		(net "M_D_CPU0_SB_DQ<19>")
	)
	(arc
		(start 328.344022 -285.10357)
		(mid 328.526273 -285.05322)
		(end 328.709782 -285.098744)
		(width 0.0889)
		(layer "In4.Cu")
		(net "M_D_CPU0_SB_DQ<19>")
	)
	(arc
		(start 326.84339 -285.107126)
		(mid 327.123779 -285.179795)
		(end 327.403206 -285.10357)
		(width 0.0889)
		(layer "In4.Cu")
		(net "M_D_CPU0_SB_DQ<19>")
	)
	(arc
		(start 332.478126 -285.10357)
		(mid 332.761082 -285.179747)
		(end 333.044038 -285.10357)
		(width 0.0889)
		(layer "In4.Cu")
		(net "M_D_CPU0_SB_DQ<19>")
	)
	(segment
		(start 339.808058 -284.350206)
		(end 339.341206 -284.616144)
		(width 0.10668)
		(layer "F.Cu")
		(net "M_D_CPU0_SB_DQ<18>")
	)
	(segment
		(start 335.394046 -284.293564)
		(end 335.402428 -284.288738)
		(width 0.0889)
		(layer "In4.Cu")
		(net "M_D_CPU0_SB_DQ<18>")
	)
	(segment
		(start 328.239882 -284.288738)
		(end 328.248264 -284.293564)
		(width 0.0889)
		(layer "In4.Cu")
		(net "M_D_CPU0_SB_DQ<18>")
	)
	(segment
		(start 281.285696 -301.460154)
		(end 281.44851 -301.29734)
		(width 0.14478)
		(layer "In4.Cu")
		(net "M_D_CPU0_SB_DQ<18>")
	)
	(segment
		(start 282.954476 -300.52391)
		(end 283.11729 -300.686724)
		(width 0.14478)
		(layer "In4.Cu")
		(net "M_D_CPU0_SB_DQ<18>")
	)
	(segment
		(start 331.634084 -284.293564)
		(end 331.642466 -284.288738)
		(width 0.0889)
		(layer "In4.Cu")
		(net "M_D_CPU0_SB_DQ<18>")
	)
	(segment
		(start 339.187028 -284.350714)
		(end 339.341206 -284.616144)
		(width 0.0889)
		(layer "In4.Cu")
		(net "M_D_CPU0_SB_DQ<18>")
	)
	(segment
		(start 297.374818 -301.460154)
		(end 298.224956 -300.610016)
		(width 0.14478)
		(layer "In4.Cu")
		(net "M_D_CPU0_SB_DQ<18>")
	)
	(segment
		(start 334.819752 -284.288738)
		(end 334.828134 -284.293564)
		(width 0.0889)
		(layer "In4.Cu")
		(net "M_D_CPU0_SB_DQ<18>")
	)
	(segment
		(start 298.224956 -300.610016)
		(end 301.35576 -300.610016)
		(width 0.14478)
		(layer "In4.Cu")
		(net "M_D_CPU0_SB_DQ<18>")
	)
	(segment
		(start 327.307448 -284.293564)
		(end 327.317862 -284.29966)
		(width 0.0889)
		(layer "In4.Cu")
		(net "M_D_CPU0_SB_DQ<18>")
	)
	(segment
		(start 305.743356 -300.610016)
		(end 307.736748 -300.610016)
		(width 0.14478)
		(layer "In4.Cu")
		(net "M_D_CPU0_SB_DQ<18>")
	)
	(segment
		(start 282.00477 -301.29734)
		(end 282.167584 -301.460154)
		(width 0.14478)
		(layer "In4.Cu")
		(net "M_D_CPU0_SB_DQ<18>")
	)
	(segment
		(start 281.611324 -300.52391)
		(end 281.841956 -300.52391)
		(width 0.14478)
		(layer "In4.Cu")
		(net "M_D_CPU0_SB_DQ<18>")
	)
	(segment
		(start 324.21703 -284.92196)
		(end 324.423278 -284.715712)
		(width 0.0889)
		(layer "In4.Cu")
		(net "M_D_CPU0_SB_DQ<18>")
	)
	(segment
		(start 282.398216 -301.460154)
		(end 282.56103 -301.29734)
		(width 0.14478)
		(layer "In4.Cu")
		(net "M_D_CPU0_SB_DQ<18>")
	)
	(segment
		(start 280.635964 -301.034958)
		(end 281.06116 -301.460154)
		(width 0.14478)
		(layer "In4.Cu")
		(net "M_D_CPU0_SB_DQ<18>")
	)
	(segment
		(start 282.00477 -300.686724)
		(end 282.00477 -301.29734)
		(width 0.14478)
		(layer "In4.Cu")
		(net "M_D_CPU0_SB_DQ<18>")
	)
	(segment
		(start 282.56103 -301.29734)
		(end 282.56103 -300.686724)
		(width 0.14478)
		(layer "In4.Cu")
		(net "M_D_CPU0_SB_DQ<18>")
	)
	(segment
		(start 304.893218 -301.460154)
		(end 305.743356 -300.610016)
		(width 0.14478)
		(layer "In4.Cu")
		(net "M_D_CPU0_SB_DQ<18>")
	)
	(segment
		(start 281.06116 -301.460154)
		(end 281.285696 -301.460154)
		(width 0.14478)
		(layer "In4.Cu")
		(net "M_D_CPU0_SB_DQ<18>")
	)
	(segment
		(start 323.424804 -284.92196)
		(end 323.913754 -284.92196)
		(width 0.14478)
		(layer "In4.Cu")
		(net "M_D_CPU0_SB_DQ<18>")
	)
	(segment
		(start 281.44851 -300.686724)
		(end 281.611324 -300.52391)
		(width 0.14478)
		(layer "In4.Cu")
		(net "M_D_CPU0_SB_DQ<18>")
	)
	(segment
		(start 323.913754 -284.92196)
		(end 324.21703 -284.92196)
		(width 0.0889)
		(layer "In4.Cu")
		(net "M_D_CPU0_SB_DQ<18>")
	)
	(segment
		(start 294.941498 -301.460154)
		(end 297.374818 -301.460154)
		(width 0.14478)
		(layer "In4.Cu")
		(net "M_D_CPU0_SB_DQ<18>")
	)
	(segment
		(start 325.472298 -284.715712)
		(end 325.818246 -284.369764)
		(width 0.0889)
		(layer "In4.Cu")
		(net "M_D_CPU0_SB_DQ<18>")
	)
	(segment
		(start 281.44851 -301.29734)
		(end 281.44851 -300.686724)
		(width 0.14478)
		(layer "In4.Cu")
		(net "M_D_CPU0_SB_DQ<18>")
	)
	(segment
		(start 282.167584 -301.460154)
		(end 282.398216 -301.460154)
		(width 0.14478)
		(layer "In4.Cu")
		(net "M_D_CPU0_SB_DQ<18>")
	)
	(segment
		(start 338.579714 -284.288738)
		(end 338.588096 -284.293564)
		(width 0.0889)
		(layer "In4.Cu")
		(net "M_D_CPU0_SB_DQ<18>")
	)
	(segment
		(start 307.736748 -300.610016)
		(end 323.424804 -284.92196)
		(width 0.14478)
		(layer "In4.Cu")
		(net "M_D_CPU0_SB_DQ<18>")
	)
	(segment
		(start 302.205898 -301.460154)
		(end 304.893218 -301.460154)
		(width 0.14478)
		(layer "In4.Cu")
		(net "M_D_CPU0_SB_DQ<18>")
	)
	(segment
		(start 289.61461 -301.460154)
		(end 290.464748 -300.610016)
		(width 0.14478)
		(layer "In4.Cu")
		(net "M_D_CPU0_SB_DQ<18>")
	)
	(segment
		(start 283.11729 -300.686724)
		(end 283.11729 -301.29734)
		(width 0.14478)
		(layer "In4.Cu")
		(net "M_D_CPU0_SB_DQ<18>")
	)
	(segment
		(start 282.723844 -300.52391)
		(end 282.954476 -300.52391)
		(width 0.14478)
		(layer "In4.Cu")
		(net "M_D_CPU0_SB_DQ<18>")
	)
	(segment
		(start 330.69403 -284.293564)
		(end 330.702412 -284.288738)
		(width 0.0889)
		(layer "In4.Cu")
		(net "M_D_CPU0_SB_DQ<18>")
	)
	(segment
		(start 283.280104 -301.460154)
		(end 289.61461 -301.460154)
		(width 0.14478)
		(layer "In4.Cu")
		(net "M_D_CPU0_SB_DQ<18>")
	)
	(segment
		(start 326.93356 -284.293818)
		(end 326.949816 -284.28442)
		(width 0.0889)
		(layer "In4.Cu")
		(net "M_D_CPU0_SB_DQ<18>")
	)
	(segment
		(start 324.423278 -284.715712)
		(end 325.472298 -284.715712)
		(width 0.0889)
		(layer "In4.Cu")
		(net "M_D_CPU0_SB_DQ<18>")
	)
	(segment
		(start 301.35576 -300.610016)
		(end 302.205898 -301.460154)
		(width 0.14478)
		(layer "In4.Cu")
		(net "M_D_CPU0_SB_DQ<18>")
	)
	(segment
		(start 339.090762 -284.325314)
		(end 339.187028 -284.350714)
		(width 0.0889)
		(layer "In4.Cu")
		(net "M_D_CPU0_SB_DQ<18>")
	)
	(segment
		(start 282.56103 -300.686724)
		(end 282.723844 -300.52391)
		(width 0.14478)
		(layer "In4.Cu")
		(net "M_D_CPU0_SB_DQ<18>")
	)
	(segment
		(start 283.11729 -301.29734)
		(end 283.280104 -301.460154)
		(width 0.14478)
		(layer "In4.Cu")
		(net "M_D_CPU0_SB_DQ<18>")
	)
	(segment
		(start 281.841956 -300.52391)
		(end 282.00477 -300.686724)
		(width 0.14478)
		(layer "In4.Cu")
		(net "M_D_CPU0_SB_DQ<18>")
	)
	(segment
		(start 333.879698 -284.288738)
		(end 333.88808 -284.293564)
		(width 0.0889)
		(layer "In4.Cu")
		(net "M_D_CPU0_SB_DQ<18>")
	)
	(segment
		(start 330.119736 -284.288738)
		(end 330.128118 -284.293564)
		(width 0.0889)
		(layer "In4.Cu")
		(net "M_D_CPU0_SB_DQ<18>")
	)
	(segment
		(start 294.09136 -300.610016)
		(end 294.941498 -301.460154)
		(width 0.14478)
		(layer "In4.Cu")
		(net "M_D_CPU0_SB_DQ<18>")
	)
	(segment
		(start 336.3341 -284.293564)
		(end 336.342482 -284.288738)
		(width 0.0889)
		(layer "In4.Cu")
		(net "M_D_CPU0_SB_DQ<18>")
	)
	(segment
		(start 325.818246 -284.369764)
		(end 326.651112 -284.369764)
		(width 0.0889)
		(layer "In4.Cu")
		(net "M_D_CPU0_SB_DQ<18>")
	)
	(segment
		(start 290.464748 -300.610016)
		(end 294.09136 -300.610016)
		(width 0.14478)
		(layer "In4.Cu")
		(net "M_D_CPU0_SB_DQ<18>")
	)
	(arc
		(start 328.814176 -284.293564)
		(mid 329.00112 -284.243309)
		(end 329.188064 -284.293564)
		(width 0.0889)
		(layer "In4.Cu")
		(net "M_D_CPU0_SB_DQ<18>")
	)
	(arc
		(start 336.708242 -284.293564)
		(mid 336.991198 -284.369741)
		(end 337.274154 -284.293564)
		(width 0.0889)
		(layer "In4.Cu")
		(net "M_D_CPU0_SB_DQ<18>")
	)
	(arc
		(start 330.128118 -284.293564)
		(mid 330.411074 -284.369741)
		(end 330.69403 -284.293564)
		(width 0.0889)
		(layer "In4.Cu")
		(net "M_D_CPU0_SB_DQ<18>")
	)
	(arc
		(start 334.453992 -284.293564)
		(mid 334.636243 -284.243214)
		(end 334.819752 -284.288738)
		(width 0.0889)
		(layer "In4.Cu")
		(net "M_D_CPU0_SB_DQ<18>")
	)
	(arc
		(start 330.702412 -284.288738)
		(mid 330.88592 -284.243244)
		(end 331.068172 -284.293564)
		(width 0.0889)
		(layer "In4.Cu")
		(net "M_D_CPU0_SB_DQ<18>")
	)
	(arc
		(start 332.008226 -284.293564)
		(mid 332.291182 -284.369741)
		(end 332.574138 -284.293564)
		(width 0.0889)
		(layer "In4.Cu")
		(net "M_D_CPU0_SB_DQ<18>")
	)
	(arc
		(start 333.513938 -284.293564)
		(mid 333.696189 -284.243214)
		(end 333.879698 -284.288738)
		(width 0.0889)
		(layer "In4.Cu")
		(net "M_D_CPU0_SB_DQ<18>")
	)
	(arc
		(start 332.574138 -284.293564)
		(mid 332.761082 -284.243309)
		(end 332.948026 -284.293564)
		(width 0.0889)
		(layer "In4.Cu")
		(net "M_D_CPU0_SB_DQ<18>")
	)
	(arc
		(start 337.648042 -284.293564)
		(mid 337.930998 -284.369741)
		(end 338.213954 -284.293564)
		(width 0.0889)
		(layer "In4.Cu")
		(net "M_D_CPU0_SB_DQ<18>")
	)
	(arc
		(start 329.188064 -284.293564)
		(mid 329.47102 -284.369741)
		(end 329.753976 -284.293564)
		(width 0.0889)
		(layer "In4.Cu")
		(net "M_D_CPU0_SB_DQ<18>")
	)
	(arc
		(start 336.342482 -284.288738)
		(mid 336.52599 -284.243244)
		(end 336.708242 -284.293564)
		(width 0.0889)
		(layer "In4.Cu")
		(net "M_D_CPU0_SB_DQ<18>")
	)
	(arc
		(start 338.588096 -284.293564)
		(mid 338.835692 -284.368742)
		(end 339.090762 -284.325314)
		(width 0.0889)
		(layer "In4.Cu")
		(net "M_D_CPU0_SB_DQ<18>")
	)
	(arc
		(start 326.651112 -284.369764)
		(mid 326.79736 -284.350459)
		(end 326.93356 -284.293818)
		(width 0.0889)
		(layer "In4.Cu")
		(net "M_D_CPU0_SB_DQ<18>")
	)
	(arc
		(start 338.213954 -284.293564)
		(mid 338.396205 -284.243214)
		(end 338.579714 -284.288738)
		(width 0.0889)
		(layer "In4.Cu")
		(net "M_D_CPU0_SB_DQ<18>")
	)
	(arc
		(start 335.402428 -284.288738)
		(mid 335.585936 -284.243244)
		(end 335.768188 -284.293564)
		(width 0.0889)
		(layer "In4.Cu")
		(net "M_D_CPU0_SB_DQ<18>")
	)
	(arc
		(start 332.948026 -284.293564)
		(mid 333.230982 -284.369741)
		(end 333.513938 -284.293564)
		(width 0.0889)
		(layer "In4.Cu")
		(net "M_D_CPU0_SB_DQ<18>")
	)
	(arc
		(start 326.949816 -284.28442)
		(mid 327.129798 -284.24332)
		(end 327.307448 -284.293564)
		(width 0.0889)
		(layer "In4.Cu")
		(net "M_D_CPU0_SB_DQ<18>")
	)
	(arc
		(start 331.068172 -284.293564)
		(mid 331.351128 -284.369741)
		(end 331.634084 -284.293564)
		(width 0.0889)
		(layer "In4.Cu")
		(net "M_D_CPU0_SB_DQ<18>")
	)
	(arc
		(start 333.88808 -284.293564)
		(mid 334.171036 -284.369741)
		(end 334.453992 -284.293564)
		(width 0.0889)
		(layer "In4.Cu")
		(net "M_D_CPU0_SB_DQ<18>")
	)
	(arc
		(start 327.317862 -284.29966)
		(mid 327.596548 -284.36988)
		(end 327.873614 -284.293564)
		(width 0.0889)
		(layer "In4.Cu")
		(net "M_D_CPU0_SB_DQ<18>")
	)
	(arc
		(start 335.768188 -284.293564)
		(mid 336.051144 -284.369741)
		(end 336.3341 -284.293564)
		(width 0.0889)
		(layer "In4.Cu")
		(net "M_D_CPU0_SB_DQ<18>")
	)
	(arc
		(start 331.642466 -284.288738)
		(mid 331.825974 -284.243244)
		(end 332.008226 -284.293564)
		(width 0.0889)
		(layer "In4.Cu")
		(net "M_D_CPU0_SB_DQ<18>")
	)
	(arc
		(start 327.873614 -284.293564)
		(mid 328.056119 -284.243087)
		(end 328.239882 -284.288738)
		(width 0.0889)
		(layer "In4.Cu")
		(net "M_D_CPU0_SB_DQ<18>")
	)
	(arc
		(start 337.274154 -284.293564)
		(mid 337.461098 -284.243309)
		(end 337.648042 -284.293564)
		(width 0.0889)
		(layer "In4.Cu")
		(net "M_D_CPU0_SB_DQ<18>")
	)
	(arc
		(start 328.248264 -284.293564)
		(mid 328.53122 -284.369741)
		(end 328.814176 -284.293564)
		(width 0.0889)
		(layer "In4.Cu")
		(net "M_D_CPU0_SB_DQ<18>")
	)
	(arc
		(start 329.753976 -284.293564)
		(mid 329.936227 -284.243214)
		(end 330.119736 -284.288738)
		(width 0.0889)
		(layer "In4.Cu")
		(net "M_D_CPU0_SB_DQ<18>")
	)
	(arc
		(start 334.828134 -284.293564)
		(mid 335.11109 -284.369741)
		(end 335.394046 -284.293564)
		(width 0.0889)
		(layer "In4.Cu")
		(net "M_D_CPU0_SB_DQ<18>")
	)
	(segment
		(start 340.747858 -284.350206)
		(end 340.281006 -284.616144)
		(width 0.10668)
		(layer "F.Cu")
		(net "M_D_CPU0_SB_DQ<17>")
	)
	(segment
		(start 299.574712 -301.4599)
		(end 300.006004 -301.4599)
		(width 0.14478)
		(layer "In4.Cu")
		(net "M_D_CPU0_SB_DQ<17>")
	)
	(segment
		(start 333.879698 -284.94355)
		(end 333.88808 -284.938724)
		(width 0.0889)
		(layer "In4.Cu")
		(net "M_D_CPU0_SB_DQ<17>")
	)
	(segment
		(start 300.637448 -301.842932)
		(end 300.791372 -301.689008)
		(width 0.14478)
		(layer "In4.Cu")
		(net "M_D_CPU0_SB_DQ<17>")
	)
	(segment
		(start 298.802806 -301.231554)
		(end 298.802806 -301.675546)
		(width 0.14478)
		(layer "In4.Cu")
		(net "M_D_CPU0_SB_DQ<17>")
	)
	(segment
		(start 336.3341 -284.938724)
		(end 336.342482 -284.94355)
		(width 0.0889)
		(layer "In4.Cu")
		(net "M_D_CPU0_SB_DQ<17>")
	)
	(segment
		(start 298.639992 -301.06874)
		(end 298.802806 -301.231554)
		(width 0.14478)
		(layer "In4.Cu")
		(net "M_D_CPU0_SB_DQ<17>")
	)
	(segment
		(start 286.944816 -302.68291)
		(end 287.10763 -302.520096)
		(width 0.14478)
		(layer "In4.Cu")
		(net "M_D_CPU0_SB_DQ<17>")
	)
	(segment
		(start 287.873948 -302.310038)
		(end 289.577526 -302.310038)
		(width 0.14478)
		(layer "In4.Cu")
		(net "M_D_CPU0_SB_DQ<17>")
	)
	(segment
		(start 327.307194 -284.938724)
		(end 327.321926 -284.930088)
		(width 0.0889)
		(layer "In4.Cu")
		(net "M_D_CPU0_SB_DQ<17>")
	)
	(segment
		(start 284.736032 -301.885096)
		(end 285.533846 -302.68291)
		(width 0.14478)
		(layer "In4.Cu")
		(net "M_D_CPU0_SB_DQ<17>")
	)
	(segment
		(start 285.832296 -302.68291)
		(end 285.99511 -302.520096)
		(width 0.14478)
		(layer "In4.Cu")
		(net "M_D_CPU0_SB_DQ<17>")
	)
	(segment
		(start 306.333398 -301.551086)
		(end 306.500022 -301.71771)
		(width 0.14478)
		(layer "In4.Cu")
		(net "M_D_CPU0_SB_DQ<17>")
	)
	(segment
		(start 307.598572 -301.4599)
		(end 307.856382 -301.71771)
		(width 0.14478)
		(layer "In4.Cu")
		(net "M_D_CPU0_SB_DQ<17>")
	)
	(segment
		(start 305.84521 -301.15129)
		(end 306.17922 -301.15129)
		(width 0.14478)
		(layer "In4.Cu")
		(net "M_D_CPU0_SB_DQ<17>")
	)
	(segment
		(start 290.42741 -301.460154)
		(end 293.168578 -301.460154)
		(width 0.14478)
		(layer "In4.Cu")
		(net "M_D_CPU0_SB_DQ<17>")
	)
	(segment
		(start 300.389036 -301.842932)
		(end 300.637448 -301.842932)
		(width 0.14478)
		(layer "In4.Cu")
		(net "M_D_CPU0_SB_DQ<17>")
	)
	(segment
		(start 297.168062 -302.310038)
		(end 298.40936 -301.06874)
		(width 0.14478)
		(layer "In4.Cu")
		(net "M_D_CPU0_SB_DQ<17>")
	)
	(segment
		(start 287.501076 -301.937166)
		(end 287.873948 -302.310038)
		(width 0.14478)
		(layer "In4.Cu")
		(net "M_D_CPU0_SB_DQ<17>")
	)
	(segment
		(start 285.99511 -302.520096)
		(end 285.99511 -302.09998)
		(width 0.14478)
		(layer "In4.Cu")
		(net "M_D_CPU0_SB_DQ<17>")
	)
	(segment
		(start 340.094062 -284.938724)
		(end 340.102444 -284.94355)
		(width 0.0889)
		(layer "In4.Cu")
		(net "M_D_CPU0_SB_DQ<17>")
	)
	(segment
		(start 286.388556 -301.937166)
		(end 286.55137 -302.09998)
		(width 0.14478)
		(layer "In4.Cu")
		(net "M_D_CPU0_SB_DQ<17>")
	)
	(segment
		(start 323.617844 -285.37662)
		(end 323.898514 -285.37662)
		(width 0.14478)
		(layer "In4.Cu")
		(net "M_D_CPU0_SB_DQ<17>")
	)
	(segment
		(start 301.184818 -301.082202)
		(end 302.412654 -302.310038)
		(width 0.14478)
		(layer "In4.Cu")
		(net "M_D_CPU0_SB_DQ<17>")
	)
	(segment
		(start 285.99511 -302.09998)
		(end 286.157924 -301.937166)
		(width 0.14478)
		(layer "In4.Cu")
		(net "M_D_CPU0_SB_DQ<17>")
	)
	(segment
		(start 298.40936 -301.06874)
		(end 298.639992 -301.06874)
		(width 0.14478)
		(layer "In4.Cu")
		(net "M_D_CPU0_SB_DQ<17>")
	)
	(segment
		(start 307.005736 -301.4599)
		(end 307.598572 -301.4599)
		(width 0.14478)
		(layer "In4.Cu")
		(net "M_D_CPU0_SB_DQ<17>")
	)
	(segment
		(start 300.954186 -301.082202)
		(end 301.184818 -301.082202)
		(width 0.14478)
		(layer "In4.Cu")
		(net "M_D_CPU0_SB_DQ<17>")
	)
	(segment
		(start 334.819752 -284.94355)
		(end 334.828134 -284.938724)
		(width 0.0889)
		(layer "In4.Cu")
		(net "M_D_CPU0_SB_DQ<17>")
	)
	(segment
		(start 308.258464 -300.736)
		(end 323.617844 -285.37662)
		(width 0.14478)
		(layer "In4.Cu")
		(net "M_D_CPU0_SB_DQ<17>")
	)
	(segment
		(start 306.500022 -301.71771)
		(end 306.747926 -301.71771)
		(width 0.14478)
		(layer "In4.Cu")
		(net "M_D_CPU0_SB_DQ<17>")
	)
	(segment
		(start 286.157924 -301.937166)
		(end 286.388556 -301.937166)
		(width 0.14478)
		(layer "In4.Cu")
		(net "M_D_CPU0_SB_DQ<17>")
	)
	(segment
		(start 286.55137 -302.520096)
		(end 286.714184 -302.68291)
		(width 0.14478)
		(layer "In4.Cu")
		(net "M_D_CPU0_SB_DQ<17>")
	)
	(segment
		(start 307.856382 -301.71771)
		(end 308.104286 -301.71771)
		(width 0.14478)
		(layer "In4.Cu")
		(net "M_D_CPU0_SB_DQ<17>")
	)
	(segment
		(start 340.412832 -284.964886)
		(end 340.435184 -284.881574)
		(width 0.0889)
		(layer "In4.Cu")
		(net "M_D_CPU0_SB_DQ<17>")
	)
	(segment
		(start 324.24751 -285.37662)
		(end 324.534784 -285.089346)
		(width 0.0889)
		(layer "In4.Cu")
		(net "M_D_CPU0_SB_DQ<17>")
	)
	(segment
		(start 335.394046 -284.938724)
		(end 335.402428 -284.94355)
		(width 0.0889)
		(layer "In4.Cu")
		(net "M_D_CPU0_SB_DQ<17>")
	)
	(segment
		(start 298.802806 -301.675546)
		(end 298.96562 -301.83836)
		(width 0.14478)
		(layer "In4.Cu")
		(net "M_D_CPU0_SB_DQ<17>")
	)
	(segment
		(start 328.239882 -284.94355)
		(end 328.248264 -284.938724)
		(width 0.0889)
		(layer "In4.Cu")
		(net "M_D_CPU0_SB_DQ<17>")
	)
	(segment
		(start 338.579714 -284.94355)
		(end 338.588096 -284.938724)
		(width 0.0889)
		(layer "In4.Cu")
		(net "M_D_CPU0_SB_DQ<17>")
	)
	(segment
		(start 287.270444 -301.937166)
		(end 287.501076 -301.937166)
		(width 0.14478)
		(layer "In4.Cu")
		(net "M_D_CPU0_SB_DQ<17>")
	)
	(segment
		(start 289.577526 -302.310038)
		(end 290.42741 -301.460154)
		(width 0.14478)
		(layer "In4.Cu")
		(net "M_D_CPU0_SB_DQ<17>")
	)
	(segment
		(start 298.96562 -301.83836)
		(end 299.196252 -301.83836)
		(width 0.14478)
		(layer "In4.Cu")
		(net "M_D_CPU0_SB_DQ<17>")
	)
	(segment
		(start 287.10763 -302.520096)
		(end 287.10763 -302.09998)
		(width 0.14478)
		(layer "In4.Cu")
		(net "M_D_CPU0_SB_DQ<17>")
	)
	(segment
		(start 285.533846 -302.68291)
		(end 285.832296 -302.68291)
		(width 0.14478)
		(layer "In4.Cu")
		(net "M_D_CPU0_SB_DQ<17>")
	)
	(segment
		(start 330.69403 -284.938724)
		(end 330.702412 -284.94355)
		(width 0.0889)
		(layer "In4.Cu")
		(net "M_D_CPU0_SB_DQ<17>")
	)
	(segment
		(start 299.196252 -301.83836)
		(end 299.574712 -301.4599)
		(width 0.14478)
		(layer "In4.Cu")
		(net "M_D_CPU0_SB_DQ<17>")
	)
	(segment
		(start 306.17922 -301.15129)
		(end 306.333398 -301.305468)
		(width 0.14478)
		(layer "In4.Cu")
		(net "M_D_CPU0_SB_DQ<17>")
	)
	(segment
		(start 300.791372 -301.245016)
		(end 300.954186 -301.082202)
		(width 0.14478)
		(layer "In4.Cu")
		(net "M_D_CPU0_SB_DQ<17>")
	)
	(segment
		(start 300.791372 -301.689008)
		(end 300.791372 -301.245016)
		(width 0.14478)
		(layer "In4.Cu")
		(net "M_D_CPU0_SB_DQ<17>")
	)
	(segment
		(start 304.686462 -302.310038)
		(end 305.84521 -301.15129)
		(width 0.14478)
		(layer "In4.Cu")
		(net "M_D_CPU0_SB_DQ<17>")
	)
	(segment
		(start 326.367902 -284.938724)
		(end 326.367648 -284.938724)
		(width 0.0889)
		(layer "In4.Cu")
		(net "M_D_CPU0_SB_DQ<17>")
	)
	(segment
		(start 326.93356 -284.93847)
		(end 326.947276 -284.946344)
		(width 0.0889)
		(layer "In4.Cu")
		(net "M_D_CPU0_SB_DQ<17>")
	)
	(segment
		(start 340.435184 -284.881574)
		(end 340.281006 -284.616144)
		(width 0.0889)
		(layer "In4.Cu")
		(net "M_D_CPU0_SB_DQ<17>")
	)
	(segment
		(start 323.898514 -285.37662)
		(end 324.24751 -285.37662)
		(width 0.0889)
		(layer "In4.Cu")
		(net "M_D_CPU0_SB_DQ<17>")
	)
	(segment
		(start 306.747926 -301.71771)
		(end 307.005736 -301.4599)
		(width 0.14478)
		(layer "In4.Cu")
		(net "M_D_CPU0_SB_DQ<17>")
	)
	(segment
		(start 286.714184 -302.68291)
		(end 286.944816 -302.68291)
		(width 0.14478)
		(layer "In4.Cu")
		(net "M_D_CPU0_SB_DQ<17>")
	)
	(segment
		(start 324.615048 -285.056072)
		(end 325.932292 -285.056072)
		(width 0.0889)
		(layer "In4.Cu")
		(net "M_D_CPU0_SB_DQ<17>")
	)
	(segment
		(start 330.119736 -284.94355)
		(end 330.128118 -284.938724)
		(width 0.0889)
		(layer "In4.Cu")
		(net "M_D_CPU0_SB_DQ<17>")
	)
	(segment
		(start 302.412654 -302.310038)
		(end 304.686462 -302.310038)
		(width 0.14478)
		(layer "In4.Cu")
		(net "M_D_CPU0_SB_DQ<17>")
	)
	(segment
		(start 339.519768 -284.94355)
		(end 339.52815 -284.938724)
		(width 0.0889)
		(layer "In4.Cu")
		(net "M_D_CPU0_SB_DQ<17>")
	)
	(segment
		(start 308.258464 -301.563532)
		(end 308.258464 -300.736)
		(width 0.14478)
		(layer "In4.Cu")
		(net "M_D_CPU0_SB_DQ<17>")
	)
	(segment
		(start 287.10763 -302.09998)
		(end 287.270444 -301.937166)
		(width 0.14478)
		(layer "In4.Cu")
		(net "M_D_CPU0_SB_DQ<17>")
	)
	(segment
		(start 300.006004 -301.4599)
		(end 300.389036 -301.842932)
		(width 0.14478)
		(layer "In4.Cu")
		(net "M_D_CPU0_SB_DQ<17>")
	)
	(segment
		(start 331.634084 -284.938724)
		(end 331.642466 -284.94355)
		(width 0.0889)
		(layer "In4.Cu")
		(net "M_D_CPU0_SB_DQ<17>")
	)
	(segment
		(start 293.776654 -301.08271)
		(end 295.003982 -302.310038)
		(width 0.14478)
		(layer "In4.Cu")
		(net "M_D_CPU0_SB_DQ<17>")
	)
	(segment
		(start 326.917812 -284.929326)
		(end 326.93356 -284.93847)
		(width 0.0889)
		(layer "In4.Cu")
		(net "M_D_CPU0_SB_DQ<17>")
	)
	(segment
		(start 293.168578 -301.460154)
		(end 293.546022 -301.08271)
		(width 0.14478)
		(layer "In4.Cu")
		(net "M_D_CPU0_SB_DQ<17>")
	)
	(segment
		(start 293.546022 -301.08271)
		(end 293.776654 -301.08271)
		(width 0.14478)
		(layer "In4.Cu")
		(net "M_D_CPU0_SB_DQ<17>")
	)
	(segment
		(start 308.104286 -301.71771)
		(end 308.258464 -301.563532)
		(width 0.14478)
		(layer "In4.Cu")
		(net "M_D_CPU0_SB_DQ<17>")
	)
	(segment
		(start 306.333398 -301.305468)
		(end 306.333398 -301.551086)
		(width 0.14478)
		(layer "In4.Cu")
		(net "M_D_CPU0_SB_DQ<17>")
	)
	(segment
		(start 295.003982 -302.310038)
		(end 297.168062 -302.310038)
		(width 0.14478)
		(layer "In4.Cu")
		(net "M_D_CPU0_SB_DQ<17>")
	)
	(segment
		(start 286.55137 -302.09998)
		(end 286.55137 -302.520096)
		(width 0.14478)
		(layer "In4.Cu")
		(net "M_D_CPU0_SB_DQ<17>")
	)
	(arc
		(start 339.154008 -284.938724)
		(mid 339.336259 -284.989074)
		(end 339.519768 -284.94355)
		(width 0.0889)
		(layer "In4.Cu")
		(net "M_D_CPU0_SB_DQ<17>")
	)
	(arc
		(start 328.248264 -284.938724)
		(mid 328.53122 -284.862547)
		(end 328.814176 -284.938724)
		(width 0.0889)
		(layer "In4.Cu")
		(net "M_D_CPU0_SB_DQ<17>")
	)
	(arc
		(start 331.068172 -284.938724)
		(mid 331.351128 -284.862547)
		(end 331.634084 -284.938724)
		(width 0.0889)
		(layer "In4.Cu")
		(net "M_D_CPU0_SB_DQ<17>")
	)
	(arc
		(start 335.402428 -284.94355)
		(mid 335.585936 -284.989044)
		(end 335.768188 -284.938724)
		(width 0.0889)
		(layer "In4.Cu")
		(net "M_D_CPU0_SB_DQ<17>")
	)
	(arc
		(start 327.321926 -284.930088)
		(mid 327.598909 -284.862284)
		(end 327.873614 -284.938724)
		(width 0.0889)
		(layer "In4.Cu")
		(net "M_D_CPU0_SB_DQ<17>")
	)
	(arc
		(start 328.814176 -284.938724)
		(mid 329.00112 -284.988979)
		(end 329.188064 -284.938724)
		(width 0.0889)
		(layer "In4.Cu")
		(net "M_D_CPU0_SB_DQ<17>")
	)
	(arc
		(start 327.873614 -284.938724)
		(mid 328.056119 -284.989201)
		(end 328.239882 -284.94355)
		(width 0.0889)
		(layer "In4.Cu")
		(net "M_D_CPU0_SB_DQ<17>")
	)
	(arc
		(start 332.008226 -284.938724)
		(mid 332.291182 -284.862547)
		(end 332.574138 -284.938724)
		(width 0.0889)
		(layer "In4.Cu")
		(net "M_D_CPU0_SB_DQ<17>")
	)
	(arc
		(start 325.932292 -285.056072)
		(mid 326.157857 -285.026212)
		(end 326.367902 -284.938724)
		(width 0.0889)
		(layer "In4.Cu")
		(net "M_D_CPU0_SB_DQ<17>")
	)
	(arc
		(start 334.828134 -284.938724)
		(mid 335.11109 -284.862547)
		(end 335.394046 -284.938724)
		(width 0.0889)
		(layer "In4.Cu")
		(net "M_D_CPU0_SB_DQ<17>")
	)
	(arc
		(start 338.588096 -284.938724)
		(mid 338.871052 -284.862547)
		(end 339.154008 -284.938724)
		(width 0.0889)
		(layer "In4.Cu")
		(net "M_D_CPU0_SB_DQ<17>")
	)
	(arc
		(start 336.708242 -284.938724)
		(mid 336.991198 -284.862547)
		(end 337.274154 -284.938724)
		(width 0.0889)
		(layer "In4.Cu")
		(net "M_D_CPU0_SB_DQ<17>")
	)
	(arc
		(start 330.128118 -284.938724)
		(mid 330.411074 -284.862547)
		(end 330.69403 -284.938724)
		(width 0.0889)
		(layer "In4.Cu")
		(net "M_D_CPU0_SB_DQ<17>")
	)
	(arc
		(start 332.948026 -284.938724)
		(mid 333.230982 -284.862547)
		(end 333.513938 -284.938724)
		(width 0.0889)
		(layer "In4.Cu")
		(net "M_D_CPU0_SB_DQ<17>")
	)
	(arc
		(start 333.88808 -284.938724)
		(mid 334.171036 -284.862547)
		(end 334.453992 -284.938724)
		(width 0.0889)
		(layer "In4.Cu")
		(net "M_D_CPU0_SB_DQ<17>")
	)
	(arc
		(start 332.574138 -284.938724)
		(mid 332.761082 -284.988979)
		(end 332.948026 -284.938724)
		(width 0.0889)
		(layer "In4.Cu")
		(net "M_D_CPU0_SB_DQ<17>")
	)
	(arc
		(start 337.648042 -284.938724)
		(mid 337.930998 -284.862547)
		(end 338.213954 -284.938724)
		(width 0.0889)
		(layer "In4.Cu")
		(net "M_D_CPU0_SB_DQ<17>")
	)
	(arc
		(start 329.188064 -284.938724)
		(mid 329.47102 -284.862547)
		(end 329.753976 -284.938724)
		(width 0.0889)
		(layer "In4.Cu")
		(net "M_D_CPU0_SB_DQ<17>")
	)
	(arc
		(start 335.768188 -284.938724)
		(mid 336.051144 -284.862547)
		(end 336.3341 -284.938724)
		(width 0.0889)
		(layer "In4.Cu")
		(net "M_D_CPU0_SB_DQ<17>")
	)
	(arc
		(start 337.274154 -284.938724)
		(mid 337.461098 -284.988979)
		(end 337.648042 -284.938724)
		(width 0.0889)
		(layer "In4.Cu")
		(net "M_D_CPU0_SB_DQ<17>")
	)
	(arc
		(start 340.102444 -284.94355)
		(mid 340.255314 -284.988191)
		(end 340.412832 -284.964886)
		(width 0.0889)
		(layer "In4.Cu")
		(net "M_D_CPU0_SB_DQ<17>")
	)
	(arc
		(start 338.213954 -284.938724)
		(mid 338.396205 -284.989074)
		(end 338.579714 -284.94355)
		(width 0.0889)
		(layer "In4.Cu")
		(net "M_D_CPU0_SB_DQ<17>")
	)
	(arc
		(start 333.513938 -284.938724)
		(mid 333.696189 -284.989074)
		(end 333.879698 -284.94355)
		(width 0.0889)
		(layer "In4.Cu")
		(net "M_D_CPU0_SB_DQ<17>")
	)
	(arc
		(start 336.342482 -284.94355)
		(mid 336.52599 -284.989044)
		(end 336.708242 -284.938724)
		(width 0.0889)
		(layer "In4.Cu")
		(net "M_D_CPU0_SB_DQ<17>")
	)
	(arc
		(start 331.642466 -284.94355)
		(mid 331.825974 -284.989044)
		(end 332.008226 -284.938724)
		(width 0.0889)
		(layer "In4.Cu")
		(net "M_D_CPU0_SB_DQ<17>")
	)
	(arc
		(start 329.753976 -284.938724)
		(mid 329.936227 -284.989074)
		(end 330.119736 -284.94355)
		(width 0.0889)
		(layer "In4.Cu")
		(net "M_D_CPU0_SB_DQ<17>")
	)
	(arc
		(start 326.367648 -284.938724)
		(mid 326.641503 -284.862374)
		(end 326.917812 -284.929326)
		(width 0.0889)
		(layer "In4.Cu")
		(net "M_D_CPU0_SB_DQ<17>")
	)
	(arc
		(start 334.453992 -284.938724)
		(mid 334.636243 -284.989074)
		(end 334.819752 -284.94355)
		(width 0.0889)
		(layer "In4.Cu")
		(net "M_D_CPU0_SB_DQ<17>")
	)
	(arc
		(start 330.702412 -284.94355)
		(mid 330.88592 -284.989044)
		(end 331.068172 -284.938724)
		(width 0.0889)
		(layer "In4.Cu")
		(net "M_D_CPU0_SB_DQ<17>")
	)
	(arc
		(start 324.534784 -285.089346)
		(mid 324.571595 -285.064686)
		(end 324.615048 -285.056072)
		(width 0.0889)
		(layer "In4.Cu")
		(net "M_D_CPU0_SB_DQ<17>")
	)
	(arc
		(start 339.52815 -284.938724)
		(mid 339.811106 -284.862547)
		(end 340.094062 -284.938724)
		(width 0.0889)
		(layer "In4.Cu")
		(net "M_D_CPU0_SB_DQ<17>")
	)
	(arc
		(start 326.947276 -284.946344)
		(mid 327.128206 -284.988822)
		(end 327.307194 -284.938724)
		(width 0.0889)
		(layer "In4.Cu")
		(net "M_D_CPU0_SB_DQ<17>")
	)
	(segment
		(start 339.337904 -283.5402)
		(end 338.871052 -283.806138)
		(width 0.10668)
		(layer "F.Cu")
		(net "M_D_CPU0_SB_DQ<16>")
	)
	(segment
		(start 292.717982 -299.760132)
		(end 292.879526 -299.921676)
		(width 0.14478)
		(layer "In4.Cu")
		(net "M_D_CPU0_SB_DQ<16>")
	)
	(segment
		(start 298.684696 -299.987208)
		(end 298.84624 -300.148752)
		(width 0.14478)
		(layer "In4.Cu")
		(net "M_D_CPU0_SB_DQ<16>")
	)
	(segment
		(start 286.830008 -300.93031)
		(end 286.990028 -300.77029)
		(width 0.14478)
		(layer "In4.Cu")
		(net "M_D_CPU0_SB_DQ<16>")
	)
	(segment
		(start 292.879526 -299.921676)
		(end 292.879526 -299.994828)
		(width 0.14478)
		(layer "In4.Cu")
		(net "M_D_CPU0_SB_DQ<16>")
	)
	(segment
		(start 296.882058 -300.484286)
		(end 296.882058 -300.753526)
		(width 0.14478)
		(layer "In4.Cu")
		(net "M_D_CPU0_SB_DQ<16>")
	)
	(segment
		(start 293.592504 -299.760132)
		(end 293.901876 -299.760132)
		(width 0.14478)
		(layer "In4.Cu")
		(net "M_D_CPU0_SB_DQ<16>")
	)
	(segment
		(start 286.433768 -300.77029)
		(end 286.593788 -300.93031)
		(width 0.14478)
		(layer "In4.Cu")
		(net "M_D_CPU0_SB_DQ<16>")
	)
	(segment
		(start 338.684108 -284.128718)
		(end 338.69249 -284.133544)
		(width 0.0889)
		(layer "In4.Cu")
		(net "M_D_CPU0_SB_DQ<16>")
	)
	(segment
		(start 288.666174 -300.34103)
		(end 288.953194 -300.34103)
		(width 0.14478)
		(layer "In4.Cu")
		(net "M_D_CPU0_SB_DQ<16>")
	)
	(segment
		(start 293.43096 -299.994828)
		(end 293.43096 -299.921676)
		(width 0.14478)
		(layer "In4.Cu")
		(net "M_D_CPU0_SB_DQ<16>")
	)
	(segment
		(start 289.087814 -300.47565)
		(end 289.087814 -300.74489)
		(width 0.14478)
		(layer "In4.Cu")
		(net "M_D_CPU0_SB_DQ<16>")
	)
	(segment
		(start 339.02523 -284.071568)
		(end 338.871052 -283.806138)
		(width 0.0889)
		(layer "In4.Cu")
		(net "M_D_CPU0_SB_DQ<16>")
	)
	(segment
		(start 299.23613 -299.987208)
		(end 299.23613 -299.921676)
		(width 0.14478)
		(layer "In4.Cu")
		(net "M_D_CPU0_SB_DQ<16>")
	)
	(segment
		(start 302.762158 -300.134528)
		(end 302.762158 -300.705012)
		(width 0.14478)
		(layer "In4.Cu")
		(net "M_D_CPU0_SB_DQ<16>")
	)
	(segment
		(start 288.396934 -300.61027)
		(end 288.666174 -300.34103)
		(width 0.14478)
		(layer "In4.Cu")
		(net "M_D_CPU0_SB_DQ<16>")
	)
	(segment
		(start 290.928298 -299.760132)
		(end 291.089842 -299.921676)
		(width 0.14478)
		(layer "In4.Cu")
		(net "M_D_CPU0_SB_DQ<16>")
	)
	(segment
		(start 291.251386 -300.153832)
		(end 291.479732 -300.153832)
		(width 0.14478)
		(layer "In4.Cu")
		(net "M_D_CPU0_SB_DQ<16>")
	)
	(segment
		(start 300.335188 -299.921676)
		(end 300.335188 -299.992288)
		(width 0.14478)
		(layer "In4.Cu")
		(net "M_D_CPU0_SB_DQ<16>")
	)
	(segment
		(start 285.877508 -300.77029)
		(end 285.877508 -300.50105)
		(width 0.14478)
		(layer "In4.Cu")
		(net "M_D_CPU0_SB_DQ<16>")
	)
	(segment
		(start 329.284076 -284.128718)
		(end 329.292458 -284.133544)
		(width 0.0889)
		(layer "In4.Cu")
		(net "M_D_CPU0_SB_DQ<16>")
	)
	(segment
		(start 302.543718 -299.916088)
		(end 302.762158 -300.134528)
		(width 0.14478)
		(layer "In4.Cu")
		(net "M_D_CPU0_SB_DQ<16>")
	)
	(segment
		(start 294.752014 -300.61027)
		(end 296.199814 -300.61027)
		(width 0.14478)
		(layer "In4.Cu")
		(net "M_D_CPU0_SB_DQ<16>")
	)
	(segment
		(start 298.523152 -299.760132)
		(end 298.684696 -299.921676)
		(width 0.14478)
		(layer "In4.Cu")
		(net "M_D_CPU0_SB_DQ<16>")
	)
	(segment
		(start 287.655508 -300.61027)
		(end 288.396934 -300.61027)
		(width 0.14478)
		(layer "In4.Cu")
		(net "M_D_CPU0_SB_DQ<16>")
	)
	(segment
		(start 306.940712 -300.14291)
		(end 307.32349 -299.760132)
		(width 0.14478)
		(layer "In4.Cu")
		(net "M_D_CPU0_SB_DQ<16>")
	)
	(segment
		(start 339.002878 -284.15488)
		(end 339.02523 -284.071568)
		(width 0.0889)
		(layer "In4.Cu")
		(net "M_D_CPU0_SB_DQ<16>")
	)
	(segment
		(start 307.77688 -299.760132)
		(end 323.069712 -284.4673)
		(width 0.14478)
		(layer "In4.Cu")
		(net "M_D_CPU0_SB_DQ<16>")
	)
	(segment
		(start 306.71008 -300.14291)
		(end 306.940712 -300.14291)
		(width 0.14478)
		(layer "In4.Cu")
		(net "M_D_CPU0_SB_DQ<16>")
	)
	(segment
		(start 301.291752 -299.760132)
		(end 301.672752 -300.141132)
		(width 0.14478)
		(layer "In4.Cu")
		(net "M_D_CPU0_SB_DQ<16>")
	)
	(segment
		(start 298.684696 -299.921676)
		(end 298.684696 -299.987208)
		(width 0.14478)
		(layer "In4.Cu")
		(net "M_D_CPU0_SB_DQ<16>")
	)
	(segment
		(start 303.981104 -299.937932)
		(end 304.20945 -299.937932)
		(width 0.14478)
		(layer "In4.Cu")
		(net "M_D_CPU0_SB_DQ<16>")
	)
	(segment
		(start 326.140318 -284.179264)
		(end 326.650858 -284.179264)
		(width 0.0889)
		(layer "In4.Cu")
		(net "M_D_CPU0_SB_DQ<16>")
	)
	(segment
		(start 293.269416 -300.156372)
		(end 293.43096 -299.994828)
		(width 0.14478)
		(layer "In4.Cu")
		(net "M_D_CPU0_SB_DQ<16>")
	)
	(segment
		(start 291.089842 -299.992288)
		(end 291.251386 -300.153832)
		(width 0.14478)
		(layer "In4.Cu")
		(net "M_D_CPU0_SB_DQ<16>")
	)
	(segment
		(start 298.431712 -299.760132)
		(end 298.523152 -299.760132)
		(width 0.14478)
		(layer "In4.Cu")
		(net "M_D_CPU0_SB_DQ<16>")
	)
	(segment
		(start 331.52969 -284.133544)
		(end 331.538072 -284.128718)
		(width 0.0889)
		(layer "In4.Cu")
		(net "M_D_CPU0_SB_DQ<16>")
	)
	(segment
		(start 300.335188 -299.992288)
		(end 300.496732 -300.153832)
		(width 0.14478)
		(layer "In4.Cu")
		(net "M_D_CPU0_SB_DQ<16>")
	)
	(segment
		(start 303.040796 -300.98365)
		(end 303.658016 -300.98365)
		(width 0.14478)
		(layer "In4.Cu")
		(net "M_D_CPU0_SB_DQ<16>")
	)
	(segment
		(start 286.990028 -300.50105)
		(end 287.150048 -300.34103)
		(width 0.14478)
		(layer "In4.Cu")
		(net "M_D_CPU0_SB_DQ<16>")
	)
	(segment
		(start 304.726594 -300.98365)
		(end 305.950112 -299.760132)
		(width 0.14478)
		(layer "In4.Cu")
		(net "M_D_CPU0_SB_DQ<16>")
	)
	(segment
		(start 291.641276 -299.992288)
		(end 291.641276 -299.921676)
		(width 0.14478)
		(layer "In4.Cu")
		(net "M_D_CPU0_SB_DQ<16>")
	)
	(segment
		(start 300.886622 -299.921676)
		(end 301.048166 -299.760132)
		(width 0.14478)
		(layer "In4.Cu")
		(net "M_D_CPU0_SB_DQ<16>")
	)
	(segment
		(start 301.048166 -299.760132)
		(end 301.291752 -299.760132)
		(width 0.14478)
		(layer "In4.Cu")
		(net "M_D_CPU0_SB_DQ<16>")
	)
	(segment
		(start 304.370994 -300.822106)
		(end 304.532538 -300.98365)
		(width 0.14478)
		(layer "In4.Cu")
		(net "M_D_CPU0_SB_DQ<16>")
	)
	(segment
		(start 323.903594 -284.4673)
		(end 324.20433 -284.4673)
		(width 0.0889)
		(layer "In4.Cu")
		(net "M_D_CPU0_SB_DQ<16>")
	)
	(segment
		(start 296.460418 -300.349666)
		(end 296.747438 -300.349666)
		(width 0.14478)
		(layer "In4.Cu")
		(net "M_D_CPU0_SB_DQ<16>")
	)
	(segment
		(start 289.222434 -300.87951)
		(end 289.509454 -300.87951)
		(width 0.14478)
		(layer "In4.Cu")
		(net "M_D_CPU0_SB_DQ<16>")
	)
	(segment
		(start 303.658016 -300.98365)
		(end 303.81956 -300.822106)
		(width 0.14478)
		(layer "In4.Cu")
		(net "M_D_CPU0_SB_DQ<16>")
	)
	(segment
		(start 324.20433 -284.4673)
		(end 324.725538 -283.946092)
		(width 0.0889)
		(layer "In4.Cu")
		(net "M_D_CPU0_SB_DQ<16>")
	)
	(segment
		(start 286.433768 -300.50105)
		(end 286.433768 -300.77029)
		(width 0.14478)
		(layer "In4.Cu")
		(net "M_D_CPU0_SB_DQ<16>")
	)
	(segment
		(start 296.199814 -300.61027)
		(end 296.460418 -300.349666)
		(width 0.14478)
		(layer "In4.Cu")
		(net "M_D_CPU0_SB_DQ<16>")
	)
	(segment
		(start 291.479732 -300.153832)
		(end 291.641276 -299.992288)
		(width 0.14478)
		(layer "In4.Cu")
		(net "M_D_CPU0_SB_DQ<16>")
	)
	(segment
		(start 332.469744 -284.133544)
		(end 332.478126 -284.128718)
		(width 0.0889)
		(layer "In4.Cu")
		(net "M_D_CPU0_SB_DQ<16>")
	)
	(segment
		(start 291.641276 -299.921676)
		(end 291.80282 -299.760132)
		(width 0.14478)
		(layer "In4.Cu")
		(net "M_D_CPU0_SB_DQ<16>")
	)
	(segment
		(start 305.950112 -299.760132)
		(end 306.327302 -299.760132)
		(width 0.14478)
		(layer "In4.Cu")
		(net "M_D_CPU0_SB_DQ<16>")
	)
	(segment
		(start 291.80282 -299.760132)
		(end 292.717982 -299.760132)
		(width 0.14478)
		(layer "In4.Cu")
		(net "M_D_CPU0_SB_DQ<16>")
	)
	(segment
		(start 287.150048 -300.34103)
		(end 287.386268 -300.34103)
		(width 0.14478)
		(layer "In4.Cu")
		(net "M_D_CPU0_SB_DQ<16>")
	)
	(segment
		(start 297.016678 -300.888146)
		(end 297.303698 -300.888146)
		(width 0.14478)
		(layer "In4.Cu")
		(net "M_D_CPU0_SB_DQ<16>")
	)
	(segment
		(start 285.717488 -300.93031)
		(end 285.877508 -300.77029)
		(width 0.14478)
		(layer "In4.Cu")
		(net "M_D_CPU0_SB_DQ<16>")
	)
	(segment
		(start 286.273748 -300.34103)
		(end 286.433768 -300.50105)
		(width 0.14478)
		(layer "In4.Cu")
		(net "M_D_CPU0_SB_DQ<16>")
	)
	(segment
		(start 288.953194 -300.34103)
		(end 289.087814 -300.47565)
		(width 0.14478)
		(layer "In4.Cu")
		(net "M_D_CPU0_SB_DQ<16>")
	)
	(segment
		(start 300.725078 -300.153832)
		(end 300.886622 -299.992288)
		(width 0.14478)
		(layer "In4.Cu")
		(net "M_D_CPU0_SB_DQ<16>")
	)
	(segment
		(start 328.333608 -284.122622)
		(end 328.344022 -284.128718)
		(width 0.0889)
		(layer "In4.Cu")
		(net "M_D_CPU0_SB_DQ<16>")
	)
	(segment
		(start 302.762158 -300.705012)
		(end 303.040796 -300.98365)
		(width 0.14478)
		(layer "In4.Cu")
		(net "M_D_CPU0_SB_DQ<16>")
	)
	(segment
		(start 307.32349 -299.760132)
		(end 307.77688 -299.760132)
		(width 0.14478)
		(layer "In4.Cu")
		(net "M_D_CPU0_SB_DQ<16>")
	)
	(segment
		(start 293.43096 -299.921676)
		(end 293.592504 -299.760132)
		(width 0.14478)
		(layer "In4.Cu")
		(net "M_D_CPU0_SB_DQ<16>")
	)
	(segment
		(start 300.886622 -299.992288)
		(end 300.886622 -299.921676)
		(width 0.14478)
		(layer "In4.Cu")
		(net "M_D_CPU0_SB_DQ<16>")
	)
	(segment
		(start 297.303698 -300.888146)
		(end 298.431712 -299.760132)
		(width 0.14478)
		(layer "In4.Cu")
		(net "M_D_CPU0_SB_DQ<16>")
	)
	(segment
		(start 284.736032 -300.185074)
		(end 285.481268 -300.93031)
		(width 0.14478)
		(layer "In4.Cu")
		(net "M_D_CPU0_SB_DQ<16>")
	)
	(segment
		(start 337.16976 -284.133544)
		(end 337.178142 -284.128718)
		(width 0.0889)
		(layer "In4.Cu")
		(net "M_D_CPU0_SB_DQ<16>")
	)
	(segment
		(start 325.907146 -283.946092)
		(end 326.140318 -284.179264)
		(width 0.0889)
		(layer "In4.Cu")
		(net "M_D_CPU0_SB_DQ<16>")
	)
	(segment
		(start 286.037528 -300.34103)
		(end 286.273748 -300.34103)
		(width 0.14478)
		(layer "In4.Cu")
		(net "M_D_CPU0_SB_DQ<16>")
	)
	(segment
		(start 285.481268 -300.93031)
		(end 285.717488 -300.93031)
		(width 0.14478)
		(layer "In4.Cu")
		(net "M_D_CPU0_SB_DQ<16>")
	)
	(segment
		(start 323.069712 -284.4673)
		(end 323.903594 -284.4673)
		(width 0.14478)
		(layer "In4.Cu")
		(net "M_D_CPU0_SB_DQ<16>")
	)
	(segment
		(start 299.397674 -299.760132)
		(end 300.173644 -299.760132)
		(width 0.14478)
		(layer "In4.Cu")
		(net "M_D_CPU0_SB_DQ<16>")
	)
	(segment
		(start 285.877508 -300.50105)
		(end 286.037528 -300.34103)
		(width 0.14478)
		(layer "In4.Cu")
		(net "M_D_CPU0_SB_DQ<16>")
	)
	(segment
		(start 304.20945 -299.937932)
		(end 304.370994 -300.099476)
		(width 0.14478)
		(layer "In4.Cu")
		(net "M_D_CPU0_SB_DQ<16>")
	)
	(segment
		(start 298.84624 -300.148752)
		(end 299.074586 -300.148752)
		(width 0.14478)
		(layer "In4.Cu")
		(net "M_D_CPU0_SB_DQ<16>")
	)
	(segment
		(start 301.672752 -300.141132)
		(end 302.046894 -300.141132)
		(width 0.14478)
		(layer "In4.Cu")
		(net "M_D_CPU0_SB_DQ<16>")
	)
	(segment
		(start 336.229706 -284.133544)
		(end 336.238088 -284.128718)
		(width 0.0889)
		(layer "In4.Cu")
		(net "M_D_CPU0_SB_DQ<16>")
	)
	(segment
		(start 287.386268 -300.34103)
		(end 287.655508 -300.61027)
		(width 0.14478)
		(layer "In4.Cu")
		(net "M_D_CPU0_SB_DQ<16>")
	)
	(segment
		(start 303.81956 -300.099476)
		(end 303.981104 -299.937932)
		(width 0.14478)
		(layer "In4.Cu")
		(net "M_D_CPU0_SB_DQ<16>")
	)
	(segment
		(start 289.087814 -300.74489)
		(end 289.222434 -300.87951)
		(width 0.14478)
		(layer "In4.Cu")
		(net "M_D_CPU0_SB_DQ<16>")
	)
	(segment
		(start 286.990028 -300.77029)
		(end 286.990028 -300.50105)
		(width 0.14478)
		(layer "In4.Cu")
		(net "M_D_CPU0_SB_DQ<16>")
	)
	(segment
		(start 290.629086 -299.759878)
		(end 290.62934 -299.760132)
		(width 0.14478)
		(layer "In4.Cu")
		(net "M_D_CPU0_SB_DQ<16>")
	)
	(segment
		(start 300.496732 -300.153832)
		(end 300.725078 -300.153832)
		(width 0.14478)
		(layer "In4.Cu")
		(net "M_D_CPU0_SB_DQ<16>")
	)
	(segment
		(start 296.882058 -300.753526)
		(end 297.016678 -300.888146)
		(width 0.14478)
		(layer "In4.Cu")
		(net "M_D_CPU0_SB_DQ<16>")
	)
	(segment
		(start 328.709782 -284.133544)
		(end 328.718164 -284.128718)
		(width 0.0889)
		(layer "In4.Cu")
		(net "M_D_CPU0_SB_DQ<16>")
	)
	(segment
		(start 292.879526 -299.994828)
		(end 293.04107 -300.156372)
		(width 0.14478)
		(layer "In4.Cu")
		(net "M_D_CPU0_SB_DQ<16>")
	)
	(segment
		(start 293.04107 -300.156372)
		(end 293.269416 -300.156372)
		(width 0.14478)
		(layer "In4.Cu")
		(net "M_D_CPU0_SB_DQ<16>")
	)
	(segment
		(start 324.725538 -283.946092)
		(end 325.907146 -283.946092)
		(width 0.0889)
		(layer "In4.Cu")
		(net "M_D_CPU0_SB_DQ<16>")
	)
	(segment
		(start 290.62934 -299.760132)
		(end 290.928298 -299.760132)
		(width 0.14478)
		(layer "In4.Cu")
		(net "M_D_CPU0_SB_DQ<16>")
	)
	(segment
		(start 337.744054 -284.128718)
		(end 337.752436 -284.133544)
		(width 0.0889)
		(layer "In4.Cu")
		(net "M_D_CPU0_SB_DQ<16>")
	)
	(segment
		(start 304.370994 -300.099476)
		(end 304.370994 -300.822106)
		(width 0.14478)
		(layer "In4.Cu")
		(net "M_D_CPU0_SB_DQ<16>")
	)
	(segment
		(start 300.173644 -299.760132)
		(end 300.335188 -299.921676)
		(width 0.14478)
		(layer "In4.Cu")
		(net "M_D_CPU0_SB_DQ<16>")
	)
	(segment
		(start 302.046894 -300.141132)
		(end 302.271938 -299.916088)
		(width 0.14478)
		(layer "In4.Cu")
		(net "M_D_CPU0_SB_DQ<16>")
	)
	(segment
		(start 327.403206 -284.128718)
		(end 327.411588 -284.133544)
		(width 0.0889)
		(layer "In4.Cu")
		(net "M_D_CPU0_SB_DQ<16>")
	)
	(segment
		(start 293.901876 -299.760132)
		(end 294.752014 -300.61027)
		(width 0.14478)
		(layer "In4.Cu")
		(net "M_D_CPU0_SB_DQ<16>")
	)
	(segment
		(start 306.327302 -299.760132)
		(end 306.71008 -300.14291)
		(width 0.14478)
		(layer "In4.Cu")
		(net "M_D_CPU0_SB_DQ<16>")
	)
	(segment
		(start 299.23613 -299.921676)
		(end 299.397674 -299.760132)
		(width 0.14478)
		(layer "In4.Cu")
		(net "M_D_CPU0_SB_DQ<16>")
	)
	(segment
		(start 289.509454 -300.87951)
		(end 290.629086 -299.759878)
		(width 0.14478)
		(layer "In4.Cu")
		(net "M_D_CPU0_SB_DQ<16>")
	)
	(segment
		(start 286.593788 -300.93031)
		(end 286.830008 -300.93031)
		(width 0.14478)
		(layer "In4.Cu")
		(net "M_D_CPU0_SB_DQ<16>")
	)
	(segment
		(start 304.532538 -300.98365)
		(end 304.726594 -300.98365)
		(width 0.14478)
		(layer "In4.Cu")
		(net "M_D_CPU0_SB_DQ<16>")
	)
	(segment
		(start 326.837802 -284.128464)
		(end 326.84339 -284.125162)
		(width 0.0889)
		(layer "In4.Cu")
		(net "M_D_CPU0_SB_DQ<16>")
	)
	(segment
		(start 291.089842 -299.921676)
		(end 291.089842 -299.992288)
		(width 0.14478)
		(layer "In4.Cu")
		(net "M_D_CPU0_SB_DQ<16>")
	)
	(segment
		(start 333.044038 -284.128718)
		(end 333.05242 -284.133544)
		(width 0.0889)
		(layer "In4.Cu")
		(net "M_D_CPU0_SB_DQ<16>")
	)
	(segment
		(start 333.984092 -284.128718)
		(end 333.992474 -284.133544)
		(width 0.0889)
		(layer "In4.Cu")
		(net "M_D_CPU0_SB_DQ<16>")
	)
	(segment
		(start 303.81956 -300.822106)
		(end 303.81956 -300.099476)
		(width 0.14478)
		(layer "In4.Cu")
		(net "M_D_CPU0_SB_DQ<16>")
	)
	(segment
		(start 299.074586 -300.148752)
		(end 299.23613 -299.987208)
		(width 0.14478)
		(layer "In4.Cu")
		(net "M_D_CPU0_SB_DQ<16>")
	)
	(segment
		(start 296.747438 -300.349666)
		(end 296.882058 -300.484286)
		(width 0.14478)
		(layer "In4.Cu")
		(net "M_D_CPU0_SB_DQ<16>")
	)
	(segment
		(start 302.271938 -299.916088)
		(end 302.543718 -299.916088)
		(width 0.14478)
		(layer "In4.Cu")
		(net "M_D_CPU0_SB_DQ<16>")
	)
	(arc
		(start 337.178142 -284.128718)
		(mid 337.461098 -284.052541)
		(end 337.744054 -284.128718)
		(width 0.0889)
		(layer "In4.Cu")
		(net "M_D_CPU0_SB_DQ<16>")
	)
	(arc
		(start 335.298034 -284.128718)
		(mid 335.58099 -284.052541)
		(end 335.863946 -284.128718)
		(width 0.0889)
		(layer "In4.Cu")
		(net "M_D_CPU0_SB_DQ<16>")
	)
	(arc
		(start 335.863946 -284.128718)
		(mid 336.046197 -284.179068)
		(end 336.229706 -284.133544)
		(width 0.0889)
		(layer "In4.Cu")
		(net "M_D_CPU0_SB_DQ<16>")
	)
	(arc
		(start 338.118196 -284.128718)
		(mid 338.401152 -284.052541)
		(end 338.684108 -284.128718)
		(width 0.0889)
		(layer "In4.Cu")
		(net "M_D_CPU0_SB_DQ<16>")
	)
	(arc
		(start 337.752436 -284.133544)
		(mid 337.935944 -284.179038)
		(end 338.118196 -284.128718)
		(width 0.0889)
		(layer "In4.Cu")
		(net "M_D_CPU0_SB_DQ<16>")
	)
	(arc
		(start 334.358234 -284.128718)
		(mid 334.64119 -284.052541)
		(end 334.924146 -284.128718)
		(width 0.0889)
		(layer "In4.Cu")
		(net "M_D_CPU0_SB_DQ<16>")
	)
	(arc
		(start 331.538072 -284.128718)
		(mid 331.821028 -284.052541)
		(end 332.103984 -284.128718)
		(width 0.0889)
		(layer "In4.Cu")
		(net "M_D_CPU0_SB_DQ<16>")
	)
	(arc
		(start 332.478126 -284.128718)
		(mid 332.761082 -284.052541)
		(end 333.044038 -284.128718)
		(width 0.0889)
		(layer "In4.Cu")
		(net "M_D_CPU0_SB_DQ<16>")
	)
	(arc
		(start 338.69249 -284.133544)
		(mid 338.84536 -284.178185)
		(end 339.002878 -284.15488)
		(width 0.0889)
		(layer "In4.Cu")
		(net "M_D_CPU0_SB_DQ<16>")
	)
	(arc
		(start 326.84339 -284.125162)
		(mid 327.123779 -284.052493)
		(end 327.403206 -284.128718)
		(width 0.0889)
		(layer "In4.Cu")
		(net "M_D_CPU0_SB_DQ<16>")
	)
	(arc
		(start 336.238088 -284.128718)
		(mid 336.521044 -284.052541)
		(end 336.804 -284.128718)
		(width 0.0889)
		(layer "In4.Cu")
		(net "M_D_CPU0_SB_DQ<16>")
	)
	(arc
		(start 328.718164 -284.128718)
		(mid 329.00112 -284.052541)
		(end 329.284076 -284.128718)
		(width 0.0889)
		(layer "In4.Cu")
		(net "M_D_CPU0_SB_DQ<16>")
	)
	(arc
		(start 327.777856 -284.128718)
		(mid 328.054923 -284.052447)
		(end 328.333608 -284.122622)
		(width 0.0889)
		(layer "In4.Cu")
		(net "M_D_CPU0_SB_DQ<16>")
	)
	(arc
		(start 333.992474 -284.133544)
		(mid 334.175982 -284.179038)
		(end 334.358234 -284.128718)
		(width 0.0889)
		(layer "In4.Cu")
		(net "M_D_CPU0_SB_DQ<16>")
	)
	(arc
		(start 331.16393 -284.128718)
		(mid 331.346181 -284.179068)
		(end 331.52969 -284.133544)
		(width 0.0889)
		(layer "In4.Cu")
		(net "M_D_CPU0_SB_DQ<16>")
	)
	(arc
		(start 328.344022 -284.128718)
		(mid 328.526273 -284.179068)
		(end 328.709782 -284.133544)
		(width 0.0889)
		(layer "In4.Cu")
		(net "M_D_CPU0_SB_DQ<16>")
	)
	(arc
		(start 333.41818 -284.128718)
		(mid 333.701136 -284.052541)
		(end 333.984092 -284.128718)
		(width 0.0889)
		(layer "In4.Cu")
		(net "M_D_CPU0_SB_DQ<16>")
	)
	(arc
		(start 334.924146 -284.128718)
		(mid 335.11109 -284.178973)
		(end 335.298034 -284.128718)
		(width 0.0889)
		(layer "In4.Cu")
		(net "M_D_CPU0_SB_DQ<16>")
	)
	(arc
		(start 329.292458 -284.133544)
		(mid 329.475966 -284.179038)
		(end 329.658218 -284.128718)
		(width 0.0889)
		(layer "In4.Cu")
		(net "M_D_CPU0_SB_DQ<16>")
	)
	(arc
		(start 332.103984 -284.128718)
		(mid 332.286235 -284.179068)
		(end 332.469744 -284.133544)
		(width 0.0889)
		(layer "In4.Cu")
		(net "M_D_CPU0_SB_DQ<16>")
	)
	(arc
		(start 333.05242 -284.133544)
		(mid 333.235928 -284.179038)
		(end 333.41818 -284.128718)
		(width 0.0889)
		(layer "In4.Cu")
		(net "M_D_CPU0_SB_DQ<16>")
	)
	(arc
		(start 326.650858 -284.179264)
		(mid 326.747676 -284.166193)
		(end 326.837802 -284.128464)
		(width 0.0889)
		(layer "In4.Cu")
		(net "M_D_CPU0_SB_DQ<16>")
	)
	(arc
		(start 329.658218 -284.128718)
		(mid 329.941174 -284.052541)
		(end 330.22413 -284.128718)
		(width 0.0889)
		(layer "In4.Cu")
		(net "M_D_CPU0_SB_DQ<16>")
	)
	(arc
		(start 327.411588 -284.133544)
		(mid 327.59535 -284.17916)
		(end 327.777856 -284.128718)
		(width 0.0889)
		(layer "In4.Cu")
		(net "M_D_CPU0_SB_DQ<16>")
	)
	(arc
		(start 336.804 -284.128718)
		(mid 336.986251 -284.179068)
		(end 337.16976 -284.133544)
		(width 0.0889)
		(layer "In4.Cu")
		(net "M_D_CPU0_SB_DQ<16>")
	)
	(arc
		(start 330.22413 -284.128718)
		(mid 330.411074 -284.178973)
		(end 330.598018 -284.128718)
		(width 0.0889)
		(layer "In4.Cu")
		(net "M_D_CPU0_SB_DQ<16>")
	)
	(arc
		(start 330.598018 -284.128718)
		(mid 330.880974 -284.052541)
		(end 331.16393 -284.128718)
		(width 0.0889)
		(layer "In4.Cu")
		(net "M_D_CPU0_SB_DQ<16>")
	)
	(segment
		(start 341.218012 -283.5402)
		(end 340.75116 -283.806138)
		(width 0.10668)
		(layer "F.Cu")
		(net "M_D_CPU0_SB_DQ<15>")
	)
	(segment
		(start 280.635964 -299.33519)
		(end 281.060906 -299.760132)
		(width 0.14478)
		(layer "In4.Cu")
		(net "M_D_CPU0_SB_DQ<15>")
	)
	(segment
		(start 293.893494 -298.913804)
		(end 294.739822 -299.760132)
		(width 0.14478)
		(layer "In4.Cu")
		(net "M_D_CPU0_SB_DQ<15>")
	)
	(segment
		(start 294.739822 -299.760132)
		(end 297.644566 -299.760132)
		(width 0.14478)
		(layer "In4.Cu")
		(net "M_D_CPU0_SB_DQ<15>")
	)
	(segment
		(start 307.840126 -298.909994)
		(end 322.83908 -283.91104)
		(width 0.14478)
		(layer "In4.Cu")
		(net "M_D_CPU0_SB_DQ<15>")
	)
	(segment
		(start 323.902324 -283.91104)
		(end 324.26529 -283.91104)
		(width 0.0889)
		(layer "In4.Cu")
		(net "M_D_CPU0_SB_DQ<15>")
	)
	(segment
		(start 329.284076 -283.483558)
		(end 329.292458 -283.478732)
		(width 0.0889)
		(layer "In4.Cu")
		(net "M_D_CPU0_SB_DQ<15>")
	)
	(segment
		(start 297.644566 -299.760132)
		(end 298.494704 -298.909994)
		(width 0.14478)
		(layer "In4.Cu")
		(net "M_D_CPU0_SB_DQ<15>")
	)
	(segment
		(start 322.83908 -283.91104)
		(end 323.902324 -283.91104)
		(width 0.14478)
		(layer "In4.Cu")
		(net "M_D_CPU0_SB_DQ<15>")
	)
	(segment
		(start 327.759822 -283.472382)
		(end 327.779888 -283.483812)
		(width 0.0889)
		(layer "In4.Cu")
		(net "M_D_CPU0_SB_DQ<15>")
	)
	(segment
		(start 337.16976 -283.478732)
		(end 337.178142 -283.483558)
		(width 0.0889)
		(layer "In4.Cu")
		(net "M_D_CPU0_SB_DQ<15>")
	)
	(segment
		(start 281.060906 -299.760132)
		(end 289.841686 -299.760132)
		(width 0.14478)
		(layer "In4.Cu")
		(net "M_D_CPU0_SB_DQ<15>")
	)
	(segment
		(start 289.841686 -299.760132)
		(end 290.688014 -298.913804)
		(width 0.14478)
		(layer "In4.Cu")
		(net "M_D_CPU0_SB_DQ<15>")
	)
	(segment
		(start 340.596982 -283.540708)
		(end 340.75116 -283.806138)
		(width 0.0889)
		(layer "In4.Cu")
		(net "M_D_CPU0_SB_DQ<15>")
	)
	(segment
		(start 327.37933 -283.49956)
		(end 327.407016 -283.483558)
		(width 0.0889)
		(layer "In4.Cu")
		(net "M_D_CPU0_SB_DQ<15>")
	)
	(segment
		(start 333.044038 -283.483558)
		(end 333.05242 -283.478732)
		(width 0.0889)
		(layer "In4.Cu")
		(net "M_D_CPU0_SB_DQ<15>")
	)
	(segment
		(start 301.22876 -298.909994)
		(end 301.683674 -299.364908)
		(width 0.14478)
		(layer "In4.Cu")
		(net "M_D_CPU0_SB_DQ<15>")
	)
	(segment
		(start 336.229706 -283.478732)
		(end 336.238088 -283.483558)
		(width 0.0889)
		(layer "In4.Cu")
		(net "M_D_CPU0_SB_DQ<15>")
	)
	(segment
		(start 328.709782 -283.478732)
		(end 328.718164 -283.483558)
		(width 0.0889)
		(layer "In4.Cu")
		(net "M_D_CPU0_SB_DQ<15>")
	)
	(segment
		(start 338.684108 -283.483558)
		(end 338.69249 -283.478732)
		(width 0.0889)
		(layer "In4.Cu")
		(net "M_D_CPU0_SB_DQ<15>")
	)
	(segment
		(start 331.52969 -283.478732)
		(end 331.538072 -283.483558)
		(width 0.0889)
		(layer "In4.Cu")
		(net "M_D_CPU0_SB_DQ<15>")
	)
	(segment
		(start 333.984092 -283.483558)
		(end 333.992474 -283.478732)
		(width 0.0889)
		(layer "In4.Cu")
		(net "M_D_CPU0_SB_DQ<15>")
	)
	(segment
		(start 306.013104 -298.909994)
		(end 307.840126 -298.909994)
		(width 0.14478)
		(layer "In4.Cu")
		(net "M_D_CPU0_SB_DQ<15>")
	)
	(segment
		(start 332.469744 -283.478732)
		(end 332.478126 -283.483558)
		(width 0.0889)
		(layer "In4.Cu")
		(net "M_D_CPU0_SB_DQ<15>")
	)
	(segment
		(start 298.494704 -298.909994)
		(end 301.22876 -298.909994)
		(width 0.14478)
		(layer "In4.Cu")
		(net "M_D_CPU0_SB_DQ<15>")
	)
	(segment
		(start 327.779888 -283.483812)
		(end 327.803764 -283.497782)
		(width 0.0889)
		(layer "In4.Cu")
		(net "M_D_CPU0_SB_DQ<15>")
	)
	(segment
		(start 305.55819 -299.364908)
		(end 306.013104 -298.909994)
		(width 0.14478)
		(layer "In4.Cu")
		(net "M_D_CPU0_SB_DQ<15>")
	)
	(segment
		(start 290.688014 -298.913804)
		(end 293.893494 -298.913804)
		(width 0.14478)
		(layer "In4.Cu")
		(net "M_D_CPU0_SB_DQ<15>")
	)
	(segment
		(start 340.500716 -283.515308)
		(end 340.596982 -283.540708)
		(width 0.0889)
		(layer "In4.Cu")
		(net "M_D_CPU0_SB_DQ<15>")
	)
	(segment
		(start 324.26529 -283.91104)
		(end 324.74408 -283.43225)
		(width 0.0889)
		(layer "In4.Cu")
		(net "M_D_CPU0_SB_DQ<15>")
	)
	(segment
		(start 324.74408 -283.43225)
		(end 326.651112 -283.43225)
		(width 0.0889)
		(layer "In4.Cu")
		(net "M_D_CPU0_SB_DQ<15>")
	)
	(segment
		(start 301.683674 -299.364908)
		(end 305.55819 -299.364908)
		(width 0.14478)
		(layer "In4.Cu")
		(net "M_D_CPU0_SB_DQ<15>")
	)
	(segment
		(start 337.744054 -283.483558)
		(end 337.752436 -283.478732)
		(width 0.0889)
		(layer "In4.Cu")
		(net "M_D_CPU0_SB_DQ<15>")
	)
	(arc
		(start 332.103984 -283.483558)
		(mid 332.286235 -283.433208)
		(end 332.469744 -283.478732)
		(width 0.0889)
		(layer "In4.Cu")
		(net "M_D_CPU0_SB_DQ<15>")
	)
	(arc
		(start 336.804 -283.483558)
		(mid 336.986251 -283.433208)
		(end 337.16976 -283.478732)
		(width 0.0889)
		(layer "In4.Cu")
		(net "M_D_CPU0_SB_DQ<15>")
	)
	(arc
		(start 326.839326 -283.483558)
		(mid 327.107295 -283.560381)
		(end 327.37933 -283.49956)
		(width 0.0889)
		(layer "In4.Cu")
		(net "M_D_CPU0_SB_DQ<15>")
	)
	(arc
		(start 334.358234 -283.483558)
		(mid 334.64119 -283.559735)
		(end 334.924146 -283.483558)
		(width 0.0889)
		(layer "In4.Cu")
		(net "M_D_CPU0_SB_DQ<15>")
	)
	(arc
		(start 329.292458 -283.478732)
		(mid 329.475966 -283.433238)
		(end 329.658218 -283.483558)
		(width 0.0889)
		(layer "In4.Cu")
		(net "M_D_CPU0_SB_DQ<15>")
	)
	(arc
		(start 339.05825 -283.483558)
		(mid 339.341206 -283.559735)
		(end 339.624162 -283.483558)
		(width 0.0889)
		(layer "In4.Cu")
		(net "M_D_CPU0_SB_DQ<15>")
	)
	(arc
		(start 338.118196 -283.483558)
		(mid 338.401152 -283.559735)
		(end 338.684108 -283.483558)
		(width 0.0889)
		(layer "In4.Cu")
		(net "M_D_CPU0_SB_DQ<15>")
	)
	(arc
		(start 338.69249 -283.478732)
		(mid 338.875998 -283.433238)
		(end 339.05825 -283.483558)
		(width 0.0889)
		(layer "In4.Cu")
		(net "M_D_CPU0_SB_DQ<15>")
	)
	(arc
		(start 333.05242 -283.478732)
		(mid 333.235928 -283.433238)
		(end 333.41818 -283.483558)
		(width 0.0889)
		(layer "In4.Cu")
		(net "M_D_CPU0_SB_DQ<15>")
	)
	(arc
		(start 333.992474 -283.478732)
		(mid 334.175982 -283.433238)
		(end 334.358234 -283.483558)
		(width 0.0889)
		(layer "In4.Cu")
		(net "M_D_CPU0_SB_DQ<15>")
	)
	(arc
		(start 332.478126 -283.483558)
		(mid 332.761082 -283.559735)
		(end 333.044038 -283.483558)
		(width 0.0889)
		(layer "In4.Cu")
		(net "M_D_CPU0_SB_DQ<15>")
	)
	(arc
		(start 339.99805 -283.483558)
		(mid 340.245646 -283.558736)
		(end 340.500716 -283.515308)
		(width 0.0889)
		(layer "In4.Cu")
		(net "M_D_CPU0_SB_DQ<15>")
	)
	(arc
		(start 327.407016 -283.483558)
		(mid 327.582001 -283.433614)
		(end 327.759822 -283.472382)
		(width 0.0889)
		(layer "In4.Cu")
		(net "M_D_CPU0_SB_DQ<15>")
	)
	(arc
		(start 333.41818 -283.483558)
		(mid 333.701136 -283.559735)
		(end 333.984092 -283.483558)
		(width 0.0889)
		(layer "In4.Cu")
		(net "M_D_CPU0_SB_DQ<15>")
	)
	(arc
		(start 339.624162 -283.483558)
		(mid 339.811106 -283.433303)
		(end 339.99805 -283.483558)
		(width 0.0889)
		(layer "In4.Cu")
		(net "M_D_CPU0_SB_DQ<15>")
	)
	(arc
		(start 327.803764 -283.497782)
		(mid 328.075701 -283.559608)
		(end 328.344022 -283.483558)
		(width 0.0889)
		(layer "In4.Cu")
		(net "M_D_CPU0_SB_DQ<15>")
	)
	(arc
		(start 335.298034 -283.483558)
		(mid 335.58099 -283.559735)
		(end 335.863946 -283.483558)
		(width 0.0889)
		(layer "In4.Cu")
		(net "M_D_CPU0_SB_DQ<15>")
	)
	(arc
		(start 330.598018 -283.483558)
		(mid 330.880974 -283.559735)
		(end 331.16393 -283.483558)
		(width 0.0889)
		(layer "In4.Cu")
		(net "M_D_CPU0_SB_DQ<15>")
	)
	(arc
		(start 328.718164 -283.483558)
		(mid 329.00112 -283.559735)
		(end 329.284076 -283.483558)
		(width 0.0889)
		(layer "In4.Cu")
		(net "M_D_CPU0_SB_DQ<15>")
	)
	(arc
		(start 335.863946 -283.483558)
		(mid 336.046197 -283.433208)
		(end 336.229706 -283.478732)
		(width 0.0889)
		(layer "In4.Cu")
		(net "M_D_CPU0_SB_DQ<15>")
	)
	(arc
		(start 326.651112 -283.43225)
		(mid 326.748626 -283.445405)
		(end 326.839326 -283.483558)
		(width 0.0889)
		(layer "In4.Cu")
		(net "M_D_CPU0_SB_DQ<15>")
	)
	(arc
		(start 336.238088 -283.483558)
		(mid 336.521044 -283.559735)
		(end 336.804 -283.483558)
		(width 0.0889)
		(layer "In4.Cu")
		(net "M_D_CPU0_SB_DQ<15>")
	)
	(arc
		(start 337.178142 -283.483558)
		(mid 337.461098 -283.559735)
		(end 337.744054 -283.483558)
		(width 0.0889)
		(layer "In4.Cu")
		(net "M_D_CPU0_SB_DQ<15>")
	)
	(arc
		(start 329.658218 -283.483558)
		(mid 329.941174 -283.559735)
		(end 330.22413 -283.483558)
		(width 0.0889)
		(layer "In4.Cu")
		(net "M_D_CPU0_SB_DQ<15>")
	)
	(arc
		(start 328.344022 -283.483558)
		(mid 328.526273 -283.433208)
		(end 328.709782 -283.478732)
		(width 0.0889)
		(layer "In4.Cu")
		(net "M_D_CPU0_SB_DQ<15>")
	)
	(arc
		(start 331.16393 -283.483558)
		(mid 331.346181 -283.433208)
		(end 331.52969 -283.478732)
		(width 0.0889)
		(layer "In4.Cu")
		(net "M_D_CPU0_SB_DQ<15>")
	)
	(arc
		(start 331.538072 -283.483558)
		(mid 331.821028 -283.559735)
		(end 332.103984 -283.483558)
		(width 0.0889)
		(layer "In4.Cu")
		(net "M_D_CPU0_SB_DQ<15>")
	)
	(arc
		(start 337.752436 -283.478732)
		(mid 337.935944 -283.433238)
		(end 338.118196 -283.483558)
		(width 0.0889)
		(layer "In4.Cu")
		(net "M_D_CPU0_SB_DQ<15>")
	)
	(arc
		(start 334.924146 -283.483558)
		(mid 335.11109 -283.433303)
		(end 335.298034 -283.483558)
		(width 0.0889)
		(layer "In4.Cu")
		(net "M_D_CPU0_SB_DQ<15>")
	)
	(arc
		(start 330.22413 -283.483558)
		(mid 330.411074 -283.433303)
		(end 330.598018 -283.483558)
		(width 0.0889)
		(layer "In4.Cu")
		(net "M_D_CPU0_SB_DQ<15>")
	)
	(segment
		(start 339.808058 -282.730194)
		(end 339.341206 -282.996132)
		(width 0.10668)
		(layer "F.Cu")
		(net "M_D_CPU0_SB_DQ<14>")
	)
	(segment
		(start 324.14337 -283.00172)
		(end 324.786498 -282.358592)
		(width 0.0889)
		(layer "In4.Cu")
		(net "M_D_CPU0_SB_DQ<14>")
	)
	(segment
		(start 339.187028 -282.730702)
		(end 339.341206 -282.996132)
		(width 0.0889)
		(layer "In4.Cu")
		(net "M_D_CPU0_SB_DQ<14>")
	)
	(segment
		(start 330.119736 -282.668726)
		(end 330.128118 -282.673552)
		(width 0.0889)
		(layer "In4.Cu")
		(net "M_D_CPU0_SB_DQ<14>")
	)
	(segment
		(start 326.93356 -282.673806)
		(end 326.949816 -282.664408)
		(width 0.0889)
		(layer "In4.Cu")
		(net "M_D_CPU0_SB_DQ<14>")
	)
	(segment
		(start 282.77058 -297.552872)
		(end 282.932124 -297.714416)
		(width 0.14478)
		(layer "In4.Cu")
		(net "M_D_CPU0_SB_DQ<14>")
	)
	(segment
		(start 336.3341 -282.673552)
		(end 336.342482 -282.668726)
		(width 0.0889)
		(layer "In4.Cu")
		(net "M_D_CPU0_SB_DQ<14>")
	)
	(segment
		(start 323.908674 -283.00172)
		(end 324.14337 -283.00172)
		(width 0.0889)
		(layer "In4.Cu")
		(net "M_D_CPU0_SB_DQ<14>")
	)
	(segment
		(start 290.969192 -297.209972)
		(end 293.586916 -297.209972)
		(width 0.14478)
		(layer "In4.Cu")
		(net "M_D_CPU0_SB_DQ<14>")
	)
	(segment
		(start 322.462144 -283.00172)
		(end 323.908674 -283.00172)
		(width 0.14478)
		(layer "In4.Cu")
		(net "M_D_CPU0_SB_DQ<14>")
	)
	(segment
		(start 294.437054 -298.06011)
		(end 298.058078 -298.06011)
		(width 0.14478)
		(layer "In4.Cu")
		(net "M_D_CPU0_SB_DQ<14>")
	)
	(segment
		(start 325.853298 -282.749752)
		(end 326.651112 -282.749752)
		(width 0.0889)
		(layer "In4.Cu")
		(net "M_D_CPU0_SB_DQ<14>")
	)
	(segment
		(start 306.212494 -297.217338)
		(end 308.246526 -297.217338)
		(width 0.14478)
		(layer "In4.Cu")
		(net "M_D_CPU0_SB_DQ<14>")
	)
	(segment
		(start 293.586916 -297.209972)
		(end 294.437054 -298.06011)
		(width 0.14478)
		(layer "In4.Cu")
		(net "M_D_CPU0_SB_DQ<14>")
	)
	(segment
		(start 281.060906 -298.06011)
		(end 282.219146 -298.06011)
		(width 0.14478)
		(layer "In4.Cu")
		(net "M_D_CPU0_SB_DQ<14>")
	)
	(segment
		(start 282.219146 -298.06011)
		(end 282.38069 -297.898566)
		(width 0.14478)
		(layer "In4.Cu")
		(net "M_D_CPU0_SB_DQ<14>")
	)
	(segment
		(start 300.815248 -297.209972)
		(end 301.665386 -298.06011)
		(width 0.14478)
		(layer "In4.Cu")
		(net "M_D_CPU0_SB_DQ<14>")
	)
	(segment
		(start 335.394046 -282.673552)
		(end 335.402428 -282.668726)
		(width 0.0889)
		(layer "In4.Cu")
		(net "M_D_CPU0_SB_DQ<14>")
	)
	(segment
		(start 327.307448 -282.673552)
		(end 327.317862 -282.679648)
		(width 0.0889)
		(layer "In4.Cu")
		(net "M_D_CPU0_SB_DQ<14>")
	)
	(segment
		(start 301.665386 -298.06011)
		(end 305.369722 -298.06011)
		(width 0.14478)
		(layer "In4.Cu")
		(net "M_D_CPU0_SB_DQ<14>")
	)
	(segment
		(start 282.38069 -297.714416)
		(end 282.542234 -297.552872)
		(width 0.14478)
		(layer "In4.Cu")
		(net "M_D_CPU0_SB_DQ<14>")
	)
	(segment
		(start 282.542234 -297.552872)
		(end 282.77058 -297.552872)
		(width 0.14478)
		(layer "In4.Cu")
		(net "M_D_CPU0_SB_DQ<14>")
	)
	(segment
		(start 283.093668 -298.06011)
		(end 290.119054 -298.06011)
		(width 0.14478)
		(layer "In4.Cu")
		(net "M_D_CPU0_SB_DQ<14>")
	)
	(segment
		(start 325.462138 -282.358592)
		(end 325.853298 -282.749752)
		(width 0.0889)
		(layer "In4.Cu")
		(net "M_D_CPU0_SB_DQ<14>")
	)
	(segment
		(start 298.058078 -298.06011)
		(end 298.908216 -297.209972)
		(width 0.14478)
		(layer "In4.Cu")
		(net "M_D_CPU0_SB_DQ<14>")
	)
	(segment
		(start 305.369722 -298.06011)
		(end 306.212494 -297.217338)
		(width 0.14478)
		(layer "In4.Cu")
		(net "M_D_CPU0_SB_DQ<14>")
	)
	(segment
		(start 290.119054 -298.06011)
		(end 290.969192 -297.209972)
		(width 0.14478)
		(layer "In4.Cu")
		(net "M_D_CPU0_SB_DQ<14>")
	)
	(segment
		(start 282.932124 -297.714416)
		(end 282.932124 -297.898566)
		(width 0.14478)
		(layer "In4.Cu")
		(net "M_D_CPU0_SB_DQ<14>")
	)
	(segment
		(start 331.634084 -282.673552)
		(end 331.642466 -282.668726)
		(width 0.0889)
		(layer "In4.Cu")
		(net "M_D_CPU0_SB_DQ<14>")
	)
	(segment
		(start 334.819752 -282.668726)
		(end 334.828134 -282.673552)
		(width 0.0889)
		(layer "In4.Cu")
		(net "M_D_CPU0_SB_DQ<14>")
	)
	(segment
		(start 282.38069 -297.898566)
		(end 282.38069 -297.714416)
		(width 0.14478)
		(layer "In4.Cu")
		(net "M_D_CPU0_SB_DQ<14>")
	)
	(segment
		(start 280.635964 -297.635168)
		(end 281.060906 -298.06011)
		(width 0.14478)
		(layer "In4.Cu")
		(net "M_D_CPU0_SB_DQ<14>")
	)
	(segment
		(start 308.246526 -297.217338)
		(end 322.462144 -283.00172)
		(width 0.14478)
		(layer "In4.Cu")
		(net "M_D_CPU0_SB_DQ<14>")
	)
	(segment
		(start 339.090762 -282.705302)
		(end 339.187028 -282.730702)
		(width 0.0889)
		(layer "In4.Cu")
		(net "M_D_CPU0_SB_DQ<14>")
	)
	(segment
		(start 333.879698 -282.668726)
		(end 333.88808 -282.673552)
		(width 0.0889)
		(layer "In4.Cu")
		(net "M_D_CPU0_SB_DQ<14>")
	)
	(segment
		(start 324.786498 -282.358592)
		(end 325.462138 -282.358592)
		(width 0.0889)
		(layer "In4.Cu")
		(net "M_D_CPU0_SB_DQ<14>")
	)
	(segment
		(start 282.932124 -297.898566)
		(end 283.093668 -298.06011)
		(width 0.14478)
		(layer "In4.Cu")
		(net "M_D_CPU0_SB_DQ<14>")
	)
	(segment
		(start 330.69403 -282.673552)
		(end 330.702412 -282.668726)
		(width 0.0889)
		(layer "In4.Cu")
		(net "M_D_CPU0_SB_DQ<14>")
	)
	(segment
		(start 328.239882 -282.668726)
		(end 328.248264 -282.673552)
		(width 0.0889)
		(layer "In4.Cu")
		(net "M_D_CPU0_SB_DQ<14>")
	)
	(segment
		(start 298.908216 -297.209972)
		(end 300.815248 -297.209972)
		(width 0.14478)
		(layer "In4.Cu")
		(net "M_D_CPU0_SB_DQ<14>")
	)
	(segment
		(start 338.579714 -282.668726)
		(end 338.588096 -282.673552)
		(width 0.0889)
		(layer "In4.Cu")
		(net "M_D_CPU0_SB_DQ<14>")
	)
	(arc
		(start 337.648042 -282.673552)
		(mid 337.930998 -282.749729)
		(end 338.213954 -282.673552)
		(width 0.0889)
		(layer "In4.Cu")
		(net "M_D_CPU0_SB_DQ<14>")
	)
	(arc
		(start 332.574138 -282.673552)
		(mid 332.761082 -282.623297)
		(end 332.948026 -282.673552)
		(width 0.0889)
		(layer "In4.Cu")
		(net "M_D_CPU0_SB_DQ<14>")
	)
	(arc
		(start 327.317862 -282.679648)
		(mid 327.596548 -282.749868)
		(end 327.873614 -282.673552)
		(width 0.0889)
		(layer "In4.Cu")
		(net "M_D_CPU0_SB_DQ<14>")
	)
	(arc
		(start 334.453992 -282.673552)
		(mid 334.636243 -282.623202)
		(end 334.819752 -282.668726)
		(width 0.0889)
		(layer "In4.Cu")
		(net "M_D_CPU0_SB_DQ<14>")
	)
	(arc
		(start 338.588096 -282.673552)
		(mid 338.835692 -282.74873)
		(end 339.090762 -282.705302)
		(width 0.0889)
		(layer "In4.Cu")
		(net "M_D_CPU0_SB_DQ<14>")
	)
	(arc
		(start 329.753976 -282.673552)
		(mid 329.936227 -282.623202)
		(end 330.119736 -282.668726)
		(width 0.0889)
		(layer "In4.Cu")
		(net "M_D_CPU0_SB_DQ<14>")
	)
	(arc
		(start 332.948026 -282.673552)
		(mid 333.230982 -282.749729)
		(end 333.513938 -282.673552)
		(width 0.0889)
		(layer "In4.Cu")
		(net "M_D_CPU0_SB_DQ<14>")
	)
	(arc
		(start 331.068172 -282.673552)
		(mid 331.351128 -282.749729)
		(end 331.634084 -282.673552)
		(width 0.0889)
		(layer "In4.Cu")
		(net "M_D_CPU0_SB_DQ<14>")
	)
	(arc
		(start 328.248264 -282.673552)
		(mid 328.53122 -282.749729)
		(end 328.814176 -282.673552)
		(width 0.0889)
		(layer "In4.Cu")
		(net "M_D_CPU0_SB_DQ<14>")
	)
	(arc
		(start 333.513938 -282.673552)
		(mid 333.696189 -282.623202)
		(end 333.879698 -282.668726)
		(width 0.0889)
		(layer "In4.Cu")
		(net "M_D_CPU0_SB_DQ<14>")
	)
	(arc
		(start 326.651112 -282.749752)
		(mid 326.79736 -282.730447)
		(end 326.93356 -282.673806)
		(width 0.0889)
		(layer "In4.Cu")
		(net "M_D_CPU0_SB_DQ<14>")
	)
	(arc
		(start 328.814176 -282.673552)
		(mid 329.00112 -282.623297)
		(end 329.188064 -282.673552)
		(width 0.0889)
		(layer "In4.Cu")
		(net "M_D_CPU0_SB_DQ<14>")
	)
	(arc
		(start 334.828134 -282.673552)
		(mid 335.11109 -282.749729)
		(end 335.394046 -282.673552)
		(width 0.0889)
		(layer "In4.Cu")
		(net "M_D_CPU0_SB_DQ<14>")
	)
	(arc
		(start 338.213954 -282.673552)
		(mid 338.396205 -282.623202)
		(end 338.579714 -282.668726)
		(width 0.0889)
		(layer "In4.Cu")
		(net "M_D_CPU0_SB_DQ<14>")
	)
	(arc
		(start 330.702412 -282.668726)
		(mid 330.88592 -282.623232)
		(end 331.068172 -282.673552)
		(width 0.0889)
		(layer "In4.Cu")
		(net "M_D_CPU0_SB_DQ<14>")
	)
	(arc
		(start 331.642466 -282.668726)
		(mid 331.825974 -282.623232)
		(end 332.008226 -282.673552)
		(width 0.0889)
		(layer "In4.Cu")
		(net "M_D_CPU0_SB_DQ<14>")
	)
	(arc
		(start 336.342482 -282.668726)
		(mid 336.52599 -282.623232)
		(end 336.708242 -282.673552)
		(width 0.0889)
		(layer "In4.Cu")
		(net "M_D_CPU0_SB_DQ<14>")
	)
	(arc
		(start 335.768188 -282.673552)
		(mid 336.051144 -282.749729)
		(end 336.3341 -282.673552)
		(width 0.0889)
		(layer "In4.Cu")
		(net "M_D_CPU0_SB_DQ<14>")
	)
	(arc
		(start 327.873614 -282.673552)
		(mid 328.056119 -282.623075)
		(end 328.239882 -282.668726)
		(width 0.0889)
		(layer "In4.Cu")
		(net "M_D_CPU0_SB_DQ<14>")
	)
	(arc
		(start 333.88808 -282.673552)
		(mid 334.171036 -282.749729)
		(end 334.453992 -282.673552)
		(width 0.0889)
		(layer "In4.Cu")
		(net "M_D_CPU0_SB_DQ<14>")
	)
	(arc
		(start 335.402428 -282.668726)
		(mid 335.585936 -282.623232)
		(end 335.768188 -282.673552)
		(width 0.0889)
		(layer "In4.Cu")
		(net "M_D_CPU0_SB_DQ<14>")
	)
	(arc
		(start 337.274154 -282.673552)
		(mid 337.461098 -282.623297)
		(end 337.648042 -282.673552)
		(width 0.0889)
		(layer "In4.Cu")
		(net "M_D_CPU0_SB_DQ<14>")
	)
	(arc
		(start 330.128118 -282.673552)
		(mid 330.411074 -282.749729)
		(end 330.69403 -282.673552)
		(width 0.0889)
		(layer "In4.Cu")
		(net "M_D_CPU0_SB_DQ<14>")
	)
	(arc
		(start 336.708242 -282.673552)
		(mid 336.991198 -282.749729)
		(end 337.274154 -282.673552)
		(width 0.0889)
		(layer "In4.Cu")
		(net "M_D_CPU0_SB_DQ<14>")
	)
	(arc
		(start 332.008226 -282.673552)
		(mid 332.291182 -282.749729)
		(end 332.574138 -282.673552)
		(width 0.0889)
		(layer "In4.Cu")
		(net "M_D_CPU0_SB_DQ<14>")
	)
	(arc
		(start 326.949816 -282.664408)
		(mid 327.129798 -282.623308)
		(end 327.307448 -282.673552)
		(width 0.0889)
		(layer "In4.Cu")
		(net "M_D_CPU0_SB_DQ<14>")
	)
	(arc
		(start 329.188064 -282.673552)
		(mid 329.47102 -282.749729)
		(end 329.753976 -282.673552)
		(width 0.0889)
		(layer "In4.Cu")
		(net "M_D_CPU0_SB_DQ<14>")
	)
	(segment
		(start 340.747858 -282.730194)
		(end 340.281006 -282.996132)
		(width 0.10668)
		(layer "F.Cu")
		(net "M_D_CPU0_SB_DQ<13>")
	)
	(segment
		(start 287.849564 -298.910248)
		(end 289.929062 -298.910248)
		(width 0.14478)
		(layer "In4.Cu")
		(net "M_D_CPU0_SB_DQ<13>")
	)
	(segment
		(start 297.187874 -298.682156)
		(end 297.187874 -298.748704)
		(width 0.14478)
		(layer "In4.Cu")
		(net "M_D_CPU0_SB_DQ<13>")
	)
	(segment
		(start 287.22447 -298.515786)
		(end 287.455102 -298.515786)
		(width 0.14478)
		(layer "In4.Cu")
		(net "M_D_CPU0_SB_DQ<13>")
	)
	(segment
		(start 296.63644 -298.682156)
		(end 296.797984 -298.520612)
		(width 0.14478)
		(layer "In4.Cu")
		(net "M_D_CPU0_SB_DQ<13>")
	)
	(segment
		(start 286.342582 -298.515786)
		(end 286.505396 -298.6786)
		(width 0.14478)
		(layer "In4.Cu")
		(net "M_D_CPU0_SB_DQ<13>")
	)
	(segment
		(start 340.412832 -283.344874)
		(end 340.435184 -283.261562)
		(width 0.0889)
		(layer "In4.Cu")
		(net "M_D_CPU0_SB_DQ<13>")
	)
	(segment
		(start 296.797984 -298.520612)
		(end 297.02633 -298.520612)
		(width 0.14478)
		(layer "In4.Cu")
		(net "M_D_CPU0_SB_DQ<13>")
	)
	(segment
		(start 304.753264 -298.910248)
		(end 305.369722 -298.910248)
		(width 0.14478)
		(layer "In4.Cu")
		(net "M_D_CPU0_SB_DQ<13>")
	)
	(segment
		(start 340.435184 -283.261562)
		(end 340.281006 -282.996132)
		(width 0.0889)
		(layer "In4.Cu")
		(net "M_D_CPU0_SB_DQ<13>")
	)
	(segment
		(start 293.776908 -298.06011)
		(end 294.627046 -298.910248)
		(width 0.14478)
		(layer "In4.Cu")
		(net "M_D_CPU0_SB_DQ<13>")
	)
	(segment
		(start 306.21986 -298.06011)
		(end 308.046882 -298.06011)
		(width 0.14478)
		(layer "In4.Cu")
		(net "M_D_CPU0_SB_DQ<13>")
	)
	(segment
		(start 284.736032 -298.485052)
		(end 285.55569 -299.30471)
		(width 0.14478)
		(layer "In4.Cu")
		(net "M_D_CPU0_SB_DQ<13>")
	)
	(segment
		(start 340.094062 -283.318712)
		(end 340.102444 -283.323538)
		(width 0.0889)
		(layer "In4.Cu")
		(net "M_D_CPU0_SB_DQ<13>")
	)
	(segment
		(start 297.851322 -298.910248)
		(end 298.70146 -298.06011)
		(width 0.14478)
		(layer "In4.Cu")
		(net "M_D_CPU0_SB_DQ<13>")
	)
	(segment
		(start 323.903594 -283.45638)
		(end 324.23481 -283.45638)
		(width 0.0889)
		(layer "In4.Cu")
		(net "M_D_CPU0_SB_DQ<13>")
	)
	(segment
		(start 291.62248 -298.36491)
		(end 291.92728 -298.06011)
		(width 0.14478)
		(layer "In4.Cu")
		(net "M_D_CPU0_SB_DQ<13>")
	)
	(segment
		(start 286.505396 -298.6786)
		(end 286.505396 -299.141896)
		(width 0.14478)
		(layer "In4.Cu")
		(net "M_D_CPU0_SB_DQ<13>")
	)
	(segment
		(start 327.875138 -283.318458)
		(end 327.896982 -283.330904)
		(width 0.0889)
		(layer "In4.Cu")
		(net "M_D_CPU0_SB_DQ<13>")
	)
	(segment
		(start 297.02633 -298.520612)
		(end 297.187874 -298.682156)
		(width 0.14478)
		(layer "In4.Cu")
		(net "M_D_CPU0_SB_DQ<13>")
	)
	(segment
		(start 285.55569 -299.30471)
		(end 285.786322 -299.30471)
		(width 0.14478)
		(layer "In4.Cu")
		(net "M_D_CPU0_SB_DQ<13>")
	)
	(segment
		(start 330.119736 -283.323538)
		(end 330.128118 -283.318712)
		(width 0.0889)
		(layer "In4.Cu")
		(net "M_D_CPU0_SB_DQ<13>")
	)
	(segment
		(start 304.040286 -298.682156)
		(end 304.20183 -298.520612)
		(width 0.14478)
		(layer "In4.Cu")
		(net "M_D_CPU0_SB_DQ<13>")
	)
	(segment
		(start 286.898842 -299.30471)
		(end 287.061656 -299.141896)
		(width 0.14478)
		(layer "In4.Cu")
		(net "M_D_CPU0_SB_DQ<13>")
	)
	(segment
		(start 327.851262 -283.304488)
		(end 327.875138 -283.318458)
		(width 0.0889)
		(layer "In4.Cu")
		(net "M_D_CPU0_SB_DQ<13>")
	)
	(segment
		(start 285.786322 -299.30471)
		(end 285.949136 -299.141896)
		(width 0.14478)
		(layer "In4.Cu")
		(net "M_D_CPU0_SB_DQ<13>")
	)
	(segment
		(start 324.23481 -283.45638)
		(end 324.44944 -283.24175)
		(width 0.0889)
		(layer "In4.Cu")
		(net "M_D_CPU0_SB_DQ<13>")
	)
	(segment
		(start 327.292208 -283.329634)
		(end 327.311004 -283.318712)
		(width 0.0889)
		(layer "In4.Cu")
		(net "M_D_CPU0_SB_DQ<13>")
	)
	(segment
		(start 304.59172 -298.748704)
		(end 304.753264 -298.910248)
		(width 0.14478)
		(layer "In4.Cu")
		(net "M_D_CPU0_SB_DQ<13>")
	)
	(segment
		(start 287.455102 -298.515786)
		(end 287.849564 -298.910248)
		(width 0.14478)
		(layer "In4.Cu")
		(net "M_D_CPU0_SB_DQ<13>")
	)
	(segment
		(start 304.430176 -298.520612)
		(end 304.59172 -298.682156)
		(width 0.14478)
		(layer "In4.Cu")
		(net "M_D_CPU0_SB_DQ<13>")
	)
	(segment
		(start 285.949136 -299.141896)
		(end 285.949136 -298.6786)
		(width 0.14478)
		(layer "In4.Cu")
		(net "M_D_CPU0_SB_DQ<13>")
	)
	(segment
		(start 289.929062 -298.910248)
		(end 290.7792 -298.06011)
		(width 0.14478)
		(layer "In4.Cu")
		(net "M_D_CPU0_SB_DQ<13>")
	)
	(segment
		(start 285.949136 -298.6786)
		(end 286.11195 -298.515786)
		(width 0.14478)
		(layer "In4.Cu")
		(net "M_D_CPU0_SB_DQ<13>")
	)
	(segment
		(start 322.650612 -283.45638)
		(end 323.903594 -283.45638)
		(width 0.14478)
		(layer "In4.Cu")
		(net "M_D_CPU0_SB_DQ<13>")
	)
	(segment
		(start 304.040286 -298.748704)
		(end 304.040286 -298.682156)
		(width 0.14478)
		(layer "In4.Cu")
		(net "M_D_CPU0_SB_DQ<13>")
	)
	(segment
		(start 296.474896 -298.910248)
		(end 296.63644 -298.748704)
		(width 0.14478)
		(layer "In4.Cu")
		(net "M_D_CPU0_SB_DQ<13>")
	)
	(segment
		(start 308.046882 -298.06011)
		(end 322.650612 -283.45638)
		(width 0.14478)
		(layer "In4.Cu")
		(net "M_D_CPU0_SB_DQ<13>")
	)
	(segment
		(start 293.572692 -298.06011)
		(end 293.776908 -298.06011)
		(width 0.14478)
		(layer "In4.Cu")
		(net "M_D_CPU0_SB_DQ<13>")
	)
	(segment
		(start 324.44944 -283.24175)
		(end 326.651112 -283.24175)
		(width 0.0889)
		(layer "In4.Cu")
		(net "M_D_CPU0_SB_DQ<13>")
	)
	(segment
		(start 293.016432 -298.33951)
		(end 293.293292 -298.33951)
		(width 0.14478)
		(layer "In4.Cu")
		(net "M_D_CPU0_SB_DQ<13>")
	)
	(segment
		(start 292.737032 -298.06011)
		(end 293.016432 -298.33951)
		(width 0.14478)
		(layer "In4.Cu")
		(net "M_D_CPU0_SB_DQ<13>")
	)
	(segment
		(start 291.92728 -298.06011)
		(end 292.737032 -298.06011)
		(width 0.14478)
		(layer "In4.Cu")
		(net "M_D_CPU0_SB_DQ<13>")
	)
	(segment
		(start 286.66821 -299.30471)
		(end 286.898842 -299.30471)
		(width 0.14478)
		(layer "In4.Cu")
		(net "M_D_CPU0_SB_DQ<13>")
	)
	(segment
		(start 304.20183 -298.520612)
		(end 304.430176 -298.520612)
		(width 0.14478)
		(layer "In4.Cu")
		(net "M_D_CPU0_SB_DQ<13>")
	)
	(segment
		(start 294.627046 -298.910248)
		(end 296.474896 -298.910248)
		(width 0.14478)
		(layer "In4.Cu")
		(net "M_D_CPU0_SB_DQ<13>")
	)
	(segment
		(start 291.06622 -298.06011)
		(end 291.37102 -298.36491)
		(width 0.14478)
		(layer "In4.Cu")
		(net "M_D_CPU0_SB_DQ<13>")
	)
	(segment
		(start 296.63644 -298.748704)
		(end 296.63644 -298.682156)
		(width 0.14478)
		(layer "In4.Cu")
		(net "M_D_CPU0_SB_DQ<13>")
	)
	(segment
		(start 291.37102 -298.36491)
		(end 291.62248 -298.36491)
		(width 0.14478)
		(layer "In4.Cu")
		(net "M_D_CPU0_SB_DQ<13>")
	)
	(segment
		(start 304.59172 -298.682156)
		(end 304.59172 -298.748704)
		(width 0.14478)
		(layer "In4.Cu")
		(net "M_D_CPU0_SB_DQ<13>")
	)
	(segment
		(start 301.872142 -298.910248)
		(end 303.878742 -298.910248)
		(width 0.14478)
		(layer "In4.Cu")
		(net "M_D_CPU0_SB_DQ<13>")
	)
	(segment
		(start 286.505396 -299.141896)
		(end 286.66821 -299.30471)
		(width 0.14478)
		(layer "In4.Cu")
		(net "M_D_CPU0_SB_DQ<13>")
	)
	(segment
		(start 287.061656 -298.6786)
		(end 287.22447 -298.515786)
		(width 0.14478)
		(layer "In4.Cu")
		(net "M_D_CPU0_SB_DQ<13>")
	)
	(segment
		(start 303.878742 -298.910248)
		(end 304.040286 -298.748704)
		(width 0.14478)
		(layer "In4.Cu")
		(net "M_D_CPU0_SB_DQ<13>")
	)
	(segment
		(start 335.394046 -283.318712)
		(end 335.402428 -283.323538)
		(width 0.0889)
		(layer "In4.Cu")
		(net "M_D_CPU0_SB_DQ<13>")
	)
	(segment
		(start 286.11195 -298.515786)
		(end 286.342582 -298.515786)
		(width 0.14478)
		(layer "In4.Cu")
		(net "M_D_CPU0_SB_DQ<13>")
	)
	(segment
		(start 290.7792 -298.06011)
		(end 291.06622 -298.06011)
		(width 0.14478)
		(layer "In4.Cu")
		(net "M_D_CPU0_SB_DQ<13>")
	)
	(segment
		(start 331.634084 -283.318712)
		(end 331.642466 -283.323538)
		(width 0.0889)
		(layer "In4.Cu")
		(net "M_D_CPU0_SB_DQ<13>")
	)
	(segment
		(start 336.3341 -283.318712)
		(end 336.342482 -283.323538)
		(width 0.0889)
		(layer "In4.Cu")
		(net "M_D_CPU0_SB_DQ<13>")
	)
	(segment
		(start 334.819752 -283.323538)
		(end 334.828134 -283.318712)
		(width 0.0889)
		(layer "In4.Cu")
		(net "M_D_CPU0_SB_DQ<13>")
	)
	(segment
		(start 298.70146 -298.06011)
		(end 301.022004 -298.06011)
		(width 0.14478)
		(layer "In4.Cu")
		(net "M_D_CPU0_SB_DQ<13>")
	)
	(segment
		(start 301.022004 -298.06011)
		(end 301.872142 -298.910248)
		(width 0.14478)
		(layer "In4.Cu")
		(net "M_D_CPU0_SB_DQ<13>")
	)
	(segment
		(start 333.879698 -283.323538)
		(end 333.88808 -283.318712)
		(width 0.0889)
		(layer "In4.Cu")
		(net "M_D_CPU0_SB_DQ<13>")
	)
	(segment
		(start 287.061656 -299.141896)
		(end 287.061656 -298.6786)
		(width 0.14478)
		(layer "In4.Cu")
		(net "M_D_CPU0_SB_DQ<13>")
	)
	(segment
		(start 297.187874 -298.748704)
		(end 297.349418 -298.910248)
		(width 0.14478)
		(layer "In4.Cu")
		(net "M_D_CPU0_SB_DQ<13>")
	)
	(segment
		(start 330.69403 -283.318712)
		(end 330.702412 -283.323538)
		(width 0.0889)
		(layer "In4.Cu")
		(net "M_D_CPU0_SB_DQ<13>")
	)
	(segment
		(start 297.349418 -298.910248)
		(end 297.851322 -298.910248)
		(width 0.14478)
		(layer "In4.Cu")
		(net "M_D_CPU0_SB_DQ<13>")
	)
	(segment
		(start 338.579714 -283.323538)
		(end 338.588096 -283.318712)
		(width 0.0889)
		(layer "In4.Cu")
		(net "M_D_CPU0_SB_DQ<13>")
	)
	(segment
		(start 305.369722 -298.910248)
		(end 306.21986 -298.06011)
		(width 0.14478)
		(layer "In4.Cu")
		(net "M_D_CPU0_SB_DQ<13>")
	)
	(segment
		(start 339.519768 -283.323538)
		(end 339.52815 -283.318712)
		(width 0.0889)
		(layer "In4.Cu")
		(net "M_D_CPU0_SB_DQ<13>")
	)
	(segment
		(start 293.293292 -298.33951)
		(end 293.572692 -298.06011)
		(width 0.14478)
		(layer "In4.Cu")
		(net "M_D_CPU0_SB_DQ<13>")
	)
	(arc
		(start 331.068172 -283.318712)
		(mid 331.351128 -283.242535)
		(end 331.634084 -283.318712)
		(width 0.0889)
		(layer "In4.Cu")
		(net "M_D_CPU0_SB_DQ<13>")
	)
	(arc
		(start 335.768188 -283.318712)
		(mid 336.051144 -283.242535)
		(end 336.3341 -283.318712)
		(width 0.0889)
		(layer "In4.Cu")
		(net "M_D_CPU0_SB_DQ<13>")
	)
	(arc
		(start 328.814176 -283.318712)
		(mid 329.00112 -283.368967)
		(end 329.188064 -283.318712)
		(width 0.0889)
		(layer "In4.Cu")
		(net "M_D_CPU0_SB_DQ<13>")
	)
	(arc
		(start 329.188064 -283.318712)
		(mid 329.47102 -283.242535)
		(end 329.753976 -283.318712)
		(width 0.0889)
		(layer "In4.Cu")
		(net "M_D_CPU0_SB_DQ<13>")
	)
	(arc
		(start 334.828134 -283.318712)
		(mid 335.11109 -283.242535)
		(end 335.394046 -283.318712)
		(width 0.0889)
		(layer "In4.Cu")
		(net "M_D_CPU0_SB_DQ<13>")
	)
	(arc
		(start 332.948026 -283.318712)
		(mid 333.230982 -283.242535)
		(end 333.513938 -283.318712)
		(width 0.0889)
		(layer "In4.Cu")
		(net "M_D_CPU0_SB_DQ<13>")
	)
	(arc
		(start 326.935846 -283.318712)
		(mid 327.112637 -283.369431)
		(end 327.292208 -283.329634)
		(width 0.0889)
		(layer "In4.Cu")
		(net "M_D_CPU0_SB_DQ<13>")
	)
	(arc
		(start 338.213954 -283.318712)
		(mid 338.396205 -283.369062)
		(end 338.579714 -283.323538)
		(width 0.0889)
		(layer "In4.Cu")
		(net "M_D_CPU0_SB_DQ<13>")
	)
	(arc
		(start 333.513938 -283.318712)
		(mid 333.696189 -283.369062)
		(end 333.879698 -283.323538)
		(width 0.0889)
		(layer "In4.Cu")
		(net "M_D_CPU0_SB_DQ<13>")
	)
	(arc
		(start 334.453992 -283.318712)
		(mid 334.636243 -283.369062)
		(end 334.819752 -283.323538)
		(width 0.0889)
		(layer "In4.Cu")
		(net "M_D_CPU0_SB_DQ<13>")
	)
	(arc
		(start 339.52815 -283.318712)
		(mid 339.811106 -283.242535)
		(end 340.094062 -283.318712)
		(width 0.0889)
		(layer "In4.Cu")
		(net "M_D_CPU0_SB_DQ<13>")
	)
	(arc
		(start 337.648042 -283.318712)
		(mid 337.930998 -283.242535)
		(end 338.213954 -283.318712)
		(width 0.0889)
		(layer "In4.Cu")
		(net "M_D_CPU0_SB_DQ<13>")
	)
	(arc
		(start 330.702412 -283.323538)
		(mid 330.88592 -283.369032)
		(end 331.068172 -283.318712)
		(width 0.0889)
		(layer "In4.Cu")
		(net "M_D_CPU0_SB_DQ<13>")
	)
	(arc
		(start 328.248264 -283.318712)
		(mid 328.53122 -283.242535)
		(end 328.814176 -283.318712)
		(width 0.0889)
		(layer "In4.Cu")
		(net "M_D_CPU0_SB_DQ<13>")
	)
	(arc
		(start 338.588096 -283.318712)
		(mid 338.871052 -283.242535)
		(end 339.154008 -283.318712)
		(width 0.0889)
		(layer "In4.Cu")
		(net "M_D_CPU0_SB_DQ<13>")
	)
	(arc
		(start 340.102444 -283.323538)
		(mid 340.255314 -283.368179)
		(end 340.412832 -283.344874)
		(width 0.0889)
		(layer "In4.Cu")
		(net "M_D_CPU0_SB_DQ<13>")
	)
	(arc
		(start 329.753976 -283.318712)
		(mid 329.936227 -283.369062)
		(end 330.119736 -283.323538)
		(width 0.0889)
		(layer "In4.Cu")
		(net "M_D_CPU0_SB_DQ<13>")
	)
	(arc
		(start 326.651112 -283.24175)
		(mid 326.798599 -283.261293)
		(end 326.935846 -283.318712)
		(width 0.0889)
		(layer "In4.Cu")
		(net "M_D_CPU0_SB_DQ<13>")
	)
	(arc
		(start 327.896982 -283.330904)
		(mid 328.074164 -283.368844)
		(end 328.248264 -283.318712)
		(width 0.0889)
		(layer "In4.Cu")
		(net "M_D_CPU0_SB_DQ<13>")
	)
	(arc
		(start 327.311004 -283.318712)
		(mid 327.579324 -283.242604)
		(end 327.851262 -283.304488)
		(width 0.0889)
		(layer "In4.Cu")
		(net "M_D_CPU0_SB_DQ<13>")
	)
	(arc
		(start 337.274154 -283.318712)
		(mid 337.461098 -283.368967)
		(end 337.648042 -283.318712)
		(width 0.0889)
		(layer "In4.Cu")
		(net "M_D_CPU0_SB_DQ<13>")
	)
	(arc
		(start 333.88808 -283.318712)
		(mid 334.171036 -283.242535)
		(end 334.453992 -283.318712)
		(width 0.0889)
		(layer "In4.Cu")
		(net "M_D_CPU0_SB_DQ<13>")
	)
	(arc
		(start 330.128118 -283.318712)
		(mid 330.411074 -283.242535)
		(end 330.69403 -283.318712)
		(width 0.0889)
		(layer "In4.Cu")
		(net "M_D_CPU0_SB_DQ<13>")
	)
	(arc
		(start 331.642466 -283.323538)
		(mid 331.825974 -283.369032)
		(end 332.008226 -283.318712)
		(width 0.0889)
		(layer "In4.Cu")
		(net "M_D_CPU0_SB_DQ<13>")
	)
	(arc
		(start 332.008226 -283.318712)
		(mid 332.291182 -283.242535)
		(end 332.574138 -283.318712)
		(width 0.0889)
		(layer "In4.Cu")
		(net "M_D_CPU0_SB_DQ<13>")
	)
	(arc
		(start 339.154008 -283.318712)
		(mid 339.336259 -283.369062)
		(end 339.519768 -283.323538)
		(width 0.0889)
		(layer "In4.Cu")
		(net "M_D_CPU0_SB_DQ<13>")
	)
	(arc
		(start 336.342482 -283.323538)
		(mid 336.52599 -283.369032)
		(end 336.708242 -283.318712)
		(width 0.0889)
		(layer "In4.Cu")
		(net "M_D_CPU0_SB_DQ<13>")
	)
	(arc
		(start 332.574138 -283.318712)
		(mid 332.761082 -283.368967)
		(end 332.948026 -283.318712)
		(width 0.0889)
		(layer "In4.Cu")
		(net "M_D_CPU0_SB_DQ<13>")
	)
	(arc
		(start 335.402428 -283.323538)
		(mid 335.585936 -283.369032)
		(end 335.768188 -283.318712)
		(width 0.0889)
		(layer "In4.Cu")
		(net "M_D_CPU0_SB_DQ<13>")
	)
	(arc
		(start 336.708242 -283.318712)
		(mid 336.991198 -283.242535)
		(end 337.274154 -283.318712)
		(width 0.0889)
		(layer "In4.Cu")
		(net "M_D_CPU0_SB_DQ<13>")
	)
	(segment
		(start 339.337904 -281.920188)
		(end 338.871052 -282.186126)
		(width 0.10668)
		(layer "F.Cu")
		(net "M_D_CPU0_SB_DQ<12>")
	)
	(segment
		(start 296.908982 -297.219878)
		(end 297.137328 -297.219878)
		(width 0.14478)
		(layer "In4.Cu")
		(net "M_D_CPU0_SB_DQ<12>")
	)
	(segment
		(start 305.183794 -297.60291)
		(end 306.024026 -296.762678)
		(width 0.14478)
		(layer "In4.Cu")
		(net "M_D_CPU0_SB_DQ<12>")
	)
	(segment
		(start 308.058058 -296.762678)
		(end 322.273676 -282.54706)
		(width 0.14478)
		(layer "In4.Cu")
		(net "M_D_CPU0_SB_DQ<12>")
	)
	(segment
		(start 328.333608 -282.50261)
		(end 328.344022 -282.508706)
		(width 0.0889)
		(layer "In4.Cu")
		(net "M_D_CPU0_SB_DQ<12>")
	)
	(segment
		(start 285.17088 -297.219878)
		(end 285.666434 -297.219878)
		(width 0.14478)
		(layer "In4.Cu")
		(net "M_D_CPU0_SB_DQ<12>")
	)
	(segment
		(start 285.956248 -297.509692)
		(end 286.217868 -297.509692)
		(width 0.14478)
		(layer "In4.Cu")
		(net "M_D_CPU0_SB_DQ<12>")
	)
	(segment
		(start 324.575678 -282.168092)
		(end 325.541132 -282.168092)
		(width 0.0889)
		(layer "In4.Cu")
		(net "M_D_CPU0_SB_DQ<12>")
	)
	(segment
		(start 303.19726 -297.61053)
		(end 303.437036 -297.61053)
		(width 0.14478)
		(layer "In4.Cu")
		(net "M_D_CPU0_SB_DQ<12>")
	)
	(segment
		(start 286.217868 -297.509692)
		(end 286.507682 -297.219878)
		(width 0.14478)
		(layer "In4.Cu")
		(net "M_D_CPU0_SB_DQ<12>")
	)
	(segment
		(start 324.19671 -282.54706)
		(end 324.575678 -282.168092)
		(width 0.0889)
		(layer "In4.Cu")
		(net "M_D_CPU0_SB_DQ<12>")
	)
	(segment
		(start 289.579304 -297.219878)
		(end 290.298886 -297.219878)
		(width 0.14478)
		(layer "In4.Cu")
		(net "M_D_CPU0_SB_DQ<12>")
	)
	(segment
		(start 326.837802 -282.508452)
		(end 326.84339 -282.50515)
		(width 0.0889)
		(layer "In4.Cu")
		(net "M_D_CPU0_SB_DQ<12>")
	)
	(segment
		(start 333.984092 -282.508706)
		(end 333.992474 -282.513532)
		(width 0.0889)
		(layer "In4.Cu")
		(net "M_D_CPU0_SB_DQ<12>")
	)
	(segment
		(start 302.482758 -297.241468)
		(end 302.482758 -297.018202)
		(width 0.14478)
		(layer "In4.Cu")
		(net "M_D_CPU0_SB_DQ<12>")
	)
	(segment
		(start 303.039018 -297.018202)
		(end 303.039018 -297.452288)
		(width 0.14478)
		(layer "In4.Cu")
		(net "M_D_CPU0_SB_DQ<12>")
	)
	(segment
		(start 295.18356 -297.442128)
		(end 295.18356 -297.381422)
		(width 0.14478)
		(layer "In4.Cu")
		(net "M_D_CPU0_SB_DQ<12>")
	)
	(segment
		(start 307.711602 -296.762678)
		(end 308.058058 -296.762678)
		(width 0.14478)
		(layer "In4.Cu")
		(net "M_D_CPU0_SB_DQ<12>")
	)
	(segment
		(start 294.79367 -297.603672)
		(end 295.022016 -297.603672)
		(width 0.14478)
		(layer "In4.Cu")
		(net "M_D_CPU0_SB_DQ<12>")
	)
	(segment
		(start 297.298872 -297.439588)
		(end 297.460416 -297.601132)
		(width 0.14478)
		(layer "In4.Cu")
		(net "M_D_CPU0_SB_DQ<12>")
	)
	(segment
		(start 307.388514 -296.056812)
		(end 307.550058 -296.218356)
		(width 0.14478)
		(layer "In4.Cu")
		(net "M_D_CPU0_SB_DQ<12>")
	)
	(segment
		(start 300.620684 -296.36974)
		(end 301.650654 -297.39971)
		(width 0.14478)
		(layer "In4.Cu")
		(net "M_D_CPU0_SB_DQ<12>")
	)
	(segment
		(start 302.641 -296.85996)
		(end 302.880776 -296.85996)
		(width 0.14478)
		(layer "In4.Cu")
		(net "M_D_CPU0_SB_DQ<12>")
	)
	(segment
		(start 325.541132 -282.168092)
		(end 325.932292 -282.559252)
		(width 0.0889)
		(layer "In4.Cu")
		(net "M_D_CPU0_SB_DQ<12>")
	)
	(segment
		(start 306.998624 -296.601134)
		(end 306.998624 -296.218356)
		(width 0.14478)
		(layer "In4.Cu")
		(net "M_D_CPU0_SB_DQ<12>")
	)
	(segment
		(start 293.407084 -296.36974)
		(end 294.257222 -297.219878)
		(width 0.14478)
		(layer "In4.Cu")
		(net "M_D_CPU0_SB_DQ<12>")
	)
	(segment
		(start 296.747438 -297.381422)
		(end 296.908982 -297.219878)
		(width 0.14478)
		(layer "In4.Cu")
		(net "M_D_CPU0_SB_DQ<12>")
	)
	(segment
		(start 306.83708 -296.762678)
		(end 306.998624 -296.601134)
		(width 0.14478)
		(layer "In4.Cu")
		(net "M_D_CPU0_SB_DQ<12>")
	)
	(segment
		(start 295.022016 -297.603672)
		(end 295.18356 -297.442128)
		(width 0.14478)
		(layer "In4.Cu")
		(net "M_D_CPU0_SB_DQ<12>")
	)
	(segment
		(start 297.298872 -297.381422)
		(end 297.298872 -297.439588)
		(width 0.14478)
		(layer "In4.Cu")
		(net "M_D_CPU0_SB_DQ<12>")
	)
	(segment
		(start 296.196004 -297.381422)
		(end 296.196004 -297.439588)
		(width 0.14478)
		(layer "In4.Cu")
		(net "M_D_CPU0_SB_DQ<12>")
	)
	(segment
		(start 327.403206 -282.508706)
		(end 327.411588 -282.513532)
		(width 0.0889)
		(layer "In4.Cu")
		(net "M_D_CPU0_SB_DQ<12>")
	)
	(segment
		(start 284.736032 -296.78503)
		(end 285.17088 -297.219878)
		(width 0.14478)
		(layer "In4.Cu")
		(net "M_D_CPU0_SB_DQ<12>")
	)
	(segment
		(start 306.998624 -296.218356)
		(end 307.160168 -296.056812)
		(width 0.14478)
		(layer "In4.Cu")
		(net "M_D_CPU0_SB_DQ<12>")
	)
	(segment
		(start 289.41776 -297.381422)
		(end 289.579304 -297.219878)
		(width 0.14478)
		(layer "In4.Cu")
		(net "M_D_CPU0_SB_DQ<12>")
	)
	(segment
		(start 333.044038 -282.508706)
		(end 333.05242 -282.513532)
		(width 0.0889)
		(layer "In4.Cu")
		(net "M_D_CPU0_SB_DQ<12>")
	)
	(segment
		(start 295.18356 -297.381422)
		(end 295.345104 -297.219878)
		(width 0.14478)
		(layer "In4.Cu")
		(net "M_D_CPU0_SB_DQ<12>")
	)
	(segment
		(start 303.595278 -297.017186)
		(end 303.752504 -296.85996)
		(width 0.14478)
		(layer "In4.Cu")
		(net "M_D_CPU0_SB_DQ<12>")
	)
	(segment
		(start 296.03446 -297.219878)
		(end 296.196004 -297.381422)
		(width 0.14478)
		(layer "In4.Cu")
		(net "M_D_CPU0_SB_DQ<12>")
	)
	(segment
		(start 302.482758 -297.018202)
		(end 302.641 -296.85996)
		(width 0.14478)
		(layer "In4.Cu")
		(net "M_D_CPU0_SB_DQ<12>")
	)
	(segment
		(start 296.196004 -297.439588)
		(end 296.357548 -297.601132)
		(width 0.14478)
		(layer "In4.Cu")
		(net "M_D_CPU0_SB_DQ<12>")
	)
	(segment
		(start 294.470582 -297.219878)
		(end 294.632126 -297.381422)
		(width 0.14478)
		(layer "In4.Cu")
		(net "M_D_CPU0_SB_DQ<12>")
	)
	(segment
		(start 296.357548 -297.601132)
		(end 296.585894 -297.601132)
		(width 0.14478)
		(layer "In4.Cu")
		(net "M_D_CPU0_SB_DQ<12>")
	)
	(segment
		(start 289.41776 -297.444668)
		(end 289.41776 -297.381422)
		(width 0.14478)
		(layer "In4.Cu")
		(net "M_D_CPU0_SB_DQ<12>")
	)
	(segment
		(start 307.550058 -296.601134)
		(end 307.711602 -296.762678)
		(width 0.14478)
		(layer "In4.Cu")
		(net "M_D_CPU0_SB_DQ<12>")
	)
	(segment
		(start 302.880776 -296.85996)
		(end 303.039018 -297.018202)
		(width 0.14478)
		(layer "In4.Cu")
		(net "M_D_CPU0_SB_DQ<12>")
	)
	(segment
		(start 338.684108 -282.508706)
		(end 338.69249 -282.513532)
		(width 0.0889)
		(layer "In4.Cu")
		(net "M_D_CPU0_SB_DQ<12>")
	)
	(segment
		(start 288.866326 -297.381422)
		(end 288.866326 -297.444668)
		(width 0.14478)
		(layer "In4.Cu")
		(net "M_D_CPU0_SB_DQ<12>")
	)
	(segment
		(start 337.16976 -282.513532)
		(end 337.178142 -282.508706)
		(width 0.0889)
		(layer "In4.Cu")
		(net "M_D_CPU0_SB_DQ<12>")
	)
	(segment
		(start 325.932292 -282.559252)
		(end 326.650858 -282.559252)
		(width 0.0889)
		(layer "In4.Cu")
		(net "M_D_CPU0_SB_DQ<12>")
	)
	(segment
		(start 336.229706 -282.513532)
		(end 336.238088 -282.508706)
		(width 0.0889)
		(layer "In4.Cu")
		(net "M_D_CPU0_SB_DQ<12>")
	)
	(segment
		(start 304.041302 -296.85996)
		(end 304.784252 -297.60291)
		(width 0.14478)
		(layer "In4.Cu")
		(net "M_D_CPU0_SB_DQ<12>")
	)
	(segment
		(start 297.688762 -297.601132)
		(end 298.920154 -296.36974)
		(width 0.14478)
		(layer "In4.Cu")
		(net "M_D_CPU0_SB_DQ<12>")
	)
	(segment
		(start 288.704782 -297.219878)
		(end 288.866326 -297.381422)
		(width 0.14478)
		(layer "In4.Cu")
		(net "M_D_CPU0_SB_DQ<12>")
	)
	(segment
		(start 294.632126 -297.442128)
		(end 294.79367 -297.603672)
		(width 0.14478)
		(layer "In4.Cu")
		(net "M_D_CPU0_SB_DQ<12>")
	)
	(segment
		(start 297.137328 -297.219878)
		(end 297.298872 -297.381422)
		(width 0.14478)
		(layer "In4.Cu")
		(net "M_D_CPU0_SB_DQ<12>")
	)
	(segment
		(start 302.324516 -297.39971)
		(end 302.482758 -297.241468)
		(width 0.14478)
		(layer "In4.Cu")
		(net "M_D_CPU0_SB_DQ<12>")
	)
	(segment
		(start 290.298886 -297.219878)
		(end 291.149024 -296.36974)
		(width 0.14478)
		(layer "In4.Cu")
		(net "M_D_CPU0_SB_DQ<12>")
	)
	(segment
		(start 337.744054 -282.508706)
		(end 337.752436 -282.513532)
		(width 0.0889)
		(layer "In4.Cu")
		(net "M_D_CPU0_SB_DQ<12>")
	)
	(segment
		(start 291.149024 -296.36974)
		(end 293.407084 -296.36974)
		(width 0.14478)
		(layer "In4.Cu")
		(net "M_D_CPU0_SB_DQ<12>")
	)
	(segment
		(start 301.650654 -297.39971)
		(end 302.324516 -297.39971)
		(width 0.14478)
		(layer "In4.Cu")
		(net "M_D_CPU0_SB_DQ<12>")
	)
	(segment
		(start 331.52969 -282.513532)
		(end 331.538072 -282.508706)
		(width 0.0889)
		(layer "In4.Cu")
		(net "M_D_CPU0_SB_DQ<12>")
	)
	(segment
		(start 285.666434 -297.219878)
		(end 285.956248 -297.509692)
		(width 0.14478)
		(layer "In4.Cu")
		(net "M_D_CPU0_SB_DQ<12>")
	)
	(segment
		(start 306.024026 -296.762678)
		(end 306.83708 -296.762678)
		(width 0.14478)
		(layer "In4.Cu")
		(net "M_D_CPU0_SB_DQ<12>")
	)
	(segment
		(start 303.437036 -297.61053)
		(end 303.595278 -297.452288)
		(width 0.14478)
		(layer "In4.Cu")
		(net "M_D_CPU0_SB_DQ<12>")
	)
	(segment
		(start 307.160168 -296.056812)
		(end 307.388514 -296.056812)
		(width 0.14478)
		(layer "In4.Cu")
		(net "M_D_CPU0_SB_DQ<12>")
	)
	(segment
		(start 296.747438 -297.439588)
		(end 296.747438 -297.381422)
		(width 0.14478)
		(layer "In4.Cu")
		(net "M_D_CPU0_SB_DQ<12>")
	)
	(segment
		(start 303.595278 -297.452288)
		(end 303.595278 -297.017186)
		(width 0.14478)
		(layer "In4.Cu")
		(net "M_D_CPU0_SB_DQ<12>")
	)
	(segment
		(start 297.460416 -297.601132)
		(end 297.688762 -297.601132)
		(width 0.14478)
		(layer "In4.Cu")
		(net "M_D_CPU0_SB_DQ<12>")
	)
	(segment
		(start 287.61055 -297.219878)
		(end 288.704782 -297.219878)
		(width 0.14478)
		(layer "In4.Cu")
		(net "M_D_CPU0_SB_DQ<12>")
	)
	(segment
		(start 303.752504 -296.85996)
		(end 304.041302 -296.85996)
		(width 0.14478)
		(layer "In4.Cu")
		(net "M_D_CPU0_SB_DQ<12>")
	)
	(segment
		(start 339.002878 -282.534868)
		(end 339.02523 -282.451556)
		(width 0.0889)
		(layer "In4.Cu")
		(net "M_D_CPU0_SB_DQ<12>")
	)
	(segment
		(start 287.320736 -297.509692)
		(end 287.61055 -297.219878)
		(width 0.14478)
		(layer "In4.Cu")
		(net "M_D_CPU0_SB_DQ<12>")
	)
	(segment
		(start 307.550058 -296.218356)
		(end 307.550058 -296.601134)
		(width 0.14478)
		(layer "In4.Cu")
		(net "M_D_CPU0_SB_DQ<12>")
	)
	(segment
		(start 328.709782 -282.513532)
		(end 328.718164 -282.508706)
		(width 0.0889)
		(layer "In4.Cu")
		(net "M_D_CPU0_SB_DQ<12>")
	)
	(segment
		(start 323.898514 -282.54706)
		(end 324.19671 -282.54706)
		(width 0.0889)
		(layer "In4.Cu")
		(net "M_D_CPU0_SB_DQ<12>")
	)
	(segment
		(start 332.469744 -282.513532)
		(end 332.478126 -282.508706)
		(width 0.0889)
		(layer "In4.Cu")
		(net "M_D_CPU0_SB_DQ<12>")
	)
	(segment
		(start 304.784252 -297.60291)
		(end 305.183794 -297.60291)
		(width 0.14478)
		(layer "In4.Cu")
		(net "M_D_CPU0_SB_DQ<12>")
	)
	(segment
		(start 287.059116 -297.509692)
		(end 287.320736 -297.509692)
		(width 0.14478)
		(layer "In4.Cu")
		(net "M_D_CPU0_SB_DQ<12>")
	)
	(segment
		(start 294.257222 -297.219878)
		(end 294.470582 -297.219878)
		(width 0.14478)
		(layer "In4.Cu")
		(net "M_D_CPU0_SB_DQ<12>")
	)
	(segment
		(start 289.02787 -297.606212)
		(end 289.256216 -297.606212)
		(width 0.14478)
		(layer "In4.Cu")
		(net "M_D_CPU0_SB_DQ<12>")
	)
	(segment
		(start 329.284076 -282.508706)
		(end 329.292458 -282.513532)
		(width 0.0889)
		(layer "In4.Cu")
		(net "M_D_CPU0_SB_DQ<12>")
	)
	(segment
		(start 288.866326 -297.444668)
		(end 289.02787 -297.606212)
		(width 0.14478)
		(layer "In4.Cu")
		(net "M_D_CPU0_SB_DQ<12>")
	)
	(segment
		(start 286.507682 -297.219878)
		(end 286.769302 -297.219878)
		(width 0.14478)
		(layer "In4.Cu")
		(net "M_D_CPU0_SB_DQ<12>")
	)
	(segment
		(start 303.039018 -297.452288)
		(end 303.19726 -297.61053)
		(width 0.14478)
		(layer "In4.Cu")
		(net "M_D_CPU0_SB_DQ<12>")
	)
	(segment
		(start 322.273676 -282.54706)
		(end 323.898514 -282.54706)
		(width 0.14478)
		(layer "In4.Cu")
		(net "M_D_CPU0_SB_DQ<12>")
	)
	(segment
		(start 286.769302 -297.219878)
		(end 287.059116 -297.509692)
		(width 0.14478)
		(layer "In4.Cu")
		(net "M_D_CPU0_SB_DQ<12>")
	)
	(segment
		(start 294.632126 -297.381422)
		(end 294.632126 -297.442128)
		(width 0.14478)
		(layer "In4.Cu")
		(net "M_D_CPU0_SB_DQ<12>")
	)
	(segment
		(start 295.345104 -297.219878)
		(end 296.03446 -297.219878)
		(width 0.14478)
		(layer "In4.Cu")
		(net "M_D_CPU0_SB_DQ<12>")
	)
	(segment
		(start 298.920154 -296.36974)
		(end 300.620684 -296.36974)
		(width 0.14478)
		(layer "In4.Cu")
		(net "M_D_CPU0_SB_DQ<12>")
	)
	(segment
		(start 296.585894 -297.601132)
		(end 296.747438 -297.439588)
		(width 0.14478)
		(layer "In4.Cu")
		(net "M_D_CPU0_SB_DQ<12>")
	)
	(segment
		(start 289.256216 -297.606212)
		(end 289.41776 -297.444668)
		(width 0.14478)
		(layer "In4.Cu")
		(net "M_D_CPU0_SB_DQ<12>")
	)
	(segment
		(start 339.02523 -282.451556)
		(end 338.871052 -282.186126)
		(width 0.0889)
		(layer "In4.Cu")
		(net "M_D_CPU0_SB_DQ<12>")
	)
	(arc
		(start 334.924146 -282.508706)
		(mid 335.11109 -282.558961)
		(end 335.298034 -282.508706)
		(width 0.0889)
		(layer "In4.Cu")
		(net "M_D_CPU0_SB_DQ<12>")
	)
	(arc
		(start 327.411588 -282.513532)
		(mid 327.59535 -282.559148)
		(end 327.777856 -282.508706)
		(width 0.0889)
		(layer "In4.Cu")
		(net "M_D_CPU0_SB_DQ<12>")
	)
	(arc
		(start 327.777856 -282.508706)
		(mid 328.054923 -282.432435)
		(end 328.333608 -282.50261)
		(width 0.0889)
		(layer "In4.Cu")
		(net "M_D_CPU0_SB_DQ<12>")
	)
	(arc
		(start 331.16393 -282.508706)
		(mid 331.346181 -282.559056)
		(end 331.52969 -282.513532)
		(width 0.0889)
		(layer "In4.Cu")
		(net "M_D_CPU0_SB_DQ<12>")
	)
	(arc
		(start 333.41818 -282.508706)
		(mid 333.701136 -282.432529)
		(end 333.984092 -282.508706)
		(width 0.0889)
		(layer "In4.Cu")
		(net "M_D_CPU0_SB_DQ<12>")
	)
	(arc
		(start 338.69249 -282.513532)
		(mid 338.84536 -282.558173)
		(end 339.002878 -282.534868)
		(width 0.0889)
		(layer "In4.Cu")
		(net "M_D_CPU0_SB_DQ<12>")
	)
	(arc
		(start 336.804 -282.508706)
		(mid 336.986251 -282.559056)
		(end 337.16976 -282.513532)
		(width 0.0889)
		(layer "In4.Cu")
		(net "M_D_CPU0_SB_DQ<12>")
	)
	(arc
		(start 330.598018 -282.508706)
		(mid 330.880974 -282.432529)
		(end 331.16393 -282.508706)
		(width 0.0889)
		(layer "In4.Cu")
		(net "M_D_CPU0_SB_DQ<12>")
	)
	(arc
		(start 329.658218 -282.508706)
		(mid 329.941174 -282.432529)
		(end 330.22413 -282.508706)
		(width 0.0889)
		(layer "In4.Cu")
		(net "M_D_CPU0_SB_DQ<12>")
	)
	(arc
		(start 331.538072 -282.508706)
		(mid 331.821028 -282.432529)
		(end 332.103984 -282.508706)
		(width 0.0889)
		(layer "In4.Cu")
		(net "M_D_CPU0_SB_DQ<12>")
	)
	(arc
		(start 326.650858 -282.559252)
		(mid 326.747676 -282.546181)
		(end 326.837802 -282.508452)
		(width 0.0889)
		(layer "In4.Cu")
		(net "M_D_CPU0_SB_DQ<12>")
	)
	(arc
		(start 326.84339 -282.50515)
		(mid 327.123779 -282.432481)
		(end 327.403206 -282.508706)
		(width 0.0889)
		(layer "In4.Cu")
		(net "M_D_CPU0_SB_DQ<12>")
	)
	(arc
		(start 334.358234 -282.508706)
		(mid 334.64119 -282.432529)
		(end 334.924146 -282.508706)
		(width 0.0889)
		(layer "In4.Cu")
		(net "M_D_CPU0_SB_DQ<12>")
	)
	(arc
		(start 333.05242 -282.513532)
		(mid 333.235928 -282.559026)
		(end 333.41818 -282.508706)
		(width 0.0889)
		(layer "In4.Cu")
		(net "M_D_CPU0_SB_DQ<12>")
	)
	(arc
		(start 336.238088 -282.508706)
		(mid 336.521044 -282.432529)
		(end 336.804 -282.508706)
		(width 0.0889)
		(layer "In4.Cu")
		(net "M_D_CPU0_SB_DQ<12>")
	)
	(arc
		(start 335.298034 -282.508706)
		(mid 335.58099 -282.432529)
		(end 335.863946 -282.508706)
		(width 0.0889)
		(layer "In4.Cu")
		(net "M_D_CPU0_SB_DQ<12>")
	)
	(arc
		(start 328.344022 -282.508706)
		(mid 328.526273 -282.559056)
		(end 328.709782 -282.513532)
		(width 0.0889)
		(layer "In4.Cu")
		(net "M_D_CPU0_SB_DQ<12>")
	)
	(arc
		(start 328.718164 -282.508706)
		(mid 329.00112 -282.432529)
		(end 329.284076 -282.508706)
		(width 0.0889)
		(layer "In4.Cu")
		(net "M_D_CPU0_SB_DQ<12>")
	)
	(arc
		(start 337.752436 -282.513532)
		(mid 337.935944 -282.559026)
		(end 338.118196 -282.508706)
		(width 0.0889)
		(layer "In4.Cu")
		(net "M_D_CPU0_SB_DQ<12>")
	)
	(arc
		(start 329.292458 -282.513532)
		(mid 329.475966 -282.559026)
		(end 329.658218 -282.508706)
		(width 0.0889)
		(layer "In4.Cu")
		(net "M_D_CPU0_SB_DQ<12>")
	)
	(arc
		(start 330.22413 -282.508706)
		(mid 330.411074 -282.558961)
		(end 330.598018 -282.508706)
		(width 0.0889)
		(layer "In4.Cu")
		(net "M_D_CPU0_SB_DQ<12>")
	)
	(arc
		(start 338.118196 -282.508706)
		(mid 338.401152 -282.432529)
		(end 338.684108 -282.508706)
		(width 0.0889)
		(layer "In4.Cu")
		(net "M_D_CPU0_SB_DQ<12>")
	)
	(arc
		(start 332.478126 -282.508706)
		(mid 332.761082 -282.432529)
		(end 333.044038 -282.508706)
		(width 0.0889)
		(layer "In4.Cu")
		(net "M_D_CPU0_SB_DQ<12>")
	)
	(arc
		(start 332.103984 -282.508706)
		(mid 332.286235 -282.559056)
		(end 332.469744 -282.513532)
		(width 0.0889)
		(layer "In4.Cu")
		(net "M_D_CPU0_SB_DQ<12>")
	)
	(arc
		(start 335.863946 -282.508706)
		(mid 336.046197 -282.559056)
		(end 336.229706 -282.513532)
		(width 0.0889)
		(layer "In4.Cu")
		(net "M_D_CPU0_SB_DQ<12>")
	)
	(arc
		(start 337.178142 -282.508706)
		(mid 337.461098 -282.432529)
		(end 337.744054 -282.508706)
		(width 0.0889)
		(layer "In4.Cu")
		(net "M_D_CPU0_SB_DQ<12>")
	)
	(arc
		(start 333.992474 -282.513532)
		(mid 334.175982 -282.559026)
		(end 334.358234 -282.508706)
		(width 0.0889)
		(layer "In4.Cu")
		(net "M_D_CPU0_SB_DQ<12>")
	)
	(segment
		(start 341.218012 -280.300176)
		(end 340.75116 -280.566114)
		(width 0.10668)
		(layer "F.Cu")
		(net "M_D_CPU0_SB_DQ<11>")
	)
	(segment
		(start 305.329844 -292.960044)
		(end 306.983384 -292.960044)
		(width 0.14478)
		(layer "In4.Cu")
		(net "M_D_CPU0_SB_DQ<11>")
	)
	(segment
		(start 336.229706 -280.238708)
		(end 336.238088 -280.243534)
		(width 0.0889)
		(layer "In4.Cu")
		(net "M_D_CPU0_SB_DQ<11>")
	)
	(segment
		(start 328.709782 -280.238708)
		(end 328.718164 -280.243534)
		(width 0.0889)
		(layer "In4.Cu")
		(net "M_D_CPU0_SB_DQ<11>")
	)
	(segment
		(start 333.984092 -280.243534)
		(end 333.992474 -280.238708)
		(width 0.0889)
		(layer "In4.Cu")
		(net "M_D_CPU0_SB_DQ<11>")
	)
	(segment
		(start 313.349894 -287.937956)
		(end 313.349894 -287.071308)
		(width 0.14478)
		(layer "In4.Cu")
		(net "M_D_CPU0_SB_DQ<11>")
	)
	(segment
		(start 307.277516 -292.665912)
		(end 307.534818 -292.665912)
		(width 0.14478)
		(layer "In4.Cu")
		(net "M_D_CPU0_SB_DQ<11>")
	)
	(segment
		(start 306.983384 -292.960044)
		(end 307.277516 -292.665912)
		(width 0.14478)
		(layer "In4.Cu")
		(net "M_D_CPU0_SB_DQ<11>")
	)
	(segment
		(start 333.044038 -280.243534)
		(end 333.05242 -280.238708)
		(width 0.0889)
		(layer "In4.Cu")
		(net "M_D_CPU0_SB_DQ<11>")
	)
	(segment
		(start 289.705288 -293.800276)
		(end 290.555172 -292.950392)
		(width 0.14478)
		(layer "In4.Cu")
		(net "M_D_CPU0_SB_DQ<11>")
	)
	(segment
		(start 307.534818 -292.665912)
		(end 307.82895 -292.960044)
		(width 0.14478)
		(layer "In4.Cu")
		(net "M_D_CPU0_SB_DQ<11>")
	)
	(segment
		(start 307.82895 -292.960044)
		(end 308.327806 -292.960044)
		(width 0.14478)
		(layer "In4.Cu")
		(net "M_D_CPU0_SB_DQ<11>")
	)
	(segment
		(start 304.87493 -293.414958)
		(end 305.329844 -292.960044)
		(width 0.14478)
		(layer "In4.Cu")
		(net "M_D_CPU0_SB_DQ<11>")
	)
	(segment
		(start 320.213482 -280.20772)
		(end 324.256146 -280.20772)
		(width 0.14478)
		(layer "In4.Cu")
		(net "M_D_CPU0_SB_DQ<11>")
	)
	(segment
		(start 338.684108 -280.243534)
		(end 338.69249 -280.238708)
		(width 0.0889)
		(layer "In4.Cu")
		(net "M_D_CPU0_SB_DQ<11>")
	)
	(segment
		(start 293.416736 -292.950392)
		(end 294.26662 -293.800276)
		(width 0.14478)
		(layer "In4.Cu")
		(net "M_D_CPU0_SB_DQ<11>")
	)
	(segment
		(start 301.933102 -293.414958)
		(end 304.87493 -293.414958)
		(width 0.14478)
		(layer "In4.Cu")
		(net "M_D_CPU0_SB_DQ<11>")
	)
	(segment
		(start 328.32929 -280.25217)
		(end 328.344022 -280.243534)
		(width 0.0889)
		(layer "In4.Cu")
		(net "M_D_CPU0_SB_DQ<11>")
	)
	(segment
		(start 313.349894 -287.071308)
		(end 320.213482 -280.20772)
		(width 0.14478)
		(layer "In4.Cu")
		(net "M_D_CPU0_SB_DQ<11>")
	)
	(segment
		(start 340.596982 -280.300684)
		(end 340.75116 -280.566114)
		(width 0.0889)
		(layer "In4.Cu")
		(net "M_D_CPU0_SB_DQ<11>")
	)
	(segment
		(start 301.468536 -292.950392)
		(end 301.933102 -293.414958)
		(width 0.14478)
		(layer "In4.Cu")
		(net "M_D_CPU0_SB_DQ<11>")
	)
	(segment
		(start 340.500716 -280.275284)
		(end 340.596982 -280.300684)
		(width 0.0889)
		(layer "In4.Cu")
		(net "M_D_CPU0_SB_DQ<11>")
	)
	(segment
		(start 308.327806 -292.960044)
		(end 313.349894 -287.937956)
		(width 0.14478)
		(layer "In4.Cu")
		(net "M_D_CPU0_SB_DQ<11>")
	)
	(segment
		(start 281.051254 -293.800276)
		(end 289.705288 -293.800276)
		(width 0.14478)
		(layer "In4.Cu")
		(net "M_D_CPU0_SB_DQ<11>")
	)
	(segment
		(start 337.744054 -280.243534)
		(end 337.752436 -280.238708)
		(width 0.0889)
		(layer "In4.Cu")
		(net "M_D_CPU0_SB_DQ<11>")
	)
	(segment
		(start 324.256146 -280.20772)
		(end 324.544436 -280.20772)
		(width 0.0889)
		(layer "In4.Cu")
		(net "M_D_CPU0_SB_DQ<11>")
	)
	(segment
		(start 294.26662 -293.800276)
		(end 296.971212 -293.800276)
		(width 0.14478)
		(layer "In4.Cu")
		(net "M_D_CPU0_SB_DQ<11>")
	)
	(segment
		(start 297.821096 -292.950392)
		(end 301.468536 -292.950392)
		(width 0.14478)
		(layer "In4.Cu")
		(net "M_D_CPU0_SB_DQ<11>")
	)
	(segment
		(start 280.635964 -293.384986)
		(end 281.051254 -293.800276)
		(width 0.14478)
		(layer "In4.Cu")
		(net "M_D_CPU0_SB_DQ<11>")
	)
	(segment
		(start 331.52969 -280.238708)
		(end 331.538072 -280.243534)
		(width 0.0889)
		(layer "In4.Cu")
		(net "M_D_CPU0_SB_DQ<11>")
	)
	(segment
		(start 296.971212 -293.800276)
		(end 297.821096 -292.950392)
		(width 0.14478)
		(layer "In4.Cu")
		(net "M_D_CPU0_SB_DQ<11>")
	)
	(segment
		(start 290.555172 -292.950392)
		(end 293.416736 -292.950392)
		(width 0.14478)
		(layer "In4.Cu")
		(net "M_D_CPU0_SB_DQ<11>")
	)
	(segment
		(start 337.16976 -280.238708)
		(end 337.178142 -280.243534)
		(width 0.0889)
		(layer "In4.Cu")
		(net "M_D_CPU0_SB_DQ<11>")
	)
	(segment
		(start 329.284076 -280.243534)
		(end 329.292458 -280.238708)
		(width 0.0889)
		(layer "In4.Cu")
		(net "M_D_CPU0_SB_DQ<11>")
	)
	(segment
		(start 324.590664 -280.161492)
		(end 327.474072 -280.161492)
		(width 0.0889)
		(layer "In4.Cu")
		(net "M_D_CPU0_SB_DQ<11>")
	)
	(segment
		(start 332.469744 -280.238708)
		(end 332.478126 -280.243534)
		(width 0.0889)
		(layer "In4.Cu")
		(net "M_D_CPU0_SB_DQ<11>")
	)
	(segment
		(start 324.544436 -280.20772)
		(end 324.590664 -280.161492)
		(width 0.0889)
		(layer "In4.Cu")
		(net "M_D_CPU0_SB_DQ<11>")
	)
	(arc
		(start 337.752436 -280.238708)
		(mid 337.935944 -280.193214)
		(end 338.118196 -280.243534)
		(width 0.0889)
		(layer "In4.Cu")
		(net "M_D_CPU0_SB_DQ<11>")
	)
	(arc
		(start 332.478126 -280.243534)
		(mid 332.761082 -280.319711)
		(end 333.044038 -280.243534)
		(width 0.0889)
		(layer "In4.Cu")
		(net "M_D_CPU0_SB_DQ<11>")
	)
	(arc
		(start 329.658218 -280.243534)
		(mid 329.941174 -280.319711)
		(end 330.22413 -280.243534)
		(width 0.0889)
		(layer "In4.Cu")
		(net "M_D_CPU0_SB_DQ<11>")
	)
	(arc
		(start 335.298034 -280.243534)
		(mid 335.58099 -280.319711)
		(end 335.863946 -280.243534)
		(width 0.0889)
		(layer "In4.Cu")
		(net "M_D_CPU0_SB_DQ<11>")
	)
	(arc
		(start 331.16393 -280.243534)
		(mid 331.346181 -280.193184)
		(end 331.52969 -280.238708)
		(width 0.0889)
		(layer "In4.Cu")
		(net "M_D_CPU0_SB_DQ<11>")
	)
	(arc
		(start 337.178142 -280.243534)
		(mid 337.461098 -280.319711)
		(end 337.744054 -280.243534)
		(width 0.0889)
		(layer "In4.Cu")
		(net "M_D_CPU0_SB_DQ<11>")
	)
	(arc
		(start 329.292458 -280.238708)
		(mid 329.475966 -280.193214)
		(end 329.658218 -280.243534)
		(width 0.0889)
		(layer "In4.Cu")
		(net "M_D_CPU0_SB_DQ<11>")
	)
	(arc
		(start 339.624162 -280.243534)
		(mid 339.811106 -280.193279)
		(end 339.99805 -280.243534)
		(width 0.0889)
		(layer "In4.Cu")
		(net "M_D_CPU0_SB_DQ<11>")
	)
	(arc
		(start 333.05242 -280.238708)
		(mid 333.235928 -280.193214)
		(end 333.41818 -280.243534)
		(width 0.0889)
		(layer "In4.Cu")
		(net "M_D_CPU0_SB_DQ<11>")
	)
	(arc
		(start 327.474072 -280.161492)
		(mid 327.631292 -280.182349)
		(end 327.777602 -280.243534)
		(width 0.0889)
		(layer "In4.Cu")
		(net "M_D_CPU0_SB_DQ<11>")
	)
	(arc
		(start 334.358234 -280.243534)
		(mid 334.64119 -280.319711)
		(end 334.924146 -280.243534)
		(width 0.0889)
		(layer "In4.Cu")
		(net "M_D_CPU0_SB_DQ<11>")
	)
	(arc
		(start 330.598018 -280.243534)
		(mid 330.880974 -280.319711)
		(end 331.16393 -280.243534)
		(width 0.0889)
		(layer "In4.Cu")
		(net "M_D_CPU0_SB_DQ<11>")
	)
	(arc
		(start 336.238088 -280.243534)
		(mid 336.521044 -280.319711)
		(end 336.804 -280.243534)
		(width 0.0889)
		(layer "In4.Cu")
		(net "M_D_CPU0_SB_DQ<11>")
	)
	(arc
		(start 339.05825 -280.243534)
		(mid 339.341206 -280.319711)
		(end 339.624162 -280.243534)
		(width 0.0889)
		(layer "In4.Cu")
		(net "M_D_CPU0_SB_DQ<11>")
	)
	(arc
		(start 332.103984 -280.243534)
		(mid 332.286235 -280.193184)
		(end 332.469744 -280.238708)
		(width 0.0889)
		(layer "In4.Cu")
		(net "M_D_CPU0_SB_DQ<11>")
	)
	(arc
		(start 333.41818 -280.243534)
		(mid 333.701136 -280.319711)
		(end 333.984092 -280.243534)
		(width 0.0889)
		(layer "In4.Cu")
		(net "M_D_CPU0_SB_DQ<11>")
	)
	(arc
		(start 333.992474 -280.238708)
		(mid 334.175982 -280.193214)
		(end 334.358234 -280.243534)
		(width 0.0889)
		(layer "In4.Cu")
		(net "M_D_CPU0_SB_DQ<11>")
	)
	(arc
		(start 338.118196 -280.243534)
		(mid 338.401152 -280.319711)
		(end 338.684108 -280.243534)
		(width 0.0889)
		(layer "In4.Cu")
		(net "M_D_CPU0_SB_DQ<11>")
	)
	(arc
		(start 327.777602 -280.243534)
		(mid 328.052308 -280.319898)
		(end 328.32929 -280.25217)
		(width 0.0889)
		(layer "In4.Cu")
		(net "M_D_CPU0_SB_DQ<11>")
	)
	(arc
		(start 328.718164 -280.243534)
		(mid 329.00112 -280.319711)
		(end 329.284076 -280.243534)
		(width 0.0889)
		(layer "In4.Cu")
		(net "M_D_CPU0_SB_DQ<11>")
	)
	(arc
		(start 334.924146 -280.243534)
		(mid 335.11109 -280.193279)
		(end 335.298034 -280.243534)
		(width 0.0889)
		(layer "In4.Cu")
		(net "M_D_CPU0_SB_DQ<11>")
	)
	(arc
		(start 338.69249 -280.238708)
		(mid 338.875998 -280.193214)
		(end 339.05825 -280.243534)
		(width 0.0889)
		(layer "In4.Cu")
		(net "M_D_CPU0_SB_DQ<11>")
	)
	(arc
		(start 331.538072 -280.243534)
		(mid 331.821028 -280.319711)
		(end 332.103984 -280.243534)
		(width 0.0889)
		(layer "In4.Cu")
		(net "M_D_CPU0_SB_DQ<11>")
	)
	(arc
		(start 336.804 -280.243534)
		(mid 336.986251 -280.193184)
		(end 337.16976 -280.238708)
		(width 0.0889)
		(layer "In4.Cu")
		(net "M_D_CPU0_SB_DQ<11>")
	)
	(arc
		(start 330.22413 -280.243534)
		(mid 330.411074 -280.193279)
		(end 330.598018 -280.243534)
		(width 0.0889)
		(layer "In4.Cu")
		(net "M_D_CPU0_SB_DQ<11>")
	)
	(arc
		(start 335.863946 -280.243534)
		(mid 336.046197 -280.193184)
		(end 336.229706 -280.238708)
		(width 0.0889)
		(layer "In4.Cu")
		(net "M_D_CPU0_SB_DQ<11>")
	)
	(arc
		(start 328.344022 -280.243534)
		(mid 328.526273 -280.193184)
		(end 328.709782 -280.238708)
		(width 0.0889)
		(layer "In4.Cu")
		(net "M_D_CPU0_SB_DQ<11>")
	)
	(arc
		(start 339.99805 -280.243534)
		(mid 340.245646 -280.318712)
		(end 340.500716 -280.275284)
		(width 0.0889)
		(layer "In4.Cu")
		(net "M_D_CPU0_SB_DQ<11>")
	)
	(segment
		(start 339.808058 -279.49017)
		(end 339.341206 -279.756108)
		(width 0.10668)
		(layer "F.Cu")
		(net "M_D_CPU0_SB_DQ<10>")
	)
	(segment
		(start 289.97275 -292.11016)
		(end 290.822888 -291.260022)
		(width 0.14478)
		(layer "In4.Cu")
		(net "M_D_CPU0_SB_DQ<10>")
	)
	(segment
		(start 297.374818 -292.11016)
		(end 298.224956 -291.260022)
		(width 0.14478)
		(layer "In4.Cu")
		(net "M_D_CPU0_SB_DQ<10>")
	)
	(segment
		(start 301.498508 -291.260022)
		(end 302.348646 -292.11016)
		(width 0.14478)
		(layer "In4.Cu")
		(net "M_D_CPU0_SB_DQ<10>")
	)
	(segment
		(start 281.871928 -291.50691)
		(end 282.10256 -291.50691)
		(width 0.14478)
		(layer "In4.Cu")
		(net "M_D_CPU0_SB_DQ<10>")
	)
	(segment
		(start 330.69403 -279.433528)
		(end 330.702412 -279.428702)
		(width 0.0889)
		(layer "In4.Cu")
		(net "M_D_CPU0_SB_DQ<10>")
	)
	(segment
		(start 302.348646 -292.11016)
		(end 304.893218 -292.11016)
		(width 0.14478)
		(layer "In4.Cu")
		(net "M_D_CPU0_SB_DQ<10>")
	)
	(segment
		(start 308.1528 -291.260022)
		(end 308.755796 -291.260022)
		(width 0.14478)
		(layer "In4.Cu")
		(net "M_D_CPU0_SB_DQ<10>")
	)
	(segment
		(start 331.634084 -279.433528)
		(end 331.642466 -279.428702)
		(width 0.0889)
		(layer "In4.Cu")
		(net "M_D_CPU0_SB_DQ<10>")
	)
	(segment
		(start 280.635964 -291.684964)
		(end 281.06116 -292.11016)
		(width 0.14478)
		(layer "In4.Cu")
		(net "M_D_CPU0_SB_DQ<10>")
	)
	(segment
		(start 326.93356 -279.433782)
		(end 326.949816 -279.424384)
		(width 0.0889)
		(layer "In4.Cu")
		(net "M_D_CPU0_SB_DQ<10>")
	)
	(segment
		(start 282.10256 -291.50691)
		(end 282.265374 -291.669724)
		(width 0.14478)
		(layer "In4.Cu")
		(net "M_D_CPU0_SB_DQ<10>")
	)
	(segment
		(start 324.44563 -279.2984)
		(end 324.659498 -279.084532)
		(width 0.0889)
		(layer "In4.Cu")
		(net "M_D_CPU0_SB_DQ<10>")
	)
	(segment
		(start 298.224956 -291.260022)
		(end 301.498508 -291.260022)
		(width 0.14478)
		(layer "In4.Cu")
		(net "M_D_CPU0_SB_DQ<10>")
	)
	(segment
		(start 305.743356 -291.260022)
		(end 307.303424 -291.260022)
		(width 0.14478)
		(layer "In4.Cu")
		(net "M_D_CPU0_SB_DQ<10>")
	)
	(segment
		(start 319.7987 -279.2984)
		(end 324.285864 -279.2984)
		(width 0.14478)
		(layer "In4.Cu")
		(net "M_D_CPU0_SB_DQ<10>")
	)
	(segment
		(start 324.285864 -279.2984)
		(end 324.44563 -279.2984)
		(width 0.0889)
		(layer "In4.Cu")
		(net "M_D_CPU0_SB_DQ<10>")
	)
	(segment
		(start 304.893218 -292.11016)
		(end 305.743356 -291.260022)
		(width 0.14478)
		(layer "In4.Cu")
		(net "M_D_CPU0_SB_DQ<10>")
	)
	(segment
		(start 310.250586 -288.846514)
		(end 319.7987 -279.2984)
		(width 0.14478)
		(layer "In4.Cu")
		(net "M_D_CPU0_SB_DQ<10>")
	)
	(segment
		(start 334.819752 -279.428702)
		(end 334.828134 -279.433528)
		(width 0.0889)
		(layer "In4.Cu")
		(net "M_D_CPU0_SB_DQ<10>")
	)
	(segment
		(start 307.58384 -290.979606)
		(end 307.872384 -290.979606)
		(width 0.14478)
		(layer "In4.Cu")
		(net "M_D_CPU0_SB_DQ<10>")
	)
	(segment
		(start 339.090762 -279.465278)
		(end 339.187028 -279.490678)
		(width 0.0889)
		(layer "In4.Cu")
		(net "M_D_CPU0_SB_DQ<10>")
	)
	(segment
		(start 282.265374 -291.947346)
		(end 282.428188 -292.11016)
		(width 0.14478)
		(layer "In4.Cu")
		(net "M_D_CPU0_SB_DQ<10>")
	)
	(segment
		(start 336.3341 -279.433528)
		(end 336.342482 -279.428702)
		(width 0.0889)
		(layer "In4.Cu")
		(net "M_D_CPU0_SB_DQ<10>")
	)
	(segment
		(start 281.709114 -291.669724)
		(end 281.871928 -291.50691)
		(width 0.14478)
		(layer "In4.Cu")
		(net "M_D_CPU0_SB_DQ<10>")
	)
	(segment
		(start 327.307448 -279.433528)
		(end 327.317862 -279.439624)
		(width 0.0889)
		(layer "In4.Cu")
		(net "M_D_CPU0_SB_DQ<10>")
	)
	(segment
		(start 281.5463 -292.11016)
		(end 281.709114 -291.947346)
		(width 0.14478)
		(layer "In4.Cu")
		(net "M_D_CPU0_SB_DQ<10>")
	)
	(segment
		(start 281.709114 -291.947346)
		(end 281.709114 -291.669724)
		(width 0.14478)
		(layer "In4.Cu")
		(net "M_D_CPU0_SB_DQ<10>")
	)
	(segment
		(start 307.303424 -291.260022)
		(end 307.58384 -290.979606)
		(width 0.14478)
		(layer "In4.Cu")
		(net "M_D_CPU0_SB_DQ<10>")
	)
	(segment
		(start 281.06116 -292.11016)
		(end 281.5463 -292.11016)
		(width 0.14478)
		(layer "In4.Cu")
		(net "M_D_CPU0_SB_DQ<10>")
	)
	(segment
		(start 330.119736 -279.428702)
		(end 330.128118 -279.433528)
		(width 0.0889)
		(layer "In4.Cu")
		(net "M_D_CPU0_SB_DQ<10>")
	)
	(segment
		(start 290.822888 -291.260022)
		(end 293.27602 -291.260022)
		(width 0.14478)
		(layer "In4.Cu")
		(net "M_D_CPU0_SB_DQ<10>")
	)
	(segment
		(start 325.991982 -279.084532)
		(end 326.252332 -279.344882)
		(width 0.0889)
		(layer "In4.Cu")
		(net "M_D_CPU0_SB_DQ<10>")
	)
	(segment
		(start 308.755796 -291.260022)
		(end 310.250586 -289.765232)
		(width 0.14478)
		(layer "In4.Cu")
		(net "M_D_CPU0_SB_DQ<10>")
	)
	(segment
		(start 338.579714 -279.428702)
		(end 338.588096 -279.433528)
		(width 0.0889)
		(layer "In4.Cu")
		(net "M_D_CPU0_SB_DQ<10>")
	)
	(segment
		(start 326.917812 -279.442926)
		(end 326.93356 -279.433782)
		(width 0.0889)
		(layer "In4.Cu")
		(net "M_D_CPU0_SB_DQ<10>")
	)
	(segment
		(start 282.428188 -292.11016)
		(end 289.97275 -292.11016)
		(width 0.14478)
		(layer "In4.Cu")
		(net "M_D_CPU0_SB_DQ<10>")
	)
	(segment
		(start 293.27602 -291.260022)
		(end 294.126158 -292.11016)
		(width 0.14478)
		(layer "In4.Cu")
		(net "M_D_CPU0_SB_DQ<10>")
	)
	(segment
		(start 294.126158 -292.11016)
		(end 297.374818 -292.11016)
		(width 0.14478)
		(layer "In4.Cu")
		(net "M_D_CPU0_SB_DQ<10>")
	)
	(segment
		(start 339.187028 -279.490678)
		(end 339.341206 -279.756108)
		(width 0.0889)
		(layer "In4.Cu")
		(net "M_D_CPU0_SB_DQ<10>")
	)
	(segment
		(start 307.872384 -290.979606)
		(end 308.1528 -291.260022)
		(width 0.14478)
		(layer "In4.Cu")
		(net "M_D_CPU0_SB_DQ<10>")
	)
	(segment
		(start 333.879698 -279.428702)
		(end 333.88808 -279.433528)
		(width 0.0889)
		(layer "In4.Cu")
		(net "M_D_CPU0_SB_DQ<10>")
	)
	(segment
		(start 310.250586 -289.765232)
		(end 310.250586 -288.846514)
		(width 0.14478)
		(layer "In4.Cu")
		(net "M_D_CPU0_SB_DQ<10>")
	)
	(segment
		(start 282.265374 -291.669724)
		(end 282.265374 -291.947346)
		(width 0.14478)
		(layer "In4.Cu")
		(net "M_D_CPU0_SB_DQ<10>")
	)
	(segment
		(start 324.659498 -279.084532)
		(end 325.991982 -279.084532)
		(width 0.0889)
		(layer "In4.Cu")
		(net "M_D_CPU0_SB_DQ<10>")
	)
	(segment
		(start 328.239882 -279.428702)
		(end 328.248264 -279.433528)
		(width 0.0889)
		(layer "In4.Cu")
		(net "M_D_CPU0_SB_DQ<10>")
	)
	(segment
		(start 335.394046 -279.433528)
		(end 335.402428 -279.428702)
		(width 0.0889)
		(layer "In4.Cu")
		(net "M_D_CPU0_SB_DQ<10>")
	)
	(arc
		(start 332.574138 -279.433528)
		(mid 332.761082 -279.383273)
		(end 332.948026 -279.433528)
		(width 0.0889)
		(layer "In4.Cu")
		(net "M_D_CPU0_SB_DQ<10>")
	)
	(arc
		(start 330.128118 -279.433528)
		(mid 330.411074 -279.509705)
		(end 330.69403 -279.433528)
		(width 0.0889)
		(layer "In4.Cu")
		(net "M_D_CPU0_SB_DQ<10>")
	)
	(arc
		(start 333.513938 -279.433528)
		(mid 333.696189 -279.383178)
		(end 333.879698 -279.428702)
		(width 0.0889)
		(layer "In4.Cu")
		(net "M_D_CPU0_SB_DQ<10>")
	)
	(arc
		(start 327.873614 -279.433528)
		(mid 328.056119 -279.383051)
		(end 328.239882 -279.428702)
		(width 0.0889)
		(layer "In4.Cu")
		(net "M_D_CPU0_SB_DQ<10>")
	)
	(arc
		(start 331.642466 -279.428702)
		(mid 331.825974 -279.383208)
		(end 332.008226 -279.433528)
		(width 0.0889)
		(layer "In4.Cu")
		(net "M_D_CPU0_SB_DQ<10>")
	)
	(arc
		(start 328.248264 -279.433528)
		(mid 328.53122 -279.509705)
		(end 328.814176 -279.433528)
		(width 0.0889)
		(layer "In4.Cu")
		(net "M_D_CPU0_SB_DQ<10>")
	)
	(arc
		(start 335.768188 -279.433528)
		(mid 336.051144 -279.509705)
		(end 336.3341 -279.433528)
		(width 0.0889)
		(layer "In4.Cu")
		(net "M_D_CPU0_SB_DQ<10>")
	)
	(arc
		(start 333.88808 -279.433528)
		(mid 334.171036 -279.509705)
		(end 334.453992 -279.433528)
		(width 0.0889)
		(layer "In4.Cu")
		(net "M_D_CPU0_SB_DQ<10>")
	)
	(arc
		(start 330.702412 -279.428702)
		(mid 330.88592 -279.383208)
		(end 331.068172 -279.433528)
		(width 0.0889)
		(layer "In4.Cu")
		(net "M_D_CPU0_SB_DQ<10>")
	)
	(arc
		(start 328.814176 -279.433528)
		(mid 329.00112 -279.383273)
		(end 329.188064 -279.433528)
		(width 0.0889)
		(layer "In4.Cu")
		(net "M_D_CPU0_SB_DQ<10>")
	)
	(arc
		(start 335.402428 -279.428702)
		(mid 335.585936 -279.383208)
		(end 335.768188 -279.433528)
		(width 0.0889)
		(layer "In4.Cu")
		(net "M_D_CPU0_SB_DQ<10>")
	)
	(arc
		(start 331.068172 -279.433528)
		(mid 331.351128 -279.509705)
		(end 331.634084 -279.433528)
		(width 0.0889)
		(layer "In4.Cu")
		(net "M_D_CPU0_SB_DQ<10>")
	)
	(arc
		(start 337.648042 -279.433528)
		(mid 337.930998 -279.509705)
		(end 338.213954 -279.433528)
		(width 0.0889)
		(layer "In4.Cu")
		(net "M_D_CPU0_SB_DQ<10>")
	)
	(arc
		(start 326.949816 -279.424384)
		(mid 327.129798 -279.383284)
		(end 327.307448 -279.433528)
		(width 0.0889)
		(layer "In4.Cu")
		(net "M_D_CPU0_SB_DQ<10>")
	)
	(arc
		(start 338.213954 -279.433528)
		(mid 338.396205 -279.383178)
		(end 338.579714 -279.428702)
		(width 0.0889)
		(layer "In4.Cu")
		(net "M_D_CPU0_SB_DQ<10>")
	)
	(arc
		(start 326.367648 -279.433528)
		(mid 326.641503 -279.509878)
		(end 326.917812 -279.442926)
		(width 0.0889)
		(layer "In4.Cu")
		(net "M_D_CPU0_SB_DQ<10>")
	)
	(arc
		(start 338.588096 -279.433528)
		(mid 338.835692 -279.508706)
		(end 339.090762 -279.465278)
		(width 0.0889)
		(layer "In4.Cu")
		(net "M_D_CPU0_SB_DQ<10>")
	)
	(arc
		(start 334.828134 -279.433528)
		(mid 335.11109 -279.509705)
		(end 335.394046 -279.433528)
		(width 0.0889)
		(layer "In4.Cu")
		(net "M_D_CPU0_SB_DQ<10>")
	)
	(arc
		(start 336.342482 -279.428702)
		(mid 336.52599 -279.383208)
		(end 336.708242 -279.433528)
		(width 0.0889)
		(layer "In4.Cu")
		(net "M_D_CPU0_SB_DQ<10>")
	)
	(arc
		(start 329.188064 -279.433528)
		(mid 329.47102 -279.509705)
		(end 329.753976 -279.433528)
		(width 0.0889)
		(layer "In4.Cu")
		(net "M_D_CPU0_SB_DQ<10>")
	)
	(arc
		(start 334.453992 -279.433528)
		(mid 334.636243 -279.383178)
		(end 334.819752 -279.428702)
		(width 0.0889)
		(layer "In4.Cu")
		(net "M_D_CPU0_SB_DQ<10>")
	)
	(arc
		(start 326.252332 -279.344882)
		(mid 326.307117 -279.392942)
		(end 326.367648 -279.433528)
		(width 0.0889)
		(layer "In4.Cu")
		(net "M_D_CPU0_SB_DQ<10>")
	)
	(arc
		(start 332.948026 -279.433528)
		(mid 333.230982 -279.509705)
		(end 333.513938 -279.433528)
		(width 0.0889)
		(layer "In4.Cu")
		(net "M_D_CPU0_SB_DQ<10>")
	)
	(arc
		(start 332.008226 -279.433528)
		(mid 332.291182 -279.509705)
		(end 332.574138 -279.433528)
		(width 0.0889)
		(layer "In4.Cu")
		(net "M_D_CPU0_SB_DQ<10>")
	)
	(arc
		(start 336.708242 -279.433528)
		(mid 336.991198 -279.509705)
		(end 337.274154 -279.433528)
		(width 0.0889)
		(layer "In4.Cu")
		(net "M_D_CPU0_SB_DQ<10>")
	)
	(arc
		(start 327.317862 -279.439624)
		(mid 327.596548 -279.509844)
		(end 327.873614 -279.433528)
		(width 0.0889)
		(layer "In4.Cu")
		(net "M_D_CPU0_SB_DQ<10>")
	)
	(arc
		(start 329.753976 -279.433528)
		(mid 329.936227 -279.383178)
		(end 330.119736 -279.428702)
		(width 0.0889)
		(layer "In4.Cu")
		(net "M_D_CPU0_SB_DQ<10>")
	)
	(arc
		(start 337.274154 -279.433528)
		(mid 337.461098 -279.383273)
		(end 337.648042 -279.433528)
		(width 0.0889)
		(layer "In4.Cu")
		(net "M_D_CPU0_SB_DQ<10>")
	)
	(segment
		(start 339.337904 -273.820128)
		(end 338.871052 -274.086066)
		(width 0.10668)
		(layer "F.Cu")
		(net "M_D_CPU0_SB_DQ<0>")
	)
	(segment
		(start 307.612542 -281.05989)
		(end 308.33314 -280.339292)
		(width 0.14478)
		(layer "In4.Cu")
		(net "M_D_CPU0_SB_DQ<0>")
	)
	(segment
		(start 312.010044 -276.89048)
		(end 312.010044 -276.662388)
		(width 0.14478)
		(layer "In4.Cu")
		(net "M_D_CPU0_SB_DQ<0>")
	)
	(segment
		(start 325.475092 -273.438112)
		(end 326.386952 -274.349972)
		(width 0.0889)
		(layer "In4.Cu")
		(net "M_D_CPU0_SB_DQ<0>")
	)
	(segment
		(start 285.751524 -282.269946)
		(end 285.914338 -282.107132)
		(width 0.14478)
		(layer "In4.Cu")
		(net "M_D_CPU0_SB_DQ<0>")
	)
	(segment
		(start 313.57062 -275.101812)
		(end 313.795156 -274.877276)
		(width 0.14478)
		(layer "In4.Cu")
		(net "M_D_CPU0_SB_DQ<0>")
	)
	(segment
		(start 302.645572 -281.382216)
		(end 302.645572 -281.748484)
		(width 0.14478)
		(layer "In4.Cu")
		(net "M_D_CPU0_SB_DQ<0>")
	)
	(segment
		(start 287.223962 -281.910028)
		(end 290.24199 -281.910028)
		(width 0.14478)
		(layer "In4.Cu")
		(net "M_D_CPU0_SB_DQ<0>")
	)
	(segment
		(start 314.350908 -274.321524)
		(end 314.575444 -274.096988)
		(width 0.14478)
		(layer "In4.Cu")
		(net "M_D_CPU0_SB_DQ<0>")
	)
	(segment
		(start 310.674004 -277.998428)
		(end 311.005474 -277.998428)
		(width 0.14478)
		(layer "In4.Cu")
		(net "M_D_CPU0_SB_DQ<0>")
	)
	(segment
		(start 333.044038 -274.408646)
		(end 333.05242 -274.413472)
		(width 0.0889)
		(layer "In4.Cu")
		(net "M_D_CPU0_SB_DQ<0>")
	)
	(segment
		(start 314.126626 -274.877276)
		(end 314.351162 -274.65274)
		(width 0.14478)
		(layer "In4.Cu")
		(net "M_D_CPU0_SB_DQ<0>")
	)
	(segment
		(start 312.790586 -276.213316)
		(end 312.790332 -276.110192)
		(width 0.14478)
		(layer "In4.Cu")
		(net "M_D_CPU0_SB_DQ<0>")
	)
	(segment
		(start 339.002878 -274.434808)
		(end 339.02523 -274.351496)
		(width 0.0889)
		(layer "In4.Cu")
		(net "M_D_CPU0_SB_DQ<0>")
	)
	(segment
		(start 339.02523 -274.351496)
		(end 338.871052 -274.086066)
		(width 0.0889)
		(layer "In4.Cu")
		(net "M_D_CPU0_SB_DQ<0>")
	)
	(segment
		(start 308.888892 -279.78354)
		(end 309.113428 -279.559004)
		(width 0.14478)
		(layer "In4.Cu")
		(net "M_D_CPU0_SB_DQ<0>")
	)
	(segment
		(start 290.24199 -281.910028)
		(end 291.092128 -281.05989)
		(width 0.14478)
		(layer "In4.Cu")
		(net "M_D_CPU0_SB_DQ<0>")
	)
	(segment
		(start 304.80381 -281.910028)
		(end 305.653948 -281.05989)
		(width 0.14478)
		(layer "In4.Cu")
		(net "M_D_CPU0_SB_DQ<0>")
	)
	(segment
		(start 306.361084 -281.05989)
		(end 306.522628 -281.221434)
		(width 0.14478)
		(layer "In4.Cu")
		(net "M_D_CPU0_SB_DQ<0>")
	)
	(segment
		(start 298.776644 -281.329892)
		(end 299.058076 -281.329892)
		(width 0.14478)
		(layer "In4.Cu")
		(net "M_D_CPU0_SB_DQ<0>")
	)
	(segment
		(start 302.255682 -281.220672)
		(end 302.484028 -281.220672)
		(width 0.14478)
		(layer "In4.Cu")
		(net "M_D_CPU0_SB_DQ<0>")
	)
	(segment
		(start 313.346338 -275.657564)
		(end 313.570874 -275.433028)
		(width 0.14478)
		(layer "In4.Cu")
		(net "M_D_CPU0_SB_DQ<0>")
	)
	(segment
		(start 285.914338 -281.779218)
		(end 286.077152 -281.616404)
		(width 0.14478)
		(layer "In4.Cu")
		(net "M_D_CPU0_SB_DQ<0>")
	)
	(segment
		(start 303.930812 -281.748484)
		(end 303.930812 -281.402536)
		(width 0.14478)
		(layer "In4.Cu")
		(net "M_D_CPU0_SB_DQ<0>")
	)
	(segment
		(start 291.092128 -281.05989)
		(end 293.15918 -281.05989)
		(width 0.14478)
		(layer "In4.Cu")
		(net "M_D_CPU0_SB_DQ<0>")
	)
	(segment
		(start 307.074062 -281.221434)
		(end 307.235606 -281.05989)
		(width 0.14478)
		(layer "In4.Cu")
		(net "M_D_CPU0_SB_DQ<0>")
	)
	(segment
		(start 309.113428 -279.559004)
		(end 309.444898 -279.559004)
		(width 0.14478)
		(layer "In4.Cu")
		(net "M_D_CPU0_SB_DQ<0>")
	)
	(segment
		(start 311.785762 -277.21814)
		(end 312.010298 -276.993604)
		(width 0.14478)
		(layer "In4.Cu")
		(net "M_D_CPU0_SB_DQ<0>")
	)
	(segment
		(start 336.229706 -274.413472)
		(end 336.238088 -274.408646)
		(width 0.0889)
		(layer "In4.Cu")
		(net "M_D_CPU0_SB_DQ<0>")
	)
	(segment
		(start 302.094138 -281.382216)
		(end 302.255682 -281.220672)
		(width 0.14478)
		(layer "In4.Cu")
		(net "M_D_CPU0_SB_DQ<0>")
	)
	(segment
		(start 332.469744 -274.413472)
		(end 332.478126 -274.408646)
		(width 0.0889)
		(layer "In4.Cu")
		(net "M_D_CPU0_SB_DQ<0>")
	)
	(segment
		(start 312.010044 -276.662388)
		(end 312.23458 -276.437852)
		(width 0.14478)
		(layer "In4.Cu")
		(net "M_D_CPU0_SB_DQ<0>")
	)
	(segment
		(start 313.014868 -275.657564)
		(end 313.346338 -275.657564)
		(width 0.14478)
		(layer "In4.Cu")
		(net "M_D_CPU0_SB_DQ<0>")
	)
	(segment
		(start 299.058076 -281.329892)
		(end 299.328078 -281.05989)
		(width 0.14478)
		(layer "In4.Cu")
		(net "M_D_CPU0_SB_DQ<0>")
	)
	(segment
		(start 307.074062 -281.280108)
		(end 307.074062 -281.221434)
		(width 0.14478)
		(layer "In4.Cu")
		(net "M_D_CPU0_SB_DQ<0>")
	)
	(segment
		(start 308.66461 -280.339292)
		(end 308.889146 -280.114756)
		(width 0.14478)
		(layer "In4.Cu")
		(net "M_D_CPU0_SB_DQ<0>")
	)
	(segment
		(start 311.005474 -277.998428)
		(end 311.23001 -277.773892)
		(width 0.14478)
		(layer "In4.Cu")
		(net "M_D_CPU0_SB_DQ<0>")
	)
	(segment
		(start 314.575444 -274.096988)
		(end 314.906914 -274.096988)
		(width 0.14478)
		(layer "In4.Cu")
		(net "M_D_CPU0_SB_DQ<0>")
	)
	(segment
		(start 305.653948 -281.05989)
		(end 306.361084 -281.05989)
		(width 0.14478)
		(layer "In4.Cu")
		(net "M_D_CPU0_SB_DQ<0>")
	)
	(segment
		(start 297.043856 -282.28671)
		(end 298.270676 -281.05989)
		(width 0.14478)
		(layer "In4.Cu")
		(net "M_D_CPU0_SB_DQ<0>")
	)
	(segment
		(start 298.270676 -281.05989)
		(end 298.506642 -281.05989)
		(width 0.14478)
		(layer "In4.Cu")
		(net "M_D_CPU0_SB_DQ<0>")
	)
	(segment
		(start 293.15918 -281.05989)
		(end 294.009826 -281.910282)
		(width 0.14478)
		(layer "In4.Cu")
		(net "M_D_CPU0_SB_DQ<0>")
	)
	(segment
		(start 302.094138 -281.748484)
		(end 302.094138 -281.382216)
		(width 0.14478)
		(layer "In4.Cu")
		(net "M_D_CPU0_SB_DQ<0>")
	)
	(segment
		(start 327.403206 -274.408646)
		(end 327.411588 -274.413472)
		(width 0.0889)
		(layer "In4.Cu")
		(net "M_D_CPU0_SB_DQ<0>")
	)
	(segment
		(start 309.893716 -278.778716)
		(end 310.225186 -278.778716)
		(width 0.14478)
		(layer "In4.Cu")
		(net "M_D_CPU0_SB_DQ<0>")
	)
	(segment
		(start 326.819514 -274.418806)
		(end 326.837802 -274.408392)
		(width 0.0889)
		(layer "In4.Cu")
		(net "M_D_CPU0_SB_DQ<0>")
	)
	(segment
		(start 311.454292 -277.21814)
		(end 311.785762 -277.21814)
		(width 0.14478)
		(layer "In4.Cu")
		(net "M_D_CPU0_SB_DQ<0>")
	)
	(segment
		(start 311.229756 -277.670768)
		(end 311.229756 -277.442676)
		(width 0.14478)
		(layer "In4.Cu")
		(net "M_D_CPU0_SB_DQ<0>")
	)
	(segment
		(start 294.670988 -282.216352)
		(end 294.916098 -282.216352)
		(width 0.14478)
		(layer "In4.Cu")
		(net "M_D_CPU0_SB_DQ<0>")
	)
	(segment
		(start 286.470598 -281.779218)
		(end 286.470598 -282.107132)
		(width 0.14478)
		(layer "In4.Cu")
		(net "M_D_CPU0_SB_DQ<0>")
	)
	(segment
		(start 315.131196 -273.769328)
		(end 315.131196 -273.541236)
		(width 0.14478)
		(layer "In4.Cu")
		(net "M_D_CPU0_SB_DQ<0>")
	)
	(segment
		(start 294.364664 -281.910028)
		(end 294.670988 -282.216352)
		(width 0.14478)
		(layer "In4.Cu")
		(net "M_D_CPU0_SB_DQ<0>")
	)
	(segment
		(start 313.795156 -274.877276)
		(end 314.126626 -274.877276)
		(width 0.14478)
		(layer "In4.Cu")
		(net "M_D_CPU0_SB_DQ<0>")
	)
	(segment
		(start 308.889146 -280.114756)
		(end 308.888892 -280.011632)
		(width 0.14478)
		(layer "In4.Cu")
		(net "M_D_CPU0_SB_DQ<0>")
	)
	(segment
		(start 333.984092 -274.408646)
		(end 333.992474 -274.413472)
		(width 0.0889)
		(layer "In4.Cu")
		(net "M_D_CPU0_SB_DQ<0>")
	)
	(segment
		(start 298.506642 -281.05989)
		(end 298.776644 -281.329892)
		(width 0.14478)
		(layer "In4.Cu")
		(net "M_D_CPU0_SB_DQ<0>")
	)
	(segment
		(start 315.131196 -273.541236)
		(end 315.452252 -273.22018)
		(width 0.14478)
		(layer "In4.Cu")
		(net "M_D_CPU0_SB_DQ<0>")
	)
	(segment
		(start 286.470598 -282.107132)
		(end 286.633412 -282.269946)
		(width 0.14478)
		(layer "In4.Cu")
		(net "M_D_CPU0_SB_DQ<0>")
	)
	(segment
		(start 310.449722 -278.55418)
		(end 310.449468 -278.451056)
		(width 0.14478)
		(layer "In4.Cu")
		(net "M_D_CPU0_SB_DQ<0>")
	)
	(segment
		(start 301.654718 -281.910028)
		(end 301.932594 -281.910028)
		(width 0.14478)
		(layer "In4.Cu")
		(net "M_D_CPU0_SB_DQ<0>")
	)
	(segment
		(start 324.757796 -273.438112)
		(end 325.475092 -273.438112)
		(width 0.0889)
		(layer "In4.Cu")
		(net "M_D_CPU0_SB_DQ<0>")
	)
	(segment
		(start 303.930812 -281.402536)
		(end 304.092356 -281.240992)
		(width 0.14478)
		(layer "In4.Cu")
		(net "M_D_CPU0_SB_DQ<0>")
	)
	(segment
		(start 301.932594 -281.910028)
		(end 302.094138 -281.748484)
		(width 0.14478)
		(layer "In4.Cu")
		(net "M_D_CPU0_SB_DQ<0>")
	)
	(segment
		(start 338.684108 -274.408646)
		(end 338.69249 -274.413472)
		(width 0.0889)
		(layer "In4.Cu")
		(net "M_D_CPU0_SB_DQ<0>")
	)
	(segment
		(start 302.484028 -281.220672)
		(end 302.645572 -281.382216)
		(width 0.14478)
		(layer "In4.Cu")
		(net "M_D_CPU0_SB_DQ<0>")
	)
	(segment
		(start 311.229756 -277.442676)
		(end 311.454292 -277.21814)
		(width 0.14478)
		(layer "In4.Cu")
		(net "M_D_CPU0_SB_DQ<0>")
	)
	(segment
		(start 296.163492 -281.910028)
		(end 296.540174 -282.28671)
		(width 0.14478)
		(layer "In4.Cu")
		(net "M_D_CPU0_SB_DQ<0>")
	)
	(segment
		(start 284.736032 -281.485086)
		(end 285.520892 -282.269946)
		(width 0.14478)
		(layer "In4.Cu")
		(net "M_D_CPU0_SB_DQ<0>")
	)
	(segment
		(start 313.57062 -275.329904)
		(end 313.57062 -275.101812)
		(width 0.14478)
		(layer "In4.Cu")
		(net "M_D_CPU0_SB_DQ<0>")
	)
	(segment
		(start 306.684172 -281.441652)
		(end 306.912518 -281.441652)
		(width 0.14478)
		(layer "In4.Cu")
		(net "M_D_CPU0_SB_DQ<0>")
	)
	(segment
		(start 313.570874 -275.433028)
		(end 313.57062 -275.329904)
		(width 0.14478)
		(layer "In4.Cu")
		(net "M_D_CPU0_SB_DQ<0>")
	)
	(segment
		(start 299.328078 -281.05989)
		(end 300.80458 -281.05989)
		(width 0.14478)
		(layer "In4.Cu")
		(net "M_D_CPU0_SB_DQ<0>")
	)
	(segment
		(start 286.864044 -282.269946)
		(end 287.223962 -281.910028)
		(width 0.14478)
		(layer "In4.Cu")
		(net "M_D_CPU0_SB_DQ<0>")
	)
	(segment
		(start 307.235606 -281.05989)
		(end 307.612542 -281.05989)
		(width 0.14478)
		(layer "In4.Cu")
		(net "M_D_CPU0_SB_DQ<0>")
	)
	(segment
		(start 312.790332 -275.8821)
		(end 313.014868 -275.657564)
		(width 0.14478)
		(layer "In4.Cu")
		(net "M_D_CPU0_SB_DQ<0>")
	)
	(segment
		(start 309.66918 -279.003252)
		(end 309.893716 -278.778716)
		(width 0.14478)
		(layer "In4.Cu")
		(net "M_D_CPU0_SB_DQ<0>")
	)
	(segment
		(start 314.350908 -274.549616)
		(end 314.350908 -274.321524)
		(width 0.14478)
		(layer "In4.Cu")
		(net "M_D_CPU0_SB_DQ<0>")
	)
	(segment
		(start 296.540174 -282.28671)
		(end 297.043856 -282.28671)
		(width 0.14478)
		(layer "In4.Cu")
		(net "M_D_CPU0_SB_DQ<0>")
	)
	(segment
		(start 304.092356 -281.240992)
		(end 304.320702 -281.240992)
		(width 0.14478)
		(layer "In4.Cu")
		(net "M_D_CPU0_SB_DQ<0>")
	)
	(segment
		(start 312.010298 -276.993604)
		(end 312.010044 -276.89048)
		(width 0.14478)
		(layer "In4.Cu")
		(net "M_D_CPU0_SB_DQ<0>")
	)
	(segment
		(start 295.222422 -281.910028)
		(end 296.163492 -281.910028)
		(width 0.14478)
		(layer "In4.Cu")
		(net "M_D_CPU0_SB_DQ<0>")
	)
	(segment
		(start 309.66918 -279.231344)
		(end 309.66918 -279.003252)
		(width 0.14478)
		(layer "In4.Cu")
		(net "M_D_CPU0_SB_DQ<0>")
	)
	(segment
		(start 286.077152 -281.616404)
		(end 286.307784 -281.616404)
		(width 0.14478)
		(layer "In4.Cu")
		(net "M_D_CPU0_SB_DQ<0>")
	)
	(segment
		(start 286.633412 -282.269946)
		(end 286.864044 -282.269946)
		(width 0.14478)
		(layer "In4.Cu")
		(net "M_D_CPU0_SB_DQ<0>")
	)
	(segment
		(start 285.520892 -282.269946)
		(end 285.751524 -282.269946)
		(width 0.14478)
		(layer "In4.Cu")
		(net "M_D_CPU0_SB_DQ<0>")
	)
	(segment
		(start 311.23001 -277.773892)
		(end 311.229756 -277.670768)
		(width 0.14478)
		(layer "In4.Cu")
		(net "M_D_CPU0_SB_DQ<0>")
	)
	(segment
		(start 337.744054 -274.408646)
		(end 337.752436 -274.413472)
		(width 0.0889)
		(layer "In4.Cu")
		(net "M_D_CPU0_SB_DQ<0>")
	)
	(segment
		(start 308.33314 -280.339292)
		(end 308.66461 -280.339292)
		(width 0.14478)
		(layer "In4.Cu")
		(net "M_D_CPU0_SB_DQ<0>")
	)
	(segment
		(start 326.463406 -274.408646)
		(end 326.46366 -274.408646)
		(width 0.0889)
		(layer "In4.Cu")
		(net "M_D_CPU0_SB_DQ<0>")
	)
	(segment
		(start 312.56605 -276.437852)
		(end 312.790586 -276.213316)
		(width 0.14478)
		(layer "In4.Cu")
		(net "M_D_CPU0_SB_DQ<0>")
	)
	(segment
		(start 294.009826 -281.910282)
		(end 294.01008 -281.910028)
		(width 0.14478)
		(layer "In4.Cu")
		(net "M_D_CPU0_SB_DQ<0>")
	)
	(segment
		(start 329.284076 -274.408646)
		(end 329.292458 -274.413472)
		(width 0.0889)
		(layer "In4.Cu")
		(net "M_D_CPU0_SB_DQ<0>")
	)
	(segment
		(start 314.906914 -274.096988)
		(end 315.13145 -273.872452)
		(width 0.14478)
		(layer "In4.Cu")
		(net "M_D_CPU0_SB_DQ<0>")
	)
	(segment
		(start 328.709782 -274.413472)
		(end 328.718164 -274.408646)
		(width 0.0889)
		(layer "In4.Cu")
		(net "M_D_CPU0_SB_DQ<0>")
	)
	(segment
		(start 304.482246 -281.748484)
		(end 304.64379 -281.910028)
		(width 0.14478)
		(layer "In4.Cu")
		(net "M_D_CPU0_SB_DQ<0>")
	)
	(segment
		(start 306.522628 -281.221434)
		(end 306.522628 -281.280108)
		(width 0.14478)
		(layer "In4.Cu")
		(net "M_D_CPU0_SB_DQ<0>")
	)
	(segment
		(start 310.449468 -278.222964)
		(end 310.674004 -277.998428)
		(width 0.14478)
		(layer "In4.Cu")
		(net "M_D_CPU0_SB_DQ<0>")
	)
	(segment
		(start 303.769268 -281.910028)
		(end 303.930812 -281.748484)
		(width 0.14478)
		(layer "In4.Cu")
		(net "M_D_CPU0_SB_DQ<0>")
	)
	(segment
		(start 324.539864 -273.22018)
		(end 324.757796 -273.438112)
		(width 0.0889)
		(layer "In4.Cu")
		(net "M_D_CPU0_SB_DQ<0>")
	)
	(segment
		(start 314.351162 -274.65274)
		(end 314.350908 -274.549616)
		(width 0.14478)
		(layer "In4.Cu")
		(net "M_D_CPU0_SB_DQ<0>")
	)
	(segment
		(start 309.444898 -279.559004)
		(end 309.669434 -279.334468)
		(width 0.14478)
		(layer "In4.Cu")
		(net "M_D_CPU0_SB_DQ<0>")
	)
	(segment
		(start 306.912518 -281.441652)
		(end 307.074062 -281.280108)
		(width 0.14478)
		(layer "In4.Cu")
		(net "M_D_CPU0_SB_DQ<0>")
	)
	(segment
		(start 294.01008 -281.910028)
		(end 294.364664 -281.910028)
		(width 0.14478)
		(layer "In4.Cu")
		(net "M_D_CPU0_SB_DQ<0>")
	)
	(segment
		(start 315.13145 -273.872452)
		(end 315.131196 -273.769328)
		(width 0.14478)
		(layer "In4.Cu")
		(net "M_D_CPU0_SB_DQ<0>")
	)
	(segment
		(start 315.452252 -273.22018)
		(end 324.539864 -273.22018)
		(width 0.14478)
		(layer "In4.Cu")
		(net "M_D_CPU0_SB_DQ<0>")
	)
	(segment
		(start 312.23458 -276.437852)
		(end 312.56605 -276.437852)
		(width 0.14478)
		(layer "In4.Cu")
		(net "M_D_CPU0_SB_DQ<0>")
	)
	(segment
		(start 304.482246 -281.402536)
		(end 304.482246 -281.748484)
		(width 0.14478)
		(layer "In4.Cu")
		(net "M_D_CPU0_SB_DQ<0>")
	)
	(segment
		(start 285.914338 -282.107132)
		(end 285.914338 -281.779218)
		(width 0.14478)
		(layer "In4.Cu")
		(net "M_D_CPU0_SB_DQ<0>")
	)
	(segment
		(start 294.916098 -282.216352)
		(end 295.222422 -281.910028)
		(width 0.14478)
		(layer "In4.Cu")
		(net "M_D_CPU0_SB_DQ<0>")
	)
	(segment
		(start 300.80458 -281.05989)
		(end 301.654718 -281.910028)
		(width 0.14478)
		(layer "In4.Cu")
		(net "M_D_CPU0_SB_DQ<0>")
	)
	(segment
		(start 304.320702 -281.240992)
		(end 304.482246 -281.402536)
		(width 0.14478)
		(layer "In4.Cu")
		(net "M_D_CPU0_SB_DQ<0>")
	)
	(segment
		(start 326.837802 -274.408392)
		(end 326.84339 -274.40509)
		(width 0.0889)
		(layer "In4.Cu")
		(net "M_D_CPU0_SB_DQ<0>")
	)
	(segment
		(start 302.807116 -281.910028)
		(end 303.769268 -281.910028)
		(width 0.14478)
		(layer "In4.Cu")
		(net "M_D_CPU0_SB_DQ<0>")
	)
	(segment
		(start 302.645572 -281.748484)
		(end 302.807116 -281.910028)
		(width 0.14478)
		(layer "In4.Cu")
		(net "M_D_CPU0_SB_DQ<0>")
	)
	(segment
		(start 308.888892 -280.011632)
		(end 308.888892 -279.78354)
		(width 0.14478)
		(layer "In4.Cu")
		(net "M_D_CPU0_SB_DQ<0>")
	)
	(segment
		(start 328.333608 -274.40255)
		(end 328.344022 -274.408646)
		(width 0.0889)
		(layer "In4.Cu")
		(net "M_D_CPU0_SB_DQ<0>")
	)
	(segment
		(start 309.669434 -279.334468)
		(end 309.66918 -279.231344)
		(width 0.14478)
		(layer "In4.Cu")
		(net "M_D_CPU0_SB_DQ<0>")
	)
	(segment
		(start 310.449468 -278.451056)
		(end 310.449468 -278.222964)
		(width 0.14478)
		(layer "In4.Cu")
		(net "M_D_CPU0_SB_DQ<0>")
	)
	(segment
		(start 306.522628 -281.280108)
		(end 306.684172 -281.441652)
		(width 0.14478)
		(layer "In4.Cu")
		(net "M_D_CPU0_SB_DQ<0>")
	)
	(segment
		(start 286.307784 -281.616404)
		(end 286.470598 -281.779218)
		(width 0.14478)
		(layer "In4.Cu")
		(net "M_D_CPU0_SB_DQ<0>")
	)
	(segment
		(start 304.64379 -281.910028)
		(end 304.80381 -281.910028)
		(width 0.14478)
		(layer "In4.Cu")
		(net "M_D_CPU0_SB_DQ<0>")
	)
	(segment
		(start 337.16976 -274.413472)
		(end 337.178142 -274.408646)
		(width 0.0889)
		(layer "In4.Cu")
		(net "M_D_CPU0_SB_DQ<0>")
	)
	(segment
		(start 312.790332 -276.110192)
		(end 312.790332 -275.8821)
		(width 0.14478)
		(layer "In4.Cu")
		(net "M_D_CPU0_SB_DQ<0>")
	)
	(segment
		(start 310.225186 -278.778716)
		(end 310.449722 -278.55418)
		(width 0.14478)
		(layer "In4.Cu")
		(net "M_D_CPU0_SB_DQ<0>")
	)
	(segment
		(start 331.52969 -274.413472)
		(end 331.538072 -274.408646)
		(width 0.0889)
		(layer "In4.Cu")
		(net "M_D_CPU0_SB_DQ<0>")
	)
	(arc
		(start 334.358234 -274.408646)
		(mid 334.64119 -274.332469)
		(end 334.924146 -274.408646)
		(width 0.0889)
		(layer "In4.Cu")
		(net "M_D_CPU0_SB_DQ<0>")
	)
	(arc
		(start 331.16393 -274.408646)
		(mid 331.346181 -274.458996)
		(end 331.52969 -274.413472)
		(width 0.0889)
		(layer "In4.Cu")
		(net "M_D_CPU0_SB_DQ<0>")
	)
	(arc
		(start 333.41818 -274.408646)
		(mid 333.701136 -274.332469)
		(end 333.984092 -274.408646)
		(width 0.0889)
		(layer "In4.Cu")
		(net "M_D_CPU0_SB_DQ<0>")
	)
	(arc
		(start 338.118196 -274.408646)
		(mid 338.401152 -274.332469)
		(end 338.684108 -274.408646)
		(width 0.0889)
		(layer "In4.Cu")
		(net "M_D_CPU0_SB_DQ<0>")
	)
	(arc
		(start 327.777856 -274.408646)
		(mid 328.054923 -274.332375)
		(end 328.333608 -274.40255)
		(width 0.0889)
		(layer "In4.Cu")
		(net "M_D_CPU0_SB_DQ<0>")
	)
	(arc
		(start 328.718164 -274.408646)
		(mid 329.00112 -274.332469)
		(end 329.284076 -274.408646)
		(width 0.0889)
		(layer "In4.Cu")
		(net "M_D_CPU0_SB_DQ<0>")
	)
	(arc
		(start 326.386952 -274.349972)
		(mid 326.423279 -274.381785)
		(end 326.463406 -274.408646)
		(width 0.0889)
		(layer "In4.Cu")
		(net "M_D_CPU0_SB_DQ<0>")
	)
	(arc
		(start 326.84339 -274.40509)
		(mid 327.123779 -274.332421)
		(end 327.403206 -274.408646)
		(width 0.0889)
		(layer "In4.Cu")
		(net "M_D_CPU0_SB_DQ<0>")
	)
	(arc
		(start 330.22413 -274.408646)
		(mid 330.411074 -274.458901)
		(end 330.598018 -274.408646)
		(width 0.0889)
		(layer "In4.Cu")
		(net "M_D_CPU0_SB_DQ<0>")
	)
	(arc
		(start 334.924146 -274.408646)
		(mid 335.11109 -274.458901)
		(end 335.298034 -274.408646)
		(width 0.0889)
		(layer "In4.Cu")
		(net "M_D_CPU0_SB_DQ<0>")
	)
	(arc
		(start 336.238088 -274.408646)
		(mid 336.521044 -274.332469)
		(end 336.804 -274.408646)
		(width 0.0889)
		(layer "In4.Cu")
		(net "M_D_CPU0_SB_DQ<0>")
	)
	(arc
		(start 330.598018 -274.408646)
		(mid 330.880974 -274.332469)
		(end 331.16393 -274.408646)
		(width 0.0889)
		(layer "In4.Cu")
		(net "M_D_CPU0_SB_DQ<0>")
	)
	(arc
		(start 331.538072 -274.408646)
		(mid 331.821028 -274.332469)
		(end 332.103984 -274.408646)
		(width 0.0889)
		(layer "In4.Cu")
		(net "M_D_CPU0_SB_DQ<0>")
	)
	(arc
		(start 328.344022 -274.408646)
		(mid 328.526273 -274.458996)
		(end 328.709782 -274.413472)
		(width 0.0889)
		(layer "In4.Cu")
		(net "M_D_CPU0_SB_DQ<0>")
	)
	(arc
		(start 337.752436 -274.413472)
		(mid 337.935944 -274.458966)
		(end 338.118196 -274.408646)
		(width 0.0889)
		(layer "In4.Cu")
		(net "M_D_CPU0_SB_DQ<0>")
	)
	(arc
		(start 336.804 -274.408646)
		(mid 336.986251 -274.458996)
		(end 337.16976 -274.413472)
		(width 0.0889)
		(layer "In4.Cu")
		(net "M_D_CPU0_SB_DQ<0>")
	)
	(arc
		(start 335.863946 -274.408646)
		(mid 336.046197 -274.458996)
		(end 336.229706 -274.413472)
		(width 0.0889)
		(layer "In4.Cu")
		(net "M_D_CPU0_SB_DQ<0>")
	)
	(arc
		(start 329.658218 -274.408646)
		(mid 329.941174 -274.332469)
		(end 330.22413 -274.408646)
		(width 0.0889)
		(layer "In4.Cu")
		(net "M_D_CPU0_SB_DQ<0>")
	)
	(arc
		(start 338.69249 -274.413472)
		(mid 338.84536 -274.458113)
		(end 339.002878 -274.434808)
		(width 0.0889)
		(layer "In4.Cu")
		(net "M_D_CPU0_SB_DQ<0>")
	)
	(arc
		(start 327.411588 -274.413472)
		(mid 327.59535 -274.459088)
		(end 327.777856 -274.408646)
		(width 0.0889)
		(layer "In4.Cu")
		(net "M_D_CPU0_SB_DQ<0>")
	)
	(arc
		(start 332.103984 -274.408646)
		(mid 332.286235 -274.458996)
		(end 332.469744 -274.413472)
		(width 0.0889)
		(layer "In4.Cu")
		(net "M_D_CPU0_SB_DQ<0>")
	)
	(arc
		(start 337.178142 -274.408646)
		(mid 337.461098 -274.332469)
		(end 337.744054 -274.408646)
		(width 0.0889)
		(layer "In4.Cu")
		(net "M_D_CPU0_SB_DQ<0>")
	)
	(arc
		(start 326.46366 -274.408646)
		(mid 326.640288 -274.458879)
		(end 326.819514 -274.418806)
		(width 0.0889)
		(layer "In4.Cu")
		(net "M_D_CPU0_SB_DQ<0>")
	)
	(arc
		(start 333.992474 -274.413472)
		(mid 334.175982 -274.458966)
		(end 334.358234 -274.408646)
		(width 0.0889)
		(layer "In4.Cu")
		(net "M_D_CPU0_SB_DQ<0>")
	)
	(arc
		(start 333.05242 -274.413472)
		(mid 333.235928 -274.458966)
		(end 333.41818 -274.408646)
		(width 0.0889)
		(layer "In4.Cu")
		(net "M_D_CPU0_SB_DQ<0>")
	)
	(arc
		(start 332.478126 -274.408646)
		(mid 332.761082 -274.332469)
		(end 333.044038 -274.408646)
		(width 0.0889)
		(layer "In4.Cu")
		(net "M_D_CPU0_SB_DQ<0>")
	)
	(arc
		(start 335.298034 -274.408646)
		(mid 335.58099 -274.332469)
		(end 335.863946 -274.408646)
		(width 0.0889)
		(layer "In4.Cu")
		(net "M_D_CPU0_SB_DQ<0>")
	)
	(arc
		(start 329.292458 -274.413472)
		(mid 329.475966 -274.458966)
		(end 329.658218 -274.408646)
		(width 0.0889)
		(layer "In4.Cu")
		(net "M_D_CPU0_SB_DQ<0>")
	)
	(segment
		(start 339.808058 -266.530074)
		(end 339.341206 -266.796012)
		(width 0.10668)
		(layer "F.Cu")
		(net "M_D_CPU0_SB_CS_N<1>")
	)
	(segment
		(start 333.879698 -266.468606)
		(end 333.88808 -266.473432)
		(width 0.0889)
		(layer "In4.Cu")
		(net "M_D_CPU0_SB_CS_N<1>")
	)
	(segment
		(start 330.119736 -266.468606)
		(end 330.128118 -266.473432)
		(width 0.0889)
		(layer "In4.Cu")
		(net "M_D_CPU0_SB_CS_N<1>")
	)
	(segment
		(start 308.185058 -268.310106)
		(end 310.511444 -265.98372)
		(width 0.14478)
		(layer "In4.Cu")
		(net "M_D_CPU0_SB_CS_N<1>")
	)
	(segment
		(start 323.897244 -265.98372)
		(end 325.823326 -265.98372)
		(width 0.0889)
		(layer "In4.Cu")
		(net "M_D_CPU0_SB_CS_N<1>")
	)
	(segment
		(start 331.634084 -266.473432)
		(end 331.642466 -266.468606)
		(width 0.0889)
		(layer "In4.Cu")
		(net "M_D_CPU0_SB_CS_N<1>")
	)
	(segment
		(start 334.819752 -266.468606)
		(end 334.828134 -266.473432)
		(width 0.0889)
		(layer "In4.Cu")
		(net "M_D_CPU0_SB_CS_N<1>")
	)
	(segment
		(start 339.187028 -266.530582)
		(end 339.341206 -266.796012)
		(width 0.0889)
		(layer "In4.Cu")
		(net "M_D_CPU0_SB_CS_N<1>")
	)
	(segment
		(start 326.262492 -266.422886)
		(end 328.061066 -266.422886)
		(width 0.0889)
		(layer "In4.Cu")
		(net "M_D_CPU0_SB_CS_N<1>")
	)
	(segment
		(start 325.823326 -265.98372)
		(end 326.262492 -266.422886)
		(width 0.0889)
		(layer "In4.Cu")
		(net "M_D_CPU0_SB_CS_N<1>")
	)
	(segment
		(start 336.3341 -266.473432)
		(end 336.342482 -266.468606)
		(width 0.0889)
		(layer "In4.Cu")
		(net "M_D_CPU0_SB_CS_N<1>")
	)
	(segment
		(start 339.090762 -266.505182)
		(end 339.187028 -266.530582)
		(width 0.0889)
		(layer "In4.Cu")
		(net "M_D_CPU0_SB_CS_N<1>")
	)
	(segment
		(start 310.511444 -265.98372)
		(end 323.897244 -265.98372)
		(width 0.14478)
		(layer "In4.Cu")
		(net "M_D_CPU0_SB_CS_N<1>")
	)
	(segment
		(start 280.635964 -268.735048)
		(end 281.060906 -268.310106)
		(width 0.14478)
		(layer "In4.Cu")
		(net "M_D_CPU0_SB_CS_N<1>")
	)
	(segment
		(start 330.69403 -266.473432)
		(end 330.702412 -266.468606)
		(width 0.0889)
		(layer "In4.Cu")
		(net "M_D_CPU0_SB_CS_N<1>")
	)
	(segment
		(start 335.394046 -266.473432)
		(end 335.402428 -266.468606)
		(width 0.0889)
		(layer "In4.Cu")
		(net "M_D_CPU0_SB_CS_N<1>")
	)
	(segment
		(start 281.060906 -268.310106)
		(end 308.185058 -268.310106)
		(width 0.14478)
		(layer "In4.Cu")
		(net "M_D_CPU0_SB_CS_N<1>")
	)
	(segment
		(start 338.579714 -266.468606)
		(end 338.588096 -266.473432)
		(width 0.0889)
		(layer "In4.Cu")
		(net "M_D_CPU0_SB_CS_N<1>")
	)
	(arc
		(start 334.453992 -266.473432)
		(mid 334.636243 -266.423082)
		(end 334.819752 -266.468606)
		(width 0.0889)
		(layer "In4.Cu")
		(net "M_D_CPU0_SB_CS_N<1>")
	)
	(arc
		(start 328.814176 -266.473432)
		(mid 329.00112 -266.423177)
		(end 329.188064 -266.473432)
		(width 0.0889)
		(layer "In4.Cu")
		(net "M_D_CPU0_SB_CS_N<1>")
	)
	(arc
		(start 333.513938 -266.473432)
		(mid 333.696189 -266.423082)
		(end 333.879698 -266.468606)
		(width 0.0889)
		(layer "In4.Cu")
		(net "M_D_CPU0_SB_CS_N<1>")
	)
	(arc
		(start 337.274154 -266.473432)
		(mid 337.461098 -266.423177)
		(end 337.648042 -266.473432)
		(width 0.0889)
		(layer "In4.Cu")
		(net "M_D_CPU0_SB_CS_N<1>")
	)
	(arc
		(start 332.008226 -266.473432)
		(mid 332.291182 -266.549609)
		(end 332.574138 -266.473432)
		(width 0.0889)
		(layer "In4.Cu")
		(net "M_D_CPU0_SB_CS_N<1>")
	)
	(arc
		(start 333.88808 -266.473432)
		(mid 334.171036 -266.549609)
		(end 334.453992 -266.473432)
		(width 0.0889)
		(layer "In4.Cu")
		(net "M_D_CPU0_SB_CS_N<1>")
	)
	(arc
		(start 328.061066 -266.422886)
		(mid 328.158013 -266.435769)
		(end 328.248264 -266.473432)
		(width 0.0889)
		(layer "In4.Cu")
		(net "M_D_CPU0_SB_CS_N<1>")
	)
	(arc
		(start 332.574138 -266.473432)
		(mid 332.761082 -266.423177)
		(end 332.948026 -266.473432)
		(width 0.0889)
		(layer "In4.Cu")
		(net "M_D_CPU0_SB_CS_N<1>")
	)
	(arc
		(start 338.213954 -266.473432)
		(mid 338.396205 -266.423082)
		(end 338.579714 -266.468606)
		(width 0.0889)
		(layer "In4.Cu")
		(net "M_D_CPU0_SB_CS_N<1>")
	)
	(arc
		(start 332.948026 -266.473432)
		(mid 333.230982 -266.549609)
		(end 333.513938 -266.473432)
		(width 0.0889)
		(layer "In4.Cu")
		(net "M_D_CPU0_SB_CS_N<1>")
	)
	(arc
		(start 335.768188 -266.473432)
		(mid 336.051144 -266.549609)
		(end 336.3341 -266.473432)
		(width 0.0889)
		(layer "In4.Cu")
		(net "M_D_CPU0_SB_CS_N<1>")
	)
	(arc
		(start 328.248264 -266.473432)
		(mid 328.53122 -266.549609)
		(end 328.814176 -266.473432)
		(width 0.0889)
		(layer "In4.Cu")
		(net "M_D_CPU0_SB_CS_N<1>")
	)
	(arc
		(start 337.648042 -266.473432)
		(mid 337.930998 -266.549609)
		(end 338.213954 -266.473432)
		(width 0.0889)
		(layer "In4.Cu")
		(net "M_D_CPU0_SB_CS_N<1>")
	)
	(arc
		(start 329.188064 -266.473432)
		(mid 329.47102 -266.549609)
		(end 329.753976 -266.473432)
		(width 0.0889)
		(layer "In4.Cu")
		(net "M_D_CPU0_SB_CS_N<1>")
	)
	(arc
		(start 335.402428 -266.468606)
		(mid 335.585936 -266.423112)
		(end 335.768188 -266.473432)
		(width 0.0889)
		(layer "In4.Cu")
		(net "M_D_CPU0_SB_CS_N<1>")
	)
	(arc
		(start 331.642466 -266.468606)
		(mid 331.825974 -266.423112)
		(end 332.008226 -266.473432)
		(width 0.0889)
		(layer "In4.Cu")
		(net "M_D_CPU0_SB_CS_N<1>")
	)
	(arc
		(start 329.753976 -266.473432)
		(mid 329.936227 -266.423082)
		(end 330.119736 -266.468606)
		(width 0.0889)
		(layer "In4.Cu")
		(net "M_D_CPU0_SB_CS_N<1>")
	)
	(arc
		(start 336.708242 -266.473432)
		(mid 336.991198 -266.549609)
		(end 337.274154 -266.473432)
		(width 0.0889)
		(layer "In4.Cu")
		(net "M_D_CPU0_SB_CS_N<1>")
	)
	(arc
		(start 330.128118 -266.473432)
		(mid 330.411074 -266.549609)
		(end 330.69403 -266.473432)
		(width 0.0889)
		(layer "In4.Cu")
		(net "M_D_CPU0_SB_CS_N<1>")
	)
	(arc
		(start 330.702412 -266.468606)
		(mid 330.88592 -266.423112)
		(end 331.068172 -266.473432)
		(width 0.0889)
		(layer "In4.Cu")
		(net "M_D_CPU0_SB_CS_N<1>")
	)
	(arc
		(start 334.828134 -266.473432)
		(mid 335.11109 -266.549609)
		(end 335.394046 -266.473432)
		(width 0.0889)
		(layer "In4.Cu")
		(net "M_D_CPU0_SB_CS_N<1>")
	)
	(arc
		(start 336.342482 -266.468606)
		(mid 336.52599 -266.423112)
		(end 336.708242 -266.473432)
		(width 0.0889)
		(layer "In4.Cu")
		(net "M_D_CPU0_SB_CS_N<1>")
	)
	(arc
		(start 331.068172 -266.473432)
		(mid 331.351128 -266.549609)
		(end 331.634084 -266.473432)
		(width 0.0889)
		(layer "In4.Cu")
		(net "M_D_CPU0_SB_CS_N<1>")
	)
	(arc
		(start 338.588096 -266.473432)
		(mid 338.835692 -266.54861)
		(end 339.090762 -266.505182)
		(width 0.0889)
		(layer "In4.Cu")
		(net "M_D_CPU0_SB_CS_N<1>")
	)
	(segment
		(start 341.218012 -265.720068)
		(end 340.75116 -265.986006)
		(width 0.10668)
		(layer "F.Cu")
		(net "M_D_CPU0_SB_CS_N<0>")
	)
	(segment
		(start 308.432454 -267.17371)
		(end 310.077104 -265.52906)
		(width 0.14478)
		(layer "In4.Cu")
		(net "M_D_CPU0_SB_CS_N<0>")
	)
	(segment
		(start 298.431966 -267.460222)
		(end 298.743878 -267.14831)
		(width 0.14478)
		(layer "In4.Cu")
		(net "M_D_CPU0_SB_CS_N<0>")
	)
	(segment
		(start 333.044038 -265.663426)
		(end 333.05242 -265.6586)
		(width 0.0889)
		(layer "In4.Cu")
		(net "M_D_CPU0_SB_CS_N<0>")
	)
	(segment
		(start 304.156618 -267.14831)
		(end 304.46853 -267.460222)
		(width 0.14478)
		(layer "In4.Cu")
		(net "M_D_CPU0_SB_CS_N<0>")
	)
	(segment
		(start 294.739568 -267.460222)
		(end 296.206926 -267.460222)
		(width 0.14478)
		(layer "In4.Cu")
		(net "M_D_CPU0_SB_CS_N<0>")
	)
	(segment
		(start 300.262798 -267.460222)
		(end 300.57471 -267.14831)
		(width 0.14478)
		(layer "In4.Cu")
		(net "M_D_CPU0_SB_CS_N<0>")
	)
	(segment
		(start 294.183308 -267.14831)
		(end 294.427656 -267.14831)
		(width 0.14478)
		(layer "In4.Cu")
		(net "M_D_CPU0_SB_CS_N<0>")
	)
	(segment
		(start 293.315136 -267.14831)
		(end 293.627048 -267.460222)
		(width 0.14478)
		(layer "In4.Cu")
		(net "M_D_CPU0_SB_CS_N<0>")
	)
	(segment
		(start 328.709782 -265.6586)
		(end 328.718164 -265.663426)
		(width 0.0889)
		(layer "In4.Cu")
		(net "M_D_CPU0_SB_CS_N<0>")
	)
	(segment
		(start 290.12769 -267.14831)
		(end 290.372038 -267.14831)
		(width 0.14478)
		(layer "In4.Cu")
		(net "M_D_CPU0_SB_CS_N<0>")
	)
	(segment
		(start 296.763186 -267.14831)
		(end 297.075098 -267.460222)
		(width 0.14478)
		(layer "In4.Cu")
		(net "M_D_CPU0_SB_CS_N<0>")
	)
	(segment
		(start 302.24349 -267.460222)
		(end 302.487838 -267.460222)
		(width 0.14478)
		(layer "In4.Cu")
		(net "M_D_CPU0_SB_CS_N<0>")
	)
	(segment
		(start 306.13731 -267.14831)
		(end 306.381658 -267.14831)
		(width 0.14478)
		(layer "In4.Cu")
		(net "M_D_CPU0_SB_CS_N<0>")
	)
	(segment
		(start 297.875706 -267.14831)
		(end 298.187618 -267.460222)
		(width 0.14478)
		(layer "In4.Cu")
		(net "M_D_CPU0_SB_CS_N<0>")
	)
	(segment
		(start 298.988226 -267.14831)
		(end 299.300138 -267.460222)
		(width 0.14478)
		(layer "In4.Cu")
		(net "M_D_CPU0_SB_CS_N<0>")
	)
	(segment
		(start 287.116774 -267.17371)
		(end 287.386522 -267.17371)
		(width 0.14478)
		(layer "In4.Cu")
		(net "M_D_CPU0_SB_CS_N<0>")
	)
	(segment
		(start 303.044098 -267.14831)
		(end 303.35601 -267.460222)
		(width 0.14478)
		(layer "In4.Cu")
		(net "M_D_CPU0_SB_CS_N<0>")
	)
	(segment
		(start 287.673034 -267.460222)
		(end 288.703258 -267.460222)
		(width 0.14478)
		(layer "In4.Cu")
		(net "M_D_CPU0_SB_CS_N<0>")
	)
	(segment
		(start 305.58105 -267.460222)
		(end 305.825398 -267.460222)
		(width 0.14478)
		(layer "In4.Cu")
		(net "M_D_CPU0_SB_CS_N<0>")
	)
	(segment
		(start 304.46853 -267.460222)
		(end 304.712878 -267.460222)
		(width 0.14478)
		(layer "In4.Cu")
		(net "M_D_CPU0_SB_CS_N<0>")
	)
	(segment
		(start 303.600358 -267.460222)
		(end 303.91227 -267.14831)
		(width 0.14478)
		(layer "In4.Cu")
		(net "M_D_CPU0_SB_CS_N<0>")
	)
	(segment
		(start 301.375318 -267.460222)
		(end 301.68723 -267.14831)
		(width 0.14478)
		(layer "In4.Cu")
		(net "M_D_CPU0_SB_CS_N<0>")
	)
	(segment
		(start 292.758876 -267.460222)
		(end 293.070788 -267.14831)
		(width 0.14478)
		(layer "In4.Cu")
		(net "M_D_CPU0_SB_CS_N<0>")
	)
	(segment
		(start 289.815778 -267.460222)
		(end 290.12769 -267.14831)
		(width 0.14478)
		(layer "In4.Cu")
		(net "M_D_CPU0_SB_CS_N<0>")
	)
	(segment
		(start 297.319446 -267.460222)
		(end 297.631358 -267.14831)
		(width 0.14478)
		(layer "In4.Cu")
		(net "M_D_CPU0_SB_CS_N<0>")
	)
	(segment
		(start 329.284076 -265.663426)
		(end 329.292458 -265.6586)
		(width 0.0889)
		(layer "In4.Cu")
		(net "M_D_CPU0_SB_CS_N<0>")
	)
	(segment
		(start 299.300138 -267.460222)
		(end 300.262798 -267.460222)
		(width 0.14478)
		(layer "In4.Cu")
		(net "M_D_CPU0_SB_CS_N<0>")
	)
	(segment
		(start 290.928298 -267.460222)
		(end 291.24021 -267.14831)
		(width 0.14478)
		(layer "In4.Cu")
		(net "M_D_CPU0_SB_CS_N<0>")
	)
	(segment
		(start 290.68395 -267.460222)
		(end 290.928298 -267.460222)
		(width 0.14478)
		(layer "In4.Cu")
		(net "M_D_CPU0_SB_CS_N<0>")
	)
	(segment
		(start 304.712878 -267.460222)
		(end 305.02479 -267.14831)
		(width 0.14478)
		(layer "In4.Cu")
		(net "M_D_CPU0_SB_CS_N<0>")
	)
	(segment
		(start 291.484558 -267.14831)
		(end 291.79647 -267.460222)
		(width 0.14478)
		(layer "In4.Cu")
		(net "M_D_CPU0_SB_CS_N<0>")
	)
	(segment
		(start 286.274002 -267.17371)
		(end 286.560514 -267.460222)
		(width 0.14478)
		(layer "In4.Cu")
		(net "M_D_CPU0_SB_CS_N<0>")
	)
	(segment
		(start 333.984092 -265.663426)
		(end 333.992474 -265.6586)
		(width 0.0889)
		(layer "In4.Cu")
		(net "M_D_CPU0_SB_CS_N<0>")
	)
	(segment
		(start 337.744054 -265.663426)
		(end 337.752436 -265.6586)
		(width 0.0889)
		(layer "In4.Cu")
		(net "M_D_CPU0_SB_CS_N<0>")
	)
	(segment
		(start 296.206926 -267.460222)
		(end 296.518838 -267.14831)
		(width 0.14478)
		(layer "In4.Cu")
		(net "M_D_CPU0_SB_CS_N<0>")
	)
	(segment
		(start 330.22413 -265.663426)
		(end 330.232512 -265.6586)
		(width 0.0889)
		(layer "In4.Cu")
		(net "M_D_CPU0_SB_CS_N<0>")
	)
	(segment
		(start 296.518838 -267.14831)
		(end 296.763186 -267.14831)
		(width 0.14478)
		(layer "In4.Cu")
		(net "M_D_CPU0_SB_CS_N<0>")
	)
	(segment
		(start 291.24021 -267.14831)
		(end 291.484558 -267.14831)
		(width 0.14478)
		(layer "In4.Cu")
		(net "M_D_CPU0_SB_CS_N<0>")
	)
	(segment
		(start 306.69357 -267.460222)
		(end 307.937662 -267.460222)
		(width 0.14478)
		(layer "In4.Cu")
		(net "M_D_CPU0_SB_CS_N<0>")
	)
	(segment
		(start 337.16976 -265.6586)
		(end 337.178142 -265.663426)
		(width 0.0889)
		(layer "In4.Cu")
		(net "M_D_CPU0_SB_CS_N<0>")
	)
	(segment
		(start 302.487838 -267.460222)
		(end 302.79975 -267.14831)
		(width 0.14478)
		(layer "In4.Cu")
		(net "M_D_CPU0_SB_CS_N<0>")
	)
	(segment
		(start 307.937662 -267.460222)
		(end 308.224174 -267.17371)
		(width 0.14478)
		(layer "In4.Cu")
		(net "M_D_CPU0_SB_CS_N<0>")
	)
	(segment
		(start 298.187618 -267.460222)
		(end 298.431966 -267.460222)
		(width 0.14478)
		(layer "In4.Cu")
		(net "M_D_CPU0_SB_CS_N<0>")
	)
	(segment
		(start 285.160974 -267.460222)
		(end 285.717742 -267.460222)
		(width 0.14478)
		(layer "In4.Cu")
		(net "M_D_CPU0_SB_CS_N<0>")
	)
	(segment
		(start 286.830262 -267.460222)
		(end 287.116774 -267.17371)
		(width 0.14478)
		(layer "In4.Cu")
		(net "M_D_CPU0_SB_CS_N<0>")
	)
	(segment
		(start 286.004254 -267.17371)
		(end 286.274002 -267.17371)
		(width 0.14478)
		(layer "In4.Cu")
		(net "M_D_CPU0_SB_CS_N<0>")
	)
	(segment
		(start 306.381658 -267.14831)
		(end 306.69357 -267.460222)
		(width 0.14478)
		(layer "In4.Cu")
		(net "M_D_CPU0_SB_CS_N<0>")
	)
	(segment
		(start 293.627048 -267.460222)
		(end 293.871396 -267.460222)
		(width 0.14478)
		(layer "In4.Cu")
		(net "M_D_CPU0_SB_CS_N<0>")
	)
	(segment
		(start 332.469744 -265.6586)
		(end 332.478126 -265.663426)
		(width 0.0889)
		(layer "In4.Cu")
		(net "M_D_CPU0_SB_CS_N<0>")
	)
	(segment
		(start 300.819058 -267.14831)
		(end 301.13097 -267.460222)
		(width 0.14478)
		(layer "In4.Cu")
		(net "M_D_CPU0_SB_CS_N<0>")
	)
	(segment
		(start 340.596982 -265.720576)
		(end 340.75116 -265.986006)
		(width 0.0889)
		(layer "In4.Cu")
		(net "M_D_CPU0_SB_CS_N<0>")
	)
	(segment
		(start 297.075098 -267.460222)
		(end 297.319446 -267.460222)
		(width 0.14478)
		(layer "In4.Cu")
		(net "M_D_CPU0_SB_CS_N<0>")
	)
	(segment
		(start 310.077104 -265.52906)
		(end 324.059804 -265.52906)
		(width 0.14478)
		(layer "In4.Cu")
		(net "M_D_CPU0_SB_CS_N<0>")
	)
	(segment
		(start 298.743878 -267.14831)
		(end 298.988226 -267.14831)
		(width 0.14478)
		(layer "In4.Cu")
		(net "M_D_CPU0_SB_CS_N<0>")
	)
	(segment
		(start 336.229706 -265.6586)
		(end 336.238088 -265.663426)
		(width 0.0889)
		(layer "In4.Cu")
		(net "M_D_CPU0_SB_CS_N<0>")
	)
	(segment
		(start 287.386522 -267.17371)
		(end 287.673034 -267.460222)
		(width 0.14478)
		(layer "In4.Cu")
		(net "M_D_CPU0_SB_CS_N<0>")
	)
	(segment
		(start 303.35601 -267.460222)
		(end 303.600358 -267.460222)
		(width 0.14478)
		(layer "In4.Cu")
		(net "M_D_CPU0_SB_CS_N<0>")
	)
	(segment
		(start 301.68723 -267.14831)
		(end 301.931578 -267.14831)
		(width 0.14478)
		(layer "In4.Cu")
		(net "M_D_CPU0_SB_CS_N<0>")
	)
	(segment
		(start 324.059804 -265.52906)
		(end 327.28027 -265.52906)
		(width 0.0889)
		(layer "In4.Cu")
		(net "M_D_CPU0_SB_CS_N<0>")
	)
	(segment
		(start 303.91227 -267.14831)
		(end 304.156618 -267.14831)
		(width 0.14478)
		(layer "In4.Cu")
		(net "M_D_CPU0_SB_CS_N<0>")
	)
	(segment
		(start 294.427656 -267.14831)
		(end 294.739568 -267.460222)
		(width 0.14478)
		(layer "In4.Cu")
		(net "M_D_CPU0_SB_CS_N<0>")
	)
	(segment
		(start 285.717742 -267.460222)
		(end 286.004254 -267.17371)
		(width 0.14478)
		(layer "In4.Cu")
		(net "M_D_CPU0_SB_CS_N<0>")
	)
	(segment
		(start 286.560514 -267.460222)
		(end 286.830262 -267.460222)
		(width 0.14478)
		(layer "In4.Cu")
		(net "M_D_CPU0_SB_CS_N<0>")
	)
	(segment
		(start 297.631358 -267.14831)
		(end 297.875706 -267.14831)
		(width 0.14478)
		(layer "In4.Cu")
		(net "M_D_CPU0_SB_CS_N<0>")
	)
	(segment
		(start 289.57143 -267.460222)
		(end 289.815778 -267.460222)
		(width 0.14478)
		(layer "In4.Cu")
		(net "M_D_CPU0_SB_CS_N<0>")
	)
	(segment
		(start 288.703258 -267.460222)
		(end 289.01517 -267.14831)
		(width 0.14478)
		(layer "In4.Cu")
		(net "M_D_CPU0_SB_CS_N<0>")
	)
	(segment
		(start 300.57471 -267.14831)
		(end 300.819058 -267.14831)
		(width 0.14478)
		(layer "In4.Cu")
		(net "M_D_CPU0_SB_CS_N<0>")
	)
	(segment
		(start 308.224174 -267.17371)
		(end 308.432454 -267.17371)
		(width 0.14478)
		(layer "In4.Cu")
		(net "M_D_CPU0_SB_CS_N<0>")
	)
	(segment
		(start 305.02479 -267.14831)
		(end 305.269138 -267.14831)
		(width 0.14478)
		(layer "In4.Cu")
		(net "M_D_CPU0_SB_CS_N<0>")
	)
	(segment
		(start 291.79647 -267.460222)
		(end 292.758876 -267.460222)
		(width 0.14478)
		(layer "In4.Cu")
		(net "M_D_CPU0_SB_CS_N<0>")
	)
	(segment
		(start 301.931578 -267.14831)
		(end 302.24349 -267.460222)
		(width 0.14478)
		(layer "In4.Cu")
		(net "M_D_CPU0_SB_CS_N<0>")
	)
	(segment
		(start 289.01517 -267.14831)
		(end 289.259518 -267.14831)
		(width 0.14478)
		(layer "In4.Cu")
		(net "M_D_CPU0_SB_CS_N<0>")
	)
	(segment
		(start 305.825398 -267.460222)
		(end 306.13731 -267.14831)
		(width 0.14478)
		(layer "In4.Cu")
		(net "M_D_CPU0_SB_CS_N<0>")
	)
	(segment
		(start 340.500716 -265.695176)
		(end 340.596982 -265.720576)
		(width 0.0889)
		(layer "In4.Cu")
		(net "M_D_CPU0_SB_CS_N<0>")
	)
	(segment
		(start 305.269138 -267.14831)
		(end 305.58105 -267.460222)
		(width 0.14478)
		(layer "In4.Cu")
		(net "M_D_CPU0_SB_CS_N<0>")
	)
	(segment
		(start 293.070788 -267.14831)
		(end 293.315136 -267.14831)
		(width 0.14478)
		(layer "In4.Cu")
		(net "M_D_CPU0_SB_CS_N<0>")
	)
	(segment
		(start 290.372038 -267.14831)
		(end 290.68395 -267.460222)
		(width 0.14478)
		(layer "In4.Cu")
		(net "M_D_CPU0_SB_CS_N<0>")
	)
	(segment
		(start 284.736032 -267.885164)
		(end 285.160974 -267.460222)
		(width 0.14478)
		(layer "In4.Cu")
		(net "M_D_CPU0_SB_CS_N<0>")
	)
	(segment
		(start 328.32929 -265.672062)
		(end 328.344022 -265.663426)
		(width 0.0889)
		(layer "In4.Cu")
		(net "M_D_CPU0_SB_CS_N<0>")
	)
	(segment
		(start 293.871396 -267.460222)
		(end 294.183308 -267.14831)
		(width 0.14478)
		(layer "In4.Cu")
		(net "M_D_CPU0_SB_CS_N<0>")
	)
	(segment
		(start 302.79975 -267.14831)
		(end 303.044098 -267.14831)
		(width 0.14478)
		(layer "In4.Cu")
		(net "M_D_CPU0_SB_CS_N<0>")
	)
	(segment
		(start 289.259518 -267.14831)
		(end 289.57143 -267.460222)
		(width 0.14478)
		(layer "In4.Cu")
		(net "M_D_CPU0_SB_CS_N<0>")
	)
	(segment
		(start 338.684108 -265.663426)
		(end 338.69249 -265.6586)
		(width 0.0889)
		(layer "In4.Cu")
		(net "M_D_CPU0_SB_CS_N<0>")
	)
	(segment
		(start 301.13097 -267.460222)
		(end 301.375318 -267.460222)
		(width 0.14478)
		(layer "In4.Cu")
		(net "M_D_CPU0_SB_CS_N<0>")
	)
	(arc
		(start 329.658218 -265.663426)
		(mid 329.941174 -265.739603)
		(end 330.22413 -265.663426)
		(width 0.0889)
		(layer "In4.Cu")
		(net "M_D_CPU0_SB_CS_N<0>")
	)
	(arc
		(start 335.298034 -265.663426)
		(mid 335.58099 -265.739603)
		(end 335.863946 -265.663426)
		(width 0.0889)
		(layer "In4.Cu")
		(net "M_D_CPU0_SB_CS_N<0>")
	)
	(arc
		(start 339.05825 -265.663426)
		(mid 339.341206 -265.739603)
		(end 339.624162 -265.663426)
		(width 0.0889)
		(layer "In4.Cu")
		(net "M_D_CPU0_SB_CS_N<0>")
	)
	(arc
		(start 327.28027 -265.52906)
		(mid 327.537847 -265.563252)
		(end 327.777602 -265.663426)
		(width 0.0889)
		(layer "In4.Cu")
		(net "M_D_CPU0_SB_CS_N<0>")
	)
	(arc
		(start 338.118196 -265.663426)
		(mid 338.401152 -265.739603)
		(end 338.684108 -265.663426)
		(width 0.0889)
		(layer "In4.Cu")
		(net "M_D_CPU0_SB_CS_N<0>")
	)
	(arc
		(start 335.863946 -265.663426)
		(mid 336.046197 -265.613076)
		(end 336.229706 -265.6586)
		(width 0.0889)
		(layer "In4.Cu")
		(net "M_D_CPU0_SB_CS_N<0>")
	)
	(arc
		(start 338.69249 -265.6586)
		(mid 338.875998 -265.613106)
		(end 339.05825 -265.663426)
		(width 0.0889)
		(layer "In4.Cu")
		(net "M_D_CPU0_SB_CS_N<0>")
	)
	(arc
		(start 332.103984 -265.663426)
		(mid 332.286235 -265.613076)
		(end 332.469744 -265.6586)
		(width 0.0889)
		(layer "In4.Cu")
		(net "M_D_CPU0_SB_CS_N<0>")
	)
	(arc
		(start 327.777602 -265.663426)
		(mid 328.052308 -265.73979)
		(end 328.32929 -265.672062)
		(width 0.0889)
		(layer "In4.Cu")
		(net "M_D_CPU0_SB_CS_N<0>")
	)
	(arc
		(start 336.804 -265.663426)
		(mid 336.986251 -265.613076)
		(end 337.16976 -265.6586)
		(width 0.0889)
		(layer "In4.Cu")
		(net "M_D_CPU0_SB_CS_N<0>")
	)
	(arc
		(start 339.99805 -265.663426)
		(mid 340.245646 -265.738604)
		(end 340.500716 -265.695176)
		(width 0.0889)
		(layer "In4.Cu")
		(net "M_D_CPU0_SB_CS_N<0>")
	)
	(arc
		(start 331.538072 -265.663426)
		(mid 331.821028 -265.739603)
		(end 332.103984 -265.663426)
		(width 0.0889)
		(layer "In4.Cu")
		(net "M_D_CPU0_SB_CS_N<0>")
	)
	(arc
		(start 330.232512 -265.6586)
		(mid 330.41602 -265.613106)
		(end 330.598272 -265.663426)
		(width 0.0889)
		(layer "In4.Cu")
		(net "M_D_CPU0_SB_CS_N<0>")
	)
	(arc
		(start 339.624162 -265.663426)
		(mid 339.811106 -265.613171)
		(end 339.99805 -265.663426)
		(width 0.0889)
		(layer "In4.Cu")
		(net "M_D_CPU0_SB_CS_N<0>")
	)
	(arc
		(start 333.992474 -265.6586)
		(mid 334.175982 -265.613106)
		(end 334.358234 -265.663426)
		(width 0.0889)
		(layer "In4.Cu")
		(net "M_D_CPU0_SB_CS_N<0>")
	)
	(arc
		(start 330.598272 -265.663426)
		(mid 330.881228 -265.739603)
		(end 331.164184 -265.663426)
		(width 0.0889)
		(layer "In4.Cu")
		(net "M_D_CPU0_SB_CS_N<0>")
	)
	(arc
		(start 334.924146 -265.663426)
		(mid 335.11109 -265.613171)
		(end 335.298034 -265.663426)
		(width 0.0889)
		(layer "In4.Cu")
		(net "M_D_CPU0_SB_CS_N<0>")
	)
	(arc
		(start 333.41818 -265.663426)
		(mid 333.701136 -265.739603)
		(end 333.984092 -265.663426)
		(width 0.0889)
		(layer "In4.Cu")
		(net "M_D_CPU0_SB_CS_N<0>")
	)
	(arc
		(start 329.292458 -265.6586)
		(mid 329.475966 -265.613106)
		(end 329.658218 -265.663426)
		(width 0.0889)
		(layer "In4.Cu")
		(net "M_D_CPU0_SB_CS_N<0>")
	)
	(arc
		(start 337.178142 -265.663426)
		(mid 337.461098 -265.739603)
		(end 337.744054 -265.663426)
		(width 0.0889)
		(layer "In4.Cu")
		(net "M_D_CPU0_SB_CS_N<0>")
	)
	(arc
		(start 337.752436 -265.6586)
		(mid 337.935944 -265.613106)
		(end 338.118196 -265.663426)
		(width 0.0889)
		(layer "In4.Cu")
		(net "M_D_CPU0_SB_CS_N<0>")
	)
	(arc
		(start 334.358234 -265.663426)
		(mid 334.64119 -265.739603)
		(end 334.924146 -265.663426)
		(width 0.0889)
		(layer "In4.Cu")
		(net "M_D_CPU0_SB_CS_N<0>")
	)
	(arc
		(start 333.05242 -265.6586)
		(mid 333.235928 -265.613106)
		(end 333.41818 -265.663426)
		(width 0.0889)
		(layer "In4.Cu")
		(net "M_D_CPU0_SB_CS_N<0>")
	)
	(arc
		(start 331.164184 -265.663426)
		(mid 331.351128 -265.613171)
		(end 331.538072 -265.663426)
		(width 0.0889)
		(layer "In4.Cu")
		(net "M_D_CPU0_SB_CS_N<0>")
	)
	(arc
		(start 328.718164 -265.663426)
		(mid 329.00112 -265.739603)
		(end 329.284076 -265.663426)
		(width 0.0889)
		(layer "In4.Cu")
		(net "M_D_CPU0_SB_CS_N<0>")
	)
	(arc
		(start 328.344022 -265.663426)
		(mid 328.526273 -265.613076)
		(end 328.709782 -265.6586)
		(width 0.0889)
		(layer "In4.Cu")
		(net "M_D_CPU0_SB_CS_N<0>")
	)
	(arc
		(start 332.478126 -265.663426)
		(mid 332.761082 -265.739603)
		(end 333.044038 -265.663426)
		(width 0.0889)
		(layer "In4.Cu")
		(net "M_D_CPU0_SB_CS_N<0>")
	)
	(arc
		(start 336.238088 -265.663426)
		(mid 336.521044 -265.739603)
		(end 336.804 -265.663426)
		(width 0.0889)
		(layer "In4.Cu")
		(net "M_D_CPU0_SB_CS_N<0>")
	)
	(segment
		(start 341.218012 -270.580104)
		(end 340.75116 -270.846042)
		(width 0.10668)
		(layer "F.Cu")
		(net "M_D_CPU0_SB_CB<7>")
	)
	(segment
		(start 337.744054 -270.523462)
		(end 337.752436 -270.518636)
		(width 0.0889)
		(layer "In4.Cu")
		(net "M_D_CPU0_SB_CB<7>")
	)
	(segment
		(start 281.913076 -273.37131)
		(end 282.143708 -273.37131)
		(width 0.14478)
		(layer "In4.Cu")
		(net "M_D_CPU0_SB_CB<7>")
	)
	(segment
		(start 282.699968 -274.260056)
		(end 282.862782 -274.097242)
		(width 0.14478)
		(layer "In4.Cu")
		(net "M_D_CPU0_SB_CB<7>")
	)
	(segment
		(start 283.256228 -273.554952)
		(end 283.419042 -273.717766)
		(width 0.14478)
		(layer "In4.Cu")
		(net "M_D_CPU0_SB_CB<7>")
	)
	(segment
		(start 332.469744 -270.518636)
		(end 332.478126 -270.523462)
		(width 0.0889)
		(layer "In4.Cu")
		(net "M_D_CPU0_SB_CB<7>")
	)
	(segment
		(start 281.587448 -274.260056)
		(end 281.750262 -274.097242)
		(width 0.14478)
		(layer "In4.Cu")
		(net "M_D_CPU0_SB_CB<7>")
	)
	(segment
		(start 283.419042 -273.717766)
		(end 283.419042 -274.097242)
		(width 0.14478)
		(layer "In4.Cu")
		(net "M_D_CPU0_SB_CB<7>")
	)
	(segment
		(start 324.943978 -269.127732)
		(end 325.928736 -270.11249)
		(width 0.0889)
		(layer "In4.Cu")
		(net "M_D_CPU0_SB_CB<7>")
	)
	(segment
		(start 281.750262 -273.534124)
		(end 281.913076 -273.37131)
		(width 0.14478)
		(layer "In4.Cu")
		(net "M_D_CPU0_SB_CB<7>")
	)
	(segment
		(start 287.235392 -273.410172)
		(end 308.629304 -273.410172)
		(width 0.14478)
		(layer "In4.Cu")
		(net "M_D_CPU0_SB_CB<7>")
	)
	(segment
		(start 336.229706 -270.518636)
		(end 336.238088 -270.523462)
		(width 0.0889)
		(layer "In4.Cu")
		(net "M_D_CPU0_SB_CB<7>")
	)
	(segment
		(start 340.596982 -270.580612)
		(end 340.75116 -270.846042)
		(width 0.0889)
		(layer "In4.Cu")
		(net "M_D_CPU0_SB_CB<7>")
	)
	(segment
		(start 324.390258 -269.127732)
		(end 324.943978 -269.127732)
		(width 0.0889)
		(layer "In4.Cu")
		(net "M_D_CPU0_SB_CB<7>")
	)
	(segment
		(start 328.709782 -270.518636)
		(end 328.718164 -270.523462)
		(width 0.0889)
		(layer "In4.Cu")
		(net "M_D_CPU0_SB_CB<7>")
	)
	(segment
		(start 286.385508 -274.260056)
		(end 287.235392 -273.410172)
		(width 0.14478)
		(layer "In4.Cu")
		(net "M_D_CPU0_SB_CB<7>")
	)
	(segment
		(start 324.223126 -268.9606)
		(end 324.390258 -269.127732)
		(width 0.0889)
		(layer "In4.Cu")
		(net "M_D_CPU0_SB_CB<7>")
	)
	(segment
		(start 323.874892 -268.9606)
		(end 324.223126 -268.9606)
		(width 0.0889)
		(layer "In4.Cu")
		(net "M_D_CPU0_SB_CB<7>")
	)
	(segment
		(start 338.684108 -270.523462)
		(end 338.69249 -270.518636)
		(width 0.0889)
		(layer "In4.Cu")
		(net "M_D_CPU0_SB_CB<7>")
	)
	(segment
		(start 328.32929 -270.532098)
		(end 328.344022 -270.523462)
		(width 0.0889)
		(layer "In4.Cu")
		(net "M_D_CPU0_SB_CB<7>")
	)
	(segment
		(start 282.862782 -273.717766)
		(end 283.025596 -273.554952)
		(width 0.14478)
		(layer "In4.Cu")
		(net "M_D_CPU0_SB_CB<7>")
	)
	(segment
		(start 283.581856 -274.260056)
		(end 286.385508 -274.260056)
		(width 0.14478)
		(layer "In4.Cu")
		(net "M_D_CPU0_SB_CB<7>")
	)
	(segment
		(start 283.025596 -273.554952)
		(end 283.256228 -273.554952)
		(width 0.14478)
		(layer "In4.Cu")
		(net "M_D_CPU0_SB_CB<7>")
	)
	(segment
		(start 331.52969 -270.518636)
		(end 331.538072 -270.523462)
		(width 0.0889)
		(layer "In4.Cu")
		(net "M_D_CPU0_SB_CB<7>")
	)
	(segment
		(start 282.469336 -274.260056)
		(end 282.699968 -274.260056)
		(width 0.14478)
		(layer "In4.Cu")
		(net "M_D_CPU0_SB_CB<7>")
	)
	(segment
		(start 283.419042 -274.097242)
		(end 283.581856 -274.260056)
		(width 0.14478)
		(layer "In4.Cu")
		(net "M_D_CPU0_SB_CB<7>")
	)
	(segment
		(start 280.635964 -274.684998)
		(end 281.060906 -274.260056)
		(width 0.14478)
		(layer "In4.Cu")
		(net "M_D_CPU0_SB_CB<7>")
	)
	(segment
		(start 326.629776 -270.402812)
		(end 327.33107 -270.402812)
		(width 0.0889)
		(layer "In4.Cu")
		(net "M_D_CPU0_SB_CB<7>")
	)
	(segment
		(start 282.306522 -273.534124)
		(end 282.306522 -274.097242)
		(width 0.14478)
		(layer "In4.Cu")
		(net "M_D_CPU0_SB_CB<7>")
	)
	(segment
		(start 340.500716 -270.555212)
		(end 340.596982 -270.580612)
		(width 0.0889)
		(layer "In4.Cu")
		(net "M_D_CPU0_SB_CB<7>")
	)
	(segment
		(start 281.750262 -274.097242)
		(end 281.750262 -273.534124)
		(width 0.14478)
		(layer "In4.Cu")
		(net "M_D_CPU0_SB_CB<7>")
	)
	(segment
		(start 333.044038 -270.523462)
		(end 333.05242 -270.518636)
		(width 0.0889)
		(layer "In4.Cu")
		(net "M_D_CPU0_SB_CB<7>")
	)
	(segment
		(start 281.060906 -274.260056)
		(end 281.587448 -274.260056)
		(width 0.14478)
		(layer "In4.Cu")
		(net "M_D_CPU0_SB_CB<7>")
	)
	(segment
		(start 282.143708 -273.37131)
		(end 282.306522 -273.534124)
		(width 0.14478)
		(layer "In4.Cu")
		(net "M_D_CPU0_SB_CB<7>")
	)
	(segment
		(start 337.16976 -270.518636)
		(end 337.178142 -270.523462)
		(width 0.0889)
		(layer "In4.Cu")
		(net "M_D_CPU0_SB_CB<7>")
	)
	(segment
		(start 282.306522 -274.097242)
		(end 282.469336 -274.260056)
		(width 0.14478)
		(layer "In4.Cu")
		(net "M_D_CPU0_SB_CB<7>")
	)
	(segment
		(start 282.862782 -274.097242)
		(end 282.862782 -273.717766)
		(width 0.14478)
		(layer "In4.Cu")
		(net "M_D_CPU0_SB_CB<7>")
	)
	(segment
		(start 333.984092 -270.523462)
		(end 333.992474 -270.518636)
		(width 0.0889)
		(layer "In4.Cu")
		(net "M_D_CPU0_SB_CB<7>")
	)
	(segment
		(start 329.284076 -270.523462)
		(end 329.292458 -270.518636)
		(width 0.0889)
		(layer "In4.Cu")
		(net "M_D_CPU0_SB_CB<7>")
	)
	(segment
		(start 313.078876 -268.9606)
		(end 323.874892 -268.9606)
		(width 0.14478)
		(layer "In4.Cu")
		(net "M_D_CPU0_SB_CB<7>")
	)
	(segment
		(start 308.629304 -273.410172)
		(end 313.078876 -268.9606)
		(width 0.14478)
		(layer "In4.Cu")
		(net "M_D_CPU0_SB_CB<7>")
	)
	(arc
		(start 334.358234 -270.523462)
		(mid 334.64119 -270.599639)
		(end 334.924146 -270.523462)
		(width 0.0889)
		(layer "In4.Cu")
		(net "M_D_CPU0_SB_CB<7>")
	)
	(arc
		(start 333.41818 -270.523462)
		(mid 333.701136 -270.599639)
		(end 333.984092 -270.523462)
		(width 0.0889)
		(layer "In4.Cu")
		(net "M_D_CPU0_SB_CB<7>")
	)
	(arc
		(start 333.992474 -270.518636)
		(mid 334.175982 -270.473142)
		(end 334.358234 -270.523462)
		(width 0.0889)
		(layer "In4.Cu")
		(net "M_D_CPU0_SB_CB<7>")
	)
	(arc
		(start 325.928736 -270.11249)
		(mid 326.25039 -270.327349)
		(end 326.629776 -270.402812)
		(width 0.0889)
		(layer "In4.Cu")
		(net "M_D_CPU0_SB_CB<7>")
	)
	(arc
		(start 328.344022 -270.523462)
		(mid 328.526273 -270.473112)
		(end 328.709782 -270.518636)
		(width 0.0889)
		(layer "In4.Cu")
		(net "M_D_CPU0_SB_CB<7>")
	)
	(arc
		(start 335.298034 -270.523462)
		(mid 335.58099 -270.599639)
		(end 335.863946 -270.523462)
		(width 0.0889)
		(layer "In4.Cu")
		(net "M_D_CPU0_SB_CB<7>")
	)
	(arc
		(start 338.69249 -270.518636)
		(mid 338.875998 -270.473142)
		(end 339.05825 -270.523462)
		(width 0.0889)
		(layer "In4.Cu")
		(net "M_D_CPU0_SB_CB<7>")
	)
	(arc
		(start 327.33107 -270.402812)
		(mid 327.562339 -270.433512)
		(end 327.777602 -270.523462)
		(width 0.0889)
		(layer "In4.Cu")
		(net "M_D_CPU0_SB_CB<7>")
	)
	(arc
		(start 330.22413 -270.523462)
		(mid 330.411074 -270.473207)
		(end 330.598018 -270.523462)
		(width 0.0889)
		(layer "In4.Cu")
		(net "M_D_CPU0_SB_CB<7>")
	)
	(arc
		(start 332.103984 -270.523462)
		(mid 332.286235 -270.473112)
		(end 332.469744 -270.518636)
		(width 0.0889)
		(layer "In4.Cu")
		(net "M_D_CPU0_SB_CB<7>")
	)
	(arc
		(start 328.718164 -270.523462)
		(mid 329.00112 -270.599639)
		(end 329.284076 -270.523462)
		(width 0.0889)
		(layer "In4.Cu")
		(net "M_D_CPU0_SB_CB<7>")
	)
	(arc
		(start 333.05242 -270.518636)
		(mid 333.235928 -270.473142)
		(end 333.41818 -270.523462)
		(width 0.0889)
		(layer "In4.Cu")
		(net "M_D_CPU0_SB_CB<7>")
	)
	(arc
		(start 330.598018 -270.523462)
		(mid 330.880974 -270.599639)
		(end 331.16393 -270.523462)
		(width 0.0889)
		(layer "In4.Cu")
		(net "M_D_CPU0_SB_CB<7>")
	)
	(arc
		(start 337.752436 -270.518636)
		(mid 337.935944 -270.473142)
		(end 338.118196 -270.523462)
		(width 0.0889)
		(layer "In4.Cu")
		(net "M_D_CPU0_SB_CB<7>")
	)
	(arc
		(start 327.777602 -270.523462)
		(mid 328.052308 -270.599826)
		(end 328.32929 -270.532098)
		(width 0.0889)
		(layer "In4.Cu")
		(net "M_D_CPU0_SB_CB<7>")
	)
	(arc
		(start 336.238088 -270.523462)
		(mid 336.521044 -270.599639)
		(end 336.804 -270.523462)
		(width 0.0889)
		(layer "In4.Cu")
		(net "M_D_CPU0_SB_CB<7>")
	)
	(arc
		(start 329.292458 -270.518636)
		(mid 329.475966 -270.473142)
		(end 329.658218 -270.523462)
		(width 0.0889)
		(layer "In4.Cu")
		(net "M_D_CPU0_SB_CB<7>")
	)
	(arc
		(start 338.118196 -270.523462)
		(mid 338.401152 -270.599639)
		(end 338.684108 -270.523462)
		(width 0.0889)
		(layer "In4.Cu")
		(net "M_D_CPU0_SB_CB<7>")
	)
	(arc
		(start 339.05825 -270.523462)
		(mid 339.341206 -270.599639)
		(end 339.624162 -270.523462)
		(width 0.0889)
		(layer "In4.Cu")
		(net "M_D_CPU0_SB_CB<7>")
	)
	(arc
		(start 332.478126 -270.523462)
		(mid 332.761082 -270.599639)
		(end 333.044038 -270.523462)
		(width 0.0889)
		(layer "In4.Cu")
		(net "M_D_CPU0_SB_CB<7>")
	)
	(arc
		(start 334.924146 -270.523462)
		(mid 335.11109 -270.473207)
		(end 335.298034 -270.523462)
		(width 0.0889)
		(layer "In4.Cu")
		(net "M_D_CPU0_SB_CB<7>")
	)
	(arc
		(start 336.804 -270.523462)
		(mid 336.986251 -270.473112)
		(end 337.16976 -270.518636)
		(width 0.0889)
		(layer "In4.Cu")
		(net "M_D_CPU0_SB_CB<7>")
	)
	(arc
		(start 339.99805 -270.523462)
		(mid 340.245646 -270.59864)
		(end 340.500716 -270.555212)
		(width 0.0889)
		(layer "In4.Cu")
		(net "M_D_CPU0_SB_CB<7>")
	)
	(arc
		(start 331.16393 -270.523462)
		(mid 331.346181 -270.473112)
		(end 331.52969 -270.518636)
		(width 0.0889)
		(layer "In4.Cu")
		(net "M_D_CPU0_SB_CB<7>")
	)
	(arc
		(start 337.178142 -270.523462)
		(mid 337.461098 -270.599639)
		(end 337.744054 -270.523462)
		(width 0.0889)
		(layer "In4.Cu")
		(net "M_D_CPU0_SB_CB<7>")
	)
	(arc
		(start 329.658218 -270.523462)
		(mid 329.941174 -270.599639)
		(end 330.22413 -270.523462)
		(width 0.0889)
		(layer "In4.Cu")
		(net "M_D_CPU0_SB_CB<7>")
	)
	(arc
		(start 339.624162 -270.523462)
		(mid 339.811106 -270.473207)
		(end 339.99805 -270.523462)
		(width 0.0889)
		(layer "In4.Cu")
		(net "M_D_CPU0_SB_CB<7>")
	)
	(arc
		(start 331.538072 -270.523462)
		(mid 331.821028 -270.599639)
		(end 332.103984 -270.523462)
		(width 0.0889)
		(layer "In4.Cu")
		(net "M_D_CPU0_SB_CB<7>")
	)
	(arc
		(start 335.863946 -270.523462)
		(mid 336.046197 -270.473112)
		(end 336.229706 -270.518636)
		(width 0.0889)
		(layer "In4.Cu")
		(net "M_D_CPU0_SB_CB<7>")
	)
	(segment
		(start 339.808058 -269.770098)
		(end 339.341206 -270.036036)
		(width 0.10668)
		(layer "F.Cu")
		(net "M_D_CPU0_SB_CB<6>")
	)
	(segment
		(start 283.127958 -271.806924)
		(end 283.127958 -272.39722)
		(width 0.14478)
		(layer "In4.Cu")
		(net "M_D_CPU0_SB_CB<6>")
	)
	(segment
		(start 325.178674 -268.551152)
		(end 326.252332 -269.62481)
		(width 0.0889)
		(layer "In4.Cu")
		(net "M_D_CPU0_SB_CB<6>")
	)
	(segment
		(start 339.090762 -269.745206)
		(end 339.187028 -269.770606)
		(width 0.0889)
		(layer "In4.Cu")
		(net "M_D_CPU0_SB_CB<6>")
	)
	(segment
		(start 285.92653 -272.560034)
		(end 286.776414 -271.71015)
		(width 0.14478)
		(layer "In4.Cu")
		(net "M_D_CPU0_SB_CB<6>")
	)
	(segment
		(start 324.890638 -268.551152)
		(end 325.178674 -268.551152)
		(width 0.0889)
		(layer "In4.Cu")
		(net "M_D_CPU0_SB_CB<6>")
	)
	(segment
		(start 284.403292 -272.560034)
		(end 285.92653 -272.560034)
		(width 0.14478)
		(layer "In4.Cu")
		(net "M_D_CPU0_SB_CB<6>")
	)
	(segment
		(start 326.93356 -269.71371)
		(end 326.951848 -269.703296)
		(width 0.0889)
		(layer "In4.Cu")
		(net "M_D_CPU0_SB_CB<6>")
	)
	(segment
		(start 283.847032 -271.792192)
		(end 284.077664 -271.792192)
		(width 0.14478)
		(layer "In4.Cu")
		(net "M_D_CPU0_SB_CB<6>")
	)
	(segment
		(start 324.390766 -268.05128)
		(end 324.890638 -268.551152)
		(width 0.0889)
		(layer "In4.Cu")
		(net "M_D_CPU0_SB_CB<6>")
	)
	(segment
		(start 284.240478 -272.39722)
		(end 284.403292 -272.560034)
		(width 0.14478)
		(layer "In4.Cu")
		(net "M_D_CPU0_SB_CB<6>")
	)
	(segment
		(start 282.408884 -272.560034)
		(end 282.571698 -272.39722)
		(width 0.14478)
		(layer "In4.Cu")
		(net "M_D_CPU0_SB_CB<6>")
	)
	(segment
		(start 333.879698 -269.70863)
		(end 333.88808 -269.713456)
		(width 0.0889)
		(layer "In4.Cu")
		(net "M_D_CPU0_SB_CB<6>")
	)
	(segment
		(start 330.69403 -269.713456)
		(end 330.702412 -269.70863)
		(width 0.0889)
		(layer "In4.Cu")
		(net "M_D_CPU0_SB_CB<6>")
	)
	(segment
		(start 281.296364 -272.560034)
		(end 281.459178 -272.39722)
		(width 0.14478)
		(layer "In4.Cu")
		(net "M_D_CPU0_SB_CB<6>")
	)
	(segment
		(start 286.776414 -271.71015)
		(end 309.057294 -271.71015)
		(width 0.14478)
		(layer "In4.Cu")
		(net "M_D_CPU0_SB_CB<6>")
	)
	(segment
		(start 282.015438 -271.806924)
		(end 282.015438 -272.39722)
		(width 0.14478)
		(layer "In4.Cu")
		(net "M_D_CPU0_SB_CB<6>")
	)
	(segment
		(start 281.621992 -271.64411)
		(end 281.852624 -271.64411)
		(width 0.14478)
		(layer "In4.Cu")
		(net "M_D_CPU0_SB_CB<6>")
	)
	(segment
		(start 327.874122 -269.713456)
		(end 327.882504 -269.70863)
		(width 0.0889)
		(layer "In4.Cu")
		(net "M_D_CPU0_SB_CB<6>")
	)
	(segment
		(start 334.819752 -269.70863)
		(end 334.828134 -269.713456)
		(width 0.0889)
		(layer "In4.Cu")
		(net "M_D_CPU0_SB_CB<6>")
	)
	(segment
		(start 312.716164 -268.05128)
		(end 323.915024 -268.05128)
		(width 0.14478)
		(layer "In4.Cu")
		(net "M_D_CPU0_SB_CB<6>")
	)
	(segment
		(start 281.459178 -272.39722)
		(end 281.459178 -271.806924)
		(width 0.14478)
		(layer "In4.Cu")
		(net "M_D_CPU0_SB_CB<6>")
	)
	(segment
		(start 281.852624 -271.64411)
		(end 282.015438 -271.806924)
		(width 0.14478)
		(layer "In4.Cu")
		(net "M_D_CPU0_SB_CB<6>")
	)
	(segment
		(start 284.240478 -271.955006)
		(end 284.240478 -272.39722)
		(width 0.14478)
		(layer "In4.Cu")
		(net "M_D_CPU0_SB_CB<6>")
	)
	(segment
		(start 335.394046 -269.713456)
		(end 335.402428 -269.70863)
		(width 0.0889)
		(layer "In4.Cu")
		(net "M_D_CPU0_SB_CB<6>")
	)
	(segment
		(start 339.187028 -269.770606)
		(end 339.341206 -270.036036)
		(width 0.0889)
		(layer "In4.Cu")
		(net "M_D_CPU0_SB_CB<6>")
	)
	(segment
		(start 283.684218 -271.955006)
		(end 283.847032 -271.792192)
		(width 0.14478)
		(layer "In4.Cu")
		(net "M_D_CPU0_SB_CB<6>")
	)
	(segment
		(start 282.571698 -271.806924)
		(end 282.734512 -271.64411)
		(width 0.14478)
		(layer "In4.Cu")
		(net "M_D_CPU0_SB_CB<6>")
	)
	(segment
		(start 281.060906 -272.560034)
		(end 281.296364 -272.560034)
		(width 0.14478)
		(layer "In4.Cu")
		(net "M_D_CPU0_SB_CB<6>")
	)
	(segment
		(start 282.015438 -272.39722)
		(end 282.178252 -272.560034)
		(width 0.14478)
		(layer "In4.Cu")
		(net "M_D_CPU0_SB_CB<6>")
	)
	(segment
		(start 336.3341 -269.713456)
		(end 336.342482 -269.70863)
		(width 0.0889)
		(layer "In4.Cu")
		(net "M_D_CPU0_SB_CB<6>")
	)
	(segment
		(start 283.290772 -272.560034)
		(end 283.521404 -272.560034)
		(width 0.14478)
		(layer "In4.Cu")
		(net "M_D_CPU0_SB_CB<6>")
	)
	(segment
		(start 326.917812 -269.722854)
		(end 326.93356 -269.71371)
		(width 0.0889)
		(layer "In4.Cu")
		(net "M_D_CPU0_SB_CB<6>")
	)
	(segment
		(start 330.119736 -269.70863)
		(end 330.128118 -269.713456)
		(width 0.0889)
		(layer "In4.Cu")
		(net "M_D_CPU0_SB_CB<6>")
	)
	(segment
		(start 331.634084 -269.713456)
		(end 331.642466 -269.70863)
		(width 0.0889)
		(layer "In4.Cu")
		(net "M_D_CPU0_SB_CB<6>")
	)
	(segment
		(start 338.579714 -269.70863)
		(end 338.588096 -269.713456)
		(width 0.0889)
		(layer "In4.Cu")
		(net "M_D_CPU0_SB_CB<6>")
	)
	(segment
		(start 283.684218 -272.39722)
		(end 283.684218 -271.955006)
		(width 0.14478)
		(layer "In4.Cu")
		(net "M_D_CPU0_SB_CB<6>")
	)
	(segment
		(start 281.459178 -271.806924)
		(end 281.621992 -271.64411)
		(width 0.14478)
		(layer "In4.Cu")
		(net "M_D_CPU0_SB_CB<6>")
	)
	(segment
		(start 282.965144 -271.64411)
		(end 283.127958 -271.806924)
		(width 0.14478)
		(layer "In4.Cu")
		(net "M_D_CPU0_SB_CB<6>")
	)
	(segment
		(start 283.521404 -272.560034)
		(end 283.684218 -272.39722)
		(width 0.14478)
		(layer "In4.Cu")
		(net "M_D_CPU0_SB_CB<6>")
	)
	(segment
		(start 282.734512 -271.64411)
		(end 282.965144 -271.64411)
		(width 0.14478)
		(layer "In4.Cu")
		(net "M_D_CPU0_SB_CB<6>")
	)
	(segment
		(start 282.571698 -272.39722)
		(end 282.571698 -271.806924)
		(width 0.14478)
		(layer "In4.Cu")
		(net "M_D_CPU0_SB_CB<6>")
	)
	(segment
		(start 327.85939 -269.722092)
		(end 327.874122 -269.713456)
		(width 0.0889)
		(layer "In4.Cu")
		(net "M_D_CPU0_SB_CB<6>")
	)
	(segment
		(start 309.057294 -271.71015)
		(end 312.716164 -268.05128)
		(width 0.14478)
		(layer "In4.Cu")
		(net "M_D_CPU0_SB_CB<6>")
	)
	(segment
		(start 284.077664 -271.792192)
		(end 284.240478 -271.955006)
		(width 0.14478)
		(layer "In4.Cu")
		(net "M_D_CPU0_SB_CB<6>")
	)
	(segment
		(start 282.178252 -272.560034)
		(end 282.408884 -272.560034)
		(width 0.14478)
		(layer "In4.Cu")
		(net "M_D_CPU0_SB_CB<6>")
	)
	(segment
		(start 283.127958 -272.39722)
		(end 283.290772 -272.560034)
		(width 0.14478)
		(layer "In4.Cu")
		(net "M_D_CPU0_SB_CB<6>")
	)
	(segment
		(start 280.635964 -272.984976)
		(end 281.060906 -272.560034)
		(width 0.14478)
		(layer "In4.Cu")
		(net "M_D_CPU0_SB_CB<6>")
	)
	(segment
		(start 323.915024 -268.05128)
		(end 324.390766 -268.05128)
		(width 0.0889)
		(layer "In4.Cu")
		(net "M_D_CPU0_SB_CB<6>")
	)
	(arc
		(start 332.948026 -269.713456)
		(mid 333.230982 -269.789633)
		(end 333.513938 -269.713456)
		(width 0.0889)
		(layer "In4.Cu")
		(net "M_D_CPU0_SB_CB<6>")
	)
	(arc
		(start 326.367648 -269.713456)
		(mid 326.641503 -269.789806)
		(end 326.917812 -269.722854)
		(width 0.0889)
		(layer "In4.Cu")
		(net "M_D_CPU0_SB_CB<6>")
	)
	(arc
		(start 331.642466 -269.70863)
		(mid 331.825974 -269.663136)
		(end 332.008226 -269.713456)
		(width 0.0889)
		(layer "In4.Cu")
		(net "M_D_CPU0_SB_CB<6>")
	)
	(arc
		(start 337.274154 -269.713456)
		(mid 337.461098 -269.663201)
		(end 337.648042 -269.713456)
		(width 0.0889)
		(layer "In4.Cu")
		(net "M_D_CPU0_SB_CB<6>")
	)
	(arc
		(start 328.814176 -269.713456)
		(mid 329.00112 -269.663201)
		(end 329.188064 -269.713456)
		(width 0.0889)
		(layer "In4.Cu")
		(net "M_D_CPU0_SB_CB<6>")
	)
	(arc
		(start 337.648042 -269.713456)
		(mid 337.930998 -269.789633)
		(end 338.213954 -269.713456)
		(width 0.0889)
		(layer "In4.Cu")
		(net "M_D_CPU0_SB_CB<6>")
	)
	(arc
		(start 331.068172 -269.713456)
		(mid 331.351128 -269.789633)
		(end 331.634084 -269.713456)
		(width 0.0889)
		(layer "In4.Cu")
		(net "M_D_CPU0_SB_CB<6>")
	)
	(arc
		(start 332.008226 -269.713456)
		(mid 332.291182 -269.789633)
		(end 332.574138 -269.713456)
		(width 0.0889)
		(layer "In4.Cu")
		(net "M_D_CPU0_SB_CB<6>")
	)
	(arc
		(start 336.708242 -269.713456)
		(mid 336.991198 -269.789633)
		(end 337.274154 -269.713456)
		(width 0.0889)
		(layer "In4.Cu")
		(net "M_D_CPU0_SB_CB<6>")
	)
	(arc
		(start 335.402428 -269.70863)
		(mid 335.585936 -269.663136)
		(end 335.768188 -269.713456)
		(width 0.0889)
		(layer "In4.Cu")
		(net "M_D_CPU0_SB_CB<6>")
	)
	(arc
		(start 330.128118 -269.713456)
		(mid 330.411074 -269.789633)
		(end 330.69403 -269.713456)
		(width 0.0889)
		(layer "In4.Cu")
		(net "M_D_CPU0_SB_CB<6>")
	)
	(arc
		(start 334.453992 -269.713456)
		(mid 334.636243 -269.663106)
		(end 334.819752 -269.70863)
		(width 0.0889)
		(layer "In4.Cu")
		(net "M_D_CPU0_SB_CB<6>")
	)
	(arc
		(start 330.702412 -269.70863)
		(mid 330.88592 -269.663136)
		(end 331.068172 -269.713456)
		(width 0.0889)
		(layer "In4.Cu")
		(net "M_D_CPU0_SB_CB<6>")
	)
	(arc
		(start 338.588096 -269.713456)
		(mid 338.835692 -269.788634)
		(end 339.090762 -269.745206)
		(width 0.0889)
		(layer "In4.Cu")
		(net "M_D_CPU0_SB_CB<6>")
	)
	(arc
		(start 335.768188 -269.713456)
		(mid 336.051144 -269.789633)
		(end 336.3341 -269.713456)
		(width 0.0889)
		(layer "In4.Cu")
		(net "M_D_CPU0_SB_CB<6>")
	)
	(arc
		(start 332.574138 -269.713456)
		(mid 332.761082 -269.663201)
		(end 332.948026 -269.713456)
		(width 0.0889)
		(layer "In4.Cu")
		(net "M_D_CPU0_SB_CB<6>")
	)
	(arc
		(start 327.882504 -269.70863)
		(mid 328.066012 -269.663136)
		(end 328.248264 -269.713456)
		(width 0.0889)
		(layer "In4.Cu")
		(net "M_D_CPU0_SB_CB<6>")
	)
	(arc
		(start 333.513938 -269.713456)
		(mid 333.696189 -269.663106)
		(end 333.879698 -269.70863)
		(width 0.0889)
		(layer "In4.Cu")
		(net "M_D_CPU0_SB_CB<6>")
	)
	(arc
		(start 326.951848 -269.703296)
		(mid 327.131077 -269.663143)
		(end 327.307702 -269.713456)
		(width 0.0889)
		(layer "In4.Cu")
		(net "M_D_CPU0_SB_CB<6>")
	)
	(arc
		(start 327.307702 -269.713456)
		(mid 327.582408 -269.78982)
		(end 327.85939 -269.722092)
		(width 0.0889)
		(layer "In4.Cu")
		(net "M_D_CPU0_SB_CB<6>")
	)
	(arc
		(start 338.213954 -269.713456)
		(mid 338.396205 -269.663106)
		(end 338.579714 -269.70863)
		(width 0.0889)
		(layer "In4.Cu")
		(net "M_D_CPU0_SB_CB<6>")
	)
	(arc
		(start 328.248264 -269.713456)
		(mid 328.53122 -269.789633)
		(end 328.814176 -269.713456)
		(width 0.0889)
		(layer "In4.Cu")
		(net "M_D_CPU0_SB_CB<6>")
	)
	(arc
		(start 329.188064 -269.713456)
		(mid 329.47102 -269.789633)
		(end 329.753976 -269.713456)
		(width 0.0889)
		(layer "In4.Cu")
		(net "M_D_CPU0_SB_CB<6>")
	)
	(arc
		(start 333.88808 -269.713456)
		(mid 334.171036 -269.789633)
		(end 334.453992 -269.713456)
		(width 0.0889)
		(layer "In4.Cu")
		(net "M_D_CPU0_SB_CB<6>")
	)
	(arc
		(start 326.252332 -269.62481)
		(mid 326.307117 -269.67287)
		(end 326.367648 -269.713456)
		(width 0.0889)
		(layer "In4.Cu")
		(net "M_D_CPU0_SB_CB<6>")
	)
	(arc
		(start 329.753976 -269.713456)
		(mid 329.936227 -269.663106)
		(end 330.119736 -269.70863)
		(width 0.0889)
		(layer "In4.Cu")
		(net "M_D_CPU0_SB_CB<6>")
	)
	(arc
		(start 336.342482 -269.70863)
		(mid 336.52599 -269.663136)
		(end 336.708242 -269.713456)
		(width 0.0889)
		(layer "In4.Cu")
		(net "M_D_CPU0_SB_CB<6>")
	)
	(arc
		(start 334.828134 -269.713456)
		(mid 335.11109 -269.789633)
		(end 335.394046 -269.713456)
		(width 0.0889)
		(layer "In4.Cu")
		(net "M_D_CPU0_SB_CB<6>")
	)
	(segment
		(start 340.747858 -269.770098)
		(end 340.281006 -270.036036)
		(width 0.10668)
		(layer "F.Cu")
		(net "M_D_CPU0_SB_CB<5>")
	)
	(segment
		(start 297.28287 -272.180558)
		(end 297.445684 -272.343372)
		(width 0.14478)
		(layer "In4.Cu")
		(net "M_D_CPU0_SB_CB<5>")
	)
	(segment
		(start 334.819752 -270.363442)
		(end 334.828134 -270.358616)
		(width 0.0889)
		(layer "In4.Cu")
		(net "M_D_CPU0_SB_CB<5>")
	)
	(segment
		(start 339.519768 -270.363442)
		(end 339.52815 -270.358616)
		(width 0.0889)
		(layer "In4.Cu")
		(net "M_D_CPU0_SB_CB<5>")
	)
	(segment
		(start 293.346378 -272.776696)
		(end 293.346378 -272.343372)
		(width 0.14478)
		(layer "In4.Cu")
		(net "M_D_CPU0_SB_CB<5>")
	)
	(segment
		(start 294.621712 -272.180558)
		(end 294.852344 -272.180558)
		(width 0.14478)
		(layer "In4.Cu")
		(net "M_D_CPU0_SB_CB<5>")
	)
	(segment
		(start 298.558204 -272.776696)
		(end 298.721018 -272.93951)
		(width 0.14478)
		(layer "In4.Cu")
		(net "M_D_CPU0_SB_CB<5>")
	)
	(segment
		(start 330.69403 -270.358616)
		(end 330.702412 -270.363442)
		(width 0.0889)
		(layer "In4.Cu")
		(net "M_D_CPU0_SB_CB<5>")
	)
	(segment
		(start 340.094062 -270.358616)
		(end 340.102444 -270.363442)
		(width 0.0889)
		(layer "In4.Cu")
		(net "M_D_CPU0_SB_CB<5>")
	)
	(segment
		(start 284.736032 -273.835114)
		(end 285.160974 -273.410172)
		(width 0.14478)
		(layer "In4.Cu")
		(net "M_D_CPU0_SB_CB<5>")
	)
	(segment
		(start 293.183564 -272.93951)
		(end 293.346378 -272.776696)
		(width 0.14478)
		(layer "In4.Cu")
		(net "M_D_CPU0_SB_CB<5>")
	)
	(segment
		(start 298.001944 -272.776696)
		(end 298.001944 -272.343372)
		(width 0.14478)
		(layer "In4.Cu")
		(net "M_D_CPU0_SB_CB<5>")
	)
	(segment
		(start 285.160974 -273.410172)
		(end 286.346646 -273.410172)
		(width 0.14478)
		(layer "In4.Cu")
		(net "M_D_CPU0_SB_CB<5>")
	)
	(segment
		(start 292.573456 -272.560034)
		(end 292.952932 -272.93951)
		(width 0.14478)
		(layer "In4.Cu")
		(net "M_D_CPU0_SB_CB<5>")
	)
	(segment
		(start 323.887084 -268.50594)
		(end 324.240906 -268.50594)
		(width 0.0889)
		(layer "In4.Cu")
		(net "M_D_CPU0_SB_CB<5>")
	)
	(segment
		(start 297.608498 -272.93951)
		(end 297.83913 -272.93951)
		(width 0.14478)
		(layer "In4.Cu")
		(net "M_D_CPU0_SB_CB<5>")
	)
	(segment
		(start 312.89752 -268.50594)
		(end 323.887084 -268.50594)
		(width 0.14478)
		(layer "In4.Cu")
		(net "M_D_CPU0_SB_CB<5>")
	)
	(segment
		(start 324.964298 -268.807692)
		(end 326.054974 -269.898368)
		(width 0.0889)
		(layer "In4.Cu")
		(net "M_D_CPU0_SB_CB<5>")
	)
	(segment
		(start 340.435184 -270.301466)
		(end 340.281006 -270.036036)
		(width 0.0889)
		(layer "In4.Cu")
		(net "M_D_CPU0_SB_CB<5>")
	)
	(segment
		(start 294.458898 -272.343372)
		(end 294.621712 -272.180558)
		(width 0.14478)
		(layer "In4.Cu")
		(net "M_D_CPU0_SB_CB<5>")
	)
	(segment
		(start 289.872674 -272.328132)
		(end 290.035488 -272.490946)
		(width 0.14478)
		(layer "In4.Cu")
		(net "M_D_CPU0_SB_CB<5>")
	)
	(segment
		(start 293.902638 -272.776696)
		(end 294.065452 -272.93951)
		(width 0.14478)
		(layer "In4.Cu")
		(net "M_D_CPU0_SB_CB<5>")
	)
	(segment
		(start 287.196784 -272.560034)
		(end 288.706306 -272.560034)
		(width 0.14478)
		(layer "In4.Cu")
		(net "M_D_CPU0_SB_CB<5>")
	)
	(segment
		(start 294.458898 -272.776696)
		(end 294.458898 -272.343372)
		(width 0.14478)
		(layer "In4.Cu")
		(net "M_D_CPU0_SB_CB<5>")
	)
	(segment
		(start 291.541454 -272.93951)
		(end 291.92093 -272.560034)
		(width 0.14478)
		(layer "In4.Cu")
		(net "M_D_CPU0_SB_CB<5>")
	)
	(segment
		(start 295.23182 -272.560034)
		(end 296.116502 -272.560034)
		(width 0.14478)
		(layer "In4.Cu")
		(net "M_D_CPU0_SB_CB<5>")
	)
	(segment
		(start 297.445684 -272.343372)
		(end 297.445684 -272.776696)
		(width 0.14478)
		(layer "In4.Cu")
		(net "M_D_CPU0_SB_CB<5>")
	)
	(segment
		(start 298.721018 -272.93951)
		(end 298.95165 -272.93951)
		(width 0.14478)
		(layer "In4.Cu")
		(net "M_D_CPU0_SB_CB<5>")
	)
	(segment
		(start 294.296084 -272.93951)
		(end 294.458898 -272.776696)
		(width 0.14478)
		(layer "In4.Cu")
		(net "M_D_CPU0_SB_CB<5>")
	)
	(segment
		(start 291.92093 -272.560034)
		(end 292.573456 -272.560034)
		(width 0.14478)
		(layer "In4.Cu")
		(net "M_D_CPU0_SB_CB<5>")
	)
	(segment
		(start 293.346378 -272.343372)
		(end 293.509192 -272.180558)
		(width 0.14478)
		(layer "In4.Cu")
		(net "M_D_CPU0_SB_CB<5>")
	)
	(segment
		(start 299.331126 -272.560034)
		(end 308.843426 -272.560034)
		(width 0.14478)
		(layer "In4.Cu")
		(net "M_D_CPU0_SB_CB<5>")
	)
	(segment
		(start 335.394046 -270.358616)
		(end 335.402428 -270.363442)
		(width 0.0889)
		(layer "In4.Cu")
		(net "M_D_CPU0_SB_CB<5>")
	)
	(segment
		(start 297.052238 -272.180558)
		(end 297.28287 -272.180558)
		(width 0.14478)
		(layer "In4.Cu")
		(net "M_D_CPU0_SB_CB<5>")
	)
	(segment
		(start 289.085782 -272.93951)
		(end 289.316414 -272.93951)
		(width 0.14478)
		(layer "In4.Cu")
		(net "M_D_CPU0_SB_CB<5>")
	)
	(segment
		(start 296.116502 -272.560034)
		(end 296.495978 -272.93951)
		(width 0.14478)
		(layer "In4.Cu")
		(net "M_D_CPU0_SB_CB<5>")
	)
	(segment
		(start 297.445684 -272.776696)
		(end 297.608498 -272.93951)
		(width 0.14478)
		(layer "In4.Cu")
		(net "M_D_CPU0_SB_CB<5>")
	)
	(segment
		(start 331.634084 -270.358616)
		(end 331.642466 -270.363442)
		(width 0.0889)
		(layer "In4.Cu")
		(net "M_D_CPU0_SB_CB<5>")
	)
	(segment
		(start 294.065452 -272.93951)
		(end 294.296084 -272.93951)
		(width 0.14478)
		(layer "In4.Cu")
		(net "M_D_CPU0_SB_CB<5>")
	)
	(segment
		(start 289.642042 -272.328132)
		(end 289.872674 -272.328132)
		(width 0.14478)
		(layer "In4.Cu")
		(net "M_D_CPU0_SB_CB<5>")
	)
	(segment
		(start 298.39539 -272.180558)
		(end 298.558204 -272.343372)
		(width 0.14478)
		(layer "In4.Cu")
		(net "M_D_CPU0_SB_CB<5>")
	)
	(segment
		(start 290.428934 -272.93951)
		(end 290.591748 -272.776696)
		(width 0.14478)
		(layer "In4.Cu")
		(net "M_D_CPU0_SB_CB<5>")
	)
	(segment
		(start 290.591748 -272.546826)
		(end 290.754562 -272.384012)
		(width 0.14478)
		(layer "In4.Cu")
		(net "M_D_CPU0_SB_CB<5>")
	)
	(segment
		(start 290.035488 -272.776696)
		(end 290.198302 -272.93951)
		(width 0.14478)
		(layer "In4.Cu")
		(net "M_D_CPU0_SB_CB<5>")
	)
	(segment
		(start 290.754562 -272.384012)
		(end 290.985194 -272.384012)
		(width 0.14478)
		(layer "In4.Cu")
		(net "M_D_CPU0_SB_CB<5>")
	)
	(segment
		(start 290.035488 -272.490946)
		(end 290.035488 -272.776696)
		(width 0.14478)
		(layer "In4.Cu")
		(net "M_D_CPU0_SB_CB<5>")
	)
	(segment
		(start 288.706306 -272.560034)
		(end 289.085782 -272.93951)
		(width 0.14478)
		(layer "In4.Cu")
		(net "M_D_CPU0_SB_CB<5>")
	)
	(segment
		(start 296.889424 -272.776696)
		(end 296.889424 -272.343372)
		(width 0.14478)
		(layer "In4.Cu")
		(net "M_D_CPU0_SB_CB<5>")
	)
	(segment
		(start 338.579714 -270.363442)
		(end 338.588096 -270.358616)
		(width 0.0889)
		(layer "In4.Cu")
		(net "M_D_CPU0_SB_CB<5>")
	)
	(segment
		(start 293.739824 -272.180558)
		(end 293.902638 -272.343372)
		(width 0.14478)
		(layer "In4.Cu")
		(net "M_D_CPU0_SB_CB<5>")
	)
	(segment
		(start 330.119736 -270.363442)
		(end 330.128118 -270.358616)
		(width 0.0889)
		(layer "In4.Cu")
		(net "M_D_CPU0_SB_CB<5>")
	)
	(segment
		(start 328.239882 -270.363442)
		(end 328.248264 -270.358616)
		(width 0.0889)
		(layer "In4.Cu")
		(net "M_D_CPU0_SB_CB<5>")
	)
	(segment
		(start 298.558204 -272.343372)
		(end 298.558204 -272.776696)
		(width 0.14478)
		(layer "In4.Cu")
		(net "M_D_CPU0_SB_CB<5>")
	)
	(segment
		(start 291.148008 -272.776696)
		(end 291.310822 -272.93951)
		(width 0.14478)
		(layer "In4.Cu")
		(net "M_D_CPU0_SB_CB<5>")
	)
	(segment
		(start 289.479228 -272.776696)
		(end 289.479228 -272.490946)
		(width 0.14478)
		(layer "In4.Cu")
		(net "M_D_CPU0_SB_CB<5>")
	)
	(segment
		(start 294.852344 -272.180558)
		(end 295.23182 -272.560034)
		(width 0.14478)
		(layer "In4.Cu")
		(net "M_D_CPU0_SB_CB<5>")
	)
	(segment
		(start 340.412832 -270.384778)
		(end 340.435184 -270.301466)
		(width 0.0889)
		(layer "In4.Cu")
		(net "M_D_CPU0_SB_CB<5>")
	)
	(segment
		(start 296.889424 -272.343372)
		(end 297.052238 -272.180558)
		(width 0.14478)
		(layer "In4.Cu")
		(net "M_D_CPU0_SB_CB<5>")
	)
	(segment
		(start 324.240906 -268.50594)
		(end 324.542658 -268.807692)
		(width 0.0889)
		(layer "In4.Cu")
		(net "M_D_CPU0_SB_CB<5>")
	)
	(segment
		(start 298.164758 -272.180558)
		(end 298.39539 -272.180558)
		(width 0.14478)
		(layer "In4.Cu")
		(net "M_D_CPU0_SB_CB<5>")
	)
	(segment
		(start 298.95165 -272.93951)
		(end 299.331126 -272.560034)
		(width 0.14478)
		(layer "In4.Cu")
		(net "M_D_CPU0_SB_CB<5>")
	)
	(segment
		(start 293.509192 -272.180558)
		(end 293.739824 -272.180558)
		(width 0.14478)
		(layer "In4.Cu")
		(net "M_D_CPU0_SB_CB<5>")
	)
	(segment
		(start 297.83913 -272.93951)
		(end 298.001944 -272.776696)
		(width 0.14478)
		(layer "In4.Cu")
		(net "M_D_CPU0_SB_CB<5>")
	)
	(segment
		(start 296.495978 -272.93951)
		(end 296.72661 -272.93951)
		(width 0.14478)
		(layer "In4.Cu")
		(net "M_D_CPU0_SB_CB<5>")
	)
	(segment
		(start 292.952932 -272.93951)
		(end 293.183564 -272.93951)
		(width 0.14478)
		(layer "In4.Cu")
		(net "M_D_CPU0_SB_CB<5>")
	)
	(segment
		(start 290.198302 -272.93951)
		(end 290.428934 -272.93951)
		(width 0.14478)
		(layer "In4.Cu")
		(net "M_D_CPU0_SB_CB<5>")
	)
	(segment
		(start 308.843426 -272.560034)
		(end 312.89752 -268.50594)
		(width 0.14478)
		(layer "In4.Cu")
		(net "M_D_CPU0_SB_CB<5>")
	)
	(segment
		(start 286.346646 -273.410172)
		(end 287.196784 -272.560034)
		(width 0.14478)
		(layer "In4.Cu")
		(net "M_D_CPU0_SB_CB<5>")
	)
	(segment
		(start 298.001944 -272.343372)
		(end 298.164758 -272.180558)
		(width 0.14478)
		(layer "In4.Cu")
		(net "M_D_CPU0_SB_CB<5>")
	)
	(segment
		(start 324.542658 -268.807692)
		(end 324.964298 -268.807692)
		(width 0.0889)
		(layer "In4.Cu")
		(net "M_D_CPU0_SB_CB<5>")
	)
	(segment
		(start 291.148008 -272.546826)
		(end 291.148008 -272.776696)
		(width 0.14478)
		(layer "In4.Cu")
		(net "M_D_CPU0_SB_CB<5>")
	)
	(segment
		(start 336.3341 -270.358616)
		(end 336.342482 -270.363442)
		(width 0.0889)
		(layer "In4.Cu")
		(net "M_D_CPU0_SB_CB<5>")
	)
	(segment
		(start 326.677782 -270.156432)
		(end 327.123806 -270.156432)
		(width 0.0889)
		(layer "In4.Cu")
		(net "M_D_CPU0_SB_CB<5>")
	)
	(segment
		(start 289.479228 -272.490946)
		(end 289.642042 -272.328132)
		(width 0.14478)
		(layer "In4.Cu")
		(net "M_D_CPU0_SB_CB<5>")
	)
	(segment
		(start 293.902638 -272.343372)
		(end 293.902638 -272.776696)
		(width 0.14478)
		(layer "In4.Cu")
		(net "M_D_CPU0_SB_CB<5>")
	)
	(segment
		(start 296.72661 -272.93951)
		(end 296.889424 -272.776696)
		(width 0.14478)
		(layer "In4.Cu")
		(net "M_D_CPU0_SB_CB<5>")
	)
	(segment
		(start 290.591748 -272.776696)
		(end 290.591748 -272.546826)
		(width 0.14478)
		(layer "In4.Cu")
		(net "M_D_CPU0_SB_CB<5>")
	)
	(segment
		(start 290.985194 -272.384012)
		(end 291.148008 -272.546826)
		(width 0.14478)
		(layer "In4.Cu")
		(net "M_D_CPU0_SB_CB<5>")
	)
	(segment
		(start 333.879698 -270.363442)
		(end 333.88808 -270.358616)
		(width 0.0889)
		(layer "In4.Cu")
		(net "M_D_CPU0_SB_CB<5>")
	)
	(segment
		(start 289.316414 -272.93951)
		(end 289.479228 -272.776696)
		(width 0.14478)
		(layer "In4.Cu")
		(net "M_D_CPU0_SB_CB<5>")
	)
	(segment
		(start 291.310822 -272.93951)
		(end 291.541454 -272.93951)
		(width 0.14478)
		(layer "In4.Cu")
		(net "M_D_CPU0_SB_CB<5>")
	)
	(arc
		(start 333.513938 -270.358616)
		(mid 333.696189 -270.408966)
		(end 333.879698 -270.363442)
		(width 0.0889)
		(layer "In4.Cu")
		(net "M_D_CPU0_SB_CB<5>")
	)
	(arc
		(start 338.588096 -270.358616)
		(mid 338.871052 -270.282439)
		(end 339.154008 -270.358616)
		(width 0.0889)
		(layer "In4.Cu")
		(net "M_D_CPU0_SB_CB<5>")
	)
	(arc
		(start 330.128118 -270.358616)
		(mid 330.411074 -270.282439)
		(end 330.69403 -270.358616)
		(width 0.0889)
		(layer "In4.Cu")
		(net "M_D_CPU0_SB_CB<5>")
	)
	(arc
		(start 329.188064 -270.358616)
		(mid 329.47102 -270.282439)
		(end 329.753976 -270.358616)
		(width 0.0889)
		(layer "In4.Cu")
		(net "M_D_CPU0_SB_CB<5>")
	)
	(arc
		(start 334.453992 -270.358616)
		(mid 334.636243 -270.408966)
		(end 334.819752 -270.363442)
		(width 0.0889)
		(layer "In4.Cu")
		(net "M_D_CPU0_SB_CB<5>")
	)
	(arc
		(start 340.102444 -270.363442)
		(mid 340.255314 -270.408083)
		(end 340.412832 -270.384778)
		(width 0.0889)
		(layer "In4.Cu")
		(net "M_D_CPU0_SB_CB<5>")
	)
	(arc
		(start 326.054974 -269.898368)
		(mid 326.340706 -270.089352)
		(end 326.677782 -270.156432)
		(width 0.0889)
		(layer "In4.Cu")
		(net "M_D_CPU0_SB_CB<5>")
	)
	(arc
		(start 328.248264 -270.358616)
		(mid 328.53122 -270.282439)
		(end 328.814176 -270.358616)
		(width 0.0889)
		(layer "In4.Cu")
		(net "M_D_CPU0_SB_CB<5>")
	)
	(arc
		(start 339.52815 -270.358616)
		(mid 339.811106 -270.282439)
		(end 340.094062 -270.358616)
		(width 0.0889)
		(layer "In4.Cu")
		(net "M_D_CPU0_SB_CB<5>")
	)
	(arc
		(start 334.828134 -270.358616)
		(mid 335.11109 -270.282439)
		(end 335.394046 -270.358616)
		(width 0.0889)
		(layer "In4.Cu")
		(net "M_D_CPU0_SB_CB<5>")
	)
	(arc
		(start 328.814176 -270.358616)
		(mid 329.00112 -270.408871)
		(end 329.188064 -270.358616)
		(width 0.0889)
		(layer "In4.Cu")
		(net "M_D_CPU0_SB_CB<5>")
	)
	(arc
		(start 339.154008 -270.358616)
		(mid 339.336259 -270.408966)
		(end 339.519768 -270.363442)
		(width 0.0889)
		(layer "In4.Cu")
		(net "M_D_CPU0_SB_CB<5>")
	)
	(arc
		(start 337.274154 -270.358616)
		(mid 337.461098 -270.408871)
		(end 337.648042 -270.358616)
		(width 0.0889)
		(layer "In4.Cu")
		(net "M_D_CPU0_SB_CB<5>")
	)
	(arc
		(start 337.648042 -270.358616)
		(mid 337.930998 -270.282439)
		(end 338.213954 -270.358616)
		(width 0.0889)
		(layer "In4.Cu")
		(net "M_D_CPU0_SB_CB<5>")
	)
	(arc
		(start 327.873614 -270.358616)
		(mid 328.056119 -270.409093)
		(end 328.239882 -270.363442)
		(width 0.0889)
		(layer "In4.Cu")
		(net "M_D_CPU0_SB_CB<5>")
	)
	(arc
		(start 338.213954 -270.358616)
		(mid 338.396205 -270.408966)
		(end 338.579714 -270.363442)
		(width 0.0889)
		(layer "In4.Cu")
		(net "M_D_CPU0_SB_CB<5>")
	)
	(arc
		(start 332.574138 -270.358616)
		(mid 332.761082 -270.408871)
		(end 332.948026 -270.358616)
		(width 0.0889)
		(layer "In4.Cu")
		(net "M_D_CPU0_SB_CB<5>")
	)
	(arc
		(start 333.88808 -270.358616)
		(mid 334.171036 -270.282439)
		(end 334.453992 -270.358616)
		(width 0.0889)
		(layer "In4.Cu")
		(net "M_D_CPU0_SB_CB<5>")
	)
	(arc
		(start 335.402428 -270.363442)
		(mid 335.585936 -270.408936)
		(end 335.768188 -270.358616)
		(width 0.0889)
		(layer "In4.Cu")
		(net "M_D_CPU0_SB_CB<5>")
	)
	(arc
		(start 336.342482 -270.363442)
		(mid 336.52599 -270.408936)
		(end 336.708242 -270.358616)
		(width 0.0889)
		(layer "In4.Cu")
		(net "M_D_CPU0_SB_CB<5>")
	)
	(arc
		(start 332.948026 -270.358616)
		(mid 333.230982 -270.282439)
		(end 333.513938 -270.358616)
		(width 0.0889)
		(layer "In4.Cu")
		(net "M_D_CPU0_SB_CB<5>")
	)
	(arc
		(start 335.768188 -270.358616)
		(mid 336.051144 -270.282439)
		(end 336.3341 -270.358616)
		(width 0.0889)
		(layer "In4.Cu")
		(net "M_D_CPU0_SB_CB<5>")
	)
	(arc
		(start 327.123806 -270.156432)
		(mid 327.512097 -270.207871)
		(end 327.873614 -270.358616)
		(width 0.0889)
		(layer "In4.Cu")
		(net "M_D_CPU0_SB_CB<5>")
	)
	(arc
		(start 336.708242 -270.358616)
		(mid 336.991198 -270.282439)
		(end 337.274154 -270.358616)
		(width 0.0889)
		(layer "In4.Cu")
		(net "M_D_CPU0_SB_CB<5>")
	)
	(arc
		(start 331.642466 -270.363442)
		(mid 331.825974 -270.408936)
		(end 332.008226 -270.358616)
		(width 0.0889)
		(layer "In4.Cu")
		(net "M_D_CPU0_SB_CB<5>")
	)
	(arc
		(start 331.068172 -270.358616)
		(mid 331.351128 -270.282439)
		(end 331.634084 -270.358616)
		(width 0.0889)
		(layer "In4.Cu")
		(net "M_D_CPU0_SB_CB<5>")
	)
	(arc
		(start 332.008226 -270.358616)
		(mid 332.291182 -270.282439)
		(end 332.574138 -270.358616)
		(width 0.0889)
		(layer "In4.Cu")
		(net "M_D_CPU0_SB_CB<5>")
	)
	(arc
		(start 329.753976 -270.358616)
		(mid 329.936227 -270.408966)
		(end 330.119736 -270.363442)
		(width 0.0889)
		(layer "In4.Cu")
		(net "M_D_CPU0_SB_CB<5>")
	)
	(arc
		(start 330.702412 -270.363442)
		(mid 330.88592 -270.408936)
		(end 331.068172 -270.358616)
		(width 0.0889)
		(layer "In4.Cu")
		(net "M_D_CPU0_SB_CB<5>")
	)
	(segment
		(start 339.337904 -268.960092)
		(end 338.871052 -269.22603)
		(width 0.10668)
		(layer "F.Cu")
		(net "M_D_CPU0_SB_CB<4>")
	)
	(segment
		(start 297.246802 -270.860012)
		(end 297.5483 -271.16151)
		(width 0.14478)
		(layer "In4.Cu")
		(net "M_D_CPU0_SB_CB<4>")
	)
	(segment
		(start 290.923472 -270.860012)
		(end 291.22497 -271.16151)
		(width 0.14478)
		(layer "In4.Cu")
		(net "M_D_CPU0_SB_CB<4>")
	)
	(segment
		(start 301.60976 -271.16151)
		(end 301.864522 -271.16151)
		(width 0.14478)
		(layer "In4.Cu")
		(net "M_D_CPU0_SB_CB<4>")
	)
	(segment
		(start 325.995538 -269.098522)
		(end 326.386952 -269.489936)
		(width 0.0889)
		(layer "In4.Cu")
		(net "M_D_CPU0_SB_CB<4>")
	)
	(segment
		(start 305.50358 -270.860012)
		(end 305.758342 -270.860012)
		(width 0.14478)
		(layer "In4.Cu")
		(net "M_D_CPU0_SB_CB<4>")
	)
	(segment
		(start 325.429626 -267.59662)
		(end 325.995538 -268.162532)
		(width 0.0889)
		(layer "In4.Cu")
		(net "M_D_CPU0_SB_CB<4>")
	)
	(segment
		(start 285.677356 -271.193768)
		(end 286.011112 -270.860012)
		(width 0.14478)
		(layer "In4.Cu")
		(net "M_D_CPU0_SB_CB<4>")
	)
	(segment
		(start 336.229706 -269.553436)
		(end 336.238088 -269.54861)
		(width 0.0889)
		(layer "In4.Cu")
		(net "M_D_CPU0_SB_CB<4>")
	)
	(segment
		(start 286.011112 -270.860012)
		(end 286.441134 -270.860012)
		(width 0.14478)
		(layer "In4.Cu")
		(net "M_D_CPU0_SB_CB<4>")
	)
	(segment
		(start 293.22395 -271.16151)
		(end 293.478712 -271.16151)
		(width 0.14478)
		(layer "In4.Cu")
		(net "M_D_CPU0_SB_CB<4>")
	)
	(segment
		(start 310.741822 -269.387828)
		(end 310.903366 -269.226284)
		(width 0.14478)
		(layer "In4.Cu")
		(net "M_D_CPU0_SB_CB<4>")
	)
	(segment
		(start 309.128668 -270.344138)
		(end 309.128668 -270.115538)
		(width 0.14478)
		(layer "In4.Cu")
		(net "M_D_CPU0_SB_CB<4>")
	)
	(segment
		(start 285.677356 -271.640808)
		(end 285.677356 -271.193768)
		(width 0.14478)
		(layer "In4.Cu")
		(net "M_D_CPU0_SB_CB<4>")
	)
	(segment
		(start 301.864522 -271.16151)
		(end 302.16602 -270.860012)
		(width 0.14478)
		(layer "In4.Cu")
		(net "M_D_CPU0_SB_CB<4>")
	)
	(segment
		(start 310.689244 -268.554962)
		(end 310.850788 -268.393418)
		(width 0.14478)
		(layer "In4.Cu")
		(net "M_D_CPU0_SB_CB<4>")
	)
	(segment
		(start 286.441134 -270.860012)
		(end 286.742632 -271.16151)
		(width 0.14478)
		(layer "In4.Cu")
		(net "M_D_CPU0_SB_CB<4>")
	)
	(segment
		(start 310.0705 -269.173706)
		(end 310.2991 -269.173706)
		(width 0.14478)
		(layer "In4.Cu")
		(net "M_D_CPU0_SB_CB<4>")
	)
	(segment
		(start 331.52969 -269.553436)
		(end 331.538072 -269.54861)
		(width 0.0889)
		(layer "In4.Cu")
		(net "M_D_CPU0_SB_CB<4>")
	)
	(segment
		(start 298.359322 -270.860012)
		(end 298.66082 -271.16151)
		(width 0.14478)
		(layer "In4.Cu")
		(net "M_D_CPU0_SB_CB<4>")
	)
	(segment
		(start 288.99993 -271.16151)
		(end 289.254692 -271.16151)
		(width 0.14478)
		(layer "In4.Cu")
		(net "M_D_CPU0_SB_CB<4>")
	)
	(segment
		(start 302.977042 -271.16151)
		(end 303.27854 -270.860012)
		(width 0.14478)
		(layer "In4.Cu")
		(net "M_D_CPU0_SB_CB<4>")
	)
	(segment
		(start 311.647586 -267.59662)
		(end 323.909944 -267.59662)
		(width 0.14478)
		(layer "In4.Cu")
		(net "M_D_CPU0_SB_CB<4>")
	)
	(segment
		(start 294.034972 -270.860012)
		(end 294.33647 -271.16151)
		(width 0.14478)
		(layer "In4.Cu")
		(net "M_D_CPU0_SB_CB<4>")
	)
	(segment
		(start 306.05984 -271.16151)
		(end 306.314602 -271.16151)
		(width 0.14478)
		(layer "In4.Cu")
		(net "M_D_CPU0_SB_CB<4>")
	)
	(segment
		(start 304.645822 -270.860012)
		(end 304.94732 -271.16151)
		(width 0.14478)
		(layer "In4.Cu")
		(net "M_D_CPU0_SB_CB<4>")
	)
	(segment
		(start 291.78123 -270.860012)
		(end 292.922452 -270.860012)
		(width 0.14478)
		(layer "In4.Cu")
		(net "M_D_CPU0_SB_CB<4>")
	)
	(segment
		(start 301.308262 -270.860012)
		(end 301.60976 -271.16151)
		(width 0.14478)
		(layer "In4.Cu")
		(net "M_D_CPU0_SB_CB<4>")
	)
	(segment
		(start 304.089562 -271.16151)
		(end 304.39106 -270.860012)
		(width 0.14478)
		(layer "In4.Cu")
		(net "M_D_CPU0_SB_CB<4>")
	)
	(segment
		(start 293.478712 -271.16151)
		(end 293.78021 -270.860012)
		(width 0.14478)
		(layer "In4.Cu")
		(net "M_D_CPU0_SB_CB<4>")
	)
	(segment
		(start 300.49724 -271.16151)
		(end 300.752002 -271.16151)
		(width 0.14478)
		(layer "In4.Cu")
		(net "M_D_CPU0_SB_CB<4>")
	)
	(segment
		(start 290.11245 -271.16151)
		(end 290.367212 -271.16151)
		(width 0.14478)
		(layer "In4.Cu")
		(net "M_D_CPU0_SB_CB<4>")
	)
	(segment
		(start 310.123078 -270.006572)
		(end 310.123078 -269.777972)
		(width 0.14478)
		(layer "In4.Cu")
		(net "M_D_CPU0_SB_CB<4>")
	)
	(segment
		(start 296.43578 -271.16151)
		(end 296.690542 -271.16151)
		(width 0.14478)
		(layer "In4.Cu")
		(net "M_D_CPU0_SB_CB<4>")
	)
	(segment
		(start 298.915582 -271.16151)
		(end 299.21708 -270.860012)
		(width 0.14478)
		(layer "In4.Cu")
		(net "M_D_CPU0_SB_CB<4>")
	)
	(segment
		(start 296.134282 -270.860012)
		(end 296.43578 -271.16151)
		(width 0.14478)
		(layer "In4.Cu")
		(net "M_D_CPU0_SB_CB<4>")
	)
	(segment
		(start 302.72228 -271.16151)
		(end 302.977042 -271.16151)
		(width 0.14478)
		(layer "In4.Cu")
		(net "M_D_CPU0_SB_CB<4>")
	)
	(segment
		(start 308.952646 -270.948404)
		(end 309.181246 -270.948404)
		(width 0.14478)
		(layer "In4.Cu")
		(net "M_D_CPU0_SB_CB<4>")
	)
	(segment
		(start 304.94732 -271.16151)
		(end 305.202082 -271.16151)
		(width 0.14478)
		(layer "In4.Cu")
		(net "M_D_CPU0_SB_CB<4>")
	)
	(segment
		(start 309.908956 -269.56385)
		(end 309.908956 -269.33525)
		(width 0.14478)
		(layer "In4.Cu")
		(net "M_D_CPU0_SB_CB<4>")
	)
	(segment
		(start 293.78021 -270.860012)
		(end 294.034972 -270.860012)
		(width 0.14478)
		(layer "In4.Cu")
		(net "M_D_CPU0_SB_CB<4>")
	)
	(segment
		(start 310.850788 -268.393418)
		(end 311.079388 -268.393418)
		(width 0.14478)
		(layer "In4.Cu")
		(net "M_D_CPU0_SB_CB<4>")
	)
	(segment
		(start 300.195742 -270.860012)
		(end 300.49724 -271.16151)
		(width 0.14478)
		(layer "In4.Cu")
		(net "M_D_CPU0_SB_CB<4>")
	)
	(segment
		(start 339.002878 -269.574772)
		(end 339.02523 -269.49146)
		(width 0.0889)
		(layer "In4.Cu")
		(net "M_D_CPU0_SB_CB<4>")
	)
	(segment
		(start 337.16976 -269.553436)
		(end 337.178142 -269.54861)
		(width 0.0889)
		(layer "In4.Cu")
		(net "M_D_CPU0_SB_CB<4>")
	)
	(segment
		(start 303.8348 -271.16151)
		(end 304.089562 -271.16151)
		(width 0.14478)
		(layer "In4.Cu")
		(net "M_D_CPU0_SB_CB<4>")
	)
	(segment
		(start 289.254692 -271.16151)
		(end 289.55619 -270.860012)
		(width 0.14478)
		(layer "In4.Cu")
		(net "M_D_CPU0_SB_CB<4>")
	)
	(segment
		(start 298.10456 -270.860012)
		(end 298.359322 -270.860012)
		(width 0.14478)
		(layer "In4.Cu")
		(net "M_D_CPU0_SB_CB<4>")
	)
	(segment
		(start 302.16602 -270.860012)
		(end 302.420782 -270.860012)
		(width 0.14478)
		(layer "In4.Cu")
		(net "M_D_CPU0_SB_CB<4>")
	)
	(segment
		(start 311.469532 -267.774674)
		(end 311.647586 -267.59662)
		(width 0.14478)
		(layer "In4.Cu")
		(net "M_D_CPU0_SB_CB<4>")
	)
	(segment
		(start 298.66082 -271.16151)
		(end 298.915582 -271.16151)
		(width 0.14478)
		(layer "In4.Cu")
		(net "M_D_CPU0_SB_CB<4>")
	)
	(segment
		(start 303.533302 -270.860012)
		(end 303.8348 -271.16151)
		(width 0.14478)
		(layer "In4.Cu")
		(net "M_D_CPU0_SB_CB<4>")
	)
	(segment
		(start 310.689244 -268.783562)
		(end 310.689244 -268.554962)
		(width 0.14478)
		(layer "In4.Cu")
		(net "M_D_CPU0_SB_CB<4>")
	)
	(segment
		(start 339.02523 -269.49146)
		(end 338.871052 -269.22603)
		(width 0.0889)
		(layer "In4.Cu")
		(net "M_D_CPU0_SB_CB<4>")
	)
	(segment
		(start 290.367212 -271.16151)
		(end 290.66871 -270.860012)
		(width 0.14478)
		(layer "In4.Cu")
		(net "M_D_CPU0_SB_CB<4>")
	)
	(segment
		(start 311.29351 -268.60754)
		(end 311.52211 -268.60754)
		(width 0.14478)
		(layer "In4.Cu")
		(net "M_D_CPU0_SB_CB<4>")
	)
	(segment
		(start 291.22497 -271.16151)
		(end 291.479732 -271.16151)
		(width 0.14478)
		(layer "In4.Cu")
		(net "M_D_CPU0_SB_CB<4>")
	)
	(segment
		(start 306.314602 -271.16151)
		(end 306.6161 -270.860012)
		(width 0.14478)
		(layer "In4.Cu")
		(net "M_D_CPU0_SB_CB<4>")
	)
	(segment
		(start 308.384194 -270.860012)
		(end 308.509924 -270.734282)
		(width 0.14478)
		(layer "In4.Cu")
		(net "M_D_CPU0_SB_CB<4>")
	)
	(segment
		(start 310.2991 -269.173706)
		(end 310.513222 -269.387828)
		(width 0.14478)
		(layer "In4.Cu")
		(net "M_D_CPU0_SB_CB<4>")
	)
	(segment
		(start 328.709782 -269.553436)
		(end 328.718164 -269.54861)
		(width 0.0889)
		(layer "In4.Cu")
		(net "M_D_CPU0_SB_CB<4>")
	)
	(segment
		(start 310.513222 -269.387828)
		(end 310.741822 -269.387828)
		(width 0.14478)
		(layer "In4.Cu")
		(net "M_D_CPU0_SB_CB<4>")
	)
	(segment
		(start 294.89273 -270.860012)
		(end 296.134282 -270.860012)
		(width 0.14478)
		(layer "In4.Cu")
		(net "M_D_CPU0_SB_CB<4>")
	)
	(segment
		(start 294.33647 -271.16151)
		(end 294.591232 -271.16151)
		(width 0.14478)
		(layer "In4.Cu")
		(net "M_D_CPU0_SB_CB<4>")
	)
	(segment
		(start 325.995538 -268.162532)
		(end 325.995538 -269.098522)
		(width 0.0889)
		(layer "In4.Cu")
		(net "M_D_CPU0_SB_CB<4>")
	)
	(segment
		(start 291.479732 -271.16151)
		(end 291.78123 -270.860012)
		(width 0.14478)
		(layer "In4.Cu")
		(net "M_D_CPU0_SB_CB<4>")
	)
	(segment
		(start 301.0535 -270.860012)
		(end 301.308262 -270.860012)
		(width 0.14478)
		(layer "In4.Cu")
		(net "M_D_CPU0_SB_CB<4>")
	)
	(segment
		(start 285.50743 -271.810734)
		(end 285.677356 -271.640808)
		(width 0.14478)
		(layer "In4.Cu")
		(net "M_D_CPU0_SB_CB<4>")
	)
	(segment
		(start 303.27854 -270.860012)
		(end 303.533302 -270.860012)
		(width 0.14478)
		(layer "In4.Cu")
		(net "M_D_CPU0_SB_CB<4>")
	)
	(segment
		(start 309.908956 -269.33525)
		(end 310.0705 -269.173706)
		(width 0.14478)
		(layer "In4.Cu")
		(net "M_D_CPU0_SB_CB<4>")
	)
	(segment
		(start 290.66871 -270.860012)
		(end 290.923472 -270.860012)
		(width 0.14478)
		(layer "In4.Cu")
		(net "M_D_CPU0_SB_CB<4>")
	)
	(segment
		(start 311.683654 -268.445996)
		(end 311.683654 -268.217396)
		(width 0.14478)
		(layer "In4.Cu")
		(net "M_D_CPU0_SB_CB<4>")
	)
	(segment
		(start 300.752002 -271.16151)
		(end 301.0535 -270.860012)
		(width 0.14478)
		(layer "In4.Cu")
		(net "M_D_CPU0_SB_CB<4>")
	)
	(segment
		(start 310.123078 -269.777972)
		(end 309.908956 -269.56385)
		(width 0.14478)
		(layer "In4.Cu")
		(net "M_D_CPU0_SB_CB<4>")
	)
	(segment
		(start 337.744054 -269.54861)
		(end 337.752436 -269.553436)
		(width 0.0889)
		(layer "In4.Cu")
		(net "M_D_CPU0_SB_CB<4>")
	)
	(segment
		(start 310.903366 -269.226284)
		(end 310.903366 -268.997684)
		(width 0.14478)
		(layer "In4.Cu")
		(net "M_D_CPU0_SB_CB<4>")
	)
	(segment
		(start 308.509924 -270.734282)
		(end 308.738524 -270.734282)
		(width 0.14478)
		(layer "In4.Cu")
		(net "M_D_CPU0_SB_CB<4>")
	)
	(segment
		(start 292.922452 -270.860012)
		(end 293.22395 -271.16151)
		(width 0.14478)
		(layer "In4.Cu")
		(net "M_D_CPU0_SB_CB<4>")
	)
	(segment
		(start 309.961534 -270.168116)
		(end 310.123078 -270.006572)
		(width 0.14478)
		(layer "In4.Cu")
		(net "M_D_CPU0_SB_CB<4>")
	)
	(segment
		(start 326.463406 -269.54861)
		(end 326.46366 -269.54861)
		(width 0.0889)
		(layer "In4.Cu")
		(net "M_D_CPU0_SB_CB<4>")
	)
	(segment
		(start 287.298892 -270.860012)
		(end 288.698432 -270.860012)
		(width 0.14478)
		(layer "In4.Cu")
		(net "M_D_CPU0_SB_CB<4>")
	)
	(segment
		(start 338.684108 -269.54861)
		(end 338.69249 -269.553436)
		(width 0.0889)
		(layer "In4.Cu")
		(net "M_D_CPU0_SB_CB<4>")
	)
	(segment
		(start 311.079388 -268.393418)
		(end 311.29351 -268.60754)
		(width 0.14478)
		(layer "In4.Cu")
		(net "M_D_CPU0_SB_CB<4>")
	)
	(segment
		(start 332.469744 -269.553436)
		(end 332.478126 -269.54861)
		(width 0.0889)
		(layer "In4.Cu")
		(net "M_D_CPU0_SB_CB<4>")
	)
	(segment
		(start 309.128668 -270.115538)
		(end 309.290212 -269.953994)
		(width 0.14478)
		(layer "In4.Cu")
		(net "M_D_CPU0_SB_CB<4>")
	)
	(segment
		(start 329.284076 -269.54861)
		(end 329.292458 -269.553436)
		(width 0.0889)
		(layer "In4.Cu")
		(net "M_D_CPU0_SB_CB<4>")
	)
	(segment
		(start 285.06039 -271.810734)
		(end 285.50743 -271.810734)
		(width 0.14478)
		(layer "In4.Cu")
		(net "M_D_CPU0_SB_CB<4>")
	)
	(segment
		(start 309.34279 -270.55826)
		(end 309.128668 -270.344138)
		(width 0.14478)
		(layer "In4.Cu")
		(net "M_D_CPU0_SB_CB<4>")
	)
	(segment
		(start 309.34279 -270.78686)
		(end 309.34279 -270.55826)
		(width 0.14478)
		(layer "In4.Cu")
		(net "M_D_CPU0_SB_CB<4>")
	)
	(segment
		(start 309.290212 -269.953994)
		(end 309.518812 -269.953994)
		(width 0.14478)
		(layer "In4.Cu")
		(net "M_D_CPU0_SB_CB<4>")
	)
	(segment
		(start 297.5483 -271.16151)
		(end 297.803062 -271.16151)
		(width 0.14478)
		(layer "In4.Cu")
		(net "M_D_CPU0_SB_CB<4>")
	)
	(segment
		(start 311.683654 -268.217396)
		(end 311.469532 -268.003274)
		(width 0.14478)
		(layer "In4.Cu")
		(net "M_D_CPU0_SB_CB<4>")
	)
	(segment
		(start 289.810952 -270.860012)
		(end 290.11245 -271.16151)
		(width 0.14478)
		(layer "In4.Cu")
		(net "M_D_CPU0_SB_CB<4>")
	)
	(segment
		(start 310.903366 -268.997684)
		(end 310.689244 -268.783562)
		(width 0.14478)
		(layer "In4.Cu")
		(net "M_D_CPU0_SB_CB<4>")
	)
	(segment
		(start 288.698432 -270.860012)
		(end 288.99993 -271.16151)
		(width 0.14478)
		(layer "In4.Cu")
		(net "M_D_CPU0_SB_CB<4>")
	)
	(segment
		(start 333.044038 -269.54861)
		(end 333.05242 -269.553436)
		(width 0.0889)
		(layer "In4.Cu")
		(net "M_D_CPU0_SB_CB<4>")
	)
	(segment
		(start 311.469532 -268.003274)
		(end 311.469532 -267.774674)
		(width 0.14478)
		(layer "In4.Cu")
		(net "M_D_CPU0_SB_CB<4>")
	)
	(segment
		(start 296.690542 -271.16151)
		(end 296.99204 -270.860012)
		(width 0.14478)
		(layer "In4.Cu")
		(net "M_D_CPU0_SB_CB<4>")
	)
	(segment
		(start 284.736032 -272.135092)
		(end 285.06039 -271.810734)
		(width 0.14478)
		(layer "In4.Cu")
		(net "M_D_CPU0_SB_CB<4>")
	)
	(segment
		(start 302.420782 -270.860012)
		(end 302.72228 -271.16151)
		(width 0.14478)
		(layer "In4.Cu")
		(net "M_D_CPU0_SB_CB<4>")
	)
	(segment
		(start 309.518812 -269.953994)
		(end 309.732934 -270.168116)
		(width 0.14478)
		(layer "In4.Cu")
		(net "M_D_CPU0_SB_CB<4>")
	)
	(segment
		(start 289.55619 -270.860012)
		(end 289.810952 -270.860012)
		(width 0.14478)
		(layer "In4.Cu")
		(net "M_D_CPU0_SB_CB<4>")
	)
	(segment
		(start 326.819514 -269.55877)
		(end 326.837802 -269.548356)
		(width 0.0889)
		(layer "In4.Cu")
		(net "M_D_CPU0_SB_CB<4>")
	)
	(segment
		(start 306.6161 -270.860012)
		(end 308.384194 -270.860012)
		(width 0.14478)
		(layer "In4.Cu")
		(net "M_D_CPU0_SB_CB<4>")
	)
	(segment
		(start 326.837802 -269.548356)
		(end 326.85355 -269.539212)
		(width 0.0889)
		(layer "In4.Cu")
		(net "M_D_CPU0_SB_CB<4>")
	)
	(segment
		(start 308.738524 -270.734282)
		(end 308.952646 -270.948404)
		(width 0.14478)
		(layer "In4.Cu")
		(net "M_D_CPU0_SB_CB<4>")
	)
	(segment
		(start 294.591232 -271.16151)
		(end 294.89273 -270.860012)
		(width 0.14478)
		(layer "In4.Cu")
		(net "M_D_CPU0_SB_CB<4>")
	)
	(segment
		(start 311.52211 -268.60754)
		(end 311.683654 -268.445996)
		(width 0.14478)
		(layer "In4.Cu")
		(net "M_D_CPU0_SB_CB<4>")
	)
	(segment
		(start 286.997394 -271.16151)
		(end 287.298892 -270.860012)
		(width 0.14478)
		(layer "In4.Cu")
		(net "M_D_CPU0_SB_CB<4>")
	)
	(segment
		(start 327.766426 -269.555468)
		(end 327.77811 -269.54861)
		(width 0.0889)
		(layer "In4.Cu")
		(net "M_D_CPU0_SB_CB<4>")
	)
	(segment
		(start 305.202082 -271.16151)
		(end 305.50358 -270.860012)
		(width 0.14478)
		(layer "In4.Cu")
		(net "M_D_CPU0_SB_CB<4>")
	)
	(segment
		(start 299.21708 -270.860012)
		(end 300.195742 -270.860012)
		(width 0.14478)
		(layer "In4.Cu")
		(net "M_D_CPU0_SB_CB<4>")
	)
	(segment
		(start 296.99204 -270.860012)
		(end 297.246802 -270.860012)
		(width 0.14478)
		(layer "In4.Cu")
		(net "M_D_CPU0_SB_CB<4>")
	)
	(segment
		(start 323.909944 -267.59662)
		(end 325.429626 -267.59662)
		(width 0.0889)
		(layer "In4.Cu")
		(net "M_D_CPU0_SB_CB<4>")
	)
	(segment
		(start 286.742632 -271.16151)
		(end 286.997394 -271.16151)
		(width 0.14478)
		(layer "In4.Cu")
		(net "M_D_CPU0_SB_CB<4>")
	)
	(segment
		(start 297.803062 -271.16151)
		(end 298.10456 -270.860012)
		(width 0.14478)
		(layer "In4.Cu")
		(net "M_D_CPU0_SB_CB<4>")
	)
	(segment
		(start 333.984092 -269.54861)
		(end 333.992474 -269.553436)
		(width 0.0889)
		(layer "In4.Cu")
		(net "M_D_CPU0_SB_CB<4>")
	)
	(segment
		(start 305.758342 -270.860012)
		(end 306.05984 -271.16151)
		(width 0.14478)
		(layer "In4.Cu")
		(net "M_D_CPU0_SB_CB<4>")
	)
	(segment
		(start 309.732934 -270.168116)
		(end 309.961534 -270.168116)
		(width 0.14478)
		(layer "In4.Cu")
		(net "M_D_CPU0_SB_CB<4>")
	)
	(segment
		(start 304.39106 -270.860012)
		(end 304.645822 -270.860012)
		(width 0.14478)
		(layer "In4.Cu")
		(net "M_D_CPU0_SB_CB<4>")
	)
	(segment
		(start 309.181246 -270.948404)
		(end 309.34279 -270.78686)
		(width 0.14478)
		(layer "In4.Cu")
		(net "M_D_CPU0_SB_CB<4>")
	)
	(arc
		(start 330.598018 -269.54861)
		(mid 330.880974 -269.472433)
		(end 331.16393 -269.54861)
		(width 0.0889)
		(layer "In4.Cu")
		(net "M_D_CPU0_SB_CB<4>")
	)
	(arc
		(start 329.658218 -269.54861)
		(mid 329.941174 -269.472433)
		(end 330.22413 -269.54861)
		(width 0.0889)
		(layer "In4.Cu")
		(net "M_D_CPU0_SB_CB<4>")
	)
	(arc
		(start 337.752436 -269.553436)
		(mid 337.935944 -269.59893)
		(end 338.118196 -269.54861)
		(width 0.0889)
		(layer "In4.Cu")
		(net "M_D_CPU0_SB_CB<4>")
	)
	(arc
		(start 333.992474 -269.553436)
		(mid 334.175982 -269.59893)
		(end 334.358234 -269.54861)
		(width 0.0889)
		(layer "In4.Cu")
		(net "M_D_CPU0_SB_CB<4>")
	)
	(arc
		(start 328.718164 -269.54861)
		(mid 329.00112 -269.472433)
		(end 329.284076 -269.54861)
		(width 0.0889)
		(layer "In4.Cu")
		(net "M_D_CPU0_SB_CB<4>")
	)
	(arc
		(start 326.386952 -269.489936)
		(mid 326.423279 -269.521749)
		(end 326.463406 -269.54861)
		(width 0.0889)
		(layer "In4.Cu")
		(net "M_D_CPU0_SB_CB<4>")
	)
	(arc
		(start 333.41818 -269.54861)
		(mid 333.701136 -269.472433)
		(end 333.984092 -269.54861)
		(width 0.0889)
		(layer "In4.Cu")
		(net "M_D_CPU0_SB_CB<4>")
	)
	(arc
		(start 326.85355 -269.539212)
		(mid 327.129859 -269.472236)
		(end 327.403714 -269.54861)
		(width 0.0889)
		(layer "In4.Cu")
		(net "M_D_CPU0_SB_CB<4>")
	)
	(arc
		(start 338.118196 -269.54861)
		(mid 338.401152 -269.472433)
		(end 338.684108 -269.54861)
		(width 0.0889)
		(layer "In4.Cu")
		(net "M_D_CPU0_SB_CB<4>")
	)
	(arc
		(start 327.403714 -269.54861)
		(mid 327.584172 -269.599054)
		(end 327.766426 -269.555468)
		(width 0.0889)
		(layer "In4.Cu")
		(net "M_D_CPU0_SB_CB<4>")
	)
	(arc
		(start 337.178142 -269.54861)
		(mid 337.461098 -269.472433)
		(end 337.744054 -269.54861)
		(width 0.0889)
		(layer "In4.Cu")
		(net "M_D_CPU0_SB_CB<4>")
	)
	(arc
		(start 336.804 -269.54861)
		(mid 336.986251 -269.59896)
		(end 337.16976 -269.553436)
		(width 0.0889)
		(layer "In4.Cu")
		(net "M_D_CPU0_SB_CB<4>")
	)
	(arc
		(start 327.77811 -269.54861)
		(mid 328.061066 -269.472433)
		(end 328.344022 -269.54861)
		(width 0.0889)
		(layer "In4.Cu")
		(net "M_D_CPU0_SB_CB<4>")
	)
	(arc
		(start 338.69249 -269.553436)
		(mid 338.84536 -269.598077)
		(end 339.002878 -269.574772)
		(width 0.0889)
		(layer "In4.Cu")
		(net "M_D_CPU0_SB_CB<4>")
	)
	(arc
		(start 326.46366 -269.54861)
		(mid 326.640288 -269.598843)
		(end 326.819514 -269.55877)
		(width 0.0889)
		(layer "In4.Cu")
		(net "M_D_CPU0_SB_CB<4>")
	)
	(arc
		(start 329.292458 -269.553436)
		(mid 329.475966 -269.59893)
		(end 329.658218 -269.54861)
		(width 0.0889)
		(layer "In4.Cu")
		(net "M_D_CPU0_SB_CB<4>")
	)
	(arc
		(start 333.05242 -269.553436)
		(mid 333.235928 -269.59893)
		(end 333.41818 -269.54861)
		(width 0.0889)
		(layer "In4.Cu")
		(net "M_D_CPU0_SB_CB<4>")
	)
	(arc
		(start 334.358234 -269.54861)
		(mid 334.64119 -269.472433)
		(end 334.924146 -269.54861)
		(width 0.0889)
		(layer "In4.Cu")
		(net "M_D_CPU0_SB_CB<4>")
	)
	(arc
		(start 335.298034 -269.54861)
		(mid 335.58099 -269.472433)
		(end 335.863946 -269.54861)
		(width 0.0889)
		(layer "In4.Cu")
		(net "M_D_CPU0_SB_CB<4>")
	)
	(arc
		(start 332.478126 -269.54861)
		(mid 332.761082 -269.472433)
		(end 333.044038 -269.54861)
		(width 0.0889)
		(layer "In4.Cu")
		(net "M_D_CPU0_SB_CB<4>")
	)
	(arc
		(start 331.538072 -269.54861)
		(mid 331.821028 -269.472433)
		(end 332.103984 -269.54861)
		(width 0.0889)
		(layer "In4.Cu")
		(net "M_D_CPU0_SB_CB<4>")
	)
	(arc
		(start 336.238088 -269.54861)
		(mid 336.521044 -269.472433)
		(end 336.804 -269.54861)
		(width 0.0889)
		(layer "In4.Cu")
		(net "M_D_CPU0_SB_CB<4>")
	)
	(arc
		(start 334.924146 -269.54861)
		(mid 335.11109 -269.598865)
		(end 335.298034 -269.54861)
		(width 0.0889)
		(layer "In4.Cu")
		(net "M_D_CPU0_SB_CB<4>")
	)
	(arc
		(start 335.863946 -269.54861)
		(mid 336.046197 -269.59896)
		(end 336.229706 -269.553436)
		(width 0.0889)
		(layer "In4.Cu")
		(net "M_D_CPU0_SB_CB<4>")
	)
	(arc
		(start 331.16393 -269.54861)
		(mid 331.346181 -269.59896)
		(end 331.52969 -269.553436)
		(width 0.0889)
		(layer "In4.Cu")
		(net "M_D_CPU0_SB_CB<4>")
	)
	(arc
		(start 330.22413 -269.54861)
		(mid 330.411074 -269.598865)
		(end 330.598018 -269.54861)
		(width 0.0889)
		(layer "In4.Cu")
		(net "M_D_CPU0_SB_CB<4>")
	)
	(arc
		(start 332.103984 -269.54861)
		(mid 332.286235 -269.59896)
		(end 332.469744 -269.553436)
		(width 0.0889)
		(layer "In4.Cu")
		(net "M_D_CPU0_SB_CB<4>")
	)
	(arc
		(start 328.344022 -269.54861)
		(mid 328.526273 -269.59896)
		(end 328.709782 -269.553436)
		(width 0.0889)
		(layer "In4.Cu")
		(net "M_D_CPU0_SB_CB<4>")
	)
	(segment
		(start 341.218012 -273.820128)
		(end 340.75116 -274.086066)
		(width 0.10668)
		(layer "F.Cu")
		(net "M_D_CPU0_SB_CB<3>")
	)
	(segment
		(start 337.744054 -273.763486)
		(end 337.752436 -273.75866)
		(width 0.0889)
		(layer "In4.Cu")
		(net "M_D_CPU0_SB_CB<3>")
	)
	(segment
		(start 290.303966 -281.060144)
		(end 291.152326 -280.211784)
		(width 0.14478)
		(layer "In4.Cu")
		(net "M_D_CPU0_SB_CB<3>")
	)
	(segment
		(start 340.596982 -273.820636)
		(end 340.75116 -274.086066)
		(width 0.0889)
		(layer "In4.Cu")
		(net "M_D_CPU0_SB_CB<3>")
	)
	(segment
		(start 328.709782 -273.75866)
		(end 328.718164 -273.763486)
		(width 0.0889)
		(layer "In4.Cu")
		(net "M_D_CPU0_SB_CB<3>")
	)
	(segment
		(start 281.06116 -281.060144)
		(end 290.303966 -281.060144)
		(width 0.14478)
		(layer "In4.Cu")
		(net "M_D_CPU0_SB_CB<3>")
	)
	(segment
		(start 326.837802 -273.76374)
		(end 326.84339 -273.767042)
		(width 0.0889)
		(layer "In4.Cu")
		(net "M_D_CPU0_SB_CB<3>")
	)
	(segment
		(start 301.222664 -280.664666)
		(end 305.26228 -280.664666)
		(width 0.14478)
		(layer "In4.Cu")
		(net "M_D_CPU0_SB_CB<3>")
	)
	(segment
		(start 297.48353 -281.060144)
		(end 298.333668 -280.210006)
		(width 0.14478)
		(layer "In4.Cu")
		(net "M_D_CPU0_SB_CB<3>")
	)
	(segment
		(start 329.284076 -273.763486)
		(end 329.292458 -273.75866)
		(width 0.0889)
		(layer "In4.Cu")
		(net "M_D_CPU0_SB_CB<3>")
	)
	(segment
		(start 307.48986 -280.210006)
		(end 315.035946 -272.66392)
		(width 0.14478)
		(layer "In4.Cu")
		(net "M_D_CPU0_SB_CB<3>")
	)
	(segment
		(start 305.71694 -280.210006)
		(end 307.48986 -280.210006)
		(width 0.14478)
		(layer "In4.Cu")
		(net "M_D_CPU0_SB_CB<3>")
	)
	(segment
		(start 298.333668 -280.210006)
		(end 300.768004 -280.210006)
		(width 0.14478)
		(layer "In4.Cu")
		(net "M_D_CPU0_SB_CB<3>")
	)
	(segment
		(start 326.328786 -273.71294)
		(end 326.651112 -273.71294)
		(width 0.0889)
		(layer "In4.Cu")
		(net "M_D_CPU0_SB_CB<3>")
	)
	(segment
		(start 293.098982 -280.211784)
		(end 293.947342 -281.060144)
		(width 0.14478)
		(layer "In4.Cu")
		(net "M_D_CPU0_SB_CB<3>")
	)
	(segment
		(start 325.147178 -272.531332)
		(end 326.328786 -273.71294)
		(width 0.0889)
		(layer "In4.Cu")
		(net "M_D_CPU0_SB_CB<3>")
	)
	(segment
		(start 332.469744 -273.75866)
		(end 332.478126 -273.763486)
		(width 0.0889)
		(layer "In4.Cu")
		(net "M_D_CPU0_SB_CB<3>")
	)
	(segment
		(start 333.984092 -273.763486)
		(end 333.992474 -273.75866)
		(width 0.0889)
		(layer "In4.Cu")
		(net "M_D_CPU0_SB_CB<3>")
	)
	(segment
		(start 333.044038 -273.763486)
		(end 333.05242 -273.75866)
		(width 0.0889)
		(layer "In4.Cu")
		(net "M_D_CPU0_SB_CB<3>")
	)
	(segment
		(start 293.947342 -281.060144)
		(end 297.48353 -281.060144)
		(width 0.14478)
		(layer "In4.Cu")
		(net "M_D_CPU0_SB_CB<3>")
	)
	(segment
		(start 336.229706 -273.75866)
		(end 336.238088 -273.763486)
		(width 0.0889)
		(layer "In4.Cu")
		(net "M_D_CPU0_SB_CB<3>")
	)
	(segment
		(start 331.52969 -273.75866)
		(end 331.538072 -273.763486)
		(width 0.0889)
		(layer "In4.Cu")
		(net "M_D_CPU0_SB_CB<3>")
	)
	(segment
		(start 300.768004 -280.210006)
		(end 301.222664 -280.664666)
		(width 0.14478)
		(layer "In4.Cu")
		(net "M_D_CPU0_SB_CB<3>")
	)
	(segment
		(start 340.500716 -273.795236)
		(end 340.596982 -273.820636)
		(width 0.0889)
		(layer "In4.Cu")
		(net "M_D_CPU0_SB_CB<3>")
	)
	(segment
		(start 324.672198 -272.531332)
		(end 325.147178 -272.531332)
		(width 0.0889)
		(layer "In4.Cu")
		(net "M_D_CPU0_SB_CB<3>")
	)
	(segment
		(start 328.32929 -273.772122)
		(end 328.344022 -273.763486)
		(width 0.0889)
		(layer "In4.Cu")
		(net "M_D_CPU0_SB_CB<3>")
	)
	(segment
		(start 327.403206 -273.763486)
		(end 327.41489 -273.756628)
		(width 0.0889)
		(layer "In4.Cu")
		(net "M_D_CPU0_SB_CB<3>")
	)
	(segment
		(start 337.16976 -273.75866)
		(end 337.178142 -273.763486)
		(width 0.0889)
		(layer "In4.Cu")
		(net "M_D_CPU0_SB_CB<3>")
	)
	(segment
		(start 305.26228 -280.664666)
		(end 305.71694 -280.210006)
		(width 0.14478)
		(layer "In4.Cu")
		(net "M_D_CPU0_SB_CB<3>")
	)
	(segment
		(start 291.152326 -280.211784)
		(end 293.098982 -280.211784)
		(width 0.14478)
		(layer "In4.Cu")
		(net "M_D_CPU0_SB_CB<3>")
	)
	(segment
		(start 324.53961 -272.66392)
		(end 324.672198 -272.531332)
		(width 0.0889)
		(layer "In4.Cu")
		(net "M_D_CPU0_SB_CB<3>")
	)
	(segment
		(start 338.684108 -273.763486)
		(end 338.69249 -273.75866)
		(width 0.0889)
		(layer "In4.Cu")
		(net "M_D_CPU0_SB_CB<3>")
	)
	(segment
		(start 315.035946 -272.66392)
		(end 324.331584 -272.66392)
		(width 0.14478)
		(layer "In4.Cu")
		(net "M_D_CPU0_SB_CB<3>")
	)
	(segment
		(start 280.635964 -280.634948)
		(end 281.06116 -281.060144)
		(width 0.14478)
		(layer "In4.Cu")
		(net "M_D_CPU0_SB_CB<3>")
	)
	(segment
		(start 324.331584 -272.66392)
		(end 324.53961 -272.66392)
		(width 0.0889)
		(layer "In4.Cu")
		(net "M_D_CPU0_SB_CB<3>")
	)
	(arc
		(start 331.16393 -273.763486)
		(mid 331.346181 -273.713136)
		(end 331.52969 -273.75866)
		(width 0.0889)
		(layer "In4.Cu")
		(net "M_D_CPU0_SB_CB<3>")
	)
	(arc
		(start 326.84339 -273.767042)
		(mid 327.123779 -273.839711)
		(end 327.403206 -273.763486)
		(width 0.0889)
		(layer "In4.Cu")
		(net "M_D_CPU0_SB_CB<3>")
	)
	(arc
		(start 326.651112 -273.71294)
		(mid 326.747803 -273.726036)
		(end 326.837802 -273.76374)
		(width 0.0889)
		(layer "In4.Cu")
		(net "M_D_CPU0_SB_CB<3>")
	)
	(arc
		(start 339.05825 -273.763486)
		(mid 339.341206 -273.839663)
		(end 339.624162 -273.763486)
		(width 0.0889)
		(layer "In4.Cu")
		(net "M_D_CPU0_SB_CB<3>")
	)
	(arc
		(start 330.598018 -273.763486)
		(mid 330.880974 -273.839663)
		(end 331.16393 -273.763486)
		(width 0.0889)
		(layer "In4.Cu")
		(net "M_D_CPU0_SB_CB<3>")
	)
	(arc
		(start 332.103984 -273.763486)
		(mid 332.286235 -273.713136)
		(end 332.469744 -273.75866)
		(width 0.0889)
		(layer "In4.Cu")
		(net "M_D_CPU0_SB_CB<3>")
	)
	(arc
		(start 339.99805 -273.763486)
		(mid 340.245646 -273.838664)
		(end 340.500716 -273.795236)
		(width 0.0889)
		(layer "In4.Cu")
		(net "M_D_CPU0_SB_CB<3>")
	)
	(arc
		(start 338.118196 -273.763486)
		(mid 338.401152 -273.839663)
		(end 338.684108 -273.763486)
		(width 0.0889)
		(layer "In4.Cu")
		(net "M_D_CPU0_SB_CB<3>")
	)
	(arc
		(start 337.178142 -273.763486)
		(mid 337.461098 -273.839663)
		(end 337.744054 -273.763486)
		(width 0.0889)
		(layer "In4.Cu")
		(net "M_D_CPU0_SB_CB<3>")
	)
	(arc
		(start 336.804 -273.763486)
		(mid 336.986251 -273.713136)
		(end 337.16976 -273.75866)
		(width 0.0889)
		(layer "In4.Cu")
		(net "M_D_CPU0_SB_CB<3>")
	)
	(arc
		(start 337.752436 -273.75866)
		(mid 337.935944 -273.713166)
		(end 338.118196 -273.763486)
		(width 0.0889)
		(layer "In4.Cu")
		(net "M_D_CPU0_SB_CB<3>")
	)
	(arc
		(start 329.292458 -273.75866)
		(mid 329.475966 -273.713166)
		(end 329.658218 -273.763486)
		(width 0.0889)
		(layer "In4.Cu")
		(net "M_D_CPU0_SB_CB<3>")
	)
	(arc
		(start 333.992474 -273.75866)
		(mid 334.175982 -273.713166)
		(end 334.358234 -273.763486)
		(width 0.0889)
		(layer "In4.Cu")
		(net "M_D_CPU0_SB_CB<3>")
	)
	(arc
		(start 333.05242 -273.75866)
		(mid 333.235928 -273.713166)
		(end 333.41818 -273.763486)
		(width 0.0889)
		(layer "In4.Cu")
		(net "M_D_CPU0_SB_CB<3>")
	)
	(arc
		(start 335.863946 -273.763486)
		(mid 336.046197 -273.713136)
		(end 336.229706 -273.75866)
		(width 0.0889)
		(layer "In4.Cu")
		(net "M_D_CPU0_SB_CB<3>")
	)
	(arc
		(start 335.298034 -273.763486)
		(mid 335.58099 -273.839663)
		(end 335.863946 -273.763486)
		(width 0.0889)
		(layer "In4.Cu")
		(net "M_D_CPU0_SB_CB<3>")
	)
	(arc
		(start 328.344022 -273.763486)
		(mid 328.526273 -273.713136)
		(end 328.709782 -273.75866)
		(width 0.0889)
		(layer "In4.Cu")
		(net "M_D_CPU0_SB_CB<3>")
	)
	(arc
		(start 334.924146 -273.763486)
		(mid 335.11109 -273.713231)
		(end 335.298034 -273.763486)
		(width 0.0889)
		(layer "In4.Cu")
		(net "M_D_CPU0_SB_CB<3>")
	)
	(arc
		(start 329.658218 -273.763486)
		(mid 329.941174 -273.839663)
		(end 330.22413 -273.763486)
		(width 0.0889)
		(layer "In4.Cu")
		(net "M_D_CPU0_SB_CB<3>")
	)
	(arc
		(start 331.538072 -273.763486)
		(mid 331.821028 -273.839663)
		(end 332.103984 -273.763486)
		(width 0.0889)
		(layer "In4.Cu")
		(net "M_D_CPU0_SB_CB<3>")
	)
	(arc
		(start 332.478126 -273.763486)
		(mid 332.761082 -273.839663)
		(end 333.044038 -273.763486)
		(width 0.0889)
		(layer "In4.Cu")
		(net "M_D_CPU0_SB_CB<3>")
	)
	(arc
		(start 327.777602 -273.763486)
		(mid 328.052308 -273.83985)
		(end 328.32929 -273.772122)
		(width 0.0889)
		(layer "In4.Cu")
		(net "M_D_CPU0_SB_CB<3>")
	)
	(arc
		(start 336.238088 -273.763486)
		(mid 336.521044 -273.839663)
		(end 336.804 -273.763486)
		(width 0.0889)
		(layer "In4.Cu")
		(net "M_D_CPU0_SB_CB<3>")
	)
	(arc
		(start 333.41818 -273.763486)
		(mid 333.701136 -273.839663)
		(end 333.984092 -273.763486)
		(width 0.0889)
		(layer "In4.Cu")
		(net "M_D_CPU0_SB_CB<3>")
	)
	(arc
		(start 334.358234 -273.763486)
		(mid 334.64119 -273.839663)
		(end 334.924146 -273.763486)
		(width 0.0889)
		(layer "In4.Cu")
		(net "M_D_CPU0_SB_CB<3>")
	)
	(arc
		(start 339.624162 -273.763486)
		(mid 339.811106 -273.713231)
		(end 339.99805 -273.763486)
		(width 0.0889)
		(layer "In4.Cu")
		(net "M_D_CPU0_SB_CB<3>")
	)
	(arc
		(start 328.718164 -273.763486)
		(mid 329.00112 -273.839663)
		(end 329.284076 -273.763486)
		(width 0.0889)
		(layer "In4.Cu")
		(net "M_D_CPU0_SB_CB<3>")
	)
	(arc
		(start 327.41489 -273.756628)
		(mid 327.597145 -273.712975)
		(end 327.777602 -273.763486)
		(width 0.0889)
		(layer "In4.Cu")
		(net "M_D_CPU0_SB_CB<3>")
	)
	(arc
		(start 338.69249 -273.75866)
		(mid 338.875998 -273.713166)
		(end 339.05825 -273.763486)
		(width 0.0889)
		(layer "In4.Cu")
		(net "M_D_CPU0_SB_CB<3>")
	)
	(arc
		(start 330.22413 -273.763486)
		(mid 330.411074 -273.713231)
		(end 330.598018 -273.763486)
		(width 0.0889)
		(layer "In4.Cu")
		(net "M_D_CPU0_SB_CB<3>")
	)
	(segment
		(start 339.808058 -273.010122)
		(end 339.341206 -273.27606)
		(width 0.10668)
		(layer "F.Cu")
		(net "M_D_CPU0_SB_CB<2>")
	)
	(segment
		(start 282.23845 -278.791924)
		(end 282.23845 -279.197308)
		(width 0.14478)
		(layer "In4.Cu")
		(net "M_D_CPU0_SB_CB<2>")
	)
	(segment
		(start 306.130452 -278.509984)
		(end 307.91785 -278.509984)
		(width 0.14478)
		(layer "In4.Cu")
		(net "M_D_CPU0_SB_CB<2>")
	)
	(segment
		(start 281.519376 -279.360122)
		(end 281.68219 -279.197308)
		(width 0.14478)
		(layer "In4.Cu")
		(net "M_D_CPU0_SB_CB<2>")
	)
	(segment
		(start 324.441566 -271.7546)
		(end 324.707758 -272.020792)
		(width 0.0889)
		(layer "In4.Cu")
		(net "M_D_CPU0_SB_CB<2>")
	)
	(segment
		(start 280.635964 -278.93518)
		(end 281.060906 -279.360122)
		(width 0.14478)
		(layer "In4.Cu")
		(net "M_D_CPU0_SB_CB<2>")
	)
	(segment
		(start 314.673234 -271.7546)
		(end 323.901054 -271.7546)
		(width 0.14478)
		(layer "In4.Cu")
		(net "M_D_CPU0_SB_CB<2>")
	)
	(segment
		(start 281.845004 -278.62911)
		(end 282.075636 -278.62911)
		(width 0.14478)
		(layer "In4.Cu")
		(net "M_D_CPU0_SB_CB<2>")
	)
	(segment
		(start 328.239882 -272.948654)
		(end 328.248264 -272.95348)
		(width 0.0889)
		(layer "In4.Cu")
		(net "M_D_CPU0_SB_CB<2>")
	)
	(segment
		(start 331.634084 -272.95348)
		(end 331.642466 -272.948654)
		(width 0.0889)
		(layer "In4.Cu")
		(net "M_D_CPU0_SB_CB<2>")
	)
	(segment
		(start 339.187028 -273.01063)
		(end 339.341206 -273.27606)
		(width 0.0889)
		(layer "In4.Cu")
		(net "M_D_CPU0_SB_CB<2>")
	)
	(segment
		(start 325.40829 -272.020792)
		(end 326.252332 -272.864834)
		(width 0.0889)
		(layer "In4.Cu")
		(net "M_D_CPU0_SB_CB<2>")
	)
	(segment
		(start 293.149528 -278.509984)
		(end 293.999666 -279.360122)
		(width 0.14478)
		(layer "In4.Cu")
		(net "M_D_CPU0_SB_CB<2>")
	)
	(segment
		(start 281.060906 -279.360122)
		(end 281.519376 -279.360122)
		(width 0.14478)
		(layer "In4.Cu")
		(net "M_D_CPU0_SB_CB<2>")
	)
	(segment
		(start 294.404796 -279.360122)
		(end 294.703246 -279.658572)
		(width 0.14478)
		(layer "In4.Cu")
		(net "M_D_CPU0_SB_CB<2>")
	)
	(segment
		(start 324.707758 -272.020792)
		(end 325.40829 -272.020792)
		(width 0.0889)
		(layer "In4.Cu")
		(net "M_D_CPU0_SB_CB<2>")
	)
	(segment
		(start 338.579714 -272.948654)
		(end 338.588096 -272.95348)
		(width 0.0889)
		(layer "In4.Cu")
		(net "M_D_CPU0_SB_CB<2>")
	)
	(segment
		(start 300.769528 -278.509984)
		(end 301.549054 -279.28951)
		(width 0.14478)
		(layer "In4.Cu")
		(net "M_D_CPU0_SB_CB<2>")
	)
	(segment
		(start 335.394046 -272.95348)
		(end 335.402428 -272.948654)
		(width 0.0889)
		(layer "In4.Cu")
		(net "M_D_CPU0_SB_CB<2>")
	)
	(segment
		(start 333.879698 -272.948654)
		(end 333.88808 -272.95348)
		(width 0.0889)
		(layer "In4.Cu")
		(net "M_D_CPU0_SB_CB<2>")
	)
	(segment
		(start 298.74718 -278.509984)
		(end 300.769528 -278.509984)
		(width 0.14478)
		(layer "In4.Cu")
		(net "M_D_CPU0_SB_CB<2>")
	)
	(segment
		(start 301.549054 -279.28951)
		(end 305.350926 -279.28951)
		(width 0.14478)
		(layer "In4.Cu")
		(net "M_D_CPU0_SB_CB<2>")
	)
	(segment
		(start 305.350926 -279.28951)
		(end 306.130452 -278.509984)
		(width 0.14478)
		(layer "In4.Cu")
		(net "M_D_CPU0_SB_CB<2>")
	)
	(segment
		(start 282.401264 -279.360122)
		(end 290.607242 -279.360122)
		(width 0.14478)
		(layer "In4.Cu")
		(net "M_D_CPU0_SB_CB<2>")
	)
	(segment
		(start 293.999666 -279.360122)
		(end 294.404796 -279.360122)
		(width 0.14478)
		(layer "In4.Cu")
		(net "M_D_CPU0_SB_CB<2>")
	)
	(segment
		(start 282.23845 -279.197308)
		(end 282.401264 -279.360122)
		(width 0.14478)
		(layer "In4.Cu")
		(net "M_D_CPU0_SB_CB<2>")
	)
	(segment
		(start 307.91785 -278.509984)
		(end 314.673234 -271.7546)
		(width 0.14478)
		(layer "In4.Cu")
		(net "M_D_CPU0_SB_CB<2>")
	)
	(segment
		(start 282.075636 -278.62911)
		(end 282.23845 -278.791924)
		(width 0.14478)
		(layer "In4.Cu")
		(net "M_D_CPU0_SB_CB<2>")
	)
	(segment
		(start 336.3341 -272.95348)
		(end 336.342482 -272.948654)
		(width 0.0889)
		(layer "In4.Cu")
		(net "M_D_CPU0_SB_CB<2>")
	)
	(segment
		(start 334.819752 -272.948654)
		(end 334.828134 -272.95348)
		(width 0.0889)
		(layer "In4.Cu")
		(net "M_D_CPU0_SB_CB<2>")
	)
	(segment
		(start 290.607242 -279.360122)
		(end 291.45738 -278.509984)
		(width 0.14478)
		(layer "In4.Cu")
		(net "M_D_CPU0_SB_CB<2>")
	)
	(segment
		(start 291.45738 -278.509984)
		(end 293.149528 -278.509984)
		(width 0.14478)
		(layer "In4.Cu")
		(net "M_D_CPU0_SB_CB<2>")
	)
	(segment
		(start 295.25468 -279.360122)
		(end 297.897042 -279.360122)
		(width 0.14478)
		(layer "In4.Cu")
		(net "M_D_CPU0_SB_CB<2>")
	)
	(segment
		(start 281.68219 -278.791924)
		(end 281.845004 -278.62911)
		(width 0.14478)
		(layer "In4.Cu")
		(net "M_D_CPU0_SB_CB<2>")
	)
	(segment
		(start 327.307448 -272.95348)
		(end 327.317862 -272.959576)
		(width 0.0889)
		(layer "In4.Cu")
		(net "M_D_CPU0_SB_CB<2>")
	)
	(segment
		(start 330.119736 -272.948654)
		(end 330.128118 -272.95348)
		(width 0.0889)
		(layer "In4.Cu")
		(net "M_D_CPU0_SB_CB<2>")
	)
	(segment
		(start 297.897042 -279.360122)
		(end 298.74718 -278.509984)
		(width 0.14478)
		(layer "In4.Cu")
		(net "M_D_CPU0_SB_CB<2>")
	)
	(segment
		(start 330.69403 -272.95348)
		(end 330.702412 -272.948654)
		(width 0.0889)
		(layer "In4.Cu")
		(net "M_D_CPU0_SB_CB<2>")
	)
	(segment
		(start 326.93356 -272.953734)
		(end 326.949816 -272.944336)
		(width 0.0889)
		(layer "In4.Cu")
		(net "M_D_CPU0_SB_CB<2>")
	)
	(segment
		(start 326.917812 -272.962878)
		(end 326.93356 -272.953734)
		(width 0.0889)
		(layer "In4.Cu")
		(net "M_D_CPU0_SB_CB<2>")
	)
	(segment
		(start 294.703246 -279.658572)
		(end 294.95623 -279.658572)
		(width 0.14478)
		(layer "In4.Cu")
		(net "M_D_CPU0_SB_CB<2>")
	)
	(segment
		(start 294.95623 -279.658572)
		(end 295.25468 -279.360122)
		(width 0.14478)
		(layer "In4.Cu")
		(net "M_D_CPU0_SB_CB<2>")
	)
	(segment
		(start 323.901054 -271.7546)
		(end 324.441566 -271.7546)
		(width 0.0889)
		(layer "In4.Cu")
		(net "M_D_CPU0_SB_CB<2>")
	)
	(segment
		(start 339.090762 -272.98523)
		(end 339.187028 -273.01063)
		(width 0.0889)
		(layer "In4.Cu")
		(net "M_D_CPU0_SB_CB<2>")
	)
	(segment
		(start 281.68219 -279.197308)
		(end 281.68219 -278.791924)
		(width 0.14478)
		(layer "In4.Cu")
		(net "M_D_CPU0_SB_CB<2>")
	)
	(arc
		(start 337.648042 -272.95348)
		(mid 337.930998 -273.029657)
		(end 338.213954 -272.95348)
		(width 0.0889)
		(layer "In4.Cu")
		(net "M_D_CPU0_SB_CB<2>")
	)
	(arc
		(start 330.128118 -272.95348)
		(mid 330.411074 -273.029657)
		(end 330.69403 -272.95348)
		(width 0.0889)
		(layer "In4.Cu")
		(net "M_D_CPU0_SB_CB<2>")
	)
	(arc
		(start 337.274154 -272.95348)
		(mid 337.461098 -272.903225)
		(end 337.648042 -272.95348)
		(width 0.0889)
		(layer "In4.Cu")
		(net "M_D_CPU0_SB_CB<2>")
	)
	(arc
		(start 326.252332 -272.864834)
		(mid 326.307117 -272.912894)
		(end 326.367648 -272.95348)
		(width 0.0889)
		(layer "In4.Cu")
		(net "M_D_CPU0_SB_CB<2>")
	)
	(arc
		(start 332.948026 -272.95348)
		(mid 333.230982 -273.029657)
		(end 333.513938 -272.95348)
		(width 0.0889)
		(layer "In4.Cu")
		(net "M_D_CPU0_SB_CB<2>")
	)
	(arc
		(start 336.708242 -272.95348)
		(mid 336.991198 -273.029657)
		(end 337.274154 -272.95348)
		(width 0.0889)
		(layer "In4.Cu")
		(net "M_D_CPU0_SB_CB<2>")
	)
	(arc
		(start 326.949816 -272.944336)
		(mid 327.129798 -272.903236)
		(end 327.307448 -272.95348)
		(width 0.0889)
		(layer "In4.Cu")
		(net "M_D_CPU0_SB_CB<2>")
	)
	(arc
		(start 327.317862 -272.959576)
		(mid 327.596548 -273.029796)
		(end 327.873614 -272.95348)
		(width 0.0889)
		(layer "In4.Cu")
		(net "M_D_CPU0_SB_CB<2>")
	)
	(arc
		(start 338.588096 -272.95348)
		(mid 338.835692 -273.028658)
		(end 339.090762 -272.98523)
		(width 0.0889)
		(layer "In4.Cu")
		(net "M_D_CPU0_SB_CB<2>")
	)
	(arc
		(start 335.402428 -272.948654)
		(mid 335.585936 -272.90316)
		(end 335.768188 -272.95348)
		(width 0.0889)
		(layer "In4.Cu")
		(net "M_D_CPU0_SB_CB<2>")
	)
	(arc
		(start 329.188064 -272.95348)
		(mid 329.47102 -273.029657)
		(end 329.753976 -272.95348)
		(width 0.0889)
		(layer "In4.Cu")
		(net "M_D_CPU0_SB_CB<2>")
	)
	(arc
		(start 326.367648 -272.95348)
		(mid 326.641503 -273.02983)
		(end 326.917812 -272.962878)
		(width 0.0889)
		(layer "In4.Cu")
		(net "M_D_CPU0_SB_CB<2>")
	)
	(arc
		(start 333.88808 -272.95348)
		(mid 334.171036 -273.029657)
		(end 334.453992 -272.95348)
		(width 0.0889)
		(layer "In4.Cu")
		(net "M_D_CPU0_SB_CB<2>")
	)
	(arc
		(start 330.702412 -272.948654)
		(mid 330.88592 -272.90316)
		(end 331.068172 -272.95348)
		(width 0.0889)
		(layer "In4.Cu")
		(net "M_D_CPU0_SB_CB<2>")
	)
	(arc
		(start 334.453992 -272.95348)
		(mid 334.636243 -272.90313)
		(end 334.819752 -272.948654)
		(width 0.0889)
		(layer "In4.Cu")
		(net "M_D_CPU0_SB_CB<2>")
	)
	(arc
		(start 331.642466 -272.948654)
		(mid 331.825974 -272.90316)
		(end 332.008226 -272.95348)
		(width 0.0889)
		(layer "In4.Cu")
		(net "M_D_CPU0_SB_CB<2>")
	)
	(arc
		(start 333.513938 -272.95348)
		(mid 333.696189 -272.90313)
		(end 333.879698 -272.948654)
		(width 0.0889)
		(layer "In4.Cu")
		(net "M_D_CPU0_SB_CB<2>")
	)
	(arc
		(start 338.213954 -272.95348)
		(mid 338.396205 -272.90313)
		(end 338.579714 -272.948654)
		(width 0.0889)
		(layer "In4.Cu")
		(net "M_D_CPU0_SB_CB<2>")
	)
	(arc
		(start 335.768188 -272.95348)
		(mid 336.051144 -273.029657)
		(end 336.3341 -272.95348)
		(width 0.0889)
		(layer "In4.Cu")
		(net "M_D_CPU0_SB_CB<2>")
	)
	(arc
		(start 328.248264 -272.95348)
		(mid 328.53122 -273.029657)
		(end 328.814176 -272.95348)
		(width 0.0889)
		(layer "In4.Cu")
		(net "M_D_CPU0_SB_CB<2>")
	)
	(arc
		(start 334.828134 -272.95348)
		(mid 335.11109 -273.029657)
		(end 335.394046 -272.95348)
		(width 0.0889)
		(layer "In4.Cu")
		(net "M_D_CPU0_SB_CB<2>")
	)
	(arc
		(start 327.873614 -272.95348)
		(mid 328.056119 -272.903003)
		(end 328.239882 -272.948654)
		(width 0.0889)
		(layer "In4.Cu")
		(net "M_D_CPU0_SB_CB<2>")
	)
	(arc
		(start 328.814176 -272.95348)
		(mid 329.00112 -272.903225)
		(end 329.188064 -272.95348)
		(width 0.0889)
		(layer "In4.Cu")
		(net "M_D_CPU0_SB_CB<2>")
	)
	(arc
		(start 329.753976 -272.95348)
		(mid 329.936227 -272.90313)
		(end 330.119736 -272.948654)
		(width 0.0889)
		(layer "In4.Cu")
		(net "M_D_CPU0_SB_CB<2>")
	)
	(arc
		(start 332.574138 -272.95348)
		(mid 332.761082 -272.903225)
		(end 332.948026 -272.95348)
		(width 0.0889)
		(layer "In4.Cu")
		(net "M_D_CPU0_SB_CB<2>")
	)
	(arc
		(start 332.008226 -272.95348)
		(mid 332.291182 -273.029657)
		(end 332.574138 -272.95348)
		(width 0.0889)
		(layer "In4.Cu")
		(net "M_D_CPU0_SB_CB<2>")
	)
	(arc
		(start 336.342482 -272.948654)
		(mid 336.52599 -272.90316)
		(end 336.708242 -272.95348)
		(width 0.0889)
		(layer "In4.Cu")
		(net "M_D_CPU0_SB_CB<2>")
	)
	(arc
		(start 331.068172 -272.95348)
		(mid 331.351128 -273.029657)
		(end 331.634084 -272.95348)
		(width 0.0889)
		(layer "In4.Cu")
		(net "M_D_CPU0_SB_CB<2>")
	)
	(segment
		(start 340.747858 -273.010122)
		(end 340.281006 -273.27606)
		(width 0.10668)
		(layer "F.Cu")
		(net "M_D_CPU0_SB_CB<1>")
	)
	(segment
		(start 301.70755 -280.210006)
		(end 301.927768 -280.210006)
		(width 0.14478)
		(layer "In4.Cu")
		(net "M_D_CPU0_SB_CB<1>")
	)
	(segment
		(start 330.119736 -273.603466)
		(end 330.128118 -273.59864)
		(width 0.0889)
		(layer "In4.Cu")
		(net "M_D_CPU0_SB_CB<1>")
	)
	(segment
		(start 327.307194 -273.59864)
		(end 327.321926 -273.590004)
		(width 0.0889)
		(layer "In4.Cu")
		(net "M_D_CPU0_SB_CB<1>")
	)
	(segment
		(start 336.3341 -273.59864)
		(end 336.342482 -273.603466)
		(width 0.0889)
		(layer "In4.Cu")
		(net "M_D_CPU0_SB_CB<1>")
	)
	(segment
		(start 293.96055 -280.210006)
		(end 296.444924 -280.210006)
		(width 0.14478)
		(layer "In4.Cu")
		(net "M_D_CPU0_SB_CB<1>")
	)
	(segment
		(start 289.086036 -280.58491)
		(end 289.24885 -280.422096)
		(width 0.14478)
		(layer "In4.Cu")
		(net "M_D_CPU0_SB_CB<1>")
	)
	(segment
		(start 305.073558 -280.210006)
		(end 305.923696 -279.359868)
		(width 0.14478)
		(layer "In4.Cu")
		(net "M_D_CPU0_SB_CB<1>")
	)
	(segment
		(start 338.579714 -273.603466)
		(end 338.588096 -273.59864)
		(width 0.0889)
		(layer "In4.Cu")
		(net "M_D_CPU0_SB_CB<1>")
	)
	(segment
		(start 298.540424 -279.359868)
		(end 300.857412 -279.359868)
		(width 0.14478)
		(layer "In4.Cu")
		(net "M_D_CPU0_SB_CB<1>")
	)
	(segment
		(start 287.810194 -280.210006)
		(end 288.4805 -280.210006)
		(width 0.14478)
		(layer "In4.Cu")
		(net "M_D_CPU0_SB_CB<1>")
	)
	(segment
		(start 285.537148 -280.58618)
		(end 285.76778 -280.58618)
		(width 0.14478)
		(layer "In4.Cu")
		(net "M_D_CPU0_SB_CB<1>")
	)
	(segment
		(start 285.930594 -280.423366)
		(end 285.930594 -279.999186)
		(width 0.14478)
		(layer "In4.Cu")
		(net "M_D_CPU0_SB_CB<1>")
	)
	(segment
		(start 306.534566 -279.74671)
		(end 306.765198 -279.74671)
		(width 0.14478)
		(layer "In4.Cu")
		(net "M_D_CPU0_SB_CB<1>")
	)
	(segment
		(start 302.230282 -279.907492)
		(end 302.479202 -279.907492)
		(width 0.14478)
		(layer "In4.Cu")
		(net "M_D_CPU0_SB_CB<1>")
	)
	(segment
		(start 286.486854 -280.423366)
		(end 286.649668 -280.58618)
		(width 0.14478)
		(layer "In4.Cu")
		(net "M_D_CPU0_SB_CB<1>")
	)
	(segment
		(start 302.479202 -279.907492)
		(end 302.781716 -280.210006)
		(width 0.14478)
		(layer "In4.Cu")
		(net "M_D_CPU0_SB_CB<1>")
	)
	(segment
		(start 287.043114 -279.999186)
		(end 287.205928 -279.836372)
		(width 0.14478)
		(layer "In4.Cu")
		(net "M_D_CPU0_SB_CB<1>")
	)
	(segment
		(start 290.493958 -280.210006)
		(end 291.342318 -279.361646)
		(width 0.14478)
		(layer "In4.Cu")
		(net "M_D_CPU0_SB_CB<1>")
	)
	(segment
		(start 300.857412 -279.359868)
		(end 301.70755 -280.210006)
		(width 0.14478)
		(layer "In4.Cu")
		(net "M_D_CPU0_SB_CB<1>")
	)
	(segment
		(start 286.8803 -280.58618)
		(end 287.043114 -280.423366)
		(width 0.14478)
		(layer "In4.Cu")
		(net "M_D_CPU0_SB_CB<1>")
	)
	(segment
		(start 289.642296 -279.835102)
		(end 290.0172 -280.210006)
		(width 0.14478)
		(layer "In4.Cu")
		(net "M_D_CPU0_SB_CB<1>")
	)
	(segment
		(start 296.691558 -279.963372)
		(end 296.996358 -279.963372)
		(width 0.14478)
		(layer "In4.Cu")
		(net "M_D_CPU0_SB_CB<1>")
	)
	(segment
		(start 326.40778 -273.52244)
		(end 326.65162 -273.52244)
		(width 0.0889)
		(layer "In4.Cu")
		(net "M_D_CPU0_SB_CB<1>")
	)
	(segment
		(start 305.923696 -279.359868)
		(end 306.147724 -279.359868)
		(width 0.14478)
		(layer "In4.Cu")
		(net "M_D_CPU0_SB_CB<1>")
	)
	(segment
		(start 331.634084 -273.59864)
		(end 331.642466 -273.603466)
		(width 0.0889)
		(layer "In4.Cu")
		(net "M_D_CPU0_SB_CB<1>")
	)
	(segment
		(start 335.394046 -273.59864)
		(end 335.402428 -273.603466)
		(width 0.0889)
		(layer "In4.Cu")
		(net "M_D_CPU0_SB_CB<1>")
	)
	(segment
		(start 304.216562 -279.927812)
		(end 304.485802 -279.927812)
		(width 0.14478)
		(layer "In4.Cu")
		(net "M_D_CPU0_SB_CB<1>")
	)
	(segment
		(start 306.765198 -279.74671)
		(end 307.09997 -279.411938)
		(width 0.14478)
		(layer "In4.Cu")
		(net "M_D_CPU0_SB_CB<1>")
	)
	(segment
		(start 288.4805 -280.210006)
		(end 288.855404 -280.58491)
		(width 0.14478)
		(layer "In4.Cu")
		(net "M_D_CPU0_SB_CB<1>")
	)
	(segment
		(start 289.411664 -279.835102)
		(end 289.642296 -279.835102)
		(width 0.14478)
		(layer "In4.Cu")
		(net "M_D_CPU0_SB_CB<1>")
	)
	(segment
		(start 290.0172 -280.210006)
		(end 290.493958 -280.210006)
		(width 0.14478)
		(layer "In4.Cu")
		(net "M_D_CPU0_SB_CB<1>")
	)
	(segment
		(start 287.043114 -280.423366)
		(end 287.043114 -279.999186)
		(width 0.14478)
		(layer "In4.Cu")
		(net "M_D_CPU0_SB_CB<1>")
	)
	(segment
		(start 286.32404 -279.836372)
		(end 286.486854 -279.999186)
		(width 0.14478)
		(layer "In4.Cu")
		(net "M_D_CPU0_SB_CB<1>")
	)
	(segment
		(start 286.649668 -280.58618)
		(end 286.8803 -280.58618)
		(width 0.14478)
		(layer "In4.Cu")
		(net "M_D_CPU0_SB_CB<1>")
	)
	(segment
		(start 289.24885 -279.997916)
		(end 289.411664 -279.835102)
		(width 0.14478)
		(layer "In4.Cu")
		(net "M_D_CPU0_SB_CB<1>")
	)
	(segment
		(start 284.736032 -279.785064)
		(end 285.537148 -280.58618)
		(width 0.14478)
		(layer "In4.Cu")
		(net "M_D_CPU0_SB_CB<1>")
	)
	(segment
		(start 339.519768 -273.603466)
		(end 339.52815 -273.59864)
		(width 0.0889)
		(layer "In4.Cu")
		(net "M_D_CPU0_SB_CB<1>")
	)
	(segment
		(start 314.85459 -272.20926)
		(end 323.901054 -272.20926)
		(width 0.14478)
		(layer "In4.Cu")
		(net "M_D_CPU0_SB_CB<1>")
	)
	(segment
		(start 307.651912 -279.411938)
		(end 314.85459 -272.20926)
		(width 0.14478)
		(layer "In4.Cu")
		(net "M_D_CPU0_SB_CB<1>")
	)
	(segment
		(start 286.486854 -279.999186)
		(end 286.486854 -280.423366)
		(width 0.14478)
		(layer "In4.Cu")
		(net "M_D_CPU0_SB_CB<1>")
	)
	(segment
		(start 301.927768 -280.210006)
		(end 302.230282 -279.907492)
		(width 0.14478)
		(layer "In4.Cu")
		(net "M_D_CPU0_SB_CB<1>")
	)
	(segment
		(start 297.242992 -280.210006)
		(end 297.690286 -280.210006)
		(width 0.14478)
		(layer "In4.Cu")
		(net "M_D_CPU0_SB_CB<1>")
	)
	(segment
		(start 333.879698 -273.603466)
		(end 333.88808 -273.59864)
		(width 0.0889)
		(layer "In4.Cu")
		(net "M_D_CPU0_SB_CB<1>")
	)
	(segment
		(start 304.767996 -280.210006)
		(end 305.073558 -280.210006)
		(width 0.14478)
		(layer "In4.Cu")
		(net "M_D_CPU0_SB_CB<1>")
	)
	(segment
		(start 303.934368 -280.210006)
		(end 304.216562 -279.927812)
		(width 0.14478)
		(layer "In4.Cu")
		(net "M_D_CPU0_SB_CB<1>")
	)
	(segment
		(start 340.435184 -273.54149)
		(end 340.281006 -273.27606)
		(width 0.0889)
		(layer "In4.Cu")
		(net "M_D_CPU0_SB_CB<1>")
	)
	(segment
		(start 307.09997 -279.411938)
		(end 307.651912 -279.411938)
		(width 0.14478)
		(layer "In4.Cu")
		(net "M_D_CPU0_SB_CB<1>")
	)
	(segment
		(start 285.930594 -279.999186)
		(end 286.093408 -279.836372)
		(width 0.14478)
		(layer "In4.Cu")
		(net "M_D_CPU0_SB_CB<1>")
	)
	(segment
		(start 304.485802 -279.927812)
		(end 304.767996 -280.210006)
		(width 0.14478)
		(layer "In4.Cu")
		(net "M_D_CPU0_SB_CB<1>")
	)
	(segment
		(start 285.76778 -280.58618)
		(end 285.930594 -280.423366)
		(width 0.14478)
		(layer "In4.Cu")
		(net "M_D_CPU0_SB_CB<1>")
	)
	(segment
		(start 291.342318 -279.361646)
		(end 293.11219 -279.361646)
		(width 0.14478)
		(layer "In4.Cu")
		(net "M_D_CPU0_SB_CB<1>")
	)
	(segment
		(start 286.093408 -279.836372)
		(end 286.32404 -279.836372)
		(width 0.14478)
		(layer "In4.Cu")
		(net "M_D_CPU0_SB_CB<1>")
	)
	(segment
		(start 288.855404 -280.58491)
		(end 289.086036 -280.58491)
		(width 0.14478)
		(layer "In4.Cu")
		(net "M_D_CPU0_SB_CB<1>")
	)
	(segment
		(start 325.162672 -272.277332)
		(end 326.40778 -273.52244)
		(width 0.0889)
		(layer "In4.Cu")
		(net "M_D_CPU0_SB_CB<1>")
	)
	(segment
		(start 334.819752 -273.603466)
		(end 334.828134 -273.59864)
		(width 0.0889)
		(layer "In4.Cu")
		(net "M_D_CPU0_SB_CB<1>")
	)
	(segment
		(start 302.781716 -280.210006)
		(end 303.934368 -280.210006)
		(width 0.14478)
		(layer "In4.Cu")
		(net "M_D_CPU0_SB_CB<1>")
	)
	(segment
		(start 323.901054 -272.20926)
		(end 324.398386 -272.20926)
		(width 0.0889)
		(layer "In4.Cu")
		(net "M_D_CPU0_SB_CB<1>")
	)
	(segment
		(start 289.24885 -280.422096)
		(end 289.24885 -279.997916)
		(width 0.14478)
		(layer "In4.Cu")
		(net "M_D_CPU0_SB_CB<1>")
	)
	(segment
		(start 306.147724 -279.359868)
		(end 306.534566 -279.74671)
		(width 0.14478)
		(layer "In4.Cu")
		(net "M_D_CPU0_SB_CB<1>")
	)
	(segment
		(start 324.398386 -272.20926)
		(end 324.466458 -272.277332)
		(width 0.0889)
		(layer "In4.Cu")
		(net "M_D_CPU0_SB_CB<1>")
	)
	(segment
		(start 296.996358 -279.963372)
		(end 297.242992 -280.210006)
		(width 0.14478)
		(layer "In4.Cu")
		(net "M_D_CPU0_SB_CB<1>")
	)
	(segment
		(start 287.43656 -279.836372)
		(end 287.810194 -280.210006)
		(width 0.14478)
		(layer "In4.Cu")
		(net "M_D_CPU0_SB_CB<1>")
	)
	(segment
		(start 324.466458 -272.277332)
		(end 325.162672 -272.277332)
		(width 0.0889)
		(layer "In4.Cu")
		(net "M_D_CPU0_SB_CB<1>")
	)
	(segment
		(start 328.239882 -273.603466)
		(end 328.248264 -273.59864)
		(width 0.0889)
		(layer "In4.Cu")
		(net "M_D_CPU0_SB_CB<1>")
	)
	(segment
		(start 293.11219 -279.361646)
		(end 293.96055 -280.210006)
		(width 0.14478)
		(layer "In4.Cu")
		(net "M_D_CPU0_SB_CB<1>")
	)
	(segment
		(start 297.690286 -280.210006)
		(end 298.540424 -279.359868)
		(width 0.14478)
		(layer "In4.Cu")
		(net "M_D_CPU0_SB_CB<1>")
	)
	(segment
		(start 326.93356 -273.598386)
		(end 326.947276 -273.60626)
		(width 0.0889)
		(layer "In4.Cu")
		(net "M_D_CPU0_SB_CB<1>")
	)
	(segment
		(start 340.094062 -273.59864)
		(end 340.102444 -273.603466)
		(width 0.0889)
		(layer "In4.Cu")
		(net "M_D_CPU0_SB_CB<1>")
	)
	(segment
		(start 340.412832 -273.624802)
		(end 340.435184 -273.54149)
		(width 0.0889)
		(layer "In4.Cu")
		(net "M_D_CPU0_SB_CB<1>")
	)
	(segment
		(start 296.444924 -280.210006)
		(end 296.691558 -279.963372)
		(width 0.14478)
		(layer "In4.Cu")
		(net "M_D_CPU0_SB_CB<1>")
	)
	(segment
		(start 287.205928 -279.836372)
		(end 287.43656 -279.836372)
		(width 0.14478)
		(layer "In4.Cu")
		(net "M_D_CPU0_SB_CB<1>")
	)
	(segment
		(start 330.69403 -273.59864)
		(end 330.702412 -273.603466)
		(width 0.0889)
		(layer "In4.Cu")
		(net "M_D_CPU0_SB_CB<1>")
	)
	(arc
		(start 328.814176 -273.59864)
		(mid 329.00112 -273.648895)
		(end 329.188064 -273.59864)
		(width 0.0889)
		(layer "In4.Cu")
		(net "M_D_CPU0_SB_CB<1>")
	)
	(arc
		(start 336.342482 -273.603466)
		(mid 336.52599 -273.64896)
		(end 336.708242 -273.59864)
		(width 0.0889)
		(layer "In4.Cu")
		(net "M_D_CPU0_SB_CB<1>")
	)
	(arc
		(start 326.947276 -273.60626)
		(mid 327.128206 -273.648738)
		(end 327.307194 -273.59864)
		(width 0.0889)
		(layer "In4.Cu")
		(net "M_D_CPU0_SB_CB<1>")
	)
	(arc
		(start 327.321926 -273.590004)
		(mid 327.598909 -273.5222)
		(end 327.873614 -273.59864)
		(width 0.0889)
		(layer "In4.Cu")
		(net "M_D_CPU0_SB_CB<1>")
	)
	(arc
		(start 330.128118 -273.59864)
		(mid 330.411074 -273.522463)
		(end 330.69403 -273.59864)
		(width 0.0889)
		(layer "In4.Cu")
		(net "M_D_CPU0_SB_CB<1>")
	)
	(arc
		(start 333.88808 -273.59864)
		(mid 334.171036 -273.522463)
		(end 334.453992 -273.59864)
		(width 0.0889)
		(layer "In4.Cu")
		(net "M_D_CPU0_SB_CB<1>")
	)
	(arc
		(start 326.68337 -273.523202)
		(mid 326.812874 -273.546116)
		(end 326.93356 -273.598386)
		(width 0.0889)
		(layer "In4.Cu")
		(net "M_D_CPU0_SB_CB<1>")
	)
	(arc
		(start 332.008226 -273.59864)
		(mid 332.291182 -273.522463)
		(end 332.574138 -273.59864)
		(width 0.0889)
		(layer "In4.Cu")
		(net "M_D_CPU0_SB_CB<1>")
	)
	(arc
		(start 336.708242 -273.59864)
		(mid 336.991198 -273.522463)
		(end 337.274154 -273.59864)
		(width 0.0889)
		(layer "In4.Cu")
		(net "M_D_CPU0_SB_CB<1>")
	)
	(arc
		(start 335.402428 -273.603466)
		(mid 335.585936 -273.64896)
		(end 335.768188 -273.59864)
		(width 0.0889)
		(layer "In4.Cu")
		(net "M_D_CPU0_SB_CB<1>")
	)
	(arc
		(start 333.513938 -273.59864)
		(mid 333.696189 -273.64899)
		(end 333.879698 -273.603466)
		(width 0.0889)
		(layer "In4.Cu")
		(net "M_D_CPU0_SB_CB<1>")
	)
	(arc
		(start 328.248264 -273.59864)
		(mid 328.53122 -273.522463)
		(end 328.814176 -273.59864)
		(width 0.0889)
		(layer "In4.Cu")
		(net "M_D_CPU0_SB_CB<1>")
	)
	(arc
		(start 337.648042 -273.59864)
		(mid 337.930998 -273.522463)
		(end 338.213954 -273.59864)
		(width 0.0889)
		(layer "In4.Cu")
		(net "M_D_CPU0_SB_CB<1>")
	)
	(arc
		(start 339.154008 -273.59864)
		(mid 339.336259 -273.64899)
		(end 339.519768 -273.603466)
		(width 0.0889)
		(layer "In4.Cu")
		(net "M_D_CPU0_SB_CB<1>")
	)
	(arc
		(start 335.768188 -273.59864)
		(mid 336.051144 -273.522463)
		(end 336.3341 -273.59864)
		(width 0.0889)
		(layer "In4.Cu")
		(net "M_D_CPU0_SB_CB<1>")
	)
	(arc
		(start 327.873614 -273.59864)
		(mid 328.056119 -273.649117)
		(end 328.239882 -273.603466)
		(width 0.0889)
		(layer "In4.Cu")
		(net "M_D_CPU0_SB_CB<1>")
	)
	(arc
		(start 330.702412 -273.603466)
		(mid 330.88592 -273.64896)
		(end 331.068172 -273.59864)
		(width 0.0889)
		(layer "In4.Cu")
		(net "M_D_CPU0_SB_CB<1>")
	)
	(arc
		(start 331.642466 -273.603466)
		(mid 331.825974 -273.64896)
		(end 332.008226 -273.59864)
		(width 0.0889)
		(layer "In4.Cu")
		(net "M_D_CPU0_SB_CB<1>")
	)
	(arc
		(start 340.102444 -273.603466)
		(mid 340.255314 -273.648107)
		(end 340.412832 -273.624802)
		(width 0.0889)
		(layer "In4.Cu")
		(net "M_D_CPU0_SB_CB<1>")
	)
	(arc
		(start 334.453992 -273.59864)
		(mid 334.636243 -273.64899)
		(end 334.819752 -273.603466)
		(width 0.0889)
		(layer "In4.Cu")
		(net "M_D_CPU0_SB_CB<1>")
	)
	(arc
		(start 338.213954 -273.59864)
		(mid 338.396205 -273.64899)
		(end 338.579714 -273.603466)
		(width 0.0889)
		(layer "In4.Cu")
		(net "M_D_CPU0_SB_CB<1>")
	)
	(arc
		(start 338.588096 -273.59864)
		(mid 338.871052 -273.522463)
		(end 339.154008 -273.59864)
		(width 0.0889)
		(layer "In4.Cu")
		(net "M_D_CPU0_SB_CB<1>")
	)
	(arc
		(start 329.188064 -273.59864)
		(mid 329.47102 -273.522463)
		(end 329.753976 -273.59864)
		(width 0.0889)
		(layer "In4.Cu")
		(net "M_D_CPU0_SB_CB<1>")
	)
	(arc
		(start 326.65162 -273.52244)
		(mid 326.6675 -273.522599)
		(end 326.68337 -273.523202)
		(width 0.0889)
		(layer "In4.Cu")
		(net "M_D_CPU0_SB_CB<1>")
	)
	(arc
		(start 332.574138 -273.59864)
		(mid 332.761082 -273.648895)
		(end 332.948026 -273.59864)
		(width 0.0889)
		(layer "In4.Cu")
		(net "M_D_CPU0_SB_CB<1>")
	)
	(arc
		(start 332.948026 -273.59864)
		(mid 333.230982 -273.522463)
		(end 333.513938 -273.59864)
		(width 0.0889)
		(layer "In4.Cu")
		(net "M_D_CPU0_SB_CB<1>")
	)
	(arc
		(start 334.828134 -273.59864)
		(mid 335.11109 -273.522463)
		(end 335.394046 -273.59864)
		(width 0.0889)
		(layer "In4.Cu")
		(net "M_D_CPU0_SB_CB<1>")
	)
	(arc
		(start 339.52815 -273.59864)
		(mid 339.811106 -273.522463)
		(end 340.094062 -273.59864)
		(width 0.0889)
		(layer "In4.Cu")
		(net "M_D_CPU0_SB_CB<1>")
	)
	(arc
		(start 329.753976 -273.59864)
		(mid 329.936227 -273.64899)
		(end 330.119736 -273.603466)
		(width 0.0889)
		(layer "In4.Cu")
		(net "M_D_CPU0_SB_CB<1>")
	)
	(arc
		(start 337.274154 -273.59864)
		(mid 337.461098 -273.648895)
		(end 337.648042 -273.59864)
		(width 0.0889)
		(layer "In4.Cu")
		(net "M_D_CPU0_SB_CB<1>")
	)
	(arc
		(start 331.068172 -273.59864)
		(mid 331.351128 -273.522463)
		(end 331.634084 -273.59864)
		(width 0.0889)
		(layer "In4.Cu")
		(net "M_D_CPU0_SB_CB<1>")
	)
	(segment
		(start 339.337904 -272.200116)
		(end 338.871052 -272.466054)
		(width 0.10668)
		(layer "F.Cu")
		(net "M_D_CPU0_SB_CB<0>")
	)
	(segment
		(start 312.917332 -272.60296)
		(end 312.917332 -272.374868)
		(width 0.14478)
		(layer "In4.Cu")
		(net "M_D_CPU0_SB_CB<0>")
	)
	(segment
		(start 310.576722 -275.13534)
		(end 310.576468 -274.943824)
		(width 0.14478)
		(layer "In4.Cu")
		(net "M_D_CPU0_SB_CB<0>")
	)
	(segment
		(start 297.533568 -278.51989)
		(end 298.034202 -278.51989)
		(width 0.14478)
		(layer "In4.Cu")
		(net "M_D_CPU0_SB_CB<0>")
	)
	(segment
		(start 328.709782 -272.79346)
		(end 328.718164 -272.788634)
		(width 0.0889)
		(layer "In4.Cu")
		(net "M_D_CPU0_SB_CB<0>")
	)
	(segment
		(start 302.816006 -278.671274)
		(end 302.977042 -278.83231)
		(width 0.14478)
		(layer "In4.Cu")
		(net "M_D_CPU0_SB_CB<0>")
	)
	(segment
		(start 312.737246 -272.974816)
		(end 312.917586 -272.794476)
		(width 0.14478)
		(layer "In4.Cu")
		(net "M_D_CPU0_SB_CB<0>")
	)
	(segment
		(start 306.599336 -277.93569)
		(end 306.737004 -277.798022)
		(width 0.14478)
		(layer "In4.Cu")
		(net "M_D_CPU0_SB_CB<0>")
	)
	(segment
		(start 311.17667 -274.535392)
		(end 311.35701 -274.355052)
		(width 0.14478)
		(layer "In4.Cu")
		(net "M_D_CPU0_SB_CB<0>")
	)
	(segment
		(start 285.628334 -278.681434)
		(end 285.628334 -278.742648)
		(width 0.14478)
		(layer "In4.Cu")
		(net "M_D_CPU0_SB_CB<0>")
	)
	(segment
		(start 313.69762 -271.822672)
		(end 313.69762 -271.59458)
		(width 0.14478)
		(layer "In4.Cu")
		(net "M_D_CPU0_SB_CB<0>")
	)
	(segment
		(start 302.420782 -278.188166)
		(end 302.65497 -278.188166)
		(width 0.14478)
		(layer "In4.Cu")
		(net "M_D_CPU0_SB_CB<0>")
	)
	(segment
		(start 306.737004 -277.522178)
		(end 306.874672 -277.38451)
		(width 0.14478)
		(layer "In4.Cu")
		(net "M_D_CPU0_SB_CB<0>")
	)
	(segment
		(start 306.180744 -277.797768)
		(end 306.180744 -277.798022)
		(width 0.14478)
		(layer "In4.Cu")
		(net "M_D_CPU0_SB_CB<0>")
	)
	(segment
		(start 294.983662 -278.681434)
		(end 295.145206 -278.51989)
		(width 0.14478)
		(layer "In4.Cu")
		(net "M_D_CPU0_SB_CB<0>")
	)
	(segment
		(start 298.88434 -277.669752)
		(end 300.590204 -277.669752)
		(width 0.14478)
		(layer "In4.Cu")
		(net "M_D_CPU0_SB_CB<0>")
	)
	(segment
		(start 304.32375 -278.83231)
		(end 304.645822 -278.510238)
		(width 0.14478)
		(layer "In4.Cu")
		(net "M_D_CPU0_SB_CB<0>")
	)
	(segment
		(start 312.917332 -272.374868)
		(end 313.097672 -272.194528)
		(width 0.14478)
		(layer "In4.Cu")
		(net "M_D_CPU0_SB_CB<0>")
	)
	(segment
		(start 285.17088 -278.51989)
		(end 285.46679 -278.51989)
		(width 0.14478)
		(layer "In4.Cu")
		(net "M_D_CPU0_SB_CB<0>")
	)
	(segment
		(start 309.796434 -275.915628)
		(end 309.79618 -275.724112)
		(width 0.14478)
		(layer "In4.Cu")
		(net "M_D_CPU0_SB_CB<0>")
	)
	(segment
		(start 294.822118 -278.904192)
		(end 294.983662 -278.742648)
		(width 0.14478)
		(layer "In4.Cu")
		(net "M_D_CPU0_SB_CB<0>")
	)
	(segment
		(start 339.02523 -272.731484)
		(end 338.871052 -272.466054)
		(width 0.0889)
		(layer "In4.Cu")
		(net "M_D_CPU0_SB_CB<0>")
	)
	(segment
		(start 287.44418 -278.51989)
		(end 290.388294 -278.51989)
		(width 0.14478)
		(layer "In4.Cu")
		(net "M_D_CPU0_SB_CB<0>")
	)
	(segment
		(start 293.063168 -277.669752)
		(end 293.913306 -278.51989)
		(width 0.14478)
		(layer "In4.Cu")
		(net "M_D_CPU0_SB_CB<0>")
	)
	(segment
		(start 312.137044 -273.155156)
		(end 312.317384 -272.974816)
		(width 0.14478)
		(layer "In4.Cu")
		(net "M_D_CPU0_SB_CB<0>")
	)
	(segment
		(start 290.388294 -278.51989)
		(end 291.238432 -277.669752)
		(width 0.14478)
		(layer "In4.Cu")
		(net "M_D_CPU0_SB_CB<0>")
	)
	(segment
		(start 313.517534 -272.194528)
		(end 313.697874 -272.014188)
		(width 0.14478)
		(layer "In4.Cu")
		(net "M_D_CPU0_SB_CB<0>")
	)
	(segment
		(start 287.121092 -278.904192)
		(end 287.282636 -278.742648)
		(width 0.14478)
		(layer "In4.Cu")
		(net "M_D_CPU0_SB_CB<0>")
	)
	(segment
		(start 309.616094 -276.095968)
		(end 309.796434 -275.915628)
		(width 0.14478)
		(layer "In4.Cu")
		(net "M_D_CPU0_SB_CB<0>")
	)
	(segment
		(start 296.82059 -278.681434)
		(end 296.82059 -278.735028)
		(width 0.14478)
		(layer "In4.Cu")
		(net "M_D_CPU0_SB_CB<0>")
	)
	(segment
		(start 286.018224 -278.904192)
		(end 286.179768 -278.742648)
		(width 0.14478)
		(layer "In4.Cu")
		(net "M_D_CPU0_SB_CB<0>")
	)
	(segment
		(start 287.282636 -278.742648)
		(end 287.282636 -278.681434)
		(width 0.14478)
		(layer "In4.Cu")
		(net "M_D_CPU0_SB_CB<0>")
	)
	(segment
		(start 339.002878 -272.814796)
		(end 339.02523 -272.731484)
		(width 0.0889)
		(layer "In4.Cu")
		(net "M_D_CPU0_SB_CB<0>")
	)
	(segment
		(start 312.917586 -272.794476)
		(end 312.917332 -272.60296)
		(width 0.14478)
		(layer "In4.Cu")
		(net "M_D_CPU0_SB_CB<0>")
	)
	(segment
		(start 338.684108 -272.788634)
		(end 338.69249 -272.79346)
		(width 0.0889)
		(layer "In4.Cu")
		(net "M_D_CPU0_SB_CB<0>")
	)
	(segment
		(start 301.752762 -278.83231)
		(end 302.09871 -278.83231)
		(width 0.14478)
		(layer "In4.Cu")
		(net "M_D_CPU0_SB_CB<0>")
	)
	(segment
		(start 313.097672 -272.194528)
		(end 313.517534 -272.194528)
		(width 0.14478)
		(layer "In4.Cu")
		(net "M_D_CPU0_SB_CB<0>")
	)
	(segment
		(start 311.356756 -273.935444)
		(end 311.537096 -273.755104)
		(width 0.14478)
		(layer "In4.Cu")
		(net "M_D_CPU0_SB_CB<0>")
	)
	(segment
		(start 306.737004 -277.798022)
		(end 306.737004 -277.522178)
		(width 0.14478)
		(layer "In4.Cu")
		(net "M_D_CPU0_SB_CB<0>")
	)
	(segment
		(start 302.816006 -278.349202)
		(end 302.816006 -278.671274)
		(width 0.14478)
		(layer "In4.Cu")
		(net "M_D_CPU0_SB_CB<0>")
	)
	(segment
		(start 285.789878 -278.904192)
		(end 286.018224 -278.904192)
		(width 0.14478)
		(layer "In4.Cu")
		(net "M_D_CPU0_SB_CB<0>")
	)
	(segment
		(start 331.52969 -272.79346)
		(end 331.538072 -272.788634)
		(width 0.0889)
		(layer "In4.Cu")
		(net "M_D_CPU0_SB_CB<0>")
	)
	(segment
		(start 303.21123 -278.83231)
		(end 303.372266 -278.671274)
		(width 0.14478)
		(layer "In4.Cu")
		(net "M_D_CPU0_SB_CB<0>")
	)
	(segment
		(start 309.79618 -275.49602)
		(end 309.97652 -275.31568)
		(width 0.14478)
		(layer "In4.Cu")
		(net "M_D_CPU0_SB_CB<0>")
	)
	(segment
		(start 332.469744 -272.79346)
		(end 332.478126 -272.788634)
		(width 0.0889)
		(layer "In4.Cu")
		(net "M_D_CPU0_SB_CB<0>")
	)
	(segment
		(start 294.432228 -278.742648)
		(end 294.593772 -278.904192)
		(width 0.14478)
		(layer "In4.Cu")
		(net "M_D_CPU0_SB_CB<0>")
	)
	(segment
		(start 310.756808 -274.535392)
		(end 311.17667 -274.535392)
		(width 0.14478)
		(layer "In4.Cu")
		(net "M_D_CPU0_SB_CB<0>")
	)
	(segment
		(start 306.043076 -277.6601)
		(end 306.180744 -277.797768)
		(width 0.14478)
		(layer "In4.Cu")
		(net "M_D_CPU0_SB_CB<0>")
	)
	(segment
		(start 302.09871 -278.83231)
		(end 302.259746 -278.671274)
		(width 0.14478)
		(layer "In4.Cu")
		(net "M_D_CPU0_SB_CB<0>")
	)
	(segment
		(start 302.259746 -278.349202)
		(end 302.420782 -278.188166)
		(width 0.14478)
		(layer "In4.Cu")
		(net "M_D_CPU0_SB_CB<0>")
	)
	(segment
		(start 312.137044 -273.383248)
		(end 312.137044 -273.155156)
		(width 0.14478)
		(layer "In4.Cu")
		(net "M_D_CPU0_SB_CB<0>")
	)
	(segment
		(start 303.372266 -278.671274)
		(end 303.372266 -278.349202)
		(width 0.14478)
		(layer "In4.Cu")
		(net "M_D_CPU0_SB_CB<0>")
	)
	(segment
		(start 307.90769 -277.38451)
		(end 308.415944 -276.876256)
		(width 0.14478)
		(layer "In4.Cu")
		(net "M_D_CPU0_SB_CB<0>")
	)
	(segment
		(start 286.341312 -278.51989)
		(end 286.569658 -278.51989)
		(width 0.14478)
		(layer "In4.Cu")
		(net "M_D_CPU0_SB_CB<0>")
	)
	(segment
		(start 298.034202 -278.51989)
		(end 298.88434 -277.669752)
		(width 0.14478)
		(layer "In4.Cu")
		(net "M_D_CPU0_SB_CB<0>")
	)
	(segment
		(start 297.21048 -278.896572)
		(end 297.372024 -278.735028)
		(width 0.14478)
		(layer "In4.Cu")
		(net "M_D_CPU0_SB_CB<0>")
	)
	(segment
		(start 300.590204 -277.669752)
		(end 301.752762 -278.83231)
		(width 0.14478)
		(layer "In4.Cu")
		(net "M_D_CPU0_SB_CB<0>")
	)
	(segment
		(start 286.892746 -278.904192)
		(end 287.121092 -278.904192)
		(width 0.14478)
		(layer "In4.Cu")
		(net "M_D_CPU0_SB_CB<0>")
	)
	(segment
		(start 328.333608 -272.782538)
		(end 328.344022 -272.788634)
		(width 0.0889)
		(layer "In4.Cu")
		(net "M_D_CPU0_SB_CB<0>")
	)
	(segment
		(start 333.044038 -272.788634)
		(end 333.05242 -272.79346)
		(width 0.0889)
		(layer "In4.Cu")
		(net "M_D_CPU0_SB_CB<0>")
	)
	(segment
		(start 309.015892 -276.276308)
		(end 309.196232 -276.095968)
		(width 0.14478)
		(layer "In4.Cu")
		(net "M_D_CPU0_SB_CB<0>")
	)
	(segment
		(start 306.874672 -277.38451)
		(end 307.90769 -277.38451)
		(width 0.14478)
		(layer "In4.Cu")
		(net "M_D_CPU0_SB_CB<0>")
	)
	(segment
		(start 286.731202 -278.742648)
		(end 286.892746 -278.904192)
		(width 0.14478)
		(layer "In4.Cu")
		(net "M_D_CPU0_SB_CB<0>")
	)
	(segment
		(start 323.901054 -271.29994)
		(end 324.339966 -271.29994)
		(width 0.0889)
		(layer "In4.Cu")
		(net "M_D_CPU0_SB_CB<0>")
	)
	(segment
		(start 304.089562 -278.83231)
		(end 304.32375 -278.83231)
		(width 0.14478)
		(layer "In4.Cu")
		(net "M_D_CPU0_SB_CB<0>")
	)
	(segment
		(start 337.16976 -272.79346)
		(end 337.178142 -272.788634)
		(width 0.0889)
		(layer "In4.Cu")
		(net "M_D_CPU0_SB_CB<0>")
	)
	(segment
		(start 303.928526 -278.671274)
		(end 304.089562 -278.83231)
		(width 0.14478)
		(layer "In4.Cu")
		(net "M_D_CPU0_SB_CB<0>")
	)
	(segment
		(start 311.35701 -274.355052)
		(end 311.356756 -274.163536)
		(width 0.14478)
		(layer "In4.Cu")
		(net "M_D_CPU0_SB_CB<0>")
	)
	(segment
		(start 325.444104 -271.787112)
		(end 326.386952 -272.72996)
		(width 0.0889)
		(layer "In4.Cu")
		(net "M_D_CPU0_SB_CB<0>")
	)
	(segment
		(start 326.819514 -272.798794)
		(end 326.837802 -272.78838)
		(width 0.0889)
		(layer "In4.Cu")
		(net "M_D_CPU0_SB_CB<0>")
	)
	(segment
		(start 333.984092 -272.788634)
		(end 333.992474 -272.79346)
		(width 0.0889)
		(layer "In4.Cu")
		(net "M_D_CPU0_SB_CB<0>")
	)
	(segment
		(start 309.015892 -276.5044)
		(end 309.015892 -276.276308)
		(width 0.14478)
		(layer "In4.Cu")
		(net "M_D_CPU0_SB_CB<0>")
	)
	(segment
		(start 310.576468 -274.943824)
		(end 310.576468 -274.715732)
		(width 0.14478)
		(layer "In4.Cu")
		(net "M_D_CPU0_SB_CB<0>")
	)
	(segment
		(start 294.983662 -278.742648)
		(end 294.983662 -278.681434)
		(width 0.14478)
		(layer "In4.Cu")
		(net "M_D_CPU0_SB_CB<0>")
	)
	(segment
		(start 309.79618 -275.724112)
		(end 309.79618 -275.49602)
		(width 0.14478)
		(layer "In4.Cu")
		(net "M_D_CPU0_SB_CB<0>")
	)
	(segment
		(start 308.415944 -276.876256)
		(end 308.835806 -276.876256)
		(width 0.14478)
		(layer "In4.Cu")
		(net "M_D_CPU0_SB_CB<0>")
	)
	(segment
		(start 302.259746 -278.671274)
		(end 302.259746 -278.349202)
		(width 0.14478)
		(layer "In4.Cu")
		(net "M_D_CPU0_SB_CB<0>")
	)
	(segment
		(start 313.99226 -271.29994)
		(end 323.901054 -271.29994)
		(width 0.14478)
		(layer "In4.Cu")
		(net "M_D_CPU0_SB_CB<0>")
	)
	(segment
		(start 313.69762 -271.59458)
		(end 313.99226 -271.29994)
		(width 0.14478)
		(layer "In4.Cu")
		(net "M_D_CPU0_SB_CB<0>")
	)
	(segment
		(start 296.659046 -278.51989)
		(end 296.82059 -278.681434)
		(width 0.14478)
		(layer "In4.Cu")
		(net "M_D_CPU0_SB_CB<0>")
	)
	(segment
		(start 310.576468 -274.715732)
		(end 310.756808 -274.535392)
		(width 0.14478)
		(layer "In4.Cu")
		(net "M_D_CPU0_SB_CB<0>")
	)
	(segment
		(start 303.533302 -278.188166)
		(end 303.76749 -278.188166)
		(width 0.14478)
		(layer "In4.Cu")
		(net "M_D_CPU0_SB_CB<0>")
	)
	(segment
		(start 306.318412 -277.93569)
		(end 306.599336 -277.93569)
		(width 0.14478)
		(layer "In4.Cu")
		(net "M_D_CPU0_SB_CB<0>")
	)
	(segment
		(start 311.537096 -273.755104)
		(end 311.956958 -273.755104)
		(width 0.14478)
		(layer "In4.Cu")
		(net "M_D_CPU0_SB_CB<0>")
	)
	(segment
		(start 284.736032 -278.085042)
		(end 285.17088 -278.51989)
		(width 0.14478)
		(layer "In4.Cu")
		(net "M_D_CPU0_SB_CB<0>")
	)
	(segment
		(start 308.835806 -276.876256)
		(end 309.016146 -276.695916)
		(width 0.14478)
		(layer "In4.Cu")
		(net "M_D_CPU0_SB_CB<0>")
	)
	(segment
		(start 312.137298 -273.574764)
		(end 312.137044 -273.383248)
		(width 0.14478)
		(layer "In4.Cu")
		(net "M_D_CPU0_SB_CB<0>")
	)
	(segment
		(start 303.928526 -278.349202)
		(end 303.928526 -278.671274)
		(width 0.14478)
		(layer "In4.Cu")
		(net "M_D_CPU0_SB_CB<0>")
	)
	(segment
		(start 302.977042 -278.83231)
		(end 303.21123 -278.83231)
		(width 0.14478)
		(layer "In4.Cu")
		(net "M_D_CPU0_SB_CB<0>")
	)
	(segment
		(start 293.913306 -278.51989)
		(end 294.270684 -278.51989)
		(width 0.14478)
		(layer "In4.Cu")
		(net "M_D_CPU0_SB_CB<0>")
	)
	(segment
		(start 296.82059 -278.735028)
		(end 296.982134 -278.896572)
		(width 0.14478)
		(layer "In4.Cu")
		(net "M_D_CPU0_SB_CB<0>")
	)
	(segment
		(start 286.569658 -278.51989)
		(end 286.731202 -278.681434)
		(width 0.14478)
		(layer "In4.Cu")
		(net "M_D_CPU0_SB_CB<0>")
	)
	(segment
		(start 309.196232 -276.095968)
		(end 309.616094 -276.095968)
		(width 0.14478)
		(layer "In4.Cu")
		(net "M_D_CPU0_SB_CB<0>")
	)
	(segment
		(start 309.97652 -275.31568)
		(end 310.396382 -275.31568)
		(width 0.14478)
		(layer "In4.Cu")
		(net "M_D_CPU0_SB_CB<0>")
	)
	(segment
		(start 294.432228 -278.681434)
		(end 294.432228 -278.742648)
		(width 0.14478)
		(layer "In4.Cu")
		(net "M_D_CPU0_SB_CB<0>")
	)
	(segment
		(start 304.645822 -278.510238)
		(end 304.969926 -278.510238)
		(width 0.14478)
		(layer "In4.Cu")
		(net "M_D_CPU0_SB_CB<0>")
	)
	(segment
		(start 306.180744 -277.798022)
		(end 306.318412 -277.93569)
		(width 0.14478)
		(layer "In4.Cu")
		(net "M_D_CPU0_SB_CB<0>")
	)
	(segment
		(start 297.372024 -278.735028)
		(end 297.372024 -278.681434)
		(width 0.14478)
		(layer "In4.Cu")
		(net "M_D_CPU0_SB_CB<0>")
	)
	(segment
		(start 313.697874 -272.014188)
		(end 313.69762 -271.822672)
		(width 0.14478)
		(layer "In4.Cu")
		(net "M_D_CPU0_SB_CB<0>")
	)
	(segment
		(start 324.827138 -271.787112)
		(end 325.444104 -271.787112)
		(width 0.0889)
		(layer "In4.Cu")
		(net "M_D_CPU0_SB_CB<0>")
	)
	(segment
		(start 326.837802 -272.78838)
		(end 326.84339 -272.785078)
		(width 0.0889)
		(layer "In4.Cu")
		(net "M_D_CPU0_SB_CB<0>")
	)
	(segment
		(start 324.339966 -271.29994)
		(end 324.827138 -271.787112)
		(width 0.0889)
		(layer "In4.Cu")
		(net "M_D_CPU0_SB_CB<0>")
	)
	(segment
		(start 296.982134 -278.896572)
		(end 297.21048 -278.896572)
		(width 0.14478)
		(layer "In4.Cu")
		(net "M_D_CPU0_SB_CB<0>")
	)
	(segment
		(start 294.270684 -278.51989)
		(end 294.432228 -278.681434)
		(width 0.14478)
		(layer "In4.Cu")
		(net "M_D_CPU0_SB_CB<0>")
	)
	(segment
		(start 287.282636 -278.681434)
		(end 287.44418 -278.51989)
		(width 0.14478)
		(layer "In4.Cu")
		(net "M_D_CPU0_SB_CB<0>")
	)
	(segment
		(start 286.731202 -278.681434)
		(end 286.731202 -278.742648)
		(width 0.14478)
		(layer "In4.Cu")
		(net "M_D_CPU0_SB_CB<0>")
	)
	(segment
		(start 311.956958 -273.755104)
		(end 312.137298 -273.574764)
		(width 0.14478)
		(layer "In4.Cu")
		(net "M_D_CPU0_SB_CB<0>")
	)
	(segment
		(start 291.238432 -277.669752)
		(end 293.063168 -277.669752)
		(width 0.14478)
		(layer "In4.Cu")
		(net "M_D_CPU0_SB_CB<0>")
	)
	(segment
		(start 312.317384 -272.974816)
		(end 312.737246 -272.974816)
		(width 0.14478)
		(layer "In4.Cu")
		(net "M_D_CPU0_SB_CB<0>")
	)
	(segment
		(start 326.463406 -272.788634)
		(end 326.46366 -272.788634)
		(width 0.0889)
		(layer "In4.Cu")
		(net "M_D_CPU0_SB_CB<0>")
	)
	(segment
		(start 327.403206 -272.788634)
		(end 327.411588 -272.79346)
		(width 0.0889)
		(layer "In4.Cu")
		(net "M_D_CPU0_SB_CB<0>")
	)
	(segment
		(start 303.372266 -278.349202)
		(end 303.533302 -278.188166)
		(width 0.14478)
		(layer "In4.Cu")
		(net "M_D_CPU0_SB_CB<0>")
	)
	(segment
		(start 302.65497 -278.188166)
		(end 302.816006 -278.349202)
		(width 0.14478)
		(layer "In4.Cu")
		(net "M_D_CPU0_SB_CB<0>")
	)
	(segment
		(start 304.969926 -278.510238)
		(end 305.820064 -277.6601)
		(width 0.14478)
		(layer "In4.Cu")
		(net "M_D_CPU0_SB_CB<0>")
	)
	(segment
		(start 297.372024 -278.681434)
		(end 297.533568 -278.51989)
		(width 0.14478)
		(layer "In4.Cu")
		(net "M_D_CPU0_SB_CB<0>")
	)
	(segment
		(start 303.76749 -278.188166)
		(end 303.928526 -278.349202)
		(width 0.14478)
		(layer "In4.Cu")
		(net "M_D_CPU0_SB_CB<0>")
	)
	(segment
		(start 286.179768 -278.742648)
		(end 286.179768 -278.681434)
		(width 0.14478)
		(layer "In4.Cu")
		(net "M_D_CPU0_SB_CB<0>")
	)
	(segment
		(start 310.396382 -275.31568)
		(end 310.576722 -275.13534)
		(width 0.14478)
		(layer "In4.Cu")
		(net "M_D_CPU0_SB_CB<0>")
	)
	(segment
		(start 309.016146 -276.695916)
		(end 309.015892 -276.5044)
		(width 0.14478)
		(layer "In4.Cu")
		(net "M_D_CPU0_SB_CB<0>")
	)
	(segment
		(start 285.628334 -278.742648)
		(end 285.789878 -278.904192)
		(width 0.14478)
		(layer "In4.Cu")
		(net "M_D_CPU0_SB_CB<0>")
	)
	(segment
		(start 336.229706 -272.79346)
		(end 336.238088 -272.788634)
		(width 0.0889)
		(layer "In4.Cu")
		(net "M_D_CPU0_SB_CB<0>")
	)
	(segment
		(start 285.46679 -278.51989)
		(end 285.628334 -278.681434)
		(width 0.14478)
		(layer "In4.Cu")
		(net "M_D_CPU0_SB_CB<0>")
	)
	(segment
		(start 295.145206 -278.51989)
		(end 296.659046 -278.51989)
		(width 0.14478)
		(layer "In4.Cu")
		(net "M_D_CPU0_SB_CB<0>")
	)
	(segment
		(start 286.179768 -278.681434)
		(end 286.341312 -278.51989)
		(width 0.14478)
		(layer "In4.Cu")
		(net "M_D_CPU0_SB_CB<0>")
	)
	(segment
		(start 294.593772 -278.904192)
		(end 294.822118 -278.904192)
		(width 0.14478)
		(layer "In4.Cu")
		(net "M_D_CPU0_SB_CB<0>")
	)
	(segment
		(start 337.744054 -272.788634)
		(end 337.752436 -272.79346)
		(width 0.0889)
		(layer "In4.Cu")
		(net "M_D_CPU0_SB_CB<0>")
	)
	(segment
		(start 311.356756 -274.163536)
		(end 311.356756 -273.935444)
		(width 0.14478)
		(layer "In4.Cu")
		(net "M_D_CPU0_SB_CB<0>")
	)
	(segment
		(start 329.284076 -272.788634)
		(end 329.292458 -272.79346)
		(width 0.0889)
		(layer "In4.Cu")
		(net "M_D_CPU0_SB_CB<0>")
	)
	(segment
		(start 305.820064 -277.6601)
		(end 306.043076 -277.6601)
		(width 0.14478)
		(layer "In4.Cu")
		(net "M_D_CPU0_SB_CB<0>")
	)
	(arc
		(start 326.386952 -272.72996)
		(mid 326.423279 -272.761773)
		(end 326.463406 -272.788634)
		(width 0.0889)
		(layer "In4.Cu")
		(net "M_D_CPU0_SB_CB<0>")
	)
	(arc
		(start 330.598018 -272.788634)
		(mid 330.880974 -272.712457)
		(end 331.16393 -272.788634)
		(width 0.0889)
		(layer "In4.Cu")
		(net "M_D_CPU0_SB_CB<0>")
	)
	(arc
		(start 333.41818 -272.788634)
		(mid 333.701136 -272.712457)
		(end 333.984092 -272.788634)
		(width 0.0889)
		(layer "In4.Cu")
		(net "M_D_CPU0_SB_CB<0>")
	)
	(arc
		(start 334.924146 -272.788634)
		(mid 335.11109 -272.838889)
		(end 335.298034 -272.788634)
		(width 0.0889)
		(layer "In4.Cu")
		(net "M_D_CPU0_SB_CB<0>")
	)
	(arc
		(start 338.69249 -272.79346)
		(mid 338.84536 -272.838101)
		(end 339.002878 -272.814796)
		(width 0.0889)
		(layer "In4.Cu")
		(net "M_D_CPU0_SB_CB<0>")
	)
	(arc
		(start 330.22413 -272.788634)
		(mid 330.411074 -272.838889)
		(end 330.598018 -272.788634)
		(width 0.0889)
		(layer "In4.Cu")
		(net "M_D_CPU0_SB_CB<0>")
	)
	(arc
		(start 331.538072 -272.788634)
		(mid 331.821028 -272.712457)
		(end 332.103984 -272.788634)
		(width 0.0889)
		(layer "In4.Cu")
		(net "M_D_CPU0_SB_CB<0>")
	)
	(arc
		(start 333.992474 -272.79346)
		(mid 334.175982 -272.838954)
		(end 334.358234 -272.788634)
		(width 0.0889)
		(layer "In4.Cu")
		(net "M_D_CPU0_SB_CB<0>")
	)
	(arc
		(start 336.804 -272.788634)
		(mid 336.986251 -272.838984)
		(end 337.16976 -272.79346)
		(width 0.0889)
		(layer "In4.Cu")
		(net "M_D_CPU0_SB_CB<0>")
	)
	(arc
		(start 332.103984 -272.788634)
		(mid 332.286235 -272.838984)
		(end 332.469744 -272.79346)
		(width 0.0889)
		(layer "In4.Cu")
		(net "M_D_CPU0_SB_CB<0>")
	)
	(arc
		(start 328.718164 -272.788634)
		(mid 329.00112 -272.712457)
		(end 329.284076 -272.788634)
		(width 0.0889)
		(layer "In4.Cu")
		(net "M_D_CPU0_SB_CB<0>")
	)
	(arc
		(start 337.178142 -272.788634)
		(mid 337.461098 -272.712457)
		(end 337.744054 -272.788634)
		(width 0.0889)
		(layer "In4.Cu")
		(net "M_D_CPU0_SB_CB<0>")
	)
	(arc
		(start 328.344022 -272.788634)
		(mid 328.526273 -272.838984)
		(end 328.709782 -272.79346)
		(width 0.0889)
		(layer "In4.Cu")
		(net "M_D_CPU0_SB_CB<0>")
	)
	(arc
		(start 338.118196 -272.788634)
		(mid 338.401152 -272.712457)
		(end 338.684108 -272.788634)
		(width 0.0889)
		(layer "In4.Cu")
		(net "M_D_CPU0_SB_CB<0>")
	)
	(arc
		(start 335.863946 -272.788634)
		(mid 336.046197 -272.838984)
		(end 336.229706 -272.79346)
		(width 0.0889)
		(layer "In4.Cu")
		(net "M_D_CPU0_SB_CB<0>")
	)
	(arc
		(start 333.05242 -272.79346)
		(mid 333.235928 -272.838954)
		(end 333.41818 -272.788634)
		(width 0.0889)
		(layer "In4.Cu")
		(net "M_D_CPU0_SB_CB<0>")
	)
	(arc
		(start 329.658218 -272.788634)
		(mid 329.941174 -272.712457)
		(end 330.22413 -272.788634)
		(width 0.0889)
		(layer "In4.Cu")
		(net "M_D_CPU0_SB_CB<0>")
	)
	(arc
		(start 327.411588 -272.79346)
		(mid 327.59535 -272.839076)
		(end 327.777856 -272.788634)
		(width 0.0889)
		(layer "In4.Cu")
		(net "M_D_CPU0_SB_CB<0>")
	)
	(arc
		(start 327.777856 -272.788634)
		(mid 328.054923 -272.712363)
		(end 328.333608 -272.782538)
		(width 0.0889)
		(layer "In4.Cu")
		(net "M_D_CPU0_SB_CB<0>")
	)
	(arc
		(start 332.478126 -272.788634)
		(mid 332.761082 -272.712457)
		(end 333.044038 -272.788634)
		(width 0.0889)
		(layer "In4.Cu")
		(net "M_D_CPU0_SB_CB<0>")
	)
	(arc
		(start 331.16393 -272.788634)
		(mid 331.346181 -272.838984)
		(end 331.52969 -272.79346)
		(width 0.0889)
		(layer "In4.Cu")
		(net "M_D_CPU0_SB_CB<0>")
	)
	(arc
		(start 329.292458 -272.79346)
		(mid 329.475966 -272.838954)
		(end 329.658218 -272.788634)
		(width 0.0889)
		(layer "In4.Cu")
		(net "M_D_CPU0_SB_CB<0>")
	)
	(arc
		(start 337.752436 -272.79346)
		(mid 337.935944 -272.838954)
		(end 338.118196 -272.788634)
		(width 0.0889)
		(layer "In4.Cu")
		(net "M_D_CPU0_SB_CB<0>")
	)
	(arc
		(start 326.46366 -272.788634)
		(mid 326.640288 -272.838867)
		(end 326.819514 -272.798794)
		(width 0.0889)
		(layer "In4.Cu")
		(net "M_D_CPU0_SB_CB<0>")
	)
	(arc
		(start 326.84339 -272.785078)
		(mid 327.123779 -272.712409)
		(end 327.403206 -272.788634)
		(width 0.0889)
		(layer "In4.Cu")
		(net "M_D_CPU0_SB_CB<0>")
	)
	(arc
		(start 336.238088 -272.788634)
		(mid 336.521044 -272.712457)
		(end 336.804 -272.788634)
		(width 0.0889)
		(layer "In4.Cu")
		(net "M_D_CPU0_SB_CB<0>")
	)
	(arc
		(start 335.298034 -272.788634)
		(mid 335.58099 -272.712457)
		(end 335.863946 -272.788634)
		(width 0.0889)
		(layer "In4.Cu")
		(net "M_D_CPU0_SB_CB<0>")
	)
	(arc
		(start 334.358234 -272.788634)
		(mid 334.64119 -272.712457)
		(end 334.924146 -272.788634)
		(width 0.0889)
		(layer "In4.Cu")
		(net "M_D_CPU0_SB_CB<0>")
	)
	(segment
		(start 339.337904 -264.100056)
		(end 338.871052 -264.365994)
		(width 0.10668)
		(layer "F.Cu")
		(net "M_D_CPU0_SB_CA<6>")
	)
	(segment
		(start 304.060352 -266.08151)
		(end 304.295302 -266.08151)
		(width 0.14478)
		(layer "In4.Cu")
		(net "M_D_CPU0_SB_CA<6>")
	)
	(segment
		(start 300.883066 -266.08151)
		(end 301.204376 -265.7602)
		(width 0.14478)
		(layer "In4.Cu")
		(net "M_D_CPU0_SB_CA<6>")
	)
	(segment
		(start 284.736032 -266.185142)
		(end 285.160974 -265.7602)
		(width 0.14478)
		(layer "In4.Cu")
		(net "M_D_CPU0_SB_CA<6>")
	)
	(segment
		(start 286.95396 -266.08151)
		(end 287.18891 -266.08151)
		(width 0.14478)
		(layer "In4.Cu")
		(net "M_D_CPU0_SB_CA<6>")
	)
	(segment
		(start 289.737038 -265.7602)
		(end 290.058348 -266.08151)
		(width 0.14478)
		(layer "In4.Cu")
		(net "M_D_CPU0_SB_CA<6>")
	)
	(segment
		(start 294.392096 -266.08151)
		(end 294.713406 -265.7602)
		(width 0.14478)
		(layer "In4.Cu")
		(net "M_D_CPU0_SB_CA<6>")
	)
	(segment
		(start 304.616612 -265.7602)
		(end 304.851562 -265.7602)
		(width 0.14478)
		(layer "In4.Cu")
		(net "M_D_CPU0_SB_CA<6>")
	)
	(segment
		(start 326.837802 -264.68832)
		(end 326.84339 -264.685018)
		(width 0.0889)
		(layer "In4.Cu")
		(net "M_D_CPU0_SB_CA<6>")
	)
	(segment
		(start 307.397912 -266.08151)
		(end 307.632862 -266.08151)
		(width 0.14478)
		(layer "In4.Cu")
		(net "M_D_CPU0_SB_CA<6>")
	)
	(segment
		(start 293.835836 -265.7602)
		(end 294.157146 -266.08151)
		(width 0.14478)
		(layer "In4.Cu")
		(net "M_D_CPU0_SB_CA<6>")
	)
	(segment
		(start 290.614608 -265.7602)
		(end 290.849558 -265.7602)
		(width 0.14478)
		(layer "In4.Cu")
		(net "M_D_CPU0_SB_CA<6>")
	)
	(segment
		(start 337.16976 -264.6934)
		(end 337.178142 -264.688574)
		(width 0.0889)
		(layer "In4.Cu")
		(net "M_D_CPU0_SB_CA<6>")
	)
	(segment
		(start 285.52013 -265.7602)
		(end 285.84144 -266.08151)
		(width 0.14478)
		(layer "In4.Cu")
		(net "M_D_CPU0_SB_CA<6>")
	)
	(segment
		(start 339.02523 -264.631424)
		(end 338.871052 -264.365994)
		(width 0.0889)
		(layer "In4.Cu")
		(net "M_D_CPU0_SB_CA<6>")
	)
	(segment
		(start 298.360084 -265.7602)
		(end 298.681394 -266.08151)
		(width 0.14478)
		(layer "In4.Cu")
		(net "M_D_CPU0_SB_CA<6>")
	)
	(segment
		(start 336.229706 -264.6934)
		(end 336.238088 -264.688574)
		(width 0.0889)
		(layer "In4.Cu")
		(net "M_D_CPU0_SB_CA<6>")
	)
	(segment
		(start 305.172872 -266.08151)
		(end 305.407822 -266.08151)
		(width 0.14478)
		(layer "In4.Cu")
		(net "M_D_CPU0_SB_CA<6>")
	)
	(segment
		(start 291.405818 -266.08151)
		(end 291.727128 -265.7602)
		(width 0.14478)
		(layer "In4.Cu")
		(net "M_D_CPU0_SB_CA<6>")
	)
	(segment
		(start 305.964082 -265.7602)
		(end 306.285392 -266.08151)
		(width 0.14478)
		(layer "In4.Cu")
		(net "M_D_CPU0_SB_CA<6>")
	)
	(segment
		(start 328.709782 -264.6934)
		(end 328.718164 -264.688574)
		(width 0.0889)
		(layer "In4.Cu")
		(net "M_D_CPU0_SB_CA<6>")
	)
	(segment
		(start 287.18891 -266.08151)
		(end 287.51022 -265.7602)
		(width 0.14478)
		(layer "In4.Cu")
		(net "M_D_CPU0_SB_CA<6>")
	)
	(segment
		(start 327.403206 -264.688574)
		(end 327.411588 -264.6934)
		(width 0.0889)
		(layer "In4.Cu")
		(net "M_D_CPU0_SB_CA<6>")
	)
	(segment
		(start 297.247564 -265.7602)
		(end 297.568874 -266.08151)
		(width 0.14478)
		(layer "In4.Cu")
		(net "M_D_CPU0_SB_CA<6>")
	)
	(segment
		(start 291.170868 -266.08151)
		(end 291.405818 -266.08151)
		(width 0.14478)
		(layer "In4.Cu")
		(net "M_D_CPU0_SB_CA<6>")
	)
	(segment
		(start 287.51022 -265.7602)
		(end 288.624518 -265.7602)
		(width 0.14478)
		(layer "In4.Cu")
		(net "M_D_CPU0_SB_CA<6>")
	)
	(segment
		(start 299.237654 -265.7602)
		(end 300.326806 -265.7602)
		(width 0.14478)
		(layer "In4.Cu")
		(net "M_D_CPU0_SB_CA<6>")
	)
	(segment
		(start 306.841652 -265.7602)
		(end 307.076602 -265.7602)
		(width 0.14478)
		(layer "In4.Cu")
		(net "M_D_CPU0_SB_CA<6>")
	)
	(segment
		(start 286.3977 -265.7602)
		(end 286.63265 -265.7602)
		(width 0.14478)
		(layer "In4.Cu")
		(net "M_D_CPU0_SB_CA<6>")
	)
	(segment
		(start 294.713406 -265.7602)
		(end 296.135044 -265.7602)
		(width 0.14478)
		(layer "In4.Cu")
		(net "M_D_CPU0_SB_CA<6>")
	)
	(segment
		(start 288.624518 -265.7602)
		(end 288.945828 -266.08151)
		(width 0.14478)
		(layer "In4.Cu")
		(net "M_D_CPU0_SB_CA<6>")
	)
	(segment
		(start 290.058348 -266.08151)
		(end 290.293298 -266.08151)
		(width 0.14478)
		(layer "In4.Cu")
		(net "M_D_CPU0_SB_CA<6>")
	)
	(segment
		(start 326.094344 -264.337292)
		(end 326.386952 -264.6299)
		(width 0.0889)
		(layer "In4.Cu")
		(net "M_D_CPU0_SB_CA<6>")
	)
	(segment
		(start 296.456354 -266.08151)
		(end 296.691304 -266.08151)
		(width 0.14478)
		(layer "In4.Cu")
		(net "M_D_CPU0_SB_CA<6>")
	)
	(segment
		(start 305.407822 -266.08151)
		(end 305.729132 -265.7602)
		(width 0.14478)
		(layer "In4.Cu")
		(net "M_D_CPU0_SB_CA<6>")
	)
	(segment
		(start 326.463406 -264.688574)
		(end 326.46366 -264.688574)
		(width 0.0889)
		(layer "In4.Cu")
		(net "M_D_CPU0_SB_CA<6>")
	)
	(segment
		(start 328.333608 -264.682478)
		(end 328.344022 -264.688574)
		(width 0.0889)
		(layer "In4.Cu")
		(net "M_D_CPU0_SB_CA<6>")
	)
	(segment
		(start 323.901054 -264.61974)
		(end 324.20179 -264.61974)
		(width 0.0889)
		(layer "In4.Cu")
		(net "M_D_CPU0_SB_CA<6>")
	)
	(segment
		(start 290.849558 -265.7602)
		(end 291.170868 -266.08151)
		(width 0.14478)
		(layer "In4.Cu")
		(net "M_D_CPU0_SB_CA<6>")
	)
	(segment
		(start 301.760636 -266.08151)
		(end 301.995586 -266.08151)
		(width 0.14478)
		(layer "In4.Cu")
		(net "M_D_CPU0_SB_CA<6>")
	)
	(segment
		(start 305.729132 -265.7602)
		(end 305.964082 -265.7602)
		(width 0.14478)
		(layer "In4.Cu")
		(net "M_D_CPU0_SB_CA<6>")
	)
	(segment
		(start 298.125134 -265.7602)
		(end 298.360084 -265.7602)
		(width 0.14478)
		(layer "In4.Cu")
		(net "M_D_CPU0_SB_CA<6>")
	)
	(segment
		(start 303.739042 -265.7602)
		(end 304.060352 -266.08151)
		(width 0.14478)
		(layer "In4.Cu")
		(net "M_D_CPU0_SB_CA<6>")
	)
	(segment
		(start 333.984092 -264.688574)
		(end 333.992474 -264.6934)
		(width 0.0889)
		(layer "In4.Cu")
		(net "M_D_CPU0_SB_CA<6>")
	)
	(segment
		(start 286.63265 -265.7602)
		(end 286.95396 -266.08151)
		(width 0.14478)
		(layer "In4.Cu")
		(net "M_D_CPU0_SB_CA<6>")
	)
	(segment
		(start 288.945828 -266.08151)
		(end 289.180778 -266.08151)
		(width 0.14478)
		(layer "In4.Cu")
		(net "M_D_CPU0_SB_CA<6>")
	)
	(segment
		(start 338.684108 -264.688574)
		(end 338.69249 -264.6934)
		(width 0.0889)
		(layer "In4.Cu")
		(net "M_D_CPU0_SB_CA<6>")
	)
	(segment
		(start 304.295302 -266.08151)
		(end 304.616612 -265.7602)
		(width 0.14478)
		(layer "In4.Cu")
		(net "M_D_CPU0_SB_CA<6>")
	)
	(segment
		(start 307.076602 -265.7602)
		(end 307.397912 -266.08151)
		(width 0.14478)
		(layer "In4.Cu")
		(net "M_D_CPU0_SB_CA<6>")
	)
	(segment
		(start 300.648116 -266.08151)
		(end 300.883066 -266.08151)
		(width 0.14478)
		(layer "In4.Cu")
		(net "M_D_CPU0_SB_CA<6>")
	)
	(segment
		(start 302.316896 -265.7602)
		(end 303.739042 -265.7602)
		(width 0.14478)
		(layer "In4.Cu")
		(net "M_D_CPU0_SB_CA<6>")
	)
	(segment
		(start 293.600886 -265.7602)
		(end 293.835836 -265.7602)
		(width 0.14478)
		(layer "In4.Cu")
		(net "M_D_CPU0_SB_CA<6>")
	)
	(segment
		(start 306.285392 -266.08151)
		(end 306.520342 -266.08151)
		(width 0.14478)
		(layer "In4.Cu")
		(net "M_D_CPU0_SB_CA<6>")
	)
	(segment
		(start 296.691304 -266.08151)
		(end 297.012614 -265.7602)
		(width 0.14478)
		(layer "In4.Cu")
		(net "M_D_CPU0_SB_CA<6>")
	)
	(segment
		(start 333.044038 -264.688574)
		(end 333.05242 -264.6934)
		(width 0.0889)
		(layer "In4.Cu")
		(net "M_D_CPU0_SB_CA<6>")
	)
	(segment
		(start 307.632862 -266.08151)
		(end 309.094632 -264.61974)
		(width 0.14478)
		(layer "In4.Cu")
		(net "M_D_CPU0_SB_CA<6>")
	)
	(segment
		(start 309.094632 -264.61974)
		(end 323.901054 -264.61974)
		(width 0.14478)
		(layer "In4.Cu")
		(net "M_D_CPU0_SB_CA<6>")
	)
	(segment
		(start 301.995586 -266.08151)
		(end 302.316896 -265.7602)
		(width 0.14478)
		(layer "In4.Cu")
		(net "M_D_CPU0_SB_CA<6>")
	)
	(segment
		(start 289.502088 -265.7602)
		(end 289.737038 -265.7602)
		(width 0.14478)
		(layer "In4.Cu")
		(net "M_D_CPU0_SB_CA<6>")
	)
	(segment
		(start 297.012614 -265.7602)
		(end 297.247564 -265.7602)
		(width 0.14478)
		(layer "In4.Cu")
		(net "M_D_CPU0_SB_CA<6>")
	)
	(segment
		(start 324.484238 -264.337292)
		(end 326.094344 -264.337292)
		(width 0.0889)
		(layer "In4.Cu")
		(net "M_D_CPU0_SB_CA<6>")
	)
	(segment
		(start 301.439326 -265.7602)
		(end 301.760636 -266.08151)
		(width 0.14478)
		(layer "In4.Cu")
		(net "M_D_CPU0_SB_CA<6>")
	)
	(segment
		(start 298.916344 -266.08151)
		(end 299.237654 -265.7602)
		(width 0.14478)
		(layer "In4.Cu")
		(net "M_D_CPU0_SB_CA<6>")
	)
	(segment
		(start 332.469744 -264.6934)
		(end 332.478126 -264.688574)
		(width 0.0889)
		(layer "In4.Cu")
		(net "M_D_CPU0_SB_CA<6>")
	)
	(segment
		(start 329.284076 -264.688574)
		(end 329.292458 -264.6934)
		(width 0.0889)
		(layer "In4.Cu")
		(net "M_D_CPU0_SB_CA<6>")
	)
	(segment
		(start 296.135044 -265.7602)
		(end 296.456354 -266.08151)
		(width 0.14478)
		(layer "In4.Cu")
		(net "M_D_CPU0_SB_CA<6>")
	)
	(segment
		(start 306.520342 -266.08151)
		(end 306.841652 -265.7602)
		(width 0.14478)
		(layer "In4.Cu")
		(net "M_D_CPU0_SB_CA<6>")
	)
	(segment
		(start 294.157146 -266.08151)
		(end 294.392096 -266.08151)
		(width 0.14478)
		(layer "In4.Cu")
		(net "M_D_CPU0_SB_CA<6>")
	)
	(segment
		(start 293.279576 -266.08151)
		(end 293.600886 -265.7602)
		(width 0.14478)
		(layer "In4.Cu")
		(net "M_D_CPU0_SB_CA<6>")
	)
	(segment
		(start 292.723316 -265.7602)
		(end 293.044626 -266.08151)
		(width 0.14478)
		(layer "In4.Cu")
		(net "M_D_CPU0_SB_CA<6>")
	)
	(segment
		(start 326.819514 -264.698734)
		(end 326.837802 -264.68832)
		(width 0.0889)
		(layer "In4.Cu")
		(net "M_D_CPU0_SB_CA<6>")
	)
	(segment
		(start 337.744054 -264.688574)
		(end 337.752436 -264.6934)
		(width 0.0889)
		(layer "In4.Cu")
		(net "M_D_CPU0_SB_CA<6>")
	)
	(segment
		(start 293.044626 -266.08151)
		(end 293.279576 -266.08151)
		(width 0.14478)
		(layer "In4.Cu")
		(net "M_D_CPU0_SB_CA<6>")
	)
	(segment
		(start 298.681394 -266.08151)
		(end 298.916344 -266.08151)
		(width 0.14478)
		(layer "In4.Cu")
		(net "M_D_CPU0_SB_CA<6>")
	)
	(segment
		(start 330.22413 -264.688574)
		(end 330.232512 -264.6934)
		(width 0.0889)
		(layer "In4.Cu")
		(net "M_D_CPU0_SB_CA<6>")
	)
	(segment
		(start 324.20179 -264.61974)
		(end 324.484238 -264.337292)
		(width 0.0889)
		(layer "In4.Cu")
		(net "M_D_CPU0_SB_CA<6>")
	)
	(segment
		(start 297.568874 -266.08151)
		(end 297.803824 -266.08151)
		(width 0.14478)
		(layer "In4.Cu")
		(net "M_D_CPU0_SB_CA<6>")
	)
	(segment
		(start 304.851562 -265.7602)
		(end 305.172872 -266.08151)
		(width 0.14478)
		(layer "In4.Cu")
		(net "M_D_CPU0_SB_CA<6>")
	)
	(segment
		(start 289.180778 -266.08151)
		(end 289.502088 -265.7602)
		(width 0.14478)
		(layer "In4.Cu")
		(net "M_D_CPU0_SB_CA<6>")
	)
	(segment
		(start 290.293298 -266.08151)
		(end 290.614608 -265.7602)
		(width 0.14478)
		(layer "In4.Cu")
		(net "M_D_CPU0_SB_CA<6>")
	)
	(segment
		(start 300.326806 -265.7602)
		(end 300.648116 -266.08151)
		(width 0.14478)
		(layer "In4.Cu")
		(net "M_D_CPU0_SB_CA<6>")
	)
	(segment
		(start 285.160974 -265.7602)
		(end 285.52013 -265.7602)
		(width 0.14478)
		(layer "In4.Cu")
		(net "M_D_CPU0_SB_CA<6>")
	)
	(segment
		(start 297.803824 -266.08151)
		(end 298.125134 -265.7602)
		(width 0.14478)
		(layer "In4.Cu")
		(net "M_D_CPU0_SB_CA<6>")
	)
	(segment
		(start 301.204376 -265.7602)
		(end 301.439326 -265.7602)
		(width 0.14478)
		(layer "In4.Cu")
		(net "M_D_CPU0_SB_CA<6>")
	)
	(segment
		(start 291.727128 -265.7602)
		(end 292.723316 -265.7602)
		(width 0.14478)
		(layer "In4.Cu")
		(net "M_D_CPU0_SB_CA<6>")
	)
	(segment
		(start 286.07639 -266.08151)
		(end 286.3977 -265.7602)
		(width 0.14478)
		(layer "In4.Cu")
		(net "M_D_CPU0_SB_CA<6>")
	)
	(segment
		(start 339.002878 -264.714736)
		(end 339.02523 -264.631424)
		(width 0.0889)
		(layer "In4.Cu")
		(net "M_D_CPU0_SB_CA<6>")
	)
	(segment
		(start 285.84144 -266.08151)
		(end 286.07639 -266.08151)
		(width 0.14478)
		(layer "In4.Cu")
		(net "M_D_CPU0_SB_CA<6>")
	)
	(arc
		(start 332.478126 -264.688574)
		(mid 332.761082 -264.612397)
		(end 333.044038 -264.688574)
		(width 0.0889)
		(layer "In4.Cu")
		(net "M_D_CPU0_SB_CA<6>")
	)
	(arc
		(start 334.924146 -264.688574)
		(mid 335.11109 -264.738829)
		(end 335.298034 -264.688574)
		(width 0.0889)
		(layer "In4.Cu")
		(net "M_D_CPU0_SB_CA<6>")
	)
	(arc
		(start 335.298034 -264.688574)
		(mid 335.58099 -264.612397)
		(end 335.863946 -264.688574)
		(width 0.0889)
		(layer "In4.Cu")
		(net "M_D_CPU0_SB_CA<6>")
	)
	(arc
		(start 331.164184 -264.688574)
		(mid 331.351128 -264.738829)
		(end 331.538072 -264.688574)
		(width 0.0889)
		(layer "In4.Cu")
		(net "M_D_CPU0_SB_CA<6>")
	)
	(arc
		(start 329.292458 -264.6934)
		(mid 329.475966 -264.738894)
		(end 329.658218 -264.688574)
		(width 0.0889)
		(layer "In4.Cu")
		(net "M_D_CPU0_SB_CA<6>")
	)
	(arc
		(start 333.992474 -264.6934)
		(mid 334.175982 -264.738894)
		(end 334.358234 -264.688574)
		(width 0.0889)
		(layer "In4.Cu")
		(net "M_D_CPU0_SB_CA<6>")
	)
	(arc
		(start 335.863946 -264.688574)
		(mid 336.046197 -264.738924)
		(end 336.229706 -264.6934)
		(width 0.0889)
		(layer "In4.Cu")
		(net "M_D_CPU0_SB_CA<6>")
	)
	(arc
		(start 327.411588 -264.6934)
		(mid 327.59535 -264.739016)
		(end 327.777856 -264.688574)
		(width 0.0889)
		(layer "In4.Cu")
		(net "M_D_CPU0_SB_CA<6>")
	)
	(arc
		(start 330.232512 -264.6934)
		(mid 330.41602 -264.738894)
		(end 330.598272 -264.688574)
		(width 0.0889)
		(layer "In4.Cu")
		(net "M_D_CPU0_SB_CA<6>")
	)
	(arc
		(start 326.386952 -264.6299)
		(mid 326.423279 -264.661713)
		(end 326.463406 -264.688574)
		(width 0.0889)
		(layer "In4.Cu")
		(net "M_D_CPU0_SB_CA<6>")
	)
	(arc
		(start 337.178142 -264.688574)
		(mid 337.461098 -264.612397)
		(end 337.744054 -264.688574)
		(width 0.0889)
		(layer "In4.Cu")
		(net "M_D_CPU0_SB_CA<6>")
	)
	(arc
		(start 338.118196 -264.688574)
		(mid 338.401152 -264.612397)
		(end 338.684108 -264.688574)
		(width 0.0889)
		(layer "In4.Cu")
		(net "M_D_CPU0_SB_CA<6>")
	)
	(arc
		(start 333.05242 -264.6934)
		(mid 333.235928 -264.738894)
		(end 333.41818 -264.688574)
		(width 0.0889)
		(layer "In4.Cu")
		(net "M_D_CPU0_SB_CA<6>")
	)
	(arc
		(start 331.538072 -264.688574)
		(mid 331.821028 -264.612397)
		(end 332.103984 -264.688574)
		(width 0.0889)
		(layer "In4.Cu")
		(net "M_D_CPU0_SB_CA<6>")
	)
	(arc
		(start 330.598272 -264.688574)
		(mid 330.881228 -264.612397)
		(end 331.164184 -264.688574)
		(width 0.0889)
		(layer "In4.Cu")
		(net "M_D_CPU0_SB_CA<6>")
	)
	(arc
		(start 327.777856 -264.688574)
		(mid 328.054923 -264.612303)
		(end 328.333608 -264.682478)
		(width 0.0889)
		(layer "In4.Cu")
		(net "M_D_CPU0_SB_CA<6>")
	)
	(arc
		(start 326.84339 -264.685018)
		(mid 327.123779 -264.612349)
		(end 327.403206 -264.688574)
		(width 0.0889)
		(layer "In4.Cu")
		(net "M_D_CPU0_SB_CA<6>")
	)
	(arc
		(start 326.46366 -264.688574)
		(mid 326.640288 -264.738807)
		(end 326.819514 -264.698734)
		(width 0.0889)
		(layer "In4.Cu")
		(net "M_D_CPU0_SB_CA<6>")
	)
	(arc
		(start 334.358234 -264.688574)
		(mid 334.64119 -264.612397)
		(end 334.924146 -264.688574)
		(width 0.0889)
		(layer "In4.Cu")
		(net "M_D_CPU0_SB_CA<6>")
	)
	(arc
		(start 336.238088 -264.688574)
		(mid 336.521044 -264.612397)
		(end 336.804 -264.688574)
		(width 0.0889)
		(layer "In4.Cu")
		(net "M_D_CPU0_SB_CA<6>")
	)
	(arc
		(start 336.804 -264.688574)
		(mid 336.986251 -264.738924)
		(end 337.16976 -264.6934)
		(width 0.0889)
		(layer "In4.Cu")
		(net "M_D_CPU0_SB_CA<6>")
	)
	(arc
		(start 328.718164 -264.688574)
		(mid 329.00112 -264.612397)
		(end 329.284076 -264.688574)
		(width 0.0889)
		(layer "In4.Cu")
		(net "M_D_CPU0_SB_CA<6>")
	)
	(arc
		(start 338.69249 -264.6934)
		(mid 338.84536 -264.738041)
		(end 339.002878 -264.714736)
		(width 0.0889)
		(layer "In4.Cu")
		(net "M_D_CPU0_SB_CA<6>")
	)
	(arc
		(start 333.41818 -264.688574)
		(mid 333.701136 -264.612397)
		(end 333.984092 -264.688574)
		(width 0.0889)
		(layer "In4.Cu")
		(net "M_D_CPU0_SB_CA<6>")
	)
	(arc
		(start 332.103984 -264.688574)
		(mid 332.286235 -264.738924)
		(end 332.469744 -264.6934)
		(width 0.0889)
		(layer "In4.Cu")
		(net "M_D_CPU0_SB_CA<6>")
	)
	(arc
		(start 337.752436 -264.6934)
		(mid 337.935944 -264.738894)
		(end 338.118196 -264.688574)
		(width 0.0889)
		(layer "In4.Cu")
		(net "M_D_CPU0_SB_CA<6>")
	)
	(arc
		(start 328.344022 -264.688574)
		(mid 328.526273 -264.738924)
		(end 328.709782 -264.6934)
		(width 0.0889)
		(layer "In4.Cu")
		(net "M_D_CPU0_SB_CA<6>")
	)
	(arc
		(start 329.658218 -264.688574)
		(mid 329.941174 -264.612397)
		(end 330.22413 -264.688574)
		(width 0.0889)
		(layer "In4.Cu")
		(net "M_D_CPU0_SB_CA<6>")
	)
	(segment
		(start 341.218012 -264.100056)
		(end 340.75116 -264.365994)
		(width 0.10668)
		(layer "F.Cu")
		(net "M_D_CPU0_SB_CA<5>")
	)
	(segment
		(start 324.300596 -263.992614)
		(end 327.589896 -263.992614)
		(width 0.0889)
		(layer "In4.Cu")
		(net "M_D_CPU0_SB_CA<5>")
	)
	(segment
		(start 333.984092 -264.043414)
		(end 333.992474 -264.038588)
		(width 0.0889)
		(layer "In4.Cu")
		(net "M_D_CPU0_SB_CA<5>")
	)
	(segment
		(start 340.596982 -264.100564)
		(end 340.75116 -264.365994)
		(width 0.0889)
		(layer "In4.Cu")
		(net "M_D_CPU0_SB_CA<5>")
	)
	(segment
		(start 324.12813 -264.16508)
		(end 324.300596 -263.992614)
		(width 0.0889)
		(layer "In4.Cu")
		(net "M_D_CPU0_SB_CA<5>")
	)
	(segment
		(start 331.52969 -264.038588)
		(end 331.538072 -264.043414)
		(width 0.0889)
		(layer "In4.Cu")
		(net "M_D_CPU0_SB_CA<5>")
	)
	(segment
		(start 332.469744 -264.038588)
		(end 332.478126 -264.043414)
		(width 0.0889)
		(layer "In4.Cu")
		(net "M_D_CPU0_SB_CA<5>")
	)
	(segment
		(start 340.500716 -264.075164)
		(end 340.596982 -264.100564)
		(width 0.0889)
		(layer "In4.Cu")
		(net "M_D_CPU0_SB_CA<5>")
	)
	(segment
		(start 329.284076 -264.043414)
		(end 329.292458 -264.038588)
		(width 0.0889)
		(layer "In4.Cu")
		(net "M_D_CPU0_SB_CA<5>")
	)
	(segment
		(start 280.635964 -265.335004)
		(end 281.060906 -264.910062)
		(width 0.14478)
		(layer "In4.Cu")
		(net "M_D_CPU0_SB_CA<5>")
	)
	(segment
		(start 336.229706 -264.038588)
		(end 336.238088 -264.043414)
		(width 0.0889)
		(layer "In4.Cu")
		(net "M_D_CPU0_SB_CA<5>")
	)
	(segment
		(start 338.684108 -264.043414)
		(end 338.69249 -264.038588)
		(width 0.0889)
		(layer "In4.Cu")
		(net "M_D_CPU0_SB_CA<5>")
	)
	(segment
		(start 307.955188 -264.910062)
		(end 308.70017 -264.16508)
		(width 0.14478)
		(layer "In4.Cu")
		(net "M_D_CPU0_SB_CA<5>")
	)
	(segment
		(start 328.32929 -264.05205)
		(end 328.344022 -264.043414)
		(width 0.0889)
		(layer "In4.Cu")
		(net "M_D_CPU0_SB_CA<5>")
	)
	(segment
		(start 337.744054 -264.043414)
		(end 337.752436 -264.038588)
		(width 0.0889)
		(layer "In4.Cu")
		(net "M_D_CPU0_SB_CA<5>")
	)
	(segment
		(start 337.16976 -264.038588)
		(end 337.178142 -264.043414)
		(width 0.0889)
		(layer "In4.Cu")
		(net "M_D_CPU0_SB_CA<5>")
	)
	(segment
		(start 333.044038 -264.043414)
		(end 333.05242 -264.038588)
		(width 0.0889)
		(layer "In4.Cu")
		(net "M_D_CPU0_SB_CA<5>")
	)
	(segment
		(start 281.060906 -264.910062)
		(end 307.955188 -264.910062)
		(width 0.14478)
		(layer "In4.Cu")
		(net "M_D_CPU0_SB_CA<5>")
	)
	(segment
		(start 308.70017 -264.16508)
		(end 323.861684 -264.16508)
		(width 0.14478)
		(layer "In4.Cu")
		(net "M_D_CPU0_SB_CA<5>")
	)
	(segment
		(start 328.709782 -264.038588)
		(end 328.718164 -264.043414)
		(width 0.0889)
		(layer "In4.Cu")
		(net "M_D_CPU0_SB_CA<5>")
	)
	(segment
		(start 323.861684 -264.16508)
		(end 324.12813 -264.16508)
		(width 0.0889)
		(layer "In4.Cu")
		(net "M_D_CPU0_SB_CA<5>")
	)
	(arc
		(start 337.752436 -264.038588)
		(mid 337.935944 -263.993094)
		(end 338.118196 -264.043414)
		(width 0.0889)
		(layer "In4.Cu")
		(net "M_D_CPU0_SB_CA<5>")
	)
	(arc
		(start 327.589896 -263.992614)
		(mid 327.687121 -264.005563)
		(end 327.777602 -264.043414)
		(width 0.0889)
		(layer "In4.Cu")
		(net "M_D_CPU0_SB_CA<5>")
	)
	(arc
		(start 338.69249 -264.038588)
		(mid 338.875998 -263.993094)
		(end 339.05825 -264.043414)
		(width 0.0889)
		(layer "In4.Cu")
		(net "M_D_CPU0_SB_CA<5>")
	)
	(arc
		(start 334.924146 -264.043414)
		(mid 335.11109 -263.993159)
		(end 335.298034 -264.043414)
		(width 0.0889)
		(layer "In4.Cu")
		(net "M_D_CPU0_SB_CA<5>")
	)
	(arc
		(start 337.178142 -264.043414)
		(mid 337.461098 -264.119591)
		(end 337.744054 -264.043414)
		(width 0.0889)
		(layer "In4.Cu")
		(net "M_D_CPU0_SB_CA<5>")
	)
	(arc
		(start 328.344022 -264.043414)
		(mid 328.526273 -263.993064)
		(end 328.709782 -264.038588)
		(width 0.0889)
		(layer "In4.Cu")
		(net "M_D_CPU0_SB_CA<5>")
	)
	(arc
		(start 333.05242 -264.038588)
		(mid 333.235928 -263.993094)
		(end 333.41818 -264.043414)
		(width 0.0889)
		(layer "In4.Cu")
		(net "M_D_CPU0_SB_CA<5>")
	)
	(arc
		(start 339.624162 -264.043414)
		(mid 339.811106 -263.993159)
		(end 339.99805 -264.043414)
		(width 0.0889)
		(layer "In4.Cu")
		(net "M_D_CPU0_SB_CA<5>")
	)
	(arc
		(start 327.777602 -264.043414)
		(mid 328.052308 -264.119778)
		(end 328.32929 -264.05205)
		(width 0.0889)
		(layer "In4.Cu")
		(net "M_D_CPU0_SB_CA<5>")
	)
	(arc
		(start 331.16393 -264.043414)
		(mid 331.346181 -263.993064)
		(end 331.52969 -264.038588)
		(width 0.0889)
		(layer "In4.Cu")
		(net "M_D_CPU0_SB_CA<5>")
	)
	(arc
		(start 335.863946 -264.043414)
		(mid 336.046197 -263.993064)
		(end 336.229706 -264.038588)
		(width 0.0889)
		(layer "In4.Cu")
		(net "M_D_CPU0_SB_CA<5>")
	)
	(arc
		(start 335.298034 -264.043414)
		(mid 335.58099 -264.119591)
		(end 335.863946 -264.043414)
		(width 0.0889)
		(layer "In4.Cu")
		(net "M_D_CPU0_SB_CA<5>")
	)
	(arc
		(start 333.992474 -264.038588)
		(mid 334.175982 -263.993094)
		(end 334.358234 -264.043414)
		(width 0.0889)
		(layer "In4.Cu")
		(net "M_D_CPU0_SB_CA<5>")
	)
	(arc
		(start 339.05825 -264.043414)
		(mid 339.341206 -264.119591)
		(end 339.624162 -264.043414)
		(width 0.0889)
		(layer "In4.Cu")
		(net "M_D_CPU0_SB_CA<5>")
	)
	(arc
		(start 329.292458 -264.038588)
		(mid 329.475966 -263.993094)
		(end 329.658218 -264.043414)
		(width 0.0889)
		(layer "In4.Cu")
		(net "M_D_CPU0_SB_CA<5>")
	)
	(arc
		(start 339.99805 -264.043414)
		(mid 340.245646 -264.118592)
		(end 340.500716 -264.075164)
		(width 0.0889)
		(layer "In4.Cu")
		(net "M_D_CPU0_SB_CA<5>")
	)
	(arc
		(start 332.103984 -264.043414)
		(mid 332.286235 -263.993064)
		(end 332.469744 -264.038588)
		(width 0.0889)
		(layer "In4.Cu")
		(net "M_D_CPU0_SB_CA<5>")
	)
	(arc
		(start 330.22413 -264.043414)
		(mid 330.411074 -263.993159)
		(end 330.598018 -264.043414)
		(width 0.0889)
		(layer "In4.Cu")
		(net "M_D_CPU0_SB_CA<5>")
	)
	(arc
		(start 336.238088 -264.043414)
		(mid 336.521044 -264.119591)
		(end 336.804 -264.043414)
		(width 0.0889)
		(layer "In4.Cu")
		(net "M_D_CPU0_SB_CA<5>")
	)
	(arc
		(start 336.804 -264.043414)
		(mid 336.986251 -263.993064)
		(end 337.16976 -264.038588)
		(width 0.0889)
		(layer "In4.Cu")
		(net "M_D_CPU0_SB_CA<5>")
	)
	(arc
		(start 332.478126 -264.043414)
		(mid 332.761082 -264.119591)
		(end 333.044038 -264.043414)
		(width 0.0889)
		(layer "In4.Cu")
		(net "M_D_CPU0_SB_CA<5>")
	)
	(arc
		(start 333.41818 -264.043414)
		(mid 333.701136 -264.119591)
		(end 333.984092 -264.043414)
		(width 0.0889)
		(layer "In4.Cu")
		(net "M_D_CPU0_SB_CA<5>")
	)
	(arc
		(start 338.118196 -264.043414)
		(mid 338.401152 -264.119591)
		(end 338.684108 -264.043414)
		(width 0.0889)
		(layer "In4.Cu")
		(net "M_D_CPU0_SB_CA<5>")
	)
	(arc
		(start 330.598018 -264.043414)
		(mid 330.880974 -264.119591)
		(end 331.16393 -264.043414)
		(width 0.0889)
		(layer "In4.Cu")
		(net "M_D_CPU0_SB_CA<5>")
	)
	(arc
		(start 334.358234 -264.043414)
		(mid 334.64119 -264.119591)
		(end 334.924146 -264.043414)
		(width 0.0889)
		(layer "In4.Cu")
		(net "M_D_CPU0_SB_CA<5>")
	)
	(arc
		(start 331.538072 -264.043414)
		(mid 331.821028 -264.119591)
		(end 332.103984 -264.043414)
		(width 0.0889)
		(layer "In4.Cu")
		(net "M_D_CPU0_SB_CA<5>")
	)
	(arc
		(start 329.658218 -264.043414)
		(mid 329.941174 -264.119591)
		(end 330.22413 -264.043414)
		(width 0.0889)
		(layer "In4.Cu")
		(net "M_D_CPU0_SB_CA<5>")
	)
	(arc
		(start 328.718164 -264.043414)
		(mid 329.00112 -264.119591)
		(end 329.284076 -264.043414)
		(width 0.0889)
		(layer "In4.Cu")
		(net "M_D_CPU0_SB_CA<5>")
	)
	(segment
		(start 340.747858 -263.29005)
		(end 340.281006 -263.555988)
		(width 0.10668)
		(layer "F.Cu")
		(net "M_D_CPU0_SB_CA<4>")
	)
	(segment
		(start 338.579714 -263.883394)
		(end 338.588096 -263.878568)
		(width 0.0889)
		(layer "In4.Cu")
		(net "M_D_CPU0_SB_CA<4>")
	)
	(segment
		(start 324.852284 -263.71042)
		(end 324.943978 -263.802114)
		(width 0.0889)
		(layer "In4.Cu")
		(net "M_D_CPU0_SB_CA<4>")
	)
	(segment
		(start 301.723552 -264.37971)
		(end 301.960026 -264.37971)
		(width 0.14478)
		(layer "In4.Cu")
		(net "M_D_CPU0_SB_CA<4>")
	)
	(segment
		(start 286.496506 -264.059924)
		(end 286.73298 -264.059924)
		(width 0.14478)
		(layer "In4.Cu")
		(net "M_D_CPU0_SB_CA<4>")
	)
	(segment
		(start 324.943978 -263.802114)
		(end 327.59015 -263.802114)
		(width 0.0889)
		(layer "In4.Cu")
		(net "M_D_CPU0_SB_CA<4>")
	)
	(segment
		(start 307.697124 -264.37971)
		(end 308.366414 -263.71042)
		(width 0.14478)
		(layer "In4.Cu")
		(net "M_D_CPU0_SB_CA<4>")
	)
	(segment
		(start 299.038264 -264.37971)
		(end 299.35805 -264.059924)
		(width 0.14478)
		(layer "In4.Cu")
		(net "M_D_CPU0_SB_CA<4>")
	)
	(segment
		(start 306.584604 -264.37971)
		(end 306.90439 -264.059924)
		(width 0.14478)
		(layer "In4.Cu")
		(net "M_D_CPU0_SB_CA<4>")
	)
	(segment
		(start 304.67935 -264.059924)
		(end 304.915824 -264.059924)
		(width 0.14478)
		(layer "In4.Cu")
		(net "M_D_CPU0_SB_CA<4>")
	)
	(segment
		(start 285.62046 -264.059924)
		(end 285.940246 -264.37971)
		(width 0.14478)
		(layer "In4.Cu")
		(net "M_D_CPU0_SB_CA<4>")
	)
	(segment
		(start 340.094062 -263.878568)
		(end 340.102444 -263.883394)
		(width 0.0889)
		(layer "In4.Cu")
		(net "M_D_CPU0_SB_CA<4>")
	)
	(segment
		(start 302.279812 -264.059924)
		(end 303.803304 -264.059924)
		(width 0.14478)
		(layer "In4.Cu")
		(net "M_D_CPU0_SB_CA<4>")
	)
	(segment
		(start 287.052766 -264.37971)
		(end 287.28924 -264.37971)
		(width 0.14478)
		(layer "In4.Cu")
		(net "M_D_CPU0_SB_CA<4>")
	)
	(segment
		(start 304.359564 -264.37971)
		(end 304.67935 -264.059924)
		(width 0.14478)
		(layer "In4.Cu")
		(net "M_D_CPU0_SB_CA<4>")
	)
	(segment
		(start 303.803304 -264.059924)
		(end 304.12309 -264.37971)
		(width 0.14478)
		(layer "In4.Cu")
		(net "M_D_CPU0_SB_CA<4>")
	)
	(segment
		(start 290.279074 -264.37971)
		(end 290.59886 -264.059924)
		(width 0.14478)
		(layer "In4.Cu")
		(net "M_D_CPU0_SB_CA<4>")
	)
	(segment
		(start 305.79187 -264.059924)
		(end 306.028344 -264.059924)
		(width 0.14478)
		(layer "In4.Cu")
		(net "M_D_CPU0_SB_CA<4>")
	)
	(segment
		(start 340.435184 -263.821418)
		(end 340.281006 -263.555988)
		(width 0.0889)
		(layer "In4.Cu")
		(net "M_D_CPU0_SB_CA<4>")
	)
	(segment
		(start 306.90439 -264.059924)
		(end 307.140864 -264.059924)
		(width 0.14478)
		(layer "In4.Cu")
		(net "M_D_CPU0_SB_CA<4>")
	)
	(segment
		(start 292.943026 -264.37971)
		(end 293.1795 -264.37971)
		(width 0.14478)
		(layer "In4.Cu")
		(net "M_D_CPU0_SB_CA<4>")
	)
	(segment
		(start 323.892164 -263.71042)
		(end 324.852284 -263.71042)
		(width 0.0889)
		(layer "In4.Cu")
		(net "M_D_CPU0_SB_CA<4>")
	)
	(segment
		(start 328.239882 -263.883394)
		(end 328.248264 -263.878568)
		(width 0.0889)
		(layer "In4.Cu")
		(net "M_D_CPU0_SB_CA<4>")
	)
	(segment
		(start 293.499286 -264.059924)
		(end 293.73576 -264.059924)
		(width 0.14478)
		(layer "In4.Cu")
		(net "M_D_CPU0_SB_CA<4>")
	)
	(segment
		(start 299.35805 -264.059924)
		(end 300.291246 -264.059924)
		(width 0.14478)
		(layer "In4.Cu")
		(net "M_D_CPU0_SB_CA<4>")
	)
	(segment
		(start 333.879698 -263.883394)
		(end 333.88808 -263.878568)
		(width 0.0889)
		(layer "In4.Cu")
		(net "M_D_CPU0_SB_CA<4>")
	)
	(segment
		(start 294.055546 -264.37971)
		(end 294.29202 -264.37971)
		(width 0.14478)
		(layer "In4.Cu")
		(net "M_D_CPU0_SB_CA<4>")
	)
	(segment
		(start 289.722814 -264.059924)
		(end 290.0426 -264.37971)
		(width 0.14478)
		(layer "In4.Cu")
		(net "M_D_CPU0_SB_CA<4>")
	)
	(segment
		(start 301.167292 -264.059924)
		(end 301.403766 -264.059924)
		(width 0.14478)
		(layer "In4.Cu")
		(net "M_D_CPU0_SB_CA<4>")
	)
	(segment
		(start 297.369484 -264.059924)
		(end 297.68927 -264.37971)
		(width 0.14478)
		(layer "In4.Cu")
		(net "M_D_CPU0_SB_CA<4>")
	)
	(segment
		(start 293.1795 -264.37971)
		(end 293.499286 -264.059924)
		(width 0.14478)
		(layer "In4.Cu")
		(net "M_D_CPU0_SB_CA<4>")
	)
	(segment
		(start 298.24553 -264.059924)
		(end 298.482004 -264.059924)
		(width 0.14478)
		(layer "In4.Cu")
		(net "M_D_CPU0_SB_CA<4>")
	)
	(segment
		(start 290.59886 -264.059924)
		(end 290.835334 -264.059924)
		(width 0.14478)
		(layer "In4.Cu")
		(net "M_D_CPU0_SB_CA<4>")
	)
	(segment
		(start 287.609026 -264.059924)
		(end 288.610294 -264.059924)
		(width 0.14478)
		(layer "In4.Cu")
		(net "M_D_CPU0_SB_CA<4>")
	)
	(segment
		(start 300.291246 -264.059924)
		(end 300.611032 -264.37971)
		(width 0.14478)
		(layer "In4.Cu")
		(net "M_D_CPU0_SB_CA<4>")
	)
	(segment
		(start 291.71138 -264.059924)
		(end 292.62324 -264.059924)
		(width 0.14478)
		(layer "In4.Cu")
		(net "M_D_CPU0_SB_CA<4>")
	)
	(segment
		(start 285.161228 -264.059924)
		(end 285.62046 -264.059924)
		(width 0.14478)
		(layer "In4.Cu")
		(net "M_D_CPU0_SB_CA<4>")
	)
	(segment
		(start 296.57675 -264.37971)
		(end 296.813224 -264.37971)
		(width 0.14478)
		(layer "In4.Cu")
		(net "M_D_CPU0_SB_CA<4>")
	)
	(segment
		(start 286.73298 -264.059924)
		(end 287.052766 -264.37971)
		(width 0.14478)
		(layer "In4.Cu")
		(net "M_D_CPU0_SB_CA<4>")
	)
	(segment
		(start 307.46065 -264.37971)
		(end 307.697124 -264.37971)
		(width 0.14478)
		(layer "In4.Cu")
		(net "M_D_CPU0_SB_CA<4>")
	)
	(segment
		(start 304.12309 -264.37971)
		(end 304.359564 -264.37971)
		(width 0.14478)
		(layer "In4.Cu")
		(net "M_D_CPU0_SB_CA<4>")
	)
	(segment
		(start 293.73576 -264.059924)
		(end 294.055546 -264.37971)
		(width 0.14478)
		(layer "In4.Cu")
		(net "M_D_CPU0_SB_CA<4>")
	)
	(segment
		(start 290.0426 -264.37971)
		(end 290.279074 -264.37971)
		(width 0.14478)
		(layer "In4.Cu")
		(net "M_D_CPU0_SB_CA<4>")
	)
	(segment
		(start 297.925744 -264.37971)
		(end 298.24553 -264.059924)
		(width 0.14478)
		(layer "In4.Cu")
		(net "M_D_CPU0_SB_CA<4>")
	)
	(segment
		(start 297.13301 -264.059924)
		(end 297.369484 -264.059924)
		(width 0.14478)
		(layer "In4.Cu")
		(net "M_D_CPU0_SB_CA<4>")
	)
	(segment
		(start 304.915824 -264.059924)
		(end 305.23561 -264.37971)
		(width 0.14478)
		(layer "In4.Cu")
		(net "M_D_CPU0_SB_CA<4>")
	)
	(segment
		(start 305.472084 -264.37971)
		(end 305.79187 -264.059924)
		(width 0.14478)
		(layer "In4.Cu")
		(net "M_D_CPU0_SB_CA<4>")
	)
	(segment
		(start 288.610294 -264.059924)
		(end 288.93008 -264.37971)
		(width 0.14478)
		(layer "In4.Cu")
		(net "M_D_CPU0_SB_CA<4>")
	)
	(segment
		(start 287.28924 -264.37971)
		(end 287.609026 -264.059924)
		(width 0.14478)
		(layer "In4.Cu")
		(net "M_D_CPU0_SB_CA<4>")
	)
	(segment
		(start 291.15512 -264.37971)
		(end 291.391594 -264.37971)
		(width 0.14478)
		(layer "In4.Cu")
		(net "M_D_CPU0_SB_CA<4>")
	)
	(segment
		(start 301.403766 -264.059924)
		(end 301.723552 -264.37971)
		(width 0.14478)
		(layer "In4.Cu")
		(net "M_D_CPU0_SB_CA<4>")
	)
	(segment
		(start 336.3341 -263.878568)
		(end 336.342482 -263.883394)
		(width 0.0889)
		(layer "In4.Cu")
		(net "M_D_CPU0_SB_CA<4>")
	)
	(segment
		(start 335.394046 -263.878568)
		(end 335.402428 -263.883394)
		(width 0.0889)
		(layer "In4.Cu")
		(net "M_D_CPU0_SB_CA<4>")
	)
	(segment
		(start 305.23561 -264.37971)
		(end 305.472084 -264.37971)
		(width 0.14478)
		(layer "In4.Cu")
		(net "M_D_CPU0_SB_CA<4>")
	)
	(segment
		(start 300.611032 -264.37971)
		(end 300.847506 -264.37971)
		(width 0.14478)
		(layer "In4.Cu")
		(net "M_D_CPU0_SB_CA<4>")
	)
	(segment
		(start 294.29202 -264.37971)
		(end 294.611806 -264.059924)
		(width 0.14478)
		(layer "In4.Cu")
		(net "M_D_CPU0_SB_CA<4>")
	)
	(segment
		(start 307.140864 -264.059924)
		(end 307.46065 -264.37971)
		(width 0.14478)
		(layer "In4.Cu")
		(net "M_D_CPU0_SB_CA<4>")
	)
	(segment
		(start 289.48634 -264.059924)
		(end 289.722814 -264.059924)
		(width 0.14478)
		(layer "In4.Cu")
		(net "M_D_CPU0_SB_CA<4>")
	)
	(segment
		(start 301.960026 -264.37971)
		(end 302.279812 -264.059924)
		(width 0.14478)
		(layer "In4.Cu")
		(net "M_D_CPU0_SB_CA<4>")
	)
	(segment
		(start 308.366414 -263.71042)
		(end 323.892164 -263.71042)
		(width 0.14478)
		(layer "In4.Cu")
		(net "M_D_CPU0_SB_CA<4>")
	)
	(segment
		(start 334.819752 -263.883394)
		(end 334.828134 -263.878568)
		(width 0.0889)
		(layer "In4.Cu")
		(net "M_D_CPU0_SB_CA<4>")
	)
	(segment
		(start 291.391594 -264.37971)
		(end 291.71138 -264.059924)
		(width 0.14478)
		(layer "In4.Cu")
		(net "M_D_CPU0_SB_CA<4>")
	)
	(segment
		(start 339.519768 -263.883394)
		(end 339.52815 -263.878568)
		(width 0.0889)
		(layer "In4.Cu")
		(net "M_D_CPU0_SB_CA<4>")
	)
	(segment
		(start 286.17672 -264.37971)
		(end 286.496506 -264.059924)
		(width 0.14478)
		(layer "In4.Cu")
		(net "M_D_CPU0_SB_CA<4>")
	)
	(segment
		(start 331.634084 -263.878568)
		(end 331.642466 -263.883394)
		(width 0.0889)
		(layer "In4.Cu")
		(net "M_D_CPU0_SB_CA<4>")
	)
	(segment
		(start 296.256964 -264.059924)
		(end 296.57675 -264.37971)
		(width 0.14478)
		(layer "In4.Cu")
		(net "M_D_CPU0_SB_CA<4>")
	)
	(segment
		(start 298.80179 -264.37971)
		(end 299.038264 -264.37971)
		(width 0.14478)
		(layer "In4.Cu")
		(net "M_D_CPU0_SB_CA<4>")
	)
	(segment
		(start 297.68927 -264.37971)
		(end 297.925744 -264.37971)
		(width 0.14478)
		(layer "In4.Cu")
		(net "M_D_CPU0_SB_CA<4>")
	)
	(segment
		(start 289.166554 -264.37971)
		(end 289.48634 -264.059924)
		(width 0.14478)
		(layer "In4.Cu")
		(net "M_D_CPU0_SB_CA<4>")
	)
	(segment
		(start 292.62324 -264.059924)
		(end 292.943026 -264.37971)
		(width 0.14478)
		(layer "In4.Cu")
		(net "M_D_CPU0_SB_CA<4>")
	)
	(segment
		(start 290.835334 -264.059924)
		(end 291.15512 -264.37971)
		(width 0.14478)
		(layer "In4.Cu")
		(net "M_D_CPU0_SB_CA<4>")
	)
	(segment
		(start 296.813224 -264.37971)
		(end 297.13301 -264.059924)
		(width 0.14478)
		(layer "In4.Cu")
		(net "M_D_CPU0_SB_CA<4>")
	)
	(segment
		(start 300.847506 -264.37971)
		(end 301.167292 -264.059924)
		(width 0.14478)
		(layer "In4.Cu")
		(net "M_D_CPU0_SB_CA<4>")
	)
	(segment
		(start 285.940246 -264.37971)
		(end 286.17672 -264.37971)
		(width 0.14478)
		(layer "In4.Cu")
		(net "M_D_CPU0_SB_CA<4>")
	)
	(segment
		(start 298.482004 -264.059924)
		(end 298.80179 -264.37971)
		(width 0.14478)
		(layer "In4.Cu")
		(net "M_D_CPU0_SB_CA<4>")
	)
	(segment
		(start 330.69403 -263.878568)
		(end 330.702412 -263.883394)
		(width 0.0889)
		(layer "In4.Cu")
		(net "M_D_CPU0_SB_CA<4>")
	)
	(segment
		(start 284.736032 -264.48512)
		(end 285.161228 -264.059924)
		(width 0.14478)
		(layer "In4.Cu")
		(net "M_D_CPU0_SB_CA<4>")
	)
	(segment
		(start 306.34813 -264.37971)
		(end 306.584604 -264.37971)
		(width 0.14478)
		(layer "In4.Cu")
		(net "M_D_CPU0_SB_CA<4>")
	)
	(segment
		(start 340.412832 -263.90473)
		(end 340.435184 -263.821418)
		(width 0.0889)
		(layer "In4.Cu")
		(net "M_D_CPU0_SB_CA<4>")
	)
	(segment
		(start 294.611806 -264.059924)
		(end 296.256964 -264.059924)
		(width 0.14478)
		(layer "In4.Cu")
		(net "M_D_CPU0_SB_CA<4>")
	)
	(segment
		(start 306.028344 -264.059924)
		(end 306.34813 -264.37971)
		(width 0.14478)
		(layer "In4.Cu")
		(net "M_D_CPU0_SB_CA<4>")
	)
	(segment
		(start 288.93008 -264.37971)
		(end 289.166554 -264.37971)
		(width 0.14478)
		(layer "In4.Cu")
		(net "M_D_CPU0_SB_CA<4>")
	)
	(segment
		(start 330.119736 -263.883394)
		(end 330.128118 -263.878568)
		(width 0.0889)
		(layer "In4.Cu")
		(net "M_D_CPU0_SB_CA<4>")
	)
	(arc
		(start 327.873614 -263.878568)
		(mid 328.056119 -263.929045)
		(end 328.239882 -263.883394)
		(width 0.0889)
		(layer "In4.Cu")
		(net "M_D_CPU0_SB_CA<4>")
	)
	(arc
		(start 331.068172 -263.878568)
		(mid 331.351128 -263.802391)
		(end 331.634084 -263.878568)
		(width 0.0889)
		(layer "In4.Cu")
		(net "M_D_CPU0_SB_CA<4>")
	)
	(arc
		(start 337.274154 -263.878568)
		(mid 337.461098 -263.928823)
		(end 337.648042 -263.878568)
		(width 0.0889)
		(layer "In4.Cu")
		(net "M_D_CPU0_SB_CA<4>")
	)
	(arc
		(start 328.248264 -263.878568)
		(mid 328.53122 -263.802391)
		(end 328.814176 -263.878568)
		(width 0.0889)
		(layer "In4.Cu")
		(net "M_D_CPU0_SB_CA<4>")
	)
	(arc
		(start 335.402428 -263.883394)
		(mid 335.585936 -263.928888)
		(end 335.768188 -263.878568)
		(width 0.0889)
		(layer "In4.Cu")
		(net "M_D_CPU0_SB_CA<4>")
	)
	(arc
		(start 331.642466 -263.883394)
		(mid 331.825974 -263.928888)
		(end 332.008226 -263.878568)
		(width 0.0889)
		(layer "In4.Cu")
		(net "M_D_CPU0_SB_CA<4>")
	)
	(arc
		(start 336.342482 -263.883394)
		(mid 336.52599 -263.928888)
		(end 336.708242 -263.878568)
		(width 0.0889)
		(layer "In4.Cu")
		(net "M_D_CPU0_SB_CA<4>")
	)
	(arc
		(start 332.574138 -263.878568)
		(mid 332.761082 -263.928823)
		(end 332.948026 -263.878568)
		(width 0.0889)
		(layer "In4.Cu")
		(net "M_D_CPU0_SB_CA<4>")
	)
	(arc
		(start 338.213954 -263.878568)
		(mid 338.396205 -263.928918)
		(end 338.579714 -263.883394)
		(width 0.0889)
		(layer "In4.Cu")
		(net "M_D_CPU0_SB_CA<4>")
	)
	(arc
		(start 333.88808 -263.878568)
		(mid 334.171036 -263.802391)
		(end 334.453992 -263.878568)
		(width 0.0889)
		(layer "In4.Cu")
		(net "M_D_CPU0_SB_CA<4>")
	)
	(arc
		(start 330.702412 -263.883394)
		(mid 330.88592 -263.928888)
		(end 331.068172 -263.878568)
		(width 0.0889)
		(layer "In4.Cu")
		(net "M_D_CPU0_SB_CA<4>")
	)
	(arc
		(start 329.753976 -263.878568)
		(mid 329.936227 -263.928918)
		(end 330.119736 -263.883394)
		(width 0.0889)
		(layer "In4.Cu")
		(net "M_D_CPU0_SB_CA<4>")
	)
	(arc
		(start 330.128118 -263.878568)
		(mid 330.411074 -263.802391)
		(end 330.69403 -263.878568)
		(width 0.0889)
		(layer "In4.Cu")
		(net "M_D_CPU0_SB_CA<4>")
	)
	(arc
		(start 334.453992 -263.878568)
		(mid 334.636243 -263.928918)
		(end 334.819752 -263.883394)
		(width 0.0889)
		(layer "In4.Cu")
		(net "M_D_CPU0_SB_CA<4>")
	)
	(arc
		(start 335.768188 -263.878568)
		(mid 336.051144 -263.802391)
		(end 336.3341 -263.878568)
		(width 0.0889)
		(layer "In4.Cu")
		(net "M_D_CPU0_SB_CA<4>")
	)
	(arc
		(start 340.102444 -263.883394)
		(mid 340.255314 -263.928035)
		(end 340.412832 -263.90473)
		(width 0.0889)
		(layer "In4.Cu")
		(net "M_D_CPU0_SB_CA<4>")
	)
	(arc
		(start 333.513938 -263.878568)
		(mid 333.696189 -263.928918)
		(end 333.879698 -263.883394)
		(width 0.0889)
		(layer "In4.Cu")
		(net "M_D_CPU0_SB_CA<4>")
	)
	(arc
		(start 332.948026 -263.878568)
		(mid 333.230982 -263.802391)
		(end 333.513938 -263.878568)
		(width 0.0889)
		(layer "In4.Cu")
		(net "M_D_CPU0_SB_CA<4>")
	)
	(arc
		(start 339.52815 -263.878568)
		(mid 339.811106 -263.802391)
		(end 340.094062 -263.878568)
		(width 0.0889)
		(layer "In4.Cu")
		(net "M_D_CPU0_SB_CA<4>")
	)
	(arc
		(start 327.59015 -263.802114)
		(mid 327.73695 -263.821558)
		(end 327.873614 -263.878568)
		(width 0.0889)
		(layer "In4.Cu")
		(net "M_D_CPU0_SB_CA<4>")
	)
	(arc
		(start 329.188064 -263.878568)
		(mid 329.47102 -263.802391)
		(end 329.753976 -263.878568)
		(width 0.0889)
		(layer "In4.Cu")
		(net "M_D_CPU0_SB_CA<4>")
	)
	(arc
		(start 328.814176 -263.878568)
		(mid 329.00112 -263.928823)
		(end 329.188064 -263.878568)
		(width 0.0889)
		(layer "In4.Cu")
		(net "M_D_CPU0_SB_CA<4>")
	)
	(arc
		(start 332.008226 -263.878568)
		(mid 332.291182 -263.802391)
		(end 332.574138 -263.878568)
		(width 0.0889)
		(layer "In4.Cu")
		(net "M_D_CPU0_SB_CA<4>")
	)
	(arc
		(start 336.708242 -263.878568)
		(mid 336.991198 -263.802391)
		(end 337.274154 -263.878568)
		(width 0.0889)
		(layer "In4.Cu")
		(net "M_D_CPU0_SB_CA<4>")
	)
	(arc
		(start 337.648042 -263.878568)
		(mid 337.930998 -263.802391)
		(end 338.213954 -263.878568)
		(width 0.0889)
		(layer "In4.Cu")
		(net "M_D_CPU0_SB_CA<4>")
	)
	(arc
		(start 339.154008 -263.878568)
		(mid 339.336259 -263.928918)
		(end 339.519768 -263.883394)
		(width 0.0889)
		(layer "In4.Cu")
		(net "M_D_CPU0_SB_CA<4>")
	)
	(arc
		(start 338.588096 -263.878568)
		(mid 338.871052 -263.802391)
		(end 339.154008 -263.878568)
		(width 0.0889)
		(layer "In4.Cu")
		(net "M_D_CPU0_SB_CA<4>")
	)
	(arc
		(start 334.828134 -263.878568)
		(mid 335.11109 -263.802391)
		(end 335.394046 -263.878568)
		(width 0.0889)
		(layer "In4.Cu")
		(net "M_D_CPU0_SB_CA<4>")
	)
	(segment
		(start 339.808058 -263.29005)
		(end 339.341206 -263.555988)
		(width 0.10668)
		(layer "F.Cu")
		(net "M_D_CPU0_SB_CA<3>")
	)
	(segment
		(start 280.635964 -263.634982)
		(end 281.060906 -263.21004)
		(width 0.14478)
		(layer "In4.Cu")
		(net "M_D_CPU0_SB_CA<3>")
	)
	(segment
		(start 328.239882 -263.228582)
		(end 328.248264 -263.233408)
		(width 0.0889)
		(layer "In4.Cu")
		(net "M_D_CPU0_SB_CA<3>")
	)
	(segment
		(start 330.119736 -263.228582)
		(end 330.128118 -263.233408)
		(width 0.0889)
		(layer "In4.Cu")
		(net "M_D_CPU0_SB_CA<3>")
	)
	(segment
		(start 281.060906 -263.21004)
		(end 323.903594 -263.21004)
		(width 0.14478)
		(layer "In4.Cu")
		(net "M_D_CPU0_SB_CA<3>")
	)
	(segment
		(start 334.819752 -263.228582)
		(end 334.828134 -263.233408)
		(width 0.0889)
		(layer "In4.Cu")
		(net "M_D_CPU0_SB_CA<3>")
	)
	(segment
		(start 331.634084 -263.233408)
		(end 331.642466 -263.228582)
		(width 0.0889)
		(layer "In4.Cu")
		(net "M_D_CPU0_SB_CA<3>")
	)
	(segment
		(start 324.712838 -262.894572)
		(end 325.523098 -262.894572)
		(width 0.0889)
		(layer "In4.Cu")
		(net "M_D_CPU0_SB_CA<3>")
	)
	(segment
		(start 339.090762 -263.265158)
		(end 339.187028 -263.290558)
		(width 0.0889)
		(layer "In4.Cu")
		(net "M_D_CPU0_SB_CA<3>")
	)
	(segment
		(start 336.3341 -263.233408)
		(end 336.342482 -263.228582)
		(width 0.0889)
		(layer "In4.Cu")
		(net "M_D_CPU0_SB_CA<3>")
	)
	(segment
		(start 325.938134 -263.309608)
		(end 327.590404 -263.309608)
		(width 0.0889)
		(layer "In4.Cu")
		(net "M_D_CPU0_SB_CA<3>")
	)
	(segment
		(start 338.579714 -263.228582)
		(end 338.588096 -263.233408)
		(width 0.0889)
		(layer "In4.Cu")
		(net "M_D_CPU0_SB_CA<3>")
	)
	(segment
		(start 335.394046 -263.233408)
		(end 335.402428 -263.228582)
		(width 0.0889)
		(layer "In4.Cu")
		(net "M_D_CPU0_SB_CA<3>")
	)
	(segment
		(start 330.69403 -263.233408)
		(end 330.702412 -263.228582)
		(width 0.0889)
		(layer "In4.Cu")
		(net "M_D_CPU0_SB_CA<3>")
	)
	(segment
		(start 324.39737 -263.21004)
		(end 324.712838 -262.894572)
		(width 0.0889)
		(layer "In4.Cu")
		(net "M_D_CPU0_SB_CA<3>")
	)
	(segment
		(start 325.523098 -262.894572)
		(end 325.938134 -263.309608)
		(width 0.0889)
		(layer "In4.Cu")
		(net "M_D_CPU0_SB_CA<3>")
	)
	(segment
		(start 333.879698 -263.228582)
		(end 333.88808 -263.233408)
		(width 0.0889)
		(layer "In4.Cu")
		(net "M_D_CPU0_SB_CA<3>")
	)
	(segment
		(start 323.903594 -263.21004)
		(end 324.39737 -263.21004)
		(width 0.0889)
		(layer "In4.Cu")
		(net "M_D_CPU0_SB_CA<3>")
	)
	(segment
		(start 339.187028 -263.290558)
		(end 339.341206 -263.555988)
		(width 0.0889)
		(layer "In4.Cu")
		(net "M_D_CPU0_SB_CA<3>")
	)
	(arc
		(start 328.814176 -263.233408)
		(mid 329.00112 -263.183153)
		(end 329.188064 -263.233408)
		(width 0.0889)
		(layer "In4.Cu")
		(net "M_D_CPU0_SB_CA<3>")
	)
	(arc
		(start 336.342482 -263.228582)
		(mid 336.52599 -263.183088)
		(end 336.708242 -263.233408)
		(width 0.0889)
		(layer "In4.Cu")
		(net "M_D_CPU0_SB_CA<3>")
	)
	(arc
		(start 330.128118 -263.233408)
		(mid 330.411074 -263.309585)
		(end 330.69403 -263.233408)
		(width 0.0889)
		(layer "In4.Cu")
		(net "M_D_CPU0_SB_CA<3>")
	)
	(arc
		(start 334.453992 -263.233408)
		(mid 334.636243 -263.183058)
		(end 334.819752 -263.228582)
		(width 0.0889)
		(layer "In4.Cu")
		(net "M_D_CPU0_SB_CA<3>")
	)
	(arc
		(start 337.274154 -263.233408)
		(mid 337.461098 -263.183153)
		(end 337.648042 -263.233408)
		(width 0.0889)
		(layer "In4.Cu")
		(net "M_D_CPU0_SB_CA<3>")
	)
	(arc
		(start 328.248264 -263.233408)
		(mid 328.53122 -263.309585)
		(end 328.814176 -263.233408)
		(width 0.0889)
		(layer "In4.Cu")
		(net "M_D_CPU0_SB_CA<3>")
	)
	(arc
		(start 332.008226 -263.233408)
		(mid 332.291182 -263.309585)
		(end 332.574138 -263.233408)
		(width 0.0889)
		(layer "In4.Cu")
		(net "M_D_CPU0_SB_CA<3>")
	)
	(arc
		(start 338.213954 -263.233408)
		(mid 338.396205 -263.183058)
		(end 338.579714 -263.228582)
		(width 0.0889)
		(layer "In4.Cu")
		(net "M_D_CPU0_SB_CA<3>")
	)
	(arc
		(start 331.068172 -263.233408)
		(mid 331.351128 -263.309585)
		(end 331.634084 -263.233408)
		(width 0.0889)
		(layer "In4.Cu")
		(net "M_D_CPU0_SB_CA<3>")
	)
	(arc
		(start 331.642466 -263.228582)
		(mid 331.825974 -263.183088)
		(end 332.008226 -263.233408)
		(width 0.0889)
		(layer "In4.Cu")
		(net "M_D_CPU0_SB_CA<3>")
	)
	(arc
		(start 336.708242 -263.233408)
		(mid 336.991198 -263.309585)
		(end 337.274154 -263.233408)
		(width 0.0889)
		(layer "In4.Cu")
		(net "M_D_CPU0_SB_CA<3>")
	)
	(arc
		(start 327.590404 -263.309608)
		(mid 327.737061 -263.290271)
		(end 327.873614 -263.233408)
		(width 0.0889)
		(layer "In4.Cu")
		(net "M_D_CPU0_SB_CA<3>")
	)
	(arc
		(start 335.402428 -263.228582)
		(mid 335.585936 -263.183088)
		(end 335.768188 -263.233408)
		(width 0.0889)
		(layer "In4.Cu")
		(net "M_D_CPU0_SB_CA<3>")
	)
	(arc
		(start 334.828134 -263.233408)
		(mid 335.11109 -263.309585)
		(end 335.394046 -263.233408)
		(width 0.0889)
		(layer "In4.Cu")
		(net "M_D_CPU0_SB_CA<3>")
	)
	(arc
		(start 330.702412 -263.228582)
		(mid 330.88592 -263.183088)
		(end 331.068172 -263.233408)
		(width 0.0889)
		(layer "In4.Cu")
		(net "M_D_CPU0_SB_CA<3>")
	)
	(arc
		(start 329.753976 -263.233408)
		(mid 329.936227 -263.183058)
		(end 330.119736 -263.228582)
		(width 0.0889)
		(layer "In4.Cu")
		(net "M_D_CPU0_SB_CA<3>")
	)
	(arc
		(start 333.513938 -263.233408)
		(mid 333.696189 -263.183058)
		(end 333.879698 -263.228582)
		(width 0.0889)
		(layer "In4.Cu")
		(net "M_D_CPU0_SB_CA<3>")
	)
	(arc
		(start 337.648042 -263.233408)
		(mid 337.930998 -263.309585)
		(end 338.213954 -263.233408)
		(width 0.0889)
		(layer "In4.Cu")
		(net "M_D_CPU0_SB_CA<3>")
	)
	(arc
		(start 333.88808 -263.233408)
		(mid 334.171036 -263.309585)
		(end 334.453992 -263.233408)
		(width 0.0889)
		(layer "In4.Cu")
		(net "M_D_CPU0_SB_CA<3>")
	)
	(arc
		(start 332.948026 -263.233408)
		(mid 333.230982 -263.309585)
		(end 333.513938 -263.233408)
		(width 0.0889)
		(layer "In4.Cu")
		(net "M_D_CPU0_SB_CA<3>")
	)
	(arc
		(start 332.574138 -263.233408)
		(mid 332.761082 -263.183153)
		(end 332.948026 -263.233408)
		(width 0.0889)
		(layer "In4.Cu")
		(net "M_D_CPU0_SB_CA<3>")
	)
	(arc
		(start 327.873614 -263.233408)
		(mid 328.056119 -263.182931)
		(end 328.239882 -263.228582)
		(width 0.0889)
		(layer "In4.Cu")
		(net "M_D_CPU0_SB_CA<3>")
	)
	(arc
		(start 338.588096 -263.233408)
		(mid 338.835692 -263.308586)
		(end 339.090762 -263.265158)
		(width 0.0889)
		(layer "In4.Cu")
		(net "M_D_CPU0_SB_CA<3>")
	)
	(arc
		(start 335.768188 -263.233408)
		(mid 336.051144 -263.309585)
		(end 336.3341 -263.233408)
		(width 0.0889)
		(layer "In4.Cu")
		(net "M_D_CPU0_SB_CA<3>")
	)
	(arc
		(start 329.188064 -263.233408)
		(mid 329.47102 -263.309585)
		(end 329.753976 -263.233408)
		(width 0.0889)
		(layer "In4.Cu")
		(net "M_D_CPU0_SB_CA<3>")
	)
	(segment
		(start 339.337904 -262.480044)
		(end 338.871052 -262.745982)
		(width 0.10668)
		(layer "F.Cu")
		(net "M_D_CPU0_SB_CA<2>")
	)
	(segment
		(start 286.803338 -262.65251)
		(end 287.074356 -262.65251)
		(width 0.14478)
		(layer "In4.Cu")
		(net "M_D_CPU0_SB_CA<2>")
	)
	(segment
		(start 325.764906 -262.692134)
		(end 326.19188 -263.119108)
		(width 0.0889)
		(layer "In4.Cu")
		(net "M_D_CPU0_SB_CA<2>")
	)
	(segment
		(start 285.405576 -262.367268)
		(end 285.690818 -262.65251)
		(width 0.14478)
		(layer "In4.Cu")
		(net "M_D_CPU0_SB_CA<2>")
	)
	(segment
		(start 337.744054 -263.068562)
		(end 337.752436 -263.073388)
		(width 0.0889)
		(layer "In4.Cu")
		(net "M_D_CPU0_SB_CA<2>")
	)
	(segment
		(start 300.790102 -262.67791)
		(end 301.100744 -262.367268)
		(width 0.14478)
		(layer "In4.Cu")
		(net "M_D_CPU0_SB_CA<2>")
	)
	(segment
		(start 297.355006 -262.367268)
		(end 297.665648 -262.67791)
		(width 0.14478)
		(layer "In4.Cu")
		(net "M_D_CPU0_SB_CA<2>")
	)
	(segment
		(start 300.233842 -262.367268)
		(end 300.544484 -262.67791)
		(width 0.14478)
		(layer "In4.Cu")
		(net "M_D_CPU0_SB_CA<2>")
	)
	(segment
		(start 291.881052 -262.367268)
		(end 292.615874 -262.367268)
		(width 0.14478)
		(layer "In4.Cu")
		(net "M_D_CPU0_SB_CA<2>")
	)
	(segment
		(start 307.62321 -262.67791)
		(end 307.868828 -262.67791)
		(width 0.14478)
		(layer "In4.Cu")
		(net "M_D_CPU0_SB_CA<2>")
	)
	(segment
		(start 304.84191 -262.367268)
		(end 305.087528 -262.367268)
		(width 0.14478)
		(layer "In4.Cu")
		(net "M_D_CPU0_SB_CA<2>")
	)
	(segment
		(start 289.90163 -262.367268)
		(end 290.212272 -262.67791)
		(width 0.14478)
		(layer "In4.Cu")
		(net "M_D_CPU0_SB_CA<2>")
	)
	(segment
		(start 300.544484 -262.67791)
		(end 300.790102 -262.67791)
		(width 0.14478)
		(layer "In4.Cu")
		(net "M_D_CPU0_SB_CA<2>")
	)
	(segment
		(start 288.78911 -262.367268)
		(end 289.099752 -262.67791)
		(width 0.14478)
		(layer "In4.Cu")
		(net "M_D_CPU0_SB_CA<2>")
	)
	(segment
		(start 326.19188 -263.119108)
		(end 327.590658 -263.119108)
		(width 0.0889)
		(layer "In4.Cu")
		(net "M_D_CPU0_SB_CA<2>")
	)
	(segment
		(start 333.044038 -263.068562)
		(end 333.05242 -263.073388)
		(width 0.0889)
		(layer "In4.Cu")
		(net "M_D_CPU0_SB_CA<2>")
	)
	(segment
		(start 291.01415 -262.367268)
		(end 291.324792 -262.67791)
		(width 0.14478)
		(layer "In4.Cu")
		(net "M_D_CPU0_SB_CA<2>")
	)
	(segment
		(start 323.86905 -262.755126)
		(end 324.369684 -262.755126)
		(width 0.0889)
		(layer "In4.Cu")
		(net "M_D_CPU0_SB_CA<2>")
	)
	(segment
		(start 296.553128 -262.67791)
		(end 296.798746 -262.67791)
		(width 0.14478)
		(layer "In4.Cu")
		(net "M_D_CPU0_SB_CA<2>")
	)
	(segment
		(start 290.768532 -262.367268)
		(end 291.01415 -262.367268)
		(width 0.14478)
		(layer "In4.Cu")
		(net "M_D_CPU0_SB_CA<2>")
	)
	(segment
		(start 305.643788 -262.67791)
		(end 305.95443 -262.367268)
		(width 0.14478)
		(layer "In4.Cu")
		(net "M_D_CPU0_SB_CA<2>")
	)
	(segment
		(start 290.212272 -262.67791)
		(end 290.45789 -262.67791)
		(width 0.14478)
		(layer "In4.Cu")
		(net "M_D_CPU0_SB_CA<2>")
	)
	(segment
		(start 289.34537 -262.67791)
		(end 289.656012 -262.367268)
		(width 0.14478)
		(layer "In4.Cu")
		(net "M_D_CPU0_SB_CA<2>")
	)
	(segment
		(start 307.06695 -262.367268)
		(end 307.312568 -262.367268)
		(width 0.14478)
		(layer "In4.Cu")
		(net "M_D_CPU0_SB_CA<2>")
	)
	(segment
		(start 301.902622 -262.67791)
		(end 302.213264 -262.367268)
		(width 0.14478)
		(layer "In4.Cu")
		(net "M_D_CPU0_SB_CA<2>")
	)
	(segment
		(start 306.51069 -262.67791)
		(end 306.756308 -262.67791)
		(width 0.14478)
		(layer "In4.Cu")
		(net "M_D_CPU0_SB_CA<2>")
	)
	(segment
		(start 328.709782 -263.073388)
		(end 328.718164 -263.068562)
		(width 0.0889)
		(layer "In4.Cu")
		(net "M_D_CPU0_SB_CA<2>")
	)
	(segment
		(start 286.247078 -262.367268)
		(end 286.518096 -262.367268)
		(width 0.14478)
		(layer "In4.Cu")
		(net "M_D_CPU0_SB_CA<2>")
	)
	(segment
		(start 313.9694 -262.16229)
		(end 314.562236 -262.755126)
		(width 0.14478)
		(layer "In4.Cu")
		(net "M_D_CPU0_SB_CA<2>")
	)
	(segment
		(start 294.284654 -262.67791)
		(end 294.595296 -262.367268)
		(width 0.14478)
		(layer "In4.Cu")
		(net "M_D_CPU0_SB_CA<2>")
	)
	(segment
		(start 305.39817 -262.67791)
		(end 305.643788 -262.67791)
		(width 0.14478)
		(layer "In4.Cu")
		(net "M_D_CPU0_SB_CA<2>")
	)
	(segment
		(start 324.369684 -262.755126)
		(end 324.432676 -262.692134)
		(width 0.0889)
		(layer "In4.Cu")
		(net "M_D_CPU0_SB_CA<2>")
	)
	(segment
		(start 294.595296 -262.367268)
		(end 296.242486 -262.367268)
		(width 0.14478)
		(layer "In4.Cu")
		(net "M_D_CPU0_SB_CA<2>")
	)
	(segment
		(start 333.984092 -263.068562)
		(end 333.992474 -263.073388)
		(width 0.0889)
		(layer "In4.Cu")
		(net "M_D_CPU0_SB_CA<2>")
	)
	(segment
		(start 328.333608 -263.062466)
		(end 328.344022 -263.068562)
		(width 0.0889)
		(layer "In4.Cu")
		(net "M_D_CPU0_SB_CA<2>")
	)
	(segment
		(start 314.562236 -262.755126)
		(end 323.86905 -262.755126)
		(width 0.14478)
		(layer "In4.Cu")
		(net "M_D_CPU0_SB_CA<2>")
	)
	(segment
		(start 304.531268 -262.67791)
		(end 304.84191 -262.367268)
		(width 0.14478)
		(layer "In4.Cu")
		(net "M_D_CPU0_SB_CA<2>")
	)
	(segment
		(start 324.432676 -262.692134)
		(end 325.764906 -262.692134)
		(width 0.0889)
		(layer "In4.Cu")
		(net "M_D_CPU0_SB_CA<2>")
	)
	(segment
		(start 284.736032 -262.785098)
		(end 285.153862 -262.367268)
		(width 0.14478)
		(layer "In4.Cu")
		(net "M_D_CPU0_SB_CA<2>")
	)
	(segment
		(start 285.690818 -262.65251)
		(end 285.961836 -262.65251)
		(width 0.14478)
		(layer "In4.Cu")
		(net "M_D_CPU0_SB_CA<2>")
	)
	(segment
		(start 289.656012 -262.367268)
		(end 289.90163 -262.367268)
		(width 0.14478)
		(layer "In4.Cu")
		(net "M_D_CPU0_SB_CA<2>")
	)
	(segment
		(start 296.242486 -262.367268)
		(end 296.553128 -262.67791)
		(width 0.14478)
		(layer "In4.Cu")
		(net "M_D_CPU0_SB_CA<2>")
	)
	(segment
		(start 298.778168 -262.67791)
		(end 299.023786 -262.67791)
		(width 0.14478)
		(layer "In4.Cu")
		(net "M_D_CPU0_SB_CA<2>")
	)
	(segment
		(start 298.467526 -262.367268)
		(end 298.778168 -262.67791)
		(width 0.14478)
		(layer "In4.Cu")
		(net "M_D_CPU0_SB_CA<2>")
	)
	(segment
		(start 292.926516 -262.67791)
		(end 293.172134 -262.67791)
		(width 0.14478)
		(layer "In4.Cu")
		(net "M_D_CPU0_SB_CA<2>")
	)
	(segment
		(start 297.109388 -262.367268)
		(end 297.355006 -262.367268)
		(width 0.14478)
		(layer "In4.Cu")
		(net "M_D_CPU0_SB_CA<2>")
	)
	(segment
		(start 289.099752 -262.67791)
		(end 289.34537 -262.67791)
		(width 0.14478)
		(layer "In4.Cu")
		(net "M_D_CPU0_SB_CA<2>")
	)
	(segment
		(start 301.657004 -262.67791)
		(end 301.902622 -262.67791)
		(width 0.14478)
		(layer "In4.Cu")
		(net "M_D_CPU0_SB_CA<2>")
	)
	(segment
		(start 305.95443 -262.367268)
		(end 306.200048 -262.367268)
		(width 0.14478)
		(layer "In4.Cu")
		(net "M_D_CPU0_SB_CA<2>")
	)
	(segment
		(start 292.615874 -262.367268)
		(end 292.926516 -262.67791)
		(width 0.14478)
		(layer "In4.Cu")
		(net "M_D_CPU0_SB_CA<2>")
	)
	(segment
		(start 297.665648 -262.67791)
		(end 297.911266 -262.67791)
		(width 0.14478)
		(layer "In4.Cu")
		(net "M_D_CPU0_SB_CA<2>")
	)
	(segment
		(start 336.229706 -263.073388)
		(end 336.238088 -263.068562)
		(width 0.0889)
		(layer "In4.Cu")
		(net "M_D_CPU0_SB_CA<2>")
	)
	(segment
		(start 339.02523 -263.011412)
		(end 338.871052 -262.745982)
		(width 0.0889)
		(layer "In4.Cu")
		(net "M_D_CPU0_SB_CA<2>")
	)
	(segment
		(start 287.359598 -262.367268)
		(end 288.78911 -262.367268)
		(width 0.14478)
		(layer "In4.Cu")
		(net "M_D_CPU0_SB_CA<2>")
	)
	(segment
		(start 306.756308 -262.67791)
		(end 307.06695 -262.367268)
		(width 0.14478)
		(layer "In4.Cu")
		(net "M_D_CPU0_SB_CA<2>")
	)
	(segment
		(start 296.798746 -262.67791)
		(end 297.109388 -262.367268)
		(width 0.14478)
		(layer "In4.Cu")
		(net "M_D_CPU0_SB_CA<2>")
	)
	(segment
		(start 301.100744 -262.367268)
		(end 301.346362 -262.367268)
		(width 0.14478)
		(layer "In4.Cu")
		(net "M_D_CPU0_SB_CA<2>")
	)
	(segment
		(start 293.172134 -262.67791)
		(end 293.482776 -262.367268)
		(width 0.14478)
		(layer "In4.Cu")
		(net "M_D_CPU0_SB_CA<2>")
	)
	(segment
		(start 337.16976 -263.073388)
		(end 337.178142 -263.068562)
		(width 0.0889)
		(layer "In4.Cu")
		(net "M_D_CPU0_SB_CA<2>")
	)
	(segment
		(start 306.200048 -262.367268)
		(end 306.51069 -262.67791)
		(width 0.14478)
		(layer "In4.Cu")
		(net "M_D_CPU0_SB_CA<2>")
	)
	(segment
		(start 293.482776 -262.367268)
		(end 293.728394 -262.367268)
		(width 0.14478)
		(layer "In4.Cu")
		(net "M_D_CPU0_SB_CA<2>")
	)
	(segment
		(start 299.334428 -262.367268)
		(end 300.233842 -262.367268)
		(width 0.14478)
		(layer "In4.Cu")
		(net "M_D_CPU0_SB_CA<2>")
	)
	(segment
		(start 285.153862 -262.367268)
		(end 285.405576 -262.367268)
		(width 0.14478)
		(layer "In4.Cu")
		(net "M_D_CPU0_SB_CA<2>")
	)
	(segment
		(start 301.346362 -262.367268)
		(end 301.657004 -262.67791)
		(width 0.14478)
		(layer "In4.Cu")
		(net "M_D_CPU0_SB_CA<2>")
	)
	(segment
		(start 331.52969 -263.073388)
		(end 331.538072 -263.068562)
		(width 0.0889)
		(layer "In4.Cu")
		(net "M_D_CPU0_SB_CA<2>")
	)
	(segment
		(start 339.002878 -263.094724)
		(end 339.02523 -263.011412)
		(width 0.0889)
		(layer "In4.Cu")
		(net "M_D_CPU0_SB_CA<2>")
	)
	(segment
		(start 286.518096 -262.367268)
		(end 286.803338 -262.65251)
		(width 0.14478)
		(layer "In4.Cu")
		(net "M_D_CPU0_SB_CA<2>")
	)
	(segment
		(start 307.312568 -262.367268)
		(end 307.62321 -262.67791)
		(width 0.14478)
		(layer "In4.Cu")
		(net "M_D_CPU0_SB_CA<2>")
	)
	(segment
		(start 307.868828 -262.67791)
		(end 308.384448 -262.16229)
		(width 0.14478)
		(layer "In4.Cu")
		(net "M_D_CPU0_SB_CA<2>")
	)
	(segment
		(start 305.087528 -262.367268)
		(end 305.39817 -262.67791)
		(width 0.14478)
		(layer "In4.Cu")
		(net "M_D_CPU0_SB_CA<2>")
	)
	(segment
		(start 298.221908 -262.367268)
		(end 298.467526 -262.367268)
		(width 0.14478)
		(layer "In4.Cu")
		(net "M_D_CPU0_SB_CA<2>")
	)
	(segment
		(start 287.074356 -262.65251)
		(end 287.359598 -262.367268)
		(width 0.14478)
		(layer "In4.Cu")
		(net "M_D_CPU0_SB_CA<2>")
	)
	(segment
		(start 285.961836 -262.65251)
		(end 286.247078 -262.367268)
		(width 0.14478)
		(layer "In4.Cu")
		(net "M_D_CPU0_SB_CA<2>")
	)
	(segment
		(start 297.911266 -262.67791)
		(end 298.221908 -262.367268)
		(width 0.14478)
		(layer "In4.Cu")
		(net "M_D_CPU0_SB_CA<2>")
	)
	(segment
		(start 291.57041 -262.67791)
		(end 291.881052 -262.367268)
		(width 0.14478)
		(layer "In4.Cu")
		(net "M_D_CPU0_SB_CA<2>")
	)
	(segment
		(start 332.469744 -263.073388)
		(end 332.478126 -263.068562)
		(width 0.0889)
		(layer "In4.Cu")
		(net "M_D_CPU0_SB_CA<2>")
	)
	(segment
		(start 308.384448 -262.16229)
		(end 313.9694 -262.16229)
		(width 0.14478)
		(layer "In4.Cu")
		(net "M_D_CPU0_SB_CA<2>")
	)
	(segment
		(start 329.284076 -263.068562)
		(end 329.292458 -263.073388)
		(width 0.0889)
		(layer "In4.Cu")
		(net "M_D_CPU0_SB_CA<2>")
	)
	(segment
		(start 304.28565 -262.67791)
		(end 304.531268 -262.67791)
		(width 0.14478)
		(layer "In4.Cu")
		(net "M_D_CPU0_SB_CA<2>")
	)
	(segment
		(start 299.023786 -262.67791)
		(end 299.334428 -262.367268)
		(width 0.14478)
		(layer "In4.Cu")
		(net "M_D_CPU0_SB_CA<2>")
	)
	(segment
		(start 290.45789 -262.67791)
		(end 290.768532 -262.367268)
		(width 0.14478)
		(layer "In4.Cu")
		(net "M_D_CPU0_SB_CA<2>")
	)
	(segment
		(start 294.039036 -262.67791)
		(end 294.284654 -262.67791)
		(width 0.14478)
		(layer "In4.Cu")
		(net "M_D_CPU0_SB_CA<2>")
	)
	(segment
		(start 302.213264 -262.367268)
		(end 303.975008 -262.367268)
		(width 0.14478)
		(layer "In4.Cu")
		(net "M_D_CPU0_SB_CA<2>")
	)
	(segment
		(start 303.975008 -262.367268)
		(end 304.28565 -262.67791)
		(width 0.14478)
		(layer "In4.Cu")
		(net "M_D_CPU0_SB_CA<2>")
	)
	(segment
		(start 291.324792 -262.67791)
		(end 291.57041 -262.67791)
		(width 0.14478)
		(layer "In4.Cu")
		(net "M_D_CPU0_SB_CA<2>")
	)
	(segment
		(start 338.684108 -263.068562)
		(end 338.69249 -263.073388)
		(width 0.0889)
		(layer "In4.Cu")
		(net "M_D_CPU0_SB_CA<2>")
	)
	(segment
		(start 293.728394 -262.367268)
		(end 294.039036 -262.67791)
		(width 0.14478)
		(layer "In4.Cu")
		(net "M_D_CPU0_SB_CA<2>")
	)
	(arc
		(start 330.598018 -263.068562)
		(mid 330.880974 -262.992385)
		(end 331.16393 -263.068562)
		(width 0.0889)
		(layer "In4.Cu")
		(net "M_D_CPU0_SB_CA<2>")
	)
	(arc
		(start 331.16393 -263.068562)
		(mid 331.346181 -263.118912)
		(end 331.52969 -263.073388)
		(width 0.0889)
		(layer "In4.Cu")
		(net "M_D_CPU0_SB_CA<2>")
	)
	(arc
		(start 338.118196 -263.068562)
		(mid 338.401152 -262.992385)
		(end 338.684108 -263.068562)
		(width 0.0889)
		(layer "In4.Cu")
		(net "M_D_CPU0_SB_CA<2>")
	)
	(arc
		(start 335.298034 -263.068562)
		(mid 335.58099 -262.992385)
		(end 335.863946 -263.068562)
		(width 0.0889)
		(layer "In4.Cu")
		(net "M_D_CPU0_SB_CA<2>")
	)
	(arc
		(start 334.358234 -263.068562)
		(mid 334.64119 -262.992385)
		(end 334.924146 -263.068562)
		(width 0.0889)
		(layer "In4.Cu")
		(net "M_D_CPU0_SB_CA<2>")
	)
	(arc
		(start 330.22413 -263.068562)
		(mid 330.411074 -263.118817)
		(end 330.598018 -263.068562)
		(width 0.0889)
		(layer "In4.Cu")
		(net "M_D_CPU0_SB_CA<2>")
	)
	(arc
		(start 333.41818 -263.068562)
		(mid 333.701136 -262.992385)
		(end 333.984092 -263.068562)
		(width 0.0889)
		(layer "In4.Cu")
		(net "M_D_CPU0_SB_CA<2>")
	)
	(arc
		(start 332.478126 -263.068562)
		(mid 332.761082 -262.992385)
		(end 333.044038 -263.068562)
		(width 0.0889)
		(layer "In4.Cu")
		(net "M_D_CPU0_SB_CA<2>")
	)
	(arc
		(start 327.777856 -263.068562)
		(mid 328.054923 -262.992291)
		(end 328.333608 -263.062466)
		(width 0.0889)
		(layer "In4.Cu")
		(net "M_D_CPU0_SB_CA<2>")
	)
	(arc
		(start 337.752436 -263.073388)
		(mid 337.935944 -263.118882)
		(end 338.118196 -263.068562)
		(width 0.0889)
		(layer "In4.Cu")
		(net "M_D_CPU0_SB_CA<2>")
	)
	(arc
		(start 327.590658 -263.119108)
		(mid 327.687584 -263.106171)
		(end 327.777856 -263.068562)
		(width 0.0889)
		(layer "In4.Cu")
		(net "M_D_CPU0_SB_CA<2>")
	)
	(arc
		(start 329.658218 -263.068562)
		(mid 329.941174 -262.992385)
		(end 330.22413 -263.068562)
		(width 0.0889)
		(layer "In4.Cu")
		(net "M_D_CPU0_SB_CA<2>")
	)
	(arc
		(start 328.718164 -263.068562)
		(mid 329.00112 -262.992385)
		(end 329.284076 -263.068562)
		(width 0.0889)
		(layer "In4.Cu")
		(net "M_D_CPU0_SB_CA<2>")
	)
	(arc
		(start 338.69249 -263.073388)
		(mid 338.84536 -263.118029)
		(end 339.002878 -263.094724)
		(width 0.0889)
		(layer "In4.Cu")
		(net "M_D_CPU0_SB_CA<2>")
	)
	(arc
		(start 332.103984 -263.068562)
		(mid 332.286235 -263.118912)
		(end 332.469744 -263.073388)
		(width 0.0889)
		(layer "In4.Cu")
		(net "M_D_CPU0_SB_CA<2>")
	)
	(arc
		(start 335.863946 -263.068562)
		(mid 336.046197 -263.118912)
		(end 336.229706 -263.073388)
		(width 0.0889)
		(layer "In4.Cu")
		(net "M_D_CPU0_SB_CA<2>")
	)
	(arc
		(start 331.538072 -263.068562)
		(mid 331.821028 -262.992385)
		(end 332.103984 -263.068562)
		(width 0.0889)
		(layer "In4.Cu")
		(net "M_D_CPU0_SB_CA<2>")
	)
	(arc
		(start 333.05242 -263.073388)
		(mid 333.235928 -263.118882)
		(end 333.41818 -263.068562)
		(width 0.0889)
		(layer "In4.Cu")
		(net "M_D_CPU0_SB_CA<2>")
	)
	(arc
		(start 333.992474 -263.073388)
		(mid 334.175982 -263.118882)
		(end 334.358234 -263.068562)
		(width 0.0889)
		(layer "In4.Cu")
		(net "M_D_CPU0_SB_CA<2>")
	)
	(arc
		(start 337.178142 -263.068562)
		(mid 337.461098 -262.992385)
		(end 337.744054 -263.068562)
		(width 0.0889)
		(layer "In4.Cu")
		(net "M_D_CPU0_SB_CA<2>")
	)
	(arc
		(start 336.804 -263.068562)
		(mid 336.986251 -263.118912)
		(end 337.16976 -263.073388)
		(width 0.0889)
		(layer "In4.Cu")
		(net "M_D_CPU0_SB_CA<2>")
	)
	(arc
		(start 334.924146 -263.068562)
		(mid 335.11109 -263.118817)
		(end 335.298034 -263.068562)
		(width 0.0889)
		(layer "In4.Cu")
		(net "M_D_CPU0_SB_CA<2>")
	)
	(arc
		(start 329.292458 -263.073388)
		(mid 329.475966 -263.118882)
		(end 329.658218 -263.068562)
		(width 0.0889)
		(layer "In4.Cu")
		(net "M_D_CPU0_SB_CA<2>")
	)
	(arc
		(start 336.238088 -263.068562)
		(mid 336.521044 -262.992385)
		(end 336.804 -263.068562)
		(width 0.0889)
		(layer "In4.Cu")
		(net "M_D_CPU0_SB_CA<2>")
	)
	(arc
		(start 328.344022 -263.068562)
		(mid 328.526273 -263.118912)
		(end 328.709782 -263.073388)
		(width 0.0889)
		(layer "In4.Cu")
		(net "M_D_CPU0_SB_CA<2>")
	)
	(segment
		(start 341.218012 -262.480044)
		(end 340.75116 -262.745982)
		(width 0.10668)
		(layer "F.Cu")
		(net "M_D_CPU0_SB_CA<1>")
	)
	(segment
		(start 314.689236 -262.24611)
		(end 323.926454 -262.24611)
		(width 0.14478)
		(layer "In4.Cu")
		(net "M_D_CPU0_SB_CA<1>")
	)
	(segment
		(start 333.044038 -262.423402)
		(end 333.05242 -262.418576)
		(width 0.0889)
		(layer "In4.Cu")
		(net "M_D_CPU0_SB_CA<1>")
	)
	(segment
		(start 336.229706 -262.418576)
		(end 336.238088 -262.423402)
		(width 0.0889)
		(layer "In4.Cu")
		(net "M_D_CPU0_SB_CA<1>")
	)
	(segment
		(start 337.744054 -262.423402)
		(end 337.752436 -262.418576)
		(width 0.0889)
		(layer "In4.Cu")
		(net "M_D_CPU0_SB_CA<1>")
	)
	(segment
		(start 337.16976 -262.418576)
		(end 337.178142 -262.423402)
		(width 0.0889)
		(layer "In4.Cu")
		(net "M_D_CPU0_SB_CA<1>")
	)
	(segment
		(start 331.52969 -262.418576)
		(end 331.538072 -262.423402)
		(width 0.0889)
		(layer "In4.Cu")
		(net "M_D_CPU0_SB_CA<1>")
	)
	(segment
		(start 328.32929 -262.432038)
		(end 328.344022 -262.423402)
		(width 0.0889)
		(layer "In4.Cu")
		(net "M_D_CPU0_SB_CA<1>")
	)
	(segment
		(start 338.684108 -262.423402)
		(end 338.69249 -262.418576)
		(width 0.0889)
		(layer "In4.Cu")
		(net "M_D_CPU0_SB_CA<1>")
	)
	(segment
		(start 340.500716 -262.455152)
		(end 340.596982 -262.480552)
		(width 0.0889)
		(layer "In4.Cu")
		(net "M_D_CPU0_SB_CA<1>")
	)
	(segment
		(start 328.709782 -262.418576)
		(end 328.718164 -262.423402)
		(width 0.0889)
		(layer "In4.Cu")
		(net "M_D_CPU0_SB_CA<1>")
	)
	(segment
		(start 332.469744 -262.418576)
		(end 332.478126 -262.423402)
		(width 0.0889)
		(layer "In4.Cu")
		(net "M_D_CPU0_SB_CA<1>")
	)
	(segment
		(start 281.060906 -261.510018)
		(end 313.953144 -261.510018)
		(width 0.14478)
		(layer "In4.Cu")
		(net "M_D_CPU0_SB_CA<1>")
	)
	(segment
		(start 325.710296 -262.24611)
		(end 325.749158 -262.284972)
		(width 0.0889)
		(layer "In4.Cu")
		(net "M_D_CPU0_SB_CA<1>")
	)
	(segment
		(start 325.749158 -262.284972)
		(end 327.406508 -262.284972)
		(width 0.0889)
		(layer "In4.Cu")
		(net "M_D_CPU0_SB_CA<1>")
	)
	(segment
		(start 329.284076 -262.423402)
		(end 329.292458 -262.418576)
		(width 0.0889)
		(layer "In4.Cu")
		(net "M_D_CPU0_SB_CA<1>")
	)
	(segment
		(start 323.926454 -262.24611)
		(end 325.710296 -262.24611)
		(width 0.0889)
		(layer "In4.Cu")
		(net "M_D_CPU0_SB_CA<1>")
	)
	(segment
		(start 313.953144 -261.510018)
		(end 314.689236 -262.24611)
		(width 0.14478)
		(layer "In4.Cu")
		(net "M_D_CPU0_SB_CA<1>")
	)
	(segment
		(start 333.984092 -262.423402)
		(end 333.992474 -262.418576)
		(width 0.0889)
		(layer "In4.Cu")
		(net "M_D_CPU0_SB_CA<1>")
	)
	(segment
		(start 340.596982 -262.480552)
		(end 340.75116 -262.745982)
		(width 0.0889)
		(layer "In4.Cu")
		(net "M_D_CPU0_SB_CA<1>")
	)
	(segment
		(start 280.635964 -261.93496)
		(end 281.060906 -261.510018)
		(width 0.14478)
		(layer "In4.Cu")
		(net "M_D_CPU0_SB_CA<1>")
	)
	(arc
		(start 329.658218 -262.423402)
		(mid 329.941174 -262.499579)
		(end 330.22413 -262.423402)
		(width 0.0889)
		(layer "In4.Cu")
		(net "M_D_CPU0_SB_CA<1>")
	)
	(arc
		(start 330.598018 -262.423402)
		(mid 330.880974 -262.499579)
		(end 331.16393 -262.423402)
		(width 0.0889)
		(layer "In4.Cu")
		(net "M_D_CPU0_SB_CA<1>")
	)
	(arc
		(start 330.22413 -262.423402)
		(mid 330.411074 -262.373147)
		(end 330.598018 -262.423402)
		(width 0.0889)
		(layer "In4.Cu")
		(net "M_D_CPU0_SB_CA<1>")
	)
	(arc
		(start 328.718164 -262.423402)
		(mid 329.00112 -262.499579)
		(end 329.284076 -262.423402)
		(width 0.0889)
		(layer "In4.Cu")
		(net "M_D_CPU0_SB_CA<1>")
	)
	(arc
		(start 331.538072 -262.423402)
		(mid 331.821028 -262.499579)
		(end 332.103984 -262.423402)
		(width 0.0889)
		(layer "In4.Cu")
		(net "M_D_CPU0_SB_CA<1>")
	)
	(arc
		(start 334.358234 -262.423402)
		(mid 334.64119 -262.499579)
		(end 334.924146 -262.423402)
		(width 0.0889)
		(layer "In4.Cu")
		(net "M_D_CPU0_SB_CA<1>")
	)
	(arc
		(start 339.05825 -262.423402)
		(mid 339.341206 -262.499579)
		(end 339.624162 -262.423402)
		(width 0.0889)
		(layer "In4.Cu")
		(net "M_D_CPU0_SB_CA<1>")
	)
	(arc
		(start 335.863946 -262.423402)
		(mid 336.046197 -262.373052)
		(end 336.229706 -262.418576)
		(width 0.0889)
		(layer "In4.Cu")
		(net "M_D_CPU0_SB_CA<1>")
	)
	(arc
		(start 336.804 -262.423402)
		(mid 336.986251 -262.373052)
		(end 337.16976 -262.418576)
		(width 0.0889)
		(layer "In4.Cu")
		(net "M_D_CPU0_SB_CA<1>")
	)
	(arc
		(start 339.624162 -262.423402)
		(mid 339.811106 -262.373147)
		(end 339.99805 -262.423402)
		(width 0.0889)
		(layer "In4.Cu")
		(net "M_D_CPU0_SB_CA<1>")
	)
	(arc
		(start 338.69249 -262.418576)
		(mid 338.875998 -262.373082)
		(end 339.05825 -262.423402)
		(width 0.0889)
		(layer "In4.Cu")
		(net "M_D_CPU0_SB_CA<1>")
	)
	(arc
		(start 329.292458 -262.418576)
		(mid 329.475966 -262.373082)
		(end 329.658218 -262.423402)
		(width 0.0889)
		(layer "In4.Cu")
		(net "M_D_CPU0_SB_CA<1>")
	)
	(arc
		(start 339.99805 -262.423402)
		(mid 340.245646 -262.49858)
		(end 340.500716 -262.455152)
		(width 0.0889)
		(layer "In4.Cu")
		(net "M_D_CPU0_SB_CA<1>")
	)
	(arc
		(start 327.406508 -262.284972)
		(mid 327.451088 -262.288346)
		(end 327.494646 -262.298434)
		(width 0.0889)
		(layer "In4.Cu")
		(net "M_D_CPU0_SB_CA<1>")
	)
	(arc
		(start 333.992474 -262.418576)
		(mid 334.175982 -262.373082)
		(end 334.358234 -262.423402)
		(width 0.0889)
		(layer "In4.Cu")
		(net "M_D_CPU0_SB_CA<1>")
	)
	(arc
		(start 333.05242 -262.418576)
		(mid 333.235928 -262.373082)
		(end 333.41818 -262.423402)
		(width 0.0889)
		(layer "In4.Cu")
		(net "M_D_CPU0_SB_CA<1>")
	)
	(arc
		(start 337.178142 -262.423402)
		(mid 337.461098 -262.499579)
		(end 337.744054 -262.423402)
		(width 0.0889)
		(layer "In4.Cu")
		(net "M_D_CPU0_SB_CA<1>")
	)
	(arc
		(start 333.41818 -262.423402)
		(mid 333.701136 -262.499579)
		(end 333.984092 -262.423402)
		(width 0.0889)
		(layer "In4.Cu")
		(net "M_D_CPU0_SB_CA<1>")
	)
	(arc
		(start 331.16393 -262.423402)
		(mid 331.346181 -262.373052)
		(end 331.52969 -262.418576)
		(width 0.0889)
		(layer "In4.Cu")
		(net "M_D_CPU0_SB_CA<1>")
	)
	(arc
		(start 335.298034 -262.423402)
		(mid 335.58099 -262.499579)
		(end 335.863946 -262.423402)
		(width 0.0889)
		(layer "In4.Cu")
		(net "M_D_CPU0_SB_CA<1>")
	)
	(arc
		(start 327.494646 -262.298434)
		(mid 327.639595 -262.353059)
		(end 327.777602 -262.423402)
		(width 0.0889)
		(layer "In4.Cu")
		(net "M_D_CPU0_SB_CA<1>")
	)
	(arc
		(start 327.777602 -262.423402)
		(mid 328.052308 -262.499766)
		(end 328.32929 -262.432038)
		(width 0.0889)
		(layer "In4.Cu")
		(net "M_D_CPU0_SB_CA<1>")
	)
	(arc
		(start 328.344022 -262.423402)
		(mid 328.526273 -262.373052)
		(end 328.709782 -262.418576)
		(width 0.0889)
		(layer "In4.Cu")
		(net "M_D_CPU0_SB_CA<1>")
	)
	(arc
		(start 332.478126 -262.423402)
		(mid 332.761082 -262.499579)
		(end 333.044038 -262.423402)
		(width 0.0889)
		(layer "In4.Cu")
		(net "M_D_CPU0_SB_CA<1>")
	)
	(arc
		(start 336.238088 -262.423402)
		(mid 336.521044 -262.499579)
		(end 336.804 -262.423402)
		(width 0.0889)
		(layer "In4.Cu")
		(net "M_D_CPU0_SB_CA<1>")
	)
	(arc
		(start 338.118196 -262.423402)
		(mid 338.401152 -262.499579)
		(end 338.684108 -262.423402)
		(width 0.0889)
		(layer "In4.Cu")
		(net "M_D_CPU0_SB_CA<1>")
	)
	(arc
		(start 332.103984 -262.423402)
		(mid 332.286235 -262.373052)
		(end 332.469744 -262.418576)
		(width 0.0889)
		(layer "In4.Cu")
		(net "M_D_CPU0_SB_CA<1>")
	)
	(arc
		(start 334.924146 -262.423402)
		(mid 335.11109 -262.373147)
		(end 335.298034 -262.423402)
		(width 0.0889)
		(layer "In4.Cu")
		(net "M_D_CPU0_SB_CA<1>")
	)
	(arc
		(start 337.752436 -262.418576)
		(mid 337.935944 -262.373082)
		(end 338.118196 -262.423402)
		(width 0.0889)
		(layer "In4.Cu")
		(net "M_D_CPU0_SB_CA<1>")
	)
	(segment
		(start 340.747858 -261.670038)
		(end 340.281006 -261.935976)
		(width 0.10668)
		(layer "F.Cu")
		(net "M_D_CPU0_SB_CA<0>")
	)
	(segment
		(start 334.819752 -262.263382)
		(end 334.828134 -262.258556)
		(width 0.0889)
		(layer "In4.Cu")
		(net "M_D_CPU0_SB_CA<0>")
	)
	(segment
		(start 286.385254 -260.660134)
		(end 286.625538 -260.660134)
		(width 0.14478)
		(layer "In4.Cu")
		(net "M_D_CPU0_SB_CA<0>")
	)
	(segment
		(start 300.836076 -260.97611)
		(end 301.07636 -260.97611)
		(width 0.14478)
		(layer "In4.Cu")
		(net "M_D_CPU0_SB_CA<0>")
	)
	(segment
		(start 296.160952 -260.660134)
		(end 296.476928 -260.97611)
		(width 0.14478)
		(layer "In4.Cu")
		(net "M_D_CPU0_SB_CA<0>")
	)
	(segment
		(start 292.823392 -260.660134)
		(end 293.139368 -260.97611)
		(width 0.14478)
		(layer "In4.Cu")
		(net "M_D_CPU0_SB_CA<0>")
	)
	(segment
		(start 285.828994 -260.97611)
		(end 286.069278 -260.97611)
		(width 0.14478)
		(layer "In4.Cu")
		(net "M_D_CPU0_SB_CA<0>")
	)
	(segment
		(start 299.258228 -260.660134)
		(end 300.5201 -260.660134)
		(width 0.14478)
		(layer "In4.Cu")
		(net "M_D_CPU0_SB_CA<0>")
	)
	(segment
		(start 339.519768 -262.263382)
		(end 339.52815 -262.258556)
		(width 0.0889)
		(layer "In4.Cu")
		(net "M_D_CPU0_SB_CA<0>")
	)
	(segment
		(start 295.920668 -260.660134)
		(end 296.160952 -260.660134)
		(width 0.14478)
		(layer "In4.Cu")
		(net "M_D_CPU0_SB_CA<0>")
	)
	(segment
		(start 293.695628 -260.660134)
		(end 293.935912 -260.660134)
		(width 0.14478)
		(layer "In4.Cu")
		(net "M_D_CPU0_SB_CA<0>")
	)
	(segment
		(start 288.054034 -260.97611)
		(end 288.294318 -260.97611)
		(width 0.14478)
		(layer "In4.Cu")
		(net "M_D_CPU0_SB_CA<0>")
	)
	(segment
		(start 302.504856 -260.660134)
		(end 302.74514 -260.660134)
		(width 0.14478)
		(layer "In4.Cu")
		(net "M_D_CPU0_SB_CA<0>")
	)
	(segment
		(start 297.033188 -260.660134)
		(end 297.273472 -260.660134)
		(width 0.14478)
		(layer "In4.Cu")
		(net "M_D_CPU0_SB_CA<0>")
	)
	(segment
		(start 324.554342 -261.775956)
		(end 324.822058 -262.043672)
		(width 0.0889)
		(layer "In4.Cu")
		(net "M_D_CPU0_SB_CA<0>")
	)
	(segment
		(start 289.722814 -260.660134)
		(end 289.963098 -260.660134)
		(width 0.14478)
		(layer "In4.Cu")
		(net "M_D_CPU0_SB_CA<0>")
	)
	(segment
		(start 324.822058 -262.043672)
		(end 327.076054 -262.043672)
		(width 0.0889)
		(layer "In4.Cu")
		(net "M_D_CPU0_SB_CA<0>")
	)
	(segment
		(start 340.412832 -262.284718)
		(end 340.435184 -262.201406)
		(width 0.0889)
		(layer "In4.Cu")
		(net "M_D_CPU0_SB_CA<0>")
	)
	(segment
		(start 294.492172 -260.97611)
		(end 294.808148 -260.660134)
		(width 0.14478)
		(layer "In4.Cu")
		(net "M_D_CPU0_SB_CA<0>")
	)
	(segment
		(start 288.610294 -260.660134)
		(end 288.850578 -260.660134)
		(width 0.14478)
		(layer "In4.Cu")
		(net "M_D_CPU0_SB_CA<0>")
	)
	(segment
		(start 287.181798 -260.97611)
		(end 287.497774 -260.660134)
		(width 0.14478)
		(layer "In4.Cu")
		(net "M_D_CPU0_SB_CA<0>")
	)
	(segment
		(start 331.634084 -262.258556)
		(end 331.642466 -262.263382)
		(width 0.0889)
		(layer "In4.Cu")
		(net "M_D_CPU0_SB_CA<0>")
	)
	(segment
		(start 286.941514 -260.97611)
		(end 287.181798 -260.97611)
		(width 0.14478)
		(layer "In4.Cu")
		(net "M_D_CPU0_SB_CA<0>")
	)
	(segment
		(start 306.398676 -260.97611)
		(end 306.63896 -260.97611)
		(width 0.14478)
		(layer "In4.Cu")
		(net "M_D_CPU0_SB_CA<0>")
	)
	(segment
		(start 301.07636 -260.97611)
		(end 301.392336 -260.660134)
		(width 0.14478)
		(layer "In4.Cu")
		(net "M_D_CPU0_SB_CA<0>")
	)
	(segment
		(start 284.736032 -261.085076)
		(end 285.160974 -260.660134)
		(width 0.14478)
		(layer "In4.Cu")
		(net "M_D_CPU0_SB_CA<0>")
	)
	(segment
		(start 303.85766 -260.660134)
		(end 304.173636 -260.97611)
		(width 0.14478)
		(layer "In4.Cu")
		(net "M_D_CPU0_SB_CA<0>")
	)
	(segment
		(start 307.75148 -260.97611)
		(end 308.067456 -260.660134)
		(width 0.14478)
		(layer "In4.Cu")
		(net "M_D_CPU0_SB_CA<0>")
	)
	(segment
		(start 294.808148 -260.660134)
		(end 295.048432 -260.660134)
		(width 0.14478)
		(layer "In4.Cu")
		(net "M_D_CPU0_SB_CA<0>")
	)
	(segment
		(start 297.273472 -260.660134)
		(end 297.589448 -260.97611)
		(width 0.14478)
		(layer "In4.Cu")
		(net "M_D_CPU0_SB_CA<0>")
	)
	(segment
		(start 303.3014 -260.97611)
		(end 303.617376 -260.660134)
		(width 0.14478)
		(layer "In4.Cu")
		(net "M_D_CPU0_SB_CA<0>")
	)
	(segment
		(start 288.294318 -260.97611)
		(end 288.610294 -260.660134)
		(width 0.14478)
		(layer "In4.Cu")
		(net "M_D_CPU0_SB_CA<0>")
	)
	(segment
		(start 303.617376 -260.660134)
		(end 303.85766 -260.660134)
		(width 0.14478)
		(layer "In4.Cu")
		(net "M_D_CPU0_SB_CA<0>")
	)
	(segment
		(start 315.086238 -261.775956)
		(end 323.8881 -261.775956)
		(width 0.14478)
		(layer "In4.Cu")
		(net "M_D_CPU0_SB_CA<0>")
	)
	(segment
		(start 296.476928 -260.97611)
		(end 296.717212 -260.97611)
		(width 0.14478)
		(layer "In4.Cu")
		(net "M_D_CPU0_SB_CA<0>")
	)
	(segment
		(start 289.963098 -260.660134)
		(end 290.279074 -260.97611)
		(width 0.14478)
		(layer "In4.Cu")
		(net "M_D_CPU0_SB_CA<0>")
	)
	(segment
		(start 305.52644 -260.97611)
		(end 305.842416 -260.660134)
		(width 0.14478)
		(layer "In4.Cu")
		(net "M_D_CPU0_SB_CA<0>")
	)
	(segment
		(start 340.435184 -262.201406)
		(end 340.281006 -261.935976)
		(width 0.0889)
		(layer "In4.Cu")
		(net "M_D_CPU0_SB_CA<0>")
	)
	(segment
		(start 287.497774 -260.660134)
		(end 287.738058 -260.660134)
		(width 0.14478)
		(layer "In4.Cu")
		(net "M_D_CPU0_SB_CA<0>")
	)
	(segment
		(start 303.061116 -260.97611)
		(end 303.3014 -260.97611)
		(width 0.14478)
		(layer "In4.Cu")
		(net "M_D_CPU0_SB_CA<0>")
	)
	(segment
		(start 290.519358 -260.97611)
		(end 290.835334 -260.660134)
		(width 0.14478)
		(layer "In4.Cu")
		(net "M_D_CPU0_SB_CA<0>")
	)
	(segment
		(start 293.379652 -260.97611)
		(end 293.695628 -260.660134)
		(width 0.14478)
		(layer "In4.Cu")
		(net "M_D_CPU0_SB_CA<0>")
	)
	(segment
		(start 295.604692 -260.97611)
		(end 295.920668 -260.660134)
		(width 0.14478)
		(layer "In4.Cu")
		(net "M_D_CPU0_SB_CA<0>")
	)
	(segment
		(start 307.511196 -260.97611)
		(end 307.75148 -260.97611)
		(width 0.14478)
		(layer "In4.Cu")
		(net "M_D_CPU0_SB_CA<0>")
	)
	(segment
		(start 306.954936 -260.660134)
		(end 307.19522 -260.660134)
		(width 0.14478)
		(layer "In4.Cu")
		(net "M_D_CPU0_SB_CA<0>")
	)
	(segment
		(start 298.145708 -260.660134)
		(end 298.385992 -260.660134)
		(width 0.14478)
		(layer "In4.Cu")
		(net "M_D_CPU0_SB_CA<0>")
	)
	(segment
		(start 308.067456 -260.660134)
		(end 313.970416 -260.660134)
		(width 0.14478)
		(layer "In4.Cu")
		(net "M_D_CPU0_SB_CA<0>")
	)
	(segment
		(start 304.729896 -260.660134)
		(end 304.97018 -260.660134)
		(width 0.14478)
		(layer "In4.Cu")
		(net "M_D_CPU0_SB_CA<0>")
	)
	(segment
		(start 336.3341 -262.258556)
		(end 336.342482 -262.263382)
		(width 0.0889)
		(layer "In4.Cu")
		(net "M_D_CPU0_SB_CA<0>")
	)
	(segment
		(start 298.942252 -260.97611)
		(end 299.258228 -260.660134)
		(width 0.14478)
		(layer "In4.Cu")
		(net "M_D_CPU0_SB_CA<0>")
	)
	(segment
		(start 295.364408 -260.97611)
		(end 295.604692 -260.97611)
		(width 0.14478)
		(layer "In4.Cu")
		(net "M_D_CPU0_SB_CA<0>")
	)
	(segment
		(start 307.19522 -260.660134)
		(end 307.511196 -260.97611)
		(width 0.14478)
		(layer "In4.Cu")
		(net "M_D_CPU0_SB_CA<0>")
	)
	(segment
		(start 286.069278 -260.97611)
		(end 286.385254 -260.660134)
		(width 0.14478)
		(layer "In4.Cu")
		(net "M_D_CPU0_SB_CA<0>")
	)
	(segment
		(start 301.392336 -260.660134)
		(end 301.63262 -260.660134)
		(width 0.14478)
		(layer "In4.Cu")
		(net "M_D_CPU0_SB_CA<0>")
	)
	(segment
		(start 298.385992 -260.660134)
		(end 298.701968 -260.97611)
		(width 0.14478)
		(layer "In4.Cu")
		(net "M_D_CPU0_SB_CA<0>")
	)
	(segment
		(start 295.048432 -260.660134)
		(end 295.364408 -260.97611)
		(width 0.14478)
		(layer "In4.Cu")
		(net "M_D_CPU0_SB_CA<0>")
	)
	(segment
		(start 290.279074 -260.97611)
		(end 290.519358 -260.97611)
		(width 0.14478)
		(layer "In4.Cu")
		(net "M_D_CPU0_SB_CA<0>")
	)
	(segment
		(start 330.69403 -262.258556)
		(end 330.702412 -262.263382)
		(width 0.0889)
		(layer "In4.Cu")
		(net "M_D_CPU0_SB_CA<0>")
	)
	(segment
		(start 290.835334 -260.660134)
		(end 291.075618 -260.660134)
		(width 0.14478)
		(layer "In4.Cu")
		(net "M_D_CPU0_SB_CA<0>")
	)
	(segment
		(start 302.74514 -260.660134)
		(end 303.061116 -260.97611)
		(width 0.14478)
		(layer "In4.Cu")
		(net "M_D_CPU0_SB_CA<0>")
	)
	(segment
		(start 293.935912 -260.660134)
		(end 294.251888 -260.97611)
		(width 0.14478)
		(layer "In4.Cu")
		(net "M_D_CPU0_SB_CA<0>")
	)
	(segment
		(start 291.631878 -260.97611)
		(end 291.947854 -260.660134)
		(width 0.14478)
		(layer "In4.Cu")
		(net "M_D_CPU0_SB_CA<0>")
	)
	(segment
		(start 296.717212 -260.97611)
		(end 297.033188 -260.660134)
		(width 0.14478)
		(layer "In4.Cu")
		(net "M_D_CPU0_SB_CA<0>")
	)
	(segment
		(start 301.63262 -260.660134)
		(end 301.948596 -260.97611)
		(width 0.14478)
		(layer "In4.Cu")
		(net "M_D_CPU0_SB_CA<0>")
	)
	(segment
		(start 297.589448 -260.97611)
		(end 297.829732 -260.97611)
		(width 0.14478)
		(layer "In4.Cu")
		(net "M_D_CPU0_SB_CA<0>")
	)
	(segment
		(start 288.850578 -260.660134)
		(end 289.166554 -260.97611)
		(width 0.14478)
		(layer "In4.Cu")
		(net "M_D_CPU0_SB_CA<0>")
	)
	(segment
		(start 289.406838 -260.97611)
		(end 289.722814 -260.660134)
		(width 0.14478)
		(layer "In4.Cu")
		(net "M_D_CPU0_SB_CA<0>")
	)
	(segment
		(start 330.119736 -262.263382)
		(end 330.128118 -262.258556)
		(width 0.0889)
		(layer "In4.Cu")
		(net "M_D_CPU0_SB_CA<0>")
	)
	(segment
		(start 306.0827 -260.660134)
		(end 306.398676 -260.97611)
		(width 0.14478)
		(layer "In4.Cu")
		(net "M_D_CPU0_SB_CA<0>")
	)
	(segment
		(start 323.8881 -261.775956)
		(end 324.554342 -261.775956)
		(width 0.0889)
		(layer "In4.Cu")
		(net "M_D_CPU0_SB_CA<0>")
	)
	(segment
		(start 313.970416 -260.660134)
		(end 315.086238 -261.775956)
		(width 0.14478)
		(layer "In4.Cu")
		(net "M_D_CPU0_SB_CA<0>")
	)
	(segment
		(start 304.97018 -260.660134)
		(end 305.286156 -260.97611)
		(width 0.14478)
		(layer "In4.Cu")
		(net "M_D_CPU0_SB_CA<0>")
	)
	(segment
		(start 335.394046 -262.258556)
		(end 335.402428 -262.263382)
		(width 0.0889)
		(layer "In4.Cu")
		(net "M_D_CPU0_SB_CA<0>")
	)
	(segment
		(start 304.41392 -260.97611)
		(end 304.729896 -260.660134)
		(width 0.14478)
		(layer "In4.Cu")
		(net "M_D_CPU0_SB_CA<0>")
	)
	(segment
		(start 301.948596 -260.97611)
		(end 302.18888 -260.97611)
		(width 0.14478)
		(layer "In4.Cu")
		(net "M_D_CPU0_SB_CA<0>")
	)
	(segment
		(start 338.579714 -262.263382)
		(end 338.588096 -262.258556)
		(width 0.0889)
		(layer "In4.Cu")
		(net "M_D_CPU0_SB_CA<0>")
	)
	(segment
		(start 304.173636 -260.97611)
		(end 304.41392 -260.97611)
		(width 0.14478)
		(layer "In4.Cu")
		(net "M_D_CPU0_SB_CA<0>")
	)
	(segment
		(start 293.139368 -260.97611)
		(end 293.379652 -260.97611)
		(width 0.14478)
		(layer "In4.Cu")
		(net "M_D_CPU0_SB_CA<0>")
	)
	(segment
		(start 291.947854 -260.660134)
		(end 292.823392 -260.660134)
		(width 0.14478)
		(layer "In4.Cu")
		(net "M_D_CPU0_SB_CA<0>")
	)
	(segment
		(start 286.625538 -260.660134)
		(end 286.941514 -260.97611)
		(width 0.14478)
		(layer "In4.Cu")
		(net "M_D_CPU0_SB_CA<0>")
	)
	(segment
		(start 291.391594 -260.97611)
		(end 291.631878 -260.97611)
		(width 0.14478)
		(layer "In4.Cu")
		(net "M_D_CPU0_SB_CA<0>")
	)
	(segment
		(start 302.18888 -260.97611)
		(end 302.504856 -260.660134)
		(width 0.14478)
		(layer "In4.Cu")
		(net "M_D_CPU0_SB_CA<0>")
	)
	(segment
		(start 333.879698 -262.263382)
		(end 333.88808 -262.258556)
		(width 0.0889)
		(layer "In4.Cu")
		(net "M_D_CPU0_SB_CA<0>")
	)
	(segment
		(start 294.251888 -260.97611)
		(end 294.492172 -260.97611)
		(width 0.14478)
		(layer "In4.Cu")
		(net "M_D_CPU0_SB_CA<0>")
	)
	(segment
		(start 328.239882 -262.263382)
		(end 328.248264 -262.258556)
		(width 0.0889)
		(layer "In4.Cu")
		(net "M_D_CPU0_SB_CA<0>")
	)
	(segment
		(start 287.738058 -260.660134)
		(end 288.054034 -260.97611)
		(width 0.14478)
		(layer "In4.Cu")
		(net "M_D_CPU0_SB_CA<0>")
	)
	(segment
		(start 305.286156 -260.97611)
		(end 305.52644 -260.97611)
		(width 0.14478)
		(layer "In4.Cu")
		(net "M_D_CPU0_SB_CA<0>")
	)
	(segment
		(start 300.5201 -260.660134)
		(end 300.836076 -260.97611)
		(width 0.14478)
		(layer "In4.Cu")
		(net "M_D_CPU0_SB_CA<0>")
	)
	(segment
		(start 340.094062 -262.258556)
		(end 340.102444 -262.263382)
		(width 0.0889)
		(layer "In4.Cu")
		(net "M_D_CPU0_SB_CA<0>")
	)
	(segment
		(start 285.160974 -260.660134)
		(end 285.513018 -260.660134)
		(width 0.14478)
		(layer "In4.Cu")
		(net "M_D_CPU0_SB_CA<0>")
	)
	(segment
		(start 289.166554 -260.97611)
		(end 289.406838 -260.97611)
		(width 0.14478)
		(layer "In4.Cu")
		(net "M_D_CPU0_SB_CA<0>")
	)
	(segment
		(start 285.513018 -260.660134)
		(end 285.828994 -260.97611)
		(width 0.14478)
		(layer "In4.Cu")
		(net "M_D_CPU0_SB_CA<0>")
	)
	(segment
		(start 297.829732 -260.97611)
		(end 298.145708 -260.660134)
		(width 0.14478)
		(layer "In4.Cu")
		(net "M_D_CPU0_SB_CA<0>")
	)
	(segment
		(start 291.075618 -260.660134)
		(end 291.391594 -260.97611)
		(width 0.14478)
		(layer "In4.Cu")
		(net "M_D_CPU0_SB_CA<0>")
	)
	(segment
		(start 306.63896 -260.97611)
		(end 306.954936 -260.660134)
		(width 0.14478)
		(layer "In4.Cu")
		(net "M_D_CPU0_SB_CA<0>")
	)
	(segment
		(start 298.701968 -260.97611)
		(end 298.942252 -260.97611)
		(width 0.14478)
		(layer "In4.Cu")
		(net "M_D_CPU0_SB_CA<0>")
	)
	(segment
		(start 305.842416 -260.660134)
		(end 306.0827 -260.660134)
		(width 0.14478)
		(layer "In4.Cu")
		(net "M_D_CPU0_SB_CA<0>")
	)
	(arc
		(start 337.648042 -262.258556)
		(mid 337.930998 -262.182379)
		(end 338.213954 -262.258556)
		(width 0.0889)
		(layer "In4.Cu")
		(net "M_D_CPU0_SB_CA<0>")
	)
	(arc
		(start 331.642466 -262.263382)
		(mid 331.825974 -262.308876)
		(end 332.008226 -262.258556)
		(width 0.0889)
		(layer "In4.Cu")
		(net "M_D_CPU0_SB_CA<0>")
	)
	(arc
		(start 329.188064 -262.258556)
		(mid 329.47102 -262.182379)
		(end 329.753976 -262.258556)
		(width 0.0889)
		(layer "In4.Cu")
		(net "M_D_CPU0_SB_CA<0>")
	)
	(arc
		(start 338.213954 -262.258556)
		(mid 338.396205 -262.308906)
		(end 338.579714 -262.263382)
		(width 0.0889)
		(layer "In4.Cu")
		(net "M_D_CPU0_SB_CA<0>")
	)
	(arc
		(start 330.128118 -262.258556)
		(mid 330.411074 -262.182379)
		(end 330.69403 -262.258556)
		(width 0.0889)
		(layer "In4.Cu")
		(net "M_D_CPU0_SB_CA<0>")
	)
	(arc
		(start 331.068172 -262.258556)
		(mid 331.351128 -262.182379)
		(end 331.634084 -262.258556)
		(width 0.0889)
		(layer "In4.Cu")
		(net "M_D_CPU0_SB_CA<0>")
	)
	(arc
		(start 340.102444 -262.263382)
		(mid 340.255314 -262.308023)
		(end 340.412832 -262.284718)
		(width 0.0889)
		(layer "In4.Cu")
		(net "M_D_CPU0_SB_CA<0>")
	)
	(arc
		(start 336.708242 -262.258556)
		(mid 336.991198 -262.182379)
		(end 337.274154 -262.258556)
		(width 0.0889)
		(layer "In4.Cu")
		(net "M_D_CPU0_SB_CA<0>")
	)
	(arc
		(start 335.402428 -262.263382)
		(mid 335.585936 -262.308876)
		(end 335.768188 -262.258556)
		(width 0.0889)
		(layer "In4.Cu")
		(net "M_D_CPU0_SB_CA<0>")
	)
	(arc
		(start 337.274154 -262.258556)
		(mid 337.461098 -262.308811)
		(end 337.648042 -262.258556)
		(width 0.0889)
		(layer "In4.Cu")
		(net "M_D_CPU0_SB_CA<0>")
	)
	(arc
		(start 328.248264 -262.258556)
		(mid 328.53122 -262.182379)
		(end 328.814176 -262.258556)
		(width 0.0889)
		(layer "In4.Cu")
		(net "M_D_CPU0_SB_CA<0>")
	)
	(arc
		(start 334.453992 -262.258556)
		(mid 334.636243 -262.308906)
		(end 334.819752 -262.263382)
		(width 0.0889)
		(layer "In4.Cu")
		(net "M_D_CPU0_SB_CA<0>")
	)
	(arc
		(start 339.52815 -262.258556)
		(mid 339.811106 -262.182379)
		(end 340.094062 -262.258556)
		(width 0.0889)
		(layer "In4.Cu")
		(net "M_D_CPU0_SB_CA<0>")
	)
	(arc
		(start 332.008226 -262.258556)
		(mid 332.291182 -262.182379)
		(end 332.574138 -262.258556)
		(width 0.0889)
		(layer "In4.Cu")
		(net "M_D_CPU0_SB_CA<0>")
	)
	(arc
		(start 336.342482 -262.263382)
		(mid 336.52599 -262.308876)
		(end 336.708242 -262.258556)
		(width 0.0889)
		(layer "In4.Cu")
		(net "M_D_CPU0_SB_CA<0>")
	)
	(arc
		(start 328.814176 -262.258556)
		(mid 329.00112 -262.308811)
		(end 329.188064 -262.258556)
		(width 0.0889)
		(layer "In4.Cu")
		(net "M_D_CPU0_SB_CA<0>")
	)
	(arc
		(start 333.513938 -262.258556)
		(mid 333.696189 -262.308906)
		(end 333.879698 -262.263382)
		(width 0.0889)
		(layer "In4.Cu")
		(net "M_D_CPU0_SB_CA<0>")
	)
	(arc
		(start 339.154008 -262.258556)
		(mid 339.336259 -262.308906)
		(end 339.519768 -262.263382)
		(width 0.0889)
		(layer "In4.Cu")
		(net "M_D_CPU0_SB_CA<0>")
	)
	(arc
		(start 333.88808 -262.258556)
		(mid 334.171036 -262.182379)
		(end 334.453992 -262.258556)
		(width 0.0889)
		(layer "In4.Cu")
		(net "M_D_CPU0_SB_CA<0>")
	)
	(arc
		(start 329.753976 -262.258556)
		(mid 329.936227 -262.308906)
		(end 330.119736 -262.263382)
		(width 0.0889)
		(layer "In4.Cu")
		(net "M_D_CPU0_SB_CA<0>")
	)
	(arc
		(start 327.076054 -262.043672)
		(mid 327.489049 -262.098343)
		(end 327.873614 -262.258556)
		(width 0.0889)
		(layer "In4.Cu")
		(net "M_D_CPU0_SB_CA<0>")
	)
	(arc
		(start 335.768188 -262.258556)
		(mid 336.051144 -262.182379)
		(end 336.3341 -262.258556)
		(width 0.0889)
		(layer "In4.Cu")
		(net "M_D_CPU0_SB_CA<0>")
	)
	(arc
		(start 330.702412 -262.263382)
		(mid 330.88592 -262.308876)
		(end 331.068172 -262.258556)
		(width 0.0889)
		(layer "In4.Cu")
		(net "M_D_CPU0_SB_CA<0>")
	)
	(arc
		(start 338.588096 -262.258556)
		(mid 338.871052 -262.182379)
		(end 339.154008 -262.258556)
		(width 0.0889)
		(layer "In4.Cu")
		(net "M_D_CPU0_SB_CA<0>")
	)
	(arc
		(start 334.828134 -262.258556)
		(mid 335.11109 -262.182379)
		(end 335.394046 -262.258556)
		(width 0.0889)
		(layer "In4.Cu")
		(net "M_D_CPU0_SB_CA<0>")
	)
	(arc
		(start 332.948026 -262.258556)
		(mid 333.230982 -262.182379)
		(end 333.513938 -262.258556)
		(width 0.0889)
		(layer "In4.Cu")
		(net "M_D_CPU0_SB_CA<0>")
	)
	(arc
		(start 327.873614 -262.258556)
		(mid 328.056119 -262.309033)
		(end 328.239882 -262.263382)
		(width 0.0889)
		(layer "In4.Cu")
		(net "M_D_CPU0_SB_CA<0>")
	)
	(arc
		(start 332.574138 -262.258556)
		(mid 332.761082 -262.308811)
		(end 332.948026 -262.258556)
		(width 0.0889)
		(layer "In4.Cu")
		(net "M_D_CPU0_SB_CA<0>")
	)
	(segment
		(start 340.747858 -266.530074)
		(end 340.281006 -266.796012)
		(width 0.10668)
		(layer "F.Cu")
		(net "M_D_CPU0_SA_RSP<0>")
	)
	(segment
		(start 308.483254 -268.87551)
		(end 310.934354 -266.42441)
		(width 0.11684)
		(layer "In4.Cu")
		(net "M_D_CPU0_SA_RSP<0>")
	)
	(segment
		(start 286.760158 -269.15999)
		(end 287.044638 -268.87551)
		(width 0.11684)
		(layer "In4.Cu")
		(net "M_D_CPU0_SA_RSP<0>")
	)
	(segment
		(start 301.28337 -269.15999)
		(end 301.56785 -268.87551)
		(width 0.11684)
		(layer "In4.Cu")
		(net "M_D_CPU0_SA_RSP<0>")
	)
	(segment
		(start 329.185016 -267.113004)
		(end 329.195684 -267.106908)
		(width 0.0889)
		(layer "In4.Cu")
		(net "M_D_CPU0_SA_RSP<0>")
	)
	(segment
		(start 290.223702 -268.87551)
		(end 290.508182 -269.15999)
		(width 0.11684)
		(layer "In4.Cu")
		(net "M_D_CPU0_SA_RSP<0>")
	)
	(segment
		(start 298.27728 -269.15999)
		(end 298.56176 -268.87551)
		(width 0.11684)
		(layer "In4.Cu")
		(net "M_D_CPU0_SA_RSP<0>")
	)
	(segment
		(start 293.001192 -268.87551)
		(end 293.285672 -269.15999)
		(width 0.11684)
		(layer "In4.Cu")
		(net "M_D_CPU0_SA_RSP<0>")
	)
	(segment
		(start 291.564822 -269.15999)
		(end 292.472872 -269.15999)
		(width 0.11684)
		(layer "In4.Cu")
		(net "M_D_CPU0_SA_RSP<0>")
	)
	(segment
		(start 285.703518 -269.15999)
		(end 285.987998 -268.87551)
		(width 0.11684)
		(layer "In4.Cu")
		(net "M_D_CPU0_SA_RSP<0>")
	)
	(segment
		(start 305.50993 -269.15999)
		(end 305.79441 -268.87551)
		(width 0.11684)
		(layer "In4.Cu")
		(net "M_D_CPU0_SA_RSP<0>")
	)
	(segment
		(start 296.69232 -268.87551)
		(end 296.9768 -269.15999)
		(width 0.11684)
		(layer "In4.Cu")
		(net "M_D_CPU0_SA_RSP<0>")
	)
	(segment
		(start 308.057804 -268.87551)
		(end 308.483254 -268.87551)
		(width 0.11684)
		(layer "In4.Cu")
		(net "M_D_CPU0_SA_RSP<0>")
	)
	(segment
		(start 300.22673 -269.15999)
		(end 300.51121 -268.87551)
		(width 0.11684)
		(layer "In4.Cu")
		(net "M_D_CPU0_SA_RSP<0>")
	)
	(segment
		(start 292.757352 -268.87551)
		(end 293.001192 -268.87551)
		(width 0.11684)
		(layer "In4.Cu")
		(net "M_D_CPU0_SA_RSP<0>")
	)
	(segment
		(start 302.09617 -269.15999)
		(end 302.34001 -269.15999)
		(width 0.11684)
		(layer "In4.Cu")
		(net "M_D_CPU0_SA_RSP<0>")
	)
	(segment
		(start 305.79441 -268.87551)
		(end 306.03825 -268.87551)
		(width 0.11684)
		(layer "In4.Cu")
		(net "M_D_CPU0_SA_RSP<0>")
	)
	(segment
		(start 288.923222 -268.87551)
		(end 289.167062 -268.87551)
		(width 0.11684)
		(layer "In4.Cu")
		(net "M_D_CPU0_SA_RSP<0>")
	)
	(segment
		(start 340.406482 -267.140182)
		(end 340.42985 -267.052298)
		(width 0.0889)
		(layer "In4.Cu")
		(net "M_D_CPU0_SA_RSP<0>")
	)
	(segment
		(start 340.42985 -267.052298)
		(end 340.281006 -266.796012)
		(width 0.0889)
		(layer "In4.Cu")
		(net "M_D_CPU0_SA_RSP<0>")
	)
	(segment
		(start 303.92497 -268.87551)
		(end 304.20945 -269.15999)
		(width 0.11684)
		(layer "In4.Cu")
		(net "M_D_CPU0_SA_RSP<0>")
	)
	(segment
		(start 289.979862 -268.87551)
		(end 290.223702 -268.87551)
		(width 0.11684)
		(layer "In4.Cu")
		(net "M_D_CPU0_SA_RSP<0>")
	)
	(segment
		(start 290.508182 -269.15999)
		(end 290.752022 -269.15999)
		(width 0.11684)
		(layer "In4.Cu")
		(net "M_D_CPU0_SA_RSP<0>")
	)
	(segment
		(start 301.56785 -268.87551)
		(end 301.81169 -268.87551)
		(width 0.11684)
		(layer "In4.Cu")
		(net "M_D_CPU0_SA_RSP<0>")
	)
	(segment
		(start 302.34001 -269.15999)
		(end 302.62449 -268.87551)
		(width 0.11684)
		(layer "In4.Cu")
		(net "M_D_CPU0_SA_RSP<0>")
	)
	(segment
		(start 302.86833 -268.87551)
		(end 303.15281 -269.15999)
		(width 0.11684)
		(layer "In4.Cu")
		(net "M_D_CPU0_SA_RSP<0>")
	)
	(segment
		(start 286.231838 -268.87551)
		(end 286.516318 -269.15999)
		(width 0.11684)
		(layer "In4.Cu")
		(net "M_D_CPU0_SA_RSP<0>")
	)
	(segment
		(start 300.51121 -268.87551)
		(end 300.75505 -268.87551)
		(width 0.11684)
		(layer "In4.Cu")
		(net "M_D_CPU0_SA_RSP<0>")
	)
	(segment
		(start 286.516318 -269.15999)
		(end 286.760158 -269.15999)
		(width 0.11684)
		(layer "In4.Cu")
		(net "M_D_CPU0_SA_RSP<0>")
	)
	(segment
		(start 285.987998 -268.87551)
		(end 286.231838 -268.87551)
		(width 0.11684)
		(layer "In4.Cu")
		(net "M_D_CPU0_SA_RSP<0>")
	)
	(segment
		(start 328.806556 -267.106908)
		(end 328.817224 -267.113004)
		(width 0.0889)
		(layer "In4.Cu")
		(net "M_D_CPU0_SA_RSP<0>")
	)
	(segment
		(start 310.934354 -266.42441)
		(end 323.989954 -266.42441)
		(width 0.11684)
		(layer "In4.Cu")
		(net "M_D_CPU0_SA_RSP<0>")
	)
	(segment
		(start 328.236834 -267.11783)
		(end 328.244962 -267.113004)
		(width 0.0889)
		(layer "In4.Cu")
		(net "M_D_CPU0_SA_RSP<0>")
	)
	(segment
		(start 337.644994 -267.113004)
		(end 337.655662 -267.106908)
		(width 0.0889)
		(layer "In4.Cu")
		(net "M_D_CPU0_SA_RSP<0>")
	)
	(segment
		(start 304.98161 -268.87551)
		(end 305.26609 -269.15999)
		(width 0.11684)
		(layer "In4.Cu")
		(net "M_D_CPU0_SA_RSP<0>")
	)
	(segment
		(start 304.20945 -269.15999)
		(end 304.45329 -269.15999)
		(width 0.11684)
		(layer "In4.Cu")
		(net "M_D_CPU0_SA_RSP<0>")
	)
	(segment
		(start 289.167062 -268.87551)
		(end 289.451542 -269.15999)
		(width 0.11684)
		(layer "In4.Cu")
		(net "M_D_CPU0_SA_RSP<0>")
	)
	(segment
		(start 324.890638 -266.915392)
		(end 326.079612 -266.915392)
		(width 0.0889)
		(layer "In4.Cu")
		(net "M_D_CPU0_SA_RSP<0>")
	)
	(segment
		(start 289.451542 -269.15999)
		(end 289.695382 -269.15999)
		(width 0.11684)
		(layer "In4.Cu")
		(net "M_D_CPU0_SA_RSP<0>")
	)
	(segment
		(start 326.199754 -267.035534)
		(end 327.590404 -267.035534)
		(width 0.0889)
		(layer "In4.Cu")
		(net "M_D_CPU0_SA_RSP<0>")
	)
	(segment
		(start 290.752022 -269.15999)
		(end 291.036502 -268.87551)
		(width 0.11684)
		(layer "In4.Cu")
		(net "M_D_CPU0_SA_RSP<0>")
	)
	(segment
		(start 295.114472 -268.87551)
		(end 295.398952 -269.15999)
		(width 0.11684)
		(layer "In4.Cu")
		(net "M_D_CPU0_SA_RSP<0>")
	)
	(segment
		(start 331.626464 -267.106908)
		(end 331.637132 -267.113004)
		(width 0.0889)
		(layer "In4.Cu")
		(net "M_D_CPU0_SA_RSP<0>")
	)
	(segment
		(start 306.03825 -268.87551)
		(end 306.32273 -269.15999)
		(width 0.11684)
		(layer "In4.Cu")
		(net "M_D_CPU0_SA_RSP<0>")
	)
	(segment
		(start 306.32273 -269.15999)
		(end 307.773324 -269.15999)
		(width 0.11684)
		(layer "In4.Cu")
		(net "M_D_CPU0_SA_RSP<0>")
	)
	(segment
		(start 287.044638 -268.87551)
		(end 287.288478 -268.87551)
		(width 0.11684)
		(layer "In4.Cu")
		(net "M_D_CPU0_SA_RSP<0>")
	)
	(segment
		(start 296.44848 -268.87551)
		(end 296.69232 -268.87551)
		(width 0.11684)
		(layer "In4.Cu")
		(net "M_D_CPU0_SA_RSP<0>")
	)
	(segment
		(start 332.566518 -267.106908)
		(end 332.577186 -267.113004)
		(width 0.0889)
		(layer "In4.Cu")
		(net "M_D_CPU0_SA_RSP<0>")
	)
	(segment
		(start 332.944978 -267.113004)
		(end 332.955646 -267.106908)
		(width 0.0889)
		(layer "In4.Cu")
		(net "M_D_CPU0_SA_RSP<0>")
	)
	(segment
		(start 297.74896 -268.87551)
		(end 298.03344 -269.15999)
		(width 0.11684)
		(layer "In4.Cu")
		(net "M_D_CPU0_SA_RSP<0>")
	)
	(segment
		(start 294.870632 -268.87551)
		(end 295.114472 -268.87551)
		(width 0.11684)
		(layer "In4.Cu")
		(net "M_D_CPU0_SA_RSP<0>")
	)
	(segment
		(start 305.26609 -269.15999)
		(end 305.50993 -269.15999)
		(width 0.11684)
		(layer "In4.Cu")
		(net "M_D_CPU0_SA_RSP<0>")
	)
	(segment
		(start 294.342312 -269.15999)
		(end 294.586152 -269.15999)
		(width 0.11684)
		(layer "In4.Cu")
		(net "M_D_CPU0_SA_RSP<0>")
	)
	(segment
		(start 302.62449 -268.87551)
		(end 302.86833 -268.87551)
		(width 0.11684)
		(layer "In4.Cu")
		(net "M_D_CPU0_SA_RSP<0>")
	)
	(segment
		(start 295.398952 -269.15999)
		(end 296.164 -269.15999)
		(width 0.11684)
		(layer "In4.Cu")
		(net "M_D_CPU0_SA_RSP<0>")
	)
	(segment
		(start 288.638742 -269.15999)
		(end 288.923222 -268.87551)
		(width 0.11684)
		(layer "In4.Cu")
		(net "M_D_CPU0_SA_RSP<0>")
	)
	(segment
		(start 298.03344 -269.15999)
		(end 298.27728 -269.15999)
		(width 0.11684)
		(layer "In4.Cu")
		(net "M_D_CPU0_SA_RSP<0>")
	)
	(segment
		(start 289.695382 -269.15999)
		(end 289.979862 -268.87551)
		(width 0.11684)
		(layer "In4.Cu")
		(net "M_D_CPU0_SA_RSP<0>")
	)
	(segment
		(start 291.280342 -268.87551)
		(end 291.564822 -269.15999)
		(width 0.11684)
		(layer "In4.Cu")
		(net "M_D_CPU0_SA_RSP<0>")
	)
	(segment
		(start 307.773324 -269.15999)
		(end 308.057804 -268.87551)
		(width 0.11684)
		(layer "In4.Cu")
		(net "M_D_CPU0_SA_RSP<0>")
	)
	(segment
		(start 284.736032 -269.585186)
		(end 285.161228 -269.15999)
		(width 0.11684)
		(layer "In4.Cu")
		(net "M_D_CPU0_SA_RSP<0>")
	)
	(segment
		(start 333.885032 -267.113004)
		(end 333.8957 -267.106908)
		(width 0.0889)
		(layer "In4.Cu")
		(net "M_D_CPU0_SA_RSP<0>")
	)
	(segment
		(start 301.03953 -269.15999)
		(end 301.28337 -269.15999)
		(width 0.11684)
		(layer "In4.Cu")
		(net "M_D_CPU0_SA_RSP<0>")
	)
	(segment
		(start 296.9768 -269.15999)
		(end 297.22064 -269.15999)
		(width 0.11684)
		(layer "In4.Cu")
		(net "M_D_CPU0_SA_RSP<0>")
	)
	(segment
		(start 301.81169 -268.87551)
		(end 302.09617 -269.15999)
		(width 0.11684)
		(layer "In4.Cu")
		(net "M_D_CPU0_SA_RSP<0>")
	)
	(segment
		(start 291.036502 -268.87551)
		(end 291.280342 -268.87551)
		(width 0.11684)
		(layer "In4.Cu")
		(net "M_D_CPU0_SA_RSP<0>")
	)
	(segment
		(start 293.529512 -269.15999)
		(end 293.813992 -268.87551)
		(width 0.11684)
		(layer "In4.Cu")
		(net "M_D_CPU0_SA_RSP<0>")
	)
	(segment
		(start 294.057832 -268.87551)
		(end 294.342312 -269.15999)
		(width 0.11684)
		(layer "In4.Cu")
		(net "M_D_CPU0_SA_RSP<0>")
	)
	(segment
		(start 298.8056 -268.87551)
		(end 299.09008 -269.15999)
		(width 0.11684)
		(layer "In4.Cu")
		(net "M_D_CPU0_SA_RSP<0>")
	)
	(segment
		(start 297.22064 -269.15999)
		(end 297.50512 -268.87551)
		(width 0.11684)
		(layer "In4.Cu")
		(net "M_D_CPU0_SA_RSP<0>")
	)
	(segment
		(start 323.989954 -266.42441)
		(end 324.399656 -266.42441)
		(width 0.0889)
		(layer "In4.Cu")
		(net "M_D_CPU0_SA_RSP<0>")
	)
	(segment
		(start 303.39665 -269.15999)
		(end 303.68113 -268.87551)
		(width 0.11684)
		(layer "In4.Cu")
		(net "M_D_CPU0_SA_RSP<0>")
	)
	(segment
		(start 338.585048 -267.113004)
		(end 338.595716 -267.106908)
		(width 0.0889)
		(layer "In4.Cu")
		(net "M_D_CPU0_SA_RSP<0>")
	)
	(segment
		(start 297.50512 -268.87551)
		(end 297.74896 -268.87551)
		(width 0.11684)
		(layer "In4.Cu")
		(net "M_D_CPU0_SA_RSP<0>")
	)
	(segment
		(start 324.399656 -266.42441)
		(end 324.890638 -266.915392)
		(width 0.0889)
		(layer "In4.Cu")
		(net "M_D_CPU0_SA_RSP<0>")
	)
	(segment
		(start 287.288478 -268.87551)
		(end 287.572958 -269.15999)
		(width 0.11684)
		(layer "In4.Cu")
		(net "M_D_CPU0_SA_RSP<0>")
	)
	(segment
		(start 303.15281 -269.15999)
		(end 303.39665 -269.15999)
		(width 0.11684)
		(layer "In4.Cu")
		(net "M_D_CPU0_SA_RSP<0>")
	)
	(segment
		(start 303.68113 -268.87551)
		(end 303.92497 -268.87551)
		(width 0.11684)
		(layer "In4.Cu")
		(net "M_D_CPU0_SA_RSP<0>")
	)
	(segment
		(start 285.161228 -269.15999)
		(end 285.703518 -269.15999)
		(width 0.11684)
		(layer "In4.Cu")
		(net "M_D_CPU0_SA_RSP<0>")
	)
	(segment
		(start 292.472872 -269.15999)
		(end 292.757352 -268.87551)
		(width 0.11684)
		(layer "In4.Cu")
		(net "M_D_CPU0_SA_RSP<0>")
	)
	(segment
		(start 326.079612 -266.915392)
		(end 326.199754 -267.035534)
		(width 0.0889)
		(layer "In4.Cu")
		(net "M_D_CPU0_SA_RSP<0>")
	)
	(segment
		(start 293.813992 -268.87551)
		(end 294.057832 -268.87551)
		(width 0.11684)
		(layer "In4.Cu")
		(net "M_D_CPU0_SA_RSP<0>")
	)
	(segment
		(start 304.73777 -268.87551)
		(end 304.98161 -268.87551)
		(width 0.11684)
		(layer "In4.Cu")
		(net "M_D_CPU0_SA_RSP<0>")
	)
	(segment
		(start 293.285672 -269.15999)
		(end 293.529512 -269.15999)
		(width 0.11684)
		(layer "In4.Cu")
		(net "M_D_CPU0_SA_RSP<0>")
	)
	(segment
		(start 287.572958 -269.15999)
		(end 288.638742 -269.15999)
		(width 0.11684)
		(layer "In4.Cu")
		(net "M_D_CPU0_SA_RSP<0>")
	)
	(segment
		(start 337.266534 -267.106908)
		(end 337.277202 -267.113004)
		(width 0.0889)
		(layer "In4.Cu")
		(net "M_D_CPU0_SA_RSP<0>")
	)
	(segment
		(start 296.164 -269.15999)
		(end 296.44848 -268.87551)
		(width 0.11684)
		(layer "In4.Cu")
		(net "M_D_CPU0_SA_RSP<0>")
	)
	(segment
		(start 299.09008 -269.15999)
		(end 300.22673 -269.15999)
		(width 0.11684)
		(layer "In4.Cu")
		(net "M_D_CPU0_SA_RSP<0>")
	)
	(segment
		(start 298.56176 -268.87551)
		(end 298.8056 -268.87551)
		(width 0.11684)
		(layer "In4.Cu")
		(net "M_D_CPU0_SA_RSP<0>")
	)
	(segment
		(start 304.45329 -269.15999)
		(end 304.73777 -268.87551)
		(width 0.11684)
		(layer "In4.Cu")
		(net "M_D_CPU0_SA_RSP<0>")
	)
	(segment
		(start 336.32648 -267.106908)
		(end 336.337148 -267.113004)
		(width 0.0889)
		(layer "In4.Cu")
		(net "M_D_CPU0_SA_RSP<0>")
	)
	(segment
		(start 300.75505 -268.87551)
		(end 301.03953 -269.15999)
		(width 0.11684)
		(layer "In4.Cu")
		(net "M_D_CPU0_SA_RSP<0>")
	)
	(segment
		(start 294.586152 -269.15999)
		(end 294.870632 -268.87551)
		(width 0.11684)
		(layer "In4.Cu")
		(net "M_D_CPU0_SA_RSP<0>")
	)
	(arc
		(start 339.525102 -267.113004)
		(mid 339.811106 -267.036052)
		(end 340.09711 -267.113004)
		(width 0.0889)
		(layer "In4.Cu")
		(net "M_D_CPU0_SA_RSP<0>")
	)
	(arc
		(start 327.876916 -267.113004)
		(mid 328.056231 -267.16258)
		(end 328.236834 -267.11783)
		(width 0.0889)
		(layer "In4.Cu")
		(net "M_D_CPU0_SA_RSP<0>")
	)
	(arc
		(start 329.195684 -267.106908)
		(mid 329.477273 -267.036034)
		(end 329.757278 -267.113004)
		(width 0.0889)
		(layer "In4.Cu")
		(net "M_D_CPU0_SA_RSP<0>")
	)
	(arc
		(start 337.655662 -267.106908)
		(mid 337.937251 -267.036034)
		(end 338.217256 -267.113004)
		(width 0.0889)
		(layer "In4.Cu")
		(net "M_D_CPU0_SA_RSP<0>")
	)
	(arc
		(start 327.590404 -267.035534)
		(mid 327.593833 -267.035524)
		(end 327.597262 -267.035534)
		(width 0.0889)
		(layer "In4.Cu")
		(net "M_D_CPU0_SA_RSP<0>")
	)
	(arc
		(start 338.595716 -267.106908)
		(mid 338.877305 -267.036034)
		(end 339.15731 -267.113004)
		(width 0.0889)
		(layer "In4.Cu")
		(net "M_D_CPU0_SA_RSP<0>")
	)
	(arc
		(start 327.597262 -267.035534)
		(mid 327.742108 -267.056165)
		(end 327.876916 -267.113004)
		(width 0.0889)
		(layer "In4.Cu")
		(net "M_D_CPU0_SA_RSP<0>")
	)
	(arc
		(start 329.757278 -267.113004)
		(mid 329.941174 -267.162484)
		(end 330.12507 -267.113004)
		(width 0.0889)
		(layer "In4.Cu")
		(net "M_D_CPU0_SA_RSP<0>")
	)
	(arc
		(start 331.06487 -267.113004)
		(mid 331.344874 -267.035959)
		(end 331.626464 -267.106908)
		(width 0.0889)
		(layer "In4.Cu")
		(net "M_D_CPU0_SA_RSP<0>")
	)
	(arc
		(start 330.697078 -267.113004)
		(mid 330.880974 -267.162484)
		(end 331.06487 -267.113004)
		(width 0.0889)
		(layer "In4.Cu")
		(net "M_D_CPU0_SA_RSP<0>")
	)
	(arc
		(start 335.397094 -267.113004)
		(mid 335.58099 -267.162484)
		(end 335.764886 -267.113004)
		(width 0.0889)
		(layer "In4.Cu")
		(net "M_D_CPU0_SA_RSP<0>")
	)
	(arc
		(start 337.277202 -267.113004)
		(mid 337.461098 -267.162484)
		(end 337.644994 -267.113004)
		(width 0.0889)
		(layer "In4.Cu")
		(net "M_D_CPU0_SA_RSP<0>")
	)
	(arc
		(start 328.817224 -267.113004)
		(mid 329.00112 -267.162484)
		(end 329.185016 -267.113004)
		(width 0.0889)
		(layer "In4.Cu")
		(net "M_D_CPU0_SA_RSP<0>")
	)
	(arc
		(start 336.337148 -267.113004)
		(mid 336.521044 -267.162484)
		(end 336.70494 -267.113004)
		(width 0.0889)
		(layer "In4.Cu")
		(net "M_D_CPU0_SA_RSP<0>")
	)
	(arc
		(start 330.12507 -267.113004)
		(mid 330.411074 -267.036052)
		(end 330.697078 -267.113004)
		(width 0.0889)
		(layer "In4.Cu")
		(net "M_D_CPU0_SA_RSP<0>")
	)
	(arc
		(start 335.764886 -267.113004)
		(mid 336.04489 -267.035959)
		(end 336.32648 -267.106908)
		(width 0.0889)
		(layer "In4.Cu")
		(net "M_D_CPU0_SA_RSP<0>")
	)
	(arc
		(start 340.09711 -267.113004)
		(mid 340.248769 -267.160958)
		(end 340.406482 -267.140182)
		(width 0.0889)
		(layer "In4.Cu")
		(net "M_D_CPU0_SA_RSP<0>")
	)
	(arc
		(start 333.51724 -267.113004)
		(mid 333.701136 -267.162484)
		(end 333.885032 -267.113004)
		(width 0.0889)
		(layer "In4.Cu")
		(net "M_D_CPU0_SA_RSP<0>")
	)
	(arc
		(start 339.15731 -267.113004)
		(mid 339.341206 -267.162484)
		(end 339.525102 -267.113004)
		(width 0.0889)
		(layer "In4.Cu")
		(net "M_D_CPU0_SA_RSP<0>")
	)
	(arc
		(start 332.955646 -267.106908)
		(mid 333.237235 -267.036034)
		(end 333.51724 -267.113004)
		(width 0.0889)
		(layer "In4.Cu")
		(net "M_D_CPU0_SA_RSP<0>")
	)
	(arc
		(start 332.004924 -267.113004)
		(mid 332.284928 -267.035959)
		(end 332.566518 -267.106908)
		(width 0.0889)
		(layer "In4.Cu")
		(net "M_D_CPU0_SA_RSP<0>")
	)
	(arc
		(start 328.244962 -267.113004)
		(mid 328.524966 -267.035959)
		(end 328.806556 -267.106908)
		(width 0.0889)
		(layer "In4.Cu")
		(net "M_D_CPU0_SA_RSP<0>")
	)
	(arc
		(start 336.70494 -267.113004)
		(mid 336.984944 -267.035959)
		(end 337.266534 -267.106908)
		(width 0.0889)
		(layer "In4.Cu")
		(net "M_D_CPU0_SA_RSP<0>")
	)
	(arc
		(start 332.577186 -267.113004)
		(mid 332.761082 -267.162484)
		(end 332.944978 -267.113004)
		(width 0.0889)
		(layer "In4.Cu")
		(net "M_D_CPU0_SA_RSP<0>")
	)
	(arc
		(start 334.457294 -267.113004)
		(mid 334.64119 -267.162484)
		(end 334.825086 -267.113004)
		(width 0.0889)
		(layer "In4.Cu")
		(net "M_D_CPU0_SA_RSP<0>")
	)
	(arc
		(start 331.637132 -267.113004)
		(mid 331.821028 -267.162484)
		(end 332.004924 -267.113004)
		(width 0.0889)
		(layer "In4.Cu")
		(net "M_D_CPU0_SA_RSP<0>")
	)
	(arc
		(start 333.8957 -267.106908)
		(mid 334.177289 -267.036034)
		(end 334.457294 -267.113004)
		(width 0.0889)
		(layer "In4.Cu")
		(net "M_D_CPU0_SA_RSP<0>")
	)
	(arc
		(start 338.217256 -267.113004)
		(mid 338.401152 -267.162484)
		(end 338.585048 -267.113004)
		(width 0.0889)
		(layer "In4.Cu")
		(net "M_D_CPU0_SA_RSP<0>")
	)
	(arc
		(start 334.825086 -267.113004)
		(mid 335.11109 -267.036052)
		(end 335.397094 -267.113004)
		(width 0.0889)
		(layer "In4.Cu")
		(net "M_D_CPU0_SA_RSP<0>")
	)
	(segment
		(start 340.447884 -256.090166)
		(end 339.981032 -255.824228)
		(width 0.10668)
		(layer "F.Cu")
		(net "M_D_CPU0_SA_PAR")
	)
	(segment
		(start 290.386008 -255.580642)
		(end 290.22294 -255.74371)
		(width 0.14478)
		(layer "In4.Cu")
		(net "M_D_CPU0_SA_PAR")
	)
	(segment
		(start 289.27298 -255.368298)
		(end 289.27298 -255.580642)
		(width 0.14478)
		(layer "In4.Cu")
		(net "M_D_CPU0_SA_PAR")
	)
	(segment
		(start 289.436048 -255.20523)
		(end 289.27298 -255.368298)
		(width 0.14478)
		(layer "In4.Cu")
		(net "M_D_CPU0_SA_PAR")
	)
	(segment
		(start 327.94829 -255.501648)
		(end 327.939908 -255.496822)
		(width 0.0889)
		(layer "In4.Cu")
		(net "M_D_CPU0_SA_PAR")
	)
	(segment
		(start 289.666426 -255.20523)
		(end 289.436048 -255.20523)
		(width 0.14478)
		(layer "In4.Cu")
		(net "M_D_CPU0_SA_PAR")
	)
	(segment
		(start 290.22294 -255.74371)
		(end 289.992562 -255.74371)
		(width 0.14478)
		(layer "In4.Cu")
		(net "M_D_CPU0_SA_PAR")
	)
	(segment
		(start 289.829494 -255.580642)
		(end 289.829494 -255.368298)
		(width 0.14478)
		(layer "In4.Cu")
		(net "M_D_CPU0_SA_PAR")
	)
	(segment
		(start 339.981032 -255.824228)
		(end 340.13521 -255.558798)
		(width 0.0889)
		(layer "In4.Cu")
		(net "M_D_CPU0_SA_PAR")
	)
	(segment
		(start 324.500494 -256.60985)
		(end 320.967354 -256.60985)
		(width 0.14478)
		(layer "In4.Cu")
		(net "M_D_CPU0_SA_PAR")
	)
	(segment
		(start 329.828144 -255.501648)
		(end 329.819762 -255.496822)
		(width 0.0889)
		(layer "In4.Cu")
		(net "M_D_CPU0_SA_PAR")
	)
	(segment
		(start 289.992562 -255.74371)
		(end 289.829494 -255.580642)
		(width 0.14478)
		(layer "In4.Cu")
		(net "M_D_CPU0_SA_PAR")
	)
	(segment
		(start 335.102454 -255.496822)
		(end 335.094072 -255.501648)
		(width 0.0889)
		(layer "In4.Cu")
		(net "M_D_CPU0_SA_PAR")
	)
	(segment
		(start 336.042508 -255.496822)
		(end 336.034126 -255.501648)
		(width 0.0889)
		(layer "In4.Cu")
		(net "M_D_CPU0_SA_PAR")
	)
	(segment
		(start 330.402438 -255.496822)
		(end 330.394056 -255.501648)
		(width 0.0889)
		(layer "In4.Cu")
		(net "M_D_CPU0_SA_PAR")
	)
	(segment
		(start 338.862416 -255.496822)
		(end 338.854034 -255.501648)
		(width 0.0889)
		(layer "In4.Cu")
		(net "M_D_CPU0_SA_PAR")
	)
	(segment
		(start 324.75932 -256.60985)
		(end 324.500494 -256.60985)
		(width 0.0889)
		(layer "In4.Cu")
		(net "M_D_CPU0_SA_PAR")
	)
	(segment
		(start 291.10559 -255.74371)
		(end 290.942522 -255.580642)
		(width 0.14478)
		(layer "In4.Cu")
		(net "M_D_CPU0_SA_PAR")
	)
	(segment
		(start 334.52816 -255.501648)
		(end 334.519778 -255.496822)
		(width 0.0889)
		(layer "In4.Cu")
		(net "M_D_CPU0_SA_PAR")
	)
	(segment
		(start 290.386008 -255.368298)
		(end 290.386008 -255.580642)
		(width 0.14478)
		(layer "In4.Cu")
		(net "M_D_CPU0_SA_PAR")
	)
	(segment
		(start 327.017888 -255.507744)
		(end 327.007474 -255.501648)
		(width 0.0889)
		(layer "In4.Cu")
		(net "M_D_CPU0_SA_PAR")
	)
	(segment
		(start 289.829494 -255.368298)
		(end 289.666426 -255.20523)
		(width 0.14478)
		(layer "In4.Cu")
		(net "M_D_CPU0_SA_PAR")
	)
	(segment
		(start 290.549076 -255.20523)
		(end 290.386008 -255.368298)
		(width 0.14478)
		(layer "In4.Cu")
		(net "M_D_CPU0_SA_PAR")
	)
	(segment
		(start 320.967354 -256.60985)
		(end 319.517268 -255.159764)
		(width 0.14478)
		(layer "In4.Cu")
		(net "M_D_CPU0_SA_PAR")
	)
	(segment
		(start 312.928254 -255.74371)
		(end 291.10559 -255.74371)
		(width 0.14478)
		(layer "In4.Cu")
		(net "M_D_CPU0_SA_PAR")
	)
	(segment
		(start 289.27298 -255.580642)
		(end 289.109912 -255.74371)
		(width 0.14478)
		(layer "In4.Cu")
		(net "M_D_CPU0_SA_PAR")
	)
	(segment
		(start 290.942522 -255.368298)
		(end 290.779454 -255.20523)
		(width 0.14478)
		(layer "In4.Cu")
		(net "M_D_CPU0_SA_PAR")
	)
	(segment
		(start 313.5122 -255.159764)
		(end 312.928254 -255.74371)
		(width 0.14478)
		(layer "In4.Cu")
		(net "M_D_CPU0_SA_PAR")
	)
	(segment
		(start 326.351138 -255.577848)
		(end 325.791322 -255.577848)
		(width 0.0889)
		(layer "In4.Cu")
		(net "M_D_CPU0_SA_PAR")
	)
	(segment
		(start 290.942522 -255.580642)
		(end 290.942522 -255.368298)
		(width 0.14478)
		(layer "In4.Cu")
		(net "M_D_CPU0_SA_PAR")
	)
	(segment
		(start 319.517268 -255.159764)
		(end 313.5122 -255.159764)
		(width 0.14478)
		(layer "In4.Cu")
		(net "M_D_CPU0_SA_PAR")
	)
	(segment
		(start 340.13521 -255.558798)
		(end 340.112858 -255.475486)
		(width 0.0889)
		(layer "In4.Cu")
		(net "M_D_CPU0_SA_PAR")
	)
	(segment
		(start 339.80247 -255.496822)
		(end 339.794088 -255.501648)
		(width 0.0889)
		(layer "In4.Cu")
		(net "M_D_CPU0_SA_PAR")
	)
	(segment
		(start 289.109912 -255.74371)
		(end 286.194754 -255.74371)
		(width 0.14478)
		(layer "In4.Cu")
		(net "M_D_CPU0_SA_PAR")
	)
	(segment
		(start 326.649842 -255.492504)
		(end 326.633586 -255.501902)
		(width 0.0889)
		(layer "In4.Cu")
		(net "M_D_CPU0_SA_PAR")
	)
	(segment
		(start 338.288122 -255.501648)
		(end 338.27974 -255.496822)
		(width 0.0889)
		(layer "In4.Cu")
		(net "M_D_CPU0_SA_PAR")
	)
	(segment
		(start 286.194754 -255.74371)
		(end 284.736032 -254.284988)
		(width 0.14478)
		(layer "In4.Cu")
		(net "M_D_CPU0_SA_PAR")
	)
	(segment
		(start 290.779454 -255.20523)
		(end 290.549076 -255.20523)
		(width 0.14478)
		(layer "In4.Cu")
		(net "M_D_CPU0_SA_PAR")
	)
	(segment
		(start 325.791322 -255.577848)
		(end 324.75932 -256.60985)
		(width 0.0889)
		(layer "In4.Cu")
		(net "M_D_CPU0_SA_PAR")
	)
	(segment
		(start 333.588106 -255.501648)
		(end 333.579724 -255.496822)
		(width 0.0889)
		(layer "In4.Cu")
		(net "M_D_CPU0_SA_PAR")
	)
	(segment
		(start 331.342492 -255.496822)
		(end 331.33411 -255.501648)
		(width 0.0889)
		(layer "In4.Cu")
		(net "M_D_CPU0_SA_PAR")
	)
	(arc
		(start 339.794088 -255.501648)
		(mid 339.511132 -255.577825)
		(end 339.228176 -255.501648)
		(width 0.0889)
		(layer "In4.Cu")
		(net "M_D_CPU0_SA_PAR")
	)
	(arc
		(start 339.228176 -255.501648)
		(mid 339.045925 -255.451298)
		(end 338.862416 -255.496822)
		(width 0.0889)
		(layer "In4.Cu")
		(net "M_D_CPU0_SA_PAR")
	)
	(arc
		(start 326.633586 -255.501902)
		(mid 326.497371 -255.558487)
		(end 326.351138 -255.577848)
		(width 0.0889)
		(layer "In4.Cu")
		(net "M_D_CPU0_SA_PAR")
	)
	(arc
		(start 334.519778 -255.496822)
		(mid 334.33627 -255.451328)
		(end 334.154018 -255.501648)
		(width 0.0889)
		(layer "In4.Cu")
		(net "M_D_CPU0_SA_PAR")
	)
	(arc
		(start 338.854034 -255.501648)
		(mid 338.571078 -255.577825)
		(end 338.288122 -255.501648)
		(width 0.0889)
		(layer "In4.Cu")
		(net "M_D_CPU0_SA_PAR")
	)
	(arc
		(start 330.768198 -255.501648)
		(mid 330.585947 -255.451298)
		(end 330.402438 -255.496822)
		(width 0.0889)
		(layer "In4.Cu")
		(net "M_D_CPU0_SA_PAR")
	)
	(arc
		(start 340.112858 -255.475486)
		(mid 339.955348 -255.452288)
		(end 339.80247 -255.496822)
		(width 0.0889)
		(layer "In4.Cu")
		(net "M_D_CPU0_SA_PAR")
	)
	(arc
		(start 335.468214 -255.501648)
		(mid 335.285963 -255.451298)
		(end 335.102454 -255.496822)
		(width 0.0889)
		(layer "In4.Cu")
		(net "M_D_CPU0_SA_PAR")
	)
	(arc
		(start 329.819762 -255.496822)
		(mid 329.636254 -255.451328)
		(end 329.454002 -255.501648)
		(width 0.0889)
		(layer "In4.Cu")
		(net "M_D_CPU0_SA_PAR")
	)
	(arc
		(start 338.27974 -255.496822)
		(mid 338.096232 -255.451328)
		(end 337.91398 -255.501648)
		(width 0.0889)
		(layer "In4.Cu")
		(net "M_D_CPU0_SA_PAR")
	)
	(arc
		(start 327.939908 -255.496822)
		(mid 327.756146 -255.451206)
		(end 327.57364 -255.501648)
		(width 0.0889)
		(layer "In4.Cu")
		(net "M_D_CPU0_SA_PAR")
	)
	(arc
		(start 329.454002 -255.501648)
		(mid 329.171046 -255.577825)
		(end 328.88809 -255.501648)
		(width 0.0889)
		(layer "In4.Cu")
		(net "M_D_CPU0_SA_PAR")
	)
	(arc
		(start 328.514202 -255.501648)
		(mid 328.231246 -255.577825)
		(end 327.94829 -255.501648)
		(width 0.0889)
		(layer "In4.Cu")
		(net "M_D_CPU0_SA_PAR")
	)
	(arc
		(start 328.88809 -255.501648)
		(mid 328.701146 -255.451393)
		(end 328.514202 -255.501648)
		(width 0.0889)
		(layer "In4.Cu")
		(net "M_D_CPU0_SA_PAR")
	)
	(arc
		(start 332.274164 -255.501648)
		(mid 331.991208 -255.577825)
		(end 331.708252 -255.501648)
		(width 0.0889)
		(layer "In4.Cu")
		(net "M_D_CPU0_SA_PAR")
	)
	(arc
		(start 327.007474 -255.501648)
		(mid 326.829824 -255.451388)
		(end 326.649842 -255.492504)
		(width 0.0889)
		(layer "In4.Cu")
		(net "M_D_CPU0_SA_PAR")
	)
	(arc
		(start 336.408268 -255.501648)
		(mid 336.226017 -255.451298)
		(end 336.042508 -255.496822)
		(width 0.0889)
		(layer "In4.Cu")
		(net "M_D_CPU0_SA_PAR")
	)
	(arc
		(start 335.094072 -255.501648)
		(mid 334.811116 -255.577825)
		(end 334.52816 -255.501648)
		(width 0.0889)
		(layer "In4.Cu")
		(net "M_D_CPU0_SA_PAR")
	)
	(arc
		(start 333.213964 -255.501648)
		(mid 332.931008 -255.577825)
		(end 332.648052 -255.501648)
		(width 0.0889)
		(layer "In4.Cu")
		(net "M_D_CPU0_SA_PAR")
	)
	(arc
		(start 330.394056 -255.501648)
		(mid 330.1111 -255.577825)
		(end 329.828144 -255.501648)
		(width 0.0889)
		(layer "In4.Cu")
		(net "M_D_CPU0_SA_PAR")
	)
	(arc
		(start 327.57364 -255.501648)
		(mid 327.296573 -255.577919)
		(end 327.017888 -255.507744)
		(width 0.0889)
		(layer "In4.Cu")
		(net "M_D_CPU0_SA_PAR")
	)
	(arc
		(start 334.154018 -255.501648)
		(mid 333.871062 -255.577825)
		(end 333.588106 -255.501648)
		(width 0.0889)
		(layer "In4.Cu")
		(net "M_D_CPU0_SA_PAR")
	)
	(arc
		(start 331.708252 -255.501648)
		(mid 331.526001 -255.451298)
		(end 331.342492 -255.496822)
		(width 0.0889)
		(layer "In4.Cu")
		(net "M_D_CPU0_SA_PAR")
	)
	(arc
		(start 331.33411 -255.501648)
		(mid 331.051154 -255.577825)
		(end 330.768198 -255.501648)
		(width 0.0889)
		(layer "In4.Cu")
		(net "M_D_CPU0_SA_PAR")
	)
	(arc
		(start 332.648052 -255.501648)
		(mid 332.461108 -255.451393)
		(end 332.274164 -255.501648)
		(width 0.0889)
		(layer "In4.Cu")
		(net "M_D_CPU0_SA_PAR")
	)
	(arc
		(start 336.97418 -255.501648)
		(mid 336.691224 -255.577825)
		(end 336.408268 -255.501648)
		(width 0.0889)
		(layer "In4.Cu")
		(net "M_D_CPU0_SA_PAR")
	)
	(arc
		(start 333.579724 -255.496822)
		(mid 333.396216 -255.451328)
		(end 333.213964 -255.501648)
		(width 0.0889)
		(layer "In4.Cu")
		(net "M_D_CPU0_SA_PAR")
	)
	(arc
		(start 337.91398 -255.501648)
		(mid 337.631024 -255.577825)
		(end 337.348068 -255.501648)
		(width 0.0889)
		(layer "In4.Cu")
		(net "M_D_CPU0_SA_PAR")
	)
	(arc
		(start 336.034126 -255.501648)
		(mid 335.75117 -255.577825)
		(end 335.468214 -255.501648)
		(width 0.0889)
		(layer "In4.Cu")
		(net "M_D_CPU0_SA_PAR")
	)
	(arc
		(start 337.348068 -255.501648)
		(mid 337.161124 -255.451393)
		(end 336.97418 -255.501648)
		(width 0.0889)
		(layer "In4.Cu")
		(net "M_D_CPU0_SA_PAR")
	)
	(segment
		(start 340.447884 -247.990106)
		(end 339.981032 -247.724168)
		(width 0.12954)
		(layer "F.Cu")
		(net "M_D_CPU0_SA_DQS_DP<9>")
	)
	(segment
		(start 302.2219 -240.529618)
		(end 304.158904 -240.529618)
		(width 0.16002)
		(layer "In4.Cu")
		(net "M_D_CPU0_SA_DQS_DP<9>")
	)
	(segment
		(start 293.381684 -239.710214)
		(end 295.434766 -240.560352)
		(width 0.16002)
		(layer "In4.Cu")
		(net "M_D_CPU0_SA_DQS_DP<9>")
	)
	(segment
		(start 295.434766 -240.560352)
		(end 296.584116 -240.560352)
		(width 0.16002)
		(layer "In4.Cu")
		(net "M_D_CPU0_SA_DQS_DP<9>")
	)
	(segment
		(start 291.420804 -239.710214)
		(end 293.381684 -239.710214)
		(width 0.16002)
		(layer "In4.Cu")
		(net "M_D_CPU0_SA_DQS_DP<9>")
	)
	(segment
		(start 296.919142 -240.225326)
		(end 297.396662 -240.225326)
		(width 0.16002)
		(layer "In4.Cu")
		(net "M_D_CPU0_SA_DQS_DP<9>")
	)
	(segment
		(start 301.402496 -239.710214)
		(end 302.2219 -240.529618)
		(width 0.16002)
		(layer "In4.Cu")
		(net "M_D_CPU0_SA_DQS_DP<9>")
	)
	(segment
		(start 336.032602 -247.399048)
		(end 336.040984 -247.394222)
		(width 0.09525)
		(layer "In4.Cu")
		(net "M_D_CPU0_SA_DQS_DP<9>")
	)
	(segment
		(start 326.611234 -247.41124)
		(end 326.632062 -247.399048)
		(width 0.09525)
		(layer "In4.Cu")
		(net "M_D_CPU0_SA_DQS_DP<9>")
	)
	(segment
		(start 325.727568 -247.347486)
		(end 325.880222 -247.347486)
		(width 0.09525)
		(layer "In4.Cu")
		(net "M_D_CPU0_SA_DQS_DP<9>")
	)
	(segment
		(start 338.85251 -247.399048)
		(end 338.860892 -247.394222)
		(width 0.09525)
		(layer "In4.Cu")
		(net "M_D_CPU0_SA_DQS_DP<9>")
	)
	(segment
		(start 307.80736 -242.26012)
		(end 312.711592 -247.164352)
		(width 0.16002)
		(layer "In4.Cu")
		(net "M_D_CPU0_SA_DQS_DP<9>")
	)
	(segment
		(start 329.821286 -247.394222)
		(end 329.829668 -247.399048)
		(width 0.09525)
		(layer "In4.Cu")
		(net "M_D_CPU0_SA_DQS_DP<9>")
	)
	(segment
		(start 326.632062 -247.399048)
		(end 326.644 -247.39219)
		(width 0.09525)
		(layer "In4.Cu")
		(net "M_D_CPU0_SA_DQS_DP<9>")
	)
	(segment
		(start 283.896816 -239.726978)
		(end 284.376876 -239.726978)
		(width 0.16002)
		(layer "In4.Cu")
		(net "M_D_CPU0_SA_DQS_DP<9>")
	)
	(segment
		(start 291.051742 -239.341152)
		(end 291.420804 -239.710214)
		(width 0.16002)
		(layer "In4.Cu")
		(net "M_D_CPU0_SA_DQS_DP<9>")
	)
	(segment
		(start 335.092548 -247.399048)
		(end 335.10093 -247.394222)
		(width 0.09525)
		(layer "In4.Cu")
		(net "M_D_CPU0_SA_DQS_DP<9>")
	)
	(segment
		(start 289.040316 -240.560352)
		(end 289.375342 -240.225326)
		(width 0.16002)
		(layer "In4.Cu")
		(net "M_D_CPU0_SA_DQS_DP<9>")
	)
	(segment
		(start 323.028056 -247.164352)
		(end 323.199506 -247.335802)
		(width 0.16002)
		(layer "In4.Cu")
		(net "M_D_CPU0_SA_DQS_DP<9>")
	)
	(segment
		(start 324.443598 -247.582182)
		(end 325.492872 -247.582182)
		(width 0.09525)
		(layer "In4.Cu")
		(net "M_D_CPU0_SA_DQS_DP<9>")
	)
	(segment
		(start 297.396662 -240.225326)
		(end 298.280836 -239.341152)
		(width 0.16002)
		(layer "In4.Cu")
		(net "M_D_CPU0_SA_DQS_DP<9>")
	)
	(segment
		(start 284.973776 -239.843818)
		(end 285.090616 -239.726978)
		(width 0.16002)
		(layer "In4.Cu")
		(net "M_D_CPU0_SA_DQS_DP<9>")
	)
	(segment
		(start 290.737036 -239.341152)
		(end 291.051742 -239.341152)
		(width 0.16002)
		(layer "In4.Cu")
		(net "M_D_CPU0_SA_DQS_DP<9>")
	)
	(segment
		(start 285.090616 -239.726978)
		(end 286.286956 -239.726978)
		(width 0.16002)
		(layer "In4.Cu")
		(net "M_D_CPU0_SA_DQS_DP<9>")
	)
	(segment
		(start 325.492872 -247.582182)
		(end 325.727568 -247.347486)
		(width 0.09525)
		(layer "In4.Cu")
		(net "M_D_CPU0_SA_DQS_DP<9>")
	)
	(segment
		(start 312.711592 -247.164352)
		(end 323.028056 -247.164352)
		(width 0.16002)
		(layer "In4.Cu")
		(net "M_D_CPU0_SA_DQS_DP<9>")
	)
	(segment
		(start 283.123894 -239.380522)
		(end 283.55036 -239.380522)
		(width 0.16002)
		(layer "In4.Cu")
		(net "M_D_CPU0_SA_DQS_DP<9>")
	)
	(segment
		(start 298.280836 -239.341152)
		(end 298.595542 -239.341152)
		(width 0.16002)
		(layer "In4.Cu")
		(net "M_D_CPU0_SA_DQS_DP<9>")
	)
	(segment
		(start 334.521302 -247.394222)
		(end 334.529684 -247.399048)
		(width 0.09525)
		(layer "In4.Cu")
		(net "M_D_CPU0_SA_DQS_DP<9>")
	)
	(segment
		(start 327.941432 -247.394222)
		(end 327.949814 -247.399048)
		(width 0.09525)
		(layer "In4.Cu")
		(net "M_D_CPU0_SA_DQS_DP<9>")
	)
	(segment
		(start 340.134956 -247.458738)
		(end 339.981032 -247.724168)
		(width 0.09525)
		(layer "In4.Cu")
		(net "M_D_CPU0_SA_DQS_DP<9>")
	)
	(segment
		(start 298.964604 -239.710214)
		(end 301.402496 -239.710214)
		(width 0.16002)
		(layer "In4.Cu")
		(net "M_D_CPU0_SA_DQS_DP<9>")
	)
	(segment
		(start 323.199506 -247.335802)
		(end 323.895974 -247.335802)
		(width 0.16002)
		(layer "In4.Cu")
		(net "M_D_CPU0_SA_DQS_DP<9>")
	)
	(segment
		(start 280.635964 -239.835182)
		(end 280.909776 -239.56137)
		(width 0.16002)
		(layer "In4.Cu")
		(net "M_D_CPU0_SA_DQS_DP<9>")
	)
	(segment
		(start 324.138036 -247.27662)
		(end 324.443598 -247.582182)
		(width 0.09525)
		(layer "In4.Cu")
		(net "M_D_CPU0_SA_DQS_DP<9>")
	)
	(segment
		(start 289.852862 -240.225326)
		(end 290.737036 -239.341152)
		(width 0.16002)
		(layer "In4.Cu")
		(net "M_D_CPU0_SA_DQS_DP<9>")
	)
	(segment
		(start 339.792564 -247.399048)
		(end 339.800946 -247.394222)
		(width 0.09525)
		(layer "In4.Cu")
		(net "M_D_CPU0_SA_DQS_DP<9>")
	)
	(segment
		(start 304.463196 -240.225326)
		(end 304.96764 -240.225326)
		(width 0.16002)
		(layer "In4.Cu")
		(net "M_D_CPU0_SA_DQS_DP<9>")
	)
	(segment
		(start 333.581248 -247.394222)
		(end 333.58963 -247.399048)
		(width 0.09525)
		(layer "In4.Cu")
		(net "M_D_CPU0_SA_DQS_DP<9>")
	)
	(segment
		(start 307.002434 -242.26012)
		(end 307.80736 -242.26012)
		(width 0.16002)
		(layer "In4.Cu")
		(net "M_D_CPU0_SA_DQS_DP<9>")
	)
	(segment
		(start 283.55036 -239.380522)
		(end 283.896816 -239.726978)
		(width 0.16002)
		(layer "In4.Cu")
		(net "M_D_CPU0_SA_DQS_DP<9>")
	)
	(segment
		(start 338.281264 -247.394222)
		(end 338.289646 -247.399048)
		(width 0.09525)
		(layer "In4.Cu")
		(net "M_D_CPU0_SA_DQS_DP<9>")
	)
	(segment
		(start 330.392532 -247.399048)
		(end 330.400914 -247.394222)
		(width 0.09525)
		(layer "In4.Cu")
		(net "M_D_CPU0_SA_DQS_DP<9>")
	)
	(segment
		(start 304.158904 -240.529618)
		(end 304.463196 -240.225326)
		(width 0.16002)
		(layer "In4.Cu")
		(net "M_D_CPU0_SA_DQS_DP<9>")
	)
	(segment
		(start 323.919596 -247.335802)
		(end 323.978778 -247.27662)
		(width 0.09525)
		(layer "In4.Cu")
		(net "M_D_CPU0_SA_DQS_DP<9>")
	)
	(segment
		(start 327.008998 -247.399048)
		(end 327.019412 -247.405144)
		(width 0.09525)
		(layer "In4.Cu")
		(net "M_D_CPU0_SA_DQS_DP<9>")
	)
	(segment
		(start 284.376876 -239.726978)
		(end 284.493716 -239.843818)
		(width 0.16002)
		(layer "In4.Cu")
		(net "M_D_CPU0_SA_DQS_DP<9>")
	)
	(segment
		(start 286.286956 -239.726978)
		(end 287.12033 -240.560352)
		(width 0.16002)
		(layer "In4.Cu")
		(net "M_D_CPU0_SA_DQS_DP<9>")
	)
	(segment
		(start 280.909776 -239.56137)
		(end 282.943046 -239.56137)
		(width 0.16002)
		(layer "In4.Cu")
		(net "M_D_CPU0_SA_DQS_DP<9>")
	)
	(segment
		(start 287.12033 -240.560352)
		(end 289.040316 -240.560352)
		(width 0.16002)
		(layer "In4.Cu")
		(net "M_D_CPU0_SA_DQS_DP<9>")
	)
	(segment
		(start 298.595542 -239.341152)
		(end 298.964604 -239.710214)
		(width 0.16002)
		(layer "In4.Cu")
		(net "M_D_CPU0_SA_DQS_DP<9>")
	)
	(segment
		(start 296.584116 -240.560352)
		(end 296.919142 -240.225326)
		(width 0.16002)
		(layer "In4.Cu")
		(net "M_D_CPU0_SA_DQS_DP<9>")
	)
	(segment
		(start 323.895974 -247.335802)
		(end 323.919596 -247.335802)
		(width 0.09525)
		(layer "In4.Cu")
		(net "M_D_CPU0_SA_DQS_DP<9>")
	)
	(segment
		(start 284.493716 -239.843818)
		(end 284.973776 -239.843818)
		(width 0.16002)
		(layer "In4.Cu")
		(net "M_D_CPU0_SA_DQS_DP<9>")
	)
	(segment
		(start 340.111588 -247.37187)
		(end 340.134956 -247.458738)
		(width 0.09525)
		(layer "In4.Cu")
		(net "M_D_CPU0_SA_DQS_DP<9>")
	)
	(segment
		(start 304.96764 -240.225326)
		(end 307.002434 -242.26012)
		(width 0.16002)
		(layer "In4.Cu")
		(net "M_D_CPU0_SA_DQS_DP<9>")
	)
	(segment
		(start 323.978778 -247.27662)
		(end 324.138036 -247.27662)
		(width 0.09525)
		(layer "In4.Cu")
		(net "M_D_CPU0_SA_DQS_DP<9>")
	)
	(segment
		(start 289.375342 -240.225326)
		(end 289.852862 -240.225326)
		(width 0.16002)
		(layer "In4.Cu")
		(net "M_D_CPU0_SA_DQS_DP<9>")
	)
	(segment
		(start 282.943046 -239.56137)
		(end 283.123894 -239.380522)
		(width 0.16002)
		(layer "In4.Cu")
		(net "M_D_CPU0_SA_DQS_DP<9>")
	)
	(segment
		(start 331.332586 -247.399048)
		(end 331.340968 -247.394222)
		(width 0.09525)
		(layer "In4.Cu")
		(net "M_D_CPU0_SA_DQS_DP<9>")
	)
	(arc
		(start 338.289646 -247.399048)
		(mid 338.571078 -247.474803)
		(end 338.85251 -247.399048)
		(width 0.09525)
		(layer "In4.Cu")
		(net "M_D_CPU0_SA_DQS_DP<9>")
	)
	(arc
		(start 333.58963 -247.399048)
		(mid 333.871062 -247.474803)
		(end 334.152494 -247.399048)
		(width 0.09525)
		(layer "In4.Cu")
		(net "M_D_CPU0_SA_DQS_DP<9>")
	)
	(arc
		(start 328.889614 -247.399048)
		(mid 329.171046 -247.474803)
		(end 329.452478 -247.399048)
		(width 0.09525)
		(layer "In4.Cu")
		(net "M_D_CPU0_SA_DQS_DP<9>")
	)
	(arc
		(start 326.069198 -247.399048)
		(mid 326.338631 -247.474919)
		(end 326.611234 -247.41124)
		(width 0.09525)
		(layer "In4.Cu")
		(net "M_D_CPU0_SA_DQS_DP<9>")
	)
	(arc
		(start 332.649576 -247.399048)
		(mid 332.931008 -247.474803)
		(end 333.21244 -247.399048)
		(width 0.09525)
		(layer "In4.Cu")
		(net "M_D_CPU0_SA_DQS_DP<9>")
	)
	(arc
		(start 328.512678 -247.399048)
		(mid 328.701146 -247.348371)
		(end 328.889614 -247.399048)
		(width 0.09525)
		(layer "In4.Cu")
		(net "M_D_CPU0_SA_DQS_DP<9>")
	)
	(arc
		(start 336.409792 -247.399048)
		(mid 336.691224 -247.474803)
		(end 336.972656 -247.399048)
		(width 0.09525)
		(layer "In4.Cu")
		(net "M_D_CPU0_SA_DQS_DP<9>")
	)
	(arc
		(start 338.860892 -247.394222)
		(mid 339.045924 -247.348308)
		(end 339.2297 -247.399048)
		(width 0.09525)
		(layer "In4.Cu")
		(net "M_D_CPU0_SA_DQS_DP<9>")
	)
	(arc
		(start 326.644 -247.39219)
		(mid 326.827381 -247.348359)
		(end 327.008998 -247.399048)
		(width 0.09525)
		(layer "In4.Cu")
		(net "M_D_CPU0_SA_DQS_DP<9>")
	)
	(arc
		(start 329.452478 -247.399048)
		(mid 329.636253 -247.348276)
		(end 329.821286 -247.394222)
		(width 0.09525)
		(layer "In4.Cu")
		(net "M_D_CPU0_SA_DQS_DP<9>")
	)
	(arc
		(start 329.829668 -247.399048)
		(mid 330.1111 -247.474803)
		(end 330.392532 -247.399048)
		(width 0.09525)
		(layer "In4.Cu")
		(net "M_D_CPU0_SA_DQS_DP<9>")
	)
	(arc
		(start 333.21244 -247.399048)
		(mid 333.396215 -247.348276)
		(end 333.581248 -247.394222)
		(width 0.09525)
		(layer "In4.Cu")
		(net "M_D_CPU0_SA_DQS_DP<9>")
	)
	(arc
		(start 334.152494 -247.399048)
		(mid 334.336269 -247.348276)
		(end 334.521302 -247.394222)
		(width 0.09525)
		(layer "In4.Cu")
		(net "M_D_CPU0_SA_DQS_DP<9>")
	)
	(arc
		(start 339.800946 -247.394222)
		(mid 339.953841 -247.349394)
		(end 340.111588 -247.37187)
		(width 0.09525)
		(layer "In4.Cu")
		(net "M_D_CPU0_SA_DQS_DP<9>")
	)
	(arc
		(start 331.340968 -247.394222)
		(mid 331.526 -247.348308)
		(end 331.709776 -247.399048)
		(width 0.09525)
		(layer "In4.Cu")
		(net "M_D_CPU0_SA_DQS_DP<9>")
	)
	(arc
		(start 327.572116 -247.399048)
		(mid 327.756145 -247.348149)
		(end 327.941432 -247.394222)
		(width 0.09525)
		(layer "In4.Cu")
		(net "M_D_CPU0_SA_DQS_DP<9>")
	)
	(arc
		(start 330.769722 -247.399048)
		(mid 331.051154 -247.474803)
		(end 331.332586 -247.399048)
		(width 0.09525)
		(layer "In4.Cu")
		(net "M_D_CPU0_SA_DQS_DP<9>")
	)
	(arc
		(start 327.019412 -247.405144)
		(mid 327.296574 -247.474944)
		(end 327.572116 -247.399048)
		(width 0.09525)
		(layer "In4.Cu")
		(net "M_D_CPU0_SA_DQS_DP<9>")
	)
	(arc
		(start 330.400914 -247.394222)
		(mid 330.585946 -247.348308)
		(end 330.769722 -247.399048)
		(width 0.09525)
		(layer "In4.Cu")
		(net "M_D_CPU0_SA_DQS_DP<9>")
	)
	(arc
		(start 327.949814 -247.399048)
		(mid 328.231246 -247.474803)
		(end 328.512678 -247.399048)
		(width 0.09525)
		(layer "In4.Cu")
		(net "M_D_CPU0_SA_DQS_DP<9>")
	)
	(arc
		(start 335.469738 -247.399048)
		(mid 335.75117 -247.474803)
		(end 336.032602 -247.399048)
		(width 0.09525)
		(layer "In4.Cu")
		(net "M_D_CPU0_SA_DQS_DP<9>")
	)
	(arc
		(start 334.529684 -247.399048)
		(mid 334.811116 -247.474803)
		(end 335.092548 -247.399048)
		(width 0.09525)
		(layer "In4.Cu")
		(net "M_D_CPU0_SA_DQS_DP<9>")
	)
	(arc
		(start 337.349592 -247.399048)
		(mid 337.631024 -247.474803)
		(end 337.912456 -247.399048)
		(width 0.09525)
		(layer "In4.Cu")
		(net "M_D_CPU0_SA_DQS_DP<9>")
	)
	(arc
		(start 337.912456 -247.399048)
		(mid 338.096231 -247.348276)
		(end 338.281264 -247.394222)
		(width 0.09525)
		(layer "In4.Cu")
		(net "M_D_CPU0_SA_DQS_DP<9>")
	)
	(arc
		(start 331.709776 -247.399048)
		(mid 331.991208 -247.474803)
		(end 332.27264 -247.399048)
		(width 0.09525)
		(layer "In4.Cu")
		(net "M_D_CPU0_SA_DQS_DP<9>")
	)
	(arc
		(start 336.040984 -247.394222)
		(mid 336.226016 -247.348308)
		(end 336.409792 -247.399048)
		(width 0.09525)
		(layer "In4.Cu")
		(net "M_D_CPU0_SA_DQS_DP<9>")
	)
	(arc
		(start 336.972656 -247.399048)
		(mid 337.161124 -247.348371)
		(end 337.349592 -247.399048)
		(width 0.09525)
		(layer "In4.Cu")
		(net "M_D_CPU0_SA_DQS_DP<9>")
	)
	(arc
		(start 325.880222 -247.347486)
		(mid 325.978119 -247.360772)
		(end 326.069198 -247.399048)
		(width 0.09525)
		(layer "In4.Cu")
		(net "M_D_CPU0_SA_DQS_DP<9>")
	)
	(arc
		(start 332.27264 -247.399048)
		(mid 332.461108 -247.348371)
		(end 332.649576 -247.399048)
		(width 0.09525)
		(layer "In4.Cu")
		(net "M_D_CPU0_SA_DQS_DP<9>")
	)
	(arc
		(start 335.10093 -247.394222)
		(mid 335.285962 -247.348308)
		(end 335.469738 -247.399048)
		(width 0.09525)
		(layer "In4.Cu")
		(net "M_D_CPU0_SA_DQS_DP<9>")
	)
	(arc
		(start 339.2297 -247.399048)
		(mid 339.511132 -247.474803)
		(end 339.792564 -247.399048)
		(width 0.09525)
		(layer "In4.Cu")
		(net "M_D_CPU0_SA_DQS_DP<9>")
	)
	(segment
		(start 340.447884 -243.13007)
		(end 339.981032 -242.864132)
		(width 0.12954)
		(layer "F.Cu")
		(net "M_D_CPU0_SA_DQS_DP<8>")
	)
	(segment
		(start 324.181978 -241.598196)
		(end 324.181978 -241.723926)
		(width 0.09525)
		(layer "In4.Cu")
		(net "M_D_CPU0_SA_DQS_DP<8>")
	)
	(segment
		(start 283.896816 -230.376984)
		(end 284.376876 -230.376984)
		(width 0.16002)
		(layer "In4.Cu")
		(net "M_D_CPU0_SA_DQS_DP<8>")
	)
	(segment
		(start 335.092548 -242.539012)
		(end 335.10093 -242.534186)
		(width 0.09525)
		(layer "In4.Cu")
		(net "M_D_CPU0_SA_DQS_DP<8>")
	)
	(segment
		(start 285.090616 -230.376984)
		(end 286.286956 -230.376984)
		(width 0.16002)
		(layer "In4.Cu")
		(net "M_D_CPU0_SA_DQS_DP<8>")
	)
	(segment
		(start 334.521302 -242.534186)
		(end 334.529684 -242.539012)
		(width 0.09525)
		(layer "In4.Cu")
		(net "M_D_CPU0_SA_DQS_DP<8>")
	)
	(segment
		(start 305.187096 -230.875332)
		(end 305.522122 -231.210358)
		(width 0.16002)
		(layer "In4.Cu")
		(net "M_D_CPU0_SA_DQS_DP<8>")
	)
	(segment
		(start 289.375342 -230.875332)
		(end 289.852862 -230.875332)
		(width 0.16002)
		(layer "In4.Cu")
		(net "M_D_CPU0_SA_DQS_DP<8>")
	)
	(segment
		(start 294.63111 -231.210358)
		(end 296.584116 -231.210358)
		(width 0.16002)
		(layer "In4.Cu")
		(net "M_D_CPU0_SA_DQS_DP<8>")
	)
	(segment
		(start 298.280836 -229.991158)
		(end 298.595542 -229.991158)
		(width 0.16002)
		(layer "In4.Cu")
		(net "M_D_CPU0_SA_DQS_DP<8>")
	)
	(segment
		(start 323.920612 -241.489992)
		(end 324.073774 -241.489992)
		(width 0.09525)
		(layer "In4.Cu")
		(net "M_D_CPU0_SA_DQS_DP<8>")
	)
	(segment
		(start 340.134956 -242.598702)
		(end 339.981032 -242.864132)
		(width 0.09525)
		(layer "In4.Cu")
		(net "M_D_CPU0_SA_DQS_DP<8>")
	)
	(segment
		(start 297.396662 -230.875332)
		(end 298.280836 -229.991158)
		(width 0.16002)
		(layer "In4.Cu")
		(net "M_D_CPU0_SA_DQS_DP<8>")
	)
	(segment
		(start 296.919142 -230.875332)
		(end 297.396662 -230.875332)
		(width 0.16002)
		(layer "In4.Cu")
		(net "M_D_CPU0_SA_DQS_DP<8>")
	)
	(segment
		(start 280.635964 -230.485188)
		(end 280.91003 -230.211122)
		(width 0.16002)
		(layer "In4.Cu")
		(net "M_D_CPU0_SA_DQS_DP<8>")
	)
	(segment
		(start 287.12033 -231.210358)
		(end 289.040316 -231.210358)
		(width 0.16002)
		(layer "In4.Cu")
		(net "M_D_CPU0_SA_DQS_DP<8>")
	)
	(segment
		(start 291.051742 -229.991158)
		(end 291.420804 -230.36022)
		(width 0.16002)
		(layer "In4.Cu")
		(net "M_D_CPU0_SA_DQS_DP<8>")
	)
	(segment
		(start 283.048964 -230.030528)
		(end 283.55036 -230.030528)
		(width 0.16002)
		(layer "In4.Cu")
		(net "M_D_CPU0_SA_DQS_DP<8>")
	)
	(segment
		(start 318.147446 -241.549174)
		(end 323.837808 -241.549174)
		(width 0.16002)
		(layer "In4.Cu")
		(net "M_D_CPU0_SA_DQS_DP<8>")
	)
	(segment
		(start 290.737036 -229.991158)
		(end 291.051742 -229.991158)
		(width 0.16002)
		(layer "In4.Cu")
		(net "M_D_CPU0_SA_DQS_DP<8>")
	)
	(segment
		(start 323.837808 -241.549174)
		(end 323.86143 -241.549174)
		(width 0.09525)
		(layer "In4.Cu")
		(net "M_D_CPU0_SA_DQS_DP<8>")
	)
	(segment
		(start 293.780972 -230.36022)
		(end 294.63111 -231.210358)
		(width 0.16002)
		(layer "In4.Cu")
		(net "M_D_CPU0_SA_DQS_DP<8>")
	)
	(segment
		(start 286.286956 -230.376984)
		(end 287.12033 -231.210358)
		(width 0.16002)
		(layer "In4.Cu")
		(net "M_D_CPU0_SA_DQS_DP<8>")
	)
	(segment
		(start 291.420804 -230.36022)
		(end 293.780972 -230.36022)
		(width 0.16002)
		(layer "In4.Cu")
		(net "M_D_CPU0_SA_DQS_DP<8>")
	)
	(segment
		(start 323.86143 -241.549174)
		(end 323.920612 -241.489992)
		(width 0.09525)
		(layer "In4.Cu")
		(net "M_D_CPU0_SA_DQS_DP<8>")
	)
	(segment
		(start 283.55036 -230.030528)
		(end 283.896816 -230.376984)
		(width 0.16002)
		(layer "In4.Cu")
		(net "M_D_CPU0_SA_DQS_DP<8>")
	)
	(segment
		(start 284.376876 -230.376984)
		(end 284.493716 -230.493824)
		(width 0.16002)
		(layer "In4.Cu")
		(net "M_D_CPU0_SA_DQS_DP<8>")
	)
	(segment
		(start 338.85251 -242.539012)
		(end 338.860892 -242.534186)
		(width 0.09525)
		(layer "In4.Cu")
		(net "M_D_CPU0_SA_DQS_DP<8>")
	)
	(segment
		(start 336.032602 -242.539012)
		(end 336.040984 -242.534186)
		(width 0.09525)
		(layer "In4.Cu")
		(net "M_D_CPU0_SA_DQS_DP<8>")
	)
	(segment
		(start 298.595542 -229.991158)
		(end 298.964604 -230.36022)
		(width 0.16002)
		(layer "In4.Cu")
		(net "M_D_CPU0_SA_DQS_DP<8>")
	)
	(segment
		(start 330.392532 -242.539012)
		(end 330.400914 -242.534186)
		(width 0.09525)
		(layer "In4.Cu")
		(net "M_D_CPU0_SA_DQS_DP<8>")
	)
	(segment
		(start 305.522122 -231.210358)
		(end 307.80863 -231.210358)
		(width 0.16002)
		(layer "In4.Cu")
		(net "M_D_CPU0_SA_DQS_DP<8>")
	)
	(segment
		(start 298.964604 -230.36022)
		(end 301.397416 -230.36022)
		(width 0.16002)
		(layer "In4.Cu")
		(net "M_D_CPU0_SA_DQS_DP<8>")
	)
	(segment
		(start 339.792564 -242.539012)
		(end 339.800946 -242.534186)
		(width 0.09525)
		(layer "In4.Cu")
		(net "M_D_CPU0_SA_DQS_DP<8>")
	)
	(segment
		(start 296.584116 -231.210358)
		(end 296.919142 -230.875332)
		(width 0.16002)
		(layer "In4.Cu")
		(net "M_D_CPU0_SA_DQS_DP<8>")
	)
	(segment
		(start 289.040316 -231.210358)
		(end 289.375342 -230.875332)
		(width 0.16002)
		(layer "In4.Cu")
		(net "M_D_CPU0_SA_DQS_DP<8>")
	)
	(segment
		(start 284.973776 -230.493824)
		(end 285.090616 -230.376984)
		(width 0.16002)
		(layer "In4.Cu")
		(net "M_D_CPU0_SA_DQS_DP<8>")
	)
	(segment
		(start 324.181978 -241.723926)
		(end 324.617334 -242.159282)
		(width 0.09525)
		(layer "In4.Cu")
		(net "M_D_CPU0_SA_DQS_DP<8>")
	)
	(segment
		(start 340.111588 -242.511834)
		(end 340.134956 -242.598702)
		(width 0.09525)
		(layer "In4.Cu")
		(net "M_D_CPU0_SA_DQS_DP<8>")
	)
	(segment
		(start 284.493716 -230.493824)
		(end 284.973776 -230.493824)
		(width 0.16002)
		(layer "In4.Cu")
		(net "M_D_CPU0_SA_DQS_DP<8>")
	)
	(segment
		(start 282.86837 -230.211122)
		(end 283.048964 -230.030528)
		(width 0.16002)
		(layer "In4.Cu")
		(net "M_D_CPU0_SA_DQS_DP<8>")
	)
	(segment
		(start 325.284084 -242.159282)
		(end 325.612252 -242.48745)
		(width 0.09525)
		(layer "In4.Cu")
		(net "M_D_CPU0_SA_DQS_DP<8>")
	)
	(segment
		(start 301.397416 -230.36022)
		(end 302.21682 -231.179624)
		(width 0.16002)
		(layer "In4.Cu")
		(net "M_D_CPU0_SA_DQS_DP<8>")
	)
	(segment
		(start 289.852862 -230.875332)
		(end 290.737036 -229.991158)
		(width 0.16002)
		(layer "In4.Cu")
		(net "M_D_CPU0_SA_DQS_DP<8>")
	)
	(segment
		(start 327.572624 -242.539012)
		(end 327.581006 -242.534186)
		(width 0.09525)
		(layer "In4.Cu")
		(net "M_D_CPU0_SA_DQS_DP<8>")
	)
	(segment
		(start 304.463196 -230.875332)
		(end 305.187096 -230.875332)
		(width 0.16002)
		(layer "In4.Cu")
		(net "M_D_CPU0_SA_DQS_DP<8>")
	)
	(segment
		(start 324.073774 -241.489992)
		(end 324.181978 -241.598196)
		(width 0.09525)
		(layer "In4.Cu")
		(net "M_D_CPU0_SA_DQS_DP<8>")
	)
	(segment
		(start 338.281264 -242.534186)
		(end 338.289646 -242.539012)
		(width 0.09525)
		(layer "In4.Cu")
		(net "M_D_CPU0_SA_DQS_DP<8>")
	)
	(segment
		(start 307.80863 -231.210358)
		(end 318.147446 -241.549174)
		(width 0.16002)
		(layer "In4.Cu")
		(net "M_D_CPU0_SA_DQS_DP<8>")
	)
	(segment
		(start 327.557892 -242.547648)
		(end 327.572624 -242.539012)
		(width 0.09525)
		(layer "In4.Cu")
		(net "M_D_CPU0_SA_DQS_DP<8>")
	)
	(segment
		(start 304.158904 -231.179624)
		(end 304.463196 -230.875332)
		(width 0.16002)
		(layer "In4.Cu")
		(net "M_D_CPU0_SA_DQS_DP<8>")
	)
	(segment
		(start 329.821286 -242.534186)
		(end 329.829668 -242.539012)
		(width 0.09525)
		(layer "In4.Cu")
		(net "M_D_CPU0_SA_DQS_DP<8>")
	)
	(segment
		(start 280.91003 -230.211122)
		(end 282.86837 -230.211122)
		(width 0.16002)
		(layer "In4.Cu")
		(net "M_D_CPU0_SA_DQS_DP<8>")
	)
	(segment
		(start 302.21682 -231.179624)
		(end 304.158904 -231.179624)
		(width 0.16002)
		(layer "In4.Cu")
		(net "M_D_CPU0_SA_DQS_DP<8>")
	)
	(segment
		(start 331.332586 -242.539012)
		(end 331.340968 -242.534186)
		(width 0.09525)
		(layer "In4.Cu")
		(net "M_D_CPU0_SA_DQS_DP<8>")
	)
	(segment
		(start 324.617334 -242.159282)
		(end 325.284084 -242.159282)
		(width 0.09525)
		(layer "In4.Cu")
		(net "M_D_CPU0_SA_DQS_DP<8>")
	)
	(segment
		(start 326.611234 -242.551204)
		(end 326.632062 -242.539012)
		(width 0.09525)
		(layer "In4.Cu")
		(net "M_D_CPU0_SA_DQS_DP<8>")
	)
	(segment
		(start 333.581248 -242.534186)
		(end 333.58963 -242.539012)
		(width 0.09525)
		(layer "In4.Cu")
		(net "M_D_CPU0_SA_DQS_DP<8>")
	)
	(segment
		(start 325.612252 -242.48745)
		(end 325.880222 -242.48745)
		(width 0.09525)
		(layer "In4.Cu")
		(net "M_D_CPU0_SA_DQS_DP<8>")
	)
	(segment
		(start 326.632062 -242.539012)
		(end 326.64654 -242.53063)
		(width 0.09525)
		(layer "In4.Cu")
		(net "M_D_CPU0_SA_DQS_DP<8>")
	)
	(arc
		(start 336.040984 -242.534186)
		(mid 336.226016 -242.488272)
		(end 336.409792 -242.539012)
		(width 0.09525)
		(layer "In4.Cu")
		(net "M_D_CPU0_SA_DQS_DP<8>")
	)
	(arc
		(start 327.581006 -242.534186)
		(mid 327.766038 -242.488272)
		(end 327.949814 -242.539012)
		(width 0.09525)
		(layer "In4.Cu")
		(net "M_D_CPU0_SA_DQS_DP<8>")
	)
	(arc
		(start 330.400914 -242.534186)
		(mid 330.585946 -242.488272)
		(end 330.769722 -242.539012)
		(width 0.09525)
		(layer "In4.Cu")
		(net "M_D_CPU0_SA_DQS_DP<8>")
	)
	(arc
		(start 336.972656 -242.539012)
		(mid 337.161124 -242.488335)
		(end 337.349592 -242.539012)
		(width 0.09525)
		(layer "In4.Cu")
		(net "M_D_CPU0_SA_DQS_DP<8>")
	)
	(arc
		(start 329.829668 -242.539012)
		(mid 330.1111 -242.614767)
		(end 330.392532 -242.539012)
		(width 0.09525)
		(layer "In4.Cu")
		(net "M_D_CPU0_SA_DQS_DP<8>")
	)
	(arc
		(start 339.800946 -242.534186)
		(mid 339.953841 -242.489358)
		(end 340.111588 -242.511834)
		(width 0.09525)
		(layer "In4.Cu")
		(net "M_D_CPU0_SA_DQS_DP<8>")
	)
	(arc
		(start 329.452478 -242.539012)
		(mid 329.636253 -242.48824)
		(end 329.821286 -242.534186)
		(width 0.09525)
		(layer "In4.Cu")
		(net "M_D_CPU0_SA_DQS_DP<8>")
	)
	(arc
		(start 334.529684 -242.539012)
		(mid 334.811116 -242.614767)
		(end 335.092548 -242.539012)
		(width 0.09525)
		(layer "In4.Cu")
		(net "M_D_CPU0_SA_DQS_DP<8>")
	)
	(arc
		(start 335.10093 -242.534186)
		(mid 335.285962 -242.488272)
		(end 335.469738 -242.539012)
		(width 0.09525)
		(layer "In4.Cu")
		(net "M_D_CPU0_SA_DQS_DP<8>")
	)
	(arc
		(start 338.289646 -242.539012)
		(mid 338.571078 -242.614767)
		(end 338.85251 -242.539012)
		(width 0.09525)
		(layer "In4.Cu")
		(net "M_D_CPU0_SA_DQS_DP<8>")
	)
	(arc
		(start 335.469738 -242.539012)
		(mid 335.75117 -242.614767)
		(end 336.032602 -242.539012)
		(width 0.09525)
		(layer "In4.Cu")
		(net "M_D_CPU0_SA_DQS_DP<8>")
	)
	(arc
		(start 331.340968 -242.534186)
		(mid 331.526 -242.488272)
		(end 331.709776 -242.539012)
		(width 0.09525)
		(layer "In4.Cu")
		(net "M_D_CPU0_SA_DQS_DP<8>")
	)
	(arc
		(start 337.912456 -242.539012)
		(mid 338.096231 -242.48824)
		(end 338.281264 -242.534186)
		(width 0.09525)
		(layer "In4.Cu")
		(net "M_D_CPU0_SA_DQS_DP<8>")
	)
	(arc
		(start 330.769722 -242.539012)
		(mid 331.051154 -242.614767)
		(end 331.332586 -242.539012)
		(width 0.09525)
		(layer "In4.Cu")
		(net "M_D_CPU0_SA_DQS_DP<8>")
	)
	(arc
		(start 334.152494 -242.539012)
		(mid 334.336269 -242.48824)
		(end 334.521302 -242.534186)
		(width 0.09525)
		(layer "In4.Cu")
		(net "M_D_CPU0_SA_DQS_DP<8>")
	)
	(arc
		(start 332.27264 -242.539012)
		(mid 332.461108 -242.488335)
		(end 332.649576 -242.539012)
		(width 0.09525)
		(layer "In4.Cu")
		(net "M_D_CPU0_SA_DQS_DP<8>")
	)
	(arc
		(start 326.64654 -242.53063)
		(mid 326.828972 -242.48819)
		(end 327.009252 -242.539012)
		(width 0.09525)
		(layer "In4.Cu")
		(net "M_D_CPU0_SA_DQS_DP<8>")
	)
	(arc
		(start 328.889614 -242.539012)
		(mid 329.171046 -242.614767)
		(end 329.452478 -242.539012)
		(width 0.09525)
		(layer "In4.Cu")
		(net "M_D_CPU0_SA_DQS_DP<8>")
	)
	(arc
		(start 338.860892 -242.534186)
		(mid 339.045924 -242.488272)
		(end 339.2297 -242.539012)
		(width 0.09525)
		(layer "In4.Cu")
		(net "M_D_CPU0_SA_DQS_DP<8>")
	)
	(arc
		(start 331.709776 -242.539012)
		(mid 331.991208 -242.614767)
		(end 332.27264 -242.539012)
		(width 0.09525)
		(layer "In4.Cu")
		(net "M_D_CPU0_SA_DQS_DP<8>")
	)
	(arc
		(start 327.009252 -242.539012)
		(mid 327.282434 -242.614954)
		(end 327.557892 -242.547648)
		(width 0.09525)
		(layer "In4.Cu")
		(net "M_D_CPU0_SA_DQS_DP<8>")
	)
	(arc
		(start 337.349592 -242.539012)
		(mid 337.631024 -242.614767)
		(end 337.912456 -242.539012)
		(width 0.09525)
		(layer "In4.Cu")
		(net "M_D_CPU0_SA_DQS_DP<8>")
	)
	(arc
		(start 328.512678 -242.539012)
		(mid 328.701146 -242.488335)
		(end 328.889614 -242.539012)
		(width 0.09525)
		(layer "In4.Cu")
		(net "M_D_CPU0_SA_DQS_DP<8>")
	)
	(arc
		(start 326.069198 -242.539012)
		(mid 326.338631 -242.614883)
		(end 326.611234 -242.551204)
		(width 0.09525)
		(layer "In4.Cu")
		(net "M_D_CPU0_SA_DQS_DP<8>")
	)
	(arc
		(start 332.649576 -242.539012)
		(mid 332.931008 -242.614767)
		(end 333.21244 -242.539012)
		(width 0.09525)
		(layer "In4.Cu")
		(net "M_D_CPU0_SA_DQS_DP<8>")
	)
	(arc
		(start 333.21244 -242.539012)
		(mid 333.396215 -242.48824)
		(end 333.581248 -242.534186)
		(width 0.09525)
		(layer "In4.Cu")
		(net "M_D_CPU0_SA_DQS_DP<8>")
	)
	(arc
		(start 325.880222 -242.48745)
		(mid 325.978119 -242.500736)
		(end 326.069198 -242.539012)
		(width 0.09525)
		(layer "In4.Cu")
		(net "M_D_CPU0_SA_DQS_DP<8>")
	)
	(arc
		(start 336.409792 -242.539012)
		(mid 336.691224 -242.614767)
		(end 336.972656 -242.539012)
		(width 0.09525)
		(layer "In4.Cu")
		(net "M_D_CPU0_SA_DQS_DP<8>")
	)
	(arc
		(start 333.58963 -242.539012)
		(mid 333.871062 -242.614767)
		(end 334.152494 -242.539012)
		(width 0.09525)
		(layer "In4.Cu")
		(net "M_D_CPU0_SA_DQS_DP<8>")
	)
	(arc
		(start 327.949814 -242.539012)
		(mid 328.231246 -242.614767)
		(end 328.512678 -242.539012)
		(width 0.09525)
		(layer "In4.Cu")
		(net "M_D_CPU0_SA_DQS_DP<8>")
	)
	(arc
		(start 339.2297 -242.539012)
		(mid 339.511132 -242.614767)
		(end 339.792564 -242.539012)
		(width 0.09525)
		(layer "In4.Cu")
		(net "M_D_CPU0_SA_DQS_DP<8>")
	)
	(segment
		(start 340.447884 -238.270034)
		(end 339.981032 -238.004096)
		(width 0.12954)
		(layer "F.Cu")
		(net "M_D_CPU0_SA_DQS_DP<7>")
	)
	(segment
		(start 340.134956 -237.738666)
		(end 339.981032 -238.004096)
		(width 0.09525)
		(layer "In4.Cu")
		(net "M_D_CPU0_SA_DQS_DP<7>")
	)
	(segment
		(start 284.376876 -221.02699)
		(end 284.493716 -221.14383)
		(width 0.16002)
		(layer "In4.Cu")
		(net "M_D_CPU0_SA_DQS_DP<7>")
	)
	(segment
		(start 297.396662 -221.525338)
		(end 298.280836 -220.641164)
		(width 0.16002)
		(layer "In4.Cu")
		(net "M_D_CPU0_SA_DQS_DP<7>")
	)
	(segment
		(start 327.546208 -237.694978)
		(end 327.57364 -237.678976)
		(width 0.09525)
		(layer "In4.Cu")
		(net "M_D_CPU0_SA_DQS_DP<7>")
	)
	(segment
		(start 305.486816 -221.86011)
		(end 307.902356 -221.86011)
		(width 0.16002)
		(layer "In4.Cu")
		(net "M_D_CPU0_SA_DQS_DP<7>")
	)
	(segment
		(start 307.902356 -221.86011)
		(end 308.406038 -222.363792)
		(width 0.16002)
		(layer "In4.Cu")
		(net "M_D_CPU0_SA_DQS_DP<7>")
	)
	(segment
		(start 333.581248 -237.67415)
		(end 333.58963 -237.678976)
		(width 0.09525)
		(layer "In4.Cu")
		(net "M_D_CPU0_SA_DQS_DP<7>")
	)
	(segment
		(start 304.463196 -221.525338)
		(end 305.152044 -221.525338)
		(width 0.16002)
		(layer "In4.Cu")
		(net "M_D_CPU0_SA_DQS_DP<7>")
	)
	(segment
		(start 308.406038 -222.720154)
		(end 321.617086 -235.931202)
		(width 0.16002)
		(layer "In4.Cu")
		(net "M_D_CPU0_SA_DQS_DP<7>")
	)
	(segment
		(start 289.375342 -221.525338)
		(end 289.852862 -221.525338)
		(width 0.16002)
		(layer "In4.Cu")
		(net "M_D_CPU0_SA_DQS_DP<7>")
	)
	(segment
		(start 298.280836 -220.641164)
		(end 298.595542 -220.641164)
		(width 0.16002)
		(layer "In4.Cu")
		(net "M_D_CPU0_SA_DQS_DP<7>")
	)
	(segment
		(start 296.919142 -221.525338)
		(end 297.396662 -221.525338)
		(width 0.16002)
		(layer "In4.Cu")
		(net "M_D_CPU0_SA_DQS_DP<7>")
	)
	(segment
		(start 291.051742 -220.641164)
		(end 291.420804 -221.010226)
		(width 0.16002)
		(layer "In4.Cu")
		(net "M_D_CPU0_SA_DQS_DP<7>")
	)
	(segment
		(start 323.895974 -235.931202)
		(end 323.919596 -235.931202)
		(width 0.09525)
		(layer "In4.Cu")
		(net "M_D_CPU0_SA_DQS_DP<7>")
	)
	(segment
		(start 338.85251 -237.678976)
		(end 338.860892 -237.67415)
		(width 0.09525)
		(layer "In4.Cu")
		(net "M_D_CPU0_SA_DQS_DP<7>")
	)
	(segment
		(start 282.950158 -220.861128)
		(end 283.130752 -220.680534)
		(width 0.16002)
		(layer "In4.Cu")
		(net "M_D_CPU0_SA_DQS_DP<7>")
	)
	(segment
		(start 280.909776 -220.861128)
		(end 282.950158 -220.861128)
		(width 0.16002)
		(layer "In4.Cu")
		(net "M_D_CPU0_SA_DQS_DP<7>")
	)
	(segment
		(start 324.113652 -235.87202)
		(end 324.473824 -236.232192)
		(width 0.09525)
		(layer "In4.Cu")
		(net "M_D_CPU0_SA_DQS_DP<7>")
	)
	(segment
		(start 327.57364 -237.678976)
		(end 327.592436 -237.668308)
		(width 0.09525)
		(layer "In4.Cu")
		(net "M_D_CPU0_SA_DQS_DP<7>")
	)
	(segment
		(start 340.111588 -237.651798)
		(end 340.134956 -237.738666)
		(width 0.09525)
		(layer "In4.Cu")
		(net "M_D_CPU0_SA_DQS_DP<7>")
	)
	(segment
		(start 285.090616 -221.02699)
		(end 286.286956 -221.02699)
		(width 0.16002)
		(layer "In4.Cu")
		(net "M_D_CPU0_SA_DQS_DP<7>")
	)
	(segment
		(start 289.04057 -221.86011)
		(end 289.375342 -221.525338)
		(width 0.16002)
		(layer "In4.Cu")
		(net "M_D_CPU0_SA_DQS_DP<7>")
	)
	(segment
		(start 339.792564 -237.678976)
		(end 339.800946 -237.67415)
		(width 0.09525)
		(layer "In4.Cu")
		(net "M_D_CPU0_SA_DQS_DP<7>")
	)
	(segment
		(start 283.896816 -221.02699)
		(end 284.376876 -221.02699)
		(width 0.16002)
		(layer "In4.Cu")
		(net "M_D_CPU0_SA_DQS_DP<7>")
	)
	(segment
		(start 286.286956 -221.02699)
		(end 287.120076 -221.86011)
		(width 0.16002)
		(layer "In4.Cu")
		(net "M_D_CPU0_SA_DQS_DP<7>")
	)
	(segment
		(start 283.55036 -220.680534)
		(end 283.896816 -221.02699)
		(width 0.16002)
		(layer "In4.Cu")
		(net "M_D_CPU0_SA_DQS_DP<7>")
	)
	(segment
		(start 336.032602 -237.678976)
		(end 336.040984 -237.67415)
		(width 0.09525)
		(layer "In4.Cu")
		(net "M_D_CPU0_SA_DQS_DP<7>")
	)
	(segment
		(start 334.521302 -237.67415)
		(end 334.529684 -237.678976)
		(width 0.09525)
		(layer "In4.Cu")
		(net "M_D_CPU0_SA_DQS_DP<7>")
	)
	(segment
		(start 296.58437 -221.86011)
		(end 296.919142 -221.525338)
		(width 0.16002)
		(layer "In4.Cu")
		(net "M_D_CPU0_SA_DQS_DP<7>")
	)
	(segment
		(start 325.148448 -236.50194)
		(end 325.148448 -236.793786)
		(width 0.09525)
		(layer "In4.Cu")
		(net "M_D_CPU0_SA_DQS_DP<7>")
	)
	(segment
		(start 283.130752 -220.680534)
		(end 283.55036 -220.680534)
		(width 0.16002)
		(layer "In4.Cu")
		(net "M_D_CPU0_SA_DQS_DP<7>")
	)
	(segment
		(start 321.617086 -235.931202)
		(end 323.895974 -235.931202)
		(width 0.16002)
		(layer "In4.Cu")
		(net "M_D_CPU0_SA_DQS_DP<7>")
	)
	(segment
		(start 338.281264 -237.67415)
		(end 338.289646 -237.678976)
		(width 0.09525)
		(layer "In4.Cu")
		(net "M_D_CPU0_SA_DQS_DP<7>")
	)
	(segment
		(start 294.630856 -221.86011)
		(end 296.58437 -221.86011)
		(width 0.16002)
		(layer "In4.Cu")
		(net "M_D_CPU0_SA_DQS_DP<7>")
	)
	(segment
		(start 331.332586 -237.678976)
		(end 331.340968 -237.67415)
		(width 0.09525)
		(layer "In4.Cu")
		(net "M_D_CPU0_SA_DQS_DP<7>")
	)
	(segment
		(start 284.973776 -221.14383)
		(end 285.090616 -221.02699)
		(width 0.16002)
		(layer "In4.Cu")
		(net "M_D_CPU0_SA_DQS_DP<7>")
	)
	(segment
		(start 298.964604 -221.010226)
		(end 301.376588 -221.010226)
		(width 0.16002)
		(layer "In4.Cu")
		(net "M_D_CPU0_SA_DQS_DP<7>")
	)
	(segment
		(start 324.8787 -236.232192)
		(end 325.148448 -236.50194)
		(width 0.09525)
		(layer "In4.Cu")
		(net "M_D_CPU0_SA_DQS_DP<7>")
	)
	(segment
		(start 323.919596 -235.931202)
		(end 323.978778 -235.87202)
		(width 0.09525)
		(layer "In4.Cu")
		(net "M_D_CPU0_SA_DQS_DP<7>")
	)
	(segment
		(start 305.152044 -221.525338)
		(end 305.486816 -221.86011)
		(width 0.16002)
		(layer "In4.Cu")
		(net "M_D_CPU0_SA_DQS_DP<7>")
	)
	(segment
		(start 284.493716 -221.14383)
		(end 284.973776 -221.14383)
		(width 0.16002)
		(layer "In4.Cu")
		(net "M_D_CPU0_SA_DQS_DP<7>")
	)
	(segment
		(start 326.99071 -237.666276)
		(end 327.012554 -237.678976)
		(width 0.09525)
		(layer "In4.Cu")
		(net "M_D_CPU0_SA_DQS_DP<7>")
	)
	(segment
		(start 324.473824 -236.232192)
		(end 324.8787 -236.232192)
		(width 0.09525)
		(layer "In4.Cu")
		(net "M_D_CPU0_SA_DQS_DP<7>")
	)
	(segment
		(start 302.195992 -221.82963)
		(end 304.158904 -221.82963)
		(width 0.16002)
		(layer "In4.Cu")
		(net "M_D_CPU0_SA_DQS_DP<7>")
	)
	(segment
		(start 329.821286 -237.67415)
		(end 329.829668 -237.678976)
		(width 0.09525)
		(layer "In4.Cu")
		(net "M_D_CPU0_SA_DQS_DP<7>")
	)
	(segment
		(start 335.092548 -237.678976)
		(end 335.10093 -237.67415)
		(width 0.09525)
		(layer "In4.Cu")
		(net "M_D_CPU0_SA_DQS_DP<7>")
	)
	(segment
		(start 287.120076 -221.86011)
		(end 289.04057 -221.86011)
		(width 0.16002)
		(layer "In4.Cu")
		(net "M_D_CPU0_SA_DQS_DP<7>")
	)
	(segment
		(start 325.148448 -236.793786)
		(end 326.110092 -237.75543)
		(width 0.09525)
		(layer "In4.Cu")
		(net "M_D_CPU0_SA_DQS_DP<7>")
	)
	(segment
		(start 326.110092 -237.75543)
		(end 326.351392 -237.75543)
		(width 0.09525)
		(layer "In4.Cu")
		(net "M_D_CPU0_SA_DQS_DP<7>")
	)
	(segment
		(start 298.595542 -220.641164)
		(end 298.964604 -221.010226)
		(width 0.16002)
		(layer "In4.Cu")
		(net "M_D_CPU0_SA_DQS_DP<7>")
	)
	(segment
		(start 293.780972 -221.010226)
		(end 294.630856 -221.86011)
		(width 0.16002)
		(layer "In4.Cu")
		(net "M_D_CPU0_SA_DQS_DP<7>")
	)
	(segment
		(start 308.406038 -222.363792)
		(end 308.406038 -222.720154)
		(width 0.16002)
		(layer "In4.Cu")
		(net "M_D_CPU0_SA_DQS_DP<7>")
	)
	(segment
		(start 304.158904 -221.82963)
		(end 304.463196 -221.525338)
		(width 0.16002)
		(layer "In4.Cu")
		(net "M_D_CPU0_SA_DQS_DP<7>")
	)
	(segment
		(start 323.978778 -235.87202)
		(end 324.113652 -235.87202)
		(width 0.09525)
		(layer "In4.Cu")
		(net "M_D_CPU0_SA_DQS_DP<7>")
	)
	(segment
		(start 290.737036 -220.641164)
		(end 291.051742 -220.641164)
		(width 0.16002)
		(layer "In4.Cu")
		(net "M_D_CPU0_SA_DQS_DP<7>")
	)
	(segment
		(start 330.392532 -237.678976)
		(end 330.400914 -237.67415)
		(width 0.09525)
		(layer "In4.Cu")
		(net "M_D_CPU0_SA_DQS_DP<7>")
	)
	(segment
		(start 289.852862 -221.525338)
		(end 290.737036 -220.641164)
		(width 0.16002)
		(layer "In4.Cu")
		(net "M_D_CPU0_SA_DQS_DP<7>")
	)
	(segment
		(start 291.420804 -221.010226)
		(end 293.780972 -221.010226)
		(width 0.16002)
		(layer "In4.Cu")
		(net "M_D_CPU0_SA_DQS_DP<7>")
	)
	(segment
		(start 280.635964 -221.13494)
		(end 280.909776 -220.861128)
		(width 0.16002)
		(layer "In4.Cu")
		(net "M_D_CPU0_SA_DQS_DP<7>")
	)
	(segment
		(start 301.376588 -221.010226)
		(end 302.195992 -221.82963)
		(width 0.16002)
		(layer "In4.Cu")
		(net "M_D_CPU0_SA_DQS_DP<7>")
	)
	(arc
		(start 336.972656 -237.678976)
		(mid 337.161124 -237.628299)
		(end 337.349592 -237.678976)
		(width 0.09525)
		(layer "In4.Cu")
		(net "M_D_CPU0_SA_DQS_DP<7>")
	)
	(arc
		(start 339.2297 -237.678976)
		(mid 339.511132 -237.754731)
		(end 339.792564 -237.678976)
		(width 0.09525)
		(layer "In4.Cu")
		(net "M_D_CPU0_SA_DQS_DP<7>")
	)
	(arc
		(start 338.289646 -237.678976)
		(mid 338.571078 -237.754731)
		(end 338.85251 -237.678976)
		(width 0.09525)
		(layer "In4.Cu")
		(net "M_D_CPU0_SA_DQS_DP<7>")
	)
	(arc
		(start 327.949814 -237.678976)
		(mid 328.231246 -237.754731)
		(end 328.512678 -237.678976)
		(width 0.09525)
		(layer "In4.Cu")
		(net "M_D_CPU0_SA_DQS_DP<7>")
	)
	(arc
		(start 333.58963 -237.678976)
		(mid 333.871062 -237.754731)
		(end 334.152494 -237.678976)
		(width 0.09525)
		(layer "In4.Cu")
		(net "M_D_CPU0_SA_DQS_DP<7>")
	)
	(arc
		(start 336.040984 -237.67415)
		(mid 336.226016 -237.628236)
		(end 336.409792 -237.678976)
		(width 0.09525)
		(layer "In4.Cu")
		(net "M_D_CPU0_SA_DQS_DP<7>")
	)
	(arc
		(start 326.36587 -237.75543)
		(mid 326.504948 -237.734017)
		(end 326.634348 -237.678722)
		(width 0.09525)
		(layer "In4.Cu")
		(net "M_D_CPU0_SA_DQS_DP<7>")
	)
	(arc
		(start 338.860892 -237.67415)
		(mid 339.045924 -237.628236)
		(end 339.2297 -237.678976)
		(width 0.09525)
		(layer "In4.Cu")
		(net "M_D_CPU0_SA_DQS_DP<7>")
	)
	(arc
		(start 334.529684 -237.678976)
		(mid 334.811116 -237.754731)
		(end 335.092548 -237.678976)
		(width 0.09525)
		(layer "In4.Cu")
		(net "M_D_CPU0_SA_DQS_DP<7>")
	)
	(arc
		(start 331.709776 -237.678976)
		(mid 331.991208 -237.754731)
		(end 332.27264 -237.678976)
		(width 0.09525)
		(layer "In4.Cu")
		(net "M_D_CPU0_SA_DQS_DP<7>")
	)
	(arc
		(start 329.829668 -237.678976)
		(mid 330.1111 -237.754731)
		(end 330.392532 -237.678976)
		(width 0.09525)
		(layer "In4.Cu")
		(net "M_D_CPU0_SA_DQS_DP<7>")
	)
	(arc
		(start 333.21244 -237.678976)
		(mid 333.396215 -237.628204)
		(end 333.581248 -237.67415)
		(width 0.09525)
		(layer "In4.Cu")
		(net "M_D_CPU0_SA_DQS_DP<7>")
	)
	(arc
		(start 336.409792 -237.678976)
		(mid 336.691224 -237.754731)
		(end 336.972656 -237.678976)
		(width 0.09525)
		(layer "In4.Cu")
		(net "M_D_CPU0_SA_DQS_DP<7>")
	)
	(arc
		(start 328.512678 -237.678976)
		(mid 328.701146 -237.628299)
		(end 328.889614 -237.678976)
		(width 0.09525)
		(layer "In4.Cu")
		(net "M_D_CPU0_SA_DQS_DP<7>")
	)
	(arc
		(start 327.592436 -237.668308)
		(mid 327.772486 -237.628383)
		(end 327.949814 -237.678976)
		(width 0.09525)
		(layer "In4.Cu")
		(net "M_D_CPU0_SA_DQS_DP<7>")
	)
	(arc
		(start 328.889614 -237.678976)
		(mid 329.171046 -237.754731)
		(end 329.452478 -237.678976)
		(width 0.09525)
		(layer "In4.Cu")
		(net "M_D_CPU0_SA_DQS_DP<7>")
	)
	(arc
		(start 326.351392 -237.75543)
		(mid 326.358631 -237.755478)
		(end 326.36587 -237.75543)
		(width 0.09525)
		(layer "In4.Cu")
		(net "M_D_CPU0_SA_DQS_DP<7>")
	)
	(arc
		(start 339.800946 -237.67415)
		(mid 339.953841 -237.629322)
		(end 340.111588 -237.651798)
		(width 0.09525)
		(layer "In4.Cu")
		(net "M_D_CPU0_SA_DQS_DP<7>")
	)
	(arc
		(start 331.340968 -237.67415)
		(mid 331.526 -237.628236)
		(end 331.709776 -237.678976)
		(width 0.09525)
		(layer "In4.Cu")
		(net "M_D_CPU0_SA_DQS_DP<7>")
	)
	(arc
		(start 330.769722 -237.678976)
		(mid 331.051154 -237.754731)
		(end 331.332586 -237.678976)
		(width 0.09525)
		(layer "In4.Cu")
		(net "M_D_CPU0_SA_DQS_DP<7>")
	)
	(arc
		(start 337.349592 -237.678976)
		(mid 337.631024 -237.754731)
		(end 337.912456 -237.678976)
		(width 0.09525)
		(layer "In4.Cu")
		(net "M_D_CPU0_SA_DQS_DP<7>")
	)
	(arc
		(start 335.469738 -237.678976)
		(mid 335.75117 -237.754731)
		(end 336.032602 -237.678976)
		(width 0.09525)
		(layer "In4.Cu")
		(net "M_D_CPU0_SA_DQS_DP<7>")
	)
	(arc
		(start 334.152494 -237.678976)
		(mid 334.336269 -237.628204)
		(end 334.521302 -237.67415)
		(width 0.09525)
		(layer "In4.Cu")
		(net "M_D_CPU0_SA_DQS_DP<7>")
	)
	(arc
		(start 332.27264 -237.678976)
		(mid 332.461108 -237.628299)
		(end 332.649576 -237.678976)
		(width 0.09525)
		(layer "In4.Cu")
		(net "M_D_CPU0_SA_DQS_DP<7>")
	)
	(arc
		(start 332.649576 -237.678976)
		(mid 332.931008 -237.754731)
		(end 333.21244 -237.678976)
		(width 0.09525)
		(layer "In4.Cu")
		(net "M_D_CPU0_SA_DQS_DP<7>")
	)
	(arc
		(start 337.912456 -237.678976)
		(mid 338.096231 -237.628204)
		(end 338.281264 -237.67415)
		(width 0.09525)
		(layer "In4.Cu")
		(net "M_D_CPU0_SA_DQS_DP<7>")
	)
	(arc
		(start 326.634348 -237.678722)
		(mid 326.81096 -237.62767)
		(end 326.99071 -237.666276)
		(width 0.09525)
		(layer "In4.Cu")
		(net "M_D_CPU0_SA_DQS_DP<7>")
	)
	(arc
		(start 330.400914 -237.67415)
		(mid 330.585946 -237.628236)
		(end 330.769722 -237.678976)
		(width 0.09525)
		(layer "In4.Cu")
		(net "M_D_CPU0_SA_DQS_DP<7>")
	)
	(arc
		(start 329.452478 -237.678976)
		(mid 329.636253 -237.628204)
		(end 329.821286 -237.67415)
		(width 0.09525)
		(layer "In4.Cu")
		(net "M_D_CPU0_SA_DQS_DP<7>")
	)
	(arc
		(start 335.10093 -237.67415)
		(mid 335.285962 -237.628236)
		(end 335.469738 -237.678976)
		(width 0.09525)
		(layer "In4.Cu")
		(net "M_D_CPU0_SA_DQS_DP<7>")
	)
	(arc
		(start 327.012554 -237.678976)
		(mid 327.277363 -237.754605)
		(end 327.546208 -237.694978)
		(width 0.09525)
		(layer "In4.Cu")
		(net "M_D_CPU0_SA_DQS_DP<7>")
	)
	(segment
		(start 340.447884 -233.409998)
		(end 339.981032 -233.14406)
		(width 0.12954)
		(layer "F.Cu")
		(net "M_D_CPU0_SA_DQS_DP<6>")
	)
	(segment
		(start 297.403012 -212.190584)
		(end 298.287186 -211.30641)
		(width 0.16002)
		(layer "In4.Cu")
		(net "M_D_CPU0_SA_DQS_DP<6>")
	)
	(segment
		(start 340.111588 -232.791762)
		(end 340.134956 -232.87863)
		(width 0.09525)
		(layer "In4.Cu")
		(net "M_D_CPU0_SA_DQS_DP<6>")
	)
	(segment
		(start 324.059042 -230.366062)
		(end 324.075806 -230.382826)
		(width 0.09525)
		(layer "In4.Cu")
		(net "M_D_CPU0_SA_DQS_DP<6>")
	)
	(segment
		(start 296.925492 -212.190584)
		(end 297.403012 -212.190584)
		(width 0.16002)
		(layer "In4.Cu")
		(net "M_D_CPU0_SA_DQS_DP<6>")
	)
	(segment
		(start 324.549262 -230.772462)
		(end 325.362824 -230.772462)
		(width 0.09525)
		(layer "In4.Cu")
		(net "M_D_CPU0_SA_DQS_DP<6>")
	)
	(segment
		(start 338.85251 -232.81894)
		(end 338.860892 -232.814114)
		(width 0.09525)
		(layer "In4.Cu")
		(net "M_D_CPU0_SA_DQS_DP<6>")
	)
	(segment
		(start 283.554678 -211.332572)
		(end 283.912818 -211.690712)
		(width 0.16002)
		(layer "In4.Cu")
		(net "M_D_CPU0_SA_DQS_DP<6>")
	)
	(segment
		(start 289.833558 -212.206332)
		(end 290.735258 -211.304632)
		(width 0.16002)
		(layer "In4.Cu")
		(net "M_D_CPU0_SA_DQS_DP<6>")
	)
	(segment
		(start 320.880486 -227.187506)
		(end 324.059042 -230.366062)
		(width 0.16002)
		(layer "In4.Cu")
		(net "M_D_CPU0_SA_DQS_DP<6>")
	)
	(segment
		(start 281.600148 -211.627974)
		(end 282.080208 -211.627974)
		(width 0.16002)
		(layer "In4.Cu")
		(net "M_D_CPU0_SA_DQS_DP<6>")
	)
	(segment
		(start 301.92345 -212.190584)
		(end 305.20767 -212.190584)
		(width 0.16002)
		(layer "In4.Cu")
		(net "M_D_CPU0_SA_DQS_DP<6>")
	)
	(segment
		(start 290.735258 -211.304632)
		(end 291.043614 -211.304632)
		(width 0.16002)
		(layer "In4.Cu")
		(net "M_D_CPU0_SA_DQS_DP<6>")
	)
	(segment
		(start 301.393098 -211.660232)
		(end 301.92345 -212.190584)
		(width 0.16002)
		(layer "In4.Cu")
		(net "M_D_CPU0_SA_DQS_DP<6>")
	)
	(segment
		(start 307.777642 -212.510116)
		(end 320.410078 -225.142552)
		(width 0.16002)
		(layer "In4.Cu")
		(net "M_D_CPU0_SA_DQS_DP<6>")
	)
	(segment
		(start 282.916376 -211.511134)
		(end 283.094938 -211.332572)
		(width 0.16002)
		(layer "In4.Cu")
		(net "M_D_CPU0_SA_DQS_DP<6>")
	)
	(segment
		(start 320.410078 -226.716844)
		(end 320.880486 -227.187252)
		(width 0.16002)
		(layer "In4.Cu")
		(net "M_D_CPU0_SA_DQS_DP<6>")
	)
	(segment
		(start 334.521302 -232.814114)
		(end 334.529684 -232.81894)
		(width 0.09525)
		(layer "In4.Cu")
		(net "M_D_CPU0_SA_DQS_DP<6>")
	)
	(segment
		(start 335.092548 -232.81894)
		(end 335.10093 -232.814114)
		(width 0.09525)
		(layer "In4.Cu")
		(net "M_D_CPU0_SA_DQS_DP<6>")
	)
	(segment
		(start 330.392532 -232.81894)
		(end 330.400914 -232.814114)
		(width 0.09525)
		(layer "In4.Cu")
		(net "M_D_CPU0_SA_DQS_DP<6>")
	)
	(segment
		(start 296.60596 -212.510116)
		(end 296.925492 -212.190584)
		(width 0.16002)
		(layer "In4.Cu")
		(net "M_D_CPU0_SA_DQS_DP<6>")
	)
	(segment
		(start 327.357994 -232.767632)
		(end 327.761092 -232.767632)
		(width 0.09525)
		(layer "In4.Cu")
		(net "M_D_CPU0_SA_DQS_DP<6>")
	)
	(segment
		(start 340.134956 -232.87863)
		(end 339.981032 -233.14406)
		(width 0.09525)
		(layer "In4.Cu")
		(net "M_D_CPU0_SA_DQS_DP<6>")
	)
	(segment
		(start 291.043614 -211.304632)
		(end 291.399214 -211.660232)
		(width 0.16002)
		(layer "In4.Cu")
		(net "M_D_CPU0_SA_DQS_DP<6>")
	)
	(segment
		(start 293.759382 -211.660232)
		(end 294.609266 -212.510116)
		(width 0.16002)
		(layer "In4.Cu")
		(net "M_D_CPU0_SA_DQS_DP<6>")
	)
	(segment
		(start 281.483308 -211.511134)
		(end 281.600148 -211.627974)
		(width 0.16002)
		(layer "In4.Cu")
		(net "M_D_CPU0_SA_DQS_DP<6>")
	)
	(segment
		(start 286.318198 -211.690712)
		(end 287.137602 -212.510116)
		(width 0.16002)
		(layer "In4.Cu")
		(net "M_D_CPU0_SA_DQS_DP<6>")
	)
	(segment
		(start 331.332586 -232.81894)
		(end 331.340968 -232.814114)
		(width 0.09525)
		(layer "In4.Cu")
		(net "M_D_CPU0_SA_DQS_DP<6>")
	)
	(segment
		(start 325.362824 -230.772462)
		(end 327.357994 -232.767632)
		(width 0.09525)
		(layer "In4.Cu")
		(net "M_D_CPU0_SA_DQS_DP<6>")
	)
	(segment
		(start 298.943014 -211.660232)
		(end 301.393098 -211.660232)
		(width 0.16002)
		(layer "In4.Cu")
		(net "M_D_CPU0_SA_DQS_DP<6>")
	)
	(segment
		(start 280.909776 -211.511134)
		(end 281.483308 -211.511134)
		(width 0.16002)
		(layer "In4.Cu")
		(net "M_D_CPU0_SA_DQS_DP<6>")
	)
	(segment
		(start 283.094938 -211.332572)
		(end 283.554678 -211.332572)
		(width 0.16002)
		(layer "In4.Cu")
		(net "M_D_CPU0_SA_DQS_DP<6>")
	)
	(segment
		(start 287.137602 -212.510116)
		(end 289.049714 -212.510116)
		(width 0.16002)
		(layer "In4.Cu")
		(net "M_D_CPU0_SA_DQS_DP<6>")
	)
	(segment
		(start 336.032602 -232.81894)
		(end 336.040984 -232.814114)
		(width 0.09525)
		(layer "In4.Cu")
		(net "M_D_CPU0_SA_DQS_DP<6>")
	)
	(segment
		(start 284.989778 -211.807552)
		(end 285.106618 -211.690712)
		(width 0.16002)
		(layer "In4.Cu")
		(net "M_D_CPU0_SA_DQS_DP<6>")
	)
	(segment
		(start 283.912818 -211.690712)
		(end 284.392878 -211.690712)
		(width 0.16002)
		(layer "In4.Cu")
		(net "M_D_CPU0_SA_DQS_DP<6>")
	)
	(segment
		(start 282.197048 -211.511134)
		(end 282.916376 -211.511134)
		(width 0.16002)
		(layer "In4.Cu")
		(net "M_D_CPU0_SA_DQS_DP<6>")
	)
	(segment
		(start 298.287186 -211.30641)
		(end 298.589192 -211.30641)
		(width 0.16002)
		(layer "In4.Cu")
		(net "M_D_CPU0_SA_DQS_DP<6>")
	)
	(segment
		(start 291.399214 -211.660232)
		(end 293.759382 -211.660232)
		(width 0.16002)
		(layer "In4.Cu")
		(net "M_D_CPU0_SA_DQS_DP<6>")
	)
	(segment
		(start 324.075806 -230.382826)
		(end 324.159626 -230.382826)
		(width 0.09525)
		(layer "In4.Cu")
		(net "M_D_CPU0_SA_DQS_DP<6>")
	)
	(segment
		(start 294.609266 -212.510116)
		(end 296.60596 -212.510116)
		(width 0.16002)
		(layer "In4.Cu")
		(net "M_D_CPU0_SA_DQS_DP<6>")
	)
	(segment
		(start 305.527202 -212.510116)
		(end 307.777642 -212.510116)
		(width 0.16002)
		(layer "In4.Cu")
		(net "M_D_CPU0_SA_DQS_DP<6>")
	)
	(segment
		(start 289.049714 -212.510116)
		(end 289.353498 -212.206332)
		(width 0.16002)
		(layer "In4.Cu")
		(net "M_D_CPU0_SA_DQS_DP<6>")
	)
	(segment
		(start 282.080208 -211.627974)
		(end 282.197048 -211.511134)
		(width 0.16002)
		(layer "In4.Cu")
		(net "M_D_CPU0_SA_DQS_DP<6>")
	)
	(segment
		(start 284.392878 -211.690712)
		(end 284.509718 -211.807552)
		(width 0.16002)
		(layer "In4.Cu")
		(net "M_D_CPU0_SA_DQS_DP<6>")
	)
	(segment
		(start 320.880486 -227.187252)
		(end 320.880486 -227.187506)
		(width 0.16002)
		(layer "In4.Cu")
		(net "M_D_CPU0_SA_DQS_DP<6>")
	)
	(segment
		(start 324.159626 -230.382826)
		(end 324.549262 -230.772462)
		(width 0.09525)
		(layer "In4.Cu")
		(net "M_D_CPU0_SA_DQS_DP<6>")
	)
	(segment
		(start 280.635964 -211.784946)
		(end 280.909776 -211.511134)
		(width 0.16002)
		(layer "In4.Cu")
		(net "M_D_CPU0_SA_DQS_DP<6>")
	)
	(segment
		(start 339.792564 -232.81894)
		(end 339.800946 -232.814114)
		(width 0.09525)
		(layer "In4.Cu")
		(net "M_D_CPU0_SA_DQS_DP<6>")
	)
	(segment
		(start 305.20767 -212.190584)
		(end 305.527202 -212.510116)
		(width 0.16002)
		(layer "In4.Cu")
		(net "M_D_CPU0_SA_DQS_DP<6>")
	)
	(segment
		(start 320.410078 -225.142552)
		(end 320.410078 -226.716844)
		(width 0.16002)
		(layer "In4.Cu")
		(net "M_D_CPU0_SA_DQS_DP<6>")
	)
	(segment
		(start 338.281264 -232.814114)
		(end 338.289646 -232.81894)
		(width 0.09525)
		(layer "In4.Cu")
		(net "M_D_CPU0_SA_DQS_DP<6>")
	)
	(segment
		(start 298.589192 -211.30641)
		(end 298.943014 -211.660232)
		(width 0.16002)
		(layer "In4.Cu")
		(net "M_D_CPU0_SA_DQS_DP<6>")
	)
	(segment
		(start 333.581248 -232.814114)
		(end 333.58963 -232.81894)
		(width 0.09525)
		(layer "In4.Cu")
		(net "M_D_CPU0_SA_DQS_DP<6>")
	)
	(segment
		(start 329.821286 -232.814114)
		(end 329.829668 -232.81894)
		(width 0.09525)
		(layer "In4.Cu")
		(net "M_D_CPU0_SA_DQS_DP<6>")
	)
	(segment
		(start 284.509718 -211.807552)
		(end 284.989778 -211.807552)
		(width 0.16002)
		(layer "In4.Cu")
		(net "M_D_CPU0_SA_DQS_DP<6>")
	)
	(segment
		(start 289.353498 -212.206332)
		(end 289.833558 -212.206332)
		(width 0.16002)
		(layer "In4.Cu")
		(net "M_D_CPU0_SA_DQS_DP<6>")
	)
	(segment
		(start 285.106618 -211.690712)
		(end 286.318198 -211.690712)
		(width 0.16002)
		(layer "In4.Cu")
		(net "M_D_CPU0_SA_DQS_DP<6>")
	)
	(arc
		(start 330.769722 -232.81894)
		(mid 331.051154 -232.894695)
		(end 331.332586 -232.81894)
		(width 0.09525)
		(layer "In4.Cu")
		(net "M_D_CPU0_SA_DQS_DP<6>")
	)
	(arc
		(start 332.27264 -232.81894)
		(mid 332.461108 -232.768263)
		(end 332.649576 -232.81894)
		(width 0.09525)
		(layer "In4.Cu")
		(net "M_D_CPU0_SA_DQS_DP<6>")
	)
	(arc
		(start 339.2297 -232.81894)
		(mid 339.511132 -232.894695)
		(end 339.792564 -232.81894)
		(width 0.09525)
		(layer "In4.Cu")
		(net "M_D_CPU0_SA_DQS_DP<6>")
	)
	(arc
		(start 338.860892 -232.814114)
		(mid 339.045924 -232.7682)
		(end 339.2297 -232.81894)
		(width 0.09525)
		(layer "In4.Cu")
		(net "M_D_CPU0_SA_DQS_DP<6>")
	)
	(arc
		(start 335.10093 -232.814114)
		(mid 335.285962 -232.7682)
		(end 335.469738 -232.81894)
		(width 0.09525)
		(layer "In4.Cu")
		(net "M_D_CPU0_SA_DQS_DP<6>")
	)
	(arc
		(start 332.649576 -232.81894)
		(mid 332.931008 -232.894695)
		(end 333.21244 -232.81894)
		(width 0.09525)
		(layer "In4.Cu")
		(net "M_D_CPU0_SA_DQS_DP<6>")
	)
	(arc
		(start 327.761092 -232.767632)
		(mid 327.858838 -232.780827)
		(end 327.949814 -232.81894)
		(width 0.09525)
		(layer "In4.Cu")
		(net "M_D_CPU0_SA_DQS_DP<6>")
	)
	(arc
		(start 333.58963 -232.81894)
		(mid 333.871062 -232.894695)
		(end 334.152494 -232.81894)
		(width 0.09525)
		(layer "In4.Cu")
		(net "M_D_CPU0_SA_DQS_DP<6>")
	)
	(arc
		(start 336.972656 -232.81894)
		(mid 337.161124 -232.768263)
		(end 337.349592 -232.81894)
		(width 0.09525)
		(layer "In4.Cu")
		(net "M_D_CPU0_SA_DQS_DP<6>")
	)
	(arc
		(start 334.529684 -232.81894)
		(mid 334.811116 -232.894695)
		(end 335.092548 -232.81894)
		(width 0.09525)
		(layer "In4.Cu")
		(net "M_D_CPU0_SA_DQS_DP<6>")
	)
	(arc
		(start 328.512678 -232.81894)
		(mid 328.701146 -232.768263)
		(end 328.889614 -232.81894)
		(width 0.09525)
		(layer "In4.Cu")
		(net "M_D_CPU0_SA_DQS_DP<6>")
	)
	(arc
		(start 327.949814 -232.81894)
		(mid 328.231246 -232.894695)
		(end 328.512678 -232.81894)
		(width 0.09525)
		(layer "In4.Cu")
		(net "M_D_CPU0_SA_DQS_DP<6>")
	)
	(arc
		(start 338.289646 -232.81894)
		(mid 338.571078 -232.894695)
		(end 338.85251 -232.81894)
		(width 0.09525)
		(layer "In4.Cu")
		(net "M_D_CPU0_SA_DQS_DP<6>")
	)
	(arc
		(start 335.469738 -232.81894)
		(mid 335.75117 -232.894695)
		(end 336.032602 -232.81894)
		(width 0.09525)
		(layer "In4.Cu")
		(net "M_D_CPU0_SA_DQS_DP<6>")
	)
	(arc
		(start 329.829668 -232.81894)
		(mid 330.1111 -232.894695)
		(end 330.392532 -232.81894)
		(width 0.09525)
		(layer "In4.Cu")
		(net "M_D_CPU0_SA_DQS_DP<6>")
	)
	(arc
		(start 336.409792 -232.81894)
		(mid 336.691224 -232.894695)
		(end 336.972656 -232.81894)
		(width 0.09525)
		(layer "In4.Cu")
		(net "M_D_CPU0_SA_DQS_DP<6>")
	)
	(arc
		(start 328.889614 -232.81894)
		(mid 329.171046 -232.894695)
		(end 329.452478 -232.81894)
		(width 0.09525)
		(layer "In4.Cu")
		(net "M_D_CPU0_SA_DQS_DP<6>")
	)
	(arc
		(start 330.400914 -232.814114)
		(mid 330.585946 -232.7682)
		(end 330.769722 -232.81894)
		(width 0.09525)
		(layer "In4.Cu")
		(net "M_D_CPU0_SA_DQS_DP<6>")
	)
	(arc
		(start 329.452478 -232.81894)
		(mid 329.636253 -232.768168)
		(end 329.821286 -232.814114)
		(width 0.09525)
		(layer "In4.Cu")
		(net "M_D_CPU0_SA_DQS_DP<6>")
	)
	(arc
		(start 334.152494 -232.81894)
		(mid 334.336269 -232.768168)
		(end 334.521302 -232.814114)
		(width 0.09525)
		(layer "In4.Cu")
		(net "M_D_CPU0_SA_DQS_DP<6>")
	)
	(arc
		(start 331.709776 -232.81894)
		(mid 331.991208 -232.894695)
		(end 332.27264 -232.81894)
		(width 0.09525)
		(layer "In4.Cu")
		(net "M_D_CPU0_SA_DQS_DP<6>")
	)
	(arc
		(start 339.800946 -232.814114)
		(mid 339.953841 -232.769286)
		(end 340.111588 -232.791762)
		(width 0.09525)
		(layer "In4.Cu")
		(net "M_D_CPU0_SA_DQS_DP<6>")
	)
	(arc
		(start 333.21244 -232.81894)
		(mid 333.396215 -232.768168)
		(end 333.581248 -232.814114)
		(width 0.09525)
		(layer "In4.Cu")
		(net "M_D_CPU0_SA_DQS_DP<6>")
	)
	(arc
		(start 337.912456 -232.81894)
		(mid 338.096231 -232.768168)
		(end 338.281264 -232.814114)
		(width 0.09525)
		(layer "In4.Cu")
		(net "M_D_CPU0_SA_DQS_DP<6>")
	)
	(arc
		(start 336.040984 -232.814114)
		(mid 336.226016 -232.7682)
		(end 336.409792 -232.81894)
		(width 0.09525)
		(layer "In4.Cu")
		(net "M_D_CPU0_SA_DQS_DP<6>")
	)
	(arc
		(start 331.340968 -232.814114)
		(mid 331.526 -232.7682)
		(end 331.709776 -232.81894)
		(width 0.09525)
		(layer "In4.Cu")
		(net "M_D_CPU0_SA_DQS_DP<6>")
	)
	(arc
		(start 337.349592 -232.81894)
		(mid 337.631024 -232.894695)
		(end 337.912456 -232.81894)
		(width 0.09525)
		(layer "In4.Cu")
		(net "M_D_CPU0_SA_DQS_DP<6>")
	)
	(segment
		(start 340.447884 -228.550216)
		(end 339.981032 -228.284278)
		(width 0.12954)
		(layer "F.Cu")
		(net "M_D_CPU0_SA_DQS_DP<5>")
	)
	(segment
		(start 298.953682 -202.310238)
		(end 301.371762 -202.310238)
		(width 0.16002)
		(layer "In4.Cu")
		(net "M_D_CPU0_SA_DQS_DP<5>")
	)
	(segment
		(start 307.7718 -203.160122)
		(end 325.805038 -221.19336)
		(width 0.16002)
		(layer "In4.Cu")
		(net "M_D_CPU0_SA_DQS_DP<5>")
	)
	(segment
		(start 334.521302 -227.954332)
		(end 334.529684 -227.959158)
		(width 0.09525)
		(layer "In4.Cu")
		(net "M_D_CPU0_SA_DQS_DP<5>")
	)
	(segment
		(start 286.281876 -202.325732)
		(end 287.116266 -203.160122)
		(width 0.16002)
		(layer "In4.Cu")
		(net "M_D_CPU0_SA_DQS_DP<5>")
	)
	(segment
		(start 291.059616 -201.957432)
		(end 291.412422 -202.310238)
		(width 0.16002)
		(layer "In4.Cu")
		(net "M_D_CPU0_SA_DQS_DP<5>")
	)
	(segment
		(start 340.111588 -227.93198)
		(end 340.134956 -228.018848)
		(width 0.09525)
		(layer "In4.Cu")
		(net "M_D_CPU0_SA_DQS_DP<5>")
	)
	(segment
		(start 336.032602 -227.959158)
		(end 336.040984 -227.954332)
		(width 0.09525)
		(layer "In4.Cu")
		(net "M_D_CPU0_SA_DQS_DP<5>")
	)
	(segment
		(start 333.581248 -227.954332)
		(end 333.58963 -227.959158)
		(width 0.09525)
		(layer "In4.Cu")
		(net "M_D_CPU0_SA_DQS_DP<5>")
	)
	(segment
		(start 298.26712 -201.957432)
		(end 298.600876 -201.957432)
		(width 0.16002)
		(layer "In4.Cu")
		(net "M_D_CPU0_SA_DQS_DP<5>")
	)
	(segment
		(start 338.85251 -227.959158)
		(end 338.860892 -227.954332)
		(width 0.09525)
		(layer "In4.Cu")
		(net "M_D_CPU0_SA_DQS_DP<5>")
	)
	(segment
		(start 326.540114 -222.289116)
		(end 326.57161 -222.307404)
		(width 0.09525)
		(layer "In4.Cu")
		(net "M_D_CPU0_SA_DQS_DP<5>")
	)
	(segment
		(start 282.203652 -202.27798)
		(end 282.320492 -202.16114)
		(width 0.16002)
		(layer "In4.Cu")
		(net "M_D_CPU0_SA_DQS_DP<5>")
	)
	(segment
		(start 281.723592 -202.27798)
		(end 282.203652 -202.27798)
		(width 0.16002)
		(layer "In4.Cu")
		(net "M_D_CPU0_SA_DQS_DP<5>")
	)
	(segment
		(start 285.372048 -202.442572)
		(end 285.488888 -202.325732)
		(width 0.16002)
		(layer "In4.Cu")
		(net "M_D_CPU0_SA_DQS_DP<5>")
	)
	(segment
		(start 302.194976 -203.133452)
		(end 304.16246 -203.133452)
		(width 0.16002)
		(layer "In4.Cu")
		(net "M_D_CPU0_SA_DQS_DP<5>")
	)
	(segment
		(start 339.792564 -227.959158)
		(end 339.800946 -227.954332)
		(width 0.09525)
		(layer "In4.Cu")
		(net "M_D_CPU0_SA_DQS_DP<5>")
	)
	(segment
		(start 327.949814 -224.719134)
		(end 327.98131 -224.737422)
		(width 0.09525)
		(layer "In4.Cu")
		(net "M_D_CPU0_SA_DQS_DP<5>")
	)
	(segment
		(start 326.503538 -222.27921)
		(end 326.540114 -222.289116)
		(width 0.09525)
		(layer "In4.Cu")
		(net "M_D_CPU0_SA_DQS_DP<5>")
	)
	(segment
		(start 280.909776 -202.16114)
		(end 281.606752 -202.16114)
		(width 0.16002)
		(layer "In4.Cu")
		(net "M_D_CPU0_SA_DQS_DP<5>")
	)
	(segment
		(start 283.531056 -201.990452)
		(end 283.866336 -202.325732)
		(width 0.16002)
		(layer "In4.Cu")
		(net "M_D_CPU0_SA_DQS_DP<5>")
	)
	(segment
		(start 329.359768 -227.149152)
		(end 329.391264 -227.16744)
		(width 0.09525)
		(layer "In4.Cu")
		(net "M_D_CPU0_SA_DQS_DP<5>")
	)
	(segment
		(start 329.791568 -227.93706)
		(end 329.829668 -227.959158)
		(width 0.09525)
		(layer "In4.Cu")
		(net "M_D_CPU0_SA_DQS_DP<5>")
	)
	(segment
		(start 284.775148 -202.325732)
		(end 284.891988 -202.442572)
		(width 0.16002)
		(layer "In4.Cu")
		(net "M_D_CPU0_SA_DQS_DP<5>")
	)
	(segment
		(start 285.488888 -202.325732)
		(end 286.281876 -202.325732)
		(width 0.16002)
		(layer "In4.Cu")
		(net "M_D_CPU0_SA_DQS_DP<5>")
	)
	(segment
		(start 305.608228 -203.160122)
		(end 307.7718 -203.160122)
		(width 0.16002)
		(layer "In4.Cu")
		(net "M_D_CPU0_SA_DQS_DP<5>")
	)
	(segment
		(start 331.332586 -227.959158)
		(end 331.340968 -227.954332)
		(width 0.09525)
		(layer "In4.Cu")
		(net "M_D_CPU0_SA_DQS_DP<5>")
	)
	(segment
		(start 282.97124 -201.990452)
		(end 283.531056 -201.990452)
		(width 0.16002)
		(layer "In4.Cu")
		(net "M_D_CPU0_SA_DQS_DP<5>")
	)
	(segment
		(start 304.46472 -202.831192)
		(end 305.279298 -202.831192)
		(width 0.16002)
		(layer "In4.Cu")
		(net "M_D_CPU0_SA_DQS_DP<5>")
	)
	(segment
		(start 296.56659 -203.160122)
		(end 296.8879 -202.838812)
		(width 0.16002)
		(layer "In4.Cu")
		(net "M_D_CPU0_SA_DQS_DP<5>")
	)
	(segment
		(start 330.392532 -227.959158)
		(end 330.400914 -227.954332)
		(width 0.09525)
		(layer "In4.Cu")
		(net "M_D_CPU0_SA_DQS_DP<5>")
	)
	(segment
		(start 328.856594 -226.319842)
		(end 328.889614 -226.339146)
		(width 0.09525)
		(layer "In4.Cu")
		(net "M_D_CPU0_SA_DQS_DP<5>")
	)
	(segment
		(start 291.412422 -202.310238)
		(end 293.800022 -202.310238)
		(width 0.16002)
		(layer "In4.Cu")
		(net "M_D_CPU0_SA_DQS_DP<5>")
	)
	(segment
		(start 327.914762 -224.69856)
		(end 327.949814 -224.719134)
		(width 0.09525)
		(layer "In4.Cu")
		(net "M_D_CPU0_SA_DQS_DP<5>")
	)
	(segment
		(start 289.85972 -202.836272)
		(end 290.73856 -201.957432)
		(width 0.16002)
		(layer "In4.Cu")
		(net "M_D_CPU0_SA_DQS_DP<5>")
	)
	(segment
		(start 281.606752 -202.16114)
		(end 281.723592 -202.27798)
		(width 0.16002)
		(layer "In4.Cu")
		(net "M_D_CPU0_SA_DQS_DP<5>")
	)
	(segment
		(start 298.600876 -201.957432)
		(end 298.953682 -202.310238)
		(width 0.16002)
		(layer "In4.Cu")
		(net "M_D_CPU0_SA_DQS_DP<5>")
	)
	(segment
		(start 287.116266 -203.160122)
		(end 289.05073 -203.160122)
		(width 0.16002)
		(layer "In4.Cu")
		(net "M_D_CPU0_SA_DQS_DP<5>")
	)
	(segment
		(start 297.38574 -202.838812)
		(end 298.26712 -201.957432)
		(width 0.16002)
		(layer "In4.Cu")
		(net "M_D_CPU0_SA_DQS_DP<5>")
	)
	(segment
		(start 289.05073 -203.160122)
		(end 289.37458 -202.836272)
		(width 0.16002)
		(layer "In4.Cu")
		(net "M_D_CPU0_SA_DQS_DP<5>")
	)
	(segment
		(start 327.00976 -223.099122)
		(end 327.043542 -223.11868)
		(width 0.09525)
		(layer "In4.Cu")
		(net "M_D_CPU0_SA_DQS_DP<5>")
	)
	(segment
		(start 294.649906 -203.160122)
		(end 296.56659 -203.160122)
		(width 0.16002)
		(layer "In4.Cu")
		(net "M_D_CPU0_SA_DQS_DP<5>")
	)
	(segment
		(start 328.854562 -226.318572)
		(end 328.856594 -226.319842)
		(width 0.09525)
		(layer "In4.Cu")
		(net "M_D_CPU0_SA_DQS_DP<5>")
	)
	(segment
		(start 282.800552 -202.16114)
		(end 282.97124 -201.990452)
		(width 0.16002)
		(layer "In4.Cu")
		(net "M_D_CPU0_SA_DQS_DP<5>")
	)
	(segment
		(start 304.16246 -203.133452)
		(end 304.46472 -202.831192)
		(width 0.16002)
		(layer "In4.Cu")
		(net "M_D_CPU0_SA_DQS_DP<5>")
	)
	(segment
		(start 296.8879 -202.838812)
		(end 297.38574 -202.838812)
		(width 0.16002)
		(layer "In4.Cu")
		(net "M_D_CPU0_SA_DQS_DP<5>")
	)
	(segment
		(start 283.866336 -202.325732)
		(end 284.775148 -202.325732)
		(width 0.16002)
		(layer "In4.Cu")
		(net "M_D_CPU0_SA_DQS_DP<5>")
	)
	(segment
		(start 290.73856 -201.957432)
		(end 291.059616 -201.957432)
		(width 0.16002)
		(layer "In4.Cu")
		(net "M_D_CPU0_SA_DQS_DP<5>")
	)
	(segment
		(start 326.121522 -221.981014)
		(end 326.205342 -221.981014)
		(width 0.09525)
		(layer "In4.Cu")
		(net "M_D_CPU0_SA_DQS_DP<5>")
	)
	(segment
		(start 340.134956 -228.018848)
		(end 339.981032 -228.284278)
		(width 0.09525)
		(layer "In4.Cu")
		(net "M_D_CPU0_SA_DQS_DP<5>")
	)
	(segment
		(start 282.320492 -202.16114)
		(end 282.800552 -202.16114)
		(width 0.16002)
		(layer "In4.Cu")
		(net "M_D_CPU0_SA_DQS_DP<5>")
	)
	(segment
		(start 326.205342 -221.981014)
		(end 326.503538 -222.27921)
		(width 0.09525)
		(layer "In4.Cu")
		(net "M_D_CPU0_SA_DQS_DP<5>")
	)
	(segment
		(start 326.104758 -221.96425)
		(end 326.121522 -221.981014)
		(width 0.09525)
		(layer "In4.Cu")
		(net "M_D_CPU0_SA_DQS_DP<5>")
	)
	(segment
		(start 301.371762 -202.310238)
		(end 302.194976 -203.133452)
		(width 0.16002)
		(layer "In4.Cu")
		(net "M_D_CPU0_SA_DQS_DP<5>")
	)
	(segment
		(start 305.279298 -202.831192)
		(end 305.608228 -203.160122)
		(width 0.16002)
		(layer "In4.Cu")
		(net "M_D_CPU0_SA_DQS_DP<5>")
	)
	(segment
		(start 328.419714 -225.52914)
		(end 328.452226 -225.547936)
		(width 0.09525)
		(layer "In4.Cu")
		(net "M_D_CPU0_SA_DQS_DP<5>")
	)
	(segment
		(start 327.480168 -223.909128)
		(end 327.510394 -223.926654)
		(width 0.09525)
		(layer "In4.Cu")
		(net "M_D_CPU0_SA_DQS_DP<5>")
	)
	(segment
		(start 284.891988 -202.442572)
		(end 285.372048 -202.442572)
		(width 0.16002)
		(layer "In4.Cu")
		(net "M_D_CPU0_SA_DQS_DP<5>")
	)
	(segment
		(start 335.092548 -227.959158)
		(end 335.10093 -227.954332)
		(width 0.09525)
		(layer "In4.Cu")
		(net "M_D_CPU0_SA_DQS_DP<5>")
	)
	(segment
		(start 328.889614 -226.339146)
		(end 328.922126 -226.357942)
		(width 0.09525)
		(layer "In4.Cu")
		(net "M_D_CPU0_SA_DQS_DP<5>")
	)
	(segment
		(start 325.805038 -221.19336)
		(end 325.805038 -221.66453)
		(width 0.16002)
		(layer "In4.Cu")
		(net "M_D_CPU0_SA_DQS_DP<5>")
	)
	(segment
		(start 280.635964 -202.434952)
		(end 280.909776 -202.16114)
		(width 0.16002)
		(layer "In4.Cu")
		(net "M_D_CPU0_SA_DQS_DP<5>")
	)
	(segment
		(start 327.440798 -223.886268)
		(end 327.480168 -223.909128)
		(width 0.09525)
		(layer "In4.Cu")
		(net "M_D_CPU0_SA_DQS_DP<5>")
	)
	(segment
		(start 326.976232 -223.079564)
		(end 327.00976 -223.099122)
		(width 0.09525)
		(layer "In4.Cu")
		(net "M_D_CPU0_SA_DQS_DP<5>")
	)
	(segment
		(start 328.381614 -225.507042)
		(end 328.419714 -225.52914)
		(width 0.09525)
		(layer "In4.Cu")
		(net "M_D_CPU0_SA_DQS_DP<5>")
	)
	(segment
		(start 325.805038 -221.66453)
		(end 326.104758 -221.96425)
		(width 0.16002)
		(layer "In4.Cu")
		(net "M_D_CPU0_SA_DQS_DP<5>")
	)
	(segment
		(start 289.37458 -202.836272)
		(end 289.85972 -202.836272)
		(width 0.16002)
		(layer "In4.Cu")
		(net "M_D_CPU0_SA_DQS_DP<5>")
	)
	(segment
		(start 338.281264 -227.954332)
		(end 338.289646 -227.959158)
		(width 0.09525)
		(layer "In4.Cu")
		(net "M_D_CPU0_SA_DQS_DP<5>")
	)
	(segment
		(start 293.800022 -202.310238)
		(end 294.649906 -203.160122)
		(width 0.16002)
		(layer "In4.Cu")
		(net "M_D_CPU0_SA_DQS_DP<5>")
	)
	(segment
		(start 329.321668 -227.127054)
		(end 329.359768 -227.149152)
		(width 0.09525)
		(layer "In4.Cu")
		(net "M_D_CPU0_SA_DQS_DP<5>")
	)
	(arc
		(start 339.2297 -227.959158)
		(mid 339.511132 -228.034913)
		(end 339.792564 -227.959158)
		(width 0.09525)
		(layer "In4.Cu")
		(net "M_D_CPU0_SA_DQS_DP<5>")
	)
	(arc
		(start 339.800946 -227.954332)
		(mid 339.953841 -227.909504)
		(end 340.111588 -227.93198)
		(width 0.09525)
		(layer "In4.Cu")
		(net "M_D_CPU0_SA_DQS_DP<5>")
	)
	(arc
		(start 336.040984 -227.954332)
		(mid 336.226016 -227.908418)
		(end 336.409792 -227.959158)
		(width 0.09525)
		(layer "In4.Cu")
		(net "M_D_CPU0_SA_DQS_DP<5>")
	)
	(arc
		(start 335.10093 -227.954332)
		(mid 335.285962 -227.908418)
		(end 335.469738 -227.959158)
		(width 0.09525)
		(layer "In4.Cu")
		(net "M_D_CPU0_SA_DQS_DP<5>")
	)
	(arc
		(start 337.912456 -227.959158)
		(mid 338.096231 -227.908386)
		(end 338.281264 -227.954332)
		(width 0.09525)
		(layer "In4.Cu")
		(net "M_D_CPU0_SA_DQS_DP<5>")
	)
	(arc
		(start 333.21244 -227.959158)
		(mid 333.396215 -227.908386)
		(end 333.581248 -227.954332)
		(width 0.09525)
		(layer "In4.Cu")
		(net "M_D_CPU0_SA_DQS_DP<5>")
	)
	(arc
		(start 337.349592 -227.959158)
		(mid 337.631024 -228.034913)
		(end 337.912456 -227.959158)
		(width 0.09525)
		(layer "In4.Cu")
		(net "M_D_CPU0_SA_DQS_DP<5>")
	)
	(arc
		(start 329.391264 -227.16744)
		(mid 329.507062 -227.301834)
		(end 329.548744 -227.474272)
		(width 0.09525)
		(layer "In4.Cu")
		(net "M_D_CPU0_SA_DQS_DP<5>")
	)
	(arc
		(start 331.340968 -227.954332)
		(mid 331.526 -227.908418)
		(end 331.709776 -227.959158)
		(width 0.09525)
		(layer "In4.Cu")
		(net "M_D_CPU0_SA_DQS_DP<5>")
	)
	(arc
		(start 338.289646 -227.959158)
		(mid 338.571078 -228.034913)
		(end 338.85251 -227.959158)
		(width 0.09525)
		(layer "In4.Cu")
		(net "M_D_CPU0_SA_DQS_DP<5>")
	)
	(arc
		(start 327.669144 -224.234248)
		(mid 327.734337 -224.496877)
		(end 327.914762 -224.69856)
		(width 0.09525)
		(layer "In4.Cu")
		(net "M_D_CPU0_SA_DQS_DP<5>")
	)
	(arc
		(start 329.078844 -226.664266)
		(mid 329.143241 -226.925572)
		(end 329.321668 -227.127054)
		(width 0.09525)
		(layer "In4.Cu")
		(net "M_D_CPU0_SA_DQS_DP<5>")
	)
	(arc
		(start 327.19899 -223.424242)
		(mid 327.263092 -223.684986)
		(end 327.440798 -223.886268)
		(width 0.09525)
		(layer "In4.Cu")
		(net "M_D_CPU0_SA_DQS_DP<5>")
	)
	(arc
		(start 332.27264 -227.959158)
		(mid 332.461108 -227.908481)
		(end 332.649576 -227.959158)
		(width 0.09525)
		(layer "In4.Cu")
		(net "M_D_CPU0_SA_DQS_DP<5>")
	)
	(arc
		(start 336.972656 -227.959158)
		(mid 337.161124 -227.908481)
		(end 337.349592 -227.959158)
		(width 0.09525)
		(layer "In4.Cu")
		(net "M_D_CPU0_SA_DQS_DP<5>")
	)
	(arc
		(start 334.152494 -227.959158)
		(mid 334.336269 -227.908386)
		(end 334.521302 -227.954332)
		(width 0.09525)
		(layer "In4.Cu")
		(net "M_D_CPU0_SA_DQS_DP<5>")
	)
	(arc
		(start 330.769722 -227.959158)
		(mid 331.051154 -228.034913)
		(end 331.332586 -227.959158)
		(width 0.09525)
		(layer "In4.Cu")
		(net "M_D_CPU0_SA_DQS_DP<5>")
	)
	(arc
		(start 326.729344 -222.614236)
		(mid 326.794897 -222.877608)
		(end 326.976232 -223.079564)
		(width 0.09525)
		(layer "In4.Cu")
		(net "M_D_CPU0_SA_DQS_DP<5>")
	)
	(arc
		(start 331.709776 -227.959158)
		(mid 331.991208 -228.034913)
		(end 332.27264 -227.959158)
		(width 0.09525)
		(layer "In4.Cu")
		(net "M_D_CPU0_SA_DQS_DP<5>")
	)
	(arc
		(start 336.409792 -227.959158)
		(mid 336.691224 -228.034913)
		(end 336.972656 -227.959158)
		(width 0.09525)
		(layer "In4.Cu")
		(net "M_D_CPU0_SA_DQS_DP<5>")
	)
	(arc
		(start 332.649576 -227.959158)
		(mid 332.931008 -228.034913)
		(end 333.21244 -227.959158)
		(width 0.09525)
		(layer "In4.Cu")
		(net "M_D_CPU0_SA_DQS_DP<5>")
	)
	(arc
		(start 328.452226 -225.547936)
		(mid 328.5675 -225.682214)
		(end 328.608944 -225.85426)
		(width 0.09525)
		(layer "In4.Cu")
		(net "M_D_CPU0_SA_DQS_DP<5>")
	)
	(arc
		(start 326.57161 -222.307404)
		(mid 326.687634 -222.441725)
		(end 326.729344 -222.614236)
		(width 0.09525)
		(layer "In4.Cu")
		(net "M_D_CPU0_SA_DQS_DP<5>")
	)
	(arc
		(start 327.510394 -223.926654)
		(mid 327.627095 -224.061183)
		(end 327.669144 -224.234248)
		(width 0.09525)
		(layer "In4.Cu")
		(net "M_D_CPU0_SA_DQS_DP<5>")
	)
	(arc
		(start 329.548744 -227.474272)
		(mid 329.613141 -227.735578)
		(end 329.791568 -227.93706)
		(width 0.09525)
		(layer "In4.Cu")
		(net "M_D_CPU0_SA_DQS_DP<5>")
	)
	(arc
		(start 329.829668 -227.959158)
		(mid 330.1111 -228.034913)
		(end 330.392532 -227.959158)
		(width 0.09525)
		(layer "In4.Cu")
		(net "M_D_CPU0_SA_DQS_DP<5>")
	)
	(arc
		(start 333.58963 -227.959158)
		(mid 333.871062 -228.034913)
		(end 334.152494 -227.959158)
		(width 0.09525)
		(layer "In4.Cu")
		(net "M_D_CPU0_SA_DQS_DP<5>")
	)
	(arc
		(start 335.469738 -227.959158)
		(mid 335.75117 -228.034913)
		(end 336.032602 -227.959158)
		(width 0.09525)
		(layer "In4.Cu")
		(net "M_D_CPU0_SA_DQS_DP<5>")
	)
	(arc
		(start 330.400914 -227.954332)
		(mid 330.585946 -227.908418)
		(end 330.769722 -227.959158)
		(width 0.09525)
		(layer "In4.Cu")
		(net "M_D_CPU0_SA_DQS_DP<5>")
	)
	(arc
		(start 327.043542 -223.11868)
		(mid 327.157921 -223.252819)
		(end 327.19899 -223.424242)
		(width 0.09525)
		(layer "In4.Cu")
		(net "M_D_CPU0_SA_DQS_DP<5>")
	)
	(arc
		(start 334.529684 -227.959158)
		(mid 334.811116 -228.034913)
		(end 335.092548 -227.959158)
		(width 0.09525)
		(layer "In4.Cu")
		(net "M_D_CPU0_SA_DQS_DP<5>")
	)
	(arc
		(start 327.98131 -224.737422)
		(mid 328.097108 -224.871816)
		(end 328.13879 -225.044254)
		(width 0.09525)
		(layer "In4.Cu")
		(net "M_D_CPU0_SA_DQS_DP<5>")
	)
	(arc
		(start 338.860892 -227.954332)
		(mid 339.045924 -227.908418)
		(end 339.2297 -227.959158)
		(width 0.09525)
		(layer "In4.Cu")
		(net "M_D_CPU0_SA_DQS_DP<5>")
	)
	(arc
		(start 328.922126 -226.357942)
		(mid 329.0374 -226.49222)
		(end 329.078844 -226.664266)
		(width 0.09525)
		(layer "In4.Cu")
		(net "M_D_CPU0_SA_DQS_DP<5>")
	)
	(arc
		(start 328.608944 -225.85426)
		(mid 328.674137 -226.116889)
		(end 328.854562 -226.318572)
		(width 0.09525)
		(layer "In4.Cu")
		(net "M_D_CPU0_SA_DQS_DP<5>")
	)
	(arc
		(start 328.13879 -225.044254)
		(mid 328.203187 -225.30556)
		(end 328.381614 -225.507042)
		(width 0.09525)
		(layer "In4.Cu")
		(net "M_D_CPU0_SA_DQS_DP<5>")
	)
	(segment
		(start 339.508084 -246.370094)
		(end 339.040978 -246.104156)
		(width 0.12954)
		(layer "F.Cu")
		(net "M_D_CPU0_SA_DQS_DP<4>")
	)
	(segment
		(start 309.208678 -241.664744)
		(end 309.490872 -241.38255)
		(width 0.16002)
		(layer "In4.Cu")
		(net "M_D_CPU0_SA_DQS_DP<4>")
	)
	(segment
		(start 308.735984 -241.46891)
		(end 308.931818 -241.664744)
		(width 0.16002)
		(layer "In4.Cu")
		(net "M_D_CPU0_SA_DQS_DP<4>")
	)
	(segment
		(start 310.109616 -242.565682)
		(end 310.109616 -242.842542)
		(width 0.16002)
		(layer "In4.Cu")
		(net "M_D_CPU0_SA_DQS_DP<4>")
	)
	(segment
		(start 311.679082 -244.412008)
		(end 311.955942 -244.412008)
		(width 0.16002)
		(layer "In4.Cu")
		(net "M_D_CPU0_SA_DQS_DP<4>")
	)
	(segment
		(start 287.012634 -238.408972)
		(end 287.161732 -238.259874)
		(width 0.16002)
		(layer "In4.Cu")
		(net "M_D_CPU0_SA_DQS_DP<4>")
	)
	(segment
		(start 326.07123 -246.429276)
		(end 326.105774 -246.40921)
		(width 0.09525)
		(layer "In4.Cu")
		(net "M_D_CPU0_SA_DQS_DP<4>")
	)
	(segment
		(start 310.39181 -242.283488)
		(end 310.109616 -242.565682)
		(width 0.16002)
		(layer "In4.Cu")
		(net "M_D_CPU0_SA_DQS_DP<4>")
	)
	(segment
		(start 298.173648 -237.758732)
		(end 298.589954 -237.758732)
		(width 0.16002)
		(layer "In4.Cu")
		(net "M_D_CPU0_SA_DQS_DP<4>")
	)
	(segment
		(start 338.281264 -246.434102)
		(end 338.289646 -246.429276)
		(width 0.09525)
		(layer "In4.Cu")
		(net "M_D_CPU0_SA_DQS_DP<4>")
	)
	(segment
		(start 297.343068 -238.589312)
		(end 298.173648 -237.758732)
		(width 0.16002)
		(layer "In4.Cu")
		(net "M_D_CPU0_SA_DQS_DP<4>")
	)
	(segment
		(start 303.38395 -239.30483)
		(end 303.664112 -239.30483)
		(width 0.16002)
		(layer "In4.Cu")
		(net "M_D_CPU0_SA_DQS_DP<4>")
	)
	(segment
		(start 310.30545 -243.038376)
		(end 310.58231 -243.038376)
		(width 0.16002)
		(layer "In4.Cu")
		(net "M_D_CPU0_SA_DQS_DP<4>")
	)
	(segment
		(start 311.955942 -244.412008)
		(end 312.238136 -244.129814)
		(width 0.16002)
		(layer "In4.Cu")
		(net "M_D_CPU0_SA_DQS_DP<4>")
	)
	(segment
		(start 291.046154 -237.758732)
		(end 291.394896 -237.40999)
		(width 0.16002)
		(layer "In4.Cu")
		(net "M_D_CPU0_SA_DQS_DP<4>")
	)
	(segment
		(start 293.979092 -238.259874)
		(end 296.598594 -238.259874)
		(width 0.16002)
		(layer "In4.Cu")
		(net "M_D_CPU0_SA_DQS_DP<4>")
	)
	(segment
		(start 312.85688 -245.589806)
		(end 313.258454 -245.99138)
		(width 0.16002)
		(layer "In4.Cu")
		(net "M_D_CPU0_SA_DQS_DP<4>")
	)
	(segment
		(start 308.541674 -240.111788)
		(end 308.915308 -240.485422)
		(width 0.16002)
		(layer "In4.Cu")
		(net "M_D_CPU0_SA_DQS_DP<4>")
	)
	(segment
		(start 324.393052 -246.253254)
		(end 324.393052 -246.538242)
		(width 0.09525)
		(layer "In4.Cu")
		(net "M_D_CPU0_SA_DQS_DP<4>")
	)
	(segment
		(start 306.318666 -239.051592)
		(end 307.558186 -240.291112)
		(width 0.16002)
		(layer "In4.Cu")
		(net "M_D_CPU0_SA_DQS_DP<4>")
	)
	(segment
		(start 338.887054 -246.369586)
		(end 339.040978 -246.104156)
		(width 0.09525)
		(layer "In4.Cu")
		(net "M_D_CPU0_SA_DQS_DP<4>")
	)
	(segment
		(start 310.58231 -243.038376)
		(end 310.864504 -242.756182)
		(width 0.16002)
		(layer "In4.Cu")
		(net "M_D_CPU0_SA_DQS_DP<4>")
	)
	(segment
		(start 313.139074 -245.030752)
		(end 312.85688 -245.312946)
		(width 0.16002)
		(layer "In4.Cu")
		(net "M_D_CPU0_SA_DQS_DP<4>")
	)
	(segment
		(start 289.054794 -238.259874)
		(end 289.384232 -238.589312)
		(width 0.16002)
		(layer "In4.Cu")
		(net "M_D_CPU0_SA_DQS_DP<4>")
	)
	(segment
		(start 311.765442 -243.129816)
		(end 311.765442 -243.65712)
		(width 0.16002)
		(layer "In4.Cu")
		(net "M_D_CPU0_SA_DQS_DP<4>")
	)
	(segment
		(start 303.186084 -239.106964)
		(end 303.38395 -239.30483)
		(width 0.16002)
		(layer "In4.Cu")
		(net "M_D_CPU0_SA_DQS_DP<4>")
	)
	(segment
		(start 323.843396 -245.99138)
		(end 323.902324 -246.050308)
		(width 0.09525)
		(layer "In4.Cu")
		(net "M_D_CPU0_SA_DQS_DP<4>")
	)
	(segment
		(start 326.99325 -246.440198)
		(end 327.012046 -246.429276)
		(width 0.09525)
		(layer "In4.Cu")
		(net "M_D_CPU0_SA_DQS_DP<4>")
	)
	(segment
		(start 310.109616 -242.842542)
		(end 310.30545 -243.038376)
		(width 0.16002)
		(layer "In4.Cu")
		(net "M_D_CPU0_SA_DQS_DP<4>")
	)
	(segment
		(start 329.821286 -246.434102)
		(end 329.829668 -246.429276)
		(width 0.09525)
		(layer "In4.Cu")
		(net "M_D_CPU0_SA_DQS_DP<4>")
	)
	(segment
		(start 308.931818 -241.664744)
		(end 309.208678 -241.664744)
		(width 0.16002)
		(layer "In4.Cu")
		(net "M_D_CPU0_SA_DQS_DP<4>")
	)
	(segment
		(start 307.835046 -240.291112)
		(end 308.01437 -240.111788)
		(width 0.16002)
		(layer "In4.Cu")
		(net "M_D_CPU0_SA_DQS_DP<4>")
	)
	(segment
		(start 324.393052 -246.538242)
		(end 324.617842 -246.763032)
		(width 0.09525)
		(layer "In4.Cu")
		(net "M_D_CPU0_SA_DQS_DP<4>")
	)
	(segment
		(start 290.6014 -237.758732)
		(end 291.046154 -237.758732)
		(width 0.16002)
		(layer "In4.Cu")
		(net "M_D_CPU0_SA_DQS_DP<4>")
	)
	(segment
		(start 308.915308 -240.485422)
		(end 308.915308 -241.012726)
		(width 0.16002)
		(layer "In4.Cu")
		(net "M_D_CPU0_SA_DQS_DP<4>")
	)
	(segment
		(start 309.490872 -241.38255)
		(end 310.018176 -241.38255)
		(width 0.16002)
		(layer "In4.Cu")
		(net "M_D_CPU0_SA_DQS_DP<4>")
	)
	(segment
		(start 301.600108 -238.288322)
		(end 302.832516 -238.288322)
		(width 0.16002)
		(layer "In4.Cu")
		(net "M_D_CPU0_SA_DQS_DP<4>")
	)
	(segment
		(start 293.129208 -237.40999)
		(end 293.979092 -238.259874)
		(width 0.16002)
		(layer "In4.Cu")
		(net "M_D_CPU0_SA_DQS_DP<4>")
	)
	(segment
		(start 311.483248 -243.939314)
		(end 311.483248 -244.216174)
		(width 0.16002)
		(layer "In4.Cu")
		(net "M_D_CPU0_SA_DQS_DP<4>")
	)
	(segment
		(start 308.915308 -241.012726)
		(end 308.735984 -241.19205)
		(width 0.16002)
		(layer "In4.Cu")
		(net "M_D_CPU0_SA_DQS_DP<4>")
	)
	(segment
		(start 298.938696 -237.40999)
		(end 300.721776 -237.40999)
		(width 0.16002)
		(layer "In4.Cu")
		(net "M_D_CPU0_SA_DQS_DP<4>")
	)
	(segment
		(start 323.819774 -245.99138)
		(end 323.843396 -245.99138)
		(width 0.09525)
		(layer "In4.Cu")
		(net "M_D_CPU0_SA_DQS_DP<4>")
	)
	(segment
		(start 303.664112 -239.30483)
		(end 303.91735 -239.051592)
		(width 0.16002)
		(layer "In4.Cu")
		(net "M_D_CPU0_SA_DQS_DP<4>")
	)
	(segment
		(start 331.332586 -246.429276)
		(end 331.340968 -246.434102)
		(width 0.09525)
		(layer "In4.Cu")
		(net "M_D_CPU0_SA_DQS_DP<4>")
	)
	(segment
		(start 285.009844 -238.408972)
		(end 287.012634 -238.408972)
		(width 0.16002)
		(layer "In4.Cu")
		(net "M_D_CPU0_SA_DQS_DP<4>")
	)
	(segment
		(start 327.547986 -246.414544)
		(end 327.573386 -246.429276)
		(width 0.09525)
		(layer "In4.Cu")
		(net "M_D_CPU0_SA_DQS_DP<4>")
	)
	(segment
		(start 310.39181 -241.756184)
		(end 310.39181 -242.283488)
		(width 0.16002)
		(layer "In4.Cu")
		(net "M_D_CPU0_SA_DQS_DP<4>")
	)
	(segment
		(start 311.765442 -243.65712)
		(end 311.483248 -243.939314)
		(width 0.16002)
		(layer "In4.Cu")
		(net "M_D_CPU0_SA_DQS_DP<4>")
	)
	(segment
		(start 324.190106 -246.050308)
		(end 324.393052 -246.253254)
		(width 0.09525)
		(layer "In4.Cu")
		(net "M_D_CPU0_SA_DQS_DP<4>")
	)
	(segment
		(start 324.617842 -246.763032)
		(end 325.264018 -246.763032)
		(width 0.09525)
		(layer "In4.Cu")
		(net "M_D_CPU0_SA_DQS_DP<4>")
	)
	(segment
		(start 289.77082 -238.589312)
		(end 290.6014 -237.758732)
		(width 0.16002)
		(layer "In4.Cu")
		(net "M_D_CPU0_SA_DQS_DP<4>")
	)
	(segment
		(start 311.483248 -244.216174)
		(end 311.679082 -244.412008)
		(width 0.16002)
		(layer "In4.Cu")
		(net "M_D_CPU0_SA_DQS_DP<4>")
	)
	(segment
		(start 303.186084 -238.64189)
		(end 303.186084 -239.106964)
		(width 0.16002)
		(layer "In4.Cu")
		(net "M_D_CPU0_SA_DQS_DP<4>")
	)
	(segment
		(start 310.864504 -242.756182)
		(end 311.391808 -242.756182)
		(width 0.16002)
		(layer "In4.Cu")
		(net "M_D_CPU0_SA_DQS_DP<4>")
	)
	(segment
		(start 330.392532 -246.429276)
		(end 330.400914 -246.434102)
		(width 0.09525)
		(layer "In4.Cu")
		(net "M_D_CPU0_SA_DQS_DP<4>")
	)
	(segment
		(start 296.928032 -238.589312)
		(end 297.343068 -238.589312)
		(width 0.16002)
		(layer "In4.Cu")
		(net "M_D_CPU0_SA_DQS_DP<4>")
	)
	(segment
		(start 333.581248 -246.434102)
		(end 333.58963 -246.429276)
		(width 0.09525)
		(layer "In4.Cu")
		(net "M_D_CPU0_SA_DQS_DP<4>")
	)
	(segment
		(start 308.01437 -240.111788)
		(end 308.541674 -240.111788)
		(width 0.16002)
		(layer "In4.Cu")
		(net "M_D_CPU0_SA_DQS_DP<4>")
	)
	(segment
		(start 312.85688 -245.312946)
		(end 312.85688 -245.589806)
		(width 0.16002)
		(layer "In4.Cu")
		(net "M_D_CPU0_SA_DQS_DP<4>")
	)
	(segment
		(start 291.394896 -237.40999)
		(end 293.129208 -237.40999)
		(width 0.16002)
		(layer "In4.Cu")
		(net "M_D_CPU0_SA_DQS_DP<4>")
	)
	(segment
		(start 335.092548 -246.429276)
		(end 335.10093 -246.434102)
		(width 0.09525)
		(layer "In4.Cu")
		(net "M_D_CPU0_SA_DQS_DP<4>")
	)
	(segment
		(start 323.902324 -246.050308)
		(end 324.190106 -246.050308)
		(width 0.09525)
		(layer "In4.Cu")
		(net "M_D_CPU0_SA_DQS_DP<4>")
	)
	(segment
		(start 310.018176 -241.38255)
		(end 310.39181 -241.756184)
		(width 0.16002)
		(layer "In4.Cu")
		(net "M_D_CPU0_SA_DQS_DP<4>")
	)
	(segment
		(start 325.264018 -246.763032)
		(end 325.546974 -246.480076)
		(width 0.09525)
		(layer "In4.Cu")
		(net "M_D_CPU0_SA_DQS_DP<4>")
	)
	(segment
		(start 313.139074 -244.503448)
		(end 313.139074 -245.030752)
		(width 0.16002)
		(layer "In4.Cu")
		(net "M_D_CPU0_SA_DQS_DP<4>")
	)
	(segment
		(start 334.521302 -246.434102)
		(end 334.529684 -246.429276)
		(width 0.09525)
		(layer "In4.Cu")
		(net "M_D_CPU0_SA_DQS_DP<4>")
	)
	(segment
		(start 303.91735 -239.051592)
		(end 306.318666 -239.051592)
		(width 0.16002)
		(layer "In4.Cu")
		(net "M_D_CPU0_SA_DQS_DP<4>")
	)
	(segment
		(start 296.598594 -238.259874)
		(end 296.928032 -238.589312)
		(width 0.16002)
		(layer "In4.Cu")
		(net "M_D_CPU0_SA_DQS_DP<4>")
	)
	(segment
		(start 307.558186 -240.291112)
		(end 307.835046 -240.291112)
		(width 0.16002)
		(layer "In4.Cu")
		(net "M_D_CPU0_SA_DQS_DP<4>")
	)
	(segment
		(start 289.384232 -238.589312)
		(end 289.77082 -238.589312)
		(width 0.16002)
		(layer "In4.Cu")
		(net "M_D_CPU0_SA_DQS_DP<4>")
	)
	(segment
		(start 308.735984 -241.19205)
		(end 308.735984 -241.46891)
		(width 0.16002)
		(layer "In4.Cu")
		(net "M_D_CPU0_SA_DQS_DP<4>")
	)
	(segment
		(start 298.589954 -237.758732)
		(end 298.938696 -237.40999)
		(width 0.16002)
		(layer "In4.Cu")
		(net "M_D_CPU0_SA_DQS_DP<4>")
	)
	(segment
		(start 287.161732 -238.259874)
		(end 289.054794 -238.259874)
		(width 0.16002)
		(layer "In4.Cu")
		(net "M_D_CPU0_SA_DQS_DP<4>")
	)
	(segment
		(start 311.391808 -242.756182)
		(end 311.765442 -243.129816)
		(width 0.16002)
		(layer "In4.Cu")
		(net "M_D_CPU0_SA_DQS_DP<4>")
	)
	(segment
		(start 336.032602 -246.429276)
		(end 336.040984 -246.434102)
		(width 0.09525)
		(layer "In4.Cu")
		(net "M_D_CPU0_SA_DQS_DP<4>")
	)
	(segment
		(start 327.573386 -246.429276)
		(end 327.59015 -246.438928)
		(width 0.09525)
		(layer "In4.Cu")
		(net "M_D_CPU0_SA_DQS_DP<4>")
	)
	(segment
		(start 338.786216 -246.396256)
		(end 338.887054 -246.369586)
		(width 0.09525)
		(layer "In4.Cu")
		(net "M_D_CPU0_SA_DQS_DP<4>")
	)
	(segment
		(start 312.76544 -244.129814)
		(end 313.139074 -244.503448)
		(width 0.16002)
		(layer "In4.Cu")
		(net "M_D_CPU0_SA_DQS_DP<4>")
	)
	(segment
		(start 325.546974 -246.480076)
		(end 325.883524 -246.480076)
		(width 0.09525)
		(layer "In4.Cu")
		(net "M_D_CPU0_SA_DQS_DP<4>")
	)
	(segment
		(start 300.721776 -237.40999)
		(end 301.600108 -238.288322)
		(width 0.16002)
		(layer "In4.Cu")
		(net "M_D_CPU0_SA_DQS_DP<4>")
	)
	(segment
		(start 302.832516 -238.288322)
		(end 303.186084 -238.64189)
		(width 0.16002)
		(layer "In4.Cu")
		(net "M_D_CPU0_SA_DQS_DP<4>")
	)
	(segment
		(start 284.736032 -238.13516)
		(end 285.009844 -238.408972)
		(width 0.16002)
		(layer "In4.Cu")
		(net "M_D_CPU0_SA_DQS_DP<4>")
	)
	(segment
		(start 313.258454 -245.99138)
		(end 323.819774 -245.99138)
		(width 0.16002)
		(layer "In4.Cu")
		(net "M_D_CPU0_SA_DQS_DP<4>")
	)
	(segment
		(start 312.238136 -244.129814)
		(end 312.76544 -244.129814)
		(width 0.16002)
		(layer "In4.Cu")
		(net "M_D_CPU0_SA_DQS_DP<4>")
	)
	(arc
		(start 332.27264 -246.429276)
		(mid 332.461108 -246.479953)
		(end 332.649576 -246.429276)
		(width 0.09525)
		(layer "In4.Cu")
		(net "M_D_CPU0_SA_DQS_DP<4>")
	)
	(arc
		(start 326.63384 -246.429276)
		(mid 326.812155 -246.480418)
		(end 326.99325 -246.440198)
		(width 0.09525)
		(layer "In4.Cu")
		(net "M_D_CPU0_SA_DQS_DP<4>")
	)
	(arc
		(start 336.040984 -246.434102)
		(mid 336.226016 -246.480016)
		(end 336.409792 -246.429276)
		(width 0.09525)
		(layer "In4.Cu")
		(net "M_D_CPU0_SA_DQS_DP<4>")
	)
	(arc
		(start 328.512678 -246.429276)
		(mid 328.701146 -246.479953)
		(end 328.889614 -246.429276)
		(width 0.09525)
		(layer "In4.Cu")
		(net "M_D_CPU0_SA_DQS_DP<4>")
	)
	(arc
		(start 338.289646 -246.429276)
		(mid 338.523441 -246.355409)
		(end 338.766404 -246.388382)
		(width 0.09525)
		(layer "In4.Cu")
		(net "M_D_CPU0_SA_DQS_DP<4>")
	)
	(arc
		(start 326.105774 -246.40921)
		(mid 326.3723 -246.353273)
		(end 326.63384 -246.429276)
		(width 0.09525)
		(layer "In4.Cu")
		(net "M_D_CPU0_SA_DQS_DP<4>")
	)
	(arc
		(start 329.452478 -246.429276)
		(mid 329.636253 -246.480048)
		(end 329.821286 -246.434102)
		(width 0.09525)
		(layer "In4.Cu")
		(net "M_D_CPU0_SA_DQS_DP<4>")
	)
	(arc
		(start 331.340968 -246.434102)
		(mid 331.526 -246.480016)
		(end 331.709776 -246.429276)
		(width 0.09525)
		(layer "In4.Cu")
		(net "M_D_CPU0_SA_DQS_DP<4>")
	)
	(arc
		(start 333.21244 -246.429276)
		(mid 333.396215 -246.480048)
		(end 333.581248 -246.434102)
		(width 0.09525)
		(layer "In4.Cu")
		(net "M_D_CPU0_SA_DQS_DP<4>")
	)
	(arc
		(start 334.529684 -246.429276)
		(mid 334.811116 -246.353521)
		(end 335.092548 -246.429276)
		(width 0.09525)
		(layer "In4.Cu")
		(net "M_D_CPU0_SA_DQS_DP<4>")
	)
	(arc
		(start 335.469738 -246.429276)
		(mid 335.75117 -246.353521)
		(end 336.032602 -246.429276)
		(width 0.09525)
		(layer "In4.Cu")
		(net "M_D_CPU0_SA_DQS_DP<4>")
	)
	(arc
		(start 330.400914 -246.434102)
		(mid 330.585946 -246.480016)
		(end 330.769722 -246.429276)
		(width 0.09525)
		(layer "In4.Cu")
		(net "M_D_CPU0_SA_DQS_DP<4>")
	)
	(arc
		(start 332.649576 -246.429276)
		(mid 332.931008 -246.353521)
		(end 333.21244 -246.429276)
		(width 0.09525)
		(layer "In4.Cu")
		(net "M_D_CPU0_SA_DQS_DP<4>")
	)
	(arc
		(start 336.409792 -246.429276)
		(mid 336.691224 -246.353521)
		(end 336.972656 -246.429276)
		(width 0.09525)
		(layer "In4.Cu")
		(net "M_D_CPU0_SA_DQS_DP<4>")
	)
	(arc
		(start 335.10093 -246.434102)
		(mid 335.285962 -246.480016)
		(end 335.469738 -246.429276)
		(width 0.09525)
		(layer "In4.Cu")
		(net "M_D_CPU0_SA_DQS_DP<4>")
	)
	(arc
		(start 329.829668 -246.429276)
		(mid 330.1111 -246.353521)
		(end 330.392532 -246.429276)
		(width 0.09525)
		(layer "In4.Cu")
		(net "M_D_CPU0_SA_DQS_DP<4>")
	)
	(arc
		(start 327.012046 -246.429276)
		(mid 327.278133 -246.353731)
		(end 327.547986 -246.414544)
		(width 0.09525)
		(layer "In4.Cu")
		(net "M_D_CPU0_SA_DQS_DP<4>")
	)
	(arc
		(start 337.349592 -246.429276)
		(mid 337.631024 -246.353521)
		(end 337.912456 -246.429276)
		(width 0.09525)
		(layer "In4.Cu")
		(net "M_D_CPU0_SA_DQS_DP<4>")
	)
	(arc
		(start 325.883524 -246.480076)
		(mid 325.924288 -246.477719)
		(end 325.96455 -246.470932)
		(width 0.09525)
		(layer "In4.Cu")
		(net "M_D_CPU0_SA_DQS_DP<4>")
	)
	(arc
		(start 338.766404 -246.388382)
		(mid 338.776347 -246.392225)
		(end 338.786216 -246.396256)
		(width 0.09525)
		(layer "In4.Cu")
		(net "M_D_CPU0_SA_DQS_DP<4>")
	)
	(arc
		(start 330.769722 -246.429276)
		(mid 331.051154 -246.353521)
		(end 331.332586 -246.429276)
		(width 0.09525)
		(layer "In4.Cu")
		(net "M_D_CPU0_SA_DQS_DP<4>")
	)
	(arc
		(start 328.889614 -246.429276)
		(mid 329.171046 -246.353521)
		(end 329.452478 -246.429276)
		(width 0.09525)
		(layer "In4.Cu")
		(net "M_D_CPU0_SA_DQS_DP<4>")
	)
	(arc
		(start 331.709776 -246.429276)
		(mid 331.991208 -246.353521)
		(end 332.27264 -246.429276)
		(width 0.09525)
		(layer "In4.Cu")
		(net "M_D_CPU0_SA_DQS_DP<4>")
	)
	(arc
		(start 336.972656 -246.429276)
		(mid 337.161124 -246.479953)
		(end 337.349592 -246.429276)
		(width 0.09525)
		(layer "In4.Cu")
		(net "M_D_CPU0_SA_DQS_DP<4>")
	)
	(arc
		(start 333.58963 -246.429276)
		(mid 333.871062 -246.353521)
		(end 334.152494 -246.429276)
		(width 0.09525)
		(layer "In4.Cu")
		(net "M_D_CPU0_SA_DQS_DP<4>")
	)
	(arc
		(start 334.152494 -246.429276)
		(mid 334.336269 -246.480048)
		(end 334.521302 -246.434102)
		(width 0.09525)
		(layer "In4.Cu")
		(net "M_D_CPU0_SA_DQS_DP<4>")
	)
	(arc
		(start 327.949814 -246.429276)
		(mid 328.231246 -246.353521)
		(end 328.512678 -246.429276)
		(width 0.09525)
		(layer "In4.Cu")
		(net "M_D_CPU0_SA_DQS_DP<4>")
	)
	(arc
		(start 325.96455 -246.470932)
		(mid 326.019478 -246.454176)
		(end 326.07123 -246.429276)
		(width 0.09525)
		(layer "In4.Cu")
		(net "M_D_CPU0_SA_DQS_DP<4>")
	)
	(arc
		(start 337.912456 -246.429276)
		(mid 338.096231 -246.480048)
		(end 338.281264 -246.434102)
		(width 0.09525)
		(layer "In4.Cu")
		(net "M_D_CPU0_SA_DQS_DP<4>")
	)
	(arc
		(start 327.59015 -246.438928)
		(mid 327.771207 -246.47991)
		(end 327.949814 -246.429276)
		(width 0.09525)
		(layer "In4.Cu")
		(net "M_D_CPU0_SA_DQS_DP<4>")
	)
	(segment
		(start 339.508084 -241.510058)
		(end 339.040978 -241.24412)
		(width 0.12954)
		(layer "F.Cu")
		(net "M_D_CPU0_SA_DQS_DP<3>")
	)
	(segment
		(start 307.293772 -228.919532)
		(end 307.820822 -228.919532)
		(width 0.16002)
		(layer "In4.Cu")
		(net "M_D_CPU0_SA_DQS_DP<3>")
	)
	(segment
		(start 311.921144 -232.440226)
		(end 312.295032 -232.814114)
		(width 0.16002)
		(layer "In4.Cu")
		(net "M_D_CPU0_SA_DQS_DP<3>")
	)
	(segment
		(start 325.757794 -241.493548)
		(end 326.351138 -241.493548)
		(width 0.09525)
		(layer "In4.Cu")
		(net "M_D_CPU0_SA_DQS_DP<3>")
	)
	(segment
		(start 293.874444 -228.90988)
		(end 296.598594 -228.90988)
		(width 0.16002)
		(layer "In4.Cu")
		(net "M_D_CPU0_SA_DQS_DP<3>")
	)
	(segment
		(start 330.392532 -241.56924)
		(end 330.400914 -241.574066)
		(width 0.09525)
		(layer "In4.Cu")
		(net "M_D_CPU0_SA_DQS_DP<3>")
	)
	(segment
		(start 310.713374 -232.452926)
		(end 310.909208 -232.64876)
		(width 0.16002)
		(layer "In4.Cu")
		(net "M_D_CPU0_SA_DQS_DP<3>")
	)
	(segment
		(start 303.51476 -229.249732)
		(end 303.905158 -229.64013)
		(width 0.16002)
		(layer "In4.Cu")
		(net "M_D_CPU0_SA_DQS_DP<3>")
	)
	(segment
		(start 309.547768 -230.067104)
		(end 309.548022 -230.594154)
		(width 0.16002)
		(layer "In4.Cu")
		(net "M_D_CPU0_SA_DQS_DP<3>")
	)
	(segment
		(start 313.668918 -234.71505)
		(end 313.460638 -234.92333)
		(width 0.16002)
		(layer "In4.Cu")
		(net "M_D_CPU0_SA_DQS_DP<3>")
	)
	(segment
		(start 309.339742 -230.802434)
		(end 309.339742 -231.079294)
		(width 0.16002)
		(layer "In4.Cu")
		(net "M_D_CPU0_SA_DQS_DP<3>")
	)
	(segment
		(start 312.5597 -234.022392)
		(end 312.76798 -233.814112)
		(width 0.16002)
		(layer "In4.Cu")
		(net "M_D_CPU0_SA_DQS_DP<3>")
	)
	(segment
		(start 311.186068 -232.64876)
		(end 311.394348 -232.44048)
		(width 0.16002)
		(layer "In4.Cu")
		(net "M_D_CPU0_SA_DQS_DP<3>")
	)
	(segment
		(start 309.17388 -229.693216)
		(end 309.547768 -230.067104)
		(width 0.16002)
		(layer "In4.Cu")
		(net "M_D_CPU0_SA_DQS_DP<3>")
	)
	(segment
		(start 325.167498 -240.903252)
		(end 325.757794 -241.493548)
		(width 0.09525)
		(layer "In4.Cu")
		(net "M_D_CPU0_SA_DQS_DP<3>")
	)
	(segment
		(start 284.736032 -228.785166)
		(end 285.009844 -229.058978)
		(width 0.16002)
		(layer "In4.Cu")
		(net "M_D_CPU0_SA_DQS_DP<3>")
	)
	(segment
		(start 293.02456 -228.059996)
		(end 293.874444 -228.90988)
		(width 0.16002)
		(layer "In4.Cu")
		(net "M_D_CPU0_SA_DQS_DP<3>")
	)
	(segment
		(start 289.696144 -229.313994)
		(end 290.6014 -228.408738)
		(width 0.16002)
		(layer "In4.Cu")
		(net "M_D_CPU0_SA_DQS_DP<3>")
	)
	(segment
		(start 323.895974 -240.357152)
		(end 323.919596 -240.357152)
		(width 0.09525)
		(layer "In4.Cu")
		(net "M_D_CPU0_SA_DQS_DP<3>")
	)
	(segment
		(start 309.548022 -230.594154)
		(end 309.339742 -230.802434)
		(width 0.16002)
		(layer "In4.Cu")
		(net "M_D_CPU0_SA_DQS_DP<3>")
	)
	(segment
		(start 306.9209 -229.292404)
		(end 307.293772 -228.919532)
		(width 0.16002)
		(layer "In4.Cu")
		(net "M_D_CPU0_SA_DQS_DP<3>")
	)
	(segment
		(start 334.521302 -241.574066)
		(end 334.529684 -241.56924)
		(width 0.09525)
		(layer "In4.Cu")
		(net "M_D_CPU0_SA_DQS_DP<3>")
	)
	(segment
		(start 287.161732 -228.90988)
		(end 289.054794 -228.90988)
		(width 0.16002)
		(layer "In4.Cu")
		(net "M_D_CPU0_SA_DQS_DP<3>")
	)
	(segment
		(start 308.193694 -229.292404)
		(end 308.193694 -229.451916)
		(width 0.16002)
		(layer "In4.Cu")
		(net "M_D_CPU0_SA_DQS_DP<3>")
	)
	(segment
		(start 289.054794 -228.90988)
		(end 289.458908 -229.313994)
		(width 0.16002)
		(layer "In4.Cu")
		(net "M_D_CPU0_SA_DQS_DP<3>")
	)
	(segment
		(start 323.978778 -240.416334)
		(end 324.240906 -240.416334)
		(width 0.09525)
		(layer "In4.Cu")
		(net "M_D_CPU0_SA_DQS_DP<3>")
	)
	(segment
		(start 309.812436 -231.275128)
		(end 310.020716 -231.066848)
		(width 0.16002)
		(layer "In4.Cu")
		(net "M_D_CPU0_SA_DQS_DP<3>")
	)
	(segment
		(start 305.846226 -229.64013)
		(end 306.732686 -229.64013)
		(width 0.16002)
		(layer "In4.Cu")
		(net "M_D_CPU0_SA_DQS_DP<3>")
	)
	(segment
		(start 306.9209 -229.451916)
		(end 306.9209 -229.292404)
		(width 0.16002)
		(layer "In4.Cu")
		(net "M_D_CPU0_SA_DQS_DP<3>")
	)
	(segment
		(start 298.589954 -228.408738)
		(end 298.938696 -228.059996)
		(width 0.16002)
		(layer "In4.Cu")
		(net "M_D_CPU0_SA_DQS_DP<3>")
	)
	(segment
		(start 309.535576 -231.275128)
		(end 309.812436 -231.275128)
		(width 0.16002)
		(layer "In4.Cu")
		(net "M_D_CPU0_SA_DQS_DP<3>")
	)
	(segment
		(start 296.598594 -228.90988)
		(end 297.016932 -229.328218)
		(width 0.16002)
		(layer "In4.Cu")
		(net "M_D_CPU0_SA_DQS_DP<3>")
	)
	(segment
		(start 312.087006 -233.826558)
		(end 312.28284 -234.022392)
		(width 0.16002)
		(layer "In4.Cu")
		(net "M_D_CPU0_SA_DQS_DP<3>")
	)
	(segment
		(start 289.458908 -229.313994)
		(end 289.696144 -229.313994)
		(width 0.16002)
		(layer "In4.Cu")
		(net "M_D_CPU0_SA_DQS_DP<3>")
	)
	(segment
		(start 285.009844 -229.058978)
		(end 287.012634 -229.058978)
		(width 0.16002)
		(layer "In4.Cu")
		(net "M_D_CPU0_SA_DQS_DP<3>")
	)
	(segment
		(start 287.012634 -229.058978)
		(end 287.161732 -228.90988)
		(width 0.16002)
		(layer "In4.Cu")
		(net "M_D_CPU0_SA_DQS_DP<3>")
	)
	(segment
		(start 313.460638 -234.92333)
		(end 313.460638 -235.20019)
		(width 0.16002)
		(layer "In4.Cu")
		(net "M_D_CPU0_SA_DQS_DP<3>")
	)
	(segment
		(start 338.281264 -241.574066)
		(end 338.289646 -241.56924)
		(width 0.09525)
		(layer "In4.Cu")
		(net "M_D_CPU0_SA_DQS_DP<3>")
	)
	(segment
		(start 298.938696 -228.059996)
		(end 300.721776 -228.059996)
		(width 0.16002)
		(layer "In4.Cu")
		(net "M_D_CPU0_SA_DQS_DP<3>")
	)
	(segment
		(start 291.046154 -228.408738)
		(end 291.394896 -228.059996)
		(width 0.16002)
		(layer "In4.Cu")
		(net "M_D_CPU0_SA_DQS_DP<3>")
	)
	(segment
		(start 324.240906 -240.416334)
		(end 324.727824 -240.903252)
		(width 0.09525)
		(layer "In4.Cu")
		(net "M_D_CPU0_SA_DQS_DP<3>")
	)
	(segment
		(start 318.6176 -240.357152)
		(end 323.895974 -240.357152)
		(width 0.16002)
		(layer "In4.Cu")
		(net "M_D_CPU0_SA_DQS_DP<3>")
	)
	(segment
		(start 312.76798 -233.814112)
		(end 313.294776 -233.813858)
		(width 0.16002)
		(layer "In4.Cu")
		(net "M_D_CPU0_SA_DQS_DP<3>")
	)
	(segment
		(start 306.732686 -229.64013)
		(end 306.9209 -229.451916)
		(width 0.16002)
		(layer "In4.Cu")
		(net "M_D_CPU0_SA_DQS_DP<3>")
	)
	(segment
		(start 308.434994 -229.693216)
		(end 309.17388 -229.693216)
		(width 0.16002)
		(layer "In4.Cu")
		(net "M_D_CPU0_SA_DQS_DP<3>")
	)
	(segment
		(start 326.63257 -241.56924)
		(end 326.640952 -241.574066)
		(width 0.09525)
		(layer "In4.Cu")
		(net "M_D_CPU0_SA_DQS_DP<3>")
	)
	(segment
		(start 298.173648 -228.408738)
		(end 298.589954 -228.408738)
		(width 0.16002)
		(layer "In4.Cu")
		(net "M_D_CPU0_SA_DQS_DP<3>")
	)
	(segment
		(start 313.294776 -233.813858)
		(end 313.668664 -234.187746)
		(width 0.16002)
		(layer "In4.Cu")
		(net "M_D_CPU0_SA_DQS_DP<3>")
	)
	(segment
		(start 301.911512 -229.249732)
		(end 303.51476 -229.249732)
		(width 0.16002)
		(layer "In4.Cu")
		(net "M_D_CPU0_SA_DQS_DP<3>")
	)
	(segment
		(start 297.016932 -229.328218)
		(end 297.254168 -229.328218)
		(width 0.16002)
		(layer "In4.Cu")
		(net "M_D_CPU0_SA_DQS_DP<3>")
	)
	(segment
		(start 305.483768 -229.277672)
		(end 305.846226 -229.64013)
		(width 0.16002)
		(layer "In4.Cu")
		(net "M_D_CPU0_SA_DQS_DP<3>")
	)
	(segment
		(start 300.721776 -228.059996)
		(end 301.911512 -229.249732)
		(width 0.16002)
		(layer "In4.Cu")
		(net "M_D_CPU0_SA_DQS_DP<3>")
	)
	(segment
		(start 313.668664 -234.187746)
		(end 313.668918 -234.71505)
		(width 0.16002)
		(layer "In4.Cu")
		(net "M_D_CPU0_SA_DQS_DP<3>")
	)
	(segment
		(start 327.572624 -241.56924)
		(end 327.581006 -241.574066)
		(width 0.09525)
		(layer "In4.Cu")
		(net "M_D_CPU0_SA_DQS_DP<3>")
	)
	(segment
		(start 310.909208 -232.64876)
		(end 311.186068 -232.64876)
		(width 0.16002)
		(layer "In4.Cu")
		(net "M_D_CPU0_SA_DQS_DP<3>")
	)
	(segment
		(start 311.394348 -232.44048)
		(end 311.921144 -232.440226)
		(width 0.16002)
		(layer "In4.Cu")
		(net "M_D_CPU0_SA_DQS_DP<3>")
	)
	(segment
		(start 312.295032 -232.814114)
		(end 312.295286 -233.341418)
		(width 0.16002)
		(layer "In4.Cu")
		(net "M_D_CPU0_SA_DQS_DP<3>")
	)
	(segment
		(start 333.581248 -241.574066)
		(end 333.58963 -241.56924)
		(width 0.09525)
		(layer "In4.Cu")
		(net "M_D_CPU0_SA_DQS_DP<3>")
	)
	(segment
		(start 335.092548 -241.56924)
		(end 335.10093 -241.574066)
		(width 0.09525)
		(layer "In4.Cu")
		(net "M_D_CPU0_SA_DQS_DP<3>")
	)
	(segment
		(start 310.9214 -231.440482)
		(end 310.921654 -231.967786)
		(width 0.16002)
		(layer "In4.Cu")
		(net "M_D_CPU0_SA_DQS_DP<3>")
	)
	(segment
		(start 313.460638 -235.20019)
		(end 318.6176 -240.357152)
		(width 0.16002)
		(layer "In4.Cu")
		(net "M_D_CPU0_SA_DQS_DP<3>")
	)
	(segment
		(start 310.921654 -231.967786)
		(end 310.713374 -232.176066)
		(width 0.16002)
		(layer "In4.Cu")
		(net "M_D_CPU0_SA_DQS_DP<3>")
	)
	(segment
		(start 309.339742 -231.079294)
		(end 309.535576 -231.275128)
		(width 0.16002)
		(layer "In4.Cu")
		(net "M_D_CPU0_SA_DQS_DP<3>")
	)
	(segment
		(start 308.193694 -229.451916)
		(end 308.434994 -229.693216)
		(width 0.16002)
		(layer "In4.Cu")
		(net "M_D_CPU0_SA_DQS_DP<3>")
	)
	(segment
		(start 310.713374 -232.176066)
		(end 310.713374 -232.452926)
		(width 0.16002)
		(layer "In4.Cu")
		(net "M_D_CPU0_SA_DQS_DP<3>")
	)
	(segment
		(start 303.905158 -229.64013)
		(end 304.377598 -229.64013)
		(width 0.16002)
		(layer "In4.Cu")
		(net "M_D_CPU0_SA_DQS_DP<3>")
	)
	(segment
		(start 310.020716 -231.066848)
		(end 310.547512 -231.066594)
		(width 0.16002)
		(layer "In4.Cu")
		(net "M_D_CPU0_SA_DQS_DP<3>")
	)
	(segment
		(start 324.727824 -240.903252)
		(end 325.167498 -240.903252)
		(width 0.09525)
		(layer "In4.Cu")
		(net "M_D_CPU0_SA_DQS_DP<3>")
	)
	(segment
		(start 331.332586 -241.56924)
		(end 331.340968 -241.574066)
		(width 0.09525)
		(layer "In4.Cu")
		(net "M_D_CPU0_SA_DQS_DP<3>")
	)
	(segment
		(start 297.254168 -229.328218)
		(end 298.173648 -228.408738)
		(width 0.16002)
		(layer "In4.Cu")
		(net "M_D_CPU0_SA_DQS_DP<3>")
	)
	(segment
		(start 304.377598 -229.64013)
		(end 304.740056 -229.277672)
		(width 0.16002)
		(layer "In4.Cu")
		(net "M_D_CPU0_SA_DQS_DP<3>")
	)
	(segment
		(start 312.295286 -233.341418)
		(end 312.087006 -233.549698)
		(width 0.16002)
		(layer "In4.Cu")
		(net "M_D_CPU0_SA_DQS_DP<3>")
	)
	(segment
		(start 338.786216 -241.53622)
		(end 338.887054 -241.50955)
		(width 0.09525)
		(layer "In4.Cu")
		(net "M_D_CPU0_SA_DQS_DP<3>")
	)
	(segment
		(start 329.821286 -241.574066)
		(end 329.829668 -241.56924)
		(width 0.09525)
		(layer "In4.Cu")
		(net "M_D_CPU0_SA_DQS_DP<3>")
	)
	(segment
		(start 323.919596 -240.357152)
		(end 323.978778 -240.416334)
		(width 0.09525)
		(layer "In4.Cu")
		(net "M_D_CPU0_SA_DQS_DP<3>")
	)
	(segment
		(start 312.087006 -233.549698)
		(end 312.087006 -233.826558)
		(width 0.16002)
		(layer "In4.Cu")
		(net "M_D_CPU0_SA_DQS_DP<3>")
	)
	(segment
		(start 336.032602 -241.56924)
		(end 336.040984 -241.574066)
		(width 0.09525)
		(layer "In4.Cu")
		(net "M_D_CPU0_SA_DQS_DP<3>")
	)
	(segment
		(start 307.820822 -228.919532)
		(end 308.193694 -229.292404)
		(width 0.16002)
		(layer "In4.Cu")
		(net "M_D_CPU0_SA_DQS_DP<3>")
	)
	(segment
		(start 291.394896 -228.059996)
		(end 293.02456 -228.059996)
		(width 0.16002)
		(layer "In4.Cu")
		(net "M_D_CPU0_SA_DQS_DP<3>")
	)
	(segment
		(start 290.6014 -228.408738)
		(end 291.046154 -228.408738)
		(width 0.16002)
		(layer "In4.Cu")
		(net "M_D_CPU0_SA_DQS_DP<3>")
	)
	(segment
		(start 304.740056 -229.277672)
		(end 305.483768 -229.277672)
		(width 0.16002)
		(layer "In4.Cu")
		(net "M_D_CPU0_SA_DQS_DP<3>")
	)
	(segment
		(start 338.887054 -241.50955)
		(end 339.040978 -241.24412)
		(width 0.09525)
		(layer "In4.Cu")
		(net "M_D_CPU0_SA_DQS_DP<3>")
	)
	(segment
		(start 312.28284 -234.022392)
		(end 312.5597 -234.022392)
		(width 0.16002)
		(layer "In4.Cu")
		(net "M_D_CPU0_SA_DQS_DP<3>")
	)
	(segment
		(start 310.547512 -231.066594)
		(end 310.9214 -231.440482)
		(width 0.16002)
		(layer "In4.Cu")
		(net "M_D_CPU0_SA_DQS_DP<3>")
	)
	(arc
		(start 335.469738 -241.56924)
		(mid 335.75117 -241.493485)
		(end 336.032602 -241.56924)
		(width 0.09525)
		(layer "In4.Cu")
		(net "M_D_CPU0_SA_DQS_DP<3>")
	)
	(arc
		(start 326.351138 -241.493548)
		(mid 326.496846 -241.512816)
		(end 326.63257 -241.56924)
		(width 0.09525)
		(layer "In4.Cu")
		(net "M_D_CPU0_SA_DQS_DP<3>")
	)
	(arc
		(start 327.581006 -241.574066)
		(mid 327.766038 -241.61998)
		(end 327.949814 -241.56924)
		(width 0.09525)
		(layer "In4.Cu")
		(net "M_D_CPU0_SA_DQS_DP<3>")
	)
	(arc
		(start 338.766404 -241.528346)
		(mid 338.776347 -241.532189)
		(end 338.786216 -241.53622)
		(width 0.09525)
		(layer "In4.Cu")
		(net "M_D_CPU0_SA_DQS_DP<3>")
	)
	(arc
		(start 332.27264 -241.56924)
		(mid 332.461108 -241.619917)
		(end 332.649576 -241.56924)
		(width 0.09525)
		(layer "In4.Cu")
		(net "M_D_CPU0_SA_DQS_DP<3>")
	)
	(arc
		(start 327.00976 -241.56924)
		(mid 327.291192 -241.493485)
		(end 327.572624 -241.56924)
		(width 0.09525)
		(layer "In4.Cu")
		(net "M_D_CPU0_SA_DQS_DP<3>")
	)
	(arc
		(start 330.769722 -241.56924)
		(mid 331.051154 -241.493485)
		(end 331.332586 -241.56924)
		(width 0.09525)
		(layer "In4.Cu")
		(net "M_D_CPU0_SA_DQS_DP<3>")
	)
	(arc
		(start 338.289646 -241.56924)
		(mid 338.523441 -241.495373)
		(end 338.766404 -241.528346)
		(width 0.09525)
		(layer "In4.Cu")
		(net "M_D_CPU0_SA_DQS_DP<3>")
	)
	(arc
		(start 328.889614 -241.56924)
		(mid 329.171046 -241.493485)
		(end 329.452478 -241.56924)
		(width 0.09525)
		(layer "In4.Cu")
		(net "M_D_CPU0_SA_DQS_DP<3>")
	)
	(arc
		(start 335.10093 -241.574066)
		(mid 335.285962 -241.61998)
		(end 335.469738 -241.56924)
		(width 0.09525)
		(layer "In4.Cu")
		(net "M_D_CPU0_SA_DQS_DP<3>")
	)
	(arc
		(start 337.349592 -241.56924)
		(mid 337.631024 -241.493485)
		(end 337.912456 -241.56924)
		(width 0.09525)
		(layer "In4.Cu")
		(net "M_D_CPU0_SA_DQS_DP<3>")
	)
	(arc
		(start 334.152494 -241.56924)
		(mid 334.336269 -241.620012)
		(end 334.521302 -241.574066)
		(width 0.09525)
		(layer "In4.Cu")
		(net "M_D_CPU0_SA_DQS_DP<3>")
	)
	(arc
		(start 334.529684 -241.56924)
		(mid 334.811116 -241.493485)
		(end 335.092548 -241.56924)
		(width 0.09525)
		(layer "In4.Cu")
		(net "M_D_CPU0_SA_DQS_DP<3>")
	)
	(arc
		(start 327.949814 -241.56924)
		(mid 328.231246 -241.493485)
		(end 328.512678 -241.56924)
		(width 0.09525)
		(layer "In4.Cu")
		(net "M_D_CPU0_SA_DQS_DP<3>")
	)
	(arc
		(start 329.829668 -241.56924)
		(mid 330.1111 -241.493485)
		(end 330.392532 -241.56924)
		(width 0.09525)
		(layer "In4.Cu")
		(net "M_D_CPU0_SA_DQS_DP<3>")
	)
	(arc
		(start 336.040984 -241.574066)
		(mid 336.226016 -241.61998)
		(end 336.409792 -241.56924)
		(width 0.09525)
		(layer "In4.Cu")
		(net "M_D_CPU0_SA_DQS_DP<3>")
	)
	(arc
		(start 331.709776 -241.56924)
		(mid 331.991208 -241.493485)
		(end 332.27264 -241.56924)
		(width 0.09525)
		(layer "In4.Cu")
		(net "M_D_CPU0_SA_DQS_DP<3>")
	)
	(arc
		(start 332.649576 -241.56924)
		(mid 332.931008 -241.493485)
		(end 333.21244 -241.56924)
		(width 0.09525)
		(layer "In4.Cu")
		(net "M_D_CPU0_SA_DQS_DP<3>")
	)
	(arc
		(start 333.58963 -241.56924)
		(mid 333.871062 -241.493485)
		(end 334.152494 -241.56924)
		(width 0.09525)
		(layer "In4.Cu")
		(net "M_D_CPU0_SA_DQS_DP<3>")
	)
	(arc
		(start 330.400914 -241.574066)
		(mid 330.585946 -241.61998)
		(end 330.769722 -241.56924)
		(width 0.09525)
		(layer "In4.Cu")
		(net "M_D_CPU0_SA_DQS_DP<3>")
	)
	(arc
		(start 333.21244 -241.56924)
		(mid 333.396215 -241.620012)
		(end 333.581248 -241.574066)
		(width 0.09525)
		(layer "In4.Cu")
		(net "M_D_CPU0_SA_DQS_DP<3>")
	)
	(arc
		(start 326.640952 -241.574066)
		(mid 326.825984 -241.61998)
		(end 327.00976 -241.56924)
		(width 0.09525)
		(layer "In4.Cu")
		(net "M_D_CPU0_SA_DQS_DP<3>")
	)
	(arc
		(start 329.452478 -241.56924)
		(mid 329.636253 -241.620012)
		(end 329.821286 -241.574066)
		(width 0.09525)
		(layer "In4.Cu")
		(net "M_D_CPU0_SA_DQS_DP<3>")
	)
	(arc
		(start 336.972656 -241.56924)
		(mid 337.161124 -241.619917)
		(end 337.349592 -241.56924)
		(width 0.09525)
		(layer "In4.Cu")
		(net "M_D_CPU0_SA_DQS_DP<3>")
	)
	(arc
		(start 331.340968 -241.574066)
		(mid 331.526 -241.61998)
		(end 331.709776 -241.56924)
		(width 0.09525)
		(layer "In4.Cu")
		(net "M_D_CPU0_SA_DQS_DP<3>")
	)
	(arc
		(start 337.912456 -241.56924)
		(mid 338.096231 -241.620012)
		(end 338.281264 -241.574066)
		(width 0.09525)
		(layer "In4.Cu")
		(net "M_D_CPU0_SA_DQS_DP<3>")
	)
	(arc
		(start 328.512678 -241.56924)
		(mid 328.701146 -241.619917)
		(end 328.889614 -241.56924)
		(width 0.09525)
		(layer "In4.Cu")
		(net "M_D_CPU0_SA_DQS_DP<3>")
	)
	(arc
		(start 336.409792 -241.56924)
		(mid 336.691224 -241.493485)
		(end 336.972656 -241.56924)
		(width 0.09525)
		(layer "In4.Cu")
		(net "M_D_CPU0_SA_DQS_DP<3>")
	)
	(segment
		(start 339.508084 -236.650022)
		(end 339.040978 -236.384084)
		(width 0.12954)
		(layer "F.Cu")
		(net "M_D_CPU0_SA_DQS_DP<2>")
	)
	(segment
		(start 324.714362 -235.526072)
		(end 325.069962 -235.526072)
		(width 0.09525)
		(layer "In4.Cu")
		(net "M_D_CPU0_SA_DQS_DP<2>")
	)
	(segment
		(start 290.6014 -219.058744)
		(end 291.046154 -219.058744)
		(width 0.16002)
		(layer "In4.Cu")
		(net "M_D_CPU0_SA_DQS_DP<2>")
	)
	(segment
		(start 323.978524 -234.792774)
		(end 324.190106 -234.792774)
		(width 0.09525)
		(layer "In4.Cu")
		(net "M_D_CPU0_SA_DQS_DP<2>")
	)
	(segment
		(start 313.274964 -224.826576)
		(end 313.802268 -224.82683)
		(width 0.16002)
		(layer "In4.Cu")
		(net "M_D_CPU0_SA_DQS_DP<2>")
	)
	(segment
		(start 314.587382 -226.612196)
		(end 315.137546 -227.16236)
		(width 0.16002)
		(layer "In4.Cu")
		(net "M_D_CPU0_SA_DQS_DP<2>")
	)
	(segment
		(start 293.866316 -219.559886)
		(end 296.598594 -219.559886)
		(width 0.16002)
		(layer "In4.Cu")
		(net "M_D_CPU0_SA_DQS_DP<2>")
	)
	(segment
		(start 308.035198 -220.31833)
		(end 309.576978 -221.86011)
		(width 0.16002)
		(layer "In4.Cu")
		(net "M_D_CPU0_SA_DQS_DP<2>")
	)
	(segment
		(start 302.640492 -219.74937)
		(end 303.209452 -220.31833)
		(width 0.16002)
		(layer "In4.Cu")
		(net "M_D_CPU0_SA_DQS_DP<2>")
	)
	(segment
		(start 293.016432 -218.710002)
		(end 293.866316 -219.559886)
		(width 0.16002)
		(layer "In4.Cu")
		(net "M_D_CPU0_SA_DQS_DP<2>")
	)
	(segment
		(start 315.137546 -227.789994)
		(end 322.081398 -234.733846)
		(width 0.16002)
		(layer "In4.Cu")
		(net "M_D_CPU0_SA_DQS_DP<2>")
	)
	(segment
		(start 338.887054 -236.649514)
		(end 339.040978 -236.384084)
		(width 0.09525)
		(layer "In4.Cu")
		(net "M_D_CPU0_SA_DQS_DP<2>")
	)
	(segment
		(start 311.055004 -222.079566)
		(end 311.428892 -222.453454)
		(width 0.16002)
		(layer "In4.Cu")
		(net "M_D_CPU0_SA_DQS_DP<2>")
	)
	(segment
		(start 287.169352 -219.559886)
		(end 289.054794 -219.559886)
		(width 0.16002)
		(layer "In4.Cu")
		(net "M_D_CPU0_SA_DQS_DP<2>")
	)
	(segment
		(start 311.212484 -223.864932)
		(end 311.489344 -223.864932)
		(width 0.16002)
		(layer "In4.Cu")
		(net "M_D_CPU0_SA_DQS_DP<2>")
	)
	(segment
		(start 315.137546 -227.16236)
		(end 315.137546 -227.789994)
		(width 0.16002)
		(layer "In4.Cu")
		(net "M_D_CPU0_SA_DQS_DP<2>")
	)
	(segment
		(start 289.458908 -219.964)
		(end 289.696144 -219.964)
		(width 0.16002)
		(layer "In4.Cu")
		(net "M_D_CPU0_SA_DQS_DP<2>")
	)
	(segment
		(start 301.761144 -219.74937)
		(end 302.640492 -219.74937)
		(width 0.16002)
		(layer "In4.Cu")
		(net "M_D_CPU0_SA_DQS_DP<2>")
	)
	(segment
		(start 284.736032 -219.435172)
		(end 285.009844 -219.708984)
		(width 0.16002)
		(layer "In4.Cu")
		(net "M_D_CPU0_SA_DQS_DP<2>")
	)
	(segment
		(start 312.390282 -225.04273)
		(end 312.586116 -225.238564)
		(width 0.16002)
		(layer "In4.Cu")
		(net "M_D_CPU0_SA_DQS_DP<2>")
	)
	(segment
		(start 324.393052 -235.204762)
		(end 324.714362 -235.526072)
		(width 0.09525)
		(layer "In4.Cu")
		(net "M_D_CPU0_SA_DQS_DP<2>")
	)
	(segment
		(start 313.763914 -226.139502)
		(end 313.763914 -226.416362)
		(width 0.16002)
		(layer "In4.Cu")
		(net "M_D_CPU0_SA_DQS_DP<2>")
	)
	(segment
		(start 303.209452 -220.31833)
		(end 308.035198 -220.31833)
		(width 0.16002)
		(layer "In4.Cu")
		(net "M_D_CPU0_SA_DQS_DP<2>")
	)
	(segment
		(start 309.838852 -222.4913)
		(end 310.115712 -222.4913)
		(width 0.16002)
		(layer "In4.Cu")
		(net "M_D_CPU0_SA_DQS_DP<2>")
	)
	(segment
		(start 311.489344 -223.864932)
		(end 311.901332 -223.452944)
		(width 0.16002)
		(layer "In4.Cu")
		(net "M_D_CPU0_SA_DQS_DP<2>")
	)
	(segment
		(start 287.020254 -219.708984)
		(end 287.169352 -219.559886)
		(width 0.16002)
		(layer "In4.Cu")
		(net "M_D_CPU0_SA_DQS_DP<2>")
	)
	(segment
		(start 312.80227 -224.353882)
		(end 312.390282 -224.76587)
		(width 0.16002)
		(layer "In4.Cu")
		(net "M_D_CPU0_SA_DQS_DP<2>")
	)
	(segment
		(start 338.281264 -236.71403)
		(end 338.289646 -236.709204)
		(width 0.09525)
		(layer "In4.Cu")
		(net "M_D_CPU0_SA_DQS_DP<2>")
	)
	(segment
		(start 331.332586 -236.709204)
		(end 331.340968 -236.71403)
		(width 0.09525)
		(layer "In4.Cu")
		(net "M_D_CPU0_SA_DQS_DP<2>")
	)
	(segment
		(start 324.393052 -234.99572)
		(end 324.393052 -235.204762)
		(width 0.09525)
		(layer "In4.Cu")
		(net "M_D_CPU0_SA_DQS_DP<2>")
	)
	(segment
		(start 314.176156 -225.200718)
		(end 314.175902 -225.727514)
		(width 0.16002)
		(layer "In4.Cu")
		(net "M_D_CPU0_SA_DQS_DP<2>")
	)
	(segment
		(start 314.175902 -225.727514)
		(end 313.763914 -226.139502)
		(width 0.16002)
		(layer "In4.Cu")
		(net "M_D_CPU0_SA_DQS_DP<2>")
	)
	(segment
		(start 313.763914 -226.416362)
		(end 313.959748 -226.612196)
		(width 0.16002)
		(layer "In4.Cu")
		(net "M_D_CPU0_SA_DQS_DP<2>")
	)
	(segment
		(start 311.01665 -223.669098)
		(end 311.212484 -223.864932)
		(width 0.16002)
		(layer "In4.Cu")
		(net "M_D_CPU0_SA_DQS_DP<2>")
	)
	(segment
		(start 291.394896 -218.710002)
		(end 293.016432 -218.710002)
		(width 0.16002)
		(layer "In4.Cu")
		(net "M_D_CPU0_SA_DQS_DP<2>")
	)
	(segment
		(start 297.254168 -219.978224)
		(end 298.173648 -219.058744)
		(width 0.16002)
		(layer "In4.Cu")
		(net "M_D_CPU0_SA_DQS_DP<2>")
	)
	(segment
		(start 298.589954 -219.058744)
		(end 298.938696 -218.710002)
		(width 0.16002)
		(layer "In4.Cu")
		(net "M_D_CPU0_SA_DQS_DP<2>")
	)
	(segment
		(start 327.573386 -236.709204)
		(end 327.59015 -236.718856)
		(width 0.09525)
		(layer "In4.Cu")
		(net "M_D_CPU0_SA_DQS_DP<2>")
	)
	(segment
		(start 323.919596 -234.733846)
		(end 323.978524 -234.792774)
		(width 0.09525)
		(layer "In4.Cu")
		(net "M_D_CPU0_SA_DQS_DP<2>")
	)
	(segment
		(start 300.721776 -218.710002)
		(end 301.761144 -219.74937)
		(width 0.16002)
		(layer "In4.Cu")
		(net "M_D_CPU0_SA_DQS_DP<2>")
	)
	(segment
		(start 326.99325 -236.720126)
		(end 327.012046 -236.709204)
		(width 0.09525)
		(layer "In4.Cu")
		(net "M_D_CPU0_SA_DQS_DP<2>")
	)
	(segment
		(start 310.115712 -222.4913)
		(end 310.5277 -222.079312)
		(width 0.16002)
		(layer "In4.Cu")
		(net "M_D_CPU0_SA_DQS_DP<2>")
	)
	(segment
		(start 311.428892 -222.453454)
		(end 311.428638 -222.98025)
		(width 0.16002)
		(layer "In4.Cu")
		(net "M_D_CPU0_SA_DQS_DP<2>")
	)
	(segment
		(start 336.032602 -236.709204)
		(end 336.040984 -236.71403)
		(width 0.09525)
		(layer "In4.Cu")
		(net "M_D_CPU0_SA_DQS_DP<2>")
	)
	(segment
		(start 312.586116 -225.238564)
		(end 312.862976 -225.238564)
		(width 0.16002)
		(layer "In4.Cu")
		(net "M_D_CPU0_SA_DQS_DP<2>")
	)
	(segment
		(start 309.576978 -222.229426)
		(end 309.838852 -222.4913)
		(width 0.16002)
		(layer "In4.Cu")
		(net "M_D_CPU0_SA_DQS_DP<2>")
	)
	(segment
		(start 325.069962 -235.526072)
		(end 326.17664 -236.63275)
		(width 0.09525)
		(layer "In4.Cu")
		(net "M_D_CPU0_SA_DQS_DP<2>")
	)
	(segment
		(start 297.016932 -219.978224)
		(end 297.254168 -219.978224)
		(width 0.16002)
		(layer "In4.Cu")
		(net "M_D_CPU0_SA_DQS_DP<2>")
	)
	(segment
		(start 323.895974 -234.733846)
		(end 323.919596 -234.733846)
		(width 0.09525)
		(layer "In4.Cu")
		(net "M_D_CPU0_SA_DQS_DP<2>")
	)
	(segment
		(start 330.392532 -236.709204)
		(end 330.400914 -236.71403)
		(width 0.09525)
		(layer "In4.Cu")
		(net "M_D_CPU0_SA_DQS_DP<2>")
	)
	(segment
		(start 310.5277 -222.079312)
		(end 311.055004 -222.079566)
		(width 0.16002)
		(layer "In4.Cu")
		(net "M_D_CPU0_SA_DQS_DP<2>")
	)
	(segment
		(start 311.428638 -222.98025)
		(end 311.01665 -223.392238)
		(width 0.16002)
		(layer "In4.Cu")
		(net "M_D_CPU0_SA_DQS_DP<2>")
	)
	(segment
		(start 312.862976 -225.238564)
		(end 313.274964 -224.826576)
		(width 0.16002)
		(layer "In4.Cu")
		(net "M_D_CPU0_SA_DQS_DP<2>")
	)
	(segment
		(start 326.17664 -236.63275)
		(end 326.3519 -236.63275)
		(width 0.09525)
		(layer "In4.Cu")
		(net "M_D_CPU0_SA_DQS_DP<2>")
	)
	(segment
		(start 312.802524 -223.827086)
		(end 312.80227 -224.353882)
		(width 0.16002)
		(layer "In4.Cu")
		(net "M_D_CPU0_SA_DQS_DP<2>")
	)
	(segment
		(start 311.901332 -223.452944)
		(end 312.428636 -223.453198)
		(width 0.16002)
		(layer "In4.Cu")
		(net "M_D_CPU0_SA_DQS_DP<2>")
	)
	(segment
		(start 309.576978 -221.86011)
		(end 309.576978 -222.229426)
		(width 0.16002)
		(layer "In4.Cu")
		(net "M_D_CPU0_SA_DQS_DP<2>")
	)
	(segment
		(start 312.428636 -223.453198)
		(end 312.802524 -223.827086)
		(width 0.16002)
		(layer "In4.Cu")
		(net "M_D_CPU0_SA_DQS_DP<2>")
	)
	(segment
		(start 298.173648 -219.058744)
		(end 298.589954 -219.058744)
		(width 0.16002)
		(layer "In4.Cu")
		(net "M_D_CPU0_SA_DQS_DP<2>")
	)
	(segment
		(start 334.521302 -236.71403)
		(end 334.529684 -236.709204)
		(width 0.09525)
		(layer "In4.Cu")
		(net "M_D_CPU0_SA_DQS_DP<2>")
	)
	(segment
		(start 327.547986 -236.694472)
		(end 327.573386 -236.709204)
		(width 0.09525)
		(layer "In4.Cu")
		(net "M_D_CPU0_SA_DQS_DP<2>")
	)
	(segment
		(start 285.009844 -219.708984)
		(end 287.020254 -219.708984)
		(width 0.16002)
		(layer "In4.Cu")
		(net "M_D_CPU0_SA_DQS_DP<2>")
	)
	(segment
		(start 289.696144 -219.964)
		(end 290.6014 -219.058744)
		(width 0.16002)
		(layer "In4.Cu")
		(net "M_D_CPU0_SA_DQS_DP<2>")
	)
	(segment
		(start 291.046154 -219.058744)
		(end 291.394896 -218.710002)
		(width 0.16002)
		(layer "In4.Cu")
		(net "M_D_CPU0_SA_DQS_DP<2>")
	)
	(segment
		(start 322.081398 -234.733846)
		(end 323.895974 -234.733846)
		(width 0.16002)
		(layer "In4.Cu")
		(net "M_D_CPU0_SA_DQS_DP<2>")
	)
	(segment
		(start 313.959748 -226.612196)
		(end 314.587382 -226.612196)
		(width 0.16002)
		(layer "In4.Cu")
		(net "M_D_CPU0_SA_DQS_DP<2>")
	)
	(segment
		(start 296.598594 -219.559886)
		(end 297.016932 -219.978224)
		(width 0.16002)
		(layer "In4.Cu")
		(net "M_D_CPU0_SA_DQS_DP<2>")
	)
	(segment
		(start 313.802268 -224.82683)
		(end 314.176156 -225.200718)
		(width 0.16002)
		(layer "In4.Cu")
		(net "M_D_CPU0_SA_DQS_DP<2>")
	)
	(segment
		(start 333.581248 -236.71403)
		(end 333.58963 -236.709204)
		(width 0.09525)
		(layer "In4.Cu")
		(net "M_D_CPU0_SA_DQS_DP<2>")
	)
	(segment
		(start 312.390282 -224.76587)
		(end 312.390282 -225.04273)
		(width 0.16002)
		(layer "In4.Cu")
		(net "M_D_CPU0_SA_DQS_DP<2>")
	)
	(segment
		(start 329.821286 -236.71403)
		(end 329.829668 -236.709204)
		(width 0.09525)
		(layer "In4.Cu")
		(net "M_D_CPU0_SA_DQS_DP<2>")
	)
	(segment
		(start 324.190106 -234.792774)
		(end 324.393052 -234.99572)
		(width 0.09525)
		(layer "In4.Cu")
		(net "M_D_CPU0_SA_DQS_DP<2>")
	)
	(segment
		(start 289.054794 -219.559886)
		(end 289.458908 -219.964)
		(width 0.16002)
		(layer "In4.Cu")
		(net "M_D_CPU0_SA_DQS_DP<2>")
	)
	(segment
		(start 338.786216 -236.676184)
		(end 338.887054 -236.649514)
		(width 0.09525)
		(layer "In4.Cu")
		(net "M_D_CPU0_SA_DQS_DP<2>")
	)
	(segment
		(start 298.938696 -218.710002)
		(end 300.721776 -218.710002)
		(width 0.16002)
		(layer "In4.Cu")
		(net "M_D_CPU0_SA_DQS_DP<2>")
	)
	(segment
		(start 335.092548 -236.709204)
		(end 335.10093 -236.71403)
		(width 0.09525)
		(layer "In4.Cu")
		(net "M_D_CPU0_SA_DQS_DP<2>")
	)
	(segment
		(start 311.01665 -223.392238)
		(end 311.01665 -223.669098)
		(width 0.16002)
		(layer "In4.Cu")
		(net "M_D_CPU0_SA_DQS_DP<2>")
	)
	(arc
		(start 328.512678 -236.709204)
		(mid 328.701146 -236.759881)
		(end 328.889614 -236.709204)
		(width 0.09525)
		(layer "In4.Cu")
		(net "M_D_CPU0_SA_DQS_DP<2>")
	)
	(arc
		(start 327.59015 -236.718856)
		(mid 327.771207 -236.759838)
		(end 327.949814 -236.709204)
		(width 0.09525)
		(layer "In4.Cu")
		(net "M_D_CPU0_SA_DQS_DP<2>")
	)
	(arc
		(start 336.409792 -236.709204)
		(mid 336.691224 -236.633449)
		(end 336.972656 -236.709204)
		(width 0.09525)
		(layer "In4.Cu")
		(net "M_D_CPU0_SA_DQS_DP<2>")
	)
	(arc
		(start 326.63384 -236.709204)
		(mid 326.812155 -236.760346)
		(end 326.99325 -236.720126)
		(width 0.09525)
		(layer "In4.Cu")
		(net "M_D_CPU0_SA_DQS_DP<2>")
	)
	(arc
		(start 328.889614 -236.709204)
		(mid 329.171046 -236.633449)
		(end 329.452478 -236.709204)
		(width 0.09525)
		(layer "In4.Cu")
		(net "M_D_CPU0_SA_DQS_DP<2>")
	)
	(arc
		(start 327.949814 -236.709204)
		(mid 328.231246 -236.633449)
		(end 328.512678 -236.709204)
		(width 0.09525)
		(layer "In4.Cu")
		(net "M_D_CPU0_SA_DQS_DP<2>")
	)
	(arc
		(start 333.21244 -236.709204)
		(mid 333.396215 -236.759976)
		(end 333.581248 -236.71403)
		(width 0.09525)
		(layer "In4.Cu")
		(net "M_D_CPU0_SA_DQS_DP<2>")
	)
	(arc
		(start 336.040984 -236.71403)
		(mid 336.226016 -236.759944)
		(end 336.409792 -236.709204)
		(width 0.09525)
		(layer "In4.Cu")
		(net "M_D_CPU0_SA_DQS_DP<2>")
	)
	(arc
		(start 334.529684 -236.709204)
		(mid 334.811116 -236.633449)
		(end 335.092548 -236.709204)
		(width 0.09525)
		(layer "In4.Cu")
		(net "M_D_CPU0_SA_DQS_DP<2>")
	)
	(arc
		(start 335.10093 -236.71403)
		(mid 335.285962 -236.759944)
		(end 335.469738 -236.709204)
		(width 0.09525)
		(layer "In4.Cu")
		(net "M_D_CPU0_SA_DQS_DP<2>")
	)
	(arc
		(start 327.012046 -236.709204)
		(mid 327.278133 -236.633659)
		(end 327.547986 -236.694472)
		(width 0.09525)
		(layer "In4.Cu")
		(net "M_D_CPU0_SA_DQS_DP<2>")
	)
	(arc
		(start 329.452478 -236.709204)
		(mid 329.636253 -236.759976)
		(end 329.821286 -236.71403)
		(width 0.09525)
		(layer "In4.Cu")
		(net "M_D_CPU0_SA_DQS_DP<2>")
	)
	(arc
		(start 326.3519 -236.63275)
		(mid 326.497943 -236.652286)
		(end 326.63384 -236.709204)
		(width 0.09525)
		(layer "In4.Cu")
		(net "M_D_CPU0_SA_DQS_DP<2>")
	)
	(arc
		(start 335.469738 -236.709204)
		(mid 335.75117 -236.633449)
		(end 336.032602 -236.709204)
		(width 0.09525)
		(layer "In4.Cu")
		(net "M_D_CPU0_SA_DQS_DP<2>")
	)
	(arc
		(start 334.152494 -236.709204)
		(mid 334.336269 -236.759976)
		(end 334.521302 -236.71403)
		(width 0.09525)
		(layer "In4.Cu")
		(net "M_D_CPU0_SA_DQS_DP<2>")
	)
	(arc
		(start 332.649576 -236.709204)
		(mid 332.931008 -236.633449)
		(end 333.21244 -236.709204)
		(width 0.09525)
		(layer "In4.Cu")
		(net "M_D_CPU0_SA_DQS_DP<2>")
	)
	(arc
		(start 332.27264 -236.709204)
		(mid 332.461108 -236.759881)
		(end 332.649576 -236.709204)
		(width 0.09525)
		(layer "In4.Cu")
		(net "M_D_CPU0_SA_DQS_DP<2>")
	)
	(arc
		(start 329.829668 -236.709204)
		(mid 330.1111 -236.633449)
		(end 330.392532 -236.709204)
		(width 0.09525)
		(layer "In4.Cu")
		(net "M_D_CPU0_SA_DQS_DP<2>")
	)
	(arc
		(start 337.349592 -236.709204)
		(mid 337.631024 -236.633449)
		(end 337.912456 -236.709204)
		(width 0.09525)
		(layer "In4.Cu")
		(net "M_D_CPU0_SA_DQS_DP<2>")
	)
	(arc
		(start 336.972656 -236.709204)
		(mid 337.161124 -236.759881)
		(end 337.349592 -236.709204)
		(width 0.09525)
		(layer "In4.Cu")
		(net "M_D_CPU0_SA_DQS_DP<2>")
	)
	(arc
		(start 330.769722 -236.709204)
		(mid 331.051154 -236.633449)
		(end 331.332586 -236.709204)
		(width 0.09525)
		(layer "In4.Cu")
		(net "M_D_CPU0_SA_DQS_DP<2>")
	)
	(arc
		(start 337.912456 -236.709204)
		(mid 338.096231 -236.759976)
		(end 338.281264 -236.71403)
		(width 0.09525)
		(layer "In4.Cu")
		(net "M_D_CPU0_SA_DQS_DP<2>")
	)
	(arc
		(start 338.289646 -236.709204)
		(mid 338.523441 -236.635337)
		(end 338.766404 -236.66831)
		(width 0.09525)
		(layer "In4.Cu")
		(net "M_D_CPU0_SA_DQS_DP<2>")
	)
	(arc
		(start 333.58963 -236.709204)
		(mid 333.871062 -236.633449)
		(end 334.152494 -236.709204)
		(width 0.09525)
		(layer "In4.Cu")
		(net "M_D_CPU0_SA_DQS_DP<2>")
	)
	(arc
		(start 338.766404 -236.66831)
		(mid 338.776347 -236.672153)
		(end 338.786216 -236.676184)
		(width 0.09525)
		(layer "In4.Cu")
		(net "M_D_CPU0_SA_DQS_DP<2>")
	)
	(arc
		(start 330.400914 -236.71403)
		(mid 330.585946 -236.759944)
		(end 330.769722 -236.709204)
		(width 0.09525)
		(layer "In4.Cu")
		(net "M_D_CPU0_SA_DQS_DP<2>")
	)
	(arc
		(start 331.340968 -236.71403)
		(mid 331.526 -236.759944)
		(end 331.709776 -236.709204)
		(width 0.09525)
		(layer "In4.Cu")
		(net "M_D_CPU0_SA_DQS_DP<2>")
	)
	(arc
		(start 331.709776 -236.709204)
		(mid 331.991208 -236.633449)
		(end 332.27264 -236.709204)
		(width 0.09525)
		(layer "In4.Cu")
		(net "M_D_CPU0_SA_DQS_DP<2>")
	)
	(segment
		(start 339.508084 -231.789986)
		(end 339.040978 -231.524048)
		(width 0.12954)
		(layer "F.Cu")
		(net "M_D_CPU0_SA_DQS_DP<1>")
	)
	(segment
		(start 318.105028 -220.150436)
		(end 318.478662 -220.52407)
		(width 0.16002)
		(layer "In4.Cu")
		(net "M_D_CPU0_SA_DQS_DP<1>")
	)
	(segment
		(start 318.371982 -221.158054)
		(end 318.371982 -221.434914)
		(width 0.16002)
		(layer "In4.Cu")
		(net "M_D_CPU0_SA_DQS_DP<1>")
	)
	(segment
		(start 310.602884 -213.388956)
		(end 310.709564 -213.282276)
		(width 0.16002)
		(layer "In4.Cu")
		(net "M_D_CPU0_SA_DQS_DP<1>")
	)
	(segment
		(start 318.951356 -221.524068)
		(end 319.47866 -221.524068)
		(width 0.16002)
		(layer "In4.Cu")
		(net "M_D_CPU0_SA_DQS_DP<1>")
	)
	(segment
		(start 301.683928 -210.34375)
		(end 302.426116 -210.34375)
		(width 0.16002)
		(layer "In4.Cu")
		(net "M_D_CPU0_SA_DQS_DP<1>")
	)
	(segment
		(start 297.349418 -210.55457)
		(end 298.179998 -209.72399)
		(width 0.16002)
		(layer "In4.Cu")
		(net "M_D_CPU0_SA_DQS_DP<1>")
	)
	(segment
		(start 287.188656 -210.209892)
		(end 289.033204 -210.209892)
		(width 0.16002)
		(layer "In4.Cu")
		(net "M_D_CPU0_SA_DQS_DP<1>")
	)
	(segment
		(start 311.699656 -214.762588)
		(end 311.976516 -214.762588)
		(width 0.16002)
		(layer "In4.Cu")
		(net "M_D_CPU0_SA_DQS_DP<1>")
	)
	(segment
		(start 298.596304 -209.72399)
		(end 298.960286 -209.360008)
		(width 0.16002)
		(layer "In4.Cu")
		(net "M_D_CPU0_SA_DQS_DP<1>")
	)
	(segment
		(start 312.984134 -215.556846)
		(end 312.877454 -215.663526)
		(width 0.16002)
		(layer "In4.Cu")
		(net "M_D_CPU0_SA_DQS_DP<1>")
	)
	(segment
		(start 289.77717 -210.55457)
		(end 290.60775 -209.72399)
		(width 0.16002)
		(layer "In4.Cu")
		(net "M_D_CPU0_SA_DQS_DP<1>")
	)
	(segment
		(start 311.610502 -213.65591)
		(end 311.610502 -214.183214)
		(width 0.16002)
		(layer "In4.Cu")
		(net "M_D_CPU0_SA_DQS_DP<1>")
	)
	(segment
		(start 317.10503 -219.677742)
		(end 316.99835 -219.784422)
		(width 0.16002)
		(layer "In4.Cu")
		(net "M_D_CPU0_SA_DQS_DP<1>")
	)
	(segment
		(start 315.731398 -218.30411)
		(end 315.624718 -218.41079)
		(width 0.16002)
		(layer "In4.Cu")
		(net "M_D_CPU0_SA_DQS_DP<1>")
	)
	(segment
		(start 324.39102 -229.040182)
		(end 324.799706 -229.449122)
		(width 0.09525)
		(layer "In4.Cu")
		(net "M_D_CPU0_SA_DQS_DP<1>")
	)
	(segment
		(start 300.700186 -209.360008)
		(end 301.683928 -210.34375)
		(width 0.16002)
		(layer "In4.Cu")
		(net "M_D_CPU0_SA_DQS_DP<1>")
	)
	(segment
		(start 311.610502 -214.183214)
		(end 311.503822 -214.289894)
		(width 0.16002)
		(layer "In4.Cu")
		(net "M_D_CPU0_SA_DQS_DP<1>")
	)
	(segment
		(start 312.6105 -214.655908)
		(end 312.984134 -215.029542)
		(width 0.16002)
		(layer "In4.Cu")
		(net "M_D_CPU0_SA_DQS_DP<1>")
	)
	(segment
		(start 314.357766 -216.403174)
		(end 314.357766 -216.930478)
		(width 0.16002)
		(layer "In4.Cu")
		(net "M_D_CPU0_SA_DQS_DP<1>")
	)
	(segment
		(start 333.581248 -231.853994)
		(end 333.58963 -231.849168)
		(width 0.09525)
		(layer "In4.Cu")
		(net "M_D_CPU0_SA_DQS_DP<1>")
	)
	(segment
		(start 312.984134 -215.029542)
		(end 312.984134 -215.556846)
		(width 0.16002)
		(layer "In4.Cu")
		(net "M_D_CPU0_SA_DQS_DP<1>")
	)
	(segment
		(start 326.892158 -230.489252)
		(end 326.892158 -231.187498)
		(width 0.09525)
		(layer "In4.Cu")
		(net "M_D_CPU0_SA_DQS_DP<1>")
	)
	(segment
		(start 334.521302 -231.853994)
		(end 334.529684 -231.849168)
		(width 0.09525)
		(layer "In4.Cu")
		(net "M_D_CPU0_SA_DQS_DP<1>")
	)
	(segment
		(start 318.478662 -221.051374)
		(end 318.371982 -221.158054)
		(width 0.16002)
		(layer "In4.Cu")
		(net "M_D_CPU0_SA_DQS_DP<1>")
	)
	(segment
		(start 302.426116 -210.34375)
		(end 303.050956 -210.96859)
		(width 0.16002)
		(layer "In4.Cu")
		(net "M_D_CPU0_SA_DQS_DP<1>")
	)
	(segment
		(start 317.194184 -220.257116)
		(end 317.471044 -220.257116)
		(width 0.16002)
		(layer "In4.Cu")
		(net "M_D_CPU0_SA_DQS_DP<1>")
	)
	(segment
		(start 315.357764 -217.403172)
		(end 315.731398 -217.776806)
		(width 0.16002)
		(layer "In4.Cu")
		(net "M_D_CPU0_SA_DQS_DP<1>")
	)
	(segment
		(start 327.572624 -231.849168)
		(end 327.581006 -231.853994)
		(width 0.09525)
		(layer "In4.Cu")
		(net "M_D_CPU0_SA_DQS_DP<1>")
	)
	(segment
		(start 289.377882 -210.55457)
		(end 289.77717 -210.55457)
		(width 0.16002)
		(layer "In4.Cu")
		(net "M_D_CPU0_SA_DQS_DP<1>")
	)
	(segment
		(start 314.357766 -216.930478)
		(end 314.251086 -217.037158)
		(width 0.16002)
		(layer "In4.Cu")
		(net "M_D_CPU0_SA_DQS_DP<1>")
	)
	(segment
		(start 318.567816 -221.630748)
		(end 318.844676 -221.630748)
		(width 0.16002)
		(layer "In4.Cu")
		(net "M_D_CPU0_SA_DQS_DP<1>")
	)
	(segment
		(start 296.577004 -210.209892)
		(end 296.921682 -210.55457)
		(width 0.16002)
		(layer "In4.Cu")
		(net "M_D_CPU0_SA_DQS_DP<1>")
	)
	(segment
		(start 285.009844 -210.35899)
		(end 287.039558 -210.35899)
		(width 0.16002)
		(layer "In4.Cu")
		(net "M_D_CPU0_SA_DQS_DP<1>")
	)
	(segment
		(start 335.092548 -231.849168)
		(end 335.10093 -231.853994)
		(width 0.09525)
		(layer "In4.Cu")
		(net "M_D_CPU0_SA_DQS_DP<1>")
	)
	(segment
		(start 318.844676 -221.630748)
		(end 318.951356 -221.524068)
		(width 0.16002)
		(layer "In4.Cu")
		(net "M_D_CPU0_SA_DQS_DP<1>")
	)
	(segment
		(start 314.83046 -217.403172)
		(end 315.357764 -217.403172)
		(width 0.16002)
		(layer "In4.Cu")
		(net "M_D_CPU0_SA_DQS_DP<1>")
	)
	(segment
		(start 284.736032 -210.085178)
		(end 285.009844 -210.35899)
		(width 0.16002)
		(layer "In4.Cu")
		(net "M_D_CPU0_SA_DQS_DP<1>")
	)
	(segment
		(start 331.332586 -231.849168)
		(end 331.340968 -231.853994)
		(width 0.09525)
		(layer "In4.Cu")
		(net "M_D_CPU0_SA_DQS_DP<1>")
	)
	(segment
		(start 319.852294 -221.897702)
		(end 319.852294 -222.425006)
		(width 0.16002)
		(layer "In4.Cu")
		(net "M_D_CPU0_SA_DQS_DP<1>")
	)
	(segment
		(start 326.098662 -230.148892)
		(end 326.551798 -230.148892)
		(width 0.09525)
		(layer "In4.Cu")
		(net "M_D_CPU0_SA_DQS_DP<1>")
	)
	(segment
		(start 336.032602 -231.849168)
		(end 336.040984 -231.853994)
		(width 0.09525)
		(layer "In4.Cu")
		(net "M_D_CPU0_SA_DQS_DP<1>")
	)
	(segment
		(start 315.820552 -218.883484)
		(end 316.097412 -218.883484)
		(width 0.16002)
		(layer "In4.Cu")
		(net "M_D_CPU0_SA_DQS_DP<1>")
	)
	(segment
		(start 311.503822 -214.289894)
		(end 311.503822 -214.566754)
		(width 0.16002)
		(layer "In4.Cu")
		(net "M_D_CPU0_SA_DQS_DP<1>")
	)
	(segment
		(start 321.616578 -224.67951)
		(end 321.616578 -226.182936)
		(width 0.16002)
		(layer "In4.Cu")
		(net "M_D_CPU0_SA_DQS_DP<1>")
	)
	(segment
		(start 330.392532 -231.849168)
		(end 330.400914 -231.853994)
		(width 0.09525)
		(layer "In4.Cu")
		(net "M_D_CPU0_SA_DQS_DP<1>")
	)
	(segment
		(start 314.251086 -217.314018)
		(end 314.44692 -217.509852)
		(width 0.16002)
		(layer "In4.Cu")
		(net "M_D_CPU0_SA_DQS_DP<1>")
	)
	(segment
		(start 319.745614 -222.531686)
		(end 319.745614 -222.808546)
		(width 0.16002)
		(layer "In4.Cu")
		(net "M_D_CPU0_SA_DQS_DP<1>")
	)
	(segment
		(start 291.052504 -209.72399)
		(end 291.416486 -209.360008)
		(width 0.16002)
		(layer "In4.Cu")
		(net "M_D_CPU0_SA_DQS_DP<1>")
	)
	(segment
		(start 291.416486 -209.360008)
		(end 293.149782 -209.360008)
		(width 0.16002)
		(layer "In4.Cu")
		(net "M_D_CPU0_SA_DQS_DP<1>")
	)
	(segment
		(start 338.887054 -231.789478)
		(end 339.040978 -231.524048)
		(width 0.09525)
		(layer "In4.Cu")
		(net "M_D_CPU0_SA_DQS_DP<1>")
	)
	(segment
		(start 316.99835 -219.784422)
		(end 316.99835 -220.061282)
		(width 0.16002)
		(layer "In4.Cu")
		(net "M_D_CPU0_SA_DQS_DP<1>")
	)
	(segment
		(start 314.251086 -217.037158)
		(end 314.251086 -217.314018)
		(width 0.16002)
		(layer "In4.Cu")
		(net "M_D_CPU0_SA_DQS_DP<1>")
	)
	(segment
		(start 312.877454 -215.663526)
		(end 312.877454 -215.940386)
		(width 0.16002)
		(layer "In4.Cu")
		(net "M_D_CPU0_SA_DQS_DP<1>")
	)
	(segment
		(start 319.745614 -222.808546)
		(end 321.616578 -224.67951)
		(width 0.16002)
		(layer "In4.Cu")
		(net "M_D_CPU0_SA_DQS_DP<1>")
	)
	(segment
		(start 317.471044 -220.257116)
		(end 317.577724 -220.150436)
		(width 0.16002)
		(layer "In4.Cu")
		(net "M_D_CPU0_SA_DQS_DP<1>")
	)
	(segment
		(start 290.60775 -209.72399)
		(end 291.052504 -209.72399)
		(width 0.16002)
		(layer "In4.Cu")
		(net "M_D_CPU0_SA_DQS_DP<1>")
	)
	(segment
		(start 311.236868 -213.282276)
		(end 311.610502 -213.65591)
		(width 0.16002)
		(layer "In4.Cu")
		(net "M_D_CPU0_SA_DQS_DP<1>")
	)
	(segment
		(start 329.821286 -231.853994)
		(end 329.829668 -231.849168)
		(width 0.09525)
		(layer "In4.Cu")
		(net "M_D_CPU0_SA_DQS_DP<1>")
	)
	(segment
		(start 311.976516 -214.762588)
		(end 312.083196 -214.655908)
		(width 0.16002)
		(layer "In4.Cu")
		(net "M_D_CPU0_SA_DQS_DP<1>")
	)
	(segment
		(start 338.786216 -231.816148)
		(end 338.887054 -231.789478)
		(width 0.09525)
		(layer "In4.Cu")
		(net "M_D_CPU0_SA_DQS_DP<1>")
	)
	(segment
		(start 316.731396 -218.776804)
		(end 317.10503 -219.150438)
		(width 0.16002)
		(layer "In4.Cu")
		(net "M_D_CPU0_SA_DQS_DP<1>")
	)
	(segment
		(start 338.281264 -231.853994)
		(end 338.289646 -231.849168)
		(width 0.09525)
		(layer "In4.Cu")
		(net "M_D_CPU0_SA_DQS_DP<1>")
	)
	(segment
		(start 316.99835 -220.061282)
		(end 317.194184 -220.257116)
		(width 0.16002)
		(layer "In4.Cu")
		(net "M_D_CPU0_SA_DQS_DP<1>")
	)
	(segment
		(start 324.39102 -228.957378)
		(end 324.39102 -229.040182)
		(width 0.09525)
		(layer "In4.Cu")
		(net "M_D_CPU0_SA_DQS_DP<1>")
	)
	(segment
		(start 311.503822 -214.566754)
		(end 311.699656 -214.762588)
		(width 0.16002)
		(layer "In4.Cu")
		(net "M_D_CPU0_SA_DQS_DP<1>")
	)
	(segment
		(start 316.204092 -218.776804)
		(end 316.731396 -218.776804)
		(width 0.16002)
		(layer "In4.Cu")
		(net "M_D_CPU0_SA_DQS_DP<1>")
	)
	(segment
		(start 315.624718 -218.68765)
		(end 315.820552 -218.883484)
		(width 0.16002)
		(layer "In4.Cu")
		(net "M_D_CPU0_SA_DQS_DP<1>")
	)
	(segment
		(start 287.039558 -210.35899)
		(end 287.188656 -210.209892)
		(width 0.16002)
		(layer "In4.Cu")
		(net "M_D_CPU0_SA_DQS_DP<1>")
	)
	(segment
		(start 293.149782 -209.360008)
		(end 293.999666 -210.209892)
		(width 0.16002)
		(layer "In4.Cu")
		(net "M_D_CPU0_SA_DQS_DP<1>")
	)
	(segment
		(start 315.624718 -218.41079)
		(end 315.624718 -218.68765)
		(width 0.16002)
		(layer "In4.Cu")
		(net "M_D_CPU0_SA_DQS_DP<1>")
	)
	(segment
		(start 293.999666 -210.209892)
		(end 296.577004 -210.209892)
		(width 0.16002)
		(layer "In4.Cu")
		(net "M_D_CPU0_SA_DQS_DP<1>")
	)
	(segment
		(start 310.326024 -213.388956)
		(end 310.602884 -213.388956)
		(width 0.16002)
		(layer "In4.Cu")
		(net "M_D_CPU0_SA_DQS_DP<1>")
	)
	(segment
		(start 312.083196 -214.655908)
		(end 312.6105 -214.655908)
		(width 0.16002)
		(layer "In4.Cu")
		(net "M_D_CPU0_SA_DQS_DP<1>")
	)
	(segment
		(start 307.905658 -210.96859)
		(end 310.326024 -213.388956)
		(width 0.16002)
		(layer "In4.Cu")
		(net "M_D_CPU0_SA_DQS_DP<1>")
	)
	(segment
		(start 317.10503 -219.150438)
		(end 317.10503 -219.677742)
		(width 0.16002)
		(layer "In4.Cu")
		(net "M_D_CPU0_SA_DQS_DP<1>")
	)
	(segment
		(start 326.551798 -230.148892)
		(end 326.892158 -230.489252)
		(width 0.09525)
		(layer "In4.Cu")
		(net "M_D_CPU0_SA_DQS_DP<1>")
	)
	(segment
		(start 319.47866 -221.524068)
		(end 319.852294 -221.897702)
		(width 0.16002)
		(layer "In4.Cu")
		(net "M_D_CPU0_SA_DQS_DP<1>")
	)
	(segment
		(start 318.478662 -220.52407)
		(end 318.478662 -221.051374)
		(width 0.16002)
		(layer "In4.Cu")
		(net "M_D_CPU0_SA_DQS_DP<1>")
	)
	(segment
		(start 296.921682 -210.55457)
		(end 297.349418 -210.55457)
		(width 0.16002)
		(layer "In4.Cu")
		(net "M_D_CPU0_SA_DQS_DP<1>")
	)
	(segment
		(start 313.073288 -216.13622)
		(end 313.350148 -216.13622)
		(width 0.16002)
		(layer "In4.Cu")
		(net "M_D_CPU0_SA_DQS_DP<1>")
	)
	(segment
		(start 324.799706 -229.449122)
		(end 325.398892 -229.449122)
		(width 0.09525)
		(layer "In4.Cu")
		(net "M_D_CPU0_SA_DQS_DP<1>")
	)
	(segment
		(start 319.852294 -222.425006)
		(end 319.745614 -222.531686)
		(width 0.16002)
		(layer "In4.Cu")
		(net "M_D_CPU0_SA_DQS_DP<1>")
	)
	(segment
		(start 313.456828 -216.02954)
		(end 313.984132 -216.02954)
		(width 0.16002)
		(layer "In4.Cu")
		(net "M_D_CPU0_SA_DQS_DP<1>")
	)
	(segment
		(start 318.371982 -221.434914)
		(end 318.567816 -221.630748)
		(width 0.16002)
		(layer "In4.Cu")
		(net "M_D_CPU0_SA_DQS_DP<1>")
	)
	(segment
		(start 313.984132 -216.02954)
		(end 314.357766 -216.403174)
		(width 0.16002)
		(layer "In4.Cu")
		(net "M_D_CPU0_SA_DQS_DP<1>")
	)
	(segment
		(start 298.960286 -209.360008)
		(end 300.700186 -209.360008)
		(width 0.16002)
		(layer "In4.Cu")
		(net "M_D_CPU0_SA_DQS_DP<1>")
	)
	(segment
		(start 312.877454 -215.940386)
		(end 313.073288 -216.13622)
		(width 0.16002)
		(layer "In4.Cu")
		(net "M_D_CPU0_SA_DQS_DP<1>")
	)
	(segment
		(start 317.577724 -220.150436)
		(end 318.105028 -220.150436)
		(width 0.16002)
		(layer "In4.Cu")
		(net "M_D_CPU0_SA_DQS_DP<1>")
	)
	(segment
		(start 316.097412 -218.883484)
		(end 316.204092 -218.776804)
		(width 0.16002)
		(layer "In4.Cu")
		(net "M_D_CPU0_SA_DQS_DP<1>")
	)
	(segment
		(start 314.72378 -217.509852)
		(end 314.83046 -217.403172)
		(width 0.16002)
		(layer "In4.Cu")
		(net "M_D_CPU0_SA_DQS_DP<1>")
	)
	(segment
		(start 324.374256 -228.940614)
		(end 324.39102 -228.957378)
		(width 0.09525)
		(layer "In4.Cu")
		(net "M_D_CPU0_SA_DQS_DP<1>")
	)
	(segment
		(start 310.709564 -213.282276)
		(end 311.236868 -213.282276)
		(width 0.16002)
		(layer "In4.Cu")
		(net "M_D_CPU0_SA_DQS_DP<1>")
	)
	(segment
		(start 303.050956 -210.96859)
		(end 307.905658 -210.96859)
		(width 0.16002)
		(layer "In4.Cu")
		(net "M_D_CPU0_SA_DQS_DP<1>")
	)
	(segment
		(start 325.398892 -229.449122)
		(end 326.098662 -230.148892)
		(width 0.09525)
		(layer "In4.Cu")
		(net "M_D_CPU0_SA_DQS_DP<1>")
	)
	(segment
		(start 298.179998 -209.72399)
		(end 298.596304 -209.72399)
		(width 0.16002)
		(layer "In4.Cu")
		(net "M_D_CPU0_SA_DQS_DP<1>")
	)
	(segment
		(start 321.616578 -226.182936)
		(end 324.374256 -228.940614)
		(width 0.16002)
		(layer "In4.Cu")
		(net "M_D_CPU0_SA_DQS_DP<1>")
	)
	(segment
		(start 314.44692 -217.509852)
		(end 314.72378 -217.509852)
		(width 0.16002)
		(layer "In4.Cu")
		(net "M_D_CPU0_SA_DQS_DP<1>")
	)
	(segment
		(start 313.350148 -216.13622)
		(end 313.456828 -216.02954)
		(width 0.16002)
		(layer "In4.Cu")
		(net "M_D_CPU0_SA_DQS_DP<1>")
	)
	(segment
		(start 289.033204 -210.209892)
		(end 289.377882 -210.55457)
		(width 0.16002)
		(layer "In4.Cu")
		(net "M_D_CPU0_SA_DQS_DP<1>")
	)
	(segment
		(start 326.892158 -231.187498)
		(end 327.4949 -231.79024)
		(width 0.09525)
		(layer "In4.Cu")
		(net "M_D_CPU0_SA_DQS_DP<1>")
	)
	(segment
		(start 315.731398 -217.776806)
		(end 315.731398 -218.30411)
		(width 0.16002)
		(layer "In4.Cu")
		(net "M_D_CPU0_SA_DQS_DP<1>")
	)
	(arc
		(start 332.27264 -231.849168)
		(mid 332.461108 -231.899845)
		(end 332.649576 -231.849168)
		(width 0.09525)
		(layer "In4.Cu")
		(net "M_D_CPU0_SA_DQS_DP<1>")
	)
	(arc
		(start 328.889614 -231.849168)
		(mid 329.171046 -231.773413)
		(end 329.452478 -231.849168)
		(width 0.09525)
		(layer "In4.Cu")
		(net "M_D_CPU0_SA_DQS_DP<1>")
	)
	(arc
		(start 334.529684 -231.849168)
		(mid 334.811116 -231.773413)
		(end 335.092548 -231.849168)
		(width 0.09525)
		(layer "In4.Cu")
		(net "M_D_CPU0_SA_DQS_DP<1>")
	)
	(arc
		(start 329.452478 -231.849168)
		(mid 329.636253 -231.89994)
		(end 329.821286 -231.853994)
		(width 0.09525)
		(layer "In4.Cu")
		(net "M_D_CPU0_SA_DQS_DP<1>")
	)
	(arc
		(start 336.409792 -231.849168)
		(mid 336.691224 -231.773413)
		(end 336.972656 -231.849168)
		(width 0.09525)
		(layer "In4.Cu")
		(net "M_D_CPU0_SA_DQS_DP<1>")
	)
	(arc
		(start 334.152494 -231.849168)
		(mid 334.336269 -231.89994)
		(end 334.521302 -231.853994)
		(width 0.09525)
		(layer "In4.Cu")
		(net "M_D_CPU0_SA_DQS_DP<1>")
	)
	(arc
		(start 331.709776 -231.849168)
		(mid 331.991208 -231.773413)
		(end 332.27264 -231.849168)
		(width 0.09525)
		(layer "In4.Cu")
		(net "M_D_CPU0_SA_DQS_DP<1>")
	)
	(arc
		(start 337.912456 -231.849168)
		(mid 338.096231 -231.89994)
		(end 338.281264 -231.853994)
		(width 0.09525)
		(layer "In4.Cu")
		(net "M_D_CPU0_SA_DQS_DP<1>")
	)
	(arc
		(start 337.349592 -231.849168)
		(mid 337.631024 -231.773413)
		(end 337.912456 -231.849168)
		(width 0.09525)
		(layer "In4.Cu")
		(net "M_D_CPU0_SA_DQS_DP<1>")
	)
	(arc
		(start 327.581006 -231.853994)
		(mid 327.766038 -231.899908)
		(end 327.949814 -231.849168)
		(width 0.09525)
		(layer "In4.Cu")
		(net "M_D_CPU0_SA_DQS_DP<1>")
	)
	(arc
		(start 336.972656 -231.849168)
		(mid 337.161124 -231.899845)
		(end 337.349592 -231.849168)
		(width 0.09525)
		(layer "In4.Cu")
		(net "M_D_CPU0_SA_DQS_DP<1>")
	)
	(arc
		(start 327.4949 -231.79024)
		(mid 327.531844 -231.822233)
		(end 327.572624 -231.849168)
		(width 0.09525)
		(layer "In4.Cu")
		(net "M_D_CPU0_SA_DQS_DP<1>")
	)
	(arc
		(start 333.21244 -231.849168)
		(mid 333.396215 -231.89994)
		(end 333.581248 -231.853994)
		(width 0.09525)
		(layer "In4.Cu")
		(net "M_D_CPU0_SA_DQS_DP<1>")
	)
	(arc
		(start 338.289646 -231.849168)
		(mid 338.523441 -231.775301)
		(end 338.766404 -231.808274)
		(width 0.09525)
		(layer "In4.Cu")
		(net "M_D_CPU0_SA_DQS_DP<1>")
	)
	(arc
		(start 330.769722 -231.849168)
		(mid 331.051154 -231.773413)
		(end 331.332586 -231.849168)
		(width 0.09525)
		(layer "In4.Cu")
		(net "M_D_CPU0_SA_DQS_DP<1>")
	)
	(arc
		(start 335.469738 -231.849168)
		(mid 335.75117 -231.773413)
		(end 336.032602 -231.849168)
		(width 0.09525)
		(layer "In4.Cu")
		(net "M_D_CPU0_SA_DQS_DP<1>")
	)
	(arc
		(start 327.949814 -231.849168)
		(mid 328.231246 -231.773413)
		(end 328.512678 -231.849168)
		(width 0.09525)
		(layer "In4.Cu")
		(net "M_D_CPU0_SA_DQS_DP<1>")
	)
	(arc
		(start 332.649576 -231.849168)
		(mid 332.931008 -231.773413)
		(end 333.21244 -231.849168)
		(width 0.09525)
		(layer "In4.Cu")
		(net "M_D_CPU0_SA_DQS_DP<1>")
	)
	(arc
		(start 331.340968 -231.853994)
		(mid 331.526 -231.899908)
		(end 331.709776 -231.849168)
		(width 0.09525)
		(layer "In4.Cu")
		(net "M_D_CPU0_SA_DQS_DP<1>")
	)
	(arc
		(start 329.829668 -231.849168)
		(mid 330.1111 -231.773413)
		(end 330.392532 -231.849168)
		(width 0.09525)
		(layer "In4.Cu")
		(net "M_D_CPU0_SA_DQS_DP<1>")
	)
	(arc
		(start 333.58963 -231.849168)
		(mid 333.871062 -231.773413)
		(end 334.152494 -231.849168)
		(width 0.09525)
		(layer "In4.Cu")
		(net "M_D_CPU0_SA_DQS_DP<1>")
	)
	(arc
		(start 336.040984 -231.853994)
		(mid 336.226016 -231.899908)
		(end 336.409792 -231.849168)
		(width 0.09525)
		(layer "In4.Cu")
		(net "M_D_CPU0_SA_DQS_DP<1>")
	)
	(arc
		(start 328.512678 -231.849168)
		(mid 328.701146 -231.899845)
		(end 328.889614 -231.849168)
		(width 0.09525)
		(layer "In4.Cu")
		(net "M_D_CPU0_SA_DQS_DP<1>")
	)
	(arc
		(start 338.766404 -231.808274)
		(mid 338.776347 -231.812117)
		(end 338.786216 -231.816148)
		(width 0.09525)
		(layer "In4.Cu")
		(net "M_D_CPU0_SA_DQS_DP<1>")
	)
	(arc
		(start 330.400914 -231.853994)
		(mid 330.585946 -231.899908)
		(end 330.769722 -231.849168)
		(width 0.09525)
		(layer "In4.Cu")
		(net "M_D_CPU0_SA_DQS_DP<1>")
	)
	(arc
		(start 335.10093 -231.853994)
		(mid 335.285962 -231.899908)
		(end 335.469738 -231.849168)
		(width 0.09525)
		(layer "In4.Cu")
		(net "M_D_CPU0_SA_DQS_DP<1>")
	)
	(segment
		(start 339.508084 -226.930204)
		(end 339.040978 -226.664266)
		(width 0.12954)
		(layer "F.Cu")
		(net "M_D_CPU0_SA_DQS_DP<0>")
	)
	(segment
		(start 311.472834 -205.061566)
		(end 311.696862 -205.285594)
		(width 0.16002)
		(layer "In4.Cu")
		(net "M_D_CPU0_SA_DQS_DP<0>")
	)
	(segment
		(start 296.546524 -200.859898)
		(end 296.879518 -201.192892)
		(width 0.16002)
		(layer "In4.Cu")
		(net "M_D_CPU0_SA_DQS_DP<0>")
	)
	(segment
		(start 287.012634 -201.008996)
		(end 287.161732 -200.859898)
		(width 0.16002)
		(layer "In4.Cu")
		(net "M_D_CPU0_SA_DQS_DP<0>")
	)
	(segment
		(start 328.512678 -223.749362)
		(end 328.54773 -223.769936)
		(width 0.09525)
		(layer "In4.Cu")
		(net "M_D_CPU0_SA_DQS_DP<0>")
	)
	(segment
		(start 298.974256 -200.010014)
		(end 300.72203 -200.010014)
		(width 0.16002)
		(layer "In4.Cu")
		(net "M_D_CPU0_SA_DQS_DP<0>")
	)
	(segment
		(start 300.72203 -200.010014)
		(end 301.622206 -200.91019)
		(width 0.16002)
		(layer "In4.Cu")
		(net "M_D_CPU0_SA_DQS_DP<0>")
	)
	(segment
		(start 313.070494 -206.659226)
		(end 313.819794 -206.659226)
		(width 0.16002)
		(layer "In4.Cu")
		(net "M_D_CPU0_SA_DQS_DP<0>")
	)
	(segment
		(start 327.441814 -221.31655)
		(end 327.441814 -221.340172)
		(width 0.09525)
		(layer "In4.Cu")
		(net "M_D_CPU0_SA_DQS_DP<0>")
	)
	(segment
		(start 312.846466 -205.685898)
		(end 312.846466 -206.435198)
		(width 0.16002)
		(layer "In4.Cu")
		(net "M_D_CPU0_SA_DQS_DP<0>")
	)
	(segment
		(start 327.441814 -220.281246)
		(end 327.441814 -221.31655)
		(width 0.16002)
		(layer "In4.Cu")
		(net "M_D_CPU0_SA_DQS_DP<0>")
	)
	(segment
		(start 318.340994 -211.929726)
		(end 318.565022 -212.153754)
		(width 0.16002)
		(layer "In4.Cu")
		(net "M_D_CPU0_SA_DQS_DP<0>")
	)
	(segment
		(start 313.819794 -206.659226)
		(end 314.220098 -207.05953)
		(width 0.16002)
		(layer "In4.Cu")
		(net "M_D_CPU0_SA_DQS_DP<0>")
	)
	(segment
		(start 315.59373 -208.433162)
		(end 315.59373 -209.182462)
		(width 0.16002)
		(layer "In4.Cu")
		(net "M_D_CPU0_SA_DQS_DP<0>")
	)
	(segment
		(start 297.349418 -201.192892)
		(end 298.185078 -200.357232)
		(width 0.16002)
		(layer "In4.Cu")
		(net "M_D_CPU0_SA_DQS_DP<0>")
	)
	(segment
		(start 318.340994 -211.180426)
		(end 318.340994 -211.929726)
		(width 0.16002)
		(layer "In4.Cu")
		(net "M_D_CPU0_SA_DQS_DP<0>")
	)
	(segment
		(start 304.891186 -201.629772)
		(end 308.79034 -201.629772)
		(width 0.16002)
		(layer "In4.Cu")
		(net "M_D_CPU0_SA_DQS_DP<0>")
	)
	(segment
		(start 338.281264 -226.994212)
		(end 338.289646 -226.989386)
		(width 0.09525)
		(layer "In4.Cu")
		(net "M_D_CPU0_SA_DQS_DP<0>")
	)
	(segment
		(start 324.05955 -217.648282)
		(end 324.80885 -217.648282)
		(width 0.16002)
		(layer "In4.Cu")
		(net "M_D_CPU0_SA_DQS_DP<0>")
	)
	(segment
		(start 287.161732 -200.859898)
		(end 289.040824 -200.859898)
		(width 0.16002)
		(layer "In4.Cu")
		(net "M_D_CPU0_SA_DQS_DP<0>")
	)
	(segment
		(start 319.714626 -213.303358)
		(end 319.938654 -213.527386)
		(width 0.16002)
		(layer "In4.Cu")
		(net "M_D_CPU0_SA_DQS_DP<0>")
	)
	(segment
		(start 327.540112 -222.111062)
		(end 327.540112 -222.110554)
		(width 0.09525)
		(layer "In4.Cu")
		(net "M_D_CPU0_SA_DQS_DP<0>")
	)
	(segment
		(start 321.088258 -213.92769)
		(end 321.088258 -214.67699)
		(width 0.16002)
		(layer "In4.Cu")
		(net "M_D_CPU0_SA_DQS_DP<0>")
	)
	(segment
		(start 296.879518 -201.192892)
		(end 297.349418 -201.192892)
		(width 0.16002)
		(layer "In4.Cu")
		(net "M_D_CPU0_SA_DQS_DP<0>")
	)
	(segment
		(start 284.736032 -200.735184)
		(end 285.009844 -201.008996)
		(width 0.16002)
		(layer "In4.Cu")
		(net "M_D_CPU0_SA_DQS_DP<0>")
	)
	(segment
		(start 322.46189 -215.301322)
		(end 322.46189 -216.050622)
		(width 0.16002)
		(layer "In4.Cu")
		(net "M_D_CPU0_SA_DQS_DP<0>")
	)
	(segment
		(start 311.696862 -205.285594)
		(end 312.446162 -205.285594)
		(width 0.16002)
		(layer "In4.Cu")
		(net "M_D_CPU0_SA_DQS_DP<0>")
	)
	(segment
		(start 334.521302 -226.994212)
		(end 334.529684 -226.989386)
		(width 0.09525)
		(layer "In4.Cu")
		(net "M_D_CPU0_SA_DQS_DP<0>")
	)
	(segment
		(start 319.714626 -212.554058)
		(end 319.714626 -213.303358)
		(width 0.16002)
		(layer "In4.Cu")
		(net "M_D_CPU0_SA_DQS_DP<0>")
	)
	(segment
		(start 289.772598 -201.203052)
		(end 290.613338 -200.362312)
		(width 0.16002)
		(layer "In4.Cu")
		(net "M_D_CPU0_SA_DQS_DP<0>")
	)
	(segment
		(start 328.950066 -224.540572)
		(end 328.982578 -224.559368)
		(width 0.09525)
		(layer "In4.Cu")
		(net "M_D_CPU0_SA_DQS_DP<0>")
	)
	(segment
		(start 311.472834 -204.312266)
		(end 311.472834 -205.061566)
		(width 0.16002)
		(layer "In4.Cu")
		(net "M_D_CPU0_SA_DQS_DP<0>")
	)
	(segment
		(start 285.009844 -201.008996)
		(end 287.012634 -201.008996)
		(width 0.16002)
		(layer "In4.Cu")
		(net "M_D_CPU0_SA_DQS_DP<0>")
	)
	(segment
		(start 322.685918 -216.27465)
		(end 323.435218 -216.27465)
		(width 0.16002)
		(layer "In4.Cu")
		(net "M_D_CPU0_SA_DQS_DP<0>")
	)
	(segment
		(start 312.846466 -206.435198)
		(end 313.070494 -206.659226)
		(width 0.16002)
		(layer "In4.Cu")
		(net "M_D_CPU0_SA_DQS_DP<0>")
	)
	(segment
		(start 310.099202 -202.938634)
		(end 310.099202 -203.687934)
		(width 0.16002)
		(layer "In4.Cu")
		(net "M_D_CPU0_SA_DQS_DP<0>")
	)
	(segment
		(start 329.420982 -225.351086)
		(end 329.452478 -225.369374)
		(width 0.09525)
		(layer "In4.Cu")
		(net "M_D_CPU0_SA_DQS_DP<0>")
	)
	(segment
		(start 316.567058 -209.40649)
		(end 316.967362 -209.806794)
		(width 0.16002)
		(layer "In4.Cu")
		(net "M_D_CPU0_SA_DQS_DP<0>")
	)
	(segment
		(start 314.220098 -207.80883)
		(end 314.444126 -208.032858)
		(width 0.16002)
		(layer "In4.Cu")
		(net "M_D_CPU0_SA_DQS_DP<0>")
	)
	(segment
		(start 298.185078 -200.357232)
		(end 298.627038 -200.357232)
		(width 0.16002)
		(layer "In4.Cu")
		(net "M_D_CPU0_SA_DQS_DP<0>")
	)
	(segment
		(start 319.314322 -212.153754)
		(end 319.714626 -212.554058)
		(width 0.16002)
		(layer "In4.Cu")
		(net "M_D_CPU0_SA_DQS_DP<0>")
	)
	(segment
		(start 317.94069 -210.780122)
		(end 318.340994 -211.180426)
		(width 0.16002)
		(layer "In4.Cu")
		(net "M_D_CPU0_SA_DQS_DP<0>")
	)
	(segment
		(start 322.061586 -214.901018)
		(end 322.46189 -215.301322)
		(width 0.16002)
		(layer "In4.Cu")
		(net "M_D_CPU0_SA_DQS_DP<0>")
	)
	(segment
		(start 328.011282 -222.921068)
		(end 328.042778 -222.939356)
		(width 0.09525)
		(layer "In4.Cu")
		(net "M_D_CPU0_SA_DQS_DP<0>")
	)
	(segment
		(start 315.59373 -209.182462)
		(end 315.817758 -209.40649)
		(width 0.16002)
		(layer "In4.Cu")
		(net "M_D_CPU0_SA_DQS_DP<0>")
	)
	(segment
		(start 323.835522 -216.674954)
		(end 323.835522 -217.424254)
		(width 0.16002)
		(layer "In4.Cu")
		(net "M_D_CPU0_SA_DQS_DP<0>")
	)
	(segment
		(start 327.540112 -222.110554)
		(end 327.611994 -222.15221)
		(width 0.09525)
		(layer "In4.Cu")
		(net "M_D_CPU0_SA_DQS_DP<0>")
	)
	(segment
		(start 338.887054 -226.929696)
		(end 339.040978 -226.664266)
		(width 0.09525)
		(layer "In4.Cu")
		(net "M_D_CPU0_SA_DQS_DP<0>")
	)
	(segment
		(start 314.220098 -207.05953)
		(end 314.220098 -207.80883)
		(width 0.16002)
		(layer "In4.Cu")
		(net "M_D_CPU0_SA_DQS_DP<0>")
	)
	(segment
		(start 315.193426 -208.032858)
		(end 315.59373 -208.433162)
		(width 0.16002)
		(layer "In4.Cu")
		(net "M_D_CPU0_SA_DQS_DP<0>")
	)
	(segment
		(start 328.042778 -222.939356)
		(end 328.07783 -222.95993)
		(width 0.09525)
		(layer "In4.Cu")
		(net "M_D_CPU0_SA_DQS_DP<0>")
	)
	(segment
		(start 325.433182 -219.021914)
		(end 326.182482 -219.021914)
		(width 0.16002)
		(layer "In4.Cu")
		(net "M_D_CPU0_SA_DQS_DP<0>")
	)
	(segment
		(start 293.092378 -200.009252)
		(end 293.943024 -200.859898)
		(width 0.16002)
		(layer "In4.Cu")
		(net "M_D_CPU0_SA_DQS_DP<0>")
	)
	(segment
		(start 329.452478 -225.369374)
		(end 329.490578 -225.391472)
		(width 0.09525)
		(layer "In4.Cu")
		(net "M_D_CPU0_SA_DQS_DP<0>")
	)
	(segment
		(start 325.209154 -218.797886)
		(end 325.433182 -219.021914)
		(width 0.16002)
		(layer "In4.Cu")
		(net "M_D_CPU0_SA_DQS_DP<0>")
	)
	(segment
		(start 336.032602 -226.989386)
		(end 336.040984 -226.994212)
		(width 0.09525)
		(layer "In4.Cu")
		(net "M_D_CPU0_SA_DQS_DP<0>")
	)
	(segment
		(start 323.835522 -217.424254)
		(end 324.05955 -217.648282)
		(width 0.16002)
		(layer "In4.Cu")
		(net "M_D_CPU0_SA_DQS_DP<0>")
	)
	(segment
		(start 315.817758 -209.40649)
		(end 316.567058 -209.40649)
		(width 0.16002)
		(layer "In4.Cu")
		(net "M_D_CPU0_SA_DQS_DP<0>")
	)
	(segment
		(start 327.441814 -221.340172)
		(end 327.382886 -221.3991)
		(width 0.09525)
		(layer "In4.Cu")
		(net "M_D_CPU0_SA_DQS_DP<0>")
	)
	(segment
		(start 289.040824 -200.859898)
		(end 289.383978 -201.203052)
		(width 0.16002)
		(layer "In4.Cu")
		(net "M_D_CPU0_SA_DQS_DP<0>")
	)
	(segment
		(start 320.687954 -213.527386)
		(end 321.088258 -213.92769)
		(width 0.16002)
		(layer "In4.Cu")
		(net "M_D_CPU0_SA_DQS_DP<0>")
	)
	(segment
		(start 330.36002 -226.97059)
		(end 330.392532 -226.989386)
		(width 0.09525)
		(layer "In4.Cu")
		(net "M_D_CPU0_SA_DQS_DP<0>")
	)
	(segment
		(start 321.088258 -214.67699)
		(end 321.312286 -214.901018)
		(width 0.16002)
		(layer "In4.Cu")
		(net "M_D_CPU0_SA_DQS_DP<0>")
	)
	(segment
		(start 325.209154 -218.048586)
		(end 325.209154 -218.797886)
		(width 0.16002)
		(layer "In4.Cu")
		(net "M_D_CPU0_SA_DQS_DP<0>")
	)
	(segment
		(start 290.613338 -200.362312)
		(end 291.070538 -200.362312)
		(width 0.16002)
		(layer "In4.Cu")
		(net "M_D_CPU0_SA_DQS_DP<0>")
	)
	(segment
		(start 316.967362 -209.806794)
		(end 316.967362 -210.556094)
		(width 0.16002)
		(layer "In4.Cu")
		(net "M_D_CPU0_SA_DQS_DP<0>")
	)
	(segment
		(start 293.943024 -200.859898)
		(end 296.546524 -200.859898)
		(width 0.16002)
		(layer "In4.Cu")
		(net "M_D_CPU0_SA_DQS_DP<0>")
	)
	(segment
		(start 327.382886 -221.3991)
		(end 327.382886 -221.80423)
		(width 0.09525)
		(layer "In4.Cu")
		(net "M_D_CPU0_SA_DQS_DP<0>")
	)
	(segment
		(start 314.444126 -208.032858)
		(end 315.193426 -208.032858)
		(width 0.16002)
		(layer "In4.Cu")
		(net "M_D_CPU0_SA_DQS_DP<0>")
	)
	(segment
		(start 338.786216 -226.956366)
		(end 338.887054 -226.929696)
		(width 0.09525)
		(layer "In4.Cu")
		(net "M_D_CPU0_SA_DQS_DP<0>")
	)
	(segment
		(start 298.627038 -200.357232)
		(end 298.974256 -200.010014)
		(width 0.16002)
		(layer "In4.Cu")
		(net "M_D_CPU0_SA_DQS_DP<0>")
	)
	(segment
		(start 331.332586 -226.989386)
		(end 331.340968 -226.994212)
		(width 0.09525)
		(layer "In4.Cu")
		(net "M_D_CPU0_SA_DQS_DP<0>")
	)
	(segment
		(start 335.092548 -226.989386)
		(end 335.10093 -226.994212)
		(width 0.09525)
		(layer "In4.Cu")
		(net "M_D_CPU0_SA_DQS_DP<0>")
	)
	(segment
		(start 317.19139 -210.780122)
		(end 317.94069 -210.780122)
		(width 0.16002)
		(layer "In4.Cu")
		(net "M_D_CPU0_SA_DQS_DP<0>")
	)
	(segment
		(start 330.392532 -226.989386)
		(end 330.400914 -226.994212)
		(width 0.09525)
		(layer "In4.Cu")
		(net "M_D_CPU0_SA_DQS_DP<0>")
	)
	(segment
		(start 308.79034 -201.629772)
		(end 310.099202 -202.938634)
		(width 0.16002)
		(layer "In4.Cu")
		(net "M_D_CPU0_SA_DQS_DP<0>")
	)
	(segment
		(start 328.982578 -224.559368)
		(end 329.020678 -224.581466)
		(width 0.09525)
		(layer "In4.Cu")
		(net "M_D_CPU0_SA_DQS_DP<0>")
	)
	(segment
		(start 329.89012 -226.160584)
		(end 329.922632 -226.17938)
		(width 0.09525)
		(layer "In4.Cu")
		(net "M_D_CPU0_SA_DQS_DP<0>")
	)
	(segment
		(start 324.80885 -217.648282)
		(end 325.209154 -218.048586)
		(width 0.16002)
		(layer "In4.Cu")
		(net "M_D_CPU0_SA_DQS_DP<0>")
	)
	(segment
		(start 291.423598 -200.009252)
		(end 293.092378 -200.009252)
		(width 0.16002)
		(layer "In4.Cu")
		(net "M_D_CPU0_SA_DQS_DP<0>")
	)
	(segment
		(start 328.480166 -223.730566)
		(end 328.512678 -223.749362)
		(width 0.09525)
		(layer "In4.Cu")
		(net "M_D_CPU0_SA_DQS_DP<0>")
	)
	(segment
		(start 326.182482 -219.021914)
		(end 327.441814 -220.281246)
		(width 0.16002)
		(layer "In4.Cu")
		(net "M_D_CPU0_SA_DQS_DP<0>")
	)
	(segment
		(start 289.383978 -201.203052)
		(end 289.772598 -201.203052)
		(width 0.16002)
		(layer "In4.Cu")
		(net "M_D_CPU0_SA_DQS_DP<0>")
	)
	(segment
		(start 311.07253 -203.911962)
		(end 311.472834 -204.312266)
		(width 0.16002)
		(layer "In4.Cu")
		(net "M_D_CPU0_SA_DQS_DP<0>")
	)
	(segment
		(start 319.938654 -213.527386)
		(end 320.687954 -213.527386)
		(width 0.16002)
		(layer "In4.Cu")
		(net "M_D_CPU0_SA_DQS_DP<0>")
	)
	(segment
		(start 304.171604 -200.91019)
		(end 304.891186 -201.629772)
		(width 0.16002)
		(layer "In4.Cu")
		(net "M_D_CPU0_SA_DQS_DP<0>")
	)
	(segment
		(start 291.070538 -200.362312)
		(end 291.423598 -200.009252)
		(width 0.16002)
		(layer "In4.Cu")
		(net "M_D_CPU0_SA_DQS_DP<0>")
	)
	(segment
		(start 329.922632 -226.17938)
		(end 329.957684 -226.199954)
		(width 0.09525)
		(layer "In4.Cu")
		(net "M_D_CPU0_SA_DQS_DP<0>")
	)
	(segment
		(start 323.435218 -216.27465)
		(end 323.835522 -216.674954)
		(width 0.16002)
		(layer "In4.Cu")
		(net "M_D_CPU0_SA_DQS_DP<0>")
	)
	(segment
		(start 316.967362 -210.556094)
		(end 317.19139 -210.780122)
		(width 0.16002)
		(layer "In4.Cu")
		(net "M_D_CPU0_SA_DQS_DP<0>")
	)
	(segment
		(start 312.446162 -205.285594)
		(end 312.846466 -205.685898)
		(width 0.16002)
		(layer "In4.Cu")
		(net "M_D_CPU0_SA_DQS_DP<0>")
	)
	(segment
		(start 322.46189 -216.050622)
		(end 322.685918 -216.27465)
		(width 0.16002)
		(layer "In4.Cu")
		(net "M_D_CPU0_SA_DQS_DP<0>")
	)
	(segment
		(start 301.622206 -200.91019)
		(end 304.171604 -200.91019)
		(width 0.16002)
		(layer "In4.Cu")
		(net "M_D_CPU0_SA_DQS_DP<0>")
	)
	(segment
		(start 310.099202 -203.687934)
		(end 310.32323 -203.911962)
		(width 0.16002)
		(layer "In4.Cu")
		(net "M_D_CPU0_SA_DQS_DP<0>")
	)
	(segment
		(start 333.581248 -226.994212)
		(end 333.58963 -226.989386)
		(width 0.09525)
		(layer "In4.Cu")
		(net "M_D_CPU0_SA_DQS_DP<0>")
	)
	(segment
		(start 310.32323 -203.911962)
		(end 311.07253 -203.911962)
		(width 0.16002)
		(layer "In4.Cu")
		(net "M_D_CPU0_SA_DQS_DP<0>")
	)
	(segment
		(start 318.565022 -212.153754)
		(end 319.314322 -212.153754)
		(width 0.16002)
		(layer "In4.Cu")
		(net "M_D_CPU0_SA_DQS_DP<0>")
	)
	(segment
		(start 321.312286 -214.901018)
		(end 322.061586 -214.901018)
		(width 0.16002)
		(layer "In4.Cu")
		(net "M_D_CPU0_SA_DQS_DP<0>")
	)
	(arc
		(start 330.769722 -226.989386)
		(mid 331.051154 -226.913631)
		(end 331.332586 -226.989386)
		(width 0.09525)
		(layer "In4.Cu")
		(net "M_D_CPU0_SA_DQS_DP<0>")
	)
	(arc
		(start 329.490578 -225.391472)
		(mid 329.669028 -225.592942)
		(end 329.733402 -225.85426)
		(width 0.09525)
		(layer "In4.Cu")
		(net "M_D_CPU0_SA_DQS_DP<0>")
	)
	(arc
		(start 329.263502 -225.044254)
		(mid 329.305167 -225.216701)
		(end 329.420982 -225.351086)
		(width 0.09525)
		(layer "In4.Cu")
		(net "M_D_CPU0_SA_DQS_DP<0>")
	)
	(arc
		(start 329.020678 -224.581466)
		(mid 329.199128 -224.782936)
		(end 329.263502 -225.044254)
		(width 0.09525)
		(layer "In4.Cu")
		(net "M_D_CPU0_SA_DQS_DP<0>")
	)
	(arc
		(start 335.10093 -226.994212)
		(mid 335.285962 -227.040126)
		(end 335.469738 -226.989386)
		(width 0.09525)
		(layer "In4.Cu")
		(net "M_D_CPU0_SA_DQS_DP<0>")
	)
	(arc
		(start 332.27264 -226.989386)
		(mid 332.461108 -227.040063)
		(end 332.649576 -226.989386)
		(width 0.09525)
		(layer "In4.Cu")
		(net "M_D_CPU0_SA_DQS_DP<0>")
	)
	(arc
		(start 330.203302 -226.664266)
		(mid 330.244759 -226.836306)
		(end 330.36002 -226.97059)
		(width 0.09525)
		(layer "In4.Cu")
		(net "M_D_CPU0_SA_DQS_DP<0>")
	)
	(arc
		(start 327.611994 -222.15221)
		(mid 327.78968 -222.353502)
		(end 327.853802 -222.614236)
		(width 0.09525)
		(layer "In4.Cu")
		(net "M_D_CPU0_SA_DQS_DP<0>")
	)
	(arc
		(start 329.733402 -225.85426)
		(mid 329.774859 -226.0263)
		(end 329.89012 -226.160584)
		(width 0.09525)
		(layer "In4.Cu")
		(net "M_D_CPU0_SA_DQS_DP<0>")
	)
	(arc
		(start 337.912456 -226.989386)
		(mid 338.096231 -227.040158)
		(end 338.281264 -226.994212)
		(width 0.09525)
		(layer "In4.Cu")
		(net "M_D_CPU0_SA_DQS_DP<0>")
	)
	(arc
		(start 330.400914 -226.994212)
		(mid 330.585946 -227.040126)
		(end 330.769722 -226.989386)
		(width 0.09525)
		(layer "In4.Cu")
		(net "M_D_CPU0_SA_DQS_DP<0>")
	)
	(arc
		(start 327.382886 -221.80423)
		(mid 327.424485 -221.976609)
		(end 327.540112 -222.111062)
		(width 0.09525)
		(layer "In4.Cu")
		(net "M_D_CPU0_SA_DQS_DP<0>")
	)
	(arc
		(start 337.349592 -226.989386)
		(mid 337.631024 -226.913631)
		(end 337.912456 -226.989386)
		(width 0.09525)
		(layer "In4.Cu")
		(net "M_D_CPU0_SA_DQS_DP<0>")
	)
	(arc
		(start 331.709776 -226.989386)
		(mid 331.991208 -226.913631)
		(end 332.27264 -226.989386)
		(width 0.09525)
		(layer "In4.Cu")
		(net "M_D_CPU0_SA_DQS_DP<0>")
	)
	(arc
		(start 336.972656 -226.989386)
		(mid 337.161124 -227.040063)
		(end 337.349592 -226.989386)
		(width 0.09525)
		(layer "In4.Cu")
		(net "M_D_CPU0_SA_DQS_DP<0>")
	)
	(arc
		(start 328.07783 -222.95993)
		(mid 328.258285 -223.161596)
		(end 328.323448 -223.424242)
		(width 0.09525)
		(layer "In4.Cu")
		(net "M_D_CPU0_SA_DQS_DP<0>")
	)
	(arc
		(start 335.469738 -226.989386)
		(mid 335.75117 -226.913631)
		(end 336.032602 -226.989386)
		(width 0.09525)
		(layer "In4.Cu")
		(net "M_D_CPU0_SA_DQS_DP<0>")
	)
	(arc
		(start 328.793348 -224.234248)
		(mid 328.834805 -224.406288)
		(end 328.950066 -224.540572)
		(width 0.09525)
		(layer "In4.Cu")
		(net "M_D_CPU0_SA_DQS_DP<0>")
	)
	(arc
		(start 327.853802 -222.614236)
		(mid 327.895467 -222.786683)
		(end 328.011282 -222.921068)
		(width 0.09525)
		(layer "In4.Cu")
		(net "M_D_CPU0_SA_DQS_DP<0>")
	)
	(arc
		(start 332.649576 -226.989386)
		(mid 332.931008 -226.913631)
		(end 333.21244 -226.989386)
		(width 0.09525)
		(layer "In4.Cu")
		(net "M_D_CPU0_SA_DQS_DP<0>")
	)
	(arc
		(start 328.54773 -223.769936)
		(mid 328.728185 -223.971602)
		(end 328.793348 -224.234248)
		(width 0.09525)
		(layer "In4.Cu")
		(net "M_D_CPU0_SA_DQS_DP<0>")
	)
	(arc
		(start 329.957684 -226.199954)
		(mid 330.138139 -226.40162)
		(end 330.203302 -226.664266)
		(width 0.09525)
		(layer "In4.Cu")
		(net "M_D_CPU0_SA_DQS_DP<0>")
	)
	(arc
		(start 338.766404 -226.948492)
		(mid 338.776347 -226.952335)
		(end 338.786216 -226.956366)
		(width 0.09525)
		(layer "In4.Cu")
		(net "M_D_CPU0_SA_DQS_DP<0>")
	)
	(arc
		(start 334.152494 -226.989386)
		(mid 334.336269 -227.040158)
		(end 334.521302 -226.994212)
		(width 0.09525)
		(layer "In4.Cu")
		(net "M_D_CPU0_SA_DQS_DP<0>")
	)
	(arc
		(start 334.529684 -226.989386)
		(mid 334.811116 -226.913631)
		(end 335.092548 -226.989386)
		(width 0.09525)
		(layer "In4.Cu")
		(net "M_D_CPU0_SA_DQS_DP<0>")
	)
	(arc
		(start 333.21244 -226.989386)
		(mid 333.396215 -227.040158)
		(end 333.581248 -226.994212)
		(width 0.09525)
		(layer "In4.Cu")
		(net "M_D_CPU0_SA_DQS_DP<0>")
	)
	(arc
		(start 331.340968 -226.994212)
		(mid 331.526 -227.040126)
		(end 331.709776 -226.989386)
		(width 0.09525)
		(layer "In4.Cu")
		(net "M_D_CPU0_SA_DQS_DP<0>")
	)
	(arc
		(start 333.58963 -226.989386)
		(mid 333.871062 -226.913631)
		(end 334.152494 -226.989386)
		(width 0.09525)
		(layer "In4.Cu")
		(net "M_D_CPU0_SA_DQS_DP<0>")
	)
	(arc
		(start 336.040984 -226.994212)
		(mid 336.226016 -227.040126)
		(end 336.409792 -226.989386)
		(width 0.09525)
		(layer "In4.Cu")
		(net "M_D_CPU0_SA_DQS_DP<0>")
	)
	(arc
		(start 328.323448 -223.424242)
		(mid 328.364905 -223.596282)
		(end 328.480166 -223.730566)
		(width 0.09525)
		(layer "In4.Cu")
		(net "M_D_CPU0_SA_DQS_DP<0>")
	)
	(arc
		(start 338.289646 -226.989386)
		(mid 338.523441 -226.915519)
		(end 338.766404 -226.948492)
		(width 0.09525)
		(layer "In4.Cu")
		(net "M_D_CPU0_SA_DQS_DP<0>")
	)
	(arc
		(start 336.409792 -226.989386)
		(mid 336.691224 -226.913631)
		(end 336.972656 -226.989386)
		(width 0.09525)
		(layer "In4.Cu")
		(net "M_D_CPU0_SA_DQS_DP<0>")
	)
	(segment
		(start 340.918038 -247.1801)
		(end 340.451186 -246.914162)
		(width 0.12954)
		(layer "F.Cu")
		(net "M_D_CPU0_SA_DQS_DN<9>")
	)
	(segment
		(start 282.817824 -239.25911)
		(end 282.998672 -239.078262)
		(width 0.16002)
		(layer "In4.Cu")
		(net "M_D_CPU0_SA_DQS_DN<9>")
	)
	(segment
		(start 328.03211 -247.233186)
		(end 328.042524 -247.239282)
		(width 0.09525)
		(layer "In4.Cu")
		(net "M_D_CPU0_SA_DQS_DN<9>")
	)
	(segment
		(start 287.245552 -240.258092)
		(end 288.915094 -240.258092)
		(width 0.16002)
		(layer "In4.Cu")
		(net "M_D_CPU0_SA_DQS_DN<9>")
	)
	(segment
		(start 328.411332 -247.244108)
		(end 328.419714 -247.239282)
		(width 0.09525)
		(layer "In4.Cu")
		(net "M_D_CPU0_SA_DQS_DN<9>")
	)
	(segment
		(start 286.412178 -239.424718)
		(end 287.245552 -240.258092)
		(width 0.16002)
		(layer "In4.Cu")
		(net "M_D_CPU0_SA_DQS_DN<9>")
	)
	(segment
		(start 324.520052 -247.398032)
		(end 325.416418 -247.398032)
		(width 0.09525)
		(layer "In4.Cu")
		(net "M_D_CPU0_SA_DQS_DN<9>")
	)
	(segment
		(start 280.635964 -238.985044)
		(end 280.91003 -239.25911)
		(width 0.16002)
		(layer "In4.Cu")
		(net "M_D_CPU0_SA_DQS_DN<9>")
	)
	(segment
		(start 289.72764 -239.923066)
		(end 290.611814 -239.038892)
		(width 0.16002)
		(layer "In4.Cu")
		(net "M_D_CPU0_SA_DQS_DN<9>")
	)
	(segment
		(start 293.441882 -239.407954)
		(end 295.494964 -240.258092)
		(width 0.16002)
		(layer "In4.Cu")
		(net "M_D_CPU0_SA_DQS_DN<9>")
	)
	(segment
		(start 333.682594 -247.239282)
		(end 333.690976 -247.244108)
		(width 0.09525)
		(layer "In4.Cu")
		(net "M_D_CPU0_SA_DQS_DN<9>")
	)
	(segment
		(start 323.324728 -247.033542)
		(end 323.895974 -247.033542)
		(width 0.16002)
		(layer "In4.Cu")
		(net "M_D_CPU0_SA_DQS_DN<9>")
	)
	(segment
		(start 291.176964 -239.038892)
		(end 291.546026 -239.407954)
		(width 0.16002)
		(layer "In4.Cu")
		(net "M_D_CPU0_SA_DQS_DN<9>")
	)
	(segment
		(start 283.675582 -239.078262)
		(end 284.022038 -239.424718)
		(width 0.16002)
		(layer "In4.Cu")
		(net "M_D_CPU0_SA_DQS_DN<9>")
	)
	(segment
		(start 327.101708 -247.239282)
		(end 327.11009 -247.244108)
		(width 0.09525)
		(layer "In4.Cu")
		(net "M_D_CPU0_SA_DQS_DN<9>")
	)
	(segment
		(start 328.982578 -247.239282)
		(end 328.99096 -247.244108)
		(width 0.09525)
		(layer "In4.Cu")
		(net "M_D_CPU0_SA_DQS_DN<9>")
	)
	(segment
		(start 323.978524 -247.09247)
		(end 324.21449 -247.09247)
		(width 0.09525)
		(layer "In4.Cu")
		(net "M_D_CPU0_SA_DQS_DN<9>")
	)
	(segment
		(start 289.25012 -239.923066)
		(end 289.72764 -239.923066)
		(width 0.16002)
		(layer "In4.Cu")
		(net "M_D_CPU0_SA_DQS_DN<9>")
	)
	(segment
		(start 307.127656 -241.95786)
		(end 307.932582 -241.95786)
		(width 0.16002)
		(layer "In4.Cu")
		(net "M_D_CPU0_SA_DQS_DN<9>")
	)
	(segment
		(start 302.347122 -240.227358)
		(end 304.033682 -240.227358)
		(width 0.16002)
		(layer "In4.Cu")
		(net "M_D_CPU0_SA_DQS_DN<9>")
	)
	(segment
		(start 295.494964 -240.258092)
		(end 296.458894 -240.258092)
		(width 0.16002)
		(layer "In4.Cu")
		(net "M_D_CPU0_SA_DQS_DN<9>")
	)
	(segment
		(start 331.23124 -247.244108)
		(end 331.239622 -247.239282)
		(width 0.09525)
		(layer "In4.Cu")
		(net "M_D_CPU0_SA_DQS_DN<9>")
	)
	(segment
		(start 335.931256 -247.244108)
		(end 335.939638 -247.239282)
		(width 0.09525)
		(layer "In4.Cu")
		(net "M_D_CPU0_SA_DQS_DN<9>")
	)
	(segment
		(start 291.546026 -239.407954)
		(end 293.441882 -239.407954)
		(width 0.16002)
		(layer "In4.Cu")
		(net "M_D_CPU0_SA_DQS_DN<9>")
	)
	(segment
		(start 282.998672 -239.078262)
		(end 283.675582 -239.078262)
		(width 0.16002)
		(layer "In4.Cu")
		(net "M_D_CPU0_SA_DQS_DN<9>")
	)
	(segment
		(start 301.527718 -239.407954)
		(end 302.347122 -240.227358)
		(width 0.16002)
		(layer "In4.Cu")
		(net "M_D_CPU0_SA_DQS_DN<9>")
	)
	(segment
		(start 298.155614 -239.038892)
		(end 298.720764 -239.038892)
		(width 0.16002)
		(layer "In4.Cu")
		(net "M_D_CPU0_SA_DQS_DN<9>")
	)
	(segment
		(start 337.442556 -247.239282)
		(end 337.450938 -247.244108)
		(width 0.09525)
		(layer "In4.Cu")
		(net "M_D_CPU0_SA_DQS_DN<9>")
	)
	(segment
		(start 297.27144 -239.923066)
		(end 298.155614 -239.038892)
		(width 0.16002)
		(layer "In4.Cu")
		(net "M_D_CPU0_SA_DQS_DN<9>")
	)
	(segment
		(start 305.092862 -239.923066)
		(end 307.127656 -241.95786)
		(width 0.16002)
		(layer "In4.Cu")
		(net "M_D_CPU0_SA_DQS_DN<9>")
	)
	(segment
		(start 280.91003 -239.25911)
		(end 282.817824 -239.25911)
		(width 0.16002)
		(layer "In4.Cu")
		(net "M_D_CPU0_SA_DQS_DN<9>")
	)
	(segment
		(start 284.022038 -239.424718)
		(end 286.412178 -239.424718)
		(width 0.16002)
		(layer "In4.Cu")
		(net "M_D_CPU0_SA_DQS_DN<9>")
	)
	(segment
		(start 332.74254 -247.239282)
		(end 332.750922 -247.244108)
		(width 0.09525)
		(layer "In4.Cu")
		(net "M_D_CPU0_SA_DQS_DN<9>")
	)
	(segment
		(start 323.895974 -247.033542)
		(end 323.919596 -247.033542)
		(width 0.09525)
		(layer "In4.Cu")
		(net "M_D_CPU0_SA_DQS_DN<9>")
	)
	(segment
		(start 296.458894 -240.258092)
		(end 296.79392 -239.923066)
		(width 0.16002)
		(layer "In4.Cu")
		(net "M_D_CPU0_SA_DQS_DN<9>")
	)
	(segment
		(start 323.153278 -246.862092)
		(end 323.324728 -247.033542)
		(width 0.16002)
		(layer "In4.Cu")
		(net "M_D_CPU0_SA_DQS_DN<9>")
	)
	(segment
		(start 312.836814 -246.862092)
		(end 323.153278 -246.862092)
		(width 0.16002)
		(layer "In4.Cu")
		(net "M_D_CPU0_SA_DQS_DN<9>")
	)
	(segment
		(start 296.79392 -239.923066)
		(end 297.27144 -239.923066)
		(width 0.16002)
		(layer "In4.Cu")
		(net "M_D_CPU0_SA_DQS_DN<9>")
	)
	(segment
		(start 340.196424 -247.206262)
		(end 340.297262 -247.179592)
		(width 0.09525)
		(layer "In4.Cu")
		(net "M_D_CPU0_SA_DQS_DN<9>")
	)
	(segment
		(start 340.297262 -247.179592)
		(end 340.451186 -246.914162)
		(width 0.09525)
		(layer "In4.Cu")
		(net "M_D_CPU0_SA_DQS_DN<9>")
	)
	(segment
		(start 298.720764 -239.038892)
		(end 299.089826 -239.407954)
		(width 0.16002)
		(layer "In4.Cu")
		(net "M_D_CPU0_SA_DQS_DN<9>")
	)
	(segment
		(start 304.033682 -240.227358)
		(end 304.337974 -239.923066)
		(width 0.16002)
		(layer "In4.Cu")
		(net "M_D_CPU0_SA_DQS_DN<9>")
	)
	(segment
		(start 326.539352 -247.239282)
		(end 326.554084 -247.230646)
		(width 0.09525)
		(layer "In4.Cu")
		(net "M_D_CPU0_SA_DQS_DN<9>")
	)
	(segment
		(start 325.651114 -247.163336)
		(end 325.880222 -247.163336)
		(width 0.09525)
		(layer "In4.Cu")
		(net "M_D_CPU0_SA_DQS_DN<9>")
	)
	(segment
		(start 325.416418 -247.398032)
		(end 325.651114 -247.163336)
		(width 0.09525)
		(layer "In4.Cu")
		(net "M_D_CPU0_SA_DQS_DN<9>")
	)
	(segment
		(start 323.919596 -247.033542)
		(end 323.978524 -247.09247)
		(width 0.09525)
		(layer "In4.Cu")
		(net "M_D_CPU0_SA_DQS_DN<9>")
	)
	(segment
		(start 288.915094 -240.258092)
		(end 289.25012 -239.923066)
		(width 0.16002)
		(layer "In4.Cu")
		(net "M_D_CPU0_SA_DQS_DN<9>")
	)
	(segment
		(start 339.691218 -247.244108)
		(end 339.6996 -247.239282)
		(width 0.09525)
		(layer "In4.Cu")
		(net "M_D_CPU0_SA_DQS_DN<9>")
	)
	(segment
		(start 336.87131 -247.244108)
		(end 336.879692 -247.239282)
		(width 0.09525)
		(layer "In4.Cu")
		(net "M_D_CPU0_SA_DQS_DN<9>")
	)
	(segment
		(start 290.611814 -239.038892)
		(end 291.176964 -239.038892)
		(width 0.16002)
		(layer "In4.Cu")
		(net "M_D_CPU0_SA_DQS_DN<9>")
	)
	(segment
		(start 307.932582 -241.95786)
		(end 312.836814 -246.862092)
		(width 0.16002)
		(layer "In4.Cu")
		(net "M_D_CPU0_SA_DQS_DN<9>")
	)
	(segment
		(start 326.524874 -247.247664)
		(end 326.539352 -247.239282)
		(width 0.09525)
		(layer "In4.Cu")
		(net "M_D_CPU0_SA_DQS_DN<9>")
	)
	(segment
		(start 299.089826 -239.407954)
		(end 301.527718 -239.407954)
		(width 0.16002)
		(layer "In4.Cu")
		(net "M_D_CPU0_SA_DQS_DN<9>")
	)
	(segment
		(start 304.337974 -239.923066)
		(end 305.092862 -239.923066)
		(width 0.16002)
		(layer "In4.Cu")
		(net "M_D_CPU0_SA_DQS_DN<9>")
	)
	(segment
		(start 332.171294 -247.244108)
		(end 332.179676 -247.239282)
		(width 0.09525)
		(layer "In4.Cu")
		(net "M_D_CPU0_SA_DQS_DN<9>")
	)
	(segment
		(start 324.21449 -247.09247)
		(end 324.520052 -247.398032)
		(width 0.09525)
		(layer "In4.Cu")
		(net "M_D_CPU0_SA_DQS_DN<9>")
	)
	(arc
		(start 334.622648 -247.239282)
		(mid 334.811116 -247.289959)
		(end 334.999584 -247.239282)
		(width 0.09525)
		(layer "In4.Cu")
		(net "M_D_CPU0_SA_DQS_DN<9>")
	)
	(arc
		(start 326.554084 -247.230646)
		(mid 326.829035 -247.163503)
		(end 327.101708 -247.239282)
		(width 0.09525)
		(layer "In4.Cu")
		(net "M_D_CPU0_SA_DQS_DN<9>")
	)
	(arc
		(start 326.162162 -247.239282)
		(mid 326.342441 -247.290113)
		(end 326.524874 -247.247664)
		(width 0.09525)
		(layer "In4.Cu")
		(net "M_D_CPU0_SA_DQS_DN<9>")
	)
	(arc
		(start 338.759546 -247.239282)
		(mid 339.040978 -247.163527)
		(end 339.32241 -247.239282)
		(width 0.09525)
		(layer "In4.Cu")
		(net "M_D_CPU0_SA_DQS_DN<9>")
	)
	(arc
		(start 338.38261 -247.239282)
		(mid 338.571078 -247.289959)
		(end 338.759546 -247.239282)
		(width 0.09525)
		(layer "In4.Cu")
		(net "M_D_CPU0_SA_DQS_DN<9>")
	)
	(arc
		(start 335.562448 -247.239282)
		(mid 335.746223 -247.290054)
		(end 335.931256 -247.244108)
		(width 0.09525)
		(layer "In4.Cu")
		(net "M_D_CPU0_SA_DQS_DN<9>")
	)
	(arc
		(start 331.239622 -247.239282)
		(mid 331.521054 -247.163527)
		(end 331.802486 -247.239282)
		(width 0.09525)
		(layer "In4.Cu")
		(net "M_D_CPU0_SA_DQS_DN<9>")
	)
	(arc
		(start 334.999584 -247.239282)
		(mid 335.281016 -247.163527)
		(end 335.562448 -247.239282)
		(width 0.09525)
		(layer "In4.Cu")
		(net "M_D_CPU0_SA_DQS_DN<9>")
	)
	(arc
		(start 332.750922 -247.244108)
		(mid 332.935954 -247.290022)
		(end 333.11973 -247.239282)
		(width 0.09525)
		(layer "In4.Cu")
		(net "M_D_CPU0_SA_DQS_DN<9>")
	)
	(arc
		(start 327.479406 -247.239282)
		(mid 327.754949 -247.163433)
		(end 328.03211 -247.233186)
		(width 0.09525)
		(layer "In4.Cu")
		(net "M_D_CPU0_SA_DQS_DN<9>")
	)
	(arc
		(start 337.450938 -247.244108)
		(mid 337.63597 -247.290022)
		(end 337.819746 -247.239282)
		(width 0.09525)
		(layer "In4.Cu")
		(net "M_D_CPU0_SA_DQS_DN<9>")
	)
	(arc
		(start 329.922632 -247.239282)
		(mid 330.1111 -247.289959)
		(end 330.299568 -247.239282)
		(width 0.09525)
		(layer "In4.Cu")
		(net "M_D_CPU0_SA_DQS_DN<9>")
	)
	(arc
		(start 327.11009 -247.244108)
		(mid 327.295376 -247.290144)
		(end 327.479406 -247.239282)
		(width 0.09525)
		(layer "In4.Cu")
		(net "M_D_CPU0_SA_DQS_DN<9>")
	)
	(arc
		(start 328.99096 -247.244108)
		(mid 329.175992 -247.290022)
		(end 329.359768 -247.239282)
		(width 0.09525)
		(layer "In4.Cu")
		(net "M_D_CPU0_SA_DQS_DN<9>")
	)
	(arc
		(start 332.179676 -247.239282)
		(mid 332.461108 -247.163527)
		(end 332.74254 -247.239282)
		(width 0.09525)
		(layer "In4.Cu")
		(net "M_D_CPU0_SA_DQS_DN<9>")
	)
	(arc
		(start 336.502502 -247.239282)
		(mid 336.686277 -247.290054)
		(end 336.87131 -247.244108)
		(width 0.09525)
		(layer "In4.Cu")
		(net "M_D_CPU0_SA_DQS_DN<9>")
	)
	(arc
		(start 337.819746 -247.239282)
		(mid 338.101178 -247.163527)
		(end 338.38261 -247.239282)
		(width 0.09525)
		(layer "In4.Cu")
		(net "M_D_CPU0_SA_DQS_DN<9>")
	)
	(arc
		(start 330.299568 -247.239282)
		(mid 330.581 -247.163527)
		(end 330.862432 -247.239282)
		(width 0.09525)
		(layer "In4.Cu")
		(net "M_D_CPU0_SA_DQS_DN<9>")
	)
	(arc
		(start 329.359768 -247.239282)
		(mid 329.6412 -247.163527)
		(end 329.922632 -247.239282)
		(width 0.09525)
		(layer "In4.Cu")
		(net "M_D_CPU0_SA_DQS_DN<9>")
	)
	(arc
		(start 334.059784 -247.239282)
		(mid 334.341216 -247.163527)
		(end 334.622648 -247.239282)
		(width 0.09525)
		(layer "In4.Cu")
		(net "M_D_CPU0_SA_DQS_DN<9>")
	)
	(arc
		(start 339.6996 -247.239282)
		(mid 339.933114 -247.165439)
		(end 340.17585 -247.198134)
		(width 0.09525)
		(layer "In4.Cu")
		(net "M_D_CPU0_SA_DQS_DN<9>")
	)
	(arc
		(start 339.32241 -247.239282)
		(mid 339.506185 -247.290054)
		(end 339.691218 -247.244108)
		(width 0.09525)
		(layer "In4.Cu")
		(net "M_D_CPU0_SA_DQS_DN<9>")
	)
	(arc
		(start 325.880222 -247.163336)
		(mid 326.026217 -247.182654)
		(end 326.162162 -247.239282)
		(width 0.09525)
		(layer "In4.Cu")
		(net "M_D_CPU0_SA_DQS_DN<9>")
	)
	(arc
		(start 328.042524 -247.239282)
		(mid 328.226299 -247.290054)
		(end 328.411332 -247.244108)
		(width 0.09525)
		(layer "In4.Cu")
		(net "M_D_CPU0_SA_DQS_DN<9>")
	)
	(arc
		(start 331.802486 -247.239282)
		(mid 331.986261 -247.290054)
		(end 332.171294 -247.244108)
		(width 0.09525)
		(layer "In4.Cu")
		(net "M_D_CPU0_SA_DQS_DN<9>")
	)
	(arc
		(start 335.939638 -247.239282)
		(mid 336.22107 -247.163527)
		(end 336.502502 -247.239282)
		(width 0.09525)
		(layer "In4.Cu")
		(net "M_D_CPU0_SA_DQS_DN<9>")
	)
	(arc
		(start 328.419714 -247.239282)
		(mid 328.701146 -247.163527)
		(end 328.982578 -247.239282)
		(width 0.09525)
		(layer "In4.Cu")
		(net "M_D_CPU0_SA_DQS_DN<9>")
	)
	(arc
		(start 336.879692 -247.239282)
		(mid 337.161124 -247.163527)
		(end 337.442556 -247.239282)
		(width 0.09525)
		(layer "In4.Cu")
		(net "M_D_CPU0_SA_DQS_DN<9>")
	)
	(arc
		(start 330.862432 -247.239282)
		(mid 331.046207 -247.290054)
		(end 331.23124 -247.244108)
		(width 0.09525)
		(layer "In4.Cu")
		(net "M_D_CPU0_SA_DQS_DN<9>")
	)
	(arc
		(start 340.17585 -247.198134)
		(mid 340.186178 -247.202094)
		(end 340.196424 -247.206262)
		(width 0.09525)
		(layer "In4.Cu")
		(net "M_D_CPU0_SA_DQS_DN<9>")
	)
	(arc
		(start 333.690976 -247.244108)
		(mid 333.876008 -247.290022)
		(end 334.059784 -247.239282)
		(width 0.09525)
		(layer "In4.Cu")
		(net "M_D_CPU0_SA_DQS_DN<9>")
	)
	(arc
		(start 333.11973 -247.239282)
		(mid 333.401162 -247.163527)
		(end 333.682594 -247.239282)
		(width 0.09525)
		(layer "In4.Cu")
		(net "M_D_CPU0_SA_DQS_DN<9>")
	)
	(segment
		(start 340.918038 -242.320064)
		(end 340.451186 -242.054126)
		(width 0.12954)
		(layer "F.Cu")
		(net "M_D_CPU0_SA_DQS_DN<8>")
	)
	(segment
		(start 340.196424 -242.346226)
		(end 340.297262 -242.319556)
		(width 0.09525)
		(layer "In4.Cu")
		(net "M_D_CPU0_SA_DQS_DN<8>")
	)
	(segment
		(start 302.342042 -230.877364)
		(end 304.033682 -230.877364)
		(width 0.16002)
		(layer "In4.Cu")
		(net "M_D_CPU0_SA_DQS_DN<8>")
	)
	(segment
		(start 283.675582 -229.728268)
		(end 284.022038 -230.074724)
		(width 0.16002)
		(layer "In4.Cu")
		(net "M_D_CPU0_SA_DQS_DN<8>")
	)
	(segment
		(start 324.366128 -241.521742)
		(end 324.366128 -241.647472)
		(width 0.09525)
		(layer "In4.Cu")
		(net "M_D_CPU0_SA_DQS_DN<8>")
	)
	(segment
		(start 323.920358 -241.305842)
		(end 324.150228 -241.305842)
		(width 0.09525)
		(layer "In4.Cu")
		(net "M_D_CPU0_SA_DQS_DN<8>")
	)
	(segment
		(start 324.150228 -241.305842)
		(end 324.366128 -241.521742)
		(width 0.09525)
		(layer "In4.Cu")
		(net "M_D_CPU0_SA_DQS_DN<8>")
	)
	(segment
		(start 304.033682 -230.877364)
		(end 304.337974 -230.573072)
		(width 0.16002)
		(layer "In4.Cu")
		(net "M_D_CPU0_SA_DQS_DN<8>")
	)
	(segment
		(start 324.693788 -241.975132)
		(end 325.360538 -241.975132)
		(width 0.09525)
		(layer "In4.Cu")
		(net "M_D_CPU0_SA_DQS_DN<8>")
	)
	(segment
		(start 296.79392 -230.573072)
		(end 297.27144 -230.573072)
		(width 0.16002)
		(layer "In4.Cu")
		(net "M_D_CPU0_SA_DQS_DN<8>")
	)
	(segment
		(start 333.682594 -242.379246)
		(end 333.690976 -242.384072)
		(width 0.09525)
		(layer "In4.Cu")
		(net "M_D_CPU0_SA_DQS_DN<8>")
	)
	(segment
		(start 318.272668 -241.246914)
		(end 323.837808 -241.246914)
		(width 0.16002)
		(layer "In4.Cu")
		(net "M_D_CPU0_SA_DQS_DN<8>")
	)
	(segment
		(start 293.906194 -230.05796)
		(end 294.756332 -230.908098)
		(width 0.16002)
		(layer "In4.Cu")
		(net "M_D_CPU0_SA_DQS_DN<8>")
	)
	(segment
		(start 297.27144 -230.573072)
		(end 298.155614 -229.688898)
		(width 0.16002)
		(layer "In4.Cu")
		(net "M_D_CPU0_SA_DQS_DN<8>")
	)
	(segment
		(start 288.915094 -230.908098)
		(end 289.25012 -230.573072)
		(width 0.16002)
		(layer "In4.Cu")
		(net "M_D_CPU0_SA_DQS_DN<8>")
	)
	(segment
		(start 282.923742 -229.728268)
		(end 283.675582 -229.728268)
		(width 0.16002)
		(layer "In4.Cu")
		(net "M_D_CPU0_SA_DQS_DN<8>")
	)
	(segment
		(start 332.74254 -242.379246)
		(end 332.750922 -242.384072)
		(width 0.09525)
		(layer "In4.Cu")
		(net "M_D_CPU0_SA_DQS_DN<8>")
	)
	(segment
		(start 326.524874 -242.387628)
		(end 326.539352 -242.379246)
		(width 0.09525)
		(layer "In4.Cu")
		(net "M_D_CPU0_SA_DQS_DN<8>")
	)
	(segment
		(start 296.458894 -230.908098)
		(end 296.79392 -230.573072)
		(width 0.16002)
		(layer "In4.Cu")
		(net "M_D_CPU0_SA_DQS_DN<8>")
	)
	(segment
		(start 328.982578 -242.379246)
		(end 328.99096 -242.384072)
		(width 0.09525)
		(layer "In4.Cu")
		(net "M_D_CPU0_SA_DQS_DN<8>")
	)
	(segment
		(start 291.176964 -229.688898)
		(end 291.546026 -230.05796)
		(width 0.16002)
		(layer "In4.Cu")
		(net "M_D_CPU0_SA_DQS_DN<8>")
	)
	(segment
		(start 287.245552 -230.908098)
		(end 288.915094 -230.908098)
		(width 0.16002)
		(layer "In4.Cu")
		(net "M_D_CPU0_SA_DQS_DN<8>")
	)
	(segment
		(start 299.089826 -230.05796)
		(end 301.522638 -230.05796)
		(width 0.16002)
		(layer "In4.Cu")
		(net "M_D_CPU0_SA_DQS_DN<8>")
	)
	(segment
		(start 301.522638 -230.05796)
		(end 302.342042 -230.877364)
		(width 0.16002)
		(layer "In4.Cu")
		(net "M_D_CPU0_SA_DQS_DN<8>")
	)
	(segment
		(start 325.688706 -242.3033)
		(end 325.880222 -242.3033)
		(width 0.09525)
		(layer "In4.Cu")
		(net "M_D_CPU0_SA_DQS_DN<8>")
	)
	(segment
		(start 323.86143 -241.246914)
		(end 323.920358 -241.305842)
		(width 0.09525)
		(layer "In4.Cu")
		(net "M_D_CPU0_SA_DQS_DN<8>")
	)
	(segment
		(start 305.647344 -230.908098)
		(end 307.933852 -230.908098)
		(width 0.16002)
		(layer "In4.Cu")
		(net "M_D_CPU0_SA_DQS_DN<8>")
	)
	(segment
		(start 289.25012 -230.573072)
		(end 289.72764 -230.573072)
		(width 0.16002)
		(layer "In4.Cu")
		(net "M_D_CPU0_SA_DQS_DN<8>")
	)
	(segment
		(start 284.022038 -230.074724)
		(end 286.412178 -230.074724)
		(width 0.16002)
		(layer "In4.Cu")
		(net "M_D_CPU0_SA_DQS_DN<8>")
	)
	(segment
		(start 326.539352 -242.379246)
		(end 326.56018 -242.367054)
		(width 0.09525)
		(layer "In4.Cu")
		(net "M_D_CPU0_SA_DQS_DN<8>")
	)
	(segment
		(start 337.442556 -242.379246)
		(end 337.450938 -242.384072)
		(width 0.09525)
		(layer "In4.Cu")
		(net "M_D_CPU0_SA_DQS_DN<8>")
	)
	(segment
		(start 331.23124 -242.384072)
		(end 331.239622 -242.379246)
		(width 0.09525)
		(layer "In4.Cu")
		(net "M_D_CPU0_SA_DQS_DN<8>")
	)
	(segment
		(start 291.546026 -230.05796)
		(end 293.906194 -230.05796)
		(width 0.16002)
		(layer "In4.Cu")
		(net "M_D_CPU0_SA_DQS_DN<8>")
	)
	(segment
		(start 340.297262 -242.319556)
		(end 340.451186 -242.054126)
		(width 0.09525)
		(layer "In4.Cu")
		(net "M_D_CPU0_SA_DQS_DN<8>")
	)
	(segment
		(start 339.691218 -242.384072)
		(end 339.6996 -242.379246)
		(width 0.09525)
		(layer "In4.Cu")
		(net "M_D_CPU0_SA_DQS_DN<8>")
	)
	(segment
		(start 307.933852 -230.908098)
		(end 318.272668 -241.246914)
		(width 0.16002)
		(layer "In4.Cu")
		(net "M_D_CPU0_SA_DQS_DN<8>")
	)
	(segment
		(start 298.720764 -229.688898)
		(end 299.089826 -230.05796)
		(width 0.16002)
		(layer "In4.Cu")
		(net "M_D_CPU0_SA_DQS_DN<8>")
	)
	(segment
		(start 325.360538 -241.975132)
		(end 325.688706 -242.3033)
		(width 0.09525)
		(layer "In4.Cu")
		(net "M_D_CPU0_SA_DQS_DN<8>")
	)
	(segment
		(start 282.743148 -229.908862)
		(end 282.923742 -229.728268)
		(width 0.16002)
		(layer "In4.Cu")
		(net "M_D_CPU0_SA_DQS_DN<8>")
	)
	(segment
		(start 335.931256 -242.384072)
		(end 335.939638 -242.379246)
		(width 0.09525)
		(layer "In4.Cu")
		(net "M_D_CPU0_SA_DQS_DN<8>")
	)
	(segment
		(start 324.366128 -241.647472)
		(end 324.693788 -241.975132)
		(width 0.09525)
		(layer "In4.Cu")
		(net "M_D_CPU0_SA_DQS_DN<8>")
	)
	(segment
		(start 298.155614 -229.688898)
		(end 298.720764 -229.688898)
		(width 0.16002)
		(layer "In4.Cu")
		(net "M_D_CPU0_SA_DQS_DN<8>")
	)
	(segment
		(start 290.611814 -229.688898)
		(end 291.176964 -229.688898)
		(width 0.16002)
		(layer "In4.Cu")
		(net "M_D_CPU0_SA_DQS_DN<8>")
	)
	(segment
		(start 294.756332 -230.908098)
		(end 296.458894 -230.908098)
		(width 0.16002)
		(layer "In4.Cu")
		(net "M_D_CPU0_SA_DQS_DN<8>")
	)
	(segment
		(start 336.87131 -242.384072)
		(end 336.879692 -242.379246)
		(width 0.09525)
		(layer "In4.Cu")
		(net "M_D_CPU0_SA_DQS_DN<8>")
	)
	(segment
		(start 327.467722 -242.386104)
		(end 327.47966 -242.379246)
		(width 0.09525)
		(layer "In4.Cu")
		(net "M_D_CPU0_SA_DQS_DN<8>")
	)
	(segment
		(start 332.171294 -242.384072)
		(end 332.179676 -242.379246)
		(width 0.09525)
		(layer "In4.Cu")
		(net "M_D_CPU0_SA_DQS_DN<8>")
	)
	(segment
		(start 328.411332 -242.384072)
		(end 328.419714 -242.379246)
		(width 0.09525)
		(layer "In4.Cu")
		(net "M_D_CPU0_SA_DQS_DN<8>")
	)
	(segment
		(start 305.312318 -230.573072)
		(end 305.647344 -230.908098)
		(width 0.16002)
		(layer "In4.Cu")
		(net "M_D_CPU0_SA_DQS_DN<8>")
	)
	(segment
		(start 289.72764 -230.573072)
		(end 290.611814 -229.688898)
		(width 0.16002)
		(layer "In4.Cu")
		(net "M_D_CPU0_SA_DQS_DN<8>")
	)
	(segment
		(start 323.837808 -241.246914)
		(end 323.86143 -241.246914)
		(width 0.09525)
		(layer "In4.Cu")
		(net "M_D_CPU0_SA_DQS_DN<8>")
	)
	(segment
		(start 304.337974 -230.573072)
		(end 305.312318 -230.573072)
		(width 0.16002)
		(layer "In4.Cu")
		(net "M_D_CPU0_SA_DQS_DN<8>")
	)
	(segment
		(start 280.635964 -229.63505)
		(end 280.909776 -229.908862)
		(width 0.16002)
		(layer "In4.Cu")
		(net "M_D_CPU0_SA_DQS_DN<8>")
	)
	(segment
		(start 286.412178 -230.074724)
		(end 287.245552 -230.908098)
		(width 0.16002)
		(layer "In4.Cu")
		(net "M_D_CPU0_SA_DQS_DN<8>")
	)
	(segment
		(start 280.909776 -229.908862)
		(end 282.743148 -229.908862)
		(width 0.16002)
		(layer "In4.Cu")
		(net "M_D_CPU0_SA_DQS_DN<8>")
	)
	(arc
		(start 327.102216 -242.379246)
		(mid 327.284086 -242.430111)
		(end 327.467722 -242.386104)
		(width 0.09525)
		(layer "In4.Cu")
		(net "M_D_CPU0_SA_DQS_DN<8>")
	)
	(arc
		(start 339.32241 -242.379246)
		(mid 339.506185 -242.430018)
		(end 339.691218 -242.384072)
		(width 0.09525)
		(layer "In4.Cu")
		(net "M_D_CPU0_SA_DQS_DN<8>")
	)
	(arc
		(start 334.999584 -242.379246)
		(mid 335.281016 -242.303491)
		(end 335.562448 -242.379246)
		(width 0.09525)
		(layer "In4.Cu")
		(net "M_D_CPU0_SA_DQS_DN<8>")
	)
	(arc
		(start 328.419714 -242.379246)
		(mid 328.701146 -242.303491)
		(end 328.982578 -242.379246)
		(width 0.09525)
		(layer "In4.Cu")
		(net "M_D_CPU0_SA_DQS_DN<8>")
	)
	(arc
		(start 328.99096 -242.384072)
		(mid 329.175992 -242.429986)
		(end 329.359768 -242.379246)
		(width 0.09525)
		(layer "In4.Cu")
		(net "M_D_CPU0_SA_DQS_DN<8>")
	)
	(arc
		(start 334.059784 -242.379246)
		(mid 334.341216 -242.303491)
		(end 334.622648 -242.379246)
		(width 0.09525)
		(layer "In4.Cu")
		(net "M_D_CPU0_SA_DQS_DN<8>")
	)
	(arc
		(start 328.042524 -242.379246)
		(mid 328.226299 -242.430018)
		(end 328.411332 -242.384072)
		(width 0.09525)
		(layer "In4.Cu")
		(net "M_D_CPU0_SA_DQS_DN<8>")
	)
	(arc
		(start 336.502502 -242.379246)
		(mid 336.686277 -242.430018)
		(end 336.87131 -242.384072)
		(width 0.09525)
		(layer "In4.Cu")
		(net "M_D_CPU0_SA_DQS_DN<8>")
	)
	(arc
		(start 337.819746 -242.379246)
		(mid 338.101178 -242.303491)
		(end 338.38261 -242.379246)
		(width 0.09525)
		(layer "In4.Cu")
		(net "M_D_CPU0_SA_DQS_DN<8>")
	)
	(arc
		(start 340.17585 -242.338098)
		(mid 340.186178 -242.342058)
		(end 340.196424 -242.346226)
		(width 0.09525)
		(layer "In4.Cu")
		(net "M_D_CPU0_SA_DQS_DN<8>")
	)
	(arc
		(start 329.922632 -242.379246)
		(mid 330.1111 -242.429923)
		(end 330.299568 -242.379246)
		(width 0.09525)
		(layer "In4.Cu")
		(net "M_D_CPU0_SA_DQS_DN<8>")
	)
	(arc
		(start 332.179676 -242.379246)
		(mid 332.461108 -242.303491)
		(end 332.74254 -242.379246)
		(width 0.09525)
		(layer "In4.Cu")
		(net "M_D_CPU0_SA_DQS_DN<8>")
	)
	(arc
		(start 338.759546 -242.379246)
		(mid 339.040978 -242.303491)
		(end 339.32241 -242.379246)
		(width 0.09525)
		(layer "In4.Cu")
		(net "M_D_CPU0_SA_DQS_DN<8>")
	)
	(arc
		(start 333.690976 -242.384072)
		(mid 333.876008 -242.429986)
		(end 334.059784 -242.379246)
		(width 0.09525)
		(layer "In4.Cu")
		(net "M_D_CPU0_SA_DQS_DN<8>")
	)
	(arc
		(start 332.750922 -242.384072)
		(mid 332.935954 -242.429986)
		(end 333.11973 -242.379246)
		(width 0.09525)
		(layer "In4.Cu")
		(net "M_D_CPU0_SA_DQS_DN<8>")
	)
	(arc
		(start 331.802486 -242.379246)
		(mid 331.986261 -242.430018)
		(end 332.171294 -242.384072)
		(width 0.09525)
		(layer "In4.Cu")
		(net "M_D_CPU0_SA_DQS_DN<8>")
	)
	(arc
		(start 331.239622 -242.379246)
		(mid 331.521054 -242.303491)
		(end 331.802486 -242.379246)
		(width 0.09525)
		(layer "In4.Cu")
		(net "M_D_CPU0_SA_DQS_DN<8>")
	)
	(arc
		(start 334.622648 -242.379246)
		(mid 334.811116 -242.429923)
		(end 334.999584 -242.379246)
		(width 0.09525)
		(layer "In4.Cu")
		(net "M_D_CPU0_SA_DQS_DN<8>")
	)
	(arc
		(start 326.56018 -242.367054)
		(mid 326.832785 -242.303258)
		(end 327.102216 -242.379246)
		(width 0.09525)
		(layer "In4.Cu")
		(net "M_D_CPU0_SA_DQS_DN<8>")
	)
	(arc
		(start 339.6996 -242.379246)
		(mid 339.933114 -242.305403)
		(end 340.17585 -242.338098)
		(width 0.09525)
		(layer "In4.Cu")
		(net "M_D_CPU0_SA_DQS_DN<8>")
	)
	(arc
		(start 335.939638 -242.379246)
		(mid 336.22107 -242.303491)
		(end 336.502502 -242.379246)
		(width 0.09525)
		(layer "In4.Cu")
		(net "M_D_CPU0_SA_DQS_DN<8>")
	)
	(arc
		(start 329.359768 -242.379246)
		(mid 329.6412 -242.303491)
		(end 329.922632 -242.379246)
		(width 0.09525)
		(layer "In4.Cu")
		(net "M_D_CPU0_SA_DQS_DN<8>")
	)
	(arc
		(start 326.162162 -242.379246)
		(mid 326.342441 -242.430077)
		(end 326.524874 -242.387628)
		(width 0.09525)
		(layer "In4.Cu")
		(net "M_D_CPU0_SA_DQS_DN<8>")
	)
	(arc
		(start 337.450938 -242.384072)
		(mid 337.63597 -242.429986)
		(end 337.819746 -242.379246)
		(width 0.09525)
		(layer "In4.Cu")
		(net "M_D_CPU0_SA_DQS_DN<8>")
	)
	(arc
		(start 335.562448 -242.379246)
		(mid 335.746223 -242.430018)
		(end 335.931256 -242.384072)
		(width 0.09525)
		(layer "In4.Cu")
		(net "M_D_CPU0_SA_DQS_DN<8>")
	)
	(arc
		(start 338.38261 -242.379246)
		(mid 338.571078 -242.429923)
		(end 338.759546 -242.379246)
		(width 0.09525)
		(layer "In4.Cu")
		(net "M_D_CPU0_SA_DQS_DN<8>")
	)
	(arc
		(start 325.880222 -242.3033)
		(mid 326.026217 -242.322618)
		(end 326.162162 -242.379246)
		(width 0.09525)
		(layer "In4.Cu")
		(net "M_D_CPU0_SA_DQS_DN<8>")
	)
	(arc
		(start 327.47966 -242.379246)
		(mid 327.761092 -242.303491)
		(end 328.042524 -242.379246)
		(width 0.09525)
		(layer "In4.Cu")
		(net "M_D_CPU0_SA_DQS_DN<8>")
	)
	(arc
		(start 333.11973 -242.379246)
		(mid 333.401162 -242.303491)
		(end 333.682594 -242.379246)
		(width 0.09525)
		(layer "In4.Cu")
		(net "M_D_CPU0_SA_DQS_DN<8>")
	)
	(arc
		(start 330.862432 -242.379246)
		(mid 331.046207 -242.430018)
		(end 331.23124 -242.384072)
		(width 0.09525)
		(layer "In4.Cu")
		(net "M_D_CPU0_SA_DQS_DN<8>")
	)
	(arc
		(start 330.299568 -242.379246)
		(mid 330.581 -242.303491)
		(end 330.862432 -242.379246)
		(width 0.09525)
		(layer "In4.Cu")
		(net "M_D_CPU0_SA_DQS_DN<8>")
	)
	(arc
		(start 336.879692 -242.379246)
		(mid 337.161124 -242.303491)
		(end 337.442556 -242.379246)
		(width 0.09525)
		(layer "In4.Cu")
		(net "M_D_CPU0_SA_DQS_DN<8>")
	)
	(segment
		(start 340.918038 -237.460028)
		(end 340.451186 -237.19409)
		(width 0.12954)
		(layer "F.Cu")
		(net "M_D_CPU0_SA_DQS_DN<7>")
	)
	(segment
		(start 284.022038 -220.72473)
		(end 286.412178 -220.72473)
		(width 0.16002)
		(layer "In4.Cu")
		(net "M_D_CPU0_SA_DQS_DN<7>")
	)
	(segment
		(start 323.978524 -235.68787)
		(end 324.190106 -235.68787)
		(width 0.09525)
		(layer "In4.Cu")
		(net "M_D_CPU0_SA_DQS_DN<7>")
	)
	(segment
		(start 308.708298 -222.594932)
		(end 321.742308 -235.628942)
		(width 0.16002)
		(layer "In4.Cu")
		(net "M_D_CPU0_SA_DQS_DN<7>")
	)
	(segment
		(start 282.824936 -220.558868)
		(end 283.00553 -220.378274)
		(width 0.16002)
		(layer "In4.Cu")
		(net "M_D_CPU0_SA_DQS_DN<7>")
	)
	(segment
		(start 340.297262 -237.45952)
		(end 340.451186 -237.19409)
		(width 0.09525)
		(layer "In4.Cu")
		(net "M_D_CPU0_SA_DQS_DN<7>")
	)
	(segment
		(start 332.171294 -237.524036)
		(end 332.179676 -237.51921)
		(width 0.09525)
		(layer "In4.Cu")
		(net "M_D_CPU0_SA_DQS_DN<7>")
	)
	(segment
		(start 324.955154 -236.048042)
		(end 325.332598 -236.425486)
		(width 0.09525)
		(layer "In4.Cu")
		(net "M_D_CPU0_SA_DQS_DN<7>")
	)
	(segment
		(start 327.481438 -237.51921)
		(end 327.50887 -237.503208)
		(width 0.09525)
		(layer "In4.Cu")
		(net "M_D_CPU0_SA_DQS_DN<7>")
	)
	(segment
		(start 297.27144 -221.223078)
		(end 298.155614 -220.338904)
		(width 0.16002)
		(layer "In4.Cu")
		(net "M_D_CPU0_SA_DQS_DN<7>")
	)
	(segment
		(start 286.412178 -220.72473)
		(end 287.245298 -221.55785)
		(width 0.16002)
		(layer "In4.Cu")
		(net "M_D_CPU0_SA_DQS_DN<7>")
	)
	(segment
		(start 289.25012 -221.223078)
		(end 289.72764 -221.223078)
		(width 0.16002)
		(layer "In4.Cu")
		(net "M_D_CPU0_SA_DQS_DN<7>")
	)
	(segment
		(start 283.675582 -220.378274)
		(end 284.022038 -220.72473)
		(width 0.16002)
		(layer "In4.Cu")
		(net "M_D_CPU0_SA_DQS_DN<7>")
	)
	(segment
		(start 337.442556 -237.51921)
		(end 337.450938 -237.524036)
		(width 0.09525)
		(layer "In4.Cu")
		(net "M_D_CPU0_SA_DQS_DN<7>")
	)
	(segment
		(start 301.50181 -220.707966)
		(end 302.321214 -221.52737)
		(width 0.16002)
		(layer "In4.Cu")
		(net "M_D_CPU0_SA_DQS_DN<7>")
	)
	(segment
		(start 333.682594 -237.51921)
		(end 333.690976 -237.524036)
		(width 0.09525)
		(layer "In4.Cu")
		(net "M_D_CPU0_SA_DQS_DN<7>")
	)
	(segment
		(start 339.691218 -237.524036)
		(end 339.6996 -237.51921)
		(width 0.09525)
		(layer "In4.Cu")
		(net "M_D_CPU0_SA_DQS_DN<7>")
	)
	(segment
		(start 296.459148 -221.55785)
		(end 296.79392 -221.223078)
		(width 0.16002)
		(layer "In4.Cu")
		(net "M_D_CPU0_SA_DQS_DN<7>")
	)
	(segment
		(start 304.033682 -221.52737)
		(end 304.337974 -221.223078)
		(width 0.16002)
		(layer "In4.Cu")
		(net "M_D_CPU0_SA_DQS_DN<7>")
	)
	(segment
		(start 283.00553 -220.378274)
		(end 283.675582 -220.378274)
		(width 0.16002)
		(layer "In4.Cu")
		(net "M_D_CPU0_SA_DQS_DN<7>")
	)
	(segment
		(start 324.190106 -235.68787)
		(end 324.550278 -236.048042)
		(width 0.09525)
		(layer "In4.Cu")
		(net "M_D_CPU0_SA_DQS_DN<7>")
	)
	(segment
		(start 280.635964 -220.285056)
		(end 280.909776 -220.558868)
		(width 0.16002)
		(layer "In4.Cu")
		(net "M_D_CPU0_SA_DQS_DN<7>")
	)
	(segment
		(start 332.74254 -237.51921)
		(end 332.750922 -237.524036)
		(width 0.09525)
		(layer "In4.Cu")
		(net "M_D_CPU0_SA_DQS_DN<7>")
	)
	(segment
		(start 326.186546 -237.57128)
		(end 326.351138 -237.57128)
		(width 0.09525)
		(layer "In4.Cu")
		(net "M_D_CPU0_SA_DQS_DN<7>")
	)
	(segment
		(start 328.411332 -237.524036)
		(end 328.419714 -237.51921)
		(width 0.09525)
		(layer "In4.Cu")
		(net "M_D_CPU0_SA_DQS_DN<7>")
	)
	(segment
		(start 293.906194 -220.707966)
		(end 294.756078 -221.55785)
		(width 0.16002)
		(layer "In4.Cu")
		(net "M_D_CPU0_SA_DQS_DN<7>")
	)
	(segment
		(start 302.321214 -221.52737)
		(end 304.033682 -221.52737)
		(width 0.16002)
		(layer "In4.Cu")
		(net "M_D_CPU0_SA_DQS_DN<7>")
	)
	(segment
		(start 299.089826 -220.707966)
		(end 301.50181 -220.707966)
		(width 0.16002)
		(layer "In4.Cu")
		(net "M_D_CPU0_SA_DQS_DN<7>")
	)
	(segment
		(start 308.027578 -221.55785)
		(end 308.708298 -222.23857)
		(width 0.16002)
		(layer "In4.Cu")
		(net "M_D_CPU0_SA_DQS_DN<7>")
	)
	(segment
		(start 294.756078 -221.55785)
		(end 296.459148 -221.55785)
		(width 0.16002)
		(layer "In4.Cu")
		(net "M_D_CPU0_SA_DQS_DN<7>")
	)
	(segment
		(start 308.708298 -222.23857)
		(end 308.708298 -222.594932)
		(width 0.16002)
		(layer "In4.Cu")
		(net "M_D_CPU0_SA_DQS_DN<7>")
	)
	(segment
		(start 324.550278 -236.048042)
		(end 324.955154 -236.048042)
		(width 0.09525)
		(layer "In4.Cu")
		(net "M_D_CPU0_SA_DQS_DN<7>")
	)
	(segment
		(start 298.720764 -220.338904)
		(end 299.089826 -220.707966)
		(width 0.16002)
		(layer "In4.Cu")
		(net "M_D_CPU0_SA_DQS_DN<7>")
	)
	(segment
		(start 325.332598 -236.425486)
		(end 325.332598 -236.717332)
		(width 0.09525)
		(layer "In4.Cu")
		(net "M_D_CPU0_SA_DQS_DN<7>")
	)
	(segment
		(start 287.245298 -221.55785)
		(end 288.915348 -221.55785)
		(width 0.16002)
		(layer "In4.Cu")
		(net "M_D_CPU0_SA_DQS_DN<7>")
	)
	(segment
		(start 304.337974 -221.223078)
		(end 305.277266 -221.223078)
		(width 0.16002)
		(layer "In4.Cu")
		(net "M_D_CPU0_SA_DQS_DN<7>")
	)
	(segment
		(start 325.332598 -236.717332)
		(end 326.186546 -237.57128)
		(width 0.09525)
		(layer "In4.Cu")
		(net "M_D_CPU0_SA_DQS_DN<7>")
	)
	(segment
		(start 305.277266 -221.223078)
		(end 305.612038 -221.55785)
		(width 0.16002)
		(layer "In4.Cu")
		(net "M_D_CPU0_SA_DQS_DN<7>")
	)
	(segment
		(start 290.611814 -220.338904)
		(end 291.176964 -220.338904)
		(width 0.16002)
		(layer "In4.Cu")
		(net "M_D_CPU0_SA_DQS_DN<7>")
	)
	(segment
		(start 321.742308 -235.628942)
		(end 323.895974 -235.628942)
		(width 0.16002)
		(layer "In4.Cu")
		(net "M_D_CPU0_SA_DQS_DN<7>")
	)
	(segment
		(start 331.23124 -237.524036)
		(end 331.239622 -237.51921)
		(width 0.09525)
		(layer "In4.Cu")
		(net "M_D_CPU0_SA_DQS_DN<7>")
	)
	(segment
		(start 335.931256 -237.524036)
		(end 335.939638 -237.51921)
		(width 0.09525)
		(layer "In4.Cu")
		(net "M_D_CPU0_SA_DQS_DN<7>")
	)
	(segment
		(start 336.87131 -237.524036)
		(end 336.879692 -237.51921)
		(width 0.09525)
		(layer "In4.Cu")
		(net "M_D_CPU0_SA_DQS_DN<7>")
	)
	(segment
		(start 288.915348 -221.55785)
		(end 289.25012 -221.223078)
		(width 0.16002)
		(layer "In4.Cu")
		(net "M_D_CPU0_SA_DQS_DN<7>")
	)
	(segment
		(start 296.79392 -221.223078)
		(end 297.27144 -221.223078)
		(width 0.16002)
		(layer "In4.Cu")
		(net "M_D_CPU0_SA_DQS_DN<7>")
	)
	(segment
		(start 323.919596 -235.628942)
		(end 323.978524 -235.68787)
		(width 0.09525)
		(layer "In4.Cu")
		(net "M_D_CPU0_SA_DQS_DN<7>")
	)
	(segment
		(start 280.909776 -220.558868)
		(end 282.824936 -220.558868)
		(width 0.16002)
		(layer "In4.Cu")
		(net "M_D_CPU0_SA_DQS_DN<7>")
	)
	(segment
		(start 291.176964 -220.338904)
		(end 291.546026 -220.707966)
		(width 0.16002)
		(layer "In4.Cu")
		(net "M_D_CPU0_SA_DQS_DN<7>")
	)
	(segment
		(start 291.546026 -220.707966)
		(end 293.906194 -220.707966)
		(width 0.16002)
		(layer "In4.Cu")
		(net "M_D_CPU0_SA_DQS_DN<7>")
	)
	(segment
		(start 340.196424 -237.48619)
		(end 340.297262 -237.45952)
		(width 0.09525)
		(layer "In4.Cu")
		(net "M_D_CPU0_SA_DQS_DN<7>")
	)
	(segment
		(start 323.895974 -235.628942)
		(end 323.919596 -235.628942)
		(width 0.09525)
		(layer "In4.Cu")
		(net "M_D_CPU0_SA_DQS_DN<7>")
	)
	(segment
		(start 327.081642 -237.50524)
		(end 327.105518 -237.51921)
		(width 0.09525)
		(layer "In4.Cu")
		(net "M_D_CPU0_SA_DQS_DN<7>")
	)
	(segment
		(start 289.72764 -221.223078)
		(end 290.611814 -220.338904)
		(width 0.16002)
		(layer "In4.Cu")
		(net "M_D_CPU0_SA_DQS_DN<7>")
	)
	(segment
		(start 305.612038 -221.55785)
		(end 308.027578 -221.55785)
		(width 0.16002)
		(layer "In4.Cu")
		(net "M_D_CPU0_SA_DQS_DN<7>")
	)
	(segment
		(start 298.155614 -220.338904)
		(end 298.720764 -220.338904)
		(width 0.16002)
		(layer "In4.Cu")
		(net "M_D_CPU0_SA_DQS_DN<7>")
	)
	(segment
		(start 327.464674 -237.528862)
		(end 327.481438 -237.51921)
		(width 0.09525)
		(layer "In4.Cu")
		(net "M_D_CPU0_SA_DQS_DN<7>")
	)
	(segment
		(start 328.982578 -237.51921)
		(end 328.99096 -237.524036)
		(width 0.09525)
		(layer "In4.Cu")
		(net "M_D_CPU0_SA_DQS_DN<7>")
	)
	(arc
		(start 328.042524 -237.51921)
		(mid 328.226299 -237.569982)
		(end 328.411332 -237.524036)
		(width 0.09525)
		(layer "In4.Cu")
		(net "M_D_CPU0_SA_DQS_DN<7>")
	)
	(arc
		(start 331.802486 -237.51921)
		(mid 331.986261 -237.569982)
		(end 332.171294 -237.524036)
		(width 0.09525)
		(layer "In4.Cu")
		(net "M_D_CPU0_SA_DQS_DN<7>")
	)
	(arc
		(start 328.419714 -237.51921)
		(mid 328.701146 -237.443455)
		(end 328.982578 -237.51921)
		(width 0.09525)
		(layer "In4.Cu")
		(net "M_D_CPU0_SA_DQS_DN<7>")
	)
	(arc
		(start 335.939638 -237.51921)
		(mid 336.22107 -237.443455)
		(end 336.502502 -237.51921)
		(width 0.09525)
		(layer "In4.Cu")
		(net "M_D_CPU0_SA_DQS_DN<7>")
	)
	(arc
		(start 334.622648 -237.51921)
		(mid 334.811116 -237.569887)
		(end 334.999584 -237.51921)
		(width 0.09525)
		(layer "In4.Cu")
		(net "M_D_CPU0_SA_DQS_DN<7>")
	)
	(arc
		(start 334.059784 -237.51921)
		(mid 334.341216 -237.443455)
		(end 334.622648 -237.51921)
		(width 0.09525)
		(layer "In4.Cu")
		(net "M_D_CPU0_SA_DQS_DN<7>")
	)
	(arc
		(start 340.17585 -237.478062)
		(mid 340.186178 -237.482022)
		(end 340.196424 -237.48619)
		(width 0.09525)
		(layer "In4.Cu")
		(net "M_D_CPU0_SA_DQS_DN<7>")
	)
	(arc
		(start 330.299568 -237.51921)
		(mid 330.581 -237.443455)
		(end 330.862432 -237.51921)
		(width 0.09525)
		(layer "In4.Cu")
		(net "M_D_CPU0_SA_DQS_DN<7>")
	)
	(arc
		(start 329.922632 -237.51921)
		(mid 330.1111 -237.569887)
		(end 330.299568 -237.51921)
		(width 0.09525)
		(layer "In4.Cu")
		(net "M_D_CPU0_SA_DQS_DN<7>")
	)
	(arc
		(start 332.750922 -237.524036)
		(mid 332.935954 -237.56995)
		(end 333.11973 -237.51921)
		(width 0.09525)
		(layer "In4.Cu")
		(net "M_D_CPU0_SA_DQS_DN<7>")
	)
	(arc
		(start 337.819746 -237.51921)
		(mid 338.101178 -237.443455)
		(end 338.38261 -237.51921)
		(width 0.09525)
		(layer "In4.Cu")
		(net "M_D_CPU0_SA_DQS_DN<7>")
	)
	(arc
		(start 337.450938 -237.524036)
		(mid 337.63597 -237.56995)
		(end 337.819746 -237.51921)
		(width 0.09525)
		(layer "In4.Cu")
		(net "M_D_CPU0_SA_DQS_DN<7>")
	)
	(arc
		(start 333.690976 -237.524036)
		(mid 333.876008 -237.56995)
		(end 334.059784 -237.51921)
		(width 0.09525)
		(layer "In4.Cu")
		(net "M_D_CPU0_SA_DQS_DN<7>")
	)
	(arc
		(start 332.179676 -237.51921)
		(mid 332.461108 -237.443455)
		(end 332.74254 -237.51921)
		(width 0.09525)
		(layer "In4.Cu")
		(net "M_D_CPU0_SA_DQS_DN<7>")
	)
	(arc
		(start 339.32241 -237.51921)
		(mid 339.506185 -237.569982)
		(end 339.691218 -237.524036)
		(width 0.09525)
		(layer "In4.Cu")
		(net "M_D_CPU0_SA_DQS_DN<7>")
	)
	(arc
		(start 326.540876 -237.519464)
		(mid 326.809421 -237.442971)
		(end 327.081642 -237.50524)
		(width 0.09525)
		(layer "In4.Cu")
		(net "M_D_CPU0_SA_DQS_DN<7>")
	)
	(arc
		(start 330.862432 -237.51921)
		(mid 331.046207 -237.569982)
		(end 331.23124 -237.524036)
		(width 0.09525)
		(layer "In4.Cu")
		(net "M_D_CPU0_SA_DQS_DN<7>")
	)
	(arc
		(start 334.999584 -237.51921)
		(mid 335.281016 -237.443455)
		(end 335.562448 -237.51921)
		(width 0.09525)
		(layer "In4.Cu")
		(net "M_D_CPU0_SA_DQS_DN<7>")
	)
	(arc
		(start 326.351138 -237.57128)
		(mid 326.449444 -237.55796)
		(end 326.540876 -237.519464)
		(width 0.09525)
		(layer "In4.Cu")
		(net "M_D_CPU0_SA_DQS_DN<7>")
	)
	(arc
		(start 329.359768 -237.51921)
		(mid 329.6412 -237.443455)
		(end 329.922632 -237.51921)
		(width 0.09525)
		(layer "In4.Cu")
		(net "M_D_CPU0_SA_DQS_DN<7>")
	)
	(arc
		(start 336.502502 -237.51921)
		(mid 336.686277 -237.569982)
		(end 336.87131 -237.524036)
		(width 0.09525)
		(layer "In4.Cu")
		(net "M_D_CPU0_SA_DQS_DN<7>")
	)
	(arc
		(start 336.879692 -237.51921)
		(mid 337.161124 -237.443455)
		(end 337.442556 -237.51921)
		(width 0.09525)
		(layer "In4.Cu")
		(net "M_D_CPU0_SA_DQS_DN<7>")
	)
	(arc
		(start 327.50887 -237.503208)
		(mid 327.777713 -237.443657)
		(end 328.042524 -237.51921)
		(width 0.09525)
		(layer "In4.Cu")
		(net "M_D_CPU0_SA_DQS_DN<7>")
	)
	(arc
		(start 328.99096 -237.524036)
		(mid 329.175992 -237.56995)
		(end 329.359768 -237.51921)
		(width 0.09525)
		(layer "In4.Cu")
		(net "M_D_CPU0_SA_DQS_DN<7>")
	)
	(arc
		(start 338.759546 -237.51921)
		(mid 339.040978 -237.443455)
		(end 339.32241 -237.51921)
		(width 0.09525)
		(layer "In4.Cu")
		(net "M_D_CPU0_SA_DQS_DN<7>")
	)
	(arc
		(start 333.11973 -237.51921)
		(mid 333.401162 -237.443455)
		(end 333.682594 -237.51921)
		(width 0.09525)
		(layer "In4.Cu")
		(net "M_D_CPU0_SA_DQS_DN<7>")
	)
	(arc
		(start 331.239622 -237.51921)
		(mid 331.521054 -237.443455)
		(end 331.802486 -237.51921)
		(width 0.09525)
		(layer "In4.Cu")
		(net "M_D_CPU0_SA_DQS_DN<7>")
	)
	(arc
		(start 339.6996 -237.51921)
		(mid 339.933114 -237.445367)
		(end 340.17585 -237.478062)
		(width 0.09525)
		(layer "In4.Cu")
		(net "M_D_CPU0_SA_DQS_DN<7>")
	)
	(arc
		(start 335.562448 -237.51921)
		(mid 335.746223 -237.569982)
		(end 335.931256 -237.524036)
		(width 0.09525)
		(layer "In4.Cu")
		(net "M_D_CPU0_SA_DQS_DN<7>")
	)
	(arc
		(start 338.38261 -237.51921)
		(mid 338.571078 -237.569887)
		(end 338.759546 -237.51921)
		(width 0.09525)
		(layer "In4.Cu")
		(net "M_D_CPU0_SA_DQS_DN<7>")
	)
	(arc
		(start 327.105518 -237.51921)
		(mid 327.28387 -237.569751)
		(end 327.464674 -237.528862)
		(width 0.09525)
		(layer "In4.Cu")
		(net "M_D_CPU0_SA_DQS_DN<7>")
	)
	(segment
		(start 340.918038 -232.599992)
		(end 340.451186 -232.334054)
		(width 0.12954)
		(layer "F.Cu")
		(net "M_D_CPU0_SA_DQS_DN<6>")
	)
	(segment
		(start 328.411332 -232.664)
		(end 328.419714 -232.659174)
		(width 0.09525)
		(layer "In4.Cu")
		(net "M_D_CPU0_SA_DQS_DN<6>")
	)
	(segment
		(start 282.791154 -211.208874)
		(end 282.969716 -211.030312)
		(width 0.16002)
		(layer "In4.Cu")
		(net "M_D_CPU0_SA_DQS_DN<6>")
	)
	(segment
		(start 333.682594 -232.659174)
		(end 333.690976 -232.664)
		(width 0.09525)
		(layer "In4.Cu")
		(net "M_D_CPU0_SA_DQS_DN<6>")
	)
	(segment
		(start 284.03804 -211.388452)
		(end 286.44342 -211.388452)
		(width 0.16002)
		(layer "In4.Cu")
		(net "M_D_CPU0_SA_DQS_DN<6>")
	)
	(segment
		(start 299.068236 -211.357972)
		(end 301.51832 -211.357972)
		(width 0.16002)
		(layer "In4.Cu")
		(net "M_D_CPU0_SA_DQS_DN<6>")
	)
	(segment
		(start 302.048672 -211.888324)
		(end 305.332892 -211.888324)
		(width 0.16002)
		(layer "In4.Cu")
		(net "M_D_CPU0_SA_DQS_DN<6>")
	)
	(segment
		(start 283.6799 -211.030312)
		(end 284.03804 -211.388452)
		(width 0.16002)
		(layer "In4.Cu")
		(net "M_D_CPU0_SA_DQS_DN<6>")
	)
	(segment
		(start 328.982578 -232.659174)
		(end 328.99096 -232.664)
		(width 0.09525)
		(layer "In4.Cu")
		(net "M_D_CPU0_SA_DQS_DN<6>")
	)
	(segment
		(start 337.442556 -232.659174)
		(end 337.450938 -232.664)
		(width 0.09525)
		(layer "In4.Cu")
		(net "M_D_CPU0_SA_DQS_DN<6>")
	)
	(segment
		(start 287.262824 -212.207856)
		(end 288.924492 -212.207856)
		(width 0.16002)
		(layer "In4.Cu")
		(net "M_D_CPU0_SA_DQS_DN<6>")
	)
	(segment
		(start 301.51832 -211.357972)
		(end 302.048672 -211.888324)
		(width 0.16002)
		(layer "In4.Cu")
		(net "M_D_CPU0_SA_DQS_DN<6>")
	)
	(segment
		(start 289.708336 -211.904072)
		(end 290.610036 -211.002372)
		(width 0.16002)
		(layer "In4.Cu")
		(net "M_D_CPU0_SA_DQS_DN<6>")
	)
	(segment
		(start 320.712338 -225.01733)
		(end 320.712338 -226.591622)
		(width 0.16002)
		(layer "In4.Cu")
		(net "M_D_CPU0_SA_DQS_DN<6>")
	)
	(segment
		(start 325.439278 -230.588312)
		(end 327.434448 -232.583482)
		(width 0.09525)
		(layer "In4.Cu")
		(net "M_D_CPU0_SA_DQS_DN<6>")
	)
	(segment
		(start 340.297262 -232.599484)
		(end 340.451186 -232.334054)
		(width 0.09525)
		(layer "In4.Cu")
		(net "M_D_CPU0_SA_DQS_DN<6>")
	)
	(segment
		(start 286.44342 -211.388452)
		(end 287.262824 -212.207856)
		(width 0.16002)
		(layer "In4.Cu")
		(net "M_D_CPU0_SA_DQS_DN<6>")
	)
	(segment
		(start 280.909776 -211.208874)
		(end 282.791154 -211.208874)
		(width 0.16002)
		(layer "In4.Cu")
		(net "M_D_CPU0_SA_DQS_DN<6>")
	)
	(segment
		(start 290.610036 -211.002372)
		(end 291.168836 -211.002372)
		(width 0.16002)
		(layer "In4.Cu")
		(net "M_D_CPU0_SA_DQS_DN<6>")
	)
	(segment
		(start 324.27291 -230.152194)
		(end 324.289674 -230.168958)
		(width 0.09525)
		(layer "In4.Cu")
		(net "M_D_CPU0_SA_DQS_DN<6>")
	)
	(segment
		(start 294.734488 -212.207856)
		(end 296.480738 -212.207856)
		(width 0.16002)
		(layer "In4.Cu")
		(net "M_D_CPU0_SA_DQS_DN<6>")
	)
	(segment
		(start 282.969716 -211.030312)
		(end 283.6799 -211.030312)
		(width 0.16002)
		(layer "In4.Cu")
		(net "M_D_CPU0_SA_DQS_DN<6>")
	)
	(segment
		(start 305.332892 -211.888324)
		(end 305.652424 -212.207856)
		(width 0.16002)
		(layer "In4.Cu")
		(net "M_D_CPU0_SA_DQS_DN<6>")
	)
	(segment
		(start 331.23124 -232.664)
		(end 331.239622 -232.659174)
		(width 0.09525)
		(layer "In4.Cu")
		(net "M_D_CPU0_SA_DQS_DN<6>")
	)
	(segment
		(start 324.289674 -230.25227)
		(end 324.625716 -230.588312)
		(width 0.09525)
		(layer "In4.Cu")
		(net "M_D_CPU0_SA_DQS_DN<6>")
	)
	(segment
		(start 327.434448 -232.583482)
		(end 327.761092 -232.583482)
		(width 0.09525)
		(layer "In4.Cu")
		(net "M_D_CPU0_SA_DQS_DN<6>")
	)
	(segment
		(start 280.635964 -210.935062)
		(end 280.909776 -211.208874)
		(width 0.16002)
		(layer "In4.Cu")
		(net "M_D_CPU0_SA_DQS_DN<6>")
	)
	(segment
		(start 293.884604 -211.357972)
		(end 294.734488 -212.207856)
		(width 0.16002)
		(layer "In4.Cu")
		(net "M_D_CPU0_SA_DQS_DN<6>")
	)
	(segment
		(start 335.931256 -232.664)
		(end 335.939638 -232.659174)
		(width 0.09525)
		(layer "In4.Cu")
		(net "M_D_CPU0_SA_DQS_DN<6>")
	)
	(segment
		(start 298.161964 -211.00415)
		(end 298.714414 -211.00415)
		(width 0.16002)
		(layer "In4.Cu")
		(net "M_D_CPU0_SA_DQS_DN<6>")
	)
	(segment
		(start 307.902864 -212.207856)
		(end 320.712338 -225.01733)
		(width 0.16002)
		(layer "In4.Cu")
		(net "M_D_CPU0_SA_DQS_DN<6>")
	)
	(segment
		(start 336.87131 -232.664)
		(end 336.879692 -232.659174)
		(width 0.09525)
		(layer "In4.Cu")
		(net "M_D_CPU0_SA_DQS_DN<6>")
	)
	(segment
		(start 340.196424 -232.626154)
		(end 340.297262 -232.599484)
		(width 0.09525)
		(layer "In4.Cu")
		(net "M_D_CPU0_SA_DQS_DN<6>")
	)
	(segment
		(start 324.625716 -230.588312)
		(end 325.439278 -230.588312)
		(width 0.09525)
		(layer "In4.Cu")
		(net "M_D_CPU0_SA_DQS_DN<6>")
	)
	(segment
		(start 332.74254 -232.659174)
		(end 332.750922 -232.664)
		(width 0.09525)
		(layer "In4.Cu")
		(net "M_D_CPU0_SA_DQS_DN<6>")
	)
	(segment
		(start 339.691218 -232.664)
		(end 339.6996 -232.659174)
		(width 0.09525)
		(layer "In4.Cu")
		(net "M_D_CPU0_SA_DQS_DN<6>")
	)
	(segment
		(start 324.289674 -230.168958)
		(end 324.289674 -230.25227)
		(width 0.09525)
		(layer "In4.Cu")
		(net "M_D_CPU0_SA_DQS_DN<6>")
	)
	(segment
		(start 298.714414 -211.00415)
		(end 299.068236 -211.357972)
		(width 0.16002)
		(layer "In4.Cu")
		(net "M_D_CPU0_SA_DQS_DN<6>")
	)
	(segment
		(start 320.712338 -226.591622)
		(end 324.27291 -230.152194)
		(width 0.16002)
		(layer "In4.Cu")
		(net "M_D_CPU0_SA_DQS_DN<6>")
	)
	(segment
		(start 296.480738 -212.207856)
		(end 296.80027 -211.888324)
		(width 0.16002)
		(layer "In4.Cu")
		(net "M_D_CPU0_SA_DQS_DN<6>")
	)
	(segment
		(start 296.80027 -211.888324)
		(end 297.27779 -211.888324)
		(width 0.16002)
		(layer "In4.Cu")
		(net "M_D_CPU0_SA_DQS_DN<6>")
	)
	(segment
		(start 297.27779 -211.888324)
		(end 298.161964 -211.00415)
		(width 0.16002)
		(layer "In4.Cu")
		(net "M_D_CPU0_SA_DQS_DN<6>")
	)
	(segment
		(start 305.652424 -212.207856)
		(end 307.902864 -212.207856)
		(width 0.16002)
		(layer "In4.Cu")
		(net "M_D_CPU0_SA_DQS_DN<6>")
	)
	(segment
		(start 289.228276 -211.904072)
		(end 289.708336 -211.904072)
		(width 0.16002)
		(layer "In4.Cu")
		(net "M_D_CPU0_SA_DQS_DN<6>")
	)
	(segment
		(start 332.171294 -232.664)
		(end 332.179676 -232.659174)
		(width 0.09525)
		(layer "In4.Cu")
		(net "M_D_CPU0_SA_DQS_DN<6>")
	)
	(segment
		(start 288.924492 -212.207856)
		(end 289.228276 -211.904072)
		(width 0.16002)
		(layer "In4.Cu")
		(net "M_D_CPU0_SA_DQS_DN<6>")
	)
	(segment
		(start 291.524436 -211.357972)
		(end 293.884604 -211.357972)
		(width 0.16002)
		(layer "In4.Cu")
		(net "M_D_CPU0_SA_DQS_DN<6>")
	)
	(segment
		(start 291.168836 -211.002372)
		(end 291.524436 -211.357972)
		(width 0.16002)
		(layer "In4.Cu")
		(net "M_D_CPU0_SA_DQS_DN<6>")
	)
	(arc
		(start 336.879692 -232.659174)
		(mid 337.161124 -232.583419)
		(end 337.442556 -232.659174)
		(width 0.09525)
		(layer "In4.Cu")
		(net "M_D_CPU0_SA_DQS_DN<6>")
	)
	(arc
		(start 338.759546 -232.659174)
		(mid 339.040978 -232.583419)
		(end 339.32241 -232.659174)
		(width 0.09525)
		(layer "In4.Cu")
		(net "M_D_CPU0_SA_DQS_DN<6>")
	)
	(arc
		(start 339.32241 -232.659174)
		(mid 339.506185 -232.709946)
		(end 339.691218 -232.664)
		(width 0.09525)
		(layer "In4.Cu")
		(net "M_D_CPU0_SA_DQS_DN<6>")
	)
	(arc
		(start 337.819746 -232.659174)
		(mid 338.101178 -232.583419)
		(end 338.38261 -232.659174)
		(width 0.09525)
		(layer "In4.Cu")
		(net "M_D_CPU0_SA_DQS_DN<6>")
	)
	(arc
		(start 335.562448 -232.659174)
		(mid 335.746223 -232.709946)
		(end 335.931256 -232.664)
		(width 0.09525)
		(layer "In4.Cu")
		(net "M_D_CPU0_SA_DQS_DN<6>")
	)
	(arc
		(start 337.450938 -232.664)
		(mid 337.63597 -232.709914)
		(end 337.819746 -232.659174)
		(width 0.09525)
		(layer "In4.Cu")
		(net "M_D_CPU0_SA_DQS_DN<6>")
	)
	(arc
		(start 331.239622 -232.659174)
		(mid 331.521054 -232.583419)
		(end 331.802486 -232.659174)
		(width 0.09525)
		(layer "In4.Cu")
		(net "M_D_CPU0_SA_DQS_DN<6>")
	)
	(arc
		(start 330.299568 -232.659174)
		(mid 330.581 -232.583419)
		(end 330.862432 -232.659174)
		(width 0.09525)
		(layer "In4.Cu")
		(net "M_D_CPU0_SA_DQS_DN<6>")
	)
	(arc
		(start 334.999584 -232.659174)
		(mid 335.281016 -232.583419)
		(end 335.562448 -232.659174)
		(width 0.09525)
		(layer "In4.Cu")
		(net "M_D_CPU0_SA_DQS_DN<6>")
	)
	(arc
		(start 328.99096 -232.664)
		(mid 329.175992 -232.709914)
		(end 329.359768 -232.659174)
		(width 0.09525)
		(layer "In4.Cu")
		(net "M_D_CPU0_SA_DQS_DN<6>")
	)
	(arc
		(start 340.17585 -232.618026)
		(mid 340.186178 -232.621986)
		(end 340.196424 -232.626154)
		(width 0.09525)
		(layer "In4.Cu")
		(net "M_D_CPU0_SA_DQS_DN<6>")
	)
	(arc
		(start 329.359768 -232.659174)
		(mid 329.6412 -232.583419)
		(end 329.922632 -232.659174)
		(width 0.09525)
		(layer "In4.Cu")
		(net "M_D_CPU0_SA_DQS_DN<6>")
	)
	(arc
		(start 338.38261 -232.659174)
		(mid 338.571078 -232.709851)
		(end 338.759546 -232.659174)
		(width 0.09525)
		(layer "In4.Cu")
		(net "M_D_CPU0_SA_DQS_DN<6>")
	)
	(arc
		(start 327.761092 -232.583482)
		(mid 327.9068 -232.60275)
		(end 328.042524 -232.659174)
		(width 0.09525)
		(layer "In4.Cu")
		(net "M_D_CPU0_SA_DQS_DN<6>")
	)
	(arc
		(start 336.502502 -232.659174)
		(mid 336.686277 -232.709946)
		(end 336.87131 -232.664)
		(width 0.09525)
		(layer "In4.Cu")
		(net "M_D_CPU0_SA_DQS_DN<6>")
	)
	(arc
		(start 331.802486 -232.659174)
		(mid 331.986261 -232.709946)
		(end 332.171294 -232.664)
		(width 0.09525)
		(layer "In4.Cu")
		(net "M_D_CPU0_SA_DQS_DN<6>")
	)
	(arc
		(start 333.690976 -232.664)
		(mid 333.876008 -232.709914)
		(end 334.059784 -232.659174)
		(width 0.09525)
		(layer "In4.Cu")
		(net "M_D_CPU0_SA_DQS_DN<6>")
	)
	(arc
		(start 328.042524 -232.659174)
		(mid 328.226299 -232.709946)
		(end 328.411332 -232.664)
		(width 0.09525)
		(layer "In4.Cu")
		(net "M_D_CPU0_SA_DQS_DN<6>")
	)
	(arc
		(start 339.6996 -232.659174)
		(mid 339.933114 -232.585331)
		(end 340.17585 -232.618026)
		(width 0.09525)
		(layer "In4.Cu")
		(net "M_D_CPU0_SA_DQS_DN<6>")
	)
	(arc
		(start 335.939638 -232.659174)
		(mid 336.22107 -232.583419)
		(end 336.502502 -232.659174)
		(width 0.09525)
		(layer "In4.Cu")
		(net "M_D_CPU0_SA_DQS_DN<6>")
	)
	(arc
		(start 332.179676 -232.659174)
		(mid 332.461108 -232.583419)
		(end 332.74254 -232.659174)
		(width 0.09525)
		(layer "In4.Cu")
		(net "M_D_CPU0_SA_DQS_DN<6>")
	)
	(arc
		(start 328.419714 -232.659174)
		(mid 328.701146 -232.583419)
		(end 328.982578 -232.659174)
		(width 0.09525)
		(layer "In4.Cu")
		(net "M_D_CPU0_SA_DQS_DN<6>")
	)
	(arc
		(start 330.862432 -232.659174)
		(mid 331.046207 -232.709946)
		(end 331.23124 -232.664)
		(width 0.09525)
		(layer "In4.Cu")
		(net "M_D_CPU0_SA_DQS_DN<6>")
	)
	(arc
		(start 334.059784 -232.659174)
		(mid 334.341216 -232.583419)
		(end 334.622648 -232.659174)
		(width 0.09525)
		(layer "In4.Cu")
		(net "M_D_CPU0_SA_DQS_DN<6>")
	)
	(arc
		(start 333.11973 -232.659174)
		(mid 333.401162 -232.583419)
		(end 333.682594 -232.659174)
		(width 0.09525)
		(layer "In4.Cu")
		(net "M_D_CPU0_SA_DQS_DN<6>")
	)
	(arc
		(start 329.922632 -232.659174)
		(mid 330.1111 -232.709851)
		(end 330.299568 -232.659174)
		(width 0.09525)
		(layer "In4.Cu")
		(net "M_D_CPU0_SA_DQS_DN<6>")
	)
	(arc
		(start 334.622648 -232.659174)
		(mid 334.811116 -232.709851)
		(end 334.999584 -232.659174)
		(width 0.09525)
		(layer "In4.Cu")
		(net "M_D_CPU0_SA_DQS_DN<6>")
	)
	(arc
		(start 332.750922 -232.664)
		(mid 332.935954 -232.709914)
		(end 333.11973 -232.659174)
		(width 0.09525)
		(layer "In4.Cu")
		(net "M_D_CPU0_SA_DQS_DN<6>")
	)
	(segment
		(start 340.918038 -227.74021)
		(end 340.451186 -227.474272)
		(width 0.12954)
		(layer "F.Cu")
		(net "M_D_CPU0_SA_DQS_DN<5>")
	)
	(segment
		(start 326.428608 -221.943676)
		(end 326.555354 -222.070168)
		(width 0.09525)
		(layer "In4.Cu")
		(net "M_D_CPU0_SA_DQS_DN<5>")
	)
	(segment
		(start 302.320198 -202.831192)
		(end 304.037238 -202.831192)
		(width 0.16002)
		(layer "In4.Cu")
		(net "M_D_CPU0_SA_DQS_DN<5>")
	)
	(segment
		(start 338.371688 -227.79355)
		(end 338.381848 -227.799646)
		(width 0.09525)
		(layer "In4.Cu")
		(net "M_D_CPU0_SA_DQS_DN<5>")
	)
	(segment
		(start 331.24013 -227.799646)
		(end 331.240384 -227.799646)
		(width 0.09525)
		(layer "In4.Cu")
		(net "M_D_CPU0_SA_DQS_DN<5>")
	)
	(segment
		(start 287.241488 -202.857862)
		(end 288.925508 -202.857862)
		(width 0.16002)
		(layer "In4.Cu")
		(net "M_D_CPU0_SA_DQS_DN<5>")
	)
	(segment
		(start 339.700108 -227.799646)
		(end 339.700362 -227.799646)
		(width 0.09525)
		(layer "In4.Cu")
		(net "M_D_CPU0_SA_DQS_DN<5>")
	)
	(segment
		(start 326.107298 -221.068138)
		(end 326.107298 -221.539054)
		(width 0.16002)
		(layer "In4.Cu")
		(net "M_D_CPU0_SA_DQS_DN<5>")
	)
	(segment
		(start 328.954384 -226.163378)
		(end 328.982324 -226.179634)
		(width 0.09525)
		(layer "In4.Cu")
		(net "M_D_CPU0_SA_DQS_DN<5>")
	)
	(segment
		(start 335.940146 -227.799646)
		(end 335.9404 -227.799646)
		(width 0.09525)
		(layer "In4.Cu")
		(net "M_D_CPU0_SA_DQS_DN<5>")
	)
	(segment
		(start 283.656278 -201.688192)
		(end 283.991558 -202.023472)
		(width 0.16002)
		(layer "In4.Cu")
		(net "M_D_CPU0_SA_DQS_DN<5>")
	)
	(segment
		(start 330.300076 -227.799646)
		(end 330.30033 -227.799646)
		(width 0.09525)
		(layer "In4.Cu")
		(net "M_D_CPU0_SA_DQS_DN<5>")
	)
	(segment
		(start 296.762678 -202.536552)
		(end 297.260518 -202.536552)
		(width 0.16002)
		(layer "In4.Cu")
		(net "M_D_CPU0_SA_DQS_DN<5>")
	)
	(segment
		(start 288.925508 -202.857862)
		(end 289.249358 -202.534012)
		(width 0.16002)
		(layer "In4.Cu")
		(net "M_D_CPU0_SA_DQS_DN<5>")
	)
	(segment
		(start 298.141898 -201.655172)
		(end 298.726098 -201.655172)
		(width 0.16002)
		(layer "In4.Cu")
		(net "M_D_CPU0_SA_DQS_DN<5>")
	)
	(segment
		(start 291.537644 -202.007978)
		(end 293.925244 -202.007978)
		(width 0.16002)
		(layer "In4.Cu")
		(net "M_D_CPU0_SA_DQS_DN<5>")
	)
	(segment
		(start 289.734498 -202.534012)
		(end 290.613338 -201.655172)
		(width 0.16002)
		(layer "In4.Cu")
		(net "M_D_CPU0_SA_DQS_DN<5>")
	)
	(segment
		(start 326.33539 -221.767146)
		(end 326.33539 -221.850458)
		(width 0.09525)
		(layer "In4.Cu")
		(net "M_D_CPU0_SA_DQS_DN<5>")
	)
	(segment
		(start 280.909776 -201.85888)
		(end 282.67533 -201.85888)
		(width 0.16002)
		(layer "In4.Cu")
		(net "M_D_CPU0_SA_DQS_DN<5>")
	)
	(segment
		(start 333.671672 -227.79355)
		(end 333.681832 -227.799646)
		(width 0.09525)
		(layer "In4.Cu")
		(net "M_D_CPU0_SA_DQS_DN<5>")
	)
	(segment
		(start 304.339498 -202.528932)
		(end 305.40452 -202.528932)
		(width 0.16002)
		(layer "In4.Cu")
		(net "M_D_CPU0_SA_DQS_DN<5>")
	)
	(segment
		(start 327.540366 -223.731074)
		(end 327.572624 -223.749616)
		(width 0.09525)
		(layer "In4.Cu")
		(net "M_D_CPU0_SA_DQS_DN<5>")
	)
	(segment
		(start 297.260518 -202.536552)
		(end 298.141898 -201.655172)
		(width 0.16002)
		(layer "In4.Cu")
		(net "M_D_CPU0_SA_DQS_DN<5>")
	)
	(segment
		(start 296.441368 -202.857862)
		(end 296.762678 -202.536552)
		(width 0.16002)
		(layer "In4.Cu")
		(net "M_D_CPU0_SA_DQS_DN<5>")
	)
	(segment
		(start 299.078904 -202.007978)
		(end 301.496984 -202.007978)
		(width 0.16002)
		(layer "In4.Cu")
		(net "M_D_CPU0_SA_DQS_DN<5>")
	)
	(segment
		(start 289.249358 -202.534012)
		(end 289.734498 -202.534012)
		(width 0.16002)
		(layer "In4.Cu")
		(net "M_D_CPU0_SA_DQS_DN<5>")
	)
	(segment
		(start 305.40452 -202.528932)
		(end 305.73345 -202.857862)
		(width 0.16002)
		(layer "In4.Cu")
		(net "M_D_CPU0_SA_DQS_DN<5>")
	)
	(segment
		(start 331.240384 -227.799646)
		(end 331.250544 -227.79355)
		(width 0.09525)
		(layer "In4.Cu")
		(net "M_D_CPU0_SA_DQS_DN<5>")
	)
	(segment
		(start 328.982324 -226.179634)
		(end 329.021694 -226.202494)
		(width 0.09525)
		(layer "In4.Cu")
		(net "M_D_CPU0_SA_DQS_DN<5>")
	)
	(segment
		(start 290.613338 -201.655172)
		(end 291.184838 -201.655172)
		(width 0.16002)
		(layer "In4.Cu")
		(net "M_D_CPU0_SA_DQS_DN<5>")
	)
	(segment
		(start 340.297262 -227.739702)
		(end 340.451186 -227.474272)
		(width 0.09525)
		(layer "In4.Cu")
		(net "M_D_CPU0_SA_DQS_DN<5>")
	)
	(segment
		(start 333.681832 -227.799646)
		(end 333.682086 -227.799646)
		(width 0.09525)
		(layer "In4.Cu")
		(net "M_D_CPU0_SA_DQS_DN<5>")
	)
	(segment
		(start 335.000346 -227.799646)
		(end 335.010506 -227.79355)
		(width 0.09525)
		(layer "In4.Cu")
		(net "M_D_CPU0_SA_DQS_DN<5>")
	)
	(segment
		(start 340.19617 -227.767134)
		(end 340.196424 -227.766372)
		(width 0.09525)
		(layer "In4.Cu")
		(net "M_D_CPU0_SA_DQS_DN<5>")
	)
	(segment
		(start 327.10247 -222.93961)
		(end 327.143364 -222.963486)
		(width 0.09525)
		(layer "In4.Cu")
		(net "M_D_CPU0_SA_DQS_DN<5>")
	)
	(segment
		(start 330.30033 -227.799646)
		(end 330.31049 -227.79355)
		(width 0.09525)
		(layer "In4.Cu")
		(net "M_D_CPU0_SA_DQS_DN<5>")
	)
	(segment
		(start 329.891136 -227.781612)
		(end 329.922124 -227.799646)
		(width 0.09525)
		(layer "In4.Cu")
		(net "M_D_CPU0_SA_DQS_DN<5>")
	)
	(segment
		(start 338.381848 -227.799646)
		(end 338.382102 -227.799646)
		(width 0.09525)
		(layer "In4.Cu")
		(net "M_D_CPU0_SA_DQS_DN<5>")
	)
	(segment
		(start 301.496984 -202.007978)
		(end 302.320198 -202.831192)
		(width 0.16002)
		(layer "In4.Cu")
		(net "M_D_CPU0_SA_DQS_DN<5>")
	)
	(segment
		(start 327.075038 -222.923862)
		(end 327.10247 -222.93961)
		(width 0.09525)
		(layer "In4.Cu")
		(net "M_D_CPU0_SA_DQS_DN<5>")
	)
	(segment
		(start 307.897022 -202.857862)
		(end 326.107298 -221.068138)
		(width 0.16002)
		(layer "In4.Cu")
		(net "M_D_CPU0_SA_DQS_DN<5>")
	)
	(segment
		(start 282.67533 -201.85888)
		(end 282.846018 -201.688192)
		(width 0.16002)
		(layer "In4.Cu")
		(net "M_D_CPU0_SA_DQS_DN<5>")
	)
	(segment
		(start 328.51217 -225.369628)
		(end 328.551794 -225.392488)
		(width 0.09525)
		(layer "In4.Cu")
		(net "M_D_CPU0_SA_DQS_DN<5>")
	)
	(segment
		(start 328.042778 -224.56013)
		(end 328.080878 -224.581974)
		(width 0.09525)
		(layer "In4.Cu")
		(net "M_D_CPU0_SA_DQS_DN<5>")
	)
	(segment
		(start 326.33539 -221.850458)
		(end 326.428608 -221.943676)
		(width 0.09525)
		(layer "In4.Cu")
		(net "M_D_CPU0_SA_DQS_DN<5>")
	)
	(segment
		(start 283.991558 -202.023472)
		(end 286.407098 -202.023472)
		(width 0.16002)
		(layer "In4.Cu")
		(net "M_D_CPU0_SA_DQS_DN<5>")
	)
	(segment
		(start 286.407098 -202.023472)
		(end 287.241488 -202.857862)
		(width 0.16002)
		(layer "In4.Cu")
		(net "M_D_CPU0_SA_DQS_DN<5>")
	)
	(segment
		(start 328.481182 -225.351594)
		(end 328.51217 -225.369628)
		(width 0.09525)
		(layer "In4.Cu")
		(net "M_D_CPU0_SA_DQS_DN<5>")
	)
	(segment
		(start 326.63257 -222.129604)
		(end 326.670924 -222.151956)
		(width 0.09525)
		(layer "In4.Cu")
		(net "M_D_CPU0_SA_DQS_DN<5>")
	)
	(segment
		(start 335.9404 -227.799646)
		(end 335.95056 -227.79355)
		(width 0.09525)
		(layer "In4.Cu")
		(net "M_D_CPU0_SA_DQS_DN<5>")
	)
	(segment
		(start 294.775128 -202.857862)
		(end 296.441368 -202.857862)
		(width 0.16002)
		(layer "In4.Cu")
		(net "M_D_CPU0_SA_DQS_DN<5>")
	)
	(segment
		(start 280.635964 -201.585068)
		(end 280.909776 -201.85888)
		(width 0.16002)
		(layer "In4.Cu")
		(net "M_D_CPU0_SA_DQS_DN<5>")
	)
	(segment
		(start 334.611726 -227.79355)
		(end 334.621886 -227.799646)
		(width 0.09525)
		(layer "In4.Cu")
		(net "M_D_CPU0_SA_DQS_DN<5>")
	)
	(segment
		(start 305.73345 -202.857862)
		(end 307.897022 -202.857862)
		(width 0.16002)
		(layer "In4.Cu")
		(net "M_D_CPU0_SA_DQS_DN<5>")
	)
	(segment
		(start 304.037238 -202.831192)
		(end 304.339498 -202.528932)
		(width 0.16002)
		(layer "In4.Cu")
		(net "M_D_CPU0_SA_DQS_DN<5>")
	)
	(segment
		(start 340.196424 -227.766372)
		(end 340.297262 -227.739702)
		(width 0.09525)
		(layer "In4.Cu")
		(net "M_D_CPU0_SA_DQS_DN<5>")
	)
	(segment
		(start 293.925244 -202.007978)
		(end 294.775128 -202.857862)
		(width 0.16002)
		(layer "In4.Cu")
		(net "M_D_CPU0_SA_DQS_DN<5>")
	)
	(segment
		(start 328.013822 -224.543112)
		(end 328.042778 -224.56013)
		(width 0.09525)
		(layer "In4.Cu")
		(net "M_D_CPU0_SA_DQS_DN<5>")
	)
	(segment
		(start 291.184838 -201.655172)
		(end 291.537644 -202.007978)
		(width 0.16002)
		(layer "In4.Cu")
		(net "M_D_CPU0_SA_DQS_DN<5>")
	)
	(segment
		(start 329.452224 -226.98964)
		(end 329.490832 -227.011992)
		(width 0.09525)
		(layer "In4.Cu")
		(net "M_D_CPU0_SA_DQS_DN<5>")
	)
	(segment
		(start 334.621886 -227.799646)
		(end 334.62214 -227.799646)
		(width 0.09525)
		(layer "In4.Cu")
		(net "M_D_CPU0_SA_DQS_DN<5>")
	)
	(segment
		(start 327.572624 -223.749616)
		(end 327.609454 -223.771206)
		(width 0.09525)
		(layer "In4.Cu")
		(net "M_D_CPU0_SA_DQS_DN<5>")
	)
	(segment
		(start 282.846018 -201.688192)
		(end 283.656278 -201.688192)
		(width 0.16002)
		(layer "In4.Cu")
		(net "M_D_CPU0_SA_DQS_DN<5>")
	)
	(segment
		(start 298.726098 -201.655172)
		(end 299.078904 -202.007978)
		(width 0.16002)
		(layer "In4.Cu")
		(net "M_D_CPU0_SA_DQS_DN<5>")
	)
	(segment
		(start 329.421236 -226.971606)
		(end 329.452224 -226.98964)
		(width 0.09525)
		(layer "In4.Cu")
		(net "M_D_CPU0_SA_DQS_DN<5>")
	)
	(segment
		(start 338.760308 -227.799646)
		(end 338.770468 -227.79355)
		(width 0.09525)
		(layer "In4.Cu")
		(net "M_D_CPU0_SA_DQS_DN<5>")
	)
	(segment
		(start 339.700362 -227.799646)
		(end 339.710522 -227.79355)
		(width 0.09525)
		(layer "In4.Cu")
		(net "M_D_CPU0_SA_DQS_DN<5>")
	)
	(segment
		(start 326.107298 -221.539054)
		(end 326.318626 -221.750382)
		(width 0.16002)
		(layer "In4.Cu")
		(net "M_D_CPU0_SA_DQS_DN<5>")
	)
	(segment
		(start 326.318626 -221.750382)
		(end 326.33539 -221.767146)
		(width 0.09525)
		(layer "In4.Cu")
		(net "M_D_CPU0_SA_DQS_DN<5>")
	)
	(arc
		(start 331.250544 -227.79355)
		(mid 331.527198 -227.723964)
		(end 331.802232 -227.799646)
		(width 0.09525)
		(layer "In4.Cu")
		(net "M_D_CPU0_SA_DQS_DN<5>")
	)
	(arc
		(start 328.793094 -225.85426)
		(mid 328.835889 -226.028574)
		(end 328.954384 -226.163378)
		(width 0.09525)
		(layer "In4.Cu")
		(net "M_D_CPU0_SA_DQS_DN<5>")
	)
	(arc
		(start 331.802232 -227.799646)
		(mid 331.991208 -227.850543)
		(end 332.180184 -227.799646)
		(width 0.09525)
		(layer "In4.Cu")
		(net "M_D_CPU0_SA_DQS_DN<5>")
	)
	(arc
		(start 328.080878 -224.581974)
		(mid 328.258793 -224.783334)
		(end 328.32294 -225.044254)
		(width 0.09525)
		(layer "In4.Cu")
		(net "M_D_CPU0_SA_DQS_DN<5>")
	)
	(arc
		(start 335.010506 -227.79355)
		(mid 335.28716 -227.723964)
		(end 335.562194 -227.799646)
		(width 0.09525)
		(layer "In4.Cu")
		(net "M_D_CPU0_SA_DQS_DN<5>")
	)
	(arc
		(start 332.742032 -227.799646)
		(mid 332.931008 -227.850543)
		(end 333.119984 -227.799646)
		(width 0.09525)
		(layer "In4.Cu")
		(net "M_D_CPU0_SA_DQS_DN<5>")
	)
	(arc
		(start 330.862178 -227.799646)
		(mid 331.051154 -227.850543)
		(end 331.24013 -227.799646)
		(width 0.09525)
		(layer "In4.Cu")
		(net "M_D_CPU0_SA_DQS_DN<5>")
	)
	(arc
		(start 326.913494 -222.614236)
		(mid 326.956312 -222.788848)
		(end 327.075038 -222.923862)
		(width 0.09525)
		(layer "In4.Cu")
		(net "M_D_CPU0_SA_DQS_DN<5>")
	)
	(arc
		(start 333.119984 -227.799646)
		(mid 333.395019 -227.724018)
		(end 333.671672 -227.79355)
		(width 0.09525)
		(layer "In4.Cu")
		(net "M_D_CPU0_SA_DQS_DN<5>")
	)
	(arc
		(start 336.502248 -227.799646)
		(mid 336.691224 -227.850543)
		(end 336.8802 -227.799646)
		(width 0.09525)
		(layer "In4.Cu")
		(net "M_D_CPU0_SA_DQS_DN<5>")
	)
	(arc
		(start 326.555354 -222.070168)
		(mid 326.592031 -222.102394)
		(end 326.63257 -222.129604)
		(width 0.09525)
		(layer "In4.Cu")
		(net "M_D_CPU0_SA_DQS_DN<5>")
	)
	(arc
		(start 327.853294 -224.234248)
		(mid 327.895819 -224.408297)
		(end 328.013822 -224.543112)
		(width 0.09525)
		(layer "In4.Cu")
		(net "M_D_CPU0_SA_DQS_DN<5>")
	)
	(arc
		(start 328.551794 -225.392488)
		(mid 328.729159 -225.593732)
		(end 328.793094 -225.85426)
		(width 0.09525)
		(layer "In4.Cu")
		(net "M_D_CPU0_SA_DQS_DN<5>")
	)
	(arc
		(start 339.710522 -227.79355)
		(mid 339.939412 -227.725582)
		(end 340.17585 -227.759006)
		(width 0.09525)
		(layer "In4.Cu")
		(net "M_D_CPU0_SA_DQS_DN<5>")
	)
	(arc
		(start 337.442048 -227.799646)
		(mid 337.631024 -227.850543)
		(end 337.82 -227.799646)
		(width 0.09525)
		(layer "In4.Cu")
		(net "M_D_CPU0_SA_DQS_DN<5>")
	)
	(arc
		(start 329.262994 -226.664266)
		(mid 329.304922 -226.837093)
		(end 329.421236 -226.971606)
		(width 0.09525)
		(layer "In4.Cu")
		(net "M_D_CPU0_SA_DQS_DN<5>")
	)
	(arc
		(start 340.17585 -227.759006)
		(mid 340.18605 -227.76297)
		(end 340.19617 -227.767134)
		(width 0.09525)
		(layer "In4.Cu")
		(net "M_D_CPU0_SA_DQS_DN<5>")
	)
	(arc
		(start 327.143364 -222.963486)
		(mid 327.319586 -223.164533)
		(end 327.38314 -223.424242)
		(width 0.09525)
		(layer "In4.Cu")
		(net "M_D_CPU0_SA_DQS_DN<5>")
	)
	(arc
		(start 328.32294 -225.044254)
		(mid 328.364868 -225.217081)
		(end 328.481182 -225.351594)
		(width 0.09525)
		(layer "In4.Cu")
		(net "M_D_CPU0_SA_DQS_DN<5>")
	)
	(arc
		(start 335.95056 -227.79355)
		(mid 336.227214 -227.723964)
		(end 336.502248 -227.799646)
		(width 0.09525)
		(layer "In4.Cu")
		(net "M_D_CPU0_SA_DQS_DN<5>")
	)
	(arc
		(start 326.670924 -222.151956)
		(mid 326.849149 -222.353214)
		(end 326.913494 -222.614236)
		(width 0.09525)
		(layer "In4.Cu")
		(net "M_D_CPU0_SA_DQS_DN<5>")
	)
	(arc
		(start 332.180184 -227.799646)
		(mid 332.461108 -227.724112)
		(end 332.742032 -227.799646)
		(width 0.09525)
		(layer "In4.Cu")
		(net "M_D_CPU0_SA_DQS_DN<5>")
	)
	(arc
		(start 327.609454 -223.771206)
		(mid 327.788601 -223.97259)
		(end 327.853294 -224.234248)
		(width 0.09525)
		(layer "In4.Cu")
		(net "M_D_CPU0_SA_DQS_DN<5>")
	)
	(arc
		(start 334.62214 -227.799646)
		(mid 334.81126 -227.850671)
		(end 335.000346 -227.799646)
		(width 0.09525)
		(layer "In4.Cu")
		(net "M_D_CPU0_SA_DQS_DN<5>")
	)
	(arc
		(start 333.682086 -227.799646)
		(mid 333.871062 -227.850543)
		(end 334.060038 -227.799646)
		(width 0.09525)
		(layer "In4.Cu")
		(net "M_D_CPU0_SA_DQS_DN<5>")
	)
	(arc
		(start 338.770468 -227.79355)
		(mid 339.047122 -227.723964)
		(end 339.322156 -227.799646)
		(width 0.09525)
		(layer "In4.Cu")
		(net "M_D_CPU0_SA_DQS_DN<5>")
	)
	(arc
		(start 329.922124 -227.799646)
		(mid 330.1111 -227.850543)
		(end 330.300076 -227.799646)
		(width 0.09525)
		(layer "In4.Cu")
		(net "M_D_CPU0_SA_DQS_DN<5>")
	)
	(arc
		(start 330.31049 -227.79355)
		(mid 330.587144 -227.723964)
		(end 330.862178 -227.799646)
		(width 0.09525)
		(layer "In4.Cu")
		(net "M_D_CPU0_SA_DQS_DN<5>")
	)
	(arc
		(start 329.490832 -227.011992)
		(mid 329.668747 -227.213352)
		(end 329.732894 -227.474272)
		(width 0.09525)
		(layer "In4.Cu")
		(net "M_D_CPU0_SA_DQS_DN<5>")
	)
	(arc
		(start 334.060038 -227.799646)
		(mid 334.335073 -227.724018)
		(end 334.611726 -227.79355)
		(width 0.09525)
		(layer "In4.Cu")
		(net "M_D_CPU0_SA_DQS_DN<5>")
	)
	(arc
		(start 335.562194 -227.799646)
		(mid 335.75117 -227.850543)
		(end 335.940146 -227.799646)
		(width 0.09525)
		(layer "In4.Cu")
		(net "M_D_CPU0_SA_DQS_DN<5>")
	)
	(arc
		(start 327.38314 -223.424242)
		(mid 327.424739 -223.596621)
		(end 327.540366 -223.731074)
		(width 0.09525)
		(layer "In4.Cu")
		(net "M_D_CPU0_SA_DQS_DN<5>")
	)
	(arc
		(start 336.8802 -227.799646)
		(mid 337.161124 -227.724112)
		(end 337.442048 -227.799646)
		(width 0.09525)
		(layer "In4.Cu")
		(net "M_D_CPU0_SA_DQS_DN<5>")
	)
	(arc
		(start 329.021694 -226.202494)
		(mid 329.199059 -226.403738)
		(end 329.262994 -226.664266)
		(width 0.09525)
		(layer "In4.Cu")
		(net "M_D_CPU0_SA_DQS_DN<5>")
	)
	(arc
		(start 339.322156 -227.799646)
		(mid 339.511132 -227.850543)
		(end 339.700108 -227.799646)
		(width 0.09525)
		(layer "In4.Cu")
		(net "M_D_CPU0_SA_DQS_DN<5>")
	)
	(arc
		(start 338.382102 -227.799646)
		(mid 338.571222 -227.850671)
		(end 338.760308 -227.799646)
		(width 0.09525)
		(layer "In4.Cu")
		(net "M_D_CPU0_SA_DQS_DN<5>")
	)
	(arc
		(start 337.82 -227.799646)
		(mid 338.095035 -227.724018)
		(end 338.371688 -227.79355)
		(width 0.09525)
		(layer "In4.Cu")
		(net "M_D_CPU0_SA_DQS_DN<5>")
	)
	(arc
		(start 329.732894 -227.474272)
		(mid 329.774822 -227.647099)
		(end 329.891136 -227.781612)
		(width 0.09525)
		(layer "In4.Cu")
		(net "M_D_CPU0_SA_DQS_DN<5>")
	)
	(segment
		(start 339.03793 -247.1801)
		(end 338.571078 -246.914162)
		(width 0.12954)
		(layer "F.Cu")
		(net "M_D_CPU0_SA_DQS_DN<4>")
	)
	(segment
		(start 302.707294 -238.590582)
		(end 302.883824 -238.767112)
		(width 0.16002)
		(layer "In4.Cu")
		(net "M_D_CPU0_SA_DQS_DN<4>")
	)
	(segment
		(start 325.340472 -246.947182)
		(end 325.623428 -246.664226)
		(width 0.09525)
		(layer "In4.Cu")
		(net "M_D_CPU0_SA_DQS_DN<4>")
	)
	(segment
		(start 302.883824 -238.767112)
		(end 302.883824 -239.232186)
		(width 0.16002)
		(layer "In4.Cu")
		(net "M_D_CPU0_SA_DQS_DN<4>")
	)
	(segment
		(start 323.819774 -246.29364)
		(end 323.843396 -246.29364)
		(width 0.09525)
		(layer "In4.Cu")
		(net "M_D_CPU0_SA_DQS_DN<4>")
	)
	(segment
		(start 335.931256 -246.584216)
		(end 335.939638 -246.589042)
		(width 0.09525)
		(layer "In4.Cu")
		(net "M_D_CPU0_SA_DQS_DN<4>")
	)
	(segment
		(start 309.892954 -241.68481)
		(end 310.08955 -241.881406)
		(width 0.16002)
		(layer "In4.Cu")
		(net "M_D_CPU0_SA_DQS_DN<4>")
	)
	(segment
		(start 338.725002 -246.648732)
		(end 338.571078 -246.914162)
		(width 0.09525)
		(layer "In4.Cu")
		(net "M_D_CPU0_SA_DQS_DN<4>")
	)
	(segment
		(start 309.3339 -241.967004)
		(end 309.616094 -241.68481)
		(width 0.16002)
		(layer "In4.Cu")
		(net "M_D_CPU0_SA_DQS_DN<4>")
	)
	(segment
		(start 284.736032 -238.985044)
		(end 285.009844 -238.711232)
		(width 0.16002)
		(layer "In4.Cu")
		(net "M_D_CPU0_SA_DQS_DN<4>")
	)
	(segment
		(start 325.623428 -246.664226)
		(end 325.883778 -246.664226)
		(width 0.09525)
		(layer "In4.Cu")
		(net "M_D_CPU0_SA_DQS_DN<4>")
	)
	(segment
		(start 307.960268 -240.593372)
		(end 308.139592 -240.414048)
		(width 0.16002)
		(layer "In4.Cu")
		(net "M_D_CPU0_SA_DQS_DN<4>")
	)
	(segment
		(start 303.258728 -239.60709)
		(end 303.789334 -239.60709)
		(width 0.16002)
		(layer "In4.Cu")
		(net "M_D_CPU0_SA_DQS_DN<4>")
	)
	(segment
		(start 323.902578 -246.234458)
		(end 324.113652 -246.234458)
		(width 0.09525)
		(layer "In4.Cu")
		(net "M_D_CPU0_SA_DQS_DN<4>")
	)
	(segment
		(start 298.29887 -238.060992)
		(end 298.715176 -238.060992)
		(width 0.16002)
		(layer "In4.Cu")
		(net "M_D_CPU0_SA_DQS_DN<4>")
	)
	(segment
		(start 295.079928 -238.562134)
		(end 296.473372 -238.562134)
		(width 0.16002)
		(layer "In4.Cu")
		(net "M_D_CPU0_SA_DQS_DN<4>")
	)
	(segment
		(start 331.23124 -246.584216)
		(end 331.239622 -246.589042)
		(width 0.09525)
		(layer "In4.Cu")
		(net "M_D_CPU0_SA_DQS_DN<4>")
	)
	(segment
		(start 308.433724 -241.066828)
		(end 308.433724 -241.594132)
		(width 0.16002)
		(layer "In4.Cu")
		(net "M_D_CPU0_SA_DQS_DN<4>")
	)
	(segment
		(start 294.483028 -238.678974)
		(end 294.963088 -238.678974)
		(width 0.16002)
		(layer "In4.Cu")
		(net "M_D_CPU0_SA_DQS_DN<4>")
	)
	(segment
		(start 298.715176 -238.060992)
		(end 299.063918 -237.71225)
		(width 0.16002)
		(layer "In4.Cu")
		(net "M_D_CPU0_SA_DQS_DN<4>")
	)
	(segment
		(start 291.520118 -237.71225)
		(end 293.003986 -237.71225)
		(width 0.16002)
		(layer "In4.Cu")
		(net "M_D_CPU0_SA_DQS_DN<4>")
	)
	(segment
		(start 287.286954 -238.562134)
		(end 288.929572 -238.562134)
		(width 0.16002)
		(layer "In4.Cu")
		(net "M_D_CPU0_SA_DQS_DN<4>")
	)
	(segment
		(start 293.85387 -238.562134)
		(end 294.366188 -238.562134)
		(width 0.16002)
		(layer "In4.Cu")
		(net "M_D_CPU0_SA_DQS_DN<4>")
	)
	(segment
		(start 308.613048 -240.610644)
		(end 308.613048 -240.887504)
		(width 0.16002)
		(layer "In4.Cu")
		(net "M_D_CPU0_SA_DQS_DN<4>")
	)
	(segment
		(start 308.613048 -240.887504)
		(end 308.433724 -241.066828)
		(width 0.16002)
		(layer "In4.Cu")
		(net "M_D_CPU0_SA_DQS_DN<4>")
	)
	(segment
		(start 308.806596 -241.967004)
		(end 309.3339 -241.967004)
		(width 0.16002)
		(layer "In4.Cu")
		(net "M_D_CPU0_SA_DQS_DN<4>")
	)
	(segment
		(start 297.46829 -238.891572)
		(end 298.29887 -238.060992)
		(width 0.16002)
		(layer "In4.Cu")
		(net "M_D_CPU0_SA_DQS_DN<4>")
	)
	(segment
		(start 289.896042 -238.891572)
		(end 290.726622 -238.060992)
		(width 0.16002)
		(layer "In4.Cu")
		(net "M_D_CPU0_SA_DQS_DN<4>")
	)
	(segment
		(start 311.463182 -243.531898)
		(end 311.180988 -243.814092)
		(width 0.16002)
		(layer "In4.Cu")
		(net "M_D_CPU0_SA_DQS_DN<4>")
	)
	(segment
		(start 327.081642 -246.602504)
		(end 327.10501 -246.589042)
		(width 0.09525)
		(layer "In4.Cu")
		(net "M_D_CPU0_SA_DQS_DN<4>")
	)
	(segment
		(start 296.80281 -238.891572)
		(end 297.46829 -238.891572)
		(width 0.16002)
		(layer "In4.Cu")
		(net "M_D_CPU0_SA_DQS_DN<4>")
	)
	(segment
		(start 310.08955 -242.158266)
		(end 309.807356 -242.44046)
		(width 0.16002)
		(layer "In4.Cu")
		(net "M_D_CPU0_SA_DQS_DN<4>")
	)
	(segment
		(start 303.789334 -239.60709)
		(end 304.042572 -239.353852)
		(width 0.16002)
		(layer "In4.Cu")
		(net "M_D_CPU0_SA_DQS_DN<4>")
	)
	(segment
		(start 312.363358 -244.432074)
		(end 312.640218 -244.432074)
		(width 0.16002)
		(layer "In4.Cu")
		(net "M_D_CPU0_SA_DQS_DN<4>")
	)
	(segment
		(start 337.442556 -246.589042)
		(end 337.450938 -246.584216)
		(width 0.09525)
		(layer "In4.Cu")
		(net "M_D_CPU0_SA_DQS_DN<4>")
	)
	(segment
		(start 312.836814 -244.62867)
		(end 312.836814 -244.90553)
		(width 0.16002)
		(layer "In4.Cu")
		(net "M_D_CPU0_SA_DQS_DN<4>")
	)
	(segment
		(start 309.616094 -241.68481)
		(end 309.892954 -241.68481)
		(width 0.16002)
		(layer "In4.Cu")
		(net "M_D_CPU0_SA_DQS_DN<4>")
	)
	(segment
		(start 287.137856 -238.711232)
		(end 287.286954 -238.562134)
		(width 0.16002)
		(layer "In4.Cu")
		(net "M_D_CPU0_SA_DQS_DN<4>")
	)
	(segment
		(start 327.481184 -246.589042)
		(end 327.506584 -246.603774)
		(width 0.09525)
		(layer "In4.Cu")
		(net "M_D_CPU0_SA_DQS_DN<4>")
	)
	(segment
		(start 328.411332 -246.584216)
		(end 328.419714 -246.589042)
		(width 0.09525)
		(layer "In4.Cu")
		(net "M_D_CPU0_SA_DQS_DN<4>")
	)
	(segment
		(start 336.87131 -246.584216)
		(end 336.879692 -246.589042)
		(width 0.09525)
		(layer "In4.Cu")
		(net "M_D_CPU0_SA_DQS_DN<4>")
	)
	(segment
		(start 293.003986 -237.71225)
		(end 293.85387 -238.562134)
		(width 0.16002)
		(layer "In4.Cu")
		(net "M_D_CPU0_SA_DQS_DN<4>")
	)
	(segment
		(start 289.25901 -238.891572)
		(end 289.896042 -238.891572)
		(width 0.16002)
		(layer "In4.Cu")
		(net "M_D_CPU0_SA_DQS_DN<4>")
	)
	(segment
		(start 296.473372 -238.562134)
		(end 296.80281 -238.891572)
		(width 0.16002)
		(layer "In4.Cu")
		(net "M_D_CPU0_SA_DQS_DN<4>")
	)
	(segment
		(start 302.883824 -239.232186)
		(end 303.258728 -239.60709)
		(width 0.16002)
		(layer "In4.Cu")
		(net "M_D_CPU0_SA_DQS_DN<4>")
	)
	(segment
		(start 326.163686 -246.589042)
		(end 326.189086 -246.574564)
		(width 0.09525)
		(layer "In4.Cu")
		(net "M_D_CPU0_SA_DQS_DN<4>")
	)
	(segment
		(start 308.433724 -241.594132)
		(end 308.806596 -241.967004)
		(width 0.16002)
		(layer "In4.Cu")
		(net "M_D_CPU0_SA_DQS_DN<4>")
	)
	(segment
		(start 310.180228 -243.340636)
		(end 310.707532 -243.340636)
		(width 0.16002)
		(layer "In4.Cu")
		(net "M_D_CPU0_SA_DQS_DN<4>")
	)
	(segment
		(start 294.963088 -238.678974)
		(end 295.079928 -238.562134)
		(width 0.16002)
		(layer "In4.Cu")
		(net "M_D_CPU0_SA_DQS_DN<4>")
	)
	(segment
		(start 312.55462 -245.187724)
		(end 312.55462 -245.715028)
		(width 0.16002)
		(layer "In4.Cu")
		(net "M_D_CPU0_SA_DQS_DN<4>")
	)
	(segment
		(start 311.266586 -243.058442)
		(end 311.463182 -243.255038)
		(width 0.16002)
		(layer "In4.Cu")
		(net "M_D_CPU0_SA_DQS_DN<4>")
	)
	(segment
		(start 324.113652 -246.234458)
		(end 324.208902 -246.329708)
		(width 0.09525)
		(layer "In4.Cu")
		(net "M_D_CPU0_SA_DQS_DN<4>")
	)
	(segment
		(start 311.180988 -244.341396)
		(end 311.55386 -244.714268)
		(width 0.16002)
		(layer "In4.Cu")
		(net "M_D_CPU0_SA_DQS_DN<4>")
	)
	(segment
		(start 307.432964 -240.593372)
		(end 307.960268 -240.593372)
		(width 0.16002)
		(layer "In4.Cu")
		(net "M_D_CPU0_SA_DQS_DN<4>")
	)
	(segment
		(start 311.180988 -243.814092)
		(end 311.180988 -244.341396)
		(width 0.16002)
		(layer "In4.Cu")
		(net "M_D_CPU0_SA_DQS_DN<4>")
	)
	(segment
		(start 285.009844 -238.711232)
		(end 287.137856 -238.711232)
		(width 0.16002)
		(layer "In4.Cu")
		(net "M_D_CPU0_SA_DQS_DN<4>")
	)
	(segment
		(start 290.726622 -238.060992)
		(end 291.171376 -238.060992)
		(width 0.16002)
		(layer "In4.Cu")
		(net "M_D_CPU0_SA_DQS_DN<4>")
	)
	(segment
		(start 327.466706 -246.58066)
		(end 327.481184 -246.589042)
		(width 0.09525)
		(layer "In4.Cu")
		(net "M_D_CPU0_SA_DQS_DN<4>")
	)
	(segment
		(start 312.640218 -244.432074)
		(end 312.836814 -244.62867)
		(width 0.16002)
		(layer "In4.Cu")
		(net "M_D_CPU0_SA_DQS_DN<4>")
	)
	(segment
		(start 304.042572 -239.353852)
		(end 306.193444 -239.353852)
		(width 0.16002)
		(layer "In4.Cu")
		(net "M_D_CPU0_SA_DQS_DN<4>")
	)
	(segment
		(start 312.55462 -245.715028)
		(end 313.133232 -246.29364)
		(width 0.16002)
		(layer "In4.Cu")
		(net "M_D_CPU0_SA_DQS_DN<4>")
	)
	(segment
		(start 309.807356 -242.967764)
		(end 310.180228 -243.340636)
		(width 0.16002)
		(layer "In4.Cu")
		(net "M_D_CPU0_SA_DQS_DN<4>")
	)
	(segment
		(start 311.463182 -243.255038)
		(end 311.463182 -243.531898)
		(width 0.16002)
		(layer "In4.Cu")
		(net "M_D_CPU0_SA_DQS_DN<4>")
	)
	(segment
		(start 300.596554 -237.71225)
		(end 301.474886 -238.590582)
		(width 0.16002)
		(layer "In4.Cu")
		(net "M_D_CPU0_SA_DQS_DN<4>")
	)
	(segment
		(start 311.55386 -244.714268)
		(end 312.081164 -244.714268)
		(width 0.16002)
		(layer "In4.Cu")
		(net "M_D_CPU0_SA_DQS_DN<4>")
	)
	(segment
		(start 299.063918 -237.71225)
		(end 300.596554 -237.71225)
		(width 0.16002)
		(layer "In4.Cu")
		(net "M_D_CPU0_SA_DQS_DN<4>")
	)
	(segment
		(start 310.08955 -241.881406)
		(end 310.08955 -242.158266)
		(width 0.16002)
		(layer "In4.Cu")
		(net "M_D_CPU0_SA_DQS_DN<4>")
	)
	(segment
		(start 291.171376 -238.060992)
		(end 291.520118 -237.71225)
		(width 0.16002)
		(layer "In4.Cu")
		(net "M_D_CPU0_SA_DQS_DN<4>")
	)
	(segment
		(start 332.74254 -246.589042)
		(end 332.750922 -246.584216)
		(width 0.09525)
		(layer "In4.Cu")
		(net "M_D_CPU0_SA_DQS_DN<4>")
	)
	(segment
		(start 313.133232 -246.29364)
		(end 323.819774 -246.29364)
		(width 0.16002)
		(layer "In4.Cu")
		(net "M_D_CPU0_SA_DQS_DN<4>")
	)
	(segment
		(start 308.139592 -240.414048)
		(end 308.416452 -240.414048)
		(width 0.16002)
		(layer "In4.Cu")
		(net "M_D_CPU0_SA_DQS_DN<4>")
	)
	(segment
		(start 309.807356 -242.44046)
		(end 309.807356 -242.967764)
		(width 0.16002)
		(layer "In4.Cu")
		(net "M_D_CPU0_SA_DQS_DN<4>")
	)
	(segment
		(start 338.701888 -246.562118)
		(end 338.725002 -246.648732)
		(width 0.09525)
		(layer "In4.Cu")
		(net "M_D_CPU0_SA_DQS_DN<4>")
	)
	(segment
		(start 324.208902 -246.329708)
		(end 324.208902 -246.614696)
		(width 0.09525)
		(layer "In4.Cu")
		(net "M_D_CPU0_SA_DQS_DN<4>")
	)
	(segment
		(start 301.474886 -238.590582)
		(end 302.707294 -238.590582)
		(width 0.16002)
		(layer "In4.Cu")
		(net "M_D_CPU0_SA_DQS_DN<4>")
	)
	(segment
		(start 312.081164 -244.714268)
		(end 312.363358 -244.432074)
		(width 0.16002)
		(layer "In4.Cu")
		(net "M_D_CPU0_SA_DQS_DN<4>")
	)
	(segment
		(start 310.707532 -243.340636)
		(end 310.989726 -243.058442)
		(width 0.16002)
		(layer "In4.Cu")
		(net "M_D_CPU0_SA_DQS_DN<4>")
	)
	(segment
		(start 333.682594 -246.589042)
		(end 333.690976 -246.584216)
		(width 0.09525)
		(layer "In4.Cu")
		(net "M_D_CPU0_SA_DQS_DN<4>")
	)
	(segment
		(start 328.982578 -246.589042)
		(end 328.99096 -246.584216)
		(width 0.09525)
		(layer "In4.Cu")
		(net "M_D_CPU0_SA_DQS_DN<4>")
	)
	(segment
		(start 312.836814 -244.90553)
		(end 312.55462 -245.187724)
		(width 0.16002)
		(layer "In4.Cu")
		(net "M_D_CPU0_SA_DQS_DN<4>")
	)
	(segment
		(start 324.541388 -246.947182)
		(end 325.340472 -246.947182)
		(width 0.09525)
		(layer "In4.Cu")
		(net "M_D_CPU0_SA_DQS_DN<4>")
	)
	(segment
		(start 306.193444 -239.353852)
		(end 307.432964 -240.593372)
		(width 0.16002)
		(layer "In4.Cu")
		(net "M_D_CPU0_SA_DQS_DN<4>")
	)
	(segment
		(start 310.989726 -243.058442)
		(end 311.266586 -243.058442)
		(width 0.16002)
		(layer "In4.Cu")
		(net "M_D_CPU0_SA_DQS_DN<4>")
	)
	(segment
		(start 288.929572 -238.562134)
		(end 289.25901 -238.891572)
		(width 0.16002)
		(layer "In4.Cu")
		(net "M_D_CPU0_SA_DQS_DN<4>")
	)
	(segment
		(start 332.171294 -246.584216)
		(end 332.179676 -246.589042)
		(width 0.09525)
		(layer "In4.Cu")
		(net "M_D_CPU0_SA_DQS_DN<4>")
	)
	(segment
		(start 323.843396 -246.29364)
		(end 323.902578 -246.234458)
		(width 0.09525)
		(layer "In4.Cu")
		(net "M_D_CPU0_SA_DQS_DN<4>")
	)
	(segment
		(start 324.208902 -246.614696)
		(end 324.541388 -246.947182)
		(width 0.09525)
		(layer "In4.Cu")
		(net "M_D_CPU0_SA_DQS_DN<4>")
	)
	(segment
		(start 308.416452 -240.414048)
		(end 308.613048 -240.610644)
		(width 0.16002)
		(layer "In4.Cu")
		(net "M_D_CPU0_SA_DQS_DN<4>")
	)
	(segment
		(start 294.366188 -238.562134)
		(end 294.483028 -238.678974)
		(width 0.16002)
		(layer "In4.Cu")
		(net "M_D_CPU0_SA_DQS_DN<4>")
	)
	(arc
		(start 332.750922 -246.584216)
		(mid 332.935954 -246.538302)
		(end 333.11973 -246.589042)
		(width 0.09525)
		(layer "In4.Cu")
		(net "M_D_CPU0_SA_DQS_DN<4>")
	)
	(arc
		(start 330.299568 -246.589042)
		(mid 330.581 -246.664797)
		(end 330.862432 -246.589042)
		(width 0.09525)
		(layer "In4.Cu")
		(net "M_D_CPU0_SA_DQS_DN<4>")
	)
	(arc
		(start 331.239622 -246.589042)
		(mid 331.521054 -246.664797)
		(end 331.802486 -246.589042)
		(width 0.09525)
		(layer "In4.Cu")
		(net "M_D_CPU0_SA_DQS_DN<4>")
	)
	(arc
		(start 334.622648 -246.589042)
		(mid 334.811116 -246.538365)
		(end 334.999584 -246.589042)
		(width 0.09525)
		(layer "In4.Cu")
		(net "M_D_CPU0_SA_DQS_DN<4>")
	)
	(arc
		(start 337.819746 -246.589042)
		(mid 338.101178 -246.664797)
		(end 338.38261 -246.589042)
		(width 0.09525)
		(layer "In4.Cu")
		(net "M_D_CPU0_SA_DQS_DN<4>")
	)
	(arc
		(start 336.502502 -246.589042)
		(mid 336.686277 -246.53827)
		(end 336.87131 -246.584216)
		(width 0.09525)
		(layer "In4.Cu")
		(net "M_D_CPU0_SA_DQS_DN<4>")
	)
	(arc
		(start 330.862432 -246.589042)
		(mid 331.046207 -246.53827)
		(end 331.23124 -246.584216)
		(width 0.09525)
		(layer "In4.Cu")
		(net "M_D_CPU0_SA_DQS_DN<4>")
	)
	(arc
		(start 333.11973 -246.589042)
		(mid 333.401162 -246.664797)
		(end 333.682594 -246.589042)
		(width 0.09525)
		(layer "In4.Cu")
		(net "M_D_CPU0_SA_DQS_DN<4>")
	)
	(arc
		(start 328.419714 -246.589042)
		(mid 328.701146 -246.664797)
		(end 328.982578 -246.589042)
		(width 0.09525)
		(layer "In4.Cu")
		(net "M_D_CPU0_SA_DQS_DN<4>")
	)
	(arc
		(start 335.562448 -246.589042)
		(mid 335.746223 -246.53827)
		(end 335.931256 -246.584216)
		(width 0.09525)
		(layer "In4.Cu")
		(net "M_D_CPU0_SA_DQS_DN<4>")
	)
	(arc
		(start 328.99096 -246.584216)
		(mid 329.175992 -246.538302)
		(end 329.359768 -246.589042)
		(width 0.09525)
		(layer "In4.Cu")
		(net "M_D_CPU0_SA_DQS_DN<4>")
	)
	(arc
		(start 337.450938 -246.584216)
		(mid 337.63597 -246.538302)
		(end 337.819746 -246.589042)
		(width 0.09525)
		(layer "In4.Cu")
		(net "M_D_CPU0_SA_DQS_DN<4>")
	)
	(arc
		(start 327.506584 -246.603774)
		(mid 327.776438 -246.664653)
		(end 328.042524 -246.589042)
		(width 0.09525)
		(layer "In4.Cu")
		(net "M_D_CPU0_SA_DQS_DN<4>")
	)
	(arc
		(start 334.059784 -246.589042)
		(mid 334.341216 -246.664797)
		(end 334.622648 -246.589042)
		(width 0.09525)
		(layer "In4.Cu")
		(net "M_D_CPU0_SA_DQS_DN<4>")
	)
	(arc
		(start 338.38261 -246.589042)
		(mid 338.539237 -246.539856)
		(end 338.701888 -246.562118)
		(width 0.09525)
		(layer "In4.Cu")
		(net "M_D_CPU0_SA_DQS_DN<4>")
	)
	(arc
		(start 332.179676 -246.589042)
		(mid 332.461108 -246.664797)
		(end 332.74254 -246.589042)
		(width 0.09525)
		(layer "In4.Cu")
		(net "M_D_CPU0_SA_DQS_DN<4>")
	)
	(arc
		(start 326.004682 -246.651018)
		(mid 326.086563 -246.626131)
		(end 326.163686 -246.589042)
		(width 0.09525)
		(layer "In4.Cu")
		(net "M_D_CPU0_SA_DQS_DN<4>")
	)
	(arc
		(start 326.189086 -246.574564)
		(mid 326.366791 -246.538086)
		(end 326.540876 -246.589042)
		(width 0.09525)
		(layer "In4.Cu")
		(net "M_D_CPU0_SA_DQS_DN<4>")
	)
	(arc
		(start 325.883778 -246.664226)
		(mid 325.94459 -246.660915)
		(end 326.004682 -246.651018)
		(width 0.09525)
		(layer "In4.Cu")
		(net "M_D_CPU0_SA_DQS_DN<4>")
	)
	(arc
		(start 331.802486 -246.589042)
		(mid 331.986261 -246.53827)
		(end 332.171294 -246.584216)
		(width 0.09525)
		(layer "In4.Cu")
		(net "M_D_CPU0_SA_DQS_DN<4>")
	)
	(arc
		(start 333.690976 -246.584216)
		(mid 333.876008 -246.538302)
		(end 334.059784 -246.589042)
		(width 0.09525)
		(layer "In4.Cu")
		(net "M_D_CPU0_SA_DQS_DN<4>")
	)
	(arc
		(start 326.540876 -246.589042)
		(mid 326.809539 -246.66526)
		(end 327.081642 -246.602504)
		(width 0.09525)
		(layer "In4.Cu")
		(net "M_D_CPU0_SA_DQS_DN<4>")
	)
	(arc
		(start 335.939638 -246.589042)
		(mid 336.22107 -246.664797)
		(end 336.502502 -246.589042)
		(width 0.09525)
		(layer "In4.Cu")
		(net "M_D_CPU0_SA_DQS_DN<4>")
	)
	(arc
		(start 329.359768 -246.589042)
		(mid 329.6412 -246.664797)
		(end 329.922632 -246.589042)
		(width 0.09525)
		(layer "In4.Cu")
		(net "M_D_CPU0_SA_DQS_DN<4>")
	)
	(arc
		(start 327.10501 -246.589042)
		(mid 327.284782 -246.538466)
		(end 327.466706 -246.58066)
		(width 0.09525)
		(layer "In4.Cu")
		(net "M_D_CPU0_SA_DQS_DN<4>")
	)
	(arc
		(start 328.042524 -246.589042)
		(mid 328.226299 -246.53827)
		(end 328.411332 -246.584216)
		(width 0.09525)
		(layer "In4.Cu")
		(net "M_D_CPU0_SA_DQS_DN<4>")
	)
	(arc
		(start 334.999584 -246.589042)
		(mid 335.281016 -246.664797)
		(end 335.562448 -246.589042)
		(width 0.09525)
		(layer "In4.Cu")
		(net "M_D_CPU0_SA_DQS_DN<4>")
	)
	(arc
		(start 329.922632 -246.589042)
		(mid 330.1111 -246.538365)
		(end 330.299568 -246.589042)
		(width 0.09525)
		(layer "In4.Cu")
		(net "M_D_CPU0_SA_DQS_DN<4>")
	)
	(arc
		(start 336.879692 -246.589042)
		(mid 337.161124 -246.664797)
		(end 337.442556 -246.589042)
		(width 0.09525)
		(layer "In4.Cu")
		(net "M_D_CPU0_SA_DQS_DN<4>")
	)
	(segment
		(start 339.03793 -242.320064)
		(end 338.571078 -242.054126)
		(width 0.12954)
		(layer "F.Cu")
		(net "M_D_CPU0_SA_DQS_DN<3>")
	)
	(segment
		(start 328.411332 -241.72418)
		(end 328.419714 -241.729006)
		(width 0.09525)
		(layer "In4.Cu")
		(net "M_D_CPU0_SA_DQS_DN<3>")
	)
	(segment
		(start 313.366404 -234.313222)
		(end 313.366404 -234.589828)
		(width 0.16002)
		(layer "In4.Cu")
		(net "M_D_CPU0_SA_DQS_DN<3>")
	)
	(segment
		(start 310.61914 -231.842564)
		(end 310.411114 -232.05059)
		(width 0.16002)
		(layer "In4.Cu")
		(net "M_D_CPU0_SA_DQS_DN<3>")
	)
	(segment
		(start 335.931256 -241.72418)
		(end 335.939638 -241.729006)
		(width 0.09525)
		(layer "In4.Cu")
		(net "M_D_CPU0_SA_DQS_DN<3>")
	)
	(segment
		(start 287.137856 -229.361238)
		(end 287.286954 -229.21214)
		(width 0.16002)
		(layer "In4.Cu")
		(net "M_D_CPU0_SA_DQS_DN<3>")
	)
	(segment
		(start 309.037482 -231.204516)
		(end 309.410354 -231.577388)
		(width 0.16002)
		(layer "In4.Cu")
		(net "M_D_CPU0_SA_DQS_DN<3>")
	)
	(segment
		(start 285.009844 -229.361238)
		(end 287.137856 -229.361238)
		(width 0.16002)
		(layer "In4.Cu")
		(net "M_D_CPU0_SA_DQS_DN<3>")
	)
	(segment
		(start 324.65137 -241.087402)
		(end 325.091044 -241.087402)
		(width 0.09525)
		(layer "In4.Cu")
		(net "M_D_CPU0_SA_DQS_DN<3>")
	)
	(segment
		(start 333.682594 -241.729006)
		(end 333.690976 -241.72418)
		(width 0.09525)
		(layer "In4.Cu")
		(net "M_D_CPU0_SA_DQS_DN<3>")
	)
	(segment
		(start 307.418994 -229.221792)
		(end 307.6956 -229.221792)
		(width 0.16002)
		(layer "In4.Cu")
		(net "M_D_CPU0_SA_DQS_DN<3>")
	)
	(segment
		(start 292.899338 -228.362256)
		(end 293.749222 -229.21214)
		(width 0.16002)
		(layer "In4.Cu")
		(net "M_D_CPU0_SA_DQS_DN<3>")
	)
	(segment
		(start 293.749222 -229.21214)
		(end 294.246808 -229.21214)
		(width 0.16002)
		(layer "In4.Cu")
		(net "M_D_CPU0_SA_DQS_DN<3>")
	)
	(segment
		(start 291.171376 -228.710998)
		(end 291.520118 -228.362256)
		(width 0.16002)
		(layer "In4.Cu")
		(net "M_D_CPU0_SA_DQS_DN<3>")
	)
	(segment
		(start 300.596554 -228.362256)
		(end 301.78629 -229.551992)
		(width 0.16002)
		(layer "In4.Cu")
		(net "M_D_CPU0_SA_DQS_DN<3>")
	)
	(segment
		(start 297.37939 -229.630478)
		(end 298.29887 -228.710998)
		(width 0.16002)
		(layer "In4.Cu")
		(net "M_D_CPU0_SA_DQS_DN<3>")
	)
	(segment
		(start 310.411114 -232.05059)
		(end 310.411114 -232.578148)
		(width 0.16002)
		(layer "In4.Cu")
		(net "M_D_CPU0_SA_DQS_DN<3>")
	)
	(segment
		(start 338.701888 -241.702082)
		(end 338.725002 -241.788696)
		(width 0.09525)
		(layer "In4.Cu")
		(net "M_D_CPU0_SA_DQS_DN<3>")
	)
	(segment
		(start 305.358546 -229.579932)
		(end 305.721004 -229.94239)
		(width 0.16002)
		(layer "In4.Cu")
		(net "M_D_CPU0_SA_DQS_DN<3>")
	)
	(segment
		(start 310.42229 -231.369108)
		(end 310.61914 -231.565958)
		(width 0.16002)
		(layer "In4.Cu")
		(net "M_D_CPU0_SA_DQS_DN<3>")
	)
	(segment
		(start 309.048658 -229.995476)
		(end 309.245508 -230.192326)
		(width 0.16002)
		(layer "In4.Cu")
		(net "M_D_CPU0_SA_DQS_DN<3>")
	)
	(segment
		(start 331.23124 -241.72418)
		(end 331.239622 -241.729006)
		(width 0.09525)
		(layer "In4.Cu")
		(net "M_D_CPU0_SA_DQS_DN<3>")
	)
	(segment
		(start 307.891434 -229.577138)
		(end 308.309772 -229.995476)
		(width 0.16002)
		(layer "In4.Cu")
		(net "M_D_CPU0_SA_DQS_DN<3>")
	)
	(segment
		(start 312.893202 -234.116372)
		(end 313.169554 -234.116372)
		(width 0.16002)
		(layer "In4.Cu")
		(net "M_D_CPU0_SA_DQS_DN<3>")
	)
	(segment
		(start 325.091044 -241.087402)
		(end 325.68134 -241.677698)
		(width 0.09525)
		(layer "In4.Cu")
		(net "M_D_CPU0_SA_DQS_DN<3>")
	)
	(segment
		(start 318.492378 -240.659412)
		(end 323.895974 -240.659412)
		(width 0.16002)
		(layer "In4.Cu")
		(net "M_D_CPU0_SA_DQS_DN<3>")
	)
	(segment
		(start 311.51957 -232.74274)
		(end 311.795922 -232.74274)
		(width 0.16002)
		(layer "In4.Cu")
		(net "M_D_CPU0_SA_DQS_DN<3>")
	)
	(segment
		(start 323.919596 -240.659412)
		(end 323.978524 -240.600484)
		(width 0.09525)
		(layer "In4.Cu")
		(net "M_D_CPU0_SA_DQS_DN<3>")
	)
	(segment
		(start 305.721004 -229.94239)
		(end 306.857908 -229.94239)
		(width 0.16002)
		(layer "In4.Cu")
		(net "M_D_CPU0_SA_DQS_DN<3>")
	)
	(segment
		(start 313.169554 -234.116372)
		(end 313.366404 -234.313222)
		(width 0.16002)
		(layer "In4.Cu")
		(net "M_D_CPU0_SA_DQS_DN<3>")
	)
	(segment
		(start 289.821366 -229.616254)
		(end 290.726622 -228.710998)
		(width 0.16002)
		(layer "In4.Cu")
		(net "M_D_CPU0_SA_DQS_DN<3>")
	)
	(segment
		(start 290.726622 -228.710998)
		(end 291.171376 -228.710998)
		(width 0.16002)
		(layer "In4.Cu")
		(net "M_D_CPU0_SA_DQS_DN<3>")
	)
	(segment
		(start 294.363648 -229.32898)
		(end 294.843708 -229.32898)
		(width 0.16002)
		(layer "In4.Cu")
		(net "M_D_CPU0_SA_DQS_DN<3>")
	)
	(segment
		(start 307.22316 -229.417626)
		(end 307.418994 -229.221792)
		(width 0.16002)
		(layer "In4.Cu")
		(net "M_D_CPU0_SA_DQS_DN<3>")
	)
	(segment
		(start 296.89171 -229.630478)
		(end 297.37939 -229.630478)
		(width 0.16002)
		(layer "In4.Cu")
		(net "M_D_CPU0_SA_DQS_DN<3>")
	)
	(segment
		(start 311.784746 -233.95178)
		(end 312.157618 -234.324652)
		(width 0.16002)
		(layer "In4.Cu")
		(net "M_D_CPU0_SA_DQS_DN<3>")
	)
	(segment
		(start 306.857908 -229.94239)
		(end 307.22316 -229.577138)
		(width 0.16002)
		(layer "In4.Cu")
		(net "M_D_CPU0_SA_DQS_DN<3>")
	)
	(segment
		(start 313.158378 -235.325412)
		(end 318.492378 -240.659412)
		(width 0.16002)
		(layer "In4.Cu")
		(net "M_D_CPU0_SA_DQS_DN<3>")
	)
	(segment
		(start 291.520118 -228.362256)
		(end 292.899338 -228.362256)
		(width 0.16002)
		(layer "In4.Cu")
		(net "M_D_CPU0_SA_DQS_DN<3>")
	)
	(segment
		(start 313.158378 -234.797854)
		(end 313.158378 -235.325412)
		(width 0.16002)
		(layer "In4.Cu")
		(net "M_D_CPU0_SA_DQS_DN<3>")
	)
	(segment
		(start 307.6956 -229.221792)
		(end 307.891434 -229.417626)
		(width 0.16002)
		(layer "In4.Cu")
		(net "M_D_CPU0_SA_DQS_DN<3>")
	)
	(segment
		(start 284.736032 -229.63505)
		(end 285.009844 -229.361238)
		(width 0.16002)
		(layer "In4.Cu")
		(net "M_D_CPU0_SA_DQS_DN<3>")
	)
	(segment
		(start 303.779936 -229.94239)
		(end 304.50282 -229.94239)
		(width 0.16002)
		(layer "In4.Cu")
		(net "M_D_CPU0_SA_DQS_DN<3>")
	)
	(segment
		(start 307.891434 -229.417626)
		(end 307.891434 -229.577138)
		(width 0.16002)
		(layer "In4.Cu")
		(net "M_D_CPU0_SA_DQS_DN<3>")
	)
	(segment
		(start 313.366404 -234.589828)
		(end 313.158378 -234.797854)
		(width 0.16002)
		(layer "In4.Cu")
		(net "M_D_CPU0_SA_DQS_DN<3>")
	)
	(segment
		(start 311.31129 -232.95102)
		(end 311.51957 -232.74274)
		(width 0.16002)
		(layer "In4.Cu")
		(net "M_D_CPU0_SA_DQS_DN<3>")
	)
	(segment
		(start 311.795922 -232.74274)
		(end 311.992772 -232.93959)
		(width 0.16002)
		(layer "In4.Cu")
		(net "M_D_CPU0_SA_DQS_DN<3>")
	)
	(segment
		(start 309.937658 -231.577388)
		(end 310.145938 -231.369108)
		(width 0.16002)
		(layer "In4.Cu")
		(net "M_D_CPU0_SA_DQS_DN<3>")
	)
	(segment
		(start 325.68134 -241.677698)
		(end 326.351138 -241.677698)
		(width 0.09525)
		(layer "In4.Cu")
		(net "M_D_CPU0_SA_DQS_DN<3>")
	)
	(segment
		(start 323.978524 -240.600484)
		(end 324.164452 -240.600484)
		(width 0.09525)
		(layer "In4.Cu")
		(net "M_D_CPU0_SA_DQS_DN<3>")
	)
	(segment
		(start 311.784746 -233.424222)
		(end 311.784746 -233.95178)
		(width 0.16002)
		(layer "In4.Cu")
		(net "M_D_CPU0_SA_DQS_DN<3>")
	)
	(segment
		(start 308.309772 -229.995476)
		(end 309.048658 -229.995476)
		(width 0.16002)
		(layer "In4.Cu")
		(net "M_D_CPU0_SA_DQS_DN<3>")
	)
	(segment
		(start 323.895974 -240.659412)
		(end 323.919596 -240.659412)
		(width 0.09525)
		(layer "In4.Cu")
		(net "M_D_CPU0_SA_DQS_DN<3>")
	)
	(segment
		(start 311.992772 -233.216196)
		(end 311.784746 -233.424222)
		(width 0.16002)
		(layer "In4.Cu")
		(net "M_D_CPU0_SA_DQS_DN<3>")
	)
	(segment
		(start 296.473372 -229.21214)
		(end 296.89171 -229.630478)
		(width 0.16002)
		(layer "In4.Cu")
		(net "M_D_CPU0_SA_DQS_DN<3>")
	)
	(segment
		(start 311.992772 -232.93959)
		(end 311.992772 -233.216196)
		(width 0.16002)
		(layer "In4.Cu")
		(net "M_D_CPU0_SA_DQS_DN<3>")
	)
	(segment
		(start 332.171294 -241.72418)
		(end 332.179676 -241.729006)
		(width 0.09525)
		(layer "In4.Cu")
		(net "M_D_CPU0_SA_DQS_DN<3>")
	)
	(segment
		(start 310.411114 -232.578148)
		(end 310.783986 -232.95102)
		(width 0.16002)
		(layer "In4.Cu")
		(net "M_D_CPU0_SA_DQS_DN<3>")
	)
	(segment
		(start 309.245508 -230.192326)
		(end 309.245508 -230.468932)
		(width 0.16002)
		(layer "In4.Cu")
		(net "M_D_CPU0_SA_DQS_DN<3>")
	)
	(segment
		(start 309.037482 -230.677212)
		(end 309.037482 -231.204516)
		(width 0.16002)
		(layer "In4.Cu")
		(net "M_D_CPU0_SA_DQS_DN<3>")
	)
	(segment
		(start 301.78629 -229.551992)
		(end 303.389538 -229.551992)
		(width 0.16002)
		(layer "In4.Cu")
		(net "M_D_CPU0_SA_DQS_DN<3>")
	)
	(segment
		(start 304.50282 -229.94239)
		(end 304.865278 -229.579932)
		(width 0.16002)
		(layer "In4.Cu")
		(net "M_D_CPU0_SA_DQS_DN<3>")
	)
	(segment
		(start 310.61914 -231.565958)
		(end 310.61914 -231.842564)
		(width 0.16002)
		(layer "In4.Cu")
		(net "M_D_CPU0_SA_DQS_DN<3>")
	)
	(segment
		(start 298.29887 -228.710998)
		(end 298.715176 -228.710998)
		(width 0.16002)
		(layer "In4.Cu")
		(net "M_D_CPU0_SA_DQS_DN<3>")
	)
	(segment
		(start 309.410354 -231.577388)
		(end 309.937658 -231.577388)
		(width 0.16002)
		(layer "In4.Cu")
		(net "M_D_CPU0_SA_DQS_DN<3>")
	)
	(segment
		(start 309.245508 -230.468932)
		(end 309.037482 -230.677212)
		(width 0.16002)
		(layer "In4.Cu")
		(net "M_D_CPU0_SA_DQS_DN<3>")
	)
	(segment
		(start 288.929572 -229.21214)
		(end 289.333686 -229.616254)
		(width 0.16002)
		(layer "In4.Cu")
		(net "M_D_CPU0_SA_DQS_DN<3>")
	)
	(segment
		(start 327.471278 -241.72418)
		(end 327.47966 -241.729006)
		(width 0.09525)
		(layer "In4.Cu")
		(net "M_D_CPU0_SA_DQS_DN<3>")
	)
	(segment
		(start 312.684922 -234.324652)
		(end 312.893202 -234.116372)
		(width 0.16002)
		(layer "In4.Cu")
		(net "M_D_CPU0_SA_DQS_DN<3>")
	)
	(segment
		(start 307.22316 -229.577138)
		(end 307.22316 -229.417626)
		(width 0.16002)
		(layer "In4.Cu")
		(net "M_D_CPU0_SA_DQS_DN<3>")
	)
	(segment
		(start 310.783986 -232.95102)
		(end 311.31129 -232.95102)
		(width 0.16002)
		(layer "In4.Cu")
		(net "M_D_CPU0_SA_DQS_DN<3>")
	)
	(segment
		(start 304.865278 -229.579932)
		(end 305.358546 -229.579932)
		(width 0.16002)
		(layer "In4.Cu")
		(net "M_D_CPU0_SA_DQS_DN<3>")
	)
	(segment
		(start 299.063918 -228.362256)
		(end 300.596554 -228.362256)
		(width 0.16002)
		(layer "In4.Cu")
		(net "M_D_CPU0_SA_DQS_DN<3>")
	)
	(segment
		(start 324.164452 -240.600484)
		(end 324.65137 -241.087402)
		(width 0.09525)
		(layer "In4.Cu")
		(net "M_D_CPU0_SA_DQS_DN<3>")
	)
	(segment
		(start 337.442556 -241.729006)
		(end 337.450938 -241.72418)
		(width 0.09525)
		(layer "In4.Cu")
		(net "M_D_CPU0_SA_DQS_DN<3>")
	)
	(segment
		(start 303.389538 -229.551992)
		(end 303.779936 -229.94239)
		(width 0.16002)
		(layer "In4.Cu")
		(net "M_D_CPU0_SA_DQS_DN<3>")
	)
	(segment
		(start 294.843708 -229.32898)
		(end 294.960548 -229.21214)
		(width 0.16002)
		(layer "In4.Cu")
		(net "M_D_CPU0_SA_DQS_DN<3>")
	)
	(segment
		(start 312.157618 -234.324652)
		(end 312.684922 -234.324652)
		(width 0.16002)
		(layer "In4.Cu")
		(net "M_D_CPU0_SA_DQS_DN<3>")
	)
	(segment
		(start 336.87131 -241.72418)
		(end 336.879692 -241.729006)
		(width 0.09525)
		(layer "In4.Cu")
		(net "M_D_CPU0_SA_DQS_DN<3>")
	)
	(segment
		(start 328.982578 -241.729006)
		(end 328.99096 -241.72418)
		(width 0.09525)
		(layer "In4.Cu")
		(net "M_D_CPU0_SA_DQS_DN<3>")
	)
	(segment
		(start 310.145938 -231.369108)
		(end 310.42229 -231.369108)
		(width 0.16002)
		(layer "In4.Cu")
		(net "M_D_CPU0_SA_DQS_DN<3>")
	)
	(segment
		(start 289.333686 -229.616254)
		(end 289.821366 -229.616254)
		(width 0.16002)
		(layer "In4.Cu")
		(net "M_D_CPU0_SA_DQS_DN<3>")
	)
	(segment
		(start 332.74254 -241.729006)
		(end 332.750922 -241.72418)
		(width 0.09525)
		(layer "In4.Cu")
		(net "M_D_CPU0_SA_DQS_DN<3>")
	)
	(segment
		(start 294.246808 -229.21214)
		(end 294.363648 -229.32898)
		(width 0.16002)
		(layer "In4.Cu")
		(net "M_D_CPU0_SA_DQS_DN<3>")
	)
	(segment
		(start 287.286954 -229.21214)
		(end 288.929572 -229.21214)
		(width 0.16002)
		(layer "In4.Cu")
		(net "M_D_CPU0_SA_DQS_DN<3>")
	)
	(segment
		(start 298.715176 -228.710998)
		(end 299.063918 -228.362256)
		(width 0.16002)
		(layer "In4.Cu")
		(net "M_D_CPU0_SA_DQS_DN<3>")
	)
	(segment
		(start 338.725002 -241.788696)
		(end 338.571078 -242.054126)
		(width 0.09525)
		(layer "In4.Cu")
		(net "M_D_CPU0_SA_DQS_DN<3>")
	)
	(segment
		(start 294.960548 -229.21214)
		(end 296.473372 -229.21214)
		(width 0.16002)
		(layer "In4.Cu")
		(net "M_D_CPU0_SA_DQS_DN<3>")
	)
	(arc
		(start 330.862432 -241.729006)
		(mid 331.046207 -241.678234)
		(end 331.23124 -241.72418)
		(width 0.09525)
		(layer "In4.Cu")
		(net "M_D_CPU0_SA_DQS_DN<3>")
	)
	(arc
		(start 335.562448 -241.729006)
		(mid 335.746223 -241.678234)
		(end 335.931256 -241.72418)
		(width 0.09525)
		(layer "In4.Cu")
		(net "M_D_CPU0_SA_DQS_DN<3>")
	)
	(arc
		(start 331.239622 -241.729006)
		(mid 331.521054 -241.804761)
		(end 331.802486 -241.729006)
		(width 0.09525)
		(layer "In4.Cu")
		(net "M_D_CPU0_SA_DQS_DN<3>")
	)
	(arc
		(start 336.502502 -241.729006)
		(mid 336.686277 -241.678234)
		(end 336.87131 -241.72418)
		(width 0.09525)
		(layer "In4.Cu")
		(net "M_D_CPU0_SA_DQS_DN<3>")
	)
	(arc
		(start 333.690976 -241.72418)
		(mid 333.876008 -241.678266)
		(end 334.059784 -241.729006)
		(width 0.09525)
		(layer "In4.Cu")
		(net "M_D_CPU0_SA_DQS_DN<3>")
	)
	(arc
		(start 329.359768 -241.729006)
		(mid 329.6412 -241.804761)
		(end 329.922632 -241.729006)
		(width 0.09525)
		(layer "In4.Cu")
		(net "M_D_CPU0_SA_DQS_DN<3>")
	)
	(arc
		(start 327.10247 -241.729006)
		(mid 327.286245 -241.678234)
		(end 327.471278 -241.72418)
		(width 0.09525)
		(layer "In4.Cu")
		(net "M_D_CPU0_SA_DQS_DN<3>")
	)
	(arc
		(start 326.351138 -241.677698)
		(mid 326.448752 -241.690925)
		(end 326.539606 -241.729006)
		(width 0.09525)
		(layer "In4.Cu")
		(net "M_D_CPU0_SA_DQS_DN<3>")
	)
	(arc
		(start 336.879692 -241.729006)
		(mid 337.161124 -241.804761)
		(end 337.442556 -241.729006)
		(width 0.09525)
		(layer "In4.Cu")
		(net "M_D_CPU0_SA_DQS_DN<3>")
	)
	(arc
		(start 328.99096 -241.72418)
		(mid 329.175992 -241.678266)
		(end 329.359768 -241.729006)
		(width 0.09525)
		(layer "In4.Cu")
		(net "M_D_CPU0_SA_DQS_DN<3>")
	)
	(arc
		(start 326.539606 -241.729006)
		(mid 326.821038 -241.804761)
		(end 327.10247 -241.729006)
		(width 0.09525)
		(layer "In4.Cu")
		(net "M_D_CPU0_SA_DQS_DN<3>")
	)
	(arc
		(start 334.059784 -241.729006)
		(mid 334.341216 -241.804761)
		(end 334.622648 -241.729006)
		(width 0.09525)
		(layer "In4.Cu")
		(net "M_D_CPU0_SA_DQS_DN<3>")
	)
	(arc
		(start 329.922632 -241.729006)
		(mid 330.1111 -241.678329)
		(end 330.299568 -241.729006)
		(width 0.09525)
		(layer "In4.Cu")
		(net "M_D_CPU0_SA_DQS_DN<3>")
	)
	(arc
		(start 337.450938 -241.72418)
		(mid 337.63597 -241.678266)
		(end 337.819746 -241.729006)
		(width 0.09525)
		(layer "In4.Cu")
		(net "M_D_CPU0_SA_DQS_DN<3>")
	)
	(arc
		(start 327.47966 -241.729006)
		(mid 327.761092 -241.804761)
		(end 328.042524 -241.729006)
		(width 0.09525)
		(layer "In4.Cu")
		(net "M_D_CPU0_SA_DQS_DN<3>")
	)
	(arc
		(start 334.622648 -241.729006)
		(mid 334.811116 -241.678329)
		(end 334.999584 -241.729006)
		(width 0.09525)
		(layer "In4.Cu")
		(net "M_D_CPU0_SA_DQS_DN<3>")
	)
	(arc
		(start 330.299568 -241.729006)
		(mid 330.581 -241.804761)
		(end 330.862432 -241.729006)
		(width 0.09525)
		(layer "In4.Cu")
		(net "M_D_CPU0_SA_DQS_DN<3>")
	)
	(arc
		(start 338.38261 -241.729006)
		(mid 338.539237 -241.67982)
		(end 338.701888 -241.702082)
		(width 0.09525)
		(layer "In4.Cu")
		(net "M_D_CPU0_SA_DQS_DN<3>")
	)
	(arc
		(start 334.999584 -241.729006)
		(mid 335.281016 -241.804761)
		(end 335.562448 -241.729006)
		(width 0.09525)
		(layer "In4.Cu")
		(net "M_D_CPU0_SA_DQS_DN<3>")
	)
	(arc
		(start 328.042524 -241.729006)
		(mid 328.226299 -241.678234)
		(end 328.411332 -241.72418)
		(width 0.09525)
		(layer "In4.Cu")
		(net "M_D_CPU0_SA_DQS_DN<3>")
	)
	(arc
		(start 335.939638 -241.729006)
		(mid 336.22107 -241.804761)
		(end 336.502502 -241.729006)
		(width 0.09525)
		(layer "In4.Cu")
		(net "M_D_CPU0_SA_DQS_DN<3>")
	)
	(arc
		(start 333.11973 -241.729006)
		(mid 333.401162 -241.804761)
		(end 333.682594 -241.729006)
		(width 0.09525)
		(layer "In4.Cu")
		(net "M_D_CPU0_SA_DQS_DN<3>")
	)
	(arc
		(start 331.802486 -241.729006)
		(mid 331.986261 -241.678234)
		(end 332.171294 -241.72418)
		(width 0.09525)
		(layer "In4.Cu")
		(net "M_D_CPU0_SA_DQS_DN<3>")
	)
	(arc
		(start 337.819746 -241.729006)
		(mid 338.101178 -241.804761)
		(end 338.38261 -241.729006)
		(width 0.09525)
		(layer "In4.Cu")
		(net "M_D_CPU0_SA_DQS_DN<3>")
	)
	(arc
		(start 332.750922 -241.72418)
		(mid 332.935954 -241.678266)
		(end 333.11973 -241.729006)
		(width 0.09525)
		(layer "In4.Cu")
		(net "M_D_CPU0_SA_DQS_DN<3>")
	)
	(arc
		(start 332.179676 -241.729006)
		(mid 332.461108 -241.804761)
		(end 332.74254 -241.729006)
		(width 0.09525)
		(layer "In4.Cu")
		(net "M_D_CPU0_SA_DQS_DN<3>")
	)
	(arc
		(start 328.419714 -241.729006)
		(mid 328.701146 -241.804761)
		(end 328.982578 -241.729006)
		(width 0.09525)
		(layer "In4.Cu")
		(net "M_D_CPU0_SA_DQS_DN<3>")
	)
	(segment
		(start 339.03793 -237.460028)
		(end 338.571078 -237.19409)
		(width 0.12954)
		(layer "F.Cu")
		(net "M_D_CPU0_SA_DQS_DN<2>")
	)
	(segment
		(start 323.919596 -235.036106)
		(end 323.978778 -234.976924)
		(width 0.09525)
		(layer "In4.Cu")
		(net "M_D_CPU0_SA_DQS_DN<2>")
	)
	(segment
		(start 333.682594 -236.86897)
		(end 333.690976 -236.864144)
		(width 0.09525)
		(layer "In4.Cu")
		(net "M_D_CPU0_SA_DQS_DN<2>")
	)
	(segment
		(start 291.171376 -219.361004)
		(end 291.520118 -219.012262)
		(width 0.16002)
		(layer "In4.Cu")
		(net "M_D_CPU0_SA_DQS_DN<2>")
	)
	(segment
		(start 311.126378 -222.855028)
		(end 310.71439 -223.267016)
		(width 0.16002)
		(layer "In4.Cu")
		(net "M_D_CPU0_SA_DQS_DN<2>")
	)
	(segment
		(start 287.145476 -220.011244)
		(end 287.294574 -219.862146)
		(width 0.16002)
		(layer "In4.Cu")
		(net "M_D_CPU0_SA_DQS_DN<2>")
	)
	(segment
		(start 312.50001 -224.22866)
		(end 312.088022 -224.640648)
		(width 0.16002)
		(layer "In4.Cu")
		(net "M_D_CPU0_SA_DQS_DN<2>")
	)
	(segment
		(start 301.635922 -220.05163)
		(end 302.51527 -220.05163)
		(width 0.16002)
		(layer "In4.Cu")
		(net "M_D_CPU0_SA_DQS_DN<2>")
	)
	(segment
		(start 314.46216 -226.914456)
		(end 314.835286 -227.287582)
		(width 0.16002)
		(layer "In4.Cu")
		(net "M_D_CPU0_SA_DQS_DN<2>")
	)
	(segment
		(start 313.873642 -225.325686)
		(end 313.873642 -225.602292)
		(width 0.16002)
		(layer "In4.Cu")
		(net "M_D_CPU0_SA_DQS_DN<2>")
	)
	(segment
		(start 311.126378 -222.578422)
		(end 311.126378 -222.855028)
		(width 0.16002)
		(layer "In4.Cu")
		(net "M_D_CPU0_SA_DQS_DN<2>")
	)
	(segment
		(start 314.835286 -227.915216)
		(end 321.956176 -235.036106)
		(width 0.16002)
		(layer "In4.Cu")
		(net "M_D_CPU0_SA_DQS_DN<2>")
	)
	(segment
		(start 313.677046 -225.12909)
		(end 313.873642 -225.325686)
		(width 0.16002)
		(layer "In4.Cu")
		(net "M_D_CPU0_SA_DQS_DN<2>")
	)
	(segment
		(start 326.100186 -236.8169)
		(end 326.351138 -236.8169)
		(width 0.09525)
		(layer "In4.Cu")
		(net "M_D_CPU0_SA_DQS_DN<2>")
	)
	(segment
		(start 312.988452 -225.540824)
		(end 313.400186 -225.12909)
		(width 0.16002)
		(layer "In4.Cu")
		(net "M_D_CPU0_SA_DQS_DN<2>")
	)
	(segment
		(start 300.596554 -219.012262)
		(end 301.635922 -220.05163)
		(width 0.16002)
		(layer "In4.Cu")
		(net "M_D_CPU0_SA_DQS_DN<2>")
	)
	(segment
		(start 311.087262 -224.167192)
		(end 311.61482 -224.167192)
		(width 0.16002)
		(layer "In4.Cu")
		(net "M_D_CPU0_SA_DQS_DN<2>")
	)
	(segment
		(start 299.063918 -219.012262)
		(end 300.596554 -219.012262)
		(width 0.16002)
		(layer "In4.Cu")
		(net "M_D_CPU0_SA_DQS_DN<2>")
	)
	(segment
		(start 312.088022 -225.167952)
		(end 312.460894 -225.540824)
		(width 0.16002)
		(layer "In4.Cu")
		(net "M_D_CPU0_SA_DQS_DN<2>")
	)
	(segment
		(start 310.929782 -222.381826)
		(end 311.126378 -222.578422)
		(width 0.16002)
		(layer "In4.Cu")
		(net "M_D_CPU0_SA_DQS_DN<2>")
	)
	(segment
		(start 291.520118 -219.012262)
		(end 292.89121 -219.012262)
		(width 0.16002)
		(layer "In4.Cu")
		(net "M_D_CPU0_SA_DQS_DN<2>")
	)
	(segment
		(start 296.89171 -220.280484)
		(end 297.37939 -220.280484)
		(width 0.16002)
		(layer "In4.Cu")
		(net "M_D_CPU0_SA_DQS_DN<2>")
	)
	(segment
		(start 313.461654 -226.541584)
		(end 313.834526 -226.914456)
		(width 0.16002)
		(layer "In4.Cu")
		(net "M_D_CPU0_SA_DQS_DN<2>")
	)
	(segment
		(start 313.400186 -225.12909)
		(end 313.677046 -225.12909)
		(width 0.16002)
		(layer "In4.Cu")
		(net "M_D_CPU0_SA_DQS_DN<2>")
	)
	(segment
		(start 311.61482 -224.167192)
		(end 312.026554 -223.755458)
		(width 0.16002)
		(layer "In4.Cu")
		(net "M_D_CPU0_SA_DQS_DN<2>")
	)
	(segment
		(start 285.009844 -220.011244)
		(end 287.145476 -220.011244)
		(width 0.16002)
		(layer "In4.Cu")
		(net "M_D_CPU0_SA_DQS_DN<2>")
	)
	(segment
		(start 292.89121 -219.012262)
		(end 293.741094 -219.862146)
		(width 0.16002)
		(layer "In4.Cu")
		(net "M_D_CPU0_SA_DQS_DN<2>")
	)
	(segment
		(start 309.274718 -221.985332)
		(end 309.274718 -222.354648)
		(width 0.16002)
		(layer "In4.Cu")
		(net "M_D_CPU0_SA_DQS_DN<2>")
	)
	(segment
		(start 303.08423 -220.62059)
		(end 307.909976 -220.62059)
		(width 0.16002)
		(layer "In4.Cu")
		(net "M_D_CPU0_SA_DQS_DN<2>")
	)
	(segment
		(start 337.442556 -236.86897)
		(end 337.450938 -236.864144)
		(width 0.09525)
		(layer "In4.Cu")
		(net "M_D_CPU0_SA_DQS_DN<2>")
	)
	(segment
		(start 310.71439 -223.267016)
		(end 310.71439 -223.79432)
		(width 0.16002)
		(layer "In4.Cu")
		(net "M_D_CPU0_SA_DQS_DN<2>")
	)
	(segment
		(start 298.715176 -219.361004)
		(end 299.063918 -219.012262)
		(width 0.16002)
		(layer "In4.Cu")
		(net "M_D_CPU0_SA_DQS_DN<2>")
	)
	(segment
		(start 289.821366 -220.26626)
		(end 290.726622 -219.361004)
		(width 0.16002)
		(layer "In4.Cu")
		(net "M_D_CPU0_SA_DQS_DN<2>")
	)
	(segment
		(start 324.637908 -235.710222)
		(end 324.993508 -235.710222)
		(width 0.09525)
		(layer "In4.Cu")
		(net "M_D_CPU0_SA_DQS_DN<2>")
	)
	(segment
		(start 293.741094 -219.862146)
		(end 294.282368 -219.862146)
		(width 0.16002)
		(layer "In4.Cu")
		(net "M_D_CPU0_SA_DQS_DN<2>")
	)
	(segment
		(start 321.956176 -235.036106)
		(end 323.895974 -235.036106)
		(width 0.16002)
		(layer "In4.Cu")
		(net "M_D_CPU0_SA_DQS_DN<2>")
	)
	(segment
		(start 324.113652 -234.976924)
		(end 324.208902 -235.072174)
		(width 0.09525)
		(layer "In4.Cu")
		(net "M_D_CPU0_SA_DQS_DN<2>")
	)
	(segment
		(start 323.978778 -234.976924)
		(end 324.113652 -234.976924)
		(width 0.09525)
		(layer "In4.Cu")
		(net "M_D_CPU0_SA_DQS_DN<2>")
	)
	(segment
		(start 309.274718 -222.354648)
		(end 309.71363 -222.79356)
		(width 0.16002)
		(layer "In4.Cu")
		(net "M_D_CPU0_SA_DQS_DN<2>")
	)
	(segment
		(start 313.834526 -226.914456)
		(end 314.46216 -226.914456)
		(width 0.16002)
		(layer "In4.Cu")
		(net "M_D_CPU0_SA_DQS_DN<2>")
	)
	(segment
		(start 327.481184 -236.86897)
		(end 327.506584 -236.883702)
		(width 0.09525)
		(layer "In4.Cu")
		(net "M_D_CPU0_SA_DQS_DN<2>")
	)
	(segment
		(start 289.333686 -220.26626)
		(end 289.821366 -220.26626)
		(width 0.16002)
		(layer "In4.Cu")
		(net "M_D_CPU0_SA_DQS_DN<2>")
	)
	(segment
		(start 307.909976 -220.62059)
		(end 309.274718 -221.985332)
		(width 0.16002)
		(layer "In4.Cu")
		(net "M_D_CPU0_SA_DQS_DN<2>")
	)
	(segment
		(start 312.303414 -223.755458)
		(end 312.50001 -223.952054)
		(width 0.16002)
		(layer "In4.Cu")
		(net "M_D_CPU0_SA_DQS_DN<2>")
	)
	(segment
		(start 310.652922 -222.381826)
		(end 310.929782 -222.381826)
		(width 0.16002)
		(layer "In4.Cu")
		(net "M_D_CPU0_SA_DQS_DN<2>")
	)
	(segment
		(start 327.081642 -236.882432)
		(end 327.10501 -236.86897)
		(width 0.09525)
		(layer "In4.Cu")
		(net "M_D_CPU0_SA_DQS_DN<2>")
	)
	(segment
		(start 309.71363 -222.79356)
		(end 310.241188 -222.79356)
		(width 0.16002)
		(layer "In4.Cu")
		(net "M_D_CPU0_SA_DQS_DN<2>")
	)
	(segment
		(start 294.996108 -219.862146)
		(end 296.473372 -219.862146)
		(width 0.16002)
		(layer "In4.Cu")
		(net "M_D_CPU0_SA_DQS_DN<2>")
	)
	(segment
		(start 328.982578 -236.86897)
		(end 328.99096 -236.864144)
		(width 0.09525)
		(layer "In4.Cu")
		(net "M_D_CPU0_SA_DQS_DN<2>")
	)
	(segment
		(start 332.171294 -236.864144)
		(end 332.179676 -236.86897)
		(width 0.09525)
		(layer "In4.Cu")
		(net "M_D_CPU0_SA_DQS_DN<2>")
	)
	(segment
		(start 338.701888 -236.842046)
		(end 338.725002 -236.92866)
		(width 0.09525)
		(layer "In4.Cu")
		(net "M_D_CPU0_SA_DQS_DN<2>")
	)
	(segment
		(start 338.725002 -236.92866)
		(end 338.571078 -237.19409)
		(width 0.09525)
		(layer "In4.Cu")
		(net "M_D_CPU0_SA_DQS_DN<2>")
	)
	(segment
		(start 298.29887 -219.361004)
		(end 298.715176 -219.361004)
		(width 0.16002)
		(layer "In4.Cu")
		(net "M_D_CPU0_SA_DQS_DN<2>")
	)
	(segment
		(start 294.399208 -219.978986)
		(end 294.879268 -219.978986)
		(width 0.16002)
		(layer "In4.Cu")
		(net "M_D_CPU0_SA_DQS_DN<2>")
	)
	(segment
		(start 313.461654 -226.01428)
		(end 313.461654 -226.541584)
		(width 0.16002)
		(layer "In4.Cu")
		(net "M_D_CPU0_SA_DQS_DN<2>")
	)
	(segment
		(start 310.71439 -223.79432)
		(end 311.087262 -224.167192)
		(width 0.16002)
		(layer "In4.Cu")
		(net "M_D_CPU0_SA_DQS_DN<2>")
	)
	(segment
		(start 324.208902 -235.281216)
		(end 324.637908 -235.710222)
		(width 0.09525)
		(layer "In4.Cu")
		(net "M_D_CPU0_SA_DQS_DN<2>")
	)
	(segment
		(start 312.50001 -223.952054)
		(end 312.50001 -224.22866)
		(width 0.16002)
		(layer "In4.Cu")
		(net "M_D_CPU0_SA_DQS_DN<2>")
	)
	(segment
		(start 312.460894 -225.540824)
		(end 312.988452 -225.540824)
		(width 0.16002)
		(layer "In4.Cu")
		(net "M_D_CPU0_SA_DQS_DN<2>")
	)
	(segment
		(start 284.736032 -220.285056)
		(end 285.009844 -220.011244)
		(width 0.16002)
		(layer "In4.Cu")
		(net "M_D_CPU0_SA_DQS_DN<2>")
	)
	(segment
		(start 302.51527 -220.05163)
		(end 303.08423 -220.62059)
		(width 0.16002)
		(layer "In4.Cu")
		(net "M_D_CPU0_SA_DQS_DN<2>")
	)
	(segment
		(start 314.835286 -227.287582)
		(end 314.835286 -227.915216)
		(width 0.16002)
		(layer "In4.Cu")
		(net "M_D_CPU0_SA_DQS_DN<2>")
	)
	(segment
		(start 336.87131 -236.864144)
		(end 336.879692 -236.86897)
		(width 0.09525)
		(layer "In4.Cu")
		(net "M_D_CPU0_SA_DQS_DN<2>")
	)
	(segment
		(start 324.993508 -235.710222)
		(end 326.100186 -236.8169)
		(width 0.09525)
		(layer "In4.Cu")
		(net "M_D_CPU0_SA_DQS_DN<2>")
	)
	(segment
		(start 294.282368 -219.862146)
		(end 294.399208 -219.978986)
		(width 0.16002)
		(layer "In4.Cu")
		(net "M_D_CPU0_SA_DQS_DN<2>")
	)
	(segment
		(start 294.879268 -219.978986)
		(end 294.996108 -219.862146)
		(width 0.16002)
		(layer "In4.Cu")
		(net "M_D_CPU0_SA_DQS_DN<2>")
	)
	(segment
		(start 296.473372 -219.862146)
		(end 296.89171 -220.280484)
		(width 0.16002)
		(layer "In4.Cu")
		(net "M_D_CPU0_SA_DQS_DN<2>")
	)
	(segment
		(start 313.873642 -225.602292)
		(end 313.461654 -226.01428)
		(width 0.16002)
		(layer "In4.Cu")
		(net "M_D_CPU0_SA_DQS_DN<2>")
	)
	(segment
		(start 312.026554 -223.755458)
		(end 312.303414 -223.755458)
		(width 0.16002)
		(layer "In4.Cu")
		(net "M_D_CPU0_SA_DQS_DN<2>")
	)
	(segment
		(start 312.088022 -224.640648)
		(end 312.088022 -225.167952)
		(width 0.16002)
		(layer "In4.Cu")
		(net "M_D_CPU0_SA_DQS_DN<2>")
	)
	(segment
		(start 310.241188 -222.79356)
		(end 310.652922 -222.381826)
		(width 0.16002)
		(layer "In4.Cu")
		(net "M_D_CPU0_SA_DQS_DN<2>")
	)
	(segment
		(start 297.37939 -220.280484)
		(end 298.29887 -219.361004)
		(width 0.16002)
		(layer "In4.Cu")
		(net "M_D_CPU0_SA_DQS_DN<2>")
	)
	(segment
		(start 328.411332 -236.864144)
		(end 328.419714 -236.86897)
		(width 0.09525)
		(layer "In4.Cu")
		(net "M_D_CPU0_SA_DQS_DN<2>")
	)
	(segment
		(start 324.208902 -235.072174)
		(end 324.208902 -235.281216)
		(width 0.09525)
		(layer "In4.Cu")
		(net "M_D_CPU0_SA_DQS_DN<2>")
	)
	(segment
		(start 323.895974 -235.036106)
		(end 323.919596 -235.036106)
		(width 0.09525)
		(layer "In4.Cu")
		(net "M_D_CPU0_SA_DQS_DN<2>")
	)
	(segment
		(start 331.23124 -236.864144)
		(end 331.239622 -236.86897)
		(width 0.09525)
		(layer "In4.Cu")
		(net "M_D_CPU0_SA_DQS_DN<2>")
	)
	(segment
		(start 288.929572 -219.862146)
		(end 289.333686 -220.26626)
		(width 0.16002)
		(layer "In4.Cu")
		(net "M_D_CPU0_SA_DQS_DN<2>")
	)
	(segment
		(start 287.294574 -219.862146)
		(end 288.929572 -219.862146)
		(width 0.16002)
		(layer "In4.Cu")
		(net "M_D_CPU0_SA_DQS_DN<2>")
	)
	(segment
		(start 335.931256 -236.864144)
		(end 335.939638 -236.86897)
		(width 0.09525)
		(layer "In4.Cu")
		(net "M_D_CPU0_SA_DQS_DN<2>")
	)
	(segment
		(start 290.726622 -219.361004)
		(end 291.171376 -219.361004)
		(width 0.16002)
		(layer "In4.Cu")
		(net "M_D_CPU0_SA_DQS_DN<2>")
	)
	(segment
		(start 332.74254 -236.86897)
		(end 332.750922 -236.864144)
		(width 0.09525)
		(layer "In4.Cu")
		(net "M_D_CPU0_SA_DQS_DN<2>")
	)
	(segment
		(start 327.466706 -236.860588)
		(end 327.481184 -236.86897)
		(width 0.09525)
		(layer "In4.Cu")
		(net "M_D_CPU0_SA_DQS_DN<2>")
	)
	(arc
		(start 336.879692 -236.86897)
		(mid 337.161124 -236.944725)
		(end 337.442556 -236.86897)
		(width 0.09525)
		(layer "In4.Cu")
		(net "M_D_CPU0_SA_DQS_DN<2>")
	)
	(arc
		(start 335.562448 -236.86897)
		(mid 335.746223 -236.818198)
		(end 335.931256 -236.864144)
		(width 0.09525)
		(layer "In4.Cu")
		(net "M_D_CPU0_SA_DQS_DN<2>")
	)
	(arc
		(start 337.819746 -236.86897)
		(mid 338.101178 -236.944725)
		(end 338.38261 -236.86897)
		(width 0.09525)
		(layer "In4.Cu")
		(net "M_D_CPU0_SA_DQS_DN<2>")
	)
	(arc
		(start 329.922632 -236.86897)
		(mid 330.1111 -236.818293)
		(end 330.299568 -236.86897)
		(width 0.09525)
		(layer "In4.Cu")
		(net "M_D_CPU0_SA_DQS_DN<2>")
	)
	(arc
		(start 331.239622 -236.86897)
		(mid 331.521054 -236.944725)
		(end 331.802486 -236.86897)
		(width 0.09525)
		(layer "In4.Cu")
		(net "M_D_CPU0_SA_DQS_DN<2>")
	)
	(arc
		(start 328.99096 -236.864144)
		(mid 329.175992 -236.81823)
		(end 329.359768 -236.86897)
		(width 0.09525)
		(layer "In4.Cu")
		(net "M_D_CPU0_SA_DQS_DN<2>")
	)
	(arc
		(start 333.11973 -236.86897)
		(mid 333.401162 -236.944725)
		(end 333.682594 -236.86897)
		(width 0.09525)
		(layer "In4.Cu")
		(net "M_D_CPU0_SA_DQS_DN<2>")
	)
	(arc
		(start 333.690976 -236.864144)
		(mid 333.876008 -236.81823)
		(end 334.059784 -236.86897)
		(width 0.09525)
		(layer "In4.Cu")
		(net "M_D_CPU0_SA_DQS_DN<2>")
	)
	(arc
		(start 334.622648 -236.86897)
		(mid 334.811116 -236.818293)
		(end 334.999584 -236.86897)
		(width 0.09525)
		(layer "In4.Cu")
		(net "M_D_CPU0_SA_DQS_DN<2>")
	)
	(arc
		(start 337.450938 -236.864144)
		(mid 337.63597 -236.81823)
		(end 337.819746 -236.86897)
		(width 0.09525)
		(layer "In4.Cu")
		(net "M_D_CPU0_SA_DQS_DN<2>")
	)
	(arc
		(start 326.540876 -236.86897)
		(mid 326.809539 -236.945188)
		(end 327.081642 -236.882432)
		(width 0.09525)
		(layer "In4.Cu")
		(net "M_D_CPU0_SA_DQS_DN<2>")
	)
	(arc
		(start 329.359768 -236.86897)
		(mid 329.6412 -236.944725)
		(end 329.922632 -236.86897)
		(width 0.09525)
		(layer "In4.Cu")
		(net "M_D_CPU0_SA_DQS_DN<2>")
	)
	(arc
		(start 328.042524 -236.86897)
		(mid 328.226299 -236.818198)
		(end 328.411332 -236.864144)
		(width 0.09525)
		(layer "In4.Cu")
		(net "M_D_CPU0_SA_DQS_DN<2>")
	)
	(arc
		(start 332.179676 -236.86897)
		(mid 332.461108 -236.944725)
		(end 332.74254 -236.86897)
		(width 0.09525)
		(layer "In4.Cu")
		(net "M_D_CPU0_SA_DQS_DN<2>")
	)
	(arc
		(start 326.351138 -236.8169)
		(mid 326.449476 -236.830306)
		(end 326.540876 -236.86897)
		(width 0.09525)
		(layer "In4.Cu")
		(net "M_D_CPU0_SA_DQS_DN<2>")
	)
	(arc
		(start 328.419714 -236.86897)
		(mid 328.701146 -236.944725)
		(end 328.982578 -236.86897)
		(width 0.09525)
		(layer "In4.Cu")
		(net "M_D_CPU0_SA_DQS_DN<2>")
	)
	(arc
		(start 332.750922 -236.864144)
		(mid 332.935954 -236.81823)
		(end 333.11973 -236.86897)
		(width 0.09525)
		(layer "In4.Cu")
		(net "M_D_CPU0_SA_DQS_DN<2>")
	)
	(arc
		(start 334.059784 -236.86897)
		(mid 334.341216 -236.944725)
		(end 334.622648 -236.86897)
		(width 0.09525)
		(layer "In4.Cu")
		(net "M_D_CPU0_SA_DQS_DN<2>")
	)
	(arc
		(start 327.506584 -236.883702)
		(mid 327.776438 -236.944581)
		(end 328.042524 -236.86897)
		(width 0.09525)
		(layer "In4.Cu")
		(net "M_D_CPU0_SA_DQS_DN<2>")
	)
	(arc
		(start 335.939638 -236.86897)
		(mid 336.22107 -236.944725)
		(end 336.502502 -236.86897)
		(width 0.09525)
		(layer "In4.Cu")
		(net "M_D_CPU0_SA_DQS_DN<2>")
	)
	(arc
		(start 327.10501 -236.86897)
		(mid 327.284782 -236.818394)
		(end 327.466706 -236.860588)
		(width 0.09525)
		(layer "In4.Cu")
		(net "M_D_CPU0_SA_DQS_DN<2>")
	)
	(arc
		(start 330.862432 -236.86897)
		(mid 331.046207 -236.818198)
		(end 331.23124 -236.864144)
		(width 0.09525)
		(layer "In4.Cu")
		(net "M_D_CPU0_SA_DQS_DN<2>")
	)
	(arc
		(start 330.299568 -236.86897)
		(mid 330.581 -236.944725)
		(end 330.862432 -236.86897)
		(width 0.09525)
		(layer "In4.Cu")
		(net "M_D_CPU0_SA_DQS_DN<2>")
	)
	(arc
		(start 338.38261 -236.86897)
		(mid 338.539237 -236.819784)
		(end 338.701888 -236.842046)
		(width 0.09525)
		(layer "In4.Cu")
		(net "M_D_CPU0_SA_DQS_DN<2>")
	)
	(arc
		(start 334.999584 -236.86897)
		(mid 335.281016 -236.944725)
		(end 335.562448 -236.86897)
		(width 0.09525)
		(layer "In4.Cu")
		(net "M_D_CPU0_SA_DQS_DN<2>")
	)
	(arc
		(start 336.502502 -236.86897)
		(mid 336.686277 -236.818198)
		(end 336.87131 -236.864144)
		(width 0.09525)
		(layer "In4.Cu")
		(net "M_D_CPU0_SA_DQS_DN<2>")
	)
	(arc
		(start 331.802486 -236.86897)
		(mid 331.986261 -236.818198)
		(end 332.171294 -236.864144)
		(width 0.09525)
		(layer "In4.Cu")
		(net "M_D_CPU0_SA_DQS_DN<2>")
	)
	(segment
		(start 339.03793 -232.599992)
		(end 338.571078 -232.334054)
		(width 0.12954)
		(layer "F.Cu")
		(net "M_D_CPU0_SA_DQS_DN<1>")
	)
	(segment
		(start 326.022208 -230.333042)
		(end 326.475344 -230.333042)
		(width 0.09525)
		(layer "In4.Cu")
		(net "M_D_CPU0_SA_DQS_DN<1>")
	)
	(segment
		(start 315.322458 -218.812872)
		(end 315.69533 -219.185744)
		(width 0.16002)
		(layer "In4.Cu")
		(net "M_D_CPU0_SA_DQS_DN<1>")
	)
	(segment
		(start 324.177152 -229.170992)
		(end 324.260972 -229.170992)
		(width 0.09525)
		(layer "In4.Cu")
		(net "M_D_CPU0_SA_DQS_DN<1>")
	)
	(segment
		(start 311.201562 -214.164672)
		(end 311.201562 -214.691976)
		(width 0.16002)
		(layer "In4.Cu")
		(net "M_D_CPU0_SA_DQS_DN<1>")
	)
	(segment
		(start 317.596266 -220.559376)
		(end 317.702946 -220.452696)
		(width 0.16002)
		(layer "In4.Cu")
		(net "M_D_CPU0_SA_DQS_DN<1>")
	)
	(segment
		(start 313.948826 -216.911936)
		(end 313.948826 -217.43924)
		(width 0.16002)
		(layer "In4.Cu")
		(net "M_D_CPU0_SA_DQS_DN<1>")
	)
	(segment
		(start 321.314318 -226.308158)
		(end 324.160388 -229.154228)
		(width 0.16002)
		(layer "In4.Cu")
		(net "M_D_CPU0_SA_DQS_DN<1>")
	)
	(segment
		(start 319.353438 -221.826328)
		(end 319.550034 -222.022924)
		(width 0.16002)
		(layer "In4.Cu")
		(net "M_D_CPU0_SA_DQS_DN<1>")
	)
	(segment
		(start 294.523668 -210.628992)
		(end 295.003728 -210.628992)
		(width 0.16002)
		(layer "In4.Cu")
		(net "M_D_CPU0_SA_DQS_DN<1>")
	)
	(segment
		(start 316.222634 -219.185744)
		(end 316.329314 -219.079064)
		(width 0.16002)
		(layer "In4.Cu")
		(net "M_D_CPU0_SA_DQS_DN<1>")
	)
	(segment
		(start 302.300894 -210.64601)
		(end 302.925734 -211.27085)
		(width 0.16002)
		(layer "In4.Cu")
		(net "M_D_CPU0_SA_DQS_DN<1>")
	)
	(segment
		(start 318.969898 -221.933008)
		(end 319.076578 -221.826328)
		(width 0.16002)
		(layer "In4.Cu")
		(net "M_D_CPU0_SA_DQS_DN<1>")
	)
	(segment
		(start 325.322438 -229.633272)
		(end 326.022208 -230.333042)
		(width 0.09525)
		(layer "In4.Cu")
		(net "M_D_CPU0_SA_DQS_DN<1>")
	)
	(segment
		(start 298.721526 -210.02625)
		(end 299.085508 -209.662268)
		(width 0.16002)
		(layer "In4.Cu")
		(net "M_D_CPU0_SA_DQS_DN<1>")
	)
	(segment
		(start 319.443354 -222.933768)
		(end 321.314318 -224.804732)
		(width 0.16002)
		(layer "In4.Cu")
		(net "M_D_CPU0_SA_DQS_DN<1>")
	)
	(segment
		(start 312.681874 -215.154764)
		(end 312.681874 -215.431624)
		(width 0.16002)
		(layer "In4.Cu")
		(net "M_D_CPU0_SA_DQS_DN<1>")
	)
	(segment
		(start 312.575194 -215.538304)
		(end 312.575194 -216.065608)
		(width 0.16002)
		(layer "In4.Cu")
		(net "M_D_CPU0_SA_DQS_DN<1>")
	)
	(segment
		(start 316.606174 -219.079064)
		(end 316.80277 -219.27566)
		(width 0.16002)
		(layer "In4.Cu")
		(net "M_D_CPU0_SA_DQS_DN<1>")
	)
	(segment
		(start 314.955682 -217.705432)
		(end 315.232542 -217.705432)
		(width 0.16002)
		(layer "In4.Cu")
		(net "M_D_CPU0_SA_DQS_DN<1>")
	)
	(segment
		(start 317.702946 -220.452696)
		(end 317.979806 -220.452696)
		(width 0.16002)
		(layer "In4.Cu")
		(net "M_D_CPU0_SA_DQS_DN<1>")
	)
	(segment
		(start 316.80277 -219.27566)
		(end 316.80277 -219.55252)
		(width 0.16002)
		(layer "In4.Cu")
		(net "M_D_CPU0_SA_DQS_DN<1>")
	)
	(segment
		(start 316.69609 -219.6592)
		(end 316.69609 -220.186504)
		(width 0.16002)
		(layer "In4.Cu")
		(net "M_D_CPU0_SA_DQS_DN<1>")
	)
	(segment
		(start 310.834786 -213.584536)
		(end 311.111646 -213.584536)
		(width 0.16002)
		(layer "In4.Cu")
		(net "M_D_CPU0_SA_DQS_DN<1>")
	)
	(segment
		(start 286.304228 -210.66125)
		(end 287.16478 -210.66125)
		(width 0.16002)
		(layer "In4.Cu")
		(net "M_D_CPU0_SA_DQS_DN<1>")
	)
	(segment
		(start 338.701888 -231.98201)
		(end 338.725002 -232.068624)
		(width 0.09525)
		(layer "In4.Cu")
		(net "M_D_CPU0_SA_DQS_DN<1>")
	)
	(segment
		(start 288.907982 -210.512152)
		(end 289.25266 -210.85683)
		(width 0.16002)
		(layer "In4.Cu")
		(net "M_D_CPU0_SA_DQS_DN<1>")
	)
	(segment
		(start 335.931256 -232.004108)
		(end 335.939638 -232.008934)
		(width 0.09525)
		(layer "In4.Cu")
		(net "M_D_CPU0_SA_DQS_DN<1>")
	)
	(segment
		(start 316.329314 -219.079064)
		(end 316.606174 -219.079064)
		(width 0.16002)
		(layer "In4.Cu")
		(net "M_D_CPU0_SA_DQS_DN<1>")
	)
	(segment
		(start 313.47537 -216.43848)
		(end 313.58205 -216.3318)
		(width 0.16002)
		(layer "In4.Cu")
		(net "M_D_CPU0_SA_DQS_DN<1>")
	)
	(segment
		(start 318.069722 -221.560136)
		(end 318.442594 -221.933008)
		(width 0.16002)
		(layer "In4.Cu")
		(net "M_D_CPU0_SA_DQS_DN<1>")
	)
	(segment
		(start 316.69609 -220.186504)
		(end 317.068962 -220.559376)
		(width 0.16002)
		(layer "In4.Cu")
		(net "M_D_CPU0_SA_DQS_DN<1>")
	)
	(segment
		(start 319.443354 -222.406464)
		(end 319.443354 -222.933768)
		(width 0.16002)
		(layer "In4.Cu")
		(net "M_D_CPU0_SA_DQS_DN<1>")
	)
	(segment
		(start 313.58205 -216.3318)
		(end 313.85891 -216.3318)
		(width 0.16002)
		(layer "In4.Cu")
		(net "M_D_CPU0_SA_DQS_DN<1>")
	)
	(segment
		(start 314.321698 -217.812112)
		(end 314.849002 -217.812112)
		(width 0.16002)
		(layer "In4.Cu")
		(net "M_D_CPU0_SA_DQS_DN<1>")
	)
	(segment
		(start 314.849002 -217.812112)
		(end 314.955682 -217.705432)
		(width 0.16002)
		(layer "In4.Cu")
		(net "M_D_CPU0_SA_DQS_DN<1>")
	)
	(segment
		(start 315.429138 -217.902028)
		(end 315.429138 -218.178888)
		(width 0.16002)
		(layer "In4.Cu")
		(net "M_D_CPU0_SA_DQS_DN<1>")
	)
	(segment
		(start 311.308242 -213.781132)
		(end 311.308242 -214.057992)
		(width 0.16002)
		(layer "In4.Cu")
		(net "M_D_CPU0_SA_DQS_DN<1>")
	)
	(segment
		(start 310.200802 -213.691216)
		(end 310.728106 -213.691216)
		(width 0.16002)
		(layer "In4.Cu")
		(net "M_D_CPU0_SA_DQS_DN<1>")
	)
	(segment
		(start 290.732972 -210.02625)
		(end 291.177726 -210.02625)
		(width 0.16002)
		(layer "In4.Cu")
		(net "M_D_CPU0_SA_DQS_DN<1>")
	)
	(segment
		(start 287.16478 -210.66125)
		(end 287.313878 -210.512152)
		(width 0.16002)
		(layer "In4.Cu")
		(net "M_D_CPU0_SA_DQS_DN<1>")
	)
	(segment
		(start 331.23124 -232.004108)
		(end 331.239622 -232.008934)
		(width 0.09525)
		(layer "In4.Cu")
		(net "M_D_CPU0_SA_DQS_DN<1>")
	)
	(segment
		(start 311.308242 -214.057992)
		(end 311.201562 -214.164672)
		(width 0.16002)
		(layer "In4.Cu")
		(net "M_D_CPU0_SA_DQS_DN<1>")
	)
	(segment
		(start 313.85891 -216.3318)
		(end 314.055506 -216.528396)
		(width 0.16002)
		(layer "In4.Cu")
		(net "M_D_CPU0_SA_DQS_DN<1>")
	)
	(segment
		(start 326.708008 -231.263952)
		(end 327.364598 -231.920542)
		(width 0.09525)
		(layer "In4.Cu")
		(net "M_D_CPU0_SA_DQS_DN<1>")
	)
	(segment
		(start 315.322458 -218.285568)
		(end 315.322458 -218.812872)
		(width 0.16002)
		(layer "In4.Cu")
		(net "M_D_CPU0_SA_DQS_DN<1>")
	)
	(segment
		(start 312.485278 -214.958168)
		(end 312.681874 -215.154764)
		(width 0.16002)
		(layer "In4.Cu")
		(net "M_D_CPU0_SA_DQS_DN<1>")
	)
	(segment
		(start 319.550034 -222.299784)
		(end 319.443354 -222.406464)
		(width 0.16002)
		(layer "In4.Cu")
		(net "M_D_CPU0_SA_DQS_DN<1>")
	)
	(segment
		(start 302.925734 -211.27085)
		(end 307.780436 -211.27085)
		(width 0.16002)
		(layer "In4.Cu")
		(net "M_D_CPU0_SA_DQS_DN<1>")
	)
	(segment
		(start 315.232542 -217.705432)
		(end 315.429138 -217.902028)
		(width 0.16002)
		(layer "In4.Cu")
		(net "M_D_CPU0_SA_DQS_DN<1>")
	)
	(segment
		(start 319.550034 -222.022924)
		(end 319.550034 -222.299784)
		(width 0.16002)
		(layer "In4.Cu")
		(net "M_D_CPU0_SA_DQS_DN<1>")
	)
	(segment
		(start 317.068962 -220.559376)
		(end 317.596266 -220.559376)
		(width 0.16002)
		(layer "In4.Cu")
		(net "M_D_CPU0_SA_DQS_DN<1>")
	)
	(segment
		(start 291.541708 -209.662268)
		(end 293.02456 -209.662268)
		(width 0.16002)
		(layer "In4.Cu")
		(net "M_D_CPU0_SA_DQS_DN<1>")
	)
	(segment
		(start 314.055506 -216.528396)
		(end 314.055506 -216.805256)
		(width 0.16002)
		(layer "In4.Cu")
		(net "M_D_CPU0_SA_DQS_DN<1>")
	)
	(segment
		(start 297.47464 -210.85683)
		(end 298.30522 -210.02625)
		(width 0.16002)
		(layer "In4.Cu")
		(net "M_D_CPU0_SA_DQS_DN<1>")
	)
	(segment
		(start 313.948826 -217.43924)
		(end 314.321698 -217.812112)
		(width 0.16002)
		(layer "In4.Cu")
		(net "M_D_CPU0_SA_DQS_DN<1>")
	)
	(segment
		(start 324.160388 -229.154228)
		(end 324.177152 -229.170992)
		(width 0.09525)
		(layer "In4.Cu")
		(net "M_D_CPU0_SA_DQS_DN<1>")
	)
	(segment
		(start 289.25266 -210.85683)
		(end 289.902392 -210.85683)
		(width 0.16002)
		(layer "In4.Cu")
		(net "M_D_CPU0_SA_DQS_DN<1>")
	)
	(segment
		(start 293.874444 -210.512152)
		(end 294.406828 -210.512152)
		(width 0.16002)
		(layer "In4.Cu")
		(net "M_D_CPU0_SA_DQS_DN<1>")
	)
	(segment
		(start 336.87131 -232.004108)
		(end 336.879692 -232.008934)
		(width 0.09525)
		(layer "In4.Cu")
		(net "M_D_CPU0_SA_DQS_DN<1>")
	)
	(segment
		(start 291.177726 -210.02625)
		(end 291.541708 -209.662268)
		(width 0.16002)
		(layer "In4.Cu")
		(net "M_D_CPU0_SA_DQS_DN<1>")
	)
	(segment
		(start 321.314318 -224.804732)
		(end 321.314318 -226.308158)
		(width 0.16002)
		(layer "In4.Cu")
		(net "M_D_CPU0_SA_DQS_DN<1>")
	)
	(segment
		(start 318.069722 -221.032832)
		(end 318.069722 -221.560136)
		(width 0.16002)
		(layer "In4.Cu")
		(net "M_D_CPU0_SA_DQS_DN<1>")
	)
	(segment
		(start 312.101738 -215.064848)
		(end 312.208418 -214.958168)
		(width 0.16002)
		(layer "In4.Cu")
		(net "M_D_CPU0_SA_DQS_DN<1>")
	)
	(segment
		(start 315.429138 -218.178888)
		(end 315.322458 -218.285568)
		(width 0.16002)
		(layer "In4.Cu")
		(net "M_D_CPU0_SA_DQS_DN<1>")
	)
	(segment
		(start 332.171294 -232.004108)
		(end 332.179676 -232.008934)
		(width 0.09525)
		(layer "In4.Cu")
		(net "M_D_CPU0_SA_DQS_DN<1>")
	)
	(segment
		(start 312.575194 -216.065608)
		(end 312.948066 -216.43848)
		(width 0.16002)
		(layer "In4.Cu")
		(net "M_D_CPU0_SA_DQS_DN<1>")
	)
	(segment
		(start 324.723252 -229.633272)
		(end 325.322438 -229.633272)
		(width 0.09525)
		(layer "In4.Cu")
		(net "M_D_CPU0_SA_DQS_DN<1>")
	)
	(segment
		(start 311.201562 -214.691976)
		(end 311.574434 -215.064848)
		(width 0.16002)
		(layer "In4.Cu")
		(net "M_D_CPU0_SA_DQS_DN<1>")
	)
	(segment
		(start 296.79646 -210.85683)
		(end 297.47464 -210.85683)
		(width 0.16002)
		(layer "In4.Cu")
		(net "M_D_CPU0_SA_DQS_DN<1>")
	)
	(segment
		(start 314.055506 -216.805256)
		(end 313.948826 -216.911936)
		(width 0.16002)
		(layer "In4.Cu")
		(net "M_D_CPU0_SA_DQS_DN<1>")
	)
	(segment
		(start 317.979806 -220.452696)
		(end 318.176402 -220.649292)
		(width 0.16002)
		(layer "In4.Cu")
		(net "M_D_CPU0_SA_DQS_DN<1>")
	)
	(segment
		(start 301.558706 -210.64601)
		(end 302.300894 -210.64601)
		(width 0.16002)
		(layer "In4.Cu")
		(net "M_D_CPU0_SA_DQS_DN<1>")
	)
	(segment
		(start 332.74254 -232.008934)
		(end 332.750922 -232.004108)
		(width 0.09525)
		(layer "In4.Cu")
		(net "M_D_CPU0_SA_DQS_DN<1>")
	)
	(segment
		(start 285.707328 -210.77809)
		(end 286.187388 -210.77809)
		(width 0.16002)
		(layer "In4.Cu")
		(net "M_D_CPU0_SA_DQS_DN<1>")
	)
	(segment
		(start 328.982578 -232.008934)
		(end 328.99096 -232.004108)
		(width 0.09525)
		(layer "In4.Cu")
		(net "M_D_CPU0_SA_DQS_DN<1>")
	)
	(segment
		(start 295.120568 -210.512152)
		(end 296.451782 -210.512152)
		(width 0.16002)
		(layer "In4.Cu")
		(net "M_D_CPU0_SA_DQS_DN<1>")
	)
	(segment
		(start 285.590488 -210.66125)
		(end 285.707328 -210.77809)
		(width 0.16002)
		(layer "In4.Cu")
		(net "M_D_CPU0_SA_DQS_DN<1>")
	)
	(segment
		(start 319.076578 -221.826328)
		(end 319.353438 -221.826328)
		(width 0.16002)
		(layer "In4.Cu")
		(net "M_D_CPU0_SA_DQS_DN<1>")
	)
	(segment
		(start 299.085508 -209.662268)
		(end 300.574964 -209.662268)
		(width 0.16002)
		(layer "In4.Cu")
		(net "M_D_CPU0_SA_DQS_DN<1>")
	)
	(segment
		(start 315.69533 -219.185744)
		(end 316.222634 -219.185744)
		(width 0.16002)
		(layer "In4.Cu")
		(net "M_D_CPU0_SA_DQS_DN<1>")
	)
	(segment
		(start 285.009844 -210.66125)
		(end 285.590488 -210.66125)
		(width 0.16002)
		(layer "In4.Cu")
		(net "M_D_CPU0_SA_DQS_DN<1>")
	)
	(segment
		(start 337.442556 -232.008934)
		(end 337.450938 -232.004108)
		(width 0.09525)
		(layer "In4.Cu")
		(net "M_D_CPU0_SA_DQS_DN<1>")
	)
	(segment
		(start 296.451782 -210.512152)
		(end 296.79646 -210.85683)
		(width 0.16002)
		(layer "In4.Cu")
		(net "M_D_CPU0_SA_DQS_DN<1>")
	)
	(segment
		(start 324.260972 -229.170992)
		(end 324.723252 -229.633272)
		(width 0.09525)
		(layer "In4.Cu")
		(net "M_D_CPU0_SA_DQS_DN<1>")
	)
	(segment
		(start 311.574434 -215.064848)
		(end 312.101738 -215.064848)
		(width 0.16002)
		(layer "In4.Cu")
		(net "M_D_CPU0_SA_DQS_DN<1>")
	)
	(segment
		(start 312.681874 -215.431624)
		(end 312.575194 -215.538304)
		(width 0.16002)
		(layer "In4.Cu")
		(net "M_D_CPU0_SA_DQS_DN<1>")
	)
	(segment
		(start 298.30522 -210.02625)
		(end 298.721526 -210.02625)
		(width 0.16002)
		(layer "In4.Cu")
		(net "M_D_CPU0_SA_DQS_DN<1>")
	)
	(segment
		(start 312.948066 -216.43848)
		(end 313.47537 -216.43848)
		(width 0.16002)
		(layer "In4.Cu")
		(net "M_D_CPU0_SA_DQS_DN<1>")
	)
	(segment
		(start 310.728106 -213.691216)
		(end 310.834786 -213.584536)
		(width 0.16002)
		(layer "In4.Cu")
		(net "M_D_CPU0_SA_DQS_DN<1>")
	)
	(segment
		(start 311.111646 -213.584536)
		(end 311.308242 -213.781132)
		(width 0.16002)
		(layer "In4.Cu")
		(net "M_D_CPU0_SA_DQS_DN<1>")
	)
	(segment
		(start 284.736032 -210.935062)
		(end 285.009844 -210.66125)
		(width 0.16002)
		(layer "In4.Cu")
		(net "M_D_CPU0_SA_DQS_DN<1>")
	)
	(segment
		(start 328.411332 -232.004108)
		(end 328.419714 -232.008934)
		(width 0.09525)
		(layer "In4.Cu")
		(net "M_D_CPU0_SA_DQS_DN<1>")
	)
	(segment
		(start 326.475344 -230.333042)
		(end 326.708008 -230.565706)
		(width 0.09525)
		(layer "In4.Cu")
		(net "M_D_CPU0_SA_DQS_DN<1>")
	)
	(segment
		(start 286.187388 -210.77809)
		(end 286.304228 -210.66125)
		(width 0.16002)
		(layer "In4.Cu")
		(net "M_D_CPU0_SA_DQS_DN<1>")
	)
	(segment
		(start 287.313878 -210.512152)
		(end 288.907982 -210.512152)
		(width 0.16002)
		(layer "In4.Cu")
		(net "M_D_CPU0_SA_DQS_DN<1>")
	)
	(segment
		(start 289.902392 -210.85683)
		(end 290.732972 -210.02625)
		(width 0.16002)
		(layer "In4.Cu")
		(net "M_D_CPU0_SA_DQS_DN<1>")
	)
	(segment
		(start 316.80277 -219.55252)
		(end 316.69609 -219.6592)
		(width 0.16002)
		(layer "In4.Cu")
		(net "M_D_CPU0_SA_DQS_DN<1>")
	)
	(segment
		(start 312.208418 -214.958168)
		(end 312.485278 -214.958168)
		(width 0.16002)
		(layer "In4.Cu")
		(net "M_D_CPU0_SA_DQS_DN<1>")
	)
	(segment
		(start 300.574964 -209.662268)
		(end 301.558706 -210.64601)
		(width 0.16002)
		(layer "In4.Cu")
		(net "M_D_CPU0_SA_DQS_DN<1>")
	)
	(segment
		(start 326.708008 -230.565706)
		(end 326.708008 -231.263952)
		(width 0.09525)
		(layer "In4.Cu")
		(net "M_D_CPU0_SA_DQS_DN<1>")
	)
	(segment
		(start 307.780436 -211.27085)
		(end 310.200802 -213.691216)
		(width 0.16002)
		(layer "In4.Cu")
		(net "M_D_CPU0_SA_DQS_DN<1>")
	)
	(segment
		(start 318.176402 -220.649292)
		(end 318.176402 -220.926152)
		(width 0.16002)
		(layer "In4.Cu")
		(net "M_D_CPU0_SA_DQS_DN<1>")
	)
	(segment
		(start 318.176402 -220.926152)
		(end 318.069722 -221.032832)
		(width 0.16002)
		(layer "In4.Cu")
		(net "M_D_CPU0_SA_DQS_DN<1>")
	)
	(segment
		(start 295.003728 -210.628992)
		(end 295.120568 -210.512152)
		(width 0.16002)
		(layer "In4.Cu")
		(net "M_D_CPU0_SA_DQS_DN<1>")
	)
	(segment
		(start 318.442594 -221.933008)
		(end 318.969898 -221.933008)
		(width 0.16002)
		(layer "In4.Cu")
		(net "M_D_CPU0_SA_DQS_DN<1>")
	)
	(segment
		(start 294.406828 -210.512152)
		(end 294.523668 -210.628992)
		(width 0.16002)
		(layer "In4.Cu")
		(net "M_D_CPU0_SA_DQS_DN<1>")
	)
	(segment
		(start 338.725002 -232.068624)
		(end 338.571078 -232.334054)
		(width 0.09525)
		(layer "In4.Cu")
		(net "M_D_CPU0_SA_DQS_DN<1>")
	)
	(segment
		(start 333.682594 -232.008934)
		(end 333.690976 -232.004108)
		(width 0.09525)
		(layer "In4.Cu")
		(net "M_D_CPU0_SA_DQS_DN<1>")
	)
	(segment
		(start 293.02456 -209.662268)
		(end 293.874444 -210.512152)
		(width 0.16002)
		(layer "In4.Cu")
		(net "M_D_CPU0_SA_DQS_DN<1>")
	)
	(arc
		(start 331.802486 -232.008934)
		(mid 331.986261 -231.958162)
		(end 332.171294 -232.004108)
		(width 0.09525)
		(layer "In4.Cu")
		(net "M_D_CPU0_SA_DQS_DN<1>")
	)
	(arc
		(start 329.922632 -232.008934)
		(mid 330.1111 -231.958257)
		(end 330.299568 -232.008934)
		(width 0.09525)
		(layer "In4.Cu")
		(net "M_D_CPU0_SA_DQS_DN<1>")
	)
	(arc
		(start 327.47966 -232.008934)
		(mid 327.761092 -232.084689)
		(end 328.042524 -232.008934)
		(width 0.09525)
		(layer "In4.Cu")
		(net "M_D_CPU0_SA_DQS_DN<1>")
	)
	(arc
		(start 338.38261 -232.008934)
		(mid 338.539237 -231.959748)
		(end 338.701888 -231.98201)
		(width 0.09525)
		(layer "In4.Cu")
		(net "M_D_CPU0_SA_DQS_DN<1>")
	)
	(arc
		(start 332.750922 -232.004108)
		(mid 332.935954 -231.958194)
		(end 333.11973 -232.008934)
		(width 0.09525)
		(layer "In4.Cu")
		(net "M_D_CPU0_SA_DQS_DN<1>")
	)
	(arc
		(start 333.690976 -232.004108)
		(mid 333.876008 -231.958194)
		(end 334.059784 -232.008934)
		(width 0.09525)
		(layer "In4.Cu")
		(net "M_D_CPU0_SA_DQS_DN<1>")
	)
	(arc
		(start 327.364598 -231.920542)
		(mid 327.41926 -231.968473)
		(end 327.47966 -232.008934)
		(width 0.09525)
		(layer "In4.Cu")
		(net "M_D_CPU0_SA_DQS_DN<1>")
	)
	(arc
		(start 337.450938 -232.004108)
		(mid 337.63597 -231.958194)
		(end 337.819746 -232.008934)
		(width 0.09525)
		(layer "In4.Cu")
		(net "M_D_CPU0_SA_DQS_DN<1>")
	)
	(arc
		(start 328.419714 -232.008934)
		(mid 328.701146 -232.084689)
		(end 328.982578 -232.008934)
		(width 0.09525)
		(layer "In4.Cu")
		(net "M_D_CPU0_SA_DQS_DN<1>")
	)
	(arc
		(start 335.939638 -232.008934)
		(mid 336.22107 -232.084689)
		(end 336.502502 -232.008934)
		(width 0.09525)
		(layer "In4.Cu")
		(net "M_D_CPU0_SA_DQS_DN<1>")
	)
	(arc
		(start 330.299568 -232.008934)
		(mid 330.581 -232.084689)
		(end 330.862432 -232.008934)
		(width 0.09525)
		(layer "In4.Cu")
		(net "M_D_CPU0_SA_DQS_DN<1>")
	)
	(arc
		(start 328.99096 -232.004108)
		(mid 329.175992 -231.958194)
		(end 329.359768 -232.008934)
		(width 0.09525)
		(layer "In4.Cu")
		(net "M_D_CPU0_SA_DQS_DN<1>")
	)
	(arc
		(start 329.359768 -232.008934)
		(mid 329.6412 -232.084689)
		(end 329.922632 -232.008934)
		(width 0.09525)
		(layer "In4.Cu")
		(net "M_D_CPU0_SA_DQS_DN<1>")
	)
	(arc
		(start 334.999584 -232.008934)
		(mid 335.281016 -232.084689)
		(end 335.562448 -232.008934)
		(width 0.09525)
		(layer "In4.Cu")
		(net "M_D_CPU0_SA_DQS_DN<1>")
	)
	(arc
		(start 330.862432 -232.008934)
		(mid 331.046207 -231.958162)
		(end 331.23124 -232.004108)
		(width 0.09525)
		(layer "In4.Cu")
		(net "M_D_CPU0_SA_DQS_DN<1>")
	)
	(arc
		(start 335.562448 -232.008934)
		(mid 335.746223 -231.958162)
		(end 335.931256 -232.004108)
		(width 0.09525)
		(layer "In4.Cu")
		(net "M_D_CPU0_SA_DQS_DN<1>")
	)
	(arc
		(start 336.502502 -232.008934)
		(mid 336.686277 -231.958162)
		(end 336.87131 -232.004108)
		(width 0.09525)
		(layer "In4.Cu")
		(net "M_D_CPU0_SA_DQS_DN<1>")
	)
	(arc
		(start 334.059784 -232.008934)
		(mid 334.341216 -232.084689)
		(end 334.622648 -232.008934)
		(width 0.09525)
		(layer "In4.Cu")
		(net "M_D_CPU0_SA_DQS_DN<1>")
	)
	(arc
		(start 337.819746 -232.008934)
		(mid 338.101178 -232.084689)
		(end 338.38261 -232.008934)
		(width 0.09525)
		(layer "In4.Cu")
		(net "M_D_CPU0_SA_DQS_DN<1>")
	)
	(arc
		(start 334.622648 -232.008934)
		(mid 334.811116 -231.958257)
		(end 334.999584 -232.008934)
		(width 0.09525)
		(layer "In4.Cu")
		(net "M_D_CPU0_SA_DQS_DN<1>")
	)
	(arc
		(start 328.042524 -232.008934)
		(mid 328.226299 -231.958162)
		(end 328.411332 -232.004108)
		(width 0.09525)
		(layer "In4.Cu")
		(net "M_D_CPU0_SA_DQS_DN<1>")
	)
	(arc
		(start 333.11973 -232.008934)
		(mid 333.401162 -232.084689)
		(end 333.682594 -232.008934)
		(width 0.09525)
		(layer "In4.Cu")
		(net "M_D_CPU0_SA_DQS_DN<1>")
	)
	(arc
		(start 336.879692 -232.008934)
		(mid 337.161124 -232.084689)
		(end 337.442556 -232.008934)
		(width 0.09525)
		(layer "In4.Cu")
		(net "M_D_CPU0_SA_DQS_DN<1>")
	)
	(arc
		(start 332.179676 -232.008934)
		(mid 332.461108 -232.084689)
		(end 332.74254 -232.008934)
		(width 0.09525)
		(layer "In4.Cu")
		(net "M_D_CPU0_SA_DQS_DN<1>")
	)
	(arc
		(start 331.239622 -232.008934)
		(mid 331.521054 -232.084689)
		(end 331.802486 -232.008934)
		(width 0.09525)
		(layer "In4.Cu")
		(net "M_D_CPU0_SA_DQS_DN<1>")
	)
	(segment
		(start 339.03793 -227.74021)
		(end 338.571078 -227.474272)
		(width 0.12954)
		(layer "F.Cu")
		(net "M_D_CPU0_SA_DQS_DN<0>")
	)
	(segment
		(start 327.139554 -220.406468)
		(end 327.139554 -221.31655)
		(width 0.16002)
		(layer "In4.Cu")
		(net "M_D_CPU0_SA_DQS_DN<0>")
	)
	(segment
		(start 322.560696 -216.57691)
		(end 323.309996 -216.57691)
		(width 0.16002)
		(layer "In4.Cu")
		(net "M_D_CPU0_SA_DQS_DN<0>")
	)
	(segment
		(start 329.359768 -225.52914)
		(end 329.391264 -225.547428)
		(width 0.09525)
		(layer "In4.Cu")
		(net "M_D_CPU0_SA_DQS_DN<0>")
	)
	(segment
		(start 295.079928 -201.162158)
		(end 296.421302 -201.162158)
		(width 0.16002)
		(layer "In4.Cu")
		(net "M_D_CPU0_SA_DQS_DN<0>")
	)
	(segment
		(start 297.47464 -201.495152)
		(end 298.3103 -200.659492)
		(width 0.16002)
		(layer "In4.Cu")
		(net "M_D_CPU0_SA_DQS_DN<0>")
	)
	(segment
		(start 311.170574 -205.186788)
		(end 311.57164 -205.587854)
		(width 0.16002)
		(layer "In4.Cu")
		(net "M_D_CPU0_SA_DQS_DN<0>")
	)
	(segment
		(start 325.30796 -219.324174)
		(end 326.05726 -219.324174)
		(width 0.16002)
		(layer "In4.Cu")
		(net "M_D_CPU0_SA_DQS_DN<0>")
	)
	(segment
		(start 328.384662 -223.888554)
		(end 328.386694 -223.889824)
		(width 0.09525)
		(layer "In4.Cu")
		(net "M_D_CPU0_SA_DQS_DN<0>")
	)
	(segment
		(start 323.309996 -216.57691)
		(end 323.533262 -216.800176)
		(width 0.16002)
		(layer "In4.Cu")
		(net "M_D_CPU0_SA_DQS_DN<0>")
	)
	(segment
		(start 286.540956 -201.428096)
		(end 286.657796 -201.311256)
		(width 0.16002)
		(layer "In4.Cu")
		(net "M_D_CPU0_SA_DQS_DN<0>")
	)
	(segment
		(start 312.544206 -206.56042)
		(end 312.945272 -206.961486)
		(width 0.16002)
		(layer "In4.Cu")
		(net "M_D_CPU0_SA_DQS_DN<0>")
	)
	(segment
		(start 316.441836 -209.70875)
		(end 316.665102 -209.932016)
		(width 0.16002)
		(layer "In4.Cu")
		(net "M_D_CPU0_SA_DQS_DN<0>")
	)
	(segment
		(start 335.931256 -227.144326)
		(end 335.939638 -227.149152)
		(width 0.09525)
		(layer "In4.Cu")
		(net "M_D_CPU0_SA_DQS_DN<0>")
	)
	(segment
		(start 287.137856 -201.311256)
		(end 287.286954 -201.162158)
		(width 0.16002)
		(layer "In4.Cu")
		(net "M_D_CPU0_SA_DQS_DN<0>")
	)
	(segment
		(start 328.854562 -224.69856)
		(end 328.856594 -224.69983)
		(width 0.09525)
		(layer "In4.Cu")
		(net "M_D_CPU0_SA_DQS_DN<0>")
	)
	(segment
		(start 320.785998 -214.802212)
		(end 321.187064 -215.203278)
		(width 0.16002)
		(layer "In4.Cu")
		(net "M_D_CPU0_SA_DQS_DN<0>")
	)
	(segment
		(start 291.19576 -200.664572)
		(end 291.54882 -200.311512)
		(width 0.16002)
		(layer "In4.Cu")
		(net "M_D_CPU0_SA_DQS_DN<0>")
	)
	(segment
		(start 299.099478 -200.312274)
		(end 300.596808 -200.312274)
		(width 0.16002)
		(layer "In4.Cu")
		(net "M_D_CPU0_SA_DQS_DN<0>")
	)
	(segment
		(start 289.89782 -201.505312)
		(end 290.73856 -200.664572)
		(width 0.16002)
		(layer "In4.Cu")
		(net "M_D_CPU0_SA_DQS_DN<0>")
	)
	(segment
		(start 312.32094 -205.587854)
		(end 312.544206 -205.81112)
		(width 0.16002)
		(layer "In4.Cu")
		(net "M_D_CPU0_SA_DQS_DN<0>")
	)
	(segment
		(start 316.665102 -210.681316)
		(end 317.066168 -211.082382)
		(width 0.16002)
		(layer "In4.Cu")
		(net "M_D_CPU0_SA_DQS_DN<0>")
	)
	(segment
		(start 304.765964 -201.932032)
		(end 308.665118 -201.932032)
		(width 0.16002)
		(layer "In4.Cu")
		(net "M_D_CPU0_SA_DQS_DN<0>")
	)
	(segment
		(start 327.198736 -221.399354)
		(end 327.198736 -221.80423)
		(width 0.09525)
		(layer "In4.Cu")
		(net "M_D_CPU0_SA_DQS_DN<0>")
	)
	(segment
		(start 324.683628 -217.950542)
		(end 324.906894 -218.173808)
		(width 0.16002)
		(layer "In4.Cu")
		(net "M_D_CPU0_SA_DQS_DN<0>")
	)
	(segment
		(start 319.1891 -212.456014)
		(end 319.412366 -212.67928)
		(width 0.16002)
		(layer "In4.Cu")
		(net "M_D_CPU0_SA_DQS_DN<0>")
	)
	(segment
		(start 311.57164 -205.587854)
		(end 312.32094 -205.587854)
		(width 0.16002)
		(layer "In4.Cu")
		(net "M_D_CPU0_SA_DQS_DN<0>")
	)
	(segment
		(start 328.889614 -224.719134)
		(end 328.922126 -224.73793)
		(width 0.09525)
		(layer "In4.Cu")
		(net "M_D_CPU0_SA_DQS_DN<0>")
	)
	(segment
		(start 327.440544 -222.266256)
		(end 327.479914 -222.289116)
		(width 0.09525)
		(layer "In4.Cu")
		(net "M_D_CPU0_SA_DQS_DN<0>")
	)
	(segment
		(start 321.187064 -215.203278)
		(end 321.936364 -215.203278)
		(width 0.16002)
		(layer "In4.Cu")
		(net "M_D_CPU0_SA_DQS_DN<0>")
	)
	(segment
		(start 301.496984 -201.21245)
		(end 302.397668 -201.21245)
		(width 0.16002)
		(layer "In4.Cu")
		(net "M_D_CPU0_SA_DQS_DN<0>")
	)
	(segment
		(start 322.15963 -215.426544)
		(end 322.15963 -216.175844)
		(width 0.16002)
		(layer "In4.Cu")
		(net "M_D_CPU0_SA_DQS_DN<0>")
	)
	(segment
		(start 326.05726 -219.324174)
		(end 327.139554 -220.406468)
		(width 0.16002)
		(layer "In4.Cu")
		(net "M_D_CPU0_SA_DQS_DN<0>")
	)
	(segment
		(start 300.596808 -200.312274)
		(end 301.496984 -201.21245)
		(width 0.16002)
		(layer "In4.Cu")
		(net "M_D_CPU0_SA_DQS_DN<0>")
	)
	(segment
		(start 318.4398 -212.456014)
		(end 319.1891 -212.456014)
		(width 0.16002)
		(layer "In4.Cu")
		(net "M_D_CPU0_SA_DQS_DN<0>")
	)
	(segment
		(start 319.412366 -212.67928)
		(end 319.412366 -213.42858)
		(width 0.16002)
		(layer "In4.Cu")
		(net "M_D_CPU0_SA_DQS_DN<0>")
	)
	(segment
		(start 298.3103 -200.659492)
		(end 298.75226 -200.659492)
		(width 0.16002)
		(layer "In4.Cu")
		(net "M_D_CPU0_SA_DQS_DN<0>")
	)
	(segment
		(start 332.74254 -227.149152)
		(end 332.750922 -227.144326)
		(width 0.09525)
		(layer "In4.Cu")
		(net "M_D_CPU0_SA_DQS_DN<0>")
	)
	(segment
		(start 293.817802 -201.162158)
		(end 294.366188 -201.162158)
		(width 0.16002)
		(layer "In4.Cu")
		(net "M_D_CPU0_SA_DQS_DN<0>")
	)
	(segment
		(start 286.060896 -201.428096)
		(end 286.540956 -201.428096)
		(width 0.16002)
		(layer "In4.Cu")
		(net "M_D_CPU0_SA_DQS_DN<0>")
	)
	(segment
		(start 319.412366 -213.42858)
		(end 319.813432 -213.829646)
		(width 0.16002)
		(layer "In4.Cu")
		(net "M_D_CPU0_SA_DQS_DN<0>")
	)
	(segment
		(start 294.483028 -201.278998)
		(end 294.963088 -201.278998)
		(width 0.16002)
		(layer "In4.Cu")
		(net "M_D_CPU0_SA_DQS_DN<0>")
	)
	(segment
		(start 323.533262 -217.549476)
		(end 323.934328 -217.950542)
		(width 0.16002)
		(layer "In4.Cu")
		(net "M_D_CPU0_SA_DQS_DN<0>")
	)
	(segment
		(start 328.386694 -223.889824)
		(end 328.419714 -223.909128)
		(width 0.09525)
		(layer "In4.Cu")
		(net "M_D_CPU0_SA_DQS_DN<0>")
	)
	(segment
		(start 322.15963 -216.175844)
		(end 322.560696 -216.57691)
		(width 0.16002)
		(layer "In4.Cu")
		(net "M_D_CPU0_SA_DQS_DN<0>")
	)
	(segment
		(start 328.419714 -223.909128)
		(end 328.452226 -223.927924)
		(width 0.09525)
		(layer "In4.Cu")
		(net "M_D_CPU0_SA_DQS_DN<0>")
	)
	(segment
		(start 338.725002 -227.208842)
		(end 338.571078 -227.474272)
		(width 0.09525)
		(layer "In4.Cu")
		(net "M_D_CPU0_SA_DQS_DN<0>")
	)
	(segment
		(start 314.318904 -208.335118)
		(end 315.068204 -208.335118)
		(width 0.16002)
		(layer "In4.Cu")
		(net "M_D_CPU0_SA_DQS_DN<0>")
	)
	(segment
		(start 294.366188 -201.162158)
		(end 294.483028 -201.278998)
		(width 0.16002)
		(layer "In4.Cu")
		(net "M_D_CPU0_SA_DQS_DN<0>")
	)
	(segment
		(start 316.665102 -209.932016)
		(end 316.665102 -210.681316)
		(width 0.16002)
		(layer "In4.Cu")
		(net "M_D_CPU0_SA_DQS_DN<0>")
	)
	(segment
		(start 327.479914 -222.289116)
		(end 327.512426 -222.307912)
		(width 0.09525)
		(layer "In4.Cu")
		(net "M_D_CPU0_SA_DQS_DN<0>")
	)
	(segment
		(start 329.791568 -226.317048)
		(end 329.829668 -226.339146)
		(width 0.09525)
		(layer "In4.Cu")
		(net "M_D_CPU0_SA_DQS_DN<0>")
	)
	(segment
		(start 298.75226 -200.659492)
		(end 299.099478 -200.312274)
		(width 0.16002)
		(layer "In4.Cu")
		(net "M_D_CPU0_SA_DQS_DN<0>")
	)
	(segment
		(start 288.915602 -201.162158)
		(end 289.258756 -201.505312)
		(width 0.16002)
		(layer "In4.Cu")
		(net "M_D_CPU0_SA_DQS_DN<0>")
	)
	(segment
		(start 292.967156 -200.311512)
		(end 293.817802 -201.162158)
		(width 0.16002)
		(layer "In4.Cu")
		(net "M_D_CPU0_SA_DQS_DN<0>")
	)
	(segment
		(start 311.170574 -204.437488)
		(end 311.170574 -205.186788)
		(width 0.16002)
		(layer "In4.Cu")
		(net "M_D_CPU0_SA_DQS_DN<0>")
	)
	(segment
		(start 318.038734 -212.054948)
		(end 318.4398 -212.456014)
		(width 0.16002)
		(layer "In4.Cu")
		(net "M_D_CPU0_SA_DQS_DN<0>")
	)
	(segment
		(start 313.917838 -207.934052)
		(end 314.318904 -208.335118)
		(width 0.16002)
		(layer "In4.Cu")
		(net "M_D_CPU0_SA_DQS_DN<0>")
	)
	(segment
		(start 323.533262 -216.800176)
		(end 323.533262 -217.549476)
		(width 0.16002)
		(layer "In4.Cu")
		(net "M_D_CPU0_SA_DQS_DN<0>")
	)
	(segment
		(start 327.911968 -223.077024)
		(end 327.950068 -223.099122)
		(width 0.09525)
		(layer "In4.Cu")
		(net "M_D_CPU0_SA_DQS_DN<0>")
	)
	(segment
		(start 330.266548 -227.129848)
		(end 330.299568 -227.149152)
		(width 0.09525)
		(layer "In4.Cu")
		(net "M_D_CPU0_SA_DQS_DN<0>")
	)
	(segment
		(start 315.29147 -209.307684)
		(end 315.692536 -209.70875)
		(width 0.16002)
		(layer "In4.Cu")
		(net "M_D_CPU0_SA_DQS_DN<0>")
	)
	(segment
		(start 312.544206 -205.81112)
		(end 312.544206 -206.56042)
		(width 0.16002)
		(layer "In4.Cu")
		(net "M_D_CPU0_SA_DQS_DN<0>")
	)
	(segment
		(start 313.917838 -207.184752)
		(end 313.917838 -207.934052)
		(width 0.16002)
		(layer "In4.Cu")
		(net "M_D_CPU0_SA_DQS_DN<0>")
	)
	(segment
		(start 308.665118 -201.932032)
		(end 309.796942 -203.063856)
		(width 0.16002)
		(layer "In4.Cu")
		(net "M_D_CPU0_SA_DQS_DN<0>")
	)
	(segment
		(start 320.562732 -213.829646)
		(end 320.785998 -214.052912)
		(width 0.16002)
		(layer "In4.Cu")
		(net "M_D_CPU0_SA_DQS_DN<0>")
	)
	(segment
		(start 320.785998 -214.052912)
		(end 320.785998 -214.802212)
		(width 0.16002)
		(layer "In4.Cu")
		(net "M_D_CPU0_SA_DQS_DN<0>")
	)
	(segment
		(start 330.264516 -227.128578)
		(end 330.266548 -227.129848)
		(width 0.09525)
		(layer "In4.Cu")
		(net "M_D_CPU0_SA_DQS_DN<0>")
	)
	(segment
		(start 337.442556 -227.149152)
		(end 337.450938 -227.144326)
		(width 0.09525)
		(layer "In4.Cu")
		(net "M_D_CPU0_SA_DQS_DN<0>")
	)
	(segment
		(start 304.046382 -201.21245)
		(end 304.765964 -201.932032)
		(width 0.16002)
		(layer "In4.Cu")
		(net "M_D_CPU0_SA_DQS_DN<0>")
	)
	(segment
		(start 303.111408 -201.21245)
		(end 304.046382 -201.21245)
		(width 0.16002)
		(layer "In4.Cu")
		(net "M_D_CPU0_SA_DQS_DN<0>")
	)
	(segment
		(start 296.754296 -201.495152)
		(end 297.47464 -201.495152)
		(width 0.16002)
		(layer "In4.Cu")
		(net "M_D_CPU0_SA_DQS_DN<0>")
	)
	(segment
		(start 324.906894 -218.173808)
		(end 324.906894 -218.923108)
		(width 0.16002)
		(layer "In4.Cu")
		(net "M_D_CPU0_SA_DQS_DN<0>")
	)
	(segment
		(start 285.944056 -201.311256)
		(end 286.060896 -201.428096)
		(width 0.16002)
		(layer "In4.Cu")
		(net "M_D_CPU0_SA_DQS_DN<0>")
	)
	(segment
		(start 302.397668 -201.21245)
		(end 302.514508 -201.32929)
		(width 0.16002)
		(layer "In4.Cu")
		(net "M_D_CPU0_SA_DQS_DN<0>")
	)
	(segment
		(start 317.066168 -211.082382)
		(end 317.815468 -211.082382)
		(width 0.16002)
		(layer "In4.Cu")
		(net "M_D_CPU0_SA_DQS_DN<0>")
	)
	(segment
		(start 338.701888 -227.122228)
		(end 338.725002 -227.208842)
		(width 0.09525)
		(layer "In4.Cu")
		(net "M_D_CPU0_SA_DQS_DN<0>")
	)
	(segment
		(start 318.038734 -211.305648)
		(end 318.038734 -212.054948)
		(width 0.16002)
		(layer "In4.Cu")
		(net "M_D_CPU0_SA_DQS_DN<0>")
	)
	(segment
		(start 332.171294 -227.144326)
		(end 332.179676 -227.149152)
		(width 0.09525)
		(layer "In4.Cu")
		(net "M_D_CPU0_SA_DQS_DN<0>")
	)
	(segment
		(start 310.198008 -204.214222)
		(end 310.947308 -204.214222)
		(width 0.16002)
		(layer "In4.Cu")
		(net "M_D_CPU0_SA_DQS_DN<0>")
	)
	(segment
		(start 321.936364 -215.203278)
		(end 322.15963 -215.426544)
		(width 0.16002)
		(layer "In4.Cu")
		(net "M_D_CPU0_SA_DQS_DN<0>")
	)
	(segment
		(start 294.963088 -201.278998)
		(end 295.079928 -201.162158)
		(width 0.16002)
		(layer "In4.Cu")
		(net "M_D_CPU0_SA_DQS_DN<0>")
	)
	(segment
		(start 331.23124 -227.144326)
		(end 331.239622 -227.149152)
		(width 0.09525)
		(layer "In4.Cu")
		(net "M_D_CPU0_SA_DQS_DN<0>")
	)
	(segment
		(start 315.29147 -208.558384)
		(end 315.29147 -209.307684)
		(width 0.16002)
		(layer "In4.Cu")
		(net "M_D_CPU0_SA_DQS_DN<0>")
	)
	(segment
		(start 323.934328 -217.950542)
		(end 324.683628 -217.950542)
		(width 0.16002)
		(layer "In4.Cu")
		(net "M_D_CPU0_SA_DQS_DN<0>")
	)
	(segment
		(start 296.421302 -201.162158)
		(end 296.754296 -201.495152)
		(width 0.16002)
		(layer "In4.Cu")
		(net "M_D_CPU0_SA_DQS_DN<0>")
	)
	(segment
		(start 289.258756 -201.505312)
		(end 289.89782 -201.505312)
		(width 0.16002)
		(layer "In4.Cu")
		(net "M_D_CPU0_SA_DQS_DN<0>")
	)
	(segment
		(start 329.321668 -225.507042)
		(end 329.359768 -225.52914)
		(width 0.09525)
		(layer "In4.Cu")
		(net "M_D_CPU0_SA_DQS_DN<0>")
	)
	(segment
		(start 327.139554 -221.340172)
		(end 327.198736 -221.399354)
		(width 0.09525)
		(layer "In4.Cu")
		(net "M_D_CPU0_SA_DQS_DN<0>")
	)
	(segment
		(start 287.286954 -201.162158)
		(end 288.915602 -201.162158)
		(width 0.16002)
		(layer "In4.Cu")
		(net "M_D_CPU0_SA_DQS_DN<0>")
	)
	(segment
		(start 313.694572 -206.961486)
		(end 313.917838 -207.184752)
		(width 0.16002)
		(layer "In4.Cu")
		(net "M_D_CPU0_SA_DQS_DN<0>")
	)
	(segment
		(start 315.692536 -209.70875)
		(end 316.441836 -209.70875)
		(width 0.16002)
		(layer "In4.Cu")
		(net "M_D_CPU0_SA_DQS_DN<0>")
	)
	(segment
		(start 302.994568 -201.32929)
		(end 303.111408 -201.21245)
		(width 0.16002)
		(layer "In4.Cu")
		(net "M_D_CPU0_SA_DQS_DN<0>")
	)
	(segment
		(start 324.906894 -218.923108)
		(end 325.30796 -219.324174)
		(width 0.16002)
		(layer "In4.Cu")
		(net "M_D_CPU0_SA_DQS_DN<0>")
	)
	(segment
		(start 329.829668 -226.339146)
		(end 329.86218 -226.357942)
		(width 0.09525)
		(layer "In4.Cu")
		(net "M_D_CPU0_SA_DQS_DN<0>")
	)
	(segment
		(start 286.657796 -201.311256)
		(end 287.137856 -201.311256)
		(width 0.16002)
		(layer "In4.Cu")
		(net "M_D_CPU0_SA_DQS_DN<0>")
	)
	(segment
		(start 336.87131 -227.144326)
		(end 336.879692 -227.149152)
		(width 0.09525)
		(layer "In4.Cu")
		(net "M_D_CPU0_SA_DQS_DN<0>")
	)
	(segment
		(start 319.813432 -213.829646)
		(end 320.562732 -213.829646)
		(width 0.16002)
		(layer "In4.Cu")
		(net "M_D_CPU0_SA_DQS_DN<0>")
	)
	(segment
		(start 312.945272 -206.961486)
		(end 313.694572 -206.961486)
		(width 0.16002)
		(layer "In4.Cu")
		(net "M_D_CPU0_SA_DQS_DN<0>")
	)
	(segment
		(start 309.796942 -203.063856)
		(end 309.796942 -203.813156)
		(width 0.16002)
		(layer "In4.Cu")
		(net "M_D_CPU0_SA_DQS_DN<0>")
	)
	(segment
		(start 328.856594 -224.69983)
		(end 328.889614 -224.719134)
		(width 0.09525)
		(layer "In4.Cu")
		(net "M_D_CPU0_SA_DQS_DN<0>")
	)
	(segment
		(start 290.73856 -200.664572)
		(end 291.19576 -200.664572)
		(width 0.16002)
		(layer "In4.Cu")
		(net "M_D_CPU0_SA_DQS_DN<0>")
	)
	(segment
		(start 317.815468 -211.082382)
		(end 318.038734 -211.305648)
		(width 0.16002)
		(layer "In4.Cu")
		(net "M_D_CPU0_SA_DQS_DN<0>")
	)
	(segment
		(start 291.54882 -200.311512)
		(end 292.967156 -200.311512)
		(width 0.16002)
		(layer "In4.Cu")
		(net "M_D_CPU0_SA_DQS_DN<0>")
	)
	(segment
		(start 302.514508 -201.32929)
		(end 302.994568 -201.32929)
		(width 0.16002)
		(layer "In4.Cu")
		(net "M_D_CPU0_SA_DQS_DN<0>")
	)
	(segment
		(start 315.068204 -208.335118)
		(end 315.29147 -208.558384)
		(width 0.16002)
		(layer "In4.Cu")
		(net "M_D_CPU0_SA_DQS_DN<0>")
	)
	(segment
		(start 309.796942 -203.813156)
		(end 310.198008 -204.214222)
		(width 0.16002)
		(layer "In4.Cu")
		(net "M_D_CPU0_SA_DQS_DN<0>")
	)
	(segment
		(start 327.139554 -221.31655)
		(end 327.139554 -221.340172)
		(width 0.09525)
		(layer "In4.Cu")
		(net "M_D_CPU0_SA_DQS_DN<0>")
	)
	(segment
		(start 285.009844 -201.311256)
		(end 285.944056 -201.311256)
		(width 0.16002)
		(layer "In4.Cu")
		(net "M_D_CPU0_SA_DQS_DN<0>")
	)
	(segment
		(start 310.947308 -204.214222)
		(end 311.170574 -204.437488)
		(width 0.16002)
		(layer "In4.Cu")
		(net "M_D_CPU0_SA_DQS_DN<0>")
	)
	(segment
		(start 284.736032 -201.585068)
		(end 285.009844 -201.311256)
		(width 0.16002)
		(layer "In4.Cu")
		(net "M_D_CPU0_SA_DQS_DN<0>")
	)
	(segment
		(start 333.682594 -227.149152)
		(end 333.690976 -227.144326)
		(width 0.09525)
		(layer "In4.Cu")
		(net "M_D_CPU0_SA_DQS_DN<0>")
	)
	(segment
		(start 327.950068 -223.099122)
		(end 327.981564 -223.11741)
		(width 0.09525)
		(layer "In4.Cu")
		(net "M_D_CPU0_SA_DQS_DN<0>")
	)
	(arc
		(start 327.512426 -222.307912)
		(mid 327.6277 -222.44219)
		(end 327.669144 -222.614236)
		(width 0.09525)
		(layer "In4.Cu")
		(net "M_D_CPU0_SA_DQS_DN<0>")
	)
	(arc
		(start 333.11973 -227.149152)
		(mid 333.401162 -227.224907)
		(end 333.682594 -227.149152)
		(width 0.09525)
		(layer "In4.Cu")
		(net "M_D_CPU0_SA_DQS_DN<0>")
	)
	(arc
		(start 328.452226 -223.927924)
		(mid 328.5675 -224.062202)
		(end 328.608944 -224.234248)
		(width 0.09525)
		(layer "In4.Cu")
		(net "M_D_CPU0_SA_DQS_DN<0>")
	)
	(arc
		(start 327.669144 -222.614236)
		(mid 327.733541 -222.875542)
		(end 327.911968 -223.077024)
		(width 0.09525)
		(layer "In4.Cu")
		(net "M_D_CPU0_SA_DQS_DN<0>")
	)
	(arc
		(start 337.450938 -227.144326)
		(mid 337.63597 -227.098412)
		(end 337.819746 -227.149152)
		(width 0.09525)
		(layer "In4.Cu")
		(net "M_D_CPU0_SA_DQS_DN<0>")
	)
	(arc
		(start 331.239622 -227.149152)
		(mid 331.521054 -227.224907)
		(end 331.802486 -227.149152)
		(width 0.09525)
		(layer "In4.Cu")
		(net "M_D_CPU0_SA_DQS_DN<0>")
	)
	(arc
		(start 328.608944 -224.234248)
		(mid 328.674137 -224.496877)
		(end 328.854562 -224.69856)
		(width 0.09525)
		(layer "In4.Cu")
		(net "M_D_CPU0_SA_DQS_DN<0>")
	)
	(arc
		(start 335.562448 -227.149152)
		(mid 335.746223 -227.09838)
		(end 335.931256 -227.144326)
		(width 0.09525)
		(layer "In4.Cu")
		(net "M_D_CPU0_SA_DQS_DN<0>")
	)
	(arc
		(start 337.819746 -227.149152)
		(mid 338.101178 -227.224907)
		(end 338.38261 -227.149152)
		(width 0.09525)
		(layer "In4.Cu")
		(net "M_D_CPU0_SA_DQS_DN<0>")
	)
	(arc
		(start 338.38261 -227.149152)
		(mid 338.539237 -227.099966)
		(end 338.701888 -227.122228)
		(width 0.09525)
		(layer "In4.Cu")
		(net "M_D_CPU0_SA_DQS_DN<0>")
	)
	(arc
		(start 332.179676 -227.149152)
		(mid 332.461108 -227.224907)
		(end 332.74254 -227.149152)
		(width 0.09525)
		(layer "In4.Cu")
		(net "M_D_CPU0_SA_DQS_DN<0>")
	)
	(arc
		(start 329.078844 -225.044254)
		(mid 329.143241 -225.30556)
		(end 329.321668 -225.507042)
		(width 0.09525)
		(layer "In4.Cu")
		(net "M_D_CPU0_SA_DQS_DN<0>")
	)
	(arc
		(start 329.548744 -225.85426)
		(mid 329.613141 -226.115566)
		(end 329.791568 -226.317048)
		(width 0.09525)
		(layer "In4.Cu")
		(net "M_D_CPU0_SA_DQS_DN<0>")
	)
	(arc
		(start 332.750922 -227.144326)
		(mid 332.935954 -227.098412)
		(end 333.11973 -227.149152)
		(width 0.09525)
		(layer "In4.Cu")
		(net "M_D_CPU0_SA_DQS_DN<0>")
	)
	(arc
		(start 330.299568 -227.149152)
		(mid 330.581 -227.224907)
		(end 330.862432 -227.149152)
		(width 0.09525)
		(layer "In4.Cu")
		(net "M_D_CPU0_SA_DQS_DN<0>")
	)
	(arc
		(start 329.391264 -225.547428)
		(mid 329.507062 -225.681822)
		(end 329.548744 -225.85426)
		(width 0.09525)
		(layer "In4.Cu")
		(net "M_D_CPU0_SA_DQS_DN<0>")
	)
	(arc
		(start 336.879692 -227.149152)
		(mid 337.161124 -227.224907)
		(end 337.442556 -227.149152)
		(width 0.09525)
		(layer "In4.Cu")
		(net "M_D_CPU0_SA_DQS_DN<0>")
	)
	(arc
		(start 329.86218 -226.357942)
		(mid 329.977454 -226.49222)
		(end 330.018898 -226.664266)
		(width 0.09525)
		(layer "In4.Cu")
		(net "M_D_CPU0_SA_DQS_DN<0>")
	)
	(arc
		(start 334.059784 -227.149152)
		(mid 334.341216 -227.224907)
		(end 334.622648 -227.149152)
		(width 0.09525)
		(layer "In4.Cu")
		(net "M_D_CPU0_SA_DQS_DN<0>")
	)
	(arc
		(start 327.981564 -223.11741)
		(mid 328.097362 -223.251804)
		(end 328.139044 -223.424242)
		(width 0.09525)
		(layer "In4.Cu")
		(net "M_D_CPU0_SA_DQS_DN<0>")
	)
	(arc
		(start 335.939638 -227.149152)
		(mid 336.22107 -227.224907)
		(end 336.502502 -227.149152)
		(width 0.09525)
		(layer "In4.Cu")
		(net "M_D_CPU0_SA_DQS_DN<0>")
	)
	(arc
		(start 330.018898 -226.664266)
		(mid 330.084091 -226.926895)
		(end 330.264516 -227.128578)
		(width 0.09525)
		(layer "In4.Cu")
		(net "M_D_CPU0_SA_DQS_DN<0>")
	)
	(arc
		(start 327.198736 -221.80423)
		(mid 327.262838 -222.064974)
		(end 327.440544 -222.266256)
		(width 0.09525)
		(layer "In4.Cu")
		(net "M_D_CPU0_SA_DQS_DN<0>")
	)
	(arc
		(start 333.690976 -227.144326)
		(mid 333.876008 -227.098412)
		(end 334.059784 -227.149152)
		(width 0.09525)
		(layer "In4.Cu")
		(net "M_D_CPU0_SA_DQS_DN<0>")
	)
	(arc
		(start 334.622648 -227.149152)
		(mid 334.811116 -227.098475)
		(end 334.999584 -227.149152)
		(width 0.09525)
		(layer "In4.Cu")
		(net "M_D_CPU0_SA_DQS_DN<0>")
	)
	(arc
		(start 331.802486 -227.149152)
		(mid 331.986261 -227.09838)
		(end 332.171294 -227.144326)
		(width 0.09525)
		(layer "In4.Cu")
		(net "M_D_CPU0_SA_DQS_DN<0>")
	)
	(arc
		(start 334.999584 -227.149152)
		(mid 335.281016 -227.224907)
		(end 335.562448 -227.149152)
		(width 0.09525)
		(layer "In4.Cu")
		(net "M_D_CPU0_SA_DQS_DN<0>")
	)
	(arc
		(start 330.862432 -227.149152)
		(mid 331.046207 -227.09838)
		(end 331.23124 -227.144326)
		(width 0.09525)
		(layer "In4.Cu")
		(net "M_D_CPU0_SA_DQS_DN<0>")
	)
	(arc
		(start 328.922126 -224.73793)
		(mid 329.0374 -224.872208)
		(end 329.078844 -225.044254)
		(width 0.09525)
		(layer "In4.Cu")
		(net "M_D_CPU0_SA_DQS_DN<0>")
	)
	(arc
		(start 328.139044 -223.424242)
		(mid 328.204237 -223.686871)
		(end 328.384662 -223.888554)
		(width 0.09525)
		(layer "In4.Cu")
		(net "M_D_CPU0_SA_DQS_DN<0>")
	)
	(arc
		(start 336.502502 -227.149152)
		(mid 336.686277 -227.09838)
		(end 336.87131 -227.144326)
		(width 0.09525)
		(layer "In4.Cu")
		(net "M_D_CPU0_SA_DQS_DN<0>")
	)
	(segment
		(start 340.918038 -230.97998)
		(end 340.451186 -230.714296)
		(width 0.10668)
		(layer "F.Cu")
		(net "M_D_CPU0_SA_DQ<9>")
	)
	(segment
		(start 325.020178 -227.344732)
		(end 326.165718 -228.490272)
		(width 0.0889)
		(layer "In4.Cu")
		(net "M_D_CPU0_SA_DQ<9>")
	)
	(segment
		(start 296.4815 -209.19821)
		(end 296.711878 -209.19821)
		(width 0.14478)
		(layer "In4.Cu")
		(net "M_D_CPU0_SA_DQ<9>")
	)
	(segment
		(start 296.155364 -208.810098)
		(end 296.318432 -208.973166)
		(width 0.14478)
		(layer "In4.Cu")
		(net "M_D_CPU0_SA_DQ<9>")
	)
	(segment
		(start 303.025302 -208.973166)
		(end 303.18837 -208.810098)
		(width 0.14478)
		(layer "In4.Cu")
		(net "M_D_CPU0_SA_DQ<9>")
	)
	(segment
		(start 291.771578 -208.189322)
		(end 291.771578 -208.123282)
		(width 0.14478)
		(layer "In4.Cu")
		(net "M_D_CPU0_SA_DQ<9>")
	)
	(segment
		(start 303.581816 -208.973166)
		(end 303.581816 -209.030062)
		(width 0.14478)
		(layer "In4.Cu")
		(net "M_D_CPU0_SA_DQ<9>")
	)
	(segment
		(start 328.011536 -231.017826)
		(end 328.044048 -231.036622)
		(width 0.0889)
		(layer "In4.Cu")
		(net "M_D_CPU0_SA_DQ<9>")
	)
	(segment
		(start 296.318432 -208.973166)
		(end 296.318432 -209.035142)
		(width 0.14478)
		(layer "In4.Cu")
		(net "M_D_CPU0_SA_DQ<9>")
	)
	(segment
		(start 296.874946 -208.973166)
		(end 297.038014 -208.810098)
		(width 0.14478)
		(layer "In4.Cu")
		(net "M_D_CPU0_SA_DQ<9>")
	)
	(segment
		(start 288.694368 -208.810098)
		(end 288.857436 -208.973166)
		(width 0.14478)
		(layer "In4.Cu")
		(net "M_D_CPU0_SA_DQ<9>")
	)
	(segment
		(start 294.348662 -208.810098)
		(end 296.155364 -208.810098)
		(width 0.14478)
		(layer "In4.Cu")
		(net "M_D_CPU0_SA_DQ<9>")
	)
	(segment
		(start 301.174658 -207.960214)
		(end 302.024542 -208.810098)
		(width 0.14478)
		(layer "In4.Cu")
		(net "M_D_CPU0_SA_DQ<9>")
	)
	(segment
		(start 285.764224 -208.973166)
		(end 285.764224 -209.030062)
		(width 0.14478)
		(layer "In4.Cu")
		(net "M_D_CPU0_SA_DQ<9>")
	)
	(segment
		(start 302.468788 -209.030062)
		(end 302.631856 -209.19313)
		(width 0.14478)
		(layer "In4.Cu")
		(net "M_D_CPU0_SA_DQ<9>")
	)
	(segment
		(start 286.320738 -208.7245)
		(end 286.483806 -208.561432)
		(width 0.14478)
		(layer "In4.Cu")
		(net "M_D_CPU0_SA_DQ<9>")
	)
	(segment
		(start 298.196762 -207.960214)
		(end 298.557442 -207.960214)
		(width 0.14478)
		(layer "In4.Cu")
		(net "M_D_CPU0_SA_DQ<9>")
	)
	(segment
		(start 289.020504 -209.19313)
		(end 289.250882 -209.19313)
		(width 0.14478)
		(layer "In4.Cu")
		(net "M_D_CPU0_SA_DQ<9>")
	)
	(segment
		(start 302.024542 -208.810098)
		(end 302.30572 -208.810098)
		(width 0.14478)
		(layer "In4.Cu")
		(net "M_D_CPU0_SA_DQ<9>")
	)
	(segment
		(start 287.270698 -209.19313)
		(end 287.433766 -209.030062)
		(width 0.14478)
		(layer "In4.Cu")
		(net "M_D_CPU0_SA_DQ<9>")
	)
	(segment
		(start 320.933318 -221.552008)
		(end 320.933318 -222.381572)
		(width 0.14478)
		(layer "In4.Cu")
		(net "M_D_CPU0_SA_DQ<9>")
	)
	(segment
		(start 287.596834 -208.810098)
		(end 288.694368 -208.810098)
		(width 0.14478)
		(layer "In4.Cu")
		(net "M_D_CPU0_SA_DQ<9>")
	)
	(segment
		(start 286.714184 -208.561432)
		(end 286.877252 -208.7245)
		(width 0.14478)
		(layer "In4.Cu")
		(net "M_D_CPU0_SA_DQ<9>")
	)
	(segment
		(start 297.038014 -208.810098)
		(end 297.346878 -208.810098)
		(width 0.14478)
		(layer "In4.Cu")
		(net "M_D_CPU0_SA_DQ<9>")
	)
	(segment
		(start 285.160974 -208.810098)
		(end 285.601156 -208.810098)
		(width 0.14478)
		(layer "In4.Cu")
		(net "M_D_CPU0_SA_DQ<9>")
	)
	(segment
		(start 322.851018 -225.684334)
		(end 324.020434 -226.85375)
		(width 0.14478)
		(layer "In4.Cu")
		(net "M_D_CPU0_SA_DQ<9>")
	)
	(segment
		(start 324.020434 -226.85375)
		(end 324.511416 -227.344732)
		(width 0.0889)
		(layer "In4.Cu")
		(net "M_D_CPU0_SA_DQ<9>")
	)
	(segment
		(start 287.04032 -209.19313)
		(end 287.270698 -209.19313)
		(width 0.14478)
		(layer "In4.Cu")
		(net "M_D_CPU0_SA_DQ<9>")
	)
	(segment
		(start 289.577018 -208.810098)
		(end 289.823398 -208.810098)
		(width 0.14478)
		(layer "In4.Cu")
		(net "M_D_CPU0_SA_DQ<9>")
	)
	(segment
		(start 326.165718 -228.490272)
		(end 326.407018 -228.490272)
		(width 0.0889)
		(layer "In4.Cu")
		(net "M_D_CPU0_SA_DQ<9>")
	)
	(segment
		(start 289.823398 -208.810098)
		(end 290.673282 -207.960214)
		(width 0.14478)
		(layer "In4.Cu")
		(net "M_D_CPU0_SA_DQ<9>")
	)
	(segment
		(start 296.874946 -209.035142)
		(end 296.874946 -208.973166)
		(width 0.14478)
		(layer "In4.Cu")
		(net "M_D_CPU0_SA_DQ<9>")
	)
	(segment
		(start 335.929732 -231.041448)
		(end 335.938114 -231.036622)
		(width 0.0889)
		(layer "In4.Cu")
		(net "M_D_CPU0_SA_DQ<9>")
	)
	(segment
		(start 308.191408 -208.810098)
		(end 320.933318 -221.552008)
		(width 0.14478)
		(layer "In4.Cu")
		(net "M_D_CPU0_SA_DQ<9>")
	)
	(segment
		(start 298.557442 -207.960214)
		(end 298.72051 -208.123282)
		(width 0.14478)
		(layer "In4.Cu")
		(net "M_D_CPU0_SA_DQ<9>")
	)
	(segment
		(start 298.87926 -208.348072)
		(end 299.118274 -208.348072)
		(width 0.14478)
		(layer "In4.Cu")
		(net "M_D_CPU0_SA_DQ<9>")
	)
	(segment
		(start 285.764224 -209.030062)
		(end 285.927292 -209.19313)
		(width 0.14478)
		(layer "In4.Cu")
		(net "M_D_CPU0_SA_DQ<9>")
	)
	(segment
		(start 296.711878 -209.19821)
		(end 296.874946 -209.035142)
		(width 0.14478)
		(layer "In4.Cu")
		(net "M_D_CPU0_SA_DQ<9>")
	)
	(segment
		(start 299.118274 -208.348072)
		(end 299.277024 -208.189322)
		(width 0.14478)
		(layer "In4.Cu")
		(net "M_D_CPU0_SA_DQ<9>")
	)
	(segment
		(start 327.542398 -230.208328)
		(end 327.574148 -230.226616)
		(width 0.0889)
		(layer "In4.Cu")
		(net "M_D_CPU0_SA_DQ<9>")
	)
	(segment
		(start 290.673282 -207.960214)
		(end 291.051996 -207.960214)
		(width 0.14478)
		(layer "In4.Cu")
		(net "M_D_CPU0_SA_DQ<9>")
	)
	(segment
		(start 286.877252 -208.7245)
		(end 286.877252 -209.030062)
		(width 0.14478)
		(layer "In4.Cu")
		(net "M_D_CPU0_SA_DQ<9>")
	)
	(segment
		(start 288.857436 -209.030062)
		(end 289.020504 -209.19313)
		(width 0.14478)
		(layer "In4.Cu")
		(net "M_D_CPU0_SA_DQ<9>")
	)
	(segment
		(start 326.986138 -229.069392)
		(end 326.986138 -229.280212)
		(width 0.0889)
		(layer "In4.Cu")
		(net "M_D_CPU0_SA_DQ<9>")
	)
	(segment
		(start 328.409808 -231.041448)
		(end 328.41819 -231.036622)
		(width 0.0889)
		(layer "In4.Cu")
		(net "M_D_CPU0_SA_DQ<9>")
	)
	(segment
		(start 287.433766 -209.030062)
		(end 287.433766 -208.973166)
		(width 0.14478)
		(layer "In4.Cu")
		(net "M_D_CPU0_SA_DQ<9>")
	)
	(segment
		(start 299.277024 -208.123282)
		(end 299.440092 -207.960214)
		(width 0.14478)
		(layer "In4.Cu")
		(net "M_D_CPU0_SA_DQ<9>")
	)
	(segment
		(start 291.215064 -208.123282)
		(end 291.215064 -208.189322)
		(width 0.14478)
		(layer "In4.Cu")
		(net "M_D_CPU0_SA_DQ<9>")
	)
	(segment
		(start 303.18837 -208.810098)
		(end 303.418748 -208.810098)
		(width 0.14478)
		(layer "In4.Cu")
		(net "M_D_CPU0_SA_DQ<9>")
	)
	(segment
		(start 303.025302 -209.030062)
		(end 303.025302 -208.973166)
		(width 0.14478)
		(layer "In4.Cu")
		(net "M_D_CPU0_SA_DQ<9>")
	)
	(segment
		(start 285.927292 -209.19313)
		(end 286.15767 -209.19313)
		(width 0.14478)
		(layer "In4.Cu")
		(net "M_D_CPU0_SA_DQ<9>")
	)
	(segment
		(start 302.862234 -209.19313)
		(end 303.025302 -209.030062)
		(width 0.14478)
		(layer "In4.Cu")
		(net "M_D_CPU0_SA_DQ<9>")
	)
	(segment
		(start 331.229716 -231.041448)
		(end 331.238098 -231.036622)
		(width 0.0889)
		(layer "In4.Cu")
		(net "M_D_CPU0_SA_DQ<9>")
	)
	(segment
		(start 287.433766 -208.973166)
		(end 287.596834 -208.810098)
		(width 0.14478)
		(layer "In4.Cu")
		(net "M_D_CPU0_SA_DQ<9>")
	)
	(segment
		(start 304.13833 -208.973166)
		(end 304.301398 -208.810098)
		(width 0.14478)
		(layer "In4.Cu")
		(net "M_D_CPU0_SA_DQ<9>")
	)
	(segment
		(start 332.16977 -231.041448)
		(end 332.178152 -231.036622)
		(width 0.0889)
		(layer "In4.Cu")
		(net "M_D_CPU0_SA_DQ<9>")
	)
	(segment
		(start 299.440092 -207.960214)
		(end 301.174658 -207.960214)
		(width 0.14478)
		(layer "In4.Cu")
		(net "M_D_CPU0_SA_DQ<9>")
	)
	(segment
		(start 297.346878 -208.810098)
		(end 298.196762 -207.960214)
		(width 0.14478)
		(layer "In4.Cu")
		(net "M_D_CPU0_SA_DQ<9>")
	)
	(segment
		(start 320.933318 -222.381572)
		(end 322.851018 -224.299272)
		(width 0.14478)
		(layer "In4.Cu")
		(net "M_D_CPU0_SA_DQ<9>")
	)
	(segment
		(start 326.407018 -228.490272)
		(end 326.986138 -229.069392)
		(width 0.0889)
		(layer "In4.Cu")
		(net "M_D_CPU0_SA_DQ<9>")
	)
	(segment
		(start 288.857436 -208.973166)
		(end 288.857436 -209.030062)
		(width 0.14478)
		(layer "In4.Cu")
		(net "M_D_CPU0_SA_DQ<9>")
	)
	(segment
		(start 328.984102 -231.036622)
		(end 328.992484 -231.041448)
		(width 0.0889)
		(layer "In4.Cu")
		(net "M_D_CPU0_SA_DQ<9>")
	)
	(segment
		(start 303.581816 -209.030062)
		(end 303.744884 -209.19313)
		(width 0.14478)
		(layer "In4.Cu")
		(net "M_D_CPU0_SA_DQ<9>")
	)
	(segment
		(start 337.44408 -231.036622)
		(end 337.452462 -231.041448)
		(width 0.0889)
		(layer "In4.Cu")
		(net "M_D_CPU0_SA_DQ<9>")
	)
	(segment
		(start 289.250882 -209.19313)
		(end 289.41395 -209.030062)
		(width 0.14478)
		(layer "In4.Cu")
		(net "M_D_CPU0_SA_DQ<9>")
	)
	(segment
		(start 296.318432 -209.035142)
		(end 296.4815 -209.19821)
		(width 0.14478)
		(layer "In4.Cu")
		(net "M_D_CPU0_SA_DQ<9>")
	)
	(segment
		(start 302.30572 -208.810098)
		(end 302.468788 -208.973166)
		(width 0.14478)
		(layer "In4.Cu")
		(net "M_D_CPU0_SA_DQ<9>")
	)
	(segment
		(start 332.744064 -231.036622)
		(end 332.752446 -231.041448)
		(width 0.0889)
		(layer "In4.Cu")
		(net "M_D_CPU0_SA_DQ<9>")
	)
	(segment
		(start 286.15767 -209.19313)
		(end 286.320738 -209.030062)
		(width 0.14478)
		(layer "In4.Cu")
		(net "M_D_CPU0_SA_DQ<9>")
	)
	(segment
		(start 324.511416 -227.344732)
		(end 325.020178 -227.344732)
		(width 0.0889)
		(layer "In4.Cu")
		(net "M_D_CPU0_SA_DQ<9>")
	)
	(segment
		(start 293.498778 -207.960214)
		(end 294.348662 -208.810098)
		(width 0.14478)
		(layer "In4.Cu")
		(net "M_D_CPU0_SA_DQ<9>")
	)
	(segment
		(start 299.277024 -208.189322)
		(end 299.277024 -208.123282)
		(width 0.14478)
		(layer "In4.Cu")
		(net "M_D_CPU0_SA_DQ<9>")
	)
	(segment
		(start 291.051996 -207.960214)
		(end 291.215064 -208.123282)
		(width 0.14478)
		(layer "In4.Cu")
		(net "M_D_CPU0_SA_DQ<9>")
	)
	(segment
		(start 327.574148 -230.226616)
		(end 327.610724 -230.247952)
		(width 0.0889)
		(layer "In4.Cu")
		(net "M_D_CPU0_SA_DQ<9>")
	)
	(segment
		(start 304.13833 -209.030062)
		(end 304.13833 -208.973166)
		(width 0.14478)
		(layer "In4.Cu")
		(net "M_D_CPU0_SA_DQ<9>")
	)
	(segment
		(start 286.877252 -209.030062)
		(end 287.04032 -209.19313)
		(width 0.14478)
		(layer "In4.Cu")
		(net "M_D_CPU0_SA_DQ<9>")
	)
	(segment
		(start 303.418748 -208.810098)
		(end 303.581816 -208.973166)
		(width 0.14478)
		(layer "In4.Cu")
		(net "M_D_CPU0_SA_DQ<9>")
	)
	(segment
		(start 285.601156 -208.810098)
		(end 285.764224 -208.973166)
		(width 0.14478)
		(layer "In4.Cu")
		(net "M_D_CPU0_SA_DQ<9>")
	)
	(segment
		(start 336.869786 -231.041448)
		(end 336.878168 -231.036622)
		(width 0.0889)
		(layer "In4.Cu")
		(net "M_D_CPU0_SA_DQ<9>")
	)
	(segment
		(start 289.41395 -208.973166)
		(end 289.577018 -208.810098)
		(width 0.14478)
		(layer "In4.Cu")
		(net "M_D_CPU0_SA_DQ<9>")
	)
	(segment
		(start 291.934646 -207.960214)
		(end 293.498778 -207.960214)
		(width 0.14478)
		(layer "In4.Cu")
		(net "M_D_CPU0_SA_DQ<9>")
	)
	(segment
		(start 291.376354 -208.350612)
		(end 291.610288 -208.350612)
		(width 0.14478)
		(layer "In4.Cu")
		(net "M_D_CPU0_SA_DQ<9>")
	)
	(segment
		(start 286.320738 -209.030062)
		(end 286.320738 -208.7245)
		(width 0.14478)
		(layer "In4.Cu")
		(net "M_D_CPU0_SA_DQ<9>")
	)
	(segment
		(start 291.215064 -208.189322)
		(end 291.376354 -208.350612)
		(width 0.14478)
		(layer "In4.Cu")
		(net "M_D_CPU0_SA_DQ<9>")
	)
	(segment
		(start 289.41395 -209.030062)
		(end 289.41395 -208.973166)
		(width 0.14478)
		(layer "In4.Cu")
		(net "M_D_CPU0_SA_DQ<9>")
	)
	(segment
		(start 340.20125 -231.005126)
		(end 340.297008 -230.979726)
		(width 0.0889)
		(layer "In4.Cu")
		(net "M_D_CPU0_SA_DQ<9>")
	)
	(segment
		(start 322.851018 -224.299272)
		(end 322.851018 -225.684334)
		(width 0.14478)
		(layer "In4.Cu")
		(net "M_D_CPU0_SA_DQ<9>")
	)
	(segment
		(start 291.771578 -208.123282)
		(end 291.934646 -207.960214)
		(width 0.14478)
		(layer "In4.Cu")
		(net "M_D_CPU0_SA_DQ<9>")
	)
	(segment
		(start 284.736032 -208.385156)
		(end 285.160974 -208.810098)
		(width 0.14478)
		(layer "In4.Cu")
		(net "M_D_CPU0_SA_DQ<9>")
	)
	(segment
		(start 339.689694 -231.041448)
		(end 339.698076 -231.036622)
		(width 0.0889)
		(layer "In4.Cu")
		(net "M_D_CPU0_SA_DQ<9>")
	)
	(segment
		(start 302.631856 -209.19313)
		(end 302.862234 -209.19313)
		(width 0.14478)
		(layer "In4.Cu")
		(net "M_D_CPU0_SA_DQ<9>")
	)
	(segment
		(start 303.975262 -209.19313)
		(end 304.13833 -209.030062)
		(width 0.14478)
		(layer "In4.Cu")
		(net "M_D_CPU0_SA_DQ<9>")
	)
	(segment
		(start 298.72051 -208.123282)
		(end 298.72051 -208.189322)
		(width 0.14478)
		(layer "In4.Cu")
		(net "M_D_CPU0_SA_DQ<9>")
	)
	(segment
		(start 304.301398 -208.810098)
		(end 308.191408 -208.810098)
		(width 0.14478)
		(layer "In4.Cu")
		(net "M_D_CPU0_SA_DQ<9>")
	)
	(segment
		(start 298.72051 -208.189322)
		(end 298.87926 -208.348072)
		(width 0.14478)
		(layer "In4.Cu")
		(net "M_D_CPU0_SA_DQ<9>")
	)
	(segment
		(start 333.684118 -231.036622)
		(end 333.6925 -231.041448)
		(width 0.0889)
		(layer "In4.Cu")
		(net "M_D_CPU0_SA_DQ<9>")
	)
	(segment
		(start 340.297008 -230.979726)
		(end 340.451186 -230.714296)
		(width 0.0889)
		(layer "In4.Cu")
		(net "M_D_CPU0_SA_DQ<9>")
	)
	(segment
		(start 286.483806 -208.561432)
		(end 286.714184 -208.561432)
		(width 0.14478)
		(layer "In4.Cu")
		(net "M_D_CPU0_SA_DQ<9>")
	)
	(segment
		(start 326.986138 -229.280212)
		(end 327.278746 -229.57282)
		(width 0.0889)
		(layer "In4.Cu")
		(net "M_D_CPU0_SA_DQ<9>")
	)
	(segment
		(start 291.610288 -208.350612)
		(end 291.771578 -208.189322)
		(width 0.14478)
		(layer "In4.Cu")
		(net "M_D_CPU0_SA_DQ<9>")
	)
	(segment
		(start 303.744884 -209.19313)
		(end 303.975262 -209.19313)
		(width 0.14478)
		(layer "In4.Cu")
		(net "M_D_CPU0_SA_DQ<9>")
	)
	(segment
		(start 302.468788 -208.973166)
		(end 302.468788 -209.030062)
		(width 0.14478)
		(layer "In4.Cu")
		(net "M_D_CPU0_SA_DQ<9>")
	)
	(arc
		(start 334.624172 -231.036622)
		(mid 334.811116 -231.086911)
		(end 334.99806 -231.036622)
		(width 0.0889)
		(layer "In4.Cu")
		(net "M_D_CPU0_SA_DQ<9>")
	)
	(arc
		(start 331.80401 -231.036622)
		(mid 331.986261 -231.087006)
		(end 332.16977 -231.041448)
		(width 0.0889)
		(layer "In4.Cu")
		(net "M_D_CPU0_SA_DQ<9>")
	)
	(arc
		(start 338.758022 -231.036622)
		(mid 339.040978 -230.960445)
		(end 339.323934 -231.036622)
		(width 0.0889)
		(layer "In4.Cu")
		(net "M_D_CPU0_SA_DQ<9>")
	)
	(arc
		(start 327.386442 -229.904036)
		(mid 327.427697 -230.075007)
		(end 327.542398 -230.208328)
		(width 0.0889)
		(layer "In4.Cu")
		(net "M_D_CPU0_SA_DQ<9>")
	)
	(arc
		(start 328.044048 -231.036622)
		(mid 328.226299 -231.087006)
		(end 328.409808 -231.041448)
		(width 0.0889)
		(layer "In4.Cu")
		(net "M_D_CPU0_SA_DQ<9>")
	)
	(arc
		(start 328.41819 -231.036622)
		(mid 328.701146 -230.960445)
		(end 328.984102 -231.036622)
		(width 0.0889)
		(layer "In4.Cu")
		(net "M_D_CPU0_SA_DQ<9>")
	)
	(arc
		(start 329.358244 -231.036622)
		(mid 329.6412 -230.960445)
		(end 329.924156 -231.036622)
		(width 0.0889)
		(layer "In4.Cu")
		(net "M_D_CPU0_SA_DQ<9>")
	)
	(arc
		(start 334.99806 -231.036622)
		(mid 335.281016 -230.960445)
		(end 335.563972 -231.036622)
		(width 0.0889)
		(layer "In4.Cu")
		(net "M_D_CPU0_SA_DQ<9>")
	)
	(arc
		(start 338.384134 -231.036622)
		(mid 338.571078 -231.086911)
		(end 338.758022 -231.036622)
		(width 0.0889)
		(layer "In4.Cu")
		(net "M_D_CPU0_SA_DQ<9>")
	)
	(arc
		(start 332.752446 -231.041448)
		(mid 332.935954 -231.086973)
		(end 333.118206 -231.036622)
		(width 0.0889)
		(layer "In4.Cu")
		(net "M_D_CPU0_SA_DQ<9>")
	)
	(arc
		(start 328.992484 -231.041448)
		(mid 329.175992 -231.086973)
		(end 329.358244 -231.036622)
		(width 0.0889)
		(layer "In4.Cu")
		(net "M_D_CPU0_SA_DQ<9>")
	)
	(arc
		(start 335.938114 -231.036622)
		(mid 336.22107 -230.960445)
		(end 336.504026 -231.036622)
		(width 0.0889)
		(layer "In4.Cu")
		(net "M_D_CPU0_SA_DQ<9>")
	)
	(arc
		(start 333.6925 -231.041448)
		(mid 333.876008 -231.086973)
		(end 334.05826 -231.036622)
		(width 0.0889)
		(layer "In4.Cu")
		(net "M_D_CPU0_SA_DQ<9>")
	)
	(arc
		(start 336.504026 -231.036622)
		(mid 336.686277 -231.087006)
		(end 336.869786 -231.041448)
		(width 0.0889)
		(layer "In4.Cu")
		(net "M_D_CPU0_SA_DQ<9>")
	)
	(arc
		(start 337.452462 -231.041448)
		(mid 337.63597 -231.086973)
		(end 337.818222 -231.036622)
		(width 0.0889)
		(layer "In4.Cu")
		(net "M_D_CPU0_SA_DQ<9>")
	)
	(arc
		(start 337.818222 -231.036622)
		(mid 338.101178 -230.960445)
		(end 338.384134 -231.036622)
		(width 0.0889)
		(layer "In4.Cu")
		(net "M_D_CPU0_SA_DQ<9>")
	)
	(arc
		(start 335.563972 -231.036622)
		(mid 335.746223 -231.087006)
		(end 335.929732 -231.041448)
		(width 0.0889)
		(layer "In4.Cu")
		(net "M_D_CPU0_SA_DQ<9>")
	)
	(arc
		(start 327.610724 -230.247952)
		(mid 327.791376 -230.450697)
		(end 327.856596 -230.714296)
		(width 0.0889)
		(layer "In4.Cu")
		(net "M_D_CPU0_SA_DQ<9>")
	)
	(arc
		(start 339.698076 -231.036622)
		(mid 339.945936 -230.961539)
		(end 340.20125 -231.005126)
		(width 0.0889)
		(layer "In4.Cu")
		(net "M_D_CPU0_SA_DQ<9>")
	)
	(arc
		(start 334.05826 -231.036622)
		(mid 334.341216 -230.960445)
		(end 334.624172 -231.036622)
		(width 0.0889)
		(layer "In4.Cu")
		(net "M_D_CPU0_SA_DQ<9>")
	)
	(arc
		(start 330.298044 -231.036622)
		(mid 330.581 -230.960445)
		(end 330.863956 -231.036622)
		(width 0.0889)
		(layer "In4.Cu")
		(net "M_D_CPU0_SA_DQ<9>")
	)
	(arc
		(start 330.863956 -231.036622)
		(mid 331.046207 -231.087006)
		(end 331.229716 -231.041448)
		(width 0.0889)
		(layer "In4.Cu")
		(net "M_D_CPU0_SA_DQ<9>")
	)
	(arc
		(start 327.278746 -229.57282)
		(mid 327.358778 -229.72992)
		(end 327.386442 -229.904036)
		(width 0.0889)
		(layer "In4.Cu")
		(net "M_D_CPU0_SA_DQ<9>")
	)
	(arc
		(start 332.178152 -231.036622)
		(mid 332.461108 -230.960445)
		(end 332.744064 -231.036622)
		(width 0.0889)
		(layer "In4.Cu")
		(net "M_D_CPU0_SA_DQ<9>")
	)
	(arc
		(start 331.238098 -231.036622)
		(mid 331.521054 -230.960445)
		(end 331.80401 -231.036622)
		(width 0.0889)
		(layer "In4.Cu")
		(net "M_D_CPU0_SA_DQ<9>")
	)
	(arc
		(start 327.856596 -230.714296)
		(mid 327.897562 -230.884702)
		(end 328.011536 -231.017826)
		(width 0.0889)
		(layer "In4.Cu")
		(net "M_D_CPU0_SA_DQ<9>")
	)
	(arc
		(start 333.118206 -231.036622)
		(mid 333.401162 -230.960445)
		(end 333.684118 -231.036622)
		(width 0.0889)
		(layer "In4.Cu")
		(net "M_D_CPU0_SA_DQ<9>")
	)
	(arc
		(start 336.878168 -231.036622)
		(mid 337.161124 -230.960445)
		(end 337.44408 -231.036622)
		(width 0.0889)
		(layer "In4.Cu")
		(net "M_D_CPU0_SA_DQ<9>")
	)
	(arc
		(start 339.323934 -231.036622)
		(mid 339.506185 -231.087006)
		(end 339.689694 -231.041448)
		(width 0.0889)
		(layer "In4.Cu")
		(net "M_D_CPU0_SA_DQ<9>")
	)
	(arc
		(start 329.924156 -231.036622)
		(mid 330.1111 -231.086911)
		(end 330.298044 -231.036622)
		(width 0.0889)
		(layer "In4.Cu")
		(net "M_D_CPU0_SA_DQ<9>")
	)
	(segment
		(start 339.508084 -230.169974)
		(end 339.040978 -229.904036)
		(width 0.10668)
		(layer "F.Cu")
		(net "M_D_CPU0_SA_DQ<8>")
	)
	(segment
		(start 304.933858 -207.061816)
		(end 304.933858 -207.322928)
		(width 0.14478)
		(layer "In4.Cu")
		(net "M_D_CPU0_SA_DQ<8>")
	)
	(segment
		(start 293.498778 -206.260192)
		(end 294.348662 -207.110076)
		(width 0.14478)
		(layer "In4.Cu")
		(net "M_D_CPU0_SA_DQ<8>")
	)
	(segment
		(start 302.728122 -207.27162)
		(end 302.728122 -207.322928)
		(width 0.14478)
		(layer "In4.Cu")
		(net "M_D_CPU0_SA_DQ<8>")
	)
	(segment
		(start 286.041592 -206.829152)
		(end 286.269938 -206.829152)
		(width 0.14478)
		(layer "In4.Cu")
		(net "M_D_CPU0_SA_DQ<8>")
	)
	(segment
		(start 304.772314 -206.900272)
		(end 304.933858 -207.061816)
		(width 0.14478)
		(layer "In4.Cu")
		(net "M_D_CPU0_SA_DQ<8>")
	)
	(segment
		(start 338.887054 -230.169466)
		(end 339.040978 -229.904036)
		(width 0.0889)
		(layer "In4.Cu")
		(net "M_D_CPU0_SA_DQ<8>")
	)
	(segment
		(start 303.992534 -207.484472)
		(end 304.22088 -207.484472)
		(width 0.14478)
		(layer "In4.Cu")
		(net "M_D_CPU0_SA_DQ<8>")
	)
	(segment
		(start 286.982916 -207.348328)
		(end 286.982916 -206.980536)
		(width 0.14478)
		(layer "In4.Cu")
		(net "M_D_CPU0_SA_DQ<8>")
	)
	(segment
		(start 304.543968 -206.900272)
		(end 304.772314 -206.900272)
		(width 0.14478)
		(layer "In4.Cu")
		(net "M_D_CPU0_SA_DQ<8>")
	)
	(segment
		(start 298.430696 -206.260192)
		(end 298.59224 -206.421736)
		(width 0.14478)
		(layer "In4.Cu")
		(net "M_D_CPU0_SA_DQ<8>")
	)
	(segment
		(start 296.345864 -207.348328)
		(end 296.507408 -207.509872)
		(width 0.14478)
		(layer "In4.Cu")
		(net "M_D_CPU0_SA_DQ<8>")
	)
	(segment
		(start 303.4411 -207.110076)
		(end 303.669446 -207.110076)
		(width 0.14478)
		(layer "In4.Cu")
		(net "M_D_CPU0_SA_DQ<8>")
	)
	(segment
		(start 304.382424 -207.322928)
		(end 304.382424 -207.061816)
		(width 0.14478)
		(layer "In4.Cu")
		(net "M_D_CPU0_SA_DQ<8>")
	)
	(segment
		(start 286.269938 -206.829152)
		(end 286.431482 -206.990696)
		(width 0.14478)
		(layer "In4.Cu")
		(net "M_D_CPU0_SA_DQ<8>")
	)
	(segment
		(start 289.499802 -207.110076)
		(end 289.823398 -207.110076)
		(width 0.14478)
		(layer "In4.Cu")
		(net "M_D_CPU0_SA_DQ<8>")
	)
	(segment
		(start 305.485292 -207.27162)
		(end 305.646836 -207.110076)
		(width 0.14478)
		(layer "In4.Cu")
		(net "M_D_CPU0_SA_DQ<8>")
	)
	(segment
		(start 299.143674 -206.489808)
		(end 299.143674 -206.421736)
		(width 0.14478)
		(layer "In4.Cu")
		(net "M_D_CPU0_SA_DQ<8>")
	)
	(segment
		(start 323.823838 -223.971612)
		(end 323.823838 -224.968054)
		(width 0.14478)
		(layer "In4.Cu")
		(net "M_D_CPU0_SA_DQ<8>")
	)
	(segment
		(start 288.948368 -207.413352)
		(end 289.196526 -207.413352)
		(width 0.14478)
		(layer "In4.Cu")
		(net "M_D_CPU0_SA_DQ<8>")
	)
	(segment
		(start 329.819762 -230.231442)
		(end 329.828144 -230.226616)
		(width 0.0889)
		(layer "In4.Cu")
		(net "M_D_CPU0_SA_DQ<8>")
	)
	(segment
		(start 296.345864 -207.27162)
		(end 296.345864 -207.348328)
		(width 0.14478)
		(layer "In4.Cu")
		(net "M_D_CPU0_SA_DQ<8>")
	)
	(segment
		(start 286.982916 -206.980536)
		(end 287.14446 -206.818992)
		(width 0.14478)
		(layer "In4.Cu")
		(net "M_D_CPU0_SA_DQ<8>")
	)
	(segment
		(start 289.196526 -207.413352)
		(end 289.499802 -207.110076)
		(width 0.14478)
		(layer "In4.Cu")
		(net "M_D_CPU0_SA_DQ<8>")
	)
	(segment
		(start 303.279556 -207.27162)
		(end 303.4411 -207.110076)
		(width 0.14478)
		(layer "In4.Cu")
		(net "M_D_CPU0_SA_DQ<8>")
	)
	(segment
		(start 299.305218 -206.260192)
		(end 301.174658 -206.260192)
		(width 0.14478)
		(layer "In4.Cu")
		(net "M_D_CPU0_SA_DQ<8>")
	)
	(segment
		(start 286.431482 -206.990696)
		(end 286.431482 -207.348328)
		(width 0.14478)
		(layer "In4.Cu")
		(net "M_D_CPU0_SA_DQ<8>")
	)
	(segment
		(start 303.83099 -207.27162)
		(end 303.83099 -207.322928)
		(width 0.14478)
		(layer "In4.Cu")
		(net "M_D_CPU0_SA_DQ<8>")
	)
	(segment
		(start 287.14446 -206.818992)
		(end 287.372806 -206.818992)
		(width 0.14478)
		(layer "In4.Cu")
		(net "M_D_CPU0_SA_DQ<8>")
	)
	(segment
		(start 328.011536 -229.397814)
		(end 328.044048 -229.41661)
		(width 0.0889)
		(layer "In4.Cu")
		(net "M_D_CPU0_SA_DQ<8>")
	)
	(segment
		(start 291.782246 -206.260192)
		(end 293.498778 -206.260192)
		(width 0.14478)
		(layer "In4.Cu")
		(net "M_D_CPU0_SA_DQ<8>")
	)
	(segment
		(start 298.59224 -206.421736)
		(end 298.59224 -206.489808)
		(width 0.14478)
		(layer "In4.Cu")
		(net "M_D_CPU0_SA_DQ<8>")
	)
	(segment
		(start 326.511158 -226.994212)
		(end 327.386442 -227.869496)
		(width 0.0889)
		(layer "In4.Cu")
		(net "M_D_CPU0_SA_DQ<8>")
	)
	(segment
		(start 287.372806 -206.818992)
		(end 287.66389 -207.110076)
		(width 0.14478)
		(layer "In4.Cu")
		(net "M_D_CPU0_SA_DQ<8>")
	)
	(segment
		(start 306.036726 -207.27162)
		(end 306.036726 -207.322928)
		(width 0.14478)
		(layer "In4.Cu")
		(net "M_D_CPU0_SA_DQ<8>")
	)
	(segment
		(start 306.749704 -207.110076)
		(end 307.763418 -207.110076)
		(width 0.14478)
		(layer "In4.Cu")
		(net "M_D_CPU0_SA_DQ<8>")
	)
	(segment
		(start 286.821372 -207.509872)
		(end 286.982916 -207.348328)
		(width 0.14478)
		(layer "In4.Cu")
		(net "M_D_CPU0_SA_DQ<8>")
	)
	(segment
		(start 305.875182 -207.110076)
		(end 306.036726 -207.27162)
		(width 0.14478)
		(layer "In4.Cu")
		(net "M_D_CPU0_SA_DQ<8>")
	)
	(segment
		(start 296.897298 -207.348328)
		(end 296.897298 -207.27162)
		(width 0.14478)
		(layer "In4.Cu")
		(net "M_D_CPU0_SA_DQ<8>")
	)
	(segment
		(start 335.094072 -230.226616)
		(end 335.102454 -230.231442)
		(width 0.0889)
		(layer "In4.Cu")
		(net "M_D_CPU0_SA_DQ<8>")
	)
	(segment
		(start 296.18432 -207.110076)
		(end 296.345864 -207.27162)
		(width 0.14478)
		(layer "In4.Cu")
		(net "M_D_CPU0_SA_DQ<8>")
	)
	(segment
		(start 302.566578 -207.110076)
		(end 302.728122 -207.27162)
		(width 0.14478)
		(layer "In4.Cu")
		(net "M_D_CPU0_SA_DQ<8>")
	)
	(segment
		(start 302.728122 -207.322928)
		(end 302.889666 -207.484472)
		(width 0.14478)
		(layer "In4.Cu")
		(net "M_D_CPU0_SA_DQ<8>")
	)
	(segment
		(start 298.196762 -206.260192)
		(end 298.430696 -206.260192)
		(width 0.14478)
		(layer "In4.Cu")
		(net "M_D_CPU0_SA_DQ<8>")
	)
	(segment
		(start 333.579724 -230.231442)
		(end 333.588106 -230.226616)
		(width 0.0889)
		(layer "In4.Cu")
		(net "M_D_CPU0_SA_DQ<8>")
	)
	(segment
		(start 331.33411 -230.226616)
		(end 331.342492 -230.231442)
		(width 0.0889)
		(layer "In4.Cu")
		(net "M_D_CPU0_SA_DQ<8>")
	)
	(segment
		(start 289.823398 -207.110076)
		(end 290.673282 -206.260192)
		(width 0.14478)
		(layer "In4.Cu")
		(net "M_D_CPU0_SA_DQ<8>")
	)
	(segment
		(start 303.118012 -207.484472)
		(end 303.279556 -207.322928)
		(width 0.14478)
		(layer "In4.Cu")
		(net "M_D_CPU0_SA_DQ<8>")
	)
	(segment
		(start 323.823838 -224.968054)
		(end 324.862444 -226.00666)
		(width 0.14478)
		(layer "In4.Cu")
		(net "M_D_CPU0_SA_DQ<8>")
	)
	(segment
		(start 334.519778 -230.231442)
		(end 334.52816 -230.226616)
		(width 0.0889)
		(layer "In4.Cu")
		(net "M_D_CPU0_SA_DQ<8>")
	)
	(segment
		(start 303.279556 -207.322928)
		(end 303.279556 -207.27162)
		(width 0.14478)
		(layer "In4.Cu")
		(net "M_D_CPU0_SA_DQ<8>")
	)
	(segment
		(start 302.024542 -207.110076)
		(end 302.566578 -207.110076)
		(width 0.14478)
		(layer "In4.Cu")
		(net "M_D_CPU0_SA_DQ<8>")
	)
	(segment
		(start 301.174658 -206.260192)
		(end 302.024542 -207.110076)
		(width 0.14478)
		(layer "In4.Cu")
		(net "M_D_CPU0_SA_DQ<8>")
	)
	(segment
		(start 305.095402 -207.484472)
		(end 305.323748 -207.484472)
		(width 0.14478)
		(layer "In4.Cu")
		(net "M_D_CPU0_SA_DQ<8>")
	)
	(segment
		(start 330.394056 -230.226616)
		(end 330.402438 -230.231442)
		(width 0.0889)
		(layer "In4.Cu")
		(net "M_D_CPU0_SA_DQ<8>")
	)
	(segment
		(start 324.862444 -226.00666)
		(end 325.849996 -226.994212)
		(width 0.0889)
		(layer "In4.Cu")
		(net "M_D_CPU0_SA_DQ<8>")
	)
	(segment
		(start 302.889666 -207.484472)
		(end 303.118012 -207.484472)
		(width 0.14478)
		(layer "In4.Cu")
		(net "M_D_CPU0_SA_DQ<8>")
	)
	(segment
		(start 327.386442 -227.869496)
		(end 327.386442 -228.284278)
		(width 0.0889)
		(layer "In4.Cu")
		(net "M_D_CPU0_SA_DQ<8>")
	)
	(segment
		(start 306.036726 -207.322928)
		(end 306.19827 -207.484472)
		(width 0.14478)
		(layer "In4.Cu")
		(net "M_D_CPU0_SA_DQ<8>")
	)
	(segment
		(start 284.736032 -206.685134)
		(end 285.160974 -207.110076)
		(width 0.14478)
		(layer "In4.Cu")
		(net "M_D_CPU0_SA_DQ<8>")
	)
	(segment
		(start 305.485292 -207.322928)
		(end 305.485292 -207.27162)
		(width 0.14478)
		(layer "In4.Cu")
		(net "M_D_CPU0_SA_DQ<8>")
	)
	(segment
		(start 297.058842 -207.110076)
		(end 297.346878 -207.110076)
		(width 0.14478)
		(layer "In4.Cu")
		(net "M_D_CPU0_SA_DQ<8>")
	)
	(segment
		(start 291.230812 -206.542132)
		(end 291.500306 -206.542132)
		(width 0.14478)
		(layer "In4.Cu")
		(net "M_D_CPU0_SA_DQ<8>")
	)
	(segment
		(start 306.426616 -207.484472)
		(end 306.58816 -207.322928)
		(width 0.14478)
		(layer "In4.Cu")
		(net "M_D_CPU0_SA_DQ<8>")
	)
	(segment
		(start 327.574148 -228.606858)
		(end 327.613264 -228.629718)
		(width 0.0889)
		(layer "In4.Cu")
		(net "M_D_CPU0_SA_DQ<8>")
	)
	(segment
		(start 304.933858 -207.322928)
		(end 305.095402 -207.484472)
		(width 0.14478)
		(layer "In4.Cu")
		(net "M_D_CPU0_SA_DQ<8>")
	)
	(segment
		(start 336.034126 -230.226616)
		(end 336.042508 -230.231442)
		(width 0.0889)
		(layer "In4.Cu")
		(net "M_D_CPU0_SA_DQ<8>")
	)
	(segment
		(start 338.791042 -230.194866)
		(end 338.887054 -230.169466)
		(width 0.0889)
		(layer "In4.Cu")
		(net "M_D_CPU0_SA_DQ<8>")
	)
	(segment
		(start 286.593026 -207.509872)
		(end 286.821372 -207.509872)
		(width 0.14478)
		(layer "In4.Cu")
		(net "M_D_CPU0_SA_DQ<8>")
	)
	(segment
		(start 298.98213 -206.651352)
		(end 299.143674 -206.489808)
		(width 0.14478)
		(layer "In4.Cu")
		(net "M_D_CPU0_SA_DQ<8>")
	)
	(segment
		(start 328.044048 -229.41661)
		(end 328.081132 -229.437946)
		(width 0.0889)
		(layer "In4.Cu")
		(net "M_D_CPU0_SA_DQ<8>")
	)
	(segment
		(start 299.143674 -206.421736)
		(end 299.305218 -206.260192)
		(width 0.14478)
		(layer "In4.Cu")
		(net "M_D_CPU0_SA_DQ<8>")
	)
	(segment
		(start 325.849996 -226.994212)
		(end 326.511158 -226.994212)
		(width 0.0889)
		(layer "In4.Cu")
		(net "M_D_CPU0_SA_DQ<8>")
	)
	(segment
		(start 296.897298 -207.27162)
		(end 297.058842 -207.110076)
		(width 0.14478)
		(layer "In4.Cu")
		(net "M_D_CPU0_SA_DQ<8>")
	)
	(segment
		(start 298.59224 -206.489808)
		(end 298.753784 -206.651352)
		(width 0.14478)
		(layer "In4.Cu")
		(net "M_D_CPU0_SA_DQ<8>")
	)
	(segment
		(start 286.431482 -207.348328)
		(end 286.593026 -207.509872)
		(width 0.14478)
		(layer "In4.Cu")
		(net "M_D_CPU0_SA_DQ<8>")
	)
	(segment
		(start 297.346878 -207.110076)
		(end 298.196762 -206.260192)
		(width 0.14478)
		(layer "In4.Cu")
		(net "M_D_CPU0_SA_DQ<8>")
	)
	(segment
		(start 287.66389 -207.110076)
		(end 288.645092 -207.110076)
		(width 0.14478)
		(layer "In4.Cu")
		(net "M_D_CPU0_SA_DQ<8>")
	)
	(segment
		(start 305.646836 -207.110076)
		(end 305.875182 -207.110076)
		(width 0.14478)
		(layer "In4.Cu")
		(net "M_D_CPU0_SA_DQ<8>")
	)
	(segment
		(start 338.27974 -230.231442)
		(end 338.288122 -230.226616)
		(width 0.0889)
		(layer "In4.Cu")
		(net "M_D_CPU0_SA_DQ<8>")
	)
	(segment
		(start 327.542398 -228.58857)
		(end 327.574148 -228.606858)
		(width 0.0889)
		(layer "In4.Cu")
		(net "M_D_CPU0_SA_DQ<8>")
	)
	(segment
		(start 328.482452 -230.208328)
		(end 328.514202 -230.226616)
		(width 0.0889)
		(layer "In4.Cu")
		(net "M_D_CPU0_SA_DQ<8>")
	)
	(segment
		(start 303.669446 -207.110076)
		(end 303.83099 -207.27162)
		(width 0.14478)
		(layer "In4.Cu")
		(net "M_D_CPU0_SA_DQ<8>")
	)
	(segment
		(start 304.382424 -207.061816)
		(end 304.543968 -206.900272)
		(width 0.14478)
		(layer "In4.Cu")
		(net "M_D_CPU0_SA_DQ<8>")
	)
	(segment
		(start 290.948872 -206.260192)
		(end 291.230812 -206.542132)
		(width 0.14478)
		(layer "In4.Cu")
		(net "M_D_CPU0_SA_DQ<8>")
	)
	(segment
		(start 291.500306 -206.542132)
		(end 291.782246 -206.260192)
		(width 0.14478)
		(layer "In4.Cu")
		(net "M_D_CPU0_SA_DQ<8>")
	)
	(segment
		(start 298.753784 -206.651352)
		(end 298.98213 -206.651352)
		(width 0.14478)
		(layer "In4.Cu")
		(net "M_D_CPU0_SA_DQ<8>")
	)
	(segment
		(start 303.83099 -207.322928)
		(end 303.992534 -207.484472)
		(width 0.14478)
		(layer "In4.Cu")
		(net "M_D_CPU0_SA_DQ<8>")
	)
	(segment
		(start 294.348662 -207.110076)
		(end 296.18432 -207.110076)
		(width 0.14478)
		(layer "In4.Cu")
		(net "M_D_CPU0_SA_DQ<8>")
	)
	(segment
		(start 285.760668 -207.110076)
		(end 286.041592 -206.829152)
		(width 0.14478)
		(layer "In4.Cu")
		(net "M_D_CPU0_SA_DQ<8>")
	)
	(segment
		(start 305.323748 -207.484472)
		(end 305.485292 -207.322928)
		(width 0.14478)
		(layer "In4.Cu")
		(net "M_D_CPU0_SA_DQ<8>")
	)
	(segment
		(start 321.850258 -221.998032)
		(end 323.823838 -223.971612)
		(width 0.14478)
		(layer "In4.Cu")
		(net "M_D_CPU0_SA_DQ<8>")
	)
	(segment
		(start 288.645092 -207.110076)
		(end 288.948368 -207.413352)
		(width 0.14478)
		(layer "In4.Cu")
		(net "M_D_CPU0_SA_DQ<8>")
	)
	(segment
		(start 306.58816 -207.27162)
		(end 306.749704 -207.110076)
		(width 0.14478)
		(layer "In4.Cu")
		(net "M_D_CPU0_SA_DQ<8>")
	)
	(segment
		(start 285.160974 -207.110076)
		(end 285.760668 -207.110076)
		(width 0.14478)
		(layer "In4.Cu")
		(net "M_D_CPU0_SA_DQ<8>")
	)
	(segment
		(start 296.735754 -207.509872)
		(end 296.897298 -207.348328)
		(width 0.14478)
		(layer "In4.Cu")
		(net "M_D_CPU0_SA_DQ<8>")
	)
	(segment
		(start 306.19827 -207.484472)
		(end 306.426616 -207.484472)
		(width 0.14478)
		(layer "In4.Cu")
		(net "M_D_CPU0_SA_DQ<8>")
	)
	(segment
		(start 304.22088 -207.484472)
		(end 304.382424 -207.322928)
		(width 0.14478)
		(layer "In4.Cu")
		(net "M_D_CPU0_SA_DQ<8>")
	)
	(segment
		(start 290.673282 -206.260192)
		(end 290.948872 -206.260192)
		(width 0.14478)
		(layer "In4.Cu")
		(net "M_D_CPU0_SA_DQ<8>")
	)
	(segment
		(start 296.507408 -207.509872)
		(end 296.735754 -207.509872)
		(width 0.14478)
		(layer "In4.Cu")
		(net "M_D_CPU0_SA_DQ<8>")
	)
	(segment
		(start 328.081132 -229.437946)
		(end 328.083164 -229.43947)
		(width 0.0889)
		(layer "In4.Cu")
		(net "M_D_CPU0_SA_DQ<8>")
	)
	(segment
		(start 307.763418 -207.110076)
		(end 321.850258 -221.196916)
		(width 0.14478)
		(layer "In4.Cu")
		(net "M_D_CPU0_SA_DQ<8>")
	)
	(segment
		(start 321.850258 -221.196916)
		(end 321.850258 -221.998032)
		(width 0.14478)
		(layer "In4.Cu")
		(net "M_D_CPU0_SA_DQ<8>")
	)
	(segment
		(start 306.58816 -207.322928)
		(end 306.58816 -207.27162)
		(width 0.14478)
		(layer "In4.Cu")
		(net "M_D_CPU0_SA_DQ<8>")
	)
	(arc
		(start 332.648052 -230.226616)
		(mid 332.931008 -230.150473)
		(end 333.213964 -230.226616)
		(width 0.0889)
		(layer "In4.Cu")
		(net "M_D_CPU0_SA_DQ<8>")
	)
	(arc
		(start 327.386442 -228.284278)
		(mid 327.427697 -228.455249)
		(end 327.542398 -228.58857)
		(width 0.0889)
		(layer "In4.Cu")
		(net "M_D_CPU0_SA_DQ<8>")
	)
	(arc
		(start 329.828144 -230.226616)
		(mid 330.1111 -230.150473)
		(end 330.394056 -230.226616)
		(width 0.0889)
		(layer "In4.Cu")
		(net "M_D_CPU0_SA_DQ<8>")
	)
	(arc
		(start 334.154018 -230.226616)
		(mid 334.336269 -230.276966)
		(end 334.519778 -230.231442)
		(width 0.0889)
		(layer "In4.Cu")
		(net "M_D_CPU0_SA_DQ<8>")
	)
	(arc
		(start 337.348068 -230.226616)
		(mid 337.631024 -230.150473)
		(end 337.91398 -230.226616)
		(width 0.0889)
		(layer "In4.Cu")
		(net "M_D_CPU0_SA_DQ<8>")
	)
	(arc
		(start 328.326496 -229.904036)
		(mid 328.367751 -230.075007)
		(end 328.482452 -230.208328)
		(width 0.0889)
		(layer "In4.Cu")
		(net "M_D_CPU0_SA_DQ<8>")
	)
	(arc
		(start 336.97418 -230.226616)
		(mid 337.161124 -230.276871)
		(end 337.348068 -230.226616)
		(width 0.0889)
		(layer "In4.Cu")
		(net "M_D_CPU0_SA_DQ<8>")
	)
	(arc
		(start 336.408268 -230.226616)
		(mid 336.691224 -230.150473)
		(end 336.97418 -230.226616)
		(width 0.0889)
		(layer "In4.Cu")
		(net "M_D_CPU0_SA_DQ<8>")
	)
	(arc
		(start 328.88809 -230.226616)
		(mid 329.171046 -230.150473)
		(end 329.454002 -230.226616)
		(width 0.0889)
		(layer "In4.Cu")
		(net "M_D_CPU0_SA_DQ<8>")
	)
	(arc
		(start 328.083164 -229.43947)
		(mid 328.261977 -229.64182)
		(end 328.326496 -229.904036)
		(width 0.0889)
		(layer "In4.Cu")
		(net "M_D_CPU0_SA_DQ<8>")
	)
	(arc
		(start 333.213964 -230.226616)
		(mid 333.396215 -230.276966)
		(end 333.579724 -230.231442)
		(width 0.0889)
		(layer "In4.Cu")
		(net "M_D_CPU0_SA_DQ<8>")
	)
	(arc
		(start 334.52816 -230.226616)
		(mid 334.811116 -230.150473)
		(end 335.094072 -230.226616)
		(width 0.0889)
		(layer "In4.Cu")
		(net "M_D_CPU0_SA_DQ<8>")
	)
	(arc
		(start 329.454002 -230.226616)
		(mid 329.636253 -230.276966)
		(end 329.819762 -230.231442)
		(width 0.0889)
		(layer "In4.Cu")
		(net "M_D_CPU0_SA_DQ<8>")
	)
	(arc
		(start 338.288122 -230.226616)
		(mid 338.535835 -230.15143)
		(end 338.791042 -230.194866)
		(width 0.0889)
		(layer "In4.Cu")
		(net "M_D_CPU0_SA_DQ<8>")
	)
	(arc
		(start 330.768198 -230.226616)
		(mid 331.051154 -230.150473)
		(end 331.33411 -230.226616)
		(width 0.0889)
		(layer "In4.Cu")
		(net "M_D_CPU0_SA_DQ<8>")
	)
	(arc
		(start 335.468214 -230.226616)
		(mid 335.75117 -230.150473)
		(end 336.034126 -230.226616)
		(width 0.0889)
		(layer "In4.Cu")
		(net "M_D_CPU0_SA_DQ<8>")
	)
	(arc
		(start 335.102454 -230.231442)
		(mid 335.285962 -230.276936)
		(end 335.468214 -230.226616)
		(width 0.0889)
		(layer "In4.Cu")
		(net "M_D_CPU0_SA_DQ<8>")
	)
	(arc
		(start 327.856596 -229.094284)
		(mid 327.897562 -229.26469)
		(end 328.011536 -229.397814)
		(width 0.0889)
		(layer "In4.Cu")
		(net "M_D_CPU0_SA_DQ<8>")
	)
	(arc
		(start 327.613264 -228.629718)
		(mid 327.792077 -228.832068)
		(end 327.856596 -229.094284)
		(width 0.0889)
		(layer "In4.Cu")
		(net "M_D_CPU0_SA_DQ<8>")
	)
	(arc
		(start 336.042508 -230.231442)
		(mid 336.226016 -230.276936)
		(end 336.408268 -230.226616)
		(width 0.0889)
		(layer "In4.Cu")
		(net "M_D_CPU0_SA_DQ<8>")
	)
	(arc
		(start 337.91398 -230.226616)
		(mid 338.096231 -230.276966)
		(end 338.27974 -230.231442)
		(width 0.0889)
		(layer "In4.Cu")
		(net "M_D_CPU0_SA_DQ<8>")
	)
	(arc
		(start 333.588106 -230.226616)
		(mid 333.871062 -230.150473)
		(end 334.154018 -230.226616)
		(width 0.0889)
		(layer "In4.Cu")
		(net "M_D_CPU0_SA_DQ<8>")
	)
	(arc
		(start 330.402438 -230.231442)
		(mid 330.585946 -230.276936)
		(end 330.768198 -230.226616)
		(width 0.0889)
		(layer "In4.Cu")
		(net "M_D_CPU0_SA_DQ<8>")
	)
	(arc
		(start 331.342492 -230.231442)
		(mid 331.526 -230.276936)
		(end 331.708252 -230.226616)
		(width 0.0889)
		(layer "In4.Cu")
		(net "M_D_CPU0_SA_DQ<8>")
	)
	(arc
		(start 332.274164 -230.226616)
		(mid 332.461108 -230.276871)
		(end 332.648052 -230.226616)
		(width 0.0889)
		(layer "In4.Cu")
		(net "M_D_CPU0_SA_DQ<8>")
	)
	(arc
		(start 328.514202 -230.226616)
		(mid 328.701146 -230.276871)
		(end 328.88809 -230.226616)
		(width 0.0889)
		(layer "In4.Cu")
		(net "M_D_CPU0_SA_DQ<8>")
	)
	(arc
		(start 331.708252 -230.226616)
		(mid 331.991208 -230.150473)
		(end 332.274164 -230.226616)
		(width 0.0889)
		(layer "In4.Cu")
		(net "M_D_CPU0_SA_DQ<8>")
	)
	(segment
		(start 340.447884 -230.169974)
		(end 339.981032 -229.904036)
		(width 0.10668)
		(layer "F.Cu")
		(net "M_D_CPU0_SA_DQ<7>")
	)
	(segment
		(start 283.11475 -205.627732)
		(end 283.387292 -205.627732)
		(width 0.14478)
		(layer "In4.Cu")
		(net "M_D_CPU0_SA_DQ<7>")
	)
	(segment
		(start 282.729178 -206.260192)
		(end 282.921964 -206.067406)
		(width 0.14478)
		(layer "In4.Cu")
		(net "M_D_CPU0_SA_DQ<7>")
	)
	(segment
		(start 280.635964 -205.834996)
		(end 281.06116 -206.260192)
		(width 0.14478)
		(layer "In4.Cu")
		(net "M_D_CPU0_SA_DQ<7>")
	)
	(segment
		(start 283.580078 -205.820518)
		(end 283.580078 -206.067406)
		(width 0.14478)
		(layer "In4.Cu")
		(net "M_D_CPU0_SA_DQ<7>")
	)
	(segment
		(start 333.579724 -229.576884)
		(end 333.588106 -229.58171)
		(width 0.0889)
		(layer "In4.Cu")
		(net "M_D_CPU0_SA_DQ<7>")
	)
	(segment
		(start 339.794088 -229.58171)
		(end 339.80247 -229.576884)
		(width 0.0889)
		(layer "In4.Cu")
		(net "M_D_CPU0_SA_DQ<7>")
	)
	(segment
		(start 323.504814 -222.071946)
		(end 323.504814 -222.85071)
		(width 0.14478)
		(layer "In4.Cu")
		(net "M_D_CPU0_SA_DQ<7>")
	)
	(segment
		(start 324.904354 -224.25025)
		(end 324.904354 -224.414588)
		(width 0.14478)
		(layer "In4.Cu")
		(net "M_D_CPU0_SA_DQ<7>")
	)
	(segment
		(start 325.467218 -224.977452)
		(end 325.72579 -225.236024)
		(width 0.0889)
		(layer "In4.Cu")
		(net "M_D_CPU0_SA_DQ<7>")
	)
	(segment
		(start 328.41819 -228.771704)
		(end 328.44994 -228.789992)
		(width 0.0889)
		(layer "In4.Cu")
		(net "M_D_CPU0_SA_DQ<7>")
	)
	(segment
		(start 282.921964 -206.067406)
		(end 282.921964 -205.820518)
		(width 0.14478)
		(layer "In4.Cu")
		(net "M_D_CPU0_SA_DQ<7>")
	)
	(segment
		(start 290.674298 -205.410054)
		(end 293.507668 -205.410054)
		(width 0.14478)
		(layer "In4.Cu")
		(net "M_D_CPU0_SA_DQ<7>")
	)
	(segment
		(start 283.387292 -205.627732)
		(end 283.580078 -205.820518)
		(width 0.14478)
		(layer "In4.Cu")
		(net "M_D_CPU0_SA_DQ<7>")
	)
	(segment
		(start 325.991982 -225.992436)
		(end 327.658984 -227.659438)
		(width 0.0889)
		(layer "In4.Cu")
		(net "M_D_CPU0_SA_DQ<7>")
	)
	(segment
		(start 283.772864 -206.260192)
		(end 289.82416 -206.260192)
		(width 0.14478)
		(layer "In4.Cu")
		(net "M_D_CPU0_SA_DQ<7>")
	)
	(segment
		(start 331.33411 -229.58171)
		(end 331.342492 -229.576884)
		(width 0.0889)
		(layer "In4.Cu")
		(net "M_D_CPU0_SA_DQ<7>")
	)
	(segment
		(start 327.911968 -227.940616)
		(end 327.97877 -227.979478)
		(width 0.0889)
		(layer "In4.Cu")
		(net "M_D_CPU0_SA_DQ<7>")
	)
	(segment
		(start 340.113112 -229.555548)
		(end 340.13521 -229.638606)
		(width 0.0889)
		(layer "In4.Cu")
		(net "M_D_CPU0_SA_DQ<7>")
	)
	(segment
		(start 283.580078 -206.067406)
		(end 283.772864 -206.260192)
		(width 0.14478)
		(layer "In4.Cu")
		(net "M_D_CPU0_SA_DQ<7>")
	)
	(segment
		(start 301.196502 -205.410054)
		(end 302.04664 -206.260192)
		(width 0.14478)
		(layer "In4.Cu")
		(net "M_D_CPU0_SA_DQ<7>")
	)
	(segment
		(start 334.519778 -229.576884)
		(end 334.52816 -229.58171)
		(width 0.0889)
		(layer "In4.Cu")
		(net "M_D_CPU0_SA_DQ<7>")
	)
	(segment
		(start 307.69306 -206.260192)
		(end 323.504814 -222.071946)
		(width 0.14478)
		(layer "In4.Cu")
		(net "M_D_CPU0_SA_DQ<7>")
	)
	(segment
		(start 323.504814 -222.85071)
		(end 324.904354 -224.25025)
		(width 0.14478)
		(layer "In4.Cu")
		(net "M_D_CPU0_SA_DQ<7>")
	)
	(segment
		(start 282.456636 -206.260192)
		(end 282.729178 -206.260192)
		(width 0.14478)
		(layer "In4.Cu")
		(net "M_D_CPU0_SA_DQ<7>")
	)
	(segment
		(start 289.82416 -206.260192)
		(end 290.674298 -205.410054)
		(width 0.14478)
		(layer "In4.Cu")
		(net "M_D_CPU0_SA_DQ<7>")
	)
	(segment
		(start 293.507668 -205.410054)
		(end 294.357806 -206.260192)
		(width 0.14478)
		(layer "In4.Cu")
		(net "M_D_CPU0_SA_DQ<7>")
	)
	(segment
		(start 329.819762 -229.576884)
		(end 329.828144 -229.58171)
		(width 0.0889)
		(layer "In4.Cu")
		(net "M_D_CPU0_SA_DQ<7>")
	)
	(segment
		(start 330.394056 -229.58171)
		(end 330.402438 -229.576884)
		(width 0.0889)
		(layer "In4.Cu")
		(net "M_D_CPU0_SA_DQ<7>")
	)
	(segment
		(start 338.854034 -229.58171)
		(end 338.862416 -229.576884)
		(width 0.0889)
		(layer "In4.Cu")
		(net "M_D_CPU0_SA_DQ<7>")
	)
	(segment
		(start 325.830438 -225.4885)
		(end 325.830438 -225.602292)
		(width 0.0889)
		(layer "In4.Cu")
		(net "M_D_CPU0_SA_DQ<7>")
	)
	(segment
		(start 336.034126 -229.58171)
		(end 336.042508 -229.576884)
		(width 0.0889)
		(layer "In4.Cu")
		(net "M_D_CPU0_SA_DQ<7>")
	)
	(segment
		(start 298.162472 -205.410054)
		(end 301.196502 -205.410054)
		(width 0.14478)
		(layer "In4.Cu")
		(net "M_D_CPU0_SA_DQ<7>")
	)
	(segment
		(start 281.798522 -205.41615)
		(end 282.071064 -205.41615)
		(width 0.14478)
		(layer "In4.Cu")
		(net "M_D_CPU0_SA_DQ<7>")
	)
	(segment
		(start 281.06116 -206.260192)
		(end 281.41295 -206.260192)
		(width 0.14478)
		(layer "In4.Cu")
		(net "M_D_CPU0_SA_DQ<7>")
	)
	(segment
		(start 335.094072 -229.58171)
		(end 335.102454 -229.576884)
		(width 0.0889)
		(layer "In4.Cu")
		(net "M_D_CPU0_SA_DQ<7>")
	)
	(segment
		(start 281.605736 -206.067406)
		(end 281.605736 -205.608936)
		(width 0.14478)
		(layer "In4.Cu")
		(net "M_D_CPU0_SA_DQ<7>")
	)
	(segment
		(start 294.357806 -206.260192)
		(end 297.312334 -206.260192)
		(width 0.14478)
		(layer "In4.Cu")
		(net "M_D_CPU0_SA_DQ<7>")
	)
	(segment
		(start 328.379074 -228.748844)
		(end 328.41819 -228.771704)
		(width 0.0889)
		(layer "In4.Cu")
		(net "M_D_CPU0_SA_DQ<7>")
	)
	(segment
		(start 328.851768 -229.560628)
		(end 328.88809 -229.58171)
		(width 0.0889)
		(layer "In4.Cu")
		(net "M_D_CPU0_SA_DQ<7>")
	)
	(segment
		(start 302.04664 -206.260192)
		(end 307.69306 -206.260192)
		(width 0.14478)
		(layer "In4.Cu")
		(net "M_D_CPU0_SA_DQ<7>")
	)
	(segment
		(start 282.921964 -205.820518)
		(end 283.11475 -205.627732)
		(width 0.14478)
		(layer "In4.Cu")
		(net "M_D_CPU0_SA_DQ<7>")
	)
	(segment
		(start 282.071064 -205.41615)
		(end 282.26385 -205.608936)
		(width 0.14478)
		(layer "In4.Cu")
		(net "M_D_CPU0_SA_DQ<7>")
	)
	(segment
		(start 282.26385 -206.067406)
		(end 282.456636 -206.260192)
		(width 0.14478)
		(layer "In4.Cu")
		(net "M_D_CPU0_SA_DQ<7>")
	)
	(segment
		(start 338.27974 -229.576884)
		(end 338.288122 -229.58171)
		(width 0.0889)
		(layer "In4.Cu")
		(net "M_D_CPU0_SA_DQ<7>")
	)
	(segment
		(start 340.13521 -229.638606)
		(end 339.981032 -229.904036)
		(width 0.0889)
		(layer "In4.Cu")
		(net "M_D_CPU0_SA_DQ<7>")
	)
	(segment
		(start 281.41295 -206.260192)
		(end 281.605736 -206.067406)
		(width 0.14478)
		(layer "In4.Cu")
		(net "M_D_CPU0_SA_DQ<7>")
	)
	(segment
		(start 281.605736 -205.608936)
		(end 281.798522 -205.41615)
		(width 0.14478)
		(layer "In4.Cu")
		(net "M_D_CPU0_SA_DQ<7>")
	)
	(segment
		(start 297.312334 -206.260192)
		(end 298.162472 -205.410054)
		(width 0.14478)
		(layer "In4.Cu")
		(net "M_D_CPU0_SA_DQ<7>")
	)
	(segment
		(start 282.26385 -205.608936)
		(end 282.26385 -206.067406)
		(width 0.14478)
		(layer "In4.Cu")
		(net "M_D_CPU0_SA_DQ<7>")
	)
	(segment
		(start 324.904354 -224.414588)
		(end 325.467218 -224.977452)
		(width 0.14478)
		(layer "In4.Cu")
		(net "M_D_CPU0_SA_DQ<7>")
	)
	(arc
		(start 338.288122 -229.58171)
		(mid 338.571078 -229.657887)
		(end 338.854034 -229.58171)
		(width 0.0889)
		(layer "In4.Cu")
		(net "M_D_CPU0_SA_DQ<7>")
	)
	(arc
		(start 333.588106 -229.58171)
		(mid 333.871062 -229.657887)
		(end 334.154018 -229.58171)
		(width 0.0889)
		(layer "In4.Cu")
		(net "M_D_CPU0_SA_DQ<7>")
	)
	(arc
		(start 329.828144 -229.58171)
		(mid 330.1111 -229.657887)
		(end 330.394056 -229.58171)
		(width 0.0889)
		(layer "In4.Cu")
		(net "M_D_CPU0_SA_DQ<7>")
	)
	(arc
		(start 339.80247 -229.576884)
		(mid 339.955458 -229.532204)
		(end 340.113112 -229.555548)
		(width 0.0889)
		(layer "In4.Cu")
		(net "M_D_CPU0_SA_DQ<7>")
	)
	(arc
		(start 327.97877 -227.979478)
		(mid 328.094197 -228.112854)
		(end 328.135742 -228.284278)
		(width 0.0889)
		(layer "In4.Cu")
		(net "M_D_CPU0_SA_DQ<7>")
	)
	(arc
		(start 337.348068 -229.58171)
		(mid 337.631024 -229.657887)
		(end 337.91398 -229.58171)
		(width 0.0889)
		(layer "In4.Cu")
		(net "M_D_CPU0_SA_DQ<7>")
	)
	(arc
		(start 331.342492 -229.576884)
		(mid 331.526 -229.531359)
		(end 331.708252 -229.58171)
		(width 0.0889)
		(layer "In4.Cu")
		(net "M_D_CPU0_SA_DQ<7>")
	)
	(arc
		(start 337.91398 -229.58171)
		(mid 338.096231 -229.531326)
		(end 338.27974 -229.576884)
		(width 0.0889)
		(layer "In4.Cu")
		(net "M_D_CPU0_SA_DQ<7>")
	)
	(arc
		(start 331.708252 -229.58171)
		(mid 331.991208 -229.657887)
		(end 332.274164 -229.58171)
		(width 0.0889)
		(layer "In4.Cu")
		(net "M_D_CPU0_SA_DQ<7>")
	)
	(arc
		(start 328.605896 -229.094284)
		(mid 328.671132 -229.357875)
		(end 328.851768 -229.560628)
		(width 0.0889)
		(layer "In4.Cu")
		(net "M_D_CPU0_SA_DQ<7>")
	)
	(arc
		(start 330.768198 -229.58171)
		(mid 331.051154 -229.657887)
		(end 331.33411 -229.58171)
		(width 0.0889)
		(layer "In4.Cu")
		(net "M_D_CPU0_SA_DQ<7>")
	)
	(arc
		(start 336.97418 -229.58171)
		(mid 337.161124 -229.531421)
		(end 337.348068 -229.58171)
		(width 0.0889)
		(layer "In4.Cu")
		(net "M_D_CPU0_SA_DQ<7>")
	)
	(arc
		(start 336.042508 -229.576884)
		(mid 336.226016 -229.531359)
		(end 336.408268 -229.58171)
		(width 0.0889)
		(layer "In4.Cu")
		(net "M_D_CPU0_SA_DQ<7>")
	)
	(arc
		(start 339.228176 -229.58171)
		(mid 339.511132 -229.657887)
		(end 339.794088 -229.58171)
		(width 0.0889)
		(layer "In4.Cu")
		(net "M_D_CPU0_SA_DQ<7>")
	)
	(arc
		(start 327.658984 -227.659438)
		(mid 327.710354 -227.716651)
		(end 327.75525 -227.779072)
		(width 0.0889)
		(layer "In4.Cu")
		(net "M_D_CPU0_SA_DQ<7>")
	)
	(arc
		(start 329.454002 -229.58171)
		(mid 329.636253 -229.531326)
		(end 329.819762 -229.576884)
		(width 0.0889)
		(layer "In4.Cu")
		(net "M_D_CPU0_SA_DQ<7>")
	)
	(arc
		(start 328.135742 -228.284278)
		(mid 328.200257 -228.546497)
		(end 328.379074 -228.748844)
		(width 0.0889)
		(layer "In4.Cu")
		(net "M_D_CPU0_SA_DQ<7>")
	)
	(arc
		(start 334.52816 -229.58171)
		(mid 334.811116 -229.657887)
		(end 335.094072 -229.58171)
		(width 0.0889)
		(layer "In4.Cu")
		(net "M_D_CPU0_SA_DQ<7>")
	)
	(arc
		(start 332.648052 -229.58171)
		(mid 332.931008 -229.657887)
		(end 333.213964 -229.58171)
		(width 0.0889)
		(layer "In4.Cu")
		(net "M_D_CPU0_SA_DQ<7>")
	)
	(arc
		(start 336.408268 -229.58171)
		(mid 336.691224 -229.657887)
		(end 336.97418 -229.58171)
		(width 0.0889)
		(layer "In4.Cu")
		(net "M_D_CPU0_SA_DQ<7>")
	)
	(arc
		(start 335.468214 -229.58171)
		(mid 335.75117 -229.657887)
		(end 336.034126 -229.58171)
		(width 0.0889)
		(layer "In4.Cu")
		(net "M_D_CPU0_SA_DQ<7>")
	)
	(arc
		(start 328.44994 -228.789992)
		(mid 328.564616 -228.923326)
		(end 328.605896 -229.094284)
		(width 0.0889)
		(layer "In4.Cu")
		(net "M_D_CPU0_SA_DQ<7>")
	)
	(arc
		(start 328.88809 -229.58171)
		(mid 329.171046 -229.657887)
		(end 329.454002 -229.58171)
		(width 0.0889)
		(layer "In4.Cu")
		(net "M_D_CPU0_SA_DQ<7>")
	)
	(arc
		(start 334.154018 -229.58171)
		(mid 334.336269 -229.531326)
		(end 334.519778 -229.576884)
		(width 0.0889)
		(layer "In4.Cu")
		(net "M_D_CPU0_SA_DQ<7>")
	)
	(arc
		(start 330.402438 -229.576884)
		(mid 330.585946 -229.531359)
		(end 330.768198 -229.58171)
		(width 0.0889)
		(layer "In4.Cu")
		(net "M_D_CPU0_SA_DQ<7>")
	)
	(arc
		(start 333.213964 -229.58171)
		(mid 333.396215 -229.531326)
		(end 333.579724 -229.576884)
		(width 0.0889)
		(layer "In4.Cu")
		(net "M_D_CPU0_SA_DQ<7>")
	)
	(arc
		(start 325.72579 -225.236024)
		(mid 325.803244 -225.351847)
		(end 325.830438 -225.4885)
		(width 0.0889)
		(layer "In4.Cu")
		(net "M_D_CPU0_SA_DQ<7>")
	)
	(arc
		(start 327.75525 -227.779072)
		(mid 327.825469 -227.867744)
		(end 327.911968 -227.940616)
		(width 0.0889)
		(layer "In4.Cu")
		(net "M_D_CPU0_SA_DQ<7>")
	)
	(arc
		(start 335.102454 -229.576884)
		(mid 335.285962 -229.531359)
		(end 335.468214 -229.58171)
		(width 0.0889)
		(layer "In4.Cu")
		(net "M_D_CPU0_SA_DQ<7>")
	)
	(arc
		(start 332.274164 -229.58171)
		(mid 332.461108 -229.531421)
		(end 332.648052 -229.58171)
		(width 0.0889)
		(layer "In4.Cu")
		(net "M_D_CPU0_SA_DQ<7>")
	)
	(arc
		(start 325.830438 -225.602292)
		(mid 325.872418 -225.813428)
		(end 325.991982 -225.992436)
		(width 0.0889)
		(layer "In4.Cu")
		(net "M_D_CPU0_SA_DQ<7>")
	)
	(arc
		(start 338.862416 -229.576884)
		(mid 339.045924 -229.531359)
		(end 339.228176 -229.58171)
		(width 0.0889)
		(layer "In4.Cu")
		(net "M_D_CPU0_SA_DQ<7>")
	)
	(segment
		(start 339.03793 -229.360222)
		(end 338.571078 -229.094284)
		(width 0.10668)
		(layer "F.Cu")
		(net "M_D_CPU0_SA_DQ<6>")
	)
	(segment
		(start 298.162472 -203.710032)
		(end 301.196502 -203.710032)
		(width 0.14478)
		(layer "In4.Cu")
		(net "M_D_CPU0_SA_DQ<6>")
	)
	(segment
		(start 332.16977 -228.766878)
		(end 332.178152 -228.771704)
		(width 0.0889)
		(layer "In4.Cu")
		(net "M_D_CPU0_SA_DQ<6>")
	)
	(segment
		(start 335.929732 -228.766878)
		(end 335.938114 -228.771704)
		(width 0.0889)
		(layer "In4.Cu")
		(net "M_D_CPU0_SA_DQ<6>")
	)
	(segment
		(start 284.004766 -204.397102)
		(end 284.167834 -204.56017)
		(width 0.14478)
		(layer "In4.Cu")
		(net "M_D_CPU0_SA_DQ<6>")
	)
	(segment
		(start 327.438004 -225.508058)
		(end 327.47839 -225.53168)
		(width 0.0889)
		(layer "In4.Cu")
		(net "M_D_CPU0_SA_DQ<6>")
	)
	(segment
		(start 289.82416 -204.56017)
		(end 290.674298 -203.710032)
		(width 0.14478)
		(layer "In4.Cu")
		(net "M_D_CPU0_SA_DQ<6>")
	)
	(segment
		(start 282.172156 -204.56017)
		(end 282.335224 -204.397102)
		(width 0.14478)
		(layer "In4.Cu")
		(net "M_D_CPU0_SA_DQ<6>")
	)
	(segment
		(start 301.196502 -203.710032)
		(end 302.04664 -204.56017)
		(width 0.14478)
		(layer "In4.Cu")
		(net "M_D_CPU0_SA_DQ<6>")
	)
	(segment
		(start 327.911968 -226.320604)
		(end 327.94829 -226.341686)
		(width 0.0889)
		(layer "In4.Cu")
		(net "M_D_CPU0_SA_DQ<6>")
	)
	(segment
		(start 283.285184 -204.56017)
		(end 283.448252 -204.397102)
		(width 0.14478)
		(layer "In4.Cu")
		(net "M_D_CPU0_SA_DQ<6>")
	)
	(segment
		(start 297.312334 -204.56017)
		(end 298.162472 -203.710032)
		(width 0.14478)
		(layer "In4.Cu")
		(net "M_D_CPU0_SA_DQ<6>")
	)
	(segment
		(start 332.744064 -228.771704)
		(end 332.752446 -228.766878)
		(width 0.0889)
		(layer "In4.Cu")
		(net "M_D_CPU0_SA_DQ<6>")
	)
	(segment
		(start 284.167834 -204.56017)
		(end 289.82416 -204.56017)
		(width 0.14478)
		(layer "In4.Cu")
		(net "M_D_CPU0_SA_DQ<6>")
	)
	(segment
		(start 329.319128 -228.748844)
		(end 329.358244 -228.771704)
		(width 0.0889)
		(layer "In4.Cu")
		(net "M_D_CPU0_SA_DQ<6>")
	)
	(segment
		(start 284.004766 -203.85532)
		(end 284.004766 -204.397102)
		(width 0.14478)
		(layer "In4.Cu")
		(net "M_D_CPU0_SA_DQ<6>")
	)
	(segment
		(start 327.00849 -224.721674)
		(end 327.037954 -224.738692)
		(width 0.0889)
		(layer "In4.Cu")
		(net "M_D_CPU0_SA_DQ<6>")
	)
	(segment
		(start 283.61132 -203.692252)
		(end 283.841698 -203.692252)
		(width 0.14478)
		(layer "In4.Cu")
		(net "M_D_CPU0_SA_DQ<6>")
	)
	(segment
		(start 337.44408 -228.771704)
		(end 337.452462 -228.766878)
		(width 0.0889)
		(layer "In4.Cu")
		(net "M_D_CPU0_SA_DQ<6>")
	)
	(segment
		(start 294.357806 -204.56017)
		(end 297.312334 -204.56017)
		(width 0.14478)
		(layer "In4.Cu")
		(net "M_D_CPU0_SA_DQ<6>")
	)
	(segment
		(start 283.841698 -203.692252)
		(end 284.004766 -203.85532)
		(width 0.14478)
		(layer "In4.Cu")
		(net "M_D_CPU0_SA_DQ<6>")
	)
	(segment
		(start 327.47839 -225.53168)
		(end 327.51014 -225.549968)
		(width 0.0889)
		(layer "In4.Cu")
		(net "M_D_CPU0_SA_DQ<6>")
	)
	(segment
		(start 326.504808 -223.892364)
		(end 326.571864 -223.931226)
		(width 0.0889)
		(layer "In4.Cu")
		(net "M_D_CPU0_SA_DQ<6>")
	)
	(segment
		(start 282.72867 -203.58735)
		(end 282.891738 -203.750418)
		(width 0.14478)
		(layer "In4.Cu")
		(net "M_D_CPU0_SA_DQ<6>")
	)
	(segment
		(start 326.968104 -224.698052)
		(end 327.00849 -224.721674)
		(width 0.0889)
		(layer "In4.Cu")
		(net "M_D_CPU0_SA_DQ<6>")
	)
	(segment
		(start 324.447154 -221.690438)
		(end 324.447154 -222.44685)
		(width 0.14478)
		(layer "In4.Cu")
		(net "M_D_CPU0_SA_DQ<6>")
	)
	(segment
		(start 328.88809 -227.961698)
		(end 328.91984 -227.979986)
		(width 0.0889)
		(layer "In4.Cu")
		(net "M_D_CPU0_SA_DQ<6>")
	)
	(segment
		(start 280.635964 -204.134974)
		(end 281.06116 -204.56017)
		(width 0.14478)
		(layer "In4.Cu")
		(net "M_D_CPU0_SA_DQ<6>")
	)
	(segment
		(start 282.498292 -203.58735)
		(end 282.72867 -203.58735)
		(width 0.14478)
		(layer "In4.Cu")
		(net "M_D_CPU0_SA_DQ<6>")
	)
	(segment
		(start 326.41032 -223.812608)
		(end 326.421496 -223.823784)
		(width 0.0889)
		(layer "In4.Cu")
		(net "M_D_CPU0_SA_DQ<6>")
	)
	(segment
		(start 328.379074 -227.128832)
		(end 328.41819 -227.151692)
		(width 0.0889)
		(layer "In4.Cu")
		(net "M_D_CPU0_SA_DQ<6>")
	)
	(segment
		(start 331.229716 -228.766878)
		(end 331.238098 -228.771704)
		(width 0.0889)
		(layer "In4.Cu")
		(net "M_D_CPU0_SA_DQ<6>")
	)
	(segment
		(start 282.891738 -203.750418)
		(end 282.891738 -204.397102)
		(width 0.14478)
		(layer "In4.Cu")
		(net "M_D_CPU0_SA_DQ<6>")
	)
	(segment
		(start 290.674298 -203.710032)
		(end 293.507668 -203.710032)
		(width 0.14478)
		(layer "In4.Cu")
		(net "M_D_CPU0_SA_DQ<6>")
	)
	(segment
		(start 333.684118 -228.771704)
		(end 333.6925 -228.766878)
		(width 0.0889)
		(layer "In4.Cu")
		(net "M_D_CPU0_SA_DQ<6>")
	)
	(segment
		(start 338.70265 -228.745542)
		(end 338.725002 -228.828854)
		(width 0.0889)
		(layer "In4.Cu")
		(net "M_D_CPU0_SA_DQ<6>")
	)
	(segment
		(start 302.04664 -204.56017)
		(end 307.316886 -204.56017)
		(width 0.14478)
		(layer "In4.Cu")
		(net "M_D_CPU0_SA_DQ<6>")
	)
	(segment
		(start 282.335224 -203.750418)
		(end 282.498292 -203.58735)
		(width 0.14478)
		(layer "In4.Cu")
		(net "M_D_CPU0_SA_DQ<6>")
	)
	(segment
		(start 324.447154 -222.44685)
		(end 324.591934 -222.59163)
		(width 0.14478)
		(layer "In4.Cu")
		(net "M_D_CPU0_SA_DQ<6>")
	)
	(segment
		(start 282.891738 -204.397102)
		(end 283.054806 -204.56017)
		(width 0.14478)
		(layer "In4.Cu")
		(net "M_D_CPU0_SA_DQ<6>")
	)
	(segment
		(start 325.148194 -222.59163)
		(end 325.446898 -222.890334)
		(width 0.0889)
		(layer "In4.Cu")
		(net "M_D_CPU0_SA_DQ<6>")
	)
	(segment
		(start 283.054806 -204.56017)
		(end 283.285184 -204.56017)
		(width 0.14478)
		(layer "In4.Cu")
		(net "M_D_CPU0_SA_DQ<6>")
	)
	(segment
		(start 283.448252 -203.85532)
		(end 283.61132 -203.692252)
		(width 0.14478)
		(layer "In4.Cu")
		(net "M_D_CPU0_SA_DQ<6>")
	)
	(segment
		(start 307.316886 -204.56017)
		(end 324.447154 -221.690438)
		(width 0.14478)
		(layer "In4.Cu")
		(net "M_D_CPU0_SA_DQ<6>")
	)
	(segment
		(start 328.41819 -227.151692)
		(end 328.44994 -227.16998)
		(width 0.0889)
		(layer "In4.Cu")
		(net "M_D_CPU0_SA_DQ<6>")
	)
	(segment
		(start 327.94829 -226.341686)
		(end 327.97877 -226.359466)
		(width 0.0889)
		(layer "In4.Cu")
		(net "M_D_CPU0_SA_DQ<6>")
	)
	(segment
		(start 328.851768 -227.940616)
		(end 328.88809 -227.961698)
		(width 0.0889)
		(layer "In4.Cu")
		(net "M_D_CPU0_SA_DQ<6>")
	)
	(segment
		(start 336.869786 -228.766878)
		(end 336.878168 -228.771704)
		(width 0.0889)
		(layer "In4.Cu")
		(net "M_D_CPU0_SA_DQ<6>")
	)
	(segment
		(start 293.507668 -203.710032)
		(end 294.357806 -204.56017)
		(width 0.14478)
		(layer "In4.Cu")
		(net "M_D_CPU0_SA_DQ<6>")
	)
	(segment
		(start 325.892668 -223.074992)
		(end 325.900288 -223.074992)
		(width 0.0889)
		(layer "In4.Cu")
		(net "M_D_CPU0_SA_DQ<6>")
	)
	(segment
		(start 283.448252 -204.397102)
		(end 283.448252 -203.85532)
		(width 0.14478)
		(layer "In4.Cu")
		(net "M_D_CPU0_SA_DQ<6>")
	)
	(segment
		(start 282.335224 -204.397102)
		(end 282.335224 -203.750418)
		(width 0.14478)
		(layer "In4.Cu")
		(net "M_D_CPU0_SA_DQ<6>")
	)
	(segment
		(start 338.725002 -228.828854)
		(end 338.571078 -229.094284)
		(width 0.0889)
		(layer "In4.Cu")
		(net "M_D_CPU0_SA_DQ<6>")
	)
	(segment
		(start 281.06116 -204.56017)
		(end 282.172156 -204.56017)
		(width 0.14478)
		(layer "In4.Cu")
		(net "M_D_CPU0_SA_DQ<6>")
	)
	(segment
		(start 324.591934 -222.59163)
		(end 325.148194 -222.59163)
		(width 0.14478)
		(layer "In4.Cu")
		(net "M_D_CPU0_SA_DQ<6>")
	)
	(arc
		(start 330.298044 -228.771704)
		(mid 330.581 -228.847881)
		(end 330.863956 -228.771704)
		(width 0.0889)
		(layer "In4.Cu")
		(net "M_D_CPU0_SA_DQ<6>")
	)
	(arc
		(start 332.752446 -228.766878)
		(mid 332.935954 -228.721384)
		(end 333.118206 -228.771704)
		(width 0.0889)
		(layer "In4.Cu")
		(net "M_D_CPU0_SA_DQ<6>")
	)
	(arc
		(start 338.384134 -228.771704)
		(mid 338.540453 -228.722709)
		(end 338.70265 -228.745542)
		(width 0.0889)
		(layer "In4.Cu")
		(net "M_D_CPU0_SA_DQ<6>")
	)
	(arc
		(start 334.624172 -228.771704)
		(mid 334.811116 -228.721449)
		(end 334.99806 -228.771704)
		(width 0.0889)
		(layer "In4.Cu")
		(net "M_D_CPU0_SA_DQ<6>")
	)
	(arc
		(start 326.421496 -223.823784)
		(mid 326.461508 -223.860071)
		(end 326.504808 -223.892364)
		(width 0.0889)
		(layer "In4.Cu")
		(net "M_D_CPU0_SA_DQ<6>")
	)
	(arc
		(start 325.900288 -223.074992)
		(mid 326.147245 -223.177285)
		(end 326.249538 -223.424242)
		(width 0.0889)
		(layer "In4.Cu")
		(net "M_D_CPU0_SA_DQ<6>")
	)
	(arc
		(start 336.504026 -228.771704)
		(mid 336.686277 -228.721354)
		(end 336.869786 -228.766878)
		(width 0.0889)
		(layer "In4.Cu")
		(net "M_D_CPU0_SA_DQ<6>")
	)
	(arc
		(start 329.358244 -228.771704)
		(mid 329.6412 -228.847881)
		(end 329.924156 -228.771704)
		(width 0.0889)
		(layer "In4.Cu")
		(net "M_D_CPU0_SA_DQ<6>")
	)
	(arc
		(start 326.571864 -223.931226)
		(mid 326.685271 -224.064256)
		(end 326.726042 -224.234248)
		(width 0.0889)
		(layer "In4.Cu")
		(net "M_D_CPU0_SA_DQ<6>")
	)
	(arc
		(start 337.452462 -228.766878)
		(mid 337.63597 -228.721384)
		(end 337.818222 -228.771704)
		(width 0.0889)
		(layer "In4.Cu")
		(net "M_D_CPU0_SA_DQ<6>")
	)
	(arc
		(start 335.563972 -228.771704)
		(mid 335.746223 -228.721354)
		(end 335.929732 -228.766878)
		(width 0.0889)
		(layer "In4.Cu")
		(net "M_D_CPU0_SA_DQ<6>")
	)
	(arc
		(start 327.195688 -225.044254)
		(mid 327.259981 -225.305859)
		(end 327.438004 -225.508058)
		(width 0.0889)
		(layer "In4.Cu")
		(net "M_D_CPU0_SA_DQ<6>")
	)
	(arc
		(start 327.97877 -226.359466)
		(mid 328.094197 -226.492842)
		(end 328.135742 -226.664266)
		(width 0.0889)
		(layer "In4.Cu")
		(net "M_D_CPU0_SA_DQ<6>")
	)
	(arc
		(start 328.44994 -227.16998)
		(mid 328.564616 -227.303314)
		(end 328.605896 -227.474272)
		(width 0.0889)
		(layer "In4.Cu")
		(net "M_D_CPU0_SA_DQ<6>")
	)
	(arc
		(start 328.605896 -227.474272)
		(mid 328.671132 -227.737863)
		(end 328.851768 -227.940616)
		(width 0.0889)
		(layer "In4.Cu")
		(net "M_D_CPU0_SA_DQ<6>")
	)
	(arc
		(start 337.818222 -228.771704)
		(mid 338.101178 -228.847881)
		(end 338.384134 -228.771704)
		(width 0.0889)
		(layer "In4.Cu")
		(net "M_D_CPU0_SA_DQ<6>")
	)
	(arc
		(start 334.99806 -228.771704)
		(mid 335.281016 -228.847881)
		(end 335.563972 -228.771704)
		(width 0.0889)
		(layer "In4.Cu")
		(net "M_D_CPU0_SA_DQ<6>")
	)
	(arc
		(start 332.178152 -228.771704)
		(mid 332.461108 -228.847881)
		(end 332.744064 -228.771704)
		(width 0.0889)
		(layer "In4.Cu")
		(net "M_D_CPU0_SA_DQ<6>")
	)
	(arc
		(start 331.80401 -228.771704)
		(mid 331.986261 -228.721354)
		(end 332.16977 -228.766878)
		(width 0.0889)
		(layer "In4.Cu")
		(net "M_D_CPU0_SA_DQ<6>")
	)
	(arc
		(start 330.863956 -228.771704)
		(mid 331.046207 -228.721354)
		(end 331.229716 -228.766878)
		(width 0.0889)
		(layer "In4.Cu")
		(net "M_D_CPU0_SA_DQ<6>")
	)
	(arc
		(start 333.6925 -228.766878)
		(mid 333.876008 -228.721384)
		(end 334.05826 -228.771704)
		(width 0.0889)
		(layer "In4.Cu")
		(net "M_D_CPU0_SA_DQ<6>")
	)
	(arc
		(start 328.91984 -227.979986)
		(mid 329.034516 -228.11332)
		(end 329.075796 -228.284278)
		(width 0.0889)
		(layer "In4.Cu")
		(net "M_D_CPU0_SA_DQ<6>")
	)
	(arc
		(start 329.075796 -228.284278)
		(mid 329.140311 -228.546497)
		(end 329.319128 -228.748844)
		(width 0.0889)
		(layer "In4.Cu")
		(net "M_D_CPU0_SA_DQ<6>")
	)
	(arc
		(start 325.446898 -222.890334)
		(mid 325.651419 -223.026991)
		(end 325.892668 -223.074992)
		(width 0.0889)
		(layer "In4.Cu")
		(net "M_D_CPU0_SA_DQ<6>")
	)
	(arc
		(start 328.135742 -226.664266)
		(mid 328.200257 -226.926485)
		(end 328.379074 -227.128832)
		(width 0.0889)
		(layer "In4.Cu")
		(net "M_D_CPU0_SA_DQ<6>")
	)
	(arc
		(start 327.666096 -225.85426)
		(mid 327.731332 -226.117851)
		(end 327.911968 -226.320604)
		(width 0.0889)
		(layer "In4.Cu")
		(net "M_D_CPU0_SA_DQ<6>")
	)
	(arc
		(start 336.878168 -228.771704)
		(mid 337.161124 -228.847881)
		(end 337.44408 -228.771704)
		(width 0.0889)
		(layer "In4.Cu")
		(net "M_D_CPU0_SA_DQ<6>")
	)
	(arc
		(start 326.249538 -223.424242)
		(mid 326.291324 -223.634406)
		(end 326.41032 -223.812608)
		(width 0.0889)
		(layer "In4.Cu")
		(net "M_D_CPU0_SA_DQ<6>")
	)
	(arc
		(start 327.51014 -225.549968)
		(mid 327.624816 -225.683302)
		(end 327.666096 -225.85426)
		(width 0.0889)
		(layer "In4.Cu")
		(net "M_D_CPU0_SA_DQ<6>")
	)
	(arc
		(start 334.05826 -228.771704)
		(mid 334.341216 -228.847881)
		(end 334.624172 -228.771704)
		(width 0.0889)
		(layer "In4.Cu")
		(net "M_D_CPU0_SA_DQ<6>")
	)
	(arc
		(start 331.238098 -228.771704)
		(mid 331.521054 -228.847881)
		(end 331.80401 -228.771704)
		(width 0.0889)
		(layer "In4.Cu")
		(net "M_D_CPU0_SA_DQ<6>")
	)
	(arc
		(start 333.118206 -228.771704)
		(mid 333.401162 -228.847881)
		(end 333.684118 -228.771704)
		(width 0.0889)
		(layer "In4.Cu")
		(net "M_D_CPU0_SA_DQ<6>")
	)
	(arc
		(start 335.938114 -228.771704)
		(mid 336.22107 -228.847881)
		(end 336.504026 -228.771704)
		(width 0.0889)
		(layer "In4.Cu")
		(net "M_D_CPU0_SA_DQ<6>")
	)
	(arc
		(start 326.726042 -224.234248)
		(mid 326.790195 -224.495837)
		(end 326.968104 -224.698052)
		(width 0.0889)
		(layer "In4.Cu")
		(net "M_D_CPU0_SA_DQ<6>")
	)
	(arc
		(start 327.037954 -224.738692)
		(mid 327.153907 -224.872325)
		(end 327.195688 -225.044254)
		(width 0.0889)
		(layer "In4.Cu")
		(net "M_D_CPU0_SA_DQ<6>")
	)
	(arc
		(start 329.924156 -228.771704)
		(mid 330.1111 -228.721449)
		(end 330.298044 -228.771704)
		(width 0.0889)
		(layer "In4.Cu")
		(net "M_D_CPU0_SA_DQ<6>")
	)
	(segment
		(start 340.918038 -229.360222)
		(end 340.451186 -229.094284)
		(width 0.10668)
		(layer "F.Cu")
		(net "M_D_CPU0_SA_DQ<5>")
	)
	(segment
		(start 307.530754 -205.410054)
		(end 323.969634 -221.848934)
		(width 0.14478)
		(layer "In4.Cu")
		(net "M_D_CPU0_SA_DQ<5>")
	)
	(segment
		(start 302.62449 -205.410054)
		(end 302.787558 -205.573122)
		(width 0.14478)
		(layer "In4.Cu")
		(net "M_D_CPU0_SA_DQ<5>")
	)
	(segment
		(start 304.063654 -205.79207)
		(end 304.294032 -205.79207)
		(width 0.14478)
		(layer "In4.Cu")
		(net "M_D_CPU0_SA_DQ<5>")
	)
	(segment
		(start 340.20125 -229.385114)
		(end 340.297008 -229.359714)
		(width 0.0889)
		(layer "In4.Cu")
		(net "M_D_CPU0_SA_DQ<5>")
	)
	(segment
		(start 328.514202 -228.606858)
		(end 328.550524 -228.62794)
		(width 0.0889)
		(layer "In4.Cu")
		(net "M_D_CPU0_SA_DQ<5>")
	)
	(segment
		(start 291.461698 -204.94371)
		(end 291.624766 -204.780642)
		(width 0.14478)
		(layer "In4.Cu")
		(net "M_D_CPU0_SA_DQ<5>")
	)
	(segment
		(start 298.650406 -204.785722)
		(end 298.813474 -204.94879)
		(width 0.14478)
		(layer "In4.Cu")
		(net "M_D_CPU0_SA_DQ<5>")
	)
	(segment
		(start 303.344072 -205.629002)
		(end 303.344072 -205.573122)
		(width 0.14478)
		(layer "In4.Cu")
		(net "M_D_CPU0_SA_DQ<5>")
	)
	(segment
		(start 294.348662 -205.410054)
		(end 296.238168 -205.410054)
		(width 0.14478)
		(layer "In4.Cu")
		(net "M_D_CPU0_SA_DQ<5>")
	)
	(segment
		(start 299.043852 -204.94879)
		(end 299.20692 -204.785722)
		(width 0.14478)
		(layer "In4.Cu")
		(net "M_D_CPU0_SA_DQ<5>")
	)
	(segment
		(start 286.295592 -205.63205)
		(end 286.45866 -205.795118)
		(width 0.14478)
		(layer "In4.Cu")
		(net "M_D_CPU0_SA_DQ<5>")
	)
	(segment
		(start 287.015174 -205.02499)
		(end 287.245552 -205.02499)
		(width 0.14478)
		(layer "In4.Cu")
		(net "M_D_CPU0_SA_DQ<5>")
	)
	(segment
		(start 299.20692 -204.723238)
		(end 299.369988 -204.56017)
		(width 0.14478)
		(layer "In4.Cu")
		(net "M_D_CPU0_SA_DQ<5>")
	)
	(segment
		(start 332.744064 -229.41661)
		(end 332.752446 -229.421436)
		(width 0.0889)
		(layer "In4.Cu")
		(net "M_D_CPU0_SA_DQ<5>")
	)
	(segment
		(start 297.120818 -205.410054)
		(end 297.346878 -205.410054)
		(width 0.14478)
		(layer "In4.Cu")
		(net "M_D_CPU0_SA_DQ<5>")
	)
	(segment
		(start 298.650406 -204.723238)
		(end 298.650406 -204.785722)
		(width 0.14478)
		(layer "In4.Cu")
		(net "M_D_CPU0_SA_DQ<5>")
	)
	(segment
		(start 296.564304 -205.80223)
		(end 296.794682 -205.80223)
		(width 0.14478)
		(layer "In4.Cu")
		(net "M_D_CPU0_SA_DQ<5>")
	)
	(segment
		(start 286.852106 -205.188058)
		(end 287.015174 -205.02499)
		(width 0.14478)
		(layer "In4.Cu")
		(net "M_D_CPU0_SA_DQ<5>")
	)
	(segment
		(start 323.969634 -221.848934)
		(end 323.969634 -222.65005)
		(width 0.14478)
		(layer "In4.Cu")
		(net "M_D_CPU0_SA_DQ<5>")
	)
	(segment
		(start 289.263836 -205.80223)
		(end 289.426904 -205.639162)
		(width 0.14478)
		(layer "In4.Cu")
		(net "M_D_CPU0_SA_DQ<5>")
	)
	(segment
		(start 291.068252 -204.780642)
		(end 291.23132 -204.94371)
		(width 0.14478)
		(layer "In4.Cu")
		(net "M_D_CPU0_SA_DQ<5>")
	)
	(segment
		(start 325.654924 -223.724724)
		(end 325.694548 -223.747584)
		(width 0.0889)
		(layer "In4.Cu")
		(net "M_D_CPU0_SA_DQ<5>")
	)
	(segment
		(start 306.295044 -205.367636)
		(end 306.295044 -205.646528)
		(width 0.14478)
		(layer "In4.Cu")
		(net "M_D_CPU0_SA_DQ<5>")
	)
	(segment
		(start 298.813474 -204.94879)
		(end 299.043852 -204.94879)
		(width 0.14478)
		(layer "In4.Cu")
		(net "M_D_CPU0_SA_DQ<5>")
	)
	(segment
		(start 340.297008 -229.359714)
		(end 340.451186 -229.094284)
		(width 0.0889)
		(layer "In4.Cu")
		(net "M_D_CPU0_SA_DQ<5>")
	)
	(segment
		(start 296.401236 -205.573122)
		(end 296.401236 -205.639162)
		(width 0.14478)
		(layer "In4.Cu")
		(net "M_D_CPU0_SA_DQ<5>")
	)
	(segment
		(start 306.1335 -205.206092)
		(end 306.295044 -205.367636)
		(width 0.14478)
		(layer "In4.Cu")
		(net "M_D_CPU0_SA_DQ<5>")
	)
	(segment
		(start 302.787558 -205.629002)
		(end 302.950626 -205.79207)
		(width 0.14478)
		(layer "In4.Cu")
		(net "M_D_CPU0_SA_DQ<5>")
	)
	(segment
		(start 286.852106 -205.63205)
		(end 286.852106 -205.188058)
		(width 0.14478)
		(layer "In4.Cu")
		(net "M_D_CPU0_SA_DQ<5>")
	)
	(segment
		(start 327.574148 -226.9871)
		(end 327.609454 -227.007674)
		(width 0.0889)
		(layer "In4.Cu")
		(net "M_D_CPU0_SA_DQ<5>")
	)
	(segment
		(start 291.787834 -204.56017)
		(end 293.498778 -204.56017)
		(width 0.14478)
		(layer "In4.Cu")
		(net "M_D_CPU0_SA_DQ<5>")
	)
	(segment
		(start 332.16977 -229.421436)
		(end 332.178152 -229.41661)
		(width 0.0889)
		(layer "In4.Cu")
		(net "M_D_CPU0_SA_DQ<5>")
	)
	(segment
		(start 302.787558 -205.573122)
		(end 302.787558 -205.629002)
		(width 0.14478)
		(layer "In4.Cu")
		(net "M_D_CPU0_SA_DQ<5>")
	)
	(segment
		(start 323.969634 -222.65005)
		(end 324.365874 -223.04629)
		(width 0.14478)
		(layer "In4.Cu")
		(net "M_D_CPU0_SA_DQ<5>")
	)
	(segment
		(start 306.295044 -205.646528)
		(end 306.456588 -205.808072)
		(width 0.14478)
		(layer "In4.Cu")
		(net "M_D_CPU0_SA_DQ<5>")
	)
	(segment
		(start 328.044048 -227.796852)
		(end 328.083164 -227.819712)
		(width 0.0889)
		(layer "In4.Cu")
		(net "M_D_CPU0_SA_DQ<5>")
	)
	(segment
		(start 290.905184 -204.56017)
		(end 291.068252 -204.723238)
		(width 0.14478)
		(layer "In4.Cu")
		(net "M_D_CPU0_SA_DQ<5>")
	)
	(segment
		(start 305.192176 -205.646528)
		(end 305.35372 -205.808072)
		(width 0.14478)
		(layer "In4.Cu")
		(net "M_D_CPU0_SA_DQ<5>")
	)
	(segment
		(start 337.44408 -229.41661)
		(end 337.452462 -229.421436)
		(width 0.0889)
		(layer "In4.Cu")
		(net "M_D_CPU0_SA_DQ<5>")
	)
	(segment
		(start 326.60463 -225.349816)
		(end 326.634094 -225.366834)
		(width 0.0889)
		(layer "In4.Cu")
		(net "M_D_CPU0_SA_DQ<5>")
	)
	(segment
		(start 299.20692 -204.785722)
		(end 299.20692 -204.723238)
		(width 0.14478)
		(layer "In4.Cu")
		(net "M_D_CPU0_SA_DQ<5>")
	)
	(segment
		(start 286.45866 -205.795118)
		(end 286.689038 -205.795118)
		(width 0.14478)
		(layer "In4.Cu")
		(net "M_D_CPU0_SA_DQ<5>")
	)
	(segment
		(start 328.950574 -229.397052)
		(end 328.984102 -229.41661)
		(width 0.0889)
		(layer "In4.Cu")
		(net "M_D_CPU0_SA_DQ<5>")
	)
	(segment
		(start 305.74361 -205.646528)
		(end 305.74361 -205.367636)
		(width 0.14478)
		(layer "In4.Cu")
		(net "M_D_CPU0_SA_DQ<5>")
	)
	(segment
		(start 325.417942 -223.487742)
		(end 325.654924 -223.724724)
		(width 0.0889)
		(layer "In4.Cu")
		(net "M_D_CPU0_SA_DQ<5>")
	)
	(segment
		(start 286.295592 -205.188058)
		(end 286.295592 -205.63205)
		(width 0.14478)
		(layer "In4.Cu")
		(net "M_D_CPU0_SA_DQ<5>")
	)
	(segment
		(start 305.582066 -205.808072)
		(end 305.74361 -205.646528)
		(width 0.14478)
		(layer "In4.Cu")
		(net "M_D_CPU0_SA_DQ<5>")
	)
	(segment
		(start 291.624766 -204.723238)
		(end 291.787834 -204.56017)
		(width 0.14478)
		(layer "In4.Cu")
		(net "M_D_CPU0_SA_DQ<5>")
	)
	(segment
		(start 327.104502 -226.177602)
		(end 327.140824 -226.198684)
		(width 0.0889)
		(layer "In4.Cu")
		(net "M_D_CPU0_SA_DQ<5>")
	)
	(segment
		(start 326.634094 -225.366834)
		(end 326.67321 -225.389694)
		(width 0.0889)
		(layer "In4.Cu")
		(net "M_D_CPU0_SA_DQ<5>")
	)
	(segment
		(start 305.35372 -205.808072)
		(end 305.582066 -205.808072)
		(width 0.14478)
		(layer "In4.Cu")
		(net "M_D_CPU0_SA_DQ<5>")
	)
	(segment
		(start 289.589972 -205.410054)
		(end 289.823398 -205.410054)
		(width 0.14478)
		(layer "In4.Cu")
		(net "M_D_CPU0_SA_DQ<5>")
	)
	(segment
		(start 327.54697 -226.971352)
		(end 327.574148 -226.9871)
		(width 0.0889)
		(layer "In4.Cu")
		(net "M_D_CPU0_SA_DQ<5>")
	)
	(segment
		(start 296.238168 -205.410054)
		(end 296.401236 -205.573122)
		(width 0.14478)
		(layer "In4.Cu")
		(net "M_D_CPU0_SA_DQ<5>")
	)
	(segment
		(start 287.40862 -205.246986)
		(end 287.571688 -205.410054)
		(width 0.14478)
		(layer "In4.Cu")
		(net "M_D_CPU0_SA_DQ<5>")
	)
	(segment
		(start 326.136508 -224.541334)
		(end 326.164194 -224.557336)
		(width 0.0889)
		(layer "In4.Cu")
		(net "M_D_CPU0_SA_DQ<5>")
	)
	(segment
		(start 296.794682 -205.80223)
		(end 296.95775 -205.639162)
		(width 0.14478)
		(layer "In4.Cu")
		(net "M_D_CPU0_SA_DQ<5>")
	)
	(segment
		(start 304.620168 -205.410054)
		(end 305.030632 -205.410054)
		(width 0.14478)
		(layer "In4.Cu")
		(net "M_D_CPU0_SA_DQ<5>")
	)
	(segment
		(start 303.900586 -205.629002)
		(end 304.063654 -205.79207)
		(width 0.14478)
		(layer "In4.Cu")
		(net "M_D_CPU0_SA_DQ<5>")
	)
	(segment
		(start 288.707322 -205.410054)
		(end 288.87039 -205.573122)
		(width 0.14478)
		(layer "In4.Cu")
		(net "M_D_CPU0_SA_DQ<5>")
	)
	(segment
		(start 333.684118 -229.41661)
		(end 333.6925 -229.421436)
		(width 0.0889)
		(layer "In4.Cu")
		(net "M_D_CPU0_SA_DQ<5>")
	)
	(segment
		(start 287.245552 -205.02499)
		(end 287.40862 -205.188058)
		(width 0.14478)
		(layer "In4.Cu")
		(net "M_D_CPU0_SA_DQ<5>")
	)
	(segment
		(start 289.426904 -205.573122)
		(end 289.589972 -205.410054)
		(width 0.14478)
		(layer "In4.Cu")
		(net "M_D_CPU0_SA_DQ<5>")
	)
	(segment
		(start 303.344072 -205.573122)
		(end 303.50714 -205.410054)
		(width 0.14478)
		(layer "In4.Cu")
		(net "M_D_CPU0_SA_DQ<5>")
	)
	(segment
		(start 306.846478 -205.571598)
		(end 307.008022 -205.410054)
		(width 0.14478)
		(layer "In4.Cu")
		(net "M_D_CPU0_SA_DQ<5>")
	)
	(segment
		(start 285.739078 -205.188058)
		(end 285.902146 -205.02499)
		(width 0.14478)
		(layer "In4.Cu")
		(net "M_D_CPU0_SA_DQ<5>")
	)
	(segment
		(start 285.902146 -205.02499)
		(end 286.132524 -205.02499)
		(width 0.14478)
		(layer "In4.Cu")
		(net "M_D_CPU0_SA_DQ<5>")
	)
	(segment
		(start 306.684934 -205.808072)
		(end 306.846478 -205.646528)
		(width 0.14478)
		(layer "In4.Cu")
		(net "M_D_CPU0_SA_DQ<5>")
	)
	(segment
		(start 325.121016 -223.04629)
		(end 325.315834 -223.241108)
		(width 0.0889)
		(layer "In4.Cu")
		(net "M_D_CPU0_SA_DQ<5>")
	)
	(segment
		(start 307.008022 -205.410054)
		(end 307.530754 -205.410054)
		(width 0.14478)
		(layer "In4.Cu")
		(net "M_D_CPU0_SA_DQ<5>")
	)
	(segment
		(start 304.4571 -205.573122)
		(end 304.620168 -205.410054)
		(width 0.14478)
		(layer "In4.Cu")
		(net "M_D_CPU0_SA_DQ<5>")
	)
	(segment
		(start 298.196762 -204.56017)
		(end 298.487338 -204.56017)
		(width 0.14478)
		(layer "In4.Cu")
		(net "M_D_CPU0_SA_DQ<5>")
	)
	(segment
		(start 304.4571 -205.629002)
		(end 304.4571 -205.573122)
		(width 0.14478)
		(layer "In4.Cu")
		(net "M_D_CPU0_SA_DQ<5>")
	)
	(segment
		(start 287.571688 -205.410054)
		(end 288.707322 -205.410054)
		(width 0.14478)
		(layer "In4.Cu")
		(net "M_D_CPU0_SA_DQ<5>")
	)
	(segment
		(start 285.57601 -205.410054)
		(end 285.739078 -205.246986)
		(width 0.14478)
		(layer "In4.Cu")
		(net "M_D_CPU0_SA_DQ<5>")
	)
	(segment
		(start 305.030632 -205.410054)
		(end 305.192176 -205.571598)
		(width 0.14478)
		(layer "In4.Cu")
		(net "M_D_CPU0_SA_DQ<5>")
	)
	(segment
		(start 285.739078 -205.246986)
		(end 285.739078 -205.188058)
		(width 0.14478)
		(layer "In4.Cu")
		(net "M_D_CPU0_SA_DQ<5>")
	)
	(segment
		(start 325.694548 -223.747584)
		(end 325.737728 -223.77273)
		(width 0.0889)
		(layer "In4.Cu")
		(net "M_D_CPU0_SA_DQ<5>")
	)
	(segment
		(start 304.294032 -205.79207)
		(end 304.4571 -205.629002)
		(width 0.14478)
		(layer "In4.Cu")
		(net "M_D_CPU0_SA_DQ<5>")
	)
	(segment
		(start 293.498778 -204.56017)
		(end 294.348662 -205.410054)
		(width 0.14478)
		(layer "In4.Cu")
		(net "M_D_CPU0_SA_DQ<5>")
	)
	(segment
		(start 288.87039 -205.573122)
		(end 288.87039 -205.639162)
		(width 0.14478)
		(layer "In4.Cu")
		(net "M_D_CPU0_SA_DQ<5>")
	)
	(segment
		(start 327.068942 -226.157028)
		(end 327.104502 -226.177602)
		(width 0.0889)
		(layer "In4.Cu")
		(net "M_D_CPU0_SA_DQ<5>")
	)
	(segment
		(start 291.23132 -204.94371)
		(end 291.461698 -204.94371)
		(width 0.14478)
		(layer "In4.Cu")
		(net "M_D_CPU0_SA_DQ<5>")
	)
	(segment
		(start 324.365874 -223.04629)
		(end 324.904354 -223.04629)
		(width 0.14478)
		(layer "In4.Cu")
		(net "M_D_CPU0_SA_DQ<5>")
	)
	(segment
		(start 331.229716 -229.421436)
		(end 331.238098 -229.41661)
		(width 0.0889)
		(layer "In4.Cu")
		(net "M_D_CPU0_SA_DQ<5>")
	)
	(segment
		(start 290.673282 -204.56017)
		(end 290.905184 -204.56017)
		(width 0.14478)
		(layer "In4.Cu")
		(net "M_D_CPU0_SA_DQ<5>")
	)
	(segment
		(start 306.456588 -205.808072)
		(end 306.684934 -205.808072)
		(width 0.14478)
		(layer "In4.Cu")
		(net "M_D_CPU0_SA_DQ<5>")
	)
	(segment
		(start 305.74361 -205.367636)
		(end 305.905154 -205.206092)
		(width 0.14478)
		(layer "In4.Cu")
		(net "M_D_CPU0_SA_DQ<5>")
	)
	(segment
		(start 301.174658 -204.56017)
		(end 302.024542 -205.410054)
		(width 0.14478)
		(layer "In4.Cu")
		(net "M_D_CPU0_SA_DQ<5>")
	)
	(segment
		(start 302.024542 -205.410054)
		(end 302.62449 -205.410054)
		(width 0.14478)
		(layer "In4.Cu")
		(net "M_D_CPU0_SA_DQ<5>")
	)
	(segment
		(start 286.132524 -205.02499)
		(end 286.295592 -205.188058)
		(width 0.14478)
		(layer "In4.Cu")
		(net "M_D_CPU0_SA_DQ<5>")
	)
	(segment
		(start 288.87039 -205.639162)
		(end 289.033458 -205.80223)
		(width 0.14478)
		(layer "In4.Cu")
		(net "M_D_CPU0_SA_DQ<5>")
	)
	(segment
		(start 297.346878 -205.410054)
		(end 298.196762 -204.56017)
		(width 0.14478)
		(layer "In4.Cu")
		(net "M_D_CPU0_SA_DQ<5>")
	)
	(segment
		(start 289.823398 -205.410054)
		(end 290.673282 -204.56017)
		(width 0.14478)
		(layer "In4.Cu")
		(net "M_D_CPU0_SA_DQ<5>")
	)
	(segment
		(start 296.95775 -205.639162)
		(end 296.95775 -205.573122)
		(width 0.14478)
		(layer "In4.Cu")
		(net "M_D_CPU0_SA_DQ<5>")
	)
	(segment
		(start 328.482452 -228.58857)
		(end 328.514202 -228.606858)
		(width 0.0889)
		(layer "In4.Cu")
		(net "M_D_CPU0_SA_DQ<5>")
	)
	(segment
		(start 303.900586 -205.573122)
		(end 303.900586 -205.629002)
		(width 0.14478)
		(layer "In4.Cu")
		(net "M_D_CPU0_SA_DQ<5>")
	)
	(segment
		(start 299.369988 -204.56017)
		(end 301.174658 -204.56017)
		(width 0.14478)
		(layer "In4.Cu")
		(net "M_D_CPU0_SA_DQ<5>")
	)
	(segment
		(start 328.984102 -229.41661)
		(end 328.992484 -229.421436)
		(width 0.0889)
		(layer "In4.Cu")
		(net "M_D_CPU0_SA_DQ<5>")
	)
	(segment
		(start 328.013568 -227.779072)
		(end 328.044048 -227.796852)
		(width 0.0889)
		(layer "In4.Cu")
		(net "M_D_CPU0_SA_DQ<5>")
	)
	(segment
		(start 303.50714 -205.410054)
		(end 303.737518 -205.410054)
		(width 0.14478)
		(layer "In4.Cu")
		(net "M_D_CPU0_SA_DQ<5>")
	)
	(segment
		(start 298.487338 -204.56017)
		(end 298.650406 -204.723238)
		(width 0.14478)
		(layer "In4.Cu")
		(net "M_D_CPU0_SA_DQ<5>")
	)
	(segment
		(start 289.426904 -205.639162)
		(end 289.426904 -205.573122)
		(width 0.14478)
		(layer "In4.Cu")
		(net "M_D_CPU0_SA_DQ<5>")
	)
	(segment
		(start 291.068252 -204.723238)
		(end 291.068252 -204.780642)
		(width 0.14478)
		(layer "In4.Cu")
		(net "M_D_CPU0_SA_DQ<5>")
	)
	(segment
		(start 303.181004 -205.79207)
		(end 303.344072 -205.629002)
		(width 0.14478)
		(layer "In4.Cu")
		(net "M_D_CPU0_SA_DQ<5>")
	)
	(segment
		(start 336.869786 -229.421436)
		(end 336.878168 -229.41661)
		(width 0.0889)
		(layer "In4.Cu")
		(net "M_D_CPU0_SA_DQ<5>")
	)
	(segment
		(start 285.160974 -205.410054)
		(end 285.57601 -205.410054)
		(width 0.14478)
		(layer "In4.Cu")
		(net "M_D_CPU0_SA_DQ<5>")
	)
	(segment
		(start 303.737518 -205.410054)
		(end 303.900586 -205.573122)
		(width 0.14478)
		(layer "In4.Cu")
		(net "M_D_CPU0_SA_DQ<5>")
	)
	(segment
		(start 296.401236 -205.639162)
		(end 296.564304 -205.80223)
		(width 0.14478)
		(layer "In4.Cu")
		(net "M_D_CPU0_SA_DQ<5>")
	)
	(segment
		(start 305.905154 -205.206092)
		(end 306.1335 -205.206092)
		(width 0.14478)
		(layer "In4.Cu")
		(net "M_D_CPU0_SA_DQ<5>")
	)
	(segment
		(start 339.689694 -229.421436)
		(end 339.698076 -229.41661)
		(width 0.0889)
		(layer "In4.Cu")
		(net "M_D_CPU0_SA_DQ<5>")
	)
	(segment
		(start 326.164194 -224.557336)
		(end 326.191626 -224.573338)
		(width 0.0889)
		(layer "In4.Cu")
		(net "M_D_CPU0_SA_DQ<5>")
	)
	(segment
		(start 302.950626 -205.79207)
		(end 303.181004 -205.79207)
		(width 0.14478)
		(layer "In4.Cu")
		(net "M_D_CPU0_SA_DQ<5>")
	)
	(segment
		(start 289.033458 -205.80223)
		(end 289.263836 -205.80223)
		(width 0.14478)
		(layer "In4.Cu")
		(net "M_D_CPU0_SA_DQ<5>")
	)
	(segment
		(start 286.689038 -205.795118)
		(end 286.852106 -205.63205)
		(width 0.14478)
		(layer "In4.Cu")
		(net "M_D_CPU0_SA_DQ<5>")
	)
	(segment
		(start 291.624766 -204.780642)
		(end 291.624766 -204.723238)
		(width 0.14478)
		(layer "In4.Cu")
		(net "M_D_CPU0_SA_DQ<5>")
	)
	(segment
		(start 284.736032 -204.985112)
		(end 285.160974 -205.410054)
		(width 0.14478)
		(layer "In4.Cu")
		(net "M_D_CPU0_SA_DQ<5>")
	)
	(segment
		(start 335.929732 -229.421436)
		(end 335.938114 -229.41661)
		(width 0.0889)
		(layer "In4.Cu")
		(net "M_D_CPU0_SA_DQ<5>")
	)
	(segment
		(start 287.40862 -205.188058)
		(end 287.40862 -205.246986)
		(width 0.14478)
		(layer "In4.Cu")
		(net "M_D_CPU0_SA_DQ<5>")
	)
	(segment
		(start 296.95775 -205.573122)
		(end 297.120818 -205.410054)
		(width 0.14478)
		(layer "In4.Cu")
		(net "M_D_CPU0_SA_DQ<5>")
	)
	(segment
		(start 305.192176 -205.571598)
		(end 305.192176 -205.646528)
		(width 0.14478)
		(layer "In4.Cu")
		(net "M_D_CPU0_SA_DQ<5>")
	)
	(segment
		(start 306.846478 -205.646528)
		(end 306.846478 -205.571598)
		(width 0.14478)
		(layer "In4.Cu")
		(net "M_D_CPU0_SA_DQ<5>")
	)
	(segment
		(start 324.904354 -223.04629)
		(end 325.121016 -223.04629)
		(width 0.0889)
		(layer "In4.Cu")
		(net "M_D_CPU0_SA_DQ<5>")
	)
	(arc
		(start 330.863956 -229.41661)
		(mid 331.046207 -229.466994)
		(end 331.229716 -229.421436)
		(width 0.0889)
		(layer "In4.Cu")
		(net "M_D_CPU0_SA_DQ<5>")
	)
	(arc
		(start 329.924156 -229.41661)
		(mid 330.1111 -229.466899)
		(end 330.298044 -229.41661)
		(width 0.0889)
		(layer "In4.Cu")
		(net "M_D_CPU0_SA_DQ<5>")
	)
	(arc
		(start 336.878168 -229.41661)
		(mid 337.161124 -229.340433)
		(end 337.44408 -229.41661)
		(width 0.0889)
		(layer "In4.Cu")
		(net "M_D_CPU0_SA_DQ<5>")
	)
	(arc
		(start 334.624172 -229.41661)
		(mid 334.811116 -229.466899)
		(end 334.99806 -229.41661)
		(width 0.0889)
		(layer "In4.Cu")
		(net "M_D_CPU0_SA_DQ<5>")
	)
	(arc
		(start 326.446642 -225.044508)
		(mid 326.488541 -225.216353)
		(end 326.60463 -225.349816)
		(width 0.0889)
		(layer "In4.Cu")
		(net "M_D_CPU0_SA_DQ<5>")
	)
	(arc
		(start 336.504026 -229.41661)
		(mid 336.686277 -229.466994)
		(end 336.869786 -229.421436)
		(width 0.0889)
		(layer "In4.Cu")
		(net "M_D_CPU0_SA_DQ<5>")
	)
	(arc
		(start 328.550524 -228.62794)
		(mid 328.731176 -228.830685)
		(end 328.796396 -229.094284)
		(width 0.0889)
		(layer "In4.Cu")
		(net "M_D_CPU0_SA_DQ<5>")
	)
	(arc
		(start 333.6925 -229.421436)
		(mid 333.876008 -229.466961)
		(end 334.05826 -229.41661)
		(width 0.0889)
		(layer "In4.Cu")
		(net "M_D_CPU0_SA_DQ<5>")
	)
	(arc
		(start 335.563972 -229.41661)
		(mid 335.746223 -229.466994)
		(end 335.929732 -229.421436)
		(width 0.0889)
		(layer "In4.Cu")
		(net "M_D_CPU0_SA_DQ<5>")
	)
	(arc
		(start 326.67321 -225.389694)
		(mid 326.852122 -225.592407)
		(end 326.916542 -225.855022)
		(width 0.0889)
		(layer "In4.Cu")
		(net "M_D_CPU0_SA_DQ<5>")
	)
	(arc
		(start 331.238098 -229.41661)
		(mid 331.521054 -229.340433)
		(end 331.80401 -229.41661)
		(width 0.0889)
		(layer "In4.Cu")
		(net "M_D_CPU0_SA_DQ<5>")
	)
	(arc
		(start 337.818222 -229.41661)
		(mid 338.101178 -229.340433)
		(end 338.384134 -229.41661)
		(width 0.0889)
		(layer "In4.Cu")
		(net "M_D_CPU0_SA_DQ<5>")
	)
	(arc
		(start 334.99806 -229.41661)
		(mid 335.281016 -229.340433)
		(end 335.563972 -229.41661)
		(width 0.0889)
		(layer "In4.Cu")
		(net "M_D_CPU0_SA_DQ<5>")
	)
	(arc
		(start 327.856596 -227.474272)
		(mid 327.898145 -227.645694)
		(end 328.013568 -227.779072)
		(width 0.0889)
		(layer "In4.Cu")
		(net "M_D_CPU0_SA_DQ<5>")
	)
	(arc
		(start 332.178152 -229.41661)
		(mid 332.461108 -229.340433)
		(end 332.744064 -229.41661)
		(width 0.0889)
		(layer "In4.Cu")
		(net "M_D_CPU0_SA_DQ<5>")
	)
	(arc
		(start 326.916542 -225.855022)
		(mid 326.956749 -226.024187)
		(end 327.068942 -226.157028)
		(width 0.0889)
		(layer "In4.Cu")
		(net "M_D_CPU0_SA_DQ<5>")
	)
	(arc
		(start 332.752446 -229.421436)
		(mid 332.935954 -229.466961)
		(end 333.118206 -229.41661)
		(width 0.0889)
		(layer "In4.Cu")
		(net "M_D_CPU0_SA_DQ<5>")
	)
	(arc
		(start 325.403718 -223.453452)
		(mid 325.407411 -223.472018)
		(end 325.417942 -223.487742)
		(width 0.0889)
		(layer "In4.Cu")
		(net "M_D_CPU0_SA_DQ<5>")
	)
	(arc
		(start 328.796396 -229.094284)
		(mid 328.837158 -229.264168)
		(end 328.950574 -229.397052)
		(width 0.0889)
		(layer "In4.Cu")
		(net "M_D_CPU0_SA_DQ<5>")
	)
	(arc
		(start 325.976488 -224.234248)
		(mid 326.018894 -224.407385)
		(end 326.136508 -224.541334)
		(width 0.0889)
		(layer "In4.Cu")
		(net "M_D_CPU0_SA_DQ<5>")
	)
	(arc
		(start 337.452462 -229.421436)
		(mid 337.63597 -229.466961)
		(end 337.818222 -229.41661)
		(width 0.0889)
		(layer "In4.Cu")
		(net "M_D_CPU0_SA_DQ<5>")
	)
	(arc
		(start 333.118206 -229.41661)
		(mid 333.401162 -229.340433)
		(end 333.684118 -229.41661)
		(width 0.0889)
		(layer "In4.Cu")
		(net "M_D_CPU0_SA_DQ<5>")
	)
	(arc
		(start 326.191626 -224.573338)
		(mid 326.378496 -224.776778)
		(end 326.446642 -225.044508)
		(width 0.0889)
		(layer "In4.Cu")
		(net "M_D_CPU0_SA_DQ<5>")
	)
	(arc
		(start 335.938114 -229.41661)
		(mid 336.22107 -229.340433)
		(end 336.504026 -229.41661)
		(width 0.0889)
		(layer "In4.Cu")
		(net "M_D_CPU0_SA_DQ<5>")
	)
	(arc
		(start 325.315834 -223.241108)
		(mid 325.380877 -223.338546)
		(end 325.403718 -223.453452)
		(width 0.0889)
		(layer "In4.Cu")
		(net "M_D_CPU0_SA_DQ<5>")
	)
	(arc
		(start 339.698076 -229.41661)
		(mid 339.945936 -229.341527)
		(end 340.20125 -229.385114)
		(width 0.0889)
		(layer "In4.Cu")
		(net "M_D_CPU0_SA_DQ<5>")
	)
	(arc
		(start 339.323934 -229.41661)
		(mid 339.506185 -229.466994)
		(end 339.689694 -229.421436)
		(width 0.0889)
		(layer "In4.Cu")
		(net "M_D_CPU0_SA_DQ<5>")
	)
	(arc
		(start 325.737728 -223.77273)
		(mid 325.913272 -223.974435)
		(end 325.976488 -224.234248)
		(width 0.0889)
		(layer "In4.Cu")
		(net "M_D_CPU0_SA_DQ<5>")
	)
	(arc
		(start 328.992484 -229.421436)
		(mid 329.175992 -229.466961)
		(end 329.358244 -229.41661)
		(width 0.0889)
		(layer "In4.Cu")
		(net "M_D_CPU0_SA_DQ<5>")
	)
	(arc
		(start 338.384134 -229.41661)
		(mid 338.571078 -229.466899)
		(end 338.758022 -229.41661)
		(width 0.0889)
		(layer "In4.Cu")
		(net "M_D_CPU0_SA_DQ<5>")
	)
	(arc
		(start 328.083164 -227.819712)
		(mid 328.261977 -228.022062)
		(end 328.326496 -228.284278)
		(width 0.0889)
		(layer "In4.Cu")
		(net "M_D_CPU0_SA_DQ<5>")
	)
	(arc
		(start 327.140824 -226.198684)
		(mid 327.321358 -226.401204)
		(end 327.386696 -226.66452)
		(width 0.0889)
		(layer "In4.Cu")
		(net "M_D_CPU0_SA_DQ<5>")
	)
	(arc
		(start 327.609454 -227.007674)
		(mid 327.790836 -227.210343)
		(end 327.856596 -227.474272)
		(width 0.0889)
		(layer "In4.Cu")
		(net "M_D_CPU0_SA_DQ<5>")
	)
	(arc
		(start 338.758022 -229.41661)
		(mid 339.040978 -229.340433)
		(end 339.323934 -229.41661)
		(width 0.0889)
		(layer "In4.Cu")
		(net "M_D_CPU0_SA_DQ<5>")
	)
	(arc
		(start 330.298044 -229.41661)
		(mid 330.581 -229.340433)
		(end 330.863956 -229.41661)
		(width 0.0889)
		(layer "In4.Cu")
		(net "M_D_CPU0_SA_DQ<5>")
	)
	(arc
		(start 331.80401 -229.41661)
		(mid 331.986261 -229.466994)
		(end 332.16977 -229.421436)
		(width 0.0889)
		(layer "In4.Cu")
		(net "M_D_CPU0_SA_DQ<5>")
	)
	(arc
		(start 334.05826 -229.41661)
		(mid 334.341216 -229.340433)
		(end 334.624172 -229.41661)
		(width 0.0889)
		(layer "In4.Cu")
		(net "M_D_CPU0_SA_DQ<5>")
	)
	(arc
		(start 328.326496 -228.284278)
		(mid 328.367751 -228.455249)
		(end 328.482452 -228.58857)
		(width 0.0889)
		(layer "In4.Cu")
		(net "M_D_CPU0_SA_DQ<5>")
	)
	(arc
		(start 327.386696 -226.66452)
		(mid 327.429228 -226.837583)
		(end 327.54697 -226.971352)
		(width 0.0889)
		(layer "In4.Cu")
		(net "M_D_CPU0_SA_DQ<5>")
	)
	(arc
		(start 329.358244 -229.41661)
		(mid 329.6412 -229.340433)
		(end 329.924156 -229.41661)
		(width 0.0889)
		(layer "In4.Cu")
		(net "M_D_CPU0_SA_DQ<5>")
	)
	(segment
		(start 339.508084 -228.550216)
		(end 339.040978 -228.284278)
		(width 0.10668)
		(layer "F.Cu")
		(net "M_D_CPU0_SA_DQ<4>")
	)
	(segment
		(start 324.18655 -220.770196)
		(end 324.414642 -220.770196)
		(width 0.14478)
		(layer "In4.Cu")
		(net "M_D_CPU0_SA_DQ<4>")
	)
	(segment
		(start 312.29427 -208.473294)
		(end 312.29427 -208.877916)
		(width 0.14478)
		(layer "In4.Cu")
		(net "M_D_CPU0_SA_DQ<4>")
	)
	(segment
		(start 296.415968 -204.035152)
		(end 296.651934 -204.035152)
		(width 0.14478)
		(layer "In4.Cu")
		(net "M_D_CPU0_SA_DQ<4>")
	)
	(segment
		(start 296.1005 -203.719684)
		(end 296.415968 -204.035152)
		(width 0.14478)
		(layer "In4.Cu")
		(net "M_D_CPU0_SA_DQ<4>")
	)
	(segment
		(start 314.823094 -211.40674)
		(end 315.051186 -211.40674)
		(width 0.14478)
		(layer "In4.Cu")
		(net "M_D_CPU0_SA_DQ<4>")
	)
	(segment
		(start 313.854846 -210.03387)
		(end 313.854846 -210.438492)
		(width 0.14478)
		(layer "In4.Cu")
		(net "M_D_CPU0_SA_DQ<4>")
	)
	(segment
		(start 294.358314 -203.719684)
		(end 296.1005 -203.719684)
		(width 0.14478)
		(layer "In4.Cu")
		(net "M_D_CPU0_SA_DQ<4>")
	)
	(segment
		(start 298.50842 -202.8698)
		(end 298.779692 -203.141072)
		(width 0.14478)
		(layer "In4.Cu")
		(net "M_D_CPU0_SA_DQ<4>")
	)
	(segment
		(start 291.207952 -203.179172)
		(end 291.450014 -203.179172)
		(width 0.14478)
		(layer "In4.Cu")
		(net "M_D_CPU0_SA_DQ<4>")
	)
	(segment
		(start 308.39283 -204.976476)
		(end 308.58079 -205.164436)
		(width 0.14478)
		(layer "In4.Cu")
		(net "M_D_CPU0_SA_DQ<4>")
	)
	(segment
		(start 331.33411 -228.606858)
		(end 331.342492 -228.611684)
		(width 0.0889)
		(layer "In4.Cu")
		(net "M_D_CPU0_SA_DQ<4>")
	)
	(segment
		(start 333.579724 -228.611684)
		(end 333.588106 -228.606858)
		(width 0.0889)
		(layer "In4.Cu")
		(net "M_D_CPU0_SA_DQ<4>")
	)
	(segment
		(start 325.167498 -221.346522)
		(end 325.167498 -221.967552)
		(width 0.14478)
		(layer "In4.Cu")
		(net "M_D_CPU0_SA_DQ<4>")
	)
	(segment
		(start 304.992278 -204.002132)
		(end 305.261264 -204.002132)
		(width 0.14478)
		(layer "In4.Cu")
		(net "M_D_CPU0_SA_DQ<4>")
	)
	(segment
		(start 324.414642 -220.770196)
		(end 324.590918 -220.769942)
		(width 0.14478)
		(layer "In4.Cu")
		(net "M_D_CPU0_SA_DQ<4>")
	)
	(segment
		(start 305.543712 -203.719684)
		(end 305.812698 -203.719684)
		(width 0.14478)
		(layer "In4.Cu")
		(net "M_D_CPU0_SA_DQ<4>")
	)
	(segment
		(start 309.173118 -205.352142)
		(end 309.173118 -205.756764)
		(width 0.14478)
		(layer "In4.Cu")
		(net "M_D_CPU0_SA_DQ<4>")
	)
	(segment
		(start 311.326022 -207.505046)
		(end 311.513982 -207.693006)
		(width 0.14478)
		(layer "In4.Cu")
		(net "M_D_CPU0_SA_DQ<4>")
	)
	(segment
		(start 303.055528 -204.002132)
		(end 303.337976 -203.719684)
		(width 0.14478)
		(layer "In4.Cu")
		(net "M_D_CPU0_SA_DQ<4>")
	)
	(segment
		(start 313.854846 -210.438492)
		(end 314.042806 -210.626452)
		(width 0.14478)
		(layer "In4.Cu")
		(net "M_D_CPU0_SA_DQ<4>")
	)
	(segment
		(start 309.361078 -205.944724)
		(end 309.58917 -205.944724)
		(width 0.14478)
		(layer "In4.Cu")
		(net "M_D_CPU0_SA_DQ<4>")
	)
	(segment
		(start 312.29427 -208.877916)
		(end 312.48223 -209.065876)
		(width 0.14478)
		(layer "In4.Cu")
		(net "M_D_CPU0_SA_DQ<4>")
	)
	(segment
		(start 322.438014 -218.617038)
		(end 322.438014 -219.02166)
		(width 0.14478)
		(layer "In4.Cu")
		(net "M_D_CPU0_SA_DQ<4>")
	)
	(segment
		(start 328.514202 -226.986846)
		(end 328.550524 -227.007928)
		(width 0.0889)
		(layer "In4.Cu")
		(net "M_D_CPU0_SA_DQ<4>")
	)
	(segment
		(start 318.536574 -215.12022)
		(end 318.724534 -215.30818)
		(width 0.14478)
		(layer "In4.Cu")
		(net "M_D_CPU0_SA_DQ<4>")
	)
	(segment
		(start 316.975998 -213.559644)
		(end 317.163958 -213.747604)
		(width 0.14478)
		(layer "In4.Cu")
		(net "M_D_CPU0_SA_DQ<4>")
	)
	(segment
		(start 322.854066 -219.20962)
		(end 323.030342 -219.209366)
		(width 0.14478)
		(layer "In4.Cu")
		(net "M_D_CPU0_SA_DQ<4>")
	)
	(segment
		(start 326.134222 -222.919036)
		(end 326.164702 -222.936816)
		(width 0.0889)
		(layer "In4.Cu")
		(net "M_D_CPU0_SA_DQ<4>")
	)
	(segment
		(start 305.812698 -203.719684)
		(end 306.095146 -204.002132)
		(width 0.14478)
		(layer "In4.Cu")
		(net "M_D_CPU0_SA_DQ<4>")
	)
	(segment
		(start 321.845686 -218.429332)
		(end 322.073778 -218.429332)
		(width 0.14478)
		(layer "In4.Cu")
		(net "M_D_CPU0_SA_DQ<4>")
	)
	(segment
		(start 323.406262 -219.989908)
		(end 323.634354 -219.989908)
		(width 0.14478)
		(layer "In4.Cu")
		(net "M_D_CPU0_SA_DQ<4>")
	)
	(segment
		(start 325.657718 -222.442532)
		(end 326.134222 -222.919036)
		(width 0.0889)
		(layer "In4.Cu")
		(net "M_D_CPU0_SA_DQ<4>")
	)
	(segment
		(start 299.059854 -203.141072)
		(end 299.331126 -202.8698)
		(width 0.14478)
		(layer "In4.Cu")
		(net "M_D_CPU0_SA_DQ<4>")
	)
	(segment
		(start 321.657726 -217.83675)
		(end 321.657726 -218.241372)
		(width 0.14478)
		(layer "In4.Cu")
		(net "M_D_CPU0_SA_DQ<4>")
	)
	(segment
		(start 315.415422 -211.999068)
		(end 315.603382 -212.187028)
		(width 0.14478)
		(layer "In4.Cu")
		(net "M_D_CPU0_SA_DQ<4>")
	)
	(segment
		(start 321.065398 -217.649044)
		(end 321.29349 -217.649044)
		(width 0.14478)
		(layer "In4.Cu")
		(net "M_D_CPU0_SA_DQ<4>")
	)
	(segment
		(start 291.450014 -203.179172)
		(end 291.759386 -202.8698)
		(width 0.14478)
		(layer "In4.Cu")
		(net "M_D_CPU0_SA_DQ<4>")
	)
	(segment
		(start 322.438014 -219.02166)
		(end 322.625974 -219.20962)
		(width 0.14478)
		(layer "In4.Cu")
		(net "M_D_CPU0_SA_DQ<4>")
	)
	(segment
		(start 318.348614 -214.527638)
		(end 318.536574 -214.715598)
		(width 0.14478)
		(layer "In4.Cu")
		(net "M_D_CPU0_SA_DQ<4>")
	)
	(segment
		(start 330.394056 -228.606858)
		(end 330.402438 -228.611684)
		(width 0.0889)
		(layer "In4.Cu")
		(net "M_D_CPU0_SA_DQ<4>")
	)
	(segment
		(start 338.887054 -228.549708)
		(end 339.040978 -228.284278)
		(width 0.0889)
		(layer "In4.Cu")
		(net "M_D_CPU0_SA_DQ<4>")
	)
	(segment
		(start 313.074558 -209.658204)
		(end 313.262518 -209.846164)
		(width 0.14478)
		(layer "In4.Cu")
		(net "M_D_CPU0_SA_DQ<4>")
	)
	(segment
		(start 313.074558 -209.253582)
		(end 313.074558 -209.658204)
		(width 0.14478)
		(layer "In4.Cu")
		(net "M_D_CPU0_SA_DQ<4>")
	)
	(segment
		(start 317.568326 -213.74735)
		(end 317.756286 -213.93531)
		(width 0.14478)
		(layer "In4.Cu")
		(net "M_D_CPU0_SA_DQ<4>")
	)
	(segment
		(start 297.337226 -203.719684)
		(end 298.18711 -202.8698)
		(width 0.14478)
		(layer "In4.Cu")
		(net "M_D_CPU0_SA_DQ<4>")
	)
	(segment
		(start 319.316862 -215.900508)
		(end 319.504822 -216.088468)
		(width 0.14478)
		(layer "In4.Cu")
		(net "M_D_CPU0_SA_DQ<4>")
	)
	(segment
		(start 314.042806 -210.626452)
		(end 314.270898 -210.626452)
		(width 0.14478)
		(layer "In4.Cu")
		(net "M_D_CPU0_SA_DQ<4>")
	)
	(segment
		(start 313.49061 -209.846164)
		(end 313.666886 -209.84591)
		(width 0.14478)
		(layer "In4.Cu")
		(net "M_D_CPU0_SA_DQ<4>")
	)
	(segment
		(start 319.732914 -216.088468)
		(end 319.90919 -216.088214)
		(width 0.14478)
		(layer "In4.Cu")
		(net "M_D_CPU0_SA_DQ<4>")
	)
	(segment
		(start 302.786542 -204.002132)
		(end 303.055528 -204.002132)
		(width 0.14478)
		(layer "In4.Cu")
		(net "M_D_CPU0_SA_DQ<4>")
	)
	(segment
		(start 322.625974 -219.20962)
		(end 322.854066 -219.20962)
		(width 0.14478)
		(layer "In4.Cu")
		(net "M_D_CPU0_SA_DQ<4>")
	)
	(segment
		(start 317.39205 -213.747604)
		(end 317.568326 -213.74735)
		(width 0.14478)
		(layer "In4.Cu")
		(net "M_D_CPU0_SA_DQ<4>")
	)
	(segment
		(start 323.218302 -219.397326)
		(end 323.218302 -219.801948)
		(width 0.14478)
		(layer "In4.Cu")
		(net "M_D_CPU0_SA_DQ<4>")
	)
	(segment
		(start 315.831474 -212.187028)
		(end 316.00775 -212.186774)
		(width 0.14478)
		(layer "In4.Cu")
		(net "M_D_CPU0_SA_DQ<4>")
	)
	(segment
		(start 323.99859 -220.582236)
		(end 324.18655 -220.770196)
		(width 0.14478)
		(layer "In4.Cu")
		(net "M_D_CPU0_SA_DQ<4>")
	)
	(segment
		(start 315.603382 -212.187028)
		(end 315.831474 -212.187028)
		(width 0.14478)
		(layer "In4.Cu")
		(net "M_D_CPU0_SA_DQ<4>")
	)
	(segment
		(start 317.756286 -213.93531)
		(end 317.756286 -214.339932)
		(width 0.14478)
		(layer "In4.Cu")
		(net "M_D_CPU0_SA_DQ<4>")
	)
	(segment
		(start 323.030342 -219.209366)
		(end 323.218302 -219.397326)
		(width 0.14478)
		(layer "In4.Cu")
		(net "M_D_CPU0_SA_DQ<4>")
	)
	(segment
		(start 312.48223 -209.065876)
		(end 312.710322 -209.065876)
		(width 0.14478)
		(layer "In4.Cu")
		(net "M_D_CPU0_SA_DQ<4>")
	)
	(segment
		(start 334.519778 -228.611684)
		(end 334.52816 -228.606858)
		(width 0.0889)
		(layer "In4.Cu")
		(net "M_D_CPU0_SA_DQ<4>")
	)
	(segment
		(start 298.779692 -203.141072)
		(end 299.059854 -203.141072)
		(width 0.14478)
		(layer "In4.Cu")
		(net "M_D_CPU0_SA_DQ<4>")
	)
	(segment
		(start 310.141366 -206.725012)
		(end 310.369458 -206.725012)
		(width 0.14478)
		(layer "In4.Cu")
		(net "M_D_CPU0_SA_DQ<4>")
	)
	(segment
		(start 321.469766 -217.64879)
		(end 321.657726 -217.83675)
		(width 0.14478)
		(layer "In4.Cu")
		(net "M_D_CPU0_SA_DQ<4>")
	)
	(segment
		(start 311.930034 -208.285588)
		(end 312.10631 -208.285334)
		(width 0.14478)
		(layer "In4.Cu")
		(net "M_D_CPU0_SA_DQ<4>")
	)
	(segment
		(start 301.05223 -202.8698)
		(end 301.902114 -203.719684)
		(width 0.14478)
		(layer "In4.Cu")
		(net "M_D_CPU0_SA_DQ<4>")
	)
	(segment
		(start 314.635134 -210.814158)
		(end 314.635134 -211.21878)
		(width 0.14478)
		(layer "In4.Cu")
		(net "M_D_CPU0_SA_DQ<4>")
	)
	(segment
		(start 310.369458 -206.725012)
		(end 310.545734 -206.724758)
		(width 0.14478)
		(layer "In4.Cu")
		(net "M_D_CPU0_SA_DQ<4>")
	)
	(segment
		(start 323.218302 -219.801948)
		(end 323.406262 -219.989908)
		(width 0.14478)
		(layer "In4.Cu")
		(net "M_D_CPU0_SA_DQ<4>")
	)
	(segment
		(start 315.415422 -211.594446)
		(end 315.415422 -211.999068)
		(width 0.14478)
		(layer "In4.Cu")
		(net "M_D_CPU0_SA_DQ<4>")
	)
	(segment
		(start 296.651934 -204.035152)
		(end 296.967402 -203.719684)
		(width 0.14478)
		(layer "In4.Cu")
		(net "M_D_CPU0_SA_DQ<4>")
	)
	(segment
		(start 326.60463 -223.729804)
		(end 326.634094 -223.746822)
		(width 0.0889)
		(layer "In4.Cu")
		(net "M_D_CPU0_SA_DQ<4>")
	)
	(segment
		(start 314.270898 -210.626452)
		(end 314.447174 -210.626198)
		(width 0.14478)
		(layer "In4.Cu")
		(net "M_D_CPU0_SA_DQ<4>")
	)
	(segment
		(start 319.128902 -215.307926)
		(end 319.316862 -215.495886)
		(width 0.14478)
		(layer "In4.Cu")
		(net "M_D_CPU0_SA_DQ<4>")
	)
	(segment
		(start 317.944246 -214.527892)
		(end 318.172338 -214.527892)
		(width 0.14478)
		(layer "In4.Cu")
		(net "M_D_CPU0_SA_DQ<4>")
	)
	(segment
		(start 322.073778 -218.429332)
		(end 322.250054 -218.429078)
		(width 0.14478)
		(layer "In4.Cu")
		(net "M_D_CPU0_SA_DQ<4>")
	)
	(segment
		(start 316.975998 -213.155022)
		(end 316.975998 -213.559644)
		(width 0.14478)
		(layer "In4.Cu")
		(net "M_D_CPU0_SA_DQ<4>")
	)
	(segment
		(start 316.611762 -212.967316)
		(end 316.788038 -212.967062)
		(width 0.14478)
		(layer "In4.Cu")
		(net "M_D_CPU0_SA_DQ<4>")
	)
	(segment
		(start 302.504094 -203.719684)
		(end 302.786542 -204.002132)
		(width 0.14478)
		(layer "In4.Cu")
		(net "M_D_CPU0_SA_DQ<4>")
	)
	(segment
		(start 319.316862 -215.495886)
		(end 319.316862 -215.900508)
		(width 0.14478)
		(layer "In4.Cu")
		(net "M_D_CPU0_SA_DQ<4>")
	)
	(segment
		(start 328.013568 -226.15906)
		(end 328.044048 -226.17684)
		(width 0.0889)
		(layer "In4.Cu")
		(net "M_D_CPU0_SA_DQ<4>")
	)
	(segment
		(start 315.051186 -211.40674)
		(end 315.227462 -211.406486)
		(width 0.14478)
		(layer "In4.Cu")
		(net "M_D_CPU0_SA_DQ<4>")
	)
	(segment
		(start 304.440844 -203.719684)
		(end 304.70983 -203.719684)
		(width 0.14478)
		(layer "In4.Cu")
		(net "M_D_CPU0_SA_DQ<4>")
	)
	(segment
		(start 291.759386 -202.8698)
		(end 293.50843 -202.8698)
		(width 0.14478)
		(layer "In4.Cu")
		(net "M_D_CPU0_SA_DQ<4>")
	)
	(segment
		(start 316.788038 -212.967062)
		(end 316.975998 -213.155022)
		(width 0.14478)
		(layer "In4.Cu")
		(net "M_D_CPU0_SA_DQ<4>")
	)
	(segment
		(start 321.657726 -218.241372)
		(end 321.845686 -218.429332)
		(width 0.14478)
		(layer "In4.Cu")
		(net "M_D_CPU0_SA_DQ<4>")
	)
	(segment
		(start 304.70983 -203.719684)
		(end 304.992278 -204.002132)
		(width 0.14478)
		(layer "In4.Cu")
		(net "M_D_CPU0_SA_DQ<4>")
	)
	(segment
		(start 318.724534 -215.30818)
		(end 318.952626 -215.30818)
		(width 0.14478)
		(layer "In4.Cu")
		(net "M_D_CPU0_SA_DQ<4>")
	)
	(segment
		(start 323.634354 -219.989908)
		(end 323.81063 -219.989654)
		(width 0.14478)
		(layer "In4.Cu")
		(net "M_D_CPU0_SA_DQ<4>")
	)
	(segment
		(start 312.10631 -208.285334)
		(end 312.29427 -208.473294)
		(width 0.14478)
		(layer "In4.Cu")
		(net "M_D_CPU0_SA_DQ<4>")
	)
	(segment
		(start 306.095146 -204.002132)
		(end 306.364132 -204.002132)
		(width 0.14478)
		(layer "In4.Cu")
		(net "M_D_CPU0_SA_DQ<4>")
	)
	(segment
		(start 338.27974 -228.611684)
		(end 338.288122 -228.606858)
		(width 0.0889)
		(layer "In4.Cu")
		(net "M_D_CPU0_SA_DQ<4>")
	)
	(segment
		(start 318.172338 -214.527892)
		(end 318.348614 -214.527638)
		(width 0.14478)
		(layer "In4.Cu")
		(net "M_D_CPU0_SA_DQ<4>")
	)
	(segment
		(start 336.034126 -228.606858)
		(end 336.042508 -228.611684)
		(width 0.0889)
		(layer "In4.Cu")
		(net "M_D_CPU0_SA_DQ<4>")
	)
	(segment
		(start 319.504822 -216.088468)
		(end 319.732914 -216.088468)
		(width 0.14478)
		(layer "In4.Cu")
		(net "M_D_CPU0_SA_DQ<4>")
	)
	(segment
		(start 329.819762 -228.611684)
		(end 329.828144 -228.606858)
		(width 0.0889)
		(layer "In4.Cu")
		(net "M_D_CPU0_SA_DQ<4>")
	)
	(segment
		(start 293.50843 -202.8698)
		(end 294.358314 -203.719684)
		(width 0.14478)
		(layer "In4.Cu")
		(net "M_D_CPU0_SA_DQ<4>")
	)
	(segment
		(start 308.808882 -205.164436)
		(end 308.985158 -205.164182)
		(width 0.14478)
		(layer "In4.Cu")
		(net "M_D_CPU0_SA_DQ<4>")
	)
	(segment
		(start 317.756286 -214.339932)
		(end 317.944246 -214.527892)
		(width 0.14478)
		(layer "In4.Cu")
		(net "M_D_CPU0_SA_DQ<4>")
	)
	(segment
		(start 310.921654 -207.5053)
		(end 311.149746 -207.5053)
		(width 0.14478)
		(layer "In4.Cu")
		(net "M_D_CPU0_SA_DQ<4>")
	)
	(segment
		(start 285.170626 -203.719684)
		(end 289.813746 -203.719684)
		(width 0.14478)
		(layer "In4.Cu")
		(net "M_D_CPU0_SA_DQ<4>")
	)
	(segment
		(start 308.58079 -205.164436)
		(end 308.808882 -205.164436)
		(width 0.14478)
		(layer "In4.Cu")
		(net "M_D_CPU0_SA_DQ<4>")
	)
	(segment
		(start 319.90919 -216.088214)
		(end 320.09715 -216.276174)
		(width 0.14478)
		(layer "In4.Cu")
		(net "M_D_CPU0_SA_DQ<4>")
	)
	(segment
		(start 316.00775 -212.186774)
		(end 316.19571 -212.374734)
		(width 0.14478)
		(layer "In4.Cu")
		(net "M_D_CPU0_SA_DQ<4>")
	)
	(segment
		(start 325.642478 -222.442532)
		(end 325.657718 -222.442532)
		(width 0.0889)
		(layer "In4.Cu")
		(net "M_D_CPU0_SA_DQ<4>")
	)
	(segment
		(start 328.952352 -227.778564)
		(end 328.984102 -227.796852)
		(width 0.0889)
		(layer "In4.Cu")
		(net "M_D_CPU0_SA_DQ<4>")
	)
	(segment
		(start 338.791042 -228.575108)
		(end 338.887054 -228.549708)
		(width 0.0889)
		(layer "In4.Cu")
		(net "M_D_CPU0_SA_DQ<4>")
	)
	(segment
		(start 311.513982 -208.097628)
		(end 311.701942 -208.285588)
		(width 0.14478)
		(layer "In4.Cu")
		(net "M_D_CPU0_SA_DQ<4>")
	)
	(segment
		(start 327.574148 -225.366834)
		(end 327.611994 -225.388678)
		(width 0.0889)
		(layer "In4.Cu")
		(net "M_D_CPU0_SA_DQ<4>")
	)
	(segment
		(start 309.953406 -206.13243)
		(end 309.953406 -206.537052)
		(width 0.14478)
		(layer "In4.Cu")
		(net "M_D_CPU0_SA_DQ<4>")
	)
	(segment
		(start 313.262518 -209.846164)
		(end 313.49061 -209.846164)
		(width 0.14478)
		(layer "In4.Cu")
		(net "M_D_CPU0_SA_DQ<4>")
	)
	(segment
		(start 328.044048 -226.17684)
		(end 328.083164 -226.1997)
		(width 0.0889)
		(layer "In4.Cu")
		(net "M_D_CPU0_SA_DQ<4>")
	)
	(segment
		(start 298.18711 -202.8698)
		(end 298.50842 -202.8698)
		(width 0.14478)
		(layer "In4.Cu")
		(net "M_D_CPU0_SA_DQ<4>")
	)
	(segment
		(start 320.689478 -216.868502)
		(end 320.877438 -217.056462)
		(width 0.14478)
		(layer "In4.Cu")
		(net "M_D_CPU0_SA_DQ<4>")
	)
	(segment
		(start 284.736032 -203.28509)
		(end 285.170626 -203.719684)
		(width 0.14478)
		(layer "In4.Cu")
		(net "M_D_CPU0_SA_DQ<4>")
	)
	(segment
		(start 308.985158 -205.164182)
		(end 309.173118 -205.352142)
		(width 0.14478)
		(layer "In4.Cu")
		(net "M_D_CPU0_SA_DQ<4>")
	)
	(segment
		(start 324.590918 -220.769942)
		(end 325.167498 -221.346522)
		(width 0.14478)
		(layer "In4.Cu")
		(net "M_D_CPU0_SA_DQ<4>")
	)
	(segment
		(start 299.331126 -202.8698)
		(end 301.05223 -202.8698)
		(width 0.14478)
		(layer "In4.Cu")
		(net "M_D_CPU0_SA_DQ<4>")
	)
	(segment
		(start 301.902114 -203.719684)
		(end 302.504094 -203.719684)
		(width 0.14478)
		(layer "In4.Cu")
		(net "M_D_CPU0_SA_DQ<4>")
	)
	(segment
		(start 320.877438 -217.461084)
		(end 321.065398 -217.649044)
		(width 0.14478)
		(layer "In4.Cu")
		(net "M_D_CPU0_SA_DQ<4>")
	)
	(segment
		(start 320.09715 -216.680796)
		(end 320.28511 -216.868756)
		(width 0.14478)
		(layer "In4.Cu")
		(net "M_D_CPU0_SA_DQ<4>")
	)
	(segment
		(start 316.19571 -212.779356)
		(end 316.38367 -212.967316)
		(width 0.14478)
		(layer "In4.Cu")
		(net "M_D_CPU0_SA_DQ<4>")
	)
	(segment
		(start 311.149746 -207.5053)
		(end 311.326022 -207.505046)
		(width 0.14478)
		(layer "In4.Cu")
		(net "M_D_CPU0_SA_DQ<4>")
	)
	(segment
		(start 305.261264 -204.002132)
		(end 305.543712 -203.719684)
		(width 0.14478)
		(layer "In4.Cu")
		(net "M_D_CPU0_SA_DQ<4>")
	)
	(segment
		(start 335.094072 -228.606858)
		(end 335.102454 -228.611684)
		(width 0.0889)
		(layer "In4.Cu")
		(net "M_D_CPU0_SA_DQ<4>")
	)
	(segment
		(start 318.536574 -214.715598)
		(end 318.536574 -215.12022)
		(width 0.14478)
		(layer "In4.Cu")
		(net "M_D_CPU0_SA_DQ<4>")
	)
	(segment
		(start 317.163958 -213.747604)
		(end 317.39205 -213.747604)
		(width 0.14478)
		(layer "In4.Cu")
		(net "M_D_CPU0_SA_DQ<4>")
	)
	(segment
		(start 326.164702 -222.936816)
		(end 326.197976 -222.95612)
		(width 0.0889)
		(layer "In4.Cu")
		(net "M_D_CPU0_SA_DQ<4>")
	)
	(segment
		(start 290.66363 -202.8698)
		(end 290.89858 -202.8698)
		(width 0.14478)
		(layer "In4.Cu")
		(net "M_D_CPU0_SA_DQ<4>")
	)
	(segment
		(start 303.337976 -203.719684)
		(end 303.606962 -203.719684)
		(width 0.14478)
		(layer "In4.Cu")
		(net "M_D_CPU0_SA_DQ<4>")
	)
	(segment
		(start 309.58917 -205.944724)
		(end 309.765446 -205.94447)
		(width 0.14478)
		(layer "In4.Cu")
		(net "M_D_CPU0_SA_DQ<4>")
	)
	(segment
		(start 311.513982 -207.693006)
		(end 311.513982 -208.097628)
		(width 0.14478)
		(layer "In4.Cu")
		(net "M_D_CPU0_SA_DQ<4>")
	)
	(segment
		(start 310.733694 -206.912718)
		(end 310.733694 -207.31734)
		(width 0.14478)
		(layer "In4.Cu")
		(net "M_D_CPU0_SA_DQ<4>")
	)
	(segment
		(start 296.967402 -203.719684)
		(end 297.337226 -203.719684)
		(width 0.14478)
		(layer "In4.Cu")
		(net "M_D_CPU0_SA_DQ<4>")
	)
	(segment
		(start 327.072498 -224.53854)
		(end 327.104248 -224.556828)
		(width 0.0889)
		(layer "In4.Cu")
		(net "M_D_CPU0_SA_DQ<4>")
	)
	(segment
		(start 328.984102 -227.796852)
		(end 329.023218 -227.819712)
		(width 0.0889)
		(layer "In4.Cu")
		(net "M_D_CPU0_SA_DQ<4>")
	)
	(segment
		(start 320.513202 -216.868756)
		(end 320.689478 -216.868502)
		(width 0.14478)
		(layer "In4.Cu")
		(net "M_D_CPU0_SA_DQ<4>")
	)
	(segment
		(start 325.167498 -221.967552)
		(end 325.642478 -222.442532)
		(width 0.14478)
		(layer "In4.Cu")
		(net "M_D_CPU0_SA_DQ<4>")
	)
	(segment
		(start 306.364132 -204.002132)
		(end 306.64658 -203.719684)
		(width 0.14478)
		(layer "In4.Cu")
		(net "M_D_CPU0_SA_DQ<4>")
	)
	(segment
		(start 314.447174 -210.626198)
		(end 314.635134 -210.814158)
		(width 0.14478)
		(layer "In4.Cu")
		(net "M_D_CPU0_SA_DQ<4>")
	)
	(segment
		(start 327.542398 -225.348546)
		(end 327.574148 -225.366834)
		(width 0.0889)
		(layer "In4.Cu")
		(net "M_D_CPU0_SA_DQ<4>")
	)
	(segment
		(start 315.227462 -211.406486)
		(end 315.415422 -211.594446)
		(width 0.14478)
		(layer "In4.Cu")
		(net "M_D_CPU0_SA_DQ<4>")
	)
	(segment
		(start 309.953406 -206.537052)
		(end 310.141366 -206.725012)
		(width 0.14478)
		(layer "In4.Cu")
		(net "M_D_CPU0_SA_DQ<4>")
	)
	(segment
		(start 314.635134 -211.21878)
		(end 314.823094 -211.40674)
		(width 0.14478)
		(layer "In4.Cu")
		(net "M_D_CPU0_SA_DQ<4>")
	)
	(segment
		(start 321.29349 -217.649044)
		(end 321.469766 -217.64879)
		(width 0.14478)
		(layer "In4.Cu")
		(net "M_D_CPU0_SA_DQ<4>")
	)
	(segment
		(start 289.813746 -203.719684)
		(end 290.66363 -202.8698)
		(width 0.14478)
		(layer "In4.Cu")
		(net "M_D_CPU0_SA_DQ<4>")
	)
	(segment
		(start 303.606962 -203.719684)
		(end 303.88941 -204.002132)
		(width 0.14478)
		(layer "In4.Cu")
		(net "M_D_CPU0_SA_DQ<4>")
	)
	(segment
		(start 312.710322 -209.065876)
		(end 312.886598 -209.065622)
		(width 0.14478)
		(layer "In4.Cu")
		(net "M_D_CPU0_SA_DQ<4>")
	)
	(segment
		(start 320.28511 -216.868756)
		(end 320.513202 -216.868756)
		(width 0.14478)
		(layer "In4.Cu")
		(net "M_D_CPU0_SA_DQ<4>")
	)
	(segment
		(start 310.545734 -206.724758)
		(end 310.733694 -206.912718)
		(width 0.14478)
		(layer "In4.Cu")
		(net "M_D_CPU0_SA_DQ<4>")
	)
	(segment
		(start 328.482452 -226.968558)
		(end 328.514202 -226.986846)
		(width 0.0889)
		(layer "In4.Cu")
		(net "M_D_CPU0_SA_DQ<4>")
	)
	(segment
		(start 320.877438 -217.056462)
		(end 320.877438 -217.461084)
		(width 0.14478)
		(layer "In4.Cu")
		(net "M_D_CPU0_SA_DQ<4>")
	)
	(segment
		(start 304.158396 -204.002132)
		(end 304.440844 -203.719684)
		(width 0.14478)
		(layer "In4.Cu")
		(net "M_D_CPU0_SA_DQ<4>")
	)
	(segment
		(start 316.19571 -212.374734)
		(end 316.19571 -212.779356)
		(width 0.14478)
		(layer "In4.Cu")
		(net "M_D_CPU0_SA_DQ<4>")
	)
	(segment
		(start 307.54066 -203.719684)
		(end 308.39283 -204.571854)
		(width 0.14478)
		(layer "In4.Cu")
		(net "M_D_CPU0_SA_DQ<4>")
	)
	(segment
		(start 308.39283 -204.571854)
		(end 308.39283 -204.976476)
		(width 0.14478)
		(layer "In4.Cu")
		(net "M_D_CPU0_SA_DQ<4>")
	)
	(segment
		(start 313.666886 -209.84591)
		(end 313.854846 -210.03387)
		(width 0.14478)
		(layer "In4.Cu")
		(net "M_D_CPU0_SA_DQ<4>")
	)
	(segment
		(start 323.99859 -220.177614)
		(end 323.99859 -220.582236)
		(width 0.14478)
		(layer "In4.Cu")
		(net "M_D_CPU0_SA_DQ<4>")
	)
	(segment
		(start 290.89858 -202.8698)
		(end 291.207952 -203.179172)
		(width 0.14478)
		(layer "In4.Cu")
		(net "M_D_CPU0_SA_DQ<4>")
	)
	(segment
		(start 318.952626 -215.30818)
		(end 319.128902 -215.307926)
		(width 0.14478)
		(layer "In4.Cu")
		(net "M_D_CPU0_SA_DQ<4>")
	)
	(segment
		(start 320.09715 -216.276174)
		(end 320.09715 -216.680796)
		(width 0.14478)
		(layer "In4.Cu")
		(net "M_D_CPU0_SA_DQ<4>")
	)
	(segment
		(start 311.701942 -208.285588)
		(end 311.930034 -208.285588)
		(width 0.14478)
		(layer "In4.Cu")
		(net "M_D_CPU0_SA_DQ<4>")
	)
	(segment
		(start 329.423522 -228.589078)
		(end 329.454002 -228.606858)
		(width 0.0889)
		(layer "In4.Cu")
		(net "M_D_CPU0_SA_DQ<4>")
	)
	(segment
		(start 323.81063 -219.989654)
		(end 323.99859 -220.177614)
		(width 0.14478)
		(layer "In4.Cu")
		(net "M_D_CPU0_SA_DQ<4>")
	)
	(segment
		(start 326.634094 -223.746822)
		(end 326.676004 -223.771206)
		(width 0.0889)
		(layer "In4.Cu")
		(net "M_D_CPU0_SA_DQ<4>")
	)
	(segment
		(start 327.104248 -224.556828)
		(end 327.14184 -224.578672)
		(width 0.0889)
		(layer "In4.Cu")
		(net "M_D_CPU0_SA_DQ<4>")
	)
	(segment
		(start 316.38367 -212.967316)
		(end 316.611762 -212.967316)
		(width 0.14478)
		(layer "In4.Cu")
		(net "M_D_CPU0_SA_DQ<4>")
	)
	(segment
		(start 309.765446 -205.94447)
		(end 309.953406 -206.13243)
		(width 0.14478)
		(layer "In4.Cu")
		(net "M_D_CPU0_SA_DQ<4>")
	)
	(segment
		(start 309.173118 -205.756764)
		(end 309.361078 -205.944724)
		(width 0.14478)
		(layer "In4.Cu")
		(net "M_D_CPU0_SA_DQ<4>")
	)
	(segment
		(start 312.886598 -209.065622)
		(end 313.074558 -209.253582)
		(width 0.14478)
		(layer "In4.Cu")
		(net "M_D_CPU0_SA_DQ<4>")
	)
	(segment
		(start 303.88941 -204.002132)
		(end 304.158396 -204.002132)
		(width 0.14478)
		(layer "In4.Cu")
		(net "M_D_CPU0_SA_DQ<4>")
	)
	(segment
		(start 306.64658 -203.719684)
		(end 307.54066 -203.719684)
		(width 0.14478)
		(layer "In4.Cu")
		(net "M_D_CPU0_SA_DQ<4>")
	)
	(segment
		(start 310.733694 -207.31734)
		(end 310.921654 -207.5053)
		(width 0.14478)
		(layer "In4.Cu")
		(net "M_D_CPU0_SA_DQ<4>")
	)
	(segment
		(start 322.250054 -218.429078)
		(end 322.438014 -218.617038)
		(width 0.14478)
		(layer "In4.Cu")
		(net "M_D_CPU0_SA_DQ<4>")
	)
	(arc
		(start 331.342492 -228.611684)
		(mid 331.526 -228.657178)
		(end 331.708252 -228.606858)
		(width 0.0889)
		(layer "In4.Cu")
		(net "M_D_CPU0_SA_DQ<4>")
	)
	(arc
		(start 328.796396 -227.474272)
		(mid 328.837651 -227.645243)
		(end 328.952352 -227.778564)
		(width 0.0889)
		(layer "In4.Cu")
		(net "M_D_CPU0_SA_DQ<4>")
	)
	(arc
		(start 328.550524 -227.007928)
		(mid 328.731176 -227.210673)
		(end 328.796396 -227.474272)
		(width 0.0889)
		(layer "In4.Cu")
		(net "M_D_CPU0_SA_DQ<4>")
	)
	(arc
		(start 336.408268 -228.606858)
		(mid 336.691224 -228.530681)
		(end 336.97418 -228.606858)
		(width 0.0889)
		(layer "In4.Cu")
		(net "M_D_CPU0_SA_DQ<4>")
	)
	(arc
		(start 327.14184 -224.578672)
		(mid 327.321569 -224.781292)
		(end 327.386442 -225.044254)
		(width 0.0889)
		(layer "In4.Cu")
		(net "M_D_CPU0_SA_DQ<4>")
	)
	(arc
		(start 330.768198 -228.606858)
		(mid 331.051154 -228.530681)
		(end 331.33411 -228.606858)
		(width 0.0889)
		(layer "In4.Cu")
		(net "M_D_CPU0_SA_DQ<4>")
	)
	(arc
		(start 329.023218 -227.819712)
		(mid 329.202031 -228.022062)
		(end 329.26655 -228.284278)
		(width 0.0889)
		(layer "In4.Cu")
		(net "M_D_CPU0_SA_DQ<4>")
	)
	(arc
		(start 330.402438 -228.611684)
		(mid 330.585946 -228.657178)
		(end 330.768198 -228.606858)
		(width 0.0889)
		(layer "In4.Cu")
		(net "M_D_CPU0_SA_DQ<4>")
	)
	(arc
		(start 327.611994 -225.388678)
		(mid 327.791723 -225.591298)
		(end 327.856596 -225.85426)
		(width 0.0889)
		(layer "In4.Cu")
		(net "M_D_CPU0_SA_DQ<4>")
	)
	(arc
		(start 335.468214 -228.606858)
		(mid 335.75117 -228.530681)
		(end 336.034126 -228.606858)
		(width 0.0889)
		(layer "In4.Cu")
		(net "M_D_CPU0_SA_DQ<4>")
	)
	(arc
		(start 328.083164 -226.1997)
		(mid 328.261977 -226.40205)
		(end 328.326496 -226.664266)
		(width 0.0889)
		(layer "In4.Cu")
		(net "M_D_CPU0_SA_DQ<4>")
	)
	(arc
		(start 331.708252 -228.606858)
		(mid 331.991208 -228.530681)
		(end 332.274164 -228.606858)
		(width 0.0889)
		(layer "In4.Cu")
		(net "M_D_CPU0_SA_DQ<4>")
	)
	(arc
		(start 336.97418 -228.606858)
		(mid 337.161124 -228.657113)
		(end 337.348068 -228.606858)
		(width 0.0889)
		(layer "In4.Cu")
		(net "M_D_CPU0_SA_DQ<4>")
	)
	(arc
		(start 332.648052 -228.606858)
		(mid 332.931008 -228.530681)
		(end 333.213964 -228.606858)
		(width 0.0889)
		(layer "In4.Cu")
		(net "M_D_CPU0_SA_DQ<4>")
	)
	(arc
		(start 329.828144 -228.606858)
		(mid 330.1111 -228.530681)
		(end 330.394056 -228.606858)
		(width 0.0889)
		(layer "In4.Cu")
		(net "M_D_CPU0_SA_DQ<4>")
	)
	(arc
		(start 329.26655 -228.284278)
		(mid 329.308099 -228.4557)
		(end 329.423522 -228.589078)
		(width 0.0889)
		(layer "In4.Cu")
		(net "M_D_CPU0_SA_DQ<4>")
	)
	(arc
		(start 338.288122 -228.606858)
		(mid 338.535835 -228.531638)
		(end 338.791042 -228.575108)
		(width 0.0889)
		(layer "In4.Cu")
		(net "M_D_CPU0_SA_DQ<4>")
	)
	(arc
		(start 332.274164 -228.606858)
		(mid 332.461108 -228.657113)
		(end 332.648052 -228.606858)
		(width 0.0889)
		(layer "In4.Cu")
		(net "M_D_CPU0_SA_DQ<4>")
	)
	(arc
		(start 326.676004 -223.771206)
		(mid 326.852986 -223.973298)
		(end 326.916796 -224.234248)
		(width 0.0889)
		(layer "In4.Cu")
		(net "M_D_CPU0_SA_DQ<4>")
	)
	(arc
		(start 329.454002 -228.606858)
		(mid 329.636253 -228.657208)
		(end 329.819762 -228.611684)
		(width 0.0889)
		(layer "In4.Cu")
		(net "M_D_CPU0_SA_DQ<4>")
	)
	(arc
		(start 328.326496 -226.664266)
		(mid 328.367751 -226.835237)
		(end 328.482452 -226.968558)
		(width 0.0889)
		(layer "In4.Cu")
		(net "M_D_CPU0_SA_DQ<4>")
	)
	(arc
		(start 334.154018 -228.606858)
		(mid 334.336269 -228.657208)
		(end 334.519778 -228.611684)
		(width 0.0889)
		(layer "In4.Cu")
		(net "M_D_CPU0_SA_DQ<4>")
	)
	(arc
		(start 337.91398 -228.606858)
		(mid 338.096231 -228.657208)
		(end 338.27974 -228.611684)
		(width 0.0889)
		(layer "In4.Cu")
		(net "M_D_CPU0_SA_DQ<4>")
	)
	(arc
		(start 333.588106 -228.606858)
		(mid 333.871062 -228.530681)
		(end 334.154018 -228.606858)
		(width 0.0889)
		(layer "In4.Cu")
		(net "M_D_CPU0_SA_DQ<4>")
	)
	(arc
		(start 335.102454 -228.611684)
		(mid 335.285962 -228.657178)
		(end 335.468214 -228.606858)
		(width 0.0889)
		(layer "In4.Cu")
		(net "M_D_CPU0_SA_DQ<4>")
	)
	(arc
		(start 327.856596 -225.85426)
		(mid 327.898145 -226.025682)
		(end 328.013568 -226.15906)
		(width 0.0889)
		(layer "In4.Cu")
		(net "M_D_CPU0_SA_DQ<4>")
	)
	(arc
		(start 327.386442 -225.044254)
		(mid 327.427697 -225.215225)
		(end 327.542398 -225.348546)
		(width 0.0889)
		(layer "In4.Cu")
		(net "M_D_CPU0_SA_DQ<4>")
	)
	(arc
		(start 326.916796 -224.234248)
		(mid 326.957985 -224.405152)
		(end 327.072498 -224.53854)
		(width 0.0889)
		(layer "In4.Cu")
		(net "M_D_CPU0_SA_DQ<4>")
	)
	(arc
		(start 334.52816 -228.606858)
		(mid 334.811116 -228.530681)
		(end 335.094072 -228.606858)
		(width 0.0889)
		(layer "In4.Cu")
		(net "M_D_CPU0_SA_DQ<4>")
	)
	(arc
		(start 336.042508 -228.611684)
		(mid 336.226016 -228.657178)
		(end 336.408268 -228.606858)
		(width 0.0889)
		(layer "In4.Cu")
		(net "M_D_CPU0_SA_DQ<4>")
	)
	(arc
		(start 326.446642 -223.424242)
		(mid 326.488482 -223.596228)
		(end 326.60463 -223.729804)
		(width 0.0889)
		(layer "In4.Cu")
		(net "M_D_CPU0_SA_DQ<4>")
	)
	(arc
		(start 326.197976 -222.95612)
		(mid 326.380638 -223.159201)
		(end 326.446642 -223.424242)
		(width 0.0889)
		(layer "In4.Cu")
		(net "M_D_CPU0_SA_DQ<4>")
	)
	(arc
		(start 333.213964 -228.606858)
		(mid 333.396215 -228.657208)
		(end 333.579724 -228.611684)
		(width 0.0889)
		(layer "In4.Cu")
		(net "M_D_CPU0_SA_DQ<4>")
	)
	(arc
		(start 337.348068 -228.606858)
		(mid 337.631024 -228.530681)
		(end 337.91398 -228.606858)
		(width 0.0889)
		(layer "In4.Cu")
		(net "M_D_CPU0_SA_DQ<4>")
	)
	(segment
		(start 340.447884 -226.930204)
		(end 339.981032 -226.664266)
		(width 0.10668)
		(layer "F.Cu")
		(net "M_D_CPU0_SA_DQ<3>")
	)
	(segment
		(start 282.198572 -200.04024)
		(end 282.198572 -200.147174)
		(width 0.14478)
		(layer "In4.Cu")
		(net "M_D_CPU0_SA_DQ<3>")
	)
	(segment
		(start 331.33411 -226.341686)
		(end 331.342492 -226.33686)
		(width 0.0889)
		(layer "In4.Cu")
		(net "M_D_CPU0_SA_DQ<3>")
	)
	(segment
		(start 330.261722 -225.510598)
		(end 330.298044 -225.53168)
		(width 0.0889)
		(layer "In4.Cu")
		(net "M_D_CPU0_SA_DQ<3>")
	)
	(segment
		(start 340.13521 -226.398836)
		(end 339.981032 -226.664266)
		(width 0.0889)
		(layer "In4.Cu")
		(net "M_D_CPU0_SA_DQ<3>")
	)
	(segment
		(start 338.27974 -226.33686)
		(end 338.288122 -226.341686)
		(width 0.0889)
		(layer "In4.Cu")
		(net "M_D_CPU0_SA_DQ<3>")
	)
	(segment
		(start 308.31917 -200.310242)
		(end 328.015854 -220.006926)
		(width 0.14478)
		(layer "In4.Cu")
		(net "M_D_CPU0_SA_DQ<3>")
	)
	(segment
		(start 302.04664 -200.310242)
		(end 308.31917 -200.310242)
		(width 0.14478)
		(layer "In4.Cu")
		(net "M_D_CPU0_SA_DQ<3>")
	)
	(segment
		(start 282.035504 -199.877172)
		(end 282.198572 -200.04024)
		(width 0.14478)
		(layer "In4.Cu")
		(net "M_D_CPU0_SA_DQ<3>")
	)
	(segment
		(start 328.015854 -221.404688)
		(end 328.135996 -221.52483)
		(width 0.0889)
		(layer "In4.Cu")
		(net "M_D_CPU0_SA_DQ<3>")
	)
	(segment
		(start 281.06116 -200.310242)
		(end 281.47899 -200.310242)
		(width 0.14478)
		(layer "In4.Cu")
		(net "M_D_CPU0_SA_DQ<3>")
	)
	(segment
		(start 281.642058 -200.147174)
		(end 281.642058 -200.04024)
		(width 0.14478)
		(layer "In4.Cu")
		(net "M_D_CPU0_SA_DQ<3>")
	)
	(segment
		(start 328.851768 -223.08058)
		(end 328.88809 -223.101662)
		(width 0.0889)
		(layer "In4.Cu")
		(net "M_D_CPU0_SA_DQ<3>")
	)
	(segment
		(start 328.135996 -221.52483)
		(end 328.135996 -221.80423)
		(width 0.0889)
		(layer "In4.Cu")
		(net "M_D_CPU0_SA_DQ<3>")
	)
	(segment
		(start 340.112858 -226.315524)
		(end 340.13521 -226.398836)
		(width 0.0889)
		(layer "In4.Cu")
		(net "M_D_CPU0_SA_DQ<3>")
	)
	(segment
		(start 336.034126 -226.341686)
		(end 336.042508 -226.33686)
		(width 0.0889)
		(layer "In4.Cu")
		(net "M_D_CPU0_SA_DQ<3>")
	)
	(segment
		(start 330.298044 -225.53168)
		(end 330.329794 -225.549968)
		(width 0.0889)
		(layer "In4.Cu")
		(net "M_D_CPU0_SA_DQ<3>")
	)
	(segment
		(start 293.444676 -199.450452)
		(end 294.29456 -200.300336)
		(width 0.14478)
		(layer "In4.Cu")
		(net "M_D_CPU0_SA_DQ<3>")
	)
	(segment
		(start 297.32224 -200.300336)
		(end 298.172124 -199.450452)
		(width 0.14478)
		(layer "In4.Cu")
		(net "M_D_CPU0_SA_DQ<3>")
	)
	(segment
		(start 338.854034 -226.341686)
		(end 338.862416 -226.33686)
		(width 0.0889)
		(layer "In4.Cu")
		(net "M_D_CPU0_SA_DQ<3>")
	)
	(segment
		(start 328.418698 -222.291656)
		(end 328.446892 -222.307912)
		(width 0.0889)
		(layer "In4.Cu")
		(net "M_D_CPU0_SA_DQ<3>")
	)
	(segment
		(start 298.172124 -199.450452)
		(end 301.18685 -199.450452)
		(width 0.14478)
		(layer "In4.Cu")
		(net "M_D_CPU0_SA_DQ<3>")
	)
	(segment
		(start 281.805126 -199.877172)
		(end 282.035504 -199.877172)
		(width 0.14478)
		(layer "In4.Cu")
		(net "M_D_CPU0_SA_DQ<3>")
	)
	(segment
		(start 339.794088 -226.341686)
		(end 339.80247 -226.33686)
		(width 0.0889)
		(layer "In4.Cu")
		(net "M_D_CPU0_SA_DQ<3>")
	)
	(segment
		(start 335.094072 -226.341686)
		(end 335.102454 -226.33686)
		(width 0.0889)
		(layer "In4.Cu")
		(net "M_D_CPU0_SA_DQ<3>")
	)
	(segment
		(start 281.642058 -200.04024)
		(end 281.805126 -199.877172)
		(width 0.14478)
		(layer "In4.Cu")
		(net "M_D_CPU0_SA_DQ<3>")
	)
	(segment
		(start 328.376788 -222.267272)
		(end 328.418698 -222.291656)
		(width 0.0889)
		(layer "In4.Cu")
		(net "M_D_CPU0_SA_DQ<3>")
	)
	(segment
		(start 328.88809 -223.101662)
		(end 328.91984 -223.11995)
		(width 0.0889)
		(layer "In4.Cu")
		(net "M_D_CPU0_SA_DQ<3>")
	)
	(segment
		(start 282.198572 -200.147174)
		(end 282.351734 -200.300336)
		(width 0.14478)
		(layer "In4.Cu")
		(net "M_D_CPU0_SA_DQ<3>")
	)
	(segment
		(start 280.635964 -199.885046)
		(end 281.06116 -200.310242)
		(width 0.14478)
		(layer "In4.Cu")
		(net "M_D_CPU0_SA_DQ<3>")
	)
	(segment
		(start 282.351734 -200.300336)
		(end 289.834066 -200.300336)
		(width 0.14478)
		(layer "In4.Cu")
		(net "M_D_CPU0_SA_DQ<3>")
	)
	(segment
		(start 329.789028 -224.698814)
		(end 329.828144 -224.721674)
		(width 0.0889)
		(layer "In4.Cu")
		(net "M_D_CPU0_SA_DQ<3>")
	)
	(segment
		(start 328.015854 -221.23527)
		(end 328.015854 -221.404688)
		(width 0.0889)
		(layer "In4.Cu")
		(net "M_D_CPU0_SA_DQ<3>")
	)
	(segment
		(start 328.015854 -220.006926)
		(end 328.015854 -221.23527)
		(width 0.14478)
		(layer "In4.Cu")
		(net "M_D_CPU0_SA_DQ<3>")
	)
	(segment
		(start 301.18685 -199.450452)
		(end 302.04664 -200.310242)
		(width 0.14478)
		(layer "In4.Cu")
		(net "M_D_CPU0_SA_DQ<3>")
	)
	(segment
		(start 333.579724 -226.33686)
		(end 333.588106 -226.341686)
		(width 0.0889)
		(layer "In4.Cu")
		(net "M_D_CPU0_SA_DQ<3>")
	)
	(segment
		(start 294.29456 -200.300336)
		(end 297.32224 -200.300336)
		(width 0.14478)
		(layer "In4.Cu")
		(net "M_D_CPU0_SA_DQ<3>")
	)
	(segment
		(start 329.358244 -223.911668)
		(end 329.388724 -223.929448)
		(width 0.0889)
		(layer "In4.Cu")
		(net "M_D_CPU0_SA_DQ<3>")
	)
	(segment
		(start 329.319128 -223.888808)
		(end 329.358244 -223.911668)
		(width 0.0889)
		(layer "In4.Cu")
		(net "M_D_CPU0_SA_DQ<3>")
	)
	(segment
		(start 281.47899 -200.310242)
		(end 281.642058 -200.147174)
		(width 0.14478)
		(layer "In4.Cu")
		(net "M_D_CPU0_SA_DQ<3>")
	)
	(segment
		(start 330.729082 -226.318826)
		(end 330.768198 -226.341686)
		(width 0.0889)
		(layer "In4.Cu")
		(net "M_D_CPU0_SA_DQ<3>")
	)
	(segment
		(start 289.834066 -200.300336)
		(end 290.68395 -199.450452)
		(width 0.14478)
		(layer "In4.Cu")
		(net "M_D_CPU0_SA_DQ<3>")
	)
	(segment
		(start 290.68395 -199.450452)
		(end 293.444676 -199.450452)
		(width 0.14478)
		(layer "In4.Cu")
		(net "M_D_CPU0_SA_DQ<3>")
	)
	(segment
		(start 329.828144 -224.721674)
		(end 329.859894 -224.739962)
		(width 0.0889)
		(layer "In4.Cu")
		(net "M_D_CPU0_SA_DQ<3>")
	)
	(segment
		(start 334.519778 -226.33686)
		(end 334.52816 -226.341686)
		(width 0.0889)
		(layer "In4.Cu")
		(net "M_D_CPU0_SA_DQ<3>")
	)
	(arc
		(start 336.97418 -226.341686)
		(mid 337.161124 -226.291431)
		(end 337.348068 -226.341686)
		(width 0.0889)
		(layer "In4.Cu")
		(net "M_D_CPU0_SA_DQ<3>")
	)
	(arc
		(start 328.135996 -221.80423)
		(mid 328.199788 -222.065189)
		(end 328.376788 -222.267272)
		(width 0.0889)
		(layer "In4.Cu")
		(net "M_D_CPU0_SA_DQ<3>")
	)
	(arc
		(start 333.588106 -226.341686)
		(mid 333.871062 -226.417863)
		(end 334.154018 -226.341686)
		(width 0.0889)
		(layer "In4.Cu")
		(net "M_D_CPU0_SA_DQ<3>")
	)
	(arc
		(start 333.213964 -226.341686)
		(mid 333.396215 -226.291336)
		(end 333.579724 -226.33686)
		(width 0.0889)
		(layer "In4.Cu")
		(net "M_D_CPU0_SA_DQ<3>")
	)
	(arc
		(start 331.708252 -226.341686)
		(mid 331.991208 -226.417863)
		(end 332.274164 -226.341686)
		(width 0.0889)
		(layer "In4.Cu")
		(net "M_D_CPU0_SA_DQ<3>")
	)
	(arc
		(start 337.91398 -226.341686)
		(mid 338.096231 -226.291336)
		(end 338.27974 -226.33686)
		(width 0.0889)
		(layer "In4.Cu")
		(net "M_D_CPU0_SA_DQ<3>")
	)
	(arc
		(start 336.408268 -226.341686)
		(mid 336.691224 -226.417863)
		(end 336.97418 -226.341686)
		(width 0.0889)
		(layer "In4.Cu")
		(net "M_D_CPU0_SA_DQ<3>")
	)
	(arc
		(start 338.288122 -226.341686)
		(mid 338.571078 -226.417863)
		(end 338.854034 -226.341686)
		(width 0.0889)
		(layer "In4.Cu")
		(net "M_D_CPU0_SA_DQ<3>")
	)
	(arc
		(start 337.348068 -226.341686)
		(mid 337.631024 -226.417863)
		(end 337.91398 -226.341686)
		(width 0.0889)
		(layer "In4.Cu")
		(net "M_D_CPU0_SA_DQ<3>")
	)
	(arc
		(start 334.154018 -226.341686)
		(mid 334.336269 -226.291336)
		(end 334.519778 -226.33686)
		(width 0.0889)
		(layer "In4.Cu")
		(net "M_D_CPU0_SA_DQ<3>")
	)
	(arc
		(start 329.859894 -224.739962)
		(mid 329.97457 -224.873296)
		(end 330.01585 -225.044254)
		(width 0.0889)
		(layer "In4.Cu")
		(net "M_D_CPU0_SA_DQ<3>")
	)
	(arc
		(start 330.01585 -225.044254)
		(mid 330.081086 -225.307845)
		(end 330.261722 -225.510598)
		(width 0.0889)
		(layer "In4.Cu")
		(net "M_D_CPU0_SA_DQ<3>")
	)
	(arc
		(start 329.075796 -223.424242)
		(mid 329.140311 -223.686461)
		(end 329.319128 -223.888808)
		(width 0.0889)
		(layer "In4.Cu")
		(net "M_D_CPU0_SA_DQ<3>")
	)
	(arc
		(start 334.52816 -226.341686)
		(mid 334.811116 -226.417863)
		(end 335.094072 -226.341686)
		(width 0.0889)
		(layer "In4.Cu")
		(net "M_D_CPU0_SA_DQ<3>")
	)
	(arc
		(start 330.329794 -225.549968)
		(mid 330.44447 -225.683302)
		(end 330.48575 -225.85426)
		(width 0.0889)
		(layer "In4.Cu")
		(net "M_D_CPU0_SA_DQ<3>")
	)
	(arc
		(start 331.342492 -226.33686)
		(mid 331.526 -226.291366)
		(end 331.708252 -226.341686)
		(width 0.0889)
		(layer "In4.Cu")
		(net "M_D_CPU0_SA_DQ<3>")
	)
	(arc
		(start 332.274164 -226.341686)
		(mid 332.461108 -226.291431)
		(end 332.648052 -226.341686)
		(width 0.0889)
		(layer "In4.Cu")
		(net "M_D_CPU0_SA_DQ<3>")
	)
	(arc
		(start 328.446892 -222.307912)
		(mid 328.563753 -222.441677)
		(end 328.605896 -222.614236)
		(width 0.0889)
		(layer "In4.Cu")
		(net "M_D_CPU0_SA_DQ<3>")
	)
	(arc
		(start 335.468214 -226.341686)
		(mid 335.75117 -226.417863)
		(end 336.034126 -226.341686)
		(width 0.0889)
		(layer "In4.Cu")
		(net "M_D_CPU0_SA_DQ<3>")
	)
	(arc
		(start 338.862416 -226.33686)
		(mid 339.045924 -226.291366)
		(end 339.228176 -226.341686)
		(width 0.0889)
		(layer "In4.Cu")
		(net "M_D_CPU0_SA_DQ<3>")
	)
	(arc
		(start 330.48575 -225.85426)
		(mid 330.550265 -226.116479)
		(end 330.729082 -226.318826)
		(width 0.0889)
		(layer "In4.Cu")
		(net "M_D_CPU0_SA_DQ<3>")
	)
	(arc
		(start 329.388724 -223.929448)
		(mid 329.504151 -224.062824)
		(end 329.545696 -224.234248)
		(width 0.0889)
		(layer "In4.Cu")
		(net "M_D_CPU0_SA_DQ<3>")
	)
	(arc
		(start 332.648052 -226.341686)
		(mid 332.931008 -226.417863)
		(end 333.213964 -226.341686)
		(width 0.0889)
		(layer "In4.Cu")
		(net "M_D_CPU0_SA_DQ<3>")
	)
	(arc
		(start 336.042508 -226.33686)
		(mid 336.226016 -226.291366)
		(end 336.408268 -226.341686)
		(width 0.0889)
		(layer "In4.Cu")
		(net "M_D_CPU0_SA_DQ<3>")
	)
	(arc
		(start 339.228176 -226.341686)
		(mid 339.511132 -226.417863)
		(end 339.794088 -226.341686)
		(width 0.0889)
		(layer "In4.Cu")
		(net "M_D_CPU0_SA_DQ<3>")
	)
	(arc
		(start 328.605896 -222.614236)
		(mid 328.671132 -222.877827)
		(end 328.851768 -223.08058)
		(width 0.0889)
		(layer "In4.Cu")
		(net "M_D_CPU0_SA_DQ<3>")
	)
	(arc
		(start 339.80247 -226.33686)
		(mid 339.95534 -226.292219)
		(end 340.112858 -226.315524)
		(width 0.0889)
		(layer "In4.Cu")
		(net "M_D_CPU0_SA_DQ<3>")
	)
	(arc
		(start 330.768198 -226.341686)
		(mid 331.051154 -226.417863)
		(end 331.33411 -226.341686)
		(width 0.0889)
		(layer "In4.Cu")
		(net "M_D_CPU0_SA_DQ<3>")
	)
	(arc
		(start 335.102454 -226.33686)
		(mid 335.285962 -226.291366)
		(end 335.468214 -226.341686)
		(width 0.0889)
		(layer "In4.Cu")
		(net "M_D_CPU0_SA_DQ<3>")
	)
	(arc
		(start 328.91984 -223.11995)
		(mid 329.034516 -223.253284)
		(end 329.075796 -223.424242)
		(width 0.0889)
		(layer "In4.Cu")
		(net "M_D_CPU0_SA_DQ<3>")
	)
	(arc
		(start 329.545696 -224.234248)
		(mid 329.610211 -224.496467)
		(end 329.789028 -224.698814)
		(width 0.0889)
		(layer "In4.Cu")
		(net "M_D_CPU0_SA_DQ<3>")
	)
	(segment
		(start 340.447884 -244.750082)
		(end 339.981032 -244.484144)
		(width 0.10668)
		(layer "F.Cu")
		(net "M_D_CPU0_SA_DQ<31>")
	)
	(segment
		(start 324.14464 -243.510054)
		(end 324.446138 -243.811552)
		(width 0.0889)
		(layer "In4.Cu")
		(net "M_D_CPU0_SA_DQ<31>")
	)
	(segment
		(start 280.635964 -233.884978)
		(end 281.06116 -234.310174)
		(width 0.14478)
		(layer "In4.Cu")
		(net "M_D_CPU0_SA_DQ<31>")
	)
	(segment
		(start 327.007474 -244.161564)
		(end 327.017888 -244.16766)
		(width 0.0889)
		(layer "In4.Cu")
		(net "M_D_CPU0_SA_DQ<31>")
	)
	(segment
		(start 331.33411 -244.161564)
		(end 331.342492 -244.156738)
		(width 0.0889)
		(layer "In4.Cu")
		(net "M_D_CPU0_SA_DQ<31>")
	)
	(segment
		(start 326.617838 -244.170962)
		(end 326.633586 -244.161818)
		(width 0.0889)
		(layer "In4.Cu")
		(net "M_D_CPU0_SA_DQ<31>")
	)
	(segment
		(start 333.579724 -244.156738)
		(end 333.588106 -244.161564)
		(width 0.0889)
		(layer "In4.Cu")
		(net "M_D_CPU0_SA_DQ<31>")
	)
	(segment
		(start 281.850338 -234.117388)
		(end 281.850338 -233.393996)
		(width 0.14478)
		(layer "In4.Cu")
		(net "M_D_CPU0_SA_DQ<31>")
	)
	(segment
		(start 339.794088 -244.161564)
		(end 339.80247 -244.156738)
		(width 0.0889)
		(layer "In4.Cu")
		(net "M_D_CPU0_SA_DQ<31>")
	)
	(segment
		(start 340.13521 -244.218714)
		(end 339.981032 -244.484144)
		(width 0.0889)
		(layer "In4.Cu")
		(net "M_D_CPU0_SA_DQ<31>")
	)
	(segment
		(start 329.819762 -244.156738)
		(end 329.828144 -244.161564)
		(width 0.0889)
		(layer "In4.Cu")
		(net "M_D_CPU0_SA_DQ<31>")
	)
	(segment
		(start 340.112858 -244.135402)
		(end 340.13521 -244.218714)
		(width 0.0889)
		(layer "In4.Cu")
		(net "M_D_CPU0_SA_DQ<31>")
	)
	(segment
		(start 282.315666 -233.20121)
		(end 282.508452 -233.393996)
		(width 0.14478)
		(layer "In4.Cu")
		(net "M_D_CPU0_SA_DQ<31>")
	)
	(segment
		(start 298.162472 -233.460036)
		(end 301.139606 -233.460036)
		(width 0.14478)
		(layer "In4.Cu")
		(net "M_D_CPU0_SA_DQ<31>")
	)
	(segment
		(start 330.394056 -244.161564)
		(end 330.402438 -244.156738)
		(width 0.0889)
		(layer "In4.Cu")
		(net "M_D_CPU0_SA_DQ<31>")
	)
	(segment
		(start 336.034126 -244.161564)
		(end 336.042508 -244.156738)
		(width 0.0889)
		(layer "In4.Cu")
		(net "M_D_CPU0_SA_DQ<31>")
	)
	(segment
		(start 325.398892 -244.111018)
		(end 325.880476 -244.111018)
		(width 0.0889)
		(layer "In4.Cu")
		(net "M_D_CPU0_SA_DQ<31>")
	)
	(segment
		(start 338.27974 -244.156738)
		(end 338.288122 -244.161564)
		(width 0.0889)
		(layer "In4.Cu")
		(net "M_D_CPU0_SA_DQ<31>")
	)
	(segment
		(start 326.633586 -244.161818)
		(end 326.649842 -244.15242)
		(width 0.0889)
		(layer "In4.Cu")
		(net "M_D_CPU0_SA_DQ<31>")
	)
	(segment
		(start 327.939908 -244.156738)
		(end 327.94829 -244.161564)
		(width 0.0889)
		(layer "In4.Cu")
		(net "M_D_CPU0_SA_DQ<31>")
	)
	(segment
		(start 334.519778 -244.156738)
		(end 334.52816 -244.161564)
		(width 0.0889)
		(layer "In4.Cu")
		(net "M_D_CPU0_SA_DQ<31>")
	)
	(segment
		(start 307.528214 -234.310174)
		(end 316.728094 -243.510054)
		(width 0.14478)
		(layer "In4.Cu")
		(net "M_D_CPU0_SA_DQ<31>")
	)
	(segment
		(start 325.099426 -243.811552)
		(end 325.398892 -244.111018)
		(width 0.0889)
		(layer "In4.Cu")
		(net "M_D_CPU0_SA_DQ<31>")
	)
	(segment
		(start 281.657552 -234.310174)
		(end 281.850338 -234.117388)
		(width 0.14478)
		(layer "In4.Cu")
		(net "M_D_CPU0_SA_DQ<31>")
	)
	(segment
		(start 282.701238 -234.310174)
		(end 289.82416 -234.310174)
		(width 0.14478)
		(layer "In4.Cu")
		(net "M_D_CPU0_SA_DQ<31>")
	)
	(segment
		(start 281.06116 -234.310174)
		(end 281.657552 -234.310174)
		(width 0.14478)
		(layer "In4.Cu")
		(net "M_D_CPU0_SA_DQ<31>")
	)
	(segment
		(start 281.850338 -233.393996)
		(end 282.043124 -233.20121)
		(width 0.14478)
		(layer "In4.Cu")
		(net "M_D_CPU0_SA_DQ<31>")
	)
	(segment
		(start 297.312334 -234.310174)
		(end 298.162472 -233.460036)
		(width 0.14478)
		(layer "In4.Cu")
		(net "M_D_CPU0_SA_DQ<31>")
	)
	(segment
		(start 282.508452 -234.117388)
		(end 282.701238 -234.310174)
		(width 0.14478)
		(layer "In4.Cu")
		(net "M_D_CPU0_SA_DQ<31>")
	)
	(segment
		(start 294.357806 -234.310174)
		(end 297.312334 -234.310174)
		(width 0.14478)
		(layer "In4.Cu")
		(net "M_D_CPU0_SA_DQ<31>")
	)
	(segment
		(start 289.82416 -234.310174)
		(end 290.674298 -233.460036)
		(width 0.14478)
		(layer "In4.Cu")
		(net "M_D_CPU0_SA_DQ<31>")
	)
	(segment
		(start 324.446138 -243.811552)
		(end 325.099426 -243.811552)
		(width 0.0889)
		(layer "In4.Cu")
		(net "M_D_CPU0_SA_DQ<31>")
	)
	(segment
		(start 301.139606 -233.460036)
		(end 301.989744 -234.310174)
		(width 0.14478)
		(layer "In4.Cu")
		(net "M_D_CPU0_SA_DQ<31>")
	)
	(segment
		(start 301.989744 -234.310174)
		(end 307.528214 -234.310174)
		(width 0.14478)
		(layer "In4.Cu")
		(net "M_D_CPU0_SA_DQ<31>")
	)
	(segment
		(start 290.674298 -233.460036)
		(end 293.507668 -233.460036)
		(width 0.14478)
		(layer "In4.Cu")
		(net "M_D_CPU0_SA_DQ<31>")
	)
	(segment
		(start 335.094072 -244.161564)
		(end 335.102454 -244.156738)
		(width 0.0889)
		(layer "In4.Cu")
		(net "M_D_CPU0_SA_DQ<31>")
	)
	(segment
		(start 316.728094 -243.510054)
		(end 323.868034 -243.510054)
		(width 0.14478)
		(layer "In4.Cu")
		(net "M_D_CPU0_SA_DQ<31>")
	)
	(segment
		(start 282.043124 -233.20121)
		(end 282.315666 -233.20121)
		(width 0.14478)
		(layer "In4.Cu")
		(net "M_D_CPU0_SA_DQ<31>")
	)
	(segment
		(start 293.507668 -233.460036)
		(end 294.357806 -234.310174)
		(width 0.14478)
		(layer "In4.Cu")
		(net "M_D_CPU0_SA_DQ<31>")
	)
	(segment
		(start 338.854034 -244.161564)
		(end 338.862416 -244.156738)
		(width 0.0889)
		(layer "In4.Cu")
		(net "M_D_CPU0_SA_DQ<31>")
	)
	(segment
		(start 323.868034 -243.510054)
		(end 324.14464 -243.510054)
		(width 0.0889)
		(layer "In4.Cu")
		(net "M_D_CPU0_SA_DQ<31>")
	)
	(segment
		(start 282.508452 -233.393996)
		(end 282.508452 -234.117388)
		(width 0.14478)
		(layer "In4.Cu")
		(net "M_D_CPU0_SA_DQ<31>")
	)
	(arc
		(start 335.102454 -244.156738)
		(mid 335.285962 -244.111244)
		(end 335.468214 -244.161564)
		(width 0.0889)
		(layer "In4.Cu")
		(net "M_D_CPU0_SA_DQ<31>")
	)
	(arc
		(start 325.880476 -244.111018)
		(mid 325.977427 -244.123893)
		(end 326.067674 -244.161564)
		(width 0.0889)
		(layer "In4.Cu")
		(net "M_D_CPU0_SA_DQ<31>")
	)
	(arc
		(start 339.80247 -244.156738)
		(mid 339.95534 -244.112097)
		(end 340.112858 -244.135402)
		(width 0.0889)
		(layer "In4.Cu")
		(net "M_D_CPU0_SA_DQ<31>")
	)
	(arc
		(start 336.97418 -244.161564)
		(mid 337.161124 -244.111309)
		(end 337.348068 -244.161564)
		(width 0.0889)
		(layer "In4.Cu")
		(net "M_D_CPU0_SA_DQ<31>")
	)
	(arc
		(start 327.017888 -244.16766)
		(mid 327.296574 -244.23788)
		(end 327.57364 -244.161564)
		(width 0.0889)
		(layer "In4.Cu")
		(net "M_D_CPU0_SA_DQ<31>")
	)
	(arc
		(start 331.342492 -244.156738)
		(mid 331.526 -244.111244)
		(end 331.708252 -244.161564)
		(width 0.0889)
		(layer "In4.Cu")
		(net "M_D_CPU0_SA_DQ<31>")
	)
	(arc
		(start 328.88809 -244.161564)
		(mid 329.171046 -244.237741)
		(end 329.454002 -244.161564)
		(width 0.0889)
		(layer "In4.Cu")
		(net "M_D_CPU0_SA_DQ<31>")
	)
	(arc
		(start 328.514202 -244.161564)
		(mid 328.701146 -244.111309)
		(end 328.88809 -244.161564)
		(width 0.0889)
		(layer "In4.Cu")
		(net "M_D_CPU0_SA_DQ<31>")
	)
	(arc
		(start 335.468214 -244.161564)
		(mid 335.75117 -244.237741)
		(end 336.034126 -244.161564)
		(width 0.0889)
		(layer "In4.Cu")
		(net "M_D_CPU0_SA_DQ<31>")
	)
	(arc
		(start 329.454002 -244.161564)
		(mid 329.636253 -244.111214)
		(end 329.819762 -244.156738)
		(width 0.0889)
		(layer "In4.Cu")
		(net "M_D_CPU0_SA_DQ<31>")
	)
	(arc
		(start 334.52816 -244.161564)
		(mid 334.811116 -244.237741)
		(end 335.094072 -244.161564)
		(width 0.0889)
		(layer "In4.Cu")
		(net "M_D_CPU0_SA_DQ<31>")
	)
	(arc
		(start 329.828144 -244.161564)
		(mid 330.1111 -244.237741)
		(end 330.394056 -244.161564)
		(width 0.0889)
		(layer "In4.Cu")
		(net "M_D_CPU0_SA_DQ<31>")
	)
	(arc
		(start 326.649842 -244.15242)
		(mid 326.829824 -244.11132)
		(end 327.007474 -244.161564)
		(width 0.0889)
		(layer "In4.Cu")
		(net "M_D_CPU0_SA_DQ<31>")
	)
	(arc
		(start 334.154018 -244.161564)
		(mid 334.336269 -244.111214)
		(end 334.519778 -244.156738)
		(width 0.0889)
		(layer "In4.Cu")
		(net "M_D_CPU0_SA_DQ<31>")
	)
	(arc
		(start 327.57364 -244.161564)
		(mid 327.756145 -244.111087)
		(end 327.939908 -244.156738)
		(width 0.0889)
		(layer "In4.Cu")
		(net "M_D_CPU0_SA_DQ<31>")
	)
	(arc
		(start 330.768198 -244.161564)
		(mid 331.051154 -244.237741)
		(end 331.33411 -244.161564)
		(width 0.0889)
		(layer "In4.Cu")
		(net "M_D_CPU0_SA_DQ<31>")
	)
	(arc
		(start 338.862416 -244.156738)
		(mid 339.045924 -244.111244)
		(end 339.228176 -244.161564)
		(width 0.0889)
		(layer "In4.Cu")
		(net "M_D_CPU0_SA_DQ<31>")
	)
	(arc
		(start 333.588106 -244.161564)
		(mid 333.871062 -244.237741)
		(end 334.154018 -244.161564)
		(width 0.0889)
		(layer "In4.Cu")
		(net "M_D_CPU0_SA_DQ<31>")
	)
	(arc
		(start 332.648052 -244.161564)
		(mid 332.931008 -244.237741)
		(end 333.213964 -244.161564)
		(width 0.0889)
		(layer "In4.Cu")
		(net "M_D_CPU0_SA_DQ<31>")
	)
	(arc
		(start 332.274164 -244.161564)
		(mid 332.461108 -244.111309)
		(end 332.648052 -244.161564)
		(width 0.0889)
		(layer "In4.Cu")
		(net "M_D_CPU0_SA_DQ<31>")
	)
	(arc
		(start 337.348068 -244.161564)
		(mid 337.631024 -244.237741)
		(end 337.91398 -244.161564)
		(width 0.0889)
		(layer "In4.Cu")
		(net "M_D_CPU0_SA_DQ<31>")
	)
	(arc
		(start 326.067674 -244.161564)
		(mid 326.341529 -244.237914)
		(end 326.617838 -244.170962)
		(width 0.0889)
		(layer "In4.Cu")
		(net "M_D_CPU0_SA_DQ<31>")
	)
	(arc
		(start 330.402438 -244.156738)
		(mid 330.585946 -244.111244)
		(end 330.768198 -244.161564)
		(width 0.0889)
		(layer "In4.Cu")
		(net "M_D_CPU0_SA_DQ<31>")
	)
	(arc
		(start 336.408268 -244.161564)
		(mid 336.691224 -244.237741)
		(end 336.97418 -244.161564)
		(width 0.0889)
		(layer "In4.Cu")
		(net "M_D_CPU0_SA_DQ<31>")
	)
	(arc
		(start 331.708252 -244.161564)
		(mid 331.991208 -244.237741)
		(end 332.274164 -244.161564)
		(width 0.0889)
		(layer "In4.Cu")
		(net "M_D_CPU0_SA_DQ<31>")
	)
	(arc
		(start 333.213964 -244.161564)
		(mid 333.396215 -244.111214)
		(end 333.579724 -244.156738)
		(width 0.0889)
		(layer "In4.Cu")
		(net "M_D_CPU0_SA_DQ<31>")
	)
	(arc
		(start 327.94829 -244.161564)
		(mid 328.231246 -244.237741)
		(end 328.514202 -244.161564)
		(width 0.0889)
		(layer "In4.Cu")
		(net "M_D_CPU0_SA_DQ<31>")
	)
	(arc
		(start 337.91398 -244.161564)
		(mid 338.096231 -244.111214)
		(end 338.27974 -244.156738)
		(width 0.0889)
		(layer "In4.Cu")
		(net "M_D_CPU0_SA_DQ<31>")
	)
	(arc
		(start 339.228176 -244.161564)
		(mid 339.511132 -244.237741)
		(end 339.794088 -244.161564)
		(width 0.0889)
		(layer "In4.Cu")
		(net "M_D_CPU0_SA_DQ<31>")
	)
	(arc
		(start 336.042508 -244.156738)
		(mid 336.226016 -244.111244)
		(end 336.408268 -244.161564)
		(width 0.0889)
		(layer "In4.Cu")
		(net "M_D_CPU0_SA_DQ<31>")
	)
	(arc
		(start 338.288122 -244.161564)
		(mid 338.571078 -244.237741)
		(end 338.854034 -244.161564)
		(width 0.0889)
		(layer "In4.Cu")
		(net "M_D_CPU0_SA_DQ<31>")
	)
	(segment
		(start 339.03793 -243.940076)
		(end 338.571078 -243.674138)
		(width 0.10668)
		(layer "F.Cu")
		(net "M_D_CPU0_SA_DQ<30>")
	)
	(segment
		(start 283.170376 -232.610152)
		(end 283.333444 -232.447084)
		(width 0.14478)
		(layer "In4.Cu")
		(net "M_D_CPU0_SA_DQ<30>")
	)
	(segment
		(start 325.55815 -243.300504)
		(end 326.351138 -243.300504)
		(width 0.0889)
		(layer "In4.Cu")
		(net "M_D_CPU0_SA_DQ<30>")
	)
	(segment
		(start 327.47966 -243.351812)
		(end 327.50125 -243.364258)
		(width 0.0889)
		(layer "In4.Cu")
		(net "M_D_CPU0_SA_DQ<30>")
	)
	(segment
		(start 317.398654 -242.595654)
		(end 323.900038 -242.595654)
		(width 0.14478)
		(layer "In4.Cu")
		(net "M_D_CPU0_SA_DQ<30>")
	)
	(segment
		(start 337.44408 -243.351558)
		(end 337.452462 -243.346732)
		(width 0.0889)
		(layer "In4.Cu")
		(net "M_D_CPU0_SA_DQ<30>")
	)
	(segment
		(start 328.409808 -243.346732)
		(end 328.41819 -243.351558)
		(width 0.0889)
		(layer "In4.Cu")
		(net "M_D_CPU0_SA_DQ<30>")
	)
	(segment
		(start 282.77693 -232.447084)
		(end 282.939998 -232.610152)
		(width 0.14478)
		(layer "In4.Cu")
		(net "M_D_CPU0_SA_DQ<30>")
	)
	(segment
		(start 331.229716 -243.346732)
		(end 331.238098 -243.351558)
		(width 0.0889)
		(layer "In4.Cu")
		(net "M_D_CPU0_SA_DQ<30>")
	)
	(segment
		(start 282.383484 -231.63911)
		(end 282.613862 -231.63911)
		(width 0.14478)
		(layer "In4.Cu")
		(net "M_D_CPU0_SA_DQ<30>")
	)
	(segment
		(start 282.220416 -231.802178)
		(end 282.383484 -231.63911)
		(width 0.14478)
		(layer "In4.Cu")
		(net "M_D_CPU0_SA_DQ<30>")
	)
	(segment
		(start 297.312334 -232.610152)
		(end 298.162472 -231.760014)
		(width 0.14478)
		(layer "In4.Cu")
		(net "M_D_CPU0_SA_DQ<30>")
	)
	(segment
		(start 282.939998 -232.610152)
		(end 283.170376 -232.610152)
		(width 0.14478)
		(layer "In4.Cu")
		(net "M_D_CPU0_SA_DQ<30>")
	)
	(segment
		(start 327.461372 -243.341398)
		(end 327.47966 -243.351812)
		(width 0.0889)
		(layer "In4.Cu")
		(net "M_D_CPU0_SA_DQ<30>")
	)
	(segment
		(start 324.24878 -242.595654)
		(end 324.390258 -242.737132)
		(width 0.0889)
		(layer "In4.Cu")
		(net "M_D_CPU0_SA_DQ<30>")
	)
	(segment
		(start 293.507668 -231.760014)
		(end 294.357806 -232.610152)
		(width 0.14478)
		(layer "In4.Cu")
		(net "M_D_CPU0_SA_DQ<30>")
	)
	(segment
		(start 294.357806 -232.610152)
		(end 297.312334 -232.610152)
		(width 0.14478)
		(layer "In4.Cu")
		(net "M_D_CPU0_SA_DQ<30>")
	)
	(segment
		(start 323.900038 -242.595654)
		(end 324.24878 -242.595654)
		(width 0.0889)
		(layer "In4.Cu")
		(net "M_D_CPU0_SA_DQ<30>")
	)
	(segment
		(start 332.16977 -243.346732)
		(end 332.178152 -243.351558)
		(width 0.0889)
		(layer "In4.Cu")
		(net "M_D_CPU0_SA_DQ<30>")
	)
	(segment
		(start 283.333444 -232.447084)
		(end 283.333444 -231.95026)
		(width 0.14478)
		(layer "In4.Cu")
		(net "M_D_CPU0_SA_DQ<30>")
	)
	(segment
		(start 327.083166 -243.365274)
		(end 327.106534 -243.351558)
		(width 0.0889)
		(layer "In4.Cu")
		(net "M_D_CPU0_SA_DQ<30>")
	)
	(segment
		(start 283.333444 -231.95026)
		(end 283.496512 -231.787192)
		(width 0.14478)
		(layer "In4.Cu")
		(net "M_D_CPU0_SA_DQ<30>")
	)
	(segment
		(start 284.053026 -232.610152)
		(end 289.82416 -232.610152)
		(width 0.14478)
		(layer "In4.Cu")
		(net "M_D_CPU0_SA_DQ<30>")
	)
	(segment
		(start 282.77693 -231.802178)
		(end 282.77693 -232.447084)
		(width 0.14478)
		(layer "In4.Cu")
		(net "M_D_CPU0_SA_DQ<30>")
	)
	(segment
		(start 301.196502 -231.760014)
		(end 302.04664 -232.610152)
		(width 0.14478)
		(layer "In4.Cu")
		(net "M_D_CPU0_SA_DQ<30>")
	)
	(segment
		(start 335.929732 -243.346732)
		(end 335.938114 -243.351558)
		(width 0.0889)
		(layer "In4.Cu")
		(net "M_D_CPU0_SA_DQ<30>")
	)
	(segment
		(start 282.220416 -232.447084)
		(end 282.220416 -231.802178)
		(width 0.14478)
		(layer "In4.Cu")
		(net "M_D_CPU0_SA_DQ<30>")
	)
	(segment
		(start 324.994778 -242.737132)
		(end 325.55815 -243.300504)
		(width 0.0889)
		(layer "In4.Cu")
		(net "M_D_CPU0_SA_DQ<30>")
	)
	(segment
		(start 281.06116 -232.610152)
		(end 282.057348 -232.610152)
		(width 0.14478)
		(layer "In4.Cu")
		(net "M_D_CPU0_SA_DQ<30>")
	)
	(segment
		(start 298.162472 -231.760014)
		(end 301.196502 -231.760014)
		(width 0.14478)
		(layer "In4.Cu")
		(net "M_D_CPU0_SA_DQ<30>")
	)
	(segment
		(start 280.635964 -232.184956)
		(end 281.06116 -232.610152)
		(width 0.14478)
		(layer "In4.Cu")
		(net "M_D_CPU0_SA_DQ<30>")
	)
	(segment
		(start 289.82416 -232.610152)
		(end 290.674298 -231.760014)
		(width 0.14478)
		(layer "In4.Cu")
		(net "M_D_CPU0_SA_DQ<30>")
	)
	(segment
		(start 324.390258 -242.737132)
		(end 324.994778 -242.737132)
		(width 0.0889)
		(layer "In4.Cu")
		(net "M_D_CPU0_SA_DQ<30>")
	)
	(segment
		(start 283.889958 -232.447084)
		(end 284.053026 -232.610152)
		(width 0.14478)
		(layer "In4.Cu")
		(net "M_D_CPU0_SA_DQ<30>")
	)
	(segment
		(start 338.725002 -243.408708)
		(end 338.571078 -243.674138)
		(width 0.0889)
		(layer "In4.Cu")
		(net "M_D_CPU0_SA_DQ<30>")
	)
	(segment
		(start 328.984102 -243.351558)
		(end 328.992484 -243.346732)
		(width 0.0889)
		(layer "In4.Cu")
		(net "M_D_CPU0_SA_DQ<30>")
	)
	(segment
		(start 302.04664 -232.610152)
		(end 307.413152 -232.610152)
		(width 0.14478)
		(layer "In4.Cu")
		(net "M_D_CPU0_SA_DQ<30>")
	)
	(segment
		(start 307.413152 -232.610152)
		(end 317.398654 -242.595654)
		(width 0.14478)
		(layer "In4.Cu")
		(net "M_D_CPU0_SA_DQ<30>")
	)
	(segment
		(start 282.057348 -232.610152)
		(end 282.220416 -232.447084)
		(width 0.14478)
		(layer "In4.Cu")
		(net "M_D_CPU0_SA_DQ<30>")
	)
	(segment
		(start 283.889958 -231.95026)
		(end 283.889958 -232.447084)
		(width 0.14478)
		(layer "In4.Cu")
		(net "M_D_CPU0_SA_DQ<30>")
	)
	(segment
		(start 332.744064 -243.351558)
		(end 332.752446 -243.346732)
		(width 0.0889)
		(layer "In4.Cu")
		(net "M_D_CPU0_SA_DQ<30>")
	)
	(segment
		(start 283.72689 -231.787192)
		(end 283.889958 -231.95026)
		(width 0.14478)
		(layer "In4.Cu")
		(net "M_D_CPU0_SA_DQ<30>")
	)
	(segment
		(start 282.613862 -231.63911)
		(end 282.77693 -231.802178)
		(width 0.14478)
		(layer "In4.Cu")
		(net "M_D_CPU0_SA_DQ<30>")
	)
	(segment
		(start 290.674298 -231.760014)
		(end 293.507668 -231.760014)
		(width 0.14478)
		(layer "In4.Cu")
		(net "M_D_CPU0_SA_DQ<30>")
	)
	(segment
		(start 283.496512 -231.787192)
		(end 283.72689 -231.787192)
		(width 0.14478)
		(layer "In4.Cu")
		(net "M_D_CPU0_SA_DQ<30>")
	)
	(segment
		(start 333.684118 -243.351558)
		(end 333.6925 -243.346732)
		(width 0.0889)
		(layer "In4.Cu")
		(net "M_D_CPU0_SA_DQ<30>")
	)
	(segment
		(start 336.869786 -243.346732)
		(end 336.878168 -243.351558)
		(width 0.0889)
		(layer "In4.Cu")
		(net "M_D_CPU0_SA_DQ<30>")
	)
	(segment
		(start 338.70265 -243.325396)
		(end 338.725002 -243.408708)
		(width 0.0889)
		(layer "In4.Cu")
		(net "M_D_CPU0_SA_DQ<30>")
	)
	(arc
		(start 327.50125 -243.364258)
		(mid 327.774279 -243.427577)
		(end 328.044048 -243.351558)
		(width 0.0889)
		(layer "In4.Cu")
		(net "M_D_CPU0_SA_DQ<30>")
	)
	(arc
		(start 333.6925 -243.346732)
		(mid 333.876008 -243.301238)
		(end 334.05826 -243.351558)
		(width 0.0889)
		(layer "In4.Cu")
		(net "M_D_CPU0_SA_DQ<30>")
	)
	(arc
		(start 335.938114 -243.351558)
		(mid 336.22107 -243.427735)
		(end 336.504026 -243.351558)
		(width 0.0889)
		(layer "In4.Cu")
		(net "M_D_CPU0_SA_DQ<30>")
	)
	(arc
		(start 329.924156 -243.351558)
		(mid 330.1111 -243.301303)
		(end 330.298044 -243.351558)
		(width 0.0889)
		(layer "In4.Cu")
		(net "M_D_CPU0_SA_DQ<30>")
	)
	(arc
		(start 337.452462 -243.346732)
		(mid 337.63597 -243.301238)
		(end 337.818222 -243.351558)
		(width 0.0889)
		(layer "In4.Cu")
		(net "M_D_CPU0_SA_DQ<30>")
	)
	(arc
		(start 329.358244 -243.351558)
		(mid 329.6412 -243.427735)
		(end 329.924156 -243.351558)
		(width 0.0889)
		(layer "In4.Cu")
		(net "M_D_CPU0_SA_DQ<30>")
	)
	(arc
		(start 333.118206 -243.351558)
		(mid 333.401162 -243.427735)
		(end 333.684118 -243.351558)
		(width 0.0889)
		(layer "In4.Cu")
		(net "M_D_CPU0_SA_DQ<30>")
	)
	(arc
		(start 332.178152 -243.351558)
		(mid 332.461108 -243.427735)
		(end 332.744064 -243.351558)
		(width 0.0889)
		(layer "In4.Cu")
		(net "M_D_CPU0_SA_DQ<30>")
	)
	(arc
		(start 328.992484 -243.346732)
		(mid 329.175992 -243.301238)
		(end 329.358244 -243.351558)
		(width 0.0889)
		(layer "In4.Cu")
		(net "M_D_CPU0_SA_DQ<30>")
	)
	(arc
		(start 334.05826 -243.351558)
		(mid 334.341216 -243.427735)
		(end 334.624172 -243.351558)
		(width 0.0889)
		(layer "In4.Cu")
		(net "M_D_CPU0_SA_DQ<30>")
	)
	(arc
		(start 326.351138 -243.300504)
		(mid 326.448641 -243.313519)
		(end 326.539352 -243.351558)
		(width 0.0889)
		(layer "In4.Cu")
		(net "M_D_CPU0_SA_DQ<30>")
	)
	(arc
		(start 338.384134 -243.351558)
		(mid 338.540453 -243.302563)
		(end 338.70265 -243.325396)
		(width 0.0889)
		(layer "In4.Cu")
		(net "M_D_CPU0_SA_DQ<30>")
	)
	(arc
		(start 330.863956 -243.351558)
		(mid 331.046207 -243.301208)
		(end 331.229716 -243.346732)
		(width 0.0889)
		(layer "In4.Cu")
		(net "M_D_CPU0_SA_DQ<30>")
	)
	(arc
		(start 334.624172 -243.351558)
		(mid 334.811116 -243.301303)
		(end 334.99806 -243.351558)
		(width 0.0889)
		(layer "In4.Cu")
		(net "M_D_CPU0_SA_DQ<30>")
	)
	(arc
		(start 336.878168 -243.351558)
		(mid 337.161124 -243.427735)
		(end 337.44408 -243.351558)
		(width 0.0889)
		(layer "In4.Cu")
		(net "M_D_CPU0_SA_DQ<30>")
	)
	(arc
		(start 334.99806 -243.351558)
		(mid 335.281016 -243.427735)
		(end 335.563972 -243.351558)
		(width 0.0889)
		(layer "In4.Cu")
		(net "M_D_CPU0_SA_DQ<30>")
	)
	(arc
		(start 331.80401 -243.351558)
		(mid 331.986261 -243.301208)
		(end 332.16977 -243.346732)
		(width 0.0889)
		(layer "In4.Cu")
		(net "M_D_CPU0_SA_DQ<30>")
	)
	(arc
		(start 327.106534 -243.351558)
		(mid 327.282654 -243.30158)
		(end 327.461372 -243.341398)
		(width 0.0889)
		(layer "In4.Cu")
		(net "M_D_CPU0_SA_DQ<30>")
	)
	(arc
		(start 337.818222 -243.351558)
		(mid 338.101178 -243.427735)
		(end 338.384134 -243.351558)
		(width 0.0889)
		(layer "In4.Cu")
		(net "M_D_CPU0_SA_DQ<30>")
	)
	(arc
		(start 336.504026 -243.351558)
		(mid 336.686277 -243.301208)
		(end 336.869786 -243.346732)
		(width 0.0889)
		(layer "In4.Cu")
		(net "M_D_CPU0_SA_DQ<30>")
	)
	(arc
		(start 328.41819 -243.351558)
		(mid 328.701146 -243.427735)
		(end 328.984102 -243.351558)
		(width 0.0889)
		(layer "In4.Cu")
		(net "M_D_CPU0_SA_DQ<30>")
	)
	(arc
		(start 330.298044 -243.351558)
		(mid 330.581 -243.427735)
		(end 330.863956 -243.351558)
		(width 0.0889)
		(layer "In4.Cu")
		(net "M_D_CPU0_SA_DQ<30>")
	)
	(arc
		(start 328.044048 -243.351558)
		(mid 328.226299 -243.301208)
		(end 328.409808 -243.346732)
		(width 0.0889)
		(layer "In4.Cu")
		(net "M_D_CPU0_SA_DQ<30>")
	)
	(arc
		(start 332.752446 -243.346732)
		(mid 332.935954 -243.301238)
		(end 333.118206 -243.351558)
		(width 0.0889)
		(layer "In4.Cu")
		(net "M_D_CPU0_SA_DQ<30>")
	)
	(arc
		(start 331.238098 -243.351558)
		(mid 331.521054 -243.427735)
		(end 331.80401 -243.351558)
		(width 0.0889)
		(layer "In4.Cu")
		(net "M_D_CPU0_SA_DQ<30>")
	)
	(arc
		(start 326.539352 -243.351558)
		(mid 326.809509 -243.42832)
		(end 327.083166 -243.365274)
		(width 0.0889)
		(layer "In4.Cu")
		(net "M_D_CPU0_SA_DQ<30>")
	)
	(arc
		(start 335.563972 -243.351558)
		(mid 335.746223 -243.301208)
		(end 335.929732 -243.346732)
		(width 0.0889)
		(layer "In4.Cu")
		(net "M_D_CPU0_SA_DQ<30>")
	)
	(segment
		(start 339.03793 -226.120198)
		(end 338.571078 -225.85426)
		(width 0.10668)
		(layer "F.Cu")
		(net "M_D_CPU0_SA_DQ<2>")
	)
	(segment
		(start 329.034394 -221.30385)
		(end 329.034394 -221.521528)
		(width 0.0889)
		(layer "In4.Cu")
		(net "M_D_CPU0_SA_DQ<2>")
	)
	(segment
		(start 280.635964 -198.185024)
		(end 281.06116 -198.61022)
		(width 0.14478)
		(layer "In4.Cu")
		(net "M_D_CPU0_SA_DQ<2>")
	)
	(segment
		(start 329.034394 -219.73921)
		(end 329.034394 -221.30385)
		(width 0.14478)
		(layer "In4.Cu")
		(net "M_D_CPU0_SA_DQ<2>")
	)
	(segment
		(start 297.312334 -198.61022)
		(end 298.162472 -197.760082)
		(width 0.14478)
		(layer "In4.Cu")
		(net "M_D_CPU0_SA_DQ<2>")
	)
	(segment
		(start 338.70265 -225.505518)
		(end 338.725002 -225.58883)
		(width 0.0889)
		(layer "In4.Cu")
		(net "M_D_CPU0_SA_DQ<2>")
	)
	(segment
		(start 329.828144 -223.101662)
		(end 329.859894 -223.11995)
		(width 0.0889)
		(layer "In4.Cu")
		(net "M_D_CPU0_SA_DQ<2>")
	)
	(segment
		(start 282.540202 -198.61022)
		(end 282.77058 -198.61022)
		(width 0.14478)
		(layer "In4.Cu")
		(net "M_D_CPU0_SA_DQ<2>")
	)
	(segment
		(start 298.162472 -197.760082)
		(end 301.196502 -197.760082)
		(width 0.14478)
		(layer "In4.Cu")
		(net "M_D_CPU0_SA_DQ<2>")
	)
	(segment
		(start 282.77058 -198.61022)
		(end 282.933648 -198.447152)
		(width 0.14478)
		(layer "In4.Cu")
		(net "M_D_CPU0_SA_DQ<2>")
	)
	(segment
		(start 281.82062 -198.447152)
		(end 281.82062 -198.16826)
		(width 0.14478)
		(layer "In4.Cu")
		(net "M_D_CPU0_SA_DQ<2>")
	)
	(segment
		(start 333.684118 -225.53168)
		(end 333.6925 -225.526854)
		(width 0.0889)
		(layer "In4.Cu")
		(net "M_D_CPU0_SA_DQ<2>")
	)
	(segment
		(start 294.357806 -198.61022)
		(end 297.312334 -198.61022)
		(width 0.14478)
		(layer "In4.Cu")
		(net "M_D_CPU0_SA_DQ<2>")
	)
	(segment
		(start 283.327094 -198.015352)
		(end 283.490162 -198.17842)
		(width 0.14478)
		(layer "In4.Cu")
		(net "M_D_CPU0_SA_DQ<2>")
	)
	(segment
		(start 282.214066 -198.005192)
		(end 282.377134 -198.16826)
		(width 0.14478)
		(layer "In4.Cu")
		(net "M_D_CPU0_SA_DQ<2>")
	)
	(segment
		(start 281.657552 -198.61022)
		(end 281.82062 -198.447152)
		(width 0.14478)
		(layer "In4.Cu")
		(net "M_D_CPU0_SA_DQ<2>")
	)
	(segment
		(start 330.261722 -223.890586)
		(end 330.298044 -223.911668)
		(width 0.0889)
		(layer "In4.Cu")
		(net "M_D_CPU0_SA_DQ<2>")
	)
	(segment
		(start 293.507668 -197.760082)
		(end 294.357806 -198.61022)
		(width 0.14478)
		(layer "In4.Cu")
		(net "M_D_CPU0_SA_DQ<2>")
	)
	(segment
		(start 302.04664 -198.61022)
		(end 307.905404 -198.61022)
		(width 0.14478)
		(layer "In4.Cu")
		(net "M_D_CPU0_SA_DQ<2>")
	)
	(segment
		(start 335.929732 -225.526854)
		(end 335.938114 -225.53168)
		(width 0.0889)
		(layer "In4.Cu")
		(net "M_D_CPU0_SA_DQ<2>")
	)
	(segment
		(start 281.06116 -198.61022)
		(end 281.657552 -198.61022)
		(width 0.14478)
		(layer "In4.Cu")
		(net "M_D_CPU0_SA_DQ<2>")
	)
	(segment
		(start 331.198982 -225.50882)
		(end 331.238098 -225.53168)
		(width 0.0889)
		(layer "In4.Cu")
		(net "M_D_CPU0_SA_DQ<2>")
	)
	(segment
		(start 332.16977 -225.526854)
		(end 332.178152 -225.53168)
		(width 0.0889)
		(layer "In4.Cu")
		(net "M_D_CPU0_SA_DQ<2>")
	)
	(segment
		(start 281.82062 -198.16826)
		(end 281.983688 -198.005192)
		(width 0.14478)
		(layer "In4.Cu")
		(net "M_D_CPU0_SA_DQ<2>")
	)
	(segment
		(start 282.933648 -198.447152)
		(end 282.933648 -198.17842)
		(width 0.14478)
		(layer "In4.Cu")
		(net "M_D_CPU0_SA_DQ<2>")
	)
	(segment
		(start 283.096716 -198.015352)
		(end 283.327094 -198.015352)
		(width 0.14478)
		(layer "In4.Cu")
		(net "M_D_CPU0_SA_DQ<2>")
	)
	(segment
		(start 289.82416 -198.61022)
		(end 290.674298 -197.760082)
		(width 0.14478)
		(layer "In4.Cu")
		(net "M_D_CPU0_SA_DQ<2>")
	)
	(segment
		(start 329.789028 -223.078802)
		(end 329.828144 -223.101662)
		(width 0.0889)
		(layer "In4.Cu")
		(net "M_D_CPU0_SA_DQ<2>")
	)
	(segment
		(start 283.490162 -198.447152)
		(end 283.65323 -198.61022)
		(width 0.14478)
		(layer "In4.Cu")
		(net "M_D_CPU0_SA_DQ<2>")
	)
	(segment
		(start 330.768198 -224.721674)
		(end 330.798678 -224.739454)
		(width 0.0889)
		(layer "In4.Cu")
		(net "M_D_CPU0_SA_DQ<2>")
	)
	(segment
		(start 332.744064 -225.53168)
		(end 332.752446 -225.526854)
		(width 0.0889)
		(layer "In4.Cu")
		(net "M_D_CPU0_SA_DQ<2>")
	)
	(segment
		(start 336.869786 -225.526854)
		(end 336.878168 -225.53168)
		(width 0.0889)
		(layer "In4.Cu")
		(net "M_D_CPU0_SA_DQ<2>")
	)
	(segment
		(start 283.65323 -198.61022)
		(end 289.82416 -198.61022)
		(width 0.14478)
		(layer "In4.Cu")
		(net "M_D_CPU0_SA_DQ<2>")
	)
	(segment
		(start 282.377134 -198.447152)
		(end 282.540202 -198.61022)
		(width 0.14478)
		(layer "In4.Cu")
		(net "M_D_CPU0_SA_DQ<2>")
	)
	(segment
		(start 307.905404 -198.61022)
		(end 329.034394 -219.73921)
		(width 0.14478)
		(layer "In4.Cu")
		(net "M_D_CPU0_SA_DQ<2>")
	)
	(segment
		(start 282.933648 -198.17842)
		(end 283.096716 -198.015352)
		(width 0.14478)
		(layer "In4.Cu")
		(net "M_D_CPU0_SA_DQ<2>")
	)
	(segment
		(start 301.196502 -197.760082)
		(end 302.04664 -198.61022)
		(width 0.14478)
		(layer "In4.Cu")
		(net "M_D_CPU0_SA_DQ<2>")
	)
	(segment
		(start 290.674298 -197.760082)
		(end 293.507668 -197.760082)
		(width 0.14478)
		(layer "In4.Cu")
		(net "M_D_CPU0_SA_DQ<2>")
	)
	(segment
		(start 330.298044 -223.911668)
		(end 330.329794 -223.929956)
		(width 0.0889)
		(layer "In4.Cu")
		(net "M_D_CPU0_SA_DQ<2>")
	)
	(segment
		(start 329.034394 -221.521528)
		(end 329.545696 -222.03283)
		(width 0.0889)
		(layer "In4.Cu")
		(net "M_D_CPU0_SA_DQ<2>")
	)
	(segment
		(start 282.377134 -198.16826)
		(end 282.377134 -198.447152)
		(width 0.14478)
		(layer "In4.Cu")
		(net "M_D_CPU0_SA_DQ<2>")
	)
	(segment
		(start 337.44408 -225.53168)
		(end 337.452462 -225.526854)
		(width 0.0889)
		(layer "In4.Cu")
		(net "M_D_CPU0_SA_DQ<2>")
	)
	(segment
		(start 281.983688 -198.005192)
		(end 282.214066 -198.005192)
		(width 0.14478)
		(layer "In4.Cu")
		(net "M_D_CPU0_SA_DQ<2>")
	)
	(segment
		(start 330.729082 -224.698814)
		(end 330.768198 -224.721674)
		(width 0.0889)
		(layer "In4.Cu")
		(net "M_D_CPU0_SA_DQ<2>")
	)
	(segment
		(start 283.490162 -198.17842)
		(end 283.490162 -198.447152)
		(width 0.14478)
		(layer "In4.Cu")
		(net "M_D_CPU0_SA_DQ<2>")
	)
	(segment
		(start 338.725002 -225.58883)
		(end 338.571078 -225.85426)
		(width 0.0889)
		(layer "In4.Cu")
		(net "M_D_CPU0_SA_DQ<2>")
	)
	(segment
		(start 329.545696 -222.03283)
		(end 329.545696 -222.614236)
		(width 0.0889)
		(layer "In4.Cu")
		(net "M_D_CPU0_SA_DQ<2>")
	)
	(arc
		(start 330.48575 -224.234248)
		(mid 330.550265 -224.496467)
		(end 330.729082 -224.698814)
		(width 0.0889)
		(layer "In4.Cu")
		(net "M_D_CPU0_SA_DQ<2>")
	)
	(arc
		(start 336.504026 -225.53168)
		(mid 336.686277 -225.48133)
		(end 336.869786 -225.526854)
		(width 0.0889)
		(layer "In4.Cu")
		(net "M_D_CPU0_SA_DQ<2>")
	)
	(arc
		(start 333.118206 -225.53168)
		(mid 333.401162 -225.607857)
		(end 333.684118 -225.53168)
		(width 0.0889)
		(layer "In4.Cu")
		(net "M_D_CPU0_SA_DQ<2>")
	)
	(arc
		(start 338.384134 -225.53168)
		(mid 338.540453 -225.482685)
		(end 338.70265 -225.505518)
		(width 0.0889)
		(layer "In4.Cu")
		(net "M_D_CPU0_SA_DQ<2>")
	)
	(arc
		(start 329.545696 -222.614236)
		(mid 329.610211 -222.876455)
		(end 329.789028 -223.078802)
		(width 0.0889)
		(layer "In4.Cu")
		(net "M_D_CPU0_SA_DQ<2>")
	)
	(arc
		(start 333.6925 -225.526854)
		(mid 333.876008 -225.48136)
		(end 334.05826 -225.53168)
		(width 0.0889)
		(layer "In4.Cu")
		(net "M_D_CPU0_SA_DQ<2>")
	)
	(arc
		(start 332.178152 -225.53168)
		(mid 332.461108 -225.607857)
		(end 332.744064 -225.53168)
		(width 0.0889)
		(layer "In4.Cu")
		(net "M_D_CPU0_SA_DQ<2>")
	)
	(arc
		(start 330.798678 -224.739454)
		(mid 330.914105 -224.87283)
		(end 330.95565 -225.044254)
		(width 0.0889)
		(layer "In4.Cu")
		(net "M_D_CPU0_SA_DQ<2>")
	)
	(arc
		(start 337.452462 -225.526854)
		(mid 337.63597 -225.48136)
		(end 337.818222 -225.53168)
		(width 0.0889)
		(layer "In4.Cu")
		(net "M_D_CPU0_SA_DQ<2>")
	)
	(arc
		(start 330.01585 -223.424242)
		(mid 330.081086 -223.687833)
		(end 330.261722 -223.890586)
		(width 0.0889)
		(layer "In4.Cu")
		(net "M_D_CPU0_SA_DQ<2>")
	)
	(arc
		(start 332.752446 -225.526854)
		(mid 332.935954 -225.48136)
		(end 333.118206 -225.53168)
		(width 0.0889)
		(layer "In4.Cu")
		(net "M_D_CPU0_SA_DQ<2>")
	)
	(arc
		(start 337.818222 -225.53168)
		(mid 338.101178 -225.607857)
		(end 338.384134 -225.53168)
		(width 0.0889)
		(layer "In4.Cu")
		(net "M_D_CPU0_SA_DQ<2>")
	)
	(arc
		(start 330.95565 -225.044254)
		(mid 331.020165 -225.306473)
		(end 331.198982 -225.50882)
		(width 0.0889)
		(layer "In4.Cu")
		(net "M_D_CPU0_SA_DQ<2>")
	)
	(arc
		(start 331.238098 -225.53168)
		(mid 331.521054 -225.607857)
		(end 331.80401 -225.53168)
		(width 0.0889)
		(layer "In4.Cu")
		(net "M_D_CPU0_SA_DQ<2>")
	)
	(arc
		(start 330.329794 -223.929956)
		(mid 330.44447 -224.06329)
		(end 330.48575 -224.234248)
		(width 0.0889)
		(layer "In4.Cu")
		(net "M_D_CPU0_SA_DQ<2>")
	)
	(arc
		(start 331.80401 -225.53168)
		(mid 331.986261 -225.48133)
		(end 332.16977 -225.526854)
		(width 0.0889)
		(layer "In4.Cu")
		(net "M_D_CPU0_SA_DQ<2>")
	)
	(arc
		(start 334.99806 -225.53168)
		(mid 335.281016 -225.607857)
		(end 335.563972 -225.53168)
		(width 0.0889)
		(layer "In4.Cu")
		(net "M_D_CPU0_SA_DQ<2>")
	)
	(arc
		(start 336.878168 -225.53168)
		(mid 337.161124 -225.607857)
		(end 337.44408 -225.53168)
		(width 0.0889)
		(layer "In4.Cu")
		(net "M_D_CPU0_SA_DQ<2>")
	)
	(arc
		(start 335.563972 -225.53168)
		(mid 335.746223 -225.48133)
		(end 335.929732 -225.526854)
		(width 0.0889)
		(layer "In4.Cu")
		(net "M_D_CPU0_SA_DQ<2>")
	)
	(arc
		(start 329.859894 -223.11995)
		(mid 329.97457 -223.253284)
		(end 330.01585 -223.424242)
		(width 0.0889)
		(layer "In4.Cu")
		(net "M_D_CPU0_SA_DQ<2>")
	)
	(arc
		(start 335.938114 -225.53168)
		(mid 336.22107 -225.607857)
		(end 336.504026 -225.53168)
		(width 0.0889)
		(layer "In4.Cu")
		(net "M_D_CPU0_SA_DQ<2>")
	)
	(arc
		(start 334.05826 -225.53168)
		(mid 334.341216 -225.607857)
		(end 334.624172 -225.53168)
		(width 0.0889)
		(layer "In4.Cu")
		(net "M_D_CPU0_SA_DQ<2>")
	)
	(arc
		(start 334.624172 -225.53168)
		(mid 334.811116 -225.481425)
		(end 334.99806 -225.53168)
		(width 0.0889)
		(layer "In4.Cu")
		(net "M_D_CPU0_SA_DQ<2>")
	)
	(segment
		(start 340.918038 -243.940076)
		(end 340.451186 -243.674138)
		(width 0.10668)
		(layer "F.Cu")
		(net "M_D_CPU0_SA_DQ<29>")
	)
	(segment
		(start 328.033634 -243.990622)
		(end 328.044048 -243.996718)
		(width 0.0889)
		(layer "In4.Cu")
		(net "M_D_CPU0_SA_DQ<29>")
	)
	(segment
		(start 306.42433 -233.062272)
		(end 306.652676 -233.062272)
		(width 0.14478)
		(layer "In4.Cu")
		(net "M_D_CPU0_SA_DQ<29>")
	)
	(segment
		(start 302.931576 -233.849672)
		(end 303.895506 -233.849672)
		(width 0.14478)
		(layer "In4.Cu")
		(net "M_D_CPU0_SA_DQ<29>")
	)
	(segment
		(start 293.498778 -232.610152)
		(end 294.348662 -233.460036)
		(width 0.14478)
		(layer "In4.Cu")
		(net "M_D_CPU0_SA_DQ<29>")
	)
	(segment
		(start 304.05705 -233.223816)
		(end 304.218594 -233.062272)
		(width 0.14478)
		(layer "In4.Cu")
		(net "M_D_CPU0_SA_DQ<29>")
	)
	(segment
		(start 284.736032 -233.035094)
		(end 285.160974 -233.460036)
		(width 0.14478)
		(layer "In4.Cu")
		(net "M_D_CPU0_SA_DQ<29>")
	)
	(segment
		(start 285.6865 -233.675682)
		(end 285.849568 -233.83875)
		(width 0.14478)
		(layer "In4.Cu")
		(net "M_D_CPU0_SA_DQ<29>")
	)
	(segment
		(start 300.93793 -232.610152)
		(end 301.787814 -233.460036)
		(width 0.14478)
		(layer "In4.Cu")
		(net "M_D_CPU0_SA_DQ<29>")
	)
	(segment
		(start 326.51954 -244.006878)
		(end 326.537828 -243.996464)
		(width 0.0889)
		(layer "In4.Cu")
		(net "M_D_CPU0_SA_DQ<29>")
	)
	(segment
		(start 306.262786 -233.223816)
		(end 306.42433 -233.062272)
		(width 0.14478)
		(layer "In4.Cu")
		(net "M_D_CPU0_SA_DQ<29>")
	)
	(segment
		(start 336.869786 -244.001544)
		(end 336.878168 -243.996718)
		(width 0.0889)
		(layer "In4.Cu")
		(net "M_D_CPU0_SA_DQ<29>")
	)
	(segment
		(start 286.799528 -233.675682)
		(end 286.962596 -233.83875)
		(width 0.14478)
		(layer "In4.Cu")
		(net "M_D_CPU0_SA_DQ<29>")
	)
	(segment
		(start 324.12686 -243.050314)
		(end 324.595998 -243.519452)
		(width 0.0889)
		(layer "In4.Cu")
		(net "M_D_CPU0_SA_DQ<29>")
	)
	(segment
		(start 305.549808 -233.062272)
		(end 305.711352 -233.223816)
		(width 0.14478)
		(layer "In4.Cu")
		(net "M_D_CPU0_SA_DQ<29>")
	)
	(segment
		(start 317.133986 -243.050314)
		(end 323.882258 -243.050314)
		(width 0.14478)
		(layer "In4.Cu")
		(net "M_D_CPU0_SA_DQ<29>")
	)
	(segment
		(start 340.200742 -243.964968)
		(end 340.297008 -243.939568)
		(width 0.0889)
		(layer "In4.Cu")
		(net "M_D_CPU0_SA_DQ<29>")
	)
	(segment
		(start 304.218594 -233.062272)
		(end 304.44694 -233.062272)
		(width 0.14478)
		(layer "In4.Cu")
		(net "M_D_CPU0_SA_DQ<29>")
	)
	(segment
		(start 285.6865 -233.623104)
		(end 285.6865 -233.675682)
		(width 0.14478)
		(layer "In4.Cu")
		(net "M_D_CPU0_SA_DQ<29>")
	)
	(segment
		(start 331.229716 -244.001544)
		(end 331.238098 -243.996718)
		(width 0.0889)
		(layer "In4.Cu")
		(net "M_D_CPU0_SA_DQ<29>")
	)
	(segment
		(start 287.192974 -233.83875)
		(end 287.356042 -233.675682)
		(width 0.14478)
		(layer "In4.Cu")
		(net "M_D_CPU0_SA_DQ<29>")
	)
	(segment
		(start 286.63646 -233.081322)
		(end 286.799528 -233.24439)
		(width 0.14478)
		(layer "In4.Cu")
		(net "M_D_CPU0_SA_DQ<29>")
	)
	(segment
		(start 326.537828 -243.996464)
		(end 326.543416 -243.993162)
		(width 0.0889)
		(layer "In4.Cu")
		(net "M_D_CPU0_SA_DQ<29>")
	)
	(segment
		(start 294.348662 -233.460036)
		(end 297.346878 -233.460036)
		(width 0.14478)
		(layer "In4.Cu")
		(net "M_D_CPU0_SA_DQ<29>")
	)
	(segment
		(start 302.768508 -233.237278)
		(end 302.768508 -233.686604)
		(width 0.14478)
		(layer "In4.Cu")
		(net "M_D_CPU0_SA_DQ<29>")
	)
	(segment
		(start 306.81422 -233.223816)
		(end 306.81422 -233.298492)
		(width 0.14478)
		(layer "In4.Cu")
		(net "M_D_CPU0_SA_DQ<29>")
	)
	(segment
		(start 340.297008 -243.939568)
		(end 340.451186 -243.674138)
		(width 0.0889)
		(layer "In4.Cu")
		(net "M_D_CPU0_SA_DQ<29>")
	)
	(segment
		(start 285.523432 -233.460036)
		(end 285.6865 -233.623104)
		(width 0.14478)
		(layer "In4.Cu")
		(net "M_D_CPU0_SA_DQ<29>")
	)
	(segment
		(start 302.768508 -233.686604)
		(end 302.931576 -233.849672)
		(width 0.14478)
		(layer "In4.Cu")
		(net "M_D_CPU0_SA_DQ<29>")
	)
	(segment
		(start 302.60544 -233.07421)
		(end 302.768508 -233.237278)
		(width 0.14478)
		(layer "In4.Cu")
		(net "M_D_CPU0_SA_DQ<29>")
	)
	(segment
		(start 304.998374 -233.8578)
		(end 305.159918 -233.696256)
		(width 0.14478)
		(layer "In4.Cu")
		(net "M_D_CPU0_SA_DQ<29>")
	)
	(segment
		(start 325.221092 -243.519452)
		(end 325.622158 -243.920518)
		(width 0.0889)
		(layer "In4.Cu")
		(net "M_D_CPU0_SA_DQ<29>")
	)
	(segment
		(start 286.243014 -233.24439)
		(end 286.406082 -233.081322)
		(width 0.14478)
		(layer "In4.Cu")
		(net "M_D_CPU0_SA_DQ<29>")
	)
	(segment
		(start 305.872896 -233.8578)
		(end 306.101242 -233.8578)
		(width 0.14478)
		(layer "In4.Cu")
		(net "M_D_CPU0_SA_DQ<29>")
	)
	(segment
		(start 306.262786 -233.696256)
		(end 306.262786 -233.223816)
		(width 0.14478)
		(layer "In4.Cu")
		(net "M_D_CPU0_SA_DQ<29>")
	)
	(segment
		(start 286.799528 -233.24439)
		(end 286.799528 -233.675682)
		(width 0.14478)
		(layer "In4.Cu")
		(net "M_D_CPU0_SA_DQ<29>")
	)
	(segment
		(start 285.160974 -233.460036)
		(end 285.523432 -233.460036)
		(width 0.14478)
		(layer "In4.Cu")
		(net "M_D_CPU0_SA_DQ<29>")
	)
	(segment
		(start 286.406082 -233.081322)
		(end 286.63646 -233.081322)
		(width 0.14478)
		(layer "In4.Cu")
		(net "M_D_CPU0_SA_DQ<29>")
	)
	(segment
		(start 337.44408 -243.996718)
		(end 337.452462 -244.001544)
		(width 0.0889)
		(layer "In4.Cu")
		(net "M_D_CPU0_SA_DQ<29>")
	)
	(segment
		(start 305.711352 -233.696256)
		(end 305.872896 -233.8578)
		(width 0.14478)
		(layer "In4.Cu")
		(net "M_D_CPU0_SA_DQ<29>")
	)
	(segment
		(start 302.048926 -233.460036)
		(end 302.211994 -233.296968)
		(width 0.14478)
		(layer "In4.Cu")
		(net "M_D_CPU0_SA_DQ<29>")
	)
	(segment
		(start 333.684118 -243.996718)
		(end 333.6925 -244.001544)
		(width 0.0889)
		(layer "In4.Cu")
		(net "M_D_CPU0_SA_DQ<29>")
	)
	(segment
		(start 290.673282 -232.610152)
		(end 293.498778 -232.610152)
		(width 0.14478)
		(layer "In4.Cu")
		(net "M_D_CPU0_SA_DQ<29>")
	)
	(segment
		(start 307.543708 -233.460036)
		(end 317.133986 -243.050314)
		(width 0.14478)
		(layer "In4.Cu")
		(net "M_D_CPU0_SA_DQ<29>")
	)
	(segment
		(start 306.81422 -233.298492)
		(end 306.975764 -233.460036)
		(width 0.14478)
		(layer "In4.Cu")
		(net "M_D_CPU0_SA_DQ<29>")
	)
	(segment
		(start 286.962596 -233.83875)
		(end 287.192974 -233.83875)
		(width 0.14478)
		(layer "In4.Cu")
		(net "M_D_CPU0_SA_DQ<29>")
	)
	(segment
		(start 306.652676 -233.062272)
		(end 306.81422 -233.223816)
		(width 0.14478)
		(layer "In4.Cu")
		(net "M_D_CPU0_SA_DQ<29>")
	)
	(segment
		(start 304.608484 -233.223816)
		(end 304.608484 -233.696256)
		(width 0.14478)
		(layer "In4.Cu")
		(net "M_D_CPU0_SA_DQ<29>")
	)
	(segment
		(start 305.321462 -233.062272)
		(end 305.549808 -233.062272)
		(width 0.14478)
		(layer "In4.Cu")
		(net "M_D_CPU0_SA_DQ<29>")
	)
	(segment
		(start 287.51911 -233.460036)
		(end 289.823398 -233.460036)
		(width 0.14478)
		(layer "In4.Cu")
		(net "M_D_CPU0_SA_DQ<29>")
	)
	(segment
		(start 323.882258 -243.050314)
		(end 324.12686 -243.050314)
		(width 0.0889)
		(layer "In4.Cu")
		(net "M_D_CPU0_SA_DQ<29>")
	)
	(segment
		(start 332.16977 -244.001544)
		(end 332.178152 -243.996718)
		(width 0.0889)
		(layer "In4.Cu")
		(net "M_D_CPU0_SA_DQ<29>")
	)
	(segment
		(start 328.409808 -244.001544)
		(end 328.41819 -243.996718)
		(width 0.0889)
		(layer "In4.Cu")
		(net "M_D_CPU0_SA_DQ<29>")
	)
	(segment
		(start 305.159918 -233.696256)
		(end 305.159918 -233.223816)
		(width 0.14478)
		(layer "In4.Cu")
		(net "M_D_CPU0_SA_DQ<29>")
	)
	(segment
		(start 305.159918 -233.223816)
		(end 305.321462 -233.062272)
		(width 0.14478)
		(layer "In4.Cu")
		(net "M_D_CPU0_SA_DQ<29>")
	)
	(segment
		(start 324.595998 -243.519452)
		(end 325.221092 -243.519452)
		(width 0.0889)
		(layer "In4.Cu")
		(net "M_D_CPU0_SA_DQ<29>")
	)
	(segment
		(start 306.975764 -233.460036)
		(end 307.543708 -233.460036)
		(width 0.14478)
		(layer "In4.Cu")
		(net "M_D_CPU0_SA_DQ<29>")
	)
	(segment
		(start 304.608484 -233.696256)
		(end 304.770028 -233.8578)
		(width 0.14478)
		(layer "In4.Cu")
		(net "M_D_CPU0_SA_DQ<29>")
	)
	(segment
		(start 304.05705 -233.688128)
		(end 304.05705 -233.223816)
		(width 0.14478)
		(layer "In4.Cu")
		(net "M_D_CPU0_SA_DQ<29>")
	)
	(segment
		(start 286.243014 -233.675682)
		(end 286.243014 -233.24439)
		(width 0.14478)
		(layer "In4.Cu")
		(net "M_D_CPU0_SA_DQ<29>")
	)
	(segment
		(start 325.622158 -243.920518)
		(end 325.880476 -243.920518)
		(width 0.0889)
		(layer "In4.Cu")
		(net "M_D_CPU0_SA_DQ<29>")
	)
	(segment
		(start 339.689694 -244.001544)
		(end 339.698076 -243.996718)
		(width 0.0889)
		(layer "In4.Cu")
		(net "M_D_CPU0_SA_DQ<29>")
	)
	(segment
		(start 301.787814 -233.460036)
		(end 302.048926 -233.460036)
		(width 0.14478)
		(layer "In4.Cu")
		(net "M_D_CPU0_SA_DQ<29>")
	)
	(segment
		(start 285.849568 -233.83875)
		(end 286.079946 -233.83875)
		(width 0.14478)
		(layer "In4.Cu")
		(net "M_D_CPU0_SA_DQ<29>")
	)
	(segment
		(start 304.44694 -233.062272)
		(end 304.608484 -233.223816)
		(width 0.14478)
		(layer "In4.Cu")
		(net "M_D_CPU0_SA_DQ<29>")
	)
	(segment
		(start 297.346878 -233.460036)
		(end 298.196762 -232.610152)
		(width 0.14478)
		(layer "In4.Cu")
		(net "M_D_CPU0_SA_DQ<29>")
	)
	(segment
		(start 287.356042 -233.623104)
		(end 287.51911 -233.460036)
		(width 0.14478)
		(layer "In4.Cu")
		(net "M_D_CPU0_SA_DQ<29>")
	)
	(segment
		(start 286.079946 -233.83875)
		(end 286.243014 -233.675682)
		(width 0.14478)
		(layer "In4.Cu")
		(net "M_D_CPU0_SA_DQ<29>")
	)
	(segment
		(start 306.101242 -233.8578)
		(end 306.262786 -233.696256)
		(width 0.14478)
		(layer "In4.Cu")
		(net "M_D_CPU0_SA_DQ<29>")
	)
	(segment
		(start 287.356042 -233.675682)
		(end 287.356042 -233.623104)
		(width 0.14478)
		(layer "In4.Cu")
		(net "M_D_CPU0_SA_DQ<29>")
	)
	(segment
		(start 305.711352 -233.223816)
		(end 305.711352 -233.696256)
		(width 0.14478)
		(layer "In4.Cu")
		(net "M_D_CPU0_SA_DQ<29>")
	)
	(segment
		(start 289.823398 -233.460036)
		(end 290.673282 -232.610152)
		(width 0.14478)
		(layer "In4.Cu")
		(net "M_D_CPU0_SA_DQ<29>")
	)
	(segment
		(start 303.895506 -233.849672)
		(end 304.05705 -233.688128)
		(width 0.14478)
		(layer "In4.Cu")
		(net "M_D_CPU0_SA_DQ<29>")
	)
	(segment
		(start 302.211994 -233.296968)
		(end 302.211994 -233.237278)
		(width 0.14478)
		(layer "In4.Cu")
		(net "M_D_CPU0_SA_DQ<29>")
	)
	(segment
		(start 328.984102 -243.996718)
		(end 328.992484 -244.001544)
		(width 0.0889)
		(layer "In4.Cu")
		(net "M_D_CPU0_SA_DQ<29>")
	)
	(segment
		(start 327.103232 -243.996718)
		(end 327.111614 -244.001544)
		(width 0.0889)
		(layer "In4.Cu")
		(net "M_D_CPU0_SA_DQ<29>")
	)
	(segment
		(start 302.375062 -233.07421)
		(end 302.60544 -233.07421)
		(width 0.14478)
		(layer "In4.Cu")
		(net "M_D_CPU0_SA_DQ<29>")
	)
	(segment
		(start 298.196762 -232.610152)
		(end 300.93793 -232.610152)
		(width 0.14478)
		(layer "In4.Cu")
		(net "M_D_CPU0_SA_DQ<29>")
	)
	(segment
		(start 335.929732 -244.001544)
		(end 335.938114 -243.996718)
		(width 0.0889)
		(layer "In4.Cu")
		(net "M_D_CPU0_SA_DQ<29>")
	)
	(segment
		(start 304.770028 -233.8578)
		(end 304.998374 -233.8578)
		(width 0.14478)
		(layer "In4.Cu")
		(net "M_D_CPU0_SA_DQ<29>")
	)
	(segment
		(start 332.744064 -243.996718)
		(end 332.752446 -244.001544)
		(width 0.0889)
		(layer "In4.Cu")
		(net "M_D_CPU0_SA_DQ<29>")
	)
	(segment
		(start 302.211994 -233.237278)
		(end 302.375062 -233.07421)
		(width 0.14478)
		(layer "In4.Cu")
		(net "M_D_CPU0_SA_DQ<29>")
	)
	(arc
		(start 339.323934 -243.996718)
		(mid 339.506185 -244.047068)
		(end 339.689694 -244.001544)
		(width 0.0889)
		(layer "In4.Cu")
		(net "M_D_CPU0_SA_DQ<29>")
	)
	(arc
		(start 334.99806 -243.996718)
		(mid 335.281016 -243.920541)
		(end 335.563972 -243.996718)
		(width 0.0889)
		(layer "In4.Cu")
		(net "M_D_CPU0_SA_DQ<29>")
	)
	(arc
		(start 330.298044 -243.996718)
		(mid 330.581 -243.920541)
		(end 330.863956 -243.996718)
		(width 0.0889)
		(layer "In4.Cu")
		(net "M_D_CPU0_SA_DQ<29>")
	)
	(arc
		(start 332.178152 -243.996718)
		(mid 332.461108 -243.920541)
		(end 332.744064 -243.996718)
		(width 0.0889)
		(layer "In4.Cu")
		(net "M_D_CPU0_SA_DQ<29>")
	)
	(arc
		(start 335.563972 -243.996718)
		(mid 335.746223 -244.047068)
		(end 335.929732 -244.001544)
		(width 0.0889)
		(layer "In4.Cu")
		(net "M_D_CPU0_SA_DQ<29>")
	)
	(arc
		(start 331.80401 -243.996718)
		(mid 331.986261 -244.047068)
		(end 332.16977 -244.001544)
		(width 0.0889)
		(layer "In4.Cu")
		(net "M_D_CPU0_SA_DQ<29>")
	)
	(arc
		(start 331.238098 -243.996718)
		(mid 331.521054 -243.920541)
		(end 331.80401 -243.996718)
		(width 0.0889)
		(layer "In4.Cu")
		(net "M_D_CPU0_SA_DQ<29>")
	)
	(arc
		(start 326.543416 -243.993162)
		(mid 326.823805 -243.920493)
		(end 327.103232 -243.996718)
		(width 0.0889)
		(layer "In4.Cu")
		(net "M_D_CPU0_SA_DQ<29>")
	)
	(arc
		(start 325.880476 -243.920518)
		(mid 326.027133 -243.939855)
		(end 326.163686 -243.996718)
		(width 0.0889)
		(layer "In4.Cu")
		(net "M_D_CPU0_SA_DQ<29>")
	)
	(arc
		(start 338.758022 -243.996718)
		(mid 339.040978 -243.920541)
		(end 339.323934 -243.996718)
		(width 0.0889)
		(layer "In4.Cu")
		(net "M_D_CPU0_SA_DQ<29>")
	)
	(arc
		(start 327.111614 -244.001544)
		(mid 327.295376 -244.04716)
		(end 327.477882 -243.996718)
		(width 0.0889)
		(layer "In4.Cu")
		(net "M_D_CPU0_SA_DQ<29>")
	)
	(arc
		(start 338.384134 -243.996718)
		(mid 338.571078 -244.046973)
		(end 338.758022 -243.996718)
		(width 0.0889)
		(layer "In4.Cu")
		(net "M_D_CPU0_SA_DQ<29>")
	)
	(arc
		(start 337.452462 -244.001544)
		(mid 337.63597 -244.047038)
		(end 337.818222 -243.996718)
		(width 0.0889)
		(layer "In4.Cu")
		(net "M_D_CPU0_SA_DQ<29>")
	)
	(arc
		(start 328.41819 -243.996718)
		(mid 328.701146 -243.920541)
		(end 328.984102 -243.996718)
		(width 0.0889)
		(layer "In4.Cu")
		(net "M_D_CPU0_SA_DQ<29>")
	)
	(arc
		(start 329.358244 -243.996718)
		(mid 329.6412 -243.920541)
		(end 329.924156 -243.996718)
		(width 0.0889)
		(layer "In4.Cu")
		(net "M_D_CPU0_SA_DQ<29>")
	)
	(arc
		(start 333.118206 -243.996718)
		(mid 333.401162 -243.920541)
		(end 333.684118 -243.996718)
		(width 0.0889)
		(layer "In4.Cu")
		(net "M_D_CPU0_SA_DQ<29>")
	)
	(arc
		(start 333.6925 -244.001544)
		(mid 333.876008 -244.047038)
		(end 334.05826 -243.996718)
		(width 0.0889)
		(layer "In4.Cu")
		(net "M_D_CPU0_SA_DQ<29>")
	)
	(arc
		(start 334.624172 -243.996718)
		(mid 334.811116 -244.046973)
		(end 334.99806 -243.996718)
		(width 0.0889)
		(layer "In4.Cu")
		(net "M_D_CPU0_SA_DQ<29>")
	)
	(arc
		(start 336.504026 -243.996718)
		(mid 336.686277 -244.047068)
		(end 336.869786 -244.001544)
		(width 0.0889)
		(layer "In4.Cu")
		(net "M_D_CPU0_SA_DQ<29>")
	)
	(arc
		(start 332.752446 -244.001544)
		(mid 332.935954 -244.047038)
		(end 333.118206 -243.996718)
		(width 0.0889)
		(layer "In4.Cu")
		(net "M_D_CPU0_SA_DQ<29>")
	)
	(arc
		(start 335.938114 -243.996718)
		(mid 336.22107 -243.920541)
		(end 336.504026 -243.996718)
		(width 0.0889)
		(layer "In4.Cu")
		(net "M_D_CPU0_SA_DQ<29>")
	)
	(arc
		(start 339.698076 -243.996718)
		(mid 339.945672 -243.92154)
		(end 340.200742 -243.964968)
		(width 0.0889)
		(layer "In4.Cu")
		(net "M_D_CPU0_SA_DQ<29>")
	)
	(arc
		(start 328.044048 -243.996718)
		(mid 328.226299 -244.047068)
		(end 328.409808 -244.001544)
		(width 0.0889)
		(layer "In4.Cu")
		(net "M_D_CPU0_SA_DQ<29>")
	)
	(arc
		(start 334.05826 -243.996718)
		(mid 334.341216 -243.920541)
		(end 334.624172 -243.996718)
		(width 0.0889)
		(layer "In4.Cu")
		(net "M_D_CPU0_SA_DQ<29>")
	)
	(arc
		(start 330.863956 -243.996718)
		(mid 331.046207 -244.047068)
		(end 331.229716 -244.001544)
		(width 0.0889)
		(layer "In4.Cu")
		(net "M_D_CPU0_SA_DQ<29>")
	)
	(arc
		(start 336.878168 -243.996718)
		(mid 337.161124 -243.920541)
		(end 337.44408 -243.996718)
		(width 0.0889)
		(layer "In4.Cu")
		(net "M_D_CPU0_SA_DQ<29>")
	)
	(arc
		(start 337.818222 -243.996718)
		(mid 338.101178 -243.920541)
		(end 338.384134 -243.996718)
		(width 0.0889)
		(layer "In4.Cu")
		(net "M_D_CPU0_SA_DQ<29>")
	)
	(arc
		(start 327.477882 -243.996718)
		(mid 327.754949 -243.920447)
		(end 328.033634 -243.990622)
		(width 0.0889)
		(layer "In4.Cu")
		(net "M_D_CPU0_SA_DQ<29>")
	)
	(arc
		(start 328.992484 -244.001544)
		(mid 329.175992 -244.047038)
		(end 329.358244 -243.996718)
		(width 0.0889)
		(layer "In4.Cu")
		(net "M_D_CPU0_SA_DQ<29>")
	)
	(arc
		(start 329.924156 -243.996718)
		(mid 330.1111 -244.046973)
		(end 330.298044 -243.996718)
		(width 0.0889)
		(layer "In4.Cu")
		(net "M_D_CPU0_SA_DQ<29>")
	)
	(arc
		(start 326.163686 -243.996718)
		(mid 326.340314 -244.046951)
		(end 326.51954 -244.006878)
		(width 0.0889)
		(layer "In4.Cu")
		(net "M_D_CPU0_SA_DQ<29>")
	)
	(segment
		(start 339.508084 -243.13007)
		(end 339.040978 -242.864132)
		(width 0.10668)
		(layer "F.Cu")
		(net "M_D_CPU0_SA_DQ<28>")
	)
	(segment
		(start 309.153306 -233.357674)
		(end 309.394098 -233.598466)
		(width 0.14478)
		(layer "In4.Cu")
		(net "M_D_CPU0_SA_DQ<28>")
	)
	(segment
		(start 306.430934 -232.158032)
		(end 306.65928 -232.158032)
		(width 0.14478)
		(layer "In4.Cu")
		(net "M_D_CPU0_SA_DQ<28>")
	)
	(segment
		(start 315.877194 -240.38052)
		(end 316.105286 -240.38052)
		(width 0.14478)
		(layer "In4.Cu")
		(net "M_D_CPU0_SA_DQ<28>")
	)
	(segment
		(start 302.559466 -231.991662)
		(end 302.722534 -232.15473)
		(width 0.14478)
		(layer "In4.Cu")
		(net "M_D_CPU0_SA_DQ<28>")
	)
	(segment
		(start 306.65928 -232.158032)
		(end 306.820824 -231.996488)
		(width 0.14478)
		(layer "In4.Cu")
		(net "M_D_CPU0_SA_DQ<28>")
	)
	(segment
		(start 316.956186 -241.160554)
		(end 317.196978 -241.401346)
		(width 0.14478)
		(layer "In4.Cu")
		(net "M_D_CPU0_SA_DQ<28>")
	)
	(segment
		(start 303.672494 -231.991662)
		(end 303.835562 -232.15473)
		(width 0.14478)
		(layer "In4.Cu")
		(net "M_D_CPU0_SA_DQ<28>")
	)
	(segment
		(start 303.835562 -232.15473)
		(end 304.06594 -232.15473)
		(width 0.14478)
		(layer "In4.Cu")
		(net "M_D_CPU0_SA_DQ<28>")
	)
	(segment
		(start 305.166522 -231.996488)
		(end 305.328066 -232.158032)
		(width 0.14478)
		(layer "In4.Cu")
		(net "M_D_CPU0_SA_DQ<28>")
	)
	(segment
		(start 317.196978 -241.700304)
		(end 317.43777 -241.941096)
		(width 0.14478)
		(layer "In4.Cu")
		(net "M_D_CPU0_SA_DQ<28>")
	)
	(segment
		(start 325.837296 -243.110004)
		(end 326.351138 -243.110004)
		(width 0.0889)
		(layer "In4.Cu")
		(net "M_D_CPU0_SA_DQ<28>")
	)
	(segment
		(start 315.636402 -240.139728)
		(end 315.877194 -240.38052)
		(width 0.14478)
		(layer "In4.Cu")
		(net "M_D_CPU0_SA_DQ<28>")
	)
	(segment
		(start 293.50843 -230.919782)
		(end 294.358314 -231.769666)
		(width 0.14478)
		(layer "In4.Cu")
		(net "M_D_CPU0_SA_DQ<28>")
	)
	(segment
		(start 302.396398 -231.760014)
		(end 302.559466 -231.923082)
		(width 0.14478)
		(layer "In4.Cu")
		(net "M_D_CPU0_SA_DQ<28>")
	)
	(segment
		(start 291.531802 -231.30129)
		(end 291.69487 -231.138222)
		(width 0.14478)
		(layer "In4.Cu")
		(net "M_D_CPU0_SA_DQ<28>")
	)
	(segment
		(start 291.138356 -231.073198)
		(end 291.138356 -231.138222)
		(width 0.14478)
		(layer "In4.Cu")
		(net "M_D_CPU0_SA_DQ<28>")
	)
	(segment
		(start 298.65066 -231.133142)
		(end 298.813728 -231.29621)
		(width 0.14478)
		(layer "In4.Cu")
		(net "M_D_CPU0_SA_DQ<28>")
	)
	(segment
		(start 305.328066 -232.158032)
		(end 305.556412 -232.158032)
		(width 0.14478)
		(layer "In4.Cu")
		(net "M_D_CPU0_SA_DQ<28>")
	)
	(segment
		(start 286.238696 -231.769666)
		(end 286.614362 -231.769666)
		(width 0.14478)
		(layer "In4.Cu")
		(net "M_D_CPU0_SA_DQ<28>")
	)
	(segment
		(start 310.713882 -234.91825)
		(end 310.954674 -235.159042)
		(width 0.14478)
		(layer "In4.Cu")
		(net "M_D_CPU0_SA_DQ<28>")
	)
	(segment
		(start 331.33411 -243.186712)
		(end 331.342492 -243.191538)
		(width 0.0889)
		(layer "In4.Cu")
		(net "M_D_CPU0_SA_DQ<28>")
	)
	(segment
		(start 308.61381 -232.818178)
		(end 308.61381 -233.117136)
		(width 0.14478)
		(layer "In4.Cu")
		(net "M_D_CPU0_SA_DQ<28>")
	)
	(segment
		(start 285.509462 -231.121458)
		(end 285.67253 -230.95839)
		(width 0.14478)
		(layer "In4.Cu")
		(net "M_D_CPU0_SA_DQ<28>")
	)
	(segment
		(start 297.337226 -231.769666)
		(end 298.18711 -230.919782)
		(width 0.14478)
		(layer "In4.Cu")
		(net "M_D_CPU0_SA_DQ<28>")
	)
	(segment
		(start 310.64327 -234.918504)
		(end 310.713882 -234.91825)
		(width 0.14478)
		(layer "In4.Cu")
		(net "M_D_CPU0_SA_DQ<28>")
	)
	(segment
		(start 327.57491 -243.186458)
		(end 327.594976 -243.197888)
		(width 0.0889)
		(layer "In4.Cu")
		(net "M_D_CPU0_SA_DQ<28>")
	)
	(segment
		(start 285.346394 -231.760014)
		(end 285.509462 -231.596946)
		(width 0.14478)
		(layer "In4.Cu")
		(net "M_D_CPU0_SA_DQ<28>")
	)
	(segment
		(start 317.43777 -241.941096)
		(end 317.665862 -241.941096)
		(width 0.14478)
		(layer "In4.Cu")
		(net "M_D_CPU0_SA_DQ<28>")
	)
	(segment
		(start 302.559466 -231.923082)
		(end 302.559466 -231.991662)
		(width 0.14478)
		(layer "In4.Cu")
		(net "M_D_CPU0_SA_DQ<28>")
	)
	(segment
		(start 316.41669 -240.920016)
		(end 316.657482 -241.160808)
		(width 0.14478)
		(layer "In4.Cu")
		(net "M_D_CPU0_SA_DQ<28>")
	)
	(segment
		(start 338.27974 -243.191538)
		(end 338.288122 -243.186712)
		(width 0.0889)
		(layer "In4.Cu")
		(net "M_D_CPU0_SA_DQ<28>")
	)
	(segment
		(start 313.835034 -238.039402)
		(end 314.075826 -238.280194)
		(width 0.14478)
		(layer "In4.Cu")
		(net "M_D_CPU0_SA_DQ<28>")
	)
	(segment
		(start 326.991726 -243.197634)
		(end 327.010522 -243.186712)
		(width 0.0889)
		(layer "In4.Cu")
		(net "M_D_CPU0_SA_DQ<28>")
	)
	(segment
		(start 291.301424 -231.30129)
		(end 291.531802 -231.30129)
		(width 0.14478)
		(layer "In4.Cu")
		(net "M_D_CPU0_SA_DQ<28>")
	)
	(segment
		(start 286.614362 -231.769666)
		(end 286.767778 -231.923082)
		(width 0.14478)
		(layer "In4.Cu")
		(net "M_D_CPU0_SA_DQ<28>")
	)
	(segment
		(start 306.982368 -231.769666)
		(end 307.565298 -231.769666)
		(width 0.14478)
		(layer "In4.Cu")
		(net "M_D_CPU0_SA_DQ<28>")
	)
	(segment
		(start 310.954674 -235.458)
		(end 311.195466 -235.698792)
		(width 0.14478)
		(layer "In4.Cu")
		(net "M_D_CPU0_SA_DQ<28>")
	)
	(segment
		(start 301.048166 -230.919782)
		(end 301.888398 -231.760014)
		(width 0.14478)
		(layer "In4.Cu")
		(net "M_D_CPU0_SA_DQ<28>")
	)
	(segment
		(start 316.41669 -240.621058)
		(end 316.41669 -240.920016)
		(width 0.14478)
		(layer "In4.Cu")
		(net "M_D_CPU0_SA_DQ<28>")
	)
	(segment
		(start 288.828988 -231.978962)
		(end 288.992056 -232.14203)
		(width 0.14478)
		(layer "In4.Cu")
		(net "M_D_CPU0_SA_DQ<28>")
	)
	(segment
		(start 304.229008 -231.991662)
		(end 304.229008 -231.923082)
		(width 0.14478)
		(layer "In4.Cu")
		(net "M_D_CPU0_SA_DQ<28>")
	)
	(segment
		(start 299.207174 -231.073198)
		(end 299.36059 -230.919782)
		(width 0.14478)
		(layer "In4.Cu")
		(net "M_D_CPU0_SA_DQ<28>")
	)
	(segment
		(start 312.274458 -236.478826)
		(end 312.51525 -236.719618)
		(width 0.14478)
		(layer "In4.Cu")
		(net "M_D_CPU0_SA_DQ<28>")
	)
	(segment
		(start 310.415178 -234.918504)
		(end 310.64327 -234.918504)
		(width 0.14478)
		(layer "In4.Cu")
		(net "M_D_CPU0_SA_DQ<28>")
	)
	(segment
		(start 289.54857 -231.760014)
		(end 289.823398 -231.760014)
		(width 0.14478)
		(layer "In4.Cu")
		(net "M_D_CPU0_SA_DQ<28>")
	)
	(segment
		(start 311.195466 -235.698792)
		(end 311.423558 -235.698792)
		(width 0.14478)
		(layer "In4.Cu")
		(net "M_D_CPU0_SA_DQ<28>")
	)
	(segment
		(start 298.813728 -231.29621)
		(end 299.044106 -231.29621)
		(width 0.14478)
		(layer "In4.Cu")
		(net "M_D_CPU0_SA_DQ<28>")
	)
	(segment
		(start 324.552818 -242.480592)
		(end 325.207884 -242.480592)
		(width 0.0889)
		(layer "In4.Cu")
		(net "M_D_CPU0_SA_DQ<28>")
	)
	(segment
		(start 307.565298 -231.769666)
		(end 308.61381 -232.818178)
		(width 0.14478)
		(layer "In4.Cu")
		(net "M_D_CPU0_SA_DQ<28>")
	)
	(segment
		(start 286.767778 -231.978962)
		(end 286.930846 -232.14203)
		(width 0.14478)
		(layer "In4.Cu")
		(net "M_D_CPU0_SA_DQ<28>")
	)
	(segment
		(start 303.11598 -231.991662)
		(end 303.11598 -231.923082)
		(width 0.14478)
		(layer "In4.Cu")
		(net "M_D_CPU0_SA_DQ<28>")
	)
	(segment
		(start 308.61381 -233.117136)
		(end 308.854602 -233.357928)
		(width 0.14478)
		(layer "In4.Cu")
		(net "M_D_CPU0_SA_DQ<28>")
	)
	(segment
		(start 286.767778 -231.923082)
		(end 286.767778 -231.978962)
		(width 0.14478)
		(layer "In4.Cu")
		(net "M_D_CPU0_SA_DQ<28>")
	)
	(segment
		(start 313.295538 -237.499906)
		(end 313.295538 -237.798864)
		(width 0.14478)
		(layer "In4.Cu")
		(net "M_D_CPU0_SA_DQ<28>")
	)
	(segment
		(start 285.509462 -231.596946)
		(end 285.509462 -231.121458)
		(width 0.14478)
		(layer "In4.Cu")
		(net "M_D_CPU0_SA_DQ<28>")
	)
	(segment
		(start 289.823398 -231.760014)
		(end 290.66363 -230.919782)
		(width 0.14478)
		(layer "In4.Cu")
		(net "M_D_CPU0_SA_DQ<28>")
	)
	(segment
		(start 285.160974 -231.760014)
		(end 285.346394 -231.760014)
		(width 0.14478)
		(layer "In4.Cu")
		(net "M_D_CPU0_SA_DQ<28>")
	)
	(segment
		(start 309.082694 -233.357928)
		(end 309.153306 -233.357674)
		(width 0.14478)
		(layer "In4.Cu")
		(net "M_D_CPU0_SA_DQ<28>")
	)
	(segment
		(start 305.8795 -231.769666)
		(end 306.107846 -231.769666)
		(width 0.14478)
		(layer "In4.Cu")
		(net "M_D_CPU0_SA_DQ<28>")
	)
	(segment
		(start 314.856114 -239.35944)
		(end 315.096906 -239.600232)
		(width 0.14478)
		(layer "In4.Cu")
		(net "M_D_CPU0_SA_DQ<28>")
	)
	(segment
		(start 314.075826 -238.579152)
		(end 314.316618 -238.819944)
		(width 0.14478)
		(layer "In4.Cu")
		(net "M_D_CPU0_SA_DQ<28>")
	)
	(segment
		(start 290.98494 -230.919782)
		(end 291.138356 -231.073198)
		(width 0.14478)
		(layer "In4.Cu")
		(net "M_D_CPU0_SA_DQ<28>")
	)
	(segment
		(start 314.856114 -239.060482)
		(end 314.856114 -239.35944)
		(width 0.14478)
		(layer "In4.Cu")
		(net "M_D_CPU0_SA_DQ<28>")
	)
	(segment
		(start 316.105286 -240.38052)
		(end 316.175898 -240.380266)
		(width 0.14478)
		(layer "In4.Cu")
		(net "M_D_CPU0_SA_DQ<28>")
	)
	(segment
		(start 334.519778 -243.191538)
		(end 334.52816 -243.186712)
		(width 0.0889)
		(layer "In4.Cu")
		(net "M_D_CPU0_SA_DQ<28>")
	)
	(segment
		(start 288.828988 -231.923082)
		(end 288.828988 -231.978962)
		(width 0.14478)
		(layer "In4.Cu")
		(net "M_D_CPU0_SA_DQ<28>")
	)
	(segment
		(start 298.18711 -230.919782)
		(end 298.497244 -230.919782)
		(width 0.14478)
		(layer "In4.Cu")
		(net "M_D_CPU0_SA_DQ<28>")
	)
	(segment
		(start 312.203846 -236.47908)
		(end 312.274458 -236.478826)
		(width 0.14478)
		(layer "In4.Cu")
		(net "M_D_CPU0_SA_DQ<28>")
	)
	(segment
		(start 313.295538 -237.798864)
		(end 313.53633 -238.039656)
		(width 0.14478)
		(layer "In4.Cu")
		(net "M_D_CPU0_SA_DQ<28>")
	)
	(segment
		(start 299.207174 -231.133142)
		(end 299.207174 -231.073198)
		(width 0.14478)
		(layer "In4.Cu")
		(net "M_D_CPU0_SA_DQ<28>")
	)
	(segment
		(start 329.819762 -243.191538)
		(end 329.828144 -243.186712)
		(width 0.0889)
		(layer "In4.Cu")
		(net "M_D_CPU0_SA_DQ<28>")
	)
	(segment
		(start 298.497244 -230.919782)
		(end 298.65066 -231.073198)
		(width 0.14478)
		(layer "In4.Cu")
		(net "M_D_CPU0_SA_DQ<28>")
	)
	(segment
		(start 306.107846 -231.769666)
		(end 306.26939 -231.93121)
		(width 0.14478)
		(layer "In4.Cu")
		(net "M_D_CPU0_SA_DQ<28>")
	)
	(segment
		(start 303.672494 -231.923082)
		(end 303.672494 -231.991662)
		(width 0.14478)
		(layer "In4.Cu")
		(net "M_D_CPU0_SA_DQ<28>")
	)
	(segment
		(start 317.736474 -241.940842)
		(end 317.936626 -242.140994)
		(width 0.14478)
		(layer "In4.Cu")
		(net "M_D_CPU0_SA_DQ<28>")
	)
	(segment
		(start 311.734962 -236.238288)
		(end 311.975754 -236.47908)
		(width 0.14478)
		(layer "In4.Cu")
		(net "M_D_CPU0_SA_DQ<28>")
	)
	(segment
		(start 287.161224 -232.14203)
		(end 287.324292 -231.978962)
		(width 0.14478)
		(layer "In4.Cu")
		(net "M_D_CPU0_SA_DQ<28>")
	)
	(segment
		(start 308.854602 -233.357928)
		(end 309.082694 -233.357928)
		(width 0.14478)
		(layer "In4.Cu")
		(net "M_D_CPU0_SA_DQ<28>")
	)
	(segment
		(start 287.324292 -231.923082)
		(end 287.477708 -231.769666)
		(width 0.14478)
		(layer "In4.Cu")
		(net "M_D_CPU0_SA_DQ<28>")
	)
	(segment
		(start 291.69487 -231.138222)
		(end 291.69487 -231.073198)
		(width 0.14478)
		(layer "In4.Cu")
		(net "M_D_CPU0_SA_DQ<28>")
	)
	(segment
		(start 309.63489 -234.138216)
		(end 309.862982 -234.138216)
		(width 0.14478)
		(layer "In4.Cu")
		(net "M_D_CPU0_SA_DQ<28>")
	)
	(segment
		(start 313.764422 -238.039656)
		(end 313.835034 -238.039402)
		(width 0.14478)
		(layer "In4.Cu")
		(net "M_D_CPU0_SA_DQ<28>")
	)
	(segment
		(start 298.65066 -231.073198)
		(end 298.65066 -231.133142)
		(width 0.14478)
		(layer "In4.Cu")
		(net "M_D_CPU0_SA_DQ<28>")
	)
	(segment
		(start 336.034126 -243.186712)
		(end 336.042508 -243.191538)
		(width 0.0889)
		(layer "In4.Cu")
		(net "M_D_CPU0_SA_DQ<28>")
	)
	(segment
		(start 323.869558 -242.140994)
		(end 324.21322 -242.140994)
		(width 0.0889)
		(layer "In4.Cu")
		(net "M_D_CPU0_SA_DQ<28>")
	)
	(segment
		(start 338.791042 -243.154962)
		(end 338.887054 -243.129562)
		(width 0.0889)
		(layer "In4.Cu")
		(net "M_D_CPU0_SA_DQ<28>")
	)
	(segment
		(start 309.394098 -233.897424)
		(end 309.63489 -234.138216)
		(width 0.14478)
		(layer "In4.Cu")
		(net "M_D_CPU0_SA_DQ<28>")
	)
	(segment
		(start 304.382424 -231.769666)
		(end 305.004978 -231.769666)
		(width 0.14478)
		(layer "In4.Cu")
		(net "M_D_CPU0_SA_DQ<28>")
	)
	(segment
		(start 315.636402 -239.84077)
		(end 315.636402 -240.139728)
		(width 0.14478)
		(layer "In4.Cu")
		(net "M_D_CPU0_SA_DQ<28>")
	)
	(segment
		(start 312.984134 -237.259368)
		(end 313.054746 -237.259114)
		(width 0.14478)
		(layer "In4.Cu")
		(net "M_D_CPU0_SA_DQ<28>")
	)
	(segment
		(start 312.756042 -237.259368)
		(end 312.984134 -237.259368)
		(width 0.14478)
		(layer "In4.Cu")
		(net "M_D_CPU0_SA_DQ<28>")
	)
	(segment
		(start 309.933594 -234.137962)
		(end 310.174386 -234.378754)
		(width 0.14478)
		(layer "In4.Cu")
		(net "M_D_CPU0_SA_DQ<28>")
	)
	(segment
		(start 289.222434 -232.14203)
		(end 289.385502 -231.978962)
		(width 0.14478)
		(layer "In4.Cu")
		(net "M_D_CPU0_SA_DQ<28>")
	)
	(segment
		(start 299.36059 -230.919782)
		(end 301.048166 -230.919782)
		(width 0.14478)
		(layer "In4.Cu")
		(net "M_D_CPU0_SA_DQ<28>")
	)
	(segment
		(start 313.054746 -237.259114)
		(end 313.295538 -237.499906)
		(width 0.14478)
		(layer "In4.Cu")
		(net "M_D_CPU0_SA_DQ<28>")
	)
	(segment
		(start 316.657482 -241.160808)
		(end 316.885574 -241.160808)
		(width 0.14478)
		(layer "In4.Cu")
		(net "M_D_CPU0_SA_DQ<28>")
	)
	(segment
		(start 285.67253 -230.95839)
		(end 285.902908 -230.95839)
		(width 0.14478)
		(layer "In4.Cu")
		(net "M_D_CPU0_SA_DQ<28>")
	)
	(segment
		(start 311.975754 -236.47908)
		(end 312.203846 -236.47908)
		(width 0.14478)
		(layer "In4.Cu")
		(net "M_D_CPU0_SA_DQ<28>")
	)
	(segment
		(start 291.848286 -230.919782)
		(end 293.50843 -230.919782)
		(width 0.14478)
		(layer "In4.Cu")
		(net "M_D_CPU0_SA_DQ<28>")
	)
	(segment
		(start 291.69487 -231.073198)
		(end 291.848286 -230.919782)
		(width 0.14478)
		(layer "In4.Cu")
		(net "M_D_CPU0_SA_DQ<28>")
	)
	(segment
		(start 310.174386 -234.677712)
		(end 310.415178 -234.918504)
		(width 0.14478)
		(layer "In4.Cu")
		(net "M_D_CPU0_SA_DQ<28>")
	)
	(segment
		(start 287.324292 -231.978962)
		(end 287.324292 -231.923082)
		(width 0.14478)
		(layer "In4.Cu")
		(net "M_D_CPU0_SA_DQ<28>")
	)
	(segment
		(start 310.954674 -235.159042)
		(end 310.954674 -235.458)
		(width 0.14478)
		(layer "In4.Cu")
		(net "M_D_CPU0_SA_DQ<28>")
	)
	(segment
		(start 290.66363 -230.919782)
		(end 290.98494 -230.919782)
		(width 0.14478)
		(layer "In4.Cu")
		(net "M_D_CPU0_SA_DQ<28>")
	)
	(segment
		(start 315.324998 -239.600232)
		(end 315.39561 -239.599978)
		(width 0.14478)
		(layer "In4.Cu")
		(net "M_D_CPU0_SA_DQ<28>")
	)
	(segment
		(start 305.166522 -231.93121)
		(end 305.166522 -231.996488)
		(width 0.14478)
		(layer "In4.Cu")
		(net "M_D_CPU0_SA_DQ<28>")
	)
	(segment
		(start 304.06594 -232.15473)
		(end 304.229008 -231.991662)
		(width 0.14478)
		(layer "In4.Cu")
		(net "M_D_CPU0_SA_DQ<28>")
	)
	(segment
		(start 311.423558 -235.698792)
		(end 311.49417 -235.698538)
		(width 0.14478)
		(layer "In4.Cu")
		(net "M_D_CPU0_SA_DQ<28>")
	)
	(segment
		(start 317.936626 -242.140994)
		(end 323.869558 -242.140994)
		(width 0.14478)
		(layer "In4.Cu")
		(net "M_D_CPU0_SA_DQ<28>")
	)
	(segment
		(start 305.004978 -231.769666)
		(end 305.166522 -231.93121)
		(width 0.14478)
		(layer "In4.Cu")
		(net "M_D_CPU0_SA_DQ<28>")
	)
	(segment
		(start 286.930846 -232.14203)
		(end 287.161224 -232.14203)
		(width 0.14478)
		(layer "In4.Cu")
		(net "M_D_CPU0_SA_DQ<28>")
	)
	(segment
		(start 303.279048 -231.760014)
		(end 303.509426 -231.760014)
		(width 0.14478)
		(layer "In4.Cu")
		(net "M_D_CPU0_SA_DQ<28>")
	)
	(segment
		(start 305.717956 -231.93121)
		(end 305.8795 -231.769666)
		(width 0.14478)
		(layer "In4.Cu")
		(net "M_D_CPU0_SA_DQ<28>")
	)
	(segment
		(start 305.556412 -232.158032)
		(end 305.717956 -231.996488)
		(width 0.14478)
		(layer "In4.Cu")
		(net "M_D_CPU0_SA_DQ<28>")
	)
	(segment
		(start 291.138356 -231.138222)
		(end 291.301424 -231.30129)
		(width 0.14478)
		(layer "In4.Cu")
		(net "M_D_CPU0_SA_DQ<28>")
	)
	(segment
		(start 316.175898 -240.380266)
		(end 316.41669 -240.621058)
		(width 0.14478)
		(layer "In4.Cu")
		(net "M_D_CPU0_SA_DQ<28>")
	)
	(segment
		(start 309.394098 -233.598466)
		(end 309.394098 -233.897424)
		(width 0.14478)
		(layer "In4.Cu")
		(net "M_D_CPU0_SA_DQ<28>")
	)
	(segment
		(start 324.21322 -242.140994)
		(end 324.552818 -242.480592)
		(width 0.0889)
		(layer "In4.Cu")
		(net "M_D_CPU0_SA_DQ<28>")
	)
	(segment
		(start 305.717956 -231.996488)
		(end 305.717956 -231.93121)
		(width 0.14478)
		(layer "In4.Cu")
		(net "M_D_CPU0_SA_DQ<28>")
	)
	(segment
		(start 325.207884 -242.480592)
		(end 325.837296 -243.110004)
		(width 0.0889)
		(layer "In4.Cu")
		(net "M_D_CPU0_SA_DQ<28>")
	)
	(segment
		(start 287.477708 -231.769666)
		(end 288.675572 -231.769666)
		(width 0.14478)
		(layer "In4.Cu")
		(net "M_D_CPU0_SA_DQ<28>")
	)
	(segment
		(start 304.229008 -231.923082)
		(end 304.382424 -231.769666)
		(width 0.14478)
		(layer "In4.Cu")
		(net "M_D_CPU0_SA_DQ<28>")
	)
	(segment
		(start 288.992056 -232.14203)
		(end 289.222434 -232.14203)
		(width 0.14478)
		(layer "In4.Cu")
		(net "M_D_CPU0_SA_DQ<28>")
	)
	(segment
		(start 288.675572 -231.769666)
		(end 288.828988 -231.923082)
		(width 0.14478)
		(layer "In4.Cu")
		(net "M_D_CPU0_SA_DQ<28>")
	)
	(segment
		(start 309.862982 -234.138216)
		(end 309.933594 -234.137962)
		(width 0.14478)
		(layer "In4.Cu")
		(net "M_D_CPU0_SA_DQ<28>")
	)
	(segment
		(start 315.39561 -239.599978)
		(end 315.636402 -239.84077)
		(width 0.14478)
		(layer "In4.Cu")
		(net "M_D_CPU0_SA_DQ<28>")
	)
	(segment
		(start 286.065976 -231.121458)
		(end 286.065976 -231.596946)
		(width 0.14478)
		(layer "In4.Cu")
		(net "M_D_CPU0_SA_DQ<28>")
	)
	(segment
		(start 306.26939 -231.996488)
		(end 306.430934 -232.158032)
		(width 0.14478)
		(layer "In4.Cu")
		(net "M_D_CPU0_SA_DQ<28>")
	)
	(segment
		(start 314.54471 -238.819944)
		(end 314.615322 -238.81969)
		(width 0.14478)
		(layer "In4.Cu")
		(net "M_D_CPU0_SA_DQ<28>")
	)
	(segment
		(start 312.51525 -236.719618)
		(end 312.51525 -237.018576)
		(width 0.14478)
		(layer "In4.Cu")
		(net "M_D_CPU0_SA_DQ<28>")
	)
	(segment
		(start 316.885574 -241.160808)
		(end 316.956186 -241.160554)
		(width 0.14478)
		(layer "In4.Cu")
		(net "M_D_CPU0_SA_DQ<28>")
	)
	(segment
		(start 327.55332 -243.174012)
		(end 327.57491 -243.186458)
		(width 0.0889)
		(layer "In4.Cu")
		(net "M_D_CPU0_SA_DQ<28>")
	)
	(segment
		(start 306.820824 -231.996488)
		(end 306.820824 -231.93121)
		(width 0.14478)
		(layer "In4.Cu")
		(net "M_D_CPU0_SA_DQ<28>")
	)
	(segment
		(start 314.615322 -238.81969)
		(end 314.856114 -239.060482)
		(width 0.14478)
		(layer "In4.Cu")
		(net "M_D_CPU0_SA_DQ<28>")
	)
	(segment
		(start 285.902908 -230.95839)
		(end 286.065976 -231.121458)
		(width 0.14478)
		(layer "In4.Cu")
		(net "M_D_CPU0_SA_DQ<28>")
	)
	(segment
		(start 314.075826 -238.280194)
		(end 314.075826 -238.579152)
		(width 0.14478)
		(layer "In4.Cu")
		(net "M_D_CPU0_SA_DQ<28>")
	)
	(segment
		(start 317.665862 -241.941096)
		(end 317.736474 -241.940842)
		(width 0.14478)
		(layer "In4.Cu")
		(net "M_D_CPU0_SA_DQ<28>")
	)
	(segment
		(start 313.53633 -238.039656)
		(end 313.764422 -238.039656)
		(width 0.14478)
		(layer "In4.Cu")
		(net "M_D_CPU0_SA_DQ<28>")
	)
	(segment
		(start 306.820824 -231.93121)
		(end 306.982368 -231.769666)
		(width 0.14478)
		(layer "In4.Cu")
		(net "M_D_CPU0_SA_DQ<28>")
	)
	(segment
		(start 303.11598 -231.923082)
		(end 303.279048 -231.760014)
		(width 0.14478)
		(layer "In4.Cu")
		(net "M_D_CPU0_SA_DQ<28>")
	)
	(segment
		(start 289.385502 -231.978962)
		(end 289.385502 -231.923082)
		(width 0.14478)
		(layer "In4.Cu")
		(net "M_D_CPU0_SA_DQ<28>")
	)
	(segment
		(start 286.065976 -231.596946)
		(end 286.238696 -231.769666)
		(width 0.14478)
		(layer "In4.Cu")
		(net "M_D_CPU0_SA_DQ<28>")
	)
	(segment
		(start 294.358314 -231.769666)
		(end 297.337226 -231.769666)
		(width 0.14478)
		(layer "In4.Cu")
		(net "M_D_CPU0_SA_DQ<28>")
	)
	(segment
		(start 314.316618 -238.819944)
		(end 314.54471 -238.819944)
		(width 0.14478)
		(layer "In4.Cu")
		(net "M_D_CPU0_SA_DQ<28>")
	)
	(segment
		(start 317.196978 -241.401346)
		(end 317.196978 -241.700304)
		(width 0.14478)
		(layer "In4.Cu")
		(net "M_D_CPU0_SA_DQ<28>")
	)
	(segment
		(start 289.385502 -231.923082)
		(end 289.54857 -231.760014)
		(width 0.14478)
		(layer "In4.Cu")
		(net "M_D_CPU0_SA_DQ<28>")
	)
	(segment
		(start 333.579724 -243.191538)
		(end 333.588106 -243.186712)
		(width 0.0889)
		(layer "In4.Cu")
		(net "M_D_CPU0_SA_DQ<28>")
	)
	(segment
		(start 310.174386 -234.378754)
		(end 310.174386 -234.677712)
		(width 0.14478)
		(layer "In4.Cu")
		(net "M_D_CPU0_SA_DQ<28>")
	)
	(segment
		(start 330.394056 -243.186712)
		(end 330.402438 -243.191538)
		(width 0.0889)
		(layer "In4.Cu")
		(net "M_D_CPU0_SA_DQ<28>")
	)
	(segment
		(start 338.887054 -243.129562)
		(end 339.040978 -242.864132)
		(width 0.0889)
		(layer "In4.Cu")
		(net "M_D_CPU0_SA_DQ<28>")
	)
	(segment
		(start 284.736032 -231.335072)
		(end 285.160974 -231.760014)
		(width 0.14478)
		(layer "In4.Cu")
		(net "M_D_CPU0_SA_DQ<28>")
	)
	(segment
		(start 306.26939 -231.93121)
		(end 306.26939 -231.996488)
		(width 0.14478)
		(layer "In4.Cu")
		(net "M_D_CPU0_SA_DQ<28>")
	)
	(segment
		(start 311.49417 -235.698538)
		(end 311.734962 -235.93933)
		(width 0.14478)
		(layer "In4.Cu")
		(net "M_D_CPU0_SA_DQ<28>")
	)
	(segment
		(start 301.888398 -231.760014)
		(end 302.396398 -231.760014)
		(width 0.14478)
		(layer "In4.Cu")
		(net "M_D_CPU0_SA_DQ<28>")
	)
	(segment
		(start 311.734962 -235.93933)
		(end 311.734962 -236.238288)
		(width 0.14478)
		(layer "In4.Cu")
		(net "M_D_CPU0_SA_DQ<28>")
	)
	(segment
		(start 335.094072 -243.186712)
		(end 335.102454 -243.191538)
		(width 0.0889)
		(layer "In4.Cu")
		(net "M_D_CPU0_SA_DQ<28>")
	)
	(segment
		(start 303.509426 -231.760014)
		(end 303.672494 -231.923082)
		(width 0.14478)
		(layer "In4.Cu")
		(net "M_D_CPU0_SA_DQ<28>")
	)
	(segment
		(start 315.096906 -239.600232)
		(end 315.324998 -239.600232)
		(width 0.14478)
		(layer "In4.Cu")
		(net "M_D_CPU0_SA_DQ<28>")
	)
	(segment
		(start 302.722534 -232.15473)
		(end 302.952912 -232.15473)
		(width 0.14478)
		(layer "In4.Cu")
		(net "M_D_CPU0_SA_DQ<28>")
	)
	(segment
		(start 302.952912 -232.15473)
		(end 303.11598 -231.991662)
		(width 0.14478)
		(layer "In4.Cu")
		(net "M_D_CPU0_SA_DQ<28>")
	)
	(segment
		(start 312.51525 -237.018576)
		(end 312.756042 -237.259368)
		(width 0.14478)
		(layer "In4.Cu")
		(net "M_D_CPU0_SA_DQ<28>")
	)
	(segment
		(start 299.044106 -231.29621)
		(end 299.207174 -231.133142)
		(width 0.14478)
		(layer "In4.Cu")
		(net "M_D_CPU0_SA_DQ<28>")
	)
	(arc
		(start 326.351138 -243.110004)
		(mid 326.498347 -243.129481)
		(end 326.635364 -243.186712)
		(width 0.0889)
		(layer "In4.Cu")
		(net "M_D_CPU0_SA_DQ<28>")
	)
	(arc
		(start 335.468214 -243.186712)
		(mid 335.75117 -243.110535)
		(end 336.034126 -243.186712)
		(width 0.0889)
		(layer "In4.Cu")
		(net "M_D_CPU0_SA_DQ<28>")
	)
	(arc
		(start 336.042508 -243.191538)
		(mid 336.226016 -243.237032)
		(end 336.408268 -243.186712)
		(width 0.0889)
		(layer "In4.Cu")
		(net "M_D_CPU0_SA_DQ<28>")
	)
	(arc
		(start 330.768198 -243.186712)
		(mid 331.051154 -243.110535)
		(end 331.33411 -243.186712)
		(width 0.0889)
		(layer "In4.Cu")
		(net "M_D_CPU0_SA_DQ<28>")
	)
	(arc
		(start 335.102454 -243.191538)
		(mid 335.285962 -243.237032)
		(end 335.468214 -243.186712)
		(width 0.0889)
		(layer "In4.Cu")
		(net "M_D_CPU0_SA_DQ<28>")
	)
	(arc
		(start 334.154018 -243.186712)
		(mid 334.336269 -243.237062)
		(end 334.519778 -243.191538)
		(width 0.0889)
		(layer "In4.Cu")
		(net "M_D_CPU0_SA_DQ<28>")
	)
	(arc
		(start 327.010522 -243.186712)
		(mid 327.280291 -243.110689)
		(end 327.55332 -243.174012)
		(width 0.0889)
		(layer "In4.Cu")
		(net "M_D_CPU0_SA_DQ<28>")
	)
	(arc
		(start 327.94829 -243.186712)
		(mid 328.231246 -243.110535)
		(end 328.514202 -243.186712)
		(width 0.0889)
		(layer "In4.Cu")
		(net "M_D_CPU0_SA_DQ<28>")
	)
	(arc
		(start 337.348068 -243.186712)
		(mid 337.631024 -243.110535)
		(end 337.91398 -243.186712)
		(width 0.0889)
		(layer "In4.Cu")
		(net "M_D_CPU0_SA_DQ<28>")
	)
	(arc
		(start 331.708252 -243.186712)
		(mid 331.991208 -243.110535)
		(end 332.274164 -243.186712)
		(width 0.0889)
		(layer "In4.Cu")
		(net "M_D_CPU0_SA_DQ<28>")
	)
	(arc
		(start 336.408268 -243.186712)
		(mid 336.691224 -243.110535)
		(end 336.97418 -243.186712)
		(width 0.0889)
		(layer "In4.Cu")
		(net "M_D_CPU0_SA_DQ<28>")
	)
	(arc
		(start 326.635364 -243.186712)
		(mid 326.812155 -243.237431)
		(end 326.991726 -243.197634)
		(width 0.0889)
		(layer "In4.Cu")
		(net "M_D_CPU0_SA_DQ<28>")
	)
	(arc
		(start 329.454002 -243.186712)
		(mid 329.636253 -243.237062)
		(end 329.819762 -243.191538)
		(width 0.0889)
		(layer "In4.Cu")
		(net "M_D_CPU0_SA_DQ<28>")
	)
	(arc
		(start 333.588106 -243.186712)
		(mid 333.871062 -243.110535)
		(end 334.154018 -243.186712)
		(width 0.0889)
		(layer "In4.Cu")
		(net "M_D_CPU0_SA_DQ<28>")
	)
	(arc
		(start 330.402438 -243.191538)
		(mid 330.585946 -243.237032)
		(end 330.768198 -243.186712)
		(width 0.0889)
		(layer "In4.Cu")
		(net "M_D_CPU0_SA_DQ<28>")
	)
	(arc
		(start 334.52816 -243.186712)
		(mid 334.811116 -243.110535)
		(end 335.094072 -243.186712)
		(width 0.0889)
		(layer "In4.Cu")
		(net "M_D_CPU0_SA_DQ<28>")
	)
	(arc
		(start 332.274164 -243.186712)
		(mid 332.461108 -243.236967)
		(end 332.648052 -243.186712)
		(width 0.0889)
		(layer "In4.Cu")
		(net "M_D_CPU0_SA_DQ<28>")
	)
	(arc
		(start 332.648052 -243.186712)
		(mid 332.931008 -243.110535)
		(end 333.213964 -243.186712)
		(width 0.0889)
		(layer "In4.Cu")
		(net "M_D_CPU0_SA_DQ<28>")
	)
	(arc
		(start 336.97418 -243.186712)
		(mid 337.161124 -243.236967)
		(end 337.348068 -243.186712)
		(width 0.0889)
		(layer "In4.Cu")
		(net "M_D_CPU0_SA_DQ<28>")
	)
	(arc
		(start 328.514202 -243.186712)
		(mid 328.701146 -243.236967)
		(end 328.88809 -243.186712)
		(width 0.0889)
		(layer "In4.Cu")
		(net "M_D_CPU0_SA_DQ<28>")
	)
	(arc
		(start 327.594976 -243.197888)
		(mid 327.773054 -243.236872)
		(end 327.94829 -243.186712)
		(width 0.0889)
		(layer "In4.Cu")
		(net "M_D_CPU0_SA_DQ<28>")
	)
	(arc
		(start 328.88809 -243.186712)
		(mid 329.171046 -243.110535)
		(end 329.454002 -243.186712)
		(width 0.0889)
		(layer "In4.Cu")
		(net "M_D_CPU0_SA_DQ<28>")
	)
	(arc
		(start 337.91398 -243.186712)
		(mid 338.096231 -243.237062)
		(end 338.27974 -243.191538)
		(width 0.0889)
		(layer "In4.Cu")
		(net "M_D_CPU0_SA_DQ<28>")
	)
	(arc
		(start 338.288122 -243.186712)
		(mid 338.535835 -243.111492)
		(end 338.791042 -243.154962)
		(width 0.0889)
		(layer "In4.Cu")
		(net "M_D_CPU0_SA_DQ<28>")
	)
	(arc
		(start 333.213964 -243.186712)
		(mid 333.396215 -243.237062)
		(end 333.579724 -243.191538)
		(width 0.0889)
		(layer "In4.Cu")
		(net "M_D_CPU0_SA_DQ<28>")
	)
	(arc
		(start 329.828144 -243.186712)
		(mid 330.1111 -243.110535)
		(end 330.394056 -243.186712)
		(width 0.0889)
		(layer "In4.Cu")
		(net "M_D_CPU0_SA_DQ<28>")
	)
	(arc
		(start 331.342492 -243.191538)
		(mid 331.526 -243.237032)
		(end 331.708252 -243.186712)
		(width 0.0889)
		(layer "In4.Cu")
		(net "M_D_CPU0_SA_DQ<28>")
	)
	(segment
		(start 340.447884 -241.510058)
		(end 339.981032 -241.24412)
		(width 0.10668)
		(layer "F.Cu")
		(net "M_D_CPU0_SA_DQ<27>")
	)
	(segment
		(start 318.8335 -239.782604)
		(end 323.886068 -239.782604)
		(width 0.14478)
		(layer "In4.Cu")
		(net "M_D_CPU0_SA_DQ<27>")
	)
	(segment
		(start 326.999346 -240.916714)
		(end 327.007728 -240.92154)
		(width 0.0889)
		(layer "In4.Cu")
		(net "M_D_CPU0_SA_DQ<27>")
	)
	(segment
		(start 302.04664 -228.360224)
		(end 308.659784 -228.360224)
		(width 0.14478)
		(layer "In4.Cu")
		(net "M_D_CPU0_SA_DQ<27>")
	)
	(segment
		(start 280.635964 -227.935028)
		(end 281.052016 -228.35108)
		(width 0.14478)
		(layer "In4.Cu")
		(net "M_D_CPU0_SA_DQ<27>")
	)
	(segment
		(start 323.886068 -239.782604)
		(end 324.02653 -239.782604)
		(width 0.0889)
		(layer "In4.Cu")
		(net "M_D_CPU0_SA_DQ<27>")
	)
	(segment
		(start 327.007728 -240.92154)
		(end 327.02246 -240.930176)
		(width 0.0889)
		(layer "In4.Cu")
		(net "M_D_CPU0_SA_DQ<27>")
	)
	(segment
		(start 325.764906 -240.99774)
		(end 326.351138 -240.99774)
		(width 0.0889)
		(layer "In4.Cu")
		(net "M_D_CPU0_SA_DQ<27>")
	)
	(segment
		(start 298.172124 -227.500434)
		(end 301.18685 -227.500434)
		(width 0.14478)
		(layer "In4.Cu")
		(net "M_D_CPU0_SA_DQ<27>")
	)
	(segment
		(start 336.034126 -240.92154)
		(end 336.042508 -240.916714)
		(width 0.0889)
		(layer "In4.Cu")
		(net "M_D_CPU0_SA_DQ<27>")
	)
	(segment
		(start 329.819762 -240.916714)
		(end 329.828144 -240.92154)
		(width 0.0889)
		(layer "In4.Cu")
		(net "M_D_CPU0_SA_DQ<27>")
	)
	(segment
		(start 327.939908 -240.916714)
		(end 327.94829 -240.92154)
		(width 0.0889)
		(layer "In4.Cu")
		(net "M_D_CPU0_SA_DQ<27>")
	)
	(segment
		(start 294.3479 -228.350318)
		(end 297.32224 -228.350318)
		(width 0.14478)
		(layer "In4.Cu")
		(net "M_D_CPU0_SA_DQ<27>")
	)
	(segment
		(start 338.27974 -240.916714)
		(end 338.288122 -240.92154)
		(width 0.0889)
		(layer "In4.Cu")
		(net "M_D_CPU0_SA_DQ<27>")
	)
	(segment
		(start 330.394056 -240.92154)
		(end 330.402438 -240.916714)
		(width 0.0889)
		(layer "In4.Cu")
		(net "M_D_CPU0_SA_DQ<27>")
	)
	(segment
		(start 325.175118 -240.407952)
		(end 325.764906 -240.99774)
		(width 0.0889)
		(layer "In4.Cu")
		(net "M_D_CPU0_SA_DQ<27>")
	)
	(segment
		(start 338.854034 -240.92154)
		(end 338.862416 -240.916714)
		(width 0.0889)
		(layer "In4.Cu")
		(net "M_D_CPU0_SA_DQ<27>")
	)
	(segment
		(start 340.13521 -240.97869)
		(end 339.981032 -241.24412)
		(width 0.0889)
		(layer "In4.Cu")
		(net "M_D_CPU0_SA_DQ<27>")
	)
	(segment
		(start 281.052016 -228.35108)
		(end 289.833304 -228.35108)
		(width 0.14478)
		(layer "In4.Cu")
		(net "M_D_CPU0_SA_DQ<27>")
	)
	(segment
		(start 293.498016 -227.500434)
		(end 294.3479 -228.350318)
		(width 0.14478)
		(layer "In4.Cu")
		(net "M_D_CPU0_SA_DQ<27>")
	)
	(segment
		(start 333.579724 -240.916714)
		(end 333.588106 -240.92154)
		(width 0.0889)
		(layer "In4.Cu")
		(net "M_D_CPU0_SA_DQ<27>")
	)
	(segment
		(start 324.651878 -240.407952)
		(end 325.175118 -240.407952)
		(width 0.0889)
		(layer "In4.Cu")
		(net "M_D_CPU0_SA_DQ<27>")
	)
	(segment
		(start 308.659784 -228.360224)
		(end 314.271914 -233.972354)
		(width 0.14478)
		(layer "In4.Cu")
		(net "M_D_CPU0_SA_DQ<27>")
	)
	(segment
		(start 301.18685 -227.500434)
		(end 302.04664 -228.360224)
		(width 0.14478)
		(layer "In4.Cu")
		(net "M_D_CPU0_SA_DQ<27>")
	)
	(segment
		(start 331.33411 -240.92154)
		(end 331.342492 -240.916714)
		(width 0.0889)
		(layer "In4.Cu")
		(net "M_D_CPU0_SA_DQ<27>")
	)
	(segment
		(start 314.271914 -233.972354)
		(end 314.271914 -235.221018)
		(width 0.14478)
		(layer "In4.Cu")
		(net "M_D_CPU0_SA_DQ<27>")
	)
	(segment
		(start 339.794088 -240.92154)
		(end 339.80247 -240.916714)
		(width 0.0889)
		(layer "In4.Cu")
		(net "M_D_CPU0_SA_DQ<27>")
	)
	(segment
		(start 335.094072 -240.92154)
		(end 335.102454 -240.916714)
		(width 0.0889)
		(layer "In4.Cu")
		(net "M_D_CPU0_SA_DQ<27>")
	)
	(segment
		(start 314.271914 -235.221018)
		(end 318.8335 -239.782604)
		(width 0.14478)
		(layer "In4.Cu")
		(net "M_D_CPU0_SA_DQ<27>")
	)
	(segment
		(start 334.519778 -240.916714)
		(end 334.52816 -240.92154)
		(width 0.0889)
		(layer "In4.Cu")
		(net "M_D_CPU0_SA_DQ<27>")
	)
	(segment
		(start 324.02653 -239.782604)
		(end 324.651878 -240.407952)
		(width 0.0889)
		(layer "In4.Cu")
		(net "M_D_CPU0_SA_DQ<27>")
	)
	(segment
		(start 297.32224 -228.350318)
		(end 298.172124 -227.500434)
		(width 0.14478)
		(layer "In4.Cu")
		(net "M_D_CPU0_SA_DQ<27>")
	)
	(segment
		(start 289.833304 -228.35108)
		(end 290.68395 -227.500434)
		(width 0.14478)
		(layer "In4.Cu")
		(net "M_D_CPU0_SA_DQ<27>")
	)
	(segment
		(start 290.68395 -227.500434)
		(end 293.498016 -227.500434)
		(width 0.14478)
		(layer "In4.Cu")
		(net "M_D_CPU0_SA_DQ<27>")
	)
	(segment
		(start 340.112858 -240.895378)
		(end 340.13521 -240.97869)
		(width 0.0889)
		(layer "In4.Cu")
		(net "M_D_CPU0_SA_DQ<27>")
	)
	(arc
		(start 339.80247 -240.916714)
		(mid 339.95534 -240.872073)
		(end 340.112858 -240.895378)
		(width 0.0889)
		(layer "In4.Cu")
		(net "M_D_CPU0_SA_DQ<27>")
	)
	(arc
		(start 335.102454 -240.916714)
		(mid 335.285962 -240.87122)
		(end 335.468214 -240.92154)
		(width 0.0889)
		(layer "In4.Cu")
		(net "M_D_CPU0_SA_DQ<27>")
	)
	(arc
		(start 336.408268 -240.92154)
		(mid 336.691224 -240.997717)
		(end 336.97418 -240.92154)
		(width 0.0889)
		(layer "In4.Cu")
		(net "M_D_CPU0_SA_DQ<27>")
	)
	(arc
		(start 331.708252 -240.92154)
		(mid 331.991208 -240.997717)
		(end 332.274164 -240.92154)
		(width 0.0889)
		(layer "In4.Cu")
		(net "M_D_CPU0_SA_DQ<27>")
	)
	(arc
		(start 336.97418 -240.92154)
		(mid 337.161124 -240.871285)
		(end 337.348068 -240.92154)
		(width 0.0889)
		(layer "In4.Cu")
		(net "M_D_CPU0_SA_DQ<27>")
	)
	(arc
		(start 332.648052 -240.92154)
		(mid 332.931008 -240.997717)
		(end 333.213964 -240.92154)
		(width 0.0889)
		(layer "In4.Cu")
		(net "M_D_CPU0_SA_DQ<27>")
	)
	(arc
		(start 337.91398 -240.92154)
		(mid 338.096231 -240.87119)
		(end 338.27974 -240.916714)
		(width 0.0889)
		(layer "In4.Cu")
		(net "M_D_CPU0_SA_DQ<27>")
	)
	(arc
		(start 333.588106 -240.92154)
		(mid 333.871062 -240.997717)
		(end 334.154018 -240.92154)
		(width 0.0889)
		(layer "In4.Cu")
		(net "M_D_CPU0_SA_DQ<27>")
	)
	(arc
		(start 329.454002 -240.92154)
		(mid 329.636253 -240.87119)
		(end 329.819762 -240.916714)
		(width 0.0889)
		(layer "In4.Cu")
		(net "M_D_CPU0_SA_DQ<27>")
	)
	(arc
		(start 333.213964 -240.92154)
		(mid 333.396215 -240.87119)
		(end 333.579724 -240.916714)
		(width 0.0889)
		(layer "In4.Cu")
		(net "M_D_CPU0_SA_DQ<27>")
	)
	(arc
		(start 334.154018 -240.92154)
		(mid 334.336269 -240.87119)
		(end 334.519778 -240.916714)
		(width 0.0889)
		(layer "In4.Cu")
		(net "M_D_CPU0_SA_DQ<27>")
	)
	(arc
		(start 329.828144 -240.92154)
		(mid 330.1111 -240.997717)
		(end 330.394056 -240.92154)
		(width 0.0889)
		(layer "In4.Cu")
		(net "M_D_CPU0_SA_DQ<27>")
	)
	(arc
		(start 327.02246 -240.930176)
		(mid 327.299189 -240.997859)
		(end 327.57364 -240.92154)
		(width 0.0889)
		(layer "In4.Cu")
		(net "M_D_CPU0_SA_DQ<27>")
	)
	(arc
		(start 336.042508 -240.916714)
		(mid 336.226016 -240.87122)
		(end 336.408268 -240.92154)
		(width 0.0889)
		(layer "In4.Cu")
		(net "M_D_CPU0_SA_DQ<27>")
	)
	(arc
		(start 339.228176 -240.92154)
		(mid 339.511132 -240.997717)
		(end 339.794088 -240.92154)
		(width 0.0889)
		(layer "In4.Cu")
		(net "M_D_CPU0_SA_DQ<27>")
	)
	(arc
		(start 330.768198 -240.92154)
		(mid 331.051154 -240.997717)
		(end 331.33411 -240.92154)
		(width 0.0889)
		(layer "In4.Cu")
		(net "M_D_CPU0_SA_DQ<27>")
	)
	(arc
		(start 330.402438 -240.916714)
		(mid 330.585946 -240.87122)
		(end 330.768198 -240.92154)
		(width 0.0889)
		(layer "In4.Cu")
		(net "M_D_CPU0_SA_DQ<27>")
	)
	(arc
		(start 338.288122 -240.92154)
		(mid 338.571078 -240.997717)
		(end 338.854034 -240.92154)
		(width 0.0889)
		(layer "In4.Cu")
		(net "M_D_CPU0_SA_DQ<27>")
	)
	(arc
		(start 335.468214 -240.92154)
		(mid 335.75117 -240.997717)
		(end 336.034126 -240.92154)
		(width 0.0889)
		(layer "In4.Cu")
		(net "M_D_CPU0_SA_DQ<27>")
	)
	(arc
		(start 337.348068 -240.92154)
		(mid 337.631024 -240.997717)
		(end 337.91398 -240.92154)
		(width 0.0889)
		(layer "In4.Cu")
		(net "M_D_CPU0_SA_DQ<27>")
	)
	(arc
		(start 326.634094 -240.92154)
		(mid 326.816091 -240.871318)
		(end 326.999346 -240.916714)
		(width 0.0889)
		(layer "In4.Cu")
		(net "M_D_CPU0_SA_DQ<27>")
	)
	(arc
		(start 328.88809 -240.92154)
		(mid 329.171046 -240.997717)
		(end 329.454002 -240.92154)
		(width 0.0889)
		(layer "In4.Cu")
		(net "M_D_CPU0_SA_DQ<27>")
	)
	(arc
		(start 327.57364 -240.92154)
		(mid 327.756145 -240.871063)
		(end 327.939908 -240.916714)
		(width 0.0889)
		(layer "In4.Cu")
		(net "M_D_CPU0_SA_DQ<27>")
	)
	(arc
		(start 328.514202 -240.92154)
		(mid 328.701146 -240.871285)
		(end 328.88809 -240.92154)
		(width 0.0889)
		(layer "In4.Cu")
		(net "M_D_CPU0_SA_DQ<27>")
	)
	(arc
		(start 338.862416 -240.916714)
		(mid 339.045924 -240.87122)
		(end 339.228176 -240.92154)
		(width 0.0889)
		(layer "In4.Cu")
		(net "M_D_CPU0_SA_DQ<27>")
	)
	(arc
		(start 327.94829 -240.92154)
		(mid 328.231246 -240.997717)
		(end 328.514202 -240.92154)
		(width 0.0889)
		(layer "In4.Cu")
		(net "M_D_CPU0_SA_DQ<27>")
	)
	(arc
		(start 334.52816 -240.92154)
		(mid 334.811116 -240.997717)
		(end 335.094072 -240.92154)
		(width 0.0889)
		(layer "In4.Cu")
		(net "M_D_CPU0_SA_DQ<27>")
	)
	(arc
		(start 326.351138 -240.99774)
		(mid 326.497655 -240.978354)
		(end 326.634094 -240.92154)
		(width 0.0889)
		(layer "In4.Cu")
		(net "M_D_CPU0_SA_DQ<27>")
	)
	(arc
		(start 331.342492 -240.916714)
		(mid 331.526 -240.87122)
		(end 331.708252 -240.92154)
		(width 0.0889)
		(layer "In4.Cu")
		(net "M_D_CPU0_SA_DQ<27>")
	)
	(arc
		(start 332.274164 -240.92154)
		(mid 332.461108 -240.871285)
		(end 332.648052 -240.92154)
		(width 0.0889)
		(layer "In4.Cu")
		(net "M_D_CPU0_SA_DQ<27>")
	)
	(segment
		(start 339.03793 -240.700052)
		(end 338.571078 -240.434114)
		(width 0.10668)
		(layer "F.Cu")
		(net "M_D_CPU0_SA_DQ<26>")
	)
	(segment
		(start 328.409808 -240.106708)
		(end 328.41819 -240.111534)
		(width 0.0889)
		(layer "In4.Cu")
		(net "M_D_CPU0_SA_DQ<26>")
	)
	(segment
		(start 290.674298 -225.810064)
		(end 293.507668 -225.810064)
		(width 0.14478)
		(layer "In4.Cu")
		(net "M_D_CPU0_SA_DQ<26>")
	)
	(segment
		(start 327.083166 -240.12525)
		(end 327.106534 -240.111534)
		(width 0.0889)
		(layer "In4.Cu")
		(net "M_D_CPU0_SA_DQ<26>")
	)
	(segment
		(start 281.06116 -226.660202)
		(end 282.894786 -226.660202)
		(width 0.14478)
		(layer "In4.Cu")
		(net "M_D_CPU0_SA_DQ<26>")
	)
	(segment
		(start 298.162472 -225.810064)
		(end 301.196502 -225.810064)
		(width 0.14478)
		(layer "In4.Cu")
		(net "M_D_CPU0_SA_DQ<26>")
	)
	(segment
		(start 324.17385 -238.873284)
		(end 324.352158 -239.051592)
		(width 0.0889)
		(layer "In4.Cu")
		(net "M_D_CPU0_SA_DQ<26>")
	)
	(segment
		(start 336.869786 -240.106708)
		(end 336.878168 -240.111534)
		(width 0.0889)
		(layer "In4.Cu")
		(net "M_D_CPU0_SA_DQ<26>")
	)
	(segment
		(start 315.211714 -233.640122)
		(end 315.211714 -234.888786)
		(width 0.14478)
		(layer "In4.Cu")
		(net "M_D_CPU0_SA_DQ<26>")
	)
	(segment
		(start 308.231794 -226.660202)
		(end 315.211714 -233.640122)
		(width 0.14478)
		(layer "In4.Cu")
		(net "M_D_CPU0_SA_DQ<26>")
	)
	(segment
		(start 293.507668 -225.810064)
		(end 294.357806 -226.660202)
		(width 0.14478)
		(layer "In4.Cu")
		(net "M_D_CPU0_SA_DQ<26>")
	)
	(segment
		(start 315.211714 -234.888786)
		(end 319.196212 -238.873284)
		(width 0.14478)
		(layer "In4.Cu")
		(net "M_D_CPU0_SA_DQ<26>")
	)
	(segment
		(start 280.635964 -226.235006)
		(end 281.06116 -226.660202)
		(width 0.14478)
		(layer "In4.Cu")
		(net "M_D_CPU0_SA_DQ<26>")
	)
	(segment
		(start 338.70265 -240.085372)
		(end 338.725002 -240.168684)
		(width 0.0889)
		(layer "In4.Cu")
		(net "M_D_CPU0_SA_DQ<26>")
	)
	(segment
		(start 283.759148 -226.660202)
		(end 289.82416 -226.660202)
		(width 0.14478)
		(layer "In4.Cu")
		(net "M_D_CPU0_SA_DQ<26>")
	)
	(segment
		(start 323.865748 -238.873284)
		(end 324.17385 -238.873284)
		(width 0.0889)
		(layer "In4.Cu")
		(net "M_D_CPU0_SA_DQ<26>")
	)
	(segment
		(start 327.47966 -240.111788)
		(end 327.50125 -240.124234)
		(width 0.0889)
		(layer "In4.Cu")
		(net "M_D_CPU0_SA_DQ<26>")
	)
	(segment
		(start 332.16977 -240.106708)
		(end 332.178152 -240.111534)
		(width 0.0889)
		(layer "In4.Cu")
		(net "M_D_CPU0_SA_DQ<26>")
	)
	(segment
		(start 301.196502 -225.810064)
		(end 302.04664 -226.660202)
		(width 0.14478)
		(layer "In4.Cu")
		(net "M_D_CPU0_SA_DQ<26>")
	)
	(segment
		(start 294.357806 -226.660202)
		(end 297.312334 -226.660202)
		(width 0.14478)
		(layer "In4.Cu")
		(net "M_D_CPU0_SA_DQ<26>")
	)
	(segment
		(start 283.59608 -226.82327)
		(end 283.759148 -226.660202)
		(width 0.14478)
		(layer "In4.Cu")
		(net "M_D_CPU0_SA_DQ<26>")
	)
	(segment
		(start 328.984102 -240.111534)
		(end 328.992484 -240.106708)
		(width 0.0889)
		(layer "In4.Cu")
		(net "M_D_CPU0_SA_DQ<26>")
	)
	(segment
		(start 331.229716 -240.106708)
		(end 331.238098 -240.111534)
		(width 0.0889)
		(layer "In4.Cu")
		(net "M_D_CPU0_SA_DQ<26>")
	)
	(segment
		(start 282.894786 -226.660202)
		(end 283.039566 -226.804982)
		(width 0.14478)
		(layer "In4.Cu")
		(net "M_D_CPU0_SA_DQ<26>")
	)
	(segment
		(start 283.039566 -226.804982)
		(end 283.039566 -227.195126)
		(width 0.14478)
		(layer "In4.Cu")
		(net "M_D_CPU0_SA_DQ<26>")
	)
	(segment
		(start 332.744064 -240.111534)
		(end 332.752446 -240.106708)
		(width 0.0889)
		(layer "In4.Cu")
		(net "M_D_CPU0_SA_DQ<26>")
	)
	(segment
		(start 327.461372 -240.101374)
		(end 327.47966 -240.111788)
		(width 0.0889)
		(layer "In4.Cu")
		(net "M_D_CPU0_SA_DQ<26>")
	)
	(segment
		(start 335.929732 -240.106708)
		(end 335.938114 -240.111534)
		(width 0.0889)
		(layer "In4.Cu")
		(net "M_D_CPU0_SA_DQ<26>")
	)
	(segment
		(start 283.59608 -227.195126)
		(end 283.59608 -226.82327)
		(width 0.14478)
		(layer "In4.Cu")
		(net "M_D_CPU0_SA_DQ<26>")
	)
	(segment
		(start 324.352158 -239.051592)
		(end 325.053198 -239.051592)
		(width 0.0889)
		(layer "In4.Cu")
		(net "M_D_CPU0_SA_DQ<26>")
	)
	(segment
		(start 302.04664 -226.660202)
		(end 308.231794 -226.660202)
		(width 0.14478)
		(layer "In4.Cu")
		(net "M_D_CPU0_SA_DQ<26>")
	)
	(segment
		(start 289.82416 -226.660202)
		(end 290.674298 -225.810064)
		(width 0.14478)
		(layer "In4.Cu")
		(net "M_D_CPU0_SA_DQ<26>")
	)
	(segment
		(start 297.312334 -226.660202)
		(end 298.162472 -225.810064)
		(width 0.14478)
		(layer "In4.Cu")
		(net "M_D_CPU0_SA_DQ<26>")
	)
	(segment
		(start 333.684118 -240.111534)
		(end 333.6925 -240.106708)
		(width 0.0889)
		(layer "In4.Cu")
		(net "M_D_CPU0_SA_DQ<26>")
	)
	(segment
		(start 283.039566 -227.195126)
		(end 283.202634 -227.358194)
		(width 0.14478)
		(layer "In4.Cu")
		(net "M_D_CPU0_SA_DQ<26>")
	)
	(segment
		(start 337.44408 -240.111534)
		(end 337.452462 -240.106708)
		(width 0.0889)
		(layer "In4.Cu")
		(net "M_D_CPU0_SA_DQ<26>")
	)
	(segment
		(start 283.433012 -227.358194)
		(end 283.59608 -227.195126)
		(width 0.14478)
		(layer "In4.Cu")
		(net "M_D_CPU0_SA_DQ<26>")
	)
	(segment
		(start 338.725002 -240.168684)
		(end 338.571078 -240.434114)
		(width 0.0889)
		(layer "In4.Cu")
		(net "M_D_CPU0_SA_DQ<26>")
	)
	(segment
		(start 319.196212 -238.873284)
		(end 323.865748 -238.873284)
		(width 0.14478)
		(layer "In4.Cu")
		(net "M_D_CPU0_SA_DQ<26>")
	)
	(segment
		(start 325.053198 -239.051592)
		(end 326.062086 -240.06048)
		(width 0.0889)
		(layer "In4.Cu")
		(net "M_D_CPU0_SA_DQ<26>")
	)
	(segment
		(start 283.202634 -227.358194)
		(end 283.433012 -227.358194)
		(width 0.14478)
		(layer "In4.Cu")
		(net "M_D_CPU0_SA_DQ<26>")
	)
	(segment
		(start 326.062086 -240.06048)
		(end 326.351138 -240.06048)
		(width 0.0889)
		(layer "In4.Cu")
		(net "M_D_CPU0_SA_DQ<26>")
	)
	(arc
		(start 335.563972 -240.111534)
		(mid 335.746223 -240.061184)
		(end 335.929732 -240.106708)
		(width 0.0889)
		(layer "In4.Cu")
		(net "M_D_CPU0_SA_DQ<26>")
	)
	(arc
		(start 337.818222 -240.111534)
		(mid 338.101178 -240.187711)
		(end 338.384134 -240.111534)
		(width 0.0889)
		(layer "In4.Cu")
		(net "M_D_CPU0_SA_DQ<26>")
	)
	(arc
		(start 328.992484 -240.106708)
		(mid 329.175992 -240.061214)
		(end 329.358244 -240.111534)
		(width 0.0889)
		(layer "In4.Cu")
		(net "M_D_CPU0_SA_DQ<26>")
	)
	(arc
		(start 326.351138 -240.06048)
		(mid 326.448641 -240.073495)
		(end 326.539352 -240.111534)
		(width 0.0889)
		(layer "In4.Cu")
		(net "M_D_CPU0_SA_DQ<26>")
	)
	(arc
		(start 337.452462 -240.106708)
		(mid 337.63597 -240.061214)
		(end 337.818222 -240.111534)
		(width 0.0889)
		(layer "In4.Cu")
		(net "M_D_CPU0_SA_DQ<26>")
	)
	(arc
		(start 338.384134 -240.111534)
		(mid 338.540453 -240.062539)
		(end 338.70265 -240.085372)
		(width 0.0889)
		(layer "In4.Cu")
		(net "M_D_CPU0_SA_DQ<26>")
	)
	(arc
		(start 330.298044 -240.111534)
		(mid 330.581 -240.187711)
		(end 330.863956 -240.111534)
		(width 0.0889)
		(layer "In4.Cu")
		(net "M_D_CPU0_SA_DQ<26>")
	)
	(arc
		(start 327.50125 -240.124234)
		(mid 327.774279 -240.187553)
		(end 328.044048 -240.111534)
		(width 0.0889)
		(layer "In4.Cu")
		(net "M_D_CPU0_SA_DQ<26>")
	)
	(arc
		(start 332.752446 -240.106708)
		(mid 332.935954 -240.061214)
		(end 333.118206 -240.111534)
		(width 0.0889)
		(layer "In4.Cu")
		(net "M_D_CPU0_SA_DQ<26>")
	)
	(arc
		(start 336.504026 -240.111534)
		(mid 336.686277 -240.061184)
		(end 336.869786 -240.106708)
		(width 0.0889)
		(layer "In4.Cu")
		(net "M_D_CPU0_SA_DQ<26>")
	)
	(arc
		(start 327.106534 -240.111534)
		(mid 327.282654 -240.061556)
		(end 327.461372 -240.101374)
		(width 0.0889)
		(layer "In4.Cu")
		(net "M_D_CPU0_SA_DQ<26>")
	)
	(arc
		(start 329.358244 -240.111534)
		(mid 329.6412 -240.187711)
		(end 329.924156 -240.111534)
		(width 0.0889)
		(layer "In4.Cu")
		(net "M_D_CPU0_SA_DQ<26>")
	)
	(arc
		(start 333.6925 -240.106708)
		(mid 333.876008 -240.061214)
		(end 334.05826 -240.111534)
		(width 0.0889)
		(layer "In4.Cu")
		(net "M_D_CPU0_SA_DQ<26>")
	)
	(arc
		(start 333.118206 -240.111534)
		(mid 333.401162 -240.187711)
		(end 333.684118 -240.111534)
		(width 0.0889)
		(layer "In4.Cu")
		(net "M_D_CPU0_SA_DQ<26>")
	)
	(arc
		(start 328.044048 -240.111534)
		(mid 328.226299 -240.061184)
		(end 328.409808 -240.106708)
		(width 0.0889)
		(layer "In4.Cu")
		(net "M_D_CPU0_SA_DQ<26>")
	)
	(arc
		(start 334.05826 -240.111534)
		(mid 334.341216 -240.187711)
		(end 334.624172 -240.111534)
		(width 0.0889)
		(layer "In4.Cu")
		(net "M_D_CPU0_SA_DQ<26>")
	)
	(arc
		(start 329.924156 -240.111534)
		(mid 330.1111 -240.061279)
		(end 330.298044 -240.111534)
		(width 0.0889)
		(layer "In4.Cu")
		(net "M_D_CPU0_SA_DQ<26>")
	)
	(arc
		(start 326.539352 -240.111534)
		(mid 326.809509 -240.188296)
		(end 327.083166 -240.12525)
		(width 0.0889)
		(layer "In4.Cu")
		(net "M_D_CPU0_SA_DQ<26>")
	)
	(arc
		(start 330.863956 -240.111534)
		(mid 331.046207 -240.061184)
		(end 331.229716 -240.106708)
		(width 0.0889)
		(layer "In4.Cu")
		(net "M_D_CPU0_SA_DQ<26>")
	)
	(arc
		(start 331.238098 -240.111534)
		(mid 331.521054 -240.187711)
		(end 331.80401 -240.111534)
		(width 0.0889)
		(layer "In4.Cu")
		(net "M_D_CPU0_SA_DQ<26>")
	)
	(arc
		(start 336.878168 -240.111534)
		(mid 337.161124 -240.187711)
		(end 337.44408 -240.111534)
		(width 0.0889)
		(layer "In4.Cu")
		(net "M_D_CPU0_SA_DQ<26>")
	)
	(arc
		(start 335.938114 -240.111534)
		(mid 336.22107 -240.187711)
		(end 336.504026 -240.111534)
		(width 0.0889)
		(layer "In4.Cu")
		(net "M_D_CPU0_SA_DQ<26>")
	)
	(arc
		(start 334.99806 -240.111534)
		(mid 335.281016 -240.187711)
		(end 335.563972 -240.111534)
		(width 0.0889)
		(layer "In4.Cu")
		(net "M_D_CPU0_SA_DQ<26>")
	)
	(arc
		(start 334.624172 -240.111534)
		(mid 334.811116 -240.061279)
		(end 334.99806 -240.111534)
		(width 0.0889)
		(layer "In4.Cu")
		(net "M_D_CPU0_SA_DQ<26>")
	)
	(arc
		(start 332.178152 -240.111534)
		(mid 332.461108 -240.187711)
		(end 332.744064 -240.111534)
		(width 0.0889)
		(layer "In4.Cu")
		(net "M_D_CPU0_SA_DQ<26>")
	)
	(arc
		(start 328.41819 -240.111534)
		(mid 328.701146 -240.187711)
		(end 328.984102 -240.111534)
		(width 0.0889)
		(layer "In4.Cu")
		(net "M_D_CPU0_SA_DQ<26>")
	)
	(arc
		(start 331.80401 -240.111534)
		(mid 331.986261 -240.061184)
		(end 332.16977 -240.106708)
		(width 0.0889)
		(layer "In4.Cu")
		(net "M_D_CPU0_SA_DQ<26>")
	)
	(segment
		(start 340.918038 -240.700052)
		(end 340.451186 -240.434114)
		(width 0.10668)
		(layer "F.Cu")
		(net "M_D_CPU0_SA_DQ<25>")
	)
	(segment
		(start 328.033634 -240.750598)
		(end 328.044048 -240.756694)
		(width 0.0889)
		(layer "In4.Cu")
		(net "M_D_CPU0_SA_DQ<25>")
	)
	(segment
		(start 304.46091 -227.510086)
		(end 308.445662 -227.510086)
		(width 0.14478)
		(layer "In4.Cu")
		(net "M_D_CPU0_SA_DQ<25>")
	)
	(segment
		(start 304.297842 -227.347018)
		(end 304.46091 -227.510086)
		(width 0.14478)
		(layer "In4.Cu")
		(net "M_D_CPU0_SA_DQ<25>")
	)
	(segment
		(start 297.120818 -227.510086)
		(end 297.346878 -227.510086)
		(width 0.14478)
		(layer "In4.Cu")
		(net "M_D_CPU0_SA_DQ<25>")
	)
	(segment
		(start 319.014856 -239.327944)
		(end 323.859398 -239.327944)
		(width 0.14478)
		(layer "In4.Cu")
		(net "M_D_CPU0_SA_DQ<25>")
	)
	(segment
		(start 333.684118 -240.756694)
		(end 333.6925 -240.76152)
		(width 0.0889)
		(layer "In4.Cu")
		(net "M_D_CPU0_SA_DQ<25>")
	)
	(segment
		(start 290.673282 -226.660202)
		(end 290.956492 -226.660202)
		(width 0.14478)
		(layer "In4.Cu")
		(net "M_D_CPU0_SA_DQ<25>")
	)
	(segment
		(start 328.409808 -240.76152)
		(end 328.41819 -240.756694)
		(width 0.0889)
		(layer "In4.Cu")
		(net "M_D_CPU0_SA_DQ<25>")
	)
	(segment
		(start 298.500292 -226.660202)
		(end 298.66336 -226.82327)
		(width 0.14478)
		(layer "In4.Cu")
		(net "M_D_CPU0_SA_DQ<25>")
	)
	(segment
		(start 302.952658 -227.510086)
		(end 303.347882 -227.90531)
		(width 0.14478)
		(layer "In4.Cu")
		(net "M_D_CPU0_SA_DQ<25>")
	)
	(segment
		(start 287.163256 -227.898452)
		(end 287.319466 -227.742242)
		(width 0.14478)
		(layer "In4.Cu")
		(net "M_D_CPU0_SA_DQ<25>")
	)
	(segment
		(start 291.27831 -227.047552)
		(end 291.517324 -227.047552)
		(width 0.14478)
		(layer "In4.Cu")
		(net "M_D_CPU0_SA_DQ<25>")
	)
	(segment
		(start 294.348662 -227.510086)
		(end 296.238168 -227.510086)
		(width 0.14478)
		(layer "In4.Cu")
		(net "M_D_CPU0_SA_DQ<25>")
	)
	(segment
		(start 314.751974 -233.816398)
		(end 314.751974 -235.065062)
		(width 0.14478)
		(layer "In4.Cu")
		(net "M_D_CPU0_SA_DQ<25>")
	)
	(segment
		(start 335.929732 -240.76152)
		(end 335.938114 -240.756694)
		(width 0.0889)
		(layer "In4.Cu")
		(net "M_D_CPU0_SA_DQ<25>")
	)
	(segment
		(start 332.744064 -240.756694)
		(end 332.752446 -240.76152)
		(width 0.0889)
		(layer "In4.Cu")
		(net "M_D_CPU0_SA_DQ<25>")
	)
	(segment
		(start 286.919162 -227.898452)
		(end 287.163256 -227.898452)
		(width 0.14478)
		(layer "In4.Cu")
		(net "M_D_CPU0_SA_DQ<25>")
	)
	(segment
		(start 291.676074 -226.888802)
		(end 291.676074 -226.82327)
		(width 0.14478)
		(layer "In4.Cu")
		(net "M_D_CPU0_SA_DQ<25>")
	)
	(segment
		(start 299.382942 -226.660202)
		(end 301.174658 -226.660202)
		(width 0.14478)
		(layer "In4.Cu")
		(net "M_D_CPU0_SA_DQ<25>")
	)
	(segment
		(start 325.8439 -240.80724)
		(end 326.351138 -240.80724)
		(width 0.0889)
		(layer "In4.Cu")
		(net "M_D_CPU0_SA_DQ<25>")
	)
	(segment
		(start 324.15607 -239.327944)
		(end 324.278498 -239.450372)
		(width 0.0889)
		(layer "In4.Cu")
		(net "M_D_CPU0_SA_DQ<25>")
	)
	(segment
		(start 308.445662 -227.510086)
		(end 314.751974 -233.816398)
		(width 0.14478)
		(layer "In4.Cu")
		(net "M_D_CPU0_SA_DQ<25>")
	)
	(segment
		(start 286.206438 -227.27793)
		(end 286.369506 -227.114862)
		(width 0.14478)
		(layer "In4.Cu")
		(net "M_D_CPU0_SA_DQ<25>")
	)
	(segment
		(start 296.401236 -227.742242)
		(end 296.557446 -227.898452)
		(width 0.14478)
		(layer "In4.Cu")
		(net "M_D_CPU0_SA_DQ<25>")
	)
	(segment
		(start 314.751974 -235.065062)
		(end 319.014856 -239.327944)
		(width 0.14478)
		(layer "In4.Cu")
		(net "M_D_CPU0_SA_DQ<25>")
	)
	(segment
		(start 287.319466 -227.673154)
		(end 287.482534 -227.510086)
		(width 0.14478)
		(layer "In4.Cu")
		(net "M_D_CPU0_SA_DQ<25>")
	)
	(segment
		(start 291.11956 -226.888802)
		(end 291.27831 -227.047552)
		(width 0.14478)
		(layer "In4.Cu")
		(net "M_D_CPU0_SA_DQ<25>")
	)
	(segment
		(start 287.482534 -227.510086)
		(end 289.823398 -227.510086)
		(width 0.14478)
		(layer "In4.Cu")
		(net "M_D_CPU0_SA_DQ<25>")
	)
	(segment
		(start 291.676074 -226.82327)
		(end 291.839142 -226.660202)
		(width 0.14478)
		(layer "In4.Cu")
		(net "M_D_CPU0_SA_DQ<25>")
	)
	(segment
		(start 296.95775 -227.742242)
		(end 296.95775 -227.673154)
		(width 0.14478)
		(layer "In4.Cu")
		(net "M_D_CPU0_SA_DQ<25>")
	)
	(segment
		(start 296.95775 -227.673154)
		(end 297.120818 -227.510086)
		(width 0.14478)
		(layer "In4.Cu")
		(net "M_D_CPU0_SA_DQ<25>")
	)
	(segment
		(start 302.024542 -227.510086)
		(end 302.952658 -227.510086)
		(width 0.14478)
		(layer "In4.Cu")
		(net "M_D_CPU0_SA_DQ<25>")
	)
	(segment
		(start 286.762952 -227.742242)
		(end 286.919162 -227.898452)
		(width 0.14478)
		(layer "In4.Cu")
		(net "M_D_CPU0_SA_DQ<25>")
	)
	(segment
		(start 327.093326 -240.750598)
		(end 327.10374 -240.756694)
		(width 0.0889)
		(layer "In4.Cu")
		(net "M_D_CPU0_SA_DQ<25>")
	)
	(segment
		(start 303.741328 -227.278438)
		(end 303.904396 -227.11537)
		(width 0.14478)
		(layer "In4.Cu")
		(net "M_D_CPU0_SA_DQ<25>")
	)
	(segment
		(start 328.984102 -240.756694)
		(end 328.992484 -240.76152)
		(width 0.0889)
		(layer "In4.Cu")
		(net "M_D_CPU0_SA_DQ<25>")
	)
	(segment
		(start 303.904396 -227.11537)
		(end 304.134774 -227.11537)
		(width 0.14478)
		(layer "In4.Cu")
		(net "M_D_CPU0_SA_DQ<25>")
	)
	(segment
		(start 299.061124 -227.047552)
		(end 299.219874 -226.888802)
		(width 0.14478)
		(layer "In4.Cu")
		(net "M_D_CPU0_SA_DQ<25>")
	)
	(segment
		(start 339.689694 -240.76152)
		(end 339.698076 -240.756694)
		(width 0.0889)
		(layer "In4.Cu")
		(net "M_D_CPU0_SA_DQ<25>")
	)
	(segment
		(start 290.956492 -226.660202)
		(end 291.11956 -226.82327)
		(width 0.14478)
		(layer "In4.Cu")
		(net "M_D_CPU0_SA_DQ<25>")
	)
	(segment
		(start 286.369506 -227.114862)
		(end 286.599884 -227.114862)
		(width 0.14478)
		(layer "In4.Cu")
		(net "M_D_CPU0_SA_DQ<25>")
	)
	(segment
		(start 298.82211 -227.047552)
		(end 299.061124 -227.047552)
		(width 0.14478)
		(layer "In4.Cu")
		(net "M_D_CPU0_SA_DQ<25>")
	)
	(segment
		(start 286.050228 -227.898452)
		(end 286.206438 -227.742242)
		(width 0.14478)
		(layer "In4.Cu")
		(net "M_D_CPU0_SA_DQ<25>")
	)
	(segment
		(start 303.57826 -227.90531)
		(end 303.741328 -227.742242)
		(width 0.14478)
		(layer "In4.Cu")
		(net "M_D_CPU0_SA_DQ<25>")
	)
	(segment
		(start 286.762952 -227.27793)
		(end 286.762952 -227.742242)
		(width 0.14478)
		(layer "In4.Cu")
		(net "M_D_CPU0_SA_DQ<25>")
	)
	(segment
		(start 299.219874 -226.888802)
		(end 299.219874 -226.82327)
		(width 0.14478)
		(layer "In4.Cu")
		(net "M_D_CPU0_SA_DQ<25>")
	)
	(segment
		(start 324.964298 -239.450372)
		(end 325.429118 -239.915192)
		(width 0.0889)
		(layer "In4.Cu")
		(net "M_D_CPU0_SA_DQ<25>")
	)
	(segment
		(start 323.859398 -239.327944)
		(end 324.15607 -239.327944)
		(width 0.0889)
		(layer "In4.Cu")
		(net "M_D_CPU0_SA_DQ<25>")
	)
	(segment
		(start 291.517324 -227.047552)
		(end 291.676074 -226.888802)
		(width 0.14478)
		(layer "In4.Cu")
		(net "M_D_CPU0_SA_DQ<25>")
	)
	(segment
		(start 291.11956 -226.82327)
		(end 291.11956 -226.888802)
		(width 0.14478)
		(layer "In4.Cu")
		(net "M_D_CPU0_SA_DQ<25>")
	)
	(segment
		(start 285.649924 -227.742242)
		(end 285.806134 -227.898452)
		(width 0.14478)
		(layer "In4.Cu")
		(net "M_D_CPU0_SA_DQ<25>")
	)
	(segment
		(start 298.196762 -226.660202)
		(end 298.500292 -226.660202)
		(width 0.14478)
		(layer "In4.Cu")
		(net "M_D_CPU0_SA_DQ<25>")
	)
	(segment
		(start 327.10374 -240.756694)
		(end 327.118218 -240.765076)
		(width 0.0889)
		(layer "In4.Cu")
		(net "M_D_CPU0_SA_DQ<25>")
	)
	(segment
		(start 340.297008 -240.699544)
		(end 340.451186 -240.434114)
		(width 0.0889)
		(layer "In4.Cu")
		(net "M_D_CPU0_SA_DQ<25>")
	)
	(segment
		(start 304.297842 -227.278438)
		(end 304.297842 -227.347018)
		(width 0.14478)
		(layer "In4.Cu")
		(net "M_D_CPU0_SA_DQ<25>")
	)
	(segment
		(start 296.238168 -227.510086)
		(end 296.401236 -227.673154)
		(width 0.14478)
		(layer "In4.Cu")
		(net "M_D_CPU0_SA_DQ<25>")
	)
	(segment
		(start 324.278498 -239.450372)
		(end 324.964298 -239.450372)
		(width 0.0889)
		(layer "In4.Cu")
		(net "M_D_CPU0_SA_DQ<25>")
	)
	(segment
		(start 304.134774 -227.11537)
		(end 304.297842 -227.278438)
		(width 0.14478)
		(layer "In4.Cu")
		(net "M_D_CPU0_SA_DQ<25>")
	)
	(segment
		(start 325.429118 -240.392458)
		(end 325.8439 -240.80724)
		(width 0.0889)
		(layer "In4.Cu")
		(net "M_D_CPU0_SA_DQ<25>")
	)
	(segment
		(start 298.66336 -226.82327)
		(end 298.66336 -226.888802)
		(width 0.14478)
		(layer "In4.Cu")
		(net "M_D_CPU0_SA_DQ<25>")
	)
	(segment
		(start 289.823398 -227.510086)
		(end 290.673282 -226.660202)
		(width 0.14478)
		(layer "In4.Cu")
		(net "M_D_CPU0_SA_DQ<25>")
	)
	(segment
		(start 284.736032 -227.085144)
		(end 285.160974 -227.510086)
		(width 0.14478)
		(layer "In4.Cu")
		(net "M_D_CPU0_SA_DQ<25>")
	)
	(segment
		(start 336.869786 -240.76152)
		(end 336.878168 -240.756694)
		(width 0.0889)
		(layer "In4.Cu")
		(net "M_D_CPU0_SA_DQ<25>")
	)
	(segment
		(start 285.806134 -227.898452)
		(end 286.050228 -227.898452)
		(width 0.14478)
		(layer "In4.Cu")
		(net "M_D_CPU0_SA_DQ<25>")
	)
	(segment
		(start 298.66336 -226.888802)
		(end 298.82211 -227.047552)
		(width 0.14478)
		(layer "In4.Cu")
		(net "M_D_CPU0_SA_DQ<25>")
	)
	(segment
		(start 332.16977 -240.76152)
		(end 332.178152 -240.756694)
		(width 0.0889)
		(layer "In4.Cu")
		(net "M_D_CPU0_SA_DQ<25>")
	)
	(segment
		(start 301.174658 -226.660202)
		(end 302.024542 -227.510086)
		(width 0.14478)
		(layer "In4.Cu")
		(net "M_D_CPU0_SA_DQ<25>")
	)
	(segment
		(start 285.486856 -227.510086)
		(end 285.649924 -227.673154)
		(width 0.14478)
		(layer "In4.Cu")
		(net "M_D_CPU0_SA_DQ<25>")
	)
	(segment
		(start 293.498778 -226.660202)
		(end 294.348662 -227.510086)
		(width 0.14478)
		(layer "In4.Cu")
		(net "M_D_CPU0_SA_DQ<25>")
	)
	(segment
		(start 285.160974 -227.510086)
		(end 285.486856 -227.510086)
		(width 0.14478)
		(layer "In4.Cu")
		(net "M_D_CPU0_SA_DQ<25>")
	)
	(segment
		(start 286.599884 -227.114862)
		(end 286.762952 -227.27793)
		(width 0.14478)
		(layer "In4.Cu")
		(net "M_D_CPU0_SA_DQ<25>")
	)
	(segment
		(start 291.839142 -226.660202)
		(end 293.498778 -226.660202)
		(width 0.14478)
		(layer "In4.Cu")
		(net "M_D_CPU0_SA_DQ<25>")
	)
	(segment
		(start 303.741328 -227.742242)
		(end 303.741328 -227.278438)
		(width 0.14478)
		(layer "In4.Cu")
		(net "M_D_CPU0_SA_DQ<25>")
	)
	(segment
		(start 287.319466 -227.742242)
		(end 287.319466 -227.673154)
		(width 0.14478)
		(layer "In4.Cu")
		(net "M_D_CPU0_SA_DQ<25>")
	)
	(segment
		(start 331.229716 -240.76152)
		(end 331.238098 -240.756694)
		(width 0.0889)
		(layer "In4.Cu")
		(net "M_D_CPU0_SA_DQ<25>")
	)
	(segment
		(start 325.429118 -239.915192)
		(end 325.429118 -240.392458)
		(width 0.0889)
		(layer "In4.Cu")
		(net "M_D_CPU0_SA_DQ<25>")
	)
	(segment
		(start 299.219874 -226.82327)
		(end 299.382942 -226.660202)
		(width 0.14478)
		(layer "In4.Cu")
		(net "M_D_CPU0_SA_DQ<25>")
	)
	(segment
		(start 285.649924 -227.673154)
		(end 285.649924 -227.742242)
		(width 0.14478)
		(layer "In4.Cu")
		(net "M_D_CPU0_SA_DQ<25>")
	)
	(segment
		(start 296.401236 -227.673154)
		(end 296.401236 -227.742242)
		(width 0.14478)
		(layer "In4.Cu")
		(net "M_D_CPU0_SA_DQ<25>")
	)
	(segment
		(start 337.44408 -240.756694)
		(end 337.452462 -240.76152)
		(width 0.0889)
		(layer "In4.Cu")
		(net "M_D_CPU0_SA_DQ<25>")
	)
	(segment
		(start 286.206438 -227.742242)
		(end 286.206438 -227.27793)
		(width 0.14478)
		(layer "In4.Cu")
		(net "M_D_CPU0_SA_DQ<25>")
	)
	(segment
		(start 296.80154 -227.898452)
		(end 296.95775 -227.742242)
		(width 0.14478)
		(layer "In4.Cu")
		(net "M_D_CPU0_SA_DQ<25>")
	)
	(segment
		(start 296.557446 -227.898452)
		(end 296.80154 -227.898452)
		(width 0.14478)
		(layer "In4.Cu")
		(net "M_D_CPU0_SA_DQ<25>")
	)
	(segment
		(start 297.346878 -227.510086)
		(end 298.196762 -226.660202)
		(width 0.14478)
		(layer "In4.Cu")
		(net "M_D_CPU0_SA_DQ<25>")
	)
	(segment
		(start 303.347882 -227.90531)
		(end 303.57826 -227.90531)
		(width 0.14478)
		(layer "In4.Cu")
		(net "M_D_CPU0_SA_DQ<25>")
	)
	(segment
		(start 340.200742 -240.724944)
		(end 340.297008 -240.699544)
		(width 0.0889)
		(layer "In4.Cu")
		(net "M_D_CPU0_SA_DQ<25>")
	)
	(arc
		(start 335.938114 -240.756694)
		(mid 336.22107 -240.680517)
		(end 336.504026 -240.756694)
		(width 0.0889)
		(layer "In4.Cu")
		(net "M_D_CPU0_SA_DQ<25>")
	)
	(arc
		(start 331.80401 -240.756694)
		(mid 331.986261 -240.807044)
		(end 332.16977 -240.76152)
		(width 0.0889)
		(layer "In4.Cu")
		(net "M_D_CPU0_SA_DQ<25>")
	)
	(arc
		(start 332.752446 -240.76152)
		(mid 332.935954 -240.807014)
		(end 333.118206 -240.756694)
		(width 0.0889)
		(layer "In4.Cu")
		(net "M_D_CPU0_SA_DQ<25>")
	)
	(arc
		(start 334.05826 -240.756694)
		(mid 334.341216 -240.680517)
		(end 334.624172 -240.756694)
		(width 0.0889)
		(layer "In4.Cu")
		(net "M_D_CPU0_SA_DQ<25>")
	)
	(arc
		(start 338.758022 -240.756694)
		(mid 339.040978 -240.680517)
		(end 339.323934 -240.756694)
		(width 0.0889)
		(layer "In4.Cu")
		(net "M_D_CPU0_SA_DQ<25>")
	)
	(arc
		(start 330.298044 -240.756694)
		(mid 330.581 -240.680517)
		(end 330.863956 -240.756694)
		(width 0.0889)
		(layer "In4.Cu")
		(net "M_D_CPU0_SA_DQ<25>")
	)
	(arc
		(start 337.818222 -240.756694)
		(mid 338.101178 -240.680517)
		(end 338.384134 -240.756694)
		(width 0.0889)
		(layer "In4.Cu")
		(net "M_D_CPU0_SA_DQ<25>")
	)
	(arc
		(start 339.323934 -240.756694)
		(mid 339.506185 -240.807044)
		(end 339.689694 -240.76152)
		(width 0.0889)
		(layer "In4.Cu")
		(net "M_D_CPU0_SA_DQ<25>")
	)
	(arc
		(start 328.044048 -240.756694)
		(mid 328.226299 -240.807044)
		(end 328.409808 -240.76152)
		(width 0.0889)
		(layer "In4.Cu")
		(net "M_D_CPU0_SA_DQ<25>")
	)
	(arc
		(start 328.41819 -240.756694)
		(mid 328.701146 -240.680517)
		(end 328.984102 -240.756694)
		(width 0.0889)
		(layer "In4.Cu")
		(net "M_D_CPU0_SA_DQ<25>")
	)
	(arc
		(start 338.384134 -240.756694)
		(mid 338.571078 -240.806949)
		(end 338.758022 -240.756694)
		(width 0.0889)
		(layer "In4.Cu")
		(net "M_D_CPU0_SA_DQ<25>")
	)
	(arc
		(start 333.118206 -240.756694)
		(mid 333.401162 -240.680517)
		(end 333.684118 -240.756694)
		(width 0.0889)
		(layer "In4.Cu")
		(net "M_D_CPU0_SA_DQ<25>")
	)
	(arc
		(start 333.6925 -240.76152)
		(mid 333.876008 -240.807014)
		(end 334.05826 -240.756694)
		(width 0.0889)
		(layer "In4.Cu")
		(net "M_D_CPU0_SA_DQ<25>")
	)
	(arc
		(start 339.698076 -240.756694)
		(mid 339.945672 -240.681516)
		(end 340.200742 -240.724944)
		(width 0.0889)
		(layer "In4.Cu")
		(net "M_D_CPU0_SA_DQ<25>")
	)
	(arc
		(start 329.924156 -240.756694)
		(mid 330.1111 -240.806949)
		(end 330.298044 -240.756694)
		(width 0.0889)
		(layer "In4.Cu")
		(net "M_D_CPU0_SA_DQ<25>")
	)
	(arc
		(start 330.863956 -240.756694)
		(mid 331.046207 -240.807044)
		(end 331.229716 -240.76152)
		(width 0.0889)
		(layer "In4.Cu")
		(net "M_D_CPU0_SA_DQ<25>")
	)
	(arc
		(start 336.504026 -240.756694)
		(mid 336.686277 -240.807044)
		(end 336.869786 -240.76152)
		(width 0.0889)
		(layer "In4.Cu")
		(net "M_D_CPU0_SA_DQ<25>")
	)
	(arc
		(start 334.99806 -240.756694)
		(mid 335.281016 -240.680517)
		(end 335.563972 -240.756694)
		(width 0.0889)
		(layer "In4.Cu")
		(net "M_D_CPU0_SA_DQ<25>")
	)
	(arc
		(start 336.878168 -240.756694)
		(mid 337.161124 -240.680517)
		(end 337.44408 -240.756694)
		(width 0.0889)
		(layer "In4.Cu")
		(net "M_D_CPU0_SA_DQ<25>")
	)
	(arc
		(start 328.992484 -240.76152)
		(mid 329.175992 -240.807014)
		(end 329.358244 -240.756694)
		(width 0.0889)
		(layer "In4.Cu")
		(net "M_D_CPU0_SA_DQ<25>")
	)
	(arc
		(start 337.452462 -240.76152)
		(mid 337.63597 -240.807014)
		(end 337.818222 -240.756694)
		(width 0.0889)
		(layer "In4.Cu")
		(net "M_D_CPU0_SA_DQ<25>")
	)
	(arc
		(start 334.624172 -240.756694)
		(mid 334.811116 -240.806949)
		(end 334.99806 -240.756694)
		(width 0.0889)
		(layer "In4.Cu")
		(net "M_D_CPU0_SA_DQ<25>")
	)
	(arc
		(start 332.178152 -240.756694)
		(mid 332.461108 -240.680517)
		(end 332.744064 -240.756694)
		(width 0.0889)
		(layer "In4.Cu")
		(net "M_D_CPU0_SA_DQ<25>")
	)
	(arc
		(start 327.477882 -240.756694)
		(mid 327.754949 -240.680423)
		(end 328.033634 -240.750598)
		(width 0.0889)
		(layer "In4.Cu")
		(net "M_D_CPU0_SA_DQ<25>")
	)
	(arc
		(start 331.238098 -240.756694)
		(mid 331.521054 -240.680517)
		(end 331.80401 -240.756694)
		(width 0.0889)
		(layer "In4.Cu")
		(net "M_D_CPU0_SA_DQ<25>")
	)
	(arc
		(start 329.358244 -240.756694)
		(mid 329.6412 -240.680517)
		(end 329.924156 -240.756694)
		(width 0.0889)
		(layer "In4.Cu")
		(net "M_D_CPU0_SA_DQ<25>")
	)
	(arc
		(start 326.538082 -240.756694)
		(mid 326.814895 -240.680551)
		(end 327.093326 -240.750598)
		(width 0.0889)
		(layer "In4.Cu")
		(net "M_D_CPU0_SA_DQ<25>")
	)
	(arc
		(start 335.563972 -240.756694)
		(mid 335.746223 -240.807044)
		(end 335.929732 -240.76152)
		(width 0.0889)
		(layer "In4.Cu")
		(net "M_D_CPU0_SA_DQ<25>")
	)
	(arc
		(start 326.351138 -240.80724)
		(mid 326.447949 -240.794316)
		(end 326.538082 -240.756694)
		(width 0.0889)
		(layer "In4.Cu")
		(net "M_D_CPU0_SA_DQ<25>")
	)
	(arc
		(start 327.118218 -240.765076)
		(mid 327.299126 -240.807098)
		(end 327.477882 -240.756694)
		(width 0.0889)
		(layer "In4.Cu")
		(net "M_D_CPU0_SA_DQ<25>")
	)
	(segment
		(start 339.508084 -239.890046)
		(end 339.040978 -239.624108)
		(width 0.10668)
		(layer "F.Cu")
		(net "M_D_CPU0_SA_DQ<24>")
	)
	(segment
		(start 289.823398 -225.810064)
		(end 290.673282 -224.96018)
		(width 0.14478)
		(layer "In4.Cu")
		(net "M_D_CPU0_SA_DQ<24>")
	)
	(segment
		(start 298.196762 -224.96018)
		(end 298.512738 -224.96018)
		(width 0.14478)
		(layer "In4.Cu")
		(net "M_D_CPU0_SA_DQ<24>")
	)
	(segment
		(start 285.870142 -226.19843)
		(end 286.10052 -226.19843)
		(width 0.14478)
		(layer "In4.Cu")
		(net "M_D_CPU0_SA_DQ<24>")
	)
	(segment
		(start 286.657034 -225.53549)
		(end 286.820102 -225.698558)
		(width 0.14478)
		(layer "In4.Cu")
		(net "M_D_CPU0_SA_DQ<24>")
	)
	(segment
		(start 304.927508 -225.971608)
		(end 304.927508 -226.035108)
		(width 0.14478)
		(layer "In4.Cu")
		(net "M_D_CPU0_SA_DQ<24>")
	)
	(segment
		(start 294.348662 -225.810064)
		(end 296.120566 -225.810064)
		(width 0.14478)
		(layer "In4.Cu")
		(net "M_D_CPU0_SA_DQ<24>")
	)
	(segment
		(start 303.886616 -226.19843)
		(end 304.116994 -226.19843)
		(width 0.14478)
		(layer "In4.Cu")
		(net "M_D_CPU0_SA_DQ<24>")
	)
	(segment
		(start 287.213548 -226.19843)
		(end 287.376616 -226.035362)
		(width 0.14478)
		(layer "In4.Cu")
		(net "M_D_CPU0_SA_DQ<24>")
	)
	(segment
		(start 297.346878 -225.810064)
		(end 298.196762 -224.96018)
		(width 0.14478)
		(layer "In4.Cu")
		(net "M_D_CPU0_SA_DQ<24>")
	)
	(segment
		(start 306.19192 -226.196652)
		(end 306.420266 -226.196652)
		(width 0.14478)
		(layer "In4.Cu")
		(net "M_D_CPU0_SA_DQ<24>")
	)
	(segment
		(start 290.673282 -224.96018)
		(end 290.918138 -224.96018)
		(width 0.14478)
		(layer "In4.Cu")
		(net "M_D_CPU0_SA_DQ<24>")
	)
	(segment
		(start 296.120566 -225.810064)
		(end 296.283634 -225.973132)
		(width 0.14478)
		(layer "In4.Cu")
		(net "M_D_CPU0_SA_DQ<24>")
	)
	(segment
		(start 296.67708 -226.19843)
		(end 296.840148 -226.035362)
		(width 0.14478)
		(layer "In4.Cu")
		(net "M_D_CPU0_SA_DQ<24>")
	)
	(segment
		(start 302.61052 -225.973132)
		(end 302.61052 -226.035362)
		(width 0.14478)
		(layer "In4.Cu")
		(net "M_D_CPU0_SA_DQ<24>")
	)
	(segment
		(start 315.666374 -233.458766)
		(end 315.666374 -234.70743)
		(width 0.14478)
		(layer "In4.Cu")
		(net "M_D_CPU0_SA_DQ<24>")
	)
	(segment
		(start 303.167034 -225.973132)
		(end 303.330102 -225.810064)
		(width 0.14478)
		(layer "In4.Cu")
		(net "M_D_CPU0_SA_DQ<24>")
	)
	(segment
		(start 306.420266 -226.196652)
		(end 306.58181 -226.035108)
		(width 0.14478)
		(layer "In4.Cu")
		(net "M_D_CPU0_SA_DQ<24>")
	)
	(segment
		(start 289.00501 -226.19335)
		(end 289.235388 -226.19335)
		(width 0.14478)
		(layer "In4.Cu")
		(net "M_D_CPU0_SA_DQ<24>")
	)
	(segment
		(start 306.030376 -225.971608)
		(end 306.030376 -226.035108)
		(width 0.14478)
		(layer "In4.Cu")
		(net "M_D_CPU0_SA_DQ<24>")
	)
	(segment
		(start 302.773588 -226.19843)
		(end 303.003966 -226.19843)
		(width 0.14478)
		(layer "In4.Cu")
		(net "M_D_CPU0_SA_DQ<24>")
	)
	(segment
		(start 285.707074 -225.973132)
		(end 285.707074 -226.035362)
		(width 0.14478)
		(layer "In4.Cu")
		(net "M_D_CPU0_SA_DQ<24>")
	)
	(segment
		(start 291.081206 -225.181922)
		(end 291.244274 -225.34499)
		(width 0.14478)
		(layer "In4.Cu")
		(net "M_D_CPU0_SA_DQ<24>")
	)
	(segment
		(start 286.263588 -225.698558)
		(end 286.426656 -225.53549)
		(width 0.14478)
		(layer "In4.Cu")
		(net "M_D_CPU0_SA_DQ<24>")
	)
	(segment
		(start 289.561524 -225.810064)
		(end 289.823398 -225.810064)
		(width 0.14478)
		(layer "In4.Cu")
		(net "M_D_CPU0_SA_DQ<24>")
	)
	(segment
		(start 287.376616 -226.035362)
		(end 287.376616 -225.973132)
		(width 0.14478)
		(layer "In4.Cu")
		(net "M_D_CPU0_SA_DQ<24>")
	)
	(segment
		(start 296.446702 -226.19843)
		(end 296.67708 -226.19843)
		(width 0.14478)
		(layer "In4.Cu")
		(net "M_D_CPU0_SA_DQ<24>")
	)
	(segment
		(start 304.765964 -225.810064)
		(end 304.927508 -225.971608)
		(width 0.14478)
		(layer "In4.Cu")
		(net "M_D_CPU0_SA_DQ<24>")
	)
	(segment
		(start 338.887054 -239.889538)
		(end 339.040978 -239.624108)
		(width 0.0889)
		(layer "In4.Cu")
		(net "M_D_CPU0_SA_DQ<24>")
	)
	(segment
		(start 329.819762 -239.951514)
		(end 329.828144 -239.946688)
		(width 0.0889)
		(layer "In4.Cu")
		(net "M_D_CPU0_SA_DQ<24>")
	)
	(segment
		(start 305.478942 -225.971608)
		(end 305.640486 -225.810064)
		(width 0.14478)
		(layer "In4.Cu")
		(net "M_D_CPU0_SA_DQ<24>")
	)
	(segment
		(start 289.235388 -226.19335)
		(end 289.398456 -226.030282)
		(width 0.14478)
		(layer "In4.Cu")
		(net "M_D_CPU0_SA_DQ<24>")
	)
	(segment
		(start 299.23232 -225.187002)
		(end 299.23232 -225.123248)
		(width 0.14478)
		(layer "In4.Cu")
		(net "M_D_CPU0_SA_DQ<24>")
	)
	(segment
		(start 305.317398 -226.196652)
		(end 305.478942 -226.035108)
		(width 0.14478)
		(layer "In4.Cu")
		(net "M_D_CPU0_SA_DQ<24>")
	)
	(segment
		(start 303.723548 -225.973132)
		(end 303.723548 -226.035362)
		(width 0.14478)
		(layer "In4.Cu")
		(net "M_D_CPU0_SA_DQ<24>")
	)
	(segment
		(start 286.426656 -225.53549)
		(end 286.657034 -225.53549)
		(width 0.14478)
		(layer "In4.Cu")
		(net "M_D_CPU0_SA_DQ<24>")
	)
	(segment
		(start 335.094072 -239.946688)
		(end 335.102454 -239.951514)
		(width 0.0889)
		(layer "In4.Cu")
		(net "M_D_CPU0_SA_DQ<24>")
	)
	(segment
		(start 306.030376 -226.035108)
		(end 306.19192 -226.196652)
		(width 0.14478)
		(layer "In4.Cu")
		(net "M_D_CPU0_SA_DQ<24>")
	)
	(segment
		(start 298.838874 -225.35007)
		(end 299.069252 -225.35007)
		(width 0.14478)
		(layer "In4.Cu")
		(net "M_D_CPU0_SA_DQ<24>")
	)
	(segment
		(start 327.57491 -239.946434)
		(end 327.594976 -239.957864)
		(width 0.0889)
		(layer "In4.Cu")
		(net "M_D_CPU0_SA_DQ<24>")
	)
	(segment
		(start 291.244274 -225.34499)
		(end 291.474652 -225.34499)
		(width 0.14478)
		(layer "In4.Cu")
		(net "M_D_CPU0_SA_DQ<24>")
	)
	(segment
		(start 338.27974 -239.951514)
		(end 338.288122 -239.946688)
		(width 0.0889)
		(layer "In4.Cu")
		(net "M_D_CPU0_SA_DQ<24>")
	)
	(segment
		(start 291.63772 -225.123248)
		(end 291.800788 -224.96018)
		(width 0.14478)
		(layer "In4.Cu")
		(net "M_D_CPU0_SA_DQ<24>")
	)
	(segment
		(start 291.081206 -225.123248)
		(end 291.081206 -225.181922)
		(width 0.14478)
		(layer "In4.Cu")
		(net "M_D_CPU0_SA_DQ<24>")
	)
	(segment
		(start 296.283634 -226.035362)
		(end 296.446702 -226.19843)
		(width 0.14478)
		(layer "In4.Cu")
		(net "M_D_CPU0_SA_DQ<24>")
	)
	(segment
		(start 303.330102 -225.810064)
		(end 303.56048 -225.810064)
		(width 0.14478)
		(layer "In4.Cu")
		(net "M_D_CPU0_SA_DQ<24>")
	)
	(segment
		(start 330.394056 -239.946688)
		(end 330.402438 -239.951514)
		(width 0.0889)
		(layer "In4.Cu")
		(net "M_D_CPU0_SA_DQ<24>")
	)
	(segment
		(start 305.478942 -226.035108)
		(end 305.478942 -225.971608)
		(width 0.14478)
		(layer "In4.Cu")
		(net "M_D_CPU0_SA_DQ<24>")
	)
	(segment
		(start 299.395388 -224.96018)
		(end 301.174658 -224.96018)
		(width 0.14478)
		(layer "In4.Cu")
		(net "M_D_CPU0_SA_DQ<24>")
	)
	(segment
		(start 286.820102 -226.035362)
		(end 286.98317 -226.19843)
		(width 0.14478)
		(layer "In4.Cu")
		(net "M_D_CPU0_SA_DQ<24>")
	)
	(segment
		(start 334.519778 -239.951514)
		(end 334.52816 -239.946688)
		(width 0.0889)
		(layer "In4.Cu")
		(net "M_D_CPU0_SA_DQ<24>")
	)
	(segment
		(start 296.283634 -225.973132)
		(end 296.283634 -226.035362)
		(width 0.14478)
		(layer "In4.Cu")
		(net "M_D_CPU0_SA_DQ<24>")
	)
	(segment
		(start 302.61052 -226.035362)
		(end 302.773588 -226.19843)
		(width 0.14478)
		(layer "In4.Cu")
		(net "M_D_CPU0_SA_DQ<24>")
	)
	(segment
		(start 296.840148 -225.973132)
		(end 297.003216 -225.810064)
		(width 0.14478)
		(layer "In4.Cu")
		(net "M_D_CPU0_SA_DQ<24>")
	)
	(segment
		(start 303.003966 -226.19843)
		(end 303.167034 -226.035362)
		(width 0.14478)
		(layer "In4.Cu")
		(net "M_D_CPU0_SA_DQ<24>")
	)
	(segment
		(start 289.398456 -226.030282)
		(end 289.398456 -225.973132)
		(width 0.14478)
		(layer "In4.Cu")
		(net "M_D_CPU0_SA_DQ<24>")
	)
	(segment
		(start 333.579724 -239.951514)
		(end 333.588106 -239.946688)
		(width 0.0889)
		(layer "In4.Cu")
		(net "M_D_CPU0_SA_DQ<24>")
	)
	(segment
		(start 287.539684 -225.810064)
		(end 288.678874 -225.810064)
		(width 0.14478)
		(layer "In4.Cu")
		(net "M_D_CPU0_SA_DQ<24>")
	)
	(segment
		(start 326.991726 -239.95761)
		(end 327.010522 -239.946688)
		(width 0.0889)
		(layer "In4.Cu")
		(net "M_D_CPU0_SA_DQ<24>")
	)
	(segment
		(start 285.544006 -225.810064)
		(end 285.707074 -225.973132)
		(width 0.14478)
		(layer "In4.Cu")
		(net "M_D_CPU0_SA_DQ<24>")
	)
	(segment
		(start 325.012812 -238.741712)
		(end 326.14108 -239.86998)
		(width 0.0889)
		(layer "In4.Cu")
		(net "M_D_CPU0_SA_DQ<24>")
	)
	(segment
		(start 286.263588 -226.035362)
		(end 286.263588 -225.698558)
		(width 0.14478)
		(layer "In4.Cu")
		(net "M_D_CPU0_SA_DQ<24>")
	)
	(segment
		(start 285.707074 -226.035362)
		(end 285.870142 -226.19843)
		(width 0.14478)
		(layer "In4.Cu")
		(net "M_D_CPU0_SA_DQ<24>")
	)
	(segment
		(start 289.398456 -225.973132)
		(end 289.561524 -225.810064)
		(width 0.14478)
		(layer "In4.Cu")
		(net "M_D_CPU0_SA_DQ<24>")
	)
	(segment
		(start 287.376616 -225.973132)
		(end 287.539684 -225.810064)
		(width 0.14478)
		(layer "In4.Cu")
		(net "M_D_CPU0_SA_DQ<24>")
	)
	(segment
		(start 299.23232 -225.123248)
		(end 299.395388 -224.96018)
		(width 0.14478)
		(layer "In4.Cu")
		(net "M_D_CPU0_SA_DQ<24>")
	)
	(segment
		(start 315.666374 -234.70743)
		(end 319.377568 -238.418624)
		(width 0.14478)
		(layer "In4.Cu")
		(net "M_D_CPU0_SA_DQ<24>")
	)
	(segment
		(start 304.280062 -226.035362)
		(end 304.280062 -225.973132)
		(width 0.14478)
		(layer "In4.Cu")
		(net "M_D_CPU0_SA_DQ<24>")
	)
	(segment
		(start 305.089052 -226.196652)
		(end 305.317398 -226.196652)
		(width 0.14478)
		(layer "In4.Cu")
		(net "M_D_CPU0_SA_DQ<24>")
	)
	(segment
		(start 305.868832 -225.810064)
		(end 306.030376 -225.971608)
		(width 0.14478)
		(layer "In4.Cu")
		(net "M_D_CPU0_SA_DQ<24>")
	)
	(segment
		(start 285.160974 -225.810064)
		(end 285.544006 -225.810064)
		(width 0.14478)
		(layer "In4.Cu")
		(net "M_D_CPU0_SA_DQ<24>")
	)
	(segment
		(start 324.598538 -238.741712)
		(end 325.012812 -238.741712)
		(width 0.0889)
		(layer "In4.Cu")
		(net "M_D_CPU0_SA_DQ<24>")
	)
	(segment
		(start 299.069252 -225.35007)
		(end 299.23232 -225.187002)
		(width 0.14478)
		(layer "In4.Cu")
		(net "M_D_CPU0_SA_DQ<24>")
	)
	(segment
		(start 319.377568 -238.418624)
		(end 323.889878 -238.418624)
		(width 0.14478)
		(layer "In4.Cu")
		(net "M_D_CPU0_SA_DQ<24>")
	)
	(segment
		(start 298.512738 -224.96018)
		(end 298.675806 -225.123248)
		(width 0.14478)
		(layer "In4.Cu")
		(net "M_D_CPU0_SA_DQ<24>")
	)
	(segment
		(start 323.889878 -238.418624)
		(end 324.27545 -238.418624)
		(width 0.0889)
		(layer "In4.Cu")
		(net "M_D_CPU0_SA_DQ<24>")
	)
	(segment
		(start 305.640486 -225.810064)
		(end 305.868832 -225.810064)
		(width 0.14478)
		(layer "In4.Cu")
		(net "M_D_CPU0_SA_DQ<24>")
	)
	(segment
		(start 303.56048 -225.810064)
		(end 303.723548 -225.973132)
		(width 0.14478)
		(layer "In4.Cu")
		(net "M_D_CPU0_SA_DQ<24>")
	)
	(segment
		(start 298.675806 -225.123248)
		(end 298.675806 -225.187002)
		(width 0.14478)
		(layer "In4.Cu")
		(net "M_D_CPU0_SA_DQ<24>")
	)
	(segment
		(start 308.017672 -225.810064)
		(end 315.666374 -233.458766)
		(width 0.14478)
		(layer "In4.Cu")
		(net "M_D_CPU0_SA_DQ<24>")
	)
	(segment
		(start 288.678874 -225.810064)
		(end 288.841942 -225.973132)
		(width 0.14478)
		(layer "In4.Cu")
		(net "M_D_CPU0_SA_DQ<24>")
	)
	(segment
		(start 296.840148 -226.035362)
		(end 296.840148 -225.973132)
		(width 0.14478)
		(layer "In4.Cu")
		(net "M_D_CPU0_SA_DQ<24>")
	)
	(segment
		(start 326.14108 -239.86998)
		(end 326.351138 -239.86998)
		(width 0.0889)
		(layer "In4.Cu")
		(net "M_D_CPU0_SA_DQ<24>")
	)
	(segment
		(start 297.003216 -225.810064)
		(end 297.346878 -225.810064)
		(width 0.14478)
		(layer "In4.Cu")
		(net "M_D_CPU0_SA_DQ<24>")
	)
	(segment
		(start 284.736032 -225.385122)
		(end 285.160974 -225.810064)
		(width 0.14478)
		(layer "In4.Cu")
		(net "M_D_CPU0_SA_DQ<24>")
	)
	(segment
		(start 306.58181 -226.035108)
		(end 306.58181 -225.971608)
		(width 0.14478)
		(layer "In4.Cu")
		(net "M_D_CPU0_SA_DQ<24>")
	)
	(segment
		(start 327.55332 -239.933988)
		(end 327.57491 -239.946434)
		(width 0.0889)
		(layer "In4.Cu")
		(net "M_D_CPU0_SA_DQ<24>")
	)
	(segment
		(start 331.33411 -239.946688)
		(end 331.342492 -239.951514)
		(width 0.0889)
		(layer "In4.Cu")
		(net "M_D_CPU0_SA_DQ<24>")
	)
	(segment
		(start 288.841942 -225.973132)
		(end 288.841942 -226.030282)
		(width 0.14478)
		(layer "In4.Cu")
		(net "M_D_CPU0_SA_DQ<24>")
	)
	(segment
		(start 288.841942 -226.030282)
		(end 289.00501 -226.19335)
		(width 0.14478)
		(layer "In4.Cu")
		(net "M_D_CPU0_SA_DQ<24>")
	)
	(segment
		(start 304.116994 -226.19843)
		(end 304.280062 -226.035362)
		(width 0.14478)
		(layer "In4.Cu")
		(net "M_D_CPU0_SA_DQ<24>")
	)
	(segment
		(start 290.918138 -224.96018)
		(end 291.081206 -225.123248)
		(width 0.14478)
		(layer "In4.Cu")
		(net "M_D_CPU0_SA_DQ<24>")
	)
	(segment
		(start 291.63772 -225.181922)
		(end 291.63772 -225.123248)
		(width 0.14478)
		(layer "In4.Cu")
		(net "M_D_CPU0_SA_DQ<24>")
	)
	(segment
		(start 291.474652 -225.34499)
		(end 291.63772 -225.181922)
		(width 0.14478)
		(layer "In4.Cu")
		(net "M_D_CPU0_SA_DQ<24>")
	)
	(segment
		(start 336.034126 -239.946688)
		(end 336.042508 -239.951514)
		(width 0.0889)
		(layer "In4.Cu")
		(net "M_D_CPU0_SA_DQ<24>")
	)
	(segment
		(start 304.44313 -225.810064)
		(end 304.765964 -225.810064)
		(width 0.14478)
		(layer "In4.Cu")
		(net "M_D_CPU0_SA_DQ<24>")
	)
	(segment
		(start 302.447452 -225.810064)
		(end 302.61052 -225.973132)
		(width 0.14478)
		(layer "In4.Cu")
		(net "M_D_CPU0_SA_DQ<24>")
	)
	(segment
		(start 301.174658 -224.96018)
		(end 302.024542 -225.810064)
		(width 0.14478)
		(layer "In4.Cu")
		(net "M_D_CPU0_SA_DQ<24>")
	)
	(segment
		(start 302.024542 -225.810064)
		(end 302.447452 -225.810064)
		(width 0.14478)
		(layer "In4.Cu")
		(net "M_D_CPU0_SA_DQ<24>")
	)
	(segment
		(start 324.27545 -238.418624)
		(end 324.598538 -238.741712)
		(width 0.0889)
		(layer "In4.Cu")
		(net "M_D_CPU0_SA_DQ<24>")
	)
	(segment
		(start 298.675806 -225.187002)
		(end 298.838874 -225.35007)
		(width 0.14478)
		(layer "In4.Cu")
		(net "M_D_CPU0_SA_DQ<24>")
	)
	(segment
		(start 338.791042 -239.914938)
		(end 338.887054 -239.889538)
		(width 0.0889)
		(layer "In4.Cu")
		(net "M_D_CPU0_SA_DQ<24>")
	)
	(segment
		(start 304.927508 -226.035108)
		(end 305.089052 -226.196652)
		(width 0.14478)
		(layer "In4.Cu")
		(net "M_D_CPU0_SA_DQ<24>")
	)
	(segment
		(start 306.743354 -225.810064)
		(end 308.017672 -225.810064)
		(width 0.14478)
		(layer "In4.Cu")
		(net "M_D_CPU0_SA_DQ<24>")
	)
	(segment
		(start 291.800788 -224.96018)
		(end 293.498778 -224.96018)
		(width 0.14478)
		(layer "In4.Cu")
		(net "M_D_CPU0_SA_DQ<24>")
	)
	(segment
		(start 293.498778 -224.96018)
		(end 294.348662 -225.810064)
		(width 0.14478)
		(layer "In4.Cu")
		(net "M_D_CPU0_SA_DQ<24>")
	)
	(segment
		(start 304.280062 -225.973132)
		(end 304.44313 -225.810064)
		(width 0.14478)
		(layer "In4.Cu")
		(net "M_D_CPU0_SA_DQ<24>")
	)
	(segment
		(start 286.98317 -226.19843)
		(end 287.213548 -226.19843)
		(width 0.14478)
		(layer "In4.Cu")
		(net "M_D_CPU0_SA_DQ<24>")
	)
	(segment
		(start 286.820102 -225.698558)
		(end 286.820102 -226.035362)
		(width 0.14478)
		(layer "In4.Cu")
		(net "M_D_CPU0_SA_DQ<24>")
	)
	(segment
		(start 286.10052 -226.19843)
		(end 286.263588 -226.035362)
		(width 0.14478)
		(layer "In4.Cu")
		(net "M_D_CPU0_SA_DQ<24>")
	)
	(segment
		(start 303.167034 -226.035362)
		(end 303.167034 -225.973132)
		(width 0.14478)
		(layer "In4.Cu")
		(net "M_D_CPU0_SA_DQ<24>")
	)
	(segment
		(start 306.58181 -225.971608)
		(end 306.743354 -225.810064)
		(width 0.14478)
		(layer "In4.Cu")
		(net "M_D_CPU0_SA_DQ<24>")
	)
	(segment
		(start 303.723548 -226.035362)
		(end 303.886616 -226.19843)
		(width 0.14478)
		(layer "In4.Cu")
		(net "M_D_CPU0_SA_DQ<24>")
	)
	(arc
		(start 334.52816 -239.946688)
		(mid 334.811116 -239.870511)
		(end 335.094072 -239.946688)
		(width 0.0889)
		(layer "In4.Cu")
		(net "M_D_CPU0_SA_DQ<24>")
	)
	(arc
		(start 336.97418 -239.946688)
		(mid 337.161124 -239.996943)
		(end 337.348068 -239.946688)
		(width 0.0889)
		(layer "In4.Cu")
		(net "M_D_CPU0_SA_DQ<24>")
	)
	(arc
		(start 332.274164 -239.946688)
		(mid 332.461108 -239.996943)
		(end 332.648052 -239.946688)
		(width 0.0889)
		(layer "In4.Cu")
		(net "M_D_CPU0_SA_DQ<24>")
	)
	(arc
		(start 327.594976 -239.957864)
		(mid 327.773054 -239.996848)
		(end 327.94829 -239.946688)
		(width 0.0889)
		(layer "In4.Cu")
		(net "M_D_CPU0_SA_DQ<24>")
	)
	(arc
		(start 331.342492 -239.951514)
		(mid 331.526 -239.997008)
		(end 331.708252 -239.946688)
		(width 0.0889)
		(layer "In4.Cu")
		(net "M_D_CPU0_SA_DQ<24>")
	)
	(arc
		(start 330.402438 -239.951514)
		(mid 330.585946 -239.997008)
		(end 330.768198 -239.946688)
		(width 0.0889)
		(layer "In4.Cu")
		(net "M_D_CPU0_SA_DQ<24>")
	)
	(arc
		(start 328.514202 -239.946688)
		(mid 328.701146 -239.996943)
		(end 328.88809 -239.946688)
		(width 0.0889)
		(layer "In4.Cu")
		(net "M_D_CPU0_SA_DQ<24>")
	)
	(arc
		(start 327.010522 -239.946688)
		(mid 327.280291 -239.870665)
		(end 327.55332 -239.933988)
		(width 0.0889)
		(layer "In4.Cu")
		(net "M_D_CPU0_SA_DQ<24>")
	)
	(arc
		(start 333.213964 -239.946688)
		(mid 333.396215 -239.997038)
		(end 333.579724 -239.951514)
		(width 0.0889)
		(layer "In4.Cu")
		(net "M_D_CPU0_SA_DQ<24>")
	)
	(arc
		(start 332.648052 -239.946688)
		(mid 332.931008 -239.870511)
		(end 333.213964 -239.946688)
		(width 0.0889)
		(layer "In4.Cu")
		(net "M_D_CPU0_SA_DQ<24>")
	)
	(arc
		(start 331.708252 -239.946688)
		(mid 331.991208 -239.870511)
		(end 332.274164 -239.946688)
		(width 0.0889)
		(layer "In4.Cu")
		(net "M_D_CPU0_SA_DQ<24>")
	)
	(arc
		(start 327.94829 -239.946688)
		(mid 328.231246 -239.870511)
		(end 328.514202 -239.946688)
		(width 0.0889)
		(layer "In4.Cu")
		(net "M_D_CPU0_SA_DQ<24>")
	)
	(arc
		(start 326.351138 -239.86998)
		(mid 326.498347 -239.889457)
		(end 326.635364 -239.946688)
		(width 0.0889)
		(layer "In4.Cu")
		(net "M_D_CPU0_SA_DQ<24>")
	)
	(arc
		(start 337.348068 -239.946688)
		(mid 337.631024 -239.870511)
		(end 337.91398 -239.946688)
		(width 0.0889)
		(layer "In4.Cu")
		(net "M_D_CPU0_SA_DQ<24>")
	)
	(arc
		(start 338.288122 -239.946688)
		(mid 338.535835 -239.871468)
		(end 338.791042 -239.914938)
		(width 0.0889)
		(layer "In4.Cu")
		(net "M_D_CPU0_SA_DQ<24>")
	)
	(arc
		(start 326.635364 -239.946688)
		(mid 326.812155 -239.997407)
		(end 326.991726 -239.95761)
		(width 0.0889)
		(layer "In4.Cu")
		(net "M_D_CPU0_SA_DQ<24>")
	)
	(arc
		(start 336.408268 -239.946688)
		(mid 336.691224 -239.870511)
		(end 336.97418 -239.946688)
		(width 0.0889)
		(layer "In4.Cu")
		(net "M_D_CPU0_SA_DQ<24>")
	)
	(arc
		(start 328.88809 -239.946688)
		(mid 329.171046 -239.870511)
		(end 329.454002 -239.946688)
		(width 0.0889)
		(layer "In4.Cu")
		(net "M_D_CPU0_SA_DQ<24>")
	)
	(arc
		(start 329.454002 -239.946688)
		(mid 329.636253 -239.997038)
		(end 329.819762 -239.951514)
		(width 0.0889)
		(layer "In4.Cu")
		(net "M_D_CPU0_SA_DQ<24>")
	)
	(arc
		(start 334.154018 -239.946688)
		(mid 334.336269 -239.997038)
		(end 334.519778 -239.951514)
		(width 0.0889)
		(layer "In4.Cu")
		(net "M_D_CPU0_SA_DQ<24>")
	)
	(arc
		(start 336.042508 -239.951514)
		(mid 336.226016 -239.997008)
		(end 336.408268 -239.946688)
		(width 0.0889)
		(layer "In4.Cu")
		(net "M_D_CPU0_SA_DQ<24>")
	)
	(arc
		(start 335.468214 -239.946688)
		(mid 335.75117 -239.870511)
		(end 336.034126 -239.946688)
		(width 0.0889)
		(layer "In4.Cu")
		(net "M_D_CPU0_SA_DQ<24>")
	)
	(arc
		(start 333.588106 -239.946688)
		(mid 333.871062 -239.870511)
		(end 334.154018 -239.946688)
		(width 0.0889)
		(layer "In4.Cu")
		(net "M_D_CPU0_SA_DQ<24>")
	)
	(arc
		(start 337.91398 -239.946688)
		(mid 338.096231 -239.997038)
		(end 338.27974 -239.951514)
		(width 0.0889)
		(layer "In4.Cu")
		(net "M_D_CPU0_SA_DQ<24>")
	)
	(arc
		(start 330.768198 -239.946688)
		(mid 331.051154 -239.870511)
		(end 331.33411 -239.946688)
		(width 0.0889)
		(layer "In4.Cu")
		(net "M_D_CPU0_SA_DQ<24>")
	)
	(arc
		(start 335.102454 -239.951514)
		(mid 335.285962 -239.997008)
		(end 335.468214 -239.946688)
		(width 0.0889)
		(layer "In4.Cu")
		(net "M_D_CPU0_SA_DQ<24>")
	)
	(arc
		(start 329.828144 -239.946688)
		(mid 330.1111 -239.870511)
		(end 330.394056 -239.946688)
		(width 0.0889)
		(layer "In4.Cu")
		(net "M_D_CPU0_SA_DQ<24>")
	)
	(segment
		(start 340.447884 -239.890046)
		(end 339.981032 -239.624108)
		(width 0.10668)
		(layer "F.Cu")
		(net "M_D_CPU0_SA_DQ<23>")
	)
	(segment
		(start 338.288122 -239.301528)
		(end 338.27974 -239.296702)
		(width 0.0889)
		(layer "In4.Cu")
		(net "M_D_CPU0_SA_DQ<23>")
	)
	(segment
		(start 334.52816 -239.301528)
		(end 334.519778 -239.296702)
		(width 0.0889)
		(layer "In4.Cu")
		(net "M_D_CPU0_SA_DQ<23>")
	)
	(segment
		(start 281.799284 -224.96018)
		(end 281.06116 -224.96018)
		(width 0.14478)
		(layer "In4.Cu")
		(net "M_D_CPU0_SA_DQ<23>")
	)
	(segment
		(start 329.828144 -239.301528)
		(end 329.819762 -239.296702)
		(width 0.0889)
		(layer "In4.Cu")
		(net "M_D_CPU0_SA_DQ<23>")
	)
	(segment
		(start 327.597008 -239.289336)
		(end 327.575164 -239.301782)
		(width 0.0889)
		(layer "In4.Cu")
		(net "M_D_CPU0_SA_DQ<23>")
	)
	(segment
		(start 289.82416 -224.96018)
		(end 282.681934 -224.96018)
		(width 0.14478)
		(layer "In4.Cu")
		(net "M_D_CPU0_SA_DQ<23>")
	)
	(segment
		(start 282.355798 -224.15119)
		(end 282.12542 -224.15119)
		(width 0.14478)
		(layer "In4.Cu")
		(net "M_D_CPU0_SA_DQ<23>")
	)
	(segment
		(start 319.57899 -237.958884)
		(end 316.123574 -234.503468)
		(width 0.14478)
		(layer "In4.Cu")
		(net "M_D_CPU0_SA_DQ<23>")
	)
	(segment
		(start 307.789072 -224.96018)
		(end 302.04664 -224.96018)
		(width 0.14478)
		(layer "In4.Cu")
		(net "M_D_CPU0_SA_DQ<23>")
	)
	(segment
		(start 333.588106 -239.301528)
		(end 333.579724 -239.296702)
		(width 0.0889)
		(layer "In4.Cu")
		(net "M_D_CPU0_SA_DQ<23>")
	)
	(segment
		(start 297.312334 -224.96018)
		(end 294.357806 -224.96018)
		(width 0.14478)
		(layer "In4.Cu")
		(net "M_D_CPU0_SA_DQ<23>")
	)
	(segment
		(start 339.981032 -239.624108)
		(end 340.13521 -239.358678)
		(width 0.0889)
		(layer "In4.Cu")
		(net "M_D_CPU0_SA_DQ<23>")
	)
	(segment
		(start 293.507668 -224.110042)
		(end 290.674298 -224.110042)
		(width 0.14478)
		(layer "In4.Cu")
		(net "M_D_CPU0_SA_DQ<23>")
	)
	(segment
		(start 282.518866 -224.314258)
		(end 282.355798 -224.15119)
		(width 0.14478)
		(layer "In4.Cu")
		(net "M_D_CPU0_SA_DQ<23>")
	)
	(segment
		(start 330.402438 -239.296702)
		(end 330.394056 -239.301528)
		(width 0.0889)
		(layer "In4.Cu")
		(net "M_D_CPU0_SA_DQ<23>")
	)
	(segment
		(start 316.123574 -234.503468)
		(end 316.123574 -233.294682)
		(width 0.14478)
		(layer "In4.Cu")
		(net "M_D_CPU0_SA_DQ<23>")
	)
	(segment
		(start 298.162472 -224.110042)
		(end 297.312334 -224.96018)
		(width 0.14478)
		(layer "In4.Cu")
		(net "M_D_CPU0_SA_DQ<23>")
	)
	(segment
		(start 323.789548 -237.958884)
		(end 319.57899 -237.958884)
		(width 0.14478)
		(layer "In4.Cu")
		(net "M_D_CPU0_SA_DQ<23>")
	)
	(segment
		(start 326.351138 -239.37849)
		(end 326.337676 -239.37849)
		(width 0.0889)
		(layer "In4.Cu")
		(net "M_D_CPU0_SA_DQ<23>")
	)
	(segment
		(start 338.862416 -239.296702)
		(end 338.854034 -239.301528)
		(width 0.0889)
		(layer "In4.Cu")
		(net "M_D_CPU0_SA_DQ<23>")
	)
	(segment
		(start 281.06116 -224.96018)
		(end 280.635964 -224.534984)
		(width 0.14478)
		(layer "In4.Cu")
		(net "M_D_CPU0_SA_DQ<23>")
	)
	(segment
		(start 336.042508 -239.296702)
		(end 336.034126 -239.301528)
		(width 0.0889)
		(layer "In4.Cu")
		(net "M_D_CPU0_SA_DQ<23>")
	)
	(segment
		(start 325.705978 -238.746792)
		(end 325.705978 -238.67618)
		(width 0.0889)
		(layer "In4.Cu")
		(net "M_D_CPU0_SA_DQ<23>")
	)
	(segment
		(start 281.962352 -224.797112)
		(end 281.799284 -224.96018)
		(width 0.14478)
		(layer "In4.Cu")
		(net "M_D_CPU0_SA_DQ<23>")
	)
	(segment
		(start 335.102454 -239.296702)
		(end 335.094072 -239.301528)
		(width 0.0889)
		(layer "In4.Cu")
		(net "M_D_CPU0_SA_DQ<23>")
	)
	(segment
		(start 327.01103 -239.301528)
		(end 326.992234 -239.290606)
		(width 0.0889)
		(layer "In4.Cu")
		(net "M_D_CPU0_SA_DQ<23>")
	)
	(segment
		(start 290.674298 -224.110042)
		(end 289.82416 -224.96018)
		(width 0.14478)
		(layer "In4.Cu")
		(net "M_D_CPU0_SA_DQ<23>")
	)
	(segment
		(start 282.681934 -224.96018)
		(end 282.518866 -224.797112)
		(width 0.14478)
		(layer "In4.Cu")
		(net "M_D_CPU0_SA_DQ<23>")
	)
	(segment
		(start 324.220078 -237.862364)
		(end 324.123558 -237.958884)
		(width 0.0889)
		(layer "In4.Cu")
		(net "M_D_CPU0_SA_DQ<23>")
	)
	(segment
		(start 325.705978 -238.67618)
		(end 324.892162 -237.862364)
		(width 0.0889)
		(layer "In4.Cu")
		(net "M_D_CPU0_SA_DQ<23>")
	)
	(segment
		(start 294.357806 -224.96018)
		(end 293.507668 -224.110042)
		(width 0.14478)
		(layer "In4.Cu")
		(net "M_D_CPU0_SA_DQ<23>")
	)
	(segment
		(start 282.12542 -224.15119)
		(end 281.962352 -224.314258)
		(width 0.14478)
		(layer "In4.Cu")
		(net "M_D_CPU0_SA_DQ<23>")
	)
	(segment
		(start 301.196502 -224.110042)
		(end 298.162472 -224.110042)
		(width 0.14478)
		(layer "In4.Cu")
		(net "M_D_CPU0_SA_DQ<23>")
	)
	(segment
		(start 281.962352 -224.314258)
		(end 281.962352 -224.797112)
		(width 0.14478)
		(layer "In4.Cu")
		(net "M_D_CPU0_SA_DQ<23>")
	)
	(segment
		(start 324.123558 -237.958884)
		(end 323.789548 -237.958884)
		(width 0.0889)
		(layer "In4.Cu")
		(net "M_D_CPU0_SA_DQ<23>")
	)
	(segment
		(start 339.80247 -239.296702)
		(end 339.794088 -239.301528)
		(width 0.0889)
		(layer "In4.Cu")
		(net "M_D_CPU0_SA_DQ<23>")
	)
	(segment
		(start 324.892162 -237.862364)
		(end 324.220078 -237.862364)
		(width 0.0889)
		(layer "In4.Cu")
		(net "M_D_CPU0_SA_DQ<23>")
	)
	(segment
		(start 316.123574 -233.294682)
		(end 307.789072 -224.96018)
		(width 0.14478)
		(layer "In4.Cu")
		(net "M_D_CPU0_SA_DQ<23>")
	)
	(segment
		(start 327.575164 -239.301782)
		(end 327.551288 -239.315752)
		(width 0.0889)
		(layer "In4.Cu")
		(net "M_D_CPU0_SA_DQ<23>")
	)
	(segment
		(start 282.518866 -224.797112)
		(end 282.518866 -224.314258)
		(width 0.14478)
		(layer "In4.Cu")
		(net "M_D_CPU0_SA_DQ<23>")
	)
	(segment
		(start 302.04664 -224.96018)
		(end 301.196502 -224.110042)
		(width 0.14478)
		(layer "In4.Cu")
		(net "M_D_CPU0_SA_DQ<23>")
	)
	(segment
		(start 340.13521 -239.358678)
		(end 340.112858 -239.275366)
		(width 0.0889)
		(layer "In4.Cu")
		(net "M_D_CPU0_SA_DQ<23>")
	)
	(segment
		(start 331.342492 -239.296702)
		(end 331.33411 -239.301528)
		(width 0.0889)
		(layer "In4.Cu")
		(net "M_D_CPU0_SA_DQ<23>")
	)
	(arc
		(start 339.228176 -239.301528)
		(mid 339.045925 -239.251178)
		(end 338.862416 -239.296702)
		(width 0.0889)
		(layer "In4.Cu")
		(net "M_D_CPU0_SA_DQ<23>")
	)
	(arc
		(start 337.348068 -239.301528)
		(mid 337.161124 -239.251273)
		(end 336.97418 -239.301528)
		(width 0.0889)
		(layer "In4.Cu")
		(net "M_D_CPU0_SA_DQ<23>")
	)
	(arc
		(start 327.551288 -239.315752)
		(mid 327.279351 -239.377578)
		(end 327.01103 -239.301528)
		(width 0.0889)
		(layer "In4.Cu")
		(net "M_D_CPU0_SA_DQ<23>")
	)
	(arc
		(start 332.274164 -239.301528)
		(mid 331.991208 -239.377705)
		(end 331.708252 -239.301528)
		(width 0.0889)
		(layer "In4.Cu")
		(net "M_D_CPU0_SA_DQ<23>")
	)
	(arc
		(start 338.27974 -239.296702)
		(mid 338.096232 -239.251208)
		(end 337.91398 -239.301528)
		(width 0.0889)
		(layer "In4.Cu")
		(net "M_D_CPU0_SA_DQ<23>")
	)
	(arc
		(start 331.33411 -239.301528)
		(mid 331.051154 -239.377705)
		(end 330.768198 -239.301528)
		(width 0.0889)
		(layer "In4.Cu")
		(net "M_D_CPU0_SA_DQ<23>")
	)
	(arc
		(start 332.648052 -239.301528)
		(mid 332.461108 -239.251273)
		(end 332.274164 -239.301528)
		(width 0.0889)
		(layer "In4.Cu")
		(net "M_D_CPU0_SA_DQ<23>")
	)
	(arc
		(start 327.94829 -239.301528)
		(mid 327.774186 -239.251494)
		(end 327.597008 -239.289336)
		(width 0.0889)
		(layer "In4.Cu")
		(net "M_D_CPU0_SA_DQ<23>")
	)
	(arc
		(start 328.514202 -239.301528)
		(mid 328.231246 -239.377705)
		(end 327.94829 -239.301528)
		(width 0.0889)
		(layer "In4.Cu")
		(net "M_D_CPU0_SA_DQ<23>")
	)
	(arc
		(start 331.708252 -239.301528)
		(mid 331.526001 -239.251178)
		(end 331.342492 -239.296702)
		(width 0.0889)
		(layer "In4.Cu")
		(net "M_D_CPU0_SA_DQ<23>")
	)
	(arc
		(start 336.034126 -239.301528)
		(mid 335.75117 -239.377705)
		(end 335.468214 -239.301528)
		(width 0.0889)
		(layer "In4.Cu")
		(net "M_D_CPU0_SA_DQ<23>")
	)
	(arc
		(start 333.213964 -239.301528)
		(mid 332.931008 -239.377705)
		(end 332.648052 -239.301528)
		(width 0.0889)
		(layer "In4.Cu")
		(net "M_D_CPU0_SA_DQ<23>")
	)
	(arc
		(start 334.519778 -239.296702)
		(mid 334.33627 -239.251208)
		(end 334.154018 -239.301528)
		(width 0.0889)
		(layer "In4.Cu")
		(net "M_D_CPU0_SA_DQ<23>")
	)
	(arc
		(start 340.112858 -239.275366)
		(mid 339.955348 -239.252168)
		(end 339.80247 -239.296702)
		(width 0.0889)
		(layer "In4.Cu")
		(net "M_D_CPU0_SA_DQ<23>")
	)
	(arc
		(start 326.337676 -239.37849)
		(mid 325.890998 -239.19347)
		(end 325.705978 -238.746792)
		(width 0.0889)
		(layer "In4.Cu")
		(net "M_D_CPU0_SA_DQ<23>")
	)
	(arc
		(start 337.91398 -239.301528)
		(mid 337.631024 -239.377705)
		(end 337.348068 -239.301528)
		(width 0.0889)
		(layer "In4.Cu")
		(net "M_D_CPU0_SA_DQ<23>")
	)
	(arc
		(start 326.635872 -239.301528)
		(mid 326.49862 -239.358929)
		(end 326.351138 -239.37849)
		(width 0.0889)
		(layer "In4.Cu")
		(net "M_D_CPU0_SA_DQ<23>")
	)
	(arc
		(start 338.854034 -239.301528)
		(mid 338.571078 -239.377705)
		(end 338.288122 -239.301528)
		(width 0.0889)
		(layer "In4.Cu")
		(net "M_D_CPU0_SA_DQ<23>")
	)
	(arc
		(start 335.094072 -239.301528)
		(mid 334.811116 -239.377705)
		(end 334.52816 -239.301528)
		(width 0.0889)
		(layer "In4.Cu")
		(net "M_D_CPU0_SA_DQ<23>")
	)
	(arc
		(start 328.88809 -239.301528)
		(mid 328.701146 -239.251273)
		(end 328.514202 -239.301528)
		(width 0.0889)
		(layer "In4.Cu")
		(net "M_D_CPU0_SA_DQ<23>")
	)
	(arc
		(start 336.408268 -239.301528)
		(mid 336.226017 -239.251178)
		(end 336.042508 -239.296702)
		(width 0.0889)
		(layer "In4.Cu")
		(net "M_D_CPU0_SA_DQ<23>")
	)
	(arc
		(start 329.819762 -239.296702)
		(mid 329.636254 -239.251208)
		(end 329.454002 -239.301528)
		(width 0.0889)
		(layer "In4.Cu")
		(net "M_D_CPU0_SA_DQ<23>")
	)
	(arc
		(start 334.154018 -239.301528)
		(mid 333.871062 -239.377705)
		(end 333.588106 -239.301528)
		(width 0.0889)
		(layer "In4.Cu")
		(net "M_D_CPU0_SA_DQ<23>")
	)
	(arc
		(start 330.394056 -239.301528)
		(mid 330.1111 -239.377705)
		(end 329.828144 -239.301528)
		(width 0.0889)
		(layer "In4.Cu")
		(net "M_D_CPU0_SA_DQ<23>")
	)
	(arc
		(start 333.579724 -239.296702)
		(mid 333.396216 -239.251208)
		(end 333.213964 -239.301528)
		(width 0.0889)
		(layer "In4.Cu")
		(net "M_D_CPU0_SA_DQ<23>")
	)
	(arc
		(start 330.768198 -239.301528)
		(mid 330.585947 -239.251178)
		(end 330.402438 -239.296702)
		(width 0.0889)
		(layer "In4.Cu")
		(net "M_D_CPU0_SA_DQ<23>")
	)
	(arc
		(start 329.454002 -239.301528)
		(mid 329.171046 -239.377705)
		(end 328.88809 -239.301528)
		(width 0.0889)
		(layer "In4.Cu")
		(net "M_D_CPU0_SA_DQ<23>")
	)
	(arc
		(start 326.992234 -239.290606)
		(mid 326.812663 -239.250789)
		(end 326.635872 -239.301528)
		(width 0.0889)
		(layer "In4.Cu")
		(net "M_D_CPU0_SA_DQ<23>")
	)
	(arc
		(start 336.97418 -239.301528)
		(mid 336.691224 -239.377705)
		(end 336.408268 -239.301528)
		(width 0.0889)
		(layer "In4.Cu")
		(net "M_D_CPU0_SA_DQ<23>")
	)
	(arc
		(start 339.794088 -239.301528)
		(mid 339.511132 -239.377705)
		(end 339.228176 -239.301528)
		(width 0.0889)
		(layer "In4.Cu")
		(net "M_D_CPU0_SA_DQ<23>")
	)
	(arc
		(start 335.468214 -239.301528)
		(mid 335.285963 -239.251178)
		(end 335.102454 -239.296702)
		(width 0.0889)
		(layer "In4.Cu")
		(net "M_D_CPU0_SA_DQ<23>")
	)
	(segment
		(start 339.03793 -239.08004)
		(end 338.571078 -238.814102)
		(width 0.10668)
		(layer "F.Cu")
		(net "M_D_CPU0_SA_DQ<22>")
	)
	(segment
		(start 282.30322 -223.09709)
		(end 282.30322 -222.526098)
		(width 0.14478)
		(layer "In4.Cu")
		(net "M_D_CPU0_SA_DQ<22>")
	)
	(segment
		(start 293.507668 -222.41002)
		(end 294.357806 -223.260158)
		(width 0.14478)
		(layer "In4.Cu")
		(net "M_D_CPU0_SA_DQ<22>")
	)
	(segment
		(start 332.744064 -238.491522)
		(end 332.752446 -238.486696)
		(width 0.0889)
		(layer "In4.Cu")
		(net "M_D_CPU0_SA_DQ<22>")
	)
	(segment
		(start 327.083166 -238.505238)
		(end 327.106534 -238.491522)
		(width 0.0889)
		(layer "In4.Cu")
		(net "M_D_CPU0_SA_DQ<22>")
	)
	(segment
		(start 317.131954 -232.882694)
		(end 317.131954 -234.094782)
		(width 0.14478)
		(layer "In4.Cu")
		(net "M_D_CPU0_SA_DQ<22>")
	)
	(segment
		(start 283.579316 -222.467932)
		(end 283.809694 -222.467932)
		(width 0.14478)
		(layer "In4.Cu")
		(net "M_D_CPU0_SA_DQ<22>")
	)
	(segment
		(start 280.635964 -222.834962)
		(end 281.06116 -223.260158)
		(width 0.14478)
		(layer "In4.Cu")
		(net "M_D_CPU0_SA_DQ<22>")
	)
	(segment
		(start 282.696666 -222.36303)
		(end 282.859734 -222.526098)
		(width 0.14478)
		(layer "In4.Cu")
		(net "M_D_CPU0_SA_DQ<22>")
	)
	(segment
		(start 283.809694 -222.467932)
		(end 283.972762 -222.631)
		(width 0.14478)
		(layer "In4.Cu")
		(net "M_D_CPU0_SA_DQ<22>")
	)
	(segment
		(start 327.461372 -238.481362)
		(end 327.47966 -238.491776)
		(width 0.0889)
		(layer "In4.Cu")
		(net "M_D_CPU0_SA_DQ<22>")
	)
	(segment
		(start 332.16977 -238.486696)
		(end 332.178152 -238.491522)
		(width 0.0889)
		(layer "In4.Cu")
		(net "M_D_CPU0_SA_DQ<22>")
	)
	(segment
		(start 307.509418 -223.260158)
		(end 317.131954 -232.882694)
		(width 0.14478)
		(layer "In4.Cu")
		(net "M_D_CPU0_SA_DQ<22>")
	)
	(segment
		(start 283.416248 -222.631)
		(end 283.579316 -222.467932)
		(width 0.14478)
		(layer "In4.Cu")
		(net "M_D_CPU0_SA_DQ<22>")
	)
	(segment
		(start 324.430898 -237.304072)
		(end 325.114158 -237.304072)
		(width 0.0889)
		(layer "In4.Cu")
		(net "M_D_CPU0_SA_DQ<22>")
	)
	(segment
		(start 283.972762 -223.09709)
		(end 284.13583 -223.260158)
		(width 0.14478)
		(layer "In4.Cu")
		(net "M_D_CPU0_SA_DQ<22>")
	)
	(segment
		(start 289.82416 -223.260158)
		(end 290.674298 -222.41002)
		(width 0.14478)
		(layer "In4.Cu")
		(net "M_D_CPU0_SA_DQ<22>")
	)
	(segment
		(start 335.929732 -238.486696)
		(end 335.938114 -238.491522)
		(width 0.0889)
		(layer "In4.Cu")
		(net "M_D_CPU0_SA_DQ<22>")
	)
	(segment
		(start 323.903848 -236.953044)
		(end 324.07987 -236.953044)
		(width 0.0889)
		(layer "In4.Cu")
		(net "M_D_CPU0_SA_DQ<22>")
	)
	(segment
		(start 338.70265 -238.46536)
		(end 338.725002 -238.548672)
		(width 0.0889)
		(layer "In4.Cu")
		(net "M_D_CPU0_SA_DQ<22>")
	)
	(segment
		(start 301.196502 -222.41002)
		(end 302.04664 -223.260158)
		(width 0.14478)
		(layer "In4.Cu")
		(net "M_D_CPU0_SA_DQ<22>")
	)
	(segment
		(start 283.972762 -222.631)
		(end 283.972762 -223.09709)
		(width 0.14478)
		(layer "In4.Cu")
		(net "M_D_CPU0_SA_DQ<22>")
	)
	(segment
		(start 282.859734 -222.526098)
		(end 282.859734 -223.09709)
		(width 0.14478)
		(layer "In4.Cu")
		(net "M_D_CPU0_SA_DQ<22>")
	)
	(segment
		(start 294.357806 -223.260158)
		(end 297.312334 -223.260158)
		(width 0.14478)
		(layer "In4.Cu")
		(net "M_D_CPU0_SA_DQ<22>")
	)
	(segment
		(start 281.06116 -223.260158)
		(end 282.140152 -223.260158)
		(width 0.14478)
		(layer "In4.Cu")
		(net "M_D_CPU0_SA_DQ<22>")
	)
	(segment
		(start 297.312334 -223.260158)
		(end 298.162472 -222.41002)
		(width 0.14478)
		(layer "In4.Cu")
		(net "M_D_CPU0_SA_DQ<22>")
	)
	(segment
		(start 290.674298 -222.41002)
		(end 293.507668 -222.41002)
		(width 0.14478)
		(layer "In4.Cu")
		(net "M_D_CPU0_SA_DQ<22>")
	)
	(segment
		(start 282.466288 -222.36303)
		(end 282.696666 -222.36303)
		(width 0.14478)
		(layer "In4.Cu")
		(net "M_D_CPU0_SA_DQ<22>")
	)
	(segment
		(start 328.984102 -238.491522)
		(end 328.992484 -238.486696)
		(width 0.0889)
		(layer "In4.Cu")
		(net "M_D_CPU0_SA_DQ<22>")
	)
	(segment
		(start 333.684118 -238.491522)
		(end 333.6925 -238.486696)
		(width 0.0889)
		(layer "In4.Cu")
		(net "M_D_CPU0_SA_DQ<22>")
	)
	(segment
		(start 331.229716 -238.486696)
		(end 331.238098 -238.491522)
		(width 0.0889)
		(layer "In4.Cu")
		(net "M_D_CPU0_SA_DQ<22>")
	)
	(segment
		(start 283.416248 -223.09709)
		(end 283.416248 -222.631)
		(width 0.14478)
		(layer "In4.Cu")
		(net "M_D_CPU0_SA_DQ<22>")
	)
	(segment
		(start 317.131954 -234.094782)
		(end 319.990216 -236.953044)
		(width 0.14478)
		(layer "In4.Cu")
		(net "M_D_CPU0_SA_DQ<22>")
	)
	(segment
		(start 283.022802 -223.260158)
		(end 283.25318 -223.260158)
		(width 0.14478)
		(layer "In4.Cu")
		(net "M_D_CPU0_SA_DQ<22>")
	)
	(segment
		(start 327.47966 -238.491776)
		(end 327.50125 -238.504222)
		(width 0.0889)
		(layer "In4.Cu")
		(net "M_D_CPU0_SA_DQ<22>")
	)
	(segment
		(start 283.25318 -223.260158)
		(end 283.416248 -223.09709)
		(width 0.14478)
		(layer "In4.Cu")
		(net "M_D_CPU0_SA_DQ<22>")
	)
	(segment
		(start 337.44408 -238.491522)
		(end 337.452462 -238.486696)
		(width 0.0889)
		(layer "In4.Cu")
		(net "M_D_CPU0_SA_DQ<22>")
	)
	(segment
		(start 338.725002 -238.548672)
		(end 338.571078 -238.814102)
		(width 0.0889)
		(layer "In4.Cu")
		(net "M_D_CPU0_SA_DQ<22>")
	)
	(segment
		(start 282.30322 -222.526098)
		(end 282.466288 -222.36303)
		(width 0.14478)
		(layer "In4.Cu")
		(net "M_D_CPU0_SA_DQ<22>")
	)
	(segment
		(start 302.04664 -223.260158)
		(end 307.509418 -223.260158)
		(width 0.14478)
		(layer "In4.Cu")
		(net "M_D_CPU0_SA_DQ<22>")
	)
	(segment
		(start 298.162472 -222.41002)
		(end 301.196502 -222.41002)
		(width 0.14478)
		(layer "In4.Cu")
		(net "M_D_CPU0_SA_DQ<22>")
	)
	(segment
		(start 336.869786 -238.486696)
		(end 336.878168 -238.491522)
		(width 0.0889)
		(layer "In4.Cu")
		(net "M_D_CPU0_SA_DQ<22>")
	)
	(segment
		(start 328.409808 -238.486696)
		(end 328.41819 -238.491522)
		(width 0.0889)
		(layer "In4.Cu")
		(net "M_D_CPU0_SA_DQ<22>")
	)
	(segment
		(start 282.859734 -223.09709)
		(end 283.022802 -223.260158)
		(width 0.14478)
		(layer "In4.Cu")
		(net "M_D_CPU0_SA_DQ<22>")
	)
	(segment
		(start 284.13583 -223.260158)
		(end 289.82416 -223.260158)
		(width 0.14478)
		(layer "In4.Cu")
		(net "M_D_CPU0_SA_DQ<22>")
	)
	(segment
		(start 282.140152 -223.260158)
		(end 282.30322 -223.09709)
		(width 0.14478)
		(layer "In4.Cu")
		(net "M_D_CPU0_SA_DQ<22>")
	)
	(segment
		(start 325.114158 -237.304072)
		(end 326.250554 -238.440468)
		(width 0.0889)
		(layer "In4.Cu")
		(net "M_D_CPU0_SA_DQ<22>")
	)
	(segment
		(start 319.990216 -236.953044)
		(end 323.903848 -236.953044)
		(width 0.14478)
		(layer "In4.Cu")
		(net "M_D_CPU0_SA_DQ<22>")
	)
	(segment
		(start 324.07987 -236.953044)
		(end 324.430898 -237.304072)
		(width 0.0889)
		(layer "In4.Cu")
		(net "M_D_CPU0_SA_DQ<22>")
	)
	(segment
		(start 326.250554 -238.440468)
		(end 326.351138 -238.440468)
		(width 0.0889)
		(layer "In4.Cu")
		(net "M_D_CPU0_SA_DQ<22>")
	)
	(arc
		(start 337.452462 -238.486696)
		(mid 337.63597 -238.441202)
		(end 337.818222 -238.491522)
		(width 0.0889)
		(layer "In4.Cu")
		(net "M_D_CPU0_SA_DQ<22>")
	)
	(arc
		(start 329.358244 -238.491522)
		(mid 329.6412 -238.567699)
		(end 329.924156 -238.491522)
		(width 0.0889)
		(layer "In4.Cu")
		(net "M_D_CPU0_SA_DQ<22>")
	)
	(arc
		(start 327.50125 -238.504222)
		(mid 327.774279 -238.567541)
		(end 328.044048 -238.491522)
		(width 0.0889)
		(layer "In4.Cu")
		(net "M_D_CPU0_SA_DQ<22>")
	)
	(arc
		(start 327.106534 -238.491522)
		(mid 327.282654 -238.441544)
		(end 327.461372 -238.481362)
		(width 0.0889)
		(layer "In4.Cu")
		(net "M_D_CPU0_SA_DQ<22>")
	)
	(arc
		(start 336.504026 -238.491522)
		(mid 336.686277 -238.441172)
		(end 336.869786 -238.486696)
		(width 0.0889)
		(layer "In4.Cu")
		(net "M_D_CPU0_SA_DQ<22>")
	)
	(arc
		(start 330.298044 -238.491522)
		(mid 330.581 -238.567699)
		(end 330.863956 -238.491522)
		(width 0.0889)
		(layer "In4.Cu")
		(net "M_D_CPU0_SA_DQ<22>")
	)
	(arc
		(start 328.044048 -238.491522)
		(mid 328.226299 -238.441172)
		(end 328.409808 -238.486696)
		(width 0.0889)
		(layer "In4.Cu")
		(net "M_D_CPU0_SA_DQ<22>")
	)
	(arc
		(start 335.938114 -238.491522)
		(mid 336.22107 -238.567699)
		(end 336.504026 -238.491522)
		(width 0.0889)
		(layer "In4.Cu")
		(net "M_D_CPU0_SA_DQ<22>")
	)
	(arc
		(start 330.863956 -238.491522)
		(mid 331.046207 -238.441172)
		(end 331.229716 -238.486696)
		(width 0.0889)
		(layer "In4.Cu")
		(net "M_D_CPU0_SA_DQ<22>")
	)
	(arc
		(start 334.05826 -238.491522)
		(mid 334.341216 -238.567699)
		(end 334.624172 -238.491522)
		(width 0.0889)
		(layer "In4.Cu")
		(net "M_D_CPU0_SA_DQ<22>")
	)
	(arc
		(start 331.238098 -238.491522)
		(mid 331.521054 -238.567699)
		(end 331.80401 -238.491522)
		(width 0.0889)
		(layer "In4.Cu")
		(net "M_D_CPU0_SA_DQ<22>")
	)
	(arc
		(start 326.351138 -238.440468)
		(mid 326.448641 -238.453483)
		(end 326.539352 -238.491522)
		(width 0.0889)
		(layer "In4.Cu")
		(net "M_D_CPU0_SA_DQ<22>")
	)
	(arc
		(start 338.384134 -238.491522)
		(mid 338.540453 -238.442527)
		(end 338.70265 -238.46536)
		(width 0.0889)
		(layer "In4.Cu")
		(net "M_D_CPU0_SA_DQ<22>")
	)
	(arc
		(start 334.624172 -238.491522)
		(mid 334.811116 -238.441267)
		(end 334.99806 -238.491522)
		(width 0.0889)
		(layer "In4.Cu")
		(net "M_D_CPU0_SA_DQ<22>")
	)
	(arc
		(start 337.818222 -238.491522)
		(mid 338.101178 -238.567699)
		(end 338.384134 -238.491522)
		(width 0.0889)
		(layer "In4.Cu")
		(net "M_D_CPU0_SA_DQ<22>")
	)
	(arc
		(start 333.118206 -238.491522)
		(mid 333.401162 -238.567699)
		(end 333.684118 -238.491522)
		(width 0.0889)
		(layer "In4.Cu")
		(net "M_D_CPU0_SA_DQ<22>")
	)
	(arc
		(start 332.752446 -238.486696)
		(mid 332.935954 -238.441202)
		(end 333.118206 -238.491522)
		(width 0.0889)
		(layer "In4.Cu")
		(net "M_D_CPU0_SA_DQ<22>")
	)
	(arc
		(start 333.6925 -238.486696)
		(mid 333.876008 -238.441202)
		(end 334.05826 -238.491522)
		(width 0.0889)
		(layer "In4.Cu")
		(net "M_D_CPU0_SA_DQ<22>")
	)
	(arc
		(start 332.178152 -238.491522)
		(mid 332.461108 -238.567699)
		(end 332.744064 -238.491522)
		(width 0.0889)
		(layer "In4.Cu")
		(net "M_D_CPU0_SA_DQ<22>")
	)
	(arc
		(start 336.878168 -238.491522)
		(mid 337.161124 -238.567699)
		(end 337.44408 -238.491522)
		(width 0.0889)
		(layer "In4.Cu")
		(net "M_D_CPU0_SA_DQ<22>")
	)
	(arc
		(start 334.99806 -238.491522)
		(mid 335.281016 -238.567699)
		(end 335.563972 -238.491522)
		(width 0.0889)
		(layer "In4.Cu")
		(net "M_D_CPU0_SA_DQ<22>")
	)
	(arc
		(start 329.924156 -238.491522)
		(mid 330.1111 -238.441267)
		(end 330.298044 -238.491522)
		(width 0.0889)
		(layer "In4.Cu")
		(net "M_D_CPU0_SA_DQ<22>")
	)
	(arc
		(start 331.80401 -238.491522)
		(mid 331.986261 -238.441172)
		(end 332.16977 -238.486696)
		(width 0.0889)
		(layer "In4.Cu")
		(net "M_D_CPU0_SA_DQ<22>")
	)
	(arc
		(start 335.563972 -238.491522)
		(mid 335.746223 -238.441172)
		(end 335.929732 -238.486696)
		(width 0.0889)
		(layer "In4.Cu")
		(net "M_D_CPU0_SA_DQ<22>")
	)
	(arc
		(start 326.539352 -238.491522)
		(mid 326.809509 -238.568284)
		(end 327.083166 -238.505238)
		(width 0.0889)
		(layer "In4.Cu")
		(net "M_D_CPU0_SA_DQ<22>")
	)
	(arc
		(start 328.992484 -238.486696)
		(mid 329.175992 -238.441202)
		(end 329.358244 -238.491522)
		(width 0.0889)
		(layer "In4.Cu")
		(net "M_D_CPU0_SA_DQ<22>")
	)
	(arc
		(start 328.41819 -238.491522)
		(mid 328.701146 -238.567699)
		(end 328.984102 -238.491522)
		(width 0.0889)
		(layer "In4.Cu")
		(net "M_D_CPU0_SA_DQ<22>")
	)
	(segment
		(start 340.918038 -239.08004)
		(end 340.451186 -238.814102)
		(width 0.10668)
		(layer "F.Cu")
		(net "M_D_CPU0_SA_DQ<21>")
	)
	(segment
		(start 331.229716 -239.141508)
		(end 331.238098 -239.136682)
		(width 0.0889)
		(layer "In4.Cu")
		(net "M_D_CPU0_SA_DQ<21>")
	)
	(segment
		(start 296.564304 -224.49663)
		(end 296.794682 -224.49663)
		(width 0.14478)
		(layer "In4.Cu")
		(net "M_D_CPU0_SA_DQ<21>")
	)
	(segment
		(start 298.196762 -223.260158)
		(end 298.500038 -223.260158)
		(width 0.14478)
		(layer "In4.Cu")
		(net "M_D_CPU0_SA_DQ<21>")
	)
	(segment
		(start 296.401236 -224.333562)
		(end 296.564304 -224.49663)
		(width 0.14478)
		(layer "In4.Cu")
		(net "M_D_CPU0_SA_DQ<21>")
	)
	(segment
		(start 285.67507 -224.27311)
		(end 285.67507 -224.318322)
		(width 0.14478)
		(layer "In4.Cu")
		(net "M_D_CPU0_SA_DQ<21>")
	)
	(segment
		(start 306.023772 -224.499932)
		(end 306.185316 -224.338388)
		(width 0.14478)
		(layer "In4.Cu")
		(net "M_D_CPU0_SA_DQ<21>")
	)
	(segment
		(start 304.531014 -224.338388)
		(end 304.692558 -224.499932)
		(width 0.14478)
		(layer "In4.Cu")
		(net "M_D_CPU0_SA_DQ<21>")
	)
	(segment
		(start 325.896478 -238.452914)
		(end 325.896478 -238.746792)
		(width 0.0889)
		(layer "In4.Cu")
		(net "M_D_CPU0_SA_DQ<21>")
	)
	(segment
		(start 289.168078 -224.50171)
		(end 289.331146 -224.338642)
		(width 0.14478)
		(layer "In4.Cu")
		(net "M_D_CPU0_SA_DQ<21>")
	)
	(segment
		(start 306.73675 -223.881696)
		(end 306.73675 -223.948498)
		(width 0.14478)
		(layer "In4.Cu")
		(net "M_D_CPU0_SA_DQ<21>")
	)
	(segment
		(start 325.001636 -237.558072)
		(end 325.896478 -238.452914)
		(width 0.0889)
		(layer "In4.Cu")
		(net "M_D_CPU0_SA_DQ<21>")
	)
	(segment
		(start 335.929732 -239.141508)
		(end 335.938114 -239.136682)
		(width 0.0889)
		(layer "In4.Cu")
		(net "M_D_CPU0_SA_DQ<21>")
	)
	(segment
		(start 305.633882 -223.881696)
		(end 305.633882 -224.338388)
		(width 0.14478)
		(layer "In4.Cu")
		(net "M_D_CPU0_SA_DQ<21>")
	)
	(segment
		(start 305.472338 -223.720152)
		(end 305.633882 -223.881696)
		(width 0.14478)
		(layer "In4.Cu")
		(net "M_D_CPU0_SA_DQ<21>")
	)
	(segment
		(start 306.185316 -223.881696)
		(end 306.34686 -223.720152)
		(width 0.14478)
		(layer "In4.Cu")
		(net "M_D_CPU0_SA_DQ<21>")
	)
	(segment
		(start 339.689694 -239.141508)
		(end 339.698076 -239.136682)
		(width 0.0889)
		(layer "In4.Cu")
		(net "M_D_CPU0_SA_DQ<21>")
	)
	(segment
		(start 304.920904 -224.499932)
		(end 305.082448 -224.338388)
		(width 0.14478)
		(layer "In4.Cu")
		(net "M_D_CPU0_SA_DQ<21>")
	)
	(segment
		(start 293.498778 -223.260158)
		(end 294.348662 -224.110042)
		(width 0.14478)
		(layer "In4.Cu")
		(net "M_D_CPU0_SA_DQ<21>")
	)
	(segment
		(start 327.479914 -239.136428)
		(end 327.50379 -239.122458)
		(width 0.0889)
		(layer "In4.Cu")
		(net "M_D_CPU0_SA_DQ<21>")
	)
	(segment
		(start 285.67507 -224.318322)
		(end 285.838138 -224.48139)
		(width 0.14478)
		(layer "In4.Cu")
		(net "M_D_CPU0_SA_DQ<21>")
	)
	(segment
		(start 305.633882 -224.338388)
		(end 305.795426 -224.499932)
		(width 0.14478)
		(layer "In4.Cu")
		(net "M_D_CPU0_SA_DQ<21>")
	)
	(segment
		(start 299.056552 -223.65081)
		(end 299.21962 -223.487742)
		(width 0.14478)
		(layer "In4.Cu")
		(net "M_D_CPU0_SA_DQ<21>")
	)
	(segment
		(start 291.493702 -223.65081)
		(end 291.65677 -223.487742)
		(width 0.14478)
		(layer "In4.Cu")
		(net "M_D_CPU0_SA_DQ<21>")
	)
	(segment
		(start 288.774632 -224.338642)
		(end 288.9377 -224.50171)
		(width 0.14478)
		(layer "In4.Cu")
		(net "M_D_CPU0_SA_DQ<21>")
	)
	(segment
		(start 285.838138 -224.48139)
		(end 286.068516 -224.48139)
		(width 0.14478)
		(layer "In4.Cu")
		(net "M_D_CPU0_SA_DQ<21>")
	)
	(segment
		(start 291.819838 -223.260158)
		(end 293.498778 -223.260158)
		(width 0.14478)
		(layer "In4.Cu")
		(net "M_D_CPU0_SA_DQ<21>")
	)
	(segment
		(start 306.185316 -224.338388)
		(end 306.185316 -223.881696)
		(width 0.14478)
		(layer "In4.Cu")
		(net "M_D_CPU0_SA_DQ<21>")
	)
	(segment
		(start 336.869786 -239.141508)
		(end 336.878168 -239.136682)
		(width 0.0889)
		(layer "In4.Cu")
		(net "M_D_CPU0_SA_DQ<21>")
	)
	(segment
		(start 296.238168 -224.110042)
		(end 296.401236 -224.27311)
		(width 0.14478)
		(layer "In4.Cu")
		(net "M_D_CPU0_SA_DQ<21>")
	)
	(segment
		(start 286.62503 -223.738694)
		(end 286.788098 -223.901762)
		(width 0.14478)
		(layer "In4.Cu")
		(net "M_D_CPU0_SA_DQ<21>")
	)
	(segment
		(start 305.082448 -223.881696)
		(end 305.243992 -223.720152)
		(width 0.14478)
		(layer "In4.Cu")
		(net "M_D_CPU0_SA_DQ<21>")
	)
	(segment
		(start 306.34686 -223.720152)
		(end 306.575206 -223.720152)
		(width 0.14478)
		(layer "In4.Cu")
		(net "M_D_CPU0_SA_DQ<21>")
	)
	(segment
		(start 286.231584 -224.318322)
		(end 286.231584 -223.901762)
		(width 0.14478)
		(layer "In4.Cu")
		(net "M_D_CPU0_SA_DQ<21>")
	)
	(segment
		(start 291.65677 -223.423226)
		(end 291.819838 -223.260158)
		(width 0.14478)
		(layer "In4.Cu")
		(net "M_D_CPU0_SA_DQ<21>")
	)
	(segment
		(start 332.744064 -239.136682)
		(end 332.752446 -239.141508)
		(width 0.0889)
		(layer "In4.Cu")
		(net "M_D_CPU0_SA_DQ<21>")
	)
	(segment
		(start 287.50768 -224.110042)
		(end 288.611564 -224.110042)
		(width 0.14478)
		(layer "In4.Cu")
		(net "M_D_CPU0_SA_DQ<21>")
	)
	(segment
		(start 340.200742 -239.104932)
		(end 340.297008 -239.079532)
		(width 0.0889)
		(layer "In4.Cu")
		(net "M_D_CPU0_SA_DQ<21>")
	)
	(segment
		(start 305.795426 -224.499932)
		(end 306.023772 -224.499932)
		(width 0.14478)
		(layer "In4.Cu")
		(net "M_D_CPU0_SA_DQ<21>")
	)
	(segment
		(start 297.120818 -224.110042)
		(end 297.346878 -224.110042)
		(width 0.14478)
		(layer "In4.Cu")
		(net "M_D_CPU0_SA_DQ<21>")
	)
	(segment
		(start 307.723286 -224.110042)
		(end 316.674754 -233.06151)
		(width 0.14478)
		(layer "In4.Cu")
		(net "M_D_CPU0_SA_DQ<21>")
	)
	(segment
		(start 299.21962 -223.423226)
		(end 299.382688 -223.260158)
		(width 0.14478)
		(layer "In4.Cu")
		(net "M_D_CPU0_SA_DQ<21>")
	)
	(segment
		(start 316.674754 -234.273852)
		(end 319.808606 -237.407704)
		(width 0.14478)
		(layer "In4.Cu")
		(net "M_D_CPU0_SA_DQ<21>")
	)
	(segment
		(start 306.73675 -223.948498)
		(end 306.898294 -224.110042)
		(width 0.14478)
		(layer "In4.Cu")
		(net "M_D_CPU0_SA_DQ<21>")
	)
	(segment
		(start 296.794682 -224.49663)
		(end 296.95775 -224.333562)
		(width 0.14478)
		(layer "In4.Cu")
		(net "M_D_CPU0_SA_DQ<21>")
	)
	(segment
		(start 306.575206 -223.720152)
		(end 306.73675 -223.881696)
		(width 0.14478)
		(layer "In4.Cu")
		(net "M_D_CPU0_SA_DQ<21>")
	)
	(segment
		(start 301.174658 -223.260158)
		(end 302.024542 -224.110042)
		(width 0.14478)
		(layer "In4.Cu")
		(net "M_D_CPU0_SA_DQ<21>")
	)
	(segment
		(start 288.9377 -224.50171)
		(end 289.168078 -224.50171)
		(width 0.14478)
		(layer "In4.Cu")
		(net "M_D_CPU0_SA_DQ<21>")
	)
	(segment
		(start 332.16977 -239.141508)
		(end 332.178152 -239.136682)
		(width 0.0889)
		(layer "In4.Cu")
		(net "M_D_CPU0_SA_DQ<21>")
	)
	(segment
		(start 287.344612 -224.27311)
		(end 287.50768 -224.110042)
		(width 0.14478)
		(layer "In4.Cu")
		(net "M_D_CPU0_SA_DQ<21>")
	)
	(segment
		(start 291.263324 -223.65081)
		(end 291.493702 -223.65081)
		(width 0.14478)
		(layer "In4.Cu")
		(net "M_D_CPU0_SA_DQ<21>")
	)
	(segment
		(start 327.459848 -239.147858)
		(end 327.479914 -239.136428)
		(width 0.0889)
		(layer "In4.Cu")
		(net "M_D_CPU0_SA_DQ<21>")
	)
	(segment
		(start 340.297008 -239.079532)
		(end 340.451186 -238.814102)
		(width 0.0889)
		(layer "In4.Cu")
		(net "M_D_CPU0_SA_DQ<21>")
	)
	(segment
		(start 286.231584 -223.901762)
		(end 286.394652 -223.738694)
		(width 0.14478)
		(layer "In4.Cu")
		(net "M_D_CPU0_SA_DQ<21>")
	)
	(segment
		(start 327.079356 -239.12068)
		(end 327.107042 -239.136682)
		(width 0.0889)
		(layer "In4.Cu")
		(net "M_D_CPU0_SA_DQ<21>")
	)
	(segment
		(start 289.331146 -224.338642)
		(end 289.331146 -224.27311)
		(width 0.14478)
		(layer "In4.Cu")
		(net "M_D_CPU0_SA_DQ<21>")
	)
	(segment
		(start 304.531014 -224.271586)
		(end 304.531014 -224.338388)
		(width 0.14478)
		(layer "In4.Cu")
		(net "M_D_CPU0_SA_DQ<21>")
	)
	(segment
		(start 291.100256 -223.423226)
		(end 291.100256 -223.487742)
		(width 0.14478)
		(layer "In4.Cu")
		(net "M_D_CPU0_SA_DQ<21>")
	)
	(segment
		(start 296.95775 -224.27311)
		(end 297.120818 -224.110042)
		(width 0.14478)
		(layer "In4.Cu")
		(net "M_D_CPU0_SA_DQ<21>")
	)
	(segment
		(start 296.401236 -224.27311)
		(end 296.401236 -224.333562)
		(width 0.14478)
		(layer "In4.Cu")
		(net "M_D_CPU0_SA_DQ<21>")
	)
	(segment
		(start 285.512002 -224.110042)
		(end 285.67507 -224.27311)
		(width 0.14478)
		(layer "In4.Cu")
		(net "M_D_CPU0_SA_DQ<21>")
	)
	(segment
		(start 305.243992 -223.720152)
		(end 305.472338 -223.720152)
		(width 0.14478)
		(layer "In4.Cu")
		(net "M_D_CPU0_SA_DQ<21>")
	)
	(segment
		(start 284.736032 -223.6851)
		(end 285.160974 -224.110042)
		(width 0.14478)
		(layer "In4.Cu")
		(net "M_D_CPU0_SA_DQ<21>")
	)
	(segment
		(start 296.95775 -224.333562)
		(end 296.95775 -224.27311)
		(width 0.14478)
		(layer "In4.Cu")
		(net "M_D_CPU0_SA_DQ<21>")
	)
	(segment
		(start 328.984102 -239.136682)
		(end 328.992484 -239.141508)
		(width 0.0889)
		(layer "In4.Cu")
		(net "M_D_CPU0_SA_DQ<21>")
	)
	(segment
		(start 288.774632 -224.27311)
		(end 288.774632 -224.338642)
		(width 0.14478)
		(layer "In4.Cu")
		(net "M_D_CPU0_SA_DQ<21>")
	)
	(segment
		(start 287.344612 -224.318322)
		(end 287.344612 -224.27311)
		(width 0.14478)
		(layer "In4.Cu")
		(net "M_D_CPU0_SA_DQ<21>")
	)
	(segment
		(start 302.024542 -224.110042)
		(end 304.36947 -224.110042)
		(width 0.14478)
		(layer "In4.Cu")
		(net "M_D_CPU0_SA_DQ<21>")
	)
	(segment
		(start 305.082448 -224.338388)
		(end 305.082448 -223.881696)
		(width 0.14478)
		(layer "In4.Cu")
		(net "M_D_CPU0_SA_DQ<21>")
	)
	(segment
		(start 328.409808 -239.141508)
		(end 328.41819 -239.136682)
		(width 0.0889)
		(layer "In4.Cu")
		(net "M_D_CPU0_SA_DQ<21>")
	)
	(segment
		(start 324.189598 -237.558072)
		(end 325.001636 -237.558072)
		(width 0.0889)
		(layer "In4.Cu")
		(net "M_D_CPU0_SA_DQ<21>")
	)
	(segment
		(start 289.494214 -224.110042)
		(end 289.823398 -224.110042)
		(width 0.14478)
		(layer "In4.Cu")
		(net "M_D_CPU0_SA_DQ<21>")
	)
	(segment
		(start 333.684118 -239.136682)
		(end 333.6925 -239.141508)
		(width 0.0889)
		(layer "In4.Cu")
		(net "M_D_CPU0_SA_DQ<21>")
	)
	(segment
		(start 306.898294 -224.110042)
		(end 307.723286 -224.110042)
		(width 0.14478)
		(layer "In4.Cu")
		(net "M_D_CPU0_SA_DQ<21>")
	)
	(segment
		(start 286.951166 -224.48139)
		(end 287.181544 -224.48139)
		(width 0.14478)
		(layer "In4.Cu")
		(net "M_D_CPU0_SA_DQ<21>")
	)
	(segment
		(start 299.382688 -223.260158)
		(end 301.174658 -223.260158)
		(width 0.14478)
		(layer "In4.Cu")
		(net "M_D_CPU0_SA_DQ<21>")
	)
	(segment
		(start 324.03923 -237.407704)
		(end 324.189598 -237.558072)
		(width 0.0889)
		(layer "In4.Cu")
		(net "M_D_CPU0_SA_DQ<21>")
	)
	(segment
		(start 290.673282 -223.260158)
		(end 290.937188 -223.260158)
		(width 0.14478)
		(layer "In4.Cu")
		(net "M_D_CPU0_SA_DQ<21>")
	)
	(segment
		(start 291.65677 -223.487742)
		(end 291.65677 -223.423226)
		(width 0.14478)
		(layer "In4.Cu")
		(net "M_D_CPU0_SA_DQ<21>")
	)
	(segment
		(start 289.823398 -224.110042)
		(end 290.673282 -223.260158)
		(width 0.14478)
		(layer "In4.Cu")
		(net "M_D_CPU0_SA_DQ<21>")
	)
	(segment
		(start 290.937188 -223.260158)
		(end 291.100256 -223.423226)
		(width 0.14478)
		(layer "In4.Cu")
		(net "M_D_CPU0_SA_DQ<21>")
	)
	(segment
		(start 286.788098 -224.318322)
		(end 286.951166 -224.48139)
		(width 0.14478)
		(layer "In4.Cu")
		(net "M_D_CPU0_SA_DQ<21>")
	)
	(segment
		(start 285.160974 -224.110042)
		(end 285.512002 -224.110042)
		(width 0.14478)
		(layer "In4.Cu")
		(net "M_D_CPU0_SA_DQ<21>")
	)
	(segment
		(start 323.873368 -237.407704)
		(end 324.03923 -237.407704)
		(width 0.0889)
		(layer "In4.Cu")
		(net "M_D_CPU0_SA_DQ<21>")
	)
	(segment
		(start 304.36947 -224.110042)
		(end 304.531014 -224.271586)
		(width 0.14478)
		(layer "In4.Cu")
		(net "M_D_CPU0_SA_DQ<21>")
	)
	(segment
		(start 337.44408 -239.136682)
		(end 337.452462 -239.141508)
		(width 0.0889)
		(layer "In4.Cu")
		(net "M_D_CPU0_SA_DQ<21>")
	)
	(segment
		(start 298.500038 -223.260158)
		(end 298.663106 -223.423226)
		(width 0.14478)
		(layer "In4.Cu")
		(net "M_D_CPU0_SA_DQ<21>")
	)
	(segment
		(start 286.394652 -223.738694)
		(end 286.62503 -223.738694)
		(width 0.14478)
		(layer "In4.Cu")
		(net "M_D_CPU0_SA_DQ<21>")
	)
	(segment
		(start 316.674754 -233.06151)
		(end 316.674754 -234.273852)
		(width 0.14478)
		(layer "In4.Cu")
		(net "M_D_CPU0_SA_DQ<21>")
	)
	(segment
		(start 319.808606 -237.407704)
		(end 323.873368 -237.407704)
		(width 0.14478)
		(layer "In4.Cu")
		(net "M_D_CPU0_SA_DQ<21>")
	)
	(segment
		(start 304.692558 -224.499932)
		(end 304.920904 -224.499932)
		(width 0.14478)
		(layer "In4.Cu")
		(net "M_D_CPU0_SA_DQ<21>")
	)
	(segment
		(start 289.331146 -224.27311)
		(end 289.494214 -224.110042)
		(width 0.14478)
		(layer "In4.Cu")
		(net "M_D_CPU0_SA_DQ<21>")
	)
	(segment
		(start 291.100256 -223.487742)
		(end 291.263324 -223.65081)
		(width 0.14478)
		(layer "In4.Cu")
		(net "M_D_CPU0_SA_DQ<21>")
	)
	(segment
		(start 298.663106 -223.487742)
		(end 298.826174 -223.65081)
		(width 0.14478)
		(layer "In4.Cu")
		(net "M_D_CPU0_SA_DQ<21>")
	)
	(segment
		(start 286.788098 -223.901762)
		(end 286.788098 -224.318322)
		(width 0.14478)
		(layer "In4.Cu")
		(net "M_D_CPU0_SA_DQ<21>")
	)
	(segment
		(start 297.346878 -224.110042)
		(end 298.196762 -223.260158)
		(width 0.14478)
		(layer "In4.Cu")
		(net "M_D_CPU0_SA_DQ<21>")
	)
	(segment
		(start 299.21962 -223.487742)
		(end 299.21962 -223.423226)
		(width 0.14478)
		(layer "In4.Cu")
		(net "M_D_CPU0_SA_DQ<21>")
	)
	(segment
		(start 298.826174 -223.65081)
		(end 299.056552 -223.65081)
		(width 0.14478)
		(layer "In4.Cu")
		(net "M_D_CPU0_SA_DQ<21>")
	)
	(segment
		(start 294.348662 -224.110042)
		(end 296.238168 -224.110042)
		(width 0.14478)
		(layer "In4.Cu")
		(net "M_D_CPU0_SA_DQ<21>")
	)
	(segment
		(start 286.068516 -224.48139)
		(end 286.231584 -224.318322)
		(width 0.14478)
		(layer "In4.Cu")
		(net "M_D_CPU0_SA_DQ<21>")
	)
	(segment
		(start 326.337676 -239.18799)
		(end 326.351138 -239.18799)
		(width 0.0889)
		(layer "In4.Cu")
		(net "M_D_CPU0_SA_DQ<21>")
	)
	(segment
		(start 287.181544 -224.48139)
		(end 287.344612 -224.318322)
		(width 0.14478)
		(layer "In4.Cu")
		(net "M_D_CPU0_SA_DQ<21>")
	)
	(segment
		(start 288.611564 -224.110042)
		(end 288.774632 -224.27311)
		(width 0.14478)
		(layer "In4.Cu")
		(net "M_D_CPU0_SA_DQ<21>")
	)
	(segment
		(start 298.663106 -223.423226)
		(end 298.663106 -223.487742)
		(width 0.14478)
		(layer "In4.Cu")
		(net "M_D_CPU0_SA_DQ<21>")
	)
	(arc
		(start 332.178152 -239.136682)
		(mid 332.461108 -239.060505)
		(end 332.744064 -239.136682)
		(width 0.0889)
		(layer "In4.Cu")
		(net "M_D_CPU0_SA_DQ<21>")
	)
	(arc
		(start 327.107042 -239.136682)
		(mid 327.282027 -239.186626)
		(end 327.459848 -239.147858)
		(width 0.0889)
		(layer "In4.Cu")
		(net "M_D_CPU0_SA_DQ<21>")
	)
	(arc
		(start 333.118206 -239.136682)
		(mid 333.401162 -239.060505)
		(end 333.684118 -239.136682)
		(width 0.0889)
		(layer "In4.Cu")
		(net "M_D_CPU0_SA_DQ<21>")
	)
	(arc
		(start 336.504026 -239.136682)
		(mid 336.686277 -239.187032)
		(end 336.869786 -239.141508)
		(width 0.0889)
		(layer "In4.Cu")
		(net "M_D_CPU0_SA_DQ<21>")
	)
	(arc
		(start 329.358244 -239.136682)
		(mid 329.6412 -239.060505)
		(end 329.924156 -239.136682)
		(width 0.0889)
		(layer "In4.Cu")
		(net "M_D_CPU0_SA_DQ<21>")
	)
	(arc
		(start 339.698076 -239.136682)
		(mid 339.945672 -239.061504)
		(end 340.200742 -239.104932)
		(width 0.0889)
		(layer "In4.Cu")
		(net "M_D_CPU0_SA_DQ<21>")
	)
	(arc
		(start 331.238098 -239.136682)
		(mid 331.521054 -239.060505)
		(end 331.80401 -239.136682)
		(width 0.0889)
		(layer "In4.Cu")
		(net "M_D_CPU0_SA_DQ<21>")
	)
	(arc
		(start 336.878168 -239.136682)
		(mid 337.161124 -239.060505)
		(end 337.44408 -239.136682)
		(width 0.0889)
		(layer "In4.Cu")
		(net "M_D_CPU0_SA_DQ<21>")
	)
	(arc
		(start 335.563972 -239.136682)
		(mid 335.746223 -239.187032)
		(end 335.929732 -239.141508)
		(width 0.0889)
		(layer "In4.Cu")
		(net "M_D_CPU0_SA_DQ<21>")
	)
	(arc
		(start 328.044048 -239.136682)
		(mid 328.226299 -239.187032)
		(end 328.409808 -239.141508)
		(width 0.0889)
		(layer "In4.Cu")
		(net "M_D_CPU0_SA_DQ<21>")
	)
	(arc
		(start 332.752446 -239.141508)
		(mid 332.935954 -239.187002)
		(end 333.118206 -239.136682)
		(width 0.0889)
		(layer "In4.Cu")
		(net "M_D_CPU0_SA_DQ<21>")
	)
	(arc
		(start 328.41819 -239.136682)
		(mid 328.701146 -239.060505)
		(end 328.984102 -239.136682)
		(width 0.0889)
		(layer "In4.Cu")
		(net "M_D_CPU0_SA_DQ<21>")
	)
	(arc
		(start 338.758022 -239.136682)
		(mid 339.040978 -239.060505)
		(end 339.323934 -239.136682)
		(width 0.0889)
		(layer "In4.Cu")
		(net "M_D_CPU0_SA_DQ<21>")
	)
	(arc
		(start 331.80401 -239.136682)
		(mid 331.986261 -239.187032)
		(end 332.16977 -239.141508)
		(width 0.0889)
		(layer "In4.Cu")
		(net "M_D_CPU0_SA_DQ<21>")
	)
	(arc
		(start 339.323934 -239.136682)
		(mid 339.506185 -239.187032)
		(end 339.689694 -239.141508)
		(width 0.0889)
		(layer "In4.Cu")
		(net "M_D_CPU0_SA_DQ<21>")
	)
	(arc
		(start 330.863956 -239.136682)
		(mid 331.046207 -239.187032)
		(end 331.229716 -239.141508)
		(width 0.0889)
		(layer "In4.Cu")
		(net "M_D_CPU0_SA_DQ<21>")
	)
	(arc
		(start 335.938114 -239.136682)
		(mid 336.22107 -239.060505)
		(end 336.504026 -239.136682)
		(width 0.0889)
		(layer "In4.Cu")
		(net "M_D_CPU0_SA_DQ<21>")
	)
	(arc
		(start 330.298044 -239.136682)
		(mid 330.581 -239.060505)
		(end 330.863956 -239.136682)
		(width 0.0889)
		(layer "In4.Cu")
		(net "M_D_CPU0_SA_DQ<21>")
	)
	(arc
		(start 329.924156 -239.136682)
		(mid 330.1111 -239.186937)
		(end 330.298044 -239.136682)
		(width 0.0889)
		(layer "In4.Cu")
		(net "M_D_CPU0_SA_DQ<21>")
	)
	(arc
		(start 325.896478 -238.746792)
		(mid 326.025702 -239.058766)
		(end 326.337676 -239.18799)
		(width 0.0889)
		(layer "In4.Cu")
		(net "M_D_CPU0_SA_DQ<21>")
	)
	(arc
		(start 334.99806 -239.136682)
		(mid 335.281016 -239.060505)
		(end 335.563972 -239.136682)
		(width 0.0889)
		(layer "In4.Cu")
		(net "M_D_CPU0_SA_DQ<21>")
	)
	(arc
		(start 326.539352 -239.136682)
		(mid 326.807321 -239.059859)
		(end 327.079356 -239.12068)
		(width 0.0889)
		(layer "In4.Cu")
		(net "M_D_CPU0_SA_DQ<21>")
	)
	(arc
		(start 337.452462 -239.141508)
		(mid 337.63597 -239.187002)
		(end 337.818222 -239.136682)
		(width 0.0889)
		(layer "In4.Cu")
		(net "M_D_CPU0_SA_DQ<21>")
	)
	(arc
		(start 334.624172 -239.136682)
		(mid 334.811116 -239.186937)
		(end 334.99806 -239.136682)
		(width 0.0889)
		(layer "In4.Cu")
		(net "M_D_CPU0_SA_DQ<21>")
	)
	(arc
		(start 326.351138 -239.18799)
		(mid 326.448652 -239.174835)
		(end 326.539352 -239.136682)
		(width 0.0889)
		(layer "In4.Cu")
		(net "M_D_CPU0_SA_DQ<21>")
	)
	(arc
		(start 333.6925 -239.141508)
		(mid 333.876008 -239.187002)
		(end 334.05826 -239.136682)
		(width 0.0889)
		(layer "In4.Cu")
		(net "M_D_CPU0_SA_DQ<21>")
	)
	(arc
		(start 328.992484 -239.141508)
		(mid 329.175992 -239.187002)
		(end 329.358244 -239.136682)
		(width 0.0889)
		(layer "In4.Cu")
		(net "M_D_CPU0_SA_DQ<21>")
	)
	(arc
		(start 338.384134 -239.136682)
		(mid 338.571078 -239.186937)
		(end 338.758022 -239.136682)
		(width 0.0889)
		(layer "In4.Cu")
		(net "M_D_CPU0_SA_DQ<21>")
	)
	(arc
		(start 334.05826 -239.136682)
		(mid 334.341216 -239.060505)
		(end 334.624172 -239.136682)
		(width 0.0889)
		(layer "In4.Cu")
		(net "M_D_CPU0_SA_DQ<21>")
	)
	(arc
		(start 337.818222 -239.136682)
		(mid 338.101178 -239.060505)
		(end 338.384134 -239.136682)
		(width 0.0889)
		(layer "In4.Cu")
		(net "M_D_CPU0_SA_DQ<21>")
	)
	(arc
		(start 327.50379 -239.122458)
		(mid 327.775727 -239.060632)
		(end 328.044048 -239.136682)
		(width 0.0889)
		(layer "In4.Cu")
		(net "M_D_CPU0_SA_DQ<21>")
	)
	(segment
		(start 339.508084 -238.270034)
		(end 339.040978 -238.004096)
		(width 0.10668)
		(layer "F.Cu")
		(net "M_D_CPU0_SA_DQ<20>")
	)
	(segment
		(start 331.33411 -238.326676)
		(end 331.342492 -238.331502)
		(width 0.0889)
		(layer "In4.Cu")
		(net "M_D_CPU0_SA_DQ<20>")
	)
	(segment
		(start 318.82715 -234.159552)
		(end 318.444118 -234.542584)
		(width 0.14478)
		(layer "In4.Cu")
		(net "M_D_CPU0_SA_DQ<20>")
	)
	(segment
		(start 319.607438 -234.93984)
		(end 319.224406 -235.322872)
		(width 0.14478)
		(layer "In4.Cu")
		(net "M_D_CPU0_SA_DQ<20>")
	)
	(segment
		(start 333.579724 -238.331502)
		(end 333.588106 -238.326676)
		(width 0.0889)
		(layer "In4.Cu")
		(net "M_D_CPU0_SA_DQ<20>")
	)
	(segment
		(start 286.837882 -222.636842)
		(end 287.00095 -222.79991)
		(width 0.14478)
		(layer "In4.Cu")
		(net "M_D_CPU0_SA_DQ<20>")
	)
	(segment
		(start 335.094072 -238.326676)
		(end 335.102454 -238.331502)
		(width 0.0889)
		(layer "In4.Cu")
		(net "M_D_CPU0_SA_DQ<20>")
	)
	(segment
		(start 318.444118 -234.770676)
		(end 318.60617 -234.932728)
		(width 0.14478)
		(layer "In4.Cu")
		(net "M_D_CPU0_SA_DQ<20>")
	)
	(segment
		(start 320.77787 -236.110526)
		(end 321.005962 -236.110526)
		(width 0.14478)
		(layer "In4.Cu")
		(net "M_D_CPU0_SA_DQ<20>")
	)
	(segment
		(start 319.445386 -234.54995)
		(end 319.607438 -234.712002)
		(width 0.14478)
		(layer "In4.Cu")
		(net "M_D_CPU0_SA_DQ<20>")
	)
	(segment
		(start 319.997582 -235.330238)
		(end 320.225674 -235.330238)
		(width 0.14478)
		(layer "In4.Cu")
		(net "M_D_CPU0_SA_DQ<20>")
	)
	(segment
		(start 287.394396 -222.636842)
		(end 287.394396 -222.573088)
		(width 0.14478)
		(layer "In4.Cu")
		(net "M_D_CPU0_SA_DQ<20>")
	)
	(segment
		(start 338.27974 -238.331502)
		(end 338.288122 -238.326676)
		(width 0.0889)
		(layer "In4.Cu")
		(net "M_D_CPU0_SA_DQ<20>")
	)
	(segment
		(start 317.825882 -234.15244)
		(end 318.054228 -234.15244)
		(width 0.14478)
		(layer "In4.Cu")
		(net "M_D_CPU0_SA_DQ<20>")
	)
	(segment
		(start 318.046862 -233.151426)
		(end 318.046862 -233.379264)
		(width 0.14478)
		(layer "In4.Cu")
		(net "M_D_CPU0_SA_DQ<20>")
	)
	(segment
		(start 318.834516 -234.932728)
		(end 319.217294 -234.54995)
		(width 0.14478)
		(layer "In4.Cu")
		(net "M_D_CPU0_SA_DQ<20>")
	)
	(segment
		(start 285.947612 -221.70771)
		(end 286.11068 -221.870778)
		(width 0.14478)
		(layer "In4.Cu")
		(net "M_D_CPU0_SA_DQ<20>")
	)
	(segment
		(start 287.00095 -222.79991)
		(end 287.231328 -222.79991)
		(width 0.14478)
		(layer "In4.Cu")
		(net "M_D_CPU0_SA_DQ<20>")
	)
	(segment
		(start 338.887054 -238.269526)
		(end 339.040978 -238.004096)
		(width 0.0889)
		(layer "In4.Cu")
		(net "M_D_CPU0_SA_DQ<20>")
	)
	(segment
		(start 321.39382 -236.498384)
		(end 323.897498 -236.498384)
		(width 0.14478)
		(layer "In4.Cu")
		(net "M_D_CPU0_SA_DQ<20>")
	)
	(segment
		(start 338.791042 -238.294926)
		(end 338.887054 -238.269526)
		(width 0.0889)
		(layer "In4.Cu")
		(net "M_D_CPU0_SA_DQ<20>")
	)
	(segment
		(start 318.054228 -234.15244)
		(end 318.437006 -233.769662)
		(width 0.14478)
		(layer "In4.Cu")
		(net "M_D_CPU0_SA_DQ<20>")
	)
	(segment
		(start 286.837882 -222.573088)
		(end 286.837882 -222.636842)
		(width 0.14478)
		(layer "In4.Cu")
		(net "M_D_CPU0_SA_DQ<20>")
	)
	(segment
		(start 318.437006 -233.769662)
		(end 318.665098 -233.769662)
		(width 0.14478)
		(layer "In4.Cu")
		(net "M_D_CPU0_SA_DQ<20>")
	)
	(segment
		(start 319.614804 -235.713016)
		(end 319.997582 -235.330238)
		(width 0.14478)
		(layer "In4.Cu")
		(net "M_D_CPU0_SA_DQ<20>")
	)
	(segment
		(start 290.66363 -221.569788)
		(end 293.50843 -221.569788)
		(width 0.14478)
		(layer "In4.Cu")
		(net "M_D_CPU0_SA_DQ<20>")
	)
	(segment
		(start 287.394396 -222.573088)
		(end 287.547812 -222.419672)
		(width 0.14478)
		(layer "In4.Cu")
		(net "M_D_CPU0_SA_DQ<20>")
	)
	(segment
		(start 307.824378 -222.600012)
		(end 307.824378 -222.928942)
		(width 0.14478)
		(layer "In4.Cu")
		(net "M_D_CPU0_SA_DQ<20>")
	)
	(segment
		(start 293.50843 -221.569788)
		(end 294.358314 -222.419672)
		(width 0.14478)
		(layer "In4.Cu")
		(net "M_D_CPU0_SA_DQ<20>")
	)
	(segment
		(start 319.224406 -235.322872)
		(end 319.224406 -235.550964)
		(width 0.14478)
		(layer "In4.Cu")
		(net "M_D_CPU0_SA_DQ<20>")
	)
	(segment
		(start 318.444118 -234.542584)
		(end 318.444118 -234.770676)
		(width 0.14478)
		(layer "In4.Cu")
		(net "M_D_CPU0_SA_DQ<20>")
	)
	(segment
		(start 326.991726 -238.337598)
		(end 327.010522 -238.326676)
		(width 0.0889)
		(layer "In4.Cu")
		(net "M_D_CPU0_SA_DQ<20>")
	)
	(segment
		(start 286.2834 -222.419672)
		(end 286.684466 -222.419672)
		(width 0.14478)
		(layer "In4.Cu")
		(net "M_D_CPU0_SA_DQ<20>")
	)
	(segment
		(start 319.224406 -235.550964)
		(end 319.386458 -235.713016)
		(width 0.14478)
		(layer "In4.Cu")
		(net "M_D_CPU0_SA_DQ<20>")
	)
	(segment
		(start 320.004694 -236.331252)
		(end 320.166746 -236.493304)
		(width 0.14478)
		(layer "In4.Cu")
		(net "M_D_CPU0_SA_DQ<20>")
	)
	(segment
		(start 297.337226 -222.419672)
		(end 298.18711 -221.569788)
		(width 0.14478)
		(layer "In4.Cu")
		(net "M_D_CPU0_SA_DQ<20>")
	)
	(segment
		(start 320.395092 -236.493304)
		(end 320.77787 -236.110526)
		(width 0.14478)
		(layer "In4.Cu")
		(net "M_D_CPU0_SA_DQ<20>")
	)
	(segment
		(start 320.166746 -236.493304)
		(end 320.395092 -236.493304)
		(width 0.14478)
		(layer "In4.Cu")
		(net "M_D_CPU0_SA_DQ<20>")
	)
	(segment
		(start 320.387726 -235.49229)
		(end 320.387726 -235.720128)
		(width 0.14478)
		(layer "In4.Cu")
		(net "M_D_CPU0_SA_DQ<20>")
	)
	(segment
		(start 301.106078 -221.569788)
		(end 301.955962 -222.419672)
		(width 0.14478)
		(layer "In4.Cu")
		(net "M_D_CPU0_SA_DQ<20>")
	)
	(segment
		(start 330.394056 -238.326676)
		(end 330.402438 -238.331502)
		(width 0.0889)
		(layer "In4.Cu")
		(net "M_D_CPU0_SA_DQ<20>")
	)
	(segment
		(start 320.004694 -236.10316)
		(end 320.004694 -236.331252)
		(width 0.14478)
		(layer "In4.Cu")
		(net "M_D_CPU0_SA_DQ<20>")
	)
	(segment
		(start 326.329548 -238.249968)
		(end 326.351138 -238.249968)
		(width 0.0889)
		(layer "In4.Cu")
		(net "M_D_CPU0_SA_DQ<20>")
	)
	(segment
		(start 307.824378 -222.928942)
		(end 318.046862 -233.151426)
		(width 0.14478)
		(layer "In4.Cu")
		(net "M_D_CPU0_SA_DQ<20>")
	)
	(segment
		(start 286.11068 -221.870778)
		(end 286.11068 -222.246952)
		(width 0.14478)
		(layer "In4.Cu")
		(net "M_D_CPU0_SA_DQ<20>")
	)
	(segment
		(start 285.391098 -222.41002)
		(end 285.554166 -222.246952)
		(width 0.14478)
		(layer "In4.Cu")
		(net "M_D_CPU0_SA_DQ<20>")
	)
	(segment
		(start 325.101712 -237.022132)
		(end 326.329548 -238.249968)
		(width 0.0889)
		(layer "In4.Cu")
		(net "M_D_CPU0_SA_DQ<20>")
	)
	(segment
		(start 318.046862 -233.379264)
		(end 317.66383 -233.762296)
		(width 0.14478)
		(layer "In4.Cu")
		(net "M_D_CPU0_SA_DQ<20>")
	)
	(segment
		(start 285.717234 -221.70771)
		(end 285.947612 -221.70771)
		(width 0.14478)
		(layer "In4.Cu")
		(net "M_D_CPU0_SA_DQ<20>")
	)
	(segment
		(start 318.82715 -233.931714)
		(end 318.82715 -234.159552)
		(width 0.14478)
		(layer "In4.Cu")
		(net "M_D_CPU0_SA_DQ<20>")
	)
	(segment
		(start 334.519778 -238.331502)
		(end 334.52816 -238.326676)
		(width 0.0889)
		(layer "In4.Cu")
		(net "M_D_CPU0_SA_DQ<20>")
	)
	(segment
		(start 318.665098 -233.769662)
		(end 318.82715 -233.931714)
		(width 0.14478)
		(layer "In4.Cu")
		(net "M_D_CPU0_SA_DQ<20>")
	)
	(segment
		(start 285.160974 -222.41002)
		(end 285.391098 -222.41002)
		(width 0.14478)
		(layer "In4.Cu")
		(net "M_D_CPU0_SA_DQ<20>")
	)
	(segment
		(start 319.607438 -234.712002)
		(end 319.607438 -234.93984)
		(width 0.14478)
		(layer "In4.Cu")
		(net "M_D_CPU0_SA_DQ<20>")
	)
	(segment
		(start 294.358314 -222.419672)
		(end 297.337226 -222.419672)
		(width 0.14478)
		(layer "In4.Cu")
		(net "M_D_CPU0_SA_DQ<20>")
	)
	(segment
		(start 287.547812 -222.419672)
		(end 289.813746 -222.419672)
		(width 0.14478)
		(layer "In4.Cu")
		(net "M_D_CPU0_SA_DQ<20>")
	)
	(segment
		(start 321.005962 -236.110526)
		(end 321.39382 -236.498384)
		(width 0.14478)
		(layer "In4.Cu")
		(net "M_D_CPU0_SA_DQ<20>")
	)
	(segment
		(start 284.736032 -221.985078)
		(end 285.160974 -222.41002)
		(width 0.14478)
		(layer "In4.Cu")
		(net "M_D_CPU0_SA_DQ<20>")
	)
	(segment
		(start 320.387726 -235.720128)
		(end 320.004694 -236.10316)
		(width 0.14478)
		(layer "In4.Cu")
		(net "M_D_CPU0_SA_DQ<20>")
	)
	(segment
		(start 318.60617 -234.932728)
		(end 318.834516 -234.932728)
		(width 0.14478)
		(layer "In4.Cu")
		(net "M_D_CPU0_SA_DQ<20>")
	)
	(segment
		(start 323.897498 -236.498384)
		(end 324.07987 -236.498384)
		(width 0.0889)
		(layer "In4.Cu")
		(net "M_D_CPU0_SA_DQ<20>")
	)
	(segment
		(start 287.231328 -222.79991)
		(end 287.394396 -222.636842)
		(width 0.14478)
		(layer "In4.Cu")
		(net "M_D_CPU0_SA_DQ<20>")
	)
	(segment
		(start 327.55332 -238.313976)
		(end 327.57491 -238.326422)
		(width 0.0889)
		(layer "In4.Cu")
		(net "M_D_CPU0_SA_DQ<20>")
	)
	(segment
		(start 327.57491 -238.326422)
		(end 327.594976 -238.337852)
		(width 0.0889)
		(layer "In4.Cu")
		(net "M_D_CPU0_SA_DQ<20>")
	)
	(segment
		(start 298.18711 -221.569788)
		(end 301.106078 -221.569788)
		(width 0.14478)
		(layer "In4.Cu")
		(net "M_D_CPU0_SA_DQ<20>")
	)
	(segment
		(start 324.07987 -236.498384)
		(end 324.603618 -237.022132)
		(width 0.0889)
		(layer "In4.Cu")
		(net "M_D_CPU0_SA_DQ<20>")
	)
	(segment
		(start 320.225674 -235.330238)
		(end 320.387726 -235.49229)
		(width 0.14478)
		(layer "In4.Cu")
		(net "M_D_CPU0_SA_DQ<20>")
	)
	(segment
		(start 285.554166 -222.246952)
		(end 285.554166 -221.870778)
		(width 0.14478)
		(layer "In4.Cu")
		(net "M_D_CPU0_SA_DQ<20>")
	)
	(segment
		(start 336.034126 -238.326676)
		(end 336.042508 -238.331502)
		(width 0.0889)
		(layer "In4.Cu")
		(net "M_D_CPU0_SA_DQ<20>")
	)
	(segment
		(start 317.66383 -233.762296)
		(end 317.66383 -233.990388)
		(width 0.14478)
		(layer "In4.Cu")
		(net "M_D_CPU0_SA_DQ<20>")
	)
	(segment
		(start 301.955962 -222.419672)
		(end 307.644038 -222.419672)
		(width 0.14478)
		(layer "In4.Cu")
		(net "M_D_CPU0_SA_DQ<20>")
	)
	(segment
		(start 324.603618 -237.022132)
		(end 325.101712 -237.022132)
		(width 0.0889)
		(layer "In4.Cu")
		(net "M_D_CPU0_SA_DQ<20>")
	)
	(segment
		(start 329.819762 -238.331502)
		(end 329.828144 -238.326676)
		(width 0.0889)
		(layer "In4.Cu")
		(net "M_D_CPU0_SA_DQ<20>")
	)
	(segment
		(start 286.684466 -222.419672)
		(end 286.837882 -222.573088)
		(width 0.14478)
		(layer "In4.Cu")
		(net "M_D_CPU0_SA_DQ<20>")
	)
	(segment
		(start 307.644038 -222.419672)
		(end 307.824378 -222.600012)
		(width 0.14478)
		(layer "In4.Cu")
		(net "M_D_CPU0_SA_DQ<20>")
	)
	(segment
		(start 289.813746 -222.419672)
		(end 290.66363 -221.569788)
		(width 0.14478)
		(layer "In4.Cu")
		(net "M_D_CPU0_SA_DQ<20>")
	)
	(segment
		(start 286.11068 -222.246952)
		(end 286.2834 -222.419672)
		(width 0.14478)
		(layer "In4.Cu")
		(net "M_D_CPU0_SA_DQ<20>")
	)
	(segment
		(start 285.554166 -221.870778)
		(end 285.717234 -221.70771)
		(width 0.14478)
		(layer "In4.Cu")
		(net "M_D_CPU0_SA_DQ<20>")
	)
	(segment
		(start 317.66383 -233.990388)
		(end 317.825882 -234.15244)
		(width 0.14478)
		(layer "In4.Cu")
		(net "M_D_CPU0_SA_DQ<20>")
	)
	(segment
		(start 319.217294 -234.54995)
		(end 319.445386 -234.54995)
		(width 0.14478)
		(layer "In4.Cu")
		(net "M_D_CPU0_SA_DQ<20>")
	)
	(segment
		(start 319.386458 -235.713016)
		(end 319.614804 -235.713016)
		(width 0.14478)
		(layer "In4.Cu")
		(net "M_D_CPU0_SA_DQ<20>")
	)
	(arc
		(start 326.351138 -238.249968)
		(mid 326.498347 -238.269445)
		(end 326.635364 -238.326676)
		(width 0.0889)
		(layer "In4.Cu")
		(net "M_D_CPU0_SA_DQ<20>")
	)
	(arc
		(start 337.348068 -238.326676)
		(mid 337.631024 -238.250499)
		(end 337.91398 -238.326676)
		(width 0.0889)
		(layer "In4.Cu")
		(net "M_D_CPU0_SA_DQ<20>")
	)
	(arc
		(start 330.402438 -238.331502)
		(mid 330.585946 -238.376996)
		(end 330.768198 -238.326676)
		(width 0.0889)
		(layer "In4.Cu")
		(net "M_D_CPU0_SA_DQ<20>")
	)
	(arc
		(start 328.514202 -238.326676)
		(mid 328.701146 -238.376931)
		(end 328.88809 -238.326676)
		(width 0.0889)
		(layer "In4.Cu")
		(net "M_D_CPU0_SA_DQ<20>")
	)
	(arc
		(start 331.342492 -238.331502)
		(mid 331.526 -238.376996)
		(end 331.708252 -238.326676)
		(width 0.0889)
		(layer "In4.Cu")
		(net "M_D_CPU0_SA_DQ<20>")
	)
	(arc
		(start 327.594976 -238.337852)
		(mid 327.773054 -238.376836)
		(end 327.94829 -238.326676)
		(width 0.0889)
		(layer "In4.Cu")
		(net "M_D_CPU0_SA_DQ<20>")
	)
	(arc
		(start 336.042508 -238.331502)
		(mid 336.226016 -238.376996)
		(end 336.408268 -238.326676)
		(width 0.0889)
		(layer "In4.Cu")
		(net "M_D_CPU0_SA_DQ<20>")
	)
	(arc
		(start 329.828144 -238.326676)
		(mid 330.1111 -238.250499)
		(end 330.394056 -238.326676)
		(width 0.0889)
		(layer "In4.Cu")
		(net "M_D_CPU0_SA_DQ<20>")
	)
	(arc
		(start 337.91398 -238.326676)
		(mid 338.096231 -238.377026)
		(end 338.27974 -238.331502)
		(width 0.0889)
		(layer "In4.Cu")
		(net "M_D_CPU0_SA_DQ<20>")
	)
	(arc
		(start 331.708252 -238.326676)
		(mid 331.991208 -238.250499)
		(end 332.274164 -238.326676)
		(width 0.0889)
		(layer "In4.Cu")
		(net "M_D_CPU0_SA_DQ<20>")
	)
	(arc
		(start 332.274164 -238.326676)
		(mid 332.461108 -238.376931)
		(end 332.648052 -238.326676)
		(width 0.0889)
		(layer "In4.Cu")
		(net "M_D_CPU0_SA_DQ<20>")
	)
	(arc
		(start 336.97418 -238.326676)
		(mid 337.161124 -238.376931)
		(end 337.348068 -238.326676)
		(width 0.0889)
		(layer "In4.Cu")
		(net "M_D_CPU0_SA_DQ<20>")
	)
	(arc
		(start 334.52816 -238.326676)
		(mid 334.811116 -238.250499)
		(end 335.094072 -238.326676)
		(width 0.0889)
		(layer "In4.Cu")
		(net "M_D_CPU0_SA_DQ<20>")
	)
	(arc
		(start 338.288122 -238.326676)
		(mid 338.535835 -238.251456)
		(end 338.791042 -238.294926)
		(width 0.0889)
		(layer "In4.Cu")
		(net "M_D_CPU0_SA_DQ<20>")
	)
	(arc
		(start 329.454002 -238.326676)
		(mid 329.636253 -238.377026)
		(end 329.819762 -238.331502)
		(width 0.0889)
		(layer "In4.Cu")
		(net "M_D_CPU0_SA_DQ<20>")
	)
	(arc
		(start 333.588106 -238.326676)
		(mid 333.871062 -238.250499)
		(end 334.154018 -238.326676)
		(width 0.0889)
		(layer "In4.Cu")
		(net "M_D_CPU0_SA_DQ<20>")
	)
	(arc
		(start 327.94829 -238.326676)
		(mid 328.231246 -238.250499)
		(end 328.514202 -238.326676)
		(width 0.0889)
		(layer "In4.Cu")
		(net "M_D_CPU0_SA_DQ<20>")
	)
	(arc
		(start 330.768198 -238.326676)
		(mid 331.051154 -238.250499)
		(end 331.33411 -238.326676)
		(width 0.0889)
		(layer "In4.Cu")
		(net "M_D_CPU0_SA_DQ<20>")
	)
	(arc
		(start 334.154018 -238.326676)
		(mid 334.336269 -238.377026)
		(end 334.519778 -238.331502)
		(width 0.0889)
		(layer "In4.Cu")
		(net "M_D_CPU0_SA_DQ<20>")
	)
	(arc
		(start 327.010522 -238.326676)
		(mid 327.280291 -238.250653)
		(end 327.55332 -238.313976)
		(width 0.0889)
		(layer "In4.Cu")
		(net "M_D_CPU0_SA_DQ<20>")
	)
	(arc
		(start 326.635364 -238.326676)
		(mid 326.812155 -238.377395)
		(end 326.991726 -238.337598)
		(width 0.0889)
		(layer "In4.Cu")
		(net "M_D_CPU0_SA_DQ<20>")
	)
	(arc
		(start 335.102454 -238.331502)
		(mid 335.285962 -238.376996)
		(end 335.468214 -238.326676)
		(width 0.0889)
		(layer "In4.Cu")
		(net "M_D_CPU0_SA_DQ<20>")
	)
	(arc
		(start 328.88809 -238.326676)
		(mid 329.171046 -238.250499)
		(end 329.454002 -238.326676)
		(width 0.0889)
		(layer "In4.Cu")
		(net "M_D_CPU0_SA_DQ<20>")
	)
	(arc
		(start 332.648052 -238.326676)
		(mid 332.931008 -238.250499)
		(end 333.213964 -238.326676)
		(width 0.0889)
		(layer "In4.Cu")
		(net "M_D_CPU0_SA_DQ<20>")
	)
	(arc
		(start 335.468214 -238.326676)
		(mid 335.75117 -238.250499)
		(end 336.034126 -238.326676)
		(width 0.0889)
		(layer "In4.Cu")
		(net "M_D_CPU0_SA_DQ<20>")
	)
	(arc
		(start 336.408268 -238.326676)
		(mid 336.691224 -238.250499)
		(end 336.97418 -238.326676)
		(width 0.0889)
		(layer "In4.Cu")
		(net "M_D_CPU0_SA_DQ<20>")
	)
	(arc
		(start 333.213964 -238.326676)
		(mid 333.396215 -238.377026)
		(end 333.579724 -238.331502)
		(width 0.0889)
		(layer "In4.Cu")
		(net "M_D_CPU0_SA_DQ<20>")
	)
	(segment
		(start 340.918038 -226.120198)
		(end 340.451186 -225.85426)
		(width 0.10668)
		(layer "F.Cu")
		(net "M_D_CPU0_SA_DQ<1>")
	)
	(segment
		(start 286.784288 -199.196452)
		(end 286.947356 -199.35952)
		(width 0.14478)
		(layer "In4.Cu")
		(net "M_D_CPU0_SA_DQ<1>")
	)
	(segment
		(start 286.947356 -199.35952)
		(end 286.947356 -199.677782)
		(width 0.14478)
		(layer "In4.Cu")
		(net "M_D_CPU0_SA_DQ<1>")
	)
	(segment
		(start 285.997396 -199.84085)
		(end 286.227774 -199.84085)
		(width 0.14478)
		(layer "In4.Cu")
		(net "M_D_CPU0_SA_DQ<1>")
	)
	(segment
		(start 286.227774 -199.84085)
		(end 286.390842 -199.677782)
		(width 0.14478)
		(layer "In4.Cu")
		(net "M_D_CPU0_SA_DQ<1>")
	)
	(segment
		(start 298.605702 -198.773288)
		(end 298.605702 -198.837042)
		(width 0.14478)
		(layer "In4.Cu")
		(net "M_D_CPU0_SA_DQ<1>")
	)
	(segment
		(start 288.787332 -199.690482)
		(end 288.940494 -199.843644)
		(width 0.14478)
		(layer "In4.Cu")
		(net "M_D_CPU0_SA_DQ<1>")
	)
	(segment
		(start 303.659794 -199.690482)
		(end 303.822862 -199.85355)
		(width 0.14478)
		(layer "In4.Cu")
		(net "M_D_CPU0_SA_DQ<1>")
	)
	(segment
		(start 303.496726 -199.460104)
		(end 303.659794 -199.623172)
		(width 0.14478)
		(layer "In4.Cu")
		(net "M_D_CPU0_SA_DQ<1>")
	)
	(segment
		(start 296.545254 -199.84085)
		(end 296.775632 -199.84085)
		(width 0.14478)
		(layer "In4.Cu")
		(net "M_D_CPU0_SA_DQ<1>")
	)
	(segment
		(start 330.833476 -226.15906)
		(end 330.863956 -226.17684)
		(width 0.0889)
		(layer "In4.Cu")
		(net "M_D_CPU0_SA_DQ<1>")
	)
	(segment
		(start 299.162216 -198.837042)
		(end 299.162216 -198.773288)
		(width 0.14478)
		(layer "In4.Cu")
		(net "M_D_CPU0_SA_DQ<1>")
	)
	(segment
		(start 328.473054 -219.820998)
		(end 328.473054 -221.18955)
		(width 0.14478)
		(layer "In4.Cu")
		(net "M_D_CPU0_SA_DQ<1>")
	)
	(segment
		(start 296.219118 -199.460104)
		(end 296.382186 -199.623172)
		(width 0.14478)
		(layer "In4.Cu")
		(net "M_D_CPU0_SA_DQ<1>")
	)
	(segment
		(start 294.348662 -199.460104)
		(end 296.219118 -199.460104)
		(width 0.14478)
		(layer "In4.Cu")
		(net "M_D_CPU0_SA_DQ<1>")
	)
	(segment
		(start 291.726874 -198.842122)
		(end 291.726874 -198.773288)
		(width 0.14478)
		(layer "In4.Cu")
		(net "M_D_CPU0_SA_DQ<1>")
	)
	(segment
		(start 296.382186 -199.677782)
		(end 296.545254 -199.84085)
		(width 0.14478)
		(layer "In4.Cu")
		(net "M_D_CPU0_SA_DQ<1>")
	)
	(segment
		(start 328.954638 -222.919798)
		(end 328.984102 -222.936816)
		(width 0.0889)
		(layer "In4.Cu")
		(net "M_D_CPU0_SA_DQ<1>")
	)
	(segment
		(start 302.940212 -199.85355)
		(end 303.10328 -199.690482)
		(width 0.14478)
		(layer "In4.Cu")
		(net "M_D_CPU0_SA_DQ<1>")
	)
	(segment
		(start 287.110424 -199.84085)
		(end 287.340802 -199.84085)
		(width 0.14478)
		(layer "In4.Cu")
		(net "M_D_CPU0_SA_DQ<1>")
	)
	(segment
		(start 290.673282 -198.61022)
		(end 291.007292 -198.61022)
		(width 0.14478)
		(layer "In4.Cu")
		(net "M_D_CPU0_SA_DQ<1>")
	)
	(segment
		(start 298.605702 -198.837042)
		(end 298.76877 -199.00011)
		(width 0.14478)
		(layer "In4.Cu")
		(net "M_D_CPU0_SA_DQ<1>")
	)
	(segment
		(start 291.889942 -198.61022)
		(end 293.498778 -198.61022)
		(width 0.14478)
		(layer "In4.Cu")
		(net "M_D_CPU0_SA_DQ<1>")
	)
	(segment
		(start 332.744064 -226.17684)
		(end 332.752446 -226.181666)
		(width 0.0889)
		(layer "In4.Cu")
		(net "M_D_CPU0_SA_DQ<1>")
	)
	(segment
		(start 288.624264 -199.460104)
		(end 288.787332 -199.623172)
		(width 0.14478)
		(layer "In4.Cu")
		(net "M_D_CPU0_SA_DQ<1>")
	)
	(segment
		(start 288.940494 -199.843644)
		(end 289.190684 -199.843644)
		(width 0.14478)
		(layer "In4.Cu")
		(net "M_D_CPU0_SA_DQ<1>")
	)
	(segment
		(start 335.929732 -226.181666)
		(end 335.938114 -226.17684)
		(width 0.0889)
		(layer "In4.Cu")
		(net "M_D_CPU0_SA_DQ<1>")
	)
	(segment
		(start 303.10328 -199.623172)
		(end 303.266348 -199.460104)
		(width 0.14478)
		(layer "In4.Cu")
		(net "M_D_CPU0_SA_DQ<1>")
	)
	(segment
		(start 296.775632 -199.84085)
		(end 296.9387 -199.677782)
		(width 0.14478)
		(layer "In4.Cu")
		(net "M_D_CPU0_SA_DQ<1>")
	)
	(segment
		(start 302.546766 -199.690482)
		(end 302.709834 -199.85355)
		(width 0.14478)
		(layer "In4.Cu")
		(net "M_D_CPU0_SA_DQ<1>")
	)
	(segment
		(start 285.834328 -199.677782)
		(end 285.997396 -199.84085)
		(width 0.14478)
		(layer "In4.Cu")
		(net "M_D_CPU0_SA_DQ<1>")
	)
	(segment
		(start 299.162216 -198.773288)
		(end 299.325284 -198.61022)
		(width 0.14478)
		(layer "In4.Cu")
		(net "M_D_CPU0_SA_DQ<1>")
	)
	(segment
		(start 302.709834 -199.85355)
		(end 302.940212 -199.85355)
		(width 0.14478)
		(layer "In4.Cu")
		(net "M_D_CPU0_SA_DQ<1>")
	)
	(segment
		(start 329.423522 -223.729042)
		(end 329.454002 -223.746822)
		(width 0.0889)
		(layer "In4.Cu")
		(net "M_D_CPU0_SA_DQ<1>")
	)
	(segment
		(start 336.869786 -226.181666)
		(end 336.878168 -226.17684)
		(width 0.0889)
		(layer "In4.Cu")
		(net "M_D_CPU0_SA_DQ<1>")
	)
	(segment
		(start 286.55391 -199.196452)
		(end 286.784288 -199.196452)
		(width 0.14478)
		(layer "In4.Cu")
		(net "M_D_CPU0_SA_DQ<1>")
	)
	(segment
		(start 328.984102 -222.936816)
		(end 329.023218 -222.959676)
		(width 0.0889)
		(layer "In4.Cu")
		(net "M_D_CPU0_SA_DQ<1>")
	)
	(segment
		(start 302.383698 -199.460104)
		(end 302.546766 -199.623172)
		(width 0.14478)
		(layer "In4.Cu")
		(net "M_D_CPU0_SA_DQ<1>")
	)
	(segment
		(start 304.216308 -199.623172)
		(end 304.379376 -199.460104)
		(width 0.14478)
		(layer "In4.Cu")
		(net "M_D_CPU0_SA_DQ<1>")
	)
	(segment
		(start 337.44408 -226.17684)
		(end 337.452462 -226.181666)
		(width 0.0889)
		(layer "In4.Cu")
		(net "M_D_CPU0_SA_DQ<1>")
	)
	(segment
		(start 291.323776 -198.995538)
		(end 291.573458 -198.995538)
		(width 0.14478)
		(layer "In4.Cu")
		(net "M_D_CPU0_SA_DQ<1>")
	)
	(segment
		(start 333.684118 -226.17684)
		(end 333.6925 -226.181666)
		(width 0.0889)
		(layer "In4.Cu")
		(net "M_D_CPU0_SA_DQ<1>")
	)
	(segment
		(start 287.666938 -199.460104)
		(end 288.624264 -199.460104)
		(width 0.14478)
		(layer "In4.Cu")
		(net "M_D_CPU0_SA_DQ<1>")
	)
	(segment
		(start 293.498778 -198.61022)
		(end 294.348662 -199.460104)
		(width 0.14478)
		(layer "In4.Cu")
		(net "M_D_CPU0_SA_DQ<1>")
	)
	(segment
		(start 302.024542 -199.460104)
		(end 302.383698 -199.460104)
		(width 0.14478)
		(layer "In4.Cu")
		(net "M_D_CPU0_SA_DQ<1>")
	)
	(segment
		(start 298.442634 -198.61022)
		(end 298.605702 -198.773288)
		(width 0.14478)
		(layer "In4.Cu")
		(net "M_D_CPU0_SA_DQ<1>")
	)
	(segment
		(start 286.390842 -199.35952)
		(end 286.55391 -199.196452)
		(width 0.14478)
		(layer "In4.Cu")
		(net "M_D_CPU0_SA_DQ<1>")
	)
	(segment
		(start 287.50387 -199.623172)
		(end 287.666938 -199.460104)
		(width 0.14478)
		(layer "In4.Cu")
		(net "M_D_CPU0_SA_DQ<1>")
	)
	(segment
		(start 289.343846 -199.690482)
		(end 289.343846 -199.623172)
		(width 0.14478)
		(layer "In4.Cu")
		(net "M_D_CPU0_SA_DQ<1>")
	)
	(segment
		(start 328.473054 -221.18955)
		(end 328.473054 -222.000572)
		(width 0.0889)
		(layer "In4.Cu")
		(net "M_D_CPU0_SA_DQ<1>")
	)
	(segment
		(start 340.297008 -226.11969)
		(end 340.451186 -225.85426)
		(width 0.0889)
		(layer "In4.Cu")
		(net "M_D_CPU0_SA_DQ<1>")
	)
	(segment
		(start 329.924156 -224.556828)
		(end 329.960478 -224.57791)
		(width 0.0889)
		(layer "In4.Cu")
		(net "M_D_CPU0_SA_DQ<1>")
	)
	(segment
		(start 285.160974 -199.460104)
		(end 285.67126 -199.460104)
		(width 0.14478)
		(layer "In4.Cu")
		(net "M_D_CPU0_SA_DQ<1>")
	)
	(segment
		(start 287.50387 -199.677782)
		(end 287.50387 -199.623172)
		(width 0.14478)
		(layer "In4.Cu")
		(net "M_D_CPU0_SA_DQ<1>")
	)
	(segment
		(start 285.67126 -199.460104)
		(end 285.834328 -199.623172)
		(width 0.14478)
		(layer "In4.Cu")
		(net "M_D_CPU0_SA_DQ<1>")
	)
	(segment
		(start 297.346878 -199.460104)
		(end 298.196762 -198.61022)
		(width 0.14478)
		(layer "In4.Cu")
		(net "M_D_CPU0_SA_DQ<1>")
	)
	(segment
		(start 331.229716 -226.181666)
		(end 331.238098 -226.17684)
		(width 0.0889)
		(layer "In4.Cu")
		(net "M_D_CPU0_SA_DQ<1>")
	)
	(segment
		(start 303.266348 -199.460104)
		(end 303.496726 -199.460104)
		(width 0.14478)
		(layer "In4.Cu")
		(net "M_D_CPU0_SA_DQ<1>")
	)
	(segment
		(start 303.822862 -199.85355)
		(end 304.05324 -199.85355)
		(width 0.14478)
		(layer "In4.Cu")
		(net "M_D_CPU0_SA_DQ<1>")
	)
	(segment
		(start 308.11216 -199.460104)
		(end 328.473054 -219.820998)
		(width 0.14478)
		(layer "In4.Cu")
		(net "M_D_CPU0_SA_DQ<1>")
	)
	(segment
		(start 289.190684 -199.843644)
		(end 289.343846 -199.690482)
		(width 0.14478)
		(layer "In4.Cu")
		(net "M_D_CPU0_SA_DQ<1>")
	)
	(segment
		(start 291.573458 -198.995538)
		(end 291.726874 -198.842122)
		(width 0.14478)
		(layer "In4.Cu")
		(net "M_D_CPU0_SA_DQ<1>")
	)
	(segment
		(start 287.340802 -199.84085)
		(end 287.50387 -199.677782)
		(width 0.14478)
		(layer "In4.Cu")
		(net "M_D_CPU0_SA_DQ<1>")
	)
	(segment
		(start 291.007292 -198.61022)
		(end 291.17036 -198.773288)
		(width 0.14478)
		(layer "In4.Cu")
		(net "M_D_CPU0_SA_DQ<1>")
	)
	(segment
		(start 298.196762 -198.61022)
		(end 298.442634 -198.61022)
		(width 0.14478)
		(layer "In4.Cu")
		(net "M_D_CPU0_SA_DQ<1>")
	)
	(segment
		(start 297.101768 -199.460104)
		(end 297.346878 -199.460104)
		(width 0.14478)
		(layer "In4.Cu")
		(net "M_D_CPU0_SA_DQ<1>")
	)
	(segment
		(start 303.659794 -199.623172)
		(end 303.659794 -199.690482)
		(width 0.14478)
		(layer "In4.Cu")
		(net "M_D_CPU0_SA_DQ<1>")
	)
	(segment
		(start 296.9387 -199.677782)
		(end 296.9387 -199.623172)
		(width 0.14478)
		(layer "In4.Cu")
		(net "M_D_CPU0_SA_DQ<1>")
	)
	(segment
		(start 302.546766 -199.623172)
		(end 302.546766 -199.690482)
		(width 0.14478)
		(layer "In4.Cu")
		(net "M_D_CPU0_SA_DQ<1>")
	)
	(segment
		(start 299.325284 -198.61022)
		(end 301.174658 -198.61022)
		(width 0.14478)
		(layer "In4.Cu")
		(net "M_D_CPU0_SA_DQ<1>")
	)
	(segment
		(start 298.999148 -199.00011)
		(end 299.162216 -198.837042)
		(width 0.14478)
		(layer "In4.Cu")
		(net "M_D_CPU0_SA_DQ<1>")
	)
	(segment
		(start 301.174658 -198.61022)
		(end 302.024542 -199.460104)
		(width 0.14478)
		(layer "In4.Cu")
		(net "M_D_CPU0_SA_DQ<1>")
	)
	(segment
		(start 330.394056 -225.366834)
		(end 330.433172 -225.389694)
		(width 0.0889)
		(layer "In4.Cu")
		(net "M_D_CPU0_SA_DQ<1>")
	)
	(segment
		(start 291.17036 -198.773288)
		(end 291.17036 -198.842122)
		(width 0.14478)
		(layer "In4.Cu")
		(net "M_D_CPU0_SA_DQ<1>")
	)
	(segment
		(start 289.343846 -199.623172)
		(end 289.506914 -199.460104)
		(width 0.14478)
		(layer "In4.Cu")
		(net "M_D_CPU0_SA_DQ<1>")
	)
	(segment
		(start 298.76877 -199.00011)
		(end 298.999148 -199.00011)
		(width 0.14478)
		(layer "In4.Cu")
		(net "M_D_CPU0_SA_DQ<1>")
	)
	(segment
		(start 304.05324 -199.85355)
		(end 304.216308 -199.690482)
		(width 0.14478)
		(layer "In4.Cu")
		(net "M_D_CPU0_SA_DQ<1>")
	)
	(segment
		(start 288.787332 -199.623172)
		(end 288.787332 -199.690482)
		(width 0.14478)
		(layer "In4.Cu")
		(net "M_D_CPU0_SA_DQ<1>")
	)
	(segment
		(start 303.10328 -199.690482)
		(end 303.10328 -199.623172)
		(width 0.14478)
		(layer "In4.Cu")
		(net "M_D_CPU0_SA_DQ<1>")
	)
	(segment
		(start 289.506914 -199.460104)
		(end 289.823398 -199.460104)
		(width 0.14478)
		(layer "In4.Cu")
		(net "M_D_CPU0_SA_DQ<1>")
	)
	(segment
		(start 296.9387 -199.623172)
		(end 297.101768 -199.460104)
		(width 0.14478)
		(layer "In4.Cu")
		(net "M_D_CPU0_SA_DQ<1>")
	)
	(segment
		(start 304.216308 -199.690482)
		(end 304.216308 -199.623172)
		(width 0.14478)
		(layer "In4.Cu")
		(net "M_D_CPU0_SA_DQ<1>")
	)
	(segment
		(start 296.382186 -199.623172)
		(end 296.382186 -199.677782)
		(width 0.14478)
		(layer "In4.Cu")
		(net "M_D_CPU0_SA_DQ<1>")
	)
	(segment
		(start 284.736032 -199.035162)
		(end 285.160974 -199.460104)
		(width 0.14478)
		(layer "In4.Cu")
		(net "M_D_CPU0_SA_DQ<1>")
	)
	(segment
		(start 285.834328 -199.623172)
		(end 285.834328 -199.677782)
		(width 0.14478)
		(layer "In4.Cu")
		(net "M_D_CPU0_SA_DQ<1>")
	)
	(segment
		(start 286.947356 -199.677782)
		(end 287.110424 -199.84085)
		(width 0.14478)
		(layer "In4.Cu")
		(net "M_D_CPU0_SA_DQ<1>")
	)
	(segment
		(start 329.454002 -223.746822)
		(end 329.493118 -223.769682)
		(width 0.0889)
		(layer "In4.Cu")
		(net "M_D_CPU0_SA_DQ<1>")
	)
	(segment
		(start 304.379376 -199.460104)
		(end 308.11216 -199.460104)
		(width 0.14478)
		(layer "In4.Cu")
		(net "M_D_CPU0_SA_DQ<1>")
	)
	(segment
		(start 340.200742 -226.14509)
		(end 340.297008 -226.11969)
		(width 0.0889)
		(layer "In4.Cu")
		(net "M_D_CPU0_SA_DQ<1>")
	)
	(segment
		(start 329.892406 -224.53854)
		(end 329.924156 -224.556828)
		(width 0.0889)
		(layer "In4.Cu")
		(net "M_D_CPU0_SA_DQ<1>")
	)
	(segment
		(start 291.17036 -198.842122)
		(end 291.323776 -198.995538)
		(width 0.14478)
		(layer "In4.Cu")
		(net "M_D_CPU0_SA_DQ<1>")
	)
	(segment
		(start 339.689694 -226.181666)
		(end 339.698076 -226.17684)
		(width 0.0889)
		(layer "In4.Cu")
		(net "M_D_CPU0_SA_DQ<1>")
	)
	(segment
		(start 332.16977 -226.181666)
		(end 332.178152 -226.17684)
		(width 0.0889)
		(layer "In4.Cu")
		(net "M_D_CPU0_SA_DQ<1>")
	)
	(segment
		(start 291.726874 -198.773288)
		(end 291.889942 -198.61022)
		(width 0.14478)
		(layer "In4.Cu")
		(net "M_D_CPU0_SA_DQ<1>")
	)
	(segment
		(start 286.390842 -199.677782)
		(end 286.390842 -199.35952)
		(width 0.14478)
		(layer "In4.Cu")
		(net "M_D_CPU0_SA_DQ<1>")
	)
	(segment
		(start 330.362306 -225.348546)
		(end 330.394056 -225.366834)
		(width 0.0889)
		(layer "In4.Cu")
		(net "M_D_CPU0_SA_DQ<1>")
	)
	(segment
		(start 289.823398 -199.460104)
		(end 290.673282 -198.61022)
		(width 0.14478)
		(layer "In4.Cu")
		(net "M_D_CPU0_SA_DQ<1>")
	)
	(arc
		(start 338.758022 -226.17684)
		(mid 339.040978 -226.100663)
		(end 339.323934 -226.17684)
		(width 0.0889)
		(layer "In4.Cu")
		(net "M_D_CPU0_SA_DQ<1>")
	)
	(arc
		(start 335.563972 -226.17684)
		(mid 335.746223 -226.22719)
		(end 335.929732 -226.181666)
		(width 0.0889)
		(layer "In4.Cu")
		(net "M_D_CPU0_SA_DQ<1>")
	)
	(arc
		(start 334.99806 -226.17684)
		(mid 335.281016 -226.100663)
		(end 335.563972 -226.17684)
		(width 0.0889)
		(layer "In4.Cu")
		(net "M_D_CPU0_SA_DQ<1>")
	)
	(arc
		(start 335.938114 -226.17684)
		(mid 336.22107 -226.100663)
		(end 336.504026 -226.17684)
		(width 0.0889)
		(layer "In4.Cu")
		(net "M_D_CPU0_SA_DQ<1>")
	)
	(arc
		(start 336.504026 -226.17684)
		(mid 336.686277 -226.22719)
		(end 336.869786 -226.181666)
		(width 0.0889)
		(layer "In4.Cu")
		(net "M_D_CPU0_SA_DQ<1>")
	)
	(arc
		(start 333.118206 -226.17684)
		(mid 333.401162 -226.100663)
		(end 333.684118 -226.17684)
		(width 0.0889)
		(layer "In4.Cu")
		(net "M_D_CPU0_SA_DQ<1>")
	)
	(arc
		(start 333.6925 -226.181666)
		(mid 333.876008 -226.22716)
		(end 334.05826 -226.17684)
		(width 0.0889)
		(layer "In4.Cu")
		(net "M_D_CPU0_SA_DQ<1>")
	)
	(arc
		(start 337.818222 -226.17684)
		(mid 338.101178 -226.100663)
		(end 338.384134 -226.17684)
		(width 0.0889)
		(layer "In4.Cu")
		(net "M_D_CPU0_SA_DQ<1>")
	)
	(arc
		(start 330.20635 -225.044254)
		(mid 330.247605 -225.215225)
		(end 330.362306 -225.348546)
		(width 0.0889)
		(layer "In4.Cu")
		(net "M_D_CPU0_SA_DQ<1>")
	)
	(arc
		(start 339.698076 -226.17684)
		(mid 339.945672 -226.101662)
		(end 340.200742 -226.14509)
		(width 0.0889)
		(layer "In4.Cu")
		(net "M_D_CPU0_SA_DQ<1>")
	)
	(arc
		(start 334.05826 -226.17684)
		(mid 334.341216 -226.100663)
		(end 334.624172 -226.17684)
		(width 0.0889)
		(layer "In4.Cu")
		(net "M_D_CPU0_SA_DQ<1>")
	)
	(arc
		(start 329.960478 -224.57791)
		(mid 330.14113 -224.780655)
		(end 330.20635 -225.044254)
		(width 0.0889)
		(layer "In4.Cu")
		(net "M_D_CPU0_SA_DQ<1>")
	)
	(arc
		(start 329.73645 -224.234248)
		(mid 329.777705 -224.405219)
		(end 329.892406 -224.53854)
		(width 0.0889)
		(layer "In4.Cu")
		(net "M_D_CPU0_SA_DQ<1>")
	)
	(arc
		(start 328.473054 -222.000572)
		(mid 328.49367 -222.083863)
		(end 328.550778 -222.147892)
		(width 0.0889)
		(layer "In4.Cu")
		(net "M_D_CPU0_SA_DQ<1>")
	)
	(arc
		(start 329.26655 -223.424242)
		(mid 329.308099 -223.595664)
		(end 329.423522 -223.729042)
		(width 0.0889)
		(layer "In4.Cu")
		(net "M_D_CPU0_SA_DQ<1>")
	)
	(arc
		(start 339.323934 -226.17684)
		(mid 339.506185 -226.22719)
		(end 339.689694 -226.181666)
		(width 0.0889)
		(layer "In4.Cu")
		(net "M_D_CPU0_SA_DQ<1>")
	)
	(arc
		(start 330.863956 -226.17684)
		(mid 331.046207 -226.22719)
		(end 331.229716 -226.181666)
		(width 0.0889)
		(layer "In4.Cu")
		(net "M_D_CPU0_SA_DQ<1>")
	)
	(arc
		(start 330.676504 -225.85426)
		(mid 330.718053 -226.025682)
		(end 330.833476 -226.15906)
		(width 0.0889)
		(layer "In4.Cu")
		(net "M_D_CPU0_SA_DQ<1>")
	)
	(arc
		(start 332.752446 -226.181666)
		(mid 332.935954 -226.22716)
		(end 333.118206 -226.17684)
		(width 0.0889)
		(layer "In4.Cu")
		(net "M_D_CPU0_SA_DQ<1>")
	)
	(arc
		(start 337.452462 -226.181666)
		(mid 337.63597 -226.22716)
		(end 337.818222 -226.17684)
		(width 0.0889)
		(layer "In4.Cu")
		(net "M_D_CPU0_SA_DQ<1>")
	)
	(arc
		(start 334.624172 -226.17684)
		(mid 334.811116 -226.227095)
		(end 334.99806 -226.17684)
		(width 0.0889)
		(layer "In4.Cu")
		(net "M_D_CPU0_SA_DQ<1>")
	)
	(arc
		(start 328.79665 -222.614236)
		(mid 328.83849 -222.786222)
		(end 328.954638 -222.919798)
		(width 0.0889)
		(layer "In4.Cu")
		(net "M_D_CPU0_SA_DQ<1>")
	)
	(arc
		(start 338.384134 -226.17684)
		(mid 338.571078 -226.227095)
		(end 338.758022 -226.17684)
		(width 0.0889)
		(layer "In4.Cu")
		(net "M_D_CPU0_SA_DQ<1>")
	)
	(arc
		(start 336.878168 -226.17684)
		(mid 337.161124 -226.100663)
		(end 337.44408 -226.17684)
		(width 0.0889)
		(layer "In4.Cu")
		(net "M_D_CPU0_SA_DQ<1>")
	)
	(arc
		(start 329.493118 -223.769682)
		(mid 329.671931 -223.972032)
		(end 329.73645 -224.234248)
		(width 0.0889)
		(layer "In4.Cu")
		(net "M_D_CPU0_SA_DQ<1>")
	)
	(arc
		(start 332.178152 -226.17684)
		(mid 332.461108 -226.100663)
		(end 332.744064 -226.17684)
		(width 0.0889)
		(layer "In4.Cu")
		(net "M_D_CPU0_SA_DQ<1>")
	)
	(arc
		(start 331.238098 -226.17684)
		(mid 331.521054 -226.100663)
		(end 331.80401 -226.17684)
		(width 0.0889)
		(layer "In4.Cu")
		(net "M_D_CPU0_SA_DQ<1>")
	)
	(arc
		(start 331.80401 -226.17684)
		(mid 331.986261 -226.22719)
		(end 332.16977 -226.181666)
		(width 0.0889)
		(layer "In4.Cu")
		(net "M_D_CPU0_SA_DQ<1>")
	)
	(arc
		(start 329.023218 -222.959676)
		(mid 329.202031 -223.162026)
		(end 329.26655 -223.424242)
		(width 0.0889)
		(layer "In4.Cu")
		(net "M_D_CPU0_SA_DQ<1>")
	)
	(arc
		(start 330.433172 -225.389694)
		(mid 330.611985 -225.592044)
		(end 330.676504 -225.85426)
		(width 0.0889)
		(layer "In4.Cu")
		(net "M_D_CPU0_SA_DQ<1>")
	)
	(arc
		(start 328.550778 -222.147892)
		(mid 328.73143 -222.350637)
		(end 328.79665 -222.614236)
		(width 0.0889)
		(layer "In4.Cu")
		(net "M_D_CPU0_SA_DQ<1>")
	)
	(segment
		(start 340.447884 -236.650022)
		(end 339.981032 -236.384084)
		(width 0.10668)
		(layer "F.Cu")
		(net "M_D_CPU0_SA_DQ<19>")
	)
	(segment
		(start 308.776116 -219.01023)
		(end 315.749178 -225.983292)
		(width 0.14478)
		(layer "In4.Cu")
		(net "M_D_CPU0_SA_DQ<19>")
	)
	(segment
		(start 330.394056 -236.061504)
		(end 330.402438 -236.056678)
		(width 0.0889)
		(layer "In4.Cu")
		(net "M_D_CPU0_SA_DQ<19>")
	)
	(segment
		(start 331.33411 -236.061504)
		(end 331.342492 -236.056678)
		(width 0.0889)
		(layer "In4.Cu")
		(net "M_D_CPU0_SA_DQ<19>")
	)
	(segment
		(start 340.13521 -236.118654)
		(end 339.981032 -236.384084)
		(width 0.0889)
		(layer "In4.Cu")
		(net "M_D_CPU0_SA_DQ<19>")
	)
	(segment
		(start 334.519778 -236.056678)
		(end 334.52816 -236.061504)
		(width 0.0889)
		(layer "In4.Cu")
		(net "M_D_CPU0_SA_DQ<19>")
	)
	(segment
		(start 325.266558 -235.284772)
		(end 326.119744 -236.137958)
		(width 0.0889)
		(layer "In4.Cu")
		(net "M_D_CPU0_SA_DQ<19>")
	)
	(segment
		(start 280.635964 -218.585034)
		(end 281.051254 -219.000324)
		(width 0.14478)
		(layer "In4.Cu")
		(net "M_D_CPU0_SA_DQ<19>")
	)
	(segment
		(start 325.266558 -234.868212)
		(end 325.266558 -235.284772)
		(width 0.0889)
		(layer "In4.Cu")
		(net "M_D_CPU0_SA_DQ<19>")
	)
	(segment
		(start 294.3479 -219.000324)
		(end 297.32224 -219.000324)
		(width 0.14478)
		(layer "In4.Cu")
		(net "M_D_CPU0_SA_DQ<19>")
	)
	(segment
		(start 324.06463 -234.159044)
		(end 324.408038 -234.502452)
		(width 0.0889)
		(layer "In4.Cu")
		(net "M_D_CPU0_SA_DQ<19>")
	)
	(segment
		(start 340.112858 -236.035342)
		(end 340.13521 -236.118654)
		(width 0.0889)
		(layer "In4.Cu")
		(net "M_D_CPU0_SA_DQ<19>")
	)
	(segment
		(start 333.579724 -236.056678)
		(end 333.588106 -236.061504)
		(width 0.0889)
		(layer "In4.Cu")
		(net "M_D_CPU0_SA_DQ<19>")
	)
	(segment
		(start 289.834066 -219.000324)
		(end 290.68395 -218.15044)
		(width 0.14478)
		(layer "In4.Cu")
		(net "M_D_CPU0_SA_DQ<19>")
	)
	(segment
		(start 326.119744 -236.137958)
		(end 327.290176 -236.137958)
		(width 0.0889)
		(layer "In4.Cu")
		(net "M_D_CPU0_SA_DQ<19>")
	)
	(segment
		(start 338.854034 -236.061504)
		(end 338.862416 -236.056678)
		(width 0.0889)
		(layer "In4.Cu")
		(net "M_D_CPU0_SA_DQ<19>")
	)
	(segment
		(start 329.819762 -236.056678)
		(end 329.828144 -236.061504)
		(width 0.0889)
		(layer "In4.Cu")
		(net "M_D_CPU0_SA_DQ<19>")
	)
	(segment
		(start 315.749178 -227.565458)
		(end 322.342764 -234.159044)
		(width 0.14478)
		(layer "In4.Cu")
		(net "M_D_CPU0_SA_DQ<19>")
	)
	(segment
		(start 322.342764 -234.159044)
		(end 323.879718 -234.159044)
		(width 0.14478)
		(layer "In4.Cu")
		(net "M_D_CPU0_SA_DQ<19>")
	)
	(segment
		(start 338.27974 -236.056678)
		(end 338.288122 -236.061504)
		(width 0.0889)
		(layer "In4.Cu")
		(net "M_D_CPU0_SA_DQ<19>")
	)
	(segment
		(start 315.749178 -225.983292)
		(end 315.749178 -227.565458)
		(width 0.14478)
		(layer "In4.Cu")
		(net "M_D_CPU0_SA_DQ<19>")
	)
	(segment
		(start 327.939908 -236.056678)
		(end 327.94829 -236.061504)
		(width 0.0889)
		(layer "In4.Cu")
		(net "M_D_CPU0_SA_DQ<19>")
	)
	(segment
		(start 281.051254 -219.000324)
		(end 289.834066 -219.000324)
		(width 0.14478)
		(layer "In4.Cu")
		(net "M_D_CPU0_SA_DQ<19>")
	)
	(segment
		(start 335.094072 -236.061504)
		(end 335.102454 -236.056678)
		(width 0.0889)
		(layer "In4.Cu")
		(net "M_D_CPU0_SA_DQ<19>")
	)
	(segment
		(start 339.794088 -236.061504)
		(end 339.80247 -236.056678)
		(width 0.0889)
		(layer "In4.Cu")
		(net "M_D_CPU0_SA_DQ<19>")
	)
	(segment
		(start 302.04664 -219.01023)
		(end 308.776116 -219.01023)
		(width 0.14478)
		(layer "In4.Cu")
		(net "M_D_CPU0_SA_DQ<19>")
	)
	(segment
		(start 301.18685 -218.15044)
		(end 302.04664 -219.01023)
		(width 0.14478)
		(layer "In4.Cu")
		(net "M_D_CPU0_SA_DQ<19>")
	)
	(segment
		(start 324.900798 -234.502452)
		(end 325.266558 -234.868212)
		(width 0.0889)
		(layer "In4.Cu")
		(net "M_D_CPU0_SA_DQ<19>")
	)
	(segment
		(start 323.879718 -234.159044)
		(end 324.06463 -234.159044)
		(width 0.0889)
		(layer "In4.Cu")
		(net "M_D_CPU0_SA_DQ<19>")
	)
	(segment
		(start 290.68395 -218.15044)
		(end 293.498016 -218.15044)
		(width 0.14478)
		(layer "In4.Cu")
		(net "M_D_CPU0_SA_DQ<19>")
	)
	(segment
		(start 293.498016 -218.15044)
		(end 294.3479 -219.000324)
		(width 0.14478)
		(layer "In4.Cu")
		(net "M_D_CPU0_SA_DQ<19>")
	)
	(segment
		(start 297.32224 -219.000324)
		(end 298.172124 -218.15044)
		(width 0.14478)
		(layer "In4.Cu")
		(net "M_D_CPU0_SA_DQ<19>")
	)
	(segment
		(start 324.408038 -234.502452)
		(end 324.900798 -234.502452)
		(width 0.0889)
		(layer "In4.Cu")
		(net "M_D_CPU0_SA_DQ<19>")
	)
	(segment
		(start 298.172124 -218.15044)
		(end 301.18685 -218.15044)
		(width 0.14478)
		(layer "In4.Cu")
		(net "M_D_CPU0_SA_DQ<19>")
	)
	(segment
		(start 336.034126 -236.061504)
		(end 336.042508 -236.056678)
		(width 0.0889)
		(layer "In4.Cu")
		(net "M_D_CPU0_SA_DQ<19>")
	)
	(arc
		(start 330.402438 -236.056678)
		(mid 330.585946 -236.011184)
		(end 330.768198 -236.061504)
		(width 0.0889)
		(layer "In4.Cu")
		(net "M_D_CPU0_SA_DQ<19>")
	)
	(arc
		(start 339.228176 -236.061504)
		(mid 339.511132 -236.137681)
		(end 339.794088 -236.061504)
		(width 0.0889)
		(layer "In4.Cu")
		(net "M_D_CPU0_SA_DQ<19>")
	)
	(arc
		(start 327.290176 -236.137958)
		(mid 327.43698 -236.118522)
		(end 327.57364 -236.061504)
		(width 0.0889)
		(layer "In4.Cu")
		(net "M_D_CPU0_SA_DQ<19>")
	)
	(arc
		(start 333.213964 -236.061504)
		(mid 333.396215 -236.011154)
		(end 333.579724 -236.056678)
		(width 0.0889)
		(layer "In4.Cu")
		(net "M_D_CPU0_SA_DQ<19>")
	)
	(arc
		(start 338.862416 -236.056678)
		(mid 339.045924 -236.011184)
		(end 339.228176 -236.061504)
		(width 0.0889)
		(layer "In4.Cu")
		(net "M_D_CPU0_SA_DQ<19>")
	)
	(arc
		(start 336.042508 -236.056678)
		(mid 336.226016 -236.011184)
		(end 336.408268 -236.061504)
		(width 0.0889)
		(layer "In4.Cu")
		(net "M_D_CPU0_SA_DQ<19>")
	)
	(arc
		(start 335.468214 -236.061504)
		(mid 335.75117 -236.137681)
		(end 336.034126 -236.061504)
		(width 0.0889)
		(layer "In4.Cu")
		(net "M_D_CPU0_SA_DQ<19>")
	)
	(arc
		(start 332.648052 -236.061504)
		(mid 332.931008 -236.137681)
		(end 333.213964 -236.061504)
		(width 0.0889)
		(layer "In4.Cu")
		(net "M_D_CPU0_SA_DQ<19>")
	)
	(arc
		(start 328.514202 -236.061504)
		(mid 328.701146 -236.011249)
		(end 328.88809 -236.061504)
		(width 0.0889)
		(layer "In4.Cu")
		(net "M_D_CPU0_SA_DQ<19>")
	)
	(arc
		(start 330.768198 -236.061504)
		(mid 331.051154 -236.137681)
		(end 331.33411 -236.061504)
		(width 0.0889)
		(layer "In4.Cu")
		(net "M_D_CPU0_SA_DQ<19>")
	)
	(arc
		(start 331.342492 -236.056678)
		(mid 331.526 -236.011184)
		(end 331.708252 -236.061504)
		(width 0.0889)
		(layer "In4.Cu")
		(net "M_D_CPU0_SA_DQ<19>")
	)
	(arc
		(start 328.88809 -236.061504)
		(mid 329.171046 -236.137681)
		(end 329.454002 -236.061504)
		(width 0.0889)
		(layer "In4.Cu")
		(net "M_D_CPU0_SA_DQ<19>")
	)
	(arc
		(start 329.828144 -236.061504)
		(mid 330.1111 -236.137681)
		(end 330.394056 -236.061504)
		(width 0.0889)
		(layer "In4.Cu")
		(net "M_D_CPU0_SA_DQ<19>")
	)
	(arc
		(start 334.154018 -236.061504)
		(mid 334.336269 -236.011154)
		(end 334.519778 -236.056678)
		(width 0.0889)
		(layer "In4.Cu")
		(net "M_D_CPU0_SA_DQ<19>")
	)
	(arc
		(start 327.57364 -236.061504)
		(mid 327.756145 -236.011027)
		(end 327.939908 -236.056678)
		(width 0.0889)
		(layer "In4.Cu")
		(net "M_D_CPU0_SA_DQ<19>")
	)
	(arc
		(start 334.52816 -236.061504)
		(mid 334.811116 -236.137681)
		(end 335.094072 -236.061504)
		(width 0.0889)
		(layer "In4.Cu")
		(net "M_D_CPU0_SA_DQ<19>")
	)
	(arc
		(start 336.408268 -236.061504)
		(mid 336.691224 -236.137681)
		(end 336.97418 -236.061504)
		(width 0.0889)
		(layer "In4.Cu")
		(net "M_D_CPU0_SA_DQ<19>")
	)
	(arc
		(start 333.588106 -236.061504)
		(mid 333.871062 -236.137681)
		(end 334.154018 -236.061504)
		(width 0.0889)
		(layer "In4.Cu")
		(net "M_D_CPU0_SA_DQ<19>")
	)
	(arc
		(start 337.348068 -236.061504)
		(mid 337.631024 -236.137681)
		(end 337.91398 -236.061504)
		(width 0.0889)
		(layer "In4.Cu")
		(net "M_D_CPU0_SA_DQ<19>")
	)
	(arc
		(start 336.97418 -236.061504)
		(mid 337.161124 -236.011249)
		(end 337.348068 -236.061504)
		(width 0.0889)
		(layer "In4.Cu")
		(net "M_D_CPU0_SA_DQ<19>")
	)
	(arc
		(start 331.708252 -236.061504)
		(mid 331.991208 -236.137681)
		(end 332.274164 -236.061504)
		(width 0.0889)
		(layer "In4.Cu")
		(net "M_D_CPU0_SA_DQ<19>")
	)
	(arc
		(start 337.91398 -236.061504)
		(mid 338.096231 -236.011154)
		(end 338.27974 -236.056678)
		(width 0.0889)
		(layer "In4.Cu")
		(net "M_D_CPU0_SA_DQ<19>")
	)
	(arc
		(start 332.274164 -236.061504)
		(mid 332.461108 -236.011249)
		(end 332.648052 -236.061504)
		(width 0.0889)
		(layer "In4.Cu")
		(net "M_D_CPU0_SA_DQ<19>")
	)
	(arc
		(start 335.102454 -236.056678)
		(mid 335.285962 -236.011184)
		(end 335.468214 -236.061504)
		(width 0.0889)
		(layer "In4.Cu")
		(net "M_D_CPU0_SA_DQ<19>")
	)
	(arc
		(start 327.94829 -236.061504)
		(mid 328.231246 -236.137681)
		(end 328.514202 -236.061504)
		(width 0.0889)
		(layer "In4.Cu")
		(net "M_D_CPU0_SA_DQ<19>")
	)
	(arc
		(start 329.454002 -236.061504)
		(mid 329.636253 -236.011154)
		(end 329.819762 -236.056678)
		(width 0.0889)
		(layer "In4.Cu")
		(net "M_D_CPU0_SA_DQ<19>")
	)
	(arc
		(start 338.288122 -236.061504)
		(mid 338.571078 -236.137681)
		(end 338.854034 -236.061504)
		(width 0.0889)
		(layer "In4.Cu")
		(net "M_D_CPU0_SA_DQ<19>")
	)
	(arc
		(start 339.80247 -236.056678)
		(mid 339.95534 -236.012037)
		(end 340.112858 -236.035342)
		(width 0.0889)
		(layer "In4.Cu")
		(net "M_D_CPU0_SA_DQ<19>")
	)
	(segment
		(start 339.03793 -235.840016)
		(end 338.571078 -235.574078)
		(width 0.10668)
		(layer "F.Cu")
		(net "M_D_CPU0_SA_DQ<18>")
	)
	(segment
		(start 328.984102 -235.251498)
		(end 328.992484 -235.246672)
		(width 0.0889)
		(layer "In4.Cu")
		(net "M_D_CPU0_SA_DQ<18>")
	)
	(segment
		(start 332.16977 -235.246672)
		(end 332.178152 -235.251498)
		(width 0.0889)
		(layer "In4.Cu")
		(net "M_D_CPU0_SA_DQ<18>")
	)
	(segment
		(start 282.989528 -216.562178)
		(end 283.152596 -216.39911)
		(width 0.14478)
		(layer "In4.Cu")
		(net "M_D_CPU0_SA_DQ<18>")
	)
	(segment
		(start 333.684118 -235.251498)
		(end 333.6925 -235.246672)
		(width 0.0889)
		(layer "In4.Cu")
		(net "M_D_CPU0_SA_DQ<18>")
	)
	(segment
		(start 283.382974 -216.39911)
		(end 283.546042 -216.562178)
		(width 0.14478)
		(layer "In4.Cu")
		(net "M_D_CPU0_SA_DQ<18>")
	)
	(segment
		(start 323.867018 -233.247184)
		(end 324.05193 -233.247184)
		(width 0.0889)
		(layer "In4.Cu")
		(net "M_D_CPU0_SA_DQ<18>")
	)
	(segment
		(start 301.196502 -216.46007)
		(end 302.04664 -217.310208)
		(width 0.14478)
		(layer "In4.Cu")
		(net "M_D_CPU0_SA_DQ<18>")
	)
	(segment
		(start 281.069034 -217.318082)
		(end 282.844748 -217.318082)
		(width 0.14478)
		(layer "In4.Cu")
		(net "M_D_CPU0_SA_DQ<18>")
	)
	(segment
		(start 338.725002 -235.308648)
		(end 338.571078 -235.574078)
		(width 0.0889)
		(layer "In4.Cu")
		(net "M_D_CPU0_SA_DQ<18>")
	)
	(segment
		(start 328.409808 -235.246672)
		(end 328.41819 -235.251498)
		(width 0.0889)
		(layer "In4.Cu")
		(net "M_D_CPU0_SA_DQ<18>")
	)
	(segment
		(start 302.04664 -217.310208)
		(end 308.380892 -217.310208)
		(width 0.14478)
		(layer "In4.Cu")
		(net "M_D_CPU0_SA_DQ<18>")
	)
	(segment
		(start 297.312334 -217.310208)
		(end 298.162472 -216.46007)
		(width 0.14478)
		(layer "In4.Cu")
		(net "M_D_CPU0_SA_DQ<18>")
	)
	(segment
		(start 294.357806 -217.310208)
		(end 297.312334 -217.310208)
		(width 0.14478)
		(layer "In4.Cu")
		(net "M_D_CPU0_SA_DQ<18>")
	)
	(segment
		(start 283.546042 -216.562178)
		(end 283.546042 -217.14714)
		(width 0.14478)
		(layer "In4.Cu")
		(net "M_D_CPU0_SA_DQ<18>")
	)
	(segment
		(start 327.47966 -235.251752)
		(end 327.50125 -235.264198)
		(width 0.0889)
		(layer "In4.Cu")
		(net "M_D_CPU0_SA_DQ<18>")
	)
	(segment
		(start 336.869786 -235.246672)
		(end 336.878168 -235.251498)
		(width 0.0889)
		(layer "In4.Cu")
		(net "M_D_CPU0_SA_DQ<18>")
	)
	(segment
		(start 335.929732 -235.246672)
		(end 335.938114 -235.251498)
		(width 0.0889)
		(layer "In4.Cu")
		(net "M_D_CPU0_SA_DQ<18>")
	)
	(segment
		(start 337.44408 -235.251498)
		(end 337.452462 -235.246672)
		(width 0.0889)
		(layer "In4.Cu")
		(net "M_D_CPU0_SA_DQ<18>")
	)
	(segment
		(start 332.744064 -235.251498)
		(end 332.752446 -235.246672)
		(width 0.0889)
		(layer "In4.Cu")
		(net "M_D_CPU0_SA_DQ<18>")
	)
	(segment
		(start 325.899018 -234.614212)
		(end 326.292718 -234.614212)
		(width 0.0889)
		(layer "In4.Cu")
		(net "M_D_CPU0_SA_DQ<18>")
	)
	(segment
		(start 293.507668 -216.46007)
		(end 294.357806 -217.310208)
		(width 0.14478)
		(layer "In4.Cu")
		(net "M_D_CPU0_SA_DQ<18>")
	)
	(segment
		(start 283.70911 -217.310208)
		(end 289.82416 -217.310208)
		(width 0.14478)
		(layer "In4.Cu")
		(net "M_D_CPU0_SA_DQ<18>")
	)
	(segment
		(start 331.229716 -235.246672)
		(end 331.238098 -235.251498)
		(width 0.0889)
		(layer "In4.Cu")
		(net "M_D_CPU0_SA_DQ<18>")
	)
	(segment
		(start 283.546042 -217.14714)
		(end 283.70911 -217.310208)
		(width 0.14478)
		(layer "In4.Cu")
		(net "M_D_CPU0_SA_DQ<18>")
	)
	(segment
		(start 308.380892 -217.310208)
		(end 316.676278 -225.605594)
		(width 0.14478)
		(layer "In4.Cu")
		(net "M_D_CPU0_SA_DQ<18>")
	)
	(segment
		(start 289.82416 -217.310208)
		(end 290.674298 -216.46007)
		(width 0.14478)
		(layer "In4.Cu")
		(net "M_D_CPU0_SA_DQ<18>")
	)
	(segment
		(start 290.674298 -216.46007)
		(end 293.507668 -216.46007)
		(width 0.14478)
		(layer "In4.Cu")
		(net "M_D_CPU0_SA_DQ<18>")
	)
	(segment
		(start 316.676278 -227.203762)
		(end 322.7197 -233.247184)
		(width 0.14478)
		(layer "In4.Cu")
		(net "M_D_CPU0_SA_DQ<18>")
	)
	(segment
		(start 283.152596 -216.39911)
		(end 283.382974 -216.39911)
		(width 0.14478)
		(layer "In4.Cu")
		(net "M_D_CPU0_SA_DQ<18>")
	)
	(segment
		(start 338.70265 -235.225336)
		(end 338.725002 -235.308648)
		(width 0.0889)
		(layer "In4.Cu")
		(net "M_D_CPU0_SA_DQ<18>")
	)
	(segment
		(start 324.05193 -233.247184)
		(end 324.722998 -233.918252)
		(width 0.0889)
		(layer "In4.Cu")
		(net "M_D_CPU0_SA_DQ<18>")
	)
	(segment
		(start 282.844748 -217.318082)
		(end 282.989528 -217.173302)
		(width 0.14478)
		(layer "In4.Cu")
		(net "M_D_CPU0_SA_DQ<18>")
	)
	(segment
		(start 326.292718 -234.614212)
		(end 326.894444 -235.215938)
		(width 0.0889)
		(layer "In4.Cu")
		(net "M_D_CPU0_SA_DQ<18>")
	)
	(segment
		(start 325.203058 -233.918252)
		(end 325.899018 -234.614212)
		(width 0.0889)
		(layer "In4.Cu")
		(net "M_D_CPU0_SA_DQ<18>")
	)
	(segment
		(start 316.676278 -225.605594)
		(end 316.676278 -227.203762)
		(width 0.14478)
		(layer "In4.Cu")
		(net "M_D_CPU0_SA_DQ<18>")
	)
	(segment
		(start 322.7197 -233.247184)
		(end 323.867018 -233.247184)
		(width 0.14478)
		(layer "In4.Cu")
		(net "M_D_CPU0_SA_DQ<18>")
	)
	(segment
		(start 282.989528 -217.173302)
		(end 282.989528 -216.562178)
		(width 0.14478)
		(layer "In4.Cu")
		(net "M_D_CPU0_SA_DQ<18>")
	)
	(segment
		(start 326.894444 -235.215938)
		(end 327.395078 -235.215938)
		(width 0.0889)
		(layer "In4.Cu")
		(net "M_D_CPU0_SA_DQ<18>")
	)
	(segment
		(start 298.162472 -216.46007)
		(end 301.196502 -216.46007)
		(width 0.14478)
		(layer "In4.Cu")
		(net "M_D_CPU0_SA_DQ<18>")
	)
	(segment
		(start 280.635964 -216.885012)
		(end 281.069034 -217.318082)
		(width 0.14478)
		(layer "In4.Cu")
		(net "M_D_CPU0_SA_DQ<18>")
	)
	(segment
		(start 324.722998 -233.918252)
		(end 325.203058 -233.918252)
		(width 0.0889)
		(layer "In4.Cu")
		(net "M_D_CPU0_SA_DQ<18>")
	)
	(arc
		(start 331.80401 -235.251498)
		(mid 331.986261 -235.201148)
		(end 332.16977 -235.246672)
		(width 0.0889)
		(layer "In4.Cu")
		(net "M_D_CPU0_SA_DQ<18>")
	)
	(arc
		(start 337.452462 -235.246672)
		(mid 337.63597 -235.201178)
		(end 337.818222 -235.251498)
		(width 0.0889)
		(layer "In4.Cu")
		(net "M_D_CPU0_SA_DQ<18>")
	)
	(arc
		(start 334.624172 -235.251498)
		(mid 334.811116 -235.201243)
		(end 334.99806 -235.251498)
		(width 0.0889)
		(layer "In4.Cu")
		(net "M_D_CPU0_SA_DQ<18>")
	)
	(arc
		(start 331.238098 -235.251498)
		(mid 331.521054 -235.327675)
		(end 331.80401 -235.251498)
		(width 0.0889)
		(layer "In4.Cu")
		(net "M_D_CPU0_SA_DQ<18>")
	)
	(arc
		(start 330.298044 -235.251498)
		(mid 330.581 -235.327675)
		(end 330.863956 -235.251498)
		(width 0.0889)
		(layer "In4.Cu")
		(net "M_D_CPU0_SA_DQ<18>")
	)
	(arc
		(start 334.99806 -235.251498)
		(mid 335.281016 -235.327675)
		(end 335.563972 -235.251498)
		(width 0.0889)
		(layer "In4.Cu")
		(net "M_D_CPU0_SA_DQ<18>")
	)
	(arc
		(start 328.044048 -235.251498)
		(mid 328.226299 -235.201148)
		(end 328.409808 -235.246672)
		(width 0.0889)
		(layer "In4.Cu")
		(net "M_D_CPU0_SA_DQ<18>")
	)
	(arc
		(start 330.863956 -235.251498)
		(mid 331.046207 -235.201148)
		(end 331.229716 -235.246672)
		(width 0.0889)
		(layer "In4.Cu")
		(net "M_D_CPU0_SA_DQ<18>")
	)
	(arc
		(start 334.05826 -235.251498)
		(mid 334.341216 -235.327675)
		(end 334.624172 -235.251498)
		(width 0.0889)
		(layer "In4.Cu")
		(net "M_D_CPU0_SA_DQ<18>")
	)
	(arc
		(start 332.752446 -235.246672)
		(mid 332.935954 -235.201178)
		(end 333.118206 -235.251498)
		(width 0.0889)
		(layer "In4.Cu")
		(net "M_D_CPU0_SA_DQ<18>")
	)
	(arc
		(start 329.924156 -235.251498)
		(mid 330.1111 -235.201243)
		(end 330.298044 -235.251498)
		(width 0.0889)
		(layer "In4.Cu")
		(net "M_D_CPU0_SA_DQ<18>")
	)
	(arc
		(start 327.395078 -235.215938)
		(mid 327.438478 -235.231226)
		(end 327.47966 -235.251752)
		(width 0.0889)
		(layer "In4.Cu")
		(net "M_D_CPU0_SA_DQ<18>")
	)
	(arc
		(start 335.563972 -235.251498)
		(mid 335.746223 -235.201148)
		(end 335.929732 -235.246672)
		(width 0.0889)
		(layer "In4.Cu")
		(net "M_D_CPU0_SA_DQ<18>")
	)
	(arc
		(start 336.504026 -235.251498)
		(mid 336.686277 -235.201148)
		(end 336.869786 -235.246672)
		(width 0.0889)
		(layer "In4.Cu")
		(net "M_D_CPU0_SA_DQ<18>")
	)
	(arc
		(start 337.818222 -235.251498)
		(mid 338.101178 -235.327675)
		(end 338.384134 -235.251498)
		(width 0.0889)
		(layer "In4.Cu")
		(net "M_D_CPU0_SA_DQ<18>")
	)
	(arc
		(start 328.992484 -235.246672)
		(mid 329.175992 -235.201178)
		(end 329.358244 -235.251498)
		(width 0.0889)
		(layer "In4.Cu")
		(net "M_D_CPU0_SA_DQ<18>")
	)
	(arc
		(start 327.50125 -235.264198)
		(mid 327.774279 -235.327517)
		(end 328.044048 -235.251498)
		(width 0.0889)
		(layer "In4.Cu")
		(net "M_D_CPU0_SA_DQ<18>")
	)
	(arc
		(start 333.6925 -235.246672)
		(mid 333.876008 -235.201178)
		(end 334.05826 -235.251498)
		(width 0.0889)
		(layer "In4.Cu")
		(net "M_D_CPU0_SA_DQ<18>")
	)
	(arc
		(start 338.384134 -235.251498)
		(mid 338.540453 -235.202503)
		(end 338.70265 -235.225336)
		(width 0.0889)
		(layer "In4.Cu")
		(net "M_D_CPU0_SA_DQ<18>")
	)
	(arc
		(start 333.118206 -235.251498)
		(mid 333.401162 -235.327675)
		(end 333.684118 -235.251498)
		(width 0.0889)
		(layer "In4.Cu")
		(net "M_D_CPU0_SA_DQ<18>")
	)
	(arc
		(start 328.41819 -235.251498)
		(mid 328.701146 -235.327675)
		(end 328.984102 -235.251498)
		(width 0.0889)
		(layer "In4.Cu")
		(net "M_D_CPU0_SA_DQ<18>")
	)
	(arc
		(start 329.358244 -235.251498)
		(mid 329.6412 -235.327675)
		(end 329.924156 -235.251498)
		(width 0.0889)
		(layer "In4.Cu")
		(net "M_D_CPU0_SA_DQ<18>")
	)
	(arc
		(start 332.178152 -235.251498)
		(mid 332.461108 -235.327675)
		(end 332.744064 -235.251498)
		(width 0.0889)
		(layer "In4.Cu")
		(net "M_D_CPU0_SA_DQ<18>")
	)
	(arc
		(start 336.878168 -235.251498)
		(mid 337.161124 -235.327675)
		(end 337.44408 -235.251498)
		(width 0.0889)
		(layer "In4.Cu")
		(net "M_D_CPU0_SA_DQ<18>")
	)
	(arc
		(start 335.938114 -235.251498)
		(mid 336.22107 -235.327675)
		(end 336.504026 -235.251498)
		(width 0.0889)
		(layer "In4.Cu")
		(net "M_D_CPU0_SA_DQ<18>")
	)
	(segment
		(start 340.918038 -235.840016)
		(end 340.451186 -235.574078)
		(width 0.10668)
		(layer "F.Cu")
		(net "M_D_CPU0_SA_DQ<17>")
	)
	(segment
		(start 298.68876 -217.541602)
		(end 298.84243 -217.695272)
		(width 0.14478)
		(layer "In4.Cu")
		(net "M_D_CPU0_SA_DQ<17>")
	)
	(segment
		(start 304.666142 -218.160092)
		(end 308.561994 -218.160092)
		(width 0.14478)
		(layer "In4.Cu")
		(net "M_D_CPU0_SA_DQ<17>")
	)
	(segment
		(start 288.94659 -218.32316)
		(end 288.94659 -218.389962)
		(width 0.14478)
		(layer "In4.Cu")
		(net "M_D_CPU0_SA_DQ<17>")
	)
	(segment
		(start 299.091604 -217.695272)
		(end 299.245274 -217.541602)
		(width 0.14478)
		(layer "In4.Cu")
		(net "M_D_CPU0_SA_DQ<17>")
	)
	(segment
		(start 285.719774 -218.382342)
		(end 285.882842 -218.54541)
		(width 0.14478)
		(layer "In4.Cu")
		(net "M_D_CPU0_SA_DQ<17>")
	)
	(segment
		(start 298.196762 -217.310208)
		(end 298.525692 -217.310208)
		(width 0.14478)
		(layer "In4.Cu")
		(net "M_D_CPU0_SA_DQ<17>")
	)
	(segment
		(start 287.389316 -218.382342)
		(end 287.389316 -218.32316)
		(width 0.14478)
		(layer "In4.Cu")
		(net "M_D_CPU0_SA_DQ<17>")
	)
	(segment
		(start 299.408342 -217.310208)
		(end 301.174658 -217.310208)
		(width 0.14478)
		(layer "In4.Cu")
		(net "M_D_CPU0_SA_DQ<17>")
	)
	(segment
		(start 287.552384 -218.160092)
		(end 288.783522 -218.160092)
		(width 0.14478)
		(layer "In4.Cu")
		(net "M_D_CPU0_SA_DQ<17>")
	)
	(segment
		(start 299.245274 -217.473276)
		(end 299.408342 -217.310208)
		(width 0.14478)
		(layer "In4.Cu")
		(net "M_D_CPU0_SA_DQ<17>")
	)
	(segment
		(start 303.94656 -218.32316)
		(end 303.94656 -218.389962)
		(width 0.14478)
		(layer "In4.Cu")
		(net "M_D_CPU0_SA_DQ<17>")
	)
	(segment
		(start 302.833532 -218.32316)
		(end 302.833532 -218.389962)
		(width 0.14478)
		(layer "In4.Cu")
		(net "M_D_CPU0_SA_DQ<17>")
	)
	(segment
		(start 288.783522 -218.160092)
		(end 288.94659 -218.32316)
		(width 0.14478)
		(layer "In4.Cu")
		(net "M_D_CPU0_SA_DQ<17>")
	)
	(segment
		(start 291.15766 -217.473276)
		(end 291.15766 -217.536522)
		(width 0.14478)
		(layer "In4.Cu")
		(net "M_D_CPU0_SA_DQ<17>")
	)
	(segment
		(start 285.719774 -218.32316)
		(end 285.719774 -218.382342)
		(width 0.14478)
		(layer "In4.Cu")
		(net "M_D_CPU0_SA_DQ<17>")
	)
	(segment
		(start 289.344354 -218.548712)
		(end 289.503104 -218.389962)
		(width 0.14478)
		(layer "In4.Cu")
		(net "M_D_CPU0_SA_DQ<17>")
	)
	(segment
		(start 296.843704 -218.548712)
		(end 297.002454 -218.389962)
		(width 0.14478)
		(layer "In4.Cu")
		(net "M_D_CPU0_SA_DQ<17>")
	)
	(segment
		(start 332.16977 -235.901484)
		(end 332.178152 -235.896658)
		(width 0.0889)
		(layer "In4.Cu")
		(net "M_D_CPU0_SA_DQ<17>")
	)
	(segment
		(start 291.877242 -217.310208)
		(end 293.498778 -217.310208)
		(width 0.14478)
		(layer "In4.Cu")
		(net "M_D_CPU0_SA_DQ<17>")
	)
	(segment
		(start 316.221618 -225.819716)
		(end 316.221618 -227.39223)
		(width 0.14478)
		(layer "In4.Cu")
		(net "M_D_CPU0_SA_DQ<17>")
	)
	(segment
		(start 335.929732 -235.901484)
		(end 335.938114 -235.896658)
		(width 0.0889)
		(layer "In4.Cu")
		(net "M_D_CPU0_SA_DQ<17>")
	)
	(segment
		(start 308.561994 -218.160092)
		(end 316.221618 -225.819716)
		(width 0.14478)
		(layer "In4.Cu")
		(net "M_D_CPU0_SA_DQ<17>")
	)
	(segment
		(start 286.276288 -218.07932)
		(end 286.439356 -217.916252)
		(width 0.14478)
		(layer "In4.Cu")
		(net "M_D_CPU0_SA_DQ<17>")
	)
	(segment
		(start 297.002454 -218.389962)
		(end 297.002454 -218.32316)
		(width 0.14478)
		(layer "In4.Cu")
		(net "M_D_CPU0_SA_DQ<17>")
	)
	(segment
		(start 296.44594 -218.389962)
		(end 296.60469 -218.548712)
		(width 0.14478)
		(layer "In4.Cu")
		(net "M_D_CPU0_SA_DQ<17>")
	)
	(segment
		(start 302.833532 -218.389962)
		(end 302.9966 -218.55303)
		(width 0.14478)
		(layer "In4.Cu")
		(net "M_D_CPU0_SA_DQ<17>")
	)
	(segment
		(start 286.11322 -218.54541)
		(end 286.276288 -218.382342)
		(width 0.14478)
		(layer "In4.Cu")
		(net "M_D_CPU0_SA_DQ<17>")
	)
	(segment
		(start 303.226978 -218.55303)
		(end 303.390046 -218.389962)
		(width 0.14478)
		(layer "In4.Cu")
		(net "M_D_CPU0_SA_DQ<17>")
	)
	(segment
		(start 328.984102 -235.896658)
		(end 328.992484 -235.901484)
		(width 0.0889)
		(layer "In4.Cu")
		(net "M_D_CPU0_SA_DQ<17>")
	)
	(segment
		(start 324.616318 -234.172252)
		(end 324.976998 -234.172252)
		(width 0.0889)
		(layer "In4.Cu")
		(net "M_D_CPU0_SA_DQ<17>")
	)
	(segment
		(start 285.160974 -218.160092)
		(end 285.556706 -218.160092)
		(width 0.14478)
		(layer "In4.Cu")
		(net "M_D_CPU0_SA_DQ<17>")
	)
	(segment
		(start 316.221618 -227.39223)
		(end 322.531232 -233.701844)
		(width 0.14478)
		(layer "In4.Cu")
		(net "M_D_CPU0_SA_DQ<17>")
	)
	(segment
		(start 284.736032 -217.73515)
		(end 285.160974 -218.160092)
		(width 0.14478)
		(layer "In4.Cu")
		(net "M_D_CPU0_SA_DQ<17>")
	)
	(segment
		(start 303.390046 -218.32316)
		(end 303.553114 -218.160092)
		(width 0.14478)
		(layer "In4.Cu")
		(net "M_D_CPU0_SA_DQ<17>")
	)
	(segment
		(start 285.556706 -218.160092)
		(end 285.719774 -218.32316)
		(width 0.14478)
		(layer "In4.Cu")
		(net "M_D_CPU0_SA_DQ<17>")
	)
	(segment
		(start 324.14591 -233.701844)
		(end 324.616318 -234.172252)
		(width 0.0889)
		(layer "In4.Cu")
		(net "M_D_CPU0_SA_DQ<17>")
	)
	(segment
		(start 286.832802 -218.07932)
		(end 286.832802 -218.382342)
		(width 0.14478)
		(layer "In4.Cu")
		(net "M_D_CPU0_SA_DQ<17>")
	)
	(segment
		(start 336.869786 -235.901484)
		(end 336.878168 -235.896658)
		(width 0.0889)
		(layer "In4.Cu")
		(net "M_D_CPU0_SA_DQ<17>")
	)
	(segment
		(start 337.44408 -235.896658)
		(end 337.452462 -235.901484)
		(width 0.0889)
		(layer "In4.Cu")
		(net "M_D_CPU0_SA_DQ<17>")
	)
	(segment
		(start 298.84243 -217.695272)
		(end 299.091604 -217.695272)
		(width 0.14478)
		(layer "In4.Cu")
		(net "M_D_CPU0_SA_DQ<17>")
	)
	(segment
		(start 303.783492 -218.160092)
		(end 303.94656 -218.32316)
		(width 0.14478)
		(layer "In4.Cu")
		(net "M_D_CPU0_SA_DQ<17>")
	)
	(segment
		(start 291.714174 -217.473276)
		(end 291.877242 -217.310208)
		(width 0.14478)
		(layer "In4.Cu")
		(net "M_D_CPU0_SA_DQ<17>")
	)
	(segment
		(start 302.670464 -218.160092)
		(end 302.833532 -218.32316)
		(width 0.14478)
		(layer "In4.Cu")
		(net "M_D_CPU0_SA_DQ<17>")
	)
	(segment
		(start 331.229716 -235.901484)
		(end 331.238098 -235.896658)
		(width 0.0889)
		(layer "In4.Cu")
		(net "M_D_CPU0_SA_DQ<17>")
	)
	(segment
		(start 290.994592 -217.310208)
		(end 291.15766 -217.473276)
		(width 0.14478)
		(layer "In4.Cu")
		(net "M_D_CPU0_SA_DQ<17>")
	)
	(segment
		(start 289.10534 -218.548712)
		(end 289.344354 -218.548712)
		(width 0.14478)
		(layer "In4.Cu")
		(net "M_D_CPU0_SA_DQ<17>")
	)
	(segment
		(start 299.245274 -217.541602)
		(end 299.245274 -217.473276)
		(width 0.14478)
		(layer "In4.Cu")
		(net "M_D_CPU0_SA_DQ<17>")
	)
	(segment
		(start 303.553114 -218.160092)
		(end 303.783492 -218.160092)
		(width 0.14478)
		(layer "In4.Cu")
		(net "M_D_CPU0_SA_DQ<17>")
	)
	(segment
		(start 298.68876 -217.473276)
		(end 298.68876 -217.541602)
		(width 0.14478)
		(layer "In4.Cu")
		(net "M_D_CPU0_SA_DQ<17>")
	)
	(segment
		(start 296.282872 -218.160092)
		(end 296.44594 -218.32316)
		(width 0.14478)
		(layer "In4.Cu")
		(net "M_D_CPU0_SA_DQ<17>")
	)
	(segment
		(start 289.503104 -218.32316)
		(end 289.666172 -218.160092)
		(width 0.14478)
		(layer "In4.Cu")
		(net "M_D_CPU0_SA_DQ<17>")
	)
	(segment
		(start 286.276288 -218.382342)
		(end 286.276288 -218.07932)
		(width 0.14478)
		(layer "In4.Cu")
		(net "M_D_CPU0_SA_DQ<17>")
	)
	(segment
		(start 286.439356 -217.916252)
		(end 286.669734 -217.916252)
		(width 0.14478)
		(layer "In4.Cu")
		(net "M_D_CPU0_SA_DQ<17>")
	)
	(segment
		(start 340.200742 -235.864908)
		(end 340.297008 -235.839508)
		(width 0.0889)
		(layer "In4.Cu")
		(net "M_D_CPU0_SA_DQ<17>")
	)
	(segment
		(start 325.535798 -234.731052)
		(end 325.535798 -235.284518)
		(width 0.0889)
		(layer "In4.Cu")
		(net "M_D_CPU0_SA_DQ<17>")
	)
	(segment
		(start 296.60469 -218.548712)
		(end 296.843704 -218.548712)
		(width 0.14478)
		(layer "In4.Cu")
		(net "M_D_CPU0_SA_DQ<17>")
	)
	(segment
		(start 287.389316 -218.32316)
		(end 287.552384 -218.160092)
		(width 0.14478)
		(layer "In4.Cu")
		(net "M_D_CPU0_SA_DQ<17>")
	)
	(segment
		(start 288.94659 -218.389962)
		(end 289.10534 -218.548712)
		(width 0.14478)
		(layer "In4.Cu")
		(net "M_D_CPU0_SA_DQ<17>")
	)
	(segment
		(start 294.348662 -218.160092)
		(end 296.282872 -218.160092)
		(width 0.14478)
		(layer "In4.Cu")
		(net "M_D_CPU0_SA_DQ<17>")
	)
	(segment
		(start 325.535798 -235.284518)
		(end 326.198738 -235.947458)
		(width 0.0889)
		(layer "In4.Cu")
		(net "M_D_CPU0_SA_DQ<17>")
	)
	(segment
		(start 301.174658 -217.310208)
		(end 302.024542 -218.160092)
		(width 0.14478)
		(layer "In4.Cu")
		(net "M_D_CPU0_SA_DQ<17>")
	)
	(segment
		(start 303.94656 -218.389962)
		(end 304.109628 -218.55303)
		(width 0.14478)
		(layer "In4.Cu")
		(net "M_D_CPU0_SA_DQ<17>")
	)
	(segment
		(start 322.531232 -233.701844)
		(end 323.879718 -233.701844)
		(width 0.14478)
		(layer "In4.Cu")
		(net "M_D_CPU0_SA_DQ<17>")
	)
	(segment
		(start 286.832802 -218.382342)
		(end 286.99587 -218.54541)
		(width 0.14478)
		(layer "In4.Cu")
		(net "M_D_CPU0_SA_DQ<17>")
	)
	(segment
		(start 289.503104 -218.389962)
		(end 289.503104 -218.32316)
		(width 0.14478)
		(layer "In4.Cu")
		(net "M_D_CPU0_SA_DQ<17>")
	)
	(segment
		(start 332.744064 -235.896658)
		(end 332.752446 -235.901484)
		(width 0.0889)
		(layer "In4.Cu")
		(net "M_D_CPU0_SA_DQ<17>")
	)
	(segment
		(start 298.525692 -217.310208)
		(end 298.68876 -217.473276)
		(width 0.14478)
		(layer "In4.Cu")
		(net "M_D_CPU0_SA_DQ<17>")
	)
	(segment
		(start 304.503074 -218.389962)
		(end 304.503074 -218.32316)
		(width 0.14478)
		(layer "In4.Cu")
		(net "M_D_CPU0_SA_DQ<17>")
	)
	(segment
		(start 289.666172 -218.160092)
		(end 289.823398 -218.160092)
		(width 0.14478)
		(layer "In4.Cu")
		(net "M_D_CPU0_SA_DQ<17>")
	)
	(segment
		(start 286.99587 -218.54541)
		(end 287.226248 -218.54541)
		(width 0.14478)
		(layer "In4.Cu")
		(net "M_D_CPU0_SA_DQ<17>")
	)
	(segment
		(start 304.503074 -218.32316)
		(end 304.666142 -218.160092)
		(width 0.14478)
		(layer "In4.Cu")
		(net "M_D_CPU0_SA_DQ<17>")
	)
	(segment
		(start 291.15766 -217.536522)
		(end 291.320728 -217.69959)
		(width 0.14478)
		(layer "In4.Cu")
		(net "M_D_CPU0_SA_DQ<17>")
	)
	(segment
		(start 290.673282 -217.310208)
		(end 290.994592 -217.310208)
		(width 0.14478)
		(layer "In4.Cu")
		(net "M_D_CPU0_SA_DQ<17>")
	)
	(segment
		(start 296.44594 -218.32316)
		(end 296.44594 -218.389962)
		(width 0.14478)
		(layer "In4.Cu")
		(net "M_D_CPU0_SA_DQ<17>")
	)
	(segment
		(start 297.002454 -218.32316)
		(end 297.165522 -218.160092)
		(width 0.14478)
		(layer "In4.Cu")
		(net "M_D_CPU0_SA_DQ<17>")
	)
	(segment
		(start 323.879718 -233.701844)
		(end 324.14591 -233.701844)
		(width 0.0889)
		(layer "In4.Cu")
		(net "M_D_CPU0_SA_DQ<17>")
	)
	(segment
		(start 304.109628 -218.55303)
		(end 304.340006 -218.55303)
		(width 0.14478)
		(layer "In4.Cu")
		(net "M_D_CPU0_SA_DQ<17>")
	)
	(segment
		(start 297.165522 -218.160092)
		(end 297.346878 -218.160092)
		(width 0.14478)
		(layer "In4.Cu")
		(net "M_D_CPU0_SA_DQ<17>")
	)
	(segment
		(start 291.551106 -217.69959)
		(end 291.714174 -217.536522)
		(width 0.14478)
		(layer "In4.Cu")
		(net "M_D_CPU0_SA_DQ<17>")
	)
	(segment
		(start 339.689694 -235.901484)
		(end 339.698076 -235.896658)
		(width 0.0889)
		(layer "In4.Cu")
		(net "M_D_CPU0_SA_DQ<17>")
	)
	(segment
		(start 328.033634 -235.890562)
		(end 328.044048 -235.896658)
		(width 0.0889)
		(layer "In4.Cu")
		(net "M_D_CPU0_SA_DQ<17>")
	)
	(segment
		(start 340.297008 -235.839508)
		(end 340.451186 -235.574078)
		(width 0.0889)
		(layer "In4.Cu")
		(net "M_D_CPU0_SA_DQ<17>")
	)
	(segment
		(start 302.024542 -218.160092)
		(end 302.670464 -218.160092)
		(width 0.14478)
		(layer "In4.Cu")
		(net "M_D_CPU0_SA_DQ<17>")
	)
	(segment
		(start 324.976998 -234.172252)
		(end 325.535798 -234.731052)
		(width 0.0889)
		(layer "In4.Cu")
		(net "M_D_CPU0_SA_DQ<17>")
	)
	(segment
		(start 302.9966 -218.55303)
		(end 303.226978 -218.55303)
		(width 0.14478)
		(layer "In4.Cu")
		(net "M_D_CPU0_SA_DQ<17>")
	)
	(segment
		(start 326.198738 -235.947458)
		(end 327.289922 -235.947458)
		(width 0.0889)
		(layer "In4.Cu")
		(net "M_D_CPU0_SA_DQ<17>")
	)
	(segment
		(start 291.714174 -217.536522)
		(end 291.714174 -217.473276)
		(width 0.14478)
		(layer "In4.Cu")
		(net "M_D_CPU0_SA_DQ<17>")
	)
	(segment
		(start 333.684118 -235.896658)
		(end 333.6925 -235.901484)
		(width 0.0889)
		(layer "In4.Cu")
		(net "M_D_CPU0_SA_DQ<17>")
	)
	(segment
		(start 287.226248 -218.54541)
		(end 287.389316 -218.382342)
		(width 0.14478)
		(layer "In4.Cu")
		(net "M_D_CPU0_SA_DQ<17>")
	)
	(segment
		(start 304.340006 -218.55303)
		(end 304.503074 -218.389962)
		(width 0.14478)
		(layer "In4.Cu")
		(net "M_D_CPU0_SA_DQ<17>")
	)
	(segment
		(start 291.320728 -217.69959)
		(end 291.551106 -217.69959)
		(width 0.14478)
		(layer "In4.Cu")
		(net "M_D_CPU0_SA_DQ<17>")
	)
	(segment
		(start 286.669734 -217.916252)
		(end 286.832802 -218.07932)
		(width 0.14478)
		(layer "In4.Cu")
		(net "M_D_CPU0_SA_DQ<17>")
	)
	(segment
		(start 328.409808 -235.901484)
		(end 328.41819 -235.896658)
		(width 0.0889)
		(layer "In4.Cu")
		(net "M_D_CPU0_SA_DQ<17>")
	)
	(segment
		(start 289.823398 -218.160092)
		(end 290.673282 -217.310208)
		(width 0.14478)
		(layer "In4.Cu")
		(net "M_D_CPU0_SA_DQ<17>")
	)
	(segment
		(start 293.498778 -217.310208)
		(end 294.348662 -218.160092)
		(width 0.14478)
		(layer "In4.Cu")
		(net "M_D_CPU0_SA_DQ<17>")
	)
	(segment
		(start 303.390046 -218.389962)
		(end 303.390046 -218.32316)
		(width 0.14478)
		(layer "In4.Cu")
		(net "M_D_CPU0_SA_DQ<17>")
	)
	(segment
		(start 297.346878 -218.160092)
		(end 298.196762 -217.310208)
		(width 0.14478)
		(layer "In4.Cu")
		(net "M_D_CPU0_SA_DQ<17>")
	)
	(segment
		(start 285.882842 -218.54541)
		(end 286.11322 -218.54541)
		(width 0.14478)
		(layer "In4.Cu")
		(net "M_D_CPU0_SA_DQ<17>")
	)
	(arc
		(start 334.99806 -235.896658)
		(mid 335.281016 -235.820481)
		(end 335.563972 -235.896658)
		(width 0.0889)
		(layer "In4.Cu")
		(net "M_D_CPU0_SA_DQ<17>")
	)
	(arc
		(start 333.118206 -235.896658)
		(mid 333.401162 -235.820481)
		(end 333.684118 -235.896658)
		(width 0.0889)
		(layer "In4.Cu")
		(net "M_D_CPU0_SA_DQ<17>")
	)
	(arc
		(start 331.80401 -235.896658)
		(mid 331.986261 -235.947008)
		(end 332.16977 -235.901484)
		(width 0.0889)
		(layer "In4.Cu")
		(net "M_D_CPU0_SA_DQ<17>")
	)
	(arc
		(start 336.504026 -235.896658)
		(mid 336.686277 -235.947008)
		(end 336.869786 -235.901484)
		(width 0.0889)
		(layer "In4.Cu")
		(net "M_D_CPU0_SA_DQ<17>")
	)
	(arc
		(start 330.863956 -235.896658)
		(mid 331.046207 -235.947008)
		(end 331.229716 -235.901484)
		(width 0.0889)
		(layer "In4.Cu")
		(net "M_D_CPU0_SA_DQ<17>")
	)
	(arc
		(start 339.323934 -235.896658)
		(mid 339.506185 -235.947008)
		(end 339.689694 -235.901484)
		(width 0.0889)
		(layer "In4.Cu")
		(net "M_D_CPU0_SA_DQ<17>")
	)
	(arc
		(start 337.452462 -235.901484)
		(mid 337.63597 -235.946978)
		(end 337.818222 -235.896658)
		(width 0.0889)
		(layer "In4.Cu")
		(net "M_D_CPU0_SA_DQ<17>")
	)
	(arc
		(start 334.624172 -235.896658)
		(mid 334.811116 -235.946913)
		(end 334.99806 -235.896658)
		(width 0.0889)
		(layer "In4.Cu")
		(net "M_D_CPU0_SA_DQ<17>")
	)
	(arc
		(start 335.563972 -235.896658)
		(mid 335.746223 -235.947008)
		(end 335.929732 -235.901484)
		(width 0.0889)
		(layer "In4.Cu")
		(net "M_D_CPU0_SA_DQ<17>")
	)
	(arc
		(start 335.938114 -235.896658)
		(mid 336.22107 -235.820481)
		(end 336.504026 -235.896658)
		(width 0.0889)
		(layer "In4.Cu")
		(net "M_D_CPU0_SA_DQ<17>")
	)
	(arc
		(start 334.05826 -235.896658)
		(mid 334.341216 -235.820481)
		(end 334.624172 -235.896658)
		(width 0.0889)
		(layer "In4.Cu")
		(net "M_D_CPU0_SA_DQ<17>")
	)
	(arc
		(start 337.818222 -235.896658)
		(mid 338.101178 -235.820481)
		(end 338.384134 -235.896658)
		(width 0.0889)
		(layer "In4.Cu")
		(net "M_D_CPU0_SA_DQ<17>")
	)
	(arc
		(start 327.289922 -235.947458)
		(mid 327.387283 -235.93455)
		(end 327.477882 -235.896658)
		(width 0.0889)
		(layer "In4.Cu")
		(net "M_D_CPU0_SA_DQ<17>")
	)
	(arc
		(start 332.752446 -235.901484)
		(mid 332.935954 -235.946978)
		(end 333.118206 -235.896658)
		(width 0.0889)
		(layer "In4.Cu")
		(net "M_D_CPU0_SA_DQ<17>")
	)
	(arc
		(start 329.924156 -235.896658)
		(mid 330.1111 -235.946913)
		(end 330.298044 -235.896658)
		(width 0.0889)
		(layer "In4.Cu")
		(net "M_D_CPU0_SA_DQ<17>")
	)
	(arc
		(start 338.384134 -235.896658)
		(mid 338.571078 -235.946913)
		(end 338.758022 -235.896658)
		(width 0.0889)
		(layer "In4.Cu")
		(net "M_D_CPU0_SA_DQ<17>")
	)
	(arc
		(start 328.044048 -235.896658)
		(mid 328.226299 -235.947008)
		(end 328.409808 -235.901484)
		(width 0.0889)
		(layer "In4.Cu")
		(net "M_D_CPU0_SA_DQ<17>")
	)
	(arc
		(start 328.41819 -235.896658)
		(mid 328.701146 -235.820481)
		(end 328.984102 -235.896658)
		(width 0.0889)
		(layer "In4.Cu")
		(net "M_D_CPU0_SA_DQ<17>")
	)
	(arc
		(start 339.698076 -235.896658)
		(mid 339.945672 -235.82148)
		(end 340.200742 -235.864908)
		(width 0.0889)
		(layer "In4.Cu")
		(net "M_D_CPU0_SA_DQ<17>")
	)
	(arc
		(start 329.358244 -235.896658)
		(mid 329.6412 -235.820481)
		(end 329.924156 -235.896658)
		(width 0.0889)
		(layer "In4.Cu")
		(net "M_D_CPU0_SA_DQ<17>")
	)
	(arc
		(start 330.298044 -235.896658)
		(mid 330.581 -235.820481)
		(end 330.863956 -235.896658)
		(width 0.0889)
		(layer "In4.Cu")
		(net "M_D_CPU0_SA_DQ<17>")
	)
	(arc
		(start 327.477882 -235.896658)
		(mid 327.754949 -235.820387)
		(end 328.033634 -235.890562)
		(width 0.0889)
		(layer "In4.Cu")
		(net "M_D_CPU0_SA_DQ<17>")
	)
	(arc
		(start 328.992484 -235.901484)
		(mid 329.175992 -235.946978)
		(end 329.358244 -235.896658)
		(width 0.0889)
		(layer "In4.Cu")
		(net "M_D_CPU0_SA_DQ<17>")
	)
	(arc
		(start 338.758022 -235.896658)
		(mid 339.040978 -235.820481)
		(end 339.323934 -235.896658)
		(width 0.0889)
		(layer "In4.Cu")
		(net "M_D_CPU0_SA_DQ<17>")
	)
	(arc
		(start 332.178152 -235.896658)
		(mid 332.461108 -235.820481)
		(end 332.744064 -235.896658)
		(width 0.0889)
		(layer "In4.Cu")
		(net "M_D_CPU0_SA_DQ<17>")
	)
	(arc
		(start 336.878168 -235.896658)
		(mid 337.161124 -235.820481)
		(end 337.44408 -235.896658)
		(width 0.0889)
		(layer "In4.Cu")
		(net "M_D_CPU0_SA_DQ<17>")
	)
	(arc
		(start 333.6925 -235.901484)
		(mid 333.876008 -235.946978)
		(end 334.05826 -235.896658)
		(width 0.0889)
		(layer "In4.Cu")
		(net "M_D_CPU0_SA_DQ<17>")
	)
	(arc
		(start 331.238098 -235.896658)
		(mid 331.521054 -235.820481)
		(end 331.80401 -235.896658)
		(width 0.0889)
		(layer "In4.Cu")
		(net "M_D_CPU0_SA_DQ<17>")
	)
	(segment
		(start 339.508084 -235.03001)
		(end 339.040978 -234.764072)
		(width 0.10668)
		(layer "F.Cu")
		(net "M_D_CPU0_SA_DQ<16>")
	)
	(segment
		(start 303.773078 -216.621614)
		(end 303.773078 -216.698068)
		(width 0.14478)
		(layer "In4.Cu")
		(net "M_D_CPU0_SA_DQ<16>")
	)
	(segment
		(start 305.03749 -216.859612)
		(end 305.265836 -216.859612)
		(width 0.14478)
		(layer "In4.Cu")
		(net "M_D_CPU0_SA_DQ<16>")
	)
	(segment
		(start 301.174658 -215.610186)
		(end 302.024542 -216.46007)
		(width 0.14478)
		(layer "In4.Cu")
		(net "M_D_CPU0_SA_DQ<16>")
	)
	(segment
		(start 304.486056 -216.168732)
		(end 304.714402 -216.168732)
		(width 0.14478)
		(layer "In4.Cu")
		(net "M_D_CPU0_SA_DQ<16>")
	)
	(segment
		(start 323.889878 -232.792524)
		(end 324.68693 -232.792524)
		(width 0.0889)
		(layer "In4.Cu")
		(net "M_D_CPU0_SA_DQ<16>")
	)
	(segment
		(start 317.130938 -227.015294)
		(end 322.908168 -232.792524)
		(width 0.14478)
		(layer "In4.Cu")
		(net "M_D_CPU0_SA_DQ<16>")
	)
	(segment
		(start 287.386014 -216.695528)
		(end 287.386014 -216.621614)
		(width 0.14478)
		(layer "In4.Cu")
		(net "M_D_CPU0_SA_DQ<16>")
	)
	(segment
		(start 326.541384 -234.423712)
		(end 327.14311 -235.025438)
		(width 0.0889)
		(layer "In4.Cu")
		(net "M_D_CPU0_SA_DQ<16>")
	)
	(segment
		(start 331.33411 -235.086652)
		(end 331.342492 -235.091478)
		(width 0.0889)
		(layer "In4.Cu")
		(net "M_D_CPU0_SA_DQ<16>")
	)
	(segment
		(start 338.791042 -235.054902)
		(end 338.887054 -235.029502)
		(width 0.0889)
		(layer "In4.Cu")
		(net "M_D_CPU0_SA_DQ<16>")
	)
	(segment
		(start 302.349154 -216.46007)
		(end 302.636936 -216.747852)
		(width 0.14478)
		(layer "In4.Cu")
		(net "M_D_CPU0_SA_DQ<16>")
	)
	(segment
		(start 305.42738 -216.698068)
		(end 305.42738 -216.330276)
		(width 0.14478)
		(layer "In4.Cu")
		(net "M_D_CPU0_SA_DQ<16>")
	)
	(segment
		(start 306.530248 -216.621614)
		(end 306.691792 -216.46007)
		(width 0.14478)
		(layer "In4.Cu")
		(net "M_D_CPU0_SA_DQ<16>")
	)
	(segment
		(start 290.673282 -215.610186)
		(end 290.929822 -215.610186)
		(width 0.14478)
		(layer "In4.Cu")
		(net "M_D_CPU0_SA_DQ<16>")
	)
	(segment
		(start 285.731712 -216.695528)
		(end 285.893256 -216.857072)
		(width 0.14478)
		(layer "In4.Cu")
		(net "M_D_CPU0_SA_DQ<16>")
	)
	(segment
		(start 305.265836 -216.859612)
		(end 305.42738 -216.698068)
		(width 0.14478)
		(layer "In4.Cu")
		(net "M_D_CPU0_SA_DQ<16>")
	)
	(segment
		(start 291.241988 -215.922352)
		(end 291.481256 -215.922352)
		(width 0.14478)
		(layer "In4.Cu")
		(net "M_D_CPU0_SA_DQ<16>")
	)
	(segment
		(start 296.139108 -216.46007)
		(end 296.41419 -216.735152)
		(width 0.14478)
		(layer "In4.Cu")
		(net "M_D_CPU0_SA_DQ<16>")
	)
	(segment
		(start 285.731712 -216.621614)
		(end 285.731712 -216.695528)
		(width 0.14478)
		(layer "In4.Cu")
		(net "M_D_CPU0_SA_DQ<16>")
	)
	(segment
		(start 338.887054 -235.029502)
		(end 339.040978 -234.764072)
		(width 0.0889)
		(layer "In4.Cu")
		(net "M_D_CPU0_SA_DQ<16>")
	)
	(segment
		(start 299.437806 -215.610186)
		(end 301.174658 -215.610186)
		(width 0.14478)
		(layer "In4.Cu")
		(net "M_D_CPU0_SA_DQ<16>")
	)
	(segment
		(start 303.773078 -216.698068)
		(end 303.934622 -216.859612)
		(width 0.14478)
		(layer "In4.Cu")
		(net "M_D_CPU0_SA_DQ<16>")
	)
	(segment
		(start 304.714402 -216.168732)
		(end 304.875946 -216.330276)
		(width 0.14478)
		(layer "In4.Cu")
		(net "M_D_CPU0_SA_DQ<16>")
	)
	(segment
		(start 306.140358 -216.859612)
		(end 306.368704 -216.859612)
		(width 0.14478)
		(layer "In4.Cu")
		(net "M_D_CPU0_SA_DQ<16>")
	)
	(segment
		(start 338.27974 -235.091478)
		(end 338.288122 -235.086652)
		(width 0.0889)
		(layer "In4.Cu")
		(net "M_D_CPU0_SA_DQ<16>")
	)
	(segment
		(start 303.18837 -216.46007)
		(end 303.611534 -216.46007)
		(width 0.14478)
		(layer "In4.Cu")
		(net "M_D_CPU0_SA_DQ<16>")
	)
	(segment
		(start 291.481256 -215.922352)
		(end 291.793422 -215.610186)
		(width 0.14478)
		(layer "In4.Cu")
		(net "M_D_CPU0_SA_DQ<16>")
	)
	(segment
		(start 317.130938 -225.424238)
		(end 317.130938 -227.015294)
		(width 0.14478)
		(layer "In4.Cu")
		(net "M_D_CPU0_SA_DQ<16>")
	)
	(segment
		(start 290.929822 -215.610186)
		(end 291.241988 -215.922352)
		(width 0.14478)
		(layer "In4.Cu")
		(net "M_D_CPU0_SA_DQ<16>")
	)
	(segment
		(start 287.547558 -216.46007)
		(end 289.823398 -216.46007)
		(width 0.14478)
		(layer "In4.Cu")
		(net "M_D_CPU0_SA_DQ<16>")
	)
	(segment
		(start 286.83458 -216.335356)
		(end 286.83458 -216.695528)
		(width 0.14478)
		(layer "In4.Cu")
		(net "M_D_CPU0_SA_DQ<16>")
	)
	(segment
		(start 305.978814 -216.330276)
		(end 305.978814 -216.698068)
		(width 0.14478)
		(layer "In4.Cu")
		(net "M_D_CPU0_SA_DQ<16>")
	)
	(segment
		(start 334.519778 -235.091478)
		(end 334.52816 -235.086652)
		(width 0.0889)
		(layer "In4.Cu")
		(net "M_D_CPU0_SA_DQ<16>")
	)
	(segment
		(start 289.823398 -216.46007)
		(end 290.673282 -215.610186)
		(width 0.14478)
		(layer "In4.Cu")
		(net "M_D_CPU0_SA_DQ<16>")
	)
	(segment
		(start 298.599606 -215.610186)
		(end 298.886372 -215.896952)
		(width 0.14478)
		(layer "In4.Cu")
		(net "M_D_CPU0_SA_DQ<16>")
	)
	(segment
		(start 287.22447 -216.857072)
		(end 287.386014 -216.695528)
		(width 0.14478)
		(layer "In4.Cu")
		(net "M_D_CPU0_SA_DQ<16>")
	)
	(segment
		(start 286.283146 -216.335356)
		(end 286.44469 -216.173812)
		(width 0.14478)
		(layer "In4.Cu")
		(net "M_D_CPU0_SA_DQ<16>")
	)
	(segment
		(start 296.41419 -216.735152)
		(end 296.690542 -216.735152)
		(width 0.14478)
		(layer "In4.Cu")
		(net "M_D_CPU0_SA_DQ<16>")
	)
	(segment
		(start 294.348662 -216.46007)
		(end 296.139108 -216.46007)
		(width 0.14478)
		(layer "In4.Cu")
		(net "M_D_CPU0_SA_DQ<16>")
	)
	(segment
		(start 304.324512 -216.330276)
		(end 304.486056 -216.168732)
		(width 0.14478)
		(layer "In4.Cu")
		(net "M_D_CPU0_SA_DQ<16>")
	)
	(segment
		(start 305.588924 -216.168732)
		(end 305.81727 -216.168732)
		(width 0.14478)
		(layer "In4.Cu")
		(net "M_D_CPU0_SA_DQ<16>")
	)
	(segment
		(start 326.165972 -234.423712)
		(end 326.541384 -234.423712)
		(width 0.0889)
		(layer "In4.Cu")
		(net "M_D_CPU0_SA_DQ<16>")
	)
	(segment
		(start 291.793422 -215.610186)
		(end 293.498778 -215.610186)
		(width 0.14478)
		(layer "In4.Cu")
		(net "M_D_CPU0_SA_DQ<16>")
	)
	(segment
		(start 304.324512 -216.698068)
		(end 304.324512 -216.330276)
		(width 0.14478)
		(layer "In4.Cu")
		(net "M_D_CPU0_SA_DQ<16>")
	)
	(segment
		(start 299.15104 -215.896952)
		(end 299.437806 -215.610186)
		(width 0.14478)
		(layer "In4.Cu")
		(net "M_D_CPU0_SA_DQ<16>")
	)
	(segment
		(start 304.162968 -216.859612)
		(end 304.324512 -216.698068)
		(width 0.14478)
		(layer "In4.Cu")
		(net "M_D_CPU0_SA_DQ<16>")
	)
	(segment
		(start 285.893256 -216.857072)
		(end 286.121602 -216.857072)
		(width 0.14478)
		(layer "In4.Cu")
		(net "M_D_CPU0_SA_DQ<16>")
	)
	(segment
		(start 308.16677 -216.46007)
		(end 317.130938 -225.424238)
		(width 0.14478)
		(layer "In4.Cu")
		(net "M_D_CPU0_SA_DQ<16>")
	)
	(segment
		(start 327.14311 -235.025438)
		(end 327.418954 -235.025438)
		(width 0.0889)
		(layer "In4.Cu")
		(net "M_D_CPU0_SA_DQ<16>")
	)
	(segment
		(start 284.736032 -216.035128)
		(end 285.160974 -216.46007)
		(width 0.14478)
		(layer "In4.Cu")
		(net "M_D_CPU0_SA_DQ<16>")
	)
	(segment
		(start 329.819762 -235.091478)
		(end 329.828144 -235.086652)
		(width 0.0889)
		(layer "In4.Cu")
		(net "M_D_CPU0_SA_DQ<16>")
	)
	(segment
		(start 287.386014 -216.621614)
		(end 287.547558 -216.46007)
		(width 0.14478)
		(layer "In4.Cu")
		(net "M_D_CPU0_SA_DQ<16>")
	)
	(segment
		(start 330.394056 -235.086652)
		(end 330.402438 -235.091478)
		(width 0.0889)
		(layer "In4.Cu")
		(net "M_D_CPU0_SA_DQ<16>")
	)
	(segment
		(start 304.875946 -216.698068)
		(end 305.03749 -216.859612)
		(width 0.14478)
		(layer "In4.Cu")
		(net "M_D_CPU0_SA_DQ<16>")
	)
	(segment
		(start 327.57491 -235.086652)
		(end 327.57491 -235.086398)
		(width 0.0889)
		(layer "In4.Cu")
		(net "M_D_CPU0_SA_DQ<16>")
	)
	(segment
		(start 286.83458 -216.695528)
		(end 286.996124 -216.857072)
		(width 0.14478)
		(layer "In4.Cu")
		(net "M_D_CPU0_SA_DQ<16>")
	)
	(segment
		(start 296.690542 -216.735152)
		(end 296.965624 -216.46007)
		(width 0.14478)
		(layer "In4.Cu")
		(net "M_D_CPU0_SA_DQ<16>")
	)
	(segment
		(start 286.283146 -216.695528)
		(end 286.283146 -216.335356)
		(width 0.14478)
		(layer "In4.Cu")
		(net "M_D_CPU0_SA_DQ<16>")
	)
	(segment
		(start 302.024542 -216.46007)
		(end 302.349154 -216.46007)
		(width 0.14478)
		(layer "In4.Cu")
		(net "M_D_CPU0_SA_DQ<16>")
	)
	(segment
		(start 303.934622 -216.859612)
		(end 304.162968 -216.859612)
		(width 0.14478)
		(layer "In4.Cu")
		(net "M_D_CPU0_SA_DQ<16>")
	)
	(segment
		(start 305.81727 -216.168732)
		(end 305.978814 -216.330276)
		(width 0.14478)
		(layer "In4.Cu")
		(net "M_D_CPU0_SA_DQ<16>")
	)
	(segment
		(start 296.965624 -216.46007)
		(end 297.346878 -216.46007)
		(width 0.14478)
		(layer "In4.Cu")
		(net "M_D_CPU0_SA_DQ<16>")
	)
	(segment
		(start 303.611534 -216.46007)
		(end 303.773078 -216.621614)
		(width 0.14478)
		(layer "In4.Cu")
		(net "M_D_CPU0_SA_DQ<16>")
	)
	(segment
		(start 286.996124 -216.857072)
		(end 287.22447 -216.857072)
		(width 0.14478)
		(layer "In4.Cu")
		(net "M_D_CPU0_SA_DQ<16>")
	)
	(segment
		(start 285.160974 -216.46007)
		(end 285.570168 -216.46007)
		(width 0.14478)
		(layer "In4.Cu")
		(net "M_D_CPU0_SA_DQ<16>")
	)
	(segment
		(start 286.121602 -216.857072)
		(end 286.283146 -216.695528)
		(width 0.14478)
		(layer "In4.Cu")
		(net "M_D_CPU0_SA_DQ<16>")
	)
	(segment
		(start 333.579724 -235.091478)
		(end 333.588106 -235.086652)
		(width 0.0889)
		(layer "In4.Cu")
		(net "M_D_CPU0_SA_DQ<16>")
	)
	(segment
		(start 305.42738 -216.330276)
		(end 305.588924 -216.168732)
		(width 0.14478)
		(layer "In4.Cu")
		(net "M_D_CPU0_SA_DQ<16>")
	)
	(segment
		(start 304.875946 -216.330276)
		(end 304.875946 -216.698068)
		(width 0.14478)
		(layer "In4.Cu")
		(net "M_D_CPU0_SA_DQ<16>")
	)
	(segment
		(start 293.498778 -215.610186)
		(end 294.348662 -216.46007)
		(width 0.14478)
		(layer "In4.Cu")
		(net "M_D_CPU0_SA_DQ<16>")
	)
	(segment
		(start 336.034126 -235.086652)
		(end 336.042508 -235.091478)
		(width 0.0889)
		(layer "In4.Cu")
		(net "M_D_CPU0_SA_DQ<16>")
	)
	(segment
		(start 297.346878 -216.46007)
		(end 298.196762 -215.610186)
		(width 0.14478)
		(layer "In4.Cu")
		(net "M_D_CPU0_SA_DQ<16>")
	)
	(segment
		(start 286.673036 -216.173812)
		(end 286.83458 -216.335356)
		(width 0.14478)
		(layer "In4.Cu")
		(net "M_D_CPU0_SA_DQ<16>")
	)
	(segment
		(start 306.368704 -216.859612)
		(end 306.530248 -216.698068)
		(width 0.14478)
		(layer "In4.Cu")
		(net "M_D_CPU0_SA_DQ<16>")
	)
	(segment
		(start 325.355458 -233.461052)
		(end 325.355458 -233.613198)
		(width 0.0889)
		(layer "In4.Cu")
		(net "M_D_CPU0_SA_DQ<16>")
	)
	(segment
		(start 306.530248 -216.698068)
		(end 306.530248 -216.621614)
		(width 0.14478)
		(layer "In4.Cu")
		(net "M_D_CPU0_SA_DQ<16>")
	)
	(segment
		(start 286.44469 -216.173812)
		(end 286.673036 -216.173812)
		(width 0.14478)
		(layer "In4.Cu")
		(net "M_D_CPU0_SA_DQ<16>")
	)
	(segment
		(start 298.886372 -215.896952)
		(end 299.15104 -215.896952)
		(width 0.14478)
		(layer "In4.Cu")
		(net "M_D_CPU0_SA_DQ<16>")
	)
	(segment
		(start 322.908168 -232.792524)
		(end 323.889878 -232.792524)
		(width 0.14478)
		(layer "In4.Cu")
		(net "M_D_CPU0_SA_DQ<16>")
	)
	(segment
		(start 285.570168 -216.46007)
		(end 285.731712 -216.621614)
		(width 0.14478)
		(layer "In4.Cu")
		(net "M_D_CPU0_SA_DQ<16>")
	)
	(segment
		(start 324.68693 -232.792524)
		(end 325.355458 -233.461052)
		(width 0.0889)
		(layer "In4.Cu")
		(net "M_D_CPU0_SA_DQ<16>")
	)
	(segment
		(start 302.900588 -216.747852)
		(end 303.18837 -216.46007)
		(width 0.14478)
		(layer "In4.Cu")
		(net "M_D_CPU0_SA_DQ<16>")
	)
	(segment
		(start 327.57491 -235.086398)
		(end 327.594976 -235.097828)
		(width 0.0889)
		(layer "In4.Cu")
		(net "M_D_CPU0_SA_DQ<16>")
	)
	(segment
		(start 302.636936 -216.747852)
		(end 302.900588 -216.747852)
		(width 0.14478)
		(layer "In4.Cu")
		(net "M_D_CPU0_SA_DQ<16>")
	)
	(segment
		(start 325.355458 -233.613198)
		(end 326.165972 -234.423712)
		(width 0.0889)
		(layer "In4.Cu")
		(net "M_D_CPU0_SA_DQ<16>")
	)
	(segment
		(start 298.196762 -215.610186)
		(end 298.599606 -215.610186)
		(width 0.14478)
		(layer "In4.Cu")
		(net "M_D_CPU0_SA_DQ<16>")
	)
	(segment
		(start 335.094072 -235.086652)
		(end 335.102454 -235.091478)
		(width 0.0889)
		(layer "In4.Cu")
		(net "M_D_CPU0_SA_DQ<16>")
	)
	(segment
		(start 306.691792 -216.46007)
		(end 308.16677 -216.46007)
		(width 0.14478)
		(layer "In4.Cu")
		(net "M_D_CPU0_SA_DQ<16>")
	)
	(segment
		(start 305.978814 -216.698068)
		(end 306.140358 -216.859612)
		(width 0.14478)
		(layer "In4.Cu")
		(net "M_D_CPU0_SA_DQ<16>")
	)
	(arc
		(start 336.042508 -235.091478)
		(mid 336.226016 -235.136972)
		(end 336.408268 -235.086652)
		(width 0.0889)
		(layer "In4.Cu")
		(net "M_D_CPU0_SA_DQ<16>")
	)
	(arc
		(start 334.52816 -235.086652)
		(mid 334.811116 -235.010475)
		(end 335.094072 -235.086652)
		(width 0.0889)
		(layer "In4.Cu")
		(net "M_D_CPU0_SA_DQ<16>")
	)
	(arc
		(start 329.828144 -235.086652)
		(mid 330.1111 -235.010475)
		(end 330.394056 -235.086652)
		(width 0.0889)
		(layer "In4.Cu")
		(net "M_D_CPU0_SA_DQ<16>")
	)
	(arc
		(start 332.274164 -235.086652)
		(mid 332.461108 -235.136907)
		(end 332.648052 -235.086652)
		(width 0.0889)
		(layer "In4.Cu")
		(net "M_D_CPU0_SA_DQ<16>")
	)
	(arc
		(start 333.588106 -235.086652)
		(mid 333.871062 -235.010475)
		(end 334.154018 -235.086652)
		(width 0.0889)
		(layer "In4.Cu")
		(net "M_D_CPU0_SA_DQ<16>")
	)
	(arc
		(start 337.91398 -235.086652)
		(mid 338.096231 -235.137002)
		(end 338.27974 -235.091478)
		(width 0.0889)
		(layer "In4.Cu")
		(net "M_D_CPU0_SA_DQ<16>")
	)
	(arc
		(start 335.102454 -235.091478)
		(mid 335.285962 -235.136972)
		(end 335.468214 -235.086652)
		(width 0.0889)
		(layer "In4.Cu")
		(net "M_D_CPU0_SA_DQ<16>")
	)
	(arc
		(start 337.348068 -235.086652)
		(mid 337.631024 -235.010475)
		(end 337.91398 -235.086652)
		(width 0.0889)
		(layer "In4.Cu")
		(net "M_D_CPU0_SA_DQ<16>")
	)
	(arc
		(start 328.514202 -235.086652)
		(mid 328.701146 -235.136907)
		(end 328.88809 -235.086652)
		(width 0.0889)
		(layer "In4.Cu")
		(net "M_D_CPU0_SA_DQ<16>")
	)
	(arc
		(start 331.342492 -235.091478)
		(mid 331.526 -235.136972)
		(end 331.708252 -235.086652)
		(width 0.0889)
		(layer "In4.Cu")
		(net "M_D_CPU0_SA_DQ<16>")
	)
	(arc
		(start 327.418954 -235.025438)
		(mid 327.49922 -235.050215)
		(end 327.57491 -235.086652)
		(width 0.0889)
		(layer "In4.Cu")
		(net "M_D_CPU0_SA_DQ<16>")
	)
	(arc
		(start 327.94829 -235.086652)
		(mid 328.231246 -235.010475)
		(end 328.514202 -235.086652)
		(width 0.0889)
		(layer "In4.Cu")
		(net "M_D_CPU0_SA_DQ<16>")
	)
	(arc
		(start 338.288122 -235.086652)
		(mid 338.535835 -235.011432)
		(end 338.791042 -235.054902)
		(width 0.0889)
		(layer "In4.Cu")
		(net "M_D_CPU0_SA_DQ<16>")
	)
	(arc
		(start 330.402438 -235.091478)
		(mid 330.585946 -235.136972)
		(end 330.768198 -235.086652)
		(width 0.0889)
		(layer "In4.Cu")
		(net "M_D_CPU0_SA_DQ<16>")
	)
	(arc
		(start 336.97418 -235.086652)
		(mid 337.161124 -235.136907)
		(end 337.348068 -235.086652)
		(width 0.0889)
		(layer "In4.Cu")
		(net "M_D_CPU0_SA_DQ<16>")
	)
	(arc
		(start 332.648052 -235.086652)
		(mid 332.931008 -235.010475)
		(end 333.213964 -235.086652)
		(width 0.0889)
		(layer "In4.Cu")
		(net "M_D_CPU0_SA_DQ<16>")
	)
	(arc
		(start 328.88809 -235.086652)
		(mid 329.171046 -235.010475)
		(end 329.454002 -235.086652)
		(width 0.0889)
		(layer "In4.Cu")
		(net "M_D_CPU0_SA_DQ<16>")
	)
	(arc
		(start 335.468214 -235.086652)
		(mid 335.75117 -235.010475)
		(end 336.034126 -235.086652)
		(width 0.0889)
		(layer "In4.Cu")
		(net "M_D_CPU0_SA_DQ<16>")
	)
	(arc
		(start 330.768198 -235.086652)
		(mid 331.051154 -235.010475)
		(end 331.33411 -235.086652)
		(width 0.0889)
		(layer "In4.Cu")
		(net "M_D_CPU0_SA_DQ<16>")
	)
	(arc
		(start 336.408268 -235.086652)
		(mid 336.691224 -235.010475)
		(end 336.97418 -235.086652)
		(width 0.0889)
		(layer "In4.Cu")
		(net "M_D_CPU0_SA_DQ<16>")
	)
	(arc
		(start 334.154018 -235.086652)
		(mid 334.336269 -235.137002)
		(end 334.519778 -235.091478)
		(width 0.0889)
		(layer "In4.Cu")
		(net "M_D_CPU0_SA_DQ<16>")
	)
	(arc
		(start 331.708252 -235.086652)
		(mid 331.991208 -235.010475)
		(end 332.274164 -235.086652)
		(width 0.0889)
		(layer "In4.Cu")
		(net "M_D_CPU0_SA_DQ<16>")
	)
	(arc
		(start 327.594976 -235.097828)
		(mid 327.773054 -235.136812)
		(end 327.94829 -235.086652)
		(width 0.0889)
		(layer "In4.Cu")
		(net "M_D_CPU0_SA_DQ<16>")
	)
	(arc
		(start 333.213964 -235.086652)
		(mid 333.396215 -235.137002)
		(end 333.579724 -235.091478)
		(width 0.0889)
		(layer "In4.Cu")
		(net "M_D_CPU0_SA_DQ<16>")
	)
	(arc
		(start 329.454002 -235.086652)
		(mid 329.636253 -235.137002)
		(end 329.819762 -235.091478)
		(width 0.0889)
		(layer "In4.Cu")
		(net "M_D_CPU0_SA_DQ<16>")
	)
	(segment
		(start 340.447884 -235.03001)
		(end 339.981032 -234.764072)
		(width 0.10668)
		(layer "F.Cu")
		(net "M_D_CPU0_SA_DQ<15>")
	)
	(segment
		(start 283.54401 -215.162638)
		(end 283.54401 -215.447118)
		(width 0.14478)
		(layer "In4.Cu")
		(net "M_D_CPU0_SA_DQ<15>")
	)
	(segment
		(start 307.953156 -215.610186)
		(end 317.580518 -225.237548)
		(width 0.14478)
		(layer "In4.Cu")
		(net "M_D_CPU0_SA_DQ<15>")
	)
	(segment
		(start 327.331832 -234.390946)
		(end 327.761092 -234.390946)
		(width 0.0889)
		(layer "In4.Cu")
		(net "M_D_CPU0_SA_DQ<15>")
	)
	(segment
		(start 302.04664 -215.610186)
		(end 307.953156 -215.610186)
		(width 0.14478)
		(layer "In4.Cu")
		(net "M_D_CPU0_SA_DQ<15>")
	)
	(segment
		(start 338.27974 -234.436666)
		(end 338.288122 -234.441492)
		(width 0.0889)
		(layer "In4.Cu")
		(net "M_D_CPU0_SA_DQ<15>")
	)
	(segment
		(start 283.150564 -214.99957)
		(end 283.380942 -214.99957)
		(width 0.14478)
		(layer "In4.Cu")
		(net "M_D_CPU0_SA_DQ<15>")
	)
	(segment
		(start 334.519778 -234.436666)
		(end 334.52816 -234.441492)
		(width 0.0889)
		(layer "In4.Cu")
		(net "M_D_CPU0_SA_DQ<15>")
	)
	(segment
		(start 324.19671 -232.337864)
		(end 324.400418 -232.541572)
		(width 0.0889)
		(layer "In4.Cu")
		(net "M_D_CPU0_SA_DQ<15>")
	)
	(segment
		(start 281.874468 -215.447118)
		(end 281.874468 -215.162638)
		(width 0.14478)
		(layer "In4.Cu")
		(net "M_D_CPU0_SA_DQ<15>")
	)
	(segment
		(start 301.196502 -214.760048)
		(end 302.04664 -215.610186)
		(width 0.14478)
		(layer "In4.Cu")
		(net "M_D_CPU0_SA_DQ<15>")
	)
	(segment
		(start 331.33411 -234.441492)
		(end 331.342492 -234.436666)
		(width 0.0889)
		(layer "In4.Cu")
		(net "M_D_CPU0_SA_DQ<15>")
	)
	(segment
		(start 281.874468 -215.162638)
		(end 282.037536 -214.99957)
		(width 0.14478)
		(layer "In4.Cu")
		(net "M_D_CPU0_SA_DQ<15>")
	)
	(segment
		(start 338.854034 -234.441492)
		(end 338.862416 -234.436666)
		(width 0.0889)
		(layer "In4.Cu")
		(net "M_D_CPU0_SA_DQ<15>")
	)
	(segment
		(start 282.267914 -214.99957)
		(end 282.430982 -215.162638)
		(width 0.14478)
		(layer "In4.Cu")
		(net "M_D_CPU0_SA_DQ<15>")
	)
	(segment
		(start 329.819762 -234.436666)
		(end 329.828144 -234.441492)
		(width 0.0889)
		(layer "In4.Cu")
		(net "M_D_CPU0_SA_DQ<15>")
	)
	(segment
		(start 324.400418 -232.541572)
		(end 324.786498 -232.541572)
		(width 0.0889)
		(layer "In4.Cu")
		(net "M_D_CPU0_SA_DQ<15>")
	)
	(segment
		(start 323.12229 -232.337864)
		(end 324.19671 -232.337864)
		(width 0.14478)
		(layer "In4.Cu")
		(net "M_D_CPU0_SA_DQ<15>")
	)
	(segment
		(start 282.824428 -215.610186)
		(end 282.987496 -215.447118)
		(width 0.14478)
		(layer "In4.Cu")
		(net "M_D_CPU0_SA_DQ<15>")
	)
	(segment
		(start 282.037536 -214.99957)
		(end 282.267914 -214.99957)
		(width 0.14478)
		(layer "In4.Cu")
		(net "M_D_CPU0_SA_DQ<15>")
	)
	(segment
		(start 330.394056 -234.441492)
		(end 330.402438 -234.436666)
		(width 0.0889)
		(layer "In4.Cu")
		(net "M_D_CPU0_SA_DQ<15>")
	)
	(segment
		(start 280.635964 -215.18499)
		(end 281.06116 -215.610186)
		(width 0.14478)
		(layer "In4.Cu")
		(net "M_D_CPU0_SA_DQ<15>")
	)
	(segment
		(start 282.59405 -215.610186)
		(end 282.824428 -215.610186)
		(width 0.14478)
		(layer "In4.Cu")
		(net "M_D_CPU0_SA_DQ<15>")
	)
	(segment
		(start 317.580518 -225.237548)
		(end 317.580518 -226.796092)
		(width 0.14478)
		(layer "In4.Cu")
		(net "M_D_CPU0_SA_DQ<15>")
	)
	(segment
		(start 333.579724 -234.436666)
		(end 333.588106 -234.441492)
		(width 0.0889)
		(layer "In4.Cu")
		(net "M_D_CPU0_SA_DQ<15>")
	)
	(segment
		(start 281.7114 -215.610186)
		(end 281.874468 -215.447118)
		(width 0.14478)
		(layer "In4.Cu")
		(net "M_D_CPU0_SA_DQ<15>")
	)
	(segment
		(start 282.987496 -215.447118)
		(end 282.987496 -215.162638)
		(width 0.14478)
		(layer "In4.Cu")
		(net "M_D_CPU0_SA_DQ<15>")
	)
	(segment
		(start 336.034126 -234.441492)
		(end 336.042508 -234.436666)
		(width 0.0889)
		(layer "In4.Cu")
		(net "M_D_CPU0_SA_DQ<15>")
	)
	(segment
		(start 293.507668 -214.760048)
		(end 294.357806 -215.610186)
		(width 0.14478)
		(layer "In4.Cu")
		(net "M_D_CPU0_SA_DQ<15>")
	)
	(segment
		(start 289.82416 -215.610186)
		(end 290.674298 -214.760048)
		(width 0.14478)
		(layer "In4.Cu")
		(net "M_D_CPU0_SA_DQ<15>")
	)
	(segment
		(start 282.987496 -215.162638)
		(end 283.150564 -214.99957)
		(width 0.14478)
		(layer "In4.Cu")
		(net "M_D_CPU0_SA_DQ<15>")
	)
	(segment
		(start 281.06116 -215.610186)
		(end 281.7114 -215.610186)
		(width 0.14478)
		(layer "In4.Cu")
		(net "M_D_CPU0_SA_DQ<15>")
	)
	(segment
		(start 290.674298 -214.760048)
		(end 293.507668 -214.760048)
		(width 0.14478)
		(layer "In4.Cu")
		(net "M_D_CPU0_SA_DQ<15>")
	)
	(segment
		(start 282.430982 -215.162638)
		(end 282.430982 -215.447118)
		(width 0.14478)
		(layer "In4.Cu")
		(net "M_D_CPU0_SA_DQ<15>")
	)
	(segment
		(start 339.794088 -234.441492)
		(end 339.80247 -234.436666)
		(width 0.0889)
		(layer "In4.Cu")
		(net "M_D_CPU0_SA_DQ<15>")
	)
	(segment
		(start 283.380942 -214.99957)
		(end 283.54401 -215.162638)
		(width 0.14478)
		(layer "In4.Cu")
		(net "M_D_CPU0_SA_DQ<15>")
	)
	(segment
		(start 335.094072 -234.441492)
		(end 335.102454 -234.436666)
		(width 0.0889)
		(layer "In4.Cu")
		(net "M_D_CPU0_SA_DQ<15>")
	)
	(segment
		(start 317.580518 -226.796092)
		(end 323.12229 -232.337864)
		(width 0.14478)
		(layer "In4.Cu")
		(net "M_D_CPU0_SA_DQ<15>")
	)
	(segment
		(start 282.430982 -215.447118)
		(end 282.59405 -215.610186)
		(width 0.14478)
		(layer "In4.Cu")
		(net "M_D_CPU0_SA_DQ<15>")
	)
	(segment
		(start 297.312334 -215.610186)
		(end 298.162472 -214.760048)
		(width 0.14478)
		(layer "In4.Cu")
		(net "M_D_CPU0_SA_DQ<15>")
	)
	(segment
		(start 283.707078 -215.610186)
		(end 289.82416 -215.610186)
		(width 0.14478)
		(layer "In4.Cu")
		(net "M_D_CPU0_SA_DQ<15>")
	)
	(segment
		(start 340.13521 -234.498642)
		(end 339.981032 -234.764072)
		(width 0.0889)
		(layer "In4.Cu")
		(net "M_D_CPU0_SA_DQ<15>")
	)
	(segment
		(start 326.539098 -233.598212)
		(end 327.331832 -234.390946)
		(width 0.0889)
		(layer "In4.Cu")
		(net "M_D_CPU0_SA_DQ<15>")
	)
	(segment
		(start 298.162472 -214.760048)
		(end 301.196502 -214.760048)
		(width 0.14478)
		(layer "In4.Cu")
		(net "M_D_CPU0_SA_DQ<15>")
	)
	(segment
		(start 283.54401 -215.447118)
		(end 283.707078 -215.610186)
		(width 0.14478)
		(layer "In4.Cu")
		(net "M_D_CPU0_SA_DQ<15>")
	)
	(segment
		(start 340.112858 -234.41533)
		(end 340.13521 -234.498642)
		(width 0.0889)
		(layer "In4.Cu")
		(net "M_D_CPU0_SA_DQ<15>")
	)
	(segment
		(start 325.843138 -233.598212)
		(end 326.539098 -233.598212)
		(width 0.0889)
		(layer "In4.Cu")
		(net "M_D_CPU0_SA_DQ<15>")
	)
	(segment
		(start 294.357806 -215.610186)
		(end 297.312334 -215.610186)
		(width 0.14478)
		(layer "In4.Cu")
		(net "M_D_CPU0_SA_DQ<15>")
	)
	(segment
		(start 324.786498 -232.541572)
		(end 325.843138 -233.598212)
		(width 0.0889)
		(layer "In4.Cu")
		(net "M_D_CPU0_SA_DQ<15>")
	)
	(arc
		(start 331.342492 -234.436666)
		(mid 331.526 -234.391172)
		(end 331.708252 -234.441492)
		(width 0.0889)
		(layer "In4.Cu")
		(net "M_D_CPU0_SA_DQ<15>")
	)
	(arc
		(start 335.102454 -234.436666)
		(mid 335.285962 -234.391172)
		(end 335.468214 -234.441492)
		(width 0.0889)
		(layer "In4.Cu")
		(net "M_D_CPU0_SA_DQ<15>")
	)
	(arc
		(start 338.288122 -234.441492)
		(mid 338.571078 -234.517669)
		(end 338.854034 -234.441492)
		(width 0.0889)
		(layer "In4.Cu")
		(net "M_D_CPU0_SA_DQ<15>")
	)
	(arc
		(start 331.708252 -234.441492)
		(mid 331.991208 -234.517669)
		(end 332.274164 -234.441492)
		(width 0.0889)
		(layer "In4.Cu")
		(net "M_D_CPU0_SA_DQ<15>")
	)
	(arc
		(start 329.454002 -234.441492)
		(mid 329.636253 -234.391142)
		(end 329.819762 -234.436666)
		(width 0.0889)
		(layer "In4.Cu")
		(net "M_D_CPU0_SA_DQ<15>")
	)
	(arc
		(start 336.97418 -234.441492)
		(mid 337.161124 -234.391237)
		(end 337.348068 -234.441492)
		(width 0.0889)
		(layer "In4.Cu")
		(net "M_D_CPU0_SA_DQ<15>")
	)
	(arc
		(start 334.154018 -234.441492)
		(mid 334.336269 -234.391142)
		(end 334.519778 -234.436666)
		(width 0.0889)
		(layer "In4.Cu")
		(net "M_D_CPU0_SA_DQ<15>")
	)
	(arc
		(start 330.402438 -234.436666)
		(mid 330.585946 -234.391172)
		(end 330.768198 -234.441492)
		(width 0.0889)
		(layer "In4.Cu")
		(net "M_D_CPU0_SA_DQ<15>")
	)
	(arc
		(start 336.408268 -234.441492)
		(mid 336.691224 -234.517669)
		(end 336.97418 -234.441492)
		(width 0.0889)
		(layer "In4.Cu")
		(net "M_D_CPU0_SA_DQ<15>")
	)
	(arc
		(start 328.88809 -234.441492)
		(mid 329.171046 -234.517669)
		(end 329.454002 -234.441492)
		(width 0.0889)
		(layer "In4.Cu")
		(net "M_D_CPU0_SA_DQ<15>")
	)
	(arc
		(start 337.348068 -234.441492)
		(mid 337.631024 -234.517669)
		(end 337.91398 -234.441492)
		(width 0.0889)
		(layer "In4.Cu")
		(net "M_D_CPU0_SA_DQ<15>")
	)
	(arc
		(start 328.514202 -234.441492)
		(mid 328.701146 -234.391237)
		(end 328.88809 -234.441492)
		(width 0.0889)
		(layer "In4.Cu")
		(net "M_D_CPU0_SA_DQ<15>")
	)
	(arc
		(start 336.042508 -234.436666)
		(mid 336.226016 -234.391172)
		(end 336.408268 -234.441492)
		(width 0.0889)
		(layer "In4.Cu")
		(net "M_D_CPU0_SA_DQ<15>")
	)
	(arc
		(start 335.468214 -234.441492)
		(mid 335.75117 -234.517669)
		(end 336.034126 -234.441492)
		(width 0.0889)
		(layer "In4.Cu")
		(net "M_D_CPU0_SA_DQ<15>")
	)
	(arc
		(start 330.768198 -234.441492)
		(mid 331.051154 -234.517669)
		(end 331.33411 -234.441492)
		(width 0.0889)
		(layer "In4.Cu")
		(net "M_D_CPU0_SA_DQ<15>")
	)
	(arc
		(start 338.862416 -234.436666)
		(mid 339.045924 -234.391172)
		(end 339.228176 -234.441492)
		(width 0.0889)
		(layer "In4.Cu")
		(net "M_D_CPU0_SA_DQ<15>")
	)
	(arc
		(start 327.761092 -234.390946)
		(mid 327.858039 -234.403829)
		(end 327.94829 -234.441492)
		(width 0.0889)
		(layer "In4.Cu")
		(net "M_D_CPU0_SA_DQ<15>")
	)
	(arc
		(start 339.80247 -234.436666)
		(mid 339.95534 -234.392025)
		(end 340.112858 -234.41533)
		(width 0.0889)
		(layer "In4.Cu")
		(net "M_D_CPU0_SA_DQ<15>")
	)
	(arc
		(start 334.52816 -234.441492)
		(mid 334.811116 -234.517669)
		(end 335.094072 -234.441492)
		(width 0.0889)
		(layer "In4.Cu")
		(net "M_D_CPU0_SA_DQ<15>")
	)
	(arc
		(start 332.274164 -234.441492)
		(mid 332.461108 -234.391237)
		(end 332.648052 -234.441492)
		(width 0.0889)
		(layer "In4.Cu")
		(net "M_D_CPU0_SA_DQ<15>")
	)
	(arc
		(start 332.648052 -234.441492)
		(mid 332.931008 -234.517669)
		(end 333.213964 -234.441492)
		(width 0.0889)
		(layer "In4.Cu")
		(net "M_D_CPU0_SA_DQ<15>")
	)
	(arc
		(start 333.588106 -234.441492)
		(mid 333.871062 -234.517669)
		(end 334.154018 -234.441492)
		(width 0.0889)
		(layer "In4.Cu")
		(net "M_D_CPU0_SA_DQ<15>")
	)
	(arc
		(start 339.228176 -234.441492)
		(mid 339.511132 -234.517669)
		(end 339.794088 -234.441492)
		(width 0.0889)
		(layer "In4.Cu")
		(net "M_D_CPU0_SA_DQ<15>")
	)
	(arc
		(start 333.213964 -234.441492)
		(mid 333.396215 -234.391142)
		(end 333.579724 -234.436666)
		(width 0.0889)
		(layer "In4.Cu")
		(net "M_D_CPU0_SA_DQ<15>")
	)
	(arc
		(start 329.828144 -234.441492)
		(mid 330.1111 -234.517669)
		(end 330.394056 -234.441492)
		(width 0.0889)
		(layer "In4.Cu")
		(net "M_D_CPU0_SA_DQ<15>")
	)
	(arc
		(start 337.91398 -234.441492)
		(mid 338.096231 -234.391142)
		(end 338.27974 -234.436666)
		(width 0.0889)
		(layer "In4.Cu")
		(net "M_D_CPU0_SA_DQ<15>")
	)
	(arc
		(start 327.94829 -234.441492)
		(mid 328.231246 -234.517669)
		(end 328.514202 -234.441492)
		(width 0.0889)
		(layer "In4.Cu")
		(net "M_D_CPU0_SA_DQ<15>")
	)
	(segment
		(start 339.03793 -234.220004)
		(end 338.571078 -233.954066)
		(width 0.10668)
		(layer "F.Cu")
		(net "M_D_CPU0_SA_DQ<14>")
	)
	(segment
		(start 335.929732 -233.62666)
		(end 335.938114 -233.631486)
		(width 0.0889)
		(layer "In4.Cu")
		(net "M_D_CPU0_SA_DQ<14>")
	)
	(segment
		(start 327.47966 -233.63174)
		(end 327.50125 -233.644186)
		(width 0.0889)
		(layer "In4.Cu")
		(net "M_D_CPU0_SA_DQ<14>")
	)
	(segment
		(start 283.471112 -213.067392)
		(end 283.70149 -213.067392)
		(width 0.14478)
		(layer "In4.Cu")
		(net "M_D_CPU0_SA_DQ<14>")
	)
	(segment
		(start 282.031948 -213.910164)
		(end 282.195016 -213.747096)
		(width 0.14478)
		(layer "In4.Cu")
		(net "M_D_CPU0_SA_DQ<14>")
	)
	(segment
		(start 282.195016 -213.288118)
		(end 282.358084 -213.12505)
		(width 0.14478)
		(layer "In4.Cu")
		(net "M_D_CPU0_SA_DQ<14>")
	)
	(segment
		(start 326.743568 -232.922572)
		(end 327.363074 -233.542078)
		(width 0.0889)
		(layer "In4.Cu")
		(net "M_D_CPU0_SA_DQ<14>")
	)
	(segment
		(start 283.308044 -213.747096)
		(end 283.308044 -213.23046)
		(width 0.14478)
		(layer "In4.Cu")
		(net "M_D_CPU0_SA_DQ<14>")
	)
	(segment
		(start 282.75153 -213.288118)
		(end 282.75153 -213.747096)
		(width 0.14478)
		(layer "In4.Cu")
		(net "M_D_CPU0_SA_DQ<14>")
	)
	(segment
		(start 331.229716 -233.62666)
		(end 331.238098 -233.631486)
		(width 0.0889)
		(layer "In4.Cu")
		(net "M_D_CPU0_SA_DQ<14>")
	)
	(segment
		(start 293.507668 -213.060026)
		(end 294.357806 -213.910164)
		(width 0.14478)
		(layer "In4.Cu")
		(net "M_D_CPU0_SA_DQ<14>")
	)
	(segment
		(start 324.83552 -231.320594)
		(end 325.157338 -231.642412)
		(width 0.0889)
		(layer "In4.Cu")
		(net "M_D_CPU0_SA_DQ<14>")
	)
	(segment
		(start 328.984102 -233.631486)
		(end 328.992484 -233.62666)
		(width 0.0889)
		(layer "In4.Cu")
		(net "M_D_CPU0_SA_DQ<14>")
	)
	(segment
		(start 298.162472 -213.060026)
		(end 301.196502 -213.060026)
		(width 0.14478)
		(layer "In4.Cu")
		(net "M_D_CPU0_SA_DQ<14>")
	)
	(segment
		(start 282.588462 -213.12505)
		(end 282.75153 -213.288118)
		(width 0.14478)
		(layer "In4.Cu")
		(net "M_D_CPU0_SA_DQ<14>")
	)
	(segment
		(start 283.144976 -213.910164)
		(end 283.308044 -213.747096)
		(width 0.14478)
		(layer "In4.Cu")
		(net "M_D_CPU0_SA_DQ<14>")
	)
	(segment
		(start 323.53123 -231.320594)
		(end 323.859398 -231.320594)
		(width 0.14478)
		(layer "In4.Cu")
		(net "M_D_CPU0_SA_DQ<14>")
	)
	(segment
		(start 281.06116 -213.910164)
		(end 282.031948 -213.910164)
		(width 0.14478)
		(layer "In4.Cu")
		(net "M_D_CPU0_SA_DQ<14>")
	)
	(segment
		(start 282.75153 -213.747096)
		(end 282.914598 -213.910164)
		(width 0.14478)
		(layer "In4.Cu")
		(net "M_D_CPU0_SA_DQ<14>")
	)
	(segment
		(start 282.914598 -213.910164)
		(end 283.144976 -213.910164)
		(width 0.14478)
		(layer "In4.Cu")
		(net "M_D_CPU0_SA_DQ<14>")
	)
	(segment
		(start 318.597788 -224.839276)
		(end 318.597788 -226.387152)
		(width 0.14478)
		(layer "In4.Cu")
		(net "M_D_CPU0_SA_DQ<14>")
	)
	(segment
		(start 338.725002 -233.688636)
		(end 338.571078 -233.954066)
		(width 0.0889)
		(layer "In4.Cu")
		(net "M_D_CPU0_SA_DQ<14>")
	)
	(segment
		(start 283.308044 -213.23046)
		(end 283.471112 -213.067392)
		(width 0.14478)
		(layer "In4.Cu")
		(net "M_D_CPU0_SA_DQ<14>")
	)
	(segment
		(start 318.597788 -226.387152)
		(end 323.53123 -231.320594)
		(width 0.14478)
		(layer "In4.Cu")
		(net "M_D_CPU0_SA_DQ<14>")
	)
	(segment
		(start 289.82416 -213.910164)
		(end 290.674298 -213.060026)
		(width 0.14478)
		(layer "In4.Cu")
		(net "M_D_CPU0_SA_DQ<14>")
	)
	(segment
		(start 323.859398 -231.320594)
		(end 324.83552 -231.320594)
		(width 0.0889)
		(layer "In4.Cu")
		(net "M_D_CPU0_SA_DQ<14>")
	)
	(segment
		(start 336.869786 -233.62666)
		(end 336.878168 -233.631486)
		(width 0.0889)
		(layer "In4.Cu")
		(net "M_D_CPU0_SA_DQ<14>")
	)
	(segment
		(start 328.409808 -233.62666)
		(end 328.41819 -233.631486)
		(width 0.0889)
		(layer "In4.Cu")
		(net "M_D_CPU0_SA_DQ<14>")
	)
	(segment
		(start 294.357806 -213.910164)
		(end 297.312334 -213.910164)
		(width 0.14478)
		(layer "In4.Cu")
		(net "M_D_CPU0_SA_DQ<14>")
	)
	(segment
		(start 338.70265 -233.605324)
		(end 338.725002 -233.688636)
		(width 0.0889)
		(layer "In4.Cu")
		(net "M_D_CPU0_SA_DQ<14>")
	)
	(segment
		(start 325.157338 -231.642412)
		(end 325.157338 -231.957372)
		(width 0.0889)
		(layer "In4.Cu")
		(net "M_D_CPU0_SA_DQ<14>")
	)
	(segment
		(start 290.674298 -213.060026)
		(end 293.507668 -213.060026)
		(width 0.14478)
		(layer "In4.Cu")
		(net "M_D_CPU0_SA_DQ<14>")
	)
	(segment
		(start 283.864558 -213.23046)
		(end 283.864558 -213.747096)
		(width 0.14478)
		(layer "In4.Cu")
		(net "M_D_CPU0_SA_DQ<14>")
	)
	(segment
		(start 282.358084 -213.12505)
		(end 282.588462 -213.12505)
		(width 0.14478)
		(layer "In4.Cu")
		(net "M_D_CPU0_SA_DQ<14>")
	)
	(segment
		(start 297.312334 -213.910164)
		(end 298.162472 -213.060026)
		(width 0.14478)
		(layer "In4.Cu")
		(net "M_D_CPU0_SA_DQ<14>")
	)
	(segment
		(start 301.196502 -213.060026)
		(end 302.04664 -213.910164)
		(width 0.14478)
		(layer "In4.Cu")
		(net "M_D_CPU0_SA_DQ<14>")
	)
	(segment
		(start 332.16977 -233.62666)
		(end 332.178152 -233.631486)
		(width 0.0889)
		(layer "In4.Cu")
		(net "M_D_CPU0_SA_DQ<14>")
	)
	(segment
		(start 333.684118 -233.631486)
		(end 333.6925 -233.62666)
		(width 0.0889)
		(layer "In4.Cu")
		(net "M_D_CPU0_SA_DQ<14>")
	)
	(segment
		(start 326.122538 -232.922572)
		(end 326.743568 -232.922572)
		(width 0.0889)
		(layer "In4.Cu")
		(net "M_D_CPU0_SA_DQ<14>")
	)
	(segment
		(start 280.635964 -213.484968)
		(end 281.06116 -213.910164)
		(width 0.14478)
		(layer "In4.Cu")
		(net "M_D_CPU0_SA_DQ<14>")
	)
	(segment
		(start 337.44408 -233.631486)
		(end 337.452462 -233.62666)
		(width 0.0889)
		(layer "In4.Cu")
		(net "M_D_CPU0_SA_DQ<14>")
	)
	(segment
		(start 302.04664 -213.910164)
		(end 307.668676 -213.910164)
		(width 0.14478)
		(layer "In4.Cu")
		(net "M_D_CPU0_SA_DQ<14>")
	)
	(segment
		(start 332.744064 -233.631486)
		(end 332.752446 -233.62666)
		(width 0.0889)
		(layer "In4.Cu")
		(net "M_D_CPU0_SA_DQ<14>")
	)
	(segment
		(start 283.864558 -213.747096)
		(end 284.027626 -213.910164)
		(width 0.14478)
		(layer "In4.Cu")
		(net "M_D_CPU0_SA_DQ<14>")
	)
	(segment
		(start 325.157338 -231.957372)
		(end 326.122538 -232.922572)
		(width 0.0889)
		(layer "In4.Cu")
		(net "M_D_CPU0_SA_DQ<14>")
	)
	(segment
		(start 283.70149 -213.067392)
		(end 283.864558 -213.23046)
		(width 0.14478)
		(layer "In4.Cu")
		(net "M_D_CPU0_SA_DQ<14>")
	)
	(segment
		(start 307.668676 -213.910164)
		(end 318.597788 -224.839276)
		(width 0.14478)
		(layer "In4.Cu")
		(net "M_D_CPU0_SA_DQ<14>")
	)
	(segment
		(start 284.027626 -213.910164)
		(end 289.82416 -213.910164)
		(width 0.14478)
		(layer "In4.Cu")
		(net "M_D_CPU0_SA_DQ<14>")
	)
	(segment
		(start 282.195016 -213.747096)
		(end 282.195016 -213.288118)
		(width 0.14478)
		(layer "In4.Cu")
		(net "M_D_CPU0_SA_DQ<14>")
	)
	(arc
		(start 336.878168 -233.631486)
		(mid 337.161124 -233.707663)
		(end 337.44408 -233.631486)
		(width 0.0889)
		(layer "In4.Cu")
		(net "M_D_CPU0_SA_DQ<14>")
	)
	(arc
		(start 337.452462 -233.62666)
		(mid 337.63597 -233.581166)
		(end 337.818222 -233.631486)
		(width 0.0889)
		(layer "In4.Cu")
		(net "M_D_CPU0_SA_DQ<14>")
	)
	(arc
		(start 327.363074 -233.542078)
		(mid 327.418423 -233.590737)
		(end 327.47966 -233.63174)
		(width 0.0889)
		(layer "In4.Cu")
		(net "M_D_CPU0_SA_DQ<14>")
	)
	(arc
		(start 331.80401 -233.631486)
		(mid 331.986261 -233.581136)
		(end 332.16977 -233.62666)
		(width 0.0889)
		(layer "In4.Cu")
		(net "M_D_CPU0_SA_DQ<14>")
	)
	(arc
		(start 335.938114 -233.631486)
		(mid 336.22107 -233.707663)
		(end 336.504026 -233.631486)
		(width 0.0889)
		(layer "In4.Cu")
		(net "M_D_CPU0_SA_DQ<14>")
	)
	(arc
		(start 330.863956 -233.631486)
		(mid 331.046207 -233.581136)
		(end 331.229716 -233.62666)
		(width 0.0889)
		(layer "In4.Cu")
		(net "M_D_CPU0_SA_DQ<14>")
	)
	(arc
		(start 338.384134 -233.631486)
		(mid 338.540453 -233.582491)
		(end 338.70265 -233.605324)
		(width 0.0889)
		(layer "In4.Cu")
		(net "M_D_CPU0_SA_DQ<14>")
	)
	(arc
		(start 327.50125 -233.644186)
		(mid 327.774279 -233.707505)
		(end 328.044048 -233.631486)
		(width 0.0889)
		(layer "In4.Cu")
		(net "M_D_CPU0_SA_DQ<14>")
	)
	(arc
		(start 331.238098 -233.631486)
		(mid 331.521054 -233.707663)
		(end 331.80401 -233.631486)
		(width 0.0889)
		(layer "In4.Cu")
		(net "M_D_CPU0_SA_DQ<14>")
	)
	(arc
		(start 334.99806 -233.631486)
		(mid 335.281016 -233.707663)
		(end 335.563972 -233.631486)
		(width 0.0889)
		(layer "In4.Cu")
		(net "M_D_CPU0_SA_DQ<14>")
	)
	(arc
		(start 333.118206 -233.631486)
		(mid 333.401162 -233.707663)
		(end 333.684118 -233.631486)
		(width 0.0889)
		(layer "In4.Cu")
		(net "M_D_CPU0_SA_DQ<14>")
	)
	(arc
		(start 328.41819 -233.631486)
		(mid 328.701146 -233.707663)
		(end 328.984102 -233.631486)
		(width 0.0889)
		(layer "In4.Cu")
		(net "M_D_CPU0_SA_DQ<14>")
	)
	(arc
		(start 335.563972 -233.631486)
		(mid 335.746223 -233.581136)
		(end 335.929732 -233.62666)
		(width 0.0889)
		(layer "In4.Cu")
		(net "M_D_CPU0_SA_DQ<14>")
	)
	(arc
		(start 330.298044 -233.631486)
		(mid 330.581 -233.707663)
		(end 330.863956 -233.631486)
		(width 0.0889)
		(layer "In4.Cu")
		(net "M_D_CPU0_SA_DQ<14>")
	)
	(arc
		(start 328.992484 -233.62666)
		(mid 329.175992 -233.581166)
		(end 329.358244 -233.631486)
		(width 0.0889)
		(layer "In4.Cu")
		(net "M_D_CPU0_SA_DQ<14>")
	)
	(arc
		(start 328.044048 -233.631486)
		(mid 328.226299 -233.581136)
		(end 328.409808 -233.62666)
		(width 0.0889)
		(layer "In4.Cu")
		(net "M_D_CPU0_SA_DQ<14>")
	)
	(arc
		(start 329.358244 -233.631486)
		(mid 329.6412 -233.707663)
		(end 329.924156 -233.631486)
		(width 0.0889)
		(layer "In4.Cu")
		(net "M_D_CPU0_SA_DQ<14>")
	)
	(arc
		(start 337.818222 -233.631486)
		(mid 338.101178 -233.707663)
		(end 338.384134 -233.631486)
		(width 0.0889)
		(layer "In4.Cu")
		(net "M_D_CPU0_SA_DQ<14>")
	)
	(arc
		(start 333.6925 -233.62666)
		(mid 333.876008 -233.581166)
		(end 334.05826 -233.631486)
		(width 0.0889)
		(layer "In4.Cu")
		(net "M_D_CPU0_SA_DQ<14>")
	)
	(arc
		(start 332.752446 -233.62666)
		(mid 332.935954 -233.581166)
		(end 333.118206 -233.631486)
		(width 0.0889)
		(layer "In4.Cu")
		(net "M_D_CPU0_SA_DQ<14>")
	)
	(arc
		(start 336.504026 -233.631486)
		(mid 336.686277 -233.581136)
		(end 336.869786 -233.62666)
		(width 0.0889)
		(layer "In4.Cu")
		(net "M_D_CPU0_SA_DQ<14>")
	)
	(arc
		(start 332.178152 -233.631486)
		(mid 332.461108 -233.707663)
		(end 332.744064 -233.631486)
		(width 0.0889)
		(layer "In4.Cu")
		(net "M_D_CPU0_SA_DQ<14>")
	)
	(arc
		(start 334.05826 -233.631486)
		(mid 334.341216 -233.707663)
		(end 334.624172 -233.631486)
		(width 0.0889)
		(layer "In4.Cu")
		(net "M_D_CPU0_SA_DQ<14>")
	)
	(arc
		(start 329.924156 -233.631486)
		(mid 330.1111 -233.581231)
		(end 330.298044 -233.631486)
		(width 0.0889)
		(layer "In4.Cu")
		(net "M_D_CPU0_SA_DQ<14>")
	)
	(arc
		(start 334.624172 -233.631486)
		(mid 334.811116 -233.581231)
		(end 334.99806 -233.631486)
		(width 0.0889)
		(layer "In4.Cu")
		(net "M_D_CPU0_SA_DQ<14>")
	)
	(segment
		(start 340.918038 -234.220004)
		(end 340.451186 -233.954066)
		(width 0.10668)
		(layer "F.Cu")
		(net "M_D_CPU0_SA_DQ<13>")
	)
	(segment
		(start 291.481002 -214.29599)
		(end 291.64407 -214.132922)
		(width 0.14478)
		(layer "In4.Cu")
		(net "M_D_CPU0_SA_DQ<13>")
	)
	(segment
		(start 304.66157 -214.372952)
		(end 304.823114 -214.534496)
		(width 0.14478)
		(layer "In4.Cu")
		(net "M_D_CPU0_SA_DQ<13>")
	)
	(segment
		(start 302.62195 -214.986362)
		(end 302.785018 -215.14943)
		(width 0.14478)
		(layer "In4.Cu")
		(net "M_D_CPU0_SA_DQ<13>")
	)
	(segment
		(start 307.190394 -214.760048)
		(end 307.882544 -214.760048)
		(width 0.14478)
		(layer "In4.Cu")
		(net "M_D_CPU0_SA_DQ<13>")
	)
	(segment
		(start 288.717228 -214.923116)
		(end 288.717228 -214.986362)
		(width 0.14478)
		(layer "In4.Cu")
		(net "M_D_CPU0_SA_DQ<13>")
	)
	(segment
		(start 340.297008 -234.219496)
		(end 340.451186 -233.954066)
		(width 0.0889)
		(layer "In4.Cu")
		(net "M_D_CPU0_SA_DQ<13>")
	)
	(segment
		(start 296.193718 -214.760048)
		(end 296.356786 -214.923116)
		(width 0.14478)
		(layer "In4.Cu")
		(net "M_D_CPU0_SA_DQ<13>")
	)
	(segment
		(start 307.02885 -214.598504)
		(end 307.190394 -214.760048)
		(width 0.14478)
		(layer "In4.Cu")
		(net "M_D_CPU0_SA_DQ<13>")
	)
	(segment
		(start 331.229716 -234.281472)
		(end 331.238098 -234.276646)
		(width 0.0889)
		(layer "In4.Cu")
		(net "M_D_CPU0_SA_DQ<13>")
	)
	(segment
		(start 303.178464 -214.923116)
		(end 303.341532 -214.760048)
		(width 0.14478)
		(layer "In4.Cu")
		(net "M_D_CPU0_SA_DQ<13>")
	)
	(segment
		(start 285.82493 -214.923116)
		(end 285.82493 -214.981282)
		(width 0.14478)
		(layer "In4.Cu")
		(net "M_D_CPU0_SA_DQ<13>")
	)
	(segment
		(start 286.381444 -214.981282)
		(end 286.381444 -214.538814)
		(width 0.14478)
		(layer "In4.Cu")
		(net "M_D_CPU0_SA_DQ<13>")
	)
	(segment
		(start 293.498778 -213.910164)
		(end 294.348662 -214.760048)
		(width 0.14478)
		(layer "In4.Cu")
		(net "M_D_CPU0_SA_DQ<13>")
	)
	(segment
		(start 305.764438 -214.372952)
		(end 305.925982 -214.534496)
		(width 0.14478)
		(layer "In4.Cu")
		(net "M_D_CPU0_SA_DQ<13>")
	)
	(segment
		(start 288.55416 -214.760048)
		(end 288.717228 -214.923116)
		(width 0.14478)
		(layer "In4.Cu")
		(net "M_D_CPU0_SA_DQ<13>")
	)
	(segment
		(start 328.984102 -234.276646)
		(end 328.992484 -234.281472)
		(width 0.0889)
		(layer "In4.Cu")
		(net "M_D_CPU0_SA_DQ<13>")
	)
	(segment
		(start 284.736032 -214.335106)
		(end 285.160974 -214.760048)
		(width 0.14478)
		(layer "In4.Cu")
		(net "M_D_CPU0_SA_DQ<13>")
	)
	(segment
		(start 296.9133 -214.986362)
		(end 296.9133 -214.923116)
		(width 0.14478)
		(layer "In4.Cu")
		(net "M_D_CPU0_SA_DQ<13>")
	)
	(segment
		(start 305.925982 -214.534496)
		(end 305.925982 -214.854028)
		(width 0.14478)
		(layer "In4.Cu")
		(net "M_D_CPU0_SA_DQ<13>")
	)
	(segment
		(start 289.43681 -214.760048)
		(end 289.823398 -214.760048)
		(width 0.14478)
		(layer "In4.Cu")
		(net "M_D_CPU0_SA_DQ<13>")
	)
	(segment
		(start 340.200742 -234.244896)
		(end 340.297008 -234.219496)
		(width 0.0889)
		(layer "In4.Cu")
		(net "M_D_CPU0_SA_DQ<13>")
	)
	(segment
		(start 286.77489 -214.375746)
		(end 286.937958 -214.538814)
		(width 0.14478)
		(layer "In4.Cu")
		(net "M_D_CPU0_SA_DQ<13>")
	)
	(segment
		(start 286.544512 -214.375746)
		(end 286.77489 -214.375746)
		(width 0.14478)
		(layer "In4.Cu")
		(net "M_D_CPU0_SA_DQ<13>")
	)
	(segment
		(start 294.348662 -214.760048)
		(end 296.193718 -214.760048)
		(width 0.14478)
		(layer "In4.Cu")
		(net "M_D_CPU0_SA_DQ<13>")
	)
	(segment
		(start 326.674988 -233.306112)
		(end 327.569322 -234.200446)
		(width 0.0889)
		(layer "In4.Cu")
		(net "M_D_CPU0_SA_DQ<13>")
	)
	(segment
		(start 306.477416 -214.534496)
		(end 306.63896 -214.372952)
		(width 0.14478)
		(layer "In4.Cu")
		(net "M_D_CPU0_SA_DQ<13>")
	)
	(segment
		(start 301.174658 -213.910164)
		(end 302.024542 -214.760048)
		(width 0.14478)
		(layer "In4.Cu")
		(net "M_D_CPU0_SA_DQ<13>")
	)
	(segment
		(start 289.273742 -214.923116)
		(end 289.43681 -214.760048)
		(width 0.14478)
		(layer "In4.Cu")
		(net "M_D_CPU0_SA_DQ<13>")
	)
	(segment
		(start 307.02885 -214.534496)
		(end 307.02885 -214.598504)
		(width 0.14478)
		(layer "In4.Cu")
		(net "M_D_CPU0_SA_DQ<13>")
	)
	(segment
		(start 286.937958 -214.538814)
		(end 286.937958 -214.981282)
		(width 0.14478)
		(layer "In4.Cu")
		(net "M_D_CPU0_SA_DQ<13>")
	)
	(segment
		(start 332.16977 -234.281472)
		(end 332.178152 -234.276646)
		(width 0.0889)
		(layer "In4.Cu")
		(net "M_D_CPU0_SA_DQ<13>")
	)
	(segment
		(start 291.087556 -214.132922)
		(end 291.250624 -214.29599)
		(width 0.14478)
		(layer "In4.Cu")
		(net "M_D_CPU0_SA_DQ<13>")
	)
	(segment
		(start 291.807138 -213.910164)
		(end 293.498778 -213.910164)
		(width 0.14478)
		(layer "In4.Cu")
		(net "M_D_CPU0_SA_DQ<13>")
	)
	(segment
		(start 303.341532 -214.760048)
		(end 304.110136 -214.760048)
		(width 0.14478)
		(layer "In4.Cu")
		(net "M_D_CPU0_SA_DQ<13>")
	)
	(segment
		(start 302.62195 -214.923116)
		(end 302.62195 -214.986362)
		(width 0.14478)
		(layer "In4.Cu")
		(net "M_D_CPU0_SA_DQ<13>")
	)
	(segment
		(start 291.250624 -214.29599)
		(end 291.481002 -214.29599)
		(width 0.14478)
		(layer "In4.Cu")
		(net "M_D_CPU0_SA_DQ<13>")
	)
	(segment
		(start 323.342762 -231.775254)
		(end 323.910198 -231.775254)
		(width 0.14478)
		(layer "In4.Cu")
		(net "M_D_CPU0_SA_DQ<13>")
	)
	(segment
		(start 305.925982 -214.854028)
		(end 306.087526 -215.015572)
		(width 0.14478)
		(layer "In4.Cu")
		(net "M_D_CPU0_SA_DQ<13>")
	)
	(segment
		(start 285.160974 -214.760048)
		(end 285.661862 -214.760048)
		(width 0.14478)
		(layer "In4.Cu")
		(net "M_D_CPU0_SA_DQ<13>")
	)
	(segment
		(start 324.560438 -232.239312)
		(end 324.897496 -232.239312)
		(width 0.0889)
		(layer "In4.Cu")
		(net "M_D_CPU0_SA_DQ<13>")
	)
	(segment
		(start 298.493688 -213.910164)
		(end 298.656756 -214.073232)
		(width 0.14478)
		(layer "In4.Cu")
		(net "M_D_CPU0_SA_DQ<13>")
	)
	(segment
		(start 306.315872 -215.015572)
		(end 306.477416 -214.854028)
		(width 0.14478)
		(layer "In4.Cu")
		(net "M_D_CPU0_SA_DQ<13>")
	)
	(segment
		(start 305.213004 -214.934292)
		(end 305.374548 -214.772748)
		(width 0.14478)
		(layer "In4.Cu")
		(net "M_D_CPU0_SA_DQ<13>")
	)
	(segment
		(start 325.964296 -233.306112)
		(end 326.674988 -233.306112)
		(width 0.0889)
		(layer "In4.Cu")
		(net "M_D_CPU0_SA_DQ<13>")
	)
	(segment
		(start 328.409808 -234.281472)
		(end 328.41819 -234.276646)
		(width 0.0889)
		(layer "In4.Cu")
		(net "M_D_CPU0_SA_DQ<13>")
	)
	(segment
		(start 298.656756 -214.140542)
		(end 298.819824 -214.30361)
		(width 0.14478)
		(layer "In4.Cu")
		(net "M_D_CPU0_SA_DQ<13>")
	)
	(segment
		(start 291.64407 -214.073232)
		(end 291.807138 -213.910164)
		(width 0.14478)
		(layer "In4.Cu")
		(net "M_D_CPU0_SA_DQ<13>")
	)
	(segment
		(start 296.356786 -214.923116)
		(end 296.356786 -214.986362)
		(width 0.14478)
		(layer "In4.Cu")
		(net "M_D_CPU0_SA_DQ<13>")
	)
	(segment
		(start 335.929732 -234.281472)
		(end 335.938114 -234.276646)
		(width 0.0889)
		(layer "In4.Cu")
		(net "M_D_CPU0_SA_DQ<13>")
	)
	(segment
		(start 339.689694 -234.281472)
		(end 339.698076 -234.276646)
		(width 0.0889)
		(layer "In4.Cu")
		(net "M_D_CPU0_SA_DQ<13>")
	)
	(segment
		(start 299.21327 -214.140542)
		(end 299.21327 -214.073232)
		(width 0.14478)
		(layer "In4.Cu")
		(net "M_D_CPU0_SA_DQ<13>")
	)
	(segment
		(start 296.356786 -214.986362)
		(end 296.519854 -215.14943)
		(width 0.14478)
		(layer "In4.Cu")
		(net "M_D_CPU0_SA_DQ<13>")
	)
	(segment
		(start 288.880296 -215.14943)
		(end 289.110674 -215.14943)
		(width 0.14478)
		(layer "In4.Cu")
		(net "M_D_CPU0_SA_DQ<13>")
	)
	(segment
		(start 297.076368 -214.760048)
		(end 297.346878 -214.760048)
		(width 0.14478)
		(layer "In4.Cu")
		(net "M_D_CPU0_SA_DQ<13>")
	)
	(segment
		(start 302.024542 -214.760048)
		(end 302.458882 -214.760048)
		(width 0.14478)
		(layer "In4.Cu")
		(net "M_D_CPU0_SA_DQ<13>")
	)
	(segment
		(start 289.823398 -214.760048)
		(end 290.673282 -213.910164)
		(width 0.14478)
		(layer "In4.Cu")
		(net "M_D_CPU0_SA_DQ<13>")
	)
	(segment
		(start 332.744064 -234.276646)
		(end 332.752446 -234.281472)
		(width 0.0889)
		(layer "In4.Cu")
		(net "M_D_CPU0_SA_DQ<13>")
	)
	(segment
		(start 303.015396 -215.14943)
		(end 303.178464 -214.986362)
		(width 0.14478)
		(layer "In4.Cu")
		(net "M_D_CPU0_SA_DQ<13>")
	)
	(segment
		(start 304.823114 -214.772748)
		(end 304.984658 -214.934292)
		(width 0.14478)
		(layer "In4.Cu")
		(net "M_D_CPU0_SA_DQ<13>")
	)
	(segment
		(start 306.477416 -214.854028)
		(end 306.477416 -214.534496)
		(width 0.14478)
		(layer "In4.Cu")
		(net "M_D_CPU0_SA_DQ<13>")
	)
	(segment
		(start 287.494472 -214.981282)
		(end 287.494472 -214.923116)
		(width 0.14478)
		(layer "In4.Cu")
		(net "M_D_CPU0_SA_DQ<13>")
	)
	(segment
		(start 324.09638 -231.775254)
		(end 324.560438 -232.239312)
		(width 0.0889)
		(layer "In4.Cu")
		(net "M_D_CPU0_SA_DQ<13>")
	)
	(segment
		(start 285.987998 -215.14435)
		(end 286.218376 -215.14435)
		(width 0.14478)
		(layer "In4.Cu")
		(net "M_D_CPU0_SA_DQ<13>")
	)
	(segment
		(start 305.536092 -214.372952)
		(end 305.764438 -214.372952)
		(width 0.14478)
		(layer "In4.Cu")
		(net "M_D_CPU0_SA_DQ<13>")
	)
	(segment
		(start 304.27168 -214.534496)
		(end 304.433224 -214.372952)
		(width 0.14478)
		(layer "In4.Cu")
		(net "M_D_CPU0_SA_DQ<13>")
	)
	(segment
		(start 299.376338 -213.910164)
		(end 301.174658 -213.910164)
		(width 0.14478)
		(layer "In4.Cu")
		(net "M_D_CPU0_SA_DQ<13>")
	)
	(segment
		(start 296.750232 -215.14943)
		(end 296.9133 -214.986362)
		(width 0.14478)
		(layer "In4.Cu")
		(net "M_D_CPU0_SA_DQ<13>")
	)
	(segment
		(start 287.331404 -215.14435)
		(end 287.494472 -214.981282)
		(width 0.14478)
		(layer "In4.Cu")
		(net "M_D_CPU0_SA_DQ<13>")
	)
	(segment
		(start 287.65754 -214.760048)
		(end 288.55416 -214.760048)
		(width 0.14478)
		(layer "In4.Cu")
		(net "M_D_CPU0_SA_DQ<13>")
	)
	(segment
		(start 289.273742 -214.986362)
		(end 289.273742 -214.923116)
		(width 0.14478)
		(layer "In4.Cu")
		(net "M_D_CPU0_SA_DQ<13>")
	)
	(segment
		(start 298.819824 -214.30361)
		(end 299.050202 -214.30361)
		(width 0.14478)
		(layer "In4.Cu")
		(net "M_D_CPU0_SA_DQ<13>")
	)
	(segment
		(start 304.433224 -214.372952)
		(end 304.66157 -214.372952)
		(width 0.14478)
		(layer "In4.Cu")
		(net "M_D_CPU0_SA_DQ<13>")
	)
	(segment
		(start 299.21327 -214.073232)
		(end 299.376338 -213.910164)
		(width 0.14478)
		(layer "In4.Cu")
		(net "M_D_CPU0_SA_DQ<13>")
	)
	(segment
		(start 318.143128 -225.020632)
		(end 318.143128 -226.57562)
		(width 0.14478)
		(layer "In4.Cu")
		(net "M_D_CPU0_SA_DQ<13>")
	)
	(segment
		(start 304.984658 -214.934292)
		(end 305.213004 -214.934292)
		(width 0.14478)
		(layer "In4.Cu")
		(net "M_D_CPU0_SA_DQ<13>")
	)
	(segment
		(start 286.937958 -214.981282)
		(end 287.101026 -215.14435)
		(width 0.14478)
		(layer "In4.Cu")
		(net "M_D_CPU0_SA_DQ<13>")
	)
	(segment
		(start 296.9133 -214.923116)
		(end 297.076368 -214.760048)
		(width 0.14478)
		(layer "In4.Cu")
		(net "M_D_CPU0_SA_DQ<13>")
	)
	(segment
		(start 306.63896 -214.372952)
		(end 306.867306 -214.372952)
		(width 0.14478)
		(layer "In4.Cu")
		(net "M_D_CPU0_SA_DQ<13>")
	)
	(segment
		(start 302.785018 -215.14943)
		(end 303.015396 -215.14943)
		(width 0.14478)
		(layer "In4.Cu")
		(net "M_D_CPU0_SA_DQ<13>")
	)
	(segment
		(start 286.381444 -214.538814)
		(end 286.544512 -214.375746)
		(width 0.14478)
		(layer "In4.Cu")
		(net "M_D_CPU0_SA_DQ<13>")
	)
	(segment
		(start 296.519854 -215.14943)
		(end 296.750232 -215.14943)
		(width 0.14478)
		(layer "In4.Cu")
		(net "M_D_CPU0_SA_DQ<13>")
	)
	(segment
		(start 324.897496 -232.239312)
		(end 325.964296 -233.306112)
		(width 0.0889)
		(layer "In4.Cu")
		(net "M_D_CPU0_SA_DQ<13>")
	)
	(segment
		(start 285.82493 -214.981282)
		(end 285.987998 -215.14435)
		(width 0.14478)
		(layer "In4.Cu")
		(net "M_D_CPU0_SA_DQ<13>")
	)
	(segment
		(start 286.218376 -215.14435)
		(end 286.381444 -214.981282)
		(width 0.14478)
		(layer "In4.Cu")
		(net "M_D_CPU0_SA_DQ<13>")
	)
	(segment
		(start 287.101026 -215.14435)
		(end 287.331404 -215.14435)
		(width 0.14478)
		(layer "In4.Cu")
		(net "M_D_CPU0_SA_DQ<13>")
	)
	(segment
		(start 306.867306 -214.372952)
		(end 307.02885 -214.534496)
		(width 0.14478)
		(layer "In4.Cu")
		(net "M_D_CPU0_SA_DQ<13>")
	)
	(segment
		(start 298.196762 -213.910164)
		(end 298.493688 -213.910164)
		(width 0.14478)
		(layer "In4.Cu")
		(net "M_D_CPU0_SA_DQ<13>")
	)
	(segment
		(start 288.717228 -214.986362)
		(end 288.880296 -215.14943)
		(width 0.14478)
		(layer "In4.Cu")
		(net "M_D_CPU0_SA_DQ<13>")
	)
	(segment
		(start 289.110674 -215.14943)
		(end 289.273742 -214.986362)
		(width 0.14478)
		(layer "In4.Cu")
		(net "M_D_CPU0_SA_DQ<13>")
	)
	(segment
		(start 303.178464 -214.986362)
		(end 303.178464 -214.923116)
		(width 0.14478)
		(layer "In4.Cu")
		(net "M_D_CPU0_SA_DQ<13>")
	)
	(segment
		(start 318.143128 -226.57562)
		(end 323.342762 -231.775254)
		(width 0.14478)
		(layer "In4.Cu")
		(net "M_D_CPU0_SA_DQ<13>")
	)
	(segment
		(start 302.458882 -214.760048)
		(end 302.62195 -214.923116)
		(width 0.14478)
		(layer "In4.Cu")
		(net "M_D_CPU0_SA_DQ<13>")
	)
	(segment
		(start 297.346878 -214.760048)
		(end 298.196762 -213.910164)
		(width 0.14478)
		(layer "In4.Cu")
		(net "M_D_CPU0_SA_DQ<13>")
	)
	(segment
		(start 291.64407 -214.132922)
		(end 291.64407 -214.073232)
		(width 0.14478)
		(layer "In4.Cu")
		(net "M_D_CPU0_SA_DQ<13>")
	)
	(segment
		(start 306.087526 -215.015572)
		(end 306.315872 -215.015572)
		(width 0.14478)
		(layer "In4.Cu")
		(net "M_D_CPU0_SA_DQ<13>")
	)
	(segment
		(start 290.673282 -213.910164)
		(end 290.924488 -213.910164)
		(width 0.14478)
		(layer "In4.Cu")
		(net "M_D_CPU0_SA_DQ<13>")
	)
	(segment
		(start 336.869786 -234.281472)
		(end 336.878168 -234.276646)
		(width 0.0889)
		(layer "In4.Cu")
		(net "M_D_CPU0_SA_DQ<13>")
	)
	(segment
		(start 299.050202 -214.30361)
		(end 299.21327 -214.140542)
		(width 0.14478)
		(layer "In4.Cu")
		(net "M_D_CPU0_SA_DQ<13>")
	)
	(segment
		(start 333.684118 -234.276646)
		(end 333.6925 -234.281472)
		(width 0.0889)
		(layer "In4.Cu")
		(net "M_D_CPU0_SA_DQ<13>")
	)
	(segment
		(start 290.924488 -213.910164)
		(end 291.087556 -214.073232)
		(width 0.14478)
		(layer "In4.Cu")
		(net "M_D_CPU0_SA_DQ<13>")
	)
	(segment
		(start 298.656756 -214.073232)
		(end 298.656756 -214.140542)
		(width 0.14478)
		(layer "In4.Cu")
		(net "M_D_CPU0_SA_DQ<13>")
	)
	(segment
		(start 307.882544 -214.760048)
		(end 318.143128 -225.020632)
		(width 0.14478)
		(layer "In4.Cu")
		(net "M_D_CPU0_SA_DQ<13>")
	)
	(segment
		(start 323.910198 -231.775254)
		(end 324.09638 -231.775254)
		(width 0.0889)
		(layer "In4.Cu")
		(net "M_D_CPU0_SA_DQ<13>")
	)
	(segment
		(start 327.569322 -234.200446)
		(end 327.761346 -234.200446)
		(width 0.0889)
		(layer "In4.Cu")
		(net "M_D_CPU0_SA_DQ<13>")
	)
	(segment
		(start 337.44408 -234.276646)
		(end 337.452462 -234.281472)
		(width 0.0889)
		(layer "In4.Cu")
		(net "M_D_CPU0_SA_DQ<13>")
	)
	(segment
		(start 304.110136 -214.760048)
		(end 304.27168 -214.598504)
		(width 0.14478)
		(layer "In4.Cu")
		(net "M_D_CPU0_SA_DQ<13>")
	)
	(segment
		(start 304.27168 -214.598504)
		(end 304.27168 -214.534496)
		(width 0.14478)
		(layer "In4.Cu")
		(net "M_D_CPU0_SA_DQ<13>")
	)
	(segment
		(start 305.374548 -214.772748)
		(end 305.374548 -214.534496)
		(width 0.14478)
		(layer "In4.Cu")
		(net "M_D_CPU0_SA_DQ<13>")
	)
	(segment
		(start 305.374548 -214.534496)
		(end 305.536092 -214.372952)
		(width 0.14478)
		(layer "In4.Cu")
		(net "M_D_CPU0_SA_DQ<13>")
	)
	(segment
		(start 285.661862 -214.760048)
		(end 285.82493 -214.923116)
		(width 0.14478)
		(layer "In4.Cu")
		(net "M_D_CPU0_SA_DQ<13>")
	)
	(segment
		(start 304.823114 -214.534496)
		(end 304.823114 -214.772748)
		(width 0.14478)
		(layer "In4.Cu")
		(net "M_D_CPU0_SA_DQ<13>")
	)
	(segment
		(start 291.087556 -214.073232)
		(end 291.087556 -214.132922)
		(width 0.14478)
		(layer "In4.Cu")
		(net "M_D_CPU0_SA_DQ<13>")
	)
	(segment
		(start 287.494472 -214.923116)
		(end 287.65754 -214.760048)
		(width 0.14478)
		(layer "In4.Cu")
		(net "M_D_CPU0_SA_DQ<13>")
	)
	(arc
		(start 328.41819 -234.276646)
		(mid 328.701146 -234.200469)
		(end 328.984102 -234.276646)
		(width 0.0889)
		(layer "In4.Cu")
		(net "M_D_CPU0_SA_DQ<13>")
	)
	(arc
		(start 334.99806 -234.276646)
		(mid 335.281016 -234.200469)
		(end 335.563972 -234.276646)
		(width 0.0889)
		(layer "In4.Cu")
		(net "M_D_CPU0_SA_DQ<13>")
	)
	(arc
		(start 334.05826 -234.276646)
		(mid 334.341216 -234.200469)
		(end 334.624172 -234.276646)
		(width 0.0889)
		(layer "In4.Cu")
		(net "M_D_CPU0_SA_DQ<13>")
	)
	(arc
		(start 333.6925 -234.281472)
		(mid 333.876008 -234.326966)
		(end 334.05826 -234.276646)
		(width 0.0889)
		(layer "In4.Cu")
		(net "M_D_CPU0_SA_DQ<13>")
	)
	(arc
		(start 335.563972 -234.276646)
		(mid 335.746223 -234.326996)
		(end 335.929732 -234.281472)
		(width 0.0889)
		(layer "In4.Cu")
		(net "M_D_CPU0_SA_DQ<13>")
	)
	(arc
		(start 332.178152 -234.276646)
		(mid 332.461108 -234.200469)
		(end 332.744064 -234.276646)
		(width 0.0889)
		(layer "In4.Cu")
		(net "M_D_CPU0_SA_DQ<13>")
	)
	(arc
		(start 332.752446 -234.281472)
		(mid 332.935954 -234.326966)
		(end 333.118206 -234.276646)
		(width 0.0889)
		(layer "In4.Cu")
		(net "M_D_CPU0_SA_DQ<13>")
	)
	(arc
		(start 329.358244 -234.276646)
		(mid 329.6412 -234.200469)
		(end 329.924156 -234.276646)
		(width 0.0889)
		(layer "In4.Cu")
		(net "M_D_CPU0_SA_DQ<13>")
	)
	(arc
		(start 335.938114 -234.276646)
		(mid 336.22107 -234.200469)
		(end 336.504026 -234.276646)
		(width 0.0889)
		(layer "In4.Cu")
		(net "M_D_CPU0_SA_DQ<13>")
	)
	(arc
		(start 328.044048 -234.276646)
		(mid 328.226299 -234.326996)
		(end 328.409808 -234.281472)
		(width 0.0889)
		(layer "In4.Cu")
		(net "M_D_CPU0_SA_DQ<13>")
	)
	(arc
		(start 331.80401 -234.276646)
		(mid 331.986261 -234.326996)
		(end 332.16977 -234.281472)
		(width 0.0889)
		(layer "In4.Cu")
		(net "M_D_CPU0_SA_DQ<13>")
	)
	(arc
		(start 334.624172 -234.276646)
		(mid 334.811116 -234.326901)
		(end 334.99806 -234.276646)
		(width 0.0889)
		(layer "In4.Cu")
		(net "M_D_CPU0_SA_DQ<13>")
	)
	(arc
		(start 338.384134 -234.276646)
		(mid 338.571078 -234.326901)
		(end 338.758022 -234.276646)
		(width 0.0889)
		(layer "In4.Cu")
		(net "M_D_CPU0_SA_DQ<13>")
	)
	(arc
		(start 337.818222 -234.276646)
		(mid 338.101178 -234.200469)
		(end 338.384134 -234.276646)
		(width 0.0889)
		(layer "In4.Cu")
		(net "M_D_CPU0_SA_DQ<13>")
	)
	(arc
		(start 338.758022 -234.276646)
		(mid 339.040978 -234.200469)
		(end 339.323934 -234.276646)
		(width 0.0889)
		(layer "In4.Cu")
		(net "M_D_CPU0_SA_DQ<13>")
	)
	(arc
		(start 330.863956 -234.276646)
		(mid 331.046207 -234.326996)
		(end 331.229716 -234.281472)
		(width 0.0889)
		(layer "In4.Cu")
		(net "M_D_CPU0_SA_DQ<13>")
	)
	(arc
		(start 327.761346 -234.200446)
		(mid 327.907736 -234.219857)
		(end 328.044048 -234.276646)
		(width 0.0889)
		(layer "In4.Cu")
		(net "M_D_CPU0_SA_DQ<13>")
	)
	(arc
		(start 330.298044 -234.276646)
		(mid 330.581 -234.200469)
		(end 330.863956 -234.276646)
		(width 0.0889)
		(layer "In4.Cu")
		(net "M_D_CPU0_SA_DQ<13>")
	)
	(arc
		(start 333.118206 -234.276646)
		(mid 333.401162 -234.200469)
		(end 333.684118 -234.276646)
		(width 0.0889)
		(layer "In4.Cu")
		(net "M_D_CPU0_SA_DQ<13>")
	)
	(arc
		(start 336.504026 -234.276646)
		(mid 336.686277 -234.326996)
		(end 336.869786 -234.281472)
		(width 0.0889)
		(layer "In4.Cu")
		(net "M_D_CPU0_SA_DQ<13>")
	)
	(arc
		(start 339.323934 -234.276646)
		(mid 339.506185 -234.326996)
		(end 339.689694 -234.281472)
		(width 0.0889)
		(layer "In4.Cu")
		(net "M_D_CPU0_SA_DQ<13>")
	)
	(arc
		(start 339.698076 -234.276646)
		(mid 339.945672 -234.201468)
		(end 340.200742 -234.244896)
		(width 0.0889)
		(layer "In4.Cu")
		(net "M_D_CPU0_SA_DQ<13>")
	)
	(arc
		(start 329.924156 -234.276646)
		(mid 330.1111 -234.326901)
		(end 330.298044 -234.276646)
		(width 0.0889)
		(layer "In4.Cu")
		(net "M_D_CPU0_SA_DQ<13>")
	)
	(arc
		(start 336.878168 -234.276646)
		(mid 337.161124 -234.200469)
		(end 337.44408 -234.276646)
		(width 0.0889)
		(layer "In4.Cu")
		(net "M_D_CPU0_SA_DQ<13>")
	)
	(arc
		(start 337.452462 -234.281472)
		(mid 337.63597 -234.326966)
		(end 337.818222 -234.276646)
		(width 0.0889)
		(layer "In4.Cu")
		(net "M_D_CPU0_SA_DQ<13>")
	)
	(arc
		(start 328.992484 -234.281472)
		(mid 329.175992 -234.326966)
		(end 329.358244 -234.276646)
		(width 0.0889)
		(layer "In4.Cu")
		(net "M_D_CPU0_SA_DQ<13>")
	)
	(arc
		(start 331.238098 -234.276646)
		(mid 331.521054 -234.200469)
		(end 331.80401 -234.276646)
		(width 0.0889)
		(layer "In4.Cu")
		(net "M_D_CPU0_SA_DQ<13>")
	)
	(segment
		(start 339.508084 -233.409998)
		(end 339.040978 -233.14406)
		(width 0.10668)
		(layer "F.Cu")
		(net "M_D_CPU0_SA_DQ<12>")
	)
	(segment
		(start 284.736032 -212.635084)
		(end 285.160974 -213.060026)
		(width 0.14478)
		(layer "In4.Cu")
		(net "M_D_CPU0_SA_DQ<12>")
	)
	(segment
		(start 323.859398 -230.871014)
		(end 324.17258 -230.871014)
		(width 0.0889)
		(layer "In4.Cu")
		(net "M_D_CPU0_SA_DQ<12>")
	)
	(segment
		(start 303.753774 -212.934296)
		(end 303.753774 -213.294468)
		(width 0.14478)
		(layer "In4.Cu")
		(net "M_D_CPU0_SA_DQ<12>")
	)
	(segment
		(start 304.466752 -213.069678)
		(end 304.695098 -213.069678)
		(width 0.14478)
		(layer "In4.Cu")
		(net "M_D_CPU0_SA_DQ<12>")
	)
	(segment
		(start 327.497948 -233.407458)
		(end 327.497948 -233.407204)
		(width 0.0889)
		(layer "In4.Cu")
		(net "M_D_CPU0_SA_DQ<12>")
	)
	(segment
		(start 325.469758 -232.000298)
		(end 326.201532 -232.732072)
		(width 0.0889)
		(layer "In4.Cu")
		(net "M_D_CPU0_SA_DQ<12>")
	)
	(segment
		(start 331.33411 -233.46664)
		(end 331.342492 -233.471466)
		(width 0.0889)
		(layer "In4.Cu")
		(net "M_D_CPU0_SA_DQ<12>")
	)
	(segment
		(start 289.17773 -213.45271)
		(end 289.340798 -213.289642)
		(width 0.14478)
		(layer "In4.Cu")
		(net "M_D_CPU0_SA_DQ<12>")
	)
	(segment
		(start 304.143664 -213.456012)
		(end 304.305208 -213.294468)
		(width 0.14478)
		(layer "In4.Cu")
		(net "M_D_CPU0_SA_DQ<12>")
	)
	(segment
		(start 334.519778 -233.471466)
		(end 334.52816 -233.46664)
		(width 0.0889)
		(layer "In4.Cu")
		(net "M_D_CPU0_SA_DQ<12>")
	)
	(segment
		(start 299.334428 -212.219794)
		(end 301.060358 -212.219794)
		(width 0.14478)
		(layer "In4.Cu")
		(net "M_D_CPU0_SA_DQ<12>")
	)
	(segment
		(start 291.010848 -212.441028)
		(end 291.172392 -212.602572)
		(width 0.14478)
		(layer "In4.Cu")
		(net "M_D_CPU0_SA_DQ<12>")
	)
	(segment
		(start 298.62145 -212.448648)
		(end 298.782994 -212.610192)
		(width 0.14478)
		(layer "In4.Cu")
		(net "M_D_CPU0_SA_DQ<12>")
	)
	(segment
		(start 324.979538 -231.070912)
		(end 325.469758 -231.561132)
		(width 0.0889)
		(layer "In4.Cu")
		(net "M_D_CPU0_SA_DQ<12>")
	)
	(segment
		(start 288.947352 -213.45271)
		(end 289.17773 -213.45271)
		(width 0.14478)
		(layer "In4.Cu")
		(net "M_D_CPU0_SA_DQ<12>")
	)
	(segment
		(start 288.784284 -213.289642)
		(end 288.947352 -213.45271)
		(width 0.14478)
		(layer "In4.Cu")
		(net "M_D_CPU0_SA_DQ<12>")
	)
	(segment
		(start 298.62145 -212.381338)
		(end 298.62145 -212.448648)
		(width 0.14478)
		(layer "In4.Cu")
		(net "M_D_CPU0_SA_DQ<12>")
	)
	(segment
		(start 288.630868 -213.069678)
		(end 288.784284 -213.223094)
		(width 0.14478)
		(layer "In4.Cu")
		(net "M_D_CPU0_SA_DQ<12>")
	)
	(segment
		(start 329.819762 -233.471466)
		(end 329.828144 -233.46664)
		(width 0.0889)
		(layer "In4.Cu")
		(net "M_D_CPU0_SA_DQ<12>")
	)
	(segment
		(start 305.95951 -213.294468)
		(end 306.121054 -213.456012)
		(width 0.14478)
		(layer "In4.Cu")
		(net "M_D_CPU0_SA_DQ<12>")
	)
	(segment
		(start 290.849304 -212.219794)
		(end 291.010848 -212.381338)
		(width 0.14478)
		(layer "In4.Cu")
		(net "M_D_CPU0_SA_DQ<12>")
	)
	(segment
		(start 287.377886 -213.45017)
		(end 287.540954 -213.287102)
		(width 0.14478)
		(layer "In4.Cu")
		(net "M_D_CPU0_SA_DQ<12>")
	)
	(segment
		(start 319.813178 -225.339656)
		(end 319.813178 -225.568002)
		(width 0.14478)
		(layer "In4.Cu")
		(net "M_D_CPU0_SA_DQ<12>")
	)
	(segment
		(start 305.56962 -213.069678)
		(end 305.797966 -213.069678)
		(width 0.14478)
		(layer "In4.Cu")
		(net "M_D_CPU0_SA_DQ<12>")
	)
	(segment
		(start 304.856642 -213.294468)
		(end 305.018186 -213.456012)
		(width 0.14478)
		(layer "In4.Cu")
		(net "M_D_CPU0_SA_DQ<12>")
	)
	(segment
		(start 306.672488 -213.069678)
		(end 307.540406 -213.069678)
		(width 0.14478)
		(layer "In4.Cu")
		(net "M_D_CPU0_SA_DQ<12>")
	)
	(segment
		(start 288.784284 -213.223094)
		(end 288.784284 -213.289642)
		(width 0.14478)
		(layer "In4.Cu")
		(net "M_D_CPU0_SA_DQ<12>")
	)
	(segment
		(start 323.750178 -230.871014)
		(end 323.859398 -230.871014)
		(width 0.14478)
		(layer "In4.Cu")
		(net "M_D_CPU0_SA_DQ<12>")
	)
	(segment
		(start 285.928562 -212.27161)
		(end 286.09163 -212.434678)
		(width 0.14478)
		(layer "In4.Cu")
		(net "M_D_CPU0_SA_DQ<12>")
	)
	(segment
		(start 286.09163 -212.896958)
		(end 286.26435 -213.069678)
		(width 0.14478)
		(layer "In4.Cu")
		(net "M_D_CPU0_SA_DQ<12>")
	)
	(segment
		(start 287.540954 -213.223094)
		(end 287.69437 -213.069678)
		(width 0.14478)
		(layer "In4.Cu")
		(net "M_D_CPU0_SA_DQ<12>")
	)
	(segment
		(start 291.010848 -212.381338)
		(end 291.010848 -212.441028)
		(width 0.14478)
		(layer "In4.Cu")
		(net "M_D_CPU0_SA_DQ<12>")
	)
	(segment
		(start 306.121054 -213.456012)
		(end 306.3494 -213.456012)
		(width 0.14478)
		(layer "In4.Cu")
		(net "M_D_CPU0_SA_DQ<12>")
	)
	(segment
		(start 289.503866 -213.060026)
		(end 289.823398 -213.060026)
		(width 0.14478)
		(layer "In4.Cu")
		(net "M_D_CPU0_SA_DQ<12>")
	)
	(segment
		(start 291.172392 -212.602572)
		(end 291.400738 -212.602572)
		(width 0.14478)
		(layer "In4.Cu")
		(net "M_D_CPU0_SA_DQ<12>")
	)
	(segment
		(start 296.85234 -213.286848)
		(end 296.85234 -213.231222)
		(width 0.14478)
		(layer "In4.Cu")
		(net "M_D_CPU0_SA_DQ<12>")
	)
	(segment
		(start 304.305208 -213.294468)
		(end 304.305208 -213.231222)
		(width 0.14478)
		(layer "In4.Cu")
		(net "M_D_CPU0_SA_DQ<12>")
	)
	(segment
		(start 303.363884 -212.772752)
		(end 303.59223 -212.772752)
		(width 0.14478)
		(layer "In4.Cu")
		(net "M_D_CPU0_SA_DQ<12>")
	)
	(segment
		(start 285.535116 -212.896958)
		(end 285.535116 -212.434678)
		(width 0.14478)
		(layer "In4.Cu")
		(net "M_D_CPU0_SA_DQ<12>")
	)
	(segment
		(start 319.332102 -225.729546)
		(end 319.170558 -225.89109)
		(width 0.14478)
		(layer "In4.Cu")
		(net "M_D_CPU0_SA_DQ<12>")
	)
	(segment
		(start 319.332102 -225.178112)
		(end 319.651634 -225.178112)
		(width 0.14478)
		(layer "In4.Cu")
		(net "M_D_CPU0_SA_DQ<12>")
	)
	(segment
		(start 304.695098 -213.069678)
		(end 304.856642 -213.231222)
		(width 0.14478)
		(layer "In4.Cu")
		(net "M_D_CPU0_SA_DQ<12>")
	)
	(segment
		(start 306.3494 -213.456012)
		(end 306.510944 -213.294468)
		(width 0.14478)
		(layer "In4.Cu")
		(net "M_D_CPU0_SA_DQ<12>")
	)
	(segment
		(start 285.535116 -212.434678)
		(end 285.698184 -212.27161)
		(width 0.14478)
		(layer "In4.Cu")
		(net "M_D_CPU0_SA_DQ<12>")
	)
	(segment
		(start 286.831024 -213.069678)
		(end 286.98444 -213.223094)
		(width 0.14478)
		(layer "In4.Cu")
		(net "M_D_CPU0_SA_DQ<12>")
	)
	(segment
		(start 302.650906 -213.231222)
		(end 302.650906 -213.294468)
		(width 0.14478)
		(layer "In4.Cu")
		(net "M_D_CPU0_SA_DQ<12>")
	)
	(segment
		(start 291.562282 -212.381338)
		(end 291.723826 -212.219794)
		(width 0.14478)
		(layer "In4.Cu")
		(net "M_D_CPU0_SA_DQ<12>")
	)
	(segment
		(start 286.09163 -212.434678)
		(end 286.09163 -212.896958)
		(width 0.14478)
		(layer "In4.Cu")
		(net "M_D_CPU0_SA_DQ<12>")
	)
	(segment
		(start 303.915318 -213.456012)
		(end 304.143664 -213.456012)
		(width 0.14478)
		(layer "In4.Cu")
		(net "M_D_CPU0_SA_DQ<12>")
	)
	(segment
		(start 289.340798 -213.223094)
		(end 289.503866 -213.060026)
		(width 0.14478)
		(layer "In4.Cu")
		(net "M_D_CPU0_SA_DQ<12>")
	)
	(segment
		(start 335.094072 -233.46664)
		(end 335.102454 -233.471466)
		(width 0.0889)
		(layer "In4.Cu")
		(net "M_D_CPU0_SA_DQ<12>")
	)
	(segment
		(start 324.372478 -231.070912)
		(end 324.979538 -231.070912)
		(width 0.0889)
		(layer "In4.Cu")
		(net "M_D_CPU0_SA_DQ<12>")
	)
	(segment
		(start 327.57491 -233.466386)
		(end 327.594976 -233.477816)
		(width 0.0889)
		(layer "In4.Cu")
		(net "M_D_CPU0_SA_DQ<12>")
	)
	(segment
		(start 305.408076 -213.294468)
		(end 305.408076 -213.231222)
		(width 0.14478)
		(layer "In4.Cu")
		(net "M_D_CPU0_SA_DQ<12>")
	)
	(segment
		(start 296.300906 -213.286848)
		(end 296.46245 -213.448392)
		(width 0.14478)
		(layer "In4.Cu")
		(net "M_D_CPU0_SA_DQ<12>")
	)
	(segment
		(start 301.060358 -212.219794)
		(end 301.910242 -213.069678)
		(width 0.14478)
		(layer "In4.Cu")
		(net "M_D_CPU0_SA_DQ<12>")
	)
	(segment
		(start 296.300906 -213.231222)
		(end 296.300906 -213.286848)
		(width 0.14478)
		(layer "In4.Cu")
		(net "M_D_CPU0_SA_DQ<12>")
	)
	(segment
		(start 305.018186 -213.456012)
		(end 305.246532 -213.456012)
		(width 0.14478)
		(layer "In4.Cu")
		(net "M_D_CPU0_SA_DQ<12>")
	)
	(segment
		(start 338.27974 -233.471466)
		(end 338.288122 -233.46664)
		(width 0.0889)
		(layer "In4.Cu")
		(net "M_D_CPU0_SA_DQ<12>")
	)
	(segment
		(start 336.034126 -233.46664)
		(end 336.042508 -233.471466)
		(width 0.0889)
		(layer "In4.Cu")
		(net "M_D_CPU0_SA_DQ<12>")
	)
	(segment
		(start 289.340798 -213.289642)
		(end 289.340798 -213.223094)
		(width 0.14478)
		(layer "In4.Cu")
		(net "M_D_CPU0_SA_DQ<12>")
	)
	(segment
		(start 326.201532 -232.732072)
		(end 326.822562 -232.732072)
		(width 0.0889)
		(layer "In4.Cu")
		(net "M_D_CPU0_SA_DQ<12>")
	)
	(segment
		(start 296.85234 -213.231222)
		(end 297.013884 -213.069678)
		(width 0.14478)
		(layer "In4.Cu")
		(net "M_D_CPU0_SA_DQ<12>")
	)
	(segment
		(start 333.579724 -233.471466)
		(end 333.588106 -233.46664)
		(width 0.0889)
		(layer "In4.Cu")
		(net "M_D_CPU0_SA_DQ<12>")
	)
	(segment
		(start 291.562282 -212.441028)
		(end 291.562282 -212.381338)
		(width 0.14478)
		(layer "In4.Cu")
		(net "M_D_CPU0_SA_DQ<12>")
	)
	(segment
		(start 285.160974 -213.060026)
		(end 285.372048 -213.060026)
		(width 0.14478)
		(layer "In4.Cu")
		(net "M_D_CPU0_SA_DQ<12>")
	)
	(segment
		(start 319.170558 -224.69983)
		(end 319.170558 -225.016568)
		(width 0.14478)
		(layer "In4.Cu")
		(net "M_D_CPU0_SA_DQ<12>")
	)
	(segment
		(start 303.040796 -213.456012)
		(end 303.20234 -213.294468)
		(width 0.14478)
		(layer "In4.Cu")
		(net "M_D_CPU0_SA_DQ<12>")
	)
	(segment
		(start 297.337226 -213.069678)
		(end 298.18711 -212.219794)
		(width 0.14478)
		(layer "In4.Cu")
		(net "M_D_CPU0_SA_DQ<12>")
	)
	(segment
		(start 291.400738 -212.602572)
		(end 291.562282 -212.441028)
		(width 0.14478)
		(layer "In4.Cu")
		(net "M_D_CPU0_SA_DQ<12>")
	)
	(segment
		(start 286.98444 -213.287102)
		(end 287.147508 -213.45017)
		(width 0.14478)
		(layer "In4.Cu")
		(net "M_D_CPU0_SA_DQ<12>")
	)
	(segment
		(start 319.651634 -225.729546)
		(end 319.332102 -225.729546)
		(width 0.14478)
		(layer "In4.Cu")
		(net "M_D_CPU0_SA_DQ<12>")
	)
	(segment
		(start 304.856642 -213.231222)
		(end 304.856642 -213.294468)
		(width 0.14478)
		(layer "In4.Cu")
		(net "M_D_CPU0_SA_DQ<12>")
	)
	(segment
		(start 319.170558 -225.89109)
		(end 319.170558 -226.291394)
		(width 0.14478)
		(layer "In4.Cu")
		(net "M_D_CPU0_SA_DQ<12>")
	)
	(segment
		(start 285.698184 -212.27161)
		(end 285.928562 -212.27161)
		(width 0.14478)
		(layer "In4.Cu")
		(net "M_D_CPU0_SA_DQ<12>")
	)
	(segment
		(start 302.489362 -213.069678)
		(end 302.650906 -213.231222)
		(width 0.14478)
		(layer "In4.Cu")
		(net "M_D_CPU0_SA_DQ<12>")
	)
	(segment
		(start 299.172884 -212.381338)
		(end 299.334428 -212.219794)
		(width 0.14478)
		(layer "In4.Cu")
		(net "M_D_CPU0_SA_DQ<12>")
	)
	(segment
		(start 286.98444 -213.223094)
		(end 286.98444 -213.287102)
		(width 0.14478)
		(layer "In4.Cu")
		(net "M_D_CPU0_SA_DQ<12>")
	)
	(segment
		(start 324.17258 -230.871014)
		(end 324.372478 -231.070912)
		(width 0.0889)
		(layer "In4.Cu")
		(net "M_D_CPU0_SA_DQ<12>")
	)
	(segment
		(start 326.822562 -232.732072)
		(end 327.497948 -233.407458)
		(width 0.0889)
		(layer "In4.Cu")
		(net "M_D_CPU0_SA_DQ<12>")
	)
	(segment
		(start 305.95951 -213.231222)
		(end 305.95951 -213.294468)
		(width 0.14478)
		(layer "In4.Cu")
		(net "M_D_CPU0_SA_DQ<12>")
	)
	(segment
		(start 289.823398 -213.060026)
		(end 290.66363 -212.219794)
		(width 0.14478)
		(layer "In4.Cu")
		(net "M_D_CPU0_SA_DQ<12>")
	)
	(segment
		(start 302.650906 -213.294468)
		(end 302.81245 -213.456012)
		(width 0.14478)
		(layer "In4.Cu")
		(net "M_D_CPU0_SA_DQ<12>")
	)
	(segment
		(start 306.510944 -213.294468)
		(end 306.510944 -213.231222)
		(width 0.14478)
		(layer "In4.Cu")
		(net "M_D_CPU0_SA_DQ<12>")
	)
	(segment
		(start 305.246532 -213.456012)
		(end 305.408076 -213.294468)
		(width 0.14478)
		(layer "In4.Cu")
		(net "M_D_CPU0_SA_DQ<12>")
	)
	(segment
		(start 303.753774 -213.294468)
		(end 303.915318 -213.456012)
		(width 0.14478)
		(layer "In4.Cu")
		(net "M_D_CPU0_SA_DQ<12>")
	)
	(segment
		(start 319.170558 -225.016568)
		(end 319.332102 -225.178112)
		(width 0.14478)
		(layer "In4.Cu")
		(net "M_D_CPU0_SA_DQ<12>")
	)
	(segment
		(start 325.469758 -231.561132)
		(end 325.469758 -232.000298)
		(width 0.0889)
		(layer "In4.Cu")
		(net "M_D_CPU0_SA_DQ<12>")
	)
	(segment
		(start 285.372048 -213.060026)
		(end 285.535116 -212.896958)
		(width 0.14478)
		(layer "In4.Cu")
		(net "M_D_CPU0_SA_DQ<12>")
	)
	(segment
		(start 303.20234 -212.934296)
		(end 303.363884 -212.772752)
		(width 0.14478)
		(layer "In4.Cu")
		(net "M_D_CPU0_SA_DQ<12>")
	)
	(segment
		(start 302.81245 -213.456012)
		(end 303.040796 -213.456012)
		(width 0.14478)
		(layer "In4.Cu")
		(net "M_D_CPU0_SA_DQ<12>")
	)
	(segment
		(start 294.358314 -213.069678)
		(end 296.139362 -213.069678)
		(width 0.14478)
		(layer "In4.Cu")
		(net "M_D_CPU0_SA_DQ<12>")
	)
	(segment
		(start 298.18711 -212.219794)
		(end 298.459906 -212.219794)
		(width 0.14478)
		(layer "In4.Cu")
		(net "M_D_CPU0_SA_DQ<12>")
	)
	(segment
		(start 305.797966 -213.069678)
		(end 305.95951 -213.231222)
		(width 0.14478)
		(layer "In4.Cu")
		(net "M_D_CPU0_SA_DQ<12>")
	)
	(segment
		(start 338.887054 -233.40949)
		(end 339.040978 -233.14406)
		(width 0.0889)
		(layer "In4.Cu")
		(net "M_D_CPU0_SA_DQ<12>")
	)
	(segment
		(start 296.690796 -213.448392)
		(end 296.85234 -213.286848)
		(width 0.14478)
		(layer "In4.Cu")
		(net "M_D_CPU0_SA_DQ<12>")
	)
	(segment
		(start 301.910242 -213.069678)
		(end 302.489362 -213.069678)
		(width 0.14478)
		(layer "In4.Cu")
		(net "M_D_CPU0_SA_DQ<12>")
	)
	(segment
		(start 287.540954 -213.287102)
		(end 287.540954 -213.223094)
		(width 0.14478)
		(layer "In4.Cu")
		(net "M_D_CPU0_SA_DQ<12>")
	)
	(segment
		(start 286.26435 -213.069678)
		(end 286.831024 -213.069678)
		(width 0.14478)
		(layer "In4.Cu")
		(net "M_D_CPU0_SA_DQ<12>")
	)
	(segment
		(start 304.305208 -213.231222)
		(end 304.466752 -213.069678)
		(width 0.14478)
		(layer "In4.Cu")
		(net "M_D_CPU0_SA_DQ<12>")
	)
	(segment
		(start 303.59223 -212.772752)
		(end 303.753774 -212.934296)
		(width 0.14478)
		(layer "In4.Cu")
		(net "M_D_CPU0_SA_DQ<12>")
	)
	(segment
		(start 298.459906 -212.219794)
		(end 298.62145 -212.381338)
		(width 0.14478)
		(layer "In4.Cu")
		(net "M_D_CPU0_SA_DQ<12>")
	)
	(segment
		(start 297.013884 -213.069678)
		(end 297.337226 -213.069678)
		(width 0.14478)
		(layer "In4.Cu")
		(net "M_D_CPU0_SA_DQ<12>")
	)
	(segment
		(start 299.172884 -212.448648)
		(end 299.172884 -212.381338)
		(width 0.14478)
		(layer "In4.Cu")
		(net "M_D_CPU0_SA_DQ<12>")
	)
	(segment
		(start 293.50843 -212.219794)
		(end 294.358314 -213.069678)
		(width 0.14478)
		(layer "In4.Cu")
		(net "M_D_CPU0_SA_DQ<12>")
	)
	(segment
		(start 291.723826 -212.219794)
		(end 293.50843 -212.219794)
		(width 0.14478)
		(layer "In4.Cu")
		(net "M_D_CPU0_SA_DQ<12>")
	)
	(segment
		(start 287.147508 -213.45017)
		(end 287.377886 -213.45017)
		(width 0.14478)
		(layer "In4.Cu")
		(net "M_D_CPU0_SA_DQ<12>")
	)
	(segment
		(start 319.813178 -225.568002)
		(end 319.651634 -225.729546)
		(width 0.14478)
		(layer "In4.Cu")
		(net "M_D_CPU0_SA_DQ<12>")
	)
	(segment
		(start 305.408076 -213.231222)
		(end 305.56962 -213.069678)
		(width 0.14478)
		(layer "In4.Cu")
		(net "M_D_CPU0_SA_DQ<12>")
	)
	(segment
		(start 296.139362 -213.069678)
		(end 296.300906 -213.231222)
		(width 0.14478)
		(layer "In4.Cu")
		(net "M_D_CPU0_SA_DQ<12>")
	)
	(segment
		(start 290.66363 -212.219794)
		(end 290.849304 -212.219794)
		(width 0.14478)
		(layer "In4.Cu")
		(net "M_D_CPU0_SA_DQ<12>")
	)
	(segment
		(start 303.20234 -213.294468)
		(end 303.20234 -212.934296)
		(width 0.14478)
		(layer "In4.Cu")
		(net "M_D_CPU0_SA_DQ<12>")
	)
	(segment
		(start 298.782994 -212.610192)
		(end 299.01134 -212.610192)
		(width 0.14478)
		(layer "In4.Cu")
		(net "M_D_CPU0_SA_DQ<12>")
	)
	(segment
		(start 287.69437 -213.069678)
		(end 288.630868 -213.069678)
		(width 0.14478)
		(layer "In4.Cu")
		(net "M_D_CPU0_SA_DQ<12>")
	)
	(segment
		(start 338.791042 -233.43489)
		(end 338.887054 -233.40949)
		(width 0.0889)
		(layer "In4.Cu")
		(net "M_D_CPU0_SA_DQ<12>")
	)
	(segment
		(start 319.170558 -226.291394)
		(end 323.750178 -230.871014)
		(width 0.14478)
		(layer "In4.Cu")
		(net "M_D_CPU0_SA_DQ<12>")
	)
	(segment
		(start 330.394056 -233.46664)
		(end 330.402438 -233.471466)
		(width 0.0889)
		(layer "In4.Cu")
		(net "M_D_CPU0_SA_DQ<12>")
	)
	(segment
		(start 296.46245 -213.448392)
		(end 296.690796 -213.448392)
		(width 0.14478)
		(layer "In4.Cu")
		(net "M_D_CPU0_SA_DQ<12>")
	)
	(segment
		(start 307.540406 -213.069678)
		(end 319.170558 -224.69983)
		(width 0.14478)
		(layer "In4.Cu")
		(net "M_D_CPU0_SA_DQ<12>")
	)
	(segment
		(start 306.510944 -213.231222)
		(end 306.672488 -213.069678)
		(width 0.14478)
		(layer "In4.Cu")
		(net "M_D_CPU0_SA_DQ<12>")
	)
	(segment
		(start 299.01134 -212.610192)
		(end 299.172884 -212.448648)
		(width 0.14478)
		(layer "In4.Cu")
		(net "M_D_CPU0_SA_DQ<12>")
	)
	(segment
		(start 319.651634 -225.178112)
		(end 319.813178 -225.339656)
		(width 0.14478)
		(layer "In4.Cu")
		(net "M_D_CPU0_SA_DQ<12>")
	)
	(arc
		(start 334.154018 -233.46664)
		(mid 334.336269 -233.51699)
		(end 334.519778 -233.471466)
		(width 0.0889)
		(layer "In4.Cu")
		(net "M_D_CPU0_SA_DQ<12>")
	)
	(arc
		(start 332.648052 -233.46664)
		(mid 332.931008 -233.390463)
		(end 333.213964 -233.46664)
		(width 0.0889)
		(layer "In4.Cu")
		(net "M_D_CPU0_SA_DQ<12>")
	)
	(arc
		(start 332.274164 -233.46664)
		(mid 332.461108 -233.516895)
		(end 332.648052 -233.46664)
		(width 0.0889)
		(layer "In4.Cu")
		(net "M_D_CPU0_SA_DQ<12>")
	)
	(arc
		(start 334.52816 -233.46664)
		(mid 334.811116 -233.390463)
		(end 335.094072 -233.46664)
		(width 0.0889)
		(layer "In4.Cu")
		(net "M_D_CPU0_SA_DQ<12>")
	)
	(arc
		(start 337.91398 -233.46664)
		(mid 338.096231 -233.51699)
		(end 338.27974 -233.471466)
		(width 0.0889)
		(layer "In4.Cu")
		(net "M_D_CPU0_SA_DQ<12>")
	)
	(arc
		(start 327.594976 -233.477816)
		(mid 327.773054 -233.5168)
		(end 327.94829 -233.46664)
		(width 0.0889)
		(layer "In4.Cu")
		(net "M_D_CPU0_SA_DQ<12>")
	)
	(arc
		(start 335.468214 -233.46664)
		(mid 335.75117 -233.390463)
		(end 336.034126 -233.46664)
		(width 0.0889)
		(layer "In4.Cu")
		(net "M_D_CPU0_SA_DQ<12>")
	)
	(arc
		(start 328.88809 -233.46664)
		(mid 329.171046 -233.390463)
		(end 329.454002 -233.46664)
		(width 0.0889)
		(layer "In4.Cu")
		(net "M_D_CPU0_SA_DQ<12>")
	)
	(arc
		(start 330.402438 -233.471466)
		(mid 330.585946 -233.51696)
		(end 330.768198 -233.46664)
		(width 0.0889)
		(layer "In4.Cu")
		(net "M_D_CPU0_SA_DQ<12>")
	)
	(arc
		(start 329.828144 -233.46664)
		(mid 330.1111 -233.390463)
		(end 330.394056 -233.46664)
		(width 0.0889)
		(layer "In4.Cu")
		(net "M_D_CPU0_SA_DQ<12>")
	)
	(arc
		(start 328.514202 -233.46664)
		(mid 328.701146 -233.516895)
		(end 328.88809 -233.46664)
		(width 0.0889)
		(layer "In4.Cu")
		(net "M_D_CPU0_SA_DQ<12>")
	)
	(arc
		(start 336.408268 -233.46664)
		(mid 336.691224 -233.390463)
		(end 336.97418 -233.46664)
		(width 0.0889)
		(layer "In4.Cu")
		(net "M_D_CPU0_SA_DQ<12>")
	)
	(arc
		(start 327.94829 -233.46664)
		(mid 328.231246 -233.390463)
		(end 328.514202 -233.46664)
		(width 0.0889)
		(layer "In4.Cu")
		(net "M_D_CPU0_SA_DQ<12>")
	)
	(arc
		(start 331.708252 -233.46664)
		(mid 331.991208 -233.390463)
		(end 332.274164 -233.46664)
		(width 0.0889)
		(layer "In4.Cu")
		(net "M_D_CPU0_SA_DQ<12>")
	)
	(arc
		(start 329.454002 -233.46664)
		(mid 329.636253 -233.51699)
		(end 329.819762 -233.471466)
		(width 0.0889)
		(layer "In4.Cu")
		(net "M_D_CPU0_SA_DQ<12>")
	)
	(arc
		(start 330.768198 -233.46664)
		(mid 331.051154 -233.390463)
		(end 331.33411 -233.46664)
		(width 0.0889)
		(layer "In4.Cu")
		(net "M_D_CPU0_SA_DQ<12>")
	)
	(arc
		(start 333.213964 -233.46664)
		(mid 333.396215 -233.51699)
		(end 333.579724 -233.471466)
		(width 0.0889)
		(layer "In4.Cu")
		(net "M_D_CPU0_SA_DQ<12>")
	)
	(arc
		(start 335.102454 -233.471466)
		(mid 335.285962 -233.51696)
		(end 335.468214 -233.46664)
		(width 0.0889)
		(layer "In4.Cu")
		(net "M_D_CPU0_SA_DQ<12>")
	)
	(arc
		(start 338.288122 -233.46664)
		(mid 338.535835 -233.39142)
		(end 338.791042 -233.43489)
		(width 0.0889)
		(layer "In4.Cu")
		(net "M_D_CPU0_SA_DQ<12>")
	)
	(arc
		(start 337.348068 -233.46664)
		(mid 337.631024 -233.390463)
		(end 337.91398 -233.46664)
		(width 0.0889)
		(layer "In4.Cu")
		(net "M_D_CPU0_SA_DQ<12>")
	)
	(arc
		(start 333.588106 -233.46664)
		(mid 333.871062 -233.390463)
		(end 334.154018 -233.46664)
		(width 0.0889)
		(layer "In4.Cu")
		(net "M_D_CPU0_SA_DQ<12>")
	)
	(arc
		(start 336.97418 -233.46664)
		(mid 337.161124 -233.516895)
		(end 337.348068 -233.46664)
		(width 0.0889)
		(layer "In4.Cu")
		(net "M_D_CPU0_SA_DQ<12>")
	)
	(arc
		(start 336.042508 -233.471466)
		(mid 336.226016 -233.51696)
		(end 336.408268 -233.46664)
		(width 0.0889)
		(layer "In4.Cu")
		(net "M_D_CPU0_SA_DQ<12>")
	)
	(arc
		(start 327.497948 -233.407204)
		(mid 327.53449 -233.439316)
		(end 327.57491 -233.466386)
		(width 0.0889)
		(layer "In4.Cu")
		(net "M_D_CPU0_SA_DQ<12>")
	)
	(arc
		(start 331.342492 -233.471466)
		(mid 331.526 -233.51696)
		(end 331.708252 -233.46664)
		(width 0.0889)
		(layer "In4.Cu")
		(net "M_D_CPU0_SA_DQ<12>")
	)
	(segment
		(start 340.447884 -231.789986)
		(end 339.981032 -231.524048)
		(width 0.10668)
		(layer "F.Cu")
		(net "M_D_CPU0_SA_DQ<11>")
	)
	(segment
		(start 334.519778 -231.196896)
		(end 334.52816 -231.201722)
		(width 0.0889)
		(layer "In4.Cu")
		(net "M_D_CPU0_SA_DQ<11>")
	)
	(segment
		(start 298.172124 -208.800446)
		(end 301.18685 -208.800446)
		(width 0.14478)
		(layer "In4.Cu")
		(net "M_D_CPU0_SA_DQ<11>")
	)
	(segment
		(start 323.992494 -227.67417)
		(end 324.140576 -227.822252)
		(width 0.0889)
		(layer "In4.Cu")
		(net "M_D_CPU0_SA_DQ<11>")
	)
	(segment
		(start 302.04664 -209.660236)
		(end 304.71999 -209.660236)
		(width 0.14478)
		(layer "In4.Cu")
		(net "M_D_CPU0_SA_DQ<11>")
	)
	(segment
		(start 304.71999 -209.660236)
		(end 307.638196 -210.240626)
		(width 0.14478)
		(layer "In4.Cu")
		(net "M_D_CPU0_SA_DQ<11>")
	)
	(segment
		(start 307.638196 -210.240626)
		(end 308.268116 -210.501484)
		(width 0.14478)
		(layer "In4.Cu")
		(net "M_D_CPU0_SA_DQ<11>")
	)
	(segment
		(start 308.268116 -210.501484)
		(end 311.217818 -212.472524)
		(width 0.14478)
		(layer "In4.Cu")
		(net "M_D_CPU0_SA_DQ<11>")
	)
	(segment
		(start 327.909174 -231.178862)
		(end 327.94829 -231.201722)
		(width 0.0889)
		(layer "In4.Cu")
		(net "M_D_CPU0_SA_DQ<11>")
	)
	(segment
		(start 333.579724 -231.196896)
		(end 333.588106 -231.201722)
		(width 0.0889)
		(layer "In4.Cu")
		(net "M_D_CPU0_SA_DQ<11>")
	)
	(segment
		(start 325.058278 -227.822252)
		(end 325.700898 -228.464872)
		(width 0.0889)
		(layer "In4.Cu")
		(net "M_D_CPU0_SA_DQ<11>")
	)
	(segment
		(start 326.686418 -229.793292)
		(end 327.14565 -230.252524)
		(width 0.0889)
		(layer "In4.Cu")
		(net "M_D_CPU0_SA_DQ<11>")
	)
	(segment
		(start 331.33411 -231.201722)
		(end 331.342492 -231.196896)
		(width 0.0889)
		(layer "In4.Cu")
		(net "M_D_CPU0_SA_DQ<11>")
	)
	(segment
		(start 280.635964 -209.23504)
		(end 281.051254 -209.65033)
		(width 0.14478)
		(layer "In4.Cu")
		(net "M_D_CPU0_SA_DQ<11>")
	)
	(segment
		(start 290.68395 -208.800446)
		(end 293.498016 -208.800446)
		(width 0.14478)
		(layer "In4.Cu")
		(net "M_D_CPU0_SA_DQ<11>")
	)
	(segment
		(start 335.094072 -231.201722)
		(end 335.102454 -231.196896)
		(width 0.0889)
		(layer "In4.Cu")
		(net "M_D_CPU0_SA_DQ<11>")
	)
	(segment
		(start 330.394056 -231.201722)
		(end 330.402438 -231.196896)
		(width 0.0889)
		(layer "In4.Cu")
		(net "M_D_CPU0_SA_DQ<11>")
	)
	(segment
		(start 293.498016 -208.800446)
		(end 294.3479 -209.65033)
		(width 0.14478)
		(layer "In4.Cu")
		(net "M_D_CPU0_SA_DQ<11>")
	)
	(segment
		(start 294.3479 -209.65033)
		(end 297.32224 -209.65033)
		(width 0.14478)
		(layer "In4.Cu")
		(net "M_D_CPU0_SA_DQ<11>")
	)
	(segment
		(start 320.453258 -222.541592)
		(end 322.307458 -224.395792)
		(width 0.14478)
		(layer "In4.Cu")
		(net "M_D_CPU0_SA_DQ<11>")
	)
	(segment
		(start 326.330818 -229.793292)
		(end 326.686418 -229.793292)
		(width 0.0889)
		(layer "In4.Cu")
		(net "M_D_CPU0_SA_DQ<11>")
	)
	(segment
		(start 320.453258 -221.707964)
		(end 320.453258 -222.541592)
		(width 0.14478)
		(layer "In4.Cu")
		(net "M_D_CPU0_SA_DQ<11>")
	)
	(segment
		(start 297.32224 -209.65033)
		(end 298.172124 -208.800446)
		(width 0.14478)
		(layer "In4.Cu")
		(net "M_D_CPU0_SA_DQ<11>")
	)
	(segment
		(start 338.27974 -231.196896)
		(end 338.288122 -231.201722)
		(width 0.0889)
		(layer "In4.Cu")
		(net "M_D_CPU0_SA_DQ<11>")
	)
	(segment
		(start 336.034126 -231.201722)
		(end 336.042508 -231.196896)
		(width 0.0889)
		(layer "In4.Cu")
		(net "M_D_CPU0_SA_DQ<11>")
	)
	(segment
		(start 311.217818 -212.472524)
		(end 320.453258 -221.707964)
		(width 0.14478)
		(layer "In4.Cu")
		(net "M_D_CPU0_SA_DQ<11>")
	)
	(segment
		(start 324.140576 -227.822252)
		(end 325.058278 -227.822252)
		(width 0.0889)
		(layer "In4.Cu")
		(net "M_D_CPU0_SA_DQ<11>")
	)
	(segment
		(start 289.834066 -209.65033)
		(end 290.68395 -208.800446)
		(width 0.14478)
		(layer "In4.Cu")
		(net "M_D_CPU0_SA_DQ<11>")
	)
	(segment
		(start 340.113112 -231.17556)
		(end 340.13521 -231.258618)
		(width 0.0889)
		(layer "In4.Cu")
		(net "M_D_CPU0_SA_DQ<11>")
	)
	(segment
		(start 329.819762 -231.196896)
		(end 329.828144 -231.201722)
		(width 0.0889)
		(layer "In4.Cu")
		(net "M_D_CPU0_SA_DQ<11>")
	)
	(segment
		(start 281.051254 -209.65033)
		(end 289.834066 -209.65033)
		(width 0.14478)
		(layer "In4.Cu")
		(net "M_D_CPU0_SA_DQ<11>")
	)
	(segment
		(start 322.307458 -225.989134)
		(end 323.992494 -227.67417)
		(width 0.14478)
		(layer "In4.Cu")
		(net "M_D_CPU0_SA_DQ<11>")
	)
	(segment
		(start 338.854034 -231.201722)
		(end 338.862416 -231.196896)
		(width 0.0889)
		(layer "In4.Cu")
		(net "M_D_CPU0_SA_DQ<11>")
	)
	(segment
		(start 339.794088 -231.201722)
		(end 339.80247 -231.196896)
		(width 0.0889)
		(layer "In4.Cu")
		(net "M_D_CPU0_SA_DQ<11>")
	)
	(segment
		(start 301.18685 -208.800446)
		(end 302.04664 -209.660236)
		(width 0.14478)
		(layer "In4.Cu")
		(net "M_D_CPU0_SA_DQ<11>")
	)
	(segment
		(start 322.307458 -224.395792)
		(end 322.307458 -225.989134)
		(width 0.14478)
		(layer "In4.Cu")
		(net "M_D_CPU0_SA_DQ<11>")
	)
	(segment
		(start 325.700898 -229.163372)
		(end 326.330818 -229.793292)
		(width 0.0889)
		(layer "In4.Cu")
		(net "M_D_CPU0_SA_DQ<11>")
	)
	(segment
		(start 325.700898 -228.464872)
		(end 325.700898 -229.163372)
		(width 0.0889)
		(layer "In4.Cu")
		(net "M_D_CPU0_SA_DQ<11>")
	)
	(segment
		(start 340.13521 -231.258618)
		(end 339.981032 -231.524048)
		(width 0.0889)
		(layer "In4.Cu")
		(net "M_D_CPU0_SA_DQ<11>")
	)
	(arc
		(start 328.88809 -231.201722)
		(mid 329.171046 -231.277899)
		(end 329.454002 -231.201722)
		(width 0.0889)
		(layer "In4.Cu")
		(net "M_D_CPU0_SA_DQ<11>")
	)
	(arc
		(start 336.408268 -231.201722)
		(mid 336.691224 -231.277899)
		(end 336.97418 -231.201722)
		(width 0.0889)
		(layer "In4.Cu")
		(net "M_D_CPU0_SA_DQ<11>")
	)
	(arc
		(start 327.665842 -230.714296)
		(mid 327.730357 -230.976515)
		(end 327.909174 -231.178862)
		(width 0.0889)
		(layer "In4.Cu")
		(net "M_D_CPU0_SA_DQ<11>")
	)
	(arc
		(start 331.708252 -231.201722)
		(mid 331.991208 -231.277899)
		(end 332.274164 -231.201722)
		(width 0.0889)
		(layer "In4.Cu")
		(net "M_D_CPU0_SA_DQ<11>")
	)
	(arc
		(start 337.91398 -231.201722)
		(mid 338.096231 -231.151338)
		(end 338.27974 -231.196896)
		(width 0.0889)
		(layer "In4.Cu")
		(net "M_D_CPU0_SA_DQ<11>")
	)
	(arc
		(start 328.514202 -231.201722)
		(mid 328.701146 -231.151433)
		(end 328.88809 -231.201722)
		(width 0.0889)
		(layer "In4.Cu")
		(net "M_D_CPU0_SA_DQ<11>")
	)
	(arc
		(start 339.80247 -231.196896)
		(mid 339.955458 -231.152216)
		(end 340.113112 -231.17556)
		(width 0.0889)
		(layer "In4.Cu")
		(net "M_D_CPU0_SA_DQ<11>")
	)
	(arc
		(start 334.154018 -231.201722)
		(mid 334.336269 -231.151338)
		(end 334.519778 -231.196896)
		(width 0.0889)
		(layer "In4.Cu")
		(net "M_D_CPU0_SA_DQ<11>")
	)
	(arc
		(start 335.468214 -231.201722)
		(mid 335.75117 -231.277899)
		(end 336.034126 -231.201722)
		(width 0.0889)
		(layer "In4.Cu")
		(net "M_D_CPU0_SA_DQ<11>")
	)
	(arc
		(start 327.94829 -231.201722)
		(mid 328.231246 -231.277899)
		(end 328.514202 -231.201722)
		(width 0.0889)
		(layer "In4.Cu")
		(net "M_D_CPU0_SA_DQ<11>")
	)
	(arc
		(start 327.14565 -230.252524)
		(mid 327.232518 -230.314368)
		(end 327.33488 -230.344218)
		(width 0.0889)
		(layer "In4.Cu")
		(net "M_D_CPU0_SA_DQ<11>")
	)
	(arc
		(start 337.348068 -231.201722)
		(mid 337.631024 -231.277899)
		(end 337.91398 -231.201722)
		(width 0.0889)
		(layer "In4.Cu")
		(net "M_D_CPU0_SA_DQ<11>")
	)
	(arc
		(start 338.862416 -231.196896)
		(mid 339.045924 -231.151371)
		(end 339.228176 -231.201722)
		(width 0.0889)
		(layer "In4.Cu")
		(net "M_D_CPU0_SA_DQ<11>")
	)
	(arc
		(start 336.042508 -231.196896)
		(mid 336.226016 -231.151371)
		(end 336.408268 -231.201722)
		(width 0.0889)
		(layer "In4.Cu")
		(net "M_D_CPU0_SA_DQ<11>")
	)
	(arc
		(start 338.288122 -231.201722)
		(mid 338.571078 -231.277899)
		(end 338.854034 -231.201722)
		(width 0.0889)
		(layer "In4.Cu")
		(net "M_D_CPU0_SA_DQ<11>")
	)
	(arc
		(start 331.342492 -231.196896)
		(mid 331.526 -231.151371)
		(end 331.708252 -231.201722)
		(width 0.0889)
		(layer "In4.Cu")
		(net "M_D_CPU0_SA_DQ<11>")
	)
	(arc
		(start 333.588106 -231.201722)
		(mid 333.871062 -231.277899)
		(end 334.154018 -231.201722)
		(width 0.0889)
		(layer "In4.Cu")
		(net "M_D_CPU0_SA_DQ<11>")
	)
	(arc
		(start 339.228176 -231.201722)
		(mid 339.511132 -231.277899)
		(end 339.794088 -231.201722)
		(width 0.0889)
		(layer "In4.Cu")
		(net "M_D_CPU0_SA_DQ<11>")
	)
	(arc
		(start 330.402438 -231.196896)
		(mid 330.585946 -231.151371)
		(end 330.768198 -231.201722)
		(width 0.0889)
		(layer "In4.Cu")
		(net "M_D_CPU0_SA_DQ<11>")
	)
	(arc
		(start 332.274164 -231.201722)
		(mid 332.461108 -231.151433)
		(end 332.648052 -231.201722)
		(width 0.0889)
		(layer "In4.Cu")
		(net "M_D_CPU0_SA_DQ<11>")
	)
	(arc
		(start 333.213964 -231.201722)
		(mid 333.396215 -231.151338)
		(end 333.579724 -231.196896)
		(width 0.0889)
		(layer "In4.Cu")
		(net "M_D_CPU0_SA_DQ<11>")
	)
	(arc
		(start 329.454002 -231.201722)
		(mid 329.636253 -231.151338)
		(end 329.819762 -231.196896)
		(width 0.0889)
		(layer "In4.Cu")
		(net "M_D_CPU0_SA_DQ<11>")
	)
	(arc
		(start 336.97418 -231.201722)
		(mid 337.161124 -231.151433)
		(end 337.348068 -231.201722)
		(width 0.0889)
		(layer "In4.Cu")
		(net "M_D_CPU0_SA_DQ<11>")
	)
	(arc
		(start 334.52816 -231.201722)
		(mid 334.811116 -231.277899)
		(end 335.094072 -231.201722)
		(width 0.0889)
		(layer "In4.Cu")
		(net "M_D_CPU0_SA_DQ<11>")
	)
	(arc
		(start 335.102454 -231.196896)
		(mid 335.285962 -231.151371)
		(end 335.468214 -231.201722)
		(width 0.0889)
		(layer "In4.Cu")
		(net "M_D_CPU0_SA_DQ<11>")
	)
	(arc
		(start 329.828144 -231.201722)
		(mid 330.1111 -231.277899)
		(end 330.394056 -231.201722)
		(width 0.0889)
		(layer "In4.Cu")
		(net "M_D_CPU0_SA_DQ<11>")
	)
	(arc
		(start 327.33488 -230.344218)
		(mid 327.410323 -230.36115)
		(end 327.480676 -230.39324)
		(width 0.0889)
		(layer "In4.Cu")
		(net "M_D_CPU0_SA_DQ<11>")
	)
	(arc
		(start 327.480676 -230.39324)
		(mid 327.616261 -230.528973)
		(end 327.665842 -230.714296)
		(width 0.0889)
		(layer "In4.Cu")
		(net "M_D_CPU0_SA_DQ<11>")
	)
	(arc
		(start 332.648052 -231.201722)
		(mid 332.931008 -231.277899)
		(end 333.213964 -231.201722)
		(width 0.0889)
		(layer "In4.Cu")
		(net "M_D_CPU0_SA_DQ<11>")
	)
	(arc
		(start 330.768198 -231.201722)
		(mid 331.051154 -231.277899)
		(end 331.33411 -231.201722)
		(width 0.0889)
		(layer "In4.Cu")
		(net "M_D_CPU0_SA_DQ<11>")
	)
	(segment
		(start 339.03793 -230.97998)
		(end 338.571078 -230.714296)
		(width 0.10668)
		(layer "F.Cu")
		(net "M_D_CPU0_SA_DQ<10>")
	)
	(segment
		(start 298.162472 -207.110076)
		(end 301.196502 -207.110076)
		(width 0.14478)
		(layer "In4.Cu")
		(net "M_D_CPU0_SA_DQ<10>")
	)
	(segment
		(start 321.390518 -222.201232)
		(end 323.311774 -224.122488)
		(width 0.14478)
		(layer "In4.Cu")
		(net "M_D_CPU0_SA_DQ<10>")
	)
	(segment
		(start 307.97754 -207.960214)
		(end 321.390518 -221.373192)
		(width 0.14478)
		(layer "In4.Cu")
		(net "M_D_CPU0_SA_DQ<10>")
	)
	(segment
		(start 283.291026 -207.797146)
		(end 283.454094 -207.960214)
		(width 0.14478)
		(layer "In4.Cu")
		(net "M_D_CPU0_SA_DQ<10>")
	)
	(segment
		(start 337.44408 -230.391716)
		(end 337.452462 -230.38689)
		(width 0.0889)
		(layer "In4.Cu")
		(net "M_D_CPU0_SA_DQ<10>")
	)
	(segment
		(start 327.909174 -229.55885)
		(end 327.980802 -229.600506)
		(width 0.0889)
		(layer "In4.Cu")
		(net "M_D_CPU0_SA_DQ<10>")
	)
	(segment
		(start 324.318884 -226.34448)
		(end 324.489318 -226.514914)
		(width 0.0889)
		(layer "In4.Cu")
		(net "M_D_CPU0_SA_DQ<10>")
	)
	(segment
		(start 324.489318 -226.742752)
		(end 324.778878 -227.032312)
		(width 0.0889)
		(layer "In4.Cu")
		(net "M_D_CPU0_SA_DQ<10>")
	)
	(segment
		(start 338.70265 -230.365554)
		(end 338.725002 -230.448866)
		(width 0.0889)
		(layer "In4.Cu")
		(net "M_D_CPU0_SA_DQ<10>")
	)
	(segment
		(start 326.307958 -227.857812)
		(end 327.57237 -229.122224)
		(width 0.0889)
		(layer "In4.Cu")
		(net "M_D_CPU0_SA_DQ<10>")
	)
	(segment
		(start 294.357806 -207.960214)
		(end 297.312334 -207.960214)
		(width 0.14478)
		(layer "In4.Cu")
		(net "M_D_CPU0_SA_DQ<10>")
	)
	(segment
		(start 336.869786 -230.38689)
		(end 336.878168 -230.391716)
		(width 0.0889)
		(layer "In4.Cu")
		(net "M_D_CPU0_SA_DQ<10>")
	)
	(segment
		(start 281.06116 -207.960214)
		(end 282.571444 -207.960214)
		(width 0.14478)
		(layer "In4.Cu")
		(net "M_D_CPU0_SA_DQ<10>")
	)
	(segment
		(start 283.454094 -207.960214)
		(end 289.82416 -207.960214)
		(width 0.14478)
		(layer "In4.Cu")
		(net "M_D_CPU0_SA_DQ<10>")
	)
	(segment
		(start 282.571444 -207.960214)
		(end 282.734512 -207.797146)
		(width 0.14478)
		(layer "In4.Cu")
		(net "M_D_CPU0_SA_DQ<10>")
	)
	(segment
		(start 332.16977 -230.38689)
		(end 332.178152 -230.391716)
		(width 0.0889)
		(layer "In4.Cu")
		(net "M_D_CPU0_SA_DQ<10>")
	)
	(segment
		(start 293.507668 -207.110076)
		(end 294.357806 -207.960214)
		(width 0.14478)
		(layer "In4.Cu")
		(net "M_D_CPU0_SA_DQ<10>")
	)
	(segment
		(start 331.229716 -230.38689)
		(end 331.238098 -230.391716)
		(width 0.0889)
		(layer "In4.Cu")
		(net "M_D_CPU0_SA_DQ<10>")
	)
	(segment
		(start 297.312334 -207.960214)
		(end 298.162472 -207.110076)
		(width 0.14478)
		(layer "In4.Cu")
		(net "M_D_CPU0_SA_DQ<10>")
	)
	(segment
		(start 282.734512 -207.43418)
		(end 282.89758 -207.271112)
		(width 0.14478)
		(layer "In4.Cu")
		(net "M_D_CPU0_SA_DQ<10>")
	)
	(segment
		(start 338.725002 -230.448866)
		(end 338.571078 -230.714296)
		(width 0.0889)
		(layer "In4.Cu")
		(net "M_D_CPU0_SA_DQ<10>")
	)
	(segment
		(start 290.674298 -207.110076)
		(end 293.507668 -207.110076)
		(width 0.14478)
		(layer "In4.Cu")
		(net "M_D_CPU0_SA_DQ<10>")
	)
	(segment
		(start 301.196502 -207.110076)
		(end 302.04664 -207.960214)
		(width 0.14478)
		(layer "In4.Cu")
		(net "M_D_CPU0_SA_DQ<10>")
	)
	(segment
		(start 323.311774 -225.33737)
		(end 324.318884 -226.34448)
		(width 0.14478)
		(layer "In4.Cu")
		(net "M_D_CPU0_SA_DQ<10>")
	)
	(segment
		(start 324.778878 -227.032312)
		(end 325.332598 -227.032312)
		(width 0.0889)
		(layer "In4.Cu")
		(net "M_D_CPU0_SA_DQ<10>")
	)
	(segment
		(start 280.635964 -207.535018)
		(end 281.06116 -207.960214)
		(width 0.14478)
		(layer "In4.Cu")
		(net "M_D_CPU0_SA_DQ<10>")
	)
	(segment
		(start 283.127958 -207.271112)
		(end 283.291026 -207.43418)
		(width 0.14478)
		(layer "In4.Cu")
		(net "M_D_CPU0_SA_DQ<10>")
	)
	(segment
		(start 324.489318 -226.514914)
		(end 324.489318 -226.742752)
		(width 0.0889)
		(layer "In4.Cu")
		(net "M_D_CPU0_SA_DQ<10>")
	)
	(segment
		(start 282.89758 -207.271112)
		(end 283.127958 -207.271112)
		(width 0.14478)
		(layer "In4.Cu")
		(net "M_D_CPU0_SA_DQ<10>")
	)
	(segment
		(start 328.984102 -230.391716)
		(end 328.992484 -230.38689)
		(width 0.0889)
		(layer "In4.Cu")
		(net "M_D_CPU0_SA_DQ<10>")
	)
	(segment
		(start 333.684118 -230.391716)
		(end 333.6925 -230.38689)
		(width 0.0889)
		(layer "In4.Cu")
		(net "M_D_CPU0_SA_DQ<10>")
	)
	(segment
		(start 328.381614 -230.37038)
		(end 328.41819 -230.391716)
		(width 0.0889)
		(layer "In4.Cu")
		(net "M_D_CPU0_SA_DQ<10>")
	)
	(segment
		(start 283.291026 -207.43418)
		(end 283.291026 -207.797146)
		(width 0.14478)
		(layer "In4.Cu")
		(net "M_D_CPU0_SA_DQ<10>")
	)
	(segment
		(start 332.744064 -230.391716)
		(end 332.752446 -230.38689)
		(width 0.0889)
		(layer "In4.Cu")
		(net "M_D_CPU0_SA_DQ<10>")
	)
	(segment
		(start 335.929732 -230.38689)
		(end 335.938114 -230.391716)
		(width 0.0889)
		(layer "In4.Cu")
		(net "M_D_CPU0_SA_DQ<10>")
	)
	(segment
		(start 323.311774 -224.122488)
		(end 323.311774 -225.33737)
		(width 0.14478)
		(layer "In4.Cu")
		(net "M_D_CPU0_SA_DQ<10>")
	)
	(segment
		(start 326.158098 -227.857812)
		(end 326.307958 -227.857812)
		(width 0.0889)
		(layer "In4.Cu")
		(net "M_D_CPU0_SA_DQ<10>")
	)
	(segment
		(start 325.332598 -227.032312)
		(end 326.158098 -227.857812)
		(width 0.0889)
		(layer "In4.Cu")
		(net "M_D_CPU0_SA_DQ<10>")
	)
	(segment
		(start 321.390518 -221.373192)
		(end 321.390518 -222.201232)
		(width 0.14478)
		(layer "In4.Cu")
		(net "M_D_CPU0_SA_DQ<10>")
	)
	(segment
		(start 289.82416 -207.960214)
		(end 290.674298 -207.110076)
		(width 0.14478)
		(layer "In4.Cu")
		(net "M_D_CPU0_SA_DQ<10>")
	)
	(segment
		(start 302.04664 -207.960214)
		(end 307.97754 -207.960214)
		(width 0.14478)
		(layer "In4.Cu")
		(net "M_D_CPU0_SA_DQ<10>")
	)
	(segment
		(start 282.734512 -207.797146)
		(end 282.734512 -207.43418)
		(width 0.14478)
		(layer "In4.Cu")
		(net "M_D_CPU0_SA_DQ<10>")
	)
	(arc
		(start 327.980802 -229.600506)
		(mid 328.094731 -229.733653)
		(end 328.135742 -229.904036)
		(width 0.0889)
		(layer "In4.Cu")
		(net "M_D_CPU0_SA_DQ<10>")
	)
	(arc
		(start 334.99806 -230.391716)
		(mid 335.281016 -230.467859)
		(end 335.563972 -230.391716)
		(width 0.0889)
		(layer "In4.Cu")
		(net "M_D_CPU0_SA_DQ<10>")
	)
	(arc
		(start 333.118206 -230.391716)
		(mid 333.401162 -230.467859)
		(end 333.684118 -230.391716)
		(width 0.0889)
		(layer "In4.Cu")
		(net "M_D_CPU0_SA_DQ<10>")
	)
	(arc
		(start 329.924156 -230.391716)
		(mid 330.1111 -230.341461)
		(end 330.298044 -230.391716)
		(width 0.0889)
		(layer "In4.Cu")
		(net "M_D_CPU0_SA_DQ<10>")
	)
	(arc
		(start 329.358244 -230.391716)
		(mid 329.6412 -230.467859)
		(end 329.924156 -230.391716)
		(width 0.0889)
		(layer "In4.Cu")
		(net "M_D_CPU0_SA_DQ<10>")
	)
	(arc
		(start 332.178152 -230.391716)
		(mid 332.461108 -230.467859)
		(end 332.744064 -230.391716)
		(width 0.0889)
		(layer "In4.Cu")
		(net "M_D_CPU0_SA_DQ<10>")
	)
	(arc
		(start 332.752446 -230.38689)
		(mid 332.935954 -230.341396)
		(end 333.118206 -230.391716)
		(width 0.0889)
		(layer "In4.Cu")
		(net "M_D_CPU0_SA_DQ<10>")
	)
	(arc
		(start 334.05826 -230.391716)
		(mid 334.341216 -230.467859)
		(end 334.624172 -230.391716)
		(width 0.0889)
		(layer "In4.Cu")
		(net "M_D_CPU0_SA_DQ<10>")
	)
	(arc
		(start 338.384134 -230.391716)
		(mid 338.540453 -230.342721)
		(end 338.70265 -230.365554)
		(width 0.0889)
		(layer "In4.Cu")
		(net "M_D_CPU0_SA_DQ<10>")
	)
	(arc
		(start 328.992484 -230.38689)
		(mid 329.175992 -230.341396)
		(end 329.358244 -230.391716)
		(width 0.0889)
		(layer "In4.Cu")
		(net "M_D_CPU0_SA_DQ<10>")
	)
	(arc
		(start 327.57237 -229.122224)
		(mid 327.654262 -229.220048)
		(end 327.717658 -229.330758)
		(width 0.0889)
		(layer "In4.Cu")
		(net "M_D_CPU0_SA_DQ<10>")
	)
	(arc
		(start 335.563972 -230.391716)
		(mid 335.746223 -230.341366)
		(end 335.929732 -230.38689)
		(width 0.0889)
		(layer "In4.Cu")
		(net "M_D_CPU0_SA_DQ<10>")
	)
	(arc
		(start 336.878168 -230.391716)
		(mid 337.161124 -230.467859)
		(end 337.44408 -230.391716)
		(width 0.0889)
		(layer "In4.Cu")
		(net "M_D_CPU0_SA_DQ<10>")
	)
	(arc
		(start 334.624172 -230.391716)
		(mid 334.811116 -230.341461)
		(end 334.99806 -230.391716)
		(width 0.0889)
		(layer "In4.Cu")
		(net "M_D_CPU0_SA_DQ<10>")
	)
	(arc
		(start 333.6925 -230.38689)
		(mid 333.876008 -230.341396)
		(end 334.05826 -230.391716)
		(width 0.0889)
		(layer "In4.Cu")
		(net "M_D_CPU0_SA_DQ<10>")
	)
	(arc
		(start 337.818222 -230.391716)
		(mid 338.101178 -230.467859)
		(end 338.384134 -230.391716)
		(width 0.0889)
		(layer "In4.Cu")
		(net "M_D_CPU0_SA_DQ<10>")
	)
	(arc
		(start 328.41819 -230.391716)
		(mid 328.701146 -230.467859)
		(end 328.984102 -230.391716)
		(width 0.0889)
		(layer "In4.Cu")
		(net "M_D_CPU0_SA_DQ<10>")
	)
	(arc
		(start 327.717658 -229.330758)
		(mid 327.798108 -229.457661)
		(end 327.909174 -229.55885)
		(width 0.0889)
		(layer "In4.Cu")
		(net "M_D_CPU0_SA_DQ<10>")
	)
	(arc
		(start 335.938114 -230.391716)
		(mid 336.22107 -230.467859)
		(end 336.504026 -230.391716)
		(width 0.0889)
		(layer "In4.Cu")
		(net "M_D_CPU0_SA_DQ<10>")
	)
	(arc
		(start 336.504026 -230.391716)
		(mid 336.686277 -230.341366)
		(end 336.869786 -230.38689)
		(width 0.0889)
		(layer "In4.Cu")
		(net "M_D_CPU0_SA_DQ<10>")
	)
	(arc
		(start 330.863956 -230.391716)
		(mid 331.046207 -230.341366)
		(end 331.229716 -230.38689)
		(width 0.0889)
		(layer "In4.Cu")
		(net "M_D_CPU0_SA_DQ<10>")
	)
	(arc
		(start 328.135742 -229.904036)
		(mid 328.200978 -230.167627)
		(end 328.381614 -230.37038)
		(width 0.0889)
		(layer "In4.Cu")
		(net "M_D_CPU0_SA_DQ<10>")
	)
	(arc
		(start 331.80401 -230.391716)
		(mid 331.986261 -230.341366)
		(end 332.16977 -230.38689)
		(width 0.0889)
		(layer "In4.Cu")
		(net "M_D_CPU0_SA_DQ<10>")
	)
	(arc
		(start 337.452462 -230.38689)
		(mid 337.63597 -230.341396)
		(end 337.818222 -230.391716)
		(width 0.0889)
		(layer "In4.Cu")
		(net "M_D_CPU0_SA_DQ<10>")
	)
	(arc
		(start 330.298044 -230.391716)
		(mid 330.581 -230.467859)
		(end 330.863956 -230.391716)
		(width 0.0889)
		(layer "In4.Cu")
		(net "M_D_CPU0_SA_DQ<10>")
	)
	(arc
		(start 331.238098 -230.391716)
		(mid 331.521054 -230.467859)
		(end 331.80401 -230.391716)
		(width 0.0889)
		(layer "In4.Cu")
		(net "M_D_CPU0_SA_DQ<10>")
	)
	(segment
		(start 339.508084 -225.310192)
		(end 339.040978 -225.044254)
		(width 0.10668)
		(layer "F.Cu")
		(net "M_D_CPU0_SA_DQ<0>")
	)
	(segment
		(start 286.352742 -197.20052)
		(end 286.352742 -197.597014)
		(width 0.14478)
		(layer "In4.Cu")
		(net "M_D_CPU0_SA_DQ<0>")
	)
	(segment
		(start 289.13963 -196.32803)
		(end 289.302698 -196.491098)
		(width 0.14478)
		(layer "In4.Cu")
		(net "M_D_CPU0_SA_DQ<0>")
	)
	(segment
		(start 287.46577 -197.597014)
		(end 287.628838 -197.760082)
		(width 0.14478)
		(layer "In4.Cu")
		(net "M_D_CPU0_SA_DQ<0>")
	)
	(segment
		(start 286.746188 -197.760082)
		(end 286.909256 -197.597014)
		(width 0.14478)
		(layer "In4.Cu")
		(net "M_D_CPU0_SA_DQ<0>")
	)
	(segment
		(start 286.909256 -197.597014)
		(end 286.909256 -196.823838)
		(width 0.14478)
		(layer "In4.Cu")
		(net "M_D_CPU0_SA_DQ<0>")
	)
	(segment
		(start 336.034126 -225.366834)
		(end 336.042508 -225.37166)
		(width 0.0889)
		(layer "In4.Cu")
		(net "M_D_CPU0_SA_DQ<0>")
	)
	(segment
		(start 289.302698 -197.597014)
		(end 289.465766 -197.760082)
		(width 0.14478)
		(layer "In4.Cu")
		(net "M_D_CPU0_SA_DQ<0>")
	)
	(segment
		(start 287.072324 -196.66077)
		(end 287.302702 -196.66077)
		(width 0.14478)
		(layer "In4.Cu")
		(net "M_D_CPU0_SA_DQ<0>")
	)
	(segment
		(start 297.346878 -197.760082)
		(end 298.196762 -196.910198)
		(width 0.14478)
		(layer "In4.Cu")
		(net "M_D_CPU0_SA_DQ<0>")
	)
	(segment
		(start 333.579724 -225.37166)
		(end 333.588106 -225.366834)
		(width 0.0889)
		(layer "In4.Cu")
		(net "M_D_CPU0_SA_DQ<0>")
	)
	(segment
		(start 289.823398 -197.760082)
		(end 290.673282 -196.910198)
		(width 0.14478)
		(layer "In4.Cu")
		(net "M_D_CPU0_SA_DQ<0>")
	)
	(segment
		(start 335.094072 -225.366834)
		(end 335.102454 -225.37166)
		(width 0.0889)
		(layer "In4.Cu")
		(net "M_D_CPU0_SA_DQ<0>")
	)
	(segment
		(start 285.63316 -197.760082)
		(end 285.796228 -197.597014)
		(width 0.14478)
		(layer "In4.Cu")
		(net "M_D_CPU0_SA_DQ<0>")
	)
	(segment
		(start 334.519778 -225.37166)
		(end 334.52816 -225.366834)
		(width 0.0889)
		(layer "In4.Cu")
		(net "M_D_CPU0_SA_DQ<0>")
	)
	(segment
		(start 289.302698 -196.491098)
		(end 289.302698 -197.597014)
		(width 0.14478)
		(layer "In4.Cu")
		(net "M_D_CPU0_SA_DQ<0>")
	)
	(segment
		(start 287.628838 -197.760082)
		(end 288.583116 -197.760082)
		(width 0.14478)
		(layer "In4.Cu")
		(net "M_D_CPU0_SA_DQ<0>")
	)
	(segment
		(start 284.736032 -197.33514)
		(end 285.160974 -197.760082)
		(width 0.14478)
		(layer "In4.Cu")
		(net "M_D_CPU0_SA_DQ<0>")
	)
	(segment
		(start 294.348662 -197.760082)
		(end 297.346878 -197.760082)
		(width 0.14478)
		(layer "In4.Cu")
		(net "M_D_CPU0_SA_DQ<0>")
	)
	(segment
		(start 293.498778 -196.910198)
		(end 294.348662 -197.760082)
		(width 0.14478)
		(layer "In4.Cu")
		(net "M_D_CPU0_SA_DQ<0>")
	)
	(segment
		(start 286.51581 -197.760082)
		(end 286.746188 -197.760082)
		(width 0.14478)
		(layer "In4.Cu")
		(net "M_D_CPU0_SA_DQ<0>")
	)
	(segment
		(start 330.362306 -223.728534)
		(end 330.394056 -223.746822)
		(width 0.0889)
		(layer "In4.Cu")
		(net "M_D_CPU0_SA_DQ<0>")
	)
	(segment
		(start 287.302702 -196.66077)
		(end 287.46577 -196.823838)
		(width 0.14478)
		(layer "In4.Cu")
		(net "M_D_CPU0_SA_DQ<0>")
	)
	(segment
		(start 285.959296 -197.037452)
		(end 286.189674 -197.037452)
		(width 0.14478)
		(layer "In4.Cu")
		(net "M_D_CPU0_SA_DQ<0>")
	)
	(segment
		(start 329.514454 -221.361508)
		(end 329.73645 -221.583504)
		(width 0.0889)
		(layer "In4.Cu")
		(net "M_D_CPU0_SA_DQ<0>")
	)
	(segment
		(start 289.465766 -197.760082)
		(end 289.823398 -197.760082)
		(width 0.14478)
		(layer "In4.Cu")
		(net "M_D_CPU0_SA_DQ<0>")
	)
	(segment
		(start 329.514454 -219.576142)
		(end 329.514454 -221.25305)
		(width 0.14478)
		(layer "In4.Cu")
		(net "M_D_CPU0_SA_DQ<0>")
	)
	(segment
		(start 330.833476 -224.539048)
		(end 330.863956 -224.556828)
		(width 0.0889)
		(layer "In4.Cu")
		(net "M_D_CPU0_SA_DQ<0>")
	)
	(segment
		(start 302.024542 -197.760082)
		(end 307.698394 -197.760082)
		(width 0.14478)
		(layer "In4.Cu")
		(net "M_D_CPU0_SA_DQ<0>")
	)
	(segment
		(start 307.698394 -197.760082)
		(end 329.514454 -219.576142)
		(width 0.14478)
		(layer "In4.Cu")
		(net "M_D_CPU0_SA_DQ<0>")
	)
	(segment
		(start 286.909256 -196.823838)
		(end 287.072324 -196.66077)
		(width 0.14478)
		(layer "In4.Cu")
		(net "M_D_CPU0_SA_DQ<0>")
	)
	(segment
		(start 329.892406 -222.918528)
		(end 329.960478 -222.957898)
		(width 0.0889)
		(layer "In4.Cu")
		(net "M_D_CPU0_SA_DQ<0>")
	)
	(segment
		(start 298.196762 -196.910198)
		(end 301.174658 -196.910198)
		(width 0.14478)
		(layer "In4.Cu")
		(net "M_D_CPU0_SA_DQ<0>")
	)
	(segment
		(start 301.174658 -196.910198)
		(end 302.024542 -197.760082)
		(width 0.14478)
		(layer "In4.Cu")
		(net "M_D_CPU0_SA_DQ<0>")
	)
	(segment
		(start 338.27974 -225.37166)
		(end 338.288122 -225.366834)
		(width 0.0889)
		(layer "In4.Cu")
		(net "M_D_CPU0_SA_DQ<0>")
	)
	(segment
		(start 290.673282 -196.910198)
		(end 293.498778 -196.910198)
		(width 0.14478)
		(layer "In4.Cu")
		(net "M_D_CPU0_SA_DQ<0>")
	)
	(segment
		(start 329.73645 -221.583504)
		(end 329.73645 -222.614236)
		(width 0.0889)
		(layer "In4.Cu")
		(net "M_D_CPU0_SA_DQ<0>")
	)
	(segment
		(start 285.160974 -197.760082)
		(end 285.63316 -197.760082)
		(width 0.14478)
		(layer "In4.Cu")
		(net "M_D_CPU0_SA_DQ<0>")
	)
	(segment
		(start 338.887054 -225.309684)
		(end 339.040978 -225.044254)
		(width 0.0889)
		(layer "In4.Cu")
		(net "M_D_CPU0_SA_DQ<0>")
	)
	(segment
		(start 285.796228 -197.597014)
		(end 285.796228 -197.20052)
		(width 0.14478)
		(layer "In4.Cu")
		(net "M_D_CPU0_SA_DQ<0>")
	)
	(segment
		(start 329.514454 -221.25305)
		(end 329.514454 -221.361508)
		(width 0.0889)
		(layer "In4.Cu")
		(net "M_D_CPU0_SA_DQ<0>")
	)
	(segment
		(start 331.30236 -225.348546)
		(end 331.33411 -225.366834)
		(width 0.0889)
		(layer "In4.Cu")
		(net "M_D_CPU0_SA_DQ<0>")
	)
	(segment
		(start 285.796228 -197.20052)
		(end 285.959296 -197.037452)
		(width 0.14478)
		(layer "In4.Cu")
		(net "M_D_CPU0_SA_DQ<0>")
	)
	(segment
		(start 286.352742 -197.597014)
		(end 286.51581 -197.760082)
		(width 0.14478)
		(layer "In4.Cu")
		(net "M_D_CPU0_SA_DQ<0>")
	)
	(segment
		(start 330.863956 -224.556828)
		(end 330.903072 -224.579688)
		(width 0.0889)
		(layer "In4.Cu")
		(net "M_D_CPU0_SA_DQ<0>")
	)
	(segment
		(start 288.909252 -196.32803)
		(end 289.13963 -196.32803)
		(width 0.14478)
		(layer "In4.Cu")
		(net "M_D_CPU0_SA_DQ<0>")
	)
	(segment
		(start 286.189674 -197.037452)
		(end 286.352742 -197.20052)
		(width 0.14478)
		(layer "In4.Cu")
		(net "M_D_CPU0_SA_DQ<0>")
	)
	(segment
		(start 331.33411 -225.366834)
		(end 331.342492 -225.37166)
		(width 0.0889)
		(layer "In4.Cu")
		(net "M_D_CPU0_SA_DQ<0>")
	)
	(segment
		(start 330.394056 -223.746822)
		(end 330.433172 -223.769682)
		(width 0.0889)
		(layer "In4.Cu")
		(net "M_D_CPU0_SA_DQ<0>")
	)
	(segment
		(start 287.46577 -196.823838)
		(end 287.46577 -197.597014)
		(width 0.14478)
		(layer "In4.Cu")
		(net "M_D_CPU0_SA_DQ<0>")
	)
	(segment
		(start 288.583116 -197.760082)
		(end 288.746184 -197.597014)
		(width 0.14478)
		(layer "In4.Cu")
		(net "M_D_CPU0_SA_DQ<0>")
	)
	(segment
		(start 288.746184 -196.491098)
		(end 288.909252 -196.32803)
		(width 0.14478)
		(layer "In4.Cu")
		(net "M_D_CPU0_SA_DQ<0>")
	)
	(segment
		(start 338.791042 -225.335084)
		(end 338.887054 -225.309684)
		(width 0.0889)
		(layer "In4.Cu")
		(net "M_D_CPU0_SA_DQ<0>")
	)
	(segment
		(start 288.746184 -197.597014)
		(end 288.746184 -196.491098)
		(width 0.14478)
		(layer "In4.Cu")
		(net "M_D_CPU0_SA_DQ<0>")
	)
	(arc
		(start 335.468214 -225.366834)
		(mid 335.75117 -225.290657)
		(end 336.034126 -225.366834)
		(width 0.0889)
		(layer "In4.Cu")
		(net "M_D_CPU0_SA_DQ<0>")
	)
	(arc
		(start 333.213964 -225.366834)
		(mid 333.396215 -225.417184)
		(end 333.579724 -225.37166)
		(width 0.0889)
		(layer "In4.Cu")
		(net "M_D_CPU0_SA_DQ<0>")
	)
	(arc
		(start 329.960478 -222.957898)
		(mid 330.14113 -223.160643)
		(end 330.20635 -223.424242)
		(width 0.0889)
		(layer "In4.Cu")
		(net "M_D_CPU0_SA_DQ<0>")
	)
	(arc
		(start 336.408268 -225.366834)
		(mid 336.691224 -225.290657)
		(end 336.97418 -225.366834)
		(width 0.0889)
		(layer "In4.Cu")
		(net "M_D_CPU0_SA_DQ<0>")
	)
	(arc
		(start 332.648052 -225.366834)
		(mid 332.931008 -225.290657)
		(end 333.213964 -225.366834)
		(width 0.0889)
		(layer "In4.Cu")
		(net "M_D_CPU0_SA_DQ<0>")
	)
	(arc
		(start 337.348068 -225.366834)
		(mid 337.631024 -225.290657)
		(end 337.91398 -225.366834)
		(width 0.0889)
		(layer "In4.Cu")
		(net "M_D_CPU0_SA_DQ<0>")
	)
	(arc
		(start 337.91398 -225.366834)
		(mid 338.096231 -225.417184)
		(end 338.27974 -225.37166)
		(width 0.0889)
		(layer "In4.Cu")
		(net "M_D_CPU0_SA_DQ<0>")
	)
	(arc
		(start 333.588106 -225.366834)
		(mid 333.871062 -225.290657)
		(end 334.154018 -225.366834)
		(width 0.0889)
		(layer "In4.Cu")
		(net "M_D_CPU0_SA_DQ<0>")
	)
	(arc
		(start 330.433172 -223.769682)
		(mid 330.611985 -223.972032)
		(end 330.676504 -224.234248)
		(width 0.0889)
		(layer "In4.Cu")
		(net "M_D_CPU0_SA_DQ<0>")
	)
	(arc
		(start 336.042508 -225.37166)
		(mid 336.226016 -225.417154)
		(end 336.408268 -225.366834)
		(width 0.0889)
		(layer "In4.Cu")
		(net "M_D_CPU0_SA_DQ<0>")
	)
	(arc
		(start 331.146404 -225.044254)
		(mid 331.187659 -225.215225)
		(end 331.30236 -225.348546)
		(width 0.0889)
		(layer "In4.Cu")
		(net "M_D_CPU0_SA_DQ<0>")
	)
	(arc
		(start 329.73645 -222.614236)
		(mid 329.777705 -222.785207)
		(end 329.892406 -222.918528)
		(width 0.0889)
		(layer "In4.Cu")
		(net "M_D_CPU0_SA_DQ<0>")
	)
	(arc
		(start 330.903072 -224.579688)
		(mid 331.081885 -224.782038)
		(end 331.146404 -225.044254)
		(width 0.0889)
		(layer "In4.Cu")
		(net "M_D_CPU0_SA_DQ<0>")
	)
	(arc
		(start 330.20635 -223.424242)
		(mid 330.247605 -223.595213)
		(end 330.362306 -223.728534)
		(width 0.0889)
		(layer "In4.Cu")
		(net "M_D_CPU0_SA_DQ<0>")
	)
	(arc
		(start 331.708252 -225.366834)
		(mid 331.991208 -225.290657)
		(end 332.274164 -225.366834)
		(width 0.0889)
		(layer "In4.Cu")
		(net "M_D_CPU0_SA_DQ<0>")
	)
	(arc
		(start 331.342492 -225.37166)
		(mid 331.526 -225.417154)
		(end 331.708252 -225.366834)
		(width 0.0889)
		(layer "In4.Cu")
		(net "M_D_CPU0_SA_DQ<0>")
	)
	(arc
		(start 335.102454 -225.37166)
		(mid 335.285962 -225.417154)
		(end 335.468214 -225.366834)
		(width 0.0889)
		(layer "In4.Cu")
		(net "M_D_CPU0_SA_DQ<0>")
	)
	(arc
		(start 336.97418 -225.366834)
		(mid 337.161124 -225.417089)
		(end 337.348068 -225.366834)
		(width 0.0889)
		(layer "In4.Cu")
		(net "M_D_CPU0_SA_DQ<0>")
	)
	(arc
		(start 338.288122 -225.366834)
		(mid 338.535835 -225.291614)
		(end 338.791042 -225.335084)
		(width 0.0889)
		(layer "In4.Cu")
		(net "M_D_CPU0_SA_DQ<0>")
	)
	(arc
		(start 332.274164 -225.366834)
		(mid 332.461108 -225.417089)
		(end 332.648052 -225.366834)
		(width 0.0889)
		(layer "In4.Cu")
		(net "M_D_CPU0_SA_DQ<0>")
	)
	(arc
		(start 334.154018 -225.366834)
		(mid 334.336269 -225.417184)
		(end 334.519778 -225.37166)
		(width 0.0889)
		(layer "In4.Cu")
		(net "M_D_CPU0_SA_DQ<0>")
	)
	(arc
		(start 330.676504 -224.234248)
		(mid 330.718053 -224.40567)
		(end 330.833476 -224.539048)
		(width 0.0889)
		(layer "In4.Cu")
		(net "M_D_CPU0_SA_DQ<0>")
	)
	(arc
		(start 334.52816 -225.366834)
		(mid 334.811116 -225.290657)
		(end 335.094072 -225.366834)
		(width 0.0889)
		(layer "In4.Cu")
		(net "M_D_CPU0_SA_DQ<0>")
	)
	(segment
		(start 340.447884 -252.850142)
		(end 339.981032 -252.584204)
		(width 0.10668)
		(layer "F.Cu")
		(net "M_D_CPU0_SA_CS_N<1>")
	)
	(segment
		(start 286.796988 -248.75998)
		(end 307.796946 -248.75998)
		(width 0.14478)
		(layer "In4.Cu")
		(net "M_D_CPU0_SA_CS_N<1>")
	)
	(segment
		(start 324.007734 -252.13691)
		(end 325.404988 -252.13691)
		(width 0.0889)
		(layer "In4.Cu")
		(net "M_D_CPU0_SA_CS_N<1>")
	)
	(segment
		(start 336.034126 -252.261624)
		(end 336.042508 -252.256798)
		(width 0.0889)
		(layer "In4.Cu")
		(net "M_D_CPU0_SA_CS_N<1>")
	)
	(segment
		(start 326.633586 -252.261878)
		(end 326.649842 -252.25248)
		(width 0.0889)
		(layer "In4.Cu")
		(net "M_D_CPU0_SA_CS_N<1>")
	)
	(segment
		(start 340.13521 -252.318774)
		(end 339.981032 -252.584204)
		(width 0.0889)
		(layer "In4.Cu")
		(net "M_D_CPU0_SA_CS_N<1>")
	)
	(segment
		(start 321.805554 -252.13691)
		(end 324.007734 -252.13691)
		(width 0.14478)
		(layer "In4.Cu")
		(net "M_D_CPU0_SA_CS_N<1>")
	)
	(segment
		(start 335.094072 -252.261624)
		(end 335.102454 -252.256798)
		(width 0.0889)
		(layer "In4.Cu")
		(net "M_D_CPU0_SA_CS_N<1>")
	)
	(segment
		(start 340.112858 -252.235462)
		(end 340.13521 -252.318774)
		(width 0.0889)
		(layer "In4.Cu")
		(net "M_D_CPU0_SA_CS_N<1>")
	)
	(segment
		(start 310.535066 -251.4981)
		(end 321.166744 -251.4981)
		(width 0.14478)
		(layer "In4.Cu")
		(net "M_D_CPU0_SA_CS_N<1>")
	)
	(segment
		(start 331.33411 -252.261624)
		(end 331.342492 -252.256798)
		(width 0.0889)
		(layer "In4.Cu")
		(net "M_D_CPU0_SA_CS_N<1>")
	)
	(segment
		(start 338.27974 -252.256798)
		(end 338.288122 -252.261624)
		(width 0.0889)
		(layer "In4.Cu")
		(net "M_D_CPU0_SA_CS_N<1>")
	)
	(segment
		(start 338.854034 -252.261624)
		(end 338.862416 -252.256798)
		(width 0.0889)
		(layer "In4.Cu")
		(net "M_D_CPU0_SA_CS_N<1>")
	)
	(segment
		(start 327.939908 -252.256798)
		(end 327.94829 -252.261624)
		(width 0.0889)
		(layer "In4.Cu")
		(net "M_D_CPU0_SA_CS_N<1>")
	)
	(segment
		(start 285.096966 -247.059958)
		(end 286.796988 -248.75998)
		(width 0.14478)
		(layer "In4.Cu")
		(net "M_D_CPU0_SA_CS_N<1>")
	)
	(segment
		(start 325.404988 -252.13691)
		(end 325.480934 -252.212856)
		(width 0.0889)
		(layer "In4.Cu")
		(net "M_D_CPU0_SA_CS_N<1>")
	)
	(segment
		(start 334.519778 -252.256798)
		(end 334.52816 -252.261624)
		(width 0.0889)
		(layer "In4.Cu")
		(net "M_D_CPU0_SA_CS_N<1>")
	)
	(segment
		(start 326.617838 -252.271022)
		(end 326.633586 -252.261878)
		(width 0.0889)
		(layer "In4.Cu")
		(net "M_D_CPU0_SA_CS_N<1>")
	)
	(segment
		(start 325.480934 -252.212856)
		(end 325.915274 -252.212856)
		(width 0.0889)
		(layer "In4.Cu")
		(net "M_D_CPU0_SA_CS_N<1>")
	)
	(segment
		(start 280.635964 -246.635016)
		(end 281.060906 -247.059958)
		(width 0.14478)
		(layer "In4.Cu")
		(net "M_D_CPU0_SA_CS_N<1>")
	)
	(segment
		(start 333.579724 -252.256798)
		(end 333.588106 -252.261624)
		(width 0.0889)
		(layer "In4.Cu")
		(net "M_D_CPU0_SA_CS_N<1>")
	)
	(segment
		(start 339.794088 -252.261624)
		(end 339.80247 -252.256798)
		(width 0.0889)
		(layer "In4.Cu")
		(net "M_D_CPU0_SA_CS_N<1>")
	)
	(segment
		(start 327.007474 -252.261624)
		(end 327.017888 -252.26772)
		(width 0.0889)
		(layer "In4.Cu")
		(net "M_D_CPU0_SA_CS_N<1>")
	)
	(segment
		(start 307.796946 -248.75998)
		(end 310.535066 -251.4981)
		(width 0.14478)
		(layer "In4.Cu")
		(net "M_D_CPU0_SA_CS_N<1>")
	)
	(segment
		(start 329.819762 -252.256798)
		(end 329.828144 -252.261624)
		(width 0.0889)
		(layer "In4.Cu")
		(net "M_D_CPU0_SA_CS_N<1>")
	)
	(segment
		(start 330.394056 -252.261624)
		(end 330.402438 -252.256798)
		(width 0.0889)
		(layer "In4.Cu")
		(net "M_D_CPU0_SA_CS_N<1>")
	)
	(segment
		(start 281.060906 -247.059958)
		(end 285.096966 -247.059958)
		(width 0.14478)
		(layer "In4.Cu")
		(net "M_D_CPU0_SA_CS_N<1>")
	)
	(segment
		(start 321.166744 -251.4981)
		(end 321.805554 -252.13691)
		(width 0.14478)
		(layer "In4.Cu")
		(net "M_D_CPU0_SA_CS_N<1>")
	)
	(arc
		(start 330.768198 -252.261624)
		(mid 331.051154 -252.337801)
		(end 331.33411 -252.261624)
		(width 0.0889)
		(layer "In4.Cu")
		(net "M_D_CPU0_SA_CS_N<1>")
	)
	(arc
		(start 325.915274 -252.212856)
		(mid 325.994123 -252.228965)
		(end 326.067674 -252.261624)
		(width 0.0889)
		(layer "In4.Cu")
		(net "M_D_CPU0_SA_CS_N<1>")
	)
	(arc
		(start 339.228176 -252.261624)
		(mid 339.511132 -252.337801)
		(end 339.794088 -252.261624)
		(width 0.0889)
		(layer "In4.Cu")
		(net "M_D_CPU0_SA_CS_N<1>")
	)
	(arc
		(start 329.454002 -252.261624)
		(mid 329.636253 -252.211274)
		(end 329.819762 -252.256798)
		(width 0.0889)
		(layer "In4.Cu")
		(net "M_D_CPU0_SA_CS_N<1>")
	)
	(arc
		(start 331.708252 -252.261624)
		(mid 331.991208 -252.337801)
		(end 332.274164 -252.261624)
		(width 0.0889)
		(layer "In4.Cu")
		(net "M_D_CPU0_SA_CS_N<1>")
	)
	(arc
		(start 334.154018 -252.261624)
		(mid 334.336269 -252.211274)
		(end 334.519778 -252.256798)
		(width 0.0889)
		(layer "In4.Cu")
		(net "M_D_CPU0_SA_CS_N<1>")
	)
	(arc
		(start 337.91398 -252.261624)
		(mid 338.096231 -252.211274)
		(end 338.27974 -252.256798)
		(width 0.0889)
		(layer "In4.Cu")
		(net "M_D_CPU0_SA_CS_N<1>")
	)
	(arc
		(start 326.067674 -252.261624)
		(mid 326.341529 -252.337974)
		(end 326.617838 -252.271022)
		(width 0.0889)
		(layer "In4.Cu")
		(net "M_D_CPU0_SA_CS_N<1>")
	)
	(arc
		(start 336.408268 -252.261624)
		(mid 336.691224 -252.337801)
		(end 336.97418 -252.261624)
		(width 0.0889)
		(layer "In4.Cu")
		(net "M_D_CPU0_SA_CS_N<1>")
	)
	(arc
		(start 336.042508 -252.256798)
		(mid 336.226016 -252.211304)
		(end 336.408268 -252.261624)
		(width 0.0889)
		(layer "In4.Cu")
		(net "M_D_CPU0_SA_CS_N<1>")
	)
	(arc
		(start 333.588106 -252.261624)
		(mid 333.871062 -252.337801)
		(end 334.154018 -252.261624)
		(width 0.0889)
		(layer "In4.Cu")
		(net "M_D_CPU0_SA_CS_N<1>")
	)
	(arc
		(start 338.288122 -252.261624)
		(mid 338.571078 -252.337801)
		(end 338.854034 -252.261624)
		(width 0.0889)
		(layer "In4.Cu")
		(net "M_D_CPU0_SA_CS_N<1>")
	)
	(arc
		(start 332.648052 -252.261624)
		(mid 332.931008 -252.337801)
		(end 333.213964 -252.261624)
		(width 0.0889)
		(layer "In4.Cu")
		(net "M_D_CPU0_SA_CS_N<1>")
	)
	(arc
		(start 326.649842 -252.25248)
		(mid 326.829824 -252.21138)
		(end 327.007474 -252.261624)
		(width 0.0889)
		(layer "In4.Cu")
		(net "M_D_CPU0_SA_CS_N<1>")
	)
	(arc
		(start 335.468214 -252.261624)
		(mid 335.75117 -252.337801)
		(end 336.034126 -252.261624)
		(width 0.0889)
		(layer "In4.Cu")
		(net "M_D_CPU0_SA_CS_N<1>")
	)
	(arc
		(start 332.274164 -252.261624)
		(mid 332.461108 -252.211369)
		(end 332.648052 -252.261624)
		(width 0.0889)
		(layer "In4.Cu")
		(net "M_D_CPU0_SA_CS_N<1>")
	)
	(arc
		(start 331.342492 -252.256798)
		(mid 331.526 -252.211304)
		(end 331.708252 -252.261624)
		(width 0.0889)
		(layer "In4.Cu")
		(net "M_D_CPU0_SA_CS_N<1>")
	)
	(arc
		(start 338.862416 -252.256798)
		(mid 339.045924 -252.211304)
		(end 339.228176 -252.261624)
		(width 0.0889)
		(layer "In4.Cu")
		(net "M_D_CPU0_SA_CS_N<1>")
	)
	(arc
		(start 328.88809 -252.261624)
		(mid 329.171046 -252.337801)
		(end 329.454002 -252.261624)
		(width 0.0889)
		(layer "In4.Cu")
		(net "M_D_CPU0_SA_CS_N<1>")
	)
	(arc
		(start 339.80247 -252.256798)
		(mid 339.95534 -252.212157)
		(end 340.112858 -252.235462)
		(width 0.0889)
		(layer "In4.Cu")
		(net "M_D_CPU0_SA_CS_N<1>")
	)
	(arc
		(start 327.94829 -252.261624)
		(mid 328.231246 -252.337801)
		(end 328.514202 -252.261624)
		(width 0.0889)
		(layer "In4.Cu")
		(net "M_D_CPU0_SA_CS_N<1>")
	)
	(arc
		(start 327.017888 -252.26772)
		(mid 327.296574 -252.33794)
		(end 327.57364 -252.261624)
		(width 0.0889)
		(layer "In4.Cu")
		(net "M_D_CPU0_SA_CS_N<1>")
	)
	(arc
		(start 336.97418 -252.261624)
		(mid 337.161124 -252.211369)
		(end 337.348068 -252.261624)
		(width 0.0889)
		(layer "In4.Cu")
		(net "M_D_CPU0_SA_CS_N<1>")
	)
	(arc
		(start 334.52816 -252.261624)
		(mid 334.811116 -252.337801)
		(end 335.094072 -252.261624)
		(width 0.0889)
		(layer "In4.Cu")
		(net "M_D_CPU0_SA_CS_N<1>")
	)
	(arc
		(start 333.213964 -252.261624)
		(mid 333.396215 -252.211274)
		(end 333.579724 -252.256798)
		(width 0.0889)
		(layer "In4.Cu")
		(net "M_D_CPU0_SA_CS_N<1>")
	)
	(arc
		(start 328.514202 -252.261624)
		(mid 328.701146 -252.211369)
		(end 328.88809 -252.261624)
		(width 0.0889)
		(layer "In4.Cu")
		(net "M_D_CPU0_SA_CS_N<1>")
	)
	(arc
		(start 329.828144 -252.261624)
		(mid 330.1111 -252.337801)
		(end 330.394056 -252.261624)
		(width 0.0889)
		(layer "In4.Cu")
		(net "M_D_CPU0_SA_CS_N<1>")
	)
	(arc
		(start 327.57364 -252.261624)
		(mid 327.756145 -252.211147)
		(end 327.939908 -252.256798)
		(width 0.0889)
		(layer "In4.Cu")
		(net "M_D_CPU0_SA_CS_N<1>")
	)
	(arc
		(start 335.102454 -252.256798)
		(mid 335.285962 -252.211304)
		(end 335.468214 -252.261624)
		(width 0.0889)
		(layer "In4.Cu")
		(net "M_D_CPU0_SA_CS_N<1>")
	)
	(arc
		(start 330.402438 -252.256798)
		(mid 330.585946 -252.211304)
		(end 330.768198 -252.261624)
		(width 0.0889)
		(layer "In4.Cu")
		(net "M_D_CPU0_SA_CS_N<1>")
	)
	(arc
		(start 337.348068 -252.261624)
		(mid 337.631024 -252.337801)
		(end 337.91398 -252.261624)
		(width 0.0889)
		(layer "In4.Cu")
		(net "M_D_CPU0_SA_CS_N<1>")
	)
	(segment
		(start 339.03793 -252.040136)
		(end 338.571078 -251.774198)
		(width 0.10668)
		(layer "F.Cu")
		(net "M_D_CPU0_SA_CS_N<0>")
	)
	(segment
		(start 289.160458 -247.910096)
		(end 289.323526 -248.073164)
		(width 0.14478)
		(layer "In4.Cu")
		(net "M_D_CPU0_SA_CS_N<0>")
	)
	(segment
		(start 297.619674 -247.910096)
		(end 297.850052 -247.910096)
		(width 0.14478)
		(layer "In4.Cu")
		(net "M_D_CPU0_SA_CS_N<0>")
	)
	(segment
		(start 325.202296 -251.528072)
		(end 325.880222 -251.528072)
		(width 0.0889)
		(layer "In4.Cu")
		(net "M_D_CPU0_SA_CS_N<0>")
	)
	(segment
		(start 338.702904 -251.425456)
		(end 338.725256 -251.508768)
		(width 0.0889)
		(layer "In4.Cu")
		(net "M_D_CPU0_SA_CS_N<0>")
	)
	(segment
		(start 301.549562 -248.140982)
		(end 301.549562 -248.073164)
		(width 0.14478)
		(layer "In4.Cu")
		(net "M_D_CPU0_SA_CS_N<0>")
	)
	(segment
		(start 290.993068 -248.140982)
		(end 290.993068 -248.073164)
		(width 0.14478)
		(layer "In4.Cu")
		(net "M_D_CPU0_SA_CS_N<0>")
	)
	(segment
		(start 296.900092 -248.133362)
		(end 297.06316 -248.29643)
		(width 0.14478)
		(layer "In4.Cu")
		(net "M_D_CPU0_SA_CS_N<0>")
	)
	(segment
		(start 300.82998 -247.910096)
		(end 300.993048 -248.073164)
		(width 0.14478)
		(layer "In4.Cu")
		(net "M_D_CPU0_SA_CS_N<0>")
	)
	(segment
		(start 296.900092 -248.073164)
		(end 296.900092 -248.133362)
		(width 0.14478)
		(layer "In4.Cu")
		(net "M_D_CPU0_SA_CS_N<0>")
	)
	(segment
		(start 301.549562 -248.073164)
		(end 301.71263 -247.910096)
		(width 0.14478)
		(layer "In4.Cu")
		(net "M_D_CPU0_SA_CS_N<0>")
	)
	(segment
		(start 289.88004 -248.140982)
		(end 289.88004 -248.073164)
		(width 0.14478)
		(layer "In4.Cu")
		(net "M_D_CPU0_SA_CS_N<0>")
	)
	(segment
		(start 332.16977 -251.446792)
		(end 332.178152 -251.451618)
		(width 0.0889)
		(layer "In4.Cu")
		(net "M_D_CPU0_SA_CS_N<0>")
	)
	(segment
		(start 324.010274 -251.59335)
		(end 325.137018 -251.59335)
		(width 0.0889)
		(layer "In4.Cu")
		(net "M_D_CPU0_SA_CS_N<0>")
	)
	(segment
		(start 337.44408 -251.451618)
		(end 337.452462 -251.446792)
		(width 0.0889)
		(layer "In4.Cu")
		(net "M_D_CPU0_SA_CS_N<0>")
	)
	(segment
		(start 291.156136 -247.910096)
		(end 293.661846 -247.910096)
		(width 0.14478)
		(layer "In4.Cu")
		(net "M_D_CPU0_SA_CS_N<0>")
	)
	(segment
		(start 284.736032 -245.785132)
		(end 286.860996 -247.910096)
		(width 0.14478)
		(layer "In4.Cu")
		(net "M_D_CPU0_SA_CS_N<0>")
	)
	(segment
		(start 338.725256 -251.508768)
		(end 338.571078 -251.774198)
		(width 0.0889)
		(layer "In4.Cu")
		(net "M_D_CPU0_SA_CS_N<0>")
	)
	(segment
		(start 298.01312 -248.073164)
		(end 298.01312 -248.133362)
		(width 0.14478)
		(layer "In4.Cu")
		(net "M_D_CPU0_SA_CS_N<0>")
	)
	(segment
		(start 290.83 -248.30405)
		(end 290.993068 -248.140982)
		(width 0.14478)
		(layer "In4.Cu")
		(net "M_D_CPU0_SA_CS_N<0>")
	)
	(segment
		(start 298.176188 -248.29643)
		(end 298.406566 -248.29643)
		(width 0.14478)
		(layer "In4.Cu")
		(net "M_D_CPU0_SA_CS_N<0>")
	)
	(segment
		(start 290.436554 -248.140982)
		(end 290.599622 -248.30405)
		(width 0.14478)
		(layer "In4.Cu")
		(net "M_D_CPU0_SA_CS_N<0>")
	)
	(segment
		(start 307.606446 -247.910096)
		(end 310.74487 -251.04852)
		(width 0.14478)
		(layer "In4.Cu")
		(net "M_D_CPU0_SA_CS_N<0>")
	)
	(segment
		(start 338.384134 -251.451618)
		(end 338.392516 -251.446792)
		(width 0.0889)
		(layer "In4.Cu")
		(net "M_D_CPU0_SA_CS_N<0>")
	)
	(segment
		(start 289.323526 -248.073164)
		(end 289.323526 -248.140982)
		(width 0.14478)
		(layer "In4.Cu")
		(net "M_D_CPU0_SA_CS_N<0>")
	)
	(segment
		(start 298.569634 -248.133362)
		(end 298.569634 -248.073164)
		(width 0.14478)
		(layer "In4.Cu")
		(net "M_D_CPU0_SA_CS_N<0>")
	)
	(segment
		(start 297.850052 -247.910096)
		(end 298.01312 -248.073164)
		(width 0.14478)
		(layer "In4.Cu")
		(net "M_D_CPU0_SA_CS_N<0>")
	)
	(segment
		(start 293.824914 -248.140982)
		(end 293.987982 -248.30405)
		(width 0.14478)
		(layer "In4.Cu")
		(net "M_D_CPU0_SA_CS_N<0>")
	)
	(segment
		(start 335.929732 -251.446792)
		(end 335.938114 -251.451618)
		(width 0.0889)
		(layer "In4.Cu")
		(net "M_D_CPU0_SA_CS_N<0>")
	)
	(segment
		(start 290.273486 -247.910096)
		(end 290.436554 -248.073164)
		(width 0.14478)
		(layer "In4.Cu")
		(net "M_D_CPU0_SA_CS_N<0>")
	)
	(segment
		(start 289.323526 -248.140982)
		(end 289.486594 -248.30405)
		(width 0.14478)
		(layer "In4.Cu")
		(net "M_D_CPU0_SA_CS_N<0>")
	)
	(segment
		(start 290.436554 -248.073164)
		(end 290.436554 -248.140982)
		(width 0.14478)
		(layer "In4.Cu")
		(net "M_D_CPU0_SA_CS_N<0>")
	)
	(segment
		(start 286.860996 -247.910096)
		(end 289.160458 -247.910096)
		(width 0.14478)
		(layer "In4.Cu")
		(net "M_D_CPU0_SA_CS_N<0>")
	)
	(segment
		(start 333.684118 -251.451618)
		(end 333.6925 -251.446792)
		(width 0.0889)
		(layer "In4.Cu")
		(net "M_D_CPU0_SA_CS_N<0>")
	)
	(segment
		(start 289.88004 -248.073164)
		(end 290.043108 -247.910096)
		(width 0.14478)
		(layer "In4.Cu")
		(net "M_D_CPU0_SA_CS_N<0>")
	)
	(segment
		(start 298.01312 -248.133362)
		(end 298.176188 -248.29643)
		(width 0.14478)
		(layer "In4.Cu")
		(net "M_D_CPU0_SA_CS_N<0>")
	)
	(segment
		(start 326.526398 -251.44476)
		(end 326.538082 -251.451618)
		(width 0.0889)
		(layer "In4.Cu")
		(net "M_D_CPU0_SA_CS_N<0>")
	)
	(segment
		(start 294.381428 -248.073164)
		(end 294.544496 -247.910096)
		(width 0.14478)
		(layer "In4.Cu")
		(net "M_D_CPU0_SA_CS_N<0>")
	)
	(segment
		(start 336.869786 -251.446792)
		(end 336.878168 -251.451618)
		(width 0.0889)
		(layer "In4.Cu")
		(net "M_D_CPU0_SA_CS_N<0>")
	)
	(segment
		(start 328.409808 -251.446792)
		(end 328.41819 -251.451618)
		(width 0.0889)
		(layer "In4.Cu")
		(net "M_D_CPU0_SA_CS_N<0>")
	)
	(segment
		(start 301.156116 -248.30405)
		(end 301.386494 -248.30405)
		(width 0.14478)
		(layer "In4.Cu")
		(net "M_D_CPU0_SA_CS_N<0>")
	)
	(segment
		(start 290.599622 -248.30405)
		(end 290.83 -248.30405)
		(width 0.14478)
		(layer "In4.Cu")
		(net "M_D_CPU0_SA_CS_N<0>")
	)
	(segment
		(start 300.993048 -248.140982)
		(end 301.156116 -248.30405)
		(width 0.14478)
		(layer "In4.Cu")
		(net "M_D_CPU0_SA_CS_N<0>")
	)
	(segment
		(start 289.716972 -248.30405)
		(end 289.88004 -248.140982)
		(width 0.14478)
		(layer "In4.Cu")
		(net "M_D_CPU0_SA_CS_N<0>")
	)
	(segment
		(start 289.486594 -248.30405)
		(end 289.716972 -248.30405)
		(width 0.14478)
		(layer "In4.Cu")
		(net "M_D_CPU0_SA_CS_N<0>")
	)
	(segment
		(start 290.993068 -248.073164)
		(end 291.156136 -247.910096)
		(width 0.14478)
		(layer "In4.Cu")
		(net "M_D_CPU0_SA_CS_N<0>")
	)
	(segment
		(start 301.386494 -248.30405)
		(end 301.549562 -248.140982)
		(width 0.14478)
		(layer "In4.Cu")
		(net "M_D_CPU0_SA_CS_N<0>")
	)
	(segment
		(start 332.744064 -251.451618)
		(end 332.752446 -251.446792)
		(width 0.0889)
		(layer "In4.Cu")
		(net "M_D_CPU0_SA_CS_N<0>")
	)
	(segment
		(start 321.905122 -251.59335)
		(end 324.010274 -251.59335)
		(width 0.14478)
		(layer "In4.Cu")
		(net "M_D_CPU0_SA_CS_N<0>")
	)
	(segment
		(start 293.824914 -248.073164)
		(end 293.824914 -248.140982)
		(width 0.14478)
		(layer "In4.Cu")
		(net "M_D_CPU0_SA_CS_N<0>")
	)
	(segment
		(start 296.737024 -247.910096)
		(end 296.900092 -248.073164)
		(width 0.14478)
		(layer "In4.Cu")
		(net "M_D_CPU0_SA_CS_N<0>")
	)
	(segment
		(start 294.21836 -248.30405)
		(end 294.381428 -248.140982)
		(width 0.14478)
		(layer "In4.Cu")
		(net "M_D_CPU0_SA_CS_N<0>")
	)
	(segment
		(start 328.033634 -251.457714)
		(end 328.044048 -251.451618)
		(width 0.0889)
		(layer "In4.Cu")
		(net "M_D_CPU0_SA_CS_N<0>")
	)
	(segment
		(start 297.293538 -248.29643)
		(end 297.456606 -248.133362)
		(width 0.14478)
		(layer "In4.Cu")
		(net "M_D_CPU0_SA_CS_N<0>")
	)
	(segment
		(start 293.987982 -248.30405)
		(end 294.21836 -248.30405)
		(width 0.14478)
		(layer "In4.Cu")
		(net "M_D_CPU0_SA_CS_N<0>")
	)
	(segment
		(start 300.993048 -248.073164)
		(end 300.993048 -248.140982)
		(width 0.14478)
		(layer "In4.Cu")
		(net "M_D_CPU0_SA_CS_N<0>")
	)
	(segment
		(start 290.043108 -247.910096)
		(end 290.273486 -247.910096)
		(width 0.14478)
		(layer "In4.Cu")
		(net "M_D_CPU0_SA_CS_N<0>")
	)
	(segment
		(start 294.381428 -248.140982)
		(end 294.381428 -248.073164)
		(width 0.14478)
		(layer "In4.Cu")
		(net "M_D_CPU0_SA_CS_N<0>")
	)
	(segment
		(start 297.456606 -248.073164)
		(end 297.619674 -247.910096)
		(width 0.14478)
		(layer "In4.Cu")
		(net "M_D_CPU0_SA_CS_N<0>")
	)
	(segment
		(start 327.093326 -251.457714)
		(end 327.10374 -251.451618)
		(width 0.0889)
		(layer "In4.Cu")
		(net "M_D_CPU0_SA_CS_N<0>")
	)
	(segment
		(start 297.456606 -248.133362)
		(end 297.456606 -248.073164)
		(width 0.14478)
		(layer "In4.Cu")
		(net "M_D_CPU0_SA_CS_N<0>")
	)
	(segment
		(start 298.732702 -247.910096)
		(end 300.82998 -247.910096)
		(width 0.14478)
		(layer "In4.Cu")
		(net "M_D_CPU0_SA_CS_N<0>")
	)
	(segment
		(start 331.229716 -251.446792)
		(end 331.238098 -251.451618)
		(width 0.0889)
		(layer "In4.Cu")
		(net "M_D_CPU0_SA_CS_N<0>")
	)
	(segment
		(start 321.360292 -251.04852)
		(end 321.905122 -251.59335)
		(width 0.14478)
		(layer "In4.Cu")
		(net "M_D_CPU0_SA_CS_N<0>")
	)
	(segment
		(start 327.10374 -251.451618)
		(end 327.118218 -251.443236)
		(width 0.0889)
		(layer "In4.Cu")
		(net "M_D_CPU0_SA_CS_N<0>")
	)
	(segment
		(start 325.137018 -251.59335)
		(end 325.202296 -251.528072)
		(width 0.0889)
		(layer "In4.Cu")
		(net "M_D_CPU0_SA_CS_N<0>")
	)
	(segment
		(start 293.661846 -247.910096)
		(end 293.824914 -248.073164)
		(width 0.14478)
		(layer "In4.Cu")
		(net "M_D_CPU0_SA_CS_N<0>")
	)
	(segment
		(start 310.74487 -251.04852)
		(end 321.360292 -251.04852)
		(width 0.14478)
		(layer "In4.Cu")
		(net "M_D_CPU0_SA_CS_N<0>")
	)
	(segment
		(start 328.984102 -251.451618)
		(end 328.992484 -251.446792)
		(width 0.0889)
		(layer "In4.Cu")
		(net "M_D_CPU0_SA_CS_N<0>")
	)
	(segment
		(start 294.544496 -247.910096)
		(end 296.737024 -247.910096)
		(width 0.14478)
		(layer "In4.Cu")
		(net "M_D_CPU0_SA_CS_N<0>")
	)
	(segment
		(start 297.06316 -248.29643)
		(end 297.293538 -248.29643)
		(width 0.14478)
		(layer "In4.Cu")
		(net "M_D_CPU0_SA_CS_N<0>")
	)
	(segment
		(start 301.71263 -247.910096)
		(end 307.606446 -247.910096)
		(width 0.14478)
		(layer "In4.Cu")
		(net "M_D_CPU0_SA_CS_N<0>")
	)
	(segment
		(start 298.406566 -248.29643)
		(end 298.569634 -248.133362)
		(width 0.14478)
		(layer "In4.Cu")
		(net "M_D_CPU0_SA_CS_N<0>")
	)
	(segment
		(start 298.569634 -248.073164)
		(end 298.732702 -247.910096)
		(width 0.14478)
		(layer "In4.Cu")
		(net "M_D_CPU0_SA_CS_N<0>")
	)
	(arc
		(start 331.238098 -251.451618)
		(mid 331.521054 -251.527795)
		(end 331.80401 -251.451618)
		(width 0.0889)
		(layer "In4.Cu")
		(net "M_D_CPU0_SA_CS_N<0>")
	)
	(arc
		(start 332.752446 -251.446792)
		(mid 332.935954 -251.401298)
		(end 333.118206 -251.451618)
		(width 0.0889)
		(layer "In4.Cu")
		(net "M_D_CPU0_SA_CS_N<0>")
	)
	(arc
		(start 329.358244 -251.451618)
		(mid 329.6412 -251.527795)
		(end 329.924156 -251.451618)
		(width 0.0889)
		(layer "In4.Cu")
		(net "M_D_CPU0_SA_CS_N<0>")
	)
	(arc
		(start 334.624172 -251.451618)
		(mid 334.811116 -251.401363)
		(end 334.99806 -251.451618)
		(width 0.0889)
		(layer "In4.Cu")
		(net "M_D_CPU0_SA_CS_N<0>")
	)
	(arc
		(start 332.178152 -251.451618)
		(mid 332.461108 -251.527795)
		(end 332.744064 -251.451618)
		(width 0.0889)
		(layer "In4.Cu")
		(net "M_D_CPU0_SA_CS_N<0>")
	)
	(arc
		(start 334.99806 -251.451618)
		(mid 335.281016 -251.527795)
		(end 335.563972 -251.451618)
		(width 0.0889)
		(layer "In4.Cu")
		(net "M_D_CPU0_SA_CS_N<0>")
	)
	(arc
		(start 337.818222 -251.451618)
		(mid 338.101178 -251.527795)
		(end 338.384134 -251.451618)
		(width 0.0889)
		(layer "In4.Cu")
		(net "M_D_CPU0_SA_CS_N<0>")
	)
	(arc
		(start 334.05826 -251.451618)
		(mid 334.341216 -251.527795)
		(end 334.624172 -251.451618)
		(width 0.0889)
		(layer "In4.Cu")
		(net "M_D_CPU0_SA_CS_N<0>")
	)
	(arc
		(start 337.452462 -251.446792)
		(mid 337.63597 -251.401298)
		(end 337.818222 -251.451618)
		(width 0.0889)
		(layer "In4.Cu")
		(net "M_D_CPU0_SA_CS_N<0>")
	)
	(arc
		(start 325.880222 -251.528072)
		(mid 326.027026 -251.508636)
		(end 326.163686 -251.451618)
		(width 0.0889)
		(layer "In4.Cu")
		(net "M_D_CPU0_SA_CS_N<0>")
	)
	(arc
		(start 330.863956 -251.451618)
		(mid 331.046207 -251.401268)
		(end 331.229716 -251.446792)
		(width 0.0889)
		(layer "In4.Cu")
		(net "M_D_CPU0_SA_CS_N<0>")
	)
	(arc
		(start 331.80401 -251.451618)
		(mid 331.986261 -251.401268)
		(end 332.16977 -251.446792)
		(width 0.0889)
		(layer "In4.Cu")
		(net "M_D_CPU0_SA_CS_N<0>")
	)
	(arc
		(start 338.392516 -251.446792)
		(mid 338.545386 -251.402151)
		(end 338.702904 -251.425456)
		(width 0.0889)
		(layer "In4.Cu")
		(net "M_D_CPU0_SA_CS_N<0>")
	)
	(arc
		(start 330.298044 -251.451618)
		(mid 330.581 -251.527795)
		(end 330.863956 -251.451618)
		(width 0.0889)
		(layer "In4.Cu")
		(net "M_D_CPU0_SA_CS_N<0>")
	)
	(arc
		(start 335.563972 -251.451618)
		(mid 335.746223 -251.401268)
		(end 335.929732 -251.446792)
		(width 0.0889)
		(layer "In4.Cu")
		(net "M_D_CPU0_SA_CS_N<0>")
	)
	(arc
		(start 335.938114 -251.451618)
		(mid 336.22107 -251.527795)
		(end 336.504026 -251.451618)
		(width 0.0889)
		(layer "In4.Cu")
		(net "M_D_CPU0_SA_CS_N<0>")
	)
	(arc
		(start 328.41819 -251.451618)
		(mid 328.701146 -251.527795)
		(end 328.984102 -251.451618)
		(width 0.0889)
		(layer "In4.Cu")
		(net "M_D_CPU0_SA_CS_N<0>")
	)
	(arc
		(start 328.992484 -251.446792)
		(mid 329.175992 -251.401298)
		(end 329.358244 -251.451618)
		(width 0.0889)
		(layer "In4.Cu")
		(net "M_D_CPU0_SA_CS_N<0>")
	)
	(arc
		(start 326.163686 -251.451618)
		(mid 326.344144 -251.401174)
		(end 326.526398 -251.44476)
		(width 0.0889)
		(layer "In4.Cu")
		(net "M_D_CPU0_SA_CS_N<0>")
	)
	(arc
		(start 328.044048 -251.451618)
		(mid 328.226299 -251.401268)
		(end 328.409808 -251.446792)
		(width 0.0889)
		(layer "In4.Cu")
		(net "M_D_CPU0_SA_CS_N<0>")
	)
	(arc
		(start 329.924156 -251.451618)
		(mid 330.1111 -251.401363)
		(end 330.298044 -251.451618)
		(width 0.0889)
		(layer "In4.Cu")
		(net "M_D_CPU0_SA_CS_N<0>")
	)
	(arc
		(start 326.538082 -251.451618)
		(mid 326.814895 -251.527761)
		(end 327.093326 -251.457714)
		(width 0.0889)
		(layer "In4.Cu")
		(net "M_D_CPU0_SA_CS_N<0>")
	)
	(arc
		(start 327.118218 -251.443236)
		(mid 327.299126 -251.401214)
		(end 327.477882 -251.451618)
		(width 0.0889)
		(layer "In4.Cu")
		(net "M_D_CPU0_SA_CS_N<0>")
	)
	(arc
		(start 333.118206 -251.451618)
		(mid 333.401162 -251.527795)
		(end 333.684118 -251.451618)
		(width 0.0889)
		(layer "In4.Cu")
		(net "M_D_CPU0_SA_CS_N<0>")
	)
	(arc
		(start 333.6925 -251.446792)
		(mid 333.876008 -251.401298)
		(end 334.05826 -251.451618)
		(width 0.0889)
		(layer "In4.Cu")
		(net "M_D_CPU0_SA_CS_N<0>")
	)
	(arc
		(start 336.504026 -251.451618)
		(mid 336.686277 -251.401268)
		(end 336.869786 -251.446792)
		(width 0.0889)
		(layer "In4.Cu")
		(net "M_D_CPU0_SA_CS_N<0>")
	)
	(arc
		(start 336.878168 -251.451618)
		(mid 337.161124 -251.527795)
		(end 337.44408 -251.451618)
		(width 0.0889)
		(layer "In4.Cu")
		(net "M_D_CPU0_SA_CS_N<0>")
	)
	(arc
		(start 327.477882 -251.451618)
		(mid 327.754949 -251.527889)
		(end 328.033634 -251.457714)
		(width 0.0889)
		(layer "In4.Cu")
		(net "M_D_CPU0_SA_CS_N<0>")
	)
	(segment
		(start 340.447884 -249.610118)
		(end 339.981032 -249.34418)
		(width 0.10668)
		(layer "F.Cu")
		(net "M_D_CPU0_SA_CB<7>")
	)
	(segment
		(start 282.607258 -243.660168)
		(end 282.837636 -243.660168)
		(width 0.14478)
		(layer "In4.Cu")
		(net "M_D_CPU0_SA_CB<7>")
	)
	(segment
		(start 340.112858 -248.995438)
		(end 340.13521 -249.07875)
		(width 0.0889)
		(layer "In4.Cu")
		(net "M_D_CPU0_SA_CB<7>")
	)
	(segment
		(start 303.601374 -243.660168)
		(end 305.055778 -245.114572)
		(width 0.14478)
		(layer "In4.Cu")
		(net "M_D_CPU0_SA_CB<7>")
	)
	(segment
		(start 324.618858 -249.201432)
		(end 325.025258 -249.201432)
		(width 0.0889)
		(layer "In4.Cu")
		(net "M_D_CPU0_SA_CB<7>")
	)
	(segment
		(start 324.36054 -249.45975)
		(end 324.618858 -249.201432)
		(width 0.0889)
		(layer "In4.Cu")
		(net "M_D_CPU0_SA_CB<7>")
	)
	(segment
		(start 327.007474 -249.0216)
		(end 327.017888 -249.027696)
		(width 0.0889)
		(layer "In4.Cu")
		(net "M_D_CPU0_SA_CB<7>")
	)
	(segment
		(start 283.163772 -242.960652)
		(end 283.39415 -242.960652)
		(width 0.14478)
		(layer "In4.Cu")
		(net "M_D_CPU0_SA_CB<7>")
	)
	(segment
		(start 282.050744 -242.44173)
		(end 282.281122 -242.44173)
		(width 0.14478)
		(layer "In4.Cu")
		(net "M_D_CPU0_SA_CB<7>")
	)
	(segment
		(start 325.693278 -249.0216)
		(end 325.704962 -249.014742)
		(width 0.0889)
		(layer "In4.Cu")
		(net "M_D_CPU0_SA_CB<7>")
	)
	(segment
		(start 282.281122 -242.44173)
		(end 282.44419 -242.604798)
		(width 0.14478)
		(layer "In4.Cu")
		(net "M_D_CPU0_SA_CB<7>")
	)
	(segment
		(start 334.519778 -249.016774)
		(end 334.52816 -249.0216)
		(width 0.0889)
		(layer "In4.Cu")
		(net "M_D_CPU0_SA_CB<7>")
	)
	(segment
		(start 338.854034 -249.0216)
		(end 338.862416 -249.016774)
		(width 0.0889)
		(layer "In4.Cu")
		(net "M_D_CPU0_SA_CB<7>")
	)
	(segment
		(start 282.44419 -243.4971)
		(end 282.607258 -243.660168)
		(width 0.14478)
		(layer "In4.Cu")
		(net "M_D_CPU0_SA_CB<7>")
	)
	(segment
		(start 281.06116 -243.660168)
		(end 281.724608 -243.660168)
		(width 0.14478)
		(layer "In4.Cu")
		(net "M_D_CPU0_SA_CB<7>")
	)
	(segment
		(start 283.000704 -243.4971)
		(end 283.000704 -243.12372)
		(width 0.14478)
		(layer "In4.Cu")
		(net "M_D_CPU0_SA_CB<7>")
	)
	(segment
		(start 283.000704 -243.12372)
		(end 283.163772 -242.960652)
		(width 0.14478)
		(layer "In4.Cu")
		(net "M_D_CPU0_SA_CB<7>")
	)
	(segment
		(start 281.887676 -242.604798)
		(end 282.050744 -242.44173)
		(width 0.14478)
		(layer "In4.Cu")
		(net "M_D_CPU0_SA_CB<7>")
	)
	(segment
		(start 333.579724 -249.016774)
		(end 333.588106 -249.0216)
		(width 0.0889)
		(layer "In4.Cu")
		(net "M_D_CPU0_SA_CB<7>")
	)
	(segment
		(start 327.939908 -249.016774)
		(end 327.94829 -249.0216)
		(width 0.0889)
		(layer "In4.Cu")
		(net "M_D_CPU0_SA_CB<7>")
	)
	(segment
		(start 308.148228 -245.469664)
		(end 311.824624 -249.14606)
		(width 0.14478)
		(layer "In4.Cu")
		(net "M_D_CPU0_SA_CB<7>")
	)
	(segment
		(start 306.290218 -245.114572)
		(end 306.64531 -245.469664)
		(width 0.14478)
		(layer "In4.Cu")
		(net "M_D_CPU0_SA_CB<7>")
	)
	(segment
		(start 283.557218 -243.12372)
		(end 283.557218 -243.4971)
		(width 0.14478)
		(layer "In4.Cu")
		(net "M_D_CPU0_SA_CB<7>")
	)
	(segment
		(start 338.27974 -249.016774)
		(end 338.288122 -249.0216)
		(width 0.0889)
		(layer "In4.Cu")
		(net "M_D_CPU0_SA_CB<7>")
	)
	(segment
		(start 322.208144 -249.14606)
		(end 322.521834 -249.45975)
		(width 0.14478)
		(layer "In4.Cu")
		(net "M_D_CPU0_SA_CB<7>")
	)
	(segment
		(start 281.724608 -243.660168)
		(end 281.887676 -243.4971)
		(width 0.14478)
		(layer "In4.Cu")
		(net "M_D_CPU0_SA_CB<7>")
	)
	(segment
		(start 305.055778 -245.114572)
		(end 306.290218 -245.114572)
		(width 0.14478)
		(layer "In4.Cu")
		(net "M_D_CPU0_SA_CB<7>")
	)
	(segment
		(start 282.837636 -243.660168)
		(end 283.000704 -243.4971)
		(width 0.14478)
		(layer "In4.Cu")
		(net "M_D_CPU0_SA_CB<7>")
	)
	(segment
		(start 340.13521 -249.07875)
		(end 339.981032 -249.34418)
		(width 0.0889)
		(layer "In4.Cu")
		(net "M_D_CPU0_SA_CB<7>")
	)
	(segment
		(start 306.64531 -245.469664)
		(end 308.148228 -245.469664)
		(width 0.14478)
		(layer "In4.Cu")
		(net "M_D_CPU0_SA_CB<7>")
	)
	(segment
		(start 326.617838 -249.030998)
		(end 326.633586 -249.021854)
		(width 0.0889)
		(layer "In4.Cu")
		(net "M_D_CPU0_SA_CB<7>")
	)
	(segment
		(start 330.394056 -249.0216)
		(end 330.402438 -249.016774)
		(width 0.0889)
		(layer "In4.Cu")
		(net "M_D_CPU0_SA_CB<7>")
	)
	(segment
		(start 335.094072 -249.0216)
		(end 335.102454 -249.016774)
		(width 0.0889)
		(layer "In4.Cu")
		(net "M_D_CPU0_SA_CB<7>")
	)
	(segment
		(start 336.034126 -249.0216)
		(end 336.042508 -249.016774)
		(width 0.0889)
		(layer "In4.Cu")
		(net "M_D_CPU0_SA_CB<7>")
	)
	(segment
		(start 283.39415 -242.960652)
		(end 283.557218 -243.12372)
		(width 0.14478)
		(layer "In4.Cu")
		(net "M_D_CPU0_SA_CB<7>")
	)
	(segment
		(start 322.521834 -249.45975)
		(end 323.880734 -249.45975)
		(width 0.14478)
		(layer "In4.Cu")
		(net "M_D_CPU0_SA_CB<7>")
	)
	(segment
		(start 329.819762 -249.016774)
		(end 329.828144 -249.0216)
		(width 0.0889)
		(layer "In4.Cu")
		(net "M_D_CPU0_SA_CB<7>")
	)
	(segment
		(start 282.44419 -242.604798)
		(end 282.44419 -243.4971)
		(width 0.14478)
		(layer "In4.Cu")
		(net "M_D_CPU0_SA_CB<7>")
	)
	(segment
		(start 280.635964 -243.234972)
		(end 281.06116 -243.660168)
		(width 0.14478)
		(layer "In4.Cu")
		(net "M_D_CPU0_SA_CB<7>")
	)
	(segment
		(start 283.557218 -243.4971)
		(end 283.720286 -243.660168)
		(width 0.14478)
		(layer "In4.Cu")
		(net "M_D_CPU0_SA_CB<7>")
	)
	(segment
		(start 281.887676 -243.4971)
		(end 281.887676 -242.604798)
		(width 0.14478)
		(layer "In4.Cu")
		(net "M_D_CPU0_SA_CB<7>")
	)
	(segment
		(start 283.720286 -243.660168)
		(end 303.601374 -243.660168)
		(width 0.14478)
		(layer "In4.Cu")
		(net "M_D_CPU0_SA_CB<7>")
	)
	(segment
		(start 311.824624 -249.14606)
		(end 322.208144 -249.14606)
		(width 0.14478)
		(layer "In4.Cu")
		(net "M_D_CPU0_SA_CB<7>")
	)
	(segment
		(start 331.33411 -249.0216)
		(end 331.342492 -249.016774)
		(width 0.0889)
		(layer "In4.Cu")
		(net "M_D_CPU0_SA_CB<7>")
	)
	(segment
		(start 339.794088 -249.0216)
		(end 339.80247 -249.016774)
		(width 0.0889)
		(layer "In4.Cu")
		(net "M_D_CPU0_SA_CB<7>")
	)
	(segment
		(start 326.633586 -249.021854)
		(end 326.649842 -249.012456)
		(width 0.0889)
		(layer "In4.Cu")
		(net "M_D_CPU0_SA_CB<7>")
	)
	(segment
		(start 323.880734 -249.45975)
		(end 324.36054 -249.45975)
		(width 0.0889)
		(layer "In4.Cu")
		(net "M_D_CPU0_SA_CB<7>")
	)
	(arc
		(start 329.828144 -249.0216)
		(mid 330.1111 -249.097777)
		(end 330.394056 -249.0216)
		(width 0.0889)
		(layer "In4.Cu")
		(net "M_D_CPU0_SA_CB<7>")
	)
	(arc
		(start 325.025258 -249.201432)
		(mid 325.371151 -249.155673)
		(end 325.693278 -249.0216)
		(width 0.0889)
		(layer "In4.Cu")
		(net "M_D_CPU0_SA_CB<7>")
	)
	(arc
		(start 332.648052 -249.0216)
		(mid 332.931008 -249.097777)
		(end 333.213964 -249.0216)
		(width 0.0889)
		(layer "In4.Cu")
		(net "M_D_CPU0_SA_CB<7>")
	)
	(arc
		(start 327.57364 -249.0216)
		(mid 327.756145 -248.971123)
		(end 327.939908 -249.016774)
		(width 0.0889)
		(layer "In4.Cu")
		(net "M_D_CPU0_SA_CB<7>")
	)
	(arc
		(start 331.708252 -249.0216)
		(mid 331.991208 -249.097777)
		(end 332.274164 -249.0216)
		(width 0.0889)
		(layer "In4.Cu")
		(net "M_D_CPU0_SA_CB<7>")
	)
	(arc
		(start 336.408268 -249.0216)
		(mid 336.691224 -249.097777)
		(end 336.97418 -249.0216)
		(width 0.0889)
		(layer "In4.Cu")
		(net "M_D_CPU0_SA_CB<7>")
	)
	(arc
		(start 325.704962 -249.014742)
		(mid 325.887217 -248.971089)
		(end 326.067674 -249.0216)
		(width 0.0889)
		(layer "In4.Cu")
		(net "M_D_CPU0_SA_CB<7>")
	)
	(arc
		(start 332.274164 -249.0216)
		(mid 332.461108 -248.971345)
		(end 332.648052 -249.0216)
		(width 0.0889)
		(layer "In4.Cu")
		(net "M_D_CPU0_SA_CB<7>")
	)
	(arc
		(start 334.52816 -249.0216)
		(mid 334.811116 -249.097777)
		(end 335.094072 -249.0216)
		(width 0.0889)
		(layer "In4.Cu")
		(net "M_D_CPU0_SA_CB<7>")
	)
	(arc
		(start 333.213964 -249.0216)
		(mid 333.396215 -248.97125)
		(end 333.579724 -249.016774)
		(width 0.0889)
		(layer "In4.Cu")
		(net "M_D_CPU0_SA_CB<7>")
	)
	(arc
		(start 334.154018 -249.0216)
		(mid 334.336269 -248.97125)
		(end 334.519778 -249.016774)
		(width 0.0889)
		(layer "In4.Cu")
		(net "M_D_CPU0_SA_CB<7>")
	)
	(arc
		(start 336.97418 -249.0216)
		(mid 337.161124 -248.971345)
		(end 337.348068 -249.0216)
		(width 0.0889)
		(layer "In4.Cu")
		(net "M_D_CPU0_SA_CB<7>")
	)
	(arc
		(start 338.862416 -249.016774)
		(mid 339.045924 -248.97128)
		(end 339.228176 -249.0216)
		(width 0.0889)
		(layer "In4.Cu")
		(net "M_D_CPU0_SA_CB<7>")
	)
	(arc
		(start 339.80247 -249.016774)
		(mid 339.95534 -248.972133)
		(end 340.112858 -248.995438)
		(width 0.0889)
		(layer "In4.Cu")
		(net "M_D_CPU0_SA_CB<7>")
	)
	(arc
		(start 328.514202 -249.0216)
		(mid 328.701146 -248.971345)
		(end 328.88809 -249.0216)
		(width 0.0889)
		(layer "In4.Cu")
		(net "M_D_CPU0_SA_CB<7>")
	)
	(arc
		(start 335.468214 -249.0216)
		(mid 335.75117 -249.097777)
		(end 336.034126 -249.0216)
		(width 0.0889)
		(layer "In4.Cu")
		(net "M_D_CPU0_SA_CB<7>")
	)
	(arc
		(start 338.288122 -249.0216)
		(mid 338.571078 -249.097777)
		(end 338.854034 -249.0216)
		(width 0.0889)
		(layer "In4.Cu")
		(net "M_D_CPU0_SA_CB<7>")
	)
	(arc
		(start 328.88809 -249.0216)
		(mid 329.171046 -249.097777)
		(end 329.454002 -249.0216)
		(width 0.0889)
		(layer "In4.Cu")
		(net "M_D_CPU0_SA_CB<7>")
	)
	(arc
		(start 327.017888 -249.027696)
		(mid 327.296574 -249.097916)
		(end 327.57364 -249.0216)
		(width 0.0889)
		(layer "In4.Cu")
		(net "M_D_CPU0_SA_CB<7>")
	)
	(arc
		(start 329.454002 -249.0216)
		(mid 329.636253 -248.97125)
		(end 329.819762 -249.016774)
		(width 0.0889)
		(layer "In4.Cu")
		(net "M_D_CPU0_SA_CB<7>")
	)
	(arc
		(start 326.067674 -249.0216)
		(mid 326.341529 -249.09795)
		(end 326.617838 -249.030998)
		(width 0.0889)
		(layer "In4.Cu")
		(net "M_D_CPU0_SA_CB<7>")
	)
	(arc
		(start 331.342492 -249.016774)
		(mid 331.526 -248.97128)
		(end 331.708252 -249.0216)
		(width 0.0889)
		(layer "In4.Cu")
		(net "M_D_CPU0_SA_CB<7>")
	)
	(arc
		(start 336.042508 -249.016774)
		(mid 336.226016 -248.97128)
		(end 336.408268 -249.0216)
		(width 0.0889)
		(layer "In4.Cu")
		(net "M_D_CPU0_SA_CB<7>")
	)
	(arc
		(start 327.94829 -249.0216)
		(mid 328.231246 -249.097777)
		(end 328.514202 -249.0216)
		(width 0.0889)
		(layer "In4.Cu")
		(net "M_D_CPU0_SA_CB<7>")
	)
	(arc
		(start 337.348068 -249.0216)
		(mid 337.631024 -249.097777)
		(end 337.91398 -249.0216)
		(width 0.0889)
		(layer "In4.Cu")
		(net "M_D_CPU0_SA_CB<7>")
	)
	(arc
		(start 335.102454 -249.016774)
		(mid 335.285962 -248.97128)
		(end 335.468214 -249.0216)
		(width 0.0889)
		(layer "In4.Cu")
		(net "M_D_CPU0_SA_CB<7>")
	)
	(arc
		(start 330.768198 -249.0216)
		(mid 331.051154 -249.097777)
		(end 331.33411 -249.0216)
		(width 0.0889)
		(layer "In4.Cu")
		(net "M_D_CPU0_SA_CB<7>")
	)
	(arc
		(start 333.588106 -249.0216)
		(mid 333.871062 -249.097777)
		(end 334.154018 -249.0216)
		(width 0.0889)
		(layer "In4.Cu")
		(net "M_D_CPU0_SA_CB<7>")
	)
	(arc
		(start 330.402438 -249.016774)
		(mid 330.585946 -248.97128)
		(end 330.768198 -249.0216)
		(width 0.0889)
		(layer "In4.Cu")
		(net "M_D_CPU0_SA_CB<7>")
	)
	(arc
		(start 337.91398 -249.0216)
		(mid 338.096231 -248.97125)
		(end 338.27974 -249.016774)
		(width 0.0889)
		(layer "In4.Cu")
		(net "M_D_CPU0_SA_CB<7>")
	)
	(arc
		(start 326.649842 -249.012456)
		(mid 326.829824 -248.971356)
		(end 327.007474 -249.0216)
		(width 0.0889)
		(layer "In4.Cu")
		(net "M_D_CPU0_SA_CB<7>")
	)
	(arc
		(start 339.228176 -249.0216)
		(mid 339.511132 -249.097777)
		(end 339.794088 -249.0216)
		(width 0.0889)
		(layer "In4.Cu")
		(net "M_D_CPU0_SA_CB<7>")
	)
	(segment
		(start 339.03793 -248.800112)
		(end 338.571078 -248.534174)
		(width 0.10668)
		(layer "F.Cu")
		(net "M_D_CPU0_SA_CB<6>")
	)
	(segment
		(start 323.868034 -248.54281)
		(end 324.201536 -248.54281)
		(width 0.0889)
		(layer "In4.Cu")
		(net "M_D_CPU0_SA_CB<6>")
	)
	(segment
		(start 283.038296 -240.9825)
		(end 283.038296 -241.797078)
		(width 0.14478)
		(layer "In4.Cu")
		(net "M_D_CPU0_SA_CB<6>")
	)
	(segment
		(start 326.16521 -248.211848)
		(end 326.192642 -248.1961)
		(width 0.0889)
		(layer "In4.Cu")
		(net "M_D_CPU0_SA_CB<6>")
	)
	(segment
		(start 282.875228 -240.819432)
		(end 283.038296 -240.9825)
		(width 0.14478)
		(layer "In4.Cu")
		(net "M_D_CPU0_SA_CB<6>")
	)
	(segment
		(start 332.16977 -248.206768)
		(end 332.178152 -248.211594)
		(width 0.0889)
		(layer "In4.Cu")
		(net "M_D_CPU0_SA_CB<6>")
	)
	(segment
		(start 328.984102 -248.211594)
		(end 328.992484 -248.206768)
		(width 0.0889)
		(layer "In4.Cu")
		(net "M_D_CPU0_SA_CB<6>")
	)
	(segment
		(start 306.445666 -243.666772)
		(end 307.683916 -243.666772)
		(width 0.14478)
		(layer "In4.Cu")
		(net "M_D_CPU0_SA_CB<6>")
	)
	(segment
		(start 327.47966 -248.211848)
		(end 327.50125 -248.224294)
		(width 0.0889)
		(layer "In4.Cu")
		(net "M_D_CPU0_SA_CB<6>")
	)
	(segment
		(start 304.73904 -241.960146)
		(end 306.445666 -243.666772)
		(width 0.14478)
		(layer "In4.Cu")
		(net "M_D_CPU0_SA_CB<6>")
	)
	(segment
		(start 282.318714 -241.960146)
		(end 282.481782 -241.797078)
		(width 0.14478)
		(layer "In4.Cu")
		(net "M_D_CPU0_SA_CB<6>")
	)
	(segment
		(start 331.229716 -248.206768)
		(end 331.238098 -248.211594)
		(width 0.0889)
		(layer "In4.Cu")
		(net "M_D_CPU0_SA_CB<6>")
	)
	(segment
		(start 338.725002 -248.268744)
		(end 338.571078 -248.534174)
		(width 0.0889)
		(layer "In4.Cu")
		(net "M_D_CPU0_SA_CB<6>")
	)
	(segment
		(start 283.59481 -240.811558)
		(end 283.757878 -240.64849)
		(width 0.14478)
		(layer "In4.Cu")
		(net "M_D_CPU0_SA_CB<6>")
	)
	(segment
		(start 337.44408 -248.211594)
		(end 337.452462 -248.206768)
		(width 0.0889)
		(layer "In4.Cu")
		(net "M_D_CPU0_SA_CB<6>")
	)
	(segment
		(start 282.481782 -241.797078)
		(end 282.481782 -240.9825)
		(width 0.14478)
		(layer "In4.Cu")
		(net "M_D_CPU0_SA_CB<6>")
	)
	(segment
		(start 325.815452 -248.543572)
		(end 326.087994 -248.27103)
		(width 0.0889)
		(layer "In4.Cu")
		(net "M_D_CPU0_SA_CB<6>")
	)
	(segment
		(start 284.314392 -241.960146)
		(end 304.73904 -241.960146)
		(width 0.14478)
		(layer "In4.Cu")
		(net "M_D_CPU0_SA_CB<6>")
	)
	(segment
		(start 283.59481 -241.797078)
		(end 283.59481 -240.811558)
		(width 0.14478)
		(layer "In4.Cu")
		(net "M_D_CPU0_SA_CB<6>")
	)
	(segment
		(start 307.683916 -243.666772)
		(end 312.253884 -248.23674)
		(width 0.14478)
		(layer "In4.Cu")
		(net "M_D_CPU0_SA_CB<6>")
	)
	(segment
		(start 283.988256 -240.64849)
		(end 284.151324 -240.811558)
		(width 0.14478)
		(layer "In4.Cu")
		(net "M_D_CPU0_SA_CB<6>")
	)
	(segment
		(start 327.461372 -248.201434)
		(end 327.47966 -248.211848)
		(width 0.0889)
		(layer "In4.Cu")
		(net "M_D_CPU0_SA_CB<6>")
	)
	(segment
		(start 325.464678 -248.543572)
		(end 325.815452 -248.543572)
		(width 0.0889)
		(layer "In4.Cu")
		(net "M_D_CPU0_SA_CB<6>")
	)
	(segment
		(start 324.293738 -248.635012)
		(end 325.373238 -248.635012)
		(width 0.0889)
		(layer "In4.Cu")
		(net "M_D_CPU0_SA_CB<6>")
	)
	(segment
		(start 284.151324 -240.811558)
		(end 284.151324 -241.797078)
		(width 0.14478)
		(layer "In4.Cu")
		(net "M_D_CPU0_SA_CB<6>")
	)
	(segment
		(start 312.253884 -248.23674)
		(end 322.606924 -248.23674)
		(width 0.14478)
		(layer "In4.Cu")
		(net "M_D_CPU0_SA_CB<6>")
	)
	(segment
		(start 282.64485 -240.819432)
		(end 282.875228 -240.819432)
		(width 0.14478)
		(layer "In4.Cu")
		(net "M_D_CPU0_SA_CB<6>")
	)
	(segment
		(start 284.151324 -241.797078)
		(end 284.314392 -241.960146)
		(width 0.14478)
		(layer "In4.Cu")
		(net "M_D_CPU0_SA_CB<6>")
	)
	(segment
		(start 327.083166 -248.22531)
		(end 327.106534 -248.211594)
		(width 0.0889)
		(layer "In4.Cu")
		(net "M_D_CPU0_SA_CB<6>")
	)
	(segment
		(start 335.929732 -248.206768)
		(end 335.938114 -248.211594)
		(width 0.0889)
		(layer "In4.Cu")
		(net "M_D_CPU0_SA_CB<6>")
	)
	(segment
		(start 328.409808 -248.206768)
		(end 328.41819 -248.211594)
		(width 0.0889)
		(layer "In4.Cu")
		(net "M_D_CPU0_SA_CB<6>")
	)
	(segment
		(start 281.06116 -241.960146)
		(end 282.318714 -241.960146)
		(width 0.14478)
		(layer "In4.Cu")
		(net "M_D_CPU0_SA_CB<6>")
	)
	(segment
		(start 325.373238 -248.635012)
		(end 325.464678 -248.543572)
		(width 0.0889)
		(layer "In4.Cu")
		(net "M_D_CPU0_SA_CB<6>")
	)
	(segment
		(start 336.869786 -248.206768)
		(end 336.878168 -248.211594)
		(width 0.0889)
		(layer "In4.Cu")
		(net "M_D_CPU0_SA_CB<6>")
	)
	(segment
		(start 332.744064 -248.211594)
		(end 332.752446 -248.206768)
		(width 0.0889)
		(layer "In4.Cu")
		(net "M_D_CPU0_SA_CB<6>")
	)
	(segment
		(start 283.201364 -241.960146)
		(end 283.431742 -241.960146)
		(width 0.14478)
		(layer "In4.Cu")
		(net "M_D_CPU0_SA_CB<6>")
	)
	(segment
		(start 322.912994 -248.54281)
		(end 323.868034 -248.54281)
		(width 0.14478)
		(layer "In4.Cu")
		(net "M_D_CPU0_SA_CB<6>")
	)
	(segment
		(start 283.038296 -241.797078)
		(end 283.201364 -241.960146)
		(width 0.14478)
		(layer "In4.Cu")
		(net "M_D_CPU0_SA_CB<6>")
	)
	(segment
		(start 333.684118 -248.211594)
		(end 333.6925 -248.206768)
		(width 0.0889)
		(layer "In4.Cu")
		(net "M_D_CPU0_SA_CB<6>")
	)
	(segment
		(start 338.70265 -248.185432)
		(end 338.725002 -248.268744)
		(width 0.0889)
		(layer "In4.Cu")
		(net "M_D_CPU0_SA_CB<6>")
	)
	(segment
		(start 283.757878 -240.64849)
		(end 283.988256 -240.64849)
		(width 0.14478)
		(layer "In4.Cu")
		(net "M_D_CPU0_SA_CB<6>")
	)
	(segment
		(start 324.201536 -248.54281)
		(end 324.293738 -248.635012)
		(width 0.0889)
		(layer "In4.Cu")
		(net "M_D_CPU0_SA_CB<6>")
	)
	(segment
		(start 282.481782 -240.9825)
		(end 282.64485 -240.819432)
		(width 0.14478)
		(layer "In4.Cu")
		(net "M_D_CPU0_SA_CB<6>")
	)
	(segment
		(start 322.606924 -248.23674)
		(end 322.912994 -248.54281)
		(width 0.14478)
		(layer "In4.Cu")
		(net "M_D_CPU0_SA_CB<6>")
	)
	(segment
		(start 280.635964 -241.53495)
		(end 281.06116 -241.960146)
		(width 0.14478)
		(layer "In4.Cu")
		(net "M_D_CPU0_SA_CB<6>")
	)
	(segment
		(start 283.431742 -241.960146)
		(end 283.59481 -241.797078)
		(width 0.14478)
		(layer "In4.Cu")
		(net "M_D_CPU0_SA_CB<6>")
	)
	(arc
		(start 337.818222 -248.211594)
		(mid 338.101178 -248.287771)
		(end 338.384134 -248.211594)
		(width 0.0889)
		(layer "In4.Cu")
		(net "M_D_CPU0_SA_CB<6>")
	)
	(arc
		(start 326.087994 -248.27103)
		(mid 326.12465 -248.23889)
		(end 326.16521 -248.211848)
		(width 0.0889)
		(layer "In4.Cu")
		(net "M_D_CPU0_SA_CB<6>")
	)
	(arc
		(start 337.452462 -248.206768)
		(mid 337.63597 -248.161274)
		(end 337.818222 -248.211594)
		(width 0.0889)
		(layer "In4.Cu")
		(net "M_D_CPU0_SA_CB<6>")
	)
	(arc
		(start 332.752446 -248.206768)
		(mid 332.935954 -248.161274)
		(end 333.118206 -248.211594)
		(width 0.0889)
		(layer "In4.Cu")
		(net "M_D_CPU0_SA_CB<6>")
	)
	(arc
		(start 330.863956 -248.211594)
		(mid 331.046207 -248.161244)
		(end 331.229716 -248.206768)
		(width 0.0889)
		(layer "In4.Cu")
		(net "M_D_CPU0_SA_CB<6>")
	)
	(arc
		(start 332.178152 -248.211594)
		(mid 332.461108 -248.287771)
		(end 332.744064 -248.211594)
		(width 0.0889)
		(layer "In4.Cu")
		(net "M_D_CPU0_SA_CB<6>")
	)
	(arc
		(start 326.539352 -248.211594)
		(mid 326.809509 -248.288356)
		(end 327.083166 -248.22531)
		(width 0.0889)
		(layer "In4.Cu")
		(net "M_D_CPU0_SA_CB<6>")
	)
	(arc
		(start 331.238098 -248.211594)
		(mid 331.521054 -248.287771)
		(end 331.80401 -248.211594)
		(width 0.0889)
		(layer "In4.Cu")
		(net "M_D_CPU0_SA_CB<6>")
	)
	(arc
		(start 329.924156 -248.211594)
		(mid 330.1111 -248.161339)
		(end 330.298044 -248.211594)
		(width 0.0889)
		(layer "In4.Cu")
		(net "M_D_CPU0_SA_CB<6>")
	)
	(arc
		(start 333.6925 -248.206768)
		(mid 333.876008 -248.161274)
		(end 334.05826 -248.211594)
		(width 0.0889)
		(layer "In4.Cu")
		(net "M_D_CPU0_SA_CB<6>")
	)
	(arc
		(start 326.192642 -248.1961)
		(mid 326.367893 -248.161167)
		(end 326.539352 -248.211594)
		(width 0.0889)
		(layer "In4.Cu")
		(net "M_D_CPU0_SA_CB<6>")
	)
	(arc
		(start 328.992484 -248.206768)
		(mid 329.175992 -248.161274)
		(end 329.358244 -248.211594)
		(width 0.0889)
		(layer "In4.Cu")
		(net "M_D_CPU0_SA_CB<6>")
	)
	(arc
		(start 336.504026 -248.211594)
		(mid 336.686277 -248.161244)
		(end 336.869786 -248.206768)
		(width 0.0889)
		(layer "In4.Cu")
		(net "M_D_CPU0_SA_CB<6>")
	)
	(arc
		(start 329.358244 -248.211594)
		(mid 329.6412 -248.287771)
		(end 329.924156 -248.211594)
		(width 0.0889)
		(layer "In4.Cu")
		(net "M_D_CPU0_SA_CB<6>")
	)
	(arc
		(start 333.118206 -248.211594)
		(mid 333.401162 -248.287771)
		(end 333.684118 -248.211594)
		(width 0.0889)
		(layer "In4.Cu")
		(net "M_D_CPU0_SA_CB<6>")
	)
	(arc
		(start 335.563972 -248.211594)
		(mid 335.746223 -248.161244)
		(end 335.929732 -248.206768)
		(width 0.0889)
		(layer "In4.Cu")
		(net "M_D_CPU0_SA_CB<6>")
	)
	(arc
		(start 338.384134 -248.211594)
		(mid 338.540453 -248.162599)
		(end 338.70265 -248.185432)
		(width 0.0889)
		(layer "In4.Cu")
		(net "M_D_CPU0_SA_CB<6>")
	)
	(arc
		(start 334.624172 -248.211594)
		(mid 334.811116 -248.161339)
		(end 334.99806 -248.211594)
		(width 0.0889)
		(layer "In4.Cu")
		(net "M_D_CPU0_SA_CB<6>")
	)
	(arc
		(start 330.298044 -248.211594)
		(mid 330.581 -248.287771)
		(end 330.863956 -248.211594)
		(width 0.0889)
		(layer "In4.Cu")
		(net "M_D_CPU0_SA_CB<6>")
	)
	(arc
		(start 335.938114 -248.211594)
		(mid 336.22107 -248.287771)
		(end 336.504026 -248.211594)
		(width 0.0889)
		(layer "In4.Cu")
		(net "M_D_CPU0_SA_CB<6>")
	)
	(arc
		(start 334.05826 -248.211594)
		(mid 334.341216 -248.287771)
		(end 334.624172 -248.211594)
		(width 0.0889)
		(layer "In4.Cu")
		(net "M_D_CPU0_SA_CB<6>")
	)
	(arc
		(start 328.41819 -248.211594)
		(mid 328.701146 -248.287771)
		(end 328.984102 -248.211594)
		(width 0.0889)
		(layer "In4.Cu")
		(net "M_D_CPU0_SA_CB<6>")
	)
	(arc
		(start 334.99806 -248.211594)
		(mid 335.281016 -248.287771)
		(end 335.563972 -248.211594)
		(width 0.0889)
		(layer "In4.Cu")
		(net "M_D_CPU0_SA_CB<6>")
	)
	(arc
		(start 327.106534 -248.211594)
		(mid 327.282654 -248.161616)
		(end 327.461372 -248.201434)
		(width 0.0889)
		(layer "In4.Cu")
		(net "M_D_CPU0_SA_CB<6>")
	)
	(arc
		(start 331.80401 -248.211594)
		(mid 331.986261 -248.161244)
		(end 332.16977 -248.206768)
		(width 0.0889)
		(layer "In4.Cu")
		(net "M_D_CPU0_SA_CB<6>")
	)
	(arc
		(start 328.044048 -248.211594)
		(mid 328.226299 -248.161244)
		(end 328.409808 -248.206768)
		(width 0.0889)
		(layer "In4.Cu")
		(net "M_D_CPU0_SA_CB<6>")
	)
	(arc
		(start 336.878168 -248.211594)
		(mid 337.161124 -248.287771)
		(end 337.44408 -248.211594)
		(width 0.0889)
		(layer "In4.Cu")
		(net "M_D_CPU0_SA_CB<6>")
	)
	(arc
		(start 327.50125 -248.224294)
		(mid 327.774279 -248.287613)
		(end 328.044048 -248.211594)
		(width 0.0889)
		(layer "In4.Cu")
		(net "M_D_CPU0_SA_CB<6>")
	)
	(segment
		(start 340.918038 -248.800112)
		(end 340.451186 -248.534174)
		(width 0.10668)
		(layer "F.Cu")
		(net "M_D_CPU0_SA_CB<5>")
	)
	(segment
		(start 301.368714 -242.573556)
		(end 301.368714 -242.885468)
		(width 0.14478)
		(layer "In4.Cu")
		(net "M_D_CPU0_SA_CB<5>")
	)
	(segment
		(start 323.890894 -249.00255)
		(end 324.0913 -249.00255)
		(width 0.0889)
		(layer "In4.Cu")
		(net "M_D_CPU0_SA_CB<5>")
	)
	(segment
		(start 293.828978 -243.043964)
		(end 293.990522 -243.205508)
		(width 0.14478)
		(layer "In4.Cu")
		(net "M_D_CPU0_SA_CB<5>")
	)
	(segment
		(start 293.828978 -242.743736)
		(end 293.828978 -243.043964)
		(width 0.14478)
		(layer "In4.Cu")
		(net "M_D_CPU0_SA_CB<5>")
	)
	(segment
		(start 298.91228 -242.412012)
		(end 299.140626 -242.412012)
		(width 0.14478)
		(layer "In4.Cu")
		(net "M_D_CPU0_SA_CB<5>")
	)
	(segment
		(start 327.103232 -248.856754)
		(end 327.111614 -248.86158)
		(width 0.0889)
		(layer "In4.Cu")
		(net "M_D_CPU0_SA_CB<5>")
	)
	(segment
		(start 296.706544 -242.412012)
		(end 296.93489 -242.412012)
		(width 0.14478)
		(layer "In4.Cu")
		(net "M_D_CPU0_SA_CB<5>")
	)
	(segment
		(start 303.701958 -242.81003)
		(end 304.044096 -243.152168)
		(width 0.14478)
		(layer "In4.Cu")
		(net "M_D_CPU0_SA_CB<5>")
	)
	(segment
		(start 302.633126 -242.81003)
		(end 303.701958 -242.81003)
		(width 0.14478)
		(layer "In4.Cu")
		(net "M_D_CPU0_SA_CB<5>")
	)
	(segment
		(start 298.750736 -242.573556)
		(end 298.91228 -242.412012)
		(width 0.14478)
		(layer "In4.Cu")
		(net "M_D_CPU0_SA_CB<5>")
	)
	(segment
		(start 301.368714 -242.885468)
		(end 301.530258 -243.047012)
		(width 0.14478)
		(layer "In4.Cu")
		(net "M_D_CPU0_SA_CB<5>")
	)
	(segment
		(start 325.597266 -248.856754)
		(end 325.611998 -248.848118)
		(width 0.0889)
		(layer "In4.Cu")
		(net "M_D_CPU0_SA_CB<5>")
	)
	(segment
		(start 302.081692 -242.412012)
		(end 302.310038 -242.412012)
		(width 0.14478)
		(layer "In4.Cu")
		(net "M_D_CPU0_SA_CB<5>")
	)
	(segment
		(start 305.033172 -242.94338)
		(end 305.033172 -243.17198)
		(width 0.14478)
		(layer "In4.Cu")
		(net "M_D_CPU0_SA_CB<5>")
	)
	(segment
		(start 293.439088 -242.582192)
		(end 293.667434 -242.582192)
		(width 0.14478)
		(layer "In4.Cu")
		(net "M_D_CPU0_SA_CB<5>")
	)
	(segment
		(start 333.684118 -248.856754)
		(end 333.6925 -248.86158)
		(width 0.0889)
		(layer "In4.Cu")
		(net "M_D_CPU0_SA_CB<5>")
	)
	(segment
		(start 293.277544 -243.043964)
		(end 293.277544 -242.743736)
		(width 0.14478)
		(layer "In4.Cu")
		(net "M_D_CPU0_SA_CB<5>")
	)
	(segment
		(start 299.140626 -242.412012)
		(end 299.30217 -242.573556)
		(width 0.14478)
		(layer "In4.Cu")
		(net "M_D_CPU0_SA_CB<5>")
	)
	(segment
		(start 299.463714 -242.81003)
		(end 300.655736 -242.81003)
		(width 0.14478)
		(layer "In4.Cu")
		(net "M_D_CPU0_SA_CB<5>")
	)
	(segment
		(start 297.647868 -242.715796)
		(end 297.809412 -242.554252)
		(width 0.14478)
		(layer "In4.Cu")
		(net "M_D_CPU0_SA_CB<5>")
	)
	(segment
		(start 293.116 -243.205508)
		(end 293.277544 -243.043964)
		(width 0.14478)
		(layer "In4.Cu")
		(net "M_D_CPU0_SA_CB<5>")
	)
	(segment
		(start 294.380412 -242.576096)
		(end 294.541956 -242.414552)
		(width 0.14478)
		(layer "In4.Cu")
		(net "M_D_CPU0_SA_CB<5>")
	)
	(segment
		(start 297.257978 -243.208048)
		(end 297.486324 -243.208048)
		(width 0.14478)
		(layer "In4.Cu")
		(net "M_D_CPU0_SA_CB<5>")
	)
	(segment
		(start 298.199302 -242.715796)
		(end 298.199302 -243.046504)
		(width 0.14478)
		(layer "In4.Cu")
		(net "M_D_CPU0_SA_CB<5>")
	)
	(segment
		(start 332.744064 -248.856754)
		(end 332.752446 -248.86158)
		(width 0.0889)
		(layer "In4.Cu")
		(net "M_D_CPU0_SA_CB<5>")
	)
	(segment
		(start 304.044096 -243.152168)
		(end 304.272696 -243.152168)
		(width 0.14478)
		(layer "In4.Cu")
		(net "M_D_CPU0_SA_CB<5>")
	)
	(segment
		(start 292.72611 -243.043964)
		(end 292.887654 -243.205508)
		(width 0.14478)
		(layer "In4.Cu")
		(net "M_D_CPU0_SA_CB<5>")
	)
	(segment
		(start 299.30217 -242.573556)
		(end 299.30217 -242.648486)
		(width 0.14478)
		(layer "In4.Cu")
		(net "M_D_CPU0_SA_CB<5>")
	)
	(segment
		(start 298.750736 -243.046504)
		(end 298.750736 -242.573556)
		(width 0.14478)
		(layer "In4.Cu")
		(net "M_D_CPU0_SA_CB<5>")
	)
	(segment
		(start 324.189598 -248.904252)
		(end 324.42023 -248.904252)
		(width 0.0889)
		(layer "In4.Cu")
		(net "M_D_CPU0_SA_CB<5>")
	)
	(segment
		(start 292.564566 -242.81003)
		(end 292.72611 -242.971574)
		(width 0.14478)
		(layer "In4.Cu")
		(net "M_D_CPU0_SA_CB<5>")
	)
	(segment
		(start 296.93489 -242.412012)
		(end 297.096434 -242.573556)
		(width 0.14478)
		(layer "In4.Cu")
		(net "M_D_CPU0_SA_CB<5>")
	)
	(segment
		(start 322.403724 -248.6914)
		(end 322.714874 -249.00255)
		(width 0.14478)
		(layer "In4.Cu")
		(net "M_D_CPU0_SA_CB<5>")
	)
	(segment
		(start 301.920148 -242.573556)
		(end 302.081692 -242.412012)
		(width 0.14478)
		(layer "In4.Cu")
		(net "M_D_CPU0_SA_CB<5>")
	)
	(segment
		(start 337.44408 -248.856754)
		(end 337.452462 -248.86158)
		(width 0.0889)
		(layer "In4.Cu")
		(net "M_D_CPU0_SA_CB<5>")
	)
	(segment
		(start 331.229716 -248.86158)
		(end 331.238098 -248.856754)
		(width 0.0889)
		(layer "In4.Cu")
		(net "M_D_CPU0_SA_CB<5>")
	)
	(segment
		(start 302.310038 -242.412012)
		(end 302.471582 -242.573556)
		(width 0.14478)
		(layer "In4.Cu")
		(net "M_D_CPU0_SA_CB<5>")
	)
	(segment
		(start 307.866796 -244.515132)
		(end 312.043064 -248.6914)
		(width 0.14478)
		(layer "In4.Cu")
		(net "M_D_CPU0_SA_CB<5>")
	)
	(segment
		(start 304.871628 -242.781836)
		(end 305.033172 -242.94338)
		(width 0.14478)
		(layer "In4.Cu")
		(net "M_D_CPU0_SA_CB<5>")
	)
	(segment
		(start 302.471582 -242.648486)
		(end 302.633126 -242.81003)
		(width 0.14478)
		(layer "In4.Cu")
		(net "M_D_CPU0_SA_CB<5>")
	)
	(segment
		(start 304.272696 -243.152168)
		(end 304.643028 -242.781836)
		(width 0.14478)
		(layer "In4.Cu")
		(net "M_D_CPU0_SA_CB<5>")
	)
	(segment
		(start 305.033172 -243.17198)
		(end 304.66284 -243.542312)
		(width 0.14478)
		(layer "In4.Cu")
		(net "M_D_CPU0_SA_CB<5>")
	)
	(segment
		(start 324.0913 -249.00255)
		(end 324.189598 -248.904252)
		(width 0.0889)
		(layer "In4.Cu")
		(net "M_D_CPU0_SA_CB<5>")
	)
	(segment
		(start 294.541956 -242.414552)
		(end 294.770302 -242.414552)
		(width 0.14478)
		(layer "In4.Cu")
		(net "M_D_CPU0_SA_CB<5>")
	)
	(segment
		(start 332.16977 -248.86158)
		(end 332.178152 -248.856754)
		(width 0.0889)
		(layer "In4.Cu")
		(net "M_D_CPU0_SA_CB<5>")
	)
	(segment
		(start 326.537828 -248.8565)
		(end 326.543416 -248.853198)
		(width 0.0889)
		(layer "In4.Cu")
		(net "M_D_CPU0_SA_CB<5>")
	)
	(segment
		(start 297.809412 -242.554252)
		(end 298.037758 -242.554252)
		(width 0.14478)
		(layer "In4.Cu")
		(net "M_D_CPU0_SA_CB<5>")
	)
	(segment
		(start 339.689694 -248.86158)
		(end 339.698076 -248.856754)
		(width 0.0889)
		(layer "In4.Cu")
		(net "M_D_CPU0_SA_CB<5>")
	)
	(segment
		(start 292.72611 -242.971574)
		(end 292.72611 -243.043964)
		(width 0.14478)
		(layer "In4.Cu")
		(net "M_D_CPU0_SA_CB<5>")
	)
	(segment
		(start 328.033634 -248.850658)
		(end 328.044048 -248.856754)
		(width 0.0889)
		(layer "In4.Cu")
		(net "M_D_CPU0_SA_CB<5>")
	)
	(segment
		(start 296.545 -242.573556)
		(end 296.706544 -242.412012)
		(width 0.14478)
		(layer "In4.Cu")
		(net "M_D_CPU0_SA_CB<5>")
	)
	(segment
		(start 298.199302 -243.046504)
		(end 298.360846 -243.208048)
		(width 0.14478)
		(layer "In4.Cu")
		(net "M_D_CPU0_SA_CB<5>")
	)
	(segment
		(start 293.990522 -243.205508)
		(end 294.218868 -243.205508)
		(width 0.14478)
		(layer "In4.Cu")
		(net "M_D_CPU0_SA_CB<5>")
	)
	(segment
		(start 299.30217 -242.648486)
		(end 299.463714 -242.81003)
		(width 0.14478)
		(layer "In4.Cu")
		(net "M_D_CPU0_SA_CB<5>")
	)
	(segment
		(start 284.736032 -242.385088)
		(end 285.160974 -242.81003)
		(width 0.14478)
		(layer "In4.Cu")
		(net "M_D_CPU0_SA_CB<5>")
	)
	(segment
		(start 294.931846 -242.576096)
		(end 294.931846 -242.648486)
		(width 0.14478)
		(layer "In4.Cu")
		(net "M_D_CPU0_SA_CB<5>")
	)
	(segment
		(start 298.037758 -242.554252)
		(end 298.199302 -242.715796)
		(width 0.14478)
		(layer "In4.Cu")
		(net "M_D_CPU0_SA_CB<5>")
	)
	(segment
		(start 322.714874 -249.00255)
		(end 323.890894 -249.00255)
		(width 0.14478)
		(layer "In4.Cu")
		(net "M_D_CPU0_SA_CB<5>")
	)
	(segment
		(start 294.380412 -243.043964)
		(end 294.380412 -242.576096)
		(width 0.14478)
		(layer "In4.Cu")
		(net "M_D_CPU0_SA_CB<5>")
	)
	(segment
		(start 328.984102 -248.856754)
		(end 328.992484 -248.86158)
		(width 0.0889)
		(layer "In4.Cu")
		(net "M_D_CPU0_SA_CB<5>")
	)
	(segment
		(start 301.920148 -242.885468)
		(end 301.920148 -242.573556)
		(width 0.14478)
		(layer "In4.Cu")
		(net "M_D_CPU0_SA_CB<5>")
	)
	(segment
		(start 336.869786 -248.86158)
		(end 336.878168 -248.856754)
		(width 0.0889)
		(layer "In4.Cu")
		(net "M_D_CPU0_SA_CB<5>")
	)
	(segment
		(start 301.20717 -242.412012)
		(end 301.368714 -242.573556)
		(width 0.14478)
		(layer "In4.Cu")
		(net "M_D_CPU0_SA_CB<5>")
	)
	(segment
		(start 301.530258 -243.047012)
		(end 301.758604 -243.047012)
		(width 0.14478)
		(layer "In4.Cu")
		(net "M_D_CPU0_SA_CB<5>")
	)
	(segment
		(start 285.160974 -242.81003)
		(end 292.564566 -242.81003)
		(width 0.14478)
		(layer "In4.Cu")
		(net "M_D_CPU0_SA_CB<5>")
	)
	(segment
		(start 304.66284 -243.770912)
		(end 305.40706 -244.515132)
		(width 0.14478)
		(layer "In4.Cu")
		(net "M_D_CPU0_SA_CB<5>")
	)
	(segment
		(start 340.297008 -248.799604)
		(end 340.451186 -248.534174)
		(width 0.0889)
		(layer "In4.Cu")
		(net "M_D_CPU0_SA_CB<5>")
	)
	(segment
		(start 297.647868 -243.046504)
		(end 297.647868 -242.715796)
		(width 0.14478)
		(layer "In4.Cu")
		(net "M_D_CPU0_SA_CB<5>")
	)
	(segment
		(start 297.096434 -243.046504)
		(end 297.257978 -243.208048)
		(width 0.14478)
		(layer "In4.Cu")
		(net "M_D_CPU0_SA_CB<5>")
	)
	(segment
		(start 294.770302 -242.414552)
		(end 294.931846 -242.576096)
		(width 0.14478)
		(layer "In4.Cu")
		(net "M_D_CPU0_SA_CB<5>")
	)
	(segment
		(start 324.42023 -248.904252)
		(end 324.423278 -248.9073)
		(width 0.0889)
		(layer "In4.Cu")
		(net "M_D_CPU0_SA_CB<5>")
	)
	(segment
		(start 302.471582 -242.573556)
		(end 302.471582 -242.648486)
		(width 0.14478)
		(layer "In4.Cu")
		(net "M_D_CPU0_SA_CB<5>")
	)
	(segment
		(start 305.40706 -244.515132)
		(end 307.866796 -244.515132)
		(width 0.14478)
		(layer "In4.Cu")
		(net "M_D_CPU0_SA_CB<5>")
	)
	(segment
		(start 294.218868 -243.205508)
		(end 294.380412 -243.043964)
		(width 0.14478)
		(layer "In4.Cu")
		(net "M_D_CPU0_SA_CB<5>")
	)
	(segment
		(start 296.545 -242.648486)
		(end 296.545 -242.573556)
		(width 0.14478)
		(layer "In4.Cu")
		(net "M_D_CPU0_SA_CB<5>")
	)
	(segment
		(start 292.887654 -243.205508)
		(end 293.116 -243.205508)
		(width 0.14478)
		(layer "In4.Cu")
		(net "M_D_CPU0_SA_CB<5>")
	)
	(segment
		(start 340.200742 -248.825004)
		(end 340.297008 -248.799604)
		(width 0.0889)
		(layer "In4.Cu")
		(net "M_D_CPU0_SA_CB<5>")
	)
	(segment
		(start 298.589192 -243.208048)
		(end 298.750736 -243.046504)
		(width 0.14478)
		(layer "In4.Cu")
		(net "M_D_CPU0_SA_CB<5>")
	)
	(segment
		(start 296.383456 -242.81003)
		(end 296.545 -242.648486)
		(width 0.14478)
		(layer "In4.Cu")
		(net "M_D_CPU0_SA_CB<5>")
	)
	(segment
		(start 301.758604 -243.047012)
		(end 301.920148 -242.885468)
		(width 0.14478)
		(layer "In4.Cu")
		(net "M_D_CPU0_SA_CB<5>")
	)
	(segment
		(start 324.423278 -248.9073)
		(end 325.409814 -248.9073)
		(width 0.0889)
		(layer "In4.Cu")
		(net "M_D_CPU0_SA_CB<5>")
	)
	(segment
		(start 300.655736 -242.81003)
		(end 300.81728 -242.648486)
		(width 0.14478)
		(layer "In4.Cu")
		(net "M_D_CPU0_SA_CB<5>")
	)
	(segment
		(start 325.409814 -248.9073)
		(end 325.410068 -248.907046)
		(width 0.0889)
		(layer "In4.Cu")
		(net "M_D_CPU0_SA_CB<5>")
	)
	(segment
		(start 295.09339 -242.81003)
		(end 296.383456 -242.81003)
		(width 0.14478)
		(layer "In4.Cu")
		(net "M_D_CPU0_SA_CB<5>")
	)
	(segment
		(start 335.929732 -248.86158)
		(end 335.938114 -248.856754)
		(width 0.0889)
		(layer "In4.Cu")
		(net "M_D_CPU0_SA_CB<5>")
	)
	(segment
		(start 294.931846 -242.648486)
		(end 295.09339 -242.81003)
		(width 0.14478)
		(layer "In4.Cu")
		(net "M_D_CPU0_SA_CB<5>")
	)
	(segment
		(start 326.51954 -248.866914)
		(end 326.537828 -248.8565)
		(width 0.0889)
		(layer "In4.Cu")
		(net "M_D_CPU0_SA_CB<5>")
	)
	(segment
		(start 297.096434 -242.573556)
		(end 297.096434 -243.046504)
		(width 0.14478)
		(layer "In4.Cu")
		(net "M_D_CPU0_SA_CB<5>")
	)
	(segment
		(start 300.978824 -242.412012)
		(end 301.20717 -242.412012)
		(width 0.14478)
		(layer "In4.Cu")
		(net "M_D_CPU0_SA_CB<5>")
	)
	(segment
		(start 328.409808 -248.86158)
		(end 328.41819 -248.856754)
		(width 0.0889)
		(layer "In4.Cu")
		(net "M_D_CPU0_SA_CB<5>")
	)
	(segment
		(start 300.81728 -242.573556)
		(end 300.978824 -242.412012)
		(width 0.14478)
		(layer "In4.Cu")
		(net "M_D_CPU0_SA_CB<5>")
	)
	(segment
		(start 293.667434 -242.582192)
		(end 293.828978 -242.743736)
		(width 0.14478)
		(layer "In4.Cu")
		(net "M_D_CPU0_SA_CB<5>")
	)
	(segment
		(start 298.360846 -243.208048)
		(end 298.589192 -243.208048)
		(width 0.14478)
		(layer "In4.Cu")
		(net "M_D_CPU0_SA_CB<5>")
	)
	(segment
		(start 300.81728 -242.648486)
		(end 300.81728 -242.573556)
		(width 0.14478)
		(layer "In4.Cu")
		(net "M_D_CPU0_SA_CB<5>")
	)
	(segment
		(start 304.66284 -243.542312)
		(end 304.66284 -243.770912)
		(width 0.14478)
		(layer "In4.Cu")
		(net "M_D_CPU0_SA_CB<5>")
	)
	(segment
		(start 297.486324 -243.208048)
		(end 297.647868 -243.046504)
		(width 0.14478)
		(layer "In4.Cu")
		(net "M_D_CPU0_SA_CB<5>")
	)
	(segment
		(start 304.643028 -242.781836)
		(end 304.871628 -242.781836)
		(width 0.14478)
		(layer "In4.Cu")
		(net "M_D_CPU0_SA_CB<5>")
	)
	(segment
		(start 293.277544 -242.743736)
		(end 293.439088 -242.582192)
		(width 0.14478)
		(layer "In4.Cu")
		(net "M_D_CPU0_SA_CB<5>")
	)
	(segment
		(start 312.043064 -248.6914)
		(end 322.403724 -248.6914)
		(width 0.14478)
		(layer "In4.Cu")
		(net "M_D_CPU0_SA_CB<5>")
	)
	(arc
		(start 330.298044 -248.856754)
		(mid 330.581 -248.780577)
		(end 330.863956 -248.856754)
		(width 0.0889)
		(layer "In4.Cu")
		(net "M_D_CPU0_SA_CB<5>")
	)
	(arc
		(start 338.384134 -248.856754)
		(mid 338.571078 -248.907009)
		(end 338.758022 -248.856754)
		(width 0.0889)
		(layer "In4.Cu")
		(net "M_D_CPU0_SA_CB<5>")
	)
	(arc
		(start 327.477882 -248.856754)
		(mid 327.754949 -248.780483)
		(end 328.033634 -248.850658)
		(width 0.0889)
		(layer "In4.Cu")
		(net "M_D_CPU0_SA_CB<5>")
	)
	(arc
		(start 326.543416 -248.853198)
		(mid 326.823805 -248.780529)
		(end 327.103232 -248.856754)
		(width 0.0889)
		(layer "In4.Cu")
		(net "M_D_CPU0_SA_CB<5>")
	)
	(arc
		(start 331.80401 -248.856754)
		(mid 331.986261 -248.907104)
		(end 332.16977 -248.86158)
		(width 0.0889)
		(layer "In4.Cu")
		(net "M_D_CPU0_SA_CB<5>")
	)
	(arc
		(start 328.41819 -248.856754)
		(mid 328.701146 -248.780577)
		(end 328.984102 -248.856754)
		(width 0.0889)
		(layer "In4.Cu")
		(net "M_D_CPU0_SA_CB<5>")
	)
	(arc
		(start 329.358244 -248.856754)
		(mid 329.6412 -248.780577)
		(end 329.924156 -248.856754)
		(width 0.0889)
		(layer "In4.Cu")
		(net "M_D_CPU0_SA_CB<5>")
	)
	(arc
		(start 329.924156 -248.856754)
		(mid 330.1111 -248.907009)
		(end 330.298044 -248.856754)
		(width 0.0889)
		(layer "In4.Cu")
		(net "M_D_CPU0_SA_CB<5>")
	)
	(arc
		(start 331.238098 -248.856754)
		(mid 331.521054 -248.780577)
		(end 331.80401 -248.856754)
		(width 0.0889)
		(layer "In4.Cu")
		(net "M_D_CPU0_SA_CB<5>")
	)
	(arc
		(start 339.698076 -248.856754)
		(mid 339.945672 -248.781576)
		(end 340.200742 -248.825004)
		(width 0.0889)
		(layer "In4.Cu")
		(net "M_D_CPU0_SA_CB<5>")
	)
	(arc
		(start 338.758022 -248.856754)
		(mid 339.040978 -248.780577)
		(end 339.323934 -248.856754)
		(width 0.0889)
		(layer "In4.Cu")
		(net "M_D_CPU0_SA_CB<5>")
	)
	(arc
		(start 327.111614 -248.86158)
		(mid 327.295376 -248.907196)
		(end 327.477882 -248.856754)
		(width 0.0889)
		(layer "In4.Cu")
		(net "M_D_CPU0_SA_CB<5>")
	)
	(arc
		(start 332.178152 -248.856754)
		(mid 332.461108 -248.780577)
		(end 332.744064 -248.856754)
		(width 0.0889)
		(layer "In4.Cu")
		(net "M_D_CPU0_SA_CB<5>")
	)
	(arc
		(start 333.118206 -248.856754)
		(mid 333.401162 -248.780577)
		(end 333.684118 -248.856754)
		(width 0.0889)
		(layer "In4.Cu")
		(net "M_D_CPU0_SA_CB<5>")
	)
	(arc
		(start 337.452462 -248.86158)
		(mid 337.63597 -248.907074)
		(end 337.818222 -248.856754)
		(width 0.0889)
		(layer "In4.Cu")
		(net "M_D_CPU0_SA_CB<5>")
	)
	(arc
		(start 336.878168 -248.856754)
		(mid 337.161124 -248.780577)
		(end 337.44408 -248.856754)
		(width 0.0889)
		(layer "In4.Cu")
		(net "M_D_CPU0_SA_CB<5>")
	)
	(arc
		(start 328.992484 -248.86158)
		(mid 329.175992 -248.907074)
		(end 329.358244 -248.856754)
		(width 0.0889)
		(layer "In4.Cu")
		(net "M_D_CPU0_SA_CB<5>")
	)
	(arc
		(start 326.163686 -248.856754)
		(mid 326.340314 -248.906987)
		(end 326.51954 -248.866914)
		(width 0.0889)
		(layer "In4.Cu")
		(net "M_D_CPU0_SA_CB<5>")
	)
	(arc
		(start 339.323934 -248.856754)
		(mid 339.506185 -248.907104)
		(end 339.689694 -248.86158)
		(width 0.0889)
		(layer "In4.Cu")
		(net "M_D_CPU0_SA_CB<5>")
	)
	(arc
		(start 334.99806 -248.856754)
		(mid 335.281016 -248.780577)
		(end 335.563972 -248.856754)
		(width 0.0889)
		(layer "In4.Cu")
		(net "M_D_CPU0_SA_CB<5>")
	)
	(arc
		(start 325.611998 -248.848118)
		(mid 325.888981 -248.780314)
		(end 326.163686 -248.856754)
		(width 0.0889)
		(layer "In4.Cu")
		(net "M_D_CPU0_SA_CB<5>")
	)
	(arc
		(start 335.563972 -248.856754)
		(mid 335.746223 -248.907104)
		(end 335.929732 -248.86158)
		(width 0.0889)
		(layer "In4.Cu")
		(net "M_D_CPU0_SA_CB<5>")
	)
	(arc
		(start 332.752446 -248.86158)
		(mid 332.935954 -248.907074)
		(end 333.118206 -248.856754)
		(width 0.0889)
		(layer "In4.Cu")
		(net "M_D_CPU0_SA_CB<5>")
	)
	(arc
		(start 325.410068 -248.907046)
		(mid 325.507 -248.894295)
		(end 325.597266 -248.856754)
		(width 0.0889)
		(layer "In4.Cu")
		(net "M_D_CPU0_SA_CB<5>")
	)
	(arc
		(start 336.504026 -248.856754)
		(mid 336.686277 -248.907104)
		(end 336.869786 -248.86158)
		(width 0.0889)
		(layer "In4.Cu")
		(net "M_D_CPU0_SA_CB<5>")
	)
	(arc
		(start 330.863956 -248.856754)
		(mid 331.046207 -248.907104)
		(end 331.229716 -248.86158)
		(width 0.0889)
		(layer "In4.Cu")
		(net "M_D_CPU0_SA_CB<5>")
	)
	(arc
		(start 328.044048 -248.856754)
		(mid 328.226299 -248.907104)
		(end 328.409808 -248.86158)
		(width 0.0889)
		(layer "In4.Cu")
		(net "M_D_CPU0_SA_CB<5>")
	)
	(arc
		(start 334.624172 -248.856754)
		(mid 334.811116 -248.907009)
		(end 334.99806 -248.856754)
		(width 0.0889)
		(layer "In4.Cu")
		(net "M_D_CPU0_SA_CB<5>")
	)
	(arc
		(start 333.6925 -248.86158)
		(mid 333.876008 -248.907074)
		(end 334.05826 -248.856754)
		(width 0.0889)
		(layer "In4.Cu")
		(net "M_D_CPU0_SA_CB<5>")
	)
	(arc
		(start 335.938114 -248.856754)
		(mid 336.22107 -248.780577)
		(end 336.504026 -248.856754)
		(width 0.0889)
		(layer "In4.Cu")
		(net "M_D_CPU0_SA_CB<5>")
	)
	(arc
		(start 337.818222 -248.856754)
		(mid 338.101178 -248.780577)
		(end 338.384134 -248.856754)
		(width 0.0889)
		(layer "In4.Cu")
		(net "M_D_CPU0_SA_CB<5>")
	)
	(arc
		(start 334.05826 -248.856754)
		(mid 334.341216 -248.780577)
		(end 334.624172 -248.856754)
		(width 0.0889)
		(layer "In4.Cu")
		(net "M_D_CPU0_SA_CB<5>")
	)
	(segment
		(start 339.508084 -247.990106)
		(end 339.040978 -247.724168)
		(width 0.10668)
		(layer "F.Cu")
		(net "M_D_CPU0_SA_CB<4>")
	)
	(segment
		(start 326.069706 -248.046494)
		(end 326.101456 -248.028206)
		(width 0.0889)
		(layer "In4.Cu")
		(net "M_D_CPU0_SA_CB<4>")
	)
	(segment
		(start 292.747446 -240.423192)
		(end 292.747446 -241.326162)
		(width 0.14478)
		(layer "In4.Cu")
		(net "M_D_CPU0_SA_CB<4>")
	)
	(segment
		(start 286.207454 -241.11966)
		(end 289.813746 -241.11966)
		(width 0.14478)
		(layer "In4.Cu")
		(net "M_D_CPU0_SA_CB<4>")
	)
	(segment
		(start 324.285356 -248.08307)
		(end 324.555358 -248.353072)
		(width 0.0889)
		(layer "In4.Cu")
		(net "M_D_CPU0_SA_CB<4>")
	)
	(segment
		(start 293.49954 -240.47323)
		(end 293.711884 -240.47323)
		(width 0.14478)
		(layer "In4.Cu")
		(net "M_D_CPU0_SA_CB<4>")
	)
	(segment
		(start 290.879784 -240.260124)
		(end 291.042852 -240.423192)
		(width 0.14478)
		(layer "In4.Cu")
		(net "M_D_CPU0_SA_CB<4>")
	)
	(segment
		(start 286.034734 -240.94694)
		(end 286.207454 -241.11966)
		(width 0.14478)
		(layer "In4.Cu")
		(net "M_D_CPU0_SA_CB<4>")
	)
	(segment
		(start 298.70781 -241.199162)
		(end 298.870878 -241.36223)
		(width 0.14478)
		(layer "In4.Cu")
		(net "M_D_CPU0_SA_CB<4>")
	)
	(segment
		(start 291.599366 -241.313462)
		(end 291.599366 -240.423192)
		(width 0.14478)
		(layer "In4.Cu")
		(net "M_D_CPU0_SA_CB<4>")
	)
	(segment
		(start 322.807584 -247.78208)
		(end 323.108574 -248.08307)
		(width 0.14478)
		(layer "In4.Cu")
		(net "M_D_CPU0_SA_CB<4>")
	)
	(segment
		(start 293.30396 -241.326162)
		(end 293.30396 -240.66881)
		(width 0.14478)
		(layer "In4.Cu")
		(net "M_D_CPU0_SA_CB<4>")
	)
	(segment
		(start 290.673282 -240.260124)
		(end 290.879784 -240.260124)
		(width 0.14478)
		(layer "In4.Cu")
		(net "M_D_CPU0_SA_CB<4>")
	)
	(segment
		(start 336.034126 -248.046748)
		(end 336.042508 -248.051574)
		(width 0.0889)
		(layer "In4.Cu")
		(net "M_D_CPU0_SA_CB<4>")
	)
	(segment
		(start 323.108574 -248.08307)
		(end 323.895974 -248.08307)
		(width 0.14478)
		(layer "In4.Cu")
		(net "M_D_CPU0_SA_CB<4>")
	)
	(segment
		(start 338.887054 -247.989598)
		(end 339.040978 -247.724168)
		(width 0.0889)
		(layer "In4.Cu")
		(net "M_D_CPU0_SA_CB<4>")
	)
	(segment
		(start 299.101256 -241.36223)
		(end 299.264324 -241.199162)
		(width 0.14478)
		(layer "In4.Cu")
		(net "M_D_CPU0_SA_CB<4>")
	)
	(segment
		(start 285.47822 -240.56594)
		(end 285.641288 -240.402872)
		(width 0.14478)
		(layer "In4.Cu")
		(net "M_D_CPU0_SA_CB<4>")
	)
	(segment
		(start 325.736458 -248.353072)
		(end 325.95312 -248.136156)
		(width 0.0889)
		(layer "In4.Cu")
		(net "M_D_CPU0_SA_CB<4>")
	)
	(segment
		(start 297.337226 -241.11966)
		(end 298.18711 -240.269776)
		(width 0.14478)
		(layer "In4.Cu")
		(net "M_D_CPU0_SA_CB<4>")
	)
	(segment
		(start 285.871666 -240.402872)
		(end 286.034734 -240.56594)
		(width 0.14478)
		(layer "In4.Cu")
		(net "M_D_CPU0_SA_CB<4>")
	)
	(segment
		(start 293.711884 -240.47323)
		(end 294.358314 -241.11966)
		(width 0.14478)
		(layer "In4.Cu")
		(net "M_D_CPU0_SA_CB<4>")
	)
	(segment
		(start 294.358314 -241.11966)
		(end 297.337226 -241.11966)
		(width 0.14478)
		(layer "In4.Cu")
		(net "M_D_CPU0_SA_CB<4>")
	)
	(segment
		(start 291.20592 -241.47653)
		(end 291.436298 -241.47653)
		(width 0.14478)
		(layer "In4.Cu")
		(net "M_D_CPU0_SA_CB<4>")
	)
	(segment
		(start 327.57491 -248.046494)
		(end 327.594976 -248.057924)
		(width 0.0889)
		(layer "In4.Cu")
		(net "M_D_CPU0_SA_CB<4>")
	)
	(segment
		(start 329.819762 -248.051574)
		(end 329.828144 -248.046748)
		(width 0.0889)
		(layer "In4.Cu")
		(net "M_D_CPU0_SA_CB<4>")
	)
	(segment
		(start 298.554394 -240.269776)
		(end 298.70781 -240.423192)
		(width 0.14478)
		(layer "In4.Cu")
		(net "M_D_CPU0_SA_CB<4>")
	)
	(segment
		(start 285.641288 -240.402872)
		(end 285.871666 -240.402872)
		(width 0.14478)
		(layer "In4.Cu")
		(net "M_D_CPU0_SA_CB<4>")
	)
	(segment
		(start 292.747446 -241.326162)
		(end 292.910514 -241.48923)
		(width 0.14478)
		(layer "In4.Cu")
		(net "M_D_CPU0_SA_CB<4>")
	)
	(segment
		(start 338.27974 -248.051574)
		(end 338.288122 -248.046748)
		(width 0.0889)
		(layer "In4.Cu")
		(net "M_D_CPU0_SA_CB<4>")
	)
	(segment
		(start 334.519778 -248.051574)
		(end 334.52816 -248.046748)
		(width 0.0889)
		(layer "In4.Cu")
		(net "M_D_CPU0_SA_CB<4>")
	)
	(segment
		(start 285.47822 -240.94694)
		(end 285.47822 -240.56594)
		(width 0.14478)
		(layer "In4.Cu")
		(net "M_D_CPU0_SA_CB<4>")
	)
	(segment
		(start 285.315152 -241.110008)
		(end 285.47822 -240.94694)
		(width 0.14478)
		(layer "In4.Cu")
		(net "M_D_CPU0_SA_CB<4>")
	)
	(segment
		(start 298.870878 -241.36223)
		(end 299.101256 -241.36223)
		(width 0.14478)
		(layer "In4.Cu")
		(net "M_D_CPU0_SA_CB<4>")
	)
	(segment
		(start 306.590192 -242.819682)
		(end 307.554122 -242.819682)
		(width 0.14478)
		(layer "In4.Cu")
		(net "M_D_CPU0_SA_CB<4>")
	)
	(segment
		(start 293.30396 -240.66881)
		(end 293.49954 -240.47323)
		(width 0.14478)
		(layer "In4.Cu")
		(net "M_D_CPU0_SA_CB<4>")
	)
	(segment
		(start 338.791042 -248.014998)
		(end 338.887054 -247.989598)
		(width 0.0889)
		(layer "In4.Cu")
		(net "M_D_CPU0_SA_CB<4>")
	)
	(segment
		(start 307.554122 -242.819682)
		(end 312.51652 -247.78208)
		(width 0.14478)
		(layer "In4.Cu")
		(net "M_D_CPU0_SA_CB<4>")
	)
	(segment
		(start 293.140892 -241.48923)
		(end 293.30396 -241.326162)
		(width 0.14478)
		(layer "In4.Cu")
		(net "M_D_CPU0_SA_CB<4>")
	)
	(segment
		(start 299.264324 -240.423192)
		(end 299.41774 -240.269776)
		(width 0.14478)
		(layer "In4.Cu")
		(net "M_D_CPU0_SA_CB<4>")
	)
	(segment
		(start 292.59403 -240.269776)
		(end 292.747446 -240.423192)
		(width 0.14478)
		(layer "In4.Cu")
		(net "M_D_CPU0_SA_CB<4>")
	)
	(segment
		(start 301.855886 -241.110008)
		(end 304.880518 -241.110008)
		(width 0.14478)
		(layer "In4.Cu")
		(net "M_D_CPU0_SA_CB<4>")
	)
	(segment
		(start 291.752782 -240.269776)
		(end 292.59403 -240.269776)
		(width 0.14478)
		(layer "In4.Cu")
		(net "M_D_CPU0_SA_CB<4>")
	)
	(segment
		(start 291.436298 -241.47653)
		(end 291.599366 -241.313462)
		(width 0.14478)
		(layer "In4.Cu")
		(net "M_D_CPU0_SA_CB<4>")
	)
	(segment
		(start 291.042852 -240.423192)
		(end 291.042852 -241.313462)
		(width 0.14478)
		(layer "In4.Cu")
		(net "M_D_CPU0_SA_CB<4>")
	)
	(segment
		(start 292.910514 -241.48923)
		(end 293.140892 -241.48923)
		(width 0.14478)
		(layer "In4.Cu")
		(net "M_D_CPU0_SA_CB<4>")
	)
	(segment
		(start 301.015654 -240.269776)
		(end 301.855886 -241.110008)
		(width 0.14478)
		(layer "In4.Cu")
		(net "M_D_CPU0_SA_CB<4>")
	)
	(segment
		(start 291.042852 -241.313462)
		(end 291.20592 -241.47653)
		(width 0.14478)
		(layer "In4.Cu")
		(net "M_D_CPU0_SA_CB<4>")
	)
	(segment
		(start 291.599366 -240.423192)
		(end 291.752782 -240.269776)
		(width 0.14478)
		(layer "In4.Cu")
		(net "M_D_CPU0_SA_CB<4>")
	)
	(segment
		(start 335.094072 -248.046748)
		(end 335.102454 -248.051574)
		(width 0.0889)
		(layer "In4.Cu")
		(net "M_D_CPU0_SA_CB<4>")
	)
	(segment
		(start 299.264324 -241.199162)
		(end 299.264324 -240.423192)
		(width 0.14478)
		(layer "In4.Cu")
		(net "M_D_CPU0_SA_CB<4>")
	)
	(segment
		(start 326.991726 -248.05767)
		(end 327.010522 -248.046748)
		(width 0.0889)
		(layer "In4.Cu")
		(net "M_D_CPU0_SA_CB<4>")
	)
	(segment
		(start 298.70781 -240.423192)
		(end 298.70781 -241.199162)
		(width 0.14478)
		(layer "In4.Cu")
		(net "M_D_CPU0_SA_CB<4>")
	)
	(segment
		(start 330.394056 -248.046748)
		(end 330.402438 -248.051574)
		(width 0.0889)
		(layer "In4.Cu")
		(net "M_D_CPU0_SA_CB<4>")
	)
	(segment
		(start 323.895974 -248.08307)
		(end 324.285356 -248.08307)
		(width 0.0889)
		(layer "In4.Cu")
		(net "M_D_CPU0_SA_CB<4>")
	)
	(segment
		(start 324.555358 -248.353072)
		(end 325.736458 -248.353072)
		(width 0.0889)
		(layer "In4.Cu")
		(net "M_D_CPU0_SA_CB<4>")
	)
	(segment
		(start 284.736032 -240.685066)
		(end 285.160974 -241.110008)
		(width 0.14478)
		(layer "In4.Cu")
		(net "M_D_CPU0_SA_CB<4>")
	)
	(segment
		(start 286.034734 -240.56594)
		(end 286.034734 -240.94694)
		(width 0.14478)
		(layer "In4.Cu")
		(net "M_D_CPU0_SA_CB<4>")
	)
	(segment
		(start 285.160974 -241.110008)
		(end 285.315152 -241.110008)
		(width 0.14478)
		(layer "In4.Cu")
		(net "M_D_CPU0_SA_CB<4>")
	)
	(segment
		(start 333.579724 -248.051574)
		(end 333.588106 -248.046748)
		(width 0.0889)
		(layer "In4.Cu")
		(net "M_D_CPU0_SA_CB<4>")
	)
	(segment
		(start 327.55332 -248.034048)
		(end 327.57491 -248.046494)
		(width 0.0889)
		(layer "In4.Cu")
		(net "M_D_CPU0_SA_CB<4>")
	)
	(segment
		(start 298.18711 -240.269776)
		(end 298.554394 -240.269776)
		(width 0.14478)
		(layer "In4.Cu")
		(net "M_D_CPU0_SA_CB<4>")
	)
	(segment
		(start 312.51652 -247.78208)
		(end 322.807584 -247.78208)
		(width 0.14478)
		(layer "In4.Cu")
		(net "M_D_CPU0_SA_CB<4>")
	)
	(segment
		(start 331.33411 -248.046748)
		(end 331.342492 -248.051574)
		(width 0.0889)
		(layer "In4.Cu")
		(net "M_D_CPU0_SA_CB<4>")
	)
	(segment
		(start 304.880518 -241.110008)
		(end 306.590192 -242.819682)
		(width 0.14478)
		(layer "In4.Cu")
		(net "M_D_CPU0_SA_CB<4>")
	)
	(segment
		(start 289.813746 -241.11966)
		(end 290.673282 -240.260124)
		(width 0.14478)
		(layer "In4.Cu")
		(net "M_D_CPU0_SA_CB<4>")
	)
	(segment
		(start 299.41774 -240.269776)
		(end 301.015654 -240.269776)
		(width 0.14478)
		(layer "In4.Cu")
		(net "M_D_CPU0_SA_CB<4>")
	)
	(arc
		(start 327.010522 -248.046748)
		(mid 327.280291 -247.970725)
		(end 327.55332 -248.034048)
		(width 0.0889)
		(layer "In4.Cu")
		(net "M_D_CPU0_SA_CB<4>")
	)
	(arc
		(start 331.342492 -248.051574)
		(mid 331.526 -248.097068)
		(end 331.708252 -248.046748)
		(width 0.0889)
		(layer "In4.Cu")
		(net "M_D_CPU0_SA_CB<4>")
	)
	(arc
		(start 333.213964 -248.046748)
		(mid 333.396215 -248.097098)
		(end 333.579724 -248.051574)
		(width 0.0889)
		(layer "In4.Cu")
		(net "M_D_CPU0_SA_CB<4>")
	)
	(arc
		(start 338.288122 -248.046748)
		(mid 338.535835 -247.971528)
		(end 338.791042 -248.014998)
		(width 0.0889)
		(layer "In4.Cu")
		(net "M_D_CPU0_SA_CB<4>")
	)
	(arc
		(start 326.635364 -248.046748)
		(mid 326.812155 -248.097467)
		(end 326.991726 -248.05767)
		(width 0.0889)
		(layer "In4.Cu")
		(net "M_D_CPU0_SA_CB<4>")
	)
	(arc
		(start 325.95312 -248.136156)
		(mid 326.008469 -248.087497)
		(end 326.069706 -248.046494)
		(width 0.0889)
		(layer "In4.Cu")
		(net "M_D_CPU0_SA_CB<4>")
	)
	(arc
		(start 327.94829 -248.046748)
		(mid 328.231246 -247.970571)
		(end 328.514202 -248.046748)
		(width 0.0889)
		(layer "In4.Cu")
		(net "M_D_CPU0_SA_CB<4>")
	)
	(arc
		(start 337.348068 -248.046748)
		(mid 337.631024 -247.970571)
		(end 337.91398 -248.046748)
		(width 0.0889)
		(layer "In4.Cu")
		(net "M_D_CPU0_SA_CB<4>")
	)
	(arc
		(start 333.588106 -248.046748)
		(mid 333.871062 -247.970571)
		(end 334.154018 -248.046748)
		(width 0.0889)
		(layer "In4.Cu")
		(net "M_D_CPU0_SA_CB<4>")
	)
	(arc
		(start 328.88809 -248.046748)
		(mid 329.171046 -247.970571)
		(end 329.454002 -248.046748)
		(width 0.0889)
		(layer "In4.Cu")
		(net "M_D_CPU0_SA_CB<4>")
	)
	(arc
		(start 334.154018 -248.046748)
		(mid 334.336269 -248.097098)
		(end 334.519778 -248.051574)
		(width 0.0889)
		(layer "In4.Cu")
		(net "M_D_CPU0_SA_CB<4>")
	)
	(arc
		(start 332.274164 -248.046748)
		(mid 332.461108 -248.097003)
		(end 332.648052 -248.046748)
		(width 0.0889)
		(layer "In4.Cu")
		(net "M_D_CPU0_SA_CB<4>")
	)
	(arc
		(start 335.102454 -248.051574)
		(mid 335.285962 -248.097068)
		(end 335.468214 -248.046748)
		(width 0.0889)
		(layer "In4.Cu")
		(net "M_D_CPU0_SA_CB<4>")
	)
	(arc
		(start 334.52816 -248.046748)
		(mid 334.811116 -247.970571)
		(end 335.094072 -248.046748)
		(width 0.0889)
		(layer "In4.Cu")
		(net "M_D_CPU0_SA_CB<4>")
	)
	(arc
		(start 336.97418 -248.046748)
		(mid 337.161124 -248.097003)
		(end 337.348068 -248.046748)
		(width 0.0889)
		(layer "In4.Cu")
		(net "M_D_CPU0_SA_CB<4>")
	)
	(arc
		(start 337.91398 -248.046748)
		(mid 338.096231 -248.097098)
		(end 338.27974 -248.051574)
		(width 0.0889)
		(layer "In4.Cu")
		(net "M_D_CPU0_SA_CB<4>")
	)
	(arc
		(start 336.408268 -248.046748)
		(mid 336.691224 -247.970571)
		(end 336.97418 -248.046748)
		(width 0.0889)
		(layer "In4.Cu")
		(net "M_D_CPU0_SA_CB<4>")
	)
	(arc
		(start 330.768198 -248.046748)
		(mid 331.051154 -247.970571)
		(end 331.33411 -248.046748)
		(width 0.0889)
		(layer "In4.Cu")
		(net "M_D_CPU0_SA_CB<4>")
	)
	(arc
		(start 329.454002 -248.046748)
		(mid 329.636253 -248.097098)
		(end 329.819762 -248.051574)
		(width 0.0889)
		(layer "In4.Cu")
		(net "M_D_CPU0_SA_CB<4>")
	)
	(arc
		(start 332.648052 -248.046748)
		(mid 332.931008 -247.970571)
		(end 333.213964 -248.046748)
		(width 0.0889)
		(layer "In4.Cu")
		(net "M_D_CPU0_SA_CB<4>")
	)
	(arc
		(start 336.042508 -248.051574)
		(mid 336.226016 -248.097068)
		(end 336.408268 -248.046748)
		(width 0.0889)
		(layer "In4.Cu")
		(net "M_D_CPU0_SA_CB<4>")
	)
	(arc
		(start 335.468214 -248.046748)
		(mid 335.75117 -247.970571)
		(end 336.034126 -248.046748)
		(width 0.0889)
		(layer "In4.Cu")
		(net "M_D_CPU0_SA_CB<4>")
	)
	(arc
		(start 328.514202 -248.046748)
		(mid 328.701146 -248.097003)
		(end 328.88809 -248.046748)
		(width 0.0889)
		(layer "In4.Cu")
		(net "M_D_CPU0_SA_CB<4>")
	)
	(arc
		(start 330.402438 -248.051574)
		(mid 330.585946 -248.097068)
		(end 330.768198 -248.046748)
		(width 0.0889)
		(layer "In4.Cu")
		(net "M_D_CPU0_SA_CB<4>")
	)
	(arc
		(start 331.708252 -248.046748)
		(mid 331.991208 -247.970571)
		(end 332.274164 -248.046748)
		(width 0.0889)
		(layer "In4.Cu")
		(net "M_D_CPU0_SA_CB<4>")
	)
	(arc
		(start 329.828144 -248.046748)
		(mid 330.1111 -247.970571)
		(end 330.394056 -248.046748)
		(width 0.0889)
		(layer "In4.Cu")
		(net "M_D_CPU0_SA_CB<4>")
	)
	(arc
		(start 326.101456 -248.028206)
		(mid 326.370741 -247.970294)
		(end 326.635364 -248.046748)
		(width 0.0889)
		(layer "In4.Cu")
		(net "M_D_CPU0_SA_CB<4>")
	)
	(arc
		(start 327.594976 -248.057924)
		(mid 327.773054 -248.096908)
		(end 327.94829 -248.046748)
		(width 0.0889)
		(layer "In4.Cu")
		(net "M_D_CPU0_SA_CB<4>")
	)
	(segment
		(start 340.447884 -246.370094)
		(end 339.981032 -246.104156)
		(width 0.10668)
		(layer "F.Cu")
		(net "M_D_CPU0_SA_CB<3>")
	)
	(segment
		(start 323.810884 -245.43258)
		(end 324.176898 -245.43258)
		(width 0.0889)
		(layer "In4.Cu")
		(net "M_D_CPU0_SA_CB<3>")
	)
	(segment
		(start 324.475348 -245.73103)
		(end 325.880476 -245.73103)
		(width 0.0889)
		(layer "In4.Cu")
		(net "M_D_CPU0_SA_CB<3>")
	)
	(segment
		(start 307.360574 -238.501682)
		(end 307.360574 -238.730282)
		(width 0.14478)
		(layer "In4.Cu")
		(net "M_D_CPU0_SA_CB<3>")
	)
	(segment
		(start 298.172124 -236.850428)
		(end 301.18685 -236.850428)
		(width 0.14478)
		(layer "In4.Cu")
		(net "M_D_CPU0_SA_CB<3>")
	)
	(segment
		(start 307.750718 -238.891826)
		(end 307.926232 -238.716312)
		(width 0.14478)
		(layer "In4.Cu")
		(net "M_D_CPU0_SA_CB<3>")
	)
	(segment
		(start 340.13521 -245.838726)
		(end 339.981032 -246.104156)
		(width 0.0889)
		(layer "In4.Cu")
		(net "M_D_CPU0_SA_CB<3>")
	)
	(segment
		(start 282.426664 -237.479332)
		(end 282.647644 -237.700312)
		(width 0.14478)
		(layer "In4.Cu")
		(net "M_D_CPU0_SA_CB<3>")
	)
	(segment
		(start 308.154832 -238.716312)
		(end 314.8711 -245.43258)
		(width 0.14478)
		(layer "In4.Cu")
		(net "M_D_CPU0_SA_CB<3>")
	)
	(segment
		(start 289.834066 -237.700312)
		(end 290.68395 -236.850428)
		(width 0.14478)
		(layer "In4.Cu")
		(net "M_D_CPU0_SA_CB<3>")
	)
	(segment
		(start 327.007474 -245.781576)
		(end 327.017888 -245.787672)
		(width 0.0889)
		(layer "In4.Cu")
		(net "M_D_CPU0_SA_CB<3>")
	)
	(segment
		(start 339.794088 -245.781576)
		(end 339.80247 -245.77675)
		(width 0.0889)
		(layer "In4.Cu")
		(net "M_D_CPU0_SA_CB<3>")
	)
	(segment
		(start 324.176898 -245.43258)
		(end 324.475348 -245.73103)
		(width 0.0889)
		(layer "In4.Cu")
		(net "M_D_CPU0_SA_CB<3>")
	)
	(segment
		(start 294.3479 -237.700312)
		(end 297.32224 -237.700312)
		(width 0.14478)
		(layer "In4.Cu")
		(net "M_D_CPU0_SA_CB<3>")
	)
	(segment
		(start 329.819762 -245.77675)
		(end 329.828144 -245.781576)
		(width 0.0889)
		(layer "In4.Cu")
		(net "M_D_CPU0_SA_CB<3>")
	)
	(segment
		(start 336.034126 -245.781576)
		(end 336.042508 -245.77675)
		(width 0.0889)
		(layer "In4.Cu")
		(net "M_D_CPU0_SA_CB<3>")
	)
	(segment
		(start 281.06116 -237.710218)
		(end 281.7749 -237.710218)
		(width 0.14478)
		(layer "In4.Cu")
		(net "M_D_CPU0_SA_CB<3>")
	)
	(segment
		(start 307.522118 -238.891826)
		(end 307.750718 -238.891826)
		(width 0.14478)
		(layer "In4.Cu")
		(net "M_D_CPU0_SA_CB<3>")
	)
	(segment
		(start 330.394056 -245.781576)
		(end 330.402438 -245.77675)
		(width 0.0889)
		(layer "In4.Cu")
		(net "M_D_CPU0_SA_CB<3>")
	)
	(segment
		(start 297.32224 -237.700312)
		(end 298.172124 -236.850428)
		(width 0.14478)
		(layer "In4.Cu")
		(net "M_D_CPU0_SA_CB<3>")
	)
	(segment
		(start 307.148738 -237.710218)
		(end 307.536088 -238.097568)
		(width 0.14478)
		(layer "In4.Cu")
		(net "M_D_CPU0_SA_CB<3>")
	)
	(segment
		(start 335.094072 -245.781576)
		(end 335.102454 -245.77675)
		(width 0.0889)
		(layer "In4.Cu")
		(net "M_D_CPU0_SA_CB<3>")
	)
	(segment
		(start 314.8711 -245.43258)
		(end 323.810884 -245.43258)
		(width 0.14478)
		(layer "In4.Cu")
		(net "M_D_CPU0_SA_CB<3>")
	)
	(segment
		(start 307.360574 -238.730282)
		(end 307.522118 -238.891826)
		(width 0.14478)
		(layer "In4.Cu")
		(net "M_D_CPU0_SA_CB<3>")
	)
	(segment
		(start 338.27974 -245.77675)
		(end 338.288122 -245.781576)
		(width 0.0889)
		(layer "In4.Cu")
		(net "M_D_CPU0_SA_CB<3>")
	)
	(segment
		(start 334.519778 -245.77675)
		(end 334.52816 -245.781576)
		(width 0.0889)
		(layer "In4.Cu")
		(net "M_D_CPU0_SA_CB<3>")
	)
	(segment
		(start 307.536088 -238.097568)
		(end 307.536088 -238.326168)
		(width 0.14478)
		(layer "In4.Cu")
		(net "M_D_CPU0_SA_CB<3>")
	)
	(segment
		(start 326.617838 -245.790974)
		(end 326.633586 -245.78183)
		(width 0.0889)
		(layer "In4.Cu")
		(net "M_D_CPU0_SA_CB<3>")
	)
	(segment
		(start 293.498016 -236.850428)
		(end 294.3479 -237.700312)
		(width 0.14478)
		(layer "In4.Cu")
		(net "M_D_CPU0_SA_CB<3>")
	)
	(segment
		(start 307.536088 -238.326168)
		(end 307.360574 -238.501682)
		(width 0.14478)
		(layer "In4.Cu")
		(net "M_D_CPU0_SA_CB<3>")
	)
	(segment
		(start 338.854034 -245.781576)
		(end 338.862416 -245.77675)
		(width 0.0889)
		(layer "In4.Cu")
		(net "M_D_CPU0_SA_CB<3>")
	)
	(segment
		(start 282.005786 -237.479332)
		(end 282.426664 -237.479332)
		(width 0.14478)
		(layer "In4.Cu")
		(net "M_D_CPU0_SA_CB<3>")
	)
	(segment
		(start 302.04664 -237.710218)
		(end 307.148738 -237.710218)
		(width 0.14478)
		(layer "In4.Cu")
		(net "M_D_CPU0_SA_CB<3>")
	)
	(segment
		(start 282.647644 -237.700312)
		(end 289.834066 -237.700312)
		(width 0.14478)
		(layer "In4.Cu")
		(net "M_D_CPU0_SA_CB<3>")
	)
	(segment
		(start 280.635964 -237.285022)
		(end 281.06116 -237.710218)
		(width 0.14478)
		(layer "In4.Cu")
		(net "M_D_CPU0_SA_CB<3>")
	)
	(segment
		(start 301.18685 -236.850428)
		(end 302.04664 -237.710218)
		(width 0.14478)
		(layer "In4.Cu")
		(net "M_D_CPU0_SA_CB<3>")
	)
	(segment
		(start 331.33411 -245.781576)
		(end 331.342492 -245.77675)
		(width 0.0889)
		(layer "In4.Cu")
		(net "M_D_CPU0_SA_CB<3>")
	)
	(segment
		(start 326.633586 -245.78183)
		(end 326.649842 -245.772432)
		(width 0.0889)
		(layer "In4.Cu")
		(net "M_D_CPU0_SA_CB<3>")
	)
	(segment
		(start 307.926232 -238.716312)
		(end 308.154832 -238.716312)
		(width 0.14478)
		(layer "In4.Cu")
		(net "M_D_CPU0_SA_CB<3>")
	)
	(segment
		(start 333.579724 -245.77675)
		(end 333.588106 -245.781576)
		(width 0.0889)
		(layer "In4.Cu")
		(net "M_D_CPU0_SA_CB<3>")
	)
	(segment
		(start 281.7749 -237.710218)
		(end 282.005786 -237.479332)
		(width 0.14478)
		(layer "In4.Cu")
		(net "M_D_CPU0_SA_CB<3>")
	)
	(segment
		(start 290.68395 -236.850428)
		(end 293.498016 -236.850428)
		(width 0.14478)
		(layer "In4.Cu")
		(net "M_D_CPU0_SA_CB<3>")
	)
	(segment
		(start 340.112858 -245.755414)
		(end 340.13521 -245.838726)
		(width 0.0889)
		(layer "In4.Cu")
		(net "M_D_CPU0_SA_CB<3>")
	)
	(segment
		(start 327.939908 -245.77675)
		(end 327.94829 -245.781576)
		(width 0.0889)
		(layer "In4.Cu")
		(net "M_D_CPU0_SA_CB<3>")
	)
	(arc
		(start 334.154018 -245.781576)
		(mid 334.336269 -245.731226)
		(end 334.519778 -245.77675)
		(width 0.0889)
		(layer "In4.Cu")
		(net "M_D_CPU0_SA_CB<3>")
	)
	(arc
		(start 335.468214 -245.781576)
		(mid 335.75117 -245.857753)
		(end 336.034126 -245.781576)
		(width 0.0889)
		(layer "In4.Cu")
		(net "M_D_CPU0_SA_CB<3>")
	)
	(arc
		(start 332.648052 -245.781576)
		(mid 332.931008 -245.857753)
		(end 333.213964 -245.781576)
		(width 0.0889)
		(layer "In4.Cu")
		(net "M_D_CPU0_SA_CB<3>")
	)
	(arc
		(start 328.514202 -245.781576)
		(mid 328.701146 -245.731321)
		(end 328.88809 -245.781576)
		(width 0.0889)
		(layer "In4.Cu")
		(net "M_D_CPU0_SA_CB<3>")
	)
	(arc
		(start 330.768198 -245.781576)
		(mid 331.051154 -245.857753)
		(end 331.33411 -245.781576)
		(width 0.0889)
		(layer "In4.Cu")
		(net "M_D_CPU0_SA_CB<3>")
	)
	(arc
		(start 336.042508 -245.77675)
		(mid 336.226016 -245.731256)
		(end 336.408268 -245.781576)
		(width 0.0889)
		(layer "In4.Cu")
		(net "M_D_CPU0_SA_CB<3>")
	)
	(arc
		(start 332.274164 -245.781576)
		(mid 332.461108 -245.731321)
		(end 332.648052 -245.781576)
		(width 0.0889)
		(layer "In4.Cu")
		(net "M_D_CPU0_SA_CB<3>")
	)
	(arc
		(start 337.91398 -245.781576)
		(mid 338.096231 -245.731226)
		(end 338.27974 -245.77675)
		(width 0.0889)
		(layer "In4.Cu")
		(net "M_D_CPU0_SA_CB<3>")
	)
	(arc
		(start 329.454002 -245.781576)
		(mid 329.636253 -245.731226)
		(end 329.819762 -245.77675)
		(width 0.0889)
		(layer "In4.Cu")
		(net "M_D_CPU0_SA_CB<3>")
	)
	(arc
		(start 329.828144 -245.781576)
		(mid 330.1111 -245.857753)
		(end 330.394056 -245.781576)
		(width 0.0889)
		(layer "In4.Cu")
		(net "M_D_CPU0_SA_CB<3>")
	)
	(arc
		(start 334.52816 -245.781576)
		(mid 334.811116 -245.857753)
		(end 335.094072 -245.781576)
		(width 0.0889)
		(layer "In4.Cu")
		(net "M_D_CPU0_SA_CB<3>")
	)
	(arc
		(start 327.57364 -245.781576)
		(mid 327.756145 -245.731099)
		(end 327.939908 -245.77675)
		(width 0.0889)
		(layer "In4.Cu")
		(net "M_D_CPU0_SA_CB<3>")
	)
	(arc
		(start 333.213964 -245.781576)
		(mid 333.396215 -245.731226)
		(end 333.579724 -245.77675)
		(width 0.0889)
		(layer "In4.Cu")
		(net "M_D_CPU0_SA_CB<3>")
	)
	(arc
		(start 336.408268 -245.781576)
		(mid 336.691224 -245.857753)
		(end 336.97418 -245.781576)
		(width 0.0889)
		(layer "In4.Cu")
		(net "M_D_CPU0_SA_CB<3>")
	)
	(arc
		(start 327.94829 -245.781576)
		(mid 328.231246 -245.857753)
		(end 328.514202 -245.781576)
		(width 0.0889)
		(layer "In4.Cu")
		(net "M_D_CPU0_SA_CB<3>")
	)
	(arc
		(start 336.97418 -245.781576)
		(mid 337.161124 -245.731321)
		(end 337.348068 -245.781576)
		(width 0.0889)
		(layer "In4.Cu")
		(net "M_D_CPU0_SA_CB<3>")
	)
	(arc
		(start 325.880476 -245.73103)
		(mid 325.977427 -245.743905)
		(end 326.067674 -245.781576)
		(width 0.0889)
		(layer "In4.Cu")
		(net "M_D_CPU0_SA_CB<3>")
	)
	(arc
		(start 339.80247 -245.77675)
		(mid 339.95534 -245.732109)
		(end 340.112858 -245.755414)
		(width 0.0889)
		(layer "In4.Cu")
		(net "M_D_CPU0_SA_CB<3>")
	)
	(arc
		(start 331.342492 -245.77675)
		(mid 331.526 -245.731256)
		(end 331.708252 -245.781576)
		(width 0.0889)
		(layer "In4.Cu")
		(net "M_D_CPU0_SA_CB<3>")
	)
	(arc
		(start 333.588106 -245.781576)
		(mid 333.871062 -245.857753)
		(end 334.154018 -245.781576)
		(width 0.0889)
		(layer "In4.Cu")
		(net "M_D_CPU0_SA_CB<3>")
	)
	(arc
		(start 328.88809 -245.781576)
		(mid 329.171046 -245.857753)
		(end 329.454002 -245.781576)
		(width 0.0889)
		(layer "In4.Cu")
		(net "M_D_CPU0_SA_CB<3>")
	)
	(arc
		(start 330.402438 -245.77675)
		(mid 330.585946 -245.731256)
		(end 330.768198 -245.781576)
		(width 0.0889)
		(layer "In4.Cu")
		(net "M_D_CPU0_SA_CB<3>")
	)
	(arc
		(start 339.228176 -245.781576)
		(mid 339.511132 -245.857753)
		(end 339.794088 -245.781576)
		(width 0.0889)
		(layer "In4.Cu")
		(net "M_D_CPU0_SA_CB<3>")
	)
	(arc
		(start 338.862416 -245.77675)
		(mid 339.045924 -245.731256)
		(end 339.228176 -245.781576)
		(width 0.0889)
		(layer "In4.Cu")
		(net "M_D_CPU0_SA_CB<3>")
	)
	(arc
		(start 338.288122 -245.781576)
		(mid 338.571078 -245.857753)
		(end 338.854034 -245.781576)
		(width 0.0889)
		(layer "In4.Cu")
		(net "M_D_CPU0_SA_CB<3>")
	)
	(arc
		(start 327.017888 -245.787672)
		(mid 327.296574 -245.857892)
		(end 327.57364 -245.781576)
		(width 0.0889)
		(layer "In4.Cu")
		(net "M_D_CPU0_SA_CB<3>")
	)
	(arc
		(start 326.067674 -245.781576)
		(mid 326.341529 -245.857926)
		(end 326.617838 -245.790974)
		(width 0.0889)
		(layer "In4.Cu")
		(net "M_D_CPU0_SA_CB<3>")
	)
	(arc
		(start 331.708252 -245.781576)
		(mid 331.991208 -245.857753)
		(end 332.274164 -245.781576)
		(width 0.0889)
		(layer "In4.Cu")
		(net "M_D_CPU0_SA_CB<3>")
	)
	(arc
		(start 326.649842 -245.772432)
		(mid 326.829824 -245.731332)
		(end 327.007474 -245.781576)
		(width 0.0889)
		(layer "In4.Cu")
		(net "M_D_CPU0_SA_CB<3>")
	)
	(arc
		(start 335.102454 -245.77675)
		(mid 335.285962 -245.731256)
		(end 335.468214 -245.781576)
		(width 0.0889)
		(layer "In4.Cu")
		(net "M_D_CPU0_SA_CB<3>")
	)
	(arc
		(start 337.348068 -245.781576)
		(mid 337.631024 -245.857753)
		(end 337.91398 -245.781576)
		(width 0.0889)
		(layer "In4.Cu")
		(net "M_D_CPU0_SA_CB<3>")
	)
	(segment
		(start 339.03793 -245.560088)
		(end 338.571078 -245.29415)
		(width 0.10668)
		(layer "F.Cu")
		(net "M_D_CPU0_SA_CB<2>")
	)
	(segment
		(start 307.835554 -237.041182)
		(end 315.327792 -244.53342)
		(width 0.14478)
		(layer "In4.Cu")
		(net "M_D_CPU0_SA_CB<2>")
	)
	(segment
		(start 289.82416 -236.010196)
		(end 290.674298 -235.160058)
		(width 0.14478)
		(layer "In4.Cu")
		(net "M_D_CPU0_SA_CB<2>")
	)
	(segment
		(start 338.725002 -245.02872)
		(end 338.571078 -245.29415)
		(width 0.0889)
		(layer "In4.Cu")
		(net "M_D_CPU0_SA_CB<2>")
	)
	(segment
		(start 293.507668 -235.160058)
		(end 294.357806 -236.010196)
		(width 0.14478)
		(layer "In4.Cu")
		(net "M_D_CPU0_SA_CB<2>")
	)
	(segment
		(start 301.196502 -235.160058)
		(end 302.04664 -236.010196)
		(width 0.14478)
		(layer "In4.Cu")
		(net "M_D_CPU0_SA_CB<2>")
	)
	(segment
		(start 298.162472 -235.160058)
		(end 301.196502 -235.160058)
		(width 0.14478)
		(layer "In4.Cu")
		(net "M_D_CPU0_SA_CB<2>")
	)
	(segment
		(start 336.869786 -244.966744)
		(end 336.878168 -244.97157)
		(width 0.0889)
		(layer "In4.Cu")
		(net "M_D_CPU0_SA_CB<2>")
	)
	(segment
		(start 337.44408 -244.97157)
		(end 337.452462 -244.966744)
		(width 0.0889)
		(layer "In4.Cu")
		(net "M_D_CPU0_SA_CB<2>")
	)
	(segment
		(start 327.47966 -244.971824)
		(end 327.50125 -244.98427)
		(width 0.0889)
		(layer "In4.Cu")
		(net "M_D_CPU0_SA_CB<2>")
	)
	(segment
		(start 280.635964 -235.585)
		(end 281.06116 -236.010196)
		(width 0.14478)
		(layer "In4.Cu")
		(net "M_D_CPU0_SA_CB<2>")
	)
	(segment
		(start 307.819044 -236.277404)
		(end 307.980588 -236.438948)
		(width 0.14478)
		(layer "In4.Cu")
		(net "M_D_CPU0_SA_CB<2>")
	)
	(segment
		(start 302.04664 -236.010196)
		(end 306.804568 -236.010196)
		(width 0.14478)
		(layer "In4.Cu")
		(net "M_D_CPU0_SA_CB<2>")
	)
	(segment
		(start 332.744064 -244.97157)
		(end 332.752446 -244.966744)
		(width 0.0889)
		(layer "In4.Cu")
		(net "M_D_CPU0_SA_CB<2>")
	)
	(segment
		(start 306.804568 -236.010196)
		(end 307.21681 -236.422438)
		(width 0.14478)
		(layer "In4.Cu")
		(net "M_D_CPU0_SA_CB<2>")
	)
	(segment
		(start 331.229716 -244.966744)
		(end 331.238098 -244.97157)
		(width 0.0889)
		(layer "In4.Cu")
		(net "M_D_CPU0_SA_CB<2>")
	)
	(segment
		(start 282.247848 -235.847128)
		(end 282.247848 -235.396278)
		(width 0.14478)
		(layer "In4.Cu")
		(net "M_D_CPU0_SA_CB<2>")
	)
	(segment
		(start 338.70265 -244.945408)
		(end 338.725002 -245.02872)
		(width 0.0889)
		(layer "In4.Cu")
		(net "M_D_CPU0_SA_CB<2>")
	)
	(segment
		(start 324.293992 -244.377972)
		(end 324.961758 -244.377972)
		(width 0.0889)
		(layer "In4.Cu")
		(net "M_D_CPU0_SA_CB<2>")
	)
	(segment
		(start 282.804362 -235.396278)
		(end 282.804362 -235.847128)
		(width 0.14478)
		(layer "In4.Cu")
		(net "M_D_CPU0_SA_CB<2>")
	)
	(segment
		(start 324.961758 -244.377972)
		(end 325.504302 -244.920516)
		(width 0.0889)
		(layer "In4.Cu")
		(net "M_D_CPU0_SA_CB<2>")
	)
	(segment
		(start 307.835554 -236.812582)
		(end 307.835554 -237.041182)
		(width 0.14478)
		(layer "In4.Cu")
		(net "M_D_CPU0_SA_CB<2>")
	)
	(segment
		(start 307.590444 -236.277404)
		(end 307.819044 -236.277404)
		(width 0.14478)
		(layer "In4.Cu")
		(net "M_D_CPU0_SA_CB<2>")
	)
	(segment
		(start 307.980588 -236.438948)
		(end 307.980588 -236.667548)
		(width 0.14478)
		(layer "In4.Cu")
		(net "M_D_CPU0_SA_CB<2>")
	)
	(segment
		(start 333.684118 -244.97157)
		(end 333.6925 -244.966744)
		(width 0.0889)
		(layer "In4.Cu")
		(net "M_D_CPU0_SA_CB<2>")
	)
	(segment
		(start 290.674298 -235.160058)
		(end 293.507668 -235.160058)
		(width 0.14478)
		(layer "In4.Cu")
		(net "M_D_CPU0_SA_CB<2>")
	)
	(segment
		(start 282.804362 -235.847128)
		(end 282.96743 -236.010196)
		(width 0.14478)
		(layer "In4.Cu")
		(net "M_D_CPU0_SA_CB<2>")
	)
	(segment
		(start 325.504302 -244.920516)
		(end 326.351138 -244.920516)
		(width 0.0889)
		(layer "In4.Cu")
		(net "M_D_CPU0_SA_CB<2>")
	)
	(segment
		(start 332.16977 -244.966744)
		(end 332.178152 -244.97157)
		(width 0.0889)
		(layer "In4.Cu")
		(net "M_D_CPU0_SA_CB<2>")
	)
	(segment
		(start 307.44541 -236.422438)
		(end 307.590444 -236.277404)
		(width 0.14478)
		(layer "In4.Cu")
		(net "M_D_CPU0_SA_CB<2>")
	)
	(segment
		(start 315.327792 -244.53342)
		(end 324.138544 -244.53342)
		(width 0.14478)
		(layer "In4.Cu")
		(net "M_D_CPU0_SA_CB<2>")
	)
	(segment
		(start 281.06116 -236.010196)
		(end 282.08478 -236.010196)
		(width 0.14478)
		(layer "In4.Cu")
		(net "M_D_CPU0_SA_CB<2>")
	)
	(segment
		(start 327.083166 -244.985286)
		(end 327.106534 -244.97157)
		(width 0.0889)
		(layer "In4.Cu")
		(net "M_D_CPU0_SA_CB<2>")
	)
	(segment
		(start 328.409808 -244.966744)
		(end 328.41819 -244.97157)
		(width 0.0889)
		(layer "In4.Cu")
		(net "M_D_CPU0_SA_CB<2>")
	)
	(segment
		(start 282.410916 -235.23321)
		(end 282.641294 -235.23321)
		(width 0.14478)
		(layer "In4.Cu")
		(net "M_D_CPU0_SA_CB<2>")
	)
	(segment
		(start 335.929732 -244.966744)
		(end 335.938114 -244.97157)
		(width 0.0889)
		(layer "In4.Cu")
		(net "M_D_CPU0_SA_CB<2>")
	)
	(segment
		(start 282.641294 -235.23321)
		(end 282.804362 -235.396278)
		(width 0.14478)
		(layer "In4.Cu")
		(net "M_D_CPU0_SA_CB<2>")
	)
	(segment
		(start 328.984102 -244.97157)
		(end 328.992484 -244.966744)
		(width 0.0889)
		(layer "In4.Cu")
		(net "M_D_CPU0_SA_CB<2>")
	)
	(segment
		(start 282.96743 -236.010196)
		(end 289.82416 -236.010196)
		(width 0.14478)
		(layer "In4.Cu")
		(net "M_D_CPU0_SA_CB<2>")
	)
	(segment
		(start 307.21681 -236.422438)
		(end 307.44541 -236.422438)
		(width 0.14478)
		(layer "In4.Cu")
		(net "M_D_CPU0_SA_CB<2>")
	)
	(segment
		(start 324.138544 -244.53342)
		(end 324.293992 -244.377972)
		(width 0.0889)
		(layer "In4.Cu")
		(net "M_D_CPU0_SA_CB<2>")
	)
	(segment
		(start 282.08478 -236.010196)
		(end 282.247848 -235.847128)
		(width 0.14478)
		(layer "In4.Cu")
		(net "M_D_CPU0_SA_CB<2>")
	)
	(segment
		(start 327.461372 -244.96141)
		(end 327.47966 -244.971824)
		(width 0.0889)
		(layer "In4.Cu")
		(net "M_D_CPU0_SA_CB<2>")
	)
	(segment
		(start 282.247848 -235.396278)
		(end 282.410916 -235.23321)
		(width 0.14478)
		(layer "In4.Cu")
		(net "M_D_CPU0_SA_CB<2>")
	)
	(segment
		(start 307.980588 -236.667548)
		(end 307.835554 -236.812582)
		(width 0.14478)
		(layer "In4.Cu")
		(net "M_D_CPU0_SA_CB<2>")
	)
	(segment
		(start 297.312334 -236.010196)
		(end 298.162472 -235.160058)
		(width 0.14478)
		(layer "In4.Cu")
		(net "M_D_CPU0_SA_CB<2>")
	)
	(segment
		(start 294.357806 -236.010196)
		(end 297.312334 -236.010196)
		(width 0.14478)
		(layer "In4.Cu")
		(net "M_D_CPU0_SA_CB<2>")
	)
	(arc
		(start 329.924156 -244.97157)
		(mid 330.1111 -244.921315)
		(end 330.298044 -244.97157)
		(width 0.0889)
		(layer "In4.Cu")
		(net "M_D_CPU0_SA_CB<2>")
	)
	(arc
		(start 337.818222 -244.97157)
		(mid 338.101178 -245.047747)
		(end 338.384134 -244.97157)
		(width 0.0889)
		(layer "In4.Cu")
		(net "M_D_CPU0_SA_CB<2>")
	)
	(arc
		(start 328.992484 -244.966744)
		(mid 329.175992 -244.92125)
		(end 329.358244 -244.97157)
		(width 0.0889)
		(layer "In4.Cu")
		(net "M_D_CPU0_SA_CB<2>")
	)
	(arc
		(start 330.298044 -244.97157)
		(mid 330.581 -245.047747)
		(end 330.863956 -244.97157)
		(width 0.0889)
		(layer "In4.Cu")
		(net "M_D_CPU0_SA_CB<2>")
	)
	(arc
		(start 333.6925 -244.966744)
		(mid 333.876008 -244.92125)
		(end 334.05826 -244.97157)
		(width 0.0889)
		(layer "In4.Cu")
		(net "M_D_CPU0_SA_CB<2>")
	)
	(arc
		(start 333.118206 -244.97157)
		(mid 333.401162 -245.047747)
		(end 333.684118 -244.97157)
		(width 0.0889)
		(layer "In4.Cu")
		(net "M_D_CPU0_SA_CB<2>")
	)
	(arc
		(start 336.504026 -244.97157)
		(mid 336.686277 -244.92122)
		(end 336.869786 -244.966744)
		(width 0.0889)
		(layer "In4.Cu")
		(net "M_D_CPU0_SA_CB<2>")
	)
	(arc
		(start 334.624172 -244.97157)
		(mid 334.811116 -244.921315)
		(end 334.99806 -244.97157)
		(width 0.0889)
		(layer "In4.Cu")
		(net "M_D_CPU0_SA_CB<2>")
	)
	(arc
		(start 331.238098 -244.97157)
		(mid 331.521054 -245.047747)
		(end 331.80401 -244.97157)
		(width 0.0889)
		(layer "In4.Cu")
		(net "M_D_CPU0_SA_CB<2>")
	)
	(arc
		(start 335.563972 -244.97157)
		(mid 335.746223 -244.92122)
		(end 335.929732 -244.966744)
		(width 0.0889)
		(layer "In4.Cu")
		(net "M_D_CPU0_SA_CB<2>")
	)
	(arc
		(start 326.351138 -244.920516)
		(mid 326.448641 -244.933531)
		(end 326.539352 -244.97157)
		(width 0.0889)
		(layer "In4.Cu")
		(net "M_D_CPU0_SA_CB<2>")
	)
	(arc
		(start 336.878168 -244.97157)
		(mid 337.161124 -245.047747)
		(end 337.44408 -244.97157)
		(width 0.0889)
		(layer "In4.Cu")
		(net "M_D_CPU0_SA_CB<2>")
	)
	(arc
		(start 328.41819 -244.97157)
		(mid 328.701146 -245.047747)
		(end 328.984102 -244.97157)
		(width 0.0889)
		(layer "In4.Cu")
		(net "M_D_CPU0_SA_CB<2>")
	)
	(arc
		(start 332.178152 -244.97157)
		(mid 332.461108 -245.047747)
		(end 332.744064 -244.97157)
		(width 0.0889)
		(layer "In4.Cu")
		(net "M_D_CPU0_SA_CB<2>")
	)
	(arc
		(start 331.80401 -244.97157)
		(mid 331.986261 -244.92122)
		(end 332.16977 -244.966744)
		(width 0.0889)
		(layer "In4.Cu")
		(net "M_D_CPU0_SA_CB<2>")
	)
	(arc
		(start 327.106534 -244.97157)
		(mid 327.282654 -244.921592)
		(end 327.461372 -244.96141)
		(width 0.0889)
		(layer "In4.Cu")
		(net "M_D_CPU0_SA_CB<2>")
	)
	(arc
		(start 327.50125 -244.98427)
		(mid 327.774279 -245.047589)
		(end 328.044048 -244.97157)
		(width 0.0889)
		(layer "In4.Cu")
		(net "M_D_CPU0_SA_CB<2>")
	)
	(arc
		(start 334.99806 -244.97157)
		(mid 335.281016 -245.047747)
		(end 335.563972 -244.97157)
		(width 0.0889)
		(layer "In4.Cu")
		(net "M_D_CPU0_SA_CB<2>")
	)
	(arc
		(start 334.05826 -244.97157)
		(mid 334.341216 -245.047747)
		(end 334.624172 -244.97157)
		(width 0.0889)
		(layer "In4.Cu")
		(net "M_D_CPU0_SA_CB<2>")
	)
	(arc
		(start 337.452462 -244.966744)
		(mid 337.63597 -244.92125)
		(end 337.818222 -244.97157)
		(width 0.0889)
		(layer "In4.Cu")
		(net "M_D_CPU0_SA_CB<2>")
	)
	(arc
		(start 326.539352 -244.97157)
		(mid 326.809509 -245.048332)
		(end 327.083166 -244.985286)
		(width 0.0889)
		(layer "In4.Cu")
		(net "M_D_CPU0_SA_CB<2>")
	)
	(arc
		(start 330.863956 -244.97157)
		(mid 331.046207 -244.92122)
		(end 331.229716 -244.966744)
		(width 0.0889)
		(layer "In4.Cu")
		(net "M_D_CPU0_SA_CB<2>")
	)
	(arc
		(start 329.358244 -244.97157)
		(mid 329.6412 -245.047747)
		(end 329.924156 -244.97157)
		(width 0.0889)
		(layer "In4.Cu")
		(net "M_D_CPU0_SA_CB<2>")
	)
	(arc
		(start 332.752446 -244.966744)
		(mid 332.935954 -244.92125)
		(end 333.118206 -244.97157)
		(width 0.0889)
		(layer "In4.Cu")
		(net "M_D_CPU0_SA_CB<2>")
	)
	(arc
		(start 328.044048 -244.97157)
		(mid 328.226299 -244.92122)
		(end 328.409808 -244.966744)
		(width 0.0889)
		(layer "In4.Cu")
		(net "M_D_CPU0_SA_CB<2>")
	)
	(arc
		(start 338.384134 -244.97157)
		(mid 338.540453 -244.922575)
		(end 338.70265 -244.945408)
		(width 0.0889)
		(layer "In4.Cu")
		(net "M_D_CPU0_SA_CB<2>")
	)
	(arc
		(start 335.938114 -244.97157)
		(mid 336.22107 -245.047747)
		(end 336.504026 -244.97157)
		(width 0.0889)
		(layer "In4.Cu")
		(net "M_D_CPU0_SA_CB<2>")
	)
	(segment
		(start 340.918038 -245.560088)
		(end 340.451186 -245.29415)
		(width 0.10668)
		(layer "F.Cu")
		(net "M_D_CPU0_SA_CB<1>")
	)
	(segment
		(start 291.15766 -236.173264)
		(end 291.15766 -236.236002)
		(width 0.14478)
		(layer "In4.Cu")
		(net "M_D_CPU0_SA_CB<1>")
	)
	(segment
		(start 295.081452 -236.615732)
		(end 295.3258 -236.86008)
		(width 0.14478)
		(layer "In4.Cu")
		(net "M_D_CPU0_SA_CB<1>")
	)
	(segment
		(start 291.714174 -236.236002)
		(end 291.714174 -236.173264)
		(width 0.14478)
		(layer "In4.Cu")
		(net "M_D_CPU0_SA_CB<1>")
	)
	(segment
		(start 296.93235 -236.633258)
		(end 296.93235 -236.697012)
		(width 0.14478)
		(layer "In4.Cu")
		(net "M_D_CPU0_SA_CB<1>")
	)
	(segment
		(start 302.024542 -236.86008)
		(end 302.319944 -236.86008)
		(width 0.14478)
		(layer "In4.Cu")
		(net "M_D_CPU0_SA_CB<1>")
	)
	(segment
		(start 303.039526 -237.023148)
		(end 303.202594 -236.86008)
		(width 0.14478)
		(layer "In4.Cu")
		(net "M_D_CPU0_SA_CB<1>")
	)
	(segment
		(start 303.989486 -237.25251)
		(end 304.152554 -237.089442)
		(width 0.14478)
		(layer "In4.Cu")
		(net "M_D_CPU0_SA_CB<1>")
	)
	(segment
		(start 301.023528 -236.010196)
		(end 301.174658 -236.010196)
		(width 0.14478)
		(layer "In4.Cu")
		(net "M_D_CPU0_SA_CB<1>")
	)
	(segment
		(start 291.714174 -236.173264)
		(end 291.877242 -236.010196)
		(width 0.14478)
		(layer "In4.Cu")
		(net "M_D_CPU0_SA_CB<1>")
	)
	(segment
		(start 302.64608 -237.25251)
		(end 302.876458 -237.25251)
		(width 0.14478)
		(layer "In4.Cu")
		(net "M_D_CPU0_SA_CB<1>")
	)
	(segment
		(start 287.509204 -237.023148)
		(end 287.672272 -236.86008)
		(width 0.14478)
		(layer "In4.Cu")
		(net "M_D_CPU0_SA_CB<1>")
	)
	(segment
		(start 289.293046 -236.557312)
		(end 289.595814 -236.86008)
		(width 0.14478)
		(layer "In4.Cu")
		(net "M_D_CPU0_SA_CB<1>")
	)
	(segment
		(start 294.774366 -236.615732)
		(end 295.081452 -236.615732)
		(width 0.14478)
		(layer "In4.Cu")
		(net "M_D_CPU0_SA_CB<1>")
	)
	(segment
		(start 286.237426 -237.248192)
		(end 286.396176 -237.089442)
		(width 0.14478)
		(layer "In4.Cu")
		(net "M_D_CPU0_SA_CB<1>")
	)
	(segment
		(start 286.396176 -237.089442)
		(end 286.396176 -236.658658)
		(width 0.14478)
		(layer "In4.Cu")
		(net "M_D_CPU0_SA_CB<1>")
	)
	(segment
		(start 304.152554 -237.023148)
		(end 304.315622 -236.86008)
		(width 0.14478)
		(layer "In4.Cu")
		(net "M_D_CPU0_SA_CB<1>")
	)
	(segment
		(start 326.537828 -245.616476)
		(end 326.543416 -245.613174)
		(width 0.0889)
		(layer "In4.Cu")
		(net "M_D_CPU0_SA_CB<1>")
	)
	(segment
		(start 299.376338 -236.010196)
		(end 300.23181 -236.010196)
		(width 0.14478)
		(layer "In4.Cu")
		(net "M_D_CPU0_SA_CB<1>")
	)
	(segment
		(start 290.994592 -236.010196)
		(end 291.15766 -236.173264)
		(width 0.14478)
		(layer "In4.Cu")
		(net "M_D_CPU0_SA_CB<1>")
	)
	(segment
		(start 284.736032 -236.435138)
		(end 285.160974 -236.86008)
		(width 0.14478)
		(layer "In4.Cu")
		(net "M_D_CPU0_SA_CB<1>")
	)
	(segment
		(start 304.485802 -236.86008)
		(end 304.78095 -236.564932)
		(width 0.14478)
		(layer "In4.Cu")
		(net "M_D_CPU0_SA_CB<1>")
	)
	(segment
		(start 299.21327 -236.236002)
		(end 299.21327 -236.173264)
		(width 0.14478)
		(layer "In4.Cu")
		(net "M_D_CPU0_SA_CB<1>")
	)
	(segment
		(start 297.346878 -236.86008)
		(end 298.196762 -236.010196)
		(width 0.14478)
		(layer "In4.Cu")
		(net "M_D_CPU0_SA_CB<1>")
	)
	(segment
		(start 332.744064 -245.61673)
		(end 332.752446 -245.621556)
		(width 0.0889)
		(layer "In4.Cu")
		(net "M_D_CPU0_SA_CB<1>")
	)
	(segment
		(start 325.645272 -245.54053)
		(end 325.880476 -245.54053)
		(width 0.0889)
		(layer "In4.Cu")
		(net "M_D_CPU0_SA_CB<1>")
	)
	(segment
		(start 299.050202 -236.39907)
		(end 299.21327 -236.236002)
		(width 0.14478)
		(layer "In4.Cu")
		(net "M_D_CPU0_SA_CB<1>")
	)
	(segment
		(start 304.78095 -236.564932)
		(end 305.037236 -236.564932)
		(width 0.14478)
		(layer "In4.Cu")
		(net "M_D_CPU0_SA_CB<1>")
	)
	(segment
		(start 296.375836 -236.697012)
		(end 296.375836 -236.633258)
		(width 0.14478)
		(layer "In4.Cu")
		(net "M_D_CPU0_SA_CB<1>")
	)
	(segment
		(start 291.15766 -236.236002)
		(end 291.320728 -236.39907)
		(width 0.14478)
		(layer "In4.Cu")
		(net "M_D_CPU0_SA_CB<1>")
	)
	(segment
		(start 289.823398 -236.86008)
		(end 290.673282 -236.010196)
		(width 0.14478)
		(layer "In4.Cu")
		(net "M_D_CPU0_SA_CB<1>")
	)
	(segment
		(start 327.103232 -245.61673)
		(end 327.111614 -245.621556)
		(width 0.0889)
		(layer "In4.Cu")
		(net "M_D_CPU0_SA_CB<1>")
	)
	(segment
		(start 332.16977 -245.621556)
		(end 332.178152 -245.61673)
		(width 0.0889)
		(layer "In4.Cu")
		(net "M_D_CPU0_SA_CB<1>")
	)
	(segment
		(start 291.877242 -236.010196)
		(end 293.498778 -236.010196)
		(width 0.14478)
		(layer "In4.Cu")
		(net "M_D_CPU0_SA_CB<1>")
	)
	(segment
		(start 293.498778 -236.010196)
		(end 294.348662 -236.86008)
		(width 0.14478)
		(layer "In4.Cu")
		(net "M_D_CPU0_SA_CB<1>")
	)
	(segment
		(start 285.998412 -237.248192)
		(end 286.237426 -237.248192)
		(width 0.14478)
		(layer "In4.Cu")
		(net "M_D_CPU0_SA_CB<1>")
	)
	(segment
		(start 296.375836 -236.633258)
		(end 296.538904 -236.47019)
		(width 0.14478)
		(layer "In4.Cu")
		(net "M_D_CPU0_SA_CB<1>")
	)
	(segment
		(start 296.538904 -236.47019)
		(end 296.769282 -236.47019)
		(width 0.14478)
		(layer "In4.Cu")
		(net "M_D_CPU0_SA_CB<1>")
	)
	(segment
		(start 291.320728 -236.39907)
		(end 291.551106 -236.39907)
		(width 0.14478)
		(layer "In4.Cu")
		(net "M_D_CPU0_SA_CB<1>")
	)
	(segment
		(start 303.59604 -237.089442)
		(end 303.759108 -237.25251)
		(width 0.14478)
		(layer "In4.Cu")
		(net "M_D_CPU0_SA_CB<1>")
	)
	(segment
		(start 306.140104 -236.564932)
		(end 306.435252 -236.86008)
		(width 0.14478)
		(layer "In4.Cu")
		(net "M_D_CPU0_SA_CB<1>")
	)
	(segment
		(start 304.315622 -236.86008)
		(end 304.485802 -236.86008)
		(width 0.14478)
		(layer "In4.Cu")
		(net "M_D_CPU0_SA_CB<1>")
	)
	(segment
		(start 286.95269 -237.089442)
		(end 287.11144 -237.248192)
		(width 0.14478)
		(layer "In4.Cu")
		(net "M_D_CPU0_SA_CB<1>")
	)
	(segment
		(start 288.741612 -236.86008)
		(end 289.04438 -236.557312)
		(width 0.14478)
		(layer "In4.Cu")
		(net "M_D_CPU0_SA_CB<1>")
	)
	(segment
		(start 302.876458 -237.25251)
		(end 303.039526 -237.089442)
		(width 0.14478)
		(layer "In4.Cu")
		(net "M_D_CPU0_SA_CB<1>")
	)
	(segment
		(start 286.559244 -236.49559)
		(end 286.789622 -236.49559)
		(width 0.14478)
		(layer "In4.Cu")
		(net "M_D_CPU0_SA_CB<1>")
	)
	(segment
		(start 324.179184 -244.983)
		(end 324.569836 -245.373652)
		(width 0.0889)
		(layer "In4.Cu")
		(net "M_D_CPU0_SA_CB<1>")
	)
	(segment
		(start 297.095418 -236.86008)
		(end 297.346878 -236.86008)
		(width 0.14478)
		(layer "In4.Cu")
		(net "M_D_CPU0_SA_CB<1>")
	)
	(segment
		(start 286.95269 -236.658658)
		(end 286.95269 -237.089442)
		(width 0.14478)
		(layer "In4.Cu")
		(net "M_D_CPU0_SA_CB<1>")
	)
	(segment
		(start 335.929732 -245.621556)
		(end 335.938114 -245.61673)
		(width 0.0889)
		(layer "In4.Cu")
		(net "M_D_CPU0_SA_CB<1>")
	)
	(segment
		(start 305.332384 -236.86008)
		(end 305.58867 -236.86008)
		(width 0.14478)
		(layer "In4.Cu")
		(net "M_D_CPU0_SA_CB<1>")
	)
	(segment
		(start 302.319944 -236.86008)
		(end 302.483012 -237.023148)
		(width 0.14478)
		(layer "In4.Cu")
		(net "M_D_CPU0_SA_CB<1>")
	)
	(segment
		(start 285.839662 -237.023148)
		(end 285.839662 -237.089442)
		(width 0.14478)
		(layer "In4.Cu")
		(net "M_D_CPU0_SA_CB<1>")
	)
	(segment
		(start 300.472094 -235.769912)
		(end 300.783244 -235.769912)
		(width 0.14478)
		(layer "In4.Cu")
		(net "M_D_CPU0_SA_CB<1>")
	)
	(segment
		(start 305.037236 -236.564932)
		(end 305.332384 -236.86008)
		(width 0.14478)
		(layer "In4.Cu")
		(net "M_D_CPU0_SA_CB<1>")
	)
	(segment
		(start 302.483012 -237.089442)
		(end 302.64608 -237.25251)
		(width 0.14478)
		(layer "In4.Cu")
		(net "M_D_CPU0_SA_CB<1>")
	)
	(segment
		(start 328.033634 -245.610634)
		(end 328.044048 -245.61673)
		(width 0.0889)
		(layer "In4.Cu")
		(net "M_D_CPU0_SA_CB<1>")
	)
	(segment
		(start 296.93235 -236.697012)
		(end 297.095418 -236.86008)
		(width 0.14478)
		(layer "In4.Cu")
		(net "M_D_CPU0_SA_CB<1>")
	)
	(segment
		(start 299.21327 -236.173264)
		(end 299.376338 -236.010196)
		(width 0.14478)
		(layer "In4.Cu")
		(net "M_D_CPU0_SA_CB<1>")
	)
	(segment
		(start 305.883818 -236.564932)
		(end 306.140104 -236.564932)
		(width 0.14478)
		(layer "In4.Cu")
		(net "M_D_CPU0_SA_CB<1>")
	)
	(segment
		(start 328.409808 -245.621556)
		(end 328.41819 -245.61673)
		(width 0.0889)
		(layer "In4.Cu")
		(net "M_D_CPU0_SA_CB<1>")
	)
	(segment
		(start 301.174658 -236.010196)
		(end 302.024542 -236.86008)
		(width 0.14478)
		(layer "In4.Cu")
		(net "M_D_CPU0_SA_CB<1>")
	)
	(segment
		(start 337.44408 -245.61673)
		(end 337.452462 -245.621556)
		(width 0.0889)
		(layer "In4.Cu")
		(net "M_D_CPU0_SA_CB<1>")
	)
	(segment
		(start 285.160974 -236.86008)
		(end 285.676594 -236.86008)
		(width 0.14478)
		(layer "In4.Cu")
		(net "M_D_CPU0_SA_CB<1>")
	)
	(segment
		(start 289.595814 -236.86008)
		(end 289.823398 -236.86008)
		(width 0.14478)
		(layer "In4.Cu")
		(net "M_D_CPU0_SA_CB<1>")
	)
	(segment
		(start 285.839662 -237.089442)
		(end 285.998412 -237.248192)
		(width 0.14478)
		(layer "In4.Cu")
		(net "M_D_CPU0_SA_CB<1>")
	)
	(segment
		(start 303.202594 -236.86008)
		(end 303.432972 -236.86008)
		(width 0.14478)
		(layer "In4.Cu")
		(net "M_D_CPU0_SA_CB<1>")
	)
	(segment
		(start 304.152554 -237.089442)
		(end 304.152554 -237.023148)
		(width 0.14478)
		(layer "In4.Cu")
		(net "M_D_CPU0_SA_CB<1>")
	)
	(segment
		(start 287.350454 -237.248192)
		(end 287.509204 -237.089442)
		(width 0.14478)
		(layer "In4.Cu")
		(net "M_D_CPU0_SA_CB<1>")
	)
	(segment
		(start 303.759108 -237.25251)
		(end 303.989486 -237.25251)
		(width 0.14478)
		(layer "In4.Cu")
		(net "M_D_CPU0_SA_CB<1>")
	)
	(segment
		(start 336.869786 -245.621556)
		(end 336.878168 -245.61673)
		(width 0.0889)
		(layer "In4.Cu")
		(net "M_D_CPU0_SA_CB<1>")
	)
	(segment
		(start 294.348662 -236.86008)
		(end 294.530018 -236.86008)
		(width 0.14478)
		(layer "In4.Cu")
		(net "M_D_CPU0_SA_CB<1>")
	)
	(segment
		(start 333.684118 -245.61673)
		(end 333.6925 -245.621556)
		(width 0.0889)
		(layer "In4.Cu")
		(net "M_D_CPU0_SA_CB<1>")
	)
	(segment
		(start 295.3258 -236.86008)
		(end 296.212768 -236.86008)
		(width 0.14478)
		(layer "In4.Cu")
		(net "M_D_CPU0_SA_CB<1>")
	)
	(segment
		(start 302.483012 -237.023148)
		(end 302.483012 -237.089442)
		(width 0.14478)
		(layer "In4.Cu")
		(net "M_D_CPU0_SA_CB<1>")
	)
	(segment
		(start 296.769282 -236.47019)
		(end 296.93235 -236.633258)
		(width 0.14478)
		(layer "In4.Cu")
		(net "M_D_CPU0_SA_CB<1>")
	)
	(segment
		(start 339.689694 -245.621556)
		(end 339.698076 -245.61673)
		(width 0.0889)
		(layer "In4.Cu")
		(net "M_D_CPU0_SA_CB<1>")
	)
	(segment
		(start 303.039526 -237.089442)
		(end 303.039526 -237.023148)
		(width 0.14478)
		(layer "In4.Cu")
		(net "M_D_CPU0_SA_CB<1>")
	)
	(segment
		(start 298.819824 -236.39907)
		(end 299.050202 -236.39907)
		(width 0.14478)
		(layer "In4.Cu")
		(net "M_D_CPU0_SA_CB<1>")
	)
	(segment
		(start 305.58867 -236.86008)
		(end 305.883818 -236.564932)
		(width 0.14478)
		(layer "In4.Cu")
		(net "M_D_CPU0_SA_CB<1>")
	)
	(segment
		(start 286.789622 -236.49559)
		(end 286.95269 -236.658658)
		(width 0.14478)
		(layer "In4.Cu")
		(net "M_D_CPU0_SA_CB<1>")
	)
	(segment
		(start 306.435252 -236.86008)
		(end 306.940712 -236.86008)
		(width 0.14478)
		(layer "In4.Cu")
		(net "M_D_CPU0_SA_CB<1>")
	)
	(segment
		(start 340.200742 -245.58498)
		(end 340.297008 -245.55958)
		(width 0.0889)
		(layer "In4.Cu")
		(net "M_D_CPU0_SA_CB<1>")
	)
	(segment
		(start 298.656756 -236.173264)
		(end 298.656756 -236.236002)
		(width 0.14478)
		(layer "In4.Cu")
		(net "M_D_CPU0_SA_CB<1>")
	)
	(segment
		(start 289.04438 -236.557312)
		(end 289.293046 -236.557312)
		(width 0.14478)
		(layer "In4.Cu")
		(net "M_D_CPU0_SA_CB<1>")
	)
	(segment
		(start 287.509204 -237.089442)
		(end 287.509204 -237.023148)
		(width 0.14478)
		(layer "In4.Cu")
		(net "M_D_CPU0_SA_CB<1>")
	)
	(segment
		(start 294.530018 -236.86008)
		(end 294.774366 -236.615732)
		(width 0.14478)
		(layer "In4.Cu")
		(net "M_D_CPU0_SA_CB<1>")
	)
	(segment
		(start 303.432972 -236.86008)
		(end 303.59604 -237.023148)
		(width 0.14478)
		(layer "In4.Cu")
		(net "M_D_CPU0_SA_CB<1>")
	)
	(segment
		(start 340.297008 -245.55958)
		(end 340.451186 -245.29415)
		(width 0.0889)
		(layer "In4.Cu")
		(net "M_D_CPU0_SA_CB<1>")
	)
	(segment
		(start 328.984102 -245.61673)
		(end 328.992484 -245.621556)
		(width 0.0889)
		(layer "In4.Cu")
		(net "M_D_CPU0_SA_CB<1>")
	)
	(segment
		(start 298.656756 -236.236002)
		(end 298.819824 -236.39907)
		(width 0.14478)
		(layer "In4.Cu")
		(net "M_D_CPU0_SA_CB<1>")
	)
	(segment
		(start 286.396176 -236.658658)
		(end 286.559244 -236.49559)
		(width 0.14478)
		(layer "In4.Cu")
		(net "M_D_CPU0_SA_CB<1>")
	)
	(segment
		(start 298.196762 -236.010196)
		(end 298.493688 -236.010196)
		(width 0.14478)
		(layer "In4.Cu")
		(net "M_D_CPU0_SA_CB<1>")
	)
	(segment
		(start 300.23181 -236.010196)
		(end 300.472094 -235.769912)
		(width 0.14478)
		(layer "In4.Cu")
		(net "M_D_CPU0_SA_CB<1>")
	)
	(segment
		(start 287.11144 -237.248192)
		(end 287.350454 -237.248192)
		(width 0.14478)
		(layer "In4.Cu")
		(net "M_D_CPU0_SA_CB<1>")
	)
	(segment
		(start 325.478394 -245.373652)
		(end 325.645272 -245.54053)
		(width 0.0889)
		(layer "In4.Cu")
		(net "M_D_CPU0_SA_CB<1>")
	)
	(segment
		(start 298.493688 -236.010196)
		(end 298.656756 -236.173264)
		(width 0.14478)
		(layer "In4.Cu")
		(net "M_D_CPU0_SA_CB<1>")
	)
	(segment
		(start 287.672272 -236.86008)
		(end 288.741612 -236.86008)
		(width 0.14478)
		(layer "In4.Cu")
		(net "M_D_CPU0_SA_CB<1>")
	)
	(segment
		(start 306.940712 -236.86008)
		(end 315.063632 -244.983)
		(width 0.14478)
		(layer "In4.Cu")
		(net "M_D_CPU0_SA_CB<1>")
	)
	(segment
		(start 331.229716 -245.621556)
		(end 331.238098 -245.61673)
		(width 0.0889)
		(layer "In4.Cu")
		(net "M_D_CPU0_SA_CB<1>")
	)
	(segment
		(start 324.569836 -245.373652)
		(end 325.478394 -245.373652)
		(width 0.0889)
		(layer "In4.Cu")
		(net "M_D_CPU0_SA_CB<1>")
	)
	(segment
		(start 291.551106 -236.39907)
		(end 291.714174 -236.236002)
		(width 0.14478)
		(layer "In4.Cu")
		(net "M_D_CPU0_SA_CB<1>")
	)
	(segment
		(start 296.212768 -236.86008)
		(end 296.375836 -236.697012)
		(width 0.14478)
		(layer "In4.Cu")
		(net "M_D_CPU0_SA_CB<1>")
	)
	(segment
		(start 285.676594 -236.86008)
		(end 285.839662 -237.023148)
		(width 0.14478)
		(layer "In4.Cu")
		(net "M_D_CPU0_SA_CB<1>")
	)
	(segment
		(start 326.51954 -245.62689)
		(end 326.537828 -245.616476)
		(width 0.0889)
		(layer "In4.Cu")
		(net "M_D_CPU0_SA_CB<1>")
	)
	(segment
		(start 303.59604 -237.023148)
		(end 303.59604 -237.089442)
		(width 0.14478)
		(layer "In4.Cu")
		(net "M_D_CPU0_SA_CB<1>")
	)
	(segment
		(start 315.063632 -244.983)
		(end 324.179184 -244.983)
		(width 0.14478)
		(layer "In4.Cu")
		(net "M_D_CPU0_SA_CB<1>")
	)
	(segment
		(start 290.673282 -236.010196)
		(end 290.994592 -236.010196)
		(width 0.14478)
		(layer "In4.Cu")
		(net "M_D_CPU0_SA_CB<1>")
	)
	(segment
		(start 300.783244 -235.769912)
		(end 301.023528 -236.010196)
		(width 0.14478)
		(layer "In4.Cu")
		(net "M_D_CPU0_SA_CB<1>")
	)
	(arc
		(start 331.238098 -245.61673)
		(mid 331.521054 -245.540553)
		(end 331.80401 -245.61673)
		(width 0.0889)
		(layer "In4.Cu")
		(net "M_D_CPU0_SA_CB<1>")
	)
	(arc
		(start 328.044048 -245.61673)
		(mid 328.226299 -245.66708)
		(end 328.409808 -245.621556)
		(width 0.0889)
		(layer "In4.Cu")
		(net "M_D_CPU0_SA_CB<1>")
	)
	(arc
		(start 332.752446 -245.621556)
		(mid 332.935954 -245.66705)
		(end 333.118206 -245.61673)
		(width 0.0889)
		(layer "In4.Cu")
		(net "M_D_CPU0_SA_CB<1>")
	)
	(arc
		(start 328.41819 -245.61673)
		(mid 328.701146 -245.540553)
		(end 328.984102 -245.61673)
		(width 0.0889)
		(layer "In4.Cu")
		(net "M_D_CPU0_SA_CB<1>")
	)
	(arc
		(start 333.6925 -245.621556)
		(mid 333.876008 -245.66705)
		(end 334.05826 -245.61673)
		(width 0.0889)
		(layer "In4.Cu")
		(net "M_D_CPU0_SA_CB<1>")
	)
	(arc
		(start 335.938114 -245.61673)
		(mid 336.22107 -245.540553)
		(end 336.504026 -245.61673)
		(width 0.0889)
		(layer "In4.Cu")
		(net "M_D_CPU0_SA_CB<1>")
	)
	(arc
		(start 328.992484 -245.621556)
		(mid 329.175992 -245.66705)
		(end 329.358244 -245.61673)
		(width 0.0889)
		(layer "In4.Cu")
		(net "M_D_CPU0_SA_CB<1>")
	)
	(arc
		(start 333.118206 -245.61673)
		(mid 333.401162 -245.540553)
		(end 333.684118 -245.61673)
		(width 0.0889)
		(layer "In4.Cu")
		(net "M_D_CPU0_SA_CB<1>")
	)
	(arc
		(start 337.452462 -245.621556)
		(mid 337.63597 -245.66705)
		(end 337.818222 -245.61673)
		(width 0.0889)
		(layer "In4.Cu")
		(net "M_D_CPU0_SA_CB<1>")
	)
	(arc
		(start 339.323934 -245.61673)
		(mid 339.506185 -245.66708)
		(end 339.689694 -245.621556)
		(width 0.0889)
		(layer "In4.Cu")
		(net "M_D_CPU0_SA_CB<1>")
	)
	(arc
		(start 336.504026 -245.61673)
		(mid 336.686277 -245.66708)
		(end 336.869786 -245.621556)
		(width 0.0889)
		(layer "In4.Cu")
		(net "M_D_CPU0_SA_CB<1>")
	)
	(arc
		(start 335.563972 -245.61673)
		(mid 335.746223 -245.66708)
		(end 335.929732 -245.621556)
		(width 0.0889)
		(layer "In4.Cu")
		(net "M_D_CPU0_SA_CB<1>")
	)
	(arc
		(start 334.99806 -245.61673)
		(mid 335.281016 -245.540553)
		(end 335.563972 -245.61673)
		(width 0.0889)
		(layer "In4.Cu")
		(net "M_D_CPU0_SA_CB<1>")
	)
	(arc
		(start 334.624172 -245.61673)
		(mid 334.811116 -245.666985)
		(end 334.99806 -245.61673)
		(width 0.0889)
		(layer "In4.Cu")
		(net "M_D_CPU0_SA_CB<1>")
	)
	(arc
		(start 329.924156 -245.61673)
		(mid 330.1111 -245.666985)
		(end 330.298044 -245.61673)
		(width 0.0889)
		(layer "In4.Cu")
		(net "M_D_CPU0_SA_CB<1>")
	)
	(arc
		(start 334.05826 -245.61673)
		(mid 334.341216 -245.540553)
		(end 334.624172 -245.61673)
		(width 0.0889)
		(layer "In4.Cu")
		(net "M_D_CPU0_SA_CB<1>")
	)
	(arc
		(start 337.818222 -245.61673)
		(mid 338.101178 -245.540553)
		(end 338.384134 -245.61673)
		(width 0.0889)
		(layer "In4.Cu")
		(net "M_D_CPU0_SA_CB<1>")
	)
	(arc
		(start 327.477882 -245.61673)
		(mid 327.754949 -245.540459)
		(end 328.033634 -245.610634)
		(width 0.0889)
		(layer "In4.Cu")
		(net "M_D_CPU0_SA_CB<1>")
	)
	(arc
		(start 338.384134 -245.61673)
		(mid 338.571078 -245.666985)
		(end 338.758022 -245.61673)
		(width 0.0889)
		(layer "In4.Cu")
		(net "M_D_CPU0_SA_CB<1>")
	)
	(arc
		(start 326.163686 -245.61673)
		(mid 326.340314 -245.666963)
		(end 326.51954 -245.62689)
		(width 0.0889)
		(layer "In4.Cu")
		(net "M_D_CPU0_SA_CB<1>")
	)
	(arc
		(start 339.698076 -245.61673)
		(mid 339.945672 -245.541552)
		(end 340.200742 -245.58498)
		(width 0.0889)
		(layer "In4.Cu")
		(net "M_D_CPU0_SA_CB<1>")
	)
	(arc
		(start 336.878168 -245.61673)
		(mid 337.161124 -245.540553)
		(end 337.44408 -245.61673)
		(width 0.0889)
		(layer "In4.Cu")
		(net "M_D_CPU0_SA_CB<1>")
	)
	(arc
		(start 326.543416 -245.613174)
		(mid 326.823805 -245.540505)
		(end 327.103232 -245.61673)
		(width 0.0889)
		(layer "In4.Cu")
		(net "M_D_CPU0_SA_CB<1>")
	)
	(arc
		(start 330.298044 -245.61673)
		(mid 330.581 -245.540553)
		(end 330.863956 -245.61673)
		(width 0.0889)
		(layer "In4.Cu")
		(net "M_D_CPU0_SA_CB<1>")
	)
	(arc
		(start 332.178152 -245.61673)
		(mid 332.461108 -245.540553)
		(end 332.744064 -245.61673)
		(width 0.0889)
		(layer "In4.Cu")
		(net "M_D_CPU0_SA_CB<1>")
	)
	(arc
		(start 327.111614 -245.621556)
		(mid 327.295376 -245.667172)
		(end 327.477882 -245.61673)
		(width 0.0889)
		(layer "In4.Cu")
		(net "M_D_CPU0_SA_CB<1>")
	)
	(arc
		(start 331.80401 -245.61673)
		(mid 331.986261 -245.66708)
		(end 332.16977 -245.621556)
		(width 0.0889)
		(layer "In4.Cu")
		(net "M_D_CPU0_SA_CB<1>")
	)
	(arc
		(start 330.863956 -245.61673)
		(mid 331.046207 -245.66708)
		(end 331.229716 -245.621556)
		(width 0.0889)
		(layer "In4.Cu")
		(net "M_D_CPU0_SA_CB<1>")
	)
	(arc
		(start 329.358244 -245.61673)
		(mid 329.6412 -245.540553)
		(end 329.924156 -245.61673)
		(width 0.0889)
		(layer "In4.Cu")
		(net "M_D_CPU0_SA_CB<1>")
	)
	(arc
		(start 338.758022 -245.61673)
		(mid 339.040978 -245.540553)
		(end 339.323934 -245.61673)
		(width 0.0889)
		(layer "In4.Cu")
		(net "M_D_CPU0_SA_CB<1>")
	)
	(arc
		(start 325.880476 -245.54053)
		(mid 326.027133 -245.559867)
		(end 326.163686 -245.61673)
		(width 0.0889)
		(layer "In4.Cu")
		(net "M_D_CPU0_SA_CB<1>")
	)
	(segment
		(start 339.508084 -244.750082)
		(end 339.040978 -244.484144)
		(width 0.10668)
		(layer "F.Cu")
		(net "M_D_CPU0_SA_CB<0>")
	)
	(segment
		(start 285.755588 -235.55071)
		(end 285.985966 -235.55071)
		(width 0.14478)
		(layer "In4.Cu")
		(net "M_D_CPU0_SA_CB<0>")
	)
	(segment
		(start 310.71947 -239.055656)
		(end 310.947562 -239.055656)
		(width 0.14478)
		(layer "In4.Cu")
		(net "M_D_CPU0_SA_CB<0>")
	)
	(segment
		(start 338.27974 -244.81155)
		(end 338.288122 -244.806724)
		(width 0.0889)
		(layer "In4.Cu")
		(net "M_D_CPU0_SA_CB<0>")
	)
	(segment
		(start 298.436284 -234.310174)
		(end 298.599352 -234.473242)
		(width 0.14478)
		(layer "In4.Cu")
		(net "M_D_CPU0_SA_CB<0>")
	)
	(segment
		(start 291.570156 -234.70235)
		(end 291.733224 -234.539282)
		(width 0.14478)
		(layer "In4.Cu")
		(net "M_D_CPU0_SA_CB<0>")
	)
	(segment
		(start 285.59252 -235.323126)
		(end 285.59252 -235.387642)
		(width 0.14478)
		(layer "In4.Cu")
		(net "M_D_CPU0_SA_CB<0>")
	)
	(segment
		(start 299.318934 -234.310174)
		(end 300.118526 -234.310174)
		(width 0.14478)
		(layer "In4.Cu")
		(net "M_D_CPU0_SA_CB<0>")
	)
	(segment
		(start 287.262062 -235.387642)
		(end 287.262062 -235.323126)
		(width 0.14478)
		(layer "In4.Cu")
		(net "M_D_CPU0_SA_CB<0>")
	)
	(segment
		(start 304.659792 -235.160058)
		(end 307.56733 -235.160058)
		(width 0.14478)
		(layer "In4.Cu")
		(net "M_D_CPU0_SA_CB<0>")
	)
	(segment
		(start 286.868616 -235.55071)
		(end 287.098994 -235.55071)
		(width 0.14478)
		(layer "In4.Cu")
		(net "M_D_CPU0_SA_CB<0>")
	)
	(segment
		(start 286.149034 -235.27512)
		(end 286.312102 -235.112052)
		(width 0.14478)
		(layer "In4.Cu")
		(net "M_D_CPU0_SA_CB<0>")
	)
	(segment
		(start 299.155866 -234.534202)
		(end 299.155866 -234.473242)
		(width 0.14478)
		(layer "In4.Cu")
		(net "M_D_CPU0_SA_CB<0>")
	)
	(segment
		(start 286.705548 -235.27512)
		(end 286.705548 -235.387642)
		(width 0.14478)
		(layer "In4.Cu")
		(net "M_D_CPU0_SA_CB<0>")
	)
	(segment
		(start 304.496724 -235.323126)
		(end 304.659792 -235.160058)
		(width 0.14478)
		(layer "In4.Cu")
		(net "M_D_CPU0_SA_CB<0>")
	)
	(segment
		(start 296.321988 -235.323126)
		(end 296.321988 -235.387642)
		(width 0.14478)
		(layer "In4.Cu")
		(net "M_D_CPU0_SA_CB<0>")
	)
	(segment
		(start 310.700928 -238.521748)
		(end 310.557418 -238.665258)
		(width 0.14478)
		(layer "In4.Cu")
		(net "M_D_CPU0_SA_CB<0>")
	)
	(segment
		(start 296.15892 -235.160058)
		(end 296.321988 -235.323126)
		(width 0.14478)
		(layer "In4.Cu")
		(net "M_D_CPU0_SA_CB<0>")
	)
	(segment
		(start 310.557418 -238.665258)
		(end 310.557418 -238.893604)
		(width 0.14478)
		(layer "In4.Cu")
		(net "M_D_CPU0_SA_CB<0>")
	)
	(segment
		(start 294.649144 -235.382562)
		(end 294.812212 -235.54563)
		(width 0.14478)
		(layer "In4.Cu")
		(net "M_D_CPU0_SA_CB<0>")
	)
	(segment
		(start 300.838108 -234.473242)
		(end 301.001176 -234.310174)
		(width 0.14478)
		(layer "In4.Cu")
		(net "M_D_CPU0_SA_CB<0>")
	)
	(segment
		(start 290.673282 -234.310174)
		(end 291.013642 -234.310174)
		(width 0.14478)
		(layer "In4.Cu")
		(net "M_D_CPU0_SA_CB<0>")
	)
	(segment
		(start 303.777142 -235.160058)
		(end 303.94021 -235.323126)
		(width 0.14478)
		(layer "In4.Cu")
		(net "M_D_CPU0_SA_CB<0>")
	)
	(segment
		(start 303.546764 -235.160058)
		(end 303.777142 -235.160058)
		(width 0.14478)
		(layer "In4.Cu")
		(net "M_D_CPU0_SA_CB<0>")
	)
	(segment
		(start 286.312102 -235.112052)
		(end 286.54248 -235.112052)
		(width 0.14478)
		(layer "In4.Cu")
		(net "M_D_CPU0_SA_CB<0>")
	)
	(segment
		(start 302.99025 -235.55071)
		(end 303.220628 -235.55071)
		(width 0.14478)
		(layer "In4.Cu")
		(net "M_D_CPU0_SA_CB<0>")
	)
	(segment
		(start 303.220628 -235.55071)
		(end 303.383696 -235.387642)
		(width 0.14478)
		(layer "In4.Cu")
		(net "M_D_CPU0_SA_CB<0>")
	)
	(segment
		(start 327.55332 -244.794024)
		(end 327.57491 -244.80647)
		(width 0.0889)
		(layer "In4.Cu")
		(net "M_D_CPU0_SA_CB<0>")
	)
	(segment
		(start 309.158894 -237.49508)
		(end 309.386986 -237.49508)
		(width 0.14478)
		(layer "In4.Cu")
		(net "M_D_CPU0_SA_CB<0>")
	)
	(segment
		(start 323.864478 -244.066314)
		(end 324.919594 -244.066314)
		(width 0.0889)
		(layer "In4.Cu")
		(net "M_D_CPU0_SA_CB<0>")
	)
	(segment
		(start 338.791042 -244.774974)
		(end 338.887054 -244.749574)
		(width 0.0889)
		(layer "In4.Cu")
		(net "M_D_CPU0_SA_CB<0>")
	)
	(segment
		(start 296.878502 -235.323126)
		(end 297.04157 -235.160058)
		(width 0.14478)
		(layer "In4.Cu")
		(net "M_D_CPU0_SA_CB<0>")
	)
	(segment
		(start 284.736032 -234.735116)
		(end 285.160974 -235.160058)
		(width 0.14478)
		(layer "In4.Cu")
		(net "M_D_CPU0_SA_CB<0>")
	)
	(segment
		(start 291.17671 -234.539282)
		(end 291.339778 -234.70235)
		(width 0.14478)
		(layer "In4.Cu")
		(net "M_D_CPU0_SA_CB<0>")
	)
	(segment
		(start 294.348662 -235.160058)
		(end 294.486076 -235.160058)
		(width 0.14478)
		(layer "In4.Cu")
		(net "M_D_CPU0_SA_CB<0>")
	)
	(segment
		(start 311.319164 -238.911892)
		(end 316.473586 -244.066314)
		(width 0.14478)
		(layer "In4.Cu")
		(net "M_D_CPU0_SA_CB<0>")
	)
	(segment
		(start 291.733224 -234.539282)
		(end 291.733224 -234.473242)
		(width 0.14478)
		(layer "In4.Cu")
		(net "M_D_CPU0_SA_CB<0>")
	)
	(segment
		(start 302.827182 -235.387642)
		(end 302.99025 -235.55071)
		(width 0.14478)
		(layer "In4.Cu")
		(net "M_D_CPU0_SA_CB<0>")
	)
	(segment
		(start 285.59252 -235.387642)
		(end 285.755588 -235.55071)
		(width 0.14478)
		(layer "In4.Cu")
		(net "M_D_CPU0_SA_CB<0>")
	)
	(segment
		(start 334.519778 -244.81155)
		(end 334.52816 -244.806724)
		(width 0.0889)
		(layer "In4.Cu")
		(net "M_D_CPU0_SA_CB<0>")
	)
	(segment
		(start 287.098994 -235.55071)
		(end 287.262062 -235.387642)
		(width 0.14478)
		(layer "In4.Cu")
		(net "M_D_CPU0_SA_CB<0>")
	)
	(segment
		(start 338.887054 -244.749574)
		(end 339.040978 -244.484144)
		(width 0.0889)
		(layer "In4.Cu")
		(net "M_D_CPU0_SA_CB<0>")
	)
	(segment
		(start 302.664114 -235.160058)
		(end 302.827182 -235.323126)
		(width 0.14478)
		(layer "In4.Cu")
		(net "M_D_CPU0_SA_CB<0>")
	)
	(segment
		(start 301.174658 -234.310174)
		(end 302.024542 -235.160058)
		(width 0.14478)
		(layer "In4.Cu")
		(net "M_D_CPU0_SA_CB<0>")
	)
	(segment
		(start 310.700928 -238.293656)
		(end 310.700928 -238.521748)
		(width 0.14478)
		(layer "In4.Cu")
		(net "M_D_CPU0_SA_CB<0>")
	)
	(segment
		(start 330.394056 -244.806724)
		(end 330.402438 -244.81155)
		(width 0.0889)
		(layer "In4.Cu")
		(net "M_D_CPU0_SA_CB<0>")
	)
	(segment
		(start 287.262062 -235.323126)
		(end 287.42513 -235.160058)
		(width 0.14478)
		(layer "In4.Cu")
		(net "M_D_CPU0_SA_CB<0>")
	)
	(segment
		(start 291.896292 -234.310174)
		(end 293.498778 -234.310174)
		(width 0.14478)
		(layer "In4.Cu")
		(net "M_D_CPU0_SA_CB<0>")
	)
	(segment
		(start 310.538876 -238.131604)
		(end 310.700928 -238.293656)
		(width 0.14478)
		(layer "In4.Cu")
		(net "M_D_CPU0_SA_CB<0>")
	)
	(segment
		(start 309.92064 -237.513368)
		(end 309.92064 -237.74146)
		(width 0.14478)
		(layer "In4.Cu")
		(net "M_D_CPU0_SA_CB<0>")
	)
	(segment
		(start 304.333656 -235.55071)
		(end 304.496724 -235.387642)
		(width 0.14478)
		(layer "In4.Cu")
		(net "M_D_CPU0_SA_CB<0>")
	)
	(segment
		(start 286.54248 -235.112052)
		(end 286.705548 -235.27512)
		(width 0.14478)
		(layer "In4.Cu")
		(net "M_D_CPU0_SA_CB<0>")
	)
	(segment
		(start 285.160974 -235.160058)
		(end 285.429452 -235.160058)
		(width 0.14478)
		(layer "In4.Cu")
		(net "M_D_CPU0_SA_CB<0>")
	)
	(segment
		(start 287.42513 -235.160058)
		(end 289.823398 -235.160058)
		(width 0.14478)
		(layer "In4.Cu")
		(net "M_D_CPU0_SA_CB<0>")
	)
	(segment
		(start 309.386986 -237.49508)
		(end 309.530496 -237.351316)
		(width 0.14478)
		(layer "In4.Cu")
		(net "M_D_CPU0_SA_CB<0>")
	)
	(segment
		(start 331.33411 -244.806724)
		(end 331.342492 -244.81155)
		(width 0.0889)
		(layer "In4.Cu")
		(net "M_D_CPU0_SA_CB<0>")
	)
	(segment
		(start 294.486076 -235.160058)
		(end 294.649144 -235.323126)
		(width 0.14478)
		(layer "In4.Cu")
		(net "M_D_CPU0_SA_CB<0>")
	)
	(segment
		(start 295.205658 -235.382562)
		(end 295.205658 -235.323126)
		(width 0.14478)
		(layer "In4.Cu")
		(net "M_D_CPU0_SA_CB<0>")
	)
	(segment
		(start 325.583296 -244.730016)
		(end 326.351138 -244.730016)
		(width 0.0889)
		(layer "In4.Cu")
		(net "M_D_CPU0_SA_CB<0>")
	)
	(segment
		(start 310.167274 -238.275368)
		(end 310.310784 -238.131604)
		(width 0.14478)
		(layer "In4.Cu")
		(net "M_D_CPU0_SA_CB<0>")
	)
	(segment
		(start 300.118526 -234.310174)
		(end 300.281594 -234.473242)
		(width 0.14478)
		(layer "In4.Cu")
		(net "M_D_CPU0_SA_CB<0>")
	)
	(segment
		(start 308.996842 -237.104682)
		(end 308.996842 -237.333028)
		(width 0.14478)
		(layer "In4.Cu")
		(net "M_D_CPU0_SA_CB<0>")
	)
	(segment
		(start 310.947562 -239.055656)
		(end 311.091072 -238.911892)
		(width 0.14478)
		(layer "In4.Cu")
		(net "M_D_CPU0_SA_CB<0>")
	)
	(segment
		(start 302.024542 -235.160058)
		(end 302.664114 -235.160058)
		(width 0.14478)
		(layer "In4.Cu")
		(net "M_D_CPU0_SA_CB<0>")
	)
	(segment
		(start 309.758588 -237.351316)
		(end 309.92064 -237.513368)
		(width 0.14478)
		(layer "In4.Cu")
		(net "M_D_CPU0_SA_CB<0>")
	)
	(segment
		(start 286.149034 -235.387642)
		(end 286.149034 -235.27512)
		(width 0.14478)
		(layer "In4.Cu")
		(net "M_D_CPU0_SA_CB<0>")
	)
	(segment
		(start 309.530496 -237.351316)
		(end 309.758588 -237.351316)
		(width 0.14478)
		(layer "In4.Cu")
		(net "M_D_CPU0_SA_CB<0>")
	)
	(segment
		(start 335.094072 -244.806724)
		(end 335.102454 -244.81155)
		(width 0.0889)
		(layer "In4.Cu")
		(net "M_D_CPU0_SA_CB<0>")
	)
	(segment
		(start 308.996842 -237.333028)
		(end 309.158894 -237.49508)
		(width 0.14478)
		(layer "In4.Cu")
		(net "M_D_CPU0_SA_CB<0>")
	)
	(segment
		(start 295.205658 -235.323126)
		(end 295.368726 -235.160058)
		(width 0.14478)
		(layer "In4.Cu")
		(net "M_D_CPU0_SA_CB<0>")
	)
	(segment
		(start 309.92064 -237.74146)
		(end 309.77713 -237.88497)
		(width 0.14478)
		(layer "In4.Cu")
		(net "M_D_CPU0_SA_CB<0>")
	)
	(segment
		(start 289.823398 -235.160058)
		(end 290.673282 -234.310174)
		(width 0.14478)
		(layer "In4.Cu")
		(net "M_D_CPU0_SA_CB<0>")
	)
	(segment
		(start 296.878502 -235.387642)
		(end 296.878502 -235.323126)
		(width 0.14478)
		(layer "In4.Cu")
		(net "M_D_CPU0_SA_CB<0>")
	)
	(segment
		(start 299.155866 -234.473242)
		(end 299.318934 -234.310174)
		(width 0.14478)
		(layer "In4.Cu")
		(net "M_D_CPU0_SA_CB<0>")
	)
	(segment
		(start 297.346878 -235.160058)
		(end 298.196762 -234.310174)
		(width 0.14478)
		(layer "In4.Cu")
		(net "M_D_CPU0_SA_CB<0>")
	)
	(segment
		(start 291.733224 -234.473242)
		(end 291.896292 -234.310174)
		(width 0.14478)
		(layer "In4.Cu")
		(net "M_D_CPU0_SA_CB<0>")
	)
	(segment
		(start 310.310784 -238.131604)
		(end 310.538876 -238.131604)
		(width 0.14478)
		(layer "In4.Cu")
		(net "M_D_CPU0_SA_CB<0>")
	)
	(segment
		(start 304.496724 -235.387642)
		(end 304.496724 -235.323126)
		(width 0.14478)
		(layer "In4.Cu")
		(net "M_D_CPU0_SA_CB<0>")
	)
	(segment
		(start 329.819762 -244.81155)
		(end 329.828144 -244.806724)
		(width 0.0889)
		(layer "In4.Cu")
		(net "M_D_CPU0_SA_CB<0>")
	)
	(segment
		(start 298.599352 -234.473242)
		(end 298.599352 -234.534202)
		(width 0.14478)
		(layer "In4.Cu")
		(net "M_D_CPU0_SA_CB<0>")
	)
	(segment
		(start 309.77713 -237.88497)
		(end 309.77713 -238.113316)
		(width 0.14478)
		(layer "In4.Cu")
		(net "M_D_CPU0_SA_CB<0>")
	)
	(segment
		(start 303.94021 -235.323126)
		(end 303.94021 -235.387642)
		(width 0.14478)
		(layer "In4.Cu")
		(net "M_D_CPU0_SA_CB<0>")
	)
	(segment
		(start 316.473586 -244.066314)
		(end 323.864478 -244.066314)
		(width 0.14478)
		(layer "In4.Cu")
		(net "M_D_CPU0_SA_CB<0>")
	)
	(segment
		(start 300.67504 -234.70489)
		(end 300.838108 -234.541822)
		(width 0.14478)
		(layer "In4.Cu")
		(net "M_D_CPU0_SA_CB<0>")
	)
	(segment
		(start 285.985966 -235.55071)
		(end 286.149034 -235.387642)
		(width 0.14478)
		(layer "In4.Cu")
		(net "M_D_CPU0_SA_CB<0>")
	)
	(segment
		(start 285.429452 -235.160058)
		(end 285.59252 -235.323126)
		(width 0.14478)
		(layer "In4.Cu")
		(net "M_D_CPU0_SA_CB<0>")
	)
	(segment
		(start 303.94021 -235.387642)
		(end 304.103278 -235.55071)
		(width 0.14478)
		(layer "In4.Cu")
		(net "M_D_CPU0_SA_CB<0>")
	)
	(segment
		(start 295.368726 -235.160058)
		(end 296.15892 -235.160058)
		(width 0.14478)
		(layer "In4.Cu")
		(net "M_D_CPU0_SA_CB<0>")
	)
	(segment
		(start 297.04157 -235.160058)
		(end 297.346878 -235.160058)
		(width 0.14478)
		(layer "In4.Cu")
		(net "M_D_CPU0_SA_CB<0>")
	)
	(segment
		(start 294.649144 -235.323126)
		(end 294.649144 -235.382562)
		(width 0.14478)
		(layer "In4.Cu")
		(net "M_D_CPU0_SA_CB<0>")
	)
	(segment
		(start 293.498778 -234.310174)
		(end 294.348662 -235.160058)
		(width 0.14478)
		(layer "In4.Cu")
		(net "M_D_CPU0_SA_CB<0>")
	)
	(segment
		(start 286.705548 -235.387642)
		(end 286.868616 -235.55071)
		(width 0.14478)
		(layer "In4.Cu")
		(net "M_D_CPU0_SA_CB<0>")
	)
	(segment
		(start 294.812212 -235.54563)
		(end 295.04259 -235.54563)
		(width 0.14478)
		(layer "In4.Cu")
		(net "M_D_CPU0_SA_CB<0>")
	)
	(segment
		(start 336.034126 -244.806724)
		(end 336.042508 -244.81155)
		(width 0.0889)
		(layer "In4.Cu")
		(net "M_D_CPU0_SA_CB<0>")
	)
	(segment
		(start 324.919594 -244.066314)
		(end 325.583296 -244.730016)
		(width 0.0889)
		(layer "In4.Cu")
		(net "M_D_CPU0_SA_CB<0>")
	)
	(segment
		(start 291.339778 -234.70235)
		(end 291.570156 -234.70235)
		(width 0.14478)
		(layer "In4.Cu")
		(net "M_D_CPU0_SA_CB<0>")
	)
	(segment
		(start 303.383696 -235.387642)
		(end 303.383696 -235.323126)
		(width 0.14478)
		(layer "In4.Cu")
		(net "M_D_CPU0_SA_CB<0>")
	)
	(segment
		(start 309.140352 -236.73308)
		(end 309.140352 -236.961172)
		(width 0.14478)
		(layer "In4.Cu")
		(net "M_D_CPU0_SA_CB<0>")
	)
	(segment
		(start 309.140352 -236.961172)
		(end 308.996842 -237.104682)
		(width 0.14478)
		(layer "In4.Cu")
		(net "M_D_CPU0_SA_CB<0>")
	)
	(segment
		(start 310.557418 -238.893604)
		(end 310.71947 -239.055656)
		(width 0.14478)
		(layer "In4.Cu")
		(net "M_D_CPU0_SA_CB<0>")
	)
	(segment
		(start 295.04259 -235.54563)
		(end 295.205658 -235.382562)
		(width 0.14478)
		(layer "In4.Cu")
		(net "M_D_CPU0_SA_CB<0>")
	)
	(segment
		(start 304.103278 -235.55071)
		(end 304.333656 -235.55071)
		(width 0.14478)
		(layer "In4.Cu")
		(net "M_D_CPU0_SA_CB<0>")
	)
	(segment
		(start 300.281594 -234.541822)
		(end 300.444662 -234.70489)
		(width 0.14478)
		(layer "In4.Cu")
		(net "M_D_CPU0_SA_CB<0>")
	)
	(segment
		(start 298.599352 -234.534202)
		(end 298.76242 -234.69727)
		(width 0.14478)
		(layer "In4.Cu")
		(net "M_D_CPU0_SA_CB<0>")
	)
	(segment
		(start 303.383696 -235.323126)
		(end 303.546764 -235.160058)
		(width 0.14478)
		(layer "In4.Cu")
		(net "M_D_CPU0_SA_CB<0>")
	)
	(segment
		(start 300.281594 -234.473242)
		(end 300.281594 -234.541822)
		(width 0.14478)
		(layer "In4.Cu")
		(net "M_D_CPU0_SA_CB<0>")
	)
	(segment
		(start 333.579724 -244.81155)
		(end 333.588106 -244.806724)
		(width 0.0889)
		(layer "In4.Cu")
		(net "M_D_CPU0_SA_CB<0>")
	)
	(segment
		(start 302.827182 -235.323126)
		(end 302.827182 -235.387642)
		(width 0.14478)
		(layer "In4.Cu")
		(net "M_D_CPU0_SA_CB<0>")
	)
	(segment
		(start 298.76242 -234.69727)
		(end 298.992798 -234.69727)
		(width 0.14478)
		(layer "In4.Cu")
		(net "M_D_CPU0_SA_CB<0>")
	)
	(segment
		(start 300.838108 -234.541822)
		(end 300.838108 -234.473242)
		(width 0.14478)
		(layer "In4.Cu")
		(net "M_D_CPU0_SA_CB<0>")
	)
	(segment
		(start 291.013642 -234.310174)
		(end 291.17671 -234.473242)
		(width 0.14478)
		(layer "In4.Cu")
		(net "M_D_CPU0_SA_CB<0>")
	)
	(segment
		(start 298.992798 -234.69727)
		(end 299.155866 -234.534202)
		(width 0.14478)
		(layer "In4.Cu")
		(net "M_D_CPU0_SA_CB<0>")
	)
	(segment
		(start 296.321988 -235.387642)
		(end 296.485056 -235.55071)
		(width 0.14478)
		(layer "In4.Cu")
		(net "M_D_CPU0_SA_CB<0>")
	)
	(segment
		(start 296.715434 -235.55071)
		(end 296.878502 -235.387642)
		(width 0.14478)
		(layer "In4.Cu")
		(net "M_D_CPU0_SA_CB<0>")
	)
	(segment
		(start 307.56733 -235.160058)
		(end 309.140352 -236.73308)
		(width 0.14478)
		(layer "In4.Cu")
		(net "M_D_CPU0_SA_CB<0>")
	)
	(segment
		(start 296.485056 -235.55071)
		(end 296.715434 -235.55071)
		(width 0.14478)
		(layer "In4.Cu")
		(net "M_D_CPU0_SA_CB<0>")
	)
	(segment
		(start 311.091072 -238.911892)
		(end 311.319164 -238.911892)
		(width 0.14478)
		(layer "In4.Cu")
		(net "M_D_CPU0_SA_CB<0>")
	)
	(segment
		(start 327.57491 -244.80647)
		(end 327.594976 -244.8179)
		(width 0.0889)
		(layer "In4.Cu")
		(net "M_D_CPU0_SA_CB<0>")
	)
	(segment
		(start 326.991726 -244.817646)
		(end 327.010522 -244.806724)
		(width 0.0889)
		(layer "In4.Cu")
		(net "M_D_CPU0_SA_CB<0>")
	)
	(segment
		(start 301.001176 -234.310174)
		(end 301.174658 -234.310174)
		(width 0.14478)
		(layer "In4.Cu")
		(net "M_D_CPU0_SA_CB<0>")
	)
	(segment
		(start 300.444662 -234.70489)
		(end 300.67504 -234.70489)
		(width 0.14478)
		(layer "In4.Cu")
		(net "M_D_CPU0_SA_CB<0>")
	)
	(segment
		(start 309.77713 -238.113316)
		(end 309.939182 -238.275368)
		(width 0.14478)
		(layer "In4.Cu")
		(net "M_D_CPU0_SA_CB<0>")
	)
	(segment
		(start 298.196762 -234.310174)
		(end 298.436284 -234.310174)
		(width 0.14478)
		(layer "In4.Cu")
		(net "M_D_CPU0_SA_CB<0>")
	)
	(segment
		(start 309.939182 -238.275368)
		(end 310.167274 -238.275368)
		(width 0.14478)
		(layer "In4.Cu")
		(net "M_D_CPU0_SA_CB<0>")
	)
	(segment
		(start 291.17671 -234.473242)
		(end 291.17671 -234.539282)
		(width 0.14478)
		(layer "In4.Cu")
		(net "M_D_CPU0_SA_CB<0>")
	)
	(arc
		(start 331.708252 -244.806724)
		(mid 331.991208 -244.730547)
		(end 332.274164 -244.806724)
		(width 0.0889)
		(layer "In4.Cu")
		(net "M_D_CPU0_SA_CB<0>")
	)
	(arc
		(start 326.351138 -244.730016)
		(mid 326.498347 -244.749493)
		(end 326.635364 -244.806724)
		(width 0.0889)
		(layer "In4.Cu")
		(net "M_D_CPU0_SA_CB<0>")
	)
	(arc
		(start 333.213964 -244.806724)
		(mid 333.396215 -244.857074)
		(end 333.579724 -244.81155)
		(width 0.0889)
		(layer "In4.Cu")
		(net "M_D_CPU0_SA_CB<0>")
	)
	(arc
		(start 336.042508 -244.81155)
		(mid 336.226016 -244.857044)
		(end 336.408268 -244.806724)
		(width 0.0889)
		(layer "In4.Cu")
		(net "M_D_CPU0_SA_CB<0>")
	)
	(arc
		(start 333.588106 -244.806724)
		(mid 333.871062 -244.730547)
		(end 334.154018 -244.806724)
		(width 0.0889)
		(layer "In4.Cu")
		(net "M_D_CPU0_SA_CB<0>")
	)
	(arc
		(start 336.408268 -244.806724)
		(mid 336.691224 -244.730547)
		(end 336.97418 -244.806724)
		(width 0.0889)
		(layer "In4.Cu")
		(net "M_D_CPU0_SA_CB<0>")
	)
	(arc
		(start 331.342492 -244.81155)
		(mid 331.526 -244.857044)
		(end 331.708252 -244.806724)
		(width 0.0889)
		(layer "In4.Cu")
		(net "M_D_CPU0_SA_CB<0>")
	)
	(arc
		(start 334.154018 -244.806724)
		(mid 334.336269 -244.857074)
		(end 334.519778 -244.81155)
		(width 0.0889)
		(layer "In4.Cu")
		(net "M_D_CPU0_SA_CB<0>")
	)
	(arc
		(start 336.97418 -244.806724)
		(mid 337.161124 -244.856979)
		(end 337.348068 -244.806724)
		(width 0.0889)
		(layer "In4.Cu")
		(net "M_D_CPU0_SA_CB<0>")
	)
	(arc
		(start 330.768198 -244.806724)
		(mid 331.051154 -244.730547)
		(end 331.33411 -244.806724)
		(width 0.0889)
		(layer "In4.Cu")
		(net "M_D_CPU0_SA_CB<0>")
	)
	(arc
		(start 327.94829 -244.806724)
		(mid 328.231246 -244.730547)
		(end 328.514202 -244.806724)
		(width 0.0889)
		(layer "In4.Cu")
		(net "M_D_CPU0_SA_CB<0>")
	)
	(arc
		(start 328.88809 -244.806724)
		(mid 329.171046 -244.730547)
		(end 329.454002 -244.806724)
		(width 0.0889)
		(layer "In4.Cu")
		(net "M_D_CPU0_SA_CB<0>")
	)
	(arc
		(start 330.402438 -244.81155)
		(mid 330.585946 -244.857044)
		(end 330.768198 -244.806724)
		(width 0.0889)
		(layer "In4.Cu")
		(net "M_D_CPU0_SA_CB<0>")
	)
	(arc
		(start 337.91398 -244.806724)
		(mid 338.096231 -244.857074)
		(end 338.27974 -244.81155)
		(width 0.0889)
		(layer "In4.Cu")
		(net "M_D_CPU0_SA_CB<0>")
	)
	(arc
		(start 329.454002 -244.806724)
		(mid 329.636253 -244.857074)
		(end 329.819762 -244.81155)
		(width 0.0889)
		(layer "In4.Cu")
		(net "M_D_CPU0_SA_CB<0>")
	)
	(arc
		(start 327.010522 -244.806724)
		(mid 327.280291 -244.730701)
		(end 327.55332 -244.794024)
		(width 0.0889)
		(layer "In4.Cu")
		(net "M_D_CPU0_SA_CB<0>")
	)
	(arc
		(start 329.828144 -244.806724)
		(mid 330.1111 -244.730547)
		(end 330.394056 -244.806724)
		(width 0.0889)
		(layer "In4.Cu")
		(net "M_D_CPU0_SA_CB<0>")
	)
	(arc
		(start 328.514202 -244.806724)
		(mid 328.701146 -244.856979)
		(end 328.88809 -244.806724)
		(width 0.0889)
		(layer "In4.Cu")
		(net "M_D_CPU0_SA_CB<0>")
	)
	(arc
		(start 332.648052 -244.806724)
		(mid 332.931008 -244.730547)
		(end 333.213964 -244.806724)
		(width 0.0889)
		(layer "In4.Cu")
		(net "M_D_CPU0_SA_CB<0>")
	)
	(arc
		(start 335.102454 -244.81155)
		(mid 335.285962 -244.857044)
		(end 335.468214 -244.806724)
		(width 0.0889)
		(layer "In4.Cu")
		(net "M_D_CPU0_SA_CB<0>")
	)
	(arc
		(start 334.52816 -244.806724)
		(mid 334.811116 -244.730547)
		(end 335.094072 -244.806724)
		(width 0.0889)
		(layer "In4.Cu")
		(net "M_D_CPU0_SA_CB<0>")
	)
	(arc
		(start 332.274164 -244.806724)
		(mid 332.461108 -244.856979)
		(end 332.648052 -244.806724)
		(width 0.0889)
		(layer "In4.Cu")
		(net "M_D_CPU0_SA_CB<0>")
	)
	(arc
		(start 326.635364 -244.806724)
		(mid 326.812155 -244.857443)
		(end 326.991726 -244.817646)
		(width 0.0889)
		(layer "In4.Cu")
		(net "M_D_CPU0_SA_CB<0>")
	)
	(arc
		(start 338.288122 -244.806724)
		(mid 338.535835 -244.731504)
		(end 338.791042 -244.774974)
		(width 0.0889)
		(layer "In4.Cu")
		(net "M_D_CPU0_SA_CB<0>")
	)
	(arc
		(start 327.594976 -244.8179)
		(mid 327.773054 -244.856884)
		(end 327.94829 -244.806724)
		(width 0.0889)
		(layer "In4.Cu")
		(net "M_D_CPU0_SA_CB<0>")
	)
	(arc
		(start 337.348068 -244.806724)
		(mid 337.631024 -244.730547)
		(end 337.91398 -244.806724)
		(width 0.0889)
		(layer "In4.Cu")
		(net "M_D_CPU0_SA_CB<0>")
	)
	(arc
		(start 335.468214 -244.806724)
		(mid 335.75117 -244.730547)
		(end 336.034126 -244.806724)
		(width 0.0889)
		(layer "In4.Cu")
		(net "M_D_CPU0_SA_CB<0>")
	)
	(segment
		(start 340.918038 -255.28016)
		(end 340.451186 -255.014222)
		(width 0.10668)
		(layer "F.Cu")
		(net "M_D_CPU0_SA_CA<6>")
	)
	(segment
		(start 285.44774 -253.296674)
		(end 284.736032 -252.584966)
		(width 0.14478)
		(layer "In4.Cu")
		(net "M_D_CPU0_SA_CA<6>")
	)
	(segment
		(start 332.752446 -255.341628)
		(end 332.744064 -255.336802)
		(width 0.0889)
		(layer "In4.Cu")
		(net "M_D_CPU0_SA_CA<6>")
	)
	(segment
		(start 326.543416 -255.333246)
		(end 326.537828 -255.336548)
		(width 0.0889)
		(layer "In4.Cu")
		(net "M_D_CPU0_SA_CA<6>")
	)
	(segment
		(start 331.238098 -255.336802)
		(end 331.229716 -255.341628)
		(width 0.0889)
		(layer "In4.Cu")
		(net "M_D_CPU0_SA_CA<6>")
	)
	(segment
		(start 340.297008 -255.279652)
		(end 340.200742 -255.305052)
		(width 0.0889)
		(layer "In4.Cu")
		(net "M_D_CPU0_SA_CA<6>")
	)
	(segment
		(start 325.392542 -255.387348)
		(end 325.09714 -255.68275)
		(width 0.0889)
		(layer "In4.Cu")
		(net "M_D_CPU0_SA_CA<6>")
	)
	(segment
		(start 320.80581 -255.68275)
		(end 319.833244 -254.710184)
		(width 0.14478)
		(layer "In4.Cu")
		(net "M_D_CPU0_SA_CA<6>")
	)
	(segment
		(start 286.071818 -253.920752)
		(end 285.841186 -253.920752)
		(width 0.14478)
		(layer "In4.Cu")
		(net "M_D_CPU0_SA_CA<6>")
	)
	(segment
		(start 328.41819 -255.336802)
		(end 328.409808 -255.341628)
		(width 0.0889)
		(layer "In4.Cu")
		(net "M_D_CPU0_SA_CA<6>")
	)
	(segment
		(start 333.6925 -255.341628)
		(end 333.684118 -255.336802)
		(width 0.0889)
		(layer "In4.Cu")
		(net "M_D_CPU0_SA_CA<6>")
	)
	(segment
		(start 340.451186 -255.014222)
		(end 340.297008 -255.279652)
		(width 0.0889)
		(layer "In4.Cu")
		(net "M_D_CPU0_SA_CA<6>")
	)
	(segment
		(start 326.350884 -255.387348)
		(end 325.392542 -255.387348)
		(width 0.0889)
		(layer "In4.Cu")
		(net "M_D_CPU0_SA_CA<6>")
	)
	(segment
		(start 285.982664 -254.797052)
		(end 285.982664 -254.56642)
		(width 0.14478)
		(layer "In4.Cu")
		(net "M_D_CPU0_SA_CA<6>")
	)
	(segment
		(start 286.145732 -254.96012)
		(end 285.982664 -254.797052)
		(width 0.14478)
		(layer "In4.Cu")
		(net "M_D_CPU0_SA_CA<6>")
	)
	(segment
		(start 335.938114 -255.336802)
		(end 335.929732 -255.341628)
		(width 0.0889)
		(layer "In4.Cu")
		(net "M_D_CPU0_SA_CA<6>")
	)
	(segment
		(start 286.23514 -254.084074)
		(end 286.071818 -253.920752)
		(width 0.14478)
		(layer "In4.Cu")
		(net "M_D_CPU0_SA_CA<6>")
	)
	(segment
		(start 328.044048 -255.336802)
		(end 328.033634 -255.330706)
		(width 0.0889)
		(layer "In4.Cu")
		(net "M_D_CPU0_SA_CA<6>")
	)
	(segment
		(start 285.358332 -254.17272)
		(end 285.195264 -254.009652)
		(width 0.14478)
		(layer "In4.Cu")
		(net "M_D_CPU0_SA_CA<6>")
	)
	(segment
		(start 336.878168 -255.336802)
		(end 336.869786 -255.341628)
		(width 0.0889)
		(layer "In4.Cu")
		(net "M_D_CPU0_SA_CA<6>")
	)
	(segment
		(start 332.178152 -255.336802)
		(end 332.16977 -255.341628)
		(width 0.0889)
		(layer "In4.Cu")
		(net "M_D_CPU0_SA_CA<6>")
	)
	(segment
		(start 337.452462 -255.341628)
		(end 337.44408 -255.336802)
		(width 0.0889)
		(layer "In4.Cu")
		(net "M_D_CPU0_SA_CA<6>")
	)
	(segment
		(start 323.941694 -255.68275)
		(end 320.80581 -255.68275)
		(width 0.14478)
		(layer "In4.Cu")
		(net "M_D_CPU0_SA_CA<6>")
	)
	(segment
		(start 319.833244 -254.710184)
		(end 286.626554 -254.710184)
		(width 0.14478)
		(layer "In4.Cu")
		(net "M_D_CPU0_SA_CA<6>")
	)
	(segment
		(start 339.698076 -255.336802)
		(end 339.689694 -255.341628)
		(width 0.0889)
		(layer "In4.Cu")
		(net "M_D_CPU0_SA_CA<6>")
	)
	(segment
		(start 285.447486 -253.526798)
		(end 285.44774 -253.296674)
		(width 0.14478)
		(layer "In4.Cu")
		(net "M_D_CPU0_SA_CA<6>")
	)
	(segment
		(start 327.111614 -255.341628)
		(end 327.103232 -255.336802)
		(width 0.0889)
		(layer "In4.Cu")
		(net "M_D_CPU0_SA_CA<6>")
	)
	(segment
		(start 286.626554 -254.710184)
		(end 286.376364 -254.960374)
		(width 0.14478)
		(layer "In4.Cu")
		(net "M_D_CPU0_SA_CA<6>")
	)
	(segment
		(start 328.992484 -255.341628)
		(end 328.984102 -255.336802)
		(width 0.0889)
		(layer "In4.Cu")
		(net "M_D_CPU0_SA_CA<6>")
	)
	(segment
		(start 285.841186 -253.920752)
		(end 285.588964 -254.172974)
		(width 0.14478)
		(layer "In4.Cu")
		(net "M_D_CPU0_SA_CA<6>")
	)
	(segment
		(start 285.588964 -254.172974)
		(end 285.358332 -254.17272)
		(width 0.14478)
		(layer "In4.Cu")
		(net "M_D_CPU0_SA_CA<6>")
	)
	(segment
		(start 285.195264 -254.009652)
		(end 285.195264 -253.77902)
		(width 0.14478)
		(layer "In4.Cu")
		(net "M_D_CPU0_SA_CA<6>")
	)
	(segment
		(start 285.195264 -253.77902)
		(end 285.447486 -253.526798)
		(width 0.14478)
		(layer "In4.Cu")
		(net "M_D_CPU0_SA_CA<6>")
	)
	(segment
		(start 325.09714 -255.68275)
		(end 323.941694 -255.68275)
		(width 0.0889)
		(layer "In4.Cu")
		(net "M_D_CPU0_SA_CA<6>")
	)
	(segment
		(start 286.376364 -254.960374)
		(end 286.145732 -254.96012)
		(width 0.14478)
		(layer "In4.Cu")
		(net "M_D_CPU0_SA_CA<6>")
	)
	(segment
		(start 285.982664 -254.56642)
		(end 286.234886 -254.314198)
		(width 0.14478)
		(layer "In4.Cu")
		(net "M_D_CPU0_SA_CA<6>")
	)
	(segment
		(start 286.234886 -254.314198)
		(end 286.23514 -254.084074)
		(width 0.14478)
		(layer "In4.Cu")
		(net "M_D_CPU0_SA_CA<6>")
	)
	(arc
		(start 339.323934 -255.336802)
		(mid 339.040978 -255.260625)
		(end 338.758022 -255.336802)
		(width 0.0889)
		(layer "In4.Cu")
		(net "M_D_CPU0_SA_CA<6>")
	)
	(arc
		(start 331.80401 -255.336802)
		(mid 331.521054 -255.260625)
		(end 331.238098 -255.336802)
		(width 0.0889)
		(layer "In4.Cu")
		(net "M_D_CPU0_SA_CA<6>")
	)
	(arc
		(start 328.033634 -255.330706)
		(mid 327.754948 -255.260486)
		(end 327.477882 -255.336802)
		(width 0.0889)
		(layer "In4.Cu")
		(net "M_D_CPU0_SA_CA<6>")
	)
	(arc
		(start 336.869786 -255.341628)
		(mid 336.686278 -255.387122)
		(end 336.504026 -255.336802)
		(width 0.0889)
		(layer "In4.Cu")
		(net "M_D_CPU0_SA_CA<6>")
	)
	(arc
		(start 333.118206 -255.336802)
		(mid 332.935955 -255.387152)
		(end 332.752446 -255.341628)
		(width 0.0889)
		(layer "In4.Cu")
		(net "M_D_CPU0_SA_CA<6>")
	)
	(arc
		(start 328.409808 -255.341628)
		(mid 328.2263 -255.387122)
		(end 328.044048 -255.336802)
		(width 0.0889)
		(layer "In4.Cu")
		(net "M_D_CPU0_SA_CA<6>")
	)
	(arc
		(start 330.863956 -255.336802)
		(mid 330.581 -255.260625)
		(end 330.298044 -255.336802)
		(width 0.0889)
		(layer "In4.Cu")
		(net "M_D_CPU0_SA_CA<6>")
	)
	(arc
		(start 337.44408 -255.336802)
		(mid 337.161124 -255.260625)
		(end 336.878168 -255.336802)
		(width 0.0889)
		(layer "In4.Cu")
		(net "M_D_CPU0_SA_CA<6>")
	)
	(arc
		(start 331.229716 -255.341628)
		(mid 331.046208 -255.387122)
		(end 330.863956 -255.336802)
		(width 0.0889)
		(layer "In4.Cu")
		(net "M_D_CPU0_SA_CA<6>")
	)
	(arc
		(start 335.563972 -255.336802)
		(mid 335.281016 -255.260625)
		(end 334.99806 -255.336802)
		(width 0.0889)
		(layer "In4.Cu")
		(net "M_D_CPU0_SA_CA<6>")
	)
	(arc
		(start 338.758022 -255.336802)
		(mid 338.571078 -255.387057)
		(end 338.384134 -255.336802)
		(width 0.0889)
		(layer "In4.Cu")
		(net "M_D_CPU0_SA_CA<6>")
	)
	(arc
		(start 337.818222 -255.336802)
		(mid 337.635971 -255.387152)
		(end 337.452462 -255.341628)
		(width 0.0889)
		(layer "In4.Cu")
		(net "M_D_CPU0_SA_CA<6>")
	)
	(arc
		(start 340.200742 -255.305052)
		(mid 339.945677 -255.261701)
		(end 339.698076 -255.336802)
		(width 0.0889)
		(layer "In4.Cu")
		(net "M_D_CPU0_SA_CA<6>")
	)
	(arc
		(start 329.358244 -255.336802)
		(mid 329.175993 -255.387152)
		(end 328.992484 -255.341628)
		(width 0.0889)
		(layer "In4.Cu")
		(net "M_D_CPU0_SA_CA<6>")
	)
	(arc
		(start 332.744064 -255.336802)
		(mid 332.461108 -255.260625)
		(end 332.178152 -255.336802)
		(width 0.0889)
		(layer "In4.Cu")
		(net "M_D_CPU0_SA_CA<6>")
	)
	(arc
		(start 334.05826 -255.336802)
		(mid 333.876009 -255.387152)
		(end 333.6925 -255.341628)
		(width 0.0889)
		(layer "In4.Cu")
		(net "M_D_CPU0_SA_CA<6>")
	)
	(arc
		(start 330.298044 -255.336802)
		(mid 330.1111 -255.387057)
		(end 329.924156 -255.336802)
		(width 0.0889)
		(layer "In4.Cu")
		(net "M_D_CPU0_SA_CA<6>")
	)
	(arc
		(start 326.537828 -255.336548)
		(mid 326.447719 -255.374342)
		(end 326.350884 -255.387348)
		(width 0.0889)
		(layer "In4.Cu")
		(net "M_D_CPU0_SA_CA<6>")
	)
	(arc
		(start 333.684118 -255.336802)
		(mid 333.401162 -255.260625)
		(end 333.118206 -255.336802)
		(width 0.0889)
		(layer "In4.Cu")
		(net "M_D_CPU0_SA_CA<6>")
	)
	(arc
		(start 332.16977 -255.341628)
		(mid 331.986262 -255.387122)
		(end 331.80401 -255.336802)
		(width 0.0889)
		(layer "In4.Cu")
		(net "M_D_CPU0_SA_CA<6>")
	)
	(arc
		(start 329.924156 -255.336802)
		(mid 329.6412 -255.260625)
		(end 329.358244 -255.336802)
		(width 0.0889)
		(layer "In4.Cu")
		(net "M_D_CPU0_SA_CA<6>")
	)
	(arc
		(start 327.477882 -255.336802)
		(mid 327.295377 -255.387279)
		(end 327.111614 -255.341628)
		(width 0.0889)
		(layer "In4.Cu")
		(net "M_D_CPU0_SA_CA<6>")
	)
	(arc
		(start 328.984102 -255.336802)
		(mid 328.701146 -255.260625)
		(end 328.41819 -255.336802)
		(width 0.0889)
		(layer "In4.Cu")
		(net "M_D_CPU0_SA_CA<6>")
	)
	(arc
		(start 334.99806 -255.336802)
		(mid 334.811116 -255.387057)
		(end 334.624172 -255.336802)
		(width 0.0889)
		(layer "In4.Cu")
		(net "M_D_CPU0_SA_CA<6>")
	)
	(arc
		(start 338.384134 -255.336802)
		(mid 338.101178 -255.260625)
		(end 337.818222 -255.336802)
		(width 0.0889)
		(layer "In4.Cu")
		(net "M_D_CPU0_SA_CA<6>")
	)
	(arc
		(start 334.624172 -255.336802)
		(mid 334.341216 -255.260625)
		(end 334.05826 -255.336802)
		(width 0.0889)
		(layer "In4.Cu")
		(net "M_D_CPU0_SA_CA<6>")
	)
	(arc
		(start 327.103232 -255.336802)
		(mid 326.823804 -255.260636)
		(end 326.543416 -255.333246)
		(width 0.0889)
		(layer "In4.Cu")
		(net "M_D_CPU0_SA_CA<6>")
	)
	(arc
		(start 335.929732 -255.341628)
		(mid 335.746224 -255.387122)
		(end 335.563972 -255.336802)
		(width 0.0889)
		(layer "In4.Cu")
		(net "M_D_CPU0_SA_CA<6>")
	)
	(arc
		(start 336.504026 -255.336802)
		(mid 336.22107 -255.260625)
		(end 335.938114 -255.336802)
		(width 0.0889)
		(layer "In4.Cu")
		(net "M_D_CPU0_SA_CA<6>")
	)
	(arc
		(start 339.689694 -255.341628)
		(mid 339.506186 -255.387122)
		(end 339.323934 -255.336802)
		(width 0.0889)
		(layer "In4.Cu")
		(net "M_D_CPU0_SA_CA<6>")
	)
	(segment
		(start 339.03793 -255.28016)
		(end 338.571078 -255.014222)
		(width 0.10668)
		(layer "F.Cu")
		(net "M_D_CPU0_SA_CA<5>")
	)
	(segment
		(start 327.461372 -254.681482)
		(end 327.47966 -254.691896)
		(width 0.0889)
		(layer "In4.Cu")
		(net "M_D_CPU0_SA_CA<5>")
	)
	(segment
		(start 332.16977 -254.686816)
		(end 332.178152 -254.691642)
		(width 0.0889)
		(layer "In4.Cu")
		(net "M_D_CPU0_SA_CA<5>")
	)
	(segment
		(start 323.913754 -255.22555)
		(end 325.0438 -255.22555)
		(width 0.0889)
		(layer "In4.Cu")
		(net "M_D_CPU0_SA_CA<5>")
	)
	(segment
		(start 335.929732 -254.686816)
		(end 335.938114 -254.691642)
		(width 0.0889)
		(layer "In4.Cu")
		(net "M_D_CPU0_SA_CA<5>")
	)
	(segment
		(start 325.0438 -255.22555)
		(end 325.297038 -254.972312)
		(width 0.0889)
		(layer "In4.Cu")
		(net "M_D_CPU0_SA_CA<5>")
	)
	(segment
		(start 319.961768 -254.19558)
		(end 320.991738 -255.22555)
		(width 0.14478)
		(layer "In4.Cu")
		(net "M_D_CPU0_SA_CA<5>")
	)
	(segment
		(start 337.44408 -254.691642)
		(end 337.452462 -254.686816)
		(width 0.0889)
		(layer "In4.Cu")
		(net "M_D_CPU0_SA_CA<5>")
	)
	(segment
		(start 325.297038 -254.972312)
		(end 325.86676 -254.972312)
		(width 0.0889)
		(layer "In4.Cu")
		(net "M_D_CPU0_SA_CA<5>")
	)
	(segment
		(start 326.16521 -254.691896)
		(end 326.192642 -254.676148)
		(width 0.0889)
		(layer "In4.Cu")
		(net "M_D_CPU0_SA_CA<5>")
	)
	(segment
		(start 281.060906 -252.160024)
		(end 285.096966 -252.160024)
		(width 0.14478)
		(layer "In4.Cu")
		(net "M_D_CPU0_SA_CA<5>")
	)
	(segment
		(start 325.86676 -254.972312)
		(end 326.087994 -254.751078)
		(width 0.0889)
		(layer "In4.Cu")
		(net "M_D_CPU0_SA_CA<5>")
	)
	(segment
		(start 306.260246 -253.860046)
		(end 306.59578 -254.19558)
		(width 0.14478)
		(layer "In4.Cu")
		(net "M_D_CPU0_SA_CA<5>")
	)
	(segment
		(start 328.984102 -254.691642)
		(end 328.992484 -254.686816)
		(width 0.0889)
		(layer "In4.Cu")
		(net "M_D_CPU0_SA_CA<5>")
	)
	(segment
		(start 327.47966 -254.691896)
		(end 327.50125 -254.704342)
		(width 0.0889)
		(layer "In4.Cu")
		(net "M_D_CPU0_SA_CA<5>")
	)
	(segment
		(start 306.59578 -254.19558)
		(end 319.961768 -254.19558)
		(width 0.14478)
		(layer "In4.Cu")
		(net "M_D_CPU0_SA_CA<5>")
	)
	(segment
		(start 338.70265 -254.66548)
		(end 338.725002 -254.748792)
		(width 0.0889)
		(layer "In4.Cu")
		(net "M_D_CPU0_SA_CA<5>")
	)
	(segment
		(start 328.409808 -254.686816)
		(end 328.41819 -254.691642)
		(width 0.0889)
		(layer "In4.Cu")
		(net "M_D_CPU0_SA_CA<5>")
	)
	(segment
		(start 320.991738 -255.22555)
		(end 323.913754 -255.22555)
		(width 0.14478)
		(layer "In4.Cu")
		(net "M_D_CPU0_SA_CA<5>")
	)
	(segment
		(start 338.725002 -254.748792)
		(end 338.571078 -255.014222)
		(width 0.0889)
		(layer "In4.Cu")
		(net "M_D_CPU0_SA_CA<5>")
	)
	(segment
		(start 280.635964 -251.735082)
		(end 281.060906 -252.160024)
		(width 0.14478)
		(layer "In4.Cu")
		(net "M_D_CPU0_SA_CA<5>")
	)
	(segment
		(start 285.096966 -252.160024)
		(end 286.796988 -253.860046)
		(width 0.14478)
		(layer "In4.Cu")
		(net "M_D_CPU0_SA_CA<5>")
	)
	(segment
		(start 332.744064 -254.691642)
		(end 332.752446 -254.686816)
		(width 0.0889)
		(layer "In4.Cu")
		(net "M_D_CPU0_SA_CA<5>")
	)
	(segment
		(start 333.684118 -254.691642)
		(end 333.6925 -254.686816)
		(width 0.0889)
		(layer "In4.Cu")
		(net "M_D_CPU0_SA_CA<5>")
	)
	(segment
		(start 327.083166 -254.705358)
		(end 327.106534 -254.691642)
		(width 0.0889)
		(layer "In4.Cu")
		(net "M_D_CPU0_SA_CA<5>")
	)
	(segment
		(start 331.229716 -254.686816)
		(end 331.238098 -254.691642)
		(width 0.0889)
		(layer "In4.Cu")
		(net "M_D_CPU0_SA_CA<5>")
	)
	(segment
		(start 336.869786 -254.686816)
		(end 336.878168 -254.691642)
		(width 0.0889)
		(layer "In4.Cu")
		(net "M_D_CPU0_SA_CA<5>")
	)
	(segment
		(start 286.796988 -253.860046)
		(end 306.260246 -253.860046)
		(width 0.14478)
		(layer "In4.Cu")
		(net "M_D_CPU0_SA_CA<5>")
	)
	(arc
		(start 331.80401 -254.691642)
		(mid 331.986261 -254.641292)
		(end 332.16977 -254.686816)
		(width 0.0889)
		(layer "In4.Cu")
		(net "M_D_CPU0_SA_CA<5>")
	)
	(arc
		(start 327.106534 -254.691642)
		(mid 327.282654 -254.641664)
		(end 327.461372 -254.681482)
		(width 0.0889)
		(layer "In4.Cu")
		(net "M_D_CPU0_SA_CA<5>")
	)
	(arc
		(start 330.863956 -254.691642)
		(mid 331.046207 -254.641292)
		(end 331.229716 -254.686816)
		(width 0.0889)
		(layer "In4.Cu")
		(net "M_D_CPU0_SA_CA<5>")
	)
	(arc
		(start 328.41819 -254.691642)
		(mid 328.701146 -254.767819)
		(end 328.984102 -254.691642)
		(width 0.0889)
		(layer "In4.Cu")
		(net "M_D_CPU0_SA_CA<5>")
	)
	(arc
		(start 330.298044 -254.691642)
		(mid 330.581 -254.767819)
		(end 330.863956 -254.691642)
		(width 0.0889)
		(layer "In4.Cu")
		(net "M_D_CPU0_SA_CA<5>")
	)
	(arc
		(start 331.238098 -254.691642)
		(mid 331.521054 -254.767819)
		(end 331.80401 -254.691642)
		(width 0.0889)
		(layer "In4.Cu")
		(net "M_D_CPU0_SA_CA<5>")
	)
	(arc
		(start 336.504026 -254.691642)
		(mid 336.686277 -254.641292)
		(end 336.869786 -254.686816)
		(width 0.0889)
		(layer "In4.Cu")
		(net "M_D_CPU0_SA_CA<5>")
	)
	(arc
		(start 329.924156 -254.691642)
		(mid 330.1111 -254.641387)
		(end 330.298044 -254.691642)
		(width 0.0889)
		(layer "In4.Cu")
		(net "M_D_CPU0_SA_CA<5>")
	)
	(arc
		(start 332.752446 -254.686816)
		(mid 332.935954 -254.641322)
		(end 333.118206 -254.691642)
		(width 0.0889)
		(layer "In4.Cu")
		(net "M_D_CPU0_SA_CA<5>")
	)
	(arc
		(start 334.05826 -254.691642)
		(mid 334.341216 -254.767819)
		(end 334.624172 -254.691642)
		(width 0.0889)
		(layer "In4.Cu")
		(net "M_D_CPU0_SA_CA<5>")
	)
	(arc
		(start 327.50125 -254.704342)
		(mid 327.774279 -254.767661)
		(end 328.044048 -254.691642)
		(width 0.0889)
		(layer "In4.Cu")
		(net "M_D_CPU0_SA_CA<5>")
	)
	(arc
		(start 326.192642 -254.676148)
		(mid 326.367893 -254.641215)
		(end 326.539352 -254.691642)
		(width 0.0889)
		(layer "In4.Cu")
		(net "M_D_CPU0_SA_CA<5>")
	)
	(arc
		(start 334.99806 -254.691642)
		(mid 335.281016 -254.767819)
		(end 335.563972 -254.691642)
		(width 0.0889)
		(layer "In4.Cu")
		(net "M_D_CPU0_SA_CA<5>")
	)
	(arc
		(start 326.539352 -254.691642)
		(mid 326.809509 -254.768404)
		(end 327.083166 -254.705358)
		(width 0.0889)
		(layer "In4.Cu")
		(net "M_D_CPU0_SA_CA<5>")
	)
	(arc
		(start 337.818222 -254.691642)
		(mid 338.101178 -254.767819)
		(end 338.384134 -254.691642)
		(width 0.0889)
		(layer "In4.Cu")
		(net "M_D_CPU0_SA_CA<5>")
	)
	(arc
		(start 332.178152 -254.691642)
		(mid 332.461108 -254.767819)
		(end 332.744064 -254.691642)
		(width 0.0889)
		(layer "In4.Cu")
		(net "M_D_CPU0_SA_CA<5>")
	)
	(arc
		(start 334.624172 -254.691642)
		(mid 334.811116 -254.641387)
		(end 334.99806 -254.691642)
		(width 0.0889)
		(layer "In4.Cu")
		(net "M_D_CPU0_SA_CA<5>")
	)
	(arc
		(start 328.044048 -254.691642)
		(mid 328.226299 -254.641292)
		(end 328.409808 -254.686816)
		(width 0.0889)
		(layer "In4.Cu")
		(net "M_D_CPU0_SA_CA<5>")
	)
	(arc
		(start 328.992484 -254.686816)
		(mid 329.175992 -254.641322)
		(end 329.358244 -254.691642)
		(width 0.0889)
		(layer "In4.Cu")
		(net "M_D_CPU0_SA_CA<5>")
	)
	(arc
		(start 333.6925 -254.686816)
		(mid 333.876008 -254.641322)
		(end 334.05826 -254.691642)
		(width 0.0889)
		(layer "In4.Cu")
		(net "M_D_CPU0_SA_CA<5>")
	)
	(arc
		(start 337.452462 -254.686816)
		(mid 337.63597 -254.641322)
		(end 337.818222 -254.691642)
		(width 0.0889)
		(layer "In4.Cu")
		(net "M_D_CPU0_SA_CA<5>")
	)
	(arc
		(start 338.384134 -254.691642)
		(mid 338.540453 -254.642647)
		(end 338.70265 -254.66548)
		(width 0.0889)
		(layer "In4.Cu")
		(net "M_D_CPU0_SA_CA<5>")
	)
	(arc
		(start 326.087994 -254.751078)
		(mid 326.12465 -254.718938)
		(end 326.16521 -254.691896)
		(width 0.0889)
		(layer "In4.Cu")
		(net "M_D_CPU0_SA_CA<5>")
	)
	(arc
		(start 336.878168 -254.691642)
		(mid 337.161124 -254.767819)
		(end 337.44408 -254.691642)
		(width 0.0889)
		(layer "In4.Cu")
		(net "M_D_CPU0_SA_CA<5>")
	)
	(arc
		(start 335.563972 -254.691642)
		(mid 335.746223 -254.641292)
		(end 335.929732 -254.686816)
		(width 0.0889)
		(layer "In4.Cu")
		(net "M_D_CPU0_SA_CA<5>")
	)
	(arc
		(start 335.938114 -254.691642)
		(mid 336.22107 -254.767819)
		(end 336.504026 -254.691642)
		(width 0.0889)
		(layer "In4.Cu")
		(net "M_D_CPU0_SA_CA<5>")
	)
	(arc
		(start 329.358244 -254.691642)
		(mid 329.6412 -254.767819)
		(end 329.924156 -254.691642)
		(width 0.0889)
		(layer "In4.Cu")
		(net "M_D_CPU0_SA_CA<5>")
	)
	(arc
		(start 333.118206 -254.691642)
		(mid 333.401162 -254.767819)
		(end 333.684118 -254.691642)
		(width 0.0889)
		(layer "In4.Cu")
		(net "M_D_CPU0_SA_CA<5>")
	)
	(segment
		(start 339.508084 -254.470154)
		(end 339.040978 -254.204216)
		(width 0.10668)
		(layer "F.Cu")
		(net "M_D_CPU0_SA_CA<4>")
	)
	(segment
		(start 301.587916 -253.172976)
		(end 301.750984 -253.009908)
		(width 0.14478)
		(layer "In4.Cu")
		(net "M_D_CPU0_SA_CA<4>")
	)
	(segment
		(start 301.19447 -253.39929)
		(end 301.424848 -253.39929)
		(width 0.14478)
		(layer "In4.Cu")
		(net "M_D_CPU0_SA_CA<4>")
	)
	(segment
		(start 293.300658 -253.172976)
		(end 293.300658 -253.238762)
		(width 0.14478)
		(layer "In4.Cu")
		(net "M_D_CPU0_SA_CA<4>")
	)
	(segment
		(start 327.55332 -254.514096)
		(end 327.57491 -254.526542)
		(width 0.0889)
		(layer "In4.Cu")
		(net "M_D_CPU0_SA_CA<4>")
	)
	(segment
		(start 293.857172 -253.238762)
		(end 293.857172 -253.172976)
		(width 0.14478)
		(layer "In4.Cu")
		(net "M_D_CPU0_SA_CA<4>")
	)
	(segment
		(start 298.701968 -253.009908)
		(end 300.868334 -253.009908)
		(width 0.14478)
		(layer "In4.Cu")
		(net "M_D_CPU0_SA_CA<4>")
	)
	(segment
		(start 338.791042 -254.495046)
		(end 338.887054 -254.469646)
		(width 0.0889)
		(layer "In4.Cu")
		(net "M_D_CPU0_SA_CA<4>")
	)
	(segment
		(start 325.858632 -254.710692)
		(end 325.95312 -254.616204)
		(width 0.0889)
		(layer "In4.Cu")
		(net "M_D_CPU0_SA_CA<4>")
	)
	(segment
		(start 301.031402 -253.236222)
		(end 301.19447 -253.39929)
		(width 0.14478)
		(layer "In4.Cu")
		(net "M_D_CPU0_SA_CA<4>")
	)
	(segment
		(start 327.57491 -254.526542)
		(end 327.594976 -254.537972)
		(width 0.0889)
		(layer "In4.Cu")
		(net "M_D_CPU0_SA_CA<4>")
	)
	(segment
		(start 320.195956 -253.746)
		(end 321.210686 -254.76073)
		(width 0.14478)
		(layer "In4.Cu")
		(net "M_D_CPU0_SA_CA<4>")
	)
	(segment
		(start 289.015424 -253.172976)
		(end 289.015424 -253.238762)
		(width 0.14478)
		(layer "In4.Cu")
		(net "M_D_CPU0_SA_CA<4>")
	)
	(segment
		(start 290.128452 -253.172976)
		(end 290.128452 -253.238762)
		(width 0.14478)
		(layer "In4.Cu")
		(net "M_D_CPU0_SA_CA<4>")
	)
	(segment
		(start 301.587916 -253.236222)
		(end 301.587916 -253.172976)
		(width 0.14478)
		(layer "In4.Cu")
		(net "M_D_CPU0_SA_CA<4>")
	)
	(segment
		(start 290.684966 -253.172976)
		(end 290.848034 -253.009908)
		(width 0.14478)
		(layer "In4.Cu")
		(net "M_D_CPU0_SA_CA<4>")
	)
	(segment
		(start 338.887054 -254.469646)
		(end 339.040978 -254.204216)
		(width 0.0889)
		(layer "In4.Cu")
		(net "M_D_CPU0_SA_CA<4>")
	)
	(segment
		(start 331.33411 -254.526796)
		(end 331.342492 -254.531622)
		(width 0.0889)
		(layer "In4.Cu")
		(net "M_D_CPU0_SA_CA<4>")
	)
	(segment
		(start 324.313296 -254.76073)
		(end 324.392036 -254.83947)
		(width 0.0889)
		(layer "In4.Cu")
		(net "M_D_CPU0_SA_CA<4>")
	)
	(segment
		(start 338.27974 -254.531622)
		(end 338.288122 -254.526796)
		(width 0.0889)
		(layer "In4.Cu")
		(net "M_D_CPU0_SA_CA<4>")
	)
	(segment
		(start 330.394056 -254.526796)
		(end 330.402438 -254.531622)
		(width 0.0889)
		(layer "In4.Cu")
		(net "M_D_CPU0_SA_CA<4>")
	)
	(segment
		(start 297.58894 -253.009908)
		(end 297.819318 -253.009908)
		(width 0.14478)
		(layer "In4.Cu")
		(net "M_D_CPU0_SA_CA<4>")
	)
	(segment
		(start 298.5389 -253.172976)
		(end 298.701968 -253.009908)
		(width 0.14478)
		(layer "In4.Cu")
		(net "M_D_CPU0_SA_CA<4>")
	)
	(segment
		(start 289.40887 -253.40183)
		(end 289.571938 -253.238762)
		(width 0.14478)
		(layer "In4.Cu")
		(net "M_D_CPU0_SA_CA<4>")
	)
	(segment
		(start 288.852356 -253.009908)
		(end 289.015424 -253.172976)
		(width 0.14478)
		(layer "In4.Cu")
		(net "M_D_CPU0_SA_CA<4>")
	)
	(segment
		(start 290.521898 -253.40183)
		(end 290.684966 -253.238762)
		(width 0.14478)
		(layer "In4.Cu")
		(net "M_D_CPU0_SA_CA<4>")
	)
	(segment
		(start 336.034126 -254.526796)
		(end 336.042508 -254.531622)
		(width 0.0889)
		(layer "In4.Cu")
		(net "M_D_CPU0_SA_CA<4>")
	)
	(segment
		(start 293.13759 -253.009908)
		(end 293.300658 -253.172976)
		(width 0.14478)
		(layer "In4.Cu")
		(net "M_D_CPU0_SA_CA<4>")
	)
	(segment
		(start 289.571938 -253.238762)
		(end 289.571938 -253.172976)
		(width 0.14478)
		(layer "In4.Cu")
		(net "M_D_CPU0_SA_CA<4>")
	)
	(segment
		(start 297.819318 -253.009908)
		(end 297.982386 -253.172976)
		(width 0.14478)
		(layer "In4.Cu")
		(net "M_D_CPU0_SA_CA<4>")
	)
	(segment
		(start 334.519778 -254.531622)
		(end 334.52816 -254.526796)
		(width 0.0889)
		(layer "In4.Cu")
		(net "M_D_CPU0_SA_CA<4>")
	)
	(segment
		(start 284.736032 -250.884944)
		(end 286.860996 -253.009908)
		(width 0.14478)
		(layer "In4.Cu")
		(net "M_D_CPU0_SA_CA<4>")
	)
	(segment
		(start 290.29152 -253.40183)
		(end 290.521898 -253.40183)
		(width 0.14478)
		(layer "In4.Cu")
		(net "M_D_CPU0_SA_CA<4>")
	)
	(segment
		(start 297.425872 -253.172976)
		(end 297.58894 -253.009908)
		(width 0.14478)
		(layer "In4.Cu")
		(net "M_D_CPU0_SA_CA<4>")
	)
	(segment
		(start 294.02024 -253.009908)
		(end 294.250618 -253.009908)
		(width 0.14478)
		(layer "In4.Cu")
		(net "M_D_CPU0_SA_CA<4>")
	)
	(segment
		(start 294.250618 -253.009908)
		(end 294.413686 -253.172976)
		(width 0.14478)
		(layer "In4.Cu")
		(net "M_D_CPU0_SA_CA<4>")
	)
	(segment
		(start 298.5389 -253.238762)
		(end 298.5389 -253.172976)
		(width 0.14478)
		(layer "In4.Cu")
		(net "M_D_CPU0_SA_CA<4>")
	)
	(segment
		(start 289.015424 -253.238762)
		(end 289.178492 -253.40183)
		(width 0.14478)
		(layer "In4.Cu")
		(net "M_D_CPU0_SA_CA<4>")
	)
	(segment
		(start 301.750984 -253.009908)
		(end 307.760878 -253.009908)
		(width 0.14478)
		(layer "In4.Cu")
		(net "M_D_CPU0_SA_CA<4>")
	)
	(segment
		(start 289.735006 -253.009908)
		(end 289.965384 -253.009908)
		(width 0.14478)
		(layer "In4.Cu")
		(net "M_D_CPU0_SA_CA<4>")
	)
	(segment
		(start 297.032426 -253.40183)
		(end 297.262804 -253.40183)
		(width 0.14478)
		(layer "In4.Cu")
		(net "M_D_CPU0_SA_CA<4>")
	)
	(segment
		(start 297.262804 -253.40183)
		(end 297.425872 -253.238762)
		(width 0.14478)
		(layer "In4.Cu")
		(net "M_D_CPU0_SA_CA<4>")
	)
	(segment
		(start 294.9702 -253.172976)
		(end 295.133268 -253.009908)
		(width 0.14478)
		(layer "In4.Cu")
		(net "M_D_CPU0_SA_CA<4>")
	)
	(segment
		(start 333.579724 -254.531622)
		(end 333.588106 -254.526796)
		(width 0.0889)
		(layer "In4.Cu")
		(net "M_D_CPU0_SA_CA<4>")
	)
	(segment
		(start 290.684966 -253.238762)
		(end 290.684966 -253.172976)
		(width 0.14478)
		(layer "In4.Cu")
		(net "M_D_CPU0_SA_CA<4>")
	)
	(segment
		(start 324.392036 -254.83947)
		(end 325.028306 -254.83947)
		(width 0.0889)
		(layer "In4.Cu")
		(net "M_D_CPU0_SA_CA<4>")
	)
	(segment
		(start 298.375832 -253.40183)
		(end 298.5389 -253.238762)
		(width 0.14478)
		(layer "In4.Cu")
		(net "M_D_CPU0_SA_CA<4>")
	)
	(segment
		(start 296.869358 -253.172976)
		(end 296.869358 -253.238762)
		(width 0.14478)
		(layer "In4.Cu")
		(net "M_D_CPU0_SA_CA<4>")
	)
	(segment
		(start 294.807132 -253.40183)
		(end 294.9702 -253.238762)
		(width 0.14478)
		(layer "In4.Cu")
		(net "M_D_CPU0_SA_CA<4>")
	)
	(segment
		(start 293.300658 -253.238762)
		(end 293.463726 -253.40183)
		(width 0.14478)
		(layer "In4.Cu")
		(net "M_D_CPU0_SA_CA<4>")
	)
	(segment
		(start 297.425872 -253.238762)
		(end 297.425872 -253.172976)
		(width 0.14478)
		(layer "In4.Cu")
		(net "M_D_CPU0_SA_CA<4>")
	)
	(segment
		(start 294.576754 -253.40183)
		(end 294.807132 -253.40183)
		(width 0.14478)
		(layer "In4.Cu")
		(net "M_D_CPU0_SA_CA<4>")
	)
	(segment
		(start 298.145454 -253.40183)
		(end 298.375832 -253.40183)
		(width 0.14478)
		(layer "In4.Cu")
		(net "M_D_CPU0_SA_CA<4>")
	)
	(segment
		(start 325.157084 -254.710692)
		(end 325.858632 -254.710692)
		(width 0.0889)
		(layer "In4.Cu")
		(net "M_D_CPU0_SA_CA<4>")
	)
	(segment
		(start 324.203314 -254.76073)
		(end 324.313296 -254.76073)
		(width 0.0889)
		(layer "In4.Cu")
		(net "M_D_CPU0_SA_CA<4>")
	)
	(segment
		(start 294.413686 -253.238762)
		(end 294.576754 -253.40183)
		(width 0.14478)
		(layer "In4.Cu")
		(net "M_D_CPU0_SA_CA<4>")
	)
	(segment
		(start 300.868334 -253.009908)
		(end 301.031402 -253.172976)
		(width 0.14478)
		(layer "In4.Cu")
		(net "M_D_CPU0_SA_CA<4>")
	)
	(segment
		(start 294.413686 -253.172976)
		(end 294.413686 -253.238762)
		(width 0.14478)
		(layer "In4.Cu")
		(net "M_D_CPU0_SA_CA<4>")
	)
	(segment
		(start 297.982386 -253.238762)
		(end 298.145454 -253.40183)
		(width 0.14478)
		(layer "In4.Cu")
		(net "M_D_CPU0_SA_CA<4>")
	)
	(segment
		(start 293.857172 -253.172976)
		(end 294.02024 -253.009908)
		(width 0.14478)
		(layer "In4.Cu")
		(net "M_D_CPU0_SA_CA<4>")
	)
	(segment
		(start 295.133268 -253.009908)
		(end 296.70629 -253.009908)
		(width 0.14478)
		(layer "In4.Cu")
		(net "M_D_CPU0_SA_CA<4>")
	)
	(segment
		(start 289.178492 -253.40183)
		(end 289.40887 -253.40183)
		(width 0.14478)
		(layer "In4.Cu")
		(net "M_D_CPU0_SA_CA<4>")
	)
	(segment
		(start 289.571938 -253.172976)
		(end 289.735006 -253.009908)
		(width 0.14478)
		(layer "In4.Cu")
		(net "M_D_CPU0_SA_CA<4>")
	)
	(segment
		(start 290.128452 -253.238762)
		(end 290.29152 -253.40183)
		(width 0.14478)
		(layer "In4.Cu")
		(net "M_D_CPU0_SA_CA<4>")
	)
	(segment
		(start 326.991726 -254.537718)
		(end 327.010522 -254.526796)
		(width 0.0889)
		(layer "In4.Cu")
		(net "M_D_CPU0_SA_CA<4>")
	)
	(segment
		(start 293.694104 -253.40183)
		(end 293.857172 -253.238762)
		(width 0.14478)
		(layer "In4.Cu")
		(net "M_D_CPU0_SA_CA<4>")
	)
	(segment
		(start 301.031402 -253.172976)
		(end 301.031402 -253.236222)
		(width 0.14478)
		(layer "In4.Cu")
		(net "M_D_CPU0_SA_CA<4>")
	)
	(segment
		(start 329.819762 -254.531622)
		(end 329.828144 -254.526796)
		(width 0.0889)
		(layer "In4.Cu")
		(net "M_D_CPU0_SA_CA<4>")
	)
	(segment
		(start 301.424848 -253.39929)
		(end 301.587916 -253.236222)
		(width 0.14478)
		(layer "In4.Cu")
		(net "M_D_CPU0_SA_CA<4>")
	)
	(segment
		(start 290.848034 -253.009908)
		(end 293.13759 -253.009908)
		(width 0.14478)
		(layer "In4.Cu")
		(net "M_D_CPU0_SA_CA<4>")
	)
	(segment
		(start 296.70629 -253.009908)
		(end 296.869358 -253.172976)
		(width 0.14478)
		(layer "In4.Cu")
		(net "M_D_CPU0_SA_CA<4>")
	)
	(segment
		(start 335.094072 -254.526796)
		(end 335.102454 -254.531622)
		(width 0.0889)
		(layer "In4.Cu")
		(net "M_D_CPU0_SA_CA<4>")
	)
	(segment
		(start 326.069706 -254.526542)
		(end 326.101456 -254.508254)
		(width 0.0889)
		(layer "In4.Cu")
		(net "M_D_CPU0_SA_CA<4>")
	)
	(segment
		(start 294.9702 -253.238762)
		(end 294.9702 -253.172976)
		(width 0.14478)
		(layer "In4.Cu")
		(net "M_D_CPU0_SA_CA<4>")
	)
	(segment
		(start 307.760878 -253.009908)
		(end 308.49697 -253.746)
		(width 0.14478)
		(layer "In4.Cu")
		(net "M_D_CPU0_SA_CA<4>")
	)
	(segment
		(start 296.869358 -253.238762)
		(end 297.032426 -253.40183)
		(width 0.14478)
		(layer "In4.Cu")
		(net "M_D_CPU0_SA_CA<4>")
	)
	(segment
		(start 286.860996 -253.009908)
		(end 288.852356 -253.009908)
		(width 0.14478)
		(layer "In4.Cu")
		(net "M_D_CPU0_SA_CA<4>")
	)
	(segment
		(start 289.965384 -253.009908)
		(end 290.128452 -253.172976)
		(width 0.14478)
		(layer "In4.Cu")
		(net "M_D_CPU0_SA_CA<4>")
	)
	(segment
		(start 293.463726 -253.40183)
		(end 293.694104 -253.40183)
		(width 0.14478)
		(layer "In4.Cu")
		(net "M_D_CPU0_SA_CA<4>")
	)
	(segment
		(start 297.982386 -253.172976)
		(end 297.982386 -253.238762)
		(width 0.14478)
		(layer "In4.Cu")
		(net "M_D_CPU0_SA_CA<4>")
	)
	(segment
		(start 308.49697 -253.746)
		(end 320.195956 -253.746)
		(width 0.14478)
		(layer "In4.Cu")
		(net "M_D_CPU0_SA_CA<4>")
	)
	(segment
		(start 325.028306 -254.83947)
		(end 325.157084 -254.710692)
		(width 0.0889)
		(layer "In4.Cu")
		(net "M_D_CPU0_SA_CA<4>")
	)
	(segment
		(start 321.210686 -254.76073)
		(end 324.203314 -254.76073)
		(width 0.14478)
		(layer "In4.Cu")
		(net "M_D_CPU0_SA_CA<4>")
	)
	(arc
		(start 337.91398 -254.526796)
		(mid 338.096231 -254.577146)
		(end 338.27974 -254.531622)
		(width 0.0889)
		(layer "In4.Cu")
		(net "M_D_CPU0_SA_CA<4>")
	)
	(arc
		(start 333.588106 -254.526796)
		(mid 333.871062 -254.450619)
		(end 334.154018 -254.526796)
		(width 0.0889)
		(layer "In4.Cu")
		(net "M_D_CPU0_SA_CA<4>")
	)
	(arc
		(start 326.101456 -254.508254)
		(mid 326.370741 -254.450342)
		(end 326.635364 -254.526796)
		(width 0.0889)
		(layer "In4.Cu")
		(net "M_D_CPU0_SA_CA<4>")
	)
	(arc
		(start 333.213964 -254.526796)
		(mid 333.396215 -254.577146)
		(end 333.579724 -254.531622)
		(width 0.0889)
		(layer "In4.Cu")
		(net "M_D_CPU0_SA_CA<4>")
	)
	(arc
		(start 332.648052 -254.526796)
		(mid 332.931008 -254.450619)
		(end 333.213964 -254.526796)
		(width 0.0889)
		(layer "In4.Cu")
		(net "M_D_CPU0_SA_CA<4>")
	)
	(arc
		(start 336.97418 -254.526796)
		(mid 337.161124 -254.577051)
		(end 337.348068 -254.526796)
		(width 0.0889)
		(layer "In4.Cu")
		(net "M_D_CPU0_SA_CA<4>")
	)
	(arc
		(start 328.88809 -254.526796)
		(mid 329.171046 -254.450619)
		(end 329.454002 -254.526796)
		(width 0.0889)
		(layer "In4.Cu")
		(net "M_D_CPU0_SA_CA<4>")
	)
	(arc
		(start 330.402438 -254.531622)
		(mid 330.585946 -254.577116)
		(end 330.768198 -254.526796)
		(width 0.0889)
		(layer "In4.Cu")
		(net "M_D_CPU0_SA_CA<4>")
	)
	(arc
		(start 337.348068 -254.526796)
		(mid 337.631024 -254.450619)
		(end 337.91398 -254.526796)
		(width 0.0889)
		(layer "In4.Cu")
		(net "M_D_CPU0_SA_CA<4>")
	)
	(arc
		(start 325.95312 -254.616204)
		(mid 326.008469 -254.567545)
		(end 326.069706 -254.526542)
		(width 0.0889)
		(layer "In4.Cu")
		(net "M_D_CPU0_SA_CA<4>")
	)
	(arc
		(start 329.828144 -254.526796)
		(mid 330.1111 -254.450619)
		(end 330.394056 -254.526796)
		(width 0.0889)
		(layer "In4.Cu")
		(net "M_D_CPU0_SA_CA<4>")
	)
	(arc
		(start 330.768198 -254.526796)
		(mid 331.051154 -254.450619)
		(end 331.33411 -254.526796)
		(width 0.0889)
		(layer "In4.Cu")
		(net "M_D_CPU0_SA_CA<4>")
	)
	(arc
		(start 334.154018 -254.526796)
		(mid 334.336269 -254.577146)
		(end 334.519778 -254.531622)
		(width 0.0889)
		(layer "In4.Cu")
		(net "M_D_CPU0_SA_CA<4>")
	)
	(arc
		(start 336.408268 -254.526796)
		(mid 336.691224 -254.450619)
		(end 336.97418 -254.526796)
		(width 0.0889)
		(layer "In4.Cu")
		(net "M_D_CPU0_SA_CA<4>")
	)
	(arc
		(start 327.594976 -254.537972)
		(mid 327.773054 -254.576956)
		(end 327.94829 -254.526796)
		(width 0.0889)
		(layer "In4.Cu")
		(net "M_D_CPU0_SA_CA<4>")
	)
	(arc
		(start 338.288122 -254.526796)
		(mid 338.535835 -254.451576)
		(end 338.791042 -254.495046)
		(width 0.0889)
		(layer "In4.Cu")
		(net "M_D_CPU0_SA_CA<4>")
	)
	(arc
		(start 328.514202 -254.526796)
		(mid 328.701146 -254.577051)
		(end 328.88809 -254.526796)
		(width 0.0889)
		(layer "In4.Cu")
		(net "M_D_CPU0_SA_CA<4>")
	)
	(arc
		(start 326.635364 -254.526796)
		(mid 326.812155 -254.577515)
		(end 326.991726 -254.537718)
		(width 0.0889)
		(layer "In4.Cu")
		(net "M_D_CPU0_SA_CA<4>")
	)
	(arc
		(start 332.274164 -254.526796)
		(mid 332.461108 -254.577051)
		(end 332.648052 -254.526796)
		(width 0.0889)
		(layer "In4.Cu")
		(net "M_D_CPU0_SA_CA<4>")
	)
	(arc
		(start 327.94829 -254.526796)
		(mid 328.231246 -254.450619)
		(end 328.514202 -254.526796)
		(width 0.0889)
		(layer "In4.Cu")
		(net "M_D_CPU0_SA_CA<4>")
	)
	(arc
		(start 334.52816 -254.526796)
		(mid 334.811116 -254.450619)
		(end 335.094072 -254.526796)
		(width 0.0889)
		(layer "In4.Cu")
		(net "M_D_CPU0_SA_CA<4>")
	)
	(arc
		(start 331.708252 -254.526796)
		(mid 331.991208 -254.450619)
		(end 332.274164 -254.526796)
		(width 0.0889)
		(layer "In4.Cu")
		(net "M_D_CPU0_SA_CA<4>")
	)
	(arc
		(start 336.042508 -254.531622)
		(mid 336.226016 -254.577116)
		(end 336.408268 -254.526796)
		(width 0.0889)
		(layer "In4.Cu")
		(net "M_D_CPU0_SA_CA<4>")
	)
	(arc
		(start 329.454002 -254.526796)
		(mid 329.636253 -254.577146)
		(end 329.819762 -254.531622)
		(width 0.0889)
		(layer "In4.Cu")
		(net "M_D_CPU0_SA_CA<4>")
	)
	(arc
		(start 327.010522 -254.526796)
		(mid 327.280291 -254.450773)
		(end 327.55332 -254.514096)
		(width 0.0889)
		(layer "In4.Cu")
		(net "M_D_CPU0_SA_CA<4>")
	)
	(arc
		(start 335.102454 -254.531622)
		(mid 335.285962 -254.577116)
		(end 335.468214 -254.526796)
		(width 0.0889)
		(layer "In4.Cu")
		(net "M_D_CPU0_SA_CA<4>")
	)
	(arc
		(start 331.342492 -254.531622)
		(mid 331.526 -254.577116)
		(end 331.708252 -254.526796)
		(width 0.0889)
		(layer "In4.Cu")
		(net "M_D_CPU0_SA_CA<4>")
	)
	(arc
		(start 335.468214 -254.526796)
		(mid 335.75117 -254.450619)
		(end 336.034126 -254.526796)
		(width 0.0889)
		(layer "In4.Cu")
		(net "M_D_CPU0_SA_CA<4>")
	)
	(segment
		(start 340.447884 -254.470154)
		(end 339.981032 -254.204216)
		(width 0.10668)
		(layer "F.Cu")
		(net "M_D_CPU0_SA_CA<3>")
	)
	(segment
		(start 336.034126 -253.881636)
		(end 336.042508 -253.87681)
		(width 0.0889)
		(layer "In4.Cu")
		(net "M_D_CPU0_SA_CA<3>")
	)
	(segment
		(start 280.635964 -250.03506)
		(end 281.060906 -250.460002)
		(width 0.14478)
		(layer "In4.Cu")
		(net "M_D_CPU0_SA_CA<3>")
	)
	(segment
		(start 320.389504 -253.29642)
		(end 321.394074 -254.30099)
		(width 0.14478)
		(layer "In4.Cu")
		(net "M_D_CPU0_SA_CA<3>")
	)
	(segment
		(start 281.060906 -250.460002)
		(end 285.096966 -250.460002)
		(width 0.14478)
		(layer "In4.Cu")
		(net "M_D_CPU0_SA_CA<3>")
	)
	(segment
		(start 308.683406 -253.29642)
		(end 320.389504 -253.29642)
		(width 0.14478)
		(layer "In4.Cu")
		(net "M_D_CPU0_SA_CA<3>")
	)
	(segment
		(start 285.096966 -250.460002)
		(end 286.796988 -252.160024)
		(width 0.14478)
		(layer "In4.Cu")
		(net "M_D_CPU0_SA_CA<3>")
	)
	(segment
		(start 286.796988 -252.160024)
		(end 307.54701 -252.160024)
		(width 0.14478)
		(layer "In4.Cu")
		(net "M_D_CPU0_SA_CA<3>")
	)
	(segment
		(start 338.27974 -253.87681)
		(end 338.288122 -253.881636)
		(width 0.0889)
		(layer "In4.Cu")
		(net "M_D_CPU0_SA_CA<3>")
	)
	(segment
		(start 335.094072 -253.881636)
		(end 335.102454 -253.87681)
		(width 0.0889)
		(layer "In4.Cu")
		(net "M_D_CPU0_SA_CA<3>")
	)
	(segment
		(start 334.519778 -253.87681)
		(end 334.52816 -253.881636)
		(width 0.0889)
		(layer "In4.Cu")
		(net "M_D_CPU0_SA_CA<3>")
	)
	(segment
		(start 326.617838 -253.891034)
		(end 326.633586 -253.88189)
		(width 0.0889)
		(layer "In4.Cu")
		(net "M_D_CPU0_SA_CA<3>")
	)
	(segment
		(start 321.394074 -254.30099)
		(end 323.895974 -254.30099)
		(width 0.14478)
		(layer "In4.Cu")
		(net "M_D_CPU0_SA_CA<3>")
	)
	(segment
		(start 327.939908 -253.87681)
		(end 327.94829 -253.881636)
		(width 0.0889)
		(layer "In4.Cu")
		(net "M_D_CPU0_SA_CA<3>")
	)
	(segment
		(start 340.13521 -253.938786)
		(end 339.981032 -254.204216)
		(width 0.0889)
		(layer "In4.Cu")
		(net "M_D_CPU0_SA_CA<3>")
	)
	(segment
		(start 325.693278 -253.881636)
		(end 325.704962 -253.874778)
		(width 0.0889)
		(layer "In4.Cu")
		(net "M_D_CPU0_SA_CA<3>")
	)
	(segment
		(start 307.54701 -252.160024)
		(end 308.683406 -253.29642)
		(width 0.14478)
		(layer "In4.Cu")
		(net "M_D_CPU0_SA_CA<3>")
	)
	(segment
		(start 333.579724 -253.87681)
		(end 333.588106 -253.881636)
		(width 0.0889)
		(layer "In4.Cu")
		(net "M_D_CPU0_SA_CA<3>")
	)
	(segment
		(start 324.21576 -254.30099)
		(end 324.435978 -254.080772)
		(width 0.0889)
		(layer "In4.Cu")
		(net "M_D_CPU0_SA_CA<3>")
	)
	(segment
		(start 329.819762 -253.87681)
		(end 329.828144 -253.881636)
		(width 0.0889)
		(layer "In4.Cu")
		(net "M_D_CPU0_SA_CA<3>")
	)
	(segment
		(start 338.854034 -253.881636)
		(end 338.862416 -253.87681)
		(width 0.0889)
		(layer "In4.Cu")
		(net "M_D_CPU0_SA_CA<3>")
	)
	(segment
		(start 331.33411 -253.881636)
		(end 331.342492 -253.87681)
		(width 0.0889)
		(layer "In4.Cu")
		(net "M_D_CPU0_SA_CA<3>")
	)
	(segment
		(start 326.633586 -253.88189)
		(end 326.649842 -253.872492)
		(width 0.0889)
		(layer "In4.Cu")
		(net "M_D_CPU0_SA_CA<3>")
	)
	(segment
		(start 327.007474 -253.881636)
		(end 327.017888 -253.887732)
		(width 0.0889)
		(layer "In4.Cu")
		(net "M_D_CPU0_SA_CA<3>")
	)
	(segment
		(start 330.394056 -253.881636)
		(end 330.402438 -253.87681)
		(width 0.0889)
		(layer "In4.Cu")
		(net "M_D_CPU0_SA_CA<3>")
	)
	(segment
		(start 324.435978 -254.080772)
		(end 324.95363 -254.080772)
		(width 0.0889)
		(layer "In4.Cu")
		(net "M_D_CPU0_SA_CA<3>")
	)
	(segment
		(start 323.895974 -254.30099)
		(end 324.21576 -254.30099)
		(width 0.0889)
		(layer "In4.Cu")
		(net "M_D_CPU0_SA_CA<3>")
	)
	(segment
		(start 340.112858 -253.855474)
		(end 340.13521 -253.938786)
		(width 0.0889)
		(layer "In4.Cu")
		(net "M_D_CPU0_SA_CA<3>")
	)
	(segment
		(start 339.794088 -253.881636)
		(end 339.80247 -253.87681)
		(width 0.0889)
		(layer "In4.Cu")
		(net "M_D_CPU0_SA_CA<3>")
	)
	(arc
		(start 333.588106 -253.881636)
		(mid 333.871062 -253.957813)
		(end 334.154018 -253.881636)
		(width 0.0889)
		(layer "In4.Cu")
		(net "M_D_CPU0_SA_CA<3>")
	)
	(arc
		(start 333.213964 -253.881636)
		(mid 333.396215 -253.831286)
		(end 333.579724 -253.87681)
		(width 0.0889)
		(layer "In4.Cu")
		(net "M_D_CPU0_SA_CA<3>")
	)
	(arc
		(start 337.348068 -253.881636)
		(mid 337.631024 -253.957813)
		(end 337.91398 -253.881636)
		(width 0.0889)
		(layer "In4.Cu")
		(net "M_D_CPU0_SA_CA<3>")
	)
	(arc
		(start 330.402438 -253.87681)
		(mid 330.585946 -253.831316)
		(end 330.768198 -253.881636)
		(width 0.0889)
		(layer "In4.Cu")
		(net "M_D_CPU0_SA_CA<3>")
	)
	(arc
		(start 330.768198 -253.881636)
		(mid 331.051154 -253.957813)
		(end 331.33411 -253.881636)
		(width 0.0889)
		(layer "In4.Cu")
		(net "M_D_CPU0_SA_CA<3>")
	)
	(arc
		(start 336.97418 -253.881636)
		(mid 337.161124 -253.831381)
		(end 337.348068 -253.881636)
		(width 0.0889)
		(layer "In4.Cu")
		(net "M_D_CPU0_SA_CA<3>")
	)
	(arc
		(start 327.57364 -253.881636)
		(mid 327.756145 -253.831159)
		(end 327.939908 -253.87681)
		(width 0.0889)
		(layer "In4.Cu")
		(net "M_D_CPU0_SA_CA<3>")
	)
	(arc
		(start 332.648052 -253.881636)
		(mid 332.931008 -253.957813)
		(end 333.213964 -253.881636)
		(width 0.0889)
		(layer "In4.Cu")
		(net "M_D_CPU0_SA_CA<3>")
	)
	(arc
		(start 335.102454 -253.87681)
		(mid 335.285962 -253.831316)
		(end 335.468214 -253.881636)
		(width 0.0889)
		(layer "In4.Cu")
		(net "M_D_CPU0_SA_CA<3>")
	)
	(arc
		(start 331.342492 -253.87681)
		(mid 331.526 -253.831316)
		(end 331.708252 -253.881636)
		(width 0.0889)
		(layer "In4.Cu")
		(net "M_D_CPU0_SA_CA<3>")
	)
	(arc
		(start 332.274164 -253.881636)
		(mid 332.461108 -253.831381)
		(end 332.648052 -253.881636)
		(width 0.0889)
		(layer "In4.Cu")
		(net "M_D_CPU0_SA_CA<3>")
	)
	(arc
		(start 328.514202 -253.881636)
		(mid 328.701146 -253.831381)
		(end 328.88809 -253.881636)
		(width 0.0889)
		(layer "In4.Cu")
		(net "M_D_CPU0_SA_CA<3>")
	)
	(arc
		(start 334.52816 -253.881636)
		(mid 334.811116 -253.957813)
		(end 335.094072 -253.881636)
		(width 0.0889)
		(layer "In4.Cu")
		(net "M_D_CPU0_SA_CA<3>")
	)
	(arc
		(start 327.94829 -253.881636)
		(mid 328.231246 -253.957813)
		(end 328.514202 -253.881636)
		(width 0.0889)
		(layer "In4.Cu")
		(net "M_D_CPU0_SA_CA<3>")
	)
	(arc
		(start 325.704962 -253.874778)
		(mid 325.887217 -253.831125)
		(end 326.067674 -253.881636)
		(width 0.0889)
		(layer "In4.Cu")
		(net "M_D_CPU0_SA_CA<3>")
	)
	(arc
		(start 328.88809 -253.881636)
		(mid 329.171046 -253.957813)
		(end 329.454002 -253.881636)
		(width 0.0889)
		(layer "In4.Cu")
		(net "M_D_CPU0_SA_CA<3>")
	)
	(arc
		(start 337.91398 -253.881636)
		(mid 338.096231 -253.831286)
		(end 338.27974 -253.87681)
		(width 0.0889)
		(layer "In4.Cu")
		(net "M_D_CPU0_SA_CA<3>")
	)
	(arc
		(start 326.649842 -253.872492)
		(mid 326.829824 -253.831392)
		(end 327.007474 -253.881636)
		(width 0.0889)
		(layer "In4.Cu")
		(net "M_D_CPU0_SA_CA<3>")
	)
	(arc
		(start 335.468214 -253.881636)
		(mid 335.75117 -253.957813)
		(end 336.034126 -253.881636)
		(width 0.0889)
		(layer "In4.Cu")
		(net "M_D_CPU0_SA_CA<3>")
	)
	(arc
		(start 327.017888 -253.887732)
		(mid 327.296574 -253.957952)
		(end 327.57364 -253.881636)
		(width 0.0889)
		(layer "In4.Cu")
		(net "M_D_CPU0_SA_CA<3>")
	)
	(arc
		(start 329.828144 -253.881636)
		(mid 330.1111 -253.957813)
		(end 330.394056 -253.881636)
		(width 0.0889)
		(layer "In4.Cu")
		(net "M_D_CPU0_SA_CA<3>")
	)
	(arc
		(start 339.228176 -253.881636)
		(mid 339.511132 -253.957813)
		(end 339.794088 -253.881636)
		(width 0.0889)
		(layer "In4.Cu")
		(net "M_D_CPU0_SA_CA<3>")
	)
	(arc
		(start 326.067674 -253.881636)
		(mid 326.341529 -253.957986)
		(end 326.617838 -253.891034)
		(width 0.0889)
		(layer "In4.Cu")
		(net "M_D_CPU0_SA_CA<3>")
	)
	(arc
		(start 338.288122 -253.881636)
		(mid 338.571078 -253.957813)
		(end 338.854034 -253.881636)
		(width 0.0889)
		(layer "In4.Cu")
		(net "M_D_CPU0_SA_CA<3>")
	)
	(arc
		(start 329.454002 -253.881636)
		(mid 329.636253 -253.831286)
		(end 329.819762 -253.87681)
		(width 0.0889)
		(layer "In4.Cu")
		(net "M_D_CPU0_SA_CA<3>")
	)
	(arc
		(start 324.95363 -254.080772)
		(mid 325.336623 -254.030117)
		(end 325.693278 -253.881636)
		(width 0.0889)
		(layer "In4.Cu")
		(net "M_D_CPU0_SA_CA<3>")
	)
	(arc
		(start 336.042508 -253.87681)
		(mid 336.226016 -253.831316)
		(end 336.408268 -253.881636)
		(width 0.0889)
		(layer "In4.Cu")
		(net "M_D_CPU0_SA_CA<3>")
	)
	(arc
		(start 336.408268 -253.881636)
		(mid 336.691224 -253.957813)
		(end 336.97418 -253.881636)
		(width 0.0889)
		(layer "In4.Cu")
		(net "M_D_CPU0_SA_CA<3>")
	)
	(arc
		(start 339.80247 -253.87681)
		(mid 339.95534 -253.832169)
		(end 340.112858 -253.855474)
		(width 0.0889)
		(layer "In4.Cu")
		(net "M_D_CPU0_SA_CA<3>")
	)
	(arc
		(start 331.708252 -253.881636)
		(mid 331.991208 -253.957813)
		(end 332.274164 -253.881636)
		(width 0.0889)
		(layer "In4.Cu")
		(net "M_D_CPU0_SA_CA<3>")
	)
	(arc
		(start 334.154018 -253.881636)
		(mid 334.336269 -253.831286)
		(end 334.519778 -253.87681)
		(width 0.0889)
		(layer "In4.Cu")
		(net "M_D_CPU0_SA_CA<3>")
	)
	(arc
		(start 338.862416 -253.87681)
		(mid 339.045924 -253.831316)
		(end 339.228176 -253.881636)
		(width 0.0889)
		(layer "In4.Cu")
		(net "M_D_CPU0_SA_CA<3>")
	)
	(segment
		(start 340.918038 -253.660148)
		(end 340.451186 -253.39421)
		(width 0.10668)
		(layer "F.Cu")
		(net "M_D_CPU0_SA_CA<2>")
	)
	(segment
		(start 289.842702 -251.309886)
		(end 290.07308 -251.309886)
		(width 0.14478)
		(layer "In4.Cu")
		(net "M_D_CPU0_SA_CA<2>")
	)
	(segment
		(start 325.597266 -253.71679)
		(end 325.611998 -253.708154)
		(width 0.0889)
		(layer "In4.Cu")
		(net "M_D_CPU0_SA_CA<2>")
	)
	(segment
		(start 290.792662 -251.472954)
		(end 290.95573 -251.309886)
		(width 0.14478)
		(layer "In4.Cu")
		(net "M_D_CPU0_SA_CA<2>")
	)
	(segment
		(start 290.07308 -251.309886)
		(end 290.236148 -251.472954)
		(width 0.14478)
		(layer "In4.Cu")
		(net "M_D_CPU0_SA_CA<2>")
	)
	(segment
		(start 307.552598 -251.309886)
		(end 309.089552 -252.84684)
		(width 0.14478)
		(layer "In4.Cu")
		(net "M_D_CPU0_SA_CA<2>")
	)
	(segment
		(start 294.091106 -251.70257)
		(end 294.254174 -251.539502)
		(width 0.14478)
		(layer "In4.Cu")
		(net "M_D_CPU0_SA_CA<2>")
	)
	(segment
		(start 327.103232 -253.71679)
		(end 327.111614 -253.721616)
		(width 0.0889)
		(layer "In4.Cu")
		(net "M_D_CPU0_SA_CA<2>")
	)
	(segment
		(start 309.089552 -252.84684)
		(end 320.583052 -252.84684)
		(width 0.14478)
		(layer "In4.Cu")
		(net "M_D_CPU0_SA_CA<2>")
	)
	(segment
		(start 289.286188 -251.70257)
		(end 289.516566 -251.70257)
		(width 0.14478)
		(layer "In4.Cu")
		(net "M_D_CPU0_SA_CA<2>")
	)
	(segment
		(start 289.12312 -251.539502)
		(end 289.286188 -251.70257)
		(width 0.14478)
		(layer "In4.Cu")
		(net "M_D_CPU0_SA_CA<2>")
	)
	(segment
		(start 339.689694 -253.721616)
		(end 339.698076 -253.71679)
		(width 0.0889)
		(layer "In4.Cu")
		(net "M_D_CPU0_SA_CA<2>")
	)
	(segment
		(start 289.12312 -251.472954)
		(end 289.12312 -251.539502)
		(width 0.14478)
		(layer "In4.Cu")
		(net "M_D_CPU0_SA_CA<2>")
	)
	(segment
		(start 294.254174 -251.472954)
		(end 294.417242 -251.309886)
		(width 0.14478)
		(layer "In4.Cu")
		(net "M_D_CPU0_SA_CA<2>")
	)
	(segment
		(start 293.534592 -251.309886)
		(end 293.69766 -251.472954)
		(width 0.14478)
		(layer "In4.Cu")
		(net "M_D_CPU0_SA_CA<2>")
	)
	(segment
		(start 340.297008 -253.65964)
		(end 340.451186 -253.39421)
		(width 0.0889)
		(layer "In4.Cu")
		(net "M_D_CPU0_SA_CA<2>")
	)
	(segment
		(start 328.984102 -253.71679)
		(end 328.992484 -253.721616)
		(width 0.0889)
		(layer "In4.Cu")
		(net "M_D_CPU0_SA_CA<2>")
	)
	(segment
		(start 284.736032 -249.185176)
		(end 286.860742 -251.309886)
		(width 0.14478)
		(layer "In4.Cu")
		(net "M_D_CPU0_SA_CA<2>")
	)
	(segment
		(start 294.417242 -251.309886)
		(end 307.552598 -251.309886)
		(width 0.14478)
		(layer "In4.Cu")
		(net "M_D_CPU0_SA_CA<2>")
	)
	(segment
		(start 290.236148 -251.539502)
		(end 290.399216 -251.70257)
		(width 0.14478)
		(layer "In4.Cu")
		(net "M_D_CPU0_SA_CA<2>")
	)
	(segment
		(start 293.69766 -251.539502)
		(end 293.860728 -251.70257)
		(width 0.14478)
		(layer "In4.Cu")
		(net "M_D_CPU0_SA_CA<2>")
	)
	(segment
		(start 326.51954 -253.72695)
		(end 326.537828 -253.716536)
		(width 0.0889)
		(layer "In4.Cu")
		(net "M_D_CPU0_SA_CA<2>")
	)
	(segment
		(start 337.44408 -253.71679)
		(end 337.452462 -253.721616)
		(width 0.0889)
		(layer "In4.Cu")
		(net "M_D_CPU0_SA_CA<2>")
	)
	(segment
		(start 321.580002 -253.84379)
		(end 323.901054 -253.84379)
		(width 0.14478)
		(layer "In4.Cu")
		(net "M_D_CPU0_SA_CA<2>")
	)
	(segment
		(start 290.399216 -251.70257)
		(end 290.629594 -251.70257)
		(width 0.14478)
		(layer "In4.Cu")
		(net "M_D_CPU0_SA_CA<2>")
	)
	(segment
		(start 328.409808 -253.721616)
		(end 328.41819 -253.71679)
		(width 0.0889)
		(layer "In4.Cu")
		(net "M_D_CPU0_SA_CA<2>")
	)
	(segment
		(start 324.18528 -253.84379)
		(end 324.261734 -253.767336)
		(width 0.0889)
		(layer "In4.Cu")
		(net "M_D_CPU0_SA_CA<2>")
	)
	(segment
		(start 326.537828 -253.716536)
		(end 326.543416 -253.713234)
		(width 0.0889)
		(layer "In4.Cu")
		(net "M_D_CPU0_SA_CA<2>")
	)
	(segment
		(start 289.679634 -251.539502)
		(end 289.679634 -251.472954)
		(width 0.14478)
		(layer "In4.Cu")
		(net "M_D_CPU0_SA_CA<2>")
	)
	(segment
		(start 332.744064 -253.71679)
		(end 332.752446 -253.721616)
		(width 0.0889)
		(layer "In4.Cu")
		(net "M_D_CPU0_SA_CA<2>")
	)
	(segment
		(start 336.869786 -253.721616)
		(end 336.878168 -253.71679)
		(width 0.0889)
		(layer "In4.Cu")
		(net "M_D_CPU0_SA_CA<2>")
	)
	(segment
		(start 290.95573 -251.309886)
		(end 293.534592 -251.309886)
		(width 0.14478)
		(layer "In4.Cu")
		(net "M_D_CPU0_SA_CA<2>")
	)
	(segment
		(start 323.901054 -253.84379)
		(end 324.18528 -253.84379)
		(width 0.0889)
		(layer "In4.Cu")
		(net "M_D_CPU0_SA_CA<2>")
	)
	(segment
		(start 288.960052 -251.309886)
		(end 289.12312 -251.472954)
		(width 0.14478)
		(layer "In4.Cu")
		(net "M_D_CPU0_SA_CA<2>")
	)
	(segment
		(start 293.860728 -251.70257)
		(end 294.091106 -251.70257)
		(width 0.14478)
		(layer "In4.Cu")
		(net "M_D_CPU0_SA_CA<2>")
	)
	(segment
		(start 335.929732 -253.721616)
		(end 335.938114 -253.71679)
		(width 0.0889)
		(layer "In4.Cu")
		(net "M_D_CPU0_SA_CA<2>")
	)
	(segment
		(start 290.629594 -251.70257)
		(end 290.792662 -251.539502)
		(width 0.14478)
		(layer "In4.Cu")
		(net "M_D_CPU0_SA_CA<2>")
	)
	(segment
		(start 290.792662 -251.539502)
		(end 290.792662 -251.472954)
		(width 0.14478)
		(layer "In4.Cu")
		(net "M_D_CPU0_SA_CA<2>")
	)
	(segment
		(start 290.236148 -251.472954)
		(end 290.236148 -251.539502)
		(width 0.14478)
		(layer "In4.Cu")
		(net "M_D_CPU0_SA_CA<2>")
	)
	(segment
		(start 320.583052 -252.84684)
		(end 321.580002 -253.84379)
		(width 0.14478)
		(layer "In4.Cu")
		(net "M_D_CPU0_SA_CA<2>")
	)
	(segment
		(start 333.684118 -253.71679)
		(end 333.6925 -253.721616)
		(width 0.0889)
		(layer "In4.Cu")
		(net "M_D_CPU0_SA_CA<2>")
	)
	(segment
		(start 293.69766 -251.472954)
		(end 293.69766 -251.539502)
		(width 0.14478)
		(layer "In4.Cu")
		(net "M_D_CPU0_SA_CA<2>")
	)
	(segment
		(start 340.200742 -253.68504)
		(end 340.297008 -253.65964)
		(width 0.0889)
		(layer "In4.Cu")
		(net "M_D_CPU0_SA_CA<2>")
	)
	(segment
		(start 331.229716 -253.721616)
		(end 331.238098 -253.71679)
		(width 0.0889)
		(layer "In4.Cu")
		(net "M_D_CPU0_SA_CA<2>")
	)
	(segment
		(start 289.516566 -251.70257)
		(end 289.679634 -251.539502)
		(width 0.14478)
		(layer "In4.Cu")
		(net "M_D_CPU0_SA_CA<2>")
	)
	(segment
		(start 294.254174 -251.539502)
		(end 294.254174 -251.472954)
		(width 0.14478)
		(layer "In4.Cu")
		(net "M_D_CPU0_SA_CA<2>")
	)
	(segment
		(start 332.16977 -253.721616)
		(end 332.178152 -253.71679)
		(width 0.0889)
		(layer "In4.Cu")
		(net "M_D_CPU0_SA_CA<2>")
	)
	(segment
		(start 286.860742 -251.309886)
		(end 288.960052 -251.309886)
		(width 0.14478)
		(layer "In4.Cu")
		(net "M_D_CPU0_SA_CA<2>")
	)
	(segment
		(start 328.033634 -253.710694)
		(end 328.044048 -253.71679)
		(width 0.0889)
		(layer "In4.Cu")
		(net "M_D_CPU0_SA_CA<2>")
	)
	(segment
		(start 325.409814 -253.767336)
		(end 325.410068 -253.767082)
		(width 0.0889)
		(layer "In4.Cu")
		(net "M_D_CPU0_SA_CA<2>")
	)
	(segment
		(start 289.679634 -251.472954)
		(end 289.842702 -251.309886)
		(width 0.14478)
		(layer "In4.Cu")
		(net "M_D_CPU0_SA_CA<2>")
	)
	(segment
		(start 324.261734 -253.767336)
		(end 325.409814 -253.767336)
		(width 0.0889)
		(layer "In4.Cu")
		(net "M_D_CPU0_SA_CA<2>")
	)
	(arc
		(start 334.99806 -253.71679)
		(mid 335.281016 -253.640613)
		(end 335.563972 -253.71679)
		(width 0.0889)
		(layer "In4.Cu")
		(net "M_D_CPU0_SA_CA<2>")
	)
	(arc
		(start 328.044048 -253.71679)
		(mid 328.226299 -253.76714)
		(end 328.409808 -253.721616)
		(width 0.0889)
		(layer "In4.Cu")
		(net "M_D_CPU0_SA_CA<2>")
	)
	(arc
		(start 334.624172 -253.71679)
		(mid 334.811116 -253.767045)
		(end 334.99806 -253.71679)
		(width 0.0889)
		(layer "In4.Cu")
		(net "M_D_CPU0_SA_CA<2>")
	)
	(arc
		(start 325.611998 -253.708154)
		(mid 325.888981 -253.64035)
		(end 326.163686 -253.71679)
		(width 0.0889)
		(layer "In4.Cu")
		(net "M_D_CPU0_SA_CA<2>")
	)
	(arc
		(start 333.6925 -253.721616)
		(mid 333.876008 -253.76711)
		(end 334.05826 -253.71679)
		(width 0.0889)
		(layer "In4.Cu")
		(net "M_D_CPU0_SA_CA<2>")
	)
	(arc
		(start 336.504026 -253.71679)
		(mid 336.686277 -253.76714)
		(end 336.869786 -253.721616)
		(width 0.0889)
		(layer "In4.Cu")
		(net "M_D_CPU0_SA_CA<2>")
	)
	(arc
		(start 326.543416 -253.713234)
		(mid 326.823805 -253.640565)
		(end 327.103232 -253.71679)
		(width 0.0889)
		(layer "In4.Cu")
		(net "M_D_CPU0_SA_CA<2>")
	)
	(arc
		(start 329.924156 -253.71679)
		(mid 330.1111 -253.767045)
		(end 330.298044 -253.71679)
		(width 0.0889)
		(layer "In4.Cu")
		(net "M_D_CPU0_SA_CA<2>")
	)
	(arc
		(start 329.358244 -253.71679)
		(mid 329.6412 -253.640613)
		(end 329.924156 -253.71679)
		(width 0.0889)
		(layer "In4.Cu")
		(net "M_D_CPU0_SA_CA<2>")
	)
	(arc
		(start 335.938114 -253.71679)
		(mid 336.22107 -253.640613)
		(end 336.504026 -253.71679)
		(width 0.0889)
		(layer "In4.Cu")
		(net "M_D_CPU0_SA_CA<2>")
	)
	(arc
		(start 339.323934 -253.71679)
		(mid 339.506185 -253.76714)
		(end 339.689694 -253.721616)
		(width 0.0889)
		(layer "In4.Cu")
		(net "M_D_CPU0_SA_CA<2>")
	)
	(arc
		(start 335.563972 -253.71679)
		(mid 335.746223 -253.76714)
		(end 335.929732 -253.721616)
		(width 0.0889)
		(layer "In4.Cu")
		(net "M_D_CPU0_SA_CA<2>")
	)
	(arc
		(start 330.298044 -253.71679)
		(mid 330.581 -253.640613)
		(end 330.863956 -253.71679)
		(width 0.0889)
		(layer "In4.Cu")
		(net "M_D_CPU0_SA_CA<2>")
	)
	(arc
		(start 339.698076 -253.71679)
		(mid 339.945672 -253.641612)
		(end 340.200742 -253.68504)
		(width 0.0889)
		(layer "In4.Cu")
		(net "M_D_CPU0_SA_CA<2>")
	)
	(arc
		(start 337.818222 -253.71679)
		(mid 338.101178 -253.640613)
		(end 338.384134 -253.71679)
		(width 0.0889)
		(layer "In4.Cu")
		(net "M_D_CPU0_SA_CA<2>")
	)
	(arc
		(start 337.452462 -253.721616)
		(mid 337.63597 -253.76711)
		(end 337.818222 -253.71679)
		(width 0.0889)
		(layer "In4.Cu")
		(net "M_D_CPU0_SA_CA<2>")
	)
	(arc
		(start 327.111614 -253.721616)
		(mid 327.295376 -253.767232)
		(end 327.477882 -253.71679)
		(width 0.0889)
		(layer "In4.Cu")
		(net "M_D_CPU0_SA_CA<2>")
	)
	(arc
		(start 328.41819 -253.71679)
		(mid 328.701146 -253.640613)
		(end 328.984102 -253.71679)
		(width 0.0889)
		(layer "In4.Cu")
		(net "M_D_CPU0_SA_CA<2>")
	)
	(arc
		(start 338.384134 -253.71679)
		(mid 338.571078 -253.767045)
		(end 338.758022 -253.71679)
		(width 0.0889)
		(layer "In4.Cu")
		(net "M_D_CPU0_SA_CA<2>")
	)
	(arc
		(start 328.992484 -253.721616)
		(mid 329.175992 -253.76711)
		(end 329.358244 -253.71679)
		(width 0.0889)
		(layer "In4.Cu")
		(net "M_D_CPU0_SA_CA<2>")
	)
	(arc
		(start 332.752446 -253.721616)
		(mid 332.935954 -253.76711)
		(end 333.118206 -253.71679)
		(width 0.0889)
		(layer "In4.Cu")
		(net "M_D_CPU0_SA_CA<2>")
	)
	(arc
		(start 326.163686 -253.71679)
		(mid 326.340314 -253.767023)
		(end 326.51954 -253.72695)
		(width 0.0889)
		(layer "In4.Cu")
		(net "M_D_CPU0_SA_CA<2>")
	)
	(arc
		(start 333.118206 -253.71679)
		(mid 333.401162 -253.640613)
		(end 333.684118 -253.71679)
		(width 0.0889)
		(layer "In4.Cu")
		(net "M_D_CPU0_SA_CA<2>")
	)
	(arc
		(start 336.878168 -253.71679)
		(mid 337.161124 -253.640613)
		(end 337.44408 -253.71679)
		(width 0.0889)
		(layer "In4.Cu")
		(net "M_D_CPU0_SA_CA<2>")
	)
	(arc
		(start 334.05826 -253.71679)
		(mid 334.341216 -253.640613)
		(end 334.624172 -253.71679)
		(width 0.0889)
		(layer "In4.Cu")
		(net "M_D_CPU0_SA_CA<2>")
	)
	(arc
		(start 327.477882 -253.71679)
		(mid 327.754949 -253.640519)
		(end 328.033634 -253.710694)
		(width 0.0889)
		(layer "In4.Cu")
		(net "M_D_CPU0_SA_CA<2>")
	)
	(arc
		(start 331.238098 -253.71679)
		(mid 331.521054 -253.640613)
		(end 331.80401 -253.71679)
		(width 0.0889)
		(layer "In4.Cu")
		(net "M_D_CPU0_SA_CA<2>")
	)
	(arc
		(start 332.178152 -253.71679)
		(mid 332.461108 -253.640613)
		(end 332.744064 -253.71679)
		(width 0.0889)
		(layer "In4.Cu")
		(net "M_D_CPU0_SA_CA<2>")
	)
	(arc
		(start 325.410068 -253.767082)
		(mid 325.507 -253.754331)
		(end 325.597266 -253.71679)
		(width 0.0889)
		(layer "In4.Cu")
		(net "M_D_CPU0_SA_CA<2>")
	)
	(arc
		(start 338.758022 -253.71679)
		(mid 339.040978 -253.640613)
		(end 339.323934 -253.71679)
		(width 0.0889)
		(layer "In4.Cu")
		(net "M_D_CPU0_SA_CA<2>")
	)
	(arc
		(start 331.80401 -253.71679)
		(mid 331.986261 -253.76714)
		(end 332.16977 -253.721616)
		(width 0.0889)
		(layer "In4.Cu")
		(net "M_D_CPU0_SA_CA<2>")
	)
	(arc
		(start 330.863956 -253.71679)
		(mid 331.046207 -253.76714)
		(end 331.229716 -253.721616)
		(width 0.0889)
		(layer "In4.Cu")
		(net "M_D_CPU0_SA_CA<2>")
	)
	(segment
		(start 339.03793 -253.660148)
		(end 338.571078 -253.39421)
		(width 0.10668)
		(layer "F.Cu")
		(net "M_D_CPU0_SA_CA<1>")
	)
	(segment
		(start 328.409808 -253.066804)
		(end 328.41819 -253.07163)
		(width 0.0889)
		(layer "In4.Cu")
		(net "M_D_CPU0_SA_CA<1>")
	)
	(segment
		(start 338.725002 -253.12878)
		(end 338.571078 -253.39421)
		(width 0.0889)
		(layer "In4.Cu")
		(net "M_D_CPU0_SA_CA<1>")
	)
	(segment
		(start 285.096966 -248.75998)
		(end 286.796988 -250.460002)
		(width 0.14478)
		(layer "In4.Cu")
		(net "M_D_CPU0_SA_CA<1>")
	)
	(segment
		(start 335.929732 -253.066804)
		(end 335.938114 -253.07163)
		(width 0.0889)
		(layer "In4.Cu")
		(net "M_D_CPU0_SA_CA<1>")
	)
	(segment
		(start 286.796988 -250.460002)
		(end 307.33873 -250.460002)
		(width 0.14478)
		(layer "In4.Cu")
		(net "M_D_CPU0_SA_CA<1>")
	)
	(segment
		(start 331.229716 -253.066804)
		(end 331.238098 -253.07163)
		(width 0.0889)
		(layer "In4.Cu")
		(net "M_D_CPU0_SA_CA<1>")
	)
	(segment
		(start 337.44408 -253.07163)
		(end 337.452462 -253.066804)
		(width 0.0889)
		(layer "In4.Cu")
		(net "M_D_CPU0_SA_CA<1>")
	)
	(segment
		(start 323.908674 -253.38151)
		(end 325.00062 -253.38151)
		(width 0.0889)
		(layer "In4.Cu")
		(net "M_D_CPU0_SA_CA<1>")
	)
	(segment
		(start 280.635964 -248.335038)
		(end 281.060906 -248.75998)
		(width 0.14478)
		(layer "In4.Cu")
		(net "M_D_CPU0_SA_CA<1>")
	)
	(segment
		(start 327.083166 -253.085346)
		(end 327.106534 -253.07163)
		(width 0.0889)
		(layer "In4.Cu")
		(net "M_D_CPU0_SA_CA<1>")
	)
	(segment
		(start 332.16977 -253.066804)
		(end 332.178152 -253.07163)
		(width 0.0889)
		(layer "In4.Cu")
		(net "M_D_CPU0_SA_CA<1>")
	)
	(segment
		(start 333.684118 -253.07163)
		(end 333.6925 -253.066804)
		(width 0.0889)
		(layer "In4.Cu")
		(net "M_D_CPU0_SA_CA<1>")
	)
	(segment
		(start 327.47966 -253.071884)
		(end 327.50125 -253.08433)
		(width 0.0889)
		(layer "In4.Cu")
		(net "M_D_CPU0_SA_CA<1>")
	)
	(segment
		(start 320.779648 -252.39726)
		(end 321.763898 -253.38151)
		(width 0.14478)
		(layer "In4.Cu")
		(net "M_D_CPU0_SA_CA<1>")
	)
	(segment
		(start 325.234808 -253.147322)
		(end 325.883524 -253.147322)
		(width 0.0889)
		(layer "In4.Cu")
		(net "M_D_CPU0_SA_CA<1>")
	)
	(segment
		(start 281.060906 -248.75998)
		(end 285.096966 -248.75998)
		(width 0.14478)
		(layer "In4.Cu")
		(net "M_D_CPU0_SA_CA<1>")
	)
	(segment
		(start 332.744064 -253.07163)
		(end 332.752446 -253.066804)
		(width 0.0889)
		(layer "In4.Cu")
		(net "M_D_CPU0_SA_CA<1>")
	)
	(segment
		(start 309.275988 -252.39726)
		(end 320.779648 -252.39726)
		(width 0.14478)
		(layer "In4.Cu")
		(net "M_D_CPU0_SA_CA<1>")
	)
	(segment
		(start 336.869786 -253.066804)
		(end 336.878168 -253.07163)
		(width 0.0889)
		(layer "In4.Cu")
		(net "M_D_CPU0_SA_CA<1>")
	)
	(segment
		(start 326.16521 -253.071884)
		(end 326.192642 -253.056136)
		(width 0.0889)
		(layer "In4.Cu")
		(net "M_D_CPU0_SA_CA<1>")
	)
	(segment
		(start 338.70265 -253.045468)
		(end 338.725002 -253.12878)
		(width 0.0889)
		(layer "In4.Cu")
		(net "M_D_CPU0_SA_CA<1>")
	)
	(segment
		(start 321.763898 -253.38151)
		(end 323.908674 -253.38151)
		(width 0.14478)
		(layer "In4.Cu")
		(net "M_D_CPU0_SA_CA<1>")
	)
	(segment
		(start 307.33873 -250.460002)
		(end 309.275988 -252.39726)
		(width 0.14478)
		(layer "In4.Cu")
		(net "M_D_CPU0_SA_CA<1>")
	)
	(segment
		(start 327.461372 -253.06147)
		(end 327.47966 -253.071884)
		(width 0.0889)
		(layer "In4.Cu")
		(net "M_D_CPU0_SA_CA<1>")
	)
	(segment
		(start 325.00062 -253.38151)
		(end 325.234808 -253.147322)
		(width 0.0889)
		(layer "In4.Cu")
		(net "M_D_CPU0_SA_CA<1>")
	)
	(segment
		(start 328.984102 -253.07163)
		(end 328.992484 -253.066804)
		(width 0.0889)
		(layer "In4.Cu")
		(net "M_D_CPU0_SA_CA<1>")
	)
	(arc
		(start 330.298044 -253.07163)
		(mid 330.581 -253.147807)
		(end 330.863956 -253.07163)
		(width 0.0889)
		(layer "In4.Cu")
		(net "M_D_CPU0_SA_CA<1>")
	)
	(arc
		(start 331.238098 -253.07163)
		(mid 331.521054 -253.147807)
		(end 331.80401 -253.07163)
		(width 0.0889)
		(layer "In4.Cu")
		(net "M_D_CPU0_SA_CA<1>")
	)
	(arc
		(start 334.624172 -253.07163)
		(mid 334.811116 -253.021375)
		(end 334.99806 -253.07163)
		(width 0.0889)
		(layer "In4.Cu")
		(net "M_D_CPU0_SA_CA<1>")
	)
	(arc
		(start 337.452462 -253.066804)
		(mid 337.63597 -253.02131)
		(end 337.818222 -253.07163)
		(width 0.0889)
		(layer "In4.Cu")
		(net "M_D_CPU0_SA_CA<1>")
	)
	(arc
		(start 336.504026 -253.07163)
		(mid 336.686277 -253.02128)
		(end 336.869786 -253.066804)
		(width 0.0889)
		(layer "In4.Cu")
		(net "M_D_CPU0_SA_CA<1>")
	)
	(arc
		(start 328.992484 -253.066804)
		(mid 329.175992 -253.02131)
		(end 329.358244 -253.07163)
		(width 0.0889)
		(layer "In4.Cu")
		(net "M_D_CPU0_SA_CA<1>")
	)
	(arc
		(start 333.118206 -253.07163)
		(mid 333.401162 -253.147807)
		(end 333.684118 -253.07163)
		(width 0.0889)
		(layer "In4.Cu")
		(net "M_D_CPU0_SA_CA<1>")
	)
	(arc
		(start 333.6925 -253.066804)
		(mid 333.876008 -253.02131)
		(end 334.05826 -253.07163)
		(width 0.0889)
		(layer "In4.Cu")
		(net "M_D_CPU0_SA_CA<1>")
	)
	(arc
		(start 325.883524 -253.147322)
		(mid 326.029347 -253.128182)
		(end 326.16521 -253.071884)
		(width 0.0889)
		(layer "In4.Cu")
		(net "M_D_CPU0_SA_CA<1>")
	)
	(arc
		(start 327.50125 -253.08433)
		(mid 327.774279 -253.147649)
		(end 328.044048 -253.07163)
		(width 0.0889)
		(layer "In4.Cu")
		(net "M_D_CPU0_SA_CA<1>")
	)
	(arc
		(start 334.99806 -253.07163)
		(mid 335.281016 -253.147807)
		(end 335.563972 -253.07163)
		(width 0.0889)
		(layer "In4.Cu")
		(net "M_D_CPU0_SA_CA<1>")
	)
	(arc
		(start 335.563972 -253.07163)
		(mid 335.746223 -253.02128)
		(end 335.929732 -253.066804)
		(width 0.0889)
		(layer "In4.Cu")
		(net "M_D_CPU0_SA_CA<1>")
	)
	(arc
		(start 336.878168 -253.07163)
		(mid 337.161124 -253.147807)
		(end 337.44408 -253.07163)
		(width 0.0889)
		(layer "In4.Cu")
		(net "M_D_CPU0_SA_CA<1>")
	)
	(arc
		(start 335.938114 -253.07163)
		(mid 336.22107 -253.147807)
		(end 336.504026 -253.07163)
		(width 0.0889)
		(layer "In4.Cu")
		(net "M_D_CPU0_SA_CA<1>")
	)
	(arc
		(start 326.539352 -253.07163)
		(mid 326.809509 -253.148392)
		(end 327.083166 -253.085346)
		(width 0.0889)
		(layer "In4.Cu")
		(net "M_D_CPU0_SA_CA<1>")
	)
	(arc
		(start 334.05826 -253.07163)
		(mid 334.341216 -253.147807)
		(end 334.624172 -253.07163)
		(width 0.0889)
		(layer "In4.Cu")
		(net "M_D_CPU0_SA_CA<1>")
	)
	(arc
		(start 332.178152 -253.07163)
		(mid 332.461108 -253.147807)
		(end 332.744064 -253.07163)
		(width 0.0889)
		(layer "In4.Cu")
		(net "M_D_CPU0_SA_CA<1>")
	)
	(arc
		(start 337.818222 -253.07163)
		(mid 338.101178 -253.147807)
		(end 338.384134 -253.07163)
		(width 0.0889)
		(layer "In4.Cu")
		(net "M_D_CPU0_SA_CA<1>")
	)
	(arc
		(start 329.358244 -253.07163)
		(mid 329.6412 -253.147807)
		(end 329.924156 -253.07163)
		(width 0.0889)
		(layer "In4.Cu")
		(net "M_D_CPU0_SA_CA<1>")
	)
	(arc
		(start 328.41819 -253.07163)
		(mid 328.701146 -253.147807)
		(end 328.984102 -253.07163)
		(width 0.0889)
		(layer "In4.Cu")
		(net "M_D_CPU0_SA_CA<1>")
	)
	(arc
		(start 338.384134 -253.07163)
		(mid 338.540453 -253.022635)
		(end 338.70265 -253.045468)
		(width 0.0889)
		(layer "In4.Cu")
		(net "M_D_CPU0_SA_CA<1>")
	)
	(arc
		(start 331.80401 -253.07163)
		(mid 331.986261 -253.02128)
		(end 332.16977 -253.066804)
		(width 0.0889)
		(layer "In4.Cu")
		(net "M_D_CPU0_SA_CA<1>")
	)
	(arc
		(start 328.044048 -253.07163)
		(mid 328.226299 -253.02128)
		(end 328.409808 -253.066804)
		(width 0.0889)
		(layer "In4.Cu")
		(net "M_D_CPU0_SA_CA<1>")
	)
	(arc
		(start 327.106534 -253.07163)
		(mid 327.282654 -253.021652)
		(end 327.461372 -253.06147)
		(width 0.0889)
		(layer "In4.Cu")
		(net "M_D_CPU0_SA_CA<1>")
	)
	(arc
		(start 326.192642 -253.056136)
		(mid 326.367893 -253.021203)
		(end 326.539352 -253.07163)
		(width 0.0889)
		(layer "In4.Cu")
		(net "M_D_CPU0_SA_CA<1>")
	)
	(arc
		(start 329.924156 -253.07163)
		(mid 330.1111 -253.021375)
		(end 330.298044 -253.07163)
		(width 0.0889)
		(layer "In4.Cu")
		(net "M_D_CPU0_SA_CA<1>")
	)
	(arc
		(start 330.863956 -253.07163)
		(mid 331.046207 -253.02128)
		(end 331.229716 -253.066804)
		(width 0.0889)
		(layer "In4.Cu")
		(net "M_D_CPU0_SA_CA<1>")
	)
	(arc
		(start 332.752446 -253.066804)
		(mid 332.935954 -253.02131)
		(end 333.118206 -253.07163)
		(width 0.0889)
		(layer "In4.Cu")
		(net "M_D_CPU0_SA_CA<1>")
	)
	(segment
		(start 339.508084 -252.850142)
		(end 339.040978 -252.584204)
		(width 0.10668)
		(layer "F.Cu")
		(net "M_D_CPU0_SA_CA<0>")
	)
	(segment
		(start 324.489318 -252.467872)
		(end 324.973188 -252.467872)
		(width 0.0889)
		(layer "In4.Cu")
		(net "M_D_CPU0_SA_CA<0>")
	)
	(segment
		(start 297.155616 -250.00331)
		(end 297.385994 -250.00331)
		(width 0.14478)
		(layer "In4.Cu")
		(net "M_D_CPU0_SA_CA<0>")
	)
	(segment
		(start 298.105576 -249.840242)
		(end 298.268644 -250.00331)
		(width 0.14478)
		(layer "In4.Cu")
		(net "M_D_CPU0_SA_CA<0>")
	)
	(segment
		(start 289.88131 -249.610118)
		(end 290.111688 -249.610118)
		(width 0.14478)
		(layer "In4.Cu")
		(net "M_D_CPU0_SA_CA<0>")
	)
	(segment
		(start 298.825158 -249.610118)
		(end 300.85665 -249.610118)
		(width 0.14478)
		(layer "In4.Cu")
		(net "M_D_CPU0_SA_CA<0>")
	)
	(segment
		(start 293.871142 -249.773186)
		(end 293.871142 -249.837702)
		(width 0.14478)
		(layer "In4.Cu")
		(net "M_D_CPU0_SA_CA<0>")
	)
	(segment
		(start 296.992548 -249.773186)
		(end 296.992548 -249.840242)
		(width 0.14478)
		(layer "In4.Cu")
		(net "M_D_CPU0_SA_CA<0>")
	)
	(segment
		(start 301.413164 -250.00331)
		(end 301.576232 -249.840242)
		(width 0.14478)
		(layer "In4.Cu")
		(net "M_D_CPU0_SA_CA<0>")
	)
	(segment
		(start 286.860996 -249.610118)
		(end 288.99866 -249.610118)
		(width 0.14478)
		(layer "In4.Cu")
		(net "M_D_CPU0_SA_CA<0>")
	)
	(segment
		(start 293.871142 -249.837702)
		(end 294.03421 -250.00077)
		(width 0.14478)
		(layer "In4.Cu")
		(net "M_D_CPU0_SA_CA<0>")
	)
	(segment
		(start 326.991726 -252.917706)
		(end 327.010522 -252.906784)
		(width 0.0889)
		(layer "In4.Cu")
		(net "M_D_CPU0_SA_CA<0>")
	)
	(segment
		(start 290.111688 -249.610118)
		(end 290.274756 -249.773186)
		(width 0.14478)
		(layer "In4.Cu")
		(net "M_D_CPU0_SA_CA<0>")
	)
	(segment
		(start 298.499022 -250.00331)
		(end 298.66209 -249.840242)
		(width 0.14478)
		(layer "In4.Cu")
		(net "M_D_CPU0_SA_CA<0>")
	)
	(segment
		(start 326.06996 -252.906784)
		(end 326.06996 -252.90653)
		(width 0.0889)
		(layer "In4.Cu")
		(net "M_D_CPU0_SA_CA<0>")
	)
	(segment
		(start 298.268644 -250.00331)
		(end 298.499022 -250.00331)
		(width 0.14478)
		(layer "In4.Cu")
		(net "M_D_CPU0_SA_CA<0>")
	)
	(segment
		(start 288.99866 -249.610118)
		(end 289.161728 -249.773186)
		(width 0.14478)
		(layer "In4.Cu")
		(net "M_D_CPU0_SA_CA<0>")
	)
	(segment
		(start 326.06996 -252.90653)
		(end 326.069706 -252.90653)
		(width 0.0889)
		(layer "In4.Cu")
		(net "M_D_CPU0_SA_CA<0>")
	)
	(segment
		(start 289.161728 -249.837702)
		(end 289.324796 -250.00077)
		(width 0.14478)
		(layer "In4.Cu")
		(net "M_D_CPU0_SA_CA<0>")
	)
	(segment
		(start 294.264588 -250.00077)
		(end 294.427656 -249.837702)
		(width 0.14478)
		(layer "In4.Cu")
		(net "M_D_CPU0_SA_CA<0>")
	)
	(segment
		(start 301.7393 -249.610118)
		(end 307.979318 -249.610118)
		(width 0.14478)
		(layer "In4.Cu")
		(net "M_D_CPU0_SA_CA<0>")
	)
	(segment
		(start 320.973196 -251.94768)
		(end 321.749166 -252.72365)
		(width 0.14478)
		(layer "In4.Cu")
		(net "M_D_CPU0_SA_CA<0>")
	)
	(segment
		(start 294.03421 -250.00077)
		(end 294.264588 -250.00077)
		(width 0.14478)
		(layer "In4.Cu")
		(net "M_D_CPU0_SA_CA<0>")
	)
	(segment
		(start 307.979318 -249.610118)
		(end 310.31688 -251.94768)
		(width 0.14478)
		(layer "In4.Cu")
		(net "M_D_CPU0_SA_CA<0>")
	)
	(segment
		(start 301.019718 -249.773186)
		(end 301.019718 -249.840242)
		(width 0.14478)
		(layer "In4.Cu")
		(net "M_D_CPU0_SA_CA<0>")
	)
	(segment
		(start 338.791042 -252.875034)
		(end 338.887054 -252.849634)
		(width 0.0889)
		(layer "In4.Cu")
		(net "M_D_CPU0_SA_CA<0>")
	)
	(segment
		(start 289.718242 -249.837702)
		(end 289.718242 -249.773186)
		(width 0.14478)
		(layer "In4.Cu")
		(net "M_D_CPU0_SA_CA<0>")
	)
	(segment
		(start 284.736032 -247.485154)
		(end 286.860996 -249.610118)
		(width 0.14478)
		(layer "In4.Cu")
		(net "M_D_CPU0_SA_CA<0>")
	)
	(segment
		(start 324.23354 -252.72365)
		(end 324.489318 -252.467872)
		(width 0.0889)
		(layer "In4.Cu")
		(net "M_D_CPU0_SA_CA<0>")
	)
	(segment
		(start 296.82948 -249.610118)
		(end 296.992548 -249.773186)
		(width 0.14478)
		(layer "In4.Cu")
		(net "M_D_CPU0_SA_CA<0>")
	)
	(segment
		(start 324.063614 -252.72365)
		(end 324.23354 -252.72365)
		(width 0.0889)
		(layer "In4.Cu")
		(net "M_D_CPU0_SA_CA<0>")
	)
	(segment
		(start 290.994338 -249.610118)
		(end 293.708074 -249.610118)
		(width 0.14478)
		(layer "In4.Cu")
		(net "M_D_CPU0_SA_CA<0>")
	)
	(segment
		(start 331.33411 -252.906784)
		(end 331.342492 -252.91161)
		(width 0.0889)
		(layer "In4.Cu")
		(net "M_D_CPU0_SA_CA<0>")
	)
	(segment
		(start 334.519778 -252.91161)
		(end 334.52816 -252.906784)
		(width 0.0889)
		(layer "In4.Cu")
		(net "M_D_CPU0_SA_CA<0>")
	)
	(segment
		(start 335.094072 -252.906784)
		(end 335.102454 -252.91161)
		(width 0.0889)
		(layer "In4.Cu")
		(net "M_D_CPU0_SA_CA<0>")
	)
	(segment
		(start 326.069706 -252.90653)
		(end 326.101456 -252.888242)
		(width 0.0889)
		(layer "In4.Cu")
		(net "M_D_CPU0_SA_CA<0>")
	)
	(segment
		(start 296.992548 -249.840242)
		(end 297.155616 -250.00331)
		(width 0.14478)
		(layer "In4.Cu")
		(net "M_D_CPU0_SA_CA<0>")
	)
	(segment
		(start 290.437824 -250.00077)
		(end 290.668202 -250.00077)
		(width 0.14478)
		(layer "In4.Cu")
		(net "M_D_CPU0_SA_CA<0>")
	)
	(segment
		(start 289.718242 -249.773186)
		(end 289.88131 -249.610118)
		(width 0.14478)
		(layer "In4.Cu")
		(net "M_D_CPU0_SA_CA<0>")
	)
	(segment
		(start 301.576232 -249.773186)
		(end 301.7393 -249.610118)
		(width 0.14478)
		(layer "In4.Cu")
		(net "M_D_CPU0_SA_CA<0>")
	)
	(segment
		(start 297.942508 -249.610118)
		(end 298.105576 -249.773186)
		(width 0.14478)
		(layer "In4.Cu")
		(net "M_D_CPU0_SA_CA<0>")
	)
	(segment
		(start 325.462138 -252.956822)
		(end 325.883778 -252.956822)
		(width 0.0889)
		(layer "In4.Cu")
		(net "M_D_CPU0_SA_CA<0>")
	)
	(segment
		(start 301.576232 -249.840242)
		(end 301.576232 -249.773186)
		(width 0.14478)
		(layer "In4.Cu")
		(net "M_D_CPU0_SA_CA<0>")
	)
	(segment
		(start 293.708074 -249.610118)
		(end 293.871142 -249.773186)
		(width 0.14478)
		(layer "In4.Cu")
		(net "M_D_CPU0_SA_CA<0>")
	)
	(segment
		(start 336.034126 -252.906784)
		(end 336.042508 -252.91161)
		(width 0.0889)
		(layer "In4.Cu")
		(net "M_D_CPU0_SA_CA<0>")
	)
	(segment
		(start 290.274756 -249.773186)
		(end 290.274756 -249.837702)
		(width 0.14478)
		(layer "In4.Cu")
		(net "M_D_CPU0_SA_CA<0>")
	)
	(segment
		(start 324.973188 -252.467872)
		(end 325.462138 -252.956822)
		(width 0.0889)
		(layer "In4.Cu")
		(net "M_D_CPU0_SA_CA<0>")
	)
	(segment
		(start 297.71213 -249.610118)
		(end 297.942508 -249.610118)
		(width 0.14478)
		(layer "In4.Cu")
		(net "M_D_CPU0_SA_CA<0>")
	)
	(segment
		(start 329.819762 -252.91161)
		(end 329.828144 -252.906784)
		(width 0.0889)
		(layer "In4.Cu")
		(net "M_D_CPU0_SA_CA<0>")
	)
	(segment
		(start 289.555174 -250.00077)
		(end 289.718242 -249.837702)
		(width 0.14478)
		(layer "In4.Cu")
		(net "M_D_CPU0_SA_CA<0>")
	)
	(segment
		(start 301.182786 -250.00331)
		(end 301.413164 -250.00331)
		(width 0.14478)
		(layer "In4.Cu")
		(net "M_D_CPU0_SA_CA<0>")
	)
	(segment
		(start 294.427656 -249.773186)
		(end 294.590724 -249.610118)
		(width 0.14478)
		(layer "In4.Cu")
		(net "M_D_CPU0_SA_CA<0>")
	)
	(segment
		(start 297.385994 -250.00331)
		(end 297.549062 -249.840242)
		(width 0.14478)
		(layer "In4.Cu")
		(net "M_D_CPU0_SA_CA<0>")
	)
	(segment
		(start 300.85665 -249.610118)
		(end 301.019718 -249.773186)
		(width 0.14478)
		(layer "In4.Cu")
		(net "M_D_CPU0_SA_CA<0>")
	)
	(segment
		(start 327.57491 -252.90653)
		(end 327.594976 -252.91796)
		(width 0.0889)
		(layer "In4.Cu")
		(net "M_D_CPU0_SA_CA<0>")
	)
	(segment
		(start 330.394056 -252.906784)
		(end 330.402438 -252.91161)
		(width 0.0889)
		(layer "In4.Cu")
		(net "M_D_CPU0_SA_CA<0>")
	)
	(segment
		(start 338.887054 -252.849634)
		(end 339.040978 -252.584204)
		(width 0.0889)
		(layer "In4.Cu")
		(net "M_D_CPU0_SA_CA<0>")
	)
	(segment
		(start 289.324796 -250.00077)
		(end 289.555174 -250.00077)
		(width 0.14478)
		(layer "In4.Cu")
		(net "M_D_CPU0_SA_CA<0>")
	)
	(segment
		(start 290.274756 -249.837702)
		(end 290.437824 -250.00077)
		(width 0.14478)
		(layer "In4.Cu")
		(net "M_D_CPU0_SA_CA<0>")
	)
	(segment
		(start 297.549062 -249.773186)
		(end 297.71213 -249.610118)
		(width 0.14478)
		(layer "In4.Cu")
		(net "M_D_CPU0_SA_CA<0>")
	)
	(segment
		(start 298.105576 -249.773186)
		(end 298.105576 -249.840242)
		(width 0.14478)
		(layer "In4.Cu")
		(net "M_D_CPU0_SA_CA<0>")
	)
	(segment
		(start 298.66209 -249.840242)
		(end 298.66209 -249.773186)
		(width 0.14478)
		(layer "In4.Cu")
		(net "M_D_CPU0_SA_CA<0>")
	)
	(segment
		(start 338.27974 -252.91161)
		(end 338.288122 -252.906784)
		(width 0.0889)
		(layer "In4.Cu")
		(net "M_D_CPU0_SA_CA<0>")
	)
	(segment
		(start 290.83127 -249.837702)
		(end 290.83127 -249.773186)
		(width 0.14478)
		(layer "In4.Cu")
		(net "M_D_CPU0_SA_CA<0>")
	)
	(segment
		(start 310.31688 -251.94768)
		(end 320.973196 -251.94768)
		(width 0.14478)
		(layer "In4.Cu")
		(net "M_D_CPU0_SA_CA<0>")
	)
	(segment
		(start 289.161728 -249.773186)
		(end 289.161728 -249.837702)
		(width 0.14478)
		(layer "In4.Cu")
		(net "M_D_CPU0_SA_CA<0>")
	)
	(segment
		(start 321.749166 -252.72365)
		(end 324.063614 -252.72365)
		(width 0.14478)
		(layer "In4.Cu")
		(net "M_D_CPU0_SA_CA<0>")
	)
	(segment
		(start 297.549062 -249.840242)
		(end 297.549062 -249.773186)
		(width 0.14478)
		(layer "In4.Cu")
		(net "M_D_CPU0_SA_CA<0>")
	)
	(segment
		(start 290.668202 -250.00077)
		(end 290.83127 -249.837702)
		(width 0.14478)
		(layer "In4.Cu")
		(net "M_D_CPU0_SA_CA<0>")
	)
	(segment
		(start 333.579724 -252.91161)
		(end 333.588106 -252.906784)
		(width 0.0889)
		(layer "In4.Cu")
		(net "M_D_CPU0_SA_CA<0>")
	)
	(segment
		(start 294.590724 -249.610118)
		(end 296.82948 -249.610118)
		(width 0.14478)
		(layer "In4.Cu")
		(net "M_D_CPU0_SA_CA<0>")
	)
	(segment
		(start 294.427656 -249.837702)
		(end 294.427656 -249.773186)
		(width 0.14478)
		(layer "In4.Cu")
		(net "M_D_CPU0_SA_CA<0>")
	)
	(segment
		(start 301.019718 -249.840242)
		(end 301.182786 -250.00331)
		(width 0.14478)
		(layer "In4.Cu")
		(net "M_D_CPU0_SA_CA<0>")
	)
	(segment
		(start 327.55332 -252.894084)
		(end 327.57491 -252.90653)
		(width 0.0889)
		(layer "In4.Cu")
		(net "M_D_CPU0_SA_CA<0>")
	)
	(segment
		(start 290.83127 -249.773186)
		(end 290.994338 -249.610118)
		(width 0.14478)
		(layer "In4.Cu")
		(net "M_D_CPU0_SA_CA<0>")
	)
	(segment
		(start 298.66209 -249.773186)
		(end 298.825158 -249.610118)
		(width 0.14478)
		(layer "In4.Cu")
		(net "M_D_CPU0_SA_CA<0>")
	)
	(arc
		(start 331.708252 -252.906784)
		(mid 331.991208 -252.830607)
		(end 332.274164 -252.906784)
		(width 0.0889)
		(layer "In4.Cu")
		(net "M_D_CPU0_SA_CA<0>")
	)
	(arc
		(start 337.348068 -252.906784)
		(mid 337.631024 -252.830607)
		(end 337.91398 -252.906784)
		(width 0.0889)
		(layer "In4.Cu")
		(net "M_D_CPU0_SA_CA<0>")
	)
	(arc
		(start 327.594976 -252.91796)
		(mid 327.773054 -252.956944)
		(end 327.94829 -252.906784)
		(width 0.0889)
		(layer "In4.Cu")
		(net "M_D_CPU0_SA_CA<0>")
	)
	(arc
		(start 331.342492 -252.91161)
		(mid 331.526 -252.957104)
		(end 331.708252 -252.906784)
		(width 0.0889)
		(layer "In4.Cu")
		(net "M_D_CPU0_SA_CA<0>")
	)
	(arc
		(start 329.454002 -252.906784)
		(mid 329.636253 -252.957134)
		(end 329.819762 -252.91161)
		(width 0.0889)
		(layer "In4.Cu")
		(net "M_D_CPU0_SA_CA<0>")
	)
	(arc
		(start 334.154018 -252.906784)
		(mid 334.336269 -252.957134)
		(end 334.519778 -252.91161)
		(width 0.0889)
		(layer "In4.Cu")
		(net "M_D_CPU0_SA_CA<0>")
	)
	(arc
		(start 327.010522 -252.906784)
		(mid 327.280291 -252.830761)
		(end 327.55332 -252.894084)
		(width 0.0889)
		(layer "In4.Cu")
		(net "M_D_CPU0_SA_CA<0>")
	)
	(arc
		(start 328.514202 -252.906784)
		(mid 328.701146 -252.957039)
		(end 328.88809 -252.906784)
		(width 0.0889)
		(layer "In4.Cu")
		(net "M_D_CPU0_SA_CA<0>")
	)
	(arc
		(start 338.288122 -252.906784)
		(mid 338.535835 -252.831564)
		(end 338.791042 -252.875034)
		(width 0.0889)
		(layer "In4.Cu")
		(net "M_D_CPU0_SA_CA<0>")
	)
	(arc
		(start 326.635364 -252.906784)
		(mid 326.812155 -252.957503)
		(end 326.991726 -252.917706)
		(width 0.0889)
		(layer "In4.Cu")
		(net "M_D_CPU0_SA_CA<0>")
	)
	(arc
		(start 332.274164 -252.906784)
		(mid 332.461108 -252.957039)
		(end 332.648052 -252.906784)
		(width 0.0889)
		(layer "In4.Cu")
		(net "M_D_CPU0_SA_CA<0>")
	)
	(arc
		(start 329.828144 -252.906784)
		(mid 330.1111 -252.830607)
		(end 330.394056 -252.906784)
		(width 0.0889)
		(layer "In4.Cu")
		(net "M_D_CPU0_SA_CA<0>")
	)
	(arc
		(start 333.213964 -252.906784)
		(mid 333.396215 -252.957134)
		(end 333.579724 -252.91161)
		(width 0.0889)
		(layer "In4.Cu")
		(net "M_D_CPU0_SA_CA<0>")
	)
	(arc
		(start 332.648052 -252.906784)
		(mid 332.931008 -252.830607)
		(end 333.213964 -252.906784)
		(width 0.0889)
		(layer "In4.Cu")
		(net "M_D_CPU0_SA_CA<0>")
	)
	(arc
		(start 330.768198 -252.906784)
		(mid 331.051154 -252.830607)
		(end 331.33411 -252.906784)
		(width 0.0889)
		(layer "In4.Cu")
		(net "M_D_CPU0_SA_CA<0>")
	)
	(arc
		(start 336.97418 -252.906784)
		(mid 337.161124 -252.957039)
		(end 337.348068 -252.906784)
		(width 0.0889)
		(layer "In4.Cu")
		(net "M_D_CPU0_SA_CA<0>")
	)
	(arc
		(start 333.588106 -252.906784)
		(mid 333.871062 -252.830607)
		(end 334.154018 -252.906784)
		(width 0.0889)
		(layer "In4.Cu")
		(net "M_D_CPU0_SA_CA<0>")
	)
	(arc
		(start 335.102454 -252.91161)
		(mid 335.285962 -252.957104)
		(end 335.468214 -252.906784)
		(width 0.0889)
		(layer "In4.Cu")
		(net "M_D_CPU0_SA_CA<0>")
	)
	(arc
		(start 336.408268 -252.906784)
		(mid 336.691224 -252.830607)
		(end 336.97418 -252.906784)
		(width 0.0889)
		(layer "In4.Cu")
		(net "M_D_CPU0_SA_CA<0>")
	)
	(arc
		(start 327.94829 -252.906784)
		(mid 328.231246 -252.830607)
		(end 328.514202 -252.906784)
		(width 0.0889)
		(layer "In4.Cu")
		(net "M_D_CPU0_SA_CA<0>")
	)
	(arc
		(start 325.883778 -252.956822)
		(mid 325.980169 -252.944071)
		(end 326.06996 -252.906784)
		(width 0.0889)
		(layer "In4.Cu")
		(net "M_D_CPU0_SA_CA<0>")
	)
	(arc
		(start 337.91398 -252.906784)
		(mid 338.096231 -252.957134)
		(end 338.27974 -252.91161)
		(width 0.0889)
		(layer "In4.Cu")
		(net "M_D_CPU0_SA_CA<0>")
	)
	(arc
		(start 335.468214 -252.906784)
		(mid 335.75117 -252.830607)
		(end 336.034126 -252.906784)
		(width 0.0889)
		(layer "In4.Cu")
		(net "M_D_CPU0_SA_CA<0>")
	)
	(arc
		(start 326.101456 -252.888242)
		(mid 326.370741 -252.83033)
		(end 326.635364 -252.906784)
		(width 0.0889)
		(layer "In4.Cu")
		(net "M_D_CPU0_SA_CA<0>")
	)
	(arc
		(start 334.52816 -252.906784)
		(mid 334.811116 -252.830607)
		(end 335.094072 -252.906784)
		(width 0.0889)
		(layer "In4.Cu")
		(net "M_D_CPU0_SA_CA<0>")
	)
	(arc
		(start 328.88809 -252.906784)
		(mid 329.171046 -252.830607)
		(end 329.454002 -252.906784)
		(width 0.0889)
		(layer "In4.Cu")
		(net "M_D_CPU0_SA_CA<0>")
	)
	(arc
		(start 330.402438 -252.91161)
		(mid 330.585946 -252.957104)
		(end 330.768198 -252.906784)
		(width 0.0889)
		(layer "In4.Cu")
		(net "M_D_CPU0_SA_CA<0>")
	)
	(arc
		(start 336.042508 -252.91161)
		(mid 336.226016 -252.957104)
		(end 336.408268 -252.906784)
		(width 0.0889)
		(layer "In4.Cu")
		(net "M_D_CPU0_SA_CA<0>")
	)
	(segment
		(start 340.447884 -251.23013)
		(end 339.981032 -250.964192)
		(width 0.10668)
		(layer "F.Cu")
		(net "M_D_CPU0_RESET_N")
	)
	(segment
		(start 324.316598 -250.771152)
		(end 326.451468 -250.771152)
		(width 0.0889)
		(layer "In4.Cu")
		(net "M_D_CPU0_RESET_N")
	)
	(segment
		(start 340.13521 -250.698762)
		(end 339.981032 -250.964192)
		(width 0.0889)
		(layer "In4.Cu")
		(net "M_D_CPU0_RESET_N")
	)
	(segment
		(start 329.819762 -250.636786)
		(end 329.828144 -250.641612)
		(width 0.0889)
		(layer "In4.Cu")
		(net "M_D_CPU0_RESET_N")
	)
	(segment
		(start 336.034126 -250.641612)
		(end 336.042508 -250.636786)
		(width 0.0889)
		(layer "In4.Cu")
		(net "M_D_CPU0_RESET_N")
	)
	(segment
		(start 334.519778 -250.636786)
		(end 334.52816 -250.641612)
		(width 0.0889)
		(layer "In4.Cu")
		(net "M_D_CPU0_RESET_N")
	)
	(segment
		(start 324.25386 -250.83389)
		(end 324.316598 -250.771152)
		(width 0.0889)
		(layer "In4.Cu")
		(net "M_D_CPU0_RESET_N")
	)
	(segment
		(start 339.794088 -250.641612)
		(end 339.80247 -250.636786)
		(width 0.0889)
		(layer "In4.Cu")
		(net "M_D_CPU0_RESET_N")
	)
	(segment
		(start 322.20027 -250.83389)
		(end 323.954394 -250.83389)
		(width 0.11684)
		(layer "In4.Cu")
		(net "M_D_CPU0_RESET_N")
	)
	(segment
		(start 331.33411 -250.641612)
		(end 331.342492 -250.636786)
		(width 0.0889)
		(layer "In4.Cu")
		(net "M_D_CPU0_RESET_N")
	)
	(segment
		(start 281.060906 -245.359936)
		(end 285.620206 -245.359936)
		(width 0.11684)
		(layer "In4.Cu")
		(net "M_D_CPU0_RESET_N")
	)
	(segment
		(start 338.27974 -250.636786)
		(end 338.288122 -250.641612)
		(width 0.0889)
		(layer "In4.Cu")
		(net "M_D_CPU0_RESET_N")
	)
	(segment
		(start 339.219794 -250.636786)
		(end 339.228176 -250.641612)
		(width 0.0889)
		(layer "In4.Cu")
		(net "M_D_CPU0_RESET_N")
	)
	(segment
		(start 285.620206 -245.359936)
		(end 287.320228 -247.059958)
		(width 0.11684)
		(layer "In4.Cu")
		(net "M_D_CPU0_RESET_N")
	)
	(segment
		(start 333.579724 -250.636786)
		(end 333.588106 -250.641612)
		(width 0.0889)
		(layer "In4.Cu")
		(net "M_D_CPU0_RESET_N")
	)
	(segment
		(start 326.531732 -250.737878)
		(end 326.595232 -250.674378)
		(width 0.0889)
		(layer "In4.Cu")
		(net "M_D_CPU0_RESET_N")
	)
	(segment
		(start 340.112858 -250.61545)
		(end 340.13521 -250.698762)
		(width 0.0889)
		(layer "In4.Cu")
		(net "M_D_CPU0_RESET_N")
	)
	(segment
		(start 330.394056 -250.641612)
		(end 330.402438 -250.636786)
		(width 0.0889)
		(layer "In4.Cu")
		(net "M_D_CPU0_RESET_N")
	)
	(segment
		(start 335.094072 -250.641612)
		(end 335.102454 -250.636786)
		(width 0.0889)
		(layer "In4.Cu")
		(net "M_D_CPU0_RESET_N")
	)
	(segment
		(start 280.635964 -244.934994)
		(end 281.060906 -245.359936)
		(width 0.11684)
		(layer "In4.Cu")
		(net "M_D_CPU0_RESET_N")
	)
	(segment
		(start 307.830474 -247.059958)
		(end 311.078626 -250.30811)
		(width 0.11684)
		(layer "In4.Cu")
		(net "M_D_CPU0_RESET_N")
	)
	(segment
		(start 321.67449 -250.30811)
		(end 322.20027 -250.83389)
		(width 0.11684)
		(layer "In4.Cu")
		(net "M_D_CPU0_RESET_N")
	)
	(segment
		(start 323.954394 -250.83389)
		(end 324.25386 -250.83389)
		(width 0.0889)
		(layer "In4.Cu")
		(net "M_D_CPU0_RESET_N")
	)
	(segment
		(start 311.078626 -250.30811)
		(end 321.67449 -250.30811)
		(width 0.11684)
		(layer "In4.Cu")
		(net "M_D_CPU0_RESET_N")
	)
	(segment
		(start 287.320228 -247.059958)
		(end 307.830474 -247.059958)
		(width 0.11684)
		(layer "In4.Cu")
		(net "M_D_CPU0_RESET_N")
	)
	(segment
		(start 327.574148 -250.641612)
		(end 327.58253 -250.636786)
		(width 0.0889)
		(layer "In4.Cu")
		(net "M_D_CPU0_RESET_N")
	)
	(arc
		(start 338.854034 -250.641612)
		(mid 339.036285 -250.591262)
		(end 339.219794 -250.636786)
		(width 0.0889)
		(layer "In4.Cu")
		(net "M_D_CPU0_RESET_N")
	)
	(arc
		(start 336.408268 -250.641612)
		(mid 336.691224 -250.717789)
		(end 336.97418 -250.641612)
		(width 0.0889)
		(layer "In4.Cu")
		(net "M_D_CPU0_RESET_N")
	)
	(arc
		(start 326.668384 -250.623832)
		(mid 326.840465 -250.591673)
		(end 327.008236 -250.641612)
		(width 0.0889)
		(layer "In4.Cu")
		(net "M_D_CPU0_RESET_N")
	)
	(arc
		(start 329.454002 -250.641612)
		(mid 329.636253 -250.591262)
		(end 329.819762 -250.636786)
		(width 0.0889)
		(layer "In4.Cu")
		(net "M_D_CPU0_RESET_N")
	)
	(arc
		(start 326.595232 -250.674378)
		(mid 326.629496 -250.645758)
		(end 326.668384 -250.623832)
		(width 0.0889)
		(layer "In4.Cu")
		(net "M_D_CPU0_RESET_N")
	)
	(arc
		(start 335.102454 -250.636786)
		(mid 335.285962 -250.591292)
		(end 335.468214 -250.641612)
		(width 0.0889)
		(layer "In4.Cu")
		(net "M_D_CPU0_RESET_N")
	)
	(arc
		(start 331.708252 -250.641612)
		(mid 331.991208 -250.717789)
		(end 332.274164 -250.641612)
		(width 0.0889)
		(layer "In4.Cu")
		(net "M_D_CPU0_RESET_N")
	)
	(arc
		(start 329.828144 -250.641612)
		(mid 330.1111 -250.717789)
		(end 330.394056 -250.641612)
		(width 0.0889)
		(layer "In4.Cu")
		(net "M_D_CPU0_RESET_N")
	)
	(arc
		(start 335.468214 -250.641612)
		(mid 335.75117 -250.717789)
		(end 336.034126 -250.641612)
		(width 0.0889)
		(layer "In4.Cu")
		(net "M_D_CPU0_RESET_N")
	)
	(arc
		(start 328.514202 -250.641612)
		(mid 328.701146 -250.591357)
		(end 328.88809 -250.641612)
		(width 0.0889)
		(layer "In4.Cu")
		(net "M_D_CPU0_RESET_N")
	)
	(arc
		(start 332.648052 -250.641612)
		(mid 332.931008 -250.717789)
		(end 333.213964 -250.641612)
		(width 0.0889)
		(layer "In4.Cu")
		(net "M_D_CPU0_RESET_N")
	)
	(arc
		(start 339.228176 -250.641612)
		(mid 339.511132 -250.717789)
		(end 339.794088 -250.641612)
		(width 0.0889)
		(layer "In4.Cu")
		(net "M_D_CPU0_RESET_N")
	)
	(arc
		(start 336.042508 -250.636786)
		(mid 336.226016 -250.591292)
		(end 336.408268 -250.641612)
		(width 0.0889)
		(layer "In4.Cu")
		(net "M_D_CPU0_RESET_N")
	)
	(arc
		(start 333.213964 -250.641612)
		(mid 333.396215 -250.591262)
		(end 333.579724 -250.636786)
		(width 0.0889)
		(layer "In4.Cu")
		(net "M_D_CPU0_RESET_N")
	)
	(arc
		(start 332.274164 -250.641612)
		(mid 332.461108 -250.591357)
		(end 332.648052 -250.641612)
		(width 0.0889)
		(layer "In4.Cu")
		(net "M_D_CPU0_RESET_N")
	)
	(arc
		(start 330.768198 -250.641612)
		(mid 331.051154 -250.717789)
		(end 331.33411 -250.641612)
		(width 0.0889)
		(layer "In4.Cu")
		(net "M_D_CPU0_RESET_N")
	)
	(arc
		(start 328.88809 -250.641612)
		(mid 329.171046 -250.717789)
		(end 329.454002 -250.641612)
		(width 0.0889)
		(layer "In4.Cu")
		(net "M_D_CPU0_RESET_N")
	)
	(arc
		(start 327.94829 -250.641612)
		(mid 328.231246 -250.717789)
		(end 328.514202 -250.641612)
		(width 0.0889)
		(layer "In4.Cu")
		(net "M_D_CPU0_RESET_N")
	)
	(arc
		(start 334.52816 -250.641612)
		(mid 334.811116 -250.717789)
		(end 335.094072 -250.641612)
		(width 0.0889)
		(layer "In4.Cu")
		(net "M_D_CPU0_RESET_N")
	)
	(arc
		(start 337.348068 -250.641612)
		(mid 337.631024 -250.717789)
		(end 337.91398 -250.641612)
		(width 0.0889)
		(layer "In4.Cu")
		(net "M_D_CPU0_RESET_N")
	)
	(arc
		(start 339.80247 -250.636786)
		(mid 339.95534 -250.592145)
		(end 340.112858 -250.61545)
		(width 0.0889)
		(layer "In4.Cu")
		(net "M_D_CPU0_RESET_N")
	)
	(arc
		(start 327.58253 -250.636786)
		(mid 327.766038 -250.591292)
		(end 327.94829 -250.641612)
		(width 0.0889)
		(layer "In4.Cu")
		(net "M_D_CPU0_RESET_N")
	)
	(arc
		(start 326.451468 -250.771152)
		(mid 326.494903 -250.762494)
		(end 326.531732 -250.737878)
		(width 0.0889)
		(layer "In4.Cu")
		(net "M_D_CPU0_RESET_N")
	)
	(arc
		(start 331.342492 -250.636786)
		(mid 331.526 -250.591292)
		(end 331.708252 -250.641612)
		(width 0.0889)
		(layer "In4.Cu")
		(net "M_D_CPU0_RESET_N")
	)
	(arc
		(start 333.588106 -250.641612)
		(mid 333.871062 -250.717789)
		(end 334.154018 -250.641612)
		(width 0.0889)
		(layer "In4.Cu")
		(net "M_D_CPU0_RESET_N")
	)
	(arc
		(start 327.008236 -250.641612)
		(mid 327.291192 -250.717789)
		(end 327.574148 -250.641612)
		(width 0.0889)
		(layer "In4.Cu")
		(net "M_D_CPU0_RESET_N")
	)
	(arc
		(start 330.402438 -250.636786)
		(mid 330.585946 -250.591292)
		(end 330.768198 -250.641612)
		(width 0.0889)
		(layer "In4.Cu")
		(net "M_D_CPU0_RESET_N")
	)
	(arc
		(start 337.91398 -250.641612)
		(mid 338.096231 -250.591262)
		(end 338.27974 -250.636786)
		(width 0.0889)
		(layer "In4.Cu")
		(net "M_D_CPU0_RESET_N")
	)
	(arc
		(start 338.288122 -250.641612)
		(mid 338.571078 -250.717789)
		(end 338.854034 -250.641612)
		(width 0.0889)
		(layer "In4.Cu")
		(net "M_D_CPU0_RESET_N")
	)
	(arc
		(start 336.97418 -250.641612)
		(mid 337.161124 -250.591357)
		(end 337.348068 -250.641612)
		(width 0.0889)
		(layer "In4.Cu")
		(net "M_D_CPU0_RESET_N")
	)
	(arc
		(start 334.154018 -250.641612)
		(mid 334.336269 -250.591262)
		(end 334.519778 -250.636786)
		(width 0.0889)
		(layer "In4.Cu")
		(net "M_D_CPU0_RESET_N")
	)
	(segment
		(start 339.508084 -256.090166)
		(end 339.040978 -255.824228)
		(width 0.14732)
		(layer "F.Cu")
		(net "M_D_CPU0_CLK_DP<0>")
	)
	(segment
		(start 313.337194 -256.43205)
		(end 284.520894 -256.43205)
		(width 0.16002)
		(layer "In4.Cu")
		(net "M_D_CPU0_CLK_DP<0>")
	)
	(segment
		(start 281.79776 -253.708916)
		(end 280.909776 -253.708916)
		(width 0.16002)
		(layer "In4.Cu")
		(net "M_D_CPU0_CLK_DP<0>")
	)
	(segment
		(start 324.843648 -257.349752)
		(end 324.225158 -257.349752)
		(width 0.09525)
		(layer "In4.Cu")
		(net "M_D_CPU0_CLK_DP<0>")
	)
	(segment
		(start 324.165976 -257.29057)
		(end 324.142354 -257.29057)
		(width 0.09525)
		(layer "In4.Cu")
		(net "M_D_CPU0_CLK_DP<0>")
	)
	(segment
		(start 324.225158 -257.349752)
		(end 324.165976 -257.29057)
		(width 0.09525)
		(layer "In4.Cu")
		(net "M_D_CPU0_CLK_DP<0>")
	)
	(segment
		(start 319.243456 -255.820164)
		(end 313.94908 -255.820164)
		(width 0.16002)
		(layer "In4.Cu")
		(net "M_D_CPU0_CLK_DP<0>")
	)
	(segment
		(start 335.10093 -256.154174)
		(end 335.092548 -256.149348)
		(width 0.09525)
		(layer "In4.Cu")
		(net "M_D_CPU0_CLK_DP<0>")
	)
	(segment
		(start 331.340968 -256.154174)
		(end 331.332586 -256.149348)
		(width 0.09525)
		(layer "In4.Cu")
		(net "M_D_CPU0_CLK_DP<0>")
	)
	(segment
		(start 326.105774 -256.129282)
		(end 326.07123 -256.149348)
		(width 0.09525)
		(layer "In4.Cu")
		(net "M_D_CPU0_CLK_DP<0>")
	)
	(segment
		(start 324.142354 -257.29057)
		(end 320.713862 -257.29057)
		(width 0.16002)
		(layer "In4.Cu")
		(net "M_D_CPU0_CLK_DP<0>")
	)
	(segment
		(start 313.94908 -255.820164)
		(end 313.337194 -256.43205)
		(width 0.16002)
		(layer "In4.Cu")
		(net "M_D_CPU0_CLK_DP<0>")
	)
	(segment
		(start 327.036684 -256.134616)
		(end 327.011284 -256.149348)
		(width 0.09525)
		(layer "In4.Cu")
		(net "M_D_CPU0_CLK_DP<0>")
	)
	(segment
		(start 339.040978 -255.824228)
		(end 338.887054 -256.089658)
		(width 0.09525)
		(layer "In4.Cu")
		(net "M_D_CPU0_CLK_DP<0>")
	)
	(segment
		(start 336.040984 -256.154174)
		(end 336.032602 -256.149348)
		(width 0.09525)
		(layer "In4.Cu")
		(net "M_D_CPU0_CLK_DP<0>")
	)
	(segment
		(start 320.713862 -257.29057)
		(end 319.243456 -255.820164)
		(width 0.16002)
		(layer "In4.Cu")
		(net "M_D_CPU0_CLK_DP<0>")
	)
	(segment
		(start 280.909776 -253.708916)
		(end 280.635964 -253.435104)
		(width 0.16002)
		(layer "In4.Cu")
		(net "M_D_CPU0_CLK_DP<0>")
	)
	(segment
		(start 338.887054 -256.089658)
		(end 338.786216 -256.116328)
		(width 0.09525)
		(layer "In4.Cu")
		(net "M_D_CPU0_CLK_DP<0>")
	)
	(segment
		(start 329.829668 -256.149348)
		(end 329.821286 -256.154174)
		(width 0.09525)
		(layer "In4.Cu")
		(net "M_D_CPU0_CLK_DP<0>")
	)
	(segment
		(start 327.581006 -256.154174)
		(end 327.572624 -256.149348)
		(width 0.09525)
		(layer "In4.Cu")
		(net "M_D_CPU0_CLK_DP<0>")
	)
	(segment
		(start 325.955406 -256.237994)
		(end 324.843648 -257.349752)
		(width 0.09525)
		(layer "In4.Cu")
		(net "M_D_CPU0_CLK_DP<0>")
	)
	(segment
		(start 333.58963 -256.149348)
		(end 333.581248 -256.154174)
		(width 0.09525)
		(layer "In4.Cu")
		(net "M_D_CPU0_CLK_DP<0>")
	)
	(segment
		(start 327.011284 -256.149348)
		(end 326.987408 -256.163064)
		(width 0.09525)
		(layer "In4.Cu")
		(net "M_D_CPU0_CLK_DP<0>")
	)
	(segment
		(start 330.400914 -256.154174)
		(end 330.392532 -256.149348)
		(width 0.09525)
		(layer "In4.Cu")
		(net "M_D_CPU0_CLK_DP<0>")
	)
	(segment
		(start 338.289646 -256.149348)
		(end 338.281264 -256.154174)
		(width 0.09525)
		(layer "In4.Cu")
		(net "M_D_CPU0_CLK_DP<0>")
	)
	(segment
		(start 334.529684 -256.149348)
		(end 334.521302 -256.154174)
		(width 0.09525)
		(layer "In4.Cu")
		(net "M_D_CPU0_CLK_DP<0>")
	)
	(segment
		(start 284.520894 -256.43205)
		(end 281.79776 -253.708916)
		(width 0.16002)
		(layer "In4.Cu")
		(net "M_D_CPU0_CLK_DP<0>")
	)
	(arc
		(start 329.821286 -256.154174)
		(mid 329.636254 -256.200088)
		(end 329.452478 -256.149348)
		(width 0.09525)
		(layer "In4.Cu")
		(net "M_D_CPU0_CLK_DP<0>")
	)
	(arc
		(start 333.21244 -256.149348)
		(mid 332.931008 -256.073593)
		(end 332.649576 -256.149348)
		(width 0.09525)
		(layer "In4.Cu")
		(net "M_D_CPU0_CLK_DP<0>")
	)
	(arc
		(start 335.469738 -256.149348)
		(mid 335.285963 -256.20012)
		(end 335.10093 -256.154174)
		(width 0.09525)
		(layer "In4.Cu")
		(net "M_D_CPU0_CLK_DP<0>")
	)
	(arc
		(start 336.409792 -256.149348)
		(mid 336.226017 -256.20012)
		(end 336.040984 -256.154174)
		(width 0.09525)
		(layer "In4.Cu")
		(net "M_D_CPU0_CLK_DP<0>")
	)
	(arc
		(start 332.649576 -256.149348)
		(mid 332.461108 -256.200025)
		(end 332.27264 -256.149348)
		(width 0.09525)
		(layer "In4.Cu")
		(net "M_D_CPU0_CLK_DP<0>")
	)
	(arc
		(start 330.392532 -256.149348)
		(mid 330.1111 -256.073593)
		(end 329.829668 -256.149348)
		(width 0.09525)
		(layer "In4.Cu")
		(net "M_D_CPU0_CLK_DP<0>")
	)
	(arc
		(start 327.572624 -256.149348)
		(mid 327.306537 -256.073803)
		(end 327.036684 -256.134616)
		(width 0.09525)
		(layer "In4.Cu")
		(net "M_D_CPU0_CLK_DP<0>")
	)
	(arc
		(start 326.63384 -256.149348)
		(mid 326.372304 -256.073235)
		(end 326.105774 -256.129282)
		(width 0.09525)
		(layer "In4.Cu")
		(net "M_D_CPU0_CLK_DP<0>")
	)
	(arc
		(start 332.27264 -256.149348)
		(mid 331.991208 -256.073593)
		(end 331.709776 -256.149348)
		(width 0.09525)
		(layer "In4.Cu")
		(net "M_D_CPU0_CLK_DP<0>")
	)
	(arc
		(start 329.452478 -256.149348)
		(mid 329.171046 -256.073593)
		(end 328.889614 -256.149348)
		(width 0.09525)
		(layer "In4.Cu")
		(net "M_D_CPU0_CLK_DP<0>")
	)
	(arc
		(start 331.332586 -256.149348)
		(mid 331.051154 -256.073593)
		(end 330.769722 -256.149348)
		(width 0.09525)
		(layer "In4.Cu")
		(net "M_D_CPU0_CLK_DP<0>")
	)
	(arc
		(start 325.981568 -256.21361)
		(mid 325.968292 -256.225593)
		(end 325.955406 -256.237994)
		(width 0.09525)
		(layer "In4.Cu")
		(net "M_D_CPU0_CLK_DP<0>")
	)
	(arc
		(start 338.281264 -256.154174)
		(mid 338.096232 -256.200088)
		(end 337.912456 -256.149348)
		(width 0.09525)
		(layer "In4.Cu")
		(net "M_D_CPU0_CLK_DP<0>")
	)
	(arc
		(start 333.581248 -256.154174)
		(mid 333.396216 -256.200088)
		(end 333.21244 -256.149348)
		(width 0.09525)
		(layer "In4.Cu")
		(net "M_D_CPU0_CLK_DP<0>")
	)
	(arc
		(start 336.032602 -256.149348)
		(mid 335.75117 -256.073593)
		(end 335.469738 -256.149348)
		(width 0.09525)
		(layer "In4.Cu")
		(net "M_D_CPU0_CLK_DP<0>")
	)
	(arc
		(start 338.786216 -256.116328)
		(mid 338.534075 -256.074758)
		(end 338.289646 -256.149348)
		(width 0.09525)
		(layer "In4.Cu")
		(net "M_D_CPU0_CLK_DP<0>")
	)
	(arc
		(start 326.987408 -256.163064)
		(mid 326.808922 -256.200307)
		(end 326.63384 -256.149348)
		(width 0.09525)
		(layer "In4.Cu")
		(net "M_D_CPU0_CLK_DP<0>")
	)
	(arc
		(start 327.949814 -256.149348)
		(mid 327.766039 -256.20012)
		(end 327.581006 -256.154174)
		(width 0.09525)
		(layer "In4.Cu")
		(net "M_D_CPU0_CLK_DP<0>")
	)
	(arc
		(start 328.512678 -256.149348)
		(mid 328.231246 -256.073593)
		(end 327.949814 -256.149348)
		(width 0.09525)
		(layer "In4.Cu")
		(net "M_D_CPU0_CLK_DP<0>")
	)
	(arc
		(start 331.709776 -256.149348)
		(mid 331.526001 -256.20012)
		(end 331.340968 -256.154174)
		(width 0.09525)
		(layer "In4.Cu")
		(net "M_D_CPU0_CLK_DP<0>")
	)
	(arc
		(start 335.092548 -256.149348)
		(mid 334.811116 -256.073593)
		(end 334.529684 -256.149348)
		(width 0.09525)
		(layer "In4.Cu")
		(net "M_D_CPU0_CLK_DP<0>")
	)
	(arc
		(start 330.769722 -256.149348)
		(mid 330.585947 -256.20012)
		(end 330.400914 -256.154174)
		(width 0.09525)
		(layer "In4.Cu")
		(net "M_D_CPU0_CLK_DP<0>")
	)
	(arc
		(start 334.152494 -256.149348)
		(mid 333.871062 -256.073593)
		(end 333.58963 -256.149348)
		(width 0.09525)
		(layer "In4.Cu")
		(net "M_D_CPU0_CLK_DP<0>")
	)
	(arc
		(start 326.07123 -256.149348)
		(mid 326.024812 -256.179264)
		(end 325.981568 -256.21361)
		(width 0.09525)
		(layer "In4.Cu")
		(net "M_D_CPU0_CLK_DP<0>")
	)
	(arc
		(start 334.521302 -256.154174)
		(mid 334.33627 -256.200088)
		(end 334.152494 -256.149348)
		(width 0.09525)
		(layer "In4.Cu")
		(net "M_D_CPU0_CLK_DP<0>")
	)
	(arc
		(start 337.912456 -256.149348)
		(mid 337.631024 -256.073593)
		(end 337.349592 -256.149348)
		(width 0.09525)
		(layer "In4.Cu")
		(net "M_D_CPU0_CLK_DP<0>")
	)
	(arc
		(start 328.889614 -256.149348)
		(mid 328.701146 -256.200025)
		(end 328.512678 -256.149348)
		(width 0.09525)
		(layer "In4.Cu")
		(net "M_D_CPU0_CLK_DP<0>")
	)
	(arc
		(start 336.972656 -256.149348)
		(mid 336.691224 -256.073593)
		(end 336.409792 -256.149348)
		(width 0.09525)
		(layer "In4.Cu")
		(net "M_D_CPU0_CLK_DP<0>")
	)
	(arc
		(start 337.349592 -256.149348)
		(mid 337.161124 -256.200025)
		(end 336.972656 -256.149348)
		(width 0.09525)
		(layer "In4.Cu")
		(net "M_D_CPU0_CLK_DP<0>")
	)
	(segment
		(start 339.03793 -256.900172)
		(end 338.571078 -256.634234)
		(width 0.14732)
		(layer "F.Cu")
		(net "M_D_CPU0_CLK_DN<0>")
	)
	(segment
		(start 328.99096 -256.304288)
		(end 328.982578 -256.309114)
		(width 0.09525)
		(layer "In4.Cu")
		(net "M_D_CPU0_CLK_DN<0>")
	)
	(segment
		(start 333.690976 -256.304288)
		(end 333.682594 -256.309114)
		(width 0.09525)
		(layer "In4.Cu")
		(net "M_D_CPU0_CLK_DN<0>")
	)
	(segment
		(start 319.118234 -256.122424)
		(end 314.074302 -256.122424)
		(width 0.16002)
		(layer "In4.Cu")
		(net "M_D_CPU0_CLK_DN<0>")
	)
	(segment
		(start 314.074302 -256.122424)
		(end 313.462416 -256.73431)
		(width 0.16002)
		(layer "In4.Cu")
		(net "M_D_CPU0_CLK_DN<0>")
	)
	(segment
		(start 332.750922 -256.304288)
		(end 332.74254 -256.309114)
		(width 0.09525)
		(layer "In4.Cu")
		(net "M_D_CPU0_CLK_DN<0>")
	)
	(segment
		(start 324.920102 -257.533902)
		(end 324.224904 -257.533902)
		(width 0.09525)
		(layer "In4.Cu")
		(net "M_D_CPU0_CLK_DN<0>")
	)
	(segment
		(start 282.680918 -255.18491)
		(end 282.34132 -254.845312)
		(width 0.16002)
		(layer "In4.Cu")
		(net "M_D_CPU0_CLK_DN<0>")
	)
	(segment
		(start 328.419714 -256.309114)
		(end 328.411332 -256.304288)
		(width 0.09525)
		(layer "In4.Cu")
		(net "M_D_CPU0_CLK_DN<0>")
	)
	(segment
		(start 324.142354 -257.59283)
		(end 320.58864 -257.59283)
		(width 0.16002)
		(layer "In4.Cu")
		(net "M_D_CPU0_CLK_DN<0>")
	)
	(segment
		(start 313.462416 -256.73431)
		(end 284.395672 -256.73431)
		(width 0.16002)
		(layer "In4.Cu")
		(net "M_D_CPU0_CLK_DN<0>")
	)
	(segment
		(start 284.395672 -256.73431)
		(end 282.846272 -255.18491)
		(width 0.16002)
		(layer "In4.Cu")
		(net "M_D_CPU0_CLK_DN<0>")
	)
	(segment
		(start 324.224904 -257.533902)
		(end 324.165976 -257.59283)
		(width 0.09525)
		(layer "In4.Cu")
		(net "M_D_CPU0_CLK_DN<0>")
	)
	(segment
		(start 338.725002 -256.368804)
		(end 338.701888 -256.28219)
		(width 0.09525)
		(layer "In4.Cu")
		(net "M_D_CPU0_CLK_DN<0>")
	)
	(segment
		(start 282.846272 -255.18491)
		(end 282.680918 -255.18491)
		(width 0.16002)
		(layer "In4.Cu")
		(net "M_D_CPU0_CLK_DN<0>")
	)
	(segment
		(start 331.239622 -256.309114)
		(end 331.23124 -256.304288)
		(width 0.09525)
		(layer "In4.Cu")
		(net "M_D_CPU0_CLK_DN<0>")
	)
	(segment
		(start 326.189086 -256.294636)
		(end 326.163686 -256.309114)
		(width 0.09525)
		(layer "In4.Cu")
		(net "M_D_CPU0_CLK_DN<0>")
	)
	(segment
		(start 327.117964 -256.300732)
		(end 327.103486 -256.309114)
		(width 0.09525)
		(layer "In4.Cu")
		(net "M_D_CPU0_CLK_DN<0>")
	)
	(segment
		(start 326.085454 -256.36855)
		(end 324.920102 -257.533902)
		(width 0.09525)
		(layer "In4.Cu")
		(net "M_D_CPU0_CLK_DN<0>")
	)
	(segment
		(start 281.672538 -254.011176)
		(end 280.909776 -254.011176)
		(width 0.16002)
		(layer "In4.Cu")
		(net "M_D_CPU0_CLK_DN<0>")
	)
	(segment
		(start 338.571078 -256.634234)
		(end 338.725002 -256.368804)
		(width 0.09525)
		(layer "In4.Cu")
		(net "M_D_CPU0_CLK_DN<0>")
	)
	(segment
		(start 324.165976 -257.59283)
		(end 324.142354 -257.59283)
		(width 0.09525)
		(layer "In4.Cu")
		(net "M_D_CPU0_CLK_DN<0>")
	)
	(segment
		(start 337.450938 -256.304288)
		(end 337.442556 -256.309114)
		(width 0.09525)
		(layer "In4.Cu")
		(net "M_D_CPU0_CLK_DN<0>")
	)
	(segment
		(start 332.179676 -256.309114)
		(end 332.171294 -256.304288)
		(width 0.09525)
		(layer "In4.Cu")
		(net "M_D_CPU0_CLK_DN<0>")
	)
	(segment
		(start 320.58864 -257.59283)
		(end 319.118234 -256.122424)
		(width 0.16002)
		(layer "In4.Cu")
		(net "M_D_CPU0_CLK_DN<0>")
	)
	(segment
		(start 280.909776 -254.011176)
		(end 280.635964 -254.284988)
		(width 0.16002)
		(layer "In4.Cu")
		(net "M_D_CPU0_CLK_DN<0>")
	)
	(segment
		(start 335.939638 -256.309114)
		(end 335.931256 -256.304288)
		(width 0.09525)
		(layer "In4.Cu")
		(net "M_D_CPU0_CLK_DN<0>")
	)
	(segment
		(start 282.34132 -254.845312)
		(end 282.34132 -254.679958)
		(width 0.16002)
		(layer "In4.Cu")
		(net "M_D_CPU0_CLK_DN<0>")
	)
	(segment
		(start 282.34132 -254.679958)
		(end 281.672538 -254.011176)
		(width 0.16002)
		(layer "In4.Cu")
		(net "M_D_CPU0_CLK_DN<0>")
	)
	(segment
		(start 327.103486 -256.309114)
		(end 327.068942 -256.32918)
		(width 0.09525)
		(layer "In4.Cu")
		(net "M_D_CPU0_CLK_DN<0>")
	)
	(segment
		(start 336.879692 -256.309114)
		(end 336.87131 -256.304288)
		(width 0.09525)
		(layer "In4.Cu")
		(net "M_D_CPU0_CLK_DN<0>")
	)
	(arc
		(start 336.87131 -256.304288)
		(mid 336.686278 -256.258374)
		(end 336.502502 -256.309114)
		(width 0.09525)
		(layer "In4.Cu")
		(net "M_D_CPU0_CLK_DN<0>")
	)
	(arc
		(start 326.102726 -256.352548)
		(mid 326.093965 -256.360414)
		(end 326.085454 -256.36855)
		(width 0.09525)
		(layer "In4.Cu")
		(net "M_D_CPU0_CLK_DN<0>")
	)
	(arc
		(start 334.622648 -256.309114)
		(mid 334.341216 -256.384869)
		(end 334.059784 -256.309114)
		(width 0.09525)
		(layer "In4.Cu")
		(net "M_D_CPU0_CLK_DN<0>")
	)
	(arc
		(start 327.068942 -256.32918)
		(mid 326.802416 -256.385117)
		(end 326.540876 -256.309114)
		(width 0.09525)
		(layer "In4.Cu")
		(net "M_D_CPU0_CLK_DN<0>")
	)
	(arc
		(start 328.042524 -256.309114)
		(mid 327.761092 -256.384869)
		(end 327.47966 -256.309114)
		(width 0.09525)
		(layer "In4.Cu")
		(net "M_D_CPU0_CLK_DN<0>")
	)
	(arc
		(start 337.442556 -256.309114)
		(mid 337.161124 -256.384869)
		(end 336.879692 -256.309114)
		(width 0.09525)
		(layer "In4.Cu")
		(net "M_D_CPU0_CLK_DN<0>")
	)
	(arc
		(start 338.38261 -256.309114)
		(mid 338.101178 -256.384869)
		(end 337.819746 -256.309114)
		(width 0.09525)
		(layer "In4.Cu")
		(net "M_D_CPU0_CLK_DN<0>")
	)
	(arc
		(start 328.982578 -256.309114)
		(mid 328.701146 -256.384869)
		(end 328.419714 -256.309114)
		(width 0.09525)
		(layer "In4.Cu")
		(net "M_D_CPU0_CLK_DN<0>")
	)
	(arc
		(start 338.701888 -256.28219)
		(mid 338.539237 -256.25993)
		(end 338.38261 -256.309114)
		(width 0.09525)
		(layer "In4.Cu")
		(net "M_D_CPU0_CLK_DN<0>")
	)
	(arc
		(start 333.11973 -256.309114)
		(mid 332.935955 -256.258342)
		(end 332.750922 -256.304288)
		(width 0.09525)
		(layer "In4.Cu")
		(net "M_D_CPU0_CLK_DN<0>")
	)
	(arc
		(start 334.999584 -256.309114)
		(mid 334.811116 -256.258437)
		(end 334.622648 -256.309114)
		(width 0.09525)
		(layer "In4.Cu")
		(net "M_D_CPU0_CLK_DN<0>")
	)
	(arc
		(start 333.682594 -256.309114)
		(mid 333.401162 -256.384869)
		(end 333.11973 -256.309114)
		(width 0.09525)
		(layer "In4.Cu")
		(net "M_D_CPU0_CLK_DN<0>")
	)
	(arc
		(start 335.562448 -256.309114)
		(mid 335.281016 -256.384869)
		(end 334.999584 -256.309114)
		(width 0.09525)
		(layer "In4.Cu")
		(net "M_D_CPU0_CLK_DN<0>")
	)
	(arc
		(start 329.359768 -256.309114)
		(mid 329.175993 -256.258342)
		(end 328.99096 -256.304288)
		(width 0.09525)
		(layer "In4.Cu")
		(net "M_D_CPU0_CLK_DN<0>")
	)
	(arc
		(start 331.802486 -256.309114)
		(mid 331.521054 -256.384869)
		(end 331.239622 -256.309114)
		(width 0.09525)
		(layer "In4.Cu")
		(net "M_D_CPU0_CLK_DN<0>")
	)
	(arc
		(start 336.502502 -256.309114)
		(mid 336.22107 -256.384869)
		(end 335.939638 -256.309114)
		(width 0.09525)
		(layer "In4.Cu")
		(net "M_D_CPU0_CLK_DN<0>")
	)
	(arc
		(start 326.540876 -256.309114)
		(mid 326.366787 -256.258242)
		(end 326.189086 -256.294636)
		(width 0.09525)
		(layer "In4.Cu")
		(net "M_D_CPU0_CLK_DN<0>")
	)
	(arc
		(start 326.163686 -256.309114)
		(mid 326.132131 -256.329321)
		(end 326.102726 -256.352548)
		(width 0.09525)
		(layer "In4.Cu")
		(net "M_D_CPU0_CLK_DN<0>")
	)
	(arc
		(start 330.862432 -256.309114)
		(mid 330.581 -256.384869)
		(end 330.299568 -256.309114)
		(width 0.09525)
		(layer "In4.Cu")
		(net "M_D_CPU0_CLK_DN<0>")
	)
	(arc
		(start 332.74254 -256.309114)
		(mid 332.461108 -256.384869)
		(end 332.179676 -256.309114)
		(width 0.09525)
		(layer "In4.Cu")
		(net "M_D_CPU0_CLK_DN<0>")
	)
	(arc
		(start 335.931256 -256.304288)
		(mid 335.746224 -256.258374)
		(end 335.562448 -256.309114)
		(width 0.09525)
		(layer "In4.Cu")
		(net "M_D_CPU0_CLK_DN<0>")
	)
	(arc
		(start 331.23124 -256.304288)
		(mid 331.046208 -256.258374)
		(end 330.862432 -256.309114)
		(width 0.09525)
		(layer "In4.Cu")
		(net "M_D_CPU0_CLK_DN<0>")
	)
	(arc
		(start 330.299568 -256.309114)
		(mid 330.1111 -256.258437)
		(end 329.922632 -256.309114)
		(width 0.09525)
		(layer "In4.Cu")
		(net "M_D_CPU0_CLK_DN<0>")
	)
	(arc
		(start 334.059784 -256.309114)
		(mid 333.876009 -256.258342)
		(end 333.690976 -256.304288)
		(width 0.09525)
		(layer "In4.Cu")
		(net "M_D_CPU0_CLK_DN<0>")
	)
	(arc
		(start 327.47966 -256.309114)
		(mid 327.299888 -256.258538)
		(end 327.117964 -256.300732)
		(width 0.09525)
		(layer "In4.Cu")
		(net "M_D_CPU0_CLK_DN<0>")
	)
	(arc
		(start 328.411332 -256.304288)
		(mid 328.2263 -256.258374)
		(end 328.042524 -256.309114)
		(width 0.09525)
		(layer "In4.Cu")
		(net "M_D_CPU0_CLK_DN<0>")
	)
	(arc
		(start 332.171294 -256.304288)
		(mid 331.986262 -256.258374)
		(end 331.802486 -256.309114)
		(width 0.09525)
		(layer "In4.Cu")
		(net "M_D_CPU0_CLK_DN<0>")
	)
	(arc
		(start 329.922632 -256.309114)
		(mid 329.6412 -256.384869)
		(end 329.359768 -256.309114)
		(width 0.09525)
		(layer "In4.Cu")
		(net "M_D_CPU0_CLK_DN<0>")
	)
	(arc
		(start 337.819746 -256.309114)
		(mid 337.635971 -256.258342)
		(end 337.450938 -256.304288)
		(width 0.09525)
		(layer "In4.Cu")
		(net "M_D_CPU0_CLK_DN<0>")
	)
	(segment
		(start 340.918038 -250.420124)
		(end 340.451186 -250.154186)
		(width 0.10668)
		(layer "F.Cu")
		(net "M_D_CPU0_ALERT_R_N")
	)
	(segment
		(start 311.488074 -249.88647)
		(end 321.856354 -249.88647)
		(width 0.11684)
		(layer "In4.Cu")
		(net "M_D_CPU0_ALERT_R_N")
	)
	(segment
		(start 328.409808 -250.481592)
		(end 328.41819 -250.476766)
		(width 0.0889)
		(layer "In4.Cu")
		(net "M_D_CPU0_ALERT_R_N")
	)
	(segment
		(start 307.811678 -246.210074)
		(end 311.488074 -249.88647)
		(width 0.11684)
		(layer "In4.Cu")
		(net "M_D_CPU0_ALERT_R_N")
	)
	(segment
		(start 324.961758 -250.400312)
		(end 325.880222 -250.400312)
		(width 0.0889)
		(layer "In4.Cu")
		(net "M_D_CPU0_ALERT_R_N")
	)
	(segment
		(start 306.434236 -246.210074)
		(end 307.811678 -246.210074)
		(width 0.11684)
		(layer "In4.Cu")
		(net "M_D_CPU0_ALERT_R_N")
	)
	(segment
		(start 286.133032 -244.08511)
		(end 286.133032 -244.820948)
		(width 0.11684)
		(layer "In4.Cu")
		(net "M_D_CPU0_ALERT_R_N")
	)
	(segment
		(start 332.744064 -250.476766)
		(end 332.752446 -250.481592)
		(width 0.0889)
		(layer "In4.Cu")
		(net "M_D_CPU0_ALERT_R_N")
	)
	(segment
		(start 340.297008 -250.419616)
		(end 340.451186 -250.154186)
		(width 0.0889)
		(layer "In4.Cu")
		(net "M_D_CPU0_ALERT_R_N")
	)
	(segment
		(start 304.791618 -246.210074)
		(end 305.047396 -246.465852)
		(width 0.11684)
		(layer "In4.Cu")
		(net "M_D_CPU0_ALERT_R_N")
	)
	(segment
		(start 326.526398 -250.483624)
		(end 326.538082 -250.476766)
		(width 0.0889)
		(layer "In4.Cu")
		(net "M_D_CPU0_ALERT_R_N")
	)
	(segment
		(start 321.856354 -249.88647)
		(end 322.308728 -250.338844)
		(width 0.11684)
		(layer "In4.Cu")
		(net "M_D_CPU0_ALERT_R_N")
	)
	(segment
		(start 287.522158 -246.210074)
		(end 304.791618 -246.210074)
		(width 0.11684)
		(layer "In4.Cu")
		(net "M_D_CPU0_ALERT_R_N")
	)
	(segment
		(start 340.200742 -250.445016)
		(end 340.297008 -250.419616)
		(width 0.0889)
		(layer "In4.Cu")
		(net "M_D_CPU0_ALERT_R_N")
	)
	(segment
		(start 286.133032 -244.820948)
		(end 287.522158 -246.210074)
		(width 0.11684)
		(layer "In4.Cu")
		(net "M_D_CPU0_ALERT_R_N")
	)
	(segment
		(start 324.90029 -250.338844)
		(end 324.961758 -250.400312)
		(width 0.0889)
		(layer "In4.Cu")
		(net "M_D_CPU0_ALERT_R_N")
	)
	(segment
		(start 335.929732 -250.481592)
		(end 335.938114 -250.476766)
		(width 0.0889)
		(layer "In4.Cu")
		(net "M_D_CPU0_ALERT_R_N")
	)
	(segment
		(start 331.229716 -250.481592)
		(end 331.238098 -250.476766)
		(width 0.0889)
		(layer "In4.Cu")
		(net "M_D_CPU0_ALERT_R_N")
	)
	(segment
		(start 322.308728 -250.338844)
		(end 324.247002 -250.338844)
		(width 0.11684)
		(layer "In4.Cu")
		(net "M_D_CPU0_ALERT_R_N")
	)
	(segment
		(start 338.384134 -250.476766)
		(end 338.392516 -250.481592)
		(width 0.0889)
		(layer "In4.Cu")
		(net "M_D_CPU0_ALERT_R_N")
	)
	(segment
		(start 336.869786 -250.481592)
		(end 336.878168 -250.476766)
		(width 0.0889)
		(layer "In4.Cu")
		(net "M_D_CPU0_ALERT_R_N")
	)
	(segment
		(start 306.178458 -246.465852)
		(end 306.434236 -246.210074)
		(width 0.11684)
		(layer "In4.Cu")
		(net "M_D_CPU0_ALERT_R_N")
	)
	(segment
		(start 332.16977 -250.481592)
		(end 332.178152 -250.476766)
		(width 0.0889)
		(layer "In4.Cu")
		(net "M_D_CPU0_ALERT_R_N")
	)
	(segment
		(start 333.684118 -250.476766)
		(end 333.6925 -250.481592)
		(width 0.0889)
		(layer "In4.Cu")
		(net "M_D_CPU0_ALERT_R_N")
	)
	(segment
		(start 324.247002 -250.338844)
		(end 324.90029 -250.338844)
		(width 0.0889)
		(layer "In4.Cu")
		(net "M_D_CPU0_ALERT_R_N")
	)
	(segment
		(start 337.44408 -250.476766)
		(end 337.452462 -250.481592)
		(width 0.0889)
		(layer "In4.Cu")
		(net "M_D_CPU0_ALERT_R_N")
	)
	(segment
		(start 327.469754 -250.481592)
		(end 327.478136 -250.476766)
		(width 0.0889)
		(layer "In4.Cu")
		(net "M_D_CPU0_ALERT_R_N")
	)
	(segment
		(start 328.984102 -250.476766)
		(end 328.992484 -250.481592)
		(width 0.0889)
		(layer "In4.Cu")
		(net "M_D_CPU0_ALERT_R_N")
	)
	(segment
		(start 305.047396 -246.465852)
		(end 306.178458 -246.465852)
		(width 0.11684)
		(layer "In4.Cu")
		(net "M_D_CPU0_ALERT_R_N")
	)
	(arc
		(start 339.698076 -250.476766)
		(mid 339.945672 -250.401588)
		(end 340.200742 -250.445016)
		(width 0.0889)
		(layer "In4.Cu")
		(net "M_D_CPU0_ALERT_R_N")
	)
	(arc
		(start 337.818222 -250.476766)
		(mid 338.101178 -250.400589)
		(end 338.384134 -250.476766)
		(width 0.0889)
		(layer "In4.Cu")
		(net "M_D_CPU0_ALERT_R_N")
	)
	(arc
		(start 333.118206 -250.476766)
		(mid 333.401162 -250.400589)
		(end 333.684118 -250.476766)
		(width 0.0889)
		(layer "In4.Cu")
		(net "M_D_CPU0_ALERT_R_N")
	)
	(arc
		(start 326.538082 -250.476766)
		(mid 326.821038 -250.400589)
		(end 327.103994 -250.476766)
		(width 0.0889)
		(layer "In4.Cu")
		(net "M_D_CPU0_ALERT_R_N")
	)
	(arc
		(start 331.238098 -250.476766)
		(mid 331.521054 -250.400589)
		(end 331.80401 -250.476766)
		(width 0.0889)
		(layer "In4.Cu")
		(net "M_D_CPU0_ALERT_R_N")
	)
	(arc
		(start 336.878168 -250.476766)
		(mid 337.161124 -250.400589)
		(end 337.44408 -250.476766)
		(width 0.0889)
		(layer "In4.Cu")
		(net "M_D_CPU0_ALERT_R_N")
	)
	(arc
		(start 332.178152 -250.476766)
		(mid 332.461108 -250.400589)
		(end 332.744064 -250.476766)
		(width 0.0889)
		(layer "In4.Cu")
		(net "M_D_CPU0_ALERT_R_N")
	)
	(arc
		(start 327.478136 -250.476766)
		(mid 327.761092 -250.400589)
		(end 328.044048 -250.476766)
		(width 0.0889)
		(layer "In4.Cu")
		(net "M_D_CPU0_ALERT_R_N")
	)
	(arc
		(start 337.452462 -250.481592)
		(mid 337.63597 -250.527086)
		(end 337.818222 -250.476766)
		(width 0.0889)
		(layer "In4.Cu")
		(net "M_D_CPU0_ALERT_R_N")
	)
	(arc
		(start 338.758276 -250.476766)
		(mid 339.041232 -250.400589)
		(end 339.324188 -250.476766)
		(width 0.0889)
		(layer "In4.Cu")
		(net "M_D_CPU0_ALERT_R_N")
	)
	(arc
		(start 334.05826 -250.476766)
		(mid 334.341216 -250.400589)
		(end 334.624172 -250.476766)
		(width 0.0889)
		(layer "In4.Cu")
		(net "M_D_CPU0_ALERT_R_N")
	)
	(arc
		(start 328.992484 -250.481592)
		(mid 329.175992 -250.527086)
		(end 329.358244 -250.476766)
		(width 0.0889)
		(layer "In4.Cu")
		(net "M_D_CPU0_ALERT_R_N")
	)
	(arc
		(start 335.563972 -250.476766)
		(mid 335.746223 -250.527116)
		(end 335.929732 -250.481592)
		(width 0.0889)
		(layer "In4.Cu")
		(net "M_D_CPU0_ALERT_R_N")
	)
	(arc
		(start 326.163686 -250.476766)
		(mid 326.344144 -250.52721)
		(end 326.526398 -250.483624)
		(width 0.0889)
		(layer "In4.Cu")
		(net "M_D_CPU0_ALERT_R_N")
	)
	(arc
		(start 329.358244 -250.476766)
		(mid 329.6412 -250.400589)
		(end 329.924156 -250.476766)
		(width 0.0889)
		(layer "In4.Cu")
		(net "M_D_CPU0_ALERT_R_N")
	)
	(arc
		(start 334.99806 -250.476766)
		(mid 335.281016 -250.400589)
		(end 335.563972 -250.476766)
		(width 0.0889)
		(layer "In4.Cu")
		(net "M_D_CPU0_ALERT_R_N")
	)
	(arc
		(start 331.80401 -250.476766)
		(mid 331.986261 -250.527116)
		(end 332.16977 -250.481592)
		(width 0.0889)
		(layer "In4.Cu")
		(net "M_D_CPU0_ALERT_R_N")
	)
	(arc
		(start 329.924156 -250.476766)
		(mid 330.1111 -250.527021)
		(end 330.298044 -250.476766)
		(width 0.0889)
		(layer "In4.Cu")
		(net "M_D_CPU0_ALERT_R_N")
	)
	(arc
		(start 334.624172 -250.476766)
		(mid 334.811116 -250.527021)
		(end 334.99806 -250.476766)
		(width 0.0889)
		(layer "In4.Cu")
		(net "M_D_CPU0_ALERT_R_N")
	)
	(arc
		(start 330.298044 -250.476766)
		(mid 330.581 -250.400589)
		(end 330.863956 -250.476766)
		(width 0.0889)
		(layer "In4.Cu")
		(net "M_D_CPU0_ALERT_R_N")
	)
	(arc
		(start 325.880222 -250.400312)
		(mid 325.946594 -250.404154)
		(end 326.012048 -250.415806)
		(width 0.0889)
		(layer "In4.Cu")
		(net "M_D_CPU0_ALERT_R_N")
	)
	(arc
		(start 330.863956 -250.476766)
		(mid 331.046207 -250.527116)
		(end 331.229716 -250.481592)
		(width 0.0889)
		(layer "In4.Cu")
		(net "M_D_CPU0_ALERT_R_N")
	)
	(arc
		(start 335.938114 -250.476766)
		(mid 336.22107 -250.400589)
		(end 336.504026 -250.476766)
		(width 0.0889)
		(layer "In4.Cu")
		(net "M_D_CPU0_ALERT_R_N")
	)
	(arc
		(start 339.324188 -250.476766)
		(mid 339.511132 -250.527021)
		(end 339.698076 -250.476766)
		(width 0.0889)
		(layer "In4.Cu")
		(net "M_D_CPU0_ALERT_R_N")
	)
	(arc
		(start 328.044048 -250.476766)
		(mid 328.226299 -250.527116)
		(end 328.409808 -250.481592)
		(width 0.0889)
		(layer "In4.Cu")
		(net "M_D_CPU0_ALERT_R_N")
	)
	(arc
		(start 328.41819 -250.476766)
		(mid 328.701146 -250.400589)
		(end 328.984102 -250.476766)
		(width 0.0889)
		(layer "In4.Cu")
		(net "M_D_CPU0_ALERT_R_N")
	)
	(arc
		(start 333.6925 -250.481592)
		(mid 333.876008 -250.527086)
		(end 334.05826 -250.476766)
		(width 0.0889)
		(layer "In4.Cu")
		(net "M_D_CPU0_ALERT_R_N")
	)
	(arc
		(start 326.012048 -250.415806)
		(mid 326.090089 -250.440759)
		(end 326.163686 -250.476766)
		(width 0.0889)
		(layer "In4.Cu")
		(net "M_D_CPU0_ALERT_R_N")
	)
	(arc
		(start 336.504026 -250.476766)
		(mid 336.686277 -250.527116)
		(end 336.869786 -250.481592)
		(width 0.0889)
		(layer "In4.Cu")
		(net "M_D_CPU0_ALERT_R_N")
	)
	(arc
		(start 338.392516 -250.481592)
		(mid 338.576024 -250.527086)
		(end 338.758276 -250.476766)
		(width 0.0889)
		(layer "In4.Cu")
		(net "M_D_CPU0_ALERT_R_N")
	)
	(arc
		(start 327.103994 -250.476766)
		(mid 327.286245 -250.527116)
		(end 327.469754 -250.481592)
		(width 0.0889)
		(layer "In4.Cu")
		(net "M_D_CPU0_ALERT_R_N")
	)
	(arc
		(start 332.752446 -250.481592)
		(mid 332.935954 -250.527086)
		(end 333.118206 -250.476766)
		(width 0.0889)
		(layer "In4.Cu")
		(net "M_D_CPU0_ALERT_R_N")
	)
	(via
		(at 284.736032 -244.08511)
		(size 0.4826)
		(drill 0.254)
		(layers "F.Cu" "B.Cu")
		(net "M_D_CPU0_ALERT_N")
	)
	(segment
		(start 285.332932 -244.08511)
		(end 284.736032 -244.08511)
		(width 0.10668)
		(layer "B.Cu")
		(net "M_D_CPU0_ALERT_N")
	)
	(segment
		(start 95.157798 -267.340334)
		(end 94.690946 -267.606272)
		(width 0.10668)
		(layer "F.Cu")
		(net "M_C_CPU1_SB_RSP<0>")
	)
	(segment
		(start 82.654902 -267.923264)
		(end 82.66557 -267.917168)
		(width 0.0889)
		(layer "In2.Cu")
		(net "M_C_CPU1_SB_RSP<0>")
	)
	(segment
		(start 57.131458 -269.586964)
		(end 57.286144 -269.74165)
		(width 0.11684)
		(layer "In2.Cu")
		(net "M_C_CPU1_SB_RSP<0>")
	)
	(segment
		(start 45.574458 -269.868396)
		(end 45.574458 -269.75435)
		(width 0.11684)
		(layer "In2.Cu")
		(net "M_C_CPU1_SB_RSP<0>")
	)
	(segment
		(start 50.80127 -269.855696)
		(end 50.955956 -270.010382)
		(width 0.11684)
		(layer "In2.Cu")
		(net "M_C_CPU1_SB_RSP<0>")
	)
	(segment
		(start 94.542102 -267.862558)
		(end 94.690946 -267.606272)
		(width 0.0889)
		(layer "In2.Cu")
		(net "M_C_CPU1_SB_RSP<0>")
	)
	(segment
		(start 58.342784 -269.855696)
		(end 58.49747 -270.010382)
		(width 0.11684)
		(layer "In2.Cu")
		(net "M_C_CPU1_SB_RSP<0>")
	)
	(segment
		(start 50.118264 -270.010382)
		(end 50.27295 -269.855696)
		(width 0.11684)
		(layer "In2.Cu")
		(net "M_C_CPU1_SB_RSP<0>")
	)
	(segment
		(start 47.301404 -270.010382)
		(end 48.004984 -270.010382)
		(width 0.11684)
		(layer "In2.Cu")
		(net "M_C_CPU1_SB_RSP<0>")
	)
	(segment
		(start 52.833016 -270.010382)
		(end 52.992782 -269.850616)
		(width 0.11684)
		(layer "In2.Cu")
		(net "M_C_CPU1_SB_RSP<0>")
	)
	(segment
		(start 50.27295 -269.855696)
		(end 50.27295 -269.74165)
		(width 0.11684)
		(layer "In2.Cu")
		(net "M_C_CPU1_SB_RSP<0>")
	)
	(segment
		(start 48.004984 -270.010382)
		(end 48.15967 -269.855696)
		(width 0.11684)
		(layer "In2.Cu")
		(net "M_C_CPU1_SB_RSP<0>")
	)
	(segment
		(start 49.370996 -269.586964)
		(end 49.589944 -269.586964)
		(width 0.11684)
		(layer "In2.Cu")
		(net "M_C_CPU1_SB_RSP<0>")
	)
	(segment
		(start 46.785784 -269.599664)
		(end 47.004732 -269.599664)
		(width 0.11684)
		(layer "In2.Cu")
		(net "M_C_CPU1_SB_RSP<0>")
	)
	(segment
		(start 55.85587 -269.586964)
		(end 56.074818 -269.586964)
		(width 0.11684)
		(layer "In2.Cu")
		(net "M_C_CPU1_SB_RSP<0>")
	)
	(segment
		(start 53.675788 -270.005302)
		(end 53.894736 -270.005302)
		(width 0.11684)
		(layer "In2.Cu")
		(net "M_C_CPU1_SB_RSP<0>")
	)
	(segment
		(start 50.80127 -269.74165)
		(end 50.80127 -269.855696)
		(width 0.11684)
		(layer "In2.Cu")
		(net "M_C_CPU1_SB_RSP<0>")
	)
	(segment
		(start 50.427636 -269.586964)
		(end 50.646584 -269.586964)
		(width 0.11684)
		(layer "In2.Cu")
		(net "M_C_CPU1_SB_RSP<0>")
	)
	(segment
		(start 46.631098 -269.75435)
		(end 46.785784 -269.599664)
		(width 0.11684)
		(layer "In2.Cu")
		(net "M_C_CPU1_SB_RSP<0>")
	)
	(segment
		(start 49.899316 -270.010382)
		(end 50.118264 -270.010382)
		(width 0.11684)
		(layer "In2.Cu")
		(net "M_C_CPU1_SB_RSP<0>")
	)
	(segment
		(start 56.757824 -269.74165)
		(end 56.91251 -269.586964)
		(width 0.11684)
		(layer "In2.Cu")
		(net "M_C_CPU1_SB_RSP<0>")
	)
	(segment
		(start 54.577742 -269.74927)
		(end 54.577742 -269.850616)
		(width 0.11684)
		(layer "In2.Cu")
		(net "M_C_CPU1_SB_RSP<0>")
	)
	(segment
		(start 54.577742 -269.850616)
		(end 54.737508 -270.010382)
		(width 0.11684)
		(layer "In2.Cu")
		(net "M_C_CPU1_SB_RSP<0>")
	)
	(segment
		(start 57.286144 -269.74165)
		(end 57.286144 -269.855696)
		(width 0.11684)
		(layer "In2.Cu")
		(net "M_C_CPU1_SB_RSP<0>")
	)
	(segment
		(start 87.354918 -267.923264)
		(end 87.365586 -267.917168)
		(width 0.0889)
		(layer "In2.Cu")
		(net "M_C_CPU1_SB_RSP<0>")
	)
	(segment
		(start 45.432472 -270.010382)
		(end 45.574458 -269.868396)
		(width 0.11684)
		(layer "In2.Cu")
		(net "M_C_CPU1_SB_RSP<0>")
	)
	(segment
		(start 57.44083 -270.010382)
		(end 57.659778 -270.010382)
		(width 0.11684)
		(layer "In2.Cu")
		(net "M_C_CPU1_SB_RSP<0>")
	)
	(segment
		(start 46.631098 -269.868396)
		(end 46.631098 -269.75435)
		(width 0.11684)
		(layer "In2.Cu")
		(net "M_C_CPU1_SB_RSP<0>")
	)
	(segment
		(start 63.329566 -266.851384)
		(end 76.141326 -266.851384)
		(width 0.11684)
		(layer "In2.Cu")
		(net "M_C_CPU1_SB_RSP<0>")
	)
	(segment
		(start 49.061624 -270.010382)
		(end 49.21631 -269.855696)
		(width 0.11684)
		(layer "In2.Cu")
		(net "M_C_CPU1_SB_RSP<0>")
	)
	(segment
		(start 46.257464 -270.023082)
		(end 46.476412 -270.023082)
		(width 0.11684)
		(layer "In2.Cu")
		(net "M_C_CPU1_SB_RSP<0>")
	)
	(segment
		(start 57.96915 -269.586964)
		(end 58.188098 -269.586964)
		(width 0.11684)
		(layer "In2.Cu")
		(net "M_C_CPU1_SB_RSP<0>")
	)
	(segment
		(start 50.955956 -270.010382)
		(end 52.833016 -270.010382)
		(width 0.11684)
		(layer "In2.Cu")
		(net "M_C_CPU1_SB_RSP<0>")
	)
	(segment
		(start 56.229504 -269.855696)
		(end 56.38419 -270.010382)
		(width 0.11684)
		(layer "In2.Cu")
		(net "M_C_CPU1_SB_RSP<0>")
	)
	(segment
		(start 48.15967 -269.855696)
		(end 48.15967 -269.74165)
		(width 0.11684)
		(layer "In2.Cu")
		(net "M_C_CPU1_SB_RSP<0>")
	)
	(segment
		(start 56.074818 -269.586964)
		(end 56.229504 -269.74165)
		(width 0.11684)
		(layer "In2.Cu")
		(net "M_C_CPU1_SB_RSP<0>")
	)
	(segment
		(start 57.659778 -270.010382)
		(end 57.814464 -269.855696)
		(width 0.11684)
		(layer "In2.Cu")
		(net "M_C_CPU1_SB_RSP<0>")
	)
	(segment
		(start 48.68799 -269.74165)
		(end 48.68799 -269.855696)
		(width 0.11684)
		(layer "In2.Cu")
		(net "M_C_CPU1_SB_RSP<0>")
	)
	(segment
		(start 57.286144 -269.855696)
		(end 57.44083 -270.010382)
		(width 0.11684)
		(layer "In2.Cu")
		(net "M_C_CPU1_SB_RSP<0>")
	)
	(segment
		(start 94.439486 -267.889736)
		(end 94.542102 -267.862558)
		(width 0.0889)
		(layer "In2.Cu")
		(net "M_C_CPU1_SB_RSP<0>")
	)
	(segment
		(start 56.757824 -269.855696)
		(end 56.757824 -269.74165)
		(width 0.11684)
		(layer "In2.Cu")
		(net "M_C_CPU1_SB_RSP<0>")
	)
	(segment
		(start 48.842676 -270.010382)
		(end 49.061624 -270.010382)
		(width 0.11684)
		(layer "In2.Cu")
		(net "M_C_CPU1_SB_RSP<0>")
	)
	(segment
		(start 56.603138 -270.010382)
		(end 56.757824 -269.855696)
		(width 0.11684)
		(layer "In2.Cu")
		(net "M_C_CPU1_SB_RSP<0>")
	)
	(segment
		(start 44.340018 -270.435324)
		(end 44.76496 -270.010382)
		(width 0.11684)
		(layer "In2.Cu")
		(net "M_C_CPU1_SB_RSP<0>")
	)
	(segment
		(start 45.729144 -269.599664)
		(end 45.948092 -269.599664)
		(width 0.11684)
		(layer "In2.Cu")
		(net "M_C_CPU1_SB_RSP<0>")
	)
	(segment
		(start 86.976458 -267.917168)
		(end 86.987126 -267.923264)
		(width 0.0889)
		(layer "In2.Cu")
		(net "M_C_CPU1_SB_RSP<0>")
	)
	(segment
		(start 60.170568 -270.010382)
		(end 63.329566 -266.851384)
		(width 0.11684)
		(layer "In2.Cu")
		(net "M_C_CPU1_SB_RSP<0>")
	)
	(segment
		(start 53.894736 -270.005302)
		(end 54.049422 -269.850616)
		(width 0.11684)
		(layer "In2.Cu")
		(net "M_C_CPU1_SB_RSP<0>")
	)
	(segment
		(start 48.68799 -269.855696)
		(end 48.842676 -270.010382)
		(width 0.11684)
		(layer "In2.Cu")
		(net "M_C_CPU1_SB_RSP<0>")
	)
	(segment
		(start 86.036404 -267.917168)
		(end 86.047072 -267.923264)
		(width 0.0889)
		(layer "In2.Cu")
		(net "M_C_CPU1_SB_RSP<0>")
	)
	(segment
		(start 54.049422 -269.74927)
		(end 54.204108 -269.594584)
		(width 0.11684)
		(layer "In2.Cu")
		(net "M_C_CPU1_SB_RSP<0>")
	)
	(segment
		(start 57.814464 -269.855696)
		(end 57.814464 -269.74165)
		(width 0.11684)
		(layer "In2.Cu")
		(net "M_C_CPU1_SB_RSP<0>")
	)
	(segment
		(start 76.463906 -267.173964)
		(end 78.88224 -267.173964)
		(width 0.11684)
		(layer "In2.Cu")
		(net "M_C_CPU1_SB_RSP<0>")
	)
	(segment
		(start 45.948092 -269.599664)
		(end 46.102778 -269.75435)
		(width 0.11684)
		(layer "In2.Cu")
		(net "M_C_CPU1_SB_RSP<0>")
	)
	(segment
		(start 44.76496 -270.010382)
		(end 45.432472 -270.010382)
		(width 0.11684)
		(layer "In2.Cu")
		(net "M_C_CPU1_SB_RSP<0>")
	)
	(segment
		(start 57.814464 -269.74165)
		(end 57.96915 -269.586964)
		(width 0.11684)
		(layer "In2.Cu")
		(net "M_C_CPU1_SB_RSP<0>")
	)
	(segment
		(start 48.533304 -269.586964)
		(end 48.68799 -269.74165)
		(width 0.11684)
		(layer "In2.Cu")
		(net "M_C_CPU1_SB_RSP<0>")
	)
	(segment
		(start 55.701184 -269.74165)
		(end 55.85587 -269.586964)
		(width 0.11684)
		(layer "In2.Cu")
		(net "M_C_CPU1_SB_RSP<0>")
	)
	(segment
		(start 56.38419 -270.010382)
		(end 56.603138 -270.010382)
		(width 0.11684)
		(layer "In2.Cu")
		(net "M_C_CPU1_SB_RSP<0>")
	)
	(segment
		(start 53.147468 -269.581884)
		(end 53.366416 -269.581884)
		(width 0.11684)
		(layer "In2.Cu")
		(net "M_C_CPU1_SB_RSP<0>")
	)
	(segment
		(start 79.49184 -267.783564)
		(end 79.887826 -267.783564)
		(width 0.0889)
		(layer "In2.Cu")
		(net "M_C_CPU1_SB_RSP<0>")
	)
	(segment
		(start 78.88224 -267.173964)
		(end 79.49184 -267.783564)
		(width 0.11684)
		(layer "In2.Cu")
		(net "M_C_CPU1_SB_RSP<0>")
	)
	(segment
		(start 47.004732 -269.599664)
		(end 47.159418 -269.75435)
		(width 0.11684)
		(layer "In2.Cu")
		(net "M_C_CPU1_SB_RSP<0>")
	)
	(segment
		(start 56.91251 -269.586964)
		(end 57.131458 -269.586964)
		(width 0.11684)
		(layer "In2.Cu")
		(net "M_C_CPU1_SB_RSP<0>")
	)
	(segment
		(start 56.229504 -269.74165)
		(end 56.229504 -269.855696)
		(width 0.11684)
		(layer "In2.Cu")
		(net "M_C_CPU1_SB_RSP<0>")
	)
	(segment
		(start 47.159418 -269.75435)
		(end 47.159418 -269.868396)
		(width 0.11684)
		(layer "In2.Cu")
		(net "M_C_CPU1_SB_RSP<0>")
	)
	(segment
		(start 55.546498 -270.010382)
		(end 55.701184 -269.855696)
		(width 0.11684)
		(layer "In2.Cu")
		(net "M_C_CPU1_SB_RSP<0>")
	)
	(segment
		(start 54.423056 -269.594584)
		(end 54.577742 -269.74927)
		(width 0.11684)
		(layer "In2.Cu")
		(net "M_C_CPU1_SB_RSP<0>")
	)
	(segment
		(start 54.204108 -269.594584)
		(end 54.423056 -269.594584)
		(width 0.11684)
		(layer "In2.Cu")
		(net "M_C_CPU1_SB_RSP<0>")
	)
	(segment
		(start 49.21631 -269.74165)
		(end 49.370996 -269.586964)
		(width 0.11684)
		(layer "In2.Cu")
		(net "M_C_CPU1_SB_RSP<0>")
	)
	(segment
		(start 52.992782 -269.73657)
		(end 53.147468 -269.581884)
		(width 0.11684)
		(layer "In2.Cu")
		(net "M_C_CPU1_SB_RSP<0>")
	)
	(segment
		(start 49.74463 -269.855696)
		(end 49.899316 -270.010382)
		(width 0.11684)
		(layer "In2.Cu")
		(net "M_C_CPU1_SB_RSP<0>")
	)
	(segment
		(start 47.159418 -269.868396)
		(end 47.301404 -270.010382)
		(width 0.11684)
		(layer "In2.Cu")
		(net "M_C_CPU1_SB_RSP<0>")
	)
	(segment
		(start 92.994988 -267.923264)
		(end 93.005656 -267.917168)
		(width 0.0889)
		(layer "In2.Cu")
		(net "M_C_CPU1_SB_RSP<0>")
	)
	(segment
		(start 82.276442 -267.917168)
		(end 82.28711 -267.923264)
		(width 0.0889)
		(layer "In2.Cu")
		(net "M_C_CPU1_SB_RSP<0>")
	)
	(segment
		(start 46.476412 -270.023082)
		(end 46.631098 -269.868396)
		(width 0.11684)
		(layer "In2.Cu")
		(net "M_C_CPU1_SB_RSP<0>")
	)
	(segment
		(start 54.049422 -269.850616)
		(end 54.049422 -269.74927)
		(width 0.11684)
		(layer "In2.Cu")
		(net "M_C_CPU1_SB_RSP<0>")
	)
	(segment
		(start 53.521102 -269.73657)
		(end 53.521102 -269.850616)
		(width 0.11684)
		(layer "In2.Cu")
		(net "M_C_CPU1_SB_RSP<0>")
	)
	(segment
		(start 48.314356 -269.586964)
		(end 48.533304 -269.586964)
		(width 0.11684)
		(layer "In2.Cu")
		(net "M_C_CPU1_SB_RSP<0>")
	)
	(segment
		(start 54.737508 -270.010382)
		(end 55.546498 -270.010382)
		(width 0.11684)
		(layer "In2.Cu")
		(net "M_C_CPU1_SB_RSP<0>")
	)
	(segment
		(start 53.521102 -269.850616)
		(end 53.675788 -270.005302)
		(width 0.11684)
		(layer "In2.Cu")
		(net "M_C_CPU1_SB_RSP<0>")
	)
	(segment
		(start 46.102778 -269.868396)
		(end 46.257464 -270.023082)
		(width 0.11684)
		(layer "In2.Cu")
		(net "M_C_CPU1_SB_RSP<0>")
	)
	(segment
		(start 58.49747 -270.010382)
		(end 60.170568 -270.010382)
		(width 0.11684)
		(layer "In2.Cu")
		(net "M_C_CPU1_SB_RSP<0>")
	)
	(segment
		(start 48.15967 -269.74165)
		(end 48.314356 -269.586964)
		(width 0.11684)
		(layer "In2.Cu")
		(net "M_C_CPU1_SB_RSP<0>")
	)
	(segment
		(start 58.342784 -269.74165)
		(end 58.342784 -269.855696)
		(width 0.11684)
		(layer "In2.Cu")
		(net "M_C_CPU1_SB_RSP<0>")
	)
	(segment
		(start 52.992782 -269.850616)
		(end 52.992782 -269.73657)
		(width 0.11684)
		(layer "In2.Cu")
		(net "M_C_CPU1_SB_RSP<0>")
	)
	(segment
		(start 92.054934 -267.923264)
		(end 92.065602 -267.917168)
		(width 0.0889)
		(layer "In2.Cu")
		(net "M_C_CPU1_SB_RSP<0>")
	)
	(segment
		(start 58.188098 -269.586964)
		(end 58.342784 -269.74165)
		(width 0.11684)
		(layer "In2.Cu")
		(net "M_C_CPU1_SB_RSP<0>")
	)
	(segment
		(start 45.574458 -269.75435)
		(end 45.729144 -269.599664)
		(width 0.11684)
		(layer "In2.Cu")
		(net "M_C_CPU1_SB_RSP<0>")
	)
	(segment
		(start 83.594956 -267.923264)
		(end 83.605624 -267.917168)
		(width 0.0889)
		(layer "In2.Cu")
		(net "M_C_CPU1_SB_RSP<0>")
	)
	(segment
		(start 50.646584 -269.586964)
		(end 50.80127 -269.74165)
		(width 0.11684)
		(layer "In2.Cu")
		(net "M_C_CPU1_SB_RSP<0>")
	)
	(segment
		(start 91.676474 -267.917168)
		(end 91.687142 -267.923264)
		(width 0.0889)
		(layer "In2.Cu")
		(net "M_C_CPU1_SB_RSP<0>")
	)
	(segment
		(start 49.589944 -269.586964)
		(end 49.74463 -269.74165)
		(width 0.11684)
		(layer "In2.Cu")
		(net "M_C_CPU1_SB_RSP<0>")
	)
	(segment
		(start 55.701184 -269.855696)
		(end 55.701184 -269.74165)
		(width 0.11684)
		(layer "In2.Cu")
		(net "M_C_CPU1_SB_RSP<0>")
	)
	(segment
		(start 88.294972 -267.923264)
		(end 88.30564 -267.917168)
		(width 0.0889)
		(layer "In2.Cu")
		(net "M_C_CPU1_SB_RSP<0>")
	)
	(segment
		(start 50.27295 -269.74165)
		(end 50.427636 -269.586964)
		(width 0.11684)
		(layer "In2.Cu")
		(net "M_C_CPU1_SB_RSP<0>")
	)
	(segment
		(start 49.21631 -269.855696)
		(end 49.21631 -269.74165)
		(width 0.11684)
		(layer "In2.Cu")
		(net "M_C_CPU1_SB_RSP<0>")
	)
	(segment
		(start 49.74463 -269.74165)
		(end 49.74463 -269.855696)
		(width 0.11684)
		(layer "In2.Cu")
		(net "M_C_CPU1_SB_RSP<0>")
	)
	(segment
		(start 53.366416 -269.581884)
		(end 53.521102 -269.73657)
		(width 0.11684)
		(layer "In2.Cu")
		(net "M_C_CPU1_SB_RSP<0>")
	)
	(segment
		(start 76.141326 -266.851384)
		(end 76.463906 -267.173964)
		(width 0.11684)
		(layer "In2.Cu")
		(net "M_C_CPU1_SB_RSP<0>")
	)
	(segment
		(start 90.73642 -267.917168)
		(end 90.747088 -267.923264)
		(width 0.0889)
		(layer "In2.Cu")
		(net "M_C_CPU1_SB_RSP<0>")
	)
	(segment
		(start 46.102778 -269.75435)
		(end 46.102778 -269.868396)
		(width 0.11684)
		(layer "In2.Cu")
		(net "M_C_CPU1_SB_RSP<0>")
	)
	(arc
		(start 81.347056 -267.923264)
		(mid 81.530952 -267.972744)
		(end 81.714848 -267.923264)
		(width 0.0889)
		(layer "In2.Cu")
		(net "M_C_CPU1_SB_RSP<0>")
	)
	(arc
		(start 91.687142 -267.923264)
		(mid 91.871038 -267.972744)
		(end 92.054934 -267.923264)
		(width 0.0889)
		(layer "In2.Cu")
		(net "M_C_CPU1_SB_RSP<0>")
	)
	(arc
		(start 87.365586 -267.917168)
		(mid 87.647175 -267.846294)
		(end 87.92718 -267.923264)
		(width 0.0889)
		(layer "In2.Cu")
		(net "M_C_CPU1_SB_RSP<0>")
	)
	(arc
		(start 92.065602 -267.917168)
		(mid 92.347191 -267.846294)
		(end 92.627196 -267.923264)
		(width 0.0889)
		(layer "In2.Cu")
		(net "M_C_CPU1_SB_RSP<0>")
	)
	(arc
		(start 92.627196 -267.923264)
		(mid 92.811092 -267.972744)
		(end 92.994988 -267.923264)
		(width 0.0889)
		(layer "In2.Cu")
		(net "M_C_CPU1_SB_RSP<0>")
	)
	(arc
		(start 87.92718 -267.923264)
		(mid 88.111076 -267.972744)
		(end 88.294972 -267.923264)
		(width 0.0889)
		(layer "In2.Cu")
		(net "M_C_CPU1_SB_RSP<0>")
	)
	(arc
		(start 86.414864 -267.923264)
		(mid 86.694868 -267.846219)
		(end 86.976458 -267.917168)
		(width 0.0889)
		(layer "In2.Cu")
		(net "M_C_CPU1_SB_RSP<0>")
	)
	(arc
		(start 79.887826 -267.783564)
		(mid 80.156783 -267.819059)
		(end 80.407256 -267.923264)
		(width 0.0889)
		(layer "In2.Cu")
		(net "M_C_CPU1_SB_RSP<0>")
	)
	(arc
		(start 80.775048 -267.923264)
		(mid 81.061052 -267.846312)
		(end 81.347056 -267.923264)
		(width 0.0889)
		(layer "In2.Cu")
		(net "M_C_CPU1_SB_RSP<0>")
	)
	(arc
		(start 91.11488 -267.923264)
		(mid 91.394884 -267.846219)
		(end 91.676474 -267.917168)
		(width 0.0889)
		(layer "In2.Cu")
		(net "M_C_CPU1_SB_RSP<0>")
	)
	(arc
		(start 83.605624 -267.917168)
		(mid 83.887213 -267.846294)
		(end 84.167218 -267.923264)
		(width 0.0889)
		(layer "In2.Cu")
		(net "M_C_CPU1_SB_RSP<0>")
	)
	(arc
		(start 82.28711 -267.923264)
		(mid 82.471006 -267.972744)
		(end 82.654902 -267.923264)
		(width 0.0889)
		(layer "In2.Cu")
		(net "M_C_CPU1_SB_RSP<0>")
	)
	(arc
		(start 81.714848 -267.923264)
		(mid 81.994852 -267.846219)
		(end 82.276442 -267.917168)
		(width 0.0889)
		(layer "In2.Cu")
		(net "M_C_CPU1_SB_RSP<0>")
	)
	(arc
		(start 84.53501 -267.923264)
		(mid 84.821014 -267.846312)
		(end 85.107018 -267.923264)
		(width 0.0889)
		(layer "In2.Cu")
		(net "M_C_CPU1_SB_RSP<0>")
	)
	(arc
		(start 82.66557 -267.917168)
		(mid 82.947159 -267.846294)
		(end 83.227164 -267.923264)
		(width 0.0889)
		(layer "In2.Cu")
		(net "M_C_CPU1_SB_RSP<0>")
	)
	(arc
		(start 88.867234 -267.923264)
		(mid 89.05113 -267.972744)
		(end 89.235026 -267.923264)
		(width 0.0889)
		(layer "In2.Cu")
		(net "M_C_CPU1_SB_RSP<0>")
	)
	(arc
		(start 93.005656 -267.917168)
		(mid 93.287245 -267.846294)
		(end 93.56725 -267.923264)
		(width 0.0889)
		(layer "In2.Cu")
		(net "M_C_CPU1_SB_RSP<0>")
	)
	(arc
		(start 90.747088 -267.923264)
		(mid 90.930984 -267.972744)
		(end 91.11488 -267.923264)
		(width 0.0889)
		(layer "In2.Cu")
		(net "M_C_CPU1_SB_RSP<0>")
	)
	(arc
		(start 88.30564 -267.917168)
		(mid 88.587229 -267.846294)
		(end 88.867234 -267.923264)
		(width 0.0889)
		(layer "In2.Cu")
		(net "M_C_CPU1_SB_RSP<0>")
	)
	(arc
		(start 93.935042 -267.923264)
		(mid 94.183336 -267.847561)
		(end 94.439486 -267.889736)
		(width 0.0889)
		(layer "In2.Cu")
		(net "M_C_CPU1_SB_RSP<0>")
	)
	(arc
		(start 86.987126 -267.923264)
		(mid 87.171022 -267.972744)
		(end 87.354918 -267.923264)
		(width 0.0889)
		(layer "In2.Cu")
		(net "M_C_CPU1_SB_RSP<0>")
	)
	(arc
		(start 89.807034 -267.923264)
		(mid 89.99093 -267.972744)
		(end 90.174826 -267.923264)
		(width 0.0889)
		(layer "In2.Cu")
		(net "M_C_CPU1_SB_RSP<0>")
	)
	(arc
		(start 93.56725 -267.923264)
		(mid 93.751146 -267.972744)
		(end 93.935042 -267.923264)
		(width 0.0889)
		(layer "In2.Cu")
		(net "M_C_CPU1_SB_RSP<0>")
	)
	(arc
		(start 86.047072 -267.923264)
		(mid 86.230968 -267.972744)
		(end 86.414864 -267.923264)
		(width 0.0889)
		(layer "In2.Cu")
		(net "M_C_CPU1_SB_RSP<0>")
	)
	(arc
		(start 84.167218 -267.923264)
		(mid 84.351114 -267.972744)
		(end 84.53501 -267.923264)
		(width 0.0889)
		(layer "In2.Cu")
		(net "M_C_CPU1_SB_RSP<0>")
	)
	(arc
		(start 85.107018 -267.923264)
		(mid 85.290914 -267.972744)
		(end 85.47481 -267.923264)
		(width 0.0889)
		(layer "In2.Cu")
		(net "M_C_CPU1_SB_RSP<0>")
	)
	(arc
		(start 85.47481 -267.923264)
		(mid 85.754814 -267.846219)
		(end 86.036404 -267.917168)
		(width 0.0889)
		(layer "In2.Cu")
		(net "M_C_CPU1_SB_RSP<0>")
	)
	(arc
		(start 89.235026 -267.923264)
		(mid 89.52103 -267.846312)
		(end 89.807034 -267.923264)
		(width 0.0889)
		(layer "In2.Cu")
		(net "M_C_CPU1_SB_RSP<0>")
	)
	(arc
		(start 80.407256 -267.923264)
		(mid 80.591152 -267.972744)
		(end 80.775048 -267.923264)
		(width 0.0889)
		(layer "In2.Cu")
		(net "M_C_CPU1_SB_RSP<0>")
	)
	(arc
		(start 83.227164 -267.923264)
		(mid 83.41106 -267.972744)
		(end 83.594956 -267.923264)
		(width 0.0889)
		(layer "In2.Cu")
		(net "M_C_CPU1_SB_RSP<0>")
	)
	(arc
		(start 90.174826 -267.923264)
		(mid 90.45483 -267.846219)
		(end 90.73642 -267.917168)
		(width 0.0889)
		(layer "In2.Cu")
		(net "M_C_CPU1_SB_RSP<0>")
	)
	(segment
		(start 94.687898 -264.910316)
		(end 94.221046 -265.176254)
		(width 0.10668)
		(layer "F.Cu")
		(net "M_C_CPU1_SB_PAR")
	)
	(segment
		(start 93.094048 -264.853674)
		(end 93.10243 -264.848848)
		(width 0.0889)
		(layer "In2.Cu")
		(net "M_C_CPU1_SB_PAR")
	)
	(segment
		(start 86.879684 -264.848848)
		(end 86.888066 -264.853674)
		(width 0.0889)
		(layer "In2.Cu")
		(net "M_C_CPU1_SB_PAR")
	)
	(segment
		(start 41.732454 -265.751564)
		(end 41.963086 -265.751564)
		(width 0.14478)
		(layer "In2.Cu")
		(net "M_C_CPU1_SB_PAR")
	)
	(segment
		(start 61.728096 -265.074654)
		(end 75.949556 -265.074654)
		(width 0.14478)
		(layer "In2.Cu")
		(net "M_C_CPU1_SB_PAR")
	)
	(segment
		(start 40.23995 -267.03528)
		(end 40.664892 -266.610338)
		(width 0.14478)
		(layer "In2.Cu")
		(net "M_C_CPU1_SB_PAR")
	)
	(segment
		(start 83.119722 -264.848848)
		(end 83.128104 -264.853674)
		(width 0.0889)
		(layer "In2.Cu")
		(net "M_C_CPU1_SB_PAR")
	)
	(segment
		(start 88.394032 -264.853674)
		(end 88.402414 -264.848848)
		(width 0.0889)
		(layer "In2.Cu")
		(net "M_C_CPU1_SB_PAR")
	)
	(segment
		(start 91.5797 -264.848848)
		(end 91.588082 -264.853674)
		(width 0.0889)
		(layer "In2.Cu")
		(net "M_C_CPU1_SB_PAR")
	)
	(segment
		(start 42.1259 -265.914378)
		(end 42.1259 -266.447524)
		(width 0.14478)
		(layer "In2.Cu")
		(net "M_C_CPU1_SB_PAR")
	)
	(segment
		(start 79.350616 -264.841736)
		(end 79.37119 -264.853674)
		(width 0.0889)
		(layer "In2.Cu")
		(net "M_C_CPU1_SB_PAR")
	)
	(segment
		(start 42.1259 -266.447524)
		(end 42.288714 -266.610338)
		(width 0.14478)
		(layer "In2.Cu")
		(net "M_C_CPU1_SB_PAR")
	)
	(segment
		(start 41.963086 -265.751564)
		(end 42.1259 -265.914378)
		(width 0.14478)
		(layer "In2.Cu")
		(net "M_C_CPU1_SB_PAR")
	)
	(segment
		(start 94.352618 -264.827512)
		(end 94.37497 -264.910824)
		(width 0.0889)
		(layer "In2.Cu")
		(net "M_C_CPU1_SB_PAR")
	)
	(segment
		(start 60.192412 -266.610338)
		(end 61.728096 -265.074654)
		(width 0.14478)
		(layer "In2.Cu")
		(net "M_C_CPU1_SB_PAR")
	)
	(segment
		(start 79.935324 -264.853928)
		(end 79.958692 -264.840466)
		(width 0.0889)
		(layer "In2.Cu")
		(net "M_C_CPU1_SB_PAR")
	)
	(segment
		(start 85.93963 -264.848848)
		(end 85.948012 -264.853674)
		(width 0.0889)
		(layer "In2.Cu")
		(net "M_C_CPU1_SB_PAR")
	)
	(segment
		(start 94.37497 -264.910824)
		(end 94.221046 -265.176254)
		(width 0.0889)
		(layer "In2.Cu")
		(net "M_C_CPU1_SB_PAR")
	)
	(segment
		(start 82.179668 -264.848848)
		(end 82.18805 -264.853674)
		(width 0.0889)
		(layer "In2.Cu")
		(net "M_C_CPU1_SB_PAR")
	)
	(segment
		(start 40.664892 -266.610338)
		(end 41.406826 -266.610338)
		(width 0.14478)
		(layer "In2.Cu")
		(net "M_C_CPU1_SB_PAR")
	)
	(segment
		(start 41.56964 -265.914378)
		(end 41.732454 -265.751564)
		(width 0.14478)
		(layer "In2.Cu")
		(net "M_C_CPU1_SB_PAR")
	)
	(segment
		(start 90.639646 -264.848848)
		(end 90.648028 -264.853674)
		(width 0.0889)
		(layer "In2.Cu")
		(net "M_C_CPU1_SB_PAR")
	)
	(segment
		(start 79.911448 -264.867898)
		(end 79.935324 -264.853928)
		(width 0.0889)
		(layer "In2.Cu")
		(net "M_C_CPU1_SB_PAR")
	)
	(segment
		(start 41.406826 -266.610338)
		(end 41.56964 -266.447524)
		(width 0.14478)
		(layer "In2.Cu")
		(net "M_C_CPU1_SB_PAR")
	)
	(segment
		(start 75.949556 -265.074654)
		(end 76.419456 -265.074654)
		(width 0.0889)
		(layer "In2.Cu")
		(net "M_C_CPU1_SB_PAR")
	)
	(segment
		(start 92.153994 -264.853674)
		(end 92.162376 -264.848848)
		(width 0.0889)
		(layer "In2.Cu")
		(net "M_C_CPU1_SB_PAR")
	)
	(segment
		(start 42.288714 -266.610338)
		(end 60.192412 -266.610338)
		(width 0.14478)
		(layer "In2.Cu")
		(net "M_C_CPU1_SB_PAR")
	)
	(segment
		(start 41.56964 -266.447524)
		(end 41.56964 -265.914378)
		(width 0.14478)
		(layer "In2.Cu")
		(net "M_C_CPU1_SB_PAR")
	)
	(segment
		(start 78.093062 -264.554716)
		(end 78.307946 -264.7696)
		(width 0.0889)
		(layer "In2.Cu")
		(net "M_C_CPU1_SB_PAR")
	)
	(segment
		(start 76.419456 -265.074654)
		(end 76.939394 -264.554716)
		(width 0.0889)
		(layer "In2.Cu")
		(net "M_C_CPU1_SB_PAR")
	)
	(segment
		(start 76.939394 -264.554716)
		(end 78.093062 -264.554716)
		(width 0.0889)
		(layer "In2.Cu")
		(net "M_C_CPU1_SB_PAR")
	)
	(segment
		(start 87.453978 -264.853674)
		(end 87.46236 -264.848848)
		(width 0.0889)
		(layer "In2.Cu")
		(net "M_C_CPU1_SB_PAR")
	)
	(segment
		(start 78.38059 -264.82548)
		(end 78.467966 -264.875772)
		(width 0.0889)
		(layer "In2.Cu")
		(net "M_C_CPU1_SB_PAR")
	)
	(segment
		(start 83.694016 -264.853674)
		(end 83.702398 -264.848848)
		(width 0.0889)
		(layer "In2.Cu")
		(net "M_C_CPU1_SB_PAR")
	)
	(arc
		(start 92.528136 -264.853674)
		(mid 92.811092 -264.929851)
		(end 93.094048 -264.853674)
		(width 0.0889)
		(layer "In2.Cu")
		(net "M_C_CPU1_SB_PAR")
	)
	(arc
		(start 80.874108 -264.853674)
		(mid 81.061052 -264.803419)
		(end 81.247996 -264.853674)
		(width 0.0889)
		(layer "In2.Cu")
		(net "M_C_CPU1_SB_PAR")
	)
	(arc
		(start 82.18805 -264.853674)
		(mid 82.471006 -264.929851)
		(end 82.753962 -264.853674)
		(width 0.0889)
		(layer "In2.Cu")
		(net "M_C_CPU1_SB_PAR")
	)
	(arc
		(start 85.57387 -264.853674)
		(mid 85.756121 -264.803324)
		(end 85.93963 -264.848848)
		(width 0.0889)
		(layer "In2.Cu")
		(net "M_C_CPU1_SB_PAR")
	)
	(arc
		(start 93.46819 -264.853674)
		(mid 93.751146 -264.929851)
		(end 94.034102 -264.853674)
		(width 0.0889)
		(layer "In2.Cu")
		(net "M_C_CPU1_SB_PAR")
	)
	(arc
		(start 79.958692 -264.840466)
		(mid 80.135087 -264.803563)
		(end 80.308196 -264.853674)
		(width 0.0889)
		(layer "In2.Cu")
		(net "M_C_CPU1_SB_PAR")
	)
	(arc
		(start 84.068158 -264.853674)
		(mid 84.351114 -264.929851)
		(end 84.63407 -264.853674)
		(width 0.0889)
		(layer "In2.Cu")
		(net "M_C_CPU1_SB_PAR")
	)
	(arc
		(start 93.10243 -264.848848)
		(mid 93.285938 -264.803354)
		(end 93.46819 -264.853674)
		(width 0.0889)
		(layer "In2.Cu")
		(net "M_C_CPU1_SB_PAR")
	)
	(arc
		(start 78.467966 -264.875772)
		(mid 78.734622 -264.930292)
		(end 78.995778 -264.853674)
		(width 0.0889)
		(layer "In2.Cu")
		(net "M_C_CPU1_SB_PAR")
	)
	(arc
		(start 86.513924 -264.853674)
		(mid 86.696175 -264.803324)
		(end 86.879684 -264.848848)
		(width 0.0889)
		(layer "In2.Cu")
		(net "M_C_CPU1_SB_PAR")
	)
	(arc
		(start 87.82812 -264.853674)
		(mid 88.111076 -264.929851)
		(end 88.394032 -264.853674)
		(width 0.0889)
		(layer "In2.Cu")
		(net "M_C_CPU1_SB_PAR")
	)
	(arc
		(start 83.702398 -264.848848)
		(mid 83.885906 -264.803354)
		(end 84.068158 -264.853674)
		(width 0.0889)
		(layer "In2.Cu")
		(net "M_C_CPU1_SB_PAR")
	)
	(arc
		(start 87.46236 -264.848848)
		(mid 87.645868 -264.803354)
		(end 87.82812 -264.853674)
		(width 0.0889)
		(layer "In2.Cu")
		(net "M_C_CPU1_SB_PAR")
	)
	(arc
		(start 78.307946 -264.7696)
		(mid 78.342429 -264.799931)
		(end 78.38059 -264.82548)
		(width 0.0889)
		(layer "In2.Cu")
		(net "M_C_CPU1_SB_PAR")
	)
	(arc
		(start 86.888066 -264.853674)
		(mid 87.171022 -264.929851)
		(end 87.453978 -264.853674)
		(width 0.0889)
		(layer "In2.Cu")
		(net "M_C_CPU1_SB_PAR")
	)
	(arc
		(start 88.402414 -264.848848)
		(mid 88.585922 -264.803354)
		(end 88.768174 -264.853674)
		(width 0.0889)
		(layer "In2.Cu")
		(net "M_C_CPU1_SB_PAR")
	)
	(arc
		(start 84.63407 -264.853674)
		(mid 84.821014 -264.803419)
		(end 85.007958 -264.853674)
		(width 0.0889)
		(layer "In2.Cu")
		(net "M_C_CPU1_SB_PAR")
	)
	(arc
		(start 89.707974 -264.853674)
		(mid 89.99093 -264.929851)
		(end 90.273886 -264.853674)
		(width 0.0889)
		(layer "In2.Cu")
		(net "M_C_CPU1_SB_PAR")
	)
	(arc
		(start 85.007958 -264.853674)
		(mid 85.290914 -264.929851)
		(end 85.57387 -264.853674)
		(width 0.0889)
		(layer "In2.Cu")
		(net "M_C_CPU1_SB_PAR")
	)
	(arc
		(start 83.128104 -264.853674)
		(mid 83.41106 -264.929851)
		(end 83.694016 -264.853674)
		(width 0.0889)
		(layer "In2.Cu")
		(net "M_C_CPU1_SB_PAR")
	)
	(arc
		(start 82.753962 -264.853674)
		(mid 82.936213 -264.803324)
		(end 83.119722 -264.848848)
		(width 0.0889)
		(layer "In2.Cu")
		(net "M_C_CPU1_SB_PAR")
	)
	(arc
		(start 81.813908 -264.853674)
		(mid 81.996159 -264.803324)
		(end 82.179668 -264.848848)
		(width 0.0889)
		(layer "In2.Cu")
		(net "M_C_CPU1_SB_PAR")
	)
	(arc
		(start 91.588082 -264.853674)
		(mid 91.871038 -264.929851)
		(end 92.153994 -264.853674)
		(width 0.0889)
		(layer "In2.Cu")
		(net "M_C_CPU1_SB_PAR")
	)
	(arc
		(start 79.37119 -264.853674)
		(mid 79.63951 -264.929782)
		(end 79.911448 -264.867898)
		(width 0.0889)
		(layer "In2.Cu")
		(net "M_C_CPU1_SB_PAR")
	)
	(arc
		(start 90.648028 -264.853674)
		(mid 90.930984 -264.929851)
		(end 91.21394 -264.853674)
		(width 0.0889)
		(layer "In2.Cu")
		(net "M_C_CPU1_SB_PAR")
	)
	(arc
		(start 81.247996 -264.853674)
		(mid 81.530952 -264.929851)
		(end 81.813908 -264.853674)
		(width 0.0889)
		(layer "In2.Cu")
		(net "M_C_CPU1_SB_PAR")
	)
	(arc
		(start 88.768174 -264.853674)
		(mid 89.05113 -264.929851)
		(end 89.334086 -264.853674)
		(width 0.0889)
		(layer "In2.Cu")
		(net "M_C_CPU1_SB_PAR")
	)
	(arc
		(start 78.995778 -264.853674)
		(mid 79.171688 -264.802864)
		(end 79.350616 -264.841736)
		(width 0.0889)
		(layer "In2.Cu")
		(net "M_C_CPU1_SB_PAR")
	)
	(arc
		(start 89.334086 -264.853674)
		(mid 89.52103 -264.803419)
		(end 89.707974 -264.853674)
		(width 0.0889)
		(layer "In2.Cu")
		(net "M_C_CPU1_SB_PAR")
	)
	(arc
		(start 85.948012 -264.853674)
		(mid 86.230968 -264.929851)
		(end 86.513924 -264.853674)
		(width 0.0889)
		(layer "In2.Cu")
		(net "M_C_CPU1_SB_PAR")
	)
	(arc
		(start 92.162376 -264.848848)
		(mid 92.345884 -264.803354)
		(end 92.528136 -264.853674)
		(width 0.0889)
		(layer "In2.Cu")
		(net "M_C_CPU1_SB_PAR")
	)
	(arc
		(start 94.034102 -264.853674)
		(mid 94.190421 -264.804679)
		(end 94.352618 -264.827512)
		(width 0.0889)
		(layer "In2.Cu")
		(net "M_C_CPU1_SB_PAR")
	)
	(arc
		(start 80.308196 -264.853674)
		(mid 80.591152 -264.929851)
		(end 80.874108 -264.853674)
		(width 0.0889)
		(layer "In2.Cu")
		(net "M_C_CPU1_SB_PAR")
	)
	(arc
		(start 91.21394 -264.853674)
		(mid 91.396191 -264.803324)
		(end 91.5797 -264.848848)
		(width 0.0889)
		(layer "In2.Cu")
		(net "M_C_CPU1_SB_PAR")
	)
	(arc
		(start 90.273886 -264.853674)
		(mid 90.456137 -264.803324)
		(end 90.639646 -264.848848)
		(width 0.0889)
		(layer "In2.Cu")
		(net "M_C_CPU1_SB_PAR")
	)
	(segment
		(start 95.157798 -270.580358)
		(end 94.690946 -270.846296)
		(width 0.12954)
		(layer "F.Cu")
		(net "M_C_CPU1_SB_DQS_DP<9>")
	)
	(segment
		(start 64.539368 -271.209008)
		(end 64.539368 -270.932148)
		(width 0.16002)
		(layer "In2.Cu")
		(net "M_C_CPU1_SB_DQS_DP<9>")
	)
	(segment
		(start 62.057026 -272.669762)
		(end 62.58433 -272.669762)
		(width 0.16002)
		(layer "In2.Cu")
		(net "M_C_CPU1_SB_DQS_DP<9>")
	)
	(segment
		(start 78.523846 -271.171162)
		(end 78.55585 -271.189704)
		(width 0.09525)
		(layer "In2.Cu")
		(net "M_C_CPU1_SB_DQS_DP<9>")
	)
	(segment
		(start 77.008228 -270.196564)
		(end 77.529944 -270.196564)
		(width 0.09525)
		(layer "In2.Cu")
		(net "M_C_CPU1_SB_DQS_DP<9>")
	)
	(segment
		(start 62.58433 -272.669762)
		(end 62.693042 -272.778474)
		(width 0.16002)
		(layer "In2.Cu")
		(net "M_C_CPU1_SB_DQS_DP<9>")
	)
	(segment
		(start 58.798206 -274.535646)
		(end 61.21273 -274.535646)
		(width 0.16002)
		(layer "In2.Cu")
		(net "M_C_CPU1_SB_DQS_DP<9>")
	)
	(segment
		(start 46.539912 -274.820126)
		(end 47.104046 -275.38426)
		(width 0.16002)
		(layer "In2.Cu")
		(net "M_C_CPU1_SB_DQS_DP<9>")
	)
	(segment
		(start 64.297306 -270.690086)
		(end 64.297306 -270.162782)
		(width 0.16002)
		(layer "In2.Cu")
		(net "M_C_CPU1_SB_DQS_DP<9>")
	)
	(segment
		(start 61.792104 -273.679412)
		(end 61.683392 -273.5707)
		(width 0.16002)
		(layer "In2.Cu")
		(net "M_C_CPU1_SB_DQS_DP<9>")
	)
	(segment
		(start 61.683392 -273.5707)
		(end 61.683392 -273.043396)
		(width 0.16002)
		(layer "In2.Cu")
		(net "M_C_CPU1_SB_DQS_DP<9>")
	)
	(segment
		(start 48.402748 -275.38426)
		(end 48.99406 -275.975572)
		(width 0.16002)
		(layer "In2.Cu")
		(net "M_C_CPU1_SB_DQS_DP<9>")
	)
	(segment
		(start 92.991178 -271.176242)
		(end 92.99956 -271.171416)
		(width 0.09525)
		(layer "In2.Cu")
		(net "M_C_CPU1_SB_DQS_DP<9>")
	)
	(segment
		(start 64.297306 -270.162782)
		(end 64.67094 -269.789148)
		(width 0.16002)
		(layer "In2.Cu")
		(net "M_C_CPU1_SB_DQS_DP<9>")
	)
	(segment
		(start 58.138568 -275.195284)
		(end 58.798206 -274.535646)
		(width 0.16002)
		(layer "In2.Cu")
		(net "M_C_CPU1_SB_DQS_DP<9>")
	)
	(segment
		(start 63.824612 -271.16278)
		(end 64.066674 -271.404842)
		(width 0.16002)
		(layer "In2.Cu")
		(net "M_C_CPU1_SB_DQS_DP<9>")
	)
	(segment
		(start 57.661048 -275.195284)
		(end 58.138568 -275.195284)
		(width 0.16002)
		(layer "In2.Cu")
		(net "M_C_CPU1_SB_DQS_DP<9>")
	)
	(segment
		(start 64.343534 -271.404842)
		(end 64.539368 -271.209008)
		(width 0.16002)
		(layer "In2.Cu")
		(net "M_C_CPU1_SB_DQS_DP<9>")
	)
	(segment
		(start 62.923674 -271.536414)
		(end 63.297308 -271.16278)
		(width 0.16002)
		(layer "In2.Cu")
		(net "M_C_CPU1_SB_DQS_DP<9>")
	)
	(segment
		(start 65.440306 -270.03121)
		(end 65.717166 -270.03121)
		(width 0.16002)
		(layer "In2.Cu")
		(net "M_C_CPU1_SB_DQS_DP<9>")
	)
	(segment
		(start 61.683392 -273.043396)
		(end 62.057026 -272.669762)
		(width 0.16002)
		(layer "In2.Cu")
		(net "M_C_CPU1_SB_DQS_DP<9>")
	)
	(segment
		(start 54.19979 -275.223986)
		(end 54.35981 -275.384006)
		(width 0.16002)
		(layer "In2.Cu")
		(net "M_C_CPU1_SB_DQS_DP<9>")
	)
	(segment
		(start 52.79517 -274.528026)
		(end 53.233574 -274.089622)
		(width 0.16002)
		(layer "In2.Cu")
		(net "M_C_CPU1_SB_DQS_DP<9>")
	)
	(segment
		(start 89.802462 -271.171416)
		(end 89.810844 -271.176242)
		(width 0.09525)
		(layer "In2.Cu")
		(net "M_C_CPU1_SB_DQS_DP<9>")
	)
	(segment
		(start 66.214752 -269.533624)
		(end 75.955906 -269.533624)
		(width 0.16002)
		(layer "In2.Cu")
		(net "M_C_CPU1_SB_DQS_DP<9>")
	)
	(segment
		(start 83.591146 -271.176242)
		(end 83.599528 -271.171416)
		(width 0.09525)
		(layer "In2.Cu")
		(net "M_C_CPU1_SB_DQS_DP<9>")
	)
	(segment
		(start 86.0425 -271.171416)
		(end 86.050882 -271.176242)
		(width 0.09525)
		(layer "In2.Cu")
		(net "M_C_CPU1_SB_DQS_DP<9>")
	)
	(segment
		(start 89.231216 -271.176242)
		(end 89.239598 -271.171416)
		(width 0.09525)
		(layer "In2.Cu")
		(net "M_C_CPU1_SB_DQS_DP<9>")
	)
	(segment
		(start 61.792104 -273.956272)
		(end 61.792104 -273.679412)
		(width 0.16002)
		(layer "In2.Cu")
		(net "M_C_CPU1_SB_DQS_DP<9>")
	)
	(segment
		(start 65.717166 -270.03121)
		(end 66.214752 -269.533624)
		(width 0.16002)
		(layer "In2.Cu")
		(net "M_C_CPU1_SB_DQS_DP<9>")
	)
	(segment
		(start 56.807354 -276.048978)
		(end 57.661048 -275.195284)
		(width 0.16002)
		(layer "In2.Cu")
		(net "M_C_CPU1_SB_DQS_DP<9>")
	)
	(segment
		(start 75.955906 -269.533624)
		(end 75.979528 -269.533624)
		(width 0.09525)
		(layer "In2.Cu")
		(net "M_C_CPU1_SB_DQS_DP<9>")
	)
	(segment
		(start 64.539368 -270.932148)
		(end 64.297306 -270.690086)
		(width 0.16002)
		(layer "In2.Cu")
		(net "M_C_CPU1_SB_DQS_DP<9>")
	)
	(segment
		(start 79.441802 -271.157446)
		(end 79.465678 -271.171416)
		(width 0.09525)
		(layer "In2.Cu")
		(net "M_C_CPU1_SB_DQS_DP<9>")
	)
	(segment
		(start 45.893228 -274.820126)
		(end 46.539912 -274.820126)
		(width 0.16002)
		(layer "In2.Cu")
		(net "M_C_CPU1_SB_DQS_DP<9>")
	)
	(segment
		(start 50.661824 -275.121624)
		(end 51.255422 -274.528026)
		(width 0.16002)
		(layer "In2.Cu")
		(net "M_C_CPU1_SB_DQS_DP<9>")
	)
	(segment
		(start 45.47997 -275.649182)
		(end 45.47997 -275.233384)
		(width 0.16002)
		(layer "In2.Cu")
		(net "M_C_CPU1_SB_DQS_DP<9>")
	)
	(segment
		(start 49.44364 -275.975572)
		(end 50.297588 -275.121624)
		(width 0.16002)
		(layer "In2.Cu")
		(net "M_C_CPU1_SB_DQS_DP<9>")
	)
	(segment
		(start 90.742516 -271.171416)
		(end 90.750898 -271.176242)
		(width 0.09525)
		(layer "In2.Cu")
		(net "M_C_CPU1_SB_DQS_DP<9>")
	)
	(segment
		(start 54.35981 -275.384006)
		(end 55.915814 -275.384006)
		(width 0.16002)
		(layer "In2.Cu")
		(net "M_C_CPU1_SB_DQS_DP<9>")
	)
	(segment
		(start 63.165736 -272.58264)
		(end 63.165736 -272.30578)
		(width 0.16002)
		(layer "In2.Cu")
		(net "M_C_CPU1_SB_DQS_DP<9>")
	)
	(segment
		(start 85.102446 -271.171416)
		(end 85.110828 -271.176242)
		(width 0.09525)
		(layer "In2.Cu")
		(net "M_C_CPU1_SB_DQS_DP<9>")
	)
	(segment
		(start 63.165736 -272.30578)
		(end 62.923674 -272.063718)
		(width 0.16002)
		(layer "In2.Cu")
		(net "M_C_CPU1_SB_DQS_DP<9>")
	)
	(segment
		(start 56.580786 -276.048978)
		(end 56.807354 -276.048978)
		(width 0.16002)
		(layer "In2.Cu")
		(net "M_C_CPU1_SB_DQS_DP<9>")
	)
	(segment
		(start 55.915814 -275.384006)
		(end 56.580786 -276.048978)
		(width 0.16002)
		(layer "In2.Cu")
		(net "M_C_CPU1_SB_DQS_DP<9>")
	)
	(segment
		(start 47.104046 -275.38426)
		(end 48.402748 -275.38426)
		(width 0.16002)
		(layer "In2.Cu")
		(net "M_C_CPU1_SB_DQS_DP<9>")
	)
	(segment
		(start 53.233574 -274.089622)
		(end 53.862478 -274.089622)
		(width 0.16002)
		(layer "In2.Cu")
		(net "M_C_CPU1_SB_DQS_DP<9>")
	)
	(segment
		(start 53.862478 -274.089622)
		(end 54.19979 -274.426934)
		(width 0.16002)
		(layer "In2.Cu")
		(net "M_C_CPU1_SB_DQS_DP<9>")
	)
	(segment
		(start 76.03871 -269.592806)
		(end 76.40447 -269.592806)
		(width 0.09525)
		(layer "In2.Cu")
		(net "M_C_CPU1_SB_DQS_DP<9>")
	)
	(segment
		(start 48.99406 -275.975572)
		(end 49.44364 -275.975572)
		(width 0.16002)
		(layer "In2.Cu")
		(net "M_C_CPU1_SB_DQS_DP<9>")
	)
	(segment
		(start 62.923674 -272.063718)
		(end 62.923674 -271.536414)
		(width 0.16002)
		(layer "In2.Cu")
		(net "M_C_CPU1_SB_DQS_DP<9>")
	)
	(segment
		(start 79.841344 -271.171162)
		(end 79.86522 -271.157446)
		(width 0.09525)
		(layer "In2.Cu")
		(net "M_C_CPU1_SB_DQS_DP<9>")
	)
	(segment
		(start 94.436184 -271.138396)
		(end 94.537022 -271.111726)
		(width 0.09525)
		(layer "In2.Cu")
		(net "M_C_CPU1_SB_DQS_DP<9>")
	)
	(segment
		(start 62.693042 -272.778474)
		(end 62.969902 -272.778474)
		(width 0.16002)
		(layer "In2.Cu")
		(net "M_C_CPU1_SB_DQS_DP<9>")
	)
	(segment
		(start 65.198244 -269.789148)
		(end 65.440306 -270.03121)
		(width 0.16002)
		(layer "In2.Cu")
		(net "M_C_CPU1_SB_DQS_DP<9>")
	)
	(segment
		(start 81.342484 -271.171416)
		(end 81.350866 -271.176242)
		(width 0.09525)
		(layer "In2.Cu")
		(net "M_C_CPU1_SB_DQS_DP<9>")
	)
	(segment
		(start 94.537022 -271.111726)
		(end 94.690946 -270.846296)
		(width 0.09525)
		(layer "In2.Cu")
		(net "M_C_CPU1_SB_DQS_DP<9>")
	)
	(segment
		(start 76.40447 -269.592806)
		(end 77.008228 -270.196564)
		(width 0.09525)
		(layer "In2.Cu")
		(net "M_C_CPU1_SB_DQS_DP<9>")
	)
	(segment
		(start 84.5312 -271.176242)
		(end 84.539582 -271.171416)
		(width 0.09525)
		(layer "In2.Cu")
		(net "M_C_CPU1_SB_DQS_DP<9>")
	)
	(segment
		(start 61.21273 -274.535646)
		(end 61.792104 -273.956272)
		(width 0.16002)
		(layer "In2.Cu")
		(net "M_C_CPU1_SB_DQS_DP<9>")
	)
	(segment
		(start 51.255422 -274.528026)
		(end 52.79517 -274.528026)
		(width 0.16002)
		(layer "In2.Cu")
		(net "M_C_CPU1_SB_DQS_DP<9>")
	)
	(segment
		(start 75.979528 -269.533624)
		(end 76.03871 -269.592806)
		(width 0.09525)
		(layer "In2.Cu")
		(net "M_C_CPU1_SB_DQS_DP<9>")
	)
	(segment
		(start 79.8195 -271.183608)
		(end 79.841344 -271.171162)
		(width 0.09525)
		(layer "In2.Cu")
		(net "M_C_CPU1_SB_DQS_DP<9>")
	)
	(segment
		(start 64.67094 -269.789148)
		(end 65.198244 -269.789148)
		(width 0.16002)
		(layer "In2.Cu")
		(net "M_C_CPU1_SB_DQS_DP<9>")
	)
	(segment
		(start 50.297588 -275.121624)
		(end 50.661824 -275.121624)
		(width 0.16002)
		(layer "In2.Cu")
		(net "M_C_CPU1_SB_DQS_DP<9>")
	)
	(segment
		(start 44.61383 -275.809202)
		(end 45.31995 -275.809202)
		(width 0.16002)
		(layer "In2.Cu")
		(net "M_C_CPU1_SB_DQS_DP<9>")
	)
	(segment
		(start 44.340018 -275.53539)
		(end 44.61383 -275.809202)
		(width 0.16002)
		(layer "In2.Cu")
		(net "M_C_CPU1_SB_DQS_DP<9>")
	)
	(segment
		(start 80.771238 -271.176242)
		(end 80.77962 -271.171416)
		(width 0.09525)
		(layer "In2.Cu")
		(net "M_C_CPU1_SB_DQS_DP<9>")
	)
	(segment
		(start 45.31995 -275.809202)
		(end 45.47997 -275.649182)
		(width 0.16002)
		(layer "In2.Cu")
		(net "M_C_CPU1_SB_DQS_DP<9>")
	)
	(segment
		(start 93.931232 -271.176242)
		(end 93.939614 -271.171416)
		(width 0.09525)
		(layer "In2.Cu")
		(net "M_C_CPU1_SB_DQS_DP<9>")
	)
	(segment
		(start 62.969902 -272.778474)
		(end 63.165736 -272.58264)
		(width 0.16002)
		(layer "In2.Cu")
		(net "M_C_CPU1_SB_DQS_DP<9>")
	)
	(segment
		(start 63.297308 -271.16278)
		(end 63.824612 -271.16278)
		(width 0.16002)
		(layer "In2.Cu")
		(net "M_C_CPU1_SB_DQS_DP<9>")
	)
	(segment
		(start 54.19979 -274.426934)
		(end 54.19979 -275.223986)
		(width 0.16002)
		(layer "In2.Cu")
		(net "M_C_CPU1_SB_DQS_DP<9>")
	)
	(segment
		(start 64.066674 -271.404842)
		(end 64.343534 -271.404842)
		(width 0.16002)
		(layer "In2.Cu")
		(net "M_C_CPU1_SB_DQS_DP<9>")
	)
	(segment
		(start 45.47997 -275.233384)
		(end 45.893228 -274.820126)
		(width 0.16002)
		(layer "In2.Cu")
		(net "M_C_CPU1_SB_DQS_DP<9>")
	)
	(segment
		(start 88.291162 -271.176242)
		(end 88.299544 -271.171416)
		(width 0.09525)
		(layer "In2.Cu")
		(net "M_C_CPU1_SB_DQS_DP<9>")
	)
	(segment
		(start 77.529944 -270.196564)
		(end 78.44536 -271.11198)
		(width 0.09525)
		(layer "In2.Cu")
		(net "M_C_CPU1_SB_DQS_DP<9>")
	)
	(arc
		(start 86.982554 -271.171416)
		(mid 87.171022 -271.222093)
		(end 87.35949 -271.171416)
		(width 0.09525)
		(layer "In2.Cu")
		(net "M_C_CPU1_SB_DQS_DP<9>")
	)
	(arc
		(start 81.719674 -271.171416)
		(mid 82.001106 -271.095661)
		(end 82.282538 -271.171416)
		(width 0.09525)
		(layer "In2.Cu")
		(net "M_C_CPU1_SB_DQS_DP<9>")
	)
	(arc
		(start 87.922354 -271.171416)
		(mid 88.106129 -271.222188)
		(end 88.291162 -271.176242)
		(width 0.09525)
		(layer "In2.Cu")
		(net "M_C_CPU1_SB_DQS_DP<9>")
	)
	(arc
		(start 88.862408 -271.171416)
		(mid 89.046183 -271.222188)
		(end 89.231216 -271.176242)
		(width 0.09525)
		(layer "In2.Cu")
		(net "M_C_CPU1_SB_DQS_DP<9>")
	)
	(arc
		(start 80.40243 -271.171416)
		(mid 80.586205 -271.222188)
		(end 80.771238 -271.176242)
		(width 0.09525)
		(layer "In2.Cu")
		(net "M_C_CPU1_SB_DQS_DP<9>")
	)
	(arc
		(start 81.350866 -271.176242)
		(mid 81.535898 -271.222156)
		(end 81.719674 -271.171416)
		(width 0.09525)
		(layer "In2.Cu")
		(net "M_C_CPU1_SB_DQS_DP<9>")
	)
	(arc
		(start 91.119706 -271.171416)
		(mid 91.401138 -271.095661)
		(end 91.68257 -271.171416)
		(width 0.09525)
		(layer "In2.Cu")
		(net "M_C_CPU1_SB_DQS_DP<9>")
	)
	(arc
		(start 78.44536 -271.11198)
		(mid 78.482662 -271.144144)
		(end 78.523846 -271.171162)
		(width 0.09525)
		(layer "In2.Cu")
		(net "M_C_CPU1_SB_DQS_DP<9>")
	)
	(arc
		(start 90.750898 -271.176242)
		(mid 90.93593 -271.222156)
		(end 91.119706 -271.171416)
		(width 0.09525)
		(layer "In2.Cu")
		(net "M_C_CPU1_SB_DQS_DP<9>")
	)
	(arc
		(start 89.239598 -271.171416)
		(mid 89.52103 -271.095661)
		(end 89.802462 -271.171416)
		(width 0.09525)
		(layer "In2.Cu")
		(net "M_C_CPU1_SB_DQS_DP<9>")
	)
	(arc
		(start 85.110828 -271.176242)
		(mid 85.29586 -271.222156)
		(end 85.479636 -271.171416)
		(width 0.09525)
		(layer "In2.Cu")
		(net "M_C_CPU1_SB_DQS_DP<9>")
	)
	(arc
		(start 89.810844 -271.176242)
		(mid 89.995876 -271.222156)
		(end 90.179652 -271.171416)
		(width 0.09525)
		(layer "In2.Cu")
		(net "M_C_CPU1_SB_DQS_DP<9>")
	)
	(arc
		(start 85.479636 -271.171416)
		(mid 85.761068 -271.095661)
		(end 86.0425 -271.171416)
		(width 0.09525)
		(layer "In2.Cu")
		(net "M_C_CPU1_SB_DQS_DP<9>")
	)
	(arc
		(start 84.539582 -271.171416)
		(mid 84.821014 -271.095661)
		(end 85.102446 -271.171416)
		(width 0.09525)
		(layer "In2.Cu")
		(net "M_C_CPU1_SB_DQS_DP<9>")
	)
	(arc
		(start 92.059506 -271.171416)
		(mid 92.340938 -271.095661)
		(end 92.62237 -271.171416)
		(width 0.09525)
		(layer "In2.Cu")
		(net "M_C_CPU1_SB_DQS_DP<9>")
	)
	(arc
		(start 87.35949 -271.171416)
		(mid 87.640922 -271.095661)
		(end 87.922354 -271.171416)
		(width 0.09525)
		(layer "In2.Cu")
		(net "M_C_CPU1_SB_DQS_DP<9>")
	)
	(arc
		(start 79.465678 -271.171416)
		(mid 79.641052 -271.221746)
		(end 79.8195 -271.183608)
		(width 0.09525)
		(layer "In2.Cu")
		(net "M_C_CPU1_SB_DQS_DP<9>")
	)
	(arc
		(start 78.55585 -271.189704)
		(mid 78.730642 -271.222634)
		(end 78.901036 -271.17167)
		(width 0.09525)
		(layer "In2.Cu")
		(net "M_C_CPU1_SB_DQS_DP<9>")
	)
	(arc
		(start 93.562424 -271.171416)
		(mid 93.746199 -271.222188)
		(end 93.931232 -271.176242)
		(width 0.09525)
		(layer "In2.Cu")
		(net "M_C_CPU1_SB_DQS_DP<9>")
	)
	(arc
		(start 79.86522 -271.157446)
		(mid 80.135603 -271.095886)
		(end 80.40243 -271.171416)
		(width 0.09525)
		(layer "In2.Cu")
		(net "M_C_CPU1_SB_DQS_DP<9>")
	)
	(arc
		(start 80.77962 -271.171416)
		(mid 81.061052 -271.095661)
		(end 81.342484 -271.171416)
		(width 0.09525)
		(layer "In2.Cu")
		(net "M_C_CPU1_SB_DQS_DP<9>")
	)
	(arc
		(start 86.41969 -271.171416)
		(mid 86.701122 -271.095661)
		(end 86.982554 -271.171416)
		(width 0.09525)
		(layer "In2.Cu")
		(net "M_C_CPU1_SB_DQS_DP<9>")
	)
	(arc
		(start 82.282538 -271.171416)
		(mid 82.471006 -271.222093)
		(end 82.659474 -271.171416)
		(width 0.09525)
		(layer "In2.Cu")
		(net "M_C_CPU1_SB_DQS_DP<9>")
	)
	(arc
		(start 92.62237 -271.171416)
		(mid 92.806145 -271.222188)
		(end 92.991178 -271.176242)
		(width 0.09525)
		(layer "In2.Cu")
		(net "M_C_CPU1_SB_DQS_DP<9>")
	)
	(arc
		(start 93.939614 -271.171416)
		(mid 94.18404 -271.096773)
		(end 94.436184 -271.138396)
		(width 0.09525)
		(layer "In2.Cu")
		(net "M_C_CPU1_SB_DQS_DP<9>")
	)
	(arc
		(start 83.599528 -271.171416)
		(mid 83.88096 -271.095661)
		(end 84.162392 -271.171416)
		(width 0.09525)
		(layer "In2.Cu")
		(net "M_C_CPU1_SB_DQS_DP<9>")
	)
	(arc
		(start 91.68257 -271.171416)
		(mid 91.871038 -271.222093)
		(end 92.059506 -271.171416)
		(width 0.09525)
		(layer "In2.Cu")
		(net "M_C_CPU1_SB_DQS_DP<9>")
	)
	(arc
		(start 83.222338 -271.171416)
		(mid 83.406113 -271.222188)
		(end 83.591146 -271.176242)
		(width 0.09525)
		(layer "In2.Cu")
		(net "M_C_CPU1_SB_DQS_DP<9>")
	)
	(arc
		(start 86.050882 -271.176242)
		(mid 86.235914 -271.222156)
		(end 86.41969 -271.171416)
		(width 0.09525)
		(layer "In2.Cu")
		(net "M_C_CPU1_SB_DQS_DP<9>")
	)
	(arc
		(start 90.179652 -271.171416)
		(mid 90.461084 -271.095661)
		(end 90.742516 -271.171416)
		(width 0.09525)
		(layer "In2.Cu")
		(net "M_C_CPU1_SB_DQS_DP<9>")
	)
	(arc
		(start 92.99956 -271.171416)
		(mid 93.280992 -271.095661)
		(end 93.562424 -271.171416)
		(width 0.09525)
		(layer "In2.Cu")
		(net "M_C_CPU1_SB_DQS_DP<9>")
	)
	(arc
		(start 88.299544 -271.171416)
		(mid 88.580976 -271.095661)
		(end 88.862408 -271.171416)
		(width 0.09525)
		(layer "In2.Cu")
		(net "M_C_CPU1_SB_DQS_DP<9>")
	)
	(arc
		(start 82.659474 -271.171416)
		(mid 82.940906 -271.095661)
		(end 83.222338 -271.171416)
		(width 0.09525)
		(layer "In2.Cu")
		(net "M_C_CPU1_SB_DQS_DP<9>")
	)
	(arc
		(start 78.901036 -271.17167)
		(mid 79.169581 -271.095177)
		(end 79.441802 -271.157446)
		(width 0.09525)
		(layer "In2.Cu")
		(net "M_C_CPU1_SB_DQS_DP<9>")
	)
	(arc
		(start 84.162392 -271.171416)
		(mid 84.346167 -271.222188)
		(end 84.5312 -271.176242)
		(width 0.09525)
		(layer "In2.Cu")
		(net "M_C_CPU1_SB_DQS_DP<9>")
	)
	(segment
		(start 96.097852 -291.64026)
		(end 95.631 -291.906198)
		(width 0.12954)
		(layer "F.Cu")
		(net "M_C_CPU1_SB_DQS_DP<8>")
	)
	(segment
		(start 77.507846 -295.726866)
		(end 77.507846 -294.551354)
		(width 0.09525)
		(layer "In2.Cu")
		(net "M_C_CPU1_SB_DQS_DP<8>")
	)
	(segment
		(start 56.54675 -315.01334)
		(end 57.04713 -315.01334)
		(width 0.16002)
		(layer "In2.Cu")
		(net "M_C_CPU1_SB_DQS_DP<8>")
	)
	(segment
		(start 48.98771 -315.0362)
		(end 49.47793 -315.0362)
		(width 0.16002)
		(layer "In2.Cu")
		(net "M_C_CPU1_SB_DQS_DP<8>")
	)
	(segment
		(start 84.5312 -291.576252)
		(end 84.539582 -291.581078)
		(width 0.09525)
		(layer "In2.Cu")
		(net "M_C_CPU1_SB_DQS_DP<8>")
	)
	(segment
		(start 81.342484 -291.581078)
		(end 81.350866 -291.576252)
		(width 0.09525)
		(layer "In2.Cu")
		(net "M_C_CPU1_SB_DQS_DP<8>")
	)
	(segment
		(start 86.0425 -291.581078)
		(end 86.050882 -291.576252)
		(width 0.09525)
		(layer "In2.Cu")
		(net "M_C_CPU1_SB_DQS_DP<8>")
	)
	(segment
		(start 46.049184 -314.769754)
		(end 46.639988 -315.360558)
		(width 0.16002)
		(layer "In2.Cu")
		(net "M_C_CPU1_SB_DQS_DP<8>")
	)
	(segment
		(start 89.802462 -291.581078)
		(end 89.810844 -291.576252)
		(width 0.09525)
		(layer "In2.Cu")
		(net "M_C_CPU1_SB_DQS_DP<8>")
	)
	(segment
		(start 83.591146 -291.576252)
		(end 83.599528 -291.581078)
		(width 0.09525)
		(layer "In2.Cu")
		(net "M_C_CPU1_SB_DQS_DP<8>")
	)
	(segment
		(start 42.032428 -314.361576)
		(end 42.231564 -314.16244)
		(width 0.16002)
		(layer "In2.Cu")
		(net "M_C_CPU1_SB_DQS_DP<8>")
	)
	(segment
		(start 92.991178 -291.576252)
		(end 92.99956 -291.581078)
		(width 0.09525)
		(layer "In2.Cu")
		(net "M_C_CPU1_SB_DQS_DP<8>")
	)
	(segment
		(start 43.106848 -314.16244)
		(end 43.714162 -314.769754)
		(width 0.16002)
		(layer "In2.Cu")
		(net "M_C_CPU1_SB_DQS_DP<8>")
	)
	(segment
		(start 42.231564 -314.16244)
		(end 43.106848 -314.16244)
		(width 0.16002)
		(layer "In2.Cu")
		(net "M_C_CPU1_SB_DQS_DP<8>")
	)
	(segment
		(start 95.442532 -291.581078)
		(end 95.450914 -291.576252)
		(width 0.09525)
		(layer "In2.Cu")
		(net "M_C_CPU1_SB_DQS_DP<8>")
	)
	(segment
		(start 56.22671 -315.33338)
		(end 56.54675 -315.01334)
		(width 0.16002)
		(layer "In2.Cu")
		(net "M_C_CPU1_SB_DQS_DP<8>")
	)
	(segment
		(start 49.47793 -315.0362)
		(end 50.33137 -314.18276)
		(width 0.16002)
		(layer "In2.Cu")
		(net "M_C_CPU1_SB_DQS_DP<8>")
	)
	(segment
		(start 77.566774 -295.785794)
		(end 77.507846 -295.726866)
		(width 0.09525)
		(layer "In2.Cu")
		(net "M_C_CPU1_SB_DQS_DP<8>")
	)
	(segment
		(start 51.03495 -314.52312)
		(end 53.38699 -314.52312)
		(width 0.16002)
		(layer "In2.Cu")
		(net "M_C_CPU1_SB_DQS_DP<8>")
	)
	(segment
		(start 78.535022 -293.193978)
		(end 78.535022 -293.19347)
		(width 0.09525)
		(layer "In2.Cu")
		(net "M_C_CPU1_SB_DQS_DP<8>")
	)
	(segment
		(start 79.46898 -291.995352)
		(end 79.807562 -291.65677)
		(width 0.09525)
		(layer "In2.Cu")
		(net "M_C_CPU1_SB_DQS_DP<8>")
	)
	(segment
		(start 57.849262 -314.211208)
		(end 58.253376 -314.211208)
		(width 0.16002)
		(layer "In2.Cu")
		(net "M_C_CPU1_SB_DQS_DP<8>")
	)
	(segment
		(start 90.742516 -291.581078)
		(end 90.750898 -291.576252)
		(width 0.09525)
		(layer "In2.Cu")
		(net "M_C_CPU1_SB_DQS_DP<8>")
	)
	(segment
		(start 85.102446 -291.581078)
		(end 85.110828 -291.576252)
		(width 0.09525)
		(layer "In2.Cu")
		(net "M_C_CPU1_SB_DQS_DP<8>")
	)
	(segment
		(start 57.04713 -315.01334)
		(end 57.849262 -314.211208)
		(width 0.16002)
		(layer "In2.Cu")
		(net "M_C_CPU1_SB_DQS_DP<8>")
	)
	(segment
		(start 77.507846 -294.551354)
		(end 78.333346 -293.725854)
		(width 0.09525)
		(layer "In2.Cu")
		(net "M_C_CPU1_SB_DQS_DP<8>")
	)
	(segment
		(start 58.511948 -314.46978)
		(end 62.462918 -314.46978)
		(width 0.16002)
		(layer "In2.Cu")
		(net "M_C_CPU1_SB_DQS_DP<8>")
	)
	(segment
		(start 79.807562 -291.65677)
		(end 80.121252 -291.65677)
		(width 0.09525)
		(layer "In2.Cu")
		(net "M_C_CPU1_SB_DQS_DP<8>")
	)
	(segment
		(start 50.33137 -314.18276)
		(end 50.69459 -314.18276)
		(width 0.16002)
		(layer "In2.Cu")
		(net "M_C_CPU1_SB_DQS_DP<8>")
	)
	(segment
		(start 78.333346 -293.725854)
		(end 78.333346 -293.52621)
		(width 0.09525)
		(layer "In2.Cu")
		(net "M_C_CPU1_SB_DQS_DP<8>")
	)
	(segment
		(start 54.19725 -315.33338)
		(end 56.22671 -315.33338)
		(width 0.16002)
		(layer "In2.Cu")
		(net "M_C_CPU1_SB_DQS_DP<8>")
	)
	(segment
		(start 94.502478 -291.581078)
		(end 94.51086 -291.576252)
		(width 0.09525)
		(layer "In2.Cu")
		(net "M_C_CPU1_SB_DQS_DP<8>")
	)
	(segment
		(start 78.966822 -292.453568)
		(end 79.156306 -292.262052)
		(width 0.09525)
		(layer "In2.Cu")
		(net "M_C_CPU1_SB_DQS_DP<8>")
	)
	(segment
		(start 40.23995 -314.635388)
		(end 40.513762 -314.361576)
		(width 0.16002)
		(layer "In2.Cu")
		(net "M_C_CPU1_SB_DQS_DP<8>")
	)
	(segment
		(start 65.887092 -311.045606)
		(end 67.185032 -311.045606)
		(width 0.16002)
		(layer "In2.Cu")
		(net "M_C_CPU1_SB_DQS_DP<8>")
	)
	(segment
		(start 50.69459 -314.18276)
		(end 51.03495 -314.52312)
		(width 0.16002)
		(layer "In2.Cu")
		(net "M_C_CPU1_SB_DQS_DP<8>")
	)
	(segment
		(start 48.663352 -315.360558)
		(end 48.98771 -315.0362)
		(width 0.16002)
		(layer "In2.Cu")
		(net "M_C_CPU1_SB_DQS_DP<8>")
	)
	(segment
		(start 40.513762 -314.361576)
		(end 42.032428 -314.361576)
		(width 0.16002)
		(layer "In2.Cu")
		(net "M_C_CPU1_SB_DQS_DP<8>")
	)
	(segment
		(start 80.771238 -291.576252)
		(end 80.77962 -291.581078)
		(width 0.09525)
		(layer "In2.Cu")
		(net "M_C_CPU1_SB_DQS_DP<8>")
	)
	(segment
		(start 43.714162 -314.769754)
		(end 46.049184 -314.769754)
		(width 0.16002)
		(layer "In2.Cu")
		(net "M_C_CPU1_SB_DQS_DP<8>")
	)
	(segment
		(start 93.931232 -291.576252)
		(end 93.939614 -291.581078)
		(width 0.09525)
		(layer "In2.Cu")
		(net "M_C_CPU1_SB_DQS_DP<8>")
	)
	(segment
		(start 58.253376 -314.211208)
		(end 58.511948 -314.46978)
		(width 0.16002)
		(layer "In2.Cu")
		(net "M_C_CPU1_SB_DQS_DP<8>")
	)
	(segment
		(start 95.784924 -291.640768)
		(end 95.631 -291.906198)
		(width 0.09525)
		(layer "In2.Cu")
		(net "M_C_CPU1_SB_DQS_DP<8>")
	)
	(segment
		(start 95.761556 -291.5539)
		(end 95.784924 -291.640768)
		(width 0.09525)
		(layer "In2.Cu")
		(net "M_C_CPU1_SB_DQS_DP<8>")
	)
	(segment
		(start 78.490064 -293.219886)
		(end 78.522576 -293.20109)
		(width 0.09525)
		(layer "In2.Cu")
		(net "M_C_CPU1_SB_DQS_DP<8>")
	)
	(segment
		(start 77.566774 -300.663864)
		(end 77.566774 -295.809416)
		(width 0.16002)
		(layer "In2.Cu")
		(net "M_C_CPU1_SB_DQS_DP<8>")
	)
	(segment
		(start 88.291162 -291.576252)
		(end 88.299544 -291.581078)
		(width 0.09525)
		(layer "In2.Cu")
		(net "M_C_CPU1_SB_DQS_DP<8>")
	)
	(segment
		(start 53.38699 -314.52312)
		(end 54.19725 -315.33338)
		(width 0.16002)
		(layer "In2.Cu")
		(net "M_C_CPU1_SB_DQS_DP<8>")
	)
	(segment
		(start 78.522576 -293.20109)
		(end 78.535022 -293.193978)
		(width 0.09525)
		(layer "In2.Cu")
		(net "M_C_CPU1_SB_DQS_DP<8>")
	)
	(segment
		(start 62.462918 -314.46978)
		(end 65.887092 -311.045606)
		(width 0.16002)
		(layer "In2.Cu")
		(net "M_C_CPU1_SB_DQS_DP<8>")
	)
	(segment
		(start 46.639988 -315.360558)
		(end 48.663352 -315.360558)
		(width 0.16002)
		(layer "In2.Cu")
		(net "M_C_CPU1_SB_DQS_DP<8>")
	)
	(segment
		(start 67.185032 -311.045606)
		(end 77.566774 -300.663864)
		(width 0.16002)
		(layer "In2.Cu")
		(net "M_C_CPU1_SB_DQS_DP<8>")
	)
	(segment
		(start 77.566774 -295.809416)
		(end 77.566774 -295.785794)
		(width 0.09525)
		(layer "In2.Cu")
		(net "M_C_CPU1_SB_DQS_DP<8>")
	)
	(segment
		(start 89.231216 -291.576252)
		(end 89.239598 -291.581078)
		(width 0.09525)
		(layer "In2.Cu")
		(net "M_C_CPU1_SB_DQS_DP<8>")
	)
	(arc
		(start 88.299544 -291.581078)
		(mid 88.580976 -291.656833)
		(end 88.862408 -291.581078)
		(width 0.09525)
		(layer "In2.Cu")
		(net "M_C_CPU1_SB_DQS_DP<8>")
	)
	(arc
		(start 95.450914 -291.576252)
		(mid 95.603809 -291.531424)
		(end 95.761556 -291.5539)
		(width 0.09525)
		(layer "In2.Cu")
		(net "M_C_CPU1_SB_DQS_DP<8>")
	)
	(arc
		(start 81.719674 -291.581078)
		(mid 81.993828 -291.656786)
		(end 82.269838 -291.58819)
		(width 0.09525)
		(layer "In2.Cu")
		(net "M_C_CPU1_SB_DQS_DP<8>")
	)
	(arc
		(start 87.922354 -291.581078)
		(mid 88.106129 -291.530306)
		(end 88.291162 -291.576252)
		(width 0.09525)
		(layer "In2.Cu")
		(net "M_C_CPU1_SB_DQS_DP<8>")
	)
	(arc
		(start 82.282538 -291.581078)
		(mid 82.471006 -291.530401)
		(end 82.659474 -291.581078)
		(width 0.09525)
		(layer "In2.Cu")
		(net "M_C_CPU1_SB_DQS_DP<8>")
	)
	(arc
		(start 91.119706 -291.581078)
		(mid 91.39386 -291.656786)
		(end 91.66987 -291.58819)
		(width 0.09525)
		(layer "In2.Cu")
		(net "M_C_CPU1_SB_DQS_DP<8>")
	)
	(arc
		(start 78.64983 -293.101776)
		(mid 78.749162 -292.956478)
		(end 78.798674 -292.787578)
		(width 0.09525)
		(layer "In2.Cu")
		(net "M_C_CPU1_SB_DQS_DP<8>")
	)
	(arc
		(start 79.29118 -292.146736)
		(mid 79.383123 -292.074619)
		(end 79.46898 -291.995352)
		(width 0.09525)
		(layer "In2.Cu")
		(net "M_C_CPU1_SB_DQS_DP<8>")
	)
	(arc
		(start 85.110828 -291.576252)
		(mid 85.29586 -291.530338)
		(end 85.479636 -291.581078)
		(width 0.09525)
		(layer "In2.Cu")
		(net "M_C_CPU1_SB_DQS_DP<8>")
	)
	(arc
		(start 89.239598 -291.581078)
		(mid 89.52103 -291.656833)
		(end 89.802462 -291.581078)
		(width 0.09525)
		(layer "In2.Cu")
		(net "M_C_CPU1_SB_DQS_DP<8>")
	)
	(arc
		(start 86.969854 -291.58819)
		(mid 86.976228 -291.584677)
		(end 86.982554 -291.581078)
		(width 0.09525)
		(layer "In2.Cu")
		(net "M_C_CPU1_SB_DQS_DP<8>")
	)
	(arc
		(start 78.87335 -292.58133)
		(mid 78.915324 -292.513966)
		(end 78.966822 -292.453568)
		(width 0.09525)
		(layer "In2.Cu")
		(net "M_C_CPU1_SB_DQS_DP<8>")
	)
	(arc
		(start 83.599528 -291.581078)
		(mid 83.88096 -291.656833)
		(end 84.162392 -291.581078)
		(width 0.09525)
		(layer "In2.Cu")
		(net "M_C_CPU1_SB_DQS_DP<8>")
	)
	(arc
		(start 79.156306 -292.262052)
		(mid 79.184521 -292.234609)
		(end 79.21371 -292.208204)
		(width 0.09525)
		(layer "In2.Cu")
		(net "M_C_CPU1_SB_DQS_DP<8>")
	)
	(arc
		(start 87.35949 -291.581078)
		(mid 87.640922 -291.656833)
		(end 87.922354 -291.581078)
		(width 0.09525)
		(layer "In2.Cu")
		(net "M_C_CPU1_SB_DQS_DP<8>")
	)
	(arc
		(start 80.40243 -291.581078)
		(mid 80.586205 -291.530306)
		(end 80.771238 -291.576252)
		(width 0.09525)
		(layer "In2.Cu")
		(net "M_C_CPU1_SB_DQS_DP<8>")
	)
	(arc
		(start 84.162392 -291.581078)
		(mid 84.346167 -291.530306)
		(end 84.5312 -291.576252)
		(width 0.09525)
		(layer "In2.Cu")
		(net "M_C_CPU1_SB_DQS_DP<8>")
	)
	(arc
		(start 92.059506 -291.581078)
		(mid 92.340938 -291.656833)
		(end 92.62237 -291.581078)
		(width 0.09525)
		(layer "In2.Cu")
		(net "M_C_CPU1_SB_DQS_DP<8>")
	)
	(arc
		(start 91.68257 -291.581078)
		(mid 91.871038 -291.530401)
		(end 92.059506 -291.581078)
		(width 0.09525)
		(layer "In2.Cu")
		(net "M_C_CPU1_SB_DQS_DP<8>")
	)
	(arc
		(start 90.750898 -291.576252)
		(mid 90.93593 -291.530338)
		(end 91.119706 -291.581078)
		(width 0.09525)
		(layer "In2.Cu")
		(net "M_C_CPU1_SB_DQS_DP<8>")
	)
	(arc
		(start 78.535022 -293.19347)
		(mid 78.595692 -293.151712)
		(end 78.64983 -293.101776)
		(width 0.09525)
		(layer "In2.Cu")
		(net "M_C_CPU1_SB_DQS_DP<8>")
	)
	(arc
		(start 86.982554 -291.581078)
		(mid 87.171022 -291.530401)
		(end 87.35949 -291.581078)
		(width 0.09525)
		(layer "In2.Cu")
		(net "M_C_CPU1_SB_DQS_DP<8>")
	)
	(arc
		(start 94.51086 -291.576252)
		(mid 94.695892 -291.530338)
		(end 94.879668 -291.581078)
		(width 0.09525)
		(layer "In2.Cu")
		(net "M_C_CPU1_SB_DQS_DP<8>")
	)
	(arc
		(start 81.350866 -291.576252)
		(mid 81.535898 -291.530338)
		(end 81.719674 -291.581078)
		(width 0.09525)
		(layer "In2.Cu")
		(net "M_C_CPU1_SB_DQS_DP<8>")
	)
	(arc
		(start 93.939614 -291.581078)
		(mid 94.221046 -291.656833)
		(end 94.502478 -291.581078)
		(width 0.09525)
		(layer "In2.Cu")
		(net "M_C_CPU1_SB_DQS_DP<8>")
	)
	(arc
		(start 84.539582 -291.581078)
		(mid 84.821014 -291.656833)
		(end 85.102446 -291.581078)
		(width 0.09525)
		(layer "In2.Cu")
		(net "M_C_CPU1_SB_DQS_DP<8>")
	)
	(arc
		(start 86.41969 -291.581078)
		(mid 86.693844 -291.656786)
		(end 86.969854 -291.58819)
		(width 0.09525)
		(layer "In2.Cu")
		(net "M_C_CPU1_SB_DQS_DP<8>")
	)
	(arc
		(start 90.179652 -291.581078)
		(mid 90.453663 -291.65666)
		(end 90.729562 -291.58819)
		(width 0.09525)
		(layer "In2.Cu")
		(net "M_C_CPU1_SB_DQS_DP<8>")
	)
	(arc
		(start 90.729562 -291.58819)
		(mid 90.736061 -291.584675)
		(end 90.742516 -291.581078)
		(width 0.09525)
		(layer "In2.Cu")
		(net "M_C_CPU1_SB_DQS_DP<8>")
	)
	(arc
		(start 86.050882 -291.576252)
		(mid 86.235914 -291.530338)
		(end 86.41969 -291.581078)
		(width 0.09525)
		(layer "In2.Cu")
		(net "M_C_CPU1_SB_DQS_DP<8>")
	)
	(arc
		(start 88.862408 -291.581078)
		(mid 89.046183 -291.530306)
		(end 89.231216 -291.576252)
		(width 0.09525)
		(layer "In2.Cu")
		(net "M_C_CPU1_SB_DQS_DP<8>")
	)
	(arc
		(start 85.479636 -291.581078)
		(mid 85.753647 -291.65666)
		(end 86.029546 -291.58819)
		(width 0.09525)
		(layer "In2.Cu")
		(net "M_C_CPU1_SB_DQS_DP<8>")
	)
	(arc
		(start 86.029546 -291.58819)
		(mid 86.036045 -291.584675)
		(end 86.0425 -291.581078)
		(width 0.09525)
		(layer "In2.Cu")
		(net "M_C_CPU1_SB_DQS_DP<8>")
	)
	(arc
		(start 83.222338 -291.581078)
		(mid 83.406113 -291.530306)
		(end 83.591146 -291.576252)
		(width 0.09525)
		(layer "In2.Cu")
		(net "M_C_CPU1_SB_DQS_DP<8>")
	)
	(arc
		(start 78.822296 -292.695122)
		(mid 78.844354 -292.642583)
		(end 78.868524 -292.590982)
		(width 0.09525)
		(layer "In2.Cu")
		(net "M_C_CPU1_SB_DQS_DP<8>")
	)
	(arc
		(start 95.429578 -291.58819)
		(mid 95.436077 -291.584675)
		(end 95.442532 -291.581078)
		(width 0.09525)
		(layer "In2.Cu")
		(net "M_C_CPU1_SB_DQS_DP<8>")
	)
	(arc
		(start 92.62237 -291.581078)
		(mid 92.806145 -291.530306)
		(end 92.991178 -291.576252)
		(width 0.09525)
		(layer "In2.Cu")
		(net "M_C_CPU1_SB_DQS_DP<8>")
	)
	(arc
		(start 89.810844 -291.576252)
		(mid 89.995876 -291.530338)
		(end 90.179652 -291.581078)
		(width 0.09525)
		(layer "In2.Cu")
		(net "M_C_CPU1_SB_DQS_DP<8>")
	)
	(arc
		(start 82.269838 -291.58819)
		(mid 82.276212 -291.584677)
		(end 82.282538 -291.581078)
		(width 0.09525)
		(layer "In2.Cu")
		(net "M_C_CPU1_SB_DQS_DP<8>")
	)
	(arc
		(start 79.21371 -292.208204)
		(mid 79.251739 -292.17658)
		(end 79.29118 -292.146736)
		(width 0.09525)
		(layer "In2.Cu")
		(net "M_C_CPU1_SB_DQS_DP<8>")
	)
	(arc
		(start 93.562424 -291.581078)
		(mid 93.746199 -291.530306)
		(end 93.931232 -291.576252)
		(width 0.09525)
		(layer "In2.Cu")
		(net "M_C_CPU1_SB_DQS_DP<8>")
	)
	(arc
		(start 82.659474 -291.581078)
		(mid 82.940906 -291.656833)
		(end 83.222338 -291.581078)
		(width 0.09525)
		(layer "In2.Cu")
		(net "M_C_CPU1_SB_DQS_DP<8>")
	)
	(arc
		(start 80.121252 -291.65677)
		(mid 80.266829 -291.637469)
		(end 80.40243 -291.581078)
		(width 0.09525)
		(layer "In2.Cu")
		(net "M_C_CPU1_SB_DQS_DP<8>")
	)
	(arc
		(start 78.868524 -292.590982)
		(mid 78.870913 -292.586144)
		(end 78.87335 -292.58133)
		(width 0.09525)
		(layer "In2.Cu")
		(net "M_C_CPU1_SB_DQS_DP<8>")
	)
	(arc
		(start 78.798674 -292.787578)
		(mid 78.807564 -292.740605)
		(end 78.822296 -292.695122)
		(width 0.09525)
		(layer "In2.Cu")
		(net "M_C_CPU1_SB_DQS_DP<8>")
	)
	(arc
		(start 94.879668 -291.581078)
		(mid 95.153679 -291.65666)
		(end 95.429578 -291.58819)
		(width 0.09525)
		(layer "In2.Cu")
		(net "M_C_CPU1_SB_DQS_DP<8>")
	)
	(arc
		(start 91.66987 -291.58819)
		(mid 91.676244 -291.584677)
		(end 91.68257 -291.581078)
		(width 0.09525)
		(layer "In2.Cu")
		(net "M_C_CPU1_SB_DQS_DP<8>")
	)
	(arc
		(start 92.99956 -291.581078)
		(mid 93.280992 -291.656833)
		(end 93.562424 -291.581078)
		(width 0.09525)
		(layer "In2.Cu")
		(net "M_C_CPU1_SB_DQS_DP<8>")
	)
	(arc
		(start 78.333346 -293.52621)
		(mid 78.374803 -293.35417)
		(end 78.490064 -293.219886)
		(width 0.09525)
		(layer "In2.Cu")
		(net "M_C_CPU1_SB_DQS_DP<8>")
	)
	(arc
		(start 80.77962 -291.581078)
		(mid 81.061052 -291.656833)
		(end 81.342484 -291.581078)
		(width 0.09525)
		(layer "In2.Cu")
		(net "M_C_CPU1_SB_DQS_DP<8>")
	)
	(segment
		(start 96.097852 -286.780478)
		(end 95.631 -287.046162)
		(width 0.12954)
		(layer "F.Cu")
		(net "M_C_CPU1_SB_DQS_DP<7>")
	)
	(segment
		(start 71.769986 -292.36289)
		(end 76.175362 -287.956752)
		(width 0.16002)
		(layer "In2.Cu")
		(net "M_C_CPU1_SB_DQS_DP<7>")
	)
	(segment
		(start 44.181522 -305.41976)
		(end 45.278548 -305.41976)
		(width 0.16002)
		(layer "In2.Cu")
		(net "M_C_CPU1_SB_DQS_DP<7>")
	)
	(segment
		(start 76.192126 -287.939988)
		(end 76.191872 -287.857184)
		(width 0.09525)
		(layer "In2.Cu")
		(net "M_C_CPU1_SB_DQS_DP<7>")
	)
	(segment
		(start 48.98771 -305.686206)
		(end 49.28362 -305.563524)
		(width 0.16002)
		(layer "In2.Cu")
		(net "M_C_CPU1_SB_DQS_DP<7>")
	)
	(segment
		(start 40.23995 -305.285394)
		(end 40.513762 -305.011582)
		(width 0.16002)
		(layer "In2.Cu")
		(net "M_C_CPU1_SB_DQS_DP<7>")
	)
	(segment
		(start 79.461614 -286.721042)
		(end 79.473552 -286.714184)
		(width 0.09525)
		(layer "In2.Cu")
		(net "M_C_CPU1_SB_DQS_DP<7>")
	)
	(segment
		(start 86.0425 -286.721042)
		(end 86.050882 -286.716216)
		(width 0.09525)
		(layer "In2.Cu")
		(net "M_C_CPU1_SB_DQS_DP<7>")
	)
	(segment
		(start 56.22671 -305.983386)
		(end 56.54675 -305.663346)
		(width 0.16002)
		(layer "In2.Cu")
		(net "M_C_CPU1_SB_DQS_DP<7>")
	)
	(segment
		(start 58.253376 -304.861214)
		(end 58.511948 -305.119786)
		(width 0.16002)
		(layer "In2.Cu")
		(net "M_C_CPU1_SB_DQS_DP<7>")
	)
	(segment
		(start 48.663352 -306.010564)
		(end 48.98771 -305.686206)
		(width 0.16002)
		(layer "In2.Cu")
		(net "M_C_CPU1_SB_DQS_DP<7>")
	)
	(segment
		(start 45.278548 -305.41976)
		(end 46.705012 -306.010564)
		(width 0.16002)
		(layer "In2.Cu")
		(net "M_C_CPU1_SB_DQS_DP<7>")
	)
	(segment
		(start 77.604366 -287.195514)
		(end 78.002638 -286.797242)
		(width 0.09525)
		(layer "In2.Cu")
		(net "M_C_CPU1_SB_DQS_DP<7>")
	)
	(segment
		(start 57.849262 -304.861214)
		(end 58.253376 -304.861214)
		(width 0.16002)
		(layer "In2.Cu")
		(net "M_C_CPU1_SB_DQS_DP<7>")
	)
	(segment
		(start 49.28362 -305.563524)
		(end 50.23866 -304.925476)
		(width 0.16002)
		(layer "In2.Cu")
		(net "M_C_CPU1_SB_DQS_DP<7>")
	)
	(segment
		(start 50.69459 -304.832766)
		(end 51.02225 -305.160426)
		(width 0.16002)
		(layer "In2.Cu")
		(net "M_C_CPU1_SB_DQS_DP<7>")
	)
	(segment
		(start 77.038962 -287.195514)
		(end 77.604366 -287.195514)
		(width 0.09525)
		(layer "In2.Cu")
		(net "M_C_CPU1_SB_DQS_DP<7>")
	)
	(segment
		(start 51.02225 -305.160426)
		(end 52.955698 -305.160426)
		(width 0.16002)
		(layer "In2.Cu")
		(net "M_C_CPU1_SB_DQS_DP<7>")
	)
	(segment
		(start 43.150028 -304.855626)
		(end 43.383708 -305.089306)
		(width 0.16002)
		(layer "In2.Cu")
		(net "M_C_CPU1_SB_DQS_DP<7>")
	)
	(segment
		(start 56.816498 -305.551586)
		(end 57.849262 -304.861214)
		(width 0.16002)
		(layer "In2.Cu")
		(net "M_C_CPU1_SB_DQS_DP<7>")
	)
	(segment
		(start 88.291162 -286.716216)
		(end 88.299544 -286.721042)
		(width 0.09525)
		(layer "In2.Cu")
		(net "M_C_CPU1_SB_DQS_DP<7>")
	)
	(segment
		(start 50.23866 -304.925476)
		(end 50.33137 -304.832766)
		(width 0.16002)
		(layer "In2.Cu")
		(net "M_C_CPU1_SB_DQS_DP<7>")
	)
	(segment
		(start 80.771238 -286.716216)
		(end 80.77962 -286.721042)
		(width 0.09525)
		(layer "In2.Cu")
		(net "M_C_CPU1_SB_DQS_DP<7>")
	)
	(segment
		(start 42.032428 -305.011582)
		(end 42.188384 -304.855626)
		(width 0.16002)
		(layer "In2.Cu")
		(net "M_C_CPU1_SB_DQS_DP<7>")
	)
	(segment
		(start 92.991178 -286.716216)
		(end 92.99956 -286.721042)
		(width 0.09525)
		(layer "In2.Cu")
		(net "M_C_CPU1_SB_DQS_DP<7>")
	)
	(segment
		(start 95.784924 -286.780732)
		(end 95.631 -287.046162)
		(width 0.09525)
		(layer "In2.Cu")
		(net "M_C_CPU1_SB_DQS_DP<7>")
	)
	(segment
		(start 78.002638 -286.797242)
		(end 78.240128 -286.797242)
		(width 0.09525)
		(layer "In2.Cu")
		(net "M_C_CPU1_SB_DQS_DP<7>")
	)
	(segment
		(start 93.931232 -286.716216)
		(end 93.939614 -286.721042)
		(width 0.09525)
		(layer "In2.Cu")
		(net "M_C_CPU1_SB_DQS_DP<7>")
	)
	(segment
		(start 83.591146 -286.716216)
		(end 83.599528 -286.721042)
		(width 0.09525)
		(layer "In2.Cu")
		(net "M_C_CPU1_SB_DQS_DP<7>")
	)
	(segment
		(start 54.19725 -305.983386)
		(end 56.22671 -305.983386)
		(width 0.16002)
		(layer "In2.Cu")
		(net "M_C_CPU1_SB_DQS_DP<7>")
	)
	(segment
		(start 78.899258 -286.721296)
		(end 78.904846 -286.724598)
		(width 0.09525)
		(layer "In2.Cu")
		(net "M_C_CPU1_SB_DQS_DP<7>")
	)
	(segment
		(start 95.761556 -286.693864)
		(end 95.784924 -286.780732)
		(width 0.09525)
		(layer "In2.Cu")
		(net "M_C_CPU1_SB_DQS_DP<7>")
	)
	(segment
		(start 50.33137 -304.832766)
		(end 50.69459 -304.832766)
		(width 0.16002)
		(layer "In2.Cu")
		(net "M_C_CPU1_SB_DQS_DP<7>")
	)
	(segment
		(start 81.342484 -286.721042)
		(end 81.350866 -286.716216)
		(width 0.09525)
		(layer "In2.Cu")
		(net "M_C_CPU1_SB_DQS_DP<7>")
	)
	(segment
		(start 71.769986 -295.616376)
		(end 71.769986 -292.36289)
		(width 0.16002)
		(layer "In2.Cu")
		(net "M_C_CPU1_SB_DQS_DP<7>")
	)
	(segment
		(start 52.955698 -305.160426)
		(end 53.6702 -305.456336)
		(width 0.16002)
		(layer "In2.Cu")
		(net "M_C_CPU1_SB_DQS_DP<7>")
	)
	(segment
		(start 89.231216 -286.716216)
		(end 89.239598 -286.721042)
		(width 0.09525)
		(layer "In2.Cu")
		(net "M_C_CPU1_SB_DQS_DP<7>")
	)
	(segment
		(start 90.742516 -286.721042)
		(end 90.750898 -286.716216)
		(width 0.09525)
		(layer "In2.Cu")
		(net "M_C_CPU1_SB_DQS_DP<7>")
	)
	(segment
		(start 42.188384 -304.855626)
		(end 43.150028 -304.855626)
		(width 0.16002)
		(layer "In2.Cu")
		(net "M_C_CPU1_SB_DQS_DP<7>")
	)
	(segment
		(start 40.513762 -305.011582)
		(end 42.032428 -305.011582)
		(width 0.16002)
		(layer "In2.Cu")
		(net "M_C_CPU1_SB_DQS_DP<7>")
	)
	(segment
		(start 85.102446 -286.721042)
		(end 85.110828 -286.716216)
		(width 0.09525)
		(layer "In2.Cu")
		(net "M_C_CPU1_SB_DQS_DP<7>")
	)
	(segment
		(start 62.266576 -305.119786)
		(end 71.769986 -295.616376)
		(width 0.16002)
		(layer "In2.Cu")
		(net "M_C_CPU1_SB_DQS_DP<7>")
	)
	(segment
		(start 56.54675 -305.663346)
		(end 56.816498 -305.551586)
		(width 0.16002)
		(layer "In2.Cu")
		(net "M_C_CPU1_SB_DQS_DP<7>")
	)
	(segment
		(start 84.5312 -286.716216)
		(end 84.539582 -286.721042)
		(width 0.09525)
		(layer "In2.Cu")
		(net "M_C_CPU1_SB_DQS_DP<7>")
	)
	(segment
		(start 95.442532 -286.721042)
		(end 95.450914 -286.716216)
		(width 0.09525)
		(layer "In2.Cu")
		(net "M_C_CPU1_SB_DQS_DP<7>")
	)
	(segment
		(start 58.511948 -305.119786)
		(end 62.266576 -305.119786)
		(width 0.16002)
		(layer "In2.Cu")
		(net "M_C_CPU1_SB_DQS_DP<7>")
	)
	(segment
		(start 80.387698 -286.729678)
		(end 80.40243 -286.721042)
		(width 0.09525)
		(layer "In2.Cu")
		(net "M_C_CPU1_SB_DQS_DP<7>")
	)
	(segment
		(start 76.191872 -287.857184)
		(end 76.722224 -287.326832)
		(width 0.09525)
		(layer "In2.Cu")
		(net "M_C_CPU1_SB_DQS_DP<7>")
	)
	(segment
		(start 46.705012 -306.010564)
		(end 48.663352 -306.010564)
		(width 0.16002)
		(layer "In2.Cu")
		(net "M_C_CPU1_SB_DQS_DP<7>")
	)
	(segment
		(start 53.6702 -305.456336)
		(end 54.19725 -305.983386)
		(width 0.16002)
		(layer "In2.Cu")
		(net "M_C_CPU1_SB_DQS_DP<7>")
	)
	(segment
		(start 43.383708 -305.089306)
		(end 44.181522 -305.41976)
		(width 0.16002)
		(layer "In2.Cu")
		(net "M_C_CPU1_SB_DQS_DP<7>")
	)
	(segment
		(start 78.88097 -286.710882)
		(end 78.899258 -286.721296)
		(width 0.09525)
		(layer "In2.Cu")
		(net "M_C_CPU1_SB_DQS_DP<7>")
	)
	(segment
		(start 76.175362 -287.956752)
		(end 76.192126 -287.939988)
		(width 0.09525)
		(layer "In2.Cu")
		(net "M_C_CPU1_SB_DQS_DP<7>")
	)
	(segment
		(start 94.502478 -286.721042)
		(end 94.51086 -286.716216)
		(width 0.09525)
		(layer "In2.Cu")
		(net "M_C_CPU1_SB_DQS_DP<7>")
	)
	(segment
		(start 89.802462 -286.721042)
		(end 89.810844 -286.716216)
		(width 0.09525)
		(layer "In2.Cu")
		(net "M_C_CPU1_SB_DQS_DP<7>")
	)
	(arc
		(start 92.059506 -286.721042)
		(mid 92.340938 -286.796831)
		(end 92.62237 -286.721042)
		(width 0.09525)
		(layer "In2.Cu")
		(net "M_C_CPU1_SB_DQS_DP<7>")
	)
	(arc
		(start 83.599528 -286.721042)
		(mid 83.88096 -286.796831)
		(end 84.162392 -286.721042)
		(width 0.09525)
		(layer "In2.Cu")
		(net "M_C_CPU1_SB_DQS_DP<7>")
	)
	(arc
		(start 93.939614 -286.721042)
		(mid 94.221046 -286.796831)
		(end 94.502478 -286.721042)
		(width 0.09525)
		(layer "In2.Cu")
		(net "M_C_CPU1_SB_DQS_DP<7>")
	)
	(arc
		(start 79.839058 -286.721042)
		(mid 80.11224 -286.797018)
		(end 80.387698 -286.729678)
		(width 0.09525)
		(layer "In2.Cu")
		(net "M_C_CPU1_SB_DQS_DP<7>")
	)
	(arc
		(start 84.539582 -286.721042)
		(mid 84.821014 -286.796831)
		(end 85.102446 -286.721042)
		(width 0.09525)
		(layer "In2.Cu")
		(net "M_C_CPU1_SB_DQS_DP<7>")
	)
	(arc
		(start 79.473552 -286.714184)
		(mid 79.657187 -286.670234)
		(end 79.839058 -286.721042)
		(width 0.09525)
		(layer "In2.Cu")
		(net "M_C_CPU1_SB_DQS_DP<7>")
	)
	(arc
		(start 81.719674 -286.721042)
		(mid 82.001106 -286.796831)
		(end 82.282538 -286.721042)
		(width 0.09525)
		(layer "In2.Cu")
		(net "M_C_CPU1_SB_DQS_DP<7>")
	)
	(arc
		(start 93.562424 -286.721042)
		(mid 93.746199 -286.67027)
		(end 93.931232 -286.716216)
		(width 0.09525)
		(layer "In2.Cu")
		(net "M_C_CPU1_SB_DQS_DP<7>")
	)
	(arc
		(start 85.479636 -286.721042)
		(mid 85.761068 -286.796831)
		(end 86.0425 -286.721042)
		(width 0.09525)
		(layer "In2.Cu")
		(net "M_C_CPU1_SB_DQS_DP<7>")
	)
	(arc
		(start 84.162392 -286.721042)
		(mid 84.346167 -286.67027)
		(end 84.5312 -286.716216)
		(width 0.09525)
		(layer "In2.Cu")
		(net "M_C_CPU1_SB_DQS_DP<7>")
	)
	(arc
		(start 94.879668 -286.721042)
		(mid 95.1611 -286.796831)
		(end 95.442532 -286.721042)
		(width 0.09525)
		(layer "In2.Cu")
		(net "M_C_CPU1_SB_DQS_DP<7>")
	)
	(arc
		(start 87.35949 -286.721042)
		(mid 87.640922 -286.796831)
		(end 87.922354 -286.721042)
		(width 0.09525)
		(layer "In2.Cu")
		(net "M_C_CPU1_SB_DQS_DP<7>")
	)
	(arc
		(start 89.239598 -286.721042)
		(mid 89.52103 -286.796831)
		(end 89.802462 -286.721042)
		(width 0.09525)
		(layer "In2.Cu")
		(net "M_C_CPU1_SB_DQS_DP<7>")
	)
	(arc
		(start 92.99956 -286.721042)
		(mid 93.280992 -286.796831)
		(end 93.562424 -286.721042)
		(width 0.09525)
		(layer "In2.Cu")
		(net "M_C_CPU1_SB_DQS_DP<7>")
	)
	(arc
		(start 89.810844 -286.716216)
		(mid 89.995876 -286.670302)
		(end 90.179652 -286.721042)
		(width 0.09525)
		(layer "In2.Cu")
		(net "M_C_CPU1_SB_DQS_DP<7>")
	)
	(arc
		(start 86.982554 -286.721042)
		(mid 87.171022 -286.670365)
		(end 87.35949 -286.721042)
		(width 0.09525)
		(layer "In2.Cu")
		(net "M_C_CPU1_SB_DQS_DP<7>")
	)
	(arc
		(start 76.722224 -287.326832)
		(mid 76.86753 -287.229649)
		(end 77.038962 -287.195514)
		(width 0.09525)
		(layer "In2.Cu")
		(net "M_C_CPU1_SB_DQS_DP<7>")
	)
	(arc
		(start 86.41969 -286.721042)
		(mid 86.701122 -286.796831)
		(end 86.982554 -286.721042)
		(width 0.09525)
		(layer "In2.Cu")
		(net "M_C_CPU1_SB_DQS_DP<7>")
	)
	(arc
		(start 88.862408 -286.721042)
		(mid 89.046183 -286.67027)
		(end 89.231216 -286.716216)
		(width 0.09525)
		(layer "In2.Cu")
		(net "M_C_CPU1_SB_DQS_DP<7>")
	)
	(arc
		(start 78.522068 -286.721042)
		(mid 78.70022 -286.670386)
		(end 78.88097 -286.710882)
		(width 0.09525)
		(layer "In2.Cu")
		(net "M_C_CPU1_SB_DQS_DP<7>")
	)
	(arc
		(start 91.119706 -286.721042)
		(mid 91.401138 -286.796831)
		(end 91.68257 -286.721042)
		(width 0.09525)
		(layer "In2.Cu")
		(net "M_C_CPU1_SB_DQS_DP<7>")
	)
	(arc
		(start 90.750898 -286.716216)
		(mid 90.93593 -286.670302)
		(end 91.119706 -286.721042)
		(width 0.09525)
		(layer "In2.Cu")
		(net "M_C_CPU1_SB_DQS_DP<7>")
	)
	(arc
		(start 88.299544 -286.721042)
		(mid 88.580976 -286.796831)
		(end 88.862408 -286.721042)
		(width 0.09525)
		(layer "In2.Cu")
		(net "M_C_CPU1_SB_DQS_DP<7>")
	)
	(arc
		(start 78.240128 -286.797242)
		(mid 78.386151 -286.77783)
		(end 78.522068 -286.721042)
		(width 0.09525)
		(layer "In2.Cu")
		(net "M_C_CPU1_SB_DQS_DP<7>")
	)
	(arc
		(start 80.40243 -286.721042)
		(mid 80.586205 -286.67027)
		(end 80.771238 -286.716216)
		(width 0.09525)
		(layer "In2.Cu")
		(net "M_C_CPU1_SB_DQS_DP<7>")
	)
	(arc
		(start 91.68257 -286.721042)
		(mid 91.871038 -286.670365)
		(end 92.059506 -286.721042)
		(width 0.09525)
		(layer "In2.Cu")
		(net "M_C_CPU1_SB_DQS_DP<7>")
	)
	(arc
		(start 95.450914 -286.716216)
		(mid 95.603809 -286.671388)
		(end 95.761556 -286.693864)
		(width 0.09525)
		(layer "In2.Cu")
		(net "M_C_CPU1_SB_DQS_DP<7>")
	)
	(arc
		(start 83.222338 -286.721042)
		(mid 83.406113 -286.67027)
		(end 83.591146 -286.716216)
		(width 0.09525)
		(layer "In2.Cu")
		(net "M_C_CPU1_SB_DQS_DP<7>")
	)
	(arc
		(start 80.77962 -286.721042)
		(mid 81.061052 -286.796831)
		(end 81.342484 -286.721042)
		(width 0.09525)
		(layer "In2.Cu")
		(net "M_C_CPU1_SB_DQS_DP<7>")
	)
	(arc
		(start 82.659474 -286.721042)
		(mid 82.940906 -286.796831)
		(end 83.222338 -286.721042)
		(width 0.09525)
		(layer "In2.Cu")
		(net "M_C_CPU1_SB_DQS_DP<7>")
	)
	(arc
		(start 85.110828 -286.716216)
		(mid 85.29586 -286.670302)
		(end 85.479636 -286.721042)
		(width 0.09525)
		(layer "In2.Cu")
		(net "M_C_CPU1_SB_DQS_DP<7>")
	)
	(arc
		(start 82.282538 -286.721042)
		(mid 82.471006 -286.670365)
		(end 82.659474 -286.721042)
		(width 0.09525)
		(layer "In2.Cu")
		(net "M_C_CPU1_SB_DQS_DP<7>")
	)
	(arc
		(start 92.62237 -286.721042)
		(mid 92.806145 -286.67027)
		(end 92.991178 -286.716216)
		(width 0.09525)
		(layer "In2.Cu")
		(net "M_C_CPU1_SB_DQS_DP<7>")
	)
	(arc
		(start 94.51086 -286.716216)
		(mid 94.695892 -286.670302)
		(end 94.879668 -286.721042)
		(width 0.09525)
		(layer "In2.Cu")
		(net "M_C_CPU1_SB_DQS_DP<7>")
	)
	(arc
		(start 81.350866 -286.716216)
		(mid 81.535898 -286.670302)
		(end 81.719674 -286.721042)
		(width 0.09525)
		(layer "In2.Cu")
		(net "M_C_CPU1_SB_DQS_DP<7>")
	)
	(arc
		(start 90.179652 -286.721042)
		(mid 90.461084 -286.796831)
		(end 90.742516 -286.721042)
		(width 0.09525)
		(layer "In2.Cu")
		(net "M_C_CPU1_SB_DQS_DP<7>")
	)
	(arc
		(start 87.922354 -286.721042)
		(mid 88.106129 -286.67027)
		(end 88.291162 -286.716216)
		(width 0.09525)
		(layer "In2.Cu")
		(net "M_C_CPU1_SB_DQS_DP<7>")
	)
	(arc
		(start 86.050882 -286.716216)
		(mid 86.235914 -286.670302)
		(end 86.41969 -286.721042)
		(width 0.09525)
		(layer "In2.Cu")
		(net "M_C_CPU1_SB_DQS_DP<7>")
	)
	(arc
		(start 78.904846 -286.724598)
		(mid 79.183711 -286.796879)
		(end 79.461614 -286.721042)
		(width 0.09525)
		(layer "In2.Cu")
		(net "M_C_CPU1_SB_DQS_DP<7>")
	)
	(segment
		(start 96.097852 -281.920442)
		(end 95.631 -282.18638)
		(width 0.12954)
		(layer "F.Cu")
		(net "M_C_CPU1_SB_DQS_DP<6>")
	)
	(segment
		(start 54.19725 -296.633392)
		(end 56.22671 -296.633392)
		(width 0.16002)
		(layer "In2.Cu")
		(net "M_C_CPU1_SB_DQS_DP<6>")
	)
	(segment
		(start 78.087728 -281.809698)
		(end 79.650082 -281.809698)
		(width 0.09525)
		(layer "In2.Cu")
		(net "M_C_CPU1_SB_DQS_DP<6>")
	)
	(segment
		(start 58.253376 -295.51122)
		(end 58.511948 -295.769792)
		(width 0.16002)
		(layer "In2.Cu")
		(net "M_C_CPU1_SB_DQS_DP<6>")
	)
	(segment
		(start 40.513762 -295.661588)
		(end 42.325036 -295.661588)
		(width 0.16002)
		(layer "In2.Cu")
		(net "M_C_CPU1_SB_DQS_DP<6>")
	)
	(segment
		(start 75.979528 -281.974544)
		(end 76.038456 -281.915616)
		(width 0.09525)
		(layer "In2.Cu")
		(net "M_C_CPU1_SB_DQS_DP<6>")
	)
	(segment
		(start 92.991178 -281.856434)
		(end 92.99956 -281.86126)
		(width 0.09525)
		(layer "In2.Cu")
		(net "M_C_CPU1_SB_DQS_DP<6>")
	)
	(segment
		(start 45.278548 -296.069766)
		(end 46.705012 -296.66057)
		(width 0.16002)
		(layer "In2.Cu")
		(net "M_C_CPU1_SB_DQS_DP<6>")
	)
	(segment
		(start 53.788818 -296.22496)
		(end 54.19725 -296.633392)
		(width 0.16002)
		(layer "In2.Cu")
		(net "M_C_CPU1_SB_DQS_DP<6>")
	)
	(segment
		(start 81.342484 -281.86126)
		(end 81.350866 -281.856434)
		(width 0.09525)
		(layer "In2.Cu")
		(net "M_C_CPU1_SB_DQS_DP<6>")
	)
	(segment
		(start 95.761556 -281.834082)
		(end 95.784924 -281.92095)
		(width 0.09525)
		(layer "In2.Cu")
		(net "M_C_CPU1_SB_DQS_DP<6>")
	)
	(segment
		(start 51.02225 -295.810432)
		(end 52.787804 -295.810432)
		(width 0.16002)
		(layer "In2.Cu")
		(net "M_C_CPU1_SB_DQS_DP<6>")
	)
	(segment
		(start 42.69486 -295.508426)
		(end 43.152822 -295.508426)
		(width 0.16002)
		(layer "In2.Cu")
		(net "M_C_CPU1_SB_DQS_DP<6>")
	)
	(segment
		(start 42.325036 -295.661588)
		(end 42.69486 -295.508426)
		(width 0.16002)
		(layer "In2.Cu")
		(net "M_C_CPU1_SB_DQS_DP<6>")
	)
	(segment
		(start 95.784924 -281.92095)
		(end 95.631 -282.18638)
		(width 0.09525)
		(layer "In2.Cu")
		(net "M_C_CPU1_SB_DQS_DP<6>")
	)
	(segment
		(start 49.162462 -296.263822)
		(end 50.33137 -295.482772)
		(width 0.16002)
		(layer "In2.Cu")
		(net "M_C_CPU1_SB_DQS_DP<6>")
	)
	(segment
		(start 48.663352 -296.66057)
		(end 48.98771 -296.336212)
		(width 0.16002)
		(layer "In2.Cu")
		(net "M_C_CPU1_SB_DQS_DP<6>")
	)
	(segment
		(start 93.931232 -281.856434)
		(end 93.939614 -281.86126)
		(width 0.09525)
		(layer "In2.Cu")
		(net "M_C_CPU1_SB_DQS_DP<6>")
	)
	(segment
		(start 56.816498 -296.201592)
		(end 57.849262 -295.51122)
		(width 0.16002)
		(layer "In2.Cu")
		(net "M_C_CPU1_SB_DQS_DP<6>")
	)
	(segment
		(start 80.771238 -281.856434)
		(end 80.77962 -281.86126)
		(width 0.09525)
		(layer "In2.Cu")
		(net "M_C_CPU1_SB_DQS_DP<6>")
	)
	(segment
		(start 85.102446 -281.86126)
		(end 85.110828 -281.856434)
		(width 0.09525)
		(layer "In2.Cu")
		(net "M_C_CPU1_SB_DQS_DP<6>")
	)
	(segment
		(start 89.231216 -281.856434)
		(end 89.239598 -281.86126)
		(width 0.09525)
		(layer "In2.Cu")
		(net "M_C_CPU1_SB_DQS_DP<6>")
	)
	(segment
		(start 66.287396 -289.841178)
		(end 74.15403 -281.974544)
		(width 0.16002)
		(layer "In2.Cu")
		(net "M_C_CPU1_SB_DQS_DP<6>")
	)
	(segment
		(start 56.54675 -296.313352)
		(end 56.816498 -296.201592)
		(width 0.16002)
		(layer "In2.Cu")
		(net "M_C_CPU1_SB_DQS_DP<6>")
	)
	(segment
		(start 44.149264 -296.069766)
		(end 45.278548 -296.069766)
		(width 0.16002)
		(layer "In2.Cu")
		(net "M_C_CPU1_SB_DQS_DP<6>")
	)
	(segment
		(start 94.502478 -281.86126)
		(end 94.51086 -281.856434)
		(width 0.09525)
		(layer "In2.Cu")
		(net "M_C_CPU1_SB_DQS_DP<6>")
	)
	(segment
		(start 95.442532 -281.86126)
		(end 95.450914 -281.856434)
		(width 0.09525)
		(layer "In2.Cu")
		(net "M_C_CPU1_SB_DQS_DP<6>")
	)
	(segment
		(start 84.5312 -281.856434)
		(end 84.539582 -281.86126)
		(width 0.09525)
		(layer "In2.Cu")
		(net "M_C_CPU1_SB_DQS_DP<6>")
	)
	(segment
		(start 48.98771 -296.336212)
		(end 49.162462 -296.263822)
		(width 0.16002)
		(layer "In2.Cu")
		(net "M_C_CPU1_SB_DQS_DP<6>")
	)
	(segment
		(start 80.387698 -281.869896)
		(end 80.40243 -281.86126)
		(width 0.09525)
		(layer "In2.Cu")
		(net "M_C_CPU1_SB_DQS_DP<6>")
	)
	(segment
		(start 76.038456 -281.915616)
		(end 77.98181 -281.915616)
		(width 0.09525)
		(layer "In2.Cu")
		(net "M_C_CPU1_SB_DQS_DP<6>")
	)
	(segment
		(start 43.152822 -295.508426)
		(end 43.406568 -295.762172)
		(width 0.16002)
		(layer "In2.Cu")
		(net "M_C_CPU1_SB_DQS_DP<6>")
	)
	(segment
		(start 46.705012 -296.66057)
		(end 48.663352 -296.66057)
		(width 0.16002)
		(layer "In2.Cu")
		(net "M_C_CPU1_SB_DQS_DP<6>")
	)
	(segment
		(start 77.98181 -281.915616)
		(end 78.087728 -281.809698)
		(width 0.09525)
		(layer "In2.Cu")
		(net "M_C_CPU1_SB_DQS_DP<6>")
	)
	(segment
		(start 61.716666 -295.769792)
		(end 66.12255 -291.363908)
		(width 0.16002)
		(layer "In2.Cu")
		(net "M_C_CPU1_SB_DQS_DP<6>")
	)
	(segment
		(start 90.742516 -281.86126)
		(end 90.750898 -281.856434)
		(width 0.09525)
		(layer "In2.Cu")
		(net "M_C_CPU1_SB_DQS_DP<6>")
	)
	(segment
		(start 83.591146 -281.856434)
		(end 83.599528 -281.86126)
		(width 0.09525)
		(layer "In2.Cu")
		(net "M_C_CPU1_SB_DQS_DP<6>")
	)
	(segment
		(start 40.23995 -295.9354)
		(end 40.513762 -295.661588)
		(width 0.16002)
		(layer "In2.Cu")
		(net "M_C_CPU1_SB_DQS_DP<6>")
	)
	(segment
		(start 74.15403 -281.974544)
		(end 75.955906 -281.974544)
		(width 0.16002)
		(layer "In2.Cu")
		(net "M_C_CPU1_SB_DQS_DP<6>")
	)
	(segment
		(start 43.406568 -295.762172)
		(end 44.149264 -296.069766)
		(width 0.16002)
		(layer "In2.Cu")
		(net "M_C_CPU1_SB_DQS_DP<6>")
	)
	(segment
		(start 75.955906 -281.974544)
		(end 75.979528 -281.974544)
		(width 0.09525)
		(layer "In2.Cu")
		(net "M_C_CPU1_SB_DQS_DP<6>")
	)
	(segment
		(start 88.291162 -281.856434)
		(end 88.299544 -281.86126)
		(width 0.09525)
		(layer "In2.Cu")
		(net "M_C_CPU1_SB_DQS_DP<6>")
	)
	(segment
		(start 50.33137 -295.482772)
		(end 50.69459 -295.482772)
		(width 0.16002)
		(layer "In2.Cu")
		(net "M_C_CPU1_SB_DQS_DP<6>")
	)
	(segment
		(start 89.802462 -281.86126)
		(end 89.810844 -281.856434)
		(width 0.09525)
		(layer "In2.Cu")
		(net "M_C_CPU1_SB_DQS_DP<6>")
	)
	(segment
		(start 66.12255 -290.238942)
		(end 66.287396 -289.841178)
		(width 0.16002)
		(layer "In2.Cu")
		(net "M_C_CPU1_SB_DQS_DP<6>")
	)
	(segment
		(start 52.787804 -295.810432)
		(end 53.788818 -296.22496)
		(width 0.16002)
		(layer "In2.Cu")
		(net "M_C_CPU1_SB_DQS_DP<6>")
	)
	(segment
		(start 56.22671 -296.633392)
		(end 56.54675 -296.313352)
		(width 0.16002)
		(layer "In2.Cu")
		(net "M_C_CPU1_SB_DQS_DP<6>")
	)
	(segment
		(start 58.511948 -295.769792)
		(end 61.716666 -295.769792)
		(width 0.16002)
		(layer "In2.Cu")
		(net "M_C_CPU1_SB_DQS_DP<6>")
	)
	(segment
		(start 50.69459 -295.482772)
		(end 51.02225 -295.810432)
		(width 0.16002)
		(layer "In2.Cu")
		(net "M_C_CPU1_SB_DQS_DP<6>")
	)
	(segment
		(start 57.849262 -295.51122)
		(end 58.253376 -295.51122)
		(width 0.16002)
		(layer "In2.Cu")
		(net "M_C_CPU1_SB_DQS_DP<6>")
	)
	(segment
		(start 66.12255 -291.363908)
		(end 66.12255 -290.238942)
		(width 0.16002)
		(layer "In2.Cu")
		(net "M_C_CPU1_SB_DQS_DP<6>")
	)
	(segment
		(start 86.0425 -281.86126)
		(end 86.050882 -281.856434)
		(width 0.09525)
		(layer "In2.Cu")
		(net "M_C_CPU1_SB_DQS_DP<6>")
	)
	(arc
		(start 89.810844 -281.856434)
		(mid 89.995876 -281.81052)
		(end 90.179652 -281.86126)
		(width 0.09525)
		(layer "In2.Cu")
		(net "M_C_CPU1_SB_DQS_DP<6>")
	)
	(arc
		(start 92.62237 -281.86126)
		(mid 92.806145 -281.810488)
		(end 92.991178 -281.856434)
		(width 0.09525)
		(layer "In2.Cu")
		(net "M_C_CPU1_SB_DQS_DP<6>")
	)
	(arc
		(start 85.110828 -281.856434)
		(mid 85.29586 -281.81052)
		(end 85.479636 -281.86126)
		(width 0.09525)
		(layer "In2.Cu")
		(net "M_C_CPU1_SB_DQS_DP<6>")
	)
	(arc
		(start 88.862408 -281.86126)
		(mid 89.046183 -281.810488)
		(end 89.231216 -281.856434)
		(width 0.09525)
		(layer "In2.Cu")
		(net "M_C_CPU1_SB_DQS_DP<6>")
	)
	(arc
		(start 90.179652 -281.86126)
		(mid 90.461084 -281.937015)
		(end 90.742516 -281.86126)
		(width 0.09525)
		(layer "In2.Cu")
		(net "M_C_CPU1_SB_DQS_DP<6>")
	)
	(arc
		(start 81.350866 -281.856434)
		(mid 81.535898 -281.81052)
		(end 81.719674 -281.86126)
		(width 0.09525)
		(layer "In2.Cu")
		(net "M_C_CPU1_SB_DQS_DP<6>")
	)
	(arc
		(start 89.239598 -281.86126)
		(mid 89.52103 -281.937015)
		(end 89.802462 -281.86126)
		(width 0.09525)
		(layer "In2.Cu")
		(net "M_C_CPU1_SB_DQS_DP<6>")
	)
	(arc
		(start 93.562424 -281.86126)
		(mid 93.746199 -281.810488)
		(end 93.931232 -281.856434)
		(width 0.09525)
		(layer "In2.Cu")
		(net "M_C_CPU1_SB_DQS_DP<6>")
	)
	(arc
		(start 94.51086 -281.856434)
		(mid 94.695892 -281.81052)
		(end 94.879668 -281.86126)
		(width 0.09525)
		(layer "In2.Cu")
		(net "M_C_CPU1_SB_DQS_DP<6>")
	)
	(arc
		(start 80.77962 -281.86126)
		(mid 81.061052 -281.937015)
		(end 81.342484 -281.86126)
		(width 0.09525)
		(layer "In2.Cu")
		(net "M_C_CPU1_SB_DQS_DP<6>")
	)
	(arc
		(start 92.059506 -281.86126)
		(mid 92.340938 -281.937015)
		(end 92.62237 -281.86126)
		(width 0.09525)
		(layer "In2.Cu")
		(net "M_C_CPU1_SB_DQS_DP<6>")
	)
	(arc
		(start 79.650082 -281.809698)
		(mid 79.747979 -281.822984)
		(end 79.839058 -281.86126)
		(width 0.09525)
		(layer "In2.Cu")
		(net "M_C_CPU1_SB_DQS_DP<6>")
	)
	(arc
		(start 86.982554 -281.86126)
		(mid 87.171022 -281.810583)
		(end 87.35949 -281.86126)
		(width 0.09525)
		(layer "In2.Cu")
		(net "M_C_CPU1_SB_DQS_DP<6>")
	)
	(arc
		(start 90.750898 -281.856434)
		(mid 90.93593 -281.81052)
		(end 91.119706 -281.86126)
		(width 0.09525)
		(layer "In2.Cu")
		(net "M_C_CPU1_SB_DQS_DP<6>")
	)
	(arc
		(start 81.719674 -281.86126)
		(mid 82.001106 -281.937015)
		(end 82.282538 -281.86126)
		(width 0.09525)
		(layer "In2.Cu")
		(net "M_C_CPU1_SB_DQS_DP<6>")
	)
	(arc
		(start 86.41969 -281.86126)
		(mid 86.701122 -281.937015)
		(end 86.982554 -281.86126)
		(width 0.09525)
		(layer "In2.Cu")
		(net "M_C_CPU1_SB_DQS_DP<6>")
	)
	(arc
		(start 92.99956 -281.86126)
		(mid 93.280992 -281.937015)
		(end 93.562424 -281.86126)
		(width 0.09525)
		(layer "In2.Cu")
		(net "M_C_CPU1_SB_DQS_DP<6>")
	)
	(arc
		(start 87.35949 -281.86126)
		(mid 87.640922 -281.937015)
		(end 87.922354 -281.86126)
		(width 0.09525)
		(layer "In2.Cu")
		(net "M_C_CPU1_SB_DQS_DP<6>")
	)
	(arc
		(start 80.40243 -281.86126)
		(mid 80.586205 -281.810488)
		(end 80.771238 -281.856434)
		(width 0.09525)
		(layer "In2.Cu")
		(net "M_C_CPU1_SB_DQS_DP<6>")
	)
	(arc
		(start 87.922354 -281.86126)
		(mid 88.106129 -281.810488)
		(end 88.291162 -281.856434)
		(width 0.09525)
		(layer "In2.Cu")
		(net "M_C_CPU1_SB_DQS_DP<6>")
	)
	(arc
		(start 83.599528 -281.86126)
		(mid 83.88096 -281.937015)
		(end 84.162392 -281.86126)
		(width 0.09525)
		(layer "In2.Cu")
		(net "M_C_CPU1_SB_DQS_DP<6>")
	)
	(arc
		(start 88.299544 -281.86126)
		(mid 88.580976 -281.937015)
		(end 88.862408 -281.86126)
		(width 0.09525)
		(layer "In2.Cu")
		(net "M_C_CPU1_SB_DQS_DP<6>")
	)
	(arc
		(start 82.282538 -281.86126)
		(mid 82.471006 -281.810583)
		(end 82.659474 -281.86126)
		(width 0.09525)
		(layer "In2.Cu")
		(net "M_C_CPU1_SB_DQS_DP<6>")
	)
	(arc
		(start 94.879668 -281.86126)
		(mid 95.1611 -281.937015)
		(end 95.442532 -281.86126)
		(width 0.09525)
		(layer "In2.Cu")
		(net "M_C_CPU1_SB_DQS_DP<6>")
	)
	(arc
		(start 85.479636 -281.86126)
		(mid 85.761068 -281.937015)
		(end 86.0425 -281.86126)
		(width 0.09525)
		(layer "In2.Cu")
		(net "M_C_CPU1_SB_DQS_DP<6>")
	)
	(arc
		(start 95.450914 -281.856434)
		(mid 95.603809 -281.811606)
		(end 95.761556 -281.834082)
		(width 0.09525)
		(layer "In2.Cu")
		(net "M_C_CPU1_SB_DQS_DP<6>")
	)
	(arc
		(start 82.659474 -281.86126)
		(mid 82.940906 -281.937015)
		(end 83.222338 -281.86126)
		(width 0.09525)
		(layer "In2.Cu")
		(net "M_C_CPU1_SB_DQS_DP<6>")
	)
	(arc
		(start 84.539582 -281.86126)
		(mid 84.821014 -281.937015)
		(end 85.102446 -281.86126)
		(width 0.09525)
		(layer "In2.Cu")
		(net "M_C_CPU1_SB_DQS_DP<6>")
	)
	(arc
		(start 84.162392 -281.86126)
		(mid 84.346167 -281.810488)
		(end 84.5312 -281.856434)
		(width 0.09525)
		(layer "In2.Cu")
		(net "M_C_CPU1_SB_DQS_DP<6>")
	)
	(arc
		(start 86.050882 -281.856434)
		(mid 86.235914 -281.81052)
		(end 86.41969 -281.86126)
		(width 0.09525)
		(layer "In2.Cu")
		(net "M_C_CPU1_SB_DQS_DP<6>")
	)
	(arc
		(start 93.939614 -281.86126)
		(mid 94.221046 -281.937015)
		(end 94.502478 -281.86126)
		(width 0.09525)
		(layer "In2.Cu")
		(net "M_C_CPU1_SB_DQS_DP<6>")
	)
	(arc
		(start 79.839058 -281.86126)
		(mid 80.11224 -281.937202)
		(end 80.387698 -281.869896)
		(width 0.09525)
		(layer "In2.Cu")
		(net "M_C_CPU1_SB_DQS_DP<6>")
	)
	(arc
		(start 83.222338 -281.86126)
		(mid 83.406113 -281.810488)
		(end 83.591146 -281.856434)
		(width 0.09525)
		(layer "In2.Cu")
		(net "M_C_CPU1_SB_DQS_DP<6>")
	)
	(arc
		(start 91.119706 -281.86126)
		(mid 91.401138 -281.937015)
		(end 91.68257 -281.86126)
		(width 0.09525)
		(layer "In2.Cu")
		(net "M_C_CPU1_SB_DQS_DP<6>")
	)
	(arc
		(start 91.68257 -281.86126)
		(mid 91.871038 -281.810583)
		(end 92.059506 -281.86126)
		(width 0.09525)
		(layer "In2.Cu")
		(net "M_C_CPU1_SB_DQS_DP<6>")
	)
	(segment
		(start 96.097852 -277.060406)
		(end 95.631 -277.326344)
		(width 0.12954)
		(layer "F.Cu")
		(net "M_C_CPU1_SB_DQS_DP<5>")
	)
	(segment
		(start 92.991178 -276.996398)
		(end 92.99956 -277.001224)
		(width 0.09525)
		(layer "In2.Cu")
		(net "M_C_CPU1_SB_DQS_DP<5>")
	)
	(segment
		(start 83.591146 -276.996398)
		(end 83.599528 -277.001224)
		(width 0.09525)
		(layer "In2.Cu")
		(net "M_C_CPU1_SB_DQS_DP<5>")
	)
	(segment
		(start 57.849262 -286.161226)
		(end 58.253376 -286.161226)
		(width 0.16002)
		(layer "In2.Cu")
		(net "M_C_CPU1_SB_DQS_DP<5>")
	)
	(segment
		(start 89.802462 -277.001224)
		(end 89.810844 -276.996398)
		(width 0.09525)
		(layer "In2.Cu")
		(net "M_C_CPU1_SB_DQS_DP<5>")
	)
	(segment
		(start 42.571416 -286.161226)
		(end 43.155616 -286.161226)
		(width 0.16002)
		(layer "In2.Cu")
		(net "M_C_CPU1_SB_DQS_DP<5>")
	)
	(segment
		(start 40.513762 -286.311594)
		(end 42.421048 -286.311594)
		(width 0.16002)
		(layer "In2.Cu")
		(net "M_C_CPU1_SB_DQS_DP<5>")
	)
	(segment
		(start 61.938408 -285.902908)
		(end 62.001654 -285.75)
		(width 0.16002)
		(layer "In2.Cu")
		(net "M_C_CPU1_SB_DQS_DP<5>")
	)
	(segment
		(start 79.461614 -277.001224)
		(end 79.473552 -276.994366)
		(width 0.09525)
		(layer "In2.Cu")
		(net "M_C_CPU1_SB_DQS_DP<5>")
	)
	(segment
		(start 42.421048 -286.311594)
		(end 42.571416 -286.161226)
		(width 0.16002)
		(layer "In2.Cu")
		(net "M_C_CPU1_SB_DQS_DP<5>")
	)
	(segment
		(start 50.69459 -286.132778)
		(end 51.02225 -286.460438)
		(width 0.16002)
		(layer "In2.Cu")
		(net "M_C_CPU1_SB_DQS_DP<5>")
	)
	(segment
		(start 48.663352 -287.310576)
		(end 49.103026 -286.870902)
		(width 0.16002)
		(layer "In2.Cu")
		(net "M_C_CPU1_SB_DQS_DP<5>")
	)
	(segment
		(start 86.0425 -277.001224)
		(end 86.050882 -276.996398)
		(width 0.09525)
		(layer "In2.Cu")
		(net "M_C_CPU1_SB_DQS_DP<5>")
	)
	(segment
		(start 56.816498 -286.851598)
		(end 57.849262 -286.161226)
		(width 0.16002)
		(layer "In2.Cu")
		(net "M_C_CPU1_SB_DQS_DP<5>")
	)
	(segment
		(start 44.081954 -286.719772)
		(end 45.860462 -286.719772)
		(width 0.16002)
		(layer "In2.Cu")
		(net "M_C_CPU1_SB_DQS_DP<5>")
	)
	(segment
		(start 56.54675 -286.963358)
		(end 56.816498 -286.851598)
		(width 0.16002)
		(layer "In2.Cu")
		(net "M_C_CPU1_SB_DQS_DP<5>")
	)
	(segment
		(start 94.502478 -277.001224)
		(end 94.51086 -276.996398)
		(width 0.09525)
		(layer "In2.Cu")
		(net "M_C_CPU1_SB_DQS_DP<5>")
	)
	(segment
		(start 61.49467 -286.08655)
		(end 61.938408 -285.902908)
		(width 0.16002)
		(layer "In2.Cu")
		(net "M_C_CPU1_SB_DQS_DP<5>")
	)
	(segment
		(start 43.454066 -286.459676)
		(end 44.081954 -286.719772)
		(width 0.16002)
		(layer "In2.Cu")
		(net "M_C_CPU1_SB_DQS_DP<5>")
	)
	(segment
		(start 56.22671 -287.283398)
		(end 56.54675 -286.963358)
		(width 0.16002)
		(layer "In2.Cu")
		(net "M_C_CPU1_SB_DQS_DP<5>")
	)
	(segment
		(start 80.387698 -277.00986)
		(end 80.40243 -277.001224)
		(width 0.09525)
		(layer "In2.Cu")
		(net "M_C_CPU1_SB_DQS_DP<5>")
	)
	(segment
		(start 53.721762 -286.80791)
		(end 54.19725 -287.283398)
		(width 0.16002)
		(layer "In2.Cu")
		(net "M_C_CPU1_SB_DQS_DP<5>")
	)
	(segment
		(start 76.038456 -276.292056)
		(end 76.320396 -276.292056)
		(width 0.09525)
		(layer "In2.Cu")
		(net "M_C_CPU1_SB_DQS_DP<5>")
	)
	(segment
		(start 62.445138 -285.566358)
		(end 71.660512 -276.350984)
		(width 0.16002)
		(layer "In2.Cu")
		(net "M_C_CPU1_SB_DQS_DP<5>")
	)
	(segment
		(start 71.660512 -276.350984)
		(end 75.955906 -276.350984)
		(width 0.16002)
		(layer "In2.Cu")
		(net "M_C_CPU1_SB_DQS_DP<5>")
	)
	(segment
		(start 51.02225 -286.460438)
		(end 52.8828 -286.460438)
		(width 0.16002)
		(layer "In2.Cu")
		(net "M_C_CPU1_SB_DQS_DP<5>")
	)
	(segment
		(start 81.342484 -277.001224)
		(end 81.350866 -276.996398)
		(width 0.09525)
		(layer "In2.Cu")
		(net "M_C_CPU1_SB_DQS_DP<5>")
	)
	(segment
		(start 50.33137 -286.132778)
		(end 50.69459 -286.132778)
		(width 0.16002)
		(layer "In2.Cu")
		(net "M_C_CPU1_SB_DQS_DP<5>")
	)
	(segment
		(start 95.442532 -277.001224)
		(end 95.450914 -276.996398)
		(width 0.09525)
		(layer "In2.Cu")
		(net "M_C_CPU1_SB_DQS_DP<5>")
	)
	(segment
		(start 76.705968 -276.677628)
		(end 77.364082 -276.95017)
		(width 0.09525)
		(layer "In2.Cu")
		(net "M_C_CPU1_SB_DQS_DP<5>")
	)
	(segment
		(start 85.102446 -277.001224)
		(end 85.110828 -276.996398)
		(width 0.09525)
		(layer "In2.Cu")
		(net "M_C_CPU1_SB_DQS_DP<5>")
	)
	(segment
		(start 60.384944 -286.419798)
		(end 61.342016 -286.023304)
		(width 0.16002)
		(layer "In2.Cu")
		(net "M_C_CPU1_SB_DQS_DP<5>")
	)
	(segment
		(start 95.784924 -277.060914)
		(end 95.631 -277.326344)
		(width 0.09525)
		(layer "In2.Cu")
		(net "M_C_CPU1_SB_DQS_DP<5>")
	)
	(segment
		(start 88.291162 -276.996398)
		(end 88.299544 -277.001224)
		(width 0.09525)
		(layer "In2.Cu")
		(net "M_C_CPU1_SB_DQS_DP<5>")
	)
	(segment
		(start 76.320396 -276.292056)
		(end 76.705968 -276.677628)
		(width 0.09525)
		(layer "In2.Cu")
		(net "M_C_CPU1_SB_DQS_DP<5>")
	)
	(segment
		(start 80.771238 -276.996398)
		(end 80.77962 -277.001224)
		(width 0.09525)
		(layer "In2.Cu")
		(net "M_C_CPU1_SB_DQS_DP<5>")
	)
	(segment
		(start 46.70044 -287.310576)
		(end 48.663352 -287.310576)
		(width 0.16002)
		(layer "In2.Cu")
		(net "M_C_CPU1_SB_DQS_DP<5>")
	)
	(segment
		(start 78.899258 -277.001224)
		(end 78.90256 -277.003002)
		(width 0.09525)
		(layer "In2.Cu")
		(net "M_C_CPU1_SB_DQS_DP<5>")
	)
	(segment
		(start 78.90256 -277.003002)
		(end 78.91399 -277.00986)
		(width 0.09525)
		(layer "In2.Cu")
		(net "M_C_CPU1_SB_DQS_DP<5>")
	)
	(segment
		(start 58.253376 -286.161226)
		(end 58.511948 -286.419798)
		(width 0.16002)
		(layer "In2.Cu")
		(net "M_C_CPU1_SB_DQS_DP<5>")
	)
	(segment
		(start 93.931232 -276.996398)
		(end 93.939614 -277.001224)
		(width 0.09525)
		(layer "In2.Cu")
		(net "M_C_CPU1_SB_DQS_DP<5>")
	)
	(segment
		(start 43.155616 -286.161226)
		(end 43.454066 -286.459676)
		(width 0.16002)
		(layer "In2.Cu")
		(net "M_C_CPU1_SB_DQS_DP<5>")
	)
	(segment
		(start 49.939956 -286.524192)
		(end 50.33137 -286.132778)
		(width 0.16002)
		(layer "In2.Cu")
		(net "M_C_CPU1_SB_DQS_DP<5>")
	)
	(segment
		(start 77.364082 -276.95017)
		(end 78.711298 -276.95017)
		(width 0.09525)
		(layer "In2.Cu")
		(net "M_C_CPU1_SB_DQS_DP<5>")
	)
	(segment
		(start 75.955906 -276.350984)
		(end 75.979528 -276.350984)
		(width 0.09525)
		(layer "In2.Cu")
		(net "M_C_CPU1_SB_DQS_DP<5>")
	)
	(segment
		(start 49.103026 -286.870902)
		(end 49.939956 -286.524192)
		(width 0.16002)
		(layer "In2.Cu")
		(net "M_C_CPU1_SB_DQS_DP<5>")
	)
	(segment
		(start 75.979528 -276.350984)
		(end 76.038456 -276.292056)
		(width 0.09525)
		(layer "In2.Cu")
		(net "M_C_CPU1_SB_DQS_DP<5>")
	)
	(segment
		(start 40.23995 -286.585406)
		(end 40.513762 -286.311594)
		(width 0.16002)
		(layer "In2.Cu")
		(net "M_C_CPU1_SB_DQS_DP<5>")
	)
	(segment
		(start 89.231216 -276.996398)
		(end 89.239598 -277.001224)
		(width 0.09525)
		(layer "In2.Cu")
		(net "M_C_CPU1_SB_DQS_DP<5>")
	)
	(segment
		(start 61.342016 -286.023304)
		(end 61.49467 -286.08655)
		(width 0.16002)
		(layer "In2.Cu")
		(net "M_C_CPU1_SB_DQS_DP<5>")
	)
	(segment
		(start 52.8828 -286.460438)
		(end 53.721762 -286.80791)
		(width 0.16002)
		(layer "In2.Cu")
		(net "M_C_CPU1_SB_DQS_DP<5>")
	)
	(segment
		(start 45.860462 -286.719772)
		(end 46.285912 -286.896048)
		(width 0.16002)
		(layer "In2.Cu")
		(net "M_C_CPU1_SB_DQS_DP<5>")
	)
	(segment
		(start 62.001654 -285.75)
		(end 62.445138 -285.566358)
		(width 0.16002)
		(layer "In2.Cu")
		(net "M_C_CPU1_SB_DQS_DP<5>")
	)
	(segment
		(start 84.5312 -276.996398)
		(end 84.539582 -277.001224)
		(width 0.09525)
		(layer "In2.Cu")
		(net "M_C_CPU1_SB_DQS_DP<5>")
	)
	(segment
		(start 90.742516 -277.001224)
		(end 90.750898 -276.996398)
		(width 0.09525)
		(layer "In2.Cu")
		(net "M_C_CPU1_SB_DQS_DP<5>")
	)
	(segment
		(start 46.285912 -286.896048)
		(end 46.70044 -287.310576)
		(width 0.16002)
		(layer "In2.Cu")
		(net "M_C_CPU1_SB_DQS_DP<5>")
	)
	(segment
		(start 54.19725 -287.283398)
		(end 56.22671 -287.283398)
		(width 0.16002)
		(layer "In2.Cu")
		(net "M_C_CPU1_SB_DQS_DP<5>")
	)
	(segment
		(start 95.761556 -276.974046)
		(end 95.784924 -277.060914)
		(width 0.09525)
		(layer "In2.Cu")
		(net "M_C_CPU1_SB_DQS_DP<5>")
	)
	(segment
		(start 58.511948 -286.419798)
		(end 60.384944 -286.419798)
		(width 0.16002)
		(layer "In2.Cu")
		(net "M_C_CPU1_SB_DQS_DP<5>")
	)
	(arc
		(start 93.939614 -277.001224)
		(mid 94.221046 -277.076979)
		(end 94.502478 -277.001224)
		(width 0.09525)
		(layer "In2.Cu")
		(net "M_C_CPU1_SB_DQS_DP<5>")
	)
	(arc
		(start 80.77962 -277.001224)
		(mid 81.061052 -277.076979)
		(end 81.342484 -277.001224)
		(width 0.09525)
		(layer "In2.Cu")
		(net "M_C_CPU1_SB_DQS_DP<5>")
	)
	(arc
		(start 78.91399 -277.00986)
		(mid 79.188941 -277.077003)
		(end 79.461614 -277.001224)
		(width 0.09525)
		(layer "In2.Cu")
		(net "M_C_CPU1_SB_DQS_DP<5>")
	)
	(arc
		(start 81.350866 -276.996398)
		(mid 81.535898 -276.950484)
		(end 81.719674 -277.001224)
		(width 0.09525)
		(layer "In2.Cu")
		(net "M_C_CPU1_SB_DQS_DP<5>")
	)
	(arc
		(start 82.282538 -277.001224)
		(mid 82.471006 -276.950547)
		(end 82.659474 -277.001224)
		(width 0.09525)
		(layer "In2.Cu")
		(net "M_C_CPU1_SB_DQS_DP<5>")
	)
	(arc
		(start 88.299544 -277.001224)
		(mid 88.580976 -277.076979)
		(end 88.862408 -277.001224)
		(width 0.09525)
		(layer "In2.Cu")
		(net "M_C_CPU1_SB_DQS_DP<5>")
	)
	(arc
		(start 92.62237 -277.001224)
		(mid 92.806145 -276.950452)
		(end 92.991178 -276.996398)
		(width 0.09525)
		(layer "In2.Cu")
		(net "M_C_CPU1_SB_DQS_DP<5>")
	)
	(arc
		(start 86.050882 -276.996398)
		(mid 86.235914 -276.950484)
		(end 86.41969 -277.001224)
		(width 0.09525)
		(layer "In2.Cu")
		(net "M_C_CPU1_SB_DQS_DP<5>")
	)
	(arc
		(start 86.982554 -277.001224)
		(mid 87.171022 -276.950547)
		(end 87.35949 -277.001224)
		(width 0.09525)
		(layer "In2.Cu")
		(net "M_C_CPU1_SB_DQS_DP<5>")
	)
	(arc
		(start 93.562424 -277.001224)
		(mid 93.746199 -276.950452)
		(end 93.931232 -276.996398)
		(width 0.09525)
		(layer "In2.Cu")
		(net "M_C_CPU1_SB_DQS_DP<5>")
	)
	(arc
		(start 91.68257 -277.001224)
		(mid 91.871038 -276.950547)
		(end 92.059506 -277.001224)
		(width 0.09525)
		(layer "In2.Cu")
		(net "M_C_CPU1_SB_DQS_DP<5>")
	)
	(arc
		(start 91.119706 -277.001224)
		(mid 91.401138 -277.076979)
		(end 91.68257 -277.001224)
		(width 0.09525)
		(layer "In2.Cu")
		(net "M_C_CPU1_SB_DQS_DP<5>")
	)
	(arc
		(start 94.879668 -277.001224)
		(mid 95.1611 -277.076979)
		(end 95.442532 -277.001224)
		(width 0.09525)
		(layer "In2.Cu")
		(net "M_C_CPU1_SB_DQS_DP<5>")
	)
	(arc
		(start 94.51086 -276.996398)
		(mid 94.695892 -276.950484)
		(end 94.879668 -277.001224)
		(width 0.09525)
		(layer "In2.Cu")
		(net "M_C_CPU1_SB_DQS_DP<5>")
	)
	(arc
		(start 84.162392 -277.001224)
		(mid 84.346167 -276.950452)
		(end 84.5312 -276.996398)
		(width 0.09525)
		(layer "In2.Cu")
		(net "M_C_CPU1_SB_DQS_DP<5>")
	)
	(arc
		(start 88.862408 -277.001224)
		(mid 89.046183 -276.950452)
		(end 89.231216 -276.996398)
		(width 0.09525)
		(layer "In2.Cu")
		(net "M_C_CPU1_SB_DQS_DP<5>")
	)
	(arc
		(start 85.479636 -277.001224)
		(mid 85.761068 -277.076979)
		(end 86.0425 -277.001224)
		(width 0.09525)
		(layer "In2.Cu")
		(net "M_C_CPU1_SB_DQS_DP<5>")
	)
	(arc
		(start 78.711298 -276.95017)
		(mid 78.808634 -276.963331)
		(end 78.899258 -277.001224)
		(width 0.09525)
		(layer "In2.Cu")
		(net "M_C_CPU1_SB_DQS_DP<5>")
	)
	(arc
		(start 86.41969 -277.001224)
		(mid 86.701122 -277.076979)
		(end 86.982554 -277.001224)
		(width 0.09525)
		(layer "In2.Cu")
		(net "M_C_CPU1_SB_DQS_DP<5>")
	)
	(arc
		(start 89.239598 -277.001224)
		(mid 89.52103 -277.076979)
		(end 89.802462 -277.001224)
		(width 0.09525)
		(layer "In2.Cu")
		(net "M_C_CPU1_SB_DQS_DP<5>")
	)
	(arc
		(start 90.750898 -276.996398)
		(mid 90.93593 -276.950484)
		(end 91.119706 -277.001224)
		(width 0.09525)
		(layer "In2.Cu")
		(net "M_C_CPU1_SB_DQS_DP<5>")
	)
	(arc
		(start 81.719674 -277.001224)
		(mid 82.001106 -277.076979)
		(end 82.282538 -277.001224)
		(width 0.09525)
		(layer "In2.Cu")
		(net "M_C_CPU1_SB_DQS_DP<5>")
	)
	(arc
		(start 85.110828 -276.996398)
		(mid 85.29586 -276.950484)
		(end 85.479636 -277.001224)
		(width 0.09525)
		(layer "In2.Cu")
		(net "M_C_CPU1_SB_DQS_DP<5>")
	)
	(arc
		(start 79.839058 -277.001224)
		(mid 80.11224 -277.077166)
		(end 80.387698 -277.00986)
		(width 0.09525)
		(layer "In2.Cu")
		(net "M_C_CPU1_SB_DQS_DP<5>")
	)
	(arc
		(start 82.659474 -277.001224)
		(mid 82.940906 -277.076979)
		(end 83.222338 -277.001224)
		(width 0.09525)
		(layer "In2.Cu")
		(net "M_C_CPU1_SB_DQS_DP<5>")
	)
	(arc
		(start 83.599528 -277.001224)
		(mid 83.88096 -277.076979)
		(end 84.162392 -277.001224)
		(width 0.09525)
		(layer "In2.Cu")
		(net "M_C_CPU1_SB_DQS_DP<5>")
	)
	(arc
		(start 92.059506 -277.001224)
		(mid 92.340938 -277.076979)
		(end 92.62237 -277.001224)
		(width 0.09525)
		(layer "In2.Cu")
		(net "M_C_CPU1_SB_DQS_DP<5>")
	)
	(arc
		(start 95.450914 -276.996398)
		(mid 95.603809 -276.95157)
		(end 95.761556 -276.974046)
		(width 0.09525)
		(layer "In2.Cu")
		(net "M_C_CPU1_SB_DQS_DP<5>")
	)
	(arc
		(start 79.473552 -276.994366)
		(mid 79.657187 -276.950416)
		(end 79.839058 -277.001224)
		(width 0.09525)
		(layer "In2.Cu")
		(net "M_C_CPU1_SB_DQS_DP<5>")
	)
	(arc
		(start 90.179652 -277.001224)
		(mid 90.461084 -277.076979)
		(end 90.742516 -277.001224)
		(width 0.09525)
		(layer "In2.Cu")
		(net "M_C_CPU1_SB_DQS_DP<5>")
	)
	(arc
		(start 92.99956 -277.001224)
		(mid 93.280992 -277.076979)
		(end 93.562424 -277.001224)
		(width 0.09525)
		(layer "In2.Cu")
		(net "M_C_CPU1_SB_DQS_DP<5>")
	)
	(arc
		(start 87.35949 -277.001224)
		(mid 87.640922 -277.076979)
		(end 87.922354 -277.001224)
		(width 0.09525)
		(layer "In2.Cu")
		(net "M_C_CPU1_SB_DQS_DP<5>")
	)
	(arc
		(start 87.922354 -277.001224)
		(mid 88.106129 -276.950452)
		(end 88.291162 -276.996398)
		(width 0.09525)
		(layer "In2.Cu")
		(net "M_C_CPU1_SB_DQS_DP<5>")
	)
	(arc
		(start 84.539582 -277.001224)
		(mid 84.821014 -277.076979)
		(end 85.102446 -277.001224)
		(width 0.09525)
		(layer "In2.Cu")
		(net "M_C_CPU1_SB_DQS_DP<5>")
	)
	(arc
		(start 89.810844 -276.996398)
		(mid 89.995876 -276.950484)
		(end 90.179652 -277.001224)
		(width 0.09525)
		(layer "In2.Cu")
		(net "M_C_CPU1_SB_DQS_DP<5>")
	)
	(arc
		(start 80.40243 -277.001224)
		(mid 80.586205 -276.950452)
		(end 80.771238 -276.996398)
		(width 0.09525)
		(layer "In2.Cu")
		(net "M_C_CPU1_SB_DQS_DP<5>")
	)
	(arc
		(start 83.222338 -277.001224)
		(mid 83.406113 -276.950452)
		(end 83.591146 -276.996398)
		(width 0.09525)
		(layer "In2.Cu")
		(net "M_C_CPU1_SB_DQS_DP<5>")
	)
	(segment
		(start 96.097852 -272.20037)
		(end 95.631 -272.466308)
		(width 0.12954)
		(layer "F.Cu")
		(net "M_C_CPU1_SB_DQS_DP<4>")
	)
	(segment
		(start 50.239168 -276.874986)
		(end 50.33137 -276.782784)
		(width 0.16002)
		(layer "In2.Cu")
		(net "M_C_CPU1_SB_DQS_DP<4>")
	)
	(segment
		(start 45.222668 -277.369778)
		(end 46.649132 -277.960582)
		(width 0.16002)
		(layer "In2.Cu")
		(net "M_C_CPU1_SB_DQS_DP<4>")
	)
	(segment
		(start 95.784924 -272.200878)
		(end 95.631 -272.466308)
		(width 0.09525)
		(layer "In2.Cu")
		(net "M_C_CPU1_SB_DQS_DP<4>")
	)
	(segment
		(start 85.102446 -272.141188)
		(end 85.110828 -272.136362)
		(width 0.09525)
		(layer "In2.Cu")
		(net "M_C_CPU1_SB_DQS_DP<4>")
	)
	(segment
		(start 42.452036 -276.9616)
		(end 42.60469 -276.808946)
		(width 0.16002)
		(layer "In2.Cu")
		(net "M_C_CPU1_SB_DQS_DP<4>")
	)
	(segment
		(start 75.979528 -270.727424)
		(end 76.038456 -270.668496)
		(width 0.09525)
		(layer "In2.Cu")
		(net "M_C_CPU1_SB_DQS_DP<4>")
	)
	(segment
		(start 48.663352 -277.960582)
		(end 48.98771 -277.636224)
		(width 0.16002)
		(layer "In2.Cu")
		(net "M_C_CPU1_SB_DQS_DP<4>")
	)
	(segment
		(start 56.505094 -277.682198)
		(end 57.80786 -276.811232)
		(width 0.16002)
		(layer "In2.Cu")
		(net "M_C_CPU1_SB_DQS_DP<4>")
	)
	(segment
		(start 77.170788 -270.918178)
		(end 78.342744 -272.090134)
		(width 0.09525)
		(layer "In2.Cu")
		(net "M_C_CPU1_SB_DQS_DP<4>")
	)
	(segment
		(start 50.33137 -276.782784)
		(end 50.645314 -276.782784)
		(width 0.16002)
		(layer "In2.Cu")
		(net "M_C_CPU1_SB_DQS_DP<4>")
	)
	(segment
		(start 79.461614 -272.141188)
		(end 79.473552 -272.13433)
		(width 0.09525)
		(layer "In2.Cu")
		(net "M_C_CPU1_SB_DQS_DP<4>")
	)
	(segment
		(start 86.0425 -272.141188)
		(end 86.050882 -272.136362)
		(width 0.09525)
		(layer "In2.Cu")
		(net "M_C_CPU1_SB_DQS_DP<4>")
	)
	(segment
		(start 90.742516 -272.141188)
		(end 90.750898 -272.136362)
		(width 0.09525)
		(layer "In2.Cu")
		(net "M_C_CPU1_SB_DQS_DP<4>")
	)
	(segment
		(start 41.258236 -276.9616)
		(end 41.375076 -277.07844)
		(width 0.16002)
		(layer "In2.Cu")
		(net "M_C_CPU1_SB_DQS_DP<4>")
	)
	(segment
		(start 94.502478 -272.141188)
		(end 94.51086 -272.136362)
		(width 0.09525)
		(layer "In2.Cu")
		(net "M_C_CPU1_SB_DQS_DP<4>")
	)
	(segment
		(start 56.253634 -277.933404)
		(end 56.505094 -277.682198)
		(width 0.16002)
		(layer "In2.Cu")
		(net "M_C_CPU1_SB_DQS_DP<4>")
	)
	(segment
		(start 95.442532 -272.141188)
		(end 95.450914 -272.136362)
		(width 0.09525)
		(layer "In2.Cu")
		(net "M_C_CPU1_SB_DQS_DP<4>")
	)
	(segment
		(start 75.955906 -270.727424)
		(end 75.979528 -270.727424)
		(width 0.09525)
		(layer "In2.Cu")
		(net "M_C_CPU1_SB_DQS_DP<4>")
	)
	(segment
		(start 41.855136 -277.07844)
		(end 41.971976 -276.9616)
		(width 0.16002)
		(layer "In2.Cu")
		(net "M_C_CPU1_SB_DQS_DP<4>")
	)
	(segment
		(start 80.771238 -272.136362)
		(end 80.77962 -272.141188)
		(width 0.09525)
		(layer "In2.Cu")
		(net "M_C_CPU1_SB_DQS_DP<4>")
	)
	(segment
		(start 52.869846 -277.110444)
		(end 53.024786 -277.174706)
		(width 0.16002)
		(layer "In2.Cu")
		(net "M_C_CPU1_SB_DQS_DP<4>")
	)
	(segment
		(start 42.60469 -276.808946)
		(end 43.14063 -276.808946)
		(width 0.16002)
		(layer "In2.Cu")
		(net "M_C_CPU1_SB_DQS_DP<4>")
	)
	(segment
		(start 50.645314 -276.782784)
		(end 50.972974 -277.110444)
		(width 0.16002)
		(layer "In2.Cu")
		(net "M_C_CPU1_SB_DQS_DP<4>")
	)
	(segment
		(start 78.342744 -272.090134)
		(end 78.711044 -272.090134)
		(width 0.09525)
		(layer "In2.Cu")
		(net "M_C_CPU1_SB_DQS_DP<4>")
	)
	(segment
		(start 76.038456 -270.668496)
		(end 76.53274 -270.668496)
		(width 0.09525)
		(layer "In2.Cu")
		(net "M_C_CPU1_SB_DQS_DP<4>")
	)
	(segment
		(start 92.991178 -272.136362)
		(end 92.99956 -272.141188)
		(width 0.09525)
		(layer "In2.Cu")
		(net "M_C_CPU1_SB_DQS_DP<4>")
	)
	(segment
		(start 76.53274 -270.668496)
		(end 76.782422 -270.918178)
		(width 0.09525)
		(layer "In2.Cu")
		(net "M_C_CPU1_SB_DQS_DP<4>")
	)
	(segment
		(start 40.23995 -277.235412)
		(end 40.513762 -276.9616)
		(width 0.16002)
		(layer "In2.Cu")
		(net "M_C_CPU1_SB_DQS_DP<4>")
	)
	(segment
		(start 88.291162 -272.136362)
		(end 88.299544 -272.141188)
		(width 0.09525)
		(layer "In2.Cu")
		(net "M_C_CPU1_SB_DQS_DP<4>")
	)
	(segment
		(start 66.728594 -270.727424)
		(end 75.955906 -270.727424)
		(width 0.16002)
		(layer "In2.Cu")
		(net "M_C_CPU1_SB_DQS_DP<4>")
	)
	(segment
		(start 84.5312 -272.136362)
		(end 84.539582 -272.141188)
		(width 0.09525)
		(layer "In2.Cu")
		(net "M_C_CPU1_SB_DQS_DP<4>")
	)
	(segment
		(start 41.375076 -277.07844)
		(end 41.855136 -277.07844)
		(width 0.16002)
		(layer "In2.Cu")
		(net "M_C_CPU1_SB_DQS_DP<4>")
	)
	(segment
		(start 43.14063 -276.808946)
		(end 43.701462 -277.369778)
		(width 0.16002)
		(layer "In2.Cu")
		(net "M_C_CPU1_SB_DQS_DP<4>")
	)
	(segment
		(start 50.972974 -277.110444)
		(end 52.869846 -277.110444)
		(width 0.16002)
		(layer "In2.Cu")
		(net "M_C_CPU1_SB_DQS_DP<4>")
	)
	(segment
		(start 53.024786 -277.174706)
		(end 54.160674 -277.933404)
		(width 0.16002)
		(layer "In2.Cu")
		(net "M_C_CPU1_SB_DQS_DP<4>")
	)
	(segment
		(start 95.761556 -272.11401)
		(end 95.784924 -272.200878)
		(width 0.09525)
		(layer "In2.Cu")
		(net "M_C_CPU1_SB_DQS_DP<4>")
	)
	(segment
		(start 80.387698 -272.149824)
		(end 80.40243 -272.141188)
		(width 0.09525)
		(layer "In2.Cu")
		(net "M_C_CPU1_SB_DQS_DP<4>")
	)
	(segment
		(start 89.802462 -272.141188)
		(end 89.810844 -272.136362)
		(width 0.09525)
		(layer "In2.Cu")
		(net "M_C_CPU1_SB_DQS_DP<4>")
	)
	(segment
		(start 83.591146 -272.136362)
		(end 83.599528 -272.141188)
		(width 0.09525)
		(layer "In2.Cu")
		(net "M_C_CPU1_SB_DQS_DP<4>")
	)
	(segment
		(start 54.160674 -277.933404)
		(end 56.253634 -277.933404)
		(width 0.16002)
		(layer "In2.Cu")
		(net "M_C_CPU1_SB_DQS_DP<4>")
	)
	(segment
		(start 78.899258 -272.141188)
		(end 78.91399 -272.149824)
		(width 0.09525)
		(layer "In2.Cu")
		(net "M_C_CPU1_SB_DQS_DP<4>")
	)
	(segment
		(start 40.513762 -276.9616)
		(end 41.258236 -276.9616)
		(width 0.16002)
		(layer "In2.Cu")
		(net "M_C_CPU1_SB_DQS_DP<4>")
	)
	(segment
		(start 60.386214 -277.069804)
		(end 66.728594 -270.727424)
		(width 0.16002)
		(layer "In2.Cu")
		(net "M_C_CPU1_SB_DQS_DP<4>")
	)
	(segment
		(start 41.971976 -276.9616)
		(end 42.452036 -276.9616)
		(width 0.16002)
		(layer "In2.Cu")
		(net "M_C_CPU1_SB_DQS_DP<4>")
	)
	(segment
		(start 57.80786 -276.811232)
		(end 58.253376 -276.811232)
		(width 0.16002)
		(layer "In2.Cu")
		(net "M_C_CPU1_SB_DQS_DP<4>")
	)
	(segment
		(start 76.782422 -270.918178)
		(end 77.170788 -270.918178)
		(width 0.09525)
		(layer "In2.Cu")
		(net "M_C_CPU1_SB_DQS_DP<4>")
	)
	(segment
		(start 89.231216 -272.136362)
		(end 89.239598 -272.141188)
		(width 0.09525)
		(layer "In2.Cu")
		(net "M_C_CPU1_SB_DQS_DP<4>")
	)
	(segment
		(start 49.283112 -277.513796)
		(end 50.239168 -276.874986)
		(width 0.16002)
		(layer "In2.Cu")
		(net "M_C_CPU1_SB_DQS_DP<4>")
	)
	(segment
		(start 46.649132 -277.960582)
		(end 48.663352 -277.960582)
		(width 0.16002)
		(layer "In2.Cu")
		(net "M_C_CPU1_SB_DQS_DP<4>")
	)
	(segment
		(start 93.931232 -272.136362)
		(end 93.939614 -272.141188)
		(width 0.09525)
		(layer "In2.Cu")
		(net "M_C_CPU1_SB_DQS_DP<4>")
	)
	(segment
		(start 81.342484 -272.141188)
		(end 81.350866 -272.136362)
		(width 0.09525)
		(layer "In2.Cu")
		(net "M_C_CPU1_SB_DQS_DP<4>")
	)
	(segment
		(start 58.253376 -276.811232)
		(end 58.511948 -277.069804)
		(width 0.16002)
		(layer "In2.Cu")
		(net "M_C_CPU1_SB_DQS_DP<4>")
	)
	(segment
		(start 58.511948 -277.069804)
		(end 60.386214 -277.069804)
		(width 0.16002)
		(layer "In2.Cu")
		(net "M_C_CPU1_SB_DQS_DP<4>")
	)
	(segment
		(start 48.98771 -277.636224)
		(end 49.283112 -277.513796)
		(width 0.16002)
		(layer "In2.Cu")
		(net "M_C_CPU1_SB_DQS_DP<4>")
	)
	(segment
		(start 43.701462 -277.369778)
		(end 45.222668 -277.369778)
		(width 0.16002)
		(layer "In2.Cu")
		(net "M_C_CPU1_SB_DQS_DP<4>")
	)
	(arc
		(start 86.050882 -272.136362)
		(mid 86.235914 -272.090448)
		(end 86.41969 -272.141188)
		(width 0.09525)
		(layer "In2.Cu")
		(net "M_C_CPU1_SB_DQS_DP<4>")
	)
	(arc
		(start 83.222338 -272.141188)
		(mid 83.406113 -272.090416)
		(end 83.591146 -272.136362)
		(width 0.09525)
		(layer "In2.Cu")
		(net "M_C_CPU1_SB_DQS_DP<4>")
	)
	(arc
		(start 80.77962 -272.141188)
		(mid 81.061052 -272.216943)
		(end 81.342484 -272.141188)
		(width 0.09525)
		(layer "In2.Cu")
		(net "M_C_CPU1_SB_DQS_DP<4>")
	)
	(arc
		(start 86.41969 -272.141188)
		(mid 86.701122 -272.216943)
		(end 86.982554 -272.141188)
		(width 0.09525)
		(layer "In2.Cu")
		(net "M_C_CPU1_SB_DQS_DP<4>")
	)
	(arc
		(start 94.879668 -272.141188)
		(mid 95.1611 -272.216943)
		(end 95.442532 -272.141188)
		(width 0.09525)
		(layer "In2.Cu")
		(net "M_C_CPU1_SB_DQS_DP<4>")
	)
	(arc
		(start 93.939614 -272.141188)
		(mid 94.221046 -272.216943)
		(end 94.502478 -272.141188)
		(width 0.09525)
		(layer "In2.Cu")
		(net "M_C_CPU1_SB_DQS_DP<4>")
	)
	(arc
		(start 89.810844 -272.136362)
		(mid 89.995876 -272.090448)
		(end 90.179652 -272.141188)
		(width 0.09525)
		(layer "In2.Cu")
		(net "M_C_CPU1_SB_DQS_DP<4>")
	)
	(arc
		(start 84.539582 -272.141188)
		(mid 84.821014 -272.216943)
		(end 85.102446 -272.141188)
		(width 0.09525)
		(layer "In2.Cu")
		(net "M_C_CPU1_SB_DQS_DP<4>")
	)
	(arc
		(start 81.350866 -272.136362)
		(mid 81.535898 -272.090448)
		(end 81.719674 -272.141188)
		(width 0.09525)
		(layer "In2.Cu")
		(net "M_C_CPU1_SB_DQS_DP<4>")
	)
	(arc
		(start 93.562424 -272.141188)
		(mid 93.746199 -272.090416)
		(end 93.931232 -272.136362)
		(width 0.09525)
		(layer "In2.Cu")
		(net "M_C_CPU1_SB_DQS_DP<4>")
	)
	(arc
		(start 87.35949 -272.141188)
		(mid 87.640922 -272.216943)
		(end 87.922354 -272.141188)
		(width 0.09525)
		(layer "In2.Cu")
		(net "M_C_CPU1_SB_DQS_DP<4>")
	)
	(arc
		(start 91.119706 -272.141188)
		(mid 91.401138 -272.216943)
		(end 91.68257 -272.141188)
		(width 0.09525)
		(layer "In2.Cu")
		(net "M_C_CPU1_SB_DQS_DP<4>")
	)
	(arc
		(start 95.450914 -272.136362)
		(mid 95.603809 -272.091534)
		(end 95.761556 -272.11401)
		(width 0.09525)
		(layer "In2.Cu")
		(net "M_C_CPU1_SB_DQS_DP<4>")
	)
	(arc
		(start 89.239598 -272.141188)
		(mid 89.52103 -272.216943)
		(end 89.802462 -272.141188)
		(width 0.09525)
		(layer "In2.Cu")
		(net "M_C_CPU1_SB_DQS_DP<4>")
	)
	(arc
		(start 92.99956 -272.141188)
		(mid 93.280992 -272.216943)
		(end 93.562424 -272.141188)
		(width 0.09525)
		(layer "In2.Cu")
		(net "M_C_CPU1_SB_DQS_DP<4>")
	)
	(arc
		(start 78.91399 -272.149824)
		(mid 79.188941 -272.216967)
		(end 79.461614 -272.141188)
		(width 0.09525)
		(layer "In2.Cu")
		(net "M_C_CPU1_SB_DQS_DP<4>")
	)
	(arc
		(start 92.62237 -272.141188)
		(mid 92.806145 -272.090416)
		(end 92.991178 -272.136362)
		(width 0.09525)
		(layer "In2.Cu")
		(net "M_C_CPU1_SB_DQS_DP<4>")
	)
	(arc
		(start 82.282538 -272.141188)
		(mid 82.471006 -272.090511)
		(end 82.659474 -272.141188)
		(width 0.09525)
		(layer "In2.Cu")
		(net "M_C_CPU1_SB_DQS_DP<4>")
	)
	(arc
		(start 90.179652 -272.141188)
		(mid 90.461084 -272.216943)
		(end 90.742516 -272.141188)
		(width 0.09525)
		(layer "In2.Cu")
		(net "M_C_CPU1_SB_DQS_DP<4>")
	)
	(arc
		(start 79.839058 -272.141188)
		(mid 80.11224 -272.21713)
		(end 80.387698 -272.149824)
		(width 0.09525)
		(layer "In2.Cu")
		(net "M_C_CPU1_SB_DQS_DP<4>")
	)
	(arc
		(start 83.599528 -272.141188)
		(mid 83.88096 -272.216943)
		(end 84.162392 -272.141188)
		(width 0.09525)
		(layer "In2.Cu")
		(net "M_C_CPU1_SB_DQS_DP<4>")
	)
	(arc
		(start 85.110828 -272.136362)
		(mid 85.29586 -272.090448)
		(end 85.479636 -272.141188)
		(width 0.09525)
		(layer "In2.Cu")
		(net "M_C_CPU1_SB_DQS_DP<4>")
	)
	(arc
		(start 80.40243 -272.141188)
		(mid 80.586205 -272.090416)
		(end 80.771238 -272.136362)
		(width 0.09525)
		(layer "In2.Cu")
		(net "M_C_CPU1_SB_DQS_DP<4>")
	)
	(arc
		(start 82.659474 -272.141188)
		(mid 82.940906 -272.216943)
		(end 83.222338 -272.141188)
		(width 0.09525)
		(layer "In2.Cu")
		(net "M_C_CPU1_SB_DQS_DP<4>")
	)
	(arc
		(start 94.51086 -272.136362)
		(mid 94.695892 -272.090448)
		(end 94.879668 -272.141188)
		(width 0.09525)
		(layer "In2.Cu")
		(net "M_C_CPU1_SB_DQS_DP<4>")
	)
	(arc
		(start 86.982554 -272.141188)
		(mid 87.171022 -272.090511)
		(end 87.35949 -272.141188)
		(width 0.09525)
		(layer "In2.Cu")
		(net "M_C_CPU1_SB_DQS_DP<4>")
	)
	(arc
		(start 79.473552 -272.13433)
		(mid 79.657187 -272.09038)
		(end 79.839058 -272.141188)
		(width 0.09525)
		(layer "In2.Cu")
		(net "M_C_CPU1_SB_DQS_DP<4>")
	)
	(arc
		(start 90.750898 -272.136362)
		(mid 90.93593 -272.090448)
		(end 91.119706 -272.141188)
		(width 0.09525)
		(layer "In2.Cu")
		(net "M_C_CPU1_SB_DQS_DP<4>")
	)
	(arc
		(start 81.719674 -272.141188)
		(mid 82.001106 -272.216943)
		(end 82.282538 -272.141188)
		(width 0.09525)
		(layer "In2.Cu")
		(net "M_C_CPU1_SB_DQS_DP<4>")
	)
	(arc
		(start 88.862408 -272.141188)
		(mid 89.046183 -272.090416)
		(end 89.231216 -272.136362)
		(width 0.09525)
		(layer "In2.Cu")
		(net "M_C_CPU1_SB_DQS_DP<4>")
	)
	(arc
		(start 91.68257 -272.141188)
		(mid 91.871038 -272.090511)
		(end 92.059506 -272.141188)
		(width 0.09525)
		(layer "In2.Cu")
		(net "M_C_CPU1_SB_DQS_DP<4>")
	)
	(arc
		(start 88.299544 -272.141188)
		(mid 88.580976 -272.216943)
		(end 88.862408 -272.141188)
		(width 0.09525)
		(layer "In2.Cu")
		(net "M_C_CPU1_SB_DQS_DP<4>")
	)
	(arc
		(start 85.479636 -272.141188)
		(mid 85.761068 -272.216943)
		(end 86.0425 -272.141188)
		(width 0.09525)
		(layer "In2.Cu")
		(net "M_C_CPU1_SB_DQS_DP<4>")
	)
	(arc
		(start 87.922354 -272.141188)
		(mid 88.106129 -272.090416)
		(end 88.291162 -272.136362)
		(width 0.09525)
		(layer "In2.Cu")
		(net "M_C_CPU1_SB_DQS_DP<4>")
	)
	(arc
		(start 84.162392 -272.141188)
		(mid 84.346167 -272.090416)
		(end 84.5312 -272.136362)
		(width 0.09525)
		(layer "In2.Cu")
		(net "M_C_CPU1_SB_DQS_DP<4>")
	)
	(arc
		(start 78.711044 -272.090134)
		(mid 78.808512 -272.103262)
		(end 78.899258 -272.141188)
		(width 0.09525)
		(layer "In2.Cu")
		(net "M_C_CPU1_SB_DQS_DP<4>")
	)
	(arc
		(start 92.059506 -272.141188)
		(mid 92.340938 -272.216943)
		(end 92.62237 -272.141188)
		(width 0.09525)
		(layer "In2.Cu")
		(net "M_C_CPU1_SB_DQS_DP<4>")
	)
	(segment
		(start 95.157798 -290.020248)
		(end 94.690946 -290.286186)
		(width 0.12954)
		(layer "F.Cu")
		(net "M_C_CPU1_SB_DQS_DP<3>")
	)
	(segment
		(start 76.861416 -293.510716)
		(end 77.148436 -293.510716)
		(width 0.09525)
		(layer "In2.Cu")
		(net "M_C_CPU1_SB_DQS_DP<3>")
	)
	(segment
		(start 76.35748 -295.319958)
		(end 76.35748 -295.296336)
		(width 0.09525)
		(layer "In2.Cu")
		(net "M_C_CPU1_SB_DQS_DP<3>")
	)
	(segment
		(start 79.47025 -290.954968)
		(end 79.725012 -290.700206)
		(width 0.09525)
		(layer "In2.Cu")
		(net "M_C_CPU1_SB_DQS_DP<3>")
	)
	(segment
		(start 60.800742 -312.24474)
		(end 61.173614 -312.617612)
		(width 0.16002)
		(layer "In2.Cu")
		(net "M_C_CPU1_SB_DQS_DP<3>")
	)
	(segment
		(start 72.76973 -303.783746)
		(end 76.35748 -300.195996)
		(width 0.16002)
		(layer "In2.Cu")
		(net "M_C_CPU1_SB_DQS_DP<3>")
	)
	(segment
		(start 58.138568 -312.59526)
		(end 58.489088 -312.24474)
		(width 0.16002)
		(layer "In2.Cu")
		(net "M_C_CPU1_SB_DQS_DP<3>")
	)
	(segment
		(start 67.045078 -309.24627)
		(end 66.753994 -308.955186)
		(width 0.16002)
		(layer "In2.Cu")
		(net "M_C_CPU1_SB_DQS_DP<3>")
	)
	(segment
		(start 70.87489 -304.306986)
		(end 71.39813 -303.783746)
		(width 0.16002)
		(layer "In2.Cu")
		(net "M_C_CPU1_SB_DQS_DP<3>")
	)
	(segment
		(start 61.173614 -312.825892)
		(end 61.369448 -313.021726)
		(width 0.16002)
		(layer "In2.Cu")
		(net "M_C_CPU1_SB_DQS_DP<3>")
	)
	(segment
		(start 84.5312 -290.616132)
		(end 84.539582 -290.611306)
		(width 0.09525)
		(layer "In2.Cu")
		(net "M_C_CPU1_SB_DQS_DP<3>")
	)
	(segment
		(start 81.342484 -290.611306)
		(end 81.350866 -290.616132)
		(width 0.09525)
		(layer "In2.Cu")
		(net "M_C_CPU1_SB_DQS_DP<3>")
	)
	(segment
		(start 51.015392 -312.210196)
		(end 53.132228 -312.210196)
		(width 0.16002)
		(layer "In2.Cu")
		(net "M_C_CPU1_SB_DQS_DP<3>")
	)
	(segment
		(start 69.318886 -306.972462)
		(end 69.595746 -306.972462)
		(width 0.16002)
		(layer "In2.Cu")
		(net "M_C_CPU1_SB_DQS_DP<3>")
	)
	(segment
		(start 85.102446 -290.611306)
		(end 85.110828 -290.616132)
		(width 0.09525)
		(layer "In2.Cu")
		(net "M_C_CPU1_SB_DQS_DP<3>")
	)
	(segment
		(start 66.571622 -309.719726)
		(end 66.848482 -309.719726)
		(width 0.16002)
		(layer "In2.Cu")
		(net "M_C_CPU1_SB_DQS_DP<3>")
	)
	(segment
		(start 68.222114 -308.346094)
		(end 68.41871 -308.149498)
		(width 0.16002)
		(layer "In2.Cu")
		(net "M_C_CPU1_SB_DQS_DP<3>")
	)
	(segment
		(start 69.595746 -306.972462)
		(end 69.792342 -306.775866)
		(width 0.16002)
		(layer "In2.Cu")
		(net "M_C_CPU1_SB_DQS_DP<3>")
	)
	(segment
		(start 78.12786 -292.531292)
		(end 78.12786 -291.642292)
		(width 0.09525)
		(layer "In2.Cu")
		(net "M_C_CPU1_SB_DQS_DP<3>")
	)
	(segment
		(start 90.742516 -290.611306)
		(end 90.750898 -290.616132)
		(width 0.09525)
		(layer "In2.Cu")
		(net "M_C_CPU1_SB_DQS_DP<3>")
	)
	(segment
		(start 56.235092 -313.10326)
		(end 56.524652 -313.39282)
		(width 0.16002)
		(layer "In2.Cu")
		(net "M_C_CPU1_SB_DQS_DP<3>")
	)
	(segment
		(start 80.771238 -290.616132)
		(end 80.77962 -290.611306)
		(width 0.09525)
		(layer "In2.Cu")
		(net "M_C_CPU1_SB_DQS_DP<3>")
	)
	(segment
		(start 61.173614 -312.617612)
		(end 61.173614 -312.825892)
		(width 0.16002)
		(layer "In2.Cu")
		(net "M_C_CPU1_SB_DQS_DP<3>")
	)
	(segment
		(start 68.127626 -307.05425)
		(end 68.500498 -306.681378)
		(width 0.16002)
		(layer "In2.Cu")
		(net "M_C_CPU1_SB_DQS_DP<3>")
	)
	(segment
		(start 44.340018 -312.935366)
		(end 44.61383 -313.209178)
		(width 0.16002)
		(layer "In2.Cu")
		(net "M_C_CPU1_SB_DQS_DP<3>")
	)
	(segment
		(start 67.945254 -308.346094)
		(end 68.222114 -308.346094)
		(width 0.16002)
		(layer "In2.Cu")
		(net "M_C_CPU1_SB_DQS_DP<3>")
	)
	(segment
		(start 92.991178 -290.616132)
		(end 92.99956 -290.611306)
		(width 0.09525)
		(layer "In2.Cu")
		(net "M_C_CPU1_SB_DQS_DP<3>")
	)
	(segment
		(start 61.841888 -312.825892)
		(end 61.841888 -312.617612)
		(width 0.16002)
		(layer "In2.Cu")
		(net "M_C_CPU1_SB_DQS_DP<3>")
	)
	(segment
		(start 66.848482 -309.719726)
		(end 67.045078 -309.52313)
		(width 0.16002)
		(layer "In2.Cu")
		(net "M_C_CPU1_SB_DQS_DP<3>")
	)
	(segment
		(start 65.753234 -309.428642)
		(end 66.280538 -309.428642)
		(width 0.16002)
		(layer "In2.Cu")
		(net "M_C_CPU1_SB_DQS_DP<3>")
	)
	(segment
		(start 67.126866 -308.05501)
		(end 67.65417 -308.05501)
		(width 0.16002)
		(layer "In2.Cu")
		(net "M_C_CPU1_SB_DQS_DP<3>")
	)
	(segment
		(start 53.132228 -312.210196)
		(end 54.025292 -313.10326)
		(width 0.16002)
		(layer "In2.Cu")
		(net "M_C_CPU1_SB_DQS_DP<3>")
	)
	(segment
		(start 78.12786 -291.642292)
		(end 78.351888 -291.418264)
		(width 0.09525)
		(layer "In2.Cu")
		(net "M_C_CPU1_SB_DQS_DP<3>")
	)
	(segment
		(start 50.297588 -312.5216)
		(end 50.703988 -312.5216)
		(width 0.16002)
		(layer "In2.Cu")
		(net "M_C_CPU1_SB_DQS_DP<3>")
	)
	(segment
		(start 67.045078 -309.52313)
		(end 67.045078 -309.24627)
		(width 0.16002)
		(layer "In2.Cu")
		(net "M_C_CPU1_SB_DQS_DP<3>")
	)
	(segment
		(start 67.65417 -308.05501)
		(end 67.945254 -308.346094)
		(width 0.16002)
		(layer "In2.Cu")
		(net "M_C_CPU1_SB_DQS_DP<3>")
	)
	(segment
		(start 45.501814 -313.209178)
		(end 45.650912 -313.06008)
		(width 0.16002)
		(layer "In2.Cu")
		(net "M_C_CPU1_SB_DQS_DP<3>")
	)
	(segment
		(start 89.802462 -290.611306)
		(end 89.810844 -290.616132)
		(width 0.09525)
		(layer "In2.Cu")
		(net "M_C_CPU1_SB_DQS_DP<3>")
	)
	(segment
		(start 48.678592 -313.06008)
		(end 48.993552 -313.37504)
		(width 0.16002)
		(layer "In2.Cu")
		(net "M_C_CPU1_SB_DQS_DP<3>")
	)
	(segment
		(start 78.351888 -291.418264)
		(end 79.47025 -290.954968)
		(width 0.09525)
		(layer "In2.Cu")
		(net "M_C_CPU1_SB_DQS_DP<3>")
	)
	(segment
		(start 76.416662 -293.95547)
		(end 76.861416 -293.510716)
		(width 0.09525)
		(layer "In2.Cu")
		(net "M_C_CPU1_SB_DQS_DP<3>")
	)
	(segment
		(start 79.841344 -290.611052)
		(end 79.86522 -290.597336)
		(width 0.09525)
		(layer "In2.Cu")
		(net "M_C_CPU1_SB_DQS_DP<3>")
	)
	(segment
		(start 61.646054 -313.021726)
		(end 61.841888 -312.825892)
		(width 0.16002)
		(layer "In2.Cu")
		(net "M_C_CPU1_SB_DQS_DP<3>")
	)
	(segment
		(start 69.501258 -306.207922)
		(end 69.501258 -305.680618)
		(width 0.16002)
		(layer "In2.Cu")
		(net "M_C_CPU1_SB_DQS_DP<3>")
	)
	(segment
		(start 57.661048 -312.59526)
		(end 58.138568 -312.59526)
		(width 0.16002)
		(layer "In2.Cu")
		(net "M_C_CPU1_SB_DQS_DP<3>")
	)
	(segment
		(start 61.369448 -313.021726)
		(end 61.646054 -313.021726)
		(width 0.16002)
		(layer "In2.Cu")
		(net "M_C_CPU1_SB_DQS_DP<3>")
	)
	(segment
		(start 71.165974 -305.125374)
		(end 70.87489 -304.83429)
		(width 0.16002)
		(layer "In2.Cu")
		(net "M_C_CPU1_SB_DQS_DP<3>")
	)
	(segment
		(start 45.650912 -313.06008)
		(end 48.678592 -313.06008)
		(width 0.16002)
		(layer "In2.Cu")
		(net "M_C_CPU1_SB_DQS_DP<3>")
	)
	(segment
		(start 70.401434 -305.307746)
		(end 70.692518 -305.59883)
		(width 0.16002)
		(layer "In2.Cu")
		(net "M_C_CPU1_SB_DQS_DP<3>")
	)
	(segment
		(start 76.416662 -295.237154)
		(end 76.416662 -293.95547)
		(width 0.09525)
		(layer "In2.Cu")
		(net "M_C_CPU1_SB_DQS_DP<3>")
	)
	(segment
		(start 69.792342 -306.499006)
		(end 69.501258 -306.207922)
		(width 0.16002)
		(layer "In2.Cu")
		(net "M_C_CPU1_SB_DQS_DP<3>")
	)
	(segment
		(start 94.436184 -290.578286)
		(end 94.537022 -290.551616)
		(width 0.09525)
		(layer "In2.Cu")
		(net "M_C_CPU1_SB_DQS_DP<3>")
	)
	(segment
		(start 68.41871 -307.872638)
		(end 68.127626 -307.581554)
		(width 0.16002)
		(layer "In2.Cu")
		(net "M_C_CPU1_SB_DQS_DP<3>")
	)
	(segment
		(start 70.692518 -305.59883)
		(end 70.969378 -305.59883)
		(width 0.16002)
		(layer "In2.Cu")
		(net "M_C_CPU1_SB_DQS_DP<3>")
	)
	(segment
		(start 66.753994 -308.427882)
		(end 67.126866 -308.05501)
		(width 0.16002)
		(layer "In2.Cu")
		(net "M_C_CPU1_SB_DQS_DP<3>")
	)
	(segment
		(start 70.969378 -305.59883)
		(end 71.165974 -305.402234)
		(width 0.16002)
		(layer "In2.Cu")
		(net "M_C_CPU1_SB_DQS_DP<3>")
	)
	(segment
		(start 66.753994 -308.955186)
		(end 66.753994 -308.427882)
		(width 0.16002)
		(layer "In2.Cu")
		(net "M_C_CPU1_SB_DQS_DP<3>")
	)
	(segment
		(start 86.0425 -290.611306)
		(end 86.050882 -290.616132)
		(width 0.09525)
		(layer "In2.Cu")
		(net "M_C_CPU1_SB_DQS_DP<3>")
	)
	(segment
		(start 56.863488 -313.39282)
		(end 57.661048 -312.59526)
		(width 0.16002)
		(layer "In2.Cu")
		(net "M_C_CPU1_SB_DQS_DP<3>")
	)
	(segment
		(start 66.280538 -309.428642)
		(end 66.571622 -309.719726)
		(width 0.16002)
		(layer "In2.Cu")
		(net "M_C_CPU1_SB_DQS_DP<3>")
	)
	(segment
		(start 71.165974 -305.402234)
		(end 71.165974 -305.125374)
		(width 0.16002)
		(layer "In2.Cu")
		(net "M_C_CPU1_SB_DQS_DP<3>")
	)
	(segment
		(start 68.41871 -308.149498)
		(end 68.41871 -307.872638)
		(width 0.16002)
		(layer "In2.Cu")
		(net "M_C_CPU1_SB_DQS_DP<3>")
	)
	(segment
		(start 69.87413 -305.307746)
		(end 70.401434 -305.307746)
		(width 0.16002)
		(layer "In2.Cu")
		(net "M_C_CPU1_SB_DQS_DP<3>")
	)
	(segment
		(start 61.841888 -312.617612)
		(end 62.21476 -312.24474)
		(width 0.16002)
		(layer "In2.Cu")
		(net "M_C_CPU1_SB_DQS_DP<3>")
	)
	(segment
		(start 70.87489 -304.83429)
		(end 70.87489 -304.306986)
		(width 0.16002)
		(layer "In2.Cu")
		(net "M_C_CPU1_SB_DQS_DP<3>")
	)
	(segment
		(start 49.444148 -313.37504)
		(end 50.297588 -312.5216)
		(width 0.16002)
		(layer "In2.Cu")
		(net "M_C_CPU1_SB_DQS_DP<3>")
	)
	(segment
		(start 89.231216 -290.616132)
		(end 89.239598 -290.611306)
		(width 0.09525)
		(layer "In2.Cu")
		(net "M_C_CPU1_SB_DQS_DP<3>")
	)
	(segment
		(start 44.61383 -313.209178)
		(end 45.501814 -313.209178)
		(width 0.16002)
		(layer "In2.Cu")
		(net "M_C_CPU1_SB_DQS_DP<3>")
	)
	(segment
		(start 62.937136 -312.24474)
		(end 65.753234 -309.428642)
		(width 0.16002)
		(layer "In2.Cu")
		(net "M_C_CPU1_SB_DQS_DP<3>")
	)
	(segment
		(start 50.703988 -312.5216)
		(end 51.015392 -312.210196)
		(width 0.16002)
		(layer "In2.Cu")
		(net "M_C_CPU1_SB_DQS_DP<3>")
	)
	(segment
		(start 48.993552 -313.37504)
		(end 49.444148 -313.37504)
		(width 0.16002)
		(layer "In2.Cu")
		(net "M_C_CPU1_SB_DQS_DP<3>")
	)
	(segment
		(start 76.35748 -300.195996)
		(end 76.35748 -295.319958)
		(width 0.16002)
		(layer "In2.Cu")
		(net "M_C_CPU1_SB_DQS_DP<3>")
	)
	(segment
		(start 76.35748 -295.296336)
		(end 76.416662 -295.237154)
		(width 0.09525)
		(layer "In2.Cu")
		(net "M_C_CPU1_SB_DQS_DP<3>")
	)
	(segment
		(start 93.931232 -290.616132)
		(end 93.939614 -290.611306)
		(width 0.09525)
		(layer "In2.Cu")
		(net "M_C_CPU1_SB_DQS_DP<3>")
	)
	(segment
		(start 83.591146 -290.616132)
		(end 83.599528 -290.611306)
		(width 0.09525)
		(layer "In2.Cu")
		(net "M_C_CPU1_SB_DQS_DP<3>")
	)
	(segment
		(start 94.537022 -290.551616)
		(end 94.690946 -290.286186)
		(width 0.09525)
		(layer "In2.Cu")
		(net "M_C_CPU1_SB_DQS_DP<3>")
	)
	(segment
		(start 88.291162 -290.616132)
		(end 88.299544 -290.611306)
		(width 0.09525)
		(layer "In2.Cu")
		(net "M_C_CPU1_SB_DQS_DP<3>")
	)
	(segment
		(start 68.127626 -307.581554)
		(end 68.127626 -307.05425)
		(width 0.16002)
		(layer "In2.Cu")
		(net "M_C_CPU1_SB_DQS_DP<3>")
	)
	(segment
		(start 77.148436 -293.510716)
		(end 78.12786 -292.531292)
		(width 0.09525)
		(layer "In2.Cu")
		(net "M_C_CPU1_SB_DQS_DP<3>")
	)
	(segment
		(start 69.792342 -306.775866)
		(end 69.792342 -306.499006)
		(width 0.16002)
		(layer "In2.Cu")
		(net "M_C_CPU1_SB_DQS_DP<3>")
	)
	(segment
		(start 69.027802 -306.681378)
		(end 69.318886 -306.972462)
		(width 0.16002)
		(layer "In2.Cu")
		(net "M_C_CPU1_SB_DQS_DP<3>")
	)
	(segment
		(start 68.500498 -306.681378)
		(end 69.027802 -306.681378)
		(width 0.16002)
		(layer "In2.Cu")
		(net "M_C_CPU1_SB_DQS_DP<3>")
	)
	(segment
		(start 69.501258 -305.680618)
		(end 69.87413 -305.307746)
		(width 0.16002)
		(layer "In2.Cu")
		(net "M_C_CPU1_SB_DQS_DP<3>")
	)
	(segment
		(start 71.39813 -303.783746)
		(end 72.76973 -303.783746)
		(width 0.16002)
		(layer "In2.Cu")
		(net "M_C_CPU1_SB_DQS_DP<3>")
	)
	(segment
		(start 56.524652 -313.39282)
		(end 56.863488 -313.39282)
		(width 0.16002)
		(layer "In2.Cu")
		(net "M_C_CPU1_SB_DQS_DP<3>")
	)
	(segment
		(start 58.489088 -312.24474)
		(end 60.800742 -312.24474)
		(width 0.16002)
		(layer "In2.Cu")
		(net "M_C_CPU1_SB_DQS_DP<3>")
	)
	(segment
		(start 54.025292 -313.10326)
		(end 56.235092 -313.10326)
		(width 0.16002)
		(layer "In2.Cu")
		(net "M_C_CPU1_SB_DQS_DP<3>")
	)
	(segment
		(start 62.21476 -312.24474)
		(end 62.937136 -312.24474)
		(width 0.16002)
		(layer "In2.Cu")
		(net "M_C_CPU1_SB_DQS_DP<3>")
	)
	(arc
		(start 92.99956 -290.611306)
		(mid 93.280992 -290.535551)
		(end 93.562424 -290.611306)
		(width 0.09525)
		(layer "In2.Cu")
		(net "M_C_CPU1_SB_DQS_DP<3>")
	)
	(arc
		(start 82.282538 -290.611306)
		(mid 82.471006 -290.661983)
		(end 82.659474 -290.611306)
		(width 0.09525)
		(layer "In2.Cu")
		(net "M_C_CPU1_SB_DQS_DP<3>")
	)
	(arc
		(start 86.982554 -290.611306)
		(mid 87.171022 -290.661983)
		(end 87.35949 -290.611306)
		(width 0.09525)
		(layer "In2.Cu")
		(net "M_C_CPU1_SB_DQS_DP<3>")
	)
	(arc
		(start 91.68257 -290.611306)
		(mid 91.871038 -290.661983)
		(end 92.059506 -290.611306)
		(width 0.09525)
		(layer "In2.Cu")
		(net "M_C_CPU1_SB_DQS_DP<3>")
	)
	(arc
		(start 82.659474 -290.611306)
		(mid 82.940906 -290.535551)
		(end 83.222338 -290.611306)
		(width 0.09525)
		(layer "In2.Cu")
		(net "M_C_CPU1_SB_DQS_DP<3>")
	)
	(arc
		(start 86.050882 -290.616132)
		(mid 86.235914 -290.662046)
		(end 86.41969 -290.611306)
		(width 0.09525)
		(layer "In2.Cu")
		(net "M_C_CPU1_SB_DQS_DP<3>")
	)
	(arc
		(start 89.810844 -290.616132)
		(mid 89.995876 -290.662046)
		(end 90.179652 -290.611306)
		(width 0.09525)
		(layer "In2.Cu")
		(net "M_C_CPU1_SB_DQS_DP<3>")
	)
	(arc
		(start 89.239598 -290.611306)
		(mid 89.52103 -290.535551)
		(end 89.802462 -290.611306)
		(width 0.09525)
		(layer "In2.Cu")
		(net "M_C_CPU1_SB_DQS_DP<3>")
	)
	(arc
		(start 85.479636 -290.611306)
		(mid 85.761068 -290.535551)
		(end 86.0425 -290.611306)
		(width 0.09525)
		(layer "In2.Cu")
		(net "M_C_CPU1_SB_DQS_DP<3>")
	)
	(arc
		(start 79.86522 -290.597336)
		(mid 80.135603 -290.535776)
		(end 80.40243 -290.611306)
		(width 0.09525)
		(layer "In2.Cu")
		(net "M_C_CPU1_SB_DQS_DP<3>")
	)
	(arc
		(start 90.179652 -290.611306)
		(mid 90.461084 -290.535551)
		(end 90.742516 -290.611306)
		(width 0.09525)
		(layer "In2.Cu")
		(net "M_C_CPU1_SB_DQS_DP<3>")
	)
	(arc
		(start 93.562424 -290.611306)
		(mid 93.746199 -290.662078)
		(end 93.931232 -290.616132)
		(width 0.09525)
		(layer "In2.Cu")
		(net "M_C_CPU1_SB_DQS_DP<3>")
	)
	(arc
		(start 83.599528 -290.611306)
		(mid 83.88096 -290.535551)
		(end 84.162392 -290.611306)
		(width 0.09525)
		(layer "In2.Cu")
		(net "M_C_CPU1_SB_DQS_DP<3>")
	)
	(arc
		(start 87.922354 -290.611306)
		(mid 88.106129 -290.662078)
		(end 88.291162 -290.616132)
		(width 0.09525)
		(layer "In2.Cu")
		(net "M_C_CPU1_SB_DQS_DP<3>")
	)
	(arc
		(start 92.059506 -290.611306)
		(mid 92.340938 -290.535551)
		(end 92.62237 -290.611306)
		(width 0.09525)
		(layer "In2.Cu")
		(net "M_C_CPU1_SB_DQS_DP<3>")
	)
	(arc
		(start 83.222338 -290.611306)
		(mid 83.406113 -290.662078)
		(end 83.591146 -290.616132)
		(width 0.09525)
		(layer "In2.Cu")
		(net "M_C_CPU1_SB_DQS_DP<3>")
	)
	(arc
		(start 84.539582 -290.611306)
		(mid 84.821014 -290.535551)
		(end 85.102446 -290.611306)
		(width 0.09525)
		(layer "In2.Cu")
		(net "M_C_CPU1_SB_DQS_DP<3>")
	)
	(arc
		(start 80.40243 -290.611306)
		(mid 80.586205 -290.662078)
		(end 80.771238 -290.616132)
		(width 0.09525)
		(layer "In2.Cu")
		(net "M_C_CPU1_SB_DQS_DP<3>")
	)
	(arc
		(start 81.350866 -290.616132)
		(mid 81.535898 -290.662046)
		(end 81.719674 -290.611306)
		(width 0.09525)
		(layer "In2.Cu")
		(net "M_C_CPU1_SB_DQS_DP<3>")
	)
	(arc
		(start 86.41969 -290.611306)
		(mid 86.701122 -290.535551)
		(end 86.982554 -290.611306)
		(width 0.09525)
		(layer "In2.Cu")
		(net "M_C_CPU1_SB_DQS_DP<3>")
	)
	(arc
		(start 88.862408 -290.611306)
		(mid 89.046183 -290.662078)
		(end 89.231216 -290.616132)
		(width 0.09525)
		(layer "In2.Cu")
		(net "M_C_CPU1_SB_DQS_DP<3>")
	)
	(arc
		(start 91.119706 -290.611306)
		(mid 91.401138 -290.535551)
		(end 91.68257 -290.611306)
		(width 0.09525)
		(layer "In2.Cu")
		(net "M_C_CPU1_SB_DQS_DP<3>")
	)
	(arc
		(start 85.110828 -290.616132)
		(mid 85.29586 -290.662046)
		(end 85.479636 -290.611306)
		(width 0.09525)
		(layer "In2.Cu")
		(net "M_C_CPU1_SB_DQS_DP<3>")
	)
	(arc
		(start 79.725012 -290.700206)
		(mid 79.780238 -290.651791)
		(end 79.841344 -290.611052)
		(width 0.09525)
		(layer "In2.Cu")
		(net "M_C_CPU1_SB_DQS_DP<3>")
	)
	(arc
		(start 87.35949 -290.611306)
		(mid 87.640922 -290.535551)
		(end 87.922354 -290.611306)
		(width 0.09525)
		(layer "In2.Cu")
		(net "M_C_CPU1_SB_DQS_DP<3>")
	)
	(arc
		(start 92.62237 -290.611306)
		(mid 92.806145 -290.662078)
		(end 92.991178 -290.616132)
		(width 0.09525)
		(layer "In2.Cu")
		(net "M_C_CPU1_SB_DQS_DP<3>")
	)
	(arc
		(start 84.162392 -290.611306)
		(mid 84.346167 -290.662078)
		(end 84.5312 -290.616132)
		(width 0.09525)
		(layer "In2.Cu")
		(net "M_C_CPU1_SB_DQS_DP<3>")
	)
	(arc
		(start 81.719674 -290.611306)
		(mid 82.001106 -290.535551)
		(end 82.282538 -290.611306)
		(width 0.09525)
		(layer "In2.Cu")
		(net "M_C_CPU1_SB_DQS_DP<3>")
	)
	(arc
		(start 80.77962 -290.611306)
		(mid 81.061052 -290.535551)
		(end 81.342484 -290.611306)
		(width 0.09525)
		(layer "In2.Cu")
		(net "M_C_CPU1_SB_DQS_DP<3>")
	)
	(arc
		(start 88.299544 -290.611306)
		(mid 88.580976 -290.535551)
		(end 88.862408 -290.611306)
		(width 0.09525)
		(layer "In2.Cu")
		(net "M_C_CPU1_SB_DQS_DP<3>")
	)
	(arc
		(start 93.939614 -290.611306)
		(mid 94.18404 -290.536663)
		(end 94.436184 -290.578286)
		(width 0.09525)
		(layer "In2.Cu")
		(net "M_C_CPU1_SB_DQS_DP<3>")
	)
	(arc
		(start 90.750898 -290.616132)
		(mid 90.93593 -290.662046)
		(end 91.119706 -290.611306)
		(width 0.09525)
		(layer "In2.Cu")
		(net "M_C_CPU1_SB_DQS_DP<3>")
	)
	(segment
		(start 95.157798 -285.160466)
		(end 94.690946 -285.426404)
		(width 0.12954)
		(layer "F.Cu")
		(net "M_C_CPU1_SB_DQS_DP<2>")
	)
	(segment
		(start 62.839854 -302.153574)
		(end 62.839854 -301.626016)
		(width 0.16002)
		(layer "In2.Cu")
		(net "M_C_CPU1_SB_DQS_DP<2>")
	)
	(segment
		(start 92.991178 -285.75635)
		(end 92.99956 -285.751524)
		(width 0.09525)
		(layer "In2.Cu")
		(net "M_C_CPU1_SB_DQS_DP<2>")
	)
	(segment
		(start 86.0425 -285.751524)
		(end 86.050882 -285.75635)
		(width 0.09525)
		(layer "In2.Cu")
		(net "M_C_CPU1_SB_DQS_DP<2>")
	)
	(segment
		(start 51.015392 -302.860202)
		(end 52.999132 -302.860202)
		(width 0.16002)
		(layer "In2.Cu")
		(net "M_C_CPU1_SB_DQS_DP<2>")
	)
	(segment
		(start 44.340018 -303.585372)
		(end 44.61383 -303.859184)
		(width 0.16002)
		(layer "In2.Cu")
		(net "M_C_CPU1_SB_DQS_DP<2>")
	)
	(segment
		(start 53.38953 -303.940464)
		(end 53.555392 -304.106326)
		(width 0.16002)
		(layer "In2.Cu")
		(net "M_C_CPU1_SB_DQS_DP<2>")
	)
	(segment
		(start 58.489088 -302.894746)
		(end 60.581032 -302.894746)
		(width 0.16002)
		(layer "In2.Cu")
		(net "M_C_CPU1_SB_DQS_DP<2>")
	)
	(segment
		(start 65.113662 -299.879512)
		(end 65.343786 -300.109636)
		(width 0.16002)
		(layer "In2.Cu")
		(net "M_C_CPU1_SB_DQS_DP<2>")
	)
	(segment
		(start 64.443356 -301.286418)
		(end 64.443356 -301.009812)
		(width 0.16002)
		(layer "In2.Cu")
		(net "M_C_CPU1_SB_DQS_DP<2>")
	)
	(segment
		(start 70.599046 -295.130728)
		(end 70.599046 -291.798756)
		(width 0.16002)
		(layer "In2.Cu")
		(net "M_C_CPU1_SB_DQS_DP<2>")
	)
	(segment
		(start 76.24826 -286.472376)
		(end 76.918566 -286.472376)
		(width 0.09525)
		(layer "In2.Cu")
		(net "M_C_CPU1_SB_DQS_DP<2>")
	)
	(segment
		(start 53.937408 -304.106326)
		(end 54.290468 -303.753266)
		(width 0.16002)
		(layer "In2.Cu")
		(net "M_C_CPU1_SB_DQS_DP<2>")
	)
	(segment
		(start 70.599046 -291.798756)
		(end 75.984608 -286.413194)
		(width 0.16002)
		(layer "In2.Cu")
		(net "M_C_CPU1_SB_DQS_DP<2>")
	)
	(segment
		(start 53.555392 -304.106326)
		(end 53.937408 -304.106326)
		(width 0.16002)
		(layer "In2.Cu")
		(net "M_C_CPU1_SB_DQS_DP<2>")
	)
	(segment
		(start 62.835282 -302.894746)
		(end 63.069724 -302.660304)
		(width 0.16002)
		(layer "In2.Cu")
		(net "M_C_CPU1_SB_DQS_DP<2>")
	)
	(segment
		(start 85.102446 -285.751524)
		(end 85.110828 -285.75635)
		(width 0.09525)
		(layer "In2.Cu")
		(net "M_C_CPU1_SB_DQS_DP<2>")
	)
	(segment
		(start 60.953904 -303.737772)
		(end 61.149738 -303.933606)
		(width 0.16002)
		(layer "In2.Cu")
		(net "M_C_CPU1_SB_DQS_DP<2>")
	)
	(segment
		(start 83.591146 -285.75635)
		(end 83.599528 -285.751524)
		(width 0.09525)
		(layer "In2.Cu")
		(net "M_C_CPU1_SB_DQS_DP<2>")
	)
	(segment
		(start 66.99377 -298.736004)
		(end 70.599046 -295.130728)
		(width 0.16002)
		(layer "In2.Cu")
		(net "M_C_CPU1_SB_DQS_DP<2>")
	)
	(segment
		(start 89.802462 -285.751524)
		(end 89.810844 -285.75635)
		(width 0.09525)
		(layer "In2.Cu")
		(net "M_C_CPU1_SB_DQS_DP<2>")
	)
	(segment
		(start 63.069724 -302.383444)
		(end 62.839854 -302.153574)
		(width 0.16002)
		(layer "In2.Cu")
		(net "M_C_CPU1_SB_DQS_DP<2>")
	)
	(segment
		(start 65.343786 -300.109636)
		(end 65.620138 -300.109636)
		(width 0.16002)
		(layer "In2.Cu")
		(net "M_C_CPU1_SB_DQS_DP<2>")
	)
	(segment
		(start 63.212726 -301.253144)
		(end 63.74003 -301.253144)
		(width 0.16002)
		(layer "In2.Cu")
		(net "M_C_CPU1_SB_DQS_DP<2>")
	)
	(segment
		(start 65.816988 -299.63618)
		(end 65.711578 -299.53077)
		(width 0.16002)
		(layer "In2.Cu")
		(net "M_C_CPU1_SB_DQS_DP<2>")
	)
	(segment
		(start 64.213486 -300.252384)
		(end 64.586358 -299.879512)
		(width 0.16002)
		(layer "In2.Cu")
		(net "M_C_CPU1_SB_DQS_DP<2>")
	)
	(segment
		(start 63.970154 -301.483268)
		(end 64.246506 -301.483268)
		(width 0.16002)
		(layer "In2.Cu")
		(net "M_C_CPU1_SB_DQS_DP<2>")
	)
	(segment
		(start 65.816988 -299.912786)
		(end 65.816988 -299.63618)
		(width 0.16002)
		(layer "In2.Cu")
		(net "M_C_CPU1_SB_DQS_DP<2>")
	)
	(segment
		(start 54.290468 -303.753266)
		(end 56.235092 -303.753266)
		(width 0.16002)
		(layer "In2.Cu")
		(net "M_C_CPU1_SB_DQS_DP<2>")
	)
	(segment
		(start 56.524652 -304.042826)
		(end 56.863488 -304.042826)
		(width 0.16002)
		(layer "In2.Cu")
		(net "M_C_CPU1_SB_DQS_DP<2>")
	)
	(segment
		(start 93.931232 -285.75635)
		(end 93.939614 -285.751524)
		(width 0.09525)
		(layer "In2.Cu")
		(net "M_C_CPU1_SB_DQS_DP<2>")
	)
	(segment
		(start 66.08445 -298.63034)
		(end 66.611754 -298.63034)
		(width 0.16002)
		(layer "In2.Cu")
		(net "M_C_CPU1_SB_DQS_DP<2>")
	)
	(segment
		(start 50.297588 -303.171606)
		(end 50.703988 -303.171606)
		(width 0.16002)
		(layer "In2.Cu")
		(net "M_C_CPU1_SB_DQS_DP<2>")
	)
	(segment
		(start 52.999132 -302.860202)
		(end 53.38953 -303.2506)
		(width 0.16002)
		(layer "In2.Cu")
		(net "M_C_CPU1_SB_DQS_DP<2>")
	)
	(segment
		(start 64.586358 -299.879512)
		(end 65.113662 -299.879512)
		(width 0.16002)
		(layer "In2.Cu")
		(net "M_C_CPU1_SB_DQS_DP<2>")
	)
	(segment
		(start 58.138568 -303.245266)
		(end 58.489088 -302.894746)
		(width 0.16002)
		(layer "In2.Cu")
		(net "M_C_CPU1_SB_DQS_DP<2>")
	)
	(segment
		(start 61.99505 -302.894746)
		(end 62.835282 -302.894746)
		(width 0.16002)
		(layer "In2.Cu")
		(net "M_C_CPU1_SB_DQS_DP<2>")
	)
	(segment
		(start 62.839854 -301.626016)
		(end 63.212726 -301.253144)
		(width 0.16002)
		(layer "In2.Cu")
		(net "M_C_CPU1_SB_DQS_DP<2>")
	)
	(segment
		(start 64.443356 -301.009812)
		(end 64.213486 -300.779942)
		(width 0.16002)
		(layer "In2.Cu")
		(net "M_C_CPU1_SB_DQS_DP<2>")
	)
	(segment
		(start 49.444148 -304.025046)
		(end 50.297588 -303.171606)
		(width 0.16002)
		(layer "In2.Cu")
		(net "M_C_CPU1_SB_DQS_DP<2>")
	)
	(segment
		(start 77.37475 -286.2834)
		(end 77.749146 -285.909004)
		(width 0.09525)
		(layer "In2.Cu")
		(net "M_C_CPU1_SB_DQS_DP<2>")
	)
	(segment
		(start 57.661048 -303.245266)
		(end 58.138568 -303.245266)
		(width 0.16002)
		(layer "In2.Cu")
		(net "M_C_CPU1_SB_DQS_DP<2>")
	)
	(segment
		(start 90.742516 -285.751524)
		(end 90.750898 -285.75635)
		(width 0.09525)
		(layer "In2.Cu")
		(net "M_C_CPU1_SB_DQS_DP<2>")
	)
	(segment
		(start 61.426344 -303.933606)
		(end 61.622178 -303.737772)
		(width 0.16002)
		(layer "In2.Cu")
		(net "M_C_CPU1_SB_DQS_DP<2>")
	)
	(segment
		(start 48.678592 -303.710086)
		(end 48.993552 -304.025046)
		(width 0.16002)
		(layer "In2.Cu")
		(net "M_C_CPU1_SB_DQS_DP<2>")
	)
	(segment
		(start 56.235092 -303.753266)
		(end 56.524652 -304.042826)
		(width 0.16002)
		(layer "In2.Cu")
		(net "M_C_CPU1_SB_DQS_DP<2>")
	)
	(segment
		(start 61.622178 -303.267618)
		(end 61.99505 -302.894746)
		(width 0.16002)
		(layer "In2.Cu")
		(net "M_C_CPU1_SB_DQS_DP<2>")
	)
	(segment
		(start 53.38953 -303.2506)
		(end 53.38953 -303.940464)
		(width 0.16002)
		(layer "In2.Cu")
		(net "M_C_CPU1_SB_DQS_DP<2>")
	)
	(segment
		(start 61.622178 -303.737772)
		(end 61.622178 -303.267618)
		(width 0.16002)
		(layer "In2.Cu")
		(net "M_C_CPU1_SB_DQS_DP<2>")
	)
	(segment
		(start 66.717418 -298.736004)
		(end 66.99377 -298.736004)
		(width 0.16002)
		(layer "In2.Cu")
		(net "M_C_CPU1_SB_DQS_DP<2>")
	)
	(segment
		(start 76.189078 -286.413194)
		(end 76.24826 -286.472376)
		(width 0.09525)
		(layer "In2.Cu")
		(net "M_C_CPU1_SB_DQS_DP<2>")
	)
	(segment
		(start 46.838616 -303.710086)
		(end 48.678592 -303.710086)
		(width 0.16002)
		(layer "In2.Cu")
		(net "M_C_CPU1_SB_DQS_DP<2>")
	)
	(segment
		(start 65.711578 -299.53077)
		(end 65.711578 -299.003212)
		(width 0.16002)
		(layer "In2.Cu")
		(net "M_C_CPU1_SB_DQS_DP<2>")
	)
	(segment
		(start 44.61383 -303.859184)
		(end 46.689518 -303.859184)
		(width 0.16002)
		(layer "In2.Cu")
		(net "M_C_CPU1_SB_DQS_DP<2>")
	)
	(segment
		(start 50.703988 -303.171606)
		(end 51.015392 -302.860202)
		(width 0.16002)
		(layer "In2.Cu")
		(net "M_C_CPU1_SB_DQS_DP<2>")
	)
	(segment
		(start 65.711578 -299.003212)
		(end 66.08445 -298.63034)
		(width 0.16002)
		(layer "In2.Cu")
		(net "M_C_CPU1_SB_DQS_DP<2>")
	)
	(segment
		(start 48.993552 -304.025046)
		(end 49.444148 -304.025046)
		(width 0.16002)
		(layer "In2.Cu")
		(net "M_C_CPU1_SB_DQS_DP<2>")
	)
	(segment
		(start 94.537022 -285.691834)
		(end 94.690946 -285.426404)
		(width 0.09525)
		(layer "In2.Cu")
		(net "M_C_CPU1_SB_DQS_DP<2>")
	)
	(segment
		(start 88.291162 -285.75635)
		(end 88.299544 -285.751524)
		(width 0.09525)
		(layer "In2.Cu")
		(net "M_C_CPU1_SB_DQS_DP<2>")
	)
	(segment
		(start 61.149738 -303.933606)
		(end 61.426344 -303.933606)
		(width 0.16002)
		(layer "In2.Cu")
		(net "M_C_CPU1_SB_DQS_DP<2>")
	)
	(segment
		(start 79.841344 -285.75127)
		(end 79.86522 -285.737554)
		(width 0.09525)
		(layer "In2.Cu")
		(net "M_C_CPU1_SB_DQS_DP<2>")
	)
	(segment
		(start 94.436184 -285.718504)
		(end 94.537022 -285.691834)
		(width 0.09525)
		(layer "In2.Cu")
		(net "M_C_CPU1_SB_DQS_DP<2>")
	)
	(segment
		(start 75.984608 -286.413194)
		(end 76.165456 -286.413194)
		(width 0.16002)
		(layer "In2.Cu")
		(net "M_C_CPU1_SB_DQS_DP<2>")
	)
	(segment
		(start 66.611754 -298.63034)
		(end 66.717418 -298.736004)
		(width 0.16002)
		(layer "In2.Cu")
		(net "M_C_CPU1_SB_DQS_DP<2>")
	)
	(segment
		(start 46.689518 -303.859184)
		(end 46.838616 -303.710086)
		(width 0.16002)
		(layer "In2.Cu")
		(net "M_C_CPU1_SB_DQS_DP<2>")
	)
	(segment
		(start 64.246506 -301.483268)
		(end 64.443356 -301.286418)
		(width 0.16002)
		(layer "In2.Cu")
		(net "M_C_CPU1_SB_DQS_DP<2>")
	)
	(segment
		(start 78.003654 -285.803594)
		(end 78.711044 -285.803594)
		(width 0.09525)
		(layer "In2.Cu")
		(net "M_C_CPU1_SB_DQS_DP<2>")
	)
	(segment
		(start 64.213486 -300.779942)
		(end 64.213486 -300.252384)
		(width 0.16002)
		(layer "In2.Cu")
		(net "M_C_CPU1_SB_DQS_DP<2>")
	)
	(segment
		(start 63.74003 -301.253144)
		(end 63.970154 -301.483268)
		(width 0.16002)
		(layer "In2.Cu")
		(net "M_C_CPU1_SB_DQS_DP<2>")
	)
	(segment
		(start 63.069724 -302.660304)
		(end 63.069724 -302.383444)
		(width 0.16002)
		(layer "In2.Cu")
		(net "M_C_CPU1_SB_DQS_DP<2>")
	)
	(segment
		(start 65.620138 -300.109636)
		(end 65.816988 -299.912786)
		(width 0.16002)
		(layer "In2.Cu")
		(net "M_C_CPU1_SB_DQS_DP<2>")
	)
	(segment
		(start 89.231216 -285.75635)
		(end 89.239598 -285.751524)
		(width 0.09525)
		(layer "In2.Cu")
		(net "M_C_CPU1_SB_DQS_DP<2>")
	)
	(segment
		(start 76.165456 -286.413194)
		(end 76.189078 -286.413194)
		(width 0.09525)
		(layer "In2.Cu")
		(net "M_C_CPU1_SB_DQS_DP<2>")
	)
	(segment
		(start 84.5312 -285.75635)
		(end 84.539582 -285.751524)
		(width 0.09525)
		(layer "In2.Cu")
		(net "M_C_CPU1_SB_DQS_DP<2>")
	)
	(segment
		(start 60.953904 -303.267618)
		(end 60.953904 -303.737772)
		(width 0.16002)
		(layer "In2.Cu")
		(net "M_C_CPU1_SB_DQS_DP<2>")
	)
	(segment
		(start 60.581032 -302.894746)
		(end 60.953904 -303.267618)
		(width 0.16002)
		(layer "In2.Cu")
		(net "M_C_CPU1_SB_DQS_DP<2>")
	)
	(segment
		(start 79.8195 -285.763716)
		(end 79.841344 -285.75127)
		(width 0.09525)
		(layer "In2.Cu")
		(net "M_C_CPU1_SB_DQS_DP<2>")
	)
	(segment
		(start 81.342484 -285.751524)
		(end 81.350866 -285.75635)
		(width 0.09525)
		(layer "In2.Cu")
		(net "M_C_CPU1_SB_DQS_DP<2>")
	)
	(segment
		(start 79.441802 -285.737554)
		(end 79.465678 -285.751524)
		(width 0.09525)
		(layer "In2.Cu")
		(net "M_C_CPU1_SB_DQS_DP<2>")
	)
	(segment
		(start 56.863488 -304.042826)
		(end 57.661048 -303.245266)
		(width 0.16002)
		(layer "In2.Cu")
		(net "M_C_CPU1_SB_DQS_DP<2>")
	)
	(segment
		(start 80.771238 -285.75635)
		(end 80.77962 -285.751524)
		(width 0.09525)
		(layer "In2.Cu")
		(net "M_C_CPU1_SB_DQS_DP<2>")
	)
	(arc
		(start 85.110828 -285.75635)
		(mid 85.29586 -285.802264)
		(end 85.479636 -285.751524)
		(width 0.09525)
		(layer "In2.Cu")
		(net "M_C_CPU1_SB_DQS_DP<2>")
	)
	(arc
		(start 92.059506 -285.751524)
		(mid 92.340938 -285.675769)
		(end 92.62237 -285.751524)
		(width 0.09525)
		(layer "In2.Cu")
		(net "M_C_CPU1_SB_DQS_DP<2>")
	)
	(arc
		(start 83.222338 -285.751524)
		(mid 83.406113 -285.802296)
		(end 83.591146 -285.75635)
		(width 0.09525)
		(layer "In2.Cu")
		(net "M_C_CPU1_SB_DQS_DP<2>")
	)
	(arc
		(start 93.562424 -285.751524)
		(mid 93.746199 -285.802296)
		(end 93.931232 -285.75635)
		(width 0.09525)
		(layer "In2.Cu")
		(net "M_C_CPU1_SB_DQS_DP<2>")
	)
	(arc
		(start 92.62237 -285.751524)
		(mid 92.806145 -285.802296)
		(end 92.991178 -285.75635)
		(width 0.09525)
		(layer "In2.Cu")
		(net "M_C_CPU1_SB_DQS_DP<2>")
	)
	(arc
		(start 78.711044 -285.803594)
		(mid 78.809481 -285.790307)
		(end 78.901036 -285.751778)
		(width 0.09525)
		(layer "In2.Cu")
		(net "M_C_CPU1_SB_DQS_DP<2>")
	)
	(arc
		(start 80.40243 -285.751524)
		(mid 80.586205 -285.802296)
		(end 80.771238 -285.75635)
		(width 0.09525)
		(layer "In2.Cu")
		(net "M_C_CPU1_SB_DQS_DP<2>")
	)
	(arc
		(start 79.86522 -285.737554)
		(mid 80.135603 -285.675994)
		(end 80.40243 -285.751524)
		(width 0.09525)
		(layer "In2.Cu")
		(net "M_C_CPU1_SB_DQS_DP<2>")
	)
	(arc
		(start 81.350866 -285.75635)
		(mid 81.535898 -285.802264)
		(end 81.719674 -285.751524)
		(width 0.09525)
		(layer "In2.Cu")
		(net "M_C_CPU1_SB_DQS_DP<2>")
	)
	(arc
		(start 84.162392 -285.751524)
		(mid 84.346167 -285.802296)
		(end 84.5312 -285.75635)
		(width 0.09525)
		(layer "In2.Cu")
		(net "M_C_CPU1_SB_DQS_DP<2>")
	)
	(arc
		(start 90.750898 -285.75635)
		(mid 90.93593 -285.802264)
		(end 91.119706 -285.751524)
		(width 0.09525)
		(layer "In2.Cu")
		(net "M_C_CPU1_SB_DQS_DP<2>")
	)
	(arc
		(start 78.901036 -285.751778)
		(mid 79.169581 -285.675285)
		(end 79.441802 -285.737554)
		(width 0.09525)
		(layer "In2.Cu")
		(net "M_C_CPU1_SB_DQS_DP<2>")
	)
	(arc
		(start 83.599528 -285.751524)
		(mid 83.88096 -285.675769)
		(end 84.162392 -285.751524)
		(width 0.09525)
		(layer "In2.Cu")
		(net "M_C_CPU1_SB_DQS_DP<2>")
	)
	(arc
		(start 93.939614 -285.751524)
		(mid 94.18404 -285.676881)
		(end 94.436184 -285.718504)
		(width 0.09525)
		(layer "In2.Cu")
		(net "M_C_CPU1_SB_DQS_DP<2>")
	)
	(arc
		(start 82.659474 -285.751524)
		(mid 82.940906 -285.675769)
		(end 83.222338 -285.751524)
		(width 0.09525)
		(layer "In2.Cu")
		(net "M_C_CPU1_SB_DQS_DP<2>")
	)
	(arc
		(start 79.465678 -285.751524)
		(mid 79.641052 -285.801854)
		(end 79.8195 -285.763716)
		(width 0.09525)
		(layer "In2.Cu")
		(net "M_C_CPU1_SB_DQS_DP<2>")
	)
	(arc
		(start 89.239598 -285.751524)
		(mid 89.52103 -285.675769)
		(end 89.802462 -285.751524)
		(width 0.09525)
		(layer "In2.Cu")
		(net "M_C_CPU1_SB_DQS_DP<2>")
	)
	(arc
		(start 86.982554 -285.751524)
		(mid 87.171022 -285.802201)
		(end 87.35949 -285.751524)
		(width 0.09525)
		(layer "In2.Cu")
		(net "M_C_CPU1_SB_DQS_DP<2>")
	)
	(arc
		(start 89.810844 -285.75635)
		(mid 89.995876 -285.802264)
		(end 90.179652 -285.751524)
		(width 0.09525)
		(layer "In2.Cu")
		(net "M_C_CPU1_SB_DQS_DP<2>")
	)
	(arc
		(start 91.68257 -285.751524)
		(mid 91.871038 -285.802201)
		(end 92.059506 -285.751524)
		(width 0.09525)
		(layer "In2.Cu")
		(net "M_C_CPU1_SB_DQS_DP<2>")
	)
	(arc
		(start 92.99956 -285.751524)
		(mid 93.280992 -285.675769)
		(end 93.562424 -285.751524)
		(width 0.09525)
		(layer "In2.Cu")
		(net "M_C_CPU1_SB_DQS_DP<2>")
	)
	(arc
		(start 77.749146 -285.909004)
		(mid 77.865915 -285.830981)
		(end 78.003654 -285.803594)
		(width 0.09525)
		(layer "In2.Cu")
		(net "M_C_CPU1_SB_DQS_DP<2>")
	)
	(arc
		(start 80.77962 -285.751524)
		(mid 81.061052 -285.675769)
		(end 81.342484 -285.751524)
		(width 0.09525)
		(layer "In2.Cu")
		(net "M_C_CPU1_SB_DQS_DP<2>")
	)
	(arc
		(start 76.918566 -286.472376)
		(mid 77.165458 -286.423266)
		(end 77.37475 -286.2834)
		(width 0.09525)
		(layer "In2.Cu")
		(net "M_C_CPU1_SB_DQS_DP<2>")
	)
	(arc
		(start 88.299544 -285.751524)
		(mid 88.580976 -285.675769)
		(end 88.862408 -285.751524)
		(width 0.09525)
		(layer "In2.Cu")
		(net "M_C_CPU1_SB_DQS_DP<2>")
	)
	(arc
		(start 85.479636 -285.751524)
		(mid 85.761068 -285.675769)
		(end 86.0425 -285.751524)
		(width 0.09525)
		(layer "In2.Cu")
		(net "M_C_CPU1_SB_DQS_DP<2>")
	)
	(arc
		(start 88.862408 -285.751524)
		(mid 89.046183 -285.802296)
		(end 89.231216 -285.75635)
		(width 0.09525)
		(layer "In2.Cu")
		(net "M_C_CPU1_SB_DQS_DP<2>")
	)
	(arc
		(start 90.179652 -285.751524)
		(mid 90.461084 -285.675769)
		(end 90.742516 -285.751524)
		(width 0.09525)
		(layer "In2.Cu")
		(net "M_C_CPU1_SB_DQS_DP<2>")
	)
	(arc
		(start 82.282538 -285.751524)
		(mid 82.471006 -285.802201)
		(end 82.659474 -285.751524)
		(width 0.09525)
		(layer "In2.Cu")
		(net "M_C_CPU1_SB_DQS_DP<2>")
	)
	(arc
		(start 86.41969 -285.751524)
		(mid 86.701122 -285.675769)
		(end 86.982554 -285.751524)
		(width 0.09525)
		(layer "In2.Cu")
		(net "M_C_CPU1_SB_DQS_DP<2>")
	)
	(arc
		(start 81.719674 -285.751524)
		(mid 82.001106 -285.675769)
		(end 82.282538 -285.751524)
		(width 0.09525)
		(layer "In2.Cu")
		(net "M_C_CPU1_SB_DQS_DP<2>")
	)
	(arc
		(start 91.119706 -285.751524)
		(mid 91.401138 -285.675769)
		(end 91.68257 -285.751524)
		(width 0.09525)
		(layer "In2.Cu")
		(net "M_C_CPU1_SB_DQS_DP<2>")
	)
	(arc
		(start 86.050882 -285.75635)
		(mid 86.235914 -285.802264)
		(end 86.41969 -285.751524)
		(width 0.09525)
		(layer "In2.Cu")
		(net "M_C_CPU1_SB_DQS_DP<2>")
	)
	(arc
		(start 84.539582 -285.751524)
		(mid 84.821014 -285.675769)
		(end 85.102446 -285.751524)
		(width 0.09525)
		(layer "In2.Cu")
		(net "M_C_CPU1_SB_DQS_DP<2>")
	)
	(arc
		(start 87.922354 -285.751524)
		(mid 88.106129 -285.802296)
		(end 88.291162 -285.75635)
		(width 0.09525)
		(layer "In2.Cu")
		(net "M_C_CPU1_SB_DQS_DP<2>")
	)
	(arc
		(start 87.35949 -285.751524)
		(mid 87.640922 -285.675769)
		(end 87.922354 -285.751524)
		(width 0.09525)
		(layer "In2.Cu")
		(net "M_C_CPU1_SB_DQS_DP<2>")
	)
	(segment
		(start 95.157798 -280.30043)
		(end 94.690946 -280.566368)
		(width 0.12954)
		(layer "F.Cu")
		(net "M_C_CPU1_SB_DQS_DP<1>")
	)
	(segment
		(start 63.003176 -292.528752)
		(end 63.280036 -292.528752)
		(width 0.16002)
		(layer "In2.Cu")
		(net "M_C_CPU1_SB_DQS_DP<1>")
	)
	(segment
		(start 51.015392 -293.510208)
		(end 53.132228 -293.510208)
		(width 0.16002)
		(layer "In2.Cu")
		(net "M_C_CPU1_SB_DQS_DP<1>")
	)
	(segment
		(start 64.536066 -289.890454)
		(end 65.02908 -289.39744)
		(width 0.16002)
		(layer "In2.Cu")
		(net "M_C_CPU1_SB_DQS_DP<1>")
	)
	(segment
		(start 48.993552 -294.675052)
		(end 49.3268 -294.675052)
		(width 0.16002)
		(layer "In2.Cu")
		(net "M_C_CPU1_SB_DQS_DP<1>")
	)
	(segment
		(start 60.82919 -294.375586)
		(end 60.98921 -294.535606)
		(width 0.16002)
		(layer "In2.Cu")
		(net "M_C_CPU1_SB_DQS_DP<1>")
	)
	(segment
		(start 49.3268 -294.675052)
		(end 50.18024 -293.821612)
		(width 0.16002)
		(layer "In2.Cu")
		(net "M_C_CPU1_SB_DQS_DP<1>")
	)
	(segment
		(start 63.491618 -290.797234)
		(end 64.018922 -290.797234)
		(width 0.16002)
		(layer "In2.Cu")
		(net "M_C_CPU1_SB_DQS_DP<1>")
	)
	(segment
		(start 50.703988 -293.821612)
		(end 51.015392 -293.510208)
		(width 0.16002)
		(layer "In2.Cu")
		(net "M_C_CPU1_SB_DQS_DP<1>")
	)
	(segment
		(start 64.018922 -290.797234)
		(end 64.376808 -291.15512)
		(width 0.16002)
		(layer "In2.Cu")
		(net "M_C_CPU1_SB_DQS_DP<1>")
	)
	(segment
		(start 88.291162 -280.896314)
		(end 88.299544 -280.891488)
		(width 0.09525)
		(layer "In2.Cu")
		(net "M_C_CPU1_SB_DQS_DP<1>")
	)
	(segment
		(start 57.661048 -293.895272)
		(end 58.138568 -293.895272)
		(width 0.16002)
		(layer "In2.Cu")
		(net "M_C_CPU1_SB_DQS_DP<1>")
	)
	(segment
		(start 63.118746 -291.69741)
		(end 63.118746 -291.170106)
		(width 0.16002)
		(layer "In2.Cu")
		(net "M_C_CPU1_SB_DQS_DP<1>")
	)
	(segment
		(start 56.547004 -294.692832)
		(end 56.863488 -294.692832)
		(width 0.16002)
		(layer "In2.Cu")
		(net "M_C_CPU1_SB_DQS_DP<1>")
	)
	(segment
		(start 62.117986 -292.170866)
		(end 62.64529 -292.170866)
		(width 0.16002)
		(layer "In2.Cu")
		(net "M_C_CPU1_SB_DQS_DP<1>")
	)
	(segment
		(start 90.742516 -280.891488)
		(end 90.750898 -280.896314)
		(width 0.09525)
		(layer "In2.Cu")
		(net "M_C_CPU1_SB_DQS_DP<1>")
	)
	(segment
		(start 58.489088 -293.544752)
		(end 60.423298 -293.544752)
		(width 0.16002)
		(layer "In2.Cu")
		(net "M_C_CPU1_SB_DQS_DP<1>")
	)
	(segment
		(start 73.645776 -280.780744)
		(end 75.955906 -280.780744)
		(width 0.16002)
		(layer "In2.Cu")
		(net "M_C_CPU1_SB_DQS_DP<1>")
	)
	(segment
		(start 65.02908 -289.39744)
		(end 65.02908 -289.160204)
		(width 0.16002)
		(layer "In2.Cu")
		(net "M_C_CPU1_SB_DQS_DP<1>")
	)
	(segment
		(start 94.537022 -280.831798)
		(end 94.690946 -280.566368)
		(width 0.09525)
		(layer "In2.Cu")
		(net "M_C_CPU1_SB_DQS_DP<1>")
	)
	(segment
		(start 77.578458 -280.528014)
		(end 77.992478 -280.942034)
		(width 0.09525)
		(layer "In2.Cu")
		(net "M_C_CPU1_SB_DQS_DP<1>")
	)
	(segment
		(start 67.422268 -287.004252)
		(end 67.776344 -286.650176)
		(width 0.16002)
		(layer "In2.Cu")
		(net "M_C_CPU1_SB_DQS_DP<1>")
	)
	(segment
		(start 56.863488 -294.692832)
		(end 57.661048 -293.895272)
		(width 0.16002)
		(layer "In2.Cu")
		(net "M_C_CPU1_SB_DQS_DP<1>")
	)
	(segment
		(start 60.423298 -293.544752)
		(end 60.82919 -293.950644)
		(width 0.16002)
		(layer "In2.Cu")
		(net "M_C_CPU1_SB_DQS_DP<1>")
	)
	(segment
		(start 53.132228 -293.510208)
		(end 54.025292 -294.403272)
		(width 0.16002)
		(layer "In2.Cu")
		(net "M_C_CPU1_SB_DQS_DP<1>")
	)
	(segment
		(start 66.048636 -288.377884)
		(end 66.402712 -288.023808)
		(width 0.16002)
		(layer "In2.Cu")
		(net "M_C_CPU1_SB_DQS_DP<1>")
	)
	(segment
		(start 66.402712 -288.023808)
		(end 66.402712 -287.786572)
		(width 0.16002)
		(layer "In2.Cu")
		(net "M_C_CPU1_SB_DQS_DP<1>")
	)
	(segment
		(start 54.025292 -294.403272)
		(end 56.257444 -294.403272)
		(width 0.16002)
		(layer "In2.Cu")
		(net "M_C_CPU1_SB_DQS_DP<1>")
	)
	(segment
		(start 89.802462 -280.891488)
		(end 89.810844 -280.896314)
		(width 0.09525)
		(layer "In2.Cu")
		(net "M_C_CPU1_SB_DQS_DP<1>")
	)
	(segment
		(start 56.257444 -294.403272)
		(end 56.547004 -294.692832)
		(width 0.16002)
		(layer "In2.Cu")
		(net "M_C_CPU1_SB_DQS_DP<1>")
	)
	(segment
		(start 64.850264 -290.958524)
		(end 64.850264 -290.681664)
		(width 0.16002)
		(layer "In2.Cu")
		(net "M_C_CPU1_SB_DQS_DP<1>")
	)
	(segment
		(start 76.695808 -280.528014)
		(end 77.578458 -280.528014)
		(width 0.09525)
		(layer "In2.Cu")
		(net "M_C_CPU1_SB_DQS_DP<1>")
	)
	(segment
		(start 85.102446 -280.891488)
		(end 85.110828 -280.896314)
		(width 0.09525)
		(layer "In2.Cu")
		(net "M_C_CPU1_SB_DQS_DP<1>")
	)
	(segment
		(start 92.991178 -280.896314)
		(end 92.99956 -280.891488)
		(width 0.09525)
		(layer "In2.Cu")
		(net "M_C_CPU1_SB_DQS_DP<1>")
	)
	(segment
		(start 61.280802 -294.535606)
		(end 62.103 -293.713408)
		(width 0.16002)
		(layer "In2.Cu")
		(net "M_C_CPU1_SB_DQS_DP<1>")
	)
	(segment
		(start 45.307758 -294.50919)
		(end 45.456856 -294.360092)
		(width 0.16002)
		(layer "In2.Cu")
		(net "M_C_CPU1_SB_DQS_DP<1>")
	)
	(segment
		(start 89.231216 -280.896314)
		(end 89.239598 -280.891488)
		(width 0.09525)
		(layer "In2.Cu")
		(net "M_C_CPU1_SB_DQS_DP<1>")
	)
	(segment
		(start 58.138568 -293.895272)
		(end 58.489088 -293.544752)
		(width 0.16002)
		(layer "In2.Cu")
		(net "M_C_CPU1_SB_DQS_DP<1>")
	)
	(segment
		(start 67.185032 -287.004252)
		(end 67.422268 -287.004252)
		(width 0.16002)
		(layer "In2.Cu")
		(net "M_C_CPU1_SB_DQS_DP<1>")
	)
	(segment
		(start 63.118746 -291.170106)
		(end 63.491618 -290.797234)
		(width 0.16002)
		(layer "In2.Cu")
		(net "M_C_CPU1_SB_DQS_DP<1>")
	)
	(segment
		(start 60.82919 -293.950644)
		(end 60.82919 -294.375586)
		(width 0.16002)
		(layer "In2.Cu")
		(net "M_C_CPU1_SB_DQS_DP<1>")
	)
	(segment
		(start 80.771238 -280.896314)
		(end 80.77962 -280.891488)
		(width 0.09525)
		(layer "In2.Cu")
		(net "M_C_CPU1_SB_DQS_DP<1>")
	)
	(segment
		(start 60.98921 -294.535606)
		(end 61.280802 -294.535606)
		(width 0.16002)
		(layer "In2.Cu")
		(net "M_C_CPU1_SB_DQS_DP<1>")
	)
	(segment
		(start 65.02908 -289.160204)
		(end 65.8114 -288.377884)
		(width 0.16002)
		(layer "In2.Cu")
		(net "M_C_CPU1_SB_DQS_DP<1>")
	)
	(segment
		(start 48.678592 -294.360092)
		(end 48.993552 -294.675052)
		(width 0.16002)
		(layer "In2.Cu")
		(net "M_C_CPU1_SB_DQS_DP<1>")
	)
	(segment
		(start 77.992478 -280.942034)
		(end 79.654146 -280.942034)
		(width 0.09525)
		(layer "In2.Cu")
		(net "M_C_CPU1_SB_DQS_DP<1>")
	)
	(segment
		(start 44.340018 -294.235378)
		(end 44.61383 -294.50919)
		(width 0.16002)
		(layer "In2.Cu")
		(net "M_C_CPU1_SB_DQS_DP<1>")
	)
	(segment
		(start 64.536066 -290.367466)
		(end 64.536066 -289.890454)
		(width 0.16002)
		(layer "In2.Cu")
		(net "M_C_CPU1_SB_DQS_DP<1>")
	)
	(segment
		(start 66.402712 -287.786572)
		(end 67.185032 -287.004252)
		(width 0.16002)
		(layer "In2.Cu")
		(net "M_C_CPU1_SB_DQS_DP<1>")
	)
	(segment
		(start 86.0425 -280.891488)
		(end 86.050882 -280.896314)
		(width 0.09525)
		(layer "In2.Cu")
		(net "M_C_CPU1_SB_DQS_DP<1>")
	)
	(segment
		(start 63.280036 -292.528752)
		(end 63.476632 -292.332156)
		(width 0.16002)
		(layer "In2.Cu")
		(net "M_C_CPU1_SB_DQS_DP<1>")
	)
	(segment
		(start 75.979528 -280.780744)
		(end 76.03871 -280.839926)
		(width 0.09525)
		(layer "In2.Cu")
		(net "M_C_CPU1_SB_DQS_DP<1>")
	)
	(segment
		(start 83.591146 -280.896314)
		(end 83.599528 -280.891488)
		(width 0.09525)
		(layer "In2.Cu")
		(net "M_C_CPU1_SB_DQS_DP<1>")
	)
	(segment
		(start 67.776344 -286.650176)
		(end 67.776344 -286.41294)
		(width 0.16002)
		(layer "In2.Cu")
		(net "M_C_CPU1_SB_DQS_DP<1>")
	)
	(segment
		(start 67.776344 -286.41294)
		(end 68.558664 -285.63062)
		(width 0.16002)
		(layer "In2.Cu")
		(net "M_C_CPU1_SB_DQS_DP<1>")
	)
	(segment
		(start 50.18024 -293.821612)
		(end 50.703988 -293.821612)
		(width 0.16002)
		(layer "In2.Cu")
		(net "M_C_CPU1_SB_DQS_DP<1>")
	)
	(segment
		(start 79.841344 -280.891234)
		(end 79.86522 -280.877518)
		(width 0.09525)
		(layer "In2.Cu")
		(net "M_C_CPU1_SB_DQS_DP<1>")
	)
	(segment
		(start 62.64529 -292.170866)
		(end 63.003176 -292.528752)
		(width 0.16002)
		(layer "In2.Cu")
		(net "M_C_CPU1_SB_DQS_DP<1>")
	)
	(segment
		(start 62.103 -293.428928)
		(end 61.745114 -293.071042)
		(width 0.16002)
		(layer "In2.Cu")
		(net "M_C_CPU1_SB_DQS_DP<1>")
	)
	(segment
		(start 68.7959 -285.63062)
		(end 73.645776 -280.780744)
		(width 0.16002)
		(layer "In2.Cu")
		(net "M_C_CPU1_SB_DQS_DP<1>")
	)
	(segment
		(start 64.850264 -290.681664)
		(end 64.536066 -290.367466)
		(width 0.16002)
		(layer "In2.Cu")
		(net "M_C_CPU1_SB_DQS_DP<1>")
	)
	(segment
		(start 61.745114 -292.543738)
		(end 62.117986 -292.170866)
		(width 0.16002)
		(layer "In2.Cu")
		(net "M_C_CPU1_SB_DQS_DP<1>")
	)
	(segment
		(start 63.476632 -292.055296)
		(end 63.118746 -291.69741)
		(width 0.16002)
		(layer "In2.Cu")
		(net "M_C_CPU1_SB_DQS_DP<1>")
	)
	(segment
		(start 84.5312 -280.896314)
		(end 84.539582 -280.891488)
		(width 0.09525)
		(layer "In2.Cu")
		(net "M_C_CPU1_SB_DQS_DP<1>")
	)
	(segment
		(start 75.955906 -280.780744)
		(end 75.979528 -280.780744)
		(width 0.09525)
		(layer "In2.Cu")
		(net "M_C_CPU1_SB_DQS_DP<1>")
	)
	(segment
		(start 64.653668 -291.15512)
		(end 64.850264 -290.958524)
		(width 0.16002)
		(layer "In2.Cu")
		(net "M_C_CPU1_SB_DQS_DP<1>")
	)
	(segment
		(start 76.03871 -280.839926)
		(end 76.383896 -280.839926)
		(width 0.09525)
		(layer "In2.Cu")
		(net "M_C_CPU1_SB_DQS_DP<1>")
	)
	(segment
		(start 68.558664 -285.63062)
		(end 68.7959 -285.63062)
		(width 0.16002)
		(layer "In2.Cu")
		(net "M_C_CPU1_SB_DQS_DP<1>")
	)
	(segment
		(start 93.931232 -280.896314)
		(end 93.939614 -280.891488)
		(width 0.09525)
		(layer "In2.Cu")
		(net "M_C_CPU1_SB_DQS_DP<1>")
	)
	(segment
		(start 45.456856 -294.360092)
		(end 48.678592 -294.360092)
		(width 0.16002)
		(layer "In2.Cu")
		(net "M_C_CPU1_SB_DQS_DP<1>")
	)
	(segment
		(start 81.342484 -280.891488)
		(end 81.350866 -280.896314)
		(width 0.09525)
		(layer "In2.Cu")
		(net "M_C_CPU1_SB_DQS_DP<1>")
	)
	(segment
		(start 44.61383 -294.50919)
		(end 45.307758 -294.50919)
		(width 0.16002)
		(layer "In2.Cu")
		(net "M_C_CPU1_SB_DQS_DP<1>")
	)
	(segment
		(start 76.383896 -280.839926)
		(end 76.695808 -280.528014)
		(width 0.09525)
		(layer "In2.Cu")
		(net "M_C_CPU1_SB_DQS_DP<1>")
	)
	(segment
		(start 65.8114 -288.377884)
		(end 66.048636 -288.377884)
		(width 0.16002)
		(layer "In2.Cu")
		(net "M_C_CPU1_SB_DQS_DP<1>")
	)
	(segment
		(start 64.376808 -291.15512)
		(end 64.653668 -291.15512)
		(width 0.16002)
		(layer "In2.Cu")
		(net "M_C_CPU1_SB_DQS_DP<1>")
	)
	(segment
		(start 63.476632 -292.332156)
		(end 63.476632 -292.055296)
		(width 0.16002)
		(layer "In2.Cu")
		(net "M_C_CPU1_SB_DQS_DP<1>")
	)
	(segment
		(start 61.745114 -293.071042)
		(end 61.745114 -292.543738)
		(width 0.16002)
		(layer "In2.Cu")
		(net "M_C_CPU1_SB_DQS_DP<1>")
	)
	(segment
		(start 62.103 -293.713408)
		(end 62.103 -293.428928)
		(width 0.16002)
		(layer "In2.Cu")
		(net "M_C_CPU1_SB_DQS_DP<1>")
	)
	(segment
		(start 94.436184 -280.858468)
		(end 94.537022 -280.831798)
		(width 0.09525)
		(layer "In2.Cu")
		(net "M_C_CPU1_SB_DQS_DP<1>")
	)
	(arc
		(start 85.479636 -280.891488)
		(mid 85.761068 -280.815733)
		(end 86.0425 -280.891488)
		(width 0.09525)
		(layer "In2.Cu")
		(net "M_C_CPU1_SB_DQS_DP<1>")
	)
	(arc
		(start 81.719674 -280.891488)
		(mid 82.001106 -280.815733)
		(end 82.282538 -280.891488)
		(width 0.09525)
		(layer "In2.Cu")
		(net "M_C_CPU1_SB_DQS_DP<1>")
	)
	(arc
		(start 89.239598 -280.891488)
		(mid 89.52103 -280.815733)
		(end 89.802462 -280.891488)
		(width 0.09525)
		(layer "In2.Cu")
		(net "M_C_CPU1_SB_DQS_DP<1>")
	)
	(arc
		(start 83.599528 -280.891488)
		(mid 83.88096 -280.815733)
		(end 84.162392 -280.891488)
		(width 0.09525)
		(layer "In2.Cu")
		(net "M_C_CPU1_SB_DQS_DP<1>")
	)
	(arc
		(start 86.982554 -280.891488)
		(mid 87.171022 -280.942165)
		(end 87.35949 -280.891488)
		(width 0.09525)
		(layer "In2.Cu")
		(net "M_C_CPU1_SB_DQS_DP<1>")
	)
	(arc
		(start 80.40243 -280.891488)
		(mid 80.586205 -280.94226)
		(end 80.771238 -280.896314)
		(width 0.09525)
		(layer "In2.Cu")
		(net "M_C_CPU1_SB_DQS_DP<1>")
	)
	(arc
		(start 84.539582 -280.891488)
		(mid 84.821014 -280.815733)
		(end 85.102446 -280.891488)
		(width 0.09525)
		(layer "In2.Cu")
		(net "M_C_CPU1_SB_DQS_DP<1>")
	)
	(arc
		(start 93.939614 -280.891488)
		(mid 94.173409 -280.817621)
		(end 94.416372 -280.850594)
		(width 0.09525)
		(layer "In2.Cu")
		(net "M_C_CPU1_SB_DQS_DP<1>")
	)
	(arc
		(start 86.41969 -280.891488)
		(mid 86.701122 -280.815733)
		(end 86.982554 -280.891488)
		(width 0.09525)
		(layer "In2.Cu")
		(net "M_C_CPU1_SB_DQS_DP<1>")
	)
	(arc
		(start 85.110828 -280.896314)
		(mid 85.29586 -280.942228)
		(end 85.479636 -280.891488)
		(width 0.09525)
		(layer "In2.Cu")
		(net "M_C_CPU1_SB_DQS_DP<1>")
	)
	(arc
		(start 88.299544 -280.891488)
		(mid 88.580976 -280.815733)
		(end 88.862408 -280.891488)
		(width 0.09525)
		(layer "In2.Cu")
		(net "M_C_CPU1_SB_DQS_DP<1>")
	)
	(arc
		(start 92.62237 -280.891488)
		(mid 92.806145 -280.94226)
		(end 92.991178 -280.896314)
		(width 0.09525)
		(layer "In2.Cu")
		(net "M_C_CPU1_SB_DQS_DP<1>")
	)
	(arc
		(start 92.99956 -280.891488)
		(mid 93.280992 -280.815733)
		(end 93.562424 -280.891488)
		(width 0.09525)
		(layer "In2.Cu")
		(net "M_C_CPU1_SB_DQS_DP<1>")
	)
	(arc
		(start 83.222338 -280.891488)
		(mid 83.406113 -280.94226)
		(end 83.591146 -280.896314)
		(width 0.09525)
		(layer "In2.Cu")
		(net "M_C_CPU1_SB_DQS_DP<1>")
	)
	(arc
		(start 82.282538 -280.891488)
		(mid 82.471006 -280.942165)
		(end 82.659474 -280.891488)
		(width 0.09525)
		(layer "In2.Cu")
		(net "M_C_CPU1_SB_DQS_DP<1>")
	)
	(arc
		(start 91.119706 -280.891488)
		(mid 91.401138 -280.815733)
		(end 91.68257 -280.891488)
		(width 0.09525)
		(layer "In2.Cu")
		(net "M_C_CPU1_SB_DQS_DP<1>")
	)
	(arc
		(start 79.86522 -280.877518)
		(mid 80.135603 -280.815958)
		(end 80.40243 -280.891488)
		(width 0.09525)
		(layer "In2.Cu")
		(net "M_C_CPU1_SB_DQS_DP<1>")
	)
	(arc
		(start 81.350866 -280.896314)
		(mid 81.535898 -280.942228)
		(end 81.719674 -280.891488)
		(width 0.09525)
		(layer "In2.Cu")
		(net "M_C_CPU1_SB_DQS_DP<1>")
	)
	(arc
		(start 90.750898 -280.896314)
		(mid 90.93593 -280.942228)
		(end 91.119706 -280.891488)
		(width 0.09525)
		(layer "In2.Cu")
		(net "M_C_CPU1_SB_DQS_DP<1>")
	)
	(arc
		(start 92.059506 -280.891488)
		(mid 92.340938 -280.815733)
		(end 92.62237 -280.891488)
		(width 0.09525)
		(layer "In2.Cu")
		(net "M_C_CPU1_SB_DQS_DP<1>")
	)
	(arc
		(start 79.654146 -280.942034)
		(mid 79.751069 -280.928899)
		(end 79.841344 -280.891234)
		(width 0.09525)
		(layer "In2.Cu")
		(net "M_C_CPU1_SB_DQS_DP<1>")
	)
	(arc
		(start 90.179652 -280.891488)
		(mid 90.461084 -280.815733)
		(end 90.742516 -280.891488)
		(width 0.09525)
		(layer "In2.Cu")
		(net "M_C_CPU1_SB_DQS_DP<1>")
	)
	(arc
		(start 80.77962 -280.891488)
		(mid 81.061052 -280.815733)
		(end 81.342484 -280.891488)
		(width 0.09525)
		(layer "In2.Cu")
		(net "M_C_CPU1_SB_DQS_DP<1>")
	)
	(arc
		(start 89.810844 -280.896314)
		(mid 89.995876 -280.942228)
		(end 90.179652 -280.891488)
		(width 0.09525)
		(layer "In2.Cu")
		(net "M_C_CPU1_SB_DQS_DP<1>")
	)
	(arc
		(start 88.862408 -280.891488)
		(mid 89.046183 -280.94226)
		(end 89.231216 -280.896314)
		(width 0.09525)
		(layer "In2.Cu")
		(net "M_C_CPU1_SB_DQS_DP<1>")
	)
	(arc
		(start 94.416372 -280.850594)
		(mid 94.426315 -280.854437)
		(end 94.436184 -280.858468)
		(width 0.09525)
		(layer "In2.Cu")
		(net "M_C_CPU1_SB_DQS_DP<1>")
	)
	(arc
		(start 86.050882 -280.896314)
		(mid 86.235914 -280.942228)
		(end 86.41969 -280.891488)
		(width 0.09525)
		(layer "In2.Cu")
		(net "M_C_CPU1_SB_DQS_DP<1>")
	)
	(arc
		(start 87.35949 -280.891488)
		(mid 87.640922 -280.815733)
		(end 87.922354 -280.891488)
		(width 0.09525)
		(layer "In2.Cu")
		(net "M_C_CPU1_SB_DQS_DP<1>")
	)
	(arc
		(start 87.922354 -280.891488)
		(mid 88.106129 -280.94226)
		(end 88.291162 -280.896314)
		(width 0.09525)
		(layer "In2.Cu")
		(net "M_C_CPU1_SB_DQS_DP<1>")
	)
	(arc
		(start 93.562424 -280.891488)
		(mid 93.746199 -280.94226)
		(end 93.931232 -280.896314)
		(width 0.09525)
		(layer "In2.Cu")
		(net "M_C_CPU1_SB_DQS_DP<1>")
	)
	(arc
		(start 84.162392 -280.891488)
		(mid 84.346167 -280.94226)
		(end 84.5312 -280.896314)
		(width 0.09525)
		(layer "In2.Cu")
		(net "M_C_CPU1_SB_DQS_DP<1>")
	)
	(arc
		(start 91.68257 -280.891488)
		(mid 91.871038 -280.942165)
		(end 92.059506 -280.891488)
		(width 0.09525)
		(layer "In2.Cu")
		(net "M_C_CPU1_SB_DQS_DP<1>")
	)
	(arc
		(start 82.659474 -280.891488)
		(mid 82.940906 -280.815733)
		(end 83.222338 -280.891488)
		(width 0.09525)
		(layer "In2.Cu")
		(net "M_C_CPU1_SB_DQS_DP<1>")
	)
	(segment
		(start 95.157798 -275.440394)
		(end 94.690946 -275.706332)
		(width 0.12954)
		(layer "F.Cu")
		(net "M_C_CPU1_SB_DQS_DP<0>")
	)
	(segment
		(start 61.482986 -284.54604)
		(end 61.759592 -284.54604)
		(width 0.16002)
		(layer "In2.Cu")
		(net "M_C_CPU1_SB_DQS_DP<0>")
	)
	(segment
		(start 67.07886 -278.751284)
		(end 67.59321 -278.236934)
		(width 0.16002)
		(layer "In2.Cu")
		(net "M_C_CPU1_SB_DQS_DP<0>")
	)
	(segment
		(start 50.99558 -284.160214)
		(end 53.132228 -284.160214)
		(width 0.16002)
		(layer "In2.Cu")
		(net "M_C_CPU1_SB_DQS_DP<0>")
	)
	(segment
		(start 94.436184 -275.998432)
		(end 94.537022 -275.971762)
		(width 0.09525)
		(layer "In2.Cu")
		(net "M_C_CPU1_SB_DQS_DP<0>")
	)
	(segment
		(start 76.03871 -275.216366)
		(end 76.416916 -275.216366)
		(width 0.09525)
		(layer "In2.Cu")
		(net "M_C_CPU1_SB_DQS_DP<0>")
	)
	(segment
		(start 69.826124 -276.00402)
		(end 70.340474 -275.48967)
		(width 0.16002)
		(layer "In2.Cu")
		(net "M_C_CPU1_SB_DQS_DP<0>")
	)
	(segment
		(start 61.759592 -284.54604)
		(end 61.956442 -284.34919)
		(width 0.16002)
		(layer "In2.Cu")
		(net "M_C_CPU1_SB_DQS_DP<0>")
	)
	(segment
		(start 65.705228 -280.646886)
		(end 65.705228 -280.124916)
		(width 0.16002)
		(layer "In2.Cu")
		(net "M_C_CPU1_SB_DQS_DP<0>")
	)
	(segment
		(start 61.956442 -284.34919)
		(end 61.956442 -284.072838)
		(width 0.16002)
		(layer "In2.Cu")
		(net "M_C_CPU1_SB_DQS_DP<0>")
	)
	(segment
		(start 89.802462 -276.031452)
		(end 89.810844 -276.036278)
		(width 0.09525)
		(layer "In2.Cu")
		(net "M_C_CPU1_SB_DQS_DP<0>")
	)
	(segment
		(start 54.301136 -285.053278)
		(end 56.274716 -285.053278)
		(width 0.16002)
		(layer "In2.Cu")
		(net "M_C_CPU1_SB_DQS_DP<0>")
	)
	(segment
		(start 68.966842 -276.863302)
		(end 69.49186 -276.863302)
		(width 0.16002)
		(layer "In2.Cu")
		(net "M_C_CPU1_SB_DQS_DP<0>")
	)
	(segment
		(start 78.89748 -276.031198)
		(end 78.930754 -276.012148)
		(width 0.09525)
		(layer "In2.Cu")
		(net "M_C_CPU1_SB_DQS_DP<0>")
	)
	(segment
		(start 77.338936 -275.657564)
		(end 78.362556 -276.08149)
		(width 0.09525)
		(layer "In2.Cu")
		(net "M_C_CPU1_SB_DQS_DP<0>")
	)
	(segment
		(start 71.197978 -275.157184)
		(end 75.955906 -275.157184)
		(width 0.16002)
		(layer "In2.Cu")
		(net "M_C_CPU1_SB_DQS_DP<0>")
	)
	(segment
		(start 56.564276 -285.342838)
		(end 56.863488 -285.342838)
		(width 0.16002)
		(layer "In2.Cu")
		(net "M_C_CPU1_SB_DQS_DP<0>")
	)
	(segment
		(start 78.362556 -276.08149)
		(end 78.711044 -276.08149)
		(width 0.09525)
		(layer "In2.Cu")
		(net "M_C_CPU1_SB_DQS_DP<0>")
	)
	(segment
		(start 58.489088 -284.194758)
		(end 60.728606 -284.194758)
		(width 0.16002)
		(layer "In2.Cu")
		(net "M_C_CPU1_SB_DQS_DP<0>")
	)
	(segment
		(start 92.991178 -276.036278)
		(end 92.99956 -276.031452)
		(width 0.09525)
		(layer "In2.Cu")
		(net "M_C_CPU1_SB_DQS_DP<0>")
	)
	(segment
		(start 53.952648 -285.401766)
		(end 54.301136 -285.053278)
		(width 0.16002)
		(layer "In2.Cu")
		(net "M_C_CPU1_SB_DQS_DP<0>")
	)
	(segment
		(start 63.330074 -282.975812)
		(end 63.330074 -282.699206)
		(width 0.16002)
		(layer "In2.Cu")
		(net "M_C_CPU1_SB_DQS_DP<0>")
	)
	(segment
		(start 63.457582 -281.353006)
		(end 64.999108 -281.353006)
		(width 0.16002)
		(layer "In2.Cu")
		(net "M_C_CPU1_SB_DQS_DP<0>")
	)
	(segment
		(start 80.37068 -276.01291)
		(end 80.40243 -276.031452)
		(width 0.09525)
		(layer "In2.Cu")
		(net "M_C_CPU1_SB_DQS_DP<0>")
	)
	(segment
		(start 44.340018 -284.885384)
		(end 44.61383 -285.159196)
		(width 0.16002)
		(layer "In2.Cu")
		(net "M_C_CPU1_SB_DQS_DP<0>")
	)
	(segment
		(start 45.501814 -285.159196)
		(end 45.650912 -285.010098)
		(width 0.16002)
		(layer "In2.Cu")
		(net "M_C_CPU1_SB_DQS_DP<0>")
	)
	(segment
		(start 44.61383 -285.159196)
		(end 45.501814 -285.159196)
		(width 0.16002)
		(layer "In2.Cu")
		(net "M_C_CPU1_SB_DQS_DP<0>")
	)
	(segment
		(start 94.537022 -275.971762)
		(end 94.690946 -275.706332)
		(width 0.09525)
		(layer "In2.Cu")
		(net "M_C_CPU1_SB_DQS_DP<0>")
	)
	(segment
		(start 48.993552 -285.325058)
		(end 49.444148 -285.325058)
		(width 0.16002)
		(layer "In2.Cu")
		(net "M_C_CPU1_SB_DQS_DP<0>")
	)
	(segment
		(start 61.131196 -284.19425)
		(end 61.482986 -284.54604)
		(width 0.16002)
		(layer "In2.Cu")
		(net "M_C_CPU1_SB_DQS_DP<0>")
	)
	(segment
		(start 79.457296 -276.031452)
		(end 79.483712 -276.046692)
		(width 0.09525)
		(layer "In2.Cu")
		(net "M_C_CPU1_SB_DQS_DP<0>")
	)
	(segment
		(start 93.931232 -276.036278)
		(end 93.939614 -276.031452)
		(width 0.09525)
		(layer "In2.Cu")
		(net "M_C_CPU1_SB_DQS_DP<0>")
	)
	(segment
		(start 56.274716 -285.053278)
		(end 56.564276 -285.342838)
		(width 0.16002)
		(layer "In2.Cu")
		(net "M_C_CPU1_SB_DQS_DP<0>")
	)
	(segment
		(start 75.979528 -275.157184)
		(end 76.03871 -275.216366)
		(width 0.09525)
		(layer "In2.Cu")
		(net "M_C_CPU1_SB_DQS_DP<0>")
	)
	(segment
		(start 86.0425 -276.031452)
		(end 86.050882 -276.036278)
		(width 0.09525)
		(layer "In2.Cu")
		(net "M_C_CPU1_SB_DQS_DP<0>")
	)
	(segment
		(start 88.291162 -276.036278)
		(end 88.299544 -276.031452)
		(width 0.09525)
		(layer "In2.Cu")
		(net "M_C_CPU1_SB_DQS_DP<0>")
	)
	(segment
		(start 57.661048 -284.545278)
		(end 58.138568 -284.545278)
		(width 0.16002)
		(layer "In2.Cu")
		(net "M_C_CPU1_SB_DQS_DP<0>")
	)
	(segment
		(start 70.865492 -275.48967)
		(end 71.197978 -275.157184)
		(width 0.16002)
		(layer "In2.Cu")
		(net "M_C_CPU1_SB_DQS_DP<0>")
	)
	(segment
		(start 56.863488 -285.342838)
		(end 57.661048 -284.545278)
		(width 0.16002)
		(layer "In2.Cu")
		(net "M_C_CPU1_SB_DQS_DP<0>")
	)
	(segment
		(start 69.826124 -276.529038)
		(end 69.826124 -276.00402)
		(width 0.16002)
		(layer "In2.Cu")
		(net "M_C_CPU1_SB_DQS_DP<0>")
	)
	(segment
		(start 67.07886 -279.276302)
		(end 67.07886 -278.751284)
		(width 0.16002)
		(layer "In2.Cu")
		(net "M_C_CPU1_SB_DQS_DP<0>")
	)
	(segment
		(start 61.572394 -283.161486)
		(end 61.945266 -282.788614)
		(width 0.16002)
		(layer "In2.Cu")
		(net "M_C_CPU1_SB_DQS_DP<0>")
	)
	(segment
		(start 61.945266 -282.788614)
		(end 62.472824 -282.788614)
		(width 0.16002)
		(layer "In2.Cu")
		(net "M_C_CPU1_SB_DQS_DP<0>")
	)
	(segment
		(start 63.330074 -282.699206)
		(end 62.978284 -282.347416)
		(width 0.16002)
		(layer "In2.Cu")
		(net "M_C_CPU1_SB_DQS_DP<0>")
	)
	(segment
		(start 68.452492 -277.377652)
		(end 68.966842 -276.863302)
		(width 0.16002)
		(layer "In2.Cu")
		(net "M_C_CPU1_SB_DQS_DP<0>")
	)
	(segment
		(start 62.978284 -282.347416)
		(end 62.978284 -281.832304)
		(width 0.16002)
		(layer "In2.Cu")
		(net "M_C_CPU1_SB_DQS_DP<0>")
	)
	(segment
		(start 70.340474 -275.48967)
		(end 70.865492 -275.48967)
		(width 0.16002)
		(layer "In2.Cu")
		(net "M_C_CPU1_SB_DQS_DP<0>")
	)
	(segment
		(start 64.999108 -281.353006)
		(end 65.705228 -280.646886)
		(width 0.16002)
		(layer "In2.Cu")
		(net "M_C_CPU1_SB_DQS_DP<0>")
	)
	(segment
		(start 61.956442 -284.072838)
		(end 61.572394 -283.68879)
		(width 0.16002)
		(layer "In2.Cu")
		(net "M_C_CPU1_SB_DQS_DP<0>")
	)
	(segment
		(start 50.684176 -284.471618)
		(end 50.99558 -284.160214)
		(width 0.16002)
		(layer "In2.Cu")
		(net "M_C_CPU1_SB_DQS_DP<0>")
	)
	(segment
		(start 66.219578 -279.610566)
		(end 66.744596 -279.610566)
		(width 0.16002)
		(layer "In2.Cu")
		(net "M_C_CPU1_SB_DQS_DP<0>")
	)
	(segment
		(start 66.744596 -279.610566)
		(end 67.07886 -279.276302)
		(width 0.16002)
		(layer "In2.Cu")
		(net "M_C_CPU1_SB_DQS_DP<0>")
	)
	(segment
		(start 84.5312 -276.036278)
		(end 84.539582 -276.031452)
		(width 0.09525)
		(layer "In2.Cu")
		(net "M_C_CPU1_SB_DQS_DP<0>")
	)
	(segment
		(start 58.138568 -284.545278)
		(end 58.489088 -284.194758)
		(width 0.16002)
		(layer "In2.Cu")
		(net "M_C_CPU1_SB_DQS_DP<0>")
	)
	(segment
		(start 48.678592 -285.010098)
		(end 48.993552 -285.325058)
		(width 0.16002)
		(layer "In2.Cu")
		(net "M_C_CPU1_SB_DQS_DP<0>")
	)
	(segment
		(start 53.47081 -285.192724)
		(end 53.679852 -285.401766)
		(width 0.16002)
		(layer "In2.Cu")
		(net "M_C_CPU1_SB_DQS_DP<0>")
	)
	(segment
		(start 62.472824 -282.788614)
		(end 62.856618 -283.172408)
		(width 0.16002)
		(layer "In2.Cu")
		(net "M_C_CPU1_SB_DQS_DP<0>")
	)
	(segment
		(start 53.679852 -285.401766)
		(end 53.952648 -285.401766)
		(width 0.16002)
		(layer "In2.Cu")
		(net "M_C_CPU1_SB_DQS_DP<0>")
	)
	(segment
		(start 90.742516 -276.031452)
		(end 90.750898 -276.036278)
		(width 0.09525)
		(layer "In2.Cu")
		(net "M_C_CPU1_SB_DQS_DP<0>")
	)
	(segment
		(start 68.118228 -278.236934)
		(end 68.452492 -277.90267)
		(width 0.16002)
		(layer "In2.Cu")
		(net "M_C_CPU1_SB_DQS_DP<0>")
	)
	(segment
		(start 83.591146 -276.036278)
		(end 83.599528 -276.031452)
		(width 0.09525)
		(layer "In2.Cu")
		(net "M_C_CPU1_SB_DQS_DP<0>")
	)
	(segment
		(start 45.650912 -285.010098)
		(end 48.678592 -285.010098)
		(width 0.16002)
		(layer "In2.Cu")
		(net "M_C_CPU1_SB_DQS_DP<0>")
	)
	(segment
		(start 89.231216 -276.036278)
		(end 89.239598 -276.031452)
		(width 0.09525)
		(layer "In2.Cu")
		(net "M_C_CPU1_SB_DQS_DP<0>")
	)
	(segment
		(start 69.49186 -276.863302)
		(end 69.826124 -276.529038)
		(width 0.16002)
		(layer "In2.Cu")
		(net "M_C_CPU1_SB_DQS_DP<0>")
	)
	(segment
		(start 49.444148 -285.325058)
		(end 50.297588 -284.471618)
		(width 0.16002)
		(layer "In2.Cu")
		(net "M_C_CPU1_SB_DQS_DP<0>")
	)
	(segment
		(start 65.705228 -280.124916)
		(end 66.219578 -279.610566)
		(width 0.16002)
		(layer "In2.Cu")
		(net "M_C_CPU1_SB_DQS_DP<0>")
	)
	(segment
		(start 63.133478 -283.172408)
		(end 63.330074 -282.975812)
		(width 0.16002)
		(layer "In2.Cu")
		(net "M_C_CPU1_SB_DQS_DP<0>")
	)
	(segment
		(start 85.102446 -276.031452)
		(end 85.110828 -276.036278)
		(width 0.09525)
		(layer "In2.Cu")
		(net "M_C_CPU1_SB_DQS_DP<0>")
	)
	(segment
		(start 50.297588 -284.471618)
		(end 50.684176 -284.471618)
		(width 0.16002)
		(layer "In2.Cu")
		(net "M_C_CPU1_SB_DQS_DP<0>")
	)
	(segment
		(start 61.572394 -283.68879)
		(end 61.572394 -283.161486)
		(width 0.16002)
		(layer "In2.Cu")
		(net "M_C_CPU1_SB_DQS_DP<0>")
	)
	(segment
		(start 62.978284 -281.832304)
		(end 63.457582 -281.353006)
		(width 0.16002)
		(layer "In2.Cu")
		(net "M_C_CPU1_SB_DQS_DP<0>")
	)
	(segment
		(start 81.342484 -276.031452)
		(end 81.350866 -276.036278)
		(width 0.09525)
		(layer "In2.Cu")
		(net "M_C_CPU1_SB_DQS_DP<0>")
	)
	(segment
		(start 53.47081 -284.498796)
		(end 53.47081 -285.192724)
		(width 0.16002)
		(layer "In2.Cu")
		(net "M_C_CPU1_SB_DQS_DP<0>")
	)
	(segment
		(start 76.858114 -275.657564)
		(end 77.338936 -275.657564)
		(width 0.09525)
		(layer "In2.Cu")
		(net "M_C_CPU1_SB_DQS_DP<0>")
	)
	(segment
		(start 76.416916 -275.216366)
		(end 76.858114 -275.657564)
		(width 0.09525)
		(layer "In2.Cu")
		(net "M_C_CPU1_SB_DQS_DP<0>")
	)
	(segment
		(start 68.452492 -277.90267)
		(end 68.452492 -277.377652)
		(width 0.16002)
		(layer "In2.Cu")
		(net "M_C_CPU1_SB_DQS_DP<0>")
	)
	(segment
		(start 75.955906 -275.157184)
		(end 75.979528 -275.157184)
		(width 0.09525)
		(layer "In2.Cu")
		(net "M_C_CPU1_SB_DQS_DP<0>")
	)
	(segment
		(start 53.132228 -284.160214)
		(end 53.47081 -284.498796)
		(width 0.16002)
		(layer "In2.Cu")
		(net "M_C_CPU1_SB_DQS_DP<0>")
	)
	(segment
		(start 62.856618 -283.172408)
		(end 63.133478 -283.172408)
		(width 0.16002)
		(layer "In2.Cu")
		(net "M_C_CPU1_SB_DQS_DP<0>")
	)
	(segment
		(start 60.728606 -284.194758)
		(end 61.131196 -284.19425)
		(width 0.16002)
		(layer "In2.Cu")
		(net "M_C_CPU1_SB_DQS_DP<0>")
	)
	(segment
		(start 80.771238 -276.036278)
		(end 80.77962 -276.031452)
		(width 0.09525)
		(layer "In2.Cu")
		(net "M_C_CPU1_SB_DQS_DP<0>")
	)
	(segment
		(start 67.59321 -278.236934)
		(end 68.118228 -278.236934)
		(width 0.16002)
		(layer "In2.Cu")
		(net "M_C_CPU1_SB_DQS_DP<0>")
	)
	(arc
		(start 84.162392 -276.031452)
		(mid 84.346167 -276.082224)
		(end 84.5312 -276.036278)
		(width 0.09525)
		(layer "In2.Cu")
		(net "M_C_CPU1_SB_DQS_DP<0>")
	)
	(arc
		(start 86.41969 -276.031452)
		(mid 86.701122 -275.955697)
		(end 86.982554 -276.031452)
		(width 0.09525)
		(layer "In2.Cu")
		(net "M_C_CPU1_SB_DQS_DP<0>")
	)
	(arc
		(start 92.059506 -276.031452)
		(mid 92.340938 -275.955697)
		(end 92.62237 -276.031452)
		(width 0.09525)
		(layer "In2.Cu")
		(net "M_C_CPU1_SB_DQS_DP<0>")
	)
	(arc
		(start 90.750898 -276.036278)
		(mid 90.93593 -276.082192)
		(end 91.119706 -276.031452)
		(width 0.09525)
		(layer "In2.Cu")
		(net "M_C_CPU1_SB_DQS_DP<0>")
	)
	(arc
		(start 89.239598 -276.031452)
		(mid 89.52103 -275.955697)
		(end 89.802462 -276.031452)
		(width 0.09525)
		(layer "In2.Cu")
		(net "M_C_CPU1_SB_DQS_DP<0>")
	)
	(arc
		(start 91.68257 -276.031452)
		(mid 91.871038 -276.082129)
		(end 92.059506 -276.031452)
		(width 0.09525)
		(layer "In2.Cu")
		(net "M_C_CPU1_SB_DQS_DP<0>")
	)
	(arc
		(start 81.350866 -276.036278)
		(mid 81.535898 -276.082192)
		(end 81.719674 -276.031452)
		(width 0.09525)
		(layer "In2.Cu")
		(net "M_C_CPU1_SB_DQS_DP<0>")
	)
	(arc
		(start 79.483712 -276.046692)
		(mid 79.662093 -276.083068)
		(end 79.836772 -276.031706)
		(width 0.09525)
		(layer "In2.Cu")
		(net "M_C_CPU1_SB_DQS_DP<0>")
	)
	(arc
		(start 85.110828 -276.036278)
		(mid 85.29586 -276.082192)
		(end 85.479636 -276.031452)
		(width 0.09525)
		(layer "In2.Cu")
		(net "M_C_CPU1_SB_DQS_DP<0>")
	)
	(arc
		(start 89.810844 -276.036278)
		(mid 89.995876 -276.082192)
		(end 90.179652 -276.031452)
		(width 0.09525)
		(layer "In2.Cu")
		(net "M_C_CPU1_SB_DQS_DP<0>")
	)
	(arc
		(start 91.119706 -276.031452)
		(mid 91.401138 -275.955697)
		(end 91.68257 -276.031452)
		(width 0.09525)
		(layer "In2.Cu")
		(net "M_C_CPU1_SB_DQS_DP<0>")
	)
	(arc
		(start 83.222338 -276.031452)
		(mid 83.406113 -276.082224)
		(end 83.591146 -276.036278)
		(width 0.09525)
		(layer "In2.Cu")
		(net "M_C_CPU1_SB_DQS_DP<0>")
	)
	(arc
		(start 82.659474 -276.031452)
		(mid 82.940906 -275.955697)
		(end 83.222338 -276.031452)
		(width 0.09525)
		(layer "In2.Cu")
		(net "M_C_CPU1_SB_DQS_DP<0>")
	)
	(arc
		(start 90.179652 -276.031452)
		(mid 90.461084 -275.955697)
		(end 90.742516 -276.031452)
		(width 0.09525)
		(layer "In2.Cu")
		(net "M_C_CPU1_SB_DQS_DP<0>")
	)
	(arc
		(start 92.99956 -276.031452)
		(mid 93.280992 -275.955697)
		(end 93.562424 -276.031452)
		(width 0.09525)
		(layer "In2.Cu")
		(net "M_C_CPU1_SB_DQS_DP<0>")
	)
	(arc
		(start 84.539582 -276.031452)
		(mid 84.821014 -275.955697)
		(end 85.102446 -276.031452)
		(width 0.09525)
		(layer "In2.Cu")
		(net "M_C_CPU1_SB_DQS_DP<0>")
	)
	(arc
		(start 83.599528 -276.031452)
		(mid 83.88096 -275.955697)
		(end 84.162392 -276.031452)
		(width 0.09525)
		(layer "In2.Cu")
		(net "M_C_CPU1_SB_DQS_DP<0>")
	)
	(arc
		(start 80.77962 -276.031452)
		(mid 81.061052 -275.955697)
		(end 81.342484 -276.031452)
		(width 0.09525)
		(layer "In2.Cu")
		(net "M_C_CPU1_SB_DQS_DP<0>")
	)
	(arc
		(start 82.282538 -276.031452)
		(mid 82.471006 -276.082129)
		(end 82.659474 -276.031452)
		(width 0.09525)
		(layer "In2.Cu")
		(net "M_C_CPU1_SB_DQS_DP<0>")
	)
	(arc
		(start 88.862408 -276.031452)
		(mid 89.046183 -276.082224)
		(end 89.231216 -276.036278)
		(width 0.09525)
		(layer "In2.Cu")
		(net "M_C_CPU1_SB_DQS_DP<0>")
	)
	(arc
		(start 78.930754 -276.012148)
		(mid 79.19643 -275.956103)
		(end 79.457296 -276.031452)
		(width 0.09525)
		(layer "In2.Cu")
		(net "M_C_CPU1_SB_DQS_DP<0>")
	)
	(arc
		(start 86.982554 -276.031452)
		(mid 87.171022 -276.082129)
		(end 87.35949 -276.031452)
		(width 0.09525)
		(layer "In2.Cu")
		(net "M_C_CPU1_SB_DQS_DP<0>")
	)
	(arc
		(start 81.719674 -276.031452)
		(mid 82.001106 -275.955697)
		(end 82.282538 -276.031452)
		(width 0.09525)
		(layer "In2.Cu")
		(net "M_C_CPU1_SB_DQS_DP<0>")
	)
	(arc
		(start 85.479636 -276.031452)
		(mid 85.761068 -275.955697)
		(end 86.0425 -276.031452)
		(width 0.09525)
		(layer "In2.Cu")
		(net "M_C_CPU1_SB_DQS_DP<0>")
	)
	(arc
		(start 78.711044 -276.08149)
		(mid 78.807567 -276.068581)
		(end 78.89748 -276.031198)
		(width 0.09525)
		(layer "In2.Cu")
		(net "M_C_CPU1_SB_DQS_DP<0>")
	)
	(arc
		(start 93.939614 -276.031452)
		(mid 94.18404 -275.956809)
		(end 94.436184 -275.998432)
		(width 0.09525)
		(layer "In2.Cu")
		(net "M_C_CPU1_SB_DQS_DP<0>")
	)
	(arc
		(start 92.62237 -276.031452)
		(mid 92.806145 -276.082224)
		(end 92.991178 -276.036278)
		(width 0.09525)
		(layer "In2.Cu")
		(net "M_C_CPU1_SB_DQS_DP<0>")
	)
	(arc
		(start 80.40243 -276.031452)
		(mid 80.586205 -276.082224)
		(end 80.771238 -276.036278)
		(width 0.09525)
		(layer "In2.Cu")
		(net "M_C_CPU1_SB_DQS_DP<0>")
	)
	(arc
		(start 86.050882 -276.036278)
		(mid 86.235914 -276.082192)
		(end 86.41969 -276.031452)
		(width 0.09525)
		(layer "In2.Cu")
		(net "M_C_CPU1_SB_DQS_DP<0>")
	)
	(arc
		(start 87.35949 -276.031452)
		(mid 87.640922 -275.955697)
		(end 87.922354 -276.031452)
		(width 0.09525)
		(layer "In2.Cu")
		(net "M_C_CPU1_SB_DQS_DP<0>")
	)
	(arc
		(start 87.922354 -276.031452)
		(mid 88.106129 -276.082224)
		(end 88.291162 -276.036278)
		(width 0.09525)
		(layer "In2.Cu")
		(net "M_C_CPU1_SB_DQS_DP<0>")
	)
	(arc
		(start 79.836772 -276.031706)
		(mid 80.101337 -275.954852)
		(end 80.37068 -276.01291)
		(width 0.09525)
		(layer "In2.Cu")
		(net "M_C_CPU1_SB_DQS_DP<0>")
	)
	(arc
		(start 93.562424 -276.031452)
		(mid 93.746199 -276.082224)
		(end 93.931232 -276.036278)
		(width 0.09525)
		(layer "In2.Cu")
		(net "M_C_CPU1_SB_DQS_DP<0>")
	)
	(arc
		(start 88.299544 -276.031452)
		(mid 88.580976 -275.955697)
		(end 88.862408 -276.031452)
		(width 0.09525)
		(layer "In2.Cu")
		(net "M_C_CPU1_SB_DQS_DP<0>")
	)
	(segment
		(start 94.687898 -271.390364)
		(end 94.221046 -271.656302)
		(width 0.12954)
		(layer "F.Cu")
		(net "M_C_CPU1_SB_DQS_DN<9>")
	)
	(segment
		(start 63.467996 -272.707862)
		(end 63.467996 -272.180558)
		(width 0.16002)
		(layer "In2.Cu")
		(net "M_C_CPU1_SB_DQS_DN<9>")
	)
	(segment
		(start 58.923428 -274.837906)
		(end 60.144152 -274.837906)
		(width 0.16002)
		(layer "In2.Cu")
		(net "M_C_CPU1_SB_DQS_DN<9>")
	)
	(segment
		(start 60.741052 -274.954746)
		(end 60.857892 -274.837906)
		(width 0.16002)
		(layer "In2.Cu")
		(net "M_C_CPU1_SB_DQS_DN<9>")
	)
	(segment
		(start 52.920392 -274.830286)
		(end 53.358796 -274.391882)
		(width 0.16002)
		(layer "In2.Cu")
		(net "M_C_CPU1_SB_DQS_DN<9>")
	)
	(segment
		(start 76.328016 -269.776956)
		(end 76.931774 -270.380714)
		(width 0.09525)
		(layer "In2.Cu")
		(net "M_C_CPU1_SB_DQS_DN<9>")
	)
	(segment
		(start 62.56782 -273.080734)
		(end 63.095124 -273.080734)
		(width 0.16002)
		(layer "In2.Cu")
		(net "M_C_CPU1_SB_DQS_DN<9>")
	)
	(segment
		(start 65.073022 -270.091408)
		(end 65.315084 -270.33347)
		(width 0.16002)
		(layer "In2.Cu")
		(net "M_C_CPU1_SB_DQS_DN<9>")
	)
	(segment
		(start 64.599566 -270.564864)
		(end 64.599566 -270.288004)
		(width 0.16002)
		(layer "In2.Cu")
		(net "M_C_CPU1_SB_DQS_DN<9>")
	)
	(segment
		(start 63.467996 -272.180558)
		(end 63.225934 -271.938496)
		(width 0.16002)
		(layer "In2.Cu")
		(net "M_C_CPU1_SB_DQS_DN<9>")
	)
	(segment
		(start 53.89753 -274.552156)
		(end 53.89753 -275.349208)
		(width 0.16002)
		(layer "In2.Cu")
		(net "M_C_CPU1_SB_DQS_DN<9>")
	)
	(segment
		(start 76.931774 -270.380714)
		(end 77.45349 -270.380714)
		(width 0.09525)
		(layer "In2.Cu")
		(net "M_C_CPU1_SB_DQS_DN<9>")
	)
	(segment
		(start 53.358796 -274.391882)
		(end 53.737256 -274.391882)
		(width 0.16002)
		(layer "In2.Cu")
		(net "M_C_CPU1_SB_DQS_DN<9>")
	)
	(segment
		(start 62.459108 -272.972022)
		(end 62.56782 -273.080734)
		(width 0.16002)
		(layer "In2.Cu")
		(net "M_C_CPU1_SB_DQS_DN<9>")
	)
	(segment
		(start 63.69939 -271.46504)
		(end 63.941452 -271.707102)
		(width 0.16002)
		(layer "In2.Cu")
		(net "M_C_CPU1_SB_DQS_DN<9>")
	)
	(segment
		(start 64.841628 -271.33423)
		(end 64.841628 -270.806926)
		(width 0.16002)
		(layer "In2.Cu")
		(net "M_C_CPU1_SB_DQS_DN<9>")
	)
	(segment
		(start 64.599566 -270.288004)
		(end 64.796162 -270.091408)
		(width 0.16002)
		(layer "In2.Cu")
		(net "M_C_CPU1_SB_DQS_DN<9>")
	)
	(segment
		(start 57.78627 -275.497544)
		(end 58.26379 -275.497544)
		(width 0.16002)
		(layer "In2.Cu")
		(net "M_C_CPU1_SB_DQS_DN<9>")
	)
	(segment
		(start 50.42281 -275.423884)
		(end 50.787046 -275.423884)
		(width 0.16002)
		(layer "In2.Cu")
		(net "M_C_CPU1_SB_DQS_DN<9>")
	)
	(segment
		(start 50.787046 -275.423884)
		(end 51.380644 -274.830286)
		(width 0.16002)
		(layer "In2.Cu")
		(net "M_C_CPU1_SB_DQS_DN<9>")
	)
	(segment
		(start 91.581224 -271.326356)
		(end 91.589606 -271.331182)
		(width 0.09525)
		(layer "In2.Cu")
		(net "M_C_CPU1_SB_DQS_DN<9>")
	)
	(segment
		(start 44.61383 -276.111462)
		(end 45.445172 -276.111462)
		(width 0.16002)
		(layer "In2.Cu")
		(net "M_C_CPU1_SB_DQS_DN<9>")
	)
	(segment
		(start 46.41469 -275.122386)
		(end 46.978824 -275.68652)
		(width 0.16002)
		(layer "In2.Cu")
		(net "M_C_CPU1_SB_DQS_DN<9>")
	)
	(segment
		(start 90.64117 -271.326356)
		(end 90.649552 -271.331182)
		(width 0.09525)
		(layer "In2.Cu")
		(net "M_C_CPU1_SB_DQS_DN<9>")
	)
	(segment
		(start 94.351856 -271.304258)
		(end 94.37497 -271.390872)
		(width 0.09525)
		(layer "In2.Cu")
		(net "M_C_CPU1_SB_DQS_DN<9>")
	)
	(segment
		(start 79.909924 -271.345152)
		(end 79.9338 -271.331436)
		(width 0.09525)
		(layer "In2.Cu")
		(net "M_C_CPU1_SB_DQS_DN<9>")
	)
	(segment
		(start 62.182248 -272.972022)
		(end 62.459108 -272.972022)
		(width 0.16002)
		(layer "In2.Cu")
		(net "M_C_CPU1_SB_DQS_DN<9>")
	)
	(segment
		(start 60.857892 -274.837906)
		(end 61.337952 -274.837906)
		(width 0.16002)
		(layer "In2.Cu")
		(net "M_C_CPU1_SB_DQS_DN<9>")
	)
	(segment
		(start 46.01845 -275.122386)
		(end 46.41469 -275.122386)
		(width 0.16002)
		(layer "In2.Cu")
		(net "M_C_CPU1_SB_DQS_DN<9>")
	)
	(segment
		(start 55.790592 -275.686266)
		(end 56.455564 -276.351238)
		(width 0.16002)
		(layer "In2.Cu")
		(net "M_C_CPU1_SB_DQS_DN<9>")
	)
	(segment
		(start 63.941452 -271.707102)
		(end 64.468756 -271.707102)
		(width 0.16002)
		(layer "In2.Cu")
		(net "M_C_CPU1_SB_DQS_DN<9>")
	)
	(segment
		(start 88.392508 -271.331182)
		(end 88.40089 -271.326356)
		(width 0.09525)
		(layer "In2.Cu")
		(net "M_C_CPU1_SB_DQS_DN<9>")
	)
	(segment
		(start 63.42253 -271.46504)
		(end 63.69939 -271.46504)
		(width 0.16002)
		(layer "In2.Cu")
		(net "M_C_CPU1_SB_DQS_DN<9>")
	)
	(segment
		(start 56.932576 -276.351238)
		(end 57.78627 -275.497544)
		(width 0.16002)
		(layer "In2.Cu")
		(net "M_C_CPU1_SB_DQS_DN<9>")
	)
	(segment
		(start 82.752438 -271.331182)
		(end 82.76082 -271.326356)
		(width 0.09525)
		(layer "In2.Cu")
		(net "M_C_CPU1_SB_DQS_DN<9>")
	)
	(segment
		(start 63.225934 -271.938496)
		(end 63.225934 -271.661636)
		(width 0.16002)
		(layer "In2.Cu")
		(net "M_C_CPU1_SB_DQS_DN<9>")
	)
	(segment
		(start 75.979528 -269.835884)
		(end 76.038456 -269.776956)
		(width 0.09525)
		(layer "In2.Cu")
		(net "M_C_CPU1_SB_DQS_DN<9>")
	)
	(segment
		(start 87.452454 -271.331182)
		(end 87.460836 -271.326356)
		(width 0.09525)
		(layer "In2.Cu")
		(net "M_C_CPU1_SB_DQS_DN<9>")
	)
	(segment
		(start 66.339974 -269.835884)
		(end 75.955906 -269.835884)
		(width 0.16002)
		(layer "In2.Cu")
		(net "M_C_CPU1_SB_DQS_DN<9>")
	)
	(segment
		(start 64.796162 -270.091408)
		(end 65.073022 -270.091408)
		(width 0.16002)
		(layer "In2.Cu")
		(net "M_C_CPU1_SB_DQS_DN<9>")
	)
	(segment
		(start 75.955906 -269.835884)
		(end 75.979528 -269.835884)
		(width 0.09525)
		(layer "In2.Cu")
		(net "M_C_CPU1_SB_DQS_DN<9>")
	)
	(segment
		(start 65.315084 -270.33347)
		(end 65.842388 -270.33347)
		(width 0.16002)
		(layer "In2.Cu")
		(net "M_C_CPU1_SB_DQS_DN<9>")
	)
	(segment
		(start 92.15247 -271.331182)
		(end 92.160852 -271.326356)
		(width 0.09525)
		(layer "In2.Cu")
		(net "M_C_CPU1_SB_DQS_DN<9>")
	)
	(segment
		(start 63.225934 -271.661636)
		(end 63.42253 -271.46504)
		(width 0.16002)
		(layer "In2.Cu")
		(net "M_C_CPU1_SB_DQS_DN<9>")
	)
	(segment
		(start 63.095124 -273.080734)
		(end 63.467996 -272.707862)
		(width 0.16002)
		(layer "In2.Cu")
		(net "M_C_CPU1_SB_DQS_DN<9>")
	)
	(segment
		(start 76.038456 -269.776956)
		(end 76.328016 -269.776956)
		(width 0.09525)
		(layer "In2.Cu")
		(net "M_C_CPU1_SB_DQS_DN<9>")
	)
	(segment
		(start 53.737256 -274.391882)
		(end 53.89753 -274.552156)
		(width 0.16002)
		(layer "In2.Cu")
		(net "M_C_CPU1_SB_DQS_DN<9>")
	)
	(segment
		(start 46.978824 -275.68652)
		(end 48.277526 -275.68652)
		(width 0.16002)
		(layer "In2.Cu")
		(net "M_C_CPU1_SB_DQS_DN<9>")
	)
	(segment
		(start 62.094364 -274.081494)
		(end 62.094364 -273.55419)
		(width 0.16002)
		(layer "In2.Cu")
		(net "M_C_CPU1_SB_DQS_DN<9>")
	)
	(segment
		(start 93.092524 -271.331182)
		(end 93.100906 -271.326356)
		(width 0.09525)
		(layer "In2.Cu")
		(net "M_C_CPU1_SB_DQS_DN<9>")
	)
	(segment
		(start 56.455564 -276.351238)
		(end 56.932576 -276.351238)
		(width 0.16002)
		(layer "In2.Cu")
		(net "M_C_CPU1_SB_DQS_DN<9>")
	)
	(segment
		(start 61.337952 -274.837906)
		(end 62.094364 -274.081494)
		(width 0.16002)
		(layer "In2.Cu")
		(net "M_C_CPU1_SB_DQS_DN<9>")
	)
	(segment
		(start 82.181192 -271.326356)
		(end 82.189574 -271.331182)
		(width 0.09525)
		(layer "In2.Cu")
		(net "M_C_CPU1_SB_DQS_DN<9>")
	)
	(segment
		(start 45.78223 -275.358606)
		(end 46.01845 -275.122386)
		(width 0.16002)
		(layer "In2.Cu")
		(net "M_C_CPU1_SB_DQS_DN<9>")
	)
	(segment
		(start 79.9338 -271.331436)
		(end 79.957168 -271.317974)
		(width 0.09525)
		(layer "In2.Cu")
		(net "M_C_CPU1_SB_DQS_DN<9>")
	)
	(segment
		(start 60.260992 -274.954746)
		(end 60.741052 -274.954746)
		(width 0.16002)
		(layer "In2.Cu")
		(net "M_C_CPU1_SB_DQS_DN<9>")
	)
	(segment
		(start 49.568862 -276.277832)
		(end 50.42281 -275.423884)
		(width 0.16002)
		(layer "In2.Cu")
		(net "M_C_CPU1_SB_DQS_DN<9>")
	)
	(segment
		(start 62.094364 -273.55419)
		(end 61.985652 -273.445478)
		(width 0.16002)
		(layer "In2.Cu")
		(net "M_C_CPU1_SB_DQS_DN<9>")
	)
	(segment
		(start 94.37497 -271.390872)
		(end 94.221046 -271.656302)
		(width 0.09525)
		(layer "In2.Cu")
		(net "M_C_CPU1_SB_DQS_DN<9>")
	)
	(segment
		(start 65.842388 -270.33347)
		(end 66.339974 -269.835884)
		(width 0.16002)
		(layer "In2.Cu")
		(net "M_C_CPU1_SB_DQS_DN<9>")
	)
	(segment
		(start 61.985652 -273.445478)
		(end 61.985652 -273.168618)
		(width 0.16002)
		(layer "In2.Cu")
		(net "M_C_CPU1_SB_DQS_DN<9>")
	)
	(segment
		(start 78.431644 -271.331436)
		(end 78.46695 -271.351756)
		(width 0.09525)
		(layer "In2.Cu")
		(net "M_C_CPU1_SB_DQS_DN<9>")
	)
	(segment
		(start 61.985652 -273.168618)
		(end 62.182248 -272.972022)
		(width 0.16002)
		(layer "In2.Cu")
		(net "M_C_CPU1_SB_DQS_DN<9>")
	)
	(segment
		(start 85.941154 -271.326356)
		(end 85.949536 -271.331182)
		(width 0.09525)
		(layer "In2.Cu")
		(net "M_C_CPU1_SB_DQS_DN<9>")
	)
	(segment
		(start 79.349346 -271.31772)
		(end 79.372714 -271.331182)
		(width 0.09525)
		(layer "In2.Cu")
		(net "M_C_CPU1_SB_DQS_DN<9>")
	)
	(segment
		(start 60.144152 -274.837906)
		(end 60.260992 -274.954746)
		(width 0.16002)
		(layer "In2.Cu")
		(net "M_C_CPU1_SB_DQS_DN<9>")
	)
	(segment
		(start 45.445172 -276.111462)
		(end 45.78223 -275.774404)
		(width 0.16002)
		(layer "In2.Cu")
		(net "M_C_CPU1_SB_DQS_DN<9>")
	)
	(segment
		(start 77.45349 -270.380714)
		(end 78.315312 -271.24279)
		(width 0.09525)
		(layer "In2.Cu")
		(net "M_C_CPU1_SB_DQS_DN<9>")
	)
	(segment
		(start 83.692492 -271.331182)
		(end 83.700874 -271.326356)
		(width 0.09525)
		(layer "In2.Cu")
		(net "M_C_CPU1_SB_DQS_DN<9>")
	)
	(segment
		(start 48.868838 -276.277832)
		(end 49.568862 -276.277832)
		(width 0.16002)
		(layer "In2.Cu")
		(net "M_C_CPU1_SB_DQS_DN<9>")
	)
	(segment
		(start 64.468756 -271.707102)
		(end 64.841628 -271.33423)
		(width 0.16002)
		(layer "In2.Cu")
		(net "M_C_CPU1_SB_DQS_DN<9>")
	)
	(segment
		(start 44.340018 -276.385274)
		(end 44.61383 -276.111462)
		(width 0.16002)
		(layer "In2.Cu")
		(net "M_C_CPU1_SB_DQS_DN<9>")
	)
	(segment
		(start 58.26379 -275.497544)
		(end 58.923428 -274.837906)
		(width 0.16002)
		(layer "In2.Cu")
		(net "M_C_CPU1_SB_DQS_DN<9>")
	)
	(segment
		(start 64.841628 -270.806926)
		(end 64.599566 -270.564864)
		(width 0.16002)
		(layer "In2.Cu")
		(net "M_C_CPU1_SB_DQS_DN<9>")
	)
	(segment
		(start 53.89753 -275.349208)
		(end 54.234588 -275.686266)
		(width 0.16002)
		(layer "In2.Cu")
		(net "M_C_CPU1_SB_DQS_DN<9>")
	)
	(segment
		(start 51.380644 -274.830286)
		(end 52.920392 -274.830286)
		(width 0.16002)
		(layer "In2.Cu")
		(net "M_C_CPU1_SB_DQS_DN<9>")
	)
	(segment
		(start 45.78223 -275.774404)
		(end 45.78223 -275.358606)
		(width 0.16002)
		(layer "In2.Cu")
		(net "M_C_CPU1_SB_DQS_DN<9>")
	)
	(segment
		(start 86.881208 -271.326356)
		(end 86.88959 -271.331182)
		(width 0.09525)
		(layer "In2.Cu")
		(net "M_C_CPU1_SB_DQS_DN<9>")
	)
	(segment
		(start 48.277526 -275.68652)
		(end 48.868838 -276.277832)
		(width 0.16002)
		(layer "In2.Cu")
		(net "M_C_CPU1_SB_DQS_DN<9>")
	)
	(segment
		(start 54.234588 -275.686266)
		(end 55.790592 -275.686266)
		(width 0.16002)
		(layer "In2.Cu")
		(net "M_C_CPU1_SB_DQS_DN<9>")
	)
	(arc
		(start 85.009482 -271.331182)
		(mid 85.290914 -271.406937)
		(end 85.572346 -271.331182)
		(width 0.09525)
		(layer "In2.Cu")
		(net "M_C_CPU1_SB_DQS_DN<9>")
	)
	(arc
		(start 79.957168 -271.317974)
		(mid 80.135087 -271.280659)
		(end 80.30972 -271.331182)
		(width 0.09525)
		(layer "In2.Cu")
		(net "M_C_CPU1_SB_DQS_DN<9>")
	)
	(arc
		(start 91.212416 -271.331182)
		(mid 91.396191 -271.28041)
		(end 91.581224 -271.326356)
		(width 0.09525)
		(layer "In2.Cu")
		(net "M_C_CPU1_SB_DQS_DN<9>")
	)
	(arc
		(start 78.351634 -271.275556)
		(mid 78.390416 -271.305248)
		(end 78.431644 -271.331436)
		(width 0.09525)
		(layer "In2.Cu")
		(net "M_C_CPU1_SB_DQS_DN<9>")
	)
	(arc
		(start 93.469714 -271.331182)
		(mid 93.751146 -271.406937)
		(end 94.032578 -271.331182)
		(width 0.09525)
		(layer "In2.Cu")
		(net "M_C_CPU1_SB_DQS_DN<9>")
	)
	(arc
		(start 82.189574 -271.331182)
		(mid 82.471006 -271.406937)
		(end 82.752438 -271.331182)
		(width 0.09525)
		(layer "In2.Cu")
		(net "M_C_CPU1_SB_DQS_DN<9>")
	)
	(arc
		(start 86.88959 -271.331182)
		(mid 87.171022 -271.406937)
		(end 87.452454 -271.331182)
		(width 0.09525)
		(layer "In2.Cu")
		(net "M_C_CPU1_SB_DQS_DN<9>")
	)
	(arc
		(start 92.52966 -271.331182)
		(mid 92.811092 -271.406937)
		(end 93.092524 -271.331182)
		(width 0.09525)
		(layer "In2.Cu")
		(net "M_C_CPU1_SB_DQS_DN<9>")
	)
	(arc
		(start 94.032578 -271.331182)
		(mid 94.189205 -271.281996)
		(end 94.351856 -271.304258)
		(width 0.09525)
		(layer "In2.Cu")
		(net "M_C_CPU1_SB_DQS_DN<9>")
	)
	(arc
		(start 85.949536 -271.331182)
		(mid 86.230968 -271.406937)
		(end 86.5124 -271.331182)
		(width 0.09525)
		(layer "In2.Cu")
		(net "M_C_CPU1_SB_DQS_DN<9>")
	)
	(arc
		(start 84.632546 -271.331182)
		(mid 84.821014 -271.280505)
		(end 85.009482 -271.331182)
		(width 0.09525)
		(layer "In2.Cu")
		(net "M_C_CPU1_SB_DQS_DN<9>")
	)
	(arc
		(start 81.812384 -271.331182)
		(mid 81.996159 -271.28041)
		(end 82.181192 -271.326356)
		(width 0.09525)
		(layer "In2.Cu")
		(net "M_C_CPU1_SB_DQS_DN<9>")
	)
	(arc
		(start 89.709498 -271.331182)
		(mid 89.99093 -271.406937)
		(end 90.272362 -271.331182)
		(width 0.09525)
		(layer "In2.Cu")
		(net "M_C_CPU1_SB_DQS_DN<9>")
	)
	(arc
		(start 78.315312 -271.24279)
		(mid 78.333115 -271.25957)
		(end 78.351634 -271.275556)
		(width 0.09525)
		(layer "In2.Cu")
		(net "M_C_CPU1_SB_DQS_DN<9>")
	)
	(arc
		(start 87.829644 -271.331182)
		(mid 88.111076 -271.406937)
		(end 88.392508 -271.331182)
		(width 0.09525)
		(layer "In2.Cu")
		(net "M_C_CPU1_SB_DQS_DN<9>")
	)
	(arc
		(start 83.700874 -271.326356)
		(mid 83.885906 -271.280442)
		(end 84.069682 -271.331182)
		(width 0.09525)
		(layer "In2.Cu")
		(net "M_C_CPU1_SB_DQS_DN<9>")
	)
	(arc
		(start 86.5124 -271.331182)
		(mid 86.696175 -271.28041)
		(end 86.881208 -271.326356)
		(width 0.09525)
		(layer "In2.Cu")
		(net "M_C_CPU1_SB_DQS_DN<9>")
	)
	(arc
		(start 90.272362 -271.331182)
		(mid 90.456137 -271.28041)
		(end 90.64117 -271.326356)
		(width 0.09525)
		(layer "In2.Cu")
		(net "M_C_CPU1_SB_DQS_DN<9>")
	)
	(arc
		(start 78.46695 -271.351756)
		(mid 78.733202 -271.407171)
		(end 78.994254 -271.330928)
		(width 0.09525)
		(layer "In2.Cu")
		(net "M_C_CPU1_SB_DQS_DN<9>")
	)
	(arc
		(start 85.572346 -271.331182)
		(mid 85.756121 -271.28041)
		(end 85.941154 -271.326356)
		(width 0.09525)
		(layer "In2.Cu")
		(net "M_C_CPU1_SB_DQS_DN<9>")
	)
	(arc
		(start 79.372714 -271.331182)
		(mid 79.63954 -271.406747)
		(end 79.909924 -271.345152)
		(width 0.09525)
		(layer "In2.Cu")
		(net "M_C_CPU1_SB_DQS_DN<9>")
	)
	(arc
		(start 90.649552 -271.331182)
		(mid 90.930984 -271.406937)
		(end 91.212416 -271.331182)
		(width 0.09525)
		(layer "In2.Cu")
		(net "M_C_CPU1_SB_DQS_DN<9>")
	)
	(arc
		(start 78.994254 -271.330928)
		(mid 79.170155 -271.279783)
		(end 79.349346 -271.31772)
		(width 0.09525)
		(layer "In2.Cu")
		(net "M_C_CPU1_SB_DQS_DN<9>")
	)
	(arc
		(start 88.40089 -271.326356)
		(mid 88.585922 -271.280442)
		(end 88.769698 -271.331182)
		(width 0.09525)
		(layer "In2.Cu")
		(net "M_C_CPU1_SB_DQS_DN<9>")
	)
	(arc
		(start 89.332562 -271.331182)
		(mid 89.52103 -271.280505)
		(end 89.709498 -271.331182)
		(width 0.09525)
		(layer "In2.Cu")
		(net "M_C_CPU1_SB_DQS_DN<9>")
	)
	(arc
		(start 87.460836 -271.326356)
		(mid 87.645868 -271.280442)
		(end 87.829644 -271.331182)
		(width 0.09525)
		(layer "In2.Cu")
		(net "M_C_CPU1_SB_DQS_DN<9>")
	)
	(arc
		(start 81.24952 -271.331182)
		(mid 81.530952 -271.406937)
		(end 81.812384 -271.331182)
		(width 0.09525)
		(layer "In2.Cu")
		(net "M_C_CPU1_SB_DQS_DN<9>")
	)
	(arc
		(start 80.30972 -271.331182)
		(mid 80.591152 -271.406937)
		(end 80.872584 -271.331182)
		(width 0.09525)
		(layer "In2.Cu")
		(net "M_C_CPU1_SB_DQS_DN<9>")
	)
	(arc
		(start 80.872584 -271.331182)
		(mid 81.061052 -271.280505)
		(end 81.24952 -271.331182)
		(width 0.09525)
		(layer "In2.Cu")
		(net "M_C_CPU1_SB_DQS_DN<9>")
	)
	(arc
		(start 91.589606 -271.331182)
		(mid 91.871038 -271.406937)
		(end 92.15247 -271.331182)
		(width 0.09525)
		(layer "In2.Cu")
		(net "M_C_CPU1_SB_DQS_DN<9>")
	)
	(arc
		(start 92.160852 -271.326356)
		(mid 92.345884 -271.280442)
		(end 92.52966 -271.331182)
		(width 0.09525)
		(layer "In2.Cu")
		(net "M_C_CPU1_SB_DQS_DN<9>")
	)
	(arc
		(start 93.100906 -271.326356)
		(mid 93.285938 -271.280442)
		(end 93.469714 -271.331182)
		(width 0.09525)
		(layer "In2.Cu")
		(net "M_C_CPU1_SB_DQS_DN<9>")
	)
	(arc
		(start 83.129628 -271.331182)
		(mid 83.41106 -271.406937)
		(end 83.692492 -271.331182)
		(width 0.09525)
		(layer "In2.Cu")
		(net "M_C_CPU1_SB_DQS_DN<9>")
	)
	(arc
		(start 82.76082 -271.326356)
		(mid 82.945852 -271.280442)
		(end 83.129628 -271.331182)
		(width 0.09525)
		(layer "In2.Cu")
		(net "M_C_CPU1_SB_DQS_DN<9>")
	)
	(arc
		(start 88.769698 -271.331182)
		(mid 89.05113 -271.406937)
		(end 89.332562 -271.331182)
		(width 0.09525)
		(layer "In2.Cu")
		(net "M_C_CPU1_SB_DQS_DN<9>")
	)
	(arc
		(start 84.069682 -271.331182)
		(mid 84.351114 -271.406937)
		(end 84.632546 -271.331182)
		(width 0.09525)
		(layer "In2.Cu")
		(net "M_C_CPU1_SB_DQS_DN<9>")
	)
	(segment
		(start 96.568006 -290.830254)
		(end 96.101154 -291.096192)
		(width 0.12954)
		(layer "F.Cu")
		(net "M_C_CPU1_SB_DQS_DN<8>")
	)
	(segment
		(start 78.835758 -292.323774)
		(end 79.025242 -292.132258)
		(width 0.09525)
		(layer "In2.Cu")
		(net "M_C_CPU1_SB_DQS_DN<8>")
	)
	(segment
		(start 95.94723 -291.361622)
		(end 96.101154 -291.096192)
		(width 0.09525)
		(layer "In2.Cu")
		(net "M_C_CPU1_SB_DQS_DN<8>")
	)
	(segment
		(start 50.206148 -313.8805)
		(end 50.819812 -313.8805)
		(width 0.16002)
		(layer "In2.Cu")
		(net "M_C_CPU1_SB_DQS_DN<8>")
	)
	(segment
		(start 77.323696 -294.4749)
		(end 78.149196 -293.6494)
		(width 0.09525)
		(layer "In2.Cu")
		(net "M_C_CPU1_SB_DQS_DN<8>")
	)
	(segment
		(start 46.76521 -315.058298)
		(end 48.53813 -315.058298)
		(width 0.16002)
		(layer "In2.Cu")
		(net "M_C_CPU1_SB_DQS_DN<8>")
	)
	(segment
		(start 50.819812 -313.8805)
		(end 51.160172 -314.22086)
		(width 0.16002)
		(layer "In2.Cu")
		(net "M_C_CPU1_SB_DQS_DN<8>")
	)
	(segment
		(start 95.846392 -291.388292)
		(end 95.94723 -291.361622)
		(width 0.09525)
		(layer "In2.Cu")
		(net "M_C_CPU1_SB_DQS_DN<8>")
	)
	(segment
		(start 78.390496 -293.064438)
		(end 78.392528 -293.063168)
		(width 0.09525)
		(layer "In2.Cu")
		(net "M_C_CPU1_SB_DQS_DN<8>")
	)
	(segment
		(start 86.881208 -291.426138)
		(end 86.88959 -291.421312)
		(width 0.09525)
		(layer "In2.Cu")
		(net "M_C_CPU1_SB_DQS_DN<8>")
	)
	(segment
		(start 56.921908 -314.71108)
		(end 57.72404 -313.908948)
		(width 0.16002)
		(layer "In2.Cu")
		(net "M_C_CPU1_SB_DQS_DN<8>")
	)
	(segment
		(start 90.64117 -291.426138)
		(end 90.649552 -291.421312)
		(width 0.09525)
		(layer "In2.Cu")
		(net "M_C_CPU1_SB_DQS_DN<8>")
	)
	(segment
		(start 43.23207 -313.86018)
		(end 43.839384 -314.467494)
		(width 0.16002)
		(layer "In2.Cu")
		(net "M_C_CPU1_SB_DQS_DN<8>")
	)
	(segment
		(start 93.092524 -291.421312)
		(end 93.100906 -291.426138)
		(width 0.09525)
		(layer "In2.Cu")
		(net "M_C_CPU1_SB_DQS_DN<8>")
	)
	(segment
		(start 40.23995 -313.78525)
		(end 40.514016 -314.059316)
		(width 0.16002)
		(layer "In2.Cu")
		(net "M_C_CPU1_SB_DQS_DN<8>")
	)
	(segment
		(start 41.907206 -314.059316)
		(end 42.106342 -313.86018)
		(width 0.16002)
		(layer "In2.Cu")
		(net "M_C_CPU1_SB_DQS_DN<8>")
	)
	(segment
		(start 54.322472 -315.03112)
		(end 56.101488 -315.03112)
		(width 0.16002)
		(layer "In2.Cu")
		(net "M_C_CPU1_SB_DQS_DN<8>")
	)
	(segment
		(start 78.149196 -293.6494)
		(end 78.149196 -293.52621)
		(width 0.09525)
		(layer "In2.Cu")
		(net "M_C_CPU1_SB_DQS_DN<8>")
	)
	(segment
		(start 65.76187 -310.743346)
		(end 67.05981 -310.743346)
		(width 0.16002)
		(layer "In2.Cu")
		(net "M_C_CPU1_SB_DQS_DN<8>")
	)
	(segment
		(start 85.941154 -291.426138)
		(end 85.949536 -291.421312)
		(width 0.09525)
		(layer "In2.Cu")
		(net "M_C_CPU1_SB_DQS_DN<8>")
	)
	(segment
		(start 49.352708 -314.73394)
		(end 50.206148 -313.8805)
		(width 0.16002)
		(layer "In2.Cu")
		(net "M_C_CPU1_SB_DQS_DN<8>")
	)
	(segment
		(start 67.05981 -310.743346)
		(end 72.391524 -305.411632)
		(width 0.16002)
		(layer "In2.Cu")
		(net "M_C_CPU1_SB_DQS_DN<8>")
	)
	(segment
		(start 58.63717 -314.16752)
		(end 62.337696 -314.16752)
		(width 0.16002)
		(layer "In2.Cu")
		(net "M_C_CPU1_SB_DQS_DN<8>")
	)
	(segment
		(start 79.338678 -291.86505)
		(end 79.731108 -291.47262)
		(width 0.09525)
		(layer "In2.Cu")
		(net "M_C_CPU1_SB_DQS_DN<8>")
	)
	(segment
		(start 77.264514 -295.785794)
		(end 77.323696 -295.726612)
		(width 0.09525)
		(layer "In2.Cu")
		(net "M_C_CPU1_SB_DQS_DN<8>")
	)
	(segment
		(start 56.421528 -314.71108)
		(end 56.921908 -314.71108)
		(width 0.16002)
		(layer "In2.Cu")
		(net "M_C_CPU1_SB_DQS_DN<8>")
	)
	(segment
		(start 95.341186 -291.426138)
		(end 95.349568 -291.421312)
		(width 0.09525)
		(layer "In2.Cu")
		(net "M_C_CPU1_SB_DQS_DN<8>")
	)
	(segment
		(start 79.731108 -291.47262)
		(end 80.120998 -291.47262)
		(width 0.09525)
		(layer "In2.Cu")
		(net "M_C_CPU1_SB_DQS_DN<8>")
	)
	(segment
		(start 77.323696 -295.726612)
		(end 77.323696 -294.4749)
		(width 0.09525)
		(layer "In2.Cu")
		(net "M_C_CPU1_SB_DQS_DN<8>")
	)
	(segment
		(start 58.378598 -313.908948)
		(end 58.63717 -314.16752)
		(width 0.16002)
		(layer "In2.Cu")
		(net "M_C_CPU1_SB_DQS_DN<8>")
	)
	(segment
		(start 83.692492 -291.421312)
		(end 83.700874 -291.426138)
		(width 0.09525)
		(layer "In2.Cu")
		(net "M_C_CPU1_SB_DQS_DN<8>")
	)
	(segment
		(start 46.174406 -314.467494)
		(end 46.76521 -315.058298)
		(width 0.16002)
		(layer "In2.Cu")
		(net "M_C_CPU1_SB_DQS_DN<8>")
	)
	(segment
		(start 48.53813 -315.058298)
		(end 48.862488 -314.73394)
		(width 0.16002)
		(layer "In2.Cu")
		(net "M_C_CPU1_SB_DQS_DN<8>")
	)
	(segment
		(start 91.581224 -291.426138)
		(end 91.589606 -291.421312)
		(width 0.09525)
		(layer "In2.Cu")
		(net "M_C_CPU1_SB_DQS_DN<8>")
	)
	(segment
		(start 82.752438 -291.421312)
		(end 82.76082 -291.426138)
		(width 0.09525)
		(layer "In2.Cu")
		(net "M_C_CPU1_SB_DQS_DN<8>")
	)
	(segment
		(start 82.181192 -291.426138)
		(end 82.189574 -291.421312)
		(width 0.09525)
		(layer "In2.Cu")
		(net "M_C_CPU1_SB_DQS_DN<8>")
	)
	(segment
		(start 72.391524 -305.411632)
		(end 72.391524 -305.21402)
		(width 0.16002)
		(layer "In2.Cu")
		(net "M_C_CPU1_SB_DQS_DN<8>")
	)
	(segment
		(start 53.512212 -314.22086)
		(end 54.322472 -315.03112)
		(width 0.16002)
		(layer "In2.Cu")
		(net "M_C_CPU1_SB_DQS_DN<8>")
	)
	(segment
		(start 92.15247 -291.421312)
		(end 92.160852 -291.426138)
		(width 0.09525)
		(layer "In2.Cu")
		(net "M_C_CPU1_SB_DQS_DN<8>")
	)
	(segment
		(start 77.264514 -295.809416)
		(end 77.264514 -295.785794)
		(width 0.09525)
		(layer "In2.Cu")
		(net "M_C_CPU1_SB_DQS_DN<8>")
	)
	(segment
		(start 40.514016 -314.059316)
		(end 41.907206 -314.059316)
		(width 0.16002)
		(layer "In2.Cu")
		(net "M_C_CPU1_SB_DQS_DN<8>")
	)
	(segment
		(start 48.862488 -314.73394)
		(end 49.352708 -314.73394)
		(width 0.16002)
		(layer "In2.Cu")
		(net "M_C_CPU1_SB_DQS_DN<8>")
	)
	(segment
		(start 72.731122 -304.874422)
		(end 72.928734 -304.874422)
		(width 0.16002)
		(layer "In2.Cu")
		(net "M_C_CPU1_SB_DQS_DN<8>")
	)
	(segment
		(start 42.106342 -313.86018)
		(end 43.23207 -313.86018)
		(width 0.16002)
		(layer "In2.Cu")
		(net "M_C_CPU1_SB_DQS_DN<8>")
	)
	(segment
		(start 56.101488 -315.03112)
		(end 56.421528 -314.71108)
		(width 0.16002)
		(layer "In2.Cu")
		(net "M_C_CPU1_SB_DQS_DN<8>")
	)
	(segment
		(start 72.391524 -305.21402)
		(end 72.731122 -304.874422)
		(width 0.16002)
		(layer "In2.Cu")
		(net "M_C_CPU1_SB_DQS_DN<8>")
	)
	(segment
		(start 62.337696 -314.16752)
		(end 65.76187 -310.743346)
		(width 0.16002)
		(layer "In2.Cu")
		(net "M_C_CPU1_SB_DQS_DN<8>")
	)
	(segment
		(start 88.392508 -291.421312)
		(end 88.40089 -291.426138)
		(width 0.09525)
		(layer "In2.Cu")
		(net "M_C_CPU1_SB_DQS_DN<8>")
	)
	(segment
		(start 72.928734 -304.874422)
		(end 77.264514 -300.538642)
		(width 0.16002)
		(layer "In2.Cu")
		(net "M_C_CPU1_SB_DQS_DN<8>")
	)
	(segment
		(start 57.72404 -313.908948)
		(end 58.378598 -313.908948)
		(width 0.16002)
		(layer "In2.Cu")
		(net "M_C_CPU1_SB_DQS_DN<8>")
	)
	(segment
		(start 77.264514 -300.538642)
		(end 77.264514 -295.809416)
		(width 0.16002)
		(layer "In2.Cu")
		(net "M_C_CPU1_SB_DQS_DN<8>")
	)
	(segment
		(start 78.39456 -293.061898)
		(end 78.441042 -293.034974)
		(width 0.09525)
		(layer "In2.Cu")
		(net "M_C_CPU1_SB_DQS_DN<8>")
	)
	(segment
		(start 87.452454 -291.421312)
		(end 87.460836 -291.426138)
		(width 0.09525)
		(layer "In2.Cu")
		(net "M_C_CPU1_SB_DQS_DN<8>")
	)
	(segment
		(start 43.839384 -314.467494)
		(end 46.174406 -314.467494)
		(width 0.16002)
		(layer "In2.Cu")
		(net "M_C_CPU1_SB_DQS_DN<8>")
	)
	(segment
		(start 51.160172 -314.22086)
		(end 53.512212 -314.22086)
		(width 0.16002)
		(layer "In2.Cu")
		(net "M_C_CPU1_SB_DQS_DN<8>")
	)
	(arc
		(start 84.632546 -291.421312)
		(mid 84.821014 -291.471989)
		(end 85.009482 -291.421312)
		(width 0.09525)
		(layer "In2.Cu")
		(net "M_C_CPU1_SB_DQS_DN<8>")
	)
	(arc
		(start 90.649552 -291.421312)
		(mid 90.656005 -291.417712)
		(end 90.662506 -291.4142)
		(width 0.09525)
		(layer "In2.Cu")
		(net "M_C_CPU1_SB_DQS_DN<8>")
	)
	(arc
		(start 78.515718 -292.975538)
		(mid 78.582615 -292.877581)
		(end 78.615794 -292.763702)
		(width 0.09525)
		(layer "In2.Cu")
		(net "M_C_CPU1_SB_DQS_DN<8>")
	)
	(arc
		(start 94.019878 -291.4142)
		(mid 94.026252 -291.417713)
		(end 94.032578 -291.421312)
		(width 0.09525)
		(layer "In2.Cu")
		(net "M_C_CPU1_SB_DQS_DN<8>")
	)
	(arc
		(start 94.032578 -291.421312)
		(mid 94.221046 -291.471989)
		(end 94.409514 -291.421312)
		(width 0.09525)
		(layer "In2.Cu")
		(net "M_C_CPU1_SB_DQS_DN<8>")
	)
	(arc
		(start 93.07957 -291.4142)
		(mid 93.086069 -291.417715)
		(end 93.092524 -291.421312)
		(width 0.09525)
		(layer "In2.Cu")
		(net "M_C_CPU1_SB_DQS_DN<8>")
	)
	(arc
		(start 79.092552 -292.069266)
		(mid 79.137065 -292.03216)
		(end 79.18323 -291.99713)
		(width 0.09525)
		(layer "In2.Cu")
		(net "M_C_CPU1_SB_DQS_DN<8>")
	)
	(arc
		(start 83.129628 -291.421312)
		(mid 83.403639 -291.34573)
		(end 83.679538 -291.4142)
		(width 0.09525)
		(layer "In2.Cu")
		(net "M_C_CPU1_SB_DQS_DN<8>")
	)
	(arc
		(start 88.769698 -291.421312)
		(mid 89.043852 -291.345604)
		(end 89.319862 -291.4142)
		(width 0.09525)
		(layer "In2.Cu")
		(net "M_C_CPU1_SB_DQS_DN<8>")
	)
	(arc
		(start 80.85963 -291.4142)
		(mid 80.866129 -291.417715)
		(end 80.872584 -291.421312)
		(width 0.09525)
		(layer "In2.Cu")
		(net "M_C_CPU1_SB_DQS_DN<8>")
	)
	(arc
		(start 92.160852 -291.426138)
		(mid 92.345884 -291.472052)
		(end 92.52966 -291.421312)
		(width 0.09525)
		(layer "In2.Cu")
		(net "M_C_CPU1_SB_DQS_DN<8>")
	)
	(arc
		(start 86.88959 -291.421312)
		(mid 87.171022 -291.345557)
		(end 87.452454 -291.421312)
		(width 0.09525)
		(layer "In2.Cu")
		(net "M_C_CPU1_SB_DQS_DN<8>")
	)
	(arc
		(start 88.40089 -291.426138)
		(mid 88.585922 -291.472052)
		(end 88.769698 -291.421312)
		(width 0.09525)
		(layer "In2.Cu")
		(net "M_C_CPU1_SB_DQS_DN<8>")
	)
	(arc
		(start 90.662506 -291.4142)
		(mid 90.938406 -291.345638)
		(end 91.212416 -291.421312)
		(width 0.09525)
		(layer "In2.Cu")
		(net "M_C_CPU1_SB_DQS_DN<8>")
	)
	(arc
		(start 91.212416 -291.421312)
		(mid 91.396191 -291.472084)
		(end 91.581224 -291.426138)
		(width 0.09525)
		(layer "In2.Cu")
		(net "M_C_CPU1_SB_DQS_DN<8>")
	)
	(arc
		(start 84.619846 -291.4142)
		(mid 84.62622 -291.417713)
		(end 84.632546 -291.421312)
		(width 0.09525)
		(layer "In2.Cu")
		(net "M_C_CPU1_SB_DQS_DN<8>")
	)
	(arc
		(start 80.872584 -291.421312)
		(mid 81.061052 -291.471989)
		(end 81.24952 -291.421312)
		(width 0.09525)
		(layer "In2.Cu")
		(net "M_C_CPU1_SB_DQS_DN<8>")
	)
	(arc
		(start 80.120998 -291.47262)
		(mid 80.218744 -291.459425)
		(end 80.30972 -291.421312)
		(width 0.09525)
		(layer "In2.Cu")
		(net "M_C_CPU1_SB_DQS_DN<8>")
	)
	(arc
		(start 85.022182 -291.4142)
		(mid 85.298192 -291.345639)
		(end 85.572346 -291.421312)
		(width 0.09525)
		(layer "In2.Cu")
		(net "M_C_CPU1_SB_DQS_DN<8>")
	)
	(arc
		(start 90.272362 -291.421312)
		(mid 90.456137 -291.472084)
		(end 90.64117 -291.426138)
		(width 0.09525)
		(layer "In2.Cu")
		(net "M_C_CPU1_SB_DQS_DN<8>")
	)
	(arc
		(start 78.392528 -293.063168)
		(mid 78.393543 -293.062532)
		(end 78.39456 -293.061898)
		(width 0.09525)
		(layer "In2.Cu")
		(net "M_C_CPU1_SB_DQS_DN<8>")
	)
	(arc
		(start 85.009482 -291.421312)
		(mid 85.01581 -291.417716)
		(end 85.022182 -291.4142)
		(width 0.09525)
		(layer "In2.Cu")
		(net "M_C_CPU1_SB_DQS_DN<8>")
	)
	(arc
		(start 87.460836 -291.426138)
		(mid 87.645868 -291.472052)
		(end 87.829644 -291.421312)
		(width 0.09525)
		(layer "In2.Cu")
		(net "M_C_CPU1_SB_DQS_DN<8>")
	)
	(arc
		(start 78.149196 -293.52621)
		(mid 78.213095 -293.265663)
		(end 78.390496 -293.064438)
		(width 0.09525)
		(layer "In2.Cu")
		(net "M_C_CPU1_SB_DQS_DN<8>")
	)
	(arc
		(start 94.422214 -291.4142)
		(mid 94.698224 -291.345639)
		(end 94.972378 -291.421312)
		(width 0.09525)
		(layer "In2.Cu")
		(net "M_C_CPU1_SB_DQS_DN<8>")
	)
	(arc
		(start 85.572346 -291.421312)
		(mid 85.756121 -291.472084)
		(end 85.941154 -291.426138)
		(width 0.09525)
		(layer "In2.Cu")
		(net "M_C_CPU1_SB_DQS_DN<8>")
	)
	(arc
		(start 95.349568 -291.421312)
		(mid 95.583082 -291.347469)
		(end 95.825818 -291.380164)
		(width 0.09525)
		(layer "In2.Cu")
		(net "M_C_CPU1_SB_DQS_DN<8>")
	)
	(arc
		(start 81.262474 -291.4142)
		(mid 81.538374 -291.345638)
		(end 81.812384 -291.421312)
		(width 0.09525)
		(layer "In2.Cu")
		(net "M_C_CPU1_SB_DQS_DN<8>")
	)
	(arc
		(start 80.30972 -291.421312)
		(mid 80.583731 -291.34573)
		(end 80.85963 -291.4142)
		(width 0.09525)
		(layer "In2.Cu")
		(net "M_C_CPU1_SB_DQS_DN<8>")
	)
	(arc
		(start 85.949536 -291.421312)
		(mid 85.955989 -291.417712)
		(end 85.96249 -291.4142)
		(width 0.09525)
		(layer "In2.Cu")
		(net "M_C_CPU1_SB_DQS_DN<8>")
	)
	(arc
		(start 89.722198 -291.4142)
		(mid 89.998208 -291.345639)
		(end 90.272362 -291.421312)
		(width 0.09525)
		(layer "In2.Cu")
		(net "M_C_CPU1_SB_DQS_DN<8>")
	)
	(arc
		(start 84.069682 -291.421312)
		(mid 84.343836 -291.345604)
		(end 84.619846 -291.4142)
		(width 0.09525)
		(layer "In2.Cu")
		(net "M_C_CPU1_SB_DQS_DN<8>")
	)
	(arc
		(start 83.700874 -291.426138)
		(mid 83.885906 -291.472052)
		(end 84.069682 -291.421312)
		(width 0.09525)
		(layer "In2.Cu")
		(net "M_C_CPU1_SB_DQS_DN<8>")
	)
	(arc
		(start 86.5124 -291.421312)
		(mid 86.696175 -291.472084)
		(end 86.881208 -291.426138)
		(width 0.09525)
		(layer "In2.Cu")
		(net "M_C_CPU1_SB_DQS_DN<8>")
	)
	(arc
		(start 93.100906 -291.426138)
		(mid 93.285938 -291.472052)
		(end 93.469714 -291.421312)
		(width 0.09525)
		(layer "In2.Cu")
		(net "M_C_CPU1_SB_DQS_DN<8>")
	)
	(arc
		(start 88.379554 -291.4142)
		(mid 88.386053 -291.417715)
		(end 88.392508 -291.421312)
		(width 0.09525)
		(layer "In2.Cu")
		(net "M_C_CPU1_SB_DQS_DN<8>")
	)
	(arc
		(start 87.829644 -291.421312)
		(mid 88.103655 -291.34573)
		(end 88.379554 -291.4142)
		(width 0.09525)
		(layer "In2.Cu")
		(net "M_C_CPU1_SB_DQS_DN<8>")
	)
	(arc
		(start 82.76082 -291.426138)
		(mid 82.945852 -291.472052)
		(end 83.129628 -291.421312)
		(width 0.09525)
		(layer "In2.Cu")
		(net "M_C_CPU1_SB_DQS_DN<8>")
	)
	(arc
		(start 78.441042 -293.034974)
		(mid 78.480505 -293.007928)
		(end 78.515718 -292.975538)
		(width 0.09525)
		(layer "In2.Cu")
		(net "M_C_CPU1_SB_DQS_DN<8>")
	)
	(arc
		(start 94.409514 -291.421312)
		(mid 94.415842 -291.417716)
		(end 94.422214 -291.4142)
		(width 0.09525)
		(layer "In2.Cu")
		(net "M_C_CPU1_SB_DQS_DN<8>")
	)
	(arc
		(start 79.18323 -291.99713)
		(mid 79.263616 -291.934223)
		(end 79.338678 -291.86505)
		(width 0.09525)
		(layer "In2.Cu")
		(net "M_C_CPU1_SB_DQS_DN<8>")
	)
	(arc
		(start 89.709498 -291.421312)
		(mid 89.715826 -291.417716)
		(end 89.722198 -291.4142)
		(width 0.09525)
		(layer "In2.Cu")
		(net "M_C_CPU1_SB_DQS_DN<8>")
	)
	(arc
		(start 82.189574 -291.421312)
		(mid 82.471006 -291.345557)
		(end 82.752438 -291.421312)
		(width 0.09525)
		(layer "In2.Cu")
		(net "M_C_CPU1_SB_DQS_DN<8>")
	)
	(arc
		(start 85.96249 -291.4142)
		(mid 86.23839 -291.345638)
		(end 86.5124 -291.421312)
		(width 0.09525)
		(layer "In2.Cu")
		(net "M_C_CPU1_SB_DQS_DN<8>")
	)
	(arc
		(start 79.025242 -292.132258)
		(mid 79.058324 -292.100149)
		(end 79.092552 -292.069266)
		(width 0.09525)
		(layer "In2.Cu")
		(net "M_C_CPU1_SB_DQS_DN<8>")
	)
	(arc
		(start 78.6511 -292.62705)
		(mid 78.679076 -292.560723)
		(end 78.710028 -292.495732)
		(width 0.09525)
		(layer "In2.Cu")
		(net "M_C_CPU1_SB_DQS_DN<8>")
	)
	(arc
		(start 91.589606 -291.421312)
		(mid 91.871038 -291.345557)
		(end 92.15247 -291.421312)
		(width 0.09525)
		(layer "In2.Cu")
		(net "M_C_CPU1_SB_DQS_DN<8>")
	)
	(arc
		(start 83.679538 -291.4142)
		(mid 83.686037 -291.417715)
		(end 83.692492 -291.421312)
		(width 0.09525)
		(layer "In2.Cu")
		(net "M_C_CPU1_SB_DQS_DN<8>")
	)
	(arc
		(start 89.332562 -291.421312)
		(mid 89.52103 -291.471989)
		(end 89.709498 -291.421312)
		(width 0.09525)
		(layer "In2.Cu")
		(net "M_C_CPU1_SB_DQS_DN<8>")
	)
	(arc
		(start 92.52966 -291.421312)
		(mid 92.803671 -291.34573)
		(end 93.07957 -291.4142)
		(width 0.09525)
		(layer "In2.Cu")
		(net "M_C_CPU1_SB_DQS_DN<8>")
	)
	(arc
		(start 95.825818 -291.380164)
		(mid 95.836146 -291.384124)
		(end 95.846392 -291.388292)
		(width 0.09525)
		(layer "In2.Cu")
		(net "M_C_CPU1_SB_DQS_DN<8>")
	)
	(arc
		(start 78.615794 -292.763702)
		(mid 78.629123 -292.694258)
		(end 78.6511 -292.62705)
		(width 0.09525)
		(layer "In2.Cu")
		(net "M_C_CPU1_SB_DQS_DN<8>")
	)
	(arc
		(start 93.469714 -291.421312)
		(mid 93.743868 -291.345604)
		(end 94.019878 -291.4142)
		(width 0.09525)
		(layer "In2.Cu")
		(net "M_C_CPU1_SB_DQS_DN<8>")
	)
	(arc
		(start 78.710028 -292.495732)
		(mid 78.766467 -292.405054)
		(end 78.835758 -292.323774)
		(width 0.09525)
		(layer "In2.Cu")
		(net "M_C_CPU1_SB_DQS_DN<8>")
	)
	(arc
		(start 94.972378 -291.421312)
		(mid 95.156153 -291.472084)
		(end 95.341186 -291.426138)
		(width 0.09525)
		(layer "In2.Cu")
		(net "M_C_CPU1_SB_DQS_DN<8>")
	)
	(arc
		(start 81.24952 -291.421312)
		(mid 81.255973 -291.417712)
		(end 81.262474 -291.4142)
		(width 0.09525)
		(layer "In2.Cu")
		(net "M_C_CPU1_SB_DQS_DN<8>")
	)
	(arc
		(start 89.319862 -291.4142)
		(mid 89.326236 -291.417713)
		(end 89.332562 -291.421312)
		(width 0.09525)
		(layer "In2.Cu")
		(net "M_C_CPU1_SB_DQS_DN<8>")
	)
	(arc
		(start 81.812384 -291.421312)
		(mid 81.996159 -291.472084)
		(end 82.181192 -291.426138)
		(width 0.09525)
		(layer "In2.Cu")
		(net "M_C_CPU1_SB_DQS_DN<8>")
	)
	(segment
		(start 96.568006 -285.970472)
		(end 96.101154 -286.23641)
		(width 0.12954)
		(layer "F.Cu")
		(net "M_C_CPU1_SB_DQS_DN<7>")
	)
	(segment
		(start 95.846392 -286.52851)
		(end 95.94723 -286.50184)
		(width 0.09525)
		(layer "In2.Cu")
		(net "M_C_CPU1_SB_DQS_DN<7>")
	)
	(segment
		(start 58.63717 -304.817526)
		(end 62.141354 -304.817526)
		(width 0.16002)
		(layer "In2.Cu")
		(net "M_C_CPU1_SB_DQS_DN<7>")
	)
	(segment
		(start 95.341186 -286.566356)
		(end 95.349568 -286.56153)
		(width 0.09525)
		(layer "In2.Cu")
		(net "M_C_CPU1_SB_DQS_DN<7>")
	)
	(segment
		(start 54.322472 -305.681126)
		(end 56.101488 -305.681126)
		(width 0.16002)
		(layer "In2.Cu")
		(net "M_C_CPU1_SB_DQS_DN<7>")
	)
	(segment
		(start 48.816514 -305.42992)
		(end 49.140364 -305.295554)
		(width 0.16002)
		(layer "In2.Cu")
		(net "M_C_CPU1_SB_DQS_DN<7>")
	)
	(segment
		(start 43.27525 -304.553366)
		(end 43.554904 -304.83302)
		(width 0.16002)
		(layer "In2.Cu")
		(net "M_C_CPU1_SB_DQS_DN<7>")
	)
	(segment
		(start 83.692492 -286.56153)
		(end 83.700874 -286.566356)
		(width 0.09525)
		(layer "In2.Cu")
		(net "M_C_CPU1_SB_DQS_DN<7>")
	)
	(segment
		(start 82.181192 -286.566356)
		(end 82.189574 -286.56153)
		(width 0.09525)
		(layer "In2.Cu")
		(net "M_C_CPU1_SB_DQS_DN<7>")
	)
	(segment
		(start 77.038962 -287.011364)
		(end 77.527912 -287.011364)
		(width 0.09525)
		(layer "In2.Cu")
		(net "M_C_CPU1_SB_DQS_DN<7>")
	)
	(segment
		(start 85.941154 -286.566356)
		(end 85.949536 -286.56153)
		(width 0.09525)
		(layer "In2.Cu")
		(net "M_C_CPU1_SB_DQS_DN<7>")
	)
	(segment
		(start 88.392508 -286.56153)
		(end 88.40089 -286.566356)
		(width 0.09525)
		(layer "In2.Cu")
		(net "M_C_CPU1_SB_DQS_DN<7>")
	)
	(segment
		(start 56.673242 -305.283616)
		(end 57.757314 -304.558954)
		(width 0.16002)
		(layer "In2.Cu")
		(net "M_C_CPU1_SB_DQS_DN<7>")
	)
	(segment
		(start 56.375554 -305.40706)
		(end 56.673242 -305.283616)
		(width 0.16002)
		(layer "In2.Cu")
		(net "M_C_CPU1_SB_DQS_DN<7>")
	)
	(segment
		(start 77.527912 -287.011364)
		(end 77.926184 -286.613092)
		(width 0.09525)
		(layer "In2.Cu")
		(net "M_C_CPU1_SB_DQS_DN<7>")
	)
	(segment
		(start 41.907206 -304.709322)
		(end 42.063162 -304.553366)
		(width 0.16002)
		(layer "In2.Cu")
		(net "M_C_CPU1_SB_DQS_DN<7>")
	)
	(segment
		(start 45.338746 -305.1175)
		(end 46.76521 -305.708304)
		(width 0.16002)
		(layer "In2.Cu")
		(net "M_C_CPU1_SB_DQS_DN<7>")
	)
	(segment
		(start 42.063162 -304.553366)
		(end 43.27525 -304.553366)
		(width 0.16002)
		(layer "In2.Cu")
		(net "M_C_CPU1_SB_DQS_DN<7>")
	)
	(segment
		(start 53.841396 -305.20005)
		(end 54.322472 -305.681126)
		(width 0.16002)
		(layer "In2.Cu")
		(net "M_C_CPU1_SB_DQS_DN<7>")
	)
	(segment
		(start 48.53813 -305.708304)
		(end 48.816514 -305.42992)
		(width 0.16002)
		(layer "In2.Cu")
		(net "M_C_CPU1_SB_DQS_DN<7>")
	)
	(segment
		(start 82.752438 -286.56153)
		(end 82.76082 -286.566356)
		(width 0.09525)
		(layer "In2.Cu")
		(net "M_C_CPU1_SB_DQS_DN<7>")
	)
	(segment
		(start 80.301338 -286.566356)
		(end 80.30972 -286.56153)
		(width 0.09525)
		(layer "In2.Cu")
		(net "M_C_CPU1_SB_DQS_DN<7>")
	)
	(segment
		(start 77.926184 -286.613092)
		(end 78.239874 -286.613092)
		(width 0.09525)
		(layer "In2.Cu")
		(net "M_C_CPU1_SB_DQS_DN<7>")
	)
	(segment
		(start 43.554904 -304.83302)
		(end 44.24172 -305.1175)
		(width 0.16002)
		(layer "In2.Cu")
		(net "M_C_CPU1_SB_DQS_DN<7>")
	)
	(segment
		(start 78.991968 -286.561276)
		(end 79.005938 -286.56915)
		(width 0.09525)
		(layer "In2.Cu")
		(net "M_C_CPU1_SB_DQS_DN<7>")
	)
	(segment
		(start 49.140364 -305.295554)
		(end 50.045874 -304.690526)
		(width 0.16002)
		(layer "In2.Cu")
		(net "M_C_CPU1_SB_DQS_DN<7>")
	)
	(segment
		(start 50.045874 -304.690526)
		(end 50.206148 -304.530506)
		(width 0.16002)
		(layer "In2.Cu")
		(net "M_C_CPU1_SB_DQS_DN<7>")
	)
	(segment
		(start 75.978512 -287.72612)
		(end 76.062332 -287.72612)
		(width 0.09525)
		(layer "In2.Cu")
		(net "M_C_CPU1_SB_DQS_DN<7>")
	)
	(segment
		(start 71.467726 -292.237668)
		(end 75.961748 -287.742884)
		(width 0.16002)
		(layer "In2.Cu")
		(net "M_C_CPU1_SB_DQS_DN<7>")
	)
	(segment
		(start 51.147472 -304.858166)
		(end 53.015896 -304.858166)
		(width 0.16002)
		(layer "In2.Cu")
		(net "M_C_CPU1_SB_DQS_DN<7>")
	)
	(segment
		(start 78.97622 -286.552132)
		(end 78.991968 -286.561276)
		(width 0.09525)
		(layer "In2.Cu")
		(net "M_C_CPU1_SB_DQS_DN<7>")
	)
	(segment
		(start 93.092524 -286.56153)
		(end 93.100906 -286.566356)
		(width 0.09525)
		(layer "In2.Cu")
		(net "M_C_CPU1_SB_DQS_DN<7>")
	)
	(segment
		(start 46.76521 -305.708304)
		(end 48.53813 -305.708304)
		(width 0.16002)
		(layer "In2.Cu")
		(net "M_C_CPU1_SB_DQS_DN<7>")
	)
	(segment
		(start 92.15247 -286.56153)
		(end 92.160852 -286.566356)
		(width 0.09525)
		(layer "In2.Cu")
		(net "M_C_CPU1_SB_DQS_DN<7>")
	)
	(segment
		(start 75.961748 -287.742884)
		(end 75.978512 -287.72612)
		(width 0.09525)
		(layer "In2.Cu")
		(net "M_C_CPU1_SB_DQS_DN<7>")
	)
	(segment
		(start 71.467726 -295.491154)
		(end 71.467726 -292.237668)
		(width 0.16002)
		(layer "In2.Cu")
		(net "M_C_CPU1_SB_DQS_DN<7>")
	)
	(segment
		(start 40.514016 -304.709322)
		(end 41.907206 -304.709322)
		(width 0.16002)
		(layer "In2.Cu")
		(net "M_C_CPU1_SB_DQS_DN<7>")
	)
	(segment
		(start 40.23995 -304.435256)
		(end 40.514016 -304.709322)
		(width 0.16002)
		(layer "In2.Cu")
		(net "M_C_CPU1_SB_DQS_DN<7>")
	)
	(segment
		(start 53.015896 -304.858166)
		(end 53.841396 -305.20005)
		(width 0.16002)
		(layer "In2.Cu")
		(net "M_C_CPU1_SB_DQS_DN<7>")
	)
	(segment
		(start 50.206148 -304.530506)
		(end 50.819812 -304.530506)
		(width 0.16002)
		(layer "In2.Cu")
		(net "M_C_CPU1_SB_DQS_DN<7>")
	)
	(segment
		(start 86.881208 -286.566356)
		(end 86.88959 -286.56153)
		(width 0.09525)
		(layer "In2.Cu")
		(net "M_C_CPU1_SB_DQS_DN<7>")
	)
	(segment
		(start 76.062332 -287.72612)
		(end 76.591922 -287.19653)
		(width 0.09525)
		(layer "In2.Cu")
		(net "M_C_CPU1_SB_DQS_DN<7>")
	)
	(segment
		(start 58.378598 -304.558954)
		(end 58.63717 -304.817526)
		(width 0.16002)
		(layer "In2.Cu")
		(net "M_C_CPU1_SB_DQS_DN<7>")
	)
	(segment
		(start 56.101488 -305.681126)
		(end 56.375554 -305.40706)
		(width 0.16002)
		(layer "In2.Cu")
		(net "M_C_CPU1_SB_DQS_DN<7>")
	)
	(segment
		(start 62.141354 -304.817526)
		(end 71.467726 -295.491154)
		(width 0.16002)
		(layer "In2.Cu")
		(net "M_C_CPU1_SB_DQS_DN<7>")
	)
	(segment
		(start 79.36865 -286.56153)
		(end 79.383382 -286.552894)
		(width 0.09525)
		(layer "In2.Cu")
		(net "M_C_CPU1_SB_DQS_DN<7>")
	)
	(segment
		(start 44.24172 -305.1175)
		(end 45.338746 -305.1175)
		(width 0.16002)
		(layer "In2.Cu")
		(net "M_C_CPU1_SB_DQS_DN<7>")
	)
	(segment
		(start 87.452454 -286.56153)
		(end 87.460836 -286.566356)
		(width 0.09525)
		(layer "In2.Cu")
		(net "M_C_CPU1_SB_DQS_DN<7>")
	)
	(segment
		(start 50.819812 -304.530506)
		(end 51.147472 -304.858166)
		(width 0.16002)
		(layer "In2.Cu")
		(net "M_C_CPU1_SB_DQS_DN<7>")
	)
	(segment
		(start 57.757314 -304.558954)
		(end 58.378598 -304.558954)
		(width 0.16002)
		(layer "In2.Cu")
		(net "M_C_CPU1_SB_DQS_DN<7>")
	)
	(segment
		(start 91.581224 -286.566356)
		(end 91.589606 -286.56153)
		(width 0.09525)
		(layer "In2.Cu")
		(net "M_C_CPU1_SB_DQS_DN<7>")
	)
	(segment
		(start 90.64117 -286.566356)
		(end 90.649552 -286.56153)
		(width 0.09525)
		(layer "In2.Cu")
		(net "M_C_CPU1_SB_DQS_DN<7>")
	)
	(segment
		(start 95.94723 -286.50184)
		(end 96.101154 -286.23641)
		(width 0.09525)
		(layer "In2.Cu")
		(net "M_C_CPU1_SB_DQS_DN<7>")
	)
	(arc
		(start 84.069682 -286.56153)
		(mid 84.351114 -286.485741)
		(end 84.632546 -286.56153)
		(width 0.09525)
		(layer "In2.Cu")
		(net "M_C_CPU1_SB_DQS_DN<7>")
	)
	(arc
		(start 85.572346 -286.56153)
		(mid 85.756121 -286.612302)
		(end 85.941154 -286.566356)
		(width 0.09525)
		(layer "In2.Cu")
		(net "M_C_CPU1_SB_DQS_DN<7>")
	)
	(arc
		(start 88.40089 -286.566356)
		(mid 88.585922 -286.61227)
		(end 88.769698 -286.56153)
		(width 0.09525)
		(layer "In2.Cu")
		(net "M_C_CPU1_SB_DQS_DN<7>")
	)
	(arc
		(start 92.52966 -286.56153)
		(mid 92.811092 -286.485741)
		(end 93.092524 -286.56153)
		(width 0.09525)
		(layer "In2.Cu")
		(net "M_C_CPU1_SB_DQS_DN<7>")
	)
	(arc
		(start 94.409514 -286.56153)
		(mid 94.690946 -286.485741)
		(end 94.972378 -286.56153)
		(width 0.09525)
		(layer "In2.Cu")
		(net "M_C_CPU1_SB_DQS_DN<7>")
	)
	(arc
		(start 87.460836 -286.566356)
		(mid 87.645868 -286.61227)
		(end 87.829644 -286.56153)
		(width 0.09525)
		(layer "In2.Cu")
		(net "M_C_CPU1_SB_DQS_DN<7>")
	)
	(arc
		(start 79.932022 -286.56153)
		(mid 80.116051 -286.612429)
		(end 80.301338 -286.566356)
		(width 0.09525)
		(layer "In2.Cu")
		(net "M_C_CPU1_SB_DQS_DN<7>")
	)
	(arc
		(start 91.212416 -286.56153)
		(mid 91.396191 -286.612302)
		(end 91.581224 -286.566356)
		(width 0.09525)
		(layer "In2.Cu")
		(net "M_C_CPU1_SB_DQS_DN<7>")
	)
	(arc
		(start 90.272362 -286.56153)
		(mid 90.456137 -286.612302)
		(end 90.64117 -286.566356)
		(width 0.09525)
		(layer "In2.Cu")
		(net "M_C_CPU1_SB_DQS_DN<7>")
	)
	(arc
		(start 78.429104 -286.56153)
		(mid 78.701435 -286.485568)
		(end 78.97622 -286.552132)
		(width 0.09525)
		(layer "In2.Cu")
		(net "M_C_CPU1_SB_DQS_DN<7>")
	)
	(arc
		(start 79.383382 -286.552894)
		(mid 79.658841 -286.485479)
		(end 79.932022 -286.56153)
		(width 0.09525)
		(layer "In2.Cu")
		(net "M_C_CPU1_SB_DQS_DN<7>")
	)
	(arc
		(start 95.349568 -286.56153)
		(mid 95.59411 -286.486811)
		(end 95.846392 -286.52851)
		(width 0.09525)
		(layer "In2.Cu")
		(net "M_C_CPU1_SB_DQS_DN<7>")
	)
	(arc
		(start 83.700874 -286.566356)
		(mid 83.885906 -286.61227)
		(end 84.069682 -286.56153)
		(width 0.09525)
		(layer "In2.Cu")
		(net "M_C_CPU1_SB_DQS_DN<7>")
	)
	(arc
		(start 76.591922 -287.19653)
		(mid 76.797026 -287.059484)
		(end 77.038962 -287.011364)
		(width 0.09525)
		(layer "In2.Cu")
		(net "M_C_CPU1_SB_DQS_DN<7>")
	)
	(arc
		(start 82.76082 -286.566356)
		(mid 82.945852 -286.61227)
		(end 83.129628 -286.56153)
		(width 0.09525)
		(layer "In2.Cu")
		(net "M_C_CPU1_SB_DQS_DN<7>")
	)
	(arc
		(start 81.812384 -286.56153)
		(mid 81.996159 -286.612302)
		(end 82.181192 -286.566356)
		(width 0.09525)
		(layer "In2.Cu")
		(net "M_C_CPU1_SB_DQS_DN<7>")
	)
	(arc
		(start 86.5124 -286.56153)
		(mid 86.696175 -286.612302)
		(end 86.881208 -286.566356)
		(width 0.09525)
		(layer "In2.Cu")
		(net "M_C_CPU1_SB_DQS_DN<7>")
	)
	(arc
		(start 83.129628 -286.56153)
		(mid 83.41106 -286.485741)
		(end 83.692492 -286.56153)
		(width 0.09525)
		(layer "In2.Cu")
		(net "M_C_CPU1_SB_DQS_DN<7>")
	)
	(arc
		(start 88.769698 -286.56153)
		(mid 89.05113 -286.485741)
		(end 89.332562 -286.56153)
		(width 0.09525)
		(layer "In2.Cu")
		(net "M_C_CPU1_SB_DQS_DN<7>")
	)
	(arc
		(start 91.589606 -286.56153)
		(mid 91.871038 -286.485741)
		(end 92.15247 -286.56153)
		(width 0.09525)
		(layer "In2.Cu")
		(net "M_C_CPU1_SB_DQS_DN<7>")
	)
	(arc
		(start 80.30972 -286.56153)
		(mid 80.591152 -286.485741)
		(end 80.872584 -286.56153)
		(width 0.09525)
		(layer "In2.Cu")
		(net "M_C_CPU1_SB_DQS_DN<7>")
	)
	(arc
		(start 93.100906 -286.566356)
		(mid 93.285938 -286.61227)
		(end 93.469714 -286.56153)
		(width 0.09525)
		(layer "In2.Cu")
		(net "M_C_CPU1_SB_DQS_DN<7>")
	)
	(arc
		(start 87.829644 -286.56153)
		(mid 88.111076 -286.485741)
		(end 88.392508 -286.56153)
		(width 0.09525)
		(layer "In2.Cu")
		(net "M_C_CPU1_SB_DQS_DN<7>")
	)
	(arc
		(start 94.972378 -286.56153)
		(mid 95.156153 -286.612302)
		(end 95.341186 -286.566356)
		(width 0.09525)
		(layer "In2.Cu")
		(net "M_C_CPU1_SB_DQS_DN<7>")
	)
	(arc
		(start 79.005938 -286.56915)
		(mid 79.188282 -286.612048)
		(end 79.36865 -286.56153)
		(width 0.09525)
		(layer "In2.Cu")
		(net "M_C_CPU1_SB_DQS_DN<7>")
	)
	(arc
		(start 85.009482 -286.56153)
		(mid 85.290914 -286.485741)
		(end 85.572346 -286.56153)
		(width 0.09525)
		(layer "In2.Cu")
		(net "M_C_CPU1_SB_DQS_DN<7>")
	)
	(arc
		(start 94.032578 -286.56153)
		(mid 94.221046 -286.612207)
		(end 94.409514 -286.56153)
		(width 0.09525)
		(layer "In2.Cu")
		(net "M_C_CPU1_SB_DQS_DN<7>")
	)
	(arc
		(start 86.88959 -286.56153)
		(mid 87.171022 -286.485741)
		(end 87.452454 -286.56153)
		(width 0.09525)
		(layer "In2.Cu")
		(net "M_C_CPU1_SB_DQS_DN<7>")
	)
	(arc
		(start 93.469714 -286.56153)
		(mid 93.751146 -286.485741)
		(end 94.032578 -286.56153)
		(width 0.09525)
		(layer "In2.Cu")
		(net "M_C_CPU1_SB_DQS_DN<7>")
	)
	(arc
		(start 92.160852 -286.566356)
		(mid 92.345884 -286.61227)
		(end 92.52966 -286.56153)
		(width 0.09525)
		(layer "In2.Cu")
		(net "M_C_CPU1_SB_DQS_DN<7>")
	)
	(arc
		(start 90.649552 -286.56153)
		(mid 90.930984 -286.485741)
		(end 91.212416 -286.56153)
		(width 0.09525)
		(layer "In2.Cu")
		(net "M_C_CPU1_SB_DQS_DN<7>")
	)
	(arc
		(start 89.709498 -286.56153)
		(mid 89.99093 -286.485741)
		(end 90.272362 -286.56153)
		(width 0.09525)
		(layer "In2.Cu")
		(net "M_C_CPU1_SB_DQS_DN<7>")
	)
	(arc
		(start 80.872584 -286.56153)
		(mid 81.061052 -286.612207)
		(end 81.24952 -286.56153)
		(width 0.09525)
		(layer "In2.Cu")
		(net "M_C_CPU1_SB_DQS_DN<7>")
	)
	(arc
		(start 78.239874 -286.613092)
		(mid 78.337898 -286.599831)
		(end 78.429104 -286.56153)
		(width 0.09525)
		(layer "In2.Cu")
		(net "M_C_CPU1_SB_DQS_DN<7>")
	)
	(arc
		(start 84.632546 -286.56153)
		(mid 84.821014 -286.612207)
		(end 85.009482 -286.56153)
		(width 0.09525)
		(layer "In2.Cu")
		(net "M_C_CPU1_SB_DQS_DN<7>")
	)
	(arc
		(start 81.24952 -286.56153)
		(mid 81.530952 -286.485741)
		(end 81.812384 -286.56153)
		(width 0.09525)
		(layer "In2.Cu")
		(net "M_C_CPU1_SB_DQS_DN<7>")
	)
	(arc
		(start 85.949536 -286.56153)
		(mid 86.230968 -286.485741)
		(end 86.5124 -286.56153)
		(width 0.09525)
		(layer "In2.Cu")
		(net "M_C_CPU1_SB_DQS_DN<7>")
	)
	(arc
		(start 82.189574 -286.56153)
		(mid 82.471006 -286.485741)
		(end 82.752438 -286.56153)
		(width 0.09525)
		(layer "In2.Cu")
		(net "M_C_CPU1_SB_DQS_DN<7>")
	)
	(arc
		(start 89.332562 -286.56153)
		(mid 89.52103 -286.612207)
		(end 89.709498 -286.56153)
		(width 0.09525)
		(layer "In2.Cu")
		(net "M_C_CPU1_SB_DQS_DN<7>")
	)
	(segment
		(start 96.568006 -281.110436)
		(end 96.101154 -281.376374)
		(width 0.12954)
		(layer "F.Cu")
		(net "M_C_CPU1_SB_DQS_DN<6>")
	)
	(segment
		(start 88.392508 -281.701494)
		(end 88.40089 -281.70632)
		(width 0.09525)
		(layer "In2.Cu")
		(net "M_C_CPU1_SB_DQS_DN<6>")
	)
	(segment
		(start 56.375554 -296.057066)
		(end 56.673242 -295.933622)
		(width 0.16002)
		(layer "In2.Cu")
		(net "M_C_CPU1_SB_DQS_DN<6>")
	)
	(segment
		(start 66.03111 -289.669982)
		(end 74.028808 -281.672284)
		(width 0.16002)
		(layer "In2.Cu")
		(net "M_C_CPU1_SB_DQS_DN<6>")
	)
	(segment
		(start 56.101488 -296.331132)
		(end 56.375554 -296.057066)
		(width 0.16002)
		(layer "In2.Cu")
		(net "M_C_CPU1_SB_DQS_DN<6>")
	)
	(segment
		(start 48.816514 -296.079926)
		(end 49.019206 -295.995852)
		(width 0.16002)
		(layer "In2.Cu")
		(net "M_C_CPU1_SB_DQS_DN<6>")
	)
	(segment
		(start 49.019206 -295.995852)
		(end 50.239676 -295.180512)
		(width 0.16002)
		(layer "In2.Cu")
		(net "M_C_CPU1_SB_DQS_DN<6>")
	)
	(segment
		(start 95.94723 -281.641804)
		(end 96.101154 -281.376374)
		(width 0.09525)
		(layer "In2.Cu")
		(net "M_C_CPU1_SB_DQS_DN<6>")
	)
	(segment
		(start 91.581224 -281.70632)
		(end 91.589606 -281.701494)
		(width 0.09525)
		(layer "In2.Cu")
		(net "M_C_CPU1_SB_DQS_DN<6>")
	)
	(segment
		(start 77.905356 -281.731466)
		(end 78.011274 -281.625548)
		(width 0.09525)
		(layer "In2.Cu")
		(net "M_C_CPU1_SB_DQS_DN<6>")
	)
	(segment
		(start 43.577764 -295.505886)
		(end 44.209462 -295.767506)
		(width 0.16002)
		(layer "In2.Cu")
		(net "M_C_CPU1_SB_DQS_DN<6>")
	)
	(segment
		(start 42.264838 -295.359328)
		(end 42.634662 -295.206166)
		(width 0.16002)
		(layer "In2.Cu")
		(net "M_C_CPU1_SB_DQS_DN<6>")
	)
	(segment
		(start 80.301338 -281.70632)
		(end 80.30972 -281.701494)
		(width 0.09525)
		(layer "In2.Cu")
		(net "M_C_CPU1_SB_DQS_DN<6>")
	)
	(segment
		(start 45.338746 -295.767506)
		(end 46.76521 -296.35831)
		(width 0.16002)
		(layer "In2.Cu")
		(net "M_C_CPU1_SB_DQS_DN<6>")
	)
	(segment
		(start 44.209462 -295.767506)
		(end 45.338746 -295.767506)
		(width 0.16002)
		(layer "In2.Cu")
		(net "M_C_CPU1_SB_DQS_DN<6>")
	)
	(segment
		(start 82.181192 -281.70632)
		(end 82.189574 -281.701494)
		(width 0.09525)
		(layer "In2.Cu")
		(net "M_C_CPU1_SB_DQS_DN<6>")
	)
	(segment
		(start 90.64117 -281.70632)
		(end 90.649552 -281.701494)
		(width 0.09525)
		(layer "In2.Cu")
		(net "M_C_CPU1_SB_DQS_DN<6>")
	)
	(segment
		(start 43.278044 -295.206166)
		(end 43.577764 -295.505886)
		(width 0.16002)
		(layer "In2.Cu")
		(net "M_C_CPU1_SB_DQS_DN<6>")
	)
	(segment
		(start 65.82029 -291.238686)
		(end 65.82029 -290.178744)
		(width 0.16002)
		(layer "In2.Cu")
		(net "M_C_CPU1_SB_DQS_DN<6>")
	)
	(segment
		(start 65.82029 -290.178744)
		(end 66.03111 -289.669982)
		(width 0.16002)
		(layer "In2.Cu")
		(net "M_C_CPU1_SB_DQS_DN<6>")
	)
	(segment
		(start 75.955906 -281.672284)
		(end 75.979528 -281.672284)
		(width 0.09525)
		(layer "In2.Cu")
		(net "M_C_CPU1_SB_DQS_DN<6>")
	)
	(segment
		(start 40.23995 -295.085262)
		(end 40.514016 -295.359328)
		(width 0.16002)
		(layer "In2.Cu")
		(net "M_C_CPU1_SB_DQS_DN<6>")
	)
	(segment
		(start 93.092524 -281.701494)
		(end 93.100906 -281.70632)
		(width 0.09525)
		(layer "In2.Cu")
		(net "M_C_CPU1_SB_DQS_DN<6>")
	)
	(segment
		(start 75.979528 -281.672284)
		(end 76.03871 -281.731466)
		(width 0.09525)
		(layer "In2.Cu")
		(net "M_C_CPU1_SB_DQS_DN<6>")
	)
	(segment
		(start 95.341186 -281.70632)
		(end 95.349568 -281.701494)
		(width 0.09525)
		(layer "In2.Cu")
		(net "M_C_CPU1_SB_DQS_DN<6>")
	)
	(segment
		(start 46.76521 -296.35831)
		(end 48.53813 -296.35831)
		(width 0.16002)
		(layer "In2.Cu")
		(net "M_C_CPU1_SB_DQS_DN<6>")
	)
	(segment
		(start 40.514016 -295.359328)
		(end 42.264838 -295.359328)
		(width 0.16002)
		(layer "In2.Cu")
		(net "M_C_CPU1_SB_DQS_DN<6>")
	)
	(segment
		(start 87.452454 -281.701494)
		(end 87.460836 -281.70632)
		(width 0.09525)
		(layer "In2.Cu")
		(net "M_C_CPU1_SB_DQS_DN<6>")
	)
	(segment
		(start 86.881208 -281.70632)
		(end 86.88959 -281.701494)
		(width 0.09525)
		(layer "In2.Cu")
		(net "M_C_CPU1_SB_DQS_DN<6>")
	)
	(segment
		(start 48.53813 -296.35831)
		(end 48.816514 -296.079926)
		(width 0.16002)
		(layer "In2.Cu")
		(net "M_C_CPU1_SB_DQS_DN<6>")
	)
	(segment
		(start 42.634662 -295.206166)
		(end 43.278044 -295.206166)
		(width 0.16002)
		(layer "In2.Cu")
		(net "M_C_CPU1_SB_DQS_DN<6>")
	)
	(segment
		(start 58.63717 -295.467532)
		(end 61.591444 -295.467532)
		(width 0.16002)
		(layer "In2.Cu")
		(net "M_C_CPU1_SB_DQS_DN<6>")
	)
	(segment
		(start 57.757314 -295.20896)
		(end 58.378598 -295.20896)
		(width 0.16002)
		(layer "In2.Cu")
		(net "M_C_CPU1_SB_DQS_DN<6>")
	)
	(segment
		(start 53.960014 -295.968674)
		(end 54.322472 -296.331132)
		(width 0.16002)
		(layer "In2.Cu")
		(net "M_C_CPU1_SB_DQS_DN<6>")
	)
	(segment
		(start 83.692492 -281.701494)
		(end 83.700874 -281.70632)
		(width 0.09525)
		(layer "In2.Cu")
		(net "M_C_CPU1_SB_DQS_DN<6>")
	)
	(segment
		(start 92.15247 -281.701494)
		(end 92.160852 -281.70632)
		(width 0.09525)
		(layer "In2.Cu")
		(net "M_C_CPU1_SB_DQS_DN<6>")
	)
	(segment
		(start 95.846392 -281.668474)
		(end 95.94723 -281.641804)
		(width 0.09525)
		(layer "In2.Cu")
		(net "M_C_CPU1_SB_DQS_DN<6>")
	)
	(segment
		(start 50.819812 -295.180512)
		(end 51.147472 -295.508172)
		(width 0.16002)
		(layer "In2.Cu")
		(net "M_C_CPU1_SB_DQS_DN<6>")
	)
	(segment
		(start 85.941154 -281.70632)
		(end 85.949536 -281.701494)
		(width 0.09525)
		(layer "In2.Cu")
		(net "M_C_CPU1_SB_DQS_DN<6>")
	)
	(segment
		(start 78.011274 -281.625548)
		(end 79.650082 -281.625548)
		(width 0.09525)
		(layer "In2.Cu")
		(net "M_C_CPU1_SB_DQS_DN<6>")
	)
	(segment
		(start 50.239676 -295.180512)
		(end 50.819812 -295.180512)
		(width 0.16002)
		(layer "In2.Cu")
		(net "M_C_CPU1_SB_DQS_DN<6>")
	)
	(segment
		(start 76.03871 -281.731466)
		(end 77.905356 -281.731466)
		(width 0.09525)
		(layer "In2.Cu")
		(net "M_C_CPU1_SB_DQS_DN<6>")
	)
	(segment
		(start 74.028808 -281.672284)
		(end 75.955906 -281.672284)
		(width 0.16002)
		(layer "In2.Cu")
		(net "M_C_CPU1_SB_DQS_DN<6>")
	)
	(segment
		(start 82.752438 -281.701494)
		(end 82.76082 -281.70632)
		(width 0.09525)
		(layer "In2.Cu")
		(net "M_C_CPU1_SB_DQS_DN<6>")
	)
	(segment
		(start 54.322472 -296.331132)
		(end 56.101488 -296.331132)
		(width 0.16002)
		(layer "In2.Cu")
		(net "M_C_CPU1_SB_DQS_DN<6>")
	)
	(segment
		(start 58.378598 -295.20896)
		(end 58.63717 -295.467532)
		(width 0.16002)
		(layer "In2.Cu")
		(net "M_C_CPU1_SB_DQS_DN<6>")
	)
	(segment
		(start 52.848002 -295.508172)
		(end 53.960014 -295.968674)
		(width 0.16002)
		(layer "In2.Cu")
		(net "M_C_CPU1_SB_DQS_DN<6>")
	)
	(segment
		(start 51.147472 -295.508172)
		(end 52.848002 -295.508172)
		(width 0.16002)
		(layer "In2.Cu")
		(net "M_C_CPU1_SB_DQS_DN<6>")
	)
	(segment
		(start 61.591444 -295.467532)
		(end 65.82029 -291.238686)
		(width 0.16002)
		(layer "In2.Cu")
		(net "M_C_CPU1_SB_DQS_DN<6>")
	)
	(segment
		(start 56.673242 -295.933622)
		(end 57.757314 -295.20896)
		(width 0.16002)
		(layer "In2.Cu")
		(net "M_C_CPU1_SB_DQS_DN<6>")
	)
	(arc
		(start 84.632546 -281.701494)
		(mid 84.821014 -281.752171)
		(end 85.009482 -281.701494)
		(width 0.09525)
		(layer "In2.Cu")
		(net "M_C_CPU1_SB_DQS_DN<6>")
	)
	(arc
		(start 82.189574 -281.701494)
		(mid 82.471006 -281.625739)
		(end 82.752438 -281.701494)
		(width 0.09525)
		(layer "In2.Cu")
		(net "M_C_CPU1_SB_DQS_DN<6>")
	)
	(arc
		(start 88.40089 -281.70632)
		(mid 88.585922 -281.752234)
		(end 88.769698 -281.701494)
		(width 0.09525)
		(layer "In2.Cu")
		(net "M_C_CPU1_SB_DQS_DN<6>")
	)
	(arc
		(start 85.949536 -281.701494)
		(mid 86.230968 -281.625739)
		(end 86.5124 -281.701494)
		(width 0.09525)
		(layer "In2.Cu")
		(net "M_C_CPU1_SB_DQS_DN<6>")
	)
	(arc
		(start 86.5124 -281.701494)
		(mid 86.696175 -281.752266)
		(end 86.881208 -281.70632)
		(width 0.09525)
		(layer "In2.Cu")
		(net "M_C_CPU1_SB_DQS_DN<6>")
	)
	(arc
		(start 83.129628 -281.701494)
		(mid 83.41106 -281.625739)
		(end 83.692492 -281.701494)
		(width 0.09525)
		(layer "In2.Cu")
		(net "M_C_CPU1_SB_DQS_DN<6>")
	)
	(arc
		(start 91.212416 -281.701494)
		(mid 91.396191 -281.752266)
		(end 91.581224 -281.70632)
		(width 0.09525)
		(layer "In2.Cu")
		(net "M_C_CPU1_SB_DQS_DN<6>")
	)
	(arc
		(start 88.769698 -281.701494)
		(mid 89.05113 -281.625739)
		(end 89.332562 -281.701494)
		(width 0.09525)
		(layer "In2.Cu")
		(net "M_C_CPU1_SB_DQS_DN<6>")
	)
	(arc
		(start 94.409514 -281.701494)
		(mid 94.690946 -281.625739)
		(end 94.972378 -281.701494)
		(width 0.09525)
		(layer "In2.Cu")
		(net "M_C_CPU1_SB_DQS_DN<6>")
	)
	(arc
		(start 95.349568 -281.701494)
		(mid 95.59411 -281.626809)
		(end 95.846392 -281.668474)
		(width 0.09525)
		(layer "In2.Cu")
		(net "M_C_CPU1_SB_DQS_DN<6>")
	)
	(arc
		(start 90.272362 -281.701494)
		(mid 90.456137 -281.752266)
		(end 90.64117 -281.70632)
		(width 0.09525)
		(layer "In2.Cu")
		(net "M_C_CPU1_SB_DQS_DN<6>")
	)
	(arc
		(start 83.700874 -281.70632)
		(mid 83.885906 -281.752234)
		(end 84.069682 -281.701494)
		(width 0.09525)
		(layer "In2.Cu")
		(net "M_C_CPU1_SB_DQS_DN<6>")
	)
	(arc
		(start 93.469714 -281.701494)
		(mid 93.751146 -281.625739)
		(end 94.032578 -281.701494)
		(width 0.09525)
		(layer "In2.Cu")
		(net "M_C_CPU1_SB_DQS_DN<6>")
	)
	(arc
		(start 92.52966 -281.701494)
		(mid 92.811092 -281.625739)
		(end 93.092524 -281.701494)
		(width 0.09525)
		(layer "In2.Cu")
		(net "M_C_CPU1_SB_DQS_DN<6>")
	)
	(arc
		(start 91.589606 -281.701494)
		(mid 91.871038 -281.625739)
		(end 92.15247 -281.701494)
		(width 0.09525)
		(layer "In2.Cu")
		(net "M_C_CPU1_SB_DQS_DN<6>")
	)
	(arc
		(start 80.30972 -281.701494)
		(mid 80.591152 -281.625739)
		(end 80.872584 -281.701494)
		(width 0.09525)
		(layer "In2.Cu")
		(net "M_C_CPU1_SB_DQS_DN<6>")
	)
	(arc
		(start 94.972378 -281.701494)
		(mid 95.156153 -281.752266)
		(end 95.341186 -281.70632)
		(width 0.09525)
		(layer "In2.Cu")
		(net "M_C_CPU1_SB_DQS_DN<6>")
	)
	(arc
		(start 82.76082 -281.70632)
		(mid 82.945852 -281.752234)
		(end 83.129628 -281.701494)
		(width 0.09525)
		(layer "In2.Cu")
		(net "M_C_CPU1_SB_DQS_DN<6>")
	)
	(arc
		(start 87.829644 -281.701494)
		(mid 88.111076 -281.625739)
		(end 88.392508 -281.701494)
		(width 0.09525)
		(layer "In2.Cu")
		(net "M_C_CPU1_SB_DQS_DN<6>")
	)
	(arc
		(start 85.009482 -281.701494)
		(mid 85.290914 -281.625739)
		(end 85.572346 -281.701494)
		(width 0.09525)
		(layer "In2.Cu")
		(net "M_C_CPU1_SB_DQS_DN<6>")
	)
	(arc
		(start 89.332562 -281.701494)
		(mid 89.52103 -281.752171)
		(end 89.709498 -281.701494)
		(width 0.09525)
		(layer "In2.Cu")
		(net "M_C_CPU1_SB_DQS_DN<6>")
	)
	(arc
		(start 81.812384 -281.701494)
		(mid 81.996159 -281.752266)
		(end 82.181192 -281.70632)
		(width 0.09525)
		(layer "In2.Cu")
		(net "M_C_CPU1_SB_DQS_DN<6>")
	)
	(arc
		(start 80.872584 -281.701494)
		(mid 81.061052 -281.752171)
		(end 81.24952 -281.701494)
		(width 0.09525)
		(layer "In2.Cu")
		(net "M_C_CPU1_SB_DQS_DN<6>")
	)
	(arc
		(start 79.932022 -281.701494)
		(mid 80.116051 -281.752393)
		(end 80.301338 -281.70632)
		(width 0.09525)
		(layer "In2.Cu")
		(net "M_C_CPU1_SB_DQS_DN<6>")
	)
	(arc
		(start 93.100906 -281.70632)
		(mid 93.285938 -281.752234)
		(end 93.469714 -281.701494)
		(width 0.09525)
		(layer "In2.Cu")
		(net "M_C_CPU1_SB_DQS_DN<6>")
	)
	(arc
		(start 81.24952 -281.701494)
		(mid 81.530952 -281.625739)
		(end 81.812384 -281.701494)
		(width 0.09525)
		(layer "In2.Cu")
		(net "M_C_CPU1_SB_DQS_DN<6>")
	)
	(arc
		(start 94.032578 -281.701494)
		(mid 94.221046 -281.752171)
		(end 94.409514 -281.701494)
		(width 0.09525)
		(layer "In2.Cu")
		(net "M_C_CPU1_SB_DQS_DN<6>")
	)
	(arc
		(start 92.160852 -281.70632)
		(mid 92.345884 -281.752234)
		(end 92.52966 -281.701494)
		(width 0.09525)
		(layer "In2.Cu")
		(net "M_C_CPU1_SB_DQS_DN<6>")
	)
	(arc
		(start 79.650082 -281.625548)
		(mid 79.796077 -281.644866)
		(end 79.932022 -281.701494)
		(width 0.09525)
		(layer "In2.Cu")
		(net "M_C_CPU1_SB_DQS_DN<6>")
	)
	(arc
		(start 90.649552 -281.701494)
		(mid 90.930984 -281.625739)
		(end 91.212416 -281.701494)
		(width 0.09525)
		(layer "In2.Cu")
		(net "M_C_CPU1_SB_DQS_DN<6>")
	)
	(arc
		(start 89.709498 -281.701494)
		(mid 89.99093 -281.625739)
		(end 90.272362 -281.701494)
		(width 0.09525)
		(layer "In2.Cu")
		(net "M_C_CPU1_SB_DQS_DN<6>")
	)
	(arc
		(start 85.572346 -281.701494)
		(mid 85.756121 -281.752266)
		(end 85.941154 -281.70632)
		(width 0.09525)
		(layer "In2.Cu")
		(net "M_C_CPU1_SB_DQS_DN<6>")
	)
	(arc
		(start 86.88959 -281.701494)
		(mid 87.171022 -281.625739)
		(end 87.452454 -281.701494)
		(width 0.09525)
		(layer "In2.Cu")
		(net "M_C_CPU1_SB_DQS_DN<6>")
	)
	(arc
		(start 87.460836 -281.70632)
		(mid 87.645868 -281.752234)
		(end 87.829644 -281.701494)
		(width 0.09525)
		(layer "In2.Cu")
		(net "M_C_CPU1_SB_DQS_DN<6>")
	)
	(arc
		(start 84.069682 -281.701494)
		(mid 84.351114 -281.625739)
		(end 84.632546 -281.701494)
		(width 0.09525)
		(layer "In2.Cu")
		(net "M_C_CPU1_SB_DQS_DN<6>")
	)
	(segment
		(start 96.568006 -276.2504)
		(end 96.101154 -276.516338)
		(width 0.12954)
		(layer "F.Cu")
		(net "M_C_CPU1_SB_DQS_DN<5>")
	)
	(segment
		(start 86.881208 -276.846284)
		(end 86.88959 -276.841458)
		(width 0.09525)
		(layer "In2.Cu")
		(net "M_C_CPU1_SB_DQS_DN<5>")
	)
	(segment
		(start 50.206148 -285.830518)
		(end 50.819812 -285.830518)
		(width 0.16002)
		(layer "In2.Cu")
		(net "M_C_CPU1_SB_DQS_DN<5>")
	)
	(segment
		(start 48.53813 -287.008316)
		(end 48.93183 -286.614616)
		(width 0.16002)
		(layer "In2.Cu")
		(net "M_C_CPU1_SB_DQS_DN<5>")
	)
	(segment
		(start 88.392508 -276.841458)
		(end 88.40089 -276.846284)
		(width 0.09525)
		(layer "In2.Cu")
		(net "M_C_CPU1_SB_DQS_DN<5>")
	)
	(segment
		(start 76.810362 -276.521418)
		(end 77.400912 -276.76602)
		(width 0.09525)
		(layer "In2.Cu")
		(net "M_C_CPU1_SB_DQS_DN<5>")
	)
	(segment
		(start 49.76876 -286.267906)
		(end 50.206148 -285.830518)
		(width 0.16002)
		(layer "In2.Cu")
		(net "M_C_CPU1_SB_DQS_DN<5>")
	)
	(segment
		(start 50.819812 -285.830518)
		(end 51.147472 -286.158178)
		(width 0.16002)
		(layer "In2.Cu")
		(net "M_C_CPU1_SB_DQS_DN<5>")
	)
	(segment
		(start 57.757314 -285.858966)
		(end 58.378598 -285.858966)
		(width 0.16002)
		(layer "In2.Cu")
		(net "M_C_CPU1_SB_DQS_DN<5>")
	)
	(segment
		(start 78.991968 -276.841458)
		(end 79.00035 -276.846284)
		(width 0.09525)
		(layer "In2.Cu")
		(net "M_C_CPU1_SB_DQS_DN<5>")
	)
	(segment
		(start 75.955906 -276.048724)
		(end 75.979528 -276.048724)
		(width 0.09525)
		(layer "In2.Cu")
		(net "M_C_CPU1_SB_DQS_DN<5>")
	)
	(segment
		(start 54.322472 -286.981138)
		(end 56.101488 -286.981138)
		(width 0.16002)
		(layer "In2.Cu")
		(net "M_C_CPU1_SB_DQS_DN<5>")
	)
	(segment
		(start 56.101488 -286.981138)
		(end 56.375554 -286.707072)
		(width 0.16002)
		(layer "In2.Cu")
		(net "M_C_CPU1_SB_DQS_DN<5>")
	)
	(segment
		(start 95.341186 -276.846284)
		(end 95.349568 -276.841458)
		(width 0.09525)
		(layer "In2.Cu")
		(net "M_C_CPU1_SB_DQS_DN<5>")
	)
	(segment
		(start 76.03871 -276.107906)
		(end 76.39685 -276.107906)
		(width 0.09525)
		(layer "In2.Cu")
		(net "M_C_CPU1_SB_DQS_DN<5>")
	)
	(segment
		(start 43.280838 -285.858966)
		(end 43.625262 -286.20339)
		(width 0.16002)
		(layer "In2.Cu")
		(net "M_C_CPU1_SB_DQS_DN<5>")
	)
	(segment
		(start 53.892958 -286.551624)
		(end 54.322472 -286.981138)
		(width 0.16002)
		(layer "In2.Cu")
		(net "M_C_CPU1_SB_DQS_DN<5>")
	)
	(segment
		(start 60.324746 -286.117538)
		(end 62.273942 -285.310072)
		(width 0.16002)
		(layer "In2.Cu")
		(net "M_C_CPU1_SB_DQS_DN<5>")
	)
	(segment
		(start 76.39685 -276.107906)
		(end 76.810362 -276.521418)
		(width 0.09525)
		(layer "In2.Cu")
		(net "M_C_CPU1_SB_DQS_DN<5>")
	)
	(segment
		(start 82.181192 -276.846284)
		(end 82.189574 -276.841458)
		(width 0.09525)
		(layer "In2.Cu")
		(net "M_C_CPU1_SB_DQS_DN<5>")
	)
	(segment
		(start 93.092524 -276.841458)
		(end 93.100906 -276.846284)
		(width 0.09525)
		(layer "In2.Cu")
		(net "M_C_CPU1_SB_DQS_DN<5>")
	)
	(segment
		(start 85.941154 -276.846284)
		(end 85.949536 -276.841458)
		(width 0.09525)
		(layer "In2.Cu")
		(net "M_C_CPU1_SB_DQS_DN<5>")
	)
	(segment
		(start 71.53529 -276.048724)
		(end 75.955906 -276.048724)
		(width 0.16002)
		(layer "In2.Cu")
		(net "M_C_CPU1_SB_DQS_DN<5>")
	)
	(segment
		(start 58.63717 -286.117538)
		(end 60.324746 -286.117538)
		(width 0.16002)
		(layer "In2.Cu")
		(net "M_C_CPU1_SB_DQS_DN<5>")
	)
	(segment
		(start 92.15247 -276.841458)
		(end 92.160852 -276.846284)
		(width 0.09525)
		(layer "In2.Cu")
		(net "M_C_CPU1_SB_DQS_DN<5>")
	)
	(segment
		(start 43.625262 -286.20339)
		(end 44.142152 -286.417512)
		(width 0.16002)
		(layer "In2.Cu")
		(net "M_C_CPU1_SB_DQS_DN<5>")
	)
	(segment
		(start 80.301338 -276.846284)
		(end 80.30972 -276.841458)
		(width 0.09525)
		(layer "In2.Cu")
		(net "M_C_CPU1_SB_DQS_DN<5>")
	)
	(segment
		(start 79.36865 -276.841458)
		(end 79.383382 -276.832822)
		(width 0.09525)
		(layer "In2.Cu")
		(net "M_C_CPU1_SB_DQS_DN<5>")
	)
	(segment
		(start 83.692492 -276.841458)
		(end 83.700874 -276.846284)
		(width 0.09525)
		(layer "In2.Cu")
		(net "M_C_CPU1_SB_DQS_DN<5>")
	)
	(segment
		(start 44.142152 -286.417512)
		(end 45.92066 -286.417512)
		(width 0.16002)
		(layer "In2.Cu")
		(net "M_C_CPU1_SB_DQS_DN<5>")
	)
	(segment
		(start 42.295826 -286.009334)
		(end 42.446194 -285.858966)
		(width 0.16002)
		(layer "In2.Cu")
		(net "M_C_CPU1_SB_DQS_DN<5>")
	)
	(segment
		(start 56.375554 -286.707072)
		(end 56.673242 -286.583628)
		(width 0.16002)
		(layer "In2.Cu")
		(net "M_C_CPU1_SB_DQS_DN<5>")
	)
	(segment
		(start 45.92066 -286.417512)
		(end 46.457108 -286.639762)
		(width 0.16002)
		(layer "In2.Cu")
		(net "M_C_CPU1_SB_DQS_DN<5>")
	)
	(segment
		(start 42.446194 -285.858966)
		(end 43.280838 -285.858966)
		(width 0.16002)
		(layer "In2.Cu")
		(net "M_C_CPU1_SB_DQS_DN<5>")
	)
	(segment
		(start 87.452454 -276.841458)
		(end 87.460836 -276.846284)
		(width 0.09525)
		(layer "In2.Cu")
		(net "M_C_CPU1_SB_DQS_DN<5>")
	)
	(segment
		(start 46.825662 -287.008316)
		(end 48.53813 -287.008316)
		(width 0.16002)
		(layer "In2.Cu")
		(net "M_C_CPU1_SB_DQS_DN<5>")
	)
	(segment
		(start 62.273942 -285.310072)
		(end 71.53529 -276.048724)
		(width 0.16002)
		(layer "In2.Cu")
		(net "M_C_CPU1_SB_DQS_DN<5>")
	)
	(segment
		(start 40.23995 -285.735268)
		(end 40.514016 -286.009334)
		(width 0.16002)
		(layer "In2.Cu")
		(net "M_C_CPU1_SB_DQS_DN<5>")
	)
	(segment
		(start 95.94723 -276.781768)
		(end 96.101154 -276.516338)
		(width 0.09525)
		(layer "In2.Cu")
		(net "M_C_CPU1_SB_DQS_DN<5>")
	)
	(segment
		(start 51.147472 -286.158178)
		(end 52.942998 -286.158178)
		(width 0.16002)
		(layer "In2.Cu")
		(net "M_C_CPU1_SB_DQS_DN<5>")
	)
	(segment
		(start 95.846392 -276.808438)
		(end 95.94723 -276.781768)
		(width 0.09525)
		(layer "In2.Cu")
		(net "M_C_CPU1_SB_DQS_DN<5>")
	)
	(segment
		(start 75.979528 -276.048724)
		(end 76.03871 -276.107906)
		(width 0.09525)
		(layer "In2.Cu")
		(net "M_C_CPU1_SB_DQS_DN<5>")
	)
	(segment
		(start 82.752438 -276.841458)
		(end 82.76082 -276.846284)
		(width 0.09525)
		(layer "In2.Cu")
		(net "M_C_CPU1_SB_DQS_DN<5>")
	)
	(segment
		(start 90.64117 -276.846284)
		(end 90.649552 -276.841458)
		(width 0.09525)
		(layer "In2.Cu")
		(net "M_C_CPU1_SB_DQS_DN<5>")
	)
	(segment
		(start 91.581224 -276.846284)
		(end 91.589606 -276.841458)
		(width 0.09525)
		(layer "In2.Cu")
		(net "M_C_CPU1_SB_DQS_DN<5>")
	)
	(segment
		(start 77.400912 -276.76602)
		(end 78.711044 -276.76602)
		(width 0.09525)
		(layer "In2.Cu")
		(net "M_C_CPU1_SB_DQS_DN<5>")
	)
	(segment
		(start 58.378598 -285.858966)
		(end 58.63717 -286.117538)
		(width 0.16002)
		(layer "In2.Cu")
		(net "M_C_CPU1_SB_DQS_DN<5>")
	)
	(segment
		(start 46.457108 -286.639762)
		(end 46.825662 -287.008316)
		(width 0.16002)
		(layer "In2.Cu")
		(net "M_C_CPU1_SB_DQS_DN<5>")
	)
	(segment
		(start 56.673242 -286.583628)
		(end 57.757314 -285.858966)
		(width 0.16002)
		(layer "In2.Cu")
		(net "M_C_CPU1_SB_DQS_DN<5>")
	)
	(segment
		(start 40.514016 -286.009334)
		(end 42.295826 -286.009334)
		(width 0.16002)
		(layer "In2.Cu")
		(net "M_C_CPU1_SB_DQS_DN<5>")
	)
	(segment
		(start 48.93183 -286.614616)
		(end 49.76876 -286.267906)
		(width 0.16002)
		(layer "In2.Cu")
		(net "M_C_CPU1_SB_DQS_DN<5>")
	)
	(segment
		(start 52.942998 -286.158178)
		(end 53.892958 -286.551624)
		(width 0.16002)
		(layer "In2.Cu")
		(net "M_C_CPU1_SB_DQS_DN<5>")
	)
	(arc
		(start 92.52966 -276.841458)
		(mid 92.811092 -276.765703)
		(end 93.092524 -276.841458)
		(width 0.09525)
		(layer "In2.Cu")
		(net "M_C_CPU1_SB_DQS_DN<5>")
	)
	(arc
		(start 84.632546 -276.841458)
		(mid 84.821014 -276.892135)
		(end 85.009482 -276.841458)
		(width 0.09525)
		(layer "In2.Cu")
		(net "M_C_CPU1_SB_DQS_DN<5>")
	)
	(arc
		(start 86.88959 -276.841458)
		(mid 87.171022 -276.765703)
		(end 87.452454 -276.841458)
		(width 0.09525)
		(layer "In2.Cu")
		(net "M_C_CPU1_SB_DQS_DN<5>")
	)
	(arc
		(start 84.069682 -276.841458)
		(mid 84.351114 -276.765703)
		(end 84.632546 -276.841458)
		(width 0.09525)
		(layer "In2.Cu")
		(net "M_C_CPU1_SB_DQS_DN<5>")
	)
	(arc
		(start 89.709498 -276.841458)
		(mid 89.99093 -276.765703)
		(end 90.272362 -276.841458)
		(width 0.09525)
		(layer "In2.Cu")
		(net "M_C_CPU1_SB_DQS_DN<5>")
	)
	(arc
		(start 86.5124 -276.841458)
		(mid 86.696175 -276.89223)
		(end 86.881208 -276.846284)
		(width 0.09525)
		(layer "In2.Cu")
		(net "M_C_CPU1_SB_DQS_DN<5>")
	)
	(arc
		(start 89.332562 -276.841458)
		(mid 89.52103 -276.892135)
		(end 89.709498 -276.841458)
		(width 0.09525)
		(layer "In2.Cu")
		(net "M_C_CPU1_SB_DQS_DN<5>")
	)
	(arc
		(start 85.949536 -276.841458)
		(mid 86.230968 -276.765703)
		(end 86.5124 -276.841458)
		(width 0.09525)
		(layer "In2.Cu")
		(net "M_C_CPU1_SB_DQS_DN<5>")
	)
	(arc
		(start 79.00035 -276.846284)
		(mid 79.185128 -276.892077)
		(end 79.36865 -276.841458)
		(width 0.09525)
		(layer "In2.Cu")
		(net "M_C_CPU1_SB_DQS_DN<5>")
	)
	(arc
		(start 91.212416 -276.841458)
		(mid 91.396191 -276.89223)
		(end 91.581224 -276.846284)
		(width 0.09525)
		(layer "In2.Cu")
		(net "M_C_CPU1_SB_DQS_DN<5>")
	)
	(arc
		(start 80.30972 -276.841458)
		(mid 80.591152 -276.765703)
		(end 80.872584 -276.841458)
		(width 0.09525)
		(layer "In2.Cu")
		(net "M_C_CPU1_SB_DQS_DN<5>")
	)
	(arc
		(start 81.812384 -276.841458)
		(mid 81.996159 -276.89223)
		(end 82.181192 -276.846284)
		(width 0.09525)
		(layer "In2.Cu")
		(net "M_C_CPU1_SB_DQS_DN<5>")
	)
	(arc
		(start 79.383382 -276.832822)
		(mid 79.658841 -276.765437)
		(end 79.932022 -276.841458)
		(width 0.09525)
		(layer "In2.Cu")
		(net "M_C_CPU1_SB_DQS_DN<5>")
	)
	(arc
		(start 85.009482 -276.841458)
		(mid 85.290914 -276.765703)
		(end 85.572346 -276.841458)
		(width 0.09525)
		(layer "In2.Cu")
		(net "M_C_CPU1_SB_DQS_DN<5>")
	)
	(arc
		(start 82.189574 -276.841458)
		(mid 82.471006 -276.765703)
		(end 82.752438 -276.841458)
		(width 0.09525)
		(layer "In2.Cu")
		(net "M_C_CPU1_SB_DQS_DN<5>")
	)
	(arc
		(start 80.872584 -276.841458)
		(mid 81.061052 -276.892135)
		(end 81.24952 -276.841458)
		(width 0.09525)
		(layer "In2.Cu")
		(net "M_C_CPU1_SB_DQS_DN<5>")
	)
	(arc
		(start 83.700874 -276.846284)
		(mid 83.885906 -276.892198)
		(end 84.069682 -276.841458)
		(width 0.09525)
		(layer "In2.Cu")
		(net "M_C_CPU1_SB_DQS_DN<5>")
	)
	(arc
		(start 94.032578 -276.841458)
		(mid 94.221046 -276.892135)
		(end 94.409514 -276.841458)
		(width 0.09525)
		(layer "In2.Cu")
		(net "M_C_CPU1_SB_DQS_DN<5>")
	)
	(arc
		(start 83.129628 -276.841458)
		(mid 83.41106 -276.765703)
		(end 83.692492 -276.841458)
		(width 0.09525)
		(layer "In2.Cu")
		(net "M_C_CPU1_SB_DQS_DN<5>")
	)
	(arc
		(start 91.589606 -276.841458)
		(mid 91.871038 -276.765703)
		(end 92.15247 -276.841458)
		(width 0.09525)
		(layer "In2.Cu")
		(net "M_C_CPU1_SB_DQS_DN<5>")
	)
	(arc
		(start 94.409514 -276.841458)
		(mid 94.690946 -276.765703)
		(end 94.972378 -276.841458)
		(width 0.09525)
		(layer "In2.Cu")
		(net "M_C_CPU1_SB_DQS_DN<5>")
	)
	(arc
		(start 90.272362 -276.841458)
		(mid 90.456137 -276.89223)
		(end 90.64117 -276.846284)
		(width 0.09525)
		(layer "In2.Cu")
		(net "M_C_CPU1_SB_DQS_DN<5>")
	)
	(arc
		(start 85.572346 -276.841458)
		(mid 85.756121 -276.89223)
		(end 85.941154 -276.846284)
		(width 0.09525)
		(layer "In2.Cu")
		(net "M_C_CPU1_SB_DQS_DN<5>")
	)
	(arc
		(start 88.769698 -276.841458)
		(mid 89.05113 -276.765703)
		(end 89.332562 -276.841458)
		(width 0.09525)
		(layer "In2.Cu")
		(net "M_C_CPU1_SB_DQS_DN<5>")
	)
	(arc
		(start 95.349568 -276.841458)
		(mid 95.59411 -276.766773)
		(end 95.846392 -276.808438)
		(width 0.09525)
		(layer "In2.Cu")
		(net "M_C_CPU1_SB_DQS_DN<5>")
	)
	(arc
		(start 93.469714 -276.841458)
		(mid 93.751146 -276.765703)
		(end 94.032578 -276.841458)
		(width 0.09525)
		(layer "In2.Cu")
		(net "M_C_CPU1_SB_DQS_DN<5>")
	)
	(arc
		(start 88.40089 -276.846284)
		(mid 88.585922 -276.892198)
		(end 88.769698 -276.841458)
		(width 0.09525)
		(layer "In2.Cu")
		(net "M_C_CPU1_SB_DQS_DN<5>")
	)
	(arc
		(start 87.829644 -276.841458)
		(mid 88.111076 -276.765703)
		(end 88.392508 -276.841458)
		(width 0.09525)
		(layer "In2.Cu")
		(net "M_C_CPU1_SB_DQS_DN<5>")
	)
	(arc
		(start 79.932022 -276.841458)
		(mid 80.116051 -276.892357)
		(end 80.301338 -276.846284)
		(width 0.09525)
		(layer "In2.Cu")
		(net "M_C_CPU1_SB_DQS_DN<5>")
	)
	(arc
		(start 82.76082 -276.846284)
		(mid 82.945852 -276.892198)
		(end 83.129628 -276.841458)
		(width 0.09525)
		(layer "In2.Cu")
		(net "M_C_CPU1_SB_DQS_DN<5>")
	)
	(arc
		(start 81.24952 -276.841458)
		(mid 81.530952 -276.765703)
		(end 81.812384 -276.841458)
		(width 0.09525)
		(layer "In2.Cu")
		(net "M_C_CPU1_SB_DQS_DN<5>")
	)
	(arc
		(start 78.711044 -276.76602)
		(mid 78.856474 -276.785222)
		(end 78.991968 -276.841458)
		(width 0.09525)
		(layer "In2.Cu")
		(net "M_C_CPU1_SB_DQS_DN<5>")
	)
	(arc
		(start 87.460836 -276.846284)
		(mid 87.645868 -276.892198)
		(end 87.829644 -276.841458)
		(width 0.09525)
		(layer "In2.Cu")
		(net "M_C_CPU1_SB_DQS_DN<5>")
	)
	(arc
		(start 94.972378 -276.841458)
		(mid 95.156153 -276.89223)
		(end 95.341186 -276.846284)
		(width 0.09525)
		(layer "In2.Cu")
		(net "M_C_CPU1_SB_DQS_DN<5>")
	)
	(arc
		(start 93.100906 -276.846284)
		(mid 93.285938 -276.892198)
		(end 93.469714 -276.841458)
		(width 0.09525)
		(layer "In2.Cu")
		(net "M_C_CPU1_SB_DQS_DN<5>")
	)
	(arc
		(start 92.160852 -276.846284)
		(mid 92.345884 -276.892198)
		(end 92.52966 -276.841458)
		(width 0.09525)
		(layer "In2.Cu")
		(net "M_C_CPU1_SB_DQS_DN<5>")
	)
	(arc
		(start 90.649552 -276.841458)
		(mid 90.930984 -276.765703)
		(end 91.212416 -276.841458)
		(width 0.09525)
		(layer "In2.Cu")
		(net "M_C_CPU1_SB_DQS_DN<5>")
	)
	(segment
		(start 96.568006 -271.390364)
		(end 96.101154 -271.656302)
		(width 0.12954)
		(layer "F.Cu")
		(net "M_C_CPU1_SB_DQS_DN<4>")
	)
	(segment
		(start 76.609194 -270.484346)
		(end 76.858876 -270.734028)
		(width 0.09525)
		(layer "In2.Cu")
		(net "M_C_CPU1_SB_DQS_DN<4>")
	)
	(segment
		(start 48.53813 -277.658322)
		(end 48.816514 -277.379938)
		(width 0.16002)
		(layer "In2.Cu")
		(net "M_C_CPU1_SB_DQS_DN<4>")
	)
	(segment
		(start 80.301338 -271.986248)
		(end 80.30972 -271.981422)
		(width 0.09525)
		(layer "In2.Cu")
		(net "M_C_CPU1_SB_DQS_DN<4>")
	)
	(segment
		(start 50.770536 -276.480524)
		(end 51.098196 -276.808184)
		(width 0.16002)
		(layer "In2.Cu")
		(net "M_C_CPU1_SB_DQS_DN<4>")
	)
	(segment
		(start 42.479468 -276.506686)
		(end 43.265852 -276.506686)
		(width 0.16002)
		(layer "In2.Cu")
		(net "M_C_CPU1_SB_DQS_DN<4>")
	)
	(segment
		(start 49.139856 -277.245826)
		(end 50.046382 -276.640036)
		(width 0.16002)
		(layer "In2.Cu")
		(net "M_C_CPU1_SB_DQS_DN<4>")
	)
	(segment
		(start 50.206148 -276.480524)
		(end 50.770536 -276.480524)
		(width 0.16002)
		(layer "In2.Cu")
		(net "M_C_CPU1_SB_DQS_DN<4>")
	)
	(segment
		(start 95.341186 -271.986248)
		(end 95.349568 -271.981422)
		(width 0.09525)
		(layer "In2.Cu")
		(net "M_C_CPU1_SB_DQS_DN<4>")
	)
	(segment
		(start 85.941154 -271.986248)
		(end 85.949536 -271.981422)
		(width 0.09525)
		(layer "In2.Cu")
		(net "M_C_CPU1_SB_DQS_DN<4>")
	)
	(segment
		(start 42.326814 -276.65934)
		(end 42.479468 -276.506686)
		(width 0.16002)
		(layer "In2.Cu")
		(net "M_C_CPU1_SB_DQS_DN<4>")
	)
	(segment
		(start 91.581224 -271.986248)
		(end 91.589606 -271.981422)
		(width 0.09525)
		(layer "In2.Cu")
		(net "M_C_CPU1_SB_DQS_DN<4>")
	)
	(segment
		(start 88.392508 -271.981422)
		(end 88.40089 -271.986248)
		(width 0.09525)
		(layer "In2.Cu")
		(net "M_C_CPU1_SB_DQS_DN<4>")
	)
	(segment
		(start 56.312308 -277.447248)
		(end 57.715912 -276.508972)
		(width 0.16002)
		(layer "In2.Cu")
		(net "M_C_CPU1_SB_DQS_DN<4>")
	)
	(segment
		(start 95.94723 -271.921732)
		(end 96.101154 -271.656302)
		(width 0.09525)
		(layer "In2.Cu")
		(net "M_C_CPU1_SB_DQS_DN<4>")
	)
	(segment
		(start 57.715912 -276.508972)
		(end 58.378598 -276.508972)
		(width 0.16002)
		(layer "In2.Cu")
		(net "M_C_CPU1_SB_DQS_DN<4>")
	)
	(segment
		(start 86.881208 -271.986248)
		(end 86.88959 -271.981422)
		(width 0.09525)
		(layer "In2.Cu")
		(net "M_C_CPU1_SB_DQS_DN<4>")
	)
	(segment
		(start 60.260992 -276.767544)
		(end 66.603372 -270.425164)
		(width 0.16002)
		(layer "In2.Cu")
		(net "M_C_CPU1_SB_DQS_DN<4>")
	)
	(segment
		(start 78.991968 -271.981422)
		(end 79.00035 -271.986248)
		(width 0.09525)
		(layer "In2.Cu")
		(net "M_C_CPU1_SB_DQS_DN<4>")
	)
	(segment
		(start 76.03871 -270.484346)
		(end 76.609194 -270.484346)
		(width 0.09525)
		(layer "In2.Cu")
		(net "M_C_CPU1_SB_DQS_DN<4>")
	)
	(segment
		(start 82.181192 -271.986248)
		(end 82.189574 -271.981422)
		(width 0.09525)
		(layer "In2.Cu")
		(net "M_C_CPU1_SB_DQS_DN<4>")
	)
	(segment
		(start 82.752438 -271.981422)
		(end 82.76082 -271.986248)
		(width 0.09525)
		(layer "In2.Cu")
		(net "M_C_CPU1_SB_DQS_DN<4>")
	)
	(segment
		(start 76.858876 -270.734028)
		(end 77.247242 -270.734028)
		(width 0.09525)
		(layer "In2.Cu")
		(net "M_C_CPU1_SB_DQS_DN<4>")
	)
	(segment
		(start 53.168042 -276.906736)
		(end 54.252368 -277.631144)
		(width 0.16002)
		(layer "In2.Cu")
		(net "M_C_CPU1_SB_DQS_DN<4>")
	)
	(segment
		(start 83.692492 -271.981422)
		(end 83.700874 -271.986248)
		(width 0.09525)
		(layer "In2.Cu")
		(net "M_C_CPU1_SB_DQS_DN<4>")
	)
	(segment
		(start 48.816514 -277.379938)
		(end 49.139856 -277.245826)
		(width 0.16002)
		(layer "In2.Cu")
		(net "M_C_CPU1_SB_DQS_DN<4>")
	)
	(segment
		(start 77.247242 -270.734028)
		(end 78.419198 -271.905984)
		(width 0.09525)
		(layer "In2.Cu")
		(net "M_C_CPU1_SB_DQS_DN<4>")
	)
	(segment
		(start 79.36865 -271.981422)
		(end 79.383382 -271.972786)
		(width 0.09525)
		(layer "In2.Cu")
		(net "M_C_CPU1_SB_DQS_DN<4>")
	)
	(segment
		(start 43.265852 -276.506686)
		(end 43.826684 -277.067518)
		(width 0.16002)
		(layer "In2.Cu")
		(net "M_C_CPU1_SB_DQS_DN<4>")
	)
	(segment
		(start 40.514016 -276.65934)
		(end 42.326814 -276.65934)
		(width 0.16002)
		(layer "In2.Cu")
		(net "M_C_CPU1_SB_DQS_DN<4>")
	)
	(segment
		(start 52.930298 -276.808184)
		(end 53.168042 -276.906736)
		(width 0.16002)
		(layer "In2.Cu")
		(net "M_C_CPU1_SB_DQS_DN<4>")
	)
	(segment
		(start 54.252368 -277.631144)
		(end 56.128412 -277.631144)
		(width 0.16002)
		(layer "In2.Cu")
		(net "M_C_CPU1_SB_DQS_DN<4>")
	)
	(segment
		(start 75.955906 -270.425164)
		(end 75.979528 -270.425164)
		(width 0.09525)
		(layer "In2.Cu")
		(net "M_C_CPU1_SB_DQS_DN<4>")
	)
	(segment
		(start 40.23995 -276.385274)
		(end 40.514016 -276.65934)
		(width 0.16002)
		(layer "In2.Cu")
		(net "M_C_CPU1_SB_DQS_DN<4>")
	)
	(segment
		(start 50.046382 -276.640036)
		(end 50.206148 -276.480524)
		(width 0.16002)
		(layer "In2.Cu")
		(net "M_C_CPU1_SB_DQS_DN<4>")
	)
	(segment
		(start 58.63717 -276.767544)
		(end 60.260992 -276.767544)
		(width 0.16002)
		(layer "In2.Cu")
		(net "M_C_CPU1_SB_DQS_DN<4>")
	)
	(segment
		(start 45.282866 -277.067518)
		(end 46.709584 -277.658322)
		(width 0.16002)
		(layer "In2.Cu")
		(net "M_C_CPU1_SB_DQS_DN<4>")
	)
	(segment
		(start 43.826684 -277.067518)
		(end 45.282866 -277.067518)
		(width 0.16002)
		(layer "In2.Cu")
		(net "M_C_CPU1_SB_DQS_DN<4>")
	)
	(segment
		(start 66.603372 -270.425164)
		(end 75.955906 -270.425164)
		(width 0.16002)
		(layer "In2.Cu")
		(net "M_C_CPU1_SB_DQS_DN<4>")
	)
	(segment
		(start 46.709584 -277.658322)
		(end 48.53813 -277.658322)
		(width 0.16002)
		(layer "In2.Cu")
		(net "M_C_CPU1_SB_DQS_DN<4>")
	)
	(segment
		(start 95.846392 -271.948402)
		(end 95.94723 -271.921732)
		(width 0.09525)
		(layer "In2.Cu")
		(net "M_C_CPU1_SB_DQS_DN<4>")
	)
	(segment
		(start 75.979528 -270.425164)
		(end 76.03871 -270.484346)
		(width 0.09525)
		(layer "In2.Cu")
		(net "M_C_CPU1_SB_DQS_DN<4>")
	)
	(segment
		(start 56.128412 -277.631144)
		(end 56.312308 -277.447248)
		(width 0.16002)
		(layer "In2.Cu")
		(net "M_C_CPU1_SB_DQS_DN<4>")
	)
	(segment
		(start 58.378598 -276.508972)
		(end 58.63717 -276.767544)
		(width 0.16002)
		(layer "In2.Cu")
		(net "M_C_CPU1_SB_DQS_DN<4>")
	)
	(segment
		(start 93.092524 -271.981422)
		(end 93.100906 -271.986248)
		(width 0.09525)
		(layer "In2.Cu")
		(net "M_C_CPU1_SB_DQS_DN<4>")
	)
	(segment
		(start 78.419198 -271.905984)
		(end 78.711044 -271.905984)
		(width 0.09525)
		(layer "In2.Cu")
		(net "M_C_CPU1_SB_DQS_DN<4>")
	)
	(segment
		(start 51.098196 -276.808184)
		(end 52.930298 -276.808184)
		(width 0.16002)
		(layer "In2.Cu")
		(net "M_C_CPU1_SB_DQS_DN<4>")
	)
	(segment
		(start 92.15247 -271.981422)
		(end 92.160852 -271.986248)
		(width 0.09525)
		(layer "In2.Cu")
		(net "M_C_CPU1_SB_DQS_DN<4>")
	)
	(segment
		(start 87.452454 -271.981422)
		(end 87.460836 -271.986248)
		(width 0.09525)
		(layer "In2.Cu")
		(net "M_C_CPU1_SB_DQS_DN<4>")
	)
	(segment
		(start 90.64117 -271.986248)
		(end 90.649552 -271.981422)
		(width 0.09525)
		(layer "In2.Cu")
		(net "M_C_CPU1_SB_DQS_DN<4>")
	)
	(arc
		(start 79.383382 -271.972786)
		(mid 79.658841 -271.905401)
		(end 79.932022 -271.981422)
		(width 0.09525)
		(layer "In2.Cu")
		(net "M_C_CPU1_SB_DQS_DN<4>")
	)
	(arc
		(start 94.972378 -271.981422)
		(mid 95.156153 -272.032194)
		(end 95.341186 -271.986248)
		(width 0.09525)
		(layer "In2.Cu")
		(net "M_C_CPU1_SB_DQS_DN<4>")
	)
	(arc
		(start 82.189574 -271.981422)
		(mid 82.471006 -271.905667)
		(end 82.752438 -271.981422)
		(width 0.09525)
		(layer "In2.Cu")
		(net "M_C_CPU1_SB_DQS_DN<4>")
	)
	(arc
		(start 86.88959 -271.981422)
		(mid 87.171022 -271.905667)
		(end 87.452454 -271.981422)
		(width 0.09525)
		(layer "In2.Cu")
		(net "M_C_CPU1_SB_DQS_DN<4>")
	)
	(arc
		(start 87.460836 -271.986248)
		(mid 87.645868 -272.032162)
		(end 87.829644 -271.981422)
		(width 0.09525)
		(layer "In2.Cu")
		(net "M_C_CPU1_SB_DQS_DN<4>")
	)
	(arc
		(start 90.272362 -271.981422)
		(mid 90.456137 -272.032194)
		(end 90.64117 -271.986248)
		(width 0.09525)
		(layer "In2.Cu")
		(net "M_C_CPU1_SB_DQS_DN<4>")
	)
	(arc
		(start 94.032578 -271.981422)
		(mid 94.221046 -272.032099)
		(end 94.409514 -271.981422)
		(width 0.09525)
		(layer "In2.Cu")
		(net "M_C_CPU1_SB_DQS_DN<4>")
	)
	(arc
		(start 84.069682 -271.981422)
		(mid 84.351114 -271.905667)
		(end 84.632546 -271.981422)
		(width 0.09525)
		(layer "In2.Cu")
		(net "M_C_CPU1_SB_DQS_DN<4>")
	)
	(arc
		(start 95.349568 -271.981422)
		(mid 95.583082 -271.907579)
		(end 95.825818 -271.940274)
		(width 0.09525)
		(layer "In2.Cu")
		(net "M_C_CPU1_SB_DQS_DN<4>")
	)
	(arc
		(start 82.76082 -271.986248)
		(mid 82.945852 -272.032162)
		(end 83.129628 -271.981422)
		(width 0.09525)
		(layer "In2.Cu")
		(net "M_C_CPU1_SB_DQS_DN<4>")
	)
	(arc
		(start 80.30972 -271.981422)
		(mid 80.591152 -271.905667)
		(end 80.872584 -271.981422)
		(width 0.09525)
		(layer "In2.Cu")
		(net "M_C_CPU1_SB_DQS_DN<4>")
	)
	(arc
		(start 89.709498 -271.981422)
		(mid 89.99093 -271.905667)
		(end 90.272362 -271.981422)
		(width 0.09525)
		(layer "In2.Cu")
		(net "M_C_CPU1_SB_DQS_DN<4>")
	)
	(arc
		(start 85.009482 -271.981422)
		(mid 85.290914 -271.905667)
		(end 85.572346 -271.981422)
		(width 0.09525)
		(layer "In2.Cu")
		(net "M_C_CPU1_SB_DQS_DN<4>")
	)
	(arc
		(start 83.129628 -271.981422)
		(mid 83.41106 -271.905667)
		(end 83.692492 -271.981422)
		(width 0.09525)
		(layer "In2.Cu")
		(net "M_C_CPU1_SB_DQS_DN<4>")
	)
	(arc
		(start 93.469714 -271.981422)
		(mid 93.751146 -271.905667)
		(end 94.032578 -271.981422)
		(width 0.09525)
		(layer "In2.Cu")
		(net "M_C_CPU1_SB_DQS_DN<4>")
	)
	(arc
		(start 93.100906 -271.986248)
		(mid 93.285938 -272.032162)
		(end 93.469714 -271.981422)
		(width 0.09525)
		(layer "In2.Cu")
		(net "M_C_CPU1_SB_DQS_DN<4>")
	)
	(arc
		(start 91.212416 -271.981422)
		(mid 91.396191 -272.032194)
		(end 91.581224 -271.986248)
		(width 0.09525)
		(layer "In2.Cu")
		(net "M_C_CPU1_SB_DQS_DN<4>")
	)
	(arc
		(start 88.40089 -271.986248)
		(mid 88.585922 -272.032162)
		(end 88.769698 -271.981422)
		(width 0.09525)
		(layer "In2.Cu")
		(net "M_C_CPU1_SB_DQS_DN<4>")
	)
	(arc
		(start 79.00035 -271.986248)
		(mid 79.185128 -272.032041)
		(end 79.36865 -271.981422)
		(width 0.09525)
		(layer "In2.Cu")
		(net "M_C_CPU1_SB_DQS_DN<4>")
	)
	(arc
		(start 85.949536 -271.981422)
		(mid 86.230968 -271.905667)
		(end 86.5124 -271.981422)
		(width 0.09525)
		(layer "In2.Cu")
		(net "M_C_CPU1_SB_DQS_DN<4>")
	)
	(arc
		(start 83.700874 -271.986248)
		(mid 83.885906 -272.032162)
		(end 84.069682 -271.981422)
		(width 0.09525)
		(layer "In2.Cu")
		(net "M_C_CPU1_SB_DQS_DN<4>")
	)
	(arc
		(start 89.332562 -271.981422)
		(mid 89.52103 -272.032099)
		(end 89.709498 -271.981422)
		(width 0.09525)
		(layer "In2.Cu")
		(net "M_C_CPU1_SB_DQS_DN<4>")
	)
	(arc
		(start 79.932022 -271.981422)
		(mid 80.116051 -272.032321)
		(end 80.301338 -271.986248)
		(width 0.09525)
		(layer "In2.Cu")
		(net "M_C_CPU1_SB_DQS_DN<4>")
	)
	(arc
		(start 88.769698 -271.981422)
		(mid 89.05113 -271.905667)
		(end 89.332562 -271.981422)
		(width 0.09525)
		(layer "In2.Cu")
		(net "M_C_CPU1_SB_DQS_DN<4>")
	)
	(arc
		(start 92.160852 -271.986248)
		(mid 92.345884 -272.032162)
		(end 92.52966 -271.981422)
		(width 0.09525)
		(layer "In2.Cu")
		(net "M_C_CPU1_SB_DQS_DN<4>")
	)
	(arc
		(start 81.812384 -271.981422)
		(mid 81.996159 -272.032194)
		(end 82.181192 -271.986248)
		(width 0.09525)
		(layer "In2.Cu")
		(net "M_C_CPU1_SB_DQS_DN<4>")
	)
	(arc
		(start 78.711044 -271.905984)
		(mid 78.856474 -271.925186)
		(end 78.991968 -271.981422)
		(width 0.09525)
		(layer "In2.Cu")
		(net "M_C_CPU1_SB_DQS_DN<4>")
	)
	(arc
		(start 86.5124 -271.981422)
		(mid 86.696175 -272.032194)
		(end 86.881208 -271.986248)
		(width 0.09525)
		(layer "In2.Cu")
		(net "M_C_CPU1_SB_DQS_DN<4>")
	)
	(arc
		(start 92.52966 -271.981422)
		(mid 92.811092 -271.905667)
		(end 93.092524 -271.981422)
		(width 0.09525)
		(layer "In2.Cu")
		(net "M_C_CPU1_SB_DQS_DN<4>")
	)
	(arc
		(start 94.409514 -271.981422)
		(mid 94.690946 -271.905667)
		(end 94.972378 -271.981422)
		(width 0.09525)
		(layer "In2.Cu")
		(net "M_C_CPU1_SB_DQS_DN<4>")
	)
	(arc
		(start 81.24952 -271.981422)
		(mid 81.530952 -271.905667)
		(end 81.812384 -271.981422)
		(width 0.09525)
		(layer "In2.Cu")
		(net "M_C_CPU1_SB_DQS_DN<4>")
	)
	(arc
		(start 95.825818 -271.940274)
		(mid 95.836146 -271.944234)
		(end 95.846392 -271.948402)
		(width 0.09525)
		(layer "In2.Cu")
		(net "M_C_CPU1_SB_DQS_DN<4>")
	)
	(arc
		(start 85.572346 -271.981422)
		(mid 85.756121 -272.032194)
		(end 85.941154 -271.986248)
		(width 0.09525)
		(layer "In2.Cu")
		(net "M_C_CPU1_SB_DQS_DN<4>")
	)
	(arc
		(start 91.589606 -271.981422)
		(mid 91.871038 -271.905667)
		(end 92.15247 -271.981422)
		(width 0.09525)
		(layer "In2.Cu")
		(net "M_C_CPU1_SB_DQS_DN<4>")
	)
	(arc
		(start 90.649552 -271.981422)
		(mid 90.930984 -271.905667)
		(end 91.212416 -271.981422)
		(width 0.09525)
		(layer "In2.Cu")
		(net "M_C_CPU1_SB_DQS_DN<4>")
	)
	(arc
		(start 84.632546 -271.981422)
		(mid 84.821014 -272.032099)
		(end 85.009482 -271.981422)
		(width 0.09525)
		(layer "In2.Cu")
		(net "M_C_CPU1_SB_DQS_DN<4>")
	)
	(arc
		(start 87.829644 -271.981422)
		(mid 88.111076 -271.905667)
		(end 88.392508 -271.981422)
		(width 0.09525)
		(layer "In2.Cu")
		(net "M_C_CPU1_SB_DQS_DN<4>")
	)
	(arc
		(start 80.872584 -271.981422)
		(mid 81.061052 -272.032099)
		(end 81.24952 -271.981422)
		(width 0.09525)
		(layer "In2.Cu")
		(net "M_C_CPU1_SB_DQS_DN<4>")
	)
	(segment
		(start 94.687898 -290.830254)
		(end 94.221046 -291.096192)
		(width 0.12954)
		(layer "F.Cu")
		(net "M_C_CPU1_SB_DQS_DN<3>")
	)
	(segment
		(start 48.55337 -313.36234)
		(end 48.86833 -313.6773)
		(width 0.16002)
		(layer "In2.Cu")
		(net "M_C_CPU1_SB_DQS_DN<3>")
	)
	(segment
		(start 88.392508 -290.771072)
		(end 88.40089 -290.766246)
		(width 0.09525)
		(layer "In2.Cu")
		(net "M_C_CPU1_SB_DQS_DN<3>")
	)
	(segment
		(start 82.181192 -290.766246)
		(end 82.189574 -290.771072)
		(width 0.09525)
		(layer "In2.Cu")
		(net "M_C_CPU1_SB_DQS_DN<3>")
	)
	(segment
		(start 93.092524 -290.771072)
		(end 93.100906 -290.766246)
		(width 0.09525)
		(layer "In2.Cu")
		(net "M_C_CPU1_SB_DQS_DN<3>")
	)
	(segment
		(start 67.820032 -308.648354)
		(end 68.347336 -308.648354)
		(width 0.16002)
		(layer "In2.Cu")
		(net "M_C_CPU1_SB_DQS_DN<3>")
	)
	(segment
		(start 56.20385 -313.499246)
		(end 56.39943 -313.69508)
		(width 0.16002)
		(layer "In2.Cu")
		(net "M_C_CPU1_SB_DQS_DN<3>")
	)
	(segment
		(start 50.42281 -312.82386)
		(end 50.82921 -312.82386)
		(width 0.16002)
		(layer "In2.Cu")
		(net "M_C_CPU1_SB_DQS_DN<3>")
	)
	(segment
		(start 68.347336 -308.648354)
		(end 68.72097 -308.27472)
		(width 0.16002)
		(layer "In2.Cu")
		(net "M_C_CPU1_SB_DQS_DN<3>")
	)
	(segment
		(start 72.894952 -304.086006)
		(end 76.65974 -300.321218)
		(width 0.16002)
		(layer "In2.Cu")
		(net "M_C_CPU1_SB_DQS_DN<3>")
	)
	(segment
		(start 70.094602 -306.901088)
		(end 70.094602 -306.373784)
		(width 0.16002)
		(layer "In2.Cu")
		(net "M_C_CPU1_SB_DQS_DN<3>")
	)
	(segment
		(start 70.276212 -305.610006)
		(end 70.567296 -305.90109)
		(width 0.16002)
		(layer "In2.Cu")
		(net "M_C_CPU1_SB_DQS_DN<3>")
	)
	(segment
		(start 79.932784 -290.771072)
		(end 79.943452 -290.764976)
		(width 0.09525)
		(layer "In2.Cu")
		(net "M_C_CPU1_SB_DQS_DN<3>")
	)
	(segment
		(start 76.93787 -293.694866)
		(end 77.22489 -293.694866)
		(width 0.09525)
		(layer "In2.Cu")
		(net "M_C_CPU1_SB_DQS_DN<3>")
	)
	(segment
		(start 68.72097 -307.747416)
		(end 68.429886 -307.456332)
		(width 0.16002)
		(layer "In2.Cu")
		(net "M_C_CPU1_SB_DQS_DN<3>")
	)
	(segment
		(start 76.65974 -295.296336)
		(end 76.600812 -295.237408)
		(width 0.09525)
		(layer "In2.Cu")
		(net "M_C_CPU1_SB_DQS_DN<3>")
	)
	(segment
		(start 44.61383 -313.511438)
		(end 45.627036 -313.511438)
		(width 0.16002)
		(layer "In2.Cu")
		(net "M_C_CPU1_SB_DQS_DN<3>")
	)
	(segment
		(start 53.90007 -313.40552)
		(end 56.10987 -313.40552)
		(width 0.16002)
		(layer "In2.Cu")
		(net "M_C_CPU1_SB_DQS_DN<3>")
	)
	(segment
		(start 56.98871 -313.69508)
		(end 57.78627 -312.89752)
		(width 0.16002)
		(layer "In2.Cu")
		(net "M_C_CPU1_SB_DQS_DN<3>")
	)
	(segment
		(start 66.4464 -310.021986)
		(end 66.973704 -310.021986)
		(width 0.16002)
		(layer "In2.Cu")
		(net "M_C_CPU1_SB_DQS_DN<3>")
	)
	(segment
		(start 68.62572 -306.983638)
		(end 68.90258 -306.983638)
		(width 0.16002)
		(layer "In2.Cu")
		(net "M_C_CPU1_SB_DQS_DN<3>")
	)
	(segment
		(start 56.39943 -313.69508)
		(end 56.98871 -313.69508)
		(width 0.16002)
		(layer "In2.Cu")
		(net "M_C_CPU1_SB_DQS_DN<3>")
	)
	(segment
		(start 66.973704 -310.021986)
		(end 67.347338 -309.648352)
		(width 0.16002)
		(layer "In2.Cu")
		(net "M_C_CPU1_SB_DQS_DN<3>")
	)
	(segment
		(start 67.347338 -309.121048)
		(end 67.056254 -308.829964)
		(width 0.16002)
		(layer "In2.Cu")
		(net "M_C_CPU1_SB_DQS_DN<3>")
	)
	(segment
		(start 87.452454 -290.771072)
		(end 87.460836 -290.766246)
		(width 0.09525)
		(layer "In2.Cu")
		(net "M_C_CPU1_SB_DQS_DN<3>")
	)
	(segment
		(start 57.78627 -312.89752)
		(end 58.26379 -312.89752)
		(width 0.16002)
		(layer "In2.Cu")
		(net "M_C_CPU1_SB_DQS_DN<3>")
	)
	(segment
		(start 94.351856 -290.744148)
		(end 94.37497 -290.830762)
		(width 0.09525)
		(layer "In2.Cu")
		(net "M_C_CPU1_SB_DQS_DN<3>")
	)
	(segment
		(start 76.600812 -295.237408)
		(end 76.600812 -294.031924)
		(width 0.09525)
		(layer "In2.Cu")
		(net "M_C_CPU1_SB_DQS_DN<3>")
	)
	(segment
		(start 66.155316 -309.730902)
		(end 66.4464 -310.021986)
		(width 0.16002)
		(layer "In2.Cu")
		(net "M_C_CPU1_SB_DQS_DN<3>")
	)
	(segment
		(start 91.581224 -290.766246)
		(end 91.589606 -290.771072)
		(width 0.09525)
		(layer "In2.Cu")
		(net "M_C_CPU1_SB_DQS_DN<3>")
	)
	(segment
		(start 68.72097 -308.27472)
		(end 68.72097 -307.747416)
		(width 0.16002)
		(layer "In2.Cu")
		(net "M_C_CPU1_SB_DQS_DN<3>")
	)
	(segment
		(start 58.26379 -312.89752)
		(end 58.61431 -312.547)
		(width 0.16002)
		(layer "In2.Cu")
		(net "M_C_CPU1_SB_DQS_DN<3>")
	)
	(segment
		(start 77.22489 -293.694866)
		(end 78.31201 -292.607746)
		(width 0.09525)
		(layer "In2.Cu")
		(net "M_C_CPU1_SB_DQS_DN<3>")
	)
	(segment
		(start 78.31201 -292.607746)
		(end 78.31201 -291.718746)
		(width 0.09525)
		(layer "In2.Cu")
		(net "M_C_CPU1_SB_DQS_DN<3>")
	)
	(segment
		(start 67.056254 -308.553104)
		(end 67.252088 -308.35727)
		(width 0.16002)
		(layer "In2.Cu")
		(net "M_C_CPU1_SB_DQS_DN<3>")
	)
	(segment
		(start 76.600812 -294.031924)
		(end 76.93787 -293.694866)
		(width 0.09525)
		(layer "In2.Cu")
		(net "M_C_CPU1_SB_DQS_DN<3>")
	)
	(segment
		(start 60.871354 -312.951114)
		(end 61.244226 -313.323986)
		(width 0.16002)
		(layer "In2.Cu")
		(net "M_C_CPU1_SB_DQS_DN<3>")
	)
	(segment
		(start 60.871354 -312.742834)
		(end 60.871354 -312.951114)
		(width 0.16002)
		(layer "In2.Cu")
		(net "M_C_CPU1_SB_DQS_DN<3>")
	)
	(segment
		(start 51.140614 -312.512456)
		(end 53.007006 -312.512456)
		(width 0.16002)
		(layer "In2.Cu")
		(net "M_C_CPU1_SB_DQS_DN<3>")
	)
	(segment
		(start 78.456282 -291.574474)
		(end 79.574644 -291.111178)
		(width 0.09525)
		(layer "In2.Cu")
		(net "M_C_CPU1_SB_DQS_DN<3>")
	)
	(segment
		(start 62.144148 -312.742834)
		(end 62.339982 -312.547)
		(width 0.16002)
		(layer "In2.Cu")
		(net "M_C_CPU1_SB_DQS_DN<3>")
	)
	(segment
		(start 69.720968 -307.274722)
		(end 70.094602 -306.901088)
		(width 0.16002)
		(layer "In2.Cu")
		(net "M_C_CPU1_SB_DQS_DN<3>")
	)
	(segment
		(start 60.67552 -312.547)
		(end 60.871354 -312.742834)
		(width 0.16002)
		(layer "In2.Cu")
		(net "M_C_CPU1_SB_DQS_DN<3>")
	)
	(segment
		(start 44.340018 -313.78525)
		(end 44.61383 -313.511438)
		(width 0.16002)
		(layer "In2.Cu")
		(net "M_C_CPU1_SB_DQS_DN<3>")
	)
	(segment
		(start 62.144148 -312.951114)
		(end 62.144148 -312.742834)
		(width 0.16002)
		(layer "In2.Cu")
		(net "M_C_CPU1_SB_DQS_DN<3>")
	)
	(segment
		(start 79.943452 -290.764976)
		(end 79.957168 -290.757864)
		(width 0.09525)
		(layer "In2.Cu")
		(net "M_C_CPU1_SB_DQS_DN<3>")
	)
	(segment
		(start 71.0946 -305.90109)
		(end 71.468234 -305.527456)
		(width 0.16002)
		(layer "In2.Cu")
		(net "M_C_CPU1_SB_DQS_DN<3>")
	)
	(segment
		(start 68.429886 -307.179472)
		(end 68.62572 -306.983638)
		(width 0.16002)
		(layer "In2.Cu")
		(net "M_C_CPU1_SB_DQS_DN<3>")
	)
	(segment
		(start 85.941154 -290.766246)
		(end 85.949536 -290.771072)
		(width 0.09525)
		(layer "In2.Cu")
		(net "M_C_CPU1_SB_DQS_DN<3>")
	)
	(segment
		(start 70.094602 -306.373784)
		(end 69.803518 -306.0827)
		(width 0.16002)
		(layer "In2.Cu")
		(net "M_C_CPU1_SB_DQS_DN<3>")
	)
	(segment
		(start 71.17715 -304.709068)
		(end 71.17715 -304.432208)
		(width 0.16002)
		(layer "In2.Cu")
		(net "M_C_CPU1_SB_DQS_DN<3>")
	)
	(segment
		(start 71.17715 -304.432208)
		(end 71.523352 -304.086006)
		(width 0.16002)
		(layer "In2.Cu")
		(net "M_C_CPU1_SB_DQS_DN<3>")
	)
	(segment
		(start 61.771276 -313.323986)
		(end 62.144148 -312.951114)
		(width 0.16002)
		(layer "In2.Cu")
		(net "M_C_CPU1_SB_DQS_DN<3>")
	)
	(segment
		(start 68.429886 -307.456332)
		(end 68.429886 -307.179472)
		(width 0.16002)
		(layer "In2.Cu")
		(net "M_C_CPU1_SB_DQS_DN<3>")
	)
	(segment
		(start 45.776134 -313.36234)
		(end 48.55337 -313.36234)
		(width 0.16002)
		(layer "In2.Cu")
		(net "M_C_CPU1_SB_DQS_DN<3>")
	)
	(segment
		(start 71.468234 -305.000152)
		(end 71.17715 -304.709068)
		(width 0.16002)
		(layer "In2.Cu")
		(net "M_C_CPU1_SB_DQS_DN<3>")
	)
	(segment
		(start 49.56937 -313.6773)
		(end 50.42281 -312.82386)
		(width 0.16002)
		(layer "In2.Cu")
		(net "M_C_CPU1_SB_DQS_DN<3>")
	)
	(segment
		(start 69.803518 -305.80584)
		(end 69.999352 -305.610006)
		(width 0.16002)
		(layer "In2.Cu")
		(net "M_C_CPU1_SB_DQS_DN<3>")
	)
	(segment
		(start 69.999352 -305.610006)
		(end 70.276212 -305.610006)
		(width 0.16002)
		(layer "In2.Cu")
		(net "M_C_CPU1_SB_DQS_DN<3>")
	)
	(segment
		(start 65.878456 -309.730902)
		(end 66.155316 -309.730902)
		(width 0.16002)
		(layer "In2.Cu")
		(net "M_C_CPU1_SB_DQS_DN<3>")
	)
	(segment
		(start 79.574644 -291.111178)
		(end 79.855314 -290.830508)
		(width 0.09525)
		(layer "In2.Cu")
		(net "M_C_CPU1_SB_DQS_DN<3>")
	)
	(segment
		(start 61.244226 -313.323986)
		(end 61.771276 -313.323986)
		(width 0.16002)
		(layer "In2.Cu")
		(net "M_C_CPU1_SB_DQS_DN<3>")
	)
	(segment
		(start 82.752438 -290.771072)
		(end 82.76082 -290.766246)
		(width 0.09525)
		(layer "In2.Cu")
		(net "M_C_CPU1_SB_DQS_DN<3>")
	)
	(segment
		(start 71.523352 -304.086006)
		(end 72.894952 -304.086006)
		(width 0.16002)
		(layer "In2.Cu")
		(net "M_C_CPU1_SB_DQS_DN<3>")
	)
	(segment
		(start 71.468234 -305.527456)
		(end 71.468234 -305.000152)
		(width 0.16002)
		(layer "In2.Cu")
		(net "M_C_CPU1_SB_DQS_DN<3>")
	)
	(segment
		(start 63.062358 -312.547)
		(end 65.878456 -309.730902)
		(width 0.16002)
		(layer "In2.Cu")
		(net "M_C_CPU1_SB_DQS_DN<3>")
	)
	(segment
		(start 68.90258 -306.983638)
		(end 69.193664 -307.274722)
		(width 0.16002)
		(layer "In2.Cu")
		(net "M_C_CPU1_SB_DQS_DN<3>")
	)
	(segment
		(start 76.65974 -295.319958)
		(end 76.65974 -295.296336)
		(width 0.09525)
		(layer "In2.Cu")
		(net "M_C_CPU1_SB_DQS_DN<3>")
	)
	(segment
		(start 86.881208 -290.766246)
		(end 86.88959 -290.771072)
		(width 0.09525)
		(layer "In2.Cu")
		(net "M_C_CPU1_SB_DQS_DN<3>")
	)
	(segment
		(start 92.15247 -290.771072)
		(end 92.160852 -290.766246)
		(width 0.09525)
		(layer "In2.Cu")
		(net "M_C_CPU1_SB_DQS_DN<3>")
	)
	(segment
		(start 48.86833 -313.6773)
		(end 49.56937 -313.6773)
		(width 0.16002)
		(layer "In2.Cu")
		(net "M_C_CPU1_SB_DQS_DN<3>")
	)
	(segment
		(start 69.803518 -306.0827)
		(end 69.803518 -305.80584)
		(width 0.16002)
		(layer "In2.Cu")
		(net "M_C_CPU1_SB_DQS_DN<3>")
	)
	(segment
		(start 67.056254 -308.829964)
		(end 67.056254 -308.553104)
		(width 0.16002)
		(layer "In2.Cu")
		(net "M_C_CPU1_SB_DQS_DN<3>")
	)
	(segment
		(start 58.61431 -312.547)
		(end 60.67552 -312.547)
		(width 0.16002)
		(layer "In2.Cu")
		(net "M_C_CPU1_SB_DQS_DN<3>")
	)
	(segment
		(start 50.82921 -312.82386)
		(end 51.140614 -312.512456)
		(width 0.16002)
		(layer "In2.Cu")
		(net "M_C_CPU1_SB_DQS_DN<3>")
	)
	(segment
		(start 56.10987 -313.40552)
		(end 56.20385 -313.499246)
		(width 0.16002)
		(layer "In2.Cu")
		(net "M_C_CPU1_SB_DQS_DN<3>")
	)
	(segment
		(start 70.567296 -305.90109)
		(end 71.0946 -305.90109)
		(width 0.16002)
		(layer "In2.Cu")
		(net "M_C_CPU1_SB_DQS_DN<3>")
	)
	(segment
		(start 45.627036 -313.511438)
		(end 45.776134 -313.36234)
		(width 0.16002)
		(layer "In2.Cu")
		(net "M_C_CPU1_SB_DQS_DN<3>")
	)
	(segment
		(start 78.31201 -291.718746)
		(end 78.456282 -291.574474)
		(width 0.09525)
		(layer "In2.Cu")
		(net "M_C_CPU1_SB_DQS_DN<3>")
	)
	(segment
		(start 83.692492 -290.771072)
		(end 83.700874 -290.766246)
		(width 0.09525)
		(layer "In2.Cu")
		(net "M_C_CPU1_SB_DQS_DN<3>")
	)
	(segment
		(start 90.64117 -290.766246)
		(end 90.649552 -290.771072)
		(width 0.09525)
		(layer "In2.Cu")
		(net "M_C_CPU1_SB_DQS_DN<3>")
	)
	(segment
		(start 69.193664 -307.274722)
		(end 69.720968 -307.274722)
		(width 0.16002)
		(layer "In2.Cu")
		(net "M_C_CPU1_SB_DQS_DN<3>")
	)
	(segment
		(start 76.65974 -300.321218)
		(end 76.65974 -295.319958)
		(width 0.16002)
		(layer "In2.Cu")
		(net "M_C_CPU1_SB_DQS_DN<3>")
	)
	(segment
		(start 94.37497 -290.830762)
		(end 94.221046 -291.096192)
		(width 0.09525)
		(layer "In2.Cu")
		(net "M_C_CPU1_SB_DQS_DN<3>")
	)
	(segment
		(start 62.339982 -312.547)
		(end 63.062358 -312.547)
		(width 0.16002)
		(layer "In2.Cu")
		(net "M_C_CPU1_SB_DQS_DN<3>")
	)
	(segment
		(start 67.252088 -308.35727)
		(end 67.528948 -308.35727)
		(width 0.16002)
		(layer "In2.Cu")
		(net "M_C_CPU1_SB_DQS_DN<3>")
	)
	(segment
		(start 67.347338 -309.648352)
		(end 67.347338 -309.121048)
		(width 0.16002)
		(layer "In2.Cu")
		(net "M_C_CPU1_SB_DQS_DN<3>")
	)
	(segment
		(start 53.007006 -312.512456)
		(end 53.90007 -313.40552)
		(width 0.16002)
		(layer "In2.Cu")
		(net "M_C_CPU1_SB_DQS_DN<3>")
	)
	(segment
		(start 67.528948 -308.35727)
		(end 67.820032 -308.648354)
		(width 0.16002)
		(layer "In2.Cu")
		(net "M_C_CPU1_SB_DQS_DN<3>")
	)
	(arc
		(start 87.829644 -290.771072)
		(mid 88.111076 -290.846827)
		(end 88.392508 -290.771072)
		(width 0.09525)
		(layer "In2.Cu")
		(net "M_C_CPU1_SB_DQS_DN<3>")
	)
	(arc
		(start 91.212416 -290.771072)
		(mid 91.396191 -290.7203)
		(end 91.581224 -290.766246)
		(width 0.09525)
		(layer "In2.Cu")
		(net "M_C_CPU1_SB_DQS_DN<3>")
	)
	(arc
		(start 93.469714 -290.771072)
		(mid 93.751146 -290.846827)
		(end 94.032578 -290.771072)
		(width 0.09525)
		(layer "In2.Cu")
		(net "M_C_CPU1_SB_DQS_DN<3>")
	)
	(arc
		(start 84.069682 -290.771072)
		(mid 84.351114 -290.846827)
		(end 84.632546 -290.771072)
		(width 0.09525)
		(layer "In2.Cu")
		(net "M_C_CPU1_SB_DQS_DN<3>")
	)
	(arc
		(start 80.872584 -290.771072)
		(mid 81.061052 -290.720395)
		(end 81.24952 -290.771072)
		(width 0.09525)
		(layer "In2.Cu")
		(net "M_C_CPU1_SB_DQS_DN<3>")
	)
	(arc
		(start 92.160852 -290.766246)
		(mid 92.345884 -290.720332)
		(end 92.52966 -290.771072)
		(width 0.09525)
		(layer "In2.Cu")
		(net "M_C_CPU1_SB_DQS_DN<3>")
	)
	(arc
		(start 93.100906 -290.766246)
		(mid 93.285938 -290.720332)
		(end 93.469714 -290.771072)
		(width 0.09525)
		(layer "In2.Cu")
		(net "M_C_CPU1_SB_DQS_DN<3>")
	)
	(arc
		(start 90.272362 -290.771072)
		(mid 90.456137 -290.7203)
		(end 90.64117 -290.766246)
		(width 0.09525)
		(layer "In2.Cu")
		(net "M_C_CPU1_SB_DQS_DN<3>")
	)
	(arc
		(start 83.129628 -290.771072)
		(mid 83.41106 -290.846827)
		(end 83.692492 -290.771072)
		(width 0.09525)
		(layer "In2.Cu")
		(net "M_C_CPU1_SB_DQS_DN<3>")
	)
	(arc
		(start 89.709498 -290.771072)
		(mid 89.99093 -290.846827)
		(end 90.272362 -290.771072)
		(width 0.09525)
		(layer "In2.Cu")
		(net "M_C_CPU1_SB_DQS_DN<3>")
	)
	(arc
		(start 83.700874 -290.766246)
		(mid 83.885906 -290.720332)
		(end 84.069682 -290.771072)
		(width 0.09525)
		(layer "In2.Cu")
		(net "M_C_CPU1_SB_DQS_DN<3>")
	)
	(arc
		(start 85.572346 -290.771072)
		(mid 85.756121 -290.7203)
		(end 85.941154 -290.766246)
		(width 0.09525)
		(layer "In2.Cu")
		(net "M_C_CPU1_SB_DQS_DN<3>")
	)
	(arc
		(start 91.589606 -290.771072)
		(mid 91.871038 -290.846827)
		(end 92.15247 -290.771072)
		(width 0.09525)
		(layer "In2.Cu")
		(net "M_C_CPU1_SB_DQS_DN<3>")
	)
	(arc
		(start 89.332562 -290.771072)
		(mid 89.52103 -290.720395)
		(end 89.709498 -290.771072)
		(width 0.09525)
		(layer "In2.Cu")
		(net "M_C_CPU1_SB_DQS_DN<3>")
	)
	(arc
		(start 87.460836 -290.766246)
		(mid 87.645868 -290.720332)
		(end 87.829644 -290.771072)
		(width 0.09525)
		(layer "In2.Cu")
		(net "M_C_CPU1_SB_DQS_DN<3>")
	)
	(arc
		(start 88.769698 -290.771072)
		(mid 89.05113 -290.846827)
		(end 89.332562 -290.771072)
		(width 0.09525)
		(layer "In2.Cu")
		(net "M_C_CPU1_SB_DQS_DN<3>")
	)
	(arc
		(start 82.189574 -290.771072)
		(mid 82.471006 -290.846827)
		(end 82.752438 -290.771072)
		(width 0.09525)
		(layer "In2.Cu")
		(net "M_C_CPU1_SB_DQS_DN<3>")
	)
	(arc
		(start 79.855314 -290.830508)
		(mid 79.892118 -290.798275)
		(end 79.932784 -290.771072)
		(width 0.09525)
		(layer "In2.Cu")
		(net "M_C_CPU1_SB_DQS_DN<3>")
	)
	(arc
		(start 88.40089 -290.766246)
		(mid 88.585922 -290.720332)
		(end 88.769698 -290.771072)
		(width 0.09525)
		(layer "In2.Cu")
		(net "M_C_CPU1_SB_DQS_DN<3>")
	)
	(arc
		(start 81.24952 -290.771072)
		(mid 81.530952 -290.846827)
		(end 81.812384 -290.771072)
		(width 0.09525)
		(layer "In2.Cu")
		(net "M_C_CPU1_SB_DQS_DN<3>")
	)
	(arc
		(start 86.5124 -290.771072)
		(mid 86.696175 -290.7203)
		(end 86.881208 -290.766246)
		(width 0.09525)
		(layer "In2.Cu")
		(net "M_C_CPU1_SB_DQS_DN<3>")
	)
	(arc
		(start 79.957168 -290.757864)
		(mid 80.135087 -290.720549)
		(end 80.30972 -290.771072)
		(width 0.09525)
		(layer "In2.Cu")
		(net "M_C_CPU1_SB_DQS_DN<3>")
	)
	(arc
		(start 94.032578 -290.771072)
		(mid 94.189205 -290.721886)
		(end 94.351856 -290.744148)
		(width 0.09525)
		(layer "In2.Cu")
		(net "M_C_CPU1_SB_DQS_DN<3>")
	)
	(arc
		(start 84.632546 -290.771072)
		(mid 84.821014 -290.720395)
		(end 85.009482 -290.771072)
		(width 0.09525)
		(layer "In2.Cu")
		(net "M_C_CPU1_SB_DQS_DN<3>")
	)
	(arc
		(start 85.949536 -290.771072)
		(mid 86.230968 -290.846827)
		(end 86.5124 -290.771072)
		(width 0.09525)
		(layer "In2.Cu")
		(net "M_C_CPU1_SB_DQS_DN<3>")
	)
	(arc
		(start 85.009482 -290.771072)
		(mid 85.290914 -290.846827)
		(end 85.572346 -290.771072)
		(width 0.09525)
		(layer "In2.Cu")
		(net "M_C_CPU1_SB_DQS_DN<3>")
	)
	(arc
		(start 86.88959 -290.771072)
		(mid 87.171022 -290.846827)
		(end 87.452454 -290.771072)
		(width 0.09525)
		(layer "In2.Cu")
		(net "M_C_CPU1_SB_DQS_DN<3>")
	)
	(arc
		(start 90.649552 -290.771072)
		(mid 90.930984 -290.846827)
		(end 91.212416 -290.771072)
		(width 0.09525)
		(layer "In2.Cu")
		(net "M_C_CPU1_SB_DQS_DN<3>")
	)
	(arc
		(start 92.52966 -290.771072)
		(mid 92.811092 -290.846827)
		(end 93.092524 -290.771072)
		(width 0.09525)
		(layer "In2.Cu")
		(net "M_C_CPU1_SB_DQS_DN<3>")
	)
	(arc
		(start 82.76082 -290.766246)
		(mid 82.945852 -290.720332)
		(end 83.129628 -290.771072)
		(width 0.09525)
		(layer "In2.Cu")
		(net "M_C_CPU1_SB_DQS_DN<3>")
	)
	(arc
		(start 80.30972 -290.771072)
		(mid 80.591152 -290.846827)
		(end 80.872584 -290.771072)
		(width 0.09525)
		(layer "In2.Cu")
		(net "M_C_CPU1_SB_DQS_DN<3>")
	)
	(arc
		(start 81.812384 -290.771072)
		(mid 81.996159 -290.7203)
		(end 82.181192 -290.766246)
		(width 0.09525)
		(layer "In2.Cu")
		(net "M_C_CPU1_SB_DQS_DN<3>")
	)
	(segment
		(start 94.687898 -285.970472)
		(end 94.221046 -286.23641)
		(width 0.12954)
		(layer "F.Cu")
		(net "M_C_CPU1_SB_DQS_DN<2>")
	)
	(segment
		(start 63.372238 -302.258222)
		(end 63.142114 -302.028098)
		(width 0.16002)
		(layer "In2.Cu")
		(net "M_C_CPU1_SB_DQS_DN<2>")
	)
	(segment
		(start 66.209672 -298.9326)
		(end 66.486532 -298.9326)
		(width 0.16002)
		(layer "In2.Cu")
		(net "M_C_CPU1_SB_DQS_DN<2>")
	)
	(segment
		(start 76.189078 -286.715454)
		(end 76.248006 -286.656526)
		(width 0.09525)
		(layer "In2.Cu")
		(net "M_C_CPU1_SB_DQS_DN<2>")
	)
	(segment
		(start 63.844932 -301.785528)
		(end 64.371728 -301.785782)
		(width 0.16002)
		(layer "In2.Cu")
		(net "M_C_CPU1_SB_DQS_DN<2>")
	)
	(segment
		(start 44.61383 -304.161444)
		(end 45.57522 -304.161444)
		(width 0.16002)
		(layer "In2.Cu")
		(net "M_C_CPU1_SB_DQS_DN<2>")
	)
	(segment
		(start 92.15247 -285.91129)
		(end 92.160852 -285.906464)
		(width 0.09525)
		(layer "In2.Cu")
		(net "M_C_CPU1_SB_DQS_DN<2>")
	)
	(segment
		(start 65.74536 -300.41215)
		(end 66.119248 -300.038008)
		(width 0.16002)
		(layer "In2.Cu")
		(net "M_C_CPU1_SB_DQS_DN<2>")
	)
	(segment
		(start 82.752438 -285.91129)
		(end 82.76082 -285.906464)
		(width 0.09525)
		(layer "In2.Cu")
		(net "M_C_CPU1_SB_DQS_DN<2>")
	)
	(segment
		(start 65.218564 -300.411896)
		(end 65.74536 -300.41215)
		(width 0.16002)
		(layer "In2.Cu")
		(net "M_C_CPU1_SB_DQS_DN<2>")
	)
	(segment
		(start 66.119248 -300.038008)
		(end 66.119248 -299.510958)
		(width 0.16002)
		(layer "In2.Cu")
		(net "M_C_CPU1_SB_DQS_DN<2>")
	)
	(segment
		(start 46.963838 -304.012346)
		(end 48.55337 -304.012346)
		(width 0.16002)
		(layer "In2.Cu")
		(net "M_C_CPU1_SB_DQS_DN<2>")
	)
	(segment
		(start 62.120272 -303.197006)
		(end 62.960504 -303.197006)
		(width 0.16002)
		(layer "In2.Cu")
		(net "M_C_CPU1_SB_DQS_DN<2>")
	)
	(segment
		(start 63.337948 -301.555404)
		(end 63.614808 -301.555404)
		(width 0.16002)
		(layer "In2.Cu")
		(net "M_C_CPU1_SB_DQS_DN<2>")
	)
	(segment
		(start 70.901306 -295.256204)
		(end 70.901306 -291.923978)
		(width 0.16002)
		(layer "In2.Cu")
		(net "M_C_CPU1_SB_DQS_DN<2>")
	)
	(segment
		(start 56.98871 -304.345086)
		(end 57.78627 -303.547526)
		(width 0.16002)
		(layer "In2.Cu")
		(net "M_C_CPU1_SB_DQS_DN<2>")
	)
	(segment
		(start 78.003654 -285.987744)
		(end 78.711298 -285.987744)
		(width 0.09525)
		(layer "In2.Cu")
		(net "M_C_CPU1_SB_DQS_DN<2>")
	)
	(segment
		(start 44.340018 -304.435256)
		(end 44.61383 -304.161444)
		(width 0.16002)
		(layer "In2.Cu")
		(net "M_C_CPU1_SB_DQS_DN<2>")
	)
	(segment
		(start 48.86833 -304.327306)
		(end 49.56937 -304.327306)
		(width 0.16002)
		(layer "In2.Cu")
		(net "M_C_CPU1_SB_DQS_DN<2>")
	)
	(segment
		(start 66.486532 -298.9326)
		(end 66.592196 -299.038264)
		(width 0.16002)
		(layer "In2.Cu")
		(net "M_C_CPU1_SB_DQS_DN<2>")
	)
	(segment
		(start 46.17212 -304.278284)
		(end 46.28896 -304.161444)
		(width 0.16002)
		(layer "In2.Cu")
		(net "M_C_CPU1_SB_DQS_DN<2>")
	)
	(segment
		(start 61.924438 -303.862994)
		(end 61.924438 -303.39284)
		(width 0.16002)
		(layer "In2.Cu")
		(net "M_C_CPU1_SB_DQS_DN<2>")
	)
	(segment
		(start 85.941154 -285.906464)
		(end 85.949536 -285.91129)
		(width 0.09525)
		(layer "In2.Cu")
		(net "M_C_CPU1_SB_DQS_DN<2>")
	)
	(segment
		(start 56.10987 -304.055526)
		(end 56.39943 -304.345086)
		(width 0.16002)
		(layer "In2.Cu")
		(net "M_C_CPU1_SB_DQS_DN<2>")
	)
	(segment
		(start 94.37497 -285.97098)
		(end 94.221046 -286.23641)
		(width 0.09525)
		(layer "In2.Cu")
		(net "M_C_CPU1_SB_DQS_DN<2>")
	)
	(segment
		(start 67.118992 -299.038264)
		(end 70.812914 -295.344342)
		(width 0.16002)
		(layer "In2.Cu")
		(net "M_C_CPU1_SB_DQS_DN<2>")
	)
	(segment
		(start 87.452454 -285.91129)
		(end 87.460836 -285.906464)
		(width 0.09525)
		(layer "In2.Cu")
		(net "M_C_CPU1_SB_DQS_DN<2>")
	)
	(segment
		(start 66.119248 -299.510958)
		(end 66.013838 -299.405548)
		(width 0.16002)
		(layer "In2.Cu")
		(net "M_C_CPU1_SB_DQS_DN<2>")
	)
	(segment
		(start 57.78627 -303.547526)
		(end 58.26379 -303.547526)
		(width 0.16002)
		(layer "In2.Cu")
		(net "M_C_CPU1_SB_DQS_DN<2>")
	)
	(segment
		(start 58.26379 -303.547526)
		(end 58.61431 -303.197006)
		(width 0.16002)
		(layer "In2.Cu")
		(net "M_C_CPU1_SB_DQS_DN<2>")
	)
	(segment
		(start 66.592196 -299.038264)
		(end 67.118992 -299.038264)
		(width 0.16002)
		(layer "In2.Cu")
		(net "M_C_CPU1_SB_DQS_DN<2>")
	)
	(segment
		(start 50.42281 -303.473866)
		(end 50.82921 -303.473866)
		(width 0.16002)
		(layer "In2.Cu")
		(net "M_C_CPU1_SB_DQS_DN<2>")
	)
	(segment
		(start 58.61431 -303.197006)
		(end 60.45581 -303.197006)
		(width 0.16002)
		(layer "In2.Cu")
		(net "M_C_CPU1_SB_DQS_DN<2>")
	)
	(segment
		(start 46.81474 -304.161444)
		(end 46.963838 -304.012346)
		(width 0.16002)
		(layer "In2.Cu")
		(net "M_C_CPU1_SB_DQS_DN<2>")
	)
	(segment
		(start 79.349346 -285.897828)
		(end 79.372714 -285.91129)
		(width 0.09525)
		(layer "In2.Cu")
		(net "M_C_CPU1_SB_DQS_DN<2>")
	)
	(segment
		(start 64.71158 -300.181772)
		(end 64.98844 -300.181772)
		(width 0.16002)
		(layer "In2.Cu")
		(net "M_C_CPU1_SB_DQS_DN<2>")
	)
	(segment
		(start 88.392508 -285.91129)
		(end 88.40089 -285.906464)
		(width 0.09525)
		(layer "In2.Cu")
		(net "M_C_CPU1_SB_DQS_DN<2>")
	)
	(segment
		(start 94.351856 -285.884366)
		(end 94.37497 -285.97098)
		(width 0.09525)
		(layer "In2.Cu")
		(net "M_C_CPU1_SB_DQS_DN<2>")
	)
	(segment
		(start 45.69206 -304.278284)
		(end 46.17212 -304.278284)
		(width 0.16002)
		(layer "In2.Cu")
		(net "M_C_CPU1_SB_DQS_DN<2>")
	)
	(segment
		(start 66.013838 -299.128434)
		(end 66.209672 -298.9326)
		(width 0.16002)
		(layer "In2.Cu")
		(net "M_C_CPU1_SB_DQS_DN<2>")
	)
	(segment
		(start 63.142114 -301.751238)
		(end 63.337948 -301.555404)
		(width 0.16002)
		(layer "In2.Cu")
		(net "M_C_CPU1_SB_DQS_DN<2>")
	)
	(segment
		(start 49.56937 -304.327306)
		(end 50.42281 -303.473866)
		(width 0.16002)
		(layer "In2.Cu")
		(net "M_C_CPU1_SB_DQS_DN<2>")
	)
	(segment
		(start 53.43017 -304.408586)
		(end 54.06263 -304.408586)
		(width 0.16002)
		(layer "In2.Cu")
		(net "M_C_CPU1_SB_DQS_DN<2>")
	)
	(segment
		(start 70.901306 -291.923978)
		(end 76.10983 -286.715454)
		(width 0.16002)
		(layer "In2.Cu")
		(net "M_C_CPU1_SB_DQS_DN<2>")
	)
	(segment
		(start 53.08727 -303.375822)
		(end 53.08727 -304.065686)
		(width 0.16002)
		(layer "In2.Cu")
		(net "M_C_CPU1_SB_DQS_DN<2>")
	)
	(segment
		(start 77.505052 -286.413702)
		(end 77.879448 -286.039306)
		(width 0.09525)
		(layer "In2.Cu")
		(net "M_C_CPU1_SB_DQS_DN<2>")
	)
	(segment
		(start 54.06263 -304.408586)
		(end 54.41569 -304.055526)
		(width 0.16002)
		(layer "In2.Cu")
		(net "M_C_CPU1_SB_DQS_DN<2>")
	)
	(segment
		(start 64.98844 -300.181772)
		(end 65.218564 -300.411896)
		(width 0.16002)
		(layer "In2.Cu")
		(net "M_C_CPU1_SB_DQS_DN<2>")
	)
	(segment
		(start 91.581224 -285.906464)
		(end 91.589606 -285.91129)
		(width 0.09525)
		(layer "In2.Cu")
		(net "M_C_CPU1_SB_DQS_DN<2>")
	)
	(segment
		(start 60.45581 -303.197006)
		(end 60.651644 -303.39284)
		(width 0.16002)
		(layer "In2.Cu")
		(net "M_C_CPU1_SB_DQS_DN<2>")
	)
	(segment
		(start 61.024516 -304.235866)
		(end 61.551566 -304.235866)
		(width 0.16002)
		(layer "In2.Cu")
		(net "M_C_CPU1_SB_DQS_DN<2>")
	)
	(segment
		(start 64.371728 -301.785782)
		(end 64.745616 -301.411894)
		(width 0.16002)
		(layer "In2.Cu")
		(net "M_C_CPU1_SB_DQS_DN<2>")
	)
	(segment
		(start 82.181192 -285.906464)
		(end 82.189574 -285.91129)
		(width 0.09525)
		(layer "In2.Cu")
		(net "M_C_CPU1_SB_DQS_DN<2>")
	)
	(segment
		(start 60.651644 -303.862994)
		(end 61.024516 -304.235866)
		(width 0.16002)
		(layer "In2.Cu")
		(net "M_C_CPU1_SB_DQS_DN<2>")
	)
	(segment
		(start 54.41569 -304.055526)
		(end 56.10987 -304.055526)
		(width 0.16002)
		(layer "In2.Cu")
		(net "M_C_CPU1_SB_DQS_DN<2>")
	)
	(segment
		(start 64.515746 -300.377606)
		(end 64.71158 -300.181772)
		(width 0.16002)
		(layer "In2.Cu")
		(net "M_C_CPU1_SB_DQS_DN<2>")
	)
	(segment
		(start 64.745616 -301.411894)
		(end 64.74587 -300.88459)
		(width 0.16002)
		(layer "In2.Cu")
		(net "M_C_CPU1_SB_DQS_DN<2>")
	)
	(segment
		(start 70.812914 -295.344342)
		(end 70.813168 -295.344342)
		(width 0.16002)
		(layer "In2.Cu")
		(net "M_C_CPU1_SB_DQS_DN<2>")
	)
	(segment
		(start 60.651644 -303.39284)
		(end 60.651644 -303.862994)
		(width 0.16002)
		(layer "In2.Cu")
		(net "M_C_CPU1_SB_DQS_DN<2>")
	)
	(segment
		(start 90.64117 -285.906464)
		(end 90.649552 -285.91129)
		(width 0.09525)
		(layer "In2.Cu")
		(net "M_C_CPU1_SB_DQS_DN<2>")
	)
	(segment
		(start 86.881208 -285.906464)
		(end 86.88959 -285.91129)
		(width 0.09525)
		(layer "In2.Cu")
		(net "M_C_CPU1_SB_DQS_DN<2>")
	)
	(segment
		(start 63.142114 -302.028098)
		(end 63.142114 -301.751238)
		(width 0.16002)
		(layer "In2.Cu")
		(net "M_C_CPU1_SB_DQS_DN<2>")
	)
	(segment
		(start 45.57522 -304.161444)
		(end 45.69206 -304.278284)
		(width 0.16002)
		(layer "In2.Cu")
		(net "M_C_CPU1_SB_DQS_DN<2>")
	)
	(segment
		(start 83.692492 -285.91129)
		(end 83.700874 -285.906464)
		(width 0.09525)
		(layer "In2.Cu")
		(net "M_C_CPU1_SB_DQS_DN<2>")
	)
	(segment
		(start 48.55337 -304.012346)
		(end 48.86833 -304.327306)
		(width 0.16002)
		(layer "In2.Cu")
		(net "M_C_CPU1_SB_DQS_DN<2>")
	)
	(segment
		(start 79.9338 -285.911544)
		(end 79.957168 -285.898082)
		(width 0.09525)
		(layer "In2.Cu")
		(net "M_C_CPU1_SB_DQS_DN<2>")
	)
	(segment
		(start 52.87391 -303.162462)
		(end 53.08727 -303.375822)
		(width 0.16002)
		(layer "In2.Cu")
		(net "M_C_CPU1_SB_DQS_DN<2>")
	)
	(segment
		(start 76.248006 -286.656526)
		(end 76.918566 -286.656526)
		(width 0.09525)
		(layer "In2.Cu")
		(net "M_C_CPU1_SB_DQS_DN<2>")
	)
	(segment
		(start 63.614808 -301.555404)
		(end 63.844932 -301.785528)
		(width 0.16002)
		(layer "In2.Cu")
		(net "M_C_CPU1_SB_DQS_DN<2>")
	)
	(segment
		(start 76.165456 -286.715454)
		(end 76.189078 -286.715454)
		(width 0.09525)
		(layer "In2.Cu")
		(net "M_C_CPU1_SB_DQS_DN<2>")
	)
	(segment
		(start 64.515746 -300.654466)
		(end 64.515746 -300.377606)
		(width 0.16002)
		(layer "In2.Cu")
		(net "M_C_CPU1_SB_DQS_DN<2>")
	)
	(segment
		(start 50.82921 -303.473866)
		(end 51.140614 -303.162462)
		(width 0.16002)
		(layer "In2.Cu")
		(net "M_C_CPU1_SB_DQS_DN<2>")
	)
	(segment
		(start 64.74587 -300.88459)
		(end 64.515746 -300.654466)
		(width 0.16002)
		(layer "In2.Cu")
		(net "M_C_CPU1_SB_DQS_DN<2>")
	)
	(segment
		(start 70.813168 -295.344342)
		(end 70.901306 -295.256204)
		(width 0.16002)
		(layer "In2.Cu")
		(net "M_C_CPU1_SB_DQS_DN<2>")
	)
	(segment
		(start 56.39943 -304.345086)
		(end 56.98871 -304.345086)
		(width 0.16002)
		(layer "In2.Cu")
		(net "M_C_CPU1_SB_DQS_DN<2>")
	)
	(segment
		(start 61.551566 -304.235866)
		(end 61.924438 -303.862994)
		(width 0.16002)
		(layer "In2.Cu")
		(net "M_C_CPU1_SB_DQS_DN<2>")
	)
	(segment
		(start 93.092524 -285.91129)
		(end 93.100906 -285.906464)
		(width 0.09525)
		(layer "In2.Cu")
		(net "M_C_CPU1_SB_DQS_DN<2>")
	)
	(segment
		(start 66.013838 -299.405548)
		(end 66.013838 -299.128434)
		(width 0.16002)
		(layer "In2.Cu")
		(net "M_C_CPU1_SB_DQS_DN<2>")
	)
	(segment
		(start 76.10983 -286.715454)
		(end 76.165456 -286.715454)
		(width 0.16002)
		(layer "In2.Cu")
		(net "M_C_CPU1_SB_DQS_DN<2>")
	)
	(segment
		(start 53.08727 -304.065686)
		(end 53.43017 -304.408586)
		(width 0.16002)
		(layer "In2.Cu")
		(net "M_C_CPU1_SB_DQS_DN<2>")
	)
	(segment
		(start 62.960504 -303.197006)
		(end 63.371984 -302.785526)
		(width 0.16002)
		(layer "In2.Cu")
		(net "M_C_CPU1_SB_DQS_DN<2>")
	)
	(segment
		(start 79.909924 -285.92526)
		(end 79.9338 -285.911544)
		(width 0.09525)
		(layer "In2.Cu")
		(net "M_C_CPU1_SB_DQS_DN<2>")
	)
	(segment
		(start 63.371984 -302.785526)
		(end 63.372238 -302.258222)
		(width 0.16002)
		(layer "In2.Cu")
		(net "M_C_CPU1_SB_DQS_DN<2>")
	)
	(segment
		(start 46.28896 -304.161444)
		(end 46.81474 -304.161444)
		(width 0.16002)
		(layer "In2.Cu")
		(net "M_C_CPU1_SB_DQS_DN<2>")
	)
	(segment
		(start 61.924438 -303.39284)
		(end 62.120272 -303.197006)
		(width 0.16002)
		(layer "In2.Cu")
		(net "M_C_CPU1_SB_DQS_DN<2>")
	)
	(segment
		(start 51.140614 -303.162462)
		(end 52.87391 -303.162462)
		(width 0.16002)
		(layer "In2.Cu")
		(net "M_C_CPU1_SB_DQS_DN<2>")
	)
	(arc
		(start 81.24952 -285.91129)
		(mid 81.530952 -285.987045)
		(end 81.812384 -285.91129)
		(width 0.09525)
		(layer "In2.Cu")
		(net "M_C_CPU1_SB_DQS_DN<2>")
	)
	(arc
		(start 89.332562 -285.91129)
		(mid 89.52103 -285.860613)
		(end 89.709498 -285.91129)
		(width 0.09525)
		(layer "In2.Cu")
		(net "M_C_CPU1_SB_DQS_DN<2>")
	)
	(arc
		(start 88.769698 -285.91129)
		(mid 89.05113 -285.987045)
		(end 89.332562 -285.91129)
		(width 0.09525)
		(layer "In2.Cu")
		(net "M_C_CPU1_SB_DQS_DN<2>")
	)
	(arc
		(start 93.469714 -285.91129)
		(mid 93.751146 -285.987045)
		(end 94.032578 -285.91129)
		(width 0.09525)
		(layer "In2.Cu")
		(net "M_C_CPU1_SB_DQS_DN<2>")
	)
	(arc
		(start 77.879448 -286.039306)
		(mid 77.936419 -286.001146)
		(end 78.003654 -285.987744)
		(width 0.09525)
		(layer "In2.Cu")
		(net "M_C_CPU1_SB_DQS_DN<2>")
	)
	(arc
		(start 78.711298 -285.987744)
		(mid 78.857872 -285.968192)
		(end 78.994254 -285.911036)
		(width 0.09525)
		(layer "In2.Cu")
		(net "M_C_CPU1_SB_DQS_DN<2>")
	)
	(arc
		(start 85.572346 -285.91129)
		(mid 85.756121 -285.860518)
		(end 85.941154 -285.906464)
		(width 0.09525)
		(layer "In2.Cu")
		(net "M_C_CPU1_SB_DQS_DN<2>")
	)
	(arc
		(start 86.88959 -285.91129)
		(mid 87.171022 -285.987045)
		(end 87.452454 -285.91129)
		(width 0.09525)
		(layer "In2.Cu")
		(net "M_C_CPU1_SB_DQS_DN<2>")
	)
	(arc
		(start 79.957168 -285.898082)
		(mid 80.135087 -285.860767)
		(end 80.30972 -285.91129)
		(width 0.09525)
		(layer "In2.Cu")
		(net "M_C_CPU1_SB_DQS_DN<2>")
	)
	(arc
		(start 91.212416 -285.91129)
		(mid 91.396191 -285.860518)
		(end 91.581224 -285.906464)
		(width 0.09525)
		(layer "In2.Cu")
		(net "M_C_CPU1_SB_DQS_DN<2>")
	)
	(arc
		(start 89.709498 -285.91129)
		(mid 89.99093 -285.987045)
		(end 90.272362 -285.91129)
		(width 0.09525)
		(layer "In2.Cu")
		(net "M_C_CPU1_SB_DQS_DN<2>")
	)
	(arc
		(start 85.009482 -285.91129)
		(mid 85.290914 -285.987045)
		(end 85.572346 -285.91129)
		(width 0.09525)
		(layer "In2.Cu")
		(net "M_C_CPU1_SB_DQS_DN<2>")
	)
	(arc
		(start 80.872584 -285.91129)
		(mid 81.061052 -285.860613)
		(end 81.24952 -285.91129)
		(width 0.09525)
		(layer "In2.Cu")
		(net "M_C_CPU1_SB_DQS_DN<2>")
	)
	(arc
		(start 88.40089 -285.906464)
		(mid 88.585922 -285.86055)
		(end 88.769698 -285.91129)
		(width 0.09525)
		(layer "In2.Cu")
		(net "M_C_CPU1_SB_DQS_DN<2>")
	)
	(arc
		(start 83.129628 -285.91129)
		(mid 83.41106 -285.987045)
		(end 83.692492 -285.91129)
		(width 0.09525)
		(layer "In2.Cu")
		(net "M_C_CPU1_SB_DQS_DN<2>")
	)
	(arc
		(start 83.700874 -285.906464)
		(mid 83.885906 -285.86055)
		(end 84.069682 -285.91129)
		(width 0.09525)
		(layer "In2.Cu")
		(net "M_C_CPU1_SB_DQS_DN<2>")
	)
	(arc
		(start 92.160852 -285.906464)
		(mid 92.345884 -285.86055)
		(end 92.52966 -285.91129)
		(width 0.09525)
		(layer "In2.Cu")
		(net "M_C_CPU1_SB_DQS_DN<2>")
	)
	(arc
		(start 86.5124 -285.91129)
		(mid 86.696175 -285.860518)
		(end 86.881208 -285.906464)
		(width 0.09525)
		(layer "In2.Cu")
		(net "M_C_CPU1_SB_DQS_DN<2>")
	)
	(arc
		(start 76.918566 -286.656526)
		(mid 77.235983 -286.593482)
		(end 77.505052 -286.413702)
		(width 0.09525)
		(layer "In2.Cu")
		(net "M_C_CPU1_SB_DQS_DN<2>")
	)
	(arc
		(start 91.589606 -285.91129)
		(mid 91.871038 -285.987045)
		(end 92.15247 -285.91129)
		(width 0.09525)
		(layer "In2.Cu")
		(net "M_C_CPU1_SB_DQS_DN<2>")
	)
	(arc
		(start 80.30972 -285.91129)
		(mid 80.591152 -285.987045)
		(end 80.872584 -285.91129)
		(width 0.09525)
		(layer "In2.Cu")
		(net "M_C_CPU1_SB_DQS_DN<2>")
	)
	(arc
		(start 87.460836 -285.906464)
		(mid 87.645868 -285.86055)
		(end 87.829644 -285.91129)
		(width 0.09525)
		(layer "In2.Cu")
		(net "M_C_CPU1_SB_DQS_DN<2>")
	)
	(arc
		(start 82.76082 -285.906464)
		(mid 82.945852 -285.86055)
		(end 83.129628 -285.91129)
		(width 0.09525)
		(layer "In2.Cu")
		(net "M_C_CPU1_SB_DQS_DN<2>")
	)
	(arc
		(start 93.100906 -285.906464)
		(mid 93.285938 -285.86055)
		(end 93.469714 -285.91129)
		(width 0.09525)
		(layer "In2.Cu")
		(net "M_C_CPU1_SB_DQS_DN<2>")
	)
	(arc
		(start 82.189574 -285.91129)
		(mid 82.471006 -285.987045)
		(end 82.752438 -285.91129)
		(width 0.09525)
		(layer "In2.Cu")
		(net "M_C_CPU1_SB_DQS_DN<2>")
	)
	(arc
		(start 94.032578 -285.91129)
		(mid 94.189205 -285.862104)
		(end 94.351856 -285.884366)
		(width 0.09525)
		(layer "In2.Cu")
		(net "M_C_CPU1_SB_DQS_DN<2>")
	)
	(arc
		(start 92.52966 -285.91129)
		(mid 92.811092 -285.987045)
		(end 93.092524 -285.91129)
		(width 0.09525)
		(layer "In2.Cu")
		(net "M_C_CPU1_SB_DQS_DN<2>")
	)
	(arc
		(start 87.829644 -285.91129)
		(mid 88.111076 -285.987045)
		(end 88.392508 -285.91129)
		(width 0.09525)
		(layer "In2.Cu")
		(net "M_C_CPU1_SB_DQS_DN<2>")
	)
	(arc
		(start 85.949536 -285.91129)
		(mid 86.230968 -285.987045)
		(end 86.5124 -285.91129)
		(width 0.09525)
		(layer "In2.Cu")
		(net "M_C_CPU1_SB_DQS_DN<2>")
	)
	(arc
		(start 90.649552 -285.91129)
		(mid 90.930984 -285.987045)
		(end 91.212416 -285.91129)
		(width 0.09525)
		(layer "In2.Cu")
		(net "M_C_CPU1_SB_DQS_DN<2>")
	)
	(arc
		(start 84.069682 -285.91129)
		(mid 84.351114 -285.987045)
		(end 84.632546 -285.91129)
		(width 0.09525)
		(layer "In2.Cu")
		(net "M_C_CPU1_SB_DQS_DN<2>")
	)
	(arc
		(start 81.812384 -285.91129)
		(mid 81.996159 -285.860518)
		(end 82.181192 -285.906464)
		(width 0.09525)
		(layer "In2.Cu")
		(net "M_C_CPU1_SB_DQS_DN<2>")
	)
	(arc
		(start 78.994254 -285.911036)
		(mid 79.170155 -285.859891)
		(end 79.349346 -285.897828)
		(width 0.09525)
		(layer "In2.Cu")
		(net "M_C_CPU1_SB_DQS_DN<2>")
	)
	(arc
		(start 90.272362 -285.91129)
		(mid 90.456137 -285.860518)
		(end 90.64117 -285.906464)
		(width 0.09525)
		(layer "In2.Cu")
		(net "M_C_CPU1_SB_DQS_DN<2>")
	)
	(arc
		(start 84.632546 -285.91129)
		(mid 84.821014 -285.860613)
		(end 85.009482 -285.91129)
		(width 0.09525)
		(layer "In2.Cu")
		(net "M_C_CPU1_SB_DQS_DN<2>")
	)
	(arc
		(start 79.372714 -285.91129)
		(mid 79.63954 -285.986855)
		(end 79.909924 -285.92526)
		(width 0.09525)
		(layer "In2.Cu")
		(net "M_C_CPU1_SB_DQS_DN<2>")
	)
	(segment
		(start 94.687898 -281.110436)
		(end 94.221046 -281.376374)
		(width 0.12954)
		(layer "F.Cu")
		(net "M_C_CPU1_SB_DQS_DN<1>")
	)
	(segment
		(start 92.15247 -281.051254)
		(end 92.160852 -281.046428)
		(width 0.09525)
		(layer "In2.Cu")
		(net "M_C_CPU1_SB_DQS_DN<1>")
	)
	(segment
		(start 66.173858 -288.680144)
		(end 66.704972 -288.14903)
		(width 0.16002)
		(layer "In2.Cu")
		(net "M_C_CPU1_SB_DQS_DN<1>")
	)
	(segment
		(start 46.775878 -294.662352)
		(end 48.55337 -294.662352)
		(width 0.16002)
		(layer "In2.Cu")
		(net "M_C_CPU1_SB_DQS_DN<1>")
	)
	(segment
		(start 82.752438 -281.051254)
		(end 82.76082 -281.046428)
		(width 0.09525)
		(layer "In2.Cu")
		(net "M_C_CPU1_SB_DQS_DN<1>")
	)
	(segment
		(start 87.452454 -281.051254)
		(end 87.460836 -281.046428)
		(width 0.09525)
		(layer "In2.Cu")
		(net "M_C_CPU1_SB_DQS_DN<1>")
	)
	(segment
		(start 60.52693 -294.075866)
		(end 60.52693 -294.500808)
		(width 0.16002)
		(layer "In2.Cu")
		(net "M_C_CPU1_SB_DQS_DN<1>")
	)
	(segment
		(start 62.243208 -292.473126)
		(end 62.520068 -292.473126)
		(width 0.16002)
		(layer "In2.Cu")
		(net "M_C_CPU1_SB_DQS_DN<1>")
	)
	(segment
		(start 85.941154 -281.046428)
		(end 85.949536 -281.051254)
		(width 0.09525)
		(layer "In2.Cu")
		(net "M_C_CPU1_SB_DQS_DN<1>")
	)
	(segment
		(start 53.90007 -294.705532)
		(end 56.132222 -294.705532)
		(width 0.16002)
		(layer "In2.Cu")
		(net "M_C_CPU1_SB_DQS_DN<1>")
	)
	(segment
		(start 67.310254 -287.306512)
		(end 67.54749 -287.306512)
		(width 0.16002)
		(layer "In2.Cu")
		(net "M_C_CPU1_SB_DQS_DN<1>")
	)
	(segment
		(start 45.43298 -294.81145)
		(end 45.582078 -294.662352)
		(width 0.16002)
		(layer "In2.Cu")
		(net "M_C_CPU1_SB_DQS_DN<1>")
	)
	(segment
		(start 64.251586 -291.45738)
		(end 64.77889 -291.45738)
		(width 0.16002)
		(layer "In2.Cu")
		(net "M_C_CPU1_SB_DQS_DN<1>")
	)
	(segment
		(start 62.877954 -292.831012)
		(end 63.405258 -292.831012)
		(width 0.16002)
		(layer "In2.Cu")
		(net "M_C_CPU1_SB_DQS_DN<1>")
	)
	(segment
		(start 94.351856 -281.02433)
		(end 94.37497 -281.110944)
		(width 0.09525)
		(layer "In2.Cu")
		(net "M_C_CPU1_SB_DQS_DN<1>")
	)
	(segment
		(start 73.770998 -281.083004)
		(end 75.955906 -281.083004)
		(width 0.16002)
		(layer "In2.Cu")
		(net "M_C_CPU1_SB_DQS_DN<1>")
	)
	(segment
		(start 45.582078 -294.662352)
		(end 46.062138 -294.662352)
		(width 0.16002)
		(layer "In2.Cu")
		(net "M_C_CPU1_SB_DQS_DN<1>")
	)
	(segment
		(start 63.421006 -291.295328)
		(end 63.61684 -291.099494)
		(width 0.16002)
		(layer "In2.Cu")
		(net "M_C_CPU1_SB_DQS_DN<1>")
	)
	(segment
		(start 60.298076 -293.847012)
		(end 60.52693 -294.075866)
		(width 0.16002)
		(layer "In2.Cu")
		(net "M_C_CPU1_SB_DQS_DN<1>")
	)
	(segment
		(start 56.132222 -294.705532)
		(end 56.421782 -294.995092)
		(width 0.16002)
		(layer "In2.Cu")
		(net "M_C_CPU1_SB_DQS_DN<1>")
	)
	(segment
		(start 64.838326 -290.242244)
		(end 64.838326 -290.015676)
		(width 0.16002)
		(layer "In2.Cu")
		(net "M_C_CPU1_SB_DQS_DN<1>")
	)
	(segment
		(start 62.40526 -293.83863)
		(end 62.40526 -293.303706)
		(width 0.16002)
		(layer "In2.Cu")
		(net "M_C_CPU1_SB_DQS_DN<1>")
	)
	(segment
		(start 53.007006 -293.812468)
		(end 53.90007 -294.705532)
		(width 0.16002)
		(layer "In2.Cu")
		(net "M_C_CPU1_SB_DQS_DN<1>")
	)
	(segment
		(start 66.704972 -288.14903)
		(end 66.704972 -287.911794)
		(width 0.16002)
		(layer "In2.Cu")
		(net "M_C_CPU1_SB_DQS_DN<1>")
	)
	(segment
		(start 44.340018 -295.085262)
		(end 44.61383 -294.81145)
		(width 0.16002)
		(layer "In2.Cu")
		(net "M_C_CPU1_SB_DQS_DN<1>")
	)
	(segment
		(start 76.038456 -281.024076)
		(end 76.46035 -281.024076)
		(width 0.09525)
		(layer "In2.Cu")
		(net "M_C_CPU1_SB_DQS_DN<1>")
	)
	(segment
		(start 64.77889 -291.45738)
		(end 65.152524 -291.083746)
		(width 0.16002)
		(layer "In2.Cu")
		(net "M_C_CPU1_SB_DQS_DN<1>")
	)
	(segment
		(start 63.8937 -291.099494)
		(end 64.251586 -291.45738)
		(width 0.16002)
		(layer "In2.Cu")
		(net "M_C_CPU1_SB_DQS_DN<1>")
	)
	(segment
		(start 66.704972 -287.911794)
		(end 67.310254 -287.306512)
		(width 0.16002)
		(layer "In2.Cu")
		(net "M_C_CPU1_SB_DQS_DN<1>")
	)
	(segment
		(start 79.9338 -281.051508)
		(end 79.957168 -281.038046)
		(width 0.09525)
		(layer "In2.Cu")
		(net "M_C_CPU1_SB_DQS_DN<1>")
	)
	(segment
		(start 58.26379 -294.197532)
		(end 58.61431 -293.847012)
		(width 0.16002)
		(layer "In2.Cu")
		(net "M_C_CPU1_SB_DQS_DN<1>")
	)
	(segment
		(start 57.78627 -294.197532)
		(end 58.26379 -294.197532)
		(width 0.16002)
		(layer "In2.Cu")
		(net "M_C_CPU1_SB_DQS_DN<1>")
	)
	(segment
		(start 68.921122 -285.93288)
		(end 73.770998 -281.083004)
		(width 0.16002)
		(layer "In2.Cu")
		(net "M_C_CPU1_SB_DQS_DN<1>")
	)
	(segment
		(start 75.955906 -281.083004)
		(end 75.979528 -281.083004)
		(width 0.09525)
		(layer "In2.Cu")
		(net "M_C_CPU1_SB_DQS_DN<1>")
	)
	(segment
		(start 67.54749 -287.306512)
		(end 68.078604 -286.775398)
		(width 0.16002)
		(layer "In2.Cu")
		(net "M_C_CPU1_SB_DQS_DN<1>")
	)
	(segment
		(start 86.881208 -281.046428)
		(end 86.88959 -281.051254)
		(width 0.09525)
		(layer "In2.Cu")
		(net "M_C_CPU1_SB_DQS_DN<1>")
	)
	(segment
		(start 68.683886 -285.93288)
		(end 68.921122 -285.93288)
		(width 0.16002)
		(layer "In2.Cu")
		(net "M_C_CPU1_SB_DQS_DN<1>")
	)
	(segment
		(start 63.421006 -291.572188)
		(end 63.421006 -291.295328)
		(width 0.16002)
		(layer "In2.Cu")
		(net "M_C_CPU1_SB_DQS_DN<1>")
	)
	(segment
		(start 46.659038 -294.779192)
		(end 46.775878 -294.662352)
		(width 0.16002)
		(layer "In2.Cu")
		(net "M_C_CPU1_SB_DQS_DN<1>")
	)
	(segment
		(start 83.692492 -281.051254)
		(end 83.700874 -281.046428)
		(width 0.09525)
		(layer "In2.Cu")
		(net "M_C_CPU1_SB_DQS_DN<1>")
	)
	(segment
		(start 93.092524 -281.051254)
		(end 93.100906 -281.046428)
		(width 0.09525)
		(layer "In2.Cu")
		(net "M_C_CPU1_SB_DQS_DN<1>")
	)
	(segment
		(start 48.55337 -294.662352)
		(end 48.86833 -294.977312)
		(width 0.16002)
		(layer "In2.Cu")
		(net "M_C_CPU1_SB_DQS_DN<1>")
	)
	(segment
		(start 77.916024 -281.126184)
		(end 79.654146 -281.126184)
		(width 0.09525)
		(layer "In2.Cu")
		(net "M_C_CPU1_SB_DQS_DN<1>")
	)
	(segment
		(start 60.863988 -294.837866)
		(end 61.406024 -294.837866)
		(width 0.16002)
		(layer "In2.Cu")
		(net "M_C_CPU1_SB_DQS_DN<1>")
	)
	(segment
		(start 63.778892 -291.930074)
		(end 63.421006 -291.572188)
		(width 0.16002)
		(layer "In2.Cu")
		(net "M_C_CPU1_SB_DQS_DN<1>")
	)
	(segment
		(start 60.52693 -294.500808)
		(end 60.863988 -294.837866)
		(width 0.16002)
		(layer "In2.Cu")
		(net "M_C_CPU1_SB_DQS_DN<1>")
	)
	(segment
		(start 63.778892 -292.457378)
		(end 63.778892 -291.930074)
		(width 0.16002)
		(layer "In2.Cu")
		(net "M_C_CPU1_SB_DQS_DN<1>")
	)
	(segment
		(start 68.078604 -286.538162)
		(end 68.683886 -285.93288)
		(width 0.16002)
		(layer "In2.Cu")
		(net "M_C_CPU1_SB_DQS_DN<1>")
	)
	(segment
		(start 68.078604 -286.775398)
		(end 68.078604 -286.538162)
		(width 0.16002)
		(layer "In2.Cu")
		(net "M_C_CPU1_SB_DQS_DN<1>")
	)
	(segment
		(start 64.838326 -290.015676)
		(end 65.33134 -289.522662)
		(width 0.16002)
		(layer "In2.Cu")
		(net "M_C_CPU1_SB_DQS_DN<1>")
	)
	(segment
		(start 75.979528 -281.083004)
		(end 76.038456 -281.024076)
		(width 0.09525)
		(layer "In2.Cu")
		(net "M_C_CPU1_SB_DQS_DN<1>")
	)
	(segment
		(start 90.64117 -281.046428)
		(end 90.649552 -281.051254)
		(width 0.09525)
		(layer "In2.Cu")
		(net "M_C_CPU1_SB_DQS_DN<1>")
	)
	(segment
		(start 94.37497 -281.110944)
		(end 94.221046 -281.376374)
		(width 0.09525)
		(layer "In2.Cu")
		(net "M_C_CPU1_SB_DQS_DN<1>")
	)
	(segment
		(start 63.405258 -292.831012)
		(end 63.778892 -292.457378)
		(width 0.16002)
		(layer "In2.Cu")
		(net "M_C_CPU1_SB_DQS_DN<1>")
	)
	(segment
		(start 65.33134 -289.522662)
		(end 65.33134 -289.285426)
		(width 0.16002)
		(layer "In2.Cu")
		(net "M_C_CPU1_SB_DQS_DN<1>")
	)
	(segment
		(start 88.392508 -281.051254)
		(end 88.40089 -281.046428)
		(width 0.09525)
		(layer "In2.Cu")
		(net "M_C_CPU1_SB_DQS_DN<1>")
	)
	(segment
		(start 48.86833 -294.977312)
		(end 49.452022 -294.977312)
		(width 0.16002)
		(layer "In2.Cu")
		(net "M_C_CPU1_SB_DQS_DN<1>")
	)
	(segment
		(start 62.40526 -293.303706)
		(end 62.047374 -292.94582)
		(width 0.16002)
		(layer "In2.Cu")
		(net "M_C_CPU1_SB_DQS_DN<1>")
	)
	(segment
		(start 62.520068 -292.473126)
		(end 62.877954 -292.831012)
		(width 0.16002)
		(layer "In2.Cu")
		(net "M_C_CPU1_SB_DQS_DN<1>")
	)
	(segment
		(start 51.140614 -293.812468)
		(end 53.007006 -293.812468)
		(width 0.16002)
		(layer "In2.Cu")
		(net "M_C_CPU1_SB_DQS_DN<1>")
	)
	(segment
		(start 65.936622 -288.680144)
		(end 66.173858 -288.680144)
		(width 0.16002)
		(layer "In2.Cu")
		(net "M_C_CPU1_SB_DQS_DN<1>")
	)
	(segment
		(start 56.421782 -294.995092)
		(end 56.98871 -294.995092)
		(width 0.16002)
		(layer "In2.Cu")
		(net "M_C_CPU1_SB_DQS_DN<1>")
	)
	(segment
		(start 91.581224 -281.046428)
		(end 91.589606 -281.051254)
		(width 0.09525)
		(layer "In2.Cu")
		(net "M_C_CPU1_SB_DQS_DN<1>")
	)
	(segment
		(start 65.152524 -291.083746)
		(end 65.152524 -290.556442)
		(width 0.16002)
		(layer "In2.Cu")
		(net "M_C_CPU1_SB_DQS_DN<1>")
	)
	(segment
		(start 58.61431 -293.847012)
		(end 60.298076 -293.847012)
		(width 0.16002)
		(layer "In2.Cu")
		(net "M_C_CPU1_SB_DQS_DN<1>")
	)
	(segment
		(start 44.61383 -294.81145)
		(end 45.43298 -294.81145)
		(width 0.16002)
		(layer "In2.Cu")
		(net "M_C_CPU1_SB_DQS_DN<1>")
	)
	(segment
		(start 50.82921 -294.123872)
		(end 51.140614 -293.812468)
		(width 0.16002)
		(layer "In2.Cu")
		(net "M_C_CPU1_SB_DQS_DN<1>")
	)
	(segment
		(start 77.502004 -280.712164)
		(end 77.916024 -281.126184)
		(width 0.09525)
		(layer "In2.Cu")
		(net "M_C_CPU1_SB_DQS_DN<1>")
	)
	(segment
		(start 50.305462 -294.123872)
		(end 50.82921 -294.123872)
		(width 0.16002)
		(layer "In2.Cu")
		(net "M_C_CPU1_SB_DQS_DN<1>")
	)
	(segment
		(start 61.406024 -294.837866)
		(end 62.40526 -293.83863)
		(width 0.16002)
		(layer "In2.Cu")
		(net "M_C_CPU1_SB_DQS_DN<1>")
	)
	(segment
		(start 62.047374 -292.66896)
		(end 62.243208 -292.473126)
		(width 0.16002)
		(layer "In2.Cu")
		(net "M_C_CPU1_SB_DQS_DN<1>")
	)
	(segment
		(start 82.181192 -281.046428)
		(end 82.189574 -281.051254)
		(width 0.09525)
		(layer "In2.Cu")
		(net "M_C_CPU1_SB_DQS_DN<1>")
	)
	(segment
		(start 56.98871 -294.995092)
		(end 57.78627 -294.197532)
		(width 0.16002)
		(layer "In2.Cu")
		(net "M_C_CPU1_SB_DQS_DN<1>")
	)
	(segment
		(start 76.46035 -281.024076)
		(end 76.772262 -280.712164)
		(width 0.09525)
		(layer "In2.Cu")
		(net "M_C_CPU1_SB_DQS_DN<1>")
	)
	(segment
		(start 63.61684 -291.099494)
		(end 63.8937 -291.099494)
		(width 0.16002)
		(layer "In2.Cu")
		(net "M_C_CPU1_SB_DQS_DN<1>")
	)
	(segment
		(start 76.772262 -280.712164)
		(end 77.502004 -280.712164)
		(width 0.09525)
		(layer "In2.Cu")
		(net "M_C_CPU1_SB_DQS_DN<1>")
	)
	(segment
		(start 65.152524 -290.556442)
		(end 64.838326 -290.242244)
		(width 0.16002)
		(layer "In2.Cu")
		(net "M_C_CPU1_SB_DQS_DN<1>")
	)
	(segment
		(start 65.33134 -289.285426)
		(end 65.936622 -288.680144)
		(width 0.16002)
		(layer "In2.Cu")
		(net "M_C_CPU1_SB_DQS_DN<1>")
	)
	(segment
		(start 62.047374 -292.94582)
		(end 62.047374 -292.66896)
		(width 0.16002)
		(layer "In2.Cu")
		(net "M_C_CPU1_SB_DQS_DN<1>")
	)
	(segment
		(start 46.178978 -294.779192)
		(end 46.659038 -294.779192)
		(width 0.16002)
		(layer "In2.Cu")
		(net "M_C_CPU1_SB_DQS_DN<1>")
	)
	(segment
		(start 49.452022 -294.977312)
		(end 50.305462 -294.123872)
		(width 0.16002)
		(layer "In2.Cu")
		(net "M_C_CPU1_SB_DQS_DN<1>")
	)
	(segment
		(start 46.062138 -294.662352)
		(end 46.178978 -294.779192)
		(width 0.16002)
		(layer "In2.Cu")
		(net "M_C_CPU1_SB_DQS_DN<1>")
	)
	(arc
		(start 85.949536 -281.051254)
		(mid 86.230968 -281.127009)
		(end 86.5124 -281.051254)
		(width 0.09525)
		(layer "In2.Cu")
		(net "M_C_CPU1_SB_DQS_DN<1>")
	)
	(arc
		(start 84.069682 -281.051254)
		(mid 84.351114 -281.127009)
		(end 84.632546 -281.051254)
		(width 0.09525)
		(layer "In2.Cu")
		(net "M_C_CPU1_SB_DQS_DN<1>")
	)
	(arc
		(start 91.589606 -281.051254)
		(mid 91.871038 -281.127009)
		(end 92.15247 -281.051254)
		(width 0.09525)
		(layer "In2.Cu")
		(net "M_C_CPU1_SB_DQS_DN<1>")
	)
	(arc
		(start 85.009482 -281.051254)
		(mid 85.290914 -281.127009)
		(end 85.572346 -281.051254)
		(width 0.09525)
		(layer "In2.Cu")
		(net "M_C_CPU1_SB_DQS_DN<1>")
	)
	(arc
		(start 93.100906 -281.046428)
		(mid 93.285938 -281.000514)
		(end 93.469714 -281.051254)
		(width 0.09525)
		(layer "In2.Cu")
		(net "M_C_CPU1_SB_DQS_DN<1>")
	)
	(arc
		(start 93.469714 -281.051254)
		(mid 93.751146 -281.127009)
		(end 94.032578 -281.051254)
		(width 0.09525)
		(layer "In2.Cu")
		(net "M_C_CPU1_SB_DQS_DN<1>")
	)
	(arc
		(start 85.572346 -281.051254)
		(mid 85.756121 -281.000482)
		(end 85.941154 -281.046428)
		(width 0.09525)
		(layer "In2.Cu")
		(net "M_C_CPU1_SB_DQS_DN<1>")
	)
	(arc
		(start 87.829644 -281.051254)
		(mid 88.111076 -281.127009)
		(end 88.392508 -281.051254)
		(width 0.09525)
		(layer "In2.Cu")
		(net "M_C_CPU1_SB_DQS_DN<1>")
	)
	(arc
		(start 84.632546 -281.051254)
		(mid 84.821014 -281.000577)
		(end 85.009482 -281.051254)
		(width 0.09525)
		(layer "In2.Cu")
		(net "M_C_CPU1_SB_DQS_DN<1>")
	)
	(arc
		(start 91.212416 -281.051254)
		(mid 91.396191 -281.000482)
		(end 91.581224 -281.046428)
		(width 0.09525)
		(layer "In2.Cu")
		(net "M_C_CPU1_SB_DQS_DN<1>")
	)
	(arc
		(start 83.700874 -281.046428)
		(mid 83.885906 -281.000514)
		(end 84.069682 -281.051254)
		(width 0.09525)
		(layer "In2.Cu")
		(net "M_C_CPU1_SB_DQS_DN<1>")
	)
	(arc
		(start 81.24952 -281.051254)
		(mid 81.530952 -281.127009)
		(end 81.812384 -281.051254)
		(width 0.09525)
		(layer "In2.Cu")
		(net "M_C_CPU1_SB_DQS_DN<1>")
	)
	(arc
		(start 80.872584 -281.051254)
		(mid 81.061052 -281.000577)
		(end 81.24952 -281.051254)
		(width 0.09525)
		(layer "In2.Cu")
		(net "M_C_CPU1_SB_DQS_DN<1>")
	)
	(arc
		(start 90.649552 -281.051254)
		(mid 90.930984 -281.127009)
		(end 91.212416 -281.051254)
		(width 0.09525)
		(layer "In2.Cu")
		(net "M_C_CPU1_SB_DQS_DN<1>")
	)
	(arc
		(start 86.88959 -281.051254)
		(mid 87.171022 -281.127009)
		(end 87.452454 -281.051254)
		(width 0.09525)
		(layer "In2.Cu")
		(net "M_C_CPU1_SB_DQS_DN<1>")
	)
	(arc
		(start 87.460836 -281.046428)
		(mid 87.645868 -281.000514)
		(end 87.829644 -281.051254)
		(width 0.09525)
		(layer "In2.Cu")
		(net "M_C_CPU1_SB_DQS_DN<1>")
	)
	(arc
		(start 94.032578 -281.051254)
		(mid 94.189205 -281.002068)
		(end 94.351856 -281.02433)
		(width 0.09525)
		(layer "In2.Cu")
		(net "M_C_CPU1_SB_DQS_DN<1>")
	)
	(arc
		(start 86.5124 -281.051254)
		(mid 86.696175 -281.000482)
		(end 86.881208 -281.046428)
		(width 0.09525)
		(layer "In2.Cu")
		(net "M_C_CPU1_SB_DQS_DN<1>")
	)
	(arc
		(start 79.957168 -281.038046)
		(mid 80.135087 -281.000731)
		(end 80.30972 -281.051254)
		(width 0.09525)
		(layer "In2.Cu")
		(net "M_C_CPU1_SB_DQS_DN<1>")
	)
	(arc
		(start 80.30972 -281.051254)
		(mid 80.591152 -281.127009)
		(end 80.872584 -281.051254)
		(width 0.09525)
		(layer "In2.Cu")
		(net "M_C_CPU1_SB_DQS_DN<1>")
	)
	(arc
		(start 88.769698 -281.051254)
		(mid 89.05113 -281.127009)
		(end 89.332562 -281.051254)
		(width 0.09525)
		(layer "In2.Cu")
		(net "M_C_CPU1_SB_DQS_DN<1>")
	)
	(arc
		(start 89.332562 -281.051254)
		(mid 89.52103 -281.000577)
		(end 89.709498 -281.051254)
		(width 0.09525)
		(layer "In2.Cu")
		(net "M_C_CPU1_SB_DQS_DN<1>")
	)
	(arc
		(start 88.40089 -281.046428)
		(mid 88.585922 -281.000514)
		(end 88.769698 -281.051254)
		(width 0.09525)
		(layer "In2.Cu")
		(net "M_C_CPU1_SB_DQS_DN<1>")
	)
	(arc
		(start 83.129628 -281.051254)
		(mid 83.41106 -281.127009)
		(end 83.692492 -281.051254)
		(width 0.09525)
		(layer "In2.Cu")
		(net "M_C_CPU1_SB_DQS_DN<1>")
	)
	(arc
		(start 90.272362 -281.051254)
		(mid 90.456137 -281.000482)
		(end 90.64117 -281.046428)
		(width 0.09525)
		(layer "In2.Cu")
		(net "M_C_CPU1_SB_DQS_DN<1>")
	)
	(arc
		(start 81.812384 -281.051254)
		(mid 81.996159 -281.000482)
		(end 82.181192 -281.046428)
		(width 0.09525)
		(layer "In2.Cu")
		(net "M_C_CPU1_SB_DQS_DN<1>")
	)
	(arc
		(start 89.709498 -281.051254)
		(mid 89.99093 -281.127009)
		(end 90.272362 -281.051254)
		(width 0.09525)
		(layer "In2.Cu")
		(net "M_C_CPU1_SB_DQS_DN<1>")
	)
	(arc
		(start 82.189574 -281.051254)
		(mid 82.471006 -281.127009)
		(end 82.752438 -281.051254)
		(width 0.09525)
		(layer "In2.Cu")
		(net "M_C_CPU1_SB_DQS_DN<1>")
	)
	(arc
		(start 79.654146 -281.126184)
		(mid 79.798882 -281.107227)
		(end 79.9338 -281.051508)
		(width 0.09525)
		(layer "In2.Cu")
		(net "M_C_CPU1_SB_DQS_DN<1>")
	)
	(arc
		(start 92.160852 -281.046428)
		(mid 92.345884 -281.000514)
		(end 92.52966 -281.051254)
		(width 0.09525)
		(layer "In2.Cu")
		(net "M_C_CPU1_SB_DQS_DN<1>")
	)
	(arc
		(start 82.76082 -281.046428)
		(mid 82.945852 -281.000514)
		(end 83.129628 -281.051254)
		(width 0.09525)
		(layer "In2.Cu")
		(net "M_C_CPU1_SB_DQS_DN<1>")
	)
	(arc
		(start 92.52966 -281.051254)
		(mid 92.811092 -281.127009)
		(end 93.092524 -281.051254)
		(width 0.09525)
		(layer "In2.Cu")
		(net "M_C_CPU1_SB_DQS_DN<1>")
	)
	(segment
		(start 94.687898 -276.2504)
		(end 94.221046 -276.516338)
		(width 0.12954)
		(layer "F.Cu")
		(net "M_C_CPU1_SB_DQS_DN<0>")
	)
	(segment
		(start 53.16855 -285.317946)
		(end 53.55463 -285.704026)
		(width 0.16002)
		(layer "In2.Cu")
		(net "M_C_CPU1_SB_DQS_DN<0>")
	)
	(segment
		(start 64.179704 -281.772106)
		(end 64.659764 -281.772106)
		(width 0.16002)
		(layer "In2.Cu")
		(net "M_C_CPU1_SB_DQS_DN<0>")
	)
	(segment
		(start 76.340462 -275.400516)
		(end 76.78166 -275.841714)
		(width 0.09525)
		(layer "In2.Cu")
		(net "M_C_CPU1_SB_DQS_DN<0>")
	)
	(segment
		(start 76.78166 -275.841714)
		(end 77.302106 -275.841714)
		(width 0.09525)
		(layer "In2.Cu")
		(net "M_C_CPU1_SB_DQS_DN<0>")
	)
	(segment
		(start 49.56937 -285.627318)
		(end 50.42281 -284.773878)
		(width 0.16002)
		(layer "In2.Cu")
		(net "M_C_CPU1_SB_DQS_DN<0>")
	)
	(segment
		(start 90.64117 -276.186392)
		(end 90.649552 -276.191218)
		(width 0.09525)
		(layer "In2.Cu")
		(net "M_C_CPU1_SB_DQS_DN<0>")
	)
	(segment
		(start 54.07787 -285.704026)
		(end 54.426358 -285.355538)
		(width 0.16002)
		(layer "In2.Cu")
		(net "M_C_CPU1_SB_DQS_DN<0>")
	)
	(segment
		(start 63.2587 -283.474668)
		(end 63.632334 -283.101034)
		(width 0.16002)
		(layer "In2.Cu")
		(net "M_C_CPU1_SB_DQS_DN<0>")
	)
	(segment
		(start 78.325726 -276.26564)
		(end 78.711298 -276.26564)
		(width 0.09525)
		(layer "In2.Cu")
		(net "M_C_CPU1_SB_DQS_DN<0>")
	)
	(segment
		(start 61.885068 -284.8483)
		(end 62.258956 -284.474412)
		(width 0.16002)
		(layer "In2.Cu")
		(net "M_C_CPU1_SB_DQS_DN<0>")
	)
	(segment
		(start 44.340018 -285.735268)
		(end 44.61383 -285.461456)
		(width 0.16002)
		(layer "In2.Cu")
		(net "M_C_CPU1_SB_DQS_DN<0>")
	)
	(segment
		(start 87.452454 -276.191218)
		(end 87.460836 -276.186392)
		(width 0.09525)
		(layer "In2.Cu")
		(net "M_C_CPU1_SB_DQS_DN<0>")
	)
	(segment
		(start 76.038456 -275.400516)
		(end 76.340462 -275.400516)
		(width 0.09525)
		(layer "In2.Cu")
		(net "M_C_CPU1_SB_DQS_DN<0>")
	)
	(segment
		(start 58.26379 -284.847538)
		(end 58.61431 -284.497018)
		(width 0.16002)
		(layer "In2.Cu")
		(net "M_C_CPU1_SB_DQS_DN<0>")
	)
	(segment
		(start 61.874654 -283.563568)
		(end 61.874654 -283.286708)
		(width 0.16002)
		(layer "In2.Cu")
		(net "M_C_CPU1_SB_DQS_DN<0>")
	)
	(segment
		(start 63.632334 -282.573984)
		(end 63.280544 -282.222194)
		(width 0.16002)
		(layer "In2.Cu")
		(net "M_C_CPU1_SB_DQS_DN<0>")
	)
	(segment
		(start 53.007006 -284.462474)
		(end 53.16855 -284.624018)
		(width 0.16002)
		(layer "In2.Cu")
		(net "M_C_CPU1_SB_DQS_DN<0>")
	)
	(segment
		(start 66.007488 -280.772108)
		(end 66.007488 -280.250138)
		(width 0.16002)
		(layer "In2.Cu")
		(net "M_C_CPU1_SB_DQS_DN<0>")
	)
	(segment
		(start 71.3232 -275.459444)
		(end 75.955906 -275.459444)
		(width 0.16002)
		(layer "In2.Cu")
		(net "M_C_CPU1_SB_DQS_DN<0>")
	)
	(segment
		(start 79.364586 -276.191218)
		(end 79.396336 -276.20976)
		(width 0.09525)
		(layer "In2.Cu")
		(net "M_C_CPU1_SB_DQS_DN<0>")
	)
	(segment
		(start 94.37497 -276.250908)
		(end 94.221046 -276.516338)
		(width 0.09525)
		(layer "In2.Cu")
		(net "M_C_CPU1_SB_DQS_DN<0>")
	)
	(segment
		(start 67.38112 -279.401524)
		(end 67.38112 -278.876506)
		(width 0.16002)
		(layer "In2.Cu")
		(net "M_C_CPU1_SB_DQS_DN<0>")
	)
	(segment
		(start 45.627036 -285.461456)
		(end 45.776134 -285.312358)
		(width 0.16002)
		(layer "In2.Cu")
		(net "M_C_CPU1_SB_DQS_DN<0>")
	)
	(segment
		(start 62.258702 -284.211014)
		(end 62.258702 -283.947616)
		(width 0.16002)
		(layer "In2.Cu")
		(net "M_C_CPU1_SB_DQS_DN<0>")
	)
	(segment
		(start 45.776134 -285.312358)
		(end 48.55337 -285.312358)
		(width 0.16002)
		(layer "In2.Cu")
		(net "M_C_CPU1_SB_DQS_DN<0>")
	)
	(segment
		(start 64.062864 -281.655266)
		(end 64.179704 -281.772106)
		(width 0.16002)
		(layer "In2.Cu")
		(net "M_C_CPU1_SB_DQS_DN<0>")
	)
	(segment
		(start 63.632334 -283.101034)
		(end 63.632334 -282.573984)
		(width 0.16002)
		(layer "In2.Cu")
		(net "M_C_CPU1_SB_DQS_DN<0>")
	)
	(segment
		(start 66.007488 -280.250138)
		(end 66.3448 -279.912826)
		(width 0.16002)
		(layer "In2.Cu")
		(net "M_C_CPU1_SB_DQS_DN<0>")
	)
	(segment
		(start 77.302106 -275.841714)
		(end 78.325726 -276.26564)
		(width 0.09525)
		(layer "In2.Cu")
		(net "M_C_CPU1_SB_DQS_DN<0>")
	)
	(segment
		(start 80.283304 -276.175978)
		(end 80.30972 -276.191218)
		(width 0.09525)
		(layer "In2.Cu")
		(net "M_C_CPU1_SB_DQS_DN<0>")
	)
	(segment
		(start 63.280544 -282.222194)
		(end 63.280544 -281.957526)
		(width 0.16002)
		(layer "In2.Cu")
		(net "M_C_CPU1_SB_DQS_DN<0>")
	)
	(segment
		(start 57.78627 -284.847538)
		(end 58.26379 -284.847538)
		(width 0.16002)
		(layer "In2.Cu")
		(net "M_C_CPU1_SB_DQS_DN<0>")
	)
	(segment
		(start 70.990714 -275.79193)
		(end 71.3232 -275.459444)
		(width 0.16002)
		(layer "In2.Cu")
		(net "M_C_CPU1_SB_DQS_DN<0>")
	)
	(segment
		(start 91.581224 -276.186392)
		(end 91.589606 -276.191218)
		(width 0.09525)
		(layer "In2.Cu")
		(net "M_C_CPU1_SB_DQS_DN<0>")
	)
	(segment
		(start 85.941154 -276.186392)
		(end 85.949536 -276.191218)
		(width 0.09525)
		(layer "In2.Cu")
		(net "M_C_CPU1_SB_DQS_DN<0>")
	)
	(segment
		(start 88.392508 -276.191218)
		(end 88.40089 -276.186392)
		(width 0.09525)
		(layer "In2.Cu")
		(net "M_C_CPU1_SB_DQS_DN<0>")
	)
	(segment
		(start 82.752438 -276.191218)
		(end 82.76082 -276.186392)
		(width 0.09525)
		(layer "In2.Cu")
		(net "M_C_CPU1_SB_DQS_DN<0>")
	)
	(segment
		(start 78.989174 -276.190964)
		(end 79.00289 -276.18309)
		(width 0.09525)
		(layer "In2.Cu")
		(net "M_C_CPU1_SB_DQS_DN<0>")
	)
	(segment
		(start 79.00289 -276.18309)
		(end 79.003398 -276.183344)
		(width 0.09525)
		(layer "In2.Cu")
		(net "M_C_CPU1_SB_DQS_DN<0>")
	)
	(segment
		(start 68.754752 -278.027892)
		(end 68.754752 -277.502874)
		(width 0.16002)
		(layer "In2.Cu")
		(net "M_C_CPU1_SB_DQS_DN<0>")
	)
	(segment
		(start 62.731396 -283.474668)
		(end 63.2587 -283.474668)
		(width 0.16002)
		(layer "In2.Cu")
		(net "M_C_CPU1_SB_DQS_DN<0>")
	)
	(segment
		(start 70.128384 -276.129242)
		(end 70.465696 -275.79193)
		(width 0.16002)
		(layer "In2.Cu")
		(net "M_C_CPU1_SB_DQS_DN<0>")
	)
	(segment
		(start 56.149494 -285.355538)
		(end 56.439054 -285.645098)
		(width 0.16002)
		(layer "In2.Cu")
		(net "M_C_CPU1_SB_DQS_DN<0>")
	)
	(segment
		(start 75.979528 -275.459444)
		(end 76.038456 -275.400516)
		(width 0.09525)
		(layer "In2.Cu")
		(net "M_C_CPU1_SB_DQS_DN<0>")
	)
	(segment
		(start 62.258956 -284.474412)
		(end 62.258702 -284.211014)
		(width 0.16002)
		(layer "In2.Cu")
		(net "M_C_CPU1_SB_DQS_DN<0>")
	)
	(segment
		(start 67.38112 -278.876506)
		(end 67.718432 -278.539194)
		(width 0.16002)
		(layer "In2.Cu")
		(net "M_C_CPU1_SB_DQS_DN<0>")
	)
	(segment
		(start 61.005974 -284.496764)
		(end 61.357764 -284.848554)
		(width 0.16002)
		(layer "In2.Cu")
		(net "M_C_CPU1_SB_DQS_DN<0>")
	)
	(segment
		(start 56.98871 -285.645098)
		(end 57.78627 -284.847538)
		(width 0.16002)
		(layer "In2.Cu")
		(net "M_C_CPU1_SB_DQS_DN<0>")
	)
	(segment
		(start 70.128384 -276.65426)
		(end 70.128384 -276.129242)
		(width 0.16002)
		(layer "In2.Cu")
		(net "M_C_CPU1_SB_DQS_DN<0>")
	)
	(segment
		(start 68.24345 -278.539194)
		(end 68.754752 -278.027892)
		(width 0.16002)
		(layer "In2.Cu")
		(net "M_C_CPU1_SB_DQS_DN<0>")
	)
	(segment
		(start 53.55463 -285.704026)
		(end 54.07787 -285.704026)
		(width 0.16002)
		(layer "In2.Cu")
		(net "M_C_CPU1_SB_DQS_DN<0>")
	)
	(segment
		(start 66.869818 -279.912826)
		(end 67.38112 -279.401524)
		(width 0.16002)
		(layer "In2.Cu")
		(net "M_C_CPU1_SB_DQS_DN<0>")
	)
	(segment
		(start 61.357764 -284.848554)
		(end 61.885068 -284.8483)
		(width 0.16002)
		(layer "In2.Cu")
		(net "M_C_CPU1_SB_DQS_DN<0>")
	)
	(segment
		(start 66.3448 -279.912826)
		(end 66.869818 -279.912826)
		(width 0.16002)
		(layer "In2.Cu")
		(net "M_C_CPU1_SB_DQS_DN<0>")
	)
	(segment
		(start 48.86833 -285.627318)
		(end 49.56937 -285.627318)
		(width 0.16002)
		(layer "In2.Cu")
		(net "M_C_CPU1_SB_DQS_DN<0>")
	)
	(segment
		(start 50.42281 -284.773878)
		(end 50.809398 -284.773878)
		(width 0.16002)
		(layer "In2.Cu")
		(net "M_C_CPU1_SB_DQS_DN<0>")
	)
	(segment
		(start 86.881208 -276.186392)
		(end 86.88959 -276.191218)
		(width 0.09525)
		(layer "In2.Cu")
		(net "M_C_CPU1_SB_DQS_DN<0>")
	)
	(segment
		(start 44.61383 -285.461456)
		(end 45.627036 -285.461456)
		(width 0.16002)
		(layer "In2.Cu")
		(net "M_C_CPU1_SB_DQS_DN<0>")
	)
	(segment
		(start 63.280544 -281.957526)
		(end 63.582804 -281.655266)
		(width 0.16002)
		(layer "In2.Cu")
		(net "M_C_CPU1_SB_DQS_DN<0>")
	)
	(segment
		(start 53.16855 -284.624018)
		(end 53.16855 -285.317946)
		(width 0.16002)
		(layer "In2.Cu")
		(net "M_C_CPU1_SB_DQS_DN<0>")
	)
	(segment
		(start 64.776604 -281.655266)
		(end 65.12433 -281.655266)
		(width 0.16002)
		(layer "In2.Cu")
		(net "M_C_CPU1_SB_DQS_DN<0>")
	)
	(segment
		(start 48.55337 -285.312358)
		(end 48.86833 -285.627318)
		(width 0.16002)
		(layer "In2.Cu")
		(net "M_C_CPU1_SB_DQS_DN<0>")
	)
	(segment
		(start 79.003398 -276.183344)
		(end 79.017114 -276.175724)
		(width 0.09525)
		(layer "In2.Cu")
		(net "M_C_CPU1_SB_DQS_DN<0>")
	)
	(segment
		(start 94.351856 -276.164294)
		(end 94.37497 -276.250908)
		(width 0.09525)
		(layer "In2.Cu")
		(net "M_C_CPU1_SB_DQS_DN<0>")
	)
	(segment
		(start 61.874654 -283.286708)
		(end 62.070488 -283.090874)
		(width 0.16002)
		(layer "In2.Cu")
		(net "M_C_CPU1_SB_DQS_DN<0>")
	)
	(segment
		(start 50.809398 -284.773878)
		(end 51.120802 -284.462474)
		(width 0.16002)
		(layer "In2.Cu")
		(net "M_C_CPU1_SB_DQS_DN<0>")
	)
	(segment
		(start 51.120802 -284.462474)
		(end 53.007006 -284.462474)
		(width 0.16002)
		(layer "In2.Cu")
		(net "M_C_CPU1_SB_DQS_DN<0>")
	)
	(segment
		(start 65.12433 -281.655266)
		(end 66.007488 -280.772108)
		(width 0.16002)
		(layer "In2.Cu")
		(net "M_C_CPU1_SB_DQS_DN<0>")
	)
	(segment
		(start 83.692492 -276.191218)
		(end 83.700874 -276.186392)
		(width 0.09525)
		(layer "In2.Cu")
		(net "M_C_CPU1_SB_DQS_DN<0>")
	)
	(segment
		(start 70.465696 -275.79193)
		(end 70.990714 -275.79193)
		(width 0.16002)
		(layer "In2.Cu")
		(net "M_C_CPU1_SB_DQS_DN<0>")
	)
	(segment
		(start 69.092064 -277.165562)
		(end 69.617082 -277.165562)
		(width 0.16002)
		(layer "In2.Cu")
		(net "M_C_CPU1_SB_DQS_DN<0>")
	)
	(segment
		(start 64.659764 -281.772106)
		(end 64.776604 -281.655266)
		(width 0.16002)
		(layer "In2.Cu")
		(net "M_C_CPU1_SB_DQS_DN<0>")
	)
	(segment
		(start 56.439054 -285.645098)
		(end 56.98871 -285.645098)
		(width 0.16002)
		(layer "In2.Cu")
		(net "M_C_CPU1_SB_DQS_DN<0>")
	)
	(segment
		(start 67.718432 -278.539194)
		(end 68.24345 -278.539194)
		(width 0.16002)
		(layer "In2.Cu")
		(net "M_C_CPU1_SB_DQS_DN<0>")
	)
	(segment
		(start 54.426358 -285.355538)
		(end 56.149494 -285.355538)
		(width 0.16002)
		(layer "In2.Cu")
		(net "M_C_CPU1_SB_DQS_DN<0>")
	)
	(segment
		(start 82.181192 -276.186392)
		(end 82.189574 -276.191218)
		(width 0.09525)
		(layer "In2.Cu")
		(net "M_C_CPU1_SB_DQS_DN<0>")
	)
	(segment
		(start 68.754752 -277.502874)
		(end 69.092064 -277.165562)
		(width 0.16002)
		(layer "In2.Cu")
		(net "M_C_CPU1_SB_DQS_DN<0>")
	)
	(segment
		(start 58.61431 -284.497018)
		(end 60.72886 -284.497018)
		(width 0.16002)
		(layer "In2.Cu")
		(net "M_C_CPU1_SB_DQS_DN<0>")
	)
	(segment
		(start 75.955906 -275.459444)
		(end 75.979528 -275.459444)
		(width 0.09525)
		(layer "In2.Cu")
		(net "M_C_CPU1_SB_DQS_DN<0>")
	)
	(segment
		(start 92.15247 -276.191218)
		(end 92.160852 -276.186392)
		(width 0.09525)
		(layer "In2.Cu")
		(net "M_C_CPU1_SB_DQS_DN<0>")
	)
	(segment
		(start 69.617082 -277.165562)
		(end 70.128384 -276.65426)
		(width 0.16002)
		(layer "In2.Cu")
		(net "M_C_CPU1_SB_DQS_DN<0>")
	)
	(segment
		(start 93.092524 -276.191218)
		(end 93.100906 -276.186392)
		(width 0.09525)
		(layer "In2.Cu")
		(net "M_C_CPU1_SB_DQS_DN<0>")
	)
	(segment
		(start 63.582804 -281.655266)
		(end 64.062864 -281.655266)
		(width 0.16002)
		(layer "In2.Cu")
		(net "M_C_CPU1_SB_DQS_DN<0>")
	)
	(segment
		(start 60.72886 -284.497018)
		(end 61.005974 -284.496764)
		(width 0.16002)
		(layer "In2.Cu")
		(net "M_C_CPU1_SB_DQS_DN<0>")
	)
	(segment
		(start 62.070488 -283.090874)
		(end 62.347602 -283.090874)
		(width 0.16002)
		(layer "In2.Cu")
		(net "M_C_CPU1_SB_DQS_DN<0>")
	)
	(segment
		(start 62.347602 -283.090874)
		(end 62.731396 -283.474668)
		(width 0.16002)
		(layer "In2.Cu")
		(net "M_C_CPU1_SB_DQS_DN<0>")
	)
	(segment
		(start 62.258702 -283.947616)
		(end 61.874654 -283.563568)
		(width 0.16002)
		(layer "In2.Cu")
		(net "M_C_CPU1_SB_DQS_DN<0>")
	)
	(arc
		(start 80.30972 -276.191218)
		(mid 80.591152 -276.266973)
		(end 80.872584 -276.191218)
		(width 0.09525)
		(layer "In2.Cu")
		(net "M_C_CPU1_SB_DQS_DN<0>")
	)
	(arc
		(start 84.632546 -276.191218)
		(mid 84.821014 -276.140541)
		(end 85.009482 -276.191218)
		(width 0.09525)
		(layer "In2.Cu")
		(net "M_C_CPU1_SB_DQS_DN<0>")
	)
	(arc
		(start 91.212416 -276.191218)
		(mid 91.396191 -276.140446)
		(end 91.581224 -276.186392)
		(width 0.09525)
		(layer "In2.Cu")
		(net "M_C_CPU1_SB_DQS_DN<0>")
	)
	(arc
		(start 79.396336 -276.20976)
		(mid 79.665683 -276.267932)
		(end 79.930244 -276.190964)
		(width 0.09525)
		(layer "In2.Cu")
		(net "M_C_CPU1_SB_DQS_DN<0>")
	)
	(arc
		(start 86.88959 -276.191218)
		(mid 87.171022 -276.266973)
		(end 87.452454 -276.191218)
		(width 0.09525)
		(layer "In2.Cu")
		(net "M_C_CPU1_SB_DQS_DN<0>")
	)
	(arc
		(start 83.700874 -276.186392)
		(mid 83.885906 -276.140478)
		(end 84.069682 -276.191218)
		(width 0.09525)
		(layer "In2.Cu")
		(net "M_C_CPU1_SB_DQS_DN<0>")
	)
	(arc
		(start 82.76082 -276.186392)
		(mid 82.945852 -276.140478)
		(end 83.129628 -276.191218)
		(width 0.09525)
		(layer "In2.Cu")
		(net "M_C_CPU1_SB_DQS_DN<0>")
	)
	(arc
		(start 85.009482 -276.191218)
		(mid 85.290914 -276.266973)
		(end 85.572346 -276.191218)
		(width 0.09525)
		(layer "In2.Cu")
		(net "M_C_CPU1_SB_DQS_DN<0>")
	)
	(arc
		(start 90.649552 -276.191218)
		(mid 90.930984 -276.266973)
		(end 91.212416 -276.191218)
		(width 0.09525)
		(layer "In2.Cu")
		(net "M_C_CPU1_SB_DQS_DN<0>")
	)
	(arc
		(start 81.812384 -276.191218)
		(mid 81.996159 -276.140446)
		(end 82.181192 -276.186392)
		(width 0.09525)
		(layer "In2.Cu")
		(net "M_C_CPU1_SB_DQS_DN<0>")
	)
	(arc
		(start 85.572346 -276.191218)
		(mid 85.756121 -276.140446)
		(end 85.941154 -276.186392)
		(width 0.09525)
		(layer "In2.Cu")
		(net "M_C_CPU1_SB_DQS_DN<0>")
	)
	(arc
		(start 91.589606 -276.191218)
		(mid 91.871038 -276.266973)
		(end 92.15247 -276.191218)
		(width 0.09525)
		(layer "In2.Cu")
		(net "M_C_CPU1_SB_DQS_DN<0>")
	)
	(arc
		(start 94.032578 -276.191218)
		(mid 94.189205 -276.142032)
		(end 94.351856 -276.164294)
		(width 0.09525)
		(layer "In2.Cu")
		(net "M_C_CPU1_SB_DQS_DN<0>")
	)
	(arc
		(start 80.872584 -276.191218)
		(mid 81.061052 -276.140541)
		(end 81.24952 -276.191218)
		(width 0.09525)
		(layer "In2.Cu")
		(net "M_C_CPU1_SB_DQS_DN<0>")
	)
	(arc
		(start 89.332562 -276.191218)
		(mid 89.52103 -276.140541)
		(end 89.709498 -276.191218)
		(width 0.09525)
		(layer "In2.Cu")
		(net "M_C_CPU1_SB_DQS_DN<0>")
	)
	(arc
		(start 86.5124 -276.191218)
		(mid 86.696175 -276.140446)
		(end 86.881208 -276.186392)
		(width 0.09525)
		(layer "In2.Cu")
		(net "M_C_CPU1_SB_DQS_DN<0>")
	)
	(arc
		(start 79.017114 -276.175724)
		(mid 79.192765 -276.140808)
		(end 79.364586 -276.191218)
		(width 0.09525)
		(layer "In2.Cu")
		(net "M_C_CPU1_SB_DQS_DN<0>")
	)
	(arc
		(start 78.711298 -276.26564)
		(mid 78.855122 -276.246485)
		(end 78.989174 -276.190964)
		(width 0.09525)
		(layer "In2.Cu")
		(net "M_C_CPU1_SB_DQS_DN<0>")
	)
	(arc
		(start 88.769698 -276.191218)
		(mid 89.05113 -276.266973)
		(end 89.332562 -276.191218)
		(width 0.09525)
		(layer "In2.Cu")
		(net "M_C_CPU1_SB_DQS_DN<0>")
	)
	(arc
		(start 87.829644 -276.191218)
		(mid 88.111076 -276.266973)
		(end 88.392508 -276.191218)
		(width 0.09525)
		(layer "In2.Cu")
		(net "M_C_CPU1_SB_DQS_DN<0>")
	)
	(arc
		(start 93.100906 -276.186392)
		(mid 93.285938 -276.140478)
		(end 93.469714 -276.191218)
		(width 0.09525)
		(layer "In2.Cu")
		(net "M_C_CPU1_SB_DQS_DN<0>")
	)
	(arc
		(start 82.189574 -276.191218)
		(mid 82.471006 -276.266973)
		(end 82.752438 -276.191218)
		(width 0.09525)
		(layer "In2.Cu")
		(net "M_C_CPU1_SB_DQS_DN<0>")
	)
	(arc
		(start 92.160852 -276.186392)
		(mid 92.345884 -276.140478)
		(end 92.52966 -276.191218)
		(width 0.09525)
		(layer "In2.Cu")
		(net "M_C_CPU1_SB_DQS_DN<0>")
	)
	(arc
		(start 90.272362 -276.191218)
		(mid 90.456137 -276.140446)
		(end 90.64117 -276.186392)
		(width 0.09525)
		(layer "In2.Cu")
		(net "M_C_CPU1_SB_DQS_DN<0>")
	)
	(arc
		(start 93.469714 -276.191218)
		(mid 93.751146 -276.266973)
		(end 94.032578 -276.191218)
		(width 0.09525)
		(layer "In2.Cu")
		(net "M_C_CPU1_SB_DQS_DN<0>")
	)
	(arc
		(start 88.40089 -276.186392)
		(mid 88.585922 -276.140478)
		(end 88.769698 -276.191218)
		(width 0.09525)
		(layer "In2.Cu")
		(net "M_C_CPU1_SB_DQS_DN<0>")
	)
	(arc
		(start 87.460836 -276.186392)
		(mid 87.645868 -276.140478)
		(end 87.829644 -276.191218)
		(width 0.09525)
		(layer "In2.Cu")
		(net "M_C_CPU1_SB_DQS_DN<0>")
	)
	(arc
		(start 89.709498 -276.191218)
		(mid 89.99093 -276.266973)
		(end 90.272362 -276.191218)
		(width 0.09525)
		(layer "In2.Cu")
		(net "M_C_CPU1_SB_DQS_DN<0>")
	)
	(arc
		(start 92.52966 -276.191218)
		(mid 92.811092 -276.266973)
		(end 93.092524 -276.191218)
		(width 0.09525)
		(layer "In2.Cu")
		(net "M_C_CPU1_SB_DQS_DN<0>")
	)
	(arc
		(start 84.069682 -276.191218)
		(mid 84.351114 -276.266973)
		(end 84.632546 -276.191218)
		(width 0.09525)
		(layer "In2.Cu")
		(net "M_C_CPU1_SB_DQS_DN<0>")
	)
	(arc
		(start 81.24952 -276.191218)
		(mid 81.530952 -276.266973)
		(end 81.812384 -276.191218)
		(width 0.09525)
		(layer "In2.Cu")
		(net "M_C_CPU1_SB_DQS_DN<0>")
	)
	(arc
		(start 85.949536 -276.191218)
		(mid 86.230968 -276.266973)
		(end 86.5124 -276.191218)
		(width 0.09525)
		(layer "In2.Cu")
		(net "M_C_CPU1_SB_DQS_DN<0>")
	)
	(arc
		(start 83.129628 -276.191218)
		(mid 83.41106 -276.266973)
		(end 83.692492 -276.191218)
		(width 0.09525)
		(layer "In2.Cu")
		(net "M_C_CPU1_SB_DQS_DN<0>")
	)
	(arc
		(start 79.930244 -276.190964)
		(mid 80.104919 -276.139513)
		(end 80.283304 -276.175978)
		(width 0.09525)
		(layer "In2.Cu")
		(net "M_C_CPU1_SB_DQS_DN<0>")
	)
	(segment
		(start 96.568006 -279.490424)
		(end 96.101154 -279.756362)
		(width 0.10668)
		(layer "F.Cu")
		(net "M_C_CPU1_SB_DQ<9>")
	)
	(segment
		(start 57.488328 -292.218364)
		(end 57.75071 -292.218364)
		(width 0.14478)
		(layer "In2.Cu")
		(net "M_C_CPU1_SB_DQ<9>")
	)
	(segment
		(start 93.094048 -280.078942)
		(end 93.10243 -280.083768)
		(width 0.0889)
		(layer "In2.Cu")
		(net "M_C_CPU1_SB_DQ<9>")
	)
	(segment
		(start 88.394032 -280.078942)
		(end 88.402414 -280.083768)
		(width 0.0889)
		(layer "In2.Cu")
		(net "M_C_CPU1_SB_DQ<9>")
	)
	(segment
		(start 46.199552 -292.736778)
		(end 46.199552 -293.17315)
		(width 0.14478)
		(layer "In2.Cu")
		(net "M_C_CPU1_SB_DQ<9>")
	)
	(segment
		(start 45.643292 -293.17315)
		(end 45.643292 -292.736778)
		(width 0.14478)
		(layer "In2.Cu")
		(net "M_C_CPU1_SB_DQ<9>")
	)
	(segment
		(start 46.918626 -292.573964)
		(end 47.149258 -292.573964)
		(width 0.14478)
		(layer "In2.Cu")
		(net "M_C_CPU1_SB_DQ<9>")
	)
	(segment
		(start 53.213508 -292.497764)
		(end 53.571648 -292.139624)
		(width 0.14478)
		(layer "In2.Cu")
		(net "M_C_CPU1_SB_DQ<9>")
	)
	(segment
		(start 58.03011 -292.497764)
		(end 58.260742 -292.497764)
		(width 0.14478)
		(layer "In2.Cu")
		(net "M_C_CPU1_SB_DQ<9>")
	)
	(segment
		(start 92.153994 -280.078942)
		(end 92.162376 -280.083768)
		(width 0.0889)
		(layer "In2.Cu")
		(net "M_C_CPU1_SB_DQ<9>")
	)
	(segment
		(start 58.817002 -291.735764)
		(end 59.191398 -292.11016)
		(width 0.14478)
		(layer "In2.Cu")
		(net "M_C_CPU1_SB_DQ<9>")
	)
	(segment
		(start 52.820062 -292.33495)
		(end 52.982876 -292.497764)
		(width 0.14478)
		(layer "In2.Cu")
		(net "M_C_CPU1_SB_DQ<9>")
	)
	(segment
		(start 78.979014 -280.069036)
		(end 78.996032 -280.078942)
		(width 0.0889)
		(layer "In2.Cu")
		(net "M_C_CPU1_SB_DQ<9>")
	)
	(segment
		(start 58.58637 -291.735764)
		(end 58.817002 -291.735764)
		(width 0.14478)
		(layer "In2.Cu")
		(net "M_C_CPU1_SB_DQ<9>")
	)
	(segment
		(start 44.340018 -292.535356)
		(end 44.76496 -292.960298)
		(width 0.14478)
		(layer "In2.Cu")
		(net "M_C_CPU1_SB_DQ<9>")
	)
	(segment
		(start 45.806106 -292.573964)
		(end 46.036738 -292.573964)
		(width 0.14478)
		(layer "In2.Cu")
		(net "M_C_CPU1_SB_DQ<9>")
	)
	(segment
		(start 52.982876 -292.497764)
		(end 53.213508 -292.497764)
		(width 0.14478)
		(layer "In2.Cu")
		(net "M_C_CPU1_SB_DQ<9>")
	)
	(segment
		(start 73.246742 -279.753314)
		(end 75.963526 -279.753314)
		(width 0.14478)
		(layer "In2.Cu")
		(net "M_C_CPU1_SB_DQ<9>")
	)
	(segment
		(start 46.036738 -292.573964)
		(end 46.199552 -292.736778)
		(width 0.14478)
		(layer "In2.Cu")
		(net "M_C_CPU1_SB_DQ<9>")
	)
	(segment
		(start 68.252848 -284.509464)
		(end 68.490592 -284.509464)
		(width 0.14478)
		(layer "In2.Cu")
		(net "M_C_CPU1_SB_DQ<9>")
	)
	(segment
		(start 76.792074 -279.996392)
		(end 78.711044 -279.996392)
		(width 0.0889)
		(layer "In2.Cu")
		(net "M_C_CPU1_SB_DQ<9>")
	)
	(segment
		(start 90.639646 -280.083768)
		(end 90.648028 -280.078942)
		(width 0.0889)
		(layer "In2.Cu")
		(net "M_C_CPU1_SB_DQ<9>")
	)
	(segment
		(start 59.191398 -292.11016)
		(end 59.643264 -292.11016)
		(width 0.14478)
		(layer "In2.Cu")
		(net "M_C_CPU1_SB_DQ<9>")
	)
	(segment
		(start 50.793142 -292.33749)
		(end 50.793142 -291.902642)
		(width 0.14478)
		(layer "In2.Cu")
		(net "M_C_CPU1_SB_DQ<9>")
	)
	(segment
		(start 44.87418 -292.960298)
		(end 45.249846 -293.335964)
		(width 0.14478)
		(layer "In2.Cu")
		(net "M_C_CPU1_SB_DQ<9>")
	)
	(segment
		(start 79.349346 -280.091896)
		(end 79.371698 -280.078942)
		(width 0.0889)
		(layer "In2.Cu")
		(net "M_C_CPU1_SB_DQ<9>")
	)
	(segment
		(start 68.490592 -284.509464)
		(end 73.246742 -279.753314)
		(width 0.14478)
		(layer "In2.Cu")
		(net "M_C_CPU1_SB_DQ<9>")
	)
	(segment
		(start 95.339662 -280.083768)
		(end 95.348044 -280.078942)
		(width 0.0889)
		(layer "In2.Cu")
		(net "M_C_CPU1_SB_DQ<9>")
	)
	(segment
		(start 52.426616 -291.735764)
		(end 52.657248 -291.735764)
		(width 0.14478)
		(layer "In2.Cu")
		(net "M_C_CPU1_SB_DQ<9>")
	)
	(segment
		(start 46.362366 -293.335964)
		(end 46.592998 -293.335964)
		(width 0.14478)
		(layer "In2.Cu")
		(net "M_C_CPU1_SB_DQ<9>")
	)
	(segment
		(start 46.755812 -293.17315)
		(end 46.755812 -292.736778)
		(width 0.14478)
		(layer "In2.Cu")
		(net "M_C_CPU1_SB_DQ<9>")
	)
	(segment
		(start 75.963526 -279.753314)
		(end 76.548996 -279.753314)
		(width 0.0889)
		(layer "In2.Cu")
		(net "M_C_CPU1_SB_DQ<9>")
	)
	(segment
		(start 79.935578 -280.078688)
		(end 79.96047 -280.092912)
		(width 0.0889)
		(layer "In2.Cu")
		(net "M_C_CPU1_SB_DQ<9>")
	)
	(segment
		(start 86.879684 -280.083768)
		(end 86.888066 -280.078942)
		(width 0.0889)
		(layer "In2.Cu")
		(net "M_C_CPU1_SB_DQ<9>")
	)
	(segment
		(start 45.643292 -292.736778)
		(end 45.806106 -292.573964)
		(width 0.14478)
		(layer "In2.Cu")
		(net "M_C_CPU1_SB_DQ<9>")
	)
	(segment
		(start 51.235102 -291.761164)
		(end 51.584098 -292.11016)
		(width 0.14478)
		(layer "In2.Cu")
		(net "M_C_CPU1_SB_DQ<9>")
	)
	(segment
		(start 91.5797 -280.083768)
		(end 91.588082 -280.078942)
		(width 0.0889)
		(layer "In2.Cu")
		(net "M_C_CPU1_SB_DQ<9>")
	)
	(segment
		(start 50.634392 -292.49624)
		(end 50.793142 -292.33749)
		(width 0.14478)
		(layer "In2.Cu")
		(net "M_C_CPU1_SB_DQ<9>")
	)
	(segment
		(start 46.199552 -293.17315)
		(end 46.362366 -293.335964)
		(width 0.14478)
		(layer "In2.Cu")
		(net "M_C_CPU1_SB_DQ<9>")
	)
	(segment
		(start 59.802268 -291.951156)
		(end 59.802268 -291.87521)
		(width 0.14478)
		(layer "In2.Cu")
		(net "M_C_CPU1_SB_DQ<9>")
	)
	(segment
		(start 53.783992 -292.139624)
		(end 53.880258 -292.23589)
		(width 0.14478)
		(layer "In2.Cu")
		(net "M_C_CPU1_SB_DQ<9>")
	)
	(segment
		(start 57.75071 -292.218364)
		(end 58.03011 -292.497764)
		(width 0.14478)
		(layer "In2.Cu")
		(net "M_C_CPU1_SB_DQ<9>")
	)
	(segment
		(start 82.753962 -280.078942)
		(end 82.762344 -280.083768)
		(width 0.0889)
		(layer "In2.Cu")
		(net "M_C_CPU1_SB_DQ<9>")
	)
	(segment
		(start 60.809886 -291.952426)
		(end 68.252848 -284.509464)
		(width 0.14478)
		(layer "In2.Cu")
		(net "M_C_CPU1_SB_DQ<9>")
	)
	(segment
		(start 58.260742 -292.497764)
		(end 58.423556 -292.33495)
		(width 0.14478)
		(layer "In2.Cu")
		(net "M_C_CPU1_SB_DQ<9>")
	)
	(segment
		(start 50.793142 -291.902642)
		(end 50.93462 -291.761164)
		(width 0.14478)
		(layer "In2.Cu")
		(net "M_C_CPU1_SB_DQ<9>")
	)
	(segment
		(start 53.880258 -292.23589)
		(end 53.880258 -292.696138)
		(width 0.14478)
		(layer "In2.Cu")
		(net "M_C_CPU1_SB_DQ<9>")
	)
	(segment
		(start 59.963812 -291.713666)
		(end 60.192158 -291.713666)
		(width 0.14478)
		(layer "In2.Cu")
		(net "M_C_CPU1_SB_DQ<9>")
	)
	(segment
		(start 60.430918 -291.952426)
		(end 60.809886 -291.952426)
		(width 0.14478)
		(layer "In2.Cu")
		(net "M_C_CPU1_SB_DQ<9>")
	)
	(segment
		(start 60.192158 -291.713666)
		(end 60.430918 -291.952426)
		(width 0.14478)
		(layer "In2.Cu")
		(net "M_C_CPU1_SB_DQ<9>")
	)
	(segment
		(start 51.584098 -292.11016)
		(end 52.05222 -292.11016)
		(width 0.14478)
		(layer "In2.Cu")
		(net "M_C_CPU1_SB_DQ<9>")
	)
	(segment
		(start 47.149258 -292.573964)
		(end 47.535592 -292.960298)
		(width 0.14478)
		(layer "In2.Cu")
		(net "M_C_CPU1_SB_DQ<9>")
	)
	(segment
		(start 58.423556 -292.33495)
		(end 58.423556 -291.898578)
		(width 0.14478)
		(layer "In2.Cu")
		(net "M_C_CPU1_SB_DQ<9>")
	)
	(segment
		(start 47.535592 -292.960298)
		(end 49.592484 -292.960298)
		(width 0.14478)
		(layer "In2.Cu")
		(net "M_C_CPU1_SB_DQ<9>")
	)
	(segment
		(start 46.592998 -293.335964)
		(end 46.755812 -293.17315)
		(width 0.14478)
		(layer "In2.Cu")
		(net "M_C_CPU1_SB_DQ<9>")
	)
	(segment
		(start 79.909416 -280.063702)
		(end 79.935578 -280.078688)
		(width 0.0889)
		(layer "In2.Cu")
		(net "M_C_CPU1_SB_DQ<9>")
	)
	(segment
		(start 76.548996 -279.753314)
		(end 76.792074 -279.996392)
		(width 0.0889)
		(layer "In2.Cu")
		(net "M_C_CPU1_SB_DQ<9>")
	)
	(segment
		(start 85.93963 -280.083768)
		(end 85.948012 -280.078942)
		(width 0.0889)
		(layer "In2.Cu")
		(net "M_C_CPU1_SB_DQ<9>")
	)
	(segment
		(start 52.820062 -291.898578)
		(end 52.820062 -292.33495)
		(width 0.14478)
		(layer "In2.Cu")
		(net "M_C_CPU1_SB_DQ<9>")
	)
	(segment
		(start 53.571648 -292.139624)
		(end 53.783992 -292.139624)
		(width 0.14478)
		(layer "In2.Cu")
		(net "M_C_CPU1_SB_DQ<9>")
	)
	(segment
		(start 95.85071 -280.047192)
		(end 95.946976 -280.021792)
		(width 0.0889)
		(layer "In2.Cu")
		(net "M_C_CPU1_SB_DQ<9>")
	)
	(segment
		(start 50.056542 -292.49624)
		(end 50.634392 -292.49624)
		(width 0.14478)
		(layer "In2.Cu")
		(net "M_C_CPU1_SB_DQ<9>")
	)
	(segment
		(start 56.746394 -292.960298)
		(end 57.488328 -292.218364)
		(width 0.14478)
		(layer "In2.Cu")
		(net "M_C_CPU1_SB_DQ<9>")
	)
	(segment
		(start 49.592484 -292.960298)
		(end 50.056542 -292.49624)
		(width 0.14478)
		(layer "In2.Cu")
		(net "M_C_CPU1_SB_DQ<9>")
	)
	(segment
		(start 83.694016 -280.078942)
		(end 83.702398 -280.083768)
		(width 0.0889)
		(layer "In2.Cu")
		(net "M_C_CPU1_SB_DQ<9>")
	)
	(segment
		(start 52.05222 -292.11016)
		(end 52.426616 -291.735764)
		(width 0.14478)
		(layer "In2.Cu")
		(net "M_C_CPU1_SB_DQ<9>")
	)
	(segment
		(start 59.643264 -292.11016)
		(end 59.802268 -291.951156)
		(width 0.14478)
		(layer "In2.Cu")
		(net "M_C_CPU1_SB_DQ<9>")
	)
	(segment
		(start 45.480478 -293.335964)
		(end 45.643292 -293.17315)
		(width 0.14478)
		(layer "In2.Cu")
		(net "M_C_CPU1_SB_DQ<9>")
	)
	(segment
		(start 58.423556 -291.898578)
		(end 58.58637 -291.735764)
		(width 0.14478)
		(layer "In2.Cu")
		(net "M_C_CPU1_SB_DQ<9>")
	)
	(segment
		(start 46.755812 -292.736778)
		(end 46.918626 -292.573964)
		(width 0.14478)
		(layer "In2.Cu")
		(net "M_C_CPU1_SB_DQ<9>")
	)
	(segment
		(start 44.76496 -292.960298)
		(end 44.87418 -292.960298)
		(width 0.14478)
		(layer "In2.Cu")
		(net "M_C_CPU1_SB_DQ<9>")
	)
	(segment
		(start 59.802268 -291.87521)
		(end 59.963812 -291.713666)
		(width 0.14478)
		(layer "In2.Cu")
		(net "M_C_CPU1_SB_DQ<9>")
	)
	(segment
		(start 82.179668 -280.083768)
		(end 82.18805 -280.078942)
		(width 0.0889)
		(layer "In2.Cu")
		(net "M_C_CPU1_SB_DQ<9>")
	)
	(segment
		(start 53.880258 -292.696138)
		(end 54.144418 -292.960298)
		(width 0.14478)
		(layer "In2.Cu")
		(net "M_C_CPU1_SB_DQ<9>")
	)
	(segment
		(start 95.946976 -280.021792)
		(end 96.101154 -279.756362)
		(width 0.0889)
		(layer "In2.Cu")
		(net "M_C_CPU1_SB_DQ<9>")
	)
	(segment
		(start 52.657248 -291.735764)
		(end 52.820062 -291.898578)
		(width 0.14478)
		(layer "In2.Cu")
		(net "M_C_CPU1_SB_DQ<9>")
	)
	(segment
		(start 50.93462 -291.761164)
		(end 51.235102 -291.761164)
		(width 0.14478)
		(layer "In2.Cu")
		(net "M_C_CPU1_SB_DQ<9>")
	)
	(segment
		(start 45.249846 -293.335964)
		(end 45.480478 -293.335964)
		(width 0.14478)
		(layer "In2.Cu")
		(net "M_C_CPU1_SB_DQ<9>")
	)
	(segment
		(start 87.453978 -280.078942)
		(end 87.46236 -280.083768)
		(width 0.0889)
		(layer "In2.Cu")
		(net "M_C_CPU1_SB_DQ<9>")
	)
	(segment
		(start 54.144418 -292.960298)
		(end 56.746394 -292.960298)
		(width 0.14478)
		(layer "In2.Cu")
		(net "M_C_CPU1_SB_DQ<9>")
	)
	(arc
		(start 85.57387 -280.078942)
		(mid 85.756121 -280.129292)
		(end 85.93963 -280.083768)
		(width 0.0889)
		(layer "In2.Cu")
		(net "M_C_CPU1_SB_DQ<9>")
	)
	(arc
		(start 90.273886 -280.078942)
		(mid 90.456137 -280.129292)
		(end 90.639646 -280.083768)
		(width 0.0889)
		(layer "In2.Cu")
		(net "M_C_CPU1_SB_DQ<9>")
	)
	(arc
		(start 82.762344 -280.083768)
		(mid 82.945852 -280.129262)
		(end 83.128104 -280.078942)
		(width 0.0889)
		(layer "In2.Cu")
		(net "M_C_CPU1_SB_DQ<9>")
	)
	(arc
		(start 94.973902 -280.078942)
		(mid 95.156153 -280.129292)
		(end 95.339662 -280.083768)
		(width 0.0889)
		(layer "In2.Cu")
		(net "M_C_CPU1_SB_DQ<9>")
	)
	(arc
		(start 91.588082 -280.078942)
		(mid 91.871038 -280.002765)
		(end 92.153994 -280.078942)
		(width 0.0889)
		(layer "In2.Cu")
		(net "M_C_CPU1_SB_DQ<9>")
	)
	(arc
		(start 83.128104 -280.078942)
		(mid 83.41106 -280.002765)
		(end 83.694016 -280.078942)
		(width 0.0889)
		(layer "In2.Cu")
		(net "M_C_CPU1_SB_DQ<9>")
	)
	(arc
		(start 88.402414 -280.083768)
		(mid 88.585922 -280.129262)
		(end 88.768174 -280.078942)
		(width 0.0889)
		(layer "In2.Cu")
		(net "M_C_CPU1_SB_DQ<9>")
	)
	(arc
		(start 92.528136 -280.078942)
		(mid 92.811092 -280.002765)
		(end 93.094048 -280.078942)
		(width 0.0889)
		(layer "In2.Cu")
		(net "M_C_CPU1_SB_DQ<9>")
	)
	(arc
		(start 91.21394 -280.078942)
		(mid 91.396191 -280.129292)
		(end 91.5797 -280.083768)
		(width 0.0889)
		(layer "In2.Cu")
		(net "M_C_CPU1_SB_DQ<9>")
	)
	(arc
		(start 84.63407 -280.078942)
		(mid 84.821014 -280.129197)
		(end 85.007958 -280.078942)
		(width 0.0889)
		(layer "In2.Cu")
		(net "M_C_CPU1_SB_DQ<9>")
	)
	(arc
		(start 85.007958 -280.078942)
		(mid 85.290914 -280.002765)
		(end 85.57387 -280.078942)
		(width 0.0889)
		(layer "In2.Cu")
		(net "M_C_CPU1_SB_DQ<9>")
	)
	(arc
		(start 86.513924 -280.078942)
		(mid 86.696175 -280.129292)
		(end 86.879684 -280.083768)
		(width 0.0889)
		(layer "In2.Cu")
		(net "M_C_CPU1_SB_DQ<9>")
	)
	(arc
		(start 86.888066 -280.078942)
		(mid 87.171022 -280.002765)
		(end 87.453978 -280.078942)
		(width 0.0889)
		(layer "In2.Cu")
		(net "M_C_CPU1_SB_DQ<9>")
	)
	(arc
		(start 93.10243 -280.083768)
		(mid 93.285938 -280.129262)
		(end 93.46819 -280.078942)
		(width 0.0889)
		(layer "In2.Cu")
		(net "M_C_CPU1_SB_DQ<9>")
	)
	(arc
		(start 78.711044 -279.996392)
		(mid 78.84987 -280.014866)
		(end 78.979014 -280.069036)
		(width 0.0889)
		(layer "In2.Cu")
		(net "M_C_CPU1_SB_DQ<9>")
	)
	(arc
		(start 92.162376 -280.083768)
		(mid 92.345884 -280.129262)
		(end 92.528136 -280.078942)
		(width 0.0889)
		(layer "In2.Cu")
		(net "M_C_CPU1_SB_DQ<9>")
	)
	(arc
		(start 83.702398 -280.083768)
		(mid 83.885906 -280.129262)
		(end 84.068158 -280.078942)
		(width 0.0889)
		(layer "In2.Cu")
		(net "M_C_CPU1_SB_DQ<9>")
	)
	(arc
		(start 79.96047 -280.092912)
		(mid 80.13605 -280.128932)
		(end 80.308196 -280.078942)
		(width 0.0889)
		(layer "In2.Cu")
		(net "M_C_CPU1_SB_DQ<9>")
	)
	(arc
		(start 80.308196 -280.078942)
		(mid 80.591152 -280.002765)
		(end 80.874108 -280.078942)
		(width 0.0889)
		(layer "In2.Cu")
		(net "M_C_CPU1_SB_DQ<9>")
	)
	(arc
		(start 79.371698 -280.078942)
		(mid 79.638628 -280.002993)
		(end 79.909416 -280.063702)
		(width 0.0889)
		(layer "In2.Cu")
		(net "M_C_CPU1_SB_DQ<9>")
	)
	(arc
		(start 94.034102 -280.078942)
		(mid 94.221046 -280.129197)
		(end 94.40799 -280.078942)
		(width 0.0889)
		(layer "In2.Cu")
		(net "M_C_CPU1_SB_DQ<9>")
	)
	(arc
		(start 87.46236 -280.083768)
		(mid 87.645868 -280.129262)
		(end 87.82812 -280.078942)
		(width 0.0889)
		(layer "In2.Cu")
		(net "M_C_CPU1_SB_DQ<9>")
	)
	(arc
		(start 88.768174 -280.078942)
		(mid 89.05113 -280.002765)
		(end 89.334086 -280.078942)
		(width 0.0889)
		(layer "In2.Cu")
		(net "M_C_CPU1_SB_DQ<9>")
	)
	(arc
		(start 93.46819 -280.078942)
		(mid 93.751146 -280.002765)
		(end 94.034102 -280.078942)
		(width 0.0889)
		(layer "In2.Cu")
		(net "M_C_CPU1_SB_DQ<9>")
	)
	(arc
		(start 90.648028 -280.078942)
		(mid 90.930984 -280.002765)
		(end 91.21394 -280.078942)
		(width 0.0889)
		(layer "In2.Cu")
		(net "M_C_CPU1_SB_DQ<9>")
	)
	(arc
		(start 82.18805 -280.078942)
		(mid 82.471006 -280.002765)
		(end 82.753962 -280.078942)
		(width 0.0889)
		(layer "In2.Cu")
		(net "M_C_CPU1_SB_DQ<9>")
	)
	(arc
		(start 84.068158 -280.078942)
		(mid 84.351114 -280.002765)
		(end 84.63407 -280.078942)
		(width 0.0889)
		(layer "In2.Cu")
		(net "M_C_CPU1_SB_DQ<9>")
	)
	(arc
		(start 81.813908 -280.078942)
		(mid 81.996159 -280.129292)
		(end 82.179668 -280.083768)
		(width 0.0889)
		(layer "In2.Cu")
		(net "M_C_CPU1_SB_DQ<9>")
	)
	(arc
		(start 94.40799 -280.078942)
		(mid 94.690946 -280.002765)
		(end 94.973902 -280.078942)
		(width 0.0889)
		(layer "In2.Cu")
		(net "M_C_CPU1_SB_DQ<9>")
	)
	(arc
		(start 80.874108 -280.078942)
		(mid 81.061052 -280.129197)
		(end 81.247996 -280.078942)
		(width 0.0889)
		(layer "In2.Cu")
		(net "M_C_CPU1_SB_DQ<9>")
	)
	(arc
		(start 78.996032 -280.078942)
		(mid 79.17106 -280.129841)
		(end 79.349346 -280.091896)
		(width 0.0889)
		(layer "In2.Cu")
		(net "M_C_CPU1_SB_DQ<9>")
	)
	(arc
		(start 95.348044 -280.078942)
		(mid 95.59564 -280.003764)
		(end 95.85071 -280.047192)
		(width 0.0889)
		(layer "In2.Cu")
		(net "M_C_CPU1_SB_DQ<9>")
	)
	(arc
		(start 87.82812 -280.078942)
		(mid 88.111076 -280.002765)
		(end 88.394032 -280.078942)
		(width 0.0889)
		(layer "In2.Cu")
		(net "M_C_CPU1_SB_DQ<9>")
	)
	(arc
		(start 85.948012 -280.078942)
		(mid 86.230968 -280.002765)
		(end 86.513924 -280.078942)
		(width 0.0889)
		(layer "In2.Cu")
		(net "M_C_CPU1_SB_DQ<9>")
	)
	(arc
		(start 81.247996 -280.078942)
		(mid 81.530952 -280.002765)
		(end 81.813908 -280.078942)
		(width 0.0889)
		(layer "In2.Cu")
		(net "M_C_CPU1_SB_DQ<9>")
	)
	(arc
		(start 89.707974 -280.078942)
		(mid 89.99093 -280.002765)
		(end 90.273886 -280.078942)
		(width 0.0889)
		(layer "In2.Cu")
		(net "M_C_CPU1_SB_DQ<9>")
	)
	(arc
		(start 89.334086 -280.078942)
		(mid 89.52103 -280.129197)
		(end 89.707974 -280.078942)
		(width 0.0889)
		(layer "In2.Cu")
		(net "M_C_CPU1_SB_DQ<9>")
	)
	(segment
		(start 95.157798 -278.680418)
		(end 94.690946 -278.946356)
		(width 0.10668)
		(layer "F.Cu")
		(net "M_C_CPU1_SB_DQ<8>")
	)
	(segment
		(start 53.217064 -290.777676)
		(end 53.217064 -291.008054)
		(width 0.14478)
		(layer "In2.Cu")
		(net "M_C_CPU1_SB_DQ<8>")
	)
	(segment
		(start 49.224692 -292.046406)
		(end 49.38776 -291.883338)
		(width 0.14478)
		(layer "In2.Cu")
		(net "M_C_CPU1_SB_DQ<8>")
	)
	(segment
		(start 45.54855 -291.487606)
		(end 45.54855 -291.152834)
		(width 0.14478)
		(layer "In2.Cu")
		(net "M_C_CPU1_SB_DQ<8>")
	)
	(segment
		(start 54.35092 -291.207698)
		(end 54.59095 -290.967668)
		(width 0.14478)
		(layer "In2.Cu")
		(net "M_C_CPU1_SB_DQ<8>")
	)
	(segment
		(start 51.31562 -290.135564)
		(end 51.590448 -290.410392)
		(width 0.14478)
		(layer "In2.Cu")
		(net "M_C_CPU1_SB_DQ<8>")
	)
	(segment
		(start 80.769714 -279.273762)
		(end 80.778096 -279.268936)
		(width 0.0889)
		(layer "In2.Cu")
		(net "M_C_CPU1_SB_DQ<8>")
	)
	(segment
		(start 53.746654 -291.035232)
		(end 53.976524 -291.035232)
		(width 0.14478)
		(layer "In2.Cu")
		(net "M_C_CPU1_SB_DQ<8>")
	)
	(segment
		(start 89.229692 -279.273762)
		(end 89.238074 -279.268936)
		(width 0.0889)
		(layer "In2.Cu")
		(net "M_C_CPU1_SB_DQ<8>")
	)
	(segment
		(start 55.127906 -291.273738)
		(end 55.647844 -291.273738)
		(width 0.14478)
		(layer "In2.Cu")
		(net "M_C_CPU1_SB_DQ<8>")
	)
	(segment
		(start 57.80024 -291.049964)
		(end 58.028586 -290.821618)
		(width 0.14478)
		(layer "In2.Cu")
		(net "M_C_CPU1_SB_DQ<8>")
	)
	(segment
		(start 49.38776 -291.423598)
		(end 49.550828 -291.26053)
		(width 0.14478)
		(layer "In2.Cu")
		(net "M_C_CPU1_SB_DQ<8>")
	)
	(segment
		(start 71.475346 -280.2509)
		(end 71.475346 -280.01468)
		(width 0.14478)
		(layer "In2.Cu")
		(net "M_C_CPU1_SB_DQ<8>")
	)
	(segment
		(start 55.922418 -290.999164)
		(end 56.265826 -290.999164)
		(width 0.14478)
		(layer "In2.Cu")
		(net "M_C_CPU1_SB_DQ<8>")
	)
	(segment
		(start 81.344008 -279.268936)
		(end 81.35239 -279.273762)
		(width 0.0889)
		(layer "In2.Cu")
		(net "M_C_CPU1_SB_DQ<8>")
	)
	(segment
		(start 53.976524 -291.035232)
		(end 54.14899 -291.207698)
		(width 0.14478)
		(layer "In2.Cu")
		(net "M_C_CPU1_SB_DQ<8>")
	)
	(segment
		(start 55.647844 -291.273738)
		(end 55.922418 -290.999164)
		(width 0.14478)
		(layer "In2.Cu")
		(net "M_C_CPU1_SB_DQ<8>")
	)
	(segment
		(start 92.989654 -279.273762)
		(end 92.998036 -279.268936)
		(width 0.0889)
		(layer "In2.Cu")
		(net "M_C_CPU1_SB_DQ<8>")
	)
	(segment
		(start 53.217064 -291.008054)
		(end 53.380386 -291.171376)
		(width 0.14478)
		(layer "In2.Cu")
		(net "M_C_CPU1_SB_DQ<8>")
	)
	(segment
		(start 54.59095 -290.967668)
		(end 54.821836 -290.967668)
		(width 0.14478)
		(layer "In2.Cu")
		(net "M_C_CPU1_SB_DQ<8>")
	)
	(segment
		(start 89.803986 -279.268936)
		(end 89.812368 -279.273762)
		(width 0.0889)
		(layer "In2.Cu")
		(net "M_C_CPU1_SB_DQ<8>")
	)
	(segment
		(start 79.439516 -279.252934)
		(end 79.467202 -279.268936)
		(width 0.0889)
		(layer "In2.Cu")
		(net "M_C_CPU1_SB_DQ<8>")
	)
	(segment
		(start 50.230786 -290.795964)
		(end 50.591466 -290.795964)
		(width 0.14478)
		(layer "In2.Cu")
		(net "M_C_CPU1_SB_DQ<8>")
	)
	(segment
		(start 86.044024 -279.268936)
		(end 86.052406 -279.273762)
		(width 0.0889)
		(layer "In2.Cu")
		(net "M_C_CPU1_SB_DQ<8>")
	)
	(segment
		(start 93.929708 -279.273762)
		(end 93.93809 -279.268936)
		(width 0.0889)
		(layer "In2.Cu")
		(net "M_C_CPU1_SB_DQ<8>")
	)
	(segment
		(start 69.406516 -282.08351)
		(end 69.642736 -282.08351)
		(width 0.14478)
		(layer "In2.Cu")
		(net "M_C_CPU1_SB_DQ<8>")
	)
	(segment
		(start 48.831246 -291.883338)
		(end 48.994314 -292.046406)
		(width 0.14478)
		(layer "In2.Cu")
		(net "M_C_CPU1_SB_DQ<8>")
	)
	(segment
		(start 76.042266 -278.843994)
		(end 77.600048 -278.843994)
		(width 0.0889)
		(layer "In2.Cu")
		(net "M_C_CPU1_SB_DQ<8>")
	)
	(segment
		(start 45.711364 -290.99002)
		(end 45.941996 -290.99002)
		(width 0.14478)
		(layer "In2.Cu")
		(net "M_C_CPU1_SB_DQ<8>")
	)
	(segment
		(start 45.155104 -291.65042)
		(end 45.385736 -291.65042)
		(width 0.14478)
		(layer "In2.Cu")
		(net "M_C_CPU1_SB_DQ<8>")
	)
	(segment
		(start 72.255634 -279.470612)
		(end 72.255634 -279.234392)
		(width 0.14478)
		(layer "In2.Cu")
		(net "M_C_CPU1_SB_DQ<8>")
	)
	(segment
		(start 90.74404 -279.268936)
		(end 90.752422 -279.273762)
		(width 0.0889)
		(layer "In2.Cu")
		(net "M_C_CPU1_SB_DQ<8>")
	)
	(segment
		(start 57.370472 -291.049964)
		(end 57.80024 -291.049964)
		(width 0.14478)
		(layer "In2.Cu")
		(net "M_C_CPU1_SB_DQ<8>")
	)
	(segment
		(start 48.831246 -291.158422)
		(end 48.831246 -291.883338)
		(width 0.14478)
		(layer "In2.Cu")
		(net "M_C_CPU1_SB_DQ<8>")
	)
	(segment
		(start 46.267624 -291.65042)
		(end 46.498256 -291.65042)
		(width 0.14478)
		(layer "In2.Cu")
		(net "M_C_CPU1_SB_DQ<8>")
	)
	(segment
		(start 46.498256 -291.65042)
		(end 46.66107 -291.487606)
		(width 0.14478)
		(layer "In2.Cu")
		(net "M_C_CPU1_SB_DQ<8>")
	)
	(segment
		(start 45.54855 -291.152834)
		(end 45.711364 -290.99002)
		(width 0.14478)
		(layer "In2.Cu")
		(net "M_C_CPU1_SB_DQ<8>")
	)
	(segment
		(start 70.186804 -281.303222)
		(end 70.423024 -281.303222)
		(width 0.14478)
		(layer "In2.Cu")
		(net "M_C_CPU1_SB_DQ<8>")
	)
	(segment
		(start 46.66107 -291.487606)
		(end 46.66107 -291.152834)
		(width 0.14478)
		(layer "In2.Cu")
		(net "M_C_CPU1_SB_DQ<8>")
	)
	(segment
		(start 45.941996 -290.99002)
		(end 46.10481 -291.152834)
		(width 0.14478)
		(layer "In2.Cu")
		(net "M_C_CPU1_SB_DQ<8>")
	)
	(segment
		(start 69.134482 -282.355544)
		(end 69.406516 -282.08351)
		(width 0.14478)
		(layer "In2.Cu")
		(net "M_C_CPU1_SB_DQ<8>")
	)
	(segment
		(start 52.700682 -290.135564)
		(end 53.076856 -290.135564)
		(width 0.14478)
		(layer "In2.Cu")
		(net "M_C_CPU1_SB_DQ<8>")
	)
	(segment
		(start 85.10397 -279.268936)
		(end 85.112352 -279.273762)
		(width 0.0889)
		(layer "In2.Cu")
		(net "M_C_CPU1_SB_DQ<8>")
	)
	(segment
		(start 53.61051 -291.171376)
		(end 53.746654 -291.035232)
		(width 0.14478)
		(layer "In2.Cu")
		(net "M_C_CPU1_SB_DQ<8>")
	)
	(segment
		(start 69.134482 -282.591764)
		(end 69.134482 -282.355544)
		(width 0.14478)
		(layer "In2.Cu")
		(net "M_C_CPU1_SB_DQ<8>")
	)
	(segment
		(start 47.495206 -291.26053)
		(end 48.008286 -291.26053)
		(width 0.14478)
		(layer "In2.Cu")
		(net "M_C_CPU1_SB_DQ<8>")
	)
	(segment
		(start 71.203312 -280.522934)
		(end 71.475346 -280.2509)
		(width 0.14478)
		(layer "In2.Cu")
		(net "M_C_CPU1_SB_DQ<8>")
	)
	(segment
		(start 50.591466 -290.795964)
		(end 50.741326 -290.646104)
		(width 0.14478)
		(layer "In2.Cu")
		(net "M_C_CPU1_SB_DQ<8>")
	)
	(segment
		(start 71.74738 -279.742646)
		(end 71.9836 -279.742646)
		(width 0.14478)
		(layer "In2.Cu")
		(net "M_C_CPU1_SB_DQ<8>")
	)
	(segment
		(start 58.028586 -290.39185)
		(end 58.259472 -290.160964)
		(width 0.14478)
		(layer "In2.Cu")
		(net "M_C_CPU1_SB_DQ<8>")
	)
	(segment
		(start 69.91477 -281.811476)
		(end 69.91477 -281.575256)
		(width 0.14478)
		(layer "In2.Cu")
		(net "M_C_CPU1_SB_DQ<8>")
	)
	(segment
		(start 53.380386 -291.171376)
		(end 53.61051 -291.171376)
		(width 0.14478)
		(layer "In2.Cu")
		(net "M_C_CPU1_SB_DQ<8>")
	)
	(segment
		(start 72.646032 -278.843994)
		(end 76.042266 -278.843994)
		(width 0.14478)
		(layer "In2.Cu")
		(net "M_C_CPU1_SB_DQ<8>")
	)
	(segment
		(start 94.537022 -279.211786)
		(end 94.690946 -278.946356)
		(width 0.0889)
		(layer "In2.Cu")
		(net "M_C_CPU1_SB_DQ<8>")
	)
	(segment
		(start 48.994314 -292.046406)
		(end 49.224692 -292.046406)
		(width 0.14478)
		(layer "In2.Cu")
		(net "M_C_CPU1_SB_DQ<8>")
	)
	(segment
		(start 48.64481 -290.971986)
		(end 48.831246 -291.158422)
		(width 0.14478)
		(layer "In2.Cu")
		(net "M_C_CPU1_SB_DQ<8>")
	)
	(segment
		(start 56.851296 -291.56914)
		(end 57.370472 -291.049964)
		(width 0.14478)
		(layer "In2.Cu")
		(net "M_C_CPU1_SB_DQ<8>")
	)
	(segment
		(start 46.66107 -291.152834)
		(end 46.84014 -290.973764)
		(width 0.14478)
		(layer "In2.Cu")
		(net "M_C_CPU1_SB_DQ<8>")
	)
	(segment
		(start 71.475346 -280.01468)
		(end 71.74738 -279.742646)
		(width 0.14478)
		(layer "In2.Cu")
		(net "M_C_CPU1_SB_DQ<8>")
	)
	(segment
		(start 70.967092 -280.522934)
		(end 71.203312 -280.522934)
		(width 0.14478)
		(layer "In2.Cu")
		(net "M_C_CPU1_SB_DQ<8>")
	)
	(segment
		(start 59.100974 -290.410392)
		(end 59.872118 -290.410392)
		(width 0.14478)
		(layer "In2.Cu")
		(net "M_C_CPU1_SB_DQ<8>")
	)
	(segment
		(start 53.076856 -290.135564)
		(end 53.352954 -290.411662)
		(width 0.14478)
		(layer "In2.Cu")
		(net "M_C_CPU1_SB_DQ<8>")
	)
	(segment
		(start 78.711044 -279.313132)
		(end 78.73619 -279.313132)
		(width 0.0889)
		(layer "In2.Cu")
		(net "M_C_CPU1_SB_DQ<8>")
	)
	(segment
		(start 45.385736 -291.65042)
		(end 45.54855 -291.487606)
		(width 0.14478)
		(layer "In2.Cu")
		(net "M_C_CPU1_SB_DQ<8>")
	)
	(segment
		(start 70.695058 -280.794968)
		(end 70.967092 -280.522934)
		(width 0.14478)
		(layer "In2.Cu")
		(net "M_C_CPU1_SB_DQ<8>")
	)
	(segment
		(start 50.891186 -290.135564)
		(end 51.31562 -290.135564)
		(width 0.14478)
		(layer "In2.Cu")
		(net "M_C_CPU1_SB_DQ<8>")
	)
	(segment
		(start 83.589622 -279.273762)
		(end 83.598004 -279.268936)
		(width 0.0889)
		(layer "In2.Cu")
		(net "M_C_CPU1_SB_DQ<8>")
	)
	(segment
		(start 69.91477 -281.575256)
		(end 70.186804 -281.303222)
		(width 0.14478)
		(layer "In2.Cu")
		(net "M_C_CPU1_SB_DQ<8>")
	)
	(segment
		(start 71.9836 -279.742646)
		(end 72.255634 -279.470612)
		(width 0.14478)
		(layer "In2.Cu")
		(net "M_C_CPU1_SB_DQ<8>")
	)
	(segment
		(start 58.851546 -290.160964)
		(end 59.100974 -290.410392)
		(width 0.14478)
		(layer "In2.Cu")
		(net "M_C_CPU1_SB_DQ<8>")
	)
	(segment
		(start 69.642736 -282.08351)
		(end 69.91477 -281.811476)
		(width 0.14478)
		(layer "In2.Cu")
		(net "M_C_CPU1_SB_DQ<8>")
	)
	(segment
		(start 46.10481 -291.487606)
		(end 46.267624 -291.65042)
		(width 0.14478)
		(layer "In2.Cu")
		(net "M_C_CPU1_SB_DQ<8>")
	)
	(segment
		(start 88.289638 -279.273762)
		(end 88.29802 -279.268936)
		(width 0.0889)
		(layer "In2.Cu")
		(net "M_C_CPU1_SB_DQ<8>")
	)
	(segment
		(start 48.008286 -291.26053)
		(end 48.29683 -290.971986)
		(width 0.14478)
		(layer "In2.Cu")
		(net "M_C_CPU1_SB_DQ<8>")
	)
	(segment
		(start 58.028586 -290.821618)
		(end 58.028586 -290.39185)
		(width 0.14478)
		(layer "In2.Cu")
		(net "M_C_CPU1_SB_DQ<8>")
	)
	(segment
		(start 54.14899 -291.207698)
		(end 54.35092 -291.207698)
		(width 0.14478)
		(layer "In2.Cu")
		(net "M_C_CPU1_SB_DQ<8>")
	)
	(segment
		(start 56.265826 -290.999164)
		(end 56.489346 -291.222684)
		(width 0.14478)
		(layer "In2.Cu")
		(net "M_C_CPU1_SB_DQ<8>")
	)
	(segment
		(start 44.340018 -290.835334)
		(end 45.155104 -291.65042)
		(width 0.14478)
		(layer "In2.Cu")
		(net "M_C_CPU1_SB_DQ<8>")
	)
	(segment
		(start 53.352954 -290.411662)
		(end 53.352954 -290.641786)
		(width 0.14478)
		(layer "In2.Cu")
		(net "M_C_CPU1_SB_DQ<8>")
	)
	(segment
		(start 79.83982 -279.268682)
		(end 79.863696 -279.254712)
		(width 0.0889)
		(layer "In2.Cu")
		(net "M_C_CPU1_SB_DQ<8>")
	)
	(segment
		(start 56.639206 -291.56914)
		(end 56.851296 -291.56914)
		(width 0.14478)
		(layer "In2.Cu")
		(net "M_C_CPU1_SB_DQ<8>")
	)
	(segment
		(start 49.765712 -291.26053)
		(end 49.765966 -291.260784)
		(width 0.14478)
		(layer "In2.Cu")
		(net "M_C_CPU1_SB_DQ<8>")
	)
	(segment
		(start 59.872118 -290.410392)
		(end 60.146946 -290.135564)
		(width 0.14478)
		(layer "In2.Cu")
		(net "M_C_CPU1_SB_DQ<8>")
	)
	(segment
		(start 50.741326 -290.285424)
		(end 50.891186 -290.135564)
		(width 0.14478)
		(layer "In2.Cu")
		(net "M_C_CPU1_SB_DQ<8>")
	)
	(segment
		(start 68.626228 -282.863798)
		(end 68.862448 -282.863798)
		(width 0.14478)
		(layer "In2.Cu")
		(net "M_C_CPU1_SB_DQ<8>")
	)
	(segment
		(start 78.246986 -279.111964)
		(end 78.262226 -279.127204)
		(width 0.0889)
		(layer "In2.Cu")
		(net "M_C_CPU1_SB_DQ<8>")
	)
	(segment
		(start 53.352954 -290.641786)
		(end 53.217064 -290.777676)
		(width 0.14478)
		(layer "In2.Cu")
		(net "M_C_CPU1_SB_DQ<8>")
	)
	(segment
		(start 52.425854 -290.410392)
		(end 52.700682 -290.135564)
		(width 0.14478)
		(layer "In2.Cu")
		(net "M_C_CPU1_SB_DQ<8>")
	)
	(segment
		(start 46.84014 -290.973764)
		(end 47.20844 -290.973764)
		(width 0.14478)
		(layer "In2.Cu")
		(net "M_C_CPU1_SB_DQ<8>")
	)
	(segment
		(start 72.255634 -279.234392)
		(end 72.646032 -278.843994)
		(width 0.14478)
		(layer "In2.Cu")
		(net "M_C_CPU1_SB_DQ<8>")
	)
	(segment
		(start 51.590448 -290.410392)
		(end 52.425854 -290.410392)
		(width 0.14478)
		(layer "In2.Cu")
		(net "M_C_CPU1_SB_DQ<8>")
	)
	(segment
		(start 70.695058 -281.031188)
		(end 70.695058 -280.794968)
		(width 0.14478)
		(layer "In2.Cu")
		(net "M_C_CPU1_SB_DQ<8>")
	)
	(segment
		(start 48.29683 -290.971986)
		(end 48.64481 -290.971986)
		(width 0.14478)
		(layer "In2.Cu")
		(net "M_C_CPU1_SB_DQ<8>")
	)
	(segment
		(start 58.259472 -290.160964)
		(end 58.851546 -290.160964)
		(width 0.14478)
		(layer "In2.Cu")
		(net "M_C_CPU1_SB_DQ<8>")
	)
	(segment
		(start 60.146946 -290.135564)
		(end 61.354462 -290.135564)
		(width 0.14478)
		(layer "In2.Cu")
		(net "M_C_CPU1_SB_DQ<8>")
	)
	(segment
		(start 54.821836 -290.967668)
		(end 55.127906 -291.273738)
		(width 0.14478)
		(layer "In2.Cu")
		(net "M_C_CPU1_SB_DQ<8>")
	)
	(segment
		(start 61.354462 -290.135564)
		(end 68.626228 -282.863798)
		(width 0.14478)
		(layer "In2.Cu")
		(net "M_C_CPU1_SB_DQ<8>")
	)
	(segment
		(start 49.38776 -291.883338)
		(end 49.38776 -291.423598)
		(width 0.14478)
		(layer "In2.Cu")
		(net "M_C_CPU1_SB_DQ<8>")
	)
	(segment
		(start 70.423024 -281.303222)
		(end 70.695058 -281.031188)
		(width 0.14478)
		(layer "In2.Cu")
		(net "M_C_CPU1_SB_DQ<8>")
	)
	(segment
		(start 56.489346 -291.41928)
		(end 56.639206 -291.56914)
		(width 0.14478)
		(layer "In2.Cu")
		(net "M_C_CPU1_SB_DQ<8>")
	)
	(segment
		(start 50.741326 -290.646104)
		(end 50.741326 -290.285424)
		(width 0.14478)
		(layer "In2.Cu")
		(net "M_C_CPU1_SB_DQ<8>")
	)
	(segment
		(start 68.862448 -282.863798)
		(end 69.134482 -282.591764)
		(width 0.14478)
		(layer "In2.Cu")
		(net "M_C_CPU1_SB_DQ<8>")
	)
	(segment
		(start 56.489346 -291.222684)
		(end 56.489346 -291.41928)
		(width 0.14478)
		(layer "In2.Cu")
		(net "M_C_CPU1_SB_DQ<8>")
	)
	(segment
		(start 47.20844 -290.973764)
		(end 47.495206 -291.26053)
		(width 0.14478)
		(layer "In2.Cu")
		(net "M_C_CPU1_SB_DQ<8>")
	)
	(segment
		(start 84.529676 -279.273762)
		(end 84.538058 -279.268936)
		(width 0.0889)
		(layer "In2.Cu")
		(net "M_C_CPU1_SB_DQ<8>")
	)
	(segment
		(start 79.817976 -279.281128)
		(end 79.83982 -279.268682)
		(width 0.0889)
		(layer "In2.Cu")
		(net "M_C_CPU1_SB_DQ<8>")
	)
	(segment
		(start 49.550828 -291.26053)
		(end 49.765712 -291.26053)
		(width 0.14478)
		(layer "In2.Cu")
		(net "M_C_CPU1_SB_DQ<8>")
	)
	(segment
		(start 49.765966 -291.260784)
		(end 50.230786 -290.795964)
		(width 0.14478)
		(layer "In2.Cu")
		(net "M_C_CPU1_SB_DQ<8>")
	)
	(segment
		(start 94.44101 -279.237186)
		(end 94.537022 -279.211786)
		(width 0.0889)
		(layer "In2.Cu")
		(net "M_C_CPU1_SB_DQ<8>")
	)
	(segment
		(start 46.10481 -291.152834)
		(end 46.10481 -291.487606)
		(width 0.14478)
		(layer "In2.Cu")
		(net "M_C_CPU1_SB_DQ<8>")
	)
	(arc
		(start 90.178128 -279.268936)
		(mid 90.461084 -279.192759)
		(end 90.74404 -279.268936)
		(width 0.0889)
		(layer "In2.Cu")
		(net "M_C_CPU1_SB_DQ<8>")
	)
	(arc
		(start 85.478112 -279.268936)
		(mid 85.761068 -279.192759)
		(end 86.044024 -279.268936)
		(width 0.0889)
		(layer "In2.Cu")
		(net "M_C_CPU1_SB_DQ<8>")
	)
	(arc
		(start 88.29802 -279.268936)
		(mid 88.580976 -279.192759)
		(end 88.863932 -279.268936)
		(width 0.0889)
		(layer "In2.Cu")
		(net "M_C_CPU1_SB_DQ<8>")
	)
	(arc
		(start 78.899512 -279.268936)
		(mid 79.167481 -279.192113)
		(end 79.439516 -279.252934)
		(width 0.0889)
		(layer "In2.Cu")
		(net "M_C_CPU1_SB_DQ<8>")
	)
	(arc
		(start 89.812368 -279.273762)
		(mid 89.995876 -279.319256)
		(end 90.178128 -279.268936)
		(width 0.0889)
		(layer "In2.Cu")
		(net "M_C_CPU1_SB_DQ<8>")
	)
	(arc
		(start 88.863932 -279.268936)
		(mid 89.046183 -279.319286)
		(end 89.229692 -279.273762)
		(width 0.0889)
		(layer "In2.Cu")
		(net "M_C_CPU1_SB_DQ<8>")
	)
	(arc
		(start 78.262226 -279.127204)
		(mid 78.468145 -279.264795)
		(end 78.711044 -279.313132)
		(width 0.0889)
		(layer "In2.Cu")
		(net "M_C_CPU1_SB_DQ<8>")
	)
	(arc
		(start 90.752422 -279.273762)
		(mid 90.93593 -279.319256)
		(end 91.118182 -279.268936)
		(width 0.0889)
		(layer "In2.Cu")
		(net "M_C_CPU1_SB_DQ<8>")
	)
	(arc
		(start 82.284062 -279.268936)
		(mid 82.471006 -279.319191)
		(end 82.65795 -279.268936)
		(width 0.0889)
		(layer "In2.Cu")
		(net "M_C_CPU1_SB_DQ<8>")
	)
	(arc
		(start 92.623894 -279.268936)
		(mid 92.806145 -279.319286)
		(end 92.989654 -279.273762)
		(width 0.0889)
		(layer "In2.Cu")
		(net "M_C_CPU1_SB_DQ<8>")
	)
	(arc
		(start 86.052406 -279.273762)
		(mid 86.235914 -279.319256)
		(end 86.418166 -279.268936)
		(width 0.0889)
		(layer "In2.Cu")
		(net "M_C_CPU1_SB_DQ<8>")
	)
	(arc
		(start 84.538058 -279.268936)
		(mid 84.821014 -279.192759)
		(end 85.10397 -279.268936)
		(width 0.0889)
		(layer "In2.Cu")
		(net "M_C_CPU1_SB_DQ<8>")
	)
	(arc
		(start 86.418166 -279.268936)
		(mid 86.701122 -279.192759)
		(end 86.984078 -279.268936)
		(width 0.0889)
		(layer "In2.Cu")
		(net "M_C_CPU1_SB_DQ<8>")
	)
	(arc
		(start 86.984078 -279.268936)
		(mid 87.171022 -279.319191)
		(end 87.357966 -279.268936)
		(width 0.0889)
		(layer "In2.Cu")
		(net "M_C_CPU1_SB_DQ<8>")
	)
	(arc
		(start 93.563948 -279.268936)
		(mid 93.746199 -279.319286)
		(end 93.929708 -279.273762)
		(width 0.0889)
		(layer "In2.Cu")
		(net "M_C_CPU1_SB_DQ<8>")
	)
	(arc
		(start 89.238074 -279.268936)
		(mid 89.52103 -279.192759)
		(end 89.803986 -279.268936)
		(width 0.0889)
		(layer "In2.Cu")
		(net "M_C_CPU1_SB_DQ<8>")
	)
	(arc
		(start 81.35239 -279.273762)
		(mid 81.535898 -279.319256)
		(end 81.71815 -279.268936)
		(width 0.0889)
		(layer "In2.Cu")
		(net "M_C_CPU1_SB_DQ<8>")
	)
	(arc
		(start 93.93809 -279.268936)
		(mid 94.185803 -279.193716)
		(end 94.44101 -279.237186)
		(width 0.0889)
		(layer "In2.Cu")
		(net "M_C_CPU1_SB_DQ<8>")
	)
	(arc
		(start 77.600048 -278.843994)
		(mid 77.950168 -278.913637)
		(end 78.246986 -279.111964)
		(width 0.0889)
		(layer "In2.Cu")
		(net "M_C_CPU1_SB_DQ<8>")
	)
	(arc
		(start 83.598004 -279.268936)
		(mid 83.88096 -279.192759)
		(end 84.163916 -279.268936)
		(width 0.0889)
		(layer "In2.Cu")
		(net "M_C_CPU1_SB_DQ<8>")
	)
	(arc
		(start 78.73619 -279.313132)
		(mid 78.820783 -279.301879)
		(end 78.899512 -279.268936)
		(width 0.0889)
		(layer "In2.Cu")
		(net "M_C_CPU1_SB_DQ<8>")
	)
	(arc
		(start 92.057982 -279.268936)
		(mid 92.340938 -279.192759)
		(end 92.623894 -279.268936)
		(width 0.0889)
		(layer "In2.Cu")
		(net "M_C_CPU1_SB_DQ<8>")
	)
	(arc
		(start 80.778096 -279.268936)
		(mid 81.061052 -279.192759)
		(end 81.344008 -279.268936)
		(width 0.0889)
		(layer "In2.Cu")
		(net "M_C_CPU1_SB_DQ<8>")
	)
	(arc
		(start 91.684094 -279.268936)
		(mid 91.871038 -279.319191)
		(end 92.057982 -279.268936)
		(width 0.0889)
		(layer "In2.Cu")
		(net "M_C_CPU1_SB_DQ<8>")
	)
	(arc
		(start 92.998036 -279.268936)
		(mid 93.280992 -279.192759)
		(end 93.563948 -279.268936)
		(width 0.0889)
		(layer "In2.Cu")
		(net "M_C_CPU1_SB_DQ<8>")
	)
	(arc
		(start 80.403954 -279.268936)
		(mid 80.586205 -279.319286)
		(end 80.769714 -279.273762)
		(width 0.0889)
		(layer "In2.Cu")
		(net "M_C_CPU1_SB_DQ<8>")
	)
	(arc
		(start 87.357966 -279.268936)
		(mid 87.640922 -279.192759)
		(end 87.923878 -279.268936)
		(width 0.0889)
		(layer "In2.Cu")
		(net "M_C_CPU1_SB_DQ<8>")
	)
	(arc
		(start 85.112352 -279.273762)
		(mid 85.29586 -279.319256)
		(end 85.478112 -279.268936)
		(width 0.0889)
		(layer "In2.Cu")
		(net "M_C_CPU1_SB_DQ<8>")
	)
	(arc
		(start 79.863696 -279.254712)
		(mid 80.135633 -279.192886)
		(end 80.403954 -279.268936)
		(width 0.0889)
		(layer "In2.Cu")
		(net "M_C_CPU1_SB_DQ<8>")
	)
	(arc
		(start 82.65795 -279.268936)
		(mid 82.940906 -279.192759)
		(end 83.223862 -279.268936)
		(width 0.0889)
		(layer "In2.Cu")
		(net "M_C_CPU1_SB_DQ<8>")
	)
	(arc
		(start 83.223862 -279.268936)
		(mid 83.406113 -279.319286)
		(end 83.589622 -279.273762)
		(width 0.0889)
		(layer "In2.Cu")
		(net "M_C_CPU1_SB_DQ<8>")
	)
	(arc
		(start 91.118182 -279.268936)
		(mid 91.401138 -279.192759)
		(end 91.684094 -279.268936)
		(width 0.0889)
		(layer "In2.Cu")
		(net "M_C_CPU1_SB_DQ<8>")
	)
	(arc
		(start 79.467202 -279.268936)
		(mid 79.641052 -279.318842)
		(end 79.817976 -279.281128)
		(width 0.0889)
		(layer "In2.Cu")
		(net "M_C_CPU1_SB_DQ<8>")
	)
	(arc
		(start 84.163916 -279.268936)
		(mid 84.346167 -279.319286)
		(end 84.529676 -279.273762)
		(width 0.0889)
		(layer "In2.Cu")
		(net "M_C_CPU1_SB_DQ<8>")
	)
	(arc
		(start 81.71815 -279.268936)
		(mid 82.001106 -279.192759)
		(end 82.284062 -279.268936)
		(width 0.0889)
		(layer "In2.Cu")
		(net "M_C_CPU1_SB_DQ<8>")
	)
	(arc
		(start 87.923878 -279.268936)
		(mid 88.106129 -279.319286)
		(end 88.289638 -279.273762)
		(width 0.0889)
		(layer "In2.Cu")
		(net "M_C_CPU1_SB_DQ<8>")
	)
	(segment
		(start 96.097852 -278.680418)
		(end 95.631 -278.946356)
		(width 0.10668)
		(layer "F.Cu")
		(net "M_C_CPU1_SB_DQ<7>")
	)
	(segment
		(start 76.414376 -278.287734)
		(end 76.57846 -278.451818)
		(width 0.0889)
		(layer "In2.Cu")
		(net "M_C_CPU1_SB_DQ<7>")
	)
	(segment
		(start 54.13883 -290.410392)
		(end 57.222898 -290.410392)
		(width 0.14478)
		(layer "In2.Cu")
		(net "M_C_CPU1_SB_DQ<7>")
	)
	(segment
		(start 95.762826 -278.597614)
		(end 95.785178 -278.680926)
		(width 0.0889)
		(layer "In2.Cu")
		(net "M_C_CPU1_SB_DQ<7>")
	)
	(segment
		(start 58.073036 -289.560254)
		(end 61.150246 -289.560254)
		(width 0.14478)
		(layer "In2.Cu")
		(net "M_C_CPU1_SB_DQ<7>")
	)
	(segment
		(start 57.222898 -290.410392)
		(end 58.073036 -289.560254)
		(width 0.14478)
		(layer "In2.Cu")
		(net "M_C_CPU1_SB_DQ<7>")
	)
	(segment
		(start 85.10397 -278.623776)
		(end 85.112352 -278.61895)
		(width 0.0889)
		(layer "In2.Cu")
		(net "M_C_CPU1_SB_DQ<7>")
	)
	(segment
		(start 81.344008 -278.623776)
		(end 81.35239 -278.61895)
		(width 0.0889)
		(layer "In2.Cu")
		(net "M_C_CPU1_SB_DQ<7>")
	)
	(segment
		(start 89.229692 -278.61895)
		(end 89.238074 -278.623776)
		(width 0.0889)
		(layer "In2.Cu")
		(net "M_C_CPU1_SB_DQ<7>")
	)
	(segment
		(start 90.74404 -278.623776)
		(end 90.752422 -278.61895)
		(width 0.0889)
		(layer "In2.Cu")
		(net "M_C_CPU1_SB_DQ<7>")
	)
	(segment
		(start 78.897734 -278.62403)
		(end 78.903322 -278.627332)
		(width 0.0889)
		(layer "In2.Cu")
		(net "M_C_CPU1_SB_DQ<7>")
	)
	(segment
		(start 76.57846 -278.451818)
		(end 78.267814 -278.451818)
		(width 0.0889)
		(layer "In2.Cu")
		(net "M_C_CPU1_SB_DQ<7>")
	)
	(segment
		(start 40.664892 -290.410392)
		(end 49.82845 -290.410392)
		(width 0.14478)
		(layer "In2.Cu")
		(net "M_C_CPU1_SB_DQ<7>")
	)
	(segment
		(start 40.23995 -289.98545)
		(end 40.664892 -290.410392)
		(width 0.14478)
		(layer "In2.Cu")
		(net "M_C_CPU1_SB_DQ<7>")
	)
	(segment
		(start 80.769714 -278.61895)
		(end 80.778096 -278.623776)
		(width 0.0889)
		(layer "In2.Cu")
		(net "M_C_CPU1_SB_DQ<7>")
	)
	(segment
		(start 89.803986 -278.623776)
		(end 89.812368 -278.61895)
		(width 0.0889)
		(layer "In2.Cu")
		(net "M_C_CPU1_SB_DQ<7>")
	)
	(segment
		(start 53.288692 -289.560254)
		(end 54.13883 -290.410392)
		(width 0.14478)
		(layer "In2.Cu")
		(net "M_C_CPU1_SB_DQ<7>")
	)
	(segment
		(start 80.389222 -278.632412)
		(end 80.403954 -278.623776)
		(width 0.0889)
		(layer "In2.Cu")
		(net "M_C_CPU1_SB_DQ<7>")
	)
	(segment
		(start 86.044024 -278.623776)
		(end 86.052406 -278.61895)
		(width 0.0889)
		(layer "In2.Cu")
		(net "M_C_CPU1_SB_DQ<7>")
	)
	(segment
		(start 61.150246 -289.560254)
		(end 72.422766 -278.287734)
		(width 0.14478)
		(layer "In2.Cu")
		(net "M_C_CPU1_SB_DQ<7>")
	)
	(segment
		(start 75.957176 -278.287734)
		(end 76.414376 -278.287734)
		(width 0.0889)
		(layer "In2.Cu")
		(net "M_C_CPU1_SB_DQ<7>")
	)
	(segment
		(start 83.589622 -278.61895)
		(end 83.598004 -278.623776)
		(width 0.0889)
		(layer "In2.Cu")
		(net "M_C_CPU1_SB_DQ<7>")
	)
	(segment
		(start 50.678588 -289.560254)
		(end 53.288692 -289.560254)
		(width 0.14478)
		(layer "In2.Cu")
		(net "M_C_CPU1_SB_DQ<7>")
	)
	(segment
		(start 92.989654 -278.61895)
		(end 92.998036 -278.623776)
		(width 0.0889)
		(layer "In2.Cu")
		(net "M_C_CPU1_SB_DQ<7>")
	)
	(segment
		(start 93.929708 -278.61895)
		(end 93.93809 -278.623776)
		(width 0.0889)
		(layer "In2.Cu")
		(net "M_C_CPU1_SB_DQ<7>")
	)
	(segment
		(start 72.422766 -278.287734)
		(end 75.957176 -278.287734)
		(width 0.14478)
		(layer "In2.Cu")
		(net "M_C_CPU1_SB_DQ<7>")
	)
	(segment
		(start 88.289638 -278.61895)
		(end 88.29802 -278.623776)
		(width 0.0889)
		(layer "In2.Cu")
		(net "M_C_CPU1_SB_DQ<7>")
	)
	(segment
		(start 49.82845 -290.410392)
		(end 50.678588 -289.560254)
		(width 0.14478)
		(layer "In2.Cu")
		(net "M_C_CPU1_SB_DQ<7>")
	)
	(segment
		(start 95.785178 -278.680926)
		(end 95.631 -278.946356)
		(width 0.0889)
		(layer "In2.Cu")
		(net "M_C_CPU1_SB_DQ<7>")
	)
	(segment
		(start 79.463138 -278.623776)
		(end 79.474822 -278.616918)
		(width 0.0889)
		(layer "In2.Cu")
		(net "M_C_CPU1_SB_DQ<7>")
	)
	(segment
		(start 95.444056 -278.623776)
		(end 95.452438 -278.61895)
		(width 0.0889)
		(layer "In2.Cu")
		(net "M_C_CPU1_SB_DQ<7>")
	)
	(segment
		(start 94.504002 -278.623776)
		(end 94.512384 -278.61895)
		(width 0.0889)
		(layer "In2.Cu")
		(net "M_C_CPU1_SB_DQ<7>")
	)
	(segment
		(start 84.529676 -278.61895)
		(end 84.538058 -278.623776)
		(width 0.0889)
		(layer "In2.Cu")
		(net "M_C_CPU1_SB_DQ<7>")
	)
	(arc
		(start 91.684094 -278.623776)
		(mid 91.871038 -278.573521)
		(end 92.057982 -278.623776)
		(width 0.0889)
		(layer "In2.Cu")
		(net "M_C_CPU1_SB_DQ<7>")
	)
	(arc
		(start 80.403954 -278.623776)
		(mid 80.586205 -278.573426)
		(end 80.769714 -278.61895)
		(width 0.0889)
		(layer "In2.Cu")
		(net "M_C_CPU1_SB_DQ<7>")
	)
	(arc
		(start 84.163916 -278.623776)
		(mid 84.346167 -278.573426)
		(end 84.529676 -278.61895)
		(width 0.0889)
		(layer "In2.Cu")
		(net "M_C_CPU1_SB_DQ<7>")
	)
	(arc
		(start 90.752422 -278.61895)
		(mid 90.93593 -278.573456)
		(end 91.118182 -278.623776)
		(width 0.0889)
		(layer "In2.Cu")
		(net "M_C_CPU1_SB_DQ<7>")
	)
	(arc
		(start 83.598004 -278.623776)
		(mid 83.88096 -278.699953)
		(end 84.163916 -278.623776)
		(width 0.0889)
		(layer "In2.Cu")
		(net "M_C_CPU1_SB_DQ<7>")
	)
	(arc
		(start 78.903322 -278.627332)
		(mid 79.183711 -278.700001)
		(end 79.463138 -278.623776)
		(width 0.0889)
		(layer "In2.Cu")
		(net "M_C_CPU1_SB_DQ<7>")
	)
	(arc
		(start 91.118182 -278.623776)
		(mid 91.401138 -278.699953)
		(end 91.684094 -278.623776)
		(width 0.0889)
		(layer "In2.Cu")
		(net "M_C_CPU1_SB_DQ<7>")
	)
	(arc
		(start 89.812368 -278.61895)
		(mid 89.995876 -278.573456)
		(end 90.178128 -278.623776)
		(width 0.0889)
		(layer "In2.Cu")
		(net "M_C_CPU1_SB_DQ<7>")
	)
	(arc
		(start 88.29802 -278.623776)
		(mid 88.580976 -278.699953)
		(end 88.863932 -278.623776)
		(width 0.0889)
		(layer "In2.Cu")
		(net "M_C_CPU1_SB_DQ<7>")
	)
	(arc
		(start 92.623894 -278.623776)
		(mid 92.806145 -278.573426)
		(end 92.989654 -278.61895)
		(width 0.0889)
		(layer "In2.Cu")
		(net "M_C_CPU1_SB_DQ<7>")
	)
	(arc
		(start 93.93809 -278.623776)
		(mid 94.221046 -278.699953)
		(end 94.504002 -278.623776)
		(width 0.0889)
		(layer "In2.Cu")
		(net "M_C_CPU1_SB_DQ<7>")
	)
	(arc
		(start 84.538058 -278.623776)
		(mid 84.821014 -278.699953)
		(end 85.10397 -278.623776)
		(width 0.0889)
		(layer "In2.Cu")
		(net "M_C_CPU1_SB_DQ<7>")
	)
	(arc
		(start 82.65795 -278.623776)
		(mid 82.940906 -278.699953)
		(end 83.223862 -278.623776)
		(width 0.0889)
		(layer "In2.Cu")
		(net "M_C_CPU1_SB_DQ<7>")
	)
	(arc
		(start 79.837534 -278.623776)
		(mid 80.11224 -278.70014)
		(end 80.389222 -278.632412)
		(width 0.0889)
		(layer "In2.Cu")
		(net "M_C_CPU1_SB_DQ<7>")
	)
	(arc
		(start 92.998036 -278.623776)
		(mid 93.280992 -278.699953)
		(end 93.563948 -278.623776)
		(width 0.0889)
		(layer "In2.Cu")
		(net "M_C_CPU1_SB_DQ<7>")
	)
	(arc
		(start 90.178128 -278.623776)
		(mid 90.461084 -278.699953)
		(end 90.74404 -278.623776)
		(width 0.0889)
		(layer "In2.Cu")
		(net "M_C_CPU1_SB_DQ<7>")
	)
	(arc
		(start 93.563948 -278.623776)
		(mid 93.746199 -278.573426)
		(end 93.929708 -278.61895)
		(width 0.0889)
		(layer "In2.Cu")
		(net "M_C_CPU1_SB_DQ<7>")
	)
	(arc
		(start 82.284062 -278.623776)
		(mid 82.471006 -278.573521)
		(end 82.65795 -278.623776)
		(width 0.0889)
		(layer "In2.Cu")
		(net "M_C_CPU1_SB_DQ<7>")
	)
	(arc
		(start 94.512384 -278.61895)
		(mid 94.695892 -278.573456)
		(end 94.878144 -278.623776)
		(width 0.0889)
		(layer "In2.Cu")
		(net "M_C_CPU1_SB_DQ<7>")
	)
	(arc
		(start 81.71815 -278.623776)
		(mid 82.001106 -278.699953)
		(end 82.284062 -278.623776)
		(width 0.0889)
		(layer "In2.Cu")
		(net "M_C_CPU1_SB_DQ<7>")
	)
	(arc
		(start 80.778096 -278.623776)
		(mid 81.061052 -278.699953)
		(end 81.344008 -278.623776)
		(width 0.0889)
		(layer "In2.Cu")
		(net "M_C_CPU1_SB_DQ<7>")
	)
	(arc
		(start 87.357966 -278.623776)
		(mid 87.640922 -278.699953)
		(end 87.923878 -278.623776)
		(width 0.0889)
		(layer "In2.Cu")
		(net "M_C_CPU1_SB_DQ<7>")
	)
	(arc
		(start 87.923878 -278.623776)
		(mid 88.106129 -278.573426)
		(end 88.289638 -278.61895)
		(width 0.0889)
		(layer "In2.Cu")
		(net "M_C_CPU1_SB_DQ<7>")
	)
	(arc
		(start 86.984078 -278.623776)
		(mid 87.171022 -278.573521)
		(end 87.357966 -278.623776)
		(width 0.0889)
		(layer "In2.Cu")
		(net "M_C_CPU1_SB_DQ<7>")
	)
	(arc
		(start 86.052406 -278.61895)
		(mid 86.235914 -278.573456)
		(end 86.418166 -278.623776)
		(width 0.0889)
		(layer "In2.Cu")
		(net "M_C_CPU1_SB_DQ<7>")
	)
	(arc
		(start 81.35239 -278.61895)
		(mid 81.535898 -278.573456)
		(end 81.71815 -278.623776)
		(width 0.0889)
		(layer "In2.Cu")
		(net "M_C_CPU1_SB_DQ<7>")
	)
	(arc
		(start 79.474822 -278.616918)
		(mid 79.657077 -278.573265)
		(end 79.837534 -278.623776)
		(width 0.0889)
		(layer "In2.Cu")
		(net "M_C_CPU1_SB_DQ<7>")
	)
	(arc
		(start 85.112352 -278.61895)
		(mid 85.29586 -278.573456)
		(end 85.478112 -278.623776)
		(width 0.0889)
		(layer "In2.Cu")
		(net "M_C_CPU1_SB_DQ<7>")
	)
	(arc
		(start 94.878144 -278.623776)
		(mid 95.1611 -278.699953)
		(end 95.444056 -278.623776)
		(width 0.0889)
		(layer "In2.Cu")
		(net "M_C_CPU1_SB_DQ<7>")
	)
	(arc
		(start 83.223862 -278.623776)
		(mid 83.406113 -278.573426)
		(end 83.589622 -278.61895)
		(width 0.0889)
		(layer "In2.Cu")
		(net "M_C_CPU1_SB_DQ<7>")
	)
	(arc
		(start 89.238074 -278.623776)
		(mid 89.52103 -278.699953)
		(end 89.803986 -278.623776)
		(width 0.0889)
		(layer "In2.Cu")
		(net "M_C_CPU1_SB_DQ<7>")
	)
	(arc
		(start 78.267814 -278.451818)
		(mid 78.594333 -278.495644)
		(end 78.897734 -278.62403)
		(width 0.0889)
		(layer "In2.Cu")
		(net "M_C_CPU1_SB_DQ<7>")
	)
	(arc
		(start 88.863932 -278.623776)
		(mid 89.046183 -278.573426)
		(end 89.229692 -278.61895)
		(width 0.0889)
		(layer "In2.Cu")
		(net "M_C_CPU1_SB_DQ<7>")
	)
	(arc
		(start 86.418166 -278.623776)
		(mid 86.701122 -278.699953)
		(end 86.984078 -278.623776)
		(width 0.0889)
		(layer "In2.Cu")
		(net "M_C_CPU1_SB_DQ<7>")
	)
	(arc
		(start 92.057982 -278.623776)
		(mid 92.340938 -278.699953)
		(end 92.623894 -278.623776)
		(width 0.0889)
		(layer "In2.Cu")
		(net "M_C_CPU1_SB_DQ<7>")
	)
	(arc
		(start 95.452438 -278.61895)
		(mid 95.605308 -278.574309)
		(end 95.762826 -278.597614)
		(width 0.0889)
		(layer "In2.Cu")
		(net "M_C_CPU1_SB_DQ<7>")
	)
	(arc
		(start 85.478112 -278.623776)
		(mid 85.761068 -278.699953)
		(end 86.044024 -278.623776)
		(width 0.0889)
		(layer "In2.Cu")
		(net "M_C_CPU1_SB_DQ<7>")
	)
	(segment
		(start 94.687898 -277.870412)
		(end 94.221046 -278.13635)
		(width 0.10668)
		(layer "F.Cu")
		(net "M_C_CPU1_SB_DQ<6>")
	)
	(segment
		(start 43.046904 -288.71037)
		(end 48.199294 -288.71037)
		(width 0.14478)
		(layer "In2.Cu")
		(net "M_C_CPU1_SB_DQ<6>")
	)
	(segment
		(start 80.282034 -277.79853)
		(end 80.308196 -277.81377)
		(width 0.0889)
		(layer "In2.Cu")
		(net "M_C_CPU1_SB_DQ<6>")
	)
	(segment
		(start 42.32783 -287.9725)
		(end 42.490644 -287.809686)
		(width 0.14478)
		(layer "In2.Cu")
		(net "M_C_CPU1_SB_DQ<6>")
	)
	(segment
		(start 53.725318 -288.71037)
		(end 57.63641 -288.71037)
		(width 0.14478)
		(layer "In2.Cu")
		(net "M_C_CPU1_SB_DQ<6>")
	)
	(segment
		(start 49.84115 -289.107626)
		(end 51.088544 -287.860232)
		(width 0.14478)
		(layer "In2.Cu")
		(net "M_C_CPU1_SB_DQ<6>")
	)
	(segment
		(start 90.639646 -277.808944)
		(end 90.648028 -277.81377)
		(width 0.0889)
		(layer "In2.Cu")
		(net "M_C_CPU1_SB_DQ<6>")
	)
	(segment
		(start 42.490644 -287.809686)
		(end 42.721276 -287.809686)
		(width 0.14478)
		(layer "In2.Cu")
		(net "M_C_CPU1_SB_DQ<6>")
	)
	(segment
		(start 48.59655 -289.107626)
		(end 49.84115 -289.107626)
		(width 0.14478)
		(layer "In2.Cu")
		(net "M_C_CPU1_SB_DQ<6>")
	)
	(segment
		(start 75.954636 -277.378414)
		(end 76.49845 -277.378414)
		(width 0.0889)
		(layer "In2.Cu")
		(net "M_C_CPU1_SB_DQ<6>")
	)
	(segment
		(start 60.29071 -287.860232)
		(end 60.684156 -287.466786)
		(width 0.14478)
		(layer "In2.Cu")
		(net "M_C_CPU1_SB_DQ<6>")
	)
	(segment
		(start 77.80655 -277.502112)
		(end 78.200758 -277.89632)
		(width 0.0889)
		(layer "In2.Cu")
		(net "M_C_CPU1_SB_DQ<6>")
	)
	(segment
		(start 92.153994 -277.81377)
		(end 92.162376 -277.808944)
		(width 0.0889)
		(layer "In2.Cu")
		(net "M_C_CPU1_SB_DQ<6>")
	)
	(segment
		(start 51.088544 -287.860232)
		(end 52.87518 -287.860232)
		(width 0.14478)
		(layer "In2.Cu")
		(net "M_C_CPU1_SB_DQ<6>")
	)
	(segment
		(start 78.200758 -277.89632)
		(end 78.711044 -277.89632)
		(width 0.0889)
		(layer "In2.Cu")
		(net "M_C_CPU1_SB_DQ<6>")
	)
	(segment
		(start 42.88409 -287.9725)
		(end 42.88409 -288.547556)
		(width 0.14478)
		(layer "In2.Cu")
		(net "M_C_CPU1_SB_DQ<6>")
	)
	(segment
		(start 52.87518 -287.860232)
		(end 53.725318 -288.71037)
		(width 0.14478)
		(layer "In2.Cu")
		(net "M_C_CPU1_SB_DQ<6>")
	)
	(segment
		(start 42.721276 -287.809686)
		(end 42.88409 -287.9725)
		(width 0.14478)
		(layer "In2.Cu")
		(net "M_C_CPU1_SB_DQ<6>")
	)
	(segment
		(start 42.88409 -288.547556)
		(end 43.046904 -288.71037)
		(width 0.14478)
		(layer "In2.Cu")
		(net "M_C_CPU1_SB_DQ<6>")
	)
	(segment
		(start 42.32783 -288.547556)
		(end 42.32783 -287.9725)
		(width 0.14478)
		(layer "In2.Cu")
		(net "M_C_CPU1_SB_DQ<6>")
	)
	(segment
		(start 82.753962 -277.81377)
		(end 82.762344 -277.808944)
		(width 0.0889)
		(layer "In2.Cu")
		(net "M_C_CPU1_SB_DQ<6>")
	)
	(segment
		(start 93.094048 -277.81377)
		(end 93.10243 -277.808944)
		(width 0.0889)
		(layer "In2.Cu")
		(net "M_C_CPU1_SB_DQ<6>")
	)
	(segment
		(start 48.199294 -288.71037)
		(end 48.59655 -289.107626)
		(width 0.14478)
		(layer "In2.Cu")
		(net "M_C_CPU1_SB_DQ<6>")
	)
	(segment
		(start 85.93963 -277.808944)
		(end 85.948012 -277.81377)
		(width 0.0889)
		(layer "In2.Cu")
		(net "M_C_CPU1_SB_DQ<6>")
	)
	(segment
		(start 91.5797 -277.808944)
		(end 91.588082 -277.81377)
		(width 0.0889)
		(layer "In2.Cu")
		(net "M_C_CPU1_SB_DQ<6>")
	)
	(segment
		(start 60.684156 -287.466786)
		(end 61.971428 -287.466786)
		(width 0.14478)
		(layer "In2.Cu")
		(net "M_C_CPU1_SB_DQ<6>")
	)
	(segment
		(start 78.96606 -277.828248)
		(end 79.018384 -277.798276)
		(width 0.0889)
		(layer "In2.Cu")
		(net "M_C_CPU1_SB_DQ<6>")
	)
	(segment
		(start 83.694016 -277.81377)
		(end 83.702398 -277.808944)
		(width 0.0889)
		(layer "In2.Cu")
		(net "M_C_CPU1_SB_DQ<6>")
	)
	(segment
		(start 42.165016 -288.71037)
		(end 42.32783 -288.547556)
		(width 0.14478)
		(layer "In2.Cu")
		(net "M_C_CPU1_SB_DQ<6>")
	)
	(segment
		(start 94.352618 -277.787608)
		(end 94.37497 -277.87092)
		(width 0.0889)
		(layer "In2.Cu")
		(net "M_C_CPU1_SB_DQ<6>")
	)
	(segment
		(start 61.971428 -287.466786)
		(end 72.0598 -277.378414)
		(width 0.14478)
		(layer "In2.Cu")
		(net "M_C_CPU1_SB_DQ<6>")
	)
	(segment
		(start 87.453978 -277.81377)
		(end 87.46236 -277.808944)
		(width 0.0889)
		(layer "In2.Cu")
		(net "M_C_CPU1_SB_DQ<6>")
	)
	(segment
		(start 76.49845 -277.378414)
		(end 76.622148 -277.502112)
		(width 0.0889)
		(layer "In2.Cu")
		(net "M_C_CPU1_SB_DQ<6>")
	)
	(segment
		(start 79.363062 -277.81377)
		(end 79.394812 -277.832312)
		(width 0.0889)
		(layer "In2.Cu")
		(net "M_C_CPU1_SB_DQ<6>")
	)
	(segment
		(start 40.23995 -288.285428)
		(end 40.664892 -288.71037)
		(width 0.14478)
		(layer "In2.Cu")
		(net "M_C_CPU1_SB_DQ<6>")
	)
	(segment
		(start 94.37497 -277.87092)
		(end 94.221046 -278.13635)
		(width 0.0889)
		(layer "In2.Cu")
		(net "M_C_CPU1_SB_DQ<6>")
	)
	(segment
		(start 76.622148 -277.502112)
		(end 77.80655 -277.502112)
		(width 0.0889)
		(layer "In2.Cu")
		(net "M_C_CPU1_SB_DQ<6>")
	)
	(segment
		(start 57.63641 -288.71037)
		(end 58.486548 -287.860232)
		(width 0.14478)
		(layer "In2.Cu")
		(net "M_C_CPU1_SB_DQ<6>")
	)
	(segment
		(start 88.394032 -277.81377)
		(end 88.402414 -277.808944)
		(width 0.0889)
		(layer "In2.Cu")
		(net "M_C_CPU1_SB_DQ<6>")
	)
	(segment
		(start 40.664892 -288.71037)
		(end 42.165016 -288.71037)
		(width 0.14478)
		(layer "In2.Cu")
		(net "M_C_CPU1_SB_DQ<6>")
	)
	(segment
		(start 86.879684 -277.808944)
		(end 86.888066 -277.81377)
		(width 0.0889)
		(layer "In2.Cu")
		(net "M_C_CPU1_SB_DQ<6>")
	)
	(segment
		(start 72.0598 -277.378414)
		(end 75.954636 -277.378414)
		(width 0.14478)
		(layer "In2.Cu")
		(net "M_C_CPU1_SB_DQ<6>")
	)
	(segment
		(start 58.486548 -287.860232)
		(end 60.29071 -287.860232)
		(width 0.14478)
		(layer "In2.Cu")
		(net "M_C_CPU1_SB_DQ<6>")
	)
	(segment
		(start 82.179668 -277.808944)
		(end 82.18805 -277.81377)
		(width 0.0889)
		(layer "In2.Cu")
		(net "M_C_CPU1_SB_DQ<6>")
	)
	(arc
		(start 81.247996 -277.81377)
		(mid 81.530952 -277.889947)
		(end 81.813908 -277.81377)
		(width 0.0889)
		(layer "In2.Cu")
		(net "M_C_CPU1_SB_DQ<6>")
	)
	(arc
		(start 86.513924 -277.81377)
		(mid 86.696175 -277.76342)
		(end 86.879684 -277.808944)
		(width 0.0889)
		(layer "In2.Cu")
		(net "M_C_CPU1_SB_DQ<6>")
	)
	(arc
		(start 85.57387 -277.81377)
		(mid 85.756121 -277.76342)
		(end 85.93963 -277.808944)
		(width 0.0889)
		(layer "In2.Cu")
		(net "M_C_CPU1_SB_DQ<6>")
	)
	(arc
		(start 82.762344 -277.808944)
		(mid 82.945852 -277.76345)
		(end 83.128104 -277.81377)
		(width 0.0889)
		(layer "In2.Cu")
		(net "M_C_CPU1_SB_DQ<6>")
	)
	(arc
		(start 91.588082 -277.81377)
		(mid 91.871038 -277.889947)
		(end 92.153994 -277.81377)
		(width 0.0889)
		(layer "In2.Cu")
		(net "M_C_CPU1_SB_DQ<6>")
	)
	(arc
		(start 79.394812 -277.832312)
		(mid 79.665683 -277.890898)
		(end 79.931768 -277.813516)
		(width 0.0889)
		(layer "In2.Cu")
		(net "M_C_CPU1_SB_DQ<6>")
	)
	(arc
		(start 82.18805 -277.81377)
		(mid 82.471006 -277.889947)
		(end 82.753962 -277.81377)
		(width 0.0889)
		(layer "In2.Cu")
		(net "M_C_CPU1_SB_DQ<6>")
	)
	(arc
		(start 88.402414 -277.808944)
		(mid 88.585922 -277.76345)
		(end 88.768174 -277.81377)
		(width 0.0889)
		(layer "In2.Cu")
		(net "M_C_CPU1_SB_DQ<6>")
	)
	(arc
		(start 86.888066 -277.81377)
		(mid 87.171022 -277.889947)
		(end 87.453978 -277.81377)
		(width 0.0889)
		(layer "In2.Cu")
		(net "M_C_CPU1_SB_DQ<6>")
	)
	(arc
		(start 84.068158 -277.81377)
		(mid 84.351114 -277.889947)
		(end 84.63407 -277.81377)
		(width 0.0889)
		(layer "In2.Cu")
		(net "M_C_CPU1_SB_DQ<6>")
	)
	(arc
		(start 79.931768 -277.813516)
		(mid 80.105034 -277.762485)
		(end 80.282034 -277.79853)
		(width 0.0889)
		(layer "In2.Cu")
		(net "M_C_CPU1_SB_DQ<6>")
	)
	(arc
		(start 89.334086 -277.81377)
		(mid 89.52103 -277.763515)
		(end 89.707974 -277.81377)
		(width 0.0889)
		(layer "In2.Cu")
		(net "M_C_CPU1_SB_DQ<6>")
	)
	(arc
		(start 80.308196 -277.81377)
		(mid 80.591152 -277.889947)
		(end 80.874108 -277.81377)
		(width 0.0889)
		(layer "In2.Cu")
		(net "M_C_CPU1_SB_DQ<6>")
	)
	(arc
		(start 85.007958 -277.81377)
		(mid 85.290914 -277.889947)
		(end 85.57387 -277.81377)
		(width 0.0889)
		(layer "In2.Cu")
		(net "M_C_CPU1_SB_DQ<6>")
	)
	(arc
		(start 83.128104 -277.81377)
		(mid 83.41106 -277.889947)
		(end 83.694016 -277.81377)
		(width 0.0889)
		(layer "In2.Cu")
		(net "M_C_CPU1_SB_DQ<6>")
	)
	(arc
		(start 81.813908 -277.81377)
		(mid 81.996159 -277.76342)
		(end 82.179668 -277.808944)
		(width 0.0889)
		(layer "In2.Cu")
		(net "M_C_CPU1_SB_DQ<6>")
	)
	(arc
		(start 80.874108 -277.81377)
		(mid 81.061052 -277.763515)
		(end 81.247996 -277.81377)
		(width 0.0889)
		(layer "In2.Cu")
		(net "M_C_CPU1_SB_DQ<6>")
	)
	(arc
		(start 93.10243 -277.808944)
		(mid 93.285938 -277.76345)
		(end 93.46819 -277.81377)
		(width 0.0889)
		(layer "In2.Cu")
		(net "M_C_CPU1_SB_DQ<6>")
	)
	(arc
		(start 84.63407 -277.81377)
		(mid 84.821014 -277.763515)
		(end 85.007958 -277.81377)
		(width 0.0889)
		(layer "In2.Cu")
		(net "M_C_CPU1_SB_DQ<6>")
	)
	(arc
		(start 83.702398 -277.808944)
		(mid 83.885906 -277.76345)
		(end 84.068158 -277.81377)
		(width 0.0889)
		(layer "In2.Cu")
		(net "M_C_CPU1_SB_DQ<6>")
	)
	(arc
		(start 90.273886 -277.81377)
		(mid 90.456137 -277.76342)
		(end 90.639646 -277.808944)
		(width 0.0889)
		(layer "In2.Cu")
		(net "M_C_CPU1_SB_DQ<6>")
	)
	(arc
		(start 85.948012 -277.81377)
		(mid 86.230968 -277.889947)
		(end 86.513924 -277.81377)
		(width 0.0889)
		(layer "In2.Cu")
		(net "M_C_CPU1_SB_DQ<6>")
	)
	(arc
		(start 90.648028 -277.81377)
		(mid 90.930984 -277.889947)
		(end 91.21394 -277.81377)
		(width 0.0889)
		(layer "In2.Cu")
		(net "M_C_CPU1_SB_DQ<6>")
	)
	(arc
		(start 89.707974 -277.81377)
		(mid 89.99093 -277.889947)
		(end 90.273886 -277.81377)
		(width 0.0889)
		(layer "In2.Cu")
		(net "M_C_CPU1_SB_DQ<6>")
	)
	(arc
		(start 94.034102 -277.81377)
		(mid 94.190421 -277.764775)
		(end 94.352618 -277.787608)
		(width 0.0889)
		(layer "In2.Cu")
		(net "M_C_CPU1_SB_DQ<6>")
	)
	(arc
		(start 87.82812 -277.81377)
		(mid 88.111076 -277.889947)
		(end 88.394032 -277.81377)
		(width 0.0889)
		(layer "In2.Cu")
		(net "M_C_CPU1_SB_DQ<6>")
	)
	(arc
		(start 78.711044 -277.89632)
		(mid 78.843022 -277.87902)
		(end 78.96606 -277.828248)
		(width 0.0889)
		(layer "In2.Cu")
		(net "M_C_CPU1_SB_DQ<6>")
	)
	(arc
		(start 91.21394 -277.81377)
		(mid 91.396191 -277.76342)
		(end 91.5797 -277.808944)
		(width 0.0889)
		(layer "In2.Cu")
		(net "M_C_CPU1_SB_DQ<6>")
	)
	(arc
		(start 88.768174 -277.81377)
		(mid 89.05113 -277.889947)
		(end 89.334086 -277.81377)
		(width 0.0889)
		(layer "In2.Cu")
		(net "M_C_CPU1_SB_DQ<6>")
	)
	(arc
		(start 92.528136 -277.81377)
		(mid 92.811092 -277.889947)
		(end 93.094048 -277.81377)
		(width 0.0889)
		(layer "In2.Cu")
		(net "M_C_CPU1_SB_DQ<6>")
	)
	(arc
		(start 92.162376 -277.808944)
		(mid 92.345884 -277.76345)
		(end 92.528136 -277.81377)
		(width 0.0889)
		(layer "In2.Cu")
		(net "M_C_CPU1_SB_DQ<6>")
	)
	(arc
		(start 79.018384 -277.798276)
		(mid 79.192621 -277.763774)
		(end 79.363062 -277.81377)
		(width 0.0889)
		(layer "In2.Cu")
		(net "M_C_CPU1_SB_DQ<6>")
	)
	(arc
		(start 87.46236 -277.808944)
		(mid 87.645868 -277.76345)
		(end 87.82812 -277.81377)
		(width 0.0889)
		(layer "In2.Cu")
		(net "M_C_CPU1_SB_DQ<6>")
	)
	(arc
		(start 93.46819 -277.81377)
		(mid 93.751146 -277.889947)
		(end 94.034102 -277.81377)
		(width 0.0889)
		(layer "In2.Cu")
		(net "M_C_CPU1_SB_DQ<6>")
	)
	(segment
		(start 96.568006 -277.870412)
		(end 96.101154 -278.13635)
		(width 0.10668)
		(layer "F.Cu")
		(net "M_C_CPU1_SB_DQ<5>")
	)
	(segment
		(start 49.710086 -289.881564)
		(end 50.88128 -288.71037)
		(width 0.14478)
		(layer "In2.Cu")
		(net "M_C_CPU1_SB_DQ<5>")
	)
	(segment
		(start 88.394032 -278.45893)
		(end 88.402414 -278.463756)
		(width 0.0889)
		(layer "In2.Cu")
		(net "M_C_CPU1_SB_DQ<5>")
	)
	(segment
		(start 87.453978 -278.45893)
		(end 87.46236 -278.463756)
		(width 0.0889)
		(layer "In2.Cu")
		(net "M_C_CPU1_SB_DQ<5>")
	)
	(segment
		(start 46.256702 -289.838384)
		(end 46.469046 -289.838384)
		(width 0.14478)
		(layer "In2.Cu")
		(net "M_C_CPU1_SB_DQ<5>")
	)
	(segment
		(start 46.746922 -289.560508)
		(end 49.007268 -289.560508)
		(width 0.14478)
		(layer "In2.Cu")
		(net "M_C_CPU1_SB_DQ<5>")
	)
	(segment
		(start 58.279792 -288.71037)
		(end 60.305696 -288.71037)
		(width 0.14478)
		(layer "In2.Cu")
		(net "M_C_CPU1_SB_DQ<5>")
	)
	(segment
		(start 54.089808 -289.521646)
		(end 54.44109 -289.170364)
		(width 0.14478)
		(layer "In2.Cu")
		(net "M_C_CPU1_SB_DQ<5>")
	)
	(segment
		(start 60.85713 -288.183066)
		(end 61.018674 -288.34461)
		(width 0.14478)
		(layer "In2.Cu")
		(net "M_C_CPU1_SB_DQ<5>")
	)
	(segment
		(start 44.340018 -289.135312)
		(end 45.157136 -289.95243)
		(width 0.14478)
		(layer "In2.Cu")
		(net "M_C_CPU1_SB_DQ<5>")
	)
	(segment
		(start 80.299814 -278.463756)
		(end 80.308196 -278.45893)
		(width 0.0889)
		(layer "In2.Cu")
		(net "M_C_CPU1_SB_DQ<5>")
	)
	(segment
		(start 54.44109 -289.170364)
		(end 54.69763 -289.170364)
		(width 0.14478)
		(layer "In2.Cu")
		(net "M_C_CPU1_SB_DQ<5>")
	)
	(segment
		(start 46.106842 -289.353244)
		(end 46.106842 -289.688524)
		(width 0.14478)
		(layer "In2.Cu")
		(net "M_C_CPU1_SB_DQ<5>")
	)
	(segment
		(start 45.157136 -289.95243)
		(end 45.387768 -289.95243)
		(width 0.14478)
		(layer "In2.Cu")
		(net "M_C_CPU1_SB_DQ<5>")
	)
	(segment
		(start 93.094048 -278.45893)
		(end 93.10243 -278.463756)
		(width 0.0889)
		(layer "In2.Cu")
		(net "M_C_CPU1_SB_DQ<5>")
	)
	(segment
		(start 56.603646 -289.320224)
		(end 56.603646 -289.782504)
		(width 0.14478)
		(layer "In2.Cu")
		(net "M_C_CPU1_SB_DQ<5>")
	)
	(segment
		(start 56.197246 -289.170364)
		(end 56.453786 -289.170364)
		(width 0.14478)
		(layer "In2.Cu")
		(net "M_C_CPU1_SB_DQ<5>")
	)
	(segment
		(start 95.339662 -278.463756)
		(end 95.348044 -278.45893)
		(width 0.0889)
		(layer "In2.Cu")
		(net "M_C_CPU1_SB_DQ<5>")
	)
	(segment
		(start 54.69763 -289.170364)
		(end 55.087774 -289.560508)
		(width 0.14478)
		(layer "In2.Cu")
		(net "M_C_CPU1_SB_DQ<5>")
	)
	(segment
		(start 45.550582 -289.789616)
		(end 45.550582 -289.353244)
		(width 0.14478)
		(layer "In2.Cu")
		(net "M_C_CPU1_SB_DQ<5>")
	)
	(segment
		(start 72.24141 -277.833074)
		(end 75.966066 -277.833074)
		(width 0.14478)
		(layer "In2.Cu")
		(net "M_C_CPU1_SB_DQ<5>")
	)
	(segment
		(start 49.328324 -289.881564)
		(end 49.710086 -289.881564)
		(width 0.14478)
		(layer "In2.Cu")
		(net "M_C_CPU1_SB_DQ<5>")
	)
	(segment
		(start 45.550582 -289.353244)
		(end 45.713396 -289.19043)
		(width 0.14478)
		(layer "In2.Cu")
		(net "M_C_CPU1_SB_DQ<5>")
	)
	(segment
		(start 86.879684 -278.463756)
		(end 86.888066 -278.45893)
		(width 0.0889)
		(layer "In2.Cu")
		(net "M_C_CPU1_SB_DQ<5>")
	)
	(segment
		(start 92.153994 -278.45893)
		(end 92.162376 -278.463756)
		(width 0.0889)
		(layer "In2.Cu")
		(net "M_C_CPU1_SB_DQ<5>")
	)
	(segment
		(start 95.85071 -278.42718)
		(end 95.946976 -278.40178)
		(width 0.0889)
		(layer "In2.Cu")
		(net "M_C_CPU1_SB_DQ<5>")
	)
	(segment
		(start 56.453786 -289.170364)
		(end 56.603646 -289.320224)
		(width 0.14478)
		(layer "In2.Cu")
		(net "M_C_CPU1_SB_DQ<5>")
	)
	(segment
		(start 53.893212 -289.521646)
		(end 54.089808 -289.521646)
		(width 0.14478)
		(layer "In2.Cu")
		(net "M_C_CPU1_SB_DQ<5>")
	)
	(segment
		(start 79.367126 -278.45893)
		(end 79.381858 -278.450294)
		(width 0.0889)
		(layer "In2.Cu")
		(net "M_C_CPU1_SB_DQ<5>")
	)
	(segment
		(start 55.087774 -289.560508)
		(end 55.807102 -289.560508)
		(width 0.14478)
		(layer "In2.Cu")
		(net "M_C_CPU1_SB_DQ<5>")
	)
	(segment
		(start 82.753962 -278.45893)
		(end 82.762344 -278.463756)
		(width 0.0889)
		(layer "In2.Cu")
		(net "M_C_CPU1_SB_DQ<5>")
	)
	(segment
		(start 56.753506 -289.932364)
		(end 57.057798 -289.932364)
		(width 0.14478)
		(layer "In2.Cu")
		(net "M_C_CPU1_SB_DQ<5>")
	)
	(segment
		(start 85.93963 -278.463756)
		(end 85.948012 -278.45893)
		(width 0.0889)
		(layer "In2.Cu")
		(net "M_C_CPU1_SB_DQ<5>")
	)
	(segment
		(start 46.106842 -289.688524)
		(end 46.256702 -289.838384)
		(width 0.14478)
		(layer "In2.Cu")
		(net "M_C_CPU1_SB_DQ<5>")
	)
	(segment
		(start 45.387768 -289.95243)
		(end 45.550582 -289.789616)
		(width 0.14478)
		(layer "In2.Cu")
		(net "M_C_CPU1_SB_DQ<5>")
	)
	(segment
		(start 50.88128 -288.71037)
		(end 53.081936 -288.71037)
		(width 0.14478)
		(layer "In2.Cu")
		(net "M_C_CPU1_SB_DQ<5>")
	)
	(segment
		(start 55.807102 -289.560508)
		(end 56.197246 -289.170364)
		(width 0.14478)
		(layer "In2.Cu")
		(net "M_C_CPU1_SB_DQ<5>")
	)
	(segment
		(start 61.374782 -288.699702)
		(end 72.24141 -277.833074)
		(width 0.14478)
		(layer "In2.Cu")
		(net "M_C_CPU1_SB_DQ<5>")
	)
	(segment
		(start 49.007268 -289.560508)
		(end 49.328324 -289.881564)
		(width 0.14478)
		(layer "In2.Cu")
		(net "M_C_CPU1_SB_DQ<5>")
	)
	(segment
		(start 60.305696 -288.71037)
		(end 60.46724 -288.548826)
		(width 0.14478)
		(layer "In2.Cu")
		(net "M_C_CPU1_SB_DQ<5>")
	)
	(segment
		(start 95.946976 -278.40178)
		(end 96.101154 -278.13635)
		(width 0.0889)
		(layer "In2.Cu")
		(net "M_C_CPU1_SB_DQ<5>")
	)
	(segment
		(start 60.628784 -288.183066)
		(end 60.85713 -288.183066)
		(width 0.14478)
		(layer "In2.Cu")
		(net "M_C_CPU1_SB_DQ<5>")
	)
	(segment
		(start 91.5797 -278.463756)
		(end 91.588082 -278.45893)
		(width 0.0889)
		(layer "In2.Cu")
		(net "M_C_CPU1_SB_DQ<5>")
	)
	(segment
		(start 76.515976 -277.833074)
		(end 76.931266 -278.248364)
		(width 0.0889)
		(layer "In2.Cu")
		(net "M_C_CPU1_SB_DQ<5>")
	)
	(segment
		(start 57.057798 -289.932364)
		(end 58.279792 -288.71037)
		(width 0.14478)
		(layer "In2.Cu")
		(net "M_C_CPU1_SB_DQ<5>")
	)
	(segment
		(start 78.966822 -278.443436)
		(end 79.007208 -278.46655)
		(width 0.0889)
		(layer "In2.Cu")
		(net "M_C_CPU1_SB_DQ<5>")
	)
	(segment
		(start 61.16955 -288.699702)
		(end 61.374782 -288.699702)
		(width 0.14478)
		(layer "In2.Cu")
		(net "M_C_CPU1_SB_DQ<5>")
	)
	(segment
		(start 45.713396 -289.19043)
		(end 45.944028 -289.19043)
		(width 0.14478)
		(layer "In2.Cu")
		(net "M_C_CPU1_SB_DQ<5>")
	)
	(segment
		(start 53.081936 -288.71037)
		(end 53.893212 -289.521646)
		(width 0.14478)
		(layer "In2.Cu")
		(net "M_C_CPU1_SB_DQ<5>")
	)
	(segment
		(start 61.018674 -288.548826)
		(end 61.16955 -288.699702)
		(width 0.14478)
		(layer "In2.Cu")
		(net "M_C_CPU1_SB_DQ<5>")
	)
	(segment
		(start 45.944028 -289.19043)
		(end 46.106842 -289.353244)
		(width 0.14478)
		(layer "In2.Cu")
		(net "M_C_CPU1_SB_DQ<5>")
	)
	(segment
		(start 61.018674 -288.34461)
		(end 61.018674 -288.548826)
		(width 0.14478)
		(layer "In2.Cu")
		(net "M_C_CPU1_SB_DQ<5>")
	)
	(segment
		(start 76.931266 -278.248364)
		(end 78.235556 -278.248364)
		(width 0.0889)
		(layer "In2.Cu")
		(net "M_C_CPU1_SB_DQ<5>")
	)
	(segment
		(start 56.603646 -289.782504)
		(end 56.753506 -289.932364)
		(width 0.14478)
		(layer "In2.Cu")
		(net "M_C_CPU1_SB_DQ<5>")
	)
	(segment
		(start 83.694016 -278.45893)
		(end 83.702398 -278.463756)
		(width 0.0889)
		(layer "In2.Cu")
		(net "M_C_CPU1_SB_DQ<5>")
	)
	(segment
		(start 60.46724 -288.34461)
		(end 60.628784 -288.183066)
		(width 0.14478)
		(layer "In2.Cu")
		(net "M_C_CPU1_SB_DQ<5>")
	)
	(segment
		(start 75.966066 -277.833074)
		(end 76.515976 -277.833074)
		(width 0.0889)
		(layer "In2.Cu")
		(net "M_C_CPU1_SB_DQ<5>")
	)
	(segment
		(start 82.179668 -278.463756)
		(end 82.18805 -278.45893)
		(width 0.0889)
		(layer "In2.Cu")
		(net "M_C_CPU1_SB_DQ<5>")
	)
	(segment
		(start 90.639646 -278.463756)
		(end 90.648028 -278.45893)
		(width 0.0889)
		(layer "In2.Cu")
		(net "M_C_CPU1_SB_DQ<5>")
	)
	(segment
		(start 46.469046 -289.838384)
		(end 46.746922 -289.560508)
		(width 0.14478)
		(layer "In2.Cu")
		(net "M_C_CPU1_SB_DQ<5>")
	)
	(segment
		(start 60.46724 -288.548826)
		(end 60.46724 -288.34461)
		(width 0.14478)
		(layer "In2.Cu")
		(net "M_C_CPU1_SB_DQ<5>")
	)
	(arc
		(start 81.247996 -278.45893)
		(mid 81.530952 -278.382753)
		(end 81.813908 -278.45893)
		(width 0.0889)
		(layer "In2.Cu")
		(net "M_C_CPU1_SB_DQ<5>")
	)
	(arc
		(start 94.40799 -278.45893)
		(mid 94.690946 -278.382753)
		(end 94.973902 -278.45893)
		(width 0.0889)
		(layer "In2.Cu")
		(net "M_C_CPU1_SB_DQ<5>")
	)
	(arc
		(start 93.46819 -278.45893)
		(mid 93.751146 -278.382753)
		(end 94.034102 -278.45893)
		(width 0.0889)
		(layer "In2.Cu")
		(net "M_C_CPU1_SB_DQ<5>")
	)
	(arc
		(start 88.768174 -278.45893)
		(mid 89.05113 -278.382753)
		(end 89.334086 -278.45893)
		(width 0.0889)
		(layer "In2.Cu")
		(net "M_C_CPU1_SB_DQ<5>")
	)
	(arc
		(start 94.973902 -278.45893)
		(mid 95.156153 -278.50928)
		(end 95.339662 -278.463756)
		(width 0.0889)
		(layer "In2.Cu")
		(net "M_C_CPU1_SB_DQ<5>")
	)
	(arc
		(start 83.702398 -278.463756)
		(mid 83.885906 -278.50925)
		(end 84.068158 -278.45893)
		(width 0.0889)
		(layer "In2.Cu")
		(net "M_C_CPU1_SB_DQ<5>")
	)
	(arc
		(start 79.933546 -278.45893)
		(mid 80.116051 -278.509407)
		(end 80.299814 -278.463756)
		(width 0.0889)
		(layer "In2.Cu")
		(net "M_C_CPU1_SB_DQ<5>")
	)
	(arc
		(start 95.348044 -278.45893)
		(mid 95.59564 -278.383752)
		(end 95.85071 -278.42718)
		(width 0.0889)
		(layer "In2.Cu")
		(net "M_C_CPU1_SB_DQ<5>")
	)
	(arc
		(start 82.762344 -278.463756)
		(mid 82.945852 -278.50925)
		(end 83.128104 -278.45893)
		(width 0.0889)
		(layer "In2.Cu")
		(net "M_C_CPU1_SB_DQ<5>")
	)
	(arc
		(start 84.63407 -278.45893)
		(mid 84.821014 -278.509185)
		(end 85.007958 -278.45893)
		(width 0.0889)
		(layer "In2.Cu")
		(net "M_C_CPU1_SB_DQ<5>")
	)
	(arc
		(start 78.235556 -278.248364)
		(mid 78.613982 -278.297957)
		(end 78.966822 -278.443436)
		(width 0.0889)
		(layer "In2.Cu")
		(net "M_C_CPU1_SB_DQ<5>")
	)
	(arc
		(start 88.402414 -278.463756)
		(mid 88.585922 -278.50925)
		(end 88.768174 -278.45893)
		(width 0.0889)
		(layer "In2.Cu")
		(net "M_C_CPU1_SB_DQ<5>")
	)
	(arc
		(start 80.308196 -278.45893)
		(mid 80.591152 -278.382753)
		(end 80.874108 -278.45893)
		(width 0.0889)
		(layer "In2.Cu")
		(net "M_C_CPU1_SB_DQ<5>")
	)
	(arc
		(start 90.273886 -278.45893)
		(mid 90.456137 -278.50928)
		(end 90.639646 -278.463756)
		(width 0.0889)
		(layer "In2.Cu")
		(net "M_C_CPU1_SB_DQ<5>")
	)
	(arc
		(start 79.007208 -278.46655)
		(mid 79.188138 -278.509028)
		(end 79.367126 -278.45893)
		(width 0.0889)
		(layer "In2.Cu")
		(net "M_C_CPU1_SB_DQ<5>")
	)
	(arc
		(start 93.10243 -278.463756)
		(mid 93.285938 -278.50925)
		(end 93.46819 -278.45893)
		(width 0.0889)
		(layer "In2.Cu")
		(net "M_C_CPU1_SB_DQ<5>")
	)
	(arc
		(start 81.813908 -278.45893)
		(mid 81.996159 -278.50928)
		(end 82.179668 -278.463756)
		(width 0.0889)
		(layer "In2.Cu")
		(net "M_C_CPU1_SB_DQ<5>")
	)
	(arc
		(start 83.128104 -278.45893)
		(mid 83.41106 -278.382753)
		(end 83.694016 -278.45893)
		(width 0.0889)
		(layer "In2.Cu")
		(net "M_C_CPU1_SB_DQ<5>")
	)
	(arc
		(start 85.948012 -278.45893)
		(mid 86.230968 -278.382753)
		(end 86.513924 -278.45893)
		(width 0.0889)
		(layer "In2.Cu")
		(net "M_C_CPU1_SB_DQ<5>")
	)
	(arc
		(start 90.648028 -278.45893)
		(mid 90.930984 -278.382753)
		(end 91.21394 -278.45893)
		(width 0.0889)
		(layer "In2.Cu")
		(net "M_C_CPU1_SB_DQ<5>")
	)
	(arc
		(start 89.707974 -278.45893)
		(mid 89.99093 -278.382753)
		(end 90.273886 -278.45893)
		(width 0.0889)
		(layer "In2.Cu")
		(net "M_C_CPU1_SB_DQ<5>")
	)
	(arc
		(start 91.588082 -278.45893)
		(mid 91.871038 -278.382753)
		(end 92.153994 -278.45893)
		(width 0.0889)
		(layer "In2.Cu")
		(net "M_C_CPU1_SB_DQ<5>")
	)
	(arc
		(start 79.381858 -278.450294)
		(mid 79.658841 -278.38249)
		(end 79.933546 -278.45893)
		(width 0.0889)
		(layer "In2.Cu")
		(net "M_C_CPU1_SB_DQ<5>")
	)
	(arc
		(start 87.46236 -278.463756)
		(mid 87.645868 -278.50925)
		(end 87.82812 -278.45893)
		(width 0.0889)
		(layer "In2.Cu")
		(net "M_C_CPU1_SB_DQ<5>")
	)
	(arc
		(start 86.513924 -278.45893)
		(mid 86.696175 -278.50928)
		(end 86.879684 -278.463756)
		(width 0.0889)
		(layer "In2.Cu")
		(net "M_C_CPU1_SB_DQ<5>")
	)
	(arc
		(start 85.57387 -278.45893)
		(mid 85.756121 -278.50928)
		(end 85.93963 -278.463756)
		(width 0.0889)
		(layer "In2.Cu")
		(net "M_C_CPU1_SB_DQ<5>")
	)
	(arc
		(start 84.068158 -278.45893)
		(mid 84.351114 -278.382753)
		(end 84.63407 -278.45893)
		(width 0.0889)
		(layer "In2.Cu")
		(net "M_C_CPU1_SB_DQ<5>")
	)
	(arc
		(start 94.034102 -278.45893)
		(mid 94.221046 -278.509185)
		(end 94.40799 -278.45893)
		(width 0.0889)
		(layer "In2.Cu")
		(net "M_C_CPU1_SB_DQ<5>")
	)
	(arc
		(start 87.82812 -278.45893)
		(mid 88.111076 -278.382753)
		(end 88.394032 -278.45893)
		(width 0.0889)
		(layer "In2.Cu")
		(net "M_C_CPU1_SB_DQ<5>")
	)
	(arc
		(start 92.528136 -278.45893)
		(mid 92.811092 -278.382753)
		(end 93.094048 -278.45893)
		(width 0.0889)
		(layer "In2.Cu")
		(net "M_C_CPU1_SB_DQ<5>")
	)
	(arc
		(start 85.007958 -278.45893)
		(mid 85.290914 -278.382753)
		(end 85.57387 -278.45893)
		(width 0.0889)
		(layer "In2.Cu")
		(net "M_C_CPU1_SB_DQ<5>")
	)
	(arc
		(start 89.334086 -278.45893)
		(mid 89.52103 -278.509185)
		(end 89.707974 -278.45893)
		(width 0.0889)
		(layer "In2.Cu")
		(net "M_C_CPU1_SB_DQ<5>")
	)
	(arc
		(start 92.162376 -278.463756)
		(mid 92.345884 -278.50925)
		(end 92.528136 -278.45893)
		(width 0.0889)
		(layer "In2.Cu")
		(net "M_C_CPU1_SB_DQ<5>")
	)
	(arc
		(start 91.21394 -278.45893)
		(mid 91.396191 -278.50928)
		(end 91.5797 -278.463756)
		(width 0.0889)
		(layer "In2.Cu")
		(net "M_C_CPU1_SB_DQ<5>")
	)
	(arc
		(start 80.874108 -278.45893)
		(mid 81.061052 -278.509185)
		(end 81.247996 -278.45893)
		(width 0.0889)
		(layer "In2.Cu")
		(net "M_C_CPU1_SB_DQ<5>")
	)
	(arc
		(start 86.888066 -278.45893)
		(mid 87.171022 -278.382753)
		(end 87.453978 -278.45893)
		(width 0.0889)
		(layer "In2.Cu")
		(net "M_C_CPU1_SB_DQ<5>")
	)
	(arc
		(start 82.18805 -278.45893)
		(mid 82.471006 -278.382753)
		(end 82.753962 -278.45893)
		(width 0.0889)
		(layer "In2.Cu")
		(net "M_C_CPU1_SB_DQ<5>")
	)
	(segment
		(start 95.157798 -277.060406)
		(end 94.690946 -277.326344)
		(width 0.10668)
		(layer "F.Cu")
		(net "M_C_CPU1_SB_DQ<4>")
	)
	(segment
		(start 44.340018 -287.43529)
		(end 45.150532 -288.245804)
		(width 0.14478)
		(layer "In2.Cu")
		(net "M_C_CPU1_SB_DQ<4>")
	)
	(segment
		(start 85.10397 -277.648924)
		(end 85.112352 -277.65375)
		(width 0.0889)
		(layer "In2.Cu")
		(net "M_C_CPU1_SB_DQ<4>")
	)
	(segment
		(start 48.776382 -287.870138)
		(end 48.92929 -288.023046)
		(width 0.14478)
		(layer "In2.Cu")
		(net "M_C_CPU1_SB_DQ<4>")
	)
	(segment
		(start 48.92929 -288.457894)
		(end 49.121822 -288.650426)
		(width 0.14478)
		(layer "In2.Cu")
		(net "M_C_CPU1_SB_DQ<4>")
	)
	(segment
		(start 92.989654 -277.65375)
		(end 92.998036 -277.648924)
		(width 0.0889)
		(layer "In2.Cu")
		(net "M_C_CPU1_SB_DQ<4>")
	)
	(segment
		(start 94.44101 -277.617174)
		(end 94.537022 -277.591774)
		(width 0.0889)
		(layer "In2.Cu")
		(net "M_C_CPU1_SB_DQ<4>")
	)
	(segment
		(start 49.599342 -288.460434)
		(end 49.599342 -287.364424)
		(width 0.14478)
		(layer "In2.Cu")
		(net "M_C_CPU1_SB_DQ<4>")
	)
	(segment
		(start 90.74404 -277.648924)
		(end 90.752422 -277.65375)
		(width 0.0889)
		(layer "In2.Cu")
		(net "M_C_CPU1_SB_DQ<4>")
	)
	(segment
		(start 56.784748 -288.107882)
		(end 56.995822 -287.896808)
		(width 0.14478)
		(layer "In2.Cu")
		(net "M_C_CPU1_SB_DQ<4>")
	)
	(segment
		(start 46.090332 -287.522412)
		(end 46.090332 -288.082736)
		(width 0.14478)
		(layer "In2.Cu")
		(net "M_C_CPU1_SB_DQ<4>")
	)
	(segment
		(start 48.92929 -288.023046)
		(end 48.92929 -288.457894)
		(width 0.14478)
		(layer "In2.Cu")
		(net "M_C_CPU1_SB_DQ<4>")
	)
	(segment
		(start 45.696886 -287.359344)
		(end 45.927264 -287.359344)
		(width 0.14478)
		(layer "In2.Cu")
		(net "M_C_CPU1_SB_DQ<4>")
	)
	(segment
		(start 94.537022 -277.591774)
		(end 94.690946 -277.326344)
		(width 0.0889)
		(layer "In2.Cu")
		(net "M_C_CPU1_SB_DQ<4>")
	)
	(segment
		(start 61.31052 -286.775906)
		(end 61.544962 -287.010348)
		(width 0.14478)
		(layer "In2.Cu")
		(net "M_C_CPU1_SB_DQ<4>")
	)
	(segment
		(start 57.882282 -287.010348)
		(end 60.759086 -287.010348)
		(width 0.14478)
		(layer "In2.Cu")
		(net "M_C_CPU1_SB_DQ<4>")
	)
	(segment
		(start 60.759086 -287.010348)
		(end 60.993528 -286.775906)
		(width 0.14478)
		(layer "In2.Cu")
		(net "M_C_CPU1_SB_DQ<4>")
	)
	(segment
		(start 52.753768 -287.02)
		(end 53.020976 -287.287208)
		(width 0.14478)
		(layer "In2.Cu")
		(net "M_C_CPU1_SB_DQ<4>")
	)
	(segment
		(start 80.769714 -277.65375)
		(end 80.778096 -277.648924)
		(width 0.0889)
		(layer "In2.Cu")
		(net "M_C_CPU1_SB_DQ<4>")
	)
	(segment
		(start 53.811932 -288.128964)
		(end 54.040786 -288.128964)
		(width 0.14478)
		(layer "In2.Cu")
		(net "M_C_CPU1_SB_DQ<4>")
	)
	(segment
		(start 50.244502 -287.453324)
		(end 50.456846 -287.453324)
		(width 0.14478)
		(layer "In2.Cu")
		(net "M_C_CPU1_SB_DQ<4>")
	)
	(segment
		(start 49.749202 -287.214564)
		(end 50.005742 -287.214564)
		(width 0.14478)
		(layer "In2.Cu")
		(net "M_C_CPU1_SB_DQ<4>")
	)
	(segment
		(start 61.544962 -287.010348)
		(end 61.79185 -287.010348)
		(width 0.14478)
		(layer "In2.Cu")
		(net "M_C_CPU1_SB_DQ<4>")
	)
	(segment
		(start 46.2534 -288.245804)
		(end 46.42104 -288.245804)
		(width 0.14478)
		(layer "In2.Cu")
		(net "M_C_CPU1_SB_DQ<4>")
	)
	(segment
		(start 89.229692 -277.65375)
		(end 89.238074 -277.648924)
		(width 0.0889)
		(layer "In2.Cu")
		(net "M_C_CPU1_SB_DQ<4>")
	)
	(segment
		(start 53.020976 -287.287208)
		(end 53.40223 -287.287208)
		(width 0.14478)
		(layer "In2.Cu")
		(net "M_C_CPU1_SB_DQ<4>")
	)
	(segment
		(start 71.878444 -276.923754)
		(end 75.957176 -276.923754)
		(width 0.14478)
		(layer "In2.Cu")
		(net "M_C_CPU1_SB_DQ<4>")
	)
	(segment
		(start 54.040786 -288.128964)
		(end 54.309264 -287.860486)
		(width 0.14478)
		(layer "In2.Cu")
		(net "M_C_CPU1_SB_DQ<4>")
	)
	(segment
		(start 78.895956 -277.64867)
		(end 78.92923 -277.629366)
		(width 0.0889)
		(layer "In2.Cu")
		(net "M_C_CPU1_SB_DQ<4>")
	)
	(segment
		(start 45.927264 -287.359344)
		(end 46.090332 -287.522412)
		(width 0.14478)
		(layer "In2.Cu")
		(net "M_C_CPU1_SB_DQ<4>")
	)
	(segment
		(start 86.044024 -277.648924)
		(end 86.052406 -277.65375)
		(width 0.0889)
		(layer "In2.Cu")
		(net "M_C_CPU1_SB_DQ<4>")
	)
	(segment
		(start 57.644792 -287.503362)
		(end 57.644792 -287.247838)
		(width 0.14478)
		(layer "In2.Cu")
		(net "M_C_CPU1_SB_DQ<4>")
	)
	(segment
		(start 81.344008 -277.648924)
		(end 81.35239 -277.65375)
		(width 0.0889)
		(layer "In2.Cu")
		(net "M_C_CPU1_SB_DQ<4>")
	)
	(segment
		(start 89.803986 -277.648924)
		(end 89.812368 -277.65375)
		(width 0.0889)
		(layer "In2.Cu")
		(net "M_C_CPU1_SB_DQ<4>")
	)
	(segment
		(start 53.40223 -287.287208)
		(end 53.593746 -287.478724)
		(width 0.14478)
		(layer "In2.Cu")
		(net "M_C_CPU1_SB_DQ<4>")
	)
	(segment
		(start 88.289638 -277.65375)
		(end 88.29802 -277.648924)
		(width 0.0889)
		(layer "In2.Cu")
		(net "M_C_CPU1_SB_DQ<4>")
	)
	(segment
		(start 76.802234 -277.311612)
		(end 77.954632 -277.311612)
		(width 0.0889)
		(layer "In2.Cu")
		(net "M_C_CPU1_SB_DQ<4>")
	)
	(segment
		(start 77.954632 -277.311612)
		(end 78.33614 -277.69312)
		(width 0.0889)
		(layer "In2.Cu")
		(net "M_C_CPU1_SB_DQ<4>")
	)
	(segment
		(start 56.995822 -287.896808)
		(end 57.251346 -287.896808)
		(width 0.14478)
		(layer "In2.Cu")
		(net "M_C_CPU1_SB_DQ<4>")
	)
	(segment
		(start 57.642506 -288.057844)
		(end 57.805828 -287.894522)
		(width 0.14478)
		(layer "In2.Cu")
		(net "M_C_CPU1_SB_DQ<4>")
	)
	(segment
		(start 93.929708 -277.65375)
		(end 93.93809 -277.648924)
		(width 0.0889)
		(layer "In2.Cu")
		(net "M_C_CPU1_SB_DQ<4>")
	)
	(segment
		(start 46.796706 -287.870138)
		(end 48.776382 -287.870138)
		(width 0.14478)
		(layer "In2.Cu")
		(net "M_C_CPU1_SB_DQ<4>")
	)
	(segment
		(start 49.40935 -288.650426)
		(end 49.599342 -288.460434)
		(width 0.14478)
		(layer "In2.Cu")
		(net "M_C_CPU1_SB_DQ<4>")
	)
	(segment
		(start 45.533818 -288.082736)
		(end 45.533818 -287.522412)
		(width 0.14478)
		(layer "In2.Cu")
		(net "M_C_CPU1_SB_DQ<4>")
	)
	(segment
		(start 78.33614 -277.69312)
		(end 78.730856 -277.69312)
		(width 0.0889)
		(layer "In2.Cu")
		(net "M_C_CPU1_SB_DQ<4>")
	)
	(segment
		(start 75.957176 -276.923754)
		(end 76.414376 -276.923754)
		(width 0.0889)
		(layer "In2.Cu")
		(net "M_C_CPU1_SB_DQ<4>")
	)
	(segment
		(start 80.372204 -277.630382)
		(end 80.403954 -277.648924)
		(width 0.0889)
		(layer "In2.Cu")
		(net "M_C_CPU1_SB_DQ<4>")
	)
	(segment
		(start 61.79185 -287.010348)
		(end 71.878444 -276.923754)
		(width 0.14478)
		(layer "In2.Cu")
		(net "M_C_CPU1_SB_DQ<4>")
	)
	(segment
		(start 53.593746 -287.478724)
		(end 53.593746 -287.910778)
		(width 0.14478)
		(layer "In2.Cu")
		(net "M_C_CPU1_SB_DQ<4>")
	)
	(segment
		(start 60.993528 -286.775906)
		(end 61.31052 -286.775906)
		(width 0.14478)
		(layer "In2.Cu")
		(net "M_C_CPU1_SB_DQ<4>")
	)
	(segment
		(start 45.37075 -288.245804)
		(end 45.533818 -288.082736)
		(width 0.14478)
		(layer "In2.Cu")
		(net "M_C_CPU1_SB_DQ<4>")
	)
	(segment
		(start 57.412382 -288.057844)
		(end 57.642506 -288.057844)
		(width 0.14478)
		(layer "In2.Cu")
		(net "M_C_CPU1_SB_DQ<4>")
	)
	(segment
		(start 57.644792 -287.247838)
		(end 57.882282 -287.010348)
		(width 0.14478)
		(layer "In2.Cu")
		(net "M_C_CPU1_SB_DQ<4>")
	)
	(segment
		(start 50.005742 -287.214564)
		(end 50.244502 -287.453324)
		(width 0.14478)
		(layer "In2.Cu")
		(net "M_C_CPU1_SB_DQ<4>")
	)
	(segment
		(start 57.251346 -287.896808)
		(end 57.412382 -288.057844)
		(width 0.14478)
		(layer "In2.Cu")
		(net "M_C_CPU1_SB_DQ<4>")
	)
	(segment
		(start 83.589622 -277.65375)
		(end 83.598004 -277.648924)
		(width 0.0889)
		(layer "In2.Cu")
		(net "M_C_CPU1_SB_DQ<4>")
	)
	(segment
		(start 57.805828 -287.894522)
		(end 57.805828 -287.664398)
		(width 0.14478)
		(layer "In2.Cu")
		(net "M_C_CPU1_SB_DQ<4>")
	)
	(segment
		(start 53.593746 -287.910778)
		(end 53.811932 -288.128964)
		(width 0.14478)
		(layer "In2.Cu")
		(net "M_C_CPU1_SB_DQ<4>")
	)
	(segment
		(start 50.456846 -287.453324)
		(end 50.89017 -287.02)
		(width 0.14478)
		(layer "In2.Cu")
		(net "M_C_CPU1_SB_DQ<4>")
	)
	(segment
		(start 84.529676 -277.65375)
		(end 84.538058 -277.648924)
		(width 0.0889)
		(layer "In2.Cu")
		(net "M_C_CPU1_SB_DQ<4>")
	)
	(segment
		(start 79.45882 -277.648924)
		(end 79.484982 -277.664164)
		(width 0.0889)
		(layer "In2.Cu")
		(net "M_C_CPU1_SB_DQ<4>")
	)
	(segment
		(start 46.090332 -288.082736)
		(end 46.2534 -288.245804)
		(width 0.14478)
		(layer "In2.Cu")
		(net "M_C_CPU1_SB_DQ<4>")
	)
	(segment
		(start 57.805828 -287.664398)
		(end 57.644792 -287.503362)
		(width 0.14478)
		(layer "In2.Cu")
		(net "M_C_CPU1_SB_DQ<4>")
	)
	(segment
		(start 45.150532 -288.245804)
		(end 45.37075 -288.245804)
		(width 0.14478)
		(layer "In2.Cu")
		(net "M_C_CPU1_SB_DQ<4>")
	)
	(segment
		(start 49.121822 -288.650426)
		(end 49.40935 -288.650426)
		(width 0.14478)
		(layer "In2.Cu")
		(net "M_C_CPU1_SB_DQ<4>")
	)
	(segment
		(start 56.572658 -288.107882)
		(end 56.784748 -288.107882)
		(width 0.14478)
		(layer "In2.Cu")
		(net "M_C_CPU1_SB_DQ<4>")
	)
	(segment
		(start 46.42104 -288.245804)
		(end 46.796706 -287.870138)
		(width 0.14478)
		(layer "In2.Cu")
		(net "M_C_CPU1_SB_DQ<4>")
	)
	(segment
		(start 56.325262 -287.860486)
		(end 56.572658 -288.107882)
		(width 0.14478)
		(layer "In2.Cu")
		(net "M_C_CPU1_SB_DQ<4>")
	)
	(segment
		(start 45.533818 -287.522412)
		(end 45.696886 -287.359344)
		(width 0.14478)
		(layer "In2.Cu")
		(net "M_C_CPU1_SB_DQ<4>")
	)
	(segment
		(start 76.414376 -276.923754)
		(end 76.802234 -277.311612)
		(width 0.0889)
		(layer "In2.Cu")
		(net "M_C_CPU1_SB_DQ<4>")
	)
	(segment
		(start 50.89017 -287.02)
		(end 52.753768 -287.02)
		(width 0.14478)
		(layer "In2.Cu")
		(net "M_C_CPU1_SB_DQ<4>")
	)
	(segment
		(start 54.309264 -287.860486)
		(end 56.325262 -287.860486)
		(width 0.14478)
		(layer "In2.Cu")
		(net "M_C_CPU1_SB_DQ<4>")
	)
	(segment
		(start 49.599342 -287.364424)
		(end 49.749202 -287.214564)
		(width 0.14478)
		(layer "In2.Cu")
		(net "M_C_CPU1_SB_DQ<4>")
	)
	(arc
		(start 82.65795 -277.648924)
		(mid 82.940906 -277.572747)
		(end 83.223862 -277.648924)
		(width 0.0889)
		(layer "In2.Cu")
		(net "M_C_CPU1_SB_DQ<4>")
	)
	(arc
		(start 84.538058 -277.648924)
		(mid 84.821014 -277.572747)
		(end 85.10397 -277.648924)
		(width 0.0889)
		(layer "In2.Cu")
		(net "M_C_CPU1_SB_DQ<4>")
	)
	(arc
		(start 89.812368 -277.65375)
		(mid 89.995876 -277.699244)
		(end 90.178128 -277.648924)
		(width 0.0889)
		(layer "In2.Cu")
		(net "M_C_CPU1_SB_DQ<4>")
	)
	(arc
		(start 78.92923 -277.629366)
		(mid 79.19646 -277.573055)
		(end 79.45882 -277.648924)
		(width 0.0889)
		(layer "In2.Cu")
		(net "M_C_CPU1_SB_DQ<4>")
	)
	(arc
		(start 89.238074 -277.648924)
		(mid 89.52103 -277.572747)
		(end 89.803986 -277.648924)
		(width 0.0889)
		(layer "In2.Cu")
		(net "M_C_CPU1_SB_DQ<4>")
	)
	(arc
		(start 79.484982 -277.664164)
		(mid 79.661983 -277.700242)
		(end 79.835248 -277.649178)
		(width 0.0889)
		(layer "In2.Cu")
		(net "M_C_CPU1_SB_DQ<4>")
	)
	(arc
		(start 90.752422 -277.65375)
		(mid 90.93593 -277.699244)
		(end 91.118182 -277.648924)
		(width 0.0889)
		(layer "In2.Cu")
		(net "M_C_CPU1_SB_DQ<4>")
	)
	(arc
		(start 91.684094 -277.648924)
		(mid 91.871038 -277.699179)
		(end 92.057982 -277.648924)
		(width 0.0889)
		(layer "In2.Cu")
		(net "M_C_CPU1_SB_DQ<4>")
	)
	(arc
		(start 88.29802 -277.648924)
		(mid 88.580976 -277.572747)
		(end 88.863932 -277.648924)
		(width 0.0889)
		(layer "In2.Cu")
		(net "M_C_CPU1_SB_DQ<4>")
	)
	(arc
		(start 78.730856 -277.69312)
		(mid 78.816352 -277.681824)
		(end 78.895956 -277.64867)
		(width 0.0889)
		(layer "In2.Cu")
		(net "M_C_CPU1_SB_DQ<4>")
	)
	(arc
		(start 83.223862 -277.648924)
		(mid 83.406113 -277.699274)
		(end 83.589622 -277.65375)
		(width 0.0889)
		(layer "In2.Cu")
		(net "M_C_CPU1_SB_DQ<4>")
	)
	(arc
		(start 86.052406 -277.65375)
		(mid 86.235914 -277.699244)
		(end 86.418166 -277.648924)
		(width 0.0889)
		(layer "In2.Cu")
		(net "M_C_CPU1_SB_DQ<4>")
	)
	(arc
		(start 85.478112 -277.648924)
		(mid 85.761068 -277.572747)
		(end 86.044024 -277.648924)
		(width 0.0889)
		(layer "In2.Cu")
		(net "M_C_CPU1_SB_DQ<4>")
	)
	(arc
		(start 79.835248 -277.649178)
		(mid 80.101337 -277.571901)
		(end 80.372204 -277.630382)
		(width 0.0889)
		(layer "In2.Cu")
		(net "M_C_CPU1_SB_DQ<4>")
	)
	(arc
		(start 80.403954 -277.648924)
		(mid 80.586205 -277.699274)
		(end 80.769714 -277.65375)
		(width 0.0889)
		(layer "In2.Cu")
		(net "M_C_CPU1_SB_DQ<4>")
	)
	(arc
		(start 84.163916 -277.648924)
		(mid 84.346167 -277.699274)
		(end 84.529676 -277.65375)
		(width 0.0889)
		(layer "In2.Cu")
		(net "M_C_CPU1_SB_DQ<4>")
	)
	(arc
		(start 82.284062 -277.648924)
		(mid 82.471006 -277.699179)
		(end 82.65795 -277.648924)
		(width 0.0889)
		(layer "In2.Cu")
		(net "M_C_CPU1_SB_DQ<4>")
	)
	(arc
		(start 91.118182 -277.648924)
		(mid 91.401138 -277.572747)
		(end 91.684094 -277.648924)
		(width 0.0889)
		(layer "In2.Cu")
		(net "M_C_CPU1_SB_DQ<4>")
	)
	(arc
		(start 88.863932 -277.648924)
		(mid 89.046183 -277.699274)
		(end 89.229692 -277.65375)
		(width 0.0889)
		(layer "In2.Cu")
		(net "M_C_CPU1_SB_DQ<4>")
	)
	(arc
		(start 92.998036 -277.648924)
		(mid 93.280992 -277.572747)
		(end 93.563948 -277.648924)
		(width 0.0889)
		(layer "In2.Cu")
		(net "M_C_CPU1_SB_DQ<4>")
	)
	(arc
		(start 80.778096 -277.648924)
		(mid 81.061052 -277.572747)
		(end 81.344008 -277.648924)
		(width 0.0889)
		(layer "In2.Cu")
		(net "M_C_CPU1_SB_DQ<4>")
	)
	(arc
		(start 81.71815 -277.648924)
		(mid 82.001106 -277.572747)
		(end 82.284062 -277.648924)
		(width 0.0889)
		(layer "In2.Cu")
		(net "M_C_CPU1_SB_DQ<4>")
	)
	(arc
		(start 93.563948 -277.648924)
		(mid 93.746199 -277.699274)
		(end 93.929708 -277.65375)
		(width 0.0889)
		(layer "In2.Cu")
		(net "M_C_CPU1_SB_DQ<4>")
	)
	(arc
		(start 83.598004 -277.648924)
		(mid 83.88096 -277.572747)
		(end 84.163916 -277.648924)
		(width 0.0889)
		(layer "In2.Cu")
		(net "M_C_CPU1_SB_DQ<4>")
	)
	(arc
		(start 87.923878 -277.648924)
		(mid 88.106129 -277.699274)
		(end 88.289638 -277.65375)
		(width 0.0889)
		(layer "In2.Cu")
		(net "M_C_CPU1_SB_DQ<4>")
	)
	(arc
		(start 93.93809 -277.648924)
		(mid 94.185803 -277.573704)
		(end 94.44101 -277.617174)
		(width 0.0889)
		(layer "In2.Cu")
		(net "M_C_CPU1_SB_DQ<4>")
	)
	(arc
		(start 81.35239 -277.65375)
		(mid 81.535898 -277.699244)
		(end 81.71815 -277.648924)
		(width 0.0889)
		(layer "In2.Cu")
		(net "M_C_CPU1_SB_DQ<4>")
	)
	(arc
		(start 87.357966 -277.648924)
		(mid 87.640922 -277.572747)
		(end 87.923878 -277.648924)
		(width 0.0889)
		(layer "In2.Cu")
		(net "M_C_CPU1_SB_DQ<4>")
	)
	(arc
		(start 85.112352 -277.65375)
		(mid 85.29586 -277.699244)
		(end 85.478112 -277.648924)
		(width 0.0889)
		(layer "In2.Cu")
		(net "M_C_CPU1_SB_DQ<4>")
	)
	(arc
		(start 92.623894 -277.648924)
		(mid 92.806145 -277.699274)
		(end 92.989654 -277.65375)
		(width 0.0889)
		(layer "In2.Cu")
		(net "M_C_CPU1_SB_DQ<4>")
	)
	(arc
		(start 92.057982 -277.648924)
		(mid 92.340938 -277.572747)
		(end 92.623894 -277.648924)
		(width 0.0889)
		(layer "In2.Cu")
		(net "M_C_CPU1_SB_DQ<4>")
	)
	(arc
		(start 90.178128 -277.648924)
		(mid 90.461084 -277.572747)
		(end 90.74404 -277.648924)
		(width 0.0889)
		(layer "In2.Cu")
		(net "M_C_CPU1_SB_DQ<4>")
	)
	(arc
		(start 86.418166 -277.648924)
		(mid 86.701122 -277.572747)
		(end 86.984078 -277.648924)
		(width 0.0889)
		(layer "In2.Cu")
		(net "M_C_CPU1_SB_DQ<4>")
	)
	(arc
		(start 86.984078 -277.648924)
		(mid 87.171022 -277.699179)
		(end 87.357966 -277.648924)
		(width 0.0889)
		(layer "In2.Cu")
		(net "M_C_CPU1_SB_DQ<4>")
	)
	(segment
		(start 96.097852 -275.440394)
		(end 95.631 -275.706332)
		(width 0.10668)
		(layer "F.Cu")
		(net "M_C_CPU1_SB_DQ<3>")
	)
	(segment
		(start 78.897734 -275.384006)
		(end 78.903322 -275.387308)
		(width 0.0889)
		(layer "In2.Cu")
		(net "M_C_CPU1_SB_DQ<3>")
	)
	(segment
		(start 42.281856 -284.450536)
		(end 48.870108 -284.450536)
		(width 0.14478)
		(layer "In2.Cu")
		(net "M_C_CPU1_SB_DQ<3>")
	)
	(segment
		(start 57.7977 -283.610304)
		(end 60.332874 -283.610304)
		(width 0.14478)
		(layer "In2.Cu")
		(net "M_C_CPU1_SB_DQ<3>")
	)
	(segment
		(start 75.940666 -274.584414)
		(end 76.510896 -274.584414)
		(width 0.0889)
		(layer "In2.Cu")
		(net "M_C_CPU1_SB_DQ<3>")
	)
	(segment
		(start 95.785178 -275.440902)
		(end 95.631 -275.706332)
		(width 0.0889)
		(layer "In2.Cu")
		(net "M_C_CPU1_SB_DQ<3>")
	)
	(segment
		(start 95.762826 -275.35759)
		(end 95.785178 -275.440902)
		(width 0.0889)
		(layer "In2.Cu")
		(net "M_C_CPU1_SB_DQ<3>")
	)
	(segment
		(start 41.572688 -284.060138)
		(end 41.735502 -283.897324)
		(width 0.14478)
		(layer "In2.Cu")
		(net "M_C_CPU1_SB_DQ<3>")
	)
	(segment
		(start 40.23995 -284.035246)
		(end 40.665146 -284.460442)
		(width 0.14478)
		(layer "In2.Cu")
		(net "M_C_CPU1_SB_DQ<3>")
	)
	(segment
		(start 80.769714 -275.378926)
		(end 80.778096 -275.383752)
		(width 0.0889)
		(layer "In2.Cu")
		(net "M_C_CPU1_SB_DQ<3>")
	)
	(segment
		(start 89.229692 -275.378926)
		(end 89.238074 -275.383752)
		(width 0.0889)
		(layer "In2.Cu")
		(net "M_C_CPU1_SB_DQ<3>")
	)
	(segment
		(start 84.529676 -275.378926)
		(end 84.538058 -275.383752)
		(width 0.0889)
		(layer "In2.Cu")
		(net "M_C_CPU1_SB_DQ<3>")
	)
	(segment
		(start 92.989654 -275.378926)
		(end 92.998036 -275.383752)
		(width 0.0889)
		(layer "In2.Cu")
		(net "M_C_CPU1_SB_DQ<3>")
	)
	(segment
		(start 64.252348 -280.786586)
		(end 70.45452 -274.584414)
		(width 0.14478)
		(layer "In2.Cu")
		(net "M_C_CPU1_SB_DQ<3>")
	)
	(segment
		(start 41.735502 -283.897324)
		(end 41.966134 -283.897324)
		(width 0.14478)
		(layer "In2.Cu")
		(net "M_C_CPU1_SB_DQ<3>")
	)
	(segment
		(start 77.266038 -275.339556)
		(end 78.735174 -275.339556)
		(width 0.0889)
		(layer "In2.Cu")
		(net "M_C_CPU1_SB_DQ<3>")
	)
	(segment
		(start 63.156592 -280.786586)
		(end 64.252348 -280.786586)
		(width 0.14478)
		(layer "In2.Cu")
		(net "M_C_CPU1_SB_DQ<3>")
	)
	(segment
		(start 93.929708 -275.378926)
		(end 93.93809 -275.383752)
		(width 0.0889)
		(layer "In2.Cu")
		(net "M_C_CPU1_SB_DQ<3>")
	)
	(segment
		(start 41.409874 -284.460442)
		(end 41.572688 -284.297628)
		(width 0.14478)
		(layer "In2.Cu")
		(net "M_C_CPU1_SB_DQ<3>")
	)
	(segment
		(start 85.10397 -275.383752)
		(end 85.112352 -275.378926)
		(width 0.0889)
		(layer "In2.Cu")
		(net "M_C_CPU1_SB_DQ<3>")
	)
	(segment
		(start 40.665146 -284.460442)
		(end 41.409874 -284.460442)
		(width 0.14478)
		(layer "In2.Cu")
		(net "M_C_CPU1_SB_DQ<3>")
	)
	(segment
		(start 79.463138 -275.383752)
		(end 79.474822 -275.376894)
		(width 0.0889)
		(layer "In2.Cu")
		(net "M_C_CPU1_SB_DQ<3>")
	)
	(segment
		(start 89.803986 -275.383752)
		(end 89.812368 -275.378926)
		(width 0.0889)
		(layer "In2.Cu")
		(net "M_C_CPU1_SB_DQ<3>")
	)
	(segment
		(start 90.74404 -275.383752)
		(end 90.752422 -275.378926)
		(width 0.0889)
		(layer "In2.Cu")
		(net "M_C_CPU1_SB_DQ<3>")
	)
	(segment
		(start 53.383688 -283.600652)
		(end 54.243478 -284.460442)
		(width 0.14478)
		(layer "In2.Cu")
		(net "M_C_CPU1_SB_DQ<3>")
	)
	(segment
		(start 70.45452 -274.584414)
		(end 75.940666 -274.584414)
		(width 0.14478)
		(layer "In2.Cu")
		(net "M_C_CPU1_SB_DQ<3>")
	)
	(segment
		(start 42.128948 -284.060138)
		(end 42.128948 -284.297628)
		(width 0.14478)
		(layer "In2.Cu")
		(net "M_C_CPU1_SB_DQ<3>")
	)
	(segment
		(start 41.966134 -283.897324)
		(end 42.128948 -284.060138)
		(width 0.14478)
		(layer "In2.Cu")
		(net "M_C_CPU1_SB_DQ<3>")
	)
	(segment
		(start 76.510896 -274.584414)
		(end 77.266038 -275.339556)
		(width 0.0889)
		(layer "In2.Cu")
		(net "M_C_CPU1_SB_DQ<3>")
	)
	(segment
		(start 60.332874 -283.610304)
		(end 63.156592 -280.786586)
		(width 0.14478)
		(layer "In2.Cu")
		(net "M_C_CPU1_SB_DQ<3>")
	)
	(segment
		(start 80.389222 -275.392388)
		(end 80.403954 -275.383752)
		(width 0.0889)
		(layer "In2.Cu")
		(net "M_C_CPU1_SB_DQ<3>")
	)
	(segment
		(start 86.044024 -275.383752)
		(end 86.052406 -275.378926)
		(width 0.0889)
		(layer "In2.Cu")
		(net "M_C_CPU1_SB_DQ<3>")
	)
	(segment
		(start 42.128948 -284.297628)
		(end 42.281856 -284.450536)
		(width 0.14478)
		(layer "In2.Cu")
		(net "M_C_CPU1_SB_DQ<3>")
	)
	(segment
		(start 48.870108 -284.450536)
		(end 49.719992 -283.600652)
		(width 0.14478)
		(layer "In2.Cu")
		(net "M_C_CPU1_SB_DQ<3>")
	)
	(segment
		(start 95.444056 -275.383752)
		(end 95.452438 -275.378926)
		(width 0.0889)
		(layer "In2.Cu")
		(net "M_C_CPU1_SB_DQ<3>")
	)
	(segment
		(start 49.719992 -283.600652)
		(end 53.383688 -283.600652)
		(width 0.14478)
		(layer "In2.Cu")
		(net "M_C_CPU1_SB_DQ<3>")
	)
	(segment
		(start 56.947562 -284.460442)
		(end 57.7977 -283.610304)
		(width 0.14478)
		(layer "In2.Cu")
		(net "M_C_CPU1_SB_DQ<3>")
	)
	(segment
		(start 88.289638 -275.378926)
		(end 88.29802 -275.383752)
		(width 0.0889)
		(layer "In2.Cu")
		(net "M_C_CPU1_SB_DQ<3>")
	)
	(segment
		(start 94.504002 -275.383752)
		(end 94.512384 -275.378926)
		(width 0.0889)
		(layer "In2.Cu")
		(net "M_C_CPU1_SB_DQ<3>")
	)
	(segment
		(start 41.572688 -284.297628)
		(end 41.572688 -284.060138)
		(width 0.14478)
		(layer "In2.Cu")
		(net "M_C_CPU1_SB_DQ<3>")
	)
	(segment
		(start 54.243478 -284.460442)
		(end 56.947562 -284.460442)
		(width 0.14478)
		(layer "In2.Cu")
		(net "M_C_CPU1_SB_DQ<3>")
	)
	(segment
		(start 81.344008 -275.383752)
		(end 81.35239 -275.378926)
		(width 0.0889)
		(layer "In2.Cu")
		(net "M_C_CPU1_SB_DQ<3>")
	)
	(segment
		(start 83.589622 -275.378926)
		(end 83.598004 -275.383752)
		(width 0.0889)
		(layer "In2.Cu")
		(net "M_C_CPU1_SB_DQ<3>")
	)
	(arc
		(start 93.93809 -275.383752)
		(mid 94.221046 -275.459929)
		(end 94.504002 -275.383752)
		(width 0.0889)
		(layer "In2.Cu")
		(net "M_C_CPU1_SB_DQ<3>")
	)
	(arc
		(start 78.735174 -275.339556)
		(mid 78.819439 -275.350867)
		(end 78.897734 -275.384006)
		(width 0.0889)
		(layer "In2.Cu")
		(net "M_C_CPU1_SB_DQ<3>")
	)
	(arc
		(start 83.223862 -275.383752)
		(mid 83.406113 -275.333402)
		(end 83.589622 -275.378926)
		(width 0.0889)
		(layer "In2.Cu")
		(net "M_C_CPU1_SB_DQ<3>")
	)
	(arc
		(start 94.512384 -275.378926)
		(mid 94.695892 -275.333432)
		(end 94.878144 -275.383752)
		(width 0.0889)
		(layer "In2.Cu")
		(net "M_C_CPU1_SB_DQ<3>")
	)
	(arc
		(start 85.112352 -275.378926)
		(mid 85.29586 -275.333432)
		(end 85.478112 -275.383752)
		(width 0.0889)
		(layer "In2.Cu")
		(net "M_C_CPU1_SB_DQ<3>")
	)
	(arc
		(start 83.598004 -275.383752)
		(mid 83.88096 -275.459929)
		(end 84.163916 -275.383752)
		(width 0.0889)
		(layer "In2.Cu")
		(net "M_C_CPU1_SB_DQ<3>")
	)
	(arc
		(start 91.684094 -275.383752)
		(mid 91.871038 -275.333497)
		(end 92.057982 -275.383752)
		(width 0.0889)
		(layer "In2.Cu")
		(net "M_C_CPU1_SB_DQ<3>")
	)
	(arc
		(start 81.35239 -275.378926)
		(mid 81.535898 -275.333432)
		(end 81.71815 -275.383752)
		(width 0.0889)
		(layer "In2.Cu")
		(net "M_C_CPU1_SB_DQ<3>")
	)
	(arc
		(start 84.538058 -275.383752)
		(mid 84.821014 -275.459929)
		(end 85.10397 -275.383752)
		(width 0.0889)
		(layer "In2.Cu")
		(net "M_C_CPU1_SB_DQ<3>")
	)
	(arc
		(start 86.418166 -275.383752)
		(mid 86.701122 -275.459929)
		(end 86.984078 -275.383752)
		(width 0.0889)
		(layer "In2.Cu")
		(net "M_C_CPU1_SB_DQ<3>")
	)
	(arc
		(start 79.474822 -275.376894)
		(mid 79.657077 -275.333241)
		(end 79.837534 -275.383752)
		(width 0.0889)
		(layer "In2.Cu")
		(net "M_C_CPU1_SB_DQ<3>")
	)
	(arc
		(start 88.863932 -275.383752)
		(mid 89.046183 -275.333402)
		(end 89.229692 -275.378926)
		(width 0.0889)
		(layer "In2.Cu")
		(net "M_C_CPU1_SB_DQ<3>")
	)
	(arc
		(start 82.65795 -275.383752)
		(mid 82.940906 -275.459929)
		(end 83.223862 -275.383752)
		(width 0.0889)
		(layer "In2.Cu")
		(net "M_C_CPU1_SB_DQ<3>")
	)
	(arc
		(start 93.563948 -275.383752)
		(mid 93.746199 -275.333402)
		(end 93.929708 -275.378926)
		(width 0.0889)
		(layer "In2.Cu")
		(net "M_C_CPU1_SB_DQ<3>")
	)
	(arc
		(start 78.903322 -275.387308)
		(mid 79.183711 -275.459977)
		(end 79.463138 -275.383752)
		(width 0.0889)
		(layer "In2.Cu")
		(net "M_C_CPU1_SB_DQ<3>")
	)
	(arc
		(start 89.812368 -275.378926)
		(mid 89.995876 -275.333432)
		(end 90.178128 -275.383752)
		(width 0.0889)
		(layer "In2.Cu")
		(net "M_C_CPU1_SB_DQ<3>")
	)
	(arc
		(start 87.923878 -275.383752)
		(mid 88.106129 -275.333402)
		(end 88.289638 -275.378926)
		(width 0.0889)
		(layer "In2.Cu")
		(net "M_C_CPU1_SB_DQ<3>")
	)
	(arc
		(start 90.752422 -275.378926)
		(mid 90.93593 -275.333432)
		(end 91.118182 -275.383752)
		(width 0.0889)
		(layer "In2.Cu")
		(net "M_C_CPU1_SB_DQ<3>")
	)
	(arc
		(start 90.178128 -275.383752)
		(mid 90.461084 -275.459929)
		(end 90.74404 -275.383752)
		(width 0.0889)
		(layer "In2.Cu")
		(net "M_C_CPU1_SB_DQ<3>")
	)
	(arc
		(start 85.478112 -275.383752)
		(mid 85.761068 -275.459929)
		(end 86.044024 -275.383752)
		(width 0.0889)
		(layer "In2.Cu")
		(net "M_C_CPU1_SB_DQ<3>")
	)
	(arc
		(start 95.452438 -275.378926)
		(mid 95.605308 -275.334285)
		(end 95.762826 -275.35759)
		(width 0.0889)
		(layer "In2.Cu")
		(net "M_C_CPU1_SB_DQ<3>")
	)
	(arc
		(start 80.778096 -275.383752)
		(mid 81.061052 -275.459929)
		(end 81.344008 -275.383752)
		(width 0.0889)
		(layer "In2.Cu")
		(net "M_C_CPU1_SB_DQ<3>")
	)
	(arc
		(start 89.238074 -275.383752)
		(mid 89.52103 -275.459929)
		(end 89.803986 -275.383752)
		(width 0.0889)
		(layer "In2.Cu")
		(net "M_C_CPU1_SB_DQ<3>")
	)
	(arc
		(start 92.623894 -275.383752)
		(mid 92.806145 -275.333402)
		(end 92.989654 -275.378926)
		(width 0.0889)
		(layer "In2.Cu")
		(net "M_C_CPU1_SB_DQ<3>")
	)
	(arc
		(start 91.118182 -275.383752)
		(mid 91.401138 -275.459929)
		(end 91.684094 -275.383752)
		(width 0.0889)
		(layer "In2.Cu")
		(net "M_C_CPU1_SB_DQ<3>")
	)
	(arc
		(start 92.057982 -275.383752)
		(mid 92.340938 -275.459929)
		(end 92.623894 -275.383752)
		(width 0.0889)
		(layer "In2.Cu")
		(net "M_C_CPU1_SB_DQ<3>")
	)
	(arc
		(start 86.052406 -275.378926)
		(mid 86.235914 -275.333432)
		(end 86.418166 -275.383752)
		(width 0.0889)
		(layer "In2.Cu")
		(net "M_C_CPU1_SB_DQ<3>")
	)
	(arc
		(start 87.357966 -275.383752)
		(mid 87.640922 -275.459929)
		(end 87.923878 -275.383752)
		(width 0.0889)
		(layer "In2.Cu")
		(net "M_C_CPU1_SB_DQ<3>")
	)
	(arc
		(start 84.163916 -275.383752)
		(mid 84.346167 -275.333402)
		(end 84.529676 -275.378926)
		(width 0.0889)
		(layer "In2.Cu")
		(net "M_C_CPU1_SB_DQ<3>")
	)
	(arc
		(start 80.403954 -275.383752)
		(mid 80.586205 -275.333402)
		(end 80.769714 -275.378926)
		(width 0.0889)
		(layer "In2.Cu")
		(net "M_C_CPU1_SB_DQ<3>")
	)
	(arc
		(start 94.878144 -275.383752)
		(mid 95.1611 -275.459929)
		(end 95.444056 -275.383752)
		(width 0.0889)
		(layer "In2.Cu")
		(net "M_C_CPU1_SB_DQ<3>")
	)
	(arc
		(start 88.29802 -275.383752)
		(mid 88.580976 -275.459929)
		(end 88.863932 -275.383752)
		(width 0.0889)
		(layer "In2.Cu")
		(net "M_C_CPU1_SB_DQ<3>")
	)
	(arc
		(start 92.998036 -275.383752)
		(mid 93.280992 -275.459929)
		(end 93.563948 -275.383752)
		(width 0.0889)
		(layer "In2.Cu")
		(net "M_C_CPU1_SB_DQ<3>")
	)
	(arc
		(start 81.71815 -275.383752)
		(mid 82.001106 -275.459929)
		(end 82.284062 -275.383752)
		(width 0.0889)
		(layer "In2.Cu")
		(net "M_C_CPU1_SB_DQ<3>")
	)
	(arc
		(start 82.284062 -275.383752)
		(mid 82.471006 -275.333497)
		(end 82.65795 -275.383752)
		(width 0.0889)
		(layer "In2.Cu")
		(net "M_C_CPU1_SB_DQ<3>")
	)
	(arc
		(start 79.837534 -275.383752)
		(mid 80.11224 -275.460116)
		(end 80.389222 -275.392388)
		(width 0.0889)
		(layer "In2.Cu")
		(net "M_C_CPU1_SB_DQ<3>")
	)
	(arc
		(start 86.984078 -275.383752)
		(mid 87.171022 -275.333497)
		(end 87.357966 -275.383752)
		(width 0.0889)
		(layer "In2.Cu")
		(net "M_C_CPU1_SB_DQ<3>")
	)
	(segment
		(start 96.097852 -293.260272)
		(end 95.631 -293.52621)
		(width 0.10668)
		(layer "F.Cu")
		(net "M_C_CPU1_SB_DQ<31>")
	)
	(segment
		(start 89.229692 -293.198804)
		(end 89.238074 -293.20363)
		(width 0.0889)
		(layer "In2.Cu")
		(net "M_C_CPU1_SB_DQ<31>")
	)
	(segment
		(start 82.281268 -293.205408)
		(end 82.284062 -293.20363)
		(width 0.0889)
		(layer "In2.Cu")
		(net "M_C_CPU1_SB_DQ<31>")
	)
	(segment
		(start 42.166286 -318.460374)
		(end 62.508384 -318.460374)
		(width 0.14478)
		(layer "In2.Cu")
		(net "M_C_CPU1_SB_DQ<31>")
	)
	(segment
		(start 81.813908 -294.013636)
		(end 81.853024 -293.990776)
		(width 0.0889)
		(layer "In2.Cu")
		(net "M_C_CPU1_SB_DQ<31>")
	)
	(segment
		(start 74.304398 -307.76418)
		(end 74.304398 -306.66436)
		(width 0.14478)
		(layer "In2.Cu")
		(net "M_C_CPU1_SB_DQ<31>")
	)
	(segment
		(start 83.589622 -293.198804)
		(end 83.598004 -293.20363)
		(width 0.0889)
		(layer "In2.Cu")
		(net "M_C_CPU1_SB_DQ<31>")
	)
	(segment
		(start 80.874362 -295.633648)
		(end 80.910684 -295.612566)
		(width 0.0889)
		(layer "In2.Cu")
		(net "M_C_CPU1_SB_DQ<31>")
	)
	(segment
		(start 41.449752 -317.834518)
		(end 41.612566 -317.671704)
		(width 0.14478)
		(layer "In2.Cu")
		(net "M_C_CPU1_SB_DQ<31>")
	)
	(segment
		(start 40.23995 -318.035432)
		(end 40.664892 -318.460374)
		(width 0.14478)
		(layer "In2.Cu")
		(net "M_C_CPU1_SB_DQ<31>")
	)
	(segment
		(start 74.304398 -306.66436)
		(end 80.409542 -300.559216)
		(width 0.14478)
		(layer "In2.Cu")
		(net "M_C_CPU1_SB_DQ<31>")
	)
	(segment
		(start 80.451198 -296.420794)
		(end 80.524604 -296.347388)
		(width 0.0889)
		(layer "In2.Cu")
		(net "M_C_CPU1_SB_DQ<31>")
	)
	(segment
		(start 95.785178 -293.26078)
		(end 95.631 -293.52621)
		(width 0.0889)
		(layer "In2.Cu")
		(net "M_C_CPU1_SB_DQ<31>")
	)
	(segment
		(start 93.929708 -293.198804)
		(end 93.93809 -293.20363)
		(width 0.0889)
		(layer "In2.Cu")
		(net "M_C_CPU1_SB_DQ<31>")
	)
	(segment
		(start 81.783428 -294.031416)
		(end 81.813908 -294.013636)
		(width 0.0889)
		(layer "In2.Cu")
		(net "M_C_CPU1_SB_DQ<31>")
	)
	(segment
		(start 92.989654 -293.198804)
		(end 92.998036 -293.20363)
		(width 0.0889)
		(layer "In2.Cu")
		(net "M_C_CPU1_SB_DQ<31>")
	)
	(segment
		(start 41.843198 -317.671704)
		(end 42.006012 -317.834518)
		(width 0.14478)
		(layer "In2.Cu")
		(net "M_C_CPU1_SB_DQ<31>")
	)
	(segment
		(start 42.006012 -317.834518)
		(end 42.006012 -318.3001)
		(width 0.14478)
		(layer "In2.Cu")
		(net "M_C_CPU1_SB_DQ<31>")
	)
	(segment
		(start 62.508384 -318.460374)
		(end 69.276214 -311.692544)
		(width 0.14478)
		(layer "In2.Cu")
		(net "M_C_CPU1_SB_DQ<31>")
	)
	(segment
		(start 88.289638 -293.198804)
		(end 88.29802 -293.20363)
		(width 0.0889)
		(layer "In2.Cu")
		(net "M_C_CPU1_SB_DQ<31>")
	)
	(segment
		(start 90.74404 -293.20363)
		(end 90.752422 -293.198804)
		(width 0.0889)
		(layer "In2.Cu")
		(net "M_C_CPU1_SB_DQ<31>")
	)
	(segment
		(start 80.409542 -300.559216)
		(end 80.409542 -296.46245)
		(width 0.14478)
		(layer "In2.Cu")
		(net "M_C_CPU1_SB_DQ<31>")
	)
	(segment
		(start 80.409542 -296.46245)
		(end 80.451198 -296.420794)
		(width 0.14478)
		(layer "In2.Cu")
		(net "M_C_CPU1_SB_DQ<31>")
	)
	(segment
		(start 81.344008 -294.823642)
		(end 81.383124 -294.800782)
		(width 0.0889)
		(layer "In2.Cu")
		(net "M_C_CPU1_SB_DQ<31>")
	)
	(segment
		(start 80.842612 -295.651936)
		(end 80.874362 -295.633648)
		(width 0.0889)
		(layer "In2.Cu")
		(net "M_C_CPU1_SB_DQ<31>")
	)
	(segment
		(start 42.006012 -318.3001)
		(end 42.166286 -318.460374)
		(width 0.14478)
		(layer "In2.Cu")
		(net "M_C_CPU1_SB_DQ<31>")
	)
	(segment
		(start 95.762826 -293.177468)
		(end 95.785178 -293.26078)
		(width 0.0889)
		(layer "In2.Cu")
		(net "M_C_CPU1_SB_DQ<31>")
	)
	(segment
		(start 41.289478 -318.460374)
		(end 41.449752 -318.3001)
		(width 0.14478)
		(layer "In2.Cu")
		(net "M_C_CPU1_SB_DQ<31>")
	)
	(segment
		(start 41.612566 -317.671704)
		(end 41.843198 -317.671704)
		(width 0.14478)
		(layer "In2.Cu")
		(net "M_C_CPU1_SB_DQ<31>")
	)
	(segment
		(start 70.376034 -311.692544)
		(end 74.304398 -307.76418)
		(width 0.14478)
		(layer "In2.Cu")
		(net "M_C_CPU1_SB_DQ<31>")
	)
	(segment
		(start 95.444056 -293.20363)
		(end 95.452438 -293.198804)
		(width 0.0889)
		(layer "In2.Cu")
		(net "M_C_CPU1_SB_DQ<31>")
	)
	(segment
		(start 69.276214 -311.692544)
		(end 70.376034 -311.692544)
		(width 0.14478)
		(layer "In2.Cu")
		(net "M_C_CPU1_SB_DQ<31>")
	)
	(segment
		(start 40.664892 -318.460374)
		(end 41.289478 -318.460374)
		(width 0.14478)
		(layer "In2.Cu")
		(net "M_C_CPU1_SB_DQ<31>")
	)
	(segment
		(start 81.314544 -294.84066)
		(end 81.344008 -294.823642)
		(width 0.0889)
		(layer "In2.Cu")
		(net "M_C_CPU1_SB_DQ<31>")
	)
	(segment
		(start 84.529676 -293.198804)
		(end 84.538058 -293.20363)
		(width 0.0889)
		(layer "In2.Cu")
		(net "M_C_CPU1_SB_DQ<31>")
	)
	(segment
		(start 85.10397 -293.20363)
		(end 85.112352 -293.198804)
		(width 0.0889)
		(layer "In2.Cu")
		(net "M_C_CPU1_SB_DQ<31>")
	)
	(segment
		(start 41.449752 -318.3001)
		(end 41.449752 -317.834518)
		(width 0.14478)
		(layer "In2.Cu")
		(net "M_C_CPU1_SB_DQ<31>")
	)
	(segment
		(start 94.504002 -293.20363)
		(end 94.512384 -293.198804)
		(width 0.0889)
		(layer "In2.Cu")
		(net "M_C_CPU1_SB_DQ<31>")
	)
	(segment
		(start 89.803986 -293.20363)
		(end 89.812368 -293.198804)
		(width 0.0889)
		(layer "In2.Cu")
		(net "M_C_CPU1_SB_DQ<31>")
	)
	(segment
		(start 86.044024 -293.20363)
		(end 86.052406 -293.198804)
		(width 0.0889)
		(layer "In2.Cu")
		(net "M_C_CPU1_SB_DQ<31>")
	)
	(arc
		(start 94.512384 -293.198804)
		(mid 94.695892 -293.15331)
		(end 94.878144 -293.20363)
		(width 0.0889)
		(layer "In2.Cu")
		(net "M_C_CPU1_SB_DQ<31>")
	)
	(arc
		(start 80.524604 -296.347388)
		(mid 80.644519 -296.167922)
		(end 80.686656 -295.956228)
		(width 0.0889)
		(layer "In2.Cu")
		(net "M_C_CPU1_SB_DQ<31>")
	)
	(arc
		(start 90.178128 -293.20363)
		(mid 90.461084 -293.279807)
		(end 90.74404 -293.20363)
		(width 0.0889)
		(layer "In2.Cu")
		(net "M_C_CPU1_SB_DQ<31>")
	)
	(arc
		(start 84.538058 -293.20363)
		(mid 84.821014 -293.279807)
		(end 85.10397 -293.20363)
		(width 0.0889)
		(layer "In2.Cu")
		(net "M_C_CPU1_SB_DQ<31>")
	)
	(arc
		(start 95.452438 -293.198804)
		(mid 95.605308 -293.154163)
		(end 95.762826 -293.177468)
		(width 0.0889)
		(layer "In2.Cu")
		(net "M_C_CPU1_SB_DQ<31>")
	)
	(arc
		(start 89.812368 -293.198804)
		(mid 89.995876 -293.15331)
		(end 90.178128 -293.20363)
		(width 0.0889)
		(layer "In2.Cu")
		(net "M_C_CPU1_SB_DQ<31>")
	)
	(arc
		(start 80.686656 -295.956228)
		(mid 80.727911 -295.785257)
		(end 80.842612 -295.651936)
		(width 0.0889)
		(layer "In2.Cu")
		(net "M_C_CPU1_SB_DQ<31>")
	)
	(arc
		(start 93.93809 -293.20363)
		(mid 94.221046 -293.279807)
		(end 94.504002 -293.20363)
		(width 0.0889)
		(layer "In2.Cu")
		(net "M_C_CPU1_SB_DQ<31>")
	)
	(arc
		(start 81.853024 -293.990776)
		(mid 82.031837 -293.788426)
		(end 82.096356 -293.52621)
		(width 0.0889)
		(layer "In2.Cu")
		(net "M_C_CPU1_SB_DQ<31>")
	)
	(arc
		(start 89.238074 -293.20363)
		(mid 89.52103 -293.279807)
		(end 89.803986 -293.20363)
		(width 0.0889)
		(layer "In2.Cu")
		(net "M_C_CPU1_SB_DQ<31>")
	)
	(arc
		(start 91.684094 -293.20363)
		(mid 91.871038 -293.153375)
		(end 92.057982 -293.20363)
		(width 0.0889)
		(layer "In2.Cu")
		(net "M_C_CPU1_SB_DQ<31>")
	)
	(arc
		(start 85.112352 -293.198804)
		(mid 85.29586 -293.15331)
		(end 85.478112 -293.20363)
		(width 0.0889)
		(layer "In2.Cu")
		(net "M_C_CPU1_SB_DQ<31>")
	)
	(arc
		(start 81.626456 -294.336216)
		(mid 81.668005 -294.164794)
		(end 81.783428 -294.031416)
		(width 0.0889)
		(layer "In2.Cu")
		(net "M_C_CPU1_SB_DQ<31>")
	)
	(arc
		(start 85.478112 -293.20363)
		(mid 85.761068 -293.279807)
		(end 86.044024 -293.20363)
		(width 0.0889)
		(layer "In2.Cu")
		(net "M_C_CPU1_SB_DQ<31>")
	)
	(arc
		(start 83.598004 -293.20363)
		(mid 83.88096 -293.279807)
		(end 84.163916 -293.20363)
		(width 0.0889)
		(layer "In2.Cu")
		(net "M_C_CPU1_SB_DQ<31>")
	)
	(arc
		(start 81.156556 -295.146222)
		(mid 81.198396 -294.974236)
		(end 81.314544 -294.84066)
		(width 0.0889)
		(layer "In2.Cu")
		(net "M_C_CPU1_SB_DQ<31>")
	)
	(arc
		(start 82.096356 -293.52621)
		(mid 82.145885 -293.341057)
		(end 82.281268 -293.205408)
		(width 0.0889)
		(layer "In2.Cu")
		(net "M_C_CPU1_SB_DQ<31>")
	)
	(arc
		(start 93.563948 -293.20363)
		(mid 93.746199 -293.15328)
		(end 93.929708 -293.198804)
		(width 0.0889)
		(layer "In2.Cu")
		(net "M_C_CPU1_SB_DQ<31>")
	)
	(arc
		(start 86.052406 -293.198804)
		(mid 86.235914 -293.15331)
		(end 86.418166 -293.20363)
		(width 0.0889)
		(layer "In2.Cu")
		(net "M_C_CPU1_SB_DQ<31>")
	)
	(arc
		(start 81.383124 -294.800782)
		(mid 81.561937 -294.598432)
		(end 81.626456 -294.336216)
		(width 0.0889)
		(layer "In2.Cu")
		(net "M_C_CPU1_SB_DQ<31>")
	)
	(arc
		(start 87.923878 -293.20363)
		(mid 88.106129 -293.15328)
		(end 88.289638 -293.198804)
		(width 0.0889)
		(layer "In2.Cu")
		(net "M_C_CPU1_SB_DQ<31>")
	)
	(arc
		(start 87.357966 -293.20363)
		(mid 87.640922 -293.279807)
		(end 87.923878 -293.20363)
		(width 0.0889)
		(layer "In2.Cu")
		(net "M_C_CPU1_SB_DQ<31>")
	)
	(arc
		(start 88.29802 -293.20363)
		(mid 88.580976 -293.279807)
		(end 88.863932 -293.20363)
		(width 0.0889)
		(layer "In2.Cu")
		(net "M_C_CPU1_SB_DQ<31>")
	)
	(arc
		(start 86.418166 -293.20363)
		(mid 86.701122 -293.279807)
		(end 86.984078 -293.20363)
		(width 0.0889)
		(layer "In2.Cu")
		(net "M_C_CPU1_SB_DQ<31>")
	)
	(arc
		(start 86.984078 -293.20363)
		(mid 87.171022 -293.153375)
		(end 87.357966 -293.20363)
		(width 0.0889)
		(layer "In2.Cu")
		(net "M_C_CPU1_SB_DQ<31>")
	)
	(arc
		(start 82.65795 -293.20363)
		(mid 82.940906 -293.279807)
		(end 83.223862 -293.20363)
		(width 0.0889)
		(layer "In2.Cu")
		(net "M_C_CPU1_SB_DQ<31>")
	)
	(arc
		(start 83.223862 -293.20363)
		(mid 83.406113 -293.15328)
		(end 83.589622 -293.198804)
		(width 0.0889)
		(layer "In2.Cu")
		(net "M_C_CPU1_SB_DQ<31>")
	)
	(arc
		(start 80.910684 -295.612566)
		(mid 81.091336 -295.409821)
		(end 81.156556 -295.146222)
		(width 0.0889)
		(layer "In2.Cu")
		(net "M_C_CPU1_SB_DQ<31>")
	)
	(arc
		(start 94.878144 -293.20363)
		(mid 95.1611 -293.279807)
		(end 95.444056 -293.20363)
		(width 0.0889)
		(layer "In2.Cu")
		(net "M_C_CPU1_SB_DQ<31>")
	)
	(arc
		(start 90.752422 -293.198804)
		(mid 90.93593 -293.15331)
		(end 91.118182 -293.20363)
		(width 0.0889)
		(layer "In2.Cu")
		(net "M_C_CPU1_SB_DQ<31>")
	)
	(arc
		(start 82.284062 -293.20363)
		(mid 82.471006 -293.153375)
		(end 82.65795 -293.20363)
		(width 0.0889)
		(layer "In2.Cu")
		(net "M_C_CPU1_SB_DQ<31>")
	)
	(arc
		(start 88.863932 -293.20363)
		(mid 89.046183 -293.15328)
		(end 89.229692 -293.198804)
		(width 0.0889)
		(layer "In2.Cu")
		(net "M_C_CPU1_SB_DQ<31>")
	)
	(arc
		(start 91.118182 -293.20363)
		(mid 91.401138 -293.279807)
		(end 91.684094 -293.20363)
		(width 0.0889)
		(layer "In2.Cu")
		(net "M_C_CPU1_SB_DQ<31>")
	)
	(arc
		(start 92.623894 -293.20363)
		(mid 92.806145 -293.15328)
		(end 92.989654 -293.198804)
		(width 0.0889)
		(layer "In2.Cu")
		(net "M_C_CPU1_SB_DQ<31>")
	)
	(arc
		(start 84.163916 -293.20363)
		(mid 84.346167 -293.15328)
		(end 84.529676 -293.198804)
		(width 0.0889)
		(layer "In2.Cu")
		(net "M_C_CPU1_SB_DQ<31>")
	)
	(arc
		(start 92.057982 -293.20363)
		(mid 92.340938 -293.279807)
		(end 92.623894 -293.20363)
		(width 0.0889)
		(layer "In2.Cu")
		(net "M_C_CPU1_SB_DQ<31>")
	)
	(arc
		(start 92.998036 -293.20363)
		(mid 93.280992 -293.279807)
		(end 93.563948 -293.20363)
		(width 0.0889)
		(layer "In2.Cu")
		(net "M_C_CPU1_SB_DQ<31>")
	)
	(segment
		(start 94.687898 -292.450266)
		(end 94.221046 -292.716204)
		(width 0.10668)
		(layer "F.Cu")
		(net "M_C_CPU1_SB_DQ<30>")
	)
	(segment
		(start 92.153994 -292.393624)
		(end 92.162376 -292.388798)
		(width 0.0889)
		(layer "In2.Cu")
		(net "M_C_CPU1_SB_DQ<30>")
	)
	(segment
		(start 80.403954 -293.20363)
		(end 80.44307 -293.18077)
		(width 0.0889)
		(layer "In2.Cu")
		(net "M_C_CPU1_SB_DQ<30>")
	)
	(segment
		(start 41.570656 -316.094364)
		(end 41.801288 -316.094364)
		(width 0.14478)
		(layer "In2.Cu")
		(net "M_C_CPU1_SB_DQ<30>")
	)
	(segment
		(start 79.464408 -294.823642)
		(end 79.50073 -294.80256)
		(width 0.0889)
		(layer "In2.Cu")
		(net "M_C_CPU1_SB_DQ<30>")
	)
	(segment
		(start 62.920626 -316.760352)
		(end 78.608936 -301.072042)
		(width 0.14478)
		(layer "In2.Cu")
		(net "M_C_CPU1_SB_DQ<30>")
	)
	(segment
		(start 42.474896 -316.760352)
		(end 42.63771 -316.597538)
		(width 0.14478)
		(layer "In2.Cu")
		(net "M_C_CPU1_SB_DQ<30>")
	)
	(segment
		(start 80.871314 -292.395402)
		(end 80.874108 -292.393624)
		(width 0.0889)
		(layer "In2.Cu")
		(net "M_C_CPU1_SB_DQ<30>")
	)
	(segment
		(start 41.245028 -316.760352)
		(end 41.407842 -316.597538)
		(width 0.14478)
		(layer "In2.Cu")
		(net "M_C_CPU1_SB_DQ<30>")
	)
	(segment
		(start 78.608936 -296.009568)
		(end 78.981046 -295.637458)
		(width 0.0889)
		(layer "In2.Cu")
		(net "M_C_CPU1_SB_DQ<30>")
	)
	(segment
		(start 94.37497 -292.450774)
		(end 94.221046 -292.716204)
		(width 0.0889)
		(layer "In2.Cu")
		(net "M_C_CPU1_SB_DQ<30>")
	)
	(segment
		(start 85.93963 -292.388798)
		(end 85.948012 -292.393624)
		(width 0.0889)
		(layer "In2.Cu")
		(net "M_C_CPU1_SB_DQ<30>")
	)
	(segment
		(start 86.879684 -292.388798)
		(end 86.888066 -292.393624)
		(width 0.0889)
		(layer "In2.Cu")
		(net "M_C_CPU1_SB_DQ<30>")
	)
	(segment
		(start 43.19397 -316.597538)
		(end 43.356784 -316.760352)
		(width 0.14478)
		(layer "In2.Cu")
		(net "M_C_CPU1_SB_DQ<30>")
	)
	(segment
		(start 41.964102 -316.597538)
		(end 42.126916 -316.760352)
		(width 0.14478)
		(layer "In2.Cu")
		(net "M_C_CPU1_SB_DQ<30>")
	)
	(segment
		(start 42.63771 -316.597538)
		(end 42.63771 -315.838078)
		(width 0.14478)
		(layer "In2.Cu")
		(net "M_C_CPU1_SB_DQ<30>")
	)
	(segment
		(start 82.179668 -292.388798)
		(end 82.18805 -292.393624)
		(width 0.0889)
		(layer "In2.Cu")
		(net "M_C_CPU1_SB_DQ<30>")
	)
	(segment
		(start 79.934054 -294.013636)
		(end 79.97317 -293.990776)
		(width 0.0889)
		(layer "In2.Cu")
		(net "M_C_CPU1_SB_DQ<30>")
	)
	(segment
		(start 41.407842 -316.257178)
		(end 41.570656 -316.094364)
		(width 0.14478)
		(layer "In2.Cu")
		(net "M_C_CPU1_SB_DQ<30>")
	)
	(segment
		(start 43.19397 -315.838078)
		(end 43.19397 -316.597538)
		(width 0.14478)
		(layer "In2.Cu")
		(net "M_C_CPU1_SB_DQ<30>")
	)
	(segment
		(start 79.432658 -294.84193)
		(end 79.464408 -294.823642)
		(width 0.0889)
		(layer "In2.Cu")
		(net "M_C_CPU1_SB_DQ<30>")
	)
	(segment
		(start 87.453978 -292.393624)
		(end 87.46236 -292.388798)
		(width 0.0889)
		(layer "In2.Cu")
		(net "M_C_CPU1_SB_DQ<30>")
	)
	(segment
		(start 91.5797 -292.388798)
		(end 91.588082 -292.393624)
		(width 0.0889)
		(layer "In2.Cu")
		(net "M_C_CPU1_SB_DQ<30>")
	)
	(segment
		(start 42.63771 -315.838078)
		(end 42.800524 -315.675264)
		(width 0.14478)
		(layer "In2.Cu")
		(net "M_C_CPU1_SB_DQ<30>")
	)
	(segment
		(start 78.608936 -301.072042)
		(end 78.608936 -296.009568)
		(width 0.14478)
		(layer "In2.Cu")
		(net "M_C_CPU1_SB_DQ<30>")
	)
	(segment
		(start 40.664892 -316.760352)
		(end 41.245028 -316.760352)
		(width 0.14478)
		(layer "In2.Cu")
		(net "M_C_CPU1_SB_DQ<30>")
	)
	(segment
		(start 42.800524 -315.675264)
		(end 43.031156 -315.675264)
		(width 0.14478)
		(layer "In2.Cu")
		(net "M_C_CPU1_SB_DQ<30>")
	)
	(segment
		(start 78.981046 -295.637458)
		(end 79.138526 -295.480232)
		(width 0.0889)
		(layer "In2.Cu")
		(net "M_C_CPU1_SB_DQ<30>")
	)
	(segment
		(start 41.801288 -316.094364)
		(end 41.964102 -316.257178)
		(width 0.14478)
		(layer "In2.Cu")
		(net "M_C_CPU1_SB_DQ<30>")
	)
	(segment
		(start 43.356784 -316.760352)
		(end 62.920626 -316.760352)
		(width 0.14478)
		(layer "In2.Cu")
		(net "M_C_CPU1_SB_DQ<30>")
	)
	(segment
		(start 41.407842 -316.597538)
		(end 41.407842 -316.257178)
		(width 0.14478)
		(layer "In2.Cu")
		(net "M_C_CPU1_SB_DQ<30>")
	)
	(segment
		(start 88.394032 -292.393624)
		(end 88.402414 -292.388798)
		(width 0.0889)
		(layer "In2.Cu")
		(net "M_C_CPU1_SB_DQ<30>")
	)
	(segment
		(start 80.373474 -293.22141)
		(end 80.403954 -293.20363)
		(width 0.0889)
		(layer "In2.Cu")
		(net "M_C_CPU1_SB_DQ<30>")
	)
	(segment
		(start 83.694016 -292.393624)
		(end 83.702398 -292.388798)
		(width 0.0889)
		(layer "In2.Cu")
		(net "M_C_CPU1_SB_DQ<30>")
	)
	(segment
		(start 90.639646 -292.388798)
		(end 90.648028 -292.393624)
		(width 0.0889)
		(layer "In2.Cu")
		(net "M_C_CPU1_SB_DQ<30>")
	)
	(segment
		(start 94.352618 -292.367462)
		(end 94.37497 -292.450774)
		(width 0.0889)
		(layer "In2.Cu")
		(net "M_C_CPU1_SB_DQ<30>")
	)
	(segment
		(start 41.964102 -316.257178)
		(end 41.964102 -316.597538)
		(width 0.14478)
		(layer "In2.Cu")
		(net "M_C_CPU1_SB_DQ<30>")
	)
	(segment
		(start 82.753962 -292.393624)
		(end 82.762344 -292.388798)
		(width 0.0889)
		(layer "In2.Cu")
		(net "M_C_CPU1_SB_DQ<30>")
	)
	(segment
		(start 79.90459 -294.030654)
		(end 79.934054 -294.013636)
		(width 0.0889)
		(layer "In2.Cu")
		(net "M_C_CPU1_SB_DQ<30>")
	)
	(segment
		(start 43.031156 -315.675264)
		(end 43.19397 -315.838078)
		(width 0.14478)
		(layer "In2.Cu")
		(net "M_C_CPU1_SB_DQ<30>")
	)
	(segment
		(start 42.126916 -316.760352)
		(end 42.474896 -316.760352)
		(width 0.14478)
		(layer "In2.Cu")
		(net "M_C_CPU1_SB_DQ<30>")
	)
	(segment
		(start 93.094048 -292.393624)
		(end 93.10243 -292.388798)
		(width 0.0889)
		(layer "In2.Cu")
		(net "M_C_CPU1_SB_DQ<30>")
	)
	(segment
		(start 40.23995 -316.33541)
		(end 40.664892 -316.760352)
		(width 0.14478)
		(layer "In2.Cu")
		(net "M_C_CPU1_SB_DQ<30>")
	)
	(arc
		(start 80.44307 -293.18077)
		(mid 80.621883 -292.97842)
		(end 80.686402 -292.716204)
		(width 0.0889)
		(layer "In2.Cu")
		(net "M_C_CPU1_SB_DQ<30>")
	)
	(arc
		(start 82.18805 -292.393624)
		(mid 82.471006 -292.469801)
		(end 82.753962 -292.393624)
		(width 0.0889)
		(layer "In2.Cu")
		(net "M_C_CPU1_SB_DQ<30>")
	)
	(arc
		(start 84.068158 -292.393624)
		(mid 84.351114 -292.469801)
		(end 84.63407 -292.393624)
		(width 0.0889)
		(layer "In2.Cu")
		(net "M_C_CPU1_SB_DQ<30>")
	)
	(arc
		(start 91.588082 -292.393624)
		(mid 91.871038 -292.469801)
		(end 92.153994 -292.393624)
		(width 0.0889)
		(layer "In2.Cu")
		(net "M_C_CPU1_SB_DQ<30>")
	)
	(arc
		(start 80.686402 -292.716204)
		(mid 80.735931 -292.531051)
		(end 80.871314 -292.395402)
		(width 0.0889)
		(layer "In2.Cu")
		(net "M_C_CPU1_SB_DQ<30>")
	)
	(arc
		(start 79.138526 -295.480232)
		(mid 79.240838 -295.326972)
		(end 79.276702 -295.146222)
		(width 0.0889)
		(layer "In2.Cu")
		(net "M_C_CPU1_SB_DQ<30>")
	)
	(arc
		(start 79.746602 -294.336216)
		(mid 79.788442 -294.16423)
		(end 79.90459 -294.030654)
		(width 0.0889)
		(layer "In2.Cu")
		(net "M_C_CPU1_SB_DQ<30>")
	)
	(arc
		(start 85.007958 -292.393624)
		(mid 85.290914 -292.469801)
		(end 85.57387 -292.393624)
		(width 0.0889)
		(layer "In2.Cu")
		(net "M_C_CPU1_SB_DQ<30>")
	)
	(arc
		(start 87.46236 -292.388798)
		(mid 87.645868 -292.343304)
		(end 87.82812 -292.393624)
		(width 0.0889)
		(layer "In2.Cu")
		(net "M_C_CPU1_SB_DQ<30>")
	)
	(arc
		(start 79.276702 -295.146222)
		(mid 79.317957 -294.975251)
		(end 79.432658 -294.84193)
		(width 0.0889)
		(layer "In2.Cu")
		(net "M_C_CPU1_SB_DQ<30>")
	)
	(arc
		(start 86.513924 -292.393624)
		(mid 86.696175 -292.343274)
		(end 86.879684 -292.388798)
		(width 0.0889)
		(layer "In2.Cu")
		(net "M_C_CPU1_SB_DQ<30>")
	)
	(arc
		(start 81.813908 -292.393624)
		(mid 81.996159 -292.343274)
		(end 82.179668 -292.388798)
		(width 0.0889)
		(layer "In2.Cu")
		(net "M_C_CPU1_SB_DQ<30>")
	)
	(arc
		(start 86.888066 -292.393624)
		(mid 87.171022 -292.469801)
		(end 87.453978 -292.393624)
		(width 0.0889)
		(layer "In2.Cu")
		(net "M_C_CPU1_SB_DQ<30>")
	)
	(arc
		(start 84.63407 -292.393624)
		(mid 84.821014 -292.343369)
		(end 85.007958 -292.393624)
		(width 0.0889)
		(layer "In2.Cu")
		(net "M_C_CPU1_SB_DQ<30>")
	)
	(arc
		(start 90.273886 -292.393624)
		(mid 90.456137 -292.343274)
		(end 90.639646 -292.388798)
		(width 0.0889)
		(layer "In2.Cu")
		(net "M_C_CPU1_SB_DQ<30>")
	)
	(arc
		(start 87.82812 -292.393624)
		(mid 88.111076 -292.469801)
		(end 88.394032 -292.393624)
		(width 0.0889)
		(layer "In2.Cu")
		(net "M_C_CPU1_SB_DQ<30>")
	)
	(arc
		(start 90.648028 -292.393624)
		(mid 90.930984 -292.469801)
		(end 91.21394 -292.393624)
		(width 0.0889)
		(layer "In2.Cu")
		(net "M_C_CPU1_SB_DQ<30>")
	)
	(arc
		(start 79.97317 -293.990776)
		(mid 80.151983 -293.788426)
		(end 80.216502 -293.52621)
		(width 0.0889)
		(layer "In2.Cu")
		(net "M_C_CPU1_SB_DQ<30>")
	)
	(arc
		(start 83.702398 -292.388798)
		(mid 83.885906 -292.343304)
		(end 84.068158 -292.393624)
		(width 0.0889)
		(layer "In2.Cu")
		(net "M_C_CPU1_SB_DQ<30>")
	)
	(arc
		(start 81.247996 -292.393624)
		(mid 81.530952 -292.469801)
		(end 81.813908 -292.393624)
		(width 0.0889)
		(layer "In2.Cu")
		(net "M_C_CPU1_SB_DQ<30>")
	)
	(arc
		(start 83.128104 -292.393624)
		(mid 83.41106 -292.469801)
		(end 83.694016 -292.393624)
		(width 0.0889)
		(layer "In2.Cu")
		(net "M_C_CPU1_SB_DQ<30>")
	)
	(arc
		(start 88.768174 -292.393624)
		(mid 89.05113 -292.469801)
		(end 89.334086 -292.393624)
		(width 0.0889)
		(layer "In2.Cu")
		(net "M_C_CPU1_SB_DQ<30>")
	)
	(arc
		(start 94.034102 -292.393624)
		(mid 94.190421 -292.344629)
		(end 94.352618 -292.367462)
		(width 0.0889)
		(layer "In2.Cu")
		(net "M_C_CPU1_SB_DQ<30>")
	)
	(arc
		(start 91.21394 -292.393624)
		(mid 91.396191 -292.343274)
		(end 91.5797 -292.388798)
		(width 0.0889)
		(layer "In2.Cu")
		(net "M_C_CPU1_SB_DQ<30>")
	)
	(arc
		(start 79.50073 -294.80256)
		(mid 79.681382 -294.599815)
		(end 79.746602 -294.336216)
		(width 0.0889)
		(layer "In2.Cu")
		(net "M_C_CPU1_SB_DQ<30>")
	)
	(arc
		(start 93.10243 -292.388798)
		(mid 93.285938 -292.343304)
		(end 93.46819 -292.393624)
		(width 0.0889)
		(layer "In2.Cu")
		(net "M_C_CPU1_SB_DQ<30>")
	)
	(arc
		(start 92.528136 -292.393624)
		(mid 92.811092 -292.469801)
		(end 93.094048 -292.393624)
		(width 0.0889)
		(layer "In2.Cu")
		(net "M_C_CPU1_SB_DQ<30>")
	)
	(arc
		(start 89.707974 -292.393624)
		(mid 89.99093 -292.469801)
		(end 90.273886 -292.393624)
		(width 0.0889)
		(layer "In2.Cu")
		(net "M_C_CPU1_SB_DQ<30>")
	)
	(arc
		(start 89.334086 -292.393624)
		(mid 89.52103 -292.343369)
		(end 89.707974 -292.393624)
		(width 0.0889)
		(layer "In2.Cu")
		(net "M_C_CPU1_SB_DQ<30>")
	)
	(arc
		(start 88.402414 -292.388798)
		(mid 88.585922 -292.343304)
		(end 88.768174 -292.393624)
		(width 0.0889)
		(layer "In2.Cu")
		(net "M_C_CPU1_SB_DQ<30>")
	)
	(arc
		(start 80.216502 -293.52621)
		(mid 80.258051 -293.354788)
		(end 80.373474 -293.22141)
		(width 0.0889)
		(layer "In2.Cu")
		(net "M_C_CPU1_SB_DQ<30>")
	)
	(arc
		(start 85.57387 -292.393624)
		(mid 85.756121 -292.343274)
		(end 85.93963 -292.388798)
		(width 0.0889)
		(layer "In2.Cu")
		(net "M_C_CPU1_SB_DQ<30>")
	)
	(arc
		(start 80.874108 -292.393624)
		(mid 81.061052 -292.343369)
		(end 81.247996 -292.393624)
		(width 0.0889)
		(layer "In2.Cu")
		(net "M_C_CPU1_SB_DQ<30>")
	)
	(arc
		(start 92.162376 -292.388798)
		(mid 92.345884 -292.343304)
		(end 92.528136 -292.393624)
		(width 0.0889)
		(layer "In2.Cu")
		(net "M_C_CPU1_SB_DQ<30>")
	)
	(arc
		(start 85.948012 -292.393624)
		(mid 86.230968 -292.469801)
		(end 86.513924 -292.393624)
		(width 0.0889)
		(layer "In2.Cu")
		(net "M_C_CPU1_SB_DQ<30>")
	)
	(arc
		(start 82.762344 -292.388798)
		(mid 82.945852 -292.343304)
		(end 83.128104 -292.393624)
		(width 0.0889)
		(layer "In2.Cu")
		(net "M_C_CPU1_SB_DQ<30>")
	)
	(arc
		(start 93.46819 -292.393624)
		(mid 93.751146 -292.469801)
		(end 94.034102 -292.393624)
		(width 0.0889)
		(layer "In2.Cu")
		(net "M_C_CPU1_SB_DQ<30>")
	)
	(segment
		(start 94.687898 -274.630388)
		(end 94.221046 -274.896326)
		(width 0.10668)
		(layer "F.Cu")
		(net "M_C_CPU1_SB_DQ<2>")
	)
	(segment
		(start 94.37497 -274.630896)
		(end 94.221046 -274.896326)
		(width 0.0889)
		(layer "In2.Cu")
		(net "M_C_CPU1_SB_DQ<2>")
	)
	(segment
		(start 60.760864 -281.910282)
		(end 64.634364 -278.036782)
		(width 0.14478)
		(layer "In2.Cu")
		(net "M_C_CPU1_SB_DQ<2>")
	)
	(segment
		(start 79.350616 -274.561808)
		(end 79.37119 -274.573746)
		(width 0.0889)
		(layer "In2.Cu")
		(net "M_C_CPU1_SB_DQ<2>")
	)
	(segment
		(start 42.47642 -282.597606)
		(end 42.47642 -282.106878)
		(width 0.14478)
		(layer "In2.Cu")
		(net "M_C_CPU1_SB_DQ<2>")
	)
	(segment
		(start 50.123852 -281.910282)
		(end 53.067204 -281.910282)
		(width 0.14478)
		(layer "In2.Cu")
		(net "M_C_CPU1_SB_DQ<2>")
	)
	(segment
		(start 53.917342 -282.76042)
		(end 56.656986 -282.76042)
		(width 0.14478)
		(layer "In2.Cu")
		(net "M_C_CPU1_SB_DQ<2>")
	)
	(segment
		(start 70.077584 -273.675094)
		(end 75.936856 -273.675094)
		(width 0.14478)
		(layer "In2.Cu")
		(net "M_C_CPU1_SB_DQ<2>")
	)
	(segment
		(start 41.201086 -282.76042)
		(end 41.3639 -282.597606)
		(width 0.14478)
		(layer "In2.Cu")
		(net "M_C_CPU1_SB_DQ<2>")
	)
	(segment
		(start 88.394032 -274.573746)
		(end 88.402414 -274.56892)
		(width 0.0889)
		(layer "In2.Cu")
		(net "M_C_CPU1_SB_DQ<2>")
	)
	(segment
		(start 41.3639 -282.106878)
		(end 41.526714 -281.944064)
		(width 0.14478)
		(layer "In2.Cu")
		(net "M_C_CPU1_SB_DQ<2>")
	)
	(segment
		(start 86.879684 -274.56892)
		(end 86.888066 -274.573746)
		(width 0.0889)
		(layer "In2.Cu")
		(net "M_C_CPU1_SB_DQ<2>")
	)
	(segment
		(start 76.457556 -273.675094)
		(end 76.568046 -273.785584)
		(width 0.0889)
		(layer "In2.Cu")
		(net "M_C_CPU1_SB_DQ<2>")
	)
	(segment
		(start 41.92016 -282.597606)
		(end 42.082974 -282.76042)
		(width 0.14478)
		(layer "In2.Cu")
		(net "M_C_CPU1_SB_DQ<2>")
	)
	(segment
		(start 91.5797 -274.56892)
		(end 91.588082 -274.573746)
		(width 0.0889)
		(layer "In2.Cu")
		(net "M_C_CPU1_SB_DQ<2>")
	)
	(segment
		(start 85.93963 -274.56892)
		(end 85.948012 -274.573746)
		(width 0.0889)
		(layer "In2.Cu")
		(net "M_C_CPU1_SB_DQ<2>")
	)
	(segment
		(start 43.03268 -282.106878)
		(end 43.03268 -282.597606)
		(width 0.14478)
		(layer "In2.Cu")
		(net "M_C_CPU1_SB_DQ<2>")
	)
	(segment
		(start 76.568046 -273.785584)
		(end 77.585824 -273.785584)
		(width 0.0889)
		(layer "In2.Cu")
		(net "M_C_CPU1_SB_DQ<2>")
	)
	(segment
		(start 57.507124 -281.910282)
		(end 60.760864 -281.910282)
		(width 0.14478)
		(layer "In2.Cu")
		(net "M_C_CPU1_SB_DQ<2>")
	)
	(segment
		(start 78.978252 -274.583906)
		(end 78.995778 -274.573746)
		(width 0.0889)
		(layer "In2.Cu")
		(net "M_C_CPU1_SB_DQ<2>")
	)
	(segment
		(start 42.082974 -282.76042)
		(end 42.313606 -282.76042)
		(width 0.14478)
		(layer "In2.Cu")
		(net "M_C_CPU1_SB_DQ<2>")
	)
	(segment
		(start 43.03268 -282.597606)
		(end 43.195494 -282.76042)
		(width 0.14478)
		(layer "In2.Cu")
		(net "M_C_CPU1_SB_DQ<2>")
	)
	(segment
		(start 64.634364 -278.036782)
		(end 65.715896 -278.036782)
		(width 0.14478)
		(layer "In2.Cu")
		(net "M_C_CPU1_SB_DQ<2>")
	)
	(segment
		(start 42.869866 -281.944064)
		(end 43.03268 -282.106878)
		(width 0.14478)
		(layer "In2.Cu")
		(net "M_C_CPU1_SB_DQ<2>")
	)
	(segment
		(start 42.313606 -282.76042)
		(end 42.47642 -282.597606)
		(width 0.14478)
		(layer "In2.Cu")
		(net "M_C_CPU1_SB_DQ<2>")
	)
	(segment
		(start 77.585824 -273.785584)
		(end 78.281022 -274.480782)
		(width 0.0889)
		(layer "In2.Cu")
		(net "M_C_CPU1_SB_DQ<2>")
	)
	(segment
		(start 78.704694 -274.656296)
		(end 78.711044 -274.656296)
		(width 0.0889)
		(layer "In2.Cu")
		(net "M_C_CPU1_SB_DQ<2>")
	)
	(segment
		(start 79.911448 -274.58797)
		(end 79.935324 -274.574)
		(width 0.0889)
		(layer "In2.Cu")
		(net "M_C_CPU1_SB_DQ<2>")
	)
	(segment
		(start 93.094048 -274.573746)
		(end 93.10243 -274.56892)
		(width 0.0889)
		(layer "In2.Cu")
		(net "M_C_CPU1_SB_DQ<2>")
	)
	(segment
		(start 41.757346 -281.944064)
		(end 41.92016 -282.106878)
		(width 0.14478)
		(layer "In2.Cu")
		(net "M_C_CPU1_SB_DQ<2>")
	)
	(segment
		(start 41.3639 -282.597606)
		(end 41.3639 -282.106878)
		(width 0.14478)
		(layer "In2.Cu")
		(net "M_C_CPU1_SB_DQ<2>")
	)
	(segment
		(start 65.715896 -278.036782)
		(end 70.077584 -273.675094)
		(width 0.14478)
		(layer "In2.Cu")
		(net "M_C_CPU1_SB_DQ<2>")
	)
	(segment
		(start 40.665146 -282.76042)
		(end 41.201086 -282.76042)
		(width 0.14478)
		(layer "In2.Cu")
		(net "M_C_CPU1_SB_DQ<2>")
	)
	(segment
		(start 41.526714 -281.944064)
		(end 41.757346 -281.944064)
		(width 0.14478)
		(layer "In2.Cu")
		(net "M_C_CPU1_SB_DQ<2>")
	)
	(segment
		(start 41.92016 -282.106878)
		(end 41.92016 -282.597606)
		(width 0.14478)
		(layer "In2.Cu")
		(net "M_C_CPU1_SB_DQ<2>")
	)
	(segment
		(start 49.273714 -282.76042)
		(end 50.123852 -281.910282)
		(width 0.14478)
		(layer "In2.Cu")
		(net "M_C_CPU1_SB_DQ<2>")
	)
	(segment
		(start 53.067204 -281.910282)
		(end 53.917342 -282.76042)
		(width 0.14478)
		(layer "In2.Cu")
		(net "M_C_CPU1_SB_DQ<2>")
	)
	(segment
		(start 92.153994 -274.573746)
		(end 92.162376 -274.56892)
		(width 0.0889)
		(layer "In2.Cu")
		(net "M_C_CPU1_SB_DQ<2>")
	)
	(segment
		(start 94.352618 -274.547584)
		(end 94.37497 -274.630896)
		(width 0.0889)
		(layer "In2.Cu")
		(net "M_C_CPU1_SB_DQ<2>")
	)
	(segment
		(start 75.936856 -273.675094)
		(end 76.457556 -273.675094)
		(width 0.0889)
		(layer "In2.Cu")
		(net "M_C_CPU1_SB_DQ<2>")
	)
	(segment
		(start 82.753962 -274.573746)
		(end 82.762344 -274.56892)
		(width 0.0889)
		(layer "In2.Cu")
		(net "M_C_CPU1_SB_DQ<2>")
	)
	(segment
		(start 42.639234 -281.944064)
		(end 42.869866 -281.944064)
		(width 0.14478)
		(layer "In2.Cu")
		(net "M_C_CPU1_SB_DQ<2>")
	)
	(segment
		(start 43.195494 -282.76042)
		(end 49.273714 -282.76042)
		(width 0.14478)
		(layer "In2.Cu")
		(net "M_C_CPU1_SB_DQ<2>")
	)
	(segment
		(start 79.935324 -274.574)
		(end 79.958692 -274.560538)
		(width 0.0889)
		(layer "In2.Cu")
		(net "M_C_CPU1_SB_DQ<2>")
	)
	(segment
		(start 90.639646 -274.56892)
		(end 90.648028 -274.573746)
		(width 0.0889)
		(layer "In2.Cu")
		(net "M_C_CPU1_SB_DQ<2>")
	)
	(segment
		(start 87.453978 -274.573746)
		(end 87.46236 -274.56892)
		(width 0.0889)
		(layer "In2.Cu")
		(net "M_C_CPU1_SB_DQ<2>")
	)
	(segment
		(start 56.656986 -282.76042)
		(end 57.507124 -281.910282)
		(width 0.14478)
		(layer "In2.Cu")
		(net "M_C_CPU1_SB_DQ<2>")
	)
	(segment
		(start 40.23995 -282.335224)
		(end 40.665146 -282.76042)
		(width 0.14478)
		(layer "In2.Cu")
		(net "M_C_CPU1_SB_DQ<2>")
	)
	(segment
		(start 83.694016 -274.573746)
		(end 83.702398 -274.56892)
		(width 0.0889)
		(layer "In2.Cu")
		(net "M_C_CPU1_SB_DQ<2>")
	)
	(segment
		(start 82.179668 -274.56892)
		(end 82.18805 -274.573746)
		(width 0.0889)
		(layer "In2.Cu")
		(net "M_C_CPU1_SB_DQ<2>")
	)
	(segment
		(start 42.47642 -282.106878)
		(end 42.639234 -281.944064)
		(width 0.14478)
		(layer "In2.Cu")
		(net "M_C_CPU1_SB_DQ<2>")
	)
	(arc
		(start 81.813908 -274.573746)
		(mid 81.996159 -274.523396)
		(end 82.179668 -274.56892)
		(width 0.0889)
		(layer "In2.Cu")
		(net "M_C_CPU1_SB_DQ<2>")
	)
	(arc
		(start 78.711044 -274.656296)
		(mid 78.849473 -274.637893)
		(end 78.978252 -274.583906)
		(width 0.0889)
		(layer "In2.Cu")
		(net "M_C_CPU1_SB_DQ<2>")
	)
	(arc
		(start 91.21394 -274.573746)
		(mid 91.396191 -274.523396)
		(end 91.5797 -274.56892)
		(width 0.0889)
		(layer "In2.Cu")
		(net "M_C_CPU1_SB_DQ<2>")
	)
	(arc
		(start 89.707974 -274.573746)
		(mid 89.99093 -274.649923)
		(end 90.273886 -274.573746)
		(width 0.0889)
		(layer "In2.Cu")
		(net "M_C_CPU1_SB_DQ<2>")
	)
	(arc
		(start 85.57387 -274.573746)
		(mid 85.756121 -274.523396)
		(end 85.93963 -274.56892)
		(width 0.0889)
		(layer "In2.Cu")
		(net "M_C_CPU1_SB_DQ<2>")
	)
	(arc
		(start 89.334086 -274.573746)
		(mid 89.52103 -274.523491)
		(end 89.707974 -274.573746)
		(width 0.0889)
		(layer "In2.Cu")
		(net "M_C_CPU1_SB_DQ<2>")
	)
	(arc
		(start 92.528136 -274.573746)
		(mid 92.811092 -274.649923)
		(end 93.094048 -274.573746)
		(width 0.0889)
		(layer "In2.Cu")
		(net "M_C_CPU1_SB_DQ<2>")
	)
	(arc
		(start 85.948012 -274.573746)
		(mid 86.230968 -274.649923)
		(end 86.513924 -274.573746)
		(width 0.0889)
		(layer "In2.Cu")
		(net "M_C_CPU1_SB_DQ<2>")
	)
	(arc
		(start 78.281022 -274.480782)
		(mid 78.475404 -274.610664)
		(end 78.704694 -274.656296)
		(width 0.0889)
		(layer "In2.Cu")
		(net "M_C_CPU1_SB_DQ<2>")
	)
	(arc
		(start 93.10243 -274.56892)
		(mid 93.285938 -274.523426)
		(end 93.46819 -274.573746)
		(width 0.0889)
		(layer "In2.Cu")
		(net "M_C_CPU1_SB_DQ<2>")
	)
	(arc
		(start 93.46819 -274.573746)
		(mid 93.751146 -274.649923)
		(end 94.034102 -274.573746)
		(width 0.0889)
		(layer "In2.Cu")
		(net "M_C_CPU1_SB_DQ<2>")
	)
	(arc
		(start 90.648028 -274.573746)
		(mid 90.930984 -274.649923)
		(end 91.21394 -274.573746)
		(width 0.0889)
		(layer "In2.Cu")
		(net "M_C_CPU1_SB_DQ<2>")
	)
	(arc
		(start 88.402414 -274.56892)
		(mid 88.585922 -274.523426)
		(end 88.768174 -274.573746)
		(width 0.0889)
		(layer "In2.Cu")
		(net "M_C_CPU1_SB_DQ<2>")
	)
	(arc
		(start 79.958692 -274.560538)
		(mid 80.135087 -274.523635)
		(end 80.308196 -274.573746)
		(width 0.0889)
		(layer "In2.Cu")
		(net "M_C_CPU1_SB_DQ<2>")
	)
	(arc
		(start 82.762344 -274.56892)
		(mid 82.945852 -274.523426)
		(end 83.128104 -274.573746)
		(width 0.0889)
		(layer "In2.Cu")
		(net "M_C_CPU1_SB_DQ<2>")
	)
	(arc
		(start 88.768174 -274.573746)
		(mid 89.05113 -274.649923)
		(end 89.334086 -274.573746)
		(width 0.0889)
		(layer "In2.Cu")
		(net "M_C_CPU1_SB_DQ<2>")
	)
	(arc
		(start 80.874108 -274.573746)
		(mid 81.061052 -274.523491)
		(end 81.247996 -274.573746)
		(width 0.0889)
		(layer "In2.Cu")
		(net "M_C_CPU1_SB_DQ<2>")
	)
	(arc
		(start 92.162376 -274.56892)
		(mid 92.345884 -274.523426)
		(end 92.528136 -274.573746)
		(width 0.0889)
		(layer "In2.Cu")
		(net "M_C_CPU1_SB_DQ<2>")
	)
	(arc
		(start 84.068158 -274.573746)
		(mid 84.351114 -274.649923)
		(end 84.63407 -274.573746)
		(width 0.0889)
		(layer "In2.Cu")
		(net "M_C_CPU1_SB_DQ<2>")
	)
	(arc
		(start 87.82812 -274.573746)
		(mid 88.111076 -274.649923)
		(end 88.394032 -274.573746)
		(width 0.0889)
		(layer "In2.Cu")
		(net "M_C_CPU1_SB_DQ<2>")
	)
	(arc
		(start 90.273886 -274.573746)
		(mid 90.456137 -274.523396)
		(end 90.639646 -274.56892)
		(width 0.0889)
		(layer "In2.Cu")
		(net "M_C_CPU1_SB_DQ<2>")
	)
	(arc
		(start 80.308196 -274.573746)
		(mid 80.591152 -274.649923)
		(end 80.874108 -274.573746)
		(width 0.0889)
		(layer "In2.Cu")
		(net "M_C_CPU1_SB_DQ<2>")
	)
	(arc
		(start 79.37119 -274.573746)
		(mid 79.63951 -274.649854)
		(end 79.911448 -274.58797)
		(width 0.0889)
		(layer "In2.Cu")
		(net "M_C_CPU1_SB_DQ<2>")
	)
	(arc
		(start 86.888066 -274.573746)
		(mid 87.171022 -274.649923)
		(end 87.453978 -274.573746)
		(width 0.0889)
		(layer "In2.Cu")
		(net "M_C_CPU1_SB_DQ<2>")
	)
	(arc
		(start 86.513924 -274.573746)
		(mid 86.696175 -274.523396)
		(end 86.879684 -274.56892)
		(width 0.0889)
		(layer "In2.Cu")
		(net "M_C_CPU1_SB_DQ<2>")
	)
	(arc
		(start 82.18805 -274.573746)
		(mid 82.471006 -274.649923)
		(end 82.753962 -274.573746)
		(width 0.0889)
		(layer "In2.Cu")
		(net "M_C_CPU1_SB_DQ<2>")
	)
	(arc
		(start 91.588082 -274.573746)
		(mid 91.871038 -274.649923)
		(end 92.153994 -274.573746)
		(width 0.0889)
		(layer "In2.Cu")
		(net "M_C_CPU1_SB_DQ<2>")
	)
	(arc
		(start 84.63407 -274.573746)
		(mid 84.821014 -274.523491)
		(end 85.007958 -274.573746)
		(width 0.0889)
		(layer "In2.Cu")
		(net "M_C_CPU1_SB_DQ<2>")
	)
	(arc
		(start 83.702398 -274.56892)
		(mid 83.885906 -274.523426)
		(end 84.068158 -274.573746)
		(width 0.0889)
		(layer "In2.Cu")
		(net "M_C_CPU1_SB_DQ<2>")
	)
	(arc
		(start 87.46236 -274.56892)
		(mid 87.645868 -274.523426)
		(end 87.82812 -274.573746)
		(width 0.0889)
		(layer "In2.Cu")
		(net "M_C_CPU1_SB_DQ<2>")
	)
	(arc
		(start 83.128104 -274.573746)
		(mid 83.41106 -274.649923)
		(end 83.694016 -274.573746)
		(width 0.0889)
		(layer "In2.Cu")
		(net "M_C_CPU1_SB_DQ<2>")
	)
	(arc
		(start 78.995778 -274.573746)
		(mid 79.171688 -274.522936)
		(end 79.350616 -274.561808)
		(width 0.0889)
		(layer "In2.Cu")
		(net "M_C_CPU1_SB_DQ<2>")
	)
	(arc
		(start 94.034102 -274.573746)
		(mid 94.190421 -274.524751)
		(end 94.352618 -274.547584)
		(width 0.0889)
		(layer "In2.Cu")
		(net "M_C_CPU1_SB_DQ<2>")
	)
	(arc
		(start 81.247996 -274.573746)
		(mid 81.530952 -274.649923)
		(end 81.813908 -274.573746)
		(width 0.0889)
		(layer "In2.Cu")
		(net "M_C_CPU1_SB_DQ<2>")
	)
	(arc
		(start 85.007958 -274.573746)
		(mid 85.290914 -274.649923)
		(end 85.57387 -274.573746)
		(width 0.0889)
		(layer "In2.Cu")
		(net "M_C_CPU1_SB_DQ<2>")
	)
	(segment
		(start 96.568006 -292.450266)
		(end 96.101154 -292.716204)
		(width 0.10668)
		(layer "F.Cu")
		(net "M_C_CPU1_SB_DQ<29>")
	)
	(segment
		(start 72.863456 -308.33187)
		(end 72.542908 -308.011322)
		(width 0.14478)
		(layer "In2.Cu")
		(net "M_C_CPU1_SB_DQ<29>")
	)
	(segment
		(start 80.271874 -294.679878)
		(end 80.308196 -294.658796)
		(width 0.0889)
		(layer "In2.Cu")
		(net "M_C_CPU1_SB_DQ<29>")
	)
	(segment
		(start 71.12635 -310.2991)
		(end 71.289672 -310.135778)
		(width 0.14478)
		(layer "In2.Cu")
		(net "M_C_CPU1_SB_DQ<29>")
	)
	(segment
		(start 72.542908 -307.781198)
		(end 72.70623 -307.617876)
		(width 0.14478)
		(layer "In2.Cu")
		(net "M_C_CPU1_SB_DQ<29>")
	)
	(segment
		(start 80.308196 -294.658796)
		(end 80.338676 -294.641016)
		(width 0.0889)
		(layer "In2.Cu")
		(net "M_C_CPU1_SB_DQ<29>")
	)
	(segment
		(start 70.50278 -310.92267)
		(end 70.50278 -310.692546)
		(width 0.14478)
		(layer "In2.Cu")
		(net "M_C_CPU1_SB_DQ<29>")
	)
	(segment
		(start 72.936354 -307.617876)
		(end 73.256902 -307.938424)
		(width 0.14478)
		(layer "In2.Cu")
		(net "M_C_CPU1_SB_DQ<29>")
	)
	(segment
		(start 71.36257 -309.19166)
		(end 71.683118 -309.512208)
		(width 0.14478)
		(layer "In2.Cu")
		(net "M_C_CPU1_SB_DQ<29>")
	)
	(segment
		(start 95.85071 -293.007034)
		(end 95.946976 -292.981634)
		(width 0.0889)
		(layer "In2.Cu")
		(net "M_C_CPU1_SB_DQ<29>")
	)
	(segment
		(start 73.650348 -307.775102)
		(end 73.650348 -307.544978)
		(width 0.14478)
		(layer "In2.Cu")
		(net "M_C_CPU1_SB_DQ<29>")
	)
	(segment
		(start 88.394032 -293.038784)
		(end 88.402414 -293.04361)
		(width 0.0889)
		(layer "In2.Cu")
		(net "M_C_CPU1_SB_DQ<29>")
	)
	(segment
		(start 85.93963 -293.04361)
		(end 85.948012 -293.038784)
		(width 0.0889)
		(layer "In2.Cu")
		(net "M_C_CPU1_SB_DQ<29>")
	)
	(segment
		(start 71.289672 -310.135778)
		(end 71.289672 -309.905654)
		(width 0.14478)
		(layer "In2.Cu")
		(net "M_C_CPU1_SB_DQ<29>")
	)
	(segment
		(start 71.132446 -309.19166)
		(end 71.36257 -309.19166)
		(width 0.14478)
		(layer "In2.Cu")
		(net "M_C_CPU1_SB_DQ<29>")
	)
	(segment
		(start 71.289672 -309.905654)
		(end 70.969124 -309.585106)
		(width 0.14478)
		(layer "In2.Cu")
		(net "M_C_CPU1_SB_DQ<29>")
	)
	(segment
		(start 80.73898 -293.87165)
		(end 80.778096 -293.84879)
		(width 0.0889)
		(layer "In2.Cu")
		(net "M_C_CPU1_SB_DQ<29>")
	)
	(segment
		(start 71.683118 -309.512208)
		(end 71.913242 -309.512208)
		(width 0.14478)
		(layer "In2.Cu")
		(net "M_C_CPU1_SB_DQ<29>")
	)
	(segment
		(start 71.756016 -308.798214)
		(end 71.756016 -308.56809)
		(width 0.14478)
		(layer "In2.Cu")
		(net "M_C_CPU1_SB_DQ<29>")
	)
	(segment
		(start 69.559932 -310.765444)
		(end 69.788786 -310.765444)
		(width 0.14478)
		(layer "In2.Cu")
		(net "M_C_CPU1_SB_DQ<29>")
	)
	(segment
		(start 73.3298 -306.995576)
		(end 79.36738 -300.957996)
		(width 0.14478)
		(layer "In2.Cu")
		(net "M_C_CPU1_SB_DQ<29>")
	)
	(segment
		(start 62.714886 -317.61049)
		(end 69.559932 -310.765444)
		(width 0.14478)
		(layer "In2.Cu")
		(net "M_C_CPU1_SB_DQ<29>")
	)
	(segment
		(start 70.109334 -311.085992)
		(end 70.339458 -311.085992)
		(width 0.14478)
		(layer "In2.Cu")
		(net "M_C_CPU1_SB_DQ<29>")
	)
	(segment
		(start 71.913242 -309.512208)
		(end 72.076564 -309.348886)
		(width 0.14478)
		(layer "In2.Cu")
		(net "M_C_CPU1_SB_DQ<29>")
	)
	(segment
		(start 72.700134 -308.725316)
		(end 72.863456 -308.561994)
		(width 0.14478)
		(layer "In2.Cu")
		(net "M_C_CPU1_SB_DQ<29>")
	)
	(segment
		(start 70.969124 -309.354982)
		(end 71.132446 -309.19166)
		(width 0.14478)
		(layer "In2.Cu")
		(net "M_C_CPU1_SB_DQ<29>")
	)
	(segment
		(start 72.542908 -308.011322)
		(end 72.542908 -307.781198)
		(width 0.14478)
		(layer "In2.Cu")
		(net "M_C_CPU1_SB_DQ<29>")
	)
	(segment
		(start 82.753962 -293.038784)
		(end 82.762344 -293.04361)
		(width 0.0889)
		(layer "In2.Cu")
		(net "M_C_CPU1_SB_DQ<29>")
	)
	(segment
		(start 72.47001 -308.725316)
		(end 72.700134 -308.725316)
		(width 0.14478)
		(layer "In2.Cu")
		(net "M_C_CPU1_SB_DQ<29>")
	)
	(segment
		(start 70.339458 -311.085992)
		(end 70.50278 -310.92267)
		(width 0.14478)
		(layer "In2.Cu")
		(net "M_C_CPU1_SB_DQ<29>")
	)
	(segment
		(start 72.70623 -307.617876)
		(end 72.936354 -307.617876)
		(width 0.14478)
		(layer "In2.Cu")
		(net "M_C_CPU1_SB_DQ<29>")
	)
	(segment
		(start 72.076564 -309.118762)
		(end 71.756016 -308.798214)
		(width 0.14478)
		(layer "In2.Cu")
		(net "M_C_CPU1_SB_DQ<29>")
	)
	(segment
		(start 90.639646 -293.04361)
		(end 90.648028 -293.038784)
		(width 0.0889)
		(layer "In2.Cu")
		(net "M_C_CPU1_SB_DQ<29>")
	)
	(segment
		(start 70.182232 -310.141874)
		(end 70.345554 -309.978552)
		(width 0.14478)
		(layer "In2.Cu")
		(net "M_C_CPU1_SB_DQ<29>")
	)
	(segment
		(start 92.153994 -293.038784)
		(end 92.162376 -293.04361)
		(width 0.0889)
		(layer "In2.Cu")
		(net "M_C_CPU1_SB_DQ<29>")
	)
	(segment
		(start 72.076564 -309.348886)
		(end 72.076564 -309.118762)
		(width 0.14478)
		(layer "In2.Cu")
		(net "M_C_CPU1_SB_DQ<29>")
	)
	(segment
		(start 70.969124 -309.585106)
		(end 70.969124 -309.354982)
		(width 0.14478)
		(layer "In2.Cu")
		(net "M_C_CPU1_SB_DQ<29>")
	)
	(segment
		(start 79.36738 -296.271442)
		(end 79.466186 -296.172636)
		(width 0.0889)
		(layer "In2.Cu")
		(net "M_C_CPU1_SB_DQ<29>")
	)
	(segment
		(start 73.650348 -307.544978)
		(end 73.3298 -307.22443)
		(width 0.14478)
		(layer "In2.Cu")
		(net "M_C_CPU1_SB_DQ<29>")
	)
	(segment
		(start 73.487026 -307.938424)
		(end 73.650348 -307.775102)
		(width 0.14478)
		(layer "In2.Cu")
		(net "M_C_CPU1_SB_DQ<29>")
	)
	(segment
		(start 95.946976 -292.981634)
		(end 96.101154 -292.716204)
		(width 0.0889)
		(layer "In2.Cu")
		(net "M_C_CPU1_SB_DQ<29>")
	)
	(segment
		(start 70.896226 -310.2991)
		(end 71.12635 -310.2991)
		(width 0.14478)
		(layer "In2.Cu")
		(net "M_C_CPU1_SB_DQ<29>")
	)
	(segment
		(start 70.182232 -310.371998)
		(end 70.182232 -310.141874)
		(width 0.14478)
		(layer "In2.Cu")
		(net "M_C_CPU1_SB_DQ<29>")
	)
	(segment
		(start 79.838296 -295.468802)
		(end 79.870046 -295.450514)
		(width 0.0889)
		(layer "In2.Cu")
		(net "M_C_CPU1_SB_DQ<29>")
	)
	(segment
		(start 87.453978 -293.038784)
		(end 87.46236 -293.04361)
		(width 0.0889)
		(layer "In2.Cu")
		(net "M_C_CPU1_SB_DQ<29>")
	)
	(segment
		(start 73.3298 -307.22443)
		(end 73.3298 -306.995576)
		(width 0.14478)
		(layer "In2.Cu")
		(net "M_C_CPU1_SB_DQ<29>")
	)
	(segment
		(start 80.778096 -293.84879)
		(end 80.809846 -293.830502)
		(width 0.0889)
		(layer "In2.Cu")
		(net "M_C_CPU1_SB_DQ<29>")
	)
	(segment
		(start 71.756016 -308.56809)
		(end 71.919338 -308.404768)
		(width 0.14478)
		(layer "In2.Cu")
		(net "M_C_CPU1_SB_DQ<29>")
	)
	(segment
		(start 83.694016 -293.038784)
		(end 83.702398 -293.04361)
		(width 0.0889)
		(layer "In2.Cu")
		(net "M_C_CPU1_SB_DQ<29>")
	)
	(segment
		(start 70.345554 -309.978552)
		(end 70.575678 -309.978552)
		(width 0.14478)
		(layer "In2.Cu")
		(net "M_C_CPU1_SB_DQ<29>")
	)
	(segment
		(start 91.5797 -293.04361)
		(end 91.588082 -293.038784)
		(width 0.0889)
		(layer "In2.Cu")
		(net "M_C_CPU1_SB_DQ<29>")
	)
	(segment
		(start 82.187796 -293.038784)
		(end 82.18805 -293.038784)
		(width 0.0889)
		(layer "In2.Cu")
		(net "M_C_CPU1_SB_DQ<29>")
	)
	(segment
		(start 93.094048 -293.038784)
		(end 93.10243 -293.04361)
		(width 0.0889)
		(layer "In2.Cu")
		(net "M_C_CPU1_SB_DQ<29>")
	)
	(segment
		(start 44.765214 -317.61049)
		(end 62.714886 -317.61049)
		(width 0.14478)
		(layer "In2.Cu")
		(net "M_C_CPU1_SB_DQ<29>")
	)
	(segment
		(start 72.863456 -308.561994)
		(end 72.863456 -308.33187)
		(width 0.14478)
		(layer "In2.Cu")
		(net "M_C_CPU1_SB_DQ<29>")
	)
	(segment
		(start 81.245964 -293.040054)
		(end 81.247996 -293.038784)
		(width 0.0889)
		(layer "In2.Cu")
		(net "M_C_CPU1_SB_DQ<29>")
	)
	(segment
		(start 73.256902 -307.938424)
		(end 73.487026 -307.938424)
		(width 0.14478)
		(layer "In2.Cu")
		(net "M_C_CPU1_SB_DQ<29>")
	)
	(segment
		(start 95.339662 -293.04361)
		(end 95.348044 -293.038784)
		(width 0.0889)
		(layer "In2.Cu")
		(net "M_C_CPU1_SB_DQ<29>")
	)
	(segment
		(start 79.36738 -296.409364)
		(end 79.36738 -296.271442)
		(width 0.0889)
		(layer "In2.Cu")
		(net "M_C_CPU1_SB_DQ<29>")
	)
	(segment
		(start 71.919338 -308.404768)
		(end 72.149462 -308.404768)
		(width 0.14478)
		(layer "In2.Cu")
		(net "M_C_CPU1_SB_DQ<29>")
	)
	(segment
		(start 44.340018 -317.185294)
		(end 44.765214 -317.61049)
		(width 0.14478)
		(layer "In2.Cu")
		(net "M_C_CPU1_SB_DQ<29>")
	)
	(segment
		(start 79.79918 -295.491662)
		(end 79.838296 -295.468802)
		(width 0.0889)
		(layer "In2.Cu")
		(net "M_C_CPU1_SB_DQ<29>")
	)
	(segment
		(start 70.50278 -310.692546)
		(end 70.182232 -310.371998)
		(width 0.14478)
		(layer "In2.Cu")
		(net "M_C_CPU1_SB_DQ<29>")
	)
	(segment
		(start 79.36738 -300.957996)
		(end 79.36738 -296.409364)
		(width 0.14478)
		(layer "In2.Cu")
		(net "M_C_CPU1_SB_DQ<29>")
	)
	(segment
		(start 69.788786 -310.765444)
		(end 70.109334 -311.085992)
		(width 0.14478)
		(layer "In2.Cu")
		(net "M_C_CPU1_SB_DQ<29>")
	)
	(segment
		(start 86.879684 -293.04361)
		(end 86.888066 -293.038784)
		(width 0.0889)
		(layer "In2.Cu")
		(net "M_C_CPU1_SB_DQ<29>")
	)
	(segment
		(start 70.575678 -309.978552)
		(end 70.896226 -310.2991)
		(width 0.14478)
		(layer "In2.Cu")
		(net "M_C_CPU1_SB_DQ<29>")
	)
	(segment
		(start 72.149462 -308.404768)
		(end 72.47001 -308.725316)
		(width 0.14478)
		(layer "In2.Cu")
		(net "M_C_CPU1_SB_DQ<29>")
	)
	(arc
		(start 83.702398 -293.04361)
		(mid 83.885906 -293.089104)
		(end 84.068158 -293.038784)
		(width 0.0889)
		(layer "In2.Cu")
		(net "M_C_CPU1_SB_DQ<29>")
	)
	(arc
		(start 80.026002 -295.146222)
		(mid 80.091238 -294.882631)
		(end 80.271874 -294.679878)
		(width 0.0889)
		(layer "In2.Cu")
		(net "M_C_CPU1_SB_DQ<29>")
	)
	(arc
		(start 85.007958 -293.038784)
		(mid 85.290914 -292.962607)
		(end 85.57387 -293.038784)
		(width 0.0889)
		(layer "In2.Cu")
		(net "M_C_CPU1_SB_DQ<29>")
	)
	(arc
		(start 86.888066 -293.038784)
		(mid 87.171022 -292.962607)
		(end 87.453978 -293.038784)
		(width 0.0889)
		(layer "In2.Cu")
		(net "M_C_CPU1_SB_DQ<29>")
	)
	(arc
		(start 84.068158 -293.038784)
		(mid 84.351114 -292.962607)
		(end 84.63407 -293.038784)
		(width 0.0889)
		(layer "In2.Cu")
		(net "M_C_CPU1_SB_DQ<29>")
	)
	(arc
		(start 92.528136 -293.038784)
		(mid 92.811092 -292.962607)
		(end 93.094048 -293.038784)
		(width 0.0889)
		(layer "In2.Cu")
		(net "M_C_CPU1_SB_DQ<29>")
	)
	(arc
		(start 80.495648 -294.336216)
		(mid 80.560163 -294.073997)
		(end 80.73898 -293.87165)
		(width 0.0889)
		(layer "In2.Cu")
		(net "M_C_CPU1_SB_DQ<29>")
	)
	(arc
		(start 85.948012 -293.038784)
		(mid 86.230968 -292.962607)
		(end 86.513924 -293.038784)
		(width 0.0889)
		(layer "In2.Cu")
		(net "M_C_CPU1_SB_DQ<29>")
	)
	(arc
		(start 90.648028 -293.038784)
		(mid 90.930984 -292.962607)
		(end 91.21394 -293.038784)
		(width 0.0889)
		(layer "In2.Cu")
		(net "M_C_CPU1_SB_DQ<29>")
	)
	(arc
		(start 87.46236 -293.04361)
		(mid 87.645868 -293.089104)
		(end 87.82812 -293.038784)
		(width 0.0889)
		(layer "In2.Cu")
		(net "M_C_CPU1_SB_DQ<29>")
	)
	(arc
		(start 92.162376 -293.04361)
		(mid 92.345884 -293.089104)
		(end 92.528136 -293.038784)
		(width 0.0889)
		(layer "In2.Cu")
		(net "M_C_CPU1_SB_DQ<29>")
	)
	(arc
		(start 82.762344 -293.04361)
		(mid 82.945852 -293.089104)
		(end 83.128104 -293.038784)
		(width 0.0889)
		(layer "In2.Cu")
		(net "M_C_CPU1_SB_DQ<29>")
	)
	(arc
		(start 80.809846 -293.830502)
		(mid 80.924522 -293.697168)
		(end 80.965802 -293.52621)
		(width 0.0889)
		(layer "In2.Cu")
		(net "M_C_CPU1_SB_DQ<29>")
	)
	(arc
		(start 81.813908 -293.038784)
		(mid 82.000852 -293.089108)
		(end 82.187796 -293.038784)
		(width 0.0889)
		(layer "In2.Cu")
		(net "M_C_CPU1_SB_DQ<29>")
	)
	(arc
		(start 86.513924 -293.038784)
		(mid 86.696175 -293.089134)
		(end 86.879684 -293.04361)
		(width 0.0889)
		(layer "In2.Cu")
		(net "M_C_CPU1_SB_DQ<29>")
	)
	(arc
		(start 90.273886 -293.038784)
		(mid 90.456137 -293.089134)
		(end 90.639646 -293.04361)
		(width 0.0889)
		(layer "In2.Cu")
		(net "M_C_CPU1_SB_DQ<29>")
	)
	(arc
		(start 93.46819 -293.038784)
		(mid 93.751146 -292.962607)
		(end 94.034102 -293.038784)
		(width 0.0889)
		(layer "In2.Cu")
		(net "M_C_CPU1_SB_DQ<29>")
	)
	(arc
		(start 95.348044 -293.038784)
		(mid 95.59564 -292.963606)
		(end 95.85071 -293.007034)
		(width 0.0889)
		(layer "In2.Cu")
		(net "M_C_CPU1_SB_DQ<29>")
	)
	(arc
		(start 89.334086 -293.038784)
		(mid 89.52103 -293.089039)
		(end 89.707974 -293.038784)
		(width 0.0889)
		(layer "In2.Cu")
		(net "M_C_CPU1_SB_DQ<29>")
	)
	(arc
		(start 91.21394 -293.038784)
		(mid 91.396191 -293.089134)
		(end 91.5797 -293.04361)
		(width 0.0889)
		(layer "In2.Cu")
		(net "M_C_CPU1_SB_DQ<29>")
	)
	(arc
		(start 88.768174 -293.038784)
		(mid 89.05113 -292.962607)
		(end 89.334086 -293.038784)
		(width 0.0889)
		(layer "In2.Cu")
		(net "M_C_CPU1_SB_DQ<29>")
	)
	(arc
		(start 94.973902 -293.038784)
		(mid 95.156153 -293.089134)
		(end 95.339662 -293.04361)
		(width 0.0889)
		(layer "In2.Cu")
		(net "M_C_CPU1_SB_DQ<29>")
	)
	(arc
		(start 79.466186 -296.172636)
		(mid 79.532529 -296.073347)
		(end 79.555848 -295.956228)
		(width 0.0889)
		(layer "In2.Cu")
		(net "M_C_CPU1_SB_DQ<29>")
	)
	(arc
		(start 94.40799 -293.038784)
		(mid 94.690946 -292.962607)
		(end 94.973902 -293.038784)
		(width 0.0889)
		(layer "In2.Cu")
		(net "M_C_CPU1_SB_DQ<29>")
	)
	(arc
		(start 85.57387 -293.038784)
		(mid 85.756121 -293.089134)
		(end 85.93963 -293.04361)
		(width 0.0889)
		(layer "In2.Cu")
		(net "M_C_CPU1_SB_DQ<29>")
	)
	(arc
		(start 91.588082 -293.038784)
		(mid 91.871038 -292.962607)
		(end 92.153994 -293.038784)
		(width 0.0889)
		(layer "In2.Cu")
		(net "M_C_CPU1_SB_DQ<29>")
	)
	(arc
		(start 82.18805 -293.038784)
		(mid 82.471006 -292.962607)
		(end 82.753962 -293.038784)
		(width 0.0889)
		(layer "In2.Cu")
		(net "M_C_CPU1_SB_DQ<29>")
	)
	(arc
		(start 79.870046 -295.450514)
		(mid 79.984722 -295.31718)
		(end 80.026002 -295.146222)
		(width 0.0889)
		(layer "In2.Cu")
		(net "M_C_CPU1_SB_DQ<29>")
	)
	(arc
		(start 87.82812 -293.038784)
		(mid 88.111076 -292.962607)
		(end 88.394032 -293.038784)
		(width 0.0889)
		(layer "In2.Cu")
		(net "M_C_CPU1_SB_DQ<29>")
	)
	(arc
		(start 93.10243 -293.04361)
		(mid 93.285938 -293.089104)
		(end 93.46819 -293.038784)
		(width 0.0889)
		(layer "In2.Cu")
		(net "M_C_CPU1_SB_DQ<29>")
	)
	(arc
		(start 89.707974 -293.038784)
		(mid 89.99093 -292.962607)
		(end 90.273886 -293.038784)
		(width 0.0889)
		(layer "In2.Cu")
		(net "M_C_CPU1_SB_DQ<29>")
	)
	(arc
		(start 94.034102 -293.038784)
		(mid 94.221046 -293.089039)
		(end 94.40799 -293.038784)
		(width 0.0889)
		(layer "In2.Cu")
		(net "M_C_CPU1_SB_DQ<29>")
	)
	(arc
		(start 81.247996 -293.038784)
		(mid 81.530952 -292.962607)
		(end 81.813908 -293.038784)
		(width 0.0889)
		(layer "In2.Cu")
		(net "M_C_CPU1_SB_DQ<29>")
	)
	(arc
		(start 83.128104 -293.038784)
		(mid 83.41106 -292.962607)
		(end 83.694016 -293.038784)
		(width 0.0889)
		(layer "In2.Cu")
		(net "M_C_CPU1_SB_DQ<29>")
	)
	(arc
		(start 79.555848 -295.956228)
		(mid 79.620363 -295.694009)
		(end 79.79918 -295.491662)
		(width 0.0889)
		(layer "In2.Cu")
		(net "M_C_CPU1_SB_DQ<29>")
	)
	(arc
		(start 80.338676 -294.641016)
		(mid 80.454103 -294.50764)
		(end 80.495648 -294.336216)
		(width 0.0889)
		(layer "In2.Cu")
		(net "M_C_CPU1_SB_DQ<29>")
	)
	(arc
		(start 88.402414 -293.04361)
		(mid 88.585922 -293.089104)
		(end 88.768174 -293.038784)
		(width 0.0889)
		(layer "In2.Cu")
		(net "M_C_CPU1_SB_DQ<29>")
	)
	(arc
		(start 84.63407 -293.038784)
		(mid 84.821014 -293.089039)
		(end 85.007958 -293.038784)
		(width 0.0889)
		(layer "In2.Cu")
		(net "M_C_CPU1_SB_DQ<29>")
	)
	(arc
		(start 80.965802 -293.52621)
		(mid 81.040858 -293.245662)
		(end 81.245964 -293.040054)
		(width 0.0889)
		(layer "In2.Cu")
		(net "M_C_CPU1_SB_DQ<29>")
	)
	(segment
		(start 95.157798 -291.64026)
		(end 94.690946 -291.906198)
		(width 0.10668)
		(layer "F.Cu")
		(net "M_C_CPU1_SB_DQ<28>")
	)
	(segment
		(start 79.838296 -292.228778)
		(end 79.84871 -292.222682)
		(width 0.0889)
		(layer "In2.Cu")
		(net "M_C_CPU1_SB_DQ<28>")
	)
	(segment
		(start 85.10397 -292.228778)
		(end 85.112352 -292.233604)
		(width 0.0889)
		(layer "In2.Cu")
		(net "M_C_CPU1_SB_DQ<28>")
	)
	(segment
		(start 94.44101 -292.197028)
		(end 94.537022 -292.171628)
		(width 0.0889)
		(layer "In2.Cu")
		(net "M_C_CPU1_SB_DQ<28>")
	)
	(segment
		(start 78.860142 -293.870634)
		(end 78.897988 -293.84879)
		(width 0.0889)
		(layer "In2.Cu")
		(net "M_C_CPU1_SB_DQ<28>")
	)
	(segment
		(start 62.944248 -315.750448)
		(end 62.944248 -315.538358)
		(width 0.14478)
		(layer "In2.Cu")
		(net "M_C_CPU1_SB_DQ<28>")
	)
	(segment
		(start 66.034666 -312.890408)
		(end 66.197988 -312.727086)
		(width 0.14478)
		(layer "In2.Cu")
		(net "M_C_CPU1_SB_DQ<28>")
	)
	(segment
		(start 64.650874 -313.310524)
		(end 65.01765 -313.6773)
		(width 0.14478)
		(layer "In2.Cu")
		(net "M_C_CPU1_SB_DQ<28>")
	)
	(segment
		(start 65.437766 -312.523632)
		(end 65.804542 -312.890408)
		(width 0.14478)
		(layer "In2.Cu")
		(net "M_C_CPU1_SB_DQ<28>")
	)
	(segment
		(start 44.340018 -315.485272)
		(end 44.774866 -315.92012)
		(width 0.14478)
		(layer "In2.Cu")
		(net "M_C_CPU1_SB_DQ<28>")
	)
	(segment
		(start 63.633858 -314.097416)
		(end 63.863982 -314.097416)
		(width 0.14478)
		(layer "In2.Cu")
		(net "M_C_CPU1_SB_DQ<28>")
	)
	(segment
		(start 65.04432 -312.917078)
		(end 65.04432 -312.686954)
		(width 0.14478)
		(layer "In2.Cu")
		(net "M_C_CPU1_SB_DQ<28>")
	)
	(segment
		(start 64.624204 -314.30087)
		(end 64.624204 -314.070746)
		(width 0.14478)
		(layer "In2.Cu")
		(net "M_C_CPU1_SB_DQ<28>")
	)
	(segment
		(start 83.589622 -292.233604)
		(end 83.598004 -292.228778)
		(width 0.0889)
		(layer "In2.Cu")
		(net "M_C_CPU1_SB_DQ<28>")
	)
	(segment
		(start 93.929708 -292.233604)
		(end 93.93809 -292.228778)
		(width 0.0889)
		(layer "In2.Cu")
		(net "M_C_CPU1_SB_DQ<28>")
	)
	(segment
		(start 84.529676 -292.233604)
		(end 84.538058 -292.228778)
		(width 0.0889)
		(layer "In2.Cu")
		(net "M_C_CPU1_SB_DQ<28>")
	)
	(segment
		(start 66.197988 -312.727086)
		(end 66.197988 -312.496962)
		(width 0.14478)
		(layer "In2.Cu")
		(net "M_C_CPU1_SB_DQ<28>")
	)
	(segment
		(start 94.537022 -292.171628)
		(end 94.690946 -291.906198)
		(width 0.0889)
		(layer "In2.Cu")
		(net "M_C_CPU1_SB_DQ<28>")
	)
	(segment
		(start 81.344008 -292.228778)
		(end 81.35239 -292.233604)
		(width 0.0889)
		(layer "In2.Cu")
		(net "M_C_CPU1_SB_DQ<28>")
	)
	(segment
		(start 64.230758 -314.464192)
		(end 64.460882 -314.464192)
		(width 0.14478)
		(layer "In2.Cu")
		(net "M_C_CPU1_SB_DQ<28>")
	)
	(segment
		(start 64.624204 -314.070746)
		(end 64.257428 -313.70397)
		(width 0.14478)
		(layer "In2.Cu")
		(net "M_C_CPU1_SB_DQ<28>")
	)
	(segment
		(start 65.411096 -313.513978)
		(end 65.411096 -313.283854)
		(width 0.14478)
		(layer "In2.Cu")
		(net "M_C_CPU1_SB_DQ<28>")
	)
	(segment
		(start 63.470536 -314.260738)
		(end 63.633858 -314.097416)
		(width 0.14478)
		(layer "In2.Cu")
		(net "M_C_CPU1_SB_DQ<28>")
	)
	(segment
		(start 88.289638 -292.233604)
		(end 88.29802 -292.228778)
		(width 0.0889)
		(layer "In2.Cu")
		(net "M_C_CPU1_SB_DQ<28>")
	)
	(segment
		(start 65.411096 -313.283854)
		(end 65.04432 -312.917078)
		(width 0.14478)
		(layer "In2.Cu")
		(net "M_C_CPU1_SB_DQ<28>")
	)
	(segment
		(start 65.207642 -312.523632)
		(end 65.437766 -312.523632)
		(width 0.14478)
		(layer "In2.Cu")
		(net "M_C_CPU1_SB_DQ<28>")
	)
	(segment
		(start 79.368142 -293.038784)
		(end 79.398622 -293.021004)
		(width 0.0889)
		(layer "In2.Cu")
		(net "M_C_CPU1_SB_DQ<28>")
	)
	(segment
		(start 63.67399 -315.251084)
		(end 63.837312 -315.087762)
		(width 0.14478)
		(layer "In2.Cu")
		(net "M_C_CPU1_SB_DQ<28>")
	)
	(segment
		(start 80.777842 -292.228778)
		(end 80.778096 -292.228778)
		(width 0.0889)
		(layer "In2.Cu")
		(net "M_C_CPU1_SB_DQ<28>")
	)
	(segment
		(start 78.897988 -293.84879)
		(end 78.929738 -293.830502)
		(width 0.0889)
		(layer "In2.Cu")
		(net "M_C_CPU1_SB_DQ<28>")
	)
	(segment
		(start 63.837312 -314.857638)
		(end 63.470536 -314.490862)
		(width 0.14478)
		(layer "In2.Cu")
		(net "M_C_CPU1_SB_DQ<28>")
	)
	(segment
		(start 65.831212 -312.130186)
		(end 65.831212 -311.900062)
		(width 0.14478)
		(layer "In2.Cu")
		(net "M_C_CPU1_SB_DQ<28>")
	)
	(segment
		(start 65.247774 -313.6773)
		(end 65.411096 -313.513978)
		(width 0.14478)
		(layer "In2.Cu")
		(net "M_C_CPU1_SB_DQ<28>")
	)
	(segment
		(start 62.683644 -315.04763)
		(end 62.846966 -314.884308)
		(width 0.14478)
		(layer "In2.Cu")
		(net "M_C_CPU1_SB_DQ<28>")
	)
	(segment
		(start 66.197988 -312.496962)
		(end 65.831212 -312.130186)
		(width 0.14478)
		(layer "In2.Cu")
		(net "M_C_CPU1_SB_DQ<28>")
	)
	(segment
		(start 89.803986 -292.228778)
		(end 89.812368 -292.233604)
		(width 0.0889)
		(layer "In2.Cu")
		(net "M_C_CPU1_SB_DQ<28>")
	)
	(segment
		(start 65.04432 -312.686954)
		(end 65.207642 -312.523632)
		(width 0.14478)
		(layer "In2.Cu")
		(net "M_C_CPU1_SB_DQ<28>")
	)
	(segment
		(start 62.944248 -315.538358)
		(end 62.683644 -315.277754)
		(width 0.14478)
		(layer "In2.Cu")
		(net "M_C_CPU1_SB_DQ<28>")
	)
	(segment
		(start 66.934334 -312.103516)
		(end 78.139544 -300.898306)
		(width 0.14478)
		(layer "In2.Cu")
		(net "M_C_CPU1_SB_DQ<28>")
	)
	(segment
		(start 64.257428 -313.473846)
		(end 64.42075 -313.310524)
		(width 0.14478)
		(layer "In2.Cu")
		(net "M_C_CPU1_SB_DQ<28>")
	)
	(segment
		(start 63.470536 -314.490862)
		(end 63.470536 -314.260738)
		(width 0.14478)
		(layer "In2.Cu")
		(net "M_C_CPU1_SB_DQ<28>")
	)
	(segment
		(start 92.989654 -292.233604)
		(end 92.998036 -292.228778)
		(width 0.0889)
		(layer "In2.Cu")
		(net "M_C_CPU1_SB_DQ<28>")
	)
	(segment
		(start 64.42075 -313.310524)
		(end 64.650874 -313.310524)
		(width 0.14478)
		(layer "In2.Cu")
		(net "M_C_CPU1_SB_DQ<28>")
	)
	(segment
		(start 65.994534 -311.73674)
		(end 66.224658 -311.73674)
		(width 0.14478)
		(layer "In2.Cu")
		(net "M_C_CPU1_SB_DQ<28>")
	)
	(segment
		(start 65.804542 -312.890408)
		(end 66.034666 -312.890408)
		(width 0.14478)
		(layer "In2.Cu")
		(net "M_C_CPU1_SB_DQ<28>")
	)
	(segment
		(start 44.774866 -315.92012)
		(end 62.774576 -315.92012)
		(width 0.14478)
		(layer "In2.Cu")
		(net "M_C_CPU1_SB_DQ<28>")
	)
	(segment
		(start 86.044024 -292.228778)
		(end 86.052406 -292.233604)
		(width 0.0889)
		(layer "In2.Cu")
		(net "M_C_CPU1_SB_DQ<28>")
	)
	(segment
		(start 65.831212 -311.900062)
		(end 65.994534 -311.73674)
		(width 0.14478)
		(layer "In2.Cu")
		(net "M_C_CPU1_SB_DQ<28>")
	)
	(segment
		(start 62.774576 -315.92012)
		(end 62.944248 -315.750448)
		(width 0.14478)
		(layer "In2.Cu")
		(net "M_C_CPU1_SB_DQ<28>")
	)
	(segment
		(start 66.224658 -311.73674)
		(end 66.591434 -312.103516)
		(width 0.14478)
		(layer "In2.Cu")
		(net "M_C_CPU1_SB_DQ<28>")
	)
	(segment
		(start 63.07709 -314.884308)
		(end 63.443866 -315.251084)
		(width 0.14478)
		(layer "In2.Cu")
		(net "M_C_CPU1_SB_DQ<28>")
	)
	(segment
		(start 90.74404 -292.228778)
		(end 90.752422 -292.233604)
		(width 0.0889)
		(layer "In2.Cu")
		(net "M_C_CPU1_SB_DQ<28>")
	)
	(segment
		(start 62.683644 -315.277754)
		(end 62.683644 -315.04763)
		(width 0.14478)
		(layer "In2.Cu")
		(net "M_C_CPU1_SB_DQ<28>")
	)
	(segment
		(start 78.427834 -294.658796)
		(end 78.458568 -294.641016)
		(width 0.0889)
		(layer "In2.Cu")
		(net "M_C_CPU1_SB_DQ<28>")
	)
	(segment
		(start 62.846966 -314.884308)
		(end 63.07709 -314.884308)
		(width 0.14478)
		(layer "In2.Cu")
		(net "M_C_CPU1_SB_DQ<28>")
	)
	(segment
		(start 66.591434 -312.103516)
		(end 66.934334 -312.103516)
		(width 0.14478)
		(layer "In2.Cu")
		(net "M_C_CPU1_SB_DQ<28>")
	)
	(segment
		(start 64.257428 -313.70397)
		(end 64.257428 -313.473846)
		(width 0.14478)
		(layer "In2.Cu")
		(net "M_C_CPU1_SB_DQ<28>")
	)
	(segment
		(start 79.835502 -292.230556)
		(end 79.838296 -292.228778)
		(width 0.0889)
		(layer "In2.Cu")
		(net "M_C_CPU1_SB_DQ<28>")
	)
	(segment
		(start 78.30312 -294.747442)
		(end 78.366366 -294.684196)
		(width 0.0889)
		(layer "In2.Cu")
		(net "M_C_CPU1_SB_DQ<28>")
	)
	(segment
		(start 78.139544 -295.170606)
		(end 78.139544 -295.142412)
		(width 0.0889)
		(layer "In2.Cu")
		(net "M_C_CPU1_SB_DQ<28>")
	)
	(segment
		(start 63.837312 -315.087762)
		(end 63.837312 -314.857638)
		(width 0.14478)
		(layer "In2.Cu")
		(net "M_C_CPU1_SB_DQ<28>")
	)
	(segment
		(start 64.460882 -314.464192)
		(end 64.624204 -314.30087)
		(width 0.14478)
		(layer "In2.Cu")
		(net "M_C_CPU1_SB_DQ<28>")
	)
	(segment
		(start 78.139544 -300.898306)
		(end 78.139544 -295.170606)
		(width 0.14478)
		(layer "In2.Cu")
		(net "M_C_CPU1_SB_DQ<28>")
	)
	(segment
		(start 79.329026 -293.061644)
		(end 79.368142 -293.038784)
		(width 0.0889)
		(layer "In2.Cu")
		(net "M_C_CPU1_SB_DQ<28>")
	)
	(segment
		(start 65.01765 -313.6773)
		(end 65.247774 -313.6773)
		(width 0.14478)
		(layer "In2.Cu")
		(net "M_C_CPU1_SB_DQ<28>")
	)
	(segment
		(start 63.863982 -314.097416)
		(end 64.230758 -314.464192)
		(width 0.14478)
		(layer "In2.Cu")
		(net "M_C_CPU1_SB_DQ<28>")
	)
	(segment
		(start 89.229692 -292.233604)
		(end 89.238074 -292.228778)
		(width 0.0889)
		(layer "In2.Cu")
		(net "M_C_CPU1_SB_DQ<28>")
	)
	(segment
		(start 63.443866 -315.251084)
		(end 63.67399 -315.251084)
		(width 0.14478)
		(layer "In2.Cu")
		(net "M_C_CPU1_SB_DQ<28>")
	)
	(arc
		(start 79.398622 -293.021004)
		(mid 79.514049 -292.887628)
		(end 79.555594 -292.716204)
		(width 0.0889)
		(layer "In2.Cu")
		(net "M_C_CPU1_SB_DQ<28>")
	)
	(arc
		(start 91.118182 -292.228778)
		(mid 91.401138 -292.152601)
		(end 91.684094 -292.228778)
		(width 0.0889)
		(layer "In2.Cu")
		(net "M_C_CPU1_SB_DQ<28>")
	)
	(arc
		(start 92.623894 -292.228778)
		(mid 92.806145 -292.279128)
		(end 92.989654 -292.233604)
		(width 0.0889)
		(layer "In2.Cu")
		(net "M_C_CPU1_SB_DQ<28>")
	)
	(arc
		(start 92.057982 -292.228778)
		(mid 92.340938 -292.152601)
		(end 92.623894 -292.228778)
		(width 0.0889)
		(layer "In2.Cu")
		(net "M_C_CPU1_SB_DQ<28>")
	)
	(arc
		(start 78.366366 -294.684196)
		(mid 78.394582 -294.665406)
		(end 78.427834 -294.658796)
		(width 0.0889)
		(layer "In2.Cu")
		(net "M_C_CPU1_SB_DQ<28>")
	)
	(arc
		(start 86.052406 -292.233604)
		(mid 86.235914 -292.279098)
		(end 86.418166 -292.228778)
		(width 0.0889)
		(layer "In2.Cu")
		(net "M_C_CPU1_SB_DQ<28>")
	)
	(arc
		(start 80.778096 -292.228778)
		(mid 81.061052 -292.152601)
		(end 81.344008 -292.228778)
		(width 0.0889)
		(layer "In2.Cu")
		(net "M_C_CPU1_SB_DQ<28>")
	)
	(arc
		(start 78.929738 -293.830502)
		(mid 79.044414 -293.697168)
		(end 79.085694 -293.52621)
		(width 0.0889)
		(layer "In2.Cu")
		(net "M_C_CPU1_SB_DQ<28>")
	)
	(arc
		(start 79.84871 -292.222682)
		(mid 80.127142 -292.152584)
		(end 80.403954 -292.228778)
		(width 0.0889)
		(layer "In2.Cu")
		(net "M_C_CPU1_SB_DQ<28>")
	)
	(arc
		(start 79.085694 -293.52621)
		(mid 79.150209 -293.263991)
		(end 79.329026 -293.061644)
		(width 0.0889)
		(layer "In2.Cu")
		(net "M_C_CPU1_SB_DQ<28>")
	)
	(arc
		(start 93.563948 -292.228778)
		(mid 93.746199 -292.279128)
		(end 93.929708 -292.233604)
		(width 0.0889)
		(layer "In2.Cu")
		(net "M_C_CPU1_SB_DQ<28>")
	)
	(arc
		(start 85.478112 -292.228778)
		(mid 85.761068 -292.152601)
		(end 86.044024 -292.228778)
		(width 0.0889)
		(layer "In2.Cu")
		(net "M_C_CPU1_SB_DQ<28>")
	)
	(arc
		(start 78.139544 -295.142412)
		(mid 78.182061 -294.928666)
		(end 78.30312 -294.747442)
		(width 0.0889)
		(layer "In2.Cu")
		(net "M_C_CPU1_SB_DQ<28>")
	)
	(arc
		(start 83.223862 -292.228778)
		(mid 83.406113 -292.279128)
		(end 83.589622 -292.233604)
		(width 0.0889)
		(layer "In2.Cu")
		(net "M_C_CPU1_SB_DQ<28>")
	)
	(arc
		(start 89.812368 -292.233604)
		(mid 89.995876 -292.279098)
		(end 90.178128 -292.228778)
		(width 0.0889)
		(layer "In2.Cu")
		(net "M_C_CPU1_SB_DQ<28>")
	)
	(arc
		(start 81.35239 -292.233604)
		(mid 81.535898 -292.279098)
		(end 81.71815 -292.228778)
		(width 0.0889)
		(layer "In2.Cu")
		(net "M_C_CPU1_SB_DQ<28>")
	)
	(arc
		(start 81.71815 -292.228778)
		(mid 82.001106 -292.152601)
		(end 82.284062 -292.228778)
		(width 0.0889)
		(layer "In2.Cu")
		(net "M_C_CPU1_SB_DQ<28>")
	)
	(arc
		(start 78.458568 -294.641016)
		(mid 78.573995 -294.50764)
		(end 78.61554 -294.336216)
		(width 0.0889)
		(layer "In2.Cu")
		(net "M_C_CPU1_SB_DQ<28>")
	)
	(arc
		(start 87.923878 -292.228778)
		(mid 88.106129 -292.279128)
		(end 88.289638 -292.233604)
		(width 0.0889)
		(layer "In2.Cu")
		(net "M_C_CPU1_SB_DQ<28>")
	)
	(arc
		(start 83.598004 -292.228778)
		(mid 83.88096 -292.152601)
		(end 84.163916 -292.228778)
		(width 0.0889)
		(layer "In2.Cu")
		(net "M_C_CPU1_SB_DQ<28>")
	)
	(arc
		(start 82.65795 -292.228778)
		(mid 82.940906 -292.152601)
		(end 83.223862 -292.228778)
		(width 0.0889)
		(layer "In2.Cu")
		(net "M_C_CPU1_SB_DQ<28>")
	)
	(arc
		(start 90.752422 -292.233604)
		(mid 90.93593 -292.279098)
		(end 91.118182 -292.228778)
		(width 0.0889)
		(layer "In2.Cu")
		(net "M_C_CPU1_SB_DQ<28>")
	)
	(arc
		(start 91.684094 -292.228778)
		(mid 91.871038 -292.279033)
		(end 92.057982 -292.228778)
		(width 0.0889)
		(layer "In2.Cu")
		(net "M_C_CPU1_SB_DQ<28>")
	)
	(arc
		(start 92.998036 -292.228778)
		(mid 93.280992 -292.152601)
		(end 93.563948 -292.228778)
		(width 0.0889)
		(layer "In2.Cu")
		(net "M_C_CPU1_SB_DQ<28>")
	)
	(arc
		(start 85.112352 -292.233604)
		(mid 85.29586 -292.279098)
		(end 85.478112 -292.228778)
		(width 0.0889)
		(layer "In2.Cu")
		(net "M_C_CPU1_SB_DQ<28>")
	)
	(arc
		(start 84.538058 -292.228778)
		(mid 84.821014 -292.152601)
		(end 85.10397 -292.228778)
		(width 0.0889)
		(layer "In2.Cu")
		(net "M_C_CPU1_SB_DQ<28>")
	)
	(arc
		(start 88.863932 -292.228778)
		(mid 89.046183 -292.279128)
		(end 89.229692 -292.233604)
		(width 0.0889)
		(layer "In2.Cu")
		(net "M_C_CPU1_SB_DQ<28>")
	)
	(arc
		(start 79.555594 -292.716204)
		(mid 79.630648 -292.435982)
		(end 79.835502 -292.230556)
		(width 0.0889)
		(layer "In2.Cu")
		(net "M_C_CPU1_SB_DQ<28>")
	)
	(arc
		(start 84.163916 -292.228778)
		(mid 84.346167 -292.279128)
		(end 84.529676 -292.233604)
		(width 0.0889)
		(layer "In2.Cu")
		(net "M_C_CPU1_SB_DQ<28>")
	)
	(arc
		(start 78.61554 -294.336216)
		(mid 78.680412 -294.073253)
		(end 78.860142 -293.870634)
		(width 0.0889)
		(layer "In2.Cu")
		(net "M_C_CPU1_SB_DQ<28>")
	)
	(arc
		(start 80.403954 -292.228778)
		(mid 80.590898 -292.279102)
		(end 80.777842 -292.228778)
		(width 0.0889)
		(layer "In2.Cu")
		(net "M_C_CPU1_SB_DQ<28>")
	)
	(arc
		(start 87.357966 -292.228778)
		(mid 87.640922 -292.152601)
		(end 87.923878 -292.228778)
		(width 0.0889)
		(layer "In2.Cu")
		(net "M_C_CPU1_SB_DQ<28>")
	)
	(arc
		(start 89.238074 -292.228778)
		(mid 89.52103 -292.152601)
		(end 89.803986 -292.228778)
		(width 0.0889)
		(layer "In2.Cu")
		(net "M_C_CPU1_SB_DQ<28>")
	)
	(arc
		(start 82.284062 -292.228778)
		(mid 82.471006 -292.279033)
		(end 82.65795 -292.228778)
		(width 0.0889)
		(layer "In2.Cu")
		(net "M_C_CPU1_SB_DQ<28>")
	)
	(arc
		(start 90.178128 -292.228778)
		(mid 90.461084 -292.152601)
		(end 90.74404 -292.228778)
		(width 0.0889)
		(layer "In2.Cu")
		(net "M_C_CPU1_SB_DQ<28>")
	)
	(arc
		(start 88.29802 -292.228778)
		(mid 88.580976 -292.152601)
		(end 88.863932 -292.228778)
		(width 0.0889)
		(layer "In2.Cu")
		(net "M_C_CPU1_SB_DQ<28>")
	)
	(arc
		(start 86.418166 -292.228778)
		(mid 86.701122 -292.152601)
		(end 86.984078 -292.228778)
		(width 0.0889)
		(layer "In2.Cu")
		(net "M_C_CPU1_SB_DQ<28>")
	)
	(arc
		(start 93.93809 -292.228778)
		(mid 94.185803 -292.153558)
		(end 94.44101 -292.197028)
		(width 0.0889)
		(layer "In2.Cu")
		(net "M_C_CPU1_SB_DQ<28>")
	)
	(arc
		(start 86.984078 -292.228778)
		(mid 87.171022 -292.279033)
		(end 87.357966 -292.228778)
		(width 0.0889)
		(layer "In2.Cu")
		(net "M_C_CPU1_SB_DQ<28>")
	)
	(segment
		(start 96.097852 -290.020248)
		(end 95.631 -290.286186)
		(width 0.10668)
		(layer "F.Cu")
		(net "M_C_CPU1_SB_DQ<27>")
	)
	(segment
		(start 77.55255 -292.551866)
		(end 77.55255 -291.794946)
		(width 0.0889)
		(layer "In2.Cu")
		(net "M_C_CPU1_SB_DQ<27>")
	)
	(segment
		(start 94.504002 -289.963606)
		(end 94.512384 -289.95878)
		(width 0.0889)
		(layer "In2.Cu")
		(net "M_C_CPU1_SB_DQ<27>")
	)
	(segment
		(start 49.881028 -311.650634)
		(end 53.513736 -311.650634)
		(width 0.14478)
		(layer "In2.Cu")
		(net "M_C_CPU1_SB_DQ<27>")
	)
	(segment
		(start 53.513736 -311.650634)
		(end 54.373526 -312.510424)
		(width 0.14478)
		(layer "In2.Cu")
		(net "M_C_CPU1_SB_DQ<27>")
	)
	(segment
		(start 71.170292 -303.219104)
		(end 72.50938 -303.219104)
		(width 0.14478)
		(layer "In2.Cu")
		(net "M_C_CPU1_SB_DQ<27>")
	)
	(segment
		(start 86.044024 -289.963606)
		(end 86.052406 -289.95878)
		(width 0.0889)
		(layer "In2.Cu")
		(net "M_C_CPU1_SB_DQ<27>")
	)
	(segment
		(start 92.989654 -289.95878)
		(end 92.998036 -289.963606)
		(width 0.0889)
		(layer "In2.Cu")
		(net "M_C_CPU1_SB_DQ<27>")
	)
	(segment
		(start 88.289638 -289.95878)
		(end 88.29802 -289.963606)
		(width 0.0889)
		(layer "In2.Cu")
		(net "M_C_CPU1_SB_DQ<27>")
	)
	(segment
		(start 78.48473 -290.862766)
		(end 78.977744 -290.862766)
		(width 0.0889)
		(layer "In2.Cu")
		(net "M_C_CPU1_SB_DQ<27>")
	)
	(segment
		(start 41.337738 -312.510424)
		(end 41.495472 -312.35269)
		(width 0.14478)
		(layer "In2.Cu")
		(net "M_C_CPU1_SB_DQ<27>")
	)
	(segment
		(start 93.929708 -289.95878)
		(end 93.93809 -289.963606)
		(width 0.0889)
		(layer "In2.Cu")
		(net "M_C_CPU1_SB_DQ<27>")
	)
	(segment
		(start 42.051732 -312.132218)
		(end 42.051732 -312.35269)
		(width 0.14478)
		(layer "In2.Cu")
		(net "M_C_CPU1_SB_DQ<27>")
	)
	(segment
		(start 57.389776 -311.660286)
		(end 62.72911 -311.660286)
		(width 0.14478)
		(layer "In2.Cu")
		(net "M_C_CPU1_SB_DQ<27>")
	)
	(segment
		(start 42.19956 -312.500518)
		(end 49.031144 -312.500518)
		(width 0.14478)
		(layer "In2.Cu")
		(net "M_C_CPU1_SB_DQ<27>")
	)
	(segment
		(start 89.229692 -289.95878)
		(end 89.238074 -289.963606)
		(width 0.0889)
		(layer "In2.Cu")
		(net "M_C_CPU1_SB_DQ<27>")
	)
	(segment
		(start 95.762826 -289.937444)
		(end 95.785178 -290.020756)
		(width 0.0889)
		(layer "In2.Cu")
		(net "M_C_CPU1_SB_DQ<27>")
	)
	(segment
		(start 75.613006 -294.242744)
		(end 76.337414 -293.518336)
		(width 0.14478)
		(layer "In2.Cu")
		(net "M_C_CPU1_SB_DQ<27>")
	)
	(segment
		(start 89.803986 -289.963606)
		(end 89.812368 -289.95878)
		(width 0.0889)
		(layer "In2.Cu")
		(net "M_C_CPU1_SB_DQ<27>")
	)
	(segment
		(start 95.444056 -289.963606)
		(end 95.452438 -289.95878)
		(width 0.0889)
		(layer "In2.Cu")
		(net "M_C_CPU1_SB_DQ<27>")
	)
	(segment
		(start 41.888918 -311.969404)
		(end 42.051732 -312.132218)
		(width 0.14478)
		(layer "In2.Cu")
		(net "M_C_CPU1_SB_DQ<27>")
	)
	(segment
		(start 62.72911 -311.660286)
		(end 71.170292 -303.219104)
		(width 0.14478)
		(layer "In2.Cu")
		(net "M_C_CPU1_SB_DQ<27>")
	)
	(segment
		(start 40.23995 -312.085228)
		(end 40.665146 -312.510424)
		(width 0.14478)
		(layer "In2.Cu")
		(net "M_C_CPU1_SB_DQ<27>")
	)
	(segment
		(start 41.495472 -312.35269)
		(end 41.495472 -312.132218)
		(width 0.14478)
		(layer "In2.Cu")
		(net "M_C_CPU1_SB_DQ<27>")
	)
	(segment
		(start 83.589622 -289.95878)
		(end 83.598004 -289.963606)
		(width 0.0889)
		(layer "In2.Cu")
		(net "M_C_CPU1_SB_DQ<27>")
	)
	(segment
		(start 41.495472 -312.132218)
		(end 41.658286 -311.969404)
		(width 0.14478)
		(layer "In2.Cu")
		(net "M_C_CPU1_SB_DQ<27>")
	)
	(segment
		(start 75.613006 -300.115478)
		(end 75.613006 -294.242744)
		(width 0.14478)
		(layer "In2.Cu")
		(net "M_C_CPU1_SB_DQ<27>")
	)
	(segment
		(start 42.051732 -312.35269)
		(end 42.19956 -312.500518)
		(width 0.14478)
		(layer "In2.Cu")
		(net "M_C_CPU1_SB_DQ<27>")
	)
	(segment
		(start 77.55255 -291.794946)
		(end 78.48473 -290.862766)
		(width 0.0889)
		(layer "In2.Cu")
		(net "M_C_CPU1_SB_DQ<27>")
	)
	(segment
		(start 76.337414 -293.518336)
		(end 76.971144 -292.884606)
		(width 0.0889)
		(layer "In2.Cu")
		(net "M_C_CPU1_SB_DQ<27>")
	)
	(segment
		(start 40.665146 -312.510424)
		(end 41.337738 -312.510424)
		(width 0.14478)
		(layer "In2.Cu")
		(net "M_C_CPU1_SB_DQ<27>")
	)
	(segment
		(start 78.977744 -290.862766)
		(end 79.458058 -290.382452)
		(width 0.0889)
		(layer "In2.Cu")
		(net "M_C_CPU1_SB_DQ<27>")
	)
	(segment
		(start 72.50938 -303.219104)
		(end 75.613006 -300.115478)
		(width 0.14478)
		(layer "In2.Cu")
		(net "M_C_CPU1_SB_DQ<27>")
	)
	(segment
		(start 90.74404 -289.963606)
		(end 90.752422 -289.95878)
		(width 0.0889)
		(layer "In2.Cu")
		(net "M_C_CPU1_SB_DQ<27>")
	)
	(segment
		(start 81.344008 -289.963606)
		(end 81.35239 -289.95878)
		(width 0.0889)
		(layer "In2.Cu")
		(net "M_C_CPU1_SB_DQ<27>")
	)
	(segment
		(start 85.10397 -289.963606)
		(end 85.112352 -289.95878)
		(width 0.0889)
		(layer "In2.Cu")
		(net "M_C_CPU1_SB_DQ<27>")
	)
	(segment
		(start 77.21981 -292.884606)
		(end 77.55255 -292.551866)
		(width 0.0889)
		(layer "In2.Cu")
		(net "M_C_CPU1_SB_DQ<27>")
	)
	(segment
		(start 56.539638 -312.510424)
		(end 57.389776 -311.660286)
		(width 0.14478)
		(layer "In2.Cu")
		(net "M_C_CPU1_SB_DQ<27>")
	)
	(segment
		(start 76.971144 -292.884606)
		(end 77.21981 -292.884606)
		(width 0.0889)
		(layer "In2.Cu")
		(net "M_C_CPU1_SB_DQ<27>")
	)
	(segment
		(start 49.031144 -312.500518)
		(end 49.881028 -311.650634)
		(width 0.14478)
		(layer "In2.Cu")
		(net "M_C_CPU1_SB_DQ<27>")
	)
	(segment
		(start 80.769714 -289.95878)
		(end 80.778096 -289.963606)
		(width 0.0889)
		(layer "In2.Cu")
		(net "M_C_CPU1_SB_DQ<27>")
	)
	(segment
		(start 79.458058 -290.382452)
		(end 80.327246 -290.02228)
		(width 0.0889)
		(layer "In2.Cu")
		(net "M_C_CPU1_SB_DQ<27>")
	)
	(segment
		(start 41.658286 -311.969404)
		(end 41.888918 -311.969404)
		(width 0.14478)
		(layer "In2.Cu")
		(net "M_C_CPU1_SB_DQ<27>")
	)
	(segment
		(start 84.529676 -289.95878)
		(end 84.538058 -289.963606)
		(width 0.0889)
		(layer "In2.Cu")
		(net "M_C_CPU1_SB_DQ<27>")
	)
	(segment
		(start 95.785178 -290.020756)
		(end 95.631 -290.286186)
		(width 0.0889)
		(layer "In2.Cu")
		(net "M_C_CPU1_SB_DQ<27>")
	)
	(segment
		(start 54.373526 -312.510424)
		(end 56.539638 -312.510424)
		(width 0.14478)
		(layer "In2.Cu")
		(net "M_C_CPU1_SB_DQ<27>")
	)
	(arc
		(start 81.35239 -289.95878)
		(mid 81.535898 -289.913286)
		(end 81.71815 -289.963606)
		(width 0.0889)
		(layer "In2.Cu")
		(net "M_C_CPU1_SB_DQ<27>")
	)
	(arc
		(start 92.998036 -289.963606)
		(mid 93.280992 -290.039783)
		(end 93.563948 -289.963606)
		(width 0.0889)
		(layer "In2.Cu")
		(net "M_C_CPU1_SB_DQ<27>")
	)
	(arc
		(start 90.178128 -289.963606)
		(mid 90.461084 -290.039783)
		(end 90.74404 -289.963606)
		(width 0.0889)
		(layer "In2.Cu")
		(net "M_C_CPU1_SB_DQ<27>")
	)
	(arc
		(start 85.112352 -289.95878)
		(mid 85.29586 -289.913286)
		(end 85.478112 -289.963606)
		(width 0.0889)
		(layer "In2.Cu")
		(net "M_C_CPU1_SB_DQ<27>")
	)
	(arc
		(start 93.563948 -289.963606)
		(mid 93.746199 -289.913256)
		(end 93.929708 -289.95878)
		(width 0.0889)
		(layer "In2.Cu")
		(net "M_C_CPU1_SB_DQ<27>")
	)
	(arc
		(start 88.863932 -289.963606)
		(mid 89.046183 -289.913256)
		(end 89.229692 -289.95878)
		(width 0.0889)
		(layer "In2.Cu")
		(net "M_C_CPU1_SB_DQ<27>")
	)
	(arc
		(start 95.452438 -289.95878)
		(mid 95.605308 -289.914139)
		(end 95.762826 -289.937444)
		(width 0.0889)
		(layer "In2.Cu")
		(net "M_C_CPU1_SB_DQ<27>")
	)
	(arc
		(start 87.357966 -289.963606)
		(mid 87.640922 -290.039783)
		(end 87.923878 -289.963606)
		(width 0.0889)
		(layer "In2.Cu")
		(net "M_C_CPU1_SB_DQ<27>")
	)
	(arc
		(start 89.812368 -289.95878)
		(mid 89.995876 -289.913286)
		(end 90.178128 -289.963606)
		(width 0.0889)
		(layer "In2.Cu")
		(net "M_C_CPU1_SB_DQ<27>")
	)
	(arc
		(start 83.223862 -289.963606)
		(mid 83.406113 -289.913256)
		(end 83.589622 -289.95878)
		(width 0.0889)
		(layer "In2.Cu")
		(net "M_C_CPU1_SB_DQ<27>")
	)
	(arc
		(start 92.057982 -289.963606)
		(mid 92.340938 -290.039783)
		(end 92.623894 -289.963606)
		(width 0.0889)
		(layer "In2.Cu")
		(net "M_C_CPU1_SB_DQ<27>")
	)
	(arc
		(start 91.118182 -289.963606)
		(mid 91.401138 -290.039783)
		(end 91.684094 -289.963606)
		(width 0.0889)
		(layer "In2.Cu")
		(net "M_C_CPU1_SB_DQ<27>")
	)
	(arc
		(start 90.752422 -289.95878)
		(mid 90.93593 -289.913286)
		(end 91.118182 -289.963606)
		(width 0.0889)
		(layer "In2.Cu")
		(net "M_C_CPU1_SB_DQ<27>")
	)
	(arc
		(start 88.29802 -289.963606)
		(mid 88.580976 -290.039783)
		(end 88.863932 -289.963606)
		(width 0.0889)
		(layer "In2.Cu")
		(net "M_C_CPU1_SB_DQ<27>")
	)
	(arc
		(start 91.684094 -289.963606)
		(mid 91.871038 -289.913351)
		(end 92.057982 -289.963606)
		(width 0.0889)
		(layer "In2.Cu")
		(net "M_C_CPU1_SB_DQ<27>")
	)
	(arc
		(start 82.65795 -289.963606)
		(mid 82.940906 -290.039783)
		(end 83.223862 -289.963606)
		(width 0.0889)
		(layer "In2.Cu")
		(net "M_C_CPU1_SB_DQ<27>")
	)
	(arc
		(start 86.984078 -289.963606)
		(mid 87.171022 -289.913351)
		(end 87.357966 -289.963606)
		(width 0.0889)
		(layer "In2.Cu")
		(net "M_C_CPU1_SB_DQ<27>")
	)
	(arc
		(start 83.598004 -289.963606)
		(mid 83.88096 -290.039783)
		(end 84.163916 -289.963606)
		(width 0.0889)
		(layer "In2.Cu")
		(net "M_C_CPU1_SB_DQ<27>")
	)
	(arc
		(start 80.778096 -289.963606)
		(mid 81.061052 -290.039783)
		(end 81.344008 -289.963606)
		(width 0.0889)
		(layer "In2.Cu")
		(net "M_C_CPU1_SB_DQ<27>")
	)
	(arc
		(start 84.163916 -289.963606)
		(mid 84.346167 -289.913256)
		(end 84.529676 -289.95878)
		(width 0.0889)
		(layer "In2.Cu")
		(net "M_C_CPU1_SB_DQ<27>")
	)
	(arc
		(start 80.403954 -289.963606)
		(mid 80.586205 -289.913256)
		(end 80.769714 -289.95878)
		(width 0.0889)
		(layer "In2.Cu")
		(net "M_C_CPU1_SB_DQ<27>")
	)
	(arc
		(start 89.238074 -289.963606)
		(mid 89.52103 -290.039783)
		(end 89.803986 -289.963606)
		(width 0.0889)
		(layer "In2.Cu")
		(net "M_C_CPU1_SB_DQ<27>")
	)
	(arc
		(start 86.052406 -289.95878)
		(mid 86.235914 -289.913286)
		(end 86.418166 -289.963606)
		(width 0.0889)
		(layer "In2.Cu")
		(net "M_C_CPU1_SB_DQ<27>")
	)
	(arc
		(start 84.538058 -289.963606)
		(mid 84.821014 -290.039783)
		(end 85.10397 -289.963606)
		(width 0.0889)
		(layer "In2.Cu")
		(net "M_C_CPU1_SB_DQ<27>")
	)
	(arc
		(start 86.418166 -289.963606)
		(mid 86.701122 -290.039783)
		(end 86.984078 -289.963606)
		(width 0.0889)
		(layer "In2.Cu")
		(net "M_C_CPU1_SB_DQ<27>")
	)
	(arc
		(start 92.623894 -289.963606)
		(mid 92.806145 -289.913256)
		(end 92.989654 -289.95878)
		(width 0.0889)
		(layer "In2.Cu")
		(net "M_C_CPU1_SB_DQ<27>")
	)
	(arc
		(start 94.878144 -289.963606)
		(mid 95.1611 -290.039783)
		(end 95.444056 -289.963606)
		(width 0.0889)
		(layer "In2.Cu")
		(net "M_C_CPU1_SB_DQ<27>")
	)
	(arc
		(start 85.478112 -289.963606)
		(mid 85.761068 -290.039783)
		(end 86.044024 -289.963606)
		(width 0.0889)
		(layer "In2.Cu")
		(net "M_C_CPU1_SB_DQ<27>")
	)
	(arc
		(start 87.923878 -289.963606)
		(mid 88.106129 -289.913256)
		(end 88.289638 -289.95878)
		(width 0.0889)
		(layer "In2.Cu")
		(net "M_C_CPU1_SB_DQ<27>")
	)
	(arc
		(start 94.512384 -289.95878)
		(mid 94.695892 -289.913286)
		(end 94.878144 -289.963606)
		(width 0.0889)
		(layer "In2.Cu")
		(net "M_C_CPU1_SB_DQ<27>")
	)
	(arc
		(start 82.284062 -289.963606)
		(mid 82.471006 -289.913351)
		(end 82.65795 -289.963606)
		(width 0.0889)
		(layer "In2.Cu")
		(net "M_C_CPU1_SB_DQ<27>")
	)
	(arc
		(start 81.71815 -289.963606)
		(mid 82.001106 -290.039783)
		(end 82.284062 -289.963606)
		(width 0.0889)
		(layer "In2.Cu")
		(net "M_C_CPU1_SB_DQ<27>")
	)
	(arc
		(start 80.327246 -290.02228)
		(mid 80.363687 -289.990442)
		(end 80.403954 -289.963606)
		(width 0.0889)
		(layer "In2.Cu")
		(net "M_C_CPU1_SB_DQ<27>")
	)
	(arc
		(start 93.93809 -289.963606)
		(mid 94.221046 -290.039783)
		(end 94.504002 -289.963606)
		(width 0.0889)
		(layer "In2.Cu")
		(net "M_C_CPU1_SB_DQ<27>")
	)
	(segment
		(start 94.687898 -289.210242)
		(end 94.221046 -289.47618)
		(width 0.10668)
		(layer "F.Cu")
		(net "M_C_CPU1_SB_DQ<26>")
	)
	(segment
		(start 79.215234 -289.230562)
		(end 79.651098 -289.230562)
		(width 0.0889)
		(layer "In2.Cu")
		(net "M_C_CPU1_SB_DQ<26>")
	)
	(segment
		(start 43.244008 -310.810402)
		(end 49.43475 -310.810402)
		(width 0.14478)
		(layer "In2.Cu")
		(net "M_C_CPU1_SB_DQ<26>")
	)
	(segment
		(start 94.352618 -289.127438)
		(end 94.37497 -289.21075)
		(width 0.0889)
		(layer "In2.Cu")
		(net "M_C_CPU1_SB_DQ<26>")
	)
	(segment
		(start 75.948794 -292.620446)
		(end 76.53401 -292.03523)
		(width 0.0889)
		(layer "In2.Cu")
		(net "M_C_CPU1_SB_DQ<26>")
	)
	(segment
		(start 86.879684 -289.148774)
		(end 86.888066 -289.1536)
		(width 0.0889)
		(layer "In2.Cu")
		(net "M_C_CPU1_SB_DQ<26>")
	)
	(segment
		(start 43.081194 -310.647588)
		(end 43.244008 -310.810402)
		(width 0.14478)
		(layer "In2.Cu")
		(net "M_C_CPU1_SB_DQ<26>")
	)
	(segment
		(start 42.524934 -309.856378)
		(end 42.687748 -309.693564)
		(width 0.14478)
		(layer "In2.Cu")
		(net "M_C_CPU1_SB_DQ<26>")
	)
	(segment
		(start 85.93963 -289.148774)
		(end 85.948012 -289.1536)
		(width 0.0889)
		(layer "In2.Cu")
		(net "M_C_CPU1_SB_DQ<26>")
	)
	(segment
		(start 93.094048 -289.1536)
		(end 93.10243 -289.148774)
		(width 0.0889)
		(layer "In2.Cu")
		(net "M_C_CPU1_SB_DQ<26>")
	)
	(segment
		(start 76.621386 -291.82441)
		(end 79.215234 -289.230562)
		(width 0.0889)
		(layer "In2.Cu")
		(net "M_C_CPU1_SB_DQ<26>")
	)
	(segment
		(start 42.131488 -310.810402)
		(end 42.36212 -310.810402)
		(width 0.14478)
		(layer "In2.Cu")
		(net "M_C_CPU1_SB_DQ<26>")
	)
	(segment
		(start 41.575228 -309.693564)
		(end 41.80586 -309.693564)
		(width 0.14478)
		(layer "In2.Cu")
		(net "M_C_CPU1_SB_DQ<26>")
	)
	(segment
		(start 88.394032 -289.1536)
		(end 88.402414 -289.148774)
		(width 0.0889)
		(layer "In2.Cu")
		(net "M_C_CPU1_SB_DQ<26>")
	)
	(segment
		(start 63.126366 -309.960264)
		(end 74.703686 -298.382944)
		(width 0.14478)
		(layer "In2.Cu")
		(net "M_C_CPU1_SB_DQ<26>")
	)
	(segment
		(start 41.968674 -309.856378)
		(end 41.968674 -310.647588)
		(width 0.14478)
		(layer "In2.Cu")
		(net "M_C_CPU1_SB_DQ<26>")
	)
	(segment
		(start 82.179668 -289.148774)
		(end 82.18805 -289.1536)
		(width 0.0889)
		(layer "In2.Cu")
		(net "M_C_CPU1_SB_DQ<26>")
	)
	(segment
		(start 76.53401 -292.03523)
		(end 76.621386 -291.82441)
		(width 0.0889)
		(layer "In2.Cu")
		(net "M_C_CPU1_SB_DQ<26>")
	)
	(segment
		(start 92.153994 -289.1536)
		(end 92.162376 -289.148774)
		(width 0.0889)
		(layer "In2.Cu")
		(net "M_C_CPU1_SB_DQ<26>")
	)
	(segment
		(start 42.91838 -309.693564)
		(end 43.081194 -309.856378)
		(width 0.14478)
		(layer "In2.Cu")
		(net "M_C_CPU1_SB_DQ<26>")
	)
	(segment
		(start 41.80586 -309.693564)
		(end 41.968674 -309.856378)
		(width 0.14478)
		(layer "In2.Cu")
		(net "M_C_CPU1_SB_DQ<26>")
	)
	(segment
		(start 94.37497 -289.21075)
		(end 94.221046 -289.47618)
		(width 0.0889)
		(layer "In2.Cu")
		(net "M_C_CPU1_SB_DQ<26>")
	)
	(segment
		(start 41.2496 -310.810402)
		(end 41.412414 -310.647588)
		(width 0.14478)
		(layer "In2.Cu")
		(net "M_C_CPU1_SB_DQ<26>")
	)
	(segment
		(start 56.95315 -310.810402)
		(end 57.803288 -309.960264)
		(width 0.14478)
		(layer "In2.Cu")
		(net "M_C_CPU1_SB_DQ<26>")
	)
	(segment
		(start 82.753962 -289.1536)
		(end 82.762344 -289.148774)
		(width 0.0889)
		(layer "In2.Cu")
		(net "M_C_CPU1_SB_DQ<26>")
	)
	(segment
		(start 90.639646 -289.148774)
		(end 90.648028 -289.1536)
		(width 0.0889)
		(layer "In2.Cu")
		(net "M_C_CPU1_SB_DQ<26>")
	)
	(segment
		(start 40.665146 -310.810402)
		(end 41.2496 -310.810402)
		(width 0.14478)
		(layer "In2.Cu")
		(net "M_C_CPU1_SB_DQ<26>")
	)
	(segment
		(start 57.803288 -309.960264)
		(end 63.126366 -309.960264)
		(width 0.14478)
		(layer "In2.Cu")
		(net "M_C_CPU1_SB_DQ<26>")
	)
	(segment
		(start 91.5797 -289.148774)
		(end 91.588082 -289.1536)
		(width 0.0889)
		(layer "In2.Cu")
		(net "M_C_CPU1_SB_DQ<26>")
	)
	(segment
		(start 41.968674 -310.647588)
		(end 42.131488 -310.810402)
		(width 0.14478)
		(layer "In2.Cu")
		(net "M_C_CPU1_SB_DQ<26>")
	)
	(segment
		(start 74.703686 -298.382944)
		(end 74.703686 -293.865554)
		(width 0.14478)
		(layer "In2.Cu")
		(net "M_C_CPU1_SB_DQ<26>")
	)
	(segment
		(start 42.524934 -310.647588)
		(end 42.524934 -309.856378)
		(width 0.14478)
		(layer "In2.Cu")
		(net "M_C_CPU1_SB_DQ<26>")
	)
	(segment
		(start 79.935324 -289.153854)
		(end 79.958692 -289.140392)
		(width 0.0889)
		(layer "In2.Cu")
		(net "M_C_CPU1_SB_DQ<26>")
	)
	(segment
		(start 43.081194 -309.856378)
		(end 43.081194 -310.647588)
		(width 0.14478)
		(layer "In2.Cu")
		(net "M_C_CPU1_SB_DQ<26>")
	)
	(segment
		(start 42.687748 -309.693564)
		(end 42.91838 -309.693564)
		(width 0.14478)
		(layer "In2.Cu")
		(net "M_C_CPU1_SB_DQ<26>")
	)
	(segment
		(start 42.36212 -310.810402)
		(end 42.524934 -310.647588)
		(width 0.14478)
		(layer "In2.Cu")
		(net "M_C_CPU1_SB_DQ<26>")
	)
	(segment
		(start 53.171852 -309.960264)
		(end 54.02199 -310.810402)
		(width 0.14478)
		(layer "In2.Cu")
		(net "M_C_CPU1_SB_DQ<26>")
	)
	(segment
		(start 41.412414 -310.647588)
		(end 41.412414 -309.856378)
		(width 0.14478)
		(layer "In2.Cu")
		(net "M_C_CPU1_SB_DQ<26>")
	)
	(segment
		(start 40.23995 -310.385206)
		(end 40.665146 -310.810402)
		(width 0.14478)
		(layer "In2.Cu")
		(net "M_C_CPU1_SB_DQ<26>")
	)
	(segment
		(start 54.02199 -310.810402)
		(end 56.95315 -310.810402)
		(width 0.14478)
		(layer "In2.Cu")
		(net "M_C_CPU1_SB_DQ<26>")
	)
	(segment
		(start 50.284888 -309.960264)
		(end 53.171852 -309.960264)
		(width 0.14478)
		(layer "In2.Cu")
		(net "M_C_CPU1_SB_DQ<26>")
	)
	(segment
		(start 87.453978 -289.1536)
		(end 87.46236 -289.148774)
		(width 0.0889)
		(layer "In2.Cu")
		(net "M_C_CPU1_SB_DQ<26>")
	)
	(segment
		(start 83.694016 -289.1536)
		(end 83.702398 -289.148774)
		(width 0.0889)
		(layer "In2.Cu")
		(net "M_C_CPU1_SB_DQ<26>")
	)
	(segment
		(start 49.43475 -310.810402)
		(end 50.284888 -309.960264)
		(width 0.14478)
		(layer "In2.Cu")
		(net "M_C_CPU1_SB_DQ<26>")
	)
	(segment
		(start 41.412414 -309.856378)
		(end 41.575228 -309.693564)
		(width 0.14478)
		(layer "In2.Cu")
		(net "M_C_CPU1_SB_DQ<26>")
	)
	(segment
		(start 74.703686 -293.865554)
		(end 75.948794 -292.620446)
		(width 0.14478)
		(layer "In2.Cu")
		(net "M_C_CPU1_SB_DQ<26>")
	)
	(arc
		(start 93.46819 -289.1536)
		(mid 93.751146 -289.229777)
		(end 94.034102 -289.1536)
		(width 0.0889)
		(layer "In2.Cu")
		(net "M_C_CPU1_SB_DQ<26>")
	)
	(arc
		(start 85.007958 -289.1536)
		(mid 85.290914 -289.229777)
		(end 85.57387 -289.1536)
		(width 0.0889)
		(layer "In2.Cu")
		(net "M_C_CPU1_SB_DQ<26>")
	)
	(arc
		(start 79.651098 -289.230562)
		(mid 79.798312 -289.211093)
		(end 79.935324 -289.153854)
		(width 0.0889)
		(layer "In2.Cu")
		(net "M_C_CPU1_SB_DQ<26>")
	)
	(arc
		(start 84.63407 -289.1536)
		(mid 84.821014 -289.103345)
		(end 85.007958 -289.1536)
		(width 0.0889)
		(layer "In2.Cu")
		(net "M_C_CPU1_SB_DQ<26>")
	)
	(arc
		(start 90.273886 -289.1536)
		(mid 90.456137 -289.10325)
		(end 90.639646 -289.148774)
		(width 0.0889)
		(layer "In2.Cu")
		(net "M_C_CPU1_SB_DQ<26>")
	)
	(arc
		(start 87.82812 -289.1536)
		(mid 88.111076 -289.229777)
		(end 88.394032 -289.1536)
		(width 0.0889)
		(layer "In2.Cu")
		(net "M_C_CPU1_SB_DQ<26>")
	)
	(arc
		(start 80.874108 -289.1536)
		(mid 81.061052 -289.103345)
		(end 81.247996 -289.1536)
		(width 0.0889)
		(layer "In2.Cu")
		(net "M_C_CPU1_SB_DQ<26>")
	)
	(arc
		(start 90.648028 -289.1536)
		(mid 90.930984 -289.229777)
		(end 91.21394 -289.1536)
		(width 0.0889)
		(layer "In2.Cu")
		(net "M_C_CPU1_SB_DQ<26>")
	)
	(arc
		(start 86.888066 -289.1536)
		(mid 87.171022 -289.229777)
		(end 87.453978 -289.1536)
		(width 0.0889)
		(layer "In2.Cu")
		(net "M_C_CPU1_SB_DQ<26>")
	)
	(arc
		(start 87.46236 -289.148774)
		(mid 87.645868 -289.10328)
		(end 87.82812 -289.1536)
		(width 0.0889)
		(layer "In2.Cu")
		(net "M_C_CPU1_SB_DQ<26>")
	)
	(arc
		(start 89.707974 -289.1536)
		(mid 89.99093 -289.229777)
		(end 90.273886 -289.1536)
		(width 0.0889)
		(layer "In2.Cu")
		(net "M_C_CPU1_SB_DQ<26>")
	)
	(arc
		(start 81.247996 -289.1536)
		(mid 81.530952 -289.229777)
		(end 81.813908 -289.1536)
		(width 0.0889)
		(layer "In2.Cu")
		(net "M_C_CPU1_SB_DQ<26>")
	)
	(arc
		(start 91.588082 -289.1536)
		(mid 91.871038 -289.229777)
		(end 92.153994 -289.1536)
		(width 0.0889)
		(layer "In2.Cu")
		(net "M_C_CPU1_SB_DQ<26>")
	)
	(arc
		(start 83.128104 -289.1536)
		(mid 83.41106 -289.229777)
		(end 83.694016 -289.1536)
		(width 0.0889)
		(layer "In2.Cu")
		(net "M_C_CPU1_SB_DQ<26>")
	)
	(arc
		(start 82.18805 -289.1536)
		(mid 82.471006 -289.229777)
		(end 82.753962 -289.1536)
		(width 0.0889)
		(layer "In2.Cu")
		(net "M_C_CPU1_SB_DQ<26>")
	)
	(arc
		(start 88.768174 -289.1536)
		(mid 89.05113 -289.229777)
		(end 89.334086 -289.1536)
		(width 0.0889)
		(layer "In2.Cu")
		(net "M_C_CPU1_SB_DQ<26>")
	)
	(arc
		(start 85.57387 -289.1536)
		(mid 85.756121 -289.10325)
		(end 85.93963 -289.148774)
		(width 0.0889)
		(layer "In2.Cu")
		(net "M_C_CPU1_SB_DQ<26>")
	)
	(arc
		(start 85.948012 -289.1536)
		(mid 86.230968 -289.229777)
		(end 86.513924 -289.1536)
		(width 0.0889)
		(layer "In2.Cu")
		(net "M_C_CPU1_SB_DQ<26>")
	)
	(arc
		(start 93.10243 -289.148774)
		(mid 93.285938 -289.10328)
		(end 93.46819 -289.1536)
		(width 0.0889)
		(layer "In2.Cu")
		(net "M_C_CPU1_SB_DQ<26>")
	)
	(arc
		(start 83.702398 -289.148774)
		(mid 83.885906 -289.10328)
		(end 84.068158 -289.1536)
		(width 0.0889)
		(layer "In2.Cu")
		(net "M_C_CPU1_SB_DQ<26>")
	)
	(arc
		(start 89.334086 -289.1536)
		(mid 89.52103 -289.103345)
		(end 89.707974 -289.1536)
		(width 0.0889)
		(layer "In2.Cu")
		(net "M_C_CPU1_SB_DQ<26>")
	)
	(arc
		(start 82.762344 -289.148774)
		(mid 82.945852 -289.10328)
		(end 83.128104 -289.1536)
		(width 0.0889)
		(layer "In2.Cu")
		(net "M_C_CPU1_SB_DQ<26>")
	)
	(arc
		(start 79.958692 -289.140392)
		(mid 80.135087 -289.103489)
		(end 80.308196 -289.1536)
		(width 0.0889)
		(layer "In2.Cu")
		(net "M_C_CPU1_SB_DQ<26>")
	)
	(arc
		(start 80.308196 -289.1536)
		(mid 80.591152 -289.229777)
		(end 80.874108 -289.1536)
		(width 0.0889)
		(layer "In2.Cu")
		(net "M_C_CPU1_SB_DQ<26>")
	)
	(arc
		(start 91.21394 -289.1536)
		(mid 91.396191 -289.10325)
		(end 91.5797 -289.148774)
		(width 0.0889)
		(layer "In2.Cu")
		(net "M_C_CPU1_SB_DQ<26>")
	)
	(arc
		(start 94.034102 -289.1536)
		(mid 94.190421 -289.104605)
		(end 94.352618 -289.127438)
		(width 0.0889)
		(layer "In2.Cu")
		(net "M_C_CPU1_SB_DQ<26>")
	)
	(arc
		(start 84.068158 -289.1536)
		(mid 84.351114 -289.229777)
		(end 84.63407 -289.1536)
		(width 0.0889)
		(layer "In2.Cu")
		(net "M_C_CPU1_SB_DQ<26>")
	)
	(arc
		(start 88.402414 -289.148774)
		(mid 88.585922 -289.10328)
		(end 88.768174 -289.1536)
		(width 0.0889)
		(layer "In2.Cu")
		(net "M_C_CPU1_SB_DQ<26>")
	)
	(arc
		(start 92.162376 -289.148774)
		(mid 92.345884 -289.10328)
		(end 92.528136 -289.1536)
		(width 0.0889)
		(layer "In2.Cu")
		(net "M_C_CPU1_SB_DQ<26>")
	)
	(arc
		(start 81.813908 -289.1536)
		(mid 81.996159 -289.10325)
		(end 82.179668 -289.148774)
		(width 0.0889)
		(layer "In2.Cu")
		(net "M_C_CPU1_SB_DQ<26>")
	)
	(arc
		(start 86.513924 -289.1536)
		(mid 86.696175 -289.10325)
		(end 86.879684 -289.148774)
		(width 0.0889)
		(layer "In2.Cu")
		(net "M_C_CPU1_SB_DQ<26>")
	)
	(arc
		(start 92.528136 -289.1536)
		(mid 92.811092 -289.229777)
		(end 93.094048 -289.1536)
		(width 0.0889)
		(layer "In2.Cu")
		(net "M_C_CPU1_SB_DQ<26>")
	)
	(segment
		(start 96.568006 -289.210242)
		(end 96.101154 -289.47618)
		(width 0.10668)
		(layer "F.Cu")
		(net "M_C_CPU1_SB_DQ<25>")
	)
	(segment
		(start 80.035908 -289.874198)
		(end 80.120998 -289.85718)
		(width 0.0889)
		(layer "In2.Cu")
		(net "M_C_CPU1_SB_DQ<25>")
	)
	(segment
		(start 73.121012 -300.609)
		(end 73.351136 -300.609)
		(width 0.14478)
		(layer "In2.Cu")
		(net "M_C_CPU1_SB_DQ<25>")
	)
	(segment
		(start 88.394032 -289.79876)
		(end 88.402414 -289.803586)
		(width 0.0889)
		(layer "In2.Cu")
		(net "M_C_CPU1_SB_DQ<25>")
	)
	(segment
		(start 73.744582 -299.98543)
		(end 73.907904 -299.822108)
		(width 0.14478)
		(layer "In2.Cu")
		(net "M_C_CPU1_SB_DQ<25>")
	)
	(segment
		(start 78.89875 -290.672266)
		(end 79.456788 -290.114228)
		(width 0.0889)
		(layer "In2.Cu")
		(net "M_C_CPU1_SB_DQ<25>")
	)
	(segment
		(start 57.596532 -310.810148)
		(end 62.919864 -310.810148)
		(width 0.14478)
		(layer "In2.Cu")
		(net "M_C_CPU1_SB_DQ<25>")
	)
	(segment
		(start 75.158346 -294.054276)
		(end 76.002642 -293.20998)
		(width 0.14478)
		(layer "In2.Cu")
		(net "M_C_CPU1_SB_DQ<25>")
	)
	(segment
		(start 73.351136 -300.609)
		(end 73.79843 -301.056294)
		(width 0.14478)
		(layer "In2.Cu")
		(net "M_C_CPU1_SB_DQ<25>")
	)
	(segment
		(start 72.95769 -301.002192)
		(end 72.95769 -300.772322)
		(width 0.14478)
		(layer "In2.Cu")
		(net "M_C_CPU1_SB_DQ<25>")
	)
	(segment
		(start 90.639646 -289.803586)
		(end 90.648028 -289.79876)
		(width 0.0889)
		(layer "In2.Cu")
		(net "M_C_CPU1_SB_DQ<25>")
	)
	(segment
		(start 85.93963 -289.803586)
		(end 85.948012 -289.79876)
		(width 0.0889)
		(layer "In2.Cu")
		(net "M_C_CPU1_SB_DQ<25>")
	)
	(segment
		(start 72.95769 -300.772322)
		(end 73.121012 -300.609)
		(width 0.14478)
		(layer "In2.Cu")
		(net "M_C_CPU1_SB_DQ<25>")
	)
	(segment
		(start 71.777352 -302.182784)
		(end 72.224646 -302.630078)
		(width 0.14478)
		(layer "In2.Cu")
		(net "M_C_CPU1_SB_DQ<25>")
	)
	(segment
		(start 73.011538 -301.843186)
		(end 73.241916 -301.843186)
		(width 0.14478)
		(layer "In2.Cu")
		(net "M_C_CPU1_SB_DQ<25>")
	)
	(segment
		(start 74.19213 -300.662848)
		(end 73.744582 -300.2153)
		(width 0.14478)
		(layer "In2.Cu")
		(net "M_C_CPU1_SB_DQ<25>")
	)
	(segment
		(start 93.094048 -289.79876)
		(end 93.10243 -289.803586)
		(width 0.0889)
		(layer "In2.Cu")
		(net "M_C_CPU1_SB_DQ<25>")
	)
	(segment
		(start 78.220824 -290.672266)
		(end 78.89875 -290.672266)
		(width 0.0889)
		(layer "In2.Cu")
		(net "M_C_CPU1_SB_DQ<25>")
	)
	(segment
		(start 74.979022 -299.875956)
		(end 74.531474 -299.428408)
		(width 0.14478)
		(layer "In2.Cu")
		(net "M_C_CPU1_SB_DQ<25>")
	)
	(segment
		(start 95.339662 -289.803586)
		(end 95.348044 -289.79876)
		(width 0.0889)
		(layer "In2.Cu")
		(net "M_C_CPU1_SB_DQ<25>")
	)
	(segment
		(start 72.618346 -302.466756)
		(end 72.618346 -302.236632)
		(width 0.14478)
		(layer "In2.Cu")
		(net "M_C_CPU1_SB_DQ<25>")
	)
	(segment
		(start 91.5797 -289.803586)
		(end 91.588082 -289.79876)
		(width 0.0889)
		(layer "In2.Cu")
		(net "M_C_CPU1_SB_DQ<25>")
	)
	(segment
		(start 72.224646 -302.630078)
		(end 72.455024 -302.630078)
		(width 0.14478)
		(layer "In2.Cu")
		(net "M_C_CPU1_SB_DQ<25>")
	)
	(segment
		(start 72.170798 -301.559214)
		(end 72.33412 -301.395892)
		(width 0.14478)
		(layer "In2.Cu")
		(net "M_C_CPU1_SB_DQ<25>")
	)
	(segment
		(start 95.85071 -289.76701)
		(end 95.946976 -289.74161)
		(width 0.0889)
		(layer "In2.Cu")
		(net "M_C_CPU1_SB_DQ<25>")
	)
	(segment
		(start 73.907904 -299.822108)
		(end 74.138028 -299.822108)
		(width 0.14478)
		(layer "In2.Cu")
		(net "M_C_CPU1_SB_DQ<25>")
	)
	(segment
		(start 75.158346 -298.571666)
		(end 75.158346 -294.054276)
		(width 0.14478)
		(layer "In2.Cu")
		(net "M_C_CPU1_SB_DQ<25>")
	)
	(segment
		(start 95.946976 -289.74161)
		(end 96.101154 -289.47618)
		(width 0.0889)
		(layer "In2.Cu")
		(net "M_C_CPU1_SB_DQ<25>")
	)
	(segment
		(start 74.028808 -301.056294)
		(end 74.19213 -300.892972)
		(width 0.14478)
		(layer "In2.Cu")
		(net "M_C_CPU1_SB_DQ<25>")
	)
	(segment
		(start 73.79843 -301.056294)
		(end 74.028808 -301.056294)
		(width 0.14478)
		(layer "In2.Cu")
		(net "M_C_CPU1_SB_DQ<25>")
	)
	(segment
		(start 74.531474 -299.428408)
		(end 74.531474 -299.198538)
		(width 0.14478)
		(layer "In2.Cu")
		(net "M_C_CPU1_SB_DQ<25>")
	)
	(segment
		(start 76.831698 -292.061392)
		(end 78.220824 -290.672266)
		(width 0.0889)
		(layer "In2.Cu")
		(net "M_C_CPU1_SB_DQ<25>")
	)
	(segment
		(start 73.241916 -301.843186)
		(end 73.405238 -301.679864)
		(width 0.14478)
		(layer "In2.Cu")
		(net "M_C_CPU1_SB_DQ<25>")
	)
	(segment
		(start 87.453978 -289.79876)
		(end 87.46236 -289.803586)
		(width 0.0889)
		(layer "In2.Cu")
		(net "M_C_CPU1_SB_DQ<25>")
	)
	(segment
		(start 73.744582 -300.2153)
		(end 73.744582 -299.98543)
		(width 0.14478)
		(layer "In2.Cu")
		(net "M_C_CPU1_SB_DQ<25>")
	)
	(segment
		(start 72.33412 -301.395892)
		(end 72.564244 -301.395892)
		(width 0.14478)
		(layer "In2.Cu")
		(net "M_C_CPU1_SB_DQ<25>")
	)
	(segment
		(start 62.919864 -310.810148)
		(end 71.547228 -302.182784)
		(width 0.14478)
		(layer "In2.Cu")
		(net "M_C_CPU1_SB_DQ<25>")
	)
	(segment
		(start 74.585322 -300.269402)
		(end 74.8157 -300.269402)
		(width 0.14478)
		(layer "In2.Cu")
		(net "M_C_CPU1_SB_DQ<25>")
	)
	(segment
		(start 72.564244 -301.395892)
		(end 73.011538 -301.843186)
		(width 0.14478)
		(layer "In2.Cu")
		(net "M_C_CPU1_SB_DQ<25>")
	)
	(segment
		(start 44.340018 -311.235344)
		(end 44.76496 -311.660286)
		(width 0.14478)
		(layer "In2.Cu")
		(net "M_C_CPU1_SB_DQ<25>")
	)
	(segment
		(start 71.547228 -302.182784)
		(end 71.777352 -302.182784)
		(width 0.14478)
		(layer "In2.Cu")
		(net "M_C_CPU1_SB_DQ<25>")
	)
	(segment
		(start 73.405238 -301.44974)
		(end 72.95769 -301.002192)
		(width 0.14478)
		(layer "In2.Cu")
		(net "M_C_CPU1_SB_DQ<25>")
	)
	(segment
		(start 82.753962 -289.79876)
		(end 82.762344 -289.803586)
		(width 0.0889)
		(layer "In2.Cu")
		(net "M_C_CPU1_SB_DQ<25>")
	)
	(segment
		(start 72.170798 -301.789084)
		(end 72.170798 -301.559214)
		(width 0.14478)
		(layer "In2.Cu")
		(net "M_C_CPU1_SB_DQ<25>")
	)
	(segment
		(start 53.344064 -310.810148)
		(end 54.194202 -311.660286)
		(width 0.14478)
		(layer "In2.Cu")
		(net "M_C_CPU1_SB_DQ<25>")
	)
	(segment
		(start 73.405238 -301.679864)
		(end 73.405238 -301.44974)
		(width 0.14478)
		(layer "In2.Cu")
		(net "M_C_CPU1_SB_DQ<25>")
	)
	(segment
		(start 76.002642 -293.20998)
		(end 76.605638 -292.606984)
		(width 0.0889)
		(layer "In2.Cu")
		(net "M_C_CPU1_SB_DQ<25>")
	)
	(segment
		(start 86.879684 -289.803586)
		(end 86.888066 -289.79876)
		(width 0.0889)
		(layer "In2.Cu")
		(net "M_C_CPU1_SB_DQ<25>")
	)
	(segment
		(start 49.227994 -311.660286)
		(end 50.078132 -310.810148)
		(width 0.14478)
		(layer "In2.Cu")
		(net "M_C_CPU1_SB_DQ<25>")
	)
	(segment
		(start 72.618346 -302.236632)
		(end 72.170798 -301.789084)
		(width 0.14478)
		(layer "In2.Cu")
		(net "M_C_CPU1_SB_DQ<25>")
	)
	(segment
		(start 74.979022 -300.10608)
		(end 74.979022 -299.875956)
		(width 0.14478)
		(layer "In2.Cu")
		(net "M_C_CPU1_SB_DQ<25>")
	)
	(segment
		(start 76.605638 -292.606984)
		(end 76.831698 -292.061392)
		(width 0.0889)
		(layer "In2.Cu")
		(net "M_C_CPU1_SB_DQ<25>")
	)
	(segment
		(start 74.8157 -300.269402)
		(end 74.979022 -300.10608)
		(width 0.14478)
		(layer "In2.Cu")
		(net "M_C_CPU1_SB_DQ<25>")
	)
	(segment
		(start 54.194202 -311.660286)
		(end 56.746394 -311.660286)
		(width 0.14478)
		(layer "In2.Cu")
		(net "M_C_CPU1_SB_DQ<25>")
	)
	(segment
		(start 44.76496 -311.660286)
		(end 49.227994 -311.660286)
		(width 0.14478)
		(layer "In2.Cu")
		(net "M_C_CPU1_SB_DQ<25>")
	)
	(segment
		(start 72.455024 -302.630078)
		(end 72.618346 -302.466756)
		(width 0.14478)
		(layer "In2.Cu")
		(net "M_C_CPU1_SB_DQ<25>")
	)
	(segment
		(start 56.746394 -311.660286)
		(end 57.596532 -310.810148)
		(width 0.14478)
		(layer "In2.Cu")
		(net "M_C_CPU1_SB_DQ<25>")
	)
	(segment
		(start 79.456788 -290.114228)
		(end 80.035908 -289.874198)
		(width 0.0889)
		(layer "In2.Cu")
		(net "M_C_CPU1_SB_DQ<25>")
	)
	(segment
		(start 92.153994 -289.79876)
		(end 92.162376 -289.803586)
		(width 0.0889)
		(layer "In2.Cu")
		(net "M_C_CPU1_SB_DQ<25>")
	)
	(segment
		(start 82.179668 -289.803586)
		(end 82.18805 -289.79876)
		(width 0.0889)
		(layer "In2.Cu")
		(net "M_C_CPU1_SB_DQ<25>")
	)
	(segment
		(start 50.078132 -310.810148)
		(end 53.344064 -310.810148)
		(width 0.14478)
		(layer "In2.Cu")
		(net "M_C_CPU1_SB_DQ<25>")
	)
	(segment
		(start 83.694016 -289.79876)
		(end 83.702398 -289.803586)
		(width 0.0889)
		(layer "In2.Cu")
		(net "M_C_CPU1_SB_DQ<25>")
	)
	(segment
		(start 74.531474 -299.198538)
		(end 75.158346 -298.571666)
		(width 0.14478)
		(layer "In2.Cu")
		(net "M_C_CPU1_SB_DQ<25>")
	)
	(segment
		(start 74.138028 -299.822108)
		(end 74.585322 -300.269402)
		(width 0.14478)
		(layer "In2.Cu")
		(net "M_C_CPU1_SB_DQ<25>")
	)
	(segment
		(start 74.19213 -300.892972)
		(end 74.19213 -300.662848)
		(width 0.14478)
		(layer "In2.Cu")
		(net "M_C_CPU1_SB_DQ<25>")
	)
	(arc
		(start 92.528136 -289.79876)
		(mid 92.811092 -289.722583)
		(end 93.094048 -289.79876)
		(width 0.0889)
		(layer "In2.Cu")
		(net "M_C_CPU1_SB_DQ<25>")
	)
	(arc
		(start 81.813908 -289.79876)
		(mid 81.996159 -289.84911)
		(end 82.179668 -289.803586)
		(width 0.0889)
		(layer "In2.Cu")
		(net "M_C_CPU1_SB_DQ<25>")
	)
	(arc
		(start 86.888066 -289.79876)
		(mid 87.171022 -289.722583)
		(end 87.453978 -289.79876)
		(width 0.0889)
		(layer "In2.Cu")
		(net "M_C_CPU1_SB_DQ<25>")
	)
	(arc
		(start 82.18805 -289.79876)
		(mid 82.471006 -289.722583)
		(end 82.753962 -289.79876)
		(width 0.0889)
		(layer "In2.Cu")
		(net "M_C_CPU1_SB_DQ<25>")
	)
	(arc
		(start 85.57387 -289.79876)
		(mid 85.756121 -289.84911)
		(end 85.93963 -289.803586)
		(width 0.0889)
		(layer "In2.Cu")
		(net "M_C_CPU1_SB_DQ<25>")
	)
	(arc
		(start 80.120998 -289.85718)
		(mid 80.19035 -289.850862)
		(end 80.257396 -289.832034)
		(width 0.0889)
		(layer "In2.Cu")
		(net "M_C_CPU1_SB_DQ<25>")
	)
	(arc
		(start 81.247996 -289.79876)
		(mid 81.530952 -289.722583)
		(end 81.813908 -289.79876)
		(width 0.0889)
		(layer "In2.Cu")
		(net "M_C_CPU1_SB_DQ<25>")
	)
	(arc
		(start 83.702398 -289.803586)
		(mid 83.885906 -289.84908)
		(end 84.068158 -289.79876)
		(width 0.0889)
		(layer "In2.Cu")
		(net "M_C_CPU1_SB_DQ<25>")
	)
	(arc
		(start 88.402414 -289.803586)
		(mid 88.585922 -289.84908)
		(end 88.768174 -289.79876)
		(width 0.0889)
		(layer "In2.Cu")
		(net "M_C_CPU1_SB_DQ<25>")
	)
	(arc
		(start 91.21394 -289.79876)
		(mid 91.396191 -289.84911)
		(end 91.5797 -289.803586)
		(width 0.0889)
		(layer "In2.Cu")
		(net "M_C_CPU1_SB_DQ<25>")
	)
	(arc
		(start 92.162376 -289.803586)
		(mid 92.345884 -289.84908)
		(end 92.528136 -289.79876)
		(width 0.0889)
		(layer "In2.Cu")
		(net "M_C_CPU1_SB_DQ<25>")
	)
	(arc
		(start 90.648028 -289.79876)
		(mid 90.930984 -289.722583)
		(end 91.21394 -289.79876)
		(width 0.0889)
		(layer "In2.Cu")
		(net "M_C_CPU1_SB_DQ<25>")
	)
	(arc
		(start 94.40799 -289.79876)
		(mid 94.690946 -289.722583)
		(end 94.973902 -289.79876)
		(width 0.0889)
		(layer "In2.Cu")
		(net "M_C_CPU1_SB_DQ<25>")
	)
	(arc
		(start 85.007958 -289.79876)
		(mid 85.290914 -289.722583)
		(end 85.57387 -289.79876)
		(width 0.0889)
		(layer "In2.Cu")
		(net "M_C_CPU1_SB_DQ<25>")
	)
	(arc
		(start 80.874108 -289.79876)
		(mid 81.061052 -289.849015)
		(end 81.247996 -289.79876)
		(width 0.0889)
		(layer "In2.Cu")
		(net "M_C_CPU1_SB_DQ<25>")
	)
	(arc
		(start 88.768174 -289.79876)
		(mid 89.05113 -289.722583)
		(end 89.334086 -289.79876)
		(width 0.0889)
		(layer "In2.Cu")
		(net "M_C_CPU1_SB_DQ<25>")
	)
	(arc
		(start 87.82812 -289.79876)
		(mid 88.111076 -289.722583)
		(end 88.394032 -289.79876)
		(width 0.0889)
		(layer "In2.Cu")
		(net "M_C_CPU1_SB_DQ<25>")
	)
	(arc
		(start 93.46819 -289.79876)
		(mid 93.751146 -289.722583)
		(end 94.034102 -289.79876)
		(width 0.0889)
		(layer "In2.Cu")
		(net "M_C_CPU1_SB_DQ<25>")
	)
	(arc
		(start 87.46236 -289.803586)
		(mid 87.645868 -289.84908)
		(end 87.82812 -289.79876)
		(width 0.0889)
		(layer "In2.Cu")
		(net "M_C_CPU1_SB_DQ<25>")
	)
	(arc
		(start 95.348044 -289.79876)
		(mid 95.59564 -289.723582)
		(end 95.85071 -289.76701)
		(width 0.0889)
		(layer "In2.Cu")
		(net "M_C_CPU1_SB_DQ<25>")
	)
	(arc
		(start 94.034102 -289.79876)
		(mid 94.221046 -289.849015)
		(end 94.40799 -289.79876)
		(width 0.0889)
		(layer "In2.Cu")
		(net "M_C_CPU1_SB_DQ<25>")
	)
	(arc
		(start 90.273886 -289.79876)
		(mid 90.456137 -289.84911)
		(end 90.639646 -289.803586)
		(width 0.0889)
		(layer "In2.Cu")
		(net "M_C_CPU1_SB_DQ<25>")
	)
	(arc
		(start 84.63407 -289.79876)
		(mid 84.821014 -289.849015)
		(end 85.007958 -289.79876)
		(width 0.0889)
		(layer "In2.Cu")
		(net "M_C_CPU1_SB_DQ<25>")
	)
	(arc
		(start 89.707974 -289.79876)
		(mid 89.99093 -289.722583)
		(end 90.273886 -289.79876)
		(width 0.0889)
		(layer "In2.Cu")
		(net "M_C_CPU1_SB_DQ<25>")
	)
	(arc
		(start 85.948012 -289.79876)
		(mid 86.230968 -289.722583)
		(end 86.513924 -289.79876)
		(width 0.0889)
		(layer "In2.Cu")
		(net "M_C_CPU1_SB_DQ<25>")
	)
	(arc
		(start 89.334086 -289.79876)
		(mid 89.52103 -289.849015)
		(end 89.707974 -289.79876)
		(width 0.0889)
		(layer "In2.Cu")
		(net "M_C_CPU1_SB_DQ<25>")
	)
	(arc
		(start 84.068158 -289.79876)
		(mid 84.351114 -289.722583)
		(end 84.63407 -289.79876)
		(width 0.0889)
		(layer "In2.Cu")
		(net "M_C_CPU1_SB_DQ<25>")
	)
	(arc
		(start 80.257396 -289.832034)
		(mid 80.560788 -289.723403)
		(end 80.874108 -289.79876)
		(width 0.0889)
		(layer "In2.Cu")
		(net "M_C_CPU1_SB_DQ<25>")
	)
	(arc
		(start 82.762344 -289.803586)
		(mid 82.945852 -289.84908)
		(end 83.128104 -289.79876)
		(width 0.0889)
		(layer "In2.Cu")
		(net "M_C_CPU1_SB_DQ<25>")
	)
	(arc
		(start 86.513924 -289.79876)
		(mid 86.696175 -289.84911)
		(end 86.879684 -289.803586)
		(width 0.0889)
		(layer "In2.Cu")
		(net "M_C_CPU1_SB_DQ<25>")
	)
	(arc
		(start 91.588082 -289.79876)
		(mid 91.871038 -289.722583)
		(end 92.153994 -289.79876)
		(width 0.0889)
		(layer "In2.Cu")
		(net "M_C_CPU1_SB_DQ<25>")
	)
	(arc
		(start 83.128104 -289.79876)
		(mid 83.41106 -289.722583)
		(end 83.694016 -289.79876)
		(width 0.0889)
		(layer "In2.Cu")
		(net "M_C_CPU1_SB_DQ<25>")
	)
	(arc
		(start 93.10243 -289.803586)
		(mid 93.285938 -289.84908)
		(end 93.46819 -289.79876)
		(width 0.0889)
		(layer "In2.Cu")
		(net "M_C_CPU1_SB_DQ<25>")
	)
	(arc
		(start 94.973902 -289.79876)
		(mid 95.156153 -289.84911)
		(end 95.339662 -289.803586)
		(width 0.0889)
		(layer "In2.Cu")
		(net "M_C_CPU1_SB_DQ<25>")
	)
	(segment
		(start 95.157798 -288.400236)
		(end 94.690946 -288.666174)
		(width 0.10668)
		(layer "F.Cu")
		(net "M_C_CPU1_SB_DQ<24>")
	)
	(segment
		(start 57.159906 -309.960518)
		(end 58.010044 -309.11038)
		(width 0.14478)
		(layer "In2.Cu")
		(net "M_C_CPU1_SB_DQ<24>")
	)
	(segment
		(start 90.74404 -288.988754)
		(end 90.752422 -288.99358)
		(width 0.0889)
		(layer "In2.Cu")
		(net "M_C_CPU1_SB_DQ<24>")
	)
	(segment
		(start 70.426326 -301.834804)
		(end 70.426326 -301.60468)
		(width 0.14478)
		(layer "In2.Cu")
		(net "M_C_CPU1_SB_DQ<24>")
	)
	(segment
		(start 49.641506 -309.960518)
		(end 50.19802 -309.404004)
		(width 0.14478)
		(layer "In2.Cu")
		(net "M_C_CPU1_SB_DQ<24>")
	)
	(segment
		(start 58.010044 -309.11038)
		(end 63.332868 -309.11038)
		(width 0.14478)
		(layer "In2.Cu")
		(net "M_C_CPU1_SB_DQ<24>")
	)
	(segment
		(start 72.393556 -299.63745)
		(end 72.62368 -299.63745)
		(width 0.14478)
		(layer "In2.Cu")
		(net "M_C_CPU1_SB_DQ<24>")
	)
	(segment
		(start 44.340018 -309.535322)
		(end 44.765214 -309.960518)
		(width 0.14478)
		(layer "In2.Cu")
		(net "M_C_CPU1_SB_DQ<24>")
	)
	(segment
		(start 76.745846 -291.180266)
		(end 76.745846 -290.616894)
		(width 0.0889)
		(layer "In2.Cu")
		(net "M_C_CPU1_SB_DQ<24>")
	)
	(segment
		(start 72.787002 -299.474128)
		(end 72.787002 -299.244004)
		(width 0.14478)
		(layer "In2.Cu")
		(net "M_C_CPU1_SB_DQ<24>")
	)
	(segment
		(start 72.526652 -298.426886)
		(end 72.756776 -298.426886)
		(width 0.14478)
		(layer "In2.Cu")
		(net "M_C_CPU1_SB_DQ<24>")
	)
	(segment
		(start 71.576438 -299.3771)
		(end 71.73976 -299.213778)
		(width 0.14478)
		(layer "In2.Cu")
		(net "M_C_CPU1_SB_DQ<24>")
	)
	(segment
		(start 69.609208 -301.574454)
		(end 70.03288 -301.998126)
		(width 0.14478)
		(layer "In2.Cu")
		(net "M_C_CPU1_SB_DQ<24>")
	)
	(segment
		(start 85.10397 -288.988754)
		(end 85.112352 -288.99358)
		(width 0.0889)
		(layer "In2.Cu")
		(net "M_C_CPU1_SB_DQ<24>")
	)
	(segment
		(start 50.948844 -309.11038)
		(end 53.018436 -309.11038)
		(width 0.14478)
		(layer "In2.Cu")
		(net "M_C_CPU1_SB_DQ<24>")
	)
	(segment
		(start 50.19802 -309.404004)
		(end 50.65522 -309.404004)
		(width 0.14478)
		(layer "In2.Cu")
		(net "M_C_CPU1_SB_DQ<24>")
	)
	(segment
		(start 72.00011 -300.030896)
		(end 71.576438 -299.607224)
		(width 0.14478)
		(layer "In2.Cu")
		(net "M_C_CPU1_SB_DQ<24>")
	)
	(segment
		(start 73.150222 -297.803316)
		(end 74.249026 -296.704512)
		(width 0.14478)
		(layer "In2.Cu")
		(net "M_C_CPU1_SB_DQ<24>")
	)
	(segment
		(start 69.146166 -301.807372)
		(end 69.379084 -301.574454)
		(width 0.14478)
		(layer "In2.Cu")
		(net "M_C_CPU1_SB_DQ<24>")
	)
	(segment
		(start 78.61935 -289.313366)
		(end 78.873096 -289.05962)
		(width 0.0889)
		(layer "In2.Cu")
		(net "M_C_CPU1_SB_DQ<24>")
	)
	(segment
		(start 71.182992 -300.00067)
		(end 71.606664 -300.424342)
		(width 0.14478)
		(layer "In2.Cu")
		(net "M_C_CPU1_SB_DQ<24>")
	)
	(segment
		(start 73.180448 -298.850558)
		(end 73.410572 -298.850558)
		(width 0.14478)
		(layer "In2.Cu")
		(net "M_C_CPU1_SB_DQ<24>")
	)
	(segment
		(start 94.537022 -288.931604)
		(end 94.690946 -288.666174)
		(width 0.0889)
		(layer "In2.Cu")
		(net "M_C_CPU1_SB_DQ<24>")
	)
	(segment
		(start 73.573894 -298.687236)
		(end 73.573894 -298.457112)
		(width 0.14478)
		(layer "In2.Cu")
		(net "M_C_CPU1_SB_DQ<24>")
	)
	(segment
		(start 70.002654 -300.950884)
		(end 70.165976 -300.787562)
		(width 0.14478)
		(layer "In2.Cu")
		(net "M_C_CPU1_SB_DQ<24>")
	)
	(segment
		(start 63.332868 -309.11038)
		(end 69.63918 -302.804068)
		(width 0.14478)
		(layer "In2.Cu")
		(net "M_C_CPU1_SB_DQ<24>")
	)
	(segment
		(start 72.62368 -299.63745)
		(end 72.787002 -299.474128)
		(width 0.14478)
		(layer "In2.Cu")
		(net "M_C_CPU1_SB_DQ<24>")
	)
	(segment
		(start 70.819772 -301.211234)
		(end 71.049896 -301.211234)
		(width 0.14478)
		(layer "In2.Cu")
		(net "M_C_CPU1_SB_DQ<24>")
	)
	(segment
		(start 70.426326 -301.60468)
		(end 70.002654 -301.181008)
		(width 0.14478)
		(layer "In2.Cu")
		(net "M_C_CPU1_SB_DQ<24>")
	)
	(segment
		(start 73.410572 -298.850558)
		(end 73.573894 -298.687236)
		(width 0.14478)
		(layer "In2.Cu")
		(net "M_C_CPU1_SB_DQ<24>")
	)
	(segment
		(start 80.769714 -288.99358)
		(end 80.778096 -288.988754)
		(width 0.0889)
		(layer "In2.Cu")
		(net "M_C_CPU1_SB_DQ<24>")
	)
	(segment
		(start 84.529676 -288.99358)
		(end 84.538058 -288.988754)
		(width 0.0889)
		(layer "In2.Cu")
		(net "M_C_CPU1_SB_DQ<24>")
	)
	(segment
		(start 71.213218 -300.817788)
		(end 70.789546 -300.394116)
		(width 0.14478)
		(layer "In2.Cu")
		(net "M_C_CPU1_SB_DQ<24>")
	)
	(segment
		(start 75.935586 -291.990526)
		(end 76.745846 -291.180266)
		(width 0.0889)
		(layer "In2.Cu")
		(net "M_C_CPU1_SB_DQ<24>")
	)
	(segment
		(start 72.756776 -298.426886)
		(end 73.180448 -298.850558)
		(width 0.14478)
		(layer "In2.Cu")
		(net "M_C_CPU1_SB_DQ<24>")
	)
	(segment
		(start 72.00011 -300.26102)
		(end 72.00011 -300.030896)
		(width 0.14478)
		(layer "In2.Cu")
		(net "M_C_CPU1_SB_DQ<24>")
	)
	(segment
		(start 70.789546 -300.394116)
		(end 70.789546 -300.163992)
		(width 0.14478)
		(layer "In2.Cu")
		(net "M_C_CPU1_SB_DQ<24>")
	)
	(segment
		(start 69.63918 -302.804068)
		(end 69.63918 -302.573944)
		(width 0.14478)
		(layer "In2.Cu")
		(net "M_C_CPU1_SB_DQ<24>")
	)
	(segment
		(start 69.379084 -301.574454)
		(end 69.609208 -301.574454)
		(width 0.14478)
		(layer "In2.Cu")
		(net "M_C_CPU1_SB_DQ<24>")
	)
	(segment
		(start 78.049374 -289.313366)
		(end 78.61935 -289.313366)
		(width 0.0889)
		(layer "In2.Cu")
		(net "M_C_CPU1_SB_DQ<24>")
	)
	(segment
		(start 74.249026 -296.704512)
		(end 74.249026 -293.677086)
		(width 0.14478)
		(layer "In2.Cu")
		(net "M_C_CPU1_SB_DQ<24>")
	)
	(segment
		(start 71.049896 -301.211234)
		(end 71.213218 -301.047912)
		(width 0.14478)
		(layer "In2.Cu")
		(net "M_C_CPU1_SB_DQ<24>")
	)
	(segment
		(start 73.573894 -298.457112)
		(end 73.150222 -298.03344)
		(width 0.14478)
		(layer "In2.Cu")
		(net "M_C_CPU1_SB_DQ<24>")
	)
	(segment
		(start 93.929708 -288.99358)
		(end 93.93809 -288.988754)
		(width 0.0889)
		(layer "In2.Cu")
		(net "M_C_CPU1_SB_DQ<24>")
	)
	(segment
		(start 89.229692 -288.99358)
		(end 89.238074 -288.988754)
		(width 0.0889)
		(layer "In2.Cu")
		(net "M_C_CPU1_SB_DQ<24>")
	)
	(segment
		(start 86.044024 -288.988754)
		(end 86.052406 -288.99358)
		(width 0.0889)
		(layer "In2.Cu")
		(net "M_C_CPU1_SB_DQ<24>")
	)
	(segment
		(start 70.263004 -301.998126)
		(end 70.426326 -301.834804)
		(width 0.14478)
		(layer "In2.Cu")
		(net "M_C_CPU1_SB_DQ<24>")
	)
	(segment
		(start 83.589622 -288.99358)
		(end 83.598004 -288.988754)
		(width 0.0889)
		(layer "In2.Cu")
		(net "M_C_CPU1_SB_DQ<24>")
	)
	(segment
		(start 71.576438 -299.607224)
		(end 71.576438 -299.3771)
		(width 0.14478)
		(layer "In2.Cu")
		(net "M_C_CPU1_SB_DQ<24>")
	)
	(segment
		(start 70.952868 -300.00067)
		(end 71.182992 -300.00067)
		(width 0.14478)
		(layer "In2.Cu")
		(net "M_C_CPU1_SB_DQ<24>")
	)
	(segment
		(start 70.789546 -300.163992)
		(end 70.952868 -300.00067)
		(width 0.14478)
		(layer "In2.Cu")
		(net "M_C_CPU1_SB_DQ<24>")
	)
	(segment
		(start 53.018436 -309.11038)
		(end 53.868574 -309.960518)
		(width 0.14478)
		(layer "In2.Cu")
		(net "M_C_CPU1_SB_DQ<24>")
	)
	(segment
		(start 50.65522 -309.404004)
		(end 50.948844 -309.11038)
		(width 0.14478)
		(layer "In2.Cu")
		(net "M_C_CPU1_SB_DQ<24>")
	)
	(segment
		(start 69.63918 -302.573944)
		(end 69.146166 -302.08093)
		(width 0.14478)
		(layer "In2.Cu")
		(net "M_C_CPU1_SB_DQ<24>")
	)
	(segment
		(start 78.95336 -289.026346)
		(end 79.626968 -289.026346)
		(width 0.0889)
		(layer "In2.Cu")
		(net "M_C_CPU1_SB_DQ<24>")
	)
	(segment
		(start 88.289638 -288.99358)
		(end 88.29802 -288.988754)
		(width 0.0889)
		(layer "In2.Cu")
		(net "M_C_CPU1_SB_DQ<24>")
	)
	(segment
		(start 71.606664 -300.424342)
		(end 71.836788 -300.424342)
		(width 0.14478)
		(layer "In2.Cu")
		(net "M_C_CPU1_SB_DQ<24>")
	)
	(segment
		(start 53.868574 -309.960518)
		(end 57.159906 -309.960518)
		(width 0.14478)
		(layer "In2.Cu")
		(net "M_C_CPU1_SB_DQ<24>")
	)
	(segment
		(start 71.213218 -301.047912)
		(end 71.213218 -300.817788)
		(width 0.14478)
		(layer "In2.Cu")
		(net "M_C_CPU1_SB_DQ<24>")
	)
	(segment
		(start 74.249026 -293.677086)
		(end 75.935586 -291.990526)
		(width 0.14478)
		(layer "In2.Cu")
		(net "M_C_CPU1_SB_DQ<24>")
	)
	(segment
		(start 73.150222 -298.03344)
		(end 73.150222 -297.803316)
		(width 0.14478)
		(layer "In2.Cu")
		(net "M_C_CPU1_SB_DQ<24>")
	)
	(segment
		(start 70.165976 -300.787562)
		(end 70.3961 -300.787562)
		(width 0.14478)
		(layer "In2.Cu")
		(net "M_C_CPU1_SB_DQ<24>")
	)
	(segment
		(start 69.146166 -302.08093)
		(end 69.146166 -301.807372)
		(width 0.14478)
		(layer "In2.Cu")
		(net "M_C_CPU1_SB_DQ<24>")
	)
	(segment
		(start 71.836788 -300.424342)
		(end 72.00011 -300.26102)
		(width 0.14478)
		(layer "In2.Cu")
		(net "M_C_CPU1_SB_DQ<24>")
	)
	(segment
		(start 76.745846 -290.616894)
		(end 78.049374 -289.313366)
		(width 0.0889)
		(layer "In2.Cu")
		(net "M_C_CPU1_SB_DQ<24>")
	)
	(segment
		(start 92.989654 -288.99358)
		(end 92.998036 -288.988754)
		(width 0.0889)
		(layer "In2.Cu")
		(net "M_C_CPU1_SB_DQ<24>")
	)
	(segment
		(start 81.344008 -288.988754)
		(end 81.35239 -288.99358)
		(width 0.0889)
		(layer "In2.Cu")
		(net "M_C_CPU1_SB_DQ<24>")
	)
	(segment
		(start 72.36333 -298.590208)
		(end 72.526652 -298.426886)
		(width 0.14478)
		(layer "In2.Cu")
		(net "M_C_CPU1_SB_DQ<24>")
	)
	(segment
		(start 44.765214 -309.960518)
		(end 49.641506 -309.960518)
		(width 0.14478)
		(layer "In2.Cu")
		(net "M_C_CPU1_SB_DQ<24>")
	)
	(segment
		(start 70.3961 -300.787562)
		(end 70.819772 -301.211234)
		(width 0.14478)
		(layer "In2.Cu")
		(net "M_C_CPU1_SB_DQ<24>")
	)
	(segment
		(start 72.787002 -299.244004)
		(end 72.36333 -298.820332)
		(width 0.14478)
		(layer "In2.Cu")
		(net "M_C_CPU1_SB_DQ<24>")
	)
	(segment
		(start 72.36333 -298.820332)
		(end 72.36333 -298.590208)
		(width 0.14478)
		(layer "In2.Cu")
		(net "M_C_CPU1_SB_DQ<24>")
	)
	(segment
		(start 70.002654 -301.181008)
		(end 70.002654 -300.950884)
		(width 0.14478)
		(layer "In2.Cu")
		(net "M_C_CPU1_SB_DQ<24>")
	)
	(segment
		(start 70.03288 -301.998126)
		(end 70.263004 -301.998126)
		(width 0.14478)
		(layer "In2.Cu")
		(net "M_C_CPU1_SB_DQ<24>")
	)
	(segment
		(start 71.73976 -299.213778)
		(end 71.969884 -299.213778)
		(width 0.14478)
		(layer "In2.Cu")
		(net "M_C_CPU1_SB_DQ<24>")
	)
	(segment
		(start 94.44101 -288.957004)
		(end 94.537022 -288.931604)
		(width 0.0889)
		(layer "In2.Cu")
		(net "M_C_CPU1_SB_DQ<24>")
	)
	(segment
		(start 89.803986 -288.988754)
		(end 89.812368 -288.99358)
		(width 0.0889)
		(layer "In2.Cu")
		(net "M_C_CPU1_SB_DQ<24>")
	)
	(segment
		(start 71.969884 -299.213778)
		(end 72.393556 -299.63745)
		(width 0.14478)
		(layer "In2.Cu")
		(net "M_C_CPU1_SB_DQ<24>")
	)
	(arc
		(start 81.71815 -288.988754)
		(mid 82.001106 -288.912577)
		(end 82.284062 -288.988754)
		(width 0.0889)
		(layer "In2.Cu")
		(net "M_C_CPU1_SB_DQ<24>")
	)
	(arc
		(start 92.057982 -288.988754)
		(mid 92.340938 -288.912577)
		(end 92.623894 -288.988754)
		(width 0.0889)
		(layer "In2.Cu")
		(net "M_C_CPU1_SB_DQ<24>")
	)
	(arc
		(start 92.623894 -288.988754)
		(mid 92.806145 -289.039104)
		(end 92.989654 -288.99358)
		(width 0.0889)
		(layer "In2.Cu")
		(net "M_C_CPU1_SB_DQ<24>")
	)
	(arc
		(start 78.873096 -289.05962)
		(mid 78.909907 -289.03496)
		(end 78.95336 -289.026346)
		(width 0.0889)
		(layer "In2.Cu")
		(net "M_C_CPU1_SB_DQ<24>")
	)
	(arc
		(start 79.626968 -289.026346)
		(mid 79.753658 -289.011806)
		(end 79.873856 -288.969196)
		(width 0.0889)
		(layer "In2.Cu")
		(net "M_C_CPU1_SB_DQ<24>")
	)
	(arc
		(start 90.178128 -288.988754)
		(mid 90.461084 -288.912577)
		(end 90.74404 -288.988754)
		(width 0.0889)
		(layer "In2.Cu")
		(net "M_C_CPU1_SB_DQ<24>")
	)
	(arc
		(start 86.418166 -288.988754)
		(mid 86.701122 -288.912577)
		(end 86.984078 -288.988754)
		(width 0.0889)
		(layer "In2.Cu")
		(net "M_C_CPU1_SB_DQ<24>")
	)
	(arc
		(start 79.873856 -288.969196)
		(mid 80.141339 -288.912774)
		(end 80.403954 -288.988754)
		(width 0.0889)
		(layer "In2.Cu")
		(net "M_C_CPU1_SB_DQ<24>")
	)
	(arc
		(start 87.357966 -288.988754)
		(mid 87.640922 -288.912577)
		(end 87.923878 -288.988754)
		(width 0.0889)
		(layer "In2.Cu")
		(net "M_C_CPU1_SB_DQ<24>")
	)
	(arc
		(start 84.538058 -288.988754)
		(mid 84.821014 -288.912577)
		(end 85.10397 -288.988754)
		(width 0.0889)
		(layer "In2.Cu")
		(net "M_C_CPU1_SB_DQ<24>")
	)
	(arc
		(start 83.598004 -288.988754)
		(mid 83.88096 -288.912577)
		(end 84.163916 -288.988754)
		(width 0.0889)
		(layer "In2.Cu")
		(net "M_C_CPU1_SB_DQ<24>")
	)
	(arc
		(start 91.684094 -288.988754)
		(mid 91.871038 -289.039009)
		(end 92.057982 -288.988754)
		(width 0.0889)
		(layer "In2.Cu")
		(net "M_C_CPU1_SB_DQ<24>")
	)
	(arc
		(start 84.163916 -288.988754)
		(mid 84.346167 -289.039104)
		(end 84.529676 -288.99358)
		(width 0.0889)
		(layer "In2.Cu")
		(net "M_C_CPU1_SB_DQ<24>")
	)
	(arc
		(start 88.29802 -288.988754)
		(mid 88.580976 -288.912577)
		(end 88.863932 -288.988754)
		(width 0.0889)
		(layer "In2.Cu")
		(net "M_C_CPU1_SB_DQ<24>")
	)
	(arc
		(start 83.223862 -288.988754)
		(mid 83.406113 -289.039104)
		(end 83.589622 -288.99358)
		(width 0.0889)
		(layer "In2.Cu")
		(net "M_C_CPU1_SB_DQ<24>")
	)
	(arc
		(start 92.998036 -288.988754)
		(mid 93.280992 -288.912577)
		(end 93.563948 -288.988754)
		(width 0.0889)
		(layer "In2.Cu")
		(net "M_C_CPU1_SB_DQ<24>")
	)
	(arc
		(start 85.478112 -288.988754)
		(mid 85.761068 -288.912577)
		(end 86.044024 -288.988754)
		(width 0.0889)
		(layer "In2.Cu")
		(net "M_C_CPU1_SB_DQ<24>")
	)
	(arc
		(start 82.284062 -288.988754)
		(mid 82.471006 -289.039009)
		(end 82.65795 -288.988754)
		(width 0.0889)
		(layer "In2.Cu")
		(net "M_C_CPU1_SB_DQ<24>")
	)
	(arc
		(start 86.984078 -288.988754)
		(mid 87.171022 -289.039009)
		(end 87.357966 -288.988754)
		(width 0.0889)
		(layer "In2.Cu")
		(net "M_C_CPU1_SB_DQ<24>")
	)
	(arc
		(start 81.35239 -288.99358)
		(mid 81.535898 -289.039074)
		(end 81.71815 -288.988754)
		(width 0.0889)
		(layer "In2.Cu")
		(net "M_C_CPU1_SB_DQ<24>")
	)
	(arc
		(start 86.052406 -288.99358)
		(mid 86.235914 -289.039074)
		(end 86.418166 -288.988754)
		(width 0.0889)
		(layer "In2.Cu")
		(net "M_C_CPU1_SB_DQ<24>")
	)
	(arc
		(start 89.238074 -288.988754)
		(mid 89.52103 -288.912577)
		(end 89.803986 -288.988754)
		(width 0.0889)
		(layer "In2.Cu")
		(net "M_C_CPU1_SB_DQ<24>")
	)
	(arc
		(start 89.812368 -288.99358)
		(mid 89.995876 -289.039074)
		(end 90.178128 -288.988754)
		(width 0.0889)
		(layer "In2.Cu")
		(net "M_C_CPU1_SB_DQ<24>")
	)
	(arc
		(start 80.403954 -288.988754)
		(mid 80.586205 -289.039104)
		(end 80.769714 -288.99358)
		(width 0.0889)
		(layer "In2.Cu")
		(net "M_C_CPU1_SB_DQ<24>")
	)
	(arc
		(start 82.65795 -288.988754)
		(mid 82.940906 -288.912577)
		(end 83.223862 -288.988754)
		(width 0.0889)
		(layer "In2.Cu")
		(net "M_C_CPU1_SB_DQ<24>")
	)
	(arc
		(start 91.118182 -288.988754)
		(mid 91.401138 -288.912577)
		(end 91.684094 -288.988754)
		(width 0.0889)
		(layer "In2.Cu")
		(net "M_C_CPU1_SB_DQ<24>")
	)
	(arc
		(start 90.752422 -288.99358)
		(mid 90.93593 -289.039074)
		(end 91.118182 -288.988754)
		(width 0.0889)
		(layer "In2.Cu")
		(net "M_C_CPU1_SB_DQ<24>")
	)
	(arc
		(start 87.923878 -288.988754)
		(mid 88.106129 -289.039104)
		(end 88.289638 -288.99358)
		(width 0.0889)
		(layer "In2.Cu")
		(net "M_C_CPU1_SB_DQ<24>")
	)
	(arc
		(start 93.563948 -288.988754)
		(mid 93.746199 -289.039104)
		(end 93.929708 -288.99358)
		(width 0.0889)
		(layer "In2.Cu")
		(net "M_C_CPU1_SB_DQ<24>")
	)
	(arc
		(start 80.778096 -288.988754)
		(mid 81.061052 -288.912577)
		(end 81.344008 -288.988754)
		(width 0.0889)
		(layer "In2.Cu")
		(net "M_C_CPU1_SB_DQ<24>")
	)
	(arc
		(start 88.863932 -288.988754)
		(mid 89.046183 -289.039104)
		(end 89.229692 -288.99358)
		(width 0.0889)
		(layer "In2.Cu")
		(net "M_C_CPU1_SB_DQ<24>")
	)
	(arc
		(start 85.112352 -288.99358)
		(mid 85.29586 -289.039074)
		(end 85.478112 -288.988754)
		(width 0.0889)
		(layer "In2.Cu")
		(net "M_C_CPU1_SB_DQ<24>")
	)
	(arc
		(start 93.93809 -288.988754)
		(mid 94.185803 -288.913534)
		(end 94.44101 -288.957004)
		(width 0.0889)
		(layer "In2.Cu")
		(net "M_C_CPU1_SB_DQ<24>")
	)
	(segment
		(start 96.097852 -288.400236)
		(end 95.631 -288.666174)
		(width 0.10668)
		(layer "F.Cu")
		(net "M_C_CPU1_SB_DQ<23>")
	)
	(segment
		(start 88.289638 -288.339022)
		(end 88.29802 -288.343848)
		(width 0.0889)
		(layer "In2.Cu")
		(net "M_C_CPU1_SB_DQ<23>")
	)
	(segment
		(start 52.830476 -308.421786)
		(end 53.398166 -308.65699)
		(width 0.14478)
		(layer "In2.Cu")
		(net "M_C_CPU1_SB_DQ<23>")
	)
	(segment
		(start 78.886304 -288.33699)
		(end 78.897988 -288.343848)
		(width 0.0889)
		(layer "In2.Cu")
		(net "M_C_CPU1_SB_DQ<23>")
	)
	(segment
		(start 51.754278 -308.260242)
		(end 52.01793 -308.260242)
		(width 0.14478)
		(layer "In2.Cu")
		(net "M_C_CPU1_SB_DQ<23>")
	)
	(segment
		(start 73.692766 -293.42715)
		(end 75.949302 -291.170614)
		(width 0.14478)
		(layer "In2.Cu")
		(net "M_C_CPU1_SB_DQ<23>")
	)
	(segment
		(start 48.732694 -309.11038)
		(end 51.116484 -308.387242)
		(width 0.14478)
		(layer "In2.Cu")
		(net "M_C_CPU1_SB_DQ<23>")
	)
	(segment
		(start 62.929516 -308.077616)
		(end 63.486538 -307.814218)
		(width 0.14478)
		(layer "In2.Cu")
		(net "M_C_CPU1_SB_DQ<23>")
	)
	(segment
		(start 84.529676 -288.339022)
		(end 84.538058 -288.343848)
		(width 0.0889)
		(layer "In2.Cu")
		(net "M_C_CPU1_SB_DQ<23>")
	)
	(segment
		(start 73.692766 -296.473626)
		(end 73.692766 -293.42715)
		(width 0.14478)
		(layer "In2.Cu")
		(net "M_C_CPU1_SB_DQ<23>")
	)
	(segment
		(start 53.398166 -308.65699)
		(end 54.246526 -309.11038)
		(width 0.14478)
		(layer "In2.Cu")
		(net "M_C_CPU1_SB_DQ<23>")
	)
	(segment
		(start 57.377076 -308.71287)
		(end 58.030364 -308.51475)
		(width 0.14478)
		(layer "In2.Cu")
		(net "M_C_CPU1_SB_DQ<23>")
	)
	(segment
		(start 92.989654 -288.339022)
		(end 92.998036 -288.343848)
		(width 0.0889)
		(layer "In2.Cu")
		(net "M_C_CPU1_SB_DQ<23>")
	)
	(segment
		(start 86.044024 -288.343848)
		(end 86.052406 -288.339022)
		(width 0.0889)
		(layer "In2.Cu")
		(net "M_C_CPU1_SB_DQ<23>")
	)
	(segment
		(start 79.82966 -288.339022)
		(end 79.838042 -288.343848)
		(width 0.0889)
		(layer "In2.Cu")
		(net "M_C_CPU1_SB_DQ<23>")
	)
	(segment
		(start 93.929708 -288.339022)
		(end 93.93809 -288.343848)
		(width 0.0889)
		(layer "In2.Cu")
		(net "M_C_CPU1_SB_DQ<23>")
	)
	(segment
		(start 51.116484 -308.387242)
		(end 51.754278 -308.260242)
		(width 0.14478)
		(layer "In2.Cu")
		(net "M_C_CPU1_SB_DQ<23>")
	)
	(segment
		(start 75.949302 -291.170614)
		(end 76.484226 -290.63569)
		(width 0.0889)
		(layer "In2.Cu")
		(net "M_C_CPU1_SB_DQ<23>")
	)
	(segment
		(start 68.589906 -301.576486)
		(end 73.692766 -296.473626)
		(width 0.14478)
		(layer "In2.Cu")
		(net "M_C_CPU1_SB_DQ<23>")
	)
	(segment
		(start 52.01793 -308.260242)
		(end 52.830476 -308.421786)
		(width 0.14478)
		(layer "In2.Cu")
		(net "M_C_CPU1_SB_DQ<23>")
	)
	(segment
		(start 95.785178 -288.400744)
		(end 95.631 -288.666174)
		(width 0.0889)
		(layer "In2.Cu")
		(net "M_C_CPU1_SB_DQ<23>")
	)
	(segment
		(start 94.504002 -288.343848)
		(end 94.512384 -288.339022)
		(width 0.0889)
		(layer "In2.Cu")
		(net "M_C_CPU1_SB_DQ<23>")
	)
	(segment
		(start 76.484226 -290.63569)
		(end 76.484226 -290.36518)
		(width 0.0889)
		(layer "In2.Cu")
		(net "M_C_CPU1_SB_DQ<23>")
	)
	(segment
		(start 40.23995 -308.685438)
		(end 40.664892 -309.11038)
		(width 0.14478)
		(layer "In2.Cu")
		(net "M_C_CPU1_SB_DQ<23>")
	)
	(segment
		(start 54.246526 -309.11038)
		(end 56.231028 -309.11038)
		(width 0.14478)
		(layer "In2.Cu")
		(net "M_C_CPU1_SB_DQ<23>")
	)
	(segment
		(start 90.74404 -288.343848)
		(end 90.752422 -288.339022)
		(width 0.0889)
		(layer "In2.Cu")
		(net "M_C_CPU1_SB_DQ<23>")
	)
	(segment
		(start 76.484226 -290.36518)
		(end 78.447138 -288.402268)
		(width 0.0889)
		(layer "In2.Cu")
		(net "M_C_CPU1_SB_DQ<23>")
	)
	(segment
		(start 95.76308 -288.317686)
		(end 95.785178 -288.400744)
		(width 0.0889)
		(layer "In2.Cu")
		(net "M_C_CPU1_SB_DQ<23>")
	)
	(segment
		(start 89.229692 -288.339022)
		(end 89.238074 -288.343848)
		(width 0.0889)
		(layer "In2.Cu")
		(net "M_C_CPU1_SB_DQ<23>")
	)
	(segment
		(start 85.10397 -288.343848)
		(end 85.112352 -288.339022)
		(width 0.0889)
		(layer "In2.Cu")
		(net "M_C_CPU1_SB_DQ<23>")
	)
	(segment
		(start 63.486538 -307.814218)
		(end 68.218304 -303.082452)
		(width 0.14478)
		(layer "In2.Cu")
		(net "M_C_CPU1_SB_DQ<23>")
	)
	(segment
		(start 68.589906 -302.185324)
		(end 68.589906 -301.576486)
		(width 0.14478)
		(layer "In2.Cu")
		(net "M_C_CPU1_SB_DQ<23>")
	)
	(segment
		(start 89.803986 -288.343848)
		(end 89.812368 -288.339022)
		(width 0.0889)
		(layer "In2.Cu")
		(net "M_C_CPU1_SB_DQ<23>")
	)
	(segment
		(start 81.344008 -288.343848)
		(end 81.35239 -288.339022)
		(width 0.0889)
		(layer "In2.Cu")
		(net "M_C_CPU1_SB_DQ<23>")
	)
	(segment
		(start 56.231028 -309.11038)
		(end 56.590184 -309.039006)
		(width 0.14478)
		(layer "In2.Cu")
		(net "M_C_CPU1_SB_DQ<23>")
	)
	(segment
		(start 95.444056 -288.343848)
		(end 95.452438 -288.339022)
		(width 0.0889)
		(layer "In2.Cu")
		(net "M_C_CPU1_SB_DQ<23>")
	)
	(segment
		(start 40.664892 -309.11038)
		(end 48.732694 -309.11038)
		(width 0.14478)
		(layer "In2.Cu")
		(net "M_C_CPU1_SB_DQ<23>")
	)
	(segment
		(start 56.590184 -309.039006)
		(end 57.377076 -308.71287)
		(width 0.14478)
		(layer "In2.Cu")
		(net "M_C_CPU1_SB_DQ<23>")
	)
	(segment
		(start 68.218304 -303.082452)
		(end 68.589906 -302.185324)
		(width 0.14478)
		(layer "In2.Cu")
		(net "M_C_CPU1_SB_DQ<23>")
	)
	(segment
		(start 80.769714 -288.339022)
		(end 80.778096 -288.343848)
		(width 0.0889)
		(layer "In2.Cu")
		(net "M_C_CPU1_SB_DQ<23>")
	)
	(segment
		(start 58.030364 -308.51475)
		(end 59.309508 -308.260242)
		(width 0.14478)
		(layer "In2.Cu")
		(net "M_C_CPU1_SB_DQ<23>")
	)
	(segment
		(start 61.077602 -308.260242)
		(end 62.929516 -308.077616)
		(width 0.14478)
		(layer "In2.Cu")
		(net "M_C_CPU1_SB_DQ<23>")
	)
	(segment
		(start 83.589622 -288.339022)
		(end 83.598004 -288.343848)
		(width 0.0889)
		(layer "In2.Cu")
		(net "M_C_CPU1_SB_DQ<23>")
	)
	(segment
		(start 59.309508 -308.260242)
		(end 61.077602 -308.260242)
		(width 0.14478)
		(layer "In2.Cu")
		(net "M_C_CPU1_SB_DQ<23>")
	)
	(arc
		(start 85.112352 -288.339022)
		(mid 85.29586 -288.293497)
		(end 85.478112 -288.343848)
		(width 0.0889)
		(layer "In2.Cu")
		(net "M_C_CPU1_SB_DQ<23>")
	)
	(arc
		(start 78.523592 -288.343848)
		(mid 78.70405 -288.293369)
		(end 78.886304 -288.33699)
		(width 0.0889)
		(layer "In2.Cu")
		(net "M_C_CPU1_SB_DQ<23>")
	)
	(arc
		(start 93.93809 -288.343848)
		(mid 94.221046 -288.420025)
		(end 94.504002 -288.343848)
		(width 0.0889)
		(layer "In2.Cu")
		(net "M_C_CPU1_SB_DQ<23>")
	)
	(arc
		(start 86.984078 -288.343848)
		(mid 87.171022 -288.293559)
		(end 87.357966 -288.343848)
		(width 0.0889)
		(layer "In2.Cu")
		(net "M_C_CPU1_SB_DQ<23>")
	)
	(arc
		(start 92.057982 -288.343848)
		(mid 92.340938 -288.420025)
		(end 92.623894 -288.343848)
		(width 0.0889)
		(layer "In2.Cu")
		(net "M_C_CPU1_SB_DQ<23>")
	)
	(arc
		(start 86.418166 -288.343848)
		(mid 86.701122 -288.420025)
		(end 86.984078 -288.343848)
		(width 0.0889)
		(layer "In2.Cu")
		(net "M_C_CPU1_SB_DQ<23>")
	)
	(arc
		(start 83.223862 -288.343848)
		(mid 83.406113 -288.293464)
		(end 83.589622 -288.339022)
		(width 0.0889)
		(layer "In2.Cu")
		(net "M_C_CPU1_SB_DQ<23>")
	)
	(arc
		(start 87.357966 -288.343848)
		(mid 87.640922 -288.420025)
		(end 87.923878 -288.343848)
		(width 0.0889)
		(layer "In2.Cu")
		(net "M_C_CPU1_SB_DQ<23>")
	)
	(arc
		(start 84.163916 -288.343848)
		(mid 84.346167 -288.293464)
		(end 84.529676 -288.339022)
		(width 0.0889)
		(layer "In2.Cu")
		(net "M_C_CPU1_SB_DQ<23>")
	)
	(arc
		(start 82.284062 -288.343848)
		(mid 82.471006 -288.293559)
		(end 82.65795 -288.343848)
		(width 0.0889)
		(layer "In2.Cu")
		(net "M_C_CPU1_SB_DQ<23>")
	)
	(arc
		(start 89.812368 -288.339022)
		(mid 89.995876 -288.293497)
		(end 90.178128 -288.343848)
		(width 0.0889)
		(layer "In2.Cu")
		(net "M_C_CPU1_SB_DQ<23>")
	)
	(arc
		(start 89.238074 -288.343848)
		(mid 89.52103 -288.420025)
		(end 89.803986 -288.343848)
		(width 0.0889)
		(layer "In2.Cu")
		(net "M_C_CPU1_SB_DQ<23>")
	)
	(arc
		(start 81.35239 -288.339022)
		(mid 81.535898 -288.293497)
		(end 81.71815 -288.343848)
		(width 0.0889)
		(layer "In2.Cu")
		(net "M_C_CPU1_SB_DQ<23>")
	)
	(arc
		(start 86.052406 -288.339022)
		(mid 86.235914 -288.293497)
		(end 86.418166 -288.343848)
		(width 0.0889)
		(layer "In2.Cu")
		(net "M_C_CPU1_SB_DQ<23>")
	)
	(arc
		(start 88.29802 -288.343848)
		(mid 88.580976 -288.420025)
		(end 88.863932 -288.343848)
		(width 0.0889)
		(layer "In2.Cu")
		(net "M_C_CPU1_SB_DQ<23>")
	)
	(arc
		(start 92.623894 -288.343848)
		(mid 92.806145 -288.293464)
		(end 92.989654 -288.339022)
		(width 0.0889)
		(layer "In2.Cu")
		(net "M_C_CPU1_SB_DQ<23>")
	)
	(arc
		(start 87.923878 -288.343848)
		(mid 88.106129 -288.293464)
		(end 88.289638 -288.339022)
		(width 0.0889)
		(layer "In2.Cu")
		(net "M_C_CPU1_SB_DQ<23>")
	)
	(arc
		(start 79.838042 -288.343848)
		(mid 80.120998 -288.420025)
		(end 80.403954 -288.343848)
		(width 0.0889)
		(layer "In2.Cu")
		(net "M_C_CPU1_SB_DQ<23>")
	)
	(arc
		(start 93.563948 -288.343848)
		(mid 93.746199 -288.293464)
		(end 93.929708 -288.339022)
		(width 0.0889)
		(layer "In2.Cu")
		(net "M_C_CPU1_SB_DQ<23>")
	)
	(arc
		(start 94.512384 -288.339022)
		(mid 94.695892 -288.293497)
		(end 94.878144 -288.343848)
		(width 0.0889)
		(layer "In2.Cu")
		(net "M_C_CPU1_SB_DQ<23>")
	)
	(arc
		(start 91.118182 -288.343848)
		(mid 91.401138 -288.420025)
		(end 91.684094 -288.343848)
		(width 0.0889)
		(layer "In2.Cu")
		(net "M_C_CPU1_SB_DQ<23>")
	)
	(arc
		(start 80.778096 -288.343848)
		(mid 81.061052 -288.420025)
		(end 81.344008 -288.343848)
		(width 0.0889)
		(layer "In2.Cu")
		(net "M_C_CPU1_SB_DQ<23>")
	)
	(arc
		(start 78.897988 -288.343848)
		(mid 79.180944 -288.420025)
		(end 79.4639 -288.343848)
		(width 0.0889)
		(layer "In2.Cu")
		(net "M_C_CPU1_SB_DQ<23>")
	)
	(arc
		(start 78.447138 -288.402268)
		(mid 78.483468 -288.370574)
		(end 78.523592 -288.343848)
		(width 0.0889)
		(layer "In2.Cu")
		(net "M_C_CPU1_SB_DQ<23>")
	)
	(arc
		(start 92.998036 -288.343848)
		(mid 93.280992 -288.420025)
		(end 93.563948 -288.343848)
		(width 0.0889)
		(layer "In2.Cu")
		(net "M_C_CPU1_SB_DQ<23>")
	)
	(arc
		(start 83.598004 -288.343848)
		(mid 83.88096 -288.420025)
		(end 84.163916 -288.343848)
		(width 0.0889)
		(layer "In2.Cu")
		(net "M_C_CPU1_SB_DQ<23>")
	)
	(arc
		(start 80.403954 -288.343848)
		(mid 80.586205 -288.293464)
		(end 80.769714 -288.339022)
		(width 0.0889)
		(layer "In2.Cu")
		(net "M_C_CPU1_SB_DQ<23>")
	)
	(arc
		(start 88.863932 -288.343848)
		(mid 89.046183 -288.293464)
		(end 89.229692 -288.339022)
		(width 0.0889)
		(layer "In2.Cu")
		(net "M_C_CPU1_SB_DQ<23>")
	)
	(arc
		(start 85.478112 -288.343848)
		(mid 85.761068 -288.420025)
		(end 86.044024 -288.343848)
		(width 0.0889)
		(layer "In2.Cu")
		(net "M_C_CPU1_SB_DQ<23>")
	)
	(arc
		(start 84.538058 -288.343848)
		(mid 84.821014 -288.420025)
		(end 85.10397 -288.343848)
		(width 0.0889)
		(layer "In2.Cu")
		(net "M_C_CPU1_SB_DQ<23>")
	)
	(arc
		(start 81.71815 -288.343848)
		(mid 82.001106 -288.420025)
		(end 82.284062 -288.343848)
		(width 0.0889)
		(layer "In2.Cu")
		(net "M_C_CPU1_SB_DQ<23>")
	)
	(arc
		(start 91.684094 -288.343848)
		(mid 91.871038 -288.293559)
		(end 92.057982 -288.343848)
		(width 0.0889)
		(layer "In2.Cu")
		(net "M_C_CPU1_SB_DQ<23>")
	)
	(arc
		(start 95.452438 -288.339022)
		(mid 95.605426 -288.294342)
		(end 95.76308 -288.317686)
		(width 0.0889)
		(layer "In2.Cu")
		(net "M_C_CPU1_SB_DQ<23>")
	)
	(arc
		(start 79.4639 -288.343848)
		(mid 79.646151 -288.293464)
		(end 79.82966 -288.339022)
		(width 0.0889)
		(layer "In2.Cu")
		(net "M_C_CPU1_SB_DQ<23>")
	)
	(arc
		(start 90.752422 -288.339022)
		(mid 90.93593 -288.293497)
		(end 91.118182 -288.343848)
		(width 0.0889)
		(layer "In2.Cu")
		(net "M_C_CPU1_SB_DQ<23>")
	)
	(arc
		(start 90.178128 -288.343848)
		(mid 90.461084 -288.420025)
		(end 90.74404 -288.343848)
		(width 0.0889)
		(layer "In2.Cu")
		(net "M_C_CPU1_SB_DQ<23>")
	)
	(arc
		(start 82.65795 -288.343848)
		(mid 82.940906 -288.420025)
		(end 83.223862 -288.343848)
		(width 0.0889)
		(layer "In2.Cu")
		(net "M_C_CPU1_SB_DQ<23>")
	)
	(arc
		(start 94.878144 -288.343848)
		(mid 95.1611 -288.420025)
		(end 95.444056 -288.343848)
		(width 0.0889)
		(layer "In2.Cu")
		(net "M_C_CPU1_SB_DQ<23>")
	)
	(segment
		(start 94.687898 -287.590484)
		(end 94.221046 -287.856422)
		(width 0.10668)
		(layer "F.Cu")
		(net "M_C_CPU1_SB_DQ<22>")
	)
	(segment
		(start 40.23995 -306.985416)
		(end 40.664892 -307.410358)
		(width 0.14478)
		(layer "In2.Cu")
		(net "M_C_CPU1_SB_DQ<22>")
	)
	(segment
		(start 42.117772 -307.224684)
		(end 42.303446 -307.410358)
		(width 0.14478)
		(layer "In2.Cu")
		(net "M_C_CPU1_SB_DQ<22>")
	)
	(segment
		(start 72.783446 -292.922198)
		(end 75.957176 -289.748468)
		(width 0.14478)
		(layer "In2.Cu")
		(net "M_C_CPU1_SB_DQ<22>")
	)
	(segment
		(start 79.935324 -287.533842)
		(end 79.955898 -287.522158)
		(width 0.0889)
		(layer "In2.Cu")
		(net "M_C_CPU1_SB_DQ<22>")
	)
	(segment
		(start 57.184798 -307.410358)
		(end 58.034936 -306.56022)
		(width 0.14478)
		(layer "In2.Cu")
		(net "M_C_CPU1_SB_DQ<22>")
	)
	(segment
		(start 40.664892 -307.410358)
		(end 41.551352 -307.410358)
		(width 0.14478)
		(layer "In2.Cu")
		(net "M_C_CPU1_SB_DQ<22>")
	)
	(segment
		(start 75.957176 -289.748468)
		(end 75.957176 -289.547554)
		(width 0.0889)
		(layer "In2.Cu")
		(net "M_C_CPU1_SB_DQ<22>")
	)
	(segment
		(start 93.094048 -287.533842)
		(end 93.10243 -287.529016)
		(width 0.0889)
		(layer "In2.Cu")
		(net "M_C_CPU1_SB_DQ<22>")
	)
	(segment
		(start 41.737026 -307.224684)
		(end 42.117772 -307.224684)
		(width 0.14478)
		(layer "In2.Cu")
		(net "M_C_CPU1_SB_DQ<22>")
	)
	(segment
		(start 78.932786 -287.570418)
		(end 78.995778 -287.533588)
		(width 0.0889)
		(layer "In2.Cu")
		(net "M_C_CPU1_SB_DQ<22>")
	)
	(segment
		(start 63.453518 -306.56022)
		(end 66.45529 -303.558448)
		(width 0.14478)
		(layer "In2.Cu")
		(net "M_C_CPU1_SB_DQ<22>")
	)
	(segment
		(start 79.907638 -287.549844)
		(end 79.935324 -287.533842)
		(width 0.0889)
		(layer "In2.Cu")
		(net "M_C_CPU1_SB_DQ<22>")
	)
	(segment
		(start 85.93963 -287.529016)
		(end 85.948012 -287.533842)
		(width 0.0889)
		(layer "In2.Cu")
		(net "M_C_CPU1_SB_DQ<22>")
	)
	(segment
		(start 66.45529 -303.558448)
		(end 66.45529 -302.40732)
		(width 0.14478)
		(layer "In2.Cu")
		(net "M_C_CPU1_SB_DQ<22>")
	)
	(segment
		(start 41.551352 -307.410358)
		(end 41.737026 -307.224684)
		(width 0.14478)
		(layer "In2.Cu")
		(net "M_C_CPU1_SB_DQ<22>")
	)
	(segment
		(start 86.879684 -287.529016)
		(end 86.888066 -287.533842)
		(width 0.0889)
		(layer "In2.Cu")
		(net "M_C_CPU1_SB_DQ<22>")
	)
	(segment
		(start 79.347822 -287.52038)
		(end 79.37119 -287.533842)
		(width 0.0889)
		(layer "In2.Cu")
		(net "M_C_CPU1_SB_DQ<22>")
	)
	(segment
		(start 82.753962 -287.533842)
		(end 82.762344 -287.529016)
		(width 0.0889)
		(layer "In2.Cu")
		(net "M_C_CPU1_SB_DQ<22>")
	)
	(segment
		(start 94.352618 -287.50768)
		(end 94.37497 -287.590992)
		(width 0.0889)
		(layer "In2.Cu")
		(net "M_C_CPU1_SB_DQ<22>")
	)
	(segment
		(start 75.957176 -289.547554)
		(end 77.197966 -288.306764)
		(width 0.0889)
		(layer "In2.Cu")
		(net "M_C_CPU1_SB_DQ<22>")
	)
	(segment
		(start 91.5797 -287.529016)
		(end 91.588082 -287.533842)
		(width 0.0889)
		(layer "In2.Cu")
		(net "M_C_CPU1_SB_DQ<22>")
	)
	(segment
		(start 90.639646 -287.529016)
		(end 90.648028 -287.533842)
		(width 0.0889)
		(layer "In2.Cu")
		(net "M_C_CPU1_SB_DQ<22>")
	)
	(segment
		(start 88.394032 -287.533842)
		(end 88.402414 -287.529016)
		(width 0.0889)
		(layer "In2.Cu")
		(net "M_C_CPU1_SB_DQ<22>")
	)
	(segment
		(start 77.391514 -288.306764)
		(end 77.854302 -287.843976)
		(width 0.0889)
		(layer "In2.Cu")
		(net "M_C_CPU1_SB_DQ<22>")
	)
	(segment
		(start 52.87518 -306.56022)
		(end 53.725318 -307.410358)
		(width 0.14478)
		(layer "In2.Cu")
		(net "M_C_CPU1_SB_DQ<22>")
	)
	(segment
		(start 77.197966 -288.306764)
		(end 77.391514 -288.306764)
		(width 0.0889)
		(layer "In2.Cu")
		(net "M_C_CPU1_SB_DQ<22>")
	)
	(segment
		(start 94.37497 -287.590992)
		(end 94.221046 -287.856422)
		(width 0.0889)
		(layer "In2.Cu")
		(net "M_C_CPU1_SB_DQ<22>")
	)
	(segment
		(start 72.783446 -296.079164)
		(end 72.783446 -292.922198)
		(width 0.14478)
		(layer "In2.Cu")
		(net "M_C_CPU1_SB_DQ<22>")
	)
	(segment
		(start 53.725318 -307.410358)
		(end 57.184798 -307.410358)
		(width 0.14478)
		(layer "In2.Cu")
		(net "M_C_CPU1_SB_DQ<22>")
	)
	(segment
		(start 92.153994 -287.533842)
		(end 92.162376 -287.529016)
		(width 0.0889)
		(layer "In2.Cu")
		(net "M_C_CPU1_SB_DQ<22>")
	)
	(segment
		(start 78.41234 -287.612836)
		(end 78.775814 -287.612836)
		(width 0.0889)
		(layer "In2.Cu")
		(net "M_C_CPU1_SB_DQ<22>")
	)
	(segment
		(start 42.303446 -307.410358)
		(end 49.448466 -307.410358)
		(width 0.14478)
		(layer "In2.Cu")
		(net "M_C_CPU1_SB_DQ<22>")
	)
	(segment
		(start 49.448466 -307.410358)
		(end 50.298604 -306.56022)
		(width 0.14478)
		(layer "In2.Cu")
		(net "M_C_CPU1_SB_DQ<22>")
	)
	(segment
		(start 82.179668 -287.529016)
		(end 82.18805 -287.533842)
		(width 0.0889)
		(layer "In2.Cu")
		(net "M_C_CPU1_SB_DQ<22>")
	)
	(segment
		(start 58.034936 -306.56022)
		(end 63.453518 -306.56022)
		(width 0.14478)
		(layer "In2.Cu")
		(net "M_C_CPU1_SB_DQ<22>")
	)
	(segment
		(start 50.298604 -306.56022)
		(end 52.87518 -306.56022)
		(width 0.14478)
		(layer "In2.Cu")
		(net "M_C_CPU1_SB_DQ<22>")
	)
	(segment
		(start 83.694016 -287.533842)
		(end 83.702398 -287.529016)
		(width 0.0889)
		(layer "In2.Cu")
		(net "M_C_CPU1_SB_DQ<22>")
	)
	(segment
		(start 87.453978 -287.533842)
		(end 87.46236 -287.529016)
		(width 0.0889)
		(layer "In2.Cu")
		(net "M_C_CPU1_SB_DQ<22>")
	)
	(segment
		(start 66.45529 -302.40732)
		(end 72.783446 -296.079164)
		(width 0.14478)
		(layer "In2.Cu")
		(net "M_C_CPU1_SB_DQ<22>")
	)
	(arc
		(start 82.18805 -287.533842)
		(mid 82.471006 -287.609985)
		(end 82.753962 -287.533842)
		(width 0.0889)
		(layer "In2.Cu")
		(net "M_C_CPU1_SB_DQ<22>")
	)
	(arc
		(start 88.768174 -287.533842)
		(mid 89.05113 -287.609985)
		(end 89.334086 -287.533842)
		(width 0.0889)
		(layer "In2.Cu")
		(net "M_C_CPU1_SB_DQ<22>")
	)
	(arc
		(start 86.513924 -287.533842)
		(mid 86.696175 -287.483492)
		(end 86.879684 -287.529016)
		(width 0.0889)
		(layer "In2.Cu")
		(net "M_C_CPU1_SB_DQ<22>")
	)
	(arc
		(start 90.648028 -287.533842)
		(mid 90.930984 -287.609985)
		(end 91.21394 -287.533842)
		(width 0.0889)
		(layer "In2.Cu")
		(net "M_C_CPU1_SB_DQ<22>")
	)
	(arc
		(start 80.308196 -287.533842)
		(mid 80.591152 -287.609985)
		(end 80.874108 -287.533842)
		(width 0.0889)
		(layer "In2.Cu")
		(net "M_C_CPU1_SB_DQ<22>")
	)
	(arc
		(start 78.775814 -287.612836)
		(mid 78.857111 -287.602037)
		(end 78.932786 -287.570418)
		(width 0.0889)
		(layer "In2.Cu")
		(net "M_C_CPU1_SB_DQ<22>")
	)
	(arc
		(start 82.762344 -287.529016)
		(mid 82.945852 -287.483522)
		(end 83.128104 -287.533842)
		(width 0.0889)
		(layer "In2.Cu")
		(net "M_C_CPU1_SB_DQ<22>")
	)
	(arc
		(start 93.46819 -287.533842)
		(mid 93.751146 -287.609985)
		(end 94.034102 -287.533842)
		(width 0.0889)
		(layer "In2.Cu")
		(net "M_C_CPU1_SB_DQ<22>")
	)
	(arc
		(start 87.46236 -287.529016)
		(mid 87.645868 -287.483522)
		(end 87.82812 -287.533842)
		(width 0.0889)
		(layer "In2.Cu")
		(net "M_C_CPU1_SB_DQ<22>")
	)
	(arc
		(start 92.528136 -287.533842)
		(mid 92.811092 -287.609985)
		(end 93.094048 -287.533842)
		(width 0.0889)
		(layer "In2.Cu")
		(net "M_C_CPU1_SB_DQ<22>")
	)
	(arc
		(start 83.702398 -287.529016)
		(mid 83.885906 -287.483522)
		(end 84.068158 -287.533842)
		(width 0.0889)
		(layer "In2.Cu")
		(net "M_C_CPU1_SB_DQ<22>")
	)
	(arc
		(start 78.995778 -287.533588)
		(mid 79.170155 -287.482867)
		(end 79.347822 -287.52038)
		(width 0.0889)
		(layer "In2.Cu")
		(net "M_C_CPU1_SB_DQ<22>")
	)
	(arc
		(start 92.162376 -287.529016)
		(mid 92.345884 -287.483522)
		(end 92.528136 -287.533842)
		(width 0.0889)
		(layer "In2.Cu")
		(net "M_C_CPU1_SB_DQ<22>")
	)
	(arc
		(start 89.707974 -287.533842)
		(mid 89.99093 -287.609985)
		(end 90.273886 -287.533842)
		(width 0.0889)
		(layer "In2.Cu")
		(net "M_C_CPU1_SB_DQ<22>")
	)
	(arc
		(start 93.10243 -287.529016)
		(mid 93.285938 -287.483522)
		(end 93.46819 -287.533842)
		(width 0.0889)
		(layer "In2.Cu")
		(net "M_C_CPU1_SB_DQ<22>")
	)
	(arc
		(start 91.21394 -287.533842)
		(mid 91.396191 -287.483492)
		(end 91.5797 -287.529016)
		(width 0.0889)
		(layer "In2.Cu")
		(net "M_C_CPU1_SB_DQ<22>")
	)
	(arc
		(start 84.63407 -287.533842)
		(mid 84.821014 -287.483587)
		(end 85.007958 -287.533842)
		(width 0.0889)
		(layer "In2.Cu")
		(net "M_C_CPU1_SB_DQ<22>")
	)
	(arc
		(start 85.007958 -287.533842)
		(mid 85.290914 -287.609985)
		(end 85.57387 -287.533842)
		(width 0.0889)
		(layer "In2.Cu")
		(net "M_C_CPU1_SB_DQ<22>")
	)
	(arc
		(start 80.874108 -287.533842)
		(mid 81.061052 -287.483587)
		(end 81.247996 -287.533842)
		(width 0.0889)
		(layer "In2.Cu")
		(net "M_C_CPU1_SB_DQ<22>")
	)
	(arc
		(start 89.334086 -287.533842)
		(mid 89.52103 -287.483587)
		(end 89.707974 -287.533842)
		(width 0.0889)
		(layer "In2.Cu")
		(net "M_C_CPU1_SB_DQ<22>")
	)
	(arc
		(start 84.068158 -287.533842)
		(mid 84.351114 -287.609985)
		(end 84.63407 -287.533842)
		(width 0.0889)
		(layer "In2.Cu")
		(net "M_C_CPU1_SB_DQ<22>")
	)
	(arc
		(start 83.128104 -287.533842)
		(mid 83.41106 -287.609985)
		(end 83.694016 -287.533842)
		(width 0.0889)
		(layer "In2.Cu")
		(net "M_C_CPU1_SB_DQ<22>")
	)
	(arc
		(start 86.888066 -287.533842)
		(mid 87.171022 -287.609985)
		(end 87.453978 -287.533842)
		(width 0.0889)
		(layer "In2.Cu")
		(net "M_C_CPU1_SB_DQ<22>")
	)
	(arc
		(start 81.247996 -287.533842)
		(mid 81.530952 -287.609985)
		(end 81.813908 -287.533842)
		(width 0.0889)
		(layer "In2.Cu")
		(net "M_C_CPU1_SB_DQ<22>")
	)
	(arc
		(start 79.37119 -287.533842)
		(mid 79.637382 -287.609735)
		(end 79.907638 -287.549844)
		(width 0.0889)
		(layer "In2.Cu")
		(net "M_C_CPU1_SB_DQ<22>")
	)
	(arc
		(start 90.273886 -287.533842)
		(mid 90.456137 -287.483492)
		(end 90.639646 -287.529016)
		(width 0.0889)
		(layer "In2.Cu")
		(net "M_C_CPU1_SB_DQ<22>")
	)
	(arc
		(start 79.955898 -287.522158)
		(mid 80.133528 -287.483697)
		(end 80.308196 -287.533842)
		(width 0.0889)
		(layer "In2.Cu")
		(net "M_C_CPU1_SB_DQ<22>")
	)
	(arc
		(start 91.588082 -287.533842)
		(mid 91.871038 -287.609985)
		(end 92.153994 -287.533842)
		(width 0.0889)
		(layer "In2.Cu")
		(net "M_C_CPU1_SB_DQ<22>")
	)
	(arc
		(start 85.57387 -287.533842)
		(mid 85.756121 -287.483492)
		(end 85.93963 -287.529016)
		(width 0.0889)
		(layer "In2.Cu")
		(net "M_C_CPU1_SB_DQ<22>")
	)
	(arc
		(start 85.948012 -287.533842)
		(mid 86.230968 -287.609985)
		(end 86.513924 -287.533842)
		(width 0.0889)
		(layer "In2.Cu")
		(net "M_C_CPU1_SB_DQ<22>")
	)
	(arc
		(start 87.82812 -287.533842)
		(mid 88.111076 -287.609985)
		(end 88.394032 -287.533842)
		(width 0.0889)
		(layer "In2.Cu")
		(net "M_C_CPU1_SB_DQ<22>")
	)
	(arc
		(start 94.034102 -287.533842)
		(mid 94.190421 -287.484847)
		(end 94.352618 -287.50768)
		(width 0.0889)
		(layer "In2.Cu")
		(net "M_C_CPU1_SB_DQ<22>")
	)
	(arc
		(start 77.854302 -287.843976)
		(mid 78.110332 -287.672902)
		(end 78.41234 -287.612836)
		(width 0.0889)
		(layer "In2.Cu")
		(net "M_C_CPU1_SB_DQ<22>")
	)
	(arc
		(start 88.402414 -287.529016)
		(mid 88.585922 -287.483522)
		(end 88.768174 -287.533842)
		(width 0.0889)
		(layer "In2.Cu")
		(net "M_C_CPU1_SB_DQ<22>")
	)
	(arc
		(start 81.813908 -287.533842)
		(mid 81.996159 -287.483492)
		(end 82.179668 -287.529016)
		(width 0.0889)
		(layer "In2.Cu")
		(net "M_C_CPU1_SB_DQ<22>")
	)
	(segment
		(start 96.568006 -287.590484)
		(end 96.101154 -287.856422)
		(width 0.10668)
		(layer "F.Cu")
		(net "M_C_CPU1_SB_DQ<21>")
	)
	(segment
		(start 67.303396 -302.512222)
		(end 67.537076 -302.745902)
		(width 0.14478)
		(layer "In2.Cu")
		(net "M_C_CPU1_SB_DQ<21>")
	)
	(segment
		(start 73.238106 -293.168324)
		(end 75.927966 -290.478464)
		(width 0.14478)
		(layer "In2.Cu")
		(net "M_C_CPU1_SB_DQ<21>")
	)
	(segment
		(start 62.512956 -307.103526)
		(end 62.55639 -307.146706)
		(width 0.14478)
		(layer "In2.Cu")
		(net "M_C_CPU1_SB_DQ<21>")
	)
	(segment
		(start 61.71692 -307.410358)
		(end 61.961522 -307.410358)
		(width 0.14478)
		(layer "In2.Cu")
		(net "M_C_CPU1_SB_DQ<21>")
	)
	(segment
		(start 67.537076 -302.745902)
		(end 67.7672 -302.745902)
		(width 0.14478)
		(layer "In2.Cu")
		(net "M_C_CPU1_SB_DQ<21>")
	)
	(segment
		(start 49.377854 -308.260496)
		(end 50.227992 -307.410358)
		(width 0.14478)
		(layer "In2.Cu")
		(net "M_C_CPU1_SB_DQ<21>")
	)
	(segment
		(start 67.7672 -302.745902)
		(end 67.930522 -302.58258)
		(width 0.14478)
		(layer "In2.Cu")
		(net "M_C_CPU1_SB_DQ<21>")
	)
	(segment
		(start 85.93963 -288.183574)
		(end 85.948012 -288.178748)
		(width 0.0889)
		(layer "In2.Cu")
		(net "M_C_CPU1_SB_DQ<21>")
	)
	(segment
		(start 60.614052 -307.410358)
		(end 60.858654 -307.410358)
		(width 0.14478)
		(layer "In2.Cu")
		(net "M_C_CPU1_SB_DQ<21>")
	)
	(segment
		(start 77.942694 -288.636964)
		(end 78.312518 -288.26714)
		(width 0.0889)
		(layer "In2.Cu")
		(net "M_C_CPU1_SB_DQ<21>")
	)
	(segment
		(start 45.501052 -308.260496)
		(end 45.662596 -308.098952)
		(width 0.14478)
		(layer "In2.Cu")
		(net "M_C_CPU1_SB_DQ<21>")
	)
	(segment
		(start 67.073272 -302.512222)
		(end 67.303396 -302.512222)
		(width 0.14478)
		(layer "In2.Cu")
		(net "M_C_CPU1_SB_DQ<21>")
	)
	(segment
		(start 61.410088 -307.103526)
		(end 61.71692 -307.410358)
		(width 0.14478)
		(layer "In2.Cu")
		(net "M_C_CPU1_SB_DQ<21>")
	)
	(segment
		(start 79.934054 -288.178748)
		(end 79.942436 -288.183574)
		(width 0.0889)
		(layer "In2.Cu")
		(net "M_C_CPU1_SB_DQ<21>")
	)
	(segment
		(start 67.930522 -302.58258)
		(end 67.930522 -302.352456)
		(width 0.14478)
		(layer "In2.Cu")
		(net "M_C_CPU1_SB_DQ<21>")
	)
	(segment
		(start 88.394032 -288.178748)
		(end 88.402414 -288.183574)
		(width 0.0889)
		(layer "In2.Cu")
		(net "M_C_CPU1_SB_DQ<21>")
	)
	(segment
		(start 95.339662 -288.183574)
		(end 95.348044 -288.178748)
		(width 0.0889)
		(layer "In2.Cu")
		(net "M_C_CPU1_SB_DQ<21>")
	)
	(segment
		(start 59.755786 -307.410358)
		(end 60.062618 -307.103526)
		(width 0.14478)
		(layer "In2.Cu")
		(net "M_C_CPU1_SB_DQ<21>")
	)
	(segment
		(start 67.217544 -303.213262)
		(end 66.90995 -302.905668)
		(width 0.14478)
		(layer "In2.Cu")
		(net "M_C_CPU1_SB_DQ<21>")
	)
	(segment
		(start 44.340018 -307.8353)
		(end 44.765214 -308.260496)
		(width 0.14478)
		(layer "In2.Cu")
		(net "M_C_CPU1_SB_DQ<21>")
	)
	(segment
		(start 82.179668 -288.183574)
		(end 82.18805 -288.178748)
		(width 0.0889)
		(layer "In2.Cu")
		(net "M_C_CPU1_SB_DQ<21>")
	)
	(segment
		(start 92.153994 -288.178748)
		(end 92.162376 -288.183574)
		(width 0.0889)
		(layer "In2.Cu")
		(net "M_C_CPU1_SB_DQ<21>")
	)
	(segment
		(start 78.979268 -288.170112)
		(end 78.994 -288.178748)
		(width 0.0889)
		(layer "In2.Cu")
		(net "M_C_CPU1_SB_DQ<21>")
	)
	(segment
		(start 60.858654 -307.410358)
		(end 61.165486 -307.103526)
		(width 0.14478)
		(layer "In2.Cu")
		(net "M_C_CPU1_SB_DQ<21>")
	)
	(segment
		(start 91.5797 -288.183574)
		(end 91.588082 -288.178748)
		(width 0.0889)
		(layer "In2.Cu")
		(net "M_C_CPU1_SB_DQ<21>")
	)
	(segment
		(start 67.696842 -302.118776)
		(end 67.696842 -301.826168)
		(width 0.14478)
		(layer "In2.Cu")
		(net "M_C_CPU1_SB_DQ<21>")
	)
	(segment
		(start 67.696842 -301.826168)
		(end 73.238106 -296.284904)
		(width 0.14478)
		(layer "In2.Cu")
		(net "M_C_CPU1_SB_DQ<21>")
	)
	(segment
		(start 76.519786 -289.886644)
		(end 76.519786 -289.294824)
		(width 0.0889)
		(layer "In2.Cu")
		(net "M_C_CPU1_SB_DQ<21>")
	)
	(segment
		(start 45.662596 -308.02199)
		(end 45.82414 -307.860446)
		(width 0.14478)
		(layer "In2.Cu")
		(net "M_C_CPU1_SB_DQ<21>")
	)
	(segment
		(start 63.246508 -307.410358)
		(end 67.217544 -303.439322)
		(width 0.14478)
		(layer "In2.Cu")
		(net "M_C_CPU1_SB_DQ<21>")
	)
	(segment
		(start 60.062618 -307.103526)
		(end 60.30722 -307.103526)
		(width 0.14478)
		(layer "In2.Cu")
		(net "M_C_CPU1_SB_DQ<21>")
	)
	(segment
		(start 53.932074 -308.260496)
		(end 57.068974 -308.260496)
		(width 0.14478)
		(layer "In2.Cu")
		(net "M_C_CPU1_SB_DQ<21>")
	)
	(segment
		(start 93.094048 -288.178748)
		(end 93.10243 -288.183574)
		(width 0.0889)
		(layer "In2.Cu")
		(net "M_C_CPU1_SB_DQ<21>")
	)
	(segment
		(start 66.90995 -302.675544)
		(end 67.073272 -302.512222)
		(width 0.14478)
		(layer "In2.Cu")
		(net "M_C_CPU1_SB_DQ<21>")
	)
	(segment
		(start 50.227992 -307.410358)
		(end 53.081936 -307.410358)
		(width 0.14478)
		(layer "In2.Cu")
		(net "M_C_CPU1_SB_DQ<21>")
	)
	(segment
		(start 90.639646 -288.183574)
		(end 90.648028 -288.178748)
		(width 0.0889)
		(layer "In2.Cu")
		(net "M_C_CPU1_SB_DQ<21>")
	)
	(segment
		(start 82.753962 -288.178748)
		(end 82.762344 -288.183574)
		(width 0.0889)
		(layer "In2.Cu")
		(net "M_C_CPU1_SB_DQ<21>")
	)
	(segment
		(start 53.081936 -307.410358)
		(end 53.932074 -308.260496)
		(width 0.14478)
		(layer "In2.Cu")
		(net "M_C_CPU1_SB_DQ<21>")
	)
	(segment
		(start 95.946976 -288.121852)
		(end 96.101154 -287.856422)
		(width 0.0889)
		(layer "In2.Cu")
		(net "M_C_CPU1_SB_DQ<21>")
	)
	(segment
		(start 57.068974 -308.260496)
		(end 57.919112 -307.410358)
		(width 0.14478)
		(layer "In2.Cu")
		(net "M_C_CPU1_SB_DQ<21>")
	)
	(segment
		(start 46.375574 -308.260496)
		(end 49.377854 -308.260496)
		(width 0.14478)
		(layer "In2.Cu")
		(net "M_C_CPU1_SB_DQ<21>")
	)
	(segment
		(start 87.453978 -288.178748)
		(end 87.46236 -288.183574)
		(width 0.0889)
		(layer "In2.Cu")
		(net "M_C_CPU1_SB_DQ<21>")
	)
	(segment
		(start 45.662596 -308.098952)
		(end 45.662596 -308.02199)
		(width 0.14478)
		(layer "In2.Cu")
		(net "M_C_CPU1_SB_DQ<21>")
	)
	(segment
		(start 62.268354 -307.103526)
		(end 62.512956 -307.103526)
		(width 0.14478)
		(layer "In2.Cu")
		(net "M_C_CPU1_SB_DQ<21>")
	)
	(segment
		(start 46.21403 -308.098952)
		(end 46.375574 -308.260496)
		(width 0.14478)
		(layer "In2.Cu")
		(net "M_C_CPU1_SB_DQ<21>")
	)
	(segment
		(start 62.55639 -307.146706)
		(end 62.819788 -307.410358)
		(width 0.14478)
		(layer "In2.Cu")
		(net "M_C_CPU1_SB_DQ<21>")
	)
	(segment
		(start 67.930522 -302.352456)
		(end 67.696842 -302.118776)
		(width 0.14478)
		(layer "In2.Cu")
		(net "M_C_CPU1_SB_DQ<21>")
	)
	(segment
		(start 57.919112 -307.410358)
		(end 59.755786 -307.410358)
		(width 0.14478)
		(layer "In2.Cu")
		(net "M_C_CPU1_SB_DQ<21>")
	)
	(segment
		(start 61.961522 -307.410358)
		(end 62.268354 -307.103526)
		(width 0.14478)
		(layer "In2.Cu")
		(net "M_C_CPU1_SB_DQ<21>")
	)
	(segment
		(start 60.30722 -307.103526)
		(end 60.614052 -307.410358)
		(width 0.14478)
		(layer "In2.Cu")
		(net "M_C_CPU1_SB_DQ<21>")
	)
	(segment
		(start 77.177646 -288.636964)
		(end 77.942694 -288.636964)
		(width 0.0889)
		(layer "In2.Cu")
		(net "M_C_CPU1_SB_DQ<21>")
	)
	(segment
		(start 66.90995 -302.905668)
		(end 66.90995 -302.675544)
		(width 0.14478)
		(layer "In2.Cu")
		(net "M_C_CPU1_SB_DQ<21>")
	)
	(segment
		(start 78.994 -288.178748)
		(end 79.002382 -288.183574)
		(width 0.0889)
		(layer "In2.Cu")
		(net "M_C_CPU1_SB_DQ<21>")
	)
	(segment
		(start 45.82414 -307.860446)
		(end 46.052486 -307.860446)
		(width 0.14478)
		(layer "In2.Cu")
		(net "M_C_CPU1_SB_DQ<21>")
	)
	(segment
		(start 86.879684 -288.183574)
		(end 86.888066 -288.178748)
		(width 0.0889)
		(layer "In2.Cu")
		(net "M_C_CPU1_SB_DQ<21>")
	)
	(segment
		(start 83.694016 -288.178748)
		(end 83.702398 -288.183574)
		(width 0.0889)
		(layer "In2.Cu")
		(net "M_C_CPU1_SB_DQ<21>")
	)
	(segment
		(start 73.238106 -296.284904)
		(end 73.238106 -293.168324)
		(width 0.14478)
		(layer "In2.Cu")
		(net "M_C_CPU1_SB_DQ<21>")
	)
	(segment
		(start 46.052486 -307.860446)
		(end 46.21403 -308.02199)
		(width 0.14478)
		(layer "In2.Cu")
		(net "M_C_CPU1_SB_DQ<21>")
	)
	(segment
		(start 67.217544 -303.439322)
		(end 67.217544 -303.213262)
		(width 0.14478)
		(layer "In2.Cu")
		(net "M_C_CPU1_SB_DQ<21>")
	)
	(segment
		(start 62.819788 -307.410358)
		(end 63.246508 -307.410358)
		(width 0.14478)
		(layer "In2.Cu")
		(net "M_C_CPU1_SB_DQ<21>")
	)
	(segment
		(start 95.851218 -288.147252)
		(end 95.946976 -288.121852)
		(width 0.0889)
		(layer "In2.Cu")
		(net "M_C_CPU1_SB_DQ<21>")
	)
	(segment
		(start 76.519786 -289.294824)
		(end 77.177646 -288.636964)
		(width 0.0889)
		(layer "In2.Cu")
		(net "M_C_CPU1_SB_DQ<21>")
	)
	(segment
		(start 46.21403 -308.02199)
		(end 46.21403 -308.098952)
		(width 0.14478)
		(layer "In2.Cu")
		(net "M_C_CPU1_SB_DQ<21>")
	)
	(segment
		(start 61.165486 -307.103526)
		(end 61.410088 -307.103526)
		(width 0.14478)
		(layer "In2.Cu")
		(net "M_C_CPU1_SB_DQ<21>")
	)
	(segment
		(start 75.927966 -290.478464)
		(end 76.519786 -289.886644)
		(width 0.0889)
		(layer "In2.Cu")
		(net "M_C_CPU1_SB_DQ<21>")
	)
	(segment
		(start 44.765214 -308.260496)
		(end 45.501052 -308.260496)
		(width 0.14478)
		(layer "In2.Cu")
		(net "M_C_CPU1_SB_DQ<21>")
	)
	(arc
		(start 88.402414 -288.183574)
		(mid 88.585922 -288.229099)
		(end 88.768174 -288.178748)
		(width 0.0889)
		(layer "In2.Cu")
		(net "M_C_CPU1_SB_DQ<21>")
	)
	(arc
		(start 91.588082 -288.178748)
		(mid 91.871038 -288.102571)
		(end 92.153994 -288.178748)
		(width 0.0889)
		(layer "In2.Cu")
		(net "M_C_CPU1_SB_DQ<21>")
	)
	(arc
		(start 87.82812 -288.178748)
		(mid 88.111076 -288.102571)
		(end 88.394032 -288.178748)
		(width 0.0889)
		(layer "In2.Cu")
		(net "M_C_CPU1_SB_DQ<21>")
	)
	(arc
		(start 86.513924 -288.178748)
		(mid 86.696175 -288.229132)
		(end 86.879684 -288.183574)
		(width 0.0889)
		(layer "In2.Cu")
		(net "M_C_CPU1_SB_DQ<21>")
	)
	(arc
		(start 82.762344 -288.183574)
		(mid 82.945852 -288.229099)
		(end 83.128104 -288.178748)
		(width 0.0889)
		(layer "In2.Cu")
		(net "M_C_CPU1_SB_DQ<21>")
	)
	(arc
		(start 83.702398 -288.183574)
		(mid 83.885906 -288.229099)
		(end 84.068158 -288.178748)
		(width 0.0889)
		(layer "In2.Cu")
		(net "M_C_CPU1_SB_DQ<21>")
	)
	(arc
		(start 79.942436 -288.183574)
		(mid 80.125944 -288.229099)
		(end 80.308196 -288.178748)
		(width 0.0889)
		(layer "In2.Cu")
		(net "M_C_CPU1_SB_DQ<21>")
	)
	(arc
		(start 82.18805 -288.178748)
		(mid 82.471006 -288.102571)
		(end 82.753962 -288.178748)
		(width 0.0889)
		(layer "In2.Cu")
		(net "M_C_CPU1_SB_DQ<21>")
	)
	(arc
		(start 87.46236 -288.183574)
		(mid 87.645868 -288.229099)
		(end 87.82812 -288.178748)
		(width 0.0889)
		(layer "In2.Cu")
		(net "M_C_CPU1_SB_DQ<21>")
	)
	(arc
		(start 88.768174 -288.178748)
		(mid 89.05113 -288.102571)
		(end 89.334086 -288.178748)
		(width 0.0889)
		(layer "In2.Cu")
		(net "M_C_CPU1_SB_DQ<21>")
	)
	(arc
		(start 81.247996 -288.178748)
		(mid 81.530952 -288.102571)
		(end 81.813908 -288.178748)
		(width 0.0889)
		(layer "In2.Cu")
		(net "M_C_CPU1_SB_DQ<21>")
	)
	(arc
		(start 91.21394 -288.178748)
		(mid 91.396191 -288.229132)
		(end 91.5797 -288.183574)
		(width 0.0889)
		(layer "In2.Cu")
		(net "M_C_CPU1_SB_DQ<21>")
	)
	(arc
		(start 85.948012 -288.178748)
		(mid 86.230968 -288.102571)
		(end 86.513924 -288.178748)
		(width 0.0889)
		(layer "In2.Cu")
		(net "M_C_CPU1_SB_DQ<21>")
	)
	(arc
		(start 80.874108 -288.178748)
		(mid 81.061052 -288.229037)
		(end 81.247996 -288.178748)
		(width 0.0889)
		(layer "In2.Cu")
		(net "M_C_CPU1_SB_DQ<21>")
	)
	(arc
		(start 79.368142 -288.178748)
		(mid 79.651098 -288.102571)
		(end 79.934054 -288.178748)
		(width 0.0889)
		(layer "In2.Cu")
		(net "M_C_CPU1_SB_DQ<21>")
	)
	(arc
		(start 85.007958 -288.178748)
		(mid 85.290914 -288.102571)
		(end 85.57387 -288.178748)
		(width 0.0889)
		(layer "In2.Cu")
		(net "M_C_CPU1_SB_DQ<21>")
	)
	(arc
		(start 78.331314 -288.249106)
		(mid 78.377585 -288.21138)
		(end 78.42758 -288.178748)
		(width 0.0889)
		(layer "In2.Cu")
		(net "M_C_CPU1_SB_DQ<21>")
	)
	(arc
		(start 93.10243 -288.183574)
		(mid 93.285938 -288.229099)
		(end 93.46819 -288.178748)
		(width 0.0889)
		(layer "In2.Cu")
		(net "M_C_CPU1_SB_DQ<21>")
	)
	(arc
		(start 78.312518 -288.26714)
		(mid 78.321811 -288.258013)
		(end 78.331314 -288.249106)
		(width 0.0889)
		(layer "In2.Cu")
		(net "M_C_CPU1_SB_DQ<21>")
	)
	(arc
		(start 89.334086 -288.178748)
		(mid 89.52103 -288.229037)
		(end 89.707974 -288.178748)
		(width 0.0889)
		(layer "In2.Cu")
		(net "M_C_CPU1_SB_DQ<21>")
	)
	(arc
		(start 90.273886 -288.178748)
		(mid 90.456137 -288.229132)
		(end 90.639646 -288.183574)
		(width 0.0889)
		(layer "In2.Cu")
		(net "M_C_CPU1_SB_DQ<21>")
	)
	(arc
		(start 85.57387 -288.178748)
		(mid 85.756121 -288.229132)
		(end 85.93963 -288.183574)
		(width 0.0889)
		(layer "In2.Cu")
		(net "M_C_CPU1_SB_DQ<21>")
	)
	(arc
		(start 94.034102 -288.178748)
		(mid 94.221046 -288.229037)
		(end 94.40799 -288.178748)
		(width 0.0889)
		(layer "In2.Cu")
		(net "M_C_CPU1_SB_DQ<21>")
	)
	(arc
		(start 84.068158 -288.178748)
		(mid 84.351114 -288.102571)
		(end 84.63407 -288.178748)
		(width 0.0889)
		(layer "In2.Cu")
		(net "M_C_CPU1_SB_DQ<21>")
	)
	(arc
		(start 83.128104 -288.178748)
		(mid 83.41106 -288.102571)
		(end 83.694016 -288.178748)
		(width 0.0889)
		(layer "In2.Cu")
		(net "M_C_CPU1_SB_DQ<21>")
	)
	(arc
		(start 80.308196 -288.178748)
		(mid 80.591152 -288.102571)
		(end 80.874108 -288.178748)
		(width 0.0889)
		(layer "In2.Cu")
		(net "M_C_CPU1_SB_DQ<21>")
	)
	(arc
		(start 94.973902 -288.178748)
		(mid 95.156153 -288.229132)
		(end 95.339662 -288.183574)
		(width 0.0889)
		(layer "In2.Cu")
		(net "M_C_CPU1_SB_DQ<21>")
	)
	(arc
		(start 92.162376 -288.183574)
		(mid 92.345884 -288.229099)
		(end 92.528136 -288.178748)
		(width 0.0889)
		(layer "In2.Cu")
		(net "M_C_CPU1_SB_DQ<21>")
	)
	(arc
		(start 79.002382 -288.183574)
		(mid 79.18589 -288.229099)
		(end 79.368142 -288.178748)
		(width 0.0889)
		(layer "In2.Cu")
		(net "M_C_CPU1_SB_DQ<21>")
	)
	(arc
		(start 81.813908 -288.178748)
		(mid 81.996159 -288.229132)
		(end 82.179668 -288.183574)
		(width 0.0889)
		(layer "In2.Cu")
		(net "M_C_CPU1_SB_DQ<21>")
	)
	(arc
		(start 95.348044 -288.178748)
		(mid 95.595904 -288.103665)
		(end 95.851218 -288.147252)
		(width 0.0889)
		(layer "In2.Cu")
		(net "M_C_CPU1_SB_DQ<21>")
	)
	(arc
		(start 94.40799 -288.178748)
		(mid 94.690946 -288.102571)
		(end 94.973902 -288.178748)
		(width 0.0889)
		(layer "In2.Cu")
		(net "M_C_CPU1_SB_DQ<21>")
	)
	(arc
		(start 86.888066 -288.178748)
		(mid 87.171022 -288.102571)
		(end 87.453978 -288.178748)
		(width 0.0889)
		(layer "In2.Cu")
		(net "M_C_CPU1_SB_DQ<21>")
	)
	(arc
		(start 92.528136 -288.178748)
		(mid 92.811092 -288.102571)
		(end 93.094048 -288.178748)
		(width 0.0889)
		(layer "In2.Cu")
		(net "M_C_CPU1_SB_DQ<21>")
	)
	(arc
		(start 90.648028 -288.178748)
		(mid 90.930984 -288.102571)
		(end 91.21394 -288.178748)
		(width 0.0889)
		(layer "In2.Cu")
		(net "M_C_CPU1_SB_DQ<21>")
	)
	(arc
		(start 89.707974 -288.178748)
		(mid 89.99093 -288.102571)
		(end 90.273886 -288.178748)
		(width 0.0889)
		(layer "In2.Cu")
		(net "M_C_CPU1_SB_DQ<21>")
	)
	(arc
		(start 93.46819 -288.178748)
		(mid 93.751146 -288.102571)
		(end 94.034102 -288.178748)
		(width 0.0889)
		(layer "In2.Cu")
		(net "M_C_CPU1_SB_DQ<21>")
	)
	(arc
		(start 84.63407 -288.178748)
		(mid 84.821014 -288.229037)
		(end 85.007958 -288.178748)
		(width 0.0889)
		(layer "In2.Cu")
		(net "M_C_CPU1_SB_DQ<21>")
	)
	(arc
		(start 78.42758 -288.178748)
		(mid 78.702286 -288.102384)
		(end 78.979268 -288.170112)
		(width 0.0889)
		(layer "In2.Cu")
		(net "M_C_CPU1_SB_DQ<21>")
	)
	(segment
		(start 95.157798 -286.780478)
		(end 94.690946 -287.046162)
		(width 0.10668)
		(layer "F.Cu")
		(net "M_C_CPU1_SB_DQ<20>")
	)
	(segment
		(start 65.213738 -304.156872)
		(end 65.050416 -304.320194)
		(width 0.14478)
		(layer "In2.Cu")
		(net "M_C_CPU1_SB_DQ<20>")
	)
	(segment
		(start 72.328786 -295.848024)
		(end 65.633854 -302.542956)
		(width 0.14478)
		(layer "In2.Cu")
		(net "M_C_CPU1_SB_DQ<20>")
	)
	(segment
		(start 63.273178 -304.903632)
		(end 63.273178 -305.133756)
		(width 0.14478)
		(layer "In2.Cu")
		(net "M_C_CPU1_SB_DQ<20>")
	)
	(segment
		(start 64.453516 -303.953418)
		(end 64.223392 -303.953418)
		(width 0.14478)
		(layer "In2.Cu")
		(net "M_C_CPU1_SB_DQ<20>")
	)
	(segment
		(start 75.986386 -288.97453)
		(end 72.328786 -292.63213)
		(width 0.14478)
		(layer "In2.Cu")
		(net "M_C_CPU1_SB_DQ<20>")
	)
	(segment
		(start 79.867506 -287.35274)
		(end 79.83982 -287.368742)
		(width 0.0889)
		(layer "In2.Cu")
		(net "M_C_CPU1_SB_DQ<20>")
	)
	(segment
		(start 65.240408 -303.166526)
		(end 65.010284 -303.166526)
		(width 0.14478)
		(layer "In2.Cu")
		(net "M_C_CPU1_SB_DQ<20>")
	)
	(segment
		(start 72.328786 -292.63213)
		(end 72.328786 -295.848024)
		(width 0.14478)
		(layer "In2.Cu")
		(net "M_C_CPU1_SB_DQ<20>")
	)
	(segment
		(start 85.112352 -287.373568)
		(end 85.10397 -287.368742)
		(width 0.0889)
		(layer "In2.Cu")
		(net "M_C_CPU1_SB_DQ<20>")
	)
	(segment
		(start 65.213738 -303.926748)
		(end 65.213738 -304.156872)
		(width 0.14478)
		(layer "In2.Cu")
		(net "M_C_CPU1_SB_DQ<20>")
	)
	(segment
		(start 94.690946 -287.046162)
		(end 94.537022 -287.311592)
		(width 0.0889)
		(layer "In2.Cu")
		(net "M_C_CPU1_SB_DQ<20>")
	)
	(segment
		(start 64.223392 -303.953418)
		(end 64.06007 -304.11674)
		(width 0.14478)
		(layer "In2.Cu")
		(net "M_C_CPU1_SB_DQ<20>")
	)
	(segment
		(start 66.00063 -303.36998)
		(end 65.837308 -303.533302)
		(width 0.14478)
		(layer "In2.Cu")
		(net "M_C_CPU1_SB_DQ<20>")
	)
	(segment
		(start 65.837308 -303.533302)
		(end 65.607184 -303.533302)
		(width 0.14478)
		(layer "In2.Cu")
		(net "M_C_CPU1_SB_DQ<20>")
	)
	(segment
		(start 64.06007 -304.11674)
		(end 64.06007 -304.346864)
		(width 0.14478)
		(layer "In2.Cu")
		(net "M_C_CPU1_SB_DQ<20>")
	)
	(segment
		(start 65.633854 -302.77308)
		(end 66.00063 -303.139856)
		(width 0.14478)
		(layer "In2.Cu")
		(net "M_C_CPU1_SB_DQ<20>")
	)
	(segment
		(start 63.639954 -305.730656)
		(end 63.433706 -305.936904)
		(width 0.14478)
		(layer "In2.Cu")
		(net "M_C_CPU1_SB_DQ<20>")
	)
	(segment
		(start 64.0334 -305.107086)
		(end 63.666624 -304.74031)
		(width 0.14478)
		(layer "In2.Cu")
		(net "M_C_CPU1_SB_DQ<20>")
	)
	(segment
		(start 81.35239 -287.373568)
		(end 81.344008 -287.368742)
		(width 0.0889)
		(layer "In2.Cu")
		(net "M_C_CPU1_SB_DQ<20>")
	)
	(segment
		(start 50.445416 -305.719988)
		(end 49.595278 -306.570126)
		(width 0.14478)
		(layer "In2.Cu")
		(net "M_C_CPU1_SB_DQ<20>")
	)
	(segment
		(start 86.052406 -287.373568)
		(end 86.044024 -287.368742)
		(width 0.0889)
		(layer "In2.Cu")
		(net "M_C_CPU1_SB_DQ<20>")
	)
	(segment
		(start 64.426846 -304.943764)
		(end 64.263524 -305.107086)
		(width 0.14478)
		(layer "In2.Cu")
		(net "M_C_CPU1_SB_DQ<20>")
	)
	(segment
		(start 88.29802 -287.368742)
		(end 88.289638 -287.373568)
		(width 0.0889)
		(layer "In2.Cu")
		(net "M_C_CPU1_SB_DQ<20>")
	)
	(segment
		(start 44.774866 -306.570126)
		(end 44.340018 -306.135278)
		(width 0.14478)
		(layer "In2.Cu")
		(net "M_C_CPU1_SB_DQ<20>")
	)
	(segment
		(start 65.633854 -302.542956)
		(end 65.633854 -302.77308)
		(width 0.14478)
		(layer "In2.Cu")
		(net "M_C_CPU1_SB_DQ<20>")
	)
	(segment
		(start 64.846962 -303.559972)
		(end 65.213738 -303.926748)
		(width 0.14478)
		(layer "In2.Cu")
		(net "M_C_CPU1_SB_DQ<20>")
	)
	(segment
		(start 60.983622 -305.710336)
		(end 58.21934 -305.710336)
		(width 0.14478)
		(layer "In2.Cu")
		(net "M_C_CPU1_SB_DQ<20>")
	)
	(segment
		(start 63.433706 -305.936904)
		(end 61.21019 -305.936904)
		(width 0.14478)
		(layer "In2.Cu")
		(net "M_C_CPU1_SB_DQ<20>")
	)
	(segment
		(start 78.73619 -287.413192)
		(end 78.294992 -287.413192)
		(width 0.0889)
		(layer "In2.Cu")
		(net "M_C_CPU1_SB_DQ<20>")
	)
	(segment
		(start 89.238074 -287.368742)
		(end 89.229692 -287.373568)
		(width 0.0889)
		(layer "In2.Cu")
		(net "M_C_CPU1_SB_DQ<20>")
	)
	(segment
		(start 52.845716 -305.719988)
		(end 50.445416 -305.719988)
		(width 0.14478)
		(layer "In2.Cu")
		(net "M_C_CPU1_SB_DQ<20>")
	)
	(segment
		(start 63.666624 -304.74031)
		(end 63.4365 -304.74031)
		(width 0.14478)
		(layer "In2.Cu")
		(net "M_C_CPU1_SB_DQ<20>")
	)
	(segment
		(start 84.538058 -287.368742)
		(end 84.529676 -287.373568)
		(width 0.0889)
		(layer "In2.Cu")
		(net "M_C_CPU1_SB_DQ<20>")
	)
	(segment
		(start 65.050416 -304.320194)
		(end 64.820292 -304.320194)
		(width 0.14478)
		(layer "In2.Cu")
		(net "M_C_CPU1_SB_DQ<20>")
	)
	(segment
		(start 92.998036 -287.368742)
		(end 92.989654 -287.373568)
		(width 0.0889)
		(layer "In2.Cu")
		(net "M_C_CPU1_SB_DQ<20>")
	)
	(segment
		(start 89.812368 -287.373568)
		(end 89.803986 -287.368742)
		(width 0.0889)
		(layer "In2.Cu")
		(net "M_C_CPU1_SB_DQ<20>")
	)
	(segment
		(start 49.595278 -306.570126)
		(end 44.774866 -306.570126)
		(width 0.14478)
		(layer "In2.Cu")
		(net "M_C_CPU1_SB_DQ<20>")
	)
	(segment
		(start 63.4365 -304.74031)
		(end 63.273178 -304.903632)
		(width 0.14478)
		(layer "In2.Cu")
		(net "M_C_CPU1_SB_DQ<20>")
	)
	(segment
		(start 63.639954 -305.500532)
		(end 63.639954 -305.730656)
		(width 0.14478)
		(layer "In2.Cu")
		(net "M_C_CPU1_SB_DQ<20>")
	)
	(segment
		(start 61.21019 -305.936904)
		(end 60.983622 -305.710336)
		(width 0.14478)
		(layer "In2.Cu")
		(net "M_C_CPU1_SB_DQ<20>")
	)
	(segment
		(start 58.21934 -305.710336)
		(end 57.369202 -306.560474)
		(width 0.14478)
		(layer "In2.Cu")
		(net "M_C_CPU1_SB_DQ<20>")
	)
	(segment
		(start 94.537022 -287.311592)
		(end 94.44101 -287.336992)
		(width 0.0889)
		(layer "In2.Cu")
		(net "M_C_CPU1_SB_DQ<20>")
	)
	(segment
		(start 53.686202 -306.560474)
		(end 52.845716 -305.719988)
		(width 0.14478)
		(layer "In2.Cu")
		(net "M_C_CPU1_SB_DQ<20>")
	)
	(segment
		(start 63.273178 -305.133756)
		(end 63.639954 -305.500532)
		(width 0.14478)
		(layer "In2.Cu")
		(net "M_C_CPU1_SB_DQ<20>")
	)
	(segment
		(start 66.00063 -303.139856)
		(end 66.00063 -303.36998)
		(width 0.14478)
		(layer "In2.Cu")
		(net "M_C_CPU1_SB_DQ<20>")
	)
	(segment
		(start 64.263524 -305.107086)
		(end 64.0334 -305.107086)
		(width 0.14478)
		(layer "In2.Cu")
		(net "M_C_CPU1_SB_DQ<20>")
	)
	(segment
		(start 83.598004 -287.368742)
		(end 83.589622 -287.373568)
		(width 0.0889)
		(layer "In2.Cu")
		(net "M_C_CPU1_SB_DQ<20>")
	)
	(segment
		(start 64.426846 -304.71364)
		(end 64.426846 -304.943764)
		(width 0.14478)
		(layer "In2.Cu")
		(net "M_C_CPU1_SB_DQ<20>")
	)
	(segment
		(start 77.787246 -287.623504)
		(end 77.307186 -288.103564)
		(width 0.0889)
		(layer "In2.Cu")
		(net "M_C_CPU1_SB_DQ<20>")
	)
	(segment
		(start 93.93809 -287.368742)
		(end 93.929708 -287.373568)
		(width 0.0889)
		(layer "In2.Cu")
		(net "M_C_CPU1_SB_DQ<20>")
	)
	(segment
		(start 65.607184 -303.533302)
		(end 65.240408 -303.166526)
		(width 0.14478)
		(layer "In2.Cu")
		(net "M_C_CPU1_SB_DQ<20>")
	)
	(segment
		(start 65.010284 -303.166526)
		(end 64.846962 -303.329848)
		(width 0.14478)
		(layer "In2.Cu")
		(net "M_C_CPU1_SB_DQ<20>")
	)
	(segment
		(start 80.778096 -287.368742)
		(end 80.769714 -287.373568)
		(width 0.0889)
		(layer "In2.Cu")
		(net "M_C_CPU1_SB_DQ<20>")
	)
	(segment
		(start 90.752422 -287.373568)
		(end 90.74404 -287.368742)
		(width 0.0889)
		(layer "In2.Cu")
		(net "M_C_CPU1_SB_DQ<20>")
	)
	(segment
		(start 76.857352 -288.103564)
		(end 75.986386 -288.97453)
		(width 0.0889)
		(layer "In2.Cu")
		(net "M_C_CPU1_SB_DQ<20>")
	)
	(segment
		(start 77.307186 -288.103564)
		(end 76.857352 -288.103564)
		(width 0.0889)
		(layer "In2.Cu")
		(net "M_C_CPU1_SB_DQ<20>")
	)
	(segment
		(start 64.820292 -304.320194)
		(end 64.453516 -303.953418)
		(width 0.14478)
		(layer "In2.Cu")
		(net "M_C_CPU1_SB_DQ<20>")
	)
	(segment
		(start 57.369202 -306.560474)
		(end 53.686202 -306.560474)
		(width 0.14478)
		(layer "In2.Cu")
		(net "M_C_CPU1_SB_DQ<20>")
	)
	(segment
		(start 79.83982 -287.368742)
		(end 79.821024 -287.37941)
		(width 0.0889)
		(layer "In2.Cu")
		(net "M_C_CPU1_SB_DQ<20>")
	)
	(segment
		(start 64.06007 -304.346864)
		(end 64.426846 -304.71364)
		(width 0.14478)
		(layer "In2.Cu")
		(net "M_C_CPU1_SB_DQ<20>")
	)
	(segment
		(start 79.467202 -287.368742)
		(end 79.443326 -287.354772)
		(width 0.0889)
		(layer "In2.Cu")
		(net "M_C_CPU1_SB_DQ<20>")
	)
	(segment
		(start 64.846962 -303.329848)
		(end 64.846962 -303.559972)
		(width 0.14478)
		(layer "In2.Cu")
		(net "M_C_CPU1_SB_DQ<20>")
	)
	(arc
		(start 86.418166 -287.368742)
		(mid 86.235915 -287.419092)
		(end 86.052406 -287.373568)
		(width 0.0889)
		(layer "In2.Cu")
		(net "M_C_CPU1_SB_DQ<20>")
	)
	(arc
		(start 90.74404 -287.368742)
		(mid 90.461084 -287.292599)
		(end 90.178128 -287.368742)
		(width 0.0889)
		(layer "In2.Cu")
		(net "M_C_CPU1_SB_DQ<20>")
	)
	(arc
		(start 88.289638 -287.373568)
		(mid 88.10613 -287.419062)
		(end 87.923878 -287.368742)
		(width 0.0889)
		(layer "In2.Cu")
		(net "M_C_CPU1_SB_DQ<20>")
	)
	(arc
		(start 91.118182 -287.368742)
		(mid 90.935931 -287.419092)
		(end 90.752422 -287.373568)
		(width 0.0889)
		(layer "In2.Cu")
		(net "M_C_CPU1_SB_DQ<20>")
	)
	(arc
		(start 80.769714 -287.373568)
		(mid 80.586206 -287.419062)
		(end 80.403954 -287.368742)
		(width 0.0889)
		(layer "In2.Cu")
		(net "M_C_CPU1_SB_DQ<20>")
	)
	(arc
		(start 90.178128 -287.368742)
		(mid 89.995877 -287.419092)
		(end 89.812368 -287.373568)
		(width 0.0889)
		(layer "In2.Cu")
		(net "M_C_CPU1_SB_DQ<20>")
	)
	(arc
		(start 93.563948 -287.368742)
		(mid 93.280992 -287.292599)
		(end 92.998036 -287.368742)
		(width 0.0889)
		(layer "In2.Cu")
		(net "M_C_CPU1_SB_DQ<20>")
	)
	(arc
		(start 80.403954 -287.368742)
		(mid 80.137762 -287.292849)
		(end 79.867506 -287.35274)
		(width 0.0889)
		(layer "In2.Cu")
		(net "M_C_CPU1_SB_DQ<20>")
	)
	(arc
		(start 86.984078 -287.368742)
		(mid 86.701122 -287.292599)
		(end 86.418166 -287.368742)
		(width 0.0889)
		(layer "In2.Cu")
		(net "M_C_CPU1_SB_DQ<20>")
	)
	(arc
		(start 82.65795 -287.368742)
		(mid 82.471006 -287.418997)
		(end 82.284062 -287.368742)
		(width 0.0889)
		(layer "In2.Cu")
		(net "M_C_CPU1_SB_DQ<20>")
	)
	(arc
		(start 78.294992 -287.413192)
		(mid 78.020203 -287.467851)
		(end 77.787246 -287.623504)
		(width 0.0889)
		(layer "In2.Cu")
		(net "M_C_CPU1_SB_DQ<20>")
	)
	(arc
		(start 89.803986 -287.368742)
		(mid 89.52103 -287.292599)
		(end 89.238074 -287.368742)
		(width 0.0889)
		(layer "In2.Cu")
		(net "M_C_CPU1_SB_DQ<20>")
	)
	(arc
		(start 81.344008 -287.368742)
		(mid 81.061052 -287.292599)
		(end 80.778096 -287.368742)
		(width 0.0889)
		(layer "In2.Cu")
		(net "M_C_CPU1_SB_DQ<20>")
	)
	(arc
		(start 83.589622 -287.373568)
		(mid 83.406114 -287.419062)
		(end 83.223862 -287.368742)
		(width 0.0889)
		(layer "In2.Cu")
		(net "M_C_CPU1_SB_DQ<20>")
	)
	(arc
		(start 88.863932 -287.368742)
		(mid 88.580976 -287.292599)
		(end 88.29802 -287.368742)
		(width 0.0889)
		(layer "In2.Cu")
		(net "M_C_CPU1_SB_DQ<20>")
	)
	(arc
		(start 91.684094 -287.368742)
		(mid 91.401138 -287.292599)
		(end 91.118182 -287.368742)
		(width 0.0889)
		(layer "In2.Cu")
		(net "M_C_CPU1_SB_DQ<20>")
	)
	(arc
		(start 87.357966 -287.368742)
		(mid 87.171022 -287.418997)
		(end 86.984078 -287.368742)
		(width 0.0889)
		(layer "In2.Cu")
		(net "M_C_CPU1_SB_DQ<20>")
	)
	(arc
		(start 89.229692 -287.373568)
		(mid 89.046184 -287.419062)
		(end 88.863932 -287.368742)
		(width 0.0889)
		(layer "In2.Cu")
		(net "M_C_CPU1_SB_DQ<20>")
	)
	(arc
		(start 92.623894 -287.368742)
		(mid 92.340938 -287.292599)
		(end 92.057982 -287.368742)
		(width 0.0889)
		(layer "In2.Cu")
		(net "M_C_CPU1_SB_DQ<20>")
	)
	(arc
		(start 78.899512 -287.368996)
		(mid 78.820793 -287.401975)
		(end 78.73619 -287.413192)
		(width 0.0889)
		(layer "In2.Cu")
		(net "M_C_CPU1_SB_DQ<20>")
	)
	(arc
		(start 85.478112 -287.368742)
		(mid 85.295861 -287.419092)
		(end 85.112352 -287.373568)
		(width 0.0889)
		(layer "In2.Cu")
		(net "M_C_CPU1_SB_DQ<20>")
	)
	(arc
		(start 84.163916 -287.368742)
		(mid 83.88096 -287.292599)
		(end 83.598004 -287.368742)
		(width 0.0889)
		(layer "In2.Cu")
		(net "M_C_CPU1_SB_DQ<20>")
	)
	(arc
		(start 93.929708 -287.373568)
		(mid 93.7462 -287.419062)
		(end 93.563948 -287.368742)
		(width 0.0889)
		(layer "In2.Cu")
		(net "M_C_CPU1_SB_DQ<20>")
	)
	(arc
		(start 81.71815 -287.368742)
		(mid 81.535899 -287.419092)
		(end 81.35239 -287.373568)
		(width 0.0889)
		(layer "In2.Cu")
		(net "M_C_CPU1_SB_DQ<20>")
	)
	(arc
		(start 92.989654 -287.373568)
		(mid 92.806146 -287.419062)
		(end 92.623894 -287.368742)
		(width 0.0889)
		(layer "In2.Cu")
		(net "M_C_CPU1_SB_DQ<20>")
	)
	(arc
		(start 83.223862 -287.368742)
		(mid 82.940906 -287.292599)
		(end 82.65795 -287.368742)
		(width 0.0889)
		(layer "In2.Cu")
		(net "M_C_CPU1_SB_DQ<20>")
	)
	(arc
		(start 85.10397 -287.368742)
		(mid 84.821014 -287.292599)
		(end 84.538058 -287.368742)
		(width 0.0889)
		(layer "In2.Cu")
		(net "M_C_CPU1_SB_DQ<20>")
	)
	(arc
		(start 94.44101 -287.336992)
		(mid 94.185802 -287.293535)
		(end 93.93809 -287.368742)
		(width 0.0889)
		(layer "In2.Cu")
		(net "M_C_CPU1_SB_DQ<20>")
	)
	(arc
		(start 84.529676 -287.373568)
		(mid 84.346168 -287.419062)
		(end 84.163916 -287.368742)
		(width 0.0889)
		(layer "In2.Cu")
		(net "M_C_CPU1_SB_DQ<20>")
	)
	(arc
		(start 87.923878 -287.368742)
		(mid 87.640922 -287.292599)
		(end 87.357966 -287.368742)
		(width 0.0889)
		(layer "In2.Cu")
		(net "M_C_CPU1_SB_DQ<20>")
	)
	(arc
		(start 82.284062 -287.368742)
		(mid 82.001106 -287.292599)
		(end 81.71815 -287.368742)
		(width 0.0889)
		(layer "In2.Cu")
		(net "M_C_CPU1_SB_DQ<20>")
	)
	(arc
		(start 86.044024 -287.368742)
		(mid 85.761068 -287.292599)
		(end 85.478112 -287.368742)
		(width 0.0889)
		(layer "In2.Cu")
		(net "M_C_CPU1_SB_DQ<20>")
	)
	(arc
		(start 92.057982 -287.368742)
		(mid 91.871038 -287.418997)
		(end 91.684094 -287.368742)
		(width 0.0889)
		(layer "In2.Cu")
		(net "M_C_CPU1_SB_DQ<20>")
	)
	(arc
		(start 79.443326 -287.354772)
		(mid 79.169578 -287.292011)
		(end 78.899512 -287.368996)
		(width 0.0889)
		(layer "In2.Cu")
		(net "M_C_CPU1_SB_DQ<20>")
	)
	(arc
		(start 79.821024 -287.37941)
		(mid 79.642751 -287.418806)
		(end 79.467202 -287.368742)
		(width 0.0889)
		(layer "In2.Cu")
		(net "M_C_CPU1_SB_DQ<20>")
	)
	(segment
		(start 96.568006 -274.630388)
		(end 96.101154 -274.896326)
		(width 0.10668)
		(layer "F.Cu")
		(net "M_C_CPU1_SB_DQ<1>")
	)
	(segment
		(start 63.894208 -279.43429)
		(end 64.057276 -279.271222)
		(width 0.14478)
		(layer "In2.Cu")
		(net "M_C_CPU1_SB_DQ<1>")
	)
	(segment
		(start 64.005714 -280.333196)
		(end 64.168782 -280.170128)
		(width 0.14478)
		(layer "In2.Cu")
		(net "M_C_CPU1_SB_DQ<1>")
	)
	(segment
		(start 56.32196 -283.308044)
		(end 56.62422 -283.610304)
		(width 0.14478)
		(layer "In2.Cu")
		(net "M_C_CPU1_SB_DQ<1>")
	)
	(segment
		(start 50.638202 -282.505404)
		(end 50.939954 -282.505404)
		(width 0.14478)
		(layer "In2.Cu")
		(net "M_C_CPU1_SB_DQ<1>")
	)
	(segment
		(start 82.179668 -275.223732)
		(end 82.18805 -275.218906)
		(width 0.0889)
		(layer "In2.Cu")
		(net "M_C_CPU1_SB_DQ<1>")
	)
	(segment
		(start 80.299814 -275.223732)
		(end 80.308196 -275.218906)
		(width 0.0889)
		(layer "In2.Cu")
		(net "M_C_CPU1_SB_DQ<1>")
	)
	(segment
		(start 65.904364 -278.491442)
		(end 70.266052 -274.129754)
		(width 0.14478)
		(layer "In2.Cu")
		(net "M_C_CPU1_SB_DQ<1>")
	)
	(segment
		(start 56.8071 -283.610304)
		(end 57.657238 -282.760166)
		(width 0.14478)
		(layer "In2.Cu")
		(net "M_C_CPU1_SB_DQ<1>")
	)
	(segment
		(start 79.367126 -275.218906)
		(end 79.381858 -275.21027)
		(width 0.0889)
		(layer "In2.Cu")
		(net "M_C_CPU1_SB_DQ<1>")
	)
	(segment
		(start 63.24854 -280.058622)
		(end 63.500508 -280.058622)
		(width 0.14478)
		(layer "In2.Cu")
		(net "M_C_CPU1_SB_DQ<1>")
	)
	(segment
		(start 64.837056 -278.491442)
		(end 65.904364 -278.491442)
		(width 0.14478)
		(layer "In2.Cu")
		(net "M_C_CPU1_SB_DQ<1>")
	)
	(segment
		(start 58.055002 -282.760166)
		(end 58.363104 -282.452064)
		(width 0.14478)
		(layer "In2.Cu")
		(net "M_C_CPU1_SB_DQ<1>")
	)
	(segment
		(start 49.066958 -283.610304)
		(end 49.917096 -282.760166)
		(width 0.14478)
		(layer "In2.Cu")
		(net "M_C_CPU1_SB_DQ<1>")
	)
	(segment
		(start 64.562482 -279.545796)
		(end 64.793114 -279.545796)
		(width 0.14478)
		(layer "In2.Cu")
		(net "M_C_CPU1_SB_DQ<1>")
	)
	(segment
		(start 45.677074 -283.231844)
		(end 45.907706 -283.231844)
		(width 0.14478)
		(layer "In2.Cu")
		(net "M_C_CPU1_SB_DQ<1>")
	)
	(segment
		(start 75.953366 -274.129754)
		(end 76.414376 -274.129754)
		(width 0.0889)
		(layer "In2.Cu")
		(net "M_C_CPU1_SB_DQ<1>")
	)
	(segment
		(start 53.213508 -282.760166)
		(end 54.063646 -283.610304)
		(width 0.14478)
		(layer "In2.Cu")
		(net "M_C_CPU1_SB_DQ<1>")
	)
	(segment
		(start 46.07052 -283.394658)
		(end 46.07052 -283.80563)
		(width 0.14478)
		(layer "In2.Cu")
		(net "M_C_CPU1_SB_DQ<1>")
	)
	(segment
		(start 64.681608 -278.877522)
		(end 64.681608 -278.64689)
		(width 0.14478)
		(layer "In2.Cu")
		(net "M_C_CPU1_SB_DQ<1>")
	)
	(segment
		(start 64.057276 -279.271222)
		(end 64.287908 -279.271222)
		(width 0.14478)
		(layer "In2.Cu")
		(net "M_C_CPU1_SB_DQ<1>")
	)
	(segment
		(start 49.917096 -282.760166)
		(end 50.38344 -282.760166)
		(width 0.14478)
		(layer "In2.Cu")
		(net "M_C_CPU1_SB_DQ<1>")
	)
	(segment
		(start 58.611516 -282.452064)
		(end 58.919618 -282.760166)
		(width 0.14478)
		(layer "In2.Cu")
		(net "M_C_CPU1_SB_DQ<1>")
	)
	(segment
		(start 87.453978 -275.218906)
		(end 87.46236 -275.223732)
		(width 0.0889)
		(layer "In2.Cu")
		(net "M_C_CPU1_SB_DQ<1>")
	)
	(segment
		(start 78.970886 -275.205698)
		(end 79.007208 -275.226526)
		(width 0.0889)
		(layer "In2.Cu")
		(net "M_C_CPU1_SB_DQ<1>")
	)
	(segment
		(start 47.398686 -283.610304)
		(end 49.066958 -283.610304)
		(width 0.14478)
		(layer "In2.Cu")
		(net "M_C_CPU1_SB_DQ<1>")
	)
	(segment
		(start 60.546996 -282.760166)
		(end 63.24854 -280.058622)
		(width 0.14478)
		(layer "In2.Cu")
		(net "M_C_CPU1_SB_DQ<1>")
	)
	(segment
		(start 63.894208 -279.664922)
		(end 63.894208 -279.43429)
		(width 0.14478)
		(layer "In2.Cu")
		(net "M_C_CPU1_SB_DQ<1>")
	)
	(segment
		(start 76.542646 -274.258024)
		(end 77.502766 -274.258024)
		(width 0.0889)
		(layer "In2.Cu")
		(net "M_C_CPU1_SB_DQ<1>")
	)
	(segment
		(start 54.063646 -283.610304)
		(end 55.765446 -283.610304)
		(width 0.14478)
		(layer "In2.Cu")
		(net "M_C_CPU1_SB_DQ<1>")
	)
	(segment
		(start 83.694016 -275.218906)
		(end 83.702398 -275.223732)
		(width 0.0889)
		(layer "In2.Cu")
		(net "M_C_CPU1_SB_DQ<1>")
	)
	(segment
		(start 77.502766 -274.258024)
		(end 78.381098 -275.136356)
		(width 0.0889)
		(layer "In2.Cu")
		(net "M_C_CPU1_SB_DQ<1>")
	)
	(segment
		(start 91.5797 -275.223732)
		(end 91.588082 -275.218906)
		(width 0.0889)
		(layer "In2.Cu")
		(net "M_C_CPU1_SB_DQ<1>")
	)
	(segment
		(start 92.153994 -275.218906)
		(end 92.162376 -275.223732)
		(width 0.0889)
		(layer "In2.Cu")
		(net "M_C_CPU1_SB_DQ<1>")
	)
	(segment
		(start 51.194716 -282.760166)
		(end 53.213508 -282.760166)
		(width 0.14478)
		(layer "In2.Cu")
		(net "M_C_CPU1_SB_DQ<1>")
	)
	(segment
		(start 47.020226 -283.231844)
		(end 47.398686 -283.610304)
		(width 0.14478)
		(layer "In2.Cu")
		(net "M_C_CPU1_SB_DQ<1>")
	)
	(segment
		(start 63.775082 -280.333196)
		(end 64.005714 -280.333196)
		(width 0.14478)
		(layer "In2.Cu")
		(net "M_C_CPU1_SB_DQ<1>")
	)
	(segment
		(start 70.266052 -274.129754)
		(end 75.953366 -274.129754)
		(width 0.14478)
		(layer "In2.Cu")
		(net "M_C_CPU1_SB_DQ<1>")
	)
	(segment
		(start 64.793114 -279.545796)
		(end 64.956182 -279.382728)
		(width 0.14478)
		(layer "In2.Cu")
		(net "M_C_CPU1_SB_DQ<1>")
	)
	(segment
		(start 50.38344 -282.760166)
		(end 50.638202 -282.505404)
		(width 0.14478)
		(layer "In2.Cu")
		(net "M_C_CPU1_SB_DQ<1>")
	)
	(segment
		(start 78.381098 -275.136356)
		(end 78.711044 -275.136356)
		(width 0.0889)
		(layer "In2.Cu")
		(net "M_C_CPU1_SB_DQ<1>")
	)
	(segment
		(start 46.789594 -283.231844)
		(end 47.020226 -283.231844)
		(width 0.14478)
		(layer "In2.Cu")
		(net "M_C_CPU1_SB_DQ<1>")
	)
	(segment
		(start 64.956182 -279.152096)
		(end 64.681608 -278.877522)
		(width 0.14478)
		(layer "In2.Cu")
		(net "M_C_CPU1_SB_DQ<1>")
	)
	(segment
		(start 82.753962 -275.218906)
		(end 82.762344 -275.223732)
		(width 0.0889)
		(layer "In2.Cu")
		(net "M_C_CPU1_SB_DQ<1>")
	)
	(segment
		(start 44.736004 -283.581348)
		(end 45.32757 -283.581348)
		(width 0.14478)
		(layer "In2.Cu")
		(net "M_C_CPU1_SB_DQ<1>")
	)
	(segment
		(start 56.62422 -283.610304)
		(end 56.8071 -283.610304)
		(width 0.14478)
		(layer "In2.Cu")
		(net "M_C_CPU1_SB_DQ<1>")
	)
	(segment
		(start 46.62678 -283.80563)
		(end 46.62678 -283.394658)
		(width 0.14478)
		(layer "In2.Cu")
		(net "M_C_CPU1_SB_DQ<1>")
	)
	(segment
		(start 56.067706 -283.308044)
		(end 56.32196 -283.308044)
		(width 0.14478)
		(layer "In2.Cu")
		(net "M_C_CPU1_SB_DQ<1>")
	)
	(segment
		(start 63.500508 -280.058622)
		(end 63.775082 -280.333196)
		(width 0.14478)
		(layer "In2.Cu")
		(net "M_C_CPU1_SB_DQ<1>")
	)
	(segment
		(start 58.363104 -282.452064)
		(end 58.611516 -282.452064)
		(width 0.14478)
		(layer "In2.Cu")
		(net "M_C_CPU1_SB_DQ<1>")
	)
	(segment
		(start 76.414376 -274.129754)
		(end 76.542646 -274.258024)
		(width 0.0889)
		(layer "In2.Cu")
		(net "M_C_CPU1_SB_DQ<1>")
	)
	(segment
		(start 85.93963 -275.223732)
		(end 85.948012 -275.218906)
		(width 0.0889)
		(layer "In2.Cu")
		(net "M_C_CPU1_SB_DQ<1>")
	)
	(segment
		(start 46.62678 -283.394658)
		(end 46.789594 -283.231844)
		(width 0.14478)
		(layer "In2.Cu")
		(net "M_C_CPU1_SB_DQ<1>")
	)
	(segment
		(start 46.233334 -283.968444)
		(end 46.463966 -283.968444)
		(width 0.14478)
		(layer "In2.Cu")
		(net "M_C_CPU1_SB_DQ<1>")
	)
	(segment
		(start 55.765446 -283.610304)
		(end 56.067706 -283.308044)
		(width 0.14478)
		(layer "In2.Cu")
		(net "M_C_CPU1_SB_DQ<1>")
	)
	(segment
		(start 95.85071 -275.187156)
		(end 95.946976 -275.161756)
		(width 0.0889)
		(layer "In2.Cu")
		(net "M_C_CPU1_SB_DQ<1>")
	)
	(segment
		(start 44.340018 -283.185362)
		(end 44.736004 -283.581348)
		(width 0.14478)
		(layer "In2.Cu")
		(net "M_C_CPU1_SB_DQ<1>")
	)
	(segment
		(start 95.339662 -275.223732)
		(end 95.348044 -275.218906)
		(width 0.0889)
		(layer "In2.Cu")
		(net "M_C_CPU1_SB_DQ<1>")
	)
	(segment
		(start 86.879684 -275.223732)
		(end 86.888066 -275.218906)
		(width 0.0889)
		(layer "In2.Cu")
		(net "M_C_CPU1_SB_DQ<1>")
	)
	(segment
		(start 95.946976 -275.161756)
		(end 96.101154 -274.896326)
		(width 0.0889)
		(layer "In2.Cu")
		(net "M_C_CPU1_SB_DQ<1>")
	)
	(segment
		(start 46.07052 -283.80563)
		(end 46.233334 -283.968444)
		(width 0.14478)
		(layer "In2.Cu")
		(net "M_C_CPU1_SB_DQ<1>")
	)
	(segment
		(start 50.939954 -282.505404)
		(end 51.194716 -282.760166)
		(width 0.14478)
		(layer "In2.Cu")
		(net "M_C_CPU1_SB_DQ<1>")
	)
	(segment
		(start 88.394032 -275.218906)
		(end 88.402414 -275.223732)
		(width 0.0889)
		(layer "In2.Cu")
		(net "M_C_CPU1_SB_DQ<1>")
	)
	(segment
		(start 45.32757 -283.581348)
		(end 45.677074 -283.231844)
		(width 0.14478)
		(layer "In2.Cu")
		(net "M_C_CPU1_SB_DQ<1>")
	)
	(segment
		(start 64.681608 -278.64689)
		(end 64.837056 -278.491442)
		(width 0.14478)
		(layer "In2.Cu")
		(net "M_C_CPU1_SB_DQ<1>")
	)
	(segment
		(start 90.639646 -275.223732)
		(end 90.648028 -275.218906)
		(width 0.0889)
		(layer "In2.Cu")
		(net "M_C_CPU1_SB_DQ<1>")
	)
	(segment
		(start 64.287908 -279.271222)
		(end 64.562482 -279.545796)
		(width 0.14478)
		(layer "In2.Cu")
		(net "M_C_CPU1_SB_DQ<1>")
	)
	(segment
		(start 64.168782 -279.939496)
		(end 63.894208 -279.664922)
		(width 0.14478)
		(layer "In2.Cu")
		(net "M_C_CPU1_SB_DQ<1>")
	)
	(segment
		(start 45.907706 -283.231844)
		(end 46.07052 -283.394658)
		(width 0.14478)
		(layer "In2.Cu")
		(net "M_C_CPU1_SB_DQ<1>")
	)
	(segment
		(start 64.168782 -280.170128)
		(end 64.168782 -279.939496)
		(width 0.14478)
		(layer "In2.Cu")
		(net "M_C_CPU1_SB_DQ<1>")
	)
	(segment
		(start 57.657238 -282.760166)
		(end 58.055002 -282.760166)
		(width 0.14478)
		(layer "In2.Cu")
		(net "M_C_CPU1_SB_DQ<1>")
	)
	(segment
		(start 93.094048 -275.218906)
		(end 93.10243 -275.223732)
		(width 0.0889)
		(layer "In2.Cu")
		(net "M_C_CPU1_SB_DQ<1>")
	)
	(segment
		(start 46.463966 -283.968444)
		(end 46.62678 -283.80563)
		(width 0.14478)
		(layer "In2.Cu")
		(net "M_C_CPU1_SB_DQ<1>")
	)
	(segment
		(start 64.956182 -279.382728)
		(end 64.956182 -279.152096)
		(width 0.14478)
		(layer "In2.Cu")
		(net "M_C_CPU1_SB_DQ<1>")
	)
	(segment
		(start 58.919618 -282.760166)
		(end 60.546996 -282.760166)
		(width 0.14478)
		(layer "In2.Cu")
		(net "M_C_CPU1_SB_DQ<1>")
	)
	(arc
		(start 84.068158 -275.218906)
		(mid 84.351114 -275.142729)
		(end 84.63407 -275.218906)
		(width 0.0889)
		(layer "In2.Cu")
		(net "M_C_CPU1_SB_DQ<1>")
	)
	(arc
		(start 84.63407 -275.218906)
		(mid 84.821014 -275.269161)
		(end 85.007958 -275.218906)
		(width 0.0889)
		(layer "In2.Cu")
		(net "M_C_CPU1_SB_DQ<1>")
	)
	(arc
		(start 81.247996 -275.218906)
		(mid 81.530952 -275.142729)
		(end 81.813908 -275.218906)
		(width 0.0889)
		(layer "In2.Cu")
		(net "M_C_CPU1_SB_DQ<1>")
	)
	(arc
		(start 82.762344 -275.223732)
		(mid 82.945852 -275.269226)
		(end 83.128104 -275.218906)
		(width 0.0889)
		(layer "In2.Cu")
		(net "M_C_CPU1_SB_DQ<1>")
	)
	(arc
		(start 91.588082 -275.218906)
		(mid 91.871038 -275.142729)
		(end 92.153994 -275.218906)
		(width 0.0889)
		(layer "In2.Cu")
		(net "M_C_CPU1_SB_DQ<1>")
	)
	(arc
		(start 89.707974 -275.218906)
		(mid 89.99093 -275.142729)
		(end 90.273886 -275.218906)
		(width 0.0889)
		(layer "In2.Cu")
		(net "M_C_CPU1_SB_DQ<1>")
	)
	(arc
		(start 85.007958 -275.218906)
		(mid 85.290914 -275.142729)
		(end 85.57387 -275.218906)
		(width 0.0889)
		(layer "In2.Cu")
		(net "M_C_CPU1_SB_DQ<1>")
	)
	(arc
		(start 88.402414 -275.223732)
		(mid 88.585922 -275.269226)
		(end 88.768174 -275.218906)
		(width 0.0889)
		(layer "In2.Cu")
		(net "M_C_CPU1_SB_DQ<1>")
	)
	(arc
		(start 83.702398 -275.223732)
		(mid 83.885906 -275.269226)
		(end 84.068158 -275.218906)
		(width 0.0889)
		(layer "In2.Cu")
		(net "M_C_CPU1_SB_DQ<1>")
	)
	(arc
		(start 79.933546 -275.218906)
		(mid 80.116051 -275.269383)
		(end 80.299814 -275.223732)
		(width 0.0889)
		(layer "In2.Cu")
		(net "M_C_CPU1_SB_DQ<1>")
	)
	(arc
		(start 78.711044 -275.136356)
		(mid 78.845515 -275.153984)
		(end 78.970886 -275.205698)
		(width 0.0889)
		(layer "In2.Cu")
		(net "M_C_CPU1_SB_DQ<1>")
	)
	(arc
		(start 85.948012 -275.218906)
		(mid 86.230968 -275.142729)
		(end 86.513924 -275.218906)
		(width 0.0889)
		(layer "In2.Cu")
		(net "M_C_CPU1_SB_DQ<1>")
	)
	(arc
		(start 79.007208 -275.226526)
		(mid 79.188138 -275.269004)
		(end 79.367126 -275.218906)
		(width 0.0889)
		(layer "In2.Cu")
		(net "M_C_CPU1_SB_DQ<1>")
	)
	(arc
		(start 80.308196 -275.218906)
		(mid 80.591152 -275.142729)
		(end 80.874108 -275.218906)
		(width 0.0889)
		(layer "In2.Cu")
		(net "M_C_CPU1_SB_DQ<1>")
	)
	(arc
		(start 86.888066 -275.218906)
		(mid 87.171022 -275.142729)
		(end 87.453978 -275.218906)
		(width 0.0889)
		(layer "In2.Cu")
		(net "M_C_CPU1_SB_DQ<1>")
	)
	(arc
		(start 94.973902 -275.218906)
		(mid 95.156153 -275.269256)
		(end 95.339662 -275.223732)
		(width 0.0889)
		(layer "In2.Cu")
		(net "M_C_CPU1_SB_DQ<1>")
	)
	(arc
		(start 83.128104 -275.218906)
		(mid 83.41106 -275.142729)
		(end 83.694016 -275.218906)
		(width 0.0889)
		(layer "In2.Cu")
		(net "M_C_CPU1_SB_DQ<1>")
	)
	(arc
		(start 80.874108 -275.218906)
		(mid 81.061052 -275.269161)
		(end 81.247996 -275.218906)
		(width 0.0889)
		(layer "In2.Cu")
		(net "M_C_CPU1_SB_DQ<1>")
	)
	(arc
		(start 87.82812 -275.218906)
		(mid 88.111076 -275.142729)
		(end 88.394032 -275.218906)
		(width 0.0889)
		(layer "In2.Cu")
		(net "M_C_CPU1_SB_DQ<1>")
	)
	(arc
		(start 95.348044 -275.218906)
		(mid 95.59564 -275.143728)
		(end 95.85071 -275.187156)
		(width 0.0889)
		(layer "In2.Cu")
		(net "M_C_CPU1_SB_DQ<1>")
	)
	(arc
		(start 94.40799 -275.218906)
		(mid 94.690946 -275.142729)
		(end 94.973902 -275.218906)
		(width 0.0889)
		(layer "In2.Cu")
		(net "M_C_CPU1_SB_DQ<1>")
	)
	(arc
		(start 93.10243 -275.223732)
		(mid 93.285938 -275.269226)
		(end 93.46819 -275.218906)
		(width 0.0889)
		(layer "In2.Cu")
		(net "M_C_CPU1_SB_DQ<1>")
	)
	(arc
		(start 90.648028 -275.218906)
		(mid 90.930984 -275.142729)
		(end 91.21394 -275.218906)
		(width 0.0889)
		(layer "In2.Cu")
		(net "M_C_CPU1_SB_DQ<1>")
	)
	(arc
		(start 87.46236 -275.223732)
		(mid 87.645868 -275.269226)
		(end 87.82812 -275.218906)
		(width 0.0889)
		(layer "In2.Cu")
		(net "M_C_CPU1_SB_DQ<1>")
	)
	(arc
		(start 89.334086 -275.218906)
		(mid 89.52103 -275.269161)
		(end 89.707974 -275.218906)
		(width 0.0889)
		(layer "In2.Cu")
		(net "M_C_CPU1_SB_DQ<1>")
	)
	(arc
		(start 85.57387 -275.218906)
		(mid 85.756121 -275.269256)
		(end 85.93963 -275.223732)
		(width 0.0889)
		(layer "In2.Cu")
		(net "M_C_CPU1_SB_DQ<1>")
	)
	(arc
		(start 86.513924 -275.218906)
		(mid 86.696175 -275.269256)
		(end 86.879684 -275.223732)
		(width 0.0889)
		(layer "In2.Cu")
		(net "M_C_CPU1_SB_DQ<1>")
	)
	(arc
		(start 91.21394 -275.218906)
		(mid 91.396191 -275.269256)
		(end 91.5797 -275.223732)
		(width 0.0889)
		(layer "In2.Cu")
		(net "M_C_CPU1_SB_DQ<1>")
	)
	(arc
		(start 90.273886 -275.218906)
		(mid 90.456137 -275.269256)
		(end 90.639646 -275.223732)
		(width 0.0889)
		(layer "In2.Cu")
		(net "M_C_CPU1_SB_DQ<1>")
	)
	(arc
		(start 88.768174 -275.218906)
		(mid 89.05113 -275.142729)
		(end 89.334086 -275.218906)
		(width 0.0889)
		(layer "In2.Cu")
		(net "M_C_CPU1_SB_DQ<1>")
	)
	(arc
		(start 94.034102 -275.218906)
		(mid 94.221046 -275.269161)
		(end 94.40799 -275.218906)
		(width 0.0889)
		(layer "In2.Cu")
		(net "M_C_CPU1_SB_DQ<1>")
	)
	(arc
		(start 92.162376 -275.223732)
		(mid 92.345884 -275.269226)
		(end 92.528136 -275.218906)
		(width 0.0889)
		(layer "In2.Cu")
		(net "M_C_CPU1_SB_DQ<1>")
	)
	(arc
		(start 81.813908 -275.218906)
		(mid 81.996159 -275.269256)
		(end 82.179668 -275.223732)
		(width 0.0889)
		(layer "In2.Cu")
		(net "M_C_CPU1_SB_DQ<1>")
	)
	(arc
		(start 93.46819 -275.218906)
		(mid 93.751146 -275.142729)
		(end 94.034102 -275.218906)
		(width 0.0889)
		(layer "In2.Cu")
		(net "M_C_CPU1_SB_DQ<1>")
	)
	(arc
		(start 92.528136 -275.218906)
		(mid 92.811092 -275.142729)
		(end 93.094048 -275.218906)
		(width 0.0889)
		(layer "In2.Cu")
		(net "M_C_CPU1_SB_DQ<1>")
	)
	(arc
		(start 79.381858 -275.21027)
		(mid 79.658841 -275.142466)
		(end 79.933546 -275.218906)
		(width 0.0889)
		(layer "In2.Cu")
		(net "M_C_CPU1_SB_DQ<1>")
	)
	(arc
		(start 82.18805 -275.218906)
		(mid 82.471006 -275.142729)
		(end 82.753962 -275.218906)
		(width 0.0889)
		(layer "In2.Cu")
		(net "M_C_CPU1_SB_DQ<1>")
	)
	(segment
		(start 96.097852 -285.160466)
		(end 95.631 -285.426404)
		(width 0.10668)
		(layer "F.Cu")
		(net "M_C_CPU1_SB_DQ<19>")
	)
	(segment
		(start 40.665146 -303.16043)
		(end 41.323768 -303.16043)
		(width 0.14478)
		(layer "In2.Cu")
		(net "M_C_CPU1_SB_DQ<19>")
	)
	(segment
		(start 53.442108 -302.30064)
		(end 54.301898 -303.16043)
		(width 0.14478)
		(layer "In2.Cu")
		(net "M_C_CPU1_SB_DQ<19>")
	)
	(segment
		(start 61.356494 -302.310292)
		(end 65.59804 -298.068746)
		(width 0.14478)
		(layer "In2.Cu")
		(net "M_C_CPU1_SB_DQ<19>")
	)
	(segment
		(start 81.344008 -285.103824)
		(end 81.35239 -285.098998)
		(width 0.0889)
		(layer "In2.Cu")
		(net "M_C_CPU1_SB_DQ<19>")
	)
	(segment
		(start 41.655492 -302.828706)
		(end 41.886124 -302.828706)
		(width 0.14478)
		(layer "In2.Cu")
		(net "M_C_CPU1_SB_DQ<19>")
	)
	(segment
		(start 76.669646 -285.614364)
		(end 77.486764 -285.614364)
		(width 0.0889)
		(layer "In2.Cu")
		(net "M_C_CPU1_SB_DQ<19>")
	)
	(segment
		(start 80.769714 -285.098998)
		(end 80.778096 -285.103824)
		(width 0.0889)
		(layer "In2.Cu")
		(net "M_C_CPU1_SB_DQ<19>")
	)
	(segment
		(start 54.301898 -303.16043)
		(end 56.759094 -303.16043)
		(width 0.14478)
		(layer "In2.Cu")
		(net "M_C_CPU1_SB_DQ<19>")
	)
	(segment
		(start 89.803986 -285.103824)
		(end 89.812368 -285.098998)
		(width 0.0889)
		(layer "In2.Cu")
		(net "M_C_CPU1_SB_DQ<19>")
	)
	(segment
		(start 76.446126 -285.837884)
		(end 76.669646 -285.614364)
		(width 0.0889)
		(layer "In2.Cu")
		(net "M_C_CPU1_SB_DQ<19>")
	)
	(segment
		(start 85.10397 -285.103824)
		(end 85.112352 -285.098998)
		(width 0.0889)
		(layer "In2.Cu")
		(net "M_C_CPU1_SB_DQ<19>")
	)
	(segment
		(start 89.229692 -285.098998)
		(end 89.238074 -285.103824)
		(width 0.0889)
		(layer "In2.Cu")
		(net "M_C_CPU1_SB_DQ<19>")
	)
	(segment
		(start 70.040246 -291.549836)
		(end 75.752198 -285.837884)
		(width 0.14478)
		(layer "In2.Cu")
		(net "M_C_CPU1_SB_DQ<19>")
	)
	(segment
		(start 70.040246 -294.89908)
		(end 70.040246 -291.549836)
		(width 0.14478)
		(layer "In2.Cu")
		(net "M_C_CPU1_SB_DQ<19>")
	)
	(segment
		(start 93.929708 -285.098998)
		(end 93.93809 -285.103824)
		(width 0.0889)
		(layer "In2.Cu")
		(net "M_C_CPU1_SB_DQ<19>")
	)
	(segment
		(start 40.23995 -302.735234)
		(end 40.665146 -303.16043)
		(width 0.14478)
		(layer "In2.Cu")
		(net "M_C_CPU1_SB_DQ<19>")
	)
	(segment
		(start 88.289638 -285.098998)
		(end 88.29802 -285.103824)
		(width 0.0889)
		(layer "In2.Cu")
		(net "M_C_CPU1_SB_DQ<19>")
	)
	(segment
		(start 95.762826 -285.077662)
		(end 95.785178 -285.160974)
		(width 0.0889)
		(layer "In2.Cu")
		(net "M_C_CPU1_SB_DQ<19>")
	)
	(segment
		(start 95.444056 -285.103824)
		(end 95.452438 -285.098998)
		(width 0.0889)
		(layer "In2.Cu")
		(net "M_C_CPU1_SB_DQ<19>")
	)
	(segment
		(start 86.044024 -285.103824)
		(end 86.052406 -285.098998)
		(width 0.0889)
		(layer "In2.Cu")
		(net "M_C_CPU1_SB_DQ<19>")
	)
	(segment
		(start 75.953366 -285.837884)
		(end 76.446126 -285.837884)
		(width 0.0889)
		(layer "In2.Cu")
		(net "M_C_CPU1_SB_DQ<19>")
	)
	(segment
		(start 65.59804 -298.068746)
		(end 66.87058 -298.068746)
		(width 0.14478)
		(layer "In2.Cu")
		(net "M_C_CPU1_SB_DQ<19>")
	)
	(segment
		(start 79.463138 -285.103824)
		(end 79.474822 -285.096966)
		(width 0.0889)
		(layer "In2.Cu")
		(net "M_C_CPU1_SB_DQ<19>")
	)
	(segment
		(start 90.74404 -285.103824)
		(end 90.752422 -285.098998)
		(width 0.0889)
		(layer "In2.Cu")
		(net "M_C_CPU1_SB_DQ<19>")
	)
	(segment
		(start 78.663292 -285.053024)
		(end 78.711044 -285.053024)
		(width 0.0889)
		(layer "In2.Cu")
		(net "M_C_CPU1_SB_DQ<19>")
	)
	(segment
		(start 56.759094 -303.16043)
		(end 57.609232 -302.310292)
		(width 0.14478)
		(layer "In2.Cu")
		(net "M_C_CPU1_SB_DQ<19>")
	)
	(segment
		(start 41.323768 -303.16043)
		(end 41.655492 -302.828706)
		(width 0.14478)
		(layer "In2.Cu")
		(net "M_C_CPU1_SB_DQ<19>")
	)
	(segment
		(start 92.989654 -285.098998)
		(end 92.998036 -285.103824)
		(width 0.0889)
		(layer "In2.Cu")
		(net "M_C_CPU1_SB_DQ<19>")
	)
	(segment
		(start 80.389222 -285.11246)
		(end 80.403954 -285.103824)
		(width 0.0889)
		(layer "In2.Cu")
		(net "M_C_CPU1_SB_DQ<19>")
	)
	(segment
		(start 42.207942 -303.150524)
		(end 49.40808 -303.150524)
		(width 0.14478)
		(layer "In2.Cu")
		(net "M_C_CPU1_SB_DQ<19>")
	)
	(segment
		(start 41.886124 -302.828706)
		(end 42.207942 -303.150524)
		(width 0.14478)
		(layer "In2.Cu")
		(net "M_C_CPU1_SB_DQ<19>")
	)
	(segment
		(start 95.785178 -285.160974)
		(end 95.631 -285.426404)
		(width 0.0889)
		(layer "In2.Cu")
		(net "M_C_CPU1_SB_DQ<19>")
	)
	(segment
		(start 50.257964 -302.30064)
		(end 53.442108 -302.30064)
		(width 0.14478)
		(layer "In2.Cu")
		(net "M_C_CPU1_SB_DQ<19>")
	)
	(segment
		(start 75.752198 -285.837884)
		(end 75.953366 -285.837884)
		(width 0.14478)
		(layer "In2.Cu")
		(net "M_C_CPU1_SB_DQ<19>")
	)
	(segment
		(start 66.87058 -298.068746)
		(end 70.040246 -294.89908)
		(width 0.14478)
		(layer "In2.Cu")
		(net "M_C_CPU1_SB_DQ<19>")
	)
	(segment
		(start 94.504002 -285.103824)
		(end 94.512384 -285.098998)
		(width 0.0889)
		(layer "In2.Cu")
		(net "M_C_CPU1_SB_DQ<19>")
	)
	(segment
		(start 57.609232 -302.310292)
		(end 61.356494 -302.310292)
		(width 0.14478)
		(layer "In2.Cu")
		(net "M_C_CPU1_SB_DQ<19>")
	)
	(segment
		(start 49.40808 -303.150524)
		(end 50.257964 -302.30064)
		(width 0.14478)
		(layer "In2.Cu")
		(net "M_C_CPU1_SB_DQ<19>")
	)
	(segment
		(start 83.589622 -285.098998)
		(end 83.598004 -285.103824)
		(width 0.0889)
		(layer "In2.Cu")
		(net "M_C_CPU1_SB_DQ<19>")
	)
	(segment
		(start 84.529676 -285.098998)
		(end 84.538058 -285.103824)
		(width 0.0889)
		(layer "In2.Cu")
		(net "M_C_CPU1_SB_DQ<19>")
	)
	(segment
		(start 77.486764 -285.614364)
		(end 78.57744 -285.07309)
		(width 0.0889)
		(layer "In2.Cu")
		(net "M_C_CPU1_SB_DQ<19>")
	)
	(arc
		(start 78.903322 -285.10738)
		(mid 79.183711 -285.180049)
		(end 79.463138 -285.103824)
		(width 0.0889)
		(layer "In2.Cu")
		(net "M_C_CPU1_SB_DQ<19>")
	)
	(arc
		(start 89.812368 -285.098998)
		(mid 89.995876 -285.053504)
		(end 90.178128 -285.103824)
		(width 0.0889)
		(layer "In2.Cu")
		(net "M_C_CPU1_SB_DQ<19>")
	)
	(arc
		(start 94.878144 -285.103824)
		(mid 95.1611 -285.180001)
		(end 95.444056 -285.103824)
		(width 0.0889)
		(layer "In2.Cu")
		(net "M_C_CPU1_SB_DQ<19>")
	)
	(arc
		(start 92.998036 -285.103824)
		(mid 93.280992 -285.180001)
		(end 93.563948 -285.103824)
		(width 0.0889)
		(layer "In2.Cu")
		(net "M_C_CPU1_SB_DQ<19>")
	)
	(arc
		(start 88.29802 -285.103824)
		(mid 88.580976 -285.180001)
		(end 88.863932 -285.103824)
		(width 0.0889)
		(layer "In2.Cu")
		(net "M_C_CPU1_SB_DQ<19>")
	)
	(arc
		(start 88.863932 -285.103824)
		(mid 89.046183 -285.053474)
		(end 89.229692 -285.098998)
		(width 0.0889)
		(layer "In2.Cu")
		(net "M_C_CPU1_SB_DQ<19>")
	)
	(arc
		(start 83.598004 -285.103824)
		(mid 83.88096 -285.180001)
		(end 84.163916 -285.103824)
		(width 0.0889)
		(layer "In2.Cu")
		(net "M_C_CPU1_SB_DQ<19>")
	)
	(arc
		(start 95.452438 -285.098998)
		(mid 95.605308 -285.054357)
		(end 95.762826 -285.077662)
		(width 0.0889)
		(layer "In2.Cu")
		(net "M_C_CPU1_SB_DQ<19>")
	)
	(arc
		(start 90.752422 -285.098998)
		(mid 90.93593 -285.053504)
		(end 91.118182 -285.103824)
		(width 0.0889)
		(layer "In2.Cu")
		(net "M_C_CPU1_SB_DQ<19>")
	)
	(arc
		(start 86.418166 -285.103824)
		(mid 86.701122 -285.180001)
		(end 86.984078 -285.103824)
		(width 0.0889)
		(layer "In2.Cu")
		(net "M_C_CPU1_SB_DQ<19>")
	)
	(arc
		(start 87.357966 -285.103824)
		(mid 87.640922 -285.180001)
		(end 87.923878 -285.103824)
		(width 0.0889)
		(layer "In2.Cu")
		(net "M_C_CPU1_SB_DQ<19>")
	)
	(arc
		(start 91.684094 -285.103824)
		(mid 91.871038 -285.053569)
		(end 92.057982 -285.103824)
		(width 0.0889)
		(layer "In2.Cu")
		(net "M_C_CPU1_SB_DQ<19>")
	)
	(arc
		(start 86.984078 -285.103824)
		(mid 87.171022 -285.053569)
		(end 87.357966 -285.103824)
		(width 0.0889)
		(layer "In2.Cu")
		(net "M_C_CPU1_SB_DQ<19>")
	)
	(arc
		(start 79.837534 -285.103824)
		(mid 80.11224 -285.180188)
		(end 80.389222 -285.11246)
		(width 0.0889)
		(layer "In2.Cu")
		(net "M_C_CPU1_SB_DQ<19>")
	)
	(arc
		(start 94.512384 -285.098998)
		(mid 94.695892 -285.053504)
		(end 94.878144 -285.103824)
		(width 0.0889)
		(layer "In2.Cu")
		(net "M_C_CPU1_SB_DQ<19>")
	)
	(arc
		(start 87.923878 -285.103824)
		(mid 88.106129 -285.053474)
		(end 88.289638 -285.098998)
		(width 0.0889)
		(layer "In2.Cu")
		(net "M_C_CPU1_SB_DQ<19>")
	)
	(arc
		(start 82.65795 -285.103824)
		(mid 82.940906 -285.180001)
		(end 83.223862 -285.103824)
		(width 0.0889)
		(layer "In2.Cu")
		(net "M_C_CPU1_SB_DQ<19>")
	)
	(arc
		(start 81.71815 -285.103824)
		(mid 82.001106 -285.180001)
		(end 82.284062 -285.103824)
		(width 0.0889)
		(layer "In2.Cu")
		(net "M_C_CPU1_SB_DQ<19>")
	)
	(arc
		(start 86.052406 -285.098998)
		(mid 86.235914 -285.053504)
		(end 86.418166 -285.103824)
		(width 0.0889)
		(layer "In2.Cu")
		(net "M_C_CPU1_SB_DQ<19>")
	)
	(arc
		(start 90.178128 -285.103824)
		(mid 90.461084 -285.180001)
		(end 90.74404 -285.103824)
		(width 0.0889)
		(layer "In2.Cu")
		(net "M_C_CPU1_SB_DQ<19>")
	)
	(arc
		(start 82.284062 -285.103824)
		(mid 82.471006 -285.053569)
		(end 82.65795 -285.103824)
		(width 0.0889)
		(layer "In2.Cu")
		(net "M_C_CPU1_SB_DQ<19>")
	)
	(arc
		(start 92.057982 -285.103824)
		(mid 92.340938 -285.180001)
		(end 92.623894 -285.103824)
		(width 0.0889)
		(layer "In2.Cu")
		(net "M_C_CPU1_SB_DQ<19>")
	)
	(arc
		(start 84.538058 -285.103824)
		(mid 84.821014 -285.180001)
		(end 85.10397 -285.103824)
		(width 0.0889)
		(layer "In2.Cu")
		(net "M_C_CPU1_SB_DQ<19>")
	)
	(arc
		(start 91.118182 -285.103824)
		(mid 91.401138 -285.180001)
		(end 91.684094 -285.103824)
		(width 0.0889)
		(layer "In2.Cu")
		(net "M_C_CPU1_SB_DQ<19>")
	)
	(arc
		(start 78.57744 -285.07309)
		(mid 78.619202 -285.058073)
		(end 78.663292 -285.053024)
		(width 0.0889)
		(layer "In2.Cu")
		(net "M_C_CPU1_SB_DQ<19>")
	)
	(arc
		(start 89.238074 -285.103824)
		(mid 89.52103 -285.180001)
		(end 89.803986 -285.103824)
		(width 0.0889)
		(layer "In2.Cu")
		(net "M_C_CPU1_SB_DQ<19>")
	)
	(arc
		(start 80.778096 -285.103824)
		(mid 81.061052 -285.180001)
		(end 81.344008 -285.103824)
		(width 0.0889)
		(layer "In2.Cu")
		(net "M_C_CPU1_SB_DQ<19>")
	)
	(arc
		(start 80.403954 -285.103824)
		(mid 80.586205 -285.053474)
		(end 80.769714 -285.098998)
		(width 0.0889)
		(layer "In2.Cu")
		(net "M_C_CPU1_SB_DQ<19>")
	)
	(arc
		(start 84.163916 -285.103824)
		(mid 84.346167 -285.053474)
		(end 84.529676 -285.098998)
		(width 0.0889)
		(layer "In2.Cu")
		(net "M_C_CPU1_SB_DQ<19>")
	)
	(arc
		(start 85.478112 -285.103824)
		(mid 85.761068 -285.180001)
		(end 86.044024 -285.103824)
		(width 0.0889)
		(layer "In2.Cu")
		(net "M_C_CPU1_SB_DQ<19>")
	)
	(arc
		(start 79.474822 -285.096966)
		(mid 79.657077 -285.053313)
		(end 79.837534 -285.103824)
		(width 0.0889)
		(layer "In2.Cu")
		(net "M_C_CPU1_SB_DQ<19>")
	)
	(arc
		(start 93.563948 -285.103824)
		(mid 93.746199 -285.053474)
		(end 93.929708 -285.098998)
		(width 0.0889)
		(layer "In2.Cu")
		(net "M_C_CPU1_SB_DQ<19>")
	)
	(arc
		(start 92.623894 -285.103824)
		(mid 92.806145 -285.053474)
		(end 92.989654 -285.098998)
		(width 0.0889)
		(layer "In2.Cu")
		(net "M_C_CPU1_SB_DQ<19>")
	)
	(arc
		(start 81.35239 -285.098998)
		(mid 81.535898 -285.053504)
		(end 81.71815 -285.103824)
		(width 0.0889)
		(layer "In2.Cu")
		(net "M_C_CPU1_SB_DQ<19>")
	)
	(arc
		(start 78.711044 -285.053024)
		(mid 78.810898 -285.067067)
		(end 78.903322 -285.10738)
		(width 0.0889)
		(layer "In2.Cu")
		(net "M_C_CPU1_SB_DQ<19>")
	)
	(arc
		(start 93.93809 -285.103824)
		(mid 94.221046 -285.180001)
		(end 94.504002 -285.103824)
		(width 0.0889)
		(layer "In2.Cu")
		(net "M_C_CPU1_SB_DQ<19>")
	)
	(arc
		(start 83.223862 -285.103824)
		(mid 83.406113 -285.053474)
		(end 83.589622 -285.098998)
		(width 0.0889)
		(layer "In2.Cu")
		(net "M_C_CPU1_SB_DQ<19>")
	)
	(arc
		(start 85.112352 -285.098998)
		(mid 85.29586 -285.053504)
		(end 85.478112 -285.103824)
		(width 0.0889)
		(layer "In2.Cu")
		(net "M_C_CPU1_SB_DQ<19>")
	)
	(segment
		(start 94.687898 -284.35046)
		(end 94.221046 -284.616398)
		(width 0.10668)
		(layer "F.Cu")
		(net "M_C_CPU1_SB_DQ<18>")
	)
	(segment
		(start 90.639646 -284.288992)
		(end 90.648028 -284.293818)
		(width 0.0889)
		(layer "In2.Cu")
		(net "M_C_CPU1_SB_DQ<18>")
	)
	(segment
		(start 94.37497 -284.350968)
		(end 94.221046 -284.616398)
		(width 0.0889)
		(layer "In2.Cu")
		(net "M_C_CPU1_SB_DQ<18>")
	)
	(segment
		(start 42.4688 -301.460408)
		(end 42.631614 -301.297594)
		(width 0.14478)
		(layer "In2.Cu")
		(net "M_C_CPU1_SB_DQ<18>")
	)
	(segment
		(start 53.093112 -300.61027)
		(end 53.94325 -301.460408)
		(width 0.14478)
		(layer "In2.Cu")
		(net "M_C_CPU1_SB_DQ<18>")
	)
	(segment
		(start 79.350616 -284.28188)
		(end 79.37119 -284.293818)
		(width 0.0889)
		(layer "In2.Cu")
		(net "M_C_CPU1_SB_DQ<18>")
	)
	(segment
		(start 87.453978 -284.293818)
		(end 87.46236 -284.288992)
		(width 0.0889)
		(layer "In2.Cu")
		(net "M_C_CPU1_SB_DQ<18>")
	)
	(segment
		(start 43.187874 -300.892718)
		(end 43.187874 -301.297594)
		(width 0.14478)
		(layer "In2.Cu")
		(net "M_C_CPU1_SB_DQ<18>")
	)
	(segment
		(start 42.075354 -300.892718)
		(end 42.075354 -301.297594)
		(width 0.14478)
		(layer "In2.Cu")
		(net "M_C_CPU1_SB_DQ<18>")
	)
	(segment
		(start 41.91254 -300.729904)
		(end 42.075354 -300.892718)
		(width 0.14478)
		(layer "In2.Cu")
		(net "M_C_CPU1_SB_DQ<18>")
	)
	(segment
		(start 78.97749 -284.304486)
		(end 78.995778 -284.293818)
		(width 0.0889)
		(layer "In2.Cu")
		(net "M_C_CPU1_SB_DQ<18>")
	)
	(segment
		(start 78.308454 -284.596078)
		(end 78.39837 -284.506162)
		(width 0.0889)
		(layer "In2.Cu")
		(net "M_C_CPU1_SB_DQ<18>")
	)
	(segment
		(start 41.519094 -301.297594)
		(end 41.519094 -300.892718)
		(width 0.14478)
		(layer "In2.Cu")
		(net "M_C_CPU1_SB_DQ<18>")
	)
	(segment
		(start 43.187874 -301.297594)
		(end 43.350688 -301.460408)
		(width 0.14478)
		(layer "In2.Cu")
		(net "M_C_CPU1_SB_DQ<18>")
	)
	(segment
		(start 57.112662 -301.460408)
		(end 57.9628 -300.61027)
		(width 0.14478)
		(layer "In2.Cu")
		(net "M_C_CPU1_SB_DQ<18>")
	)
	(segment
		(start 69.130926 -294.536114)
		(end 69.130926 -291.1475)
		(width 0.14478)
		(layer "In2.Cu")
		(net "M_C_CPU1_SB_DQ<18>")
	)
	(segment
		(start 83.694016 -284.293818)
		(end 83.702398 -284.288992)
		(width 0.0889)
		(layer "In2.Cu")
		(net "M_C_CPU1_SB_DQ<18>")
	)
	(segment
		(start 43.350688 -301.460408)
		(end 49.811686 -301.460408)
		(width 0.14478)
		(layer "In2.Cu")
		(net "M_C_CPU1_SB_DQ<18>")
	)
	(segment
		(start 49.811686 -301.460408)
		(end 50.661824 -300.61027)
		(width 0.14478)
		(layer "In2.Cu")
		(net "M_C_CPU1_SB_DQ<18>")
	)
	(segment
		(start 79.935324 -284.294072)
		(end 79.958692 -284.28061)
		(width 0.0889)
		(layer "In2.Cu")
		(net "M_C_CPU1_SB_DQ<18>")
	)
	(segment
		(start 57.9628 -300.61027)
		(end 61.75121 -300.61027)
		(width 0.14478)
		(layer "In2.Cu")
		(net "M_C_CPU1_SB_DQ<18>")
	)
	(segment
		(start 94.352618 -284.267656)
		(end 94.37497 -284.350968)
		(width 0.0889)
		(layer "In2.Cu")
		(net "M_C_CPU1_SB_DQ<18>")
	)
	(segment
		(start 93.094048 -284.293818)
		(end 93.10243 -284.288992)
		(width 0.0889)
		(layer "In2.Cu")
		(net "M_C_CPU1_SB_DQ<18>")
	)
	(segment
		(start 85.93963 -284.288992)
		(end 85.948012 -284.293818)
		(width 0.0889)
		(layer "In2.Cu")
		(net "M_C_CPU1_SB_DQ<18>")
	)
	(segment
		(start 86.879684 -284.288992)
		(end 86.888066 -284.293818)
		(width 0.0889)
		(layer "In2.Cu")
		(net "M_C_CPU1_SB_DQ<18>")
	)
	(segment
		(start 42.238168 -301.460408)
		(end 42.4688 -301.460408)
		(width 0.14478)
		(layer "In2.Cu")
		(net "M_C_CPU1_SB_DQ<18>")
	)
	(segment
		(start 61.75121 -300.61027)
		(end 66.03873 -296.32275)
		(width 0.14478)
		(layer "In2.Cu")
		(net "M_C_CPU1_SB_DQ<18>")
	)
	(segment
		(start 88.394032 -284.293818)
		(end 88.402414 -284.288992)
		(width 0.0889)
		(layer "In2.Cu")
		(net "M_C_CPU1_SB_DQ<18>")
	)
	(segment
		(start 75.931776 -284.923484)
		(end 77.518006 -284.923484)
		(width 0.0889)
		(layer "In2.Cu")
		(net "M_C_CPU1_SB_DQ<18>")
	)
	(segment
		(start 79.911448 -284.308042)
		(end 79.935324 -284.294072)
		(width 0.0889)
		(layer "In2.Cu")
		(net "M_C_CPU1_SB_DQ<18>")
	)
	(segment
		(start 41.681908 -300.729904)
		(end 41.91254 -300.729904)
		(width 0.14478)
		(layer "In2.Cu")
		(net "M_C_CPU1_SB_DQ<18>")
	)
	(segment
		(start 41.35628 -301.460408)
		(end 41.519094 -301.297594)
		(width 0.14478)
		(layer "In2.Cu")
		(net "M_C_CPU1_SB_DQ<18>")
	)
	(segment
		(start 53.94325 -301.460408)
		(end 57.112662 -301.460408)
		(width 0.14478)
		(layer "In2.Cu")
		(net "M_C_CPU1_SB_DQ<18>")
	)
	(segment
		(start 82.179668 -284.288992)
		(end 82.18805 -284.293818)
		(width 0.0889)
		(layer "In2.Cu")
		(net "M_C_CPU1_SB_DQ<18>")
	)
	(segment
		(start 42.631614 -301.297594)
		(end 42.631614 -300.892718)
		(width 0.14478)
		(layer "In2.Cu")
		(net "M_C_CPU1_SB_DQ<18>")
	)
	(segment
		(start 82.753962 -284.293818)
		(end 82.762344 -284.288992)
		(width 0.0889)
		(layer "In2.Cu")
		(net "M_C_CPU1_SB_DQ<18>")
	)
	(segment
		(start 40.23995 -301.035212)
		(end 40.665146 -301.460408)
		(width 0.14478)
		(layer "In2.Cu")
		(net "M_C_CPU1_SB_DQ<18>")
	)
	(segment
		(start 91.5797 -284.288992)
		(end 91.588082 -284.293818)
		(width 0.0889)
		(layer "In2.Cu")
		(net "M_C_CPU1_SB_DQ<18>")
	)
	(segment
		(start 41.519094 -300.892718)
		(end 41.681908 -300.729904)
		(width 0.14478)
		(layer "In2.Cu")
		(net "M_C_CPU1_SB_DQ<18>")
	)
	(segment
		(start 67.34429 -296.32275)
		(end 69.130926 -294.536114)
		(width 0.14478)
		(layer "In2.Cu")
		(net "M_C_CPU1_SB_DQ<18>")
	)
	(segment
		(start 43.02506 -300.729904)
		(end 43.187874 -300.892718)
		(width 0.14478)
		(layer "In2.Cu")
		(net "M_C_CPU1_SB_DQ<18>")
	)
	(segment
		(start 42.631614 -300.892718)
		(end 42.794428 -300.729904)
		(width 0.14478)
		(layer "In2.Cu")
		(net "M_C_CPU1_SB_DQ<18>")
	)
	(segment
		(start 69.130926 -291.1475)
		(end 75.354942 -284.923484)
		(width 0.14478)
		(layer "In2.Cu")
		(net "M_C_CPU1_SB_DQ<18>")
	)
	(segment
		(start 50.661824 -300.61027)
		(end 53.093112 -300.61027)
		(width 0.14478)
		(layer "In2.Cu")
		(net "M_C_CPU1_SB_DQ<18>")
	)
	(segment
		(start 66.03873 -296.32275)
		(end 67.34429 -296.32275)
		(width 0.14478)
		(layer "In2.Cu")
		(net "M_C_CPU1_SB_DQ<18>")
	)
	(segment
		(start 42.075354 -301.297594)
		(end 42.238168 -301.460408)
		(width 0.14478)
		(layer "In2.Cu")
		(net "M_C_CPU1_SB_DQ<18>")
	)
	(segment
		(start 40.665146 -301.460408)
		(end 41.35628 -301.460408)
		(width 0.14478)
		(layer "In2.Cu")
		(net "M_C_CPU1_SB_DQ<18>")
	)
	(segment
		(start 92.153994 -284.293818)
		(end 92.162376 -284.288992)
		(width 0.0889)
		(layer "In2.Cu")
		(net "M_C_CPU1_SB_DQ<18>")
	)
	(segment
		(start 75.354942 -284.923484)
		(end 75.931776 -284.923484)
		(width 0.14478)
		(layer "In2.Cu")
		(net "M_C_CPU1_SB_DQ<18>")
	)
	(segment
		(start 42.794428 -300.729904)
		(end 43.02506 -300.729904)
		(width 0.14478)
		(layer "In2.Cu")
		(net "M_C_CPU1_SB_DQ<18>")
	)
	(arc
		(start 84.068158 -284.293818)
		(mid 84.351114 -284.369995)
		(end 84.63407 -284.293818)
		(width 0.0889)
		(layer "In2.Cu")
		(net "M_C_CPU1_SB_DQ<18>")
	)
	(arc
		(start 93.10243 -284.288992)
		(mid 93.285938 -284.243498)
		(end 93.46819 -284.293818)
		(width 0.0889)
		(layer "In2.Cu")
		(net "M_C_CPU1_SB_DQ<18>")
	)
	(arc
		(start 80.874108 -284.293818)
		(mid 81.061052 -284.243563)
		(end 81.247996 -284.293818)
		(width 0.0889)
		(layer "In2.Cu")
		(net "M_C_CPU1_SB_DQ<18>")
	)
	(arc
		(start 83.128104 -284.293818)
		(mid 83.41106 -284.369995)
		(end 83.694016 -284.293818)
		(width 0.0889)
		(layer "In2.Cu")
		(net "M_C_CPU1_SB_DQ<18>")
	)
	(arc
		(start 80.308196 -284.293818)
		(mid 80.591152 -284.369995)
		(end 80.874108 -284.293818)
		(width 0.0889)
		(layer "In2.Cu")
		(net "M_C_CPU1_SB_DQ<18>")
	)
	(arc
		(start 91.21394 -284.293818)
		(mid 91.396191 -284.243468)
		(end 91.5797 -284.288992)
		(width 0.0889)
		(layer "In2.Cu")
		(net "M_C_CPU1_SB_DQ<18>")
	)
	(arc
		(start 93.46819 -284.293818)
		(mid 93.751146 -284.369995)
		(end 94.034102 -284.293818)
		(width 0.0889)
		(layer "In2.Cu")
		(net "M_C_CPU1_SB_DQ<18>")
	)
	(arc
		(start 86.888066 -284.293818)
		(mid 87.171022 -284.369995)
		(end 87.453978 -284.293818)
		(width 0.0889)
		(layer "In2.Cu")
		(net "M_C_CPU1_SB_DQ<18>")
	)
	(arc
		(start 87.82812 -284.293818)
		(mid 88.111076 -284.369995)
		(end 88.394032 -284.293818)
		(width 0.0889)
		(layer "In2.Cu")
		(net "M_C_CPU1_SB_DQ<18>")
	)
	(arc
		(start 85.007958 -284.293818)
		(mid 85.290914 -284.369995)
		(end 85.57387 -284.293818)
		(width 0.0889)
		(layer "In2.Cu")
		(net "M_C_CPU1_SB_DQ<18>")
	)
	(arc
		(start 78.39837 -284.506162)
		(mid 78.541826 -284.410308)
		(end 78.711044 -284.376622)
		(width 0.0889)
		(layer "In2.Cu")
		(net "M_C_CPU1_SB_DQ<18>")
	)
	(arc
		(start 90.648028 -284.293818)
		(mid 90.930984 -284.369995)
		(end 91.21394 -284.293818)
		(width 0.0889)
		(layer "In2.Cu")
		(net "M_C_CPU1_SB_DQ<18>")
	)
	(arc
		(start 89.334086 -284.293818)
		(mid 89.52103 -284.243563)
		(end 89.707974 -284.293818)
		(width 0.0889)
		(layer "In2.Cu")
		(net "M_C_CPU1_SB_DQ<18>")
	)
	(arc
		(start 92.528136 -284.293818)
		(mid 92.811092 -284.369995)
		(end 93.094048 -284.293818)
		(width 0.0889)
		(layer "In2.Cu")
		(net "M_C_CPU1_SB_DQ<18>")
	)
	(arc
		(start 91.588082 -284.293818)
		(mid 91.871038 -284.369995)
		(end 92.153994 -284.293818)
		(width 0.0889)
		(layer "In2.Cu")
		(net "M_C_CPU1_SB_DQ<18>")
	)
	(arc
		(start 82.18805 -284.293818)
		(mid 82.471006 -284.369995)
		(end 82.753962 -284.293818)
		(width 0.0889)
		(layer "In2.Cu")
		(net "M_C_CPU1_SB_DQ<18>")
	)
	(arc
		(start 90.273886 -284.293818)
		(mid 90.456137 -284.243468)
		(end 90.639646 -284.288992)
		(width 0.0889)
		(layer "In2.Cu")
		(net "M_C_CPU1_SB_DQ<18>")
	)
	(arc
		(start 79.958692 -284.28061)
		(mid 80.135087 -284.243707)
		(end 80.308196 -284.293818)
		(width 0.0889)
		(layer "In2.Cu")
		(net "M_C_CPU1_SB_DQ<18>")
	)
	(arc
		(start 78.711044 -284.376622)
		(mid 78.849066 -284.358274)
		(end 78.97749 -284.304486)
		(width 0.0889)
		(layer "In2.Cu")
		(net "M_C_CPU1_SB_DQ<18>")
	)
	(arc
		(start 88.402414 -284.288992)
		(mid 88.585922 -284.243498)
		(end 88.768174 -284.293818)
		(width 0.0889)
		(layer "In2.Cu")
		(net "M_C_CPU1_SB_DQ<18>")
	)
	(arc
		(start 78.995778 -284.293818)
		(mid 79.171688 -284.243008)
		(end 79.350616 -284.28188)
		(width 0.0889)
		(layer "In2.Cu")
		(net "M_C_CPU1_SB_DQ<18>")
	)
	(arc
		(start 84.63407 -284.293818)
		(mid 84.821014 -284.243563)
		(end 85.007958 -284.293818)
		(width 0.0889)
		(layer "In2.Cu")
		(net "M_C_CPU1_SB_DQ<18>")
	)
	(arc
		(start 82.762344 -284.288992)
		(mid 82.945852 -284.243498)
		(end 83.128104 -284.293818)
		(width 0.0889)
		(layer "In2.Cu")
		(net "M_C_CPU1_SB_DQ<18>")
	)
	(arc
		(start 86.513924 -284.293818)
		(mid 86.696175 -284.243468)
		(end 86.879684 -284.288992)
		(width 0.0889)
		(layer "In2.Cu")
		(net "M_C_CPU1_SB_DQ<18>")
	)
	(arc
		(start 92.162376 -284.288992)
		(mid 92.345884 -284.243498)
		(end 92.528136 -284.293818)
		(width 0.0889)
		(layer "In2.Cu")
		(net "M_C_CPU1_SB_DQ<18>")
	)
	(arc
		(start 79.37119 -284.293818)
		(mid 79.63951 -284.369926)
		(end 79.911448 -284.308042)
		(width 0.0889)
		(layer "In2.Cu")
		(net "M_C_CPU1_SB_DQ<18>")
	)
	(arc
		(start 81.813908 -284.293818)
		(mid 81.996159 -284.243468)
		(end 82.179668 -284.288992)
		(width 0.0889)
		(layer "In2.Cu")
		(net "M_C_CPU1_SB_DQ<18>")
	)
	(arc
		(start 88.768174 -284.293818)
		(mid 89.05113 -284.369995)
		(end 89.334086 -284.293818)
		(width 0.0889)
		(layer "In2.Cu")
		(net "M_C_CPU1_SB_DQ<18>")
	)
	(arc
		(start 77.518006 -284.923484)
		(mid 77.94579 -284.838392)
		(end 78.308454 -284.596078)
		(width 0.0889)
		(layer "In2.Cu")
		(net "M_C_CPU1_SB_DQ<18>")
	)
	(arc
		(start 85.57387 -284.293818)
		(mid 85.756121 -284.243468)
		(end 85.93963 -284.288992)
		(width 0.0889)
		(layer "In2.Cu")
		(net "M_C_CPU1_SB_DQ<18>")
	)
	(arc
		(start 94.034102 -284.293818)
		(mid 94.190421 -284.244823)
		(end 94.352618 -284.267656)
		(width 0.0889)
		(layer "In2.Cu")
		(net "M_C_CPU1_SB_DQ<18>")
	)
	(arc
		(start 87.46236 -284.288992)
		(mid 87.645868 -284.243498)
		(end 87.82812 -284.293818)
		(width 0.0889)
		(layer "In2.Cu")
		(net "M_C_CPU1_SB_DQ<18>")
	)
	(arc
		(start 83.702398 -284.288992)
		(mid 83.885906 -284.243498)
		(end 84.068158 -284.293818)
		(width 0.0889)
		(layer "In2.Cu")
		(net "M_C_CPU1_SB_DQ<18>")
	)
	(arc
		(start 89.707974 -284.293818)
		(mid 89.99093 -284.369995)
		(end 90.273886 -284.293818)
		(width 0.0889)
		(layer "In2.Cu")
		(net "M_C_CPU1_SB_DQ<18>")
	)
	(arc
		(start 81.247996 -284.293818)
		(mid 81.530952 -284.369995)
		(end 81.813908 -284.293818)
		(width 0.0889)
		(layer "In2.Cu")
		(net "M_C_CPU1_SB_DQ<18>")
	)
	(arc
		(start 85.948012 -284.293818)
		(mid 86.230968 -284.369995)
		(end 86.513924 -284.293818)
		(width 0.0889)
		(layer "In2.Cu")
		(net "M_C_CPU1_SB_DQ<18>")
	)
	(segment
		(start 96.568006 -284.35046)
		(end 96.101154 -284.616398)
		(width 0.10668)
		(layer "F.Cu")
		(net "M_C_CPU1_SB_DQ<17>")
	)
	(segment
		(start 69.585586 -294.71747)
		(end 69.585586 -291.342064)
		(width 0.14478)
		(layer "In2.Cu")
		(net "M_C_CPU1_SB_DQ<17>")
	)
	(segment
		(start 56.00192 -301.999904)
		(end 56.248046 -301.999904)
		(width 0.14478)
		(layer "In2.Cu")
		(net "M_C_CPU1_SB_DQ<17>")
	)
	(segment
		(start 58.513218 -301.071026)
		(end 58.741564 -301.071026)
		(width 0.14478)
		(layer "In2.Cu")
		(net "M_C_CPU1_SB_DQ<17>")
	)
	(segment
		(start 80.299814 -284.943804)
		(end 80.308196 -284.938978)
		(width 0.0889)
		(layer "In2.Cu")
		(net "M_C_CPU1_SB_DQ<17>")
	)
	(segment
		(start 91.5797 -284.943804)
		(end 91.588082 -284.938978)
		(width 0.0889)
		(layer "In2.Cu")
		(net "M_C_CPU1_SB_DQ<17>")
	)
	(segment
		(start 45.489622 -302.52289)
		(end 45.489622 -302.089566)
		(width 0.14478)
		(layer "In2.Cu")
		(net "M_C_CPU1_SB_DQ<17>")
	)
	(segment
		(start 49.271936 -302.643286)
		(end 50.455068 -301.460154)
		(width 0.14478)
		(layer "In2.Cu")
		(net "M_C_CPU1_SB_DQ<17>")
	)
	(segment
		(start 61.263022 -301.460154)
		(end 61.542422 -301.460154)
		(width 0.14478)
		(layer "In2.Cu")
		(net "M_C_CPU1_SB_DQ<17>")
	)
	(segment
		(start 45.883068 -301.926752)
		(end 46.045882 -302.089566)
		(width 0.14478)
		(layer "In2.Cu")
		(net "M_C_CPU1_SB_DQ<17>")
	)
	(segment
		(start 56.558434 -302.310292)
		(end 56.925718 -302.310292)
		(width 0.14478)
		(layer "In2.Cu")
		(net "M_C_CPU1_SB_DQ<17>")
	)
	(segment
		(start 45.489622 -302.089566)
		(end 45.652436 -301.926752)
		(width 0.14478)
		(layer "In2.Cu")
		(net "M_C_CPU1_SB_DQ<17>")
	)
	(segment
		(start 52.93233 -301.23257)
		(end 52.93233 -301.29861)
		(width 0.14478)
		(layer "In2.Cu")
		(net "M_C_CPU1_SB_DQ<17>")
	)
	(segment
		(start 52.219352 -301.460154)
		(end 52.380896 -301.29861)
		(width 0.14478)
		(layer "In2.Cu")
		(net "M_C_CPU1_SB_DQ<17>")
	)
	(segment
		(start 46.045882 -302.525938)
		(end 46.208696 -302.688752)
		(width 0.14478)
		(layer "In2.Cu")
		(net "M_C_CPU1_SB_DQ<17>")
	)
	(segment
		(start 48.620172 -301.921164)
		(end 48.909986 -302.210978)
		(width 0.14478)
		(layer "In2.Cu")
		(net "M_C_CPU1_SB_DQ<17>")
	)
	(segment
		(start 46.439328 -302.688752)
		(end 46.602142 -302.525938)
		(width 0.14478)
		(layer "In2.Cu")
		(net "M_C_CPU1_SB_DQ<17>")
	)
	(segment
		(start 77.533246 -285.378144)
		(end 78.492604 -284.902402)
		(width 0.0889)
		(layer "In2.Cu")
		(net "M_C_CPU1_SB_DQ<17>")
	)
	(segment
		(start 46.602142 -302.114966)
		(end 46.770544 -301.946564)
		(width 0.14478)
		(layer "In2.Cu")
		(net "M_C_CPU1_SB_DQ<17>")
	)
	(segment
		(start 45.127418 -302.67275)
		(end 45.339762 -302.67275)
		(width 0.14478)
		(layer "In2.Cu")
		(net "M_C_CPU1_SB_DQ<17>")
	)
	(segment
		(start 66.12382 -297.12285)
		(end 66.124328 -296.894504)
		(width 0.14478)
		(layer "In2.Cu")
		(net "M_C_CPU1_SB_DQ<17>")
	)
	(segment
		(start 45.652436 -301.926752)
		(end 45.883068 -301.926752)
		(width 0.14478)
		(layer "In2.Cu")
		(net "M_C_CPU1_SB_DQ<17>")
	)
	(segment
		(start 82.753962 -284.938978)
		(end 82.762344 -284.943804)
		(width 0.0889)
		(layer "In2.Cu")
		(net "M_C_CPU1_SB_DQ<17>")
	)
	(segment
		(start 58.741564 -301.071026)
		(end 58.903108 -301.23257)
		(width 0.14478)
		(layer "In2.Cu")
		(net "M_C_CPU1_SB_DQ<17>")
	)
	(segment
		(start 86.879684 -284.943804)
		(end 86.888066 -284.938978)
		(width 0.0889)
		(layer "In2.Cu")
		(net "M_C_CPU1_SB_DQ<17>")
	)
	(segment
		(start 58.351674 -301.23257)
		(end 58.513218 -301.071026)
		(width 0.14478)
		(layer "In2.Cu")
		(net "M_C_CPU1_SB_DQ<17>")
	)
	(segment
		(start 92.153994 -284.938978)
		(end 92.162376 -284.943804)
		(width 0.0889)
		(layer "In2.Cu")
		(net "M_C_CPU1_SB_DQ<17>")
	)
	(segment
		(start 88.394032 -284.938978)
		(end 88.402414 -284.943804)
		(width 0.0889)
		(layer "In2.Cu")
		(net "M_C_CPU1_SB_DQ<17>")
	)
	(segment
		(start 46.602142 -302.525938)
		(end 46.602142 -302.114966)
		(width 0.14478)
		(layer "In2.Cu")
		(net "M_C_CPU1_SB_DQ<17>")
	)
	(segment
		(start 83.694016 -284.938978)
		(end 83.702398 -284.943804)
		(width 0.0889)
		(layer "In2.Cu")
		(net "M_C_CPU1_SB_DQ<17>")
	)
	(segment
		(start 61.101478 -301.29861)
		(end 61.263022 -301.460154)
		(width 0.14478)
		(layer "In2.Cu")
		(net "M_C_CPU1_SB_DQ<17>")
	)
	(segment
		(start 65.733168 -297.512232)
		(end 65.83553 -297.614848)
		(width 0.14478)
		(layer "In2.Cu")
		(net "M_C_CPU1_SB_DQ<17>")
	)
	(segment
		(start 53.257196 -301.460154)
		(end 54.107334 -302.310292)
		(width 0.14478)
		(layer "In2.Cu")
		(net "M_C_CPU1_SB_DQ<17>")
	)
	(segment
		(start 54.107334 -302.310292)
		(end 55.691532 -302.310292)
		(width 0.14478)
		(layer "In2.Cu")
		(net "M_C_CPU1_SB_DQ<17>")
	)
	(segment
		(start 47.232062 -301.946564)
		(end 47.59579 -302.310292)
		(width 0.14478)
		(layer "In2.Cu")
		(net "M_C_CPU1_SB_DQ<17>")
	)
	(segment
		(start 60.711588 -301.073566)
		(end 60.939934 -301.073566)
		(width 0.14478)
		(layer "In2.Cu")
		(net "M_C_CPU1_SB_DQ<17>")
	)
	(segment
		(start 65.505076 -297.511724)
		(end 65.733168 -297.512232)
		(width 0.14478)
		(layer "In2.Cu")
		(net "M_C_CPU1_SB_DQ<17>")
	)
	(segment
		(start 95.946976 -284.881828)
		(end 96.101154 -284.616398)
		(width 0.0889)
		(layer "In2.Cu")
		(net "M_C_CPU1_SB_DQ<17>")
	)
	(segment
		(start 61.101478 -301.23511)
		(end 61.101478 -301.29861)
		(width 0.14478)
		(layer "In2.Cu")
		(net "M_C_CPU1_SB_DQ<17>")
	)
	(segment
		(start 58.19013 -301.460154)
		(end 58.351674 -301.29861)
		(width 0.14478)
		(layer "In2.Cu")
		(net "M_C_CPU1_SB_DQ<17>")
	)
	(segment
		(start 61.542422 -301.460154)
		(end 65.505076 -297.511724)
		(width 0.14478)
		(layer "In2.Cu")
		(net "M_C_CPU1_SB_DQ<17>")
	)
	(segment
		(start 66.226182 -297.225466)
		(end 66.12382 -297.12285)
		(width 0.14478)
		(layer "In2.Cu")
		(net "M_C_CPU1_SB_DQ<17>")
	)
	(segment
		(start 52.380896 -301.23257)
		(end 52.54244 -301.071026)
		(width 0.14478)
		(layer "In2.Cu")
		(net "M_C_CPU1_SB_DQ<17>")
	)
	(segment
		(start 44.340018 -301.88535)
		(end 45.127418 -302.67275)
		(width 0.14478)
		(layer "In2.Cu")
		(net "M_C_CPU1_SB_DQ<17>")
	)
	(segment
		(start 52.770786 -301.071026)
		(end 52.93233 -301.23257)
		(width 0.14478)
		(layer "In2.Cu")
		(net "M_C_CPU1_SB_DQ<17>")
	)
	(segment
		(start 48.38954 -301.921164)
		(end 48.620172 -301.921164)
		(width 0.14478)
		(layer "In2.Cu")
		(net "M_C_CPU1_SB_DQ<17>")
	)
	(segment
		(start 60.550044 -301.29861)
		(end 60.550044 -301.23511)
		(width 0.14478)
		(layer "In2.Cu")
		(net "M_C_CPU1_SB_DQ<17>")
	)
	(segment
		(start 66.225674 -297.453812)
		(end 66.226182 -297.225466)
		(width 0.14478)
		(layer "In2.Cu")
		(net "M_C_CPU1_SB_DQ<17>")
	)
	(segment
		(start 52.54244 -301.071026)
		(end 52.770786 -301.071026)
		(width 0.14478)
		(layer "In2.Cu")
		(net "M_C_CPU1_SB_DQ<17>")
	)
	(segment
		(start 58.351674 -301.29861)
		(end 58.351674 -301.23257)
		(width 0.14478)
		(layer "In2.Cu")
		(net "M_C_CPU1_SB_DQ<17>")
	)
	(segment
		(start 93.094048 -284.938978)
		(end 93.10243 -284.943804)
		(width 0.0889)
		(layer "In2.Cu")
		(net "M_C_CPU1_SB_DQ<17>")
	)
	(segment
		(start 60.3885 -301.460154)
		(end 60.550044 -301.29861)
		(width 0.14478)
		(layer "In2.Cu")
		(net "M_C_CPU1_SB_DQ<17>")
	)
	(segment
		(start 66.124328 -296.894504)
		(end 66.245994 -296.773346)
		(width 0.14478)
		(layer "In2.Cu")
		(net "M_C_CPU1_SB_DQ<17>")
	)
	(segment
		(start 69.585586 -291.342064)
		(end 75.549506 -285.378144)
		(width 0.14478)
		(layer "In2.Cu")
		(net "M_C_CPU1_SB_DQ<17>")
	)
	(segment
		(start 57.775856 -301.460154)
		(end 58.19013 -301.460154)
		(width 0.14478)
		(layer "In2.Cu")
		(net "M_C_CPU1_SB_DQ<17>")
	)
	(segment
		(start 60.939934 -301.073566)
		(end 61.101478 -301.23511)
		(width 0.14478)
		(layer "In2.Cu")
		(net "M_C_CPU1_SB_DQ<17>")
	)
	(segment
		(start 58.903108 -301.23257)
		(end 58.903108 -301.29861)
		(width 0.14478)
		(layer "In2.Cu")
		(net "M_C_CPU1_SB_DQ<17>")
	)
	(segment
		(start 47.59579 -302.310292)
		(end 48.000412 -302.310292)
		(width 0.14478)
		(layer "In2.Cu")
		(net "M_C_CPU1_SB_DQ<17>")
	)
	(segment
		(start 66.245994 -296.773346)
		(end 67.52971 -296.773346)
		(width 0.14478)
		(layer "In2.Cu")
		(net "M_C_CPU1_SB_DQ<17>")
	)
	(segment
		(start 48.000412 -302.310292)
		(end 48.38954 -301.921164)
		(width 0.14478)
		(layer "In2.Cu")
		(net "M_C_CPU1_SB_DQ<17>")
	)
	(segment
		(start 60.550044 -301.23511)
		(end 60.711588 -301.073566)
		(width 0.14478)
		(layer "In2.Cu")
		(net "M_C_CPU1_SB_DQ<17>")
	)
	(segment
		(start 55.691532 -302.310292)
		(end 56.00192 -301.999904)
		(width 0.14478)
		(layer "In2.Cu")
		(net "M_C_CPU1_SB_DQ<17>")
	)
	(segment
		(start 56.248046 -301.999904)
		(end 56.558434 -302.310292)
		(width 0.14478)
		(layer "In2.Cu")
		(net "M_C_CPU1_SB_DQ<17>")
	)
	(segment
		(start 46.208696 -302.688752)
		(end 46.439328 -302.688752)
		(width 0.14478)
		(layer "In2.Cu")
		(net "M_C_CPU1_SB_DQ<17>")
	)
	(segment
		(start 58.903108 -301.29861)
		(end 59.064652 -301.460154)
		(width 0.14478)
		(layer "In2.Cu")
		(net "M_C_CPU1_SB_DQ<17>")
	)
	(segment
		(start 85.93963 -284.943804)
		(end 85.948012 -284.938978)
		(width 0.0889)
		(layer "In2.Cu")
		(net "M_C_CPU1_SB_DQ<17>")
	)
	(segment
		(start 65.83553 -297.614848)
		(end 66.063622 -297.615356)
		(width 0.14478)
		(layer "In2.Cu")
		(net "M_C_CPU1_SB_DQ<17>")
	)
	(segment
		(start 87.453978 -284.938978)
		(end 87.46236 -284.943804)
		(width 0.0889)
		(layer "In2.Cu")
		(net "M_C_CPU1_SB_DQ<17>")
	)
	(segment
		(start 50.455068 -301.460154)
		(end 52.219352 -301.460154)
		(width 0.14478)
		(layer "In2.Cu")
		(net "M_C_CPU1_SB_DQ<17>")
	)
	(segment
		(start 49.059846 -302.643286)
		(end 49.271936 -302.643286)
		(width 0.14478)
		(layer "In2.Cu")
		(net "M_C_CPU1_SB_DQ<17>")
	)
	(segment
		(start 82.179668 -284.943804)
		(end 82.18805 -284.938978)
		(width 0.0889)
		(layer "In2.Cu")
		(net "M_C_CPU1_SB_DQ<17>")
	)
	(segment
		(start 67.52971 -296.773346)
		(end 69.585586 -294.71747)
		(width 0.14478)
		(layer "In2.Cu")
		(net "M_C_CPU1_SB_DQ<17>")
	)
	(segment
		(start 76.002896 -285.378144)
		(end 77.533246 -285.378144)
		(width 0.0889)
		(layer "In2.Cu")
		(net "M_C_CPU1_SB_DQ<17>")
	)
	(segment
		(start 53.093874 -301.460154)
		(end 53.257196 -301.460154)
		(width 0.14478)
		(layer "In2.Cu")
		(net "M_C_CPU1_SB_DQ<17>")
	)
	(segment
		(start 95.339662 -284.943804)
		(end 95.348044 -284.938978)
		(width 0.0889)
		(layer "In2.Cu")
		(net "M_C_CPU1_SB_DQ<17>")
	)
	(segment
		(start 79.367126 -284.938978)
		(end 79.381858 -284.930342)
		(width 0.0889)
		(layer "In2.Cu")
		(net "M_C_CPU1_SB_DQ<17>")
	)
	(segment
		(start 46.045882 -302.089566)
		(end 46.045882 -302.525938)
		(width 0.14478)
		(layer "In2.Cu")
		(net "M_C_CPU1_SB_DQ<17>")
	)
	(segment
		(start 48.909986 -302.493426)
		(end 49.059846 -302.643286)
		(width 0.14478)
		(layer "In2.Cu")
		(net "M_C_CPU1_SB_DQ<17>")
	)
	(segment
		(start 59.064652 -301.460154)
		(end 60.3885 -301.460154)
		(width 0.14478)
		(layer "In2.Cu")
		(net "M_C_CPU1_SB_DQ<17>")
	)
	(segment
		(start 52.380896 -301.29861)
		(end 52.380896 -301.23257)
		(width 0.14478)
		(layer "In2.Cu")
		(net "M_C_CPU1_SB_DQ<17>")
	)
	(segment
		(start 78.663292 -284.862524)
		(end 78.711552 -284.862524)
		(width 0.0889)
		(layer "In2.Cu")
		(net "M_C_CPU1_SB_DQ<17>")
	)
	(segment
		(start 56.925718 -302.310292)
		(end 57.775856 -301.460154)
		(width 0.14478)
		(layer "In2.Cu")
		(net "M_C_CPU1_SB_DQ<17>")
	)
	(segment
		(start 66.063622 -297.615356)
		(end 66.225674 -297.453812)
		(width 0.14478)
		(layer "In2.Cu")
		(net "M_C_CPU1_SB_DQ<17>")
	)
	(segment
		(start 90.639646 -284.943804)
		(end 90.648028 -284.938978)
		(width 0.0889)
		(layer "In2.Cu")
		(net "M_C_CPU1_SB_DQ<17>")
	)
	(segment
		(start 46.770544 -301.946564)
		(end 47.232062 -301.946564)
		(width 0.14478)
		(layer "In2.Cu")
		(net "M_C_CPU1_SB_DQ<17>")
	)
	(segment
		(start 48.909986 -302.210978)
		(end 48.909986 -302.493426)
		(width 0.14478)
		(layer "In2.Cu")
		(net "M_C_CPU1_SB_DQ<17>")
	)
	(segment
		(start 45.339762 -302.67275)
		(end 45.489622 -302.52289)
		(width 0.14478)
		(layer "In2.Cu")
		(net "M_C_CPU1_SB_DQ<17>")
	)
	(segment
		(start 95.85071 -284.907228)
		(end 95.946976 -284.881828)
		(width 0.0889)
		(layer "In2.Cu")
		(net "M_C_CPU1_SB_DQ<17>")
	)
	(segment
		(start 52.93233 -301.29861)
		(end 53.093874 -301.460154)
		(width 0.14478)
		(layer "In2.Cu")
		(net "M_C_CPU1_SB_DQ<17>")
	)
	(segment
		(start 75.549506 -285.378144)
		(end 76.002896 -285.378144)
		(width 0.14478)
		(layer "In2.Cu")
		(net "M_C_CPU1_SB_DQ<17>")
	)
	(arc
		(start 90.648028 -284.938978)
		(mid 90.930984 -284.862801)
		(end 91.21394 -284.938978)
		(width 0.0889)
		(layer "In2.Cu")
		(net "M_C_CPU1_SB_DQ<17>")
	)
	(arc
		(start 79.381858 -284.930342)
		(mid 79.658841 -284.862538)
		(end 79.933546 -284.938978)
		(width 0.0889)
		(layer "In2.Cu")
		(net "M_C_CPU1_SB_DQ<17>")
	)
	(arc
		(start 87.82812 -284.938978)
		(mid 88.111076 -284.862801)
		(end 88.394032 -284.938978)
		(width 0.0889)
		(layer "In2.Cu")
		(net "M_C_CPU1_SB_DQ<17>")
	)
	(arc
		(start 80.308196 -284.938978)
		(mid 80.591152 -284.862801)
		(end 80.874108 -284.938978)
		(width 0.0889)
		(layer "In2.Cu")
		(net "M_C_CPU1_SB_DQ<17>")
	)
	(arc
		(start 93.10243 -284.943804)
		(mid 93.285938 -284.989298)
		(end 93.46819 -284.938978)
		(width 0.0889)
		(layer "In2.Cu")
		(net "M_C_CPU1_SB_DQ<17>")
	)
	(arc
		(start 85.57387 -284.938978)
		(mid 85.756121 -284.989328)
		(end 85.93963 -284.943804)
		(width 0.0889)
		(layer "In2.Cu")
		(net "M_C_CPU1_SB_DQ<17>")
	)
	(arc
		(start 86.888066 -284.938978)
		(mid 87.171022 -284.862801)
		(end 87.453978 -284.938978)
		(width 0.0889)
		(layer "In2.Cu")
		(net "M_C_CPU1_SB_DQ<17>")
	)
	(arc
		(start 91.21394 -284.938978)
		(mid 91.396191 -284.989328)
		(end 91.5797 -284.943804)
		(width 0.0889)
		(layer "In2.Cu")
		(net "M_C_CPU1_SB_DQ<17>")
	)
	(arc
		(start 91.588082 -284.938978)
		(mid 91.871038 -284.862801)
		(end 92.153994 -284.938978)
		(width 0.0889)
		(layer "In2.Cu")
		(net "M_C_CPU1_SB_DQ<17>")
	)
	(arc
		(start 81.813908 -284.938978)
		(mid 81.996159 -284.989328)
		(end 82.179668 -284.943804)
		(width 0.0889)
		(layer "In2.Cu")
		(net "M_C_CPU1_SB_DQ<17>")
	)
	(arc
		(start 81.247996 -284.938978)
		(mid 81.530952 -284.862801)
		(end 81.813908 -284.938978)
		(width 0.0889)
		(layer "In2.Cu")
		(net "M_C_CPU1_SB_DQ<17>")
	)
	(arc
		(start 89.707974 -284.938978)
		(mid 89.99093 -284.862801)
		(end 90.273886 -284.938978)
		(width 0.0889)
		(layer "In2.Cu")
		(net "M_C_CPU1_SB_DQ<17>")
	)
	(arc
		(start 93.46819 -284.938978)
		(mid 93.751146 -284.862801)
		(end 94.034102 -284.938978)
		(width 0.0889)
		(layer "In2.Cu")
		(net "M_C_CPU1_SB_DQ<17>")
	)
	(arc
		(start 80.874108 -284.938978)
		(mid 81.061052 -284.989233)
		(end 81.247996 -284.938978)
		(width 0.0889)
		(layer "In2.Cu")
		(net "M_C_CPU1_SB_DQ<17>")
	)
	(arc
		(start 78.492604 -284.902402)
		(mid 78.575636 -284.872567)
		(end 78.663292 -284.862524)
		(width 0.0889)
		(layer "In2.Cu")
		(net "M_C_CPU1_SB_DQ<17>")
	)
	(arc
		(start 88.768174 -284.938978)
		(mid 89.05113 -284.862801)
		(end 89.334086 -284.938978)
		(width 0.0889)
		(layer "In2.Cu")
		(net "M_C_CPU1_SB_DQ<17>")
	)
	(arc
		(start 90.273886 -284.938978)
		(mid 90.456137 -284.989328)
		(end 90.639646 -284.943804)
		(width 0.0889)
		(layer "In2.Cu")
		(net "M_C_CPU1_SB_DQ<17>")
	)
	(arc
		(start 87.46236 -284.943804)
		(mid 87.645868 -284.989298)
		(end 87.82812 -284.938978)
		(width 0.0889)
		(layer "In2.Cu")
		(net "M_C_CPU1_SB_DQ<17>")
	)
	(arc
		(start 78.711552 -284.862524)
		(mid 78.717648 -284.862491)
		(end 78.723744 -284.862524)
		(width 0.0889)
		(layer "In2.Cu")
		(net "M_C_CPU1_SB_DQ<17>")
	)
	(arc
		(start 83.702398 -284.943804)
		(mid 83.885906 -284.989298)
		(end 84.068158 -284.938978)
		(width 0.0889)
		(layer "In2.Cu")
		(net "M_C_CPU1_SB_DQ<17>")
	)
	(arc
		(start 83.128104 -284.938978)
		(mid 83.41106 -284.862801)
		(end 83.694016 -284.938978)
		(width 0.0889)
		(layer "In2.Cu")
		(net "M_C_CPU1_SB_DQ<17>")
	)
	(arc
		(start 94.973902 -284.938978)
		(mid 95.156153 -284.989328)
		(end 95.339662 -284.943804)
		(width 0.0889)
		(layer "In2.Cu")
		(net "M_C_CPU1_SB_DQ<17>")
	)
	(arc
		(start 95.348044 -284.938978)
		(mid 95.59564 -284.8638)
		(end 95.85071 -284.907228)
		(width 0.0889)
		(layer "In2.Cu")
		(net "M_C_CPU1_SB_DQ<17>")
	)
	(arc
		(start 82.762344 -284.943804)
		(mid 82.945852 -284.989298)
		(end 83.128104 -284.938978)
		(width 0.0889)
		(layer "In2.Cu")
		(net "M_C_CPU1_SB_DQ<17>")
	)
	(arc
		(start 78.723744 -284.862524)
		(mid 78.871093 -284.885635)
		(end 79.007208 -284.946598)
		(width 0.0889)
		(layer "In2.Cu")
		(net "M_C_CPU1_SB_DQ<17>")
	)
	(arc
		(start 82.18805 -284.938978)
		(mid 82.471006 -284.862801)
		(end 82.753962 -284.938978)
		(width 0.0889)
		(layer "In2.Cu")
		(net "M_C_CPU1_SB_DQ<17>")
	)
	(arc
		(start 86.513924 -284.938978)
		(mid 86.696175 -284.989328)
		(end 86.879684 -284.943804)
		(width 0.0889)
		(layer "In2.Cu")
		(net "M_C_CPU1_SB_DQ<17>")
	)
	(arc
		(start 89.334086 -284.938978)
		(mid 89.52103 -284.989233)
		(end 89.707974 -284.938978)
		(width 0.0889)
		(layer "In2.Cu")
		(net "M_C_CPU1_SB_DQ<17>")
	)
	(arc
		(start 85.948012 -284.938978)
		(mid 86.230968 -284.862801)
		(end 86.513924 -284.938978)
		(width 0.0889)
		(layer "In2.Cu")
		(net "M_C_CPU1_SB_DQ<17>")
	)
	(arc
		(start 94.034102 -284.938978)
		(mid 94.221046 -284.989233)
		(end 94.40799 -284.938978)
		(width 0.0889)
		(layer "In2.Cu")
		(net "M_C_CPU1_SB_DQ<17>")
	)
	(arc
		(start 88.402414 -284.943804)
		(mid 88.585922 -284.989298)
		(end 88.768174 -284.938978)
		(width 0.0889)
		(layer "In2.Cu")
		(net "M_C_CPU1_SB_DQ<17>")
	)
	(arc
		(start 92.528136 -284.938978)
		(mid 92.811092 -284.862801)
		(end 93.094048 -284.938978)
		(width 0.0889)
		(layer "In2.Cu")
		(net "M_C_CPU1_SB_DQ<17>")
	)
	(arc
		(start 94.40799 -284.938978)
		(mid 94.690946 -284.862801)
		(end 94.973902 -284.938978)
		(width 0.0889)
		(layer "In2.Cu")
		(net "M_C_CPU1_SB_DQ<17>")
	)
	(arc
		(start 84.068158 -284.938978)
		(mid 84.351114 -284.862801)
		(end 84.63407 -284.938978)
		(width 0.0889)
		(layer "In2.Cu")
		(net "M_C_CPU1_SB_DQ<17>")
	)
	(arc
		(start 92.162376 -284.943804)
		(mid 92.345884 -284.989298)
		(end 92.528136 -284.938978)
		(width 0.0889)
		(layer "In2.Cu")
		(net "M_C_CPU1_SB_DQ<17>")
	)
	(arc
		(start 79.933546 -284.938978)
		(mid 80.116051 -284.989455)
		(end 80.299814 -284.943804)
		(width 0.0889)
		(layer "In2.Cu")
		(net "M_C_CPU1_SB_DQ<17>")
	)
	(arc
		(start 84.63407 -284.938978)
		(mid 84.821014 -284.989233)
		(end 85.007958 -284.938978)
		(width 0.0889)
		(layer "In2.Cu")
		(net "M_C_CPU1_SB_DQ<17>")
	)
	(arc
		(start 79.007208 -284.946598)
		(mid 79.188138 -284.989076)
		(end 79.367126 -284.938978)
		(width 0.0889)
		(layer "In2.Cu")
		(net "M_C_CPU1_SB_DQ<17>")
	)
	(arc
		(start 85.007958 -284.938978)
		(mid 85.290914 -284.862801)
		(end 85.57387 -284.938978)
		(width 0.0889)
		(layer "In2.Cu")
		(net "M_C_CPU1_SB_DQ<17>")
	)
	(segment
		(start 95.157798 -283.540454)
		(end 94.690946 -283.806392)
		(width 0.10668)
		(layer "F.Cu")
		(net "M_C_CPU1_SB_DQ<16>")
	)
	(segment
		(start 60.572142 -299.760386)
		(end 60.733686 -299.92193)
		(width 0.14478)
		(layer "In2.Cu")
		(net "M_C_CPU1_SB_DQ<16>")
	)
	(segment
		(start 60.733686 -299.995082)
		(end 60.89523 -300.156626)
		(width 0.14478)
		(layer "In2.Cu")
		(net "M_C_CPU1_SB_DQ<16>")
	)
	(segment
		(start 92.989654 -284.133798)
		(end 92.998036 -284.128972)
		(width 0.0889)
		(layer "In2.Cu")
		(net "M_C_CPU1_SB_DQ<16>")
	)
	(segment
		(start 85.10397 -284.128972)
		(end 85.112352 -284.133798)
		(width 0.0889)
		(layer "In2.Cu")
		(net "M_C_CPU1_SB_DQ<16>")
	)
	(segment
		(start 67.926966 -295.092882)
		(end 68.089018 -294.93083)
		(width 0.14478)
		(layer "In2.Cu")
		(net "M_C_CPU1_SB_DQ<16>")
	)
	(segment
		(start 81.344008 -284.128972)
		(end 81.35239 -284.133798)
		(width 0.0889)
		(layer "In2.Cu")
		(net "M_C_CPU1_SB_DQ<16>")
	)
	(segment
		(start 46.040548 -300.81855)
		(end 46.203362 -300.981364)
		(width 0.14478)
		(layer "In2.Cu")
		(net "M_C_CPU1_SB_DQ<16>")
	)
	(segment
		(start 61.28512 -299.995082)
		(end 61.28512 -299.92193)
		(width 0.14478)
		(layer "In2.Cu")
		(net "M_C_CPU1_SB_DQ<16>")
	)
	(segment
		(start 60.733686 -299.92193)
		(end 60.733686 -299.995082)
		(width 0.14478)
		(layer "In2.Cu")
		(net "M_C_CPU1_SB_DQ<16>")
	)
	(segment
		(start 56.995822 -300.845982)
		(end 56.995822 -300.772068)
		(width 0.14478)
		(layer "In2.Cu")
		(net "M_C_CPU1_SB_DQ<16>")
	)
	(segment
		(start 79.817976 -284.141164)
		(end 79.83982 -284.128718)
		(width 0.0889)
		(layer "In2.Cu")
		(net "M_C_CPU1_SB_DQ<16>")
	)
	(segment
		(start 56.282844 -300.610524)
		(end 56.444388 -300.772068)
		(width 0.14478)
		(layer "In2.Cu")
		(net "M_C_CPU1_SB_DQ<16>")
	)
	(segment
		(start 67.258438 -294.6527)
		(end 67.698874 -295.092882)
		(width 0.14478)
		(layer "In2.Cu")
		(net "M_C_CPU1_SB_DQ<16>")
	)
	(segment
		(start 68.089018 -294.93083)
		(end 68.089018 -294.702738)
		(width 0.14478)
		(layer "In2.Cu")
		(net "M_C_CPU1_SB_DQ<16>")
	)
	(segment
		(start 67.698874 -295.092882)
		(end 67.926966 -295.092882)
		(width 0.14478)
		(layer "In2.Cu")
		(net "M_C_CPU1_SB_DQ<16>")
	)
	(segment
		(start 56.444388 -300.845982)
		(end 56.605932 -301.007526)
		(width 0.14478)
		(layer "In2.Cu")
		(net "M_C_CPU1_SB_DQ<16>")
	)
	(segment
		(start 49.535334 -300.771814)
		(end 49.696878 -300.61027)
		(width 0.14478)
		(layer "In2.Cu")
		(net "M_C_CPU1_SB_DQ<16>")
	)
	(segment
		(start 88.289638 -284.133798)
		(end 88.29802 -284.128972)
		(width 0.0889)
		(layer "In2.Cu")
		(net "M_C_CPU1_SB_DQ<16>")
	)
	(segment
		(start 56.605932 -301.007526)
		(end 56.834278 -301.007526)
		(width 0.14478)
		(layer "In2.Cu")
		(net "M_C_CPU1_SB_DQ<16>")
	)
	(segment
		(start 79.439516 -284.11297)
		(end 79.467202 -284.128972)
		(width 0.0889)
		(layer "In2.Cu")
		(net "M_C_CPU1_SB_DQ<16>")
	)
	(segment
		(start 47.27956 -300.61027)
		(end 48.822356 -300.61027)
		(width 0.14478)
		(layer "In2.Cu")
		(net "M_C_CPU1_SB_DQ<16>")
	)
	(segment
		(start 66.47815 -295.432988)
		(end 66.918586 -295.87317)
		(width 0.14478)
		(layer "In2.Cu")
		(net "M_C_CPU1_SB_DQ<16>")
	)
	(segment
		(start 44.340018 -300.185328)
		(end 45.122084 -300.967394)
		(width 0.14478)
		(layer "In2.Cu")
		(net "M_C_CPU1_SB_DQ<16>")
	)
	(segment
		(start 68.291202 -294.124634)
		(end 68.519294 -294.124634)
		(width 0.14478)
		(layer "In2.Cu")
		(net "M_C_CPU1_SB_DQ<16>")
	)
	(segment
		(start 68.681346 -293.734744)
		(end 68.42887 -293.482268)
		(width 0.14478)
		(layer "In2.Cu")
		(net "M_C_CPU1_SB_DQ<16>")
	)
	(segment
		(start 46.990254 -300.320964)
		(end 47.27956 -300.61027)
		(width 0.14478)
		(layer "In2.Cu")
		(net "M_C_CPU1_SB_DQ<16>")
	)
	(segment
		(start 86.044024 -284.128972)
		(end 86.052406 -284.133798)
		(width 0.0889)
		(layer "In2.Cu")
		(net "M_C_CPU1_SB_DQ<16>")
	)
	(segment
		(start 67.146678 -295.87317)
		(end 67.30873 -295.711118)
		(width 0.14478)
		(layer "In2.Cu")
		(net "M_C_CPU1_SB_DQ<16>")
	)
	(segment
		(start 80.769714 -284.133798)
		(end 80.778096 -284.128972)
		(width 0.0889)
		(layer "In2.Cu")
		(net "M_C_CPU1_SB_DQ<16>")
	)
	(segment
		(start 49.37379 -301.007526)
		(end 49.535334 -300.845982)
		(width 0.14478)
		(layer "In2.Cu")
		(net "M_C_CPU1_SB_DQ<16>")
	)
	(segment
		(start 46.433994 -300.981364)
		(end 46.596808 -300.81855)
		(width 0.14478)
		(layer "In2.Cu")
		(net "M_C_CPU1_SB_DQ<16>")
	)
	(segment
		(start 68.676266 -290.959032)
		(end 75.166474 -284.468824)
		(width 0.14478)
		(layer "In2.Cu")
		(net "M_C_CPU1_SB_DQ<16>")
	)
	(segment
		(start 67.30873 -295.483026)
		(end 66.868294 -295.042844)
		(width 0.14478)
		(layer "In2.Cu")
		(net "M_C_CPU1_SB_DQ<16>")
	)
	(segment
		(start 67.810634 -293.872412)
		(end 68.03898 -293.872412)
		(width 0.14478)
		(layer "In2.Cu")
		(net "M_C_CPU1_SB_DQ<16>")
	)
	(segment
		(start 53.898546 -300.610524)
		(end 56.282844 -300.610524)
		(width 0.14478)
		(layer "In2.Cu")
		(net "M_C_CPU1_SB_DQ<16>")
	)
	(segment
		(start 48.9839 -300.771814)
		(end 48.9839 -300.845982)
		(width 0.14478)
		(layer "In2.Cu")
		(net "M_C_CPU1_SB_DQ<16>")
	)
	(segment
		(start 68.42887 -293.254176)
		(end 68.676266 -293.00678)
		(width 0.14478)
		(layer "In2.Cu")
		(net "M_C_CPU1_SB_DQ<16>")
	)
	(segment
		(start 61.446664 -299.760386)
		(end 61.92266 -299.760386)
		(width 0.14478)
		(layer "In2.Cu")
		(net "M_C_CPU1_SB_DQ<16>")
	)
	(segment
		(start 67.648582 -294.262556)
		(end 67.648582 -294.034464)
		(width 0.14478)
		(layer "In2.Cu")
		(net "M_C_CPU1_SB_DQ<16>")
	)
	(segment
		(start 68.519294 -294.124634)
		(end 68.681346 -293.962582)
		(width 0.14478)
		(layer "In2.Cu")
		(net "M_C_CPU1_SB_DQ<16>")
	)
	(segment
		(start 53.048408 -299.760386)
		(end 53.898546 -300.610524)
		(width 0.14478)
		(layer "In2.Cu")
		(net "M_C_CPU1_SB_DQ<16>")
	)
	(segment
		(start 45.334428 -300.967394)
		(end 45.484288 -300.817534)
		(width 0.14478)
		(layer "In2.Cu")
		(net "M_C_CPU1_SB_DQ<16>")
	)
	(segment
		(start 89.229692 -284.133798)
		(end 89.238074 -284.128972)
		(width 0.0889)
		(layer "In2.Cu")
		(net "M_C_CPU1_SB_DQ<16>")
	)
	(segment
		(start 76.715366 -284.7086)
		(end 77.418438 -284.7086)
		(width 0.0889)
		(layer "In2.Cu")
		(net "M_C_CPU1_SB_DQ<16>")
	)
	(segment
		(start 61.28512 -299.92193)
		(end 61.446664 -299.760386)
		(width 0.14478)
		(layer "In2.Cu")
		(net "M_C_CPU1_SB_DQ<16>")
	)
	(segment
		(start 46.203362 -300.981364)
		(end 46.433994 -300.981364)
		(width 0.14478)
		(layer "In2.Cu")
		(net "M_C_CPU1_SB_DQ<16>")
	)
	(segment
		(start 78.711044 -284.173168)
		(end 78.73619 -284.173168)
		(width 0.0889)
		(layer "In2.Cu")
		(net "M_C_CPU1_SB_DQ<16>")
	)
	(segment
		(start 45.647102 -300.320964)
		(end 45.877734 -300.320964)
		(width 0.14478)
		(layer "In2.Cu")
		(net "M_C_CPU1_SB_DQ<16>")
	)
	(segment
		(start 56.995822 -300.772068)
		(end 57.157366 -300.610524)
		(width 0.14478)
		(layer "In2.Cu")
		(net "M_C_CPU1_SB_DQ<16>")
	)
	(segment
		(start 68.03898 -293.872412)
		(end 68.291202 -294.124634)
		(width 0.14478)
		(layer "In2.Cu")
		(net "M_C_CPU1_SB_DQ<16>")
	)
	(segment
		(start 57.157366 -300.610524)
		(end 57.302146 -300.610524)
		(width 0.14478)
		(layer "In2.Cu")
		(net "M_C_CPU1_SB_DQ<16>")
	)
	(segment
		(start 61.123576 -300.156626)
		(end 61.28512 -299.995082)
		(width 0.14478)
		(layer "In2.Cu")
		(net "M_C_CPU1_SB_DQ<16>")
	)
	(segment
		(start 48.9839 -300.845982)
		(end 49.145444 -301.007526)
		(width 0.14478)
		(layer "In2.Cu")
		(net "M_C_CPU1_SB_DQ<16>")
	)
	(segment
		(start 67.648582 -294.034464)
		(end 67.810634 -293.872412)
		(width 0.14478)
		(layer "In2.Cu")
		(net "M_C_CPU1_SB_DQ<16>")
	)
	(segment
		(start 94.44101 -284.097222)
		(end 94.537022 -284.071822)
		(width 0.0889)
		(layer "In2.Cu")
		(net "M_C_CPU1_SB_DQ<16>")
	)
	(segment
		(start 45.484288 -300.817534)
		(end 45.484288 -300.483778)
		(width 0.14478)
		(layer "In2.Cu")
		(net "M_C_CPU1_SB_DQ<16>")
	)
	(segment
		(start 79.83982 -284.128718)
		(end 79.863696 -284.114748)
		(width 0.0889)
		(layer "In2.Cu")
		(net "M_C_CPU1_SB_DQ<16>")
	)
	(segment
		(start 68.681346 -293.962582)
		(end 68.681346 -293.734744)
		(width 0.14478)
		(layer "In2.Cu")
		(net "M_C_CPU1_SB_DQ<16>")
	)
	(segment
		(start 49.145444 -301.007526)
		(end 49.37379 -301.007526)
		(width 0.14478)
		(layer "In2.Cu")
		(net "M_C_CPU1_SB_DQ<16>")
	)
	(segment
		(start 60.89523 -300.156626)
		(end 61.123576 -300.156626)
		(width 0.14478)
		(layer "In2.Cu")
		(net "M_C_CPU1_SB_DQ<16>")
	)
	(segment
		(start 83.589622 -284.133798)
		(end 83.598004 -284.128972)
		(width 0.0889)
		(layer "In2.Cu")
		(net "M_C_CPU1_SB_DQ<16>")
	)
	(segment
		(start 61.92266 -299.760386)
		(end 66.250058 -295.432988)
		(width 0.14478)
		(layer "In2.Cu")
		(net "M_C_CPU1_SB_DQ<16>")
	)
	(segment
		(start 46.759622 -300.320964)
		(end 46.990254 -300.320964)
		(width 0.14478)
		(layer "In2.Cu")
		(net "M_C_CPU1_SB_DQ<16>")
	)
	(segment
		(start 58.152284 -299.760386)
		(end 60.572142 -299.760386)
		(width 0.14478)
		(layer "In2.Cu")
		(net "M_C_CPU1_SB_DQ<16>")
	)
	(segment
		(start 89.803986 -284.128972)
		(end 89.812368 -284.133798)
		(width 0.0889)
		(layer "In2.Cu")
		(net "M_C_CPU1_SB_DQ<16>")
	)
	(segment
		(start 66.868294 -295.042844)
		(end 66.868294 -294.814752)
		(width 0.14478)
		(layer "In2.Cu")
		(net "M_C_CPU1_SB_DQ<16>")
	)
	(segment
		(start 90.74404 -284.128972)
		(end 90.752422 -284.133798)
		(width 0.0889)
		(layer "In2.Cu")
		(net "M_C_CPU1_SB_DQ<16>")
	)
	(segment
		(start 48.822356 -300.61027)
		(end 48.9839 -300.771814)
		(width 0.14478)
		(layer "In2.Cu")
		(net "M_C_CPU1_SB_DQ<16>")
	)
	(segment
		(start 46.596808 -300.81855)
		(end 46.596808 -300.483778)
		(width 0.14478)
		(layer "In2.Cu")
		(net "M_C_CPU1_SB_DQ<16>")
	)
	(segment
		(start 67.30873 -295.711118)
		(end 67.30873 -295.483026)
		(width 0.14478)
		(layer "In2.Cu")
		(net "M_C_CPU1_SB_DQ<16>")
	)
	(segment
		(start 75.166474 -284.468824)
		(end 75.960986 -284.468824)
		(width 0.14478)
		(layer "In2.Cu")
		(net "M_C_CPU1_SB_DQ<16>")
	)
	(segment
		(start 46.040548 -300.483778)
		(end 46.040548 -300.81855)
		(width 0.14478)
		(layer "In2.Cu")
		(net "M_C_CPU1_SB_DQ<16>")
	)
	(segment
		(start 68.089018 -294.702738)
		(end 67.648582 -294.262556)
		(width 0.14478)
		(layer "In2.Cu")
		(net "M_C_CPU1_SB_DQ<16>")
	)
	(segment
		(start 46.596808 -300.483778)
		(end 46.759622 -300.320964)
		(width 0.14478)
		(layer "In2.Cu")
		(net "M_C_CPU1_SB_DQ<16>")
	)
	(segment
		(start 66.250058 -295.432988)
		(end 66.47815 -295.432988)
		(width 0.14478)
		(layer "In2.Cu")
		(net "M_C_CPU1_SB_DQ<16>")
	)
	(segment
		(start 45.484288 -300.483778)
		(end 45.647102 -300.320964)
		(width 0.14478)
		(layer "In2.Cu")
		(net "M_C_CPU1_SB_DQ<16>")
	)
	(segment
		(start 45.122084 -300.967394)
		(end 45.334428 -300.967394)
		(width 0.14478)
		(layer "In2.Cu")
		(net "M_C_CPU1_SB_DQ<16>")
	)
	(segment
		(start 49.696878 -300.61027)
		(end 49.83988 -300.61027)
		(width 0.14478)
		(layer "In2.Cu")
		(net "M_C_CPU1_SB_DQ<16>")
	)
	(segment
		(start 56.444388 -300.772068)
		(end 56.444388 -300.845982)
		(width 0.14478)
		(layer "In2.Cu")
		(net "M_C_CPU1_SB_DQ<16>")
	)
	(segment
		(start 45.877734 -300.320964)
		(end 46.040548 -300.483778)
		(width 0.14478)
		(layer "In2.Cu")
		(net "M_C_CPU1_SB_DQ<16>")
	)
	(segment
		(start 76.47559 -284.468824)
		(end 76.715366 -284.7086)
		(width 0.0889)
		(layer "In2.Cu")
		(net "M_C_CPU1_SB_DQ<16>")
	)
	(segment
		(start 84.529676 -284.133798)
		(end 84.538058 -284.128972)
		(width 0.0889)
		(layer "In2.Cu")
		(net "M_C_CPU1_SB_DQ<16>")
	)
	(segment
		(start 75.960986 -284.468824)
		(end 76.47559 -284.468824)
		(width 0.0889)
		(layer "In2.Cu")
		(net "M_C_CPU1_SB_DQ<16>")
	)
	(segment
		(start 50.689764 -299.760386)
		(end 53.048408 -299.760386)
		(width 0.14478)
		(layer "In2.Cu")
		(net "M_C_CPU1_SB_DQ<16>")
	)
	(segment
		(start 68.676266 -293.00678)
		(end 68.676266 -290.959032)
		(width 0.14478)
		(layer "In2.Cu")
		(net "M_C_CPU1_SB_DQ<16>")
	)
	(segment
		(start 57.302146 -300.610524)
		(end 58.152284 -299.760386)
		(width 0.14478)
		(layer "In2.Cu")
		(net "M_C_CPU1_SB_DQ<16>")
	)
	(segment
		(start 66.868294 -294.814752)
		(end 67.030346 -294.6527)
		(width 0.14478)
		(layer "In2.Cu")
		(net "M_C_CPU1_SB_DQ<16>")
	)
	(segment
		(start 66.918586 -295.87317)
		(end 67.146678 -295.87317)
		(width 0.14478)
		(layer "In2.Cu")
		(net "M_C_CPU1_SB_DQ<16>")
	)
	(segment
		(start 94.537022 -284.071822)
		(end 94.690946 -283.806392)
		(width 0.0889)
		(layer "In2.Cu")
		(net "M_C_CPU1_SB_DQ<16>")
	)
	(segment
		(start 93.929708 -284.133798)
		(end 93.93809 -284.128972)
		(width 0.0889)
		(layer "In2.Cu")
		(net "M_C_CPU1_SB_DQ<16>")
	)
	(segment
		(start 56.834278 -301.007526)
		(end 56.995822 -300.845982)
		(width 0.14478)
		(layer "In2.Cu")
		(net "M_C_CPU1_SB_DQ<16>")
	)
	(segment
		(start 49.535334 -300.845982)
		(end 49.535334 -300.771814)
		(width 0.14478)
		(layer "In2.Cu")
		(net "M_C_CPU1_SB_DQ<16>")
	)
	(segment
		(start 67.030346 -294.6527)
		(end 67.258438 -294.6527)
		(width 0.14478)
		(layer "In2.Cu")
		(net "M_C_CPU1_SB_DQ<16>")
	)
	(segment
		(start 68.42887 -293.482268)
		(end 68.42887 -293.254176)
		(width 0.14478)
		(layer "In2.Cu")
		(net "M_C_CPU1_SB_DQ<16>")
	)
	(segment
		(start 49.83988 -300.61027)
		(end 50.689764 -299.760386)
		(width 0.14478)
		(layer "In2.Cu")
		(net "M_C_CPU1_SB_DQ<16>")
	)
	(arc
		(start 86.418166 -284.128972)
		(mid 86.701122 -284.052795)
		(end 86.984078 -284.128972)
		(width 0.0889)
		(layer "In2.Cu")
		(net "M_C_CPU1_SB_DQ<16>")
	)
	(arc
		(start 84.538058 -284.128972)
		(mid 84.821014 -284.052795)
		(end 85.10397 -284.128972)
		(width 0.0889)
		(layer "In2.Cu")
		(net "M_C_CPU1_SB_DQ<16>")
	)
	(arc
		(start 93.563948 -284.128972)
		(mid 93.746199 -284.179322)
		(end 93.929708 -284.133798)
		(width 0.0889)
		(layer "In2.Cu")
		(net "M_C_CPU1_SB_DQ<16>")
	)
	(arc
		(start 82.284062 -284.128972)
		(mid 82.471006 -284.179227)
		(end 82.65795 -284.128972)
		(width 0.0889)
		(layer "In2.Cu")
		(net "M_C_CPU1_SB_DQ<16>")
	)
	(arc
		(start 88.863932 -284.128972)
		(mid 89.046183 -284.179322)
		(end 89.229692 -284.133798)
		(width 0.0889)
		(layer "In2.Cu")
		(net "M_C_CPU1_SB_DQ<16>")
	)
	(arc
		(start 79.863696 -284.114748)
		(mid 80.135633 -284.052922)
		(end 80.403954 -284.128972)
		(width 0.0889)
		(layer "In2.Cu")
		(net "M_C_CPU1_SB_DQ<16>")
	)
	(arc
		(start 86.052406 -284.133798)
		(mid 86.235914 -284.179292)
		(end 86.418166 -284.128972)
		(width 0.0889)
		(layer "In2.Cu")
		(net "M_C_CPU1_SB_DQ<16>")
	)
	(arc
		(start 82.65795 -284.128972)
		(mid 82.940906 -284.052795)
		(end 83.223862 -284.128972)
		(width 0.0889)
		(layer "In2.Cu")
		(net "M_C_CPU1_SB_DQ<16>")
	)
	(arc
		(start 87.923878 -284.128972)
		(mid 88.106129 -284.179322)
		(end 88.289638 -284.133798)
		(width 0.0889)
		(layer "In2.Cu")
		(net "M_C_CPU1_SB_DQ<16>")
	)
	(arc
		(start 89.812368 -284.133798)
		(mid 89.995876 -284.179292)
		(end 90.178128 -284.128972)
		(width 0.0889)
		(layer "In2.Cu")
		(net "M_C_CPU1_SB_DQ<16>")
	)
	(arc
		(start 90.178128 -284.128972)
		(mid 90.461084 -284.052795)
		(end 90.74404 -284.128972)
		(width 0.0889)
		(layer "In2.Cu")
		(net "M_C_CPU1_SB_DQ<16>")
	)
	(arc
		(start 92.057982 -284.128972)
		(mid 92.340938 -284.052795)
		(end 92.623894 -284.128972)
		(width 0.0889)
		(layer "In2.Cu")
		(net "M_C_CPU1_SB_DQ<16>")
	)
	(arc
		(start 79.467202 -284.128972)
		(mid 79.641052 -284.178878)
		(end 79.817976 -284.141164)
		(width 0.0889)
		(layer "In2.Cu")
		(net "M_C_CPU1_SB_DQ<16>")
	)
	(arc
		(start 80.403954 -284.128972)
		(mid 80.586205 -284.179322)
		(end 80.769714 -284.133798)
		(width 0.0889)
		(layer "In2.Cu")
		(net "M_C_CPU1_SB_DQ<16>")
	)
	(arc
		(start 80.778096 -284.128972)
		(mid 81.061052 -284.052795)
		(end 81.344008 -284.128972)
		(width 0.0889)
		(layer "In2.Cu")
		(net "M_C_CPU1_SB_DQ<16>")
	)
	(arc
		(start 78.25486 -284.362144)
		(mid 78.464159 -284.222295)
		(end 78.711044 -284.173168)
		(width 0.0889)
		(layer "In2.Cu")
		(net "M_C_CPU1_SB_DQ<16>")
	)
	(arc
		(start 89.238074 -284.128972)
		(mid 89.52103 -284.052795)
		(end 89.803986 -284.128972)
		(width 0.0889)
		(layer "In2.Cu")
		(net "M_C_CPU1_SB_DQ<16>")
	)
	(arc
		(start 85.112352 -284.133798)
		(mid 85.29586 -284.179292)
		(end 85.478112 -284.128972)
		(width 0.0889)
		(layer "In2.Cu")
		(net "M_C_CPU1_SB_DQ<16>")
	)
	(arc
		(start 85.478112 -284.128972)
		(mid 85.761068 -284.052795)
		(end 86.044024 -284.128972)
		(width 0.0889)
		(layer "In2.Cu")
		(net "M_C_CPU1_SB_DQ<16>")
	)
	(arc
		(start 87.357966 -284.128972)
		(mid 87.640922 -284.052795)
		(end 87.923878 -284.128972)
		(width 0.0889)
		(layer "In2.Cu")
		(net "M_C_CPU1_SB_DQ<16>")
	)
	(arc
		(start 92.998036 -284.128972)
		(mid 93.280992 -284.052795)
		(end 93.563948 -284.128972)
		(width 0.0889)
		(layer "In2.Cu")
		(net "M_C_CPU1_SB_DQ<16>")
	)
	(arc
		(start 78.73619 -284.173168)
		(mid 78.820783 -284.161915)
		(end 78.899512 -284.128972)
		(width 0.0889)
		(layer "In2.Cu")
		(net "M_C_CPU1_SB_DQ<16>")
	)
	(arc
		(start 77.418438 -284.7086)
		(mid 77.871106 -284.618559)
		(end 78.25486 -284.362144)
		(width 0.0889)
		(layer "In2.Cu")
		(net "M_C_CPU1_SB_DQ<16>")
	)
	(arc
		(start 91.684094 -284.128972)
		(mid 91.871038 -284.179227)
		(end 92.057982 -284.128972)
		(width 0.0889)
		(layer "In2.Cu")
		(net "M_C_CPU1_SB_DQ<16>")
	)
	(arc
		(start 88.29802 -284.128972)
		(mid 88.580976 -284.052795)
		(end 88.863932 -284.128972)
		(width 0.0889)
		(layer "In2.Cu")
		(net "M_C_CPU1_SB_DQ<16>")
	)
	(arc
		(start 83.223862 -284.128972)
		(mid 83.406113 -284.179322)
		(end 83.589622 -284.133798)
		(width 0.0889)
		(layer "In2.Cu")
		(net "M_C_CPU1_SB_DQ<16>")
	)
	(arc
		(start 90.752422 -284.133798)
		(mid 90.93593 -284.179292)
		(end 91.118182 -284.128972)
		(width 0.0889)
		(layer "In2.Cu")
		(net "M_C_CPU1_SB_DQ<16>")
	)
	(arc
		(start 78.899512 -284.128972)
		(mid 79.167481 -284.052149)
		(end 79.439516 -284.11297)
		(width 0.0889)
		(layer "In2.Cu")
		(net "M_C_CPU1_SB_DQ<16>")
	)
	(arc
		(start 91.118182 -284.128972)
		(mid 91.401138 -284.052795)
		(end 91.684094 -284.128972)
		(width 0.0889)
		(layer "In2.Cu")
		(net "M_C_CPU1_SB_DQ<16>")
	)
	(arc
		(start 93.93809 -284.128972)
		(mid 94.185803 -284.053752)
		(end 94.44101 -284.097222)
		(width 0.0889)
		(layer "In2.Cu")
		(net "M_C_CPU1_SB_DQ<16>")
	)
	(arc
		(start 86.984078 -284.128972)
		(mid 87.171022 -284.179227)
		(end 87.357966 -284.128972)
		(width 0.0889)
		(layer "In2.Cu")
		(net "M_C_CPU1_SB_DQ<16>")
	)
	(arc
		(start 81.35239 -284.133798)
		(mid 81.535898 -284.179292)
		(end 81.71815 -284.128972)
		(width 0.0889)
		(layer "In2.Cu")
		(net "M_C_CPU1_SB_DQ<16>")
	)
	(arc
		(start 92.623894 -284.128972)
		(mid 92.806145 -284.179322)
		(end 92.989654 -284.133798)
		(width 0.0889)
		(layer "In2.Cu")
		(net "M_C_CPU1_SB_DQ<16>")
	)
	(arc
		(start 83.598004 -284.128972)
		(mid 83.88096 -284.052795)
		(end 84.163916 -284.128972)
		(width 0.0889)
		(layer "In2.Cu")
		(net "M_C_CPU1_SB_DQ<16>")
	)
	(arc
		(start 81.71815 -284.128972)
		(mid 82.001106 -284.052795)
		(end 82.284062 -284.128972)
		(width 0.0889)
		(layer "In2.Cu")
		(net "M_C_CPU1_SB_DQ<16>")
	)
	(arc
		(start 84.163916 -284.128972)
		(mid 84.346167 -284.179322)
		(end 84.529676 -284.133798)
		(width 0.0889)
		(layer "In2.Cu")
		(net "M_C_CPU1_SB_DQ<16>")
	)
	(segment
		(start 96.097852 -283.540454)
		(end 95.631 -283.806392)
		(width 0.10668)
		(layer "F.Cu")
		(net "M_C_CPU1_SB_DQ<15>")
	)
	(segment
		(start 40.23995 -299.335444)
		(end 40.664892 -299.760386)
		(width 0.14478)
		(layer "In2.Cu")
		(net "M_C_CPU1_SB_DQ<15>")
	)
	(segment
		(start 74.935842 -283.912564)
		(end 76.037186 -283.912564)
		(width 0.14478)
		(layer "In2.Cu")
		(net "M_C_CPU1_SB_DQ<15>")
	)
	(segment
		(start 93.929708 -283.478986)
		(end 93.93809 -283.483812)
		(width 0.0889)
		(layer "In2.Cu")
		(net "M_C_CPU1_SB_DQ<15>")
	)
	(segment
		(start 80.769714 -283.478986)
		(end 80.778096 -283.483812)
		(width 0.0889)
		(layer "In2.Cu")
		(net "M_C_CPU1_SB_DQ<15>")
	)
	(segment
		(start 78.170278 -283.811218)
		(end 78.429358 -283.552138)
		(width 0.0889)
		(layer "In2.Cu")
		(net "M_C_CPU1_SB_DQ<15>")
	)
	(segment
		(start 76.037186 -283.912564)
		(end 77.925422 -283.912564)
		(width 0.0889)
		(layer "In2.Cu")
		(net "M_C_CPU1_SB_DQ<15>")
	)
	(segment
		(start 92.989654 -283.478986)
		(end 92.998036 -283.483812)
		(width 0.0889)
		(layer "In2.Cu")
		(net "M_C_CPU1_SB_DQ<15>")
	)
	(segment
		(start 51.265836 -298.910248)
		(end 52.292758 -298.910248)
		(width 0.14478)
		(layer "In2.Cu")
		(net "M_C_CPU1_SB_DQ<15>")
	)
	(segment
		(start 52.292758 -298.910248)
		(end 53.072792 -299.105574)
		(width 0.14478)
		(layer "In2.Cu")
		(net "M_C_CPU1_SB_DQ<15>")
	)
	(segment
		(start 89.229692 -283.478986)
		(end 89.238074 -283.483812)
		(width 0.0889)
		(layer "In2.Cu")
		(net "M_C_CPU1_SB_DQ<15>")
	)
	(segment
		(start 80.389222 -283.492448)
		(end 80.403954 -283.483812)
		(width 0.0889)
		(layer "In2.Cu")
		(net "M_C_CPU1_SB_DQ<15>")
	)
	(segment
		(start 81.344008 -283.483812)
		(end 81.35239 -283.478986)
		(width 0.0889)
		(layer "In2.Cu")
		(net "M_C_CPU1_SB_DQ<15>")
	)
	(segment
		(start 95.762826 -283.45765)
		(end 95.785178 -283.540962)
		(width 0.0889)
		(layer "In2.Cu")
		(net "M_C_CPU1_SB_DQ<15>")
	)
	(segment
		(start 84.529676 -283.478986)
		(end 84.538058 -283.483812)
		(width 0.0889)
		(layer "In2.Cu")
		(net "M_C_CPU1_SB_DQ<15>")
	)
	(segment
		(start 88.289638 -283.478986)
		(end 88.29802 -283.483812)
		(width 0.0889)
		(layer "In2.Cu")
		(net "M_C_CPU1_SB_DQ<15>")
	)
	(segment
		(start 90.74404 -283.483812)
		(end 90.752422 -283.478986)
		(width 0.0889)
		(layer "In2.Cu")
		(net "M_C_CPU1_SB_DQ<15>")
	)
	(segment
		(start 68.125086 -290.72332)
		(end 74.935842 -283.912564)
		(width 0.14478)
		(layer "In2.Cu")
		(net "M_C_CPU1_SB_DQ<15>")
	)
	(segment
		(start 95.785178 -283.540962)
		(end 95.631 -283.806392)
		(width 0.0889)
		(layer "In2.Cu")
		(net "M_C_CPU1_SB_DQ<15>")
	)
	(segment
		(start 60.385452 -298.910248)
		(end 62.383416 -298.512738)
		(width 0.14478)
		(layer "In2.Cu")
		(net "M_C_CPU1_SB_DQ<15>")
	)
	(segment
		(start 94.504002 -283.483812)
		(end 94.512384 -283.478986)
		(width 0.0889)
		(layer "In2.Cu")
		(net "M_C_CPU1_SB_DQ<15>")
	)
	(segment
		(start 79.463138 -283.483812)
		(end 79.474822 -283.476954)
		(width 0.0889)
		(layer "In2.Cu")
		(net "M_C_CPU1_SB_DQ<15>")
	)
	(segment
		(start 54.298088 -299.760386)
		(end 56.963818 -299.760386)
		(width 0.14478)
		(layer "In2.Cu")
		(net "M_C_CPU1_SB_DQ<15>")
	)
	(segment
		(start 62.383416 -298.512738)
		(end 68.125086 -292.771068)
		(width 0.14478)
		(layer "In2.Cu")
		(net "M_C_CPU1_SB_DQ<15>")
	)
	(segment
		(start 86.044024 -283.483812)
		(end 86.052406 -283.478986)
		(width 0.0889)
		(layer "In2.Cu")
		(net "M_C_CPU1_SB_DQ<15>")
	)
	(segment
		(start 53.072792 -299.105574)
		(end 54.298088 -299.760386)
		(width 0.14478)
		(layer "In2.Cu")
		(net "M_C_CPU1_SB_DQ<15>")
	)
	(segment
		(start 68.125086 -292.771068)
		(end 68.125086 -290.72332)
		(width 0.14478)
		(layer "In2.Cu")
		(net "M_C_CPU1_SB_DQ<15>")
	)
	(segment
		(start 85.10397 -283.483812)
		(end 85.112352 -283.478986)
		(width 0.0889)
		(layer "In2.Cu")
		(net "M_C_CPU1_SB_DQ<15>")
	)
	(segment
		(start 95.444056 -283.483812)
		(end 95.452438 -283.478986)
		(width 0.0889)
		(layer "In2.Cu")
		(net "M_C_CPU1_SB_DQ<15>")
	)
	(segment
		(start 50.051716 -299.413168)
		(end 51.265836 -298.910248)
		(width 0.14478)
		(layer "In2.Cu")
		(net "M_C_CPU1_SB_DQ<15>")
	)
	(segment
		(start 49.704498 -299.760386)
		(end 50.051716 -299.413168)
		(width 0.14478)
		(layer "In2.Cu")
		(net "M_C_CPU1_SB_DQ<15>")
	)
	(segment
		(start 83.589622 -283.478986)
		(end 83.598004 -283.483812)
		(width 0.0889)
		(layer "In2.Cu")
		(net "M_C_CPU1_SB_DQ<15>")
	)
	(segment
		(start 56.963818 -299.760386)
		(end 58.553858 -298.910248)
		(width 0.14478)
		(layer "In2.Cu")
		(net "M_C_CPU1_SB_DQ<15>")
	)
	(segment
		(start 89.803986 -283.483812)
		(end 89.812368 -283.478986)
		(width 0.0889)
		(layer "In2.Cu")
		(net "M_C_CPU1_SB_DQ<15>")
	)
	(segment
		(start 58.553858 -298.910248)
		(end 60.385452 -298.910248)
		(width 0.14478)
		(layer "In2.Cu")
		(net "M_C_CPU1_SB_DQ<15>")
	)
	(segment
		(start 40.664892 -299.760386)
		(end 49.704498 -299.760386)
		(width 0.14478)
		(layer "In2.Cu")
		(net "M_C_CPU1_SB_DQ<15>")
	)
	(arc
		(start 85.478112 -283.483812)
		(mid 85.761068 -283.559989)
		(end 86.044024 -283.483812)
		(width 0.0889)
		(layer "In2.Cu")
		(net "M_C_CPU1_SB_DQ<15>")
	)
	(arc
		(start 87.357966 -283.483812)
		(mid 87.640922 -283.559989)
		(end 87.923878 -283.483812)
		(width 0.0889)
		(layer "In2.Cu")
		(net "M_C_CPU1_SB_DQ<15>")
	)
	(arc
		(start 93.93809 -283.483812)
		(mid 94.221046 -283.559989)
		(end 94.504002 -283.483812)
		(width 0.0889)
		(layer "In2.Cu")
		(net "M_C_CPU1_SB_DQ<15>")
	)
	(arc
		(start 84.538058 -283.483812)
		(mid 84.821014 -283.559989)
		(end 85.10397 -283.483812)
		(width 0.0889)
		(layer "In2.Cu")
		(net "M_C_CPU1_SB_DQ<15>")
	)
	(arc
		(start 90.178128 -283.483812)
		(mid 90.461084 -283.559989)
		(end 90.74404 -283.483812)
		(width 0.0889)
		(layer "In2.Cu")
		(net "M_C_CPU1_SB_DQ<15>")
	)
	(arc
		(start 81.71815 -283.483812)
		(mid 82.001106 -283.559989)
		(end 82.284062 -283.483812)
		(width 0.0889)
		(layer "In2.Cu")
		(net "M_C_CPU1_SB_DQ<15>")
	)
	(arc
		(start 91.684094 -283.483812)
		(mid 91.871038 -283.433557)
		(end 92.057982 -283.483812)
		(width 0.0889)
		(layer "In2.Cu")
		(net "M_C_CPU1_SB_DQ<15>")
	)
	(arc
		(start 84.163916 -283.483812)
		(mid 84.346167 -283.433462)
		(end 84.529676 -283.478986)
		(width 0.0889)
		(layer "In2.Cu")
		(net "M_C_CPU1_SB_DQ<15>")
	)
	(arc
		(start 83.598004 -283.483812)
		(mid 83.88096 -283.559989)
		(end 84.163916 -283.483812)
		(width 0.0889)
		(layer "In2.Cu")
		(net "M_C_CPU1_SB_DQ<15>")
	)
	(arc
		(start 93.563948 -283.483812)
		(mid 93.746199 -283.433462)
		(end 93.929708 -283.478986)
		(width 0.0889)
		(layer "In2.Cu")
		(net "M_C_CPU1_SB_DQ<15>")
	)
	(arc
		(start 91.118182 -283.483812)
		(mid 91.401138 -283.559989)
		(end 91.684094 -283.483812)
		(width 0.0889)
		(layer "In2.Cu")
		(net "M_C_CPU1_SB_DQ<15>")
	)
	(arc
		(start 78.903322 -283.487368)
		(mid 79.183711 -283.560037)
		(end 79.463138 -283.483812)
		(width 0.0889)
		(layer "In2.Cu")
		(net "M_C_CPU1_SB_DQ<15>")
	)
	(arc
		(start 92.998036 -283.483812)
		(mid 93.280992 -283.559989)
		(end 93.563948 -283.483812)
		(width 0.0889)
		(layer "In2.Cu")
		(net "M_C_CPU1_SB_DQ<15>")
	)
	(arc
		(start 77.925422 -283.912564)
		(mid 78.057922 -283.886226)
		(end 78.170278 -283.811218)
		(width 0.0889)
		(layer "In2.Cu")
		(net "M_C_CPU1_SB_DQ<15>")
	)
	(arc
		(start 83.223862 -283.483812)
		(mid 83.406113 -283.433462)
		(end 83.589622 -283.478986)
		(width 0.0889)
		(layer "In2.Cu")
		(net "M_C_CPU1_SB_DQ<15>")
	)
	(arc
		(start 92.057982 -283.483812)
		(mid 92.340938 -283.559989)
		(end 92.623894 -283.483812)
		(width 0.0889)
		(layer "In2.Cu")
		(net "M_C_CPU1_SB_DQ<15>")
	)
	(arc
		(start 79.474822 -283.476954)
		(mid 79.657077 -283.433301)
		(end 79.837534 -283.483812)
		(width 0.0889)
		(layer "In2.Cu")
		(net "M_C_CPU1_SB_DQ<15>")
	)
	(arc
		(start 90.752422 -283.478986)
		(mid 90.93593 -283.433492)
		(end 91.118182 -283.483812)
		(width 0.0889)
		(layer "In2.Cu")
		(net "M_C_CPU1_SB_DQ<15>")
	)
	(arc
		(start 94.512384 -283.478986)
		(mid 94.695892 -283.433492)
		(end 94.878144 -283.483812)
		(width 0.0889)
		(layer "In2.Cu")
		(net "M_C_CPU1_SB_DQ<15>")
	)
	(arc
		(start 88.863932 -283.483812)
		(mid 89.046183 -283.433462)
		(end 89.229692 -283.478986)
		(width 0.0889)
		(layer "In2.Cu")
		(net "M_C_CPU1_SB_DQ<15>")
	)
	(arc
		(start 80.403954 -283.483812)
		(mid 80.586205 -283.433462)
		(end 80.769714 -283.478986)
		(width 0.0889)
		(layer "In2.Cu")
		(net "M_C_CPU1_SB_DQ<15>")
	)
	(arc
		(start 95.452438 -283.478986)
		(mid 95.605308 -283.434345)
		(end 95.762826 -283.45765)
		(width 0.0889)
		(layer "In2.Cu")
		(net "M_C_CPU1_SB_DQ<15>")
	)
	(arc
		(start 86.418166 -283.483812)
		(mid 86.701122 -283.559989)
		(end 86.984078 -283.483812)
		(width 0.0889)
		(layer "In2.Cu")
		(net "M_C_CPU1_SB_DQ<15>")
	)
	(arc
		(start 89.238074 -283.483812)
		(mid 89.52103 -283.559989)
		(end 89.803986 -283.483812)
		(width 0.0889)
		(layer "In2.Cu")
		(net "M_C_CPU1_SB_DQ<15>")
	)
	(arc
		(start 80.778096 -283.483812)
		(mid 81.061052 -283.559989)
		(end 81.344008 -283.483812)
		(width 0.0889)
		(layer "In2.Cu")
		(net "M_C_CPU1_SB_DQ<15>")
	)
	(arc
		(start 86.052406 -283.478986)
		(mid 86.235914 -283.433492)
		(end 86.418166 -283.483812)
		(width 0.0889)
		(layer "In2.Cu")
		(net "M_C_CPU1_SB_DQ<15>")
	)
	(arc
		(start 87.923878 -283.483812)
		(mid 88.106129 -283.433462)
		(end 88.289638 -283.478986)
		(width 0.0889)
		(layer "In2.Cu")
		(net "M_C_CPU1_SB_DQ<15>")
	)
	(arc
		(start 85.112352 -283.478986)
		(mid 85.29586 -283.433492)
		(end 85.478112 -283.483812)
		(width 0.0889)
		(layer "In2.Cu")
		(net "M_C_CPU1_SB_DQ<15>")
	)
	(arc
		(start 86.984078 -283.483812)
		(mid 87.171022 -283.433557)
		(end 87.357966 -283.483812)
		(width 0.0889)
		(layer "In2.Cu")
		(net "M_C_CPU1_SB_DQ<15>")
	)
	(arc
		(start 92.623894 -283.483812)
		(mid 92.806145 -283.433462)
		(end 92.989654 -283.478986)
		(width 0.0889)
		(layer "In2.Cu")
		(net "M_C_CPU1_SB_DQ<15>")
	)
	(arc
		(start 89.812368 -283.478986)
		(mid 89.995876 -283.433492)
		(end 90.178128 -283.483812)
		(width 0.0889)
		(layer "In2.Cu")
		(net "M_C_CPU1_SB_DQ<15>")
	)
	(arc
		(start 82.284062 -283.483812)
		(mid 82.471006 -283.433557)
		(end 82.65795 -283.483812)
		(width 0.0889)
		(layer "In2.Cu")
		(net "M_C_CPU1_SB_DQ<15>")
	)
	(arc
		(start 81.35239 -283.478986)
		(mid 81.535898 -283.433492)
		(end 81.71815 -283.483812)
		(width 0.0889)
		(layer "In2.Cu")
		(net "M_C_CPU1_SB_DQ<15>")
	)
	(arc
		(start 88.29802 -283.483812)
		(mid 88.580976 -283.559989)
		(end 88.863932 -283.483812)
		(width 0.0889)
		(layer "In2.Cu")
		(net "M_C_CPU1_SB_DQ<15>")
	)
	(arc
		(start 94.878144 -283.483812)
		(mid 95.1611 -283.559989)
		(end 95.444056 -283.483812)
		(width 0.0889)
		(layer "In2.Cu")
		(net "M_C_CPU1_SB_DQ<15>")
	)
	(arc
		(start 79.837534 -283.483812)
		(mid 80.11224 -283.560176)
		(end 80.389222 -283.492448)
		(width 0.0889)
		(layer "In2.Cu")
		(net "M_C_CPU1_SB_DQ<15>")
	)
	(arc
		(start 82.65795 -283.483812)
		(mid 82.940906 -283.559989)
		(end 83.223862 -283.483812)
		(width 0.0889)
		(layer "In2.Cu")
		(net "M_C_CPU1_SB_DQ<15>")
	)
	(arc
		(start 78.429358 -283.552138)
		(mid 78.65544 -283.439947)
		(end 78.903322 -283.487368)
		(width 0.0889)
		(layer "In2.Cu")
		(net "M_C_CPU1_SB_DQ<15>")
	)
	(segment
		(start 94.687898 -282.730448)
		(end 94.221046 -282.996386)
		(width 0.10668)
		(layer "F.Cu")
		(net "M_C_CPU1_SB_DQ<14>")
	)
	(segment
		(start 74.560176 -283.001974)
		(end 75.936856 -283.001974)
		(width 0.14478)
		(layer "In2.Cu")
		(net "M_C_CPU1_SB_DQ<14>")
	)
	(segment
		(start 92.153994 -282.673806)
		(end 92.162376 -282.66898)
		(width 0.0889)
		(layer "In2.Cu")
		(net "M_C_CPU1_SB_DQ<14>")
	)
	(segment
		(start 42.666666 -297.509184)
		(end 42.82948 -297.671998)
		(width 0.14478)
		(layer "In2.Cu")
		(net "M_C_CPU1_SB_DQ<14>")
	)
	(segment
		(start 94.37497 -282.730956)
		(end 94.221046 -282.996386)
		(width 0.0889)
		(layer "In2.Cu")
		(net "M_C_CPU1_SB_DQ<14>")
	)
	(segment
		(start 75.936856 -283.001974)
		(end 76.69911 -283.001974)
		(width 0.0889)
		(layer "In2.Cu")
		(net "M_C_CPU1_SB_DQ<14>")
	)
	(segment
		(start 50.968148 -297.210226)
		(end 52.87518 -297.210226)
		(width 0.14478)
		(layer "In2.Cu")
		(net "M_C_CPU1_SB_DQ<14>")
	)
	(segment
		(start 42.436034 -297.509184)
		(end 42.666666 -297.509184)
		(width 0.14478)
		(layer "In2.Cu")
		(net "M_C_CPU1_SB_DQ<14>")
	)
	(segment
		(start 86.879684 -282.66898)
		(end 86.888066 -282.673806)
		(width 0.0889)
		(layer "In2.Cu")
		(net "M_C_CPU1_SB_DQ<14>")
	)
	(segment
		(start 50.11801 -298.060364)
		(end 50.968148 -297.210226)
		(width 0.14478)
		(layer "In2.Cu")
		(net "M_C_CPU1_SB_DQ<14>")
	)
	(segment
		(start 42.27322 -297.89755)
		(end 42.27322 -297.671998)
		(width 0.14478)
		(layer "In2.Cu")
		(net "M_C_CPU1_SB_DQ<14>")
	)
	(segment
		(start 76.69911 -283.001974)
		(end 76.8477 -283.150564)
		(width 0.0889)
		(layer "In2.Cu")
		(net "M_C_CPU1_SB_DQ<14>")
	)
	(segment
		(start 57.429654 -298.060364)
		(end 58.279792 -297.210226)
		(width 0.14478)
		(layer "In2.Cu")
		(net "M_C_CPU1_SB_DQ<14>")
	)
	(segment
		(start 53.725318 -298.060364)
		(end 57.429654 -298.060364)
		(width 0.14478)
		(layer "In2.Cu")
		(net "M_C_CPU1_SB_DQ<14>")
	)
	(segment
		(start 91.5797 -282.66898)
		(end 91.588082 -282.673806)
		(width 0.0889)
		(layer "In2.Cu")
		(net "M_C_CPU1_SB_DQ<14>")
	)
	(segment
		(start 85.93963 -282.66898)
		(end 85.948012 -282.673806)
		(width 0.0889)
		(layer "In2.Cu")
		(net "M_C_CPU1_SB_DQ<14>")
	)
	(segment
		(start 94.352618 -282.647644)
		(end 94.37497 -282.730956)
		(width 0.0889)
		(layer "In2.Cu")
		(net "M_C_CPU1_SB_DQ<14>")
	)
	(segment
		(start 52.87518 -297.210226)
		(end 53.725318 -298.060364)
		(width 0.14478)
		(layer "In2.Cu")
		(net "M_C_CPU1_SB_DQ<14>")
	)
	(segment
		(start 79.350616 -282.661868)
		(end 79.37119 -282.673806)
		(width 0.0889)
		(layer "In2.Cu")
		(net "M_C_CPU1_SB_DQ<14>")
	)
	(segment
		(start 87.453978 -282.673806)
		(end 87.46236 -282.66898)
		(width 0.0889)
		(layer "In2.Cu")
		(net "M_C_CPU1_SB_DQ<14>")
	)
	(segment
		(start 82.753962 -282.673806)
		(end 82.762344 -282.66898)
		(width 0.0889)
		(layer "In2.Cu")
		(net "M_C_CPU1_SB_DQ<14>")
	)
	(segment
		(start 93.094048 -282.673806)
		(end 93.10243 -282.66898)
		(width 0.0889)
		(layer "In2.Cu")
		(net "M_C_CPU1_SB_DQ<14>")
	)
	(segment
		(start 79.911448 -282.68803)
		(end 79.935324 -282.67406)
		(width 0.0889)
		(layer "In2.Cu")
		(net "M_C_CPU1_SB_DQ<14>")
	)
	(segment
		(start 83.694016 -282.673806)
		(end 83.702398 -282.66898)
		(width 0.0889)
		(layer "In2.Cu")
		(net "M_C_CPU1_SB_DQ<14>")
	)
	(segment
		(start 90.639646 -282.66898)
		(end 90.648028 -282.673806)
		(width 0.0889)
		(layer "In2.Cu")
		(net "M_C_CPU1_SB_DQ<14>")
	)
	(segment
		(start 78.978252 -282.683966)
		(end 78.995778 -282.673806)
		(width 0.0889)
		(layer "In2.Cu")
		(net "M_C_CPU1_SB_DQ<14>")
	)
	(segment
		(start 88.394032 -282.673806)
		(end 88.402414 -282.66898)
		(width 0.0889)
		(layer "In2.Cu")
		(net "M_C_CPU1_SB_DQ<14>")
	)
	(segment
		(start 77.620114 -283.150564)
		(end 77.930502 -282.840176)
		(width 0.0889)
		(layer "In2.Cu")
		(net "M_C_CPU1_SB_DQ<14>")
	)
	(segment
		(start 58.279792 -297.210226)
		(end 62.399672 -297.210226)
		(width 0.14478)
		(layer "In2.Cu")
		(net "M_C_CPU1_SB_DQ<14>")
	)
	(segment
		(start 62.399672 -297.210226)
		(end 67.215766 -292.394132)
		(width 0.14478)
		(layer "In2.Cu")
		(net "M_C_CPU1_SB_DQ<14>")
	)
	(segment
		(start 67.215766 -292.394132)
		(end 67.215766 -290.346384)
		(width 0.14478)
		(layer "In2.Cu")
		(net "M_C_CPU1_SB_DQ<14>")
	)
	(segment
		(start 78.13294 -282.756356)
		(end 78.711044 -282.756356)
		(width 0.0889)
		(layer "In2.Cu")
		(net "M_C_CPU1_SB_DQ<14>")
	)
	(segment
		(start 79.935324 -282.67406)
		(end 79.958692 -282.660598)
		(width 0.0889)
		(layer "In2.Cu")
		(net "M_C_CPU1_SB_DQ<14>")
	)
	(segment
		(start 42.27322 -297.671998)
		(end 42.436034 -297.509184)
		(width 0.14478)
		(layer "In2.Cu")
		(net "M_C_CPU1_SB_DQ<14>")
	)
	(segment
		(start 42.82948 -297.89755)
		(end 42.992294 -298.060364)
		(width 0.14478)
		(layer "In2.Cu")
		(net "M_C_CPU1_SB_DQ<14>")
	)
	(segment
		(start 76.8477 -283.150564)
		(end 77.620114 -283.150564)
		(width 0.0889)
		(layer "In2.Cu")
		(net "M_C_CPU1_SB_DQ<14>")
	)
	(segment
		(start 40.23995 -297.635422)
		(end 40.664892 -298.060364)
		(width 0.14478)
		(layer "In2.Cu")
		(net "M_C_CPU1_SB_DQ<14>")
	)
	(segment
		(start 82.179668 -282.66898)
		(end 82.18805 -282.673806)
		(width 0.0889)
		(layer "In2.Cu")
		(net "M_C_CPU1_SB_DQ<14>")
	)
	(segment
		(start 42.110406 -298.060364)
		(end 42.27322 -297.89755)
		(width 0.14478)
		(layer "In2.Cu")
		(net "M_C_CPU1_SB_DQ<14>")
	)
	(segment
		(start 42.992294 -298.060364)
		(end 50.11801 -298.060364)
		(width 0.14478)
		(layer "In2.Cu")
		(net "M_C_CPU1_SB_DQ<14>")
	)
	(segment
		(start 40.664892 -298.060364)
		(end 42.110406 -298.060364)
		(width 0.14478)
		(layer "In2.Cu")
		(net "M_C_CPU1_SB_DQ<14>")
	)
	(segment
		(start 42.82948 -297.671998)
		(end 42.82948 -297.89755)
		(width 0.14478)
		(layer "In2.Cu")
		(net "M_C_CPU1_SB_DQ<14>")
	)
	(segment
		(start 67.215766 -290.346384)
		(end 74.560176 -283.001974)
		(width 0.14478)
		(layer "In2.Cu")
		(net "M_C_CPU1_SB_DQ<14>")
	)
	(arc
		(start 79.958692 -282.660598)
		(mid 80.135087 -282.623695)
		(end 80.308196 -282.673806)
		(width 0.0889)
		(layer "In2.Cu")
		(net "M_C_CPU1_SB_DQ<14>")
	)
	(arc
		(start 78.711044 -282.756356)
		(mid 78.849473 -282.737953)
		(end 78.978252 -282.683966)
		(width 0.0889)
		(layer "In2.Cu")
		(net "M_C_CPU1_SB_DQ<14>")
	)
	(arc
		(start 85.007958 -282.673806)
		(mid 85.290914 -282.749983)
		(end 85.57387 -282.673806)
		(width 0.0889)
		(layer "In2.Cu")
		(net "M_C_CPU1_SB_DQ<14>")
	)
	(arc
		(start 82.18805 -282.673806)
		(mid 82.471006 -282.749983)
		(end 82.753962 -282.673806)
		(width 0.0889)
		(layer "In2.Cu")
		(net "M_C_CPU1_SB_DQ<14>")
	)
	(arc
		(start 91.588082 -282.673806)
		(mid 91.871038 -282.749983)
		(end 92.153994 -282.673806)
		(width 0.0889)
		(layer "In2.Cu")
		(net "M_C_CPU1_SB_DQ<14>")
	)
	(arc
		(start 83.702398 -282.66898)
		(mid 83.885906 -282.623486)
		(end 84.068158 -282.673806)
		(width 0.0889)
		(layer "In2.Cu")
		(net "M_C_CPU1_SB_DQ<14>")
	)
	(arc
		(start 93.46819 -282.673806)
		(mid 93.751146 -282.749983)
		(end 94.034102 -282.673806)
		(width 0.0889)
		(layer "In2.Cu")
		(net "M_C_CPU1_SB_DQ<14>")
	)
	(arc
		(start 85.57387 -282.673806)
		(mid 85.756121 -282.623456)
		(end 85.93963 -282.66898)
		(width 0.0889)
		(layer "In2.Cu")
		(net "M_C_CPU1_SB_DQ<14>")
	)
	(arc
		(start 88.768174 -282.673806)
		(mid 89.05113 -282.749983)
		(end 89.334086 -282.673806)
		(width 0.0889)
		(layer "In2.Cu")
		(net "M_C_CPU1_SB_DQ<14>")
	)
	(arc
		(start 78.995778 -282.673806)
		(mid 79.171688 -282.622996)
		(end 79.350616 -282.661868)
		(width 0.0889)
		(layer "In2.Cu")
		(net "M_C_CPU1_SB_DQ<14>")
	)
	(arc
		(start 86.513924 -282.673806)
		(mid 86.696175 -282.623456)
		(end 86.879684 -282.66898)
		(width 0.0889)
		(layer "In2.Cu")
		(net "M_C_CPU1_SB_DQ<14>")
	)
	(arc
		(start 92.528136 -282.673806)
		(mid 92.811092 -282.749983)
		(end 93.094048 -282.673806)
		(width 0.0889)
		(layer "In2.Cu")
		(net "M_C_CPU1_SB_DQ<14>")
	)
	(arc
		(start 87.46236 -282.66898)
		(mid 87.645868 -282.623486)
		(end 87.82812 -282.673806)
		(width 0.0889)
		(layer "In2.Cu")
		(net "M_C_CPU1_SB_DQ<14>")
	)
	(arc
		(start 90.648028 -282.673806)
		(mid 90.930984 -282.749983)
		(end 91.21394 -282.673806)
		(width 0.0889)
		(layer "In2.Cu")
		(net "M_C_CPU1_SB_DQ<14>")
	)
	(arc
		(start 82.762344 -282.66898)
		(mid 82.945852 -282.623486)
		(end 83.128104 -282.673806)
		(width 0.0889)
		(layer "In2.Cu")
		(net "M_C_CPU1_SB_DQ<14>")
	)
	(arc
		(start 90.273886 -282.673806)
		(mid 90.456137 -282.623456)
		(end 90.639646 -282.66898)
		(width 0.0889)
		(layer "In2.Cu")
		(net "M_C_CPU1_SB_DQ<14>")
	)
	(arc
		(start 83.128104 -282.673806)
		(mid 83.41106 -282.749983)
		(end 83.694016 -282.673806)
		(width 0.0889)
		(layer "In2.Cu")
		(net "M_C_CPU1_SB_DQ<14>")
	)
	(arc
		(start 89.334086 -282.673806)
		(mid 89.52103 -282.623551)
		(end 89.707974 -282.673806)
		(width 0.0889)
		(layer "In2.Cu")
		(net "M_C_CPU1_SB_DQ<14>")
	)
	(arc
		(start 84.63407 -282.673806)
		(mid 84.821014 -282.623551)
		(end 85.007958 -282.673806)
		(width 0.0889)
		(layer "In2.Cu")
		(net "M_C_CPU1_SB_DQ<14>")
	)
	(arc
		(start 80.308196 -282.673806)
		(mid 80.591152 -282.749983)
		(end 80.874108 -282.673806)
		(width 0.0889)
		(layer "In2.Cu")
		(net "M_C_CPU1_SB_DQ<14>")
	)
	(arc
		(start 81.247996 -282.673806)
		(mid 81.530952 -282.749983)
		(end 81.813908 -282.673806)
		(width 0.0889)
		(layer "In2.Cu")
		(net "M_C_CPU1_SB_DQ<14>")
	)
	(arc
		(start 92.162376 -282.66898)
		(mid 92.345884 -282.623486)
		(end 92.528136 -282.673806)
		(width 0.0889)
		(layer "In2.Cu")
		(net "M_C_CPU1_SB_DQ<14>")
	)
	(arc
		(start 80.874108 -282.673806)
		(mid 81.061052 -282.623551)
		(end 81.247996 -282.673806)
		(width 0.0889)
		(layer "In2.Cu")
		(net "M_C_CPU1_SB_DQ<14>")
	)
	(arc
		(start 84.068158 -282.673806)
		(mid 84.351114 -282.749983)
		(end 84.63407 -282.673806)
		(width 0.0889)
		(layer "In2.Cu")
		(net "M_C_CPU1_SB_DQ<14>")
	)
	(arc
		(start 91.21394 -282.673806)
		(mid 91.396191 -282.623456)
		(end 91.5797 -282.66898)
		(width 0.0889)
		(layer "In2.Cu")
		(net "M_C_CPU1_SB_DQ<14>")
	)
	(arc
		(start 94.034102 -282.673806)
		(mid 94.190421 -282.624811)
		(end 94.352618 -282.647644)
		(width 0.0889)
		(layer "In2.Cu")
		(net "M_C_CPU1_SB_DQ<14>")
	)
	(arc
		(start 88.402414 -282.66898)
		(mid 88.585922 -282.623486)
		(end 88.768174 -282.673806)
		(width 0.0889)
		(layer "In2.Cu")
		(net "M_C_CPU1_SB_DQ<14>")
	)
	(arc
		(start 87.82812 -282.673806)
		(mid 88.111076 -282.749983)
		(end 88.394032 -282.673806)
		(width 0.0889)
		(layer "In2.Cu")
		(net "M_C_CPU1_SB_DQ<14>")
	)
	(arc
		(start 79.37119 -282.673806)
		(mid 79.63951 -282.749914)
		(end 79.911448 -282.68803)
		(width 0.0889)
		(layer "In2.Cu")
		(net "M_C_CPU1_SB_DQ<14>")
	)
	(arc
		(start 89.707974 -282.673806)
		(mid 89.99093 -282.749983)
		(end 90.273886 -282.673806)
		(width 0.0889)
		(layer "In2.Cu")
		(net "M_C_CPU1_SB_DQ<14>")
	)
	(arc
		(start 85.948012 -282.673806)
		(mid 86.230968 -282.749983)
		(end 86.513924 -282.673806)
		(width 0.0889)
		(layer "In2.Cu")
		(net "M_C_CPU1_SB_DQ<14>")
	)
	(arc
		(start 93.10243 -282.66898)
		(mid 93.285938 -282.623486)
		(end 93.46819 -282.673806)
		(width 0.0889)
		(layer "In2.Cu")
		(net "M_C_CPU1_SB_DQ<14>")
	)
	(arc
		(start 77.930502 -282.840176)
		(mid 78.023381 -282.778116)
		(end 78.13294 -282.756356)
		(width 0.0889)
		(layer "In2.Cu")
		(net "M_C_CPU1_SB_DQ<14>")
	)
	(arc
		(start 81.813908 -282.673806)
		(mid 81.996159 -282.623456)
		(end 82.179668 -282.66898)
		(width 0.0889)
		(layer "In2.Cu")
		(net "M_C_CPU1_SB_DQ<14>")
	)
	(arc
		(start 86.888066 -282.673806)
		(mid 87.171022 -282.749983)
		(end 87.453978 -282.673806)
		(width 0.0889)
		(layer "In2.Cu")
		(net "M_C_CPU1_SB_DQ<14>")
	)
	(segment
		(start 96.568006 -282.730448)
		(end 96.101154 -282.996386)
		(width 0.10668)
		(layer "F.Cu")
		(net "M_C_CPU1_SB_DQ<13>")
	)
	(segment
		(start 53.081936 -298.060364)
		(end 53.932074 -298.910502)
		(width 0.14478)
		(layer "In2.Cu")
		(net "M_C_CPU1_SB_DQ<13>")
	)
	(segment
		(start 87.453978 -283.318966)
		(end 87.46236 -283.323792)
		(width 0.0889)
		(layer "In2.Cu")
		(net "M_C_CPU1_SB_DQ<13>")
	)
	(segment
		(start 82.179668 -283.323792)
		(end 82.18805 -283.318966)
		(width 0.0889)
		(layer "In2.Cu")
		(net "M_C_CPU1_SB_DQ<13>")
	)
	(segment
		(start 83.694016 -283.318966)
		(end 83.702398 -283.323792)
		(width 0.0889)
		(layer "In2.Cu")
		(net "M_C_CPU1_SB_DQ<13>")
	)
	(segment
		(start 95.946976 -283.261816)
		(end 96.101154 -282.996386)
		(width 0.0889)
		(layer "In2.Cu")
		(net "M_C_CPU1_SB_DQ<13>")
	)
	(segment
		(start 78.993492 -283.318712)
		(end 79.007208 -283.326586)
		(width 0.0889)
		(layer "In2.Cu")
		(net "M_C_CPU1_SB_DQ<13>")
	)
	(segment
		(start 45.348906 -299.263562)
		(end 45.51172 -299.100748)
		(width 0.14478)
		(layer "In2.Cu")
		(net "M_C_CPU1_SB_DQ<13>")
	)
	(segment
		(start 46.230794 -299.263562)
		(end 46.461426 -299.263562)
		(width 0.14478)
		(layer "In2.Cu")
		(net "M_C_CPU1_SB_DQ<13>")
	)
	(segment
		(start 46.461426 -299.263562)
		(end 46.814486 -298.910502)
		(width 0.14478)
		(layer "In2.Cu")
		(net "M_C_CPU1_SB_DQ<13>")
	)
	(segment
		(start 80.299814 -283.323792)
		(end 80.308196 -283.318966)
		(width 0.0889)
		(layer "In2.Cu")
		(net "M_C_CPU1_SB_DQ<13>")
	)
	(segment
		(start 45.674534 -298.578524)
		(end 45.905166 -298.578524)
		(width 0.14478)
		(layer "In2.Cu")
		(net "M_C_CPU1_SB_DQ<13>")
	)
	(segment
		(start 56.877458 -299.274484)
		(end 57.24144 -298.910502)
		(width 0.14478)
		(layer "In2.Cu")
		(net "M_C_CPU1_SB_DQ<13>")
	)
	(segment
		(start 45.51172 -298.741338)
		(end 45.674534 -298.578524)
		(width 0.14478)
		(layer "In2.Cu")
		(net "M_C_CPU1_SB_DQ<13>")
	)
	(segment
		(start 90.639646 -283.323792)
		(end 90.648028 -283.318966)
		(width 0.0889)
		(layer "In2.Cu")
		(net "M_C_CPU1_SB_DQ<13>")
	)
	(segment
		(start 92.153994 -283.318966)
		(end 92.162376 -283.323792)
		(width 0.0889)
		(layer "In2.Cu")
		(net "M_C_CPU1_SB_DQ<13>")
	)
	(segment
		(start 56.484012 -298.667424)
		(end 56.484012 -299.11167)
		(width 0.14478)
		(layer "In2.Cu")
		(net "M_C_CPU1_SB_DQ<13>")
	)
	(segment
		(start 53.932074 -298.910502)
		(end 55.578248 -298.910502)
		(width 0.14478)
		(layer "In2.Cu")
		(net "M_C_CPU1_SB_DQ<13>")
	)
	(segment
		(start 56.484012 -299.11167)
		(end 56.646826 -299.274484)
		(width 0.14478)
		(layer "In2.Cu")
		(net "M_C_CPU1_SB_DQ<13>")
	)
	(segment
		(start 93.094048 -283.318966)
		(end 93.10243 -283.323792)
		(width 0.0889)
		(layer "In2.Cu")
		(net "M_C_CPU1_SB_DQ<13>")
	)
	(segment
		(start 88.394032 -283.318966)
		(end 88.402414 -283.323792)
		(width 0.0889)
		(layer "In2.Cu")
		(net "M_C_CPU1_SB_DQ<13>")
	)
	(segment
		(start 45.51172 -299.100748)
		(end 45.51172 -298.741338)
		(width 0.14478)
		(layer "In2.Cu")
		(net "M_C_CPU1_SB_DQ<13>")
	)
	(segment
		(start 56.334152 -298.517564)
		(end 56.484012 -298.667424)
		(width 0.14478)
		(layer "In2.Cu")
		(net "M_C_CPU1_SB_DQ<13>")
	)
	(segment
		(start 91.5797 -283.323792)
		(end 91.588082 -283.318966)
		(width 0.0889)
		(layer "In2.Cu")
		(net "M_C_CPU1_SB_DQ<13>")
	)
	(segment
		(start 55.971186 -298.517564)
		(end 56.334152 -298.517564)
		(width 0.14478)
		(layer "In2.Cu")
		(net "M_C_CPU1_SB_DQ<13>")
	)
	(segment
		(start 49.049432 -299.264324)
		(end 49.557432 -299.264324)
		(width 0.14478)
		(layer "In2.Cu")
		(net "M_C_CPU1_SB_DQ<13>")
	)
	(segment
		(start 82.753962 -283.318966)
		(end 82.762344 -283.323792)
		(width 0.0889)
		(layer "In2.Cu")
		(net "M_C_CPU1_SB_DQ<13>")
	)
	(segment
		(start 46.06798 -299.100748)
		(end 46.230794 -299.263562)
		(width 0.14478)
		(layer "In2.Cu")
		(net "M_C_CPU1_SB_DQ<13>")
	)
	(segment
		(start 55.578248 -298.910502)
		(end 55.971186 -298.517564)
		(width 0.14478)
		(layer "In2.Cu")
		(net "M_C_CPU1_SB_DQ<13>")
	)
	(segment
		(start 67.670426 -290.534852)
		(end 74.748644 -283.456634)
		(width 0.14478)
		(layer "In2.Cu")
		(net "M_C_CPU1_SB_DQ<13>")
	)
	(segment
		(start 86.879684 -283.323792)
		(end 86.888066 -283.318966)
		(width 0.0889)
		(layer "In2.Cu")
		(net "M_C_CPU1_SB_DQ<13>")
	)
	(segment
		(start 67.670426 -292.5826)
		(end 67.670426 -290.534852)
		(width 0.14478)
		(layer "In2.Cu")
		(net "M_C_CPU1_SB_DQ<13>")
	)
	(segment
		(start 75.968606 -283.456634)
		(end 76.546456 -283.456634)
		(width 0.0889)
		(layer "In2.Cu")
		(net "M_C_CPU1_SB_DQ<13>")
	)
	(segment
		(start 46.06798 -298.741338)
		(end 46.06798 -299.100748)
		(width 0.14478)
		(layer "In2.Cu")
		(net "M_C_CPU1_SB_DQ<13>")
	)
	(segment
		(start 45.118274 -299.263562)
		(end 45.348906 -299.263562)
		(width 0.14478)
		(layer "In2.Cu")
		(net "M_C_CPU1_SB_DQ<13>")
	)
	(segment
		(start 58.279792 -298.060364)
		(end 62.192662 -298.060364)
		(width 0.14478)
		(layer "In2.Cu")
		(net "M_C_CPU1_SB_DQ<13>")
	)
	(segment
		(start 76.799186 -283.709364)
		(end 77.895704 -283.709364)
		(width 0.0889)
		(layer "In2.Cu")
		(net "M_C_CPU1_SB_DQ<13>")
	)
	(segment
		(start 46.814486 -298.910502)
		(end 48.69561 -298.910502)
		(width 0.14478)
		(layer "In2.Cu")
		(net "M_C_CPU1_SB_DQ<13>")
	)
	(segment
		(start 95.339662 -283.323792)
		(end 95.348044 -283.318966)
		(width 0.0889)
		(layer "In2.Cu")
		(net "M_C_CPU1_SB_DQ<13>")
	)
	(segment
		(start 79.367126 -283.318966)
		(end 79.381858 -283.31033)
		(width 0.0889)
		(layer "In2.Cu")
		(net "M_C_CPU1_SB_DQ<13>")
	)
	(segment
		(start 74.748644 -283.456634)
		(end 75.968606 -283.456634)
		(width 0.14478)
		(layer "In2.Cu")
		(net "M_C_CPU1_SB_DQ<13>")
	)
	(segment
		(start 78.977744 -283.309568)
		(end 78.993492 -283.318712)
		(width 0.0889)
		(layer "In2.Cu")
		(net "M_C_CPU1_SB_DQ<13>")
	)
	(segment
		(start 56.646826 -299.274484)
		(end 56.877458 -299.274484)
		(width 0.14478)
		(layer "In2.Cu")
		(net "M_C_CPU1_SB_DQ<13>")
	)
	(segment
		(start 48.69561 -298.910502)
		(end 49.049432 -299.264324)
		(width 0.14478)
		(layer "In2.Cu")
		(net "M_C_CPU1_SB_DQ<13>")
	)
	(segment
		(start 44.340018 -298.485306)
		(end 45.118274 -299.263562)
		(width 0.14478)
		(layer "In2.Cu")
		(net "M_C_CPU1_SB_DQ<13>")
	)
	(segment
		(start 57.429654 -298.910502)
		(end 58.279792 -298.060364)
		(width 0.14478)
		(layer "In2.Cu")
		(net "M_C_CPU1_SB_DQ<13>")
	)
	(segment
		(start 50.761392 -298.060364)
		(end 53.081936 -298.060364)
		(width 0.14478)
		(layer "In2.Cu")
		(net "M_C_CPU1_SB_DQ<13>")
	)
	(segment
		(start 45.905166 -298.578524)
		(end 46.06798 -298.741338)
		(width 0.14478)
		(layer "In2.Cu")
		(net "M_C_CPU1_SB_DQ<13>")
	)
	(segment
		(start 85.93963 -283.323792)
		(end 85.948012 -283.318966)
		(width 0.0889)
		(layer "In2.Cu")
		(net "M_C_CPU1_SB_DQ<13>")
	)
	(segment
		(start 78.018386 -283.658564)
		(end 78.275942 -283.401008)
		(width 0.0889)
		(layer "In2.Cu")
		(net "M_C_CPU1_SB_DQ<13>")
	)
	(segment
		(start 57.24144 -298.910502)
		(end 57.429654 -298.910502)
		(width 0.14478)
		(layer "In2.Cu")
		(net "M_C_CPU1_SB_DQ<13>")
	)
	(segment
		(start 49.557432 -299.264324)
		(end 50.761392 -298.060364)
		(width 0.14478)
		(layer "In2.Cu")
		(net "M_C_CPU1_SB_DQ<13>")
	)
	(segment
		(start 62.192662 -298.060364)
		(end 67.670426 -292.5826)
		(width 0.14478)
		(layer "In2.Cu")
		(net "M_C_CPU1_SB_DQ<13>")
	)
	(segment
		(start 95.85071 -283.287216)
		(end 95.946976 -283.261816)
		(width 0.0889)
		(layer "In2.Cu")
		(net "M_C_CPU1_SB_DQ<13>")
	)
	(segment
		(start 76.546456 -283.456634)
		(end 76.799186 -283.709364)
		(width 0.0889)
		(layer "In2.Cu")
		(net "M_C_CPU1_SB_DQ<13>")
	)
	(arc
		(start 93.10243 -283.323792)
		(mid 93.285938 -283.369286)
		(end 93.46819 -283.318966)
		(width 0.0889)
		(layer "In2.Cu")
		(net "M_C_CPU1_SB_DQ<13>")
	)
	(arc
		(start 85.57387 -283.318966)
		(mid 85.756121 -283.369316)
		(end 85.93963 -283.323792)
		(width 0.0889)
		(layer "In2.Cu")
		(net "M_C_CPU1_SB_DQ<13>")
	)
	(arc
		(start 82.762344 -283.323792)
		(mid 82.945852 -283.369286)
		(end 83.128104 -283.318966)
		(width 0.0889)
		(layer "In2.Cu")
		(net "M_C_CPU1_SB_DQ<13>")
	)
	(arc
		(start 86.888066 -283.318966)
		(mid 87.171022 -283.242789)
		(end 87.453978 -283.318966)
		(width 0.0889)
		(layer "In2.Cu")
		(net "M_C_CPU1_SB_DQ<13>")
	)
	(arc
		(start 81.813908 -283.318966)
		(mid 81.996159 -283.369316)
		(end 82.179668 -283.323792)
		(width 0.0889)
		(layer "In2.Cu")
		(net "M_C_CPU1_SB_DQ<13>")
	)
	(arc
		(start 89.707974 -283.318966)
		(mid 89.99093 -283.242789)
		(end 90.273886 -283.318966)
		(width 0.0889)
		(layer "In2.Cu")
		(net "M_C_CPU1_SB_DQ<13>")
	)
	(arc
		(start 88.402414 -283.323792)
		(mid 88.585922 -283.369286)
		(end 88.768174 -283.318966)
		(width 0.0889)
		(layer "In2.Cu")
		(net "M_C_CPU1_SB_DQ<13>")
	)
	(arc
		(start 83.702398 -283.323792)
		(mid 83.885906 -283.369286)
		(end 84.068158 -283.318966)
		(width 0.0889)
		(layer "In2.Cu")
		(net "M_C_CPU1_SB_DQ<13>")
	)
	(arc
		(start 85.007958 -283.318966)
		(mid 85.290914 -283.242789)
		(end 85.57387 -283.318966)
		(width 0.0889)
		(layer "In2.Cu")
		(net "M_C_CPU1_SB_DQ<13>")
	)
	(arc
		(start 79.381858 -283.31033)
		(mid 79.658841 -283.242526)
		(end 79.933546 -283.318966)
		(width 0.0889)
		(layer "In2.Cu")
		(net "M_C_CPU1_SB_DQ<13>")
	)
	(arc
		(start 83.128104 -283.318966)
		(mid 83.41106 -283.242789)
		(end 83.694016 -283.318966)
		(width 0.0889)
		(layer "In2.Cu")
		(net "M_C_CPU1_SB_DQ<13>")
	)
	(arc
		(start 87.46236 -283.323792)
		(mid 87.645868 -283.369286)
		(end 87.82812 -283.318966)
		(width 0.0889)
		(layer "In2.Cu")
		(net "M_C_CPU1_SB_DQ<13>")
	)
	(arc
		(start 82.18805 -283.318966)
		(mid 82.471006 -283.242789)
		(end 82.753962 -283.318966)
		(width 0.0889)
		(layer "In2.Cu")
		(net "M_C_CPU1_SB_DQ<13>")
	)
	(arc
		(start 90.648028 -283.318966)
		(mid 90.930984 -283.242789)
		(end 91.21394 -283.318966)
		(width 0.0889)
		(layer "In2.Cu")
		(net "M_C_CPU1_SB_DQ<13>")
	)
	(arc
		(start 84.068158 -283.318966)
		(mid 84.351114 -283.242789)
		(end 84.63407 -283.318966)
		(width 0.0889)
		(layer "In2.Cu")
		(net "M_C_CPU1_SB_DQ<13>")
	)
	(arc
		(start 81.247996 -283.318966)
		(mid 81.530952 -283.242789)
		(end 81.813908 -283.318966)
		(width 0.0889)
		(layer "In2.Cu")
		(net "M_C_CPU1_SB_DQ<13>")
	)
	(arc
		(start 89.334086 -283.318966)
		(mid 89.52103 -283.369221)
		(end 89.707974 -283.318966)
		(width 0.0889)
		(layer "In2.Cu")
		(net "M_C_CPU1_SB_DQ<13>")
	)
	(arc
		(start 80.874108 -283.318966)
		(mid 81.061052 -283.369221)
		(end 81.247996 -283.318966)
		(width 0.0889)
		(layer "In2.Cu")
		(net "M_C_CPU1_SB_DQ<13>")
	)
	(arc
		(start 92.162376 -283.323792)
		(mid 92.345884 -283.369286)
		(end 92.528136 -283.318966)
		(width 0.0889)
		(layer "In2.Cu")
		(net "M_C_CPU1_SB_DQ<13>")
	)
	(arc
		(start 86.513924 -283.318966)
		(mid 86.696175 -283.369316)
		(end 86.879684 -283.323792)
		(width 0.0889)
		(layer "In2.Cu")
		(net "M_C_CPU1_SB_DQ<13>")
	)
	(arc
		(start 78.275942 -283.401008)
		(mid 78.611309 -283.235866)
		(end 78.977744 -283.309568)
		(width 0.0889)
		(layer "In2.Cu")
		(net "M_C_CPU1_SB_DQ<13>")
	)
	(arc
		(start 79.933546 -283.318966)
		(mid 80.116051 -283.369443)
		(end 80.299814 -283.323792)
		(width 0.0889)
		(layer "In2.Cu")
		(net "M_C_CPU1_SB_DQ<13>")
	)
	(arc
		(start 93.46819 -283.318966)
		(mid 93.751146 -283.242789)
		(end 94.034102 -283.318966)
		(width 0.0889)
		(layer "In2.Cu")
		(net "M_C_CPU1_SB_DQ<13>")
	)
	(arc
		(start 91.588082 -283.318966)
		(mid 91.871038 -283.242789)
		(end 92.153994 -283.318966)
		(width 0.0889)
		(layer "In2.Cu")
		(net "M_C_CPU1_SB_DQ<13>")
	)
	(arc
		(start 85.948012 -283.318966)
		(mid 86.230968 -283.242789)
		(end 86.513924 -283.318966)
		(width 0.0889)
		(layer "In2.Cu")
		(net "M_C_CPU1_SB_DQ<13>")
	)
	(arc
		(start 92.528136 -283.318966)
		(mid 92.811092 -283.242789)
		(end 93.094048 -283.318966)
		(width 0.0889)
		(layer "In2.Cu")
		(net "M_C_CPU1_SB_DQ<13>")
	)
	(arc
		(start 95.348044 -283.318966)
		(mid 95.59564 -283.243788)
		(end 95.85071 -283.287216)
		(width 0.0889)
		(layer "In2.Cu")
		(net "M_C_CPU1_SB_DQ<13>")
	)
	(arc
		(start 77.895704 -283.709364)
		(mid 77.962093 -283.696158)
		(end 78.018386 -283.658564)
		(width 0.0889)
		(layer "In2.Cu")
		(net "M_C_CPU1_SB_DQ<13>")
	)
	(arc
		(start 80.308196 -283.318966)
		(mid 80.591152 -283.242789)
		(end 80.874108 -283.318966)
		(width 0.0889)
		(layer "In2.Cu")
		(net "M_C_CPU1_SB_DQ<13>")
	)
	(arc
		(start 88.768174 -283.318966)
		(mid 89.05113 -283.242789)
		(end 89.334086 -283.318966)
		(width 0.0889)
		(layer "In2.Cu")
		(net "M_C_CPU1_SB_DQ<13>")
	)
	(arc
		(start 84.63407 -283.318966)
		(mid 84.821014 -283.369221)
		(end 85.007958 -283.318966)
		(width 0.0889)
		(layer "In2.Cu")
		(net "M_C_CPU1_SB_DQ<13>")
	)
	(arc
		(start 79.007208 -283.326586)
		(mid 79.188138 -283.369064)
		(end 79.367126 -283.318966)
		(width 0.0889)
		(layer "In2.Cu")
		(net "M_C_CPU1_SB_DQ<13>")
	)
	(arc
		(start 87.82812 -283.318966)
		(mid 88.111076 -283.242789)
		(end 88.394032 -283.318966)
		(width 0.0889)
		(layer "In2.Cu")
		(net "M_C_CPU1_SB_DQ<13>")
	)
	(arc
		(start 91.21394 -283.318966)
		(mid 91.396191 -283.369316)
		(end 91.5797 -283.323792)
		(width 0.0889)
		(layer "In2.Cu")
		(net "M_C_CPU1_SB_DQ<13>")
	)
	(arc
		(start 94.034102 -283.318966)
		(mid 94.221046 -283.369221)
		(end 94.40799 -283.318966)
		(width 0.0889)
		(layer "In2.Cu")
		(net "M_C_CPU1_SB_DQ<13>")
	)
	(arc
		(start 94.40799 -283.318966)
		(mid 94.690946 -283.242789)
		(end 94.973902 -283.318966)
		(width 0.0889)
		(layer "In2.Cu")
		(net "M_C_CPU1_SB_DQ<13>")
	)
	(arc
		(start 94.973902 -283.318966)
		(mid 95.156153 -283.369316)
		(end 95.339662 -283.323792)
		(width 0.0889)
		(layer "In2.Cu")
		(net "M_C_CPU1_SB_DQ<13>")
	)
	(arc
		(start 90.273886 -283.318966)
		(mid 90.456137 -283.369316)
		(end 90.639646 -283.323792)
		(width 0.0889)
		(layer "In2.Cu")
		(net "M_C_CPU1_SB_DQ<13>")
	)
	(segment
		(start 95.157798 -281.920442)
		(end 94.690946 -282.18638)
		(width 0.10668)
		(layer "F.Cu")
		(net "M_C_CPU1_SB_DQ<12>")
	)
	(segment
		(start 66.247518 -292.718744)
		(end 66.247518 -292.488112)
		(width 0.14478)
		(layer "In2.Cu")
		(net "M_C_CPU1_SB_DQ<12>")
	)
	(segment
		(start 64.279018 -294.456612)
		(end 64.50965 -294.456612)
		(width 0.14478)
		(layer "In2.Cu")
		(net "M_C_CPU1_SB_DQ<12>")
	)
	(segment
		(start 66.133472 -292.374066)
		(end 66.133472 -292.143434)
		(width 0.14478)
		(layer "In2.Cu")
		(net "M_C_CPU1_SB_DQ<12>")
	)
	(segment
		(start 45.741336 -297.021504)
		(end 45.971714 -297.021504)
		(width 0.14478)
		(layer "In2.Cu")
		(net "M_C_CPU1_SB_DQ<12>")
	)
	(segment
		(start 66.761106 -290.157916)
		(end 74.371708 -282.547314)
		(width 0.14478)
		(layer "In2.Cu")
		(net "M_C_CPU1_SB_DQ<12>")
	)
	(segment
		(start 45.15739 -297.603164)
		(end 45.4152 -297.603164)
		(width 0.14478)
		(layer "In2.Cu")
		(net "M_C_CPU1_SB_DQ<12>")
	)
	(segment
		(start 63.885318 -294.850312)
		(end 63.771272 -294.736266)
		(width 0.14478)
		(layer "In2.Cu")
		(net "M_C_CPU1_SB_DQ<12>")
	)
	(segment
		(start 75.936856 -282.547314)
		(end 76.121006 -282.363164)
		(width 0.0889)
		(layer "In2.Cu")
		(net "M_C_CPU1_SB_DQ<12>")
	)
	(segment
		(start 57.333896 -297.21048)
		(end 57.635902 -297.21048)
		(width 0.14478)
		(layer "In2.Cu")
		(net "M_C_CPU1_SB_DQ<12>")
	)
	(segment
		(start 74.371708 -282.547314)
		(end 75.936856 -282.547314)
		(width 0.14478)
		(layer "In2.Cu")
		(net "M_C_CPU1_SB_DQ<12>")
	)
	(segment
		(start 44.765214 -297.21048)
		(end 44.765214 -297.210988)
		(width 0.14478)
		(layer "In2.Cu")
		(net "M_C_CPU1_SB_DQ<12>")
	)
	(segment
		(start 77.815186 -282.363164)
		(end 77.942186 -282.490164)
		(width 0.0889)
		(layer "In2.Cu")
		(net "M_C_CPU1_SB_DQ<12>")
	)
	(segment
		(start 60.870846 -296.753026)
		(end 61.099192 -296.753026)
		(width 0.14478)
		(layer "In2.Cu")
		(net "M_C_CPU1_SB_DQ<12>")
	)
	(segment
		(start 44.765214 -297.210988)
		(end 45.15739 -297.603164)
		(width 0.14478)
		(layer "In2.Cu")
		(net "M_C_CPU1_SB_DQ<12>")
	)
	(segment
		(start 60.709302 -296.521886)
		(end 60.709302 -296.591482)
		(width 0.14478)
		(layer "In2.Cu")
		(net "M_C_CPU1_SB_DQ<12>")
	)
	(segment
		(start 62.35954 -295.917366)
		(end 62.590172 -295.917366)
		(width 0.14478)
		(layer "In2.Cu")
		(net "M_C_CPU1_SB_DQ<12>")
	)
	(segment
		(start 66.133472 -292.143434)
		(end 66.761106 -291.5158)
		(width 0.14478)
		(layer "In2.Cu")
		(net "M_C_CPU1_SB_DQ<12>")
	)
	(segment
		(start 49.216818 -297.514264)
		(end 49.4919 -297.514264)
		(width 0.14478)
		(layer "In2.Cu")
		(net "M_C_CPU1_SB_DQ<12>")
	)
	(segment
		(start 65.460118 -293.506144)
		(end 65.460118 -293.275512)
		(width 0.14478)
		(layer "In2.Cu")
		(net "M_C_CPU1_SB_DQ<12>")
	)
	(segment
		(start 45.578268 -297.184572)
		(end 45.741336 -297.021504)
		(width 0.14478)
		(layer "In2.Cu")
		(net "M_C_CPU1_SB_DQ<12>")
	)
	(segment
		(start 62.704218 -296.031412)
		(end 62.93485 -296.031412)
		(width 0.14478)
		(layer "In2.Cu")
		(net "M_C_CPU1_SB_DQ<12>")
	)
	(segment
		(start 78.094332 -282.553156)
		(end 78.73619 -282.553156)
		(width 0.0889)
		(layer "In2.Cu")
		(net "M_C_CPU1_SB_DQ<12>")
	)
	(segment
		(start 76.121006 -282.363164)
		(end 77.815186 -282.363164)
		(width 0.0889)
		(layer "In2.Cu")
		(net "M_C_CPU1_SB_DQ<12>")
	)
	(segment
		(start 64.672718 -294.062912)
		(end 64.558672 -293.948866)
		(width 0.14478)
		(layer "In2.Cu")
		(net "M_C_CPU1_SB_DQ<12>")
	)
	(segment
		(start 45.578268 -297.440096)
		(end 45.578268 -297.184572)
		(width 0.14478)
		(layer "In2.Cu")
		(net "M_C_CPU1_SB_DQ<12>")
	)
	(segment
		(start 86.044024 -282.50896)
		(end 86.052406 -282.513786)
		(width 0.0889)
		(layer "In2.Cu")
		(net "M_C_CPU1_SB_DQ<12>")
	)
	(segment
		(start 60.547758 -296.360342)
		(end 60.709302 -296.521886)
		(width 0.14478)
		(layer "In2.Cu")
		(net "M_C_CPU1_SB_DQ<12>")
	)
	(segment
		(start 79.439516 -282.492958)
		(end 79.467202 -282.50896)
		(width 0.0889)
		(layer "In2.Cu")
		(net "M_C_CPU1_SB_DQ<12>")
	)
	(segment
		(start 80.769714 -282.513786)
		(end 80.778096 -282.50896)
		(width 0.0889)
		(layer "In2.Cu")
		(net "M_C_CPU1_SB_DQ<12>")
	)
	(segment
		(start 63.491618 -295.244012)
		(end 63.72225 -295.244012)
		(width 0.14478)
		(layer "In2.Cu")
		(net "M_C_CPU1_SB_DQ<12>")
	)
	(segment
		(start 66.761106 -291.5158)
		(end 66.761106 -290.157916)
		(width 0.14478)
		(layer "In2.Cu")
		(net "M_C_CPU1_SB_DQ<12>")
	)
	(segment
		(start 60.709302 -296.591482)
		(end 60.870846 -296.753026)
		(width 0.14478)
		(layer "In2.Cu")
		(net "M_C_CPU1_SB_DQ<12>")
	)
	(segment
		(start 64.72174 -293.555166)
		(end 64.952372 -293.555166)
		(width 0.14478)
		(layer "In2.Cu")
		(net "M_C_CPU1_SB_DQ<12>")
	)
	(segment
		(start 63.93434 -294.342566)
		(end 64.164972 -294.342566)
		(width 0.14478)
		(layer "In2.Cu")
		(net "M_C_CPU1_SB_DQ<12>")
	)
	(segment
		(start 89.803986 -282.50896)
		(end 89.812368 -282.513786)
		(width 0.0889)
		(layer "In2.Cu")
		(net "M_C_CPU1_SB_DQ<12>")
	)
	(segment
		(start 50.11801 -297.21048)
		(end 50.958496 -296.369994)
		(width 0.14478)
		(layer "In2.Cu")
		(net "M_C_CPU1_SB_DQ<12>")
	)
	(segment
		(start 64.558672 -293.718234)
		(end 64.72174 -293.555166)
		(width 0.14478)
		(layer "In2.Cu")
		(net "M_C_CPU1_SB_DQ<12>")
	)
	(segment
		(start 49.795684 -297.21048)
		(end 50.11801 -297.21048)
		(width 0.14478)
		(layer "In2.Cu")
		(net "M_C_CPU1_SB_DQ<12>")
	)
	(segment
		(start 79.83982 -282.508706)
		(end 79.863696 -282.494736)
		(width 0.0889)
		(layer "In2.Cu")
		(net "M_C_CPU1_SB_DQ<12>")
	)
	(segment
		(start 93.929708 -282.513786)
		(end 93.93809 -282.50896)
		(width 0.0889)
		(layer "In2.Cu")
		(net "M_C_CPU1_SB_DQ<12>")
	)
	(segment
		(start 58.486548 -296.360342)
		(end 60.547758 -296.360342)
		(width 0.14478)
		(layer "In2.Cu")
		(net "M_C_CPU1_SB_DQ<12>")
	)
	(segment
		(start 88.289638 -282.513786)
		(end 88.29802 -282.50896)
		(width 0.0889)
		(layer "In2.Cu")
		(net "M_C_CPU1_SB_DQ<12>")
	)
	(segment
		(start 46.626018 -297.603164)
		(end 47.00905 -297.220132)
		(width 0.14478)
		(layer "In2.Cu")
		(net "M_C_CPU1_SB_DQ<12>")
	)
	(segment
		(start 65.50914 -292.767766)
		(end 65.739772 -292.767766)
		(width 0.14478)
		(layer "In2.Cu")
		(net "M_C_CPU1_SB_DQ<12>")
	)
	(segment
		(start 62.983872 -295.523666)
		(end 62.983872 -295.293034)
		(width 0.14478)
		(layer "In2.Cu")
		(net "M_C_CPU1_SB_DQ<12>")
	)
	(segment
		(start 64.952372 -293.555166)
		(end 65.066418 -293.669212)
		(width 0.14478)
		(layer "In2.Cu")
		(net "M_C_CPU1_SB_DQ<12>")
	)
	(segment
		(start 89.229692 -282.513786)
		(end 89.238074 -282.50896)
		(width 0.0889)
		(layer "In2.Cu")
		(net "M_C_CPU1_SB_DQ<12>")
	)
	(segment
		(start 66.08445 -292.881812)
		(end 66.247518 -292.718744)
		(width 0.14478)
		(layer "In2.Cu")
		(net "M_C_CPU1_SB_DQ<12>")
	)
	(segment
		(start 57.636664 -297.210226)
		(end 58.486548 -296.360342)
		(width 0.14478)
		(layer "In2.Cu")
		(net "M_C_CPU1_SB_DQ<12>")
	)
	(segment
		(start 50.958496 -296.369994)
		(end 52.678076 -296.369994)
		(width 0.14478)
		(layer "In2.Cu")
		(net "M_C_CPU1_SB_DQ<12>")
	)
	(segment
		(start 65.853818 -292.881812)
		(end 66.08445 -292.881812)
		(width 0.14478)
		(layer "In2.Cu")
		(net "M_C_CPU1_SB_DQ<12>")
	)
	(segment
		(start 46.29785 -297.603164)
		(end 46.626018 -297.603164)
		(width 0.14478)
		(layer "In2.Cu")
		(net "M_C_CPU1_SB_DQ<12>")
	)
	(segment
		(start 56.451246 -297.21048)
		(end 56.75503 -297.514264)
		(width 0.14478)
		(layer "In2.Cu")
		(net "M_C_CPU1_SB_DQ<12>")
	)
	(segment
		(start 64.50965 -294.456612)
		(end 64.672718 -294.293544)
		(width 0.14478)
		(layer "In2.Cu")
		(net "M_C_CPU1_SB_DQ<12>")
	)
	(segment
		(start 47.00905 -297.220132)
		(end 48.922686 -297.220132)
		(width 0.14478)
		(layer "In2.Cu")
		(net "M_C_CPU1_SB_DQ<12>")
	)
	(segment
		(start 61.916564 -296.360342)
		(end 62.35954 -295.917366)
		(width 0.14478)
		(layer "In2.Cu")
		(net "M_C_CPU1_SB_DQ<12>")
	)
	(segment
		(start 52.678076 -296.369994)
		(end 53.518562 -297.21048)
		(width 0.14478)
		(layer "In2.Cu")
		(net "M_C_CPU1_SB_DQ<12>")
	)
	(segment
		(start 63.097918 -295.868344)
		(end 63.097918 -295.637712)
		(width 0.14478)
		(layer "In2.Cu")
		(net "M_C_CPU1_SB_DQ<12>")
	)
	(segment
		(start 65.346072 -293.161466)
		(end 65.346072 -292.930834)
		(width 0.14478)
		(layer "In2.Cu")
		(net "M_C_CPU1_SB_DQ<12>")
	)
	(segment
		(start 61.099192 -296.753026)
		(end 61.260736 -296.591482)
		(width 0.14478)
		(layer "In2.Cu")
		(net "M_C_CPU1_SB_DQ<12>")
	)
	(segment
		(start 66.247518 -292.488112)
		(end 66.133472 -292.374066)
		(width 0.14478)
		(layer "In2.Cu")
		(net "M_C_CPU1_SB_DQ<12>")
	)
	(segment
		(start 92.989654 -282.513786)
		(end 92.998036 -282.50896)
		(width 0.0889)
		(layer "In2.Cu")
		(net "M_C_CPU1_SB_DQ<12>")
	)
	(segment
		(start 64.558672 -293.948866)
		(end 64.558672 -293.718234)
		(width 0.14478)
		(layer "In2.Cu")
		(net "M_C_CPU1_SB_DQ<12>")
	)
	(segment
		(start 61.260736 -296.591482)
		(end 61.260736 -296.521886)
		(width 0.14478)
		(layer "In2.Cu")
		(net "M_C_CPU1_SB_DQ<12>")
	)
	(segment
		(start 65.066418 -293.669212)
		(end 65.29705 -293.669212)
		(width 0.14478)
		(layer "In2.Cu")
		(net "M_C_CPU1_SB_DQ<12>")
	)
	(segment
		(start 63.377572 -295.129966)
		(end 63.491618 -295.244012)
		(width 0.14478)
		(layer "In2.Cu")
		(net "M_C_CPU1_SB_DQ<12>")
	)
	(segment
		(start 45.4152 -297.603164)
		(end 45.578268 -297.440096)
		(width 0.14478)
		(layer "In2.Cu")
		(net "M_C_CPU1_SB_DQ<12>")
	)
	(segment
		(start 65.346072 -292.930834)
		(end 65.50914 -292.767766)
		(width 0.14478)
		(layer "In2.Cu")
		(net "M_C_CPU1_SB_DQ<12>")
	)
	(segment
		(start 63.771272 -294.505634)
		(end 63.93434 -294.342566)
		(width 0.14478)
		(layer "In2.Cu")
		(net "M_C_CPU1_SB_DQ<12>")
	)
	(segment
		(start 63.14694 -295.129966)
		(end 63.377572 -295.129966)
		(width 0.14478)
		(layer "In2.Cu")
		(net "M_C_CPU1_SB_DQ<12>")
	)
	(segment
		(start 45.971714 -297.021504)
		(end 46.134782 -297.184572)
		(width 0.14478)
		(layer "In2.Cu")
		(net "M_C_CPU1_SB_DQ<12>")
	)
	(segment
		(start 57.030112 -297.514264)
		(end 57.333896 -297.21048)
		(width 0.14478)
		(layer "In2.Cu")
		(net "M_C_CPU1_SB_DQ<12>")
	)
	(segment
		(start 64.164972 -294.342566)
		(end 64.279018 -294.456612)
		(width 0.14478)
		(layer "In2.Cu")
		(net "M_C_CPU1_SB_DQ<12>")
	)
	(segment
		(start 63.097918 -295.637712)
		(end 62.983872 -295.523666)
		(width 0.14478)
		(layer "In2.Cu")
		(net "M_C_CPU1_SB_DQ<12>")
	)
	(segment
		(start 62.590172 -295.917366)
		(end 62.704218 -296.031412)
		(width 0.14478)
		(layer "In2.Cu")
		(net "M_C_CPU1_SB_DQ<12>")
	)
	(segment
		(start 94.44101 -282.47721)
		(end 94.537022 -282.45181)
		(width 0.0889)
		(layer "In2.Cu")
		(net "M_C_CPU1_SB_DQ<12>")
	)
	(segment
		(start 63.771272 -294.736266)
		(end 63.771272 -294.505634)
		(width 0.14478)
		(layer "In2.Cu")
		(net "M_C_CPU1_SB_DQ<12>")
	)
	(segment
		(start 56.75503 -297.514264)
		(end 57.030112 -297.514264)
		(width 0.14478)
		(layer "In2.Cu")
		(net "M_C_CPU1_SB_DQ<12>")
	)
	(segment
		(start 46.134782 -297.184572)
		(end 46.134782 -297.440096)
		(width 0.14478)
		(layer "In2.Cu")
		(net "M_C_CPU1_SB_DQ<12>")
	)
	(segment
		(start 84.529676 -282.513786)
		(end 84.538058 -282.50896)
		(width 0.0889)
		(layer "In2.Cu")
		(net "M_C_CPU1_SB_DQ<12>")
	)
	(segment
		(start 63.72225 -295.244012)
		(end 63.885318 -295.080944)
		(width 0.14478)
		(layer "In2.Cu")
		(net "M_C_CPU1_SB_DQ<12>")
	)
	(segment
		(start 53.518562 -297.21048)
		(end 56.451246 -297.21048)
		(width 0.14478)
		(layer "In2.Cu")
		(net "M_C_CPU1_SB_DQ<12>")
	)
	(segment
		(start 49.4919 -297.514264)
		(end 49.795684 -297.21048)
		(width 0.14478)
		(layer "In2.Cu")
		(net "M_C_CPU1_SB_DQ<12>")
	)
	(segment
		(start 46.134782 -297.440096)
		(end 46.29785 -297.603164)
		(width 0.14478)
		(layer "In2.Cu")
		(net "M_C_CPU1_SB_DQ<12>")
	)
	(segment
		(start 65.460118 -293.275512)
		(end 65.346072 -293.161466)
		(width 0.14478)
		(layer "In2.Cu")
		(net "M_C_CPU1_SB_DQ<12>")
	)
	(segment
		(start 44.340018 -296.785284)
		(end 44.765214 -297.21048)
		(width 0.14478)
		(layer "In2.Cu")
		(net "M_C_CPU1_SB_DQ<12>")
	)
	(segment
		(start 94.537022 -282.45181)
		(end 94.690946 -282.18638)
		(width 0.0889)
		(layer "In2.Cu")
		(net "M_C_CPU1_SB_DQ<12>")
	)
	(segment
		(start 90.74404 -282.50896)
		(end 90.752422 -282.513786)
		(width 0.0889)
		(layer "In2.Cu")
		(net "M_C_CPU1_SB_DQ<12>")
	)
	(segment
		(start 64.672718 -294.293544)
		(end 64.672718 -294.062912)
		(width 0.14478)
		(layer "In2.Cu")
		(net "M_C_CPU1_SB_DQ<12>")
	)
	(segment
		(start 85.10397 -282.50896)
		(end 85.112352 -282.513786)
		(width 0.0889)
		(layer "In2.Cu")
		(net "M_C_CPU1_SB_DQ<12>")
	)
	(segment
		(start 48.922686 -297.220132)
		(end 49.216818 -297.514264)
		(width 0.14478)
		(layer "In2.Cu")
		(net "M_C_CPU1_SB_DQ<12>")
	)
	(segment
		(start 79.817976 -282.521152)
		(end 79.83982 -282.508706)
		(width 0.0889)
		(layer "In2.Cu")
		(net "M_C_CPU1_SB_DQ<12>")
	)
	(segment
		(start 62.93485 -296.031412)
		(end 63.097918 -295.868344)
		(width 0.14478)
		(layer "In2.Cu")
		(net "M_C_CPU1_SB_DQ<12>")
	)
	(segment
		(start 62.983872 -295.293034)
		(end 63.14694 -295.129966)
		(width 0.14478)
		(layer "In2.Cu")
		(net "M_C_CPU1_SB_DQ<12>")
	)
	(segment
		(start 61.42228 -296.360342)
		(end 61.916564 -296.360342)
		(width 0.14478)
		(layer "In2.Cu")
		(net "M_C_CPU1_SB_DQ<12>")
	)
	(segment
		(start 65.29705 -293.669212)
		(end 65.460118 -293.506144)
		(width 0.14478)
		(layer "In2.Cu")
		(net "M_C_CPU1_SB_DQ<12>")
	)
	(segment
		(start 57.635902 -297.21048)
		(end 57.636664 -297.210226)
		(width 0.14478)
		(layer "In2.Cu")
		(net "M_C_CPU1_SB_DQ<12>")
	)
	(segment
		(start 81.344008 -282.50896)
		(end 81.35239 -282.513786)
		(width 0.0889)
		(layer "In2.Cu")
		(net "M_C_CPU1_SB_DQ<12>")
	)
	(segment
		(start 61.260736 -296.521886)
		(end 61.42228 -296.360342)
		(width 0.14478)
		(layer "In2.Cu")
		(net "M_C_CPU1_SB_DQ<12>")
	)
	(segment
		(start 83.589622 -282.513786)
		(end 83.598004 -282.50896)
		(width 0.0889)
		(layer "In2.Cu")
		(net "M_C_CPU1_SB_DQ<12>")
	)
	(segment
		(start 63.885318 -295.080944)
		(end 63.885318 -294.850312)
		(width 0.14478)
		(layer "In2.Cu")
		(net "M_C_CPU1_SB_DQ<12>")
	)
	(segment
		(start 65.739772 -292.767766)
		(end 65.853818 -292.881812)
		(width 0.14478)
		(layer "In2.Cu")
		(net "M_C_CPU1_SB_DQ<12>")
	)
	(arc
		(start 80.778096 -282.50896)
		(mid 81.061052 -282.432783)
		(end 81.344008 -282.50896)
		(width 0.0889)
		(layer "In2.Cu")
		(net "M_C_CPU1_SB_DQ<12>")
	)
	(arc
		(start 85.478112 -282.50896)
		(mid 85.761068 -282.432783)
		(end 86.044024 -282.50896)
		(width 0.0889)
		(layer "In2.Cu")
		(net "M_C_CPU1_SB_DQ<12>")
	)
	(arc
		(start 78.73619 -282.553156)
		(mid 78.820783 -282.541903)
		(end 78.899512 -282.50896)
		(width 0.0889)
		(layer "In2.Cu")
		(net "M_C_CPU1_SB_DQ<12>")
	)
	(arc
		(start 85.112352 -282.513786)
		(mid 85.29586 -282.55928)
		(end 85.478112 -282.50896)
		(width 0.0889)
		(layer "In2.Cu")
		(net "M_C_CPU1_SB_DQ<12>")
	)
	(arc
		(start 86.052406 -282.513786)
		(mid 86.235914 -282.55928)
		(end 86.418166 -282.50896)
		(width 0.0889)
		(layer "In2.Cu")
		(net "M_C_CPU1_SB_DQ<12>")
	)
	(arc
		(start 81.35239 -282.513786)
		(mid 81.535898 -282.55928)
		(end 81.71815 -282.50896)
		(width 0.0889)
		(layer "In2.Cu")
		(net "M_C_CPU1_SB_DQ<12>")
	)
	(arc
		(start 77.942186 -282.490164)
		(mid 78.011991 -282.536806)
		(end 78.094332 -282.553156)
		(width 0.0889)
		(layer "In2.Cu")
		(net "M_C_CPU1_SB_DQ<12>")
	)
	(arc
		(start 82.65795 -282.50896)
		(mid 82.940906 -282.432783)
		(end 83.223862 -282.50896)
		(width 0.0889)
		(layer "In2.Cu")
		(net "M_C_CPU1_SB_DQ<12>")
	)
	(arc
		(start 81.71815 -282.50896)
		(mid 82.001106 -282.432783)
		(end 82.284062 -282.50896)
		(width 0.0889)
		(layer "In2.Cu")
		(net "M_C_CPU1_SB_DQ<12>")
	)
	(arc
		(start 86.418166 -282.50896)
		(mid 86.701122 -282.432783)
		(end 86.984078 -282.50896)
		(width 0.0889)
		(layer "In2.Cu")
		(net "M_C_CPU1_SB_DQ<12>")
	)
	(arc
		(start 91.118182 -282.50896)
		(mid 91.401138 -282.432783)
		(end 91.684094 -282.50896)
		(width 0.0889)
		(layer "In2.Cu")
		(net "M_C_CPU1_SB_DQ<12>")
	)
	(arc
		(start 91.684094 -282.50896)
		(mid 91.871038 -282.559215)
		(end 92.057982 -282.50896)
		(width 0.0889)
		(layer "In2.Cu")
		(net "M_C_CPU1_SB_DQ<12>")
	)
	(arc
		(start 82.284062 -282.50896)
		(mid 82.471006 -282.559215)
		(end 82.65795 -282.50896)
		(width 0.0889)
		(layer "In2.Cu")
		(net "M_C_CPU1_SB_DQ<12>")
	)
	(arc
		(start 78.899512 -282.50896)
		(mid 79.167481 -282.432137)
		(end 79.439516 -282.492958)
		(width 0.0889)
		(layer "In2.Cu")
		(net "M_C_CPU1_SB_DQ<12>")
	)
	(arc
		(start 83.598004 -282.50896)
		(mid 83.88096 -282.432783)
		(end 84.163916 -282.50896)
		(width 0.0889)
		(layer "In2.Cu")
		(net "M_C_CPU1_SB_DQ<12>")
	)
	(arc
		(start 83.223862 -282.50896)
		(mid 83.406113 -282.55931)
		(end 83.589622 -282.513786)
		(width 0.0889)
		(layer "In2.Cu")
		(net "M_C_CPU1_SB_DQ<12>")
	)
	(arc
		(start 79.467202 -282.50896)
		(mid 79.641052 -282.558866)
		(end 79.817976 -282.521152)
		(width 0.0889)
		(layer "In2.Cu")
		(net "M_C_CPU1_SB_DQ<12>")
	)
	(arc
		(start 89.238074 -282.50896)
		(mid 89.52103 -282.432783)
		(end 89.803986 -282.50896)
		(width 0.0889)
		(layer "In2.Cu")
		(net "M_C_CPU1_SB_DQ<12>")
	)
	(arc
		(start 79.863696 -282.494736)
		(mid 80.135633 -282.43291)
		(end 80.403954 -282.50896)
		(width 0.0889)
		(layer "In2.Cu")
		(net "M_C_CPU1_SB_DQ<12>")
	)
	(arc
		(start 87.357966 -282.50896)
		(mid 87.640922 -282.432783)
		(end 87.923878 -282.50896)
		(width 0.0889)
		(layer "In2.Cu")
		(net "M_C_CPU1_SB_DQ<12>")
	)
	(arc
		(start 88.29802 -282.50896)
		(mid 88.580976 -282.432783)
		(end 88.863932 -282.50896)
		(width 0.0889)
		(layer "In2.Cu")
		(net "M_C_CPU1_SB_DQ<12>")
	)
	(arc
		(start 93.93809 -282.50896)
		(mid 94.185803 -282.43374)
		(end 94.44101 -282.47721)
		(width 0.0889)
		(layer "In2.Cu")
		(net "M_C_CPU1_SB_DQ<12>")
	)
	(arc
		(start 92.998036 -282.50896)
		(mid 93.280992 -282.432783)
		(end 93.563948 -282.50896)
		(width 0.0889)
		(layer "In2.Cu")
		(net "M_C_CPU1_SB_DQ<12>")
	)
	(arc
		(start 86.984078 -282.50896)
		(mid 87.171022 -282.559215)
		(end 87.357966 -282.50896)
		(width 0.0889)
		(layer "In2.Cu")
		(net "M_C_CPU1_SB_DQ<12>")
	)
	(arc
		(start 84.538058 -282.50896)
		(mid 84.821014 -282.432783)
		(end 85.10397 -282.50896)
		(width 0.0889)
		(layer "In2.Cu")
		(net "M_C_CPU1_SB_DQ<12>")
	)
	(arc
		(start 89.812368 -282.513786)
		(mid 89.995876 -282.55928)
		(end 90.178128 -282.50896)
		(width 0.0889)
		(layer "In2.Cu")
		(net "M_C_CPU1_SB_DQ<12>")
	)
	(arc
		(start 80.403954 -282.50896)
		(mid 80.586205 -282.55931)
		(end 80.769714 -282.513786)
		(width 0.0889)
		(layer "In2.Cu")
		(net "M_C_CPU1_SB_DQ<12>")
	)
	(arc
		(start 90.178128 -282.50896)
		(mid 90.461084 -282.432783)
		(end 90.74404 -282.50896)
		(width 0.0889)
		(layer "In2.Cu")
		(net "M_C_CPU1_SB_DQ<12>")
	)
	(arc
		(start 87.923878 -282.50896)
		(mid 88.106129 -282.55931)
		(end 88.289638 -282.513786)
		(width 0.0889)
		(layer "In2.Cu")
		(net "M_C_CPU1_SB_DQ<12>")
	)
	(arc
		(start 93.563948 -282.50896)
		(mid 93.746199 -282.55931)
		(end 93.929708 -282.513786)
		(width 0.0889)
		(layer "In2.Cu")
		(net "M_C_CPU1_SB_DQ<12>")
	)
	(arc
		(start 92.057982 -282.50896)
		(mid 92.340938 -282.432783)
		(end 92.623894 -282.50896)
		(width 0.0889)
		(layer "In2.Cu")
		(net "M_C_CPU1_SB_DQ<12>")
	)
	(arc
		(start 92.623894 -282.50896)
		(mid 92.806145 -282.55931)
		(end 92.989654 -282.513786)
		(width 0.0889)
		(layer "In2.Cu")
		(net "M_C_CPU1_SB_DQ<12>")
	)
	(arc
		(start 90.752422 -282.513786)
		(mid 90.93593 -282.55928)
		(end 91.118182 -282.50896)
		(width 0.0889)
		(layer "In2.Cu")
		(net "M_C_CPU1_SB_DQ<12>")
	)
	(arc
		(start 88.863932 -282.50896)
		(mid 89.046183 -282.55931)
		(end 89.229692 -282.513786)
		(width 0.0889)
		(layer "In2.Cu")
		(net "M_C_CPU1_SB_DQ<12>")
	)
	(arc
		(start 84.163916 -282.50896)
		(mid 84.346167 -282.55931)
		(end 84.529676 -282.513786)
		(width 0.0889)
		(layer "In2.Cu")
		(net "M_C_CPU1_SB_DQ<12>")
	)
	(segment
		(start 96.097852 -280.30043)
		(end 95.631 -280.566368)
		(width 0.10668)
		(layer "F.Cu")
		(net "M_C_CPU1_SB_DQ<11>")
	)
	(segment
		(start 84.529676 -280.238962)
		(end 84.538058 -280.243788)
		(width 0.0889)
		(layer "In2.Cu")
		(net "M_C_CPU1_SB_DQ<11>")
	)
	(segment
		(start 95.444056 -280.243788)
		(end 95.452438 -280.238962)
		(width 0.0889)
		(layer "In2.Cu")
		(net "M_C_CPU1_SB_DQ<11>")
	)
	(segment
		(start 90.74404 -280.243788)
		(end 90.752422 -280.238962)
		(width 0.0889)
		(layer "In2.Cu")
		(net "M_C_CPU1_SB_DQ<11>")
	)
	(segment
		(start 42.203878 -293.127938)
		(end 42.203878 -293.647622)
		(width 0.14478)
		(layer "In2.Cu")
		(net "M_C_CPU1_SB_DQ<11>")
	)
	(segment
		(start 50.252376 -292.950646)
		(end 53.467508 -292.950646)
		(width 0.14478)
		(layer "In2.Cu")
		(net "M_C_CPU1_SB_DQ<11>")
	)
	(segment
		(start 53.467508 -292.950646)
		(end 54.327298 -293.810436)
		(width 0.14478)
		(layer "In2.Cu")
		(net "M_C_CPU1_SB_DQ<11>")
	)
	(segment
		(start 60.43803 -292.960298)
		(end 68.326508 -285.07182)
		(width 0.14478)
		(layer "In2.Cu")
		(net "M_C_CPU1_SB_DQ<11>")
	)
	(segment
		(start 79.438246 -280.26106)
		(end 79.46771 -280.243788)
		(width 0.0889)
		(layer "In2.Cu")
		(net "M_C_CPU1_SB_DQ<11>")
	)
	(segment
		(start 40.665146 -293.810436)
		(end 41.484804 -293.810436)
		(width 0.14478)
		(layer "In2.Cu")
		(net "M_C_CPU1_SB_DQ<11>")
	)
	(segment
		(start 79.840074 -280.244042)
		(end 79.866236 -280.259028)
		(width 0.0889)
		(layer "In2.Cu")
		(net "M_C_CPU1_SB_DQ<11>")
	)
	(segment
		(start 49.402492 -293.80053)
		(end 50.252376 -292.950646)
		(width 0.14478)
		(layer "In2.Cu")
		(net "M_C_CPU1_SB_DQ<11>")
	)
	(segment
		(start 42.203878 -293.647622)
		(end 42.356786 -293.80053)
		(width 0.14478)
		(layer "In2.Cu")
		(net "M_C_CPU1_SB_DQ<11>")
	)
	(segment
		(start 41.810432 -292.965124)
		(end 42.041064 -292.965124)
		(width 0.14478)
		(layer "In2.Cu")
		(net "M_C_CPU1_SB_DQ<11>")
	)
	(segment
		(start 89.803986 -280.243788)
		(end 89.812368 -280.238962)
		(width 0.0889)
		(layer "In2.Cu")
		(net "M_C_CPU1_SB_DQ<11>")
	)
	(segment
		(start 57.389776 -292.960298)
		(end 60.43803 -292.960298)
		(width 0.14478)
		(layer "In2.Cu")
		(net "M_C_CPU1_SB_DQ<11>")
	)
	(segment
		(start 92.989654 -280.238962)
		(end 92.998036 -280.243788)
		(width 0.0889)
		(layer "In2.Cu")
		(net "M_C_CPU1_SB_DQ<11>")
	)
	(segment
		(start 94.504002 -280.243788)
		(end 94.512384 -280.238962)
		(width 0.0889)
		(layer "In2.Cu")
		(net "M_C_CPU1_SB_DQ<11>")
	)
	(segment
		(start 68.564252 -285.07182)
		(end 73.428098 -280.207974)
		(width 0.14478)
		(layer "In2.Cu")
		(net "M_C_CPU1_SB_DQ<11>")
	)
	(segment
		(start 40.23995 -293.38524)
		(end 40.665146 -293.810436)
		(width 0.14478)
		(layer "In2.Cu")
		(net "M_C_CPU1_SB_DQ<11>")
	)
	(segment
		(start 68.326508 -285.07182)
		(end 68.564252 -285.07182)
		(width 0.14478)
		(layer "In2.Cu")
		(net "M_C_CPU1_SB_DQ<11>")
	)
	(segment
		(start 41.647618 -293.647622)
		(end 41.647618 -293.127938)
		(width 0.14478)
		(layer "In2.Cu")
		(net "M_C_CPU1_SB_DQ<11>")
	)
	(segment
		(start 80.769714 -280.238962)
		(end 80.778096 -280.243788)
		(width 0.0889)
		(layer "In2.Cu")
		(net "M_C_CPU1_SB_DQ<11>")
	)
	(segment
		(start 56.539638 -293.810436)
		(end 57.389776 -292.960298)
		(width 0.14478)
		(layer "In2.Cu")
		(net "M_C_CPU1_SB_DQ<11>")
	)
	(segment
		(start 76.013056 -280.207974)
		(end 78.767686 -280.207974)
		(width 0.0889)
		(layer "In2.Cu")
		(net "M_C_CPU1_SB_DQ<11>")
	)
	(segment
		(start 93.929708 -280.238962)
		(end 93.93809 -280.243788)
		(width 0.0889)
		(layer "In2.Cu")
		(net "M_C_CPU1_SB_DQ<11>")
	)
	(segment
		(start 86.044024 -280.243788)
		(end 86.052406 -280.238962)
		(width 0.0889)
		(layer "In2.Cu")
		(net "M_C_CPU1_SB_DQ<11>")
	)
	(segment
		(start 79.816706 -280.23058)
		(end 79.840074 -280.244042)
		(width 0.0889)
		(layer "In2.Cu")
		(net "M_C_CPU1_SB_DQ<11>")
	)
	(segment
		(start 83.589622 -280.238962)
		(end 83.598004 -280.243788)
		(width 0.0889)
		(layer "In2.Cu")
		(net "M_C_CPU1_SB_DQ<11>")
	)
	(segment
		(start 81.344008 -280.243788)
		(end 81.35239 -280.238962)
		(width 0.0889)
		(layer "In2.Cu")
		(net "M_C_CPU1_SB_DQ<11>")
	)
	(segment
		(start 42.041064 -292.965124)
		(end 42.203878 -293.127938)
		(width 0.14478)
		(layer "In2.Cu")
		(net "M_C_CPU1_SB_DQ<11>")
	)
	(segment
		(start 41.647618 -293.127938)
		(end 41.810432 -292.965124)
		(width 0.14478)
		(layer "In2.Cu")
		(net "M_C_CPU1_SB_DQ<11>")
	)
	(segment
		(start 95.762826 -280.217626)
		(end 95.785178 -280.300938)
		(width 0.0889)
		(layer "In2.Cu")
		(net "M_C_CPU1_SB_DQ<11>")
	)
	(segment
		(start 95.785178 -280.300938)
		(end 95.631 -280.566368)
		(width 0.0889)
		(layer "In2.Cu")
		(net "M_C_CPU1_SB_DQ<11>")
	)
	(segment
		(start 89.229692 -280.238962)
		(end 89.238074 -280.243788)
		(width 0.0889)
		(layer "In2.Cu")
		(net "M_C_CPU1_SB_DQ<11>")
	)
	(segment
		(start 42.356786 -293.80053)
		(end 49.402492 -293.80053)
		(width 0.14478)
		(layer "In2.Cu")
		(net "M_C_CPU1_SB_DQ<11>")
	)
	(segment
		(start 85.10397 -280.243788)
		(end 85.112352 -280.238962)
		(width 0.0889)
		(layer "In2.Cu")
		(net "M_C_CPU1_SB_DQ<11>")
	)
	(segment
		(start 88.289638 -280.238962)
		(end 88.29802 -280.243788)
		(width 0.0889)
		(layer "In2.Cu")
		(net "M_C_CPU1_SB_DQ<11>")
	)
	(segment
		(start 73.428098 -280.207974)
		(end 76.013056 -280.207974)
		(width 0.14478)
		(layer "In2.Cu")
		(net "M_C_CPU1_SB_DQ<11>")
	)
	(segment
		(start 54.327298 -293.810436)
		(end 56.539638 -293.810436)
		(width 0.14478)
		(layer "In2.Cu")
		(net "M_C_CPU1_SB_DQ<11>")
	)
	(segment
		(start 41.484804 -293.810436)
		(end 41.647618 -293.647622)
		(width 0.14478)
		(layer "In2.Cu")
		(net "M_C_CPU1_SB_DQ<11>")
	)
	(arc
		(start 90.752422 -280.238962)
		(mid 90.93593 -280.193468)
		(end 91.118182 -280.243788)
		(width 0.0889)
		(layer "In2.Cu")
		(net "M_C_CPU1_SB_DQ<11>")
	)
	(arc
		(start 91.684094 -280.243788)
		(mid 91.871038 -280.193533)
		(end 92.057982 -280.243788)
		(width 0.0889)
		(layer "In2.Cu")
		(net "M_C_CPU1_SB_DQ<11>")
	)
	(arc
		(start 86.052406 -280.238962)
		(mid 86.235914 -280.193468)
		(end 86.418166 -280.243788)
		(width 0.0889)
		(layer "In2.Cu")
		(net "M_C_CPU1_SB_DQ<11>")
	)
	(arc
		(start 82.284062 -280.243788)
		(mid 82.471006 -280.193533)
		(end 82.65795 -280.243788)
		(width 0.0889)
		(layer "In2.Cu")
		(net "M_C_CPU1_SB_DQ<11>")
	)
	(arc
		(start 89.238074 -280.243788)
		(mid 89.52103 -280.319965)
		(end 89.803986 -280.243788)
		(width 0.0889)
		(layer "In2.Cu")
		(net "M_C_CPU1_SB_DQ<11>")
	)
	(arc
		(start 81.71815 -280.243788)
		(mid 82.001106 -280.319965)
		(end 82.284062 -280.243788)
		(width 0.0889)
		(layer "In2.Cu")
		(net "M_C_CPU1_SB_DQ<11>")
	)
	(arc
		(start 78.767686 -280.207974)
		(mid 78.836114 -280.217081)
		(end 78.899766 -280.243788)
		(width 0.0889)
		(layer "In2.Cu")
		(net "M_C_CPU1_SB_DQ<11>")
	)
	(arc
		(start 83.598004 -280.243788)
		(mid 83.88096 -280.319965)
		(end 84.163916 -280.243788)
		(width 0.0889)
		(layer "In2.Cu")
		(net "M_C_CPU1_SB_DQ<11>")
	)
	(arc
		(start 92.998036 -280.243788)
		(mid 93.280992 -280.319965)
		(end 93.563948 -280.243788)
		(width 0.0889)
		(layer "In2.Cu")
		(net "M_C_CPU1_SB_DQ<11>")
	)
	(arc
		(start 80.403954 -280.243788)
		(mid 80.586205 -280.193438)
		(end 80.769714 -280.238962)
		(width 0.0889)
		(layer "In2.Cu")
		(net "M_C_CPU1_SB_DQ<11>")
	)
	(arc
		(start 94.878144 -280.243788)
		(mid 95.1611 -280.319965)
		(end 95.444056 -280.243788)
		(width 0.0889)
		(layer "In2.Cu")
		(net "M_C_CPU1_SB_DQ<11>")
	)
	(arc
		(start 86.984078 -280.243788)
		(mid 87.171022 -280.193533)
		(end 87.357966 -280.243788)
		(width 0.0889)
		(layer "In2.Cu")
		(net "M_C_CPU1_SB_DQ<11>")
	)
	(arc
		(start 85.478112 -280.243788)
		(mid 85.761068 -280.319965)
		(end 86.044024 -280.243788)
		(width 0.0889)
		(layer "In2.Cu")
		(net "M_C_CPU1_SB_DQ<11>")
	)
	(arc
		(start 91.118182 -280.243788)
		(mid 91.401138 -280.319965)
		(end 91.684094 -280.243788)
		(width 0.0889)
		(layer "In2.Cu")
		(net "M_C_CPU1_SB_DQ<11>")
	)
	(arc
		(start 94.512384 -280.238962)
		(mid 94.695892 -280.193468)
		(end 94.878144 -280.243788)
		(width 0.0889)
		(layer "In2.Cu")
		(net "M_C_CPU1_SB_DQ<11>")
	)
	(arc
		(start 79.866236 -280.259028)
		(mid 80.137022 -280.319674)
		(end 80.403954 -280.243788)
		(width 0.0889)
		(layer "In2.Cu")
		(net "M_C_CPU1_SB_DQ<11>")
	)
	(arc
		(start 88.29802 -280.243788)
		(mid 88.580976 -280.319965)
		(end 88.863932 -280.243788)
		(width 0.0889)
		(layer "In2.Cu")
		(net "M_C_CPU1_SB_DQ<11>")
	)
	(arc
		(start 79.46771 -280.243788)
		(mid 79.640565 -280.193799)
		(end 79.816706 -280.23058)
		(width 0.0889)
		(layer "In2.Cu")
		(net "M_C_CPU1_SB_DQ<11>")
	)
	(arc
		(start 89.812368 -280.238962)
		(mid 89.995876 -280.193468)
		(end 90.178128 -280.243788)
		(width 0.0889)
		(layer "In2.Cu")
		(net "M_C_CPU1_SB_DQ<11>")
	)
	(arc
		(start 84.538058 -280.243788)
		(mid 84.821014 -280.319965)
		(end 85.10397 -280.243788)
		(width 0.0889)
		(layer "In2.Cu")
		(net "M_C_CPU1_SB_DQ<11>")
	)
	(arc
		(start 87.923878 -280.243788)
		(mid 88.106129 -280.193438)
		(end 88.289638 -280.238962)
		(width 0.0889)
		(layer "In2.Cu")
		(net "M_C_CPU1_SB_DQ<11>")
	)
	(arc
		(start 85.112352 -280.238962)
		(mid 85.29586 -280.193468)
		(end 85.478112 -280.243788)
		(width 0.0889)
		(layer "In2.Cu")
		(net "M_C_CPU1_SB_DQ<11>")
	)
	(arc
		(start 81.35239 -280.238962)
		(mid 81.535898 -280.193468)
		(end 81.71815 -280.243788)
		(width 0.0889)
		(layer "In2.Cu")
		(net "M_C_CPU1_SB_DQ<11>")
	)
	(arc
		(start 92.057982 -280.243788)
		(mid 92.340938 -280.319965)
		(end 92.623894 -280.243788)
		(width 0.0889)
		(layer "In2.Cu")
		(net "M_C_CPU1_SB_DQ<11>")
	)
	(arc
		(start 87.357966 -280.243788)
		(mid 87.640922 -280.319965)
		(end 87.923878 -280.243788)
		(width 0.0889)
		(layer "In2.Cu")
		(net "M_C_CPU1_SB_DQ<11>")
	)
	(arc
		(start 88.863932 -280.243788)
		(mid 89.046183 -280.193438)
		(end 89.229692 -280.238962)
		(width 0.0889)
		(layer "In2.Cu")
		(net "M_C_CPU1_SB_DQ<11>")
	)
	(arc
		(start 93.93809 -280.243788)
		(mid 94.221046 -280.319965)
		(end 94.504002 -280.243788)
		(width 0.0889)
		(layer "In2.Cu")
		(net "M_C_CPU1_SB_DQ<11>")
	)
	(arc
		(start 83.223862 -280.243788)
		(mid 83.406113 -280.193438)
		(end 83.589622 -280.238962)
		(width 0.0889)
		(layer "In2.Cu")
		(net "M_C_CPU1_SB_DQ<11>")
	)
	(arc
		(start 78.899766 -280.243788)
		(mid 79.166823 -280.320823)
		(end 79.438246 -280.26106)
		(width 0.0889)
		(layer "In2.Cu")
		(net "M_C_CPU1_SB_DQ<11>")
	)
	(arc
		(start 80.778096 -280.243788)
		(mid 81.061052 -280.319965)
		(end 81.344008 -280.243788)
		(width 0.0889)
		(layer "In2.Cu")
		(net "M_C_CPU1_SB_DQ<11>")
	)
	(arc
		(start 92.623894 -280.243788)
		(mid 92.806145 -280.193438)
		(end 92.989654 -280.238962)
		(width 0.0889)
		(layer "In2.Cu")
		(net "M_C_CPU1_SB_DQ<11>")
	)
	(arc
		(start 86.418166 -280.243788)
		(mid 86.701122 -280.319965)
		(end 86.984078 -280.243788)
		(width 0.0889)
		(layer "In2.Cu")
		(net "M_C_CPU1_SB_DQ<11>")
	)
	(arc
		(start 95.452438 -280.238962)
		(mid 95.605308 -280.194321)
		(end 95.762826 -280.217626)
		(width 0.0889)
		(layer "In2.Cu")
		(net "M_C_CPU1_SB_DQ<11>")
	)
	(arc
		(start 84.163916 -280.243788)
		(mid 84.346167 -280.193438)
		(end 84.529676 -280.238962)
		(width 0.0889)
		(layer "In2.Cu")
		(net "M_C_CPU1_SB_DQ<11>")
	)
	(arc
		(start 82.65795 -280.243788)
		(mid 82.940906 -280.319965)
		(end 83.223862 -280.243788)
		(width 0.0889)
		(layer "In2.Cu")
		(net "M_C_CPU1_SB_DQ<11>")
	)
	(arc
		(start 93.563948 -280.243788)
		(mid 93.746199 -280.193438)
		(end 93.929708 -280.238962)
		(width 0.0889)
		(layer "In2.Cu")
		(net "M_C_CPU1_SB_DQ<11>")
	)
	(arc
		(start 90.178128 -280.243788)
		(mid 90.461084 -280.319965)
		(end 90.74404 -280.243788)
		(width 0.0889)
		(layer "In2.Cu")
		(net "M_C_CPU1_SB_DQ<11>")
	)
	(segment
		(start 94.687898 -279.490424)
		(end 94.221046 -279.756362)
		(width 0.10668)
		(layer "F.Cu")
		(net "M_C_CPU1_SB_DQ<10>")
	)
	(segment
		(start 43.436286 -292.110414)
		(end 48.160178 -292.110414)
		(width 0.14478)
		(layer "In2.Cu")
		(net "M_C_CPU1_SB_DQ<10>")
	)
	(segment
		(start 52.828698 -291.260276)
		(end 53.253386 -291.684964)
		(width 0.14478)
		(layer "In2.Cu")
		(net "M_C_CPU1_SB_DQ<10>")
	)
	(segment
		(start 40.665146 -292.110414)
		(end 41.441878 -292.110414)
		(width 0.14478)
		(layer "In2.Cu")
		(net "M_C_CPU1_SB_DQ<10>")
	)
	(segment
		(start 75.963526 -279.298654)
		(end 76.541376 -279.298654)
		(width 0.0889)
		(layer "In2.Cu")
		(net "M_C_CPU1_SB_DQ<10>")
	)
	(segment
		(start 42.717212 -291.352478)
		(end 42.880026 -291.189664)
		(width 0.14478)
		(layer "In2.Cu")
		(net "M_C_CPU1_SB_DQ<10>")
	)
	(segment
		(start 82.753962 -279.433782)
		(end 82.762344 -279.428956)
		(width 0.0889)
		(layer "In2.Cu")
		(net "M_C_CPU1_SB_DQ<10>")
	)
	(segment
		(start 76.753466 -279.086564)
		(end 77.69479 -279.086564)
		(width 0.0889)
		(layer "In2.Cu")
		(net "M_C_CPU1_SB_DQ<10>")
	)
	(segment
		(start 53.253386 -291.684964)
		(end 53.983128 -291.684964)
		(width 0.14478)
		(layer "In2.Cu")
		(net "M_C_CPU1_SB_DQ<10>")
	)
	(segment
		(start 42.323766 -292.110414)
		(end 42.554398 -292.110414)
		(width 0.14478)
		(layer "In2.Cu")
		(net "M_C_CPU1_SB_DQ<10>")
	)
	(segment
		(start 94.37497 -279.490932)
		(end 94.221046 -279.756362)
		(width 0.0889)
		(layer "In2.Cu")
		(net "M_C_CPU1_SB_DQ<10>")
	)
	(segment
		(start 43.273472 -291.9476)
		(end 43.436286 -292.110414)
		(width 0.14478)
		(layer "In2.Cu")
		(net "M_C_CPU1_SB_DQ<10>")
	)
	(segment
		(start 41.441878 -292.110414)
		(end 41.604692 -291.9476)
		(width 0.14478)
		(layer "In2.Cu")
		(net "M_C_CPU1_SB_DQ<10>")
	)
	(segment
		(start 79.935324 -279.434036)
		(end 79.958692 -279.420574)
		(width 0.0889)
		(layer "In2.Cu")
		(net "M_C_CPU1_SB_DQ<10>")
	)
	(segment
		(start 79.911448 -279.448006)
		(end 79.935324 -279.434036)
		(width 0.0889)
		(layer "In2.Cu")
		(net "M_C_CPU1_SB_DQ<10>")
	)
	(segment
		(start 53.983128 -291.684964)
		(end 54.408578 -292.110414)
		(width 0.14478)
		(layer "In2.Cu")
		(net "M_C_CPU1_SB_DQ<10>")
	)
	(segment
		(start 91.5797 -279.428956)
		(end 91.588082 -279.433782)
		(width 0.0889)
		(layer "In2.Cu")
		(net "M_C_CPU1_SB_DQ<10>")
	)
	(segment
		(start 92.153994 -279.433782)
		(end 92.162376 -279.428956)
		(width 0.0889)
		(layer "In2.Cu")
		(net "M_C_CPU1_SB_DQ<10>")
	)
	(segment
		(start 40.23995 -291.685218)
		(end 40.665146 -292.110414)
		(width 0.14478)
		(layer "In2.Cu")
		(net "M_C_CPU1_SB_DQ<10>")
	)
	(segment
		(start 88.394032 -279.433782)
		(end 88.402414 -279.428956)
		(width 0.0889)
		(layer "In2.Cu")
		(net "M_C_CPU1_SB_DQ<10>")
	)
	(segment
		(start 42.880026 -291.189664)
		(end 43.110658 -291.189664)
		(width 0.14478)
		(layer "In2.Cu")
		(net "M_C_CPU1_SB_DQ<10>")
	)
	(segment
		(start 87.453978 -279.433782)
		(end 87.46236 -279.428956)
		(width 0.0889)
		(layer "In2.Cu")
		(net "M_C_CPU1_SB_DQ<10>")
	)
	(segment
		(start 56.95315 -292.110414)
		(end 57.424066 -291.639498)
		(width 0.14478)
		(layer "In2.Cu")
		(net "M_C_CPU1_SB_DQ<10>")
	)
	(segment
		(start 42.554398 -292.110414)
		(end 42.717212 -291.9476)
		(width 0.14478)
		(layer "In2.Cu")
		(net "M_C_CPU1_SB_DQ<10>")
	)
	(segment
		(start 86.879684 -279.428956)
		(end 86.888066 -279.433782)
		(width 0.0889)
		(layer "In2.Cu")
		(net "M_C_CPU1_SB_DQ<10>")
	)
	(segment
		(start 43.273472 -291.352478)
		(end 43.273472 -291.9476)
		(width 0.14478)
		(layer "In2.Cu")
		(net "M_C_CPU1_SB_DQ<10>")
	)
	(segment
		(start 58.402728 -291.260276)
		(end 60.865766 -291.260276)
		(width 0.14478)
		(layer "In2.Cu")
		(net "M_C_CPU1_SB_DQ<10>")
	)
	(segment
		(start 41.604692 -291.352478)
		(end 41.767506 -291.189664)
		(width 0.14478)
		(layer "In2.Cu")
		(net "M_C_CPU1_SB_DQ<10>")
	)
	(segment
		(start 42.717212 -291.9476)
		(end 42.717212 -291.352478)
		(width 0.14478)
		(layer "In2.Cu")
		(net "M_C_CPU1_SB_DQ<10>")
	)
	(segment
		(start 49.409858 -292.506146)
		(end 50.655728 -291.260276)
		(width 0.14478)
		(layer "In2.Cu")
		(net "M_C_CPU1_SB_DQ<10>")
	)
	(segment
		(start 83.694016 -279.433782)
		(end 83.702398 -279.428956)
		(width 0.0889)
		(layer "In2.Cu")
		(net "M_C_CPU1_SB_DQ<10>")
	)
	(segment
		(start 41.767506 -291.189664)
		(end 41.998138 -291.189664)
		(width 0.14478)
		(layer "In2.Cu")
		(net "M_C_CPU1_SB_DQ<10>")
	)
	(segment
		(start 78.103222 -279.255728)
		(end 78.118462 -279.270968)
		(width 0.0889)
		(layer "In2.Cu")
		(net "M_C_CPU1_SB_DQ<10>")
	)
	(segment
		(start 73.063862 -279.298654)
		(end 75.963526 -279.298654)
		(width 0.14478)
		(layer "In2.Cu")
		(net "M_C_CPU1_SB_DQ<10>")
	)
	(segment
		(start 94.352618 -279.40762)
		(end 94.37497 -279.490932)
		(width 0.0889)
		(layer "In2.Cu")
		(net "M_C_CPU1_SB_DQ<10>")
	)
	(segment
		(start 42.160952 -291.9476)
		(end 42.323766 -292.110414)
		(width 0.14478)
		(layer "In2.Cu")
		(net "M_C_CPU1_SB_DQ<10>")
	)
	(segment
		(start 93.094048 -279.433782)
		(end 93.10243 -279.428956)
		(width 0.0889)
		(layer "In2.Cu")
		(net "M_C_CPU1_SB_DQ<10>")
	)
	(segment
		(start 43.110658 -291.189664)
		(end 43.273472 -291.352478)
		(width 0.14478)
		(layer "In2.Cu")
		(net "M_C_CPU1_SB_DQ<10>")
	)
	(segment
		(start 54.408578 -292.110414)
		(end 56.95315 -292.110414)
		(width 0.14478)
		(layer "In2.Cu")
		(net "M_C_CPU1_SB_DQ<10>")
	)
	(segment
		(start 41.998138 -291.189664)
		(end 42.160952 -291.352478)
		(width 0.14478)
		(layer "In2.Cu")
		(net "M_C_CPU1_SB_DQ<10>")
	)
	(segment
		(start 68.19519 -283.930852)
		(end 68.431664 -283.930852)
		(width 0.14478)
		(layer "In2.Cu")
		(net "M_C_CPU1_SB_DQ<10>")
	)
	(segment
		(start 85.93963 -279.428956)
		(end 85.948012 -279.433782)
		(width 0.0889)
		(layer "In2.Cu")
		(net "M_C_CPU1_SB_DQ<10>")
	)
	(segment
		(start 48.55591 -292.506146)
		(end 49.409858 -292.506146)
		(width 0.14478)
		(layer "In2.Cu")
		(net "M_C_CPU1_SB_DQ<10>")
	)
	(segment
		(start 82.179668 -279.428956)
		(end 82.18805 -279.433782)
		(width 0.0889)
		(layer "In2.Cu")
		(net "M_C_CPU1_SB_DQ<10>")
	)
	(segment
		(start 68.431664 -283.930852)
		(end 73.063862 -279.298654)
		(width 0.14478)
		(layer "In2.Cu")
		(net "M_C_CPU1_SB_DQ<10>")
	)
	(segment
		(start 42.160952 -291.352478)
		(end 42.160952 -291.9476)
		(width 0.14478)
		(layer "In2.Cu")
		(net "M_C_CPU1_SB_DQ<10>")
	)
	(segment
		(start 57.424066 -291.639498)
		(end 58.023506 -291.639498)
		(width 0.14478)
		(layer "In2.Cu")
		(net "M_C_CPU1_SB_DQ<10>")
	)
	(segment
		(start 78.978252 -279.443942)
		(end 78.995778 -279.433782)
		(width 0.0889)
		(layer "In2.Cu")
		(net "M_C_CPU1_SB_DQ<10>")
	)
	(segment
		(start 90.639646 -279.428956)
		(end 90.648028 -279.433782)
		(width 0.0889)
		(layer "In2.Cu")
		(net "M_C_CPU1_SB_DQ<10>")
	)
	(segment
		(start 41.604692 -291.9476)
		(end 41.604692 -291.352478)
		(width 0.14478)
		(layer "In2.Cu")
		(net "M_C_CPU1_SB_DQ<10>")
	)
	(segment
		(start 58.023506 -291.639498)
		(end 58.402728 -291.260276)
		(width 0.14478)
		(layer "In2.Cu")
		(net "M_C_CPU1_SB_DQ<10>")
	)
	(segment
		(start 60.865766 -291.260276)
		(end 68.19519 -283.930852)
		(width 0.14478)
		(layer "In2.Cu")
		(net "M_C_CPU1_SB_DQ<10>")
	)
	(segment
		(start 50.655728 -291.260276)
		(end 52.828698 -291.260276)
		(width 0.14478)
		(layer "In2.Cu")
		(net "M_C_CPU1_SB_DQ<10>")
	)
	(segment
		(start 76.541376 -279.298654)
		(end 76.753466 -279.086564)
		(width 0.0889)
		(layer "In2.Cu")
		(net "M_C_CPU1_SB_DQ<10>")
	)
	(segment
		(start 79.350616 -279.421844)
		(end 79.37119 -279.433782)
		(width 0.0889)
		(layer "In2.Cu")
		(net "M_C_CPU1_SB_DQ<10>")
	)
	(segment
		(start 48.160178 -292.110414)
		(end 48.55591 -292.506146)
		(width 0.14478)
		(layer "In2.Cu")
		(net "M_C_CPU1_SB_DQ<10>")
	)
	(segment
		(start 78.71079 -279.516332)
		(end 78.711044 -279.516332)
		(width 0.0889)
		(layer "In2.Cu")
		(net "M_C_CPU1_SB_DQ<10>")
	)
	(arc
		(start 85.948012 -279.433782)
		(mid 86.230968 -279.509959)
		(end 86.513924 -279.433782)
		(width 0.0889)
		(layer "In2.Cu")
		(net "M_C_CPU1_SB_DQ<10>")
	)
	(arc
		(start 92.162376 -279.428956)
		(mid 92.345884 -279.383462)
		(end 92.528136 -279.433782)
		(width 0.0889)
		(layer "In2.Cu")
		(net "M_C_CPU1_SB_DQ<10>")
	)
	(arc
		(start 77.69479 -279.086564)
		(mid 77.915826 -279.130531)
		(end 78.103222 -279.255728)
		(width 0.0889)
		(layer "In2.Cu")
		(net "M_C_CPU1_SB_DQ<10>")
	)
	(arc
		(start 81.813908 -279.433782)
		(mid 81.996159 -279.383432)
		(end 82.179668 -279.428956)
		(width 0.0889)
		(layer "In2.Cu")
		(net "M_C_CPU1_SB_DQ<10>")
	)
	(arc
		(start 94.034102 -279.433782)
		(mid 94.190421 -279.384787)
		(end 94.352618 -279.40762)
		(width 0.0889)
		(layer "In2.Cu")
		(net "M_C_CPU1_SB_DQ<10>")
	)
	(arc
		(start 84.068158 -279.433782)
		(mid 84.351114 -279.509959)
		(end 84.63407 -279.433782)
		(width 0.0889)
		(layer "In2.Cu")
		(net "M_C_CPU1_SB_DQ<10>")
	)
	(arc
		(start 79.958692 -279.420574)
		(mid 80.135087 -279.383671)
		(end 80.308196 -279.433782)
		(width 0.0889)
		(layer "In2.Cu")
		(net "M_C_CPU1_SB_DQ<10>")
	)
	(arc
		(start 85.007958 -279.433782)
		(mid 85.290914 -279.509959)
		(end 85.57387 -279.433782)
		(width 0.0889)
		(layer "In2.Cu")
		(net "M_C_CPU1_SB_DQ<10>")
	)
	(arc
		(start 84.63407 -279.433782)
		(mid 84.821014 -279.383527)
		(end 85.007958 -279.433782)
		(width 0.0889)
		(layer "In2.Cu")
		(net "M_C_CPU1_SB_DQ<10>")
	)
	(arc
		(start 87.46236 -279.428956)
		(mid 87.645868 -279.383462)
		(end 87.82812 -279.433782)
		(width 0.0889)
		(layer "In2.Cu")
		(net "M_C_CPU1_SB_DQ<10>")
	)
	(arc
		(start 87.82812 -279.433782)
		(mid 88.111076 -279.509959)
		(end 88.394032 -279.433782)
		(width 0.0889)
		(layer "In2.Cu")
		(net "M_C_CPU1_SB_DQ<10>")
	)
	(arc
		(start 82.762344 -279.428956)
		(mid 82.945852 -279.383462)
		(end 83.128104 -279.433782)
		(width 0.0889)
		(layer "In2.Cu")
		(net "M_C_CPU1_SB_DQ<10>")
	)
	(arc
		(start 93.10243 -279.428956)
		(mid 93.285938 -279.383462)
		(end 93.46819 -279.433782)
		(width 0.0889)
		(layer "In2.Cu")
		(net "M_C_CPU1_SB_DQ<10>")
	)
	(arc
		(start 80.308196 -279.433782)
		(mid 80.591152 -279.509959)
		(end 80.874108 -279.433782)
		(width 0.0889)
		(layer "In2.Cu")
		(net "M_C_CPU1_SB_DQ<10>")
	)
	(arc
		(start 81.247996 -279.433782)
		(mid 81.530952 -279.509959)
		(end 81.813908 -279.433782)
		(width 0.0889)
		(layer "In2.Cu")
		(net "M_C_CPU1_SB_DQ<10>")
	)
	(arc
		(start 93.46819 -279.433782)
		(mid 93.751146 -279.509959)
		(end 94.034102 -279.433782)
		(width 0.0889)
		(layer "In2.Cu")
		(net "M_C_CPU1_SB_DQ<10>")
	)
	(arc
		(start 82.18805 -279.433782)
		(mid 82.471006 -279.509959)
		(end 82.753962 -279.433782)
		(width 0.0889)
		(layer "In2.Cu")
		(net "M_C_CPU1_SB_DQ<10>")
	)
	(arc
		(start 83.702398 -279.428956)
		(mid 83.885906 -279.383462)
		(end 84.068158 -279.433782)
		(width 0.0889)
		(layer "In2.Cu")
		(net "M_C_CPU1_SB_DQ<10>")
	)
	(arc
		(start 88.402414 -279.428956)
		(mid 88.585922 -279.383462)
		(end 88.768174 -279.433782)
		(width 0.0889)
		(layer "In2.Cu")
		(net "M_C_CPU1_SB_DQ<10>")
	)
	(arc
		(start 88.768174 -279.433782)
		(mid 89.05113 -279.509959)
		(end 89.334086 -279.433782)
		(width 0.0889)
		(layer "In2.Cu")
		(net "M_C_CPU1_SB_DQ<10>")
	)
	(arc
		(start 91.21394 -279.433782)
		(mid 91.396191 -279.383432)
		(end 91.5797 -279.428956)
		(width 0.0889)
		(layer "In2.Cu")
		(net "M_C_CPU1_SB_DQ<10>")
	)
	(arc
		(start 92.528136 -279.433782)
		(mid 92.811092 -279.509959)
		(end 93.094048 -279.433782)
		(width 0.0889)
		(layer "In2.Cu")
		(net "M_C_CPU1_SB_DQ<10>")
	)
	(arc
		(start 91.588082 -279.433782)
		(mid 91.871038 -279.509959)
		(end 92.153994 -279.433782)
		(width 0.0889)
		(layer "In2.Cu")
		(net "M_C_CPU1_SB_DQ<10>")
	)
	(arc
		(start 89.334086 -279.433782)
		(mid 89.52103 -279.383527)
		(end 89.707974 -279.433782)
		(width 0.0889)
		(layer "In2.Cu")
		(net "M_C_CPU1_SB_DQ<10>")
	)
	(arc
		(start 86.513924 -279.433782)
		(mid 86.696175 -279.383432)
		(end 86.879684 -279.428956)
		(width 0.0889)
		(layer "In2.Cu")
		(net "M_C_CPU1_SB_DQ<10>")
	)
	(arc
		(start 85.57387 -279.433782)
		(mid 85.756121 -279.383432)
		(end 85.93963 -279.428956)
		(width 0.0889)
		(layer "In2.Cu")
		(net "M_C_CPU1_SB_DQ<10>")
	)
	(arc
		(start 89.707974 -279.433782)
		(mid 89.99093 -279.509959)
		(end 90.273886 -279.433782)
		(width 0.0889)
		(layer "In2.Cu")
		(net "M_C_CPU1_SB_DQ<10>")
	)
	(arc
		(start 83.128104 -279.433782)
		(mid 83.41106 -279.509959)
		(end 83.694016 -279.433782)
		(width 0.0889)
		(layer "In2.Cu")
		(net "M_C_CPU1_SB_DQ<10>")
	)
	(arc
		(start 78.995778 -279.433782)
		(mid 79.171688 -279.382972)
		(end 79.350616 -279.421844)
		(width 0.0889)
		(layer "In2.Cu")
		(net "M_C_CPU1_SB_DQ<10>")
	)
	(arc
		(start 78.711044 -279.516332)
		(mid 78.849473 -279.497929)
		(end 78.978252 -279.443942)
		(width 0.0889)
		(layer "In2.Cu")
		(net "M_C_CPU1_SB_DQ<10>")
	)
	(arc
		(start 90.273886 -279.433782)
		(mid 90.456137 -279.383432)
		(end 90.639646 -279.428956)
		(width 0.0889)
		(layer "In2.Cu")
		(net "M_C_CPU1_SB_DQ<10>")
	)
	(arc
		(start 80.874108 -279.433782)
		(mid 81.061052 -279.383527)
		(end 81.247996 -279.433782)
		(width 0.0889)
		(layer "In2.Cu")
		(net "M_C_CPU1_SB_DQ<10>")
	)
	(arc
		(start 78.118462 -279.270968)
		(mid 78.390224 -279.452554)
		(end 78.71079 -279.516332)
		(width 0.0889)
		(layer "In2.Cu")
		(net "M_C_CPU1_SB_DQ<10>")
	)
	(arc
		(start 90.648028 -279.433782)
		(mid 90.930984 -279.509959)
		(end 91.21394 -279.433782)
		(width 0.0889)
		(layer "In2.Cu")
		(net "M_C_CPU1_SB_DQ<10>")
	)
	(arc
		(start 86.888066 -279.433782)
		(mid 87.171022 -279.509959)
		(end 87.453978 -279.433782)
		(width 0.0889)
		(layer "In2.Cu")
		(net "M_C_CPU1_SB_DQ<10>")
	)
	(arc
		(start 79.37119 -279.433782)
		(mid 79.63951 -279.50989)
		(end 79.911448 -279.448006)
		(width 0.0889)
		(layer "In2.Cu")
		(net "M_C_CPU1_SB_DQ<10>")
	)
	(segment
		(start 95.157798 -273.820382)
		(end 94.690946 -274.08632)
		(width 0.10668)
		(layer "F.Cu")
		(net "M_C_CPU1_SB_DQ<0>")
	)
	(segment
		(start 65.24117 -277.031196)
		(end 65.24117 -276.801072)
		(width 0.14478)
		(layer "In2.Cu")
		(net "M_C_CPU1_SB_DQ<0>")
	)
	(segment
		(start 92.989654 -274.413726)
		(end 92.998036 -274.4089)
		(width 0.0889)
		(layer "In2.Cu")
		(net "M_C_CPU1_SB_DQ<0>")
	)
	(segment
		(start 80.769714 -274.413726)
		(end 80.778096 -274.4089)
		(width 0.0889)
		(layer "In2.Cu")
		(net "M_C_CPU1_SB_DQ<0>")
	)
	(segment
		(start 67.601846 -274.67052)
		(end 67.601846 -274.440396)
		(width 0.14478)
		(layer "In2.Cu")
		(net "M_C_CPU1_SB_DQ<0>")
	)
	(segment
		(start 53.847238 -281.910282)
		(end 56.863742 -281.910282)
		(width 0.14478)
		(layer "In2.Cu")
		(net "M_C_CPU1_SB_DQ<0>")
	)
	(segment
		(start 68.692268 -274.417282)
		(end 68.692268 -274.187158)
		(width 0.14478)
		(layer "In2.Cu")
		(net "M_C_CPU1_SB_DQ<0>")
	)
	(segment
		(start 68.298822 -274.580604)
		(end 68.528946 -274.580604)
		(width 0.14478)
		(layer "In2.Cu")
		(net "M_C_CPU1_SB_DQ<0>")
	)
	(segment
		(start 66.955162 -276.154388)
		(end 67.118484 -275.991066)
		(width 0.14478)
		(layer "In2.Cu")
		(net "M_C_CPU1_SB_DQ<0>")
	)
	(segment
		(start 45.674026 -281.620468)
		(end 45.904658 -281.620468)
		(width 0.14478)
		(layer "In2.Cu")
		(net "M_C_CPU1_SB_DQ<0>")
	)
	(segment
		(start 65.217548 -277.582122)
		(end 65.39865 -277.40102)
		(width 0.14478)
		(layer "In2.Cu")
		(net "M_C_CPU1_SB_DQ<0>")
	)
	(segment
		(start 66.331592 -276.777958)
		(end 66.331592 -276.547834)
		(width 0.14478)
		(layer "In2.Cu")
		(net "M_C_CPU1_SB_DQ<0>")
	)
	(segment
		(start 66.191384 -275.850858)
		(end 66.421508 -275.850858)
		(width 0.14478)
		(layer "In2.Cu")
		(net "M_C_CPU1_SB_DQ<0>")
	)
	(segment
		(start 46.835568 -281.910282)
		(end 49.420526 -281.910282)
		(width 0.14478)
		(layer "In2.Cu")
		(net "M_C_CPU1_SB_DQ<0>")
	)
	(segment
		(start 66.421508 -275.850858)
		(end 66.725038 -276.154388)
		(width 0.14478)
		(layer "In2.Cu")
		(net "M_C_CPU1_SB_DQ<0>")
	)
	(segment
		(start 46.230286 -282.280868)
		(end 46.464982 -282.280868)
		(width 0.14478)
		(layer "In2.Cu")
		(net "M_C_CPU1_SB_DQ<0>")
	)
	(segment
		(start 83.589622 -274.413726)
		(end 83.598004 -274.4089)
		(width 0.0889)
		(layer "In2.Cu")
		(net "M_C_CPU1_SB_DQ<0>")
	)
	(segment
		(start 67.2084 -275.063966)
		(end 67.51193 -275.367496)
		(width 0.14478)
		(layer "In2.Cu")
		(net "M_C_CPU1_SB_DQ<0>")
	)
	(segment
		(start 67.51193 -275.367496)
		(end 67.742054 -275.367496)
		(width 0.14478)
		(layer "In2.Cu")
		(net "M_C_CPU1_SB_DQ<0>")
	)
	(segment
		(start 56.863742 -281.910282)
		(end 57.71388 -281.060144)
		(width 0.14478)
		(layer "In2.Cu")
		(net "M_C_CPU1_SB_DQ<0>")
	)
	(segment
		(start 76.548996 -273.220434)
		(end 76.725526 -273.396964)
		(width 0.0889)
		(layer "In2.Cu")
		(net "M_C_CPU1_SB_DQ<0>")
	)
	(segment
		(start 50.270664 -281.060144)
		(end 52.9971 -281.060144)
		(width 0.14478)
		(layer "In2.Cu")
		(net "M_C_CPU1_SB_DQ<0>")
	)
	(segment
		(start 67.601846 -274.440396)
		(end 67.765168 -274.277074)
		(width 0.14478)
		(layer "In2.Cu")
		(net "M_C_CPU1_SB_DQ<0>")
	)
	(segment
		(start 89.803986 -274.4089)
		(end 89.812368 -274.413726)
		(width 0.0889)
		(layer "In2.Cu")
		(net "M_C_CPU1_SB_DQ<0>")
	)
	(segment
		(start 66.725038 -276.154388)
		(end 66.955162 -276.154388)
		(width 0.14478)
		(layer "In2.Cu")
		(net "M_C_CPU1_SB_DQ<0>")
	)
	(segment
		(start 68.388738 -273.653504)
		(end 68.821808 -273.220434)
		(width 0.14478)
		(layer "In2.Cu")
		(net "M_C_CPU1_SB_DQ<0>")
	)
	(segment
		(start 89.229692 -274.413726)
		(end 89.238074 -274.4089)
		(width 0.0889)
		(layer "In2.Cu")
		(net "M_C_CPU1_SB_DQ<0>")
	)
	(segment
		(start 57.71388 -281.060144)
		(end 60.974986 -281.060144)
		(width 0.14478)
		(layer "In2.Cu")
		(net "M_C_CPU1_SB_DQ<0>")
	)
	(segment
		(start 66.16827 -276.94128)
		(end 66.331592 -276.777958)
		(width 0.14478)
		(layer "In2.Cu")
		(net "M_C_CPU1_SB_DQ<0>")
	)
	(segment
		(start 79.817976 -274.421092)
		(end 79.83982 -274.408646)
		(width 0.0889)
		(layer "In2.Cu")
		(net "M_C_CPU1_SB_DQ<0>")
	)
	(segment
		(start 93.929708 -274.413726)
		(end 93.93809 -274.4089)
		(width 0.0889)
		(layer "In2.Cu")
		(net "M_C_CPU1_SB_DQ<0>")
	)
	(segment
		(start 75.966066 -273.220434)
		(end 76.548996 -273.220434)
		(width 0.0889)
		(layer "In2.Cu")
		(net "M_C_CPU1_SB_DQ<0>")
	)
	(segment
		(start 44.340018 -281.48534)
		(end 45.135546 -282.280868)
		(width 0.14478)
		(layer "In2.Cu")
		(net "M_C_CPU1_SB_DQ<0>")
	)
	(segment
		(start 79.83982 -274.408646)
		(end 79.863696 -274.394676)
		(width 0.0889)
		(layer "In2.Cu")
		(net "M_C_CPU1_SB_DQ<0>")
	)
	(segment
		(start 67.742054 -275.367496)
		(end 67.905376 -275.204174)
		(width 0.14478)
		(layer "In2.Cu")
		(net "M_C_CPU1_SB_DQ<0>")
	)
	(segment
		(start 65.938146 -276.94128)
		(end 66.16827 -276.94128)
		(width 0.14478)
		(layer "In2.Cu")
		(net "M_C_CPU1_SB_DQ<0>")
	)
	(segment
		(start 65.24117 -276.801072)
		(end 65.404492 -276.63775)
		(width 0.14478)
		(layer "In2.Cu")
		(net "M_C_CPU1_SB_DQ<0>")
	)
	(segment
		(start 77.484986 -273.396964)
		(end 78.424786 -274.336764)
		(width 0.0889)
		(layer "In2.Cu")
		(net "M_C_CPU1_SB_DQ<0>")
	)
	(segment
		(start 45.511212 -282.118054)
		(end 45.511212 -281.783282)
		(width 0.14478)
		(layer "In2.Cu")
		(net "M_C_CPU1_SB_DQ<0>")
	)
	(segment
		(start 66.028062 -276.01418)
		(end 66.191384 -275.850858)
		(width 0.14478)
		(layer "In2.Cu")
		(net "M_C_CPU1_SB_DQ<0>")
	)
	(segment
		(start 67.905376 -275.204174)
		(end 67.905376 -274.97405)
		(width 0.14478)
		(layer "In2.Cu")
		(net "M_C_CPU1_SB_DQ<0>")
	)
	(segment
		(start 46.067472 -281.783282)
		(end 46.067472 -282.118054)
		(width 0.14478)
		(layer "In2.Cu")
		(net "M_C_CPU1_SB_DQ<0>")
	)
	(segment
		(start 68.528946 -274.580604)
		(end 68.692268 -274.417282)
		(width 0.14478)
		(layer "In2.Cu")
		(net "M_C_CPU1_SB_DQ<0>")
	)
	(segment
		(start 86.044024 -274.4089)
		(end 86.052406 -274.413726)
		(width 0.0889)
		(layer "In2.Cu")
		(net "M_C_CPU1_SB_DQ<0>")
	)
	(segment
		(start 67.118484 -275.991066)
		(end 67.118484 -275.760942)
		(width 0.14478)
		(layer "In2.Cu")
		(net "M_C_CPU1_SB_DQ<0>")
	)
	(segment
		(start 45.135546 -282.280868)
		(end 45.348398 -282.280868)
		(width 0.14478)
		(layer "In2.Cu")
		(net "M_C_CPU1_SB_DQ<0>")
	)
	(segment
		(start 46.067472 -282.118054)
		(end 46.230286 -282.280868)
		(width 0.14478)
		(layer "In2.Cu")
		(net "M_C_CPU1_SB_DQ<0>")
	)
	(segment
		(start 64.847724 -277.424642)
		(end 65.005204 -277.582122)
		(width 0.14478)
		(layer "In2.Cu")
		(net "M_C_CPU1_SB_DQ<0>")
	)
	(segment
		(start 66.978276 -275.063966)
		(end 67.2084 -275.063966)
		(width 0.14478)
		(layer "In2.Cu")
		(net "M_C_CPU1_SB_DQ<0>")
	)
	(segment
		(start 49.420526 -281.910282)
		(end 50.270664 -281.060144)
		(width 0.14478)
		(layer "In2.Cu")
		(net "M_C_CPU1_SB_DQ<0>")
	)
	(segment
		(start 45.511212 -281.783282)
		(end 45.674026 -281.620468)
		(width 0.14478)
		(layer "In2.Cu")
		(net "M_C_CPU1_SB_DQ<0>")
	)
	(segment
		(start 66.814954 -275.227288)
		(end 66.978276 -275.063966)
		(width 0.14478)
		(layer "In2.Cu")
		(net "M_C_CPU1_SB_DQ<0>")
	)
	(segment
		(start 65.404492 -276.63775)
		(end 65.634616 -276.63775)
		(width 0.14478)
		(layer "In2.Cu")
		(net "M_C_CPU1_SB_DQ<0>")
	)
	(segment
		(start 67.118484 -275.760942)
		(end 66.814954 -275.457412)
		(width 0.14478)
		(layer "In2.Cu")
		(net "M_C_CPU1_SB_DQ<0>")
	)
	(segment
		(start 68.692268 -274.187158)
		(end 68.388738 -273.883628)
		(width 0.14478)
		(layer "In2.Cu")
		(net "M_C_CPU1_SB_DQ<0>")
	)
	(segment
		(start 85.10397 -274.4089)
		(end 85.112352 -274.413726)
		(width 0.0889)
		(layer "In2.Cu")
		(net "M_C_CPU1_SB_DQ<0>")
	)
	(segment
		(start 94.44101 -274.37715)
		(end 94.537022 -274.35175)
		(width 0.0889)
		(layer "In2.Cu")
		(net "M_C_CPU1_SB_DQ<0>")
	)
	(segment
		(start 84.529676 -274.413726)
		(end 84.538058 -274.4089)
		(width 0.0889)
		(layer "In2.Cu")
		(net "M_C_CPU1_SB_DQ<0>")
	)
	(segment
		(start 46.464982 -282.280868)
		(end 46.835568 -281.910282)
		(width 0.14478)
		(layer "In2.Cu")
		(net "M_C_CPU1_SB_DQ<0>")
	)
	(segment
		(start 88.289638 -274.413726)
		(end 88.29802 -274.4089)
		(width 0.0889)
		(layer "In2.Cu")
		(net "M_C_CPU1_SB_DQ<0>")
	)
	(segment
		(start 65.005204 -277.582122)
		(end 65.217548 -277.582122)
		(width 0.14478)
		(layer "In2.Cu")
		(net "M_C_CPU1_SB_DQ<0>")
	)
	(segment
		(start 79.439516 -274.392898)
		(end 79.467202 -274.4089)
		(width 0.0889)
		(layer "In2.Cu")
		(net "M_C_CPU1_SB_DQ<0>")
	)
	(segment
		(start 66.814954 -275.457412)
		(end 66.814954 -275.227288)
		(width 0.14478)
		(layer "In2.Cu")
		(net "M_C_CPU1_SB_DQ<0>")
	)
	(segment
		(start 68.821808 -273.220434)
		(end 75.966066 -273.220434)
		(width 0.14478)
		(layer "In2.Cu")
		(net "M_C_CPU1_SB_DQ<0>")
	)
	(segment
		(start 64.610488 -277.424642)
		(end 64.847724 -277.424642)
		(width 0.14478)
		(layer "In2.Cu")
		(net "M_C_CPU1_SB_DQ<0>")
	)
	(segment
		(start 65.39865 -277.40102)
		(end 65.39865 -277.188676)
		(width 0.14478)
		(layer "In2.Cu")
		(net "M_C_CPU1_SB_DQ<0>")
	)
	(segment
		(start 65.39865 -277.188676)
		(end 65.24117 -277.031196)
		(width 0.14478)
		(layer "In2.Cu")
		(net "M_C_CPU1_SB_DQ<0>")
	)
	(segment
		(start 65.634616 -276.63775)
		(end 65.938146 -276.94128)
		(width 0.14478)
		(layer "In2.Cu")
		(net "M_C_CPU1_SB_DQ<0>")
	)
	(segment
		(start 67.995292 -274.277074)
		(end 68.298822 -274.580604)
		(width 0.14478)
		(layer "In2.Cu")
		(net "M_C_CPU1_SB_DQ<0>")
	)
	(segment
		(start 45.348398 -282.280868)
		(end 45.511212 -282.118054)
		(width 0.14478)
		(layer "In2.Cu")
		(net "M_C_CPU1_SB_DQ<0>")
	)
	(segment
		(start 67.765168 -274.277074)
		(end 67.995292 -274.277074)
		(width 0.14478)
		(layer "In2.Cu")
		(net "M_C_CPU1_SB_DQ<0>")
	)
	(segment
		(start 90.74404 -274.4089)
		(end 90.752422 -274.413726)
		(width 0.0889)
		(layer "In2.Cu")
		(net "M_C_CPU1_SB_DQ<0>")
	)
	(segment
		(start 66.331592 -276.547834)
		(end 66.028062 -276.244304)
		(width 0.14478)
		(layer "In2.Cu")
		(net "M_C_CPU1_SB_DQ<0>")
	)
	(segment
		(start 67.905376 -274.97405)
		(end 67.601846 -274.67052)
		(width 0.14478)
		(layer "In2.Cu")
		(net "M_C_CPU1_SB_DQ<0>")
	)
	(segment
		(start 76.725526 -273.396964)
		(end 77.484986 -273.396964)
		(width 0.0889)
		(layer "In2.Cu")
		(net "M_C_CPU1_SB_DQ<0>")
	)
	(segment
		(start 60.974986 -281.060144)
		(end 64.610488 -277.424642)
		(width 0.14478)
		(layer "In2.Cu")
		(net "M_C_CPU1_SB_DQ<0>")
	)
	(segment
		(start 45.904658 -281.620468)
		(end 46.067472 -281.783282)
		(width 0.14478)
		(layer "In2.Cu")
		(net "M_C_CPU1_SB_DQ<0>")
	)
	(segment
		(start 94.537022 -274.35175)
		(end 94.690946 -274.08632)
		(width 0.0889)
		(layer "In2.Cu")
		(net "M_C_CPU1_SB_DQ<0>")
	)
	(segment
		(start 68.388738 -273.883628)
		(end 68.388738 -273.653504)
		(width 0.14478)
		(layer "In2.Cu")
		(net "M_C_CPU1_SB_DQ<0>")
	)
	(segment
		(start 66.028062 -276.244304)
		(end 66.028062 -276.01418)
		(width 0.14478)
		(layer "In2.Cu")
		(net "M_C_CPU1_SB_DQ<0>")
	)
	(segment
		(start 81.344008 -274.4089)
		(end 81.35239 -274.413726)
		(width 0.0889)
		(layer "In2.Cu")
		(net "M_C_CPU1_SB_DQ<0>")
	)
	(segment
		(start 78.704948 -274.452842)
		(end 78.737206 -274.452842)
		(width 0.0889)
		(layer "In2.Cu")
		(net "M_C_CPU1_SB_DQ<0>")
	)
	(segment
		(start 52.9971 -281.060144)
		(end 53.847238 -281.910282)
		(width 0.14478)
		(layer "In2.Cu")
		(net "M_C_CPU1_SB_DQ<0>")
	)
	(arc
		(start 92.623894 -274.4089)
		(mid 92.806145 -274.45925)
		(end 92.989654 -274.413726)
		(width 0.0889)
		(layer "In2.Cu")
		(net "M_C_CPU1_SB_DQ<0>")
	)
	(arc
		(start 92.998036 -274.4089)
		(mid 93.280992 -274.332723)
		(end 93.563948 -274.4089)
		(width 0.0889)
		(layer "In2.Cu")
		(net "M_C_CPU1_SB_DQ<0>")
	)
	(arc
		(start 79.467202 -274.4089)
		(mid 79.641052 -274.458806)
		(end 79.817976 -274.421092)
		(width 0.0889)
		(layer "In2.Cu")
		(net "M_C_CPU1_SB_DQ<0>")
	)
	(arc
		(start 87.357966 -274.4089)
		(mid 87.640922 -274.332723)
		(end 87.923878 -274.4089)
		(width 0.0889)
		(layer "In2.Cu")
		(net "M_C_CPU1_SB_DQ<0>")
	)
	(arc
		(start 78.737206 -274.452842)
		(mid 78.821282 -274.441665)
		(end 78.899512 -274.4089)
		(width 0.0889)
		(layer "In2.Cu")
		(net "M_C_CPU1_SB_DQ<0>")
	)
	(arc
		(start 84.538058 -274.4089)
		(mid 84.821014 -274.332723)
		(end 85.10397 -274.4089)
		(width 0.0889)
		(layer "In2.Cu")
		(net "M_C_CPU1_SB_DQ<0>")
	)
	(arc
		(start 80.403954 -274.4089)
		(mid 80.586205 -274.45925)
		(end 80.769714 -274.413726)
		(width 0.0889)
		(layer "In2.Cu")
		(net "M_C_CPU1_SB_DQ<0>")
	)
	(arc
		(start 91.118182 -274.4089)
		(mid 91.401138 -274.332723)
		(end 91.684094 -274.4089)
		(width 0.0889)
		(layer "In2.Cu")
		(net "M_C_CPU1_SB_DQ<0>")
	)
	(arc
		(start 93.93809 -274.4089)
		(mid 94.185803 -274.33368)
		(end 94.44101 -274.37715)
		(width 0.0889)
		(layer "In2.Cu")
		(net "M_C_CPU1_SB_DQ<0>")
	)
	(arc
		(start 78.424786 -274.336764)
		(mid 78.553325 -274.422651)
		(end 78.704948 -274.452842)
		(width 0.0889)
		(layer "In2.Cu")
		(net "M_C_CPU1_SB_DQ<0>")
	)
	(arc
		(start 85.478112 -274.4089)
		(mid 85.761068 -274.332723)
		(end 86.044024 -274.4089)
		(width 0.0889)
		(layer "In2.Cu")
		(net "M_C_CPU1_SB_DQ<0>")
	)
	(arc
		(start 86.418166 -274.4089)
		(mid 86.701122 -274.332723)
		(end 86.984078 -274.4089)
		(width 0.0889)
		(layer "In2.Cu")
		(net "M_C_CPU1_SB_DQ<0>")
	)
	(arc
		(start 89.238074 -274.4089)
		(mid 89.52103 -274.332723)
		(end 89.803986 -274.4089)
		(width 0.0889)
		(layer "In2.Cu")
		(net "M_C_CPU1_SB_DQ<0>")
	)
	(arc
		(start 91.684094 -274.4089)
		(mid 91.871038 -274.459155)
		(end 92.057982 -274.4089)
		(width 0.0889)
		(layer "In2.Cu")
		(net "M_C_CPU1_SB_DQ<0>")
	)
	(arc
		(start 92.057982 -274.4089)
		(mid 92.340938 -274.332723)
		(end 92.623894 -274.4089)
		(width 0.0889)
		(layer "In2.Cu")
		(net "M_C_CPU1_SB_DQ<0>")
	)
	(arc
		(start 86.052406 -274.413726)
		(mid 86.235914 -274.45922)
		(end 86.418166 -274.4089)
		(width 0.0889)
		(layer "In2.Cu")
		(net "M_C_CPU1_SB_DQ<0>")
	)
	(arc
		(start 93.563948 -274.4089)
		(mid 93.746199 -274.45925)
		(end 93.929708 -274.413726)
		(width 0.0889)
		(layer "In2.Cu")
		(net "M_C_CPU1_SB_DQ<0>")
	)
	(arc
		(start 83.223862 -274.4089)
		(mid 83.406113 -274.45925)
		(end 83.589622 -274.413726)
		(width 0.0889)
		(layer "In2.Cu")
		(net "M_C_CPU1_SB_DQ<0>")
	)
	(arc
		(start 82.65795 -274.4089)
		(mid 82.940906 -274.332723)
		(end 83.223862 -274.4089)
		(width 0.0889)
		(layer "In2.Cu")
		(net "M_C_CPU1_SB_DQ<0>")
	)
	(arc
		(start 84.163916 -274.4089)
		(mid 84.346167 -274.45925)
		(end 84.529676 -274.413726)
		(width 0.0889)
		(layer "In2.Cu")
		(net "M_C_CPU1_SB_DQ<0>")
	)
	(arc
		(start 88.29802 -274.4089)
		(mid 88.580976 -274.332723)
		(end 88.863932 -274.4089)
		(width 0.0889)
		(layer "In2.Cu")
		(net "M_C_CPU1_SB_DQ<0>")
	)
	(arc
		(start 80.778096 -274.4089)
		(mid 81.061052 -274.332723)
		(end 81.344008 -274.4089)
		(width 0.0889)
		(layer "In2.Cu")
		(net "M_C_CPU1_SB_DQ<0>")
	)
	(arc
		(start 85.112352 -274.413726)
		(mid 85.29586 -274.45922)
		(end 85.478112 -274.4089)
		(width 0.0889)
		(layer "In2.Cu")
		(net "M_C_CPU1_SB_DQ<0>")
	)
	(arc
		(start 78.899512 -274.4089)
		(mid 79.167481 -274.332077)
		(end 79.439516 -274.392898)
		(width 0.0889)
		(layer "In2.Cu")
		(net "M_C_CPU1_SB_DQ<0>")
	)
	(arc
		(start 86.984078 -274.4089)
		(mid 87.171022 -274.459155)
		(end 87.357966 -274.4089)
		(width 0.0889)
		(layer "In2.Cu")
		(net "M_C_CPU1_SB_DQ<0>")
	)
	(arc
		(start 81.35239 -274.413726)
		(mid 81.535898 -274.45922)
		(end 81.71815 -274.4089)
		(width 0.0889)
		(layer "In2.Cu")
		(net "M_C_CPU1_SB_DQ<0>")
	)
	(arc
		(start 90.178128 -274.4089)
		(mid 90.461084 -274.332723)
		(end 90.74404 -274.4089)
		(width 0.0889)
		(layer "In2.Cu")
		(net "M_C_CPU1_SB_DQ<0>")
	)
	(arc
		(start 88.863932 -274.4089)
		(mid 89.046183 -274.45925)
		(end 89.229692 -274.413726)
		(width 0.0889)
		(layer "In2.Cu")
		(net "M_C_CPU1_SB_DQ<0>")
	)
	(arc
		(start 87.923878 -274.4089)
		(mid 88.106129 -274.45925)
		(end 88.289638 -274.413726)
		(width 0.0889)
		(layer "In2.Cu")
		(net "M_C_CPU1_SB_DQ<0>")
	)
	(arc
		(start 79.863696 -274.394676)
		(mid 80.135633 -274.33285)
		(end 80.403954 -274.4089)
		(width 0.0889)
		(layer "In2.Cu")
		(net "M_C_CPU1_SB_DQ<0>")
	)
	(arc
		(start 83.598004 -274.4089)
		(mid 83.88096 -274.332723)
		(end 84.163916 -274.4089)
		(width 0.0889)
		(layer "In2.Cu")
		(net "M_C_CPU1_SB_DQ<0>")
	)
	(arc
		(start 89.812368 -274.413726)
		(mid 89.995876 -274.45922)
		(end 90.178128 -274.4089)
		(width 0.0889)
		(layer "In2.Cu")
		(net "M_C_CPU1_SB_DQ<0>")
	)
	(arc
		(start 82.284062 -274.4089)
		(mid 82.471006 -274.459155)
		(end 82.65795 -274.4089)
		(width 0.0889)
		(layer "In2.Cu")
		(net "M_C_CPU1_SB_DQ<0>")
	)
	(arc
		(start 81.71815 -274.4089)
		(mid 82.001106 -274.332723)
		(end 82.284062 -274.4089)
		(width 0.0889)
		(layer "In2.Cu")
		(net "M_C_CPU1_SB_DQ<0>")
	)
	(arc
		(start 90.752422 -274.413726)
		(mid 90.93593 -274.45922)
		(end 91.118182 -274.4089)
		(width 0.0889)
		(layer "In2.Cu")
		(net "M_C_CPU1_SB_DQ<0>")
	)
	(segment
		(start 94.687898 -266.530328)
		(end 94.221046 -266.796266)
		(width 0.10668)
		(layer "F.Cu")
		(net "M_C_CPU1_SB_CS_N<1>")
	)
	(segment
		(start 86.879684 -266.46886)
		(end 86.888066 -266.473686)
		(width 0.0889)
		(layer "In2.Cu")
		(net "M_C_CPU1_SB_CS_N<1>")
	)
	(segment
		(start 83.694016 -266.473686)
		(end 83.702398 -266.46886)
		(width 0.0889)
		(layer "In2.Cu")
		(net "M_C_CPU1_SB_CS_N<1>")
	)
	(segment
		(start 41.423336 -267.438378)
		(end 41.58615 -267.275564)
		(width 0.14478)
		(layer "In2.Cu")
		(net "M_C_CPU1_SB_CS_N<1>")
	)
	(segment
		(start 90.639646 -266.46886)
		(end 90.648028 -266.473686)
		(width 0.0889)
		(layer "In2.Cu")
		(net "M_C_CPU1_SB_CS_N<1>")
	)
	(segment
		(start 41.260522 -268.31036)
		(end 41.423336 -268.147546)
		(width 0.14478)
		(layer "In2.Cu")
		(net "M_C_CPU1_SB_CS_N<1>")
	)
	(segment
		(start 41.979596 -268.147546)
		(end 42.14241 -268.31036)
		(width 0.14478)
		(layer "In2.Cu")
		(net "M_C_CPU1_SB_CS_N<1>")
	)
	(segment
		(start 79.911448 -266.48791)
		(end 79.935324 -266.47394)
		(width 0.0889)
		(layer "In2.Cu")
		(net "M_C_CPU1_SB_CS_N<1>")
	)
	(segment
		(start 91.5797 -266.46886)
		(end 91.588082 -266.473686)
		(width 0.0889)
		(layer "In2.Cu")
		(net "M_C_CPU1_SB_CS_N<1>")
	)
	(segment
		(start 75.957176 -265.983974)
		(end 77.260196 -265.983974)
		(width 0.0889)
		(layer "In2.Cu")
		(net "M_C_CPU1_SB_CS_N<1>")
	)
	(segment
		(start 41.816782 -267.275564)
		(end 41.979596 -267.438378)
		(width 0.14478)
		(layer "In2.Cu")
		(net "M_C_CPU1_SB_CS_N<1>")
	)
	(segment
		(start 62.571376 -265.983974)
		(end 75.957176 -265.983974)
		(width 0.14478)
		(layer "In2.Cu")
		(net "M_C_CPU1_SB_CS_N<1>")
	)
	(segment
		(start 82.179668 -266.46886)
		(end 82.18805 -266.473686)
		(width 0.0889)
		(layer "In2.Cu")
		(net "M_C_CPU1_SB_CS_N<1>")
	)
	(segment
		(start 41.423336 -268.147546)
		(end 41.423336 -267.438378)
		(width 0.14478)
		(layer "In2.Cu")
		(net "M_C_CPU1_SB_CS_N<1>")
	)
	(segment
		(start 94.352618 -266.447524)
		(end 94.37497 -266.530836)
		(width 0.0889)
		(layer "In2.Cu")
		(net "M_C_CPU1_SB_CS_N<1>")
	)
	(segment
		(start 93.094048 -266.473686)
		(end 93.10243 -266.46886)
		(width 0.0889)
		(layer "In2.Cu")
		(net "M_C_CPU1_SB_CS_N<1>")
	)
	(segment
		(start 77.859128 -266.144502)
		(end 78.467966 -266.495784)
		(width 0.0889)
		(layer "In2.Cu")
		(net "M_C_CPU1_SB_CS_N<1>")
	)
	(segment
		(start 87.453978 -266.473686)
		(end 87.46236 -266.46886)
		(width 0.0889)
		(layer "In2.Cu")
		(net "M_C_CPU1_SB_CS_N<1>")
	)
	(segment
		(start 42.14241 -268.31036)
		(end 60.24499 -268.31036)
		(width 0.14478)
		(layer "In2.Cu")
		(net "M_C_CPU1_SB_CS_N<1>")
	)
	(segment
		(start 40.664892 -268.31036)
		(end 41.260522 -268.31036)
		(width 0.14478)
		(layer "In2.Cu")
		(net "M_C_CPU1_SB_CS_N<1>")
	)
	(segment
		(start 41.979596 -267.438378)
		(end 41.979596 -268.147546)
		(width 0.14478)
		(layer "In2.Cu")
		(net "M_C_CPU1_SB_CS_N<1>")
	)
	(segment
		(start 60.24499 -268.31036)
		(end 62.571376 -265.983974)
		(width 0.14478)
		(layer "In2.Cu")
		(net "M_C_CPU1_SB_CS_N<1>")
	)
	(segment
		(start 41.58615 -267.275564)
		(end 41.816782 -267.275564)
		(width 0.14478)
		(layer "In2.Cu")
		(net "M_C_CPU1_SB_CS_N<1>")
	)
	(segment
		(start 88.394032 -266.473686)
		(end 88.402414 -266.46886)
		(width 0.0889)
		(layer "In2.Cu")
		(net "M_C_CPU1_SB_CS_N<1>")
	)
	(segment
		(start 82.753962 -266.473686)
		(end 82.762344 -266.46886)
		(width 0.0889)
		(layer "In2.Cu")
		(net "M_C_CPU1_SB_CS_N<1>")
	)
	(segment
		(start 92.153994 -266.473686)
		(end 92.162376 -266.46886)
		(width 0.0889)
		(layer "In2.Cu")
		(net "M_C_CPU1_SB_CS_N<1>")
	)
	(segment
		(start 85.93963 -266.46886)
		(end 85.948012 -266.473686)
		(width 0.0889)
		(layer "In2.Cu")
		(net "M_C_CPU1_SB_CS_N<1>")
	)
	(segment
		(start 94.37497 -266.530836)
		(end 94.221046 -266.796266)
		(width 0.0889)
		(layer "In2.Cu")
		(net "M_C_CPU1_SB_CS_N<1>")
	)
	(segment
		(start 79.350616 -266.461748)
		(end 79.37119 -266.473686)
		(width 0.0889)
		(layer "In2.Cu")
		(net "M_C_CPU1_SB_CS_N<1>")
	)
	(segment
		(start 79.935324 -266.47394)
		(end 79.958692 -266.460478)
		(width 0.0889)
		(layer "In2.Cu")
		(net "M_C_CPU1_SB_CS_N<1>")
	)
	(segment
		(start 40.23995 -268.735302)
		(end 40.664892 -268.31036)
		(width 0.14478)
		(layer "In2.Cu")
		(net "M_C_CPU1_SB_CS_N<1>")
	)
	(arc
		(start 77.260196 -265.983974)
		(mid 77.570216 -266.024847)
		(end 77.859128 -266.144502)
		(width 0.0889)
		(layer "In2.Cu")
		(net "M_C_CPU1_SB_CS_N<1>")
	)
	(arc
		(start 89.707974 -266.473686)
		(mid 89.99093 -266.549863)
		(end 90.273886 -266.473686)
		(width 0.0889)
		(layer "In2.Cu")
		(net "M_C_CPU1_SB_CS_N<1>")
	)
	(arc
		(start 79.37119 -266.473686)
		(mid 79.63951 -266.549794)
		(end 79.911448 -266.48791)
		(width 0.0889)
		(layer "In2.Cu")
		(net "M_C_CPU1_SB_CS_N<1>")
	)
	(arc
		(start 80.308196 -266.473686)
		(mid 80.591152 -266.549863)
		(end 80.874108 -266.473686)
		(width 0.0889)
		(layer "In2.Cu")
		(net "M_C_CPU1_SB_CS_N<1>")
	)
	(arc
		(start 93.10243 -266.46886)
		(mid 93.285938 -266.423366)
		(end 93.46819 -266.473686)
		(width 0.0889)
		(layer "In2.Cu")
		(net "M_C_CPU1_SB_CS_N<1>")
	)
	(arc
		(start 92.528136 -266.473686)
		(mid 92.811092 -266.549863)
		(end 93.094048 -266.473686)
		(width 0.0889)
		(layer "In2.Cu")
		(net "M_C_CPU1_SB_CS_N<1>")
	)
	(arc
		(start 88.402414 -266.46886)
		(mid 88.585922 -266.423366)
		(end 88.768174 -266.473686)
		(width 0.0889)
		(layer "In2.Cu")
		(net "M_C_CPU1_SB_CS_N<1>")
	)
	(arc
		(start 78.995778 -266.473686)
		(mid 79.171688 -266.422876)
		(end 79.350616 -266.461748)
		(width 0.0889)
		(layer "In2.Cu")
		(net "M_C_CPU1_SB_CS_N<1>")
	)
	(arc
		(start 86.888066 -266.473686)
		(mid 87.171022 -266.549863)
		(end 87.453978 -266.473686)
		(width 0.0889)
		(layer "In2.Cu")
		(net "M_C_CPU1_SB_CS_N<1>")
	)
	(arc
		(start 81.247996 -266.473686)
		(mid 81.530952 -266.549863)
		(end 81.813908 -266.473686)
		(width 0.0889)
		(layer "In2.Cu")
		(net "M_C_CPU1_SB_CS_N<1>")
	)
	(arc
		(start 78.467966 -266.495784)
		(mid 78.734622 -266.550304)
		(end 78.995778 -266.473686)
		(width 0.0889)
		(layer "In2.Cu")
		(net "M_C_CPU1_SB_CS_N<1>")
	)
	(arc
		(start 91.588082 -266.473686)
		(mid 91.871038 -266.549863)
		(end 92.153994 -266.473686)
		(width 0.0889)
		(layer "In2.Cu")
		(net "M_C_CPU1_SB_CS_N<1>")
	)
	(arc
		(start 93.46819 -266.473686)
		(mid 93.751146 -266.549863)
		(end 94.034102 -266.473686)
		(width 0.0889)
		(layer "In2.Cu")
		(net "M_C_CPU1_SB_CS_N<1>")
	)
	(arc
		(start 87.82812 -266.473686)
		(mid 88.111076 -266.549863)
		(end 88.394032 -266.473686)
		(width 0.0889)
		(layer "In2.Cu")
		(net "M_C_CPU1_SB_CS_N<1>")
	)
	(arc
		(start 83.128104 -266.473686)
		(mid 83.41106 -266.549863)
		(end 83.694016 -266.473686)
		(width 0.0889)
		(layer "In2.Cu")
		(net "M_C_CPU1_SB_CS_N<1>")
	)
	(arc
		(start 88.768174 -266.473686)
		(mid 89.05113 -266.549863)
		(end 89.334086 -266.473686)
		(width 0.0889)
		(layer "In2.Cu")
		(net "M_C_CPU1_SB_CS_N<1>")
	)
	(arc
		(start 85.57387 -266.473686)
		(mid 85.756121 -266.423336)
		(end 85.93963 -266.46886)
		(width 0.0889)
		(layer "In2.Cu")
		(net "M_C_CPU1_SB_CS_N<1>")
	)
	(arc
		(start 81.813908 -266.473686)
		(mid 81.996159 -266.423336)
		(end 82.179668 -266.46886)
		(width 0.0889)
		(layer "In2.Cu")
		(net "M_C_CPU1_SB_CS_N<1>")
	)
	(arc
		(start 84.63407 -266.473686)
		(mid 84.821014 -266.423431)
		(end 85.007958 -266.473686)
		(width 0.0889)
		(layer "In2.Cu")
		(net "M_C_CPU1_SB_CS_N<1>")
	)
	(arc
		(start 84.068158 -266.473686)
		(mid 84.351114 -266.549863)
		(end 84.63407 -266.473686)
		(width 0.0889)
		(layer "In2.Cu")
		(net "M_C_CPU1_SB_CS_N<1>")
	)
	(arc
		(start 83.702398 -266.46886)
		(mid 83.885906 -266.423366)
		(end 84.068158 -266.473686)
		(width 0.0889)
		(layer "In2.Cu")
		(net "M_C_CPU1_SB_CS_N<1>")
	)
	(arc
		(start 82.762344 -266.46886)
		(mid 82.945852 -266.423366)
		(end 83.128104 -266.473686)
		(width 0.0889)
		(layer "In2.Cu")
		(net "M_C_CPU1_SB_CS_N<1>")
	)
	(arc
		(start 92.162376 -266.46886)
		(mid 92.345884 -266.423366)
		(end 92.528136 -266.473686)
		(width 0.0889)
		(layer "In2.Cu")
		(net "M_C_CPU1_SB_CS_N<1>")
	)
	(arc
		(start 86.513924 -266.473686)
		(mid 86.696175 -266.423336)
		(end 86.879684 -266.46886)
		(width 0.0889)
		(layer "In2.Cu")
		(net "M_C_CPU1_SB_CS_N<1>")
	)
	(arc
		(start 80.874108 -266.473686)
		(mid 81.061052 -266.423431)
		(end 81.247996 -266.473686)
		(width 0.0889)
		(layer "In2.Cu")
		(net "M_C_CPU1_SB_CS_N<1>")
	)
	(arc
		(start 85.948012 -266.473686)
		(mid 86.230968 -266.549863)
		(end 86.513924 -266.473686)
		(width 0.0889)
		(layer "In2.Cu")
		(net "M_C_CPU1_SB_CS_N<1>")
	)
	(arc
		(start 90.273886 -266.473686)
		(mid 90.456137 -266.423336)
		(end 90.639646 -266.46886)
		(width 0.0889)
		(layer "In2.Cu")
		(net "M_C_CPU1_SB_CS_N<1>")
	)
	(arc
		(start 79.958692 -266.460478)
		(mid 80.135087 -266.423575)
		(end 80.308196 -266.473686)
		(width 0.0889)
		(layer "In2.Cu")
		(net "M_C_CPU1_SB_CS_N<1>")
	)
	(arc
		(start 87.46236 -266.46886)
		(mid 87.645868 -266.423366)
		(end 87.82812 -266.473686)
		(width 0.0889)
		(layer "In2.Cu")
		(net "M_C_CPU1_SB_CS_N<1>")
	)
	(arc
		(start 91.21394 -266.473686)
		(mid 91.396191 -266.423336)
		(end 91.5797 -266.46886)
		(width 0.0889)
		(layer "In2.Cu")
		(net "M_C_CPU1_SB_CS_N<1>")
	)
	(arc
		(start 89.334086 -266.473686)
		(mid 89.52103 -266.423431)
		(end 89.707974 -266.473686)
		(width 0.0889)
		(layer "In2.Cu")
		(net "M_C_CPU1_SB_CS_N<1>")
	)
	(arc
		(start 82.18805 -266.473686)
		(mid 82.471006 -266.549863)
		(end 82.753962 -266.473686)
		(width 0.0889)
		(layer "In2.Cu")
		(net "M_C_CPU1_SB_CS_N<1>")
	)
	(arc
		(start 85.007958 -266.473686)
		(mid 85.290914 -266.549863)
		(end 85.57387 -266.473686)
		(width 0.0889)
		(layer "In2.Cu")
		(net "M_C_CPU1_SB_CS_N<1>")
	)
	(arc
		(start 94.034102 -266.473686)
		(mid 94.190421 -266.424691)
		(end 94.352618 -266.447524)
		(width 0.0889)
		(layer "In2.Cu")
		(net "M_C_CPU1_SB_CS_N<1>")
	)
	(arc
		(start 90.648028 -266.473686)
		(mid 90.930984 -266.549863)
		(end 91.21394 -266.473686)
		(width 0.0889)
		(layer "In2.Cu")
		(net "M_C_CPU1_SB_CS_N<1>")
	)
	(segment
		(start 96.097852 -265.720322)
		(end 95.631 -265.98626)
		(width 0.10668)
		(layer "F.Cu")
		(net "M_C_CPU1_SB_CS_N<0>")
	)
	(segment
		(start 53.24475 -267.834364)
		(end 53.475382 -267.834364)
		(width 0.14478)
		(layer "In2.Cu")
		(net "M_C_CPU1_SB_CS_N<0>")
	)
	(segment
		(start 78.879446 -265.65352)
		(end 78.897734 -265.663934)
		(width 0.0889)
		(layer "In2.Cu")
		(net "M_C_CPU1_SB_CS_N<0>")
	)
	(segment
		(start 80.769714 -265.658854)
		(end 80.778096 -265.66368)
		(width 0.0889)
		(layer "In2.Cu")
		(net "M_C_CPU1_SB_CS_N<0>")
	)
	(segment
		(start 89.803986 -265.66368)
		(end 89.812368 -265.658854)
		(width 0.0889)
		(layer "In2.Cu")
		(net "M_C_CPU1_SB_CS_N<0>")
	)
	(segment
		(start 95.762826 -265.637518)
		(end 95.785178 -265.72083)
		(width 0.0889)
		(layer "In2.Cu")
		(net "M_C_CPU1_SB_CS_N<0>")
	)
	(segment
		(start 88.289638 -265.658854)
		(end 88.29802 -265.66368)
		(width 0.0889)
		(layer "In2.Cu")
		(net "M_C_CPU1_SB_CS_N<0>")
	)
	(segment
		(start 46.060106 -267.683996)
		(end 46.060106 -267.2334)
		(width 0.14478)
		(layer "In2.Cu")
		(net "M_C_CPU1_SB_CS_N<0>")
	)
	(segment
		(start 82.284062 -265.66368)
		(end 82.292444 -265.658854)
		(width 0.0889)
		(layer "In2.Cu")
		(net "M_C_CPU1_SB_CS_N<0>")
	)
	(segment
		(start 53.80101 -267.086588)
		(end 54.031642 -267.086588)
		(width 0.14478)
		(layer "In2.Cu")
		(net "M_C_CPU1_SB_CS_N<0>")
	)
	(segment
		(start 53.638196 -267.249402)
		(end 53.80101 -267.086588)
		(width 0.14478)
		(layer "In2.Cu")
		(net "M_C_CPU1_SB_CS_N<0>")
	)
	(segment
		(start 44.340018 -267.885418)
		(end 45.141896 -267.08354)
		(width 0.14478)
		(layer "In2.Cu")
		(net "M_C_CPU1_SB_CS_N<0>")
	)
	(segment
		(start 49.37506 -267.244068)
		(end 49.537874 -267.081254)
		(width 0.14478)
		(layer "In2.Cu")
		(net "M_C_CPU1_SB_CS_N<0>")
	)
	(segment
		(start 50.324766 -267.82903)
		(end 50.69332 -267.460476)
		(width 0.14478)
		(layer "In2.Cu")
		(net "M_C_CPU1_SB_CS_N<0>")
	)
	(segment
		(start 45.353986 -267.08354)
		(end 45.503846 -267.2334)
		(width 0.14478)
		(layer "In2.Cu")
		(net "M_C_CPU1_SB_CS_N<0>")
	)
	(segment
		(start 50.69332 -267.460476)
		(end 52.870862 -267.460476)
		(width 0.14478)
		(layer "In2.Cu")
		(net "M_C_CPU1_SB_CS_N<0>")
	)
	(segment
		(start 45.66666 -267.84681)
		(end 45.897292 -267.84681)
		(width 0.14478)
		(layer "In2.Cu")
		(net "M_C_CPU1_SB_CS_N<0>")
	)
	(segment
		(start 53.475382 -267.834364)
		(end 53.638196 -267.67155)
		(width 0.14478)
		(layer "In2.Cu")
		(net "M_C_CPU1_SB_CS_N<0>")
	)
	(segment
		(start 86.044024 -265.66368)
		(end 86.052406 -265.658854)
		(width 0.0889)
		(layer "In2.Cu")
		(net "M_C_CPU1_SB_CS_N<0>")
	)
	(segment
		(start 46.060106 -267.2334)
		(end 46.22292 -267.070586)
		(width 0.14478)
		(layer "In2.Cu")
		(net "M_C_CPU1_SB_CS_N<0>")
	)
	(segment
		(start 49.93132 -267.244068)
		(end 49.93132 -267.666216)
		(width 0.14478)
		(layer "In2.Cu")
		(net "M_C_CPU1_SB_CS_N<0>")
	)
	(segment
		(start 49.93132 -267.666216)
		(end 50.094134 -267.82903)
		(width 0.14478)
		(layer "In2.Cu")
		(net "M_C_CPU1_SB_CS_N<0>")
	)
	(segment
		(start 60.205874 -267.460476)
		(end 62.137036 -265.529314)
		(width 0.14478)
		(layer "In2.Cu")
		(net "M_C_CPU1_SB_CS_N<0>")
	)
	(segment
		(start 52.870862 -267.460476)
		(end 53.24475 -267.834364)
		(width 0.14478)
		(layer "In2.Cu")
		(net "M_C_CPU1_SB_CS_N<0>")
	)
	(segment
		(start 75.940666 -265.529314)
		(end 77.462126 -265.529314)
		(width 0.0889)
		(layer "In2.Cu")
		(net "M_C_CPU1_SB_CS_N<0>")
	)
	(segment
		(start 54.194456 -267.249402)
		(end 54.194456 -267.67155)
		(width 0.14478)
		(layer "In2.Cu")
		(net "M_C_CPU1_SB_CS_N<0>")
	)
	(segment
		(start 54.031642 -267.086588)
		(end 54.194456 -267.249402)
		(width 0.14478)
		(layer "In2.Cu")
		(net "M_C_CPU1_SB_CS_N<0>")
	)
	(segment
		(start 54.96179 -267.460476)
		(end 60.205874 -267.460476)
		(width 0.14478)
		(layer "In2.Cu")
		(net "M_C_CPU1_SB_CS_N<0>")
	)
	(segment
		(start 46.22292 -267.070586)
		(end 46.453552 -267.070586)
		(width 0.14478)
		(layer "In2.Cu")
		(net "M_C_CPU1_SB_CS_N<0>")
	)
	(segment
		(start 45.503846 -267.683996)
		(end 45.66666 -267.84681)
		(width 0.14478)
		(layer "In2.Cu")
		(net "M_C_CPU1_SB_CS_N<0>")
	)
	(segment
		(start 85.10397 -265.66368)
		(end 85.112352 -265.658854)
		(width 0.0889)
		(layer "In2.Cu")
		(net "M_C_CPU1_SB_CS_N<0>")
	)
	(segment
		(start 95.444056 -265.66368)
		(end 95.452438 -265.658854)
		(width 0.0889)
		(layer "In2.Cu")
		(net "M_C_CPU1_SB_CS_N<0>")
	)
	(segment
		(start 47.95012 -267.460476)
		(end 48.318674 -267.82903)
		(width 0.14478)
		(layer "In2.Cu")
		(net "M_C_CPU1_SB_CS_N<0>")
	)
	(segment
		(start 48.318674 -267.82903)
		(end 49.212246 -267.82903)
		(width 0.14478)
		(layer "In2.Cu")
		(net "M_C_CPU1_SB_CS_N<0>")
	)
	(segment
		(start 92.989654 -265.658854)
		(end 92.998036 -265.66368)
		(width 0.0889)
		(layer "In2.Cu")
		(net "M_C_CPU1_SB_CS_N<0>")
	)
	(segment
		(start 77.957172 -265.66368)
		(end 77.971904 -265.672316)
		(width 0.0889)
		(layer "In2.Cu")
		(net "M_C_CPU1_SB_CS_N<0>")
	)
	(segment
		(start 46.453552 -267.070586)
		(end 46.843442 -267.460476)
		(width 0.14478)
		(layer "In2.Cu")
		(net "M_C_CPU1_SB_CS_N<0>")
	)
	(segment
		(start 49.537874 -267.081254)
		(end 49.768506 -267.081254)
		(width 0.14478)
		(layer "In2.Cu")
		(net "M_C_CPU1_SB_CS_N<0>")
	)
	(segment
		(start 54.35727 -267.834364)
		(end 54.587902 -267.834364)
		(width 0.14478)
		(layer "In2.Cu")
		(net "M_C_CPU1_SB_CS_N<0>")
	)
	(segment
		(start 53.638196 -267.67155)
		(end 53.638196 -267.249402)
		(width 0.14478)
		(layer "In2.Cu")
		(net "M_C_CPU1_SB_CS_N<0>")
	)
	(segment
		(start 54.194456 -267.67155)
		(end 54.35727 -267.834364)
		(width 0.14478)
		(layer "In2.Cu")
		(net "M_C_CPU1_SB_CS_N<0>")
	)
	(segment
		(start 49.768506 -267.081254)
		(end 49.93132 -267.244068)
		(width 0.14478)
		(layer "In2.Cu")
		(net "M_C_CPU1_SB_CS_N<0>")
	)
	(segment
		(start 89.229692 -265.658854)
		(end 89.238074 -265.66368)
		(width 0.0889)
		(layer "In2.Cu")
		(net "M_C_CPU1_SB_CS_N<0>")
	)
	(segment
		(start 95.785178 -265.72083)
		(end 95.631 -265.98626)
		(width 0.0889)
		(layer "In2.Cu")
		(net "M_C_CPU1_SB_CS_N<0>")
	)
	(segment
		(start 45.141896 -267.08354)
		(end 45.353986 -267.08354)
		(width 0.14478)
		(layer "In2.Cu")
		(net "M_C_CPU1_SB_CS_N<0>")
	)
	(segment
		(start 81.344008 -265.66368)
		(end 81.35239 -265.658854)
		(width 0.0889)
		(layer "In2.Cu")
		(net "M_C_CPU1_SB_CS_N<0>")
	)
	(segment
		(start 45.503846 -267.2334)
		(end 45.503846 -267.683996)
		(width 0.14478)
		(layer "In2.Cu")
		(net "M_C_CPU1_SB_CS_N<0>")
	)
	(segment
		(start 50.094134 -267.82903)
		(end 50.324766 -267.82903)
		(width 0.14478)
		(layer "In2.Cu")
		(net "M_C_CPU1_SB_CS_N<0>")
	)
	(segment
		(start 90.74404 -265.66368)
		(end 90.752422 -265.658854)
		(width 0.0889)
		(layer "In2.Cu")
		(net "M_C_CPU1_SB_CS_N<0>")
	)
	(segment
		(start 93.929708 -265.658854)
		(end 93.93809 -265.66368)
		(width 0.0889)
		(layer "In2.Cu")
		(net "M_C_CPU1_SB_CS_N<0>")
	)
	(segment
		(start 46.843442 -267.460476)
		(end 47.95012 -267.460476)
		(width 0.14478)
		(layer "In2.Cu")
		(net "M_C_CPU1_SB_CS_N<0>")
	)
	(segment
		(start 49.212246 -267.82903)
		(end 49.37506 -267.666216)
		(width 0.14478)
		(layer "In2.Cu")
		(net "M_C_CPU1_SB_CS_N<0>")
	)
	(segment
		(start 49.37506 -267.666216)
		(end 49.37506 -267.244068)
		(width 0.14478)
		(layer "In2.Cu")
		(net "M_C_CPU1_SB_CS_N<0>")
	)
	(segment
		(start 78.897734 -265.663934)
		(end 78.903322 -265.667236)
		(width 0.0889)
		(layer "In2.Cu")
		(net "M_C_CPU1_SB_CS_N<0>")
	)
	(segment
		(start 94.504002 -265.66368)
		(end 94.512384 -265.658854)
		(width 0.0889)
		(layer "In2.Cu")
		(net "M_C_CPU1_SB_CS_N<0>")
	)
	(segment
		(start 54.587902 -267.834364)
		(end 54.96179 -267.460476)
		(width 0.14478)
		(layer "In2.Cu")
		(net "M_C_CPU1_SB_CS_N<0>")
	)
	(segment
		(start 45.897292 -267.84681)
		(end 46.060106 -267.683996)
		(width 0.14478)
		(layer "In2.Cu")
		(net "M_C_CPU1_SB_CS_N<0>")
	)
	(segment
		(start 62.137036 -265.529314)
		(end 75.940666 -265.529314)
		(width 0.14478)
		(layer "In2.Cu")
		(net "M_C_CPU1_SB_CS_N<0>")
	)
	(segment
		(start 84.529676 -265.658854)
		(end 84.538058 -265.66368)
		(width 0.0889)
		(layer "In2.Cu")
		(net "M_C_CPU1_SB_CS_N<0>")
	)
	(segment
		(start 80.389222 -265.672316)
		(end 80.403954 -265.66368)
		(width 0.0889)
		(layer "In2.Cu")
		(net "M_C_CPU1_SB_CS_N<0>")
	)
	(segment
		(start 79.463138 -265.66368)
		(end 79.474822 -265.656822)
		(width 0.0889)
		(layer "In2.Cu")
		(net "M_C_CPU1_SB_CS_N<0>")
	)
	(arc
		(start 94.512384 -265.658854)
		(mid 94.695892 -265.61336)
		(end 94.878144 -265.66368)
		(width 0.0889)
		(layer "In2.Cu")
		(net "M_C_CPU1_SB_CS_N<0>")
	)
	(arc
		(start 81.71815 -265.66368)
		(mid 82.001106 -265.739857)
		(end 82.284062 -265.66368)
		(width 0.0889)
		(layer "In2.Cu")
		(net "M_C_CPU1_SB_CS_N<0>")
	)
	(arc
		(start 93.563948 -265.66368)
		(mid 93.746199 -265.61333)
		(end 93.929708 -265.658854)
		(width 0.0889)
		(layer "In2.Cu")
		(net "M_C_CPU1_SB_CS_N<0>")
	)
	(arc
		(start 88.29802 -265.66368)
		(mid 88.580976 -265.739857)
		(end 88.863932 -265.66368)
		(width 0.0889)
		(layer "In2.Cu")
		(net "M_C_CPU1_SB_CS_N<0>")
	)
	(arc
		(start 89.812368 -265.658854)
		(mid 89.995876 -265.61336)
		(end 90.178128 -265.66368)
		(width 0.0889)
		(layer "In2.Cu")
		(net "M_C_CPU1_SB_CS_N<0>")
	)
	(arc
		(start 84.538058 -265.66368)
		(mid 84.821014 -265.739857)
		(end 85.10397 -265.66368)
		(width 0.0889)
		(layer "In2.Cu")
		(net "M_C_CPU1_SB_CS_N<0>")
	)
	(arc
		(start 77.462126 -265.529314)
		(mid 77.718622 -265.563455)
		(end 77.957172 -265.66368)
		(width 0.0889)
		(layer "In2.Cu")
		(net "M_C_CPU1_SB_CS_N<0>")
	)
	(arc
		(start 86.418166 -265.66368)
		(mid 86.701122 -265.739857)
		(end 86.984078 -265.66368)
		(width 0.0889)
		(layer "In2.Cu")
		(net "M_C_CPU1_SB_CS_N<0>")
	)
	(arc
		(start 78.903322 -265.667236)
		(mid 79.183711 -265.739905)
		(end 79.463138 -265.66368)
		(width 0.0889)
		(layer "In2.Cu")
		(net "M_C_CPU1_SB_CS_N<0>")
	)
	(arc
		(start 94.878144 -265.66368)
		(mid 95.1611 -265.739857)
		(end 95.444056 -265.66368)
		(width 0.0889)
		(layer "In2.Cu")
		(net "M_C_CPU1_SB_CS_N<0>")
	)
	(arc
		(start 79.474822 -265.656822)
		(mid 79.657077 -265.613169)
		(end 79.837534 -265.66368)
		(width 0.0889)
		(layer "In2.Cu")
		(net "M_C_CPU1_SB_CS_N<0>")
	)
	(arc
		(start 92.623894 -265.66368)
		(mid 92.806145 -265.61333)
		(end 92.989654 -265.658854)
		(width 0.0889)
		(layer "In2.Cu")
		(net "M_C_CPU1_SB_CS_N<0>")
	)
	(arc
		(start 92.998036 -265.66368)
		(mid 93.280992 -265.739857)
		(end 93.563948 -265.66368)
		(width 0.0889)
		(layer "In2.Cu")
		(net "M_C_CPU1_SB_CS_N<0>")
	)
	(arc
		(start 90.178128 -265.66368)
		(mid 90.461084 -265.739857)
		(end 90.74404 -265.66368)
		(width 0.0889)
		(layer "In2.Cu")
		(net "M_C_CPU1_SB_CS_N<0>")
	)
	(arc
		(start 89.238074 -265.66368)
		(mid 89.52103 -265.739857)
		(end 89.803986 -265.66368)
		(width 0.0889)
		(layer "In2.Cu")
		(net "M_C_CPU1_SB_CS_N<0>")
	)
	(arc
		(start 81.35239 -265.658854)
		(mid 81.535898 -265.61336)
		(end 81.71815 -265.66368)
		(width 0.0889)
		(layer "In2.Cu")
		(net "M_C_CPU1_SB_CS_N<0>")
	)
	(arc
		(start 90.752422 -265.658854)
		(mid 90.93593 -265.61336)
		(end 91.118182 -265.66368)
		(width 0.0889)
		(layer "In2.Cu")
		(net "M_C_CPU1_SB_CS_N<0>")
	)
	(arc
		(start 93.93809 -265.66368)
		(mid 94.221046 -265.739857)
		(end 94.504002 -265.66368)
		(width 0.0889)
		(layer "In2.Cu")
		(net "M_C_CPU1_SB_CS_N<0>")
	)
	(arc
		(start 77.971904 -265.672316)
		(mid 78.248887 -265.74012)
		(end 78.523592 -265.66368)
		(width 0.0889)
		(layer "In2.Cu")
		(net "M_C_CPU1_SB_CS_N<0>")
	)
	(arc
		(start 82.292444 -265.658854)
		(mid 82.475952 -265.61336)
		(end 82.658204 -265.66368)
		(width 0.0889)
		(layer "In2.Cu")
		(net "M_C_CPU1_SB_CS_N<0>")
	)
	(arc
		(start 92.057982 -265.66368)
		(mid 92.340938 -265.739857)
		(end 92.623894 -265.66368)
		(width 0.0889)
		(layer "In2.Cu")
		(net "M_C_CPU1_SB_CS_N<0>")
	)
	(arc
		(start 95.452438 -265.658854)
		(mid 95.605308 -265.614213)
		(end 95.762826 -265.637518)
		(width 0.0889)
		(layer "In2.Cu")
		(net "M_C_CPU1_SB_CS_N<0>")
	)
	(arc
		(start 78.523592 -265.66368)
		(mid 78.70022 -265.613447)
		(end 78.879446 -265.65352)
		(width 0.0889)
		(layer "In2.Cu")
		(net "M_C_CPU1_SB_CS_N<0>")
	)
	(arc
		(start 87.923878 -265.66368)
		(mid 88.106129 -265.61333)
		(end 88.289638 -265.658854)
		(width 0.0889)
		(layer "In2.Cu")
		(net "M_C_CPU1_SB_CS_N<0>")
	)
	(arc
		(start 80.403954 -265.66368)
		(mid 80.586205 -265.61333)
		(end 80.769714 -265.658854)
		(width 0.0889)
		(layer "In2.Cu")
		(net "M_C_CPU1_SB_CS_N<0>")
	)
	(arc
		(start 91.684094 -265.66368)
		(mid 91.871038 -265.613425)
		(end 92.057982 -265.66368)
		(width 0.0889)
		(layer "In2.Cu")
		(net "M_C_CPU1_SB_CS_N<0>")
	)
	(arc
		(start 85.112352 -265.658854)
		(mid 85.29586 -265.61336)
		(end 85.478112 -265.66368)
		(width 0.0889)
		(layer "In2.Cu")
		(net "M_C_CPU1_SB_CS_N<0>")
	)
	(arc
		(start 88.863932 -265.66368)
		(mid 89.046183 -265.61333)
		(end 89.229692 -265.658854)
		(width 0.0889)
		(layer "In2.Cu")
		(net "M_C_CPU1_SB_CS_N<0>")
	)
	(arc
		(start 84.163916 -265.66368)
		(mid 84.346167 -265.61333)
		(end 84.529676 -265.658854)
		(width 0.0889)
		(layer "In2.Cu")
		(net "M_C_CPU1_SB_CS_N<0>")
	)
	(arc
		(start 85.478112 -265.66368)
		(mid 85.761068 -265.739857)
		(end 86.044024 -265.66368)
		(width 0.0889)
		(layer "In2.Cu")
		(net "M_C_CPU1_SB_CS_N<0>")
	)
	(arc
		(start 83.224116 -265.66368)
		(mid 83.41106 -265.613425)
		(end 83.598004 -265.66368)
		(width 0.0889)
		(layer "In2.Cu")
		(net "M_C_CPU1_SB_CS_N<0>")
	)
	(arc
		(start 79.837534 -265.66368)
		(mid 80.11224 -265.740044)
		(end 80.389222 -265.672316)
		(width 0.0889)
		(layer "In2.Cu")
		(net "M_C_CPU1_SB_CS_N<0>")
	)
	(arc
		(start 86.052406 -265.658854)
		(mid 86.235914 -265.61336)
		(end 86.418166 -265.66368)
		(width 0.0889)
		(layer "In2.Cu")
		(net "M_C_CPU1_SB_CS_N<0>")
	)
	(arc
		(start 82.658204 -265.66368)
		(mid 82.94116 -265.739857)
		(end 83.224116 -265.66368)
		(width 0.0889)
		(layer "In2.Cu")
		(net "M_C_CPU1_SB_CS_N<0>")
	)
	(arc
		(start 91.118182 -265.66368)
		(mid 91.401138 -265.739857)
		(end 91.684094 -265.66368)
		(width 0.0889)
		(layer "In2.Cu")
		(net "M_C_CPU1_SB_CS_N<0>")
	)
	(arc
		(start 86.984078 -265.66368)
		(mid 87.171022 -265.613425)
		(end 87.357966 -265.66368)
		(width 0.0889)
		(layer "In2.Cu")
		(net "M_C_CPU1_SB_CS_N<0>")
	)
	(arc
		(start 80.778096 -265.66368)
		(mid 81.061052 -265.739857)
		(end 81.344008 -265.66368)
		(width 0.0889)
		(layer "In2.Cu")
		(net "M_C_CPU1_SB_CS_N<0>")
	)
	(arc
		(start 87.357966 -265.66368)
		(mid 87.640922 -265.739857)
		(end 87.923878 -265.66368)
		(width 0.0889)
		(layer "In2.Cu")
		(net "M_C_CPU1_SB_CS_N<0>")
	)
	(arc
		(start 83.598004 -265.66368)
		(mid 83.88096 -265.739857)
		(end 84.163916 -265.66368)
		(width 0.0889)
		(layer "In2.Cu")
		(net "M_C_CPU1_SB_CS_N<0>")
	)
	(segment
		(start 96.097852 -270.580358)
		(end 95.631 -270.846296)
		(width 0.10668)
		(layer "F.Cu")
		(net "M_C_CPU1_SB_CB<7>")
	)
	(segment
		(start 41.383966 -273.661378)
		(end 41.54678 -273.498564)
		(width 0.14478)
		(layer "In2.Cu")
		(net "M_C_CPU1_SB_CB<7>")
	)
	(segment
		(start 90.74404 -270.523716)
		(end 90.752422 -270.51889)
		(width 0.0889)
		(layer "In2.Cu")
		(net "M_C_CPU1_SB_CB<7>")
	)
	(segment
		(start 42.104056 -274.261326)
		(end 50.153824 -274.261326)
		(width 0.14478)
		(layer "In2.Cu")
		(net "M_C_CPU1_SB_CB<7>")
	)
	(segment
		(start 51.004724 -273.410426)
		(end 53.99659 -273.410426)
		(width 0.14478)
		(layer "In2.Cu")
		(net "M_C_CPU1_SB_CB<7>")
	)
	(segment
		(start 40.23995 -274.685252)
		(end 40.664892 -274.26031)
		(width 0.14478)
		(layer "In2.Cu")
		(net "M_C_CPU1_SB_CB<7>")
	)
	(segment
		(start 86.044024 -270.523716)
		(end 86.052406 -270.51889)
		(width 0.0889)
		(layer "In2.Cu")
		(net "M_C_CPU1_SB_CB<7>")
	)
	(segment
		(start 83.589622 -270.51889)
		(end 83.598004 -270.523716)
		(width 0.0889)
		(layer "In2.Cu")
		(net "M_C_CPU1_SB_CB<7>")
	)
	(segment
		(start 85.10397 -270.523716)
		(end 85.112352 -270.51889)
		(width 0.0889)
		(layer "In2.Cu")
		(net "M_C_CPU1_SB_CB<7>")
	)
	(segment
		(start 57.619646 -274.26031)
		(end 58.46953 -273.410426)
		(width 0.14478)
		(layer "In2.Cu")
		(net "M_C_CPU1_SB_CB<7>")
	)
	(segment
		(start 93.929708 -270.51889)
		(end 93.93809 -270.523716)
		(width 0.0889)
		(layer "In2.Cu")
		(net "M_C_CPU1_SB_CB<7>")
	)
	(segment
		(start 75.916536 -268.960854)
		(end 76.195936 -268.960854)
		(width 0.0889)
		(layer "In2.Cu")
		(net "M_C_CPU1_SB_CB<7>")
	)
	(segment
		(start 78.387194 -270.489172)
		(end 79.709518 -270.489172)
		(width 0.0889)
		(layer "In2.Cu")
		(net "M_C_CPU1_SB_CB<7>")
	)
	(segment
		(start 54.846474 -274.26031)
		(end 57.619646 -274.26031)
		(width 0.14478)
		(layer "In2.Cu")
		(net "M_C_CPU1_SB_CB<7>")
	)
	(segment
		(start 64.708786 -268.960854)
		(end 75.916536 -268.960854)
		(width 0.14478)
		(layer "In2.Cu")
		(net "M_C_CPU1_SB_CB<7>")
	)
	(segment
		(start 53.99659 -273.410426)
		(end 54.846474 -274.26031)
		(width 0.14478)
		(layer "In2.Cu")
		(net "M_C_CPU1_SB_CB<7>")
	)
	(segment
		(start 40.664892 -274.26031)
		(end 41.221152 -274.26031)
		(width 0.14478)
		(layer "In2.Cu")
		(net "M_C_CPU1_SB_CB<7>")
	)
	(segment
		(start 77.103986 -269.205964)
		(end 78.387194 -270.489172)
		(width 0.0889)
		(layer "In2.Cu")
		(net "M_C_CPU1_SB_CB<7>")
	)
	(segment
		(start 95.762826 -270.497554)
		(end 95.785178 -270.580866)
		(width 0.0889)
		(layer "In2.Cu")
		(net "M_C_CPU1_SB_CB<7>")
	)
	(segment
		(start 89.229692 -270.51889)
		(end 89.238074 -270.523716)
		(width 0.0889)
		(layer "In2.Cu")
		(net "M_C_CPU1_SB_CB<7>")
	)
	(segment
		(start 92.989654 -270.51889)
		(end 92.998036 -270.523716)
		(width 0.0889)
		(layer "In2.Cu")
		(net "M_C_CPU1_SB_CB<7>")
	)
	(segment
		(start 84.529676 -270.51889)
		(end 84.538058 -270.523716)
		(width 0.0889)
		(layer "In2.Cu")
		(net "M_C_CPU1_SB_CB<7>")
	)
	(segment
		(start 94.504002 -270.523716)
		(end 94.512384 -270.51889)
		(width 0.0889)
		(layer "In2.Cu")
		(net "M_C_CPU1_SB_CB<7>")
	)
	(segment
		(start 58.46953 -273.410426)
		(end 60.259214 -273.410426)
		(width 0.14478)
		(layer "In2.Cu")
		(net "M_C_CPU1_SB_CB<7>")
	)
	(segment
		(start 76.441046 -269.205964)
		(end 77.103986 -269.205964)
		(width 0.0889)
		(layer "In2.Cu")
		(net "M_C_CPU1_SB_CB<7>")
	)
	(segment
		(start 41.940226 -274.097496)
		(end 42.104056 -274.261326)
		(width 0.14478)
		(layer "In2.Cu")
		(net "M_C_CPU1_SB_CB<7>")
	)
	(segment
		(start 88.289638 -270.51889)
		(end 88.29802 -270.523716)
		(width 0.0889)
		(layer "In2.Cu")
		(net "M_C_CPU1_SB_CB<7>")
	)
	(segment
		(start 80.389222 -270.532352)
		(end 80.403954 -270.523716)
		(width 0.0889)
		(layer "In2.Cu")
		(net "M_C_CPU1_SB_CB<7>")
	)
	(segment
		(start 41.777412 -273.498564)
		(end 41.940226 -273.661378)
		(width 0.14478)
		(layer "In2.Cu")
		(net "M_C_CPU1_SB_CB<7>")
	)
	(segment
		(start 95.444056 -270.523716)
		(end 95.452438 -270.51889)
		(width 0.0889)
		(layer "In2.Cu")
		(net "M_C_CPU1_SB_CB<7>")
	)
	(segment
		(start 89.803986 -270.523716)
		(end 89.812368 -270.51889)
		(width 0.0889)
		(layer "In2.Cu")
		(net "M_C_CPU1_SB_CB<7>")
	)
	(segment
		(start 41.383966 -274.097496)
		(end 41.383966 -273.661378)
		(width 0.14478)
		(layer "In2.Cu")
		(net "M_C_CPU1_SB_CB<7>")
	)
	(segment
		(start 41.54678 -273.498564)
		(end 41.777412 -273.498564)
		(width 0.14478)
		(layer "In2.Cu")
		(net "M_C_CPU1_SB_CB<7>")
	)
	(segment
		(start 41.221152 -274.26031)
		(end 41.383966 -274.097496)
		(width 0.14478)
		(layer "In2.Cu")
		(net "M_C_CPU1_SB_CB<7>")
	)
	(segment
		(start 81.344008 -270.523716)
		(end 81.35239 -270.51889)
		(width 0.0889)
		(layer "In2.Cu")
		(net "M_C_CPU1_SB_CB<7>")
	)
	(segment
		(start 60.259214 -273.410426)
		(end 64.708786 -268.960854)
		(width 0.14478)
		(layer "In2.Cu")
		(net "M_C_CPU1_SB_CB<7>")
	)
	(segment
		(start 76.195936 -268.960854)
		(end 76.441046 -269.205964)
		(width 0.0889)
		(layer "In2.Cu")
		(net "M_C_CPU1_SB_CB<7>")
	)
	(segment
		(start 50.153824 -274.261326)
		(end 51.004724 -273.410426)
		(width 0.14478)
		(layer "In2.Cu")
		(net "M_C_CPU1_SB_CB<7>")
	)
	(segment
		(start 95.785178 -270.580866)
		(end 95.631 -270.846296)
		(width 0.0889)
		(layer "In2.Cu")
		(net "M_C_CPU1_SB_CB<7>")
	)
	(segment
		(start 80.769714 -270.51889)
		(end 80.778096 -270.523716)
		(width 0.0889)
		(layer "In2.Cu")
		(net "M_C_CPU1_SB_CB<7>")
	)
	(segment
		(start 41.940226 -273.661378)
		(end 41.940226 -274.097496)
		(width 0.14478)
		(layer "In2.Cu")
		(net "M_C_CPU1_SB_CB<7>")
	)
	(arc
		(start 85.112352 -270.51889)
		(mid 85.29586 -270.473396)
		(end 85.478112 -270.523716)
		(width 0.0889)
		(layer "In2.Cu")
		(net "M_C_CPU1_SB_CB<7>")
	)
	(arc
		(start 85.478112 -270.523716)
		(mid 85.761068 -270.599893)
		(end 86.044024 -270.523716)
		(width 0.0889)
		(layer "In2.Cu")
		(net "M_C_CPU1_SB_CB<7>")
	)
	(arc
		(start 84.538058 -270.523716)
		(mid 84.821014 -270.599893)
		(end 85.10397 -270.523716)
		(width 0.0889)
		(layer "In2.Cu")
		(net "M_C_CPU1_SB_CB<7>")
	)
	(arc
		(start 79.837534 -270.523716)
		(mid 80.11224 -270.60008)
		(end 80.389222 -270.532352)
		(width 0.0889)
		(layer "In2.Cu")
		(net "M_C_CPU1_SB_CB<7>")
	)
	(arc
		(start 92.057982 -270.523716)
		(mid 92.340938 -270.599893)
		(end 92.623894 -270.523716)
		(width 0.0889)
		(layer "In2.Cu")
		(net "M_C_CPU1_SB_CB<7>")
	)
	(arc
		(start 94.512384 -270.51889)
		(mid 94.695892 -270.473396)
		(end 94.878144 -270.523716)
		(width 0.0889)
		(layer "In2.Cu")
		(net "M_C_CPU1_SB_CB<7>")
	)
	(arc
		(start 87.923878 -270.523716)
		(mid 88.106129 -270.473366)
		(end 88.289638 -270.51889)
		(width 0.0889)
		(layer "In2.Cu")
		(net "M_C_CPU1_SB_CB<7>")
	)
	(arc
		(start 95.452438 -270.51889)
		(mid 95.605308 -270.474249)
		(end 95.762826 -270.497554)
		(width 0.0889)
		(layer "In2.Cu")
		(net "M_C_CPU1_SB_CB<7>")
	)
	(arc
		(start 82.284062 -270.523716)
		(mid 82.471006 -270.473461)
		(end 82.65795 -270.523716)
		(width 0.0889)
		(layer "In2.Cu")
		(net "M_C_CPU1_SB_CB<7>")
	)
	(arc
		(start 91.118182 -270.523716)
		(mid 91.401138 -270.599893)
		(end 91.684094 -270.523716)
		(width 0.0889)
		(layer "In2.Cu")
		(net "M_C_CPU1_SB_CB<7>")
	)
	(arc
		(start 93.93809 -270.523716)
		(mid 94.221046 -270.599893)
		(end 94.504002 -270.523716)
		(width 0.0889)
		(layer "In2.Cu")
		(net "M_C_CPU1_SB_CB<7>")
	)
	(arc
		(start 88.29802 -270.523716)
		(mid 88.580976 -270.599893)
		(end 88.863932 -270.523716)
		(width 0.0889)
		(layer "In2.Cu")
		(net "M_C_CPU1_SB_CB<7>")
	)
	(arc
		(start 80.778096 -270.523716)
		(mid 81.061052 -270.599893)
		(end 81.344008 -270.523716)
		(width 0.0889)
		(layer "In2.Cu")
		(net "M_C_CPU1_SB_CB<7>")
	)
	(arc
		(start 83.223862 -270.523716)
		(mid 83.406113 -270.473366)
		(end 83.589622 -270.51889)
		(width 0.0889)
		(layer "In2.Cu")
		(net "M_C_CPU1_SB_CB<7>")
	)
	(arc
		(start 90.178128 -270.523716)
		(mid 90.461084 -270.599893)
		(end 90.74404 -270.523716)
		(width 0.0889)
		(layer "In2.Cu")
		(net "M_C_CPU1_SB_CB<7>")
	)
	(arc
		(start 80.403954 -270.523716)
		(mid 80.586205 -270.473366)
		(end 80.769714 -270.51889)
		(width 0.0889)
		(layer "In2.Cu")
		(net "M_C_CPU1_SB_CB<7>")
	)
	(arc
		(start 89.812368 -270.51889)
		(mid 89.995876 -270.473396)
		(end 90.178128 -270.523716)
		(width 0.0889)
		(layer "In2.Cu")
		(net "M_C_CPU1_SB_CB<7>")
	)
	(arc
		(start 88.863932 -270.523716)
		(mid 89.046183 -270.473366)
		(end 89.229692 -270.51889)
		(width 0.0889)
		(layer "In2.Cu")
		(net "M_C_CPU1_SB_CB<7>")
	)
	(arc
		(start 86.984078 -270.523716)
		(mid 87.171022 -270.473461)
		(end 87.357966 -270.523716)
		(width 0.0889)
		(layer "In2.Cu")
		(net "M_C_CPU1_SB_CB<7>")
	)
	(arc
		(start 83.598004 -270.523716)
		(mid 83.88096 -270.599893)
		(end 84.163916 -270.523716)
		(width 0.0889)
		(layer "In2.Cu")
		(net "M_C_CPU1_SB_CB<7>")
	)
	(arc
		(start 87.357966 -270.523716)
		(mid 87.640922 -270.599893)
		(end 87.923878 -270.523716)
		(width 0.0889)
		(layer "In2.Cu")
		(net "M_C_CPU1_SB_CB<7>")
	)
	(arc
		(start 91.684094 -270.523716)
		(mid 91.871038 -270.473461)
		(end 92.057982 -270.523716)
		(width 0.0889)
		(layer "In2.Cu")
		(net "M_C_CPU1_SB_CB<7>")
	)
	(arc
		(start 86.052406 -270.51889)
		(mid 86.235914 -270.473396)
		(end 86.418166 -270.523716)
		(width 0.0889)
		(layer "In2.Cu")
		(net "M_C_CPU1_SB_CB<7>")
	)
	(arc
		(start 84.163916 -270.523716)
		(mid 84.346167 -270.473366)
		(end 84.529676 -270.51889)
		(width 0.0889)
		(layer "In2.Cu")
		(net "M_C_CPU1_SB_CB<7>")
	)
	(arc
		(start 90.752422 -270.51889)
		(mid 90.93593 -270.473396)
		(end 91.118182 -270.523716)
		(width 0.0889)
		(layer "In2.Cu")
		(net "M_C_CPU1_SB_CB<7>")
	)
	(arc
		(start 92.623894 -270.523716)
		(mid 92.806145 -270.473366)
		(end 92.989654 -270.51889)
		(width 0.0889)
		(layer "In2.Cu")
		(net "M_C_CPU1_SB_CB<7>")
	)
	(arc
		(start 79.709518 -270.489172)
		(mid 79.77582 -270.497951)
		(end 79.837534 -270.523716)
		(width 0.0889)
		(layer "In2.Cu")
		(net "M_C_CPU1_SB_CB<7>")
	)
	(arc
		(start 86.418166 -270.523716)
		(mid 86.701122 -270.599893)
		(end 86.984078 -270.523716)
		(width 0.0889)
		(layer "In2.Cu")
		(net "M_C_CPU1_SB_CB<7>")
	)
	(arc
		(start 93.563948 -270.523716)
		(mid 93.746199 -270.473366)
		(end 93.929708 -270.51889)
		(width 0.0889)
		(layer "In2.Cu")
		(net "M_C_CPU1_SB_CB<7>")
	)
	(arc
		(start 92.998036 -270.523716)
		(mid 93.280992 -270.599893)
		(end 93.563948 -270.523716)
		(width 0.0889)
		(layer "In2.Cu")
		(net "M_C_CPU1_SB_CB<7>")
	)
	(arc
		(start 81.71815 -270.523716)
		(mid 82.001106 -270.599893)
		(end 82.284062 -270.523716)
		(width 0.0889)
		(layer "In2.Cu")
		(net "M_C_CPU1_SB_CB<7>")
	)
	(arc
		(start 94.878144 -270.523716)
		(mid 95.1611 -270.599893)
		(end 95.444056 -270.523716)
		(width 0.0889)
		(layer "In2.Cu")
		(net "M_C_CPU1_SB_CB<7>")
	)
	(arc
		(start 89.238074 -270.523716)
		(mid 89.52103 -270.599893)
		(end 89.803986 -270.523716)
		(width 0.0889)
		(layer "In2.Cu")
		(net "M_C_CPU1_SB_CB<7>")
	)
	(arc
		(start 81.35239 -270.51889)
		(mid 81.535898 -270.473396)
		(end 81.71815 -270.523716)
		(width 0.0889)
		(layer "In2.Cu")
		(net "M_C_CPU1_SB_CB<7>")
	)
	(arc
		(start 82.65795 -270.523716)
		(mid 82.940906 -270.599893)
		(end 83.223862 -270.523716)
		(width 0.0889)
		(layer "In2.Cu")
		(net "M_C_CPU1_SB_CB<7>")
	)
	(segment
		(start 94.687898 -269.770352)
		(end 94.221046 -270.03629)
		(width 0.10668)
		(layer "F.Cu")
		(net "M_C_CPU1_SB_CB<6>")
	)
	(segment
		(start 42.333672 -272.560288)
		(end 42.496486 -272.397474)
		(width 0.14478)
		(layer "In2.Cu")
		(net "M_C_CPU1_SB_CB<6>")
	)
	(segment
		(start 43.21556 -272.560288)
		(end 50.178462 -272.560288)
		(width 0.14478)
		(layer "In2.Cu")
		(net "M_C_CPU1_SB_CB<6>")
	)
	(segment
		(start 40.664892 -272.560288)
		(end 41.221152 -272.560288)
		(width 0.14478)
		(layer "In2.Cu")
		(net "M_C_CPU1_SB_CB<6>")
	)
	(segment
		(start 85.93963 -269.708884)
		(end 85.948012 -269.71371)
		(width 0.0889)
		(layer "In2.Cu")
		(net "M_C_CPU1_SB_CB<6>")
	)
	(segment
		(start 93.094048 -269.71371)
		(end 93.10243 -269.708884)
		(width 0.0889)
		(layer "In2.Cu")
		(net "M_C_CPU1_SB_CB<6>")
	)
	(segment
		(start 42.10304 -272.560288)
		(end 42.333672 -272.560288)
		(width 0.14478)
		(layer "In2.Cu")
		(net "M_C_CPU1_SB_CB<6>")
	)
	(segment
		(start 42.496486 -272.397474)
		(end 42.496486 -271.70888)
		(width 0.14478)
		(layer "In2.Cu")
		(net "M_C_CPU1_SB_CB<6>")
	)
	(segment
		(start 87.453978 -269.71371)
		(end 87.46236 -269.708884)
		(width 0.0889)
		(layer "In2.Cu")
		(net "M_C_CPU1_SB_CB<6>")
	)
	(segment
		(start 76.888086 -268.647164)
		(end 77.291692 -268.647164)
		(width 0.0889)
		(layer "In2.Cu")
		(net "M_C_CPU1_SB_CB<6>")
	)
	(segment
		(start 41.940226 -271.502378)
		(end 41.940226 -272.397474)
		(width 0.14478)
		(layer "In2.Cu")
		(net "M_C_CPU1_SB_CB<6>")
	)
	(segment
		(start 60.582302 -271.710404)
		(end 64.241172 -268.051534)
		(width 0.14478)
		(layer "In2.Cu")
		(net "M_C_CPU1_SB_CB<6>")
	)
	(segment
		(start 94.352618 -269.687548)
		(end 94.37497 -269.77086)
		(width 0.0889)
		(layer "In2.Cu")
		(net "M_C_CPU1_SB_CB<6>")
	)
	(segment
		(start 78.260702 -269.616174)
		(end 78.467966 -269.735808)
		(width 0.0889)
		(layer "In2.Cu")
		(net "M_C_CPU1_SB_CB<6>")
	)
	(segment
		(start 91.5797 -269.708884)
		(end 91.588082 -269.71371)
		(width 0.0889)
		(layer "In2.Cu")
		(net "M_C_CPU1_SB_CB<6>")
	)
	(segment
		(start 43.052746 -271.70888)
		(end 43.052746 -272.397474)
		(width 0.14478)
		(layer "In2.Cu")
		(net "M_C_CPU1_SB_CB<6>")
	)
	(segment
		(start 42.6593 -271.546066)
		(end 42.889932 -271.546066)
		(width 0.14478)
		(layer "In2.Cu")
		(net "M_C_CPU1_SB_CB<6>")
	)
	(segment
		(start 42.889932 -271.546066)
		(end 43.052746 -271.70888)
		(width 0.14478)
		(layer "In2.Cu")
		(net "M_C_CPU1_SB_CB<6>")
	)
	(segment
		(start 41.383966 -271.502378)
		(end 41.54678 -271.339564)
		(width 0.14478)
		(layer "In2.Cu")
		(net "M_C_CPU1_SB_CB<6>")
	)
	(segment
		(start 79.36992 -269.713964)
		(end 79.393796 -269.727934)
		(width 0.0889)
		(layer "In2.Cu")
		(net "M_C_CPU1_SB_CB<6>")
	)
	(segment
		(start 86.879684 -269.708884)
		(end 86.888066 -269.71371)
		(width 0.0889)
		(layer "In2.Cu")
		(net "M_C_CPU1_SB_CB<6>")
	)
	(segment
		(start 41.383966 -272.397474)
		(end 41.383966 -271.502378)
		(width 0.14478)
		(layer "In2.Cu")
		(net "M_C_CPU1_SB_CB<6>")
	)
	(segment
		(start 41.54678 -271.339564)
		(end 41.777412 -271.339564)
		(width 0.14478)
		(layer "In2.Cu")
		(net "M_C_CPU1_SB_CB<6>")
	)
	(segment
		(start 77.291692 -268.647164)
		(end 78.260702 -269.616174)
		(width 0.0889)
		(layer "In2.Cu")
		(net "M_C_CPU1_SB_CB<6>")
	)
	(segment
		(start 51.028346 -271.710404)
		(end 60.582302 -271.710404)
		(width 0.14478)
		(layer "In2.Cu")
		(net "M_C_CPU1_SB_CB<6>")
	)
	(segment
		(start 41.940226 -272.397474)
		(end 42.10304 -272.560288)
		(width 0.14478)
		(layer "In2.Cu")
		(net "M_C_CPU1_SB_CB<6>")
	)
	(segment
		(start 42.496486 -271.70888)
		(end 42.6593 -271.546066)
		(width 0.14478)
		(layer "In2.Cu")
		(net "M_C_CPU1_SB_CB<6>")
	)
	(segment
		(start 75.973686 -268.051534)
		(end 76.292456 -268.051534)
		(width 0.0889)
		(layer "In2.Cu")
		(net "M_C_CPU1_SB_CB<6>")
	)
	(segment
		(start 76.292456 -268.051534)
		(end 76.888086 -268.647164)
		(width 0.0889)
		(layer "In2.Cu")
		(net "M_C_CPU1_SB_CB<6>")
	)
	(segment
		(start 90.639646 -269.708884)
		(end 90.648028 -269.71371)
		(width 0.0889)
		(layer "In2.Cu")
		(net "M_C_CPU1_SB_CB<6>")
	)
	(segment
		(start 88.394032 -269.71371)
		(end 88.402414 -269.708884)
		(width 0.0889)
		(layer "In2.Cu")
		(net "M_C_CPU1_SB_CB<6>")
	)
	(segment
		(start 83.694016 -269.71371)
		(end 83.702398 -269.708884)
		(width 0.0889)
		(layer "In2.Cu")
		(net "M_C_CPU1_SB_CB<6>")
	)
	(segment
		(start 94.37497 -269.77086)
		(end 94.221046 -270.03629)
		(width 0.0889)
		(layer "In2.Cu")
		(net "M_C_CPU1_SB_CB<6>")
	)
	(segment
		(start 43.052746 -272.397474)
		(end 43.21556 -272.560288)
		(width 0.14478)
		(layer "In2.Cu")
		(net "M_C_CPU1_SB_CB<6>")
	)
	(segment
		(start 41.777412 -271.339564)
		(end 41.940226 -271.502378)
		(width 0.14478)
		(layer "In2.Cu")
		(net "M_C_CPU1_SB_CB<6>")
	)
	(segment
		(start 50.178462 -272.560288)
		(end 51.028346 -271.710404)
		(width 0.14478)
		(layer "In2.Cu")
		(net "M_C_CPU1_SB_CB<6>")
	)
	(segment
		(start 40.23995 -272.98523)
		(end 40.664892 -272.560288)
		(width 0.14478)
		(layer "In2.Cu")
		(net "M_C_CPU1_SB_CB<6>")
	)
	(segment
		(start 79.339948 -269.696692)
		(end 79.36992 -269.713964)
		(width 0.0889)
		(layer "In2.Cu")
		(net "M_C_CPU1_SB_CB<6>")
	)
	(segment
		(start 64.241172 -268.051534)
		(end 75.973686 -268.051534)
		(width 0.14478)
		(layer "In2.Cu")
		(net "M_C_CPU1_SB_CB<6>")
	)
	(segment
		(start 79.934054 -269.71371)
		(end 79.942436 -269.708884)
		(width 0.0889)
		(layer "In2.Cu")
		(net "M_C_CPU1_SB_CB<6>")
	)
	(segment
		(start 82.753962 -269.71371)
		(end 82.762344 -269.708884)
		(width 0.0889)
		(layer "In2.Cu")
		(net "M_C_CPU1_SB_CB<6>")
	)
	(segment
		(start 92.153994 -269.71371)
		(end 92.162376 -269.708884)
		(width 0.0889)
		(layer "In2.Cu")
		(net "M_C_CPU1_SB_CB<6>")
	)
	(segment
		(start 82.179668 -269.708884)
		(end 82.18805 -269.71371)
		(width 0.0889)
		(layer "In2.Cu")
		(net "M_C_CPU1_SB_CB<6>")
	)
	(segment
		(start 41.221152 -272.560288)
		(end 41.383966 -272.397474)
		(width 0.14478)
		(layer "In2.Cu")
		(net "M_C_CPU1_SB_CB<6>")
	)
	(arc
		(start 86.513924 -269.71371)
		(mid 86.696175 -269.66336)
		(end 86.879684 -269.708884)
		(width 0.0889)
		(layer "In2.Cu")
		(net "M_C_CPU1_SB_CB<6>")
	)
	(arc
		(start 93.10243 -269.708884)
		(mid 93.285938 -269.66339)
		(end 93.46819 -269.71371)
		(width 0.0889)
		(layer "In2.Cu")
		(net "M_C_CPU1_SB_CB<6>")
	)
	(arc
		(start 92.162376 -269.708884)
		(mid 92.345884 -269.66339)
		(end 92.528136 -269.71371)
		(width 0.0889)
		(layer "In2.Cu")
		(net "M_C_CPU1_SB_CB<6>")
	)
	(arc
		(start 91.588082 -269.71371)
		(mid 91.871038 -269.789887)
		(end 92.153994 -269.71371)
		(width 0.0889)
		(layer "In2.Cu")
		(net "M_C_CPU1_SB_CB<6>")
	)
	(arc
		(start 90.273886 -269.71371)
		(mid 90.456137 -269.66336)
		(end 90.639646 -269.708884)
		(width 0.0889)
		(layer "In2.Cu")
		(net "M_C_CPU1_SB_CB<6>")
	)
	(arc
		(start 92.528136 -269.71371)
		(mid 92.811092 -269.789887)
		(end 93.094048 -269.71371)
		(width 0.0889)
		(layer "In2.Cu")
		(net "M_C_CPU1_SB_CB<6>")
	)
	(arc
		(start 89.334086 -269.71371)
		(mid 89.52103 -269.663455)
		(end 89.707974 -269.71371)
		(width 0.0889)
		(layer "In2.Cu")
		(net "M_C_CPU1_SB_CB<6>")
	)
	(arc
		(start 91.21394 -269.71371)
		(mid 91.396191 -269.66336)
		(end 91.5797 -269.708884)
		(width 0.0889)
		(layer "In2.Cu")
		(net "M_C_CPU1_SB_CB<6>")
	)
	(arc
		(start 79.393796 -269.727934)
		(mid 79.665733 -269.78976)
		(end 79.934054 -269.71371)
		(width 0.0889)
		(layer "In2.Cu")
		(net "M_C_CPU1_SB_CB<6>")
	)
	(arc
		(start 94.034102 -269.71371)
		(mid 94.190421 -269.664715)
		(end 94.352618 -269.687548)
		(width 0.0889)
		(layer "In2.Cu")
		(net "M_C_CPU1_SB_CB<6>")
	)
	(arc
		(start 80.874108 -269.71371)
		(mid 81.061052 -269.663455)
		(end 81.247996 -269.71371)
		(width 0.0889)
		(layer "In2.Cu")
		(net "M_C_CPU1_SB_CB<6>")
	)
	(arc
		(start 88.768174 -269.71371)
		(mid 89.05113 -269.789887)
		(end 89.334086 -269.71371)
		(width 0.0889)
		(layer "In2.Cu")
		(net "M_C_CPU1_SB_CB<6>")
	)
	(arc
		(start 90.648028 -269.71371)
		(mid 90.930984 -269.789887)
		(end 91.21394 -269.71371)
		(width 0.0889)
		(layer "In2.Cu")
		(net "M_C_CPU1_SB_CB<6>")
	)
	(arc
		(start 79.942436 -269.708884)
		(mid 80.125944 -269.66339)
		(end 80.308196 -269.71371)
		(width 0.0889)
		(layer "In2.Cu")
		(net "M_C_CPU1_SB_CB<6>")
	)
	(arc
		(start 82.18805 -269.71371)
		(mid 82.471006 -269.789887)
		(end 82.753962 -269.71371)
		(width 0.0889)
		(layer "In2.Cu")
		(net "M_C_CPU1_SB_CB<6>")
	)
	(arc
		(start 81.247996 -269.71371)
		(mid 81.530952 -269.789887)
		(end 81.813908 -269.71371)
		(width 0.0889)
		(layer "In2.Cu")
		(net "M_C_CPU1_SB_CB<6>")
	)
	(arc
		(start 84.63407 -269.71371)
		(mid 84.821014 -269.663455)
		(end 85.007958 -269.71371)
		(width 0.0889)
		(layer "In2.Cu")
		(net "M_C_CPU1_SB_CB<6>")
	)
	(arc
		(start 78.995778 -269.71371)
		(mid 79.165785 -269.663145)
		(end 79.339948 -269.696692)
		(width 0.0889)
		(layer "In2.Cu")
		(net "M_C_CPU1_SB_CB<6>")
	)
	(arc
		(start 85.948012 -269.71371)
		(mid 86.230968 -269.789887)
		(end 86.513924 -269.71371)
		(width 0.0889)
		(layer "In2.Cu")
		(net "M_C_CPU1_SB_CB<6>")
	)
	(arc
		(start 87.82812 -269.71371)
		(mid 88.111076 -269.789887)
		(end 88.394032 -269.71371)
		(width 0.0889)
		(layer "In2.Cu")
		(net "M_C_CPU1_SB_CB<6>")
	)
	(arc
		(start 82.762344 -269.708884)
		(mid 82.945852 -269.66339)
		(end 83.128104 -269.71371)
		(width 0.0889)
		(layer "In2.Cu")
		(net "M_C_CPU1_SB_CB<6>")
	)
	(arc
		(start 84.068158 -269.71371)
		(mid 84.351114 -269.789887)
		(end 84.63407 -269.71371)
		(width 0.0889)
		(layer "In2.Cu")
		(net "M_C_CPU1_SB_CB<6>")
	)
	(arc
		(start 87.46236 -269.708884)
		(mid 87.645868 -269.66339)
		(end 87.82812 -269.71371)
		(width 0.0889)
		(layer "In2.Cu")
		(net "M_C_CPU1_SB_CB<6>")
	)
	(arc
		(start 85.007958 -269.71371)
		(mid 85.290914 -269.789887)
		(end 85.57387 -269.71371)
		(width 0.0889)
		(layer "In2.Cu")
		(net "M_C_CPU1_SB_CB<6>")
	)
	(arc
		(start 89.707974 -269.71371)
		(mid 89.99093 -269.789887)
		(end 90.273886 -269.71371)
		(width 0.0889)
		(layer "In2.Cu")
		(net "M_C_CPU1_SB_CB<6>")
	)
	(arc
		(start 81.813908 -269.71371)
		(mid 81.996159 -269.66336)
		(end 82.179668 -269.708884)
		(width 0.0889)
		(layer "In2.Cu")
		(net "M_C_CPU1_SB_CB<6>")
	)
	(arc
		(start 83.128104 -269.71371)
		(mid 83.41106 -269.789887)
		(end 83.694016 -269.71371)
		(width 0.0889)
		(layer "In2.Cu")
		(net "M_C_CPU1_SB_CB<6>")
	)
	(arc
		(start 78.467966 -269.735808)
		(mid 78.734622 -269.790328)
		(end 78.995778 -269.71371)
		(width 0.0889)
		(layer "In2.Cu")
		(net "M_C_CPU1_SB_CB<6>")
	)
	(arc
		(start 93.46819 -269.71371)
		(mid 93.751146 -269.789887)
		(end 94.034102 -269.71371)
		(width 0.0889)
		(layer "In2.Cu")
		(net "M_C_CPU1_SB_CB<6>")
	)
	(arc
		(start 86.888066 -269.71371)
		(mid 87.171022 -269.789887)
		(end 87.453978 -269.71371)
		(width 0.0889)
		(layer "In2.Cu")
		(net "M_C_CPU1_SB_CB<6>")
	)
	(arc
		(start 88.402414 -269.708884)
		(mid 88.585922 -269.66339)
		(end 88.768174 -269.71371)
		(width 0.0889)
		(layer "In2.Cu")
		(net "M_C_CPU1_SB_CB<6>")
	)
	(arc
		(start 80.308196 -269.71371)
		(mid 80.591152 -269.789887)
		(end 80.874108 -269.71371)
		(width 0.0889)
		(layer "In2.Cu")
		(net "M_C_CPU1_SB_CB<6>")
	)
	(arc
		(start 83.702398 -269.708884)
		(mid 83.885906 -269.66339)
		(end 84.068158 -269.71371)
		(width 0.0889)
		(layer "In2.Cu")
		(net "M_C_CPU1_SB_CB<6>")
	)
	(arc
		(start 85.57387 -269.71371)
		(mid 85.756121 -269.66336)
		(end 85.93963 -269.708884)
		(width 0.0889)
		(layer "In2.Cu")
		(net "M_C_CPU1_SB_CB<6>")
	)
	(segment
		(start 96.568006 -269.770352)
		(end 96.101154 -270.03629)
		(width 0.10668)
		(layer "F.Cu")
		(net "M_C_CPU1_SB_CB<5>")
	)
	(segment
		(start 57.455308 -272.177764)
		(end 57.733184 -272.177764)
		(width 0.14478)
		(layer "In2.Cu")
		(net "M_C_CPU1_SB_CB<5>")
	)
	(segment
		(start 58.776108 -272.560288)
		(end 60.368434 -272.560288)
		(width 0.14478)
		(layer "In2.Cu")
		(net "M_C_CPU1_SB_CB<5>")
	)
	(segment
		(start 60.368434 -272.560288)
		(end 64.422528 -268.506194)
		(width 0.14478)
		(layer "In2.Cu")
		(net "M_C_CPU1_SB_CB<5>")
	)
	(segment
		(start 53.014626 -272.664428)
		(end 53.014626 -272.551144)
		(width 0.14478)
		(layer "In2.Cu")
		(net "M_C_CPU1_SB_CB<5>")
	)
	(segment
		(start 44.76496 -273.410426)
		(end 45.656754 -273.410426)
		(width 0.14478)
		(layer "In2.Cu")
		(net "M_C_CPU1_SB_CB<5>")
	)
	(segment
		(start 75.917806 -268.506194)
		(end 76.188316 -268.506194)
		(width 0.0889)
		(layer "In2.Cu")
		(net "M_C_CPU1_SB_CB<5>")
	)
	(segment
		(start 49.434496 -273.701764)
		(end 49.725834 -273.410426)
		(width 0.14478)
		(layer "In2.Cu")
		(net "M_C_CPU1_SB_CB<5>")
	)
	(segment
		(start 83.694016 -270.35887)
		(end 83.702398 -270.363696)
		(width 0.0889)
		(layer "In2.Cu")
		(net "M_C_CPU1_SB_CB<5>")
	)
	(segment
		(start 54.72049 -272.180812)
		(end 55.099966 -272.560288)
		(width 0.14478)
		(layer "In2.Cu")
		(net "M_C_CPU1_SB_CB<5>")
	)
	(segment
		(start 57.072784 -273.81073)
		(end 57.264046 -273.619468)
		(width 0.14478)
		(layer "In2.Cu")
		(net "M_C_CPU1_SB_CB<5>")
	)
	(segment
		(start 54.190646 -272.581624)
		(end 54.190646 -272.429732)
		(width 0.14478)
		(layer "In2.Cu")
		(net "M_C_CPU1_SB_CB<5>")
	)
	(segment
		(start 54.439566 -272.180812)
		(end 54.72049 -272.180812)
		(width 0.14478)
		(layer "In2.Cu")
		(net "M_C_CPU1_SB_CB<5>")
	)
	(segment
		(start 52.458366 -272.939764)
		(end 52.73929 -272.939764)
		(width 0.14478)
		(layer "In2.Cu")
		(net "M_C_CPU1_SB_CB<5>")
	)
	(segment
		(start 86.879684 -270.363696)
		(end 86.888066 -270.35887)
		(width 0.0889)
		(layer "In2.Cu")
		(net "M_C_CPU1_SB_CB<5>")
	)
	(segment
		(start 58.115708 -272.942812)
		(end 58.393584 -272.942812)
		(width 0.14478)
		(layer "In2.Cu")
		(net "M_C_CPU1_SB_CB<5>")
	)
	(segment
		(start 52.73929 -272.939764)
		(end 53.014626 -272.664428)
		(width 0.14478)
		(layer "In2.Cu")
		(net "M_C_CPU1_SB_CB<5>")
	)
	(segment
		(start 95.85071 -270.32712)
		(end 95.946976 -270.30172)
		(width 0.0889)
		(layer "In2.Cu")
		(net "M_C_CPU1_SB_CB<5>")
	)
	(segment
		(start 57.264046 -272.369026)
		(end 57.455308 -272.177764)
		(width 0.14478)
		(layer "In2.Cu")
		(net "M_C_CPU1_SB_CB<5>")
	)
	(segment
		(start 56.603646 -272.369026)
		(end 56.603646 -273.619468)
		(width 0.14478)
		(layer "In2.Cu")
		(net "M_C_CPU1_SB_CB<5>")
	)
	(segment
		(start 49.725834 -273.410426)
		(end 50.16627 -273.410426)
		(width 0.14478)
		(layer "In2.Cu")
		(net "M_C_CPU1_SB_CB<5>")
	)
	(segment
		(start 52.07889 -272.560288)
		(end 52.458366 -272.939764)
		(width 0.14478)
		(layer "In2.Cu")
		(net "M_C_CPU1_SB_CB<5>")
	)
	(segment
		(start 45.953172 -273.706844)
		(end 46.213268 -273.706844)
		(width 0.14478)
		(layer "In2.Cu")
		(net "M_C_CPU1_SB_CB<5>")
	)
	(segment
		(start 56.794908 -273.81073)
		(end 57.072784 -273.81073)
		(width 0.14478)
		(layer "In2.Cu")
		(net "M_C_CPU1_SB_CB<5>")
	)
	(segment
		(start 85.93963 -270.363696)
		(end 85.948012 -270.35887)
		(width 0.0889)
		(layer "In2.Cu")
		(net "M_C_CPU1_SB_CB<5>")
	)
	(segment
		(start 53.39969 -272.401284)
		(end 53.72989 -272.731484)
		(width 0.14478)
		(layer "In2.Cu")
		(net "M_C_CPU1_SB_CB<5>")
	)
	(segment
		(start 90.639646 -270.363696)
		(end 90.648028 -270.35887)
		(width 0.0889)
		(layer "In2.Cu")
		(net "M_C_CPU1_SB_CB<5>")
	)
	(segment
		(start 82.179668 -270.363696)
		(end 82.18805 -270.35887)
		(width 0.0889)
		(layer "In2.Cu")
		(net "M_C_CPU1_SB_CB<5>")
	)
	(segment
		(start 87.453978 -270.35887)
		(end 87.46236 -270.363696)
		(width 0.0889)
		(layer "In2.Cu")
		(net "M_C_CPU1_SB_CB<5>")
	)
	(segment
		(start 92.153994 -270.35887)
		(end 92.162376 -270.363696)
		(width 0.0889)
		(layer "In2.Cu")
		(net "M_C_CPU1_SB_CB<5>")
	)
	(segment
		(start 76.188316 -268.506194)
		(end 76.599288 -268.917166)
		(width 0.0889)
		(layer "In2.Cu")
		(net "M_C_CPU1_SB_CB<5>")
	)
	(segment
		(start 64.422528 -268.506194)
		(end 75.917806 -268.506194)
		(width 0.14478)
		(layer "In2.Cu")
		(net "M_C_CPU1_SB_CB<5>")
	)
	(segment
		(start 57.924446 -272.369026)
		(end 57.924446 -272.75155)
		(width 0.14478)
		(layer "In2.Cu")
		(net "M_C_CPU1_SB_CB<5>")
	)
	(segment
		(start 95.946976 -270.30172)
		(end 96.101154 -270.03629)
		(width 0.0889)
		(layer "In2.Cu")
		(net "M_C_CPU1_SB_CB<5>")
	)
	(segment
		(start 50.16627 -273.410426)
		(end 51.016408 -272.560288)
		(width 0.14478)
		(layer "In2.Cu")
		(net "M_C_CPU1_SB_CB<5>")
	)
	(segment
		(start 49.16932 -273.701764)
		(end 49.434496 -273.701764)
		(width 0.14478)
		(layer "In2.Cu")
		(net "M_C_CPU1_SB_CB<5>")
	)
	(segment
		(start 53.72989 -272.731484)
		(end 54.040786 -272.731484)
		(width 0.14478)
		(layer "In2.Cu")
		(net "M_C_CPU1_SB_CB<5>")
	)
	(segment
		(start 95.339662 -270.363696)
		(end 95.348044 -270.35887)
		(width 0.0889)
		(layer "In2.Cu")
		(net "M_C_CPU1_SB_CB<5>")
	)
	(segment
		(start 93.094048 -270.35887)
		(end 93.10243 -270.363696)
		(width 0.0889)
		(layer "In2.Cu")
		(net "M_C_CPU1_SB_CB<5>")
	)
	(segment
		(start 78.488794 -270.285972)
		(end 79.66837 -270.285972)
		(width 0.0889)
		(layer "In2.Cu")
		(net "M_C_CPU1_SB_CB<5>")
	)
	(segment
		(start 56.134508 -272.177764)
		(end 56.412384 -272.177764)
		(width 0.14478)
		(layer "In2.Cu")
		(net "M_C_CPU1_SB_CB<5>")
	)
	(segment
		(start 77.119988 -268.917166)
		(end 78.488794 -270.285972)
		(width 0.0889)
		(layer "In2.Cu")
		(net "M_C_CPU1_SB_CB<5>")
	)
	(segment
		(start 46.509686 -273.410426)
		(end 48.877982 -273.410426)
		(width 0.14478)
		(layer "In2.Cu")
		(net "M_C_CPU1_SB_CB<5>")
	)
	(segment
		(start 54.190646 -272.429732)
		(end 54.439566 -272.180812)
		(width 0.14478)
		(layer "In2.Cu")
		(net "M_C_CPU1_SB_CB<5>")
	)
	(segment
		(start 48.877982 -273.410426)
		(end 49.16932 -273.701764)
		(width 0.14478)
		(layer "In2.Cu")
		(net "M_C_CPU1_SB_CB<5>")
	)
	(segment
		(start 91.5797 -270.363696)
		(end 91.588082 -270.35887)
		(width 0.0889)
		(layer "In2.Cu")
		(net "M_C_CPU1_SB_CB<5>")
	)
	(segment
		(start 57.924446 -272.75155)
		(end 58.115708 -272.942812)
		(width 0.14478)
		(layer "In2.Cu")
		(net "M_C_CPU1_SB_CB<5>")
	)
	(segment
		(start 57.264046 -273.619468)
		(end 57.264046 -272.369026)
		(width 0.14478)
		(layer "In2.Cu")
		(net "M_C_CPU1_SB_CB<5>")
	)
	(segment
		(start 80.299814 -270.363696)
		(end 80.308196 -270.35887)
		(width 0.0889)
		(layer "In2.Cu")
		(net "M_C_CPU1_SB_CB<5>")
	)
	(segment
		(start 51.016408 -272.560288)
		(end 52.07889 -272.560288)
		(width 0.14478)
		(layer "In2.Cu")
		(net "M_C_CPU1_SB_CB<5>")
	)
	(segment
		(start 58.393584 -272.942812)
		(end 58.776108 -272.560288)
		(width 0.14478)
		(layer "In2.Cu")
		(net "M_C_CPU1_SB_CB<5>")
	)
	(segment
		(start 45.656754 -273.410426)
		(end 45.953172 -273.706844)
		(width 0.14478)
		(layer "In2.Cu")
		(net "M_C_CPU1_SB_CB<5>")
	)
	(segment
		(start 82.753962 -270.35887)
		(end 82.762344 -270.363696)
		(width 0.0889)
		(layer "In2.Cu")
		(net "M_C_CPU1_SB_CB<5>")
	)
	(segment
		(start 76.599288 -268.917166)
		(end 77.119988 -268.917166)
		(width 0.0889)
		(layer "In2.Cu")
		(net "M_C_CPU1_SB_CB<5>")
	)
	(segment
		(start 56.412384 -272.177764)
		(end 56.603646 -272.369026)
		(width 0.14478)
		(layer "In2.Cu")
		(net "M_C_CPU1_SB_CB<5>")
	)
	(segment
		(start 56.603646 -273.619468)
		(end 56.794908 -273.81073)
		(width 0.14478)
		(layer "In2.Cu")
		(net "M_C_CPU1_SB_CB<5>")
	)
	(segment
		(start 54.040786 -272.731484)
		(end 54.190646 -272.581624)
		(width 0.14478)
		(layer "In2.Cu")
		(net "M_C_CPU1_SB_CB<5>")
	)
	(segment
		(start 44.340018 -273.835368)
		(end 44.76496 -273.410426)
		(width 0.14478)
		(layer "In2.Cu")
		(net "M_C_CPU1_SB_CB<5>")
	)
	(segment
		(start 53.164486 -272.401284)
		(end 53.39969 -272.401284)
		(width 0.14478)
		(layer "In2.Cu")
		(net "M_C_CPU1_SB_CB<5>")
	)
	(segment
		(start 79.928974 -270.35633)
		(end 79.933546 -270.35887)
		(width 0.0889)
		(layer "In2.Cu")
		(net "M_C_CPU1_SB_CB<5>")
	)
	(segment
		(start 55.099966 -272.560288)
		(end 55.751984 -272.560288)
		(width 0.14478)
		(layer "In2.Cu")
		(net "M_C_CPU1_SB_CB<5>")
	)
	(segment
		(start 57.733184 -272.177764)
		(end 57.924446 -272.369026)
		(width 0.14478)
		(layer "In2.Cu")
		(net "M_C_CPU1_SB_CB<5>")
	)
	(segment
		(start 46.213268 -273.706844)
		(end 46.509686 -273.410426)
		(width 0.14478)
		(layer "In2.Cu")
		(net "M_C_CPU1_SB_CB<5>")
	)
	(segment
		(start 55.751984 -272.560288)
		(end 56.134508 -272.177764)
		(width 0.14478)
		(layer "In2.Cu")
		(net "M_C_CPU1_SB_CB<5>")
	)
	(segment
		(start 53.014626 -272.551144)
		(end 53.164486 -272.401284)
		(width 0.14478)
		(layer "In2.Cu")
		(net "M_C_CPU1_SB_CB<5>")
	)
	(segment
		(start 88.394032 -270.35887)
		(end 88.402414 -270.363696)
		(width 0.0889)
		(layer "In2.Cu")
		(net "M_C_CPU1_SB_CB<5>")
	)
	(arc
		(start 91.21394 -270.35887)
		(mid 91.396191 -270.40922)
		(end 91.5797 -270.363696)
		(width 0.0889)
		(layer "In2.Cu")
		(net "M_C_CPU1_SB_CB<5>")
	)
	(arc
		(start 80.308196 -270.35887)
		(mid 80.591152 -270.282693)
		(end 80.874108 -270.35887)
		(width 0.0889)
		(layer "In2.Cu")
		(net "M_C_CPU1_SB_CB<5>")
	)
	(arc
		(start 86.888066 -270.35887)
		(mid 87.171022 -270.282693)
		(end 87.453978 -270.35887)
		(width 0.0889)
		(layer "In2.Cu")
		(net "M_C_CPU1_SB_CB<5>")
	)
	(arc
		(start 83.702398 -270.363696)
		(mid 83.885906 -270.40919)
		(end 84.068158 -270.35887)
		(width 0.0889)
		(layer "In2.Cu")
		(net "M_C_CPU1_SB_CB<5>")
	)
	(arc
		(start 81.813908 -270.35887)
		(mid 81.996159 -270.40922)
		(end 82.179668 -270.363696)
		(width 0.0889)
		(layer "In2.Cu")
		(net "M_C_CPU1_SB_CB<5>")
	)
	(arc
		(start 93.10243 -270.363696)
		(mid 93.285938 -270.40919)
		(end 93.46819 -270.35887)
		(width 0.0889)
		(layer "In2.Cu")
		(net "M_C_CPU1_SB_CB<5>")
	)
	(arc
		(start 85.007958 -270.35887)
		(mid 85.290914 -270.282693)
		(end 85.57387 -270.35887)
		(width 0.0889)
		(layer "In2.Cu")
		(net "M_C_CPU1_SB_CB<5>")
	)
	(arc
		(start 84.068158 -270.35887)
		(mid 84.351114 -270.282693)
		(end 84.63407 -270.35887)
		(width 0.0889)
		(layer "In2.Cu")
		(net "M_C_CPU1_SB_CB<5>")
	)
	(arc
		(start 84.63407 -270.35887)
		(mid 84.821014 -270.409125)
		(end 85.007958 -270.35887)
		(width 0.0889)
		(layer "In2.Cu")
		(net "M_C_CPU1_SB_CB<5>")
	)
	(arc
		(start 92.528136 -270.35887)
		(mid 92.811092 -270.282693)
		(end 93.094048 -270.35887)
		(width 0.0889)
		(layer "In2.Cu")
		(net "M_C_CPU1_SB_CB<5>")
	)
	(arc
		(start 89.334086 -270.35887)
		(mid 89.52103 -270.409125)
		(end 89.707974 -270.35887)
		(width 0.0889)
		(layer "In2.Cu")
		(net "M_C_CPU1_SB_CB<5>")
	)
	(arc
		(start 90.648028 -270.35887)
		(mid 90.930984 -270.282693)
		(end 91.21394 -270.35887)
		(width 0.0889)
		(layer "In2.Cu")
		(net "M_C_CPU1_SB_CB<5>")
	)
	(arc
		(start 88.768174 -270.35887)
		(mid 89.05113 -270.282693)
		(end 89.334086 -270.35887)
		(width 0.0889)
		(layer "In2.Cu")
		(net "M_C_CPU1_SB_CB<5>")
	)
	(arc
		(start 85.948012 -270.35887)
		(mid 86.230968 -270.282693)
		(end 86.513924 -270.35887)
		(width 0.0889)
		(layer "In2.Cu")
		(net "M_C_CPU1_SB_CB<5>")
	)
	(arc
		(start 83.128104 -270.35887)
		(mid 83.41106 -270.282693)
		(end 83.694016 -270.35887)
		(width 0.0889)
		(layer "In2.Cu")
		(net "M_C_CPU1_SB_CB<5>")
	)
	(arc
		(start 88.402414 -270.363696)
		(mid 88.585922 -270.40919)
		(end 88.768174 -270.35887)
		(width 0.0889)
		(layer "In2.Cu")
		(net "M_C_CPU1_SB_CB<5>")
	)
	(arc
		(start 86.513924 -270.35887)
		(mid 86.696175 -270.40922)
		(end 86.879684 -270.363696)
		(width 0.0889)
		(layer "In2.Cu")
		(net "M_C_CPU1_SB_CB<5>")
	)
	(arc
		(start 87.46236 -270.363696)
		(mid 87.645868 -270.40919)
		(end 87.82812 -270.35887)
		(width 0.0889)
		(layer "In2.Cu")
		(net "M_C_CPU1_SB_CB<5>")
	)
	(arc
		(start 80.874108 -270.35887)
		(mid 81.061052 -270.409125)
		(end 81.247996 -270.35887)
		(width 0.0889)
		(layer "In2.Cu")
		(net "M_C_CPU1_SB_CB<5>")
	)
	(arc
		(start 82.18805 -270.35887)
		(mid 82.471006 -270.282693)
		(end 82.753962 -270.35887)
		(width 0.0889)
		(layer "In2.Cu")
		(net "M_C_CPU1_SB_CB<5>")
	)
	(arc
		(start 94.973902 -270.35887)
		(mid 95.156153 -270.40922)
		(end 95.339662 -270.363696)
		(width 0.0889)
		(layer "In2.Cu")
		(net "M_C_CPU1_SB_CB<5>")
	)
	(arc
		(start 94.40799 -270.35887)
		(mid 94.690946 -270.282693)
		(end 94.973902 -270.35887)
		(width 0.0889)
		(layer "In2.Cu")
		(net "M_C_CPU1_SB_CB<5>")
	)
	(arc
		(start 94.034102 -270.35887)
		(mid 94.221046 -270.409125)
		(end 94.40799 -270.35887)
		(width 0.0889)
		(layer "In2.Cu")
		(net "M_C_CPU1_SB_CB<5>")
	)
	(arc
		(start 89.707974 -270.35887)
		(mid 89.99093 -270.282693)
		(end 90.273886 -270.35887)
		(width 0.0889)
		(layer "In2.Cu")
		(net "M_C_CPU1_SB_CB<5>")
	)
	(arc
		(start 82.762344 -270.363696)
		(mid 82.945852 -270.40919)
		(end 83.128104 -270.35887)
		(width 0.0889)
		(layer "In2.Cu")
		(net "M_C_CPU1_SB_CB<5>")
	)
	(arc
		(start 85.57387 -270.35887)
		(mid 85.756121 -270.40922)
		(end 85.93963 -270.363696)
		(width 0.0889)
		(layer "In2.Cu")
		(net "M_C_CPU1_SB_CB<5>")
	)
	(arc
		(start 93.46819 -270.35887)
		(mid 93.751146 -270.282693)
		(end 94.034102 -270.35887)
		(width 0.0889)
		(layer "In2.Cu")
		(net "M_C_CPU1_SB_CB<5>")
	)
	(arc
		(start 90.273886 -270.35887)
		(mid 90.456137 -270.40922)
		(end 90.639646 -270.363696)
		(width 0.0889)
		(layer "In2.Cu")
		(net "M_C_CPU1_SB_CB<5>")
	)
	(arc
		(start 95.348044 -270.35887)
		(mid 95.59564 -270.283692)
		(end 95.85071 -270.32712)
		(width 0.0889)
		(layer "In2.Cu")
		(net "M_C_CPU1_SB_CB<5>")
	)
	(arc
		(start 87.82812 -270.35887)
		(mid 88.111076 -270.282693)
		(end 88.394032 -270.35887)
		(width 0.0889)
		(layer "In2.Cu")
		(net "M_C_CPU1_SB_CB<5>")
	)
	(arc
		(start 81.247996 -270.35887)
		(mid 81.530952 -270.282693)
		(end 81.813908 -270.35887)
		(width 0.0889)
		(layer "In2.Cu")
		(net "M_C_CPU1_SB_CB<5>")
	)
	(arc
		(start 91.588082 -270.35887)
		(mid 91.871038 -270.282693)
		(end 92.153994 -270.35887)
		(width 0.0889)
		(layer "In2.Cu")
		(net "M_C_CPU1_SB_CB<5>")
	)
	(arc
		(start 92.162376 -270.363696)
		(mid 92.345884 -270.40919)
		(end 92.528136 -270.35887)
		(width 0.0889)
		(layer "In2.Cu")
		(net "M_C_CPU1_SB_CB<5>")
	)
	(arc
		(start 79.933546 -270.35887)
		(mid 80.116051 -270.409347)
		(end 80.299814 -270.363696)
		(width 0.0889)
		(layer "In2.Cu")
		(net "M_C_CPU1_SB_CB<5>")
	)
	(arc
		(start 79.66837 -270.285972)
		(mid 79.803327 -270.303906)
		(end 79.928974 -270.35633)
		(width 0.0889)
		(layer "In2.Cu")
		(net "M_C_CPU1_SB_CB<5>")
	)
	(segment
		(start 95.157798 -268.960346)
		(end 94.690946 -269.226284)
		(width 0.10668)
		(layer "F.Cu")
		(net "M_C_CPU1_SB_CB<4>")
	)
	(segment
		(start 94.537022 -269.491714)
		(end 94.690946 -269.226284)
		(width 0.0889)
		(layer "In2.Cu")
		(net "M_C_CPU1_SB_CB<4>")
	)
	(segment
		(start 77.230986 -267.596874)
		(end 77.62113 -267.987018)
		(width 0.0889)
		(layer "In2.Cu")
		(net "M_C_CPU1_SB_CB<4>")
	)
	(segment
		(start 58.204608 -271.237964)
		(end 58.582306 -270.860266)
		(width 0.14478)
		(layer "In2.Cu")
		(net "M_C_CPU1_SB_CB<4>")
	)
	(segment
		(start 62.975744 -268.25321)
		(end 63.15202 -268.076934)
		(width 0.14478)
		(layer "In2.Cu")
		(net "M_C_CPU1_SB_CB<4>")
	)
	(segment
		(start 49.464214 -270.755872)
		(end 49.657762 -270.94942)
		(width 0.14478)
		(layer "In2.Cu")
		(net "M_C_CPU1_SB_CB<4>")
	)
	(segment
		(start 64.059816 -267.596874)
		(end 75.969876 -267.596874)
		(width 0.14478)
		(layer "In2.Cu")
		(net "M_C_CPU1_SB_CB<4>")
	)
	(segment
		(start 90.74404 -269.548864)
		(end 90.752422 -269.55369)
		(width 0.0889)
		(layer "In2.Cu")
		(net "M_C_CPU1_SB_CB<4>")
	)
	(segment
		(start 77.62113 -268.696948)
		(end 78.401418 -269.477236)
		(width 0.0889)
		(layer "In2.Cu")
		(net "M_C_CPU1_SB_CB<4>")
	)
	(segment
		(start 54.167786 -271.237964)
		(end 54.545484 -270.860266)
		(width 0.14478)
		(layer "In2.Cu")
		(net "M_C_CPU1_SB_CB<4>")
	)
	(segment
		(start 94.44101 -269.517114)
		(end 94.537022 -269.491714)
		(width 0.0889)
		(layer "In2.Cu")
		(net "M_C_CPU1_SB_CB<4>")
	)
	(segment
		(start 44.76496 -271.710404)
		(end 45.244766 -271.710404)
		(width 0.14478)
		(layer "In2.Cu")
		(net "M_C_CPU1_SB_CB<4>")
	)
	(segment
		(start 86.044024 -269.548864)
		(end 86.052406 -269.55369)
		(width 0.0889)
		(layer "In2.Cu")
		(net "M_C_CPU1_SB_CB<4>")
	)
	(segment
		(start 50.040794 -272.06194)
		(end 51.242468 -270.860266)
		(width 0.14478)
		(layer "In2.Cu")
		(net "M_C_CPU1_SB_CB<4>")
	)
	(segment
		(start 45.905166 -270.723614)
		(end 46.098714 -270.917162)
		(width 0.14478)
		(layer "In2.Cu")
		(net "M_C_CPU1_SB_CB<4>")
	)
	(segment
		(start 44.340018 -272.135346)
		(end 44.76496 -271.710404)
		(width 0.14478)
		(layer "In2.Cu")
		(net "M_C_CPU1_SB_CB<4>")
	)
	(segment
		(start 57.261506 -270.860266)
		(end 57.544208 -270.860266)
		(width 0.14478)
		(layer "In2.Cu")
		(net "M_C_CPU1_SB_CB<4>")
	)
	(segment
		(start 83.589622 -269.55369)
		(end 83.598004 -269.548864)
		(width 0.0889)
		(layer "In2.Cu")
		(net "M_C_CPU1_SB_CB<4>")
	)
	(segment
		(start 62.975744 -268.680946)
		(end 62.975744 -268.25321)
		(width 0.14478)
		(layer "In2.Cu")
		(net "M_C_CPU1_SB_CB<4>")
	)
	(segment
		(start 79.465424 -269.54861)
		(end 79.487268 -269.561056)
		(width 0.0889)
		(layer "In2.Cu")
		(net "M_C_CPU1_SB_CB<4>")
	)
	(segment
		(start 53.507386 -270.860266)
		(end 53.885084 -271.237964)
		(width 0.14478)
		(layer "In2.Cu")
		(net "M_C_CPU1_SB_CB<4>")
	)
	(segment
		(start 53.885084 -271.237964)
		(end 54.167786 -271.237964)
		(width 0.14478)
		(layer "In2.Cu")
		(net "M_C_CPU1_SB_CB<4>")
	)
	(segment
		(start 79.428848 -269.527528)
		(end 79.465424 -269.54861)
		(width 0.0889)
		(layer "In2.Cu")
		(net "M_C_CPU1_SB_CB<4>")
	)
	(segment
		(start 46.098714 -271.914112)
		(end 46.29023 -272.105628)
		(width 0.14478)
		(layer "In2.Cu")
		(net "M_C_CPU1_SB_CB<4>")
	)
	(segment
		(start 48.805846 -272.105628)
		(end 48.997362 -271.914112)
		(width 0.14478)
		(layer "In2.Cu")
		(net "M_C_CPU1_SB_CB<4>")
	)
	(segment
		(start 62.799468 -268.857222)
		(end 62.975744 -268.680946)
		(width 0.14478)
		(layer "In2.Cu")
		(net "M_C_CPU1_SB_CB<4>")
	)
	(segment
		(start 56.601106 -271.237964)
		(end 56.883808 -271.237964)
		(width 0.14478)
		(layer "In2.Cu")
		(net "M_C_CPU1_SB_CB<4>")
	)
	(segment
		(start 48.997362 -270.94942)
		(end 49.19091 -270.755872)
		(width 0.14478)
		(layer "In2.Cu")
		(net "M_C_CPU1_SB_CB<4>")
	)
	(segment
		(start 46.29023 -272.105628)
		(end 46.563534 -272.105628)
		(width 0.14478)
		(layer "In2.Cu")
		(net "M_C_CPU1_SB_CB<4>")
	)
	(segment
		(start 48.137318 -271.710404)
		(end 48.532542 -272.105628)
		(width 0.14478)
		(layer "In2.Cu")
		(net "M_C_CPU1_SB_CB<4>")
	)
	(segment
		(start 49.657762 -270.94942)
		(end 49.657762 -271.900904)
		(width 0.14478)
		(layer "In2.Cu")
		(net "M_C_CPU1_SB_CB<4>")
	)
	(segment
		(start 77.62113 -267.987018)
		(end 77.62113 -268.696948)
		(width 0.0889)
		(layer "In2.Cu")
		(net "M_C_CPU1_SB_CB<4>")
	)
	(segment
		(start 49.19091 -270.755872)
		(end 49.464214 -270.755872)
		(width 0.14478)
		(layer "In2.Cu")
		(net "M_C_CPU1_SB_CB<4>")
	)
	(segment
		(start 48.532542 -272.105628)
		(end 48.805846 -272.105628)
		(width 0.14478)
		(layer "In2.Cu")
		(net "M_C_CPU1_SB_CB<4>")
	)
	(segment
		(start 56.883808 -271.237964)
		(end 57.261506 -270.860266)
		(width 0.14478)
		(layer "In2.Cu")
		(net "M_C_CPU1_SB_CB<4>")
	)
	(segment
		(start 61.415168 -270.241522)
		(end 61.415168 -269.813786)
		(width 0.14478)
		(layer "In2.Cu")
		(net "M_C_CPU1_SB_CB<4>")
	)
	(segment
		(start 84.529676 -269.55369)
		(end 84.538058 -269.548864)
		(width 0.0889)
		(layer "In2.Cu")
		(net "M_C_CPU1_SB_CB<4>")
	)
	(segment
		(start 45.438314 -271.516856)
		(end 45.438314 -270.917162)
		(width 0.14478)
		(layer "In2.Cu")
		(net "M_C_CPU1_SB_CB<4>")
	)
	(segment
		(start 52.846986 -271.237964)
		(end 53.224684 -270.860266)
		(width 0.14478)
		(layer "In2.Cu")
		(net "M_C_CPU1_SB_CB<4>")
	)
	(segment
		(start 60.796424 -270.860266)
		(end 61.415168 -270.241522)
		(width 0.14478)
		(layer "In2.Cu")
		(net "M_C_CPU1_SB_CB<4>")
	)
	(segment
		(start 63.15202 -268.076934)
		(end 63.579756 -268.076934)
		(width 0.14478)
		(layer "In2.Cu")
		(net "M_C_CPU1_SB_CB<4>")
	)
	(segment
		(start 49.657762 -271.900904)
		(end 49.818798 -272.06194)
		(width 0.14478)
		(layer "In2.Cu")
		(net "M_C_CPU1_SB_CB<4>")
	)
	(segment
		(start 46.958758 -271.710404)
		(end 48.137318 -271.710404)
		(width 0.14478)
		(layer "In2.Cu")
		(net "M_C_CPU1_SB_CB<4>")
	)
	(segment
		(start 45.244766 -271.710404)
		(end 45.438314 -271.516856)
		(width 0.14478)
		(layer "In2.Cu")
		(net "M_C_CPU1_SB_CB<4>")
	)
	(segment
		(start 62.195456 -269.033498)
		(end 62.371732 -268.857222)
		(width 0.14478)
		(layer "In2.Cu")
		(net "M_C_CPU1_SB_CB<4>")
	)
	(segment
		(start 89.803986 -269.548864)
		(end 89.812368 -269.55369)
		(width 0.0889)
		(layer "In2.Cu")
		(net "M_C_CPU1_SB_CB<4>")
	)
	(segment
		(start 63.579756 -268.076934)
		(end 64.059816 -267.596874)
		(width 0.14478)
		(layer "In2.Cu")
		(net "M_C_CPU1_SB_CB<4>")
	)
	(segment
		(start 80.769714 -269.55369)
		(end 80.778096 -269.548864)
		(width 0.0889)
		(layer "In2.Cu")
		(net "M_C_CPU1_SB_CB<4>")
	)
	(segment
		(start 52.186586 -270.860266)
		(end 52.564284 -271.237964)
		(width 0.14478)
		(layer "In2.Cu")
		(net "M_C_CPU1_SB_CB<4>")
	)
	(segment
		(start 56.223408 -270.860266)
		(end 56.601106 -271.237964)
		(width 0.14478)
		(layer "In2.Cu")
		(net "M_C_CPU1_SB_CB<4>")
	)
	(segment
		(start 61.415168 -269.813786)
		(end 61.591444 -269.63751)
		(width 0.14478)
		(layer "In2.Cu")
		(net "M_C_CPU1_SB_CB<4>")
	)
	(segment
		(start 62.01918 -269.63751)
		(end 62.195456 -269.461234)
		(width 0.14478)
		(layer "In2.Cu")
		(net "M_C_CPU1_SB_CB<4>")
	)
	(segment
		(start 53.224684 -270.860266)
		(end 53.507386 -270.860266)
		(width 0.14478)
		(layer "In2.Cu")
		(net "M_C_CPU1_SB_CB<4>")
	)
	(segment
		(start 58.582306 -270.860266)
		(end 60.796424 -270.860266)
		(width 0.14478)
		(layer "In2.Cu")
		(net "M_C_CPU1_SB_CB<4>")
	)
	(segment
		(start 45.438314 -270.917162)
		(end 45.631862 -270.723614)
		(width 0.14478)
		(layer "In2.Cu")
		(net "M_C_CPU1_SB_CB<4>")
	)
	(segment
		(start 51.242468 -270.860266)
		(end 52.186586 -270.860266)
		(width 0.14478)
		(layer "In2.Cu")
		(net "M_C_CPU1_SB_CB<4>")
	)
	(segment
		(start 46.563534 -272.105628)
		(end 46.958758 -271.710404)
		(width 0.14478)
		(layer "In2.Cu")
		(net "M_C_CPU1_SB_CB<4>")
	)
	(segment
		(start 93.929708 -269.55369)
		(end 93.93809 -269.548864)
		(width 0.0889)
		(layer "In2.Cu")
		(net "M_C_CPU1_SB_CB<4>")
	)
	(segment
		(start 45.631862 -270.723614)
		(end 45.905166 -270.723614)
		(width 0.14478)
		(layer "In2.Cu")
		(net "M_C_CPU1_SB_CB<4>")
	)
	(segment
		(start 48.997362 -271.914112)
		(end 48.997362 -270.94942)
		(width 0.14478)
		(layer "In2.Cu")
		(net "M_C_CPU1_SB_CB<4>")
	)
	(segment
		(start 57.921906 -271.237964)
		(end 58.204608 -271.237964)
		(width 0.14478)
		(layer "In2.Cu")
		(net "M_C_CPU1_SB_CB<4>")
	)
	(segment
		(start 46.098714 -270.917162)
		(end 46.098714 -271.914112)
		(width 0.14478)
		(layer "In2.Cu")
		(net "M_C_CPU1_SB_CB<4>")
	)
	(segment
		(start 92.989654 -269.55369)
		(end 92.998036 -269.548864)
		(width 0.0889)
		(layer "In2.Cu")
		(net "M_C_CPU1_SB_CB<4>")
	)
	(segment
		(start 81.344008 -269.548864)
		(end 81.35239 -269.55369)
		(width 0.0889)
		(layer "In2.Cu")
		(net "M_C_CPU1_SB_CB<4>")
	)
	(segment
		(start 85.10397 -269.548864)
		(end 85.112352 -269.55369)
		(width 0.0889)
		(layer "In2.Cu")
		(net "M_C_CPU1_SB_CB<4>")
	)
	(segment
		(start 52.564284 -271.237964)
		(end 52.846986 -271.237964)
		(width 0.14478)
		(layer "In2.Cu")
		(net "M_C_CPU1_SB_CB<4>")
	)
	(segment
		(start 61.591444 -269.63751)
		(end 62.01918 -269.63751)
		(width 0.14478)
		(layer "In2.Cu")
		(net "M_C_CPU1_SB_CB<4>")
	)
	(segment
		(start 78.401418 -269.477236)
		(end 78.555342 -269.565882)
		(width 0.0889)
		(layer "In2.Cu")
		(net "M_C_CPU1_SB_CB<4>")
	)
	(segment
		(start 57.544208 -270.860266)
		(end 57.921906 -271.237964)
		(width 0.14478)
		(layer "In2.Cu")
		(net "M_C_CPU1_SB_CB<4>")
	)
	(segment
		(start 89.229692 -269.55369)
		(end 89.238074 -269.548864)
		(width 0.0889)
		(layer "In2.Cu")
		(net "M_C_CPU1_SB_CB<4>")
	)
	(segment
		(start 62.195456 -269.461234)
		(end 62.195456 -269.033498)
		(width 0.14478)
		(layer "In2.Cu")
		(net "M_C_CPU1_SB_CB<4>")
	)
	(segment
		(start 54.545484 -270.860266)
		(end 56.223408 -270.860266)
		(width 0.14478)
		(layer "In2.Cu")
		(net "M_C_CPU1_SB_CB<4>")
	)
	(segment
		(start 75.969876 -267.596874)
		(end 77.230986 -267.596874)
		(width 0.0889)
		(layer "In2.Cu")
		(net "M_C_CPU1_SB_CB<4>")
	)
	(segment
		(start 88.289638 -269.55369)
		(end 88.29802 -269.548864)
		(width 0.0889)
		(layer "In2.Cu")
		(net "M_C_CPU1_SB_CB<4>")
	)
	(segment
		(start 62.371732 -268.857222)
		(end 62.799468 -268.857222)
		(width 0.14478)
		(layer "In2.Cu")
		(net "M_C_CPU1_SB_CB<4>")
	)
	(segment
		(start 49.818798 -272.06194)
		(end 50.040794 -272.06194)
		(width 0.14478)
		(layer "In2.Cu")
		(net "M_C_CPU1_SB_CB<4>")
	)
	(arc
		(start 83.598004 -269.548864)
		(mid 83.88096 -269.472687)
		(end 84.163916 -269.548864)
		(width 0.0889)
		(layer "In2.Cu")
		(net "M_C_CPU1_SB_CB<4>")
	)
	(arc
		(start 85.112352 -269.55369)
		(mid 85.29586 -269.599184)
		(end 85.478112 -269.548864)
		(width 0.0889)
		(layer "In2.Cu")
		(net "M_C_CPU1_SB_CB<4>")
	)
	(arc
		(start 91.684094 -269.548864)
		(mid 91.871038 -269.599119)
		(end 92.057982 -269.548864)
		(width 0.0889)
		(layer "In2.Cu")
		(net "M_C_CPU1_SB_CB<4>")
	)
	(arc
		(start 79.487268 -269.561056)
		(mid 79.664196 -269.598884)
		(end 79.838042 -269.548864)
		(width 0.0889)
		(layer "In2.Cu")
		(net "M_C_CPU1_SB_CB<4>")
	)
	(arc
		(start 78.899512 -269.548864)
		(mid 79.161521 -269.47225)
		(end 79.428848 -269.527528)
		(width 0.0889)
		(layer "In2.Cu")
		(net "M_C_CPU1_SB_CB<4>")
	)
	(arc
		(start 93.563948 -269.548864)
		(mid 93.746199 -269.599214)
		(end 93.929708 -269.55369)
		(width 0.0889)
		(layer "In2.Cu")
		(net "M_C_CPU1_SB_CB<4>")
	)
	(arc
		(start 79.838042 -269.548864)
		(mid 80.120998 -269.472687)
		(end 80.403954 -269.548864)
		(width 0.0889)
		(layer "In2.Cu")
		(net "M_C_CPU1_SB_CB<4>")
	)
	(arc
		(start 88.863932 -269.548864)
		(mid 89.046183 -269.599214)
		(end 89.229692 -269.55369)
		(width 0.0889)
		(layer "In2.Cu")
		(net "M_C_CPU1_SB_CB<4>")
	)
	(arc
		(start 81.35239 -269.55369)
		(mid 81.535898 -269.599184)
		(end 81.71815 -269.548864)
		(width 0.0889)
		(layer "In2.Cu")
		(net "M_C_CPU1_SB_CB<4>")
	)
	(arc
		(start 87.923878 -269.548864)
		(mid 88.106129 -269.599214)
		(end 88.289638 -269.55369)
		(width 0.0889)
		(layer "In2.Cu")
		(net "M_C_CPU1_SB_CB<4>")
	)
	(arc
		(start 90.752422 -269.55369)
		(mid 90.93593 -269.599184)
		(end 91.118182 -269.548864)
		(width 0.0889)
		(layer "In2.Cu")
		(net "M_C_CPU1_SB_CB<4>")
	)
	(arc
		(start 86.418166 -269.548864)
		(mid 86.701122 -269.472687)
		(end 86.984078 -269.548864)
		(width 0.0889)
		(layer "In2.Cu")
		(net "M_C_CPU1_SB_CB<4>")
	)
	(arc
		(start 84.163916 -269.548864)
		(mid 84.346167 -269.599214)
		(end 84.529676 -269.55369)
		(width 0.0889)
		(layer "In2.Cu")
		(net "M_C_CPU1_SB_CB<4>")
	)
	(arc
		(start 92.057982 -269.548864)
		(mid 92.340938 -269.472687)
		(end 92.623894 -269.548864)
		(width 0.0889)
		(layer "In2.Cu")
		(net "M_C_CPU1_SB_CB<4>")
	)
	(arc
		(start 80.778096 -269.548864)
		(mid 81.061052 -269.472687)
		(end 81.344008 -269.548864)
		(width 0.0889)
		(layer "In2.Cu")
		(net "M_C_CPU1_SB_CB<4>")
	)
	(arc
		(start 84.538058 -269.548864)
		(mid 84.821014 -269.472687)
		(end 85.10397 -269.548864)
		(width 0.0889)
		(layer "In2.Cu")
		(net "M_C_CPU1_SB_CB<4>")
	)
	(arc
		(start 86.984078 -269.548864)
		(mid 87.171022 -269.599119)
		(end 87.357966 -269.548864)
		(width 0.0889)
		(layer "In2.Cu")
		(net "M_C_CPU1_SB_CB<4>")
	)
	(arc
		(start 82.284062 -269.548864)
		(mid 82.471006 -269.599119)
		(end 82.65795 -269.548864)
		(width 0.0889)
		(layer "In2.Cu")
		(net "M_C_CPU1_SB_CB<4>")
	)
	(arc
		(start 78.555342 -269.565882)
		(mid 78.729505 -269.599418)
		(end 78.899512 -269.548864)
		(width 0.0889)
		(layer "In2.Cu")
		(net "M_C_CPU1_SB_CB<4>")
	)
	(arc
		(start 91.118182 -269.548864)
		(mid 91.401138 -269.472687)
		(end 91.684094 -269.548864)
		(width 0.0889)
		(layer "In2.Cu")
		(net "M_C_CPU1_SB_CB<4>")
	)
	(arc
		(start 82.65795 -269.548864)
		(mid 82.940906 -269.472687)
		(end 83.223862 -269.548864)
		(width 0.0889)
		(layer "In2.Cu")
		(net "M_C_CPU1_SB_CB<4>")
	)
	(arc
		(start 90.178128 -269.548864)
		(mid 90.461084 -269.472687)
		(end 90.74404 -269.548864)
		(width 0.0889)
		(layer "In2.Cu")
		(net "M_C_CPU1_SB_CB<4>")
	)
	(arc
		(start 85.478112 -269.548864)
		(mid 85.761068 -269.472687)
		(end 86.044024 -269.548864)
		(width 0.0889)
		(layer "In2.Cu")
		(net "M_C_CPU1_SB_CB<4>")
	)
	(arc
		(start 89.812368 -269.55369)
		(mid 89.995876 -269.599184)
		(end 90.178128 -269.548864)
		(width 0.0889)
		(layer "In2.Cu")
		(net "M_C_CPU1_SB_CB<4>")
	)
	(arc
		(start 87.357966 -269.548864)
		(mid 87.640922 -269.472687)
		(end 87.923878 -269.548864)
		(width 0.0889)
		(layer "In2.Cu")
		(net "M_C_CPU1_SB_CB<4>")
	)
	(arc
		(start 89.238074 -269.548864)
		(mid 89.52103 -269.472687)
		(end 89.803986 -269.548864)
		(width 0.0889)
		(layer "In2.Cu")
		(net "M_C_CPU1_SB_CB<4>")
	)
	(arc
		(start 93.93809 -269.548864)
		(mid 94.185803 -269.473644)
		(end 94.44101 -269.517114)
		(width 0.0889)
		(layer "In2.Cu")
		(net "M_C_CPU1_SB_CB<4>")
	)
	(arc
		(start 92.623894 -269.548864)
		(mid 92.806145 -269.599214)
		(end 92.989654 -269.55369)
		(width 0.0889)
		(layer "In2.Cu")
		(net "M_C_CPU1_SB_CB<4>")
	)
	(arc
		(start 92.998036 -269.548864)
		(mid 93.280992 -269.472687)
		(end 93.563948 -269.548864)
		(width 0.0889)
		(layer "In2.Cu")
		(net "M_C_CPU1_SB_CB<4>")
	)
	(arc
		(start 83.223862 -269.548864)
		(mid 83.406113 -269.599214)
		(end 83.589622 -269.55369)
		(width 0.0889)
		(layer "In2.Cu")
		(net "M_C_CPU1_SB_CB<4>")
	)
	(arc
		(start 88.29802 -269.548864)
		(mid 88.580976 -269.472687)
		(end 88.863932 -269.548864)
		(width 0.0889)
		(layer "In2.Cu")
		(net "M_C_CPU1_SB_CB<4>")
	)
	(arc
		(start 86.052406 -269.55369)
		(mid 86.235914 -269.599184)
		(end 86.418166 -269.548864)
		(width 0.0889)
		(layer "In2.Cu")
		(net "M_C_CPU1_SB_CB<4>")
	)
	(arc
		(start 81.71815 -269.548864)
		(mid 82.001106 -269.472687)
		(end 82.284062 -269.548864)
		(width 0.0889)
		(layer "In2.Cu")
		(net "M_C_CPU1_SB_CB<4>")
	)
	(arc
		(start 80.403954 -269.548864)
		(mid 80.586205 -269.599214)
		(end 80.769714 -269.55369)
		(width 0.0889)
		(layer "In2.Cu")
		(net "M_C_CPU1_SB_CB<4>")
	)
	(segment
		(start 96.097852 -273.820382)
		(end 95.631 -274.08632)
		(width 0.10668)
		(layer "F.Cu")
		(net "M_C_CPU1_SB_CB<3>")
	)
	(segment
		(start 85.10397 -273.76374)
		(end 85.112352 -273.758914)
		(width 0.0889)
		(layer "In2.Cu")
		(net "M_C_CPU1_SB_CB<3>")
	)
	(segment
		(start 50.333656 -280.21026)
		(end 52.926996 -280.21026)
		(width 0.14478)
		(layer "In2.Cu")
		(net "M_C_CPU1_SB_CB<3>")
	)
	(segment
		(start 68.591176 -272.664174)
		(end 75.985116 -272.664174)
		(width 0.14478)
		(layer "In2.Cu")
		(net "M_C_CPU1_SB_CB<3>")
	)
	(segment
		(start 92.989654 -273.758914)
		(end 92.998036 -273.76374)
		(width 0.0889)
		(layer "In2.Cu")
		(net "M_C_CPU1_SB_CB<3>")
	)
	(segment
		(start 88.289638 -273.758914)
		(end 88.29802 -273.76374)
		(width 0.0889)
		(layer "In2.Cu")
		(net "M_C_CPU1_SB_CB<3>")
	)
	(segment
		(start 93.929708 -273.758914)
		(end 93.93809 -273.76374)
		(width 0.0889)
		(layer "In2.Cu")
		(net "M_C_CPU1_SB_CB<3>")
	)
	(segment
		(start 84.529676 -273.758914)
		(end 84.538058 -273.76374)
		(width 0.0889)
		(layer "In2.Cu")
		(net "M_C_CPU1_SB_CB<3>")
	)
	(segment
		(start 61.04509 -280.21026)
		(end 68.591176 -272.664174)
		(width 0.14478)
		(layer "In2.Cu")
		(net "M_C_CPU1_SB_CB<3>")
	)
	(segment
		(start 89.229692 -273.758914)
		(end 89.238074 -273.76374)
		(width 0.0889)
		(layer "In2.Cu")
		(net "M_C_CPU1_SB_CB<3>")
	)
	(segment
		(start 79.438246 -273.781012)
		(end 79.46771 -273.76374)
		(width 0.0889)
		(layer "In2.Cu")
		(net "M_C_CPU1_SB_CB<3>")
	)
	(segment
		(start 95.762826 -273.737578)
		(end 95.785178 -273.82089)
		(width 0.0889)
		(layer "In2.Cu")
		(net "M_C_CPU1_SB_CB<3>")
	)
	(segment
		(start 40.23995 -280.635202)
		(end 40.665146 -281.060398)
		(width 0.14478)
		(layer "In2.Cu")
		(net "M_C_CPU1_SB_CB<3>")
	)
	(segment
		(start 78.358492 -273.719544)
		(end 78.736698 -273.719544)
		(width 0.0889)
		(layer "In2.Cu")
		(net "M_C_CPU1_SB_CB<3>")
	)
	(segment
		(start 90.74404 -273.76374)
		(end 90.752422 -273.758914)
		(width 0.0889)
		(layer "In2.Cu")
		(net "M_C_CPU1_SB_CB<3>")
	)
	(segment
		(start 83.589622 -273.758914)
		(end 83.598004 -273.76374)
		(width 0.0889)
		(layer "In2.Cu")
		(net "M_C_CPU1_SB_CB<3>")
	)
	(segment
		(start 75.985116 -272.664174)
		(end 76.235052 -272.664174)
		(width 0.0889)
		(layer "In2.Cu")
		(net "M_C_CPU1_SB_CB<3>")
	)
	(segment
		(start 57.776872 -280.21026)
		(end 61.04509 -280.21026)
		(width 0.14478)
		(layer "In2.Cu")
		(net "M_C_CPU1_SB_CB<3>")
	)
	(segment
		(start 80.769714 -273.758914)
		(end 80.778096 -273.76374)
		(width 0.0889)
		(layer "In2.Cu")
		(net "M_C_CPU1_SB_CB<3>")
	)
	(segment
		(start 79.816706 -273.750532)
		(end 79.840074 -273.763994)
		(width 0.0889)
		(layer "In2.Cu")
		(net "M_C_CPU1_SB_CB<3>")
	)
	(segment
		(start 95.785178 -273.82089)
		(end 95.631 -274.08632)
		(width 0.0889)
		(layer "In2.Cu")
		(net "M_C_CPU1_SB_CB<3>")
	)
	(segment
		(start 86.044024 -273.76374)
		(end 86.052406 -273.758914)
		(width 0.0889)
		(layer "In2.Cu")
		(net "M_C_CPU1_SB_CB<3>")
	)
	(segment
		(start 94.504002 -273.76374)
		(end 94.512384 -273.758914)
		(width 0.0889)
		(layer "In2.Cu")
		(net "M_C_CPU1_SB_CB<3>")
	)
	(segment
		(start 40.665146 -281.060398)
		(end 49.483518 -281.060398)
		(width 0.14478)
		(layer "In2.Cu")
		(net "M_C_CPU1_SB_CB<3>")
	)
	(segment
		(start 95.444056 -273.76374)
		(end 95.452438 -273.758914)
		(width 0.0889)
		(layer "In2.Cu")
		(net "M_C_CPU1_SB_CB<3>")
	)
	(segment
		(start 89.803986 -273.76374)
		(end 89.812368 -273.758914)
		(width 0.0889)
		(layer "In2.Cu")
		(net "M_C_CPU1_SB_CB<3>")
	)
	(segment
		(start 81.344008 -273.76374)
		(end 81.35239 -273.758914)
		(width 0.0889)
		(layer "In2.Cu")
		(net "M_C_CPU1_SB_CB<3>")
	)
	(segment
		(start 76.298044 -272.601182)
		(end 77.24013 -272.601182)
		(width 0.0889)
		(layer "In2.Cu")
		(net "M_C_CPU1_SB_CB<3>")
	)
	(segment
		(start 53.777134 -281.060398)
		(end 56.926734 -281.060398)
		(width 0.14478)
		(layer "In2.Cu")
		(net "M_C_CPU1_SB_CB<3>")
	)
	(segment
		(start 76.235052 -272.664174)
		(end 76.298044 -272.601182)
		(width 0.0889)
		(layer "In2.Cu")
		(net "M_C_CPU1_SB_CB<3>")
	)
	(segment
		(start 52.926996 -280.21026)
		(end 53.777134 -281.060398)
		(width 0.14478)
		(layer "In2.Cu")
		(net "M_C_CPU1_SB_CB<3>")
	)
	(segment
		(start 79.840074 -273.763994)
		(end 79.866236 -273.77898)
		(width 0.0889)
		(layer "In2.Cu")
		(net "M_C_CPU1_SB_CB<3>")
	)
	(segment
		(start 56.926734 -281.060398)
		(end 57.776872 -280.21026)
		(width 0.14478)
		(layer "In2.Cu")
		(net "M_C_CPU1_SB_CB<3>")
	)
	(segment
		(start 49.483518 -281.060398)
		(end 50.333656 -280.21026)
		(width 0.14478)
		(layer "In2.Cu")
		(net "M_C_CPU1_SB_CB<3>")
	)
	(segment
		(start 77.24013 -272.601182)
		(end 78.358492 -273.719544)
		(width 0.0889)
		(layer "In2.Cu")
		(net "M_C_CPU1_SB_CB<3>")
	)
	(arc
		(start 84.163916 -273.76374)
		(mid 84.346167 -273.71339)
		(end 84.529676 -273.758914)
		(width 0.0889)
		(layer "In2.Cu")
		(net "M_C_CPU1_SB_CB<3>")
	)
	(arc
		(start 81.35239 -273.758914)
		(mid 81.535898 -273.71342)
		(end 81.71815 -273.76374)
		(width 0.0889)
		(layer "In2.Cu")
		(net "M_C_CPU1_SB_CB<3>")
	)
	(arc
		(start 79.866236 -273.77898)
		(mid 80.137022 -273.839626)
		(end 80.403954 -273.76374)
		(width 0.0889)
		(layer "In2.Cu")
		(net "M_C_CPU1_SB_CB<3>")
	)
	(arc
		(start 86.418166 -273.76374)
		(mid 86.701122 -273.839917)
		(end 86.984078 -273.76374)
		(width 0.0889)
		(layer "In2.Cu")
		(net "M_C_CPU1_SB_CB<3>")
	)
	(arc
		(start 87.357966 -273.76374)
		(mid 87.640922 -273.839917)
		(end 87.923878 -273.76374)
		(width 0.0889)
		(layer "In2.Cu")
		(net "M_C_CPU1_SB_CB<3>")
	)
	(arc
		(start 92.998036 -273.76374)
		(mid 93.280992 -273.839917)
		(end 93.563948 -273.76374)
		(width 0.0889)
		(layer "In2.Cu")
		(net "M_C_CPU1_SB_CB<3>")
	)
	(arc
		(start 89.238074 -273.76374)
		(mid 89.52103 -273.839917)
		(end 89.803986 -273.76374)
		(width 0.0889)
		(layer "In2.Cu")
		(net "M_C_CPU1_SB_CB<3>")
	)
	(arc
		(start 88.29802 -273.76374)
		(mid 88.580976 -273.839917)
		(end 88.863932 -273.76374)
		(width 0.0889)
		(layer "In2.Cu")
		(net "M_C_CPU1_SB_CB<3>")
	)
	(arc
		(start 89.812368 -273.758914)
		(mid 89.995876 -273.71342)
		(end 90.178128 -273.76374)
		(width 0.0889)
		(layer "In2.Cu")
		(net "M_C_CPU1_SB_CB<3>")
	)
	(arc
		(start 90.178128 -273.76374)
		(mid 90.461084 -273.839917)
		(end 90.74404 -273.76374)
		(width 0.0889)
		(layer "In2.Cu")
		(net "M_C_CPU1_SB_CB<3>")
	)
	(arc
		(start 95.452438 -273.758914)
		(mid 95.605308 -273.714273)
		(end 95.762826 -273.737578)
		(width 0.0889)
		(layer "In2.Cu")
		(net "M_C_CPU1_SB_CB<3>")
	)
	(arc
		(start 79.46771 -273.76374)
		(mid 79.640565 -273.713751)
		(end 79.816706 -273.750532)
		(width 0.0889)
		(layer "In2.Cu")
		(net "M_C_CPU1_SB_CB<3>")
	)
	(arc
		(start 80.778096 -273.76374)
		(mid 81.061052 -273.839917)
		(end 81.344008 -273.76374)
		(width 0.0889)
		(layer "In2.Cu")
		(net "M_C_CPU1_SB_CB<3>")
	)
	(arc
		(start 91.118182 -273.76374)
		(mid 91.401138 -273.839917)
		(end 91.684094 -273.76374)
		(width 0.0889)
		(layer "In2.Cu")
		(net "M_C_CPU1_SB_CB<3>")
	)
	(arc
		(start 85.478112 -273.76374)
		(mid 85.761068 -273.839917)
		(end 86.044024 -273.76374)
		(width 0.0889)
		(layer "In2.Cu")
		(net "M_C_CPU1_SB_CB<3>")
	)
	(arc
		(start 78.899766 -273.76374)
		(mid 79.166823 -273.840775)
		(end 79.438246 -273.781012)
		(width 0.0889)
		(layer "In2.Cu")
		(net "M_C_CPU1_SB_CB<3>")
	)
	(arc
		(start 84.538058 -273.76374)
		(mid 84.821014 -273.839917)
		(end 85.10397 -273.76374)
		(width 0.0889)
		(layer "In2.Cu")
		(net "M_C_CPU1_SB_CB<3>")
	)
	(arc
		(start 90.752422 -273.758914)
		(mid 90.93593 -273.71342)
		(end 91.118182 -273.76374)
		(width 0.0889)
		(layer "In2.Cu")
		(net "M_C_CPU1_SB_CB<3>")
	)
	(arc
		(start 92.057982 -273.76374)
		(mid 92.340938 -273.839917)
		(end 92.623894 -273.76374)
		(width 0.0889)
		(layer "In2.Cu")
		(net "M_C_CPU1_SB_CB<3>")
	)
	(arc
		(start 94.512384 -273.758914)
		(mid 94.695892 -273.71342)
		(end 94.878144 -273.76374)
		(width 0.0889)
		(layer "In2.Cu")
		(net "M_C_CPU1_SB_CB<3>")
	)
	(arc
		(start 87.923878 -273.76374)
		(mid 88.106129 -273.71339)
		(end 88.289638 -273.758914)
		(width 0.0889)
		(layer "In2.Cu")
		(net "M_C_CPU1_SB_CB<3>")
	)
	(arc
		(start 91.684094 -273.76374)
		(mid 91.871038 -273.713485)
		(end 92.057982 -273.76374)
		(width 0.0889)
		(layer "In2.Cu")
		(net "M_C_CPU1_SB_CB<3>")
	)
	(arc
		(start 85.112352 -273.758914)
		(mid 85.29586 -273.71342)
		(end 85.478112 -273.76374)
		(width 0.0889)
		(layer "In2.Cu")
		(net "M_C_CPU1_SB_CB<3>")
	)
	(arc
		(start 81.71815 -273.76374)
		(mid 82.001106 -273.839917)
		(end 82.284062 -273.76374)
		(width 0.0889)
		(layer "In2.Cu")
		(net "M_C_CPU1_SB_CB<3>")
	)
	(arc
		(start 94.878144 -273.76374)
		(mid 95.1611 -273.839917)
		(end 95.444056 -273.76374)
		(width 0.0889)
		(layer "In2.Cu")
		(net "M_C_CPU1_SB_CB<3>")
	)
	(arc
		(start 82.284062 -273.76374)
		(mid 82.471006 -273.713485)
		(end 82.65795 -273.76374)
		(width 0.0889)
		(layer "In2.Cu")
		(net "M_C_CPU1_SB_CB<3>")
	)
	(arc
		(start 78.736698 -273.719544)
		(mid 78.821172 -273.730792)
		(end 78.899766 -273.76374)
		(width 0.0889)
		(layer "In2.Cu")
		(net "M_C_CPU1_SB_CB<3>")
	)
	(arc
		(start 80.403954 -273.76374)
		(mid 80.586205 -273.71339)
		(end 80.769714 -273.758914)
		(width 0.0889)
		(layer "In2.Cu")
		(net "M_C_CPU1_SB_CB<3>")
	)
	(arc
		(start 83.598004 -273.76374)
		(mid 83.88096 -273.839917)
		(end 84.163916 -273.76374)
		(width 0.0889)
		(layer "In2.Cu")
		(net "M_C_CPU1_SB_CB<3>")
	)
	(arc
		(start 93.563948 -273.76374)
		(mid 93.746199 -273.71339)
		(end 93.929708 -273.758914)
		(width 0.0889)
		(layer "In2.Cu")
		(net "M_C_CPU1_SB_CB<3>")
	)
	(arc
		(start 83.223862 -273.76374)
		(mid 83.406113 -273.71339)
		(end 83.589622 -273.758914)
		(width 0.0889)
		(layer "In2.Cu")
		(net "M_C_CPU1_SB_CB<3>")
	)
	(arc
		(start 86.052406 -273.758914)
		(mid 86.235914 -273.71342)
		(end 86.418166 -273.76374)
		(width 0.0889)
		(layer "In2.Cu")
		(net "M_C_CPU1_SB_CB<3>")
	)
	(arc
		(start 82.65795 -273.76374)
		(mid 82.940906 -273.839917)
		(end 83.223862 -273.76374)
		(width 0.0889)
		(layer "In2.Cu")
		(net "M_C_CPU1_SB_CB<3>")
	)
	(arc
		(start 88.863932 -273.76374)
		(mid 89.046183 -273.71339)
		(end 89.229692 -273.758914)
		(width 0.0889)
		(layer "In2.Cu")
		(net "M_C_CPU1_SB_CB<3>")
	)
	(arc
		(start 92.623894 -273.76374)
		(mid 92.806145 -273.71339)
		(end 92.989654 -273.758914)
		(width 0.0889)
		(layer "In2.Cu")
		(net "M_C_CPU1_SB_CB<3>")
	)
	(arc
		(start 86.984078 -273.76374)
		(mid 87.171022 -273.713485)
		(end 87.357966 -273.76374)
		(width 0.0889)
		(layer "In2.Cu")
		(net "M_C_CPU1_SB_CB<3>")
	)
	(arc
		(start 93.93809 -273.76374)
		(mid 94.221046 -273.839917)
		(end 94.504002 -273.76374)
		(width 0.0889)
		(layer "In2.Cu")
		(net "M_C_CPU1_SB_CB<3>")
	)
	(segment
		(start 94.687898 -273.010376)
		(end 94.221046 -273.276314)
		(width 0.10668)
		(layer "F.Cu")
		(net "M_C_CPU1_SB_CB<2>")
	)
	(segment
		(start 90.639646 -272.948908)
		(end 90.648028 -272.953734)
		(width 0.0889)
		(layer "In2.Cu")
		(net "M_C_CPU1_SB_CB<2>")
	)
	(segment
		(start 42.760646 -278.705564)
		(end 42.991278 -278.705564)
		(width 0.14478)
		(layer "In2.Cu")
		(net "M_C_CPU1_SB_CB<2>")
	)
	(segment
		(start 75.966066 -271.754854)
		(end 76.485496 -271.754854)
		(width 0.0889)
		(layer "In2.Cu")
		(net "M_C_CPU1_SB_CB<2>")
	)
	(segment
		(start 43.154092 -278.868378)
		(end 43.154092 -279.197562)
		(width 0.14478)
		(layer "In2.Cu")
		(net "M_C_CPU1_SB_CB<2>")
	)
	(segment
		(start 53.401722 -279.360376)
		(end 57.340246 -279.360376)
		(width 0.14478)
		(layer "In2.Cu")
		(net "M_C_CPU1_SB_CB<2>")
	)
	(segment
		(start 42.597832 -279.197562)
		(end 42.597832 -278.868378)
		(width 0.14478)
		(layer "In2.Cu")
		(net "M_C_CPU1_SB_CB<2>")
	)
	(segment
		(start 83.694016 -272.953734)
		(end 83.702398 -272.948908)
		(width 0.0889)
		(layer "In2.Cu")
		(net "M_C_CPU1_SB_CB<2>")
	)
	(segment
		(start 80.282034 -272.938494)
		(end 80.308196 -272.953734)
		(width 0.0889)
		(layer "In2.Cu")
		(net "M_C_CPU1_SB_CB<2>")
	)
	(segment
		(start 52.551584 -278.510238)
		(end 53.401722 -279.360376)
		(width 0.14478)
		(layer "In2.Cu")
		(net "M_C_CPU1_SB_CB<2>")
	)
	(segment
		(start 65.034668 -274.934426)
		(end 65.034668 -273.977354)
		(width 0.14478)
		(layer "In2.Cu")
		(net "M_C_CPU1_SB_CB<2>")
	)
	(segment
		(start 86.879684 -272.948908)
		(end 86.888066 -272.953734)
		(width 0.0889)
		(layer "In2.Cu")
		(net "M_C_CPU1_SB_CB<2>")
	)
	(segment
		(start 49.89703 -279.360376)
		(end 50.747168 -278.510238)
		(width 0.14478)
		(layer "In2.Cu")
		(net "M_C_CPU1_SB_CB<2>")
	)
	(segment
		(start 42.435018 -279.360376)
		(end 42.597832 -279.197562)
		(width 0.14478)
		(layer "In2.Cu")
		(net "M_C_CPU1_SB_CB<2>")
	)
	(segment
		(start 82.179668 -272.948908)
		(end 82.18805 -272.953734)
		(width 0.0889)
		(layer "In2.Cu")
		(net "M_C_CPU1_SB_CB<2>")
	)
	(segment
		(start 79.363062 -272.953734)
		(end 79.394812 -272.972276)
		(width 0.0889)
		(layer "In2.Cu")
		(net "M_C_CPU1_SB_CB<2>")
	)
	(segment
		(start 87.453978 -272.953734)
		(end 87.46236 -272.948908)
		(width 0.0889)
		(layer "In2.Cu")
		(net "M_C_CPU1_SB_CB<2>")
	)
	(segment
		(start 42.597832 -278.868378)
		(end 42.760646 -278.705564)
		(width 0.14478)
		(layer "In2.Cu")
		(net "M_C_CPU1_SB_CB<2>")
	)
	(segment
		(start 94.352618 -272.927572)
		(end 94.37497 -273.010884)
		(width 0.0889)
		(layer "In2.Cu")
		(net "M_C_CPU1_SB_CB<2>")
	)
	(segment
		(start 43.316906 -279.360376)
		(end 49.89703 -279.360376)
		(width 0.14478)
		(layer "In2.Cu")
		(net "M_C_CPU1_SB_CB<2>")
	)
	(segment
		(start 78.943708 -272.981166)
		(end 78.990952 -272.953988)
		(width 0.0889)
		(layer "In2.Cu")
		(net "M_C_CPU1_SB_CB<2>")
	)
	(segment
		(start 92.153994 -272.953734)
		(end 92.162376 -272.948908)
		(width 0.0889)
		(layer "In2.Cu")
		(net "M_C_CPU1_SB_CB<2>")
	)
	(segment
		(start 61.458856 -278.510238)
		(end 65.034668 -274.934426)
		(width 0.14478)
		(layer "In2.Cu")
		(net "M_C_CPU1_SB_CB<2>")
	)
	(segment
		(start 85.93963 -272.948908)
		(end 85.948012 -272.953734)
		(width 0.0889)
		(layer "In2.Cu")
		(net "M_C_CPU1_SB_CB<2>")
	)
	(segment
		(start 43.154092 -279.197562)
		(end 43.316906 -279.360376)
		(width 0.14478)
		(layer "In2.Cu")
		(net "M_C_CPU1_SB_CB<2>")
	)
	(segment
		(start 78.990952 -272.953988)
		(end 79.018384 -272.93824)
		(width 0.0889)
		(layer "In2.Cu")
		(net "M_C_CPU1_SB_CB<2>")
	)
	(segment
		(start 58.190384 -278.510238)
		(end 61.458856 -278.510238)
		(width 0.14478)
		(layer "In2.Cu")
		(net "M_C_CPU1_SB_CB<2>")
	)
	(segment
		(start 94.37497 -273.010884)
		(end 94.221046 -273.276314)
		(width 0.0889)
		(layer "In2.Cu")
		(net "M_C_CPU1_SB_CB<2>")
	)
	(segment
		(start 40.664892 -279.360376)
		(end 42.435018 -279.360376)
		(width 0.14478)
		(layer "In2.Cu")
		(net "M_C_CPU1_SB_CB<2>")
	)
	(segment
		(start 67.257168 -271.754854)
		(end 75.966066 -271.754854)
		(width 0.14478)
		(layer "In2.Cu")
		(net "M_C_CPU1_SB_CB<2>")
	)
	(segment
		(start 42.991278 -278.705564)
		(end 43.154092 -278.868378)
		(width 0.14478)
		(layer "In2.Cu")
		(net "M_C_CPU1_SB_CB<2>")
	)
	(segment
		(start 93.094048 -272.953734)
		(end 93.10243 -272.948908)
		(width 0.0889)
		(layer "In2.Cu")
		(net "M_C_CPU1_SB_CB<2>")
	)
	(segment
		(start 88.394032 -272.953734)
		(end 88.402414 -272.948908)
		(width 0.0889)
		(layer "In2.Cu")
		(net "M_C_CPU1_SB_CB<2>")
	)
	(segment
		(start 91.5797 -272.948908)
		(end 91.588082 -272.953734)
		(width 0.0889)
		(layer "In2.Cu")
		(net "M_C_CPU1_SB_CB<2>")
	)
	(segment
		(start 50.747168 -278.510238)
		(end 52.551584 -278.510238)
		(width 0.14478)
		(layer "In2.Cu")
		(net "M_C_CPU1_SB_CB<2>")
	)
	(segment
		(start 65.034668 -273.977354)
		(end 67.257168 -271.754854)
		(width 0.14478)
		(layer "In2.Cu")
		(net "M_C_CPU1_SB_CB<2>")
	)
	(segment
		(start 40.23995 -278.935434)
		(end 40.664892 -279.360376)
		(width 0.14478)
		(layer "In2.Cu")
		(net "M_C_CPU1_SB_CB<2>")
	)
	(segment
		(start 76.796646 -272.066004)
		(end 77.511656 -272.066004)
		(width 0.0889)
		(layer "In2.Cu")
		(net "M_C_CPU1_SB_CB<2>")
	)
	(segment
		(start 57.340246 -279.360376)
		(end 58.190384 -278.510238)
		(width 0.14478)
		(layer "In2.Cu")
		(net "M_C_CPU1_SB_CB<2>")
	)
	(segment
		(start 76.485496 -271.754854)
		(end 76.796646 -272.066004)
		(width 0.0889)
		(layer "In2.Cu")
		(net "M_C_CPU1_SB_CB<2>")
	)
	(segment
		(start 77.511656 -272.066004)
		(end 78.311502 -272.86585)
		(width 0.0889)
		(layer "In2.Cu")
		(net "M_C_CPU1_SB_CB<2>")
	)
	(segment
		(start 82.753962 -272.953734)
		(end 82.762344 -272.948908)
		(width 0.0889)
		(layer "In2.Cu")
		(net "M_C_CPU1_SB_CB<2>")
	)
	(arc
		(start 86.888066 -272.953734)
		(mid 87.171022 -273.029911)
		(end 87.453978 -272.953734)
		(width 0.0889)
		(layer "In2.Cu")
		(net "M_C_CPU1_SB_CB<2>")
	)
	(arc
		(start 84.068158 -272.953734)
		(mid 84.351114 -273.029911)
		(end 84.63407 -272.953734)
		(width 0.0889)
		(layer "In2.Cu")
		(net "M_C_CPU1_SB_CB<2>")
	)
	(arc
		(start 81.247996 -272.953734)
		(mid 81.530952 -273.029911)
		(end 81.813908 -272.953734)
		(width 0.0889)
		(layer "In2.Cu")
		(net "M_C_CPU1_SB_CB<2>")
	)
	(arc
		(start 87.46236 -272.948908)
		(mid 87.645868 -272.903414)
		(end 87.82812 -272.953734)
		(width 0.0889)
		(layer "In2.Cu")
		(net "M_C_CPU1_SB_CB<2>")
	)
	(arc
		(start 82.762344 -272.948908)
		(mid 82.945852 -272.903414)
		(end 83.128104 -272.953734)
		(width 0.0889)
		(layer "In2.Cu")
		(net "M_C_CPU1_SB_CB<2>")
	)
	(arc
		(start 79.018384 -272.93824)
		(mid 79.192621 -272.903738)
		(end 79.363062 -272.953734)
		(width 0.0889)
		(layer "In2.Cu")
		(net "M_C_CPU1_SB_CB<2>")
	)
	(arc
		(start 79.931768 -272.95348)
		(mid 80.105034 -272.902449)
		(end 80.282034 -272.938494)
		(width 0.0889)
		(layer "In2.Cu")
		(net "M_C_CPU1_SB_CB<2>")
	)
	(arc
		(start 85.57387 -272.953734)
		(mid 85.756121 -272.903384)
		(end 85.93963 -272.948908)
		(width 0.0889)
		(layer "In2.Cu")
		(net "M_C_CPU1_SB_CB<2>")
	)
	(arc
		(start 84.63407 -272.953734)
		(mid 84.821014 -272.903479)
		(end 85.007958 -272.953734)
		(width 0.0889)
		(layer "In2.Cu")
		(net "M_C_CPU1_SB_CB<2>")
	)
	(arc
		(start 80.308196 -272.953734)
		(mid 80.591152 -273.029911)
		(end 80.874108 -272.953734)
		(width 0.0889)
		(layer "In2.Cu")
		(net "M_C_CPU1_SB_CB<2>")
	)
	(arc
		(start 87.82812 -272.953734)
		(mid 88.111076 -273.029911)
		(end 88.394032 -272.953734)
		(width 0.0889)
		(layer "In2.Cu")
		(net "M_C_CPU1_SB_CB<2>")
	)
	(arc
		(start 83.128104 -272.953734)
		(mid 83.41106 -273.029911)
		(end 83.694016 -272.953734)
		(width 0.0889)
		(layer "In2.Cu")
		(net "M_C_CPU1_SB_CB<2>")
	)
	(arc
		(start 78.311502 -272.86585)
		(mid 78.365472 -272.913293)
		(end 78.42504 -272.95348)
		(width 0.0889)
		(layer "In2.Cu")
		(net "M_C_CPU1_SB_CB<2>")
	)
	(arc
		(start 78.42504 -272.95348)
		(mid 78.680997 -273.030429)
		(end 78.943708 -272.981166)
		(width 0.0889)
		(layer "In2.Cu")
		(net "M_C_CPU1_SB_CB<2>")
	)
	(arc
		(start 94.034102 -272.953734)
		(mid 94.190421 -272.904739)
		(end 94.352618 -272.927572)
		(width 0.0889)
		(layer "In2.Cu")
		(net "M_C_CPU1_SB_CB<2>")
	)
	(arc
		(start 89.334086 -272.953734)
		(mid 89.52103 -272.903479)
		(end 89.707974 -272.953734)
		(width 0.0889)
		(layer "In2.Cu")
		(net "M_C_CPU1_SB_CB<2>")
	)
	(arc
		(start 92.528136 -272.953734)
		(mid 92.811092 -273.029911)
		(end 93.094048 -272.953734)
		(width 0.0889)
		(layer "In2.Cu")
		(net "M_C_CPU1_SB_CB<2>")
	)
	(arc
		(start 93.46819 -272.953734)
		(mid 93.751146 -273.029911)
		(end 94.034102 -272.953734)
		(width 0.0889)
		(layer "In2.Cu")
		(net "M_C_CPU1_SB_CB<2>")
	)
	(arc
		(start 86.513924 -272.953734)
		(mid 86.696175 -272.903384)
		(end 86.879684 -272.948908)
		(width 0.0889)
		(layer "In2.Cu")
		(net "M_C_CPU1_SB_CB<2>")
	)
	(arc
		(start 80.874108 -272.953734)
		(mid 81.061052 -272.903479)
		(end 81.247996 -272.953734)
		(width 0.0889)
		(layer "In2.Cu")
		(net "M_C_CPU1_SB_CB<2>")
	)
	(arc
		(start 88.768174 -272.953734)
		(mid 89.05113 -273.029911)
		(end 89.334086 -272.953734)
		(width 0.0889)
		(layer "In2.Cu")
		(net "M_C_CPU1_SB_CB<2>")
	)
	(arc
		(start 92.162376 -272.948908)
		(mid 92.345884 -272.903414)
		(end 92.528136 -272.953734)
		(width 0.0889)
		(layer "In2.Cu")
		(net "M_C_CPU1_SB_CB<2>")
	)
	(arc
		(start 93.10243 -272.948908)
		(mid 93.285938 -272.903414)
		(end 93.46819 -272.953734)
		(width 0.0889)
		(layer "In2.Cu")
		(net "M_C_CPU1_SB_CB<2>")
	)
	(arc
		(start 79.394812 -272.972276)
		(mid 79.665683 -273.030862)
		(end 79.931768 -272.95348)
		(width 0.0889)
		(layer "In2.Cu")
		(net "M_C_CPU1_SB_CB<2>")
	)
	(arc
		(start 91.588082 -272.953734)
		(mid 91.871038 -273.029911)
		(end 92.153994 -272.953734)
		(width 0.0889)
		(layer "In2.Cu")
		(net "M_C_CPU1_SB_CB<2>")
	)
	(arc
		(start 83.702398 -272.948908)
		(mid 83.885906 -272.903414)
		(end 84.068158 -272.953734)
		(width 0.0889)
		(layer "In2.Cu")
		(net "M_C_CPU1_SB_CB<2>")
	)
	(arc
		(start 89.707974 -272.953734)
		(mid 89.99093 -273.029911)
		(end 90.273886 -272.953734)
		(width 0.0889)
		(layer "In2.Cu")
		(net "M_C_CPU1_SB_CB<2>")
	)
	(arc
		(start 90.273886 -272.953734)
		(mid 90.456137 -272.903384)
		(end 90.639646 -272.948908)
		(width 0.0889)
		(layer "In2.Cu")
		(net "M_C_CPU1_SB_CB<2>")
	)
	(arc
		(start 88.402414 -272.948908)
		(mid 88.585922 -272.903414)
		(end 88.768174 -272.953734)
		(width 0.0889)
		(layer "In2.Cu")
		(net "M_C_CPU1_SB_CB<2>")
	)
	(arc
		(start 85.948012 -272.953734)
		(mid 86.230968 -273.029911)
		(end 86.513924 -272.953734)
		(width 0.0889)
		(layer "In2.Cu")
		(net "M_C_CPU1_SB_CB<2>")
	)
	(arc
		(start 91.21394 -272.953734)
		(mid 91.396191 -272.903384)
		(end 91.5797 -272.948908)
		(width 0.0889)
		(layer "In2.Cu")
		(net "M_C_CPU1_SB_CB<2>")
	)
	(arc
		(start 85.007958 -272.953734)
		(mid 85.290914 -273.029911)
		(end 85.57387 -272.953734)
		(width 0.0889)
		(layer "In2.Cu")
		(net "M_C_CPU1_SB_CB<2>")
	)
	(arc
		(start 82.18805 -272.953734)
		(mid 82.471006 -273.029911)
		(end 82.753962 -272.953734)
		(width 0.0889)
		(layer "In2.Cu")
		(net "M_C_CPU1_SB_CB<2>")
	)
	(arc
		(start 81.813908 -272.953734)
		(mid 81.996159 -272.903384)
		(end 82.179668 -272.948908)
		(width 0.0889)
		(layer "In2.Cu")
		(net "M_C_CPU1_SB_CB<2>")
	)
	(arc
		(start 90.648028 -272.953734)
		(mid 90.930984 -273.029911)
		(end 91.21394 -272.953734)
		(width 0.0889)
		(layer "In2.Cu")
		(net "M_C_CPU1_SB_CB<2>")
	)
	(segment
		(start 96.568006 -273.010376)
		(end 96.101154 -273.276314)
		(width 0.10668)
		(layer "F.Cu")
		(net "M_C_CPU1_SB_CB<1>")
	)
	(segment
		(start 67.063112 -272.822162)
		(end 67.063112 -272.592038)
		(width 0.14478)
		(layer "In2.Cu")
		(net "M_C_CPU1_SB_CB<1>")
	)
	(segment
		(start 67.148202 -273.46402)
		(end 67.311524 -273.300698)
		(width 0.14478)
		(layer "In2.Cu")
		(net "M_C_CPU1_SB_CB<1>")
	)
	(segment
		(start 44.76496 -280.21026)
		(end 45.352716 -280.21026)
		(width 0.14478)
		(layer "In2.Cu")
		(net "M_C_CPU1_SB_CB<1>")
	)
	(segment
		(start 66.524632 -273.857466)
		(end 66.27622 -273.609054)
		(width 0.14478)
		(layer "In2.Cu")
		(net "M_C_CPU1_SB_CB<1>")
	)
	(segment
		(start 76.401676 -272.209514)
		(end 76.560426 -272.368264)
		(width 0.0889)
		(layer "In2.Cu")
		(net "M_C_CPU1_SB_CB<1>")
	)
	(segment
		(start 85.93963 -273.60372)
		(end 85.948012 -273.598894)
		(width 0.0889)
		(layer "In2.Cu")
		(net "M_C_CPU1_SB_CB<1>")
	)
	(segment
		(start 46.28388 -279.823164)
		(end 46.514512 -279.823164)
		(width 0.14478)
		(layer "In2.Cu")
		(net "M_C_CPU1_SB_CB<1>")
	)
	(segment
		(start 66.36131 -274.250912)
		(end 66.524632 -274.08759)
		(width 0.14478)
		(layer "In2.Cu")
		(net "M_C_CPU1_SB_CB<1>")
	)
	(segment
		(start 44.340018 -279.785318)
		(end 44.76496 -280.21026)
		(width 0.14478)
		(layer "In2.Cu")
		(net "M_C_CPU1_SB_CB<1>")
	)
	(segment
		(start 78.528672 -273.516344)
		(end 78.711044 -273.516344)
		(width 0.0889)
		(layer "In2.Cu")
		(net "M_C_CPU1_SB_CB<1>")
	)
	(segment
		(start 66.524632 -274.08759)
		(end 66.524632 -273.857466)
		(width 0.14478)
		(layer "In2.Cu")
		(net "M_C_CPU1_SB_CB<1>")
	)
	(segment
		(start 67.70497 -272.677128)
		(end 67.935094 -272.677128)
		(width 0.14478)
		(layer "In2.Cu")
		(net "M_C_CPU1_SB_CB<1>")
	)
	(segment
		(start 66.27622 -273.609054)
		(end 66.27622 -273.37893)
		(width 0.14478)
		(layer "In2.Cu")
		(net "M_C_CPU1_SB_CB<1>")
	)
	(segment
		(start 91.5797 -273.60372)
		(end 91.588082 -273.598894)
		(width 0.0889)
		(layer "In2.Cu")
		(net "M_C_CPU1_SB_CB<1>")
	)
	(segment
		(start 65.489328 -274.165822)
		(end 65.65265 -274.0025)
		(width 0.14478)
		(layer "In2.Cu")
		(net "M_C_CPU1_SB_CB<1>")
	)
	(segment
		(start 57.983628 -279.360122)
		(end 61.2521 -279.360122)
		(width 0.14478)
		(layer "In2.Cu")
		(net "M_C_CPU1_SB_CB<1>")
	)
	(segment
		(start 87.453978 -273.598894)
		(end 87.46236 -273.60372)
		(width 0.0889)
		(layer "In2.Cu")
		(net "M_C_CPU1_SB_CB<1>")
	)
	(segment
		(start 82.753962 -273.598894)
		(end 82.762344 -273.60372)
		(width 0.0889)
		(layer "In2.Cu")
		(net "M_C_CPU1_SB_CB<1>")
	)
	(segment
		(start 66.669666 -273.215608)
		(end 66.918078 -273.46402)
		(width 0.14478)
		(layer "In2.Cu")
		(net "M_C_CPU1_SB_CB<1>")
	)
	(segment
		(start 65.73774 -274.644358)
		(end 65.489328 -274.395946)
		(width 0.14478)
		(layer "In2.Cu")
		(net "M_C_CPU1_SB_CB<1>")
	)
	(segment
		(start 65.73774 -274.874482)
		(end 65.73774 -274.644358)
		(width 0.14478)
		(layer "In2.Cu")
		(net "M_C_CPU1_SB_CB<1>")
	)
	(segment
		(start 66.27622 -273.37893)
		(end 66.439542 -273.215608)
		(width 0.14478)
		(layer "In2.Cu")
		(net "M_C_CPU1_SB_CB<1>")
	)
	(segment
		(start 95.946976 -273.541744)
		(end 96.101154 -273.276314)
		(width 0.0889)
		(layer "In2.Cu")
		(net "M_C_CPU1_SB_CB<1>")
	)
	(segment
		(start 68.402708 -272.209514)
		(end 75.949556 -272.209514)
		(width 0.14478)
		(layer "In2.Cu")
		(net "M_C_CPU1_SB_CB<1>")
	)
	(segment
		(start 90.639646 -273.60372)
		(end 90.648028 -273.598894)
		(width 0.0889)
		(layer "In2.Cu")
		(net "M_C_CPU1_SB_CB<1>")
	)
	(segment
		(start 79.909416 -273.583654)
		(end 79.935578 -273.59864)
		(width 0.0889)
		(layer "In2.Cu")
		(net "M_C_CPU1_SB_CB<1>")
	)
	(segment
		(start 52.765452 -279.360122)
		(end 53.61559 -280.21026)
		(width 0.14478)
		(layer "In2.Cu")
		(net "M_C_CPU1_SB_CB<1>")
	)
	(segment
		(start 78.979014 -273.588988)
		(end 78.996032 -273.598894)
		(width 0.0889)
		(layer "In2.Cu")
		(net "M_C_CPU1_SB_CB<1>")
	)
	(segment
		(start 49.690274 -280.21026)
		(end 50.540412 -279.360122)
		(width 0.14478)
		(layer "In2.Cu")
		(net "M_C_CPU1_SB_CB<1>")
	)
	(segment
		(start 61.2521 -279.360122)
		(end 65.73774 -274.874482)
		(width 0.14478)
		(layer "In2.Cu")
		(net "M_C_CPU1_SB_CB<1>")
	)
	(segment
		(start 79.349346 -273.611848)
		(end 79.371698 -273.598894)
		(width 0.0889)
		(layer "In2.Cu")
		(net "M_C_CPU1_SB_CB<1>")
	)
	(segment
		(start 88.394032 -273.598894)
		(end 88.402414 -273.60372)
		(width 0.0889)
		(layer "In2.Cu")
		(net "M_C_CPU1_SB_CB<1>")
	)
	(segment
		(start 66.918078 -273.46402)
		(end 67.148202 -273.46402)
		(width 0.14478)
		(layer "In2.Cu")
		(net "M_C_CPU1_SB_CB<1>")
	)
	(segment
		(start 46.121066 -279.985978)
		(end 46.28388 -279.823164)
		(width 0.14478)
		(layer "In2.Cu")
		(net "M_C_CPU1_SB_CB<1>")
	)
	(segment
		(start 83.694016 -273.598894)
		(end 83.702398 -273.60372)
		(width 0.0889)
		(layer "In2.Cu")
		(net "M_C_CPU1_SB_CB<1>")
	)
	(segment
		(start 92.153994 -273.598894)
		(end 92.162376 -273.60372)
		(width 0.0889)
		(layer "In2.Cu")
		(net "M_C_CPU1_SB_CB<1>")
	)
	(segment
		(start 66.131186 -274.250912)
		(end 66.36131 -274.250912)
		(width 0.14478)
		(layer "In2.Cu")
		(net "M_C_CPU1_SB_CB<1>")
	)
	(segment
		(start 46.121066 -280.42235)
		(end 46.121066 -279.985978)
		(width 0.14478)
		(layer "In2.Cu")
		(net "M_C_CPU1_SB_CB<1>")
	)
	(segment
		(start 86.879684 -273.60372)
		(end 86.888066 -273.598894)
		(width 0.0889)
		(layer "In2.Cu")
		(net "M_C_CPU1_SB_CB<1>")
	)
	(segment
		(start 67.063112 -272.592038)
		(end 67.226434 -272.428716)
		(width 0.14478)
		(layer "In2.Cu")
		(net "M_C_CPU1_SB_CB<1>")
	)
	(segment
		(start 67.311524 -273.070574)
		(end 67.063112 -272.822162)
		(width 0.14478)
		(layer "In2.Cu")
		(net "M_C_CPU1_SB_CB<1>")
	)
	(segment
		(start 67.311524 -273.300698)
		(end 67.311524 -273.070574)
		(width 0.14478)
		(layer "In2.Cu")
		(net "M_C_CPU1_SB_CB<1>")
	)
	(segment
		(start 45.72762 -280.585164)
		(end 45.958252 -280.585164)
		(width 0.14478)
		(layer "In2.Cu")
		(net "M_C_CPU1_SB_CB<1>")
	)
	(segment
		(start 65.65265 -274.0025)
		(end 65.882774 -274.0025)
		(width 0.14478)
		(layer "In2.Cu")
		(net "M_C_CPU1_SB_CB<1>")
	)
	(segment
		(start 75.949556 -272.209514)
		(end 76.401676 -272.209514)
		(width 0.0889)
		(layer "In2.Cu")
		(net "M_C_CPU1_SB_CB<1>")
	)
	(segment
		(start 67.456558 -272.428716)
		(end 67.70497 -272.677128)
		(width 0.14478)
		(layer "In2.Cu")
		(net "M_C_CPU1_SB_CB<1>")
	)
	(segment
		(start 67.935094 -272.677128)
		(end 68.402708 -272.209514)
		(width 0.14478)
		(layer "In2.Cu")
		(net "M_C_CPU1_SB_CB<1>")
	)
	(segment
		(start 95.339662 -273.60372)
		(end 95.348044 -273.598894)
		(width 0.0889)
		(layer "In2.Cu")
		(net "M_C_CPU1_SB_CB<1>")
	)
	(segment
		(start 53.61559 -280.21026)
		(end 57.13349 -280.21026)
		(width 0.14478)
		(layer "In2.Cu")
		(net "M_C_CPU1_SB_CB<1>")
	)
	(segment
		(start 95.85071 -273.567144)
		(end 95.946976 -273.541744)
		(width 0.0889)
		(layer "In2.Cu")
		(net "M_C_CPU1_SB_CB<1>")
	)
	(segment
		(start 77.380592 -272.368264)
		(end 78.528672 -273.516344)
		(width 0.0889)
		(layer "In2.Cu")
		(net "M_C_CPU1_SB_CB<1>")
	)
	(segment
		(start 45.352716 -280.21026)
		(end 45.72762 -280.585164)
		(width 0.14478)
		(layer "In2.Cu")
		(net "M_C_CPU1_SB_CB<1>")
	)
	(segment
		(start 82.179668 -273.60372)
		(end 82.18805 -273.598894)
		(width 0.0889)
		(layer "In2.Cu")
		(net "M_C_CPU1_SB_CB<1>")
	)
	(segment
		(start 57.13349 -280.21026)
		(end 57.983628 -279.360122)
		(width 0.14478)
		(layer "In2.Cu")
		(net "M_C_CPU1_SB_CB<1>")
	)
	(segment
		(start 67.226434 -272.428716)
		(end 67.456558 -272.428716)
		(width 0.14478)
		(layer "In2.Cu")
		(net "M_C_CPU1_SB_CB<1>")
	)
	(segment
		(start 76.560426 -272.368264)
		(end 77.380592 -272.368264)
		(width 0.0889)
		(layer "In2.Cu")
		(net "M_C_CPU1_SB_CB<1>")
	)
	(segment
		(start 46.901608 -280.21026)
		(end 49.690274 -280.21026)
		(width 0.14478)
		(layer "In2.Cu")
		(net "M_C_CPU1_SB_CB<1>")
	)
	(segment
		(start 46.514512 -279.823164)
		(end 46.901608 -280.21026)
		(width 0.14478)
		(layer "In2.Cu")
		(net "M_C_CPU1_SB_CB<1>")
	)
	(segment
		(start 66.439542 -273.215608)
		(end 66.669666 -273.215608)
		(width 0.14478)
		(layer "In2.Cu")
		(net "M_C_CPU1_SB_CB<1>")
	)
	(segment
		(start 45.958252 -280.585164)
		(end 46.121066 -280.42235)
		(width 0.14478)
		(layer "In2.Cu")
		(net "M_C_CPU1_SB_CB<1>")
	)
	(segment
		(start 79.935578 -273.59864)
		(end 79.96047 -273.612864)
		(width 0.0889)
		(layer "In2.Cu")
		(net "M_C_CPU1_SB_CB<1>")
	)
	(segment
		(start 65.489328 -274.395946)
		(end 65.489328 -274.165822)
		(width 0.14478)
		(layer "In2.Cu")
		(net "M_C_CPU1_SB_CB<1>")
	)
	(segment
		(start 65.882774 -274.0025)
		(end 66.131186 -274.250912)
		(width 0.14478)
		(layer "In2.Cu")
		(net "M_C_CPU1_SB_CB<1>")
	)
	(segment
		(start 93.094048 -273.598894)
		(end 93.10243 -273.60372)
		(width 0.0889)
		(layer "In2.Cu")
		(net "M_C_CPU1_SB_CB<1>")
	)
	(segment
		(start 50.540412 -279.360122)
		(end 52.765452 -279.360122)
		(width 0.14478)
		(layer "In2.Cu")
		(net "M_C_CPU1_SB_CB<1>")
	)
	(arc
		(start 80.874108 -273.598894)
		(mid 81.061052 -273.649149)
		(end 81.247996 -273.598894)
		(width 0.0889)
		(layer "In2.Cu")
		(net "M_C_CPU1_SB_CB<1>")
	)
	(arc
		(start 86.888066 -273.598894)
		(mid 87.171022 -273.522717)
		(end 87.453978 -273.598894)
		(width 0.0889)
		(layer "In2.Cu")
		(net "M_C_CPU1_SB_CB<1>")
	)
	(arc
		(start 86.513924 -273.598894)
		(mid 86.696175 -273.649244)
		(end 86.879684 -273.60372)
		(width 0.0889)
		(layer "In2.Cu")
		(net "M_C_CPU1_SB_CB<1>")
	)
	(arc
		(start 79.96047 -273.612864)
		(mid 80.13605 -273.648884)
		(end 80.308196 -273.598894)
		(width 0.0889)
		(layer "In2.Cu")
		(net "M_C_CPU1_SB_CB<1>")
	)
	(arc
		(start 85.57387 -273.598894)
		(mid 85.756121 -273.649244)
		(end 85.93963 -273.60372)
		(width 0.0889)
		(layer "In2.Cu")
		(net "M_C_CPU1_SB_CB<1>")
	)
	(arc
		(start 85.948012 -273.598894)
		(mid 86.230968 -273.522717)
		(end 86.513924 -273.598894)
		(width 0.0889)
		(layer "In2.Cu")
		(net "M_C_CPU1_SB_CB<1>")
	)
	(arc
		(start 84.068158 -273.598894)
		(mid 84.351114 -273.522717)
		(end 84.63407 -273.598894)
		(width 0.0889)
		(layer "In2.Cu")
		(net "M_C_CPU1_SB_CB<1>")
	)
	(arc
		(start 81.247996 -273.598894)
		(mid 81.530952 -273.522717)
		(end 81.813908 -273.598894)
		(width 0.0889)
		(layer "In2.Cu")
		(net "M_C_CPU1_SB_CB<1>")
	)
	(arc
		(start 87.46236 -273.60372)
		(mid 87.645868 -273.649214)
		(end 87.82812 -273.598894)
		(width 0.0889)
		(layer "In2.Cu")
		(net "M_C_CPU1_SB_CB<1>")
	)
	(arc
		(start 94.40799 -273.598894)
		(mid 94.690946 -273.522717)
		(end 94.973902 -273.598894)
		(width 0.0889)
		(layer "In2.Cu")
		(net "M_C_CPU1_SB_CB<1>")
	)
	(arc
		(start 81.813908 -273.598894)
		(mid 81.996159 -273.649244)
		(end 82.179668 -273.60372)
		(width 0.0889)
		(layer "In2.Cu")
		(net "M_C_CPU1_SB_CB<1>")
	)
	(arc
		(start 84.63407 -273.598894)
		(mid 84.821014 -273.649149)
		(end 85.007958 -273.598894)
		(width 0.0889)
		(layer "In2.Cu")
		(net "M_C_CPU1_SB_CB<1>")
	)
	(arc
		(start 78.711044 -273.516344)
		(mid 78.84987 -273.534818)
		(end 78.979014 -273.588988)
		(width 0.0889)
		(layer "In2.Cu")
		(net "M_C_CPU1_SB_CB<1>")
	)
	(arc
		(start 95.348044 -273.598894)
		(mid 95.59564 -273.523716)
		(end 95.85071 -273.567144)
		(width 0.0889)
		(layer "In2.Cu")
		(net "M_C_CPU1_SB_CB<1>")
	)
	(arc
		(start 80.308196 -273.598894)
		(mid 80.591152 -273.522717)
		(end 80.874108 -273.598894)
		(width 0.0889)
		(layer "In2.Cu")
		(net "M_C_CPU1_SB_CB<1>")
	)
	(arc
		(start 90.273886 -273.598894)
		(mid 90.456137 -273.649244)
		(end 90.639646 -273.60372)
		(width 0.0889)
		(layer "In2.Cu")
		(net "M_C_CPU1_SB_CB<1>")
	)
	(arc
		(start 94.973902 -273.598894)
		(mid 95.156153 -273.649244)
		(end 95.339662 -273.60372)
		(width 0.0889)
		(layer "In2.Cu")
		(net "M_C_CPU1_SB_CB<1>")
	)
	(arc
		(start 78.996032 -273.598894)
		(mid 79.17106 -273.649793)
		(end 79.349346 -273.611848)
		(width 0.0889)
		(layer "In2.Cu")
		(net "M_C_CPU1_SB_CB<1>")
	)
	(arc
		(start 89.707974 -273.598894)
		(mid 89.99093 -273.522717)
		(end 90.273886 -273.598894)
		(width 0.0889)
		(layer "In2.Cu")
		(net "M_C_CPU1_SB_CB<1>")
	)
	(arc
		(start 91.21394 -273.598894)
		(mid 91.396191 -273.649244)
		(end 91.5797 -273.60372)
		(width 0.0889)
		(layer "In2.Cu")
		(net "M_C_CPU1_SB_CB<1>")
	)
	(arc
		(start 82.762344 -273.60372)
		(mid 82.945852 -273.649214)
		(end 83.128104 -273.598894)
		(width 0.0889)
		(layer "In2.Cu")
		(net "M_C_CPU1_SB_CB<1>")
	)
	(arc
		(start 93.10243 -273.60372)
		(mid 93.285938 -273.649214)
		(end 93.46819 -273.598894)
		(width 0.0889)
		(layer "In2.Cu")
		(net "M_C_CPU1_SB_CB<1>")
	)
	(arc
		(start 92.528136 -273.598894)
		(mid 92.811092 -273.522717)
		(end 93.094048 -273.598894)
		(width 0.0889)
		(layer "In2.Cu")
		(net "M_C_CPU1_SB_CB<1>")
	)
	(arc
		(start 82.18805 -273.598894)
		(mid 82.471006 -273.522717)
		(end 82.753962 -273.598894)
		(width 0.0889)
		(layer "In2.Cu")
		(net "M_C_CPU1_SB_CB<1>")
	)
	(arc
		(start 93.46819 -273.598894)
		(mid 93.751146 -273.522717)
		(end 94.034102 -273.598894)
		(width 0.0889)
		(layer "In2.Cu")
		(net "M_C_CPU1_SB_CB<1>")
	)
	(arc
		(start 87.82812 -273.598894)
		(mid 88.111076 -273.522717)
		(end 88.394032 -273.598894)
		(width 0.0889)
		(layer "In2.Cu")
		(net "M_C_CPU1_SB_CB<1>")
	)
	(arc
		(start 88.768174 -273.598894)
		(mid 89.05113 -273.522717)
		(end 89.334086 -273.598894)
		(width 0.0889)
		(layer "In2.Cu")
		(net "M_C_CPU1_SB_CB<1>")
	)
	(arc
		(start 79.371698 -273.598894)
		(mid 79.638628 -273.522945)
		(end 79.909416 -273.583654)
		(width 0.0889)
		(layer "In2.Cu")
		(net "M_C_CPU1_SB_CB<1>")
	)
	(arc
		(start 94.034102 -273.598894)
		(mid 94.221046 -273.649149)
		(end 94.40799 -273.598894)
		(width 0.0889)
		(layer "In2.Cu")
		(net "M_C_CPU1_SB_CB<1>")
	)
	(arc
		(start 91.588082 -273.598894)
		(mid 91.871038 -273.522717)
		(end 92.153994 -273.598894)
		(width 0.0889)
		(layer "In2.Cu")
		(net "M_C_CPU1_SB_CB<1>")
	)
	(arc
		(start 88.402414 -273.60372)
		(mid 88.585922 -273.649214)
		(end 88.768174 -273.598894)
		(width 0.0889)
		(layer "In2.Cu")
		(net "M_C_CPU1_SB_CB<1>")
	)
	(arc
		(start 83.702398 -273.60372)
		(mid 83.885906 -273.649214)
		(end 84.068158 -273.598894)
		(width 0.0889)
		(layer "In2.Cu")
		(net "M_C_CPU1_SB_CB<1>")
	)
	(arc
		(start 90.648028 -273.598894)
		(mid 90.930984 -273.522717)
		(end 91.21394 -273.598894)
		(width 0.0889)
		(layer "In2.Cu")
		(net "M_C_CPU1_SB_CB<1>")
	)
	(arc
		(start 89.334086 -273.598894)
		(mid 89.52103 -273.649149)
		(end 89.707974 -273.598894)
		(width 0.0889)
		(layer "In2.Cu")
		(net "M_C_CPU1_SB_CB<1>")
	)
	(arc
		(start 92.162376 -273.60372)
		(mid 92.345884 -273.649214)
		(end 92.528136 -273.598894)
		(width 0.0889)
		(layer "In2.Cu")
		(net "M_C_CPU1_SB_CB<1>")
	)
	(arc
		(start 85.007958 -273.598894)
		(mid 85.290914 -273.522717)
		(end 85.57387 -273.598894)
		(width 0.0889)
		(layer "In2.Cu")
		(net "M_C_CPU1_SB_CB<1>")
	)
	(arc
		(start 83.128104 -273.598894)
		(mid 83.41106 -273.522717)
		(end 83.694016 -273.598894)
		(width 0.0889)
		(layer "In2.Cu")
		(net "M_C_CPU1_SB_CB<1>")
	)
	(segment
		(start 95.157798 -272.20037)
		(end 94.690946 -272.466308)
		(width 0.10668)
		(layer "F.Cu")
		(net "M_C_CPU1_SB_CB<0>")
	)
	(segment
		(start 63.672466 -274.804632)
		(end 63.981838 -275.114004)
		(width 0.14478)
		(layer "In2.Cu")
		(net "M_C_CPU1_SB_CB<0>")
	)
	(segment
		(start 89.803986 -272.788888)
		(end 89.812368 -272.793714)
		(width 0.0889)
		(layer "In2.Cu")
		(net "M_C_CPU1_SB_CB<0>")
	)
	(segment
		(start 80.372204 -272.770346)
		(end 80.403954 -272.788888)
		(width 0.0889)
		(layer "In2.Cu")
		(net "M_C_CPU1_SB_CB<0>")
	)
	(segment
		(start 84.529676 -272.793714)
		(end 84.538058 -272.788888)
		(width 0.0889)
		(layer "In2.Cu")
		(net "M_C_CPU1_SB_CB<0>")
	)
	(segment
		(start 56.64581 -278.807164)
		(end 56.905398 -278.807164)
		(width 0.14478)
		(layer "In2.Cu")
		(net "M_C_CPU1_SB_CB<0>")
	)
	(segment
		(start 63.27902 -274.967954)
		(end 63.442342 -274.804632)
		(width 0.14478)
		(layer "In2.Cu")
		(net "M_C_CPU1_SB_CB<0>")
	)
	(segment
		(start 76.976732 -271.763744)
		(end 77.47889 -271.763744)
		(width 0.0889)
		(layer "In2.Cu")
		(net "M_C_CPU1_SB_CB<0>")
	)
	(segment
		(start 49.539906 -278.807164)
		(end 49.836578 -278.510492)
		(width 0.14478)
		(layer "In2.Cu")
		(net "M_C_CPU1_SB_CB<0>")
	)
	(segment
		(start 61.704982 -276.541484)
		(end 61.868304 -276.378162)
		(width 0.14478)
		(layer "In2.Cu")
		(net "M_C_CPU1_SB_CB<0>")
	)
	(segment
		(start 67.0687 -271.300194)
		(end 75.966066 -271.300194)
		(width 0.14478)
		(layer "In2.Cu")
		(net "M_C_CPU1_SB_CB<0>")
	)
	(segment
		(start 50.944272 -277.670006)
		(end 52.759864 -277.670006)
		(width 0.14478)
		(layer "In2.Cu")
		(net "M_C_CPU1_SB_CB<0>")
	)
	(segment
		(start 46.303946 -278.832564)
		(end 46.616366 -278.520144)
		(width 0.14478)
		(layer "In2.Cu")
		(net "M_C_CPU1_SB_CB<0>")
	)
	(segment
		(start 63.27902 -275.198078)
		(end 63.27902 -274.967954)
		(width 0.14478)
		(layer "In2.Cu")
		(net "M_C_CPU1_SB_CB<0>")
	)
	(segment
		(start 64.211962 -275.114004)
		(end 64.375284 -274.950682)
		(width 0.14478)
		(layer "In2.Cu")
		(net "M_C_CPU1_SB_CB<0>")
	)
	(segment
		(start 64.117982 -274.463256)
		(end 64.117982 -274.250912)
		(width 0.14478)
		(layer "In2.Cu")
		(net "M_C_CPU1_SB_CB<0>")
	)
	(segment
		(start 57.410858 -278.510492)
		(end 58.260996 -277.660354)
		(width 0.14478)
		(layer "In2.Cu")
		(net "M_C_CPU1_SB_CB<0>")
	)
	(segment
		(start 62.638178 -276.687788)
		(end 62.8015 -276.524466)
		(width 0.14478)
		(layer "In2.Cu")
		(net "M_C_CPU1_SB_CB<0>")
	)
	(segment
		(start 62.491874 -275.984716)
		(end 62.491874 -275.754592)
		(width 0.14478)
		(layer "In2.Cu")
		(net "M_C_CPU1_SB_CB<0>")
	)
	(segment
		(start 94.537022 -272.731738)
		(end 94.690946 -272.466308)
		(width 0.0889)
		(layer "In2.Cu")
		(net "M_C_CPU1_SB_CB<0>")
	)
	(segment
		(start 61.64834 -277.660354)
		(end 62.005972 -277.302722)
		(width 0.14478)
		(layer "In2.Cu")
		(net "M_C_CPU1_SB_CB<0>")
	)
	(segment
		(start 75.966066 -271.300194)
		(end 76.513182 -271.300194)
		(width 0.0889)
		(layer "In2.Cu")
		(net "M_C_CPU1_SB_CB<0>")
	)
	(segment
		(start 62.655196 -275.59127)
		(end 62.88532 -275.59127)
		(width 0.14478)
		(layer "In2.Cu")
		(net "M_C_CPU1_SB_CB<0>")
	)
	(segment
		(start 63.588392 -275.737574)
		(end 63.588392 -275.50745)
		(width 0.14478)
		(layer "In2.Cu")
		(net "M_C_CPU1_SB_CB<0>")
	)
	(segment
		(start 62.098428 -276.378162)
		(end 62.408054 -276.687788)
		(width 0.14478)
		(layer "In2.Cu")
		(net "M_C_CPU1_SB_CB<0>")
	)
	(segment
		(start 78.895956 -272.788634)
		(end 78.92923 -272.76933)
		(width 0.0889)
		(layer "In2.Cu")
		(net "M_C_CPU1_SB_CB<0>")
	)
	(segment
		(start 90.74404 -272.788888)
		(end 90.752422 -272.793714)
		(width 0.0889)
		(layer "In2.Cu")
		(net "M_C_CPU1_SB_CB<0>")
	)
	(segment
		(start 94.44101 -272.757138)
		(end 94.537022 -272.731738)
		(width 0.0889)
		(layer "In2.Cu")
		(net "M_C_CPU1_SB_CB<0>")
	)
	(segment
		(start 81.344008 -272.788888)
		(end 81.35239 -272.793714)
		(width 0.0889)
		(layer "In2.Cu")
		(net "M_C_CPU1_SB_CB<0>")
	)
	(segment
		(start 62.408054 -276.687788)
		(end 62.638178 -276.687788)
		(width 0.14478)
		(layer "In2.Cu")
		(net "M_C_CPU1_SB_CB<0>")
	)
	(segment
		(start 61.704982 -276.771608)
		(end 61.704982 -276.541484)
		(width 0.14478)
		(layer "In2.Cu")
		(net "M_C_CPU1_SB_CB<0>")
	)
	(segment
		(start 62.8015 -276.524466)
		(end 62.8015 -276.294342)
		(width 0.14478)
		(layer "In2.Cu")
		(net "M_C_CPU1_SB_CB<0>")
	)
	(segment
		(start 77.47889 -271.763744)
		(end 78.446122 -272.730976)
		(width 0.0889)
		(layer "In2.Cu")
		(net "M_C_CPU1_SB_CB<0>")
	)
	(segment
		(start 88.289638 -272.793714)
		(end 88.29802 -272.788888)
		(width 0.0889)
		(layer "In2.Cu")
		(net "M_C_CPU1_SB_CB<0>")
	)
	(segment
		(start 56.349138 -278.510492)
		(end 56.64581 -278.807164)
		(width 0.14478)
		(layer "In2.Cu")
		(net "M_C_CPU1_SB_CB<0>")
	)
	(segment
		(start 56.905398 -278.807164)
		(end 57.20207 -278.510492)
		(width 0.14478)
		(layer "In2.Cu")
		(net "M_C_CPU1_SB_CB<0>")
	)
	(segment
		(start 49.148746 -278.807164)
		(end 49.539906 -278.807164)
		(width 0.14478)
		(layer "In2.Cu")
		(net "M_C_CPU1_SB_CB<0>")
	)
	(segment
		(start 58.260996 -277.660354)
		(end 60.359036 -277.660354)
		(width 0.14478)
		(layer "In2.Cu")
		(net "M_C_CPU1_SB_CB<0>")
	)
	(segment
		(start 63.42507 -275.900896)
		(end 63.588392 -275.737574)
		(width 0.14478)
		(layer "In2.Cu")
		(net "M_C_CPU1_SB_CB<0>")
	)
	(segment
		(start 61.058298 -277.812246)
		(end 61.21019 -277.660354)
		(width 0.14478)
		(layer "In2.Cu")
		(net "M_C_CPU1_SB_CB<0>")
	)
	(segment
		(start 46.616366 -278.520144)
		(end 48.861726 -278.520144)
		(width 0.14478)
		(layer "In2.Cu")
		(net "M_C_CPU1_SB_CB<0>")
	)
	(segment
		(start 46.069758 -278.832564)
		(end 46.303946 -278.832564)
		(width 0.14478)
		(layer "In2.Cu")
		(net "M_C_CPU1_SB_CB<0>")
	)
	(segment
		(start 63.194946 -275.900896)
		(end 63.42507 -275.900896)
		(width 0.14478)
		(layer "In2.Cu")
		(net "M_C_CPU1_SB_CB<0>")
	)
	(segment
		(start 52.759864 -277.670006)
		(end 53.60035 -278.510492)
		(width 0.14478)
		(layer "In2.Cu")
		(net "M_C_CPU1_SB_CB<0>")
	)
	(segment
		(start 62.88532 -275.59127)
		(end 63.194946 -275.900896)
		(width 0.14478)
		(layer "In2.Cu")
		(net "M_C_CPU1_SB_CB<0>")
	)
	(segment
		(start 63.442342 -274.804632)
		(end 63.672466 -274.804632)
		(width 0.14478)
		(layer "In2.Cu")
		(net "M_C_CPU1_SB_CB<0>")
	)
	(segment
		(start 64.375284 -274.720558)
		(end 64.117982 -274.463256)
		(width 0.14478)
		(layer "In2.Cu")
		(net "M_C_CPU1_SB_CB<0>")
	)
	(segment
		(start 93.929708 -272.793714)
		(end 93.93809 -272.788888)
		(width 0.0889)
		(layer "In2.Cu")
		(net "M_C_CPU1_SB_CB<0>")
	)
	(segment
		(start 62.491874 -275.754592)
		(end 62.655196 -275.59127)
		(width 0.14478)
		(layer "In2.Cu")
		(net "M_C_CPU1_SB_CB<0>")
	)
	(segment
		(start 62.8015 -276.294342)
		(end 62.491874 -275.984716)
		(width 0.14478)
		(layer "In2.Cu")
		(net "M_C_CPU1_SB_CB<0>")
	)
	(segment
		(start 63.588392 -275.50745)
		(end 63.27902 -275.198078)
		(width 0.14478)
		(layer "In2.Cu")
		(net "M_C_CPU1_SB_CB<0>")
	)
	(segment
		(start 48.861726 -278.520144)
		(end 49.148746 -278.807164)
		(width 0.14478)
		(layer "In2.Cu")
		(net "M_C_CPU1_SB_CB<0>")
	)
	(segment
		(start 92.989654 -272.793714)
		(end 92.998036 -272.788888)
		(width 0.0889)
		(layer "In2.Cu")
		(net "M_C_CPU1_SB_CB<0>")
	)
	(segment
		(start 57.20207 -278.510492)
		(end 57.410858 -278.510492)
		(width 0.14478)
		(layer "In2.Cu")
		(net "M_C_CPU1_SB_CB<0>")
	)
	(segment
		(start 78.85684 -272.810986)
		(end 78.895956 -272.788634)
		(width 0.0889)
		(layer "In2.Cu")
		(net "M_C_CPU1_SB_CB<0>")
	)
	(segment
		(start 64.117982 -274.250912)
		(end 67.0687 -271.300194)
		(width 0.14478)
		(layer "In2.Cu")
		(net "M_C_CPU1_SB_CB<0>")
	)
	(segment
		(start 63.981838 -275.114004)
		(end 64.211962 -275.114004)
		(width 0.14478)
		(layer "In2.Cu")
		(net "M_C_CPU1_SB_CB<0>")
	)
	(segment
		(start 60.359036 -277.660354)
		(end 60.510928 -277.812246)
		(width 0.14478)
		(layer "In2.Cu")
		(net "M_C_CPU1_SB_CB<0>")
	)
	(segment
		(start 64.375284 -274.950682)
		(end 64.375284 -274.720558)
		(width 0.14478)
		(layer "In2.Cu")
		(net "M_C_CPU1_SB_CB<0>")
	)
	(segment
		(start 61.21019 -277.660354)
		(end 61.64834 -277.660354)
		(width 0.14478)
		(layer "In2.Cu")
		(net "M_C_CPU1_SB_CB<0>")
	)
	(segment
		(start 83.589622 -272.793714)
		(end 83.598004 -272.788888)
		(width 0.0889)
		(layer "In2.Cu")
		(net "M_C_CPU1_SB_CB<0>")
	)
	(segment
		(start 60.510928 -277.812246)
		(end 61.058298 -277.812246)
		(width 0.14478)
		(layer "In2.Cu")
		(net "M_C_CPU1_SB_CB<0>")
	)
	(segment
		(start 62.005972 -277.072598)
		(end 61.704982 -276.771608)
		(width 0.14478)
		(layer "In2.Cu")
		(net "M_C_CPU1_SB_CB<0>")
	)
	(segment
		(start 76.513182 -271.300194)
		(end 76.976732 -271.763744)
		(width 0.0889)
		(layer "In2.Cu")
		(net "M_C_CPU1_SB_CB<0>")
	)
	(segment
		(start 44.765214 -278.510492)
		(end 45.747686 -278.510492)
		(width 0.14478)
		(layer "In2.Cu")
		(net "M_C_CPU1_SB_CB<0>")
	)
	(segment
		(start 61.868304 -276.378162)
		(end 62.098428 -276.378162)
		(width 0.14478)
		(layer "In2.Cu")
		(net "M_C_CPU1_SB_CB<0>")
	)
	(segment
		(start 80.769714 -272.793714)
		(end 80.778096 -272.788888)
		(width 0.0889)
		(layer "In2.Cu")
		(net "M_C_CPU1_SB_CB<0>")
	)
	(segment
		(start 62.005972 -277.302722)
		(end 62.005972 -277.072598)
		(width 0.14478)
		(layer "In2.Cu")
		(net "M_C_CPU1_SB_CB<0>")
	)
	(segment
		(start 45.747686 -278.510492)
		(end 46.069758 -278.832564)
		(width 0.14478)
		(layer "In2.Cu")
		(net "M_C_CPU1_SB_CB<0>")
	)
	(segment
		(start 79.45882 -272.788888)
		(end 79.484982 -272.804128)
		(width 0.0889)
		(layer "In2.Cu")
		(net "M_C_CPU1_SB_CB<0>")
	)
	(segment
		(start 53.60035 -278.510492)
		(end 56.349138 -278.510492)
		(width 0.14478)
		(layer "In2.Cu")
		(net "M_C_CPU1_SB_CB<0>")
	)
	(segment
		(start 50.103786 -278.510492)
		(end 50.944272 -277.670006)
		(width 0.14478)
		(layer "In2.Cu")
		(net "M_C_CPU1_SB_CB<0>")
	)
	(segment
		(start 49.836578 -278.510492)
		(end 50.103786 -278.510492)
		(width 0.14478)
		(layer "In2.Cu")
		(net "M_C_CPU1_SB_CB<0>")
	)
	(segment
		(start 85.10397 -272.788888)
		(end 85.112352 -272.793714)
		(width 0.0889)
		(layer "In2.Cu")
		(net "M_C_CPU1_SB_CB<0>")
	)
	(segment
		(start 89.229692 -272.793714)
		(end 89.238074 -272.788888)
		(width 0.0889)
		(layer "In2.Cu")
		(net "M_C_CPU1_SB_CB<0>")
	)
	(segment
		(start 44.340018 -278.085296)
		(end 44.765214 -278.510492)
		(width 0.14478)
		(layer "In2.Cu")
		(net "M_C_CPU1_SB_CB<0>")
	)
	(segment
		(start 86.044024 -272.788888)
		(end 86.052406 -272.793714)
		(width 0.0889)
		(layer "In2.Cu")
		(net "M_C_CPU1_SB_CB<0>")
	)
	(arc
		(start 78.92923 -272.76933)
		(mid 79.19646 -272.713019)
		(end 79.45882 -272.788888)
		(width 0.0889)
		(layer "In2.Cu")
		(net "M_C_CPU1_SB_CB<0>")
	)
	(arc
		(start 92.057982 -272.788888)
		(mid 92.340938 -272.712711)
		(end 92.623894 -272.788888)
		(width 0.0889)
		(layer "In2.Cu")
		(net "M_C_CPU1_SB_CB<0>")
	)
	(arc
		(start 90.178128 -272.788888)
		(mid 90.461084 -272.712711)
		(end 90.74404 -272.788888)
		(width 0.0889)
		(layer "In2.Cu")
		(net "M_C_CPU1_SB_CB<0>")
	)
	(arc
		(start 83.223862 -272.788888)
		(mid 83.406113 -272.839238)
		(end 83.589622 -272.793714)
		(width 0.0889)
		(layer "In2.Cu")
		(net "M_C_CPU1_SB_CB<0>")
	)
	(arc
		(start 80.778096 -272.788888)
		(mid 81.061052 -272.712711)
		(end 81.344008 -272.788888)
		(width 0.0889)
		(layer "In2.Cu")
		(net "M_C_CPU1_SB_CB<0>")
	)
	(arc
		(start 82.65795 -272.788888)
		(mid 82.940906 -272.712711)
		(end 83.223862 -272.788888)
		(width 0.0889)
		(layer "In2.Cu")
		(net "M_C_CPU1_SB_CB<0>")
	)
	(arc
		(start 82.284062 -272.788888)
		(mid 82.471006 -272.839143)
		(end 82.65795 -272.788888)
		(width 0.0889)
		(layer "In2.Cu")
		(net "M_C_CPU1_SB_CB<0>")
	)
	(arc
		(start 92.623894 -272.788888)
		(mid 92.806145 -272.839238)
		(end 92.989654 -272.793714)
		(width 0.0889)
		(layer "In2.Cu")
		(net "M_C_CPU1_SB_CB<0>")
	)
	(arc
		(start 90.752422 -272.793714)
		(mid 90.93593 -272.839208)
		(end 91.118182 -272.788888)
		(width 0.0889)
		(layer "In2.Cu")
		(net "M_C_CPU1_SB_CB<0>")
	)
	(arc
		(start 83.598004 -272.788888)
		(mid 83.88096 -272.712711)
		(end 84.163916 -272.788888)
		(width 0.0889)
		(layer "In2.Cu")
		(net "M_C_CPU1_SB_CB<0>")
	)
	(arc
		(start 81.71815 -272.788888)
		(mid 82.001106 -272.712711)
		(end 82.284062 -272.788888)
		(width 0.0889)
		(layer "In2.Cu")
		(net "M_C_CPU1_SB_CB<0>")
	)
	(arc
		(start 91.118182 -272.788888)
		(mid 91.401138 -272.712711)
		(end 91.684094 -272.788888)
		(width 0.0889)
		(layer "In2.Cu")
		(net "M_C_CPU1_SB_CB<0>")
	)
	(arc
		(start 86.984078 -272.788888)
		(mid 87.171022 -272.839143)
		(end 87.357966 -272.788888)
		(width 0.0889)
		(layer "In2.Cu")
		(net "M_C_CPU1_SB_CB<0>")
	)
	(arc
		(start 91.684094 -272.788888)
		(mid 91.871038 -272.839143)
		(end 92.057982 -272.788888)
		(width 0.0889)
		(layer "In2.Cu")
		(net "M_C_CPU1_SB_CB<0>")
	)
	(arc
		(start 80.403954 -272.788888)
		(mid 80.586205 -272.839238)
		(end 80.769714 -272.793714)
		(width 0.0889)
		(layer "In2.Cu")
		(net "M_C_CPU1_SB_CB<0>")
	)
	(arc
		(start 88.863932 -272.788888)
		(mid 89.046183 -272.839238)
		(end 89.229692 -272.793714)
		(width 0.0889)
		(layer "In2.Cu")
		(net "M_C_CPU1_SB_CB<0>")
	)
	(arc
		(start 87.923878 -272.788888)
		(mid 88.106129 -272.839238)
		(end 88.289638 -272.793714)
		(width 0.0889)
		(layer "In2.Cu")
		(net "M_C_CPU1_SB_CB<0>")
	)
	(arc
		(start 78.52156 -272.789142)
		(mid 78.686619 -272.839844)
		(end 78.85684 -272.810986)
		(width 0.0889)
		(layer "In2.Cu")
		(net "M_C_CPU1_SB_CB<0>")
	)
	(arc
		(start 79.835248 -272.789142)
		(mid 80.101337 -272.711865)
		(end 80.372204 -272.770346)
		(width 0.0889)
		(layer "In2.Cu")
		(net "M_C_CPU1_SB_CB<0>")
	)
	(arc
		(start 84.538058 -272.788888)
		(mid 84.821014 -272.712711)
		(end 85.10397 -272.788888)
		(width 0.0889)
		(layer "In2.Cu")
		(net "M_C_CPU1_SB_CB<0>")
	)
	(arc
		(start 85.478112 -272.788888)
		(mid 85.761068 -272.712711)
		(end 86.044024 -272.788888)
		(width 0.0889)
		(layer "In2.Cu")
		(net "M_C_CPU1_SB_CB<0>")
	)
	(arc
		(start 79.484982 -272.804128)
		(mid 79.661983 -272.840206)
		(end 79.835248 -272.789142)
		(width 0.0889)
		(layer "In2.Cu")
		(net "M_C_CPU1_SB_CB<0>")
	)
	(arc
		(start 87.357966 -272.788888)
		(mid 87.640922 -272.712711)
		(end 87.923878 -272.788888)
		(width 0.0889)
		(layer "In2.Cu")
		(net "M_C_CPU1_SB_CB<0>")
	)
	(arc
		(start 81.35239 -272.793714)
		(mid 81.535898 -272.839208)
		(end 81.71815 -272.788888)
		(width 0.0889)
		(layer "In2.Cu")
		(net "M_C_CPU1_SB_CB<0>")
	)
	(arc
		(start 78.446122 -272.730976)
		(mid 78.481995 -272.762451)
		(end 78.52156 -272.789142)
		(width 0.0889)
		(layer "In2.Cu")
		(net "M_C_CPU1_SB_CB<0>")
	)
	(arc
		(start 88.29802 -272.788888)
		(mid 88.580976 -272.712711)
		(end 88.863932 -272.788888)
		(width 0.0889)
		(layer "In2.Cu")
		(net "M_C_CPU1_SB_CB<0>")
	)
	(arc
		(start 89.812368 -272.793714)
		(mid 89.995876 -272.839208)
		(end 90.178128 -272.788888)
		(width 0.0889)
		(layer "In2.Cu")
		(net "M_C_CPU1_SB_CB<0>")
	)
	(arc
		(start 84.163916 -272.788888)
		(mid 84.346167 -272.839238)
		(end 84.529676 -272.793714)
		(width 0.0889)
		(layer "In2.Cu")
		(net "M_C_CPU1_SB_CB<0>")
	)
	(arc
		(start 86.418166 -272.788888)
		(mid 86.701122 -272.712711)
		(end 86.984078 -272.788888)
		(width 0.0889)
		(layer "In2.Cu")
		(net "M_C_CPU1_SB_CB<0>")
	)
	(arc
		(start 89.238074 -272.788888)
		(mid 89.52103 -272.712711)
		(end 89.803986 -272.788888)
		(width 0.0889)
		(layer "In2.Cu")
		(net "M_C_CPU1_SB_CB<0>")
	)
	(arc
		(start 93.563948 -272.788888)
		(mid 93.746199 -272.839238)
		(end 93.929708 -272.793714)
		(width 0.0889)
		(layer "In2.Cu")
		(net "M_C_CPU1_SB_CB<0>")
	)
	(arc
		(start 93.93809 -272.788888)
		(mid 94.185803 -272.713668)
		(end 94.44101 -272.757138)
		(width 0.0889)
		(layer "In2.Cu")
		(net "M_C_CPU1_SB_CB<0>")
	)
	(arc
		(start 85.112352 -272.793714)
		(mid 85.29586 -272.839208)
		(end 85.478112 -272.788888)
		(width 0.0889)
		(layer "In2.Cu")
		(net "M_C_CPU1_SB_CB<0>")
	)
	(arc
		(start 92.998036 -272.788888)
		(mid 93.280992 -272.712711)
		(end 93.563948 -272.788888)
		(width 0.0889)
		(layer "In2.Cu")
		(net "M_C_CPU1_SB_CB<0>")
	)
	(arc
		(start 86.052406 -272.793714)
		(mid 86.235914 -272.839208)
		(end 86.418166 -272.788888)
		(width 0.0889)
		(layer "In2.Cu")
		(net "M_C_CPU1_SB_CB<0>")
	)
	(segment
		(start 95.157798 -264.10031)
		(end 94.690946 -264.366248)
		(width 0.10668)
		(layer "F.Cu")
		(net "M_C_CPU1_SB_CA<6>")
	)
	(segment
		(start 80.769714 -264.693654)
		(end 80.778096 -264.688828)
		(width 0.0889)
		(layer "In2.Cu")
		(net "M_C_CPU1_SB_CA<6>")
	)
	(segment
		(start 49.329594 -265.388344)
		(end 49.492408 -265.551158)
		(width 0.14478)
		(layer "In2.Cu")
		(net "M_C_CPU1_SB_CA<6>")
	)
	(segment
		(start 53.743352 -265.370564)
		(end 53.973984 -265.370564)
		(width 0.14478)
		(layer "In2.Cu")
		(net "M_C_CPU1_SB_CA<6>")
	)
	(segment
		(start 46.660816 -265.533378)
		(end 46.660816 -265.98753)
		(width 0.14478)
		(layer "In2.Cu")
		(net "M_C_CPU1_SB_CA<6>")
	)
	(segment
		(start 82.284062 -264.688828)
		(end 82.292444 -264.693654)
		(width 0.0889)
		(layer "In2.Cu")
		(net "M_C_CPU1_SB_CA<6>")
	)
	(segment
		(start 49.655222 -266.132564)
		(end 49.885854 -266.132564)
		(width 0.14478)
		(layer "In2.Cu")
		(net "M_C_CPU1_SB_CA<6>")
	)
	(segment
		(start 48.936148 -265.551158)
		(end 49.098962 -265.388344)
		(width 0.14478)
		(layer "In2.Cu")
		(net "M_C_CPU1_SB_CA<6>")
	)
	(segment
		(start 94.44101 -264.657078)
		(end 94.537022 -264.631678)
		(width 0.0889)
		(layer "In2.Cu")
		(net "M_C_CPU1_SB_CA<6>")
	)
	(segment
		(start 47.444152 -265.760454)
		(end 48.025812 -265.760454)
		(width 0.14478)
		(layer "In2.Cu")
		(net "M_C_CPU1_SB_CA<6>")
	)
	(segment
		(start 78.155292 -264.329164)
		(end 78.47965 -264.653522)
		(width 0.0889)
		(layer "In2.Cu")
		(net "M_C_CPU1_SB_CA<6>")
	)
	(segment
		(start 49.492408 -265.551158)
		(end 49.492408 -265.96975)
		(width 0.14478)
		(layer "In2.Cu")
		(net "M_C_CPU1_SB_CA<6>")
	)
	(segment
		(start 52.630832 -265.370564)
		(end 52.861464 -265.370564)
		(width 0.14478)
		(layer "In2.Cu")
		(net "M_C_CPU1_SB_CA<6>")
	)
	(segment
		(start 49.492408 -265.96975)
		(end 49.655222 -266.132564)
		(width 0.14478)
		(layer "In2.Cu")
		(net "M_C_CPU1_SB_CA<6>")
	)
	(segment
		(start 44.340018 -266.185396)
		(end 45.15485 -265.370564)
		(width 0.14478)
		(layer "In2.Cu")
		(net "M_C_CPU1_SB_CA<6>")
	)
	(segment
		(start 88.289638 -264.693654)
		(end 88.29802 -264.688828)
		(width 0.0889)
		(layer "In2.Cu")
		(net "M_C_CPU1_SB_CA<6>")
	)
	(segment
		(start 48.397922 -266.132564)
		(end 48.773334 -266.132564)
		(width 0.14478)
		(layer "In2.Cu")
		(net "M_C_CPU1_SB_CA<6>")
	)
	(segment
		(start 85.10397 -264.688828)
		(end 85.112352 -264.693654)
		(width 0.0889)
		(layer "In2.Cu")
		(net "M_C_CPU1_SB_CA<6>")
	)
	(segment
		(start 84.529676 -264.693654)
		(end 84.538058 -264.688828)
		(width 0.0889)
		(layer "In2.Cu")
		(net "M_C_CPU1_SB_CA<6>")
	)
	(segment
		(start 54.363874 -265.760454)
		(end 60.153296 -265.760454)
		(width 0.14478)
		(layer "In2.Cu")
		(net "M_C_CPU1_SB_CA<6>")
	)
	(segment
		(start 94.537022 -264.631678)
		(end 94.690946 -264.366248)
		(width 0.0889)
		(layer "In2.Cu")
		(net "M_C_CPU1_SB_CA<6>")
	)
	(segment
		(start 60.153296 -265.760454)
		(end 61.293756 -264.619994)
		(width 0.14478)
		(layer "In2.Cu")
		(net "M_C_CPU1_SB_CA<6>")
	)
	(segment
		(start 45.385482 -265.370564)
		(end 45.548296 -265.533378)
		(width 0.14478)
		(layer "In2.Cu")
		(net "M_C_CPU1_SB_CA<6>")
	)
	(segment
		(start 49.885854 -266.132564)
		(end 50.048668 -265.96975)
		(width 0.14478)
		(layer "In2.Cu")
		(net "M_C_CPU1_SB_CA<6>")
	)
	(segment
		(start 78.52537 -264.688574)
		(end 78.555342 -264.705846)
		(width 0.0889)
		(layer "In2.Cu")
		(net "M_C_CPU1_SB_CA<6>")
	)
	(segment
		(start 45.548296 -265.533378)
		(end 45.548296 -265.98753)
		(width 0.14478)
		(layer "In2.Cu")
		(net "M_C_CPU1_SB_CA<6>")
	)
	(segment
		(start 53.024278 -265.98753)
		(end 53.187092 -266.150344)
		(width 0.14478)
		(layer "In2.Cu")
		(net "M_C_CPU1_SB_CA<6>")
	)
	(segment
		(start 46.660816 -265.98753)
		(end 46.82363 -266.150344)
		(width 0.14478)
		(layer "In2.Cu")
		(net "M_C_CPU1_SB_CA<6>")
	)
	(segment
		(start 46.82363 -266.150344)
		(end 47.054262 -266.150344)
		(width 0.14478)
		(layer "In2.Cu")
		(net "M_C_CPU1_SB_CA<6>")
	)
	(segment
		(start 89.803986 -264.688828)
		(end 89.812368 -264.693654)
		(width 0.0889)
		(layer "In2.Cu")
		(net "M_C_CPU1_SB_CA<6>")
	)
	(segment
		(start 79.83982 -264.688574)
		(end 79.863696 -264.674604)
		(width 0.0889)
		(layer "In2.Cu")
		(net "M_C_CPU1_SB_CA<6>")
	)
	(segment
		(start 49.098962 -265.388344)
		(end 49.329594 -265.388344)
		(width 0.14478)
		(layer "In2.Cu")
		(net "M_C_CPU1_SB_CA<6>")
	)
	(segment
		(start 53.417724 -266.150344)
		(end 53.580538 -265.98753)
		(width 0.14478)
		(layer "In2.Cu")
		(net "M_C_CPU1_SB_CA<6>")
	)
	(segment
		(start 48.936148 -265.96975)
		(end 48.936148 -265.551158)
		(width 0.14478)
		(layer "In2.Cu")
		(net "M_C_CPU1_SB_CA<6>")
	)
	(segment
		(start 81.344008 -264.688828)
		(end 81.35239 -264.693654)
		(width 0.0889)
		(layer "In2.Cu")
		(net "M_C_CPU1_SB_CA<6>")
	)
	(segment
		(start 76.697586 -264.329164)
		(end 78.155292 -264.329164)
		(width 0.0889)
		(layer "In2.Cu")
		(net "M_C_CPU1_SB_CA<6>")
	)
	(segment
		(start 53.580538 -265.533378)
		(end 53.743352 -265.370564)
		(width 0.14478)
		(layer "In2.Cu")
		(net "M_C_CPU1_SB_CA<6>")
	)
	(segment
		(start 50.048668 -265.551158)
		(end 50.211482 -265.388344)
		(width 0.14478)
		(layer "In2.Cu")
		(net "M_C_CPU1_SB_CA<6>")
	)
	(segment
		(start 50.814224 -265.760454)
		(end 52.240942 -265.760454)
		(width 0.14478)
		(layer "In2.Cu")
		(net "M_C_CPU1_SB_CA<6>")
	)
	(segment
		(start 61.293756 -264.619994)
		(end 75.944476 -264.619994)
		(width 0.14478)
		(layer "In2.Cu")
		(net "M_C_CPU1_SB_CA<6>")
	)
	(segment
		(start 75.944476 -264.619994)
		(end 76.406756 -264.619994)
		(width 0.0889)
		(layer "In2.Cu")
		(net "M_C_CPU1_SB_CA<6>")
	)
	(segment
		(start 45.71111 -266.150344)
		(end 45.941742 -266.150344)
		(width 0.14478)
		(layer "In2.Cu")
		(net "M_C_CPU1_SB_CA<6>")
	)
	(segment
		(start 47.054262 -266.150344)
		(end 47.444152 -265.760454)
		(width 0.14478)
		(layer "In2.Cu")
		(net "M_C_CPU1_SB_CA<6>")
	)
	(segment
		(start 50.442114 -265.388344)
		(end 50.814224 -265.760454)
		(width 0.14478)
		(layer "In2.Cu")
		(net "M_C_CPU1_SB_CA<6>")
	)
	(segment
		(start 52.861464 -265.370564)
		(end 53.024278 -265.533378)
		(width 0.14478)
		(layer "In2.Cu")
		(net "M_C_CPU1_SB_CA<6>")
	)
	(segment
		(start 50.048668 -265.96975)
		(end 50.048668 -265.551158)
		(width 0.14478)
		(layer "In2.Cu")
		(net "M_C_CPU1_SB_CA<6>")
	)
	(segment
		(start 46.104556 -265.533378)
		(end 46.26737 -265.370564)
		(width 0.14478)
		(layer "In2.Cu")
		(net "M_C_CPU1_SB_CA<6>")
	)
	(segment
		(start 79.439516 -264.672826)
		(end 79.467202 -264.688828)
		(width 0.0889)
		(layer "In2.Cu")
		(net "M_C_CPU1_SB_CA<6>")
	)
	(segment
		(start 90.74404 -264.688828)
		(end 90.752422 -264.693654)
		(width 0.0889)
		(layer "In2.Cu")
		(net "M_C_CPU1_SB_CA<6>")
	)
	(segment
		(start 48.773334 -266.132564)
		(end 48.936148 -265.96975)
		(width 0.14478)
		(layer "In2.Cu")
		(net "M_C_CPU1_SB_CA<6>")
	)
	(segment
		(start 53.580538 -265.98753)
		(end 53.580538 -265.533378)
		(width 0.14478)
		(layer "In2.Cu")
		(net "M_C_CPU1_SB_CA<6>")
	)
	(segment
		(start 48.025812 -265.760454)
		(end 48.397922 -266.132564)
		(width 0.14478)
		(layer "In2.Cu")
		(net "M_C_CPU1_SB_CA<6>")
	)
	(segment
		(start 46.26737 -265.370564)
		(end 46.498002 -265.370564)
		(width 0.14478)
		(layer "In2.Cu")
		(net "M_C_CPU1_SB_CA<6>")
	)
	(segment
		(start 45.548296 -265.98753)
		(end 45.71111 -266.150344)
		(width 0.14478)
		(layer "In2.Cu")
		(net "M_C_CPU1_SB_CA<6>")
	)
	(segment
		(start 92.989654 -264.693654)
		(end 92.998036 -264.688828)
		(width 0.0889)
		(layer "In2.Cu")
		(net "M_C_CPU1_SB_CA<6>")
	)
	(segment
		(start 46.498002 -265.370564)
		(end 46.660816 -265.533378)
		(width 0.14478)
		(layer "In2.Cu")
		(net "M_C_CPU1_SB_CA<6>")
	)
	(segment
		(start 79.817976 -264.70102)
		(end 79.83982 -264.688574)
		(width 0.0889)
		(layer "In2.Cu")
		(net "M_C_CPU1_SB_CA<6>")
	)
	(segment
		(start 52.240942 -265.760454)
		(end 52.630832 -265.370564)
		(width 0.14478)
		(layer "In2.Cu")
		(net "M_C_CPU1_SB_CA<6>")
	)
	(segment
		(start 45.941742 -266.150344)
		(end 46.104556 -265.98753)
		(width 0.14478)
		(layer "In2.Cu")
		(net "M_C_CPU1_SB_CA<6>")
	)
	(segment
		(start 46.104556 -265.98753)
		(end 46.104556 -265.533378)
		(width 0.14478)
		(layer "In2.Cu")
		(net "M_C_CPU1_SB_CA<6>")
	)
	(segment
		(start 50.211482 -265.388344)
		(end 50.442114 -265.388344)
		(width 0.14478)
		(layer "In2.Cu")
		(net "M_C_CPU1_SB_CA<6>")
	)
	(segment
		(start 53.187092 -266.150344)
		(end 53.417724 -266.150344)
		(width 0.14478)
		(layer "In2.Cu")
		(net "M_C_CPU1_SB_CA<6>")
	)
	(segment
		(start 89.229692 -264.693654)
		(end 89.238074 -264.688828)
		(width 0.0889)
		(layer "In2.Cu")
		(net "M_C_CPU1_SB_CA<6>")
	)
	(segment
		(start 86.044024 -264.688828)
		(end 86.052406 -264.693654)
		(width 0.0889)
		(layer "In2.Cu")
		(net "M_C_CPU1_SB_CA<6>")
	)
	(segment
		(start 45.15485 -265.370564)
		(end 45.385482 -265.370564)
		(width 0.14478)
		(layer "In2.Cu")
		(net "M_C_CPU1_SB_CA<6>")
	)
	(segment
		(start 53.024278 -265.533378)
		(end 53.024278 -265.98753)
		(width 0.14478)
		(layer "In2.Cu")
		(net "M_C_CPU1_SB_CA<6>")
	)
	(segment
		(start 53.973984 -265.370564)
		(end 54.363874 -265.760454)
		(width 0.14478)
		(layer "In2.Cu")
		(net "M_C_CPU1_SB_CA<6>")
	)
	(segment
		(start 93.929708 -264.693654)
		(end 93.93809 -264.688828)
		(width 0.0889)
		(layer "In2.Cu")
		(net "M_C_CPU1_SB_CA<6>")
	)
	(segment
		(start 76.406756 -264.619994)
		(end 76.697586 -264.329164)
		(width 0.0889)
		(layer "In2.Cu")
		(net "M_C_CPU1_SB_CA<6>")
	)
	(arc
		(start 86.418166 -264.688828)
		(mid 86.701122 -264.612651)
		(end 86.984078 -264.688828)
		(width 0.0889)
		(layer "In2.Cu")
		(net "M_C_CPU1_SB_CA<6>")
	)
	(arc
		(start 90.752422 -264.693654)
		(mid 90.93593 -264.739148)
		(end 91.118182 -264.688828)
		(width 0.0889)
		(layer "In2.Cu")
		(net "M_C_CPU1_SB_CA<6>")
	)
	(arc
		(start 85.112352 -264.693654)
		(mid 85.29586 -264.739148)
		(end 85.478112 -264.688828)
		(width 0.0889)
		(layer "In2.Cu")
		(net "M_C_CPU1_SB_CA<6>")
	)
	(arc
		(start 86.984078 -264.688828)
		(mid 87.171022 -264.739083)
		(end 87.357966 -264.688828)
		(width 0.0889)
		(layer "In2.Cu")
		(net "M_C_CPU1_SB_CA<6>")
	)
	(arc
		(start 87.923878 -264.688828)
		(mid 88.106129 -264.739178)
		(end 88.289638 -264.693654)
		(width 0.0889)
		(layer "In2.Cu")
		(net "M_C_CPU1_SB_CA<6>")
	)
	(arc
		(start 78.555342 -264.705846)
		(mid 78.729505 -264.739382)
		(end 78.899512 -264.688828)
		(width 0.0889)
		(layer "In2.Cu")
		(net "M_C_CPU1_SB_CA<6>")
	)
	(arc
		(start 92.998036 -264.688828)
		(mid 93.280992 -264.612651)
		(end 93.563948 -264.688828)
		(width 0.0889)
		(layer "In2.Cu")
		(net "M_C_CPU1_SB_CA<6>")
	)
	(arc
		(start 84.163916 -264.688828)
		(mid 84.346167 -264.739178)
		(end 84.529676 -264.693654)
		(width 0.0889)
		(layer "In2.Cu")
		(net "M_C_CPU1_SB_CA<6>")
	)
	(arc
		(start 83.598004 -264.688828)
		(mid 83.88096 -264.612651)
		(end 84.163916 -264.688828)
		(width 0.0889)
		(layer "In2.Cu")
		(net "M_C_CPU1_SB_CA<6>")
	)
	(arc
		(start 78.47965 -264.653522)
		(mid 78.501358 -264.67255)
		(end 78.52537 -264.688574)
		(width 0.0889)
		(layer "In2.Cu")
		(net "M_C_CPU1_SB_CA<6>")
	)
	(arc
		(start 80.403954 -264.688828)
		(mid 80.586205 -264.739178)
		(end 80.769714 -264.693654)
		(width 0.0889)
		(layer "In2.Cu")
		(net "M_C_CPU1_SB_CA<6>")
	)
	(arc
		(start 88.29802 -264.688828)
		(mid 88.580976 -264.612651)
		(end 88.863932 -264.688828)
		(width 0.0889)
		(layer "In2.Cu")
		(net "M_C_CPU1_SB_CA<6>")
	)
	(arc
		(start 83.224116 -264.688828)
		(mid 83.41106 -264.739083)
		(end 83.598004 -264.688828)
		(width 0.0889)
		(layer "In2.Cu")
		(net "M_C_CPU1_SB_CA<6>")
	)
	(arc
		(start 92.057982 -264.688828)
		(mid 92.340938 -264.612651)
		(end 92.623894 -264.688828)
		(width 0.0889)
		(layer "In2.Cu")
		(net "M_C_CPU1_SB_CA<6>")
	)
	(arc
		(start 87.357966 -264.688828)
		(mid 87.640922 -264.612651)
		(end 87.923878 -264.688828)
		(width 0.0889)
		(layer "In2.Cu")
		(net "M_C_CPU1_SB_CA<6>")
	)
	(arc
		(start 82.658204 -264.688828)
		(mid 82.94116 -264.612651)
		(end 83.224116 -264.688828)
		(width 0.0889)
		(layer "In2.Cu")
		(net "M_C_CPU1_SB_CA<6>")
	)
	(arc
		(start 79.467202 -264.688828)
		(mid 79.641052 -264.738734)
		(end 79.817976 -264.70102)
		(width 0.0889)
		(layer "In2.Cu")
		(net "M_C_CPU1_SB_CA<6>")
	)
	(arc
		(start 78.899512 -264.688828)
		(mid 79.167481 -264.612005)
		(end 79.439516 -264.672826)
		(width 0.0889)
		(layer "In2.Cu")
		(net "M_C_CPU1_SB_CA<6>")
	)
	(arc
		(start 93.563948 -264.688828)
		(mid 93.746199 -264.739178)
		(end 93.929708 -264.693654)
		(width 0.0889)
		(layer "In2.Cu")
		(net "M_C_CPU1_SB_CA<6>")
	)
	(arc
		(start 91.684094 -264.688828)
		(mid 91.871038 -264.739083)
		(end 92.057982 -264.688828)
		(width 0.0889)
		(layer "In2.Cu")
		(net "M_C_CPU1_SB_CA<6>")
	)
	(arc
		(start 92.623894 -264.688828)
		(mid 92.806145 -264.739178)
		(end 92.989654 -264.693654)
		(width 0.0889)
		(layer "In2.Cu")
		(net "M_C_CPU1_SB_CA<6>")
	)
	(arc
		(start 81.71815 -264.688828)
		(mid 82.001106 -264.612651)
		(end 82.284062 -264.688828)
		(width 0.0889)
		(layer "In2.Cu")
		(net "M_C_CPU1_SB_CA<6>")
	)
	(arc
		(start 79.863696 -264.674604)
		(mid 80.135633 -264.612778)
		(end 80.403954 -264.688828)
		(width 0.0889)
		(layer "In2.Cu")
		(net "M_C_CPU1_SB_CA<6>")
	)
	(arc
		(start 91.118182 -264.688828)
		(mid 91.401138 -264.612651)
		(end 91.684094 -264.688828)
		(width 0.0889)
		(layer "In2.Cu")
		(net "M_C_CPU1_SB_CA<6>")
	)
	(arc
		(start 93.93809 -264.688828)
		(mid 94.185803 -264.613608)
		(end 94.44101 -264.657078)
		(width 0.0889)
		(layer "In2.Cu")
		(net "M_C_CPU1_SB_CA<6>")
	)
	(arc
		(start 81.35239 -264.693654)
		(mid 81.535898 -264.739148)
		(end 81.71815 -264.688828)
		(width 0.0889)
		(layer "In2.Cu")
		(net "M_C_CPU1_SB_CA<6>")
	)
	(arc
		(start 90.178128 -264.688828)
		(mid 90.461084 -264.612651)
		(end 90.74404 -264.688828)
		(width 0.0889)
		(layer "In2.Cu")
		(net "M_C_CPU1_SB_CA<6>")
	)
	(arc
		(start 84.538058 -264.688828)
		(mid 84.821014 -264.612651)
		(end 85.10397 -264.688828)
		(width 0.0889)
		(layer "In2.Cu")
		(net "M_C_CPU1_SB_CA<6>")
	)
	(arc
		(start 88.863932 -264.688828)
		(mid 89.046183 -264.739178)
		(end 89.229692 -264.693654)
		(width 0.0889)
		(layer "In2.Cu")
		(net "M_C_CPU1_SB_CA<6>")
	)
	(arc
		(start 89.238074 -264.688828)
		(mid 89.52103 -264.612651)
		(end 89.803986 -264.688828)
		(width 0.0889)
		(layer "In2.Cu")
		(net "M_C_CPU1_SB_CA<6>")
	)
	(arc
		(start 80.778096 -264.688828)
		(mid 81.061052 -264.612651)
		(end 81.344008 -264.688828)
		(width 0.0889)
		(layer "In2.Cu")
		(net "M_C_CPU1_SB_CA<6>")
	)
	(arc
		(start 82.292444 -264.693654)
		(mid 82.475952 -264.739148)
		(end 82.658204 -264.688828)
		(width 0.0889)
		(layer "In2.Cu")
		(net "M_C_CPU1_SB_CA<6>")
	)
	(arc
		(start 89.812368 -264.693654)
		(mid 89.995876 -264.739148)
		(end 90.178128 -264.688828)
		(width 0.0889)
		(layer "In2.Cu")
		(net "M_C_CPU1_SB_CA<6>")
	)
	(arc
		(start 85.478112 -264.688828)
		(mid 85.761068 -264.612651)
		(end 86.044024 -264.688828)
		(width 0.0889)
		(layer "In2.Cu")
		(net "M_C_CPU1_SB_CA<6>")
	)
	(arc
		(start 86.052406 -264.693654)
		(mid 86.235914 -264.739148)
		(end 86.418166 -264.688828)
		(width 0.0889)
		(layer "In2.Cu")
		(net "M_C_CPU1_SB_CA<6>")
	)
	(segment
		(start 96.097852 -264.10031)
		(end 95.631 -264.366248)
		(width 0.10668)
		(layer "F.Cu")
		(net "M_C_CPU1_SB_CA<5>")
	)
	(segment
		(start 79.816706 -264.03046)
		(end 79.840074 -264.043922)
		(width 0.0889)
		(layer "In2.Cu")
		(net "M_C_CPU1_SB_CA<5>")
	)
	(segment
		(start 76.509118 -263.948672)
		(end 78.5495 -263.948672)
		(width 0.0889)
		(layer "In2.Cu")
		(net "M_C_CPU1_SB_CA<5>")
	)
	(segment
		(start 89.803986 -264.043668)
		(end 89.812368 -264.038842)
		(width 0.0889)
		(layer "In2.Cu")
		(net "M_C_CPU1_SB_CA<5>")
	)
	(segment
		(start 95.444056 -264.043668)
		(end 95.452438 -264.038842)
		(width 0.0889)
		(layer "In2.Cu")
		(net "M_C_CPU1_SB_CA<5>")
	)
	(segment
		(start 81.344008 -264.043668)
		(end 81.35239 -264.038842)
		(width 0.0889)
		(layer "In2.Cu")
		(net "M_C_CPU1_SB_CA<5>")
	)
	(segment
		(start 41.69029 -264.747502)
		(end 41.69029 -264.390378)
		(width 0.14478)
		(layer "In2.Cu")
		(net "M_C_CPU1_SB_CA<5>")
	)
	(segment
		(start 88.289638 -264.038842)
		(end 88.29802 -264.043668)
		(width 0.0889)
		(layer "In2.Cu")
		(net "M_C_CPU1_SB_CA<5>")
	)
	(segment
		(start 41.69029 -264.390378)
		(end 41.853104 -264.227564)
		(width 0.14478)
		(layer "In2.Cu")
		(net "M_C_CPU1_SB_CA<5>")
	)
	(segment
		(start 75.947016 -264.165334)
		(end 76.292456 -264.165334)
		(width 0.0889)
		(layer "In2.Cu")
		(net "M_C_CPU1_SB_CA<5>")
	)
	(segment
		(start 95.785178 -264.100818)
		(end 95.631 -264.366248)
		(width 0.0889)
		(layer "In2.Cu")
		(net "M_C_CPU1_SB_CA<5>")
	)
	(segment
		(start 76.292456 -264.165334)
		(end 76.509118 -263.948672)
		(width 0.0889)
		(layer "In2.Cu")
		(net "M_C_CPU1_SB_CA<5>")
	)
	(segment
		(start 40.23995 -265.335258)
		(end 40.664892 -264.910316)
		(width 0.14478)
		(layer "In2.Cu")
		(net "M_C_CPU1_SB_CA<5>")
	)
	(segment
		(start 79.840074 -264.043922)
		(end 79.866236 -264.058908)
		(width 0.0889)
		(layer "In2.Cu")
		(net "M_C_CPU1_SB_CA<5>")
	)
	(segment
		(start 80.769714 -264.038842)
		(end 80.778096 -264.043668)
		(width 0.0889)
		(layer "In2.Cu")
		(net "M_C_CPU1_SB_CA<5>")
	)
	(segment
		(start 94.504002 -264.043668)
		(end 94.512384 -264.038842)
		(width 0.0889)
		(layer "In2.Cu")
		(net "M_C_CPU1_SB_CA<5>")
	)
	(segment
		(start 95.762826 -264.017506)
		(end 95.785178 -264.100818)
		(width 0.0889)
		(layer "In2.Cu")
		(net "M_C_CPU1_SB_CA<5>")
	)
	(segment
		(start 41.527476 -264.910316)
		(end 41.69029 -264.747502)
		(width 0.14478)
		(layer "In2.Cu")
		(net "M_C_CPU1_SB_CA<5>")
	)
	(segment
		(start 60.948062 -264.165334)
		(end 75.947016 -264.165334)
		(width 0.14478)
		(layer "In2.Cu")
		(net "M_C_CPU1_SB_CA<5>")
	)
	(segment
		(start 93.929708 -264.038842)
		(end 93.93809 -264.043668)
		(width 0.0889)
		(layer "In2.Cu")
		(net "M_C_CPU1_SB_CA<5>")
	)
	(segment
		(start 42.409364 -264.910316)
		(end 60.20308 -264.910316)
		(width 0.14478)
		(layer "In2.Cu")
		(net "M_C_CPU1_SB_CA<5>")
	)
	(segment
		(start 86.044024 -264.043668)
		(end 86.052406 -264.038842)
		(width 0.0889)
		(layer "In2.Cu")
		(net "M_C_CPU1_SB_CA<5>")
	)
	(segment
		(start 89.229692 -264.038842)
		(end 89.238074 -264.043668)
		(width 0.0889)
		(layer "In2.Cu")
		(net "M_C_CPU1_SB_CA<5>")
	)
	(segment
		(start 83.589622 -264.038842)
		(end 83.598004 -264.043668)
		(width 0.0889)
		(layer "In2.Cu")
		(net "M_C_CPU1_SB_CA<5>")
	)
	(segment
		(start 90.74404 -264.043668)
		(end 90.752422 -264.038842)
		(width 0.0889)
		(layer "In2.Cu")
		(net "M_C_CPU1_SB_CA<5>")
	)
	(segment
		(start 60.20308 -264.910316)
		(end 60.948062 -264.165334)
		(width 0.14478)
		(layer "In2.Cu")
		(net "M_C_CPU1_SB_CA<5>")
	)
	(segment
		(start 40.664892 -264.910316)
		(end 41.527476 -264.910316)
		(width 0.14478)
		(layer "In2.Cu")
		(net "M_C_CPU1_SB_CA<5>")
	)
	(segment
		(start 42.24655 -264.747502)
		(end 42.409364 -264.910316)
		(width 0.14478)
		(layer "In2.Cu")
		(net "M_C_CPU1_SB_CA<5>")
	)
	(segment
		(start 92.989654 -264.038842)
		(end 92.998036 -264.043668)
		(width 0.0889)
		(layer "In2.Cu")
		(net "M_C_CPU1_SB_CA<5>")
	)
	(segment
		(start 79.438246 -264.06094)
		(end 79.46771 -264.043668)
		(width 0.0889)
		(layer "In2.Cu")
		(net "M_C_CPU1_SB_CA<5>")
	)
	(segment
		(start 85.10397 -264.043668)
		(end 85.112352 -264.038842)
		(width 0.0889)
		(layer "In2.Cu")
		(net "M_C_CPU1_SB_CA<5>")
	)
	(segment
		(start 84.529676 -264.038842)
		(end 84.538058 -264.043668)
		(width 0.0889)
		(layer "In2.Cu")
		(net "M_C_CPU1_SB_CA<5>")
	)
	(segment
		(start 42.24655 -264.390378)
		(end 42.24655 -264.747502)
		(width 0.14478)
		(layer "In2.Cu")
		(net "M_C_CPU1_SB_CA<5>")
	)
	(segment
		(start 41.853104 -264.227564)
		(end 42.083736 -264.227564)
		(width 0.14478)
		(layer "In2.Cu")
		(net "M_C_CPU1_SB_CA<5>")
	)
	(segment
		(start 42.083736 -264.227564)
		(end 42.24655 -264.390378)
		(width 0.14478)
		(layer "In2.Cu")
		(net "M_C_CPU1_SB_CA<5>")
	)
	(arc
		(start 88.863932 -264.043668)
		(mid 89.046183 -263.993318)
		(end 89.229692 -264.038842)
		(width 0.0889)
		(layer "In2.Cu")
		(net "M_C_CPU1_SB_CA<5>")
	)
	(arc
		(start 82.284062 -264.043668)
		(mid 82.471006 -263.993413)
		(end 82.65795 -264.043668)
		(width 0.0889)
		(layer "In2.Cu")
		(net "M_C_CPU1_SB_CA<5>")
	)
	(arc
		(start 93.93809 -264.043668)
		(mid 94.221046 -264.119845)
		(end 94.504002 -264.043668)
		(width 0.0889)
		(layer "In2.Cu")
		(net "M_C_CPU1_SB_CA<5>")
	)
	(arc
		(start 86.984078 -264.043668)
		(mid 87.171022 -263.993413)
		(end 87.357966 -264.043668)
		(width 0.0889)
		(layer "In2.Cu")
		(net "M_C_CPU1_SB_CA<5>")
	)
	(arc
		(start 82.65795 -264.043668)
		(mid 82.940906 -264.119845)
		(end 83.223862 -264.043668)
		(width 0.0889)
		(layer "In2.Cu")
		(net "M_C_CPU1_SB_CA<5>")
	)
	(arc
		(start 89.812368 -264.038842)
		(mid 89.995876 -263.993348)
		(end 90.178128 -264.043668)
		(width 0.0889)
		(layer "In2.Cu")
		(net "M_C_CPU1_SB_CA<5>")
	)
	(arc
		(start 85.112352 -264.038842)
		(mid 85.29586 -263.993348)
		(end 85.478112 -264.043668)
		(width 0.0889)
		(layer "In2.Cu")
		(net "M_C_CPU1_SB_CA<5>")
	)
	(arc
		(start 79.46771 -264.043668)
		(mid 79.640565 -263.993679)
		(end 79.816706 -264.03046)
		(width 0.0889)
		(layer "In2.Cu")
		(net "M_C_CPU1_SB_CA<5>")
	)
	(arc
		(start 92.998036 -264.043668)
		(mid 93.280992 -264.119845)
		(end 93.563948 -264.043668)
		(width 0.0889)
		(layer "In2.Cu")
		(net "M_C_CPU1_SB_CA<5>")
	)
	(arc
		(start 95.452438 -264.038842)
		(mid 95.605308 -263.994201)
		(end 95.762826 -264.017506)
		(width 0.0889)
		(layer "In2.Cu")
		(net "M_C_CPU1_SB_CA<5>")
	)
	(arc
		(start 81.35239 -264.038842)
		(mid 81.535898 -263.993348)
		(end 81.71815 -264.043668)
		(width 0.0889)
		(layer "In2.Cu")
		(net "M_C_CPU1_SB_CA<5>")
	)
	(arc
		(start 78.899766 -264.043668)
		(mid 79.166823 -264.120703)
		(end 79.438246 -264.06094)
		(width 0.0889)
		(layer "In2.Cu")
		(net "M_C_CPU1_SB_CA<5>")
	)
	(arc
		(start 79.866236 -264.058908)
		(mid 80.137022 -264.119554)
		(end 80.403954 -264.043668)
		(width 0.0889)
		(layer "In2.Cu")
		(net "M_C_CPU1_SB_CA<5>")
	)
	(arc
		(start 88.29802 -264.043668)
		(mid 88.580976 -264.119845)
		(end 88.863932 -264.043668)
		(width 0.0889)
		(layer "In2.Cu")
		(net "M_C_CPU1_SB_CA<5>")
	)
	(arc
		(start 80.778096 -264.043668)
		(mid 81.061052 -264.119845)
		(end 81.344008 -264.043668)
		(width 0.0889)
		(layer "In2.Cu")
		(net "M_C_CPU1_SB_CA<5>")
	)
	(arc
		(start 93.563948 -264.043668)
		(mid 93.746199 -263.993318)
		(end 93.929708 -264.038842)
		(width 0.0889)
		(layer "In2.Cu")
		(net "M_C_CPU1_SB_CA<5>")
	)
	(arc
		(start 91.118182 -264.043668)
		(mid 91.401138 -264.119845)
		(end 91.684094 -264.043668)
		(width 0.0889)
		(layer "In2.Cu")
		(net "M_C_CPU1_SB_CA<5>")
	)
	(arc
		(start 86.052406 -264.038842)
		(mid 86.235914 -263.993348)
		(end 86.418166 -264.043668)
		(width 0.0889)
		(layer "In2.Cu")
		(net "M_C_CPU1_SB_CA<5>")
	)
	(arc
		(start 86.418166 -264.043668)
		(mid 86.701122 -264.119845)
		(end 86.984078 -264.043668)
		(width 0.0889)
		(layer "In2.Cu")
		(net "M_C_CPU1_SB_CA<5>")
	)
	(arc
		(start 87.357966 -264.043668)
		(mid 87.640922 -264.119845)
		(end 87.923878 -264.043668)
		(width 0.0889)
		(layer "In2.Cu")
		(net "M_C_CPU1_SB_CA<5>")
	)
	(arc
		(start 89.238074 -264.043668)
		(mid 89.52103 -264.119845)
		(end 89.803986 -264.043668)
		(width 0.0889)
		(layer "In2.Cu")
		(net "M_C_CPU1_SB_CA<5>")
	)
	(arc
		(start 94.878144 -264.043668)
		(mid 95.1611 -264.119845)
		(end 95.444056 -264.043668)
		(width 0.0889)
		(layer "In2.Cu")
		(net "M_C_CPU1_SB_CA<5>")
	)
	(arc
		(start 80.403954 -264.043668)
		(mid 80.586205 -263.993318)
		(end 80.769714 -264.038842)
		(width 0.0889)
		(layer "In2.Cu")
		(net "M_C_CPU1_SB_CA<5>")
	)
	(arc
		(start 87.923878 -264.043668)
		(mid 88.106129 -263.993318)
		(end 88.289638 -264.038842)
		(width 0.0889)
		(layer "In2.Cu")
		(net "M_C_CPU1_SB_CA<5>")
	)
	(arc
		(start 83.598004 -264.043668)
		(mid 83.88096 -264.119845)
		(end 84.163916 -264.043668)
		(width 0.0889)
		(layer "In2.Cu")
		(net "M_C_CPU1_SB_CA<5>")
	)
	(arc
		(start 85.478112 -264.043668)
		(mid 85.761068 -264.119845)
		(end 86.044024 -264.043668)
		(width 0.0889)
		(layer "In2.Cu")
		(net "M_C_CPU1_SB_CA<5>")
	)
	(arc
		(start 84.163916 -264.043668)
		(mid 84.346167 -263.993318)
		(end 84.529676 -264.038842)
		(width 0.0889)
		(layer "In2.Cu")
		(net "M_C_CPU1_SB_CA<5>")
	)
	(arc
		(start 92.057982 -264.043668)
		(mid 92.340938 -264.119845)
		(end 92.623894 -264.043668)
		(width 0.0889)
		(layer "In2.Cu")
		(net "M_C_CPU1_SB_CA<5>")
	)
	(arc
		(start 81.71815 -264.043668)
		(mid 82.001106 -264.119845)
		(end 82.284062 -264.043668)
		(width 0.0889)
		(layer "In2.Cu")
		(net "M_C_CPU1_SB_CA<5>")
	)
	(arc
		(start 90.752422 -264.038842)
		(mid 90.93593 -263.993348)
		(end 91.118182 -264.043668)
		(width 0.0889)
		(layer "In2.Cu")
		(net "M_C_CPU1_SB_CA<5>")
	)
	(arc
		(start 94.512384 -264.038842)
		(mid 94.695892 -263.993348)
		(end 94.878144 -264.043668)
		(width 0.0889)
		(layer "In2.Cu")
		(net "M_C_CPU1_SB_CA<5>")
	)
	(arc
		(start 78.5495 -263.948672)
		(mid 78.730967 -263.972829)
		(end 78.899766 -264.043668)
		(width 0.0889)
		(layer "In2.Cu")
		(net "M_C_CPU1_SB_CA<5>")
	)
	(arc
		(start 92.623894 -264.043668)
		(mid 92.806145 -263.993318)
		(end 92.989654 -264.038842)
		(width 0.0889)
		(layer "In2.Cu")
		(net "M_C_CPU1_SB_CA<5>")
	)
	(arc
		(start 91.684094 -264.043668)
		(mid 91.871038 -263.993413)
		(end 92.057982 -264.043668)
		(width 0.0889)
		(layer "In2.Cu")
		(net "M_C_CPU1_SB_CA<5>")
	)
	(arc
		(start 90.178128 -264.043668)
		(mid 90.461084 -264.119845)
		(end 90.74404 -264.043668)
		(width 0.0889)
		(layer "In2.Cu")
		(net "M_C_CPU1_SB_CA<5>")
	)
	(arc
		(start 84.538058 -264.043668)
		(mid 84.821014 -264.119845)
		(end 85.10397 -264.043668)
		(width 0.0889)
		(layer "In2.Cu")
		(net "M_C_CPU1_SB_CA<5>")
	)
	(arc
		(start 83.223862 -264.043668)
		(mid 83.406113 -263.993318)
		(end 83.589622 -264.038842)
		(width 0.0889)
		(layer "In2.Cu")
		(net "M_C_CPU1_SB_CA<5>")
	)
	(segment
		(start 96.568006 -263.290304)
		(end 96.101154 -263.556242)
		(width 0.10668)
		(layer "F.Cu")
		(net "M_C_CPU1_SB_CA<4>")
	)
	(segment
		(start 79.909416 -263.863582)
		(end 79.935578 -263.878568)
		(width 0.0889)
		(layer "In2.Cu")
		(net "M_C_CPU1_SB_CA<4>")
	)
	(segment
		(start 53.038756 -263.831578)
		(end 53.038756 -264.288778)
		(width 0.14478)
		(layer "In2.Cu")
		(net "M_C_CPU1_SB_CA<4>")
	)
	(segment
		(start 50.531522 -263.689592)
		(end 50.762154 -263.689592)
		(width 0.14478)
		(layer "In2.Cu")
		(net "M_C_CPU1_SB_CA<4>")
	)
	(segment
		(start 46.45533 -263.668764)
		(end 46.846744 -264.060178)
		(width 0.14478)
		(layer "In2.Cu")
		(net "M_C_CPU1_SB_CA<4>")
	)
	(segment
		(start 53.038756 -264.288778)
		(end 53.20157 -264.451592)
		(width 0.14478)
		(layer "In2.Cu")
		(net "M_C_CPU1_SB_CA<4>")
	)
	(segment
		(start 60.268358 -264.060178)
		(end 60.617862 -263.710674)
		(width 0.14478)
		(layer "In2.Cu")
		(net "M_C_CPU1_SB_CA<4>")
	)
	(segment
		(start 60.617862 -263.710674)
		(end 75.953366 -263.710674)
		(width 0.14478)
		(layer "In2.Cu")
		(net "M_C_CPU1_SB_CA<4>")
	)
	(segment
		(start 46.061884 -264.288778)
		(end 46.061884 -263.831578)
		(width 0.14478)
		(layer "In2.Cu")
		(net "M_C_CPU1_SB_CA<4>")
	)
	(segment
		(start 46.846744 -264.060178)
		(end 48.492156 -264.060178)
		(width 0.14478)
		(layer "In2.Cu")
		(net "M_C_CPU1_SB_CA<4>")
	)
	(segment
		(start 50.368708 -263.852406)
		(end 50.531522 -263.689592)
		(width 0.14478)
		(layer "In2.Cu")
		(net "M_C_CPU1_SB_CA<4>")
	)
	(segment
		(start 53.595016 -264.288778)
		(end 53.595016 -263.831578)
		(width 0.14478)
		(layer "In2.Cu")
		(net "M_C_CPU1_SB_CA<4>")
	)
	(segment
		(start 79.935578 -263.878568)
		(end 79.96047 -263.892792)
		(width 0.0889)
		(layer "In2.Cu")
		(net "M_C_CPU1_SB_CA<4>")
	)
	(segment
		(start 88.394032 -263.878822)
		(end 88.402414 -263.883648)
		(width 0.0889)
		(layer "In2.Cu")
		(net "M_C_CPU1_SB_CA<4>")
	)
	(segment
		(start 86.879684 -263.883648)
		(end 86.888066 -263.878822)
		(width 0.0889)
		(layer "In2.Cu")
		(net "M_C_CPU1_SB_CA<4>")
	)
	(segment
		(start 45.143674 -263.681718)
		(end 45.355764 -263.681718)
		(width 0.14478)
		(layer "In2.Cu")
		(net "M_C_CPU1_SB_CA<4>")
	)
	(segment
		(start 49.975262 -264.430764)
		(end 50.205894 -264.430764)
		(width 0.14478)
		(layer "In2.Cu")
		(net "M_C_CPU1_SB_CA<4>")
	)
	(segment
		(start 75.953366 -263.710674)
		(end 78.604618 -263.710674)
		(width 0.0889)
		(layer "In2.Cu")
		(net "M_C_CPU1_SB_CA<4>")
	)
	(segment
		(start 46.224698 -263.668764)
		(end 46.45533 -263.668764)
		(width 0.14478)
		(layer "In2.Cu")
		(net "M_C_CPU1_SB_CA<4>")
	)
	(segment
		(start 49.093374 -264.430764)
		(end 49.256188 -264.26795)
		(width 0.14478)
		(layer "In2.Cu")
		(net "M_C_CPU1_SB_CA<4>")
	)
	(segment
		(start 45.505624 -263.831578)
		(end 45.505624 -264.288778)
		(width 0.14478)
		(layer "In2.Cu")
		(net "M_C_CPU1_SB_CA<4>")
	)
	(segment
		(start 54.31409 -264.451592)
		(end 54.714902 -264.451592)
		(width 0.14478)
		(layer "In2.Cu")
		(net "M_C_CPU1_SB_CA<4>")
	)
	(segment
		(start 51.13274 -264.060178)
		(end 52.253896 -264.060178)
		(width 0.14478)
		(layer "In2.Cu")
		(net "M_C_CPU1_SB_CA<4>")
	)
	(segment
		(start 46.061884 -263.831578)
		(end 46.224698 -263.668764)
		(width 0.14478)
		(layer "In2.Cu")
		(net "M_C_CPU1_SB_CA<4>")
	)
	(segment
		(start 49.256188 -264.26795)
		(end 49.256188 -263.852406)
		(width 0.14478)
		(layer "In2.Cu")
		(net "M_C_CPU1_SB_CA<4>")
	)
	(segment
		(start 53.595016 -263.831578)
		(end 53.75783 -263.668764)
		(width 0.14478)
		(layer "In2.Cu")
		(net "M_C_CPU1_SB_CA<4>")
	)
	(segment
		(start 53.20157 -264.451592)
		(end 53.432202 -264.451592)
		(width 0.14478)
		(layer "In2.Cu")
		(net "M_C_CPU1_SB_CA<4>")
	)
	(segment
		(start 49.649634 -263.689592)
		(end 49.812448 -263.852406)
		(width 0.14478)
		(layer "In2.Cu")
		(net "M_C_CPU1_SB_CA<4>")
	)
	(segment
		(start 50.368708 -264.26795)
		(end 50.368708 -263.852406)
		(width 0.14478)
		(layer "In2.Cu")
		(net "M_C_CPU1_SB_CA<4>")
	)
	(segment
		(start 95.946976 -263.821672)
		(end 96.101154 -263.556242)
		(width 0.0889)
		(layer "In2.Cu")
		(net "M_C_CPU1_SB_CA<4>")
	)
	(segment
		(start 53.432202 -264.451592)
		(end 53.595016 -264.288778)
		(width 0.14478)
		(layer "In2.Cu")
		(net "M_C_CPU1_SB_CA<4>")
	)
	(segment
		(start 82.179668 -263.883648)
		(end 82.18805 -263.878822)
		(width 0.0889)
		(layer "In2.Cu")
		(net "M_C_CPU1_SB_CA<4>")
	)
	(segment
		(start 54.151276 -264.288778)
		(end 54.31409 -264.451592)
		(width 0.14478)
		(layer "In2.Cu")
		(net "M_C_CPU1_SB_CA<4>")
	)
	(segment
		(start 45.89907 -264.451592)
		(end 46.061884 -264.288778)
		(width 0.14478)
		(layer "In2.Cu")
		(net "M_C_CPU1_SB_CA<4>")
	)
	(segment
		(start 93.094048 -263.878822)
		(end 93.10243 -263.883648)
		(width 0.0889)
		(layer "In2.Cu")
		(net "M_C_CPU1_SB_CA<4>")
	)
	(segment
		(start 48.492156 -264.060178)
		(end 48.862742 -264.430764)
		(width 0.14478)
		(layer "In2.Cu")
		(net "M_C_CPU1_SB_CA<4>")
	)
	(segment
		(start 85.93963 -263.883648)
		(end 85.948012 -263.878822)
		(width 0.0889)
		(layer "In2.Cu")
		(net "M_C_CPU1_SB_CA<4>")
	)
	(segment
		(start 55.106316 -264.060178)
		(end 60.268358 -264.060178)
		(width 0.14478)
		(layer "In2.Cu")
		(net "M_C_CPU1_SB_CA<4>")
	)
	(segment
		(start 82.753962 -263.878822)
		(end 82.762344 -263.883648)
		(width 0.0889)
		(layer "In2.Cu")
		(net "M_C_CPU1_SB_CA<4>")
	)
	(segment
		(start 78.985618 -263.868662)
		(end 78.996032 -263.878822)
		(width 0.0889)
		(layer "In2.Cu")
		(net "M_C_CPU1_SB_CA<4>")
	)
	(segment
		(start 44.340018 -264.485374)
		(end 45.143674 -263.681718)
		(width 0.14478)
		(layer "In2.Cu")
		(net "M_C_CPU1_SB_CA<4>")
	)
	(segment
		(start 50.205894 -264.430764)
		(end 50.368708 -264.26795)
		(width 0.14478)
		(layer "In2.Cu")
		(net "M_C_CPU1_SB_CA<4>")
	)
	(segment
		(start 52.64531 -263.668764)
		(end 52.875942 -263.668764)
		(width 0.14478)
		(layer "In2.Cu")
		(net "M_C_CPU1_SB_CA<4>")
	)
	(segment
		(start 45.355764 -263.681718)
		(end 45.505624 -263.831578)
		(width 0.14478)
		(layer "In2.Cu")
		(net "M_C_CPU1_SB_CA<4>")
	)
	(segment
		(start 53.988462 -263.668764)
		(end 54.151276 -263.831578)
		(width 0.14478)
		(layer "In2.Cu")
		(net "M_C_CPU1_SB_CA<4>")
	)
	(segment
		(start 52.253896 -264.060178)
		(end 52.64531 -263.668764)
		(width 0.14478)
		(layer "In2.Cu")
		(net "M_C_CPU1_SB_CA<4>")
	)
	(segment
		(start 91.5797 -263.883648)
		(end 91.588082 -263.878822)
		(width 0.0889)
		(layer "In2.Cu")
		(net "M_C_CPU1_SB_CA<4>")
	)
	(segment
		(start 49.256188 -263.852406)
		(end 49.419002 -263.689592)
		(width 0.14478)
		(layer "In2.Cu")
		(net "M_C_CPU1_SB_CA<4>")
	)
	(segment
		(start 95.339662 -263.883648)
		(end 95.348044 -263.878822)
		(width 0.0889)
		(layer "In2.Cu")
		(net "M_C_CPU1_SB_CA<4>")
	)
	(segment
		(start 92.153994 -263.878822)
		(end 92.162376 -263.883648)
		(width 0.0889)
		(layer "In2.Cu")
		(net "M_C_CPU1_SB_CA<4>")
	)
	(segment
		(start 90.639646 -263.883648)
		(end 90.648028 -263.878822)
		(width 0.0889)
		(layer "In2.Cu")
		(net "M_C_CPU1_SB_CA<4>")
	)
	(segment
		(start 79.349346 -263.891776)
		(end 79.371698 -263.878822)
		(width 0.0889)
		(layer "In2.Cu")
		(net "M_C_CPU1_SB_CA<4>")
	)
	(segment
		(start 54.714902 -264.451592)
		(end 55.106316 -264.060178)
		(width 0.14478)
		(layer "In2.Cu")
		(net "M_C_CPU1_SB_CA<4>")
	)
	(segment
		(start 53.75783 -263.668764)
		(end 53.988462 -263.668764)
		(width 0.14478)
		(layer "In2.Cu")
		(net "M_C_CPU1_SB_CA<4>")
	)
	(segment
		(start 49.419002 -263.689592)
		(end 49.649634 -263.689592)
		(width 0.14478)
		(layer "In2.Cu")
		(net "M_C_CPU1_SB_CA<4>")
	)
	(segment
		(start 52.875942 -263.668764)
		(end 53.038756 -263.831578)
		(width 0.14478)
		(layer "In2.Cu")
		(net "M_C_CPU1_SB_CA<4>")
	)
	(segment
		(start 87.453978 -263.878822)
		(end 87.46236 -263.883648)
		(width 0.0889)
		(layer "In2.Cu")
		(net "M_C_CPU1_SB_CA<4>")
	)
	(segment
		(start 95.85071 -263.847072)
		(end 95.946976 -263.821672)
		(width 0.0889)
		(layer "In2.Cu")
		(net "M_C_CPU1_SB_CA<4>")
	)
	(segment
		(start 49.812448 -264.26795)
		(end 49.975262 -264.430764)
		(width 0.14478)
		(layer "In2.Cu")
		(net "M_C_CPU1_SB_CA<4>")
	)
	(segment
		(start 83.694016 -263.878822)
		(end 83.702398 -263.883648)
		(width 0.0889)
		(layer "In2.Cu")
		(net "M_C_CPU1_SB_CA<4>")
	)
	(segment
		(start 50.762154 -263.689592)
		(end 51.13274 -264.060178)
		(width 0.14478)
		(layer "In2.Cu")
		(net "M_C_CPU1_SB_CA<4>")
	)
	(segment
		(start 45.668438 -264.451592)
		(end 45.89907 -264.451592)
		(width 0.14478)
		(layer "In2.Cu")
		(net "M_C_CPU1_SB_CA<4>")
	)
	(segment
		(start 45.505624 -264.288778)
		(end 45.668438 -264.451592)
		(width 0.14478)
		(layer "In2.Cu")
		(net "M_C_CPU1_SB_CA<4>")
	)
	(segment
		(start 54.151276 -263.831578)
		(end 54.151276 -264.288778)
		(width 0.14478)
		(layer "In2.Cu")
		(net "M_C_CPU1_SB_CA<4>")
	)
	(segment
		(start 49.812448 -263.852406)
		(end 49.812448 -264.26795)
		(width 0.14478)
		(layer "In2.Cu")
		(net "M_C_CPU1_SB_CA<4>")
	)
	(segment
		(start 48.862742 -264.430764)
		(end 49.093374 -264.430764)
		(width 0.14478)
		(layer "In2.Cu")
		(net "M_C_CPU1_SB_CA<4>")
	)
	(arc
		(start 82.18805 -263.878822)
		(mid 82.471006 -263.802645)
		(end 82.753962 -263.878822)
		(width 0.0889)
		(layer "In2.Cu")
		(net "M_C_CPU1_SB_CA<4>")
	)
	(arc
		(start 88.768174 -263.878822)
		(mid 89.05113 -263.802645)
		(end 89.334086 -263.878822)
		(width 0.0889)
		(layer "In2.Cu")
		(net "M_C_CPU1_SB_CA<4>")
	)
	(arc
		(start 93.46819 -263.878822)
		(mid 93.751146 -263.802645)
		(end 94.034102 -263.878822)
		(width 0.0889)
		(layer "In2.Cu")
		(net "M_C_CPU1_SB_CA<4>")
	)
	(arc
		(start 84.63407 -263.878822)
		(mid 84.821014 -263.929077)
		(end 85.007958 -263.878822)
		(width 0.0889)
		(layer "In2.Cu")
		(net "M_C_CPU1_SB_CA<4>")
	)
	(arc
		(start 87.82812 -263.878822)
		(mid 88.111076 -263.802645)
		(end 88.394032 -263.878822)
		(width 0.0889)
		(layer "In2.Cu")
		(net "M_C_CPU1_SB_CA<4>")
	)
	(arc
		(start 91.588082 -263.878822)
		(mid 91.871038 -263.802645)
		(end 92.153994 -263.878822)
		(width 0.0889)
		(layer "In2.Cu")
		(net "M_C_CPU1_SB_CA<4>")
	)
	(arc
		(start 94.973902 -263.878822)
		(mid 95.156153 -263.929172)
		(end 95.339662 -263.883648)
		(width 0.0889)
		(layer "In2.Cu")
		(net "M_C_CPU1_SB_CA<4>")
	)
	(arc
		(start 85.57387 -263.878822)
		(mid 85.756121 -263.929172)
		(end 85.93963 -263.883648)
		(width 0.0889)
		(layer "In2.Cu")
		(net "M_C_CPU1_SB_CA<4>")
	)
	(arc
		(start 87.46236 -263.883648)
		(mid 87.645868 -263.929142)
		(end 87.82812 -263.878822)
		(width 0.0889)
		(layer "In2.Cu")
		(net "M_C_CPU1_SB_CA<4>")
	)
	(arc
		(start 86.888066 -263.878822)
		(mid 87.171022 -263.802645)
		(end 87.453978 -263.878822)
		(width 0.0889)
		(layer "In2.Cu")
		(net "M_C_CPU1_SB_CA<4>")
	)
	(arc
		(start 80.874108 -263.878822)
		(mid 81.061052 -263.929077)
		(end 81.247996 -263.878822)
		(width 0.0889)
		(layer "In2.Cu")
		(net "M_C_CPU1_SB_CA<4>")
	)
	(arc
		(start 80.308196 -263.878822)
		(mid 80.591152 -263.802645)
		(end 80.874108 -263.878822)
		(width 0.0889)
		(layer "In2.Cu")
		(net "M_C_CPU1_SB_CA<4>")
	)
	(arc
		(start 86.513924 -263.878822)
		(mid 86.696175 -263.929172)
		(end 86.879684 -263.883648)
		(width 0.0889)
		(layer "In2.Cu")
		(net "M_C_CPU1_SB_CA<4>")
	)
	(arc
		(start 78.604618 -263.710674)
		(mid 78.810826 -263.751785)
		(end 78.985618 -263.868662)
		(width 0.0889)
		(layer "In2.Cu")
		(net "M_C_CPU1_SB_CA<4>")
	)
	(arc
		(start 81.813908 -263.878822)
		(mid 81.996159 -263.929172)
		(end 82.179668 -263.883648)
		(width 0.0889)
		(layer "In2.Cu")
		(net "M_C_CPU1_SB_CA<4>")
	)
	(arc
		(start 90.648028 -263.878822)
		(mid 90.930984 -263.802645)
		(end 91.21394 -263.878822)
		(width 0.0889)
		(layer "In2.Cu")
		(net "M_C_CPU1_SB_CA<4>")
	)
	(arc
		(start 94.034102 -263.878822)
		(mid 94.221046 -263.929077)
		(end 94.40799 -263.878822)
		(width 0.0889)
		(layer "In2.Cu")
		(net "M_C_CPU1_SB_CA<4>")
	)
	(arc
		(start 93.10243 -263.883648)
		(mid 93.285938 -263.929142)
		(end 93.46819 -263.878822)
		(width 0.0889)
		(layer "In2.Cu")
		(net "M_C_CPU1_SB_CA<4>")
	)
	(arc
		(start 84.068158 -263.878822)
		(mid 84.351114 -263.802645)
		(end 84.63407 -263.878822)
		(width 0.0889)
		(layer "In2.Cu")
		(net "M_C_CPU1_SB_CA<4>")
	)
	(arc
		(start 83.702398 -263.883648)
		(mid 83.885906 -263.929142)
		(end 84.068158 -263.878822)
		(width 0.0889)
		(layer "In2.Cu")
		(net "M_C_CPU1_SB_CA<4>")
	)
	(arc
		(start 85.948012 -263.878822)
		(mid 86.230968 -263.802645)
		(end 86.513924 -263.878822)
		(width 0.0889)
		(layer "In2.Cu")
		(net "M_C_CPU1_SB_CA<4>")
	)
	(arc
		(start 88.402414 -263.883648)
		(mid 88.585922 -263.929142)
		(end 88.768174 -263.878822)
		(width 0.0889)
		(layer "In2.Cu")
		(net "M_C_CPU1_SB_CA<4>")
	)
	(arc
		(start 89.707974 -263.878822)
		(mid 89.99093 -263.802645)
		(end 90.273886 -263.878822)
		(width 0.0889)
		(layer "In2.Cu")
		(net "M_C_CPU1_SB_CA<4>")
	)
	(arc
		(start 92.528136 -263.878822)
		(mid 92.811092 -263.802645)
		(end 93.094048 -263.878822)
		(width 0.0889)
		(layer "In2.Cu")
		(net "M_C_CPU1_SB_CA<4>")
	)
	(arc
		(start 92.162376 -263.883648)
		(mid 92.345884 -263.929142)
		(end 92.528136 -263.878822)
		(width 0.0889)
		(layer "In2.Cu")
		(net "M_C_CPU1_SB_CA<4>")
	)
	(arc
		(start 89.334086 -263.878822)
		(mid 89.52103 -263.929077)
		(end 89.707974 -263.878822)
		(width 0.0889)
		(layer "In2.Cu")
		(net "M_C_CPU1_SB_CA<4>")
	)
	(arc
		(start 83.128104 -263.878822)
		(mid 83.41106 -263.802645)
		(end 83.694016 -263.878822)
		(width 0.0889)
		(layer "In2.Cu")
		(net "M_C_CPU1_SB_CA<4>")
	)
	(arc
		(start 91.21394 -263.878822)
		(mid 91.396191 -263.929172)
		(end 91.5797 -263.883648)
		(width 0.0889)
		(layer "In2.Cu")
		(net "M_C_CPU1_SB_CA<4>")
	)
	(arc
		(start 79.371698 -263.878822)
		(mid 79.638628 -263.802873)
		(end 79.909416 -263.863582)
		(width 0.0889)
		(layer "In2.Cu")
		(net "M_C_CPU1_SB_CA<4>")
	)
	(arc
		(start 81.247996 -263.878822)
		(mid 81.530952 -263.802645)
		(end 81.813908 -263.878822)
		(width 0.0889)
		(layer "In2.Cu")
		(net "M_C_CPU1_SB_CA<4>")
	)
	(arc
		(start 79.96047 -263.892792)
		(mid 80.13605 -263.928812)
		(end 80.308196 -263.878822)
		(width 0.0889)
		(layer "In2.Cu")
		(net "M_C_CPU1_SB_CA<4>")
	)
	(arc
		(start 94.40799 -263.878822)
		(mid 94.690946 -263.802645)
		(end 94.973902 -263.878822)
		(width 0.0889)
		(layer "In2.Cu")
		(net "M_C_CPU1_SB_CA<4>")
	)
	(arc
		(start 85.007958 -263.878822)
		(mid 85.290914 -263.802645)
		(end 85.57387 -263.878822)
		(width 0.0889)
		(layer "In2.Cu")
		(net "M_C_CPU1_SB_CA<4>")
	)
	(arc
		(start 78.996032 -263.878822)
		(mid 79.17106 -263.929721)
		(end 79.349346 -263.891776)
		(width 0.0889)
		(layer "In2.Cu")
		(net "M_C_CPU1_SB_CA<4>")
	)
	(arc
		(start 82.762344 -263.883648)
		(mid 82.945852 -263.929142)
		(end 83.128104 -263.878822)
		(width 0.0889)
		(layer "In2.Cu")
		(net "M_C_CPU1_SB_CA<4>")
	)
	(arc
		(start 95.348044 -263.878822)
		(mid 95.59564 -263.803644)
		(end 95.85071 -263.847072)
		(width 0.0889)
		(layer "In2.Cu")
		(net "M_C_CPU1_SB_CA<4>")
	)
	(arc
		(start 90.273886 -263.878822)
		(mid 90.456137 -263.929172)
		(end 90.639646 -263.883648)
		(width 0.0889)
		(layer "In2.Cu")
		(net "M_C_CPU1_SB_CA<4>")
	)
	(segment
		(start 94.687898 -263.290304)
		(end 94.221046 -263.556242)
		(width 0.10668)
		(layer "F.Cu")
		(net "M_C_CPU1_SB_CA<3>")
	)
	(segment
		(start 78.030578 -262.884412)
		(end 78.311248 -263.165082)
		(width 0.0889)
		(layer "In2.Cu")
		(net "M_C_CPU1_SB_CA<3>")
	)
	(segment
		(start 85.93963 -263.228836)
		(end 85.948012 -263.233662)
		(width 0.0889)
		(layer "In2.Cu")
		(net "M_C_CPU1_SB_CA<3>")
	)
	(segment
		(start 40.23995 -263.635236)
		(end 40.664892 -263.210294)
		(width 0.14478)
		(layer "In2.Cu")
		(net "M_C_CPU1_SB_CA<3>")
	)
	(segment
		(start 93.094048 -263.233662)
		(end 93.10243 -263.228836)
		(width 0.0889)
		(layer "In2.Cu")
		(net "M_C_CPU1_SB_CA<3>")
	)
	(segment
		(start 90.639646 -263.228836)
		(end 90.648028 -263.233662)
		(width 0.0889)
		(layer "In2.Cu")
		(net "M_C_CPU1_SB_CA<3>")
	)
	(segment
		(start 82.753962 -263.233662)
		(end 82.762344 -263.228836)
		(width 0.0889)
		(layer "In2.Cu")
		(net "M_C_CPU1_SB_CA<3>")
	)
	(segment
		(start 78.311248 -263.165082)
		(end 78.464918 -263.254236)
		(width 0.0889)
		(layer "In2.Cu")
		(net "M_C_CPU1_SB_CA<3>")
	)
	(segment
		(start 94.37497 -263.290812)
		(end 94.221046 -263.556242)
		(width 0.0889)
		(layer "In2.Cu")
		(net "M_C_CPU1_SB_CA<3>")
	)
	(segment
		(start 83.694016 -263.233662)
		(end 83.702398 -263.228836)
		(width 0.0889)
		(layer "In2.Cu")
		(net "M_C_CPU1_SB_CA<3>")
	)
	(segment
		(start 94.352618 -263.2075)
		(end 94.37497 -263.290812)
		(width 0.0889)
		(layer "In2.Cu")
		(net "M_C_CPU1_SB_CA<3>")
	)
	(segment
		(start 40.664892 -263.210294)
		(end 75.966066 -263.210294)
		(width 0.14478)
		(layer "In2.Cu")
		(net "M_C_CPU1_SB_CA<3>")
	)
	(segment
		(start 87.453978 -263.233662)
		(end 87.46236 -263.228836)
		(width 0.0889)
		(layer "In2.Cu")
		(net "M_C_CPU1_SB_CA<3>")
	)
	(segment
		(start 79.93507 -263.233916)
		(end 79.956914 -263.22147)
		(width 0.0889)
		(layer "In2.Cu")
		(net "M_C_CPU1_SB_CA<3>")
	)
	(segment
		(start 79.91348 -263.246362)
		(end 79.93507 -263.233916)
		(width 0.0889)
		(layer "In2.Cu")
		(net "M_C_CPU1_SB_CA<3>")
	)
	(segment
		(start 92.153994 -263.233662)
		(end 92.162376 -263.228836)
		(width 0.0889)
		(layer "In2.Cu")
		(net "M_C_CPU1_SB_CA<3>")
	)
	(segment
		(start 82.179668 -263.228836)
		(end 82.18805 -263.233662)
		(width 0.0889)
		(layer "In2.Cu")
		(net "M_C_CPU1_SB_CA<3>")
	)
	(segment
		(start 76.563728 -262.884412)
		(end 78.030578 -262.884412)
		(width 0.0889)
		(layer "In2.Cu")
		(net "M_C_CPU1_SB_CA<3>")
	)
	(segment
		(start 86.879684 -263.228836)
		(end 86.888066 -263.233662)
		(width 0.0889)
		(layer "In2.Cu")
		(net "M_C_CPU1_SB_CA<3>")
	)
	(segment
		(start 88.394032 -263.233662)
		(end 88.402414 -263.228836)
		(width 0.0889)
		(layer "In2.Cu")
		(net "M_C_CPU1_SB_CA<3>")
	)
	(segment
		(start 76.237846 -263.210294)
		(end 76.563728 -262.884412)
		(width 0.0889)
		(layer "In2.Cu")
		(net "M_C_CPU1_SB_CA<3>")
	)
	(segment
		(start 79.351886 -263.22274)
		(end 79.370682 -263.233662)
		(width 0.0889)
		(layer "In2.Cu")
		(net "M_C_CPU1_SB_CA<3>")
	)
	(segment
		(start 91.5797 -263.228836)
		(end 91.588082 -263.233662)
		(width 0.0889)
		(layer "In2.Cu")
		(net "M_C_CPU1_SB_CA<3>")
	)
	(segment
		(start 75.966066 -263.210294)
		(end 76.237846 -263.210294)
		(width 0.0889)
		(layer "In2.Cu")
		(net "M_C_CPU1_SB_CA<3>")
	)
	(arc
		(start 90.273886 -263.233662)
		(mid 90.456137 -263.183312)
		(end 90.639646 -263.228836)
		(width 0.0889)
		(layer "In2.Cu")
		(net "M_C_CPU1_SB_CA<3>")
	)
	(arc
		(start 81.247996 -263.233662)
		(mid 81.530952 -263.309839)
		(end 81.813908 -263.233662)
		(width 0.0889)
		(layer "In2.Cu")
		(net "M_C_CPU1_SB_CA<3>")
	)
	(arc
		(start 93.46819 -263.233662)
		(mid 93.751146 -263.309839)
		(end 94.034102 -263.233662)
		(width 0.0889)
		(layer "In2.Cu")
		(net "M_C_CPU1_SB_CA<3>")
	)
	(arc
		(start 79.370682 -263.233662)
		(mid 79.640451 -263.309685)
		(end 79.91348 -263.246362)
		(width 0.0889)
		(layer "In2.Cu")
		(net "M_C_CPU1_SB_CA<3>")
	)
	(arc
		(start 92.528136 -263.233662)
		(mid 92.811092 -263.309839)
		(end 93.094048 -263.233662)
		(width 0.0889)
		(layer "In2.Cu")
		(net "M_C_CPU1_SB_CA<3>")
	)
	(arc
		(start 78.464918 -263.254236)
		(mid 78.732808 -263.3103)
		(end 78.995524 -263.233662)
		(width 0.0889)
		(layer "In2.Cu")
		(net "M_C_CPU1_SB_CA<3>")
	)
	(arc
		(start 93.10243 -263.228836)
		(mid 93.285938 -263.183342)
		(end 93.46819 -263.233662)
		(width 0.0889)
		(layer "In2.Cu")
		(net "M_C_CPU1_SB_CA<3>")
	)
	(arc
		(start 83.128104 -263.233662)
		(mid 83.41106 -263.309839)
		(end 83.694016 -263.233662)
		(width 0.0889)
		(layer "In2.Cu")
		(net "M_C_CPU1_SB_CA<3>")
	)
	(arc
		(start 89.707974 -263.233662)
		(mid 89.99093 -263.309839)
		(end 90.273886 -263.233662)
		(width 0.0889)
		(layer "In2.Cu")
		(net "M_C_CPU1_SB_CA<3>")
	)
	(arc
		(start 84.068158 -263.233662)
		(mid 84.351114 -263.309839)
		(end 84.63407 -263.233662)
		(width 0.0889)
		(layer "In2.Cu")
		(net "M_C_CPU1_SB_CA<3>")
	)
	(arc
		(start 80.874108 -263.233662)
		(mid 81.061052 -263.183407)
		(end 81.247996 -263.233662)
		(width 0.0889)
		(layer "In2.Cu")
		(net "M_C_CPU1_SB_CA<3>")
	)
	(arc
		(start 79.956914 -263.22147)
		(mid 80.134096 -263.18353)
		(end 80.308196 -263.233662)
		(width 0.0889)
		(layer "In2.Cu")
		(net "M_C_CPU1_SB_CA<3>")
	)
	(arc
		(start 86.888066 -263.233662)
		(mid 87.171022 -263.309839)
		(end 87.453978 -263.233662)
		(width 0.0889)
		(layer "In2.Cu")
		(net "M_C_CPU1_SB_CA<3>")
	)
	(arc
		(start 85.948012 -263.233662)
		(mid 86.230968 -263.309839)
		(end 86.513924 -263.233662)
		(width 0.0889)
		(layer "In2.Cu")
		(net "M_C_CPU1_SB_CA<3>")
	)
	(arc
		(start 84.63407 -263.233662)
		(mid 84.821014 -263.183407)
		(end 85.007958 -263.233662)
		(width 0.0889)
		(layer "In2.Cu")
		(net "M_C_CPU1_SB_CA<3>")
	)
	(arc
		(start 92.162376 -263.228836)
		(mid 92.345884 -263.183342)
		(end 92.528136 -263.233662)
		(width 0.0889)
		(layer "In2.Cu")
		(net "M_C_CPU1_SB_CA<3>")
	)
	(arc
		(start 85.007958 -263.233662)
		(mid 85.290914 -263.309839)
		(end 85.57387 -263.233662)
		(width 0.0889)
		(layer "In2.Cu")
		(net "M_C_CPU1_SB_CA<3>")
	)
	(arc
		(start 87.46236 -263.228836)
		(mid 87.645868 -263.183342)
		(end 87.82812 -263.233662)
		(width 0.0889)
		(layer "In2.Cu")
		(net "M_C_CPU1_SB_CA<3>")
	)
	(arc
		(start 94.034102 -263.233662)
		(mid 94.190421 -263.184667)
		(end 94.352618 -263.2075)
		(width 0.0889)
		(layer "In2.Cu")
		(net "M_C_CPU1_SB_CA<3>")
	)
	(arc
		(start 83.702398 -263.228836)
		(mid 83.885906 -263.183342)
		(end 84.068158 -263.233662)
		(width 0.0889)
		(layer "In2.Cu")
		(net "M_C_CPU1_SB_CA<3>")
	)
	(arc
		(start 91.588082 -263.233662)
		(mid 91.871038 -263.309839)
		(end 92.153994 -263.233662)
		(width 0.0889)
		(layer "In2.Cu")
		(net "M_C_CPU1_SB_CA<3>")
	)
	(arc
		(start 88.402414 -263.228836)
		(mid 88.585922 -263.183342)
		(end 88.768174 -263.233662)
		(width 0.0889)
		(layer "In2.Cu")
		(net "M_C_CPU1_SB_CA<3>")
	)
	(arc
		(start 78.995524 -263.233662)
		(mid 79.172315 -263.182943)
		(end 79.351886 -263.22274)
		(width 0.0889)
		(layer "In2.Cu")
		(net "M_C_CPU1_SB_CA<3>")
	)
	(arc
		(start 90.648028 -263.233662)
		(mid 90.930984 -263.309839)
		(end 91.21394 -263.233662)
		(width 0.0889)
		(layer "In2.Cu")
		(net "M_C_CPU1_SB_CA<3>")
	)
	(arc
		(start 85.57387 -263.233662)
		(mid 85.756121 -263.183312)
		(end 85.93963 -263.228836)
		(width 0.0889)
		(layer "In2.Cu")
		(net "M_C_CPU1_SB_CA<3>")
	)
	(arc
		(start 89.334086 -263.233662)
		(mid 89.52103 -263.183407)
		(end 89.707974 -263.233662)
		(width 0.0889)
		(layer "In2.Cu")
		(net "M_C_CPU1_SB_CA<3>")
	)
	(arc
		(start 91.21394 -263.233662)
		(mid 91.396191 -263.183312)
		(end 91.5797 -263.228836)
		(width 0.0889)
		(layer "In2.Cu")
		(net "M_C_CPU1_SB_CA<3>")
	)
	(arc
		(start 87.82812 -263.233662)
		(mid 88.111076 -263.309839)
		(end 88.394032 -263.233662)
		(width 0.0889)
		(layer "In2.Cu")
		(net "M_C_CPU1_SB_CA<3>")
	)
	(arc
		(start 88.768174 -263.233662)
		(mid 89.05113 -263.309839)
		(end 89.334086 -263.233662)
		(width 0.0889)
		(layer "In2.Cu")
		(net "M_C_CPU1_SB_CA<3>")
	)
	(arc
		(start 82.762344 -263.228836)
		(mid 82.945852 -263.183342)
		(end 83.128104 -263.233662)
		(width 0.0889)
		(layer "In2.Cu")
		(net "M_C_CPU1_SB_CA<3>")
	)
	(arc
		(start 86.513924 -263.233662)
		(mid 86.696175 -263.183312)
		(end 86.879684 -263.228836)
		(width 0.0889)
		(layer "In2.Cu")
		(net "M_C_CPU1_SB_CA<3>")
	)
	(arc
		(start 80.308196 -263.233662)
		(mid 80.591152 -263.309839)
		(end 80.874108 -263.233662)
		(width 0.0889)
		(layer "In2.Cu")
		(net "M_C_CPU1_SB_CA<3>")
	)
	(arc
		(start 82.18805 -263.233662)
		(mid 82.471006 -263.309839)
		(end 82.753962 -263.233662)
		(width 0.0889)
		(layer "In2.Cu")
		(net "M_C_CPU1_SB_CA<3>")
	)
	(arc
		(start 81.813908 -263.233662)
		(mid 81.996159 -263.183312)
		(end 82.179668 -263.228836)
		(width 0.0889)
		(layer "In2.Cu")
		(net "M_C_CPU1_SB_CA<3>")
	)
	(segment
		(start 95.157798 -262.480298)
		(end 94.690946 -262.746236)
		(width 0.10668)
		(layer "F.Cu")
		(net "M_C_CPU1_SB_CA<2>")
	)
	(segment
		(start 79.44104 -263.05383)
		(end 79.466694 -263.068816)
		(width 0.0889)
		(layer "In2.Cu")
		(net "M_C_CPU1_SB_CA<2>")
	)
	(segment
		(start 57.410858 -262.754364)
		(end 57.64149 -262.754364)
		(width 0.14478)
		(layer "In2.Cu")
		(net "M_C_CPU1_SB_CA<2>")
	)
	(segment
		(start 57.248044 -262.143494)
		(end 57.248044 -262.59155)
		(width 0.14478)
		(layer "In2.Cu")
		(net "M_C_CPU1_SB_CA<2>")
	)
	(segment
		(start 93.929708 -263.073642)
		(end 93.93809 -263.068816)
		(width 0.0889)
		(layer "In2.Cu")
		(net "M_C_CPU1_SB_CA<2>")
	)
	(segment
		(start 48.887888 -262.754364)
		(end 49.11852 -262.754364)
		(width 0.14478)
		(layer "In2.Cu")
		(net "M_C_CPU1_SB_CA<2>")
	)
	(segment
		(start 56.467756 -262.367522)
		(end 56.854598 -261.98068)
		(width 0.14478)
		(layer "In2.Cu")
		(net "M_C_CPU1_SB_CA<2>")
	)
	(segment
		(start 83.589622 -263.073642)
		(end 83.598004 -263.068816)
		(width 0.0889)
		(layer "In2.Cu")
		(net "M_C_CPU1_SB_CA<2>")
	)
	(segment
		(start 48.501046 -262.367522)
		(end 48.887888 -262.754364)
		(width 0.14478)
		(layer "In2.Cu")
		(net "M_C_CPU1_SB_CA<2>")
	)
	(segment
		(start 76.17333 -262.75538)
		(end 76.308458 -262.620252)
		(width 0.0889)
		(layer "In2.Cu")
		(net "M_C_CPU1_SB_CA<2>")
	)
	(segment
		(start 49.444148 -261.98068)
		(end 49.67478 -261.98068)
		(width 0.14478)
		(layer "In2.Cu")
		(net "M_C_CPU1_SB_CA<2>")
	)
	(segment
		(start 66.589148 -262.75538)
		(end 75.966066 -262.75538)
		(width 0.14478)
		(layer "In2.Cu")
		(net "M_C_CPU1_SB_CA<2>")
	)
	(segment
		(start 53.625496 -261.992364)
		(end 53.856128 -261.992364)
		(width 0.14478)
		(layer "In2.Cu")
		(net "M_C_CPU1_SB_CA<2>")
	)
	(segment
		(start 94.44101 -263.037066)
		(end 94.537022 -263.011666)
		(width 0.0889)
		(layer "In2.Cu")
		(net "M_C_CPU1_SB_CA<2>")
	)
	(segment
		(start 45.120814 -262.004556)
		(end 45.351446 -262.004556)
		(width 0.14478)
		(layer "In2.Cu")
		(net "M_C_CPU1_SB_CA<2>")
	)
	(segment
		(start 90.74404 -263.068816)
		(end 90.752422 -263.073642)
		(width 0.0889)
		(layer "In2.Cu")
		(net "M_C_CPU1_SB_CA<2>")
	)
	(segment
		(start 51.174142 -262.367522)
		(end 52.137818 -262.367522)
		(width 0.14478)
		(layer "In2.Cu")
		(net "M_C_CPU1_SB_CA<2>")
	)
	(segment
		(start 89.229692 -263.073642)
		(end 89.238074 -263.068816)
		(width 0.0889)
		(layer "In2.Cu")
		(net "M_C_CPU1_SB_CA<2>")
	)
	(segment
		(start 54.018942 -262.579866)
		(end 54.181756 -262.74268)
		(width 0.14478)
		(layer "In2.Cu")
		(net "M_C_CPU1_SB_CA<2>")
	)
	(segment
		(start 46.07052 -262.16737)
		(end 46.233334 -262.004556)
		(width 0.14478)
		(layer "In2.Cu")
		(net "M_C_CPU1_SB_CA<2>")
	)
	(segment
		(start 49.837594 -262.143494)
		(end 49.837594 -262.59155)
		(width 0.14478)
		(layer "In2.Cu")
		(net "M_C_CPU1_SB_CA<2>")
	)
	(segment
		(start 54.412388 -262.74268)
		(end 54.787546 -262.367522)
		(width 0.14478)
		(layer "In2.Cu")
		(net "M_C_CPU1_SB_CA<2>")
	)
	(segment
		(start 54.787546 -262.367522)
		(end 56.467756 -262.367522)
		(width 0.14478)
		(layer "In2.Cu")
		(net "M_C_CPU1_SB_CA<2>")
	)
	(segment
		(start 47.407576 -262.367522)
		(end 48.501046 -262.367522)
		(width 0.14478)
		(layer "In2.Cu")
		(net "M_C_CPU1_SB_CA<2>")
	)
	(segment
		(start 66.20129 -262.367522)
		(end 66.589148 -262.75538)
		(width 0.14478)
		(layer "In2.Cu")
		(net "M_C_CPU1_SB_CA<2>")
	)
	(segment
		(start 78.525116 -263.068562)
		(end 78.552548 -263.08431)
		(width 0.0889)
		(layer "In2.Cu")
		(net "M_C_CPU1_SB_CA<2>")
	)
	(segment
		(start 52.743608 -261.992364)
		(end 52.906422 -262.155178)
		(width 0.14478)
		(layer "In2.Cu")
		(net "M_C_CPU1_SB_CA<2>")
	)
	(segment
		(start 52.137818 -262.367522)
		(end 52.512976 -261.992364)
		(width 0.14478)
		(layer "In2.Cu")
		(net "M_C_CPU1_SB_CA<2>")
	)
	(segment
		(start 89.803986 -263.068816)
		(end 89.812368 -263.073642)
		(width 0.0889)
		(layer "In2.Cu")
		(net "M_C_CPU1_SB_CA<2>")
	)
	(segment
		(start 52.906422 -262.579866)
		(end 53.069236 -262.74268)
		(width 0.14478)
		(layer "In2.Cu")
		(net "M_C_CPU1_SB_CA<2>")
	)
	(segment
		(start 79.839566 -263.068562)
		(end 79.861156 -263.056116)
		(width 0.0889)
		(layer "In2.Cu")
		(net "M_C_CPU1_SB_CA<2>")
	)
	(segment
		(start 46.62678 -262.592058)
		(end 46.789594 -262.754872)
		(width 0.14478)
		(layer "In2.Cu")
		(net "M_C_CPU1_SB_CA<2>")
	)
	(segment
		(start 85.10397 -263.068816)
		(end 85.112352 -263.073642)
		(width 0.0889)
		(layer "In2.Cu")
		(net "M_C_CPU1_SB_CA<2>")
	)
	(segment
		(start 80.769714 -263.073642)
		(end 80.778096 -263.068816)
		(width 0.0889)
		(layer "In2.Cu")
		(net "M_C_CPU1_SB_CA<2>")
	)
	(segment
		(start 53.299868 -262.74268)
		(end 53.462682 -262.579866)
		(width 0.14478)
		(layer "In2.Cu")
		(net "M_C_CPU1_SB_CA<2>")
	)
	(segment
		(start 53.069236 -262.74268)
		(end 53.299868 -262.74268)
		(width 0.14478)
		(layer "In2.Cu")
		(net "M_C_CPU1_SB_CA<2>")
	)
	(segment
		(start 56.854598 -261.98068)
		(end 57.08523 -261.98068)
		(width 0.14478)
		(layer "In2.Cu")
		(net "M_C_CPU1_SB_CA<2>")
	)
	(segment
		(start 49.11852 -262.754364)
		(end 49.281334 -262.59155)
		(width 0.14478)
		(layer "In2.Cu")
		(net "M_C_CPU1_SB_CA<2>")
	)
	(segment
		(start 86.044024 -263.068816)
		(end 86.052406 -263.073642)
		(width 0.0889)
		(layer "In2.Cu")
		(net "M_C_CPU1_SB_CA<2>")
	)
	(segment
		(start 50.7873 -261.98068)
		(end 51.174142 -262.367522)
		(width 0.14478)
		(layer "In2.Cu")
		(net "M_C_CPU1_SB_CA<2>")
	)
	(segment
		(start 81.344008 -263.068816)
		(end 81.35239 -263.073642)
		(width 0.0889)
		(layer "In2.Cu")
		(net "M_C_CPU1_SB_CA<2>")
	)
	(segment
		(start 57.248044 -262.59155)
		(end 57.410858 -262.754364)
		(width 0.14478)
		(layer "In2.Cu")
		(net "M_C_CPU1_SB_CA<2>")
	)
	(segment
		(start 53.856128 -261.992364)
		(end 54.018942 -262.155178)
		(width 0.14478)
		(layer "In2.Cu")
		(net "M_C_CPU1_SB_CA<2>")
	)
	(segment
		(start 50.000408 -262.754364)
		(end 50.23104 -262.754364)
		(width 0.14478)
		(layer "In2.Cu")
		(net "M_C_CPU1_SB_CA<2>")
	)
	(segment
		(start 45.51426 -262.16737)
		(end 45.51426 -262.592058)
		(width 0.14478)
		(layer "In2.Cu")
		(net "M_C_CPU1_SB_CA<2>")
	)
	(segment
		(start 45.351446 -262.004556)
		(end 45.51426 -262.16737)
		(width 0.14478)
		(layer "In2.Cu")
		(net "M_C_CPU1_SB_CA<2>")
	)
	(segment
		(start 46.62678 -262.16737)
		(end 46.62678 -262.592058)
		(width 0.14478)
		(layer "In2.Cu")
		(net "M_C_CPU1_SB_CA<2>")
	)
	(segment
		(start 84.529676 -263.073642)
		(end 84.538058 -263.068816)
		(width 0.0889)
		(layer "In2.Cu")
		(net "M_C_CPU1_SB_CA<2>")
	)
	(segment
		(start 54.018942 -262.155178)
		(end 54.018942 -262.579866)
		(width 0.14478)
		(layer "In2.Cu")
		(net "M_C_CPU1_SB_CA<2>")
	)
	(segment
		(start 50.556668 -261.98068)
		(end 50.7873 -261.98068)
		(width 0.14478)
		(layer "In2.Cu")
		(net "M_C_CPU1_SB_CA<2>")
	)
	(segment
		(start 49.67478 -261.98068)
		(end 49.837594 -262.143494)
		(width 0.14478)
		(layer "In2.Cu")
		(net "M_C_CPU1_SB_CA<2>")
	)
	(segment
		(start 46.463966 -262.004556)
		(end 46.62678 -262.16737)
		(width 0.14478)
		(layer "In2.Cu")
		(net "M_C_CPU1_SB_CA<2>")
	)
	(segment
		(start 44.340018 -262.785352)
		(end 45.120814 -262.004556)
		(width 0.14478)
		(layer "In2.Cu")
		(net "M_C_CPU1_SB_CA<2>")
	)
	(segment
		(start 54.181756 -262.74268)
		(end 54.412388 -262.74268)
		(width 0.14478)
		(layer "In2.Cu")
		(net "M_C_CPU1_SB_CA<2>")
	)
	(segment
		(start 46.07052 -262.592058)
		(end 46.07052 -262.16737)
		(width 0.14478)
		(layer "In2.Cu")
		(net "M_C_CPU1_SB_CA<2>")
	)
	(segment
		(start 58.028332 -262.367522)
		(end 66.20129 -262.367522)
		(width 0.14478)
		(layer "In2.Cu")
		(net "M_C_CPU1_SB_CA<2>")
	)
	(segment
		(start 94.537022 -263.011666)
		(end 94.690946 -262.746236)
		(width 0.0889)
		(layer "In2.Cu")
		(net "M_C_CPU1_SB_CA<2>")
	)
	(segment
		(start 57.08523 -261.98068)
		(end 57.248044 -262.143494)
		(width 0.14478)
		(layer "In2.Cu")
		(net "M_C_CPU1_SB_CA<2>")
	)
	(segment
		(start 57.64149 -262.754364)
		(end 58.028332 -262.367522)
		(width 0.14478)
		(layer "In2.Cu")
		(net "M_C_CPU1_SB_CA<2>")
	)
	(segment
		(start 50.393854 -262.143494)
		(end 50.556668 -261.98068)
		(width 0.14478)
		(layer "In2.Cu")
		(net "M_C_CPU1_SB_CA<2>")
	)
	(segment
		(start 92.989654 -263.073642)
		(end 92.998036 -263.068816)
		(width 0.0889)
		(layer "In2.Cu")
		(net "M_C_CPU1_SB_CA<2>")
	)
	(segment
		(start 53.462682 -262.155178)
		(end 53.625496 -261.992364)
		(width 0.14478)
		(layer "In2.Cu")
		(net "M_C_CPU1_SB_CA<2>")
	)
	(segment
		(start 49.281334 -262.59155)
		(end 49.281334 -262.143494)
		(width 0.14478)
		(layer "In2.Cu")
		(net "M_C_CPU1_SB_CA<2>")
	)
	(segment
		(start 50.23104 -262.754364)
		(end 50.393854 -262.59155)
		(width 0.14478)
		(layer "In2.Cu")
		(net "M_C_CPU1_SB_CA<2>")
	)
	(segment
		(start 88.289638 -263.073642)
		(end 88.29802 -263.068816)
		(width 0.0889)
		(layer "In2.Cu")
		(net "M_C_CPU1_SB_CA<2>")
	)
	(segment
		(start 52.512976 -261.992364)
		(end 52.743608 -261.992364)
		(width 0.14478)
		(layer "In2.Cu")
		(net "M_C_CPU1_SB_CA<2>")
	)
	(segment
		(start 52.906422 -262.155178)
		(end 52.906422 -262.579866)
		(width 0.14478)
		(layer "In2.Cu")
		(net "M_C_CPU1_SB_CA<2>")
	)
	(segment
		(start 46.789594 -262.754872)
		(end 47.020226 -262.754872)
		(width 0.14478)
		(layer "In2.Cu")
		(net "M_C_CPU1_SB_CA<2>")
	)
	(segment
		(start 75.966066 -262.75538)
		(end 76.17333 -262.75538)
		(width 0.0889)
		(layer "In2.Cu")
		(net "M_C_CPU1_SB_CA<2>")
	)
	(segment
		(start 45.677074 -262.754872)
		(end 45.907706 -262.754872)
		(width 0.14478)
		(layer "In2.Cu")
		(net "M_C_CPU1_SB_CA<2>")
	)
	(segment
		(start 46.233334 -262.004556)
		(end 46.463966 -262.004556)
		(width 0.14478)
		(layer "In2.Cu")
		(net "M_C_CPU1_SB_CA<2>")
	)
	(segment
		(start 49.281334 -262.143494)
		(end 49.444148 -261.98068)
		(width 0.14478)
		(layer "In2.Cu")
		(net "M_C_CPU1_SB_CA<2>")
	)
	(segment
		(start 50.393854 -262.59155)
		(end 50.393854 -262.143494)
		(width 0.14478)
		(layer "In2.Cu")
		(net "M_C_CPU1_SB_CA<2>")
	)
	(segment
		(start 78.076806 -262.620252)
		(end 78.525116 -263.068562)
		(width 0.0889)
		(layer "In2.Cu")
		(net "M_C_CPU1_SB_CA<2>")
	)
	(segment
		(start 45.907706 -262.754872)
		(end 46.07052 -262.592058)
		(width 0.14478)
		(layer "In2.Cu")
		(net "M_C_CPU1_SB_CA<2>")
	)
	(segment
		(start 79.8195 -263.079992)
		(end 79.839566 -263.068562)
		(width 0.0889)
		(layer "In2.Cu")
		(net "M_C_CPU1_SB_CA<2>")
	)
	(segment
		(start 47.020226 -262.754872)
		(end 47.407576 -262.367522)
		(width 0.14478)
		(layer "In2.Cu")
		(net "M_C_CPU1_SB_CA<2>")
	)
	(segment
		(start 45.51426 -262.592058)
		(end 45.677074 -262.754872)
		(width 0.14478)
		(layer "In2.Cu")
		(net "M_C_CPU1_SB_CA<2>")
	)
	(segment
		(start 76.308458 -262.620252)
		(end 78.076806 -262.620252)
		(width 0.0889)
		(layer "In2.Cu")
		(net "M_C_CPU1_SB_CA<2>")
	)
	(segment
		(start 49.837594 -262.59155)
		(end 50.000408 -262.754364)
		(width 0.14478)
		(layer "In2.Cu")
		(net "M_C_CPU1_SB_CA<2>")
	)
	(segment
		(start 53.462682 -262.579866)
		(end 53.462682 -262.155178)
		(width 0.14478)
		(layer "In2.Cu")
		(net "M_C_CPU1_SB_CA<2>")
	)
	(arc
		(start 80.778096 -263.068816)
		(mid 81.061052 -262.992639)
		(end 81.344008 -263.068816)
		(width 0.0889)
		(layer "In2.Cu")
		(net "M_C_CPU1_SB_CA<2>")
	)
	(arc
		(start 78.552548 -263.08431)
		(mid 78.727799 -263.119243)
		(end 78.899258 -263.068816)
		(width 0.0889)
		(layer "In2.Cu")
		(net "M_C_CPU1_SB_CA<2>")
	)
	(arc
		(start 78.899258 -263.068816)
		(mid 79.168221 -262.992086)
		(end 79.44104 -263.05383)
		(width 0.0889)
		(layer "In2.Cu")
		(net "M_C_CPU1_SB_CA<2>")
	)
	(arc
		(start 88.863932 -263.068816)
		(mid 89.046183 -263.119166)
		(end 89.229692 -263.073642)
		(width 0.0889)
		(layer "In2.Cu")
		(net "M_C_CPU1_SB_CA<2>")
	)
	(arc
		(start 79.466694 -263.068816)
		(mid 79.641679 -263.11876)
		(end 79.8195 -263.079992)
		(width 0.0889)
		(layer "In2.Cu")
		(net "M_C_CPU1_SB_CA<2>")
	)
	(arc
		(start 84.163916 -263.068816)
		(mid 84.346167 -263.119166)
		(end 84.529676 -263.073642)
		(width 0.0889)
		(layer "In2.Cu")
		(net "M_C_CPU1_SB_CA<2>")
	)
	(arc
		(start 86.418166 -263.068816)
		(mid 86.701122 -262.992639)
		(end 86.984078 -263.068816)
		(width 0.0889)
		(layer "In2.Cu")
		(net "M_C_CPU1_SB_CA<2>")
	)
	(arc
		(start 84.538058 -263.068816)
		(mid 84.821014 -262.992639)
		(end 85.10397 -263.068816)
		(width 0.0889)
		(layer "In2.Cu")
		(net "M_C_CPU1_SB_CA<2>")
	)
	(arc
		(start 88.29802 -263.068816)
		(mid 88.580976 -262.992639)
		(end 88.863932 -263.068816)
		(width 0.0889)
		(layer "In2.Cu")
		(net "M_C_CPU1_SB_CA<2>")
	)
	(arc
		(start 80.403954 -263.068816)
		(mid 80.586205 -263.119166)
		(end 80.769714 -263.073642)
		(width 0.0889)
		(layer "In2.Cu")
		(net "M_C_CPU1_SB_CA<2>")
	)
	(arc
		(start 85.478112 -263.068816)
		(mid 85.761068 -262.992639)
		(end 86.044024 -263.068816)
		(width 0.0889)
		(layer "In2.Cu")
		(net "M_C_CPU1_SB_CA<2>")
	)
	(arc
		(start 87.923878 -263.068816)
		(mid 88.106129 -263.119166)
		(end 88.289638 -263.073642)
		(width 0.0889)
		(layer "In2.Cu")
		(net "M_C_CPU1_SB_CA<2>")
	)
	(arc
		(start 92.998036 -263.068816)
		(mid 93.280992 -262.992639)
		(end 93.563948 -263.068816)
		(width 0.0889)
		(layer "In2.Cu")
		(net "M_C_CPU1_SB_CA<2>")
	)
	(arc
		(start 81.71815 -263.068816)
		(mid 82.001106 -262.992639)
		(end 82.284062 -263.068816)
		(width 0.0889)
		(layer "In2.Cu")
		(net "M_C_CPU1_SB_CA<2>")
	)
	(arc
		(start 87.357966 -263.068816)
		(mid 87.640922 -262.992639)
		(end 87.923878 -263.068816)
		(width 0.0889)
		(layer "In2.Cu")
		(net "M_C_CPU1_SB_CA<2>")
	)
	(arc
		(start 92.057982 -263.068816)
		(mid 92.340938 -262.992639)
		(end 92.623894 -263.068816)
		(width 0.0889)
		(layer "In2.Cu")
		(net "M_C_CPU1_SB_CA<2>")
	)
	(arc
		(start 82.65795 -263.068816)
		(mid 82.940906 -262.992639)
		(end 83.223862 -263.068816)
		(width 0.0889)
		(layer "In2.Cu")
		(net "M_C_CPU1_SB_CA<2>")
	)
	(arc
		(start 86.984078 -263.068816)
		(mid 87.171022 -263.119071)
		(end 87.357966 -263.068816)
		(width 0.0889)
		(layer "In2.Cu")
		(net "M_C_CPU1_SB_CA<2>")
	)
	(arc
		(start 92.623894 -263.068816)
		(mid 92.806145 -263.119166)
		(end 92.989654 -263.073642)
		(width 0.0889)
		(layer "In2.Cu")
		(net "M_C_CPU1_SB_CA<2>")
	)
	(arc
		(start 85.112352 -263.073642)
		(mid 85.29586 -263.119136)
		(end 85.478112 -263.068816)
		(width 0.0889)
		(layer "In2.Cu")
		(net "M_C_CPU1_SB_CA<2>")
	)
	(arc
		(start 89.238074 -263.068816)
		(mid 89.52103 -262.992639)
		(end 89.803986 -263.068816)
		(width 0.0889)
		(layer "In2.Cu")
		(net "M_C_CPU1_SB_CA<2>")
	)
	(arc
		(start 83.598004 -263.068816)
		(mid 83.88096 -262.992639)
		(end 84.163916 -263.068816)
		(width 0.0889)
		(layer "In2.Cu")
		(net "M_C_CPU1_SB_CA<2>")
	)
	(arc
		(start 91.118182 -263.068816)
		(mid 91.401138 -262.992639)
		(end 91.684094 -263.068816)
		(width 0.0889)
		(layer "In2.Cu")
		(net "M_C_CPU1_SB_CA<2>")
	)
	(arc
		(start 89.812368 -263.073642)
		(mid 89.995876 -263.119136)
		(end 90.178128 -263.068816)
		(width 0.0889)
		(layer "In2.Cu")
		(net "M_C_CPU1_SB_CA<2>")
	)
	(arc
		(start 90.752422 -263.073642)
		(mid 90.93593 -263.119136)
		(end 91.118182 -263.068816)
		(width 0.0889)
		(layer "In2.Cu")
		(net "M_C_CPU1_SB_CA<2>")
	)
	(arc
		(start 82.284062 -263.068816)
		(mid 82.471006 -263.119071)
		(end 82.65795 -263.068816)
		(width 0.0889)
		(layer "In2.Cu")
		(net "M_C_CPU1_SB_CA<2>")
	)
	(arc
		(start 83.223862 -263.068816)
		(mid 83.406113 -263.119166)
		(end 83.589622 -263.073642)
		(width 0.0889)
		(layer "In2.Cu")
		(net "M_C_CPU1_SB_CA<2>")
	)
	(arc
		(start 93.93809 -263.068816)
		(mid 94.185803 -262.993596)
		(end 94.44101 -263.037066)
		(width 0.0889)
		(layer "In2.Cu")
		(net "M_C_CPU1_SB_CA<2>")
	)
	(arc
		(start 91.684094 -263.068816)
		(mid 91.871038 -263.119071)
		(end 92.057982 -263.068816)
		(width 0.0889)
		(layer "In2.Cu")
		(net "M_C_CPU1_SB_CA<2>")
	)
	(arc
		(start 93.563948 -263.068816)
		(mid 93.746199 -263.119166)
		(end 93.929708 -263.073642)
		(width 0.0889)
		(layer "In2.Cu")
		(net "M_C_CPU1_SB_CA<2>")
	)
	(arc
		(start 81.35239 -263.073642)
		(mid 81.535898 -263.119136)
		(end 81.71815 -263.068816)
		(width 0.0889)
		(layer "In2.Cu")
		(net "M_C_CPU1_SB_CA<2>")
	)
	(arc
		(start 86.052406 -263.073642)
		(mid 86.235914 -263.119136)
		(end 86.418166 -263.068816)
		(width 0.0889)
		(layer "In2.Cu")
		(net "M_C_CPU1_SB_CA<2>")
	)
	(arc
		(start 79.861156 -263.056116)
		(mid 80.134185 -262.992797)
		(end 80.403954 -263.068816)
		(width 0.0889)
		(layer "In2.Cu")
		(net "M_C_CPU1_SB_CA<2>")
	)
	(arc
		(start 90.178128 -263.068816)
		(mid 90.461084 -262.992639)
		(end 90.74404 -263.068816)
		(width 0.0889)
		(layer "In2.Cu")
		(net "M_C_CPU1_SB_CA<2>")
	)
	(segment
		(start 96.097852 -262.480298)
		(end 95.631 -262.746236)
		(width 0.10668)
		(layer "F.Cu")
		(net "M_C_CPU1_SB_CA<1>")
	)
	(segment
		(start 89.803986 -262.423656)
		(end 89.812368 -262.41883)
		(width 0.0889)
		(layer "In2.Cu")
		(net "M_C_CPU1_SB_CA<1>")
	)
	(segment
		(start 94.504002 -262.423656)
		(end 94.512384 -262.41883)
		(width 0.0889)
		(layer "In2.Cu")
		(net "M_C_CPU1_SB_CA<1>")
	)
	(segment
		(start 41.890188 -261.510272)
		(end 42.053002 -261.673086)
		(width 0.14478)
		(layer "In2.Cu")
		(net "M_C_CPU1_SB_CA<1>")
	)
	(segment
		(start 42.772076 -261.510272)
		(end 66.233294 -261.510272)
		(width 0.14478)
		(layer "In2.Cu")
		(net "M_C_CPU1_SB_CA<1>")
	)
	(segment
		(start 86.044024 -262.423656)
		(end 86.052406 -262.41883)
		(width 0.0889)
		(layer "In2.Cu")
		(net "M_C_CPU1_SB_CA<1>")
	)
	(segment
		(start 40.23995 -261.935214)
		(end 40.664892 -261.510272)
		(width 0.14478)
		(layer "In2.Cu")
		(net "M_C_CPU1_SB_CA<1>")
	)
	(segment
		(start 42.446448 -262.119364)
		(end 42.609262 -261.95655)
		(width 0.14478)
		(layer "In2.Cu")
		(net "M_C_CPU1_SB_CA<1>")
	)
	(segment
		(start 81.344008 -262.423656)
		(end 81.35239 -262.41883)
		(width 0.0889)
		(layer "In2.Cu")
		(net "M_C_CPU1_SB_CA<1>")
	)
	(segment
		(start 80.769714 -262.41883)
		(end 80.778096 -262.423656)
		(width 0.0889)
		(layer "In2.Cu")
		(net "M_C_CPU1_SB_CA<1>")
	)
	(segment
		(start 89.229692 -262.41883)
		(end 89.238074 -262.423656)
		(width 0.0889)
		(layer "In2.Cu")
		(net "M_C_CPU1_SB_CA<1>")
	)
	(segment
		(start 88.289638 -262.41883)
		(end 88.29802 -262.423656)
		(width 0.0889)
		(layer "In2.Cu")
		(net "M_C_CPU1_SB_CA<1>")
	)
	(segment
		(start 40.664892 -261.510272)
		(end 41.890188 -261.510272)
		(width 0.14478)
		(layer "In2.Cu")
		(net "M_C_CPU1_SB_CA<1>")
	)
	(segment
		(start 90.74404 -262.423656)
		(end 90.752422 -262.41883)
		(width 0.0889)
		(layer "In2.Cu")
		(net "M_C_CPU1_SB_CA<1>")
	)
	(segment
		(start 42.215816 -262.119364)
		(end 42.446448 -262.119364)
		(width 0.14478)
		(layer "In2.Cu")
		(net "M_C_CPU1_SB_CA<1>")
	)
	(segment
		(start 84.529676 -262.41883)
		(end 84.538058 -262.423656)
		(width 0.0889)
		(layer "In2.Cu")
		(net "M_C_CPU1_SB_CA<1>")
	)
	(segment
		(start 42.053002 -261.673086)
		(end 42.053002 -261.95655)
		(width 0.14478)
		(layer "In2.Cu")
		(net "M_C_CPU1_SB_CA<1>")
	)
	(segment
		(start 95.785178 -262.480806)
		(end 95.631 -262.746236)
		(width 0.0889)
		(layer "In2.Cu")
		(net "M_C_CPU1_SB_CA<1>")
	)
	(segment
		(start 92.989654 -262.41883)
		(end 92.998036 -262.423656)
		(width 0.0889)
		(layer "In2.Cu")
		(net "M_C_CPU1_SB_CA<1>")
	)
	(segment
		(start 66.233294 -261.510272)
		(end 66.969386 -262.246364)
		(width 0.14478)
		(layer "In2.Cu")
		(net "M_C_CPU1_SB_CA<1>")
	)
	(segment
		(start 80.389222 -262.432292)
		(end 80.403954 -262.423656)
		(width 0.0889)
		(layer "In2.Cu")
		(net "M_C_CPU1_SB_CA<1>")
	)
	(segment
		(start 75.986386 -262.246364)
		(end 79.179928 -262.246364)
		(width 0.0889)
		(layer "In2.Cu")
		(net "M_C_CPU1_SB_CA<1>")
	)
	(segment
		(start 85.10397 -262.423656)
		(end 85.112352 -262.41883)
		(width 0.0889)
		(layer "In2.Cu")
		(net "M_C_CPU1_SB_CA<1>")
	)
	(segment
		(start 42.053002 -261.95655)
		(end 42.215816 -262.119364)
		(width 0.14478)
		(layer "In2.Cu")
		(net "M_C_CPU1_SB_CA<1>")
	)
	(segment
		(start 66.969386 -262.246364)
		(end 75.986386 -262.246364)
		(width 0.14478)
		(layer "In2.Cu")
		(net "M_C_CPU1_SB_CA<1>")
	)
	(segment
		(start 83.589622 -262.41883)
		(end 83.598004 -262.423656)
		(width 0.0889)
		(layer "In2.Cu")
		(net "M_C_CPU1_SB_CA<1>")
	)
	(segment
		(start 93.929708 -262.41883)
		(end 93.93809 -262.423656)
		(width 0.0889)
		(layer "In2.Cu")
		(net "M_C_CPU1_SB_CA<1>")
	)
	(segment
		(start 95.444056 -262.423656)
		(end 95.452438 -262.41883)
		(width 0.0889)
		(layer "In2.Cu")
		(net "M_C_CPU1_SB_CA<1>")
	)
	(segment
		(start 42.609262 -261.673086)
		(end 42.772076 -261.510272)
		(width 0.14478)
		(layer "In2.Cu")
		(net "M_C_CPU1_SB_CA<1>")
	)
	(segment
		(start 42.609262 -261.95655)
		(end 42.609262 -261.673086)
		(width 0.14478)
		(layer "In2.Cu")
		(net "M_C_CPU1_SB_CA<1>")
	)
	(segment
		(start 95.762826 -262.397494)
		(end 95.785178 -262.480806)
		(width 0.0889)
		(layer "In2.Cu")
		(net "M_C_CPU1_SB_CA<1>")
	)
	(arc
		(start 86.418166 -262.423656)
		(mid 86.701122 -262.499833)
		(end 86.984078 -262.423656)
		(width 0.0889)
		(layer "In2.Cu")
		(net "M_C_CPU1_SB_CA<1>")
	)
	(arc
		(start 80.403954 -262.423656)
		(mid 80.586205 -262.373306)
		(end 80.769714 -262.41883)
		(width 0.0889)
		(layer "In2.Cu")
		(net "M_C_CPU1_SB_CA<1>")
	)
	(arc
		(start 81.71815 -262.423656)
		(mid 82.001106 -262.499833)
		(end 82.284062 -262.423656)
		(width 0.0889)
		(layer "In2.Cu")
		(net "M_C_CPU1_SB_CA<1>")
	)
	(arc
		(start 90.178128 -262.423656)
		(mid 90.461084 -262.499833)
		(end 90.74404 -262.423656)
		(width 0.0889)
		(layer "In2.Cu")
		(net "M_C_CPU1_SB_CA<1>")
	)
	(arc
		(start 95.452438 -262.41883)
		(mid 95.605308 -262.374189)
		(end 95.762826 -262.397494)
		(width 0.0889)
		(layer "In2.Cu")
		(net "M_C_CPU1_SB_CA<1>")
	)
	(arc
		(start 82.65795 -262.423656)
		(mid 82.940906 -262.499833)
		(end 83.223862 -262.423656)
		(width 0.0889)
		(layer "In2.Cu")
		(net "M_C_CPU1_SB_CA<1>")
	)
	(arc
		(start 90.752422 -262.41883)
		(mid 90.93593 -262.373336)
		(end 91.118182 -262.423656)
		(width 0.0889)
		(layer "In2.Cu")
		(net "M_C_CPU1_SB_CA<1>")
	)
	(arc
		(start 86.052406 -262.41883)
		(mid 86.235914 -262.373336)
		(end 86.418166 -262.423656)
		(width 0.0889)
		(layer "In2.Cu")
		(net "M_C_CPU1_SB_CA<1>")
	)
	(arc
		(start 83.598004 -262.423656)
		(mid 83.88096 -262.499833)
		(end 84.163916 -262.423656)
		(width 0.0889)
		(layer "In2.Cu")
		(net "M_C_CPU1_SB_CA<1>")
	)
	(arc
		(start 85.112352 -262.41883)
		(mid 85.29586 -262.373336)
		(end 85.478112 -262.423656)
		(width 0.0889)
		(layer "In2.Cu")
		(net "M_C_CPU1_SB_CA<1>")
	)
	(arc
		(start 92.057982 -262.423656)
		(mid 92.340938 -262.499833)
		(end 92.623894 -262.423656)
		(width 0.0889)
		(layer "In2.Cu")
		(net "M_C_CPU1_SB_CA<1>")
	)
	(arc
		(start 82.284062 -262.423656)
		(mid 82.471006 -262.373401)
		(end 82.65795 -262.423656)
		(width 0.0889)
		(layer "In2.Cu")
		(net "M_C_CPU1_SB_CA<1>")
	)
	(arc
		(start 89.238074 -262.423656)
		(mid 89.52103 -262.499833)
		(end 89.803986 -262.423656)
		(width 0.0889)
		(layer "In2.Cu")
		(net "M_C_CPU1_SB_CA<1>")
	)
	(arc
		(start 88.29802 -262.423656)
		(mid 88.580976 -262.499833)
		(end 88.863932 -262.423656)
		(width 0.0889)
		(layer "In2.Cu")
		(net "M_C_CPU1_SB_CA<1>")
	)
	(arc
		(start 79.179928 -262.246364)
		(mid 79.520464 -262.291476)
		(end 79.837534 -262.423656)
		(width 0.0889)
		(layer "In2.Cu")
		(net "M_C_CPU1_SB_CA<1>")
	)
	(arc
		(start 89.812368 -262.41883)
		(mid 89.995876 -262.373336)
		(end 90.178128 -262.423656)
		(width 0.0889)
		(layer "In2.Cu")
		(net "M_C_CPU1_SB_CA<1>")
	)
	(arc
		(start 83.223862 -262.423656)
		(mid 83.406113 -262.373306)
		(end 83.589622 -262.41883)
		(width 0.0889)
		(layer "In2.Cu")
		(net "M_C_CPU1_SB_CA<1>")
	)
	(arc
		(start 87.923878 -262.423656)
		(mid 88.106129 -262.373306)
		(end 88.289638 -262.41883)
		(width 0.0889)
		(layer "In2.Cu")
		(net "M_C_CPU1_SB_CA<1>")
	)
	(arc
		(start 94.878144 -262.423656)
		(mid 95.1611 -262.499833)
		(end 95.444056 -262.423656)
		(width 0.0889)
		(layer "In2.Cu")
		(net "M_C_CPU1_SB_CA<1>")
	)
	(arc
		(start 84.163916 -262.423656)
		(mid 84.346167 -262.373306)
		(end 84.529676 -262.41883)
		(width 0.0889)
		(layer "In2.Cu")
		(net "M_C_CPU1_SB_CA<1>")
	)
	(arc
		(start 91.118182 -262.423656)
		(mid 91.401138 -262.499833)
		(end 91.684094 -262.423656)
		(width 0.0889)
		(layer "In2.Cu")
		(net "M_C_CPU1_SB_CA<1>")
	)
	(arc
		(start 85.478112 -262.423656)
		(mid 85.761068 -262.499833)
		(end 86.044024 -262.423656)
		(width 0.0889)
		(layer "In2.Cu")
		(net "M_C_CPU1_SB_CA<1>")
	)
	(arc
		(start 87.357966 -262.423656)
		(mid 87.640922 -262.499833)
		(end 87.923878 -262.423656)
		(width 0.0889)
		(layer "In2.Cu")
		(net "M_C_CPU1_SB_CA<1>")
	)
	(arc
		(start 92.998036 -262.423656)
		(mid 93.280992 -262.499833)
		(end 93.563948 -262.423656)
		(width 0.0889)
		(layer "In2.Cu")
		(net "M_C_CPU1_SB_CA<1>")
	)
	(arc
		(start 93.93809 -262.423656)
		(mid 94.221046 -262.499833)
		(end 94.504002 -262.423656)
		(width 0.0889)
		(layer "In2.Cu")
		(net "M_C_CPU1_SB_CA<1>")
	)
	(arc
		(start 94.512384 -262.41883)
		(mid 94.695892 -262.373336)
		(end 94.878144 -262.423656)
		(width 0.0889)
		(layer "In2.Cu")
		(net "M_C_CPU1_SB_CA<1>")
	)
	(arc
		(start 88.863932 -262.423656)
		(mid 89.046183 -262.373306)
		(end 89.229692 -262.41883)
		(width 0.0889)
		(layer "In2.Cu")
		(net "M_C_CPU1_SB_CA<1>")
	)
	(arc
		(start 86.984078 -262.423656)
		(mid 87.171022 -262.373401)
		(end 87.357966 -262.423656)
		(width 0.0889)
		(layer "In2.Cu")
		(net "M_C_CPU1_SB_CA<1>")
	)
	(arc
		(start 80.778096 -262.423656)
		(mid 81.061052 -262.499833)
		(end 81.344008 -262.423656)
		(width 0.0889)
		(layer "In2.Cu")
		(net "M_C_CPU1_SB_CA<1>")
	)
	(arc
		(start 84.538058 -262.423656)
		(mid 84.821014 -262.499833)
		(end 85.10397 -262.423656)
		(width 0.0889)
		(layer "In2.Cu")
		(net "M_C_CPU1_SB_CA<1>")
	)
	(arc
		(start 91.684094 -262.423656)
		(mid 91.871038 -262.373401)
		(end 92.057982 -262.423656)
		(width 0.0889)
		(layer "In2.Cu")
		(net "M_C_CPU1_SB_CA<1>")
	)
	(arc
		(start 93.563948 -262.423656)
		(mid 93.746199 -262.373306)
		(end 93.929708 -262.41883)
		(width 0.0889)
		(layer "In2.Cu")
		(net "M_C_CPU1_SB_CA<1>")
	)
	(arc
		(start 81.35239 -262.41883)
		(mid 81.535898 -262.373336)
		(end 81.71815 -262.423656)
		(width 0.0889)
		(layer "In2.Cu")
		(net "M_C_CPU1_SB_CA<1>")
	)
	(arc
		(start 92.623894 -262.423656)
		(mid 92.806145 -262.373306)
		(end 92.989654 -262.41883)
		(width 0.0889)
		(layer "In2.Cu")
		(net "M_C_CPU1_SB_CA<1>")
	)
	(arc
		(start 79.837534 -262.423656)
		(mid 80.11224 -262.50002)
		(end 80.389222 -262.432292)
		(width 0.0889)
		(layer "In2.Cu")
		(net "M_C_CPU1_SB_CA<1>")
	)
	(segment
		(start 96.568006 -261.670292)
		(end 96.101154 -261.93623)
		(width 0.10668)
		(layer "F.Cu")
		(net "M_C_CPU1_SB_CA<0>")
	)
	(segment
		(start 64.812164 -260.88975)
		(end 64.812164 -260.431026)
		(width 0.14478)
		(layer "In2.Cu")
		(net "M_C_CPU1_SB_CA<0>")
	)
	(segment
		(start 62.030864 -260.431026)
		(end 62.030864 -260.88975)
		(width 0.14478)
		(layer "In2.Cu")
		(net "M_C_CPU1_SB_CA<0>")
	)
	(segment
		(start 62.587124 -260.431026)
		(end 62.749938 -260.268212)
		(width 0.14478)
		(layer "In2.Cu")
		(net "M_C_CPU1_SB_CA<0>")
	)
	(segment
		(start 64.255904 -260.88975)
		(end 64.418718 -261.052564)
		(width 0.14478)
		(layer "In2.Cu")
		(net "M_C_CPU1_SB_CA<0>")
	)
	(segment
		(start 67.667632 -261.77621)
		(end 75.948286 -261.77621)
		(width 0.14478)
		(layer "In2.Cu")
		(net "M_C_CPU1_SB_CA<0>")
	)
	(segment
		(start 63.862458 -260.268212)
		(end 64.09309 -260.268212)
		(width 0.14478)
		(layer "In2.Cu")
		(net "M_C_CPU1_SB_CA<0>")
	)
	(segment
		(start 63.306198 -261.052564)
		(end 63.53683 -261.052564)
		(width 0.14478)
		(layer "In2.Cu")
		(net "M_C_CPU1_SB_CA<0>")
	)
	(segment
		(start 63.699644 -260.88975)
		(end 63.699644 -260.431026)
		(width 0.14478)
		(layer "In2.Cu")
		(net "M_C_CPU1_SB_CA<0>")
	)
	(segment
		(start 61.31179 -261.052564)
		(end 61.474604 -260.88975)
		(width 0.14478)
		(layer "In2.Cu")
		(net "M_C_CPU1_SB_CA<0>")
	)
	(segment
		(start 65.531238 -261.052564)
		(end 65.76187 -261.052564)
		(width 0.14478)
		(layer "In2.Cu")
		(net "M_C_CPU1_SB_CA<0>")
	)
	(segment
		(start 60.726066 -260.660388)
		(end 61.118242 -261.052564)
		(width 0.14478)
		(layer "In2.Cu")
		(net "M_C_CPU1_SB_CA<0>")
	)
	(segment
		(start 64.09309 -260.268212)
		(end 64.255904 -260.431026)
		(width 0.14478)
		(layer "In2.Cu")
		(net "M_C_CPU1_SB_CA<0>")
	)
	(segment
		(start 88.394032 -262.25881)
		(end 88.402414 -262.263636)
		(width 0.0889)
		(layer "In2.Cu")
		(net "M_C_CPU1_SB_CA<0>")
	)
	(segment
		(start 64.418718 -261.052564)
		(end 64.64935 -261.052564)
		(width 0.14478)
		(layer "In2.Cu")
		(net "M_C_CPU1_SB_CA<0>")
	)
	(segment
		(start 76.384658 -261.77621)
		(end 76.651612 -262.043164)
		(width 0.0889)
		(layer "In2.Cu")
		(net "M_C_CPU1_SB_CA<0>")
	)
	(segment
		(start 91.5797 -262.263636)
		(end 91.588082 -262.25881)
		(width 0.0889)
		(layer "In2.Cu")
		(net "M_C_CPU1_SB_CA<0>")
	)
	(segment
		(start 63.143384 -260.431026)
		(end 63.143384 -260.88975)
		(width 0.14478)
		(layer "In2.Cu")
		(net "M_C_CPU1_SB_CA<0>")
	)
	(segment
		(start 62.193678 -261.052564)
		(end 62.42431 -261.052564)
		(width 0.14478)
		(layer "In2.Cu")
		(net "M_C_CPU1_SB_CA<0>")
	)
	(segment
		(start 87.453978 -262.25881)
		(end 87.46236 -262.263636)
		(width 0.0889)
		(layer "In2.Cu")
		(net "M_C_CPU1_SB_CA<0>")
	)
	(segment
		(start 83.694016 -262.25881)
		(end 83.702398 -262.263636)
		(width 0.0889)
		(layer "In2.Cu")
		(net "M_C_CPU1_SB_CA<0>")
	)
	(segment
		(start 82.179668 -262.263636)
		(end 82.18805 -262.25881)
		(width 0.0889)
		(layer "In2.Cu")
		(net "M_C_CPU1_SB_CA<0>")
	)
	(segment
		(start 75.948286 -261.77621)
		(end 76.384658 -261.77621)
		(width 0.0889)
		(layer "In2.Cu")
		(net "M_C_CPU1_SB_CA<0>")
	)
	(segment
		(start 44.340018 -261.08533)
		(end 44.76496 -260.660388)
		(width 0.14478)
		(layer "In2.Cu")
		(net "M_C_CPU1_SB_CA<0>")
	)
	(segment
		(start 66.55181 -260.660388)
		(end 67.667632 -261.77621)
		(width 0.14478)
		(layer "In2.Cu")
		(net "M_C_CPU1_SB_CA<0>")
	)
	(segment
		(start 64.255904 -260.431026)
		(end 64.255904 -260.88975)
		(width 0.14478)
		(layer "In2.Cu")
		(net "M_C_CPU1_SB_CA<0>")
	)
	(segment
		(start 86.879684 -262.263636)
		(end 86.888066 -262.25881)
		(width 0.0889)
		(layer "In2.Cu")
		(net "M_C_CPU1_SB_CA<0>")
	)
	(segment
		(start 63.143384 -260.88975)
		(end 63.306198 -261.052564)
		(width 0.14478)
		(layer "In2.Cu")
		(net "M_C_CPU1_SB_CA<0>")
	)
	(segment
		(start 90.639646 -262.263636)
		(end 90.648028 -262.25881)
		(width 0.0889)
		(layer "In2.Cu")
		(net "M_C_CPU1_SB_CA<0>")
	)
	(segment
		(start 64.974978 -260.268212)
		(end 65.20561 -260.268212)
		(width 0.14478)
		(layer "In2.Cu")
		(net "M_C_CPU1_SB_CA<0>")
	)
	(segment
		(start 64.812164 -260.431026)
		(end 64.974978 -260.268212)
		(width 0.14478)
		(layer "In2.Cu")
		(net "M_C_CPU1_SB_CA<0>")
	)
	(segment
		(start 95.339662 -262.263636)
		(end 95.348044 -262.25881)
		(width 0.0889)
		(layer "In2.Cu")
		(net "M_C_CPU1_SB_CA<0>")
	)
	(segment
		(start 95.85071 -262.22706)
		(end 95.946976 -262.20166)
		(width 0.0889)
		(layer "In2.Cu")
		(net "M_C_CPU1_SB_CA<0>")
	)
	(segment
		(start 80.299814 -262.263636)
		(end 80.308196 -262.25881)
		(width 0.0889)
		(layer "In2.Cu")
		(net "M_C_CPU1_SB_CA<0>")
	)
	(segment
		(start 62.030864 -260.88975)
		(end 62.193678 -261.052564)
		(width 0.14478)
		(layer "In2.Cu")
		(net "M_C_CPU1_SB_CA<0>")
	)
	(segment
		(start 65.368424 -260.88975)
		(end 65.531238 -261.052564)
		(width 0.14478)
		(layer "In2.Cu")
		(net "M_C_CPU1_SB_CA<0>")
	)
	(segment
		(start 65.368424 -260.431026)
		(end 65.368424 -260.88975)
		(width 0.14478)
		(layer "In2.Cu")
		(net "M_C_CPU1_SB_CA<0>")
	)
	(segment
		(start 76.651612 -262.043164)
		(end 79.133192 -262.043164)
		(width 0.0889)
		(layer "In2.Cu")
		(net "M_C_CPU1_SB_CA<0>")
	)
	(segment
		(start 61.86805 -260.268212)
		(end 62.030864 -260.431026)
		(width 0.14478)
		(layer "In2.Cu")
		(net "M_C_CPU1_SB_CA<0>")
	)
	(segment
		(start 63.699644 -260.431026)
		(end 63.862458 -260.268212)
		(width 0.14478)
		(layer "In2.Cu")
		(net "M_C_CPU1_SB_CA<0>")
	)
	(segment
		(start 61.637418 -260.268212)
		(end 61.86805 -260.268212)
		(width 0.14478)
		(layer "In2.Cu")
		(net "M_C_CPU1_SB_CA<0>")
	)
	(segment
		(start 66.154046 -260.660388)
		(end 66.55181 -260.660388)
		(width 0.14478)
		(layer "In2.Cu")
		(net "M_C_CPU1_SB_CA<0>")
	)
	(segment
		(start 61.474604 -260.88975)
		(end 61.474604 -260.431026)
		(width 0.14478)
		(layer "In2.Cu")
		(net "M_C_CPU1_SB_CA<0>")
	)
	(segment
		(start 62.749938 -260.268212)
		(end 62.98057 -260.268212)
		(width 0.14478)
		(layer "In2.Cu")
		(net "M_C_CPU1_SB_CA<0>")
	)
	(segment
		(start 62.42431 -261.052564)
		(end 62.587124 -260.88975)
		(width 0.14478)
		(layer "In2.Cu")
		(net "M_C_CPU1_SB_CA<0>")
	)
	(segment
		(start 44.76496 -260.660388)
		(end 60.726066 -260.660388)
		(width 0.14478)
		(layer "In2.Cu")
		(net "M_C_CPU1_SB_CA<0>")
	)
	(segment
		(start 93.094048 -262.25881)
		(end 93.10243 -262.263636)
		(width 0.0889)
		(layer "In2.Cu")
		(net "M_C_CPU1_SB_CA<0>")
	)
	(segment
		(start 63.53683 -261.052564)
		(end 63.699644 -260.88975)
		(width 0.14478)
		(layer "In2.Cu")
		(net "M_C_CPU1_SB_CA<0>")
	)
	(segment
		(start 92.153994 -262.25881)
		(end 92.162376 -262.263636)
		(width 0.0889)
		(layer "In2.Cu")
		(net "M_C_CPU1_SB_CA<0>")
	)
	(segment
		(start 62.587124 -260.88975)
		(end 62.587124 -260.431026)
		(width 0.14478)
		(layer "In2.Cu")
		(net "M_C_CPU1_SB_CA<0>")
	)
	(segment
		(start 82.753962 -262.25881)
		(end 82.762344 -262.263636)
		(width 0.0889)
		(layer "In2.Cu")
		(net "M_C_CPU1_SB_CA<0>")
	)
	(segment
		(start 65.76187 -261.052564)
		(end 66.154046 -260.660388)
		(width 0.14478)
		(layer "In2.Cu")
		(net "M_C_CPU1_SB_CA<0>")
	)
	(segment
		(start 61.118242 -261.052564)
		(end 61.31179 -261.052564)
		(width 0.14478)
		(layer "In2.Cu")
		(net "M_C_CPU1_SB_CA<0>")
	)
	(segment
		(start 65.20561 -260.268212)
		(end 65.368424 -260.431026)
		(width 0.14478)
		(layer "In2.Cu")
		(net "M_C_CPU1_SB_CA<0>")
	)
	(segment
		(start 85.93963 -262.263636)
		(end 85.948012 -262.25881)
		(width 0.0889)
		(layer "In2.Cu")
		(net "M_C_CPU1_SB_CA<0>")
	)
	(segment
		(start 62.98057 -260.268212)
		(end 63.143384 -260.431026)
		(width 0.14478)
		(layer "In2.Cu")
		(net "M_C_CPU1_SB_CA<0>")
	)
	(segment
		(start 64.64935 -261.052564)
		(end 64.812164 -260.88975)
		(width 0.14478)
		(layer "In2.Cu")
		(net "M_C_CPU1_SB_CA<0>")
	)
	(segment
		(start 95.946976 -262.20166)
		(end 96.101154 -261.93623)
		(width 0.0889)
		(layer "In2.Cu")
		(net "M_C_CPU1_SB_CA<0>")
	)
	(segment
		(start 61.474604 -260.431026)
		(end 61.637418 -260.268212)
		(width 0.14478)
		(layer "In2.Cu")
		(net "M_C_CPU1_SB_CA<0>")
	)
	(arc
		(start 88.768174 -262.25881)
		(mid 89.05113 -262.182633)
		(end 89.334086 -262.25881)
		(width 0.0889)
		(layer "In2.Cu")
		(net "M_C_CPU1_SB_CA<0>")
	)
	(arc
		(start 81.247996 -262.25881)
		(mid 81.530952 -262.182633)
		(end 81.813908 -262.25881)
		(width 0.0889)
		(layer "In2.Cu")
		(net "M_C_CPU1_SB_CA<0>")
	)
	(arc
		(start 80.874108 -262.25881)
		(mid 81.061052 -262.309065)
		(end 81.247996 -262.25881)
		(width 0.0889)
		(layer "In2.Cu")
		(net "M_C_CPU1_SB_CA<0>")
	)
	(arc
		(start 85.948012 -262.25881)
		(mid 86.230968 -262.182633)
		(end 86.513924 -262.25881)
		(width 0.0889)
		(layer "In2.Cu")
		(net "M_C_CPU1_SB_CA<0>")
	)
	(arc
		(start 92.162376 -262.263636)
		(mid 92.345884 -262.30913)
		(end 92.528136 -262.25881)
		(width 0.0889)
		(layer "In2.Cu")
		(net "M_C_CPU1_SB_CA<0>")
	)
	(arc
		(start 88.402414 -262.263636)
		(mid 88.585922 -262.30913)
		(end 88.768174 -262.25881)
		(width 0.0889)
		(layer "In2.Cu")
		(net "M_C_CPU1_SB_CA<0>")
	)
	(arc
		(start 87.82812 -262.25881)
		(mid 88.111076 -262.182633)
		(end 88.394032 -262.25881)
		(width 0.0889)
		(layer "In2.Cu")
		(net "M_C_CPU1_SB_CA<0>")
	)
	(arc
		(start 94.973902 -262.25881)
		(mid 95.156153 -262.30916)
		(end 95.339662 -262.263636)
		(width 0.0889)
		(layer "In2.Cu")
		(net "M_C_CPU1_SB_CA<0>")
	)
	(arc
		(start 89.334086 -262.25881)
		(mid 89.52103 -262.309065)
		(end 89.707974 -262.25881)
		(width 0.0889)
		(layer "In2.Cu")
		(net "M_C_CPU1_SB_CA<0>")
	)
	(arc
		(start 82.18805 -262.25881)
		(mid 82.471006 -262.182633)
		(end 82.753962 -262.25881)
		(width 0.0889)
		(layer "In2.Cu")
		(net "M_C_CPU1_SB_CA<0>")
	)
	(arc
		(start 85.57387 -262.25881)
		(mid 85.756121 -262.30916)
		(end 85.93963 -262.263636)
		(width 0.0889)
		(layer "In2.Cu")
		(net "M_C_CPU1_SB_CA<0>")
	)
	(arc
		(start 94.034102 -262.25881)
		(mid 94.221046 -262.309065)
		(end 94.40799 -262.25881)
		(width 0.0889)
		(layer "In2.Cu")
		(net "M_C_CPU1_SB_CA<0>")
	)
	(arc
		(start 85.007958 -262.25881)
		(mid 85.290914 -262.182633)
		(end 85.57387 -262.25881)
		(width 0.0889)
		(layer "In2.Cu")
		(net "M_C_CPU1_SB_CA<0>")
	)
	(arc
		(start 93.10243 -262.263636)
		(mid 93.285938 -262.30913)
		(end 93.46819 -262.25881)
		(width 0.0889)
		(layer "In2.Cu")
		(net "M_C_CPU1_SB_CA<0>")
	)
	(arc
		(start 89.707974 -262.25881)
		(mid 89.99093 -262.182633)
		(end 90.273886 -262.25881)
		(width 0.0889)
		(layer "In2.Cu")
		(net "M_C_CPU1_SB_CA<0>")
	)
	(arc
		(start 81.813908 -262.25881)
		(mid 81.996159 -262.30916)
		(end 82.179668 -262.263636)
		(width 0.0889)
		(layer "In2.Cu")
		(net "M_C_CPU1_SB_CA<0>")
	)
	(arc
		(start 92.528136 -262.25881)
		(mid 92.811092 -262.182633)
		(end 93.094048 -262.25881)
		(width 0.0889)
		(layer "In2.Cu")
		(net "M_C_CPU1_SB_CA<0>")
	)
	(arc
		(start 79.133192 -262.043164)
		(mid 79.547637 -262.098027)
		(end 79.933546 -262.25881)
		(width 0.0889)
		(layer "In2.Cu")
		(net "M_C_CPU1_SB_CA<0>")
	)
	(arc
		(start 94.40799 -262.25881)
		(mid 94.690946 -262.182633)
		(end 94.973902 -262.25881)
		(width 0.0889)
		(layer "In2.Cu")
		(net "M_C_CPU1_SB_CA<0>")
	)
	(arc
		(start 82.762344 -262.263636)
		(mid 82.945852 -262.30913)
		(end 83.128104 -262.25881)
		(width 0.0889)
		(layer "In2.Cu")
		(net "M_C_CPU1_SB_CA<0>")
	)
	(arc
		(start 87.46236 -262.263636)
		(mid 87.645868 -262.30913)
		(end 87.82812 -262.25881)
		(width 0.0889)
		(layer "In2.Cu")
		(net "M_C_CPU1_SB_CA<0>")
	)
	(arc
		(start 91.21394 -262.25881)
		(mid 91.396191 -262.30916)
		(end 91.5797 -262.263636)
		(width 0.0889)
		(layer "In2.Cu")
		(net "M_C_CPU1_SB_CA<0>")
	)
	(arc
		(start 86.888066 -262.25881)
		(mid 87.171022 -262.182633)
		(end 87.453978 -262.25881)
		(width 0.0889)
		(layer "In2.Cu")
		(net "M_C_CPU1_SB_CA<0>")
	)
	(arc
		(start 84.068158 -262.25881)
		(mid 84.351114 -262.182633)
		(end 84.63407 -262.25881)
		(width 0.0889)
		(layer "In2.Cu")
		(net "M_C_CPU1_SB_CA<0>")
	)
	(arc
		(start 95.348044 -262.25881)
		(mid 95.59564 -262.183632)
		(end 95.85071 -262.22706)
		(width 0.0889)
		(layer "In2.Cu")
		(net "M_C_CPU1_SB_CA<0>")
	)
	(arc
		(start 84.63407 -262.25881)
		(mid 84.821014 -262.309065)
		(end 85.007958 -262.25881)
		(width 0.0889)
		(layer "In2.Cu")
		(net "M_C_CPU1_SB_CA<0>")
	)
	(arc
		(start 80.308196 -262.25881)
		(mid 80.591152 -262.182633)
		(end 80.874108 -262.25881)
		(width 0.0889)
		(layer "In2.Cu")
		(net "M_C_CPU1_SB_CA<0>")
	)
	(arc
		(start 83.702398 -262.263636)
		(mid 83.885906 -262.30913)
		(end 84.068158 -262.25881)
		(width 0.0889)
		(layer "In2.Cu")
		(net "M_C_CPU1_SB_CA<0>")
	)
	(arc
		(start 91.588082 -262.25881)
		(mid 91.871038 -262.182633)
		(end 92.153994 -262.25881)
		(width 0.0889)
		(layer "In2.Cu")
		(net "M_C_CPU1_SB_CA<0>")
	)
	(arc
		(start 83.128104 -262.25881)
		(mid 83.41106 -262.182633)
		(end 83.694016 -262.25881)
		(width 0.0889)
		(layer "In2.Cu")
		(net "M_C_CPU1_SB_CA<0>")
	)
	(arc
		(start 90.273886 -262.25881)
		(mid 90.456137 -262.30916)
		(end 90.639646 -262.263636)
		(width 0.0889)
		(layer "In2.Cu")
		(net "M_C_CPU1_SB_CA<0>")
	)
	(arc
		(start 93.46819 -262.25881)
		(mid 93.751146 -262.182633)
		(end 94.034102 -262.25881)
		(width 0.0889)
		(layer "In2.Cu")
		(net "M_C_CPU1_SB_CA<0>")
	)
	(arc
		(start 79.933546 -262.25881)
		(mid 80.116051 -262.309287)
		(end 80.299814 -262.263636)
		(width 0.0889)
		(layer "In2.Cu")
		(net "M_C_CPU1_SB_CA<0>")
	)
	(arc
		(start 86.513924 -262.25881)
		(mid 86.696175 -262.30916)
		(end 86.879684 -262.263636)
		(width 0.0889)
		(layer "In2.Cu")
		(net "M_C_CPU1_SB_CA<0>")
	)
	(arc
		(start 90.648028 -262.25881)
		(mid 90.930984 -262.182633)
		(end 91.21394 -262.25881)
		(width 0.0889)
		(layer "In2.Cu")
		(net "M_C_CPU1_SB_CA<0>")
	)
	(segment
		(start 96.568006 -266.530328)
		(end 96.101154 -266.796266)
		(width 0.10668)
		(layer "F.Cu")
		(net "M_C_CPU1_SA_RSP<0>")
	)
	(segment
		(start 51.666648 -269.160244)
		(end 52.348638 -269.160244)
		(width 0.11684)
		(layer "In2.Cu")
		(net "M_C_CPU1_SA_RSP<0>")
	)
	(segment
		(start 45.086778 -269.005558)
		(end 45.086778 -268.92885)
		(width 0.11684)
		(layer "In2.Cu")
		(net "M_C_CPU1_SA_RSP<0>")
	)
	(segment
		(start 57.31383 -269.160244)
		(end 57.468516 -269.005558)
		(width 0.11684)
		(layer "In2.Cu")
		(net "M_C_CPU1_SA_RSP<0>")
	)
	(segment
		(start 56.566562 -268.774164)
		(end 56.78551 -268.774164)
		(width 0.11684)
		(layer "In2.Cu")
		(net "M_C_CPU1_SA_RSP<0>")
	)
	(segment
		(start 53.565044 -268.92377)
		(end 53.71973 -268.769084)
		(width 0.11684)
		(layer "In2.Cu")
		(net "M_C_CPU1_SA_RSP<0>")
	)
	(segment
		(start 57.468516 -269.005558)
		(end 57.468516 -268.92885)
		(width 0.11684)
		(layer "In2.Cu")
		(net "M_C_CPU1_SA_RSP<0>")
	)
	(segment
		(start 52.882038 -268.769084)
		(end 53.036724 -268.92377)
		(width 0.11684)
		(layer "In2.Cu")
		(net "M_C_CPU1_SA_RSP<0>")
	)
	(segment
		(start 46.671738 -268.92885)
		(end 46.671738 -269.005558)
		(width 0.11684)
		(layer "In2.Cu")
		(net "M_C_CPU1_SA_RSP<0>")
	)
	(segment
		(start 49.927002 -269.005558)
		(end 49.927002 -268.92885)
		(width 0.11684)
		(layer "In2.Cu")
		(net "M_C_CPU1_SA_RSP<0>")
	)
	(segment
		(start 57.468516 -268.92885)
		(end 57.623202 -268.774164)
		(width 0.11684)
		(layer "In2.Cu")
		(net "M_C_CPU1_SA_RSP<0>")
	)
	(segment
		(start 46.298104 -268.774164)
		(end 46.517052 -268.774164)
		(width 0.11684)
		(layer "In2.Cu")
		(net "M_C_CPU1_SA_RSP<0>")
	)
	(segment
		(start 53.036724 -268.92377)
		(end 53.036724 -269.000478)
		(width 0.11684)
		(layer "In2.Cu")
		(net "M_C_CPU1_SA_RSP<0>")
	)
	(segment
		(start 57.623202 -268.774164)
		(end 57.84215 -268.774164)
		(width 0.11684)
		(layer "In2.Cu")
		(net "M_C_CPU1_SA_RSP<0>")
	)
	(segment
		(start 76.931266 -266.919964)
		(end 79.186532 -266.919964)
		(width 0.0889)
		(layer "In2.Cu")
		(net "M_C_CPU1_SA_RSP<0>")
	)
	(segment
		(start 49.398682 -268.92885)
		(end 49.398682 -269.005558)
		(width 0.11684)
		(layer "In2.Cu")
		(net "M_C_CPU1_SA_RSP<0>")
	)
	(segment
		(start 56.411876 -268.92885)
		(end 56.566562 -268.774164)
		(width 0.11684)
		(layer "In2.Cu")
		(net "M_C_CPU1_SA_RSP<0>")
	)
	(segment
		(start 95.344996 -267.113258)
		(end 95.355664 -267.107162)
		(width 0.0889)
		(layer "In2.Cu")
		(net "M_C_CPU1_SA_RSP<0>")
	)
	(segment
		(start 58.151522 -269.160244)
		(end 58.37047 -269.160244)
		(width 0.11684)
		(layer "In2.Cu")
		(net "M_C_CPU1_SA_RSP<0>")
	)
	(segment
		(start 58.525156 -269.005558)
		(end 58.525156 -268.92885)
		(width 0.11684)
		(layer "In2.Cu")
		(net "M_C_CPU1_SA_RSP<0>")
	)
	(segment
		(start 50.300636 -268.774164)
		(end 50.455322 -268.92885)
		(width 0.11684)
		(layer "In2.Cu")
		(net "M_C_CPU1_SA_RSP<0>")
	)
	(segment
		(start 85.00491 -267.113258)
		(end 85.015578 -267.107162)
		(width 0.0889)
		(layer "In2.Cu")
		(net "M_C_CPU1_SA_RSP<0>")
	)
	(segment
		(start 50.455322 -269.005558)
		(end 50.610008 -269.160244)
		(width 0.11684)
		(layer "In2.Cu")
		(net "M_C_CPU1_SA_RSP<0>")
	)
	(segment
		(start 58.89879 -268.774164)
		(end 59.053476 -268.92885)
		(width 0.11684)
		(layer "In2.Cu")
		(net "M_C_CPU1_SA_RSP<0>")
	)
	(segment
		(start 59.053476 -269.005558)
		(end 59.208162 -269.160244)
		(width 0.11684)
		(layer "In2.Cu")
		(net "M_C_CPU1_SA_RSP<0>")
	)
	(segment
		(start 52.348638 -269.160244)
		(end 52.508404 -269.000478)
		(width 0.11684)
		(layer "In2.Cu")
		(net "M_C_CPU1_SA_RSP<0>")
	)
	(segment
		(start 48.870362 -268.92885)
		(end 49.025048 -268.774164)
		(width 0.11684)
		(layer "In2.Cu")
		(net "M_C_CPU1_SA_RSP<0>")
	)
	(segment
		(start 54.25313 -269.160244)
		(end 56.25719 -269.160244)
		(width 0.11684)
		(layer "In2.Cu")
		(net "M_C_CPU1_SA_RSP<0>")
	)
	(segment
		(start 95.95231 -267.052552)
		(end 96.101154 -266.796266)
		(width 0.0889)
		(layer "In2.Cu")
		(net "M_C_CPU1_SA_RSP<0>")
	)
	(segment
		(start 94.404942 -267.113258)
		(end 94.41561 -267.107162)
		(width 0.0889)
		(layer "In2.Cu")
		(net "M_C_CPU1_SA_RSP<0>")
	)
	(segment
		(start 53.410358 -269.155164)
		(end 53.565044 -269.000478)
		(width 0.11684)
		(layer "In2.Cu")
		(net "M_C_CPU1_SA_RSP<0>")
	)
	(segment
		(start 45.769784 -269.160244)
		(end 45.988732 -269.160244)
		(width 0.11684)
		(layer "In2.Cu")
		(net "M_C_CPU1_SA_RSP<0>")
	)
	(segment
		(start 88.386412 -267.107162)
		(end 88.39708 -267.113258)
		(width 0.0889)
		(layer "In2.Cu")
		(net "M_C_CPU1_SA_RSP<0>")
	)
	(segment
		(start 90.64498 -267.113258)
		(end 90.655648 -267.107162)
		(width 0.0889)
		(layer "In2.Cu")
		(net "M_C_CPU1_SA_RSP<0>")
	)
	(segment
		(start 45.615098 -269.005558)
		(end 45.769784 -269.160244)
		(width 0.11684)
		(layer "In2.Cu")
		(net "M_C_CPU1_SA_RSP<0>")
	)
	(segment
		(start 57.996836 -269.005558)
		(end 58.151522 -269.160244)
		(width 0.11684)
		(layer "In2.Cu")
		(net "M_C_CPU1_SA_RSP<0>")
	)
	(segment
		(start 76.435966 -266.424664)
		(end 76.931266 -266.919964)
		(width 0.0889)
		(layer "In2.Cu")
		(net "M_C_CPU1_SA_RSP<0>")
	)
	(segment
		(start 57.84215 -268.774164)
		(end 57.996836 -268.92885)
		(width 0.11684)
		(layer "In2.Cu")
		(net "M_C_CPU1_SA_RSP<0>")
	)
	(segment
		(start 50.983642 -269.005558)
		(end 50.983642 -268.92885)
		(width 0.11684)
		(layer "In2.Cu")
		(net "M_C_CPU1_SA_RSP<0>")
	)
	(segment
		(start 57.094882 -269.160244)
		(end 57.31383 -269.160244)
		(width 0.11684)
		(layer "In2.Cu")
		(net "M_C_CPU1_SA_RSP<0>")
	)
	(segment
		(start 49.025048 -268.774164)
		(end 49.243996 -268.774164)
		(width 0.11684)
		(layer "In2.Cu")
		(net "M_C_CPU1_SA_RSP<0>")
	)
	(segment
		(start 56.940196 -269.005558)
		(end 57.094882 -269.160244)
		(width 0.11684)
		(layer "In2.Cu")
		(net "M_C_CPU1_SA_RSP<0>")
	)
	(segment
		(start 45.086778 -268.92885)
		(end 45.241464 -268.774164)
		(width 0.11684)
		(layer "In2.Cu")
		(net "M_C_CPU1_SA_RSP<0>")
	)
	(segment
		(start 45.988732 -269.160244)
		(end 46.143418 -269.005558)
		(width 0.11684)
		(layer "In2.Cu")
		(net "M_C_CPU1_SA_RSP<0>")
	)
	(segment
		(start 79.418434 -267.151866)
		(end 80.173576 -267.151866)
		(width 0.0889)
		(layer "In2.Cu")
		(net "M_C_CPU1_SA_RSP<0>")
	)
	(segment
		(start 59.208162 -269.160244)
		(end 60.106306 -269.160244)
		(width 0.11684)
		(layer "In2.Cu")
		(net "M_C_CPU1_SA_RSP<0>")
	)
	(segment
		(start 51.511962 -269.005558)
		(end 51.666648 -269.160244)
		(width 0.11684)
		(layer "In2.Cu")
		(net "M_C_CPU1_SA_RSP<0>")
	)
	(segment
		(start 81.244948 -267.113258)
		(end 81.255616 -267.107162)
		(width 0.0889)
		(layer "In2.Cu")
		(net "M_C_CPU1_SA_RSP<0>")
	)
	(segment
		(start 44.932092 -269.160244)
		(end 45.086778 -269.005558)
		(width 0.11684)
		(layer "In2.Cu")
		(net "M_C_CPU1_SA_RSP<0>")
	)
	(segment
		(start 50.455322 -268.92885)
		(end 50.455322 -269.005558)
		(width 0.11684)
		(layer "In2.Cu")
		(net "M_C_CPU1_SA_RSP<0>")
	)
	(segment
		(start 50.983642 -268.92885)
		(end 51.138328 -268.774164)
		(width 0.11684)
		(layer "In2.Cu")
		(net "M_C_CPU1_SA_RSP<0>")
	)
	(segment
		(start 57.996836 -268.92885)
		(end 57.996836 -269.005558)
		(width 0.11684)
		(layer "In2.Cu")
		(net "M_C_CPU1_SA_RSP<0>")
	)
	(segment
		(start 46.143418 -269.005558)
		(end 46.143418 -268.92885)
		(width 0.11684)
		(layer "In2.Cu")
		(net "M_C_CPU1_SA_RSP<0>")
	)
	(segment
		(start 52.508404 -268.92377)
		(end 52.66309 -268.769084)
		(width 0.11684)
		(layer "In2.Cu")
		(net "M_C_CPU1_SA_RSP<0>")
	)
	(segment
		(start 48.715676 -269.160244)
		(end 48.870362 -269.005558)
		(width 0.11684)
		(layer "In2.Cu")
		(net "M_C_CPU1_SA_RSP<0>")
	)
	(segment
		(start 51.357276 -268.774164)
		(end 51.511962 -268.92885)
		(width 0.11684)
		(layer "In2.Cu")
		(net "M_C_CPU1_SA_RSP<0>")
	)
	(segment
		(start 49.398682 -269.005558)
		(end 49.553368 -269.160244)
		(width 0.11684)
		(layer "In2.Cu")
		(net "M_C_CPU1_SA_RSP<0>")
	)
	(segment
		(start 46.517052 -268.774164)
		(end 46.671738 -268.92885)
		(width 0.11684)
		(layer "In2.Cu")
		(net "M_C_CPU1_SA_RSP<0>")
	)
	(segment
		(start 54.093364 -269.000478)
		(end 54.25313 -269.160244)
		(width 0.11684)
		(layer "In2.Cu")
		(net "M_C_CPU1_SA_RSP<0>")
	)
	(segment
		(start 49.927002 -268.92885)
		(end 50.081688 -268.774164)
		(width 0.11684)
		(layer "In2.Cu")
		(net "M_C_CPU1_SA_RSP<0>")
	)
	(segment
		(start 83.686396 -267.107162)
		(end 83.697064 -267.113258)
		(width 0.0889)
		(layer "In2.Cu")
		(net "M_C_CPU1_SA_RSP<0>")
	)
	(segment
		(start 53.71973 -268.769084)
		(end 53.938678 -268.769084)
		(width 0.11684)
		(layer "In2.Cu")
		(net "M_C_CPU1_SA_RSP<0>")
	)
	(segment
		(start 44.340018 -269.58544)
		(end 44.765214 -269.160244)
		(width 0.11684)
		(layer "In2.Cu")
		(net "M_C_CPU1_SA_RSP<0>")
	)
	(segment
		(start 46.671738 -269.005558)
		(end 46.826424 -269.160244)
		(width 0.11684)
		(layer "In2.Cu")
		(net "M_C_CPU1_SA_RSP<0>")
	)
	(segment
		(start 53.938678 -268.769084)
		(end 54.093364 -268.92377)
		(width 0.11684)
		(layer "In2.Cu")
		(net "M_C_CPU1_SA_RSP<0>")
	)
	(segment
		(start 85.944964 -267.113258)
		(end 85.955632 -267.107162)
		(width 0.0889)
		(layer "In2.Cu")
		(net "M_C_CPU1_SA_RSP<0>")
	)
	(segment
		(start 60.106306 -269.160244)
		(end 62.841886 -266.424664)
		(width 0.11684)
		(layer "In2.Cu")
		(net "M_C_CPU1_SA_RSP<0>")
	)
	(segment
		(start 48.870362 -269.005558)
		(end 48.870362 -268.92885)
		(width 0.11684)
		(layer "In2.Cu")
		(net "M_C_CPU1_SA_RSP<0>")
	)
	(segment
		(start 94.026482 -267.107162)
		(end 94.03715 -267.113258)
		(width 0.0889)
		(layer "In2.Cu")
		(net "M_C_CPU1_SA_RSP<0>")
	)
	(segment
		(start 56.940196 -268.92885)
		(end 56.940196 -269.005558)
		(width 0.11684)
		(layer "In2.Cu")
		(net "M_C_CPU1_SA_RSP<0>")
	)
	(segment
		(start 79.186532 -266.919964)
		(end 79.418434 -267.151866)
		(width 0.0889)
		(layer "In2.Cu")
		(net "M_C_CPU1_SA_RSP<0>")
	)
	(segment
		(start 50.081688 -268.774164)
		(end 50.300636 -268.774164)
		(width 0.11684)
		(layer "In2.Cu")
		(net "M_C_CPU1_SA_RSP<0>")
	)
	(segment
		(start 89.326466 -267.107162)
		(end 89.337134 -267.113258)
		(width 0.0889)
		(layer "In2.Cu")
		(net "M_C_CPU1_SA_RSP<0>")
	)
	(segment
		(start 58.37047 -269.160244)
		(end 58.525156 -269.005558)
		(width 0.11684)
		(layer "In2.Cu")
		(net "M_C_CPU1_SA_RSP<0>")
	)
	(segment
		(start 58.525156 -268.92885)
		(end 58.679842 -268.774164)
		(width 0.11684)
		(layer "In2.Cu")
		(net "M_C_CPU1_SA_RSP<0>")
	)
	(segment
		(start 49.243996 -268.774164)
		(end 49.398682 -268.92885)
		(width 0.11684)
		(layer "In2.Cu")
		(net "M_C_CPU1_SA_RSP<0>")
	)
	(segment
		(start 53.19141 -269.155164)
		(end 53.410358 -269.155164)
		(width 0.11684)
		(layer "In2.Cu")
		(net "M_C_CPU1_SA_RSP<0>")
	)
	(segment
		(start 49.553368 -269.160244)
		(end 49.772316 -269.160244)
		(width 0.11684)
		(layer "In2.Cu")
		(net "M_C_CPU1_SA_RSP<0>")
	)
	(segment
		(start 45.460412 -268.774164)
		(end 45.615098 -268.92885)
		(width 0.11684)
		(layer "In2.Cu")
		(net "M_C_CPU1_SA_RSP<0>")
	)
	(segment
		(start 46.143418 -268.92885)
		(end 46.298104 -268.774164)
		(width 0.11684)
		(layer "In2.Cu")
		(net "M_C_CPU1_SA_RSP<0>")
	)
	(segment
		(start 80.866488 -267.107162)
		(end 80.877156 -267.113258)
		(width 0.0889)
		(layer "In2.Cu")
		(net "M_C_CPU1_SA_RSP<0>")
	)
	(segment
		(start 89.704926 -267.113258)
		(end 89.715594 -267.107162)
		(width 0.0889)
		(layer "In2.Cu")
		(net "M_C_CPU1_SA_RSP<0>")
	)
	(segment
		(start 56.25719 -269.160244)
		(end 56.411876 -269.005558)
		(width 0.11684)
		(layer "In2.Cu")
		(net "M_C_CPU1_SA_RSP<0>")
	)
	(segment
		(start 52.66309 -268.769084)
		(end 52.882038 -268.769084)
		(width 0.11684)
		(layer "In2.Cu")
		(net "M_C_CPU1_SA_RSP<0>")
	)
	(segment
		(start 56.411876 -269.005558)
		(end 56.411876 -268.92885)
		(width 0.11684)
		(layer "In2.Cu")
		(net "M_C_CPU1_SA_RSP<0>")
	)
	(segment
		(start 46.826424 -269.160244)
		(end 48.715676 -269.160244)
		(width 0.11684)
		(layer "In2.Cu")
		(net "M_C_CPU1_SA_RSP<0>")
	)
	(segment
		(start 45.615098 -268.92885)
		(end 45.615098 -269.005558)
		(width 0.11684)
		(layer "In2.Cu")
		(net "M_C_CPU1_SA_RSP<0>")
	)
	(segment
		(start 51.511962 -268.92885)
		(end 51.511962 -269.005558)
		(width 0.11684)
		(layer "In2.Cu")
		(net "M_C_CPU1_SA_RSP<0>")
	)
	(segment
		(start 44.765214 -269.160244)
		(end 44.932092 -269.160244)
		(width 0.11684)
		(layer "In2.Cu")
		(net "M_C_CPU1_SA_RSP<0>")
	)
	(segment
		(start 84.62645 -267.107162)
		(end 84.637118 -267.113258)
		(width 0.0889)
		(layer "In2.Cu")
		(net "M_C_CPU1_SA_RSP<0>")
	)
	(segment
		(start 56.78551 -268.774164)
		(end 56.940196 -268.92885)
		(width 0.11684)
		(layer "In2.Cu")
		(net "M_C_CPU1_SA_RSP<0>")
	)
	(segment
		(start 59.053476 -268.92885)
		(end 59.053476 -269.005558)
		(width 0.11684)
		(layer "In2.Cu")
		(net "M_C_CPU1_SA_RSP<0>")
	)
	(segment
		(start 93.086428 -267.107162)
		(end 93.097096 -267.113258)
		(width 0.0889)
		(layer "In2.Cu")
		(net "M_C_CPU1_SA_RSP<0>")
	)
	(segment
		(start 50.610008 -269.160244)
		(end 50.828956 -269.160244)
		(width 0.11684)
		(layer "In2.Cu")
		(net "M_C_CPU1_SA_RSP<0>")
	)
	(segment
		(start 51.138328 -268.774164)
		(end 51.357276 -268.774164)
		(width 0.11684)
		(layer "In2.Cu")
		(net "M_C_CPU1_SA_RSP<0>")
	)
	(segment
		(start 53.565044 -269.000478)
		(end 53.565044 -268.92377)
		(width 0.11684)
		(layer "In2.Cu")
		(net "M_C_CPU1_SA_RSP<0>")
	)
	(segment
		(start 62.841886 -266.424664)
		(end 76.435966 -266.424664)
		(width 0.11684)
		(layer "In2.Cu")
		(net "M_C_CPU1_SA_RSP<0>")
	)
	(segment
		(start 52.508404 -269.000478)
		(end 52.508404 -268.92377)
		(width 0.11684)
		(layer "In2.Cu")
		(net "M_C_CPU1_SA_RSP<0>")
	)
	(segment
		(start 45.241464 -268.774164)
		(end 45.460412 -268.774164)
		(width 0.11684)
		(layer "In2.Cu")
		(net "M_C_CPU1_SA_RSP<0>")
	)
	(segment
		(start 80.296766 -267.118084)
		(end 80.304894 -267.113258)
		(width 0.0889)
		(layer "In2.Cu")
		(net "M_C_CPU1_SA_RSP<0>")
	)
	(segment
		(start 49.772316 -269.160244)
		(end 49.927002 -269.005558)
		(width 0.11684)
		(layer "In2.Cu")
		(net "M_C_CPU1_SA_RSP<0>")
	)
	(segment
		(start 53.036724 -269.000478)
		(end 53.19141 -269.155164)
		(width 0.11684)
		(layer "In2.Cu")
		(net "M_C_CPU1_SA_RSP<0>")
	)
	(segment
		(start 54.093364 -268.92377)
		(end 54.093364 -269.000478)
		(width 0.11684)
		(layer "In2.Cu")
		(net "M_C_CPU1_SA_RSP<0>")
	)
	(segment
		(start 50.828956 -269.160244)
		(end 50.983642 -269.005558)
		(width 0.11684)
		(layer "In2.Cu")
		(net "M_C_CPU1_SA_RSP<0>")
	)
	(segment
		(start 58.679842 -268.774164)
		(end 58.89879 -268.774164)
		(width 0.11684)
		(layer "In2.Cu")
		(net "M_C_CPU1_SA_RSP<0>")
	)
	(segment
		(start 95.849694 -267.07973)
		(end 95.95231 -267.052552)
		(width 0.0889)
		(layer "In2.Cu")
		(net "M_C_CPU1_SA_RSP<0>")
	)
	(arc
		(start 80.173576 -267.151866)
		(mid 80.237436 -267.143253)
		(end 80.296766 -267.118084)
		(width 0.0889)
		(layer "In2.Cu")
		(net "M_C_CPU1_SA_RSP<0>")
	)
	(arc
		(start 87.457026 -267.113258)
		(mid 87.640922 -267.162738)
		(end 87.824818 -267.113258)
		(width 0.0889)
		(layer "In2.Cu")
		(net "M_C_CPU1_SA_RSP<0>")
	)
	(arc
		(start 81.81721 -267.113258)
		(mid 82.001106 -267.162738)
		(end 82.185002 -267.113258)
		(width 0.0889)
		(layer "In2.Cu")
		(net "M_C_CPU1_SA_RSP<0>")
	)
	(arc
		(start 92.524834 -267.113258)
		(mid 92.804838 -267.036213)
		(end 93.086428 -267.107162)
		(width 0.0889)
		(layer "In2.Cu")
		(net "M_C_CPU1_SA_RSP<0>")
	)
	(arc
		(start 84.637118 -267.113258)
		(mid 84.821014 -267.162738)
		(end 85.00491 -267.113258)
		(width 0.0889)
		(layer "In2.Cu")
		(net "M_C_CPU1_SA_RSP<0>")
	)
	(arc
		(start 94.41561 -267.107162)
		(mid 94.697199 -267.036288)
		(end 94.977204 -267.113258)
		(width 0.0889)
		(layer "In2.Cu")
		(net "M_C_CPU1_SA_RSP<0>")
	)
	(arc
		(start 91.217242 -267.113258)
		(mid 91.401138 -267.162738)
		(end 91.585034 -267.113258)
		(width 0.0889)
		(layer "In2.Cu")
		(net "M_C_CPU1_SA_RSP<0>")
	)
	(arc
		(start 93.464888 -267.113258)
		(mid 93.744892 -267.036213)
		(end 94.026482 -267.107162)
		(width 0.0889)
		(layer "In2.Cu")
		(net "M_C_CPU1_SA_RSP<0>")
	)
	(arc
		(start 93.097096 -267.113258)
		(mid 93.280992 -267.162738)
		(end 93.464888 -267.113258)
		(width 0.0889)
		(layer "In2.Cu")
		(net "M_C_CPU1_SA_RSP<0>")
	)
	(arc
		(start 95.355664 -267.107162)
		(mid 95.599555 -267.037013)
		(end 95.849694 -267.07973)
		(width 0.0889)
		(layer "In2.Cu")
		(net "M_C_CPU1_SA_RSP<0>")
	)
	(arc
		(start 90.655648 -267.107162)
		(mid 90.937237 -267.036288)
		(end 91.217242 -267.113258)
		(width 0.0889)
		(layer "In2.Cu")
		(net "M_C_CPU1_SA_RSP<0>")
	)
	(arc
		(start 94.03715 -267.113258)
		(mid 94.221046 -267.162738)
		(end 94.404942 -267.113258)
		(width 0.0889)
		(layer "In2.Cu")
		(net "M_C_CPU1_SA_RSP<0>")
	)
	(arc
		(start 87.824818 -267.113258)
		(mid 88.104822 -267.036213)
		(end 88.386412 -267.107162)
		(width 0.0889)
		(layer "In2.Cu")
		(net "M_C_CPU1_SA_RSP<0>")
	)
	(arc
		(start 89.337134 -267.113258)
		(mid 89.52103 -267.162738)
		(end 89.704926 -267.113258)
		(width 0.0889)
		(layer "In2.Cu")
		(net "M_C_CPU1_SA_RSP<0>")
	)
	(arc
		(start 86.885018 -267.113258)
		(mid 87.171022 -267.036306)
		(end 87.457026 -267.113258)
		(width 0.0889)
		(layer "In2.Cu")
		(net "M_C_CPU1_SA_RSP<0>")
	)
	(arc
		(start 81.255616 -267.107162)
		(mid 81.537205 -267.036288)
		(end 81.81721 -267.113258)
		(width 0.0889)
		(layer "In2.Cu")
		(net "M_C_CPU1_SA_RSP<0>")
	)
	(arc
		(start 83.124802 -267.113258)
		(mid 83.404806 -267.036213)
		(end 83.686396 -267.107162)
		(width 0.0889)
		(layer "In2.Cu")
		(net "M_C_CPU1_SA_RSP<0>")
	)
	(arc
		(start 82.185002 -267.113258)
		(mid 82.471006 -267.036306)
		(end 82.75701 -267.113258)
		(width 0.0889)
		(layer "In2.Cu")
		(net "M_C_CPU1_SA_RSP<0>")
	)
	(arc
		(start 80.304894 -267.113258)
		(mid 80.584898 -267.036213)
		(end 80.866488 -267.107162)
		(width 0.0889)
		(layer "In2.Cu")
		(net "M_C_CPU1_SA_RSP<0>")
	)
	(arc
		(start 94.977204 -267.113258)
		(mid 95.1611 -267.162738)
		(end 95.344996 -267.113258)
		(width 0.0889)
		(layer "In2.Cu")
		(net "M_C_CPU1_SA_RSP<0>")
	)
	(arc
		(start 86.517226 -267.113258)
		(mid 86.701122 -267.162738)
		(end 86.885018 -267.113258)
		(width 0.0889)
		(layer "In2.Cu")
		(net "M_C_CPU1_SA_RSP<0>")
	)
	(arc
		(start 85.577172 -267.113258)
		(mid 85.761068 -267.162738)
		(end 85.944964 -267.113258)
		(width 0.0889)
		(layer "In2.Cu")
		(net "M_C_CPU1_SA_RSP<0>")
	)
	(arc
		(start 85.015578 -267.107162)
		(mid 85.297167 -267.036288)
		(end 85.577172 -267.113258)
		(width 0.0889)
		(layer "In2.Cu")
		(net "M_C_CPU1_SA_RSP<0>")
	)
	(arc
		(start 85.955632 -267.107162)
		(mid 86.237221 -267.036288)
		(end 86.517226 -267.113258)
		(width 0.0889)
		(layer "In2.Cu")
		(net "M_C_CPU1_SA_RSP<0>")
	)
	(arc
		(start 83.697064 -267.113258)
		(mid 83.88096 -267.162738)
		(end 84.064856 -267.113258)
		(width 0.0889)
		(layer "In2.Cu")
		(net "M_C_CPU1_SA_RSP<0>")
	)
	(arc
		(start 88.39708 -267.113258)
		(mid 88.580976 -267.162738)
		(end 88.764872 -267.113258)
		(width 0.0889)
		(layer "In2.Cu")
		(net "M_C_CPU1_SA_RSP<0>")
	)
	(arc
		(start 82.75701 -267.113258)
		(mid 82.940906 -267.162738)
		(end 83.124802 -267.113258)
		(width 0.0889)
		(layer "In2.Cu")
		(net "M_C_CPU1_SA_RSP<0>")
	)
	(arc
		(start 89.715594 -267.107162)
		(mid 89.997183 -267.036288)
		(end 90.277188 -267.113258)
		(width 0.0889)
		(layer "In2.Cu")
		(net "M_C_CPU1_SA_RSP<0>")
	)
	(arc
		(start 88.764872 -267.113258)
		(mid 89.044876 -267.036213)
		(end 89.326466 -267.107162)
		(width 0.0889)
		(layer "In2.Cu")
		(net "M_C_CPU1_SA_RSP<0>")
	)
	(arc
		(start 92.157042 -267.113258)
		(mid 92.340938 -267.162738)
		(end 92.524834 -267.113258)
		(width 0.0889)
		(layer "In2.Cu")
		(net "M_C_CPU1_SA_RSP<0>")
	)
	(arc
		(start 90.277188 -267.113258)
		(mid 90.461084 -267.162738)
		(end 90.64498 -267.113258)
		(width 0.0889)
		(layer "In2.Cu")
		(net "M_C_CPU1_SA_RSP<0>")
	)
	(arc
		(start 91.585034 -267.113258)
		(mid 91.871038 -267.036306)
		(end 92.157042 -267.113258)
		(width 0.0889)
		(layer "In2.Cu")
		(net "M_C_CPU1_SA_RSP<0>")
	)
	(arc
		(start 80.877156 -267.113258)
		(mid 81.061052 -267.162738)
		(end 81.244948 -267.113258)
		(width 0.0889)
		(layer "In2.Cu")
		(net "M_C_CPU1_SA_RSP<0>")
	)
	(arc
		(start 84.064856 -267.113258)
		(mid 84.34486 -267.036213)
		(end 84.62645 -267.107162)
		(width 0.0889)
		(layer "In2.Cu")
		(net "M_C_CPU1_SA_RSP<0>")
	)
	(segment
		(start 96.267778 -256.09042)
		(end 95.800926 -255.824482)
		(width 0.10668)
		(layer "F.Cu")
		(net "M_C_CPU1_SA_PAR")
	)
	(segment
		(start 46.049438 -255.56591)
		(end 48.34001 -255.56591)
		(width 0.14478)
		(layer "In2.Cu")
		(net "M_C_CPU1_SA_PAR")
	)
	(segment
		(start 77.927454 -255.660144)
		(end 78.170786 -255.660144)
		(width 0.0889)
		(layer "In2.Cu")
		(net "M_C_CPU1_SA_PAR")
	)
	(segment
		(start 68.62826 -254.941324)
		(end 71.288656 -254.941324)
		(width 0.14478)
		(layer "In2.Cu")
		(net "M_C_CPU1_SA_PAR")
	)
	(segment
		(start 50.729134 -255.402842)
		(end 50.729134 -255.335532)
		(width 0.14478)
		(layer "In2.Cu")
		(net "M_C_CPU1_SA_PAR")
	)
	(segment
		(start 51.12258 -255.172464)
		(end 51.285648 -255.335532)
		(width 0.14478)
		(layer "In2.Cu")
		(net "M_C_CPU1_SA_PAR")
	)
	(segment
		(start 53.141118 -255.56591)
		(end 53.304186 -255.402842)
		(width 0.14478)
		(layer "In2.Cu")
		(net "M_C_CPU1_SA_PAR")
	)
	(segment
		(start 48.666146 -255.172464)
		(end 48.896524 -255.172464)
		(width 0.14478)
		(layer "In2.Cu")
		(net "M_C_CPU1_SA_PAR")
	)
	(segment
		(start 95.647002 -255.559052)
		(end 95.800926 -255.824482)
		(width 0.0889)
		(layer "In2.Cu")
		(net "M_C_CPU1_SA_PAR")
	)
	(segment
		(start 91.85402 -255.501902)
		(end 91.862402 -255.497076)
		(width 0.0889)
		(layer "In2.Cu")
		(net "M_C_CPU1_SA_PAR")
	)
	(segment
		(start 53.467254 -255.187704)
		(end 53.697632 -255.187704)
		(width 0.14478)
		(layer "In2.Cu")
		(net "M_C_CPU1_SA_PAR")
	)
	(segment
		(start 44.76496 -254.710184)
		(end 45.193712 -254.710184)
		(width 0.14478)
		(layer "In2.Cu")
		(net "M_C_CPU1_SA_PAR")
	)
	(segment
		(start 48.34001 -255.56591)
		(end 48.503078 -255.402842)
		(width 0.14478)
		(layer "In2.Cu")
		(net "M_C_CPU1_SA_PAR")
	)
	(segment
		(start 67.120008 -255.56591)
		(end 68.62826 -254.941324)
		(width 0.14478)
		(layer "In2.Cu")
		(net "M_C_CPU1_SA_PAR")
	)
	(segment
		(start 48.503078 -255.402842)
		(end 48.503078 -255.335532)
		(width 0.14478)
		(layer "In2.Cu")
		(net "M_C_CPU1_SA_PAR")
	)
	(segment
		(start 48.503078 -255.335532)
		(end 48.666146 -255.172464)
		(width 0.14478)
		(layer "In2.Cu")
		(net "M_C_CPU1_SA_PAR")
	)
	(segment
		(start 79.609188 -255.517142)
		(end 79.63535 -255.502156)
		(width 0.0889)
		(layer "In2.Cu")
		(net "M_C_CPU1_SA_PAR")
	)
	(segment
		(start 90.913966 -255.501902)
		(end 90.922348 -255.497076)
		(width 0.0889)
		(layer "In2.Cu")
		(net "M_C_CPU1_SA_PAR")
	)
	(segment
		(start 49.779174 -255.172464)
		(end 50.009552 -255.172464)
		(width 0.14478)
		(layer "In2.Cu")
		(net "M_C_CPU1_SA_PAR")
	)
	(segment
		(start 50.17262 -255.335532)
		(end 50.17262 -255.402842)
		(width 0.14478)
		(layer "In2.Cu")
		(net "M_C_CPU1_SA_PAR")
	)
	(segment
		(start 50.566066 -255.56591)
		(end 50.729134 -255.402842)
		(width 0.14478)
		(layer "In2.Cu")
		(net "M_C_CPU1_SA_PAR")
	)
	(segment
		(start 50.009552 -255.172464)
		(end 50.17262 -255.335532)
		(width 0.14478)
		(layer "In2.Cu")
		(net "M_C_CPU1_SA_PAR")
	)
	(segment
		(start 51.448716 -255.56591)
		(end 53.141118 -255.56591)
		(width 0.14478)
		(layer "In2.Cu")
		(net "M_C_CPU1_SA_PAR")
	)
	(segment
		(start 83.394042 -255.501902)
		(end 83.402424 -255.497076)
		(width 0.0889)
		(layer "In2.Cu")
		(net "M_C_CPU1_SA_PAR")
	)
	(segment
		(start 94.099634 -255.497076)
		(end 94.108016 -255.501902)
		(width 0.0889)
		(layer "In2.Cu")
		(net "M_C_CPU1_SA_PAR")
	)
	(segment
		(start 50.335688 -255.56591)
		(end 50.566066 -255.56591)
		(width 0.14478)
		(layer "In2.Cu")
		(net "M_C_CPU1_SA_PAR")
	)
	(segment
		(start 50.892202 -255.172464)
		(end 51.12258 -255.172464)
		(width 0.14478)
		(layer "In2.Cu")
		(net "M_C_CPU1_SA_PAR")
	)
	(segment
		(start 76.085446 -256.495804)
		(end 77.091794 -256.495804)
		(width 0.0889)
		(layer "In2.Cu")
		(net "M_C_CPU1_SA_PAR")
	)
	(segment
		(start 49.616106 -255.335532)
		(end 49.779174 -255.172464)
		(width 0.14478)
		(layer "In2.Cu")
		(net "M_C_CPU1_SA_PAR")
	)
	(segment
		(start 53.304186 -255.350772)
		(end 53.467254 -255.187704)
		(width 0.14478)
		(layer "In2.Cu")
		(net "M_C_CPU1_SA_PAR")
	)
	(segment
		(start 85.639656 -255.497076)
		(end 85.648038 -255.501902)
		(width 0.0889)
		(layer "In2.Cu")
		(net "M_C_CPU1_SA_PAR")
	)
	(segment
		(start 51.285648 -255.402842)
		(end 51.448716 -255.56591)
		(width 0.14478)
		(layer "In2.Cu")
		(net "M_C_CPU1_SA_PAR")
	)
	(segment
		(start 87.154004 -255.501902)
		(end 87.162386 -255.497076)
		(width 0.0889)
		(layer "In2.Cu")
		(net "M_C_CPU1_SA_PAR")
	)
	(segment
		(start 81.879694 -255.497076)
		(end 81.888076 -255.501902)
		(width 0.0889)
		(layer "In2.Cu")
		(net "M_C_CPU1_SA_PAR")
	)
	(segment
		(start 79.63535 -255.502156)
		(end 79.658718 -255.488694)
		(width 0.0889)
		(layer "In2.Cu")
		(net "M_C_CPU1_SA_PAR")
	)
	(segment
		(start 95.55099 -255.533652)
		(end 95.647002 -255.559052)
		(width 0.0889)
		(layer "In2.Cu")
		(net "M_C_CPU1_SA_PAR")
	)
	(segment
		(start 48.896524 -255.172464)
		(end 49.059592 -255.335532)
		(width 0.14478)
		(layer "In2.Cu")
		(net "M_C_CPU1_SA_PAR")
	)
	(segment
		(start 77.091794 -256.495804)
		(end 77.927454 -255.660144)
		(width 0.0889)
		(layer "In2.Cu")
		(net "M_C_CPU1_SA_PAR")
	)
	(segment
		(start 50.17262 -255.402842)
		(end 50.335688 -255.56591)
		(width 0.14478)
		(layer "In2.Cu")
		(net "M_C_CPU1_SA_PAR")
	)
	(segment
		(start 79.050896 -255.489964)
		(end 79.07147 -255.501902)
		(width 0.0889)
		(layer "In2.Cu")
		(net "M_C_CPU1_SA_PAR")
	)
	(segment
		(start 49.616106 -255.402842)
		(end 49.616106 -255.335532)
		(width 0.14478)
		(layer "In2.Cu")
		(net "M_C_CPU1_SA_PAR")
	)
	(segment
		(start 53.697632 -255.187704)
		(end 53.8607 -255.350772)
		(width 0.14478)
		(layer "In2.Cu")
		(net "M_C_CPU1_SA_PAR")
	)
	(segment
		(start 49.453038 -255.56591)
		(end 49.616106 -255.402842)
		(width 0.14478)
		(layer "In2.Cu")
		(net "M_C_CPU1_SA_PAR")
	)
	(segment
		(start 49.22266 -255.56591)
		(end 49.453038 -255.56591)
		(width 0.14478)
		(layer "In2.Cu")
		(net "M_C_CPU1_SA_PAR")
	)
	(segment
		(start 44.340018 -254.285242)
		(end 44.76496 -254.710184)
		(width 0.14478)
		(layer "In2.Cu")
		(net "M_C_CPU1_SA_PAR")
	)
	(segment
		(start 45.193712 -254.710184)
		(end 46.049438 -255.56591)
		(width 0.14478)
		(layer "In2.Cu")
		(net "M_C_CPU1_SA_PAR")
	)
	(segment
		(start 53.8607 -255.350772)
		(end 53.8607 -255.402842)
		(width 0.14478)
		(layer "In2.Cu")
		(net "M_C_CPU1_SA_PAR")
	)
	(segment
		(start 86.57971 -255.497076)
		(end 86.588092 -255.501902)
		(width 0.0889)
		(layer "In2.Cu")
		(net "M_C_CPU1_SA_PAR")
	)
	(segment
		(start 53.304186 -255.402842)
		(end 53.304186 -255.350772)
		(width 0.14478)
		(layer "In2.Cu")
		(net "M_C_CPU1_SA_PAR")
	)
	(segment
		(start 95.039688 -255.497076)
		(end 95.04807 -255.501902)
		(width 0.0889)
		(layer "In2.Cu")
		(net "M_C_CPU1_SA_PAR")
	)
	(segment
		(start 88.094058 -255.501902)
		(end 88.10244 -255.497076)
		(width 0.0889)
		(layer "In2.Cu")
		(net "M_C_CPU1_SA_PAR")
	)
	(segment
		(start 71.288656 -254.941324)
		(end 72.843136 -256.495804)
		(width 0.14478)
		(layer "In2.Cu")
		(net "M_C_CPU1_SA_PAR")
	)
	(segment
		(start 90.339672 -255.497076)
		(end 90.348054 -255.501902)
		(width 0.0889)
		(layer "In2.Cu")
		(net "M_C_CPU1_SA_PAR")
	)
	(segment
		(start 51.285648 -255.335532)
		(end 51.285648 -255.402842)
		(width 0.14478)
		(layer "In2.Cu")
		(net "M_C_CPU1_SA_PAR")
	)
	(segment
		(start 53.8607 -255.402842)
		(end 54.023768 -255.56591)
		(width 0.14478)
		(layer "In2.Cu")
		(net "M_C_CPU1_SA_PAR")
	)
	(segment
		(start 50.729134 -255.335532)
		(end 50.892202 -255.172464)
		(width 0.14478)
		(layer "In2.Cu")
		(net "M_C_CPU1_SA_PAR")
	)
	(segment
		(start 72.843136 -256.495804)
		(end 76.085446 -256.495804)
		(width 0.14478)
		(layer "In2.Cu")
		(net "M_C_CPU1_SA_PAR")
	)
	(segment
		(start 49.059592 -255.335532)
		(end 49.059592 -255.402842)
		(width 0.14478)
		(layer "In2.Cu")
		(net "M_C_CPU1_SA_PAR")
	)
	(segment
		(start 78.645004 -255.531874)
		(end 78.696058 -255.501902)
		(width 0.0889)
		(layer "In2.Cu")
		(net "M_C_CPU1_SA_PAR")
	)
	(segment
		(start 82.453988 -255.501902)
		(end 82.46237 -255.497076)
		(width 0.0889)
		(layer "In2.Cu")
		(net "M_C_CPU1_SA_PAR")
	)
	(segment
		(start 54.023768 -255.56591)
		(end 67.120008 -255.56591)
		(width 0.14478)
		(layer "In2.Cu")
		(net "M_C_CPU1_SA_PAR")
	)
	(segment
		(start 49.059592 -255.402842)
		(end 49.22266 -255.56591)
		(width 0.14478)
		(layer "In2.Cu")
		(net "M_C_CPU1_SA_PAR")
	)
	(arc
		(start 90.348054 -255.501902)
		(mid 90.63101 -255.578079)
		(end 90.913966 -255.501902)
		(width 0.0889)
		(layer "In2.Cu")
		(net "M_C_CPU1_SA_PAR")
	)
	(arc
		(start 79.07147 -255.501902)
		(mid 79.3384 -255.577851)
		(end 79.609188 -255.517142)
		(width 0.0889)
		(layer "In2.Cu")
		(net "M_C_CPU1_SA_PAR")
	)
	(arc
		(start 91.288108 -255.501902)
		(mid 91.571064 -255.578079)
		(end 91.85402 -255.501902)
		(width 0.0889)
		(layer "In2.Cu")
		(net "M_C_CPU1_SA_PAR")
	)
	(arc
		(start 93.167962 -255.501902)
		(mid 93.450918 -255.578079)
		(end 93.733874 -255.501902)
		(width 0.0889)
		(layer "In2.Cu")
		(net "M_C_CPU1_SA_PAR")
	)
	(arc
		(start 83.402424 -255.497076)
		(mid 83.585932 -255.451582)
		(end 83.768184 -255.501902)
		(width 0.0889)
		(layer "In2.Cu")
		(net "M_C_CPU1_SA_PAR")
	)
	(arc
		(start 95.04807 -255.501902)
		(mid 95.295783 -255.577122)
		(end 95.55099 -255.533652)
		(width 0.0889)
		(layer "In2.Cu")
		(net "M_C_CPU1_SA_PAR")
	)
	(arc
		(start 94.108016 -255.501902)
		(mid 94.390972 -255.578079)
		(end 94.673928 -255.501902)
		(width 0.0889)
		(layer "In2.Cu")
		(net "M_C_CPU1_SA_PAR")
	)
	(arc
		(start 89.408 -255.501902)
		(mid 89.690956 -255.578079)
		(end 89.973912 -255.501902)
		(width 0.0889)
		(layer "In2.Cu")
		(net "M_C_CPU1_SA_PAR")
	)
	(arc
		(start 79.658718 -255.488694)
		(mid 79.835113 -255.451791)
		(end 80.008222 -255.501902)
		(width 0.0889)
		(layer "In2.Cu")
		(net "M_C_CPU1_SA_PAR")
	)
	(arc
		(start 81.513934 -255.501902)
		(mid 81.696185 -255.451552)
		(end 81.879694 -255.497076)
		(width 0.0889)
		(layer "In2.Cu")
		(net "M_C_CPU1_SA_PAR")
	)
	(arc
		(start 83.768184 -255.501902)
		(mid 84.05114 -255.578079)
		(end 84.334096 -255.501902)
		(width 0.0889)
		(layer "In2.Cu")
		(net "M_C_CPU1_SA_PAR")
	)
	(arc
		(start 93.733874 -255.501902)
		(mid 93.916125 -255.451552)
		(end 94.099634 -255.497076)
		(width 0.0889)
		(layer "In2.Cu")
		(net "M_C_CPU1_SA_PAR")
	)
	(arc
		(start 90.922348 -255.497076)
		(mid 91.105856 -255.451582)
		(end 91.288108 -255.501902)
		(width 0.0889)
		(layer "In2.Cu")
		(net "M_C_CPU1_SA_PAR")
	)
	(arc
		(start 89.034112 -255.501902)
		(mid 89.221056 -255.451647)
		(end 89.408 -255.501902)
		(width 0.0889)
		(layer "In2.Cu")
		(net "M_C_CPU1_SA_PAR")
	)
	(arc
		(start 81.888076 -255.501902)
		(mid 82.171032 -255.578079)
		(end 82.453988 -255.501902)
		(width 0.0889)
		(layer "In2.Cu")
		(net "M_C_CPU1_SA_PAR")
	)
	(arc
		(start 78.696058 -255.501902)
		(mid 78.871968 -255.451092)
		(end 79.050896 -255.489964)
		(width 0.0889)
		(layer "In2.Cu")
		(net "M_C_CPU1_SA_PAR")
	)
	(arc
		(start 94.673928 -255.501902)
		(mid 94.856179 -255.451552)
		(end 95.039688 -255.497076)
		(width 0.0889)
		(layer "In2.Cu")
		(net "M_C_CPU1_SA_PAR")
	)
	(arc
		(start 82.46237 -255.497076)
		(mid 82.645878 -255.451582)
		(end 82.82813 -255.501902)
		(width 0.0889)
		(layer "In2.Cu")
		(net "M_C_CPU1_SA_PAR")
	)
	(arc
		(start 86.588092 -255.501902)
		(mid 86.871048 -255.578079)
		(end 87.154004 -255.501902)
		(width 0.0889)
		(layer "In2.Cu")
		(net "M_C_CPU1_SA_PAR")
	)
	(arc
		(start 88.4682 -255.501902)
		(mid 88.751156 -255.578079)
		(end 89.034112 -255.501902)
		(width 0.0889)
		(layer "In2.Cu")
		(net "M_C_CPU1_SA_PAR")
	)
	(arc
		(start 80.948022 -255.501902)
		(mid 81.230978 -255.578079)
		(end 81.513934 -255.501902)
		(width 0.0889)
		(layer "In2.Cu")
		(net "M_C_CPU1_SA_PAR")
	)
	(arc
		(start 91.862402 -255.497076)
		(mid 92.04591 -255.451582)
		(end 92.228162 -255.501902)
		(width 0.0889)
		(layer "In2.Cu")
		(net "M_C_CPU1_SA_PAR")
	)
	(arc
		(start 85.648038 -255.501902)
		(mid 85.930994 -255.578079)
		(end 86.21395 -255.501902)
		(width 0.0889)
		(layer "In2.Cu")
		(net "M_C_CPU1_SA_PAR")
	)
	(arc
		(start 89.973912 -255.501902)
		(mid 90.156163 -255.451552)
		(end 90.339672 -255.497076)
		(width 0.0889)
		(layer "In2.Cu")
		(net "M_C_CPU1_SA_PAR")
	)
	(arc
		(start 78.170786 -255.660144)
		(mid 78.416425 -255.627543)
		(end 78.645004 -255.531874)
		(width 0.0889)
		(layer "In2.Cu")
		(net "M_C_CPU1_SA_PAR")
	)
	(arc
		(start 85.273896 -255.501902)
		(mid 85.456147 -255.451552)
		(end 85.639656 -255.497076)
		(width 0.0889)
		(layer "In2.Cu")
		(net "M_C_CPU1_SA_PAR")
	)
	(arc
		(start 87.162386 -255.497076)
		(mid 87.345894 -255.451582)
		(end 87.528146 -255.501902)
		(width 0.0889)
		(layer "In2.Cu")
		(net "M_C_CPU1_SA_PAR")
	)
	(arc
		(start 86.21395 -255.501902)
		(mid 86.396201 -255.451552)
		(end 86.57971 -255.497076)
		(width 0.0889)
		(layer "In2.Cu")
		(net "M_C_CPU1_SA_PAR")
	)
	(arc
		(start 84.334096 -255.501902)
		(mid 84.52104 -255.451647)
		(end 84.707984 -255.501902)
		(width 0.0889)
		(layer "In2.Cu")
		(net "M_C_CPU1_SA_PAR")
	)
	(arc
		(start 82.82813 -255.501902)
		(mid 83.111086 -255.578079)
		(end 83.394042 -255.501902)
		(width 0.0889)
		(layer "In2.Cu")
		(net "M_C_CPU1_SA_PAR")
	)
	(arc
		(start 88.10244 -255.497076)
		(mid 88.285948 -255.451582)
		(end 88.4682 -255.501902)
		(width 0.0889)
		(layer "In2.Cu")
		(net "M_C_CPU1_SA_PAR")
	)
	(arc
		(start 80.574134 -255.501902)
		(mid 80.761078 -255.451647)
		(end 80.948022 -255.501902)
		(width 0.0889)
		(layer "In2.Cu")
		(net "M_C_CPU1_SA_PAR")
	)
	(arc
		(start 87.528146 -255.501902)
		(mid 87.811102 -255.578079)
		(end 88.094058 -255.501902)
		(width 0.0889)
		(layer "In2.Cu")
		(net "M_C_CPU1_SA_PAR")
	)
	(arc
		(start 92.794074 -255.501902)
		(mid 92.981018 -255.451647)
		(end 93.167962 -255.501902)
		(width 0.0889)
		(layer "In2.Cu")
		(net "M_C_CPU1_SA_PAR")
	)
	(arc
		(start 84.707984 -255.501902)
		(mid 84.99094 -255.578079)
		(end 85.273896 -255.501902)
		(width 0.0889)
		(layer "In2.Cu")
		(net "M_C_CPU1_SA_PAR")
	)
	(arc
		(start 80.008222 -255.501902)
		(mid 80.291178 -255.578079)
		(end 80.574134 -255.501902)
		(width 0.0889)
		(layer "In2.Cu")
		(net "M_C_CPU1_SA_PAR")
	)
	(arc
		(start 92.228162 -255.501902)
		(mid 92.511118 -255.578079)
		(end 92.794074 -255.501902)
		(width 0.0889)
		(layer "In2.Cu")
		(net "M_C_CPU1_SA_PAR")
	)
	(segment
		(start 96.267778 -247.99036)
		(end 95.800926 -247.724422)
		(width 0.12954)
		(layer "F.Cu")
		(net "M_C_CPU1_SA_DQS_DP<9>")
	)
	(segment
		(start 81.881218 -247.394476)
		(end 81.8896 -247.399302)
		(width 0.09525)
		(layer "In2.Cu")
		(net "M_C_CPU1_SA_DQS_DP<9>")
	)
	(segment
		(start 67.251326 -246.946166)
		(end 74.641202 -246.946166)
		(width 0.16002)
		(layer "In2.Cu")
		(net "M_C_CPU1_SA_DQS_DP<9>")
	)
	(segment
		(start 51.02225 -239.710468)
		(end 53.37429 -239.710468)
		(width 0.16002)
		(layer "In2.Cu")
		(net "M_C_CPU1_SA_DQS_DP<9>")
	)
	(segment
		(start 42.231564 -239.362488)
		(end 43.106848 -239.362488)
		(width 0.16002)
		(layer "In2.Cu")
		(net "M_C_CPU1_SA_DQS_DP<9>")
	)
	(segment
		(start 58.511948 -239.669828)
		(end 59.974988 -239.669828)
		(width 0.16002)
		(layer "In2.Cu")
		(net "M_C_CPU1_SA_DQS_DP<9>")
	)
	(segment
		(start 48.98771 -240.236248)
		(end 49.47793 -240.236248)
		(width 0.16002)
		(layer "In2.Cu")
		(net "M_C_CPU1_SA_DQS_DP<9>")
	)
	(segment
		(start 40.23995 -239.835436)
		(end 40.513762 -239.561624)
		(width 0.16002)
		(layer "In2.Cu")
		(net "M_C_CPU1_SA_DQS_DP<9>")
	)
	(segment
		(start 85.64118 -247.394476)
		(end 85.649562 -247.399302)
		(width 0.09525)
		(layer "In2.Cu")
		(net "M_C_CPU1_SA_DQS_DP<9>")
	)
	(segment
		(start 78.13167 -247.399556)
		(end 78.1685 -247.420892)
		(width 0.09525)
		(layer "In2.Cu")
		(net "M_C_CPU1_SA_DQS_DP<9>")
	)
	(segment
		(start 79.633826 -247.399556)
		(end 79.657194 -247.386094)
		(width 0.09525)
		(layer "In2.Cu")
		(net "M_C_CPU1_SA_DQS_DP<9>")
	)
	(segment
		(start 94.101158 -247.394476)
		(end 94.10954 -247.399302)
		(width 0.09525)
		(layer "In2.Cu")
		(net "M_C_CPU1_SA_DQS_DP<9>")
	)
	(segment
		(start 76.127102 -247.53443)
		(end 76.150724 -247.53443)
		(width 0.09525)
		(layer "In2.Cu")
		(net "M_C_CPU1_SA_DQS_DP<9>")
	)
	(segment
		(start 82.452464 -247.399302)
		(end 82.460846 -247.394476)
		(width 0.09525)
		(layer "In2.Cu")
		(net "M_C_CPU1_SA_DQS_DP<9>")
	)
	(segment
		(start 43.106848 -239.362488)
		(end 43.714162 -239.969802)
		(width 0.16002)
		(layer "In2.Cu")
		(net "M_C_CPU1_SA_DQS_DP<9>")
	)
	(segment
		(start 57.05983 -240.213388)
		(end 57.861962 -239.411256)
		(width 0.16002)
		(layer "In2.Cu")
		(net "M_C_CPU1_SA_DQS_DP<9>")
	)
	(segment
		(start 43.714162 -239.969802)
		(end 46.049184 -239.969802)
		(width 0.16002)
		(layer "In2.Cu")
		(net "M_C_CPU1_SA_DQS_DP<9>")
	)
	(segment
		(start 78.108302 -247.386094)
		(end 78.13167 -247.399556)
		(width 0.09525)
		(layer "In2.Cu")
		(net "M_C_CPU1_SA_DQS_DP<9>")
	)
	(segment
		(start 49.47793 -240.236248)
		(end 50.33137 -239.382808)
		(width 0.16002)
		(layer "In2.Cu")
		(net "M_C_CPU1_SA_DQS_DP<9>")
	)
	(segment
		(start 50.69459 -239.382808)
		(end 51.02225 -239.710468)
		(width 0.16002)
		(layer "In2.Cu")
		(net "M_C_CPU1_SA_DQS_DP<9>")
	)
	(segment
		(start 83.392518 -247.399302)
		(end 83.4009 -247.394476)
		(width 0.09525)
		(layer "In2.Cu")
		(net "M_C_CPU1_SA_DQS_DP<9>")
	)
	(segment
		(start 88.092534 -247.399302)
		(end 88.100916 -247.394476)
		(width 0.09525)
		(layer "In2.Cu")
		(net "M_C_CPU1_SA_DQS_DP<9>")
	)
	(segment
		(start 42.032428 -239.561624)
		(end 42.231564 -239.362488)
		(width 0.16002)
		(layer "In2.Cu")
		(net "M_C_CPU1_SA_DQS_DP<9>")
	)
	(segment
		(start 79.607918 -247.414542)
		(end 79.633826 -247.399556)
		(width 0.09525)
		(layer "In2.Cu")
		(net "M_C_CPU1_SA_DQS_DP<9>")
	)
	(segment
		(start 91.852496 -247.399302)
		(end 91.860878 -247.394476)
		(width 0.09525)
		(layer "In2.Cu")
		(net "M_C_CPU1_SA_DQS_DP<9>")
	)
	(segment
		(start 56.22671 -240.533428)
		(end 56.54675 -240.213388)
		(width 0.16002)
		(layer "In2.Cu")
		(net "M_C_CPU1_SA_DQS_DP<9>")
	)
	(segment
		(start 56.54675 -240.213388)
		(end 57.05983 -240.213388)
		(width 0.16002)
		(layer "In2.Cu")
		(net "M_C_CPU1_SA_DQS_DP<9>")
	)
	(segment
		(start 40.513762 -239.561624)
		(end 42.032428 -239.561624)
		(width 0.16002)
		(layer "In2.Cu")
		(net "M_C_CPU1_SA_DQS_DP<9>")
	)
	(segment
		(start 86.581234 -247.394476)
		(end 86.589616 -247.399302)
		(width 0.09525)
		(layer "In2.Cu")
		(net "M_C_CPU1_SA_DQS_DP<9>")
	)
	(segment
		(start 50.33137 -239.382808)
		(end 50.69459 -239.382808)
		(width 0.16002)
		(layer "In2.Cu")
		(net "M_C_CPU1_SA_DQS_DP<9>")
	)
	(segment
		(start 90.341196 -247.394476)
		(end 90.349578 -247.399302)
		(width 0.09525)
		(layer "In2.Cu")
		(net "M_C_CPU1_SA_DQS_DP<9>")
	)
	(segment
		(start 95.041212 -247.394476)
		(end 95.049594 -247.399302)
		(width 0.09525)
		(layer "In2.Cu")
		(net "M_C_CPU1_SA_DQS_DP<9>")
	)
	(segment
		(start 90.912442 -247.399302)
		(end 90.920824 -247.394476)
		(width 0.09525)
		(layer "In2.Cu")
		(net "M_C_CPU1_SA_DQS_DP<9>")
	)
	(segment
		(start 95.647002 -247.458992)
		(end 95.800926 -247.724422)
		(width 0.09525)
		(layer "In2.Cu")
		(net "M_C_CPU1_SA_DQS_DP<9>")
	)
	(segment
		(start 75.229466 -247.53443)
		(end 76.127102 -247.53443)
		(width 0.16002)
		(layer "In2.Cu")
		(net "M_C_CPU1_SA_DQS_DP<9>")
	)
	(segment
		(start 76.150724 -247.53443)
		(end 76.181966 -247.503188)
		(width 0.09525)
		(layer "In2.Cu")
		(net "M_C_CPU1_SA_DQS_DP<9>")
	)
	(segment
		(start 53.37429 -239.710468)
		(end 54.19725 -240.533428)
		(width 0.16002)
		(layer "In2.Cu")
		(net "M_C_CPU1_SA_DQS_DP<9>")
	)
	(segment
		(start 48.663352 -240.560606)
		(end 48.98771 -240.236248)
		(width 0.16002)
		(layer "In2.Cu")
		(net "M_C_CPU1_SA_DQS_DP<9>")
	)
	(segment
		(start 54.19725 -240.533428)
		(end 56.22671 -240.533428)
		(width 0.16002)
		(layer "In2.Cu")
		(net "M_C_CPU1_SA_DQS_DP<9>")
	)
	(segment
		(start 87.15248 -247.399302)
		(end 87.160862 -247.394476)
		(width 0.09525)
		(layer "In2.Cu")
		(net "M_C_CPU1_SA_DQS_DP<9>")
	)
	(segment
		(start 74.641202 -246.946166)
		(end 75.229466 -247.53443)
		(width 0.16002)
		(layer "In2.Cu")
		(net "M_C_CPU1_SA_DQS_DP<9>")
	)
	(segment
		(start 58.253376 -239.411256)
		(end 58.511948 -239.669828)
		(width 0.16002)
		(layer "In2.Cu")
		(net "M_C_CPU1_SA_DQS_DP<9>")
	)
	(segment
		(start 46.049184 -239.969802)
		(end 46.639988 -240.560606)
		(width 0.16002)
		(layer "In2.Cu")
		(net "M_C_CPU1_SA_DQS_DP<9>")
	)
	(segment
		(start 59.974988 -239.669828)
		(end 67.251326 -246.946166)
		(width 0.16002)
		(layer "In2.Cu")
		(net "M_C_CPU1_SA_DQS_DP<9>")
	)
	(segment
		(start 46.639988 -240.560606)
		(end 48.663352 -240.560606)
		(width 0.16002)
		(layer "In2.Cu")
		(net "M_C_CPU1_SA_DQS_DP<9>")
	)
	(segment
		(start 57.861962 -239.411256)
		(end 58.253376 -239.411256)
		(width 0.16002)
		(layer "In2.Cu")
		(net "M_C_CPU1_SA_DQS_DP<9>")
	)
	(segment
		(start 79.049626 -247.38584)
		(end 79.072994 -247.399302)
		(width 0.09525)
		(layer "In2.Cu")
		(net "M_C_CPU1_SA_DQS_DP<9>")
	)
	(segment
		(start 76.249276 -247.475248)
		(end 77.474572 -247.475248)
		(width 0.09525)
		(layer "In2.Cu")
		(net "M_C_CPU1_SA_DQS_DP<9>")
	)
	(segment
		(start 95.546164 -247.432322)
		(end 95.647002 -247.458992)
		(width 0.09525)
		(layer "In2.Cu")
		(net "M_C_CPU1_SA_DQS_DP<9>")
	)
	(arc
		(start 82.460846 -247.394476)
		(mid 82.645878 -247.348562)
		(end 82.829654 -247.399302)
		(width 0.09525)
		(layer "In2.Cu")
		(net "M_C_CPU1_SA_DQS_DP<9>")
	)
	(arc
		(start 90.920824 -247.394476)
		(mid 91.105856 -247.348562)
		(end 91.289632 -247.399302)
		(width 0.09525)
		(layer "In2.Cu")
		(net "M_C_CPU1_SA_DQS_DP<9>")
	)
	(arc
		(start 86.212426 -247.399302)
		(mid 86.396201 -247.34853)
		(end 86.581234 -247.394476)
		(width 0.09525)
		(layer "In2.Cu")
		(net "M_C_CPU1_SA_DQS_DP<9>")
	)
	(arc
		(start 95.526352 -247.440196)
		(mid 95.536295 -247.436353)
		(end 95.546164 -247.432322)
		(width 0.09525)
		(layer "In2.Cu")
		(net "M_C_CPU1_SA_DQS_DP<9>")
	)
	(arc
		(start 88.469724 -247.399302)
		(mid 88.751156 -247.475057)
		(end 89.032588 -247.399302)
		(width 0.09525)
		(layer "In2.Cu")
		(net "M_C_CPU1_SA_DQS_DP<9>")
	)
	(arc
		(start 87.160862 -247.394476)
		(mid 87.345894 -247.348562)
		(end 87.52967 -247.399302)
		(width 0.09525)
		(layer "In2.Cu")
		(net "M_C_CPU1_SA_DQS_DP<9>")
	)
	(arc
		(start 89.972388 -247.399302)
		(mid 90.156163 -247.34853)
		(end 90.341196 -247.394476)
		(width 0.09525)
		(layer "In2.Cu")
		(net "M_C_CPU1_SA_DQS_DP<9>")
	)
	(arc
		(start 83.4009 -247.394476)
		(mid 83.585932 -247.348562)
		(end 83.769708 -247.399302)
		(width 0.09525)
		(layer "In2.Cu")
		(net "M_C_CPU1_SA_DQS_DP<9>")
	)
	(arc
		(start 80.009746 -247.399302)
		(mid 80.291178 -247.475057)
		(end 80.57261 -247.399302)
		(width 0.09525)
		(layer "In2.Cu")
		(net "M_C_CPU1_SA_DQS_DP<9>")
	)
	(arc
		(start 86.589616 -247.399302)
		(mid 86.871048 -247.475057)
		(end 87.15248 -247.399302)
		(width 0.09525)
		(layer "In2.Cu")
		(net "M_C_CPU1_SA_DQS_DP<9>")
	)
	(arc
		(start 94.10954 -247.399302)
		(mid 94.390972 -247.475057)
		(end 94.672404 -247.399302)
		(width 0.09525)
		(layer "In2.Cu")
		(net "M_C_CPU1_SA_DQS_DP<9>")
	)
	(arc
		(start 89.032588 -247.399302)
		(mid 89.221056 -247.348625)
		(end 89.409524 -247.399302)
		(width 0.09525)
		(layer "In2.Cu")
		(net "M_C_CPU1_SA_DQS_DP<9>")
	)
	(arc
		(start 84.332572 -247.399302)
		(mid 84.52104 -247.348625)
		(end 84.709508 -247.399302)
		(width 0.09525)
		(layer "In2.Cu")
		(net "M_C_CPU1_SA_DQS_DP<9>")
	)
	(arc
		(start 91.289632 -247.399302)
		(mid 91.571064 -247.475057)
		(end 91.852496 -247.399302)
		(width 0.09525)
		(layer "In2.Cu")
		(net "M_C_CPU1_SA_DQS_DP<9>")
	)
	(arc
		(start 89.409524 -247.399302)
		(mid 89.690956 -247.475057)
		(end 89.972388 -247.399302)
		(width 0.09525)
		(layer "In2.Cu")
		(net "M_C_CPU1_SA_DQS_DP<9>")
	)
	(arc
		(start 78.694534 -247.399048)
		(mid 78.870435 -247.347903)
		(end 79.049626 -247.38584)
		(width 0.09525)
		(layer "In2.Cu")
		(net "M_C_CPU1_SA_DQS_DP<9>")
	)
	(arc
		(start 78.1685 -247.420892)
		(mid 78.434219 -247.475386)
		(end 78.694534 -247.399048)
		(width 0.09525)
		(layer "In2.Cu")
		(net "M_C_CPU1_SA_DQS_DP<9>")
	)
	(arc
		(start 76.181966 -247.503188)
		(mid 76.212834 -247.482499)
		(end 76.249276 -247.475248)
		(width 0.09525)
		(layer "In2.Cu")
		(net "M_C_CPU1_SA_DQS_DP<9>")
	)
	(arc
		(start 84.709508 -247.399302)
		(mid 84.99094 -247.475057)
		(end 85.272372 -247.399302)
		(width 0.09525)
		(layer "In2.Cu")
		(net "M_C_CPU1_SA_DQS_DP<9>")
	)
	(arc
		(start 87.52967 -247.399302)
		(mid 87.811102 -247.475057)
		(end 88.092534 -247.399302)
		(width 0.09525)
		(layer "In2.Cu")
		(net "M_C_CPU1_SA_DQS_DP<9>")
	)
	(arc
		(start 79.072994 -247.399302)
		(mid 79.338514 -247.474831)
		(end 79.607918 -247.414542)
		(width 0.09525)
		(layer "In2.Cu")
		(net "M_C_CPU1_SA_DQS_DP<9>")
	)
	(arc
		(start 79.657194 -247.386094)
		(mid 79.835113 -247.348779)
		(end 80.009746 -247.399302)
		(width 0.09525)
		(layer "In2.Cu")
		(net "M_C_CPU1_SA_DQS_DP<9>")
	)
	(arc
		(start 83.769708 -247.399302)
		(mid 84.05114 -247.475057)
		(end 84.332572 -247.399302)
		(width 0.09525)
		(layer "In2.Cu")
		(net "M_C_CPU1_SA_DQS_DP<9>")
	)
	(arc
		(start 90.349578 -247.399302)
		(mid 90.63101 -247.475057)
		(end 90.912442 -247.399302)
		(width 0.09525)
		(layer "In2.Cu")
		(net "M_C_CPU1_SA_DQS_DP<9>")
	)
	(arc
		(start 81.51241 -247.399302)
		(mid 81.696185 -247.34853)
		(end 81.881218 -247.394476)
		(width 0.09525)
		(layer "In2.Cu")
		(net "M_C_CPU1_SA_DQS_DP<9>")
	)
	(arc
		(start 93.73235 -247.399302)
		(mid 93.916125 -247.34853)
		(end 94.101158 -247.394476)
		(width 0.09525)
		(layer "In2.Cu")
		(net "M_C_CPU1_SA_DQS_DP<9>")
	)
	(arc
		(start 77.756258 -247.399302)
		(mid 77.930636 -247.348889)
		(end 78.108302 -247.386094)
		(width 0.09525)
		(layer "In2.Cu")
		(net "M_C_CPU1_SA_DQS_DP<9>")
	)
	(arc
		(start 91.860878 -247.394476)
		(mid 92.04591 -247.348562)
		(end 92.229686 -247.399302)
		(width 0.09525)
		(layer "In2.Cu")
		(net "M_C_CPU1_SA_DQS_DP<9>")
	)
	(arc
		(start 85.649562 -247.399302)
		(mid 85.930994 -247.475057)
		(end 86.212426 -247.399302)
		(width 0.09525)
		(layer "In2.Cu")
		(net "M_C_CPU1_SA_DQS_DP<9>")
	)
	(arc
		(start 77.474572 -247.475248)
		(mid 77.620452 -247.455943)
		(end 77.756258 -247.399302)
		(width 0.09525)
		(layer "In2.Cu")
		(net "M_C_CPU1_SA_DQS_DP<9>")
	)
	(arc
		(start 94.672404 -247.399302)
		(mid 94.856179 -247.34853)
		(end 95.041212 -247.394476)
		(width 0.09525)
		(layer "In2.Cu")
		(net "M_C_CPU1_SA_DQS_DP<9>")
	)
	(arc
		(start 93.169486 -247.399302)
		(mid 93.450918 -247.475057)
		(end 93.73235 -247.399302)
		(width 0.09525)
		(layer "In2.Cu")
		(net "M_C_CPU1_SA_DQS_DP<9>")
	)
	(arc
		(start 92.79255 -247.399302)
		(mid 92.981018 -247.348625)
		(end 93.169486 -247.399302)
		(width 0.09525)
		(layer "In2.Cu")
		(net "M_C_CPU1_SA_DQS_DP<9>")
	)
	(arc
		(start 85.272372 -247.399302)
		(mid 85.456147 -247.34853)
		(end 85.64118 -247.394476)
		(width 0.09525)
		(layer "In2.Cu")
		(net "M_C_CPU1_SA_DQS_DP<9>")
	)
	(arc
		(start 80.57261 -247.399302)
		(mid 80.761078 -247.348625)
		(end 80.949546 -247.399302)
		(width 0.09525)
		(layer "In2.Cu")
		(net "M_C_CPU1_SA_DQS_DP<9>")
	)
	(arc
		(start 82.829654 -247.399302)
		(mid 83.111086 -247.475057)
		(end 83.392518 -247.399302)
		(width 0.09525)
		(layer "In2.Cu")
		(net "M_C_CPU1_SA_DQS_DP<9>")
	)
	(arc
		(start 80.949546 -247.399302)
		(mid 81.230978 -247.475057)
		(end 81.51241 -247.399302)
		(width 0.09525)
		(layer "In2.Cu")
		(net "M_C_CPU1_SA_DQS_DP<9>")
	)
	(arc
		(start 81.8896 -247.399302)
		(mid 82.171032 -247.475057)
		(end 82.452464 -247.399302)
		(width 0.09525)
		(layer "In2.Cu")
		(net "M_C_CPU1_SA_DQS_DP<9>")
	)
	(arc
		(start 88.100916 -247.394476)
		(mid 88.285948 -247.348562)
		(end 88.469724 -247.399302)
		(width 0.09525)
		(layer "In2.Cu")
		(net "M_C_CPU1_SA_DQS_DP<9>")
	)
	(arc
		(start 92.229686 -247.399302)
		(mid 92.511118 -247.475057)
		(end 92.79255 -247.399302)
		(width 0.09525)
		(layer "In2.Cu")
		(net "M_C_CPU1_SA_DQS_DP<9>")
	)
	(arc
		(start 95.049594 -247.399302)
		(mid 95.283389 -247.473169)
		(end 95.526352 -247.440196)
		(width 0.09525)
		(layer "In2.Cu")
		(net "M_C_CPU1_SA_DQS_DP<9>")
	)
	(segment
		(start 96.267778 -243.130324)
		(end 95.800926 -242.864386)
		(width 0.12954)
		(layer "F.Cu")
		(net "M_C_CPU1_SA_DQS_DP<8>")
	)
	(segment
		(start 58.253376 -230.061262)
		(end 58.511948 -230.319834)
		(width 0.16002)
		(layer "In2.Cu")
		(net "M_C_CPU1_SA_DQS_DP<8>")
	)
	(segment
		(start 95.647002 -242.598956)
		(end 95.800926 -242.864386)
		(width 0.09525)
		(layer "In2.Cu")
		(net "M_C_CPU1_SA_DQS_DP<8>")
	)
	(segment
		(start 50.33137 -230.032814)
		(end 50.654458 -230.032814)
		(width 0.16002)
		(layer "In2.Cu")
		(net "M_C_CPU1_SA_DQS_DP<8>")
	)
	(segment
		(start 40.513762 -230.21163)
		(end 42.032428 -230.21163)
		(width 0.16002)
		(layer "In2.Cu")
		(net "M_C_CPU1_SA_DQS_DP<8>")
	)
	(segment
		(start 50.654458 -230.032814)
		(end 50.982118 -230.360474)
		(width 0.16002)
		(layer "In2.Cu")
		(net "M_C_CPU1_SA_DQS_DP<8>")
	)
	(segment
		(start 48.663352 -231.210612)
		(end 48.98771 -230.886254)
		(width 0.16002)
		(layer "In2.Cu")
		(net "M_C_CPU1_SA_DQS_DP<8>")
	)
	(segment
		(start 79.632556 -242.539266)
		(end 79.640938 -242.53444)
		(width 0.09525)
		(layer "In2.Cu")
		(net "M_C_CPU1_SA_DQS_DP<8>")
	)
	(segment
		(start 54.19725 -231.183434)
		(end 56.244998 -231.183434)
		(width 0.16002)
		(layer "In2.Cu")
		(net "M_C_CPU1_SA_DQS_DP<8>")
	)
	(segment
		(start 71.836026 -241.255804)
		(end 75.955906 -241.255804)
		(width 0.16002)
		(layer "In2.Cu")
		(net "M_C_CPU1_SA_DQS_DP<8>")
	)
	(segment
		(start 50.982118 -230.360474)
		(end 53.37429 -230.360474)
		(width 0.16002)
		(layer "In2.Cu")
		(net "M_C_CPU1_SA_DQS_DP<8>")
	)
	(segment
		(start 83.392518 -242.539266)
		(end 83.4009 -242.53444)
		(width 0.09525)
		(layer "In2.Cu")
		(net "M_C_CPU1_SA_DQS_DP<8>")
	)
	(segment
		(start 48.98771 -230.886254)
		(end 49.47793 -230.886254)
		(width 0.16002)
		(layer "In2.Cu")
		(net "M_C_CPU1_SA_DQS_DP<8>")
	)
	(segment
		(start 76.929742 -241.097054)
		(end 77.255116 -241.422428)
		(width 0.09525)
		(layer "In2.Cu")
		(net "M_C_CPU1_SA_DQS_DP<8>")
	)
	(segment
		(start 43.714162 -230.619808)
		(end 46.049184 -230.619808)
		(width 0.16002)
		(layer "In2.Cu")
		(net "M_C_CPU1_SA_DQS_DP<8>")
	)
	(segment
		(start 53.37429 -230.360474)
		(end 54.19725 -231.183434)
		(width 0.16002)
		(layer "In2.Cu")
		(net "M_C_CPU1_SA_DQS_DP<8>")
	)
	(segment
		(start 91.852496 -242.539266)
		(end 91.860878 -242.53444)
		(width 0.09525)
		(layer "In2.Cu")
		(net "M_C_CPU1_SA_DQS_DP<8>")
	)
	(segment
		(start 60.900056 -230.319834)
		(end 71.836026 -241.255804)
		(width 0.16002)
		(layer "In2.Cu")
		(net "M_C_CPU1_SA_DQS_DP<8>")
	)
	(segment
		(start 79.03972 -242.520978)
		(end 79.071724 -242.53952)
		(width 0.09525)
		(layer "In2.Cu")
		(net "M_C_CPU1_SA_DQS_DP<8>")
	)
	(segment
		(start 88.092534 -242.539266)
		(end 88.100916 -242.53444)
		(width 0.09525)
		(layer "In2.Cu")
		(net "M_C_CPU1_SA_DQS_DP<8>")
	)
	(segment
		(start 57.040018 -230.863394)
		(end 57.84215 -230.061262)
		(width 0.16002)
		(layer "In2.Cu")
		(net "M_C_CPU1_SA_DQS_DP<8>")
	)
	(segment
		(start 46.639988 -231.210612)
		(end 48.663352 -231.210612)
		(width 0.16002)
		(layer "In2.Cu")
		(net "M_C_CPU1_SA_DQS_DP<8>")
	)
	(segment
		(start 77.255116 -241.422428)
		(end 77.255116 -241.690398)
		(width 0.09525)
		(layer "In2.Cu")
		(net "M_C_CPU1_SA_DQS_DP<8>")
	)
	(segment
		(start 78.13167 -242.53952)
		(end 78.1685 -242.560856)
		(width 0.09525)
		(layer "In2.Cu")
		(net "M_C_CPU1_SA_DQS_DP<8>")
	)
	(segment
		(start 77.255116 -241.690398)
		(end 78.015084 -242.450366)
		(width 0.09525)
		(layer "In2.Cu")
		(net "M_C_CPU1_SA_DQS_DP<8>")
	)
	(segment
		(start 49.47793 -230.886254)
		(end 50.33137 -230.032814)
		(width 0.16002)
		(layer "In2.Cu")
		(net "M_C_CPU1_SA_DQS_DP<8>")
	)
	(segment
		(start 79.071724 -242.53952)
		(end 79.097632 -242.554506)
		(width 0.09525)
		(layer "In2.Cu")
		(net "M_C_CPU1_SA_DQS_DP<8>")
	)
	(segment
		(start 75.979528 -241.255804)
		(end 76.038456 -241.196876)
		(width 0.09525)
		(layer "In2.Cu")
		(net "M_C_CPU1_SA_DQS_DP<8>")
	)
	(segment
		(start 40.23995 -230.485442)
		(end 40.513762 -230.21163)
		(width 0.16002)
		(layer "In2.Cu")
		(net "M_C_CPU1_SA_DQS_DP<8>")
	)
	(segment
		(start 57.84215 -230.061262)
		(end 58.253376 -230.061262)
		(width 0.16002)
		(layer "In2.Cu")
		(net "M_C_CPU1_SA_DQS_DP<8>")
	)
	(segment
		(start 87.15248 -242.539266)
		(end 87.160862 -242.53444)
		(width 0.09525)
		(layer "In2.Cu")
		(net "M_C_CPU1_SA_DQS_DP<8>")
	)
	(segment
		(start 86.581234 -242.53444)
		(end 86.589616 -242.539266)
		(width 0.09525)
		(layer "In2.Cu")
		(net "M_C_CPU1_SA_DQS_DP<8>")
	)
	(segment
		(start 82.452464 -242.539266)
		(end 82.460846 -242.53444)
		(width 0.09525)
		(layer "In2.Cu")
		(net "M_C_CPU1_SA_DQS_DP<8>")
	)
	(segment
		(start 56.565038 -230.863394)
		(end 57.040018 -230.863394)
		(width 0.16002)
		(layer "In2.Cu")
		(net "M_C_CPU1_SA_DQS_DP<8>")
	)
	(segment
		(start 95.546164 -242.572286)
		(end 95.647002 -242.598956)
		(width 0.09525)
		(layer "In2.Cu")
		(net "M_C_CPU1_SA_DQS_DP<8>")
	)
	(segment
		(start 90.341196 -242.53444)
		(end 90.349578 -242.539266)
		(width 0.09525)
		(layer "In2.Cu")
		(net "M_C_CPU1_SA_DQS_DP<8>")
	)
	(segment
		(start 58.511948 -230.319834)
		(end 60.900056 -230.319834)
		(width 0.16002)
		(layer "In2.Cu")
		(net "M_C_CPU1_SA_DQS_DP<8>")
	)
	(segment
		(start 42.231564 -230.012494)
		(end 43.106848 -230.012494)
		(width 0.16002)
		(layer "In2.Cu")
		(net "M_C_CPU1_SA_DQS_DP<8>")
	)
	(segment
		(start 43.106848 -230.012494)
		(end 43.714162 -230.619808)
		(width 0.16002)
		(layer "In2.Cu")
		(net "M_C_CPU1_SA_DQS_DP<8>")
	)
	(segment
		(start 90.912442 -242.539266)
		(end 90.920824 -242.53444)
		(width 0.09525)
		(layer "In2.Cu")
		(net "M_C_CPU1_SA_DQS_DP<8>")
	)
	(segment
		(start 75.955906 -241.255804)
		(end 75.979528 -241.255804)
		(width 0.09525)
		(layer "In2.Cu")
		(net "M_C_CPU1_SA_DQS_DP<8>")
	)
	(segment
		(start 56.244998 -231.183434)
		(end 56.565038 -230.863394)
		(width 0.16002)
		(layer "In2.Cu")
		(net "M_C_CPU1_SA_DQS_DP<8>")
	)
	(segment
		(start 85.64118 -242.53444)
		(end 85.649562 -242.539266)
		(width 0.09525)
		(layer "In2.Cu")
		(net "M_C_CPU1_SA_DQS_DP<8>")
	)
	(segment
		(start 76.36256 -241.097054)
		(end 76.929742 -241.097054)
		(width 0.09525)
		(layer "In2.Cu")
		(net "M_C_CPU1_SA_DQS_DP<8>")
	)
	(segment
		(start 76.262738 -241.196876)
		(end 76.36256 -241.097054)
		(width 0.09525)
		(layer "In2.Cu")
		(net "M_C_CPU1_SA_DQS_DP<8>")
	)
	(segment
		(start 95.041212 -242.53444)
		(end 95.049594 -242.539266)
		(width 0.09525)
		(layer "In2.Cu")
		(net "M_C_CPU1_SA_DQS_DP<8>")
	)
	(segment
		(start 81.881218 -242.53444)
		(end 81.8896 -242.539266)
		(width 0.09525)
		(layer "In2.Cu")
		(net "M_C_CPU1_SA_DQS_DP<8>")
	)
	(segment
		(start 46.049184 -230.619808)
		(end 46.639988 -231.210612)
		(width 0.16002)
		(layer "In2.Cu")
		(net "M_C_CPU1_SA_DQS_DP<8>")
	)
	(segment
		(start 76.038456 -241.196876)
		(end 76.262738 -241.196876)
		(width 0.09525)
		(layer "In2.Cu")
		(net "M_C_CPU1_SA_DQS_DP<8>")
	)
	(segment
		(start 42.032428 -230.21163)
		(end 42.231564 -230.012494)
		(width 0.16002)
		(layer "In2.Cu")
		(net "M_C_CPU1_SA_DQS_DP<8>")
	)
	(segment
		(start 94.101158 -242.53444)
		(end 94.10954 -242.539266)
		(width 0.09525)
		(layer "In2.Cu")
		(net "M_C_CPU1_SA_DQS_DP<8>")
	)
	(arc
		(start 82.460846 -242.53444)
		(mid 82.645878 -242.488526)
		(end 82.829654 -242.539266)
		(width 0.09525)
		(layer "In2.Cu")
		(net "M_C_CPU1_SA_DQS_DP<8>")
	)
	(arc
		(start 85.272372 -242.539266)
		(mid 85.456147 -242.488494)
		(end 85.64118 -242.53444)
		(width 0.09525)
		(layer "In2.Cu")
		(net "M_C_CPU1_SA_DQS_DP<8>")
	)
	(arc
		(start 81.51241 -242.539266)
		(mid 81.696185 -242.488494)
		(end 81.881218 -242.53444)
		(width 0.09525)
		(layer "In2.Cu")
		(net "M_C_CPU1_SA_DQS_DP<8>")
	)
	(arc
		(start 80.949546 -242.539266)
		(mid 81.230978 -242.615021)
		(end 81.51241 -242.539266)
		(width 0.09525)
		(layer "In2.Cu")
		(net "M_C_CPU1_SA_DQS_DP<8>")
	)
	(arc
		(start 92.79255 -242.539266)
		(mid 92.981018 -242.488589)
		(end 93.169486 -242.539266)
		(width 0.09525)
		(layer "In2.Cu")
		(net "M_C_CPU1_SA_DQS_DP<8>")
	)
	(arc
		(start 85.649562 -242.539266)
		(mid 85.930994 -242.615021)
		(end 86.212426 -242.539266)
		(width 0.09525)
		(layer "In2.Cu")
		(net "M_C_CPU1_SA_DQS_DP<8>")
	)
	(arc
		(start 79.097632 -242.554506)
		(mid 79.367038 -242.614854)
		(end 79.632556 -242.539266)
		(width 0.09525)
		(layer "In2.Cu")
		(net "M_C_CPU1_SA_DQS_DP<8>")
	)
	(arc
		(start 90.349578 -242.539266)
		(mid 90.63101 -242.615021)
		(end 90.912442 -242.539266)
		(width 0.09525)
		(layer "In2.Cu")
		(net "M_C_CPU1_SA_DQS_DP<8>")
	)
	(arc
		(start 95.049594 -242.539266)
		(mid 95.283389 -242.613133)
		(end 95.526352 -242.58016)
		(width 0.09525)
		(layer "In2.Cu")
		(net "M_C_CPU1_SA_DQS_DP<8>")
	)
	(arc
		(start 82.829654 -242.539266)
		(mid 83.111086 -242.615021)
		(end 83.392518 -242.539266)
		(width 0.09525)
		(layer "In2.Cu")
		(net "M_C_CPU1_SA_DQS_DP<8>")
	)
	(arc
		(start 93.169486 -242.539266)
		(mid 93.450918 -242.615021)
		(end 93.73235 -242.539266)
		(width 0.09525)
		(layer "In2.Cu")
		(net "M_C_CPU1_SA_DQS_DP<8>")
	)
	(arc
		(start 89.032588 -242.539266)
		(mid 89.221056 -242.488589)
		(end 89.409524 -242.539266)
		(width 0.09525)
		(layer "In2.Cu")
		(net "M_C_CPU1_SA_DQS_DP<8>")
	)
	(arc
		(start 94.10954 -242.539266)
		(mid 94.390972 -242.615021)
		(end 94.672404 -242.539266)
		(width 0.09525)
		(layer "In2.Cu")
		(net "M_C_CPU1_SA_DQS_DP<8>")
	)
	(arc
		(start 84.709508 -242.539266)
		(mid 84.99094 -242.615021)
		(end 85.272372 -242.539266)
		(width 0.09525)
		(layer "In2.Cu")
		(net "M_C_CPU1_SA_DQS_DP<8>")
	)
	(arc
		(start 88.469724 -242.539266)
		(mid 88.751156 -242.615021)
		(end 89.032588 -242.539266)
		(width 0.09525)
		(layer "In2.Cu")
		(net "M_C_CPU1_SA_DQS_DP<8>")
	)
	(arc
		(start 95.526352 -242.58016)
		(mid 95.536295 -242.576317)
		(end 95.546164 -242.572286)
		(width 0.09525)
		(layer "In2.Cu")
		(net "M_C_CPU1_SA_DQS_DP<8>")
	)
	(arc
		(start 89.972388 -242.539266)
		(mid 90.156163 -242.488494)
		(end 90.341196 -242.53444)
		(width 0.09525)
		(layer "In2.Cu")
		(net "M_C_CPU1_SA_DQS_DP<8>")
	)
	(arc
		(start 87.52967 -242.539266)
		(mid 87.811102 -242.615021)
		(end 88.092534 -242.539266)
		(width 0.09525)
		(layer "In2.Cu")
		(net "M_C_CPU1_SA_DQS_DP<8>")
	)
	(arc
		(start 90.920824 -242.53444)
		(mid 91.105856 -242.488526)
		(end 91.289632 -242.539266)
		(width 0.09525)
		(layer "In2.Cu")
		(net "M_C_CPU1_SA_DQS_DP<8>")
	)
	(arc
		(start 86.212426 -242.539266)
		(mid 86.396201 -242.488494)
		(end 86.581234 -242.53444)
		(width 0.09525)
		(layer "In2.Cu")
		(net "M_C_CPU1_SA_DQS_DP<8>")
	)
	(arc
		(start 91.860878 -242.53444)
		(mid 92.04591 -242.488526)
		(end 92.229686 -242.539266)
		(width 0.09525)
		(layer "In2.Cu")
		(net "M_C_CPU1_SA_DQS_DP<8>")
	)
	(arc
		(start 83.4009 -242.53444)
		(mid 83.585932 -242.488526)
		(end 83.769708 -242.539266)
		(width 0.09525)
		(layer "In2.Cu")
		(net "M_C_CPU1_SA_DQS_DP<8>")
	)
	(arc
		(start 78.694534 -242.539012)
		(mid 78.864931 -242.488113)
		(end 79.03972 -242.520978)
		(width 0.09525)
		(layer "In2.Cu")
		(net "M_C_CPU1_SA_DQS_DP<8>")
	)
	(arc
		(start 93.73235 -242.539266)
		(mid 93.916125 -242.488494)
		(end 94.101158 -242.53444)
		(width 0.09525)
		(layer "In2.Cu")
		(net "M_C_CPU1_SA_DQS_DP<8>")
	)
	(arc
		(start 81.8896 -242.539266)
		(mid 82.171032 -242.615021)
		(end 82.452464 -242.539266)
		(width 0.09525)
		(layer "In2.Cu")
		(net "M_C_CPU1_SA_DQS_DP<8>")
	)
	(arc
		(start 94.672404 -242.539266)
		(mid 94.856179 -242.488494)
		(end 95.041212 -242.53444)
		(width 0.09525)
		(layer "In2.Cu")
		(net "M_C_CPU1_SA_DQS_DP<8>")
	)
	(arc
		(start 86.589616 -242.539266)
		(mid 86.871048 -242.615021)
		(end 87.15248 -242.539266)
		(width 0.09525)
		(layer "In2.Cu")
		(net "M_C_CPU1_SA_DQS_DP<8>")
	)
	(arc
		(start 89.409524 -242.539266)
		(mid 89.690956 -242.615021)
		(end 89.972388 -242.539266)
		(width 0.09525)
		(layer "In2.Cu")
		(net "M_C_CPU1_SA_DQS_DP<8>")
	)
	(arc
		(start 88.100916 -242.53444)
		(mid 88.285948 -242.488526)
		(end 88.469724 -242.539266)
		(width 0.09525)
		(layer "In2.Cu")
		(net "M_C_CPU1_SA_DQS_DP<8>")
	)
	(arc
		(start 79.640938 -242.53444)
		(mid 79.82597 -242.488526)
		(end 80.009746 -242.539266)
		(width 0.09525)
		(layer "In2.Cu")
		(net "M_C_CPU1_SA_DQS_DP<8>")
	)
	(arc
		(start 92.229686 -242.539266)
		(mid 92.511118 -242.615021)
		(end 92.79255 -242.539266)
		(width 0.09525)
		(layer "In2.Cu")
		(net "M_C_CPU1_SA_DQS_DP<8>")
	)
	(arc
		(start 87.160862 -242.53444)
		(mid 87.345894 -242.488526)
		(end 87.52967 -242.539266)
		(width 0.09525)
		(layer "In2.Cu")
		(net "M_C_CPU1_SA_DQS_DP<8>")
	)
	(arc
		(start 91.289632 -242.539266)
		(mid 91.571064 -242.615021)
		(end 91.852496 -242.539266)
		(width 0.09525)
		(layer "In2.Cu")
		(net "M_C_CPU1_SA_DQS_DP<8>")
	)
	(arc
		(start 80.57261 -242.539266)
		(mid 80.761078 -242.488589)
		(end 80.949546 -242.539266)
		(width 0.09525)
		(layer "In2.Cu")
		(net "M_C_CPU1_SA_DQS_DP<8>")
	)
	(arc
		(start 84.332572 -242.539266)
		(mid 84.52104 -242.488589)
		(end 84.709508 -242.539266)
		(width 0.09525)
		(layer "In2.Cu")
		(net "M_C_CPU1_SA_DQS_DP<8>")
	)
	(arc
		(start 83.769708 -242.539266)
		(mid 84.05114 -242.615021)
		(end 84.332572 -242.539266)
		(width 0.09525)
		(layer "In2.Cu")
		(net "M_C_CPU1_SA_DQS_DP<8>")
	)
	(arc
		(start 78.1685 -242.560856)
		(mid 78.434219 -242.61535)
		(end 78.694534 -242.539012)
		(width 0.09525)
		(layer "In2.Cu")
		(net "M_C_CPU1_SA_DQS_DP<8>")
	)
	(arc
		(start 78.015084 -242.450366)
		(mid 78.070437 -242.498788)
		(end 78.13167 -242.53952)
		(width 0.09525)
		(layer "In2.Cu")
		(net "M_C_CPU1_SA_DQS_DP<8>")
	)
	(arc
		(start 80.009746 -242.539266)
		(mid 80.291178 -242.615021)
		(end 80.57261 -242.539266)
		(width 0.09525)
		(layer "In2.Cu")
		(net "M_C_CPU1_SA_DQS_DP<8>")
	)
	(segment
		(start 96.267778 -238.270288)
		(end 95.800926 -238.00435)
		(width 0.12954)
		(layer "F.Cu")
		(net "M_C_CPU1_SA_DQS_DP<7>")
	)
	(segment
		(start 58.250074 -220.707966)
		(end 58.511948 -220.96984)
		(width 0.16002)
		(layer "In2.Cu")
		(net "M_C_CPU1_SA_DQS_DP<7>")
	)
	(segment
		(start 91.852496 -237.67923)
		(end 91.860878 -237.674404)
		(width 0.09525)
		(layer "In2.Cu")
		(net "M_C_CPU1_SA_DQS_DP<7>")
	)
	(segment
		(start 95.546164 -237.71225)
		(end 95.647002 -237.73892)
		(width 0.09525)
		(layer "In2.Cu")
		(net "M_C_CPU1_SA_DQS_DP<7>")
	)
	(segment
		(start 69.11721 -228.18344)
		(end 69.11721 -230.14432)
		(width 0.16002)
		(layer "In2.Cu")
		(net "M_C_CPU1_SA_DQS_DP<7>")
	)
	(segment
		(start 57.033414 -221.255336)
		(end 57.852564 -220.707966)
		(width 0.16002)
		(layer "In2.Cu")
		(net "M_C_CPU1_SA_DQS_DP<7>")
	)
	(segment
		(start 85.64118 -237.674404)
		(end 85.649562 -237.67923)
		(width 0.09525)
		(layer "In2.Cu")
		(net "M_C_CPU1_SA_DQS_DP<7>")
	)
	(segment
		(start 74.558144 -235.585254)
		(end 75.955906 -235.585254)
		(width 0.16002)
		(layer "In2.Cu")
		(net "M_C_CPU1_SA_DQS_DP<7>")
	)
	(segment
		(start 87.15248 -237.67923)
		(end 87.160862 -237.674404)
		(width 0.09525)
		(layer "In2.Cu")
		(net "M_C_CPU1_SA_DQS_DP<7>")
	)
	(segment
		(start 76.992226 -235.630974)
		(end 78.137766 -236.776514)
		(width 0.09525)
		(layer "In2.Cu")
		(net "M_C_CPU1_SA_DQS_DP<7>")
	)
	(segment
		(start 56.643016 -221.417134)
		(end 57.033414 -221.255336)
		(width 0.16002)
		(layer "In2.Cu")
		(net "M_C_CPU1_SA_DQS_DP<7>")
	)
	(segment
		(start 90.341196 -237.674404)
		(end 90.349578 -237.67923)
		(width 0.09525)
		(layer "In2.Cu")
		(net "M_C_CPU1_SA_DQS_DP<7>")
	)
	(segment
		(start 79.395574 -237.627922)
		(end 79.821024 -237.627922)
		(width 0.09525)
		(layer "In2.Cu")
		(net "M_C_CPU1_SA_DQS_DP<7>")
	)
	(segment
		(start 49.010316 -221.526862)
		(end 49.82464 -221.18955)
		(width 0.16002)
		(layer "In2.Cu")
		(net "M_C_CPU1_SA_DQS_DP<7>")
	)
	(segment
		(start 54.19725 -221.83344)
		(end 56.22671 -221.83344)
		(width 0.16002)
		(layer "In2.Cu")
		(net "M_C_CPU1_SA_DQS_DP<7>")
	)
	(segment
		(start 51.02225 -221.01048)
		(end 53.035454 -221.01048)
		(width 0.16002)
		(layer "In2.Cu")
		(net "M_C_CPU1_SA_DQS_DP<7>")
	)
	(segment
		(start 48.676814 -221.860364)
		(end 49.010316 -221.526862)
		(width 0.16002)
		(layer "In2.Cu")
		(net "M_C_CPU1_SA_DQS_DP<7>")
	)
	(segment
		(start 94.101158 -237.674404)
		(end 94.10954 -237.67923)
		(width 0.09525)
		(layer "In2.Cu")
		(net "M_C_CPU1_SA_DQS_DP<7>")
	)
	(segment
		(start 43.152314 -220.707966)
		(end 43.714162 -221.269814)
		(width 0.16002)
		(layer "In2.Cu")
		(net "M_C_CPU1_SA_DQS_DP<7>")
	)
	(segment
		(start 95.041212 -237.674404)
		(end 95.049594 -237.67923)
		(width 0.09525)
		(layer "In2.Cu")
		(net "M_C_CPU1_SA_DQS_DP<7>")
	)
	(segment
		(start 75.979528 -235.585254)
		(end 76.038456 -235.526326)
		(width 0.09525)
		(layer "In2.Cu")
		(net "M_C_CPU1_SA_DQS_DP<7>")
	)
	(segment
		(start 88.092534 -237.67923)
		(end 88.100916 -237.674404)
		(width 0.09525)
		(layer "In2.Cu")
		(net "M_C_CPU1_SA_DQS_DP<7>")
	)
	(segment
		(start 46.228 -221.44863)
		(end 46.639734 -221.860364)
		(width 0.16002)
		(layer "In2.Cu")
		(net "M_C_CPU1_SA_DQS_DP<7>")
	)
	(segment
		(start 75.955906 -235.585254)
		(end 75.979528 -235.585254)
		(width 0.09525)
		(layer "In2.Cu")
		(net "M_C_CPU1_SA_DQS_DP<7>")
	)
	(segment
		(start 50.69459 -220.68282)
		(end 51.02225 -221.01048)
		(width 0.16002)
		(layer "In2.Cu")
		(net "M_C_CPU1_SA_DQS_DP<7>")
	)
	(segment
		(start 81.881218 -237.674404)
		(end 81.8896 -237.67923)
		(width 0.09525)
		(layer "In2.Cu")
		(net "M_C_CPU1_SA_DQS_DP<7>")
	)
	(segment
		(start 76.038456 -235.526326)
		(end 76.39812 -235.526326)
		(width 0.09525)
		(layer "In2.Cu")
		(net "M_C_CPU1_SA_DQS_DP<7>")
	)
	(segment
		(start 61.90361 -220.96984)
		(end 69.11721 -228.18344)
		(width 0.16002)
		(layer "In2.Cu")
		(net "M_C_CPU1_SA_DQS_DP<7>")
	)
	(segment
		(start 76.502768 -235.630974)
		(end 76.992226 -235.630974)
		(width 0.09525)
		(layer "In2.Cu")
		(net "M_C_CPU1_SA_DQS_DP<7>")
	)
	(segment
		(start 56.22671 -221.83344)
		(end 56.643016 -221.417134)
		(width 0.16002)
		(layer "In2.Cu")
		(net "M_C_CPU1_SA_DQS_DP<7>")
	)
	(segment
		(start 50.33137 -220.68282)
		(end 50.69459 -220.68282)
		(width 0.16002)
		(layer "In2.Cu")
		(net "M_C_CPU1_SA_DQS_DP<7>")
	)
	(segment
		(start 78.137766 -236.776514)
		(end 78.482444 -236.776514)
		(width 0.09525)
		(layer "In2.Cu")
		(net "M_C_CPU1_SA_DQS_DP<7>")
	)
	(segment
		(start 43.714162 -221.269814)
		(end 45.795946 -221.269814)
		(width 0.16002)
		(layer "In2.Cu")
		(net "M_C_CPU1_SA_DQS_DP<7>")
	)
	(segment
		(start 69.11721 -230.14432)
		(end 74.558144 -235.585254)
		(width 0.16002)
		(layer "In2.Cu")
		(net "M_C_CPU1_SA_DQS_DP<7>")
	)
	(segment
		(start 42.658538 -220.707966)
		(end 43.152314 -220.707966)
		(width 0.16002)
		(layer "In2.Cu")
		(net "M_C_CPU1_SA_DQS_DP<7>")
	)
	(segment
		(start 78.588108 -236.820456)
		(end 79.395574 -237.627922)
		(width 0.09525)
		(layer "In2.Cu")
		(net "M_C_CPU1_SA_DQS_DP<7>")
	)
	(segment
		(start 83.392518 -237.67923)
		(end 83.4009 -237.674404)
		(width 0.09525)
		(layer "In2.Cu")
		(net "M_C_CPU1_SA_DQS_DP<7>")
	)
	(segment
		(start 53.613812 -221.250002)
		(end 54.19725 -221.83344)
		(width 0.16002)
		(layer "In2.Cu")
		(net "M_C_CPU1_SA_DQS_DP<7>")
	)
	(segment
		(start 53.035454 -221.01048)
		(end 53.613812 -221.250002)
		(width 0.16002)
		(layer "In2.Cu")
		(net "M_C_CPU1_SA_DQS_DP<7>")
	)
	(segment
		(start 95.647002 -237.73892)
		(end 95.800926 -238.00435)
		(width 0.09525)
		(layer "In2.Cu")
		(net "M_C_CPU1_SA_DQS_DP<7>")
	)
	(segment
		(start 40.513508 -220.861636)
		(end 42.504868 -220.861636)
		(width 0.16002)
		(layer "In2.Cu")
		(net "M_C_CPU1_SA_DQS_DP<7>")
	)
	(segment
		(start 57.852564 -220.707966)
		(end 58.250074 -220.707966)
		(width 0.16002)
		(layer "In2.Cu")
		(net "M_C_CPU1_SA_DQS_DP<7>")
	)
	(segment
		(start 82.452464 -237.67923)
		(end 82.460846 -237.674404)
		(width 0.09525)
		(layer "In2.Cu")
		(net "M_C_CPU1_SA_DQS_DP<7>")
	)
	(segment
		(start 45.795946 -221.269814)
		(end 46.228 -221.44863)
		(width 0.16002)
		(layer "In2.Cu")
		(net "M_C_CPU1_SA_DQS_DP<7>")
	)
	(segment
		(start 49.82464 -221.18955)
		(end 50.33137 -220.68282)
		(width 0.16002)
		(layer "In2.Cu")
		(net "M_C_CPU1_SA_DQS_DP<7>")
	)
	(segment
		(start 58.511948 -220.96984)
		(end 61.90361 -220.96984)
		(width 0.16002)
		(layer "In2.Cu")
		(net "M_C_CPU1_SA_DQS_DP<7>")
	)
	(segment
		(start 46.639734 -221.860364)
		(end 48.676814 -221.860364)
		(width 0.16002)
		(layer "In2.Cu")
		(net "M_C_CPU1_SA_DQS_DP<7>")
	)
	(segment
		(start 42.504868 -220.861636)
		(end 42.658538 -220.707966)
		(width 0.16002)
		(layer "In2.Cu")
		(net "M_C_CPU1_SA_DQS_DP<7>")
	)
	(segment
		(start 86.581234 -237.674404)
		(end 86.589616 -237.67923)
		(width 0.09525)
		(layer "In2.Cu")
		(net "M_C_CPU1_SA_DQS_DP<7>")
	)
	(segment
		(start 76.39812 -235.526326)
		(end 76.502768 -235.630974)
		(width 0.09525)
		(layer "In2.Cu")
		(net "M_C_CPU1_SA_DQS_DP<7>")
	)
	(segment
		(start 40.23995 -221.135194)
		(end 40.513508 -220.861636)
		(width 0.16002)
		(layer "In2.Cu")
		(net "M_C_CPU1_SA_DQS_DP<7>")
	)
	(segment
		(start 90.912442 -237.67923)
		(end 90.920824 -237.674404)
		(width 0.09525)
		(layer "In2.Cu")
		(net "M_C_CPU1_SA_DQS_DP<7>")
	)
	(arc
		(start 88.100916 -237.674404)
		(mid 88.285948 -237.62849)
		(end 88.469724 -237.67923)
		(width 0.09525)
		(layer "In2.Cu")
		(net "M_C_CPU1_SA_DQS_DP<7>")
	)
	(arc
		(start 80.009746 -237.67923)
		(mid 80.291178 -237.754985)
		(end 80.57261 -237.67923)
		(width 0.09525)
		(layer "In2.Cu")
		(net "M_C_CPU1_SA_DQS_DP<7>")
	)
	(arc
		(start 94.10954 -237.67923)
		(mid 94.390972 -237.754985)
		(end 94.672404 -237.67923)
		(width 0.09525)
		(layer "In2.Cu")
		(net "M_C_CPU1_SA_DQS_DP<7>")
	)
	(arc
		(start 95.049594 -237.67923)
		(mid 95.283389 -237.753097)
		(end 95.526352 -237.720124)
		(width 0.09525)
		(layer "In2.Cu")
		(net "M_C_CPU1_SA_DQS_DP<7>")
	)
	(arc
		(start 82.460846 -237.674404)
		(mid 82.645878 -237.62849)
		(end 82.829654 -237.67923)
		(width 0.09525)
		(layer "In2.Cu")
		(net "M_C_CPU1_SA_DQS_DP<7>")
	)
	(arc
		(start 90.349578 -237.67923)
		(mid 90.63101 -237.754985)
		(end 90.912442 -237.67923)
		(width 0.09525)
		(layer "In2.Cu")
		(net "M_C_CPU1_SA_DQS_DP<7>")
	)
	(arc
		(start 81.51241 -237.67923)
		(mid 81.696185 -237.628458)
		(end 81.881218 -237.674404)
		(width 0.09525)
		(layer "In2.Cu")
		(net "M_C_CPU1_SA_DQS_DP<7>")
	)
	(arc
		(start 85.649562 -237.67923)
		(mid 85.930994 -237.754985)
		(end 86.212426 -237.67923)
		(width 0.09525)
		(layer "In2.Cu")
		(net "M_C_CPU1_SA_DQS_DP<7>")
	)
	(arc
		(start 90.920824 -237.674404)
		(mid 91.105856 -237.62849)
		(end 91.289632 -237.67923)
		(width 0.09525)
		(layer "In2.Cu")
		(net "M_C_CPU1_SA_DQS_DP<7>")
	)
	(arc
		(start 89.032588 -237.67923)
		(mid 89.221056 -237.628553)
		(end 89.409524 -237.67923)
		(width 0.09525)
		(layer "In2.Cu")
		(net "M_C_CPU1_SA_DQS_DP<7>")
	)
	(arc
		(start 93.169486 -237.67923)
		(mid 93.450918 -237.754985)
		(end 93.73235 -237.67923)
		(width 0.09525)
		(layer "In2.Cu")
		(net "M_C_CPU1_SA_DQS_DP<7>")
	)
	(arc
		(start 92.229686 -237.67923)
		(mid 92.511118 -237.754985)
		(end 92.79255 -237.67923)
		(width 0.09525)
		(layer "In2.Cu")
		(net "M_C_CPU1_SA_DQS_DP<7>")
	)
	(arc
		(start 94.672404 -237.67923)
		(mid 94.856179 -237.628458)
		(end 95.041212 -237.674404)
		(width 0.09525)
		(layer "In2.Cu")
		(net "M_C_CPU1_SA_DQS_DP<7>")
	)
	(arc
		(start 80.949546 -237.67923)
		(mid 81.230978 -237.754985)
		(end 81.51241 -237.67923)
		(width 0.09525)
		(layer "In2.Cu")
		(net "M_C_CPU1_SA_DQS_DP<7>")
	)
	(arc
		(start 85.272372 -237.67923)
		(mid 85.456147 -237.628458)
		(end 85.64118 -237.674404)
		(width 0.09525)
		(layer "In2.Cu")
		(net "M_C_CPU1_SA_DQS_DP<7>")
	)
	(arc
		(start 88.469724 -237.67923)
		(mid 88.751156 -237.754985)
		(end 89.032588 -237.67923)
		(width 0.09525)
		(layer "In2.Cu")
		(net "M_C_CPU1_SA_DQS_DP<7>")
	)
	(arc
		(start 86.212426 -237.67923)
		(mid 86.396201 -237.628458)
		(end 86.581234 -237.674404)
		(width 0.09525)
		(layer "In2.Cu")
		(net "M_C_CPU1_SA_DQS_DP<7>")
	)
	(arc
		(start 82.829654 -237.67923)
		(mid 83.111086 -237.754985)
		(end 83.392518 -237.67923)
		(width 0.09525)
		(layer "In2.Cu")
		(net "M_C_CPU1_SA_DQS_DP<7>")
	)
	(arc
		(start 92.79255 -237.67923)
		(mid 92.981018 -237.628553)
		(end 93.169486 -237.67923)
		(width 0.09525)
		(layer "In2.Cu")
		(net "M_C_CPU1_SA_DQS_DP<7>")
	)
	(arc
		(start 95.526352 -237.720124)
		(mid 95.536295 -237.716281)
		(end 95.546164 -237.71225)
		(width 0.09525)
		(layer "In2.Cu")
		(net "M_C_CPU1_SA_DQS_DP<7>")
	)
	(arc
		(start 91.860878 -237.674404)
		(mid 92.04591 -237.62849)
		(end 92.229686 -237.67923)
		(width 0.09525)
		(layer "In2.Cu")
		(net "M_C_CPU1_SA_DQS_DP<7>")
	)
	(arc
		(start 87.160862 -237.674404)
		(mid 87.345894 -237.62849)
		(end 87.52967 -237.67923)
		(width 0.09525)
		(layer "In2.Cu")
		(net "M_C_CPU1_SA_DQS_DP<7>")
	)
	(arc
		(start 81.8896 -237.67923)
		(mid 82.171032 -237.754985)
		(end 82.452464 -237.67923)
		(width 0.09525)
		(layer "In2.Cu")
		(net "M_C_CPU1_SA_DQS_DP<7>")
	)
	(arc
		(start 83.769708 -237.67923)
		(mid 84.05114 -237.754985)
		(end 84.332572 -237.67923)
		(width 0.09525)
		(layer "In2.Cu")
		(net "M_C_CPU1_SA_DQS_DP<7>")
	)
	(arc
		(start 93.73235 -237.67923)
		(mid 93.916125 -237.628458)
		(end 94.101158 -237.674404)
		(width 0.09525)
		(layer "In2.Cu")
		(net "M_C_CPU1_SA_DQS_DP<7>")
	)
	(arc
		(start 78.482444 -236.776514)
		(mid 78.539628 -236.788)
		(end 78.588108 -236.820456)
		(width 0.09525)
		(layer "In2.Cu")
		(net "M_C_CPU1_SA_DQS_DP<7>")
	)
	(arc
		(start 89.409524 -237.67923)
		(mid 89.690956 -237.754985)
		(end 89.972388 -237.67923)
		(width 0.09525)
		(layer "In2.Cu")
		(net "M_C_CPU1_SA_DQS_DP<7>")
	)
	(arc
		(start 87.52967 -237.67923)
		(mid 87.811102 -237.754985)
		(end 88.092534 -237.67923)
		(width 0.09525)
		(layer "In2.Cu")
		(net "M_C_CPU1_SA_DQS_DP<7>")
	)
	(arc
		(start 84.332572 -237.67923)
		(mid 84.52104 -237.628553)
		(end 84.709508 -237.67923)
		(width 0.09525)
		(layer "In2.Cu")
		(net "M_C_CPU1_SA_DQS_DP<7>")
	)
	(arc
		(start 84.709508 -237.67923)
		(mid 84.99094 -237.754985)
		(end 85.272372 -237.67923)
		(width 0.09525)
		(layer "In2.Cu")
		(net "M_C_CPU1_SA_DQS_DP<7>")
	)
	(arc
		(start 80.57261 -237.67923)
		(mid 80.761078 -237.628553)
		(end 80.949546 -237.67923)
		(width 0.09525)
		(layer "In2.Cu")
		(net "M_C_CPU1_SA_DQS_DP<7>")
	)
	(arc
		(start 86.589616 -237.67923)
		(mid 86.871048 -237.754985)
		(end 87.15248 -237.67923)
		(width 0.09525)
		(layer "In2.Cu")
		(net "M_C_CPU1_SA_DQS_DP<7>")
	)
	(arc
		(start 91.289632 -237.67923)
		(mid 91.571064 -237.754985)
		(end 91.852496 -237.67923)
		(width 0.09525)
		(layer "In2.Cu")
		(net "M_C_CPU1_SA_DQS_DP<7>")
	)
	(arc
		(start 83.4009 -237.674404)
		(mid 83.585932 -237.62849)
		(end 83.769708 -237.67923)
		(width 0.09525)
		(layer "In2.Cu")
		(net "M_C_CPU1_SA_DQS_DP<7>")
	)
	(arc
		(start 79.821024 -237.627922)
		(mid 79.91877 -237.641117)
		(end 80.009746 -237.67923)
		(width 0.09525)
		(layer "In2.Cu")
		(net "M_C_CPU1_SA_DQS_DP<7>")
	)
	(arc
		(start 89.972388 -237.67923)
		(mid 90.156163 -237.628458)
		(end 90.341196 -237.674404)
		(width 0.09525)
		(layer "In2.Cu")
		(net "M_C_CPU1_SA_DQS_DP<7>")
	)
	(segment
		(start 96.267778 -233.410252)
		(end 95.800926 -233.144314)
		(width 0.12954)
		(layer "F.Cu")
		(net "M_C_CPU1_SA_DQS_DP<6>")
	)
	(segment
		(start 95.546164 -232.852214)
		(end 95.647002 -232.878884)
		(width 0.09525)
		(layer "In2.Cu")
		(net "M_C_CPU1_SA_DQS_DP<6>")
	)
	(segment
		(start 90.341196 -232.814368)
		(end 90.349578 -232.819194)
		(width 0.09525)
		(layer "In2.Cu")
		(net "M_C_CPU1_SA_DQS_DP<6>")
	)
	(segment
		(start 51.02225 -211.660486)
		(end 53.37429 -211.660486)
		(width 0.16002)
		(layer "In2.Cu")
		(net "M_C_CPU1_SA_DQS_DP<6>")
	)
	(segment
		(start 56.54675 -212.163406)
		(end 57.04713 -212.163406)
		(width 0.16002)
		(layer "In2.Cu")
		(net "M_C_CPU1_SA_DQS_DP<6>")
	)
	(segment
		(start 79.50454 -231.988614)
		(end 79.506572 -231.989884)
		(width 0.09525)
		(layer "In2.Cu")
		(net "M_C_CPU1_SA_DQS_DP<6>")
	)
	(segment
		(start 78.563216 -230.36784)
		(end 78.599792 -230.389176)
		(width 0.09525)
		(layer "In2.Cu")
		(net "M_C_CPU1_SA_DQS_DP<6>")
	)
	(segment
		(start 58.253376 -211.361274)
		(end 58.511948 -211.619846)
		(width 0.16002)
		(layer "In2.Cu")
		(net "M_C_CPU1_SA_DQS_DP<6>")
	)
	(segment
		(start 86.581234 -232.814368)
		(end 86.589616 -232.819194)
		(width 0.09525)
		(layer "In2.Cu")
		(net "M_C_CPU1_SA_DQS_DP<6>")
	)
	(segment
		(start 88.092534 -232.819194)
		(end 88.100916 -232.814368)
		(width 0.09525)
		(layer "In2.Cu")
		(net "M_C_CPU1_SA_DQS_DP<6>")
	)
	(segment
		(start 79.069946 -231.199182)
		(end 79.101442 -231.21747)
		(width 0.09525)
		(layer "In2.Cu")
		(net "M_C_CPU1_SA_DQS_DP<6>")
	)
	(segment
		(start 46.639734 -212.51037)
		(end 48.663606 -212.51037)
		(width 0.16002)
		(layer "In2.Cu")
		(net "M_C_CPU1_SA_DQS_DP<6>")
	)
	(segment
		(start 42.231564 -211.312506)
		(end 43.106848 -211.312506)
		(width 0.16002)
		(layer "In2.Cu")
		(net "M_C_CPU1_SA_DQS_DP<6>")
	)
	(segment
		(start 82.452464 -232.819194)
		(end 82.460846 -232.814368)
		(width 0.09525)
		(layer "In2.Cu")
		(net "M_C_CPU1_SA_DQS_DP<6>")
	)
	(segment
		(start 69.17563 -219.964508)
		(end 74.84491 -225.633788)
		(width 0.16002)
		(layer "In2.Cu")
		(net "M_C_CPU1_SA_DQS_DP<6>")
	)
	(segment
		(start 78.129892 -229.579424)
		(end 78.164436 -229.599236)
		(width 0.09525)
		(layer "In2.Cu")
		(net "M_C_CPU1_SA_DQS_DP<6>")
	)
	(segment
		(start 83.392518 -232.819194)
		(end 83.4009 -232.814368)
		(width 0.09525)
		(layer "In2.Cu")
		(net "M_C_CPU1_SA_DQS_DP<6>")
	)
	(segment
		(start 79.971646 -232.797096)
		(end 80.009746 -232.819194)
		(width 0.09525)
		(layer "In2.Cu")
		(net "M_C_CPU1_SA_DQS_DP<6>")
	)
	(segment
		(start 77.684884 -228.782372)
		(end 77.689456 -228.785928)
		(width 0.09525)
		(layer "In2.Cu")
		(net "M_C_CPU1_SA_DQS_DP<6>")
	)
	(segment
		(start 54.19725 -212.483446)
		(end 56.22671 -212.483446)
		(width 0.16002)
		(layer "In2.Cu")
		(net "M_C_CPU1_SA_DQS_DP<6>")
	)
	(segment
		(start 50.33137 -211.332826)
		(end 50.69459 -211.332826)
		(width 0.16002)
		(layer "In2.Cu")
		(net "M_C_CPU1_SA_DQS_DP<6>")
	)
	(segment
		(start 40.513508 -211.511642)
		(end 42.032428 -211.511642)
		(width 0.16002)
		(layer "In2.Cu")
		(net "M_C_CPU1_SA_DQS_DP<6>")
	)
	(segment
		(start 75.92568 -227.849938)
		(end 76.551028 -227.849938)
		(width 0.16002)
		(layer "In2.Cu")
		(net "M_C_CPU1_SA_DQS_DP<6>")
	)
	(segment
		(start 85.64118 -232.814368)
		(end 85.649562 -232.819194)
		(width 0.09525)
		(layer "In2.Cu")
		(net "M_C_CPU1_SA_DQS_DP<6>")
	)
	(segment
		(start 48.98771 -212.186266)
		(end 49.47793 -212.186266)
		(width 0.16002)
		(layer "In2.Cu")
		(net "M_C_CPU1_SA_DQS_DP<6>")
	)
	(segment
		(start 79.506572 -231.989884)
		(end 79.539592 -232.009188)
		(width 0.09525)
		(layer "In2.Cu")
		(net "M_C_CPU1_SA_DQS_DP<6>")
	)
	(segment
		(start 49.47793 -212.186266)
		(end 50.33137 -211.332826)
		(width 0.16002)
		(layer "In2.Cu")
		(net "M_C_CPU1_SA_DQS_DP<6>")
	)
	(segment
		(start 42.032428 -211.511642)
		(end 42.231564 -211.312506)
		(width 0.16002)
		(layer "In2.Cu")
		(net "M_C_CPU1_SA_DQS_DP<6>")
	)
	(segment
		(start 74.84491 -226.769168)
		(end 75.92568 -227.849938)
		(width 0.16002)
		(layer "In2.Cu")
		(net "M_C_CPU1_SA_DQS_DP<6>")
	)
	(segment
		(start 76.57465 -227.849938)
		(end 76.633832 -227.790756)
		(width 0.09525)
		(layer "In2.Cu")
		(net "M_C_CPU1_SA_DQS_DP<6>")
	)
	(segment
		(start 46.049184 -211.91982)
		(end 46.639734 -212.51037)
		(width 0.16002)
		(layer "In2.Cu")
		(net "M_C_CPU1_SA_DQS_DP<6>")
	)
	(segment
		(start 76.551028 -227.849938)
		(end 76.57465 -227.849938)
		(width 0.09525)
		(layer "In2.Cu")
		(net "M_C_CPU1_SA_DQS_DP<6>")
	)
	(segment
		(start 50.69459 -211.332826)
		(end 51.02225 -211.660486)
		(width 0.16002)
		(layer "In2.Cu")
		(net "M_C_CPU1_SA_DQS_DP<6>")
	)
	(segment
		(start 79.539592 -232.009188)
		(end 79.572104 -232.027984)
		(width 0.09525)
		(layer "In2.Cu")
		(net "M_C_CPU1_SA_DQS_DP<6>")
	)
	(segment
		(start 57.04713 -212.163406)
		(end 57.849262 -211.361274)
		(width 0.16002)
		(layer "In2.Cu")
		(net "M_C_CPU1_SA_DQS_DP<6>")
	)
	(segment
		(start 56.22671 -212.483446)
		(end 56.54675 -212.163406)
		(width 0.16002)
		(layer "In2.Cu")
		(net "M_C_CPU1_SA_DQS_DP<6>")
	)
	(segment
		(start 78.599792 -230.389176)
		(end 78.631542 -230.407464)
		(width 0.09525)
		(layer "In2.Cu")
		(net "M_C_CPU1_SA_DQS_DP<6>")
	)
	(segment
		(start 95.647002 -232.878884)
		(end 95.800926 -233.144314)
		(width 0.09525)
		(layer "In2.Cu")
		(net "M_C_CPU1_SA_DQS_DP<6>")
	)
	(segment
		(start 74.84491 -225.633788)
		(end 74.84491 -226.769168)
		(width 0.16002)
		(layer "In2.Cu")
		(net "M_C_CPU1_SA_DQS_DP<6>")
	)
	(segment
		(start 40.23995 -211.7852)
		(end 40.513508 -211.511642)
		(width 0.16002)
		(layer "In2.Cu")
		(net "M_C_CPU1_SA_DQS_DP<6>")
	)
	(segment
		(start 69.17563 -218.191588)
		(end 69.17563 -219.964508)
		(width 0.16002)
		(layer "In2.Cu")
		(net "M_C_CPU1_SA_DQS_DP<6>")
	)
	(segment
		(start 53.37429 -211.660486)
		(end 54.19725 -212.483446)
		(width 0.16002)
		(layer "In2.Cu")
		(net "M_C_CPU1_SA_DQS_DP<6>")
	)
	(segment
		(start 78.093316 -229.558088)
		(end 78.129892 -229.579424)
		(width 0.09525)
		(layer "In2.Cu")
		(net "M_C_CPU1_SA_DQS_DP<6>")
	)
	(segment
		(start 91.852496 -232.819194)
		(end 91.860878 -232.814368)
		(width 0.09525)
		(layer "In2.Cu")
		(net "M_C_CPU1_SA_DQS_DP<6>")
	)
	(segment
		(start 77.027024 -227.790756)
		(end 77.278738 -228.042724)
		(width 0.09525)
		(layer "In2.Cu")
		(net "M_C_CPU1_SA_DQS_DP<6>")
	)
	(segment
		(start 87.15248 -232.819194)
		(end 87.160862 -232.814368)
		(width 0.09525)
		(layer "In2.Cu")
		(net "M_C_CPU1_SA_DQS_DP<6>")
	)
	(segment
		(start 48.663606 -212.51037)
		(end 48.98771 -212.186266)
		(width 0.16002)
		(layer "In2.Cu")
		(net "M_C_CPU1_SA_DQS_DP<6>")
	)
	(segment
		(start 90.912442 -232.819194)
		(end 90.920824 -232.814368)
		(width 0.09525)
		(layer "In2.Cu")
		(net "M_C_CPU1_SA_DQS_DP<6>")
	)
	(segment
		(start 81.881218 -232.814368)
		(end 81.8896 -232.819194)
		(width 0.09525)
		(layer "In2.Cu")
		(net "M_C_CPU1_SA_DQS_DP<6>")
	)
	(segment
		(start 76.633832 -227.790756)
		(end 77.027024 -227.790756)
		(width 0.09525)
		(layer "In2.Cu")
		(net "M_C_CPU1_SA_DQS_DP<6>")
	)
	(segment
		(start 94.101158 -232.814368)
		(end 94.10954 -232.819194)
		(width 0.09525)
		(layer "In2.Cu")
		(net "M_C_CPU1_SA_DQS_DP<6>")
	)
	(segment
		(start 95.041212 -232.814368)
		(end 95.049594 -232.819194)
		(width 0.09525)
		(layer "In2.Cu")
		(net "M_C_CPU1_SA_DQS_DP<6>")
	)
	(segment
		(start 57.849262 -211.361274)
		(end 58.253376 -211.361274)
		(width 0.16002)
		(layer "In2.Cu")
		(net "M_C_CPU1_SA_DQS_DP<6>")
	)
	(segment
		(start 43.106848 -211.312506)
		(end 43.714162 -211.91982)
		(width 0.16002)
		(layer "In2.Cu")
		(net "M_C_CPU1_SA_DQS_DP<6>")
	)
	(segment
		(start 43.714162 -211.91982)
		(end 46.049184 -211.91982)
		(width 0.16002)
		(layer "In2.Cu")
		(net "M_C_CPU1_SA_DQS_DP<6>")
	)
	(segment
		(start 58.511948 -211.619846)
		(end 62.603888 -211.619846)
		(width 0.16002)
		(layer "In2.Cu")
		(net "M_C_CPU1_SA_DQS_DP<6>")
	)
	(segment
		(start 77.377798 -228.25583)
		(end 77.378052 -228.25583)
		(width 0.09525)
		(layer "In2.Cu")
		(net "M_C_CPU1_SA_DQS_DP<6>")
	)
	(segment
		(start 62.603888 -211.619846)
		(end 69.17563 -218.191588)
		(width 0.16002)
		(layer "In2.Cu")
		(net "M_C_CPU1_SA_DQS_DP<6>")
	)
	(segment
		(start 79.031846 -231.177084)
		(end 79.069946 -231.199182)
		(width 0.09525)
		(layer "In2.Cu")
		(net "M_C_CPU1_SA_DQS_DP<6>")
	)
	(arc
		(start 91.860878 -232.814368)
		(mid 92.04591 -232.768454)
		(end 92.229686 -232.819194)
		(width 0.09525)
		(layer "In2.Cu")
		(net "M_C_CPU1_SA_DQS_DP<6>")
	)
	(arc
		(start 90.920824 -232.814368)
		(mid 91.105856 -232.768454)
		(end 91.289632 -232.819194)
		(width 0.09525)
		(layer "In2.Cu")
		(net "M_C_CPU1_SA_DQS_DP<6>")
	)
	(arc
		(start 78.164436 -229.599236)
		(mid 78.278277 -229.733252)
		(end 78.319122 -229.90429)
		(width 0.09525)
		(layer "In2.Cu")
		(net "M_C_CPU1_SA_DQS_DP<6>")
	)
	(arc
		(start 95.049594 -232.819194)
		(mid 95.283389 -232.893061)
		(end 95.526352 -232.860088)
		(width 0.09525)
		(layer "In2.Cu")
		(net "M_C_CPU1_SA_DQS_DP<6>")
	)
	(arc
		(start 80.57261 -232.819194)
		(mid 80.761078 -232.768517)
		(end 80.949546 -232.819194)
		(width 0.09525)
		(layer "In2.Cu")
		(net "M_C_CPU1_SA_DQS_DP<6>")
	)
	(arc
		(start 91.289632 -232.819194)
		(mid 91.571064 -232.894949)
		(end 91.852496 -232.819194)
		(width 0.09525)
		(layer "In2.Cu")
		(net "M_C_CPU1_SA_DQS_DP<6>")
	)
	(arc
		(start 94.10954 -232.819194)
		(mid 94.390972 -232.894949)
		(end 94.672404 -232.819194)
		(width 0.09525)
		(layer "In2.Cu")
		(net "M_C_CPU1_SA_DQS_DP<6>")
	)
	(arc
		(start 78.789022 -230.71455)
		(mid 78.853478 -230.975715)
		(end 79.031846 -231.177084)
		(width 0.09525)
		(layer "In2.Cu")
		(net "M_C_CPU1_SA_DQS_DP<6>")
	)
	(arc
		(start 89.972388 -232.819194)
		(mid 90.156163 -232.768422)
		(end 90.341196 -232.814368)
		(width 0.09525)
		(layer "In2.Cu")
		(net "M_C_CPU1_SA_DQS_DP<6>")
	)
	(arc
		(start 85.649562 -232.819194)
		(mid 85.930994 -232.894949)
		(end 86.212426 -232.819194)
		(width 0.09525)
		(layer "In2.Cu")
		(net "M_C_CPU1_SA_DQS_DP<6>")
	)
	(arc
		(start 88.469724 -232.819194)
		(mid 88.751156 -232.894949)
		(end 89.032588 -232.819194)
		(width 0.09525)
		(layer "In2.Cu")
		(net "M_C_CPU1_SA_DQS_DP<6>")
	)
	(arc
		(start 92.229686 -232.819194)
		(mid 92.511118 -232.894949)
		(end 92.79255 -232.819194)
		(width 0.09525)
		(layer "In2.Cu")
		(net "M_C_CPU1_SA_DQS_DP<6>")
	)
	(arc
		(start 94.672404 -232.819194)
		(mid 94.856179 -232.768422)
		(end 95.041212 -232.814368)
		(width 0.09525)
		(layer "In2.Cu")
		(net "M_C_CPU1_SA_DQS_DP<6>")
	)
	(arc
		(start 93.169486 -232.819194)
		(mid 93.450918 -232.894949)
		(end 93.73235 -232.819194)
		(width 0.09525)
		(layer "In2.Cu")
		(net "M_C_CPU1_SA_DQS_DP<6>")
	)
	(arc
		(start 90.349578 -232.819194)
		(mid 90.63101 -232.894949)
		(end 90.912442 -232.819194)
		(width 0.09525)
		(layer "In2.Cu")
		(net "M_C_CPU1_SA_DQS_DP<6>")
	)
	(arc
		(start 89.409524 -232.819194)
		(mid 89.690956 -232.894949)
		(end 89.972388 -232.819194)
		(width 0.09525)
		(layer "In2.Cu")
		(net "M_C_CPU1_SA_DQS_DP<6>")
	)
	(arc
		(start 82.829654 -232.819194)
		(mid 83.111086 -232.894949)
		(end 83.392518 -232.819194)
		(width 0.09525)
		(layer "In2.Cu")
		(net "M_C_CPU1_SA_DQS_DP<6>")
	)
	(arc
		(start 84.709508 -232.819194)
		(mid 84.99094 -232.894949)
		(end 85.272372 -232.819194)
		(width 0.09525)
		(layer "In2.Cu")
		(net "M_C_CPU1_SA_DQS_DP<6>")
	)
	(arc
		(start 89.032588 -232.819194)
		(mid 89.221056 -232.768517)
		(end 89.409524 -232.819194)
		(width 0.09525)
		(layer "In2.Cu")
		(net "M_C_CPU1_SA_DQS_DP<6>")
	)
	(arc
		(start 86.589616 -232.819194)
		(mid 86.871048 -232.894949)
		(end 87.15248 -232.819194)
		(width 0.09525)
		(layer "In2.Cu")
		(net "M_C_CPU1_SA_DQS_DP<6>")
	)
	(arc
		(start 87.52967 -232.819194)
		(mid 87.811102 -232.894949)
		(end 88.092534 -232.819194)
		(width 0.09525)
		(layer "In2.Cu")
		(net "M_C_CPU1_SA_DQS_DP<6>")
	)
	(arc
		(start 77.378052 -228.25583)
		(mid 77.472173 -228.553644)
		(end 77.684884 -228.782372)
		(width 0.09525)
		(layer "In2.Cu")
		(net "M_C_CPU1_SA_DQS_DP<6>")
	)
	(arc
		(start 83.4009 -232.814368)
		(mid 83.585932 -232.768454)
		(end 83.769708 -232.819194)
		(width 0.09525)
		(layer "In2.Cu")
		(net "M_C_CPU1_SA_DQS_DP<6>")
	)
	(arc
		(start 80.949546 -232.819194)
		(mid 81.230978 -232.894949)
		(end 81.51241 -232.819194)
		(width 0.09525)
		(layer "In2.Cu")
		(net "M_C_CPU1_SA_DQS_DP<6>")
	)
	(arc
		(start 85.272372 -232.819194)
		(mid 85.456147 -232.768422)
		(end 85.64118 -232.814368)
		(width 0.09525)
		(layer "In2.Cu")
		(net "M_C_CPU1_SA_DQS_DP<6>")
	)
	(arc
		(start 88.100916 -232.814368)
		(mid 88.285948 -232.768454)
		(end 88.469724 -232.819194)
		(width 0.09525)
		(layer "In2.Cu")
		(net "M_C_CPU1_SA_DQS_DP<6>")
	)
	(arc
		(start 84.332572 -232.819194)
		(mid 84.52104 -232.768517)
		(end 84.709508 -232.819194)
		(width 0.09525)
		(layer "In2.Cu")
		(net "M_C_CPU1_SA_DQS_DP<6>")
	)
	(arc
		(start 79.101442 -231.21747)
		(mid 79.21724 -231.351864)
		(end 79.258922 -231.524302)
		(width 0.09525)
		(layer "In2.Cu")
		(net "M_C_CPU1_SA_DQS_DP<6>")
	)
	(arc
		(start 86.212426 -232.819194)
		(mid 86.396201 -232.768422)
		(end 86.581234 -232.814368)
		(width 0.09525)
		(layer "In2.Cu")
		(net "M_C_CPU1_SA_DQS_DP<6>")
	)
	(arc
		(start 87.160862 -232.814368)
		(mid 87.345894 -232.768454)
		(end 87.52967 -232.819194)
		(width 0.09525)
		(layer "In2.Cu")
		(net "M_C_CPU1_SA_DQS_DP<6>")
	)
	(arc
		(start 79.728822 -232.334308)
		(mid 79.793219 -232.595614)
		(end 79.971646 -232.797096)
		(width 0.09525)
		(layer "In2.Cu")
		(net "M_C_CPU1_SA_DQS_DP<6>")
	)
	(arc
		(start 92.79255 -232.819194)
		(mid 92.981018 -232.768517)
		(end 93.169486 -232.819194)
		(width 0.09525)
		(layer "In2.Cu")
		(net "M_C_CPU1_SA_DQS_DP<6>")
	)
	(arc
		(start 81.8896 -232.819194)
		(mid 82.171032 -232.894949)
		(end 82.452464 -232.819194)
		(width 0.09525)
		(layer "In2.Cu")
		(net "M_C_CPU1_SA_DQS_DP<6>")
	)
	(arc
		(start 78.319122 -229.90429)
		(mid 78.383882 -230.166225)
		(end 78.563216 -230.36784)
		(width 0.09525)
		(layer "In2.Cu")
		(net "M_C_CPU1_SA_DQS_DP<6>")
	)
	(arc
		(start 95.526352 -232.860088)
		(mid 95.536295 -232.856245)
		(end 95.546164 -232.852214)
		(width 0.09525)
		(layer "In2.Cu")
		(net "M_C_CPU1_SA_DQS_DP<6>")
	)
	(arc
		(start 78.631542 -230.407464)
		(mid 78.74734 -230.542)
		(end 78.789022 -230.71455)
		(width 0.09525)
		(layer "In2.Cu")
		(net "M_C_CPU1_SA_DQS_DP<6>")
	)
	(arc
		(start 82.460846 -232.814368)
		(mid 82.645878 -232.768454)
		(end 82.829654 -232.819194)
		(width 0.09525)
		(layer "In2.Cu")
		(net "M_C_CPU1_SA_DQS_DP<6>")
	)
	(arc
		(start 79.258922 -231.524302)
		(mid 79.324115 -231.786931)
		(end 79.50454 -231.988614)
		(width 0.09525)
		(layer "In2.Cu")
		(net "M_C_CPU1_SA_DQS_DP<6>")
	)
	(arc
		(start 93.73235 -232.819194)
		(mid 93.916125 -232.768422)
		(end 94.101158 -232.814368)
		(width 0.09525)
		(layer "In2.Cu")
		(net "M_C_CPU1_SA_DQS_DP<6>")
	)
	(arc
		(start 83.769708 -232.819194)
		(mid 84.05114 -232.894949)
		(end 84.332572 -232.819194)
		(width 0.09525)
		(layer "In2.Cu")
		(net "M_C_CPU1_SA_DQS_DP<6>")
	)
	(arc
		(start 80.009746 -232.819194)
		(mid 80.291178 -232.894949)
		(end 80.57261 -232.819194)
		(width 0.09525)
		(layer "In2.Cu")
		(net "M_C_CPU1_SA_DQS_DP<6>")
	)
	(arc
		(start 81.51241 -232.819194)
		(mid 81.696185 -232.768422)
		(end 81.881218 -232.814368)
		(width 0.09525)
		(layer "In2.Cu")
		(net "M_C_CPU1_SA_DQS_DP<6>")
	)
	(arc
		(start 77.278738 -228.042724)
		(mid 77.347165 -228.140498)
		(end 77.377798 -228.25583)
		(width 0.09525)
		(layer "In2.Cu")
		(net "M_C_CPU1_SA_DQS_DP<6>")
	)
	(arc
		(start 79.572104 -232.027984)
		(mid 79.687378 -232.162262)
		(end 79.728822 -232.334308)
		(width 0.09525)
		(layer "In2.Cu")
		(net "M_C_CPU1_SA_DQS_DP<6>")
	)
	(arc
		(start 77.848968 -229.094284)
		(mid 77.913718 -229.356453)
		(end 78.093316 -229.558088)
		(width 0.09525)
		(layer "In2.Cu")
		(net "M_C_CPU1_SA_DQS_DP<6>")
	)
	(arc
		(start 77.689456 -228.785928)
		(mid 77.80676 -228.920689)
		(end 77.848968 -229.094284)
		(width 0.09525)
		(layer "In2.Cu")
		(net "M_C_CPU1_SA_DQS_DP<6>")
	)
	(segment
		(start 96.267778 -228.55047)
		(end 95.800926 -228.284532)
		(width 0.12954)
		(layer "F.Cu")
		(net "M_C_CPU1_SA_DQS_DP<5>")
	)
	(segment
		(start 85.64118 -227.954586)
		(end 85.649562 -227.959412)
		(width 0.09525)
		(layer "In2.Cu")
		(net "M_C_CPU1_SA_DQS_DP<5>")
	)
	(segment
		(start 48.98771 -202.836272)
		(end 49.47793 -202.836272)
		(width 0.16002)
		(layer "In2.Cu")
		(net "M_C_CPU1_SA_DQS_DP<5>")
	)
	(segment
		(start 56.54675 -202.813412)
		(end 57.04713 -202.813412)
		(width 0.16002)
		(layer "In2.Cu")
		(net "M_C_CPU1_SA_DQS_DP<5>")
	)
	(segment
		(start 83.392518 -227.959412)
		(end 83.4009 -227.954586)
		(width 0.09525)
		(layer "In2.Cu")
		(net "M_C_CPU1_SA_DQS_DP<5>")
	)
	(segment
		(start 88.092534 -227.959412)
		(end 88.100916 -227.954586)
		(width 0.09525)
		(layer "In2.Cu")
		(net "M_C_CPU1_SA_DQS_DP<5>")
	)
	(segment
		(start 79.973424 -223.07804)
		(end 80.01 -223.099376)
		(width 0.09525)
		(layer "In2.Cu")
		(net "M_C_CPU1_SA_DQS_DP<5>")
	)
	(segment
		(start 79.199994 -219.56903)
		(end 79.199994 -221.174564)
		(width 0.16002)
		(layer "In2.Cu")
		(net "M_C_CPU1_SA_DQS_DP<5>")
	)
	(segment
		(start 81.8896 -226.3394)
		(end 81.922112 -226.358196)
		(width 0.09525)
		(layer "In2.Cu")
		(net "M_C_CPU1_SA_DQS_DP<5>")
	)
	(segment
		(start 69.142356 -209.033618)
		(end 69.465698 -209.35696)
		(width 0.16002)
		(layer "In2.Cu")
		(net "M_C_CPU1_SA_DQS_DP<5>")
	)
	(segment
		(start 46.583854 -203.160376)
		(end 48.663606 -203.160376)
		(width 0.16002)
		(layer "In2.Cu")
		(net "M_C_CPU1_SA_DQS_DP<5>")
	)
	(segment
		(start 42.032428 -202.161648)
		(end 42.231564 -201.962512)
		(width 0.16002)
		(layer "In2.Cu")
		(net "M_C_CPU1_SA_DQS_DP<5>")
	)
	(segment
		(start 57.04713 -202.813412)
		(end 57.849262 -202.01128)
		(width 0.16002)
		(layer "In2.Cu")
		(net "M_C_CPU1_SA_DQS_DP<5>")
	)
	(segment
		(start 61.590936 -203.422504)
		(end 63.71082 -203.422504)
		(width 0.16002)
		(layer "In2.Cu")
		(net "M_C_CPU1_SA_DQS_DP<5>")
	)
	(segment
		(start 95.546164 -227.992432)
		(end 95.647002 -228.019102)
		(width 0.09525)
		(layer "In2.Cu")
		(net "M_C_CPU1_SA_DQS_DP<5>")
	)
	(segment
		(start 69.142356 -208.85404)
		(end 69.142356 -209.033618)
		(width 0.16002)
		(layer "In2.Cu")
		(net "M_C_CPU1_SA_DQS_DP<5>")
	)
	(segment
		(start 82.791554 -227.937314)
		(end 82.829654 -227.959412)
		(width 0.09525)
		(layer "In2.Cu")
		(net "M_C_CPU1_SA_DQS_DP<5>")
	)
	(segment
		(start 79.408782 -222.16618)
		(end 79.502 -222.259906)
		(width 0.09525)
		(layer "In2.Cu")
		(net "M_C_CPU1_SA_DQS_DP<5>")
	)
	(segment
		(start 63.71082 -203.422504)
		(end 69.142356 -208.85404)
		(width 0.16002)
		(layer "In2.Cu")
		(net "M_C_CPU1_SA_DQS_DP<5>")
	)
	(segment
		(start 69.645276 -209.35696)
		(end 71.804784 -211.516468)
		(width 0.16002)
		(layer "In2.Cu")
		(net "M_C_CPU1_SA_DQS_DP<5>")
	)
	(segment
		(start 49.47793 -202.836272)
		(end 50.33137 -201.982832)
		(width 0.16002)
		(layer "In2.Cu")
		(net "M_C_CPU1_SA_DQS_DP<5>")
	)
	(segment
		(start 58.253376 -202.01128)
		(end 58.511948 -202.269852)
		(width 0.16002)
		(layer "In2.Cu")
		(net "M_C_CPU1_SA_DQS_DP<5>")
	)
	(segment
		(start 42.231564 -201.962512)
		(end 43.106848 -201.962512)
		(width 0.16002)
		(layer "In2.Cu")
		(net "M_C_CPU1_SA_DQS_DP<5>")
	)
	(segment
		(start 48.663606 -203.160376)
		(end 48.98771 -202.836272)
		(width 0.16002)
		(layer "In2.Cu")
		(net "M_C_CPU1_SA_DQS_DP<5>")
	)
	(segment
		(start 81.8515 -226.317302)
		(end 81.8896 -226.3394)
		(width 0.09525)
		(layer "In2.Cu")
		(net "M_C_CPU1_SA_DQS_DP<5>")
	)
	(segment
		(start 50.69459 -201.982832)
		(end 51.02225 -202.310492)
		(width 0.16002)
		(layer "In2.Cu")
		(net "M_C_CPU1_SA_DQS_DP<5>")
	)
	(segment
		(start 43.714162 -202.569826)
		(end 45.993304 -202.569826)
		(width 0.16002)
		(layer "In2.Cu")
		(net "M_C_CPU1_SA_DQS_DP<5>")
	)
	(segment
		(start 79.539846 -222.288862)
		(end 79.539846 -222.28937)
		(width 0.09525)
		(layer "In2.Cu")
		(net "M_C_CPU1_SA_DQS_DP<5>")
	)
	(segment
		(start 60.438284 -202.269852)
		(end 61.590936 -203.422504)
		(width 0.16002)
		(layer "In2.Cu")
		(net "M_C_CPU1_SA_DQS_DP<5>")
	)
	(segment
		(start 90.341196 -227.954586)
		(end 90.349578 -227.959412)
		(width 0.09525)
		(layer "In2.Cu")
		(net "M_C_CPU1_SA_DQS_DP<5>")
	)
	(segment
		(start 71.804784 -212.17382)
		(end 79.199994 -219.56903)
		(width 0.16002)
		(layer "In2.Cu")
		(net "M_C_CPU1_SA_DQS_DP<5>")
	)
	(segment
		(start 43.106848 -201.962512)
		(end 43.714162 -202.569826)
		(width 0.16002)
		(layer "In2.Cu")
		(net "M_C_CPU1_SA_DQS_DP<5>")
	)
	(segment
		(start 80.01 -223.099376)
		(end 80.041496 -223.117664)
		(width 0.09525)
		(layer "In2.Cu")
		(net "M_C_CPU1_SA_DQS_DP<5>")
	)
	(segment
		(start 79.259176 -221.257368)
		(end 79.259176 -221.804484)
		(width 0.09525)
		(layer "In2.Cu")
		(net "M_C_CPU1_SA_DQS_DP<5>")
	)
	(segment
		(start 58.511948 -202.269852)
		(end 60.438284 -202.269852)
		(width 0.16002)
		(layer "In2.Cu")
		(net "M_C_CPU1_SA_DQS_DP<5>")
	)
	(segment
		(start 71.804784 -211.516468)
		(end 71.804784 -212.17382)
		(width 0.16002)
		(layer "In2.Cu")
		(net "M_C_CPU1_SA_DQS_DP<5>")
	)
	(segment
		(start 81.4197 -225.529394)
		(end 81.451196 -225.547682)
		(width 0.09525)
		(layer "In2.Cu")
		(net "M_C_CPU1_SA_DQS_DP<5>")
	)
	(segment
		(start 87.15248 -227.959412)
		(end 87.160862 -227.954586)
		(width 0.09525)
		(layer "In2.Cu")
		(net "M_C_CPU1_SA_DQS_DP<5>")
	)
	(segment
		(start 40.513508 -202.161648)
		(end 42.032428 -202.161648)
		(width 0.16002)
		(layer "In2.Cu")
		(net "M_C_CPU1_SA_DQS_DP<5>")
	)
	(segment
		(start 95.041212 -227.954586)
		(end 95.049594 -227.959412)
		(width 0.09525)
		(layer "In2.Cu")
		(net "M_C_CPU1_SA_DQS_DP<5>")
	)
	(segment
		(start 79.199994 -221.174564)
		(end 79.199994 -221.198186)
		(width 0.09525)
		(layer "In2.Cu")
		(net "M_C_CPU1_SA_DQS_DP<5>")
	)
	(segment
		(start 80.914494 -224.698814)
		(end 80.949546 -224.719388)
		(width 0.09525)
		(layer "In2.Cu")
		(net "M_C_CPU1_SA_DQS_DP<5>")
	)
	(segment
		(start 82.3595 -227.149406)
		(end 82.392012 -227.168202)
		(width 0.09525)
		(layer "In2.Cu")
		(net "M_C_CPU1_SA_DQS_DP<5>")
	)
	(segment
		(start 86.581234 -227.954586)
		(end 86.589616 -227.959412)
		(width 0.09525)
		(layer "In2.Cu")
		(net "M_C_CPU1_SA_DQS_DP<5>")
	)
	(segment
		(start 80.479646 -223.909382)
		(end 80.512158 -223.928178)
		(width 0.09525)
		(layer "In2.Cu")
		(net "M_C_CPU1_SA_DQS_DP<5>")
	)
	(segment
		(start 56.22671 -203.133452)
		(end 56.54675 -202.813412)
		(width 0.16002)
		(layer "In2.Cu")
		(net "M_C_CPU1_SA_DQS_DP<5>")
	)
	(segment
		(start 50.33137 -201.982832)
		(end 50.69459 -201.982832)
		(width 0.16002)
		(layer "In2.Cu")
		(net "M_C_CPU1_SA_DQS_DP<5>")
	)
	(segment
		(start 81.3816 -225.507296)
		(end 81.4197 -225.529394)
		(width 0.09525)
		(layer "In2.Cu")
		(net "M_C_CPU1_SA_DQS_DP<5>")
	)
	(segment
		(start 91.852496 -227.959412)
		(end 91.860878 -227.954586)
		(width 0.09525)
		(layer "In2.Cu")
		(net "M_C_CPU1_SA_DQS_DP<5>")
	)
	(segment
		(start 69.465698 -209.35696)
		(end 69.645276 -209.35696)
		(width 0.16002)
		(layer "In2.Cu")
		(net "M_C_CPU1_SA_DQS_DP<5>")
	)
	(segment
		(start 79.199994 -221.198186)
		(end 79.259176 -221.257368)
		(width 0.09525)
		(layer "In2.Cu")
		(net "M_C_CPU1_SA_DQS_DP<5>")
	)
	(segment
		(start 40.23995 -202.435206)
		(end 40.513508 -202.161648)
		(width 0.16002)
		(layer "In2.Cu")
		(net "M_C_CPU1_SA_DQS_DP<5>")
	)
	(segment
		(start 79.539846 -222.28937)
		(end 79.574644 -222.309436)
		(width 0.09525)
		(layer "In2.Cu")
		(net "M_C_CPU1_SA_DQS_DP<5>")
	)
	(segment
		(start 53.37429 -202.310492)
		(end 54.19725 -203.133452)
		(width 0.16002)
		(layer "In2.Cu")
		(net "M_C_CPU1_SA_DQS_DP<5>")
	)
	(segment
		(start 57.849262 -202.01128)
		(end 58.253376 -202.01128)
		(width 0.16002)
		(layer "In2.Cu")
		(net "M_C_CPU1_SA_DQS_DP<5>")
	)
	(segment
		(start 54.19725 -203.133452)
		(end 56.22671 -203.133452)
		(width 0.16002)
		(layer "In2.Cu")
		(net "M_C_CPU1_SA_DQS_DP<5>")
	)
	(segment
		(start 82.324448 -227.128832)
		(end 82.3595 -227.149406)
		(width 0.09525)
		(layer "In2.Cu")
		(net "M_C_CPU1_SA_DQS_DP<5>")
	)
	(segment
		(start 94.101158 -227.954586)
		(end 94.10954 -227.959412)
		(width 0.09525)
		(layer "In2.Cu")
		(net "M_C_CPU1_SA_DQS_DP<5>")
	)
	(segment
		(start 95.647002 -228.019102)
		(end 95.800926 -228.284532)
		(width 0.09525)
		(layer "In2.Cu")
		(net "M_C_CPU1_SA_DQS_DP<5>")
	)
	(segment
		(start 90.912442 -227.959412)
		(end 90.920824 -227.954586)
		(width 0.09525)
		(layer "In2.Cu")
		(net "M_C_CPU1_SA_DQS_DP<5>")
	)
	(segment
		(start 80.949546 -224.719388)
		(end 80.982058 -224.738184)
		(width 0.09525)
		(layer "In2.Cu")
		(net "M_C_CPU1_SA_DQS_DP<5>")
	)
	(segment
		(start 80.444594 -223.888808)
		(end 80.479646 -223.909382)
		(width 0.09525)
		(layer "In2.Cu")
		(net "M_C_CPU1_SA_DQS_DP<5>")
	)
	(segment
		(start 51.02225 -202.310492)
		(end 53.37429 -202.310492)
		(width 0.16002)
		(layer "In2.Cu")
		(net "M_C_CPU1_SA_DQS_DP<5>")
	)
	(segment
		(start 45.993304 -202.569826)
		(end 46.583854 -203.160376)
		(width 0.16002)
		(layer "In2.Cu")
		(net "M_C_CPU1_SA_DQS_DP<5>")
	)
	(arc
		(start 80.982058 -224.738184)
		(mid 81.097332 -224.872462)
		(end 81.138776 -225.044508)
		(width 0.09525)
		(layer "In2.Cu")
		(net "M_C_CPU1_SA_DQS_DP<5>")
	)
	(arc
		(start 94.10954 -227.959412)
		(mid 94.390972 -228.035167)
		(end 94.672404 -227.959412)
		(width 0.09525)
		(layer "In2.Cu")
		(net "M_C_CPU1_SA_DQS_DP<5>")
	)
	(arc
		(start 82.829654 -227.959412)
		(mid 83.111086 -228.035167)
		(end 83.392518 -227.959412)
		(width 0.09525)
		(layer "In2.Cu")
		(net "M_C_CPU1_SA_DQS_DP<5>")
	)
	(arc
		(start 91.289632 -227.959412)
		(mid 91.571064 -228.035167)
		(end 91.852496 -227.959412)
		(width 0.09525)
		(layer "In2.Cu")
		(net "M_C_CPU1_SA_DQS_DP<5>")
	)
	(arc
		(start 81.922112 -226.358196)
		(mid 82.037386 -226.492474)
		(end 82.07883 -226.66452)
		(width 0.09525)
		(layer "In2.Cu")
		(net "M_C_CPU1_SA_DQS_DP<5>")
	)
	(arc
		(start 80.512158 -223.928178)
		(mid 80.627432 -224.062456)
		(end 80.668876 -224.234502)
		(width 0.09525)
		(layer "In2.Cu")
		(net "M_C_CPU1_SA_DQS_DP<5>")
	)
	(arc
		(start 89.032588 -227.959412)
		(mid 89.221056 -227.908735)
		(end 89.409524 -227.959412)
		(width 0.09525)
		(layer "In2.Cu")
		(net "M_C_CPU1_SA_DQS_DP<5>")
	)
	(arc
		(start 95.049594 -227.959412)
		(mid 95.29402 -228.034055)
		(end 95.546164 -227.992432)
		(width 0.09525)
		(layer "In2.Cu")
		(net "M_C_CPU1_SA_DQS_DP<5>")
	)
	(arc
		(start 91.860878 -227.954586)
		(mid 92.04591 -227.908672)
		(end 92.229686 -227.959412)
		(width 0.09525)
		(layer "In2.Cu")
		(net "M_C_CPU1_SA_DQS_DP<5>")
	)
	(arc
		(start 84.709508 -227.959412)
		(mid 84.99094 -228.035167)
		(end 85.272372 -227.959412)
		(width 0.09525)
		(layer "In2.Cu")
		(net "M_C_CPU1_SA_DQS_DP<5>")
	)
	(arc
		(start 89.972388 -227.959412)
		(mid 90.156163 -227.90864)
		(end 90.341196 -227.954586)
		(width 0.09525)
		(layer "In2.Cu")
		(net "M_C_CPU1_SA_DQS_DP<5>")
	)
	(arc
		(start 80.041496 -223.117664)
		(mid 80.157294 -223.252058)
		(end 80.198976 -223.424496)
		(width 0.09525)
		(layer "In2.Cu")
		(net "M_C_CPU1_SA_DQS_DP<5>")
	)
	(arc
		(start 93.169486 -227.959412)
		(mid 93.450918 -228.035167)
		(end 93.73235 -227.959412)
		(width 0.09525)
		(layer "In2.Cu")
		(net "M_C_CPU1_SA_DQS_DP<5>")
	)
	(arc
		(start 85.649562 -227.959412)
		(mid 85.930994 -228.035167)
		(end 86.212426 -227.959412)
		(width 0.09525)
		(layer "In2.Cu")
		(net "M_C_CPU1_SA_DQS_DP<5>")
	)
	(arc
		(start 89.409524 -227.959412)
		(mid 89.690956 -228.035167)
		(end 89.972388 -227.959412)
		(width 0.09525)
		(layer "In2.Cu")
		(net "M_C_CPU1_SA_DQS_DP<5>")
	)
	(arc
		(start 79.259176 -221.804484)
		(mid 79.298157 -222.000143)
		(end 79.408782 -222.16618)
		(width 0.09525)
		(layer "In2.Cu")
		(net "M_C_CPU1_SA_DQS_DP<5>")
	)
	(arc
		(start 92.229686 -227.959412)
		(mid 92.511118 -228.035167)
		(end 92.79255 -227.959412)
		(width 0.09525)
		(layer "In2.Cu")
		(net "M_C_CPU1_SA_DQS_DP<5>")
	)
	(arc
		(start 86.589616 -227.959412)
		(mid 86.871048 -228.035167)
		(end 87.15248 -227.959412)
		(width 0.09525)
		(layer "In2.Cu")
		(net "M_C_CPU1_SA_DQS_DP<5>")
	)
	(arc
		(start 82.54873 -227.474526)
		(mid 82.613127 -227.735832)
		(end 82.791554 -227.937314)
		(width 0.09525)
		(layer "In2.Cu")
		(net "M_C_CPU1_SA_DQS_DP<5>")
	)
	(arc
		(start 88.100916 -227.954586)
		(mid 88.285948 -227.908672)
		(end 88.469724 -227.959412)
		(width 0.09525)
		(layer "In2.Cu")
		(net "M_C_CPU1_SA_DQS_DP<5>")
	)
	(arc
		(start 81.451196 -225.547682)
		(mid 81.566994 -225.682076)
		(end 81.608676 -225.854514)
		(width 0.09525)
		(layer "In2.Cu")
		(net "M_C_CPU1_SA_DQS_DP<5>")
	)
	(arc
		(start 83.4009 -227.954586)
		(mid 83.585932 -227.908672)
		(end 83.769708 -227.959412)
		(width 0.09525)
		(layer "In2.Cu")
		(net "M_C_CPU1_SA_DQS_DP<5>")
	)
	(arc
		(start 90.920824 -227.954586)
		(mid 91.105856 -227.908672)
		(end 91.289632 -227.959412)
		(width 0.09525)
		(layer "In2.Cu")
		(net "M_C_CPU1_SA_DQS_DP<5>")
	)
	(arc
		(start 81.608676 -225.854514)
		(mid 81.673073 -226.11582)
		(end 81.8515 -226.317302)
		(width 0.09525)
		(layer "In2.Cu")
		(net "M_C_CPU1_SA_DQS_DP<5>")
	)
	(arc
		(start 82.392012 -227.168202)
		(mid 82.507286 -227.30248)
		(end 82.54873 -227.474526)
		(width 0.09525)
		(layer "In2.Cu")
		(net "M_C_CPU1_SA_DQS_DP<5>")
	)
	(arc
		(start 83.769708 -227.959412)
		(mid 84.05114 -228.035167)
		(end 84.332572 -227.959412)
		(width 0.09525)
		(layer "In2.Cu")
		(net "M_C_CPU1_SA_DQS_DP<5>")
	)
	(arc
		(start 82.07883 -226.66452)
		(mid 82.144023 -226.927149)
		(end 82.324448 -227.128832)
		(width 0.09525)
		(layer "In2.Cu")
		(net "M_C_CPU1_SA_DQS_DP<5>")
	)
	(arc
		(start 86.212426 -227.959412)
		(mid 86.396201 -227.90864)
		(end 86.581234 -227.954586)
		(width 0.09525)
		(layer "In2.Cu")
		(net "M_C_CPU1_SA_DQS_DP<5>")
	)
	(arc
		(start 93.73235 -227.959412)
		(mid 93.916125 -227.90864)
		(end 94.101158 -227.954586)
		(width 0.09525)
		(layer "In2.Cu")
		(net "M_C_CPU1_SA_DQS_DP<5>")
	)
	(arc
		(start 92.79255 -227.959412)
		(mid 92.981018 -227.908735)
		(end 93.169486 -227.959412)
		(width 0.09525)
		(layer "In2.Cu")
		(net "M_C_CPU1_SA_DQS_DP<5>")
	)
	(arc
		(start 94.672404 -227.959412)
		(mid 94.856179 -227.90864)
		(end 95.041212 -227.954586)
		(width 0.09525)
		(layer "In2.Cu")
		(net "M_C_CPU1_SA_DQS_DP<5>")
	)
	(arc
		(start 88.469724 -227.959412)
		(mid 88.751156 -228.035167)
		(end 89.032588 -227.959412)
		(width 0.09525)
		(layer "In2.Cu")
		(net "M_C_CPU1_SA_DQS_DP<5>")
	)
	(arc
		(start 81.138776 -225.044508)
		(mid 81.203173 -225.305814)
		(end 81.3816 -225.507296)
		(width 0.09525)
		(layer "In2.Cu")
		(net "M_C_CPU1_SA_DQS_DP<5>")
	)
	(arc
		(start 84.332572 -227.959412)
		(mid 84.52104 -227.908735)
		(end 84.709508 -227.959412)
		(width 0.09525)
		(layer "In2.Cu")
		(net "M_C_CPU1_SA_DQS_DP<5>")
	)
	(arc
		(start 87.52967 -227.959412)
		(mid 87.811102 -228.035167)
		(end 88.092534 -227.959412)
		(width 0.09525)
		(layer "In2.Cu")
		(net "M_C_CPU1_SA_DQS_DP<5>")
	)
	(arc
		(start 87.160862 -227.954586)
		(mid 87.345894 -227.908672)
		(end 87.52967 -227.959412)
		(width 0.09525)
		(layer "In2.Cu")
		(net "M_C_CPU1_SA_DQS_DP<5>")
	)
	(arc
		(start 79.574644 -222.309436)
		(mid 79.688429 -222.44348)
		(end 79.72933 -222.61449)
		(width 0.09525)
		(layer "In2.Cu")
		(net "M_C_CPU1_SA_DQS_DP<5>")
	)
	(arc
		(start 80.198976 -223.424496)
		(mid 80.264169 -223.687125)
		(end 80.444594 -223.888808)
		(width 0.09525)
		(layer "In2.Cu")
		(net "M_C_CPU1_SA_DQS_DP<5>")
	)
	(arc
		(start 80.668876 -224.234502)
		(mid 80.734069 -224.497131)
		(end 80.914494 -224.698814)
		(width 0.09525)
		(layer "In2.Cu")
		(net "M_C_CPU1_SA_DQS_DP<5>")
	)
	(arc
		(start 90.349578 -227.959412)
		(mid 90.63101 -228.035167)
		(end 90.912442 -227.959412)
		(width 0.09525)
		(layer "In2.Cu")
		(net "M_C_CPU1_SA_DQS_DP<5>")
	)
	(arc
		(start 85.272372 -227.959412)
		(mid 85.456147 -227.90864)
		(end 85.64118 -227.954586)
		(width 0.09525)
		(layer "In2.Cu")
		(net "M_C_CPU1_SA_DQS_DP<5>")
	)
	(arc
		(start 79.502 -222.259906)
		(mid 79.519964 -222.275638)
		(end 79.539846 -222.288862)
		(width 0.09525)
		(layer "In2.Cu")
		(net "M_C_CPU1_SA_DQS_DP<5>")
	)
	(arc
		(start 79.72933 -222.61449)
		(mid 79.79409 -222.876425)
		(end 79.973424 -223.07804)
		(width 0.09525)
		(layer "In2.Cu")
		(net "M_C_CPU1_SA_DQS_DP<5>")
	)
	(segment
		(start 94.387924 -246.370348)
		(end 93.921072 -246.10441)
		(width 0.12954)
		(layer "F.Cu")
		(net "M_C_CPU1_SA_DQS_DP<4>")
	)
	(segment
		(start 48.678592 -238.260128)
		(end 48.993552 -238.575088)
		(width 0.16002)
		(layer "In2.Cu")
		(net "M_C_CPU1_SA_DQS_DP<4>")
	)
	(segment
		(start 45.501814 -238.409226)
		(end 45.650912 -238.260128)
		(width 0.16002)
		(layer "In2.Cu")
		(net "M_C_CPU1_SA_DQS_DP<4>")
	)
	(segment
		(start 65.475866 -242.716304)
		(end 65.738502 -242.453668)
		(width 0.16002)
		(layer "In2.Cu")
		(net "M_C_CPU1_SA_DQS_DP<4>")
	)
	(segment
		(start 62.505844 -239.97285)
		(end 62.505844 -240.524538)
		(width 0.16002)
		(layer "In2.Cu")
		(net "M_C_CPU1_SA_DQS_DP<4>")
	)
	(segment
		(start 67.290442 -243.648992)
		(end 67.817746 -243.648992)
		(width 0.16002)
		(layer "In2.Cu")
		(net "M_C_CPU1_SA_DQS_DP<4>")
	)
	(segment
		(start 61.132212 -238.599218)
		(end 61.132212 -239.150906)
		(width 0.16002)
		(layer "In2.Cu")
		(net "M_C_CPU1_SA_DQS_DP<4>")
	)
	(segment
		(start 60.85713 -237.892844)
		(end 60.85713 -238.324136)
		(width 0.16002)
		(layer "In2.Cu")
		(net "M_C_CPU1_SA_DQS_DP<4>")
	)
	(segment
		(start 88.092534 -246.42953)
		(end 88.100916 -246.434356)
		(width 0.09525)
		(layer "In2.Cu")
		(net "M_C_CPU1_SA_DQS_DP<4>")
	)
	(segment
		(start 63.879476 -241.89817)
		(end 64.20231 -242.221004)
		(width 0.16002)
		(layer "In2.Cu")
		(net "M_C_CPU1_SA_DQS_DP<4>")
	)
	(segment
		(start 53.792628 -238.303308)
		(end 56.235092 -238.303308)
		(width 0.16002)
		(layer "In2.Cu")
		(net "M_C_CPU1_SA_DQS_DP<4>")
	)
	(segment
		(start 44.61383 -238.409226)
		(end 45.501814 -238.409226)
		(width 0.16002)
		(layer "In2.Cu")
		(net "M_C_CPU1_SA_DQS_DP<4>")
	)
	(segment
		(start 78.691994 -246.42953)
		(end 78.700376 -246.434356)
		(width 0.09525)
		(layer "In2.Cu")
		(net "M_C_CPU1_SA_DQS_DP<4>")
	)
	(segment
		(start 61.455046 -239.47374)
		(end 62.006734 -239.47374)
		(width 0.16002)
		(layer "In2.Cu")
		(net "M_C_CPU1_SA_DQS_DP<4>")
	)
	(segment
		(start 69.298566 -245.64086)
		(end 69.415406 -245.7577)
		(width 0.16002)
		(layer "In2.Cu")
		(net "M_C_CPU1_SA_DQS_DP<4>")
	)
	(segment
		(start 75.704192 -246.339614)
		(end 75.955906 -246.339614)
		(width 0.16002)
		(layer "In2.Cu")
		(net "M_C_CPU1_SA_DQS_DP<4>")
	)
	(segment
		(start 66.63944 -242.827302)
		(end 66.63944 -243.354606)
		(width 0.16002)
		(layer "In2.Cu")
		(net "M_C_CPU1_SA_DQS_DP<4>")
	)
	(segment
		(start 63.879476 -241.346482)
		(end 63.879476 -241.89817)
		(width 0.16002)
		(layer "In2.Cu")
		(net "M_C_CPU1_SA_DQS_DP<4>")
	)
	(segment
		(start 62.505844 -240.524538)
		(end 62.828678 -240.847372)
		(width 0.16002)
		(layer "In2.Cu")
		(net "M_C_CPU1_SA_DQS_DP<4>")
	)
	(segment
		(start 66.312034 -244.35054)
		(end 66.588894 -244.35054)
		(width 0.16002)
		(layer "In2.Cu")
		(net "M_C_CPU1_SA_DQS_DP<4>")
	)
	(segment
		(start 65.249298 -242.716304)
		(end 65.475866 -242.716304)
		(width 0.16002)
		(layer "In2.Cu")
		(net "M_C_CPU1_SA_DQS_DP<4>")
	)
	(segment
		(start 67.817746 -243.648992)
		(end 68.19138 -244.022626)
		(width 0.16002)
		(layer "In2.Cu")
		(net "M_C_CPU1_SA_DQS_DP<4>")
	)
	(segment
		(start 56.863488 -238.592868)
		(end 57.661048 -237.795308)
		(width 0.16002)
		(layer "In2.Cu")
		(net "M_C_CPU1_SA_DQS_DP<4>")
	)
	(segment
		(start 50.703988 -237.721648)
		(end 51.015392 -237.410244)
		(width 0.16002)
		(layer "In2.Cu")
		(net "M_C_CPU1_SA_DQS_DP<4>")
	)
	(segment
		(start 94.074996 -246.36984)
		(end 93.921072 -246.10441)
		(width 0.09525)
		(layer "In2.Cu")
		(net "M_C_CPU1_SA_DQS_DP<4>")
	)
	(segment
		(start 76.273406 -246.398796)
		(end 76.639674 -246.765064)
		(width 0.09525)
		(layer "In2.Cu")
		(net "M_C_CPU1_SA_DQS_DP<4>")
	)
	(segment
		(start 82.452464 -246.42953)
		(end 82.460846 -246.434356)
		(width 0.09525)
		(layer "In2.Cu")
		(net "M_C_CPU1_SA_DQS_DP<4>")
	)
	(segment
		(start 66.588894 -244.35054)
		(end 67.290442 -243.648992)
		(width 0.16002)
		(layer "In2.Cu")
		(net "M_C_CPU1_SA_DQS_DP<4>")
	)
	(segment
		(start 91.852496 -246.42953)
		(end 91.860878 -246.434356)
		(width 0.09525)
		(layer "In2.Cu")
		(net "M_C_CPU1_SA_DQS_DP<4>")
	)
	(segment
		(start 77.656182 -246.765064)
		(end 77.9399 -246.481346)
		(width 0.09525)
		(layer "In2.Cu")
		(net "M_C_CPU1_SA_DQS_DP<4>")
	)
	(segment
		(start 50.297588 -237.721648)
		(end 50.703988 -237.721648)
		(width 0.16002)
		(layer "In2.Cu")
		(net "M_C_CPU1_SA_DQS_DP<4>")
	)
	(segment
		(start 94.051628 -246.456708)
		(end 94.074996 -246.36984)
		(width 0.09525)
		(layer "In2.Cu")
		(net "M_C_CPU1_SA_DQS_DP<4>")
	)
	(segment
		(start 76.639674 -246.765064)
		(end 77.656182 -246.765064)
		(width 0.09525)
		(layer "In2.Cu")
		(net "M_C_CPU1_SA_DQS_DP<4>")
	)
	(segment
		(start 44.340018 -238.135414)
		(end 44.61383 -238.409226)
		(width 0.16002)
		(layer "In2.Cu")
		(net "M_C_CPU1_SA_DQS_DP<4>")
	)
	(segment
		(start 66.265806 -242.453668)
		(end 66.63944 -242.827302)
		(width 0.16002)
		(layer "In2.Cu")
		(net "M_C_CPU1_SA_DQS_DP<4>")
	)
	(segment
		(start 63.380366 -240.847372)
		(end 63.879476 -241.346482)
		(width 0.16002)
		(layer "In2.Cu")
		(net "M_C_CPU1_SA_DQS_DP<4>")
	)
	(segment
		(start 56.524652 -238.592868)
		(end 56.863488 -238.592868)
		(width 0.16002)
		(layer "In2.Cu")
		(net "M_C_CPU1_SA_DQS_DP<4>")
	)
	(segment
		(start 56.235092 -238.303308)
		(end 56.524652 -238.592868)
		(width 0.16002)
		(layer "In2.Cu")
		(net "M_C_CPU1_SA_DQS_DP<4>")
	)
	(segment
		(start 81.881218 -246.434356)
		(end 81.8896 -246.42953)
		(width 0.09525)
		(layer "In2.Cu")
		(net "M_C_CPU1_SA_DQS_DP<4>")
	)
	(segment
		(start 68.19138 -244.022626)
		(end 68.19138 -244.54993)
		(width 0.16002)
		(layer "In2.Cu")
		(net "M_C_CPU1_SA_DQS_DP<4>")
	)
	(segment
		(start 90.912442 -246.42953)
		(end 90.920824 -246.434356)
		(width 0.09525)
		(layer "In2.Cu")
		(net "M_C_CPU1_SA_DQS_DP<4>")
	)
	(segment
		(start 51.015392 -237.410244)
		(end 52.899564 -237.410244)
		(width 0.16002)
		(layer "In2.Cu")
		(net "M_C_CPU1_SA_DQS_DP<4>")
	)
	(segment
		(start 65.738502 -242.453668)
		(end 66.265806 -242.453668)
		(width 0.16002)
		(layer "In2.Cu")
		(net "M_C_CPU1_SA_DQS_DP<4>")
	)
	(segment
		(start 45.650912 -238.260128)
		(end 48.678592 -238.260128)
		(width 0.16002)
		(layer "In2.Cu")
		(net "M_C_CPU1_SA_DQS_DP<4>")
	)
	(segment
		(start 58.489088 -237.444788)
		(end 60.409074 -237.444788)
		(width 0.16002)
		(layer "In2.Cu")
		(net "M_C_CPU1_SA_DQS_DP<4>")
	)
	(segment
		(start 68.818506 -245.64086)
		(end 69.298566 -245.64086)
		(width 0.16002)
		(layer "In2.Cu")
		(net "M_C_CPU1_SA_DQS_DP<4>")
	)
	(segment
		(start 64.753998 -242.221004)
		(end 65.249298 -242.716304)
		(width 0.16002)
		(layer "In2.Cu")
		(net "M_C_CPU1_SA_DQS_DP<4>")
	)
	(segment
		(start 60.409074 -237.444788)
		(end 60.85713 -237.892844)
		(width 0.16002)
		(layer "In2.Cu")
		(net "M_C_CPU1_SA_DQS_DP<4>")
	)
	(segment
		(start 87.15248 -246.42953)
		(end 87.160862 -246.434356)
		(width 0.09525)
		(layer "In2.Cu")
		(net "M_C_CPU1_SA_DQS_DP<4>")
	)
	(segment
		(start 58.138568 -237.795308)
		(end 58.489088 -237.444788)
		(width 0.16002)
		(layer "In2.Cu")
		(net "M_C_CPU1_SA_DQS_DP<4>")
	)
	(segment
		(start 90.341196 -246.434356)
		(end 90.349578 -246.42953)
		(width 0.09525)
		(layer "In2.Cu")
		(net "M_C_CPU1_SA_DQS_DP<4>")
	)
	(segment
		(start 48.993552 -238.575088)
		(end 49.444148 -238.575088)
		(width 0.16002)
		(layer "In2.Cu")
		(net "M_C_CPU1_SA_DQS_DP<4>")
	)
	(segment
		(start 85.64118 -246.434356)
		(end 85.649562 -246.42953)
		(width 0.09525)
		(layer "In2.Cu")
		(net "M_C_CPU1_SA_DQS_DP<4>")
	)
	(segment
		(start 80.001364 -246.434356)
		(end 80.009746 -246.42953)
		(width 0.09525)
		(layer "In2.Cu")
		(net "M_C_CPU1_SA_DQS_DP<4>")
	)
	(segment
		(start 64.20231 -242.221004)
		(end 64.753998 -242.221004)
		(width 0.16002)
		(layer "In2.Cu")
		(net "M_C_CPU1_SA_DQS_DP<4>")
	)
	(segment
		(start 86.581234 -246.434356)
		(end 86.589616 -246.42953)
		(width 0.09525)
		(layer "In2.Cu")
		(net "M_C_CPU1_SA_DQS_DP<4>")
	)
	(segment
		(start 75.955906 -246.339614)
		(end 75.979528 -246.339614)
		(width 0.09525)
		(layer "In2.Cu")
		(net "M_C_CPU1_SA_DQS_DP<4>")
	)
	(segment
		(start 57.661048 -237.795308)
		(end 58.138568 -237.795308)
		(width 0.16002)
		(layer "In2.Cu")
		(net "M_C_CPU1_SA_DQS_DP<4>")
	)
	(segment
		(start 67.741038 -245.277132)
		(end 68.221606 -245.7577)
		(width 0.16002)
		(layer "In2.Cu")
		(net "M_C_CPU1_SA_DQS_DP<4>")
	)
	(segment
		(start 75.979528 -246.339614)
		(end 76.03871 -246.398796)
		(width 0.09525)
		(layer "In2.Cu")
		(net "M_C_CPU1_SA_DQS_DP<4>")
	)
	(segment
		(start 79.068676 -246.42953)
		(end 79.083408 -246.420894)
		(width 0.09525)
		(layer "In2.Cu")
		(net "M_C_CPU1_SA_DQS_DP<4>")
	)
	(segment
		(start 67.741038 -245.000272)
		(end 67.741038 -245.277132)
		(width 0.16002)
		(layer "In2.Cu")
		(net "M_C_CPU1_SA_DQS_DP<4>")
	)
	(segment
		(start 75.122278 -245.7577)
		(end 75.704192 -246.339614)
		(width 0.16002)
		(layer "In2.Cu")
		(net "M_C_CPU1_SA_DQS_DP<4>")
	)
	(segment
		(start 68.701666 -245.7577)
		(end 68.818506 -245.64086)
		(width 0.16002)
		(layer "In2.Cu")
		(net "M_C_CPU1_SA_DQS_DP<4>")
	)
	(segment
		(start 62.828678 -240.847372)
		(end 63.380366 -240.847372)
		(width 0.16002)
		(layer "In2.Cu")
		(net "M_C_CPU1_SA_DQS_DP<4>")
	)
	(segment
		(start 66.1162 -244.154706)
		(end 66.312034 -244.35054)
		(width 0.16002)
		(layer "In2.Cu")
		(net "M_C_CPU1_SA_DQS_DP<4>")
	)
	(segment
		(start 52.899564 -237.410244)
		(end 53.792628 -238.303308)
		(width 0.16002)
		(layer "In2.Cu")
		(net "M_C_CPU1_SA_DQS_DP<4>")
	)
	(segment
		(start 62.006734 -239.47374)
		(end 62.505844 -239.97285)
		(width 0.16002)
		(layer "In2.Cu")
		(net "M_C_CPU1_SA_DQS_DP<4>")
	)
	(segment
		(start 68.221606 -245.7577)
		(end 68.701666 -245.7577)
		(width 0.16002)
		(layer "In2.Cu")
		(net "M_C_CPU1_SA_DQS_DP<4>")
	)
	(segment
		(start 83.392518 -246.42953)
		(end 83.4009 -246.434356)
		(width 0.09525)
		(layer "In2.Cu")
		(net "M_C_CPU1_SA_DQS_DP<4>")
	)
	(segment
		(start 61.132212 -239.150906)
		(end 61.455046 -239.47374)
		(width 0.16002)
		(layer "In2.Cu")
		(net "M_C_CPU1_SA_DQS_DP<4>")
	)
	(segment
		(start 68.19138 -244.54993)
		(end 67.741038 -245.000272)
		(width 0.16002)
		(layer "In2.Cu")
		(net "M_C_CPU1_SA_DQS_DP<4>")
	)
	(segment
		(start 66.1162 -243.877846)
		(end 66.1162 -244.154706)
		(width 0.16002)
		(layer "In2.Cu")
		(net "M_C_CPU1_SA_DQS_DP<4>")
	)
	(segment
		(start 60.85713 -238.324136)
		(end 61.132212 -238.599218)
		(width 0.16002)
		(layer "In2.Cu")
		(net "M_C_CPU1_SA_DQS_DP<4>")
	)
	(segment
		(start 76.03871 -246.398796)
		(end 76.273406 -246.398796)
		(width 0.09525)
		(layer "In2.Cu")
		(net "M_C_CPU1_SA_DQS_DP<4>")
	)
	(segment
		(start 69.415406 -245.7577)
		(end 75.122278 -245.7577)
		(width 0.16002)
		(layer "In2.Cu")
		(net "M_C_CPU1_SA_DQS_DP<4>")
	)
	(segment
		(start 78.671166 -246.417338)
		(end 78.691994 -246.42953)
		(width 0.09525)
		(layer "In2.Cu")
		(net "M_C_CPU1_SA_DQS_DP<4>")
	)
	(segment
		(start 66.63944 -243.354606)
		(end 66.1162 -243.877846)
		(width 0.16002)
		(layer "In2.Cu")
		(net "M_C_CPU1_SA_DQS_DP<4>")
	)
	(segment
		(start 49.444148 -238.575088)
		(end 50.297588 -237.721648)
		(width 0.16002)
		(layer "In2.Cu")
		(net "M_C_CPU1_SA_DQS_DP<4>")
	)
	(arc
		(start 78.700376 -246.434356)
		(mid 78.885154 -246.480149)
		(end 79.068676 -246.42953)
		(width 0.09525)
		(layer "In2.Cu")
		(net "M_C_CPU1_SA_DQS_DP<4>")
	)
	(arc
		(start 93.73235 -246.42953)
		(mid 93.888948 -246.478819)
		(end 94.051628 -246.456708)
		(width 0.09525)
		(layer "In2.Cu")
		(net "M_C_CPU1_SA_DQS_DP<4>")
	)
	(arc
		(start 82.829654 -246.42953)
		(mid 83.111086 -246.353775)
		(end 83.392518 -246.42953)
		(width 0.09525)
		(layer "In2.Cu")
		(net "M_C_CPU1_SA_DQS_DP<4>")
	)
	(arc
		(start 88.469724 -246.42953)
		(mid 88.751156 -246.353775)
		(end 89.032588 -246.42953)
		(width 0.09525)
		(layer "In2.Cu")
		(net "M_C_CPU1_SA_DQS_DP<4>")
	)
	(arc
		(start 86.212426 -246.42953)
		(mid 86.396201 -246.480302)
		(end 86.581234 -246.434356)
		(width 0.09525)
		(layer "In2.Cu")
		(net "M_C_CPU1_SA_DQS_DP<4>")
	)
	(arc
		(start 78.12913 -246.42953)
		(mid 78.398563 -246.353659)
		(end 78.671166 -246.417338)
		(width 0.09525)
		(layer "In2.Cu")
		(net "M_C_CPU1_SA_DQS_DP<4>")
	)
	(arc
		(start 85.649562 -246.42953)
		(mid 85.930994 -246.353775)
		(end 86.212426 -246.42953)
		(width 0.09525)
		(layer "In2.Cu")
		(net "M_C_CPU1_SA_DQS_DP<4>")
	)
	(arc
		(start 91.289632 -246.42953)
		(mid 91.571064 -246.353775)
		(end 91.852496 -246.42953)
		(width 0.09525)
		(layer "In2.Cu")
		(net "M_C_CPU1_SA_DQS_DP<4>")
	)
	(arc
		(start 87.52967 -246.42953)
		(mid 87.811102 -246.353775)
		(end 88.092534 -246.42953)
		(width 0.09525)
		(layer "In2.Cu")
		(net "M_C_CPU1_SA_DQS_DP<4>")
	)
	(arc
		(start 91.860878 -246.434356)
		(mid 92.04591 -246.48027)
		(end 92.229686 -246.42953)
		(width 0.09525)
		(layer "In2.Cu")
		(net "M_C_CPU1_SA_DQS_DP<4>")
	)
	(arc
		(start 83.769708 -246.42953)
		(mid 84.05114 -246.353775)
		(end 84.332572 -246.42953)
		(width 0.09525)
		(layer "In2.Cu")
		(net "M_C_CPU1_SA_DQS_DP<4>")
	)
	(arc
		(start 80.57261 -246.42953)
		(mid 80.761078 -246.480207)
		(end 80.949546 -246.42953)
		(width 0.09525)
		(layer "In2.Cu")
		(net "M_C_CPU1_SA_DQS_DP<4>")
	)
	(arc
		(start 87.160862 -246.434356)
		(mid 87.345894 -246.48027)
		(end 87.52967 -246.42953)
		(width 0.09525)
		(layer "In2.Cu")
		(net "M_C_CPU1_SA_DQS_DP<4>")
	)
	(arc
		(start 93.169486 -246.42953)
		(mid 93.450918 -246.353775)
		(end 93.73235 -246.42953)
		(width 0.09525)
		(layer "In2.Cu")
		(net "M_C_CPU1_SA_DQS_DP<4>")
	)
	(arc
		(start 90.349578 -246.42953)
		(mid 90.63101 -246.353775)
		(end 90.912442 -246.42953)
		(width 0.09525)
		(layer "In2.Cu")
		(net "M_C_CPU1_SA_DQS_DP<4>")
	)
	(arc
		(start 84.709508 -246.42953)
		(mid 84.99094 -246.353775)
		(end 85.272372 -246.42953)
		(width 0.09525)
		(layer "In2.Cu")
		(net "M_C_CPU1_SA_DQS_DP<4>")
	)
	(arc
		(start 84.332572 -246.42953)
		(mid 84.52104 -246.480207)
		(end 84.709508 -246.42953)
		(width 0.09525)
		(layer "In2.Cu")
		(net "M_C_CPU1_SA_DQS_DP<4>")
	)
	(arc
		(start 81.8896 -246.42953)
		(mid 82.171032 -246.353775)
		(end 82.452464 -246.42953)
		(width 0.09525)
		(layer "In2.Cu")
		(net "M_C_CPU1_SA_DQS_DP<4>")
	)
	(arc
		(start 79.083408 -246.420894)
		(mid 79.358867 -246.353509)
		(end 79.632048 -246.42953)
		(width 0.09525)
		(layer "In2.Cu")
		(net "M_C_CPU1_SA_DQS_DP<4>")
	)
	(arc
		(start 79.632048 -246.42953)
		(mid 79.816077 -246.480429)
		(end 80.001364 -246.434356)
		(width 0.09525)
		(layer "In2.Cu")
		(net "M_C_CPU1_SA_DQS_DP<4>")
	)
	(arc
		(start 80.009746 -246.42953)
		(mid 80.291178 -246.353775)
		(end 80.57261 -246.42953)
		(width 0.09525)
		(layer "In2.Cu")
		(net "M_C_CPU1_SA_DQS_DP<4>")
	)
	(arc
		(start 89.409524 -246.42953)
		(mid 89.690956 -246.353775)
		(end 89.972388 -246.42953)
		(width 0.09525)
		(layer "In2.Cu")
		(net "M_C_CPU1_SA_DQS_DP<4>")
	)
	(arc
		(start 82.460846 -246.434356)
		(mid 82.645878 -246.48027)
		(end 82.829654 -246.42953)
		(width 0.09525)
		(layer "In2.Cu")
		(net "M_C_CPU1_SA_DQS_DP<4>")
	)
	(arc
		(start 89.032588 -246.42953)
		(mid 89.221056 -246.480207)
		(end 89.409524 -246.42953)
		(width 0.09525)
		(layer "In2.Cu")
		(net "M_C_CPU1_SA_DQS_DP<4>")
	)
	(arc
		(start 85.272372 -246.42953)
		(mid 85.456147 -246.480302)
		(end 85.64118 -246.434356)
		(width 0.09525)
		(layer "In2.Cu")
		(net "M_C_CPU1_SA_DQS_DP<4>")
	)
	(arc
		(start 81.51241 -246.42953)
		(mid 81.696185 -246.480302)
		(end 81.881218 -246.434356)
		(width 0.09525)
		(layer "In2.Cu")
		(net "M_C_CPU1_SA_DQS_DP<4>")
	)
	(arc
		(start 90.920824 -246.434356)
		(mid 91.105856 -246.48027)
		(end 91.289632 -246.42953)
		(width 0.09525)
		(layer "In2.Cu")
		(net "M_C_CPU1_SA_DQS_DP<4>")
	)
	(arc
		(start 92.79255 -246.42953)
		(mid 92.981018 -246.480207)
		(end 93.169486 -246.42953)
		(width 0.09525)
		(layer "In2.Cu")
		(net "M_C_CPU1_SA_DQS_DP<4>")
	)
	(arc
		(start 83.4009 -246.434356)
		(mid 83.585932 -246.48027)
		(end 83.769708 -246.42953)
		(width 0.09525)
		(layer "In2.Cu")
		(net "M_C_CPU1_SA_DQS_DP<4>")
	)
	(arc
		(start 89.972388 -246.42953)
		(mid 90.156163 -246.480302)
		(end 90.341196 -246.434356)
		(width 0.09525)
		(layer "In2.Cu")
		(net "M_C_CPU1_SA_DQS_DP<4>")
	)
	(arc
		(start 92.229686 -246.42953)
		(mid 92.511118 -246.353775)
		(end 92.79255 -246.42953)
		(width 0.09525)
		(layer "In2.Cu")
		(net "M_C_CPU1_SA_DQS_DP<4>")
	)
	(arc
		(start 88.100916 -246.434356)
		(mid 88.285948 -246.48027)
		(end 88.469724 -246.42953)
		(width 0.09525)
		(layer "In2.Cu")
		(net "M_C_CPU1_SA_DQS_DP<4>")
	)
	(arc
		(start 77.9399 -246.481346)
		(mid 78.037934 -246.467945)
		(end 78.12913 -246.42953)
		(width 0.09525)
		(layer "In2.Cu")
		(net "M_C_CPU1_SA_DQS_DP<4>")
	)
	(arc
		(start 80.949546 -246.42953)
		(mid 81.230978 -246.353775)
		(end 81.51241 -246.42953)
		(width 0.09525)
		(layer "In2.Cu")
		(net "M_C_CPU1_SA_DQS_DP<4>")
	)
	(arc
		(start 86.589616 -246.42953)
		(mid 86.871048 -246.353775)
		(end 87.15248 -246.42953)
		(width 0.09525)
		(layer "In2.Cu")
		(net "M_C_CPU1_SA_DQS_DP<4>")
	)
	(segment
		(start 94.387924 -241.510312)
		(end 93.921072 -241.244374)
		(width 0.12954)
		(layer "F.Cu")
		(net "M_C_CPU1_SA_DQS_DP<3>")
	)
	(segment
		(start 50.297588 -228.371654)
		(end 50.67554 -228.371654)
		(width 0.16002)
		(layer "In2.Cu")
		(net "M_C_CPU1_SA_DQS_DP<3>")
	)
	(segment
		(start 94.051628 -241.596672)
		(end 94.074996 -241.509804)
		(width 0.09525)
		(layer "In2.Cu")
		(net "M_C_CPU1_SA_DQS_DP<3>")
	)
	(segment
		(start 60.4393 -228.094794)
		(end 61.440822 -229.096316)
		(width 0.16002)
		(layer "In2.Cu")
		(net "M_C_CPU1_SA_DQS_DP<3>")
	)
	(segment
		(start 62.413134 -228.350318)
		(end 62.940438 -228.350318)
		(width 0.16002)
		(layer "In2.Cu")
		(net "M_C_CPU1_SA_DQS_DP<3>")
	)
	(segment
		(start 87.15248 -241.569494)
		(end 87.160862 -241.57432)
		(width 0.09525)
		(layer "In2.Cu")
		(net "M_C_CPU1_SA_DQS_DP<3>")
	)
	(segment
		(start 64.235838 -229.802182)
		(end 64.609726 -230.17607)
		(width 0.16002)
		(layer "In2.Cu")
		(net "M_C_CPU1_SA_DQS_DP<3>")
	)
	(segment
		(start 64.609726 -230.17607)
		(end 64.609472 -230.702866)
		(width 0.16002)
		(layer "In2.Cu")
		(net "M_C_CPU1_SA_DQS_DP<3>")
	)
	(segment
		(start 63.708534 -229.801928)
		(end 64.235838 -229.802182)
		(width 0.16002)
		(layer "In2.Cu")
		(net "M_C_CPU1_SA_DQS_DP<3>")
	)
	(segment
		(start 63.026544 -230.483918)
		(end 63.708534 -229.801928)
		(width 0.16002)
		(layer "In2.Cu")
		(net "M_C_CPU1_SA_DQS_DP<3>")
	)
	(segment
		(start 46.189138 -229.059232)
		(end 46.669198 -229.059232)
		(width 0.16002)
		(layer "In2.Cu")
		(net "M_C_CPU1_SA_DQS_DP<3>")
	)
	(segment
		(start 50.986944 -228.06025)
		(end 52.89042 -228.06025)
		(width 0.16002)
		(layer "In2.Cu")
		(net "M_C_CPU1_SA_DQS_DP<3>")
	)
	(segment
		(start 63.927482 -231.661716)
		(end 72.324722 -240.058956)
		(width 0.16002)
		(layer "In2.Cu")
		(net "M_C_CPU1_SA_DQS_DP<3>")
	)
	(segment
		(start 45.475398 -229.059232)
		(end 45.592238 -228.942392)
		(width 0.16002)
		(layer "In2.Cu")
		(net "M_C_CPU1_SA_DQS_DP<3>")
	)
	(segment
		(start 50.67554 -228.371654)
		(end 50.986944 -228.06025)
		(width 0.16002)
		(layer "In2.Cu")
		(net "M_C_CPU1_SA_DQS_DP<3>")
	)
	(segment
		(start 86.581234 -241.57432)
		(end 86.589616 -241.569494)
		(width 0.09525)
		(layer "In2.Cu")
		(net "M_C_CPU1_SA_DQS_DP<3>")
	)
	(segment
		(start 90.341196 -241.57432)
		(end 90.349578 -241.569494)
		(width 0.09525)
		(layer "In2.Cu")
		(net "M_C_CPU1_SA_DQS_DP<3>")
	)
	(segment
		(start 76.04633 -240.058956)
		(end 76.069952 -240.058956)
		(width 0.09525)
		(layer "In2.Cu")
		(net "M_C_CPU1_SA_DQS_DP<3>")
	)
	(segment
		(start 91.852496 -241.569494)
		(end 91.860878 -241.57432)
		(width 0.09525)
		(layer "In2.Cu")
		(net "M_C_CPU1_SA_DQS_DP<3>")
	)
	(segment
		(start 76.647802 -240.290604)
		(end 77.053948 -240.290604)
		(width 0.09525)
		(layer "In2.Cu")
		(net "M_C_CPU1_SA_DQS_DP<3>")
	)
	(segment
		(start 76.475336 -240.118138)
		(end 76.647802 -240.290604)
		(width 0.09525)
		(layer "In2.Cu")
		(net "M_C_CPU1_SA_DQS_DP<3>")
	)
	(segment
		(start 61.440822 -229.096316)
		(end 61.667136 -229.096316)
		(width 0.16002)
		(layer "In2.Cu")
		(net "M_C_CPU1_SA_DQS_DP<3>")
	)
	(segment
		(start 57.661048 -228.445314)
		(end 58.138568 -228.445314)
		(width 0.16002)
		(layer "In2.Cu")
		(net "M_C_CPU1_SA_DQS_DP<3>")
	)
	(segment
		(start 44.340018 -228.78542)
		(end 44.61383 -229.059232)
		(width 0.16002)
		(layer "In2.Cu")
		(net "M_C_CPU1_SA_DQS_DP<3>")
	)
	(segment
		(start 77.053948 -240.290604)
		(end 78.257146 -241.493802)
		(width 0.09525)
		(layer "In2.Cu")
		(net "M_C_CPU1_SA_DQS_DP<3>")
	)
	(segment
		(start 72.324722 -240.058956)
		(end 76.04633 -240.058956)
		(width 0.16002)
		(layer "In2.Cu")
		(net "M_C_CPU1_SA_DQS_DP<3>")
	)
	(segment
		(start 83.392518 -241.569494)
		(end 83.4009 -241.57432)
		(width 0.09525)
		(layer "In2.Cu")
		(net "M_C_CPU1_SA_DQS_DP<3>")
	)
	(segment
		(start 46.669198 -229.059232)
		(end 46.818296 -228.910134)
		(width 0.16002)
		(layer "In2.Cu")
		(net "M_C_CPU1_SA_DQS_DP<3>")
	)
	(segment
		(start 64.609472 -230.702866)
		(end 63.927482 -231.384856)
		(width 0.16002)
		(layer "In2.Cu")
		(net "M_C_CPU1_SA_DQS_DP<3>")
	)
	(segment
		(start 63.927482 -231.384856)
		(end 63.927482 -231.661716)
		(width 0.16002)
		(layer "In2.Cu")
		(net "M_C_CPU1_SA_DQS_DP<3>")
	)
	(segment
		(start 56.59374 -229.286054)
		(end 56.820308 -229.286054)
		(width 0.16002)
		(layer "In2.Cu")
		(net "M_C_CPU1_SA_DQS_DP<3>")
	)
	(segment
		(start 48.678592 -228.910134)
		(end 49.105566 -229.337108)
		(width 0.16002)
		(layer "In2.Cu")
		(net "M_C_CPU1_SA_DQS_DP<3>")
	)
	(segment
		(start 46.072298 -228.942392)
		(end 46.189138 -229.059232)
		(width 0.16002)
		(layer "In2.Cu")
		(net "M_C_CPU1_SA_DQS_DP<3>")
	)
	(segment
		(start 45.592238 -228.942392)
		(end 46.072298 -228.942392)
		(width 0.16002)
		(layer "In2.Cu")
		(net "M_C_CPU1_SA_DQS_DP<3>")
	)
	(segment
		(start 76.069952 -240.058956)
		(end 76.129134 -240.118138)
		(width 0.09525)
		(layer "In2.Cu")
		(net "M_C_CPU1_SA_DQS_DP<3>")
	)
	(segment
		(start 58.489088 -228.094794)
		(end 60.4393 -228.094794)
		(width 0.16002)
		(layer "In2.Cu")
		(net "M_C_CPU1_SA_DQS_DP<3>")
	)
	(segment
		(start 94.074996 -241.509804)
		(end 93.921072 -241.244374)
		(width 0.09525)
		(layer "In2.Cu")
		(net "M_C_CPU1_SA_DQS_DP<3>")
	)
	(segment
		(start 49.105566 -229.337108)
		(end 49.332134 -229.337108)
		(width 0.16002)
		(layer "In2.Cu")
		(net "M_C_CPU1_SA_DQS_DP<3>")
	)
	(segment
		(start 56.261 -228.953314)
		(end 56.59374 -229.286054)
		(width 0.16002)
		(layer "In2.Cu")
		(net "M_C_CPU1_SA_DQS_DP<3>")
	)
	(segment
		(start 78.257146 -241.493802)
		(end 78.41107 -241.493802)
		(width 0.09525)
		(layer "In2.Cu")
		(net "M_C_CPU1_SA_DQS_DP<3>")
	)
	(segment
		(start 56.820308 -229.286054)
		(end 57.661048 -228.445314)
		(width 0.16002)
		(layer "In2.Cu")
		(net "M_C_CPU1_SA_DQS_DP<3>")
	)
	(segment
		(start 53.783484 -228.953314)
		(end 56.261 -228.953314)
		(width 0.16002)
		(layer "In2.Cu")
		(net "M_C_CPU1_SA_DQS_DP<3>")
	)
	(segment
		(start 82.452464 -241.569494)
		(end 82.460846 -241.57432)
		(width 0.09525)
		(layer "In2.Cu")
		(net "M_C_CPU1_SA_DQS_DP<3>")
	)
	(segment
		(start 44.61383 -229.059232)
		(end 45.475398 -229.059232)
		(width 0.16002)
		(layer "In2.Cu")
		(net "M_C_CPU1_SA_DQS_DP<3>")
	)
	(segment
		(start 62.55385 -230.288084)
		(end 62.749684 -230.483918)
		(width 0.16002)
		(layer "In2.Cu")
		(net "M_C_CPU1_SA_DQS_DP<3>")
	)
	(segment
		(start 62.940438 -228.350318)
		(end 63.314326 -228.724206)
		(width 0.16002)
		(layer "In2.Cu")
		(net "M_C_CPU1_SA_DQS_DP<3>")
	)
	(segment
		(start 62.749684 -230.483918)
		(end 63.026544 -230.483918)
		(width 0.16002)
		(layer "In2.Cu")
		(net "M_C_CPU1_SA_DQS_DP<3>")
	)
	(segment
		(start 88.092534 -241.569494)
		(end 88.100916 -241.57432)
		(width 0.09525)
		(layer "In2.Cu")
		(net "M_C_CPU1_SA_DQS_DP<3>")
	)
	(segment
		(start 63.314072 -229.251002)
		(end 62.55385 -230.011224)
		(width 0.16002)
		(layer "In2.Cu")
		(net "M_C_CPU1_SA_DQS_DP<3>")
	)
	(segment
		(start 62.55385 -230.011224)
		(end 62.55385 -230.288084)
		(width 0.16002)
		(layer "In2.Cu")
		(net "M_C_CPU1_SA_DQS_DP<3>")
	)
	(segment
		(start 52.89042 -228.06025)
		(end 53.783484 -228.953314)
		(width 0.16002)
		(layer "In2.Cu")
		(net "M_C_CPU1_SA_DQS_DP<3>")
	)
	(segment
		(start 76.129134 -240.118138)
		(end 76.475336 -240.118138)
		(width 0.09525)
		(layer "In2.Cu")
		(net "M_C_CPU1_SA_DQS_DP<3>")
	)
	(segment
		(start 78.692502 -241.569494)
		(end 78.700884 -241.57432)
		(width 0.09525)
		(layer "In2.Cu")
		(net "M_C_CPU1_SA_DQS_DP<3>")
	)
	(segment
		(start 58.138568 -228.445314)
		(end 58.489088 -228.094794)
		(width 0.16002)
		(layer "In2.Cu")
		(net "M_C_CPU1_SA_DQS_DP<3>")
	)
	(segment
		(start 85.64118 -241.57432)
		(end 85.649562 -241.569494)
		(width 0.09525)
		(layer "In2.Cu")
		(net "M_C_CPU1_SA_DQS_DP<3>")
	)
	(segment
		(start 61.667136 -229.096316)
		(end 62.413134 -228.350318)
		(width 0.16002)
		(layer "In2.Cu")
		(net "M_C_CPU1_SA_DQS_DP<3>")
	)
	(segment
		(start 79.632556 -241.569494)
		(end 79.640938 -241.57432)
		(width 0.09525)
		(layer "In2.Cu")
		(net "M_C_CPU1_SA_DQS_DP<3>")
	)
	(segment
		(start 63.314326 -228.724206)
		(end 63.314072 -229.251002)
		(width 0.16002)
		(layer "In2.Cu")
		(net "M_C_CPU1_SA_DQS_DP<3>")
	)
	(segment
		(start 46.818296 -228.910134)
		(end 48.678592 -228.910134)
		(width 0.16002)
		(layer "In2.Cu")
		(net "M_C_CPU1_SA_DQS_DP<3>")
	)
	(segment
		(start 49.332134 -229.337108)
		(end 50.297588 -228.371654)
		(width 0.16002)
		(layer "In2.Cu")
		(net "M_C_CPU1_SA_DQS_DP<3>")
	)
	(segment
		(start 81.881218 -241.57432)
		(end 81.8896 -241.569494)
		(width 0.09525)
		(layer "In2.Cu")
		(net "M_C_CPU1_SA_DQS_DP<3>")
	)
	(segment
		(start 90.912442 -241.569494)
		(end 90.920824 -241.57432)
		(width 0.09525)
		(layer "In2.Cu")
		(net "M_C_CPU1_SA_DQS_DP<3>")
	)
	(arc
		(start 83.4009 -241.57432)
		(mid 83.585932 -241.620234)
		(end 83.769708 -241.569494)
		(width 0.09525)
		(layer "In2.Cu")
		(net "M_C_CPU1_SA_DQS_DP<3>")
	)
	(arc
		(start 78.41107 -241.493802)
		(mid 78.556778 -241.51307)
		(end 78.692502 -241.569494)
		(width 0.09525)
		(layer "In2.Cu")
		(net "M_C_CPU1_SA_DQS_DP<3>")
	)
	(arc
		(start 91.860878 -241.57432)
		(mid 92.04591 -241.620234)
		(end 92.229686 -241.569494)
		(width 0.09525)
		(layer "In2.Cu")
		(net "M_C_CPU1_SA_DQS_DP<3>")
	)
	(arc
		(start 90.349578 -241.569494)
		(mid 90.63101 -241.493739)
		(end 90.912442 -241.569494)
		(width 0.09525)
		(layer "In2.Cu")
		(net "M_C_CPU1_SA_DQS_DP<3>")
	)
	(arc
		(start 91.289632 -241.569494)
		(mid 91.571064 -241.493739)
		(end 91.852496 -241.569494)
		(width 0.09525)
		(layer "In2.Cu")
		(net "M_C_CPU1_SA_DQS_DP<3>")
	)
	(arc
		(start 81.8896 -241.569494)
		(mid 82.171032 -241.493739)
		(end 82.452464 -241.569494)
		(width 0.09525)
		(layer "In2.Cu")
		(net "M_C_CPU1_SA_DQS_DP<3>")
	)
	(arc
		(start 89.032588 -241.569494)
		(mid 89.221056 -241.620171)
		(end 89.409524 -241.569494)
		(width 0.09525)
		(layer "In2.Cu")
		(net "M_C_CPU1_SA_DQS_DP<3>")
	)
	(arc
		(start 87.52967 -241.569494)
		(mid 87.811102 -241.493739)
		(end 88.092534 -241.569494)
		(width 0.09525)
		(layer "In2.Cu")
		(net "M_C_CPU1_SA_DQS_DP<3>")
	)
	(arc
		(start 86.212426 -241.569494)
		(mid 86.396201 -241.620266)
		(end 86.581234 -241.57432)
		(width 0.09525)
		(layer "In2.Cu")
		(net "M_C_CPU1_SA_DQS_DP<3>")
	)
	(arc
		(start 92.79255 -241.569494)
		(mid 92.981018 -241.620171)
		(end 93.169486 -241.569494)
		(width 0.09525)
		(layer "In2.Cu")
		(net "M_C_CPU1_SA_DQS_DP<3>")
	)
	(arc
		(start 82.829654 -241.569494)
		(mid 83.111086 -241.493739)
		(end 83.392518 -241.569494)
		(width 0.09525)
		(layer "In2.Cu")
		(net "M_C_CPU1_SA_DQS_DP<3>")
	)
	(arc
		(start 82.460846 -241.57432)
		(mid 82.645878 -241.620234)
		(end 82.829654 -241.569494)
		(width 0.09525)
		(layer "In2.Cu")
		(net "M_C_CPU1_SA_DQS_DP<3>")
	)
	(arc
		(start 85.649562 -241.569494)
		(mid 85.930994 -241.493739)
		(end 86.212426 -241.569494)
		(width 0.09525)
		(layer "In2.Cu")
		(net "M_C_CPU1_SA_DQS_DP<3>")
	)
	(arc
		(start 88.469724 -241.569494)
		(mid 88.751156 -241.493739)
		(end 89.032588 -241.569494)
		(width 0.09525)
		(layer "In2.Cu")
		(net "M_C_CPU1_SA_DQS_DP<3>")
	)
	(arc
		(start 84.709508 -241.569494)
		(mid 84.99094 -241.493739)
		(end 85.272372 -241.569494)
		(width 0.09525)
		(layer "In2.Cu")
		(net "M_C_CPU1_SA_DQS_DP<3>")
	)
	(arc
		(start 92.229686 -241.569494)
		(mid 92.511118 -241.493739)
		(end 92.79255 -241.569494)
		(width 0.09525)
		(layer "In2.Cu")
		(net "M_C_CPU1_SA_DQS_DP<3>")
	)
	(arc
		(start 86.589616 -241.569494)
		(mid 86.871048 -241.493739)
		(end 87.15248 -241.569494)
		(width 0.09525)
		(layer "In2.Cu")
		(net "M_C_CPU1_SA_DQS_DP<3>")
	)
	(arc
		(start 84.332572 -241.569494)
		(mid 84.52104 -241.620171)
		(end 84.709508 -241.569494)
		(width 0.09525)
		(layer "In2.Cu")
		(net "M_C_CPU1_SA_DQS_DP<3>")
	)
	(arc
		(start 93.169486 -241.569494)
		(mid 93.450918 -241.493739)
		(end 93.73235 -241.569494)
		(width 0.09525)
		(layer "In2.Cu")
		(net "M_C_CPU1_SA_DQS_DP<3>")
	)
	(arc
		(start 83.769708 -241.569494)
		(mid 84.05114 -241.493739)
		(end 84.332572 -241.569494)
		(width 0.09525)
		(layer "In2.Cu")
		(net "M_C_CPU1_SA_DQS_DP<3>")
	)
	(arc
		(start 80.949546 -241.569494)
		(mid 81.230978 -241.493739)
		(end 81.51241 -241.569494)
		(width 0.09525)
		(layer "In2.Cu")
		(net "M_C_CPU1_SA_DQS_DP<3>")
	)
	(arc
		(start 88.100916 -241.57432)
		(mid 88.285948 -241.620234)
		(end 88.469724 -241.569494)
		(width 0.09525)
		(layer "In2.Cu")
		(net "M_C_CPU1_SA_DQS_DP<3>")
	)
	(arc
		(start 81.51241 -241.569494)
		(mid 81.696185 -241.620266)
		(end 81.881218 -241.57432)
		(width 0.09525)
		(layer "In2.Cu")
		(net "M_C_CPU1_SA_DQS_DP<3>")
	)
	(arc
		(start 93.73235 -241.569494)
		(mid 93.888948 -241.618783)
		(end 94.051628 -241.596672)
		(width 0.09525)
		(layer "In2.Cu")
		(net "M_C_CPU1_SA_DQS_DP<3>")
	)
	(arc
		(start 87.160862 -241.57432)
		(mid 87.345894 -241.620234)
		(end 87.52967 -241.569494)
		(width 0.09525)
		(layer "In2.Cu")
		(net "M_C_CPU1_SA_DQS_DP<3>")
	)
	(arc
		(start 78.700884 -241.57432)
		(mid 78.885916 -241.620234)
		(end 79.069692 -241.569494)
		(width 0.09525)
		(layer "In2.Cu")
		(net "M_C_CPU1_SA_DQS_DP<3>")
	)
	(arc
		(start 80.57261 -241.569494)
		(mid 80.761078 -241.620171)
		(end 80.949546 -241.569494)
		(width 0.09525)
		(layer "In2.Cu")
		(net "M_C_CPU1_SA_DQS_DP<3>")
	)
	(arc
		(start 90.920824 -241.57432)
		(mid 91.105856 -241.620234)
		(end 91.289632 -241.569494)
		(width 0.09525)
		(layer "In2.Cu")
		(net "M_C_CPU1_SA_DQS_DP<3>")
	)
	(arc
		(start 79.069692 -241.569494)
		(mid 79.351124 -241.493739)
		(end 79.632556 -241.569494)
		(width 0.09525)
		(layer "In2.Cu")
		(net "M_C_CPU1_SA_DQS_DP<3>")
	)
	(arc
		(start 80.009746 -241.569494)
		(mid 80.291178 -241.493739)
		(end 80.57261 -241.569494)
		(width 0.09525)
		(layer "In2.Cu")
		(net "M_C_CPU1_SA_DQS_DP<3>")
	)
	(arc
		(start 79.640938 -241.57432)
		(mid 79.82597 -241.620234)
		(end 80.009746 -241.569494)
		(width 0.09525)
		(layer "In2.Cu")
		(net "M_C_CPU1_SA_DQS_DP<3>")
	)
	(arc
		(start 89.409524 -241.569494)
		(mid 89.690956 -241.493739)
		(end 89.972388 -241.569494)
		(width 0.09525)
		(layer "In2.Cu")
		(net "M_C_CPU1_SA_DQS_DP<3>")
	)
	(arc
		(start 85.272372 -241.569494)
		(mid 85.456147 -241.620266)
		(end 85.64118 -241.57432)
		(width 0.09525)
		(layer "In2.Cu")
		(net "M_C_CPU1_SA_DQS_DP<3>")
	)
	(arc
		(start 89.972388 -241.569494)
		(mid 90.156163 -241.620266)
		(end 90.341196 -241.57432)
		(width 0.09525)
		(layer "In2.Cu")
		(net "M_C_CPU1_SA_DQS_DP<3>")
	)
	(segment
		(start 94.387924 -236.650276)
		(end 93.921072 -236.384338)
		(width 0.12954)
		(layer "F.Cu")
		(net "M_C_CPU1_SA_DQS_DP<2>")
	)
	(segment
		(start 90.912442 -236.709458)
		(end 90.920824 -236.714284)
		(width 0.09525)
		(layer "In2.Cu")
		(net "M_C_CPU1_SA_DQS_DP<2>")
	)
	(segment
		(start 83.392518 -236.709458)
		(end 83.4009 -236.714284)
		(width 0.09525)
		(layer "In2.Cu")
		(net "M_C_CPU1_SA_DQS_DP<2>")
	)
	(segment
		(start 94.074996 -236.649768)
		(end 93.921072 -236.384338)
		(width 0.09525)
		(layer "In2.Cu")
		(net "M_C_CPU1_SA_DQS_DP<2>")
	)
	(segment
		(start 91.852496 -236.709458)
		(end 91.860878 -236.714284)
		(width 0.09525)
		(layer "In2.Cu")
		(net "M_C_CPU1_SA_DQS_DP<2>")
	)
	(segment
		(start 64.124586 -220.119702)
		(end 64.49822 -220.493336)
		(width 0.16002)
		(layer "In2.Cu")
		(net "M_C_CPU1_SA_DQS_DP<2>")
	)
	(segment
		(start 78.315566 -236.031024)
		(end 78.935326 -236.031024)
		(width 0.09525)
		(layer "In2.Cu")
		(net "M_C_CPU1_SA_DQS_DP<2>")
	)
	(segment
		(start 53.78958 -219.60332)
		(end 56.235092 -219.60332)
		(width 0.16002)
		(layer "In2.Cu")
		(net "M_C_CPU1_SA_DQS_DP<2>")
	)
	(segment
		(start 80.001364 -236.714284)
		(end 80.009746 -236.709458)
		(width 0.09525)
		(layer "In2.Cu")
		(net "M_C_CPU1_SA_DQS_DP<2>")
	)
	(segment
		(start 78.935326 -236.031024)
		(end 79.554832 -236.65053)
		(width 0.09525)
		(layer "In2.Cu")
		(net "M_C_CPU1_SA_DQS_DP<2>")
	)
	(segment
		(start 74.284078 -233.654854)
		(end 75.010518 -234.381294)
		(width 0.16002)
		(layer "In2.Cu")
		(net "M_C_CPU1_SA_DQS_DP<2>")
	)
	(segment
		(start 75.955906 -234.381294)
		(end 75.979528 -234.381294)
		(width 0.09525)
		(layer "In2.Cu")
		(net "M_C_CPU1_SA_DQS_DP<2>")
	)
	(segment
		(start 50.297588 -219.02166)
		(end 50.703988 -219.02166)
		(width 0.16002)
		(layer "In2.Cu")
		(net "M_C_CPU1_SA_DQS_DP<2>")
	)
	(segment
		(start 46.171358 -219.709238)
		(end 46.651418 -219.709238)
		(width 0.16002)
		(layer "In2.Cu")
		(net "M_C_CPU1_SA_DQS_DP<2>")
	)
	(segment
		(start 71.081138 -229.811834)
		(end 71.536814 -230.26751)
		(width 0.16002)
		(layer "In2.Cu")
		(net "M_C_CPU1_SA_DQS_DP<2>")
	)
	(segment
		(start 71.536814 -230.90759)
		(end 71.81469 -231.185466)
		(width 0.16002)
		(layer "In2.Cu")
		(net "M_C_CPU1_SA_DQS_DP<2>")
	)
	(segment
		(start 63.124588 -219.647008)
		(end 62.84468 -219.926916)
		(width 0.16002)
		(layer "In2.Cu")
		(net "M_C_CPU1_SA_DQS_DP<2>")
	)
	(segment
		(start 77.44714 -234.828334)
		(end 77.44714 -235.162598)
		(width 0.09525)
		(layer "In2.Cu")
		(net "M_C_CPU1_SA_DQS_DP<2>")
	)
	(segment
		(start 61.895482 -218.7448)
		(end 62.749684 -218.7448)
		(width 0.16002)
		(layer "In2.Cu")
		(net "M_C_CPU1_SA_DQS_DP<2>")
	)
	(segment
		(start 94.051628 -236.736636)
		(end 94.074996 -236.649768)
		(width 0.09525)
		(layer "In2.Cu")
		(net "M_C_CPU1_SA_DQS_DP<2>")
	)
	(segment
		(start 61.326776 -219.773246)
		(end 61.52261 -219.577412)
		(width 0.16002)
		(layer "In2.Cu")
		(net "M_C_CPU1_SA_DQS_DP<2>")
	)
	(segment
		(start 73.188322 -232.559098)
		(end 73.828402 -232.559098)
		(width 0.16002)
		(layer "In2.Cu")
		(net "M_C_CPU1_SA_DQS_DP<2>")
	)
	(segment
		(start 44.61383 -219.709238)
		(end 45.457618 -219.709238)
		(width 0.16002)
		(layer "In2.Cu")
		(net "M_C_CPU1_SA_DQS_DP<2>")
	)
	(segment
		(start 63.124588 -219.119704)
		(end 63.124588 -219.647008)
		(width 0.16002)
		(layer "In2.Cu")
		(net "M_C_CPU1_SA_DQS_DP<2>")
	)
	(segment
		(start 64.49822 -220.493336)
		(end 64.49822 -221.02064)
		(width 0.16002)
		(layer "In2.Cu")
		(net "M_C_CPU1_SA_DQS_DP<2>")
	)
	(segment
		(start 64.49822 -221.02064)
		(end 64.218312 -221.300548)
		(width 0.16002)
		(layer "In2.Cu")
		(net "M_C_CPU1_SA_DQS_DP<2>")
	)
	(segment
		(start 73.828402 -232.559098)
		(end 74.284078 -233.014774)
		(width 0.16002)
		(layer "In2.Cu")
		(net "M_C_CPU1_SA_DQS_DP<2>")
	)
	(segment
		(start 90.341196 -236.714284)
		(end 90.349578 -236.709458)
		(width 0.09525)
		(layer "In2.Cu")
		(net "M_C_CPU1_SA_DQS_DP<2>")
	)
	(segment
		(start 63.597282 -220.119702)
		(end 64.124586 -220.119702)
		(width 0.16002)
		(layer "In2.Cu")
		(net "M_C_CPU1_SA_DQS_DP<2>")
	)
	(segment
		(start 82.452464 -236.709458)
		(end 82.460846 -236.714284)
		(width 0.09525)
		(layer "In2.Cu")
		(net "M_C_CPU1_SA_DQS_DP<2>")
	)
	(segment
		(start 56.235092 -219.60332)
		(end 56.524652 -219.89288)
		(width 0.16002)
		(layer "In2.Cu")
		(net "M_C_CPU1_SA_DQS_DP<2>")
	)
	(segment
		(start 49.444148 -219.8751)
		(end 50.297588 -219.02166)
		(width 0.16002)
		(layer "In2.Cu")
		(net "M_C_CPU1_SA_DQS_DP<2>")
	)
	(segment
		(start 58.138568 -219.09532)
		(end 58.489088 -218.7448)
		(width 0.16002)
		(layer "In2.Cu")
		(net "M_C_CPU1_SA_DQS_DP<2>")
	)
	(segment
		(start 50.703988 -219.02166)
		(end 51.015392 -218.710256)
		(width 0.16002)
		(layer "In2.Cu")
		(net "M_C_CPU1_SA_DQS_DP<2>")
	)
	(segment
		(start 62.749684 -218.7448)
		(end 63.124588 -219.119704)
		(width 0.16002)
		(layer "In2.Cu")
		(net "M_C_CPU1_SA_DQS_DP<2>")
	)
	(segment
		(start 63.040514 -220.39961)
		(end 63.317374 -220.39961)
		(width 0.16002)
		(layer "In2.Cu")
		(net "M_C_CPU1_SA_DQS_DP<2>")
	)
	(segment
		(start 70.31609 -229.686866)
		(end 70.441058 -229.811834)
		(width 0.16002)
		(layer "In2.Cu")
		(net "M_C_CPU1_SA_DQS_DP<2>")
	)
	(segment
		(start 46.054518 -219.592398)
		(end 46.171358 -219.709238)
		(width 0.16002)
		(layer "In2.Cu")
		(net "M_C_CPU1_SA_DQS_DP<2>")
	)
	(segment
		(start 58.489088 -218.7448)
		(end 60.481464 -218.7448)
		(width 0.16002)
		(layer "In2.Cu")
		(net "M_C_CPU1_SA_DQS_DP<2>")
	)
	(segment
		(start 61.52261 -219.577412)
		(end 61.52261 -219.117672)
		(width 0.16002)
		(layer "In2.Cu")
		(net "M_C_CPU1_SA_DQS_DP<2>")
	)
	(segment
		(start 60.854336 -219.577412)
		(end 61.05017 -219.773246)
		(width 0.16002)
		(layer "In2.Cu")
		(net "M_C_CPU1_SA_DQS_DP<2>")
	)
	(segment
		(start 52.896516 -218.710256)
		(end 53.78958 -219.60332)
		(width 0.16002)
		(layer "In2.Cu")
		(net "M_C_CPU1_SA_DQS_DP<2>")
	)
	(segment
		(start 45.574458 -219.592398)
		(end 46.054518 -219.592398)
		(width 0.16002)
		(layer "In2.Cu")
		(net "M_C_CPU1_SA_DQS_DP<2>")
	)
	(segment
		(start 70.31609 -227.675186)
		(end 70.31609 -229.686866)
		(width 0.16002)
		(layer "In2.Cu")
		(net "M_C_CPU1_SA_DQS_DP<2>")
	)
	(segment
		(start 71.81469 -231.185466)
		(end 72.45477 -231.185466)
		(width 0.16002)
		(layer "In2.Cu")
		(net "M_C_CPU1_SA_DQS_DP<2>")
	)
	(segment
		(start 63.317374 -220.39961)
		(end 63.597282 -220.119702)
		(width 0.16002)
		(layer "In2.Cu")
		(net "M_C_CPU1_SA_DQS_DP<2>")
	)
	(segment
		(start 71.536814 -230.26751)
		(end 71.536814 -230.90759)
		(width 0.16002)
		(layer "In2.Cu")
		(net "M_C_CPU1_SA_DQS_DP<2>")
	)
	(segment
		(start 64.218312 -221.577408)
		(end 70.31609 -227.675186)
		(width 0.16002)
		(layer "In2.Cu")
		(net "M_C_CPU1_SA_DQS_DP<2>")
	)
	(segment
		(start 87.15248 -236.709458)
		(end 87.160862 -236.714284)
		(width 0.09525)
		(layer "In2.Cu")
		(net "M_C_CPU1_SA_DQS_DP<2>")
	)
	(segment
		(start 57.661048 -219.09532)
		(end 58.138568 -219.09532)
		(width 0.16002)
		(layer "In2.Cu")
		(net "M_C_CPU1_SA_DQS_DP<2>")
	)
	(segment
		(start 51.015392 -218.710256)
		(end 52.896516 -218.710256)
		(width 0.16002)
		(layer "In2.Cu")
		(net "M_C_CPU1_SA_DQS_DP<2>")
	)
	(segment
		(start 60.481464 -218.7448)
		(end 60.854336 -219.117672)
		(width 0.16002)
		(layer "In2.Cu")
		(net "M_C_CPU1_SA_DQS_DP<2>")
	)
	(segment
		(start 70.441058 -229.811834)
		(end 71.081138 -229.811834)
		(width 0.16002)
		(layer "In2.Cu")
		(net "M_C_CPU1_SA_DQS_DP<2>")
	)
	(segment
		(start 56.863488 -219.89288)
		(end 57.661048 -219.09532)
		(width 0.16002)
		(layer "In2.Cu")
		(net "M_C_CPU1_SA_DQS_DP<2>")
	)
	(segment
		(start 72.910446 -232.281222)
		(end 73.188322 -232.559098)
		(width 0.16002)
		(layer "In2.Cu")
		(net "M_C_CPU1_SA_DQS_DP<2>")
	)
	(segment
		(start 62.84468 -219.926916)
		(end 62.84468 -220.203776)
		(width 0.16002)
		(layer "In2.Cu")
		(net "M_C_CPU1_SA_DQS_DP<2>")
	)
	(segment
		(start 46.651418 -219.709238)
		(end 46.800516 -219.56014)
		(width 0.16002)
		(layer "In2.Cu")
		(net "M_C_CPU1_SA_DQS_DP<2>")
	)
	(segment
		(start 56.524652 -219.89288)
		(end 56.863488 -219.89288)
		(width 0.16002)
		(layer "In2.Cu")
		(net "M_C_CPU1_SA_DQS_DP<2>")
	)
	(segment
		(start 72.910446 -231.641142)
		(end 72.910446 -232.281222)
		(width 0.16002)
		(layer "In2.Cu")
		(net "M_C_CPU1_SA_DQS_DP<2>")
	)
	(segment
		(start 44.340018 -219.435426)
		(end 44.61383 -219.709238)
		(width 0.16002)
		(layer "In2.Cu")
		(net "M_C_CPU1_SA_DQS_DP<2>")
	)
	(segment
		(start 88.092534 -236.709458)
		(end 88.100916 -236.714284)
		(width 0.09525)
		(layer "In2.Cu")
		(net "M_C_CPU1_SA_DQS_DP<2>")
	)
	(segment
		(start 48.993552 -219.8751)
		(end 49.444148 -219.8751)
		(width 0.16002)
		(layer "In2.Cu")
		(net "M_C_CPU1_SA_DQS_DP<2>")
	)
	(segment
		(start 76.038456 -234.440222)
		(end 77.059028 -234.440222)
		(width 0.09525)
		(layer "In2.Cu")
		(net "M_C_CPU1_SA_DQS_DP<2>")
	)
	(segment
		(start 85.64118 -236.714284)
		(end 85.649562 -236.709458)
		(width 0.09525)
		(layer "In2.Cu")
		(net "M_C_CPU1_SA_DQS_DP<2>")
	)
	(segment
		(start 74.284078 -233.014774)
		(end 74.284078 -233.654854)
		(width 0.16002)
		(layer "In2.Cu")
		(net "M_C_CPU1_SA_DQS_DP<2>")
	)
	(segment
		(start 86.581234 -236.714284)
		(end 86.589616 -236.709458)
		(width 0.09525)
		(layer "In2.Cu")
		(net "M_C_CPU1_SA_DQS_DP<2>")
	)
	(segment
		(start 61.52261 -219.117672)
		(end 61.895482 -218.7448)
		(width 0.16002)
		(layer "In2.Cu")
		(net "M_C_CPU1_SA_DQS_DP<2>")
	)
	(segment
		(start 46.800516 -219.56014)
		(end 48.678592 -219.56014)
		(width 0.16002)
		(layer "In2.Cu")
		(net "M_C_CPU1_SA_DQS_DP<2>")
	)
	(segment
		(start 75.010518 -234.381294)
		(end 75.955906 -234.381294)
		(width 0.16002)
		(layer "In2.Cu")
		(net "M_C_CPU1_SA_DQS_DP<2>")
	)
	(segment
		(start 75.979528 -234.381294)
		(end 76.038456 -234.440222)
		(width 0.09525)
		(layer "In2.Cu")
		(net "M_C_CPU1_SA_DQS_DP<2>")
	)
	(segment
		(start 62.84468 -220.203776)
		(end 63.040514 -220.39961)
		(width 0.16002)
		(layer "In2.Cu")
		(net "M_C_CPU1_SA_DQS_DP<2>")
	)
	(segment
		(start 61.05017 -219.773246)
		(end 61.326776 -219.773246)
		(width 0.16002)
		(layer "In2.Cu")
		(net "M_C_CPU1_SA_DQS_DP<2>")
	)
	(segment
		(start 81.881218 -236.714284)
		(end 81.8896 -236.709458)
		(width 0.09525)
		(layer "In2.Cu")
		(net "M_C_CPU1_SA_DQS_DP<2>")
	)
	(segment
		(start 45.457618 -219.709238)
		(end 45.574458 -219.592398)
		(width 0.16002)
		(layer "In2.Cu")
		(net "M_C_CPU1_SA_DQS_DP<2>")
	)
	(segment
		(start 60.854336 -219.117672)
		(end 60.854336 -219.577412)
		(width 0.16002)
		(layer "In2.Cu")
		(net "M_C_CPU1_SA_DQS_DP<2>")
	)
	(segment
		(start 77.44714 -235.162598)
		(end 78.315566 -236.031024)
		(width 0.09525)
		(layer "In2.Cu")
		(net "M_C_CPU1_SA_DQS_DP<2>")
	)
	(segment
		(start 72.45477 -231.185466)
		(end 72.910446 -231.641142)
		(width 0.16002)
		(layer "In2.Cu")
		(net "M_C_CPU1_SA_DQS_DP<2>")
	)
	(segment
		(start 77.059028 -234.440222)
		(end 77.44714 -234.828334)
		(width 0.09525)
		(layer "In2.Cu")
		(net "M_C_CPU1_SA_DQS_DP<2>")
	)
	(segment
		(start 48.678592 -219.56014)
		(end 48.993552 -219.8751)
		(width 0.16002)
		(layer "In2.Cu")
		(net "M_C_CPU1_SA_DQS_DP<2>")
	)
	(segment
		(start 64.218312 -221.300548)
		(end 64.218312 -221.577408)
		(width 0.16002)
		(layer "In2.Cu")
		(net "M_C_CPU1_SA_DQS_DP<2>")
	)
	(arc
		(start 93.169486 -236.709458)
		(mid 93.450918 -236.633703)
		(end 93.73235 -236.709458)
		(width 0.09525)
		(layer "In2.Cu")
		(net "M_C_CPU1_SA_DQS_DP<2>")
	)
	(arc
		(start 85.272372 -236.709458)
		(mid 85.456147 -236.76023)
		(end 85.64118 -236.714284)
		(width 0.09525)
		(layer "In2.Cu")
		(net "M_C_CPU1_SA_DQS_DP<2>")
	)
	(arc
		(start 79.632048 -236.709458)
		(mid 79.816077 -236.760357)
		(end 80.001364 -236.714284)
		(width 0.09525)
		(layer "In2.Cu")
		(net "M_C_CPU1_SA_DQS_DP<2>")
	)
	(arc
		(start 84.332572 -236.709458)
		(mid 84.52104 -236.760135)
		(end 84.709508 -236.709458)
		(width 0.09525)
		(layer "In2.Cu")
		(net "M_C_CPU1_SA_DQS_DP<2>")
	)
	(arc
		(start 80.949546 -236.709458)
		(mid 81.230978 -236.633703)
		(end 81.51241 -236.709458)
		(width 0.09525)
		(layer "In2.Cu")
		(net "M_C_CPU1_SA_DQS_DP<2>")
	)
	(arc
		(start 80.009746 -236.709458)
		(mid 80.291178 -236.633703)
		(end 80.57261 -236.709458)
		(width 0.09525)
		(layer "In2.Cu")
		(net "M_C_CPU1_SA_DQS_DP<2>")
	)
	(arc
		(start 92.229686 -236.709458)
		(mid 92.511118 -236.633703)
		(end 92.79255 -236.709458)
		(width 0.09525)
		(layer "In2.Cu")
		(net "M_C_CPU1_SA_DQS_DP<2>")
	)
	(arc
		(start 90.920824 -236.714284)
		(mid 91.105856 -236.760198)
		(end 91.289632 -236.709458)
		(width 0.09525)
		(layer "In2.Cu")
		(net "M_C_CPU1_SA_DQS_DP<2>")
	)
	(arc
		(start 93.73235 -236.709458)
		(mid 93.888948 -236.758747)
		(end 94.051628 -236.736636)
		(width 0.09525)
		(layer "In2.Cu")
		(net "M_C_CPU1_SA_DQS_DP<2>")
	)
	(arc
		(start 83.769708 -236.709458)
		(mid 84.05114 -236.633703)
		(end 84.332572 -236.709458)
		(width 0.09525)
		(layer "In2.Cu")
		(net "M_C_CPU1_SA_DQS_DP<2>")
	)
	(arc
		(start 91.860878 -236.714284)
		(mid 92.04591 -236.760198)
		(end 92.229686 -236.709458)
		(width 0.09525)
		(layer "In2.Cu")
		(net "M_C_CPU1_SA_DQS_DP<2>")
	)
	(arc
		(start 89.972388 -236.709458)
		(mid 90.156163 -236.76023)
		(end 90.341196 -236.714284)
		(width 0.09525)
		(layer "In2.Cu")
		(net "M_C_CPU1_SA_DQS_DP<2>")
	)
	(arc
		(start 81.51241 -236.709458)
		(mid 81.696185 -236.76023)
		(end 81.881218 -236.714284)
		(width 0.09525)
		(layer "In2.Cu")
		(net "M_C_CPU1_SA_DQS_DP<2>")
	)
	(arc
		(start 90.349578 -236.709458)
		(mid 90.63101 -236.633703)
		(end 90.912442 -236.709458)
		(width 0.09525)
		(layer "In2.Cu")
		(net "M_C_CPU1_SA_DQS_DP<2>")
	)
	(arc
		(start 88.469724 -236.709458)
		(mid 88.751156 -236.633703)
		(end 89.032588 -236.709458)
		(width 0.09525)
		(layer "In2.Cu")
		(net "M_C_CPU1_SA_DQS_DP<2>")
	)
	(arc
		(start 87.52967 -236.709458)
		(mid 87.811102 -236.633703)
		(end 88.092534 -236.709458)
		(width 0.09525)
		(layer "In2.Cu")
		(net "M_C_CPU1_SA_DQS_DP<2>")
	)
	(arc
		(start 91.289632 -236.709458)
		(mid 91.571064 -236.633703)
		(end 91.852496 -236.709458)
		(width 0.09525)
		(layer "In2.Cu")
		(net "M_C_CPU1_SA_DQS_DP<2>")
	)
	(arc
		(start 85.649562 -236.709458)
		(mid 85.930994 -236.633703)
		(end 86.212426 -236.709458)
		(width 0.09525)
		(layer "In2.Cu")
		(net "M_C_CPU1_SA_DQS_DP<2>")
	)
	(arc
		(start 81.8896 -236.709458)
		(mid 82.171032 -236.633703)
		(end 82.452464 -236.709458)
		(width 0.09525)
		(layer "In2.Cu")
		(net "M_C_CPU1_SA_DQS_DP<2>")
	)
	(arc
		(start 86.589616 -236.709458)
		(mid 86.871048 -236.633703)
		(end 87.15248 -236.709458)
		(width 0.09525)
		(layer "In2.Cu")
		(net "M_C_CPU1_SA_DQS_DP<2>")
	)
	(arc
		(start 79.554832 -236.65053)
		(mid 79.591536 -236.682488)
		(end 79.632048 -236.709458)
		(width 0.09525)
		(layer "In2.Cu")
		(net "M_C_CPU1_SA_DQS_DP<2>")
	)
	(arc
		(start 89.032588 -236.709458)
		(mid 89.221056 -236.760135)
		(end 89.409524 -236.709458)
		(width 0.09525)
		(layer "In2.Cu")
		(net "M_C_CPU1_SA_DQS_DP<2>")
	)
	(arc
		(start 83.4009 -236.714284)
		(mid 83.585932 -236.760198)
		(end 83.769708 -236.709458)
		(width 0.09525)
		(layer "In2.Cu")
		(net "M_C_CPU1_SA_DQS_DP<2>")
	)
	(arc
		(start 82.829654 -236.709458)
		(mid 83.111086 -236.633703)
		(end 83.392518 -236.709458)
		(width 0.09525)
		(layer "In2.Cu")
		(net "M_C_CPU1_SA_DQS_DP<2>")
	)
	(arc
		(start 87.160862 -236.714284)
		(mid 87.345894 -236.760198)
		(end 87.52967 -236.709458)
		(width 0.09525)
		(layer "In2.Cu")
		(net "M_C_CPU1_SA_DQS_DP<2>")
	)
	(arc
		(start 89.409524 -236.709458)
		(mid 89.690956 -236.633703)
		(end 89.972388 -236.709458)
		(width 0.09525)
		(layer "In2.Cu")
		(net "M_C_CPU1_SA_DQS_DP<2>")
	)
	(arc
		(start 80.57261 -236.709458)
		(mid 80.761078 -236.760135)
		(end 80.949546 -236.709458)
		(width 0.09525)
		(layer "In2.Cu")
		(net "M_C_CPU1_SA_DQS_DP<2>")
	)
	(arc
		(start 86.212426 -236.709458)
		(mid 86.396201 -236.76023)
		(end 86.581234 -236.714284)
		(width 0.09525)
		(layer "In2.Cu")
		(net "M_C_CPU1_SA_DQS_DP<2>")
	)
	(arc
		(start 82.460846 -236.714284)
		(mid 82.645878 -236.760198)
		(end 82.829654 -236.709458)
		(width 0.09525)
		(layer "In2.Cu")
		(net "M_C_CPU1_SA_DQS_DP<2>")
	)
	(arc
		(start 84.709508 -236.709458)
		(mid 84.99094 -236.633703)
		(end 85.272372 -236.709458)
		(width 0.09525)
		(layer "In2.Cu")
		(net "M_C_CPU1_SA_DQS_DP<2>")
	)
	(arc
		(start 88.100916 -236.714284)
		(mid 88.285948 -236.760198)
		(end 88.469724 -236.709458)
		(width 0.09525)
		(layer "In2.Cu")
		(net "M_C_CPU1_SA_DQS_DP<2>")
	)
	(arc
		(start 92.79255 -236.709458)
		(mid 92.981018 -236.760135)
		(end 93.169486 -236.709458)
		(width 0.09525)
		(layer "In2.Cu")
		(net "M_C_CPU1_SA_DQS_DP<2>")
	)
	(segment
		(start 94.387924 -231.79024)
		(end 93.921072 -231.524302)
		(width 0.12954)
		(layer "F.Cu")
		(net "M_C_CPU1_SA_DQS_DP<1>")
	)
	(segment
		(start 45.571918 -210.242404)
		(end 46.051978 -210.242404)
		(width 0.16002)
		(layer "In2.Cu")
		(net "M_C_CPU1_SA_DQS_DP<1>")
	)
	(segment
		(start 78.222856 -227.799392)
		(end 78.259432 -227.820728)
		(width 0.09525)
		(layer "In2.Cu")
		(net "M_C_CPU1_SA_DQS_DP<1>")
	)
	(segment
		(start 79.60233 -230.211884)
		(end 79.632556 -230.22941)
		(width 0.09525)
		(layer "In2.Cu")
		(net "M_C_CPU1_SA_DQS_DP<1>")
	)
	(segment
		(start 73.204578 -222.059754)
		(end 73.204578 -222.336614)
		(width 0.16002)
		(layer "In2.Cu")
		(net "M_C_CPU1_SA_DQS_DP<1>")
	)
	(segment
		(start 72.636634 -219.35313)
		(end 72.636634 -219.880434)
		(width 0.16002)
		(layer "In2.Cu")
		(net "M_C_CPU1_SA_DQS_DP<1>")
	)
	(segment
		(start 71.830946 -220.962982)
		(end 72.02678 -221.158816)
		(width 0.16002)
		(layer "In2.Cu")
		(net "M_C_CPU1_SA_DQS_DP<1>")
	)
	(segment
		(start 91.852496 -231.849422)
		(end 91.860878 -231.854248)
		(width 0.09525)
		(layer "In2.Cu")
		(net "M_C_CPU1_SA_DQS_DP<1>")
	)
	(segment
		(start 52.908708 -209.360262)
		(end 53.801772 -210.253326)
		(width 0.16002)
		(layer "In2.Cu")
		(net "M_C_CPU1_SA_DQS_DP<1>")
	)
	(segment
		(start 90.341196 -231.854248)
		(end 90.349578 -231.849422)
		(width 0.09525)
		(layer "In2.Cu")
		(net "M_C_CPU1_SA_DQS_DP<1>")
	)
	(segment
		(start 46.797976 -210.210146)
		(end 48.678592 -210.210146)
		(width 0.16002)
		(layer "In2.Cu")
		(net "M_C_CPU1_SA_DQS_DP<1>")
	)
	(segment
		(start 72.02678 -221.158816)
		(end 72.30364 -221.158816)
		(width 0.16002)
		(layer "In2.Cu")
		(net "M_C_CPU1_SA_DQS_DP<1>")
	)
	(segment
		(start 70.930008 -219.785184)
		(end 71.735696 -218.979496)
		(width 0.16002)
		(layer "In2.Cu")
		(net "M_C_CPU1_SA_DQS_DP<1>")
	)
	(segment
		(start 76.494386 -226.048824)
		(end 76.518008 -226.048824)
		(width 0.09525)
		(layer "In2.Cu")
		(net "M_C_CPU1_SA_DQS_DP<1>")
	)
	(segment
		(start 80.07096 -231.021382)
		(end 80.102456 -231.03967)
		(width 0.09525)
		(layer "In2.Cu")
		(net "M_C_CPU1_SA_DQS_DP<1>")
	)
	(segment
		(start 72.989948 -220.472508)
		(end 73.517252 -220.472508)
		(width 0.16002)
		(layer "In2.Cu")
		(net "M_C_CPU1_SA_DQS_DP<1>")
	)
	(segment
		(start 70.653148 -219.785184)
		(end 70.930008 -219.785184)
		(width 0.16002)
		(layer "In2.Cu")
		(net "M_C_CPU1_SA_DQS_DP<1>")
	)
	(segment
		(start 76.518008 -226.048824)
		(end 76.57719 -226.108006)
		(width 0.09525)
		(layer "In2.Cu")
		(net "M_C_CPU1_SA_DQS_DP<1>")
	)
	(segment
		(start 44.340018 -210.085432)
		(end 44.61383 -210.359244)
		(width 0.16002)
		(layer "In2.Cu")
		(net "M_C_CPU1_SA_DQS_DP<1>")
	)
	(segment
		(start 83.392518 -231.849422)
		(end 83.4009 -231.854248)
		(width 0.09525)
		(layer "In2.Cu")
		(net "M_C_CPU1_SA_DQS_DP<1>")
	)
	(segment
		(start 78.222348 -227.799646)
		(end 78.222856 -227.799392)
		(width 0.09525)
		(layer "In2.Cu")
		(net "M_C_CPU1_SA_DQS_DP<1>")
	)
	(segment
		(start 46.168818 -210.359244)
		(end 46.648878 -210.359244)
		(width 0.16002)
		(layer "In2.Cu")
		(net "M_C_CPU1_SA_DQS_DP<1>")
	)
	(segment
		(start 77.752448 -226.98964)
		(end 77.790548 -227.011738)
		(width 0.09525)
		(layer "In2.Cu")
		(net "M_C_CPU1_SA_DQS_DP<1>")
	)
	(segment
		(start 76.268072 -226.048824)
		(end 76.494386 -226.048824)
		(width 0.16002)
		(layer "In2.Cu")
		(net "M_C_CPU1_SA_DQS_DP<1>")
	)
	(segment
		(start 46.648878 -210.359244)
		(end 46.797976 -210.210146)
		(width 0.16002)
		(layer "In2.Cu")
		(net "M_C_CPU1_SA_DQS_DP<1>")
	)
	(segment
		(start 82.452464 -231.849422)
		(end 82.460846 -231.854248)
		(width 0.09525)
		(layer "In2.Cu")
		(net "M_C_CPU1_SA_DQS_DP<1>")
	)
	(segment
		(start 70.49643 -217.817446)
		(end 70.49643 -219.628466)
		(width 0.16002)
		(layer "In2.Cu")
		(net "M_C_CPU1_SA_DQS_DP<1>")
	)
	(segment
		(start 76.57719 -226.108006)
		(end 77.000608 -226.108006)
		(width 0.09525)
		(layer "In2.Cu")
		(net "M_C_CPU1_SA_DQS_DP<1>")
	)
	(segment
		(start 50.703988 -209.671666)
		(end 51.015392 -209.360262)
		(width 0.16002)
		(layer "In2.Cu")
		(net "M_C_CPU1_SA_DQS_DP<1>")
	)
	(segment
		(start 79.16291 -229.419404)
		(end 79.197962 -229.439978)
		(width 0.09525)
		(layer "In2.Cu")
		(net "M_C_CPU1_SA_DQS_DP<1>")
	)
	(segment
		(start 56.524652 -210.542886)
		(end 56.863488 -210.542886)
		(width 0.16002)
		(layer "In2.Cu")
		(net "M_C_CPU1_SA_DQS_DP<1>")
	)
	(segment
		(start 73.890886 -220.846142)
		(end 73.890886 -221.373446)
		(width 0.16002)
		(layer "In2.Cu")
		(net "M_C_CPU1_SA_DQS_DP<1>")
	)
	(segment
		(start 78.692756 -228.609652)
		(end 78.729332 -228.630988)
		(width 0.09525)
		(layer "In2.Cu")
		(net "M_C_CPU1_SA_DQS_DP<1>")
	)
	(segment
		(start 73.890886 -221.373446)
		(end 73.204578 -222.059754)
		(width 0.16002)
		(layer "In2.Cu")
		(net "M_C_CPU1_SA_DQS_DP<1>")
	)
	(segment
		(start 49.444148 -210.525106)
		(end 50.297588 -209.671666)
		(width 0.16002)
		(layer "In2.Cu")
		(net "M_C_CPU1_SA_DQS_DP<1>")
	)
	(segment
		(start 71.735696 -218.979496)
		(end 72.263 -218.979496)
		(width 0.16002)
		(layer "In2.Cu")
		(net "M_C_CPU1_SA_DQS_DP<1>")
	)
	(segment
		(start 46.051978 -210.242404)
		(end 46.168818 -210.359244)
		(width 0.16002)
		(layer "In2.Cu")
		(net "M_C_CPU1_SA_DQS_DP<1>")
	)
	(segment
		(start 90.912442 -231.849422)
		(end 90.920824 -231.854248)
		(width 0.09525)
		(layer "In2.Cu")
		(net "M_C_CPU1_SA_DQS_DP<1>")
	)
	(segment
		(start 86.581234 -231.854248)
		(end 86.589616 -231.849422)
		(width 0.09525)
		(layer "In2.Cu")
		(net "M_C_CPU1_SA_DQS_DP<1>")
	)
	(segment
		(start 79.128112 -229.399338)
		(end 79.16291 -229.419404)
		(width 0.09525)
		(layer "In2.Cu")
		(net "M_C_CPU1_SA_DQS_DP<1>")
	)
	(segment
		(start 73.517252 -220.472508)
		(end 73.890886 -220.846142)
		(width 0.16002)
		(layer "In2.Cu")
		(net "M_C_CPU1_SA_DQS_DP<1>")
	)
	(segment
		(start 78.190852 -227.781358)
		(end 78.222348 -227.799646)
		(width 0.09525)
		(layer "In2.Cu")
		(net "M_C_CPU1_SA_DQS_DP<1>")
	)
	(segment
		(start 70.49643 -219.628466)
		(end 70.653148 -219.785184)
		(width 0.16002)
		(layer "In2.Cu")
		(net "M_C_CPU1_SA_DQS_DP<1>")
	)
	(segment
		(start 77.563472 -226.593146)
		(end 77.563472 -226.66452)
		(width 0.09525)
		(layer "In2.Cu")
		(net "M_C_CPU1_SA_DQS_DP<1>")
	)
	(segment
		(start 80.102456 -231.03967)
		(end 80.142842 -231.063292)
		(width 0.09525)
		(layer "In2.Cu")
		(net "M_C_CPU1_SA_DQS_DP<1>")
	)
	(segment
		(start 77.720952 -226.971352)
		(end 77.752448 -226.98964)
		(width 0.09525)
		(layer "In2.Cu")
		(net "M_C_CPU1_SA_DQS_DP<1>")
	)
	(segment
		(start 62.07379 -209.394806)
		(end 70.49643 -217.817446)
		(width 0.16002)
		(layer "In2.Cu")
		(net "M_C_CPU1_SA_DQS_DP<1>")
	)
	(segment
		(start 58.138568 -209.745326)
		(end 58.489088 -209.394806)
		(width 0.16002)
		(layer "In2.Cu")
		(net "M_C_CPU1_SA_DQS_DP<1>")
	)
	(segment
		(start 48.678592 -210.210146)
		(end 48.993552 -210.525106)
		(width 0.16002)
		(layer "In2.Cu")
		(net "M_C_CPU1_SA_DQS_DP<1>")
	)
	(segment
		(start 48.993552 -210.525106)
		(end 49.444148 -210.525106)
		(width 0.16002)
		(layer "In2.Cu")
		(net "M_C_CPU1_SA_DQS_DP<1>")
	)
	(segment
		(start 94.051628 -231.8766)
		(end 94.074996 -231.789732)
		(width 0.09525)
		(layer "In2.Cu")
		(net "M_C_CPU1_SA_DQS_DP<1>")
	)
	(segment
		(start 44.61383 -210.359244)
		(end 45.455078 -210.359244)
		(width 0.16002)
		(layer "In2.Cu")
		(net "M_C_CPU1_SA_DQS_DP<1>")
	)
	(segment
		(start 56.863488 -210.542886)
		(end 57.661048 -209.745326)
		(width 0.16002)
		(layer "In2.Cu")
		(net "M_C_CPU1_SA_DQS_DP<1>")
	)
	(segment
		(start 57.661048 -209.745326)
		(end 58.138568 -209.745326)
		(width 0.16002)
		(layer "In2.Cu")
		(net "M_C_CPU1_SA_DQS_DP<1>")
	)
	(segment
		(start 85.64118 -231.854248)
		(end 85.649562 -231.849422)
		(width 0.09525)
		(layer "In2.Cu")
		(net "M_C_CPU1_SA_DQS_DP<1>")
	)
	(segment
		(start 76.10729 -225.888042)
		(end 76.268072 -226.048824)
		(width 0.16002)
		(layer "In2.Cu")
		(net "M_C_CPU1_SA_DQS_DP<1>")
	)
	(segment
		(start 81.881218 -231.854248)
		(end 81.8896 -231.849422)
		(width 0.09525)
		(layer "In2.Cu")
		(net "M_C_CPU1_SA_DQS_DP<1>")
	)
	(segment
		(start 87.15248 -231.849422)
		(end 87.160862 -231.854248)
		(width 0.09525)
		(layer "In2.Cu")
		(net "M_C_CPU1_SA_DQS_DP<1>")
	)
	(segment
		(start 71.830946 -220.686122)
		(end 71.830946 -220.962982)
		(width 0.16002)
		(layer "In2.Cu")
		(net "M_C_CPU1_SA_DQS_DP<1>")
	)
	(segment
		(start 51.015392 -209.360262)
		(end 52.908708 -209.360262)
		(width 0.16002)
		(layer "In2.Cu")
		(net "M_C_CPU1_SA_DQS_DP<1>")
	)
	(segment
		(start 56.235092 -210.253326)
		(end 56.524652 -210.542886)
		(width 0.16002)
		(layer "In2.Cu")
		(net "M_C_CPU1_SA_DQS_DP<1>")
	)
	(segment
		(start 94.074996 -231.789732)
		(end 93.921072 -231.524302)
		(width 0.09525)
		(layer "In2.Cu")
		(net "M_C_CPU1_SA_DQS_DP<1>")
	)
	(segment
		(start 76.10729 -225.239326)
		(end 76.10729 -225.888042)
		(width 0.16002)
		(layer "In2.Cu")
		(net "M_C_CPU1_SA_DQS_DP<1>")
	)
	(segment
		(start 45.455078 -210.359244)
		(end 45.571918 -210.242404)
		(width 0.16002)
		(layer "In2.Cu")
		(net "M_C_CPU1_SA_DQS_DP<1>")
	)
	(segment
		(start 79.632556 -230.22941)
		(end 79.669132 -230.250746)
		(width 0.09525)
		(layer "In2.Cu")
		(net "M_C_CPU1_SA_DQS_DP<1>")
	)
	(segment
		(start 53.801772 -210.253326)
		(end 56.235092 -210.253326)
		(width 0.16002)
		(layer "In2.Cu")
		(net "M_C_CPU1_SA_DQS_DP<1>")
	)
	(segment
		(start 88.092534 -231.849422)
		(end 88.100916 -231.854248)
		(width 0.09525)
		(layer "In2.Cu")
		(net "M_C_CPU1_SA_DQS_DP<1>")
	)
	(segment
		(start 50.297588 -209.671666)
		(end 50.703988 -209.671666)
		(width 0.16002)
		(layer "In2.Cu")
		(net "M_C_CPU1_SA_DQS_DP<1>")
	)
	(segment
		(start 78.663292 -228.592634)
		(end 78.692756 -228.609652)
		(width 0.09525)
		(layer "In2.Cu")
		(net "M_C_CPU1_SA_DQS_DP<1>")
	)
	(segment
		(start 72.30364 -221.158816)
		(end 72.989948 -220.472508)
		(width 0.16002)
		(layer "In2.Cu")
		(net "M_C_CPU1_SA_DQS_DP<1>")
	)
	(segment
		(start 73.204578 -222.336614)
		(end 76.10729 -225.239326)
		(width 0.16002)
		(layer "In2.Cu")
		(net "M_C_CPU1_SA_DQS_DP<1>")
	)
	(segment
		(start 72.636634 -219.880434)
		(end 71.830946 -220.686122)
		(width 0.16002)
		(layer "In2.Cu")
		(net "M_C_CPU1_SA_DQS_DP<1>")
	)
	(segment
		(start 58.489088 -209.394806)
		(end 62.07379 -209.394806)
		(width 0.16002)
		(layer "In2.Cu")
		(net "M_C_CPU1_SA_DQS_DP<1>")
	)
	(segment
		(start 72.263 -218.979496)
		(end 72.636634 -219.35313)
		(width 0.16002)
		(layer "In2.Cu")
		(net "M_C_CPU1_SA_DQS_DP<1>")
	)
	(segment
		(start 80.540098 -231.830626)
		(end 80.57261 -231.849422)
		(width 0.09525)
		(layer "In2.Cu")
		(net "M_C_CPU1_SA_DQS_DP<1>")
	)
	(segment
		(start 77.400404 -226.27336)
		(end 77.452728 -226.32543)
		(width 0.09525)
		(layer "In2.Cu")
		(net "M_C_CPU1_SA_DQS_DP<1>")
	)
	(arc
		(start 82.829654 -231.849422)
		(mid 83.111086 -231.773667)
		(end 83.392518 -231.849422)
		(width 0.09525)
		(layer "In2.Cu")
		(net "M_C_CPU1_SA_DQS_DP<1>")
	)
	(arc
		(start 78.259432 -227.820728)
		(mid 78.438961 -228.022271)
		(end 78.50378 -228.284278)
		(width 0.09525)
		(layer "In2.Cu")
		(net "M_C_CPU1_SA_DQS_DP<1>")
	)
	(arc
		(start 79.669132 -230.250746)
		(mid 79.848642 -230.452428)
		(end 79.91348 -230.71455)
		(width 0.09525)
		(layer "In2.Cu")
		(net "M_C_CPU1_SA_DQS_DP<1>")
	)
	(arc
		(start 84.332572 -231.849422)
		(mid 84.52104 -231.900099)
		(end 84.709508 -231.849422)
		(width 0.09525)
		(layer "In2.Cu")
		(net "M_C_CPU1_SA_DQS_DP<1>")
	)
	(arc
		(start 81.51241 -231.849422)
		(mid 81.696185 -231.900194)
		(end 81.881218 -231.854248)
		(width 0.09525)
		(layer "In2.Cu")
		(net "M_C_CPU1_SA_DQS_DP<1>")
	)
	(arc
		(start 80.57261 -231.849422)
		(mid 80.761078 -231.900099)
		(end 80.949546 -231.849422)
		(width 0.09525)
		(layer "In2.Cu")
		(net "M_C_CPU1_SA_DQS_DP<1>")
	)
	(arc
		(start 87.52967 -231.849422)
		(mid 87.811102 -231.773667)
		(end 88.092534 -231.849422)
		(width 0.09525)
		(layer "In2.Cu")
		(net "M_C_CPU1_SA_DQS_DP<1>")
	)
	(arc
		(start 89.032588 -231.849422)
		(mid 89.221056 -231.900099)
		(end 89.409524 -231.849422)
		(width 0.09525)
		(layer "In2.Cu")
		(net "M_C_CPU1_SA_DQS_DP<1>")
	)
	(arc
		(start 91.289632 -231.849422)
		(mid 91.571064 -231.773667)
		(end 91.852496 -231.849422)
		(width 0.09525)
		(layer "In2.Cu")
		(net "M_C_CPU1_SA_DQS_DP<1>")
	)
	(arc
		(start 80.949546 -231.849422)
		(mid 81.230978 -231.773667)
		(end 81.51241 -231.849422)
		(width 0.09525)
		(layer "In2.Cu")
		(net "M_C_CPU1_SA_DQS_DP<1>")
	)
	(arc
		(start 81.8896 -231.849422)
		(mid 82.171032 -231.773667)
		(end 82.452464 -231.849422)
		(width 0.09525)
		(layer "In2.Cu")
		(net "M_C_CPU1_SA_DQS_DP<1>")
	)
	(arc
		(start 89.409524 -231.849422)
		(mid 89.690956 -231.773667)
		(end 89.972388 -231.849422)
		(width 0.09525)
		(layer "In2.Cu")
		(net "M_C_CPU1_SA_DQS_DP<1>")
	)
	(arc
		(start 82.460846 -231.854248)
		(mid 82.645878 -231.900162)
		(end 82.829654 -231.849422)
		(width 0.09525)
		(layer "In2.Cu")
		(net "M_C_CPU1_SA_DQS_DP<1>")
	)
	(arc
		(start 77.563472 -226.66452)
		(mid 77.605137 -226.836967)
		(end 77.720952 -226.971352)
		(width 0.09525)
		(layer "In2.Cu")
		(net "M_C_CPU1_SA_DQS_DP<1>")
	)
	(arc
		(start 78.033372 -227.474526)
		(mid 78.075037 -227.646973)
		(end 78.190852 -227.781358)
		(width 0.09525)
		(layer "In2.Cu")
		(net "M_C_CPU1_SA_DQS_DP<1>")
	)
	(arc
		(start 84.709508 -231.849422)
		(mid 84.99094 -231.773667)
		(end 85.272372 -231.849422)
		(width 0.09525)
		(layer "In2.Cu")
		(net "M_C_CPU1_SA_DQS_DP<1>")
	)
	(arc
		(start 92.229686 -231.849422)
		(mid 92.511118 -231.773667)
		(end 92.79255 -231.849422)
		(width 0.09525)
		(layer "In2.Cu")
		(net "M_C_CPU1_SA_DQS_DP<1>")
	)
	(arc
		(start 78.973426 -229.094284)
		(mid 79.014302 -229.265306)
		(end 79.128112 -229.399338)
		(width 0.09525)
		(layer "In2.Cu")
		(net "M_C_CPU1_SA_DQS_DP<1>")
	)
	(arc
		(start 80.38338 -231.524302)
		(mid 80.424837 -231.696342)
		(end 80.540098 -231.830626)
		(width 0.09525)
		(layer "In2.Cu")
		(net "M_C_CPU1_SA_DQS_DP<1>")
	)
	(arc
		(start 79.44358 -229.90429)
		(mid 79.485602 -230.077369)
		(end 79.60233 -230.211884)
		(width 0.09525)
		(layer "In2.Cu")
		(net "M_C_CPU1_SA_DQS_DP<1>")
	)
	(arc
		(start 89.972388 -231.849422)
		(mid 90.156163 -231.900194)
		(end 90.341196 -231.854248)
		(width 0.09525)
		(layer "In2.Cu")
		(net "M_C_CPU1_SA_DQS_DP<1>")
	)
	(arc
		(start 78.50378 -228.284278)
		(mid 78.546027 -228.457853)
		(end 78.663292 -228.592634)
		(width 0.09525)
		(layer "In2.Cu")
		(net "M_C_CPU1_SA_DQS_DP<1>")
	)
	(arc
		(start 85.272372 -231.849422)
		(mid 85.456147 -231.900194)
		(end 85.64118 -231.854248)
		(width 0.09525)
		(layer "In2.Cu")
		(net "M_C_CPU1_SA_DQS_DP<1>")
	)
	(arc
		(start 90.920824 -231.854248)
		(mid 91.105856 -231.900162)
		(end 91.289632 -231.849422)
		(width 0.09525)
		(layer "In2.Cu")
		(net "M_C_CPU1_SA_DQS_DP<1>")
	)
	(arc
		(start 91.860878 -231.854248)
		(mid 92.04591 -231.900162)
		(end 92.229686 -231.849422)
		(width 0.09525)
		(layer "In2.Cu")
		(net "M_C_CPU1_SA_DQS_DP<1>")
	)
	(arc
		(start 85.649562 -231.849422)
		(mid 85.930994 -231.773667)
		(end 86.212426 -231.849422)
		(width 0.09525)
		(layer "In2.Cu")
		(net "M_C_CPU1_SA_DQS_DP<1>")
	)
	(arc
		(start 86.589616 -231.849422)
		(mid 86.871048 -231.773667)
		(end 87.15248 -231.849422)
		(width 0.09525)
		(layer "In2.Cu")
		(net "M_C_CPU1_SA_DQS_DP<1>")
	)
	(arc
		(start 90.349578 -231.849422)
		(mid 90.63101 -231.773667)
		(end 90.912442 -231.849422)
		(width 0.09525)
		(layer "In2.Cu")
		(net "M_C_CPU1_SA_DQS_DP<1>")
	)
	(arc
		(start 86.212426 -231.849422)
		(mid 86.396201 -231.900194)
		(end 86.581234 -231.854248)
		(width 0.09525)
		(layer "In2.Cu")
		(net "M_C_CPU1_SA_DQS_DP<1>")
	)
	(arc
		(start 77.790548 -227.011738)
		(mid 77.968998 -227.213208)
		(end 78.033372 -227.474526)
		(width 0.09525)
		(layer "In2.Cu")
		(net "M_C_CPU1_SA_DQS_DP<1>")
	)
	(arc
		(start 83.4009 -231.854248)
		(mid 83.585932 -231.900162)
		(end 83.769708 -231.849422)
		(width 0.09525)
		(layer "In2.Cu")
		(net "M_C_CPU1_SA_DQS_DP<1>")
	)
	(arc
		(start 79.91348 -230.71455)
		(mid 79.955145 -230.886997)
		(end 80.07096 -231.021382)
		(width 0.09525)
		(layer "In2.Cu")
		(net "M_C_CPU1_SA_DQS_DP<1>")
	)
	(arc
		(start 88.469724 -231.849422)
		(mid 88.751156 -231.773667)
		(end 89.032588 -231.849422)
		(width 0.09525)
		(layer "In2.Cu")
		(net "M_C_CPU1_SA_DQS_DP<1>")
	)
	(arc
		(start 93.169486 -231.849422)
		(mid 93.450918 -231.773667)
		(end 93.73235 -231.849422)
		(width 0.09525)
		(layer "In2.Cu")
		(net "M_C_CPU1_SA_DQS_DP<1>")
	)
	(arc
		(start 92.79255 -231.849422)
		(mid 92.981018 -231.900099)
		(end 93.169486 -231.849422)
		(width 0.09525)
		(layer "In2.Cu")
		(net "M_C_CPU1_SA_DQS_DP<1>")
	)
	(arc
		(start 87.160862 -231.854248)
		(mid 87.345894 -231.900162)
		(end 87.52967 -231.849422)
		(width 0.09525)
		(layer "In2.Cu")
		(net "M_C_CPU1_SA_DQS_DP<1>")
	)
	(arc
		(start 83.769708 -231.849422)
		(mid 84.05114 -231.773667)
		(end 84.332572 -231.849422)
		(width 0.09525)
		(layer "In2.Cu")
		(net "M_C_CPU1_SA_DQS_DP<1>")
	)
	(arc
		(start 78.729332 -228.630988)
		(mid 78.908567 -228.832496)
		(end 78.973426 -229.094284)
		(width 0.09525)
		(layer "In2.Cu")
		(net "M_C_CPU1_SA_DQS_DP<1>")
	)
	(arc
		(start 79.197962 -229.439978)
		(mid 79.378417 -229.641644)
		(end 79.44358 -229.90429)
		(width 0.09525)
		(layer "In2.Cu")
		(net "M_C_CPU1_SA_DQS_DP<1>")
	)
	(arc
		(start 80.142842 -231.063292)
		(mid 80.319614 -231.264313)
		(end 80.38338 -231.524302)
		(width 0.09525)
		(layer "In2.Cu")
		(net "M_C_CPU1_SA_DQS_DP<1>")
	)
	(arc
		(start 77.452728 -226.32543)
		(mid 77.534717 -226.448274)
		(end 77.563472 -226.593146)
		(width 0.09525)
		(layer "In2.Cu")
		(net "M_C_CPU1_SA_DQS_DP<1>")
	)
	(arc
		(start 77.000608 -226.108006)
		(mid 77.216975 -226.150874)
		(end 77.400404 -226.27336)
		(width 0.09525)
		(layer "In2.Cu")
		(net "M_C_CPU1_SA_DQS_DP<1>")
	)
	(arc
		(start 93.73235 -231.849422)
		(mid 93.888948 -231.898711)
		(end 94.051628 -231.8766)
		(width 0.09525)
		(layer "In2.Cu")
		(net "M_C_CPU1_SA_DQS_DP<1>")
	)
	(arc
		(start 88.100916 -231.854248)
		(mid 88.285948 -231.900162)
		(end 88.469724 -231.849422)
		(width 0.09525)
		(layer "In2.Cu")
		(net "M_C_CPU1_SA_DQS_DP<1>")
	)
	(segment
		(start 94.387924 -226.930458)
		(end 93.921072 -226.66452)
		(width 0.12954)
		(layer "F.Cu")
		(net "M_C_CPU1_SA_DQS_DP<0>")
	)
	(segment
		(start 53.132228 -200.010268)
		(end 53.706268 -200.584308)
		(width 0.16002)
		(layer "In2.Cu")
		(net "M_C_CPU1_SA_DQS_DP<0>")
	)
	(segment
		(start 74.111612 -211.019136)
		(end 74.111866 -211.54644)
		(width 0.16002)
		(layer "In2.Cu")
		(net "M_C_CPU1_SA_DQS_DP<0>")
	)
	(segment
		(start 75.005438 -213.400132)
		(end 75.005438 -213.676992)
		(width 0.16002)
		(layer "In2.Cu")
		(net "M_C_CPU1_SA_DQS_DP<0>")
	)
	(segment
		(start 62.532514 -201.086212)
		(end 61.865256 -201.75347)
		(width 0.16002)
		(layer "In2.Cu")
		(net "M_C_CPU1_SA_DQS_DP<0>")
	)
	(segment
		(start 80.442054 -221.174564)
		(end 80.442054 -221.198186)
		(width 0.09525)
		(layer "In2.Cu")
		(net "M_C_CPU1_SA_DQS_DP<0>")
	)
	(segment
		(start 48.993552 -201.175112)
		(end 49.444148 -201.175112)
		(width 0.16002)
		(layer "In2.Cu")
		(net "M_C_CPU1_SA_DQS_DP<0>")
	)
	(segment
		(start 63.00597 -201.559668)
		(end 63.533274 -201.559668)
		(width 0.16002)
		(layer "In2.Cu")
		(net "M_C_CPU1_SA_DQS_DP<0>")
	)
	(segment
		(start 81.012284 -222.922084)
		(end 81.04251 -222.93961)
		(width 0.09525)
		(layer "In2.Cu")
		(net "M_C_CPU1_SA_DQS_DP<0>")
	)
	(segment
		(start 73.631806 -212.30336)
		(end 73.82764 -212.499194)
		(width 0.16002)
		(layer "In2.Cu")
		(net "M_C_CPU1_SA_DQS_DP<0>")
	)
	(segment
		(start 73.82764 -212.499194)
		(end 74.1045 -212.499194)
		(width 0.16002)
		(layer "In2.Cu")
		(net "M_C_CPU1_SA_DQS_DP<0>")
	)
	(segment
		(start 61.865256 -201.75347)
		(end 61.865256 -202.03033)
		(width 0.16002)
		(layer "In2.Cu")
		(net "M_C_CPU1_SA_DQS_DP<0>")
	)
	(segment
		(start 82.452464 -225.369628)
		(end 82.490564 -225.391726)
		(width 0.09525)
		(layer "In2.Cu")
		(net "M_C_CPU1_SA_DQS_DP<0>")
	)
	(segment
		(start 57.661048 -200.395332)
		(end 58.138568 -200.395332)
		(width 0.16002)
		(layer "In2.Cu")
		(net "M_C_CPU1_SA_DQS_DP<0>")
	)
	(segment
		(start 58.489088 -200.044812)
		(end 62.018418 -200.044812)
		(width 0.16002)
		(layer "In2.Cu")
		(net "M_C_CPU1_SA_DQS_DP<0>")
	)
	(segment
		(start 73.210928 -210.645502)
		(end 73.737978 -210.645502)
		(width 0.16002)
		(layer "In2.Cu")
		(net "M_C_CPU1_SA_DQS_DP<0>")
	)
	(segment
		(start 61.865256 -202.03033)
		(end 62.061852 -202.226926)
		(width 0.16002)
		(layer "In2.Cu")
		(net "M_C_CPU1_SA_DQS_DP<0>")
	)
	(segment
		(start 81.51241 -223.749616)
		(end 81.55051 -223.771714)
		(width 0.09525)
		(layer "In2.Cu")
		(net "M_C_CPU1_SA_DQS_DP<0>")
	)
	(segment
		(start 83.360006 -226.970844)
		(end 83.392518 -226.98964)
		(width 0.09525)
		(layer "In2.Cu")
		(net "M_C_CPU1_SA_DQS_DP<0>")
	)
	(segment
		(start 44.340018 -200.735438)
		(end 44.61383 -201.00925)
		(width 0.16002)
		(layer "In2.Cu")
		(net "M_C_CPU1_SA_DQS_DP<0>")
	)
	(segment
		(start 73.028302 -210.828128)
		(end 73.210928 -210.645502)
		(width 0.16002)
		(layer "In2.Cu")
		(net "M_C_CPU1_SA_DQS_DP<0>")
	)
	(segment
		(start 73.631806 -212.0265)
		(end 73.631806 -212.30336)
		(width 0.16002)
		(layer "In2.Cu")
		(net "M_C_CPU1_SA_DQS_DP<0>")
	)
	(segment
		(start 94.051628 -227.016818)
		(end 94.074996 -226.92995)
		(width 0.09525)
		(layer "In2.Cu")
		(net "M_C_CPU1_SA_DQS_DP<0>")
	)
	(segment
		(start 81.950052 -224.540826)
		(end 81.982564 -224.559622)
		(width 0.09525)
		(layer "In2.Cu")
		(net "M_C_CPU1_SA_DQS_DP<0>")
	)
	(segment
		(start 50.703988 -200.321672)
		(end 51.015392 -200.010268)
		(width 0.16002)
		(layer "In2.Cu")
		(net "M_C_CPU1_SA_DQS_DP<0>")
	)
	(segment
		(start 81.04251 -222.93961)
		(end 81.08061 -222.961708)
		(width 0.09525)
		(layer "In2.Cu")
		(net "M_C_CPU1_SA_DQS_DP<0>")
	)
	(segment
		(start 50.297588 -200.321672)
		(end 50.703988 -200.321672)
		(width 0.16002)
		(layer "In2.Cu")
		(net "M_C_CPU1_SA_DQS_DP<0>")
	)
	(segment
		(start 62.061852 -202.226926)
		(end 62.338712 -202.226926)
		(width 0.16002)
		(layer "In2.Cu")
		(net "M_C_CPU1_SA_DQS_DP<0>")
	)
	(segment
		(start 80.442054 -219.113608)
		(end 80.442054 -221.174564)
		(width 0.16002)
		(layer "In2.Cu")
		(net "M_C_CPU1_SA_DQS_DP<0>")
	)
	(segment
		(start 58.138568 -200.395332)
		(end 58.489088 -200.044812)
		(width 0.16002)
		(layer "In2.Cu")
		(net "M_C_CPU1_SA_DQS_DP<0>")
	)
	(segment
		(start 80.57388 -222.130112)
		(end 80.605122 -222.148146)
		(width 0.09525)
		(layer "In2.Cu")
		(net "M_C_CPU1_SA_DQS_DP<0>")
	)
	(segment
		(start 45.501814 -201.00925)
		(end 45.926756 -200.584308)
		(width 0.16002)
		(layer "In2.Cu")
		(net "M_C_CPU1_SA_DQS_DP<0>")
	)
	(segment
		(start 90.912442 -226.98964)
		(end 90.920824 -226.994466)
		(width 0.09525)
		(layer "In2.Cu")
		(net "M_C_CPU1_SA_DQS_DP<0>")
	)
	(segment
		(start 51.015392 -200.010268)
		(end 53.132228 -200.010268)
		(width 0.16002)
		(layer "In2.Cu")
		(net "M_C_CPU1_SA_DQS_DP<0>")
	)
	(segment
		(start 80.442054 -221.198186)
		(end 80.382872 -221.257368)
		(width 0.09525)
		(layer "In2.Cu")
		(net "M_C_CPU1_SA_DQS_DP<0>")
	)
	(segment
		(start 44.61383 -201.00925)
		(end 45.501814 -201.00925)
		(width 0.16002)
		(layer "In2.Cu")
		(net "M_C_CPU1_SA_DQS_DP<0>")
	)
	(segment
		(start 62.532514 -200.558908)
		(end 62.532514 -201.086212)
		(width 0.16002)
		(layer "In2.Cu")
		(net "M_C_CPU1_SA_DQS_DP<0>")
	)
	(segment
		(start 80.382872 -221.257368)
		(end 80.382872 -221.80423)
		(width 0.09525)
		(layer "In2.Cu")
		(net "M_C_CPU1_SA_DQS_DP<0>")
	)
	(segment
		(start 74.58456 -212.019134)
		(end 75.111356 -212.01888)
		(width 0.16002)
		(layer "In2.Cu")
		(net "M_C_CPU1_SA_DQS_DP<0>")
	)
	(segment
		(start 91.852496 -226.98964)
		(end 91.860878 -226.994466)
		(width 0.09525)
		(layer "In2.Cu")
		(net "M_C_CPU1_SA_DQS_DP<0>")
	)
	(segment
		(start 55.916068 -200.584308)
		(end 56.524652 -201.192892)
		(width 0.16002)
		(layer "In2.Cu")
		(net "M_C_CPU1_SA_DQS_DP<0>")
	)
	(segment
		(start 94.074996 -226.92995)
		(end 93.921072 -226.66452)
		(width 0.09525)
		(layer "In2.Cu")
		(net "M_C_CPU1_SA_DQS_DP<0>")
	)
	(segment
		(start 81.982564 -224.559622)
		(end 82.017616 -224.580196)
		(width 0.09525)
		(layer "In2.Cu")
		(net "M_C_CPU1_SA_DQS_DP<0>")
	)
	(segment
		(start 87.15248 -226.98964)
		(end 87.160862 -226.994466)
		(width 0.09525)
		(layer "In2.Cu")
		(net "M_C_CPU1_SA_DQS_DP<0>")
	)
	(segment
		(start 83.392518 -226.98964)
		(end 83.4009 -226.994466)
		(width 0.09525)
		(layer "In2.Cu")
		(net "M_C_CPU1_SA_DQS_DP<0>")
	)
	(segment
		(start 74.1045 -212.499194)
		(end 74.58456 -212.019134)
		(width 0.16002)
		(layer "In2.Cu")
		(net "M_C_CPU1_SA_DQS_DP<0>")
	)
	(segment
		(start 90.341196 -226.994466)
		(end 90.349578 -226.98964)
		(width 0.09525)
		(layer "In2.Cu")
		(net "M_C_CPU1_SA_DQS_DP<0>")
	)
	(segment
		(start 82.922364 -226.179634)
		(end 82.960464 -226.201732)
		(width 0.09525)
		(layer "In2.Cu")
		(net "M_C_CPU1_SA_DQS_DP<0>")
	)
	(segment
		(start 80.478376 -222.034608)
		(end 80.573118 -222.129604)
		(width 0.09525)
		(layer "In2.Cu")
		(net "M_C_CPU1_SA_DQS_DP<0>")
	)
	(segment
		(start 74.111866 -211.54644)
		(end 73.631806 -212.0265)
		(width 0.16002)
		(layer "In2.Cu")
		(net "M_C_CPU1_SA_DQS_DP<0>")
	)
	(segment
		(start 72.801734 -210.828128)
		(end 73.028302 -210.828128)
		(width 0.16002)
		(layer "In2.Cu")
		(net "M_C_CPU1_SA_DQS_DP<0>")
	)
	(segment
		(start 81.480914 -223.731328)
		(end 81.51241 -223.749616)
		(width 0.09525)
		(layer "In2.Cu")
		(net "M_C_CPU1_SA_DQS_DP<0>")
	)
	(segment
		(start 86.581234 -226.994466)
		(end 86.589616 -226.98964)
		(width 0.09525)
		(layer "In2.Cu")
		(net "M_C_CPU1_SA_DQS_DP<0>")
	)
	(segment
		(start 75.111356 -212.01888)
		(end 75.485244 -212.392768)
		(width 0.16002)
		(layer "In2.Cu")
		(net "M_C_CPU1_SA_DQS_DP<0>")
	)
	(segment
		(start 53.706268 -200.584308)
		(end 55.916068 -200.584308)
		(width 0.16002)
		(layer "In2.Cu")
		(net "M_C_CPU1_SA_DQS_DP<0>")
	)
	(segment
		(start 80.573118 -222.129604)
		(end 80.57388 -222.130112)
		(width 0.09525)
		(layer "In2.Cu")
		(net "M_C_CPU1_SA_DQS_DP<0>")
	)
	(segment
		(start 75.005438 -213.676992)
		(end 80.442054 -219.113608)
		(width 0.16002)
		(layer "In2.Cu")
		(net "M_C_CPU1_SA_DQS_DP<0>")
	)
	(segment
		(start 82.890868 -226.161346)
		(end 82.922364 -226.179634)
		(width 0.09525)
		(layer "In2.Cu")
		(net "M_C_CPU1_SA_DQS_DP<0>")
	)
	(segment
		(start 75.485498 -212.920072)
		(end 75.005438 -213.400132)
		(width 0.16002)
		(layer "In2.Cu")
		(net "M_C_CPU1_SA_DQS_DP<0>")
	)
	(segment
		(start 62.018418 -200.044812)
		(end 62.532514 -200.558908)
		(width 0.16002)
		(layer "In2.Cu")
		(net "M_C_CPU1_SA_DQS_DP<0>")
	)
	(segment
		(start 75.485244 -212.392768)
		(end 75.485498 -212.920072)
		(width 0.16002)
		(layer "In2.Cu")
		(net "M_C_CPU1_SA_DQS_DP<0>")
	)
	(segment
		(start 73.737978 -210.645502)
		(end 74.111612 -211.019136)
		(width 0.16002)
		(layer "In2.Cu")
		(net "M_C_CPU1_SA_DQS_DP<0>")
	)
	(segment
		(start 62.338712 -202.226926)
		(end 63.00597 -201.559668)
		(width 0.16002)
		(layer "In2.Cu")
		(net "M_C_CPU1_SA_DQS_DP<0>")
	)
	(segment
		(start 49.444148 -201.175112)
		(end 50.297588 -200.321672)
		(width 0.16002)
		(layer "In2.Cu")
		(net "M_C_CPU1_SA_DQS_DP<0>")
	)
	(segment
		(start 56.524652 -201.192892)
		(end 56.863488 -201.192892)
		(width 0.16002)
		(layer "In2.Cu")
		(net "M_C_CPU1_SA_DQS_DP<0>")
	)
	(segment
		(start 56.863488 -201.192892)
		(end 57.661048 -200.395332)
		(width 0.16002)
		(layer "In2.Cu")
		(net "M_C_CPU1_SA_DQS_DP<0>")
	)
	(segment
		(start 85.64118 -226.994466)
		(end 85.649562 -226.98964)
		(width 0.09525)
		(layer "In2.Cu")
		(net "M_C_CPU1_SA_DQS_DP<0>")
	)
	(segment
		(start 48.402748 -200.584308)
		(end 48.993552 -201.175112)
		(width 0.16002)
		(layer "In2.Cu")
		(net "M_C_CPU1_SA_DQS_DP<0>")
	)
	(segment
		(start 45.926756 -200.584308)
		(end 48.402748 -200.584308)
		(width 0.16002)
		(layer "In2.Cu")
		(net "M_C_CPU1_SA_DQS_DP<0>")
	)
	(segment
		(start 63.533274 -201.559668)
		(end 72.801734 -210.828128)
		(width 0.16002)
		(layer "In2.Cu")
		(net "M_C_CPU1_SA_DQS_DP<0>")
	)
	(segment
		(start 88.092534 -226.98964)
		(end 88.100916 -226.994466)
		(width 0.09525)
		(layer "In2.Cu")
		(net "M_C_CPU1_SA_DQS_DP<0>")
	)
	(segment
		(start 82.419952 -225.350832)
		(end 82.452464 -225.369628)
		(width 0.09525)
		(layer "In2.Cu")
		(net "M_C_CPU1_SA_DQS_DP<0>")
	)
	(arc
		(start 81.08061 -222.961708)
		(mid 81.25906 -223.163178)
		(end 81.323434 -223.424496)
		(width 0.09525)
		(layer "In2.Cu")
		(net "M_C_CPU1_SA_DQS_DP<0>")
	)
	(arc
		(start 80.853534 -222.61449)
		(mid 80.895556 -222.787569)
		(end 81.012284 -222.922084)
		(width 0.09525)
		(layer "In2.Cu")
		(net "M_C_CPU1_SA_DQS_DP<0>")
	)
	(arc
		(start 81.55051 -223.771714)
		(mid 81.72896 -223.973184)
		(end 81.793334 -224.234502)
		(width 0.09525)
		(layer "In2.Cu")
		(net "M_C_CPU1_SA_DQS_DP<0>")
	)
	(arc
		(start 86.589616 -226.98964)
		(mid 86.871048 -226.913885)
		(end 87.15248 -226.98964)
		(width 0.09525)
		(layer "In2.Cu")
		(net "M_C_CPU1_SA_DQS_DP<0>")
	)
	(arc
		(start 80.605122 -222.148146)
		(mid 80.787587 -222.350291)
		(end 80.853534 -222.61449)
		(width 0.09525)
		(layer "In2.Cu")
		(net "M_C_CPU1_SA_DQS_DP<0>")
	)
	(arc
		(start 91.289632 -226.98964)
		(mid 91.571064 -226.913885)
		(end 91.852496 -226.98964)
		(width 0.09525)
		(layer "In2.Cu")
		(net "M_C_CPU1_SA_DQS_DP<0>")
	)
	(arc
		(start 82.017616 -224.580196)
		(mid 82.198071 -224.781862)
		(end 82.263234 -225.044508)
		(width 0.09525)
		(layer "In2.Cu")
		(net "M_C_CPU1_SA_DQS_DP<0>")
	)
	(arc
		(start 86.212426 -226.98964)
		(mid 86.396201 -227.040412)
		(end 86.581234 -226.994466)
		(width 0.09525)
		(layer "In2.Cu")
		(net "M_C_CPU1_SA_DQS_DP<0>")
	)
	(arc
		(start 82.733388 -225.854514)
		(mid 82.775053 -226.026961)
		(end 82.890868 -226.161346)
		(width 0.09525)
		(layer "In2.Cu")
		(net "M_C_CPU1_SA_DQS_DP<0>")
	)
	(arc
		(start 89.972388 -226.98964)
		(mid 90.156163 -227.040412)
		(end 90.341196 -226.994466)
		(width 0.09525)
		(layer "In2.Cu")
		(net "M_C_CPU1_SA_DQS_DP<0>")
	)
	(arc
		(start 83.769708 -226.98964)
		(mid 84.05114 -226.913885)
		(end 84.332572 -226.98964)
		(width 0.09525)
		(layer "In2.Cu")
		(net "M_C_CPU1_SA_DQS_DP<0>")
	)
	(arc
		(start 83.4009 -226.994466)
		(mid 83.585932 -227.04038)
		(end 83.769708 -226.98964)
		(width 0.09525)
		(layer "In2.Cu")
		(net "M_C_CPU1_SA_DQS_DP<0>")
	)
	(arc
		(start 88.100916 -226.994466)
		(mid 88.285948 -227.04038)
		(end 88.469724 -226.98964)
		(width 0.09525)
		(layer "In2.Cu")
		(net "M_C_CPU1_SA_DQS_DP<0>")
	)
	(arc
		(start 91.860878 -226.994466)
		(mid 92.04591 -227.04038)
		(end 92.229686 -226.98964)
		(width 0.09525)
		(layer "In2.Cu")
		(net "M_C_CPU1_SA_DQS_DP<0>")
	)
	(arc
		(start 85.272372 -226.98964)
		(mid 85.456147 -227.040412)
		(end 85.64118 -226.994466)
		(width 0.09525)
		(layer "In2.Cu")
		(net "M_C_CPU1_SA_DQS_DP<0>")
	)
	(arc
		(start 92.229686 -226.98964)
		(mid 92.511118 -226.913885)
		(end 92.79255 -226.98964)
		(width 0.09525)
		(layer "In2.Cu")
		(net "M_C_CPU1_SA_DQS_DP<0>")
	)
	(arc
		(start 93.73235 -226.98964)
		(mid 93.888948 -227.038929)
		(end 94.051628 -227.016818)
		(width 0.09525)
		(layer "In2.Cu")
		(net "M_C_CPU1_SA_DQS_DP<0>")
	)
	(arc
		(start 92.79255 -226.98964)
		(mid 92.981018 -227.040317)
		(end 93.169486 -226.98964)
		(width 0.09525)
		(layer "In2.Cu")
		(net "M_C_CPU1_SA_DQS_DP<0>")
	)
	(arc
		(start 82.490564 -225.391726)
		(mid 82.669014 -225.593196)
		(end 82.733388 -225.854514)
		(width 0.09525)
		(layer "In2.Cu")
		(net "M_C_CPU1_SA_DQS_DP<0>")
	)
	(arc
		(start 87.52967 -226.98964)
		(mid 87.811102 -226.913885)
		(end 88.092534 -226.98964)
		(width 0.09525)
		(layer "In2.Cu")
		(net "M_C_CPU1_SA_DQS_DP<0>")
	)
	(arc
		(start 84.332572 -226.98964)
		(mid 84.52104 -227.040317)
		(end 84.709508 -226.98964)
		(width 0.09525)
		(layer "In2.Cu")
		(net "M_C_CPU1_SA_DQS_DP<0>")
	)
	(arc
		(start 85.649562 -226.98964)
		(mid 85.930994 -226.913885)
		(end 86.212426 -226.98964)
		(width 0.09525)
		(layer "In2.Cu")
		(net "M_C_CPU1_SA_DQS_DP<0>")
	)
	(arc
		(start 84.709508 -226.98964)
		(mid 84.99094 -226.913885)
		(end 85.272372 -226.98964)
		(width 0.09525)
		(layer "In2.Cu")
		(net "M_C_CPU1_SA_DQS_DP<0>")
	)
	(arc
		(start 87.160862 -226.994466)
		(mid 87.345894 -227.04038)
		(end 87.52967 -226.98964)
		(width 0.09525)
		(layer "In2.Cu")
		(net "M_C_CPU1_SA_DQS_DP<0>")
	)
	(arc
		(start 89.032588 -226.98964)
		(mid 89.221056 -227.040317)
		(end 89.409524 -226.98964)
		(width 0.09525)
		(layer "In2.Cu")
		(net "M_C_CPU1_SA_DQS_DP<0>")
	)
	(arc
		(start 82.960464 -226.201732)
		(mid 83.138914 -226.403202)
		(end 83.203288 -226.66452)
		(width 0.09525)
		(layer "In2.Cu")
		(net "M_C_CPU1_SA_DQS_DP<0>")
	)
	(arc
		(start 93.169486 -226.98964)
		(mid 93.450918 -226.913885)
		(end 93.73235 -226.98964)
		(width 0.09525)
		(layer "In2.Cu")
		(net "M_C_CPU1_SA_DQS_DP<0>")
	)
	(arc
		(start 81.793334 -224.234502)
		(mid 81.834791 -224.406542)
		(end 81.950052 -224.540826)
		(width 0.09525)
		(layer "In2.Cu")
		(net "M_C_CPU1_SA_DQS_DP<0>")
	)
	(arc
		(start 81.323434 -223.424496)
		(mid 81.365099 -223.596943)
		(end 81.480914 -223.731328)
		(width 0.09525)
		(layer "In2.Cu")
		(net "M_C_CPU1_SA_DQS_DP<0>")
	)
	(arc
		(start 88.469724 -226.98964)
		(mid 88.751156 -226.913885)
		(end 89.032588 -226.98964)
		(width 0.09525)
		(layer "In2.Cu")
		(net "M_C_CPU1_SA_DQS_DP<0>")
	)
	(arc
		(start 89.409524 -226.98964)
		(mid 89.690956 -226.913885)
		(end 89.972388 -226.98964)
		(width 0.09525)
		(layer "In2.Cu")
		(net "M_C_CPU1_SA_DQS_DP<0>")
	)
	(arc
		(start 80.382872 -221.80423)
		(mid 80.407784 -221.928889)
		(end 80.478376 -222.034608)
		(width 0.09525)
		(layer "In2.Cu")
		(net "M_C_CPU1_SA_DQS_DP<0>")
	)
	(arc
		(start 82.263234 -225.044508)
		(mid 82.304691 -225.216548)
		(end 82.419952 -225.350832)
		(width 0.09525)
		(layer "In2.Cu")
		(net "M_C_CPU1_SA_DQS_DP<0>")
	)
	(arc
		(start 83.203288 -226.66452)
		(mid 83.244745 -226.83656)
		(end 83.360006 -226.970844)
		(width 0.09525)
		(layer "In2.Cu")
		(net "M_C_CPU1_SA_DQS_DP<0>")
	)
	(arc
		(start 90.920824 -226.994466)
		(mid 91.105856 -227.04038)
		(end 91.289632 -226.98964)
		(width 0.09525)
		(layer "In2.Cu")
		(net "M_C_CPU1_SA_DQS_DP<0>")
	)
	(arc
		(start 90.349578 -226.98964)
		(mid 90.63101 -226.913885)
		(end 90.912442 -226.98964)
		(width 0.09525)
		(layer "In2.Cu")
		(net "M_C_CPU1_SA_DQS_DP<0>")
	)
	(segment
		(start 95.797878 -247.180354)
		(end 95.331026 -246.914416)
		(width 0.12954)
		(layer "F.Cu")
		(net "M_C_CPU1_SA_DQS_DN<9>")
	)
	(segment
		(start 79.541624 -247.239282)
		(end 79.567532 -247.224296)
		(width 0.09525)
		(layer "In2.Cu")
		(net "M_C_CPU1_SA_DQS_DN<9>")
	)
	(segment
		(start 76.150724 -247.23217)
		(end 76.181712 -247.263158)
		(width 0.09525)
		(layer "In2.Cu")
		(net "M_C_CPU1_SA_DQS_DN<9>")
	)
	(segment
		(start 54.322472 -240.231168)
		(end 56.101488 -240.231168)
		(width 0.16002)
		(layer "In2.Cu")
		(net "M_C_CPU1_SA_DQS_DN<9>")
	)
	(segment
		(start 43.839384 -239.667542)
		(end 46.174406 -239.667542)
		(width 0.16002)
		(layer "In2.Cu")
		(net "M_C_CPU1_SA_DQS_DN<9>")
	)
	(segment
		(start 66.928238 -246.195596)
		(end 67.376548 -246.643906)
		(width 0.16002)
		(layer "In2.Cu")
		(net "M_C_CPU1_SA_DQS_DN<9>")
	)
	(segment
		(start 79.139796 -247.224296)
		(end 79.165958 -247.239536)
		(width 0.09525)
		(layer "In2.Cu")
		(net "M_C_CPU1_SA_DQS_DN<9>")
	)
	(segment
		(start 50.819812 -239.080548)
		(end 51.147472 -239.408208)
		(width 0.16002)
		(layer "In2.Cu")
		(net "M_C_CPU1_SA_DQS_DN<9>")
	)
	(segment
		(start 60.10021 -239.367568)
		(end 66.42354 -245.690898)
		(width 0.16002)
		(layer "In2.Cu")
		(net "M_C_CPU1_SA_DQS_DN<9>")
	)
	(segment
		(start 48.862488 -239.933988)
		(end 49.352708 -239.933988)
		(width 0.16002)
		(layer "In2.Cu")
		(net "M_C_CPU1_SA_DQS_DN<9>")
	)
	(segment
		(start 58.378598 -239.108996)
		(end 58.63717 -239.367568)
		(width 0.16002)
		(layer "In2.Cu")
		(net "M_C_CPU1_SA_DQS_DN<9>")
	)
	(segment
		(start 66.928238 -246.030496)
		(end 66.928238 -246.195596)
		(width 0.16002)
		(layer "In2.Cu")
		(net "M_C_CPU1_SA_DQS_DN<9>")
	)
	(segment
		(start 80.471264 -247.244362)
		(end 80.479646 -247.239536)
		(width 0.09525)
		(layer "In2.Cu")
		(net "M_C_CPU1_SA_DQS_DN<9>")
	)
	(segment
		(start 84.231226 -247.244362)
		(end 84.239608 -247.239536)
		(width 0.09525)
		(layer "In2.Cu")
		(net "M_C_CPU1_SA_DQS_DN<9>")
	)
	(segment
		(start 66.42354 -245.690898)
		(end 66.58864 -245.690898)
		(width 0.16002)
		(layer "In2.Cu")
		(net "M_C_CPU1_SA_DQS_DN<9>")
	)
	(segment
		(start 67.376548 -246.643906)
		(end 74.766424 -246.643906)
		(width 0.16002)
		(layer "In2.Cu")
		(net "M_C_CPU1_SA_DQS_DN<9>")
	)
	(segment
		(start 78.224126 -247.239282)
		(end 78.2574 -247.258332)
		(width 0.09525)
		(layer "In2.Cu")
		(net "M_C_CPU1_SA_DQS_DN<9>")
	)
	(segment
		(start 57.73674 -239.108996)
		(end 58.378598 -239.108996)
		(width 0.16002)
		(layer "In2.Cu")
		(net "M_C_CPU1_SA_DQS_DN<9>")
	)
	(segment
		(start 79.51978 -247.251728)
		(end 79.541624 -247.239282)
		(width 0.09525)
		(layer "In2.Cu")
		(net "M_C_CPU1_SA_DQS_DN<9>")
	)
	(segment
		(start 40.23995 -238.985298)
		(end 40.514016 -239.259364)
		(width 0.16002)
		(layer "In2.Cu")
		(net "M_C_CPU1_SA_DQS_DN<9>")
	)
	(segment
		(start 81.04251 -247.239536)
		(end 81.050892 -247.244362)
		(width 0.09525)
		(layer "In2.Cu")
		(net "M_C_CPU1_SA_DQS_DN<9>")
	)
	(segment
		(start 76.249022 -247.291098)
		(end 77.474572 -247.291098)
		(width 0.09525)
		(layer "In2.Cu")
		(net "M_C_CPU1_SA_DQS_DN<9>")
	)
	(segment
		(start 50.206148 -239.080548)
		(end 50.819812 -239.080548)
		(width 0.16002)
		(layer "In2.Cu")
		(net "M_C_CPU1_SA_DQS_DN<9>")
	)
	(segment
		(start 89.502488 -247.239536)
		(end 89.51087 -247.244362)
		(width 0.09525)
		(layer "In2.Cu")
		(net "M_C_CPU1_SA_DQS_DN<9>")
	)
	(segment
		(start 66.58864 -245.690898)
		(end 66.928238 -246.030496)
		(width 0.16002)
		(layer "In2.Cu")
		(net "M_C_CPU1_SA_DQS_DN<9>")
	)
	(segment
		(start 48.53813 -240.258346)
		(end 48.862488 -239.933988)
		(width 0.16002)
		(layer "In2.Cu")
		(net "M_C_CPU1_SA_DQS_DN<9>")
	)
	(segment
		(start 92.691204 -247.244362)
		(end 92.699586 -247.239536)
		(width 0.09525)
		(layer "In2.Cu")
		(net "M_C_CPU1_SA_DQS_DN<9>")
	)
	(segment
		(start 41.907206 -239.259364)
		(end 42.106342 -239.060228)
		(width 0.16002)
		(layer "In2.Cu")
		(net "M_C_CPU1_SA_DQS_DN<9>")
	)
	(segment
		(start 56.934608 -239.911128)
		(end 57.73674 -239.108996)
		(width 0.16002)
		(layer "In2.Cu")
		(net "M_C_CPU1_SA_DQS_DN<9>")
	)
	(segment
		(start 42.106342 -239.060228)
		(end 43.23207 -239.060228)
		(width 0.16002)
		(layer "In2.Cu")
		(net "M_C_CPU1_SA_DQS_DN<9>")
	)
	(segment
		(start 58.63717 -239.367568)
		(end 60.10021 -239.367568)
		(width 0.16002)
		(layer "In2.Cu")
		(net "M_C_CPU1_SA_DQS_DN<9>")
	)
	(segment
		(start 46.174406 -239.667542)
		(end 46.76521 -240.258346)
		(width 0.16002)
		(layer "In2.Cu")
		(net "M_C_CPU1_SA_DQS_DN<9>")
	)
	(segment
		(start 51.147472 -239.408208)
		(end 53.499512 -239.408208)
		(width 0.16002)
		(layer "In2.Cu")
		(net "M_C_CPU1_SA_DQS_DN<9>")
	)
	(segment
		(start 43.23207 -239.060228)
		(end 43.839384 -239.667542)
		(width 0.16002)
		(layer "In2.Cu")
		(net "M_C_CPU1_SA_DQS_DN<9>")
	)
	(segment
		(start 56.421528 -239.911128)
		(end 56.934608 -239.911128)
		(width 0.16002)
		(layer "In2.Cu")
		(net "M_C_CPU1_SA_DQS_DN<9>")
	)
	(segment
		(start 95.48495 -247.179846)
		(end 95.331026 -246.914416)
		(width 0.09525)
		(layer "In2.Cu")
		(net "M_C_CPU1_SA_DQS_DN<9>")
	)
	(segment
		(start 95.461836 -247.26646)
		(end 95.48495 -247.179846)
		(width 0.09525)
		(layer "In2.Cu")
		(net "M_C_CPU1_SA_DQS_DN<9>")
	)
	(segment
		(start 93.26245 -247.239536)
		(end 93.270832 -247.244362)
		(width 0.09525)
		(layer "In2.Cu")
		(net "M_C_CPU1_SA_DQS_DN<9>")
	)
	(segment
		(start 85.742526 -247.239536)
		(end 85.750908 -247.244362)
		(width 0.09525)
		(layer "In2.Cu")
		(net "M_C_CPU1_SA_DQS_DN<9>")
	)
	(segment
		(start 78.198218 -247.224296)
		(end 78.224126 -247.239282)
		(width 0.09525)
		(layer "In2.Cu")
		(net "M_C_CPU1_SA_DQS_DN<9>")
	)
	(segment
		(start 40.514016 -239.259364)
		(end 41.907206 -239.259364)
		(width 0.16002)
		(layer "In2.Cu")
		(net "M_C_CPU1_SA_DQS_DN<9>")
	)
	(segment
		(start 83.291172 -247.244362)
		(end 83.299554 -247.239536)
		(width 0.09525)
		(layer "In2.Cu")
		(net "M_C_CPU1_SA_DQS_DN<9>")
	)
	(segment
		(start 75.354688 -247.23217)
		(end 76.127102 -247.23217)
		(width 0.16002)
		(layer "In2.Cu")
		(net "M_C_CPU1_SA_DQS_DN<9>")
	)
	(segment
		(start 84.802472 -247.239536)
		(end 84.810854 -247.244362)
		(width 0.09525)
		(layer "In2.Cu")
		(net "M_C_CPU1_SA_DQS_DN<9>")
	)
	(segment
		(start 76.127102 -247.23217)
		(end 76.150724 -247.23217)
		(width 0.09525)
		(layer "In2.Cu")
		(net "M_C_CPU1_SA_DQS_DN<9>")
	)
	(segment
		(start 94.202504 -247.239536)
		(end 94.210886 -247.244362)
		(width 0.09525)
		(layer "In2.Cu")
		(net "M_C_CPU1_SA_DQS_DN<9>")
	)
	(segment
		(start 56.101488 -240.231168)
		(end 56.421528 -239.911128)
		(width 0.16002)
		(layer "In2.Cu")
		(net "M_C_CPU1_SA_DQS_DN<9>")
	)
	(segment
		(start 53.499512 -239.408208)
		(end 54.322472 -240.231168)
		(width 0.16002)
		(layer "In2.Cu")
		(net "M_C_CPU1_SA_DQS_DN<9>")
	)
	(segment
		(start 87.991188 -247.244362)
		(end 87.99957 -247.239536)
		(width 0.09525)
		(layer "In2.Cu")
		(net "M_C_CPU1_SA_DQS_DN<9>")
	)
	(segment
		(start 49.352708 -239.933988)
		(end 50.206148 -239.080548)
		(width 0.16002)
		(layer "In2.Cu")
		(net "M_C_CPU1_SA_DQS_DN<9>")
	)
	(segment
		(start 88.931242 -247.244362)
		(end 88.939624 -247.239536)
		(width 0.09525)
		(layer "In2.Cu")
		(net "M_C_CPU1_SA_DQS_DN<9>")
	)
	(segment
		(start 74.766424 -246.643906)
		(end 75.354688 -247.23217)
		(width 0.16002)
		(layer "In2.Cu")
		(net "M_C_CPU1_SA_DQS_DN<9>")
	)
	(segment
		(start 46.76521 -240.258346)
		(end 48.53813 -240.258346)
		(width 0.16002)
		(layer "In2.Cu")
		(net "M_C_CPU1_SA_DQS_DN<9>")
	)
	(segment
		(start 91.75115 -247.244362)
		(end 91.759532 -247.239536)
		(width 0.09525)
		(layer "In2.Cu")
		(net "M_C_CPU1_SA_DQS_DN<9>")
	)
	(arc
		(start 90.819478 -247.239536)
		(mid 91.10091 -247.163781)
		(end 91.382342 -247.239536)
		(width 0.09525)
		(layer "In2.Cu")
		(net "M_C_CPU1_SA_DQS_DN<9>")
	)
	(arc
		(start 81.4197 -247.239536)
		(mid 81.701132 -247.163781)
		(end 81.982564 -247.239536)
		(width 0.09525)
		(layer "In2.Cu")
		(net "M_C_CPU1_SA_DQS_DN<9>")
	)
	(arc
		(start 90.442542 -247.239536)
		(mid 90.63101 -247.290213)
		(end 90.819478 -247.239536)
		(width 0.09525)
		(layer "In2.Cu")
		(net "M_C_CPU1_SA_DQS_DN<9>")
	)
	(arc
		(start 87.99957 -247.239536)
		(mid 88.281002 -247.163781)
		(end 88.562434 -247.239536)
		(width 0.09525)
		(layer "In2.Cu")
		(net "M_C_CPU1_SA_DQS_DN<9>")
	)
	(arc
		(start 82.922364 -247.239536)
		(mid 83.106139 -247.290308)
		(end 83.291172 -247.244362)
		(width 0.09525)
		(layer "In2.Cu")
		(net "M_C_CPU1_SA_DQS_DN<9>")
	)
	(arc
		(start 79.567532 -247.224296)
		(mid 79.836938 -247.163948)
		(end 80.102456 -247.239536)
		(width 0.09525)
		(layer "In2.Cu")
		(net "M_C_CPU1_SA_DQS_DN<9>")
	)
	(arc
		(start 81.982564 -247.239536)
		(mid 82.171032 -247.290213)
		(end 82.3595 -247.239536)
		(width 0.09525)
		(layer "In2.Cu")
		(net "M_C_CPU1_SA_DQS_DN<9>")
	)
	(arc
		(start 80.102456 -247.239536)
		(mid 80.286231 -247.290308)
		(end 80.471264 -247.244362)
		(width 0.09525)
		(layer "In2.Cu")
		(net "M_C_CPU1_SA_DQS_DN<9>")
	)
	(arc
		(start 84.239608 -247.239536)
		(mid 84.52104 -247.163781)
		(end 84.802472 -247.239536)
		(width 0.09525)
		(layer "In2.Cu")
		(net "M_C_CPU1_SA_DQS_DN<9>")
	)
	(arc
		(start 85.179662 -247.239536)
		(mid 85.461094 -247.163781)
		(end 85.742526 -247.239536)
		(width 0.09525)
		(layer "In2.Cu")
		(net "M_C_CPU1_SA_DQS_DN<9>")
	)
	(arc
		(start 88.562434 -247.239536)
		(mid 88.746209 -247.290308)
		(end 88.931242 -247.244362)
		(width 0.09525)
		(layer "In2.Cu")
		(net "M_C_CPU1_SA_DQS_DN<9>")
	)
	(arc
		(start 89.51087 -247.244362)
		(mid 89.695902 -247.290276)
		(end 89.879678 -247.239536)
		(width 0.09525)
		(layer "In2.Cu")
		(net "M_C_CPU1_SA_DQS_DN<9>")
	)
	(arc
		(start 93.63964 -247.239536)
		(mid 93.921072 -247.163781)
		(end 94.202504 -247.239536)
		(width 0.09525)
		(layer "In2.Cu")
		(net "M_C_CPU1_SA_DQS_DN<9>")
	)
	(arc
		(start 83.862418 -247.239536)
		(mid 84.046193 -247.290308)
		(end 84.231226 -247.244362)
		(width 0.09525)
		(layer "In2.Cu")
		(net "M_C_CPU1_SA_DQS_DN<9>")
	)
	(arc
		(start 84.810854 -247.244362)
		(mid 84.995886 -247.290276)
		(end 85.179662 -247.239536)
		(width 0.09525)
		(layer "In2.Cu")
		(net "M_C_CPU1_SA_DQS_DN<9>")
	)
	(arc
		(start 78.601062 -247.23979)
		(mid 78.868441 -247.163208)
		(end 79.139796 -247.224296)
		(width 0.09525)
		(layer "In2.Cu")
		(net "M_C_CPU1_SA_DQS_DN<9>")
	)
	(arc
		(start 95.142558 -247.239536)
		(mid 95.299185 -247.288722)
		(end 95.461836 -247.26646)
		(width 0.09525)
		(layer "In2.Cu")
		(net "M_C_CPU1_SA_DQS_DN<9>")
	)
	(arc
		(start 79.165958 -247.239536)
		(mid 79.341332 -247.289866)
		(end 79.51978 -247.251728)
		(width 0.09525)
		(layer "In2.Cu")
		(net "M_C_CPU1_SA_DQS_DN<9>")
	)
	(arc
		(start 89.879678 -247.239536)
		(mid 90.16111 -247.163781)
		(end 90.442542 -247.239536)
		(width 0.09525)
		(layer "In2.Cu")
		(net "M_C_CPU1_SA_DQS_DN<9>")
	)
	(arc
		(start 77.474572 -247.291098)
		(mid 77.572328 -247.277764)
		(end 77.663294 -247.239536)
		(width 0.09525)
		(layer "In2.Cu")
		(net "M_C_CPU1_SA_DQS_DN<9>")
	)
	(arc
		(start 81.050892 -247.244362)
		(mid 81.235924 -247.290276)
		(end 81.4197 -247.239536)
		(width 0.09525)
		(layer "In2.Cu")
		(net "M_C_CPU1_SA_DQS_DN<9>")
	)
	(arc
		(start 87.059516 -247.239536)
		(mid 87.340948 -247.163781)
		(end 87.62238 -247.239536)
		(width 0.09525)
		(layer "In2.Cu")
		(net "M_C_CPU1_SA_DQS_DN<9>")
	)
	(arc
		(start 76.181712 -247.263158)
		(mid 76.21258 -247.283847)
		(end 76.249022 -247.291098)
		(width 0.09525)
		(layer "In2.Cu")
		(net "M_C_CPU1_SA_DQS_DN<9>")
	)
	(arc
		(start 93.270832 -247.244362)
		(mid 93.455864 -247.290276)
		(end 93.63964 -247.239536)
		(width 0.09525)
		(layer "In2.Cu")
		(net "M_C_CPU1_SA_DQS_DN<9>")
	)
	(arc
		(start 91.382342 -247.239536)
		(mid 91.566117 -247.290308)
		(end 91.75115 -247.244362)
		(width 0.09525)
		(layer "In2.Cu")
		(net "M_C_CPU1_SA_DQS_DN<9>")
	)
	(arc
		(start 94.210886 -247.244362)
		(mid 94.395918 -247.290276)
		(end 94.579694 -247.239536)
		(width 0.09525)
		(layer "In2.Cu")
		(net "M_C_CPU1_SA_DQS_DN<9>")
	)
	(arc
		(start 86.119716 -247.239536)
		(mid 86.401148 -247.163781)
		(end 86.68258 -247.239536)
		(width 0.09525)
		(layer "In2.Cu")
		(net "M_C_CPU1_SA_DQS_DN<9>")
	)
	(arc
		(start 92.322396 -247.239536)
		(mid 92.506171 -247.290308)
		(end 92.691204 -247.244362)
		(width 0.09525)
		(layer "In2.Cu")
		(net "M_C_CPU1_SA_DQS_DN<9>")
	)
	(arc
		(start 85.750908 -247.244362)
		(mid 85.93594 -247.290276)
		(end 86.119716 -247.239536)
		(width 0.09525)
		(layer "In2.Cu")
		(net "M_C_CPU1_SA_DQS_DN<9>")
	)
	(arc
		(start 86.68258 -247.239536)
		(mid 86.871048 -247.290213)
		(end 87.059516 -247.239536)
		(width 0.09525)
		(layer "In2.Cu")
		(net "M_C_CPU1_SA_DQS_DN<9>")
	)
	(arc
		(start 83.299554 -247.239536)
		(mid 83.580986 -247.163781)
		(end 83.862418 -247.239536)
		(width 0.09525)
		(layer "In2.Cu")
		(net "M_C_CPU1_SA_DQS_DN<9>")
	)
	(arc
		(start 77.663294 -247.239536)
		(mid 77.928814 -247.164007)
		(end 78.198218 -247.224296)
		(width 0.09525)
		(layer "In2.Cu")
		(net "M_C_CPU1_SA_DQS_DN<9>")
	)
	(arc
		(start 94.579694 -247.239536)
		(mid 94.861126 -247.163781)
		(end 95.142558 -247.239536)
		(width 0.09525)
		(layer "In2.Cu")
		(net "M_C_CPU1_SA_DQS_DN<9>")
	)
	(arc
		(start 87.62238 -247.239536)
		(mid 87.806155 -247.290308)
		(end 87.991188 -247.244362)
		(width 0.09525)
		(layer "In2.Cu")
		(net "M_C_CPU1_SA_DQS_DN<9>")
	)
	(arc
		(start 92.699586 -247.239536)
		(mid 92.981018 -247.163781)
		(end 93.26245 -247.239536)
		(width 0.09525)
		(layer "In2.Cu")
		(net "M_C_CPU1_SA_DQS_DN<9>")
	)
	(arc
		(start 80.479646 -247.239536)
		(mid 80.761078 -247.163781)
		(end 81.04251 -247.239536)
		(width 0.09525)
		(layer "In2.Cu")
		(net "M_C_CPU1_SA_DQS_DN<9>")
	)
	(arc
		(start 91.759532 -247.239536)
		(mid 92.040964 -247.163781)
		(end 92.322396 -247.239536)
		(width 0.09525)
		(layer "In2.Cu")
		(net "M_C_CPU1_SA_DQS_DN<9>")
	)
	(arc
		(start 82.3595 -247.239536)
		(mid 82.640932 -247.163781)
		(end 82.922364 -247.239536)
		(width 0.09525)
		(layer "In2.Cu")
		(net "M_C_CPU1_SA_DQS_DN<9>")
	)
	(arc
		(start 78.2574 -247.258332)
		(mid 78.431458 -247.29055)
		(end 78.601062 -247.23979)
		(width 0.09525)
		(layer "In2.Cu")
		(net "M_C_CPU1_SA_DQS_DN<9>")
	)
	(arc
		(start 88.939624 -247.239536)
		(mid 89.221056 -247.163781)
		(end 89.502488 -247.239536)
		(width 0.09525)
		(layer "In2.Cu")
		(net "M_C_CPU1_SA_DQS_DN<9>")
	)
	(segment
		(start 95.797878 -242.320318)
		(end 95.331026 -242.05438)
		(width 0.12954)
		(layer "F.Cu")
		(net "M_C_CPU1_SA_DQS_DN<8>")
	)
	(segment
		(start 40.23995 -229.635304)
		(end 40.514016 -229.90937)
		(width 0.16002)
		(layer "In2.Cu")
		(net "M_C_CPU1_SA_DQS_DN<8>")
	)
	(segment
		(start 78.224126 -242.379246)
		(end 78.2574 -242.398296)
		(width 0.09525)
		(layer "In2.Cu")
		(net "M_C_CPU1_SA_DQS_DN<8>")
	)
	(segment
		(start 44.980606 -230.317548)
		(end 45.097446 -230.200708)
		(width 0.16002)
		(layer "In2.Cu")
		(net "M_C_CPU1_SA_DQS_DN<8>")
	)
	(segment
		(start 58.378598 -229.759002)
		(end 58.63717 -230.017574)
		(width 0.16002)
		(layer "In2.Cu")
		(net "M_C_CPU1_SA_DQS_DN<8>")
	)
	(segment
		(start 45.097446 -230.200708)
		(end 45.577506 -230.200708)
		(width 0.16002)
		(layer "In2.Cu")
		(net "M_C_CPU1_SA_DQS_DN<8>")
	)
	(segment
		(start 71.961248 -240.953544)
		(end 75.955906 -240.953544)
		(width 0.16002)
		(layer "In2.Cu")
		(net "M_C_CPU1_SA_DQS_DN<8>")
	)
	(segment
		(start 93.26245 -242.3795)
		(end 93.270832 -242.384326)
		(width 0.09525)
		(layer "In2.Cu")
		(net "M_C_CPU1_SA_DQS_DN<8>")
	)
	(segment
		(start 80.471264 -242.384326)
		(end 80.479646 -242.3795)
		(width 0.09525)
		(layer "In2.Cu")
		(net "M_C_CPU1_SA_DQS_DN<8>")
	)
	(segment
		(start 41.907206 -229.90937)
		(end 42.106342 -229.710234)
		(width 0.16002)
		(layer "In2.Cu")
		(net "M_C_CPU1_SA_DQS_DN<8>")
	)
	(segment
		(start 83.291172 -242.384326)
		(end 83.299554 -242.3795)
		(width 0.09525)
		(layer "In2.Cu")
		(net "M_C_CPU1_SA_DQS_DN<8>")
	)
	(segment
		(start 79.163926 -242.379246)
		(end 79.18577 -242.391692)
		(width 0.09525)
		(layer "In2.Cu")
		(net "M_C_CPU1_SA_DQS_DN<8>")
	)
	(segment
		(start 77.439266 -241.345974)
		(end 77.439266 -241.613944)
		(width 0.09525)
		(layer "In2.Cu")
		(net "M_C_CPU1_SA_DQS_DN<8>")
	)
	(segment
		(start 79.127096 -242.35791)
		(end 79.163926 -242.379246)
		(width 0.09525)
		(layer "In2.Cu")
		(net "M_C_CPU1_SA_DQS_DN<8>")
	)
	(segment
		(start 40.514016 -229.90937)
		(end 41.907206 -229.90937)
		(width 0.16002)
		(layer "In2.Cu")
		(net "M_C_CPU1_SA_DQS_DN<8>")
	)
	(segment
		(start 56.914796 -230.561134)
		(end 57.716928 -229.759002)
		(width 0.16002)
		(layer "In2.Cu")
		(net "M_C_CPU1_SA_DQS_DN<8>")
	)
	(segment
		(start 85.742526 -242.3795)
		(end 85.750908 -242.384326)
		(width 0.09525)
		(layer "In2.Cu")
		(net "M_C_CPU1_SA_DQS_DN<8>")
	)
	(segment
		(start 51.10734 -230.058214)
		(end 53.499512 -230.058214)
		(width 0.16002)
		(layer "In2.Cu")
		(net "M_C_CPU1_SA_DQS_DN<8>")
	)
	(segment
		(start 48.862488 -230.583994)
		(end 49.352708 -230.583994)
		(width 0.16002)
		(layer "In2.Cu")
		(net "M_C_CPU1_SA_DQS_DN<8>")
	)
	(segment
		(start 77.006196 -240.912904)
		(end 77.439266 -241.345974)
		(width 0.09525)
		(layer "In2.Cu")
		(net "M_C_CPU1_SA_DQS_DN<8>")
	)
	(segment
		(start 49.352708 -230.583994)
		(end 50.206148 -229.730554)
		(width 0.16002)
		(layer "In2.Cu")
		(net "M_C_CPU1_SA_DQS_DN<8>")
	)
	(segment
		(start 46.76521 -230.908352)
		(end 48.53813 -230.908352)
		(width 0.16002)
		(layer "In2.Cu")
		(net "M_C_CPU1_SA_DQS_DN<8>")
	)
	(segment
		(start 45.694346 -230.317548)
		(end 46.174406 -230.317548)
		(width 0.16002)
		(layer "In2.Cu")
		(net "M_C_CPU1_SA_DQS_DN<8>")
	)
	(segment
		(start 43.23207 -229.710234)
		(end 43.839384 -230.317548)
		(width 0.16002)
		(layer "In2.Cu")
		(net "M_C_CPU1_SA_DQS_DN<8>")
	)
	(segment
		(start 87.991188 -242.384326)
		(end 87.99957 -242.3795)
		(width 0.09525)
		(layer "In2.Cu")
		(net "M_C_CPU1_SA_DQS_DN<8>")
	)
	(segment
		(start 95.461836 -242.406424)
		(end 95.48495 -242.31981)
		(width 0.09525)
		(layer "In2.Cu")
		(net "M_C_CPU1_SA_DQS_DN<8>")
	)
	(segment
		(start 75.979528 -240.953544)
		(end 76.03871 -241.012726)
		(width 0.09525)
		(layer "In2.Cu")
		(net "M_C_CPU1_SA_DQS_DN<8>")
	)
	(segment
		(start 77.439266 -241.613944)
		(end 78.145386 -242.320064)
		(width 0.09525)
		(layer "In2.Cu")
		(net "M_C_CPU1_SA_DQS_DN<8>")
	)
	(segment
		(start 81.04251 -242.3795)
		(end 81.050892 -242.384326)
		(width 0.09525)
		(layer "In2.Cu")
		(net "M_C_CPU1_SA_DQS_DN<8>")
	)
	(segment
		(start 42.106342 -229.710234)
		(end 43.23207 -229.710234)
		(width 0.16002)
		(layer "In2.Cu")
		(net "M_C_CPU1_SA_DQS_DN<8>")
	)
	(segment
		(start 91.75115 -242.384326)
		(end 91.759532 -242.3795)
		(width 0.09525)
		(layer "In2.Cu")
		(net "M_C_CPU1_SA_DQS_DN<8>")
	)
	(segment
		(start 50.77968 -229.730554)
		(end 51.10734 -230.058214)
		(width 0.16002)
		(layer "In2.Cu")
		(net "M_C_CPU1_SA_DQS_DN<8>")
	)
	(segment
		(start 84.802472 -242.3795)
		(end 84.810854 -242.384326)
		(width 0.09525)
		(layer "In2.Cu")
		(net "M_C_CPU1_SA_DQS_DN<8>")
	)
	(segment
		(start 92.691204 -242.384326)
		(end 92.699586 -242.3795)
		(width 0.09525)
		(layer "In2.Cu")
		(net "M_C_CPU1_SA_DQS_DN<8>")
	)
	(segment
		(start 61.025278 -230.017574)
		(end 71.961248 -240.953544)
		(width 0.16002)
		(layer "In2.Cu")
		(net "M_C_CPU1_SA_DQS_DN<8>")
	)
	(segment
		(start 84.231226 -242.384326)
		(end 84.239608 -242.3795)
		(width 0.09525)
		(layer "In2.Cu")
		(net "M_C_CPU1_SA_DQS_DN<8>")
	)
	(segment
		(start 56.119776 -230.881174)
		(end 56.439816 -230.561134)
		(width 0.16002)
		(layer "In2.Cu")
		(net "M_C_CPU1_SA_DQS_DN<8>")
	)
	(segment
		(start 50.206148 -229.730554)
		(end 50.77968 -229.730554)
		(width 0.16002)
		(layer "In2.Cu")
		(net "M_C_CPU1_SA_DQS_DN<8>")
	)
	(segment
		(start 89.502488 -242.3795)
		(end 89.51087 -242.384326)
		(width 0.09525)
		(layer "In2.Cu")
		(net "M_C_CPU1_SA_DQS_DN<8>")
	)
	(segment
		(start 56.439816 -230.561134)
		(end 56.914796 -230.561134)
		(width 0.16002)
		(layer "In2.Cu")
		(net "M_C_CPU1_SA_DQS_DN<8>")
	)
	(segment
		(start 48.53813 -230.908352)
		(end 48.862488 -230.583994)
		(width 0.16002)
		(layer "In2.Cu")
		(net "M_C_CPU1_SA_DQS_DN<8>")
	)
	(segment
		(start 76.286106 -240.912904)
		(end 77.006196 -240.912904)
		(width 0.09525)
		(layer "In2.Cu")
		(net "M_C_CPU1_SA_DQS_DN<8>")
	)
	(segment
		(start 95.48495 -242.31981)
		(end 95.331026 -242.05438)
		(width 0.09525)
		(layer "In2.Cu")
		(net "M_C_CPU1_SA_DQS_DN<8>")
	)
	(segment
		(start 88.931242 -242.384326)
		(end 88.939624 -242.3795)
		(width 0.09525)
		(layer "In2.Cu")
		(net "M_C_CPU1_SA_DQS_DN<8>")
	)
	(segment
		(start 43.839384 -230.317548)
		(end 44.980606 -230.317548)
		(width 0.16002)
		(layer "In2.Cu")
		(net "M_C_CPU1_SA_DQS_DN<8>")
	)
	(segment
		(start 46.174406 -230.317548)
		(end 46.76521 -230.908352)
		(width 0.16002)
		(layer "In2.Cu")
		(net "M_C_CPU1_SA_DQS_DN<8>")
	)
	(segment
		(start 58.63717 -230.017574)
		(end 61.025278 -230.017574)
		(width 0.16002)
		(layer "In2.Cu")
		(net "M_C_CPU1_SA_DQS_DN<8>")
	)
	(segment
		(start 76.03871 -241.012726)
		(end 76.186284 -241.012726)
		(width 0.09525)
		(layer "In2.Cu")
		(net "M_C_CPU1_SA_DQS_DN<8>")
	)
	(segment
		(start 53.499512 -230.058214)
		(end 54.322472 -230.881174)
		(width 0.16002)
		(layer "In2.Cu")
		(net "M_C_CPU1_SA_DQS_DN<8>")
	)
	(segment
		(start 45.577506 -230.200708)
		(end 45.694346 -230.317548)
		(width 0.16002)
		(layer "In2.Cu")
		(net "M_C_CPU1_SA_DQS_DN<8>")
	)
	(segment
		(start 94.202504 -242.3795)
		(end 94.210886 -242.384326)
		(width 0.09525)
		(layer "In2.Cu")
		(net "M_C_CPU1_SA_DQS_DN<8>")
	)
	(segment
		(start 57.716928 -229.759002)
		(end 58.378598 -229.759002)
		(width 0.16002)
		(layer "In2.Cu")
		(net "M_C_CPU1_SA_DQS_DN<8>")
	)
	(segment
		(start 54.322472 -230.881174)
		(end 56.119776 -230.881174)
		(width 0.16002)
		(layer "In2.Cu")
		(net "M_C_CPU1_SA_DQS_DN<8>")
	)
	(segment
		(start 76.186284 -241.012726)
		(end 76.286106 -240.912904)
		(width 0.09525)
		(layer "In2.Cu")
		(net "M_C_CPU1_SA_DQS_DN<8>")
	)
	(segment
		(start 75.955906 -240.953544)
		(end 75.979528 -240.953544)
		(width 0.09525)
		(layer "In2.Cu")
		(net "M_C_CPU1_SA_DQS_DN<8>")
	)
	(arc
		(start 88.562434 -242.3795)
		(mid 88.746209 -242.430272)
		(end 88.931242 -242.384326)
		(width 0.09525)
		(layer "In2.Cu")
		(net "M_C_CPU1_SA_DQS_DN<8>")
	)
	(arc
		(start 90.442542 -242.3795)
		(mid 90.63101 -242.430177)
		(end 90.819478 -242.3795)
		(width 0.09525)
		(layer "In2.Cu")
		(net "M_C_CPU1_SA_DQS_DN<8>")
	)
	(arc
		(start 91.382342 -242.3795)
		(mid 91.566117 -242.430272)
		(end 91.75115 -242.384326)
		(width 0.09525)
		(layer "In2.Cu")
		(net "M_C_CPU1_SA_DQS_DN<8>")
	)
	(arc
		(start 82.922364 -242.3795)
		(mid 83.106139 -242.430272)
		(end 83.291172 -242.384326)
		(width 0.09525)
		(layer "In2.Cu")
		(net "M_C_CPU1_SA_DQS_DN<8>")
	)
	(arc
		(start 93.270832 -242.384326)
		(mid 93.455864 -242.43024)
		(end 93.63964 -242.3795)
		(width 0.09525)
		(layer "In2.Cu")
		(net "M_C_CPU1_SA_DQS_DN<8>")
	)
	(arc
		(start 80.479646 -242.3795)
		(mid 80.761078 -242.303745)
		(end 81.04251 -242.3795)
		(width 0.09525)
		(layer "In2.Cu")
		(net "M_C_CPU1_SA_DQS_DN<8>")
	)
	(arc
		(start 89.879678 -242.3795)
		(mid 90.16111 -242.303745)
		(end 90.442542 -242.3795)
		(width 0.09525)
		(layer "In2.Cu")
		(net "M_C_CPU1_SA_DQS_DN<8>")
	)
	(arc
		(start 85.179662 -242.3795)
		(mid 85.461094 -242.303745)
		(end 85.742526 -242.3795)
		(width 0.09525)
		(layer "In2.Cu")
		(net "M_C_CPU1_SA_DQS_DN<8>")
	)
	(arc
		(start 94.579694 -242.3795)
		(mid 94.861126 -242.303745)
		(end 95.142558 -242.3795)
		(width 0.09525)
		(layer "In2.Cu")
		(net "M_C_CPU1_SA_DQS_DN<8>")
	)
	(arc
		(start 84.239608 -242.3795)
		(mid 84.52104 -242.303745)
		(end 84.802472 -242.3795)
		(width 0.09525)
		(layer "In2.Cu")
		(net "M_C_CPU1_SA_DQS_DN<8>")
	)
	(arc
		(start 88.939624 -242.3795)
		(mid 89.221056 -242.303745)
		(end 89.502488 -242.3795)
		(width 0.09525)
		(layer "In2.Cu")
		(net "M_C_CPU1_SA_DQS_DN<8>")
	)
	(arc
		(start 83.299554 -242.3795)
		(mid 83.580986 -242.303745)
		(end 83.862418 -242.3795)
		(width 0.09525)
		(layer "In2.Cu")
		(net "M_C_CPU1_SA_DQS_DN<8>")
	)
	(arc
		(start 95.142558 -242.3795)
		(mid 95.299185 -242.428686)
		(end 95.461836 -242.406424)
		(width 0.09525)
		(layer "In2.Cu")
		(net "M_C_CPU1_SA_DQS_DN<8>")
	)
	(arc
		(start 81.050892 -242.384326)
		(mid 81.235924 -242.43024)
		(end 81.4197 -242.3795)
		(width 0.09525)
		(layer "In2.Cu")
		(net "M_C_CPU1_SA_DQS_DN<8>")
	)
	(arc
		(start 79.18577 -242.391692)
		(mid 79.364222 -242.429934)
		(end 79.539592 -242.3795)
		(width 0.09525)
		(layer "In2.Cu")
		(net "M_C_CPU1_SA_DQS_DN<8>")
	)
	(arc
		(start 78.2574 -242.398296)
		(mid 78.431458 -242.430514)
		(end 78.601062 -242.379754)
		(width 0.09525)
		(layer "In2.Cu")
		(net "M_C_CPU1_SA_DQS_DN<8>")
	)
	(arc
		(start 78.601062 -242.379754)
		(mid 78.861372 -242.303301)
		(end 79.127096 -242.35791)
		(width 0.09525)
		(layer "In2.Cu")
		(net "M_C_CPU1_SA_DQS_DN<8>")
	)
	(arc
		(start 81.982564 -242.3795)
		(mid 82.171032 -242.430177)
		(end 82.3595 -242.3795)
		(width 0.09525)
		(layer "In2.Cu")
		(net "M_C_CPU1_SA_DQS_DN<8>")
	)
	(arc
		(start 79.539592 -242.3795)
		(mid 79.821024 -242.303745)
		(end 80.102456 -242.3795)
		(width 0.09525)
		(layer "In2.Cu")
		(net "M_C_CPU1_SA_DQS_DN<8>")
	)
	(arc
		(start 83.862418 -242.3795)
		(mid 84.046193 -242.430272)
		(end 84.231226 -242.384326)
		(width 0.09525)
		(layer "In2.Cu")
		(net "M_C_CPU1_SA_DQS_DN<8>")
	)
	(arc
		(start 87.059516 -242.3795)
		(mid 87.340948 -242.303745)
		(end 87.62238 -242.3795)
		(width 0.09525)
		(layer "In2.Cu")
		(net "M_C_CPU1_SA_DQS_DN<8>")
	)
	(arc
		(start 81.4197 -242.3795)
		(mid 81.701132 -242.303745)
		(end 81.982564 -242.3795)
		(width 0.09525)
		(layer "In2.Cu")
		(net "M_C_CPU1_SA_DQS_DN<8>")
	)
	(arc
		(start 91.759532 -242.3795)
		(mid 92.040964 -242.303745)
		(end 92.322396 -242.3795)
		(width 0.09525)
		(layer "In2.Cu")
		(net "M_C_CPU1_SA_DQS_DN<8>")
	)
	(arc
		(start 94.210886 -242.384326)
		(mid 94.395918 -242.43024)
		(end 94.579694 -242.3795)
		(width 0.09525)
		(layer "In2.Cu")
		(net "M_C_CPU1_SA_DQS_DN<8>")
	)
	(arc
		(start 92.699586 -242.3795)
		(mid 92.981018 -242.303745)
		(end 93.26245 -242.3795)
		(width 0.09525)
		(layer "In2.Cu")
		(net "M_C_CPU1_SA_DQS_DN<8>")
	)
	(arc
		(start 87.99957 -242.3795)
		(mid 88.281002 -242.303745)
		(end 88.562434 -242.3795)
		(width 0.09525)
		(layer "In2.Cu")
		(net "M_C_CPU1_SA_DQS_DN<8>")
	)
	(arc
		(start 86.68258 -242.3795)
		(mid 86.871048 -242.430177)
		(end 87.059516 -242.3795)
		(width 0.09525)
		(layer "In2.Cu")
		(net "M_C_CPU1_SA_DQS_DN<8>")
	)
	(arc
		(start 89.51087 -242.384326)
		(mid 89.695902 -242.43024)
		(end 89.879678 -242.3795)
		(width 0.09525)
		(layer "In2.Cu")
		(net "M_C_CPU1_SA_DQS_DN<8>")
	)
	(arc
		(start 78.145386 -242.320064)
		(mid 78.182802 -242.352255)
		(end 78.224126 -242.379246)
		(width 0.09525)
		(layer "In2.Cu")
		(net "M_C_CPU1_SA_DQS_DN<8>")
	)
	(arc
		(start 86.119716 -242.3795)
		(mid 86.401148 -242.303745)
		(end 86.68258 -242.3795)
		(width 0.09525)
		(layer "In2.Cu")
		(net "M_C_CPU1_SA_DQS_DN<8>")
	)
	(arc
		(start 90.819478 -242.3795)
		(mid 91.10091 -242.303745)
		(end 91.382342 -242.3795)
		(width 0.09525)
		(layer "In2.Cu")
		(net "M_C_CPU1_SA_DQS_DN<8>")
	)
	(arc
		(start 85.750908 -242.384326)
		(mid 85.93594 -242.43024)
		(end 86.119716 -242.3795)
		(width 0.09525)
		(layer "In2.Cu")
		(net "M_C_CPU1_SA_DQS_DN<8>")
	)
	(arc
		(start 84.810854 -242.384326)
		(mid 84.995886 -242.43024)
		(end 85.179662 -242.3795)
		(width 0.09525)
		(layer "In2.Cu")
		(net "M_C_CPU1_SA_DQS_DN<8>")
	)
	(arc
		(start 92.322396 -242.3795)
		(mid 92.506171 -242.430272)
		(end 92.691204 -242.384326)
		(width 0.09525)
		(layer "In2.Cu")
		(net "M_C_CPU1_SA_DQS_DN<8>")
	)
	(arc
		(start 80.102456 -242.3795)
		(mid 80.286231 -242.430272)
		(end 80.471264 -242.384326)
		(width 0.09525)
		(layer "In2.Cu")
		(net "M_C_CPU1_SA_DQS_DN<8>")
	)
	(arc
		(start 93.63964 -242.3795)
		(mid 93.921072 -242.303745)
		(end 94.202504 -242.3795)
		(width 0.09525)
		(layer "In2.Cu")
		(net "M_C_CPU1_SA_DQS_DN<8>")
	)
	(arc
		(start 82.3595 -242.3795)
		(mid 82.640932 -242.303745)
		(end 82.922364 -242.3795)
		(width 0.09525)
		(layer "In2.Cu")
		(net "M_C_CPU1_SA_DQS_DN<8>")
	)
	(arc
		(start 87.62238 -242.3795)
		(mid 87.806155 -242.430272)
		(end 87.991188 -242.384326)
		(width 0.09525)
		(layer "In2.Cu")
		(net "M_C_CPU1_SA_DQS_DN<8>")
	)
	(segment
		(start 95.797878 -237.460282)
		(end 95.331026 -237.194344)
		(width 0.12954)
		(layer "F.Cu")
		(net "M_C_CPU1_SA_DQS_DN<7>")
	)
	(segment
		(start 85.742526 -237.519464)
		(end 85.750908 -237.52429)
		(width 0.09525)
		(layer "In2.Cu")
		(net "M_C_CPU1_SA_DQS_DN<7>")
	)
	(segment
		(start 54.322472 -221.53118)
		(end 56.101488 -221.53118)
		(width 0.16002)
		(layer "In2.Cu")
		(net "M_C_CPU1_SA_DQS_DN<7>")
	)
	(segment
		(start 48.551592 -221.558104)
		(end 48.83912 -221.270576)
		(width 0.16002)
		(layer "In2.Cu")
		(net "M_C_CPU1_SA_DQS_DN<7>")
	)
	(segment
		(start 75.979528 -235.282994)
		(end 76.03871 -235.342176)
		(width 0.09525)
		(layer "In2.Cu")
		(net "M_C_CPU1_SA_DQS_DN<7>")
	)
	(segment
		(start 58.63717 -220.66758)
		(end 62.028832 -220.66758)
		(width 0.16002)
		(layer "In2.Cu")
		(net "M_C_CPU1_SA_DQS_DN<7>")
	)
	(segment
		(start 84.231226 -237.52429)
		(end 84.239608 -237.519464)
		(width 0.09525)
		(layer "In2.Cu")
		(net "M_C_CPU1_SA_DQS_DN<7>")
	)
	(segment
		(start 92.691204 -237.52429)
		(end 92.699586 -237.519464)
		(width 0.09525)
		(layer "In2.Cu")
		(net "M_C_CPU1_SA_DQS_DN<7>")
	)
	(segment
		(start 46.399196 -221.192344)
		(end 46.764956 -221.558104)
		(width 0.16002)
		(layer "In2.Cu")
		(net "M_C_CPU1_SA_DQS_DN<7>")
	)
	(segment
		(start 95.461836 -237.546388)
		(end 95.48495 -237.459774)
		(width 0.09525)
		(layer "In2.Cu")
		(net "M_C_CPU1_SA_DQS_DN<7>")
	)
	(segment
		(start 69.41947 -228.058218)
		(end 69.41947 -230.019098)
		(width 0.16002)
		(layer "In2.Cu")
		(net "M_C_CPU1_SA_DQS_DN<7>")
	)
	(segment
		(start 88.931242 -237.52429)
		(end 88.939624 -237.519464)
		(width 0.09525)
		(layer "In2.Cu")
		(net "M_C_CPU1_SA_DQS_DN<7>")
	)
	(segment
		(start 62.758828 -221.397576)
		(end 62.924182 -221.397576)
		(width 0.16002)
		(layer "In2.Cu")
		(net "M_C_CPU1_SA_DQS_DN<7>")
	)
	(segment
		(start 43.277536 -220.405706)
		(end 43.839384 -220.967554)
		(width 0.16002)
		(layer "In2.Cu")
		(net "M_C_CPU1_SA_DQS_DN<7>")
	)
	(segment
		(start 56.101488 -221.53118)
		(end 56.47182 -221.160848)
		(width 0.16002)
		(layer "In2.Cu")
		(net "M_C_CPU1_SA_DQS_DN<7>")
	)
	(segment
		(start 50.206148 -220.38056)
		(end 50.819812 -220.38056)
		(width 0.16002)
		(layer "In2.Cu")
		(net "M_C_CPU1_SA_DQS_DN<7>")
	)
	(segment
		(start 87.991188 -237.52429)
		(end 87.99957 -237.519464)
		(width 0.09525)
		(layer "In2.Cu")
		(net "M_C_CPU1_SA_DQS_DN<7>")
	)
	(segment
		(start 63.26378 -221.902528)
		(end 69.41947 -228.058218)
		(width 0.16002)
		(layer "In2.Cu")
		(net "M_C_CPU1_SA_DQS_DN<7>")
	)
	(segment
		(start 62.028832 -220.66758)
		(end 62.758828 -221.397576)
		(width 0.16002)
		(layer "In2.Cu")
		(net "M_C_CPU1_SA_DQS_DN<7>")
	)
	(segment
		(start 79.472028 -237.443772)
		(end 79.821024 -237.443772)
		(width 0.09525)
		(layer "In2.Cu")
		(net "M_C_CPU1_SA_DQS_DN<7>")
	)
	(segment
		(start 53.785008 -220.993716)
		(end 54.322472 -221.53118)
		(width 0.16002)
		(layer "In2.Cu")
		(net "M_C_CPU1_SA_DQS_DN<7>")
	)
	(segment
		(start 50.819812 -220.38056)
		(end 51.147472 -220.70822)
		(width 0.16002)
		(layer "In2.Cu")
		(net "M_C_CPU1_SA_DQS_DN<7>")
	)
	(segment
		(start 42.533316 -220.405706)
		(end 43.277536 -220.405706)
		(width 0.16002)
		(layer "In2.Cu")
		(net "M_C_CPU1_SA_DQS_DN<7>")
	)
	(segment
		(start 49.653444 -220.933264)
		(end 50.206148 -220.38056)
		(width 0.16002)
		(layer "In2.Cu")
		(net "M_C_CPU1_SA_DQS_DN<7>")
	)
	(segment
		(start 76.474574 -235.342176)
		(end 76.579222 -235.446824)
		(width 0.09525)
		(layer "In2.Cu")
		(net "M_C_CPU1_SA_DQS_DN<7>")
	)
	(segment
		(start 53.095652 -220.70822)
		(end 53.785008 -220.993716)
		(width 0.16002)
		(layer "In2.Cu")
		(net "M_C_CPU1_SA_DQS_DN<7>")
	)
	(segment
		(start 77.06868 -235.446824)
		(end 78.21422 -236.592364)
		(width 0.09525)
		(layer "In2.Cu")
		(net "M_C_CPU1_SA_DQS_DN<7>")
	)
	(segment
		(start 76.03871 -235.342176)
		(end 76.474574 -235.342176)
		(width 0.09525)
		(layer "In2.Cu")
		(net "M_C_CPU1_SA_DQS_DN<7>")
	)
	(segment
		(start 95.48495 -237.459774)
		(end 95.331026 -237.194344)
		(width 0.09525)
		(layer "In2.Cu")
		(net "M_C_CPU1_SA_DQS_DN<7>")
	)
	(segment
		(start 78.21422 -236.592364)
		(end 78.482444 -236.592364)
		(width 0.09525)
		(layer "In2.Cu")
		(net "M_C_CPU1_SA_DQS_DN<7>")
	)
	(segment
		(start 56.47182 -221.160848)
		(end 56.890158 -220.987366)
		(width 0.16002)
		(layer "In2.Cu")
		(net "M_C_CPU1_SA_DQS_DN<7>")
	)
	(segment
		(start 51.147472 -220.70822)
		(end 53.095652 -220.70822)
		(width 0.16002)
		(layer "In2.Cu")
		(net "M_C_CPU1_SA_DQS_DN<7>")
	)
	(segment
		(start 80.471264 -237.52429)
		(end 80.479646 -237.519464)
		(width 0.09525)
		(layer "In2.Cu")
		(net "M_C_CPU1_SA_DQS_DN<7>")
	)
	(segment
		(start 57.76087 -220.405706)
		(end 58.375296 -220.405706)
		(width 0.16002)
		(layer "In2.Cu")
		(net "M_C_CPU1_SA_DQS_DN<7>")
	)
	(segment
		(start 89.502488 -237.519464)
		(end 89.51087 -237.52429)
		(width 0.09525)
		(layer "In2.Cu")
		(net "M_C_CPU1_SA_DQS_DN<7>")
	)
	(segment
		(start 76.579222 -235.446824)
		(end 77.06868 -235.446824)
		(width 0.09525)
		(layer "In2.Cu")
		(net "M_C_CPU1_SA_DQS_DN<7>")
	)
	(segment
		(start 40.514016 -220.559376)
		(end 42.379646 -220.559376)
		(width 0.16002)
		(layer "In2.Cu")
		(net "M_C_CPU1_SA_DQS_DN<7>")
	)
	(segment
		(start 63.26378 -221.737174)
		(end 63.26378 -221.902528)
		(width 0.16002)
		(layer "In2.Cu")
		(net "M_C_CPU1_SA_DQS_DN<7>")
	)
	(segment
		(start 42.379646 -220.559376)
		(end 42.533316 -220.405706)
		(width 0.16002)
		(layer "In2.Cu")
		(net "M_C_CPU1_SA_DQS_DN<7>")
	)
	(segment
		(start 91.75115 -237.52429)
		(end 91.759532 -237.519464)
		(width 0.09525)
		(layer "In2.Cu")
		(net "M_C_CPU1_SA_DQS_DN<7>")
	)
	(segment
		(start 84.802472 -237.519464)
		(end 84.810854 -237.52429)
		(width 0.09525)
		(layer "In2.Cu")
		(net "M_C_CPU1_SA_DQS_DN<7>")
	)
	(segment
		(start 58.375296 -220.405706)
		(end 58.63717 -220.66758)
		(width 0.16002)
		(layer "In2.Cu")
		(net "M_C_CPU1_SA_DQS_DN<7>")
	)
	(segment
		(start 62.924182 -221.397576)
		(end 63.26378 -221.737174)
		(width 0.16002)
		(layer "In2.Cu")
		(net "M_C_CPU1_SA_DQS_DN<7>")
	)
	(segment
		(start 69.41947 -230.019098)
		(end 74.683366 -235.282994)
		(width 0.16002)
		(layer "In2.Cu")
		(net "M_C_CPU1_SA_DQS_DN<7>")
	)
	(segment
		(start 83.291172 -237.52429)
		(end 83.299554 -237.519464)
		(width 0.09525)
		(layer "In2.Cu")
		(net "M_C_CPU1_SA_DQS_DN<7>")
	)
	(segment
		(start 43.839384 -220.967554)
		(end 45.856144 -220.967554)
		(width 0.16002)
		(layer "In2.Cu")
		(net "M_C_CPU1_SA_DQS_DN<7>")
	)
	(segment
		(start 75.955906 -235.282994)
		(end 75.979528 -235.282994)
		(width 0.09525)
		(layer "In2.Cu")
		(net "M_C_CPU1_SA_DQS_DN<7>")
	)
	(segment
		(start 40.23995 -220.28531)
		(end 40.514016 -220.559376)
		(width 0.16002)
		(layer "In2.Cu")
		(net "M_C_CPU1_SA_DQS_DN<7>")
	)
	(segment
		(start 56.890158 -220.987366)
		(end 57.76087 -220.405706)
		(width 0.16002)
		(layer "In2.Cu")
		(net "M_C_CPU1_SA_DQS_DN<7>")
	)
	(segment
		(start 48.83912 -221.270576)
		(end 49.653444 -220.933264)
		(width 0.16002)
		(layer "In2.Cu")
		(net "M_C_CPU1_SA_DQS_DN<7>")
	)
	(segment
		(start 78.71841 -236.690154)
		(end 79.472028 -237.443772)
		(width 0.09525)
		(layer "In2.Cu")
		(net "M_C_CPU1_SA_DQS_DN<7>")
	)
	(segment
		(start 74.683366 -235.282994)
		(end 75.955906 -235.282994)
		(width 0.16002)
		(layer "In2.Cu")
		(net "M_C_CPU1_SA_DQS_DN<7>")
	)
	(segment
		(start 45.856144 -220.967554)
		(end 46.399196 -221.192344)
		(width 0.16002)
		(layer "In2.Cu")
		(net "M_C_CPU1_SA_DQS_DN<7>")
	)
	(segment
		(start 94.202504 -237.519464)
		(end 94.210886 -237.52429)
		(width 0.09525)
		(layer "In2.Cu")
		(net "M_C_CPU1_SA_DQS_DN<7>")
	)
	(segment
		(start 81.04251 -237.519464)
		(end 81.050892 -237.52429)
		(width 0.09525)
		(layer "In2.Cu")
		(net "M_C_CPU1_SA_DQS_DN<7>")
	)
	(segment
		(start 93.26245 -237.519464)
		(end 93.270832 -237.52429)
		(width 0.09525)
		(layer "In2.Cu")
		(net "M_C_CPU1_SA_DQS_DN<7>")
	)
	(segment
		(start 46.764956 -221.558104)
		(end 48.551592 -221.558104)
		(width 0.16002)
		(layer "In2.Cu")
		(net "M_C_CPU1_SA_DQS_DN<7>")
	)
	(arc
		(start 92.699586 -237.519464)
		(mid 92.981018 -237.443709)
		(end 93.26245 -237.519464)
		(width 0.09525)
		(layer "In2.Cu")
		(net "M_C_CPU1_SA_DQS_DN<7>")
	)
	(arc
		(start 85.750908 -237.52429)
		(mid 85.93594 -237.570204)
		(end 86.119716 -237.519464)
		(width 0.09525)
		(layer "In2.Cu")
		(net "M_C_CPU1_SA_DQS_DN<7>")
	)
	(arc
		(start 82.922364 -237.519464)
		(mid 83.106139 -237.570236)
		(end 83.291172 -237.52429)
		(width 0.09525)
		(layer "In2.Cu")
		(net "M_C_CPU1_SA_DQS_DN<7>")
	)
	(arc
		(start 81.982564 -237.519464)
		(mid 82.171032 -237.570141)
		(end 82.3595 -237.519464)
		(width 0.09525)
		(layer "In2.Cu")
		(net "M_C_CPU1_SA_DQS_DN<7>")
	)
	(arc
		(start 80.479646 -237.519464)
		(mid 80.761078 -237.443709)
		(end 81.04251 -237.519464)
		(width 0.09525)
		(layer "In2.Cu")
		(net "M_C_CPU1_SA_DQS_DN<7>")
	)
	(arc
		(start 80.102456 -237.519464)
		(mid 80.286231 -237.570236)
		(end 80.471264 -237.52429)
		(width 0.09525)
		(layer "In2.Cu")
		(net "M_C_CPU1_SA_DQS_DN<7>")
	)
	(arc
		(start 86.119716 -237.519464)
		(mid 86.401148 -237.443709)
		(end 86.68258 -237.519464)
		(width 0.09525)
		(layer "In2.Cu")
		(net "M_C_CPU1_SA_DQS_DN<7>")
	)
	(arc
		(start 91.382342 -237.519464)
		(mid 91.566117 -237.570236)
		(end 91.75115 -237.52429)
		(width 0.09525)
		(layer "In2.Cu")
		(net "M_C_CPU1_SA_DQS_DN<7>")
	)
	(arc
		(start 82.3595 -237.519464)
		(mid 82.640932 -237.443709)
		(end 82.922364 -237.519464)
		(width 0.09525)
		(layer "In2.Cu")
		(net "M_C_CPU1_SA_DQS_DN<7>")
	)
	(arc
		(start 81.4197 -237.519464)
		(mid 81.701132 -237.443709)
		(end 81.982564 -237.519464)
		(width 0.09525)
		(layer "In2.Cu")
		(net "M_C_CPU1_SA_DQS_DN<7>")
	)
	(arc
		(start 88.562434 -237.519464)
		(mid 88.746209 -237.570236)
		(end 88.931242 -237.52429)
		(width 0.09525)
		(layer "In2.Cu")
		(net "M_C_CPU1_SA_DQS_DN<7>")
	)
	(arc
		(start 94.579694 -237.519464)
		(mid 94.861126 -237.443709)
		(end 95.142558 -237.519464)
		(width 0.09525)
		(layer "In2.Cu")
		(net "M_C_CPU1_SA_DQS_DN<7>")
	)
	(arc
		(start 78.482444 -236.592364)
		(mid 78.610153 -236.617785)
		(end 78.71841 -236.690154)
		(width 0.09525)
		(layer "In2.Cu")
		(net "M_C_CPU1_SA_DQS_DN<7>")
	)
	(arc
		(start 83.299554 -237.519464)
		(mid 83.580986 -237.443709)
		(end 83.862418 -237.519464)
		(width 0.09525)
		(layer "In2.Cu")
		(net "M_C_CPU1_SA_DQS_DN<7>")
	)
	(arc
		(start 93.63964 -237.519464)
		(mid 93.921072 -237.443709)
		(end 94.202504 -237.519464)
		(width 0.09525)
		(layer "In2.Cu")
		(net "M_C_CPU1_SA_DQS_DN<7>")
	)
	(arc
		(start 88.939624 -237.519464)
		(mid 89.221056 -237.443709)
		(end 89.502488 -237.519464)
		(width 0.09525)
		(layer "In2.Cu")
		(net "M_C_CPU1_SA_DQS_DN<7>")
	)
	(arc
		(start 83.862418 -237.519464)
		(mid 84.046193 -237.570236)
		(end 84.231226 -237.52429)
		(width 0.09525)
		(layer "In2.Cu")
		(net "M_C_CPU1_SA_DQS_DN<7>")
	)
	(arc
		(start 89.879678 -237.519464)
		(mid 90.16111 -237.443709)
		(end 90.442542 -237.519464)
		(width 0.09525)
		(layer "In2.Cu")
		(net "M_C_CPU1_SA_DQS_DN<7>")
	)
	(arc
		(start 87.99957 -237.519464)
		(mid 88.281002 -237.443709)
		(end 88.562434 -237.519464)
		(width 0.09525)
		(layer "In2.Cu")
		(net "M_C_CPU1_SA_DQS_DN<7>")
	)
	(arc
		(start 87.62238 -237.519464)
		(mid 87.806155 -237.570236)
		(end 87.991188 -237.52429)
		(width 0.09525)
		(layer "In2.Cu")
		(net "M_C_CPU1_SA_DQS_DN<7>")
	)
	(arc
		(start 91.759532 -237.519464)
		(mid 92.040964 -237.443709)
		(end 92.322396 -237.519464)
		(width 0.09525)
		(layer "In2.Cu")
		(net "M_C_CPU1_SA_DQS_DN<7>")
	)
	(arc
		(start 86.68258 -237.519464)
		(mid 86.871048 -237.570141)
		(end 87.059516 -237.519464)
		(width 0.09525)
		(layer "In2.Cu")
		(net "M_C_CPU1_SA_DQS_DN<7>")
	)
	(arc
		(start 90.819478 -237.519464)
		(mid 91.10091 -237.443709)
		(end 91.382342 -237.519464)
		(width 0.09525)
		(layer "In2.Cu")
		(net "M_C_CPU1_SA_DQS_DN<7>")
	)
	(arc
		(start 94.210886 -237.52429)
		(mid 94.395918 -237.570204)
		(end 94.579694 -237.519464)
		(width 0.09525)
		(layer "In2.Cu")
		(net "M_C_CPU1_SA_DQS_DN<7>")
	)
	(arc
		(start 93.270832 -237.52429)
		(mid 93.455864 -237.570204)
		(end 93.63964 -237.519464)
		(width 0.09525)
		(layer "In2.Cu")
		(net "M_C_CPU1_SA_DQS_DN<7>")
	)
	(arc
		(start 89.51087 -237.52429)
		(mid 89.695902 -237.570204)
		(end 89.879678 -237.519464)
		(width 0.09525)
		(layer "In2.Cu")
		(net "M_C_CPU1_SA_DQS_DN<7>")
	)
	(arc
		(start 90.442542 -237.519464)
		(mid 90.63101 -237.570141)
		(end 90.819478 -237.519464)
		(width 0.09525)
		(layer "In2.Cu")
		(net "M_C_CPU1_SA_DQS_DN<7>")
	)
	(arc
		(start 81.050892 -237.52429)
		(mid 81.235924 -237.570204)
		(end 81.4197 -237.519464)
		(width 0.09525)
		(layer "In2.Cu")
		(net "M_C_CPU1_SA_DQS_DN<7>")
	)
	(arc
		(start 87.059516 -237.519464)
		(mid 87.340948 -237.443709)
		(end 87.62238 -237.519464)
		(width 0.09525)
		(layer "In2.Cu")
		(net "M_C_CPU1_SA_DQS_DN<7>")
	)
	(arc
		(start 85.179662 -237.519464)
		(mid 85.461094 -237.443709)
		(end 85.742526 -237.519464)
		(width 0.09525)
		(layer "In2.Cu")
		(net "M_C_CPU1_SA_DQS_DN<7>")
	)
	(arc
		(start 95.142558 -237.519464)
		(mid 95.299185 -237.56865)
		(end 95.461836 -237.546388)
		(width 0.09525)
		(layer "In2.Cu")
		(net "M_C_CPU1_SA_DQS_DN<7>")
	)
	(arc
		(start 84.810854 -237.52429)
		(mid 84.995886 -237.570204)
		(end 85.179662 -237.519464)
		(width 0.09525)
		(layer "In2.Cu")
		(net "M_C_CPU1_SA_DQS_DN<7>")
	)
	(arc
		(start 84.239608 -237.519464)
		(mid 84.52104 -237.443709)
		(end 84.802472 -237.519464)
		(width 0.09525)
		(layer "In2.Cu")
		(net "M_C_CPU1_SA_DQS_DN<7>")
	)
	(arc
		(start 79.821024 -237.443772)
		(mid 79.966732 -237.46304)
		(end 80.102456 -237.519464)
		(width 0.09525)
		(layer "In2.Cu")
		(net "M_C_CPU1_SA_DQS_DN<7>")
	)
	(arc
		(start 92.322396 -237.519464)
		(mid 92.506171 -237.570236)
		(end 92.691204 -237.52429)
		(width 0.09525)
		(layer "In2.Cu")
		(net "M_C_CPU1_SA_DQS_DN<7>")
	)
	(segment
		(start 95.797878 -232.600246)
		(end 95.331026 -232.334308)
		(width 0.12954)
		(layer "F.Cu")
		(net "M_C_CPU1_SA_DQS_DN<6>")
	)
	(segment
		(start 62.72911 -211.317586)
		(end 69.47789 -218.066366)
		(width 0.16002)
		(layer "In2.Cu")
		(net "M_C_CPU1_SA_DQS_DN<6>")
	)
	(segment
		(start 43.23207 -211.010246)
		(end 43.839384 -211.61756)
		(width 0.16002)
		(layer "In2.Cu")
		(net "M_C_CPU1_SA_DQS_DN<6>")
	)
	(segment
		(start 50.819812 -211.030566)
		(end 51.147472 -211.358226)
		(width 0.16002)
		(layer "In2.Cu")
		(net "M_C_CPU1_SA_DQS_DN<6>")
	)
	(segment
		(start 79.632556 -231.849422)
		(end 79.670656 -231.87152)
		(width 0.09525)
		(layer "In2.Cu")
		(net "M_C_CPU1_SA_DQS_DN<6>")
	)
	(segment
		(start 56.101488 -212.181186)
		(end 56.421528 -211.861146)
		(width 0.16002)
		(layer "In2.Cu")
		(net "M_C_CPU1_SA_DQS_DN<6>")
	)
	(segment
		(start 61.13272 -211.200746)
		(end 61.61278 -211.200746)
		(width 0.16002)
		(layer "In2.Cu")
		(net "M_C_CPU1_SA_DQS_DN<6>")
	)
	(segment
		(start 87.991188 -232.664254)
		(end 87.99957 -232.659428)
		(width 0.09525)
		(layer "In2.Cu")
		(net "M_C_CPU1_SA_DQS_DN<6>")
	)
	(segment
		(start 80.07096 -232.64114)
		(end 80.102456 -232.659428)
		(width 0.09525)
		(layer "In2.Cu")
		(net "M_C_CPU1_SA_DQS_DN<6>")
	)
	(segment
		(start 78.663292 -230.212646)
		(end 78.692756 -230.229664)
		(width 0.09525)
		(layer "In2.Cu")
		(net "M_C_CPU1_SA_DQS_DN<6>")
	)
	(segment
		(start 40.23995 -210.935316)
		(end 40.514016 -211.209382)
		(width 0.16002)
		(layer "In2.Cu")
		(net "M_C_CPU1_SA_DQS_DN<6>")
	)
	(segment
		(start 92.691204 -232.664254)
		(end 92.699586 -232.659428)
		(width 0.09525)
		(layer "In2.Cu")
		(net "M_C_CPU1_SA_DQS_DN<6>")
	)
	(segment
		(start 81.04251 -232.659428)
		(end 81.050892 -232.664254)
		(width 0.09525)
		(layer "In2.Cu")
		(net "M_C_CPU1_SA_DQS_DN<6>")
	)
	(segment
		(start 80.471264 -232.664254)
		(end 80.479646 -232.659428)
		(width 0.09525)
		(layer "In2.Cu")
		(net "M_C_CPU1_SA_DQS_DN<6>")
	)
	(segment
		(start 42.106342 -211.010246)
		(end 43.23207 -211.010246)
		(width 0.16002)
		(layer "In2.Cu")
		(net "M_C_CPU1_SA_DQS_DN<6>")
	)
	(segment
		(start 95.461836 -232.686352)
		(end 95.48495 -232.599738)
		(width 0.09525)
		(layer "In2.Cu")
		(net "M_C_CPU1_SA_DQS_DN<6>")
	)
	(segment
		(start 83.291172 -232.664254)
		(end 83.299554 -232.659428)
		(width 0.09525)
		(layer "In2.Cu")
		(net "M_C_CPU1_SA_DQS_DN<6>")
	)
	(segment
		(start 84.802472 -232.659428)
		(end 84.810854 -232.664254)
		(width 0.09525)
		(layer "In2.Cu")
		(net "M_C_CPU1_SA_DQS_DN<6>")
	)
	(segment
		(start 54.322472 -212.181186)
		(end 56.101488 -212.181186)
		(width 0.16002)
		(layer "In2.Cu")
		(net "M_C_CPU1_SA_DQS_DN<6>")
	)
	(segment
		(start 53.499512 -211.358226)
		(end 54.322472 -212.181186)
		(width 0.16002)
		(layer "In2.Cu")
		(net "M_C_CPU1_SA_DQS_DN<6>")
	)
	(segment
		(start 93.26245 -232.659428)
		(end 93.270832 -232.664254)
		(width 0.09525)
		(layer "In2.Cu")
		(net "M_C_CPU1_SA_DQS_DN<6>")
	)
	(segment
		(start 46.764956 -212.20811)
		(end 48.538384 -212.20811)
		(width 0.16002)
		(layer "In2.Cu")
		(net "M_C_CPU1_SA_DQS_DN<6>")
	)
	(segment
		(start 79.128874 -231.019858)
		(end 79.162656 -231.039416)
		(width 0.09525)
		(layer "In2.Cu")
		(net "M_C_CPU1_SA_DQS_DN<6>")
	)
	(segment
		(start 75.14717 -226.643946)
		(end 76.050902 -227.547678)
		(width 0.16002)
		(layer "In2.Cu")
		(net "M_C_CPU1_SA_DQS_DN<6>")
	)
	(segment
		(start 40.514016 -211.209382)
		(end 41.907206 -211.209382)
		(width 0.16002)
		(layer "In2.Cu")
		(net "M_C_CPU1_SA_DQS_DN<6>")
	)
	(segment
		(start 79.600044 -231.830626)
		(end 79.632556 -231.849422)
		(width 0.09525)
		(layer "In2.Cu")
		(net "M_C_CPU1_SA_DQS_DN<6>")
	)
	(segment
		(start 76.633578 -227.606606)
		(end 77.103478 -227.606606)
		(width 0.09525)
		(layer "In2.Cu")
		(net "M_C_CPU1_SA_DQS_DN<6>")
	)
	(segment
		(start 51.147472 -211.358226)
		(end 53.499512 -211.358226)
		(width 0.16002)
		(layer "In2.Cu")
		(net "M_C_CPU1_SA_DQS_DN<6>")
	)
	(segment
		(start 58.378598 -211.059014)
		(end 58.63717 -211.317586)
		(width 0.16002)
		(layer "In2.Cu")
		(net "M_C_CPU1_SA_DQS_DN<6>")
	)
	(segment
		(start 61.01588 -211.317586)
		(end 61.13272 -211.200746)
		(width 0.16002)
		(layer "In2.Cu")
		(net "M_C_CPU1_SA_DQS_DN<6>")
	)
	(segment
		(start 85.742526 -232.659428)
		(end 85.750908 -232.664254)
		(width 0.09525)
		(layer "In2.Cu")
		(net "M_C_CPU1_SA_DQS_DN<6>")
	)
	(segment
		(start 91.75115 -232.664254)
		(end 91.759532 -232.659428)
		(width 0.09525)
		(layer "In2.Cu")
		(net "M_C_CPU1_SA_DQS_DN<6>")
	)
	(segment
		(start 78.190344 -229.400608)
		(end 78.222602 -229.419404)
		(width 0.09525)
		(layer "In2.Cu")
		(net "M_C_CPU1_SA_DQS_DN<6>")
	)
	(segment
		(start 48.862488 -211.884006)
		(end 49.352708 -211.884006)
		(width 0.16002)
		(layer "In2.Cu")
		(net "M_C_CPU1_SA_DQS_DN<6>")
	)
	(segment
		(start 75.14717 -225.508566)
		(end 75.14717 -226.643946)
		(width 0.16002)
		(layer "In2.Cu")
		(net "M_C_CPU1_SA_DQS_DN<6>")
	)
	(segment
		(start 61.72962 -211.317586)
		(end 62.72911 -211.317586)
		(width 0.16002)
		(layer "In2.Cu")
		(net "M_C_CPU1_SA_DQS_DN<6>")
	)
	(segment
		(start 95.48495 -232.599738)
		(end 95.331026 -232.334308)
		(width 0.09525)
		(layer "In2.Cu")
		(net "M_C_CPU1_SA_DQS_DN<6>")
	)
	(segment
		(start 49.352708 -211.884006)
		(end 50.206148 -211.030566)
		(width 0.16002)
		(layer "In2.Cu")
		(net "M_C_CPU1_SA_DQS_DN<6>")
	)
	(segment
		(start 43.839384 -211.61756)
		(end 46.174406 -211.61756)
		(width 0.16002)
		(layer "In2.Cu")
		(net "M_C_CPU1_SA_DQS_DN<6>")
	)
	(segment
		(start 76.050902 -227.547678)
		(end 76.551028 -227.547678)
		(width 0.16002)
		(layer "In2.Cu")
		(net "M_C_CPU1_SA_DQS_DN<6>")
	)
	(segment
		(start 48.538384 -212.20811)
		(end 48.862488 -211.884006)
		(width 0.16002)
		(layer "In2.Cu")
		(net "M_C_CPU1_SA_DQS_DN<6>")
	)
	(segment
		(start 79.162656 -231.039416)
		(end 79.197708 -231.05999)
		(width 0.09525)
		(layer "In2.Cu")
		(net "M_C_CPU1_SA_DQS_DN<6>")
	)
	(segment
		(start 76.551028 -227.547678)
		(end 76.57465 -227.547678)
		(width 0.09525)
		(layer "In2.Cu")
		(net "M_C_CPU1_SA_DQS_DN<6>")
	)
	(segment
		(start 46.174406 -211.61756)
		(end 46.764956 -212.20811)
		(width 0.16002)
		(layer "In2.Cu")
		(net "M_C_CPU1_SA_DQS_DN<6>")
	)
	(segment
		(start 58.63717 -211.317586)
		(end 61.01588 -211.317586)
		(width 0.16002)
		(layer "In2.Cu")
		(net "M_C_CPU1_SA_DQS_DN<6>")
	)
	(segment
		(start 88.931242 -232.664254)
		(end 88.939624 -232.659428)
		(width 0.09525)
		(layer "In2.Cu")
		(net "M_C_CPU1_SA_DQS_DN<6>")
	)
	(segment
		(start 89.502488 -232.659428)
		(end 89.51087 -232.664254)
		(width 0.09525)
		(layer "In2.Cu")
		(net "M_C_CPU1_SA_DQS_DN<6>")
	)
	(segment
		(start 78.692756 -230.229664)
		(end 78.729332 -230.251)
		(width 0.09525)
		(layer "In2.Cu")
		(net "M_C_CPU1_SA_DQS_DN<6>")
	)
	(segment
		(start 56.921908 -211.861146)
		(end 57.72404 -211.059014)
		(width 0.16002)
		(layer "In2.Cu")
		(net "M_C_CPU1_SA_DQS_DN<6>")
	)
	(segment
		(start 76.57465 -227.547678)
		(end 76.633578 -227.606606)
		(width 0.09525)
		(layer "In2.Cu")
		(net "M_C_CPU1_SA_DQS_DN<6>")
	)
	(segment
		(start 84.231226 -232.664254)
		(end 84.239608 -232.659428)
		(width 0.09525)
		(layer "In2.Cu")
		(net "M_C_CPU1_SA_DQS_DN<6>")
	)
	(segment
		(start 78.222602 -229.419404)
		(end 78.261972 -229.442264)
		(width 0.09525)
		(layer "In2.Cu")
		(net "M_C_CPU1_SA_DQS_DN<6>")
	)
	(segment
		(start 57.72404 -211.059014)
		(end 58.378598 -211.059014)
		(width 0.16002)
		(layer "In2.Cu")
		(net "M_C_CPU1_SA_DQS_DN<6>")
	)
	(segment
		(start 56.421528 -211.861146)
		(end 56.921908 -211.861146)
		(width 0.16002)
		(layer "In2.Cu")
		(net "M_C_CPU1_SA_DQS_DN<6>")
	)
	(segment
		(start 50.206148 -211.030566)
		(end 50.819812 -211.030566)
		(width 0.16002)
		(layer "In2.Cu")
		(net "M_C_CPU1_SA_DQS_DN<6>")
	)
	(segment
		(start 41.907206 -211.209382)
		(end 42.106342 -211.010246)
		(width 0.16002)
		(layer "In2.Cu")
		(net "M_C_CPU1_SA_DQS_DN<6>")
	)
	(segment
		(start 61.61278 -211.200746)
		(end 61.72962 -211.317586)
		(width 0.16002)
		(layer "In2.Cu")
		(net "M_C_CPU1_SA_DQS_DN<6>")
	)
	(segment
		(start 69.47789 -219.839286)
		(end 75.14717 -225.508566)
		(width 0.16002)
		(layer "In2.Cu")
		(net "M_C_CPU1_SA_DQS_DN<6>")
	)
	(segment
		(start 94.202504 -232.659428)
		(end 94.210886 -232.664254)
		(width 0.09525)
		(layer "In2.Cu")
		(net "M_C_CPU1_SA_DQS_DN<6>")
	)
	(segment
		(start 69.47789 -218.066366)
		(end 69.47789 -219.839286)
		(width 0.16002)
		(layer "In2.Cu")
		(net "M_C_CPU1_SA_DQS_DN<6>")
	)
	(segment
		(start 77.103478 -227.606606)
		(end 77.40904 -227.912422)
		(width 0.09525)
		(layer "In2.Cu")
		(net "M_C_CPU1_SA_DQS_DN<6>")
	)
	(arc
		(start 81.982564 -232.659428)
		(mid 82.171032 -232.710105)
		(end 82.3595 -232.659428)
		(width 0.09525)
		(layer "In2.Cu")
		(net "M_C_CPU1_SA_DQS_DN<6>")
	)
	(arc
		(start 88.939624 -232.659428)
		(mid 89.221056 -232.583673)
		(end 89.502488 -232.659428)
		(width 0.09525)
		(layer "In2.Cu")
		(net "M_C_CPU1_SA_DQS_DN<6>")
	)
	(arc
		(start 89.879678 -232.659428)
		(mid 90.16111 -232.583673)
		(end 90.442542 -232.659428)
		(width 0.09525)
		(layer "In2.Cu")
		(net "M_C_CPU1_SA_DQS_DN<6>")
	)
	(arc
		(start 94.210886 -232.664254)
		(mid 94.395918 -232.710168)
		(end 94.579694 -232.659428)
		(width 0.09525)
		(layer "In2.Cu")
		(net "M_C_CPU1_SA_DQS_DN<6>")
	)
	(arc
		(start 77.561694 -228.240336)
		(mid 77.631383 -228.46103)
		(end 77.789024 -228.63048)
		(width 0.09525)
		(layer "In2.Cu")
		(net "M_C_CPU1_SA_DQS_DN<6>")
	)
	(arc
		(start 80.479646 -232.659428)
		(mid 80.761078 -232.583673)
		(end 81.04251 -232.659428)
		(width 0.09525)
		(layer "In2.Cu")
		(net "M_C_CPU1_SA_DQS_DN<6>")
	)
	(arc
		(start 87.059516 -232.659428)
		(mid 87.340948 -232.583673)
		(end 87.62238 -232.659428)
		(width 0.09525)
		(layer "In2.Cu")
		(net "M_C_CPU1_SA_DQS_DN<6>")
	)
	(arc
		(start 78.261972 -229.442264)
		(mid 78.439658 -229.643556)
		(end 78.50378 -229.90429)
		(width 0.09525)
		(layer "In2.Cu")
		(net "M_C_CPU1_SA_DQS_DN<6>")
	)
	(arc
		(start 82.3595 -232.659428)
		(mid 82.640932 -232.583673)
		(end 82.922364 -232.659428)
		(width 0.09525)
		(layer "In2.Cu")
		(net "M_C_CPU1_SA_DQS_DN<6>")
	)
	(arc
		(start 90.442542 -232.659428)
		(mid 90.63101 -232.710105)
		(end 90.819478 -232.659428)
		(width 0.09525)
		(layer "In2.Cu")
		(net "M_C_CPU1_SA_DQS_DN<6>")
	)
	(arc
		(start 93.63964 -232.659428)
		(mid 93.921072 -232.583673)
		(end 94.202504 -232.659428)
		(width 0.09525)
		(layer "In2.Cu")
		(net "M_C_CPU1_SA_DQS_DN<6>")
	)
	(arc
		(start 91.382342 -232.659428)
		(mid 91.566117 -232.7102)
		(end 91.75115 -232.664254)
		(width 0.09525)
		(layer "In2.Cu")
		(net "M_C_CPU1_SA_DQS_DN<6>")
	)
	(arc
		(start 94.579694 -232.659428)
		(mid 94.861126 -232.583673)
		(end 95.142558 -232.659428)
		(width 0.09525)
		(layer "In2.Cu")
		(net "M_C_CPU1_SA_DQS_DN<6>")
	)
	(arc
		(start 78.973426 -230.714296)
		(mid 79.014528 -230.885702)
		(end 79.128874 -231.019858)
		(width 0.09525)
		(layer "In2.Cu")
		(net "M_C_CPU1_SA_DQS_DN<6>")
	)
	(arc
		(start 95.142558 -232.659428)
		(mid 95.299185 -232.708614)
		(end 95.461836 -232.686352)
		(width 0.09525)
		(layer "In2.Cu")
		(net "M_C_CPU1_SA_DQS_DN<6>")
	)
	(arc
		(start 87.99957 -232.659428)
		(mid 88.281002 -232.583673)
		(end 88.562434 -232.659428)
		(width 0.09525)
		(layer "In2.Cu")
		(net "M_C_CPU1_SA_DQS_DN<6>")
	)
	(arc
		(start 91.759532 -232.659428)
		(mid 92.040964 -232.583673)
		(end 92.322396 -232.659428)
		(width 0.09525)
		(layer "In2.Cu")
		(net "M_C_CPU1_SA_DQS_DN<6>")
	)
	(arc
		(start 89.51087 -232.664254)
		(mid 89.695902 -232.710168)
		(end 89.879678 -232.659428)
		(width 0.09525)
		(layer "In2.Cu")
		(net "M_C_CPU1_SA_DQS_DN<6>")
	)
	(arc
		(start 90.819478 -232.659428)
		(mid 91.10091 -232.583673)
		(end 91.382342 -232.659428)
		(width 0.09525)
		(layer "In2.Cu")
		(net "M_C_CPU1_SA_DQS_DN<6>")
	)
	(arc
		(start 81.050892 -232.664254)
		(mid 81.235924 -232.710168)
		(end 81.4197 -232.659428)
		(width 0.09525)
		(layer "In2.Cu")
		(net "M_C_CPU1_SA_DQS_DN<6>")
	)
	(arc
		(start 77.789024 -228.63048)
		(mid 77.968764 -228.832229)
		(end 78.033626 -229.094538)
		(width 0.09525)
		(layer "In2.Cu")
		(net "M_C_CPU1_SA_DQS_DN<6>")
	)
	(arc
		(start 80.102456 -232.659428)
		(mid 80.286231 -232.7102)
		(end 80.471264 -232.664254)
		(width 0.09525)
		(layer "In2.Cu")
		(net "M_C_CPU1_SA_DQS_DN<6>")
	)
	(arc
		(start 84.810854 -232.664254)
		(mid 84.995886 -232.710168)
		(end 85.179662 -232.659428)
		(width 0.09525)
		(layer "In2.Cu")
		(net "M_C_CPU1_SA_DQS_DN<6>")
	)
	(arc
		(start 81.4197 -232.659428)
		(mid 81.701132 -232.583673)
		(end 81.982564 -232.659428)
		(width 0.09525)
		(layer "In2.Cu")
		(net "M_C_CPU1_SA_DQS_DN<6>")
	)
	(arc
		(start 92.322396 -232.659428)
		(mid 92.506171 -232.7102)
		(end 92.691204 -232.664254)
		(width 0.09525)
		(layer "In2.Cu")
		(net "M_C_CPU1_SA_DQS_DN<6>")
	)
	(arc
		(start 88.562434 -232.659428)
		(mid 88.746209 -232.7102)
		(end 88.931242 -232.664254)
		(width 0.09525)
		(layer "In2.Cu")
		(net "M_C_CPU1_SA_DQS_DN<6>")
	)
	(arc
		(start 79.443326 -231.524302)
		(mid 79.484783 -231.696342)
		(end 79.600044 -231.830626)
		(width 0.09525)
		(layer "In2.Cu")
		(net "M_C_CPU1_SA_DQS_DN<6>")
	)
	(arc
		(start 84.239608 -232.659428)
		(mid 84.52104 -232.583673)
		(end 84.802472 -232.659428)
		(width 0.09525)
		(layer "In2.Cu")
		(net "M_C_CPU1_SA_DQS_DN<6>")
	)
	(arc
		(start 92.699586 -232.659428)
		(mid 92.981018 -232.583673)
		(end 93.26245 -232.659428)
		(width 0.09525)
		(layer "In2.Cu")
		(net "M_C_CPU1_SA_DQS_DN<6>")
	)
	(arc
		(start 87.62238 -232.659428)
		(mid 87.806155 -232.7102)
		(end 87.991188 -232.664254)
		(width 0.09525)
		(layer "In2.Cu")
		(net "M_C_CPU1_SA_DQS_DN<6>")
	)
	(arc
		(start 83.862418 -232.659428)
		(mid 84.046193 -232.7102)
		(end 84.231226 -232.664254)
		(width 0.09525)
		(layer "In2.Cu")
		(net "M_C_CPU1_SA_DQS_DN<6>")
	)
	(arc
		(start 79.670656 -231.87152)
		(mid 79.849106 -232.07299)
		(end 79.91348 -232.334308)
		(width 0.09525)
		(layer "In2.Cu")
		(net "M_C_CPU1_SA_DQS_DN<6>")
	)
	(arc
		(start 79.197708 -231.05999)
		(mid 79.378163 -231.261656)
		(end 79.443326 -231.524302)
		(width 0.09525)
		(layer "In2.Cu")
		(net "M_C_CPU1_SA_DQS_DN<6>")
	)
	(arc
		(start 86.68258 -232.659428)
		(mid 86.871048 -232.710105)
		(end 87.059516 -232.659428)
		(width 0.09525)
		(layer "In2.Cu")
		(net "M_C_CPU1_SA_DQS_DN<6>")
	)
	(arc
		(start 77.40904 -227.912422)
		(mid 77.514421 -228.062855)
		(end 77.561694 -228.240336)
		(width 0.09525)
		(layer "In2.Cu")
		(net "M_C_CPU1_SA_DQS_DN<6>")
	)
	(arc
		(start 93.270832 -232.664254)
		(mid 93.455864 -232.710168)
		(end 93.63964 -232.659428)
		(width 0.09525)
		(layer "In2.Cu")
		(net "M_C_CPU1_SA_DQS_DN<6>")
	)
	(arc
		(start 78.033626 -229.094538)
		(mid 78.075087 -229.266463)
		(end 78.190344 -229.400608)
		(width 0.09525)
		(layer "In2.Cu")
		(net "M_C_CPU1_SA_DQS_DN<6>")
	)
	(arc
		(start 78.50378 -229.90429)
		(mid 78.546027 -230.077865)
		(end 78.663292 -230.212646)
		(width 0.09525)
		(layer "In2.Cu")
		(net "M_C_CPU1_SA_DQS_DN<6>")
	)
	(arc
		(start 79.91348 -232.334308)
		(mid 79.955145 -232.506755)
		(end 80.07096 -232.64114)
		(width 0.09525)
		(layer "In2.Cu")
		(net "M_C_CPU1_SA_DQS_DN<6>")
	)
	(arc
		(start 83.299554 -232.659428)
		(mid 83.580986 -232.583673)
		(end 83.862418 -232.659428)
		(width 0.09525)
		(layer "In2.Cu")
		(net "M_C_CPU1_SA_DQS_DN<6>")
	)
	(arc
		(start 82.922364 -232.659428)
		(mid 83.106139 -232.7102)
		(end 83.291172 -232.664254)
		(width 0.09525)
		(layer "In2.Cu")
		(net "M_C_CPU1_SA_DQS_DN<6>")
	)
	(arc
		(start 86.119716 -232.659428)
		(mid 86.401148 -232.583673)
		(end 86.68258 -232.659428)
		(width 0.09525)
		(layer "In2.Cu")
		(net "M_C_CPU1_SA_DQS_DN<6>")
	)
	(arc
		(start 78.729332 -230.251)
		(mid 78.908567 -230.452508)
		(end 78.973426 -230.714296)
		(width 0.09525)
		(layer "In2.Cu")
		(net "M_C_CPU1_SA_DQS_DN<6>")
	)
	(arc
		(start 85.750908 -232.664254)
		(mid 85.93594 -232.710168)
		(end 86.119716 -232.659428)
		(width 0.09525)
		(layer "In2.Cu")
		(net "M_C_CPU1_SA_DQS_DN<6>")
	)
	(arc
		(start 85.179662 -232.659428)
		(mid 85.461094 -232.583673)
		(end 85.742526 -232.659428)
		(width 0.09525)
		(layer "In2.Cu")
		(net "M_C_CPU1_SA_DQS_DN<6>")
	)
	(segment
		(start 95.797878 -227.740464)
		(end 95.331026 -227.474526)
		(width 0.12954)
		(layer "F.Cu")
		(net "M_C_CPU1_SA_DQS_DN<5>")
	)
	(segment
		(start 81.480914 -225.35134)
		(end 81.51241 -225.369628)
		(width 0.09525)
		(layer "In2.Cu")
		(net "M_C_CPU1_SA_DQS_DN<5>")
	)
	(segment
		(start 50.819812 -201.680572)
		(end 51.147472 -202.008232)
		(width 0.16002)
		(layer "In2.Cu")
		(net "M_C_CPU1_SA_DQS_DN<5>")
	)
	(segment
		(start 80.069182 -222.920052)
		(end 80.102964 -222.93961)
		(width 0.09525)
		(layer "In2.Cu")
		(net "M_C_CPU1_SA_DQS_DN<5>")
	)
	(segment
		(start 79.502254 -221.198186)
		(end 79.443326 -221.257114)
		(width 0.09525)
		(layer "In2.Cu")
		(net "M_C_CPU1_SA_DQS_DN<5>")
	)
	(segment
		(start 42.106342 -201.660252)
		(end 43.23207 -201.660252)
		(width 0.16002)
		(layer "In2.Cu")
		(net "M_C_CPU1_SA_DQS_DN<5>")
	)
	(segment
		(start 56.421528 -202.511152)
		(end 56.921908 -202.511152)
		(width 0.16002)
		(layer "In2.Cu")
		(net "M_C_CPU1_SA_DQS_DN<5>")
	)
	(segment
		(start 91.75115 -227.804472)
		(end 91.759532 -227.799646)
		(width 0.09525)
		(layer "In2.Cu")
		(net "M_C_CPU1_SA_DQS_DN<5>")
	)
	(segment
		(start 57.72404 -201.70902)
		(end 58.378598 -201.70902)
		(width 0.16002)
		(layer "In2.Cu")
		(net "M_C_CPU1_SA_DQS_DN<5>")
	)
	(segment
		(start 89.502488 -227.799646)
		(end 89.51087 -227.804472)
		(width 0.09525)
		(layer "In2.Cu")
		(net "M_C_CPU1_SA_DQS_DN<5>")
	)
	(segment
		(start 72.107044 -212.048598)
		(end 79.502254 -219.443808)
		(width 0.16002)
		(layer "In2.Cu")
		(net "M_C_CPU1_SA_DQS_DN<5>")
	)
	(segment
		(start 81.51241 -225.369628)
		(end 81.55051 -225.391726)
		(width 0.09525)
		(layer "In2.Cu")
		(net "M_C_CPU1_SA_DQS_DN<5>")
	)
	(segment
		(start 81.04251 -224.559622)
		(end 81.08061 -224.58172)
		(width 0.09525)
		(layer "In2.Cu")
		(net "M_C_CPU1_SA_DQS_DN<5>")
	)
	(segment
		(start 95.461836 -227.82657)
		(end 95.48495 -227.739956)
		(width 0.09525)
		(layer "In2.Cu")
		(net "M_C_CPU1_SA_DQS_DN<5>")
	)
	(segment
		(start 88.931242 -227.804472)
		(end 88.939624 -227.799646)
		(width 0.09525)
		(layer "In2.Cu")
		(net "M_C_CPU1_SA_DQS_DN<5>")
	)
	(segment
		(start 58.378598 -201.70902)
		(end 58.63717 -201.967592)
		(width 0.16002)
		(layer "In2.Cu")
		(net "M_C_CPU1_SA_DQS_DN<5>")
	)
	(segment
		(start 81.950052 -226.160838)
		(end 81.982564 -226.179634)
		(width 0.09525)
		(layer "In2.Cu")
		(net "M_C_CPU1_SA_DQS_DN<5>")
	)
	(segment
		(start 72.107044 -211.391246)
		(end 72.107044 -212.048598)
		(width 0.16002)
		(layer "In2.Cu")
		(net "M_C_CPU1_SA_DQS_DN<5>")
	)
	(segment
		(start 83.291172 -227.804472)
		(end 83.299554 -227.799646)
		(width 0.09525)
		(layer "In2.Cu")
		(net "M_C_CPU1_SA_DQS_DN<5>")
	)
	(segment
		(start 58.63717 -201.967592)
		(end 60.563506 -201.967592)
		(width 0.16002)
		(layer "In2.Cu")
		(net "M_C_CPU1_SA_DQS_DN<5>")
	)
	(segment
		(start 84.802472 -227.799646)
		(end 84.810854 -227.804472)
		(width 0.09525)
		(layer "In2.Cu")
		(net "M_C_CPU1_SA_DQS_DN<5>")
	)
	(segment
		(start 54.322472 -202.831192)
		(end 56.101488 -202.831192)
		(width 0.16002)
		(layer "In2.Cu")
		(net "M_C_CPU1_SA_DQS_DN<5>")
	)
	(segment
		(start 82.452464 -226.98964)
		(end 82.490564 -227.011738)
		(width 0.09525)
		(layer "In2.Cu")
		(net "M_C_CPU1_SA_DQS_DN<5>")
	)
	(segment
		(start 43.839384 -202.267566)
		(end 46.118526 -202.267566)
		(width 0.16002)
		(layer "In2.Cu")
		(net "M_C_CPU1_SA_DQS_DN<5>")
	)
	(segment
		(start 41.907206 -201.859388)
		(end 42.106342 -201.660252)
		(width 0.16002)
		(layer "In2.Cu")
		(net "M_C_CPU1_SA_DQS_DN<5>")
	)
	(segment
		(start 80.57261 -223.749616)
		(end 80.607662 -223.77019)
		(width 0.09525)
		(layer "In2.Cu")
		(net "M_C_CPU1_SA_DQS_DN<5>")
	)
	(segment
		(start 87.991188 -227.804472)
		(end 87.99957 -227.799646)
		(width 0.09525)
		(layer "In2.Cu")
		(net "M_C_CPU1_SA_DQS_DN<5>")
	)
	(segment
		(start 79.502254 -219.443808)
		(end 79.502254 -221.174564)
		(width 0.16002)
		(layer "In2.Cu")
		(net "M_C_CPU1_SA_DQS_DN<5>")
	)
	(segment
		(start 82.419952 -226.970844)
		(end 82.452464 -226.98964)
		(width 0.09525)
		(layer "In2.Cu")
		(net "M_C_CPU1_SA_DQS_DN<5>")
	)
	(segment
		(start 50.206148 -201.680572)
		(end 50.819812 -201.680572)
		(width 0.16002)
		(layer "In2.Cu")
		(net "M_C_CPU1_SA_DQS_DN<5>")
	)
	(segment
		(start 51.147472 -202.008232)
		(end 53.499512 -202.008232)
		(width 0.16002)
		(layer "In2.Cu")
		(net "M_C_CPU1_SA_DQS_DN<5>")
	)
	(segment
		(start 81.982564 -226.179634)
		(end 82.017616 -226.200208)
		(width 0.09525)
		(layer "In2.Cu")
		(net "M_C_CPU1_SA_DQS_DN<5>")
	)
	(segment
		(start 40.514016 -201.859388)
		(end 41.907206 -201.859388)
		(width 0.16002)
		(layer "In2.Cu")
		(net "M_C_CPU1_SA_DQS_DN<5>")
	)
	(segment
		(start 40.23995 -201.585322)
		(end 40.514016 -201.859388)
		(width 0.16002)
		(layer "In2.Cu")
		(net "M_C_CPU1_SA_DQS_DN<5>")
	)
	(segment
		(start 93.26245 -227.799646)
		(end 93.270832 -227.804472)
		(width 0.09525)
		(layer "In2.Cu")
		(net "M_C_CPU1_SA_DQS_DN<5>")
	)
	(segment
		(start 56.101488 -202.831192)
		(end 56.421528 -202.511152)
		(width 0.16002)
		(layer "In2.Cu")
		(net "M_C_CPU1_SA_DQS_DN<5>")
	)
	(segment
		(start 53.499512 -202.008232)
		(end 54.322472 -202.831192)
		(width 0.16002)
		(layer "In2.Cu")
		(net "M_C_CPU1_SA_DQS_DN<5>")
	)
	(segment
		(start 79.443326 -221.257114)
		(end 79.443326 -221.80423)
		(width 0.09525)
		(layer "In2.Cu")
		(net "M_C_CPU1_SA_DQS_DN<5>")
	)
	(segment
		(start 81.009998 -224.540826)
		(end 81.04251 -224.559622)
		(width 0.09525)
		(layer "In2.Cu")
		(net "M_C_CPU1_SA_DQS_DN<5>")
	)
	(segment
		(start 95.48495 -227.739956)
		(end 95.331026 -227.474526)
		(width 0.09525)
		(layer "In2.Cu")
		(net "M_C_CPU1_SA_DQS_DN<5>")
	)
	(segment
		(start 63.836042 -203.120244)
		(end 72.107044 -211.391246)
		(width 0.16002)
		(layer "In2.Cu")
		(net "M_C_CPU1_SA_DQS_DN<5>")
	)
	(segment
		(start 84.231226 -227.804472)
		(end 84.239608 -227.799646)
		(width 0.09525)
		(layer "In2.Cu")
		(net "M_C_CPU1_SA_DQS_DN<5>")
	)
	(segment
		(start 79.632556 -222.129604)
		(end 79.671926 -222.152464)
		(width 0.09525)
		(layer "In2.Cu")
		(net "M_C_CPU1_SA_DQS_DN<5>")
	)
	(segment
		(start 49.352708 -202.534012)
		(end 50.206148 -201.680572)
		(width 0.16002)
		(layer "In2.Cu")
		(net "M_C_CPU1_SA_DQS_DN<5>")
	)
	(segment
		(start 43.23207 -201.660252)
		(end 43.839384 -202.267566)
		(width 0.16002)
		(layer "In2.Cu")
		(net "M_C_CPU1_SA_DQS_DN<5>")
	)
	(segment
		(start 82.890868 -227.781358)
		(end 82.922364 -227.799646)
		(width 0.09525)
		(layer "In2.Cu")
		(net "M_C_CPU1_SA_DQS_DN<5>")
	)
	(segment
		(start 79.539592 -222.036132)
		(end 79.632556 -222.129604)
		(width 0.09525)
		(layer "In2.Cu")
		(net "M_C_CPU1_SA_DQS_DN<5>")
	)
	(segment
		(start 46.118526 -202.267566)
		(end 46.709076 -202.858116)
		(width 0.16002)
		(layer "In2.Cu")
		(net "M_C_CPU1_SA_DQS_DN<5>")
	)
	(segment
		(start 85.742526 -227.799646)
		(end 85.750908 -227.804472)
		(width 0.09525)
		(layer "In2.Cu")
		(net "M_C_CPU1_SA_DQS_DN<5>")
	)
	(segment
		(start 61.716158 -203.120244)
		(end 63.836042 -203.120244)
		(width 0.16002)
		(layer "In2.Cu")
		(net "M_C_CPU1_SA_DQS_DN<5>")
	)
	(segment
		(start 56.921908 -202.511152)
		(end 57.72404 -201.70902)
		(width 0.16002)
		(layer "In2.Cu")
		(net "M_C_CPU1_SA_DQS_DN<5>")
	)
	(segment
		(start 80.540098 -223.73082)
		(end 80.57261 -223.749616)
		(width 0.09525)
		(layer "In2.Cu")
		(net "M_C_CPU1_SA_DQS_DN<5>")
	)
	(segment
		(start 92.691204 -227.804472)
		(end 92.699586 -227.799646)
		(width 0.09525)
		(layer "In2.Cu")
		(net "M_C_CPU1_SA_DQS_DN<5>")
	)
	(segment
		(start 46.709076 -202.858116)
		(end 48.538384 -202.858116)
		(width 0.16002)
		(layer "In2.Cu")
		(net "M_C_CPU1_SA_DQS_DN<5>")
	)
	(segment
		(start 48.538384 -202.858116)
		(end 48.862488 -202.534012)
		(width 0.16002)
		(layer "In2.Cu")
		(net "M_C_CPU1_SA_DQS_DN<5>")
	)
	(segment
		(start 80.102964 -222.93961)
		(end 80.136492 -222.959168)
		(width 0.09525)
		(layer "In2.Cu")
		(net "M_C_CPU1_SA_DQS_DN<5>")
	)
	(segment
		(start 79.539338 -222.036132)
		(end 79.539592 -222.036132)
		(width 0.09525)
		(layer "In2.Cu")
		(net "M_C_CPU1_SA_DQS_DN<5>")
	)
	(segment
		(start 79.502254 -221.174564)
		(end 79.502254 -221.198186)
		(width 0.09525)
		(layer "In2.Cu")
		(net "M_C_CPU1_SA_DQS_DN<5>")
	)
	(segment
		(start 60.563506 -201.967592)
		(end 61.716158 -203.120244)
		(width 0.16002)
		(layer "In2.Cu")
		(net "M_C_CPU1_SA_DQS_DN<5>")
	)
	(segment
		(start 48.862488 -202.534012)
		(end 49.352708 -202.534012)
		(width 0.16002)
		(layer "In2.Cu")
		(net "M_C_CPU1_SA_DQS_DN<5>")
	)
	(segment
		(start 94.202504 -227.799646)
		(end 94.210886 -227.804472)
		(width 0.09525)
		(layer "In2.Cu")
		(net "M_C_CPU1_SA_DQS_DN<5>")
	)
	(arc
		(start 82.733388 -227.474526)
		(mid 82.775053 -227.646973)
		(end 82.890868 -227.781358)
		(width 0.09525)
		(layer "In2.Cu")
		(net "M_C_CPU1_SA_DQS_DN<5>")
	)
	(arc
		(start 86.68258 -227.799646)
		(mid 86.871048 -227.850323)
		(end 87.059516 -227.799646)
		(width 0.09525)
		(layer "In2.Cu")
		(net "M_C_CPU1_SA_DQS_DN<5>")
	)
	(arc
		(start 82.263234 -226.66452)
		(mid 82.304691 -226.83656)
		(end 82.419952 -226.970844)
		(width 0.09525)
		(layer "In2.Cu")
		(net "M_C_CPU1_SA_DQS_DN<5>")
	)
	(arc
		(start 80.85328 -224.234502)
		(mid 80.894737 -224.406542)
		(end 81.009998 -224.540826)
		(width 0.09525)
		(layer "In2.Cu")
		(net "M_C_CPU1_SA_DQS_DN<5>")
	)
	(arc
		(start 81.793334 -225.854514)
		(mid 81.834791 -226.026554)
		(end 81.950052 -226.160838)
		(width 0.09525)
		(layer "In2.Cu")
		(net "M_C_CPU1_SA_DQS_DN<5>")
	)
	(arc
		(start 80.38338 -223.424496)
		(mid 80.424837 -223.596536)
		(end 80.540098 -223.73082)
		(width 0.09525)
		(layer "In2.Cu")
		(net "M_C_CPU1_SA_DQS_DN<5>")
	)
	(arc
		(start 81.55051 -225.391726)
		(mid 81.72896 -225.593196)
		(end 81.793334 -225.854514)
		(width 0.09525)
		(layer "In2.Cu")
		(net "M_C_CPU1_SA_DQS_DN<5>")
	)
	(arc
		(start 90.442542 -227.799646)
		(mid 90.63101 -227.850323)
		(end 90.819478 -227.799646)
		(width 0.09525)
		(layer "In2.Cu")
		(net "M_C_CPU1_SA_DQS_DN<5>")
	)
	(arc
		(start 83.862418 -227.799646)
		(mid 84.046193 -227.850418)
		(end 84.231226 -227.804472)
		(width 0.09525)
		(layer "In2.Cu")
		(net "M_C_CPU1_SA_DQS_DN<5>")
	)
	(arc
		(start 94.579694 -227.799646)
		(mid 94.861126 -227.723891)
		(end 95.142558 -227.799646)
		(width 0.09525)
		(layer "In2.Cu")
		(net "M_C_CPU1_SA_DQS_DN<5>")
	)
	(arc
		(start 87.059516 -227.799646)
		(mid 87.340948 -227.723891)
		(end 87.62238 -227.799646)
		(width 0.09525)
		(layer "In2.Cu")
		(net "M_C_CPU1_SA_DQS_DN<5>")
	)
	(arc
		(start 84.810854 -227.804472)
		(mid 84.995886 -227.850386)
		(end 85.179662 -227.799646)
		(width 0.09525)
		(layer "In2.Cu")
		(net "M_C_CPU1_SA_DQS_DN<5>")
	)
	(arc
		(start 82.922364 -227.799646)
		(mid 83.106139 -227.850418)
		(end 83.291172 -227.804472)
		(width 0.09525)
		(layer "In2.Cu")
		(net "M_C_CPU1_SA_DQS_DN<5>")
	)
	(arc
		(start 83.299554 -227.799646)
		(mid 83.580986 -227.723891)
		(end 83.862418 -227.799646)
		(width 0.09525)
		(layer "In2.Cu")
		(net "M_C_CPU1_SA_DQS_DN<5>")
	)
	(arc
		(start 79.671926 -222.152464)
		(mid 79.849612 -222.353756)
		(end 79.913734 -222.61449)
		(width 0.09525)
		(layer "In2.Cu")
		(net "M_C_CPU1_SA_DQS_DN<5>")
	)
	(arc
		(start 80.136492 -222.959168)
		(mid 80.317871 -223.1611)
		(end 80.38338 -223.424496)
		(width 0.09525)
		(layer "In2.Cu")
		(net "M_C_CPU1_SA_DQS_DN<5>")
	)
	(arc
		(start 88.562434 -227.799646)
		(mid 88.746209 -227.850418)
		(end 88.931242 -227.804472)
		(width 0.09525)
		(layer "In2.Cu")
		(net "M_C_CPU1_SA_DQS_DN<5>")
	)
	(arc
		(start 88.939624 -227.799646)
		(mid 89.221056 -227.723891)
		(end 89.502488 -227.799646)
		(width 0.09525)
		(layer "In2.Cu")
		(net "M_C_CPU1_SA_DQS_DN<5>")
	)
	(arc
		(start 79.913734 -222.61449)
		(mid 79.954836 -222.785896)
		(end 80.069182 -222.920052)
		(width 0.09525)
		(layer "In2.Cu")
		(net "M_C_CPU1_SA_DQS_DN<5>")
	)
	(arc
		(start 87.62238 -227.799646)
		(mid 87.806155 -227.850418)
		(end 87.991188 -227.804472)
		(width 0.09525)
		(layer "In2.Cu")
		(net "M_C_CPU1_SA_DQS_DN<5>")
	)
	(arc
		(start 95.142558 -227.799646)
		(mid 95.299185 -227.848832)
		(end 95.461836 -227.82657)
		(width 0.09525)
		(layer "In2.Cu")
		(net "M_C_CPU1_SA_DQS_DN<5>")
	)
	(arc
		(start 85.750908 -227.804472)
		(mid 85.93594 -227.850386)
		(end 86.119716 -227.799646)
		(width 0.09525)
		(layer "In2.Cu")
		(net "M_C_CPU1_SA_DQS_DN<5>")
	)
	(arc
		(start 94.210886 -227.804472)
		(mid 94.395918 -227.850386)
		(end 94.579694 -227.799646)
		(width 0.09525)
		(layer "In2.Cu")
		(net "M_C_CPU1_SA_DQS_DN<5>")
	)
	(arc
		(start 85.179662 -227.799646)
		(mid 85.461094 -227.723891)
		(end 85.742526 -227.799646)
		(width 0.09525)
		(layer "In2.Cu")
		(net "M_C_CPU1_SA_DQS_DN<5>")
	)
	(arc
		(start 89.51087 -227.804472)
		(mid 89.695902 -227.850386)
		(end 89.879678 -227.799646)
		(width 0.09525)
		(layer "In2.Cu")
		(net "M_C_CPU1_SA_DQS_DN<5>")
	)
	(arc
		(start 93.270832 -227.804472)
		(mid 93.455864 -227.850386)
		(end 93.63964 -227.799646)
		(width 0.09525)
		(layer "In2.Cu")
		(net "M_C_CPU1_SA_DQS_DN<5>")
	)
	(arc
		(start 90.819478 -227.799646)
		(mid 91.10091 -227.723891)
		(end 91.382342 -227.799646)
		(width 0.09525)
		(layer "In2.Cu")
		(net "M_C_CPU1_SA_DQS_DN<5>")
	)
	(arc
		(start 93.63964 -227.799646)
		(mid 93.921072 -227.723891)
		(end 94.202504 -227.799646)
		(width 0.09525)
		(layer "In2.Cu")
		(net "M_C_CPU1_SA_DQS_DN<5>")
	)
	(arc
		(start 82.490564 -227.011738)
		(mid 82.669014 -227.213208)
		(end 82.733388 -227.474526)
		(width 0.09525)
		(layer "In2.Cu")
		(net "M_C_CPU1_SA_DQS_DN<5>")
	)
	(arc
		(start 89.879678 -227.799646)
		(mid 90.16111 -227.723891)
		(end 90.442542 -227.799646)
		(width 0.09525)
		(layer "In2.Cu")
		(net "M_C_CPU1_SA_DQS_DN<5>")
	)
	(arc
		(start 91.382342 -227.799646)
		(mid 91.566117 -227.850418)
		(end 91.75115 -227.804472)
		(width 0.09525)
		(layer "In2.Cu")
		(net "M_C_CPU1_SA_DQS_DN<5>")
	)
	(arc
		(start 92.699586 -227.799646)
		(mid 92.981018 -227.723891)
		(end 93.26245 -227.799646)
		(width 0.09525)
		(layer "In2.Cu")
		(net "M_C_CPU1_SA_DQS_DN<5>")
	)
	(arc
		(start 79.443326 -221.80423)
		(mid 79.46831 -221.92972)
		(end 79.539338 -222.036132)
		(width 0.09525)
		(layer "In2.Cu")
		(net "M_C_CPU1_SA_DQS_DN<5>")
	)
	(arc
		(start 81.08061 -224.58172)
		(mid 81.25906 -224.78319)
		(end 81.323434 -225.044508)
		(width 0.09525)
		(layer "In2.Cu")
		(net "M_C_CPU1_SA_DQS_DN<5>")
	)
	(arc
		(start 87.99957 -227.799646)
		(mid 88.281002 -227.723891)
		(end 88.562434 -227.799646)
		(width 0.09525)
		(layer "In2.Cu")
		(net "M_C_CPU1_SA_DQS_DN<5>")
	)
	(arc
		(start 86.119716 -227.799646)
		(mid 86.401148 -227.723891)
		(end 86.68258 -227.799646)
		(width 0.09525)
		(layer "In2.Cu")
		(net "M_C_CPU1_SA_DQS_DN<5>")
	)
	(arc
		(start 92.322396 -227.799646)
		(mid 92.506171 -227.850418)
		(end 92.691204 -227.804472)
		(width 0.09525)
		(layer "In2.Cu")
		(net "M_C_CPU1_SA_DQS_DN<5>")
	)
	(arc
		(start 80.607662 -223.77019)
		(mid 80.788117 -223.971856)
		(end 80.85328 -224.234502)
		(width 0.09525)
		(layer "In2.Cu")
		(net "M_C_CPU1_SA_DQS_DN<5>")
	)
	(arc
		(start 91.759532 -227.799646)
		(mid 92.040964 -227.723891)
		(end 92.322396 -227.799646)
		(width 0.09525)
		(layer "In2.Cu")
		(net "M_C_CPU1_SA_DQS_DN<5>")
	)
	(arc
		(start 81.323434 -225.044508)
		(mid 81.365099 -225.216955)
		(end 81.480914 -225.35134)
		(width 0.09525)
		(layer "In2.Cu")
		(net "M_C_CPU1_SA_DQS_DN<5>")
	)
	(arc
		(start 82.017616 -226.200208)
		(mid 82.198071 -226.401874)
		(end 82.263234 -226.66452)
		(width 0.09525)
		(layer "In2.Cu")
		(net "M_C_CPU1_SA_DQS_DN<5>")
	)
	(arc
		(start 84.239608 -227.799646)
		(mid 84.52104 -227.723891)
		(end 84.802472 -227.799646)
		(width 0.09525)
		(layer "In2.Cu")
		(net "M_C_CPU1_SA_DQS_DN<5>")
	)
	(segment
		(start 94.857824 -247.180354)
		(end 94.390972 -246.914416)
		(width 0.12954)
		(layer "F.Cu")
		(net "M_C_CPU1_SA_DQS_DN<4>")
	)
	(segment
		(start 75.979528 -246.641874)
		(end 76.038456 -246.582946)
		(width 0.09525)
		(layer "In2.Cu")
		(net "M_C_CPU1_SA_DQS_DN<4>")
	)
	(segment
		(start 94.13621 -246.622316)
		(end 94.237048 -246.648986)
		(width 0.09525)
		(layer "In2.Cu")
		(net "M_C_CPU1_SA_DQS_DN<4>")
	)
	(segment
		(start 66.714116 -244.6528)
		(end 67.415664 -243.951252)
		(width 0.16002)
		(layer "In2.Cu")
		(net "M_C_CPU1_SA_DQS_DN<4>")
	)
	(segment
		(start 88.931242 -246.58447)
		(end 88.939624 -246.589296)
		(width 0.09525)
		(layer "In2.Cu")
		(net "M_C_CPU1_SA_DQS_DN<4>")
	)
	(segment
		(start 44.340018 -238.985298)
		(end 44.61383 -238.711486)
		(width 0.16002)
		(layer "In2.Cu")
		(net "M_C_CPU1_SA_DQS_DN<4>")
	)
	(segment
		(start 45.776134 -238.562388)
		(end 48.55337 -238.562388)
		(width 0.16002)
		(layer "In2.Cu")
		(net "M_C_CPU1_SA_DQS_DN<4>")
	)
	(segment
		(start 66.140584 -242.755928)
		(end 66.33718 -242.952524)
		(width 0.16002)
		(layer "In2.Cu")
		(net "M_C_CPU1_SA_DQS_DN<4>")
	)
	(segment
		(start 64.628776 -242.523264)
		(end 65.124076 -243.018564)
		(width 0.16002)
		(layer "In2.Cu")
		(net "M_C_CPU1_SA_DQS_DN<4>")
	)
	(segment
		(start 66.186812 -244.6528)
		(end 66.714116 -244.6528)
		(width 0.16002)
		(layer "In2.Cu")
		(net "M_C_CPU1_SA_DQS_DN<4>")
	)
	(segment
		(start 56.98871 -238.895128)
		(end 57.78627 -238.097568)
		(width 0.16002)
		(layer "In2.Cu")
		(net "M_C_CPU1_SA_DQS_DN<4>")
	)
	(segment
		(start 49.56937 -238.877348)
		(end 50.42281 -238.023908)
		(width 0.16002)
		(layer "In2.Cu")
		(net "M_C_CPU1_SA_DQS_DN<4>")
	)
	(segment
		(start 78.584806 -246.580914)
		(end 78.599284 -246.589296)
		(width 0.09525)
		(layer "In2.Cu")
		(net "M_C_CPU1_SA_DQS_DN<4>")
	)
	(segment
		(start 48.86833 -238.877348)
		(end 49.56937 -238.877348)
		(width 0.16002)
		(layer "In2.Cu")
		(net "M_C_CPU1_SA_DQS_DN<4>")
	)
	(segment
		(start 48.55337 -238.562388)
		(end 48.86833 -238.877348)
		(width 0.16002)
		(layer "In2.Cu")
		(net "M_C_CPU1_SA_DQS_DN<4>")
	)
	(segment
		(start 67.692524 -243.951252)
		(end 67.88912 -244.147848)
		(width 0.16002)
		(layer "In2.Cu")
		(net "M_C_CPU1_SA_DQS_DN<4>")
	)
	(segment
		(start 81.04251 -246.589296)
		(end 81.050892 -246.58447)
		(width 0.09525)
		(layer "In2.Cu")
		(net "M_C_CPU1_SA_DQS_DN<4>")
	)
	(segment
		(start 64.077088 -242.523264)
		(end 64.628776 -242.523264)
		(width 0.16002)
		(layer "In2.Cu")
		(net "M_C_CPU1_SA_DQS_DN<4>")
	)
	(segment
		(start 62.203584 -240.098072)
		(end 62.203584 -240.64976)
		(width 0.16002)
		(layer "In2.Cu")
		(net "M_C_CPU1_SA_DQS_DN<4>")
	)
	(segment
		(start 78.599284 -246.589296)
		(end 78.614016 -246.597932)
		(width 0.09525)
		(layer "In2.Cu")
		(net "M_C_CPU1_SA_DQS_DN<4>")
	)
	(segment
		(start 61.881512 -239.776)
		(end 62.203584 -240.098072)
		(width 0.16002)
		(layer "In2.Cu")
		(net "M_C_CPU1_SA_DQS_DN<4>")
	)
	(segment
		(start 63.577216 -242.023392)
		(end 64.077088 -242.523264)
		(width 0.16002)
		(layer "In2.Cu")
		(net "M_C_CPU1_SA_DQS_DN<4>")
	)
	(segment
		(start 67.438778 -245.402354)
		(end 68.096384 -246.05996)
		(width 0.16002)
		(layer "In2.Cu")
		(net "M_C_CPU1_SA_DQS_DN<4>")
	)
	(segment
		(start 56.10987 -238.605568)
		(end 56.39943 -238.895128)
		(width 0.16002)
		(layer "In2.Cu")
		(net "M_C_CPU1_SA_DQS_DN<4>")
	)
	(segment
		(start 63.255144 -241.149632)
		(end 63.577216 -241.471704)
		(width 0.16002)
		(layer "In2.Cu")
		(net "M_C_CPU1_SA_DQS_DN<4>")
	)
	(segment
		(start 77.732636 -246.949214)
		(end 78.02245 -246.6594)
		(width 0.09525)
		(layer "In2.Cu")
		(net "M_C_CPU1_SA_DQS_DN<4>")
	)
	(segment
		(start 56.39943 -238.895128)
		(end 56.98871 -238.895128)
		(width 0.16002)
		(layer "In2.Cu")
		(net "M_C_CPU1_SA_DQS_DN<4>")
	)
	(segment
		(start 80.087724 -246.597932)
		(end 80.102456 -246.589296)
		(width 0.09525)
		(layer "In2.Cu")
		(net "M_C_CPU1_SA_DQS_DN<4>")
	)
	(segment
		(start 65.601088 -243.018564)
		(end 65.863724 -242.755928)
		(width 0.16002)
		(layer "In2.Cu")
		(net "M_C_CPU1_SA_DQS_DN<4>")
	)
	(segment
		(start 45.627036 -238.711486)
		(end 45.776134 -238.562388)
		(width 0.16002)
		(layer "In2.Cu")
		(net "M_C_CPU1_SA_DQS_DN<4>")
	)
	(segment
		(start 92.691204 -246.58447)
		(end 92.699586 -246.589296)
		(width 0.09525)
		(layer "In2.Cu")
		(net "M_C_CPU1_SA_DQS_DN<4>")
	)
	(segment
		(start 50.82921 -238.023908)
		(end 51.140614 -237.712504)
		(width 0.16002)
		(layer "In2.Cu")
		(net "M_C_CPU1_SA_DQS_DN<4>")
	)
	(segment
		(start 76.038456 -246.582946)
		(end 76.196952 -246.582946)
		(width 0.09525)
		(layer "In2.Cu")
		(net "M_C_CPU1_SA_DQS_DN<4>")
	)
	(segment
		(start 66.33718 -242.952524)
		(end 66.33718 -243.229384)
		(width 0.16002)
		(layer "In2.Cu")
		(net "M_C_CPU1_SA_DQS_DN<4>")
	)
	(segment
		(start 76.56322 -246.949214)
		(end 77.732636 -246.949214)
		(width 0.09525)
		(layer "In2.Cu")
		(net "M_C_CPU1_SA_DQS_DN<4>")
	)
	(segment
		(start 51.140614 -237.712504)
		(end 52.774342 -237.712504)
		(width 0.16002)
		(layer "In2.Cu")
		(net "M_C_CPU1_SA_DQS_DN<4>")
	)
	(segment
		(start 62.203584 -240.64976)
		(end 62.703456 -241.149632)
		(width 0.16002)
		(layer "In2.Cu")
		(net "M_C_CPU1_SA_DQS_DN<4>")
	)
	(segment
		(start 67.88912 -244.424708)
		(end 67.438778 -244.87505)
		(width 0.16002)
		(layer "In2.Cu")
		(net "M_C_CPU1_SA_DQS_DN<4>")
	)
	(segment
		(start 60.829952 -239.276128)
		(end 61.329824 -239.776)
		(width 0.16002)
		(layer "In2.Cu")
		(net "M_C_CPU1_SA_DQS_DN<4>")
	)
	(segment
		(start 65.81394 -244.279928)
		(end 66.186812 -244.6528)
		(width 0.16002)
		(layer "In2.Cu")
		(net "M_C_CPU1_SA_DQS_DN<4>")
	)
	(segment
		(start 85.742526 -246.589296)
		(end 85.750908 -246.58447)
		(width 0.09525)
		(layer "In2.Cu")
		(net "M_C_CPU1_SA_DQS_DN<4>")
	)
	(segment
		(start 94.237048 -246.648986)
		(end 94.390972 -246.914416)
		(width 0.09525)
		(layer "In2.Cu")
		(net "M_C_CPU1_SA_DQS_DN<4>")
	)
	(segment
		(start 76.196952 -246.582946)
		(end 76.56322 -246.949214)
		(width 0.09525)
		(layer "In2.Cu")
		(net "M_C_CPU1_SA_DQS_DN<4>")
	)
	(segment
		(start 67.438778 -244.87505)
		(end 67.438778 -245.402354)
		(width 0.16002)
		(layer "In2.Cu")
		(net "M_C_CPU1_SA_DQS_DN<4>")
	)
	(segment
		(start 68.096384 -246.05996)
		(end 74.997056 -246.05996)
		(width 0.16002)
		(layer "In2.Cu")
		(net "M_C_CPU1_SA_DQS_DN<4>")
	)
	(segment
		(start 60.283852 -237.747048)
		(end 60.55487 -238.018066)
		(width 0.16002)
		(layer "In2.Cu")
		(net "M_C_CPU1_SA_DQS_DN<4>")
	)
	(segment
		(start 57.78627 -238.097568)
		(end 58.26379 -238.097568)
		(width 0.16002)
		(layer "In2.Cu")
		(net "M_C_CPU1_SA_DQS_DN<4>")
	)
	(segment
		(start 58.61431 -237.747048)
		(end 60.283852 -237.747048)
		(width 0.16002)
		(layer "In2.Cu")
		(net "M_C_CPU1_SA_DQS_DN<4>")
	)
	(segment
		(start 67.88912 -244.147848)
		(end 67.88912 -244.424708)
		(width 0.16002)
		(layer "In2.Cu")
		(net "M_C_CPU1_SA_DQS_DN<4>")
	)
	(segment
		(start 89.502488 -246.589296)
		(end 89.51087 -246.58447)
		(width 0.09525)
		(layer "In2.Cu")
		(net "M_C_CPU1_SA_DQS_DN<4>")
	)
	(segment
		(start 50.42281 -238.023908)
		(end 50.82921 -238.023908)
		(width 0.16002)
		(layer "In2.Cu")
		(net "M_C_CPU1_SA_DQS_DN<4>")
	)
	(segment
		(start 53.667406 -238.605568)
		(end 56.10987 -238.605568)
		(width 0.16002)
		(layer "In2.Cu")
		(net "M_C_CPU1_SA_DQS_DN<4>")
	)
	(segment
		(start 93.26245 -246.589296)
		(end 93.270832 -246.58447)
		(width 0.09525)
		(layer "In2.Cu")
		(net "M_C_CPU1_SA_DQS_DN<4>")
	)
	(segment
		(start 63.577216 -241.471704)
		(end 63.577216 -242.023392)
		(width 0.16002)
		(layer "In2.Cu")
		(net "M_C_CPU1_SA_DQS_DN<4>")
	)
	(segment
		(start 60.55487 -238.018066)
		(end 60.55487 -238.449358)
		(width 0.16002)
		(layer "In2.Cu")
		(net "M_C_CPU1_SA_DQS_DN<4>")
	)
	(segment
		(start 75.57897 -246.641874)
		(end 75.955906 -246.641874)
		(width 0.16002)
		(layer "In2.Cu")
		(net "M_C_CPU1_SA_DQS_DN<4>")
	)
	(segment
		(start 65.863724 -242.755928)
		(end 66.140584 -242.755928)
		(width 0.16002)
		(layer "In2.Cu")
		(net "M_C_CPU1_SA_DQS_DN<4>")
	)
	(segment
		(start 91.75115 -246.58447)
		(end 91.759532 -246.589296)
		(width 0.09525)
		(layer "In2.Cu")
		(net "M_C_CPU1_SA_DQS_DN<4>")
	)
	(segment
		(start 75.955906 -246.641874)
		(end 75.979528 -246.641874)
		(width 0.09525)
		(layer "In2.Cu")
		(net "M_C_CPU1_SA_DQS_DN<4>")
	)
	(segment
		(start 87.991188 -246.58447)
		(end 87.99957 -246.589296)
		(width 0.09525)
		(layer "In2.Cu")
		(net "M_C_CPU1_SA_DQS_DN<4>")
	)
	(segment
		(start 60.55487 -238.449358)
		(end 60.829952 -238.72444)
		(width 0.16002)
		(layer "In2.Cu")
		(net "M_C_CPU1_SA_DQS_DN<4>")
	)
	(segment
		(start 52.774342 -237.712504)
		(end 53.667406 -238.605568)
		(width 0.16002)
		(layer "In2.Cu")
		(net "M_C_CPU1_SA_DQS_DN<4>")
	)
	(segment
		(start 67.415664 -243.951252)
		(end 67.692524 -243.951252)
		(width 0.16002)
		(layer "In2.Cu")
		(net "M_C_CPU1_SA_DQS_DN<4>")
	)
	(segment
		(start 84.802472 -246.589296)
		(end 84.810854 -246.58447)
		(width 0.09525)
		(layer "In2.Cu")
		(net "M_C_CPU1_SA_DQS_DN<4>")
	)
	(segment
		(start 60.829952 -238.72444)
		(end 60.829952 -239.276128)
		(width 0.16002)
		(layer "In2.Cu")
		(net "M_C_CPU1_SA_DQS_DN<4>")
	)
	(segment
		(start 65.124076 -243.018564)
		(end 65.601088 -243.018564)
		(width 0.16002)
		(layer "In2.Cu")
		(net "M_C_CPU1_SA_DQS_DN<4>")
	)
	(segment
		(start 80.471264 -246.58447)
		(end 80.479646 -246.589296)
		(width 0.09525)
		(layer "In2.Cu")
		(net "M_C_CPU1_SA_DQS_DN<4>")
	)
	(segment
		(start 44.61383 -238.711486)
		(end 45.627036 -238.711486)
		(width 0.16002)
		(layer "In2.Cu")
		(net "M_C_CPU1_SA_DQS_DN<4>")
	)
	(segment
		(start 61.329824 -239.776)
		(end 61.881512 -239.776)
		(width 0.16002)
		(layer "In2.Cu")
		(net "M_C_CPU1_SA_DQS_DN<4>")
	)
	(segment
		(start 65.81394 -243.752624)
		(end 65.81394 -244.279928)
		(width 0.16002)
		(layer "In2.Cu")
		(net "M_C_CPU1_SA_DQS_DN<4>")
	)
	(segment
		(start 83.291172 -246.58447)
		(end 83.299554 -246.589296)
		(width 0.09525)
		(layer "In2.Cu")
		(net "M_C_CPU1_SA_DQS_DN<4>")
	)
	(segment
		(start 62.703456 -241.149632)
		(end 63.255144 -241.149632)
		(width 0.16002)
		(layer "In2.Cu")
		(net "M_C_CPU1_SA_DQS_DN<4>")
	)
	(segment
		(start 84.231226 -246.58447)
		(end 84.239608 -246.589296)
		(width 0.09525)
		(layer "In2.Cu")
		(net "M_C_CPU1_SA_DQS_DN<4>")
	)
	(segment
		(start 74.997056 -246.05996)
		(end 75.57897 -246.641874)
		(width 0.16002)
		(layer "In2.Cu")
		(net "M_C_CPU1_SA_DQS_DN<4>")
	)
	(segment
		(start 58.26379 -238.097568)
		(end 58.61431 -237.747048)
		(width 0.16002)
		(layer "In2.Cu")
		(net "M_C_CPU1_SA_DQS_DN<4>")
	)
	(segment
		(start 66.33718 -243.229384)
		(end 65.81394 -243.752624)
		(width 0.16002)
		(layer "In2.Cu")
		(net "M_C_CPU1_SA_DQS_DN<4>")
	)
	(segment
		(start 79.16164 -246.589296)
		(end 79.173578 -246.582438)
		(width 0.09525)
		(layer "In2.Cu")
		(net "M_C_CPU1_SA_DQS_DN<4>")
	)
	(arc
		(start 86.68258 -246.589296)
		(mid 86.871048 -246.538619)
		(end 87.059516 -246.589296)
		(width 0.09525)
		(layer "In2.Cu")
		(net "M_C_CPU1_SA_DQS_DN<4>")
	)
	(arc
		(start 92.699586 -246.589296)
		(mid 92.981018 -246.665051)
		(end 93.26245 -246.589296)
		(width 0.09525)
		(layer "In2.Cu")
		(net "M_C_CPU1_SA_DQS_DN<4>")
	)
	(arc
		(start 91.759532 -246.589296)
		(mid 92.040964 -246.665051)
		(end 92.322396 -246.589296)
		(width 0.09525)
		(layer "In2.Cu")
		(net "M_C_CPU1_SA_DQS_DN<4>")
	)
	(arc
		(start 90.819478 -246.589296)
		(mid 91.10091 -246.665051)
		(end 91.382342 -246.589296)
		(width 0.09525)
		(layer "In2.Cu")
		(net "M_C_CPU1_SA_DQS_DN<4>")
	)
	(arc
		(start 80.479646 -246.589296)
		(mid 80.761078 -246.665051)
		(end 81.04251 -246.589296)
		(width 0.09525)
		(layer "In2.Cu")
		(net "M_C_CPU1_SA_DQS_DN<4>")
	)
	(arc
		(start 81.050892 -246.58447)
		(mid 81.235924 -246.538556)
		(end 81.4197 -246.589296)
		(width 0.09525)
		(layer "In2.Cu")
		(net "M_C_CPU1_SA_DQS_DN<4>")
	)
	(arc
		(start 79.539084 -246.589296)
		(mid 79.812266 -246.665238)
		(end 80.087724 -246.597932)
		(width 0.09525)
		(layer "In2.Cu")
		(net "M_C_CPU1_SA_DQS_DN<4>")
	)
	(arc
		(start 87.059516 -246.589296)
		(mid 87.340948 -246.665051)
		(end 87.62238 -246.589296)
		(width 0.09525)
		(layer "In2.Cu")
		(net "M_C_CPU1_SA_DQS_DN<4>")
	)
	(arc
		(start 84.810854 -246.58447)
		(mid 84.995886 -246.538556)
		(end 85.179662 -246.589296)
		(width 0.09525)
		(layer "In2.Cu")
		(net "M_C_CPU1_SA_DQS_DN<4>")
	)
	(arc
		(start 82.3595 -246.589296)
		(mid 82.640932 -246.665051)
		(end 82.922364 -246.589296)
		(width 0.09525)
		(layer "In2.Cu")
		(net "M_C_CPU1_SA_DQS_DN<4>")
	)
	(arc
		(start 85.179662 -246.589296)
		(mid 85.461094 -246.665051)
		(end 85.742526 -246.589296)
		(width 0.09525)
		(layer "In2.Cu")
		(net "M_C_CPU1_SA_DQS_DN<4>")
	)
	(arc
		(start 88.562434 -246.589296)
		(mid 88.746209 -246.538524)
		(end 88.931242 -246.58447)
		(width 0.09525)
		(layer "In2.Cu")
		(net "M_C_CPU1_SA_DQS_DN<4>")
	)
	(arc
		(start 83.299554 -246.589296)
		(mid 83.580986 -246.665051)
		(end 83.862418 -246.589296)
		(width 0.09525)
		(layer "In2.Cu")
		(net "M_C_CPU1_SA_DQS_DN<4>")
	)
	(arc
		(start 81.4197 -246.589296)
		(mid 81.701132 -246.665051)
		(end 81.982564 -246.589296)
		(width 0.09525)
		(layer "In2.Cu")
		(net "M_C_CPU1_SA_DQS_DN<4>")
	)
	(arc
		(start 89.51087 -246.58447)
		(mid 89.695902 -246.538556)
		(end 89.879678 -246.589296)
		(width 0.09525)
		(layer "In2.Cu")
		(net "M_C_CPU1_SA_DQS_DN<4>")
	)
	(arc
		(start 81.982564 -246.589296)
		(mid 82.171032 -246.538619)
		(end 82.3595 -246.589296)
		(width 0.09525)
		(layer "In2.Cu")
		(net "M_C_CPU1_SA_DQS_DN<4>")
	)
	(arc
		(start 78.02245 -246.6594)
		(mid 78.125602 -246.633835)
		(end 78.222094 -246.589296)
		(width 0.09525)
		(layer "In2.Cu")
		(net "M_C_CPU1_SA_DQS_DN<4>")
	)
	(arc
		(start 84.239608 -246.589296)
		(mid 84.52104 -246.665051)
		(end 84.802472 -246.589296)
		(width 0.09525)
		(layer "In2.Cu")
		(net "M_C_CPU1_SA_DQS_DN<4>")
	)
	(arc
		(start 78.222094 -246.589296)
		(mid 78.402373 -246.538465)
		(end 78.584806 -246.580914)
		(width 0.09525)
		(layer "In2.Cu")
		(net "M_C_CPU1_SA_DQS_DN<4>")
	)
	(arc
		(start 94.11589 -246.63019)
		(mid 94.126089 -246.626353)
		(end 94.13621 -246.622316)
		(width 0.09525)
		(layer "In2.Cu")
		(net "M_C_CPU1_SA_DQS_DN<4>")
	)
	(arc
		(start 79.173578 -246.582438)
		(mid 79.357213 -246.538488)
		(end 79.539084 -246.589296)
		(width 0.09525)
		(layer "In2.Cu")
		(net "M_C_CPU1_SA_DQS_DN<4>")
	)
	(arc
		(start 90.442542 -246.589296)
		(mid 90.63101 -246.538619)
		(end 90.819478 -246.589296)
		(width 0.09525)
		(layer "In2.Cu")
		(net "M_C_CPU1_SA_DQS_DN<4>")
	)
	(arc
		(start 89.879678 -246.589296)
		(mid 90.16111 -246.665051)
		(end 90.442542 -246.589296)
		(width 0.09525)
		(layer "In2.Cu")
		(net "M_C_CPU1_SA_DQS_DN<4>")
	)
	(arc
		(start 85.750908 -246.58447)
		(mid 85.93594 -246.538556)
		(end 86.119716 -246.589296)
		(width 0.09525)
		(layer "In2.Cu")
		(net "M_C_CPU1_SA_DQS_DN<4>")
	)
	(arc
		(start 87.62238 -246.589296)
		(mid 87.806155 -246.538524)
		(end 87.991188 -246.58447)
		(width 0.09525)
		(layer "In2.Cu")
		(net "M_C_CPU1_SA_DQS_DN<4>")
	)
	(arc
		(start 80.102456 -246.589296)
		(mid 80.286231 -246.538524)
		(end 80.471264 -246.58447)
		(width 0.09525)
		(layer "In2.Cu")
		(net "M_C_CPU1_SA_DQS_DN<4>")
	)
	(arc
		(start 83.862418 -246.589296)
		(mid 84.046193 -246.538524)
		(end 84.231226 -246.58447)
		(width 0.09525)
		(layer "In2.Cu")
		(net "M_C_CPU1_SA_DQS_DN<4>")
	)
	(arc
		(start 93.270832 -246.58447)
		(mid 93.455864 -246.538556)
		(end 93.63964 -246.589296)
		(width 0.09525)
		(layer "In2.Cu")
		(net "M_C_CPU1_SA_DQS_DN<4>")
	)
	(arc
		(start 92.322396 -246.589296)
		(mid 92.506171 -246.538524)
		(end 92.691204 -246.58447)
		(width 0.09525)
		(layer "In2.Cu")
		(net "M_C_CPU1_SA_DQS_DN<4>")
	)
	(arc
		(start 86.119716 -246.589296)
		(mid 86.401148 -246.665051)
		(end 86.68258 -246.589296)
		(width 0.09525)
		(layer "In2.Cu")
		(net "M_C_CPU1_SA_DQS_DN<4>")
	)
	(arc
		(start 82.922364 -246.589296)
		(mid 83.106139 -246.538524)
		(end 83.291172 -246.58447)
		(width 0.09525)
		(layer "In2.Cu")
		(net "M_C_CPU1_SA_DQS_DN<4>")
	)
	(arc
		(start 78.614016 -246.597932)
		(mid 78.888967 -246.665075)
		(end 79.16164 -246.589296)
		(width 0.09525)
		(layer "In2.Cu")
		(net "M_C_CPU1_SA_DQS_DN<4>")
	)
	(arc
		(start 93.63964 -246.589296)
		(mid 93.873184 -246.663002)
		(end 94.11589 -246.63019)
		(width 0.09525)
		(layer "In2.Cu")
		(net "M_C_CPU1_SA_DQS_DN<4>")
	)
	(arc
		(start 87.99957 -246.589296)
		(mid 88.281002 -246.665051)
		(end 88.562434 -246.589296)
		(width 0.09525)
		(layer "In2.Cu")
		(net "M_C_CPU1_SA_DQS_DN<4>")
	)
	(arc
		(start 91.382342 -246.589296)
		(mid 91.566117 -246.538524)
		(end 91.75115 -246.58447)
		(width 0.09525)
		(layer "In2.Cu")
		(net "M_C_CPU1_SA_DQS_DN<4>")
	)
	(arc
		(start 88.939624 -246.589296)
		(mid 89.221056 -246.665051)
		(end 89.502488 -246.589296)
		(width 0.09525)
		(layer "In2.Cu")
		(net "M_C_CPU1_SA_DQS_DN<4>")
	)
	(segment
		(start 94.857824 -242.320318)
		(end 94.390972 -242.05438)
		(width 0.12954)
		(layer "F.Cu")
		(net "M_C_CPU1_SA_DQS_DN<3>")
	)
	(segment
		(start 79.53121 -241.724434)
		(end 79.539592 -241.72926)
		(width 0.09525)
		(layer "In2.Cu")
		(net "M_C_CPU1_SA_DQS_DN<3>")
	)
	(segment
		(start 60.314078 -228.397054)
		(end 61.3156 -229.398576)
		(width 0.16002)
		(layer "In2.Cu")
		(net "M_C_CPU1_SA_DQS_DN<3>")
	)
	(segment
		(start 46.943518 -229.212394)
		(end 48.55337 -229.212394)
		(width 0.16002)
		(layer "In2.Cu")
		(net "M_C_CPU1_SA_DQS_DN<3>")
	)
	(segment
		(start 50.42281 -228.673914)
		(end 50.800762 -228.673914)
		(width 0.16002)
		(layer "In2.Cu")
		(net "M_C_CPU1_SA_DQS_DN<3>")
	)
	(segment
		(start 72.1995 -240.361216)
		(end 76.04633 -240.361216)
		(width 0.16002)
		(layer "In2.Cu")
		(net "M_C_CPU1_SA_DQS_DN<3>")
	)
	(segment
		(start 76.04633 -240.361216)
		(end 76.069952 -240.361216)
		(width 0.09525)
		(layer "In2.Cu")
		(net "M_C_CPU1_SA_DQS_DN<3>")
	)
	(segment
		(start 76.12888 -240.302288)
		(end 76.398882 -240.302288)
		(width 0.09525)
		(layer "In2.Cu")
		(net "M_C_CPU1_SA_DQS_DN<3>")
	)
	(segment
		(start 63.625222 -231.786938)
		(end 72.1995 -240.361216)
		(width 0.16002)
		(layer "In2.Cu")
		(net "M_C_CPU1_SA_DQS_DN<3>")
	)
	(segment
		(start 58.61431 -228.397054)
		(end 60.314078 -228.397054)
		(width 0.16002)
		(layer "In2.Cu")
		(net "M_C_CPU1_SA_DQS_DN<3>")
	)
	(segment
		(start 76.398882 -240.302288)
		(end 76.571348 -240.474754)
		(width 0.09525)
		(layer "In2.Cu")
		(net "M_C_CPU1_SA_DQS_DN<3>")
	)
	(segment
		(start 81.04251 -241.72926)
		(end 81.050892 -241.724434)
		(width 0.09525)
		(layer "In2.Cu")
		(net "M_C_CPU1_SA_DQS_DN<3>")
	)
	(segment
		(start 64.307212 -230.301292)
		(end 64.307212 -230.577644)
		(width 0.16002)
		(layer "In2.Cu")
		(net "M_C_CPU1_SA_DQS_DN<3>")
	)
	(segment
		(start 76.977494 -240.474754)
		(end 78.180692 -241.677952)
		(width 0.09525)
		(layer "In2.Cu")
		(net "M_C_CPU1_SA_DQS_DN<3>")
	)
	(segment
		(start 91.75115 -241.724434)
		(end 91.759532 -241.72926)
		(width 0.09525)
		(layer "In2.Cu")
		(net "M_C_CPU1_SA_DQS_DN<3>")
	)
	(segment
		(start 52.765198 -228.36251)
		(end 53.658262 -229.255574)
		(width 0.16002)
		(layer "In2.Cu")
		(net "M_C_CPU1_SA_DQS_DN<3>")
	)
	(segment
		(start 85.742526 -241.72926)
		(end 85.750908 -241.724434)
		(width 0.09525)
		(layer "In2.Cu")
		(net "M_C_CPU1_SA_DQS_DN<3>")
	)
	(segment
		(start 57.78627 -228.747574)
		(end 58.26379 -228.747574)
		(width 0.16002)
		(layer "In2.Cu")
		(net "M_C_CPU1_SA_DQS_DN<3>")
	)
	(segment
		(start 62.25159 -229.886002)
		(end 62.25159 -230.413306)
		(width 0.16002)
		(layer "In2.Cu")
		(net "M_C_CPU1_SA_DQS_DN<3>")
	)
	(segment
		(start 46.79442 -229.361492)
		(end 46.943518 -229.212394)
		(width 0.16002)
		(layer "In2.Cu")
		(net "M_C_CPU1_SA_DQS_DN<3>")
	)
	(segment
		(start 94.237048 -241.78895)
		(end 94.390972 -242.05438)
		(width 0.09525)
		(layer "In2.Cu")
		(net "M_C_CPU1_SA_DQS_DN<3>")
	)
	(segment
		(start 62.538356 -228.652578)
		(end 62.815216 -228.652578)
		(width 0.16002)
		(layer "In2.Cu")
		(net "M_C_CPU1_SA_DQS_DN<3>")
	)
	(segment
		(start 56.135778 -229.255574)
		(end 56.468518 -229.588314)
		(width 0.16002)
		(layer "In2.Cu")
		(net "M_C_CPU1_SA_DQS_DN<3>")
	)
	(segment
		(start 84.802472 -241.72926)
		(end 84.810854 -241.724434)
		(width 0.09525)
		(layer "In2.Cu")
		(net "M_C_CPU1_SA_DQS_DN<3>")
	)
	(segment
		(start 44.340018 -229.635304)
		(end 44.61383 -229.361492)
		(width 0.16002)
		(layer "In2.Cu")
		(net "M_C_CPU1_SA_DQS_DN<3>")
	)
	(segment
		(start 62.25159 -230.413306)
		(end 62.624462 -230.786178)
		(width 0.16002)
		(layer "In2.Cu")
		(net "M_C_CPU1_SA_DQS_DN<3>")
	)
	(segment
		(start 80.471264 -241.724434)
		(end 80.479646 -241.72926)
		(width 0.09525)
		(layer "In2.Cu")
		(net "M_C_CPU1_SA_DQS_DN<3>")
	)
	(segment
		(start 88.931242 -241.724434)
		(end 88.939624 -241.72926)
		(width 0.09525)
		(layer "In2.Cu")
		(net "M_C_CPU1_SA_DQS_DN<3>")
	)
	(segment
		(start 63.011812 -228.849174)
		(end 63.011812 -229.12578)
		(width 0.16002)
		(layer "In2.Cu")
		(net "M_C_CPU1_SA_DQS_DN<3>")
	)
	(segment
		(start 51.112166 -228.36251)
		(end 52.765198 -228.36251)
		(width 0.16002)
		(layer "In2.Cu")
		(net "M_C_CPU1_SA_DQS_DN<3>")
	)
	(segment
		(start 63.15202 -230.786178)
		(end 63.833756 -230.104442)
		(width 0.16002)
		(layer "In2.Cu")
		(net "M_C_CPU1_SA_DQS_DN<3>")
	)
	(segment
		(start 62.624462 -230.786178)
		(end 63.15202 -230.786178)
		(width 0.16002)
		(layer "In2.Cu")
		(net "M_C_CPU1_SA_DQS_DN<3>")
	)
	(segment
		(start 76.571348 -240.474754)
		(end 76.977494 -240.474754)
		(width 0.09525)
		(layer "In2.Cu")
		(net "M_C_CPU1_SA_DQS_DN<3>")
	)
	(segment
		(start 94.13621 -241.76228)
		(end 94.237048 -241.78895)
		(width 0.09525)
		(layer "In2.Cu")
		(net "M_C_CPU1_SA_DQS_DN<3>")
	)
	(segment
		(start 44.61383 -229.361492)
		(end 46.79442 -229.361492)
		(width 0.16002)
		(layer "In2.Cu")
		(net "M_C_CPU1_SA_DQS_DN<3>")
	)
	(segment
		(start 48.980344 -229.639368)
		(end 49.457356 -229.639368)
		(width 0.16002)
		(layer "In2.Cu")
		(net "M_C_CPU1_SA_DQS_DN<3>")
	)
	(segment
		(start 56.94553 -229.588314)
		(end 57.78627 -228.747574)
		(width 0.16002)
		(layer "In2.Cu")
		(net "M_C_CPU1_SA_DQS_DN<3>")
	)
	(segment
		(start 50.800762 -228.673914)
		(end 51.112166 -228.36251)
		(width 0.16002)
		(layer "In2.Cu")
		(net "M_C_CPU1_SA_DQS_DN<3>")
	)
	(segment
		(start 61.792358 -229.398576)
		(end 62.538356 -228.652578)
		(width 0.16002)
		(layer "In2.Cu")
		(net "M_C_CPU1_SA_DQS_DN<3>")
	)
	(segment
		(start 53.658262 -229.255574)
		(end 56.135778 -229.255574)
		(width 0.16002)
		(layer "In2.Cu")
		(net "M_C_CPU1_SA_DQS_DN<3>")
	)
	(segment
		(start 64.110362 -230.104442)
		(end 64.307212 -230.301292)
		(width 0.16002)
		(layer "In2.Cu")
		(net "M_C_CPU1_SA_DQS_DN<3>")
	)
	(segment
		(start 83.291172 -241.724434)
		(end 83.299554 -241.72926)
		(width 0.09525)
		(layer "In2.Cu")
		(net "M_C_CPU1_SA_DQS_DN<3>")
	)
	(segment
		(start 84.231226 -241.724434)
		(end 84.239608 -241.72926)
		(width 0.09525)
		(layer "In2.Cu")
		(net "M_C_CPU1_SA_DQS_DN<3>")
	)
	(segment
		(start 93.26245 -241.72926)
		(end 93.270832 -241.724434)
		(width 0.09525)
		(layer "In2.Cu")
		(net "M_C_CPU1_SA_DQS_DN<3>")
	)
	(segment
		(start 87.991188 -241.724434)
		(end 87.99957 -241.72926)
		(width 0.09525)
		(layer "In2.Cu")
		(net "M_C_CPU1_SA_DQS_DN<3>")
	)
	(segment
		(start 63.833756 -230.104442)
		(end 64.110362 -230.104442)
		(width 0.16002)
		(layer "In2.Cu")
		(net "M_C_CPU1_SA_DQS_DN<3>")
	)
	(segment
		(start 92.691204 -241.724434)
		(end 92.699586 -241.72926)
		(width 0.09525)
		(layer "In2.Cu")
		(net "M_C_CPU1_SA_DQS_DN<3>")
	)
	(segment
		(start 63.011812 -229.12578)
		(end 62.25159 -229.886002)
		(width 0.16002)
		(layer "In2.Cu")
		(net "M_C_CPU1_SA_DQS_DN<3>")
	)
	(segment
		(start 49.457356 -229.639368)
		(end 50.42281 -228.673914)
		(width 0.16002)
		(layer "In2.Cu")
		(net "M_C_CPU1_SA_DQS_DN<3>")
	)
	(segment
		(start 89.502488 -241.72926)
		(end 89.51087 -241.724434)
		(width 0.09525)
		(layer "In2.Cu")
		(net "M_C_CPU1_SA_DQS_DN<3>")
	)
	(segment
		(start 48.55337 -229.212394)
		(end 48.980344 -229.639368)
		(width 0.16002)
		(layer "In2.Cu")
		(net "M_C_CPU1_SA_DQS_DN<3>")
	)
	(segment
		(start 58.26379 -228.747574)
		(end 58.61431 -228.397054)
		(width 0.16002)
		(layer "In2.Cu")
		(net "M_C_CPU1_SA_DQS_DN<3>")
	)
	(segment
		(start 63.625222 -231.259634)
		(end 63.625222 -231.786938)
		(width 0.16002)
		(layer "In2.Cu")
		(net "M_C_CPU1_SA_DQS_DN<3>")
	)
	(segment
		(start 64.307212 -230.577644)
		(end 63.625222 -231.259634)
		(width 0.16002)
		(layer "In2.Cu")
		(net "M_C_CPU1_SA_DQS_DN<3>")
	)
	(segment
		(start 62.815216 -228.652578)
		(end 63.011812 -228.849174)
		(width 0.16002)
		(layer "In2.Cu")
		(net "M_C_CPU1_SA_DQS_DN<3>")
	)
	(segment
		(start 61.3156 -229.398576)
		(end 61.792358 -229.398576)
		(width 0.16002)
		(layer "In2.Cu")
		(net "M_C_CPU1_SA_DQS_DN<3>")
	)
	(segment
		(start 56.468518 -229.588314)
		(end 56.94553 -229.588314)
		(width 0.16002)
		(layer "In2.Cu")
		(net "M_C_CPU1_SA_DQS_DN<3>")
	)
	(segment
		(start 76.069952 -240.361216)
		(end 76.12888 -240.302288)
		(width 0.09525)
		(layer "In2.Cu")
		(net "M_C_CPU1_SA_DQS_DN<3>")
	)
	(segment
		(start 78.180692 -241.677952)
		(end 78.41107 -241.677952)
		(width 0.09525)
		(layer "In2.Cu")
		(net "M_C_CPU1_SA_DQS_DN<3>")
	)
	(arc
		(start 82.922364 -241.72926)
		(mid 83.106139 -241.678488)
		(end 83.291172 -241.724434)
		(width 0.09525)
		(layer "In2.Cu")
		(net "M_C_CPU1_SA_DQS_DN<3>")
	)
	(arc
		(start 87.62238 -241.72926)
		(mid 87.806155 -241.678488)
		(end 87.991188 -241.724434)
		(width 0.09525)
		(layer "In2.Cu")
		(net "M_C_CPU1_SA_DQS_DN<3>")
	)
	(arc
		(start 89.879678 -241.72926)
		(mid 90.16111 -241.805015)
		(end 90.442542 -241.72926)
		(width 0.09525)
		(layer "In2.Cu")
		(net "M_C_CPU1_SA_DQS_DN<3>")
	)
	(arc
		(start 93.270832 -241.724434)
		(mid 93.455864 -241.67852)
		(end 93.63964 -241.72926)
		(width 0.09525)
		(layer "In2.Cu")
		(net "M_C_CPU1_SA_DQS_DN<3>")
	)
	(arc
		(start 79.539592 -241.72926)
		(mid 79.821024 -241.805015)
		(end 80.102456 -241.72926)
		(width 0.09525)
		(layer "In2.Cu")
		(net "M_C_CPU1_SA_DQS_DN<3>")
	)
	(arc
		(start 93.63964 -241.72926)
		(mid 93.873184 -241.802966)
		(end 94.11589 -241.770154)
		(width 0.09525)
		(layer "In2.Cu")
		(net "M_C_CPU1_SA_DQS_DN<3>")
	)
	(arc
		(start 80.479646 -241.72926)
		(mid 80.761078 -241.805015)
		(end 81.04251 -241.72926)
		(width 0.09525)
		(layer "In2.Cu")
		(net "M_C_CPU1_SA_DQS_DN<3>")
	)
	(arc
		(start 89.51087 -241.724434)
		(mid 89.695902 -241.67852)
		(end 89.879678 -241.72926)
		(width 0.09525)
		(layer "In2.Cu")
		(net "M_C_CPU1_SA_DQS_DN<3>")
	)
	(arc
		(start 84.239608 -241.72926)
		(mid 84.52104 -241.805015)
		(end 84.802472 -241.72926)
		(width 0.09525)
		(layer "In2.Cu")
		(net "M_C_CPU1_SA_DQS_DN<3>")
	)
	(arc
		(start 87.99957 -241.72926)
		(mid 88.281002 -241.805015)
		(end 88.562434 -241.72926)
		(width 0.09525)
		(layer "In2.Cu")
		(net "M_C_CPU1_SA_DQS_DN<3>")
	)
	(arc
		(start 85.750908 -241.724434)
		(mid 85.93594 -241.67852)
		(end 86.119716 -241.72926)
		(width 0.09525)
		(layer "In2.Cu")
		(net "M_C_CPU1_SA_DQS_DN<3>")
	)
	(arc
		(start 78.41107 -241.677952)
		(mid 78.508684 -241.691179)
		(end 78.599538 -241.72926)
		(width 0.09525)
		(layer "In2.Cu")
		(net "M_C_CPU1_SA_DQS_DN<3>")
	)
	(arc
		(start 90.819478 -241.72926)
		(mid 91.10091 -241.805015)
		(end 91.382342 -241.72926)
		(width 0.09525)
		(layer "In2.Cu")
		(net "M_C_CPU1_SA_DQS_DN<3>")
	)
	(arc
		(start 92.322396 -241.72926)
		(mid 92.506171 -241.678488)
		(end 92.691204 -241.724434)
		(width 0.09525)
		(layer "In2.Cu")
		(net "M_C_CPU1_SA_DQS_DN<3>")
	)
	(arc
		(start 86.68258 -241.72926)
		(mid 86.871048 -241.678583)
		(end 87.059516 -241.72926)
		(width 0.09525)
		(layer "In2.Cu")
		(net "M_C_CPU1_SA_DQS_DN<3>")
	)
	(arc
		(start 81.4197 -241.72926)
		(mid 81.701132 -241.805015)
		(end 81.982564 -241.72926)
		(width 0.09525)
		(layer "In2.Cu")
		(net "M_C_CPU1_SA_DQS_DN<3>")
	)
	(arc
		(start 91.382342 -241.72926)
		(mid 91.566117 -241.678488)
		(end 91.75115 -241.724434)
		(width 0.09525)
		(layer "In2.Cu")
		(net "M_C_CPU1_SA_DQS_DN<3>")
	)
	(arc
		(start 78.599538 -241.72926)
		(mid 78.88097 -241.805015)
		(end 79.162402 -241.72926)
		(width 0.09525)
		(layer "In2.Cu")
		(net "M_C_CPU1_SA_DQS_DN<3>")
	)
	(arc
		(start 86.119716 -241.72926)
		(mid 86.401148 -241.805015)
		(end 86.68258 -241.72926)
		(width 0.09525)
		(layer "In2.Cu")
		(net "M_C_CPU1_SA_DQS_DN<3>")
	)
	(arc
		(start 90.442542 -241.72926)
		(mid 90.63101 -241.678583)
		(end 90.819478 -241.72926)
		(width 0.09525)
		(layer "In2.Cu")
		(net "M_C_CPU1_SA_DQS_DN<3>")
	)
	(arc
		(start 92.699586 -241.72926)
		(mid 92.981018 -241.805015)
		(end 93.26245 -241.72926)
		(width 0.09525)
		(layer "In2.Cu")
		(net "M_C_CPU1_SA_DQS_DN<3>")
	)
	(arc
		(start 83.299554 -241.72926)
		(mid 83.580986 -241.805015)
		(end 83.862418 -241.72926)
		(width 0.09525)
		(layer "In2.Cu")
		(net "M_C_CPU1_SA_DQS_DN<3>")
	)
	(arc
		(start 87.059516 -241.72926)
		(mid 87.340948 -241.805015)
		(end 87.62238 -241.72926)
		(width 0.09525)
		(layer "In2.Cu")
		(net "M_C_CPU1_SA_DQS_DN<3>")
	)
	(arc
		(start 80.102456 -241.72926)
		(mid 80.286231 -241.678488)
		(end 80.471264 -241.724434)
		(width 0.09525)
		(layer "In2.Cu")
		(net "M_C_CPU1_SA_DQS_DN<3>")
	)
	(arc
		(start 91.759532 -241.72926)
		(mid 92.040964 -241.805015)
		(end 92.322396 -241.72926)
		(width 0.09525)
		(layer "In2.Cu")
		(net "M_C_CPU1_SA_DQS_DN<3>")
	)
	(arc
		(start 85.179662 -241.72926)
		(mid 85.461094 -241.805015)
		(end 85.742526 -241.72926)
		(width 0.09525)
		(layer "In2.Cu")
		(net "M_C_CPU1_SA_DQS_DN<3>")
	)
	(arc
		(start 81.982564 -241.72926)
		(mid 82.171032 -241.678583)
		(end 82.3595 -241.72926)
		(width 0.09525)
		(layer "In2.Cu")
		(net "M_C_CPU1_SA_DQS_DN<3>")
	)
	(arc
		(start 82.3595 -241.72926)
		(mid 82.640932 -241.805015)
		(end 82.922364 -241.72926)
		(width 0.09525)
		(layer "In2.Cu")
		(net "M_C_CPU1_SA_DQS_DN<3>")
	)
	(arc
		(start 94.11589 -241.770154)
		(mid 94.126089 -241.766317)
		(end 94.13621 -241.76228)
		(width 0.09525)
		(layer "In2.Cu")
		(net "M_C_CPU1_SA_DQS_DN<3>")
	)
	(arc
		(start 81.050892 -241.724434)
		(mid 81.235924 -241.67852)
		(end 81.4197 -241.72926)
		(width 0.09525)
		(layer "In2.Cu")
		(net "M_C_CPU1_SA_DQS_DN<3>")
	)
	(arc
		(start 88.939624 -241.72926)
		(mid 89.221056 -241.805015)
		(end 89.502488 -241.72926)
		(width 0.09525)
		(layer "In2.Cu")
		(net "M_C_CPU1_SA_DQS_DN<3>")
	)
	(arc
		(start 88.562434 -241.72926)
		(mid 88.746209 -241.678488)
		(end 88.931242 -241.724434)
		(width 0.09525)
		(layer "In2.Cu")
		(net "M_C_CPU1_SA_DQS_DN<3>")
	)
	(arc
		(start 79.162402 -241.72926)
		(mid 79.346177 -241.678488)
		(end 79.53121 -241.724434)
		(width 0.09525)
		(layer "In2.Cu")
		(net "M_C_CPU1_SA_DQS_DN<3>")
	)
	(arc
		(start 83.862418 -241.72926)
		(mid 84.046193 -241.678488)
		(end 84.231226 -241.724434)
		(width 0.09525)
		(layer "In2.Cu")
		(net "M_C_CPU1_SA_DQS_DN<3>")
	)
	(arc
		(start 84.810854 -241.724434)
		(mid 84.995886 -241.67852)
		(end 85.179662 -241.72926)
		(width 0.09525)
		(layer "In2.Cu")
		(net "M_C_CPU1_SA_DQS_DN<3>")
	)
	(segment
		(start 94.857824 -237.460282)
		(end 94.390972 -237.194344)
		(width 0.12954)
		(layer "F.Cu")
		(net "M_C_CPU1_SA_DQS_DN<2>")
	)
	(segment
		(start 50.42281 -219.32392)
		(end 50.82921 -219.32392)
		(width 0.16002)
		(layer "In2.Cu")
		(net "M_C_CPU1_SA_DQS_DN<2>")
	)
	(segment
		(start 46.77664 -220.011498)
		(end 46.925738 -219.8624)
		(width 0.16002)
		(layer "In2.Cu")
		(net "M_C_CPU1_SA_DQS_DN<2>")
	)
	(segment
		(start 51.140614 -219.012516)
		(end 52.771294 -219.012516)
		(width 0.16002)
		(layer "In2.Cu")
		(net "M_C_CPU1_SA_DQS_DN<2>")
	)
	(segment
		(start 84.802472 -236.869224)
		(end 84.810854 -236.864398)
		(width 0.09525)
		(layer "In2.Cu")
		(net "M_C_CPU1_SA_DQS_DN<2>")
	)
	(segment
		(start 58.26379 -219.39758)
		(end 58.61431 -219.04706)
		(width 0.16002)
		(layer "In2.Cu")
		(net "M_C_CPU1_SA_DQS_DN<2>")
	)
	(segment
		(start 56.39943 -220.19514)
		(end 56.98871 -220.19514)
		(width 0.16002)
		(layer "In2.Cu")
		(net "M_C_CPU1_SA_DQS_DN<2>")
	)
	(segment
		(start 83.291172 -236.864398)
		(end 83.299554 -236.869224)
		(width 0.09525)
		(layer "In2.Cu")
		(net "M_C_CPU1_SA_DQS_DN<2>")
	)
	(segment
		(start 93.26245 -236.869224)
		(end 93.270832 -236.864398)
		(width 0.09525)
		(layer "In2.Cu")
		(net "M_C_CPU1_SA_DQS_DN<2>")
	)
	(segment
		(start 80.087724 -236.87786)
		(end 80.102456 -236.869224)
		(width 0.09525)
		(layer "In2.Cu")
		(net "M_C_CPU1_SA_DQS_DN<2>")
	)
	(segment
		(start 53.664358 -219.90558)
		(end 56.10987 -219.90558)
		(width 0.16002)
		(layer "In2.Cu")
		(net "M_C_CPU1_SA_DQS_DN<2>")
	)
	(segment
		(start 73.981818 -233.780076)
		(end 74.885296 -234.683554)
		(width 0.16002)
		(layer "In2.Cu")
		(net "M_C_CPU1_SA_DQS_DN<2>")
	)
	(segment
		(start 75.979528 -234.683554)
		(end 76.03871 -234.624372)
		(width 0.09525)
		(layer "In2.Cu")
		(net "M_C_CPU1_SA_DQS_DN<2>")
	)
	(segment
		(start 64.19596 -220.618558)
		(end 64.19596 -220.895418)
		(width 0.16002)
		(layer "In2.Cu")
		(net "M_C_CPU1_SA_DQS_DN<2>")
	)
	(segment
		(start 92.691204 -236.864398)
		(end 92.699586 -236.869224)
		(width 0.09525)
		(layer "In2.Cu")
		(net "M_C_CPU1_SA_DQS_DN<2>")
	)
	(segment
		(start 56.98871 -220.19514)
		(end 57.78627 -219.39758)
		(width 0.16002)
		(layer "In2.Cu")
		(net "M_C_CPU1_SA_DQS_DN<2>")
	)
	(segment
		(start 61.82487 -219.702634)
		(end 61.82487 -219.242894)
		(width 0.16002)
		(layer "In2.Cu")
		(net "M_C_CPU1_SA_DQS_DN<2>")
	)
	(segment
		(start 49.56937 -220.17736)
		(end 50.42281 -219.32392)
		(width 0.16002)
		(layer "In2.Cu")
		(net "M_C_CPU1_SA_DQS_DN<2>")
	)
	(segment
		(start 62.020704 -219.04706)
		(end 62.624462 -219.04706)
		(width 0.16002)
		(layer "In2.Cu")
		(net "M_C_CPU1_SA_DQS_DN<2>")
	)
	(segment
		(start 60.924948 -220.075506)
		(end 61.451998 -220.075506)
		(width 0.16002)
		(layer "In2.Cu")
		(net "M_C_CPU1_SA_DQS_DN<2>")
	)
	(segment
		(start 62.54242 -219.801694)
		(end 62.54242 -220.328998)
		(width 0.16002)
		(layer "In2.Cu")
		(net "M_C_CPU1_SA_DQS_DN<2>")
	)
	(segment
		(start 85.742526 -236.869224)
		(end 85.750908 -236.864398)
		(width 0.09525)
		(layer "In2.Cu")
		(net "M_C_CPU1_SA_DQS_DN<2>")
	)
	(segment
		(start 78.239112 -236.215174)
		(end 78.858872 -236.215174)
		(width 0.09525)
		(layer "In2.Cu")
		(net "M_C_CPU1_SA_DQS_DN<2>")
	)
	(segment
		(start 81.04251 -236.869224)
		(end 81.050892 -236.864398)
		(width 0.09525)
		(layer "In2.Cu")
		(net "M_C_CPU1_SA_DQS_DN<2>")
	)
	(segment
		(start 76.982574 -234.624372)
		(end 77.26299 -234.904788)
		(width 0.09525)
		(layer "In2.Cu")
		(net "M_C_CPU1_SA_DQS_DN<2>")
	)
	(segment
		(start 71.234554 -231.032812)
		(end 71.689468 -231.487726)
		(width 0.16002)
		(layer "In2.Cu")
		(net "M_C_CPU1_SA_DQS_DN<2>")
	)
	(segment
		(start 48.55337 -219.8624)
		(end 48.86833 -220.17736)
		(width 0.16002)
		(layer "In2.Cu")
		(net "M_C_CPU1_SA_DQS_DN<2>")
	)
	(segment
		(start 63.916052 -221.175326)
		(end 63.916052 -221.70263)
		(width 0.16002)
		(layer "In2.Cu")
		(net "M_C_CPU1_SA_DQS_DN<2>")
	)
	(segment
		(start 70.315836 -230.114094)
		(end 70.955916 -230.114094)
		(width 0.16002)
		(layer "In2.Cu")
		(net "M_C_CPU1_SA_DQS_DN<2>")
	)
	(segment
		(start 75.955906 -234.683554)
		(end 75.979528 -234.683554)
		(width 0.09525)
		(layer "In2.Cu")
		(net "M_C_CPU1_SA_DQS_DN<2>")
	)
	(segment
		(start 46.925738 -219.8624)
		(end 48.55337 -219.8624)
		(width 0.16002)
		(layer "In2.Cu")
		(net "M_C_CPU1_SA_DQS_DN<2>")
	)
	(segment
		(start 71.689468 -231.487726)
		(end 72.329548 -231.487726)
		(width 0.16002)
		(layer "In2.Cu")
		(net "M_C_CPU1_SA_DQS_DN<2>")
	)
	(segment
		(start 44.340018 -220.28531)
		(end 44.61383 -220.011498)
		(width 0.16002)
		(layer "In2.Cu")
		(net "M_C_CPU1_SA_DQS_DN<2>")
	)
	(segment
		(start 77.26299 -234.904788)
		(end 77.26299 -235.239052)
		(width 0.09525)
		(layer "In2.Cu")
		(net "M_C_CPU1_SA_DQS_DN<2>")
	)
	(segment
		(start 44.61383 -220.011498)
		(end 46.77664 -220.011498)
		(width 0.16002)
		(layer "In2.Cu")
		(net "M_C_CPU1_SA_DQS_DN<2>")
	)
	(segment
		(start 60.552076 -219.702634)
		(end 60.924948 -220.075506)
		(width 0.16002)
		(layer "In2.Cu")
		(net "M_C_CPU1_SA_DQS_DN<2>")
	)
	(segment
		(start 62.822328 -219.244926)
		(end 62.822328 -219.521786)
		(width 0.16002)
		(layer "In2.Cu")
		(net "M_C_CPU1_SA_DQS_DN<2>")
	)
	(segment
		(start 64.19596 -220.895418)
		(end 63.916052 -221.175326)
		(width 0.16002)
		(layer "In2.Cu")
		(net "M_C_CPU1_SA_DQS_DN<2>")
	)
	(segment
		(start 63.916052 -221.70263)
		(end 70.01383 -227.800408)
		(width 0.16002)
		(layer "In2.Cu")
		(net "M_C_CPU1_SA_DQS_DN<2>")
	)
	(segment
		(start 48.86833 -220.17736)
		(end 49.56937 -220.17736)
		(width 0.16002)
		(layer "In2.Cu")
		(net "M_C_CPU1_SA_DQS_DN<2>")
	)
	(segment
		(start 87.991188 -236.864398)
		(end 87.99957 -236.869224)
		(width 0.09525)
		(layer "In2.Cu")
		(net "M_C_CPU1_SA_DQS_DN<2>")
	)
	(segment
		(start 80.471264 -236.864398)
		(end 80.479646 -236.869224)
		(width 0.09525)
		(layer "In2.Cu")
		(net "M_C_CPU1_SA_DQS_DN<2>")
	)
	(segment
		(start 71.234554 -230.392732)
		(end 71.234554 -231.032812)
		(width 0.16002)
		(layer "In2.Cu")
		(net "M_C_CPU1_SA_DQS_DN<2>")
	)
	(segment
		(start 52.771294 -219.012516)
		(end 53.664358 -219.90558)
		(width 0.16002)
		(layer "In2.Cu")
		(net "M_C_CPU1_SA_DQS_DN<2>")
	)
	(segment
		(start 70.01383 -227.800408)
		(end 70.01383 -229.812088)
		(width 0.16002)
		(layer "In2.Cu")
		(net "M_C_CPU1_SA_DQS_DN<2>")
	)
	(segment
		(start 63.442596 -220.70187)
		(end 63.722504 -220.421962)
		(width 0.16002)
		(layer "In2.Cu")
		(net "M_C_CPU1_SA_DQS_DN<2>")
	)
	(segment
		(start 72.608186 -232.406444)
		(end 73.0631 -232.861358)
		(width 0.16002)
		(layer "In2.Cu")
		(net "M_C_CPU1_SA_DQS_DN<2>")
	)
	(segment
		(start 70.01383 -229.812088)
		(end 70.315836 -230.114094)
		(width 0.16002)
		(layer "In2.Cu")
		(net "M_C_CPU1_SA_DQS_DN<2>")
	)
	(segment
		(start 62.624462 -219.04706)
		(end 62.822328 -219.244926)
		(width 0.16002)
		(layer "In2.Cu")
		(net "M_C_CPU1_SA_DQS_DN<2>")
	)
	(segment
		(start 73.0631 -232.861358)
		(end 73.70318 -232.861358)
		(width 0.16002)
		(layer "In2.Cu")
		(net "M_C_CPU1_SA_DQS_DN<2>")
	)
	(segment
		(start 61.451998 -220.075506)
		(end 61.82487 -219.702634)
		(width 0.16002)
		(layer "In2.Cu")
		(net "M_C_CPU1_SA_DQS_DN<2>")
	)
	(segment
		(start 63.722504 -220.421962)
		(end 63.999364 -220.421962)
		(width 0.16002)
		(layer "In2.Cu")
		(net "M_C_CPU1_SA_DQS_DN<2>")
	)
	(segment
		(start 73.981818 -233.139996)
		(end 73.981818 -233.780076)
		(width 0.16002)
		(layer "In2.Cu")
		(net "M_C_CPU1_SA_DQS_DN<2>")
	)
	(segment
		(start 89.502488 -236.869224)
		(end 89.51087 -236.864398)
		(width 0.09525)
		(layer "In2.Cu")
		(net "M_C_CPU1_SA_DQS_DN<2>")
	)
	(segment
		(start 60.552076 -219.242894)
		(end 60.552076 -219.702634)
		(width 0.16002)
		(layer "In2.Cu")
		(net "M_C_CPU1_SA_DQS_DN<2>")
	)
	(segment
		(start 91.75115 -236.864398)
		(end 91.759532 -236.869224)
		(width 0.09525)
		(layer "In2.Cu")
		(net "M_C_CPU1_SA_DQS_DN<2>")
	)
	(segment
		(start 56.10987 -219.90558)
		(end 56.39943 -220.19514)
		(width 0.16002)
		(layer "In2.Cu")
		(net "M_C_CPU1_SA_DQS_DN<2>")
	)
	(segment
		(start 84.231226 -236.864398)
		(end 84.239608 -236.869224)
		(width 0.09525)
		(layer "In2.Cu")
		(net "M_C_CPU1_SA_DQS_DN<2>")
	)
	(segment
		(start 88.931242 -236.864398)
		(end 88.939624 -236.869224)
		(width 0.09525)
		(layer "In2.Cu")
		(net "M_C_CPU1_SA_DQS_DN<2>")
	)
	(segment
		(start 78.858872 -236.215174)
		(end 79.42453 -236.780832)
		(width 0.09525)
		(layer "In2.Cu")
		(net "M_C_CPU1_SA_DQS_DN<2>")
	)
	(segment
		(start 77.26299 -235.239052)
		(end 78.239112 -236.215174)
		(width 0.09525)
		(layer "In2.Cu")
		(net "M_C_CPU1_SA_DQS_DN<2>")
	)
	(segment
		(start 61.82487 -219.242894)
		(end 62.020704 -219.04706)
		(width 0.16002)
		(layer "In2.Cu")
		(net "M_C_CPU1_SA_DQS_DN<2>")
	)
	(segment
		(start 76.03871 -234.624372)
		(end 76.982574 -234.624372)
		(width 0.09525)
		(layer "In2.Cu")
		(net "M_C_CPU1_SA_DQS_DN<2>")
	)
	(segment
		(start 62.915292 -220.70187)
		(end 63.442596 -220.70187)
		(width 0.16002)
		(layer "In2.Cu")
		(net "M_C_CPU1_SA_DQS_DN<2>")
	)
	(segment
		(start 74.885296 -234.683554)
		(end 75.955906 -234.683554)
		(width 0.16002)
		(layer "In2.Cu")
		(net "M_C_CPU1_SA_DQS_DN<2>")
	)
	(segment
		(start 72.608186 -231.766364)
		(end 72.608186 -232.406444)
		(width 0.16002)
		(layer "In2.Cu")
		(net "M_C_CPU1_SA_DQS_DN<2>")
	)
	(segment
		(start 94.13621 -236.902244)
		(end 94.237048 -236.928914)
		(width 0.09525)
		(layer "In2.Cu")
		(net "M_C_CPU1_SA_DQS_DN<2>")
	)
	(segment
		(start 94.237048 -236.928914)
		(end 94.390972 -237.194344)
		(width 0.09525)
		(layer "In2.Cu")
		(net "M_C_CPU1_SA_DQS_DN<2>")
	)
	(segment
		(start 63.999364 -220.421962)
		(end 64.19596 -220.618558)
		(width 0.16002)
		(layer "In2.Cu")
		(net "M_C_CPU1_SA_DQS_DN<2>")
	)
	(segment
		(start 60.356242 -219.04706)
		(end 60.552076 -219.242894)
		(width 0.16002)
		(layer "In2.Cu")
		(net "M_C_CPU1_SA_DQS_DN<2>")
	)
	(segment
		(start 73.70318 -232.861358)
		(end 73.981818 -233.139996)
		(width 0.16002)
		(layer "In2.Cu")
		(net "M_C_CPU1_SA_DQS_DN<2>")
	)
	(segment
		(start 58.61431 -219.04706)
		(end 60.356242 -219.04706)
		(width 0.16002)
		(layer "In2.Cu")
		(net "M_C_CPU1_SA_DQS_DN<2>")
	)
	(segment
		(start 50.82921 -219.32392)
		(end 51.140614 -219.012516)
		(width 0.16002)
		(layer "In2.Cu")
		(net "M_C_CPU1_SA_DQS_DN<2>")
	)
	(segment
		(start 62.822328 -219.521786)
		(end 62.54242 -219.801694)
		(width 0.16002)
		(layer "In2.Cu")
		(net "M_C_CPU1_SA_DQS_DN<2>")
	)
	(segment
		(start 62.54242 -220.328998)
		(end 62.915292 -220.70187)
		(width 0.16002)
		(layer "In2.Cu")
		(net "M_C_CPU1_SA_DQS_DN<2>")
	)
	(segment
		(start 57.78627 -219.39758)
		(end 58.26379 -219.39758)
		(width 0.16002)
		(layer "In2.Cu")
		(net "M_C_CPU1_SA_DQS_DN<2>")
	)
	(segment
		(start 70.955916 -230.114094)
		(end 71.234554 -230.392732)
		(width 0.16002)
		(layer "In2.Cu")
		(net "M_C_CPU1_SA_DQS_DN<2>")
	)
	(segment
		(start 72.329548 -231.487726)
		(end 72.608186 -231.766364)
		(width 0.16002)
		(layer "In2.Cu")
		(net "M_C_CPU1_SA_DQS_DN<2>")
	)
	(arc
		(start 80.479646 -236.869224)
		(mid 80.761078 -236.944979)
		(end 81.04251 -236.869224)
		(width 0.09525)
		(layer "In2.Cu")
		(net "M_C_CPU1_SA_DQS_DN<2>")
	)
	(arc
		(start 85.750908 -236.864398)
		(mid 85.93594 -236.818484)
		(end 86.119716 -236.869224)
		(width 0.09525)
		(layer "In2.Cu")
		(net "M_C_CPU1_SA_DQS_DN<2>")
	)
	(arc
		(start 79.539084 -236.869224)
		(mid 79.812266 -236.945166)
		(end 80.087724 -236.87786)
		(width 0.09525)
		(layer "In2.Cu")
		(net "M_C_CPU1_SA_DQS_DN<2>")
	)
	(arc
		(start 94.11589 -236.910118)
		(mid 94.126089 -236.906281)
		(end 94.13621 -236.902244)
		(width 0.09525)
		(layer "In2.Cu")
		(net "M_C_CPU1_SA_DQS_DN<2>")
	)
	(arc
		(start 81.4197 -236.869224)
		(mid 81.701132 -236.944979)
		(end 81.982564 -236.869224)
		(width 0.09525)
		(layer "In2.Cu")
		(net "M_C_CPU1_SA_DQS_DN<2>")
	)
	(arc
		(start 91.759532 -236.869224)
		(mid 92.040964 -236.944979)
		(end 92.322396 -236.869224)
		(width 0.09525)
		(layer "In2.Cu")
		(net "M_C_CPU1_SA_DQS_DN<2>")
	)
	(arc
		(start 93.63964 -236.869224)
		(mid 93.873184 -236.94293)
		(end 94.11589 -236.910118)
		(width 0.09525)
		(layer "In2.Cu")
		(net "M_C_CPU1_SA_DQS_DN<2>")
	)
	(arc
		(start 89.51087 -236.864398)
		(mid 89.695902 -236.818484)
		(end 89.879678 -236.869224)
		(width 0.09525)
		(layer "In2.Cu")
		(net "M_C_CPU1_SA_DQS_DN<2>")
	)
	(arc
		(start 86.119716 -236.869224)
		(mid 86.401148 -236.944979)
		(end 86.68258 -236.869224)
		(width 0.09525)
		(layer "In2.Cu")
		(net "M_C_CPU1_SA_DQS_DN<2>")
	)
	(arc
		(start 84.239608 -236.869224)
		(mid 84.52104 -236.944979)
		(end 84.802472 -236.869224)
		(width 0.09525)
		(layer "In2.Cu")
		(net "M_C_CPU1_SA_DQS_DN<2>")
	)
	(arc
		(start 86.68258 -236.869224)
		(mid 86.871048 -236.818547)
		(end 87.059516 -236.869224)
		(width 0.09525)
		(layer "In2.Cu")
		(net "M_C_CPU1_SA_DQS_DN<2>")
	)
	(arc
		(start 79.42453 -236.780832)
		(mid 79.47894 -236.828745)
		(end 79.539084 -236.869224)
		(width 0.09525)
		(layer "In2.Cu")
		(net "M_C_CPU1_SA_DQS_DN<2>")
	)
	(arc
		(start 82.3595 -236.869224)
		(mid 82.640932 -236.944979)
		(end 82.922364 -236.869224)
		(width 0.09525)
		(layer "In2.Cu")
		(net "M_C_CPU1_SA_DQS_DN<2>")
	)
	(arc
		(start 88.939624 -236.869224)
		(mid 89.221056 -236.944979)
		(end 89.502488 -236.869224)
		(width 0.09525)
		(layer "In2.Cu")
		(net "M_C_CPU1_SA_DQS_DN<2>")
	)
	(arc
		(start 92.322396 -236.869224)
		(mid 92.506171 -236.818452)
		(end 92.691204 -236.864398)
		(width 0.09525)
		(layer "In2.Cu")
		(net "M_C_CPU1_SA_DQS_DN<2>")
	)
	(arc
		(start 81.050892 -236.864398)
		(mid 81.235924 -236.818484)
		(end 81.4197 -236.869224)
		(width 0.09525)
		(layer "In2.Cu")
		(net "M_C_CPU1_SA_DQS_DN<2>")
	)
	(arc
		(start 87.99957 -236.869224)
		(mid 88.281002 -236.944979)
		(end 88.562434 -236.869224)
		(width 0.09525)
		(layer "In2.Cu")
		(net "M_C_CPU1_SA_DQS_DN<2>")
	)
	(arc
		(start 81.982564 -236.869224)
		(mid 82.171032 -236.818547)
		(end 82.3595 -236.869224)
		(width 0.09525)
		(layer "In2.Cu")
		(net "M_C_CPU1_SA_DQS_DN<2>")
	)
	(arc
		(start 87.62238 -236.869224)
		(mid 87.806155 -236.818452)
		(end 87.991188 -236.864398)
		(width 0.09525)
		(layer "In2.Cu")
		(net "M_C_CPU1_SA_DQS_DN<2>")
	)
	(arc
		(start 93.270832 -236.864398)
		(mid 93.455864 -236.818484)
		(end 93.63964 -236.869224)
		(width 0.09525)
		(layer "In2.Cu")
		(net "M_C_CPU1_SA_DQS_DN<2>")
	)
	(arc
		(start 90.819478 -236.869224)
		(mid 91.10091 -236.944979)
		(end 91.382342 -236.869224)
		(width 0.09525)
		(layer "In2.Cu")
		(net "M_C_CPU1_SA_DQS_DN<2>")
	)
	(arc
		(start 92.699586 -236.869224)
		(mid 92.981018 -236.944979)
		(end 93.26245 -236.869224)
		(width 0.09525)
		(layer "In2.Cu")
		(net "M_C_CPU1_SA_DQS_DN<2>")
	)
	(arc
		(start 90.442542 -236.869224)
		(mid 90.63101 -236.818547)
		(end 90.819478 -236.869224)
		(width 0.09525)
		(layer "In2.Cu")
		(net "M_C_CPU1_SA_DQS_DN<2>")
	)
	(arc
		(start 88.562434 -236.869224)
		(mid 88.746209 -236.818452)
		(end 88.931242 -236.864398)
		(width 0.09525)
		(layer "In2.Cu")
		(net "M_C_CPU1_SA_DQS_DN<2>")
	)
	(arc
		(start 83.862418 -236.869224)
		(mid 84.046193 -236.818452)
		(end 84.231226 -236.864398)
		(width 0.09525)
		(layer "In2.Cu")
		(net "M_C_CPU1_SA_DQS_DN<2>")
	)
	(arc
		(start 85.179662 -236.869224)
		(mid 85.461094 -236.944979)
		(end 85.742526 -236.869224)
		(width 0.09525)
		(layer "In2.Cu")
		(net "M_C_CPU1_SA_DQS_DN<2>")
	)
	(arc
		(start 87.059516 -236.869224)
		(mid 87.340948 -236.944979)
		(end 87.62238 -236.869224)
		(width 0.09525)
		(layer "In2.Cu")
		(net "M_C_CPU1_SA_DQS_DN<2>")
	)
	(arc
		(start 80.102456 -236.869224)
		(mid 80.286231 -236.818452)
		(end 80.471264 -236.864398)
		(width 0.09525)
		(layer "In2.Cu")
		(net "M_C_CPU1_SA_DQS_DN<2>")
	)
	(arc
		(start 89.879678 -236.869224)
		(mid 90.16111 -236.944979)
		(end 90.442542 -236.869224)
		(width 0.09525)
		(layer "In2.Cu")
		(net "M_C_CPU1_SA_DQS_DN<2>")
	)
	(arc
		(start 84.810854 -236.864398)
		(mid 84.995886 -236.818484)
		(end 85.179662 -236.869224)
		(width 0.09525)
		(layer "In2.Cu")
		(net "M_C_CPU1_SA_DQS_DN<2>")
	)
	(arc
		(start 83.299554 -236.869224)
		(mid 83.580986 -236.944979)
		(end 83.862418 -236.869224)
		(width 0.09525)
		(layer "In2.Cu")
		(net "M_C_CPU1_SA_DQS_DN<2>")
	)
	(arc
		(start 82.922364 -236.869224)
		(mid 83.106139 -236.818452)
		(end 83.291172 -236.864398)
		(width 0.09525)
		(layer "In2.Cu")
		(net "M_C_CPU1_SA_DQS_DN<2>")
	)
	(arc
		(start 91.382342 -236.869224)
		(mid 91.566117 -236.818452)
		(end 91.75115 -236.864398)
		(width 0.09525)
		(layer "In2.Cu")
		(net "M_C_CPU1_SA_DQS_DN<2>")
	)
	(segment
		(start 94.857824 -232.600246)
		(end 94.390972 -232.334308)
		(width 0.12954)
		(layer "F.Cu")
		(net "M_C_CPU1_SA_DQS_DN<1>")
	)
	(segment
		(start 75.80503 -226.013264)
		(end 76.14285 -226.351084)
		(width 0.16002)
		(layer "In2.Cu")
		(net "M_C_CPU1_SA_DQS_DN<1>")
	)
	(segment
		(start 56.39943 -210.845146)
		(end 56.98871 -210.845146)
		(width 0.16002)
		(layer "In2.Cu")
		(net "M_C_CPU1_SA_DQS_DN<1>")
	)
	(segment
		(start 92.691204 -232.004362)
		(end 92.699586 -232.009188)
		(width 0.09525)
		(layer "In2.Cu")
		(net "M_C_CPU1_SA_DQS_DN<1>")
	)
	(segment
		(start 51.140614 -209.662522)
		(end 52.783486 -209.662522)
		(width 0.16002)
		(layer "In2.Cu")
		(net "M_C_CPU1_SA_DQS_DN<1>")
	)
	(segment
		(start 79.50327 -230.36784)
		(end 79.539846 -230.389176)
		(width 0.09525)
		(layer "In2.Cu")
		(net "M_C_CPU1_SA_DQS_DN<1>")
	)
	(segment
		(start 83.291172 -232.004362)
		(end 83.299554 -232.009188)
		(width 0.09525)
		(layer "In2.Cu")
		(net "M_C_CPU1_SA_DQS_DN<1>")
	)
	(segment
		(start 57.78627 -210.047586)
		(end 58.26379 -210.047586)
		(width 0.16002)
		(layer "In2.Cu")
		(net "M_C_CPU1_SA_DQS_DN<1>")
	)
	(segment
		(start 46.7741 -210.661504)
		(end 46.923198 -210.512406)
		(width 0.16002)
		(layer "In2.Cu")
		(net "M_C_CPU1_SA_DQS_DN<1>")
	)
	(segment
		(start 78.599792 -228.769164)
		(end 78.631542 -228.787452)
		(width 0.09525)
		(layer "In2.Cu")
		(net "M_C_CPU1_SA_DQS_DN<1>")
	)
	(segment
		(start 76.518008 -226.351084)
		(end 76.576936 -226.292156)
		(width 0.09525)
		(layer "In2.Cu")
		(net "M_C_CPU1_SA_DQS_DN<1>")
	)
	(segment
		(start 70.19417 -217.942668)
		(end 70.19417 -219.753688)
		(width 0.16002)
		(layer "In2.Cu")
		(net "M_C_CPU1_SA_DQS_DN<1>")
	)
	(segment
		(start 56.10987 -210.555586)
		(end 56.39943 -210.845146)
		(width 0.16002)
		(layer "In2.Cu")
		(net "M_C_CPU1_SA_DQS_DN<1>")
	)
	(segment
		(start 94.237048 -232.068878)
		(end 94.390972 -232.334308)
		(width 0.09525)
		(layer "In2.Cu")
		(net "M_C_CPU1_SA_DQS_DN<1>")
	)
	(segment
		(start 71.901558 -221.461076)
		(end 72.428862 -221.461076)
		(width 0.16002)
		(layer "In2.Cu")
		(net "M_C_CPU1_SA_DQS_DN<1>")
	)
	(segment
		(start 80.009746 -231.199182)
		(end 80.041242 -231.21747)
		(width 0.09525)
		(layer "In2.Cu")
		(net "M_C_CPU1_SA_DQS_DN<1>")
	)
	(segment
		(start 79.031846 -229.557072)
		(end 79.069946 -229.57917)
		(width 0.09525)
		(layer "In2.Cu")
		(net "M_C_CPU1_SA_DQS_DN<1>")
	)
	(segment
		(start 48.86833 -210.827366)
		(end 49.56937 -210.827366)
		(width 0.16002)
		(layer "In2.Cu")
		(net "M_C_CPU1_SA_DQS_DN<1>")
	)
	(segment
		(start 78.566264 -228.749606)
		(end 78.599792 -228.769164)
		(width 0.09525)
		(layer "In2.Cu")
		(net "M_C_CPU1_SA_DQS_DN<1>")
	)
	(segment
		(start 71.860918 -219.281756)
		(end 72.137778 -219.281756)
		(width 0.16002)
		(layer "In2.Cu")
		(net "M_C_CPU1_SA_DQS_DN<1>")
	)
	(segment
		(start 72.902318 -221.934532)
		(end 72.902318 -222.461836)
		(width 0.16002)
		(layer "In2.Cu")
		(net "M_C_CPU1_SA_DQS_DN<1>")
	)
	(segment
		(start 87.991188 -232.004362)
		(end 87.99957 -232.009188)
		(width 0.09525)
		(layer "In2.Cu")
		(net "M_C_CPU1_SA_DQS_DN<1>")
	)
	(segment
		(start 80.441546 -231.98709)
		(end 80.479646 -232.009188)
		(width 0.09525)
		(layer "In2.Cu")
		(net "M_C_CPU1_SA_DQS_DN<1>")
	)
	(segment
		(start 79.069946 -229.57917)
		(end 79.100172 -229.596696)
		(width 0.09525)
		(layer "In2.Cu")
		(net "M_C_CPU1_SA_DQS_DN<1>")
	)
	(segment
		(start 77.379322 -226.664012)
		(end 77.378814 -226.66452)
		(width 0.09525)
		(layer "In2.Cu")
		(net "M_C_CPU1_SA_DQS_DN<1>")
	)
	(segment
		(start 56.98871 -210.845146)
		(end 57.78627 -210.047586)
		(width 0.16002)
		(layer "In2.Cu")
		(net "M_C_CPU1_SA_DQS_DN<1>")
	)
	(segment
		(start 76.494386 -226.351084)
		(end 76.518008 -226.351084)
		(width 0.09525)
		(layer "In2.Cu")
		(net "M_C_CPU1_SA_DQS_DN<1>")
	)
	(segment
		(start 71.528686 -220.5609)
		(end 71.528686 -221.088204)
		(width 0.16002)
		(layer "In2.Cu")
		(net "M_C_CPU1_SA_DQS_DN<1>")
	)
	(segment
		(start 50.42281 -209.973926)
		(end 50.82921 -209.973926)
		(width 0.16002)
		(layer "In2.Cu")
		(net "M_C_CPU1_SA_DQS_DN<1>")
	)
	(segment
		(start 79.539846 -230.389176)
		(end 79.572358 -230.407972)
		(width 0.09525)
		(layer "In2.Cu")
		(net "M_C_CPU1_SA_DQS_DN<1>")
	)
	(segment
		(start 44.61383 -210.661504)
		(end 46.7741 -210.661504)
		(width 0.16002)
		(layer "In2.Cu")
		(net "M_C_CPU1_SA_DQS_DN<1>")
	)
	(segment
		(start 49.56937 -210.827366)
		(end 50.42281 -209.973926)
		(width 0.16002)
		(layer "In2.Cu")
		(net "M_C_CPU1_SA_DQS_DN<1>")
	)
	(segment
		(start 78.129638 -227.959412)
		(end 78.129892 -227.959412)
		(width 0.09525)
		(layer "In2.Cu")
		(net "M_C_CPU1_SA_DQS_DN<1>")
	)
	(segment
		(start 58.61431 -209.697066)
		(end 61.948568 -209.697066)
		(width 0.16002)
		(layer "In2.Cu")
		(net "M_C_CPU1_SA_DQS_DN<1>")
	)
	(segment
		(start 76.576936 -226.292156)
		(end 77.000862 -226.292156)
		(width 0.09525)
		(layer "In2.Cu")
		(net "M_C_CPU1_SA_DQS_DN<1>")
	)
	(segment
		(start 71.05523 -220.087444)
		(end 71.860918 -219.281756)
		(width 0.16002)
		(layer "In2.Cu")
		(net "M_C_CPU1_SA_DQS_DN<1>")
	)
	(segment
		(start 91.75115 -232.004362)
		(end 91.759532 -232.009188)
		(width 0.09525)
		(layer "In2.Cu")
		(net "M_C_CPU1_SA_DQS_DN<1>")
	)
	(segment
		(start 72.902318 -222.461836)
		(end 75.80503 -225.364548)
		(width 0.16002)
		(layer "In2.Cu")
		(net "M_C_CPU1_SA_DQS_DN<1>")
	)
	(segment
		(start 70.527926 -220.087444)
		(end 71.05523 -220.087444)
		(width 0.16002)
		(layer "In2.Cu")
		(net "M_C_CPU1_SA_DQS_DN<1>")
	)
	(segment
		(start 73.588626 -221.248224)
		(end 72.902318 -221.934532)
		(width 0.16002)
		(layer "In2.Cu")
		(net "M_C_CPU1_SA_DQS_DN<1>")
	)
	(segment
		(start 70.19417 -219.753688)
		(end 70.527926 -220.087444)
		(width 0.16002)
		(layer "In2.Cu")
		(net "M_C_CPU1_SA_DQS_DN<1>")
	)
	(segment
		(start 61.948568 -209.697066)
		(end 70.19417 -217.942668)
		(width 0.16002)
		(layer "In2.Cu")
		(net "M_C_CPU1_SA_DQS_DN<1>")
	)
	(segment
		(start 44.340018 -210.935316)
		(end 44.61383 -210.661504)
		(width 0.16002)
		(layer "In2.Cu")
		(net "M_C_CPU1_SA_DQS_DN<1>")
	)
	(segment
		(start 71.528686 -221.088204)
		(end 71.901558 -221.461076)
		(width 0.16002)
		(layer "In2.Cu")
		(net "M_C_CPU1_SA_DQS_DN<1>")
	)
	(segment
		(start 81.04251 -232.009188)
		(end 81.050892 -232.004362)
		(width 0.09525)
		(layer "In2.Cu")
		(net "M_C_CPU1_SA_DQS_DN<1>")
	)
	(segment
		(start 50.82921 -209.973926)
		(end 51.140614 -209.662522)
		(width 0.16002)
		(layer "In2.Cu")
		(net "M_C_CPU1_SA_DQS_DN<1>")
	)
	(segment
		(start 72.428862 -221.461076)
		(end 73.11517 -220.774768)
		(width 0.16002)
		(layer "In2.Cu")
		(net "M_C_CPU1_SA_DQS_DN<1>")
	)
	(segment
		(start 77.270102 -226.403662)
		(end 77.322426 -226.455986)
		(width 0.09525)
		(layer "In2.Cu")
		(net "M_C_CPU1_SA_DQS_DN<1>")
	)
	(segment
		(start 52.783486 -209.662522)
		(end 53.67655 -210.555586)
		(width 0.16002)
		(layer "In2.Cu")
		(net "M_C_CPU1_SA_DQS_DN<1>")
	)
	(segment
		(start 77.659738 -227.149406)
		(end 77.691234 -227.167694)
		(width 0.09525)
		(layer "In2.Cu")
		(net "M_C_CPU1_SA_DQS_DN<1>")
	)
	(segment
		(start 72.334374 -219.478352)
		(end 72.334374 -219.755212)
		(width 0.16002)
		(layer "In2.Cu")
		(net "M_C_CPU1_SA_DQS_DN<1>")
	)
	(segment
		(start 72.137778 -219.281756)
		(end 72.334374 -219.478352)
		(width 0.16002)
		(layer "In2.Cu")
		(net "M_C_CPU1_SA_DQS_DN<1>")
	)
	(segment
		(start 88.931242 -232.004362)
		(end 88.939624 -232.009188)
		(width 0.09525)
		(layer "In2.Cu")
		(net "M_C_CPU1_SA_DQS_DN<1>")
	)
	(segment
		(start 77.379322 -226.592892)
		(end 77.379322 -226.664012)
		(width 0.09525)
		(layer "In2.Cu")
		(net "M_C_CPU1_SA_DQS_DN<1>")
	)
	(segment
		(start 46.923198 -210.512406)
		(end 48.55337 -210.512406)
		(width 0.16002)
		(layer "In2.Cu")
		(net "M_C_CPU1_SA_DQS_DN<1>")
	)
	(segment
		(start 78.129892 -227.959412)
		(end 78.165452 -227.979986)
		(width 0.09525)
		(layer "In2.Cu")
		(net "M_C_CPU1_SA_DQS_DN<1>")
	)
	(segment
		(start 73.588626 -220.971364)
		(end 73.588626 -221.248224)
		(width 0.16002)
		(layer "In2.Cu")
		(net "M_C_CPU1_SA_DQS_DN<1>")
	)
	(segment
		(start 73.39203 -220.774768)
		(end 73.588626 -220.971364)
		(width 0.16002)
		(layer "In2.Cu")
		(net "M_C_CPU1_SA_DQS_DN<1>")
	)
	(segment
		(start 78.091538 -227.937314)
		(end 78.129638 -227.959412)
		(width 0.09525)
		(layer "In2.Cu")
		(net "M_C_CPU1_SA_DQS_DN<1>")
	)
	(segment
		(start 73.11517 -220.774768)
		(end 73.39203 -220.774768)
		(width 0.16002)
		(layer "In2.Cu")
		(net "M_C_CPU1_SA_DQS_DN<1>")
	)
	(segment
		(start 77.621638 -227.127308)
		(end 77.659738 -227.149406)
		(width 0.09525)
		(layer "In2.Cu")
		(net "M_C_CPU1_SA_DQS_DN<1>")
	)
	(segment
		(start 53.67655 -210.555586)
		(end 56.10987 -210.555586)
		(width 0.16002)
		(layer "In2.Cu")
		(net "M_C_CPU1_SA_DQS_DN<1>")
	)
	(segment
		(start 48.55337 -210.512406)
		(end 48.86833 -210.827366)
		(width 0.16002)
		(layer "In2.Cu")
		(net "M_C_CPU1_SA_DQS_DN<1>")
	)
	(segment
		(start 77.379068 -226.593146)
		(end 77.379322 -226.592892)
		(width 0.09525)
		(layer "In2.Cu")
		(net "M_C_CPU1_SA_DQS_DN<1>")
	)
	(segment
		(start 94.13621 -232.042208)
		(end 94.237048 -232.068878)
		(width 0.09525)
		(layer "In2.Cu")
		(net "M_C_CPU1_SA_DQS_DN<1>")
	)
	(segment
		(start 75.80503 -225.364548)
		(end 75.80503 -226.013264)
		(width 0.16002)
		(layer "In2.Cu")
		(net "M_C_CPU1_SA_DQS_DN<1>")
	)
	(segment
		(start 72.334374 -219.755212)
		(end 71.528686 -220.5609)
		(width 0.16002)
		(layer "In2.Cu")
		(net "M_C_CPU1_SA_DQS_DN<1>")
	)
	(segment
		(start 58.26379 -210.047586)
		(end 58.61431 -209.697066)
		(width 0.16002)
		(layer "In2.Cu")
		(net "M_C_CPU1_SA_DQS_DN<1>")
	)
	(segment
		(start 84.802472 -232.009188)
		(end 84.810854 -232.004362)
		(width 0.09525)
		(layer "In2.Cu")
		(net "M_C_CPU1_SA_DQS_DN<1>")
	)
	(segment
		(start 85.742526 -232.009188)
		(end 85.750908 -232.004362)
		(width 0.09525)
		(layer "In2.Cu")
		(net "M_C_CPU1_SA_DQS_DN<1>")
	)
	(segment
		(start 84.231226 -232.004362)
		(end 84.239608 -232.009188)
		(width 0.09525)
		(layer "In2.Cu")
		(net "M_C_CPU1_SA_DQS_DN<1>")
	)
	(segment
		(start 79.972154 -231.177338)
		(end 80.009746 -231.199182)
		(width 0.09525)
		(layer "In2.Cu")
		(net "M_C_CPU1_SA_DQS_DN<1>")
	)
	(segment
		(start 93.26245 -232.009188)
		(end 93.270832 -232.004362)
		(width 0.09525)
		(layer "In2.Cu")
		(net "M_C_CPU1_SA_DQS_DN<1>")
	)
	(segment
		(start 89.502488 -232.009188)
		(end 89.51087 -232.004362)
		(width 0.09525)
		(layer "In2.Cu")
		(net "M_C_CPU1_SA_DQS_DN<1>")
	)
	(segment
		(start 76.14285 -226.351084)
		(end 76.494386 -226.351084)
		(width 0.16002)
		(layer "In2.Cu")
		(net "M_C_CPU1_SA_DQS_DN<1>")
	)
	(arc
		(start 88.562434 -232.009188)
		(mid 88.746209 -231.958416)
		(end 88.931242 -232.004362)
		(width 0.09525)
		(layer "In2.Cu")
		(net "M_C_CPU1_SA_DQS_DN<1>")
	)
	(arc
		(start 87.99957 -232.009188)
		(mid 88.281002 -232.084943)
		(end 88.562434 -232.009188)
		(width 0.09525)
		(layer "In2.Cu")
		(net "M_C_CPU1_SA_DQS_DN<1>")
	)
	(arc
		(start 79.258922 -229.90429)
		(mid 79.323751 -230.166292)
		(end 79.50327 -230.36784)
		(width 0.09525)
		(layer "In2.Cu")
		(net "M_C_CPU1_SA_DQS_DN<1>")
	)
	(arc
		(start 78.165452 -227.979986)
		(mid 78.278717 -228.11377)
		(end 78.319376 -228.284278)
		(width 0.09525)
		(layer "In2.Cu")
		(net "M_C_CPU1_SA_DQS_DN<1>")
	)
	(arc
		(start 90.819478 -232.009188)
		(mid 91.10091 -232.084943)
		(end 91.382342 -232.009188)
		(width 0.09525)
		(layer "In2.Cu")
		(net "M_C_CPU1_SA_DQS_DN<1>")
	)
	(arc
		(start 78.631542 -228.787452)
		(mid 78.74734 -228.921988)
		(end 78.789022 -229.094538)
		(width 0.09525)
		(layer "In2.Cu")
		(net "M_C_CPU1_SA_DQS_DN<1>")
	)
	(arc
		(start 83.862418 -232.009188)
		(mid 84.046193 -231.958416)
		(end 84.231226 -232.004362)
		(width 0.09525)
		(layer "In2.Cu")
		(net "M_C_CPU1_SA_DQS_DN<1>")
	)
	(arc
		(start 83.299554 -232.009188)
		(mid 83.580986 -232.084943)
		(end 83.862418 -232.009188)
		(width 0.09525)
		(layer "In2.Cu")
		(net "M_C_CPU1_SA_DQS_DN<1>")
	)
	(arc
		(start 89.879678 -232.009188)
		(mid 90.16111 -232.084943)
		(end 90.442542 -232.009188)
		(width 0.09525)
		(layer "In2.Cu")
		(net "M_C_CPU1_SA_DQS_DN<1>")
	)
	(arc
		(start 80.041242 -231.21747)
		(mid 80.15704 -231.351864)
		(end 80.198722 -231.524302)
		(width 0.09525)
		(layer "In2.Cu")
		(net "M_C_CPU1_SA_DQS_DN<1>")
	)
	(arc
		(start 92.322396 -232.009188)
		(mid 92.506171 -231.958416)
		(end 92.691204 -232.004362)
		(width 0.09525)
		(layer "In2.Cu")
		(net "M_C_CPU1_SA_DQS_DN<1>")
	)
	(arc
		(start 78.319376 -228.284278)
		(mid 78.384929 -228.54765)
		(end 78.566264 -228.749606)
		(width 0.09525)
		(layer "In2.Cu")
		(net "M_C_CPU1_SA_DQS_DN<1>")
	)
	(arc
		(start 94.11589 -232.050082)
		(mid 94.126089 -232.046245)
		(end 94.13621 -232.042208)
		(width 0.09525)
		(layer "In2.Cu")
		(net "M_C_CPU1_SA_DQS_DN<1>")
	)
	(arc
		(start 77.322426 -226.455986)
		(mid 77.364367 -226.518944)
		(end 77.379068 -226.593146)
		(width 0.09525)
		(layer "In2.Cu")
		(net "M_C_CPU1_SA_DQS_DN<1>")
	)
	(arc
		(start 93.270832 -232.004362)
		(mid 93.455864 -231.958448)
		(end 93.63964 -232.009188)
		(width 0.09525)
		(layer "In2.Cu")
		(net "M_C_CPU1_SA_DQS_DN<1>")
	)
	(arc
		(start 90.442542 -232.009188)
		(mid 90.63101 -231.958511)
		(end 90.819478 -232.009188)
		(width 0.09525)
		(layer "In2.Cu")
		(net "M_C_CPU1_SA_DQS_DN<1>")
	)
	(arc
		(start 91.759532 -232.009188)
		(mid 92.040964 -232.084943)
		(end 92.322396 -232.009188)
		(width 0.09525)
		(layer "In2.Cu")
		(net "M_C_CPU1_SA_DQS_DN<1>")
	)
	(arc
		(start 84.239608 -232.009188)
		(mid 84.52104 -232.084943)
		(end 84.802472 -232.009188)
		(width 0.09525)
		(layer "In2.Cu")
		(net "M_C_CPU1_SA_DQS_DN<1>")
	)
	(arc
		(start 79.729076 -230.714296)
		(mid 79.793482 -230.975811)
		(end 79.972154 -231.177338)
		(width 0.09525)
		(layer "In2.Cu")
		(net "M_C_CPU1_SA_DQS_DN<1>")
	)
	(arc
		(start 84.810854 -232.004362)
		(mid 84.995886 -231.958448)
		(end 85.179662 -232.009188)
		(width 0.09525)
		(layer "In2.Cu")
		(net "M_C_CPU1_SA_DQS_DN<1>")
	)
	(arc
		(start 77.848714 -227.474526)
		(mid 77.913111 -227.735832)
		(end 78.091538 -227.937314)
		(width 0.09525)
		(layer "In2.Cu")
		(net "M_C_CPU1_SA_DQS_DN<1>")
	)
	(arc
		(start 88.939624 -232.009188)
		(mid 89.221056 -232.084943)
		(end 89.502488 -232.009188)
		(width 0.09525)
		(layer "In2.Cu")
		(net "M_C_CPU1_SA_DQS_DN<1>")
	)
	(arc
		(start 81.982564 -232.009188)
		(mid 82.171032 -231.958511)
		(end 82.3595 -232.009188)
		(width 0.09525)
		(layer "In2.Cu")
		(net "M_C_CPU1_SA_DQS_DN<1>")
	)
	(arc
		(start 92.699586 -232.009188)
		(mid 92.981018 -232.084943)
		(end 93.26245 -232.009188)
		(width 0.09525)
		(layer "In2.Cu")
		(net "M_C_CPU1_SA_DQS_DN<1>")
	)
	(arc
		(start 85.750908 -232.004362)
		(mid 85.93594 -231.958448)
		(end 86.119716 -232.009188)
		(width 0.09525)
		(layer "In2.Cu")
		(net "M_C_CPU1_SA_DQS_DN<1>")
	)
	(arc
		(start 82.3595 -232.009188)
		(mid 82.640932 -232.084943)
		(end 82.922364 -232.009188)
		(width 0.09525)
		(layer "In2.Cu")
		(net "M_C_CPU1_SA_DQS_DN<1>")
	)
	(arc
		(start 77.378814 -226.66452)
		(mid 77.443211 -226.925826)
		(end 77.621638 -227.127308)
		(width 0.09525)
		(layer "In2.Cu")
		(net "M_C_CPU1_SA_DQS_DN<1>")
	)
	(arc
		(start 79.572358 -230.407972)
		(mid 79.687632 -230.54225)
		(end 79.729076 -230.714296)
		(width 0.09525)
		(layer "In2.Cu")
		(net "M_C_CPU1_SA_DQS_DN<1>")
	)
	(arc
		(start 79.100172 -229.596696)
		(mid 79.216873 -229.731225)
		(end 79.258922 -229.90429)
		(width 0.09525)
		(layer "In2.Cu")
		(net "M_C_CPU1_SA_DQS_DN<1>")
	)
	(arc
		(start 87.62238 -232.009188)
		(mid 87.806155 -231.958416)
		(end 87.991188 -232.004362)
		(width 0.09525)
		(layer "In2.Cu")
		(net "M_C_CPU1_SA_DQS_DN<1>")
	)
	(arc
		(start 80.198722 -231.524302)
		(mid 80.263119 -231.785608)
		(end 80.441546 -231.98709)
		(width 0.09525)
		(layer "In2.Cu")
		(net "M_C_CPU1_SA_DQS_DN<1>")
	)
	(arc
		(start 86.68258 -232.009188)
		(mid 86.871048 -231.958511)
		(end 87.059516 -232.009188)
		(width 0.09525)
		(layer "In2.Cu")
		(net "M_C_CPU1_SA_DQS_DN<1>")
	)
	(arc
		(start 77.691234 -227.167694)
		(mid 77.807032 -227.302088)
		(end 77.848714 -227.474526)
		(width 0.09525)
		(layer "In2.Cu")
		(net "M_C_CPU1_SA_DQS_DN<1>")
	)
	(arc
		(start 82.922364 -232.009188)
		(mid 83.106139 -231.958416)
		(end 83.291172 -232.004362)
		(width 0.09525)
		(layer "In2.Cu")
		(net "M_C_CPU1_SA_DQS_DN<1>")
	)
	(arc
		(start 80.479646 -232.009188)
		(mid 80.761078 -232.084943)
		(end 81.04251 -232.009188)
		(width 0.09525)
		(layer "In2.Cu")
		(net "M_C_CPU1_SA_DQS_DN<1>")
	)
	(arc
		(start 81.050892 -232.004362)
		(mid 81.235924 -231.958448)
		(end 81.4197 -232.009188)
		(width 0.09525)
		(layer "In2.Cu")
		(net "M_C_CPU1_SA_DQS_DN<1>")
	)
	(arc
		(start 89.51087 -232.004362)
		(mid 89.695902 -231.958448)
		(end 89.879678 -232.009188)
		(width 0.09525)
		(layer "In2.Cu")
		(net "M_C_CPU1_SA_DQS_DN<1>")
	)
	(arc
		(start 77.000862 -226.292156)
		(mid 77.146567 -226.321139)
		(end 77.270102 -226.403662)
		(width 0.09525)
		(layer "In2.Cu")
		(net "M_C_CPU1_SA_DQS_DN<1>")
	)
	(arc
		(start 81.4197 -232.009188)
		(mid 81.701132 -232.084943)
		(end 81.982564 -232.009188)
		(width 0.09525)
		(layer "In2.Cu")
		(net "M_C_CPU1_SA_DQS_DN<1>")
	)
	(arc
		(start 87.059516 -232.009188)
		(mid 87.340948 -232.084943)
		(end 87.62238 -232.009188)
		(width 0.09525)
		(layer "In2.Cu")
		(net "M_C_CPU1_SA_DQS_DN<1>")
	)
	(arc
		(start 93.63964 -232.009188)
		(mid 93.873184 -232.082894)
		(end 94.11589 -232.050082)
		(width 0.09525)
		(layer "In2.Cu")
		(net "M_C_CPU1_SA_DQS_DN<1>")
	)
	(arc
		(start 85.179662 -232.009188)
		(mid 85.461094 -232.084943)
		(end 85.742526 -232.009188)
		(width 0.09525)
		(layer "In2.Cu")
		(net "M_C_CPU1_SA_DQS_DN<1>")
	)
	(arc
		(start 91.382342 -232.009188)
		(mid 91.566117 -231.958416)
		(end 91.75115 -232.004362)
		(width 0.09525)
		(layer "In2.Cu")
		(net "M_C_CPU1_SA_DQS_DN<1>")
	)
	(arc
		(start 78.789022 -229.094538)
		(mid 78.853478 -229.355703)
		(end 79.031846 -229.557072)
		(width 0.09525)
		(layer "In2.Cu")
		(net "M_C_CPU1_SA_DQS_DN<1>")
	)
	(arc
		(start 86.119716 -232.009188)
		(mid 86.401148 -232.084943)
		(end 86.68258 -232.009188)
		(width 0.09525)
		(layer "In2.Cu")
		(net "M_C_CPU1_SA_DQS_DN<1>")
	)
	(segment
		(start 94.857824 -227.740464)
		(end 94.390972 -227.474526)
		(width 0.12954)
		(layer "F.Cu")
		(net "M_C_CPU1_SA_DQS_DN<0>")
	)
	(segment
		(start 57.78627 -200.697592)
		(end 58.26379 -200.697592)
		(width 0.16002)
		(layer "In2.Cu")
		(net "M_C_CPU1_SA_DQS_DN<0>")
	)
	(segment
		(start 73.809352 -211.421218)
		(end 73.329546 -211.901024)
		(width 0.16002)
		(layer "In2.Cu")
		(net "M_C_CPU1_SA_DQS_DN<0>")
	)
	(segment
		(start 74.703178 -213.274656)
		(end 74.703178 -213.802214)
		(width 0.16002)
		(layer "In2.Cu")
		(net "M_C_CPU1_SA_DQS_DN<0>")
	)
	(segment
		(start 63.131192 -201.861928)
		(end 63.408052 -201.861928)
		(width 0.16002)
		(layer "In2.Cu")
		(net "M_C_CPU1_SA_DQS_DN<0>")
	)
	(segment
		(start 58.26379 -200.697592)
		(end 58.61431 -200.347072)
		(width 0.16002)
		(layer "In2.Cu")
		(net "M_C_CPU1_SA_DQS_DN<0>")
	)
	(segment
		(start 81.4197 -223.909382)
		(end 81.451196 -223.92767)
		(width 0.09525)
		(layer "In2.Cu")
		(net "M_C_CPU1_SA_DQS_DN<0>")
	)
	(segment
		(start 61.07557 -200.474072)
		(end 61.20257 -200.347072)
		(width 0.16002)
		(layer "In2.Cu")
		(net "M_C_CPU1_SA_DQS_DN<0>")
	)
	(segment
		(start 82.3595 -225.529394)
		(end 82.392012 -225.54819)
		(width 0.09525)
		(layer "In2.Cu")
		(net "M_C_CPU1_SA_DQS_DN<0>")
	)
	(segment
		(start 80.48117 -222.289878)
		(end 80.509618 -222.306134)
		(width 0.09525)
		(layer "In2.Cu")
		(net "M_C_CPU1_SA_DQS_DN<0>")
	)
	(segment
		(start 51.140614 -200.312528)
		(end 53.007006 -200.312528)
		(width 0.16002)
		(layer "In2.Cu")
		(net "M_C_CPU1_SA_DQS_DN<0>")
	)
	(segment
		(start 56.39943 -201.495152)
		(end 56.98871 -201.495152)
		(width 0.16002)
		(layer "In2.Cu")
		(net "M_C_CPU1_SA_DQS_DN<0>")
	)
	(segment
		(start 75.182984 -212.79485)
		(end 74.703178 -213.274656)
		(width 0.16002)
		(layer "In2.Cu")
		(net "M_C_CPU1_SA_DQS_DN<0>")
	)
	(segment
		(start 74.709782 -212.321394)
		(end 74.986134 -212.321394)
		(width 0.16002)
		(layer "In2.Cu")
		(net "M_C_CPU1_SA_DQS_DN<0>")
	)
	(segment
		(start 62.463934 -202.529186)
		(end 63.131192 -201.861928)
		(width 0.16002)
		(layer "In2.Cu")
		(net "M_C_CPU1_SA_DQS_DN<0>")
	)
	(segment
		(start 75.182984 -212.518244)
		(end 75.182984 -212.79485)
		(width 0.16002)
		(layer "In2.Cu")
		(net "M_C_CPU1_SA_DQS_DN<0>")
	)
	(segment
		(start 53.581046 -200.886568)
		(end 55.790846 -200.886568)
		(width 0.16002)
		(layer "In2.Cu")
		(net "M_C_CPU1_SA_DQS_DN<0>")
	)
	(segment
		(start 61.20257 -200.347072)
		(end 61.893196 -200.347072)
		(width 0.16002)
		(layer "In2.Cu")
		(net "M_C_CPU1_SA_DQS_DN<0>")
	)
	(segment
		(start 81.3816 -223.887284)
		(end 81.4197 -223.909382)
		(width 0.09525)
		(layer "In2.Cu")
		(net "M_C_CPU1_SA_DQS_DN<0>")
	)
	(segment
		(start 55.790846 -200.886568)
		(end 56.39943 -201.495152)
		(width 0.16002)
		(layer "In2.Cu")
		(net "M_C_CPU1_SA_DQS_DN<0>")
	)
	(segment
		(start 82.791554 -226.317302)
		(end 82.829654 -226.3394)
		(width 0.09525)
		(layer "In2.Cu")
		(net "M_C_CPU1_SA_DQS_DN<0>")
	)
	(segment
		(start 94.237048 -227.209096)
		(end 94.390972 -227.474526)
		(width 0.09525)
		(layer "In2.Cu")
		(net "M_C_CPU1_SA_DQS_DN<0>")
	)
	(segment
		(start 80.198722 -221.257114)
		(end 80.198722 -221.804484)
		(width 0.09525)
		(layer "In2.Cu")
		(net "M_C_CPU1_SA_DQS_DN<0>")
	)
	(segment
		(start 63.408052 -201.861928)
		(end 72.676512 -211.130388)
		(width 0.16002)
		(layer "In2.Cu")
		(net "M_C_CPU1_SA_DQS_DN<0>")
	)
	(segment
		(start 60.49137 -200.347072)
		(end 60.61837 -200.474072)
		(width 0.16002)
		(layer "In2.Cu")
		(net "M_C_CPU1_SA_DQS_DN<0>")
	)
	(segment
		(start 44.340018 -201.585322)
		(end 44.61383 -201.31151)
		(width 0.16002)
		(layer "In2.Cu")
		(net "M_C_CPU1_SA_DQS_DN<0>")
	)
	(segment
		(start 80.917542 -223.080834)
		(end 80.949546 -223.099376)
		(width 0.09525)
		(layer "In2.Cu")
		(net "M_C_CPU1_SA_DQS_DN<0>")
	)
	(segment
		(start 91.75115 -227.14458)
		(end 91.759532 -227.149406)
		(width 0.09525)
		(layer "In2.Cu")
		(net "M_C_CPU1_SA_DQS_DN<0>")
	)
	(segment
		(start 80.139794 -219.23883)
		(end 80.139794 -221.174564)
		(width 0.16002)
		(layer "In2.Cu")
		(net "M_C_CPU1_SA_DQS_DN<0>")
	)
	(segment
		(start 45.627036 -201.31151)
		(end 46.051978 -200.886568)
		(width 0.16002)
		(layer "In2.Cu")
		(net "M_C_CPU1_SA_DQS_DN<0>")
	)
	(segment
		(start 74.703178 -213.802214)
		(end 80.139794 -219.23883)
		(width 0.16002)
		(layer "In2.Cu")
		(net "M_C_CPU1_SA_DQS_DN<0>")
	)
	(segment
		(start 73.809352 -211.144358)
		(end 73.809352 -211.421218)
		(width 0.16002)
		(layer "In2.Cu")
		(net "M_C_CPU1_SA_DQS_DN<0>")
	)
	(segment
		(start 61.562996 -201.628248)
		(end 61.562996 -202.155552)
		(width 0.16002)
		(layer "In2.Cu")
		(net "M_C_CPU1_SA_DQS_DN<0>")
	)
	(segment
		(start 83.261454 -227.127308)
		(end 83.299554 -227.149406)
		(width 0.09525)
		(layer "In2.Cu")
		(net "M_C_CPU1_SA_DQS_DN<0>")
	)
	(segment
		(start 44.61383 -201.31151)
		(end 45.627036 -201.31151)
		(width 0.16002)
		(layer "In2.Cu")
		(net "M_C_CPU1_SA_DQS_DN<0>")
	)
	(segment
		(start 80.139794 -221.198186)
		(end 80.198722 -221.257114)
		(width 0.09525)
		(layer "In2.Cu")
		(net "M_C_CPU1_SA_DQS_DN<0>")
	)
	(segment
		(start 53.007006 -200.312528)
		(end 53.581046 -200.886568)
		(width 0.16002)
		(layer "In2.Cu")
		(net "M_C_CPU1_SA_DQS_DN<0>")
	)
	(segment
		(start 46.051978 -200.886568)
		(end 48.277526 -200.886568)
		(width 0.16002)
		(layer "In2.Cu")
		(net "M_C_CPU1_SA_DQS_DN<0>")
	)
	(segment
		(start 82.324448 -225.50882)
		(end 82.3595 -225.529394)
		(width 0.09525)
		(layer "In2.Cu")
		(net "M_C_CPU1_SA_DQS_DN<0>")
	)
	(segment
		(start 80.949546 -223.099376)
		(end 80.982058 -223.118172)
		(width 0.09525)
		(layer "In2.Cu")
		(net "M_C_CPU1_SA_DQS_DN<0>")
	)
	(segment
		(start 48.277526 -200.886568)
		(end 48.86833 -201.477372)
		(width 0.16002)
		(layer "In2.Cu")
		(net "M_C_CPU1_SA_DQS_DN<0>")
	)
	(segment
		(start 84.231226 -227.14458)
		(end 84.239608 -227.149406)
		(width 0.09525)
		(layer "In2.Cu")
		(net "M_C_CPU1_SA_DQS_DN<0>")
	)
	(segment
		(start 56.98871 -201.495152)
		(end 57.78627 -200.697592)
		(width 0.16002)
		(layer "In2.Cu")
		(net "M_C_CPU1_SA_DQS_DN<0>")
	)
	(segment
		(start 50.82921 -200.623932)
		(end 51.140614 -200.312528)
		(width 0.16002)
		(layer "In2.Cu")
		(net "M_C_CPU1_SA_DQS_DN<0>")
	)
	(segment
		(start 81.8896 -224.719388)
		(end 81.922112 -224.738184)
		(width 0.09525)
		(layer "In2.Cu")
		(net "M_C_CPU1_SA_DQS_DN<0>")
	)
	(segment
		(start 73.612756 -210.947762)
		(end 73.809352 -211.144358)
		(width 0.16002)
		(layer "In2.Cu")
		(net "M_C_CPU1_SA_DQS_DN<0>")
	)
	(segment
		(start 48.86833 -201.477372)
		(end 49.56937 -201.477372)
		(width 0.16002)
		(layer "In2.Cu")
		(net "M_C_CPU1_SA_DQS_DN<0>")
	)
	(segment
		(start 73.153524 -211.130388)
		(end 73.33615 -210.947762)
		(width 0.16002)
		(layer "In2.Cu")
		(net "M_C_CPU1_SA_DQS_DN<0>")
	)
	(segment
		(start 93.26245 -227.149406)
		(end 93.270832 -227.14458)
		(width 0.09525)
		(layer "In2.Cu")
		(net "M_C_CPU1_SA_DQS_DN<0>")
	)
	(segment
		(start 62.230254 -200.68413)
		(end 62.230254 -200.96099)
		(width 0.16002)
		(layer "In2.Cu")
		(net "M_C_CPU1_SA_DQS_DN<0>")
	)
	(segment
		(start 61.562996 -202.155552)
		(end 61.93663 -202.529186)
		(width 0.16002)
		(layer "In2.Cu")
		(net "M_C_CPU1_SA_DQS_DN<0>")
	)
	(segment
		(start 73.329546 -211.901024)
		(end 73.329546 -212.428582)
		(width 0.16002)
		(layer "In2.Cu")
		(net "M_C_CPU1_SA_DQS_DN<0>")
	)
	(segment
		(start 50.42281 -200.623932)
		(end 50.82921 -200.623932)
		(width 0.16002)
		(layer "In2.Cu")
		(net "M_C_CPU1_SA_DQS_DN<0>")
	)
	(segment
		(start 73.33615 -210.947762)
		(end 73.612756 -210.947762)
		(width 0.16002)
		(layer "In2.Cu")
		(net "M_C_CPU1_SA_DQS_DN<0>")
	)
	(segment
		(start 80.139794 -221.174564)
		(end 80.139794 -221.198186)
		(width 0.09525)
		(layer "In2.Cu")
		(net "M_C_CPU1_SA_DQS_DN<0>")
	)
	(segment
		(start 80.480408 -222.28937)
		(end 80.48117 -222.289878)
		(width 0.09525)
		(layer "In2.Cu")
		(net "M_C_CPU1_SA_DQS_DN<0>")
	)
	(segment
		(start 62.230254 -200.96099)
		(end 61.562996 -201.628248)
		(width 0.16002)
		(layer "In2.Cu")
		(net "M_C_CPU1_SA_DQS_DN<0>")
	)
	(segment
		(start 80.455516 -222.27286)
		(end 80.480408 -222.28937)
		(width 0.09525)
		(layer "In2.Cu")
		(net "M_C_CPU1_SA_DQS_DN<0>")
	)
	(segment
		(start 84.802472 -227.149406)
		(end 84.810854 -227.14458)
		(width 0.09525)
		(layer "In2.Cu")
		(net "M_C_CPU1_SA_DQS_DN<0>")
	)
	(segment
		(start 82.829654 -226.3394)
		(end 82.86115 -226.357688)
		(width 0.09525)
		(layer "In2.Cu")
		(net "M_C_CPU1_SA_DQS_DN<0>")
	)
	(segment
		(start 94.13621 -227.182426)
		(end 94.237048 -227.209096)
		(width 0.09525)
		(layer "In2.Cu")
		(net "M_C_CPU1_SA_DQS_DN<0>")
	)
	(segment
		(start 92.691204 -227.14458)
		(end 92.699586 -227.149406)
		(width 0.09525)
		(layer "In2.Cu")
		(net "M_C_CPU1_SA_DQS_DN<0>")
	)
	(segment
		(start 73.329546 -212.428582)
		(end 73.702418 -212.801454)
		(width 0.16002)
		(layer "In2.Cu")
		(net "M_C_CPU1_SA_DQS_DN<0>")
	)
	(segment
		(start 81.8515 -224.69729)
		(end 81.8896 -224.719388)
		(width 0.09525)
		(layer "In2.Cu")
		(net "M_C_CPU1_SA_DQS_DN<0>")
	)
	(segment
		(start 58.61431 -200.347072)
		(end 60.49137 -200.347072)
		(width 0.16002)
		(layer "In2.Cu")
		(net "M_C_CPU1_SA_DQS_DN<0>")
	)
	(segment
		(start 88.931242 -227.14458)
		(end 88.939624 -227.149406)
		(width 0.09525)
		(layer "In2.Cu")
		(net "M_C_CPU1_SA_DQS_DN<0>")
	)
	(segment
		(start 87.991188 -227.14458)
		(end 87.99957 -227.149406)
		(width 0.09525)
		(layer "In2.Cu")
		(net "M_C_CPU1_SA_DQS_DN<0>")
	)
	(segment
		(start 85.742526 -227.149406)
		(end 85.750908 -227.14458)
		(width 0.09525)
		(layer "In2.Cu")
		(net "M_C_CPU1_SA_DQS_DN<0>")
	)
	(segment
		(start 74.986134 -212.321394)
		(end 75.182984 -212.518244)
		(width 0.16002)
		(layer "In2.Cu")
		(net "M_C_CPU1_SA_DQS_DN<0>")
	)
	(segment
		(start 89.502488 -227.149406)
		(end 89.51087 -227.14458)
		(width 0.09525)
		(layer "In2.Cu")
		(net "M_C_CPU1_SA_DQS_DN<0>")
	)
	(segment
		(start 80.34782 -222.164656)
		(end 80.455516 -222.27286)
		(width 0.09525)
		(layer "In2.Cu")
		(net "M_C_CPU1_SA_DQS_DN<0>")
	)
	(segment
		(start 73.702418 -212.801454)
		(end 74.229722 -212.801454)
		(width 0.16002)
		(layer "In2.Cu")
		(net "M_C_CPU1_SA_DQS_DN<0>")
	)
	(segment
		(start 61.93663 -202.529186)
		(end 62.463934 -202.529186)
		(width 0.16002)
		(layer "In2.Cu")
		(net "M_C_CPU1_SA_DQS_DN<0>")
	)
	(segment
		(start 60.61837 -200.474072)
		(end 61.07557 -200.474072)
		(width 0.16002)
		(layer "In2.Cu")
		(net "M_C_CPU1_SA_DQS_DN<0>")
	)
	(segment
		(start 49.56937 -201.477372)
		(end 50.42281 -200.623932)
		(width 0.16002)
		(layer "In2.Cu")
		(net "M_C_CPU1_SA_DQS_DN<0>")
	)
	(segment
		(start 74.229722 -212.801454)
		(end 74.709782 -212.321394)
		(width 0.16002)
		(layer "In2.Cu")
		(net "M_C_CPU1_SA_DQS_DN<0>")
	)
	(segment
		(start 61.893196 -200.347072)
		(end 62.230254 -200.68413)
		(width 0.16002)
		(layer "In2.Cu")
		(net "M_C_CPU1_SA_DQS_DN<0>")
	)
	(segment
		(start 72.676512 -211.130388)
		(end 73.153524 -211.130388)
		(width 0.16002)
		(layer "In2.Cu")
		(net "M_C_CPU1_SA_DQS_DN<0>")
	)
	(arc
		(start 88.562434 -227.149406)
		(mid 88.746209 -227.098634)
		(end 88.931242 -227.14458)
		(width 0.09525)
		(layer "In2.Cu")
		(net "M_C_CPU1_SA_DQS_DN<0>")
	)
	(arc
		(start 87.059516 -227.149406)
		(mid 87.340948 -227.225161)
		(end 87.62238 -227.149406)
		(width 0.09525)
		(layer "In2.Cu")
		(net "M_C_CPU1_SA_DQS_DN<0>")
	)
	(arc
		(start 82.07883 -225.044508)
		(mid 82.144023 -225.307137)
		(end 82.324448 -225.50882)
		(width 0.09525)
		(layer "In2.Cu")
		(net "M_C_CPU1_SA_DQS_DN<0>")
	)
	(arc
		(start 80.982058 -223.118172)
		(mid 81.097332 -223.25245)
		(end 81.138776 -223.424496)
		(width 0.09525)
		(layer "In2.Cu")
		(net "M_C_CPU1_SA_DQS_DN<0>")
	)
	(arc
		(start 91.382342 -227.149406)
		(mid 91.566117 -227.098634)
		(end 91.75115 -227.14458)
		(width 0.09525)
		(layer "In2.Cu")
		(net "M_C_CPU1_SA_DQS_DN<0>")
	)
	(arc
		(start 93.63964 -227.149406)
		(mid 93.884066 -227.224049)
		(end 94.13621 -227.182426)
		(width 0.09525)
		(layer "In2.Cu")
		(net "M_C_CPU1_SA_DQS_DN<0>")
	)
	(arc
		(start 86.119716 -227.149406)
		(mid 86.401148 -227.225161)
		(end 86.68258 -227.149406)
		(width 0.09525)
		(layer "In2.Cu")
		(net "M_C_CPU1_SA_DQS_DN<0>")
	)
	(arc
		(start 80.198722 -221.804484)
		(mid 80.237548 -221.999365)
		(end 80.34782 -222.164656)
		(width 0.09525)
		(layer "In2.Cu")
		(net "M_C_CPU1_SA_DQS_DN<0>")
	)
	(arc
		(start 85.750908 -227.14458)
		(mid 85.93594 -227.098666)
		(end 86.119716 -227.149406)
		(width 0.09525)
		(layer "In2.Cu")
		(net "M_C_CPU1_SA_DQS_DN<0>")
	)
	(arc
		(start 83.299554 -227.149406)
		(mid 83.580986 -227.225161)
		(end 83.862418 -227.149406)
		(width 0.09525)
		(layer "In2.Cu")
		(net "M_C_CPU1_SA_DQS_DN<0>")
	)
	(arc
		(start 87.99957 -227.149406)
		(mid 88.281002 -227.225161)
		(end 88.562434 -227.149406)
		(width 0.09525)
		(layer "In2.Cu")
		(net "M_C_CPU1_SA_DQS_DN<0>")
	)
	(arc
		(start 83.01863 -226.66452)
		(mid 83.083027 -226.925826)
		(end 83.261454 -227.127308)
		(width 0.09525)
		(layer "In2.Cu")
		(net "M_C_CPU1_SA_DQS_DN<0>")
	)
	(arc
		(start 85.179662 -227.149406)
		(mid 85.461094 -227.225161)
		(end 85.742526 -227.149406)
		(width 0.09525)
		(layer "In2.Cu")
		(net "M_C_CPU1_SA_DQS_DN<0>")
	)
	(arc
		(start 90.819478 -227.149406)
		(mid 91.10091 -227.225161)
		(end 91.382342 -227.149406)
		(width 0.09525)
		(layer "In2.Cu")
		(net "M_C_CPU1_SA_DQS_DN<0>")
	)
	(arc
		(start 92.322396 -227.149406)
		(mid 92.506171 -227.098634)
		(end 92.691204 -227.14458)
		(width 0.09525)
		(layer "In2.Cu")
		(net "M_C_CPU1_SA_DQS_DN<0>")
	)
	(arc
		(start 86.68258 -227.149406)
		(mid 86.871048 -227.098729)
		(end 87.059516 -227.149406)
		(width 0.09525)
		(layer "In2.Cu")
		(net "M_C_CPU1_SA_DQS_DN<0>")
	)
	(arc
		(start 89.51087 -227.14458)
		(mid 89.695902 -227.098666)
		(end 89.879678 -227.149406)
		(width 0.09525)
		(layer "In2.Cu")
		(net "M_C_CPU1_SA_DQS_DN<0>")
	)
	(arc
		(start 93.270832 -227.14458)
		(mid 93.455864 -227.098666)
		(end 93.63964 -227.149406)
		(width 0.09525)
		(layer "In2.Cu")
		(net "M_C_CPU1_SA_DQS_DN<0>")
	)
	(arc
		(start 82.86115 -226.357688)
		(mid 82.976948 -226.492082)
		(end 83.01863 -226.66452)
		(width 0.09525)
		(layer "In2.Cu")
		(net "M_C_CPU1_SA_DQS_DN<0>")
	)
	(arc
		(start 84.239608 -227.149406)
		(mid 84.52104 -227.225161)
		(end 84.802472 -227.149406)
		(width 0.09525)
		(layer "In2.Cu")
		(net "M_C_CPU1_SA_DQS_DN<0>")
	)
	(arc
		(start 84.810854 -227.14458)
		(mid 84.995886 -227.098666)
		(end 85.179662 -227.149406)
		(width 0.09525)
		(layer "In2.Cu")
		(net "M_C_CPU1_SA_DQS_DN<0>")
	)
	(arc
		(start 82.54873 -225.854514)
		(mid 82.613127 -226.11582)
		(end 82.791554 -226.317302)
		(width 0.09525)
		(layer "In2.Cu")
		(net "M_C_CPU1_SA_DQS_DN<0>")
	)
	(arc
		(start 88.939624 -227.149406)
		(mid 89.221056 -227.225161)
		(end 89.502488 -227.149406)
		(width 0.09525)
		(layer "In2.Cu")
		(net "M_C_CPU1_SA_DQS_DN<0>")
	)
	(arc
		(start 89.879678 -227.149406)
		(mid 90.16111 -227.225161)
		(end 90.442542 -227.149406)
		(width 0.09525)
		(layer "In2.Cu")
		(net "M_C_CPU1_SA_DQS_DN<0>")
	)
	(arc
		(start 91.759532 -227.149406)
		(mid 92.040964 -227.225161)
		(end 92.322396 -227.149406)
		(width 0.09525)
		(layer "In2.Cu")
		(net "M_C_CPU1_SA_DQS_DN<0>")
	)
	(arc
		(start 80.509618 -222.306134)
		(mid 80.626922 -222.440895)
		(end 80.66913 -222.61449)
		(width 0.09525)
		(layer "In2.Cu")
		(net "M_C_CPU1_SA_DQS_DN<0>")
	)
	(arc
		(start 87.62238 -227.149406)
		(mid 87.806155 -227.098634)
		(end 87.991188 -227.14458)
		(width 0.09525)
		(layer "In2.Cu")
		(net "M_C_CPU1_SA_DQS_DN<0>")
	)
	(arc
		(start 90.442542 -227.149406)
		(mid 90.63101 -227.098729)
		(end 90.819478 -227.149406)
		(width 0.09525)
		(layer "In2.Cu")
		(net "M_C_CPU1_SA_DQS_DN<0>")
	)
	(arc
		(start 81.138776 -223.424496)
		(mid 81.203173 -223.685802)
		(end 81.3816 -223.887284)
		(width 0.09525)
		(layer "In2.Cu")
		(net "M_C_CPU1_SA_DQS_DN<0>")
	)
	(arc
		(start 83.862418 -227.149406)
		(mid 84.046193 -227.098634)
		(end 84.231226 -227.14458)
		(width 0.09525)
		(layer "In2.Cu")
		(net "M_C_CPU1_SA_DQS_DN<0>")
	)
	(arc
		(start 81.922112 -224.738184)
		(mid 82.037386 -224.872462)
		(end 82.07883 -225.044508)
		(width 0.09525)
		(layer "In2.Cu")
		(net "M_C_CPU1_SA_DQS_DN<0>")
	)
	(arc
		(start 82.392012 -225.54819)
		(mid 82.507286 -225.682468)
		(end 82.54873 -225.854514)
		(width 0.09525)
		(layer "In2.Cu")
		(net "M_C_CPU1_SA_DQS_DN<0>")
	)
	(arc
		(start 92.699586 -227.149406)
		(mid 92.981018 -227.225161)
		(end 93.26245 -227.149406)
		(width 0.09525)
		(layer "In2.Cu")
		(net "M_C_CPU1_SA_DQS_DN<0>")
	)
	(arc
		(start 81.451196 -223.92767)
		(mid 81.566994 -224.062064)
		(end 81.608676 -224.234502)
		(width 0.09525)
		(layer "In2.Cu")
		(net "M_C_CPU1_SA_DQS_DN<0>")
	)
	(arc
		(start 81.608676 -224.234502)
		(mid 81.673073 -224.495808)
		(end 81.8515 -224.69729)
		(width 0.09525)
		(layer "In2.Cu")
		(net "M_C_CPU1_SA_DQS_DN<0>")
	)
	(arc
		(start 80.66913 -222.61449)
		(mid 80.735113 -222.87867)
		(end 80.917542 -223.080834)
		(width 0.09525)
		(layer "In2.Cu")
		(net "M_C_CPU1_SA_DQS_DN<0>")
	)
	(segment
		(start 95.797878 -230.980234)
		(end 95.331026 -230.71455)
		(width 0.10668)
		(layer "F.Cu")
		(net "M_C_CPU1_SA_DQ<9>")
	)
	(segment
		(start 45.604176 -208.594452)
		(end 45.767244 -208.431384)
		(width 0.14478)
		(layer "In2.Cu")
		(net "M_C_CPU1_SA_DQ<9>")
	)
	(segment
		(start 60.35421 -207.798924)
		(end 60.35421 -207.75549)
		(width 0.14478)
		(layer "In2.Cu")
		(net "M_C_CPU1_SA_DQ<9>")
	)
	(segment
		(start 58.634122 -207.565244)
		(end 58.79719 -207.728312)
		(width 0.14478)
		(layer "In2.Cu")
		(net "M_C_CPU1_SA_DQ<9>")
	)
	(segment
		(start 48.797464 -208.647284)
		(end 48.960532 -208.810352)
		(width 0.14478)
		(layer "In2.Cu")
		(net "M_C_CPU1_SA_DQ<9>")
	)
	(segment
		(start 60.515754 -207.593946)
		(end 60.7441 -207.593946)
		(width 0.14478)
		(layer "In2.Cu")
		(net "M_C_CPU1_SA_DQ<9>")
	)
	(segment
		(start 58.79719 -207.7974)
		(end 58.960258 -207.960468)
		(width 0.14478)
		(layer "In2.Cu")
		(net "M_C_CPU1_SA_DQ<9>")
	)
	(segment
		(start 76.507086 -224.115884)
		(end 76.772008 -224.380806)
		(width 0.0889)
		(layer "In2.Cu")
		(net "M_C_CPU1_SA_DQ<9>")
	)
	(segment
		(start 45.997622 -208.431384)
		(end 46.16069 -208.594452)
		(width 0.14478)
		(layer "In2.Cu")
		(net "M_C_CPU1_SA_DQ<9>")
	)
	(segment
		(start 80.071468 -229.398068)
		(end 80.10398 -229.416864)
		(width 0.0889)
		(layer "In2.Cu")
		(net "M_C_CPU1_SA_DQ<9>")
	)
	(segment
		(start 51.37785 -207.7974)
		(end 51.540918 -207.960468)
		(width 0.14478)
		(layer "In2.Cu")
		(net "M_C_CPU1_SA_DQ<9>")
	)
	(segment
		(start 58.240676 -207.7974)
		(end 58.240676 -207.728312)
		(width 0.14478)
		(layer "In2.Cu")
		(net "M_C_CPU1_SA_DQ<9>")
	)
	(segment
		(start 66.105786 -211.911184)
		(end 66.652902 -211.911184)
		(width 0.14478)
		(layer "In2.Cu")
		(net "M_C_CPU1_SA_DQ<9>")
	)
	(segment
		(start 78.69428 -226.987608)
		(end 78.736698 -227.012246)
		(width 0.0889)
		(layer "In2.Cu")
		(net "M_C_CPU1_SA_DQ<9>")
	)
	(segment
		(start 61.457078 -208.122012)
		(end 61.618622 -207.960468)
		(width 0.14478)
		(layer "In2.Cu")
		(net "M_C_CPU1_SA_DQ<9>")
	)
	(segment
		(start 49.982628 -207.960468)
		(end 50.658268 -207.960468)
		(width 0.14478)
		(layer "In2.Cu")
		(net "M_C_CPU1_SA_DQ<9>")
	)
	(segment
		(start 46.16069 -209.037936)
		(end 46.323758 -209.201004)
		(width 0.14478)
		(layer "In2.Cu")
		(net "M_C_CPU1_SA_DQ<9>")
	)
	(segment
		(start 88.929718 -231.041702)
		(end 88.9381 -231.036876)
		(width 0.0889)
		(layer "In2.Cu")
		(net "M_C_CPU1_SA_DQ<9>")
	)
	(segment
		(start 58.403744 -207.565244)
		(end 58.634122 -207.565244)
		(width 0.14478)
		(layer "In2.Cu")
		(net "M_C_CPU1_SA_DQ<9>")
	)
	(segment
		(start 74.904346 -220.162628)
		(end 74.904346 -222.513144)
		(width 0.14478)
		(layer "In2.Cu")
		(net "M_C_CPU1_SA_DQ<9>")
	)
	(segment
		(start 44.76496 -208.810352)
		(end 45.441108 -208.810352)
		(width 0.14478)
		(layer "In2.Cu")
		(net "M_C_CPU1_SA_DQ<9>")
	)
	(segment
		(start 61.457078 -208.165446)
		(end 61.457078 -208.122012)
		(width 0.14478)
		(layer "In2.Cu")
		(net "M_C_CPU1_SA_DQ<9>")
	)
	(segment
		(start 58.077608 -207.960468)
		(end 58.240676 -207.7974)
		(width 0.14478)
		(layer "In2.Cu")
		(net "M_C_CPU1_SA_DQ<9>")
	)
	(segment
		(start 57.397396 -207.960468)
		(end 58.077608 -207.960468)
		(width 0.14478)
		(layer "In2.Cu")
		(net "M_C_CPU1_SA_DQ<9>")
	)
	(segment
		(start 48.24095 -208.647284)
		(end 48.24095 -208.581752)
		(width 0.14478)
		(layer "In2.Cu")
		(net "M_C_CPU1_SA_DQ<9>")
	)
	(segment
		(start 95.462852 -231.063038)
		(end 95.48495 -230.97998)
		(width 0.0889)
		(layer "In2.Cu")
		(net "M_C_CPU1_SA_DQ<9>")
	)
	(segment
		(start 85.74405 -231.036876)
		(end 85.752432 -231.041702)
		(width 0.0889)
		(layer "In2.Cu")
		(net "M_C_CPU1_SA_DQ<9>")
	)
	(segment
		(start 53.102764 -207.960468)
		(end 53.952648 -208.810352)
		(width 0.14478)
		(layer "In2.Cu")
		(net "M_C_CPU1_SA_DQ<9>")
	)
	(segment
		(start 48.797464 -208.581752)
		(end 48.797464 -208.647284)
		(width 0.14478)
		(layer "In2.Cu")
		(net "M_C_CPU1_SA_DQ<9>")
	)
	(segment
		(start 81.044034 -231.036876)
		(end 81.052416 -231.041702)
		(width 0.0889)
		(layer "In2.Cu")
		(net "M_C_CPU1_SA_DQ<9>")
	)
	(segment
		(start 45.767244 -208.431384)
		(end 45.997622 -208.431384)
		(width 0.14478)
		(layer "In2.Cu")
		(net "M_C_CPU1_SA_DQ<9>")
	)
	(segment
		(start 79.63408 -228.607366)
		(end 79.669386 -228.62794)
		(width 0.0889)
		(layer "In2.Cu")
		(net "M_C_CPU1_SA_DQ<9>")
	)
	(segment
		(start 76.772008 -224.380806)
		(end 77.005434 -224.380806)
		(width 0.0889)
		(layer "In2.Cu")
		(net "M_C_CPU1_SA_DQ<9>")
	)
	(segment
		(start 53.952648 -208.810352)
		(end 56.547512 -208.810352)
		(width 0.14478)
		(layer "In2.Cu")
		(net "M_C_CPU1_SA_DQ<9>")
	)
	(segment
		(start 84.803996 -231.036876)
		(end 84.812378 -231.041702)
		(width 0.0889)
		(layer "In2.Cu")
		(net "M_C_CPU1_SA_DQ<9>")
	)
	(segment
		(start 47.436786 -208.810352)
		(end 48.077882 -208.810352)
		(width 0.14478)
		(layer "In2.Cu")
		(net "M_C_CPU1_SA_DQ<9>")
	)
	(segment
		(start 60.7441 -207.593946)
		(end 60.905644 -207.75549)
		(width 0.14478)
		(layer "In2.Cu")
		(net "M_C_CPU1_SA_DQ<9>")
	)
	(segment
		(start 93.263974 -231.036876)
		(end 93.272356 -231.041702)
		(width 0.0889)
		(layer "In2.Cu")
		(net "M_C_CPU1_SA_DQ<9>")
	)
	(segment
		(start 78.199234 -226.163124)
		(end 78.224126 -226.177602)
		(width 0.0889)
		(layer "In2.Cu")
		(net "M_C_CPU1_SA_DQ<9>")
	)
	(segment
		(start 46.717204 -208.594452)
		(end 46.880272 -208.431384)
		(width 0.14478)
		(layer "In2.Cu")
		(net "M_C_CPU1_SA_DQ<9>")
	)
	(segment
		(start 48.24095 -208.581752)
		(end 48.404018 -208.418684)
		(width 0.14478)
		(layer "In2.Cu")
		(net "M_C_CPU1_SA_DQ<9>")
	)
	(segment
		(start 50.821336 -207.728312)
		(end 50.984404 -207.565244)
		(width 0.14478)
		(layer "In2.Cu")
		(net "M_C_CPU1_SA_DQ<9>")
	)
	(segment
		(start 58.240676 -207.728312)
		(end 58.403744 -207.565244)
		(width 0.14478)
		(layer "In2.Cu")
		(net "M_C_CPU1_SA_DQ<9>")
	)
	(segment
		(start 56.547512 -208.810352)
		(end 57.397396 -207.960468)
		(width 0.14478)
		(layer "In2.Cu")
		(net "M_C_CPU1_SA_DQ<9>")
	)
	(segment
		(start 60.192666 -207.960468)
		(end 60.35421 -207.798924)
		(width 0.14478)
		(layer "In2.Cu")
		(net "M_C_CPU1_SA_DQ<9>")
	)
	(segment
		(start 91.749626 -231.041702)
		(end 91.758008 -231.036876)
		(width 0.0889)
		(layer "In2.Cu")
		(net "M_C_CPU1_SA_DQ<9>")
	)
	(segment
		(start 77.754734 -225.368612)
		(end 77.788008 -225.387916)
		(width 0.0889)
		(layer "In2.Cu")
		(net "M_C_CPU1_SA_DQ<9>")
	)
	(segment
		(start 83.289648 -231.041702)
		(end 83.29803 -231.036876)
		(width 0.0889)
		(layer "In2.Cu")
		(net "M_C_CPU1_SA_DQ<9>")
	)
	(segment
		(start 58.960258 -207.960468)
		(end 60.192666 -207.960468)
		(width 0.14478)
		(layer "In2.Cu")
		(net "M_C_CPU1_SA_DQ<9>")
	)
	(segment
		(start 81.010506 -231.017318)
		(end 81.044034 -231.036876)
		(width 0.0889)
		(layer "In2.Cu")
		(net "M_C_CPU1_SA_DQ<9>")
	)
	(segment
		(start 66.652902 -211.911184)
		(end 74.904346 -220.162628)
		(width 0.14478)
		(layer "In2.Cu")
		(net "M_C_CPU1_SA_DQ<9>")
	)
	(segment
		(start 61.295534 -208.32699)
		(end 61.457078 -208.165446)
		(width 0.14478)
		(layer "In2.Cu")
		(net "M_C_CPU1_SA_DQ<9>")
	)
	(segment
		(start 89.504012 -231.036876)
		(end 89.512394 -231.041702)
		(width 0.0889)
		(layer "In2.Cu")
		(net "M_C_CPU1_SA_DQ<9>")
	)
	(segment
		(start 45.441108 -208.810352)
		(end 45.604176 -208.647284)
		(width 0.14478)
		(layer "In2.Cu")
		(net "M_C_CPU1_SA_DQ<9>")
	)
	(segment
		(start 58.79719 -207.728312)
		(end 58.79719 -207.7974)
		(width 0.14478)
		(layer "In2.Cu")
		(net "M_C_CPU1_SA_DQ<9>")
	)
	(segment
		(start 87.989664 -231.041702)
		(end 87.998046 -231.036876)
		(width 0.0889)
		(layer "In2.Cu")
		(net "M_C_CPU1_SA_DQ<9>")
	)
	(segment
		(start 77.284072 -224.557082)
		(end 77.28585 -224.558352)
		(width 0.0889)
		(layer "In2.Cu")
		(net "M_C_CPU1_SA_DQ<9>")
	)
	(segment
		(start 92.68968 -231.041702)
		(end 92.698062 -231.036876)
		(width 0.0889)
		(layer "In2.Cu")
		(net "M_C_CPU1_SA_DQ<9>")
	)
	(segment
		(start 51.540918 -207.960468)
		(end 53.102764 -207.960468)
		(width 0.14478)
		(layer "In2.Cu")
		(net "M_C_CPU1_SA_DQ<9>")
	)
	(segment
		(start 95.48495 -230.97998)
		(end 95.331026 -230.71455)
		(width 0.0889)
		(layer "In2.Cu")
		(net "M_C_CPU1_SA_DQ<9>")
	)
	(segment
		(start 46.554136 -209.201004)
		(end 46.717204 -209.037936)
		(width 0.14478)
		(layer "In2.Cu")
		(net "M_C_CPU1_SA_DQ<9>")
	)
	(segment
		(start 79.128874 -227.777294)
		(end 79.164434 -227.797868)
		(width 0.0889)
		(layer "In2.Cu")
		(net "M_C_CPU1_SA_DQ<9>")
	)
	(segment
		(start 48.404018 -208.418684)
		(end 48.634396 -208.418684)
		(width 0.14478)
		(layer "In2.Cu")
		(net "M_C_CPU1_SA_DQ<9>")
	)
	(segment
		(start 78.658212 -226.96678)
		(end 78.69428 -226.987608)
		(width 0.0889)
		(layer "In2.Cu")
		(net "M_C_CPU1_SA_DQ<9>")
	)
	(segment
		(start 48.960532 -208.810352)
		(end 49.132744 -208.810352)
		(width 0.14478)
		(layer "In2.Cu")
		(net "M_C_CPU1_SA_DQ<9>")
	)
	(segment
		(start 84.229702 -231.041702)
		(end 84.238084 -231.036876)
		(width 0.0889)
		(layer "In2.Cu")
		(net "M_C_CPU1_SA_DQ<9>")
	)
	(segment
		(start 46.323758 -209.201004)
		(end 46.554136 -209.201004)
		(width 0.14478)
		(layer "In2.Cu")
		(net "M_C_CPU1_SA_DQ<9>")
	)
	(segment
		(start 62.15507 -207.960468)
		(end 66.105786 -211.911184)
		(width 0.14478)
		(layer "In2.Cu")
		(net "M_C_CPU1_SA_DQ<9>")
	)
	(segment
		(start 48.634396 -208.418684)
		(end 48.797464 -208.581752)
		(width 0.14478)
		(layer "In2.Cu")
		(net "M_C_CPU1_SA_DQ<9>")
	)
	(segment
		(start 49.132744 -208.810352)
		(end 49.982628 -207.960468)
		(width 0.14478)
		(layer "In2.Cu")
		(net "M_C_CPU1_SA_DQ<9>")
	)
	(segment
		(start 47.11065 -208.431384)
		(end 47.273718 -208.594452)
		(width 0.14478)
		(layer "In2.Cu")
		(net "M_C_CPU1_SA_DQ<9>")
	)
	(segment
		(start 80.10398 -229.416864)
		(end 80.143096 -229.439724)
		(width 0.0889)
		(layer "In2.Cu")
		(net "M_C_CPU1_SA_DQ<9>")
	)
	(segment
		(start 46.16069 -208.594452)
		(end 46.16069 -209.037936)
		(width 0.14478)
		(layer "In2.Cu")
		(net "M_C_CPU1_SA_DQ<9>")
	)
	(segment
		(start 51.37785 -207.728312)
		(end 51.37785 -207.7974)
		(width 0.14478)
		(layer "In2.Cu")
		(net "M_C_CPU1_SA_DQ<9>")
	)
	(segment
		(start 60.905644 -208.165446)
		(end 61.067188 -208.32699)
		(width 0.14478)
		(layer "In2.Cu")
		(net "M_C_CPU1_SA_DQ<9>")
	)
	(segment
		(start 51.214782 -207.565244)
		(end 51.37785 -207.728312)
		(width 0.14478)
		(layer "In2.Cu")
		(net "M_C_CPU1_SA_DQ<9>")
	)
	(segment
		(start 44.340018 -208.38541)
		(end 44.76496 -208.810352)
		(width 0.14478)
		(layer "In2.Cu")
		(net "M_C_CPU1_SA_DQ<9>")
	)
	(segment
		(start 60.35421 -207.75549)
		(end 60.515754 -207.593946)
		(width 0.14478)
		(layer "In2.Cu")
		(net "M_C_CPU1_SA_DQ<9>")
	)
	(segment
		(start 60.905644 -207.75549)
		(end 60.905644 -208.165446)
		(width 0.14478)
		(layer "In2.Cu")
		(net "M_C_CPU1_SA_DQ<9>")
	)
	(segment
		(start 80.574134 -230.22687)
		(end 80.607662 -230.246428)
		(width 0.0889)
		(layer "In2.Cu")
		(net "M_C_CPU1_SA_DQ<9>")
	)
	(segment
		(start 80.542384 -230.208582)
		(end 80.574134 -230.22687)
		(width 0.0889)
		(layer "In2.Cu")
		(net "M_C_CPU1_SA_DQ<9>")
	)
	(segment
		(start 79.164434 -227.797868)
		(end 79.200756 -227.81895)
		(width 0.0889)
		(layer "In2.Cu")
		(net "M_C_CPU1_SA_DQ<9>")
	)
	(segment
		(start 50.984404 -207.565244)
		(end 51.214782 -207.565244)
		(width 0.14478)
		(layer "In2.Cu")
		(net "M_C_CPU1_SA_DQ<9>")
	)
	(segment
		(start 46.880272 -208.431384)
		(end 47.11065 -208.431384)
		(width 0.14478)
		(layer "In2.Cu")
		(net "M_C_CPU1_SA_DQ<9>")
	)
	(segment
		(start 77.719174 -225.348038)
		(end 77.754734 -225.368612)
		(width 0.0889)
		(layer "In2.Cu")
		(net "M_C_CPU1_SA_DQ<9>")
	)
	(segment
		(start 50.821336 -207.7974)
		(end 50.821336 -207.728312)
		(width 0.14478)
		(layer "In2.Cu")
		(net "M_C_CPU1_SA_DQ<9>")
	)
	(segment
		(start 61.618622 -207.960468)
		(end 62.15507 -207.960468)
		(width 0.14478)
		(layer "In2.Cu")
		(net "M_C_CPU1_SA_DQ<9>")
	)
	(segment
		(start 74.904346 -222.513144)
		(end 76.507086 -224.115884)
		(width 0.14478)
		(layer "In2.Cu")
		(net "M_C_CPU1_SA_DQ<9>")
	)
	(segment
		(start 45.604176 -208.647284)
		(end 45.604176 -208.594452)
		(width 0.14478)
		(layer "In2.Cu")
		(net "M_C_CPU1_SA_DQ<9>")
	)
	(segment
		(start 47.273718 -208.647284)
		(end 47.436786 -208.810352)
		(width 0.14478)
		(layer "In2.Cu")
		(net "M_C_CPU1_SA_DQ<9>")
	)
	(segment
		(start 50.658268 -207.960468)
		(end 50.821336 -207.7974)
		(width 0.14478)
		(layer "In2.Cu")
		(net "M_C_CPU1_SA_DQ<9>")
	)
	(segment
		(start 47.273718 -208.594452)
		(end 47.273718 -208.647284)
		(width 0.14478)
		(layer "In2.Cu")
		(net "M_C_CPU1_SA_DQ<9>")
	)
	(segment
		(start 79.606902 -228.591618)
		(end 79.63408 -228.607366)
		(width 0.0889)
		(layer "In2.Cu")
		(net "M_C_CPU1_SA_DQ<9>")
	)
	(segment
		(start 78.224126 -226.177602)
		(end 78.255368 -226.195636)
		(width 0.0889)
		(layer "In2.Cu")
		(net "M_C_CPU1_SA_DQ<9>")
	)
	(segment
		(start 61.067188 -208.32699)
		(end 61.295534 -208.32699)
		(width 0.14478)
		(layer "In2.Cu")
		(net "M_C_CPU1_SA_DQ<9>")
	)
	(segment
		(start 94.204028 -231.036876)
		(end 94.21241 -231.041702)
		(width 0.0889)
		(layer "In2.Cu")
		(net "M_C_CPU1_SA_DQ<9>")
	)
	(segment
		(start 46.717204 -209.037936)
		(end 46.717204 -208.594452)
		(width 0.14478)
		(layer "In2.Cu")
		(net "M_C_CPU1_SA_DQ<9>")
	)
	(segment
		(start 48.077882 -208.810352)
		(end 48.24095 -208.647284)
		(width 0.14478)
		(layer "In2.Cu")
		(net "M_C_CPU1_SA_DQ<9>")
	)
	(arc
		(start 89.878154 -231.036876)
		(mid 90.16111 -230.960699)
		(end 90.444066 -231.036876)
		(width 0.0889)
		(layer "In2.Cu")
		(net "M_C_CPU1_SA_DQ<9>")
	)
	(arc
		(start 79.200756 -227.81895)
		(mid 79.38129 -228.02147)
		(end 79.446628 -228.284786)
		(width 0.0889)
		(layer "In2.Cu")
		(net "M_C_CPU1_SA_DQ<9>")
	)
	(arc
		(start 78.736698 -227.012246)
		(mid 78.913173 -227.214471)
		(end 78.976474 -227.475288)
		(width 0.0889)
		(layer "In2.Cu")
		(net "M_C_CPU1_SA_DQ<9>")
	)
	(arc
		(start 77.088238 -224.413318)
		(mid 77.182218 -224.490563)
		(end 77.284072 -224.557082)
		(width 0.0889)
		(layer "In2.Cu")
		(net "M_C_CPU1_SA_DQ<9>")
	)
	(arc
		(start 91.758008 -231.036876)
		(mid 92.040964 -230.960699)
		(end 92.32392 -231.036876)
		(width 0.0889)
		(layer "In2.Cu")
		(net "M_C_CPU1_SA_DQ<9>")
	)
	(arc
		(start 80.143096 -229.439724)
		(mid 80.321909 -229.642074)
		(end 80.386428 -229.90429)
		(width 0.0889)
		(layer "In2.Cu")
		(net "M_C_CPU1_SA_DQ<9>")
	)
	(arc
		(start 81.418176 -231.036876)
		(mid 81.701132 -230.960699)
		(end 81.984088 -231.036876)
		(width 0.0889)
		(layer "In2.Cu")
		(net "M_C_CPU1_SA_DQ<9>")
	)
	(arc
		(start 84.812378 -231.041702)
		(mid 84.995886 -231.087227)
		(end 85.178138 -231.036876)
		(width 0.0889)
		(layer "In2.Cu")
		(net "M_C_CPU1_SA_DQ<9>")
	)
	(arc
		(start 81.984088 -231.036876)
		(mid 82.171032 -231.087165)
		(end 82.357976 -231.036876)
		(width 0.0889)
		(layer "In2.Cu")
		(net "M_C_CPU1_SA_DQ<9>")
	)
	(arc
		(start 88.9381 -231.036876)
		(mid 89.221056 -230.960699)
		(end 89.504012 -231.036876)
		(width 0.0889)
		(layer "In2.Cu")
		(net "M_C_CPU1_SA_DQ<9>")
	)
	(arc
		(start 95.144082 -231.036876)
		(mid 95.300519 -231.085914)
		(end 95.462852 -231.063038)
		(width 0.0889)
		(layer "In2.Cu")
		(net "M_C_CPU1_SA_DQ<9>")
	)
	(arc
		(start 85.752432 -231.041702)
		(mid 85.93594 -231.087227)
		(end 86.118192 -231.036876)
		(width 0.0889)
		(layer "In2.Cu")
		(net "M_C_CPU1_SA_DQ<9>")
	)
	(arc
		(start 79.916528 -229.094538)
		(mid 79.957494 -229.264944)
		(end 80.071468 -229.398068)
		(width 0.0889)
		(layer "In2.Cu")
		(net "M_C_CPU1_SA_DQ<9>")
	)
	(arc
		(start 87.057992 -231.036876)
		(mid 87.340948 -230.960699)
		(end 87.623904 -231.036876)
		(width 0.0889)
		(layer "In2.Cu")
		(net "M_C_CPU1_SA_DQ<9>")
	)
	(arc
		(start 93.638116 -231.036876)
		(mid 93.921072 -230.960699)
		(end 94.204028 -231.036876)
		(width 0.0889)
		(layer "In2.Cu")
		(net "M_C_CPU1_SA_DQ<9>")
	)
	(arc
		(start 78.506828 -226.66579)
		(mid 78.546806 -226.834247)
		(end 78.658212 -226.96678)
		(width 0.0889)
		(layer "In2.Cu")
		(net "M_C_CPU1_SA_DQ<9>")
	)
	(arc
		(start 83.863942 -231.036876)
		(mid 84.046193 -231.08726)
		(end 84.229702 -231.041702)
		(width 0.0889)
		(layer "In2.Cu")
		(net "M_C_CPU1_SA_DQ<9>")
	)
	(arc
		(start 87.998046 -231.036876)
		(mid 88.281002 -230.960699)
		(end 88.563958 -231.036876)
		(width 0.0889)
		(layer "In2.Cu")
		(net "M_C_CPU1_SA_DQ<9>")
	)
	(arc
		(start 78.255368 -226.195636)
		(mid 78.440047 -226.399191)
		(end 78.506828 -226.66579)
		(width 0.0889)
		(layer "In2.Cu")
		(net "M_C_CPU1_SA_DQ<9>")
	)
	(arc
		(start 79.446628 -228.284786)
		(mid 79.48916 -228.457849)
		(end 79.606902 -228.591618)
		(width 0.0889)
		(layer "In2.Cu")
		(net "M_C_CPU1_SA_DQ<9>")
	)
	(arc
		(start 78.976474 -227.475288)
		(mid 79.016681 -227.644453)
		(end 79.128874 -227.777294)
		(width 0.0889)
		(layer "In2.Cu")
		(net "M_C_CPU1_SA_DQ<9>")
	)
	(arc
		(start 82.357976 -231.036876)
		(mid 82.640932 -230.960699)
		(end 82.923888 -231.036876)
		(width 0.0889)
		(layer "In2.Cu")
		(net "M_C_CPU1_SA_DQ<9>")
	)
	(arc
		(start 79.669386 -228.62794)
		(mid 79.850768 -228.830609)
		(end 79.916528 -229.094538)
		(width 0.0889)
		(layer "In2.Cu")
		(net "M_C_CPU1_SA_DQ<9>")
	)
	(arc
		(start 83.29803 -231.036876)
		(mid 83.580986 -230.960699)
		(end 83.863942 -231.036876)
		(width 0.0889)
		(layer "In2.Cu")
		(net "M_C_CPU1_SA_DQ<9>")
	)
	(arc
		(start 85.178138 -231.036876)
		(mid 85.461094 -230.960699)
		(end 85.74405 -231.036876)
		(width 0.0889)
		(layer "In2.Cu")
		(net "M_C_CPU1_SA_DQ<9>")
	)
	(arc
		(start 81.052416 -231.041702)
		(mid 81.235924 -231.087227)
		(end 81.418176 -231.036876)
		(width 0.0889)
		(layer "In2.Cu")
		(net "M_C_CPU1_SA_DQ<9>")
	)
	(arc
		(start 82.923888 -231.036876)
		(mid 83.106139 -231.08726)
		(end 83.289648 -231.041702)
		(width 0.0889)
		(layer "In2.Cu")
		(net "M_C_CPU1_SA_DQ<9>")
	)
	(arc
		(start 92.698062 -231.036876)
		(mid 92.981018 -230.960699)
		(end 93.263974 -231.036876)
		(width 0.0889)
		(layer "In2.Cu")
		(net "M_C_CPU1_SA_DQ<9>")
	)
	(arc
		(start 94.21241 -231.041702)
		(mid 94.395918 -231.087227)
		(end 94.57817 -231.036876)
		(width 0.0889)
		(layer "In2.Cu")
		(net "M_C_CPU1_SA_DQ<9>")
	)
	(arc
		(start 77.005434 -224.380806)
		(mid 77.049887 -224.389279)
		(end 77.088238 -224.413318)
		(width 0.0889)
		(layer "In2.Cu")
		(net "M_C_CPU1_SA_DQ<9>")
	)
	(arc
		(start 86.118192 -231.036876)
		(mid 86.401148 -230.960699)
		(end 86.684104 -231.036876)
		(width 0.0889)
		(layer "In2.Cu")
		(net "M_C_CPU1_SA_DQ<9>")
	)
	(arc
		(start 87.623904 -231.036876)
		(mid 87.806155 -231.08726)
		(end 87.989664 -231.041702)
		(width 0.0889)
		(layer "In2.Cu")
		(net "M_C_CPU1_SA_DQ<9>")
	)
	(arc
		(start 77.788008 -225.387916)
		(mid 77.970431 -225.590548)
		(end 78.036674 -225.855022)
		(width 0.0889)
		(layer "In2.Cu")
		(net "M_C_CPU1_SA_DQ<9>")
	)
	(arc
		(start 90.444066 -231.036876)
		(mid 90.63101 -231.087165)
		(end 90.817954 -231.036876)
		(width 0.0889)
		(layer "In2.Cu")
		(net "M_C_CPU1_SA_DQ<9>")
	)
	(arc
		(start 92.32392 -231.036876)
		(mid 92.506171 -231.08726)
		(end 92.68968 -231.041702)
		(width 0.0889)
		(layer "In2.Cu")
		(net "M_C_CPU1_SA_DQ<9>")
	)
	(arc
		(start 86.684104 -231.036876)
		(mid 86.871048 -231.087165)
		(end 87.057992 -231.036876)
		(width 0.0889)
		(layer "In2.Cu")
		(net "M_C_CPU1_SA_DQ<9>")
	)
	(arc
		(start 77.28585 -224.558352)
		(mid 77.491505 -224.764502)
		(end 77.566774 -225.045778)
		(width 0.0889)
		(layer "In2.Cu")
		(net "M_C_CPU1_SA_DQ<9>")
	)
	(arc
		(start 77.566774 -225.045778)
		(mid 77.606923 -225.215083)
		(end 77.719174 -225.348038)
		(width 0.0889)
		(layer "In2.Cu")
		(net "M_C_CPU1_SA_DQ<9>")
	)
	(arc
		(start 91.383866 -231.036876)
		(mid 91.566117 -231.08726)
		(end 91.749626 -231.041702)
		(width 0.0889)
		(layer "In2.Cu")
		(net "M_C_CPU1_SA_DQ<9>")
	)
	(arc
		(start 88.563958 -231.036876)
		(mid 88.746209 -231.08726)
		(end 88.929718 -231.041702)
		(width 0.0889)
		(layer "In2.Cu")
		(net "M_C_CPU1_SA_DQ<9>")
	)
	(arc
		(start 80.607662 -230.246428)
		(mid 80.790324 -230.449509)
		(end 80.856328 -230.71455)
		(width 0.0889)
		(layer "In2.Cu")
		(net "M_C_CPU1_SA_DQ<9>")
	)
	(arc
		(start 78.036674 -225.855022)
		(mid 78.079903 -226.02916)
		(end 78.199234 -226.163124)
		(width 0.0889)
		(layer "In2.Cu")
		(net "M_C_CPU1_SA_DQ<9>")
	)
	(arc
		(start 94.57817 -231.036876)
		(mid 94.861126 -230.960699)
		(end 95.144082 -231.036876)
		(width 0.0889)
		(layer "In2.Cu")
		(net "M_C_CPU1_SA_DQ<9>")
	)
	(arc
		(start 90.817954 -231.036876)
		(mid 91.10091 -230.960699)
		(end 91.383866 -231.036876)
		(width 0.0889)
		(layer "In2.Cu")
		(net "M_C_CPU1_SA_DQ<9>")
	)
	(arc
		(start 84.238084 -231.036876)
		(mid 84.52104 -230.960699)
		(end 84.803996 -231.036876)
		(width 0.0889)
		(layer "In2.Cu")
		(net "M_C_CPU1_SA_DQ<9>")
	)
	(arc
		(start 93.272356 -231.041702)
		(mid 93.455864 -231.087227)
		(end 93.638116 -231.036876)
		(width 0.0889)
		(layer "In2.Cu")
		(net "M_C_CPU1_SA_DQ<9>")
	)
	(arc
		(start 80.386428 -229.90429)
		(mid 80.427683 -230.075261)
		(end 80.542384 -230.208582)
		(width 0.0889)
		(layer "In2.Cu")
		(net "M_C_CPU1_SA_DQ<9>")
	)
	(arc
		(start 89.512394 -231.041702)
		(mid 89.695902 -231.087227)
		(end 89.878154 -231.036876)
		(width 0.0889)
		(layer "In2.Cu")
		(net "M_C_CPU1_SA_DQ<9>")
	)
	(arc
		(start 80.856328 -230.71455)
		(mid 80.89709 -230.884434)
		(end 81.010506 -231.017318)
		(width 0.0889)
		(layer "In2.Cu")
		(net "M_C_CPU1_SA_DQ<9>")
	)
	(segment
		(start 94.387924 -230.170228)
		(end 93.921072 -229.90429)
		(width 0.10668)
		(layer "F.Cu")
		(net "M_C_CPU1_SA_DQ<8>")
	)
	(segment
		(start 65.36944 -209.836004)
		(end 65.532508 -209.999072)
		(width 0.14478)
		(layer "In2.Cu")
		(net "M_C_CPU1_SA_DQ<8>")
	)
	(segment
		(start 79.131668 -226.15652)
		(end 79.164434 -226.17557)
		(width 0.0889)
		(layer "In2.Cu")
		(net "M_C_CPU1_SA_DQ<8>")
	)
	(segment
		(start 94.074996 -230.16972)
		(end 93.921072 -229.90429)
		(width 0.0889)
		(layer "In2.Cu")
		(net "M_C_CPU1_SA_DQ<8>")
	)
	(segment
		(start 64.855598 -208.544414)
		(end 64.58204 -208.817972)
		(width 0.14478)
		(layer "In2.Cu")
		(net "M_C_CPU1_SA_DQ<8>")
	)
	(segment
		(start 44.76496 -207.11033)
		(end 49.41316 -207.11033)
		(width 0.14478)
		(layer "In2.Cu")
		(net "M_C_CPU1_SA_DQ<8>")
	)
	(segment
		(start 90.913966 -230.22687)
		(end 90.922348 -230.231696)
		(width 0.0889)
		(layer "In2.Cu")
		(net "M_C_CPU1_SA_DQ<8>")
	)
	(segment
		(start 78.664562 -225.35007)
		(end 78.694026 -225.367088)
		(width 0.0889)
		(layer "In2.Cu")
		(net "M_C_CPU1_SA_DQ<8>")
	)
	(segment
		(start 81.010506 -229.397306)
		(end 81.044034 -229.416864)
		(width 0.0889)
		(layer "In2.Cu")
		(net "M_C_CPU1_SA_DQ<8>")
	)
	(segment
		(start 65.47993 -208.938114)
		(end 65.642998 -209.101182)
		(width 0.14478)
		(layer "In2.Cu")
		(net "M_C_CPU1_SA_DQ<8>")
	)
	(segment
		(start 80.542384 -228.588824)
		(end 80.574134 -228.607112)
		(width 0.0889)
		(layer "In2.Cu")
		(net "M_C_CPU1_SA_DQ<8>")
	)
	(segment
		(start 86.57971 -230.231696)
		(end 86.588092 -230.22687)
		(width 0.0889)
		(layer "In2.Cu")
		(net "M_C_CPU1_SA_DQ<8>")
	)
	(segment
		(start 63.280798 -206.969614)
		(end 63.00724 -207.243172)
		(width 0.14478)
		(layer "In2.Cu")
		(net "M_C_CPU1_SA_DQ<8>")
	)
	(segment
		(start 63.79464 -208.030572)
		(end 63.79464 -208.261204)
		(width 0.14478)
		(layer "In2.Cu")
		(net "M_C_CPU1_SA_DQ<8>")
	)
	(segment
		(start 60.27039 -206.260446)
		(end 60.630054 -206.62011)
		(width 0.14478)
		(layer "In2.Cu")
		(net "M_C_CPU1_SA_DQ<8>")
	)
	(segment
		(start 65.642998 -209.331814)
		(end 65.36944 -209.605372)
		(width 0.14478)
		(layer "In2.Cu")
		(net "M_C_CPU1_SA_DQ<8>")
	)
	(segment
		(start 49.41316 -207.11033)
		(end 50.263044 -206.260446)
		(width 0.14478)
		(layer "In2.Cu")
		(net "M_C_CPU1_SA_DQ<8>")
	)
	(segment
		(start 65.532508 -209.999072)
		(end 65.76314 -209.999072)
		(width 0.14478)
		(layer "In2.Cu")
		(net "M_C_CPU1_SA_DQ<8>")
	)
	(segment
		(start 56.950864 -207.11033)
		(end 57.800748 -206.260446)
		(width 0.14478)
		(layer "In2.Cu")
		(net "M_C_CPU1_SA_DQ<8>")
	)
	(segment
		(start 87.154004 -230.22687)
		(end 87.162386 -230.231696)
		(width 0.0889)
		(layer "In2.Cu")
		(net "M_C_CPU1_SA_DQ<8>")
	)
	(segment
		(start 50.263044 -206.260446)
		(end 53.102764 -206.260446)
		(width 0.14478)
		(layer "In2.Cu")
		(net "M_C_CPU1_SA_DQ<8>")
	)
	(segment
		(start 77.507846 -223.483424)
		(end 77.79512 -223.770698)
		(width 0.0889)
		(layer "In2.Cu")
		(net "M_C_CPU1_SA_DQ<8>")
	)
	(segment
		(start 63.674498 -207.363314)
		(end 63.90513 -207.363314)
		(width 0.14478)
		(layer "In2.Cu")
		(net "M_C_CPU1_SA_DQ<8>")
	)
	(segment
		(start 64.58204 -209.048604)
		(end 64.745108 -209.211672)
		(width 0.14478)
		(layer "In2.Cu")
		(net "M_C_CPU1_SA_DQ<8>")
	)
	(segment
		(start 90.339672 -230.231696)
		(end 90.348054 -230.22687)
		(width 0.0889)
		(layer "In2.Cu")
		(net "M_C_CPU1_SA_DQ<8>")
	)
	(segment
		(start 63.11773 -206.575914)
		(end 63.280798 -206.738982)
		(width 0.14478)
		(layer "In2.Cu")
		(net "M_C_CPU1_SA_DQ<8>")
	)
	(segment
		(start 75.849226 -221.687644)
		(end 77.507846 -223.346264)
		(width 0.14478)
		(layer "In2.Cu")
		(net "M_C_CPU1_SA_DQ<8>")
	)
	(segment
		(start 57.800748 -206.260446)
		(end 60.27039 -206.260446)
		(width 0.14478)
		(layer "In2.Cu")
		(net "M_C_CPU1_SA_DQ<8>")
	)
	(segment
		(start 63.280798 -206.738982)
		(end 63.280798 -206.969614)
		(width 0.14478)
		(layer "In2.Cu")
		(net "M_C_CPU1_SA_DQ<8>")
	)
	(segment
		(start 80.574134 -228.607112)
		(end 80.610456 -228.628194)
		(width 0.0889)
		(layer "In2.Cu")
		(net "M_C_CPU1_SA_DQ<8>")
	)
	(segment
		(start 66.15684 -210.392772)
		(end 66.15684 -210.623404)
		(width 0.14478)
		(layer "In2.Cu")
		(net "M_C_CPU1_SA_DQ<8>")
	)
	(segment
		(start 64.58204 -208.817972)
		(end 64.58204 -209.048604)
		(width 0.14478)
		(layer "In2.Cu")
		(net "M_C_CPU1_SA_DQ<8>")
	)
	(segment
		(start 63.170308 -207.636872)
		(end 63.40094 -207.636872)
		(width 0.14478)
		(layer "In2.Cu")
		(net "M_C_CPU1_SA_DQ<8>")
	)
	(segment
		(start 53.952648 -207.11033)
		(end 56.950864 -207.11033)
		(width 0.14478)
		(layer "In2.Cu")
		(net "M_C_CPU1_SA_DQ<8>")
	)
	(segment
		(start 63.00724 -207.473804)
		(end 63.170308 -207.636872)
		(width 0.14478)
		(layer "In2.Cu")
		(net "M_C_CPU1_SA_DQ<8>")
	)
	(segment
		(start 83.394042 -230.22687)
		(end 83.402424 -230.231696)
		(width 0.0889)
		(layer "In2.Cu")
		(net "M_C_CPU1_SA_DQ<8>")
	)
	(segment
		(start 62.382908 -206.849472)
		(end 62.61354 -206.849472)
		(width 0.14478)
		(layer "In2.Cu")
		(net "M_C_CPU1_SA_DQ<8>")
	)
	(segment
		(start 60.630054 -206.62011)
		(end 62.153546 -206.62011)
		(width 0.14478)
		(layer "In2.Cu")
		(net "M_C_CPU1_SA_DQ<8>")
	)
	(segment
		(start 78.694026 -225.367088)
		(end 78.735936 -225.391472)
		(width 0.0889)
		(layer "In2.Cu")
		(net "M_C_CPU1_SA_DQ<8>")
	)
	(segment
		(start 66.26733 -209.725514)
		(end 66.430398 -209.888582)
		(width 0.14478)
		(layer "In2.Cu")
		(net "M_C_CPU1_SA_DQ<8>")
	)
	(segment
		(start 64.97574 -209.211672)
		(end 65.249298 -208.938114)
		(width 0.14478)
		(layer "In2.Cu")
		(net "M_C_CPU1_SA_DQ<8>")
	)
	(segment
		(start 64.461898 -208.150714)
		(end 64.69253 -208.150714)
		(width 0.14478)
		(layer "In2.Cu")
		(net "M_C_CPU1_SA_DQ<8>")
	)
	(segment
		(start 81.879694 -230.231696)
		(end 81.888076 -230.22687)
		(width 0.0889)
		(layer "In2.Cu")
		(net "M_C_CPU1_SA_DQ<8>")
	)
	(segment
		(start 65.36944 -209.605372)
		(end 65.36944 -209.836004)
		(width 0.14478)
		(layer "In2.Cu")
		(net "M_C_CPU1_SA_DQ<8>")
	)
	(segment
		(start 62.153546 -206.62011)
		(end 62.382908 -206.849472)
		(width 0.14478)
		(layer "In2.Cu")
		(net "M_C_CPU1_SA_DQ<8>")
	)
	(segment
		(start 75.849226 -219.795344)
		(end 75.849226 -221.687644)
		(width 0.14478)
		(layer "In2.Cu")
		(net "M_C_CPU1_SA_DQ<8>")
	)
	(segment
		(start 44.340018 -206.685388)
		(end 44.76496 -207.11033)
		(width 0.14478)
		(layer "In2.Cu")
		(net "M_C_CPU1_SA_DQ<8>")
	)
	(segment
		(start 63.40094 -207.636872)
		(end 63.674498 -207.363314)
		(width 0.14478)
		(layer "In2.Cu")
		(net "M_C_CPU1_SA_DQ<8>")
	)
	(segment
		(start 66.4972 -210.963764)
		(end 67.017646 -210.963764)
		(width 0.14478)
		(layer "In2.Cu")
		(net "M_C_CPU1_SA_DQ<8>")
	)
	(segment
		(start 53.102764 -206.260446)
		(end 53.952648 -207.11033)
		(width 0.14478)
		(layer "In2.Cu")
		(net "M_C_CPU1_SA_DQ<8>")
	)
	(segment
		(start 62.61354 -206.849472)
		(end 62.887098 -206.575914)
		(width 0.14478)
		(layer "In2.Cu")
		(net "M_C_CPU1_SA_DQ<8>")
	)
	(segment
		(start 82.453988 -230.22687)
		(end 82.46237 -230.231696)
		(width 0.0889)
		(layer "In2.Cu")
		(net "M_C_CPU1_SA_DQ<8>")
	)
	(segment
		(start 79.164434 -226.17557)
		(end 79.197962 -226.195128)
		(width 0.0889)
		(layer "In2.Cu")
		(net "M_C_CPU1_SA_DQ<8>")
	)
	(segment
		(start 64.068198 -207.526382)
		(end 64.068198 -207.757014)
		(width 0.14478)
		(layer "In2.Cu")
		(net "M_C_CPU1_SA_DQ<8>")
	)
	(segment
		(start 78.22438 -224.556066)
		(end 78.26629 -224.58045)
		(width 0.0889)
		(layer "In2.Cu")
		(net "M_C_CPU1_SA_DQ<8>")
	)
	(segment
		(start 63.00724 -207.243172)
		(end 63.00724 -207.473804)
		(width 0.14478)
		(layer "In2.Cu")
		(net "M_C_CPU1_SA_DQ<8>")
	)
	(segment
		(start 63.957708 -208.424272)
		(end 64.18834 -208.424272)
		(width 0.14478)
		(layer "In2.Cu")
		(net "M_C_CPU1_SA_DQ<8>")
	)
	(segment
		(start 94.052644 -230.253032)
		(end 94.074996 -230.16972)
		(width 0.0889)
		(layer "In2.Cu")
		(net "M_C_CPU1_SA_DQ<8>")
	)
	(segment
		(start 78.184756 -224.533206)
		(end 78.22438 -224.556066)
		(width 0.0889)
		(layer "In2.Cu")
		(net "M_C_CPU1_SA_DQ<8>")
	)
	(segment
		(start 79.63408 -226.986592)
		(end 79.676498 -227.01123)
		(width 0.0889)
		(layer "In2.Cu")
		(net "M_C_CPU1_SA_DQ<8>")
	)
	(segment
		(start 66.430398 -210.119214)
		(end 66.15684 -210.392772)
		(width 0.14478)
		(layer "In2.Cu")
		(net "M_C_CPU1_SA_DQ<8>")
	)
	(segment
		(start 66.15684 -210.623404)
		(end 66.4972 -210.963764)
		(width 0.14478)
		(layer "In2.Cu")
		(net "M_C_CPU1_SA_DQ<8>")
	)
	(segment
		(start 63.79464 -208.261204)
		(end 63.957708 -208.424272)
		(width 0.14478)
		(layer "In2.Cu")
		(net "M_C_CPU1_SA_DQ<8>")
	)
	(segment
		(start 85.639656 -230.231696)
		(end 85.648038 -230.22687)
		(width 0.0889)
		(layer "In2.Cu")
		(net "M_C_CPU1_SA_DQ<8>")
	)
	(segment
		(start 64.18834 -208.424272)
		(end 64.461898 -208.150714)
		(width 0.14478)
		(layer "In2.Cu")
		(net "M_C_CPU1_SA_DQ<8>")
	)
	(segment
		(start 64.69253 -208.150714)
		(end 64.855598 -208.313782)
		(width 0.14478)
		(layer "In2.Cu")
		(net "M_C_CPU1_SA_DQ<8>")
	)
	(segment
		(start 67.017646 -210.963764)
		(end 75.849226 -219.795344)
		(width 0.14478)
		(layer "In2.Cu")
		(net "M_C_CPU1_SA_DQ<8>")
	)
	(segment
		(start 81.044034 -229.416864)
		(end 81.08315 -229.439724)
		(width 0.0889)
		(layer "In2.Cu")
		(net "M_C_CPU1_SA_DQ<8>")
	)
	(segment
		(start 78.03642 -224.20961)
		(end 78.03642 -224.234502)
		(width 0.0889)
		(layer "In2.Cu")
		(net "M_C_CPU1_SA_DQ<8>")
	)
	(segment
		(start 65.642998 -209.101182)
		(end 65.642998 -209.331814)
		(width 0.14478)
		(layer "In2.Cu")
		(net "M_C_CPU1_SA_DQ<8>")
	)
	(segment
		(start 65.76314 -209.999072)
		(end 66.036698 -209.725514)
		(width 0.14478)
		(layer "In2.Cu")
		(net "M_C_CPU1_SA_DQ<8>")
	)
	(segment
		(start 66.036698 -209.725514)
		(end 66.26733 -209.725514)
		(width 0.14478)
		(layer "In2.Cu")
		(net "M_C_CPU1_SA_DQ<8>")
	)
	(segment
		(start 81.483454 -230.20909)
		(end 81.513934 -230.22687)
		(width 0.0889)
		(layer "In2.Cu")
		(net "M_C_CPU1_SA_DQ<8>")
	)
	(segment
		(start 79.600806 -226.967288)
		(end 79.63408 -226.986592)
		(width 0.0889)
		(layer "In2.Cu")
		(net "M_C_CPU1_SA_DQ<8>")
	)
	(segment
		(start 64.855598 -208.313782)
		(end 64.855598 -208.544414)
		(width 0.14478)
		(layer "In2.Cu")
		(net "M_C_CPU1_SA_DQ<8>")
	)
	(segment
		(start 64.745108 -209.211672)
		(end 64.97574 -209.211672)
		(width 0.14478)
		(layer "In2.Cu")
		(net "M_C_CPU1_SA_DQ<8>")
	)
	(segment
		(start 66.430398 -209.888582)
		(end 66.430398 -210.119214)
		(width 0.14478)
		(layer "In2.Cu")
		(net "M_C_CPU1_SA_DQ<8>")
	)
	(segment
		(start 91.85402 -230.22687)
		(end 91.862402 -230.231696)
		(width 0.0889)
		(layer "In2.Cu")
		(net "M_C_CPU1_SA_DQ<8>")
	)
	(segment
		(start 80.10398 -227.797106)
		(end 80.143096 -227.819966)
		(width 0.0889)
		(layer "In2.Cu")
		(net "M_C_CPU1_SA_DQ<8>")
	)
	(segment
		(start 88.094058 -230.22687)
		(end 88.10244 -230.231696)
		(width 0.0889)
		(layer "In2.Cu")
		(net "M_C_CPU1_SA_DQ<8>")
	)
	(segment
		(start 65.249298 -208.938114)
		(end 65.47993 -208.938114)
		(width 0.14478)
		(layer "In2.Cu")
		(net "M_C_CPU1_SA_DQ<8>")
	)
	(segment
		(start 63.90513 -207.363314)
		(end 64.068198 -207.526382)
		(width 0.14478)
		(layer "In2.Cu")
		(net "M_C_CPU1_SA_DQ<8>")
	)
	(segment
		(start 62.887098 -206.575914)
		(end 63.11773 -206.575914)
		(width 0.14478)
		(layer "In2.Cu")
		(net "M_C_CPU1_SA_DQ<8>")
	)
	(segment
		(start 64.068198 -207.757014)
		(end 63.79464 -208.030572)
		(width 0.14478)
		(layer "In2.Cu")
		(net "M_C_CPU1_SA_DQ<8>")
	)
	(segment
		(start 77.507846 -223.346264)
		(end 77.507846 -223.483424)
		(width 0.0889)
		(layer "In2.Cu")
		(net "M_C_CPU1_SA_DQ<8>")
	)
	(segment
		(start 80.0735 -227.779326)
		(end 80.10398 -227.797106)
		(width 0.0889)
		(layer "In2.Cu")
		(net "M_C_CPU1_SA_DQ<8>")
	)
	(arc
		(start 82.82813 -230.22687)
		(mid 83.111086 -230.150727)
		(end 83.394042 -230.22687)
		(width 0.0889)
		(layer "In2.Cu")
		(net "M_C_CPU1_SA_DQ<8>")
	)
	(arc
		(start 93.167962 -230.22687)
		(mid 93.450918 -230.150727)
		(end 93.733874 -230.22687)
		(width 0.0889)
		(layer "In2.Cu")
		(net "M_C_CPU1_SA_DQ<8>")
	)
	(arc
		(start 89.408 -230.22687)
		(mid 89.690956 -230.150727)
		(end 89.973912 -230.22687)
		(width 0.0889)
		(layer "In2.Cu")
		(net "M_C_CPU1_SA_DQ<8>")
	)
	(arc
		(start 78.976728 -225.853498)
		(mid 79.017809 -226.023622)
		(end 79.131668 -226.15652)
		(width 0.0889)
		(layer "In2.Cu")
		(net "M_C_CPU1_SA_DQ<8>")
	)
	(arc
		(start 80.386428 -228.284532)
		(mid 80.427683 -228.455503)
		(end 80.542384 -228.588824)
		(width 0.0889)
		(layer "In2.Cu")
		(net "M_C_CPU1_SA_DQ<8>")
	)
	(arc
		(start 81.513934 -230.22687)
		(mid 81.696185 -230.27722)
		(end 81.879694 -230.231696)
		(width 0.0889)
		(layer "In2.Cu")
		(net "M_C_CPU1_SA_DQ<8>")
	)
	(arc
		(start 91.862402 -230.231696)
		(mid 92.04591 -230.27719)
		(end 92.228162 -230.22687)
		(width 0.0889)
		(layer "In2.Cu")
		(net "M_C_CPU1_SA_DQ<8>")
	)
	(arc
		(start 83.402424 -230.231696)
		(mid 83.585932 -230.27719)
		(end 83.768184 -230.22687)
		(width 0.0889)
		(layer "In2.Cu")
		(net "M_C_CPU1_SA_DQ<8>")
	)
	(arc
		(start 84.707984 -230.22687)
		(mid 84.99094 -230.150727)
		(end 85.273896 -230.22687)
		(width 0.0889)
		(layer "In2.Cu")
		(net "M_C_CPU1_SA_DQ<8>")
	)
	(arc
		(start 93.733874 -230.22687)
		(mid 93.890312 -230.275841)
		(end 94.052644 -230.253032)
		(width 0.0889)
		(layer "In2.Cu")
		(net "M_C_CPU1_SA_DQ<8>")
	)
	(arc
		(start 87.528146 -230.22687)
		(mid 87.811102 -230.150727)
		(end 88.094058 -230.22687)
		(width 0.0889)
		(layer "In2.Cu")
		(net "M_C_CPU1_SA_DQ<8>")
	)
	(arc
		(start 88.4682 -230.22687)
		(mid 88.751156 -230.150727)
		(end 89.034112 -230.22687)
		(width 0.0889)
		(layer "In2.Cu")
		(net "M_C_CPU1_SA_DQ<8>")
	)
	(arc
		(start 78.03642 -224.234502)
		(mid 78.075547 -224.401255)
		(end 78.184756 -224.533206)
		(width 0.0889)
		(layer "In2.Cu")
		(net "M_C_CPU1_SA_DQ<8>")
	)
	(arc
		(start 89.973912 -230.22687)
		(mid 90.156163 -230.27722)
		(end 90.339672 -230.231696)
		(width 0.0889)
		(layer "In2.Cu")
		(net "M_C_CPU1_SA_DQ<8>")
	)
	(arc
		(start 79.916528 -227.474272)
		(mid 79.958 -227.645859)
		(end 80.0735 -227.779326)
		(width 0.0889)
		(layer "In2.Cu")
		(net "M_C_CPU1_SA_DQ<8>")
	)
	(arc
		(start 79.197962 -226.195128)
		(mid 79.380783 -226.398684)
		(end 79.446628 -226.664266)
		(width 0.0889)
		(layer "In2.Cu")
		(net "M_C_CPU1_SA_DQ<8>")
	)
	(arc
		(start 90.348054 -230.22687)
		(mid 90.63101 -230.150727)
		(end 90.913966 -230.22687)
		(width 0.0889)
		(layer "In2.Cu")
		(net "M_C_CPU1_SA_DQ<8>")
	)
	(arc
		(start 92.228162 -230.22687)
		(mid 92.511118 -230.150727)
		(end 92.794074 -230.22687)
		(width 0.0889)
		(layer "In2.Cu")
		(net "M_C_CPU1_SA_DQ<8>")
	)
	(arc
		(start 80.143096 -227.819966)
		(mid 80.321909 -228.022316)
		(end 80.386428 -228.284532)
		(width 0.0889)
		(layer "In2.Cu")
		(net "M_C_CPU1_SA_DQ<8>")
	)
	(arc
		(start 82.46237 -230.231696)
		(mid 82.645878 -230.27719)
		(end 82.82813 -230.22687)
		(width 0.0889)
		(layer "In2.Cu")
		(net "M_C_CPU1_SA_DQ<8>")
	)
	(arc
		(start 79.446628 -226.664266)
		(mid 79.487332 -226.834291)
		(end 79.600806 -226.967288)
		(width 0.0889)
		(layer "In2.Cu")
		(net "M_C_CPU1_SA_DQ<8>")
	)
	(arc
		(start 77.79512 -223.770698)
		(mid 77.972082 -223.959188)
		(end 78.03642 -224.20961)
		(width 0.0889)
		(layer "In2.Cu")
		(net "M_C_CPU1_SA_DQ<8>")
	)
	(arc
		(start 80.856328 -229.094538)
		(mid 80.89709 -229.264422)
		(end 81.010506 -229.397306)
		(width 0.0889)
		(layer "In2.Cu")
		(net "M_C_CPU1_SA_DQ<8>")
	)
	(arc
		(start 92.794074 -230.22687)
		(mid 92.981018 -230.277125)
		(end 93.167962 -230.22687)
		(width 0.0889)
		(layer "In2.Cu")
		(net "M_C_CPU1_SA_DQ<8>")
	)
	(arc
		(start 86.21395 -230.22687)
		(mid 86.396201 -230.27722)
		(end 86.57971 -230.231696)
		(width 0.0889)
		(layer "In2.Cu")
		(net "M_C_CPU1_SA_DQ<8>")
	)
	(arc
		(start 83.768184 -230.22687)
		(mid 84.05114 -230.150727)
		(end 84.334096 -230.22687)
		(width 0.0889)
		(layer "In2.Cu")
		(net "M_C_CPU1_SA_DQ<8>")
	)
	(arc
		(start 87.162386 -230.231696)
		(mid 87.345894 -230.27719)
		(end 87.528146 -230.22687)
		(width 0.0889)
		(layer "In2.Cu")
		(net "M_C_CPU1_SA_DQ<8>")
	)
	(arc
		(start 90.922348 -230.231696)
		(mid 91.105856 -230.27719)
		(end 91.288108 -230.22687)
		(width 0.0889)
		(layer "In2.Cu")
		(net "M_C_CPU1_SA_DQ<8>")
	)
	(arc
		(start 86.588092 -230.22687)
		(mid 86.871048 -230.150727)
		(end 87.154004 -230.22687)
		(width 0.0889)
		(layer "In2.Cu")
		(net "M_C_CPU1_SA_DQ<8>")
	)
	(arc
		(start 88.10244 -230.231696)
		(mid 88.285948 -230.27719)
		(end 88.4682 -230.22687)
		(width 0.0889)
		(layer "In2.Cu")
		(net "M_C_CPU1_SA_DQ<8>")
	)
	(arc
		(start 78.735936 -225.391472)
		(mid 78.912683 -225.593114)
		(end 78.976728 -225.853498)
		(width 0.0889)
		(layer "In2.Cu")
		(net "M_C_CPU1_SA_DQ<8>")
	)
	(arc
		(start 89.034112 -230.22687)
		(mid 89.221056 -230.277125)
		(end 89.408 -230.22687)
		(width 0.0889)
		(layer "In2.Cu")
		(net "M_C_CPU1_SA_DQ<8>")
	)
	(arc
		(start 81.888076 -230.22687)
		(mid 82.171032 -230.150727)
		(end 82.453988 -230.22687)
		(width 0.0889)
		(layer "In2.Cu")
		(net "M_C_CPU1_SA_DQ<8>")
	)
	(arc
		(start 84.334096 -230.22687)
		(mid 84.52104 -230.277125)
		(end 84.707984 -230.22687)
		(width 0.0889)
		(layer "In2.Cu")
		(net "M_C_CPU1_SA_DQ<8>")
	)
	(arc
		(start 81.326482 -229.90429)
		(mid 81.368031 -230.075712)
		(end 81.483454 -230.20909)
		(width 0.0889)
		(layer "In2.Cu")
		(net "M_C_CPU1_SA_DQ<8>")
	)
	(arc
		(start 78.506574 -225.044)
		(mid 78.548297 -225.216268)
		(end 78.664562 -225.35007)
		(width 0.0889)
		(layer "In2.Cu")
		(net "M_C_CPU1_SA_DQ<8>")
	)
	(arc
		(start 85.273896 -230.22687)
		(mid 85.456147 -230.27722)
		(end 85.639656 -230.231696)
		(width 0.0889)
		(layer "In2.Cu")
		(net "M_C_CPU1_SA_DQ<8>")
	)
	(arc
		(start 81.08315 -229.439724)
		(mid 81.261963 -229.642074)
		(end 81.326482 -229.90429)
		(width 0.0889)
		(layer "In2.Cu")
		(net "M_C_CPU1_SA_DQ<8>")
	)
	(arc
		(start 91.288108 -230.22687)
		(mid 91.571064 -230.150727)
		(end 91.85402 -230.22687)
		(width 0.0889)
		(layer "In2.Cu")
		(net "M_C_CPU1_SA_DQ<8>")
	)
	(arc
		(start 78.26629 -224.58045)
		(mid 78.443188 -224.782801)
		(end 78.506574 -225.044)
		(width 0.0889)
		(layer "In2.Cu")
		(net "M_C_CPU1_SA_DQ<8>")
	)
	(arc
		(start 80.610456 -228.628194)
		(mid 80.791108 -228.830939)
		(end 80.856328 -229.094538)
		(width 0.0889)
		(layer "In2.Cu")
		(net "M_C_CPU1_SA_DQ<8>")
	)
	(arc
		(start 79.676498 -227.01123)
		(mid 79.853126 -227.213405)
		(end 79.916528 -227.474272)
		(width 0.0889)
		(layer "In2.Cu")
		(net "M_C_CPU1_SA_DQ<8>")
	)
	(arc
		(start 85.648038 -230.22687)
		(mid 85.930994 -230.150727)
		(end 86.21395 -230.22687)
		(width 0.0889)
		(layer "In2.Cu")
		(net "M_C_CPU1_SA_DQ<8>")
	)
	(segment
		(start 96.267778 -230.170228)
		(end 95.800926 -229.90429)
		(width 0.10668)
		(layer "F.Cu")
		(net "M_C_CPU1_SA_DQ<7>")
	)
	(segment
		(start 42.800524 -206.260446)
		(end 49.428146 -206.260446)
		(width 0.14478)
		(layer "In2.Cu")
		(net "M_C_CPU1_SA_DQ<7>")
	)
	(segment
		(start 42.637456 -205.379574)
		(end 42.637456 -206.097378)
		(width 0.14478)
		(layer "In2.Cu")
		(net "M_C_CPU1_SA_DQ<7>")
	)
	(segment
		(start 95.039688 -229.577138)
		(end 95.04807 -229.581964)
		(width 0.0889)
		(layer "In2.Cu")
		(net "M_C_CPU1_SA_DQ<7>")
	)
	(segment
		(start 42.080942 -206.097378)
		(end 42.080942 -205.379574)
		(width 0.14478)
		(layer "In2.Cu")
		(net "M_C_CPU1_SA_DQ<7>")
	)
	(segment
		(start 81.37906 -228.749098)
		(end 81.418176 -228.771958)
		(width 0.0889)
		(layer "In2.Cu")
		(net "M_C_CPU1_SA_DQ<7>")
	)
	(segment
		(start 56.950864 -206.260192)
		(end 57.800748 -205.410308)
		(width 0.14478)
		(layer "In2.Cu")
		(net "M_C_CPU1_SA_DQ<7>")
	)
	(segment
		(start 42.24401 -205.216506)
		(end 42.474388 -205.216506)
		(width 0.14478)
		(layer "In2.Cu")
		(net "M_C_CPU1_SA_DQ<7>")
	)
	(segment
		(start 87.154004 -229.581964)
		(end 87.162386 -229.577138)
		(width 0.0889)
		(layer "In2.Cu")
		(net "M_C_CPU1_SA_DQ<7>")
	)
	(segment
		(start 82.453988 -229.581964)
		(end 82.46237 -229.577138)
		(width 0.0889)
		(layer "In2.Cu")
		(net "M_C_CPU1_SA_DQ<7>")
	)
	(segment
		(start 79.068168 -224.72269)
		(end 79.104236 -224.743518)
		(width 0.0889)
		(layer "In2.Cu")
		(net "M_C_CPU1_SA_DQ<7>")
	)
	(segment
		(start 90.913966 -229.581964)
		(end 90.922348 -229.577138)
		(width 0.0889)
		(layer "In2.Cu")
		(net "M_C_CPU1_SA_DQ<7>")
	)
	(segment
		(start 81.84896 -229.559104)
		(end 81.888076 -229.581964)
		(width 0.0889)
		(layer "In2.Cu")
		(net "M_C_CPU1_SA_DQ<7>")
	)
	(segment
		(start 94.099634 -229.577138)
		(end 94.108016 -229.581964)
		(width 0.0889)
		(layer "In2.Cu")
		(net "M_C_CPU1_SA_DQ<7>")
	)
	(segment
		(start 77.587348 -222.630746)
		(end 77.939138 -222.982536)
		(width 0.0889)
		(layer "In2.Cu")
		(net "M_C_CPU1_SA_DQ<7>")
	)
	(segment
		(start 53.102764 -205.410308)
		(end 53.952648 -206.260192)
		(width 0.14478)
		(layer "In2.Cu")
		(net "M_C_CPU1_SA_DQ<7>")
	)
	(segment
		(start 91.85402 -229.581964)
		(end 91.862402 -229.577138)
		(width 0.0889)
		(layer "In2.Cu")
		(net "M_C_CPU1_SA_DQ<7>")
	)
	(segment
		(start 81.418176 -228.771958)
		(end 81.448656 -228.789738)
		(width 0.0889)
		(layer "In2.Cu")
		(net "M_C_CPU1_SA_DQ<7>")
	)
	(segment
		(start 79.9719 -226.320858)
		(end 80.008222 -226.34194)
		(width 0.0889)
		(layer "In2.Cu")
		(net "M_C_CPU1_SA_DQ<7>")
	)
	(segment
		(start 57.800748 -205.410308)
		(end 60.248546 -205.410308)
		(width 0.14478)
		(layer "In2.Cu")
		(net "M_C_CPU1_SA_DQ<7>")
	)
	(segment
		(start 40.665146 -206.260446)
		(end 41.917874 -206.260446)
		(width 0.14478)
		(layer "In2.Cu")
		(net "M_C_CPU1_SA_DQ<7>")
	)
	(segment
		(start 76.405486 -219.56141)
		(end 76.405486 -221.448884)
		(width 0.14478)
		(layer "In2.Cu")
		(net "M_C_CPU1_SA_DQ<7>")
	)
	(segment
		(start 56.950864 -206.260446)
		(end 56.950864 -206.260192)
		(width 0.14478)
		(layer "In2.Cu")
		(net "M_C_CPU1_SA_DQ<7>")
	)
	(segment
		(start 63.320676 -205.99146)
		(end 67.043046 -209.71383)
		(width 0.14478)
		(layer "In2.Cu")
		(net "M_C_CPU1_SA_DQ<7>")
	)
	(segment
		(start 80.008222 -226.34194)
		(end 80.038702 -226.35972)
		(width 0.0889)
		(layer "In2.Cu")
		(net "M_C_CPU1_SA_DQ<7>")
	)
	(segment
		(start 53.952648 -206.260192)
		(end 53.952648 -206.260446)
		(width 0.14478)
		(layer "In2.Cu")
		(net "M_C_CPU1_SA_DQ<7>")
	)
	(segment
		(start 80.948022 -227.961952)
		(end 80.979772 -227.98024)
		(width 0.0889)
		(layer "In2.Cu")
		(net "M_C_CPU1_SA_DQ<7>")
	)
	(segment
		(start 42.474388 -205.216506)
		(end 42.637456 -205.379574)
		(width 0.14478)
		(layer "In2.Cu")
		(net "M_C_CPU1_SA_DQ<7>")
	)
	(segment
		(start 86.57971 -229.577138)
		(end 86.588092 -229.581964)
		(width 0.0889)
		(layer "In2.Cu")
		(net "M_C_CPU1_SA_DQ<7>")
	)
	(segment
		(start 80.439006 -227.129086)
		(end 80.478122 -227.151946)
		(width 0.0889)
		(layer "In2.Cu")
		(net "M_C_CPU1_SA_DQ<7>")
	)
	(segment
		(start 78.56474 -223.892618)
		(end 78.598014 -223.911922)
		(width 0.0889)
		(layer "In2.Cu")
		(net "M_C_CPU1_SA_DQ<7>")
	)
	(segment
		(start 60.248546 -205.410308)
		(end 60.829698 -205.99146)
		(width 0.14478)
		(layer "In2.Cu")
		(net "M_C_CPU1_SA_DQ<7>")
	)
	(segment
		(start 60.829698 -205.99146)
		(end 63.320676 -205.99146)
		(width 0.14478)
		(layer "In2.Cu")
		(net "M_C_CPU1_SA_DQ<7>")
	)
	(segment
		(start 49.428146 -206.260446)
		(end 50.278284 -205.410308)
		(width 0.14478)
		(layer "In2.Cu")
		(net "M_C_CPU1_SA_DQ<7>")
	)
	(segment
		(start 79.504032 -225.51263)
		(end 79.538576 -225.532696)
		(width 0.0889)
		(layer "In2.Cu")
		(net "M_C_CPU1_SA_DQ<7>")
	)
	(segment
		(start 80.9117 -227.94087)
		(end 80.948022 -227.961952)
		(width 0.0889)
		(layer "In2.Cu")
		(net "M_C_CPU1_SA_DQ<7>")
	)
	(segment
		(start 83.394042 -229.581964)
		(end 83.402424 -229.577138)
		(width 0.0889)
		(layer "In2.Cu")
		(net "M_C_CPU1_SA_DQ<7>")
	)
	(segment
		(start 40.23995 -205.83525)
		(end 40.665146 -206.260446)
		(width 0.14478)
		(layer "In2.Cu")
		(net "M_C_CPU1_SA_DQ<7>")
	)
	(segment
		(start 85.639656 -229.577138)
		(end 85.648038 -229.581964)
		(width 0.0889)
		(layer "In2.Cu")
		(net "M_C_CPU1_SA_DQ<7>")
	)
	(segment
		(start 95.647002 -229.63886)
		(end 95.800926 -229.90429)
		(width 0.0889)
		(layer "In2.Cu")
		(net "M_C_CPU1_SA_DQ<7>")
	)
	(segment
		(start 79.538576 -225.532696)
		(end 79.565754 -225.548444)
		(width 0.0889)
		(layer "In2.Cu")
		(net "M_C_CPU1_SA_DQ<7>")
	)
	(segment
		(start 95.551244 -229.61346)
		(end 95.647002 -229.63886)
		(width 0.0889)
		(layer "In2.Cu")
		(net "M_C_CPU1_SA_DQ<7>")
	)
	(segment
		(start 41.917874 -206.260446)
		(end 42.080942 -206.097378)
		(width 0.14478)
		(layer "In2.Cu")
		(net "M_C_CPU1_SA_DQ<7>")
	)
	(segment
		(start 78.598014 -223.911922)
		(end 78.631796 -223.93148)
		(width 0.0889)
		(layer "In2.Cu")
		(net "M_C_CPU1_SA_DQ<7>")
	)
	(segment
		(start 76.405486 -221.448884)
		(end 77.587348 -222.630746)
		(width 0.14478)
		(layer "In2.Cu")
		(net "M_C_CPU1_SA_DQ<7>")
	)
	(segment
		(start 42.080942 -205.379574)
		(end 42.24401 -205.216506)
		(width 0.14478)
		(layer "In2.Cu")
		(net "M_C_CPU1_SA_DQ<7>")
	)
	(segment
		(start 67.043046 -209.71383)
		(end 67.043046 -210.19897)
		(width 0.14478)
		(layer "In2.Cu")
		(net "M_C_CPU1_SA_DQ<7>")
	)
	(segment
		(start 88.094058 -229.581964)
		(end 88.10244 -229.577138)
		(width 0.0889)
		(layer "In2.Cu")
		(net "M_C_CPU1_SA_DQ<7>")
	)
	(segment
		(start 42.637456 -206.097378)
		(end 42.800524 -206.260446)
		(width 0.14478)
		(layer "In2.Cu")
		(net "M_C_CPU1_SA_DQ<7>")
	)
	(segment
		(start 90.339672 -229.577138)
		(end 90.348054 -229.581964)
		(width 0.0889)
		(layer "In2.Cu")
		(net "M_C_CPU1_SA_DQ<7>")
	)
	(segment
		(start 78.009496 -223.03613)
		(end 78.130146 -223.105218)
		(width 0.0889)
		(layer "In2.Cu")
		(net "M_C_CPU1_SA_DQ<7>")
	)
	(segment
		(start 79.022448 -224.69602)
		(end 79.068168 -224.72269)
		(width 0.0889)
		(layer "In2.Cu")
		(net "M_C_CPU1_SA_DQ<7>")
	)
	(segment
		(start 67.043046 -210.19897)
		(end 76.405486 -219.56141)
		(width 0.14478)
		(layer "In2.Cu")
		(net "M_C_CPU1_SA_DQ<7>")
	)
	(segment
		(start 53.952648 -206.260446)
		(end 56.950864 -206.260446)
		(width 0.14478)
		(layer "In2.Cu")
		(net "M_C_CPU1_SA_DQ<7>")
	)
	(segment
		(start 50.278284 -205.410308)
		(end 53.102764 -205.410308)
		(width 0.14478)
		(layer "In2.Cu")
		(net "M_C_CPU1_SA_DQ<7>")
	)
	(segment
		(start 80.478122 -227.151946)
		(end 80.509872 -227.170234)
		(width 0.0889)
		(layer "In2.Cu")
		(net "M_C_CPU1_SA_DQ<7>")
	)
	(arc
		(start 84.334096 -229.581964)
		(mid 84.52104 -229.531675)
		(end 84.707984 -229.581964)
		(width 0.0889)
		(layer "In2.Cu")
		(net "M_C_CPU1_SA_DQ<7>")
	)
	(arc
		(start 93.733874 -229.581964)
		(mid 93.916125 -229.53158)
		(end 94.099634 -229.577138)
		(width 0.0889)
		(layer "In2.Cu")
		(net "M_C_CPU1_SA_DQ<7>")
	)
	(arc
		(start 80.195674 -226.66452)
		(mid 80.260189 -226.926739)
		(end 80.439006 -227.129086)
		(width 0.0889)
		(layer "In2.Cu")
		(net "M_C_CPU1_SA_DQ<7>")
	)
	(arc
		(start 89.408 -229.581964)
		(mid 89.690956 -229.658141)
		(end 89.973912 -229.581964)
		(width 0.0889)
		(layer "In2.Cu")
		(net "M_C_CPU1_SA_DQ<7>")
	)
	(arc
		(start 86.21395 -229.581964)
		(mid 86.396201 -229.53158)
		(end 86.57971 -229.577138)
		(width 0.0889)
		(layer "In2.Cu")
		(net "M_C_CPU1_SA_DQ<7>")
	)
	(arc
		(start 94.673928 -229.581964)
		(mid 94.856179 -229.53158)
		(end 95.039688 -229.577138)
		(width 0.0889)
		(layer "In2.Cu")
		(net "M_C_CPU1_SA_DQ<7>")
	)
	(arc
		(start 79.726028 -225.855276)
		(mid 79.791441 -226.118442)
		(end 79.9719 -226.320858)
		(width 0.0889)
		(layer "In2.Cu")
		(net "M_C_CPU1_SA_DQ<7>")
	)
	(arc
		(start 86.588092 -229.581964)
		(mid 86.871048 -229.658141)
		(end 87.154004 -229.581964)
		(width 0.0889)
		(layer "In2.Cu")
		(net "M_C_CPU1_SA_DQ<7>")
	)
	(arc
		(start 94.108016 -229.581964)
		(mid 94.390972 -229.658141)
		(end 94.673928 -229.581964)
		(width 0.0889)
		(layer "In2.Cu")
		(net "M_C_CPU1_SA_DQ<7>")
	)
	(arc
		(start 80.979772 -227.98024)
		(mid 81.094448 -228.113574)
		(end 81.135728 -228.284532)
		(width 0.0889)
		(layer "In2.Cu")
		(net "M_C_CPU1_SA_DQ<7>")
	)
	(arc
		(start 78.130146 -223.105218)
		(mid 78.266127 -223.240518)
		(end 78.316074 -223.425766)
		(width 0.0889)
		(layer "In2.Cu")
		(net "M_C_CPU1_SA_DQ<7>")
	)
	(arc
		(start 95.04807 -229.581964)
		(mid 95.29593 -229.657047)
		(end 95.551244 -229.61346)
		(width 0.0889)
		(layer "In2.Cu")
		(net "M_C_CPU1_SA_DQ<7>")
	)
	(arc
		(start 80.665828 -227.474526)
		(mid 80.731064 -227.738117)
		(end 80.9117 -227.94087)
		(width 0.0889)
		(layer "In2.Cu")
		(net "M_C_CPU1_SA_DQ<7>")
	)
	(arc
		(start 82.82813 -229.581964)
		(mid 83.111086 -229.658141)
		(end 83.394042 -229.581964)
		(width 0.0889)
		(layer "In2.Cu")
		(net "M_C_CPU1_SA_DQ<7>")
	)
	(arc
		(start 84.707984 -229.581964)
		(mid 84.99094 -229.658141)
		(end 85.273896 -229.581964)
		(width 0.0889)
		(layer "In2.Cu")
		(net "M_C_CPU1_SA_DQ<7>")
	)
	(arc
		(start 89.973912 -229.581964)
		(mid 90.156163 -229.53158)
		(end 90.339672 -229.577138)
		(width 0.0889)
		(layer "In2.Cu")
		(net "M_C_CPU1_SA_DQ<7>")
	)
	(arc
		(start 80.509872 -227.170234)
		(mid 80.624548 -227.303568)
		(end 80.665828 -227.474526)
		(width 0.0889)
		(layer "In2.Cu")
		(net "M_C_CPU1_SA_DQ<7>")
	)
	(arc
		(start 90.348054 -229.581964)
		(mid 90.63101 -229.658141)
		(end 90.913966 -229.581964)
		(width 0.0889)
		(layer "In2.Cu")
		(net "M_C_CPU1_SA_DQ<7>")
	)
	(arc
		(start 79.565754 -225.548444)
		(mid 79.683469 -225.682227)
		(end 79.726028 -225.855276)
		(width 0.0889)
		(layer "In2.Cu")
		(net "M_C_CPU1_SA_DQ<7>")
	)
	(arc
		(start 81.888076 -229.581964)
		(mid 82.171032 -229.658141)
		(end 82.453988 -229.581964)
		(width 0.0889)
		(layer "In2.Cu")
		(net "M_C_CPU1_SA_DQ<7>")
	)
	(arc
		(start 83.402424 -229.577138)
		(mid 83.585932 -229.531613)
		(end 83.768184 -229.581964)
		(width 0.0889)
		(layer "In2.Cu")
		(net "M_C_CPU1_SA_DQ<7>")
	)
	(arc
		(start 87.528146 -229.581964)
		(mid 87.811102 -229.658141)
		(end 88.094058 -229.581964)
		(width 0.0889)
		(layer "In2.Cu")
		(net "M_C_CPU1_SA_DQ<7>")
	)
	(arc
		(start 83.768184 -229.581964)
		(mid 84.05114 -229.658141)
		(end 84.334096 -229.581964)
		(width 0.0889)
		(layer "In2.Cu")
		(net "M_C_CPU1_SA_DQ<7>")
	)
	(arc
		(start 92.228162 -229.581964)
		(mid 92.511118 -229.658141)
		(end 92.794074 -229.581964)
		(width 0.0889)
		(layer "In2.Cu")
		(net "M_C_CPU1_SA_DQ<7>")
	)
	(arc
		(start 78.316074 -223.425766)
		(mid 78.3824 -223.690085)
		(end 78.56474 -223.892618)
		(width 0.0889)
		(layer "In2.Cu")
		(net "M_C_CPU1_SA_DQ<7>")
	)
	(arc
		(start 78.785974 -224.23501)
		(mid 78.84832 -224.494186)
		(end 79.022448 -224.69602)
		(width 0.0889)
		(layer "In2.Cu")
		(net "M_C_CPU1_SA_DQ<7>")
	)
	(arc
		(start 79.104236 -224.743518)
		(mid 79.215646 -224.876049)
		(end 79.25562 -225.044508)
		(width 0.0889)
		(layer "In2.Cu")
		(net "M_C_CPU1_SA_DQ<7>")
	)
	(arc
		(start 81.448656 -228.789738)
		(mid 81.564083 -228.923114)
		(end 81.605628 -229.094538)
		(width 0.0889)
		(layer "In2.Cu")
		(net "M_C_CPU1_SA_DQ<7>")
	)
	(arc
		(start 81.135728 -228.284532)
		(mid 81.200243 -228.546751)
		(end 81.37906 -228.749098)
		(width 0.0889)
		(layer "In2.Cu")
		(net "M_C_CPU1_SA_DQ<7>")
	)
	(arc
		(start 93.167962 -229.581964)
		(mid 93.450918 -229.658141)
		(end 93.733874 -229.581964)
		(width 0.0889)
		(layer "In2.Cu")
		(net "M_C_CPU1_SA_DQ<7>")
	)
	(arc
		(start 78.631796 -223.93148)
		(mid 78.745318 -224.064737)
		(end 78.785974 -224.23501)
		(width 0.0889)
		(layer "In2.Cu")
		(net "M_C_CPU1_SA_DQ<7>")
	)
	(arc
		(start 92.794074 -229.581964)
		(mid 92.981018 -229.531675)
		(end 93.167962 -229.581964)
		(width 0.0889)
		(layer "In2.Cu")
		(net "M_C_CPU1_SA_DQ<7>")
	)
	(arc
		(start 88.10244 -229.577138)
		(mid 88.285948 -229.531613)
		(end 88.4682 -229.581964)
		(width 0.0889)
		(layer "In2.Cu")
		(net "M_C_CPU1_SA_DQ<7>")
	)
	(arc
		(start 87.162386 -229.577138)
		(mid 87.345894 -229.531613)
		(end 87.528146 -229.581964)
		(width 0.0889)
		(layer "In2.Cu")
		(net "M_C_CPU1_SA_DQ<7>")
	)
	(arc
		(start 88.4682 -229.581964)
		(mid 88.751156 -229.658141)
		(end 89.034112 -229.581964)
		(width 0.0889)
		(layer "In2.Cu")
		(net "M_C_CPU1_SA_DQ<7>")
	)
	(arc
		(start 89.034112 -229.581964)
		(mid 89.221056 -229.531675)
		(end 89.408 -229.581964)
		(width 0.0889)
		(layer "In2.Cu")
		(net "M_C_CPU1_SA_DQ<7>")
	)
	(arc
		(start 77.939138 -222.982536)
		(mid 77.972547 -223.011654)
		(end 78.009496 -223.03613)
		(width 0.0889)
		(layer "In2.Cu")
		(net "M_C_CPU1_SA_DQ<7>")
	)
	(arc
		(start 91.288108 -229.581964)
		(mid 91.571064 -229.658141)
		(end 91.85402 -229.581964)
		(width 0.0889)
		(layer "In2.Cu")
		(net "M_C_CPU1_SA_DQ<7>")
	)
	(arc
		(start 81.605628 -229.094538)
		(mid 81.670143 -229.356757)
		(end 81.84896 -229.559104)
		(width 0.0889)
		(layer "In2.Cu")
		(net "M_C_CPU1_SA_DQ<7>")
	)
	(arc
		(start 91.862402 -229.577138)
		(mid 92.04591 -229.531613)
		(end 92.228162 -229.581964)
		(width 0.0889)
		(layer "In2.Cu")
		(net "M_C_CPU1_SA_DQ<7>")
	)
	(arc
		(start 85.273896 -229.581964)
		(mid 85.456147 -229.53158)
		(end 85.639656 -229.577138)
		(width 0.0889)
		(layer "In2.Cu")
		(net "M_C_CPU1_SA_DQ<7>")
	)
	(arc
		(start 82.46237 -229.577138)
		(mid 82.645878 -229.531613)
		(end 82.82813 -229.581964)
		(width 0.0889)
		(layer "In2.Cu")
		(net "M_C_CPU1_SA_DQ<7>")
	)
	(arc
		(start 90.922348 -229.577138)
		(mid 91.105856 -229.531613)
		(end 91.288108 -229.581964)
		(width 0.0889)
		(layer "In2.Cu")
		(net "M_C_CPU1_SA_DQ<7>")
	)
	(arc
		(start 79.25562 -225.044508)
		(mid 79.321561 -225.309495)
		(end 79.504032 -225.51263)
		(width 0.0889)
		(layer "In2.Cu")
		(net "M_C_CPU1_SA_DQ<7>")
	)
	(arc
		(start 85.648038 -229.581964)
		(mid 85.930994 -229.658141)
		(end 86.21395 -229.581964)
		(width 0.0889)
		(layer "In2.Cu")
		(net "M_C_CPU1_SA_DQ<7>")
	)
	(arc
		(start 80.038702 -226.35972)
		(mid 80.154129 -226.493096)
		(end 80.195674 -226.66452)
		(width 0.0889)
		(layer "In2.Cu")
		(net "M_C_CPU1_SA_DQ<7>")
	)
	(segment
		(start 94.857824 -229.360476)
		(end 94.390972 -229.094538)
		(width 0.10668)
		(layer "F.Cu")
		(net "M_C_CPU1_SA_DQ<6>")
	)
	(segment
		(start 81.418176 -227.151946)
		(end 81.448656 -227.169726)
		(width 0.0889)
		(layer "In2.Cu")
		(net "M_C_CPU1_SA_DQ<6>")
	)
	(segment
		(start 80.9117 -226.320858)
		(end 80.948022 -226.34194)
		(width 0.0889)
		(layer "In2.Cu")
		(net "M_C_CPU1_SA_DQ<6>")
	)
	(segment
		(start 82.321654 -228.750876)
		(end 82.357976 -228.771958)
		(width 0.0889)
		(layer "In2.Cu")
		(net "M_C_CPU1_SA_DQ<6>")
	)
	(segment
		(start 83.289648 -228.767132)
		(end 83.29803 -228.771958)
		(width 0.0889)
		(layer "In2.Cu")
		(net "M_C_CPU1_SA_DQ<6>")
	)
	(segment
		(start 81.84896 -227.939092)
		(end 81.888076 -227.961952)
		(width 0.0889)
		(layer "In2.Cu")
		(net "M_C_CPU1_SA_DQ<6>")
	)
	(segment
		(start 87.989664 -228.767132)
		(end 87.998046 -228.771958)
		(width 0.0889)
		(layer "In2.Cu")
		(net "M_C_CPU1_SA_DQ<6>")
	)
	(segment
		(start 81.888076 -227.961952)
		(end 81.919826 -227.98024)
		(width 0.0889)
		(layer "In2.Cu")
		(net "M_C_CPU1_SA_DQ<6>")
	)
	(segment
		(start 91.749626 -228.767132)
		(end 91.758008 -228.771958)
		(width 0.0889)
		(layer "In2.Cu")
		(net "M_C_CPU1_SA_DQ<6>")
	)
	(segment
		(start 77.352906 -221.100904)
		(end 78.086966 -221.834964)
		(width 0.14478)
		(layer "In2.Cu")
		(net "M_C_CPU1_SA_DQ<6>")
	)
	(segment
		(start 42.847006 -204.397356)
		(end 43.010074 -204.560424)
		(width 0.14478)
		(layer "In2.Cu")
		(net "M_C_CPU1_SA_DQ<6>")
	)
	(segment
		(start 78.086966 -221.834964)
		(end 78.479904 -222.227902)
		(width 0.0889)
		(layer "In2.Cu")
		(net "M_C_CPU1_SA_DQ<6>")
	)
	(segment
		(start 50.499264 -203.710286)
		(end 53.111654 -203.710286)
		(width 0.14478)
		(layer "In2.Cu")
		(net "M_C_CPU1_SA_DQ<6>")
	)
	(segment
		(start 79.03337 -223.081596)
		(end 79.068168 -223.101916)
		(width 0.0889)
		(layer "In2.Cu")
		(net "M_C_CPU1_SA_DQ<6>")
	)
	(segment
		(start 60.078874 -203.710286)
		(end 61.393832 -205.025244)
		(width 0.14478)
		(layer "In2.Cu")
		(net "M_C_CPU1_SA_DQ<6>")
	)
	(segment
		(start 58.193178 -203.710286)
		(end 60.078874 -203.710286)
		(width 0.14478)
		(layer "In2.Cu")
		(net "M_C_CPU1_SA_DQ<6>")
	)
	(segment
		(start 78.498446 -222.242126)
		(end 78.608174 -222.305626)
		(width 0.0889)
		(layer "In2.Cu")
		(net "M_C_CPU1_SA_DQ<6>")
	)
	(segment
		(start 88.929718 -228.767132)
		(end 88.9381 -228.771958)
		(width 0.0889)
		(layer "In2.Cu")
		(net "M_C_CPU1_SA_DQ<6>")
	)
	(segment
		(start 94.237048 -228.829108)
		(end 94.390972 -229.094538)
		(width 0.0889)
		(layer "In2.Cu")
		(net "M_C_CPU1_SA_DQ<6>")
	)
	(segment
		(start 93.263974 -228.771958)
		(end 93.272356 -228.767132)
		(width 0.0889)
		(layer "In2.Cu")
		(net "M_C_CPU1_SA_DQ<6>")
	)
	(segment
		(start 42.290492 -204.397356)
		(end 42.290492 -203.336652)
		(width 0.14478)
		(layer "In2.Cu")
		(net "M_C_CPU1_SA_DQ<6>")
	)
	(segment
		(start 61.393832 -205.025244)
		(end 63.79718 -205.025244)
		(width 0.14478)
		(layer "In2.Cu")
		(net "M_C_CPU1_SA_DQ<6>")
	)
	(segment
		(start 53.111654 -203.710286)
		(end 53.961792 -204.560424)
		(width 0.14478)
		(layer "In2.Cu")
		(net "M_C_CPU1_SA_DQ<6>")
	)
	(segment
		(start 42.127424 -204.560424)
		(end 42.290492 -204.397356)
		(width 0.14478)
		(layer "In2.Cu")
		(net "M_C_CPU1_SA_DQ<6>")
	)
	(segment
		(start 42.45356 -203.173584)
		(end 42.683938 -203.173584)
		(width 0.14478)
		(layer "In2.Cu")
		(net "M_C_CPU1_SA_DQ<6>")
	)
	(segment
		(start 42.290492 -203.336652)
		(end 42.45356 -203.173584)
		(width 0.14478)
		(layer "In2.Cu")
		(net "M_C_CPU1_SA_DQ<6>")
	)
	(segment
		(start 42.847006 -203.336652)
		(end 42.847006 -204.397356)
		(width 0.14478)
		(layer "In2.Cu")
		(net "M_C_CPU1_SA_DQ<6>")
	)
	(segment
		(start 68.010786 -209.869278)
		(end 77.352906 -219.211398)
		(width 0.14478)
		(layer "In2.Cu")
		(net "M_C_CPU1_SA_DQ<6>")
	)
	(segment
		(start 68.010786 -209.23885)
		(end 68.010786 -209.869278)
		(width 0.14478)
		(layer "In2.Cu")
		(net "M_C_CPU1_SA_DQ<6>")
	)
	(segment
		(start 94.141036 -228.803708)
		(end 94.237048 -228.829108)
		(width 0.0889)
		(layer "In2.Cu")
		(net "M_C_CPU1_SA_DQ<6>")
	)
	(segment
		(start 92.68968 -228.767132)
		(end 92.698062 -228.771958)
		(width 0.0889)
		(layer "In2.Cu")
		(net "M_C_CPU1_SA_DQ<6>")
	)
	(segment
		(start 79.538576 -223.911922)
		(end 79.56804 -223.92894)
		(width 0.0889)
		(layer "In2.Cu")
		(net "M_C_CPU1_SA_DQ<6>")
	)
	(segment
		(start 80.008222 -224.721928)
		(end 80.038702 -224.739708)
		(width 0.0889)
		(layer "In2.Cu")
		(net "M_C_CPU1_SA_DQ<6>")
	)
	(segment
		(start 80.948022 -226.34194)
		(end 80.979772 -226.360228)
		(width 0.0889)
		(layer "In2.Cu")
		(net "M_C_CPU1_SA_DQ<6>")
	)
	(segment
		(start 81.37906 -227.129086)
		(end 81.418176 -227.151946)
		(width 0.0889)
		(layer "In2.Cu")
		(net "M_C_CPU1_SA_DQ<6>")
	)
	(segment
		(start 43.010074 -204.560424)
		(end 49.649126 -204.560424)
		(width 0.14478)
		(layer "In2.Cu")
		(net "M_C_CPU1_SA_DQ<6>")
	)
	(segment
		(start 85.74405 -228.771958)
		(end 85.752432 -228.767132)
		(width 0.0889)
		(layer "In2.Cu")
		(net "M_C_CPU1_SA_DQ<6>")
	)
	(segment
		(start 42.683938 -203.173584)
		(end 42.847006 -203.336652)
		(width 0.14478)
		(layer "In2.Cu")
		(net "M_C_CPU1_SA_DQ<6>")
	)
	(segment
		(start 80.439006 -225.509074)
		(end 80.478122 -225.531934)
		(width 0.0889)
		(layer "In2.Cu")
		(net "M_C_CPU1_SA_DQ<6>")
	)
	(segment
		(start 84.803996 -228.771958)
		(end 84.812378 -228.767132)
		(width 0.0889)
		(layer "In2.Cu")
		(net "M_C_CPU1_SA_DQ<6>")
	)
	(segment
		(start 53.961792 -204.560424)
		(end 57.34304 -204.560424)
		(width 0.14478)
		(layer "In2.Cu")
		(net "M_C_CPU1_SA_DQ<6>")
	)
	(segment
		(start 89.504012 -228.771958)
		(end 89.512394 -228.767132)
		(width 0.0889)
		(layer "In2.Cu")
		(net "M_C_CPU1_SA_DQ<6>")
	)
	(segment
		(start 79.49819 -223.8883)
		(end 79.538576 -223.911922)
		(width 0.0889)
		(layer "In2.Cu")
		(net "M_C_CPU1_SA_DQ<6>")
	)
	(segment
		(start 57.34304 -204.560424)
		(end 58.193178 -203.710286)
		(width 0.14478)
		(layer "In2.Cu")
		(net "M_C_CPU1_SA_DQ<6>")
	)
	(segment
		(start 84.229702 -228.767132)
		(end 84.238084 -228.771958)
		(width 0.0889)
		(layer "In2.Cu")
		(net "M_C_CPU1_SA_DQ<6>")
	)
	(segment
		(start 79.068168 -223.101916)
		(end 79.100934 -223.120966)
		(width 0.0889)
		(layer "In2.Cu")
		(net "M_C_CPU1_SA_DQ<6>")
	)
	(segment
		(start 80.478122 -225.531934)
		(end 80.509872 -225.550222)
		(width 0.0889)
		(layer "In2.Cu")
		(net "M_C_CPU1_SA_DQ<6>")
	)
	(segment
		(start 40.665146 -204.560424)
		(end 42.127424 -204.560424)
		(width 0.14478)
		(layer "In2.Cu")
		(net "M_C_CPU1_SA_DQ<6>")
	)
	(segment
		(start 49.649126 -204.560424)
		(end 50.499264 -203.710286)
		(width 0.14478)
		(layer "In2.Cu")
		(net "M_C_CPU1_SA_DQ<6>")
	)
	(segment
		(start 63.79718 -205.025244)
		(end 68.010786 -209.23885)
		(width 0.14478)
		(layer "In2.Cu")
		(net "M_C_CPU1_SA_DQ<6>")
	)
	(segment
		(start 40.23995 -204.135228)
		(end 40.665146 -204.560424)
		(width 0.14478)
		(layer "In2.Cu")
		(net "M_C_CPU1_SA_DQ<6>")
	)
	(segment
		(start 79.9719 -224.700846)
		(end 80.008222 -224.721928)
		(width 0.0889)
		(layer "In2.Cu")
		(net "M_C_CPU1_SA_DQ<6>")
	)
	(segment
		(start 77.352906 -219.211398)
		(end 77.352906 -221.100904)
		(width 0.14478)
		(layer "In2.Cu")
		(net "M_C_CPU1_SA_DQ<6>")
	)
	(arc
		(start 87.057992 -228.771958)
		(mid 87.340948 -228.848135)
		(end 87.623904 -228.771958)
		(width 0.0889)
		(layer "In2.Cu")
		(net "M_C_CPU1_SA_DQ<6>")
	)
	(arc
		(start 87.998046 -228.771958)
		(mid 88.281002 -228.848135)
		(end 88.563958 -228.771958)
		(width 0.0889)
		(layer "In2.Cu")
		(net "M_C_CPU1_SA_DQ<6>")
	)
	(arc
		(start 83.863942 -228.771958)
		(mid 84.046193 -228.721608)
		(end 84.229702 -228.767132)
		(width 0.0889)
		(layer "In2.Cu")
		(net "M_C_CPU1_SA_DQ<6>")
	)
	(arc
		(start 88.563958 -228.771958)
		(mid 88.746209 -228.721608)
		(end 88.929718 -228.767132)
		(width 0.0889)
		(layer "In2.Cu")
		(net "M_C_CPU1_SA_DQ<6>")
	)
	(arc
		(start 79.56804 -223.92894)
		(mid 79.684221 -224.062499)
		(end 79.726028 -224.234502)
		(width 0.0889)
		(layer "In2.Cu")
		(net "M_C_CPU1_SA_DQ<6>")
	)
	(arc
		(start 91.758008 -228.771958)
		(mid 92.040964 -228.848135)
		(end 92.32392 -228.771958)
		(width 0.0889)
		(layer "In2.Cu")
		(net "M_C_CPU1_SA_DQ<6>")
	)
	(arc
		(start 84.238084 -228.771958)
		(mid 84.52104 -228.848135)
		(end 84.803996 -228.771958)
		(width 0.0889)
		(layer "In2.Cu")
		(net "M_C_CPU1_SA_DQ<6>")
	)
	(arc
		(start 79.100934 -223.120966)
		(mid 79.214863 -223.254113)
		(end 79.255874 -223.424496)
		(width 0.0889)
		(layer "In2.Cu")
		(net "M_C_CPU1_SA_DQ<6>")
	)
	(arc
		(start 78.479904 -222.227902)
		(mid 78.488707 -222.235625)
		(end 78.498446 -222.242126)
		(width 0.0889)
		(layer "In2.Cu")
		(net "M_C_CPU1_SA_DQ<6>")
	)
	(arc
		(start 91.383866 -228.771958)
		(mid 91.566117 -228.721608)
		(end 91.749626 -228.767132)
		(width 0.0889)
		(layer "In2.Cu")
		(net "M_C_CPU1_SA_DQ<6>")
	)
	(arc
		(start 82.923888 -228.771958)
		(mid 83.106139 -228.721608)
		(end 83.289648 -228.767132)
		(width 0.0889)
		(layer "In2.Cu")
		(net "M_C_CPU1_SA_DQ<6>")
	)
	(arc
		(start 85.752432 -228.767132)
		(mid 85.93594 -228.721638)
		(end 86.118192 -228.771958)
		(width 0.0889)
		(layer "In2.Cu")
		(net "M_C_CPU1_SA_DQ<6>")
	)
	(arc
		(start 81.605628 -227.474526)
		(mid 81.670143 -227.736745)
		(end 81.84896 -227.939092)
		(width 0.0889)
		(layer "In2.Cu")
		(net "M_C_CPU1_SA_DQ<6>")
	)
	(arc
		(start 79.255874 -223.424496)
		(mid 79.320167 -223.686101)
		(end 79.49819 -223.8883)
		(width 0.0889)
		(layer "In2.Cu")
		(net "M_C_CPU1_SA_DQ<6>")
	)
	(arc
		(start 93.272356 -228.767132)
		(mid 93.455864 -228.721638)
		(end 93.638116 -228.771958)
		(width 0.0889)
		(layer "In2.Cu")
		(net "M_C_CPU1_SA_DQ<6>")
	)
	(arc
		(start 85.178138 -228.771958)
		(mid 85.461094 -228.848135)
		(end 85.74405 -228.771958)
		(width 0.0889)
		(layer "In2.Cu")
		(net "M_C_CPU1_SA_DQ<6>")
	)
	(arc
		(start 90.444066 -228.771958)
		(mid 90.63101 -228.721703)
		(end 90.817954 -228.771958)
		(width 0.0889)
		(layer "In2.Cu")
		(net "M_C_CPU1_SA_DQ<6>")
	)
	(arc
		(start 92.698062 -228.771958)
		(mid 92.981018 -228.848135)
		(end 93.263974 -228.771958)
		(width 0.0889)
		(layer "In2.Cu")
		(net "M_C_CPU1_SA_DQ<6>")
	)
	(arc
		(start 86.684104 -228.771958)
		(mid 86.871048 -228.721703)
		(end 87.057992 -228.771958)
		(width 0.0889)
		(layer "In2.Cu")
		(net "M_C_CPU1_SA_DQ<6>")
	)
	(arc
		(start 80.979772 -226.360228)
		(mid 81.094448 -226.493562)
		(end 81.135728 -226.66452)
		(width 0.0889)
		(layer "In2.Cu")
		(net "M_C_CPU1_SA_DQ<6>")
	)
	(arc
		(start 80.509872 -225.550222)
		(mid 80.624548 -225.683556)
		(end 80.665828 -225.854514)
		(width 0.0889)
		(layer "In2.Cu")
		(net "M_C_CPU1_SA_DQ<6>")
	)
	(arc
		(start 83.29803 -228.771958)
		(mid 83.580986 -228.848135)
		(end 83.863942 -228.771958)
		(width 0.0889)
		(layer "In2.Cu")
		(net "M_C_CPU1_SA_DQ<6>")
	)
	(arc
		(start 93.638116 -228.771958)
		(mid 93.885829 -228.847178)
		(end 94.141036 -228.803708)
		(width 0.0889)
		(layer "In2.Cu")
		(net "M_C_CPU1_SA_DQ<6>")
	)
	(arc
		(start 82.357976 -228.771958)
		(mid 82.640932 -228.848135)
		(end 82.923888 -228.771958)
		(width 0.0889)
		(layer "In2.Cu")
		(net "M_C_CPU1_SA_DQ<6>")
	)
	(arc
		(start 81.448656 -227.169726)
		(mid 81.564083 -227.303102)
		(end 81.605628 -227.474526)
		(width 0.0889)
		(layer "In2.Cu")
		(net "M_C_CPU1_SA_DQ<6>")
	)
	(arc
		(start 78.608174 -222.305626)
		(mid 78.738543 -222.436229)
		(end 78.786228 -222.61449)
		(width 0.0889)
		(layer "In2.Cu")
		(net "M_C_CPU1_SA_DQ<6>")
	)
	(arc
		(start 82.075782 -228.284532)
		(mid 82.141018 -228.548123)
		(end 82.321654 -228.750876)
		(width 0.0889)
		(layer "In2.Cu")
		(net "M_C_CPU1_SA_DQ<6>")
	)
	(arc
		(start 86.118192 -228.771958)
		(mid 86.401148 -228.848135)
		(end 86.684104 -228.771958)
		(width 0.0889)
		(layer "In2.Cu")
		(net "M_C_CPU1_SA_DQ<6>")
	)
	(arc
		(start 90.817954 -228.771958)
		(mid 91.10091 -228.848135)
		(end 91.383866 -228.771958)
		(width 0.0889)
		(layer "In2.Cu")
		(net "M_C_CPU1_SA_DQ<6>")
	)
	(arc
		(start 81.135728 -226.66452)
		(mid 81.200243 -226.926739)
		(end 81.37906 -227.129086)
		(width 0.0889)
		(layer "In2.Cu")
		(net "M_C_CPU1_SA_DQ<6>")
	)
	(arc
		(start 92.32392 -228.771958)
		(mid 92.506171 -228.721608)
		(end 92.68968 -228.767132)
		(width 0.0889)
		(layer "In2.Cu")
		(net "M_C_CPU1_SA_DQ<6>")
	)
	(arc
		(start 80.195674 -225.044508)
		(mid 80.260189 -225.306727)
		(end 80.439006 -225.509074)
		(width 0.0889)
		(layer "In2.Cu")
		(net "M_C_CPU1_SA_DQ<6>")
	)
	(arc
		(start 89.878154 -228.771958)
		(mid 90.16111 -228.848135)
		(end 90.444066 -228.771958)
		(width 0.0889)
		(layer "In2.Cu")
		(net "M_C_CPU1_SA_DQ<6>")
	)
	(arc
		(start 80.665828 -225.854514)
		(mid 80.731064 -226.118105)
		(end 80.9117 -226.320858)
		(width 0.0889)
		(layer "In2.Cu")
		(net "M_C_CPU1_SA_DQ<6>")
	)
	(arc
		(start 81.919826 -227.98024)
		(mid 82.034502 -228.113574)
		(end 82.075782 -228.284532)
		(width 0.0889)
		(layer "In2.Cu")
		(net "M_C_CPU1_SA_DQ<6>")
	)
	(arc
		(start 79.726028 -224.234502)
		(mid 79.791264 -224.498093)
		(end 79.9719 -224.700846)
		(width 0.0889)
		(layer "In2.Cu")
		(net "M_C_CPU1_SA_DQ<6>")
	)
	(arc
		(start 88.9381 -228.771958)
		(mid 89.221056 -228.848135)
		(end 89.504012 -228.771958)
		(width 0.0889)
		(layer "In2.Cu")
		(net "M_C_CPU1_SA_DQ<6>")
	)
	(arc
		(start 84.812378 -228.767132)
		(mid 84.995886 -228.721638)
		(end 85.178138 -228.771958)
		(width 0.0889)
		(layer "In2.Cu")
		(net "M_C_CPU1_SA_DQ<6>")
	)
	(arc
		(start 80.038702 -224.739708)
		(mid 80.154129 -224.873084)
		(end 80.195674 -225.044508)
		(width 0.0889)
		(layer "In2.Cu")
		(net "M_C_CPU1_SA_DQ<6>")
	)
	(arc
		(start 89.512394 -228.767132)
		(mid 89.695902 -228.721638)
		(end 89.878154 -228.771958)
		(width 0.0889)
		(layer "In2.Cu")
		(net "M_C_CPU1_SA_DQ<6>")
	)
	(arc
		(start 78.786228 -222.61449)
		(mid 78.851829 -222.878709)
		(end 79.03337 -223.081596)
		(width 0.0889)
		(layer "In2.Cu")
		(net "M_C_CPU1_SA_DQ<6>")
	)
	(arc
		(start 87.623904 -228.771958)
		(mid 87.806155 -228.721608)
		(end 87.989664 -228.767132)
		(width 0.0889)
		(layer "In2.Cu")
		(net "M_C_CPU1_SA_DQ<6>")
	)
	(segment
		(start 95.797878 -229.360476)
		(end 95.331026 -229.094538)
		(width 0.10668)
		(layer "F.Cu")
		(net "M_C_CPU1_SA_DQ<5>")
	)
	(segment
		(start 50.675032 -204.560424)
		(end 50.8381 -204.397356)
		(width 0.14478)
		(layer "In2.Cu")
		(net "M_C_CPU1_SA_DQ<5>")
	)
	(segment
		(start 81.95056 -229.397306)
		(end 81.984088 -229.416864)
		(width 0.0889)
		(layer "In2.Cu")
		(net "M_C_CPU1_SA_DQ<5>")
	)
	(segment
		(start 47.409354 -205.410308)
		(end 48.222154 -205.410308)
		(width 0.14478)
		(layer "In2.Cu")
		(net "M_C_CPU1_SA_DQ<5>")
	)
	(segment
		(start 54.9656 -205.24724)
		(end 55.128668 -205.410308)
		(width 0.14478)
		(layer "In2.Cu")
		(net "M_C_CPU1_SA_DQ<5>")
	)
	(segment
		(start 46.526704 -205.797404)
		(end 46.689772 -205.634336)
		(width 0.14478)
		(layer "In2.Cu")
		(net "M_C_CPU1_SA_DQ<5>")
	)
	(segment
		(start 56.303926 -205.022704)
		(end 56.466994 -205.185772)
		(width 0.14478)
		(layer "In2.Cu")
		(net "M_C_CPU1_SA_DQ<5>")
	)
	(segment
		(start 76.893166 -219.40393)
		(end 76.893166 -221.284292)
		(width 0.14478)
		(layer "In2.Cu")
		(net "M_C_CPU1_SA_DQ<5>")
	)
	(segment
		(start 52.431696 -204.332332)
		(end 52.594764 -204.169264)
		(width 0.14478)
		(layer "In2.Cu")
		(net "M_C_CPU1_SA_DQ<5>")
	)
	(segment
		(start 84.229702 -229.42169)
		(end 84.238084 -229.416864)
		(width 0.0889)
		(layer "In2.Cu")
		(net "M_C_CPU1_SA_DQ<5>")
	)
	(segment
		(start 78.003146 -222.394272)
		(end 78.003146 -222.73514)
		(width 0.0889)
		(layer "In2.Cu")
		(net "M_C_CPU1_SA_DQ<5>")
	)
	(segment
		(start 91.749626 -229.42169)
		(end 91.758008 -229.416864)
		(width 0.0889)
		(layer "In2.Cu")
		(net "M_C_CPU1_SA_DQ<5>")
	)
	(segment
		(start 51.557682 -204.560424)
		(end 52.268628 -204.560424)
		(width 0.14478)
		(layer "In2.Cu")
		(net "M_C_CPU1_SA_DQ<5>")
	)
	(segment
		(start 48.222154 -205.410308)
		(end 48.385222 -205.24724)
		(width 0.14478)
		(layer "In2.Cu")
		(net "M_C_CPU1_SA_DQ<5>")
	)
	(segment
		(start 44.817538 -205.462886)
		(end 44.817538 -205.655926)
		(width 0.14478)
		(layer "In2.Cu")
		(net "M_C_CPU1_SA_DQ<5>")
	)
	(segment
		(start 54.9656 -205.208632)
		(end 54.9656 -205.24724)
		(width 0.14478)
		(layer "In2.Cu")
		(net "M_C_CPU1_SA_DQ<5>")
	)
	(segment
		(start 94.204028 -229.416864)
		(end 94.21241 -229.42169)
		(width 0.0889)
		(layer "In2.Cu")
		(net "M_C_CPU1_SA_DQ<5>")
	)
	(segment
		(start 81.513934 -228.607112)
		(end 81.55305 -228.629972)
		(width 0.0889)
		(layer "In2.Cu")
		(net "M_C_CPU1_SA_DQ<5>")
	)
	(segment
		(start 51.394614 -204.397356)
		(end 51.557682 -204.560424)
		(width 0.14478)
		(layer "In2.Cu")
		(net "M_C_CPU1_SA_DQ<5>")
	)
	(segment
		(start 80.075786 -226.160838)
		(end 80.10398 -226.177094)
		(width 0.0889)
		(layer "In2.Cu")
		(net "M_C_CPU1_SA_DQ<5>")
	)
	(segment
		(start 55.128668 -205.410308)
		(end 55.747412 -205.410308)
		(width 0.14478)
		(layer "In2.Cu")
		(net "M_C_CPU1_SA_DQ<5>")
	)
	(segment
		(start 79.164434 -224.557844)
		(end 79.207614 -224.58299)
		(width 0.0889)
		(layer "In2.Cu")
		(net "M_C_CPU1_SA_DQ<5>")
	)
	(segment
		(start 45.576744 -205.183232)
		(end 45.739812 -205.020164)
		(width 0.14478)
		(layer "In2.Cu")
		(net "M_C_CPU1_SA_DQ<5>")
	)
	(segment
		(start 57.153048 -205.410308)
		(end 58.002932 -204.560424)
		(width 0.14478)
		(layer "In2.Cu")
		(net "M_C_CPU1_SA_DQ<5>")
	)
	(segment
		(start 46.133258 -205.634336)
		(end 46.296326 -205.797404)
		(width 0.14478)
		(layer "In2.Cu")
		(net "M_C_CPU1_SA_DQ<5>")
	)
	(segment
		(start 85.74405 -229.416864)
		(end 85.752432 -229.42169)
		(width 0.0889)
		(layer "In2.Cu")
		(net "M_C_CPU1_SA_DQ<5>")
	)
	(segment
		(start 80.542384 -226.968812)
		(end 80.574134 -226.9871)
		(width 0.0889)
		(layer "In2.Cu")
		(net "M_C_CPU1_SA_DQ<5>")
	)
	(segment
		(start 56.466994 -205.185772)
		(end 56.466994 -205.24724)
		(width 0.14478)
		(layer "In2.Cu")
		(net "M_C_CPU1_SA_DQ<5>")
	)
	(segment
		(start 51.001168 -204.166724)
		(end 51.231546 -204.166724)
		(width 0.14478)
		(layer "In2.Cu")
		(net "M_C_CPU1_SA_DQ<5>")
	)
	(segment
		(start 61.169042 -205.500224)
		(end 63.60668 -205.500224)
		(width 0.14478)
		(layer "In2.Cu")
		(net "M_C_CPU1_SA_DQ<5>")
	)
	(segment
		(start 47.083218 -205.020164)
		(end 47.246286 -205.183232)
		(width 0.14478)
		(layer "In2.Cu")
		(net "M_C_CPU1_SA_DQ<5>")
	)
	(segment
		(start 50.8381 -204.397356)
		(end 50.8381 -204.329792)
		(width 0.14478)
		(layer "In2.Cu")
		(net "M_C_CPU1_SA_DQ<5>")
	)
	(segment
		(start 44.817538 -205.655926)
		(end 44.962318 -205.800706)
		(width 0.14478)
		(layer "In2.Cu")
		(net "M_C_CPU1_SA_DQ<5>")
	)
	(segment
		(start 48.778668 -205.017624)
		(end 48.941736 -205.180692)
		(width 0.14478)
		(layer "In2.Cu")
		(net "M_C_CPU1_SA_DQ<5>")
	)
	(segment
		(start 56.630062 -205.410308)
		(end 57.153048 -205.410308)
		(width 0.14478)
		(layer "In2.Cu")
		(net "M_C_CPU1_SA_DQ<5>")
	)
	(segment
		(start 55.747412 -205.410308)
		(end 55.91048 -205.24724)
		(width 0.14478)
		(layer "In2.Cu")
		(net "M_C_CPU1_SA_DQ<5>")
	)
	(segment
		(start 54.802532 -205.045564)
		(end 54.9656 -205.208632)
		(width 0.14478)
		(layer "In2.Cu")
		(net "M_C_CPU1_SA_DQ<5>")
	)
	(segment
		(start 52.594764 -204.169264)
		(end 52.825142 -204.169264)
		(width 0.14478)
		(layer "In2.Cu")
		(net "M_C_CPU1_SA_DQ<5>")
	)
	(segment
		(start 93.263974 -229.416864)
		(end 93.272356 -229.42169)
		(width 0.0889)
		(layer "In2.Cu")
		(net "M_C_CPU1_SA_DQ<5>")
	)
	(segment
		(start 58.602372 -204.192124)
		(end 58.83275 -204.192124)
		(width 0.14478)
		(layer "In2.Cu")
		(net "M_C_CPU1_SA_DQ<5>")
	)
	(segment
		(start 58.995818 -204.355192)
		(end 58.995818 -204.397356)
		(width 0.14478)
		(layer "In2.Cu")
		(net "M_C_CPU1_SA_DQ<5>")
	)
	(segment
		(start 46.133258 -205.183232)
		(end 46.133258 -205.634336)
		(width 0.14478)
		(layer "In2.Cu")
		(net "M_C_CPU1_SA_DQ<5>")
	)
	(segment
		(start 52.825142 -204.169264)
		(end 52.98821 -204.332332)
		(width 0.14478)
		(layer "In2.Cu")
		(net "M_C_CPU1_SA_DQ<5>")
	)
	(segment
		(start 80.574134 -226.9871)
		(end 80.610456 -227.008182)
		(width 0.0889)
		(layer "In2.Cu")
		(net "M_C_CPU1_SA_DQ<5>")
	)
	(segment
		(start 44.340018 -204.985366)
		(end 44.817538 -205.462886)
		(width 0.14478)
		(layer "In2.Cu")
		(net "M_C_CPU1_SA_DQ<5>")
	)
	(segment
		(start 48.385222 -205.24724)
		(end 48.385222 -205.180692)
		(width 0.14478)
		(layer "In2.Cu")
		(net "M_C_CPU1_SA_DQ<5>")
	)
	(segment
		(start 49.444656 -205.410308)
		(end 50.29454 -204.560424)
		(width 0.14478)
		(layer "In2.Cu")
		(net "M_C_CPU1_SA_DQ<5>")
	)
	(segment
		(start 44.962318 -205.800706)
		(end 45.413676 -205.800706)
		(width 0.14478)
		(layer "In2.Cu")
		(net "M_C_CPU1_SA_DQ<5>")
	)
	(segment
		(start 79.126334 -224.535746)
		(end 79.164434 -224.557844)
		(width 0.0889)
		(layer "In2.Cu")
		(net "M_C_CPU1_SA_DQ<5>")
	)
	(segment
		(start 47.246286 -205.183232)
		(end 47.246286 -205.24724)
		(width 0.14478)
		(layer "In2.Cu")
		(net "M_C_CPU1_SA_DQ<5>")
	)
	(segment
		(start 83.289648 -229.42169)
		(end 83.29803 -229.416864)
		(width 0.0889)
		(layer "In2.Cu")
		(net "M_C_CPU1_SA_DQ<5>")
	)
	(segment
		(start 88.929718 -229.42169)
		(end 88.9381 -229.416864)
		(width 0.0889)
		(layer "In2.Cu")
		(net "M_C_CPU1_SA_DQ<5>")
	)
	(segment
		(start 50.8381 -204.329792)
		(end 51.001168 -204.166724)
		(width 0.14478)
		(layer "In2.Cu")
		(net "M_C_CPU1_SA_DQ<5>")
	)
	(segment
		(start 48.54829 -205.017624)
		(end 48.778668 -205.017624)
		(width 0.14478)
		(layer "In2.Cu")
		(net "M_C_CPU1_SA_DQ<5>")
	)
	(segment
		(start 67.523106 -210.03387)
		(end 76.893166 -219.40393)
		(width 0.14478)
		(layer "In2.Cu")
		(net "M_C_CPU1_SA_DQ<5>")
	)
	(segment
		(start 54.572154 -205.045564)
		(end 54.802532 -205.045564)
		(width 0.14478)
		(layer "In2.Cu")
		(net "M_C_CPU1_SA_DQ<5>")
	)
	(segment
		(start 56.073548 -205.022704)
		(end 56.303926 -205.022704)
		(width 0.14478)
		(layer "In2.Cu")
		(net "M_C_CPU1_SA_DQ<5>")
	)
	(segment
		(start 76.893166 -221.284292)
		(end 78.003146 -222.394272)
		(width 0.14478)
		(layer "In2.Cu")
		(net "M_C_CPU1_SA_DQ<5>")
	)
	(segment
		(start 46.689772 -205.634336)
		(end 46.689772 -205.183232)
		(width 0.14478)
		(layer "In2.Cu")
		(net "M_C_CPU1_SA_DQ<5>")
	)
	(segment
		(start 79.63408 -225.367342)
		(end 79.665322 -225.385376)
		(width 0.0889)
		(layer "In2.Cu")
		(net "M_C_CPU1_SA_DQ<5>")
	)
	(segment
		(start 55.91048 -205.24724)
		(end 55.91048 -205.185772)
		(width 0.14478)
		(layer "In2.Cu")
		(net "M_C_CPU1_SA_DQ<5>")
	)
	(segment
		(start 81.012284 -227.778818)
		(end 81.044034 -227.797106)
		(width 0.0889)
		(layer "In2.Cu")
		(net "M_C_CPU1_SA_DQ<5>")
	)
	(segment
		(start 78.003146 -222.73514)
		(end 78.14818 -222.880174)
		(width 0.0889)
		(layer "In2.Cu")
		(net "M_C_CPU1_SA_DQ<5>")
	)
	(segment
		(start 49.104804 -205.410308)
		(end 49.444656 -205.410308)
		(width 0.14478)
		(layer "In2.Cu")
		(net "M_C_CPU1_SA_DQ<5>")
	)
	(segment
		(start 48.941736 -205.180692)
		(end 48.941736 -205.24724)
		(width 0.14478)
		(layer "In2.Cu")
		(net "M_C_CPU1_SA_DQ<5>")
	)
	(segment
		(start 59.158886 -204.560424)
		(end 60.229242 -204.560424)
		(width 0.14478)
		(layer "In2.Cu")
		(net "M_C_CPU1_SA_DQ<5>")
	)
	(segment
		(start 54.409086 -205.24724)
		(end 54.409086 -205.208632)
		(width 0.14478)
		(layer "In2.Cu")
		(net "M_C_CPU1_SA_DQ<5>")
	)
	(segment
		(start 54.001162 -205.410308)
		(end 54.246018 -205.410308)
		(width 0.14478)
		(layer "In2.Cu")
		(net "M_C_CPU1_SA_DQ<5>")
	)
	(segment
		(start 78.694026 -223.747076)
		(end 78.735936 -223.77146)
		(width 0.0889)
		(layer "In2.Cu")
		(net "M_C_CPU1_SA_DQ<5>")
	)
	(segment
		(start 81.044034 -227.797106)
		(end 81.08315 -227.819966)
		(width 0.0889)
		(layer "In2.Cu")
		(net "M_C_CPU1_SA_DQ<5>")
	)
	(segment
		(start 58.439304 -204.397356)
		(end 58.439304 -204.355192)
		(width 0.14478)
		(layer "In2.Cu")
		(net "M_C_CPU1_SA_DQ<5>")
	)
	(segment
		(start 58.439304 -204.355192)
		(end 58.602372 -204.192124)
		(width 0.14478)
		(layer "In2.Cu")
		(net "M_C_CPU1_SA_DQ<5>")
	)
	(segment
		(start 45.97019 -205.020164)
		(end 46.133258 -205.183232)
		(width 0.14478)
		(layer "In2.Cu")
		(net "M_C_CPU1_SA_DQ<5>")
	)
	(segment
		(start 92.68968 -229.42169)
		(end 92.698062 -229.416864)
		(width 0.0889)
		(layer "In2.Cu")
		(net "M_C_CPU1_SA_DQ<5>")
	)
	(segment
		(start 52.98821 -204.332332)
		(end 52.98821 -204.397356)
		(width 0.14478)
		(layer "In2.Cu")
		(net "M_C_CPU1_SA_DQ<5>")
	)
	(segment
		(start 58.995818 -204.397356)
		(end 59.158886 -204.560424)
		(width 0.14478)
		(layer "In2.Cu")
		(net "M_C_CPU1_SA_DQ<5>")
	)
	(segment
		(start 89.504012 -229.416864)
		(end 89.512394 -229.42169)
		(width 0.0889)
		(layer "In2.Cu")
		(net "M_C_CPU1_SA_DQ<5>")
	)
	(segment
		(start 56.466994 -205.24724)
		(end 56.630062 -205.410308)
		(width 0.14478)
		(layer "In2.Cu")
		(net "M_C_CPU1_SA_DQ<5>")
	)
	(segment
		(start 52.431696 -204.397356)
		(end 52.431696 -204.332332)
		(width 0.14478)
		(layer "In2.Cu")
		(net "M_C_CPU1_SA_DQ<5>")
	)
	(segment
		(start 45.413676 -205.800706)
		(end 45.576744 -205.637638)
		(width 0.14478)
		(layer "In2.Cu")
		(net "M_C_CPU1_SA_DQ<5>")
	)
	(segment
		(start 81.483454 -228.589332)
		(end 81.513934 -228.607112)
		(width 0.0889)
		(layer "In2.Cu")
		(net "M_C_CPU1_SA_DQ<5>")
	)
	(segment
		(start 54.409086 -205.208632)
		(end 54.572154 -205.045564)
		(width 0.14478)
		(layer "In2.Cu")
		(net "M_C_CPU1_SA_DQ<5>")
	)
	(segment
		(start 52.98821 -204.397356)
		(end 54.001162 -205.410308)
		(width 0.14478)
		(layer "In2.Cu")
		(net "M_C_CPU1_SA_DQ<5>")
	)
	(segment
		(start 63.60668 -205.500224)
		(end 67.523106 -209.41665)
		(width 0.14478)
		(layer "In2.Cu")
		(net "M_C_CPU1_SA_DQ<5>")
	)
	(segment
		(start 46.296326 -205.797404)
		(end 46.526704 -205.797404)
		(width 0.14478)
		(layer "In2.Cu")
		(net "M_C_CPU1_SA_DQ<5>")
	)
	(segment
		(start 48.941736 -205.24724)
		(end 49.104804 -205.410308)
		(width 0.14478)
		(layer "In2.Cu")
		(net "M_C_CPU1_SA_DQ<5>")
	)
	(segment
		(start 87.989664 -229.42169)
		(end 87.998046 -229.416864)
		(width 0.0889)
		(layer "In2.Cu")
		(net "M_C_CPU1_SA_DQ<5>")
	)
	(segment
		(start 55.91048 -205.185772)
		(end 56.073548 -205.022704)
		(width 0.14478)
		(layer "In2.Cu")
		(net "M_C_CPU1_SA_DQ<5>")
	)
	(segment
		(start 67.523106 -209.41665)
		(end 67.523106 -210.03387)
		(width 0.14478)
		(layer "In2.Cu")
		(net "M_C_CPU1_SA_DQ<5>")
	)
	(segment
		(start 51.231546 -204.166724)
		(end 51.394614 -204.329792)
		(width 0.14478)
		(layer "In2.Cu")
		(net "M_C_CPU1_SA_DQ<5>")
	)
	(segment
		(start 80.10398 -226.177094)
		(end 80.143096 -226.199954)
		(width 0.0889)
		(layer "In2.Cu")
		(net "M_C_CPU1_SA_DQ<5>")
	)
	(segment
		(start 78.667102 -223.731582)
		(end 78.694026 -223.747076)
		(width 0.0889)
		(layer "In2.Cu")
		(net "M_C_CPU1_SA_DQ<5>")
	)
	(segment
		(start 45.576744 -205.637638)
		(end 45.576744 -205.183232)
		(width 0.14478)
		(layer "In2.Cu")
		(net "M_C_CPU1_SA_DQ<5>")
	)
	(segment
		(start 58.002932 -204.560424)
		(end 58.276236 -204.560424)
		(width 0.14478)
		(layer "In2.Cu")
		(net "M_C_CPU1_SA_DQ<5>")
	)
	(segment
		(start 79.604362 -225.35007)
		(end 79.63408 -225.367342)
		(width 0.0889)
		(layer "In2.Cu")
		(net "M_C_CPU1_SA_DQ<5>")
	)
	(segment
		(start 84.803996 -229.416864)
		(end 84.812378 -229.42169)
		(width 0.0889)
		(layer "In2.Cu")
		(net "M_C_CPU1_SA_DQ<5>")
	)
	(segment
		(start 54.246018 -205.410308)
		(end 54.409086 -205.24724)
		(width 0.14478)
		(layer "In2.Cu")
		(net "M_C_CPU1_SA_DQ<5>")
	)
	(segment
		(start 50.29454 -204.560424)
		(end 50.675032 -204.560424)
		(width 0.14478)
		(layer "In2.Cu")
		(net "M_C_CPU1_SA_DQ<5>")
	)
	(segment
		(start 52.268628 -204.560424)
		(end 52.431696 -204.397356)
		(width 0.14478)
		(layer "In2.Cu")
		(net "M_C_CPU1_SA_DQ<5>")
	)
	(segment
		(start 95.48495 -229.359968)
		(end 95.331026 -229.094538)
		(width 0.0889)
		(layer "In2.Cu")
		(net "M_C_CPU1_SA_DQ<5>")
	)
	(segment
		(start 46.85284 -205.020164)
		(end 47.083218 -205.020164)
		(width 0.14478)
		(layer "In2.Cu")
		(net "M_C_CPU1_SA_DQ<5>")
	)
	(segment
		(start 47.246286 -205.24724)
		(end 47.409354 -205.410308)
		(width 0.14478)
		(layer "In2.Cu")
		(net "M_C_CPU1_SA_DQ<5>")
	)
	(segment
		(start 58.276236 -204.560424)
		(end 58.439304 -204.397356)
		(width 0.14478)
		(layer "In2.Cu")
		(net "M_C_CPU1_SA_DQ<5>")
	)
	(segment
		(start 51.394614 -204.329792)
		(end 51.394614 -204.397356)
		(width 0.14478)
		(layer "In2.Cu")
		(net "M_C_CPU1_SA_DQ<5>")
	)
	(segment
		(start 95.462852 -229.443026)
		(end 95.48495 -229.359968)
		(width 0.0889)
		(layer "In2.Cu")
		(net "M_C_CPU1_SA_DQ<5>")
	)
	(segment
		(start 60.229242 -204.560424)
		(end 61.169042 -205.500224)
		(width 0.14478)
		(layer "In2.Cu")
		(net "M_C_CPU1_SA_DQ<5>")
	)
	(segment
		(start 58.83275 -204.192124)
		(end 58.995818 -204.355192)
		(width 0.14478)
		(layer "In2.Cu")
		(net "M_C_CPU1_SA_DQ<5>")
	)
	(segment
		(start 45.739812 -205.020164)
		(end 45.97019 -205.020164)
		(width 0.14478)
		(layer "In2.Cu")
		(net "M_C_CPU1_SA_DQ<5>")
	)
	(segment
		(start 46.689772 -205.183232)
		(end 46.85284 -205.020164)
		(width 0.14478)
		(layer "In2.Cu")
		(net "M_C_CPU1_SA_DQ<5>")
	)
	(segment
		(start 48.385222 -205.180692)
		(end 48.54829 -205.017624)
		(width 0.14478)
		(layer "In2.Cu")
		(net "M_C_CPU1_SA_DQ<5>")
	)
	(segment
		(start 78.224888 -222.938848)
		(end 78.258162 -222.958152)
		(width 0.0889)
		(layer "In2.Cu")
		(net "M_C_CPU1_SA_DQ<5>")
	)
	(arc
		(start 90.444066 -229.416864)
		(mid 90.63101 -229.467153)
		(end 90.817954 -229.416864)
		(width 0.0889)
		(layer "In2.Cu")
		(net "M_C_CPU1_SA_DQ<5>")
	)
	(arc
		(start 85.752432 -229.42169)
		(mid 85.93594 -229.467215)
		(end 86.118192 -229.416864)
		(width 0.0889)
		(layer "In2.Cu")
		(net "M_C_CPU1_SA_DQ<5>")
	)
	(arc
		(start 87.057992 -229.416864)
		(mid 87.340948 -229.340687)
		(end 87.623904 -229.416864)
		(width 0.0889)
		(layer "In2.Cu")
		(net "M_C_CPU1_SA_DQ<5>")
	)
	(arc
		(start 84.812378 -229.42169)
		(mid 84.995886 -229.467215)
		(end 85.178138 -229.416864)
		(width 0.0889)
		(layer "In2.Cu")
		(net "M_C_CPU1_SA_DQ<5>")
	)
	(arc
		(start 84.238084 -229.416864)
		(mid 84.52104 -229.340687)
		(end 84.803996 -229.416864)
		(width 0.0889)
		(layer "In2.Cu")
		(net "M_C_CPU1_SA_DQ<5>")
	)
	(arc
		(start 90.817954 -229.416864)
		(mid 91.10091 -229.340687)
		(end 91.383866 -229.416864)
		(width 0.0889)
		(layer "In2.Cu")
		(net "M_C_CPU1_SA_DQ<5>")
	)
	(arc
		(start 79.207614 -224.58299)
		(mid 79.383158 -224.784695)
		(end 79.446374 -225.044508)
		(width 0.0889)
		(layer "In2.Cu")
		(net "M_C_CPU1_SA_DQ<5>")
	)
	(arc
		(start 80.610456 -227.008182)
		(mid 80.791108 -227.210927)
		(end 80.856328 -227.474526)
		(width 0.0889)
		(layer "In2.Cu")
		(net "M_C_CPU1_SA_DQ<5>")
	)
	(arc
		(start 81.55305 -228.629972)
		(mid 81.731863 -228.832322)
		(end 81.796382 -229.094538)
		(width 0.0889)
		(layer "In2.Cu")
		(net "M_C_CPU1_SA_DQ<5>")
	)
	(arc
		(start 81.08315 -227.819966)
		(mid 81.261963 -228.022316)
		(end 81.326482 -228.284532)
		(width 0.0889)
		(layer "In2.Cu")
		(net "M_C_CPU1_SA_DQ<5>")
	)
	(arc
		(start 81.984088 -229.416864)
		(mid 82.171032 -229.467153)
		(end 82.357976 -229.416864)
		(width 0.0889)
		(layer "In2.Cu")
		(net "M_C_CPU1_SA_DQ<5>")
	)
	(arc
		(start 89.878154 -229.416864)
		(mid 90.16111 -229.340687)
		(end 90.444066 -229.416864)
		(width 0.0889)
		(layer "In2.Cu")
		(net "M_C_CPU1_SA_DQ<5>")
	)
	(arc
		(start 86.118192 -229.416864)
		(mid 86.401148 -229.340687)
		(end 86.684104 -229.416864)
		(width 0.0889)
		(layer "In2.Cu")
		(net "M_C_CPU1_SA_DQ<5>")
	)
	(arc
		(start 91.758008 -229.416864)
		(mid 92.040964 -229.340687)
		(end 92.32392 -229.416864)
		(width 0.0889)
		(layer "In2.Cu")
		(net "M_C_CPU1_SA_DQ<5>")
	)
	(arc
		(start 78.735936 -223.77146)
		(mid 78.913152 -223.974003)
		(end 78.976728 -224.235518)
		(width 0.0889)
		(layer "In2.Cu")
		(net "M_C_CPU1_SA_DQ<5>")
	)
	(arc
		(start 81.326482 -228.284532)
		(mid 81.368031 -228.455954)
		(end 81.483454 -228.589332)
		(width 0.0889)
		(layer "In2.Cu")
		(net "M_C_CPU1_SA_DQ<5>")
	)
	(arc
		(start 87.998046 -229.416864)
		(mid 88.281002 -229.340687)
		(end 88.563958 -229.416864)
		(width 0.0889)
		(layer "In2.Cu")
		(net "M_C_CPU1_SA_DQ<5>")
	)
	(arc
		(start 82.357976 -229.416864)
		(mid 82.640932 -229.340687)
		(end 82.923888 -229.416864)
		(width 0.0889)
		(layer "In2.Cu")
		(net "M_C_CPU1_SA_DQ<5>")
	)
	(arc
		(start 82.923888 -229.416864)
		(mid 83.106139 -229.467248)
		(end 83.289648 -229.42169)
		(width 0.0889)
		(layer "In2.Cu")
		(net "M_C_CPU1_SA_DQ<5>")
	)
	(arc
		(start 93.272356 -229.42169)
		(mid 93.455864 -229.467215)
		(end 93.638116 -229.416864)
		(width 0.0889)
		(layer "In2.Cu")
		(net "M_C_CPU1_SA_DQ<5>")
	)
	(arc
		(start 94.57817 -229.416864)
		(mid 94.861126 -229.340687)
		(end 95.144082 -229.416864)
		(width 0.0889)
		(layer "In2.Cu")
		(net "M_C_CPU1_SA_DQ<5>")
	)
	(arc
		(start 85.178138 -229.416864)
		(mid 85.461094 -229.340687)
		(end 85.74405 -229.416864)
		(width 0.0889)
		(layer "In2.Cu")
		(net "M_C_CPU1_SA_DQ<5>")
	)
	(arc
		(start 78.976728 -224.235518)
		(mid 79.016103 -224.403279)
		(end 79.126334 -224.535746)
		(width 0.0889)
		(layer "In2.Cu")
		(net "M_C_CPU1_SA_DQ<5>")
	)
	(arc
		(start 83.29803 -229.416864)
		(mid 83.580986 -229.340687)
		(end 83.863942 -229.416864)
		(width 0.0889)
		(layer "In2.Cu")
		(net "M_C_CPU1_SA_DQ<5>")
	)
	(arc
		(start 92.32392 -229.416864)
		(mid 92.506171 -229.467248)
		(end 92.68968 -229.42169)
		(width 0.0889)
		(layer "In2.Cu")
		(net "M_C_CPU1_SA_DQ<5>")
	)
	(arc
		(start 88.563958 -229.416864)
		(mid 88.746209 -229.467248)
		(end 88.929718 -229.42169)
		(width 0.0889)
		(layer "In2.Cu")
		(net "M_C_CPU1_SA_DQ<5>")
	)
	(arc
		(start 78.258162 -222.958152)
		(mid 78.440525 -223.160672)
		(end 78.506828 -223.425004)
		(width 0.0889)
		(layer "In2.Cu")
		(net "M_C_CPU1_SA_DQ<5>")
	)
	(arc
		(start 80.386428 -226.66452)
		(mid 80.427683 -226.835491)
		(end 80.542384 -226.968812)
		(width 0.0889)
		(layer "In2.Cu")
		(net "M_C_CPU1_SA_DQ<5>")
	)
	(arc
		(start 93.638116 -229.416864)
		(mid 93.921072 -229.340687)
		(end 94.204028 -229.416864)
		(width 0.0889)
		(layer "In2.Cu")
		(net "M_C_CPU1_SA_DQ<5>")
	)
	(arc
		(start 92.698062 -229.416864)
		(mid 92.981018 -229.340687)
		(end 93.263974 -229.416864)
		(width 0.0889)
		(layer "In2.Cu")
		(net "M_C_CPU1_SA_DQ<5>")
	)
	(arc
		(start 88.9381 -229.416864)
		(mid 89.221056 -229.340687)
		(end 89.504012 -229.416864)
		(width 0.0889)
		(layer "In2.Cu")
		(net "M_C_CPU1_SA_DQ<5>")
	)
	(arc
		(start 79.665322 -225.385376)
		(mid 79.849821 -225.588595)
		(end 79.916782 -225.854768)
		(width 0.0889)
		(layer "In2.Cu")
		(net "M_C_CPU1_SA_DQ<5>")
	)
	(arc
		(start 94.21241 -229.42169)
		(mid 94.395918 -229.467215)
		(end 94.57817 -229.416864)
		(width 0.0889)
		(layer "In2.Cu")
		(net "M_C_CPU1_SA_DQ<5>")
	)
	(arc
		(start 78.506828 -223.425004)
		(mid 78.549438 -223.597901)
		(end 78.667102 -223.731582)
		(width 0.0889)
		(layer "In2.Cu")
		(net "M_C_CPU1_SA_DQ<5>")
	)
	(arc
		(start 83.863942 -229.416864)
		(mid 84.046193 -229.467248)
		(end 84.229702 -229.42169)
		(width 0.0889)
		(layer "In2.Cu")
		(net "M_C_CPU1_SA_DQ<5>")
	)
	(arc
		(start 79.916782 -225.854768)
		(mid 79.958973 -226.027176)
		(end 80.075786 -226.160838)
		(width 0.0889)
		(layer "In2.Cu")
		(net "M_C_CPU1_SA_DQ<5>")
	)
	(arc
		(start 89.512394 -229.42169)
		(mid 89.695902 -229.467215)
		(end 89.878154 -229.416864)
		(width 0.0889)
		(layer "In2.Cu")
		(net "M_C_CPU1_SA_DQ<5>")
	)
	(arc
		(start 78.14818 -222.880174)
		(mid 78.184623 -222.91201)
		(end 78.224888 -222.938848)
		(width 0.0889)
		(layer "In2.Cu")
		(net "M_C_CPU1_SA_DQ<5>")
	)
	(arc
		(start 91.383866 -229.416864)
		(mid 91.566117 -229.467248)
		(end 91.749626 -229.42169)
		(width 0.0889)
		(layer "In2.Cu")
		(net "M_C_CPU1_SA_DQ<5>")
	)
	(arc
		(start 80.856328 -227.474526)
		(mid 80.897583 -227.645497)
		(end 81.012284 -227.778818)
		(width 0.0889)
		(layer "In2.Cu")
		(net "M_C_CPU1_SA_DQ<5>")
	)
	(arc
		(start 87.623904 -229.416864)
		(mid 87.806155 -229.467248)
		(end 87.989664 -229.42169)
		(width 0.0889)
		(layer "In2.Cu")
		(net "M_C_CPU1_SA_DQ<5>")
	)
	(arc
		(start 86.684104 -229.416864)
		(mid 86.871048 -229.467153)
		(end 87.057992 -229.416864)
		(width 0.0889)
		(layer "In2.Cu")
		(net "M_C_CPU1_SA_DQ<5>")
	)
	(arc
		(start 81.796382 -229.094538)
		(mid 81.837144 -229.264422)
		(end 81.95056 -229.397306)
		(width 0.0889)
		(layer "In2.Cu")
		(net "M_C_CPU1_SA_DQ<5>")
	)
	(arc
		(start 80.143096 -226.199954)
		(mid 80.321909 -226.402304)
		(end 80.386428 -226.66452)
		(width 0.0889)
		(layer "In2.Cu")
		(net "M_C_CPU1_SA_DQ<5>")
	)
	(arc
		(start 79.446374 -225.044508)
		(mid 79.488214 -225.216494)
		(end 79.604362 -225.35007)
		(width 0.0889)
		(layer "In2.Cu")
		(net "M_C_CPU1_SA_DQ<5>")
	)
	(arc
		(start 95.144082 -229.416864)
		(mid 95.300519 -229.465902)
		(end 95.462852 -229.443026)
		(width 0.0889)
		(layer "In2.Cu")
		(net "M_C_CPU1_SA_DQ<5>")
	)
	(segment
		(start 94.387924 -228.55047)
		(end 93.921072 -228.284532)
		(width 0.10668)
		(layer "F.Cu")
		(net "M_C_CPU1_SA_DQ<4>")
	)
	(segment
		(start 82.453988 -228.607112)
		(end 82.46237 -228.611938)
		(width 0.0889)
		(layer "In2.Cu")
		(net "M_C_CPU1_SA_DQ<4>")
	)
	(segment
		(start 81.952338 -227.778818)
		(end 81.984088 -227.797106)
		(width 0.0889)
		(layer "In2.Cu")
		(net "M_C_CPU1_SA_DQ<4>")
	)
	(segment
		(start 56.580278 -204.103224)
		(end 56.810656 -204.103224)
		(width 0.14478)
		(layer "In2.Cu")
		(net "M_C_CPU1_SA_DQ<4>")
	)
	(segment
		(start 57.499504 -203.710286)
		(end 58.349388 -202.860402)
		(width 0.14478)
		(layer "In2.Cu")
		(net "M_C_CPU1_SA_DQ<4>")
	)
	(segment
		(start 56.810656 -204.103224)
		(end 56.973724 -203.940156)
		(width 0.14478)
		(layer "In2.Cu")
		(net "M_C_CPU1_SA_DQ<4>")
	)
	(segment
		(start 48.838612 -203.942696)
		(end 49.00168 -204.105764)
		(width 0.14478)
		(layer "In2.Cu")
		(net "M_C_CPU1_SA_DQ<4>")
	)
	(segment
		(start 46.182788 -203.937616)
		(end 46.345856 -204.100684)
		(width 0.14478)
		(layer "In2.Cu")
		(net "M_C_CPU1_SA_DQ<4>")
	)
	(segment
		(start 45.7835 -203.18095)
		(end 45.946568 -203.344018)
		(width 0.14478)
		(layer "In2.Cu")
		(net "M_C_CPU1_SA_DQ<4>")
	)
	(segment
		(start 70.530974 -211.733892)
		(end 70.761606 -211.733892)
		(width 0.14478)
		(layer "In2.Cu")
		(net "M_C_CPU1_SA_DQ<4>")
	)
	(segment
		(start 56.254142 -203.710286)
		(end 56.41721 -203.873354)
		(width 0.14478)
		(layer "In2.Cu")
		(net "M_C_CPU1_SA_DQ<4>")
	)
	(segment
		(start 56.41721 -203.873354)
		(end 56.41721 -203.940156)
		(width 0.14478)
		(layer "In2.Cu")
		(net "M_C_CPU1_SA_DQ<4>")
	)
	(segment
		(start 60.939934 -203.56195)
		(end 60.939934 -203.836524)
		(width 0.14478)
		(layer "In2.Cu")
		(net "M_C_CPU1_SA_DQ<4>")
	)
	(segment
		(start 81.044034 -226.177094)
		(end 81.08315 -226.199954)
		(width 0.0889)
		(layer "In2.Cu")
		(net "M_C_CPU1_SA_DQ<4>")
	)
	(segment
		(start 81.012284 -226.158806)
		(end 81.044034 -226.177094)
		(width 0.0889)
		(layer "In2.Cu")
		(net "M_C_CPU1_SA_DQ<4>")
	)
	(segment
		(start 83.394042 -228.607112)
		(end 83.402424 -228.611938)
		(width 0.0889)
		(layer "In2.Cu")
		(net "M_C_CPU1_SA_DQ<4>")
	)
	(segment
		(start 94.074996 -228.549962)
		(end 93.921072 -228.284532)
		(width 0.0889)
		(layer "In2.Cu")
		(net "M_C_CPU1_SA_DQ<4>")
	)
	(segment
		(start 61.392562 -204.144372)
		(end 61.392562 -204.267816)
		(width 0.14478)
		(layer "In2.Cu")
		(net "M_C_CPU1_SA_DQ<4>")
	)
	(segment
		(start 62.342522 -203.981304)
		(end 62.50559 -204.144372)
		(width 0.14478)
		(layer "In2.Cu")
		(net "M_C_CPU1_SA_DQ<4>")
	)
	(segment
		(start 53.952648 -203.710286)
		(end 56.254142 -203.710286)
		(width 0.14478)
		(layer "In2.Cu")
		(net "M_C_CPU1_SA_DQ<4>")
	)
	(segment
		(start 45.390054 -203.344018)
		(end 45.553122 -203.18095)
		(width 0.14478)
		(layer "In2.Cu")
		(net "M_C_CPU1_SA_DQ<4>")
	)
	(segment
		(start 61.949076 -204.144372)
		(end 62.112144 -203.981304)
		(width 0.14478)
		(layer "In2.Cu")
		(net "M_C_CPU1_SA_DQ<4>")
	)
	(segment
		(start 77.886306 -220.951044)
		(end 78.51267 -221.577408)
		(width 0.14478)
		(layer "In2.Cu")
		(net "M_C_CPU1_SA_DQ<4>")
	)
	(segment
		(start 69.671184 -210.462114)
		(end 69.580506 -210.552792)
		(width 0.14478)
		(layer "In2.Cu")
		(net "M_C_CPU1_SA_DQ<4>")
	)
	(segment
		(start 77.886306 -219.841826)
		(end 78.049374 -220.004894)
		(width 0.14478)
		(layer "In2.Cu")
		(net "M_C_CPU1_SA_DQ<4>")
	)
	(segment
		(start 45.390054 -203.956666)
		(end 45.390054 -203.344018)
		(width 0.14478)
		(layer "In2.Cu")
		(net "M_C_CPU1_SA_DQ<4>")
	)
	(segment
		(start 81.513934 -226.9871)
		(end 81.55305 -227.00996)
		(width 0.0889)
		(layer "In2.Cu")
		(net "M_C_CPU1_SA_DQ<4>")
	)
	(segment
		(start 60.939934 -203.836524)
		(end 61.084714 -203.981304)
		(width 0.14478)
		(layer "In2.Cu")
		(net "M_C_CPU1_SA_DQ<4>")
	)
	(segment
		(start 45.946568 -203.586334)
		(end 46.182788 -203.822554)
		(width 0.14478)
		(layer "In2.Cu")
		(net "M_C_CPU1_SA_DQ<4>")
	)
	(segment
		(start 70.458584 -211.018882)
		(end 70.458584 -211.249514)
		(width 0.14478)
		(layer "In2.Cu")
		(net "M_C_CPU1_SA_DQ<4>")
	)
	(segment
		(start 71.082916 -211.643214)
		(end 71.245984 -211.806282)
		(width 0.14478)
		(layer "In2.Cu")
		(net "M_C_CPU1_SA_DQ<4>")
	)
	(segment
		(start 46.739302 -203.873354)
		(end 46.892718 -203.719938)
		(width 0.14478)
		(layer "In2.Cu")
		(net "M_C_CPU1_SA_DQ<4>")
	)
	(segment
		(start 69.974206 -210.946492)
		(end 70.064884 -210.855814)
		(width 0.14478)
		(layer "In2.Cu")
		(net "M_C_CPU1_SA_DQ<4>")
	)
	(segment
		(start 70.295516 -210.855814)
		(end 70.458584 -211.018882)
		(width 0.14478)
		(layer "In2.Cu")
		(net "M_C_CPU1_SA_DQ<4>")
	)
	(segment
		(start 61.949076 -204.267816)
		(end 61.949076 -204.144372)
		(width 0.14478)
		(layer "In2.Cu")
		(net "M_C_CPU1_SA_DQ<4>")
	)
	(segment
		(start 82.422238 -228.588824)
		(end 82.453988 -228.607112)
		(width 0.0889)
		(layer "In2.Cu")
		(net "M_C_CPU1_SA_DQ<4>")
	)
	(segment
		(start 60.238386 -202.860402)
		(end 60.939934 -203.56195)
		(width 0.14478)
		(layer "In2.Cu")
		(net "M_C_CPU1_SA_DQ<4>")
	)
	(segment
		(start 80.075786 -224.540826)
		(end 80.10398 -224.557082)
		(width 0.0889)
		(layer "In2.Cu")
		(net "M_C_CPU1_SA_DQ<4>")
	)
	(segment
		(start 70.367906 -211.340192)
		(end 70.367906 -211.570824)
		(width 0.14478)
		(layer "In2.Cu")
		(net "M_C_CPU1_SA_DQ<4>")
	)
	(segment
		(start 46.739302 -203.937616)
		(end 46.739302 -203.873354)
		(width 0.14478)
		(layer "In2.Cu")
		(net "M_C_CPU1_SA_DQ<4>")
	)
	(segment
		(start 70.064884 -210.855814)
		(end 70.295516 -210.855814)
		(width 0.14478)
		(layer "In2.Cu")
		(net "M_C_CPU1_SA_DQ<4>")
	)
	(segment
		(start 63.062104 -204.144372)
		(end 63.225172 -203.981304)
		(width 0.14478)
		(layer "In2.Cu")
		(net "M_C_CPU1_SA_DQ<4>")
	)
	(segment
		(start 69.743574 -210.946492)
		(end 69.974206 -210.946492)
		(width 0.14478)
		(layer "In2.Cu")
		(net "M_C_CPU1_SA_DQ<4>")
	)
	(segment
		(start 87.154004 -228.607112)
		(end 87.162386 -228.611938)
		(width 0.0889)
		(layer "In2.Cu")
		(net "M_C_CPU1_SA_DQ<4>")
	)
	(segment
		(start 46.892718 -203.719938)
		(end 48.685196 -203.719938)
		(width 0.14478)
		(layer "In2.Cu")
		(net "M_C_CPU1_SA_DQ<4>")
	)
	(segment
		(start 77.886306 -220.724476)
		(end 77.886306 -220.951044)
		(width 0.14478)
		(layer "In2.Cu")
		(net "M_C_CPU1_SA_DQ<4>")
	)
	(segment
		(start 45.946568 -203.344018)
		(end 45.946568 -203.586334)
		(width 0.14478)
		(layer "In2.Cu")
		(net "M_C_CPU1_SA_DQ<4>")
	)
	(segment
		(start 79.600552 -223.727518)
		(end 79.634334 -223.747076)
		(width 0.0889)
		(layer "In2.Cu")
		(net "M_C_CPU1_SA_DQ<4>")
	)
	(segment
		(start 48.838612 -203.873354)
		(end 48.838612 -203.942696)
		(width 0.14478)
		(layer "In2.Cu")
		(net "M_C_CPU1_SA_DQ<4>")
	)
	(segment
		(start 45.553122 -203.18095)
		(end 45.7835 -203.18095)
		(width 0.14478)
		(layer "In2.Cu")
		(net "M_C_CPU1_SA_DQ<4>")
	)
	(segment
		(start 44.949618 -204.106526)
		(end 45.240194 -204.106526)
		(width 0.14478)
		(layer "In2.Cu")
		(net "M_C_CPU1_SA_DQ<4>")
	)
	(segment
		(start 49.854104 -203.710286)
		(end 50.694336 -202.870054)
		(width 0.14478)
		(layer "In2.Cu")
		(net "M_C_CPU1_SA_DQ<4>")
	)
	(segment
		(start 78.049374 -220.561408)
		(end 77.886306 -220.724476)
		(width 0.14478)
		(layer "In2.Cu")
		(net "M_C_CPU1_SA_DQ<4>")
	)
	(segment
		(start 78.241398 -220.004894)
		(end 78.404466 -220.167962)
		(width 0.14478)
		(layer "In2.Cu")
		(net "M_C_CPU1_SA_DQ<4>")
	)
	(segment
		(start 71.155306 -212.127592)
		(end 71.155306 -212.358224)
		(width 0.14478)
		(layer "In2.Cu")
		(net "M_C_CPU1_SA_DQ<4>")
	)
	(segment
		(start 79.634334 -223.747076)
		(end 79.67218 -223.76892)
		(width 0.0889)
		(layer "In2.Cu")
		(net "M_C_CPU1_SA_DQ<4>")
	)
	(segment
		(start 78.69428 -222.12681)
		(end 78.730856 -222.148146)
		(width 0.0889)
		(layer "In2.Cu")
		(net "M_C_CPU1_SA_DQ<4>")
	)
	(segment
		(start 49.232058 -204.105764)
		(end 49.395126 -203.942696)
		(width 0.14478)
		(layer "In2.Cu")
		(net "M_C_CPU1_SA_DQ<4>")
	)
	(segment
		(start 62.899036 -204.575664)
		(end 63.062104 -204.412596)
		(width 0.14478)
		(layer "In2.Cu")
		(net "M_C_CPU1_SA_DQ<4>")
	)
	(segment
		(start 62.50559 -204.144372)
		(end 62.50559 -204.412596)
		(width 0.14478)
		(layer "In2.Cu")
		(net "M_C_CPU1_SA_DQ<4>")
	)
	(segment
		(start 78.404466 -220.167962)
		(end 78.404466 -220.39834)
		(width 0.14478)
		(layer "In2.Cu")
		(net "M_C_CPU1_SA_DQ<4>")
	)
	(segment
		(start 49.395126 -203.873354)
		(end 49.558194 -203.710286)
		(width 0.14478)
		(layer "In2.Cu")
		(net "M_C_CPU1_SA_DQ<4>")
	)
	(segment
		(start 46.345856 -204.100684)
		(end 46.576234 -204.100684)
		(width 0.14478)
		(layer "In2.Cu")
		(net "M_C_CPU1_SA_DQ<4>")
	)
	(segment
		(start 63.062104 -204.412596)
		(end 63.062104 -204.144372)
		(width 0.14478)
		(layer "In2.Cu")
		(net "M_C_CPU1_SA_DQ<4>")
	)
	(segment
		(start 78.404466 -220.39834)
		(end 78.241398 -220.561408)
		(width 0.14478)
		(layer "In2.Cu")
		(net "M_C_CPU1_SA_DQ<4>")
	)
	(segment
		(start 53.112416 -202.870054)
		(end 53.952648 -203.710286)
		(width 0.14478)
		(layer "In2.Cu")
		(net "M_C_CPU1_SA_DQ<4>")
	)
	(segment
		(start 69.277484 -210.068414)
		(end 69.508116 -210.068414)
		(width 0.14478)
		(layer "In2.Cu")
		(net "M_C_CPU1_SA_DQ<4>")
	)
	(segment
		(start 46.182788 -203.822554)
		(end 46.182788 -203.937616)
		(width 0.14478)
		(layer "In2.Cu")
		(net "M_C_CPU1_SA_DQ<4>")
	)
	(segment
		(start 90.913966 -228.607112)
		(end 90.922348 -228.611938)
		(width 0.0889)
		(layer "In2.Cu")
		(net "M_C_CPU1_SA_DQ<4>")
	)
	(segment
		(start 62.50559 -204.412596)
		(end 62.668658 -204.575664)
		(width 0.14478)
		(layer "In2.Cu")
		(net "M_C_CPU1_SA_DQ<4>")
	)
	(segment
		(start 78.241398 -220.561408)
		(end 78.049374 -220.561408)
		(width 0.14478)
		(layer "In2.Cu")
		(net "M_C_CPU1_SA_DQ<4>")
	)
	(segment
		(start 80.542384 -225.3488)
		(end 80.574134 -225.367088)
		(width 0.0889)
		(layer "In2.Cu")
		(net "M_C_CPU1_SA_DQ<4>")
	)
	(segment
		(start 68.956174 -210.159092)
		(end 69.186806 -210.159092)
		(width 0.14478)
		(layer "In2.Cu")
		(net "M_C_CPU1_SA_DQ<4>")
	)
	(segment
		(start 70.367906 -211.570824)
		(end 70.530974 -211.733892)
		(width 0.14478)
		(layer "In2.Cu")
		(net "M_C_CPU1_SA_DQ<4>")
	)
	(segment
		(start 71.155306 -212.358224)
		(end 77.886306 -219.089224)
		(width 0.14478)
		(layer "In2.Cu")
		(net "M_C_CPU1_SA_DQ<4>")
	)
	(segment
		(start 80.574134 -225.367088)
		(end 80.610456 -225.38817)
		(width 0.0889)
		(layer "In2.Cu")
		(net "M_C_CPU1_SA_DQ<4>")
	)
	(segment
		(start 44.804838 -203.961746)
		(end 44.949618 -204.106526)
		(width 0.14478)
		(layer "In2.Cu")
		(net "M_C_CPU1_SA_DQ<4>")
	)
	(segment
		(start 85.639656 -228.611938)
		(end 85.648038 -228.607112)
		(width 0.0889)
		(layer "In2.Cu")
		(net "M_C_CPU1_SA_DQ<4>")
	)
	(segment
		(start 80.10398 -224.557082)
		(end 80.143096 -224.579942)
		(width 0.0889)
		(layer "In2.Cu")
		(net "M_C_CPU1_SA_DQ<4>")
	)
	(segment
		(start 61.229494 -203.981304)
		(end 61.392562 -204.144372)
		(width 0.14478)
		(layer "In2.Cu")
		(net "M_C_CPU1_SA_DQ<4>")
	)
	(segment
		(start 86.57971 -228.611938)
		(end 86.588092 -228.607112)
		(width 0.0889)
		(layer "In2.Cu")
		(net "M_C_CPU1_SA_DQ<4>")
	)
	(segment
		(start 63.426086 -203.981304)
		(end 68.485766 -209.040984)
		(width 0.14478)
		(layer "In2.Cu")
		(net "M_C_CPU1_SA_DQ<4>")
	)
	(segment
		(start 68.485766 -209.040984)
		(end 68.485766 -209.688684)
		(width 0.14478)
		(layer "In2.Cu")
		(net "M_C_CPU1_SA_DQ<4>")
	)
	(segment
		(start 46.576234 -204.100684)
		(end 46.739302 -203.937616)
		(width 0.14478)
		(layer "In2.Cu")
		(net "M_C_CPU1_SA_DQ<4>")
	)
	(segment
		(start 61.55563 -204.430884)
		(end 61.786008 -204.430884)
		(width 0.14478)
		(layer "In2.Cu")
		(net "M_C_CPU1_SA_DQ<4>")
	)
	(segment
		(start 44.340018 -203.285344)
		(end 44.804838 -203.750164)
		(width 0.14478)
		(layer "In2.Cu")
		(net "M_C_CPU1_SA_DQ<4>")
	)
	(segment
		(start 94.052644 -228.633274)
		(end 94.074996 -228.549962)
		(width 0.0889)
		(layer "In2.Cu")
		(net "M_C_CPU1_SA_DQ<4>")
	)
	(segment
		(start 78.51267 -221.577408)
		(end 78.51267 -221.815406)
		(width 0.0889)
		(layer "In2.Cu")
		(net "M_C_CPU1_SA_DQ<4>")
	)
	(segment
		(start 71.245984 -211.806282)
		(end 71.245984 -212.036914)
		(width 0.14478)
		(layer "In2.Cu")
		(net "M_C_CPU1_SA_DQ<4>")
	)
	(segment
		(start 77.886306 -219.089224)
		(end 77.886306 -219.841826)
		(width 0.14478)
		(layer "In2.Cu")
		(net "M_C_CPU1_SA_DQ<4>")
	)
	(segment
		(start 56.41721 -203.940156)
		(end 56.580278 -204.103224)
		(width 0.14478)
		(layer "In2.Cu")
		(net "M_C_CPU1_SA_DQ<4>")
	)
	(segment
		(start 61.786008 -204.430884)
		(end 61.949076 -204.267816)
		(width 0.14478)
		(layer "In2.Cu")
		(net "M_C_CPU1_SA_DQ<4>")
	)
	(segment
		(start 91.85402 -228.607112)
		(end 91.862402 -228.611938)
		(width 0.0889)
		(layer "In2.Cu")
		(net "M_C_CPU1_SA_DQ<4>")
	)
	(segment
		(start 56.973724 -203.873354)
		(end 57.136792 -203.710286)
		(width 0.14478)
		(layer "In2.Cu")
		(net "M_C_CPU1_SA_DQ<4>")
	)
	(segment
		(start 71.245984 -212.036914)
		(end 71.155306 -212.127592)
		(width 0.14478)
		(layer "In2.Cu")
		(net "M_C_CPU1_SA_DQ<4>")
	)
	(segment
		(start 45.240194 -204.106526)
		(end 45.390054 -203.956666)
		(width 0.14478)
		(layer "In2.Cu")
		(net "M_C_CPU1_SA_DQ<4>")
	)
	(segment
		(start 69.508116 -210.068414)
		(end 69.671184 -210.231482)
		(width 0.14478)
		(layer "In2.Cu")
		(net "M_C_CPU1_SA_DQ<4>")
	)
	(segment
		(start 57.136792 -203.710286)
		(end 57.499504 -203.710286)
		(width 0.14478)
		(layer "In2.Cu")
		(net "M_C_CPU1_SA_DQ<4>")
	)
	(segment
		(start 68.485766 -209.688684)
		(end 68.956174 -210.159092)
		(width 0.14478)
		(layer "In2.Cu")
		(net "M_C_CPU1_SA_DQ<4>")
	)
	(segment
		(start 49.00168 -204.105764)
		(end 49.232058 -204.105764)
		(width 0.14478)
		(layer "In2.Cu")
		(net "M_C_CPU1_SA_DQ<4>")
	)
	(segment
		(start 81.984088 -227.797106)
		(end 82.02041 -227.818188)
		(width 0.0889)
		(layer "In2.Cu")
		(net "M_C_CPU1_SA_DQ<4>")
	)
	(segment
		(start 62.668658 -204.575664)
		(end 62.899036 -204.575664)
		(width 0.14478)
		(layer "In2.Cu")
		(net "M_C_CPU1_SA_DQ<4>")
	)
	(segment
		(start 61.084714 -203.981304)
		(end 61.229494 -203.981304)
		(width 0.14478)
		(layer "In2.Cu")
		(net "M_C_CPU1_SA_DQ<4>")
	)
	(segment
		(start 81.483454 -226.96932)
		(end 81.513934 -226.9871)
		(width 0.0889)
		(layer "In2.Cu")
		(net "M_C_CPU1_SA_DQ<4>")
	)
	(segment
		(start 79.135986 -222.920814)
		(end 79.16418 -222.93707)
		(width 0.0889)
		(layer "In2.Cu")
		(net "M_C_CPU1_SA_DQ<4>")
	)
	(segment
		(start 79.16418 -222.93707)
		(end 79.201772 -222.958914)
		(width 0.0889)
		(layer "In2.Cu")
		(net "M_C_CPU1_SA_DQ<4>")
	)
	(segment
		(start 69.671184 -210.231482)
		(end 69.671184 -210.462114)
		(width 0.14478)
		(layer "In2.Cu")
		(net "M_C_CPU1_SA_DQ<4>")
	)
	(segment
		(start 44.804838 -203.750164)
		(end 44.804838 -203.961746)
		(width 0.14478)
		(layer "In2.Cu")
		(net "M_C_CPU1_SA_DQ<4>")
	)
	(segment
		(start 61.392562 -204.267816)
		(end 61.55563 -204.430884)
		(width 0.14478)
		(layer "In2.Cu")
		(net "M_C_CPU1_SA_DQ<4>")
	)
	(segment
		(start 48.685196 -203.719938)
		(end 48.838612 -203.873354)
		(width 0.14478)
		(layer "In2.Cu")
		(net "M_C_CPU1_SA_DQ<4>")
	)
	(segment
		(start 50.694336 -202.870054)
		(end 53.112416 -202.870054)
		(width 0.14478)
		(layer "In2.Cu")
		(net "M_C_CPU1_SA_DQ<4>")
	)
	(segment
		(start 63.225172 -203.981304)
		(end 63.426086 -203.981304)
		(width 0.14478)
		(layer "In2.Cu")
		(net "M_C_CPU1_SA_DQ<4>")
	)
	(segment
		(start 62.112144 -203.981304)
		(end 62.342522 -203.981304)
		(width 0.14478)
		(layer "In2.Cu")
		(net "M_C_CPU1_SA_DQ<4>")
	)
	(segment
		(start 70.761606 -211.733892)
		(end 70.852284 -211.643214)
		(width 0.14478)
		(layer "In2.Cu")
		(net "M_C_CPU1_SA_DQ<4>")
	)
	(segment
		(start 49.558194 -203.710286)
		(end 49.854104 -203.710286)
		(width 0.14478)
		(layer "In2.Cu")
		(net "M_C_CPU1_SA_DQ<4>")
	)
	(segment
		(start 88.094058 -228.607112)
		(end 88.10244 -228.611938)
		(width 0.0889)
		(layer "In2.Cu")
		(net "M_C_CPU1_SA_DQ<4>")
	)
	(segment
		(start 69.580506 -210.552792)
		(end 69.580506 -210.783424)
		(width 0.14478)
		(layer "In2.Cu")
		(net "M_C_CPU1_SA_DQ<4>")
	)
	(segment
		(start 70.458584 -211.249514)
		(end 70.367906 -211.340192)
		(width 0.14478)
		(layer "In2.Cu")
		(net "M_C_CPU1_SA_DQ<4>")
	)
	(segment
		(start 90.339672 -228.611938)
		(end 90.348054 -228.607112)
		(width 0.0889)
		(layer "In2.Cu")
		(net "M_C_CPU1_SA_DQ<4>")
	)
	(segment
		(start 69.186806 -210.159092)
		(end 69.277484 -210.068414)
		(width 0.14478)
		(layer "In2.Cu")
		(net "M_C_CPU1_SA_DQ<4>")
	)
	(segment
		(start 69.580506 -210.783424)
		(end 69.743574 -210.946492)
		(width 0.14478)
		(layer "In2.Cu")
		(net "M_C_CPU1_SA_DQ<4>")
	)
	(segment
		(start 78.049374 -220.004894)
		(end 78.241398 -220.004894)
		(width 0.14478)
		(layer "In2.Cu")
		(net "M_C_CPU1_SA_DQ<4>")
	)
	(segment
		(start 56.973724 -203.940156)
		(end 56.973724 -203.873354)
		(width 0.14478)
		(layer "In2.Cu")
		(net "M_C_CPU1_SA_DQ<4>")
	)
	(segment
		(start 49.395126 -203.942696)
		(end 49.395126 -203.873354)
		(width 0.14478)
		(layer "In2.Cu")
		(net "M_C_CPU1_SA_DQ<4>")
	)
	(segment
		(start 58.349388 -202.860402)
		(end 60.238386 -202.860402)
		(width 0.14478)
		(layer "In2.Cu")
		(net "M_C_CPU1_SA_DQ<4>")
	)
	(segment
		(start 70.852284 -211.643214)
		(end 71.082916 -211.643214)
		(width 0.14478)
		(layer "In2.Cu")
		(net "M_C_CPU1_SA_DQ<4>")
	)
	(arc
		(start 90.922348 -228.611938)
		(mid 91.105856 -228.657432)
		(end 91.288108 -228.607112)
		(width 0.0889)
		(layer "In2.Cu")
		(net "M_C_CPU1_SA_DQ<4>")
	)
	(arc
		(start 93.167962 -228.607112)
		(mid 93.450918 -228.530935)
		(end 93.733874 -228.607112)
		(width 0.0889)
		(layer "In2.Cu")
		(net "M_C_CPU1_SA_DQ<4>")
	)
	(arc
		(start 83.768184 -228.607112)
		(mid 84.05114 -228.530935)
		(end 84.334096 -228.607112)
		(width 0.0889)
		(layer "In2.Cu")
		(net "M_C_CPU1_SA_DQ<4>")
	)
	(arc
		(start 80.143096 -224.579942)
		(mid 80.321909 -224.782292)
		(end 80.386428 -225.044508)
		(width 0.0889)
		(layer "In2.Cu")
		(net "M_C_CPU1_SA_DQ<4>")
	)
	(arc
		(start 81.326482 -226.66452)
		(mid 81.368031 -226.835942)
		(end 81.483454 -226.96932)
		(width 0.0889)
		(layer "In2.Cu")
		(net "M_C_CPU1_SA_DQ<4>")
	)
	(arc
		(start 82.02041 -227.818188)
		(mid 82.201062 -228.020933)
		(end 82.266282 -228.284532)
		(width 0.0889)
		(layer "In2.Cu")
		(net "M_C_CPU1_SA_DQ<4>")
	)
	(arc
		(start 79.446374 -223.424496)
		(mid 79.487132 -223.594494)
		(end 79.600552 -223.727518)
		(width 0.0889)
		(layer "In2.Cu")
		(net "M_C_CPU1_SA_DQ<4>")
	)
	(arc
		(start 86.588092 -228.607112)
		(mid 86.871048 -228.530935)
		(end 87.154004 -228.607112)
		(width 0.0889)
		(layer "In2.Cu")
		(net "M_C_CPU1_SA_DQ<4>")
	)
	(arc
		(start 85.273896 -228.607112)
		(mid 85.456147 -228.657462)
		(end 85.639656 -228.611938)
		(width 0.0889)
		(layer "In2.Cu")
		(net "M_C_CPU1_SA_DQ<4>")
	)
	(arc
		(start 89.973912 -228.607112)
		(mid 90.156163 -228.657462)
		(end 90.339672 -228.611938)
		(width 0.0889)
		(layer "In2.Cu")
		(net "M_C_CPU1_SA_DQ<4>")
	)
	(arc
		(start 79.916782 -224.234502)
		(mid 79.958895 -224.407076)
		(end 80.075786 -224.540826)
		(width 0.0889)
		(layer "In2.Cu")
		(net "M_C_CPU1_SA_DQ<4>")
	)
	(arc
		(start 80.610456 -225.38817)
		(mid 80.791108 -225.590915)
		(end 80.856328 -225.854514)
		(width 0.0889)
		(layer "In2.Cu")
		(net "M_C_CPU1_SA_DQ<4>")
	)
	(arc
		(start 85.648038 -228.607112)
		(mid 85.930994 -228.530935)
		(end 86.21395 -228.607112)
		(width 0.0889)
		(layer "In2.Cu")
		(net "M_C_CPU1_SA_DQ<4>")
	)
	(arc
		(start 82.46237 -228.611938)
		(mid 82.645878 -228.657432)
		(end 82.82813 -228.607112)
		(width 0.0889)
		(layer "In2.Cu")
		(net "M_C_CPU1_SA_DQ<4>")
	)
	(arc
		(start 80.856328 -225.854514)
		(mid 80.897583 -226.025485)
		(end 81.012284 -226.158806)
		(width 0.0889)
		(layer "In2.Cu")
		(net "M_C_CPU1_SA_DQ<4>")
	)
	(arc
		(start 84.707984 -228.607112)
		(mid 84.99094 -228.530935)
		(end 85.273896 -228.607112)
		(width 0.0889)
		(layer "In2.Cu")
		(net "M_C_CPU1_SA_DQ<4>")
	)
	(arc
		(start 92.794074 -228.607112)
		(mid 92.981018 -228.657367)
		(end 93.167962 -228.607112)
		(width 0.0889)
		(layer "In2.Cu")
		(net "M_C_CPU1_SA_DQ<4>")
	)
	(arc
		(start 84.334096 -228.607112)
		(mid 84.52104 -228.657367)
		(end 84.707984 -228.607112)
		(width 0.0889)
		(layer "In2.Cu")
		(net "M_C_CPU1_SA_DQ<4>")
	)
	(arc
		(start 92.228162 -228.607112)
		(mid 92.511118 -228.530935)
		(end 92.794074 -228.607112)
		(width 0.0889)
		(layer "In2.Cu")
		(net "M_C_CPU1_SA_DQ<4>")
	)
	(arc
		(start 80.386428 -225.044508)
		(mid 80.427683 -225.215479)
		(end 80.542384 -225.3488)
		(width 0.0889)
		(layer "In2.Cu")
		(net "M_C_CPU1_SA_DQ<4>")
	)
	(arc
		(start 93.733874 -228.607112)
		(mid 93.890312 -228.656083)
		(end 94.052644 -228.633274)
		(width 0.0889)
		(layer "In2.Cu")
		(net "M_C_CPU1_SA_DQ<4>")
	)
	(arc
		(start 89.034112 -228.607112)
		(mid 89.221056 -228.657367)
		(end 89.408 -228.607112)
		(width 0.0889)
		(layer "In2.Cu")
		(net "M_C_CPU1_SA_DQ<4>")
	)
	(arc
		(start 91.862402 -228.611938)
		(mid 92.04591 -228.657432)
		(end 92.228162 -228.607112)
		(width 0.0889)
		(layer "In2.Cu")
		(net "M_C_CPU1_SA_DQ<4>")
	)
	(arc
		(start 81.55305 -227.00996)
		(mid 81.731863 -227.21231)
		(end 81.796382 -227.474526)
		(width 0.0889)
		(layer "In2.Cu")
		(net "M_C_CPU1_SA_DQ<4>")
	)
	(arc
		(start 78.730856 -222.148146)
		(mid 78.911665 -222.350839)
		(end 78.976982 -222.61449)
		(width 0.0889)
		(layer "In2.Cu")
		(net "M_C_CPU1_SA_DQ<4>")
	)
	(arc
		(start 86.21395 -228.607112)
		(mid 86.396201 -228.657462)
		(end 86.57971 -228.611938)
		(width 0.0889)
		(layer "In2.Cu")
		(net "M_C_CPU1_SA_DQ<4>")
	)
	(arc
		(start 89.408 -228.607112)
		(mid 89.690956 -228.530935)
		(end 89.973912 -228.607112)
		(width 0.0889)
		(layer "In2.Cu")
		(net "M_C_CPU1_SA_DQ<4>")
	)
	(arc
		(start 78.976982 -222.61449)
		(mid 79.019095 -222.787064)
		(end 79.135986 -222.920814)
		(width 0.0889)
		(layer "In2.Cu")
		(net "M_C_CPU1_SA_DQ<4>")
	)
	(arc
		(start 81.796382 -227.474526)
		(mid 81.837637 -227.645497)
		(end 81.952338 -227.778818)
		(width 0.0889)
		(layer "In2.Cu")
		(net "M_C_CPU1_SA_DQ<4>")
	)
	(arc
		(start 87.528146 -228.607112)
		(mid 87.811102 -228.530935)
		(end 88.094058 -228.607112)
		(width 0.0889)
		(layer "In2.Cu")
		(net "M_C_CPU1_SA_DQ<4>")
	)
	(arc
		(start 79.67218 -223.76892)
		(mid 79.851909 -223.97154)
		(end 79.916782 -224.234502)
		(width 0.0889)
		(layer "In2.Cu")
		(net "M_C_CPU1_SA_DQ<4>")
	)
	(arc
		(start 83.402424 -228.611938)
		(mid 83.585932 -228.657432)
		(end 83.768184 -228.607112)
		(width 0.0889)
		(layer "In2.Cu")
		(net "M_C_CPU1_SA_DQ<4>")
	)
	(arc
		(start 88.10244 -228.611938)
		(mid 88.285948 -228.657432)
		(end 88.4682 -228.607112)
		(width 0.0889)
		(layer "In2.Cu")
		(net "M_C_CPU1_SA_DQ<4>")
	)
	(arc
		(start 82.82813 -228.607112)
		(mid 83.111086 -228.530935)
		(end 83.394042 -228.607112)
		(width 0.0889)
		(layer "In2.Cu")
		(net "M_C_CPU1_SA_DQ<4>")
	)
	(arc
		(start 79.201772 -222.958914)
		(mid 79.381501 -223.161534)
		(end 79.446374 -223.424496)
		(width 0.0889)
		(layer "In2.Cu")
		(net "M_C_CPU1_SA_DQ<4>")
	)
	(arc
		(start 88.4682 -228.607112)
		(mid 88.751156 -228.530935)
		(end 89.034112 -228.607112)
		(width 0.0889)
		(layer "In2.Cu")
		(net "M_C_CPU1_SA_DQ<4>")
	)
	(arc
		(start 78.617318 -222.068136)
		(mid 78.653874 -222.1)
		(end 78.69428 -222.12681)
		(width 0.0889)
		(layer "In2.Cu")
		(net "M_C_CPU1_SA_DQ<4>")
	)
	(arc
		(start 78.51267 -221.815406)
		(mid 78.539874 -221.952169)
		(end 78.617318 -222.068136)
		(width 0.0889)
		(layer "In2.Cu")
		(net "M_C_CPU1_SA_DQ<4>")
	)
	(arc
		(start 91.288108 -228.607112)
		(mid 91.571064 -228.530935)
		(end 91.85402 -228.607112)
		(width 0.0889)
		(layer "In2.Cu")
		(net "M_C_CPU1_SA_DQ<4>")
	)
	(arc
		(start 90.348054 -228.607112)
		(mid 90.63101 -228.530935)
		(end 90.913966 -228.607112)
		(width 0.0889)
		(layer "In2.Cu")
		(net "M_C_CPU1_SA_DQ<4>")
	)
	(arc
		(start 81.08315 -226.199954)
		(mid 81.261963 -226.402304)
		(end 81.326482 -226.66452)
		(width 0.0889)
		(layer "In2.Cu")
		(net "M_C_CPU1_SA_DQ<4>")
	)
	(arc
		(start 82.266282 -228.284532)
		(mid 82.307537 -228.455503)
		(end 82.422238 -228.588824)
		(width 0.0889)
		(layer "In2.Cu")
		(net "M_C_CPU1_SA_DQ<4>")
	)
	(arc
		(start 87.162386 -228.611938)
		(mid 87.345894 -228.657432)
		(end 87.528146 -228.607112)
		(width 0.0889)
		(layer "In2.Cu")
		(net "M_C_CPU1_SA_DQ<4>")
	)
	(segment
		(start 96.267778 -226.930458)
		(end 95.800926 -226.66452)
		(width 0.10668)
		(layer "F.Cu")
		(net "M_C_CPU1_SA_DQ<3>")
	)
	(segment
		(start 83.29803 -225.531934)
		(end 83.32978 -225.550222)
		(width 0.0889)
		(layer "In2.Cu")
		(net "M_C_CPU1_SA_DQ<3>")
	)
	(segment
		(start 41.937432 -198.999094)
		(end 42.1005 -198.836026)
		(width 0.14478)
		(layer "In2.Cu")
		(net "M_C_CPU1_SA_DQ<3>")
	)
	(segment
		(start 81.605628 -222.443294)
		(end 81.605628 -222.61449)
		(width 0.0889)
		(layer "In2.Cu")
		(net "M_C_CPU1_SA_DQ<3>")
	)
	(segment
		(start 42.493946 -199.29729)
		(end 42.647362 -199.450706)
		(width 0.14478)
		(layer "In2.Cu")
		(net "M_C_CPU1_SA_DQ<3>")
	)
	(segment
		(start 83.729068 -226.31908)
		(end 83.768184 -226.34194)
		(width 0.0889)
		(layer "In2.Cu")
		(net "M_C_CPU1_SA_DQ<3>")
	)
	(segment
		(start 95.55099 -226.37369)
		(end 95.647002 -226.39909)
		(width 0.0889)
		(layer "In2.Cu")
		(net "M_C_CPU1_SA_DQ<3>")
	)
	(segment
		(start 87.154004 -226.34194)
		(end 87.162386 -226.337114)
		(width 0.0889)
		(layer "In2.Cu")
		(net "M_C_CPU1_SA_DQ<3>")
	)
	(segment
		(start 83.258914 -225.509074)
		(end 83.29803 -225.531934)
		(width 0.0889)
		(layer "In2.Cu")
		(net "M_C_CPU1_SA_DQ<3>")
	)
	(segment
		(start 86.57971 -226.337114)
		(end 86.588092 -226.34194)
		(width 0.0889)
		(layer "In2.Cu")
		(net "M_C_CPU1_SA_DQ<3>")
	)
	(segment
		(start 40.23995 -199.8853)
		(end 40.664892 -199.460358)
		(width 0.14478)
		(layer "In2.Cu")
		(net "M_C_CPU1_SA_DQ<3>")
	)
	(segment
		(start 81.131918 -218.974162)
		(end 81.131918 -221.215204)
		(width 0.14478)
		(layer "In2.Cu")
		(net "M_C_CPU1_SA_DQ<3>")
	)
	(segment
		(start 42.330878 -198.836026)
		(end 42.493946 -198.999094)
		(width 0.14478)
		(layer "In2.Cu")
		(net "M_C_CPU1_SA_DQ<3>")
	)
	(segment
		(start 95.039688 -226.337114)
		(end 95.04807 -226.34194)
		(width 0.0889)
		(layer "In2.Cu")
		(net "M_C_CPU1_SA_DQ<3>")
	)
	(segment
		(start 81.888076 -223.101916)
		(end 81.919826 -223.120204)
		(width 0.0889)
		(layer "In2.Cu")
		(net "M_C_CPU1_SA_DQ<3>")
	)
	(segment
		(start 40.664892 -199.460358)
		(end 41.774364 -199.460358)
		(width 0.14478)
		(layer "In2.Cu")
		(net "M_C_CPU1_SA_DQ<3>")
	)
	(segment
		(start 82.82813 -224.721928)
		(end 82.85861 -224.739708)
		(width 0.0889)
		(layer "In2.Cu")
		(net "M_C_CPU1_SA_DQ<3>")
	)
	(segment
		(start 42.1005 -198.836026)
		(end 42.330878 -198.836026)
		(width 0.14478)
		(layer "In2.Cu")
		(net "M_C_CPU1_SA_DQ<3>")
	)
	(segment
		(start 76.148692 -212.251036)
		(end 76.148692 -213.990936)
		(width 0.14478)
		(layer "In2.Cu")
		(net "M_C_CPU1_SA_DQ<3>")
	)
	(segment
		(start 90.339672 -226.337114)
		(end 90.348054 -226.34194)
		(width 0.0889)
		(layer "In2.Cu")
		(net "M_C_CPU1_SA_DQ<3>")
	)
	(segment
		(start 81.131918 -221.969584)
		(end 81.605628 -222.443294)
		(width 0.0889)
		(layer "In2.Cu")
		(net "M_C_CPU1_SA_DQ<3>")
	)
	(segment
		(start 72.888094 -210.054698)
		(end 73.952354 -210.054698)
		(width 0.14478)
		(layer "In2.Cu")
		(net "M_C_CPU1_SA_DQ<3>")
	)
	(segment
		(start 95.647002 -226.39909)
		(end 95.800926 -226.66452)
		(width 0.0889)
		(layer "In2.Cu")
		(net "M_C_CPU1_SA_DQ<3>")
	)
	(segment
		(start 42.493946 -198.999094)
		(end 42.493946 -199.29729)
		(width 0.14478)
		(layer "In2.Cu")
		(net "M_C_CPU1_SA_DQ<3>")
	)
	(segment
		(start 73.952354 -210.054698)
		(end 76.148692 -212.251036)
		(width 0.14478)
		(layer "In2.Cu")
		(net "M_C_CPU1_SA_DQ<3>")
	)
	(segment
		(start 81.131918 -221.215204)
		(end 81.131918 -221.969584)
		(width 0.0889)
		(layer "In2.Cu")
		(net "M_C_CPU1_SA_DQ<3>")
	)
	(segment
		(start 82.789014 -224.699068)
		(end 82.82813 -224.721928)
		(width 0.0889)
		(layer "In2.Cu")
		(net "M_C_CPU1_SA_DQ<3>")
	)
	(segment
		(start 62.284102 -199.450706)
		(end 72.888094 -210.054698)
		(width 0.14478)
		(layer "In2.Cu")
		(net "M_C_CPU1_SA_DQ<3>")
	)
	(segment
		(start 42.647362 -199.450706)
		(end 62.284102 -199.450706)
		(width 0.14478)
		(layer "In2.Cu")
		(net "M_C_CPU1_SA_DQ<3>")
	)
	(segment
		(start 94.099634 -226.337114)
		(end 94.108016 -226.34194)
		(width 0.0889)
		(layer "In2.Cu")
		(net "M_C_CPU1_SA_DQ<3>")
	)
	(segment
		(start 81.84896 -223.079056)
		(end 81.888076 -223.101916)
		(width 0.0889)
		(layer "In2.Cu")
		(net "M_C_CPU1_SA_DQ<3>")
	)
	(segment
		(start 76.148692 -213.990936)
		(end 81.131918 -218.974162)
		(width 0.14478)
		(layer "In2.Cu")
		(net "M_C_CPU1_SA_DQ<3>")
	)
	(segment
		(start 91.85402 -226.34194)
		(end 91.862402 -226.337114)
		(width 0.0889)
		(layer "In2.Cu")
		(net "M_C_CPU1_SA_DQ<3>")
	)
	(segment
		(start 41.774364 -199.460358)
		(end 41.937432 -199.29729)
		(width 0.14478)
		(layer "In2.Cu")
		(net "M_C_CPU1_SA_DQ<3>")
	)
	(segment
		(start 82.357976 -223.911922)
		(end 82.389726 -223.93021)
		(width 0.0889)
		(layer "In2.Cu")
		(net "M_C_CPU1_SA_DQ<3>")
	)
	(segment
		(start 41.937432 -199.29729)
		(end 41.937432 -198.999094)
		(width 0.14478)
		(layer "In2.Cu")
		(net "M_C_CPU1_SA_DQ<3>")
	)
	(segment
		(start 90.913966 -226.34194)
		(end 90.922348 -226.337114)
		(width 0.0889)
		(layer "In2.Cu")
		(net "M_C_CPU1_SA_DQ<3>")
	)
	(segment
		(start 82.321654 -223.89084)
		(end 82.357976 -223.911922)
		(width 0.0889)
		(layer "In2.Cu")
		(net "M_C_CPU1_SA_DQ<3>")
	)
	(segment
		(start 85.639656 -226.337114)
		(end 85.648038 -226.34194)
		(width 0.0889)
		(layer "In2.Cu")
		(net "M_C_CPU1_SA_DQ<3>")
	)
	(segment
		(start 88.094058 -226.34194)
		(end 88.10244 -226.337114)
		(width 0.0889)
		(layer "In2.Cu")
		(net "M_C_CPU1_SA_DQ<3>")
	)
	(arc
		(start 93.733874 -226.34194)
		(mid 93.916125 -226.29159)
		(end 94.099634 -226.337114)
		(width 0.0889)
		(layer "In2.Cu")
		(net "M_C_CPU1_SA_DQ<3>")
	)
	(arc
		(start 89.973912 -226.34194)
		(mid 90.156163 -226.29159)
		(end 90.339672 -226.337114)
		(width 0.0889)
		(layer "In2.Cu")
		(net "M_C_CPU1_SA_DQ<3>")
	)
	(arc
		(start 83.32978 -225.550222)
		(mid 83.444456 -225.683556)
		(end 83.485736 -225.854514)
		(width 0.0889)
		(layer "In2.Cu")
		(net "M_C_CPU1_SA_DQ<3>")
	)
	(arc
		(start 91.288108 -226.34194)
		(mid 91.571064 -226.418117)
		(end 91.85402 -226.34194)
		(width 0.0889)
		(layer "In2.Cu")
		(net "M_C_CPU1_SA_DQ<3>")
	)
	(arc
		(start 82.389726 -223.93021)
		(mid 82.504402 -224.063544)
		(end 82.545682 -224.234502)
		(width 0.0889)
		(layer "In2.Cu")
		(net "M_C_CPU1_SA_DQ<3>")
	)
	(arc
		(start 85.648038 -226.34194)
		(mid 85.930994 -226.418117)
		(end 86.21395 -226.34194)
		(width 0.0889)
		(layer "In2.Cu")
		(net "M_C_CPU1_SA_DQ<3>")
	)
	(arc
		(start 89.034112 -226.34194)
		(mid 89.221056 -226.291685)
		(end 89.408 -226.34194)
		(width 0.0889)
		(layer "In2.Cu")
		(net "M_C_CPU1_SA_DQ<3>")
	)
	(arc
		(start 81.919826 -223.120204)
		(mid 82.034502 -223.253538)
		(end 82.075782 -223.424496)
		(width 0.0889)
		(layer "In2.Cu")
		(net "M_C_CPU1_SA_DQ<3>")
	)
	(arc
		(start 88.10244 -226.337114)
		(mid 88.285948 -226.29162)
		(end 88.4682 -226.34194)
		(width 0.0889)
		(layer "In2.Cu")
		(net "M_C_CPU1_SA_DQ<3>")
	)
	(arc
		(start 92.228162 -226.34194)
		(mid 92.511118 -226.418117)
		(end 92.794074 -226.34194)
		(width 0.0889)
		(layer "In2.Cu")
		(net "M_C_CPU1_SA_DQ<3>")
	)
	(arc
		(start 87.528146 -226.34194)
		(mid 87.811102 -226.418117)
		(end 88.094058 -226.34194)
		(width 0.0889)
		(layer "In2.Cu")
		(net "M_C_CPU1_SA_DQ<3>")
	)
	(arc
		(start 83.015582 -225.044508)
		(mid 83.080097 -225.306727)
		(end 83.258914 -225.509074)
		(width 0.0889)
		(layer "In2.Cu")
		(net "M_C_CPU1_SA_DQ<3>")
	)
	(arc
		(start 91.862402 -226.337114)
		(mid 92.04591 -226.29162)
		(end 92.228162 -226.34194)
		(width 0.0889)
		(layer "In2.Cu")
		(net "M_C_CPU1_SA_DQ<3>")
	)
	(arc
		(start 82.075782 -223.424496)
		(mid 82.141018 -223.688087)
		(end 82.321654 -223.89084)
		(width 0.0889)
		(layer "In2.Cu")
		(net "M_C_CPU1_SA_DQ<3>")
	)
	(arc
		(start 95.04807 -226.34194)
		(mid 95.295783 -226.41716)
		(end 95.55099 -226.37369)
		(width 0.0889)
		(layer "In2.Cu")
		(net "M_C_CPU1_SA_DQ<3>")
	)
	(arc
		(start 82.85861 -224.739708)
		(mid 82.974037 -224.873084)
		(end 83.015582 -225.044508)
		(width 0.0889)
		(layer "In2.Cu")
		(net "M_C_CPU1_SA_DQ<3>")
	)
	(arc
		(start 85.273896 -226.34194)
		(mid 85.456147 -226.29159)
		(end 85.639656 -226.337114)
		(width 0.0889)
		(layer "In2.Cu")
		(net "M_C_CPU1_SA_DQ<3>")
	)
	(arc
		(start 90.922348 -226.337114)
		(mid 91.105856 -226.29162)
		(end 91.288108 -226.34194)
		(width 0.0889)
		(layer "In2.Cu")
		(net "M_C_CPU1_SA_DQ<3>")
	)
	(arc
		(start 87.162386 -226.337114)
		(mid 87.345894 -226.29162)
		(end 87.528146 -226.34194)
		(width 0.0889)
		(layer "In2.Cu")
		(net "M_C_CPU1_SA_DQ<3>")
	)
	(arc
		(start 86.588092 -226.34194)
		(mid 86.871048 -226.418117)
		(end 87.154004 -226.34194)
		(width 0.0889)
		(layer "In2.Cu")
		(net "M_C_CPU1_SA_DQ<3>")
	)
	(arc
		(start 92.794074 -226.34194)
		(mid 92.981018 -226.291685)
		(end 93.167962 -226.34194)
		(width 0.0889)
		(layer "In2.Cu")
		(net "M_C_CPU1_SA_DQ<3>")
	)
	(arc
		(start 83.485736 -225.854514)
		(mid 83.550251 -226.116733)
		(end 83.729068 -226.31908)
		(width 0.0889)
		(layer "In2.Cu")
		(net "M_C_CPU1_SA_DQ<3>")
	)
	(arc
		(start 84.707984 -226.34194)
		(mid 84.99094 -226.418117)
		(end 85.273896 -226.34194)
		(width 0.0889)
		(layer "In2.Cu")
		(net "M_C_CPU1_SA_DQ<3>")
	)
	(arc
		(start 81.605628 -222.61449)
		(mid 81.670143 -222.876709)
		(end 81.84896 -223.079056)
		(width 0.0889)
		(layer "In2.Cu")
		(net "M_C_CPU1_SA_DQ<3>")
	)
	(arc
		(start 94.108016 -226.34194)
		(mid 94.390972 -226.418117)
		(end 94.673928 -226.34194)
		(width 0.0889)
		(layer "In2.Cu")
		(net "M_C_CPU1_SA_DQ<3>")
	)
	(arc
		(start 88.4682 -226.34194)
		(mid 88.751156 -226.418117)
		(end 89.034112 -226.34194)
		(width 0.0889)
		(layer "In2.Cu")
		(net "M_C_CPU1_SA_DQ<3>")
	)
	(arc
		(start 86.21395 -226.34194)
		(mid 86.396201 -226.29159)
		(end 86.57971 -226.337114)
		(width 0.0889)
		(layer "In2.Cu")
		(net "M_C_CPU1_SA_DQ<3>")
	)
	(arc
		(start 90.348054 -226.34194)
		(mid 90.63101 -226.418117)
		(end 90.913966 -226.34194)
		(width 0.0889)
		(layer "In2.Cu")
		(net "M_C_CPU1_SA_DQ<3>")
	)
	(arc
		(start 89.408 -226.34194)
		(mid 89.690956 -226.418117)
		(end 89.973912 -226.34194)
		(width 0.0889)
		(layer "In2.Cu")
		(net "M_C_CPU1_SA_DQ<3>")
	)
	(arc
		(start 93.167962 -226.34194)
		(mid 93.450918 -226.418117)
		(end 93.733874 -226.34194)
		(width 0.0889)
		(layer "In2.Cu")
		(net "M_C_CPU1_SA_DQ<3>")
	)
	(arc
		(start 94.673928 -226.34194)
		(mid 94.856179 -226.29159)
		(end 95.039688 -226.337114)
		(width 0.0889)
		(layer "In2.Cu")
		(net "M_C_CPU1_SA_DQ<3>")
	)
	(arc
		(start 84.334096 -226.34194)
		(mid 84.52104 -226.291685)
		(end 84.707984 -226.34194)
		(width 0.0889)
		(layer "In2.Cu")
		(net "M_C_CPU1_SA_DQ<3>")
	)
	(arc
		(start 83.768184 -226.34194)
		(mid 84.05114 -226.418117)
		(end 84.334096 -226.34194)
		(width 0.0889)
		(layer "In2.Cu")
		(net "M_C_CPU1_SA_DQ<3>")
	)
	(arc
		(start 82.545682 -224.234502)
		(mid 82.610197 -224.496721)
		(end 82.789014 -224.699068)
		(width 0.0889)
		(layer "In2.Cu")
		(net "M_C_CPU1_SA_DQ<3>")
	)
	(segment
		(start 96.267778 -244.750336)
		(end 95.800926 -244.484398)
		(width 0.10668)
		(layer "F.Cu")
		(net "M_C_CPU1_SA_DQ<31>")
	)
	(segment
		(start 95.647002 -244.218968)
		(end 95.800926 -244.484398)
		(width 0.0889)
		(layer "In2.Cu")
		(net "M_C_CPU1_SA_DQ<31>")
	)
	(segment
		(start 66.776346 -239.858804)
		(end 67.5767 -239.858804)
		(width 0.14478)
		(layer "In2.Cu")
		(net "M_C_CPU1_SA_DQ<31>")
	)
	(segment
		(start 78.130146 -244.162072)
		(end 78.169516 -244.184932)
		(width 0.0889)
		(layer "In2.Cu")
		(net "M_C_CPU1_SA_DQ<31>")
	)
	(segment
		(start 90.913966 -244.161818)
		(end 90.922348 -244.156992)
		(width 0.0889)
		(layer "In2.Cu")
		(net "M_C_CPU1_SA_DQ<31>")
	)
	(segment
		(start 41.95953 -233.343704)
		(end 42.189908 -233.343704)
		(width 0.14478)
		(layer "In2.Cu")
		(net "M_C_CPU1_SA_DQ<31>")
	)
	(segment
		(start 42.516044 -234.310428)
		(end 49.428146 -234.310428)
		(width 0.14478)
		(layer "In2.Cu")
		(net "M_C_CPU1_SA_DQ<31>")
	)
	(segment
		(start 86.57971 -244.156992)
		(end 86.588092 -244.161818)
		(width 0.0889)
		(layer "In2.Cu")
		(net "M_C_CPU1_SA_DQ<31>")
	)
	(segment
		(start 94.099634 -244.156992)
		(end 94.108016 -244.161818)
		(width 0.0889)
		(layer "In2.Cu")
		(net "M_C_CPU1_SA_DQ<31>")
	)
	(segment
		(start 41.633394 -234.310428)
		(end 41.796462 -234.14736)
		(width 0.14478)
		(layer "In2.Cu")
		(net "M_C_CPU1_SA_DQ<31>")
	)
	(segment
		(start 57.766458 -233.46029)
		(end 60.377832 -233.46029)
		(width 0.14478)
		(layer "In2.Cu")
		(net "M_C_CPU1_SA_DQ<31>")
	)
	(segment
		(start 49.428146 -234.310428)
		(end 50.278284 -233.46029)
		(width 0.14478)
		(layer "In2.Cu")
		(net "M_C_CPU1_SA_DQ<31>")
	)
	(segment
		(start 95.039688 -244.156992)
		(end 95.04807 -244.161818)
		(width 0.0889)
		(layer "In2.Cu")
		(net "M_C_CPU1_SA_DQ<31>")
	)
	(segment
		(start 42.352976 -233.506772)
		(end 42.352976 -234.14736)
		(width 0.14478)
		(layer "In2.Cu")
		(net "M_C_CPU1_SA_DQ<31>")
	)
	(segment
		(start 83.394042 -244.161818)
		(end 83.402424 -244.156992)
		(width 0.0889)
		(layer "In2.Cu")
		(net "M_C_CPU1_SA_DQ<31>")
	)
	(segment
		(start 60.377832 -233.46029)
		(end 66.776346 -239.858804)
		(width 0.14478)
		(layer "In2.Cu")
		(net "M_C_CPU1_SA_DQ<31>")
	)
	(segment
		(start 79.63535 -244.162072)
		(end 79.658718 -244.14861)
		(width 0.0889)
		(layer "In2.Cu")
		(net "M_C_CPU1_SA_DQ<31>")
	)
	(segment
		(start 70.9422 -243.224304)
		(end 75.953366 -243.224304)
		(width 0.14478)
		(layer "In2.Cu")
		(net "M_C_CPU1_SA_DQ<31>")
	)
	(segment
		(start 79.050896 -244.14988)
		(end 79.07147 -244.161818)
		(width 0.0889)
		(layer "In2.Cu")
		(net "M_C_CPU1_SA_DQ<31>")
	)
	(segment
		(start 87.154004 -244.161818)
		(end 87.162386 -244.156992)
		(width 0.0889)
		(layer "In2.Cu")
		(net "M_C_CPU1_SA_DQ<31>")
	)
	(segment
		(start 82.453988 -244.161818)
		(end 82.46237 -244.156992)
		(width 0.0889)
		(layer "In2.Cu")
		(net "M_C_CPU1_SA_DQ<31>")
	)
	(segment
		(start 53.961792 -234.310428)
		(end 56.91632 -234.310428)
		(width 0.14478)
		(layer "In2.Cu")
		(net "M_C_CPU1_SA_DQ<31>")
	)
	(segment
		(start 53.111654 -233.46029)
		(end 53.961792 -234.310428)
		(width 0.14478)
		(layer "In2.Cu")
		(net "M_C_CPU1_SA_DQ<31>")
	)
	(segment
		(start 56.91632 -234.310428)
		(end 57.766458 -233.46029)
		(width 0.14478)
		(layer "In2.Cu")
		(net "M_C_CPU1_SA_DQ<31>")
	)
	(segment
		(start 79.609188 -244.177058)
		(end 79.63535 -244.162072)
		(width 0.0889)
		(layer "In2.Cu")
		(net "M_C_CPU1_SA_DQ<31>")
	)
	(segment
		(start 76.847446 -244.118384)
		(end 77.96784 -244.118384)
		(width 0.0889)
		(layer "In2.Cu")
		(net "M_C_CPU1_SA_DQ<31>")
	)
	(segment
		(start 81.879694 -244.156992)
		(end 81.888076 -244.161818)
		(width 0.0889)
		(layer "In2.Cu")
		(net "M_C_CPU1_SA_DQ<31>")
	)
	(segment
		(start 88.094058 -244.161818)
		(end 88.10244 -244.156992)
		(width 0.0889)
		(layer "In2.Cu")
		(net "M_C_CPU1_SA_DQ<31>")
	)
	(segment
		(start 42.352976 -234.14736)
		(end 42.516044 -234.310428)
		(width 0.14478)
		(layer "In2.Cu")
		(net "M_C_CPU1_SA_DQ<31>")
	)
	(segment
		(start 40.665146 -234.310428)
		(end 41.633394 -234.310428)
		(width 0.14478)
		(layer "In2.Cu")
		(net "M_C_CPU1_SA_DQ<31>")
	)
	(segment
		(start 41.796462 -234.14736)
		(end 41.796462 -233.506772)
		(width 0.14478)
		(layer "In2.Cu")
		(net "M_C_CPU1_SA_DQ<31>")
	)
	(segment
		(start 95.55099 -244.193568)
		(end 95.647002 -244.218968)
		(width 0.0889)
		(layer "In2.Cu")
		(net "M_C_CPU1_SA_DQ<31>")
	)
	(segment
		(start 50.278284 -233.46029)
		(end 53.111654 -233.46029)
		(width 0.14478)
		(layer "In2.Cu")
		(net "M_C_CPU1_SA_DQ<31>")
	)
	(segment
		(start 42.189908 -233.343704)
		(end 42.352976 -233.506772)
		(width 0.14478)
		(layer "In2.Cu")
		(net "M_C_CPU1_SA_DQ<31>")
	)
	(segment
		(start 41.796462 -233.506772)
		(end 41.95953 -233.343704)
		(width 0.14478)
		(layer "In2.Cu")
		(net "M_C_CPU1_SA_DQ<31>")
	)
	(segment
		(start 90.339672 -244.156992)
		(end 90.348054 -244.161818)
		(width 0.0889)
		(layer "In2.Cu")
		(net "M_C_CPU1_SA_DQ<31>")
	)
	(segment
		(start 85.639656 -244.156992)
		(end 85.648038 -244.161818)
		(width 0.0889)
		(layer "In2.Cu")
		(net "M_C_CPU1_SA_DQ<31>")
	)
	(segment
		(start 67.5767 -239.858804)
		(end 70.9422 -243.224304)
		(width 0.14478)
		(layer "In2.Cu")
		(net "M_C_CPU1_SA_DQ<31>")
	)
	(segment
		(start 91.85402 -244.161818)
		(end 91.862402 -244.156992)
		(width 0.0889)
		(layer "In2.Cu")
		(net "M_C_CPU1_SA_DQ<31>")
	)
	(segment
		(start 40.23995 -233.885232)
		(end 40.665146 -234.310428)
		(width 0.14478)
		(layer "In2.Cu")
		(net "M_C_CPU1_SA_DQ<31>")
	)
	(segment
		(start 75.953366 -243.224304)
		(end 76.847446 -244.118384)
		(width 0.0889)
		(layer "In2.Cu")
		(net "M_C_CPU1_SA_DQ<31>")
	)
	(arc
		(start 83.402424 -244.156992)
		(mid 83.585932 -244.111498)
		(end 83.768184 -244.161818)
		(width 0.0889)
		(layer "In2.Cu")
		(net "M_C_CPU1_SA_DQ<31>")
	)
	(arc
		(start 83.768184 -244.161818)
		(mid 84.05114 -244.237995)
		(end 84.334096 -244.161818)
		(width 0.0889)
		(layer "In2.Cu")
		(net "M_C_CPU1_SA_DQ<31>")
	)
	(arc
		(start 80.574134 -244.161818)
		(mid 80.761078 -244.111563)
		(end 80.948022 -244.161818)
		(width 0.0889)
		(layer "In2.Cu")
		(net "M_C_CPU1_SA_DQ<31>")
	)
	(arc
		(start 91.862402 -244.156992)
		(mid 92.04591 -244.111498)
		(end 92.228162 -244.161818)
		(width 0.0889)
		(layer "In2.Cu")
		(net "M_C_CPU1_SA_DQ<31>")
	)
	(arc
		(start 88.4682 -244.161818)
		(mid 88.751156 -244.237995)
		(end 89.034112 -244.161818)
		(width 0.0889)
		(layer "In2.Cu")
		(net "M_C_CPU1_SA_DQ<31>")
	)
	(arc
		(start 94.673928 -244.161818)
		(mid 94.856179 -244.111468)
		(end 95.039688 -244.156992)
		(width 0.0889)
		(layer "In2.Cu")
		(net "M_C_CPU1_SA_DQ<31>")
	)
	(arc
		(start 95.04807 -244.161818)
		(mid 95.295783 -244.237038)
		(end 95.55099 -244.193568)
		(width 0.0889)
		(layer "In2.Cu")
		(net "M_C_CPU1_SA_DQ<31>")
	)
	(arc
		(start 81.513934 -244.161818)
		(mid 81.696185 -244.111468)
		(end 81.879694 -244.156992)
		(width 0.0889)
		(layer "In2.Cu")
		(net "M_C_CPU1_SA_DQ<31>")
	)
	(arc
		(start 89.408 -244.161818)
		(mid 89.690956 -244.237995)
		(end 89.973912 -244.161818)
		(width 0.0889)
		(layer "In2.Cu")
		(net "M_C_CPU1_SA_DQ<31>")
	)
	(arc
		(start 82.82813 -244.161818)
		(mid 83.111086 -244.237995)
		(end 83.394042 -244.161818)
		(width 0.0889)
		(layer "In2.Cu")
		(net "M_C_CPU1_SA_DQ<31>")
	)
	(arc
		(start 92.794074 -244.161818)
		(mid 92.981018 -244.111563)
		(end 93.167962 -244.161818)
		(width 0.0889)
		(layer "In2.Cu")
		(net "M_C_CPU1_SA_DQ<31>")
	)
	(arc
		(start 78.169516 -244.184932)
		(mid 78.43564 -244.238538)
		(end 78.696058 -244.161818)
		(width 0.0889)
		(layer "In2.Cu")
		(net "M_C_CPU1_SA_DQ<31>")
	)
	(arc
		(start 82.46237 -244.156992)
		(mid 82.645878 -244.111498)
		(end 82.82813 -244.161818)
		(width 0.0889)
		(layer "In2.Cu")
		(net "M_C_CPU1_SA_DQ<31>")
	)
	(arc
		(start 85.273896 -244.161818)
		(mid 85.456147 -244.111468)
		(end 85.639656 -244.156992)
		(width 0.0889)
		(layer "In2.Cu")
		(net "M_C_CPU1_SA_DQ<31>")
	)
	(arc
		(start 89.973912 -244.161818)
		(mid 90.156163 -244.111468)
		(end 90.339672 -244.156992)
		(width 0.0889)
		(layer "In2.Cu")
		(net "M_C_CPU1_SA_DQ<31>")
	)
	(arc
		(start 80.948022 -244.161818)
		(mid 81.230978 -244.237995)
		(end 81.513934 -244.161818)
		(width 0.0889)
		(layer "In2.Cu")
		(net "M_C_CPU1_SA_DQ<31>")
	)
	(arc
		(start 79.658718 -244.14861)
		(mid 79.835113 -244.111707)
		(end 80.008222 -244.161818)
		(width 0.0889)
		(layer "In2.Cu")
		(net "M_C_CPU1_SA_DQ<31>")
	)
	(arc
		(start 93.733874 -244.161818)
		(mid 93.916125 -244.111468)
		(end 94.099634 -244.156992)
		(width 0.0889)
		(layer "In2.Cu")
		(net "M_C_CPU1_SA_DQ<31>")
	)
	(arc
		(start 87.528146 -244.161818)
		(mid 87.811102 -244.237995)
		(end 88.094058 -244.161818)
		(width 0.0889)
		(layer "In2.Cu")
		(net "M_C_CPU1_SA_DQ<31>")
	)
	(arc
		(start 94.108016 -244.161818)
		(mid 94.390972 -244.237995)
		(end 94.673928 -244.161818)
		(width 0.0889)
		(layer "In2.Cu")
		(net "M_C_CPU1_SA_DQ<31>")
	)
	(arc
		(start 90.922348 -244.156992)
		(mid 91.105856 -244.111498)
		(end 91.288108 -244.161818)
		(width 0.0889)
		(layer "In2.Cu")
		(net "M_C_CPU1_SA_DQ<31>")
	)
	(arc
		(start 84.707984 -244.161818)
		(mid 84.99094 -244.237995)
		(end 85.273896 -244.161818)
		(width 0.0889)
		(layer "In2.Cu")
		(net "M_C_CPU1_SA_DQ<31>")
	)
	(arc
		(start 80.008222 -244.161818)
		(mid 80.291178 -244.237995)
		(end 80.574134 -244.161818)
		(width 0.0889)
		(layer "In2.Cu")
		(net "M_C_CPU1_SA_DQ<31>")
	)
	(arc
		(start 81.888076 -244.161818)
		(mid 82.171032 -244.237995)
		(end 82.453988 -244.161818)
		(width 0.0889)
		(layer "In2.Cu")
		(net "M_C_CPU1_SA_DQ<31>")
	)
	(arc
		(start 89.034112 -244.161818)
		(mid 89.221056 -244.111563)
		(end 89.408 -244.161818)
		(width 0.0889)
		(layer "In2.Cu")
		(net "M_C_CPU1_SA_DQ<31>")
	)
	(arc
		(start 92.228162 -244.161818)
		(mid 92.511118 -244.237995)
		(end 92.794074 -244.161818)
		(width 0.0889)
		(layer "In2.Cu")
		(net "M_C_CPU1_SA_DQ<31>")
	)
	(arc
		(start 90.348054 -244.161818)
		(mid 90.63101 -244.237995)
		(end 90.913966 -244.161818)
		(width 0.0889)
		(layer "In2.Cu")
		(net "M_C_CPU1_SA_DQ<31>")
	)
	(arc
		(start 85.648038 -244.161818)
		(mid 85.930994 -244.237995)
		(end 86.21395 -244.161818)
		(width 0.0889)
		(layer "In2.Cu")
		(net "M_C_CPU1_SA_DQ<31>")
	)
	(arc
		(start 86.21395 -244.161818)
		(mid 86.396201 -244.111468)
		(end 86.57971 -244.156992)
		(width 0.0889)
		(layer "In2.Cu")
		(net "M_C_CPU1_SA_DQ<31>")
	)
	(arc
		(start 84.334096 -244.161818)
		(mid 84.52104 -244.111563)
		(end 84.707984 -244.161818)
		(width 0.0889)
		(layer "In2.Cu")
		(net "M_C_CPU1_SA_DQ<31>")
	)
	(arc
		(start 77.96784 -244.118384)
		(mid 78.051877 -244.129505)
		(end 78.130146 -244.162072)
		(width 0.0889)
		(layer "In2.Cu")
		(net "M_C_CPU1_SA_DQ<31>")
	)
	(arc
		(start 93.167962 -244.161818)
		(mid 93.450918 -244.237995)
		(end 93.733874 -244.161818)
		(width 0.0889)
		(layer "In2.Cu")
		(net "M_C_CPU1_SA_DQ<31>")
	)
	(arc
		(start 79.07147 -244.161818)
		(mid 79.3384 -244.237767)
		(end 79.609188 -244.177058)
		(width 0.0889)
		(layer "In2.Cu")
		(net "M_C_CPU1_SA_DQ<31>")
	)
	(arc
		(start 86.588092 -244.161818)
		(mid 86.871048 -244.237995)
		(end 87.154004 -244.161818)
		(width 0.0889)
		(layer "In2.Cu")
		(net "M_C_CPU1_SA_DQ<31>")
	)
	(arc
		(start 87.162386 -244.156992)
		(mid 87.345894 -244.111498)
		(end 87.528146 -244.161818)
		(width 0.0889)
		(layer "In2.Cu")
		(net "M_C_CPU1_SA_DQ<31>")
	)
	(arc
		(start 88.10244 -244.156992)
		(mid 88.285948 -244.111498)
		(end 88.4682 -244.161818)
		(width 0.0889)
		(layer "In2.Cu")
		(net "M_C_CPU1_SA_DQ<31>")
	)
	(arc
		(start 91.288108 -244.161818)
		(mid 91.571064 -244.237995)
		(end 91.85402 -244.161818)
		(width 0.0889)
		(layer "In2.Cu")
		(net "M_C_CPU1_SA_DQ<31>")
	)
	(arc
		(start 78.696058 -244.161818)
		(mid 78.871968 -244.111008)
		(end 79.050896 -244.14988)
		(width 0.0889)
		(layer "In2.Cu")
		(net "M_C_CPU1_SA_DQ<31>")
	)
	(segment
		(start 94.857824 -243.94033)
		(end 94.390972 -243.674392)
		(width 0.10668)
		(layer "F.Cu")
		(net "M_C_CPU1_SA_DQ<30>")
	)
	(segment
		(start 43.004994 -231.613964)
		(end 43.168062 -231.777032)
		(width 0.14478)
		(layer "In2.Cu")
		(net "M_C_CPU1_SA_DQ<30>")
	)
	(segment
		(start 85.74405 -243.351812)
		(end 85.752432 -243.346986)
		(width 0.0889)
		(layer "In2.Cu")
		(net "M_C_CPU1_SA_DQ<30>")
	)
	(segment
		(start 41.49852 -232.447338)
		(end 41.49852 -232.099612)
		(width 0.14478)
		(layer "In2.Cu")
		(net "M_C_CPU1_SA_DQ<30>")
	)
	(segment
		(start 41.661588 -231.936544)
		(end 41.891966 -231.936544)
		(width 0.14478)
		(layer "In2.Cu")
		(net "M_C_CPU1_SA_DQ<30>")
	)
	(segment
		(start 49.428146 -232.610406)
		(end 50.278284 -231.760268)
		(width 0.14478)
		(layer "In2.Cu")
		(net "M_C_CPU1_SA_DQ<30>")
	)
	(segment
		(start 67.342258 -238.908844)
		(end 67.957446 -238.908844)
		(width 0.14478)
		(layer "In2.Cu")
		(net "M_C_CPU1_SA_DQ<30>")
	)
	(segment
		(start 79.163164 -243.351812)
		(end 79.174848 -243.344954)
		(width 0.0889)
		(layer "In2.Cu")
		(net "M_C_CPU1_SA_DQ<30>")
	)
	(segment
		(start 42.611548 -231.777032)
		(end 42.774616 -231.613964)
		(width 0.14478)
		(layer "In2.Cu")
		(net "M_C_CPU1_SA_DQ<30>")
	)
	(segment
		(start 77.494638 -243.307616)
		(end 78.401926 -243.307616)
		(width 0.0889)
		(layer "In2.Cu")
		(net "M_C_CPU1_SA_DQ<30>")
	)
	(segment
		(start 43.168062 -232.447338)
		(end 43.33113 -232.610406)
		(width 0.14478)
		(layer "In2.Cu")
		(net "M_C_CPU1_SA_DQ<30>")
	)
	(segment
		(start 92.68968 -243.346986)
		(end 92.698062 -243.351812)
		(width 0.0889)
		(layer "In2.Cu")
		(net "M_C_CPU1_SA_DQ<30>")
	)
	(segment
		(start 89.504012 -243.351812)
		(end 89.512394 -243.346986)
		(width 0.0889)
		(layer "In2.Cu")
		(net "M_C_CPU1_SA_DQ<30>")
	)
	(segment
		(start 81.044034 -243.351812)
		(end 81.052416 -243.346986)
		(width 0.0889)
		(layer "In2.Cu")
		(net "M_C_CPU1_SA_DQ<30>")
	)
	(segment
		(start 50.278284 -231.760268)
		(end 53.111654 -231.760268)
		(width 0.14478)
		(layer "In2.Cu")
		(net "M_C_CPU1_SA_DQ<30>")
	)
	(segment
		(start 40.23995 -232.18521)
		(end 40.665146 -232.610406)
		(width 0.14478)
		(layer "In2.Cu")
		(net "M_C_CPU1_SA_DQ<30>")
	)
	(segment
		(start 80.46974 -243.346986)
		(end 80.478122 -243.351812)
		(width 0.0889)
		(layer "In2.Cu")
		(net "M_C_CPU1_SA_DQ<30>")
	)
	(segment
		(start 57.154064 -232.610406)
		(end 58.004202 -231.760268)
		(width 0.14478)
		(layer "In2.Cu")
		(net "M_C_CPU1_SA_DQ<30>")
	)
	(segment
		(start 93.263974 -243.351812)
		(end 93.272356 -243.346986)
		(width 0.0889)
		(layer "In2.Cu")
		(net "M_C_CPU1_SA_DQ<30>")
	)
	(segment
		(start 42.44848 -232.610406)
		(end 42.611548 -232.447338)
		(width 0.14478)
		(layer "In2.Cu")
		(net "M_C_CPU1_SA_DQ<30>")
	)
	(segment
		(start 41.49852 -232.099612)
		(end 41.661588 -231.936544)
		(width 0.14478)
		(layer "In2.Cu")
		(net "M_C_CPU1_SA_DQ<30>")
	)
	(segment
		(start 94.141036 -243.383562)
		(end 94.237048 -243.408962)
		(width 0.0889)
		(layer "In2.Cu")
		(net "M_C_CPU1_SA_DQ<30>")
	)
	(segment
		(start 84.229702 -243.346986)
		(end 84.238084 -243.351812)
		(width 0.0889)
		(layer "In2.Cu")
		(net "M_C_CPU1_SA_DQ<30>")
	)
	(segment
		(start 42.774616 -231.613964)
		(end 43.004994 -231.613964)
		(width 0.14478)
		(layer "In2.Cu")
		(net "M_C_CPU1_SA_DQ<30>")
	)
	(segment
		(start 75.958446 -242.307364)
		(end 76.494386 -242.307364)
		(width 0.0889)
		(layer "In2.Cu")
		(net "M_C_CPU1_SA_DQ<30>")
	)
	(segment
		(start 42.055034 -232.099612)
		(end 42.055034 -232.447338)
		(width 0.14478)
		(layer "In2.Cu")
		(net "M_C_CPU1_SA_DQ<30>")
	)
	(segment
		(start 87.989664 -243.346986)
		(end 87.998046 -243.351812)
		(width 0.0889)
		(layer "In2.Cu")
		(net "M_C_CPU1_SA_DQ<30>")
	)
	(segment
		(start 83.289648 -243.346986)
		(end 83.29803 -243.351812)
		(width 0.0889)
		(layer "In2.Cu")
		(net "M_C_CPU1_SA_DQ<30>")
	)
	(segment
		(start 58.004202 -231.760268)
		(end 60.726066 -231.760268)
		(width 0.14478)
		(layer "In2.Cu")
		(net "M_C_CPU1_SA_DQ<30>")
	)
	(segment
		(start 53.961792 -232.610406)
		(end 57.154064 -232.610406)
		(width 0.14478)
		(layer "In2.Cu")
		(net "M_C_CPU1_SA_DQ<30>")
	)
	(segment
		(start 43.168062 -231.777032)
		(end 43.168062 -232.447338)
		(width 0.14478)
		(layer "In2.Cu")
		(net "M_C_CPU1_SA_DQ<30>")
	)
	(segment
		(start 42.611548 -232.447338)
		(end 42.611548 -231.777032)
		(width 0.14478)
		(layer "In2.Cu")
		(net "M_C_CPU1_SA_DQ<30>")
	)
	(segment
		(start 61.17971 -232.213912)
		(end 61.17971 -232.746296)
		(width 0.14478)
		(layer "In2.Cu")
		(net "M_C_CPU1_SA_DQ<30>")
	)
	(segment
		(start 71.355966 -242.307364)
		(end 75.958446 -242.307364)
		(width 0.14478)
		(layer "In2.Cu")
		(net "M_C_CPU1_SA_DQ<30>")
	)
	(segment
		(start 42.218102 -232.610406)
		(end 42.44848 -232.610406)
		(width 0.14478)
		(layer "In2.Cu")
		(net "M_C_CPU1_SA_DQ<30>")
	)
	(segment
		(start 88.929718 -243.346986)
		(end 88.9381 -243.351812)
		(width 0.0889)
		(layer "In2.Cu")
		(net "M_C_CPU1_SA_DQ<30>")
	)
	(segment
		(start 41.335452 -232.610406)
		(end 41.49852 -232.447338)
		(width 0.14478)
		(layer "In2.Cu")
		(net "M_C_CPU1_SA_DQ<30>")
	)
	(segment
		(start 42.055034 -232.447338)
		(end 42.218102 -232.610406)
		(width 0.14478)
		(layer "In2.Cu")
		(net "M_C_CPU1_SA_DQ<30>")
	)
	(segment
		(start 53.111654 -231.760268)
		(end 53.961792 -232.610406)
		(width 0.14478)
		(layer "In2.Cu")
		(net "M_C_CPU1_SA_DQ<30>")
	)
	(segment
		(start 84.803996 -243.351812)
		(end 84.812378 -243.346986)
		(width 0.0889)
		(layer "In2.Cu")
		(net "M_C_CPU1_SA_DQ<30>")
	)
	(segment
		(start 61.17971 -232.746296)
		(end 67.342258 -238.908844)
		(width 0.14478)
		(layer "In2.Cu")
		(net "M_C_CPU1_SA_DQ<30>")
	)
	(segment
		(start 91.749626 -243.346986)
		(end 91.758008 -243.351812)
		(width 0.0889)
		(layer "In2.Cu")
		(net "M_C_CPU1_SA_DQ<30>")
	)
	(segment
		(start 41.891966 -231.936544)
		(end 42.055034 -232.099612)
		(width 0.14478)
		(layer "In2.Cu")
		(net "M_C_CPU1_SA_DQ<30>")
	)
	(segment
		(start 94.237048 -243.408962)
		(end 94.390972 -243.674392)
		(width 0.0889)
		(layer "In2.Cu")
		(net "M_C_CPU1_SA_DQ<30>")
	)
	(segment
		(start 76.494386 -242.307364)
		(end 77.494638 -243.307616)
		(width 0.0889)
		(layer "In2.Cu")
		(net "M_C_CPU1_SA_DQ<30>")
	)
	(segment
		(start 80.089248 -243.360448)
		(end 80.10398 -243.351812)
		(width 0.0889)
		(layer "In2.Cu")
		(net "M_C_CPU1_SA_DQ<30>")
	)
	(segment
		(start 40.665146 -232.610406)
		(end 41.335452 -232.610406)
		(width 0.14478)
		(layer "In2.Cu")
		(net "M_C_CPU1_SA_DQ<30>")
	)
	(segment
		(start 60.726066 -231.760268)
		(end 61.17971 -232.213912)
		(width 0.14478)
		(layer "In2.Cu")
		(net "M_C_CPU1_SA_DQ<30>")
	)
	(segment
		(start 67.957446 -238.908844)
		(end 71.355966 -242.307364)
		(width 0.14478)
		(layer "In2.Cu")
		(net "M_C_CPU1_SA_DQ<30>")
	)
	(segment
		(start 43.33113 -232.610406)
		(end 49.428146 -232.610406)
		(width 0.14478)
		(layer "In2.Cu")
		(net "M_C_CPU1_SA_DQ<30>")
	)
	(arc
		(start 88.563958 -243.351812)
		(mid 88.746209 -243.301462)
		(end 88.929718 -243.346986)
		(width 0.0889)
		(layer "In2.Cu")
		(net "M_C_CPU1_SA_DQ<30>")
	)
	(arc
		(start 86.118192 -243.351812)
		(mid 86.401148 -243.427989)
		(end 86.684104 -243.351812)
		(width 0.0889)
		(layer "In2.Cu")
		(net "M_C_CPU1_SA_DQ<30>")
	)
	(arc
		(start 82.923888 -243.351812)
		(mid 83.106139 -243.301462)
		(end 83.289648 -243.346986)
		(width 0.0889)
		(layer "In2.Cu")
		(net "M_C_CPU1_SA_DQ<30>")
	)
	(arc
		(start 86.684104 -243.351812)
		(mid 86.871048 -243.301557)
		(end 87.057992 -243.351812)
		(width 0.0889)
		(layer "In2.Cu")
		(net "M_C_CPU1_SA_DQ<30>")
	)
	(arc
		(start 81.418176 -243.351812)
		(mid 81.701132 -243.427989)
		(end 81.984088 -243.351812)
		(width 0.0889)
		(layer "In2.Cu")
		(net "M_C_CPU1_SA_DQ<30>")
	)
	(arc
		(start 79.174848 -243.344954)
		(mid 79.357103 -243.301301)
		(end 79.53756 -243.351812)
		(width 0.0889)
		(layer "In2.Cu")
		(net "M_C_CPU1_SA_DQ<30>")
	)
	(arc
		(start 91.758008 -243.351812)
		(mid 92.040964 -243.427989)
		(end 92.32392 -243.351812)
		(width 0.0889)
		(layer "In2.Cu")
		(net "M_C_CPU1_SA_DQ<30>")
	)
	(arc
		(start 87.623904 -243.351812)
		(mid 87.806155 -243.301462)
		(end 87.989664 -243.346986)
		(width 0.0889)
		(layer "In2.Cu")
		(net "M_C_CPU1_SA_DQ<30>")
	)
	(arc
		(start 88.9381 -243.351812)
		(mid 89.221056 -243.427989)
		(end 89.504012 -243.351812)
		(width 0.0889)
		(layer "In2.Cu")
		(net "M_C_CPU1_SA_DQ<30>")
	)
	(arc
		(start 85.178138 -243.351812)
		(mid 85.461094 -243.427989)
		(end 85.74405 -243.351812)
		(width 0.0889)
		(layer "In2.Cu")
		(net "M_C_CPU1_SA_DQ<30>")
	)
	(arc
		(start 93.638116 -243.351812)
		(mid 93.885829 -243.427032)
		(end 94.141036 -243.383562)
		(width 0.0889)
		(layer "In2.Cu")
		(net "M_C_CPU1_SA_DQ<30>")
	)
	(arc
		(start 90.817954 -243.351812)
		(mid 91.10091 -243.427989)
		(end 91.383866 -243.351812)
		(width 0.0889)
		(layer "In2.Cu")
		(net "M_C_CPU1_SA_DQ<30>")
	)
	(arc
		(start 84.812378 -243.346986)
		(mid 84.995886 -243.301492)
		(end 85.178138 -243.351812)
		(width 0.0889)
		(layer "In2.Cu")
		(net "M_C_CPU1_SA_DQ<30>")
	)
	(arc
		(start 93.272356 -243.346986)
		(mid 93.455864 -243.301492)
		(end 93.638116 -243.351812)
		(width 0.0889)
		(layer "In2.Cu")
		(net "M_C_CPU1_SA_DQ<30>")
	)
	(arc
		(start 89.512394 -243.346986)
		(mid 89.695902 -243.301492)
		(end 89.878154 -243.351812)
		(width 0.0889)
		(layer "In2.Cu")
		(net "M_C_CPU1_SA_DQ<30>")
	)
	(arc
		(start 92.32392 -243.351812)
		(mid 92.506171 -243.301462)
		(end 92.68968 -243.346986)
		(width 0.0889)
		(layer "In2.Cu")
		(net "M_C_CPU1_SA_DQ<30>")
	)
	(arc
		(start 78.603348 -243.355368)
		(mid 78.883737 -243.428037)
		(end 79.163164 -243.351812)
		(width 0.0889)
		(layer "In2.Cu")
		(net "M_C_CPU1_SA_DQ<30>")
	)
	(arc
		(start 91.383866 -243.351812)
		(mid 91.566117 -243.301462)
		(end 91.749626 -243.346986)
		(width 0.0889)
		(layer "In2.Cu")
		(net "M_C_CPU1_SA_DQ<30>")
	)
	(arc
		(start 81.984088 -243.351812)
		(mid 82.171032 -243.301557)
		(end 82.357976 -243.351812)
		(width 0.0889)
		(layer "In2.Cu")
		(net "M_C_CPU1_SA_DQ<30>")
	)
	(arc
		(start 87.057992 -243.351812)
		(mid 87.340948 -243.427989)
		(end 87.623904 -243.351812)
		(width 0.0889)
		(layer "In2.Cu")
		(net "M_C_CPU1_SA_DQ<30>")
	)
	(arc
		(start 82.357976 -243.351812)
		(mid 82.640932 -243.427989)
		(end 82.923888 -243.351812)
		(width 0.0889)
		(layer "In2.Cu")
		(net "M_C_CPU1_SA_DQ<30>")
	)
	(arc
		(start 90.444066 -243.351812)
		(mid 90.63101 -243.301557)
		(end 90.817954 -243.351812)
		(width 0.0889)
		(layer "In2.Cu")
		(net "M_C_CPU1_SA_DQ<30>")
	)
	(arc
		(start 78.490826 -243.31676)
		(mid 78.548254 -243.332663)
		(end 78.603348 -243.355368)
		(width 0.0889)
		(layer "In2.Cu")
		(net "M_C_CPU1_SA_DQ<30>")
	)
	(arc
		(start 83.29803 -243.351812)
		(mid 83.580986 -243.427989)
		(end 83.863942 -243.351812)
		(width 0.0889)
		(layer "In2.Cu")
		(net "M_C_CPU1_SA_DQ<30>")
	)
	(arc
		(start 89.878154 -243.351812)
		(mid 90.16111 -243.427989)
		(end 90.444066 -243.351812)
		(width 0.0889)
		(layer "In2.Cu")
		(net "M_C_CPU1_SA_DQ<30>")
	)
	(arc
		(start 80.10398 -243.351812)
		(mid 80.286231 -243.301462)
		(end 80.46974 -243.346986)
		(width 0.0889)
		(layer "In2.Cu")
		(net "M_C_CPU1_SA_DQ<30>")
	)
	(arc
		(start 83.863942 -243.351812)
		(mid 84.046193 -243.301462)
		(end 84.229702 -243.346986)
		(width 0.0889)
		(layer "In2.Cu")
		(net "M_C_CPU1_SA_DQ<30>")
	)
	(arc
		(start 84.238084 -243.351812)
		(mid 84.52104 -243.427989)
		(end 84.803996 -243.351812)
		(width 0.0889)
		(layer "In2.Cu")
		(net "M_C_CPU1_SA_DQ<30>")
	)
	(arc
		(start 92.698062 -243.351812)
		(mid 92.981018 -243.427989)
		(end 93.263974 -243.351812)
		(width 0.0889)
		(layer "In2.Cu")
		(net "M_C_CPU1_SA_DQ<30>")
	)
	(arc
		(start 85.752432 -243.346986)
		(mid 85.93594 -243.301492)
		(end 86.118192 -243.351812)
		(width 0.0889)
		(layer "In2.Cu")
		(net "M_C_CPU1_SA_DQ<30>")
	)
	(arc
		(start 79.53756 -243.351812)
		(mid 79.812266 -243.428176)
		(end 80.089248 -243.360448)
		(width 0.0889)
		(layer "In2.Cu")
		(net "M_C_CPU1_SA_DQ<30>")
	)
	(arc
		(start 78.401926 -243.307616)
		(mid 78.446617 -243.30985)
		(end 78.490826 -243.31676)
		(width 0.0889)
		(layer "In2.Cu")
		(net "M_C_CPU1_SA_DQ<30>")
	)
	(arc
		(start 87.998046 -243.351812)
		(mid 88.281002 -243.427989)
		(end 88.563958 -243.351812)
		(width 0.0889)
		(layer "In2.Cu")
		(net "M_C_CPU1_SA_DQ<30>")
	)
	(arc
		(start 81.052416 -243.346986)
		(mid 81.235924 -243.301492)
		(end 81.418176 -243.351812)
		(width 0.0889)
		(layer "In2.Cu")
		(net "M_C_CPU1_SA_DQ<30>")
	)
	(arc
		(start 80.478122 -243.351812)
		(mid 80.761078 -243.427989)
		(end 81.044034 -243.351812)
		(width 0.0889)
		(layer "In2.Cu")
		(net "M_C_CPU1_SA_DQ<30>")
	)
	(segment
		(start 94.857824 -226.120452)
		(end 94.390972 -225.854514)
		(width 0.10668)
		(layer "F.Cu")
		(net "M_C_CPU1_SA_DQ<2>")
	)
	(segment
		(start 42.02303 -197.597268)
		(end 42.02303 -196.989954)
		(width 0.14478)
		(layer "In2.Cu")
		(net "M_C_CPU1_SA_DQ<2>")
	)
	(segment
		(start 82.789014 -223.079056)
		(end 82.82813 -223.101916)
		(width 0.0889)
		(layer "In2.Cu")
		(net "M_C_CPU1_SA_DQ<2>")
	)
	(segment
		(start 42.416476 -196.826886)
		(end 42.579544 -196.989954)
		(width 0.14478)
		(layer "In2.Cu")
		(net "M_C_CPU1_SA_DQ<2>")
	)
	(segment
		(start 81.914746 -221.991682)
		(end 82.175604 -222.25254)
		(width 0.0889)
		(layer "In2.Cu")
		(net "M_C_CPU1_SA_DQ<2>")
	)
	(segment
		(start 83.258914 -223.889062)
		(end 83.29803 -223.911922)
		(width 0.0889)
		(layer "In2.Cu")
		(net "M_C_CPU1_SA_DQ<2>")
	)
	(segment
		(start 84.803996 -225.531934)
		(end 84.812378 -225.527108)
		(width 0.0889)
		(layer "In2.Cu")
		(net "M_C_CPU1_SA_DQ<2>")
	)
	(segment
		(start 82.290666 -222.25254)
		(end 82.38871 -222.30969)
		(width 0.0889)
		(layer "In2.Cu")
		(net "M_C_CPU1_SA_DQ<2>")
	)
	(segment
		(start 41.859962 -197.760336)
		(end 42.02303 -197.597268)
		(width 0.14478)
		(layer "In2.Cu")
		(net "M_C_CPU1_SA_DQ<2>")
	)
	(segment
		(start 82.051906 -221.456504)
		(end 81.914746 -221.593664)
		(width 0.0889)
		(layer "In2.Cu")
		(net "M_C_CPU1_SA_DQ<2>")
	)
	(segment
		(start 74.350626 -209.140044)
		(end 77.105764 -211.895182)
		(width 0.14478)
		(layer "In2.Cu")
		(net "M_C_CPU1_SA_DQ<2>")
	)
	(segment
		(start 83.29803 -223.911922)
		(end 83.32978 -223.93021)
		(width 0.0889)
		(layer "In2.Cu")
		(net "M_C_CPU1_SA_DQ<2>")
	)
	(segment
		(start 82.051906 -221.217744)
		(end 82.051906 -221.456504)
		(width 0.0889)
		(layer "In2.Cu")
		(net "M_C_CPU1_SA_DQ<2>")
	)
	(segment
		(start 42.579544 -197.597268)
		(end 42.742612 -197.760336)
		(width 0.14478)
		(layer "In2.Cu")
		(net "M_C_CPU1_SA_DQ<2>")
	)
	(segment
		(start 42.186098 -196.826886)
		(end 42.416476 -196.826886)
		(width 0.14478)
		(layer "In2.Cu")
		(net "M_C_CPU1_SA_DQ<2>")
	)
	(segment
		(start 93.263974 -225.531934)
		(end 93.272356 -225.527108)
		(width 0.0889)
		(layer "In2.Cu")
		(net "M_C_CPU1_SA_DQ<2>")
	)
	(segment
		(start 82.051906 -218.540584)
		(end 82.051906 -221.217744)
		(width 0.14478)
		(layer "In2.Cu")
		(net "M_C_CPU1_SA_DQ<2>")
	)
	(segment
		(start 81.914746 -221.593664)
		(end 81.914746 -221.991682)
		(width 0.0889)
		(layer "In2.Cu")
		(net "M_C_CPU1_SA_DQ<2>")
	)
	(segment
		(start 94.141036 -225.563684)
		(end 94.237048 -225.589084)
		(width 0.0889)
		(layer "In2.Cu")
		(net "M_C_CPU1_SA_DQ<2>")
	)
	(segment
		(start 89.504012 -225.531934)
		(end 89.512394 -225.527108)
		(width 0.0889)
		(layer "In2.Cu")
		(net "M_C_CPU1_SA_DQ<2>")
	)
	(segment
		(start 77.105764 -211.895182)
		(end 77.105764 -213.594442)
		(width 0.14478)
		(layer "In2.Cu")
		(net "M_C_CPU1_SA_DQ<2>")
	)
	(segment
		(start 40.664892 -197.760336)
		(end 41.859962 -197.760336)
		(width 0.14478)
		(layer "In2.Cu")
		(net "M_C_CPU1_SA_DQ<2>")
	)
	(segment
		(start 84.198968 -225.509074)
		(end 84.238084 -225.531934)
		(width 0.0889)
		(layer "In2.Cu")
		(net "M_C_CPU1_SA_DQ<2>")
	)
	(segment
		(start 40.23995 -198.185278)
		(end 40.664892 -197.760336)
		(width 0.14478)
		(layer "In2.Cu")
		(net "M_C_CPU1_SA_DQ<2>")
	)
	(segment
		(start 83.768184 -224.721928)
		(end 83.798664 -224.739708)
		(width 0.0889)
		(layer "In2.Cu")
		(net "M_C_CPU1_SA_DQ<2>")
	)
	(segment
		(start 91.749626 -225.527108)
		(end 91.758008 -225.531934)
		(width 0.0889)
		(layer "In2.Cu")
		(net "M_C_CPU1_SA_DQ<2>")
	)
	(segment
		(start 73.327006 -209.140044)
		(end 74.350626 -209.140044)
		(width 0.14478)
		(layer "In2.Cu")
		(net "M_C_CPU1_SA_DQ<2>")
	)
	(segment
		(start 85.74405 -225.531934)
		(end 85.752432 -225.527108)
		(width 0.0889)
		(layer "In2.Cu")
		(net "M_C_CPU1_SA_DQ<2>")
	)
	(segment
		(start 42.02303 -196.989954)
		(end 42.186098 -196.826886)
		(width 0.14478)
		(layer "In2.Cu")
		(net "M_C_CPU1_SA_DQ<2>")
	)
	(segment
		(start 88.929718 -225.527108)
		(end 88.9381 -225.531934)
		(width 0.0889)
		(layer "In2.Cu")
		(net "M_C_CPU1_SA_DQ<2>")
	)
	(segment
		(start 82.82813 -223.101916)
		(end 82.85861 -223.119696)
		(width 0.0889)
		(layer "In2.Cu")
		(net "M_C_CPU1_SA_DQ<2>")
	)
	(segment
		(start 82.175604 -222.25254)
		(end 82.290666 -222.25254)
		(width 0.0889)
		(layer "In2.Cu")
		(net "M_C_CPU1_SA_DQ<2>")
	)
	(segment
		(start 42.742612 -197.760336)
		(end 61.947298 -197.760336)
		(width 0.14478)
		(layer "In2.Cu")
		(net "M_C_CPU1_SA_DQ<2>")
	)
	(segment
		(start 42.579544 -196.989954)
		(end 42.579544 -197.597268)
		(width 0.14478)
		(layer "In2.Cu")
		(net "M_C_CPU1_SA_DQ<2>")
	)
	(segment
		(start 87.989664 -225.527108)
		(end 87.998046 -225.531934)
		(width 0.0889)
		(layer "In2.Cu")
		(net "M_C_CPU1_SA_DQ<2>")
	)
	(segment
		(start 61.947298 -197.760336)
		(end 73.327006 -209.140044)
		(width 0.14478)
		(layer "In2.Cu")
		(net "M_C_CPU1_SA_DQ<2>")
	)
	(segment
		(start 92.68968 -225.527108)
		(end 92.698062 -225.531934)
		(width 0.0889)
		(layer "In2.Cu")
		(net "M_C_CPU1_SA_DQ<2>")
	)
	(segment
		(start 94.237048 -225.589084)
		(end 94.390972 -225.854514)
		(width 0.0889)
		(layer "In2.Cu")
		(net "M_C_CPU1_SA_DQ<2>")
	)
	(segment
		(start 83.729068 -224.699068)
		(end 83.768184 -224.721928)
		(width 0.0889)
		(layer "In2.Cu")
		(net "M_C_CPU1_SA_DQ<2>")
	)
	(segment
		(start 77.105764 -213.594442)
		(end 82.051906 -218.540584)
		(width 0.14478)
		(layer "In2.Cu")
		(net "M_C_CPU1_SA_DQ<2>")
	)
	(arc
		(start 93.272356 -225.527108)
		(mid 93.455864 -225.481614)
		(end 93.638116 -225.531934)
		(width 0.0889)
		(layer "In2.Cu")
		(net "M_C_CPU1_SA_DQ<2>")
	)
	(arc
		(start 91.758008 -225.531934)
		(mid 92.040964 -225.608111)
		(end 92.32392 -225.531934)
		(width 0.0889)
		(layer "In2.Cu")
		(net "M_C_CPU1_SA_DQ<2>")
	)
	(arc
		(start 83.32978 -223.93021)
		(mid 83.444456 -224.063544)
		(end 83.485736 -224.234502)
		(width 0.0889)
		(layer "In2.Cu")
		(net "M_C_CPU1_SA_DQ<2>")
	)
	(arc
		(start 86.118192 -225.531934)
		(mid 86.401148 -225.608111)
		(end 86.684104 -225.531934)
		(width 0.0889)
		(layer "In2.Cu")
		(net "M_C_CPU1_SA_DQ<2>")
	)
	(arc
		(start 82.545682 -222.61449)
		(mid 82.610197 -222.876709)
		(end 82.789014 -223.079056)
		(width 0.0889)
		(layer "In2.Cu")
		(net "M_C_CPU1_SA_DQ<2>")
	)
	(arc
		(start 82.38871 -222.30969)
		(mid 82.504137 -222.443066)
		(end 82.545682 -222.61449)
		(width 0.0889)
		(layer "In2.Cu")
		(net "M_C_CPU1_SA_DQ<2>")
	)
	(arc
		(start 84.812378 -225.527108)
		(mid 84.995886 -225.481614)
		(end 85.178138 -225.531934)
		(width 0.0889)
		(layer "In2.Cu")
		(net "M_C_CPU1_SA_DQ<2>")
	)
	(arc
		(start 92.32392 -225.531934)
		(mid 92.506171 -225.481584)
		(end 92.68968 -225.527108)
		(width 0.0889)
		(layer "In2.Cu")
		(net "M_C_CPU1_SA_DQ<2>")
	)
	(arc
		(start 87.623904 -225.531934)
		(mid 87.806155 -225.481584)
		(end 87.989664 -225.527108)
		(width 0.0889)
		(layer "In2.Cu")
		(net "M_C_CPU1_SA_DQ<2>")
	)
	(arc
		(start 82.85861 -223.119696)
		(mid 82.974037 -223.253072)
		(end 83.015582 -223.424496)
		(width 0.0889)
		(layer "In2.Cu")
		(net "M_C_CPU1_SA_DQ<2>")
	)
	(arc
		(start 93.638116 -225.531934)
		(mid 93.885829 -225.607154)
		(end 94.141036 -225.563684)
		(width 0.0889)
		(layer "In2.Cu")
		(net "M_C_CPU1_SA_DQ<2>")
	)
	(arc
		(start 87.057992 -225.531934)
		(mid 87.340948 -225.608111)
		(end 87.623904 -225.531934)
		(width 0.0889)
		(layer "In2.Cu")
		(net "M_C_CPU1_SA_DQ<2>")
	)
	(arc
		(start 83.798664 -224.739708)
		(mid 83.914091 -224.873084)
		(end 83.955636 -225.044508)
		(width 0.0889)
		(layer "In2.Cu")
		(net "M_C_CPU1_SA_DQ<2>")
	)
	(arc
		(start 89.878154 -225.531934)
		(mid 90.16111 -225.608111)
		(end 90.444066 -225.531934)
		(width 0.0889)
		(layer "In2.Cu")
		(net "M_C_CPU1_SA_DQ<2>")
	)
	(arc
		(start 90.817954 -225.531934)
		(mid 91.10091 -225.608111)
		(end 91.383866 -225.531934)
		(width 0.0889)
		(layer "In2.Cu")
		(net "M_C_CPU1_SA_DQ<2>")
	)
	(arc
		(start 89.512394 -225.527108)
		(mid 89.695902 -225.481614)
		(end 89.878154 -225.531934)
		(width 0.0889)
		(layer "In2.Cu")
		(net "M_C_CPU1_SA_DQ<2>")
	)
	(arc
		(start 88.9381 -225.531934)
		(mid 89.221056 -225.608111)
		(end 89.504012 -225.531934)
		(width 0.0889)
		(layer "In2.Cu")
		(net "M_C_CPU1_SA_DQ<2>")
	)
	(arc
		(start 83.485736 -224.234502)
		(mid 83.550251 -224.496721)
		(end 83.729068 -224.699068)
		(width 0.0889)
		(layer "In2.Cu")
		(net "M_C_CPU1_SA_DQ<2>")
	)
	(arc
		(start 92.698062 -225.531934)
		(mid 92.981018 -225.608111)
		(end 93.263974 -225.531934)
		(width 0.0889)
		(layer "In2.Cu")
		(net "M_C_CPU1_SA_DQ<2>")
	)
	(arc
		(start 88.563958 -225.531934)
		(mid 88.746209 -225.481584)
		(end 88.929718 -225.527108)
		(width 0.0889)
		(layer "In2.Cu")
		(net "M_C_CPU1_SA_DQ<2>")
	)
	(arc
		(start 84.238084 -225.531934)
		(mid 84.52104 -225.608111)
		(end 84.803996 -225.531934)
		(width 0.0889)
		(layer "In2.Cu")
		(net "M_C_CPU1_SA_DQ<2>")
	)
	(arc
		(start 83.015582 -223.424496)
		(mid 83.080097 -223.686715)
		(end 83.258914 -223.889062)
		(width 0.0889)
		(layer "In2.Cu")
		(net "M_C_CPU1_SA_DQ<2>")
	)
	(arc
		(start 85.752432 -225.527108)
		(mid 85.93594 -225.481614)
		(end 86.118192 -225.531934)
		(width 0.0889)
		(layer "In2.Cu")
		(net "M_C_CPU1_SA_DQ<2>")
	)
	(arc
		(start 83.955636 -225.044508)
		(mid 84.020151 -225.306727)
		(end 84.198968 -225.509074)
		(width 0.0889)
		(layer "In2.Cu")
		(net "M_C_CPU1_SA_DQ<2>")
	)
	(arc
		(start 91.383866 -225.531934)
		(mid 91.566117 -225.481584)
		(end 91.749626 -225.527108)
		(width 0.0889)
		(layer "In2.Cu")
		(net "M_C_CPU1_SA_DQ<2>")
	)
	(arc
		(start 90.444066 -225.531934)
		(mid 90.63101 -225.481679)
		(end 90.817954 -225.531934)
		(width 0.0889)
		(layer "In2.Cu")
		(net "M_C_CPU1_SA_DQ<2>")
	)
	(arc
		(start 85.178138 -225.531934)
		(mid 85.461094 -225.608111)
		(end 85.74405 -225.531934)
		(width 0.0889)
		(layer "In2.Cu")
		(net "M_C_CPU1_SA_DQ<2>")
	)
	(arc
		(start 86.684104 -225.531934)
		(mid 86.871048 -225.481679)
		(end 87.057992 -225.531934)
		(width 0.0889)
		(layer "In2.Cu")
		(net "M_C_CPU1_SA_DQ<2>")
	)
	(arc
		(start 87.998046 -225.531934)
		(mid 88.281002 -225.608111)
		(end 88.563958 -225.531934)
		(width 0.0889)
		(layer "In2.Cu")
		(net "M_C_CPU1_SA_DQ<2>")
	)
	(segment
		(start 95.797878 -243.94033)
		(end 95.331026 -243.674392)
		(width 0.10668)
		(layer "F.Cu")
		(net "M_C_CPU1_SA_DQ<29>")
	)
	(segment
		(start 66.803524 -239.006126)
		(end 67.193922 -239.396524)
		(width 0.14478)
		(layer "In2.Cu")
		(net "M_C_CPU1_SA_DQ<29>")
	)
	(segment
		(start 59.075828 -232.610406)
		(end 59.783218 -232.610406)
		(width 0.14478)
		(layer "In2.Cu")
		(net "M_C_CPU1_SA_DQ<29>")
	)
	(segment
		(start 56.568594 -233.237532)
		(end 56.568594 -233.297222)
		(width 0.14478)
		(layer "In2.Cu")
		(net "M_C_CPU1_SA_DQ<29>")
	)
	(segment
		(start 66.291714 -238.494316)
		(end 66.29146 -238.509556)
		(width 0.14478)
		(layer "In2.Cu")
		(net "M_C_CPU1_SA_DQ<29>")
	)
	(segment
		(start 57.800748 -232.610406)
		(end 58.193178 -232.610406)
		(width 0.14478)
		(layer "In2.Cu")
		(net "M_C_CPU1_SA_DQ<29>")
	)
	(segment
		(start 54.78272 -233.245152)
		(end 54.78272 -233.297222)
		(width 0.14478)
		(layer "In2.Cu")
		(net "M_C_CPU1_SA_DQ<29>")
	)
	(segment
		(start 60.109354 -232.218484)
		(end 60.339732 -232.218484)
		(width 0.14478)
		(layer "In2.Cu")
		(net "M_C_CPU1_SA_DQ<29>")
	)
	(segment
		(start 62.658498 -235.104686)
		(end 62.902084 -235.104686)
		(width 0.14478)
		(layer "In2.Cu")
		(net "M_C_CPU1_SA_DQ<29>")
	)
	(segment
		(start 71.170292 -242.767104)
		(end 75.966066 -242.767104)
		(width 0.14478)
		(layer "In2.Cu")
		(net "M_C_CPU1_SA_DQ<29>")
	)
	(segment
		(start 83.289648 -244.001798)
		(end 83.29803 -243.996972)
		(width 0.0889)
		(layer "In2.Cu")
		(net "M_C_CPU1_SA_DQ<29>")
	)
	(segment
		(start 48.886872 -233.074464)
		(end 49.04994 -233.237532)
		(width 0.14478)
		(layer "In2.Cu")
		(net "M_C_CPU1_SA_DQ<29>")
	)
	(segment
		(start 48.330358 -233.46029)
		(end 48.493426 -233.297222)
		(width 0.14478)
		(layer "In2.Cu")
		(net "M_C_CPU1_SA_DQ<29>")
	)
	(segment
		(start 45.538136 -233.223054)
		(end 45.701204 -233.059986)
		(width 0.14478)
		(layer "In2.Cu")
		(net "M_C_CPU1_SA_DQ<29>")
	)
	(segment
		(start 85.74405 -243.996972)
		(end 85.752432 -244.001798)
		(width 0.0889)
		(layer "In2.Cu")
		(net "M_C_CPU1_SA_DQ<29>")
	)
	(segment
		(start 80.46974 -244.001798)
		(end 80.478122 -243.996972)
		(width 0.0889)
		(layer "In2.Cu")
		(net "M_C_CPU1_SA_DQ<29>")
	)
	(segment
		(start 61.87821 -234.324398)
		(end 62.121796 -234.324398)
		(width 0.14478)
		(layer "In2.Cu")
		(net "M_C_CPU1_SA_DQ<29>")
	)
	(segment
		(start 63.682372 -235.884974)
		(end 63.95085 -236.153452)
		(width 0.14478)
		(layer "In2.Cu")
		(net "M_C_CPU1_SA_DQ<29>")
	)
	(segment
		(start 92.68968 -244.001798)
		(end 92.698062 -243.996972)
		(width 0.0889)
		(layer "In2.Cu")
		(net "M_C_CPU1_SA_DQ<29>")
	)
	(segment
		(start 49.213008 -233.46029)
		(end 49.427384 -233.46029)
		(width 0.14478)
		(layer "In2.Cu")
		(net "M_C_CPU1_SA_DQ<29>")
	)
	(segment
		(start 62.39002 -234.836208)
		(end 62.658498 -235.104686)
		(width 0.14478)
		(layer "In2.Cu")
		(net "M_C_CPU1_SA_DQ<29>")
	)
	(segment
		(start 45.538136 -233.297222)
		(end 45.538136 -233.223054)
		(width 0.14478)
		(layer "In2.Cu")
		(net "M_C_CPU1_SA_DQ<29>")
	)
	(segment
		(start 46.09465 -233.223054)
		(end 46.09465 -233.69778)
		(width 0.14478)
		(layer "In2.Cu")
		(net "M_C_CPU1_SA_DQ<29>")
	)
	(segment
		(start 47.207678 -233.234992)
		(end 47.207678 -233.297222)
		(width 0.14478)
		(layer "In2.Cu")
		(net "M_C_CPU1_SA_DQ<29>")
	)
	(segment
		(start 55.849012 -233.46029)
		(end 56.01208 -233.297222)
		(width 0.14478)
		(layer "In2.Cu")
		(net "M_C_CPU1_SA_DQ<29>")
	)
	(segment
		(start 51.31689 -232.447338)
		(end 51.479958 -232.610406)
		(width 0.14478)
		(layer "In2.Cu")
		(net "M_C_CPU1_SA_DQ<29>")
	)
	(segment
		(start 46.257718 -233.860848)
		(end 46.488096 -233.860848)
		(width 0.14478)
		(layer "In2.Cu")
		(net "M_C_CPU1_SA_DQ<29>")
	)
	(segment
		(start 87.989664 -244.001798)
		(end 87.998046 -243.996972)
		(width 0.0889)
		(layer "In2.Cu")
		(net "M_C_CPU1_SA_DQ<29>")
	)
	(segment
		(start 51.153822 -232.221024)
		(end 51.31689 -232.384092)
		(width 0.14478)
		(layer "In2.Cu")
		(net "M_C_CPU1_SA_DQ<29>")
	)
	(segment
		(start 47.370746 -233.46029)
		(end 48.330358 -233.46029)
		(width 0.14478)
		(layer "In2.Cu")
		(net "M_C_CPU1_SA_DQ<29>")
	)
	(segment
		(start 65.242948 -237.44555)
		(end 65.511426 -237.714028)
		(width 0.14478)
		(layer "In2.Cu")
		(net "M_C_CPU1_SA_DQ<29>")
	)
	(segment
		(start 84.229702 -244.001798)
		(end 84.238084 -243.996972)
		(width 0.0889)
		(layer "In2.Cu")
		(net "M_C_CPU1_SA_DQ<29>")
	)
	(segment
		(start 66.023236 -238.225838)
		(end 66.291714 -238.494316)
		(width 0.14478)
		(layer "In2.Cu")
		(net "M_C_CPU1_SA_DQ<29>")
	)
	(segment
		(start 50.277268 -232.610406)
		(end 50.597308 -232.610406)
		(width 0.14478)
		(layer "In2.Cu")
		(net "M_C_CPU1_SA_DQ<29>")
	)
	(segment
		(start 63.170308 -235.388404)
		(end 63.170308 -235.616496)
		(width 0.14478)
		(layer "In2.Cu")
		(net "M_C_CPU1_SA_DQ<29>")
	)
	(segment
		(start 56.950864 -233.46029)
		(end 57.800748 -232.610406)
		(width 0.14478)
		(layer "In2.Cu")
		(net "M_C_CPU1_SA_DQ<29>")
	)
	(segment
		(start 50.923444 -232.221024)
		(end 51.153822 -232.221024)
		(width 0.14478)
		(layer "In2.Cu")
		(net "M_C_CPU1_SA_DQ<29>")
	)
	(segment
		(start 60.339732 -232.218484)
		(end 60.5028 -232.381552)
		(width 0.14478)
		(layer "In2.Cu")
		(net "M_C_CPU1_SA_DQ<29>")
	)
	(segment
		(start 94.204028 -243.996972)
		(end 94.21241 -244.001798)
		(width 0.0889)
		(layer "In2.Cu")
		(net "M_C_CPU1_SA_DQ<29>")
	)
	(segment
		(start 62.39002 -234.608116)
		(end 62.39002 -234.836208)
		(width 0.14478)
		(layer "In2.Cu")
		(net "M_C_CPU1_SA_DQ<29>")
	)
	(segment
		(start 54.389274 -233.082084)
		(end 54.619652 -233.082084)
		(width 0.14478)
		(layer "In2.Cu")
		(net "M_C_CPU1_SA_DQ<29>")
	)
	(segment
		(start 63.95085 -236.153452)
		(end 63.950596 -236.168692)
		(width 0.14478)
		(layer "In2.Cu")
		(net "M_C_CPU1_SA_DQ<29>")
	)
	(segment
		(start 50.597308 -232.610406)
		(end 50.760376 -232.447338)
		(width 0.14478)
		(layer "In2.Cu")
		(net "M_C_CPU1_SA_DQ<29>")
	)
	(segment
		(start 65.511426 -237.714028)
		(end 65.511172 -237.729268)
		(width 0.14478)
		(layer "In2.Cu")
		(net "M_C_CPU1_SA_DQ<29>")
	)
	(segment
		(start 49.04994 -233.297222)
		(end 49.213008 -233.46029)
		(width 0.14478)
		(layer "In2.Cu")
		(net "M_C_CPU1_SA_DQ<29>")
	)
	(segment
		(start 60.726066 -232.928668)
		(end 61.609986 -233.812588)
		(width 0.14478)
		(layer "In2.Cu")
		(net "M_C_CPU1_SA_DQ<29>")
	)
	(segment
		(start 45.931582 -233.059986)
		(end 46.09465 -233.223054)
		(width 0.14478)
		(layer "In2.Cu")
		(net "M_C_CPU1_SA_DQ<29>")
	)
	(segment
		(start 84.803996 -243.996972)
		(end 84.812378 -244.001798)
		(width 0.0889)
		(layer "In2.Cu")
		(net "M_C_CPU1_SA_DQ<29>")
	)
	(segment
		(start 56.405526 -233.074464)
		(end 56.568594 -233.237532)
		(width 0.14478)
		(layer "In2.Cu")
		(net "M_C_CPU1_SA_DQ<29>")
	)
	(segment
		(start 56.01208 -233.237532)
		(end 56.175148 -233.074464)
		(width 0.14478)
		(layer "In2.Cu")
		(net "M_C_CPU1_SA_DQ<29>")
	)
	(segment
		(start 67.799712 -239.396524)
		(end 71.170292 -242.767104)
		(width 0.14478)
		(layer "In2.Cu")
		(net "M_C_CPU1_SA_DQ<29>")
	)
	(segment
		(start 65.511172 -237.729268)
		(end 65.511172 -237.95736)
		(width 0.14478)
		(layer "In2.Cu")
		(net "M_C_CPU1_SA_DQ<29>")
	)
	(segment
		(start 48.493426 -233.237532)
		(end 48.656494 -233.074464)
		(width 0.14478)
		(layer "In2.Cu")
		(net "M_C_CPU1_SA_DQ<29>")
	)
	(segment
		(start 63.438786 -235.884974)
		(end 63.682372 -235.884974)
		(width 0.14478)
		(layer "In2.Cu")
		(net "M_C_CPU1_SA_DQ<29>")
	)
	(segment
		(start 45.375068 -233.46029)
		(end 45.538136 -233.297222)
		(width 0.14478)
		(layer "In2.Cu")
		(net "M_C_CPU1_SA_DQ<29>")
	)
	(segment
		(start 56.01208 -233.297222)
		(end 56.01208 -233.237532)
		(width 0.14478)
		(layer "In2.Cu")
		(net "M_C_CPU1_SA_DQ<29>")
	)
	(segment
		(start 56.175148 -233.074464)
		(end 56.405526 -233.074464)
		(width 0.14478)
		(layer "In2.Cu")
		(net "M_C_CPU1_SA_DQ<29>")
	)
	(segment
		(start 56.568594 -233.297222)
		(end 56.731662 -233.46029)
		(width 0.14478)
		(layer "In2.Cu")
		(net "M_C_CPU1_SA_DQ<29>")
	)
	(segment
		(start 46.09465 -233.69778)
		(end 46.257718 -233.860848)
		(width 0.14478)
		(layer "In2.Cu")
		(net "M_C_CPU1_SA_DQ<29>")
	)
	(segment
		(start 60.5028 -232.447338)
		(end 60.726066 -232.670604)
		(width 0.14478)
		(layer "In2.Cu")
		(net "M_C_CPU1_SA_DQ<29>")
	)
	(segment
		(start 56.731662 -233.46029)
		(end 56.950864 -233.46029)
		(width 0.14478)
		(layer "In2.Cu")
		(net "M_C_CPU1_SA_DQ<29>")
	)
	(segment
		(start 44.340018 -233.035348)
		(end 44.76496 -233.46029)
		(width 0.14478)
		(layer "In2.Cu")
		(net "M_C_CPU1_SA_DQ<29>")
	)
	(segment
		(start 53.791866 -233.46029)
		(end 54.063138 -233.46029)
		(width 0.14478)
		(layer "In2.Cu")
		(net "M_C_CPU1_SA_DQ<29>")
	)
	(segment
		(start 48.493426 -233.297222)
		(end 48.493426 -233.237532)
		(width 0.14478)
		(layer "In2.Cu")
		(net "M_C_CPU1_SA_DQ<29>")
	)
	(segment
		(start 95.48495 -243.939822)
		(end 95.331026 -243.674392)
		(width 0.0889)
		(layer "In2.Cu")
		(net "M_C_CPU1_SA_DQ<29>")
	)
	(segment
		(start 62.390274 -234.592876)
		(end 62.39002 -234.608116)
		(width 0.14478)
		(layer "In2.Cu")
		(net "M_C_CPU1_SA_DQ<29>")
	)
	(segment
		(start 79.5401 -243.996718)
		(end 79.566262 -243.981732)
		(width 0.0889)
		(layer "In2.Cu")
		(net "M_C_CPU1_SA_DQ<29>")
	)
	(segment
		(start 64.730884 -237.177072)
		(end 64.999362 -237.44555)
		(width 0.14478)
		(layer "In2.Cu")
		(net "M_C_CPU1_SA_DQ<29>")
	)
	(segment
		(start 51.31689 -232.384092)
		(end 51.31689 -232.447338)
		(width 0.14478)
		(layer "In2.Cu")
		(net "M_C_CPU1_SA_DQ<29>")
	)
	(segment
		(start 45.701204 -233.059986)
		(end 45.931582 -233.059986)
		(width 0.14478)
		(layer "In2.Cu")
		(net "M_C_CPU1_SA_DQ<29>")
	)
	(segment
		(start 77.063346 -243.915184)
		(end 77.944472 -243.915184)
		(width 0.0889)
		(layer "In2.Cu")
		(net "M_C_CPU1_SA_DQ<29>")
	)
	(segment
		(start 46.814232 -233.071924)
		(end 47.04461 -233.071924)
		(width 0.14478)
		(layer "In2.Cu")
		(net "M_C_CPU1_SA_DQ<29>")
	)
	(segment
		(start 76.138786 -242.767104)
		(end 76.456286 -243.084604)
		(width 0.0889)
		(layer "In2.Cu")
		(net "M_C_CPU1_SA_DQ<29>")
	)
	(segment
		(start 52.385468 -232.292144)
		(end 52.62372 -232.292144)
		(width 0.14478)
		(layer "In2.Cu")
		(net "M_C_CPU1_SA_DQ<29>")
	)
	(segment
		(start 76.456286 -243.084604)
		(end 76.456286 -243.308124)
		(width 0.0889)
		(layer "In2.Cu")
		(net "M_C_CPU1_SA_DQ<29>")
	)
	(segment
		(start 58.193178 -232.610406)
		(end 58.356246 -232.447338)
		(width 0.14478)
		(layer "In2.Cu")
		(net "M_C_CPU1_SA_DQ<29>")
	)
	(segment
		(start 49.427384 -233.46029)
		(end 50.277268 -232.610406)
		(width 0.14478)
		(layer "In2.Cu")
		(net "M_C_CPU1_SA_DQ<29>")
	)
	(segment
		(start 64.219074 -236.665262)
		(end 64.46266 -236.665262)
		(width 0.14478)
		(layer "In2.Cu")
		(net "M_C_CPU1_SA_DQ<29>")
	)
	(segment
		(start 54.78272 -233.297222)
		(end 54.945788 -233.46029)
		(width 0.14478)
		(layer "In2.Cu")
		(net "M_C_CPU1_SA_DQ<29>")
	)
	(segment
		(start 58.519314 -232.215944)
		(end 58.749692 -232.215944)
		(width 0.14478)
		(layer "In2.Cu")
		(net "M_C_CPU1_SA_DQ<29>")
	)
	(segment
		(start 54.226206 -233.245152)
		(end 54.389274 -233.082084)
		(width 0.14478)
		(layer "In2.Cu")
		(net "M_C_CPU1_SA_DQ<29>")
	)
	(segment
		(start 59.783218 -232.610406)
		(end 59.946286 -232.447338)
		(width 0.14478)
		(layer "In2.Cu")
		(net "M_C_CPU1_SA_DQ<29>")
	)
	(segment
		(start 49.04994 -233.237532)
		(end 49.04994 -233.297222)
		(width 0.14478)
		(layer "In2.Cu")
		(net "M_C_CPU1_SA_DQ<29>")
	)
	(segment
		(start 64.730884 -236.94898)
		(end 64.730884 -237.177072)
		(width 0.14478)
		(layer "In2.Cu")
		(net "M_C_CPU1_SA_DQ<29>")
	)
	(segment
		(start 51.479958 -232.610406)
		(end 52.067206 -232.610406)
		(width 0.14478)
		(layer "In2.Cu")
		(net "M_C_CPU1_SA_DQ<29>")
	)
	(segment
		(start 61.609986 -233.812588)
		(end 61.609732 -233.827828)
		(width 0.14478)
		(layer "In2.Cu")
		(net "M_C_CPU1_SA_DQ<29>")
	)
	(segment
		(start 62.902084 -235.104686)
		(end 63.170562 -235.373164)
		(width 0.14478)
		(layer "In2.Cu")
		(net "M_C_CPU1_SA_DQ<29>")
	)
	(segment
		(start 95.462598 -244.023134)
		(end 95.48495 -243.939822)
		(width 0.0889)
		(layer "In2.Cu")
		(net "M_C_CPU1_SA_DQ<29>")
	)
	(segment
		(start 66.29146 -238.737648)
		(end 66.559938 -239.006126)
		(width 0.14478)
		(layer "In2.Cu")
		(net "M_C_CPU1_SA_DQ<29>")
	)
	(segment
		(start 58.91276 -232.447338)
		(end 59.075828 -232.610406)
		(width 0.14478)
		(layer "In2.Cu")
		(net "M_C_CPU1_SA_DQ<29>")
	)
	(segment
		(start 46.651164 -233.69778)
		(end 46.651164 -233.234992)
		(width 0.14478)
		(layer "In2.Cu")
		(net "M_C_CPU1_SA_DQ<29>")
	)
	(segment
		(start 76.456286 -243.308124)
		(end 77.063346 -243.915184)
		(width 0.0889)
		(layer "In2.Cu")
		(net "M_C_CPU1_SA_DQ<29>")
	)
	(segment
		(start 60.5028 -232.381552)
		(end 60.5028 -232.447338)
		(width 0.14478)
		(layer "In2.Cu")
		(net "M_C_CPU1_SA_DQ<29>")
	)
	(segment
		(start 47.207678 -233.297222)
		(end 47.370746 -233.46029)
		(width 0.14478)
		(layer "In2.Cu")
		(net "M_C_CPU1_SA_DQ<29>")
	)
	(segment
		(start 63.950596 -236.168692)
		(end 63.950596 -236.396784)
		(width 0.14478)
		(layer "In2.Cu")
		(net "M_C_CPU1_SA_DQ<29>")
	)
	(segment
		(start 62.121796 -234.324398)
		(end 62.390274 -234.592876)
		(width 0.14478)
		(layer "In2.Cu")
		(net "M_C_CPU1_SA_DQ<29>")
	)
	(segment
		(start 50.760376 -232.384092)
		(end 50.923444 -232.221024)
		(width 0.14478)
		(layer "In2.Cu")
		(net "M_C_CPU1_SA_DQ<29>")
	)
	(segment
		(start 54.226206 -233.297222)
		(end 54.226206 -233.245152)
		(width 0.14478)
		(layer "In2.Cu")
		(net "M_C_CPU1_SA_DQ<29>")
	)
	(segment
		(start 79.518256 -244.009164)
		(end 79.5401 -243.996718)
		(width 0.0889)
		(layer "In2.Cu")
		(net "M_C_CPU1_SA_DQ<29>")
	)
	(segment
		(start 59.946286 -232.381552)
		(end 60.109354 -232.218484)
		(width 0.14478)
		(layer "In2.Cu")
		(net "M_C_CPU1_SA_DQ<29>")
	)
	(segment
		(start 66.559938 -239.006126)
		(end 66.803524 -239.006126)
		(width 0.14478)
		(layer "In2.Cu")
		(net "M_C_CPU1_SA_DQ<29>")
	)
	(segment
		(start 65.511172 -237.95736)
		(end 65.77965 -238.225838)
		(width 0.14478)
		(layer "In2.Cu")
		(net "M_C_CPU1_SA_DQ<29>")
	)
	(segment
		(start 60.726066 -232.670604)
		(end 60.726066 -232.928668)
		(width 0.14478)
		(layer "In2.Cu")
		(net "M_C_CPU1_SA_DQ<29>")
	)
	(segment
		(start 46.488096 -233.860848)
		(end 46.651164 -233.69778)
		(width 0.14478)
		(layer "In2.Cu")
		(net "M_C_CPU1_SA_DQ<29>")
	)
	(segment
		(start 61.609732 -233.827828)
		(end 61.609732 -234.05592)
		(width 0.14478)
		(layer "In2.Cu")
		(net "M_C_CPU1_SA_DQ<29>")
	)
	(segment
		(start 58.356246 -232.447338)
		(end 58.356246 -232.379012)
		(width 0.14478)
		(layer "In2.Cu")
		(net "M_C_CPU1_SA_DQ<29>")
	)
	(segment
		(start 91.749626 -244.001798)
		(end 91.758008 -243.996972)
		(width 0.0889)
		(layer "In2.Cu")
		(net "M_C_CPU1_SA_DQ<29>")
	)
	(segment
		(start 64.46266 -236.665262)
		(end 64.731138 -236.93374)
		(width 0.14478)
		(layer "In2.Cu")
		(net "M_C_CPU1_SA_DQ<29>")
	)
	(segment
		(start 89.504012 -243.996972)
		(end 89.512394 -244.001798)
		(width 0.0889)
		(layer "In2.Cu")
		(net "M_C_CPU1_SA_DQ<29>")
	)
	(segment
		(start 54.063138 -233.46029)
		(end 54.226206 -233.297222)
		(width 0.14478)
		(layer "In2.Cu")
		(net "M_C_CPU1_SA_DQ<29>")
	)
	(segment
		(start 46.651164 -233.234992)
		(end 46.814232 -233.071924)
		(width 0.14478)
		(layer "In2.Cu")
		(net "M_C_CPU1_SA_DQ<29>")
	)
	(segment
		(start 63.170308 -235.616496)
		(end 63.438786 -235.884974)
		(width 0.14478)
		(layer "In2.Cu")
		(net "M_C_CPU1_SA_DQ<29>")
	)
	(segment
		(start 64.731138 -236.93374)
		(end 64.730884 -236.94898)
		(width 0.14478)
		(layer "In2.Cu")
		(net "M_C_CPU1_SA_DQ<29>")
	)
	(segment
		(start 78.202282 -243.98351)
		(end 78.256892 -244.014498)
		(width 0.0889)
		(layer "In2.Cu")
		(net "M_C_CPU1_SA_DQ<29>")
	)
	(segment
		(start 59.946286 -232.447338)
		(end 59.946286 -232.381552)
		(width 0.14478)
		(layer "In2.Cu")
		(net "M_C_CPU1_SA_DQ<29>")
	)
	(segment
		(start 48.656494 -233.074464)
		(end 48.886872 -233.074464)
		(width 0.14478)
		(layer "In2.Cu")
		(net "M_C_CPU1_SA_DQ<29>")
	)
	(segment
		(start 65.77965 -238.225838)
		(end 66.023236 -238.225838)
		(width 0.14478)
		(layer "In2.Cu")
		(net "M_C_CPU1_SA_DQ<29>")
	)
	(segment
		(start 81.044034 -243.996972)
		(end 81.052416 -244.001798)
		(width 0.0889)
		(layer "In2.Cu")
		(net "M_C_CPU1_SA_DQ<29>")
	)
	(segment
		(start 54.945788 -233.46029)
		(end 55.849012 -233.46029)
		(width 0.14478)
		(layer "In2.Cu")
		(net "M_C_CPU1_SA_DQ<29>")
	)
	(segment
		(start 50.760376 -232.447338)
		(end 50.760376 -232.384092)
		(width 0.14478)
		(layer "In2.Cu")
		(net "M_C_CPU1_SA_DQ<29>")
	)
	(segment
		(start 58.356246 -232.379012)
		(end 58.519314 -232.215944)
		(width 0.14478)
		(layer "In2.Cu")
		(net "M_C_CPU1_SA_DQ<29>")
	)
	(segment
		(start 75.966066 -242.767104)
		(end 76.138786 -242.767104)
		(width 0.0889)
		(layer "In2.Cu")
		(net "M_C_CPU1_SA_DQ<29>")
	)
	(segment
		(start 67.193922 -239.396524)
		(end 67.799712 -239.396524)
		(width 0.14478)
		(layer "In2.Cu")
		(net "M_C_CPU1_SA_DQ<29>")
	)
	(segment
		(start 63.170562 -235.373164)
		(end 63.170308 -235.388404)
		(width 0.14478)
		(layer "In2.Cu")
		(net "M_C_CPU1_SA_DQ<29>")
	)
	(segment
		(start 58.91276 -232.379012)
		(end 58.91276 -232.447338)
		(width 0.14478)
		(layer "In2.Cu")
		(net "M_C_CPU1_SA_DQ<29>")
	)
	(segment
		(start 44.76496 -233.46029)
		(end 45.375068 -233.46029)
		(width 0.14478)
		(layer "In2.Cu")
		(net "M_C_CPU1_SA_DQ<29>")
	)
	(segment
		(start 79.138018 -243.9797)
		(end 79.167482 -243.996972)
		(width 0.0889)
		(layer "In2.Cu")
		(net "M_C_CPU1_SA_DQ<29>")
	)
	(segment
		(start 52.067206 -232.610406)
		(end 52.385468 -232.292144)
		(width 0.14478)
		(layer "In2.Cu")
		(net "M_C_CPU1_SA_DQ<29>")
	)
	(segment
		(start 54.619652 -233.082084)
		(end 54.78272 -233.245152)
		(width 0.14478)
		(layer "In2.Cu")
		(net "M_C_CPU1_SA_DQ<29>")
	)
	(segment
		(start 58.749692 -232.215944)
		(end 58.91276 -232.379012)
		(width 0.14478)
		(layer "In2.Cu")
		(net "M_C_CPU1_SA_DQ<29>")
	)
	(segment
		(start 93.263974 -243.996972)
		(end 93.272356 -244.001798)
		(width 0.0889)
		(layer "In2.Cu")
		(net "M_C_CPU1_SA_DQ<29>")
	)
	(segment
		(start 52.62372 -232.292144)
		(end 53.791866 -233.46029)
		(width 0.14478)
		(layer "In2.Cu")
		(net "M_C_CPU1_SA_DQ<29>")
	)
	(segment
		(start 88.929718 -244.001798)
		(end 88.9381 -243.996972)
		(width 0.0889)
		(layer "In2.Cu")
		(net "M_C_CPU1_SA_DQ<29>")
	)
	(segment
		(start 66.29146 -238.509556)
		(end 66.29146 -238.737648)
		(width 0.14478)
		(layer "In2.Cu")
		(net "M_C_CPU1_SA_DQ<29>")
	)
	(segment
		(start 61.609732 -234.05592)
		(end 61.87821 -234.324398)
		(width 0.14478)
		(layer "In2.Cu")
		(net "M_C_CPU1_SA_DQ<29>")
	)
	(segment
		(start 63.950596 -236.396784)
		(end 64.219074 -236.665262)
		(width 0.14478)
		(layer "In2.Cu")
		(net "M_C_CPU1_SA_DQ<29>")
	)
	(segment
		(start 47.04461 -233.071924)
		(end 47.207678 -233.234992)
		(width 0.14478)
		(layer "In2.Cu")
		(net "M_C_CPU1_SA_DQ<29>")
	)
	(segment
		(start 64.999362 -237.44555)
		(end 65.242948 -237.44555)
		(width 0.14478)
		(layer "In2.Cu")
		(net "M_C_CPU1_SA_DQ<29>")
	)
	(arc
		(start 93.272356 -244.001798)
		(mid 93.455864 -244.047292)
		(end 93.638116 -243.996972)
		(width 0.0889)
		(layer "In2.Cu")
		(net "M_C_CPU1_SA_DQ<29>")
	)
	(arc
		(start 95.144082 -243.996972)
		(mid 95.300401 -244.045967)
		(end 95.462598 -244.023134)
		(width 0.0889)
		(layer "In2.Cu")
		(net "M_C_CPU1_SA_DQ<29>")
	)
	(arc
		(start 81.418176 -243.996972)
		(mid 81.701132 -243.920795)
		(end 81.984088 -243.996972)
		(width 0.0889)
		(layer "In2.Cu")
		(net "M_C_CPU1_SA_DQ<29>")
	)
	(arc
		(start 86.118192 -243.996972)
		(mid 86.401148 -243.920795)
		(end 86.684104 -243.996972)
		(width 0.0889)
		(layer "In2.Cu")
		(net "M_C_CPU1_SA_DQ<29>")
	)
	(arc
		(start 89.878154 -243.996972)
		(mid 90.16111 -243.920795)
		(end 90.444066 -243.996972)
		(width 0.0889)
		(layer "In2.Cu")
		(net "M_C_CPU1_SA_DQ<29>")
	)
	(arc
		(start 78.599538 -243.996972)
		(mid 78.866595 -243.919937)
		(end 79.138018 -243.9797)
		(width 0.0889)
		(layer "In2.Cu")
		(net "M_C_CPU1_SA_DQ<29>")
	)
	(arc
		(start 85.752432 -244.001798)
		(mid 85.93594 -244.047292)
		(end 86.118192 -243.996972)
		(width 0.0889)
		(layer "In2.Cu")
		(net "M_C_CPU1_SA_DQ<29>")
	)
	(arc
		(start 82.357976 -243.996972)
		(mid 82.640932 -243.920795)
		(end 82.923888 -243.996972)
		(width 0.0889)
		(layer "In2.Cu")
		(net "M_C_CPU1_SA_DQ<29>")
	)
	(arc
		(start 86.684104 -243.996972)
		(mid 86.871048 -244.047227)
		(end 87.057992 -243.996972)
		(width 0.0889)
		(layer "In2.Cu")
		(net "M_C_CPU1_SA_DQ<29>")
	)
	(arc
		(start 77.944472 -243.915184)
		(mid 78.077814 -243.932596)
		(end 78.202282 -243.98351)
		(width 0.0889)
		(layer "In2.Cu")
		(net "M_C_CPU1_SA_DQ<29>")
	)
	(arc
		(start 83.863942 -243.996972)
		(mid 84.046193 -244.047322)
		(end 84.229702 -244.001798)
		(width 0.0889)
		(layer "In2.Cu")
		(net "M_C_CPU1_SA_DQ<29>")
	)
	(arc
		(start 79.566262 -243.981732)
		(mid 79.837048 -243.921086)
		(end 80.10398 -243.996972)
		(width 0.0889)
		(layer "In2.Cu")
		(net "M_C_CPU1_SA_DQ<29>")
	)
	(arc
		(start 83.29803 -243.996972)
		(mid 83.580986 -243.920795)
		(end 83.863942 -243.996972)
		(width 0.0889)
		(layer "In2.Cu")
		(net "M_C_CPU1_SA_DQ<29>")
	)
	(arc
		(start 92.698062 -243.996972)
		(mid 92.981018 -243.920795)
		(end 93.263974 -243.996972)
		(width 0.0889)
		(layer "In2.Cu")
		(net "M_C_CPU1_SA_DQ<29>")
	)
	(arc
		(start 87.623904 -243.996972)
		(mid 87.806155 -244.047322)
		(end 87.989664 -244.001798)
		(width 0.0889)
		(layer "In2.Cu")
		(net "M_C_CPU1_SA_DQ<29>")
	)
	(arc
		(start 90.817954 -243.996972)
		(mid 91.10091 -243.920795)
		(end 91.383866 -243.996972)
		(width 0.0889)
		(layer "In2.Cu")
		(net "M_C_CPU1_SA_DQ<29>")
	)
	(arc
		(start 87.998046 -243.996972)
		(mid 88.281002 -243.920795)
		(end 88.563958 -243.996972)
		(width 0.0889)
		(layer "In2.Cu")
		(net "M_C_CPU1_SA_DQ<29>")
	)
	(arc
		(start 88.563958 -243.996972)
		(mid 88.746209 -244.047322)
		(end 88.929718 -244.001798)
		(width 0.0889)
		(layer "In2.Cu")
		(net "M_C_CPU1_SA_DQ<29>")
	)
	(arc
		(start 90.444066 -243.996972)
		(mid 90.63101 -244.047227)
		(end 90.817954 -243.996972)
		(width 0.0889)
		(layer "In2.Cu")
		(net "M_C_CPU1_SA_DQ<29>")
	)
	(arc
		(start 81.052416 -244.001798)
		(mid 81.235924 -244.047292)
		(end 81.418176 -243.996972)
		(width 0.0889)
		(layer "In2.Cu")
		(net "M_C_CPU1_SA_DQ<29>")
	)
	(arc
		(start 88.9381 -243.996972)
		(mid 89.221056 -243.920795)
		(end 89.504012 -243.996972)
		(width 0.0889)
		(layer "In2.Cu")
		(net "M_C_CPU1_SA_DQ<29>")
	)
	(arc
		(start 84.812378 -244.001798)
		(mid 84.995886 -244.047292)
		(end 85.178138 -243.996972)
		(width 0.0889)
		(layer "In2.Cu")
		(net "M_C_CPU1_SA_DQ<29>")
	)
	(arc
		(start 91.383866 -243.996972)
		(mid 91.566117 -244.047322)
		(end 91.749626 -244.001798)
		(width 0.0889)
		(layer "In2.Cu")
		(net "M_C_CPU1_SA_DQ<29>")
	)
	(arc
		(start 94.21241 -244.001798)
		(mid 94.395918 -244.047292)
		(end 94.57817 -243.996972)
		(width 0.0889)
		(layer "In2.Cu")
		(net "M_C_CPU1_SA_DQ<29>")
	)
	(arc
		(start 85.178138 -243.996972)
		(mid 85.461094 -243.920795)
		(end 85.74405 -243.996972)
		(width 0.0889)
		(layer "In2.Cu")
		(net "M_C_CPU1_SA_DQ<29>")
	)
	(arc
		(start 79.167482 -243.996972)
		(mid 79.341332 -244.046878)
		(end 79.518256 -244.009164)
		(width 0.0889)
		(layer "In2.Cu")
		(net "M_C_CPU1_SA_DQ<29>")
	)
	(arc
		(start 81.984088 -243.996972)
		(mid 82.171032 -244.047227)
		(end 82.357976 -243.996972)
		(width 0.0889)
		(layer "In2.Cu")
		(net "M_C_CPU1_SA_DQ<29>")
	)
	(arc
		(start 78.256892 -244.014498)
		(mid 78.430354 -244.047432)
		(end 78.599538 -243.996972)
		(width 0.0889)
		(layer "In2.Cu")
		(net "M_C_CPU1_SA_DQ<29>")
	)
	(arc
		(start 94.57817 -243.996972)
		(mid 94.861126 -243.920795)
		(end 95.144082 -243.996972)
		(width 0.0889)
		(layer "In2.Cu")
		(net "M_C_CPU1_SA_DQ<29>")
	)
	(arc
		(start 92.32392 -243.996972)
		(mid 92.506171 -244.047322)
		(end 92.68968 -244.001798)
		(width 0.0889)
		(layer "In2.Cu")
		(net "M_C_CPU1_SA_DQ<29>")
	)
	(arc
		(start 91.758008 -243.996972)
		(mid 92.040964 -243.920795)
		(end 92.32392 -243.996972)
		(width 0.0889)
		(layer "In2.Cu")
		(net "M_C_CPU1_SA_DQ<29>")
	)
	(arc
		(start 80.478122 -243.996972)
		(mid 80.761078 -243.920795)
		(end 81.044034 -243.996972)
		(width 0.0889)
		(layer "In2.Cu")
		(net "M_C_CPU1_SA_DQ<29>")
	)
	(arc
		(start 87.057992 -243.996972)
		(mid 87.340948 -243.920795)
		(end 87.623904 -243.996972)
		(width 0.0889)
		(layer "In2.Cu")
		(net "M_C_CPU1_SA_DQ<29>")
	)
	(arc
		(start 82.923888 -243.996972)
		(mid 83.106139 -244.047322)
		(end 83.289648 -244.001798)
		(width 0.0889)
		(layer "In2.Cu")
		(net "M_C_CPU1_SA_DQ<29>")
	)
	(arc
		(start 93.638116 -243.996972)
		(mid 93.921072 -243.920795)
		(end 94.204028 -243.996972)
		(width 0.0889)
		(layer "In2.Cu")
		(net "M_C_CPU1_SA_DQ<29>")
	)
	(arc
		(start 89.512394 -244.001798)
		(mid 89.695902 -244.047292)
		(end 89.878154 -243.996972)
		(width 0.0889)
		(layer "In2.Cu")
		(net "M_C_CPU1_SA_DQ<29>")
	)
	(arc
		(start 80.10398 -243.996972)
		(mid 80.286231 -244.047322)
		(end 80.46974 -244.001798)
		(width 0.0889)
		(layer "In2.Cu")
		(net "M_C_CPU1_SA_DQ<29>")
	)
	(arc
		(start 84.238084 -243.996972)
		(mid 84.52104 -243.920795)
		(end 84.803996 -243.996972)
		(width 0.0889)
		(layer "In2.Cu")
		(net "M_C_CPU1_SA_DQ<29>")
	)
	(segment
		(start 94.387924 -243.130324)
		(end 93.921072 -242.864386)
		(width 0.10668)
		(layer "F.Cu")
		(net "M_C_CPU1_SA_DQ<28>")
	)
	(segment
		(start 64.091058 -234.620054)
		(end 64.00546 -234.705652)
		(width 0.14478)
		(layer "In2.Cu")
		(net "M_C_CPU1_SA_DQ<28>")
	)
	(segment
		(start 62.430406 -233.360976)
		(end 62.593728 -233.524298)
		(width 0.14478)
		(layer "In2.Cu")
		(net "M_C_CPU1_SA_DQ<28>")
	)
	(segment
		(start 46.030134 -231.981756)
		(end 46.193202 -232.144824)
		(width 0.14478)
		(layer "In2.Cu")
		(net "M_C_CPU1_SA_DQ<28>")
	)
	(segment
		(start 63.697358 -234.2261)
		(end 63.92799 -234.226354)
		(width 0.14478)
		(layer "In2.Cu")
		(net "M_C_CPU1_SA_DQ<28>")
	)
	(segment
		(start 63.92799 -234.226354)
		(end 64.091058 -234.389422)
		(width 0.14478)
		(layer "In2.Cu")
		(net "M_C_CPU1_SA_DQ<28>")
	)
	(segment
		(start 75.955906 -241.829844)
		(end 76.557886 -241.829844)
		(width 0.0889)
		(layer "In2.Cu")
		(net "M_C_CPU1_SA_DQ<28>")
	)
	(segment
		(start 61.643006 -232.573576)
		(end 61.806328 -232.736898)
		(width 0.14478)
		(layer "In2.Cu")
		(net "M_C_CPU1_SA_DQ<28>")
	)
	(segment
		(start 64.00546 -234.705652)
		(end 64.005206 -234.935776)
		(width 0.14478)
		(layer "In2.Cu")
		(net "M_C_CPU1_SA_DQ<28>")
	)
	(segment
		(start 65.665858 -235.964222)
		(end 65.665858 -236.194854)
		(width 0.14478)
		(layer "In2.Cu")
		(net "M_C_CPU1_SA_DQ<28>")
	)
	(segment
		(start 79.99984 -243.191792)
		(end 80.008222 -243.186966)
		(width 0.0889)
		(layer "In2.Cu")
		(net "M_C_CPU1_SA_DQ<28>")
	)
	(segment
		(start 48.887126 -231.76992)
		(end 49.14011 -232.022904)
		(width 0.14478)
		(layer "In2.Cu")
		(net "M_C_CPU1_SA_DQ<28>")
	)
	(segment
		(start 88.094058 -243.186966)
		(end 88.10244 -243.191792)
		(width 0.0889)
		(layer "In2.Cu")
		(net "M_C_CPU1_SA_DQ<28>")
	)
	(segment
		(start 62.909958 -233.4387)
		(end 63.14059 -233.438954)
		(width 0.14478)
		(layer "In2.Cu")
		(net "M_C_CPU1_SA_DQ<28>")
	)
	(segment
		(start 64.79286 -235.493052)
		(end 64.792606 -235.723176)
		(width 0.14478)
		(layer "In2.Cu")
		(net "M_C_CPU1_SA_DQ<28>")
	)
	(segment
		(start 79.067152 -243.186966)
		(end 79.081884 -243.17833)
		(width 0.0889)
		(layer "In2.Cu")
		(net "M_C_CPU1_SA_DQ<28>")
	)
	(segment
		(start 46.586648 -231.918256)
		(end 46.734984 -231.76992)
		(width 0.14478)
		(layer "In2.Cu")
		(net "M_C_CPU1_SA_DQ<28>")
	)
	(segment
		(start 86.57971 -243.191792)
		(end 86.588092 -243.186966)
		(width 0.0889)
		(layer "In2.Cu")
		(net "M_C_CPU1_SA_DQ<28>")
	)
	(segment
		(start 67.15506 -237.855252)
		(end 67.154806 -238.085376)
		(width 0.14478)
		(layer "In2.Cu")
		(net "M_C_CPU1_SA_DQ<28>")
	)
	(segment
		(start 66.367406 -237.297976)
		(end 66.530728 -237.461298)
		(width 0.14478)
		(layer "In2.Cu")
		(net "M_C_CPU1_SA_DQ<28>")
	)
	(segment
		(start 90.339672 -243.191792)
		(end 90.348054 -243.186966)
		(width 0.0889)
		(layer "In2.Cu")
		(net "M_C_CPU1_SA_DQ<28>")
	)
	(segment
		(start 45.310552 -232.144824)
		(end 45.47362 -231.981756)
		(width 0.14478)
		(layer "In2.Cu")
		(net "M_C_CPU1_SA_DQ<28>")
	)
	(segment
		(start 91.85402 -243.186966)
		(end 91.862402 -243.191792)
		(width 0.0889)
		(layer "In2.Cu")
		(net "M_C_CPU1_SA_DQ<28>")
	)
	(segment
		(start 46.42358 -232.144824)
		(end 46.586648 -231.981756)
		(width 0.14478)
		(layer "In2.Cu")
		(net "M_C_CPU1_SA_DQ<28>")
	)
	(segment
		(start 64.878458 -235.407454)
		(end 64.79286 -235.493052)
		(width 0.14478)
		(layer "In2.Cu")
		(net "M_C_CPU1_SA_DQ<28>")
	)
	(segment
		(start 66.29019 -236.588554)
		(end 66.453258 -236.751622)
		(width 0.14478)
		(layer "In2.Cu")
		(net "M_C_CPU1_SA_DQ<28>")
	)
	(segment
		(start 45.636688 -231.431084)
		(end 45.867066 -231.431084)
		(width 0.14478)
		(layer "In2.Cu")
		(net "M_C_CPU1_SA_DQ<28>")
	)
	(segment
		(start 57.145428 -231.760268)
		(end 57.346088 -231.760268)
		(width 0.14478)
		(layer "In2.Cu")
		(net "M_C_CPU1_SA_DQ<28>")
	)
	(segment
		(start 64.484758 -235.0135)
		(end 64.71539 -235.013754)
		(width 0.14478)
		(layer "In2.Cu")
		(net "M_C_CPU1_SA_DQ<28>")
	)
	(segment
		(start 46.586648 -231.981756)
		(end 46.586648 -231.918256)
		(width 0.14478)
		(layer "In2.Cu")
		(net "M_C_CPU1_SA_DQ<28>")
	)
	(segment
		(start 58.195972 -230.910384)
		(end 60.61202 -230.910384)
		(width 0.14478)
		(layer "In2.Cu")
		(net "M_C_CPU1_SA_DQ<28>")
	)
	(segment
		(start 64.878458 -235.176822)
		(end 64.878458 -235.407454)
		(width 0.14478)
		(layer "In2.Cu")
		(net "M_C_CPU1_SA_DQ<28>")
	)
	(segment
		(start 66.846958 -237.3757)
		(end 67.07759 -237.375954)
		(width 0.14478)
		(layer "In2.Cu")
		(net "M_C_CPU1_SA_DQ<28>")
	)
	(segment
		(start 66.059558 -236.5883)
		(end 66.29019 -236.588554)
		(width 0.14478)
		(layer "In2.Cu")
		(net "M_C_CPU1_SA_DQ<28>")
	)
	(segment
		(start 65.18656 -235.886498)
		(end 65.272158 -235.8009)
		(width 0.14478)
		(layer "In2.Cu")
		(net "M_C_CPU1_SA_DQ<28>")
	)
	(segment
		(start 46.734984 -231.76992)
		(end 48.887126 -231.76992)
		(width 0.14478)
		(layer "In2.Cu")
		(net "M_C_CPU1_SA_DQ<28>")
	)
	(segment
		(start 62.03696 -232.736898)
		(end 62.122558 -232.6513)
		(width 0.14478)
		(layer "In2.Cu")
		(net "M_C_CPU1_SA_DQ<28>")
	)
	(segment
		(start 90.913966 -243.186966)
		(end 90.922348 -243.191792)
		(width 0.0889)
		(layer "In2.Cu")
		(net "M_C_CPU1_SA_DQ<28>")
	)
	(segment
		(start 67.54876 -238.248698)
		(end 67.634358 -238.1631)
		(width 0.14478)
		(layer "In2.Cu")
		(net "M_C_CPU1_SA_DQ<28>")
	)
	(segment
		(start 61.728858 -232.027222)
		(end 61.728858 -232.257854)
		(width 0.14478)
		(layer "In2.Cu")
		(net "M_C_CPU1_SA_DQ<28>")
	)
	(segment
		(start 63.303658 -233.832654)
		(end 63.21806 -233.918252)
		(width 0.14478)
		(layer "In2.Cu")
		(net "M_C_CPU1_SA_DQ<28>")
	)
	(segment
		(start 60.61202 -230.910384)
		(end 61.728858 -232.027222)
		(width 0.14478)
		(layer "In2.Cu")
		(net "M_C_CPU1_SA_DQ<28>")
	)
	(segment
		(start 63.21806 -233.918252)
		(end 63.217806 -234.148376)
		(width 0.14478)
		(layer "In2.Cu")
		(net "M_C_CPU1_SA_DQ<28>")
	)
	(segment
		(start 61.806328 -232.736898)
		(end 62.03696 -232.736898)
		(width 0.14478)
		(layer "In2.Cu")
		(net "M_C_CPU1_SA_DQ<28>")
	)
	(segment
		(start 94.052644 -243.213128)
		(end 94.074996 -243.129816)
		(width 0.0889)
		(layer "In2.Cu")
		(net "M_C_CPU1_SA_DQ<28>")
	)
	(segment
		(start 56.588914 -232.139744)
		(end 56.819292 -232.139744)
		(width 0.14478)
		(layer "In2.Cu")
		(net "M_C_CPU1_SA_DQ<28>")
	)
	(segment
		(start 45.080174 -232.144824)
		(end 45.310552 -232.144824)
		(width 0.14478)
		(layer "In2.Cu")
		(net "M_C_CPU1_SA_DQ<28>")
	)
	(segment
		(start 77.716126 -242.988084)
		(end 78.089506 -242.988084)
		(width 0.0889)
		(layer "In2.Cu")
		(net "M_C_CPU1_SA_DQ<28>")
	)
	(segment
		(start 66.530728 -237.461298)
		(end 66.76136 -237.461298)
		(width 0.14478)
		(layer "In2.Cu")
		(net "M_C_CPU1_SA_DQ<28>")
	)
	(segment
		(start 65.665858 -236.194854)
		(end 65.58026 -236.280452)
		(width 0.14478)
		(layer "In2.Cu")
		(net "M_C_CPU1_SA_DQ<28>")
	)
	(segment
		(start 62.82436 -233.524298)
		(end 62.909958 -233.4387)
		(width 0.14478)
		(layer "In2.Cu")
		(net "M_C_CPU1_SA_DQ<28>")
	)
	(segment
		(start 64.792606 -235.723176)
		(end 64.955928 -235.886498)
		(width 0.14478)
		(layer "In2.Cu")
		(net "M_C_CPU1_SA_DQ<28>")
	)
	(segment
		(start 67.07759 -237.375954)
		(end 67.240658 -237.539022)
		(width 0.14478)
		(layer "In2.Cu")
		(net "M_C_CPU1_SA_DQ<28>")
	)
	(segment
		(start 64.168528 -235.099098)
		(end 64.39916 -235.099098)
		(width 0.14478)
		(layer "In2.Cu")
		(net "M_C_CPU1_SA_DQ<28>")
	)
	(segment
		(start 87.154004 -243.186966)
		(end 87.162386 -243.191792)
		(width 0.0889)
		(layer "In2.Cu")
		(net "M_C_CPU1_SA_DQ<28>")
	)
	(segment
		(start 56.262778 -231.760268)
		(end 56.425846 -231.923336)
		(width 0.14478)
		(layer "In2.Cu")
		(net "M_C_CPU1_SA_DQ<28>")
	)
	(segment
		(start 83.394042 -243.186966)
		(end 83.402424 -243.191792)
		(width 0.0889)
		(layer "In2.Cu")
		(net "M_C_CPU1_SA_DQ<28>")
	)
	(segment
		(start 45.47362 -231.981756)
		(end 45.47362 -231.594152)
		(width 0.14478)
		(layer "In2.Cu")
		(net "M_C_CPU1_SA_DQ<28>")
	)
	(segment
		(start 82.453988 -243.186966)
		(end 82.46237 -243.191792)
		(width 0.0889)
		(layer "In2.Cu")
		(net "M_C_CPU1_SA_DQ<28>")
	)
	(segment
		(start 81.879694 -243.191792)
		(end 81.888076 -243.186966)
		(width 0.0889)
		(layer "In2.Cu")
		(net "M_C_CPU1_SA_DQ<28>")
	)
	(segment
		(start 56.425846 -231.976676)
		(end 56.588914 -232.139744)
		(width 0.14478)
		(layer "In2.Cu")
		(net "M_C_CPU1_SA_DQ<28>")
	)
	(segment
		(start 85.639656 -243.191792)
		(end 85.648038 -243.186966)
		(width 0.0889)
		(layer "In2.Cu")
		(net "M_C_CPU1_SA_DQ<28>")
	)
	(segment
		(start 67.318128 -238.248698)
		(end 67.54876 -238.248698)
		(width 0.14478)
		(layer "In2.Cu")
		(net "M_C_CPU1_SA_DQ<28>")
	)
	(segment
		(start 45.47362 -231.594152)
		(end 45.636688 -231.431084)
		(width 0.14478)
		(layer "In2.Cu")
		(net "M_C_CPU1_SA_DQ<28>")
	)
	(segment
		(start 63.303658 -233.602022)
		(end 63.303658 -233.832654)
		(width 0.14478)
		(layer "In2.Cu")
		(net "M_C_CPU1_SA_DQ<28>")
	)
	(segment
		(start 78.205838 -243.104416)
		(end 78.41107 -243.104416)
		(width 0.0889)
		(layer "In2.Cu")
		(net "M_C_CPU1_SA_DQ<28>")
	)
	(segment
		(start 76.557886 -241.829844)
		(end 77.716126 -242.988084)
		(width 0.0889)
		(layer "In2.Cu")
		(net "M_C_CPU1_SA_DQ<28>")
	)
	(segment
		(start 44.917106 -231.981756)
		(end 45.080174 -232.144824)
		(width 0.14478)
		(layer "In2.Cu")
		(net "M_C_CPU1_SA_DQ<28>")
	)
	(segment
		(start 65.58026 -236.280452)
		(end 65.580006 -236.510576)
		(width 0.14478)
		(layer "In2.Cu")
		(net "M_C_CPU1_SA_DQ<28>")
	)
	(segment
		(start 49.36998 -232.022904)
		(end 50.472848 -230.920036)
		(width 0.14478)
		(layer "In2.Cu")
		(net "M_C_CPU1_SA_DQ<28>")
	)
	(segment
		(start 61.728858 -232.257854)
		(end 61.64326 -232.343452)
		(width 0.14478)
		(layer "In2.Cu")
		(net "M_C_CPU1_SA_DQ<28>")
	)
	(segment
		(start 45.867066 -231.431084)
		(end 46.030134 -231.594152)
		(width 0.14478)
		(layer "In2.Cu")
		(net "M_C_CPU1_SA_DQ<28>")
	)
	(segment
		(start 67.240658 -237.769654)
		(end 67.15506 -237.855252)
		(width 0.14478)
		(layer "In2.Cu")
		(net "M_C_CPU1_SA_DQ<28>")
	)
	(segment
		(start 64.955928 -235.886498)
		(end 65.18656 -235.886498)
		(width 0.14478)
		(layer "In2.Cu")
		(net "M_C_CPU1_SA_DQ<28>")
	)
	(segment
		(start 66.76136 -237.461298)
		(end 66.846958 -237.3757)
		(width 0.14478)
		(layer "In2.Cu")
		(net "M_C_CPU1_SA_DQ<28>")
	)
	(segment
		(start 44.340018 -231.335326)
		(end 44.917106 -231.912414)
		(width 0.14478)
		(layer "In2.Cu")
		(net "M_C_CPU1_SA_DQ<28>")
	)
	(segment
		(start 62.122558 -232.6513)
		(end 62.35319 -232.651554)
		(width 0.14478)
		(layer "In2.Cu")
		(net "M_C_CPU1_SA_DQ<28>")
	)
	(segment
		(start 62.35319 -232.651554)
		(end 62.516258 -232.814622)
		(width 0.14478)
		(layer "In2.Cu")
		(net "M_C_CPU1_SA_DQ<28>")
	)
	(segment
		(start 62.593728 -233.524298)
		(end 62.82436 -233.524298)
		(width 0.14478)
		(layer "In2.Cu")
		(net "M_C_CPU1_SA_DQ<28>")
	)
	(segment
		(start 57.346088 -231.760268)
		(end 58.195972 -230.910384)
		(width 0.14478)
		(layer "In2.Cu")
		(net "M_C_CPU1_SA_DQ<28>")
	)
	(segment
		(start 56.819292 -232.139744)
		(end 56.98236 -231.976676)
		(width 0.14478)
		(layer "In2.Cu")
		(net "M_C_CPU1_SA_DQ<28>")
	)
	(segment
		(start 63.381128 -234.311698)
		(end 63.61176 -234.311698)
		(width 0.14478)
		(layer "In2.Cu")
		(net "M_C_CPU1_SA_DQ<28>")
	)
	(segment
		(start 63.61176 -234.311698)
		(end 63.697358 -234.2261)
		(width 0.14478)
		(layer "In2.Cu")
		(net "M_C_CPU1_SA_DQ<28>")
	)
	(segment
		(start 50.472848 -230.920036)
		(end 52.988464 -230.920036)
		(width 0.14478)
		(layer "In2.Cu")
		(net "M_C_CPU1_SA_DQ<28>")
	)
	(segment
		(start 65.580006 -236.510576)
		(end 65.743328 -236.673898)
		(width 0.14478)
		(layer "In2.Cu")
		(net "M_C_CPU1_SA_DQ<28>")
	)
	(segment
		(start 61.64326 -232.343452)
		(end 61.643006 -232.573576)
		(width 0.14478)
		(layer "In2.Cu")
		(net "M_C_CPU1_SA_DQ<28>")
	)
	(segment
		(start 65.50279 -235.801154)
		(end 65.665858 -235.964222)
		(width 0.14478)
		(layer "In2.Cu")
		(net "M_C_CPU1_SA_DQ<28>")
	)
	(segment
		(start 66.36766 -237.067852)
		(end 66.367406 -237.297976)
		(width 0.14478)
		(layer "In2.Cu")
		(net "M_C_CPU1_SA_DQ<28>")
	)
	(segment
		(start 94.074996 -243.129816)
		(end 93.921072 -242.864386)
		(width 0.0889)
		(layer "In2.Cu")
		(net "M_C_CPU1_SA_DQ<28>")
	)
	(segment
		(start 65.272158 -235.8009)
		(end 65.50279 -235.801154)
		(width 0.14478)
		(layer "In2.Cu")
		(net "M_C_CPU1_SA_DQ<28>")
	)
	(segment
		(start 66.453258 -236.982254)
		(end 66.36766 -237.067852)
		(width 0.14478)
		(layer "In2.Cu")
		(net "M_C_CPU1_SA_DQ<28>")
	)
	(segment
		(start 78.645004 -243.162074)
		(end 78.707234 -243.194586)
		(width 0.0889)
		(layer "In2.Cu")
		(net "M_C_CPU1_SA_DQ<28>")
	)
	(segment
		(start 66.453258 -236.751622)
		(end 66.453258 -236.982254)
		(width 0.14478)
		(layer "In2.Cu")
		(net "M_C_CPU1_SA_DQ<28>")
	)
	(segment
		(start 67.154806 -238.085376)
		(end 67.318128 -238.248698)
		(width 0.14478)
		(layer "In2.Cu")
		(net "M_C_CPU1_SA_DQ<28>")
	)
	(segment
		(start 65.97396 -236.673898)
		(end 66.059558 -236.5883)
		(width 0.14478)
		(layer "In2.Cu")
		(net "M_C_CPU1_SA_DQ<28>")
	)
	(segment
		(start 64.091058 -234.389422)
		(end 64.091058 -234.620054)
		(width 0.14478)
		(layer "In2.Cu")
		(net "M_C_CPU1_SA_DQ<28>")
	)
	(segment
		(start 49.14011 -232.022904)
		(end 49.36998 -232.022904)
		(width 0.14478)
		(layer "In2.Cu")
		(net "M_C_CPU1_SA_DQ<28>")
	)
	(segment
		(start 64.39916 -235.099098)
		(end 64.484758 -235.0135)
		(width 0.14478)
		(layer "In2.Cu")
		(net "M_C_CPU1_SA_DQ<28>")
	)
	(segment
		(start 64.71539 -235.013754)
		(end 64.878458 -235.176822)
		(width 0.14478)
		(layer "In2.Cu")
		(net "M_C_CPU1_SA_DQ<28>")
	)
	(segment
		(start 62.516258 -232.814622)
		(end 62.516258 -233.045254)
		(width 0.14478)
		(layer "In2.Cu")
		(net "M_C_CPU1_SA_DQ<28>")
	)
	(segment
		(start 67.86499 -238.163354)
		(end 71.53148 -241.829844)
		(width 0.14478)
		(layer "In2.Cu")
		(net "M_C_CPU1_SA_DQ<28>")
	)
	(segment
		(start 56.425846 -231.923336)
		(end 56.425846 -231.976676)
		(width 0.14478)
		(layer "In2.Cu")
		(net "M_C_CPU1_SA_DQ<28>")
	)
	(segment
		(start 46.193202 -232.144824)
		(end 46.42358 -232.144824)
		(width 0.14478)
		(layer "In2.Cu")
		(net "M_C_CPU1_SA_DQ<28>")
	)
	(segment
		(start 63.14059 -233.438954)
		(end 63.303658 -233.602022)
		(width 0.14478)
		(layer "In2.Cu")
		(net "M_C_CPU1_SA_DQ<28>")
	)
	(segment
		(start 46.030134 -231.594152)
		(end 46.030134 -231.981756)
		(width 0.14478)
		(layer "In2.Cu")
		(net "M_C_CPU1_SA_DQ<28>")
	)
	(segment
		(start 63.217806 -234.148376)
		(end 63.381128 -234.311698)
		(width 0.14478)
		(layer "In2.Cu")
		(net "M_C_CPU1_SA_DQ<28>")
	)
	(segment
		(start 56.98236 -231.923336)
		(end 57.145428 -231.760268)
		(width 0.14478)
		(layer "In2.Cu")
		(net "M_C_CPU1_SA_DQ<28>")
	)
	(segment
		(start 44.917106 -231.912414)
		(end 44.917106 -231.981756)
		(width 0.14478)
		(layer "In2.Cu")
		(net "M_C_CPU1_SA_DQ<28>")
	)
	(segment
		(start 64.005206 -234.935776)
		(end 64.168528 -235.099098)
		(width 0.14478)
		(layer "In2.Cu")
		(net "M_C_CPU1_SA_DQ<28>")
	)
	(segment
		(start 62.43066 -233.130852)
		(end 62.430406 -233.360976)
		(width 0.14478)
		(layer "In2.Cu")
		(net "M_C_CPU1_SA_DQ<28>")
	)
	(segment
		(start 67.240658 -237.539022)
		(end 67.240658 -237.769654)
		(width 0.14478)
		(layer "In2.Cu")
		(net "M_C_CPU1_SA_DQ<28>")
	)
	(segment
		(start 52.988464 -230.920036)
		(end 53.828696 -231.760268)
		(width 0.14478)
		(layer "In2.Cu")
		(net "M_C_CPU1_SA_DQ<28>")
	)
	(segment
		(start 62.516258 -233.045254)
		(end 62.43066 -233.130852)
		(width 0.14478)
		(layer "In2.Cu")
		(net "M_C_CPU1_SA_DQ<28>")
	)
	(segment
		(start 67.634358 -238.1631)
		(end 67.86499 -238.163354)
		(width 0.14478)
		(layer "In2.Cu")
		(net "M_C_CPU1_SA_DQ<28>")
	)
	(segment
		(start 53.828696 -231.760268)
		(end 56.262778 -231.760268)
		(width 0.14478)
		(layer "In2.Cu")
		(net "M_C_CPU1_SA_DQ<28>")
	)
	(segment
		(start 65.743328 -236.673898)
		(end 65.97396 -236.673898)
		(width 0.14478)
		(layer "In2.Cu")
		(net "M_C_CPU1_SA_DQ<28>")
	)
	(segment
		(start 71.53148 -241.829844)
		(end 75.955906 -241.829844)
		(width 0.14478)
		(layer "In2.Cu")
		(net "M_C_CPU1_SA_DQ<28>")
	)
	(segment
		(start 56.98236 -231.976676)
		(end 56.98236 -231.923336)
		(width 0.14478)
		(layer "In2.Cu")
		(net "M_C_CPU1_SA_DQ<28>")
	)
	(segment
		(start 78.089506 -242.988084)
		(end 78.205838 -243.104416)
		(width 0.0889)
		(layer "In2.Cu")
		(net "M_C_CPU1_SA_DQ<28>")
	)
	(arc
		(start 82.82813 -243.186966)
		(mid 83.111086 -243.110789)
		(end 83.394042 -243.186966)
		(width 0.0889)
		(layer "In2.Cu")
		(net "M_C_CPU1_SA_DQ<28>")
	)
	(arc
		(start 80.008222 -243.186966)
		(mid 80.291178 -243.110789)
		(end 80.574134 -243.186966)
		(width 0.0889)
		(layer "In2.Cu")
		(net "M_C_CPU1_SA_DQ<28>")
	)
	(arc
		(start 90.922348 -243.191792)
		(mid 91.105856 -243.237286)
		(end 91.288108 -243.186966)
		(width 0.0889)
		(layer "In2.Cu")
		(net "M_C_CPU1_SA_DQ<28>")
	)
	(arc
		(start 87.162386 -243.191792)
		(mid 87.345894 -243.237286)
		(end 87.528146 -243.186966)
		(width 0.0889)
		(layer "In2.Cu")
		(net "M_C_CPU1_SA_DQ<28>")
	)
	(arc
		(start 83.768184 -243.186966)
		(mid 84.05114 -243.110789)
		(end 84.334096 -243.186966)
		(width 0.0889)
		(layer "In2.Cu")
		(net "M_C_CPU1_SA_DQ<28>")
	)
	(arc
		(start 78.707234 -243.194586)
		(mid 78.888164 -243.237064)
		(end 79.067152 -243.186966)
		(width 0.0889)
		(layer "In2.Cu")
		(net "M_C_CPU1_SA_DQ<28>")
	)
	(arc
		(start 92.794074 -243.186966)
		(mid 92.981018 -243.237221)
		(end 93.167962 -243.186966)
		(width 0.0889)
		(layer "In2.Cu")
		(net "M_C_CPU1_SA_DQ<28>")
	)
	(arc
		(start 79.081884 -243.17833)
		(mid 79.358867 -243.110526)
		(end 79.633572 -243.186966)
		(width 0.0889)
		(layer "In2.Cu")
		(net "M_C_CPU1_SA_DQ<28>")
	)
	(arc
		(start 84.707984 -243.186966)
		(mid 84.99094 -243.110789)
		(end 85.273896 -243.186966)
		(width 0.0889)
		(layer "In2.Cu")
		(net "M_C_CPU1_SA_DQ<28>")
	)
	(arc
		(start 86.21395 -243.186966)
		(mid 86.396201 -243.237316)
		(end 86.57971 -243.191792)
		(width 0.0889)
		(layer "In2.Cu")
		(net "M_C_CPU1_SA_DQ<28>")
	)
	(arc
		(start 88.4682 -243.186966)
		(mid 88.751156 -243.110789)
		(end 89.034112 -243.186966)
		(width 0.0889)
		(layer "In2.Cu")
		(net "M_C_CPU1_SA_DQ<28>")
	)
	(arc
		(start 79.633572 -243.186966)
		(mid 79.816077 -243.237443)
		(end 79.99984 -243.191792)
		(width 0.0889)
		(layer "In2.Cu")
		(net "M_C_CPU1_SA_DQ<28>")
	)
	(arc
		(start 90.348054 -243.186966)
		(mid 90.63101 -243.110789)
		(end 90.913966 -243.186966)
		(width 0.0889)
		(layer "In2.Cu")
		(net "M_C_CPU1_SA_DQ<28>")
	)
	(arc
		(start 91.288108 -243.186966)
		(mid 91.571064 -243.110789)
		(end 91.85402 -243.186966)
		(width 0.0889)
		(layer "In2.Cu")
		(net "M_C_CPU1_SA_DQ<28>")
	)
	(arc
		(start 80.574134 -243.186966)
		(mid 80.761078 -243.237221)
		(end 80.948022 -243.186966)
		(width 0.0889)
		(layer "In2.Cu")
		(net "M_C_CPU1_SA_DQ<28>")
	)
	(arc
		(start 81.513934 -243.186966)
		(mid 81.696185 -243.237316)
		(end 81.879694 -243.191792)
		(width 0.0889)
		(layer "In2.Cu")
		(net "M_C_CPU1_SA_DQ<28>")
	)
	(arc
		(start 86.588092 -243.186966)
		(mid 86.871048 -243.110789)
		(end 87.154004 -243.186966)
		(width 0.0889)
		(layer "In2.Cu")
		(net "M_C_CPU1_SA_DQ<28>")
	)
	(arc
		(start 85.273896 -243.186966)
		(mid 85.456147 -243.237316)
		(end 85.639656 -243.191792)
		(width 0.0889)
		(layer "In2.Cu")
		(net "M_C_CPU1_SA_DQ<28>")
	)
	(arc
		(start 93.733874 -243.186966)
		(mid 93.890312 -243.235937)
		(end 94.052644 -243.213128)
		(width 0.0889)
		(layer "In2.Cu")
		(net "M_C_CPU1_SA_DQ<28>")
	)
	(arc
		(start 92.228162 -243.186966)
		(mid 92.511118 -243.110789)
		(end 92.794074 -243.186966)
		(width 0.0889)
		(layer "In2.Cu")
		(net "M_C_CPU1_SA_DQ<28>")
	)
	(arc
		(start 93.167962 -243.186966)
		(mid 93.450918 -243.110789)
		(end 93.733874 -243.186966)
		(width 0.0889)
		(layer "In2.Cu")
		(net "M_C_CPU1_SA_DQ<28>")
	)
	(arc
		(start 84.334096 -243.186966)
		(mid 84.52104 -243.237221)
		(end 84.707984 -243.186966)
		(width 0.0889)
		(layer "In2.Cu")
		(net "M_C_CPU1_SA_DQ<28>")
	)
	(arc
		(start 80.948022 -243.186966)
		(mid 81.230978 -243.110789)
		(end 81.513934 -243.186966)
		(width 0.0889)
		(layer "In2.Cu")
		(net "M_C_CPU1_SA_DQ<28>")
	)
	(arc
		(start 78.41107 -243.104416)
		(mid 78.531527 -243.119079)
		(end 78.645004 -243.162074)
		(width 0.0889)
		(layer "In2.Cu")
		(net "M_C_CPU1_SA_DQ<28>")
	)
	(arc
		(start 81.888076 -243.186966)
		(mid 82.171032 -243.110789)
		(end 82.453988 -243.186966)
		(width 0.0889)
		(layer "In2.Cu")
		(net "M_C_CPU1_SA_DQ<28>")
	)
	(arc
		(start 91.862402 -243.191792)
		(mid 92.04591 -243.237286)
		(end 92.228162 -243.186966)
		(width 0.0889)
		(layer "In2.Cu")
		(net "M_C_CPU1_SA_DQ<28>")
	)
	(arc
		(start 89.034112 -243.186966)
		(mid 89.221056 -243.237221)
		(end 89.408 -243.186966)
		(width 0.0889)
		(layer "In2.Cu")
		(net "M_C_CPU1_SA_DQ<28>")
	)
	(arc
		(start 87.528146 -243.186966)
		(mid 87.811102 -243.110789)
		(end 88.094058 -243.186966)
		(width 0.0889)
		(layer "In2.Cu")
		(net "M_C_CPU1_SA_DQ<28>")
	)
	(arc
		(start 82.46237 -243.191792)
		(mid 82.645878 -243.237286)
		(end 82.82813 -243.186966)
		(width 0.0889)
		(layer "In2.Cu")
		(net "M_C_CPU1_SA_DQ<28>")
	)
	(arc
		(start 89.408 -243.186966)
		(mid 89.690956 -243.110789)
		(end 89.973912 -243.186966)
		(width 0.0889)
		(layer "In2.Cu")
		(net "M_C_CPU1_SA_DQ<28>")
	)
	(arc
		(start 88.10244 -243.191792)
		(mid 88.285948 -243.237286)
		(end 88.4682 -243.186966)
		(width 0.0889)
		(layer "In2.Cu")
		(net "M_C_CPU1_SA_DQ<28>")
	)
	(arc
		(start 89.973912 -243.186966)
		(mid 90.156163 -243.237316)
		(end 90.339672 -243.191792)
		(width 0.0889)
		(layer "In2.Cu")
		(net "M_C_CPU1_SA_DQ<28>")
	)
	(arc
		(start 85.648038 -243.186966)
		(mid 85.930994 -243.110789)
		(end 86.21395 -243.186966)
		(width 0.0889)
		(layer "In2.Cu")
		(net "M_C_CPU1_SA_DQ<28>")
	)
	(arc
		(start 83.402424 -243.191792)
		(mid 83.585932 -243.237286)
		(end 83.768184 -243.186966)
		(width 0.0889)
		(layer "In2.Cu")
		(net "M_C_CPU1_SA_DQ<28>")
	)
	(segment
		(start 96.267778 -241.510312)
		(end 95.800926 -241.244374)
		(width 0.10668)
		(layer "F.Cu")
		(net "M_C_CPU1_SA_DQ<27>")
	)
	(segment
		(start 64.972946 -229.592124)
		(end 65.201546 -230.144066)
		(width 0.14478)
		(layer "In2.Cu")
		(net "M_C_CPU1_SA_DQ<27>")
	)
	(segment
		(start 90.913966 -240.921794)
		(end 90.922348 -240.916968)
		(width 0.0889)
		(layer "In2.Cu")
		(net "M_C_CPU1_SA_DQ<27>")
	)
	(segment
		(start 94.099634 -240.916968)
		(end 94.108016 -240.921794)
		(width 0.0889)
		(layer "In2.Cu")
		(net "M_C_CPU1_SA_DQ<27>")
	)
	(segment
		(start 40.65524 -228.350572)
		(end 48.671226 -228.350572)
		(width 0.14478)
		(layer "In2.Cu")
		(net "M_C_CPU1_SA_DQ<27>")
	)
	(segment
		(start 54.214268 -228.2571)
		(end 54.46395 -228.360478)
		(width 0.14478)
		(layer "In2.Cu")
		(net "M_C_CPU1_SA_DQ<27>")
	)
	(segment
		(start 95.55099 -240.953544)
		(end 95.647002 -240.978944)
		(width 0.0889)
		(layer "In2.Cu")
		(net "M_C_CPU1_SA_DQ<27>")
	)
	(segment
		(start 88.094058 -240.921794)
		(end 88.10244 -240.916968)
		(width 0.0889)
		(layer "In2.Cu")
		(net "M_C_CPU1_SA_DQ<27>")
	)
	(segment
		(start 56.194452 -228.360478)
		(end 56.612536 -228.27742)
		(width 0.14478)
		(layer "In2.Cu")
		(net "M_C_CPU1_SA_DQ<27>")
	)
	(segment
		(start 75.976226 -239.477804)
		(end 76.949046 -239.477804)
		(width 0.0889)
		(layer "In2.Cu")
		(net "M_C_CPU1_SA_DQ<27>")
	)
	(segment
		(start 79.609188 -240.937034)
		(end 79.63535 -240.922048)
		(width 0.0889)
		(layer "In2.Cu")
		(net "M_C_CPU1_SA_DQ<27>")
	)
	(segment
		(start 76.949046 -239.477804)
		(end 77.190346 -239.719104)
		(width 0.0889)
		(layer "In2.Cu")
		(net "M_C_CPU1_SA_DQ<27>")
	)
	(segment
		(start 86.57971 -240.916968)
		(end 86.588092 -240.921794)
		(width 0.0889)
		(layer "In2.Cu")
		(net "M_C_CPU1_SA_DQ<27>")
	)
	(segment
		(start 65.201546 -230.144066)
		(end 65.201546 -231.898444)
		(width 0.14478)
		(layer "In2.Cu")
		(net "M_C_CPU1_SA_DQ<27>")
	)
	(segment
		(start 65.201546 -231.898444)
		(end 65.284096 -232.097834)
		(width 0.14478)
		(layer "In2.Cu")
		(net "M_C_CPU1_SA_DQ<27>")
	)
	(segment
		(start 91.85402 -240.921794)
		(end 91.862402 -240.916968)
		(width 0.0889)
		(layer "In2.Cu")
		(net "M_C_CPU1_SA_DQ<27>")
	)
	(segment
		(start 61.05525 -227.697284)
		(end 62.82436 -227.697284)
		(width 0.14478)
		(layer "In2.Cu")
		(net "M_C_CPU1_SA_DQ<27>")
	)
	(segment
		(start 49.57699 -227.975668)
		(end 50.287936 -227.500688)
		(width 0.14478)
		(layer "In2.Cu")
		(net "M_C_CPU1_SA_DQ<27>")
	)
	(segment
		(start 48.671226 -228.350572)
		(end 49.57699 -227.975668)
		(width 0.14478)
		(layer "In2.Cu")
		(net "M_C_CPU1_SA_DQ<27>")
	)
	(segment
		(start 81.879694 -240.916968)
		(end 81.888076 -240.921794)
		(width 0.0889)
		(layer "In2.Cu")
		(net "M_C_CPU1_SA_DQ<27>")
	)
	(segment
		(start 56.612536 -228.27742)
		(end 57.760362 -227.51034)
		(width 0.14478)
		(layer "In2.Cu")
		(net "M_C_CPU1_SA_DQ<27>")
	)
	(segment
		(start 95.039688 -240.916968)
		(end 95.04807 -240.921794)
		(width 0.0889)
		(layer "In2.Cu")
		(net "M_C_CPU1_SA_DQ<27>")
	)
	(segment
		(start 87.154004 -240.921794)
		(end 87.162386 -240.916968)
		(width 0.0889)
		(layer "In2.Cu")
		(net "M_C_CPU1_SA_DQ<27>")
	)
	(segment
		(start 79.63535 -240.922048)
		(end 79.658718 -240.908586)
		(width 0.0889)
		(layer "In2.Cu")
		(net "M_C_CPU1_SA_DQ<27>")
	)
	(segment
		(start 53.082444 -227.500688)
		(end 54.214268 -228.2571)
		(width 0.14478)
		(layer "In2.Cu")
		(net "M_C_CPU1_SA_DQ<27>")
	)
	(segment
		(start 79.050896 -240.909856)
		(end 79.07147 -240.921794)
		(width 0.0889)
		(layer "In2.Cu")
		(net "M_C_CPU1_SA_DQ<27>")
	)
	(segment
		(start 83.394042 -240.921794)
		(end 83.402424 -240.916968)
		(width 0.0889)
		(layer "In2.Cu")
		(net "M_C_CPU1_SA_DQ<27>")
	)
	(segment
		(start 78.08341 -240.89487)
		(end 78.169516 -240.944908)
		(width 0.0889)
		(layer "In2.Cu")
		(net "M_C_CPU1_SA_DQ<27>")
	)
	(segment
		(start 60.437776 -227.51034)
		(end 61.05525 -227.697284)
		(width 0.14478)
		(layer "In2.Cu")
		(net "M_C_CPU1_SA_DQ<27>")
	)
	(segment
		(start 54.46395 -228.360478)
		(end 56.194452 -228.360478)
		(width 0.14478)
		(layer "In2.Cu")
		(net "M_C_CPU1_SA_DQ<27>")
	)
	(segment
		(start 72.571356 -239.385094)
		(end 72.795384 -239.477804)
		(width 0.14478)
		(layer "In2.Cu")
		(net "M_C_CPU1_SA_DQ<27>")
	)
	(segment
		(start 90.339672 -240.916968)
		(end 90.348054 -240.921794)
		(width 0.0889)
		(layer "In2.Cu")
		(net "M_C_CPU1_SA_DQ<27>")
	)
	(segment
		(start 40.23995 -227.935282)
		(end 40.65524 -228.350572)
		(width 0.14478)
		(layer "In2.Cu")
		(net "M_C_CPU1_SA_DQ<27>")
	)
	(segment
		(start 77.190346 -239.719104)
		(end 77.190346 -240.018824)
		(width 0.0889)
		(layer "In2.Cu")
		(net "M_C_CPU1_SA_DQ<27>")
	)
	(segment
		(start 62.82436 -227.697284)
		(end 63.257684 -227.876862)
		(width 0.14478)
		(layer "In2.Cu")
		(net "M_C_CPU1_SA_DQ<27>")
	)
	(segment
		(start 82.453988 -240.921794)
		(end 82.46237 -240.916968)
		(width 0.0889)
		(layer "In2.Cu")
		(net "M_C_CPU1_SA_DQ<27>")
	)
	(segment
		(start 77.190346 -240.019332)
		(end 78.008734 -240.837466)
		(width 0.0889)
		(layer "In2.Cu")
		(net "M_C_CPU1_SA_DQ<27>")
	)
	(segment
		(start 50.287936 -227.500688)
		(end 53.082444 -227.500688)
		(width 0.14478)
		(layer "In2.Cu")
		(net "M_C_CPU1_SA_DQ<27>")
	)
	(segment
		(start 72.795384 -239.477804)
		(end 75.976226 -239.477804)
		(width 0.14478)
		(layer "In2.Cu")
		(net "M_C_CPU1_SA_DQ<27>")
	)
	(segment
		(start 63.257684 -227.876862)
		(end 64.972946 -229.592124)
		(width 0.14478)
		(layer "In2.Cu")
		(net "M_C_CPU1_SA_DQ<27>")
	)
	(segment
		(start 57.760362 -227.51034)
		(end 60.437776 -227.51034)
		(width 0.14478)
		(layer "In2.Cu")
		(net "M_C_CPU1_SA_DQ<27>")
	)
	(segment
		(start 65.284096 -232.097834)
		(end 72.571356 -239.385094)
		(width 0.14478)
		(layer "In2.Cu")
		(net "M_C_CPU1_SA_DQ<27>")
	)
	(segment
		(start 95.647002 -240.978944)
		(end 95.800926 -241.244374)
		(width 0.0889)
		(layer "In2.Cu")
		(net "M_C_CPU1_SA_DQ<27>")
	)
	(segment
		(start 85.639656 -240.916968)
		(end 85.648038 -240.921794)
		(width 0.0889)
		(layer "In2.Cu")
		(net "M_C_CPU1_SA_DQ<27>")
	)
	(arc
		(start 82.46237 -240.916968)
		(mid 82.645878 -240.871474)
		(end 82.82813 -240.921794)
		(width 0.0889)
		(layer "In2.Cu")
		(net "M_C_CPU1_SA_DQ<27>")
	)
	(arc
		(start 92.794074 -240.921794)
		(mid 92.981018 -240.871539)
		(end 93.167962 -240.921794)
		(width 0.0889)
		(layer "In2.Cu")
		(net "M_C_CPU1_SA_DQ<27>")
	)
	(arc
		(start 83.768184 -240.921794)
		(mid 84.05114 -240.997971)
		(end 84.334096 -240.921794)
		(width 0.0889)
		(layer "In2.Cu")
		(net "M_C_CPU1_SA_DQ<27>")
	)
	(arc
		(start 89.408 -240.921794)
		(mid 89.690956 -240.997971)
		(end 89.973912 -240.921794)
		(width 0.0889)
		(layer "In2.Cu")
		(net "M_C_CPU1_SA_DQ<27>")
	)
	(arc
		(start 85.648038 -240.921794)
		(mid 85.930994 -240.997971)
		(end 86.21395 -240.921794)
		(width 0.0889)
		(layer "In2.Cu")
		(net "M_C_CPU1_SA_DQ<27>")
	)
	(arc
		(start 77.190346 -240.018824)
		(mid 77.190286 -240.019078)
		(end 77.190346 -240.019332)
		(width 0.0889)
		(layer "In2.Cu")
		(net "M_C_CPU1_SA_DQ<27>")
	)
	(arc
		(start 90.348054 -240.921794)
		(mid 90.63101 -240.997971)
		(end 90.913966 -240.921794)
		(width 0.0889)
		(layer "In2.Cu")
		(net "M_C_CPU1_SA_DQ<27>")
	)
	(arc
		(start 84.334096 -240.921794)
		(mid 84.52104 -240.871539)
		(end 84.707984 -240.921794)
		(width 0.0889)
		(layer "In2.Cu")
		(net "M_C_CPU1_SA_DQ<27>")
	)
	(arc
		(start 86.588092 -240.921794)
		(mid 86.871048 -240.997971)
		(end 87.154004 -240.921794)
		(width 0.0889)
		(layer "In2.Cu")
		(net "M_C_CPU1_SA_DQ<27>")
	)
	(arc
		(start 90.922348 -240.916968)
		(mid 91.105856 -240.871474)
		(end 91.288108 -240.921794)
		(width 0.0889)
		(layer "In2.Cu")
		(net "M_C_CPU1_SA_DQ<27>")
	)
	(arc
		(start 80.948022 -240.921794)
		(mid 81.230978 -240.997971)
		(end 81.513934 -240.921794)
		(width 0.0889)
		(layer "In2.Cu")
		(net "M_C_CPU1_SA_DQ<27>")
	)
	(arc
		(start 80.008222 -240.921794)
		(mid 80.291178 -240.997971)
		(end 80.574134 -240.921794)
		(width 0.0889)
		(layer "In2.Cu")
		(net "M_C_CPU1_SA_DQ<27>")
	)
	(arc
		(start 85.273896 -240.921794)
		(mid 85.456147 -240.871444)
		(end 85.639656 -240.916968)
		(width 0.0889)
		(layer "In2.Cu")
		(net "M_C_CPU1_SA_DQ<27>")
	)
	(arc
		(start 86.21395 -240.921794)
		(mid 86.396201 -240.871444)
		(end 86.57971 -240.916968)
		(width 0.0889)
		(layer "In2.Cu")
		(net "M_C_CPU1_SA_DQ<27>")
	)
	(arc
		(start 93.167962 -240.921794)
		(mid 93.450918 -240.997971)
		(end 93.733874 -240.921794)
		(width 0.0889)
		(layer "In2.Cu")
		(net "M_C_CPU1_SA_DQ<27>")
	)
	(arc
		(start 92.228162 -240.921794)
		(mid 92.511118 -240.997971)
		(end 92.794074 -240.921794)
		(width 0.0889)
		(layer "In2.Cu")
		(net "M_C_CPU1_SA_DQ<27>")
	)
	(arc
		(start 87.162386 -240.916968)
		(mid 87.345894 -240.871474)
		(end 87.528146 -240.921794)
		(width 0.0889)
		(layer "In2.Cu")
		(net "M_C_CPU1_SA_DQ<27>")
	)
	(arc
		(start 93.733874 -240.921794)
		(mid 93.916125 -240.871444)
		(end 94.099634 -240.916968)
		(width 0.0889)
		(layer "In2.Cu")
		(net "M_C_CPU1_SA_DQ<27>")
	)
	(arc
		(start 91.862402 -240.916968)
		(mid 92.04591 -240.871474)
		(end 92.228162 -240.921794)
		(width 0.0889)
		(layer "In2.Cu")
		(net "M_C_CPU1_SA_DQ<27>")
	)
	(arc
		(start 81.888076 -240.921794)
		(mid 82.171032 -240.997971)
		(end 82.453988 -240.921794)
		(width 0.0889)
		(layer "In2.Cu")
		(net "M_C_CPU1_SA_DQ<27>")
	)
	(arc
		(start 89.034112 -240.921794)
		(mid 89.221056 -240.871539)
		(end 89.408 -240.921794)
		(width 0.0889)
		(layer "In2.Cu")
		(net "M_C_CPU1_SA_DQ<27>")
	)
	(arc
		(start 94.673928 -240.921794)
		(mid 94.856179 -240.871444)
		(end 95.039688 -240.916968)
		(width 0.0889)
		(layer "In2.Cu")
		(net "M_C_CPU1_SA_DQ<27>")
	)
	(arc
		(start 81.513934 -240.921794)
		(mid 81.696185 -240.871444)
		(end 81.879694 -240.916968)
		(width 0.0889)
		(layer "In2.Cu")
		(net "M_C_CPU1_SA_DQ<27>")
	)
	(arc
		(start 78.696058 -240.921794)
		(mid 78.871968 -240.870984)
		(end 79.050896 -240.909856)
		(width 0.0889)
		(layer "In2.Cu")
		(net "M_C_CPU1_SA_DQ<27>")
	)
	(arc
		(start 91.288108 -240.921794)
		(mid 91.571064 -240.997971)
		(end 91.85402 -240.921794)
		(width 0.0889)
		(layer "In2.Cu")
		(net "M_C_CPU1_SA_DQ<27>")
	)
	(arc
		(start 94.108016 -240.921794)
		(mid 94.390972 -240.997971)
		(end 94.673928 -240.921794)
		(width 0.0889)
		(layer "In2.Cu")
		(net "M_C_CPU1_SA_DQ<27>")
	)
	(arc
		(start 78.169516 -240.944908)
		(mid 78.43564 -240.998514)
		(end 78.696058 -240.921794)
		(width 0.0889)
		(layer "In2.Cu")
		(net "M_C_CPU1_SA_DQ<27>")
	)
	(arc
		(start 82.82813 -240.921794)
		(mid 83.111086 -240.997971)
		(end 83.394042 -240.921794)
		(width 0.0889)
		(layer "In2.Cu")
		(net "M_C_CPU1_SA_DQ<27>")
	)
	(arc
		(start 89.973912 -240.921794)
		(mid 90.156163 -240.871444)
		(end 90.339672 -240.916968)
		(width 0.0889)
		(layer "In2.Cu")
		(net "M_C_CPU1_SA_DQ<27>")
	)
	(arc
		(start 79.07147 -240.921794)
		(mid 79.3384 -240.997743)
		(end 79.609188 -240.937034)
		(width 0.0889)
		(layer "In2.Cu")
		(net "M_C_CPU1_SA_DQ<27>")
	)
	(arc
		(start 83.402424 -240.916968)
		(mid 83.585932 -240.871474)
		(end 83.768184 -240.921794)
		(width 0.0889)
		(layer "In2.Cu")
		(net "M_C_CPU1_SA_DQ<27>")
	)
	(arc
		(start 88.10244 -240.916968)
		(mid 88.285948 -240.871474)
		(end 88.4682 -240.921794)
		(width 0.0889)
		(layer "In2.Cu")
		(net "M_C_CPU1_SA_DQ<27>")
	)
	(arc
		(start 80.574134 -240.921794)
		(mid 80.761078 -240.871539)
		(end 80.948022 -240.921794)
		(width 0.0889)
		(layer "In2.Cu")
		(net "M_C_CPU1_SA_DQ<27>")
	)
	(arc
		(start 88.4682 -240.921794)
		(mid 88.751156 -240.997971)
		(end 89.034112 -240.921794)
		(width 0.0889)
		(layer "In2.Cu")
		(net "M_C_CPU1_SA_DQ<27>")
	)
	(arc
		(start 95.04807 -240.921794)
		(mid 95.295783 -240.997014)
		(end 95.55099 -240.953544)
		(width 0.0889)
		(layer "In2.Cu")
		(net "M_C_CPU1_SA_DQ<27>")
	)
	(arc
		(start 84.707984 -240.921794)
		(mid 84.99094 -240.997971)
		(end 85.273896 -240.921794)
		(width 0.0889)
		(layer "In2.Cu")
		(net "M_C_CPU1_SA_DQ<27>")
	)
	(arc
		(start 87.528146 -240.921794)
		(mid 87.811102 -240.997971)
		(end 88.094058 -240.921794)
		(width 0.0889)
		(layer "In2.Cu")
		(net "M_C_CPU1_SA_DQ<27>")
	)
	(arc
		(start 78.008734 -240.837466)
		(mid 78.044199 -240.868607)
		(end 78.08341 -240.89487)
		(width 0.0889)
		(layer "In2.Cu")
		(net "M_C_CPU1_SA_DQ<27>")
	)
	(arc
		(start 79.658718 -240.908586)
		(mid 79.835113 -240.871683)
		(end 80.008222 -240.921794)
		(width 0.0889)
		(layer "In2.Cu")
		(net "M_C_CPU1_SA_DQ<27>")
	)
	(segment
		(start 94.857824 -240.700306)
		(end 94.390972 -240.434368)
		(width 0.10668)
		(layer "F.Cu")
		(net "M_C_CPU1_SA_DQ<26>")
	)
	(segment
		(start 85.74405 -240.111788)
		(end 85.752432 -240.106962)
		(width 0.0889)
		(layer "In2.Cu")
		(net "M_C_CPU1_SA_DQ<26>")
	)
	(segment
		(start 53.111654 -225.810318)
		(end 53.961792 -226.660456)
		(width 0.14478)
		(layer "In2.Cu")
		(net "M_C_CPU1_SA_DQ<26>")
	)
	(segment
		(start 40.665146 -226.660456)
		(end 49.598834 -226.660456)
		(width 0.14478)
		(layer "In2.Cu")
		(net "M_C_CPU1_SA_DQ<26>")
	)
	(segment
		(start 53.961792 -226.660456)
		(end 57.153048 -226.660456)
		(width 0.14478)
		(layer "In2.Cu")
		(net "M_C_CPU1_SA_DQ<26>")
	)
	(segment
		(start 40.23995 -226.23526)
		(end 40.665146 -226.660456)
		(width 0.14478)
		(layer "In2.Cu")
		(net "M_C_CPU1_SA_DQ<26>")
	)
	(segment
		(start 66.113406 -231.634284)
		(end 73.032366 -238.553244)
		(width 0.14478)
		(layer "In2.Cu")
		(net "M_C_CPU1_SA_DQ<26>")
	)
	(segment
		(start 63.494666 -226.780344)
		(end 66.113406 -229.399084)
		(width 0.14478)
		(layer "In2.Cu")
		(net "M_C_CPU1_SA_DQ<26>")
	)
	(segment
		(start 76.512166 -238.916464)
		(end 77.152246 -238.916464)
		(width 0.0889)
		(layer "In2.Cu")
		(net "M_C_CPU1_SA_DQ<26>")
	)
	(segment
		(start 61.299852 -226.780344)
		(end 63.494666 -226.780344)
		(width 0.14478)
		(layer "In2.Cu")
		(net "M_C_CPU1_SA_DQ<26>")
	)
	(segment
		(start 78.303628 -240.067846)
		(end 78.431644 -240.067846)
		(width 0.0889)
		(layer "In2.Cu")
		(net "M_C_CPU1_SA_DQ<26>")
	)
	(segment
		(start 94.141036 -240.143538)
		(end 94.237048 -240.168938)
		(width 0.0889)
		(layer "In2.Cu")
		(net "M_C_CPU1_SA_DQ<26>")
	)
	(segment
		(start 89.504012 -240.111788)
		(end 89.512394 -240.106962)
		(width 0.0889)
		(layer "In2.Cu")
		(net "M_C_CPU1_SA_DQ<26>")
	)
	(segment
		(start 60.94349 -226.423982)
		(end 61.299852 -226.780344)
		(width 0.14478)
		(layer "In2.Cu")
		(net "M_C_CPU1_SA_DQ<26>")
	)
	(segment
		(start 81.044034 -240.111788)
		(end 81.052416 -240.106962)
		(width 0.0889)
		(layer "In2.Cu")
		(net "M_C_CPU1_SA_DQ<26>")
	)
	(segment
		(start 84.803996 -240.111788)
		(end 84.812378 -240.106962)
		(width 0.0889)
		(layer "In2.Cu")
		(net "M_C_CPU1_SA_DQ<26>")
	)
	(segment
		(start 58.003186 -225.810318)
		(end 60.61329 -225.810318)
		(width 0.14478)
		(layer "In2.Cu")
		(net "M_C_CPU1_SA_DQ<26>")
	)
	(segment
		(start 60.61329 -225.810318)
		(end 60.94349 -226.140518)
		(width 0.14478)
		(layer "In2.Cu")
		(net "M_C_CPU1_SA_DQ<26>")
	)
	(segment
		(start 93.263974 -240.111788)
		(end 93.272356 -240.106962)
		(width 0.0889)
		(layer "In2.Cu")
		(net "M_C_CPU1_SA_DQ<26>")
	)
	(segment
		(start 73.032366 -238.553244)
		(end 75.922886 -238.553244)
		(width 0.14478)
		(layer "In2.Cu")
		(net "M_C_CPU1_SA_DQ<26>")
	)
	(segment
		(start 87.989664 -240.106962)
		(end 87.998046 -240.111788)
		(width 0.0889)
		(layer "In2.Cu")
		(net "M_C_CPU1_SA_DQ<26>")
	)
	(segment
		(start 91.749626 -240.106962)
		(end 91.758008 -240.111788)
		(width 0.0889)
		(layer "In2.Cu")
		(net "M_C_CPU1_SA_DQ<26>")
	)
	(segment
		(start 88.929718 -240.106962)
		(end 88.9381 -240.111788)
		(width 0.0889)
		(layer "In2.Cu")
		(net "M_C_CPU1_SA_DQ<26>")
	)
	(segment
		(start 75.922886 -238.553244)
		(end 76.148946 -238.553244)
		(width 0.0889)
		(layer "In2.Cu")
		(net "M_C_CPU1_SA_DQ<26>")
	)
	(segment
		(start 78.595982 -240.112042)
		(end 78.629256 -240.131346)
		(width 0.0889)
		(layer "In2.Cu")
		(net "M_C_CPU1_SA_DQ<26>")
	)
	(segment
		(start 50.448972 -225.810318)
		(end 53.111654 -225.810318)
		(width 0.14478)
		(layer "In2.Cu")
		(net "M_C_CPU1_SA_DQ<26>")
	)
	(segment
		(start 57.153048 -226.660456)
		(end 58.003186 -225.810318)
		(width 0.14478)
		(layer "In2.Cu")
		(net "M_C_CPU1_SA_DQ<26>")
	)
	(segment
		(start 60.94349 -226.140518)
		(end 60.94349 -226.423982)
		(width 0.14478)
		(layer "In2.Cu")
		(net "M_C_CPU1_SA_DQ<26>")
	)
	(segment
		(start 92.68968 -240.106962)
		(end 92.698062 -240.111788)
		(width 0.0889)
		(layer "In2.Cu")
		(net "M_C_CPU1_SA_DQ<26>")
	)
	(segment
		(start 76.148946 -238.553244)
		(end 76.512166 -238.916464)
		(width 0.0889)
		(layer "In2.Cu")
		(net "M_C_CPU1_SA_DQ<26>")
	)
	(segment
		(start 66.113406 -229.399084)
		(end 66.113406 -231.634284)
		(width 0.14478)
		(layer "In2.Cu")
		(net "M_C_CPU1_SA_DQ<26>")
	)
	(segment
		(start 83.289648 -240.106962)
		(end 83.29803 -240.111788)
		(width 0.0889)
		(layer "In2.Cu")
		(net "M_C_CPU1_SA_DQ<26>")
	)
	(segment
		(start 84.229702 -240.106962)
		(end 84.238084 -240.111788)
		(width 0.0889)
		(layer "In2.Cu")
		(net "M_C_CPU1_SA_DQ<26>")
	)
	(segment
		(start 49.598834 -226.660456)
		(end 50.448972 -225.810318)
		(width 0.14478)
		(layer "In2.Cu")
		(net "M_C_CPU1_SA_DQ<26>")
	)
	(segment
		(start 79.158846 -240.111788)
		(end 79.185008 -240.096548)
		(width 0.0889)
		(layer "In2.Cu")
		(net "M_C_CPU1_SA_DQ<26>")
	)
	(segment
		(start 94.237048 -240.168938)
		(end 94.390972 -240.434368)
		(width 0.0889)
		(layer "In2.Cu")
		(net "M_C_CPU1_SA_DQ<26>")
	)
	(segment
		(start 80.46974 -240.106962)
		(end 80.478122 -240.111788)
		(width 0.0889)
		(layer "In2.Cu")
		(net "M_C_CPU1_SA_DQ<26>")
	)
	(segment
		(start 80.07223 -240.13033)
		(end 80.10398 -240.111788)
		(width 0.0889)
		(layer "In2.Cu")
		(net "M_C_CPU1_SA_DQ<26>")
	)
	(segment
		(start 77.152246 -238.916464)
		(end 78.303628 -240.067846)
		(width 0.0889)
		(layer "In2.Cu")
		(net "M_C_CPU1_SA_DQ<26>")
	)
	(arc
		(start 79.535274 -240.111534)
		(mid 79.801363 -240.188811)
		(end 80.07223 -240.13033)
		(width 0.0889)
		(layer "In2.Cu")
		(net "M_C_CPU1_SA_DQ<26>")
	)
	(arc
		(start 78.629256 -240.131346)
		(mid 78.896486 -240.187657)
		(end 79.158846 -240.111788)
		(width 0.0889)
		(layer "In2.Cu")
		(net "M_C_CPU1_SA_DQ<26>")
	)
	(arc
		(start 85.178138 -240.111788)
		(mid 85.461094 -240.187965)
		(end 85.74405 -240.111788)
		(width 0.0889)
		(layer "In2.Cu")
		(net "M_C_CPU1_SA_DQ<26>")
	)
	(arc
		(start 93.638116 -240.111788)
		(mid 93.885829 -240.187008)
		(end 94.141036 -240.143538)
		(width 0.0889)
		(layer "In2.Cu")
		(net "M_C_CPU1_SA_DQ<26>")
	)
	(arc
		(start 87.057992 -240.111788)
		(mid 87.340948 -240.187965)
		(end 87.623904 -240.111788)
		(width 0.0889)
		(layer "In2.Cu")
		(net "M_C_CPU1_SA_DQ<26>")
	)
	(arc
		(start 83.863942 -240.111788)
		(mid 84.046193 -240.061438)
		(end 84.229702 -240.106962)
		(width 0.0889)
		(layer "In2.Cu")
		(net "M_C_CPU1_SA_DQ<26>")
	)
	(arc
		(start 89.512394 -240.106962)
		(mid 89.695902 -240.061468)
		(end 89.878154 -240.111788)
		(width 0.0889)
		(layer "In2.Cu")
		(net "M_C_CPU1_SA_DQ<26>")
	)
	(arc
		(start 86.118192 -240.111788)
		(mid 86.401148 -240.187965)
		(end 86.684104 -240.111788)
		(width 0.0889)
		(layer "In2.Cu")
		(net "M_C_CPU1_SA_DQ<26>")
	)
	(arc
		(start 91.758008 -240.111788)
		(mid 92.040964 -240.187965)
		(end 92.32392 -240.111788)
		(width 0.0889)
		(layer "In2.Cu")
		(net "M_C_CPU1_SA_DQ<26>")
	)
	(arc
		(start 88.9381 -240.111788)
		(mid 89.221056 -240.187965)
		(end 89.504012 -240.111788)
		(width 0.0889)
		(layer "In2.Cu")
		(net "M_C_CPU1_SA_DQ<26>")
	)
	(arc
		(start 83.29803 -240.111788)
		(mid 83.580986 -240.187965)
		(end 83.863942 -240.111788)
		(width 0.0889)
		(layer "In2.Cu")
		(net "M_C_CPU1_SA_DQ<26>")
	)
	(arc
		(start 88.563958 -240.111788)
		(mid 88.746209 -240.061438)
		(end 88.929718 -240.106962)
		(width 0.0889)
		(layer "In2.Cu")
		(net "M_C_CPU1_SA_DQ<26>")
	)
	(arc
		(start 92.32392 -240.111788)
		(mid 92.506171 -240.061438)
		(end 92.68968 -240.106962)
		(width 0.0889)
		(layer "In2.Cu")
		(net "M_C_CPU1_SA_DQ<26>")
	)
	(arc
		(start 81.418176 -240.111788)
		(mid 81.701132 -240.187965)
		(end 81.984088 -240.111788)
		(width 0.0889)
		(layer "In2.Cu")
		(net "M_C_CPU1_SA_DQ<26>")
	)
	(arc
		(start 87.998046 -240.111788)
		(mid 88.281002 -240.187965)
		(end 88.563958 -240.111788)
		(width 0.0889)
		(layer "In2.Cu")
		(net "M_C_CPU1_SA_DQ<26>")
	)
	(arc
		(start 81.052416 -240.106962)
		(mid 81.235924 -240.061468)
		(end 81.418176 -240.111788)
		(width 0.0889)
		(layer "In2.Cu")
		(net "M_C_CPU1_SA_DQ<26>")
	)
	(arc
		(start 84.238084 -240.111788)
		(mid 84.52104 -240.187965)
		(end 84.803996 -240.111788)
		(width 0.0889)
		(layer "In2.Cu")
		(net "M_C_CPU1_SA_DQ<26>")
	)
	(arc
		(start 81.984088 -240.111788)
		(mid 82.171032 -240.061533)
		(end 82.357976 -240.111788)
		(width 0.0889)
		(layer "In2.Cu")
		(net "M_C_CPU1_SA_DQ<26>")
	)
	(arc
		(start 90.817954 -240.111788)
		(mid 91.10091 -240.187965)
		(end 91.383866 -240.111788)
		(width 0.0889)
		(layer "In2.Cu")
		(net "M_C_CPU1_SA_DQ<26>")
	)
	(arc
		(start 82.923888 -240.111788)
		(mid 83.106139 -240.061438)
		(end 83.289648 -240.106962)
		(width 0.0889)
		(layer "In2.Cu")
		(net "M_C_CPU1_SA_DQ<26>")
	)
	(arc
		(start 82.357976 -240.111788)
		(mid 82.640932 -240.187965)
		(end 82.923888 -240.111788)
		(width 0.0889)
		(layer "In2.Cu")
		(net "M_C_CPU1_SA_DQ<26>")
	)
	(arc
		(start 80.478122 -240.111788)
		(mid 80.761078 -240.187965)
		(end 81.044034 -240.111788)
		(width 0.0889)
		(layer "In2.Cu")
		(net "M_C_CPU1_SA_DQ<26>")
	)
	(arc
		(start 87.623904 -240.111788)
		(mid 87.806155 -240.061438)
		(end 87.989664 -240.106962)
		(width 0.0889)
		(layer "In2.Cu")
		(net "M_C_CPU1_SA_DQ<26>")
	)
	(arc
		(start 92.698062 -240.111788)
		(mid 92.981018 -240.187965)
		(end 93.263974 -240.111788)
		(width 0.0889)
		(layer "In2.Cu")
		(net "M_C_CPU1_SA_DQ<26>")
	)
	(arc
		(start 90.444066 -240.111788)
		(mid 90.63101 -240.061533)
		(end 90.817954 -240.111788)
		(width 0.0889)
		(layer "In2.Cu")
		(net "M_C_CPU1_SA_DQ<26>")
	)
	(arc
		(start 85.752432 -240.106962)
		(mid 85.93594 -240.061468)
		(end 86.118192 -240.111788)
		(width 0.0889)
		(layer "In2.Cu")
		(net "M_C_CPU1_SA_DQ<26>")
	)
	(arc
		(start 91.383866 -240.111788)
		(mid 91.566117 -240.061438)
		(end 91.749626 -240.106962)
		(width 0.0889)
		(layer "In2.Cu")
		(net "M_C_CPU1_SA_DQ<26>")
	)
	(arc
		(start 84.812378 -240.106962)
		(mid 84.995886 -240.061468)
		(end 85.178138 -240.111788)
		(width 0.0889)
		(layer "In2.Cu")
		(net "M_C_CPU1_SA_DQ<26>")
	)
	(arc
		(start 78.431644 -240.067846)
		(mid 78.516729 -240.079095)
		(end 78.595982 -240.112042)
		(width 0.0889)
		(layer "In2.Cu")
		(net "M_C_CPU1_SA_DQ<26>")
	)
	(arc
		(start 89.878154 -240.111788)
		(mid 90.16111 -240.187965)
		(end 90.444066 -240.111788)
		(width 0.0889)
		(layer "In2.Cu")
		(net "M_C_CPU1_SA_DQ<26>")
	)
	(arc
		(start 86.684104 -240.111788)
		(mid 86.871048 -240.061533)
		(end 87.057992 -240.111788)
		(width 0.0889)
		(layer "In2.Cu")
		(net "M_C_CPU1_SA_DQ<26>")
	)
	(arc
		(start 79.185008 -240.096548)
		(mid 79.362009 -240.06047)
		(end 79.535274 -240.111534)
		(width 0.0889)
		(layer "In2.Cu")
		(net "M_C_CPU1_SA_DQ<26>")
	)
	(arc
		(start 80.10398 -240.111788)
		(mid 80.286231 -240.061438)
		(end 80.46974 -240.106962)
		(width 0.0889)
		(layer "In2.Cu")
		(net "M_C_CPU1_SA_DQ<26>")
	)
	(arc
		(start 93.272356 -240.106962)
		(mid 93.455864 -240.061468)
		(end 93.638116 -240.111788)
		(width 0.0889)
		(layer "In2.Cu")
		(net "M_C_CPU1_SA_DQ<26>")
	)
	(segment
		(start 95.797878 -240.700306)
		(end 95.331026 -240.434368)
		(width 0.10668)
		(layer "F.Cu")
		(net "M_C_CPU1_SA_DQ<25>")
	)
	(segment
		(start 93.263974 -240.756948)
		(end 93.272356 -240.761774)
		(width 0.0889)
		(layer "In2.Cu")
		(net "M_C_CPU1_SA_DQ<25>")
	)
	(segment
		(start 56.610504 -227.286312)
		(end 56.610504 -227.347272)
		(width 0.14478)
		(layer "In2.Cu")
		(net "M_C_CPU1_SA_DQ<25>")
	)
	(segment
		(start 54.878986 -227.286312)
		(end 54.878986 -227.347272)
		(width 0.14478)
		(layer "In2.Cu")
		(net "M_C_CPU1_SA_DQ<25>")
	)
	(segment
		(start 76.138786 -239.010444)
		(end 76.321666 -239.193324)
		(width 0.0889)
		(layer "In2.Cu")
		(net "M_C_CPU1_SA_DQ<25>")
	)
	(segment
		(start 50.840386 -226.497388)
		(end 50.840386 -226.440492)
		(width 0.14478)
		(layer "In2.Cu")
		(net "M_C_CPU1_SA_DQ<25>")
	)
	(segment
		(start 54.159404 -227.51034)
		(end 54.322472 -227.347272)
		(width 0.14478)
		(layer "In2.Cu")
		(net "M_C_CPU1_SA_DQ<25>")
	)
	(segment
		(start 77.444346 -239.985296)
		(end 78.183994 -240.724944)
		(width 0.0889)
		(layer "In2.Cu")
		(net "M_C_CPU1_SA_DQ<25>")
	)
	(segment
		(start 49.245012 -227.51034)
		(end 49.427384 -227.51034)
		(width 0.14478)
		(layer "In2.Cu")
		(net "M_C_CPU1_SA_DQ<25>")
	)
	(segment
		(start 49.427384 -227.51034)
		(end 50.277268 -226.660456)
		(width 0.14478)
		(layer "In2.Cu")
		(net "M_C_CPU1_SA_DQ<25>")
	)
	(segment
		(start 83.289648 -240.761774)
		(end 83.29803 -240.756948)
		(width 0.0889)
		(layer "In2.Cu")
		(net "M_C_CPU1_SA_DQ<25>")
	)
	(segment
		(start 58.387996 -226.497388)
		(end 58.387996 -226.435412)
		(width 0.14478)
		(layer "In2.Cu")
		(net "M_C_CPU1_SA_DQ<25>")
	)
	(segment
		(start 76.321666 -239.193324)
		(end 77.060806 -239.193324)
		(width 0.0889)
		(layer "In2.Cu")
		(net "M_C_CPU1_SA_DQ<25>")
	)
	(segment
		(start 85.74405 -240.756948)
		(end 85.752432 -240.761774)
		(width 0.0889)
		(layer "In2.Cu")
		(net "M_C_CPU1_SA_DQ<25>")
	)
	(segment
		(start 55.890922 -227.51034)
		(end 56.05399 -227.347272)
		(width 0.14478)
		(layer "In2.Cu")
		(net "M_C_CPU1_SA_DQ<25>")
	)
	(segment
		(start 54.322472 -227.347272)
		(end 54.322472 -227.286312)
		(width 0.14478)
		(layer "In2.Cu")
		(net "M_C_CPU1_SA_DQ<25>")
	)
	(segment
		(start 49.081944 -227.293932)
		(end 49.081944 -227.347272)
		(width 0.14478)
		(layer "In2.Cu")
		(net "M_C_CPU1_SA_DQ<25>")
	)
	(segment
		(start 48.52543 -227.347272)
		(end 48.52543 -227.293932)
		(width 0.14478)
		(layer "In2.Cu")
		(net "M_C_CPU1_SA_DQ<25>")
	)
	(segment
		(start 92.68968 -240.761774)
		(end 92.698062 -240.756948)
		(width 0.0889)
		(layer "In2.Cu")
		(net "M_C_CPU1_SA_DQ<25>")
	)
	(segment
		(start 54.48554 -227.123244)
		(end 54.715918 -227.123244)
		(width 0.14478)
		(layer "In2.Cu")
		(net "M_C_CPU1_SA_DQ<25>")
	)
	(segment
		(start 52.82692 -226.448112)
		(end 52.82692 -226.497388)
		(width 0.14478)
		(layer "In2.Cu")
		(net "M_C_CPU1_SA_DQ<25>")
	)
	(segment
		(start 56.610504 -227.347272)
		(end 56.773572 -227.51034)
		(width 0.14478)
		(layer "In2.Cu")
		(net "M_C_CPU1_SA_DQ<25>")
	)
	(segment
		(start 56.773572 -227.51034)
		(end 56.950864 -227.51034)
		(width 0.14478)
		(layer "In2.Cu")
		(net "M_C_CPU1_SA_DQ<25>")
	)
	(segment
		(start 52.663852 -226.285044)
		(end 52.82692 -226.448112)
		(width 0.14478)
		(layer "In2.Cu")
		(net "M_C_CPU1_SA_DQ<25>")
	)
	(segment
		(start 52.989988 -226.660456)
		(end 53.102764 -226.660456)
		(width 0.14478)
		(layer "In2.Cu")
		(net "M_C_CPU1_SA_DQ<25>")
	)
	(segment
		(start 50.277268 -226.660456)
		(end 50.677318 -226.660456)
		(width 0.14478)
		(layer "In2.Cu")
		(net "M_C_CPU1_SA_DQ<25>")
	)
	(segment
		(start 52.433474 -226.285044)
		(end 52.663852 -226.285044)
		(width 0.14478)
		(layer "In2.Cu")
		(net "M_C_CPU1_SA_DQ<25>")
	)
	(segment
		(start 56.05399 -227.286312)
		(end 56.217058 -227.123244)
		(width 0.14478)
		(layer "In2.Cu")
		(net "M_C_CPU1_SA_DQ<25>")
	)
	(segment
		(start 95.48495 -240.699798)
		(end 95.331026 -240.434368)
		(width 0.0889)
		(layer "In2.Cu")
		(net "M_C_CPU1_SA_DQ<25>")
	)
	(segment
		(start 48.918876 -227.130864)
		(end 49.081944 -227.293932)
		(width 0.14478)
		(layer "In2.Cu")
		(net "M_C_CPU1_SA_DQ<25>")
	)
	(segment
		(start 95.462598 -240.78311)
		(end 95.48495 -240.699798)
		(width 0.0889)
		(layer "In2.Cu")
		(net "M_C_CPU1_SA_DQ<25>")
	)
	(segment
		(start 51.3969 -226.497388)
		(end 51.559968 -226.660456)
		(width 0.14478)
		(layer "In2.Cu")
		(net "M_C_CPU1_SA_DQ<25>")
	)
	(segment
		(start 44.340018 -227.085398)
		(end 44.76496 -227.51034)
		(width 0.14478)
		(layer "In2.Cu")
		(net "M_C_CPU1_SA_DQ<25>")
	)
	(segment
		(start 65.658746 -231.827324)
		(end 72.841866 -239.010444)
		(width 0.14478)
		(layer "In2.Cu")
		(net "M_C_CPU1_SA_DQ<25>")
	)
	(segment
		(start 56.217058 -227.123244)
		(end 56.447436 -227.123244)
		(width 0.14478)
		(layer "In2.Cu")
		(net "M_C_CPU1_SA_DQ<25>")
	)
	(segment
		(start 58.224928 -226.660456)
		(end 58.387996 -226.497388)
		(width 0.14478)
		(layer "In2.Cu")
		(net "M_C_CPU1_SA_DQ<25>")
	)
	(segment
		(start 94.204028 -240.756948)
		(end 94.21241 -240.761774)
		(width 0.0889)
		(layer "In2.Cu")
		(net "M_C_CPU1_SA_DQ<25>")
	)
	(segment
		(start 48.52543 -227.293932)
		(end 48.688498 -227.130864)
		(width 0.14478)
		(layer "In2.Cu")
		(net "M_C_CPU1_SA_DQ<25>")
	)
	(segment
		(start 79.5401 -240.756694)
		(end 79.566262 -240.741708)
		(width 0.0889)
		(layer "In2.Cu")
		(net "M_C_CPU1_SA_DQ<25>")
	)
	(segment
		(start 79.138018 -240.739676)
		(end 79.167482 -240.756948)
		(width 0.0889)
		(layer "In2.Cu")
		(net "M_C_CPU1_SA_DQ<25>")
	)
	(segment
		(start 81.044034 -240.756948)
		(end 81.052416 -240.761774)
		(width 0.0889)
		(layer "In2.Cu")
		(net "M_C_CPU1_SA_DQ<25>")
	)
	(segment
		(start 60.517786 -226.660456)
		(end 61.097414 -227.240084)
		(width 0.14478)
		(layer "In2.Cu")
		(net "M_C_CPU1_SA_DQ<25>")
	)
	(segment
		(start 84.803996 -240.756948)
		(end 84.812378 -240.761774)
		(width 0.0889)
		(layer "In2.Cu")
		(net "M_C_CPU1_SA_DQ<25>")
	)
	(segment
		(start 63.273686 -227.240084)
		(end 65.658746 -229.625144)
		(width 0.14478)
		(layer "In2.Cu")
		(net "M_C_CPU1_SA_DQ<25>")
	)
	(segment
		(start 52.270406 -226.448112)
		(end 52.433474 -226.285044)
		(width 0.14478)
		(layer "In2.Cu")
		(net "M_C_CPU1_SA_DQ<25>")
	)
	(segment
		(start 56.950864 -227.51034)
		(end 57.800748 -226.660456)
		(width 0.14478)
		(layer "In2.Cu")
		(net "M_C_CPU1_SA_DQ<25>")
	)
	(segment
		(start 52.107338 -226.660456)
		(end 52.270406 -226.497388)
		(width 0.14478)
		(layer "In2.Cu")
		(net "M_C_CPU1_SA_DQ<25>")
	)
	(segment
		(start 53.952648 -227.51034)
		(end 54.159404 -227.51034)
		(width 0.14478)
		(layer "In2.Cu")
		(net "M_C_CPU1_SA_DQ<25>")
	)
	(segment
		(start 55.042054 -227.51034)
		(end 55.890922 -227.51034)
		(width 0.14478)
		(layer "In2.Cu")
		(net "M_C_CPU1_SA_DQ<25>")
	)
	(segment
		(start 56.05399 -227.347272)
		(end 56.05399 -227.286312)
		(width 0.14478)
		(layer "In2.Cu")
		(net "M_C_CPU1_SA_DQ<25>")
	)
	(segment
		(start 48.688498 -227.130864)
		(end 48.918876 -227.130864)
		(width 0.14478)
		(layer "In2.Cu")
		(net "M_C_CPU1_SA_DQ<25>")
	)
	(segment
		(start 49.081944 -227.347272)
		(end 49.245012 -227.51034)
		(width 0.14478)
		(layer "In2.Cu")
		(net "M_C_CPU1_SA_DQ<25>")
	)
	(segment
		(start 52.82692 -226.497388)
		(end 52.989988 -226.660456)
		(width 0.14478)
		(layer "In2.Cu")
		(net "M_C_CPU1_SA_DQ<25>")
	)
	(segment
		(start 51.233832 -226.277424)
		(end 51.3969 -226.440492)
		(width 0.14478)
		(layer "In2.Cu")
		(net "M_C_CPU1_SA_DQ<25>")
	)
	(segment
		(start 51.559968 -226.660456)
		(end 52.107338 -226.660456)
		(width 0.14478)
		(layer "In2.Cu")
		(net "M_C_CPU1_SA_DQ<25>")
	)
	(segment
		(start 78.22565 -240.756694)
		(end 78.256892 -240.774474)
		(width 0.0889)
		(layer "In2.Cu")
		(net "M_C_CPU1_SA_DQ<25>")
	)
	(segment
		(start 56.447436 -227.123244)
		(end 56.610504 -227.286312)
		(width 0.14478)
		(layer "In2.Cu")
		(net "M_C_CPU1_SA_DQ<25>")
	)
	(segment
		(start 91.749626 -240.761774)
		(end 91.758008 -240.756948)
		(width 0.0889)
		(layer "In2.Cu")
		(net "M_C_CPU1_SA_DQ<25>")
	)
	(segment
		(start 51.3969 -226.440492)
		(end 51.3969 -226.497388)
		(width 0.14478)
		(layer "In2.Cu")
		(net "M_C_CPU1_SA_DQ<25>")
	)
	(segment
		(start 54.878986 -227.347272)
		(end 55.042054 -227.51034)
		(width 0.14478)
		(layer "In2.Cu")
		(net "M_C_CPU1_SA_DQ<25>")
	)
	(segment
		(start 48.362362 -227.51034)
		(end 48.52543 -227.347272)
		(width 0.14478)
		(layer "In2.Cu")
		(net "M_C_CPU1_SA_DQ<25>")
	)
	(segment
		(start 88.929718 -240.761774)
		(end 88.9381 -240.756948)
		(width 0.0889)
		(layer "In2.Cu")
		(net "M_C_CPU1_SA_DQ<25>")
	)
	(segment
		(start 58.94451 -226.497388)
		(end 59.107578 -226.660456)
		(width 0.14478)
		(layer "In2.Cu")
		(net "M_C_CPU1_SA_DQ<25>")
	)
	(segment
		(start 53.102764 -226.660456)
		(end 53.952648 -227.51034)
		(width 0.14478)
		(layer "In2.Cu")
		(net "M_C_CPU1_SA_DQ<25>")
	)
	(segment
		(start 58.551064 -226.272344)
		(end 58.781442 -226.272344)
		(width 0.14478)
		(layer "In2.Cu")
		(net "M_C_CPU1_SA_DQ<25>")
	)
	(segment
		(start 80.46974 -240.761774)
		(end 80.478122 -240.756948)
		(width 0.0889)
		(layer "In2.Cu")
		(net "M_C_CPU1_SA_DQ<25>")
	)
	(segment
		(start 79.518256 -240.76914)
		(end 79.5401 -240.756694)
		(width 0.0889)
		(layer "In2.Cu")
		(net "M_C_CPU1_SA_DQ<25>")
	)
	(segment
		(start 52.270406 -226.497388)
		(end 52.270406 -226.448112)
		(width 0.14478)
		(layer "In2.Cu")
		(net "M_C_CPU1_SA_DQ<25>")
	)
	(segment
		(start 58.387996 -226.435412)
		(end 58.551064 -226.272344)
		(width 0.14478)
		(layer "In2.Cu")
		(net "M_C_CPU1_SA_DQ<25>")
	)
	(segment
		(start 58.781442 -226.272344)
		(end 58.94451 -226.435412)
		(width 0.14478)
		(layer "In2.Cu")
		(net "M_C_CPU1_SA_DQ<25>")
	)
	(segment
		(start 65.658746 -229.625144)
		(end 65.658746 -231.827324)
		(width 0.14478)
		(layer "In2.Cu")
		(net "M_C_CPU1_SA_DQ<25>")
	)
	(segment
		(start 84.229702 -240.761774)
		(end 84.238084 -240.756948)
		(width 0.0889)
		(layer "In2.Cu")
		(net "M_C_CPU1_SA_DQ<25>")
	)
	(segment
		(start 59.107578 -226.660456)
		(end 60.517786 -226.660456)
		(width 0.14478)
		(layer "In2.Cu")
		(net "M_C_CPU1_SA_DQ<25>")
	)
	(segment
		(start 77.444346 -239.576864)
		(end 77.444346 -239.985296)
		(width 0.0889)
		(layer "In2.Cu")
		(net "M_C_CPU1_SA_DQ<25>")
	)
	(segment
		(start 44.76496 -227.51034)
		(end 48.362362 -227.51034)
		(width 0.14478)
		(layer "In2.Cu")
		(net "M_C_CPU1_SA_DQ<25>")
	)
	(segment
		(start 50.840386 -226.440492)
		(end 51.003454 -226.277424)
		(width 0.14478)
		(layer "In2.Cu")
		(net "M_C_CPU1_SA_DQ<25>")
	)
	(segment
		(start 87.989664 -240.761774)
		(end 87.998046 -240.756948)
		(width 0.0889)
		(layer "In2.Cu")
		(net "M_C_CPU1_SA_DQ<25>")
	)
	(segment
		(start 51.003454 -226.277424)
		(end 51.233832 -226.277424)
		(width 0.14478)
		(layer "In2.Cu")
		(net "M_C_CPU1_SA_DQ<25>")
	)
	(segment
		(start 61.097414 -227.240084)
		(end 63.273686 -227.240084)
		(width 0.14478)
		(layer "In2.Cu")
		(net "M_C_CPU1_SA_DQ<25>")
	)
	(segment
		(start 72.841866 -239.010444)
		(end 75.938126 -239.010444)
		(width 0.14478)
		(layer "In2.Cu")
		(net "M_C_CPU1_SA_DQ<25>")
	)
	(segment
		(start 50.677318 -226.660456)
		(end 50.840386 -226.497388)
		(width 0.14478)
		(layer "In2.Cu")
		(net "M_C_CPU1_SA_DQ<25>")
	)
	(segment
		(start 54.715918 -227.123244)
		(end 54.878986 -227.286312)
		(width 0.14478)
		(layer "In2.Cu")
		(net "M_C_CPU1_SA_DQ<25>")
	)
	(segment
		(start 75.938126 -239.010444)
		(end 76.138786 -239.010444)
		(width 0.0889)
		(layer "In2.Cu")
		(net "M_C_CPU1_SA_DQ<25>")
	)
	(segment
		(start 89.504012 -240.756948)
		(end 89.512394 -240.761774)
		(width 0.0889)
		(layer "In2.Cu")
		(net "M_C_CPU1_SA_DQ<25>")
	)
	(segment
		(start 77.060806 -239.193324)
		(end 77.444346 -239.576864)
		(width 0.0889)
		(layer "In2.Cu")
		(net "M_C_CPU1_SA_DQ<25>")
	)
	(segment
		(start 57.800748 -226.660456)
		(end 58.224928 -226.660456)
		(width 0.14478)
		(layer "In2.Cu")
		(net "M_C_CPU1_SA_DQ<25>")
	)
	(segment
		(start 58.94451 -226.435412)
		(end 58.94451 -226.497388)
		(width 0.14478)
		(layer "In2.Cu")
		(net "M_C_CPU1_SA_DQ<25>")
	)
	(segment
		(start 54.322472 -227.286312)
		(end 54.48554 -227.123244)
		(width 0.14478)
		(layer "In2.Cu")
		(net "M_C_CPU1_SA_DQ<25>")
	)
	(arc
		(start 86.684104 -240.756948)
		(mid 86.871048 -240.807203)
		(end 87.057992 -240.756948)
		(width 0.0889)
		(layer "In2.Cu")
		(net "M_C_CPU1_SA_DQ<25>")
	)
	(arc
		(start 87.998046 -240.756948)
		(mid 88.281002 -240.680771)
		(end 88.563958 -240.756948)
		(width 0.0889)
		(layer "In2.Cu")
		(net "M_C_CPU1_SA_DQ<25>")
	)
	(arc
		(start 92.32392 -240.756948)
		(mid 92.506171 -240.807298)
		(end 92.68968 -240.761774)
		(width 0.0889)
		(layer "In2.Cu")
		(net "M_C_CPU1_SA_DQ<25>")
	)
	(arc
		(start 80.10398 -240.756948)
		(mid 80.286231 -240.807298)
		(end 80.46974 -240.761774)
		(width 0.0889)
		(layer "In2.Cu")
		(net "M_C_CPU1_SA_DQ<25>")
	)
	(arc
		(start 84.238084 -240.756948)
		(mid 84.52104 -240.680771)
		(end 84.803996 -240.756948)
		(width 0.0889)
		(layer "In2.Cu")
		(net "M_C_CPU1_SA_DQ<25>")
	)
	(arc
		(start 78.599538 -240.756948)
		(mid 78.866595 -240.679913)
		(end 79.138018 -240.739676)
		(width 0.0889)
		(layer "In2.Cu")
		(net "M_C_CPU1_SA_DQ<25>")
	)
	(arc
		(start 78.183994 -240.724944)
		(mid 78.203754 -240.74222)
		(end 78.22565 -240.756694)
		(width 0.0889)
		(layer "In2.Cu")
		(net "M_C_CPU1_SA_DQ<25>")
	)
	(arc
		(start 81.052416 -240.761774)
		(mid 81.235924 -240.807268)
		(end 81.418176 -240.756948)
		(width 0.0889)
		(layer "In2.Cu")
		(net "M_C_CPU1_SA_DQ<25>")
	)
	(arc
		(start 81.418176 -240.756948)
		(mid 81.701132 -240.680771)
		(end 81.984088 -240.756948)
		(width 0.0889)
		(layer "In2.Cu")
		(net "M_C_CPU1_SA_DQ<25>")
	)
	(arc
		(start 88.563958 -240.756948)
		(mid 88.746209 -240.807298)
		(end 88.929718 -240.761774)
		(width 0.0889)
		(layer "In2.Cu")
		(net "M_C_CPU1_SA_DQ<25>")
	)
	(arc
		(start 83.29803 -240.756948)
		(mid 83.580986 -240.680771)
		(end 83.863942 -240.756948)
		(width 0.0889)
		(layer "In2.Cu")
		(net "M_C_CPU1_SA_DQ<25>")
	)
	(arc
		(start 89.512394 -240.761774)
		(mid 89.695902 -240.807268)
		(end 89.878154 -240.756948)
		(width 0.0889)
		(layer "In2.Cu")
		(net "M_C_CPU1_SA_DQ<25>")
	)
	(arc
		(start 93.638116 -240.756948)
		(mid 93.921072 -240.680771)
		(end 94.204028 -240.756948)
		(width 0.0889)
		(layer "In2.Cu")
		(net "M_C_CPU1_SA_DQ<25>")
	)
	(arc
		(start 88.9381 -240.756948)
		(mid 89.221056 -240.680771)
		(end 89.504012 -240.756948)
		(width 0.0889)
		(layer "In2.Cu")
		(net "M_C_CPU1_SA_DQ<25>")
	)
	(arc
		(start 87.623904 -240.756948)
		(mid 87.806155 -240.807298)
		(end 87.989664 -240.761774)
		(width 0.0889)
		(layer "In2.Cu")
		(net "M_C_CPU1_SA_DQ<25>")
	)
	(arc
		(start 89.878154 -240.756948)
		(mid 90.16111 -240.680771)
		(end 90.444066 -240.756948)
		(width 0.0889)
		(layer "In2.Cu")
		(net "M_C_CPU1_SA_DQ<25>")
	)
	(arc
		(start 84.812378 -240.761774)
		(mid 84.995886 -240.807268)
		(end 85.178138 -240.756948)
		(width 0.0889)
		(layer "In2.Cu")
		(net "M_C_CPU1_SA_DQ<25>")
	)
	(arc
		(start 83.863942 -240.756948)
		(mid 84.046193 -240.807298)
		(end 84.229702 -240.761774)
		(width 0.0889)
		(layer "In2.Cu")
		(net "M_C_CPU1_SA_DQ<25>")
	)
	(arc
		(start 87.057992 -240.756948)
		(mid 87.340948 -240.680771)
		(end 87.623904 -240.756948)
		(width 0.0889)
		(layer "In2.Cu")
		(net "M_C_CPU1_SA_DQ<25>")
	)
	(arc
		(start 85.752432 -240.761774)
		(mid 85.93594 -240.807268)
		(end 86.118192 -240.756948)
		(width 0.0889)
		(layer "In2.Cu")
		(net "M_C_CPU1_SA_DQ<25>")
	)
	(arc
		(start 94.21241 -240.761774)
		(mid 94.395918 -240.807268)
		(end 94.57817 -240.756948)
		(width 0.0889)
		(layer "In2.Cu")
		(net "M_C_CPU1_SA_DQ<25>")
	)
	(arc
		(start 90.444066 -240.756948)
		(mid 90.63101 -240.807203)
		(end 90.817954 -240.756948)
		(width 0.0889)
		(layer "In2.Cu")
		(net "M_C_CPU1_SA_DQ<25>")
	)
	(arc
		(start 78.256892 -240.774474)
		(mid 78.430354 -240.807408)
		(end 78.599538 -240.756948)
		(width 0.0889)
		(layer "In2.Cu")
		(net "M_C_CPU1_SA_DQ<25>")
	)
	(arc
		(start 79.167482 -240.756948)
		(mid 79.341332 -240.806854)
		(end 79.518256 -240.76914)
		(width 0.0889)
		(layer "In2.Cu")
		(net "M_C_CPU1_SA_DQ<25>")
	)
	(arc
		(start 82.923888 -240.756948)
		(mid 83.106139 -240.807298)
		(end 83.289648 -240.761774)
		(width 0.0889)
		(layer "In2.Cu")
		(net "M_C_CPU1_SA_DQ<25>")
	)
	(arc
		(start 92.698062 -240.756948)
		(mid 92.981018 -240.680771)
		(end 93.263974 -240.756948)
		(width 0.0889)
		(layer "In2.Cu")
		(net "M_C_CPU1_SA_DQ<25>")
	)
	(arc
		(start 93.272356 -240.761774)
		(mid 93.455864 -240.807268)
		(end 93.638116 -240.756948)
		(width 0.0889)
		(layer "In2.Cu")
		(net "M_C_CPU1_SA_DQ<25>")
	)
	(arc
		(start 91.758008 -240.756948)
		(mid 92.040964 -240.680771)
		(end 92.32392 -240.756948)
		(width 0.0889)
		(layer "In2.Cu")
		(net "M_C_CPU1_SA_DQ<25>")
	)
	(arc
		(start 90.817954 -240.756948)
		(mid 91.10091 -240.680771)
		(end 91.383866 -240.756948)
		(width 0.0889)
		(layer "In2.Cu")
		(net "M_C_CPU1_SA_DQ<25>")
	)
	(arc
		(start 85.178138 -240.756948)
		(mid 85.461094 -240.680771)
		(end 85.74405 -240.756948)
		(width 0.0889)
		(layer "In2.Cu")
		(net "M_C_CPU1_SA_DQ<25>")
	)
	(arc
		(start 91.383866 -240.756948)
		(mid 91.566117 -240.807298)
		(end 91.749626 -240.761774)
		(width 0.0889)
		(layer "In2.Cu")
		(net "M_C_CPU1_SA_DQ<25>")
	)
	(arc
		(start 86.118192 -240.756948)
		(mid 86.401148 -240.680771)
		(end 86.684104 -240.756948)
		(width 0.0889)
		(layer "In2.Cu")
		(net "M_C_CPU1_SA_DQ<25>")
	)
	(arc
		(start 82.357976 -240.756948)
		(mid 82.640932 -240.680771)
		(end 82.923888 -240.756948)
		(width 0.0889)
		(layer "In2.Cu")
		(net "M_C_CPU1_SA_DQ<25>")
	)
	(arc
		(start 81.984088 -240.756948)
		(mid 82.171032 -240.807203)
		(end 82.357976 -240.756948)
		(width 0.0889)
		(layer "In2.Cu")
		(net "M_C_CPU1_SA_DQ<25>")
	)
	(arc
		(start 80.478122 -240.756948)
		(mid 80.761078 -240.680771)
		(end 81.044034 -240.756948)
		(width 0.0889)
		(layer "In2.Cu")
		(net "M_C_CPU1_SA_DQ<25>")
	)
	(arc
		(start 95.144082 -240.756948)
		(mid 95.300401 -240.805943)
		(end 95.462598 -240.78311)
		(width 0.0889)
		(layer "In2.Cu")
		(net "M_C_CPU1_SA_DQ<25>")
	)
	(arc
		(start 94.57817 -240.756948)
		(mid 94.861126 -240.680771)
		(end 95.144082 -240.756948)
		(width 0.0889)
		(layer "In2.Cu")
		(net "M_C_CPU1_SA_DQ<25>")
	)
	(arc
		(start 79.566262 -240.741708)
		(mid 79.837048 -240.681062)
		(end 80.10398 -240.756948)
		(width 0.0889)
		(layer "In2.Cu")
		(net "M_C_CPU1_SA_DQ<25>")
	)
	(segment
		(start 94.387924 -239.8903)
		(end 93.921072 -239.624362)
		(width 0.10668)
		(layer "F.Cu")
		(net "M_C_CPU1_SA_DQ<24>")
	)
	(segment
		(start 78.357222 -239.708944)
		(end 78.464918 -239.708944)
		(width 0.0889)
		(layer "In2.Cu")
		(net "M_C_CPU1_SA_DQ<24>")
	)
	(segment
		(start 49.492916 -225.810318)
		(end 49.803812 -225.810318)
		(width 0.14478)
		(layer "In2.Cu")
		(net "M_C_CPU1_SA_DQ<24>")
	)
	(segment
		(start 46.037754 -226.034854)
		(end 46.200822 -226.197922)
		(width 0.14478)
		(layer "In2.Cu")
		(net "M_C_CPU1_SA_DQ<24>")
	)
	(segment
		(start 46.4312 -226.197922)
		(end 46.594268 -226.034854)
		(width 0.14478)
		(layer "In2.Cu")
		(net "M_C_CPU1_SA_DQ<24>")
	)
	(segment
		(start 61.41847 -225.742246)
		(end 61.41847 -226.133406)
		(width 0.14478)
		(layer "In2.Cu")
		(net "M_C_CPU1_SA_DQ<24>")
	)
	(segment
		(start 56.950356 -226.030536)
		(end 56.950356 -225.973386)
		(width 0.14478)
		(layer "In2.Cu")
		(net "M_C_CPU1_SA_DQ<24>")
	)
	(segment
		(start 48.610266 -225.810318)
		(end 48.773334 -225.973386)
		(width 0.14478)
		(layer "In2.Cu")
		(net "M_C_CPU1_SA_DQ<24>")
	)
	(segment
		(start 62.015878 -226.318064)
		(end 62.208664 -226.125278)
		(width 0.14478)
		(layer "In2.Cu")
		(net "M_C_CPU1_SA_DQ<24>")
	)
	(segment
		(start 63.697866 -226.318064)
		(end 66.575686 -229.195884)
		(width 0.14478)
		(layer "In2.Cu")
		(net "M_C_CPU1_SA_DQ<24>")
	)
	(segment
		(start 94.052644 -239.973104)
		(end 94.074996 -239.889792)
		(width 0.0889)
		(layer "In2.Cu")
		(net "M_C_CPU1_SA_DQ<24>")
	)
	(segment
		(start 87.154004 -239.946942)
		(end 87.162386 -239.951768)
		(width 0.0889)
		(layer "In2.Cu")
		(net "M_C_CPU1_SA_DQ<24>")
	)
	(segment
		(start 56.950356 -225.973386)
		(end 57.113424 -225.810318)
		(width 0.14478)
		(layer "In2.Cu")
		(net "M_C_CPU1_SA_DQ<24>")
	)
	(segment
		(start 44.924726 -226.034854)
		(end 45.087794 -226.197922)
		(width 0.14478)
		(layer "In2.Cu")
		(net "M_C_CPU1_SA_DQ<24>")
	)
	(segment
		(start 50.653696 -224.960434)
		(end 53.102764 -224.960434)
		(width 0.14478)
		(layer "In2.Cu")
		(net "M_C_CPU1_SA_DQ<24>")
	)
	(segment
		(start 76.108306 -238.098584)
		(end 76.644246 -238.634524)
		(width 0.0889)
		(layer "In2.Cu")
		(net "M_C_CPU1_SA_DQ<24>")
	)
	(segment
		(start 66.575686 -231.441244)
		(end 73.233026 -238.098584)
		(width 0.14478)
		(layer "In2.Cu")
		(net "M_C_CPU1_SA_DQ<24>")
	)
	(segment
		(start 85.639656 -239.951768)
		(end 85.648038 -239.946942)
		(width 0.0889)
		(layer "In2.Cu")
		(net "M_C_CPU1_SA_DQ<24>")
	)
	(segment
		(start 56.393842 -225.973386)
		(end 56.393842 -226.030536)
		(width 0.14478)
		(layer "In2.Cu")
		(net "M_C_CPU1_SA_DQ<24>")
	)
	(segment
		(start 46.594268 -225.970084)
		(end 46.754034 -225.810318)
		(width 0.14478)
		(layer "In2.Cu")
		(net "M_C_CPU1_SA_DQ<24>")
	)
	(segment
		(start 49.803812 -225.810318)
		(end 50.653696 -224.960434)
		(width 0.14478)
		(layer "In2.Cu")
		(net "M_C_CPU1_SA_DQ<24>")
	)
	(segment
		(start 81.879694 -239.951768)
		(end 81.888076 -239.946942)
		(width 0.0889)
		(layer "In2.Cu")
		(net "M_C_CPU1_SA_DQ<24>")
	)
	(segment
		(start 49.16678 -226.185984)
		(end 49.329848 -226.022916)
		(width 0.14478)
		(layer "In2.Cu")
		(net "M_C_CPU1_SA_DQ<24>")
	)
	(segment
		(start 88.094058 -239.946942)
		(end 88.10244 -239.951768)
		(width 0.0889)
		(layer "In2.Cu")
		(net "M_C_CPU1_SA_DQ<24>")
	)
	(segment
		(start 56.393842 -226.030536)
		(end 56.55691 -226.193604)
		(width 0.14478)
		(layer "In2.Cu")
		(net "M_C_CPU1_SA_DQ<24>")
	)
	(segment
		(start 45.318172 -226.197922)
		(end 45.48124 -226.034854)
		(width 0.14478)
		(layer "In2.Cu")
		(net "M_C_CPU1_SA_DQ<24>")
	)
	(segment
		(start 94.074996 -239.889792)
		(end 93.921072 -239.624362)
		(width 0.0889)
		(layer "In2.Cu")
		(net "M_C_CPU1_SA_DQ<24>")
	)
	(segment
		(start 63.059564 -226.318064)
		(end 63.697866 -226.318064)
		(width 0.14478)
		(layer "In2.Cu")
		(net "M_C_CPU1_SA_DQ<24>")
	)
	(segment
		(start 56.230774 -225.810318)
		(end 56.393842 -225.973386)
		(width 0.14478)
		(layer "In2.Cu")
		(net "M_C_CPU1_SA_DQ<24>")
	)
	(segment
		(start 48.936402 -226.185984)
		(end 49.16678 -226.185984)
		(width 0.14478)
		(layer "In2.Cu")
		(net "M_C_CPU1_SA_DQ<24>")
	)
	(segment
		(start 78.464918 -239.708944)
		(end 78.71841 -239.962436)
		(width 0.0889)
		(layer "In2.Cu")
		(net "M_C_CPU1_SA_DQ<24>")
	)
	(segment
		(start 57.113424 -225.810318)
		(end 57.337452 -225.810318)
		(width 0.14478)
		(layer "In2.Cu")
		(net "M_C_CPU1_SA_DQ<24>")
	)
	(segment
		(start 48.773334 -225.973386)
		(end 48.773334 -226.022916)
		(width 0.14478)
		(layer "In2.Cu")
		(net "M_C_CPU1_SA_DQ<24>")
	)
	(segment
		(start 62.208664 -225.50247)
		(end 62.40145 -225.309684)
		(width 0.14478)
		(layer "In2.Cu")
		(net "M_C_CPU1_SA_DQ<24>")
	)
	(segment
		(start 61.41847 -226.133406)
		(end 61.603128 -226.318064)
		(width 0.14478)
		(layer "In2.Cu")
		(net "M_C_CPU1_SA_DQ<24>")
	)
	(segment
		(start 46.594268 -226.034854)
		(end 46.594268 -225.970084)
		(width 0.14478)
		(layer "In2.Cu")
		(net "M_C_CPU1_SA_DQ<24>")
	)
	(segment
		(start 60.636658 -224.960434)
		(end 61.41847 -225.742246)
		(width 0.14478)
		(layer "In2.Cu")
		(net "M_C_CPU1_SA_DQ<24>")
	)
	(segment
		(start 53.952648 -225.810318)
		(end 56.230774 -225.810318)
		(width 0.14478)
		(layer "In2.Cu")
		(net "M_C_CPU1_SA_DQ<24>")
	)
	(segment
		(start 76.644246 -238.634524)
		(end 77.282802 -238.634524)
		(width 0.0889)
		(layer "In2.Cu")
		(net "M_C_CPU1_SA_DQ<24>")
	)
	(segment
		(start 45.644308 -225.550984)
		(end 45.874686 -225.550984)
		(width 0.14478)
		(layer "In2.Cu")
		(net "M_C_CPU1_SA_DQ<24>")
	)
	(segment
		(start 83.394042 -239.946942)
		(end 83.402424 -239.951768)
		(width 0.0889)
		(layer "In2.Cu")
		(net "M_C_CPU1_SA_DQ<24>")
	)
	(segment
		(start 90.339672 -239.951768)
		(end 90.348054 -239.946942)
		(width 0.0889)
		(layer "In2.Cu")
		(net "M_C_CPU1_SA_DQ<24>")
	)
	(segment
		(start 82.453988 -239.946942)
		(end 82.46237 -239.951768)
		(width 0.0889)
		(layer "In2.Cu")
		(net "M_C_CPU1_SA_DQ<24>")
	)
	(segment
		(start 61.603128 -226.318064)
		(end 62.015878 -226.318064)
		(width 0.14478)
		(layer "In2.Cu")
		(net "M_C_CPU1_SA_DQ<24>")
	)
	(segment
		(start 77.282802 -238.634524)
		(end 78.357222 -239.708944)
		(width 0.0889)
		(layer "In2.Cu")
		(net "M_C_CPU1_SA_DQ<24>")
	)
	(segment
		(start 56.55691 -226.193604)
		(end 56.787288 -226.193604)
		(width 0.14478)
		(layer "In2.Cu")
		(net "M_C_CPU1_SA_DQ<24>")
	)
	(segment
		(start 73.233026 -238.098584)
		(end 75.958446 -238.098584)
		(width 0.14478)
		(layer "In2.Cu")
		(net "M_C_CPU1_SA_DQ<24>")
	)
	(segment
		(start 90.913966 -239.946942)
		(end 90.922348 -239.951768)
		(width 0.0889)
		(layer "In2.Cu")
		(net "M_C_CPU1_SA_DQ<24>")
	)
	(segment
		(start 91.85402 -239.946942)
		(end 91.862402 -239.951768)
		(width 0.0889)
		(layer "In2.Cu")
		(net "M_C_CPU1_SA_DQ<24>")
	)
	(segment
		(start 53.102764 -224.960434)
		(end 53.952648 -225.810318)
		(width 0.14478)
		(layer "In2.Cu")
		(net "M_C_CPU1_SA_DQ<24>")
	)
	(segment
		(start 46.754034 -225.810318)
		(end 48.610266 -225.810318)
		(width 0.14478)
		(layer "In2.Cu")
		(net "M_C_CPU1_SA_DQ<24>")
	)
	(segment
		(start 79.98206 -239.962182)
		(end 80.008222 -239.946942)
		(width 0.0889)
		(layer "In2.Cu")
		(net "M_C_CPU1_SA_DQ<24>")
	)
	(segment
		(start 86.57971 -239.951768)
		(end 86.588092 -239.946942)
		(width 0.0889)
		(layer "In2.Cu")
		(net "M_C_CPU1_SA_DQ<24>")
	)
	(segment
		(start 62.40145 -225.309684)
		(end 62.673992 -225.309684)
		(width 0.14478)
		(layer "In2.Cu")
		(net "M_C_CPU1_SA_DQ<24>")
	)
	(segment
		(start 45.48124 -225.714052)
		(end 45.644308 -225.550984)
		(width 0.14478)
		(layer "In2.Cu")
		(net "M_C_CPU1_SA_DQ<24>")
	)
	(segment
		(start 62.673992 -225.309684)
		(end 62.866778 -225.50247)
		(width 0.14478)
		(layer "In2.Cu")
		(net "M_C_CPU1_SA_DQ<24>")
	)
	(segment
		(start 45.087794 -226.197922)
		(end 45.318172 -226.197922)
		(width 0.14478)
		(layer "In2.Cu")
		(net "M_C_CPU1_SA_DQ<24>")
	)
	(segment
		(start 46.037754 -225.714052)
		(end 46.037754 -226.034854)
		(width 0.14478)
		(layer "In2.Cu")
		(net "M_C_CPU1_SA_DQ<24>")
	)
	(segment
		(start 45.48124 -226.034854)
		(end 45.48124 -225.714052)
		(width 0.14478)
		(layer "In2.Cu")
		(net "M_C_CPU1_SA_DQ<24>")
	)
	(segment
		(start 56.787288 -226.193604)
		(end 56.950356 -226.030536)
		(width 0.14478)
		(layer "In2.Cu")
		(net "M_C_CPU1_SA_DQ<24>")
	)
	(segment
		(start 79.063088 -239.946942)
		(end 79.094838 -239.9284)
		(width 0.0889)
		(layer "In2.Cu")
		(net "M_C_CPU1_SA_DQ<24>")
	)
	(segment
		(start 62.866778 -225.50247)
		(end 62.866778 -226.125278)
		(width 0.14478)
		(layer "In2.Cu")
		(net "M_C_CPU1_SA_DQ<24>")
	)
	(segment
		(start 62.866778 -226.125278)
		(end 63.059564 -226.318064)
		(width 0.14478)
		(layer "In2.Cu")
		(net "M_C_CPU1_SA_DQ<24>")
	)
	(segment
		(start 45.874686 -225.550984)
		(end 46.037754 -225.714052)
		(width 0.14478)
		(layer "In2.Cu")
		(net "M_C_CPU1_SA_DQ<24>")
	)
	(segment
		(start 75.958446 -238.098584)
		(end 76.108306 -238.098584)
		(width 0.0889)
		(layer "In2.Cu")
		(net "M_C_CPU1_SA_DQ<24>")
	)
	(segment
		(start 49.329848 -225.973386)
		(end 49.492916 -225.810318)
		(width 0.14478)
		(layer "In2.Cu")
		(net "M_C_CPU1_SA_DQ<24>")
	)
	(segment
		(start 49.329848 -226.022916)
		(end 49.329848 -225.973386)
		(width 0.14478)
		(layer "In2.Cu")
		(net "M_C_CPU1_SA_DQ<24>")
	)
	(segment
		(start 62.208664 -226.125278)
		(end 62.208664 -225.50247)
		(width 0.14478)
		(layer "In2.Cu")
		(net "M_C_CPU1_SA_DQ<24>")
	)
	(segment
		(start 66.575686 -229.195884)
		(end 66.575686 -231.441244)
		(width 0.14478)
		(layer "In2.Cu")
		(net "M_C_CPU1_SA_DQ<24>")
	)
	(segment
		(start 48.773334 -226.022916)
		(end 48.936402 -226.185984)
		(width 0.14478)
		(layer "In2.Cu")
		(net "M_C_CPU1_SA_DQ<24>")
	)
	(segment
		(start 46.200822 -226.197922)
		(end 46.4312 -226.197922)
		(width 0.14478)
		(layer "In2.Cu")
		(net "M_C_CPU1_SA_DQ<24>")
	)
	(segment
		(start 44.340018 -225.385376)
		(end 44.924726 -225.970084)
		(width 0.14478)
		(layer "In2.Cu")
		(net "M_C_CPU1_SA_DQ<24>")
	)
	(segment
		(start 58.187336 -224.960434)
		(end 60.636658 -224.960434)
		(width 0.14478)
		(layer "In2.Cu")
		(net "M_C_CPU1_SA_DQ<24>")
	)
	(segment
		(start 57.337452 -225.810318)
		(end 58.187336 -224.960434)
		(width 0.14478)
		(layer "In2.Cu")
		(net "M_C_CPU1_SA_DQ<24>")
	)
	(segment
		(start 44.924726 -225.970084)
		(end 44.924726 -226.034854)
		(width 0.14478)
		(layer "In2.Cu")
		(net "M_C_CPU1_SA_DQ<24>")
	)
	(arc
		(start 84.334096 -239.946942)
		(mid 84.52104 -239.997197)
		(end 84.707984 -239.946942)
		(width 0.0889)
		(layer "In2.Cu")
		(net "M_C_CPU1_SA_DQ<24>")
	)
	(arc
		(start 88.10244 -239.951768)
		(mid 88.285948 -239.997262)
		(end 88.4682 -239.946942)
		(width 0.0889)
		(layer "In2.Cu")
		(net "M_C_CPU1_SA_DQ<24>")
	)
	(arc
		(start 93.733874 -239.946942)
		(mid 93.890312 -239.995913)
		(end 94.052644 -239.973104)
		(width 0.0889)
		(layer "In2.Cu")
		(net "M_C_CPU1_SA_DQ<24>")
	)
	(arc
		(start 85.273896 -239.946942)
		(mid 85.456147 -239.997292)
		(end 85.639656 -239.951768)
		(width 0.0889)
		(layer "In2.Cu")
		(net "M_C_CPU1_SA_DQ<24>")
	)
	(arc
		(start 90.922348 -239.951768)
		(mid 91.105856 -239.997262)
		(end 91.288108 -239.946942)
		(width 0.0889)
		(layer "In2.Cu")
		(net "M_C_CPU1_SA_DQ<24>")
	)
	(arc
		(start 88.4682 -239.946942)
		(mid 88.751156 -239.870765)
		(end 89.034112 -239.946942)
		(width 0.0889)
		(layer "In2.Cu")
		(net "M_C_CPU1_SA_DQ<24>")
	)
	(arc
		(start 79.094838 -239.9284)
		(mid 79.365709 -239.869814)
		(end 79.631794 -239.947196)
		(width 0.0889)
		(layer "In2.Cu")
		(net "M_C_CPU1_SA_DQ<24>")
	)
	(arc
		(start 91.862402 -239.951768)
		(mid 92.04591 -239.997262)
		(end 92.228162 -239.946942)
		(width 0.0889)
		(layer "In2.Cu")
		(net "M_C_CPU1_SA_DQ<24>")
	)
	(arc
		(start 80.574134 -239.946942)
		(mid 80.761078 -239.997197)
		(end 80.948022 -239.946942)
		(width 0.0889)
		(layer "In2.Cu")
		(net "M_C_CPU1_SA_DQ<24>")
	)
	(arc
		(start 81.513934 -239.946942)
		(mid 81.696185 -239.997292)
		(end 81.879694 -239.951768)
		(width 0.0889)
		(layer "In2.Cu")
		(net "M_C_CPU1_SA_DQ<24>")
	)
	(arc
		(start 92.228162 -239.946942)
		(mid 92.511118 -239.870765)
		(end 92.794074 -239.946942)
		(width 0.0889)
		(layer "In2.Cu")
		(net "M_C_CPU1_SA_DQ<24>")
	)
	(arc
		(start 91.288108 -239.946942)
		(mid 91.571064 -239.870765)
		(end 91.85402 -239.946942)
		(width 0.0889)
		(layer "In2.Cu")
		(net "M_C_CPU1_SA_DQ<24>")
	)
	(arc
		(start 80.948022 -239.946942)
		(mid 81.230978 -239.870765)
		(end 81.513934 -239.946942)
		(width 0.0889)
		(layer "In2.Cu")
		(net "M_C_CPU1_SA_DQ<24>")
	)
	(arc
		(start 86.588092 -239.946942)
		(mid 86.871048 -239.870765)
		(end 87.154004 -239.946942)
		(width 0.0889)
		(layer "In2.Cu")
		(net "M_C_CPU1_SA_DQ<24>")
	)
	(arc
		(start 93.167962 -239.946942)
		(mid 93.450918 -239.870765)
		(end 93.733874 -239.946942)
		(width 0.0889)
		(layer "In2.Cu")
		(net "M_C_CPU1_SA_DQ<24>")
	)
	(arc
		(start 81.888076 -239.946942)
		(mid 82.171032 -239.870765)
		(end 82.453988 -239.946942)
		(width 0.0889)
		(layer "In2.Cu")
		(net "M_C_CPU1_SA_DQ<24>")
	)
	(arc
		(start 86.21395 -239.946942)
		(mid 86.396201 -239.997292)
		(end 86.57971 -239.951768)
		(width 0.0889)
		(layer "In2.Cu")
		(net "M_C_CPU1_SA_DQ<24>")
	)
	(arc
		(start 83.768184 -239.946942)
		(mid 84.05114 -239.870765)
		(end 84.334096 -239.946942)
		(width 0.0889)
		(layer "In2.Cu")
		(net "M_C_CPU1_SA_DQ<24>")
	)
	(arc
		(start 82.46237 -239.951768)
		(mid 82.645878 -239.997262)
		(end 82.82813 -239.946942)
		(width 0.0889)
		(layer "In2.Cu")
		(net "M_C_CPU1_SA_DQ<24>")
	)
	(arc
		(start 85.648038 -239.946942)
		(mid 85.930994 -239.870765)
		(end 86.21395 -239.946942)
		(width 0.0889)
		(layer "In2.Cu")
		(net "M_C_CPU1_SA_DQ<24>")
	)
	(arc
		(start 80.008222 -239.946942)
		(mid 80.291178 -239.870765)
		(end 80.574134 -239.946942)
		(width 0.0889)
		(layer "In2.Cu")
		(net "M_C_CPU1_SA_DQ<24>")
	)
	(arc
		(start 84.707984 -239.946942)
		(mid 84.99094 -239.870765)
		(end 85.273896 -239.946942)
		(width 0.0889)
		(layer "In2.Cu")
		(net "M_C_CPU1_SA_DQ<24>")
	)
	(arc
		(start 87.162386 -239.951768)
		(mid 87.345894 -239.997262)
		(end 87.528146 -239.946942)
		(width 0.0889)
		(layer "In2.Cu")
		(net "M_C_CPU1_SA_DQ<24>")
	)
	(arc
		(start 89.408 -239.946942)
		(mid 89.690956 -239.870765)
		(end 89.973912 -239.946942)
		(width 0.0889)
		(layer "In2.Cu")
		(net "M_C_CPU1_SA_DQ<24>")
	)
	(arc
		(start 92.794074 -239.946942)
		(mid 92.981018 -239.997197)
		(end 93.167962 -239.946942)
		(width 0.0889)
		(layer "In2.Cu")
		(net "M_C_CPU1_SA_DQ<24>")
	)
	(arc
		(start 78.71841 -239.962436)
		(mid 78.892647 -239.996938)
		(end 79.063088 -239.946942)
		(width 0.0889)
		(layer "In2.Cu")
		(net "M_C_CPU1_SA_DQ<24>")
	)
	(arc
		(start 90.348054 -239.946942)
		(mid 90.63101 -239.870765)
		(end 90.913966 -239.946942)
		(width 0.0889)
		(layer "In2.Cu")
		(net "M_C_CPU1_SA_DQ<24>")
	)
	(arc
		(start 82.82813 -239.946942)
		(mid 83.111086 -239.870765)
		(end 83.394042 -239.946942)
		(width 0.0889)
		(layer "In2.Cu")
		(net "M_C_CPU1_SA_DQ<24>")
	)
	(arc
		(start 89.973912 -239.946942)
		(mid 90.156163 -239.997292)
		(end 90.339672 -239.951768)
		(width 0.0889)
		(layer "In2.Cu")
		(net "M_C_CPU1_SA_DQ<24>")
	)
	(arc
		(start 83.402424 -239.951768)
		(mid 83.585932 -239.997262)
		(end 83.768184 -239.946942)
		(width 0.0889)
		(layer "In2.Cu")
		(net "M_C_CPU1_SA_DQ<24>")
	)
	(arc
		(start 89.034112 -239.946942)
		(mid 89.221056 -239.997197)
		(end 89.408 -239.946942)
		(width 0.0889)
		(layer "In2.Cu")
		(net "M_C_CPU1_SA_DQ<24>")
	)
	(arc
		(start 87.528146 -239.946942)
		(mid 87.811102 -239.870765)
		(end 88.094058 -239.946942)
		(width 0.0889)
		(layer "In2.Cu")
		(net "M_C_CPU1_SA_DQ<24>")
	)
	(arc
		(start 79.631794 -239.947196)
		(mid 79.80506 -239.998227)
		(end 79.98206 -239.962182)
		(width 0.0889)
		(layer "In2.Cu")
		(net "M_C_CPU1_SA_DQ<24>")
	)
	(segment
		(start 96.267778 -239.8903)
		(end 95.800926 -239.624362)
		(width 0.10668)
		(layer "F.Cu")
		(net "M_C_CPU1_SA_DQ<23>")
	)
	(segment
		(start 73.47204 -237.539784)
		(end 75.966066 -237.539784)
		(width 0.14478)
		(layer "In2.Cu")
		(net "M_C_CPU1_SA_DQ<23>")
	)
	(segment
		(start 90.913966 -239.301782)
		(end 90.922348 -239.296956)
		(width 0.0889)
		(layer "In2.Cu")
		(net "M_C_CPU1_SA_DQ<23>")
	)
	(segment
		(start 75.966066 -237.539784)
		(end 76.606146 -237.539784)
		(width 0.0889)
		(layer "In2.Cu")
		(net "M_C_CPU1_SA_DQ<23>")
	)
	(segment
		(start 67.14617 -228.958648)
		(end 67.14617 -231.213914)
		(width 0.14478)
		(layer "In2.Cu")
		(net "M_C_CPU1_SA_DQ<23>")
	)
	(segment
		(start 82.453988 -239.301782)
		(end 82.46237 -239.296956)
		(width 0.0889)
		(layer "In2.Cu")
		(net "M_C_CPU1_SA_DQ<23>")
	)
	(segment
		(start 95.55099 -239.333532)
		(end 95.647002 -239.358932)
		(width 0.0889)
		(layer "In2.Cu")
		(net "M_C_CPU1_SA_DQ<23>")
	)
	(segment
		(start 85.639656 -239.296956)
		(end 85.648038 -239.301782)
		(width 0.0889)
		(layer "In2.Cu")
		(net "M_C_CPU1_SA_DQ<23>")
	)
	(segment
		(start 49.428146 -224.960434)
		(end 50.278284 -224.110296)
		(width 0.14478)
		(layer "In2.Cu")
		(net "M_C_CPU1_SA_DQ<23>")
	)
	(segment
		(start 60.582302 -224.110296)
		(end 61.21019 -224.738184)
		(width 0.14478)
		(layer "In2.Cu")
		(net "M_C_CPU1_SA_DQ<23>")
	)
	(segment
		(start 62.925706 -224.738184)
		(end 67.14617 -228.958648)
		(width 0.14478)
		(layer "In2.Cu")
		(net "M_C_CPU1_SA_DQ<23>")
	)
	(segment
		(start 42.638726 -224.797366)
		(end 42.801794 -224.960434)
		(width 0.14478)
		(layer "In2.Cu")
		(net "M_C_CPU1_SA_DQ<23>")
	)
	(segment
		(start 76.606146 -237.539784)
		(end 78.368906 -239.302544)
		(width 0.0889)
		(layer "In2.Cu")
		(net "M_C_CPU1_SA_DQ<23>")
	)
	(segment
		(start 41.919144 -224.960434)
		(end 42.082212 -224.797366)
		(width 0.14478)
		(layer "In2.Cu")
		(net "M_C_CPU1_SA_DQ<23>")
	)
	(segment
		(start 87.154004 -239.301782)
		(end 87.162386 -239.296956)
		(width 0.0889)
		(layer "In2.Cu")
		(net "M_C_CPU1_SA_DQ<23>")
	)
	(segment
		(start 67.14617 -231.213914)
		(end 73.47204 -237.539784)
		(width 0.14478)
		(layer "In2.Cu")
		(net "M_C_CPU1_SA_DQ<23>")
	)
	(segment
		(start 91.85402 -239.301782)
		(end 91.862402 -239.296956)
		(width 0.0889)
		(layer "In2.Cu")
		(net "M_C_CPU1_SA_DQ<23>")
	)
	(segment
		(start 78.368906 -239.302544)
		(end 79.634842 -239.302544)
		(width 0.0889)
		(layer "In2.Cu")
		(net "M_C_CPU1_SA_DQ<23>")
	)
	(segment
		(start 40.665146 -224.960434)
		(end 41.919144 -224.960434)
		(width 0.14478)
		(layer "In2.Cu")
		(net "M_C_CPU1_SA_DQ<23>")
	)
	(segment
		(start 79.63535 -239.302036)
		(end 79.658718 -239.288574)
		(width 0.0889)
		(layer "In2.Cu")
		(net "M_C_CPU1_SA_DQ<23>")
	)
	(segment
		(start 42.082212 -224.797366)
		(end 42.082212 -224.564194)
		(width 0.14478)
		(layer "In2.Cu")
		(net "M_C_CPU1_SA_DQ<23>")
	)
	(segment
		(start 42.638726 -224.564194)
		(end 42.638726 -224.797366)
		(width 0.14478)
		(layer "In2.Cu")
		(net "M_C_CPU1_SA_DQ<23>")
	)
	(segment
		(start 53.961792 -224.960434)
		(end 56.91632 -224.960434)
		(width 0.14478)
		(layer "In2.Cu")
		(net "M_C_CPU1_SA_DQ<23>")
	)
	(segment
		(start 53.111654 -224.110296)
		(end 53.961792 -224.960434)
		(width 0.14478)
		(layer "In2.Cu")
		(net "M_C_CPU1_SA_DQ<23>")
	)
	(segment
		(start 88.094058 -239.301782)
		(end 88.10244 -239.296956)
		(width 0.0889)
		(layer "In2.Cu")
		(net "M_C_CPU1_SA_DQ<23>")
	)
	(segment
		(start 42.24528 -224.401126)
		(end 42.475658 -224.401126)
		(width 0.14478)
		(layer "In2.Cu")
		(net "M_C_CPU1_SA_DQ<23>")
	)
	(segment
		(start 56.91632 -224.960434)
		(end 57.766458 -224.110296)
		(width 0.14478)
		(layer "In2.Cu")
		(net "M_C_CPU1_SA_DQ<23>")
	)
	(segment
		(start 79.634842 -239.302544)
		(end 79.63535 -239.302036)
		(width 0.0889)
		(layer "In2.Cu")
		(net "M_C_CPU1_SA_DQ<23>")
	)
	(segment
		(start 94.099634 -239.296956)
		(end 94.108016 -239.301782)
		(width 0.0889)
		(layer "In2.Cu")
		(net "M_C_CPU1_SA_DQ<23>")
	)
	(segment
		(start 42.801794 -224.960434)
		(end 49.428146 -224.960434)
		(width 0.14478)
		(layer "In2.Cu")
		(net "M_C_CPU1_SA_DQ<23>")
	)
	(segment
		(start 40.23995 -224.535238)
		(end 40.665146 -224.960434)
		(width 0.14478)
		(layer "In2.Cu")
		(net "M_C_CPU1_SA_DQ<23>")
	)
	(segment
		(start 61.21019 -224.738184)
		(end 62.925706 -224.738184)
		(width 0.14478)
		(layer "In2.Cu")
		(net "M_C_CPU1_SA_DQ<23>")
	)
	(segment
		(start 83.394042 -239.301782)
		(end 83.402424 -239.296956)
		(width 0.0889)
		(layer "In2.Cu")
		(net "M_C_CPU1_SA_DQ<23>")
	)
	(segment
		(start 95.647002 -239.358932)
		(end 95.800926 -239.624362)
		(width 0.0889)
		(layer "In2.Cu")
		(net "M_C_CPU1_SA_DQ<23>")
	)
	(segment
		(start 42.475658 -224.401126)
		(end 42.638726 -224.564194)
		(width 0.14478)
		(layer "In2.Cu")
		(net "M_C_CPU1_SA_DQ<23>")
	)
	(segment
		(start 90.339672 -239.296956)
		(end 90.348054 -239.301782)
		(width 0.0889)
		(layer "In2.Cu")
		(net "M_C_CPU1_SA_DQ<23>")
	)
	(segment
		(start 95.039688 -239.296956)
		(end 95.04807 -239.301782)
		(width 0.0889)
		(layer "In2.Cu")
		(net "M_C_CPU1_SA_DQ<23>")
	)
	(segment
		(start 50.278284 -224.110296)
		(end 53.111654 -224.110296)
		(width 0.14478)
		(layer "In2.Cu")
		(net "M_C_CPU1_SA_DQ<23>")
	)
	(segment
		(start 86.57971 -239.296956)
		(end 86.588092 -239.301782)
		(width 0.0889)
		(layer "In2.Cu")
		(net "M_C_CPU1_SA_DQ<23>")
	)
	(segment
		(start 42.082212 -224.564194)
		(end 42.24528 -224.401126)
		(width 0.14478)
		(layer "In2.Cu")
		(net "M_C_CPU1_SA_DQ<23>")
	)
	(segment
		(start 81.879694 -239.296956)
		(end 81.888076 -239.301782)
		(width 0.0889)
		(layer "In2.Cu")
		(net "M_C_CPU1_SA_DQ<23>")
	)
	(segment
		(start 57.766458 -224.110296)
		(end 60.582302 -224.110296)
		(width 0.14478)
		(layer "In2.Cu")
		(net "M_C_CPU1_SA_DQ<23>")
	)
	(arc
		(start 79.658718 -239.288574)
		(mid 79.835113 -239.251671)
		(end 80.008222 -239.301782)
		(width 0.0889)
		(layer "In2.Cu")
		(net "M_C_CPU1_SA_DQ<23>")
	)
	(arc
		(start 83.768184 -239.301782)
		(mid 84.05114 -239.377959)
		(end 84.334096 -239.301782)
		(width 0.0889)
		(layer "In2.Cu")
		(net "M_C_CPU1_SA_DQ<23>")
	)
	(arc
		(start 87.162386 -239.296956)
		(mid 87.345894 -239.251462)
		(end 87.528146 -239.301782)
		(width 0.0889)
		(layer "In2.Cu")
		(net "M_C_CPU1_SA_DQ<23>")
	)
	(arc
		(start 81.513934 -239.301782)
		(mid 81.696185 -239.251432)
		(end 81.879694 -239.296956)
		(width 0.0889)
		(layer "In2.Cu")
		(net "M_C_CPU1_SA_DQ<23>")
	)
	(arc
		(start 82.82813 -239.301782)
		(mid 83.111086 -239.377959)
		(end 83.394042 -239.301782)
		(width 0.0889)
		(layer "In2.Cu")
		(net "M_C_CPU1_SA_DQ<23>")
	)
	(arc
		(start 89.034112 -239.301782)
		(mid 89.221056 -239.251527)
		(end 89.408 -239.301782)
		(width 0.0889)
		(layer "In2.Cu")
		(net "M_C_CPU1_SA_DQ<23>")
	)
	(arc
		(start 86.588092 -239.301782)
		(mid 86.871048 -239.377959)
		(end 87.154004 -239.301782)
		(width 0.0889)
		(layer "In2.Cu")
		(net "M_C_CPU1_SA_DQ<23>")
	)
	(arc
		(start 94.108016 -239.301782)
		(mid 94.390972 -239.377959)
		(end 94.673928 -239.301782)
		(width 0.0889)
		(layer "In2.Cu")
		(net "M_C_CPU1_SA_DQ<23>")
	)
	(arc
		(start 88.10244 -239.296956)
		(mid 88.285948 -239.251462)
		(end 88.4682 -239.301782)
		(width 0.0889)
		(layer "In2.Cu")
		(net "M_C_CPU1_SA_DQ<23>")
	)
	(arc
		(start 85.648038 -239.301782)
		(mid 85.930994 -239.377959)
		(end 86.21395 -239.301782)
		(width 0.0889)
		(layer "In2.Cu")
		(net "M_C_CPU1_SA_DQ<23>")
	)
	(arc
		(start 90.922348 -239.296956)
		(mid 91.105856 -239.251462)
		(end 91.288108 -239.301782)
		(width 0.0889)
		(layer "In2.Cu")
		(net "M_C_CPU1_SA_DQ<23>")
	)
	(arc
		(start 92.228162 -239.301782)
		(mid 92.511118 -239.377959)
		(end 92.794074 -239.301782)
		(width 0.0889)
		(layer "In2.Cu")
		(net "M_C_CPU1_SA_DQ<23>")
	)
	(arc
		(start 89.973912 -239.301782)
		(mid 90.156163 -239.251432)
		(end 90.339672 -239.296956)
		(width 0.0889)
		(layer "In2.Cu")
		(net "M_C_CPU1_SA_DQ<23>")
	)
	(arc
		(start 91.288108 -239.301782)
		(mid 91.571064 -239.377959)
		(end 91.85402 -239.301782)
		(width 0.0889)
		(layer "In2.Cu")
		(net "M_C_CPU1_SA_DQ<23>")
	)
	(arc
		(start 80.948022 -239.301782)
		(mid 81.230978 -239.377959)
		(end 81.513934 -239.301782)
		(width 0.0889)
		(layer "In2.Cu")
		(net "M_C_CPU1_SA_DQ<23>")
	)
	(arc
		(start 86.21395 -239.301782)
		(mid 86.396201 -239.251432)
		(end 86.57971 -239.296956)
		(width 0.0889)
		(layer "In2.Cu")
		(net "M_C_CPU1_SA_DQ<23>")
	)
	(arc
		(start 89.408 -239.301782)
		(mid 89.690956 -239.377959)
		(end 89.973912 -239.301782)
		(width 0.0889)
		(layer "In2.Cu")
		(net "M_C_CPU1_SA_DQ<23>")
	)
	(arc
		(start 88.4682 -239.301782)
		(mid 88.751156 -239.377959)
		(end 89.034112 -239.301782)
		(width 0.0889)
		(layer "In2.Cu")
		(net "M_C_CPU1_SA_DQ<23>")
	)
	(arc
		(start 91.862402 -239.296956)
		(mid 92.04591 -239.251462)
		(end 92.228162 -239.301782)
		(width 0.0889)
		(layer "In2.Cu")
		(net "M_C_CPU1_SA_DQ<23>")
	)
	(arc
		(start 85.273896 -239.301782)
		(mid 85.456147 -239.251432)
		(end 85.639656 -239.296956)
		(width 0.0889)
		(layer "In2.Cu")
		(net "M_C_CPU1_SA_DQ<23>")
	)
	(arc
		(start 93.733874 -239.301782)
		(mid 93.916125 -239.251432)
		(end 94.099634 -239.296956)
		(width 0.0889)
		(layer "In2.Cu")
		(net "M_C_CPU1_SA_DQ<23>")
	)
	(arc
		(start 80.574134 -239.301782)
		(mid 80.761078 -239.251527)
		(end 80.948022 -239.301782)
		(width 0.0889)
		(layer "In2.Cu")
		(net "M_C_CPU1_SA_DQ<23>")
	)
	(arc
		(start 92.794074 -239.301782)
		(mid 92.981018 -239.251527)
		(end 93.167962 -239.301782)
		(width 0.0889)
		(layer "In2.Cu")
		(net "M_C_CPU1_SA_DQ<23>")
	)
	(arc
		(start 94.673928 -239.301782)
		(mid 94.856179 -239.251432)
		(end 95.039688 -239.296956)
		(width 0.0889)
		(layer "In2.Cu")
		(net "M_C_CPU1_SA_DQ<23>")
	)
	(arc
		(start 84.707984 -239.301782)
		(mid 84.99094 -239.377959)
		(end 85.273896 -239.301782)
		(width 0.0889)
		(layer "In2.Cu")
		(net "M_C_CPU1_SA_DQ<23>")
	)
	(arc
		(start 84.334096 -239.301782)
		(mid 84.52104 -239.251527)
		(end 84.707984 -239.301782)
		(width 0.0889)
		(layer "In2.Cu")
		(net "M_C_CPU1_SA_DQ<23>")
	)
	(arc
		(start 83.402424 -239.296956)
		(mid 83.585932 -239.251462)
		(end 83.768184 -239.301782)
		(width 0.0889)
		(layer "In2.Cu")
		(net "M_C_CPU1_SA_DQ<23>")
	)
	(arc
		(start 93.167962 -239.301782)
		(mid 93.450918 -239.377959)
		(end 93.733874 -239.301782)
		(width 0.0889)
		(layer "In2.Cu")
		(net "M_C_CPU1_SA_DQ<23>")
	)
	(arc
		(start 81.888076 -239.301782)
		(mid 82.171032 -239.377959)
		(end 82.453988 -239.301782)
		(width 0.0889)
		(layer "In2.Cu")
		(net "M_C_CPU1_SA_DQ<23>")
	)
	(arc
		(start 82.46237 -239.296956)
		(mid 82.645878 -239.251462)
		(end 82.82813 -239.301782)
		(width 0.0889)
		(layer "In2.Cu")
		(net "M_C_CPU1_SA_DQ<23>")
	)
	(arc
		(start 80.008222 -239.301782)
		(mid 80.291178 -239.377959)
		(end 80.574134 -239.301782)
		(width 0.0889)
		(layer "In2.Cu")
		(net "M_C_CPU1_SA_DQ<23>")
	)
	(arc
		(start 87.528146 -239.301782)
		(mid 87.811102 -239.377959)
		(end 88.094058 -239.301782)
		(width 0.0889)
		(layer "In2.Cu")
		(net "M_C_CPU1_SA_DQ<23>")
	)
	(arc
		(start 95.04807 -239.301782)
		(mid 95.295783 -239.377002)
		(end 95.55099 -239.333532)
		(width 0.0889)
		(layer "In2.Cu")
		(net "M_C_CPU1_SA_DQ<23>")
	)
	(arc
		(start 90.348054 -239.301782)
		(mid 90.63101 -239.377959)
		(end 90.913966 -239.301782)
		(width 0.0889)
		(layer "In2.Cu")
		(net "M_C_CPU1_SA_DQ<23>")
	)
	(segment
		(start 94.857824 -239.080294)
		(end 94.390972 -238.814356)
		(width 0.10668)
		(layer "F.Cu")
		(net "M_C_CPU1_SA_DQ<22>")
	)
	(segment
		(start 42.523664 -222.257366)
		(end 42.754042 -222.257366)
		(width 0.14478)
		(layer "In2.Cu")
		(net "M_C_CPU1_SA_DQ<22>")
	)
	(segment
		(start 94.141036 -238.523526)
		(end 94.237048 -238.548926)
		(width 0.0889)
		(layer "In2.Cu")
		(net "M_C_CPU1_SA_DQ<22>")
	)
	(segment
		(start 61.08827 -222.772478)
		(end 61.08827 -223.299782)
		(width 0.14478)
		(layer "In2.Cu")
		(net "M_C_CPU1_SA_DQ<22>")
	)
	(segment
		(start 80.46974 -238.48695)
		(end 80.478122 -238.491776)
		(width 0.0889)
		(layer "In2.Cu")
		(net "M_C_CPU1_SA_DQ<22>")
	)
	(segment
		(start 42.197528 -223.260412)
		(end 42.360596 -223.097344)
		(width 0.14478)
		(layer "In2.Cu")
		(net "M_C_CPU1_SA_DQ<22>")
	)
	(segment
		(start 56.91632 -223.260412)
		(end 57.766458 -222.410274)
		(width 0.14478)
		(layer "In2.Cu")
		(net "M_C_CPU1_SA_DQ<22>")
	)
	(segment
		(start 88.929718 -238.48695)
		(end 88.9381 -238.491776)
		(width 0.0889)
		(layer "In2.Cu")
		(net "M_C_CPU1_SA_DQ<22>")
	)
	(segment
		(start 42.754042 -222.257366)
		(end 42.91711 -222.420434)
		(width 0.14478)
		(layer "In2.Cu")
		(net "M_C_CPU1_SA_DQ<22>")
	)
	(segment
		(start 49.428146 -223.260412)
		(end 50.278284 -222.410274)
		(width 0.14478)
		(layer "In2.Cu")
		(net "M_C_CPU1_SA_DQ<22>")
	)
	(segment
		(start 68.067428 -230.817166)
		(end 73.870566 -236.620304)
		(width 0.14478)
		(layer "In2.Cu")
		(net "M_C_CPU1_SA_DQ<22>")
	)
	(segment
		(start 50.278284 -222.410274)
		(end 53.111654 -222.410274)
		(width 0.14478)
		(layer "In2.Cu")
		(net "M_C_CPU1_SA_DQ<22>")
	)
	(segment
		(start 60.726066 -222.410274)
		(end 61.08827 -222.772478)
		(width 0.14478)
		(layer "In2.Cu")
		(net "M_C_CPU1_SA_DQ<22>")
	)
	(segment
		(start 43.080178 -223.260412)
		(end 49.428146 -223.260412)
		(width 0.14478)
		(layer "In2.Cu")
		(net "M_C_CPU1_SA_DQ<22>")
	)
	(segment
		(start 89.504012 -238.491776)
		(end 89.512394 -238.48695)
		(width 0.0889)
		(layer "In2.Cu")
		(net "M_C_CPU1_SA_DQ<22>")
	)
	(segment
		(start 78.229206 -238.205264)
		(end 78.673706 -238.205264)
		(width 0.0889)
		(layer "In2.Cu")
		(net "M_C_CPU1_SA_DQ<22>")
	)
	(segment
		(start 53.111654 -222.410274)
		(end 53.961792 -223.260412)
		(width 0.14478)
		(layer "In2.Cu")
		(net "M_C_CPU1_SA_DQ<22>")
	)
	(segment
		(start 42.360596 -223.097344)
		(end 42.360596 -222.420434)
		(width 0.14478)
		(layer "In2.Cu")
		(net "M_C_CPU1_SA_DQ<22>")
	)
	(segment
		(start 61.614812 -223.826324)
		(end 63.316866 -223.826324)
		(width 0.14478)
		(layer "In2.Cu")
		(net "M_C_CPU1_SA_DQ<22>")
	)
	(segment
		(start 79.036418 -238.567976)
		(end 79.821024 -238.567976)
		(width 0.0889)
		(layer "In2.Cu")
		(net "M_C_CPU1_SA_DQ<22>")
	)
	(segment
		(start 91.749626 -238.48695)
		(end 91.758008 -238.491776)
		(width 0.0889)
		(layer "In2.Cu")
		(net "M_C_CPU1_SA_DQ<22>")
	)
	(segment
		(start 76.669646 -237.019084)
		(end 77.043026 -237.019084)
		(width 0.0889)
		(layer "In2.Cu")
		(net "M_C_CPU1_SA_DQ<22>")
	)
	(segment
		(start 57.766458 -222.410274)
		(end 60.726066 -222.410274)
		(width 0.14478)
		(layer "In2.Cu")
		(net "M_C_CPU1_SA_DQ<22>")
	)
	(segment
		(start 93.263974 -238.491776)
		(end 93.272356 -238.48695)
		(width 0.0889)
		(layer "In2.Cu")
		(net "M_C_CPU1_SA_DQ<22>")
	)
	(segment
		(start 53.961792 -223.260412)
		(end 56.91632 -223.260412)
		(width 0.14478)
		(layer "In2.Cu")
		(net "M_C_CPU1_SA_DQ<22>")
	)
	(segment
		(start 77.043026 -237.019084)
		(end 78.229206 -238.205264)
		(width 0.0889)
		(layer "In2.Cu")
		(net "M_C_CPU1_SA_DQ<22>")
	)
	(segment
		(start 85.74405 -238.491776)
		(end 85.752432 -238.48695)
		(width 0.0889)
		(layer "In2.Cu")
		(net "M_C_CPU1_SA_DQ<22>")
	)
	(segment
		(start 83.289648 -238.48695)
		(end 83.29803 -238.491776)
		(width 0.0889)
		(layer "In2.Cu")
		(net "M_C_CPU1_SA_DQ<22>")
	)
	(segment
		(start 84.803996 -238.491776)
		(end 84.812378 -238.48695)
		(width 0.0889)
		(layer "In2.Cu")
		(net "M_C_CPU1_SA_DQ<22>")
	)
	(segment
		(start 81.044034 -238.491776)
		(end 81.052416 -238.48695)
		(width 0.0889)
		(layer "In2.Cu")
		(net "M_C_CPU1_SA_DQ<22>")
	)
	(segment
		(start 61.08827 -223.299782)
		(end 61.614812 -223.826324)
		(width 0.14478)
		(layer "In2.Cu")
		(net "M_C_CPU1_SA_DQ<22>")
	)
	(segment
		(start 42.91711 -222.420434)
		(end 42.91711 -223.097344)
		(width 0.14478)
		(layer "In2.Cu")
		(net "M_C_CPU1_SA_DQ<22>")
	)
	(segment
		(start 40.665146 -223.260412)
		(end 42.197528 -223.260412)
		(width 0.14478)
		(layer "In2.Cu")
		(net "M_C_CPU1_SA_DQ<22>")
	)
	(segment
		(start 78.673706 -238.205264)
		(end 79.036418 -238.567976)
		(width 0.0889)
		(layer "In2.Cu")
		(net "M_C_CPU1_SA_DQ<22>")
	)
	(segment
		(start 84.229702 -238.48695)
		(end 84.238084 -238.491776)
		(width 0.0889)
		(layer "In2.Cu")
		(net "M_C_CPU1_SA_DQ<22>")
	)
	(segment
		(start 94.237048 -238.548926)
		(end 94.390972 -238.814356)
		(width 0.0889)
		(layer "In2.Cu")
		(net "M_C_CPU1_SA_DQ<22>")
	)
	(segment
		(start 42.91711 -223.097344)
		(end 43.080178 -223.260412)
		(width 0.14478)
		(layer "In2.Cu")
		(net "M_C_CPU1_SA_DQ<22>")
	)
	(segment
		(start 68.067428 -228.576886)
		(end 68.067428 -230.817166)
		(width 0.14478)
		(layer "In2.Cu")
		(net "M_C_CPU1_SA_DQ<22>")
	)
	(segment
		(start 75.945746 -236.620304)
		(end 76.270866 -236.620304)
		(width 0.0889)
		(layer "In2.Cu")
		(net "M_C_CPU1_SA_DQ<22>")
	)
	(segment
		(start 63.316866 -223.826324)
		(end 68.067428 -228.576886)
		(width 0.14478)
		(layer "In2.Cu")
		(net "M_C_CPU1_SA_DQ<22>")
	)
	(segment
		(start 76.270866 -236.620304)
		(end 76.669646 -237.019084)
		(width 0.0889)
		(layer "In2.Cu")
		(net "M_C_CPU1_SA_DQ<22>")
	)
	(segment
		(start 40.23995 -222.835216)
		(end 40.665146 -223.260412)
		(width 0.14478)
		(layer "In2.Cu")
		(net "M_C_CPU1_SA_DQ<22>")
	)
	(segment
		(start 92.68968 -238.48695)
		(end 92.698062 -238.491776)
		(width 0.0889)
		(layer "In2.Cu")
		(net "M_C_CPU1_SA_DQ<22>")
	)
	(segment
		(start 73.870566 -236.620304)
		(end 75.945746 -236.620304)
		(width 0.14478)
		(layer "In2.Cu")
		(net "M_C_CPU1_SA_DQ<22>")
	)
	(segment
		(start 42.360596 -222.420434)
		(end 42.523664 -222.257366)
		(width 0.14478)
		(layer "In2.Cu")
		(net "M_C_CPU1_SA_DQ<22>")
	)
	(segment
		(start 87.989664 -238.48695)
		(end 87.998046 -238.491776)
		(width 0.0889)
		(layer "In2.Cu")
		(net "M_C_CPU1_SA_DQ<22>")
	)
	(arc
		(start 88.9381 -238.491776)
		(mid 89.221056 -238.567953)
		(end 89.504012 -238.491776)
		(width 0.0889)
		(layer "In2.Cu")
		(net "M_C_CPU1_SA_DQ<22>")
	)
	(arc
		(start 84.238084 -238.491776)
		(mid 84.52104 -238.567953)
		(end 84.803996 -238.491776)
		(width 0.0889)
		(layer "In2.Cu")
		(net "M_C_CPU1_SA_DQ<22>")
	)
	(arc
		(start 84.812378 -238.48695)
		(mid 84.995886 -238.441456)
		(end 85.178138 -238.491776)
		(width 0.0889)
		(layer "In2.Cu")
		(net "M_C_CPU1_SA_DQ<22>")
	)
	(arc
		(start 88.563958 -238.491776)
		(mid 88.746209 -238.441426)
		(end 88.929718 -238.48695)
		(width 0.0889)
		(layer "In2.Cu")
		(net "M_C_CPU1_SA_DQ<22>")
	)
	(arc
		(start 87.057992 -238.491776)
		(mid 87.340948 -238.567953)
		(end 87.623904 -238.491776)
		(width 0.0889)
		(layer "In2.Cu")
		(net "M_C_CPU1_SA_DQ<22>")
	)
	(arc
		(start 79.821024 -238.567976)
		(mid 79.967541 -238.54859)
		(end 80.10398 -238.491776)
		(width 0.0889)
		(layer "In2.Cu")
		(net "M_C_CPU1_SA_DQ<22>")
	)
	(arc
		(start 91.383866 -238.491776)
		(mid 91.566117 -238.441426)
		(end 91.749626 -238.48695)
		(width 0.0889)
		(layer "In2.Cu")
		(net "M_C_CPU1_SA_DQ<22>")
	)
	(arc
		(start 91.758008 -238.491776)
		(mid 92.040964 -238.567953)
		(end 92.32392 -238.491776)
		(width 0.0889)
		(layer "In2.Cu")
		(net "M_C_CPU1_SA_DQ<22>")
	)
	(arc
		(start 80.10398 -238.491776)
		(mid 80.286231 -238.441426)
		(end 80.46974 -238.48695)
		(width 0.0889)
		(layer "In2.Cu")
		(net "M_C_CPU1_SA_DQ<22>")
	)
	(arc
		(start 85.752432 -238.48695)
		(mid 85.93594 -238.441456)
		(end 86.118192 -238.491776)
		(width 0.0889)
		(layer "In2.Cu")
		(net "M_C_CPU1_SA_DQ<22>")
	)
	(arc
		(start 81.052416 -238.48695)
		(mid 81.235924 -238.441456)
		(end 81.418176 -238.491776)
		(width 0.0889)
		(layer "In2.Cu")
		(net "M_C_CPU1_SA_DQ<22>")
	)
	(arc
		(start 90.817954 -238.491776)
		(mid 91.10091 -238.567953)
		(end 91.383866 -238.491776)
		(width 0.0889)
		(layer "In2.Cu")
		(net "M_C_CPU1_SA_DQ<22>")
	)
	(arc
		(start 86.684104 -238.491776)
		(mid 86.871048 -238.441521)
		(end 87.057992 -238.491776)
		(width 0.0889)
		(layer "In2.Cu")
		(net "M_C_CPU1_SA_DQ<22>")
	)
	(arc
		(start 83.863942 -238.491776)
		(mid 84.046193 -238.441426)
		(end 84.229702 -238.48695)
		(width 0.0889)
		(layer "In2.Cu")
		(net "M_C_CPU1_SA_DQ<22>")
	)
	(arc
		(start 89.878154 -238.491776)
		(mid 90.16111 -238.567953)
		(end 90.444066 -238.491776)
		(width 0.0889)
		(layer "In2.Cu")
		(net "M_C_CPU1_SA_DQ<22>")
	)
	(arc
		(start 93.638116 -238.491776)
		(mid 93.885829 -238.566996)
		(end 94.141036 -238.523526)
		(width 0.0889)
		(layer "In2.Cu")
		(net "M_C_CPU1_SA_DQ<22>")
	)
	(arc
		(start 80.478122 -238.491776)
		(mid 80.761078 -238.567953)
		(end 81.044034 -238.491776)
		(width 0.0889)
		(layer "In2.Cu")
		(net "M_C_CPU1_SA_DQ<22>")
	)
	(arc
		(start 87.998046 -238.491776)
		(mid 88.281002 -238.567953)
		(end 88.563958 -238.491776)
		(width 0.0889)
		(layer "In2.Cu")
		(net "M_C_CPU1_SA_DQ<22>")
	)
	(arc
		(start 85.178138 -238.491776)
		(mid 85.461094 -238.567953)
		(end 85.74405 -238.491776)
		(width 0.0889)
		(layer "In2.Cu")
		(net "M_C_CPU1_SA_DQ<22>")
	)
	(arc
		(start 93.272356 -238.48695)
		(mid 93.455864 -238.441456)
		(end 93.638116 -238.491776)
		(width 0.0889)
		(layer "In2.Cu")
		(net "M_C_CPU1_SA_DQ<22>")
	)
	(arc
		(start 81.984088 -238.491776)
		(mid 82.171032 -238.441521)
		(end 82.357976 -238.491776)
		(width 0.0889)
		(layer "In2.Cu")
		(net "M_C_CPU1_SA_DQ<22>")
	)
	(arc
		(start 92.32392 -238.491776)
		(mid 92.506171 -238.441426)
		(end 92.68968 -238.48695)
		(width 0.0889)
		(layer "In2.Cu")
		(net "M_C_CPU1_SA_DQ<22>")
	)
	(arc
		(start 82.923888 -238.491776)
		(mid 83.106139 -238.441426)
		(end 83.289648 -238.48695)
		(width 0.0889)
		(layer "In2.Cu")
		(net "M_C_CPU1_SA_DQ<22>")
	)
	(arc
		(start 81.418176 -238.491776)
		(mid 81.701132 -238.567953)
		(end 81.984088 -238.491776)
		(width 0.0889)
		(layer "In2.Cu")
		(net "M_C_CPU1_SA_DQ<22>")
	)
	(arc
		(start 82.357976 -238.491776)
		(mid 82.640932 -238.567953)
		(end 82.923888 -238.491776)
		(width 0.0889)
		(layer "In2.Cu")
		(net "M_C_CPU1_SA_DQ<22>")
	)
	(arc
		(start 83.29803 -238.491776)
		(mid 83.580986 -238.567953)
		(end 83.863942 -238.491776)
		(width 0.0889)
		(layer "In2.Cu")
		(net "M_C_CPU1_SA_DQ<22>")
	)
	(arc
		(start 87.623904 -238.491776)
		(mid 87.806155 -238.441426)
		(end 87.989664 -238.48695)
		(width 0.0889)
		(layer "In2.Cu")
		(net "M_C_CPU1_SA_DQ<22>")
	)
	(arc
		(start 86.118192 -238.491776)
		(mid 86.401148 -238.567953)
		(end 86.684104 -238.491776)
		(width 0.0889)
		(layer "In2.Cu")
		(net "M_C_CPU1_SA_DQ<22>")
	)
	(arc
		(start 92.698062 -238.491776)
		(mid 92.981018 -238.567953)
		(end 93.263974 -238.491776)
		(width 0.0889)
		(layer "In2.Cu")
		(net "M_C_CPU1_SA_DQ<22>")
	)
	(arc
		(start 89.512394 -238.48695)
		(mid 89.695902 -238.441456)
		(end 89.878154 -238.491776)
		(width 0.0889)
		(layer "In2.Cu")
		(net "M_C_CPU1_SA_DQ<22>")
	)
	(arc
		(start 90.444066 -238.491776)
		(mid 90.63101 -238.441521)
		(end 90.817954 -238.491776)
		(width 0.0889)
		(layer "In2.Cu")
		(net "M_C_CPU1_SA_DQ<22>")
	)
	(segment
		(start 95.797878 -239.080294)
		(end 95.331026 -238.814356)
		(width 0.10668)
		(layer "F.Cu")
		(net "M_C_CPU1_SA_DQ<21>")
	)
	(segment
		(start 76.121006 -237.074964)
		(end 76.281026 -237.234984)
		(width 0.0889)
		(layer "In2.Cu")
		(net "M_C_CPU1_SA_DQ<21>")
	)
	(segment
		(start 58.93181 -223.041972)
		(end 58.93181 -223.097344)
		(width 0.14478)
		(layer "In2.Cu")
		(net "M_C_CPU1_SA_DQ<21>")
	)
	(segment
		(start 78.556866 -238.454184)
		(end 79.151226 -239.048544)
		(width 0.0889)
		(layer "In2.Cu")
		(net "M_C_CPU1_SA_DQ<21>")
	)
	(segment
		(start 47.11319 -223.948752)
		(end 47.274734 -224.110296)
		(width 0.14478)
		(layer "In2.Cu")
		(net "M_C_CPU1_SA_DQ<21>")
	)
	(segment
		(start 53.952648 -224.110296)
		(end 54.1401 -224.110296)
		(width 0.14478)
		(layer "In2.Cu")
		(net "M_C_CPU1_SA_DQ<21>")
	)
	(segment
		(start 95.48495 -239.079786)
		(end 95.331026 -238.814356)
		(width 0.0889)
		(layer "In2.Cu")
		(net "M_C_CPU1_SA_DQ<21>")
	)
	(segment
		(start 79.151226 -239.048544)
		(end 79.89062 -239.048544)
		(width 0.0889)
		(layer "In2.Cu")
		(net "M_C_CPU1_SA_DQ<21>")
	)
	(segment
		(start 49.427384 -224.110296)
		(end 50.277268 -223.260412)
		(width 0.14478)
		(layer "In2.Cu")
		(net "M_C_CPU1_SA_DQ<21>")
	)
	(segment
		(start 50.60061 -223.260412)
		(end 50.763678 -223.097344)
		(width 0.14478)
		(layer "In2.Cu")
		(net "M_C_CPU1_SA_DQ<21>")
	)
	(segment
		(start 94.204028 -239.136936)
		(end 94.21241 -239.141762)
		(width 0.0889)
		(layer "In2.Cu")
		(net "M_C_CPU1_SA_DQ<21>")
	)
	(segment
		(start 51.320192 -223.029272)
		(end 51.320192 -223.097344)
		(width 0.14478)
		(layer "In2.Cu")
		(net "M_C_CPU1_SA_DQ<21>")
	)
	(segment
		(start 56.950864 -224.110296)
		(end 57.800748 -223.260412)
		(width 0.14478)
		(layer "In2.Cu")
		(net "M_C_CPU1_SA_DQ<21>")
	)
	(segment
		(start 44.76496 -224.110296)
		(end 45.297344 -224.110296)
		(width 0.14478)
		(layer "In2.Cu")
		(net "M_C_CPU1_SA_DQ<21>")
	)
	(segment
		(start 47.274734 -224.110296)
		(end 48.343312 -224.110296)
		(width 0.14478)
		(layer "In2.Cu")
		(net "M_C_CPU1_SA_DQ<21>")
	)
	(segment
		(start 83.289648 -239.141762)
		(end 83.29803 -239.136936)
		(width 0.0889)
		(layer "In2.Cu")
		(net "M_C_CPU1_SA_DQ<21>")
	)
	(segment
		(start 58.93181 -223.097344)
		(end 59.094878 -223.260412)
		(width 0.14478)
		(layer "In2.Cu")
		(net "M_C_CPU1_SA_DQ<21>")
	)
	(segment
		(start 60.452508 -222.873824)
		(end 60.615576 -223.036892)
		(width 0.14478)
		(layer "In2.Cu")
		(net "M_C_CPU1_SA_DQ<21>")
	)
	(segment
		(start 52.427124 -222.866204)
		(end 52.657502 -222.866204)
		(width 0.14478)
		(layer "In2.Cu")
		(net "M_C_CPU1_SA_DQ<21>")
	)
	(segment
		(start 50.763678 -223.029272)
		(end 50.926746 -222.866204)
		(width 0.14478)
		(layer "In2.Cu")
		(net "M_C_CPU1_SA_DQ<21>")
	)
	(segment
		(start 45.458888 -223.871536)
		(end 45.620432 -223.709992)
		(width 0.14478)
		(layer "In2.Cu")
		(net "M_C_CPU1_SA_DQ<21>")
	)
	(segment
		(start 60.059062 -223.036892)
		(end 60.22213 -222.873824)
		(width 0.14478)
		(layer "In2.Cu")
		(net "M_C_CPU1_SA_DQ<21>")
	)
	(segment
		(start 46.561756 -224.34931)
		(end 46.561756 -223.871536)
		(width 0.14478)
		(layer "In2.Cu")
		(net "M_C_CPU1_SA_DQ<21>")
	)
	(segment
		(start 48.50638 -223.887792)
		(end 48.669448 -223.724724)
		(width 0.14478)
		(layer "In2.Cu")
		(net "M_C_CPU1_SA_DQ<21>")
	)
	(segment
		(start 58.375296 -223.041972)
		(end 58.538364 -222.878904)
		(width 0.14478)
		(layer "In2.Cu")
		(net "M_C_CPU1_SA_DQ<21>")
	)
	(segment
		(start 73.664826 -237.074964)
		(end 75.925426 -237.074964)
		(width 0.14478)
		(layer "In2.Cu")
		(net "M_C_CPU1_SA_DQ<21>")
	)
	(segment
		(start 61.409326 -224.283524)
		(end 63.123826 -224.283524)
		(width 0.14478)
		(layer "In2.Cu")
		(net "M_C_CPU1_SA_DQ<21>")
	)
	(segment
		(start 78.038706 -238.454184)
		(end 78.556866 -238.454184)
		(width 0.0889)
		(layer "In2.Cu")
		(net "M_C_CPU1_SA_DQ<21>")
	)
	(segment
		(start 59.094878 -223.260412)
		(end 59.895994 -223.260412)
		(width 0.14478)
		(layer "In2.Cu")
		(net "M_C_CPU1_SA_DQ<21>")
	)
	(segment
		(start 59.895994 -223.260412)
		(end 60.059062 -223.097344)
		(width 0.14478)
		(layer "In2.Cu")
		(net "M_C_CPU1_SA_DQ<21>")
	)
	(segment
		(start 51.157124 -222.866204)
		(end 51.320192 -223.029272)
		(width 0.14478)
		(layer "In2.Cu")
		(net "M_C_CPU1_SA_DQ<21>")
	)
	(segment
		(start 52.657502 -222.866204)
		(end 52.82057 -223.029272)
		(width 0.14478)
		(layer "In2.Cu")
		(net "M_C_CPU1_SA_DQ<21>")
	)
	(segment
		(start 51.48326 -223.260412)
		(end 52.100988 -223.260412)
		(width 0.14478)
		(layer "In2.Cu")
		(net "M_C_CPU1_SA_DQ<21>")
	)
	(segment
		(start 54.303168 -223.947228)
		(end 54.303168 -223.882712)
		(width 0.14478)
		(layer "In2.Cu")
		(net "M_C_CPU1_SA_DQ<21>")
	)
	(segment
		(start 54.859682 -223.882712)
		(end 54.859682 -223.947228)
		(width 0.14478)
		(layer "In2.Cu")
		(net "M_C_CPU1_SA_DQ<21>")
	)
	(segment
		(start 46.561756 -223.871536)
		(end 46.7233 -223.709992)
		(width 0.14478)
		(layer "In2.Cu")
		(net "M_C_CPU1_SA_DQ<21>")
	)
	(segment
		(start 67.607688 -228.767386)
		(end 67.607688 -231.017826)
		(width 0.14478)
		(layer "In2.Cu")
		(net "M_C_CPU1_SA_DQ<21>")
	)
	(segment
		(start 85.74405 -239.136936)
		(end 85.752432 -239.141762)
		(width 0.0889)
		(layer "In2.Cu")
		(net "M_C_CPU1_SA_DQ<21>")
	)
	(segment
		(start 76.281026 -237.234984)
		(end 76.819506 -237.234984)
		(width 0.0889)
		(layer "In2.Cu")
		(net "M_C_CPU1_SA_DQ<21>")
	)
	(segment
		(start 48.899826 -223.724724)
		(end 49.062894 -223.887792)
		(width 0.14478)
		(layer "In2.Cu")
		(net "M_C_CPU1_SA_DQ<21>")
	)
	(segment
		(start 45.297344 -224.110296)
		(end 45.458888 -223.948752)
		(width 0.14478)
		(layer "In2.Cu")
		(net "M_C_CPU1_SA_DQ<21>")
	)
	(segment
		(start 50.763678 -223.097344)
		(end 50.763678 -223.029272)
		(width 0.14478)
		(layer "In2.Cu")
		(net "M_C_CPU1_SA_DQ<21>")
	)
	(segment
		(start 87.989664 -239.141762)
		(end 87.998046 -239.136936)
		(width 0.0889)
		(layer "In2.Cu")
		(net "M_C_CPU1_SA_DQ<21>")
	)
	(segment
		(start 60.22213 -222.873824)
		(end 60.452508 -222.873824)
		(width 0.14478)
		(layer "In2.Cu")
		(net "M_C_CPU1_SA_DQ<21>")
	)
	(segment
		(start 46.010322 -224.34931)
		(end 46.171866 -224.510854)
		(width 0.14478)
		(layer "In2.Cu")
		(net "M_C_CPU1_SA_DQ<21>")
	)
	(segment
		(start 49.062894 -223.947228)
		(end 49.225962 -224.110296)
		(width 0.14478)
		(layer "In2.Cu")
		(net "M_C_CPU1_SA_DQ<21>")
	)
	(segment
		(start 54.303168 -223.882712)
		(end 54.466236 -223.719644)
		(width 0.14478)
		(layer "In2.Cu")
		(net "M_C_CPU1_SA_DQ<21>")
	)
	(segment
		(start 52.82057 -223.029272)
		(end 52.82057 -223.097344)
		(width 0.14478)
		(layer "In2.Cu")
		(net "M_C_CPU1_SA_DQ<21>")
	)
	(segment
		(start 52.983638 -223.260412)
		(end 53.102764 -223.260412)
		(width 0.14478)
		(layer "In2.Cu")
		(net "M_C_CPU1_SA_DQ<21>")
	)
	(segment
		(start 52.82057 -223.097344)
		(end 52.983638 -223.260412)
		(width 0.14478)
		(layer "In2.Cu")
		(net "M_C_CPU1_SA_DQ<21>")
	)
	(segment
		(start 56.642508 -223.882712)
		(end 56.642508 -223.947228)
		(width 0.14478)
		(layer "In2.Cu")
		(net "M_C_CPU1_SA_DQ<21>")
	)
	(segment
		(start 56.249062 -223.719644)
		(end 56.47944 -223.719644)
		(width 0.14478)
		(layer "In2.Cu")
		(net "M_C_CPU1_SA_DQ<21>")
	)
	(segment
		(start 54.859682 -223.947228)
		(end 55.02275 -224.110296)
		(width 0.14478)
		(layer "In2.Cu")
		(net "M_C_CPU1_SA_DQ<21>")
	)
	(segment
		(start 52.264056 -223.029272)
		(end 52.427124 -222.866204)
		(width 0.14478)
		(layer "In2.Cu")
		(net "M_C_CPU1_SA_DQ<21>")
	)
	(segment
		(start 58.375296 -223.097344)
		(end 58.375296 -223.041972)
		(width 0.14478)
		(layer "In2.Cu")
		(net "M_C_CPU1_SA_DQ<21>")
	)
	(segment
		(start 48.50638 -223.947228)
		(end 48.50638 -223.887792)
		(width 0.14478)
		(layer "In2.Cu")
		(net "M_C_CPU1_SA_DQ<21>")
	)
	(segment
		(start 58.212228 -223.260412)
		(end 58.375296 -223.097344)
		(width 0.14478)
		(layer "In2.Cu")
		(net "M_C_CPU1_SA_DQ<21>")
	)
	(segment
		(start 80.46974 -239.141762)
		(end 80.478122 -239.136936)
		(width 0.0889)
		(layer "In2.Cu")
		(net "M_C_CPU1_SA_DQ<21>")
	)
	(segment
		(start 55.922926 -224.110296)
		(end 56.085994 -223.947228)
		(width 0.14478)
		(layer "In2.Cu")
		(net "M_C_CPU1_SA_DQ<21>")
	)
	(segment
		(start 45.458888 -223.948752)
		(end 45.458888 -223.871536)
		(width 0.14478)
		(layer "In2.Cu")
		(net "M_C_CPU1_SA_DQ<21>")
	)
	(segment
		(start 52.100988 -223.260412)
		(end 52.264056 -223.097344)
		(width 0.14478)
		(layer "In2.Cu")
		(net "M_C_CPU1_SA_DQ<21>")
	)
	(segment
		(start 48.343312 -224.110296)
		(end 48.50638 -223.947228)
		(width 0.14478)
		(layer "In2.Cu")
		(net "M_C_CPU1_SA_DQ<21>")
	)
	(segment
		(start 92.68968 -239.141762)
		(end 92.698062 -239.136936)
		(width 0.0889)
		(layer "In2.Cu")
		(net "M_C_CPU1_SA_DQ<21>")
	)
	(segment
		(start 58.538364 -222.878904)
		(end 58.768742 -222.878904)
		(width 0.14478)
		(layer "In2.Cu")
		(net "M_C_CPU1_SA_DQ<21>")
	)
	(segment
		(start 76.819506 -237.234984)
		(end 78.038706 -238.454184)
		(width 0.0889)
		(layer "In2.Cu")
		(net "M_C_CPU1_SA_DQ<21>")
	)
	(segment
		(start 46.951646 -223.709992)
		(end 47.11319 -223.871536)
		(width 0.14478)
		(layer "In2.Cu")
		(net "M_C_CPU1_SA_DQ<21>")
	)
	(segment
		(start 46.7233 -223.709992)
		(end 46.951646 -223.709992)
		(width 0.14478)
		(layer "In2.Cu")
		(net "M_C_CPU1_SA_DQ<21>")
	)
	(segment
		(start 63.123826 -224.283524)
		(end 67.607688 -228.767386)
		(width 0.14478)
		(layer "In2.Cu")
		(net "M_C_CPU1_SA_DQ<21>")
	)
	(segment
		(start 60.615576 -223.036892)
		(end 60.615576 -223.489774)
		(width 0.14478)
		(layer "In2.Cu")
		(net "M_C_CPU1_SA_DQ<21>")
	)
	(segment
		(start 91.749626 -239.141762)
		(end 91.758008 -239.136936)
		(width 0.0889)
		(layer "In2.Cu")
		(net "M_C_CPU1_SA_DQ<21>")
	)
	(segment
		(start 84.229702 -239.141762)
		(end 84.238084 -239.136936)
		(width 0.0889)
		(layer "In2.Cu")
		(net "M_C_CPU1_SA_DQ<21>")
	)
	(segment
		(start 88.929718 -239.141762)
		(end 88.9381 -239.136936)
		(width 0.0889)
		(layer "In2.Cu")
		(net "M_C_CPU1_SA_DQ<21>")
	)
	(segment
		(start 56.642508 -223.947228)
		(end 56.805576 -224.110296)
		(width 0.14478)
		(layer "In2.Cu")
		(net "M_C_CPU1_SA_DQ<21>")
	)
	(segment
		(start 60.615576 -223.489774)
		(end 61.409326 -224.283524)
		(width 0.14478)
		(layer "In2.Cu")
		(net "M_C_CPU1_SA_DQ<21>")
	)
	(segment
		(start 48.669448 -223.724724)
		(end 48.899826 -223.724724)
		(width 0.14478)
		(layer "In2.Cu")
		(net "M_C_CPU1_SA_DQ<21>")
	)
	(segment
		(start 75.925426 -237.074964)
		(end 76.121006 -237.074964)
		(width 0.0889)
		(layer "In2.Cu")
		(net "M_C_CPU1_SA_DQ<21>")
	)
	(segment
		(start 45.620432 -223.709992)
		(end 45.848778 -223.709992)
		(width 0.14478)
		(layer "In2.Cu")
		(net "M_C_CPU1_SA_DQ<21>")
	)
	(segment
		(start 60.059062 -223.097344)
		(end 60.059062 -223.036892)
		(width 0.14478)
		(layer "In2.Cu")
		(net "M_C_CPU1_SA_DQ<21>")
	)
	(segment
		(start 47.11319 -223.871536)
		(end 47.11319 -223.948752)
		(width 0.14478)
		(layer "In2.Cu")
		(net "M_C_CPU1_SA_DQ<21>")
	)
	(segment
		(start 57.800748 -223.260412)
		(end 58.212228 -223.260412)
		(width 0.14478)
		(layer "In2.Cu")
		(net "M_C_CPU1_SA_DQ<21>")
	)
	(segment
		(start 50.926746 -222.866204)
		(end 51.157124 -222.866204)
		(width 0.14478)
		(layer "In2.Cu")
		(net "M_C_CPU1_SA_DQ<21>")
	)
	(segment
		(start 56.805576 -224.110296)
		(end 56.950864 -224.110296)
		(width 0.14478)
		(layer "In2.Cu")
		(net "M_C_CPU1_SA_DQ<21>")
	)
	(segment
		(start 49.062894 -223.887792)
		(end 49.062894 -223.947228)
		(width 0.14478)
		(layer "In2.Cu")
		(net "M_C_CPU1_SA_DQ<21>")
	)
	(segment
		(start 50.277268 -223.260412)
		(end 50.60061 -223.260412)
		(width 0.14478)
		(layer "In2.Cu")
		(net "M_C_CPU1_SA_DQ<21>")
	)
	(segment
		(start 55.02275 -224.110296)
		(end 55.922926 -224.110296)
		(width 0.14478)
		(layer "In2.Cu")
		(net "M_C_CPU1_SA_DQ<21>")
	)
	(segment
		(start 54.696614 -223.719644)
		(end 54.859682 -223.882712)
		(width 0.14478)
		(layer "In2.Cu")
		(net "M_C_CPU1_SA_DQ<21>")
	)
	(segment
		(start 45.848778 -223.709992)
		(end 46.010322 -223.871536)
		(width 0.14478)
		(layer "In2.Cu")
		(net "M_C_CPU1_SA_DQ<21>")
	)
	(segment
		(start 46.400212 -224.510854)
		(end 46.561756 -224.34931)
		(width 0.14478)
		(layer "In2.Cu")
		(net "M_C_CPU1_SA_DQ<21>")
	)
	(segment
		(start 46.010322 -223.871536)
		(end 46.010322 -224.34931)
		(width 0.14478)
		(layer "In2.Cu")
		(net "M_C_CPU1_SA_DQ<21>")
	)
	(segment
		(start 89.504012 -239.136936)
		(end 89.512394 -239.141762)
		(width 0.0889)
		(layer "In2.Cu")
		(net "M_C_CPU1_SA_DQ<21>")
	)
	(segment
		(start 54.1401 -224.110296)
		(end 54.303168 -223.947228)
		(width 0.14478)
		(layer "In2.Cu")
		(net "M_C_CPU1_SA_DQ<21>")
	)
	(segment
		(start 46.171866 -224.510854)
		(end 46.400212 -224.510854)
		(width 0.14478)
		(layer "In2.Cu")
		(net "M_C_CPU1_SA_DQ<21>")
	)
	(segment
		(start 93.263974 -239.136936)
		(end 93.272356 -239.141762)
		(width 0.0889)
		(layer "In2.Cu")
		(net "M_C_CPU1_SA_DQ<21>")
	)
	(segment
		(start 52.264056 -223.097344)
		(end 52.264056 -223.029272)
		(width 0.14478)
		(layer "In2.Cu")
		(net "M_C_CPU1_SA_DQ<21>")
	)
	(segment
		(start 54.466236 -223.719644)
		(end 54.696614 -223.719644)
		(width 0.14478)
		(layer "In2.Cu")
		(net "M_C_CPU1_SA_DQ<21>")
	)
	(segment
		(start 81.044034 -239.136936)
		(end 81.052416 -239.141762)
		(width 0.0889)
		(layer "In2.Cu")
		(net "M_C_CPU1_SA_DQ<21>")
	)
	(segment
		(start 84.803996 -239.136936)
		(end 84.812378 -239.141762)
		(width 0.0889)
		(layer "In2.Cu")
		(net "M_C_CPU1_SA_DQ<21>")
	)
	(segment
		(start 53.102764 -223.260412)
		(end 53.952648 -224.110296)
		(width 0.14478)
		(layer "In2.Cu")
		(net "M_C_CPU1_SA_DQ<21>")
	)
	(segment
		(start 56.085994 -223.882712)
		(end 56.249062 -223.719644)
		(width 0.14478)
		(layer "In2.Cu")
		(net "M_C_CPU1_SA_DQ<21>")
	)
	(segment
		(start 44.340018 -223.685354)
		(end 44.76496 -224.110296)
		(width 0.14478)
		(layer "In2.Cu")
		(net "M_C_CPU1_SA_DQ<21>")
	)
	(segment
		(start 95.462598 -239.163098)
		(end 95.48495 -239.079786)
		(width 0.0889)
		(layer "In2.Cu")
		(net "M_C_CPU1_SA_DQ<21>")
	)
	(segment
		(start 51.320192 -223.097344)
		(end 51.48326 -223.260412)
		(width 0.14478)
		(layer "In2.Cu")
		(net "M_C_CPU1_SA_DQ<21>")
	)
	(segment
		(start 49.225962 -224.110296)
		(end 49.427384 -224.110296)
		(width 0.14478)
		(layer "In2.Cu")
		(net "M_C_CPU1_SA_DQ<21>")
	)
	(segment
		(start 56.47944 -223.719644)
		(end 56.642508 -223.882712)
		(width 0.14478)
		(layer "In2.Cu")
		(net "M_C_CPU1_SA_DQ<21>")
	)
	(segment
		(start 58.768742 -222.878904)
		(end 58.93181 -223.041972)
		(width 0.14478)
		(layer "In2.Cu")
		(net "M_C_CPU1_SA_DQ<21>")
	)
	(segment
		(start 67.607688 -231.017826)
		(end 73.664826 -237.074964)
		(width 0.14478)
		(layer "In2.Cu")
		(net "M_C_CPU1_SA_DQ<21>")
	)
	(segment
		(start 56.085994 -223.947228)
		(end 56.085994 -223.882712)
		(width 0.14478)
		(layer "In2.Cu")
		(net "M_C_CPU1_SA_DQ<21>")
	)
	(arc
		(start 87.057992 -239.136936)
		(mid 87.340948 -239.060759)
		(end 87.623904 -239.136936)
		(width 0.0889)
		(layer "In2.Cu")
		(net "M_C_CPU1_SA_DQ<21>")
	)
	(arc
		(start 89.878154 -239.136936)
		(mid 90.16111 -239.060759)
		(end 90.444066 -239.136936)
		(width 0.0889)
		(layer "In2.Cu")
		(net "M_C_CPU1_SA_DQ<21>")
	)
	(arc
		(start 87.998046 -239.136936)
		(mid 88.281002 -239.060759)
		(end 88.563958 -239.136936)
		(width 0.0889)
		(layer "In2.Cu")
		(net "M_C_CPU1_SA_DQ<21>")
	)
	(arc
		(start 81.418176 -239.136936)
		(mid 81.701132 -239.060759)
		(end 81.984088 -239.136936)
		(width 0.0889)
		(layer "In2.Cu")
		(net "M_C_CPU1_SA_DQ<21>")
	)
	(arc
		(start 94.21241 -239.141762)
		(mid 94.395918 -239.187256)
		(end 94.57817 -239.136936)
		(width 0.0889)
		(layer "In2.Cu")
		(net "M_C_CPU1_SA_DQ<21>")
	)
	(arc
		(start 85.752432 -239.141762)
		(mid 85.93594 -239.187256)
		(end 86.118192 -239.136936)
		(width 0.0889)
		(layer "In2.Cu")
		(net "M_C_CPU1_SA_DQ<21>")
	)
	(arc
		(start 84.812378 -239.141762)
		(mid 84.995886 -239.187256)
		(end 85.178138 -239.136936)
		(width 0.0889)
		(layer "In2.Cu")
		(net "M_C_CPU1_SA_DQ<21>")
	)
	(arc
		(start 91.383866 -239.136936)
		(mid 91.566117 -239.187286)
		(end 91.749626 -239.141762)
		(width 0.0889)
		(layer "In2.Cu")
		(net "M_C_CPU1_SA_DQ<21>")
	)
	(arc
		(start 84.238084 -239.136936)
		(mid 84.52104 -239.060759)
		(end 84.803996 -239.136936)
		(width 0.0889)
		(layer "In2.Cu")
		(net "M_C_CPU1_SA_DQ<21>")
	)
	(arc
		(start 87.623904 -239.136936)
		(mid 87.806155 -239.187286)
		(end 87.989664 -239.141762)
		(width 0.0889)
		(layer "In2.Cu")
		(net "M_C_CPU1_SA_DQ<21>")
	)
	(arc
		(start 82.923888 -239.136936)
		(mid 83.106139 -239.187286)
		(end 83.289648 -239.141762)
		(width 0.0889)
		(layer "In2.Cu")
		(net "M_C_CPU1_SA_DQ<21>")
	)
	(arc
		(start 90.817954 -239.136936)
		(mid 91.10091 -239.060759)
		(end 91.383866 -239.136936)
		(width 0.0889)
		(layer "In2.Cu")
		(net "M_C_CPU1_SA_DQ<21>")
	)
	(arc
		(start 94.57817 -239.136936)
		(mid 94.861126 -239.060759)
		(end 95.144082 -239.136936)
		(width 0.0889)
		(layer "In2.Cu")
		(net "M_C_CPU1_SA_DQ<21>")
	)
	(arc
		(start 95.144082 -239.136936)
		(mid 95.300401 -239.185931)
		(end 95.462598 -239.163098)
		(width 0.0889)
		(layer "In2.Cu")
		(net "M_C_CPU1_SA_DQ<21>")
	)
	(arc
		(start 88.563958 -239.136936)
		(mid 88.746209 -239.187286)
		(end 88.929718 -239.141762)
		(width 0.0889)
		(layer "In2.Cu")
		(net "M_C_CPU1_SA_DQ<21>")
	)
	(arc
		(start 83.29803 -239.136936)
		(mid 83.580986 -239.060759)
		(end 83.863942 -239.136936)
		(width 0.0889)
		(layer "In2.Cu")
		(net "M_C_CPU1_SA_DQ<21>")
	)
	(arc
		(start 81.052416 -239.141762)
		(mid 81.235924 -239.187256)
		(end 81.418176 -239.136936)
		(width 0.0889)
		(layer "In2.Cu")
		(net "M_C_CPU1_SA_DQ<21>")
	)
	(arc
		(start 93.638116 -239.136936)
		(mid 93.921072 -239.060759)
		(end 94.204028 -239.136936)
		(width 0.0889)
		(layer "In2.Cu")
		(net "M_C_CPU1_SA_DQ<21>")
	)
	(arc
		(start 80.10398 -239.136936)
		(mid 80.286231 -239.187286)
		(end 80.46974 -239.141762)
		(width 0.0889)
		(layer "In2.Cu")
		(net "M_C_CPU1_SA_DQ<21>")
	)
	(arc
		(start 93.272356 -239.141762)
		(mid 93.455864 -239.187256)
		(end 93.638116 -239.136936)
		(width 0.0889)
		(layer "In2.Cu")
		(net "M_C_CPU1_SA_DQ<21>")
	)
	(arc
		(start 90.444066 -239.136936)
		(mid 90.63101 -239.187191)
		(end 90.817954 -239.136936)
		(width 0.0889)
		(layer "In2.Cu")
		(net "M_C_CPU1_SA_DQ<21>")
	)
	(arc
		(start 91.758008 -239.136936)
		(mid 92.040964 -239.060759)
		(end 92.32392 -239.136936)
		(width 0.0889)
		(layer "In2.Cu")
		(net "M_C_CPU1_SA_DQ<21>")
	)
	(arc
		(start 82.357976 -239.136936)
		(mid 82.640932 -239.060759)
		(end 82.923888 -239.136936)
		(width 0.0889)
		(layer "In2.Cu")
		(net "M_C_CPU1_SA_DQ<21>")
	)
	(arc
		(start 86.684104 -239.136936)
		(mid 86.871048 -239.187191)
		(end 87.057992 -239.136936)
		(width 0.0889)
		(layer "In2.Cu")
		(net "M_C_CPU1_SA_DQ<21>")
	)
	(arc
		(start 83.863942 -239.136936)
		(mid 84.046193 -239.187286)
		(end 84.229702 -239.141762)
		(width 0.0889)
		(layer "In2.Cu")
		(net "M_C_CPU1_SA_DQ<21>")
	)
	(arc
		(start 81.984088 -239.136936)
		(mid 82.171032 -239.187191)
		(end 82.357976 -239.136936)
		(width 0.0889)
		(layer "In2.Cu")
		(net "M_C_CPU1_SA_DQ<21>")
	)
	(arc
		(start 92.698062 -239.136936)
		(mid 92.981018 -239.060759)
		(end 93.263974 -239.136936)
		(width 0.0889)
		(layer "In2.Cu")
		(net "M_C_CPU1_SA_DQ<21>")
	)
	(arc
		(start 88.9381 -239.136936)
		(mid 89.221056 -239.060759)
		(end 89.504012 -239.136936)
		(width 0.0889)
		(layer "In2.Cu")
		(net "M_C_CPU1_SA_DQ<21>")
	)
	(arc
		(start 80.478122 -239.136936)
		(mid 80.761078 -239.060759)
		(end 81.044034 -239.136936)
		(width 0.0889)
		(layer "In2.Cu")
		(net "M_C_CPU1_SA_DQ<21>")
	)
	(arc
		(start 86.118192 -239.136936)
		(mid 86.401148 -239.060759)
		(end 86.684104 -239.136936)
		(width 0.0889)
		(layer "In2.Cu")
		(net "M_C_CPU1_SA_DQ<21>")
	)
	(arc
		(start 89.512394 -239.141762)
		(mid 89.695902 -239.187256)
		(end 89.878154 -239.136936)
		(width 0.0889)
		(layer "In2.Cu")
		(net "M_C_CPU1_SA_DQ<21>")
	)
	(arc
		(start 92.32392 -239.136936)
		(mid 92.506171 -239.187286)
		(end 92.68968 -239.141762)
		(width 0.0889)
		(layer "In2.Cu")
		(net "M_C_CPU1_SA_DQ<21>")
	)
	(arc
		(start 85.178138 -239.136936)
		(mid 85.461094 -239.060759)
		(end 85.74405 -239.136936)
		(width 0.0889)
		(layer "In2.Cu")
		(net "M_C_CPU1_SA_DQ<21>")
	)
	(arc
		(start 79.89062 -239.048544)
		(mid 80.006095 -239.071514)
		(end 80.10398 -239.136936)
		(width 0.0889)
		(layer "In2.Cu")
		(net "M_C_CPU1_SA_DQ<21>")
	)
	(segment
		(start 94.387924 -238.270288)
		(end 93.921072 -238.00435)
		(width 0.10668)
		(layer "F.Cu")
		(net "M_C_CPU1_SA_DQ<20>")
	)
	(segment
		(start 78.831186 -237.963964)
		(end 79.193898 -238.326676)
		(width 0.0889)
		(layer "In2.Cu")
		(net "M_C_CPU1_SA_DQ<20>")
	)
	(segment
		(start 74.068686 -236.163104)
		(end 75.945746 -236.163104)
		(width 0.14478)
		(layer "In2.Cu")
		(net "M_C_CPU1_SA_DQ<20>")
	)
	(segment
		(start 70.374764 -232.192322)
		(end 70.374764 -232.469182)
		(width 0.14478)
		(layer "In2.Cu")
		(net "M_C_CPU1_SA_DQ<20>")
	)
	(segment
		(start 90.339672 -238.331756)
		(end 90.348054 -238.32693)
		(width 0.0889)
		(layer "In2.Cu")
		(net "M_C_CPU1_SA_DQ<20>")
	)
	(segment
		(start 62.86627 -222.722948)
		(end 62.86627 -223.157288)
		(width 0.14478)
		(layer "In2.Cu")
		(net "M_C_CPU1_SA_DQ<20>")
	)
	(segment
		(start 49.108106 -222.689166)
		(end 49.338484 -222.689166)
		(width 0.14478)
		(layer "In2.Cu")
		(net "M_C_CPU1_SA_DQ<20>")
	)
	(segment
		(start 86.57971 -238.331756)
		(end 86.588092 -238.32693)
		(width 0.0889)
		(layer "In2.Cu")
		(net "M_C_CPU1_SA_DQ<20>")
	)
	(segment
		(start 79.193898 -238.326676)
		(end 79.634842 -238.326676)
		(width 0.0889)
		(layer "In2.Cu")
		(net "M_C_CPU1_SA_DQ<20>")
	)
	(segment
		(start 61.941202 -223.091248)
		(end 62.47257 -222.55988)
		(width 0.14478)
		(layer "In2.Cu")
		(net "M_C_CPU1_SA_DQ<20>")
	)
	(segment
		(start 44.889166 -222.746824)
		(end 45.293788 -222.746824)
		(width 0.14478)
		(layer "In2.Cu")
		(net "M_C_CPU1_SA_DQ<20>")
	)
	(segment
		(start 52.924964 -221.570042)
		(end 53.765196 -222.410274)
		(width 0.14478)
		(layer "In2.Cu")
		(net "M_C_CPU1_SA_DQ<20>")
	)
	(segment
		(start 69.842634 -231.937052)
		(end 70.119494 -231.937052)
		(width 0.14478)
		(layer "In2.Cu")
		(net "M_C_CPU1_SA_DQ<20>")
	)
	(segment
		(start 44.340018 -221.985332)
		(end 44.739306 -222.38462)
		(width 0.14478)
		(layer "In2.Cu")
		(net "M_C_CPU1_SA_DQ<20>")
	)
	(segment
		(start 73.269094 -235.086652)
		(end 73.524364 -235.341922)
		(width 0.14478)
		(layer "In2.Cu")
		(net "M_C_CPU1_SA_DQ<20>")
	)
	(segment
		(start 71.417434 -233.511852)
		(end 71.694294 -233.511852)
		(width 0.14478)
		(layer "In2.Cu")
		(net "M_C_CPU1_SA_DQ<20>")
	)
	(segment
		(start 61.363098 -221.56039)
		(end 61.652658 -221.56039)
		(width 0.14478)
		(layer "In2.Cu")
		(net "M_C_CPU1_SA_DQ<20>")
	)
	(segment
		(start 69.01307 -230.853234)
		(end 69.276214 -231.116378)
		(width 0.14478)
		(layer "In2.Cu")
		(net "M_C_CPU1_SA_DQ<20>")
	)
	(segment
		(start 68.758816 -230.853234)
		(end 69.01307 -230.853234)
		(width 0.14478)
		(layer "In2.Cu")
		(net "M_C_CPU1_SA_DQ<20>")
	)
	(segment
		(start 44.739306 -222.38462)
		(end 44.739306 -222.596964)
		(width 0.14478)
		(layer "In2.Cu")
		(net "M_C_CPU1_SA_DQ<20>")
	)
	(segment
		(start 71.694294 -233.511852)
		(end 71.949564 -233.767122)
		(width 0.14478)
		(layer "In2.Cu")
		(net "M_C_CPU1_SA_DQ<20>")
	)
	(segment
		(start 62.062614 -221.970346)
		(end 62.062614 -222.182436)
		(width 0.14478)
		(layer "In2.Cu")
		(net "M_C_CPU1_SA_DQ<20>")
	)
	(segment
		(start 60.536328 -221.56039)
		(end 60.811664 -221.835726)
		(width 0.14478)
		(layer "In2.Cu")
		(net "M_C_CPU1_SA_DQ<20>")
	)
	(segment
		(start 61.652658 -221.56039)
		(end 62.062614 -221.970346)
		(width 0.14478)
		(layer "In2.Cu")
		(net "M_C_CPU1_SA_DQ<20>")
	)
	(segment
		(start 94.052644 -238.353092)
		(end 94.074996 -238.26978)
		(width 0.0889)
		(layer "In2.Cu")
		(net "M_C_CPU1_SA_DQ<20>")
	)
	(segment
		(start 94.074996 -238.26978)
		(end 93.921072 -238.00435)
		(width 0.0889)
		(layer "In2.Cu")
		(net "M_C_CPU1_SA_DQ<20>")
	)
	(segment
		(start 69.276214 -231.116378)
		(end 69.276214 -231.34447)
		(width 0.14478)
		(layer "In2.Cu")
		(net "M_C_CPU1_SA_DQ<20>")
	)
	(segment
		(start 69.276214 -231.34447)
		(end 69.27596 -231.370378)
		(width 0.14478)
		(layer "In2.Cu")
		(net "M_C_CPU1_SA_DQ<20>")
	)
	(segment
		(start 72.736964 -234.554522)
		(end 72.736964 -234.831382)
		(width 0.14478)
		(layer "In2.Cu")
		(net "M_C_CPU1_SA_DQ<20>")
	)
	(segment
		(start 72.204834 -234.299252)
		(end 72.481694 -234.299252)
		(width 0.14478)
		(layer "In2.Cu")
		(net "M_C_CPU1_SA_DQ<20>")
	)
	(segment
		(start 46.752764 -222.419926)
		(end 48.838866 -222.419926)
		(width 0.14478)
		(layer "In2.Cu")
		(net "M_C_CPU1_SA_DQ<20>")
	)
	(segment
		(start 71.949564 -234.043982)
		(end 72.204834 -234.299252)
		(width 0.14478)
		(layer "In2.Cu")
		(net "M_C_CPU1_SA_DQ<20>")
	)
	(segment
		(start 46.007782 -222.64116)
		(end 46.171866 -222.805244)
		(width 0.14478)
		(layer "In2.Cu")
		(net "M_C_CPU1_SA_DQ<20>")
	)
	(segment
		(start 53.765196 -222.410274)
		(end 56.950864 -222.410274)
		(width 0.14478)
		(layer "In2.Cu")
		(net "M_C_CPU1_SA_DQ<20>")
	)
	(segment
		(start 68.528946 -230.623364)
		(end 68.758816 -230.853234)
		(width 0.14478)
		(layer "In2.Cu")
		(net "M_C_CPU1_SA_DQ<20>")
	)
	(segment
		(start 46.171866 -222.805244)
		(end 46.43374 -222.805244)
		(width 0.14478)
		(layer "In2.Cu")
		(net "M_C_CPU1_SA_DQ<20>")
	)
	(segment
		(start 45.451268 -222.064072)
		(end 45.614336 -221.901004)
		(width 0.14478)
		(layer "In2.Cu")
		(net "M_C_CPU1_SA_DQ<20>")
	)
	(segment
		(start 73.524364 -235.341922)
		(end 73.524364 -235.618782)
		(width 0.14478)
		(layer "In2.Cu")
		(net "M_C_CPU1_SA_DQ<20>")
	)
	(segment
		(start 70.119494 -231.937052)
		(end 70.374764 -232.192322)
		(width 0.14478)
		(layer "In2.Cu")
		(net "M_C_CPU1_SA_DQ<20>")
	)
	(segment
		(start 72.992234 -235.086652)
		(end 73.269094 -235.086652)
		(width 0.14478)
		(layer "In2.Cu")
		(net "M_C_CPU1_SA_DQ<20>")
	)
	(segment
		(start 61.71057 -223.091248)
		(end 61.941202 -223.091248)
		(width 0.14478)
		(layer "In2.Cu")
		(net "M_C_CPU1_SA_DQ<20>")
	)
	(segment
		(start 61.547502 -222.92818)
		(end 61.71057 -223.091248)
		(width 0.14478)
		(layer "In2.Cu")
		(net "M_C_CPU1_SA_DQ<20>")
	)
	(segment
		(start 88.094058 -238.32693)
		(end 88.10244 -238.331756)
		(width 0.0889)
		(layer "In2.Cu")
		(net "M_C_CPU1_SA_DQ<20>")
	)
	(segment
		(start 71.162164 -232.979722)
		(end 71.162164 -233.256582)
		(width 0.14478)
		(layer "In2.Cu")
		(net "M_C_CPU1_SA_DQ<20>")
	)
	(segment
		(start 46.596808 -222.575882)
		(end 46.752764 -222.419926)
		(width 0.14478)
		(layer "In2.Cu")
		(net "M_C_CPU1_SA_DQ<20>")
	)
	(segment
		(start 61.087762 -221.835726)
		(end 61.363098 -221.56039)
		(width 0.14478)
		(layer "In2.Cu")
		(net "M_C_CPU1_SA_DQ<20>")
	)
	(segment
		(start 70.630034 -232.724452)
		(end 70.906894 -232.724452)
		(width 0.14478)
		(layer "In2.Cu")
		(net "M_C_CPU1_SA_DQ<20>")
	)
	(segment
		(start 45.293788 -222.746824)
		(end 45.451268 -222.589344)
		(width 0.14478)
		(layer "In2.Cu")
		(net "M_C_CPU1_SA_DQ<20>")
	)
	(segment
		(start 77.667866 -236.787944)
		(end 77.667866 -237.105444)
		(width 0.0889)
		(layer "In2.Cu")
		(net "M_C_CPU1_SA_DQ<20>")
	)
	(segment
		(start 75.945746 -236.163104)
		(end 77.043026 -236.163104)
		(width 0.0889)
		(layer "In2.Cu")
		(net "M_C_CPU1_SA_DQ<20>")
	)
	(segment
		(start 48.838866 -222.419926)
		(end 49.108106 -222.689166)
		(width 0.14478)
		(layer "In2.Cu")
		(net "M_C_CPU1_SA_DQ<20>")
	)
	(segment
		(start 63.056262 -223.34728)
		(end 63.490602 -223.34728)
		(width 0.14478)
		(layer "In2.Cu")
		(net "M_C_CPU1_SA_DQ<20>")
	)
	(segment
		(start 82.453988 -238.32693)
		(end 82.46237 -238.331756)
		(width 0.0889)
		(layer "In2.Cu")
		(net "M_C_CPU1_SA_DQ<20>")
	)
	(segment
		(start 45.451268 -222.589344)
		(end 45.451268 -222.064072)
		(width 0.14478)
		(layer "In2.Cu")
		(net "M_C_CPU1_SA_DQ<20>")
	)
	(segment
		(start 61.547502 -222.697548)
		(end 61.547502 -222.92818)
		(width 0.14478)
		(layer "In2.Cu")
		(net "M_C_CPU1_SA_DQ<20>")
	)
	(segment
		(start 68.528946 -228.385624)
		(end 68.528946 -230.623364)
		(width 0.14478)
		(layer "In2.Cu")
		(net "M_C_CPU1_SA_DQ<20>")
	)
	(segment
		(start 46.007782 -222.064072)
		(end 46.007782 -222.64116)
		(width 0.14478)
		(layer "In2.Cu")
		(net "M_C_CPU1_SA_DQ<20>")
	)
	(segment
		(start 46.596808 -222.642176)
		(end 46.596808 -222.575882)
		(width 0.14478)
		(layer "In2.Cu")
		(net "M_C_CPU1_SA_DQ<20>")
	)
	(segment
		(start 71.949564 -233.767122)
		(end 71.949564 -234.043982)
		(width 0.14478)
		(layer "In2.Cu")
		(net "M_C_CPU1_SA_DQ<20>")
	)
	(segment
		(start 78.526386 -237.963964)
		(end 78.831186 -237.963964)
		(width 0.0889)
		(layer "In2.Cu")
		(net "M_C_CPU1_SA_DQ<20>")
	)
	(segment
		(start 70.374764 -232.469182)
		(end 70.630034 -232.724452)
		(width 0.14478)
		(layer "In2.Cu")
		(net "M_C_CPU1_SA_DQ<20>")
	)
	(segment
		(start 72.736964 -234.831382)
		(end 72.992234 -235.086652)
		(width 0.14478)
		(layer "In2.Cu")
		(net "M_C_CPU1_SA_DQ<20>")
	)
	(segment
		(start 81.879694 -238.331756)
		(end 81.888076 -238.32693)
		(width 0.0889)
		(layer "In2.Cu")
		(net "M_C_CPU1_SA_DQ<20>")
	)
	(segment
		(start 70.906894 -232.724452)
		(end 71.162164 -232.979722)
		(width 0.14478)
		(layer "In2.Cu")
		(net "M_C_CPU1_SA_DQ<20>")
	)
	(segment
		(start 62.86627 -223.157288)
		(end 63.056262 -223.34728)
		(width 0.14478)
		(layer "In2.Cu")
		(net "M_C_CPU1_SA_DQ<20>")
	)
	(segment
		(start 77.043026 -236.163104)
		(end 77.667866 -236.787944)
		(width 0.0889)
		(layer "In2.Cu")
		(net "M_C_CPU1_SA_DQ<20>")
	)
	(segment
		(start 72.481694 -234.299252)
		(end 72.736964 -234.554522)
		(width 0.14478)
		(layer "In2.Cu")
		(net "M_C_CPU1_SA_DQ<20>")
	)
	(segment
		(start 45.844714 -221.901004)
		(end 46.007782 -222.064072)
		(width 0.14478)
		(layer "In2.Cu")
		(net "M_C_CPU1_SA_DQ<20>")
	)
	(segment
		(start 62.703202 -222.55988)
		(end 62.86627 -222.722948)
		(width 0.14478)
		(layer "In2.Cu")
		(net "M_C_CPU1_SA_DQ<20>")
	)
	(segment
		(start 73.524364 -235.618782)
		(end 74.068686 -236.163104)
		(width 0.14478)
		(layer "In2.Cu")
		(net "M_C_CPU1_SA_DQ<20>")
	)
	(segment
		(start 63.490602 -223.34728)
		(end 68.528946 -228.385624)
		(width 0.14478)
		(layer "In2.Cu")
		(net "M_C_CPU1_SA_DQ<20>")
	)
	(segment
		(start 87.154004 -238.32693)
		(end 87.162386 -238.331756)
		(width 0.0889)
		(layer "In2.Cu")
		(net "M_C_CPU1_SA_DQ<20>")
	)
	(segment
		(start 62.47257 -222.55988)
		(end 62.703202 -222.55988)
		(width 0.14478)
		(layer "In2.Cu")
		(net "M_C_CPU1_SA_DQ<20>")
	)
	(segment
		(start 44.739306 -222.596964)
		(end 44.889166 -222.746824)
		(width 0.14478)
		(layer "In2.Cu")
		(net "M_C_CPU1_SA_DQ<20>")
	)
	(segment
		(start 69.27596 -231.370378)
		(end 69.842634 -231.937052)
		(width 0.14478)
		(layer "In2.Cu")
		(net "M_C_CPU1_SA_DQ<20>")
	)
	(segment
		(start 77.667866 -237.105444)
		(end 78.526386 -237.963964)
		(width 0.0889)
		(layer "In2.Cu")
		(net "M_C_CPU1_SA_DQ<20>")
	)
	(segment
		(start 85.639656 -238.331756)
		(end 85.648038 -238.32693)
		(width 0.0889)
		(layer "In2.Cu")
		(net "M_C_CPU1_SA_DQ<20>")
	)
	(segment
		(start 50.457608 -221.570042)
		(end 52.924964 -221.570042)
		(width 0.14478)
		(layer "In2.Cu")
		(net "M_C_CPU1_SA_DQ<20>")
	)
	(segment
		(start 56.950864 -222.410274)
		(end 57.800748 -221.56039)
		(width 0.14478)
		(layer "In2.Cu")
		(net "M_C_CPU1_SA_DQ<20>")
	)
	(segment
		(start 46.43374 -222.805244)
		(end 46.596808 -222.642176)
		(width 0.14478)
		(layer "In2.Cu")
		(net "M_C_CPU1_SA_DQ<20>")
	)
	(segment
		(start 45.614336 -221.901004)
		(end 45.844714 -221.901004)
		(width 0.14478)
		(layer "In2.Cu")
		(net "M_C_CPU1_SA_DQ<20>")
	)
	(segment
		(start 79.634842 -238.326676)
		(end 79.654908 -238.338106)
		(width 0.0889)
		(layer "In2.Cu")
		(net "M_C_CPU1_SA_DQ<20>")
	)
	(segment
		(start 71.162164 -233.256582)
		(end 71.417434 -233.511852)
		(width 0.14478)
		(layer "In2.Cu")
		(net "M_C_CPU1_SA_DQ<20>")
	)
	(segment
		(start 83.394042 -238.32693)
		(end 83.402424 -238.331756)
		(width 0.0889)
		(layer "In2.Cu")
		(net "M_C_CPU1_SA_DQ<20>")
	)
	(segment
		(start 60.811664 -221.835726)
		(end 61.087762 -221.835726)
		(width 0.14478)
		(layer "In2.Cu")
		(net "M_C_CPU1_SA_DQ<20>")
	)
	(segment
		(start 49.338484 -222.689166)
		(end 50.457608 -221.570042)
		(width 0.14478)
		(layer "In2.Cu")
		(net "M_C_CPU1_SA_DQ<20>")
	)
	(segment
		(start 57.800748 -221.56039)
		(end 60.536328 -221.56039)
		(width 0.14478)
		(layer "In2.Cu")
		(net "M_C_CPU1_SA_DQ<20>")
	)
	(segment
		(start 62.062614 -222.182436)
		(end 61.547502 -222.697548)
		(width 0.14478)
		(layer "In2.Cu")
		(net "M_C_CPU1_SA_DQ<20>")
	)
	(segment
		(start 91.85402 -238.32693)
		(end 91.862402 -238.331756)
		(width 0.0889)
		(layer "In2.Cu")
		(net "M_C_CPU1_SA_DQ<20>")
	)
	(segment
		(start 90.913966 -238.32693)
		(end 90.922348 -238.331756)
		(width 0.0889)
		(layer "In2.Cu")
		(net "M_C_CPU1_SA_DQ<20>")
	)
	(arc
		(start 93.733874 -238.32693)
		(mid 93.890312 -238.375901)
		(end 94.052644 -238.353092)
		(width 0.0889)
		(layer "In2.Cu")
		(net "M_C_CPU1_SA_DQ<20>")
	)
	(arc
		(start 84.707984 -238.32693)
		(mid 84.99094 -238.250753)
		(end 85.273896 -238.32693)
		(width 0.0889)
		(layer "In2.Cu")
		(net "M_C_CPU1_SA_DQ<20>")
	)
	(arc
		(start 89.973912 -238.32693)
		(mid 90.156163 -238.37728)
		(end 90.339672 -238.331756)
		(width 0.0889)
		(layer "In2.Cu")
		(net "M_C_CPU1_SA_DQ<20>")
	)
	(arc
		(start 91.862402 -238.331756)
		(mid 92.04591 -238.37725)
		(end 92.228162 -238.32693)
		(width 0.0889)
		(layer "In2.Cu")
		(net "M_C_CPU1_SA_DQ<20>")
	)
	(arc
		(start 85.273896 -238.32693)
		(mid 85.456147 -238.37728)
		(end 85.639656 -238.331756)
		(width 0.0889)
		(layer "In2.Cu")
		(net "M_C_CPU1_SA_DQ<20>")
	)
	(arc
		(start 92.228162 -238.32693)
		(mid 92.511118 -238.250753)
		(end 92.794074 -238.32693)
		(width 0.0889)
		(layer "In2.Cu")
		(net "M_C_CPU1_SA_DQ<20>")
	)
	(arc
		(start 86.21395 -238.32693)
		(mid 86.396201 -238.37728)
		(end 86.57971 -238.331756)
		(width 0.0889)
		(layer "In2.Cu")
		(net "M_C_CPU1_SA_DQ<20>")
	)
	(arc
		(start 86.588092 -238.32693)
		(mid 86.871048 -238.250753)
		(end 87.154004 -238.32693)
		(width 0.0889)
		(layer "In2.Cu")
		(net "M_C_CPU1_SA_DQ<20>")
	)
	(arc
		(start 81.888076 -238.32693)
		(mid 82.171032 -238.250753)
		(end 82.453988 -238.32693)
		(width 0.0889)
		(layer "In2.Cu")
		(net "M_C_CPU1_SA_DQ<20>")
	)
	(arc
		(start 84.334096 -238.32693)
		(mid 84.52104 -238.377185)
		(end 84.707984 -238.32693)
		(width 0.0889)
		(layer "In2.Cu")
		(net "M_C_CPU1_SA_DQ<20>")
	)
	(arc
		(start 82.46237 -238.331756)
		(mid 82.645878 -238.37725)
		(end 82.82813 -238.32693)
		(width 0.0889)
		(layer "In2.Cu")
		(net "M_C_CPU1_SA_DQ<20>")
	)
	(arc
		(start 82.82813 -238.32693)
		(mid 83.111086 -238.250753)
		(end 83.394042 -238.32693)
		(width 0.0889)
		(layer "In2.Cu")
		(net "M_C_CPU1_SA_DQ<20>")
	)
	(arc
		(start 87.162386 -238.331756)
		(mid 87.345894 -238.37725)
		(end 87.528146 -238.32693)
		(width 0.0889)
		(layer "In2.Cu")
		(net "M_C_CPU1_SA_DQ<20>")
	)
	(arc
		(start 85.648038 -238.32693)
		(mid 85.930994 -238.250753)
		(end 86.21395 -238.32693)
		(width 0.0889)
		(layer "In2.Cu")
		(net "M_C_CPU1_SA_DQ<20>")
	)
	(arc
		(start 87.528146 -238.32693)
		(mid 87.811102 -238.250753)
		(end 88.094058 -238.32693)
		(width 0.0889)
		(layer "In2.Cu")
		(net "M_C_CPU1_SA_DQ<20>")
	)
	(arc
		(start 80.574134 -238.32693)
		(mid 80.761078 -238.377185)
		(end 80.948022 -238.32693)
		(width 0.0889)
		(layer "In2.Cu")
		(net "M_C_CPU1_SA_DQ<20>")
	)
	(arc
		(start 83.768184 -238.32693)
		(mid 84.05114 -238.250753)
		(end 84.334096 -238.32693)
		(width 0.0889)
		(layer "In2.Cu")
		(net "M_C_CPU1_SA_DQ<20>")
	)
	(arc
		(start 79.654908 -238.338106)
		(mid 79.832986 -238.37709)
		(end 80.008222 -238.32693)
		(width 0.0889)
		(layer "In2.Cu")
		(net "M_C_CPU1_SA_DQ<20>")
	)
	(arc
		(start 89.408 -238.32693)
		(mid 89.690956 -238.250753)
		(end 89.973912 -238.32693)
		(width 0.0889)
		(layer "In2.Cu")
		(net "M_C_CPU1_SA_DQ<20>")
	)
	(arc
		(start 80.008222 -238.32693)
		(mid 80.291178 -238.250753)
		(end 80.574134 -238.32693)
		(width 0.0889)
		(layer "In2.Cu")
		(net "M_C_CPU1_SA_DQ<20>")
	)
	(arc
		(start 91.288108 -238.32693)
		(mid 91.571064 -238.250753)
		(end 91.85402 -238.32693)
		(width 0.0889)
		(layer "In2.Cu")
		(net "M_C_CPU1_SA_DQ<20>")
	)
	(arc
		(start 88.10244 -238.331756)
		(mid 88.285948 -238.37725)
		(end 88.4682 -238.32693)
		(width 0.0889)
		(layer "In2.Cu")
		(net "M_C_CPU1_SA_DQ<20>")
	)
	(arc
		(start 92.794074 -238.32693)
		(mid 92.981018 -238.377185)
		(end 93.167962 -238.32693)
		(width 0.0889)
		(layer "In2.Cu")
		(net "M_C_CPU1_SA_DQ<20>")
	)
	(arc
		(start 81.513934 -238.32693)
		(mid 81.696185 -238.37728)
		(end 81.879694 -238.331756)
		(width 0.0889)
		(layer "In2.Cu")
		(net "M_C_CPU1_SA_DQ<20>")
	)
	(arc
		(start 80.948022 -238.32693)
		(mid 81.230978 -238.250753)
		(end 81.513934 -238.32693)
		(width 0.0889)
		(layer "In2.Cu")
		(net "M_C_CPU1_SA_DQ<20>")
	)
	(arc
		(start 88.4682 -238.32693)
		(mid 88.751156 -238.250753)
		(end 89.034112 -238.32693)
		(width 0.0889)
		(layer "In2.Cu")
		(net "M_C_CPU1_SA_DQ<20>")
	)
	(arc
		(start 90.348054 -238.32693)
		(mid 90.63101 -238.250753)
		(end 90.913966 -238.32693)
		(width 0.0889)
		(layer "In2.Cu")
		(net "M_C_CPU1_SA_DQ<20>")
	)
	(arc
		(start 83.402424 -238.331756)
		(mid 83.585932 -238.37725)
		(end 83.768184 -238.32693)
		(width 0.0889)
		(layer "In2.Cu")
		(net "M_C_CPU1_SA_DQ<20>")
	)
	(arc
		(start 89.034112 -238.32693)
		(mid 89.221056 -238.377185)
		(end 89.408 -238.32693)
		(width 0.0889)
		(layer "In2.Cu")
		(net "M_C_CPU1_SA_DQ<20>")
	)
	(arc
		(start 90.922348 -238.331756)
		(mid 91.105856 -238.37725)
		(end 91.288108 -238.32693)
		(width 0.0889)
		(layer "In2.Cu")
		(net "M_C_CPU1_SA_DQ<20>")
	)
	(arc
		(start 93.167962 -238.32693)
		(mid 93.450918 -238.250753)
		(end 93.733874 -238.32693)
		(width 0.0889)
		(layer "In2.Cu")
		(net "M_C_CPU1_SA_DQ<20>")
	)
	(segment
		(start 95.797878 -226.120452)
		(end 95.331026 -225.854514)
		(width 0.10668)
		(layer "F.Cu")
		(net "M_C_CPU1_SA_DQ<1>")
	)
	(segment
		(start 91.749626 -226.18192)
		(end 91.758008 -226.177094)
		(width 0.0889)
		(layer "In2.Cu")
		(net "M_C_CPU1_SA_DQ<1>")
	)
	(segment
		(start 44.340018 -199.035416)
		(end 44.76496 -198.610474)
		(width 0.14478)
		(layer "In2.Cu")
		(net "M_C_CPU1_SA_DQ<1>")
	)
	(segment
		(start 73.11136 -209.594704)
		(end 74.149712 -209.594704)
		(width 0.14478)
		(layer "In2.Cu")
		(net "M_C_CPU1_SA_DQ<1>")
	)
	(segment
		(start 87.989664 -226.18192)
		(end 87.998046 -226.177094)
		(width 0.0889)
		(layer "In2.Cu")
		(net "M_C_CPU1_SA_DQ<1>")
	)
	(segment
		(start 49.366678 -198.292466)
		(end 49.525682 -198.45147)
		(width 0.14478)
		(layer "In2.Cu")
		(net "M_C_CPU1_SA_DQ<1>")
	)
	(segment
		(start 89.504012 -226.177094)
		(end 89.512394 -226.18192)
		(width 0.0889)
		(layer "In2.Cu")
		(net "M_C_CPU1_SA_DQ<1>")
	)
	(segment
		(start 95.48495 -226.119944)
		(end 95.331026 -225.854514)
		(width 0.0889)
		(layer "In2.Cu")
		(net "M_C_CPU1_SA_DQ<1>")
	)
	(segment
		(start 49.525682 -198.45147)
		(end 49.525682 -198.769478)
		(width 0.14478)
		(layer "In2.Cu")
		(net "M_C_CPU1_SA_DQ<1>")
	)
	(segment
		(start 50.077116 -198.769478)
		(end 50.077116 -198.45147)
		(width 0.14478)
		(layer "In2.Cu")
		(net "M_C_CPU1_SA_DQ<1>")
	)
	(segment
		(start 95.462598 -226.203256)
		(end 95.48495 -226.119944)
		(width 0.0889)
		(layer "In2.Cu")
		(net "M_C_CPU1_SA_DQ<1>")
	)
	(segment
		(start 76.6318 -212.076792)
		(end 76.6318 -213.790784)
		(width 0.14478)
		(layer "In2.Cu")
		(net "M_C_CPU1_SA_DQ<1>")
	)
	(segment
		(start 53.99405 -198.209916)
		(end 54.157118 -198.372984)
		(width 0.14478)
		(layer "In2.Cu")
		(net "M_C_CPU1_SA_DQ<1>")
	)
	(segment
		(start 50.077116 -198.45147)
		(end 50.23612 -198.292466)
		(width 0.14478)
		(layer "In2.Cu")
		(net "M_C_CPU1_SA_DQ<1>")
	)
	(segment
		(start 48.815244 -198.610474)
		(end 49.133252 -198.292466)
		(width 0.14478)
		(layer "In2.Cu")
		(net "M_C_CPU1_SA_DQ<1>")
	)
	(segment
		(start 92.68968 -226.18192)
		(end 92.698062 -226.177094)
		(width 0.0889)
		(layer "In2.Cu")
		(net "M_C_CPU1_SA_DQ<1>")
	)
	(segment
		(start 52.881022 -198.610474)
		(end 53.04409 -198.773542)
		(width 0.14478)
		(layer "In2.Cu")
		(net "M_C_CPU1_SA_DQ<1>")
	)
	(segment
		(start 74.149712 -209.594704)
		(end 76.6318 -212.076792)
		(width 0.14478)
		(layer "In2.Cu")
		(net "M_C_CPU1_SA_DQ<1>")
	)
	(segment
		(start 55.830724 -198.610474)
		(end 55.993792 -198.773542)
		(width 0.14478)
		(layer "In2.Cu")
		(net "M_C_CPU1_SA_DQ<1>")
	)
	(segment
		(start 56.550306 -198.834756)
		(end 56.550306 -198.372984)
		(width 0.14478)
		(layer "In2.Cu")
		(net "M_C_CPU1_SA_DQ<1>")
	)
	(segment
		(start 94.204028 -226.177094)
		(end 94.21241 -226.18192)
		(width 0.0889)
		(layer "In2.Cu")
		(net "M_C_CPU1_SA_DQ<1>")
	)
	(segment
		(start 53.04409 -198.829676)
		(end 53.207158 -198.992744)
		(width 0.14478)
		(layer "In2.Cu")
		(net "M_C_CPU1_SA_DQ<1>")
	)
	(segment
		(start 81.594706 -222.05823)
		(end 81.796382 -222.259906)
		(width 0.0889)
		(layer "In2.Cu")
		(net "M_C_CPU1_SA_DQ<1>")
	)
	(segment
		(start 56.943752 -198.209916)
		(end 57.10682 -198.372984)
		(width 0.14478)
		(layer "In2.Cu")
		(net "M_C_CPU1_SA_DQ<1>")
	)
	(segment
		(start 54.550564 -198.992744)
		(end 54.713632 -198.829676)
		(width 0.14478)
		(layer "In2.Cu")
		(net "M_C_CPU1_SA_DQ<1>")
	)
	(segment
		(start 55.993792 -198.773542)
		(end 55.993792 -198.834756)
		(width 0.14478)
		(layer "In2.Cu")
		(net "M_C_CPU1_SA_DQ<1>")
	)
	(segment
		(start 53.207158 -198.992744)
		(end 53.437536 -198.992744)
		(width 0.14478)
		(layer "In2.Cu")
		(net "M_C_CPU1_SA_DQ<1>")
	)
	(segment
		(start 81.594706 -221.215204)
		(end 81.594706 -222.05823)
		(width 0.0889)
		(layer "In2.Cu")
		(net "M_C_CPU1_SA_DQ<1>")
	)
	(segment
		(start 53.04409 -198.773542)
		(end 53.04409 -198.829676)
		(width 0.14478)
		(layer "In2.Cu")
		(net "M_C_CPU1_SA_DQ<1>")
	)
	(segment
		(start 49.525682 -198.769478)
		(end 49.684686 -198.928482)
		(width 0.14478)
		(layer "In2.Cu")
		(net "M_C_CPU1_SA_DQ<1>")
	)
	(segment
		(start 57.663334 -198.773542)
		(end 57.826402 -198.610474)
		(width 0.14478)
		(layer "In2.Cu")
		(net "M_C_CPU1_SA_DQ<1>")
	)
	(segment
		(start 50.787554 -198.610474)
		(end 52.881022 -198.610474)
		(width 0.14478)
		(layer "In2.Cu")
		(net "M_C_CPU1_SA_DQ<1>")
	)
	(segment
		(start 56.15686 -198.997824)
		(end 56.387238 -198.997824)
		(width 0.14478)
		(layer "In2.Cu")
		(net "M_C_CPU1_SA_DQ<1>")
	)
	(segment
		(start 82.893408 -224.539302)
		(end 82.923888 -224.557082)
		(width 0.0889)
		(layer "In2.Cu")
		(net "M_C_CPU1_SA_DQ<1>")
	)
	(segment
		(start 53.437536 -198.992744)
		(end 53.600604 -198.829676)
		(width 0.14478)
		(layer "In2.Cu")
		(net "M_C_CPU1_SA_DQ<1>")
	)
	(segment
		(start 56.550306 -198.372984)
		(end 56.713374 -198.209916)
		(width 0.14478)
		(layer "In2.Cu")
		(net "M_C_CPU1_SA_DQ<1>")
	)
	(segment
		(start 81.984088 -222.93707)
		(end 82.02041 -222.958152)
		(width 0.0889)
		(layer "In2.Cu")
		(net "M_C_CPU1_SA_DQ<1>")
	)
	(segment
		(start 54.713632 -198.829676)
		(end 54.713632 -198.773542)
		(width 0.14478)
		(layer "In2.Cu")
		(net "M_C_CPU1_SA_DQ<1>")
	)
	(segment
		(start 54.157118 -198.829676)
		(end 54.320186 -198.992744)
		(width 0.14478)
		(layer "In2.Cu")
		(net "M_C_CPU1_SA_DQ<1>")
	)
	(segment
		(start 83.833462 -226.159314)
		(end 83.863942 -226.177094)
		(width 0.0889)
		(layer "In2.Cu")
		(net "M_C_CPU1_SA_DQ<1>")
	)
	(segment
		(start 50.23612 -198.292466)
		(end 50.469546 -198.292466)
		(width 0.14478)
		(layer "In2.Cu")
		(net "M_C_CPU1_SA_DQ<1>")
	)
	(segment
		(start 57.10682 -198.834756)
		(end 57.269888 -198.997824)
		(width 0.14478)
		(layer "In2.Cu")
		(net "M_C_CPU1_SA_DQ<1>")
	)
	(segment
		(start 54.8767 -198.610474)
		(end 55.830724 -198.610474)
		(width 0.14478)
		(layer "In2.Cu")
		(net "M_C_CPU1_SA_DQ<1>")
	)
	(segment
		(start 54.713632 -198.773542)
		(end 54.8767 -198.610474)
		(width 0.14478)
		(layer "In2.Cu")
		(net "M_C_CPU1_SA_DQ<1>")
	)
	(segment
		(start 82.923888 -224.557082)
		(end 82.963004 -224.579942)
		(width 0.0889)
		(layer "In2.Cu")
		(net "M_C_CPU1_SA_DQ<1>")
	)
	(segment
		(start 49.684686 -198.928482)
		(end 49.918112 -198.928482)
		(width 0.14478)
		(layer "In2.Cu")
		(net "M_C_CPU1_SA_DQ<1>")
	)
	(segment
		(start 49.133252 -198.292466)
		(end 49.366678 -198.292466)
		(width 0.14478)
		(layer "In2.Cu")
		(net "M_C_CPU1_SA_DQ<1>")
	)
	(segment
		(start 88.929718 -226.18192)
		(end 88.9381 -226.177094)
		(width 0.0889)
		(layer "In2.Cu")
		(net "M_C_CPU1_SA_DQ<1>")
	)
	(segment
		(start 83.362292 -225.3488)
		(end 83.394042 -225.367088)
		(width 0.0889)
		(layer "In2.Cu")
		(net "M_C_CPU1_SA_DQ<1>")
	)
	(segment
		(start 76.6318 -213.790784)
		(end 81.594706 -218.75369)
		(width 0.14478)
		(layer "In2.Cu")
		(net "M_C_CPU1_SA_DQ<1>")
	)
	(segment
		(start 44.76496 -198.610474)
		(end 48.815244 -198.610474)
		(width 0.14478)
		(layer "In2.Cu")
		(net "M_C_CPU1_SA_DQ<1>")
	)
	(segment
		(start 49.918112 -198.928482)
		(end 50.077116 -198.769478)
		(width 0.14478)
		(layer "In2.Cu")
		(net "M_C_CPU1_SA_DQ<1>")
	)
	(segment
		(start 53.600604 -198.372984)
		(end 53.763672 -198.209916)
		(width 0.14478)
		(layer "In2.Cu")
		(net "M_C_CPU1_SA_DQ<1>")
	)
	(segment
		(start 56.387238 -198.997824)
		(end 56.550306 -198.834756)
		(width 0.14478)
		(layer "In2.Cu")
		(net "M_C_CPU1_SA_DQ<1>")
	)
	(segment
		(start 57.500266 -198.997824)
		(end 57.663334 -198.834756)
		(width 0.14478)
		(layer "In2.Cu")
		(net "M_C_CPU1_SA_DQ<1>")
	)
	(segment
		(start 57.10682 -198.372984)
		(end 57.10682 -198.834756)
		(width 0.14478)
		(layer "In2.Cu")
		(net "M_C_CPU1_SA_DQ<1>")
	)
	(segment
		(start 57.663334 -198.834756)
		(end 57.663334 -198.773542)
		(width 0.14478)
		(layer "In2.Cu")
		(net "M_C_CPU1_SA_DQ<1>")
	)
	(segment
		(start 50.469546 -198.292466)
		(end 50.787554 -198.610474)
		(width 0.14478)
		(layer "In2.Cu")
		(net "M_C_CPU1_SA_DQ<1>")
	)
	(segment
		(start 81.594706 -218.75369)
		(end 81.594706 -221.215204)
		(width 0.14478)
		(layer "In2.Cu")
		(net "M_C_CPU1_SA_DQ<1>")
	)
	(segment
		(start 84.803996 -226.177094)
		(end 84.812378 -226.18192)
		(width 0.0889)
		(layer "In2.Cu")
		(net "M_C_CPU1_SA_DQ<1>")
	)
	(segment
		(start 85.74405 -226.177094)
		(end 85.752432 -226.18192)
		(width 0.0889)
		(layer "In2.Cu")
		(net "M_C_CPU1_SA_DQ<1>")
	)
	(segment
		(start 57.269888 -198.997824)
		(end 57.500266 -198.997824)
		(width 0.14478)
		(layer "In2.Cu")
		(net "M_C_CPU1_SA_DQ<1>")
	)
	(segment
		(start 53.600604 -198.829676)
		(end 53.600604 -198.372984)
		(width 0.14478)
		(layer "In2.Cu")
		(net "M_C_CPU1_SA_DQ<1>")
	)
	(segment
		(start 55.993792 -198.834756)
		(end 56.15686 -198.997824)
		(width 0.14478)
		(layer "In2.Cu")
		(net "M_C_CPU1_SA_DQ<1>")
	)
	(segment
		(start 57.826402 -198.610474)
		(end 62.12713 -198.610474)
		(width 0.14478)
		(layer "In2.Cu")
		(net "M_C_CPU1_SA_DQ<1>")
	)
	(segment
		(start 82.453988 -223.747076)
		(end 82.493104 -223.769936)
		(width 0.0889)
		(layer "In2.Cu")
		(net "M_C_CPU1_SA_DQ<1>")
	)
	(segment
		(start 53.763672 -198.209916)
		(end 53.99405 -198.209916)
		(width 0.14478)
		(layer "In2.Cu")
		(net "M_C_CPU1_SA_DQ<1>")
	)
	(segment
		(start 93.263974 -226.177094)
		(end 93.272356 -226.18192)
		(width 0.0889)
		(layer "In2.Cu")
		(net "M_C_CPU1_SA_DQ<1>")
	)
	(segment
		(start 81.796382 -222.259906)
		(end 81.796382 -222.61449)
		(width 0.0889)
		(layer "In2.Cu")
		(net "M_C_CPU1_SA_DQ<1>")
	)
	(segment
		(start 54.320186 -198.992744)
		(end 54.550564 -198.992744)
		(width 0.14478)
		(layer "In2.Cu")
		(net "M_C_CPU1_SA_DQ<1>")
	)
	(segment
		(start 62.12713 -198.610474)
		(end 73.11136 -209.594704)
		(width 0.14478)
		(layer "In2.Cu")
		(net "M_C_CPU1_SA_DQ<1>")
	)
	(segment
		(start 83.394042 -225.367088)
		(end 83.433158 -225.389948)
		(width 0.0889)
		(layer "In2.Cu")
		(net "M_C_CPU1_SA_DQ<1>")
	)
	(segment
		(start 84.229702 -226.18192)
		(end 84.238084 -226.177094)
		(width 0.0889)
		(layer "In2.Cu")
		(net "M_C_CPU1_SA_DQ<1>")
	)
	(segment
		(start 56.713374 -198.209916)
		(end 56.943752 -198.209916)
		(width 0.14478)
		(layer "In2.Cu")
		(net "M_C_CPU1_SA_DQ<1>")
	)
	(segment
		(start 82.422238 -223.728788)
		(end 82.453988 -223.747076)
		(width 0.0889)
		(layer "In2.Cu")
		(net "M_C_CPU1_SA_DQ<1>")
	)
	(segment
		(start 81.952338 -222.918782)
		(end 81.984088 -222.93707)
		(width 0.0889)
		(layer "In2.Cu")
		(net "M_C_CPU1_SA_DQ<1>")
	)
	(segment
		(start 54.157118 -198.372984)
		(end 54.157118 -198.829676)
		(width 0.14478)
		(layer "In2.Cu")
		(net "M_C_CPU1_SA_DQ<1>")
	)
	(arc
		(start 87.998046 -226.177094)
		(mid 88.281002 -226.100917)
		(end 88.563958 -226.177094)
		(width 0.0889)
		(layer "In2.Cu")
		(net "M_C_CPU1_SA_DQ<1>")
	)
	(arc
		(start 92.32392 -226.177094)
		(mid 92.506171 -226.227444)
		(end 92.68968 -226.18192)
		(width 0.0889)
		(layer "In2.Cu")
		(net "M_C_CPU1_SA_DQ<1>")
	)
	(arc
		(start 85.752432 -226.18192)
		(mid 85.93594 -226.227414)
		(end 86.118192 -226.177094)
		(width 0.0889)
		(layer "In2.Cu")
		(net "M_C_CPU1_SA_DQ<1>")
	)
	(arc
		(start 94.57817 -226.177094)
		(mid 94.861126 -226.100917)
		(end 95.144082 -226.177094)
		(width 0.0889)
		(layer "In2.Cu")
		(net "M_C_CPU1_SA_DQ<1>")
	)
	(arc
		(start 85.178138 -226.177094)
		(mid 85.461094 -226.100917)
		(end 85.74405 -226.177094)
		(width 0.0889)
		(layer "In2.Cu")
		(net "M_C_CPU1_SA_DQ<1>")
	)
	(arc
		(start 93.638116 -226.177094)
		(mid 93.921072 -226.100917)
		(end 94.204028 -226.177094)
		(width 0.0889)
		(layer "In2.Cu")
		(net "M_C_CPU1_SA_DQ<1>")
	)
	(arc
		(start 82.493104 -223.769936)
		(mid 82.671917 -223.972286)
		(end 82.736436 -224.234502)
		(width 0.0889)
		(layer "In2.Cu")
		(net "M_C_CPU1_SA_DQ<1>")
	)
	(arc
		(start 87.057992 -226.177094)
		(mid 87.340948 -226.100917)
		(end 87.623904 -226.177094)
		(width 0.0889)
		(layer "In2.Cu")
		(net "M_C_CPU1_SA_DQ<1>")
	)
	(arc
		(start 81.796382 -222.61449)
		(mid 81.837637 -222.785461)
		(end 81.952338 -222.918782)
		(width 0.0889)
		(layer "In2.Cu")
		(net "M_C_CPU1_SA_DQ<1>")
	)
	(arc
		(start 83.206336 -225.044508)
		(mid 83.247591 -225.215479)
		(end 83.362292 -225.3488)
		(width 0.0889)
		(layer "In2.Cu")
		(net "M_C_CPU1_SA_DQ<1>")
	)
	(arc
		(start 82.736436 -224.234502)
		(mid 82.777985 -224.405924)
		(end 82.893408 -224.539302)
		(width 0.0889)
		(layer "In2.Cu")
		(net "M_C_CPU1_SA_DQ<1>")
	)
	(arc
		(start 95.144082 -226.177094)
		(mid 95.300401 -226.226089)
		(end 95.462598 -226.203256)
		(width 0.0889)
		(layer "In2.Cu")
		(net "M_C_CPU1_SA_DQ<1>")
	)
	(arc
		(start 93.272356 -226.18192)
		(mid 93.455864 -226.227414)
		(end 93.638116 -226.177094)
		(width 0.0889)
		(layer "In2.Cu")
		(net "M_C_CPU1_SA_DQ<1>")
	)
	(arc
		(start 92.698062 -226.177094)
		(mid 92.981018 -226.100917)
		(end 93.263974 -226.177094)
		(width 0.0889)
		(layer "In2.Cu")
		(net "M_C_CPU1_SA_DQ<1>")
	)
	(arc
		(start 91.758008 -226.177094)
		(mid 92.040964 -226.100917)
		(end 92.32392 -226.177094)
		(width 0.0889)
		(layer "In2.Cu")
		(net "M_C_CPU1_SA_DQ<1>")
	)
	(arc
		(start 91.383866 -226.177094)
		(mid 91.566117 -226.227444)
		(end 91.749626 -226.18192)
		(width 0.0889)
		(layer "In2.Cu")
		(net "M_C_CPU1_SA_DQ<1>")
	)
	(arc
		(start 89.512394 -226.18192)
		(mid 89.695902 -226.227414)
		(end 89.878154 -226.177094)
		(width 0.0889)
		(layer "In2.Cu")
		(net "M_C_CPU1_SA_DQ<1>")
	)
	(arc
		(start 87.623904 -226.177094)
		(mid 87.806155 -226.227444)
		(end 87.989664 -226.18192)
		(width 0.0889)
		(layer "In2.Cu")
		(net "M_C_CPU1_SA_DQ<1>")
	)
	(arc
		(start 83.433158 -225.389948)
		(mid 83.611971 -225.592298)
		(end 83.67649 -225.854514)
		(width 0.0889)
		(layer "In2.Cu")
		(net "M_C_CPU1_SA_DQ<1>")
	)
	(arc
		(start 94.21241 -226.18192)
		(mid 94.395918 -226.227414)
		(end 94.57817 -226.177094)
		(width 0.0889)
		(layer "In2.Cu")
		(net "M_C_CPU1_SA_DQ<1>")
	)
	(arc
		(start 86.118192 -226.177094)
		(mid 86.401148 -226.100917)
		(end 86.684104 -226.177094)
		(width 0.0889)
		(layer "In2.Cu")
		(net "M_C_CPU1_SA_DQ<1>")
	)
	(arc
		(start 89.878154 -226.177094)
		(mid 90.16111 -226.100917)
		(end 90.444066 -226.177094)
		(width 0.0889)
		(layer "In2.Cu")
		(net "M_C_CPU1_SA_DQ<1>")
	)
	(arc
		(start 90.444066 -226.177094)
		(mid 90.63101 -226.227349)
		(end 90.817954 -226.177094)
		(width 0.0889)
		(layer "In2.Cu")
		(net "M_C_CPU1_SA_DQ<1>")
	)
	(arc
		(start 82.266282 -223.424496)
		(mid 82.307537 -223.595467)
		(end 82.422238 -223.728788)
		(width 0.0889)
		(layer "In2.Cu")
		(net "M_C_CPU1_SA_DQ<1>")
	)
	(arc
		(start 82.02041 -222.958152)
		(mid 82.201062 -223.160897)
		(end 82.266282 -223.424496)
		(width 0.0889)
		(layer "In2.Cu")
		(net "M_C_CPU1_SA_DQ<1>")
	)
	(arc
		(start 88.9381 -226.177094)
		(mid 89.221056 -226.100917)
		(end 89.504012 -226.177094)
		(width 0.0889)
		(layer "In2.Cu")
		(net "M_C_CPU1_SA_DQ<1>")
	)
	(arc
		(start 84.238084 -226.177094)
		(mid 84.52104 -226.100917)
		(end 84.803996 -226.177094)
		(width 0.0889)
		(layer "In2.Cu")
		(net "M_C_CPU1_SA_DQ<1>")
	)
	(arc
		(start 83.863942 -226.177094)
		(mid 84.046193 -226.227444)
		(end 84.229702 -226.18192)
		(width 0.0889)
		(layer "In2.Cu")
		(net "M_C_CPU1_SA_DQ<1>")
	)
	(arc
		(start 83.67649 -225.854514)
		(mid 83.718039 -226.025936)
		(end 83.833462 -226.159314)
		(width 0.0889)
		(layer "In2.Cu")
		(net "M_C_CPU1_SA_DQ<1>")
	)
	(arc
		(start 90.817954 -226.177094)
		(mid 91.10091 -226.100917)
		(end 91.383866 -226.177094)
		(width 0.0889)
		(layer "In2.Cu")
		(net "M_C_CPU1_SA_DQ<1>")
	)
	(arc
		(start 86.684104 -226.177094)
		(mid 86.871048 -226.227349)
		(end 87.057992 -226.177094)
		(width 0.0889)
		(layer "In2.Cu")
		(net "M_C_CPU1_SA_DQ<1>")
	)
	(arc
		(start 84.812378 -226.18192)
		(mid 84.995886 -226.227414)
		(end 85.178138 -226.177094)
		(width 0.0889)
		(layer "In2.Cu")
		(net "M_C_CPU1_SA_DQ<1>")
	)
	(arc
		(start 88.563958 -226.177094)
		(mid 88.746209 -226.227444)
		(end 88.929718 -226.18192)
		(width 0.0889)
		(layer "In2.Cu")
		(net "M_C_CPU1_SA_DQ<1>")
	)
	(arc
		(start 82.963004 -224.579942)
		(mid 83.141817 -224.782292)
		(end 83.206336 -225.044508)
		(width 0.0889)
		(layer "In2.Cu")
		(net "M_C_CPU1_SA_DQ<1>")
	)
	(segment
		(start 96.267778 -236.650276)
		(end 95.800926 -236.384338)
		(width 0.10668)
		(layer "F.Cu")
		(net "M_C_CPU1_SA_DQ<19>")
	)
	(segment
		(start 70.926706 -228.738684)
		(end 75.943206 -233.755184)
		(width 0.14478)
		(layer "In2.Cu")
		(net "M_C_CPU1_SA_DQ<19>")
	)
	(segment
		(start 87.154004 -236.061758)
		(end 87.162386 -236.056932)
		(width 0.0889)
		(layer "In2.Cu")
		(net "M_C_CPU1_SA_DQ<19>")
	)
	(segment
		(start 53.722524 -218.712288)
		(end 54.44236 -219.010484)
		(width 0.14478)
		(layer "In2.Cu")
		(net "M_C_CPU1_SA_DQ<19>")
	)
	(segment
		(start 49.143412 -218.840304)
		(end 49.86401 -218.35872)
		(width 0.14478)
		(layer "In2.Cu")
		(net "M_C_CPU1_SA_DQ<19>")
	)
	(segment
		(start 57.58053 -218.327732)
		(end 57.98439 -218.160346)
		(width 0.14478)
		(layer "In2.Cu")
		(net "M_C_CPU1_SA_DQ<19>")
	)
	(segment
		(start 62.976252 -218.160346)
		(end 65.193926 -220.37802)
		(width 0.14478)
		(layer "In2.Cu")
		(net "M_C_CPU1_SA_DQ<19>")
	)
	(segment
		(start 70.926706 -227.397564)
		(end 70.926706 -228.738684)
		(width 0.14478)
		(layer "In2.Cu")
		(net "M_C_CPU1_SA_DQ<19>")
	)
	(segment
		(start 90.913966 -236.061758)
		(end 90.922348 -236.056932)
		(width 0.0889)
		(layer "In2.Cu")
		(net "M_C_CPU1_SA_DQ<19>")
	)
	(segment
		(start 94.099634 -236.056932)
		(end 94.108016 -236.061758)
		(width 0.0889)
		(layer "In2.Cu")
		(net "M_C_CPU1_SA_DQ<19>")
	)
	(segment
		(start 78.151228 -235.086906)
		(end 78.51267 -235.086906)
		(width 0.0889)
		(layer "In2.Cu")
		(net "M_C_CPU1_SA_DQ<19>")
	)
	(segment
		(start 56.303418 -219.010484)
		(end 57.58053 -218.327732)
		(width 0.14478)
		(layer "In2.Cu")
		(net "M_C_CPU1_SA_DQ<19>")
	)
	(segment
		(start 76.588366 -234.186984)
		(end 77.251306 -234.186984)
		(width 0.0889)
		(layer "In2.Cu")
		(net "M_C_CPU1_SA_DQ<19>")
	)
	(segment
		(start 49.86401 -218.35872)
		(end 50.366422 -218.150694)
		(width 0.14478)
		(layer "In2.Cu")
		(net "M_C_CPU1_SA_DQ<19>")
	)
	(segment
		(start 77.251306 -234.186984)
		(end 78.151228 -235.086906)
		(width 0.0889)
		(layer "In2.Cu")
		(net "M_C_CPU1_SA_DQ<19>")
	)
	(segment
		(start 90.339672 -236.056932)
		(end 90.348054 -236.061758)
		(width 0.0889)
		(layer "In2.Cu")
		(net "M_C_CPU1_SA_DQ<19>")
	)
	(segment
		(start 85.639656 -236.056932)
		(end 85.648038 -236.061758)
		(width 0.0889)
		(layer "In2.Cu")
		(net "M_C_CPU1_SA_DQ<19>")
	)
	(segment
		(start 50.366422 -218.150694)
		(end 53.006244 -218.150694)
		(width 0.14478)
		(layer "In2.Cu")
		(net "M_C_CPU1_SA_DQ<19>")
	)
	(segment
		(start 76.156566 -233.755184)
		(end 76.588366 -234.186984)
		(width 0.0889)
		(layer "In2.Cu")
		(net "M_C_CPU1_SA_DQ<19>")
	)
	(segment
		(start 95.647002 -236.118908)
		(end 95.800926 -236.384338)
		(width 0.0889)
		(layer "In2.Cu")
		(net "M_C_CPU1_SA_DQ<19>")
	)
	(segment
		(start 54.44236 -219.010484)
		(end 56.303418 -219.010484)
		(width 0.14478)
		(layer "In2.Cu")
		(net "M_C_CPU1_SA_DQ<19>")
	)
	(segment
		(start 40.65524 -219.000578)
		(end 48.75657 -219.000578)
		(width 0.14478)
		(layer "In2.Cu")
		(net "M_C_CPU1_SA_DQ<19>")
	)
	(segment
		(start 95.55099 -236.093508)
		(end 95.647002 -236.118908)
		(width 0.0889)
		(layer "In2.Cu")
		(net "M_C_CPU1_SA_DQ<19>")
	)
	(segment
		(start 95.039688 -236.056932)
		(end 95.04807 -236.061758)
		(width 0.0889)
		(layer "In2.Cu")
		(net "M_C_CPU1_SA_DQ<19>")
	)
	(segment
		(start 81.879694 -236.056932)
		(end 81.888076 -236.061758)
		(width 0.0889)
		(layer "In2.Cu")
		(net "M_C_CPU1_SA_DQ<19>")
	)
	(segment
		(start 40.23995 -218.585288)
		(end 40.65524 -219.000578)
		(width 0.14478)
		(layer "In2.Cu")
		(net "M_C_CPU1_SA_DQ<19>")
	)
	(segment
		(start 79.44358 -236.017816)
		(end 79.864966 -236.017816)
		(width 0.0889)
		(layer "In2.Cu")
		(net "M_C_CPU1_SA_DQ<19>")
	)
	(segment
		(start 82.453988 -236.061758)
		(end 82.46237 -236.056932)
		(width 0.0889)
		(layer "In2.Cu")
		(net "M_C_CPU1_SA_DQ<19>")
	)
	(segment
		(start 53.006244 -218.150694)
		(end 53.270404 -218.260168)
		(width 0.14478)
		(layer "In2.Cu")
		(net "M_C_CPU1_SA_DQ<19>")
	)
	(segment
		(start 88.094058 -236.061758)
		(end 88.10244 -236.056932)
		(width 0.0889)
		(layer "In2.Cu")
		(net "M_C_CPU1_SA_DQ<19>")
	)
	(segment
		(start 86.57971 -236.056932)
		(end 86.588092 -236.061758)
		(width 0.0889)
		(layer "In2.Cu")
		(net "M_C_CPU1_SA_DQ<19>")
	)
	(segment
		(start 48.75657 -219.000578)
		(end 49.143412 -218.840304)
		(width 0.14478)
		(layer "In2.Cu")
		(net "M_C_CPU1_SA_DQ<19>")
	)
	(segment
		(start 53.270404 -218.260168)
		(end 53.722524 -218.712288)
		(width 0.14478)
		(layer "In2.Cu")
		(net "M_C_CPU1_SA_DQ<19>")
	)
	(segment
		(start 75.943206 -233.755184)
		(end 76.156566 -233.755184)
		(width 0.0889)
		(layer "In2.Cu")
		(net "M_C_CPU1_SA_DQ<19>")
	)
	(segment
		(start 57.98439 -218.160346)
		(end 62.976252 -218.160346)
		(width 0.14478)
		(layer "In2.Cu")
		(net "M_C_CPU1_SA_DQ<19>")
	)
	(segment
		(start 78.51267 -235.086906)
		(end 79.44358 -236.017816)
		(width 0.0889)
		(layer "In2.Cu")
		(net "M_C_CPU1_SA_DQ<19>")
	)
	(segment
		(start 65.193926 -221.664784)
		(end 70.926706 -227.397564)
		(width 0.14478)
		(layer "In2.Cu")
		(net "M_C_CPU1_SA_DQ<19>")
	)
	(segment
		(start 65.193926 -220.37802)
		(end 65.193926 -221.664784)
		(width 0.14478)
		(layer "In2.Cu")
		(net "M_C_CPU1_SA_DQ<19>")
	)
	(segment
		(start 91.85402 -236.061758)
		(end 91.862402 -236.056932)
		(width 0.0889)
		(layer "In2.Cu")
		(net "M_C_CPU1_SA_DQ<19>")
	)
	(segment
		(start 83.394042 -236.061758)
		(end 83.402424 -236.056932)
		(width 0.0889)
		(layer "In2.Cu")
		(net "M_C_CPU1_SA_DQ<19>")
	)
	(arc
		(start 89.973912 -236.061758)
		(mid 90.156163 -236.011408)
		(end 90.339672 -236.056932)
		(width 0.0889)
		(layer "In2.Cu")
		(net "M_C_CPU1_SA_DQ<19>")
	)
	(arc
		(start 80.008222 -236.061758)
		(mid 80.291178 -236.137935)
		(end 80.574134 -236.061758)
		(width 0.0889)
		(layer "In2.Cu")
		(net "M_C_CPU1_SA_DQ<19>")
	)
	(arc
		(start 93.733874 -236.061758)
		(mid 93.916125 -236.011408)
		(end 94.099634 -236.056932)
		(width 0.0889)
		(layer "In2.Cu")
		(net "M_C_CPU1_SA_DQ<19>")
	)
	(arc
		(start 82.82813 -236.061758)
		(mid 83.111086 -236.137935)
		(end 83.394042 -236.061758)
		(width 0.0889)
		(layer "In2.Cu")
		(net "M_C_CPU1_SA_DQ<19>")
	)
	(arc
		(start 79.926688 -236.026706)
		(mid 79.968503 -236.041794)
		(end 80.008222 -236.061758)
		(width 0.0889)
		(layer "In2.Cu")
		(net "M_C_CPU1_SA_DQ<19>")
	)
	(arc
		(start 88.10244 -236.056932)
		(mid 88.285948 -236.011438)
		(end 88.4682 -236.061758)
		(width 0.0889)
		(layer "In2.Cu")
		(net "M_C_CPU1_SA_DQ<19>")
	)
	(arc
		(start 86.588092 -236.061758)
		(mid 86.871048 -236.137935)
		(end 87.154004 -236.061758)
		(width 0.0889)
		(layer "In2.Cu")
		(net "M_C_CPU1_SA_DQ<19>")
	)
	(arc
		(start 82.46237 -236.056932)
		(mid 82.645878 -236.011438)
		(end 82.82813 -236.061758)
		(width 0.0889)
		(layer "In2.Cu")
		(net "M_C_CPU1_SA_DQ<19>")
	)
	(arc
		(start 92.794074 -236.061758)
		(mid 92.981018 -236.011503)
		(end 93.167962 -236.061758)
		(width 0.0889)
		(layer "In2.Cu")
		(net "M_C_CPU1_SA_DQ<19>")
	)
	(arc
		(start 85.273896 -236.061758)
		(mid 85.456147 -236.011408)
		(end 85.639656 -236.056932)
		(width 0.0889)
		(layer "In2.Cu")
		(net "M_C_CPU1_SA_DQ<19>")
	)
	(arc
		(start 95.04807 -236.061758)
		(mid 95.295783 -236.136978)
		(end 95.55099 -236.093508)
		(width 0.0889)
		(layer "In2.Cu")
		(net "M_C_CPU1_SA_DQ<19>")
	)
	(arc
		(start 93.167962 -236.061758)
		(mid 93.450918 -236.137935)
		(end 93.733874 -236.061758)
		(width 0.0889)
		(layer "In2.Cu")
		(net "M_C_CPU1_SA_DQ<19>")
	)
	(arc
		(start 91.288108 -236.061758)
		(mid 91.571064 -236.137935)
		(end 91.85402 -236.061758)
		(width 0.0889)
		(layer "In2.Cu")
		(net "M_C_CPU1_SA_DQ<19>")
	)
	(arc
		(start 80.948022 -236.061758)
		(mid 81.230978 -236.137935)
		(end 81.513934 -236.061758)
		(width 0.0889)
		(layer "In2.Cu")
		(net "M_C_CPU1_SA_DQ<19>")
	)
	(arc
		(start 79.864966 -236.017816)
		(mid 79.896143 -236.020058)
		(end 79.926688 -236.026706)
		(width 0.0889)
		(layer "In2.Cu")
		(net "M_C_CPU1_SA_DQ<19>")
	)
	(arc
		(start 92.228162 -236.061758)
		(mid 92.511118 -236.137935)
		(end 92.794074 -236.061758)
		(width 0.0889)
		(layer "In2.Cu")
		(net "M_C_CPU1_SA_DQ<19>")
	)
	(arc
		(start 84.334096 -236.061758)
		(mid 84.52104 -236.011503)
		(end 84.707984 -236.061758)
		(width 0.0889)
		(layer "In2.Cu")
		(net "M_C_CPU1_SA_DQ<19>")
	)
	(arc
		(start 94.673928 -236.061758)
		(mid 94.856179 -236.011408)
		(end 95.039688 -236.056932)
		(width 0.0889)
		(layer "In2.Cu")
		(net "M_C_CPU1_SA_DQ<19>")
	)
	(arc
		(start 94.108016 -236.061758)
		(mid 94.390972 -236.137935)
		(end 94.673928 -236.061758)
		(width 0.0889)
		(layer "In2.Cu")
		(net "M_C_CPU1_SA_DQ<19>")
	)
	(arc
		(start 81.513934 -236.061758)
		(mid 81.696185 -236.011408)
		(end 81.879694 -236.056932)
		(width 0.0889)
		(layer "In2.Cu")
		(net "M_C_CPU1_SA_DQ<19>")
	)
	(arc
		(start 80.574134 -236.061758)
		(mid 80.761078 -236.011503)
		(end 80.948022 -236.061758)
		(width 0.0889)
		(layer "In2.Cu")
		(net "M_C_CPU1_SA_DQ<19>")
	)
	(arc
		(start 81.888076 -236.061758)
		(mid 82.171032 -236.137935)
		(end 82.453988 -236.061758)
		(width 0.0889)
		(layer "In2.Cu")
		(net "M_C_CPU1_SA_DQ<19>")
	)
	(arc
		(start 90.348054 -236.061758)
		(mid 90.63101 -236.137935)
		(end 90.913966 -236.061758)
		(width 0.0889)
		(layer "In2.Cu")
		(net "M_C_CPU1_SA_DQ<19>")
	)
	(arc
		(start 83.402424 -236.056932)
		(mid 83.585932 -236.011438)
		(end 83.768184 -236.061758)
		(width 0.0889)
		(layer "In2.Cu")
		(net "M_C_CPU1_SA_DQ<19>")
	)
	(arc
		(start 83.768184 -236.061758)
		(mid 84.05114 -236.137935)
		(end 84.334096 -236.061758)
		(width 0.0889)
		(layer "In2.Cu")
		(net "M_C_CPU1_SA_DQ<19>")
	)
	(arc
		(start 86.21395 -236.061758)
		(mid 86.396201 -236.011408)
		(end 86.57971 -236.056932)
		(width 0.0889)
		(layer "In2.Cu")
		(net "M_C_CPU1_SA_DQ<19>")
	)
	(arc
		(start 89.408 -236.061758)
		(mid 89.690956 -236.137935)
		(end 89.973912 -236.061758)
		(width 0.0889)
		(layer "In2.Cu")
		(net "M_C_CPU1_SA_DQ<19>")
	)
	(arc
		(start 84.707984 -236.061758)
		(mid 84.99094 -236.137935)
		(end 85.273896 -236.061758)
		(width 0.0889)
		(layer "In2.Cu")
		(net "M_C_CPU1_SA_DQ<19>")
	)
	(arc
		(start 89.034112 -236.061758)
		(mid 89.221056 -236.011503)
		(end 89.408 -236.061758)
		(width 0.0889)
		(layer "In2.Cu")
		(net "M_C_CPU1_SA_DQ<19>")
	)
	(arc
		(start 90.922348 -236.056932)
		(mid 91.105856 -236.011438)
		(end 91.288108 -236.061758)
		(width 0.0889)
		(layer "In2.Cu")
		(net "M_C_CPU1_SA_DQ<19>")
	)
	(arc
		(start 87.528146 -236.061758)
		(mid 87.811102 -236.137935)
		(end 88.094058 -236.061758)
		(width 0.0889)
		(layer "In2.Cu")
		(net "M_C_CPU1_SA_DQ<19>")
	)
	(arc
		(start 85.648038 -236.061758)
		(mid 85.930994 -236.137935)
		(end 86.21395 -236.061758)
		(width 0.0889)
		(layer "In2.Cu")
		(net "M_C_CPU1_SA_DQ<19>")
	)
	(arc
		(start 91.862402 -236.056932)
		(mid 92.04591 -236.011438)
		(end 92.228162 -236.061758)
		(width 0.0889)
		(layer "In2.Cu")
		(net "M_C_CPU1_SA_DQ<19>")
	)
	(arc
		(start 88.4682 -236.061758)
		(mid 88.751156 -236.137935)
		(end 89.034112 -236.061758)
		(width 0.0889)
		(layer "In2.Cu")
		(net "M_C_CPU1_SA_DQ<19>")
	)
	(arc
		(start 87.162386 -236.056932)
		(mid 87.345894 -236.011438)
		(end 87.528146 -236.061758)
		(width 0.0889)
		(layer "In2.Cu")
		(net "M_C_CPU1_SA_DQ<19>")
	)
	(segment
		(start 94.857824 -235.84027)
		(end 94.390972 -235.574332)
		(width 0.10668)
		(layer "F.Cu")
		(net "M_C_CPU1_SA_DQ<18>")
	)
	(segment
		(start 91.749626 -235.246926)
		(end 91.758008 -235.251752)
		(width 0.0889)
		(layer "In2.Cu")
		(net "M_C_CPU1_SA_DQ<18>")
	)
	(segment
		(start 40.665146 -217.310462)
		(end 41.435528 -217.310462)
		(width 0.14478)
		(layer "In2.Cu")
		(net "M_C_CPU1_SA_DQ<18>")
	)
	(segment
		(start 63.337694 -217.242644)
		(end 66.113406 -220.018356)
		(width 0.14478)
		(layer "In2.Cu")
		(net "M_C_CPU1_SA_DQ<18>")
	)
	(segment
		(start 41.598596 -217.684858)
		(end 41.761664 -217.847926)
		(width 0.14478)
		(layer "In2.Cu")
		(net "M_C_CPU1_SA_DQ<18>")
	)
	(segment
		(start 53.961792 -217.310462)
		(end 56.769508 -217.310462)
		(width 0.14478)
		(layer "In2.Cu")
		(net "M_C_CPU1_SA_DQ<18>")
	)
	(segment
		(start 49.227994 -217.310462)
		(end 50.078132 -216.460324)
		(width 0.14478)
		(layer "In2.Cu")
		(net "M_C_CPU1_SA_DQ<18>")
	)
	(segment
		(start 78.290928 -234.368086)
		(end 78.545944 -234.368086)
		(width 0.0889)
		(layer "In2.Cu")
		(net "M_C_CPU1_SA_DQ<18>")
	)
	(segment
		(start 66.113406 -221.149164)
		(end 71.858124 -226.893882)
		(width 0.14478)
		(layer "In2.Cu")
		(net "M_C_CPU1_SA_DQ<18>")
	)
	(segment
		(start 66.113406 -220.018356)
		(end 66.113406 -221.149164)
		(width 0.14478)
		(layer "In2.Cu")
		(net "M_C_CPU1_SA_DQ<18>")
	)
	(segment
		(start 41.992042 -217.847926)
		(end 42.15511 -217.684858)
		(width 0.14478)
		(layer "In2.Cu")
		(net "M_C_CPU1_SA_DQ<18>")
	)
	(segment
		(start 41.435528 -217.310462)
		(end 41.598596 -217.47353)
		(width 0.14478)
		(layer "In2.Cu")
		(net "M_C_CPU1_SA_DQ<18>")
	)
	(segment
		(start 84.803996 -235.251752)
		(end 84.812378 -235.246926)
		(width 0.0889)
		(layer "In2.Cu")
		(net "M_C_CPU1_SA_DQ<18>")
	)
	(segment
		(start 76.504546 -232.581704)
		(end 78.290928 -234.368086)
		(width 0.0889)
		(layer "In2.Cu")
		(net "M_C_CPU1_SA_DQ<18>")
	)
	(segment
		(start 92.68968 -235.246926)
		(end 92.698062 -235.251752)
		(width 0.0889)
		(layer "In2.Cu")
		(net "M_C_CPU1_SA_DQ<18>")
	)
	(segment
		(start 84.229702 -235.246926)
		(end 84.238084 -235.251752)
		(width 0.0889)
		(layer "In2.Cu")
		(net "M_C_CPU1_SA_DQ<18>")
	)
	(segment
		(start 94.141036 -235.283502)
		(end 94.237048 -235.308902)
		(width 0.0889)
		(layer "In2.Cu")
		(net "M_C_CPU1_SA_DQ<18>")
	)
	(segment
		(start 78.545944 -234.368086)
		(end 79.42961 -235.251752)
		(width 0.0889)
		(layer "In2.Cu")
		(net "M_C_CPU1_SA_DQ<18>")
	)
	(segment
		(start 81.044034 -235.251752)
		(end 81.052416 -235.246926)
		(width 0.0889)
		(layer "In2.Cu")
		(net "M_C_CPU1_SA_DQ<18>")
	)
	(segment
		(start 57.619646 -216.460324)
		(end 60.624974 -216.460324)
		(width 0.14478)
		(layer "In2.Cu")
		(net "M_C_CPU1_SA_DQ<18>")
	)
	(segment
		(start 56.769508 -217.310462)
		(end 57.619646 -216.460324)
		(width 0.14478)
		(layer "In2.Cu")
		(net "M_C_CPU1_SA_DQ<18>")
	)
	(segment
		(start 89.504012 -235.251752)
		(end 89.512394 -235.246926)
		(width 0.0889)
		(layer "In2.Cu")
		(net "M_C_CPU1_SA_DQ<18>")
	)
	(segment
		(start 42.15511 -217.684858)
		(end 42.15511 -217.47353)
		(width 0.14478)
		(layer "In2.Cu")
		(net "M_C_CPU1_SA_DQ<18>")
	)
	(segment
		(start 94.237048 -235.308902)
		(end 94.390972 -235.574332)
		(width 0.0889)
		(layer "In2.Cu")
		(net "M_C_CPU1_SA_DQ<18>")
	)
	(segment
		(start 87.989664 -235.246926)
		(end 87.998046 -235.251752)
		(width 0.0889)
		(layer "In2.Cu")
		(net "M_C_CPU1_SA_DQ<18>")
	)
	(segment
		(start 60.624974 -216.460324)
		(end 61.407294 -217.242644)
		(width 0.14478)
		(layer "In2.Cu")
		(net "M_C_CPU1_SA_DQ<18>")
	)
	(segment
		(start 40.23995 -216.885266)
		(end 40.665146 -217.310462)
		(width 0.14478)
		(layer "In2.Cu")
		(net "M_C_CPU1_SA_DQ<18>")
	)
	(segment
		(start 41.761664 -217.847926)
		(end 41.992042 -217.847926)
		(width 0.14478)
		(layer "In2.Cu")
		(net "M_C_CPU1_SA_DQ<18>")
	)
	(segment
		(start 85.74405 -235.251752)
		(end 85.752432 -235.246926)
		(width 0.0889)
		(layer "In2.Cu")
		(net "M_C_CPU1_SA_DQ<18>")
	)
	(segment
		(start 71.858124 -228.298756)
		(end 76.141072 -232.581704)
		(width 0.14478)
		(layer "In2.Cu")
		(net "M_C_CPU1_SA_DQ<18>")
	)
	(segment
		(start 76.141072 -232.581704)
		(end 76.504546 -232.581704)
		(width 0.0889)
		(layer "In2.Cu")
		(net "M_C_CPU1_SA_DQ<18>")
	)
	(segment
		(start 50.078132 -216.460324)
		(end 53.111654 -216.460324)
		(width 0.14478)
		(layer "In2.Cu")
		(net "M_C_CPU1_SA_DQ<18>")
	)
	(segment
		(start 42.318178 -217.310462)
		(end 49.227994 -217.310462)
		(width 0.14478)
		(layer "In2.Cu")
		(net "M_C_CPU1_SA_DQ<18>")
	)
	(segment
		(start 88.929718 -235.246926)
		(end 88.9381 -235.251752)
		(width 0.0889)
		(layer "In2.Cu")
		(net "M_C_CPU1_SA_DQ<18>")
	)
	(segment
		(start 80.093566 -235.257848)
		(end 80.10398 -235.251752)
		(width 0.0889)
		(layer "In2.Cu")
		(net "M_C_CPU1_SA_DQ<18>")
	)
	(segment
		(start 41.598596 -217.47353)
		(end 41.598596 -217.684858)
		(width 0.14478)
		(layer "In2.Cu")
		(net "M_C_CPU1_SA_DQ<18>")
	)
	(segment
		(start 53.111654 -216.460324)
		(end 53.961792 -217.310462)
		(width 0.14478)
		(layer "In2.Cu")
		(net "M_C_CPU1_SA_DQ<18>")
	)
	(segment
		(start 93.263974 -235.251752)
		(end 93.272356 -235.246926)
		(width 0.0889)
		(layer "In2.Cu")
		(net "M_C_CPU1_SA_DQ<18>")
	)
	(segment
		(start 42.15511 -217.47353)
		(end 42.318178 -217.310462)
		(width 0.14478)
		(layer "In2.Cu")
		(net "M_C_CPU1_SA_DQ<18>")
	)
	(segment
		(start 83.289648 -235.246926)
		(end 83.29803 -235.251752)
		(width 0.0889)
		(layer "In2.Cu")
		(net "M_C_CPU1_SA_DQ<18>")
	)
	(segment
		(start 79.42961 -235.251752)
		(end 79.537814 -235.251752)
		(width 0.0889)
		(layer "In2.Cu")
		(net "M_C_CPU1_SA_DQ<18>")
	)
	(segment
		(start 80.46974 -235.246926)
		(end 80.478122 -235.251752)
		(width 0.0889)
		(layer "In2.Cu")
		(net "M_C_CPU1_SA_DQ<18>")
	)
	(segment
		(start 71.858124 -226.893882)
		(end 71.858124 -228.298756)
		(width 0.14478)
		(layer "In2.Cu")
		(net "M_C_CPU1_SA_DQ<18>")
	)
	(segment
		(start 61.407294 -217.242644)
		(end 63.337694 -217.242644)
		(width 0.14478)
		(layer "In2.Cu")
		(net "M_C_CPU1_SA_DQ<18>")
	)
	(arc
		(start 91.383866 -235.251752)
		(mid 91.566117 -235.201402)
		(end 91.749626 -235.246926)
		(width 0.0889)
		(layer "In2.Cu")
		(net "M_C_CPU1_SA_DQ<18>")
	)
	(arc
		(start 90.444066 -235.251752)
		(mid 90.63101 -235.201497)
		(end 90.817954 -235.251752)
		(width 0.0889)
		(layer "In2.Cu")
		(net "M_C_CPU1_SA_DQ<18>")
	)
	(arc
		(start 88.563958 -235.251752)
		(mid 88.746209 -235.201402)
		(end 88.929718 -235.246926)
		(width 0.0889)
		(layer "In2.Cu")
		(net "M_C_CPU1_SA_DQ<18>")
	)
	(arc
		(start 86.684104 -235.251752)
		(mid 86.871048 -235.201497)
		(end 87.057992 -235.251752)
		(width 0.0889)
		(layer "In2.Cu")
		(net "M_C_CPU1_SA_DQ<18>")
	)
	(arc
		(start 81.052416 -235.246926)
		(mid 81.235924 -235.201432)
		(end 81.418176 -235.251752)
		(width 0.0889)
		(layer "In2.Cu")
		(net "M_C_CPU1_SA_DQ<18>")
	)
	(arc
		(start 84.812378 -235.246926)
		(mid 84.995886 -235.201432)
		(end 85.178138 -235.251752)
		(width 0.0889)
		(layer "In2.Cu")
		(net "M_C_CPU1_SA_DQ<18>")
	)
	(arc
		(start 93.272356 -235.246926)
		(mid 93.455864 -235.201432)
		(end 93.638116 -235.251752)
		(width 0.0889)
		(layer "In2.Cu")
		(net "M_C_CPU1_SA_DQ<18>")
	)
	(arc
		(start 84.238084 -235.251752)
		(mid 84.52104 -235.327929)
		(end 84.803996 -235.251752)
		(width 0.0889)
		(layer "In2.Cu")
		(net "M_C_CPU1_SA_DQ<18>")
	)
	(arc
		(start 85.752432 -235.246926)
		(mid 85.93594 -235.201432)
		(end 86.118192 -235.251752)
		(width 0.0889)
		(layer "In2.Cu")
		(net "M_C_CPU1_SA_DQ<18>")
	)
	(arc
		(start 90.817954 -235.251752)
		(mid 91.10091 -235.327929)
		(end 91.383866 -235.251752)
		(width 0.0889)
		(layer "In2.Cu")
		(net "M_C_CPU1_SA_DQ<18>")
	)
	(arc
		(start 92.698062 -235.251752)
		(mid 92.981018 -235.327929)
		(end 93.263974 -235.251752)
		(width 0.0889)
		(layer "In2.Cu")
		(net "M_C_CPU1_SA_DQ<18>")
	)
	(arc
		(start 79.537814 -235.251752)
		(mid 79.814881 -235.328023)
		(end 80.093566 -235.257848)
		(width 0.0889)
		(layer "In2.Cu")
		(net "M_C_CPU1_SA_DQ<18>")
	)
	(arc
		(start 87.057992 -235.251752)
		(mid 87.340948 -235.327929)
		(end 87.623904 -235.251752)
		(width 0.0889)
		(layer "In2.Cu")
		(net "M_C_CPU1_SA_DQ<18>")
	)
	(arc
		(start 80.478122 -235.251752)
		(mid 80.761078 -235.327929)
		(end 81.044034 -235.251752)
		(width 0.0889)
		(layer "In2.Cu")
		(net "M_C_CPU1_SA_DQ<18>")
	)
	(arc
		(start 87.998046 -235.251752)
		(mid 88.281002 -235.327929)
		(end 88.563958 -235.251752)
		(width 0.0889)
		(layer "In2.Cu")
		(net "M_C_CPU1_SA_DQ<18>")
	)
	(arc
		(start 86.118192 -235.251752)
		(mid 86.401148 -235.327929)
		(end 86.684104 -235.251752)
		(width 0.0889)
		(layer "In2.Cu")
		(net "M_C_CPU1_SA_DQ<18>")
	)
	(arc
		(start 93.638116 -235.251752)
		(mid 93.885829 -235.326972)
		(end 94.141036 -235.283502)
		(width 0.0889)
		(layer "In2.Cu")
		(net "M_C_CPU1_SA_DQ<18>")
	)
	(arc
		(start 89.512394 -235.246926)
		(mid 89.695902 -235.201432)
		(end 89.878154 -235.251752)
		(width 0.0889)
		(layer "In2.Cu")
		(net "M_C_CPU1_SA_DQ<18>")
	)
	(arc
		(start 91.758008 -235.251752)
		(mid 92.040964 -235.327929)
		(end 92.32392 -235.251752)
		(width 0.0889)
		(layer "In2.Cu")
		(net "M_C_CPU1_SA_DQ<18>")
	)
	(arc
		(start 92.32392 -235.251752)
		(mid 92.506171 -235.201402)
		(end 92.68968 -235.246926)
		(width 0.0889)
		(layer "In2.Cu")
		(net "M_C_CPU1_SA_DQ<18>")
	)
	(arc
		(start 87.623904 -235.251752)
		(mid 87.806155 -235.201402)
		(end 87.989664 -235.246926)
		(width 0.0889)
		(layer "In2.Cu")
		(net "M_C_CPU1_SA_DQ<18>")
	)
	(arc
		(start 83.863942 -235.251752)
		(mid 84.046193 -235.201402)
		(end 84.229702 -235.246926)
		(width 0.0889)
		(layer "In2.Cu")
		(net "M_C_CPU1_SA_DQ<18>")
	)
	(arc
		(start 82.357976 -235.251752)
		(mid 82.640932 -235.327929)
		(end 82.923888 -235.251752)
		(width 0.0889)
		(layer "In2.Cu")
		(net "M_C_CPU1_SA_DQ<18>")
	)
	(arc
		(start 85.178138 -235.251752)
		(mid 85.461094 -235.327929)
		(end 85.74405 -235.251752)
		(width 0.0889)
		(layer "In2.Cu")
		(net "M_C_CPU1_SA_DQ<18>")
	)
	(arc
		(start 81.418176 -235.251752)
		(mid 81.701132 -235.327929)
		(end 81.984088 -235.251752)
		(width 0.0889)
		(layer "In2.Cu")
		(net "M_C_CPU1_SA_DQ<18>")
	)
	(arc
		(start 83.29803 -235.251752)
		(mid 83.580986 -235.327929)
		(end 83.863942 -235.251752)
		(width 0.0889)
		(layer "In2.Cu")
		(net "M_C_CPU1_SA_DQ<18>")
	)
	(arc
		(start 89.878154 -235.251752)
		(mid 90.16111 -235.327929)
		(end 90.444066 -235.251752)
		(width 0.0889)
		(layer "In2.Cu")
		(net "M_C_CPU1_SA_DQ<18>")
	)
	(arc
		(start 82.923888 -235.251752)
		(mid 83.106139 -235.201402)
		(end 83.289648 -235.246926)
		(width 0.0889)
		(layer "In2.Cu")
		(net "M_C_CPU1_SA_DQ<18>")
	)
	(arc
		(start 88.9381 -235.251752)
		(mid 89.221056 -235.327929)
		(end 89.504012 -235.251752)
		(width 0.0889)
		(layer "In2.Cu")
		(net "M_C_CPU1_SA_DQ<18>")
	)
	(arc
		(start 81.984088 -235.251752)
		(mid 82.171032 -235.201497)
		(end 82.357976 -235.251752)
		(width 0.0889)
		(layer "In2.Cu")
		(net "M_C_CPU1_SA_DQ<18>")
	)
	(arc
		(start 80.10398 -235.251752)
		(mid 80.286231 -235.201402)
		(end 80.46974 -235.246926)
		(width 0.0889)
		(layer "In2.Cu")
		(net "M_C_CPU1_SA_DQ<18>")
	)
	(segment
		(start 95.797878 -235.84027)
		(end 95.331026 -235.574332)
		(width 0.10668)
		(layer "F.Cu")
		(net "M_C_CPU1_SA_DQ<17>")
	)
	(segment
		(start 76.753466 -233.861864)
		(end 77.279246 -233.861864)
		(width 0.0889)
		(layer "In2.Cu")
		(net "M_C_CPU1_SA_DQ<17>")
	)
	(segment
		(start 51.3461 -217.310462)
		(end 53.102764 -217.310462)
		(width 0.14478)
		(layer "In2.Cu")
		(net "M_C_CPU1_SA_DQ<17>")
	)
	(segment
		(start 45.621194 -217.773504)
		(end 45.851572 -217.773504)
		(width 0.14478)
		(layer "In2.Cu")
		(net "M_C_CPU1_SA_DQ<17>")
	)
	(segment
		(start 80.46974 -235.901738)
		(end 80.478122 -235.896912)
		(width 0.0889)
		(layer "In2.Cu")
		(net "M_C_CPU1_SA_DQ<17>")
	)
	(segment
		(start 46.01464 -218.367356)
		(end 46.177708 -218.530424)
		(width 0.14478)
		(layer "In2.Cu")
		(net "M_C_CPU1_SA_DQ<17>")
	)
	(segment
		(start 46.734222 -217.773504)
		(end 46.9646 -217.773504)
		(width 0.14478)
		(layer "In2.Cu")
		(net "M_C_CPU1_SA_DQ<17>")
	)
	(segment
		(start 50.626518 -217.147394)
		(end 50.626518 -217.078052)
		(width 0.14478)
		(layer "In2.Cu")
		(net "M_C_CPU1_SA_DQ<17>")
	)
	(segment
		(start 58.659776 -216.922604)
		(end 58.822844 -217.085672)
		(width 0.14478)
		(layer "In2.Cu")
		(net "M_C_CPU1_SA_DQ<17>")
	)
	(segment
		(start 58.26633 -217.085672)
		(end 58.429398 -216.922604)
		(width 0.14478)
		(layer "In2.Cu")
		(net "M_C_CPU1_SA_DQ<17>")
	)
	(segment
		(start 60.608464 -217.310462)
		(end 61.002926 -217.704924)
		(width 0.14478)
		(layer "In2.Cu")
		(net "M_C_CPU1_SA_DQ<17>")
	)
	(segment
		(start 58.822844 -217.147394)
		(end 58.985912 -217.310462)
		(width 0.14478)
		(layer "In2.Cu")
		(net "M_C_CPU1_SA_DQ<17>")
	)
	(segment
		(start 53.102764 -217.310462)
		(end 53.952648 -218.160346)
		(width 0.14478)
		(layer "In2.Cu")
		(net "M_C_CPU1_SA_DQ<17>")
	)
	(segment
		(start 44.76496 -218.160346)
		(end 45.295058 -218.160346)
		(width 0.14478)
		(layer "In2.Cu")
		(net "M_C_CPU1_SA_DQ<17>")
	)
	(segment
		(start 61.002926 -217.704924)
		(end 63.156846 -217.704924)
		(width 0.14478)
		(layer "In2.Cu")
		(net "M_C_CPU1_SA_DQ<17>")
	)
	(segment
		(start 45.458126 -217.936572)
		(end 45.621194 -217.773504)
		(width 0.14478)
		(layer "In2.Cu")
		(net "M_C_CPU1_SA_DQ<17>")
	)
	(segment
		(start 51.183032 -217.147394)
		(end 51.3461 -217.310462)
		(width 0.14478)
		(layer "In2.Cu")
		(net "M_C_CPU1_SA_DQ<17>")
	)
	(segment
		(start 48.717962 -217.773504)
		(end 48.88103 -217.936572)
		(width 0.14478)
		(layer "In2.Cu")
		(net "M_C_CPU1_SA_DQ<17>")
	)
	(segment
		(start 54.821328 -217.997278)
		(end 54.984396 -218.160346)
		(width 0.14478)
		(layer "In2.Cu")
		(net "M_C_CPU1_SA_DQ<17>")
	)
	(segment
		(start 57.518808 -217.310462)
		(end 58.103262 -217.310462)
		(width 0.14478)
		(layer "In2.Cu")
		(net "M_C_CPU1_SA_DQ<17>")
	)
	(segment
		(start 46.9646 -217.773504)
		(end 47.127668 -217.936572)
		(width 0.14478)
		(layer "In2.Cu")
		(net "M_C_CPU1_SA_DQ<17>")
	)
	(segment
		(start 76.073508 -233.181906)
		(end 76.753466 -233.861864)
		(width 0.0889)
		(layer "In2.Cu")
		(net "M_C_CPU1_SA_DQ<17>")
	)
	(segment
		(start 50.46345 -217.310462)
		(end 50.626518 -217.147394)
		(width 0.14478)
		(layer "In2.Cu")
		(net "M_C_CPU1_SA_DQ<17>")
	)
	(segment
		(start 47.127668 -217.997278)
		(end 47.290736 -218.160346)
		(width 0.14478)
		(layer "In2.Cu")
		(net "M_C_CPU1_SA_DQ<17>")
	)
	(segment
		(start 48.88103 -217.936572)
		(end 48.88103 -217.997278)
		(width 0.14478)
		(layer "In2.Cu")
		(net "M_C_CPU1_SA_DQ<17>")
	)
	(segment
		(start 45.295058 -218.160346)
		(end 45.458126 -217.997278)
		(width 0.14478)
		(layer "In2.Cu")
		(net "M_C_CPU1_SA_DQ<17>")
	)
	(segment
		(start 93.263974 -235.896912)
		(end 93.272356 -235.901738)
		(width 0.0889)
		(layer "In2.Cu")
		(net "M_C_CPU1_SA_DQ<17>")
	)
	(segment
		(start 95.462598 -235.923074)
		(end 95.48495 -235.839762)
		(width 0.0889)
		(layer "In2.Cu")
		(net "M_C_CPU1_SA_DQ<17>")
	)
	(segment
		(start 45.458126 -217.997278)
		(end 45.458126 -217.936572)
		(width 0.14478)
		(layer "In2.Cu")
		(net "M_C_CPU1_SA_DQ<17>")
	)
	(segment
		(start 89.504012 -235.896912)
		(end 89.512394 -235.901738)
		(width 0.0889)
		(layer "In2.Cu")
		(net "M_C_CPU1_SA_DQ<17>")
	)
	(segment
		(start 85.74405 -235.896912)
		(end 85.752432 -235.901738)
		(width 0.0889)
		(layer "In2.Cu")
		(net "M_C_CPU1_SA_DQ<17>")
	)
	(segment
		(start 49.044098 -218.160346)
		(end 49.335944 -218.160346)
		(width 0.14478)
		(layer "In2.Cu")
		(net "M_C_CPU1_SA_DQ<17>")
	)
	(segment
		(start 47.290736 -218.160346)
		(end 48.161448 -218.160346)
		(width 0.14478)
		(layer "In2.Cu")
		(net "M_C_CPU1_SA_DQ<17>")
	)
	(segment
		(start 56.668924 -218.160346)
		(end 57.518808 -217.310462)
		(width 0.14478)
		(layer "In2.Cu")
		(net "M_C_CPU1_SA_DQ<17>")
	)
	(segment
		(start 94.204028 -235.896912)
		(end 94.21241 -235.901738)
		(width 0.0889)
		(layer "In2.Cu")
		(net "M_C_CPU1_SA_DQ<17>")
	)
	(segment
		(start 79.530956 -235.820712)
		(end 79.821024 -235.820712)
		(width 0.0889)
		(layer "In2.Cu")
		(net "M_C_CPU1_SA_DQ<17>")
	)
	(segment
		(start 54.264814 -217.936572)
		(end 54.427882 -217.773504)
		(width 0.14478)
		(layer "In2.Cu")
		(net "M_C_CPU1_SA_DQ<17>")
	)
	(segment
		(start 44.340018 -217.735404)
		(end 44.76496 -218.160346)
		(width 0.14478)
		(layer "In2.Cu")
		(net "M_C_CPU1_SA_DQ<17>")
	)
	(segment
		(start 71.393304 -228.501702)
		(end 76.073508 -233.181906)
		(width 0.14478)
		(layer "In2.Cu")
		(net "M_C_CPU1_SA_DQ<17>")
	)
	(segment
		(start 51.183032 -217.078052)
		(end 51.183032 -217.147394)
		(width 0.14478)
		(layer "In2.Cu")
		(net "M_C_CPU1_SA_DQ<17>")
	)
	(segment
		(start 71.393304 -227.208588)
		(end 71.393304 -228.501702)
		(width 0.14478)
		(layer "In2.Cu")
		(net "M_C_CPU1_SA_DQ<17>")
	)
	(segment
		(start 50.185828 -217.310462)
		(end 50.46345 -217.310462)
		(width 0.14478)
		(layer "In2.Cu")
		(net "M_C_CPU1_SA_DQ<17>")
	)
	(segment
		(start 45.851572 -217.773504)
		(end 46.01464 -217.936572)
		(width 0.14478)
		(layer "In2.Cu")
		(net "M_C_CPU1_SA_DQ<17>")
	)
	(segment
		(start 54.65826 -217.773504)
		(end 54.821328 -217.936572)
		(width 0.14478)
		(layer "In2.Cu")
		(net "M_C_CPU1_SA_DQ<17>")
	)
	(segment
		(start 54.264814 -217.997278)
		(end 54.264814 -217.936572)
		(width 0.14478)
		(layer "In2.Cu")
		(net "M_C_CPU1_SA_DQ<17>")
	)
	(segment
		(start 48.88103 -217.997278)
		(end 49.044098 -218.160346)
		(width 0.14478)
		(layer "In2.Cu")
		(net "M_C_CPU1_SA_DQ<17>")
	)
	(segment
		(start 48.324516 -217.936572)
		(end 48.487584 -217.773504)
		(width 0.14478)
		(layer "In2.Cu")
		(net "M_C_CPU1_SA_DQ<17>")
	)
	(segment
		(start 48.324516 -217.997278)
		(end 48.324516 -217.936572)
		(width 0.14478)
		(layer "In2.Cu")
		(net "M_C_CPU1_SA_DQ<17>")
	)
	(segment
		(start 88.929718 -235.901738)
		(end 88.9381 -235.896912)
		(width 0.0889)
		(layer "In2.Cu")
		(net "M_C_CPU1_SA_DQ<17>")
	)
	(segment
		(start 53.952648 -218.160346)
		(end 54.101746 -218.160346)
		(width 0.14478)
		(layer "In2.Cu")
		(net "M_C_CPU1_SA_DQ<17>")
	)
	(segment
		(start 46.571154 -217.936572)
		(end 46.734222 -217.773504)
		(width 0.14478)
		(layer "In2.Cu")
		(net "M_C_CPU1_SA_DQ<17>")
	)
	(segment
		(start 46.408086 -218.530424)
		(end 46.571154 -218.367356)
		(width 0.14478)
		(layer "In2.Cu")
		(net "M_C_CPU1_SA_DQ<17>")
	)
	(segment
		(start 54.427882 -217.773504)
		(end 54.65826 -217.773504)
		(width 0.14478)
		(layer "In2.Cu")
		(net "M_C_CPU1_SA_DQ<17>")
	)
	(segment
		(start 50.626518 -217.078052)
		(end 50.789586 -216.914984)
		(width 0.14478)
		(layer "In2.Cu")
		(net "M_C_CPU1_SA_DQ<17>")
	)
	(segment
		(start 47.127668 -217.936572)
		(end 47.127668 -217.997278)
		(width 0.14478)
		(layer "In2.Cu")
		(net "M_C_CPU1_SA_DQ<17>")
	)
	(segment
		(start 84.803996 -235.896912)
		(end 84.812378 -235.901738)
		(width 0.0889)
		(layer "In2.Cu")
		(net "M_C_CPU1_SA_DQ<17>")
	)
	(segment
		(start 48.487584 -217.773504)
		(end 48.717962 -217.773504)
		(width 0.14478)
		(layer "In2.Cu")
		(net "M_C_CPU1_SA_DQ<17>")
	)
	(segment
		(start 46.01464 -217.936572)
		(end 46.01464 -218.367356)
		(width 0.14478)
		(layer "In2.Cu")
		(net "M_C_CPU1_SA_DQ<17>")
	)
	(segment
		(start 50.789586 -216.914984)
		(end 51.019964 -216.914984)
		(width 0.14478)
		(layer "In2.Cu")
		(net "M_C_CPU1_SA_DQ<17>")
	)
	(segment
		(start 65.658746 -220.206824)
		(end 65.658746 -221.47403)
		(width 0.14478)
		(layer "In2.Cu")
		(net "M_C_CPU1_SA_DQ<17>")
	)
	(segment
		(start 84.229702 -235.901738)
		(end 84.238084 -235.896912)
		(width 0.0889)
		(layer "In2.Cu")
		(net "M_C_CPU1_SA_DQ<17>")
	)
	(segment
		(start 78.43647 -234.726226)
		(end 79.530956 -235.820712)
		(width 0.0889)
		(layer "In2.Cu")
		(net "M_C_CPU1_SA_DQ<17>")
	)
	(segment
		(start 46.177708 -218.530424)
		(end 46.408086 -218.530424)
		(width 0.14478)
		(layer "In2.Cu")
		(net "M_C_CPU1_SA_DQ<17>")
	)
	(segment
		(start 54.984396 -218.160346)
		(end 56.668924 -218.160346)
		(width 0.14478)
		(layer "In2.Cu")
		(net "M_C_CPU1_SA_DQ<17>")
	)
	(segment
		(start 77.279246 -233.861864)
		(end 78.143608 -234.726226)
		(width 0.0889)
		(layer "In2.Cu")
		(net "M_C_CPU1_SA_DQ<17>")
	)
	(segment
		(start 54.821328 -217.936572)
		(end 54.821328 -217.997278)
		(width 0.14478)
		(layer "In2.Cu")
		(net "M_C_CPU1_SA_DQ<17>")
	)
	(segment
		(start 92.68968 -235.901738)
		(end 92.698062 -235.896912)
		(width 0.0889)
		(layer "In2.Cu")
		(net "M_C_CPU1_SA_DQ<17>")
	)
	(segment
		(start 58.985912 -217.310462)
		(end 60.608464 -217.310462)
		(width 0.14478)
		(layer "In2.Cu")
		(net "M_C_CPU1_SA_DQ<17>")
	)
	(segment
		(start 51.019964 -216.914984)
		(end 51.183032 -217.078052)
		(width 0.14478)
		(layer "In2.Cu")
		(net "M_C_CPU1_SA_DQ<17>")
	)
	(segment
		(start 58.103262 -217.310462)
		(end 58.26633 -217.147394)
		(width 0.14478)
		(layer "In2.Cu")
		(net "M_C_CPU1_SA_DQ<17>")
	)
	(segment
		(start 63.156846 -217.704924)
		(end 65.658746 -220.206824)
		(width 0.14478)
		(layer "In2.Cu")
		(net "M_C_CPU1_SA_DQ<17>")
	)
	(segment
		(start 95.48495 -235.839762)
		(end 95.331026 -235.574332)
		(width 0.0889)
		(layer "In2.Cu")
		(net "M_C_CPU1_SA_DQ<17>")
	)
	(segment
		(start 91.749626 -235.901738)
		(end 91.758008 -235.896912)
		(width 0.0889)
		(layer "In2.Cu")
		(net "M_C_CPU1_SA_DQ<17>")
	)
	(segment
		(start 46.571154 -218.367356)
		(end 46.571154 -217.936572)
		(width 0.14478)
		(layer "In2.Cu")
		(net "M_C_CPU1_SA_DQ<17>")
	)
	(segment
		(start 78.143608 -234.726226)
		(end 78.43647 -234.726226)
		(width 0.0889)
		(layer "In2.Cu")
		(net "M_C_CPU1_SA_DQ<17>")
	)
	(segment
		(start 58.429398 -216.922604)
		(end 58.659776 -216.922604)
		(width 0.14478)
		(layer "In2.Cu")
		(net "M_C_CPU1_SA_DQ<17>")
	)
	(segment
		(start 49.335944 -218.160346)
		(end 50.185828 -217.310462)
		(width 0.14478)
		(layer "In2.Cu")
		(net "M_C_CPU1_SA_DQ<17>")
	)
	(segment
		(start 58.26633 -217.147394)
		(end 58.26633 -217.085672)
		(width 0.14478)
		(layer "In2.Cu")
		(net "M_C_CPU1_SA_DQ<17>")
	)
	(segment
		(start 65.658746 -221.47403)
		(end 71.393304 -227.208588)
		(width 0.14478)
		(layer "In2.Cu")
		(net "M_C_CPU1_SA_DQ<17>")
	)
	(segment
		(start 83.289648 -235.901738)
		(end 83.29803 -235.896912)
		(width 0.0889)
		(layer "In2.Cu")
		(net "M_C_CPU1_SA_DQ<17>")
	)
	(segment
		(start 48.161448 -218.160346)
		(end 48.324516 -217.997278)
		(width 0.14478)
		(layer "In2.Cu")
		(net "M_C_CPU1_SA_DQ<17>")
	)
	(segment
		(start 58.822844 -217.085672)
		(end 58.822844 -217.147394)
		(width 0.14478)
		(layer "In2.Cu")
		(net "M_C_CPU1_SA_DQ<17>")
	)
	(segment
		(start 81.044034 -235.896912)
		(end 81.052416 -235.901738)
		(width 0.0889)
		(layer "In2.Cu")
		(net "M_C_CPU1_SA_DQ<17>")
	)
	(segment
		(start 87.989664 -235.901738)
		(end 87.998046 -235.896912)
		(width 0.0889)
		(layer "In2.Cu")
		(net "M_C_CPU1_SA_DQ<17>")
	)
	(segment
		(start 54.101746 -218.160346)
		(end 54.264814 -217.997278)
		(width 0.14478)
		(layer "In2.Cu")
		(net "M_C_CPU1_SA_DQ<17>")
	)
	(arc
		(start 82.923888 -235.896912)
		(mid 83.106139 -235.947262)
		(end 83.289648 -235.901738)
		(width 0.0889)
		(layer "In2.Cu")
		(net "M_C_CPU1_SA_DQ<17>")
	)
	(arc
		(start 88.563958 -235.896912)
		(mid 88.746209 -235.947262)
		(end 88.929718 -235.901738)
		(width 0.0889)
		(layer "In2.Cu")
		(net "M_C_CPU1_SA_DQ<17>")
	)
	(arc
		(start 90.817954 -235.896912)
		(mid 91.10091 -235.820735)
		(end 91.383866 -235.896912)
		(width 0.0889)
		(layer "In2.Cu")
		(net "M_C_CPU1_SA_DQ<17>")
	)
	(arc
		(start 93.638116 -235.896912)
		(mid 93.921072 -235.820735)
		(end 94.204028 -235.896912)
		(width 0.0889)
		(layer "In2.Cu")
		(net "M_C_CPU1_SA_DQ<17>")
	)
	(arc
		(start 86.118192 -235.896912)
		(mid 86.401148 -235.820735)
		(end 86.684104 -235.896912)
		(width 0.0889)
		(layer "In2.Cu")
		(net "M_C_CPU1_SA_DQ<17>")
	)
	(arc
		(start 87.998046 -235.896912)
		(mid 88.281002 -235.820735)
		(end 88.563958 -235.896912)
		(width 0.0889)
		(layer "In2.Cu")
		(net "M_C_CPU1_SA_DQ<17>")
	)
	(arc
		(start 83.863942 -235.896912)
		(mid 84.046193 -235.947262)
		(end 84.229702 -235.901738)
		(width 0.0889)
		(layer "In2.Cu")
		(net "M_C_CPU1_SA_DQ<17>")
	)
	(arc
		(start 92.698062 -235.896912)
		(mid 92.981018 -235.820735)
		(end 93.263974 -235.896912)
		(width 0.0889)
		(layer "In2.Cu")
		(net "M_C_CPU1_SA_DQ<17>")
	)
	(arc
		(start 95.144082 -235.896912)
		(mid 95.300401 -235.945907)
		(end 95.462598 -235.923074)
		(width 0.0889)
		(layer "In2.Cu")
		(net "M_C_CPU1_SA_DQ<17>")
	)
	(arc
		(start 86.684104 -235.896912)
		(mid 86.871048 -235.947167)
		(end 87.057992 -235.896912)
		(width 0.0889)
		(layer "In2.Cu")
		(net "M_C_CPU1_SA_DQ<17>")
	)
	(arc
		(start 85.752432 -235.901738)
		(mid 85.93594 -235.947232)
		(end 86.118192 -235.896912)
		(width 0.0889)
		(layer "In2.Cu")
		(net "M_C_CPU1_SA_DQ<17>")
	)
	(arc
		(start 80.10398 -235.896912)
		(mid 80.286231 -235.947262)
		(end 80.46974 -235.901738)
		(width 0.0889)
		(layer "In2.Cu")
		(net "M_C_CPU1_SA_DQ<17>")
	)
	(arc
		(start 83.29803 -235.896912)
		(mid 83.580986 -235.820735)
		(end 83.863942 -235.896912)
		(width 0.0889)
		(layer "In2.Cu")
		(net "M_C_CPU1_SA_DQ<17>")
	)
	(arc
		(start 80.478122 -235.896912)
		(mid 80.761078 -235.820735)
		(end 81.044034 -235.896912)
		(width 0.0889)
		(layer "In2.Cu")
		(net "M_C_CPU1_SA_DQ<17>")
	)
	(arc
		(start 81.052416 -235.901738)
		(mid 81.235924 -235.947232)
		(end 81.418176 -235.896912)
		(width 0.0889)
		(layer "In2.Cu")
		(net "M_C_CPU1_SA_DQ<17>")
	)
	(arc
		(start 89.878154 -235.896912)
		(mid 90.16111 -235.820735)
		(end 90.444066 -235.896912)
		(width 0.0889)
		(layer "In2.Cu")
		(net "M_C_CPU1_SA_DQ<17>")
	)
	(arc
		(start 94.57817 -235.896912)
		(mid 94.861126 -235.820735)
		(end 95.144082 -235.896912)
		(width 0.0889)
		(layer "In2.Cu")
		(net "M_C_CPU1_SA_DQ<17>")
	)
	(arc
		(start 88.9381 -235.896912)
		(mid 89.221056 -235.820735)
		(end 89.504012 -235.896912)
		(width 0.0889)
		(layer "In2.Cu")
		(net "M_C_CPU1_SA_DQ<17>")
	)
	(arc
		(start 91.758008 -235.896912)
		(mid 92.040964 -235.820735)
		(end 92.32392 -235.896912)
		(width 0.0889)
		(layer "In2.Cu")
		(net "M_C_CPU1_SA_DQ<17>")
	)
	(arc
		(start 94.21241 -235.901738)
		(mid 94.395918 -235.947232)
		(end 94.57817 -235.896912)
		(width 0.0889)
		(layer "In2.Cu")
		(net "M_C_CPU1_SA_DQ<17>")
	)
	(arc
		(start 84.812378 -235.901738)
		(mid 84.995886 -235.947232)
		(end 85.178138 -235.896912)
		(width 0.0889)
		(layer "In2.Cu")
		(net "M_C_CPU1_SA_DQ<17>")
	)
	(arc
		(start 92.32392 -235.896912)
		(mid 92.506171 -235.947262)
		(end 92.68968 -235.901738)
		(width 0.0889)
		(layer "In2.Cu")
		(net "M_C_CPU1_SA_DQ<17>")
	)
	(arc
		(start 87.057992 -235.896912)
		(mid 87.340948 -235.820735)
		(end 87.623904 -235.896912)
		(width 0.0889)
		(layer "In2.Cu")
		(net "M_C_CPU1_SA_DQ<17>")
	)
	(arc
		(start 89.512394 -235.901738)
		(mid 89.695902 -235.947232)
		(end 89.878154 -235.896912)
		(width 0.0889)
		(layer "In2.Cu")
		(net "M_C_CPU1_SA_DQ<17>")
	)
	(arc
		(start 90.444066 -235.896912)
		(mid 90.63101 -235.947167)
		(end 90.817954 -235.896912)
		(width 0.0889)
		(layer "In2.Cu")
		(net "M_C_CPU1_SA_DQ<17>")
	)
	(arc
		(start 81.984088 -235.896912)
		(mid 82.171032 -235.947167)
		(end 82.357976 -235.896912)
		(width 0.0889)
		(layer "In2.Cu")
		(net "M_C_CPU1_SA_DQ<17>")
	)
	(arc
		(start 81.418176 -235.896912)
		(mid 81.701132 -235.820735)
		(end 81.984088 -235.896912)
		(width 0.0889)
		(layer "In2.Cu")
		(net "M_C_CPU1_SA_DQ<17>")
	)
	(arc
		(start 87.623904 -235.896912)
		(mid 87.806155 -235.947262)
		(end 87.989664 -235.901738)
		(width 0.0889)
		(layer "In2.Cu")
		(net "M_C_CPU1_SA_DQ<17>")
	)
	(arc
		(start 91.383866 -235.896912)
		(mid 91.566117 -235.947262)
		(end 91.749626 -235.901738)
		(width 0.0889)
		(layer "In2.Cu")
		(net "M_C_CPU1_SA_DQ<17>")
	)
	(arc
		(start 79.821024 -235.820712)
		(mid 79.967541 -235.840098)
		(end 80.10398 -235.896912)
		(width 0.0889)
		(layer "In2.Cu")
		(net "M_C_CPU1_SA_DQ<17>")
	)
	(arc
		(start 93.272356 -235.901738)
		(mid 93.455864 -235.947232)
		(end 93.638116 -235.896912)
		(width 0.0889)
		(layer "In2.Cu")
		(net "M_C_CPU1_SA_DQ<17>")
	)
	(arc
		(start 82.357976 -235.896912)
		(mid 82.640932 -235.820735)
		(end 82.923888 -235.896912)
		(width 0.0889)
		(layer "In2.Cu")
		(net "M_C_CPU1_SA_DQ<17>")
	)
	(arc
		(start 85.178138 -235.896912)
		(mid 85.461094 -235.820735)
		(end 85.74405 -235.896912)
		(width 0.0889)
		(layer "In2.Cu")
		(net "M_C_CPU1_SA_DQ<17>")
	)
	(arc
		(start 84.238084 -235.896912)
		(mid 84.52104 -235.820735)
		(end 84.803996 -235.896912)
		(width 0.0889)
		(layer "In2.Cu")
		(net "M_C_CPU1_SA_DQ<17>")
	)
	(segment
		(start 94.387924 -235.030264)
		(end 93.921072 -234.764326)
		(width 0.10668)
		(layer "F.Cu")
		(net "M_C_CPU1_SA_DQ<16>")
	)
	(segment
		(start 46.674024 -216.675716)
		(end 46.674024 -216.623392)
		(width 0.14478)
		(layer "In2.Cu")
		(net "M_C_CPU1_SA_DQ<16>")
	)
	(segment
		(start 62.466982 -215.61044)
		(end 62.8015 -215.61044)
		(width 0.14478)
		(layer "In2.Cu")
		(net "M_C_CPU1_SA_DQ<16>")
	)
	(segment
		(start 61.59246 -215.61044)
		(end 61.754004 -215.771984)
		(width 0.14478)
		(layer "In2.Cu")
		(net "M_C_CPU1_SA_DQ<16>")
	)
	(segment
		(start 53.952648 -216.460324)
		(end 56.950864 -216.460324)
		(width 0.14478)
		(layer "In2.Cu")
		(net "M_C_CPU1_SA_DQ<16>")
	)
	(segment
		(start 46.11751 -216.324688)
		(end 46.11751 -216.675716)
		(width 0.14478)
		(layer "In2.Cu")
		(net "M_C_CPU1_SA_DQ<16>")
	)
	(segment
		(start 61.754004 -216.622122)
		(end 61.915548 -216.783666)
		(width 0.14478)
		(layer "In2.Cu")
		(net "M_C_CPU1_SA_DQ<16>")
	)
	(segment
		(start 61.259466 -215.61044)
		(end 61.59246 -215.61044)
		(width 0.14478)
		(layer "In2.Cu")
		(net "M_C_CPU1_SA_DQ<16>")
	)
	(segment
		(start 62.305438 -216.622122)
		(end 62.305438 -215.771984)
		(width 0.14478)
		(layer "In2.Cu")
		(net "M_C_CPU1_SA_DQ<16>")
	)
	(segment
		(start 72.316086 -226.704144)
		(end 72.316086 -228.080824)
		(width 0.14478)
		(layer "In2.Cu")
		(net "M_C_CPU1_SA_DQ<16>")
	)
	(segment
		(start 82.453988 -235.086906)
		(end 82.46237 -235.091732)
		(width 0.0889)
		(layer "In2.Cu")
		(net "M_C_CPU1_SA_DQ<16>")
	)
	(segment
		(start 60.708032 -215.902286)
		(end 60.96762 -215.902286)
		(width 0.14478)
		(layer "In2.Cu")
		(net "M_C_CPU1_SA_DQ<16>")
	)
	(segment
		(start 45.560996 -216.324688)
		(end 45.724064 -216.16162)
		(width 0.14478)
		(layer "In2.Cu")
		(net "M_C_CPU1_SA_DQ<16>")
	)
	(segment
		(start 76.334366 -232.099104)
		(end 77.832966 -233.597704)
		(width 0.0889)
		(layer "In2.Cu")
		(net "M_C_CPU1_SA_DQ<16>")
	)
	(segment
		(start 45.16755 -216.838784)
		(end 45.397928 -216.838784)
		(width 0.14478)
		(layer "In2.Cu")
		(net "M_C_CPU1_SA_DQ<16>")
	)
	(segment
		(start 46.510956 -216.838784)
		(end 46.674024 -216.675716)
		(width 0.14478)
		(layer "In2.Cu")
		(net "M_C_CPU1_SA_DQ<16>")
	)
	(segment
		(start 60.416186 -215.61044)
		(end 60.708032 -215.902286)
		(width 0.14478)
		(layer "In2.Cu")
		(net "M_C_CPU1_SA_DQ<16>")
	)
	(segment
		(start 61.754004 -215.771984)
		(end 61.754004 -216.622122)
		(width 0.14478)
		(layer "In2.Cu")
		(net "M_C_CPU1_SA_DQ<16>")
	)
	(segment
		(start 44.340018 -216.035382)
		(end 44.76496 -216.460324)
		(width 0.14478)
		(layer "In2.Cu")
		(net "M_C_CPU1_SA_DQ<16>")
	)
	(segment
		(start 62.305438 -215.771984)
		(end 62.466982 -215.61044)
		(width 0.14478)
		(layer "In2.Cu")
		(net "M_C_CPU1_SA_DQ<16>")
	)
	(segment
		(start 62.94628 -216.208102)
		(end 66.568066 -219.829888)
		(width 0.14478)
		(layer "In2.Cu")
		(net "M_C_CPU1_SA_DQ<16>")
	)
	(segment
		(start 60.96762 -215.902286)
		(end 61.259466 -215.61044)
		(width 0.14478)
		(layer "In2.Cu")
		(net "M_C_CPU1_SA_DQ<16>")
	)
	(segment
		(start 45.724064 -216.16162)
		(end 45.954442 -216.16162)
		(width 0.14478)
		(layer "In2.Cu")
		(net "M_C_CPU1_SA_DQ<16>")
	)
	(segment
		(start 46.674024 -216.623392)
		(end 46.837092 -216.460324)
		(width 0.14478)
		(layer "In2.Cu")
		(net "M_C_CPU1_SA_DQ<16>")
	)
	(segment
		(start 45.397928 -216.838784)
		(end 45.560996 -216.675716)
		(width 0.14478)
		(layer "In2.Cu")
		(net "M_C_CPU1_SA_DQ<16>")
	)
	(segment
		(start 77.832966 -233.597704)
		(end 78.561946 -233.597704)
		(width 0.0889)
		(layer "In2.Cu")
		(net "M_C_CPU1_SA_DQ<16>")
	)
	(segment
		(start 78.843886 -234.315)
		(end 79.557372 -235.028232)
		(width 0.0889)
		(layer "In2.Cu")
		(net "M_C_CPU1_SA_DQ<16>")
	)
	(segment
		(start 78.561946 -233.597704)
		(end 78.843886 -233.879644)
		(width 0.0889)
		(layer "In2.Cu")
		(net "M_C_CPU1_SA_DQ<16>")
	)
	(segment
		(start 50.277268 -215.61044)
		(end 53.102764 -215.61044)
		(width 0.14478)
		(layer "In2.Cu")
		(net "M_C_CPU1_SA_DQ<16>")
	)
	(segment
		(start 62.94628 -215.75522)
		(end 62.94628 -216.208102)
		(width 0.14478)
		(layer "In2.Cu")
		(net "M_C_CPU1_SA_DQ<16>")
	)
	(segment
		(start 46.837092 -216.460324)
		(end 49.427384 -216.460324)
		(width 0.14478)
		(layer "In2.Cu")
		(net "M_C_CPU1_SA_DQ<16>")
	)
	(segment
		(start 94.074996 -235.029756)
		(end 93.921072 -234.764326)
		(width 0.0889)
		(layer "In2.Cu")
		(net "M_C_CPU1_SA_DQ<16>")
	)
	(segment
		(start 44.841414 -216.460324)
		(end 45.004482 -216.623392)
		(width 0.14478)
		(layer "In2.Cu")
		(net "M_C_CPU1_SA_DQ<16>")
	)
	(segment
		(start 49.427384 -216.460324)
		(end 50.277268 -215.61044)
		(width 0.14478)
		(layer "In2.Cu")
		(net "M_C_CPU1_SA_DQ<16>")
	)
	(segment
		(start 83.394042 -235.086906)
		(end 83.402424 -235.091732)
		(width 0.0889)
		(layer "In2.Cu")
		(net "M_C_CPU1_SA_DQ<16>")
	)
	(segment
		(start 53.102764 -215.61044)
		(end 53.952648 -216.460324)
		(width 0.14478)
		(layer "In2.Cu")
		(net "M_C_CPU1_SA_DQ<16>")
	)
	(segment
		(start 45.560996 -216.675716)
		(end 45.560996 -216.324688)
		(width 0.14478)
		(layer "In2.Cu")
		(net "M_C_CPU1_SA_DQ<16>")
	)
	(segment
		(start 62.143894 -216.783666)
		(end 62.305438 -216.622122)
		(width 0.14478)
		(layer "In2.Cu")
		(net "M_C_CPU1_SA_DQ<16>")
	)
	(segment
		(start 79.99984 -235.091732)
		(end 80.008222 -235.086906)
		(width 0.0889)
		(layer "In2.Cu")
		(net "M_C_CPU1_SA_DQ<16>")
	)
	(segment
		(start 46.280578 -216.838784)
		(end 46.510956 -216.838784)
		(width 0.14478)
		(layer "In2.Cu")
		(net "M_C_CPU1_SA_DQ<16>")
	)
	(segment
		(start 62.8015 -215.61044)
		(end 62.94628 -215.75522)
		(width 0.14478)
		(layer "In2.Cu")
		(net "M_C_CPU1_SA_DQ<16>")
	)
	(segment
		(start 66.568066 -219.829888)
		(end 66.568066 -220.956124)
		(width 0.14478)
		(layer "In2.Cu")
		(net "M_C_CPU1_SA_DQ<16>")
	)
	(segment
		(start 90.913966 -235.086906)
		(end 90.922348 -235.091732)
		(width 0.0889)
		(layer "In2.Cu")
		(net "M_C_CPU1_SA_DQ<16>")
	)
	(segment
		(start 72.316086 -228.080824)
		(end 76.334366 -232.099104)
		(width 0.14478)
		(layer "In2.Cu")
		(net "M_C_CPU1_SA_DQ<16>")
	)
	(segment
		(start 88.094058 -235.086906)
		(end 88.10244 -235.091732)
		(width 0.0889)
		(layer "In2.Cu")
		(net "M_C_CPU1_SA_DQ<16>")
	)
	(segment
		(start 57.800748 -215.61044)
		(end 60.416186 -215.61044)
		(width 0.14478)
		(layer "In2.Cu")
		(net "M_C_CPU1_SA_DQ<16>")
	)
	(segment
		(start 90.339672 -235.091732)
		(end 90.348054 -235.086906)
		(width 0.0889)
		(layer "In2.Cu")
		(net "M_C_CPU1_SA_DQ<16>")
	)
	(segment
		(start 78.843886 -233.879644)
		(end 78.843886 -234.315)
		(width 0.0889)
		(layer "In2.Cu")
		(net "M_C_CPU1_SA_DQ<16>")
	)
	(segment
		(start 66.568066 -220.956124)
		(end 72.316086 -226.704144)
		(width 0.14478)
		(layer "In2.Cu")
		(net "M_C_CPU1_SA_DQ<16>")
	)
	(segment
		(start 94.052644 -235.113068)
		(end 94.074996 -235.029756)
		(width 0.0889)
		(layer "In2.Cu")
		(net "M_C_CPU1_SA_DQ<16>")
	)
	(segment
		(start 86.57971 -235.091732)
		(end 86.588092 -235.086906)
		(width 0.0889)
		(layer "In2.Cu")
		(net "M_C_CPU1_SA_DQ<16>")
	)
	(segment
		(start 56.950864 -216.460324)
		(end 57.800748 -215.61044)
		(width 0.14478)
		(layer "In2.Cu")
		(net "M_C_CPU1_SA_DQ<16>")
	)
	(segment
		(start 45.004482 -216.623392)
		(end 45.004482 -216.675716)
		(width 0.14478)
		(layer "In2.Cu")
		(net "M_C_CPU1_SA_DQ<16>")
	)
	(segment
		(start 45.954442 -216.16162)
		(end 46.11751 -216.324688)
		(width 0.14478)
		(layer "In2.Cu")
		(net "M_C_CPU1_SA_DQ<16>")
	)
	(segment
		(start 45.004482 -216.675716)
		(end 45.16755 -216.838784)
		(width 0.14478)
		(layer "In2.Cu")
		(net "M_C_CPU1_SA_DQ<16>")
	)
	(segment
		(start 44.76496 -216.460324)
		(end 44.841414 -216.460324)
		(width 0.14478)
		(layer "In2.Cu")
		(net "M_C_CPU1_SA_DQ<16>")
	)
	(segment
		(start 87.154004 -235.086906)
		(end 87.162386 -235.091732)
		(width 0.0889)
		(layer "In2.Cu")
		(net "M_C_CPU1_SA_DQ<16>")
	)
	(segment
		(start 85.639656 -235.091732)
		(end 85.648038 -235.086906)
		(width 0.0889)
		(layer "In2.Cu")
		(net "M_C_CPU1_SA_DQ<16>")
	)
	(segment
		(start 46.11751 -216.675716)
		(end 46.280578 -216.838784)
		(width 0.14478)
		(layer "In2.Cu")
		(net "M_C_CPU1_SA_DQ<16>")
	)
	(segment
		(start 91.85402 -235.086906)
		(end 91.862402 -235.091732)
		(width 0.0889)
		(layer "In2.Cu")
		(net "M_C_CPU1_SA_DQ<16>")
	)
	(segment
		(start 61.915548 -216.783666)
		(end 62.143894 -216.783666)
		(width 0.14478)
		(layer "In2.Cu")
		(net "M_C_CPU1_SA_DQ<16>")
	)
	(segment
		(start 81.879694 -235.091732)
		(end 81.888076 -235.086906)
		(width 0.0889)
		(layer "In2.Cu")
		(net "M_C_CPU1_SA_DQ<16>")
	)
	(arc
		(start 81.888076 -235.086906)
		(mid 82.171032 -235.010729)
		(end 82.453988 -235.086906)
		(width 0.0889)
		(layer "In2.Cu")
		(net "M_C_CPU1_SA_DQ<16>")
	)
	(arc
		(start 89.034112 -235.086906)
		(mid 89.221056 -235.137161)
		(end 89.408 -235.086906)
		(width 0.0889)
		(layer "In2.Cu")
		(net "M_C_CPU1_SA_DQ<16>")
	)
	(arc
		(start 93.733874 -235.086906)
		(mid 93.890312 -235.135877)
		(end 94.052644 -235.113068)
		(width 0.0889)
		(layer "In2.Cu")
		(net "M_C_CPU1_SA_DQ<16>")
	)
	(arc
		(start 88.10244 -235.091732)
		(mid 88.285948 -235.137226)
		(end 88.4682 -235.086906)
		(width 0.0889)
		(layer "In2.Cu")
		(net "M_C_CPU1_SA_DQ<16>")
	)
	(arc
		(start 90.348054 -235.086906)
		(mid 90.63101 -235.010729)
		(end 90.913966 -235.086906)
		(width 0.0889)
		(layer "In2.Cu")
		(net "M_C_CPU1_SA_DQ<16>")
	)
	(arc
		(start 89.973912 -235.086906)
		(mid 90.156163 -235.137256)
		(end 90.339672 -235.091732)
		(width 0.0889)
		(layer "In2.Cu")
		(net "M_C_CPU1_SA_DQ<16>")
	)
	(arc
		(start 86.588092 -235.086906)
		(mid 86.871048 -235.010729)
		(end 87.154004 -235.086906)
		(width 0.0889)
		(layer "In2.Cu")
		(net "M_C_CPU1_SA_DQ<16>")
	)
	(arc
		(start 92.794074 -235.086906)
		(mid 92.981018 -235.137161)
		(end 93.167962 -235.086906)
		(width 0.0889)
		(layer "In2.Cu")
		(net "M_C_CPU1_SA_DQ<16>")
	)
	(arc
		(start 80.008222 -235.086906)
		(mid 80.291178 -235.010729)
		(end 80.574134 -235.086906)
		(width 0.0889)
		(layer "In2.Cu")
		(net "M_C_CPU1_SA_DQ<16>")
	)
	(arc
		(start 84.707984 -235.086906)
		(mid 84.99094 -235.010729)
		(end 85.273896 -235.086906)
		(width 0.0889)
		(layer "In2.Cu")
		(net "M_C_CPU1_SA_DQ<16>")
	)
	(arc
		(start 87.528146 -235.086906)
		(mid 87.811102 -235.010729)
		(end 88.094058 -235.086906)
		(width 0.0889)
		(layer "In2.Cu")
		(net "M_C_CPU1_SA_DQ<16>")
	)
	(arc
		(start 79.57058 -235.040678)
		(mid 79.600859 -235.065451)
		(end 79.633572 -235.086906)
		(width 0.0889)
		(layer "In2.Cu")
		(net "M_C_CPU1_SA_DQ<16>")
	)
	(arc
		(start 91.288108 -235.086906)
		(mid 91.571064 -235.010729)
		(end 91.85402 -235.086906)
		(width 0.0889)
		(layer "In2.Cu")
		(net "M_C_CPU1_SA_DQ<16>")
	)
	(arc
		(start 83.768184 -235.086906)
		(mid 84.05114 -235.010729)
		(end 84.334096 -235.086906)
		(width 0.0889)
		(layer "In2.Cu")
		(net "M_C_CPU1_SA_DQ<16>")
	)
	(arc
		(start 81.513934 -235.086906)
		(mid 81.696185 -235.137256)
		(end 81.879694 -235.091732)
		(width 0.0889)
		(layer "In2.Cu")
		(net "M_C_CPU1_SA_DQ<16>")
	)
	(arc
		(start 84.334096 -235.086906)
		(mid 84.52104 -235.137161)
		(end 84.707984 -235.086906)
		(width 0.0889)
		(layer "In2.Cu")
		(net "M_C_CPU1_SA_DQ<16>")
	)
	(arc
		(start 80.574134 -235.086906)
		(mid 80.761078 -235.137161)
		(end 80.948022 -235.086906)
		(width 0.0889)
		(layer "In2.Cu")
		(net "M_C_CPU1_SA_DQ<16>")
	)
	(arc
		(start 79.633572 -235.086906)
		(mid 79.816077 -235.137383)
		(end 79.99984 -235.091732)
		(width 0.0889)
		(layer "In2.Cu")
		(net "M_C_CPU1_SA_DQ<16>")
	)
	(arc
		(start 91.862402 -235.091732)
		(mid 92.04591 -235.137226)
		(end 92.228162 -235.086906)
		(width 0.0889)
		(layer "In2.Cu")
		(net "M_C_CPU1_SA_DQ<16>")
	)
	(arc
		(start 89.408 -235.086906)
		(mid 89.690956 -235.010729)
		(end 89.973912 -235.086906)
		(width 0.0889)
		(layer "In2.Cu")
		(net "M_C_CPU1_SA_DQ<16>")
	)
	(arc
		(start 86.21395 -235.086906)
		(mid 86.396201 -235.137256)
		(end 86.57971 -235.091732)
		(width 0.0889)
		(layer "In2.Cu")
		(net "M_C_CPU1_SA_DQ<16>")
	)
	(arc
		(start 88.4682 -235.086906)
		(mid 88.751156 -235.010729)
		(end 89.034112 -235.086906)
		(width 0.0889)
		(layer "In2.Cu")
		(net "M_C_CPU1_SA_DQ<16>")
	)
	(arc
		(start 90.922348 -235.091732)
		(mid 91.105856 -235.137226)
		(end 91.288108 -235.086906)
		(width 0.0889)
		(layer "In2.Cu")
		(net "M_C_CPU1_SA_DQ<16>")
	)
	(arc
		(start 92.228162 -235.086906)
		(mid 92.511118 -235.010729)
		(end 92.794074 -235.086906)
		(width 0.0889)
		(layer "In2.Cu")
		(net "M_C_CPU1_SA_DQ<16>")
	)
	(arc
		(start 83.402424 -235.091732)
		(mid 83.585932 -235.137226)
		(end 83.768184 -235.086906)
		(width 0.0889)
		(layer "In2.Cu")
		(net "M_C_CPU1_SA_DQ<16>")
	)
	(arc
		(start 79.557372 -235.028232)
		(mid 79.5639 -235.034536)
		(end 79.57058 -235.040678)
		(width 0.0889)
		(layer "In2.Cu")
		(net "M_C_CPU1_SA_DQ<16>")
	)
	(arc
		(start 82.46237 -235.091732)
		(mid 82.645878 -235.137226)
		(end 82.82813 -235.086906)
		(width 0.0889)
		(layer "In2.Cu")
		(net "M_C_CPU1_SA_DQ<16>")
	)
	(arc
		(start 85.273896 -235.086906)
		(mid 85.456147 -235.137256)
		(end 85.639656 -235.091732)
		(width 0.0889)
		(layer "In2.Cu")
		(net "M_C_CPU1_SA_DQ<16>")
	)
	(arc
		(start 82.82813 -235.086906)
		(mid 83.111086 -235.010729)
		(end 83.394042 -235.086906)
		(width 0.0889)
		(layer "In2.Cu")
		(net "M_C_CPU1_SA_DQ<16>")
	)
	(arc
		(start 93.167962 -235.086906)
		(mid 93.450918 -235.010729)
		(end 93.733874 -235.086906)
		(width 0.0889)
		(layer "In2.Cu")
		(net "M_C_CPU1_SA_DQ<16>")
	)
	(arc
		(start 80.948022 -235.086906)
		(mid 81.230978 -235.010729)
		(end 81.513934 -235.086906)
		(width 0.0889)
		(layer "In2.Cu")
		(net "M_C_CPU1_SA_DQ<16>")
	)
	(arc
		(start 85.648038 -235.086906)
		(mid 85.930994 -235.010729)
		(end 86.21395 -235.086906)
		(width 0.0889)
		(layer "In2.Cu")
		(net "M_C_CPU1_SA_DQ<16>")
	)
	(arc
		(start 87.162386 -235.091732)
		(mid 87.345894 -235.137226)
		(end 87.528146 -235.086906)
		(width 0.0889)
		(layer "In2.Cu")
		(net "M_C_CPU1_SA_DQ<16>")
	)
	(segment
		(start 96.267778 -235.030264)
		(end 95.800926 -234.764326)
		(width 0.10668)
		(layer "F.Cu")
		(net "M_C_CPU1_SA_DQ<15>")
	)
	(segment
		(start 42.567352 -215.61044)
		(end 49.428146 -215.61044)
		(width 0.14478)
		(layer "In2.Cu")
		(net "M_C_CPU1_SA_DQ<15>")
	)
	(segment
		(start 90.339672 -234.43692)
		(end 90.348054 -234.441746)
		(width 0.0889)
		(layer "In2.Cu")
		(net "M_C_CPU1_SA_DQ<15>")
	)
	(segment
		(start 41.684702 -215.61044)
		(end 41.84777 -215.447372)
		(width 0.14478)
		(layer "In2.Cu")
		(net "M_C_CPU1_SA_DQ<15>")
	)
	(segment
		(start 79.276956 -234.391454)
		(end 79.821024 -234.391454)
		(width 0.0889)
		(layer "In2.Cu")
		(net "M_C_CPU1_SA_DQ<15>")
	)
	(segment
		(start 41.84777 -214.985854)
		(end 42.010838 -214.822786)
		(width 0.14478)
		(layer "In2.Cu")
		(net "M_C_CPU1_SA_DQ<15>")
	)
	(segment
		(start 86.57971 -234.43692)
		(end 86.588092 -234.441746)
		(width 0.0889)
		(layer "In2.Cu")
		(net "M_C_CPU1_SA_DQ<15>")
	)
	(segment
		(start 42.241216 -214.822786)
		(end 42.404284 -214.985854)
		(width 0.14478)
		(layer "In2.Cu")
		(net "M_C_CPU1_SA_DQ<15>")
	)
	(segment
		(start 94.099634 -234.43692)
		(end 94.108016 -234.441746)
		(width 0.0889)
		(layer "In2.Cu")
		(net "M_C_CPU1_SA_DQ<15>")
	)
	(segment
		(start 42.404284 -215.447372)
		(end 42.567352 -215.61044)
		(width 0.14478)
		(layer "In2.Cu")
		(net "M_C_CPU1_SA_DQ<15>")
	)
	(segment
		(start 81.879694 -234.43692)
		(end 81.888076 -234.441746)
		(width 0.0889)
		(layer "In2.Cu")
		(net "M_C_CPU1_SA_DQ<15>")
	)
	(segment
		(start 49.428146 -215.61044)
		(end 50.278284 -214.760302)
		(width 0.14478)
		(layer "In2.Cu")
		(net "M_C_CPU1_SA_DQ<15>")
	)
	(segment
		(start 53.961792 -215.61044)
		(end 56.91632 -215.61044)
		(width 0.14478)
		(layer "In2.Cu")
		(net "M_C_CPU1_SA_DQ<15>")
	)
	(segment
		(start 40.665146 -215.61044)
		(end 41.684702 -215.61044)
		(width 0.14478)
		(layer "In2.Cu")
		(net "M_C_CPU1_SA_DQ<15>")
	)
	(segment
		(start 83.394042 -234.441746)
		(end 83.402424 -234.43692)
		(width 0.0889)
		(layer "In2.Cu")
		(net "M_C_CPU1_SA_DQ<15>")
	)
	(segment
		(start 42.404284 -214.985854)
		(end 42.404284 -215.447372)
		(width 0.14478)
		(layer "In2.Cu")
		(net "M_C_CPU1_SA_DQ<15>")
	)
	(segment
		(start 90.913966 -234.441746)
		(end 90.922348 -234.43692)
		(width 0.0889)
		(layer "In2.Cu")
		(net "M_C_CPU1_SA_DQ<15>")
	)
	(segment
		(start 95.039688 -234.43692)
		(end 95.04807 -234.441746)
		(width 0.0889)
		(layer "In2.Cu")
		(net "M_C_CPU1_SA_DQ<15>")
	)
	(segment
		(start 76.105766 -231.055164)
		(end 76.192126 -231.055164)
		(width 0.14478)
		(layer "In2.Cu")
		(net "M_C_CPU1_SA_DQ<15>")
	)
	(segment
		(start 56.91632 -215.61044)
		(end 57.766458 -214.760302)
		(width 0.14478)
		(layer "In2.Cu")
		(net "M_C_CPU1_SA_DQ<15>")
	)
	(segment
		(start 95.55099 -234.473496)
		(end 95.647002 -234.498896)
		(width 0.0889)
		(layer "In2.Cu")
		(net "M_C_CPU1_SA_DQ<15>")
	)
	(segment
		(start 91.85402 -234.441746)
		(end 91.862402 -234.43692)
		(width 0.0889)
		(layer "In2.Cu")
		(net "M_C_CPU1_SA_DQ<15>")
	)
	(segment
		(start 42.010838 -214.822786)
		(end 42.241216 -214.822786)
		(width 0.14478)
		(layer "In2.Cu")
		(net "M_C_CPU1_SA_DQ<15>")
	)
	(segment
		(start 77.171296 -231.379014)
		(end 77.171296 -232.473754)
		(width 0.0889)
		(layer "In2.Cu")
		(net "M_C_CPU1_SA_DQ<15>")
	)
	(segment
		(start 63.542926 -215.51773)
		(end 63.542926 -216.00541)
		(width 0.14478)
		(layer "In2.Cu")
		(net "M_C_CPU1_SA_DQ<15>")
	)
	(segment
		(start 78.081886 -233.384344)
		(end 78.650846 -233.384344)
		(width 0.0889)
		(layer "In2.Cu")
		(net "M_C_CPU1_SA_DQ<15>")
	)
	(segment
		(start 67.147948 -220.738446)
		(end 72.872346 -226.462844)
		(width 0.14478)
		(layer "In2.Cu")
		(net "M_C_CPU1_SA_DQ<15>")
	)
	(segment
		(start 78.650846 -233.384344)
		(end 79.069946 -233.803444)
		(width 0.0889)
		(layer "In2.Cu")
		(net "M_C_CPU1_SA_DQ<15>")
	)
	(segment
		(start 62.785498 -214.760302)
		(end 63.542926 -215.51773)
		(width 0.14478)
		(layer "In2.Cu")
		(net "M_C_CPU1_SA_DQ<15>")
	)
	(segment
		(start 79.069946 -233.803444)
		(end 79.069946 -234.184444)
		(width 0.0889)
		(layer "In2.Cu")
		(net "M_C_CPU1_SA_DQ<15>")
	)
	(segment
		(start 85.639656 -234.43692)
		(end 85.648038 -234.441746)
		(width 0.0889)
		(layer "In2.Cu")
		(net "M_C_CPU1_SA_DQ<15>")
	)
	(segment
		(start 76.192126 -231.055164)
		(end 76.847446 -231.055164)
		(width 0.0889)
		(layer "In2.Cu")
		(net "M_C_CPU1_SA_DQ<15>")
	)
	(segment
		(start 53.111654 -214.760302)
		(end 53.961792 -215.61044)
		(width 0.14478)
		(layer "In2.Cu")
		(net "M_C_CPU1_SA_DQ<15>")
	)
	(segment
		(start 87.154004 -234.441746)
		(end 87.162386 -234.43692)
		(width 0.0889)
		(layer "In2.Cu")
		(net "M_C_CPU1_SA_DQ<15>")
	)
	(segment
		(start 95.647002 -234.498896)
		(end 95.800926 -234.764326)
		(width 0.0889)
		(layer "In2.Cu")
		(net "M_C_CPU1_SA_DQ<15>")
	)
	(segment
		(start 72.872346 -226.462844)
		(end 72.872346 -227.821744)
		(width 0.14478)
		(layer "In2.Cu")
		(net "M_C_CPU1_SA_DQ<15>")
	)
	(segment
		(start 79.069946 -234.184444)
		(end 79.276956 -234.391454)
		(width 0.0889)
		(layer "In2.Cu")
		(net "M_C_CPU1_SA_DQ<15>")
	)
	(segment
		(start 40.23995 -215.185244)
		(end 40.665146 -215.61044)
		(width 0.14478)
		(layer "In2.Cu")
		(net "M_C_CPU1_SA_DQ<15>")
	)
	(segment
		(start 72.872346 -227.821744)
		(end 76.105766 -231.055164)
		(width 0.14478)
		(layer "In2.Cu")
		(net "M_C_CPU1_SA_DQ<15>")
	)
	(segment
		(start 41.84777 -215.447372)
		(end 41.84777 -214.985854)
		(width 0.14478)
		(layer "In2.Cu")
		(net "M_C_CPU1_SA_DQ<15>")
	)
	(segment
		(start 82.453988 -234.441746)
		(end 82.46237 -234.43692)
		(width 0.0889)
		(layer "In2.Cu")
		(net "M_C_CPU1_SA_DQ<15>")
	)
	(segment
		(start 50.278284 -214.760302)
		(end 53.111654 -214.760302)
		(width 0.14478)
		(layer "In2.Cu")
		(net "M_C_CPU1_SA_DQ<15>")
	)
	(segment
		(start 77.171296 -232.473754)
		(end 78.081886 -233.384344)
		(width 0.0889)
		(layer "In2.Cu")
		(net "M_C_CPU1_SA_DQ<15>")
	)
	(segment
		(start 88.094058 -234.441746)
		(end 88.10244 -234.43692)
		(width 0.0889)
		(layer "In2.Cu")
		(net "M_C_CPU1_SA_DQ<15>")
	)
	(segment
		(start 63.542926 -216.00541)
		(end 67.147948 -219.610432)
		(width 0.14478)
		(layer "In2.Cu")
		(net "M_C_CPU1_SA_DQ<15>")
	)
	(segment
		(start 76.847446 -231.055164)
		(end 77.171296 -231.379014)
		(width 0.0889)
		(layer "In2.Cu")
		(net "M_C_CPU1_SA_DQ<15>")
	)
	(segment
		(start 67.147948 -219.610432)
		(end 67.147948 -220.738446)
		(width 0.14478)
		(layer "In2.Cu")
		(net "M_C_CPU1_SA_DQ<15>")
	)
	(segment
		(start 57.766458 -214.760302)
		(end 62.785498 -214.760302)
		(width 0.14478)
		(layer "In2.Cu")
		(net "M_C_CPU1_SA_DQ<15>")
	)
	(arc
		(start 88.10244 -234.43692)
		(mid 88.285948 -234.391426)
		(end 88.4682 -234.441746)
		(width 0.0889)
		(layer "In2.Cu")
		(net "M_C_CPU1_SA_DQ<15>")
	)
	(arc
		(start 93.167962 -234.441746)
		(mid 93.450918 -234.517923)
		(end 93.733874 -234.441746)
		(width 0.0889)
		(layer "In2.Cu")
		(net "M_C_CPU1_SA_DQ<15>")
	)
	(arc
		(start 87.528146 -234.441746)
		(mid 87.811102 -234.517923)
		(end 88.094058 -234.441746)
		(width 0.0889)
		(layer "In2.Cu")
		(net "M_C_CPU1_SA_DQ<15>")
	)
	(arc
		(start 93.733874 -234.441746)
		(mid 93.916125 -234.391396)
		(end 94.099634 -234.43692)
		(width 0.0889)
		(layer "In2.Cu")
		(net "M_C_CPU1_SA_DQ<15>")
	)
	(arc
		(start 83.402424 -234.43692)
		(mid 83.585932 -234.391426)
		(end 83.768184 -234.441746)
		(width 0.0889)
		(layer "In2.Cu")
		(net "M_C_CPU1_SA_DQ<15>")
	)
	(arc
		(start 84.707984 -234.441746)
		(mid 84.99094 -234.517923)
		(end 85.273896 -234.441746)
		(width 0.0889)
		(layer "In2.Cu")
		(net "M_C_CPU1_SA_DQ<15>")
	)
	(arc
		(start 92.228162 -234.441746)
		(mid 92.511118 -234.517923)
		(end 92.794074 -234.441746)
		(width 0.0889)
		(layer "In2.Cu")
		(net "M_C_CPU1_SA_DQ<15>")
	)
	(arc
		(start 86.588092 -234.441746)
		(mid 86.871048 -234.517923)
		(end 87.154004 -234.441746)
		(width 0.0889)
		(layer "In2.Cu")
		(net "M_C_CPU1_SA_DQ<15>")
	)
	(arc
		(start 81.513934 -234.441746)
		(mid 81.696185 -234.391396)
		(end 81.879694 -234.43692)
		(width 0.0889)
		(layer "In2.Cu")
		(net "M_C_CPU1_SA_DQ<15>")
	)
	(arc
		(start 80.574134 -234.441746)
		(mid 80.761078 -234.391491)
		(end 80.948022 -234.441746)
		(width 0.0889)
		(layer "In2.Cu")
		(net "M_C_CPU1_SA_DQ<15>")
	)
	(arc
		(start 83.768184 -234.441746)
		(mid 84.05114 -234.517923)
		(end 84.334096 -234.441746)
		(width 0.0889)
		(layer "In2.Cu")
		(net "M_C_CPU1_SA_DQ<15>")
	)
	(arc
		(start 81.888076 -234.441746)
		(mid 82.171032 -234.517923)
		(end 82.453988 -234.441746)
		(width 0.0889)
		(layer "In2.Cu")
		(net "M_C_CPU1_SA_DQ<15>")
	)
	(arc
		(start 82.82813 -234.441746)
		(mid 83.111086 -234.517923)
		(end 83.394042 -234.441746)
		(width 0.0889)
		(layer "In2.Cu")
		(net "M_C_CPU1_SA_DQ<15>")
	)
	(arc
		(start 89.408 -234.441746)
		(mid 89.690956 -234.517923)
		(end 89.973912 -234.441746)
		(width 0.0889)
		(layer "In2.Cu")
		(net "M_C_CPU1_SA_DQ<15>")
	)
	(arc
		(start 85.648038 -234.441746)
		(mid 85.930994 -234.517923)
		(end 86.21395 -234.441746)
		(width 0.0889)
		(layer "In2.Cu")
		(net "M_C_CPU1_SA_DQ<15>")
	)
	(arc
		(start 89.973912 -234.441746)
		(mid 90.156163 -234.391396)
		(end 90.339672 -234.43692)
		(width 0.0889)
		(layer "In2.Cu")
		(net "M_C_CPU1_SA_DQ<15>")
	)
	(arc
		(start 95.04807 -234.441746)
		(mid 95.295783 -234.516966)
		(end 95.55099 -234.473496)
		(width 0.0889)
		(layer "In2.Cu")
		(net "M_C_CPU1_SA_DQ<15>")
	)
	(arc
		(start 87.162386 -234.43692)
		(mid 87.345894 -234.391426)
		(end 87.528146 -234.441746)
		(width 0.0889)
		(layer "In2.Cu")
		(net "M_C_CPU1_SA_DQ<15>")
	)
	(arc
		(start 90.922348 -234.43692)
		(mid 91.105856 -234.391426)
		(end 91.288108 -234.441746)
		(width 0.0889)
		(layer "In2.Cu")
		(net "M_C_CPU1_SA_DQ<15>")
	)
	(arc
		(start 79.821024 -234.391454)
		(mid 79.917956 -234.404205)
		(end 80.008222 -234.441746)
		(width 0.0889)
		(layer "In2.Cu")
		(net "M_C_CPU1_SA_DQ<15>")
	)
	(arc
		(start 85.273896 -234.441746)
		(mid 85.456147 -234.391396)
		(end 85.639656 -234.43692)
		(width 0.0889)
		(layer "In2.Cu")
		(net "M_C_CPU1_SA_DQ<15>")
	)
	(arc
		(start 94.673928 -234.441746)
		(mid 94.856179 -234.391396)
		(end 95.039688 -234.43692)
		(width 0.0889)
		(layer "In2.Cu")
		(net "M_C_CPU1_SA_DQ<15>")
	)
	(arc
		(start 91.288108 -234.441746)
		(mid 91.571064 -234.517923)
		(end 91.85402 -234.441746)
		(width 0.0889)
		(layer "In2.Cu")
		(net "M_C_CPU1_SA_DQ<15>")
	)
	(arc
		(start 84.334096 -234.441746)
		(mid 84.52104 -234.391491)
		(end 84.707984 -234.441746)
		(width 0.0889)
		(layer "In2.Cu")
		(net "M_C_CPU1_SA_DQ<15>")
	)
	(arc
		(start 88.4682 -234.441746)
		(mid 88.751156 -234.517923)
		(end 89.034112 -234.441746)
		(width 0.0889)
		(layer "In2.Cu")
		(net "M_C_CPU1_SA_DQ<15>")
	)
	(arc
		(start 91.862402 -234.43692)
		(mid 92.04591 -234.391426)
		(end 92.228162 -234.441746)
		(width 0.0889)
		(layer "In2.Cu")
		(net "M_C_CPU1_SA_DQ<15>")
	)
	(arc
		(start 90.348054 -234.441746)
		(mid 90.63101 -234.517923)
		(end 90.913966 -234.441746)
		(width 0.0889)
		(layer "In2.Cu")
		(net "M_C_CPU1_SA_DQ<15>")
	)
	(arc
		(start 80.948022 -234.441746)
		(mid 81.230978 -234.517923)
		(end 81.513934 -234.441746)
		(width 0.0889)
		(layer "In2.Cu")
		(net "M_C_CPU1_SA_DQ<15>")
	)
	(arc
		(start 86.21395 -234.441746)
		(mid 86.396201 -234.391396)
		(end 86.57971 -234.43692)
		(width 0.0889)
		(layer "In2.Cu")
		(net "M_C_CPU1_SA_DQ<15>")
	)
	(arc
		(start 82.46237 -234.43692)
		(mid 82.645878 -234.391426)
		(end 82.82813 -234.441746)
		(width 0.0889)
		(layer "In2.Cu")
		(net "M_C_CPU1_SA_DQ<15>")
	)
	(arc
		(start 94.108016 -234.441746)
		(mid 94.390972 -234.517923)
		(end 94.673928 -234.441746)
		(width 0.0889)
		(layer "In2.Cu")
		(net "M_C_CPU1_SA_DQ<15>")
	)
	(arc
		(start 80.008222 -234.441746)
		(mid 80.291178 -234.517923)
		(end 80.574134 -234.441746)
		(width 0.0889)
		(layer "In2.Cu")
		(net "M_C_CPU1_SA_DQ<15>")
	)
	(arc
		(start 89.034112 -234.441746)
		(mid 89.221056 -234.391491)
		(end 89.408 -234.441746)
		(width 0.0889)
		(layer "In2.Cu")
		(net "M_C_CPU1_SA_DQ<15>")
	)
	(arc
		(start 92.794074 -234.441746)
		(mid 92.981018 -234.391491)
		(end 93.167962 -234.441746)
		(width 0.0889)
		(layer "In2.Cu")
		(net "M_C_CPU1_SA_DQ<15>")
	)
	(segment
		(start 94.857824 -234.220258)
		(end 94.390972 -233.95432)
		(width 0.10668)
		(layer "F.Cu")
		(net "M_C_CPU1_SA_DQ<14>")
	)
	(segment
		(start 40.665146 -213.910418)
		(end 42.20972 -213.910418)
		(width 0.14478)
		(layer "In2.Cu")
		(net "M_C_CPU1_SA_DQ<14>")
	)
	(segment
		(start 78.79334 -232.929684)
		(end 79.410052 -233.546396)
		(width 0.0889)
		(layer "In2.Cu")
		(net "M_C_CPU1_SA_DQ<14>")
	)
	(segment
		(start 43.09237 -213.910418)
		(end 49.640998 -213.910418)
		(width 0.14478)
		(layer "In2.Cu")
		(net "M_C_CPU1_SA_DQ<14>")
	)
	(segment
		(start 73.786746 -226.065842)
		(end 73.786746 -227.346764)
		(width 0.14478)
		(layer "In2.Cu")
		(net "M_C_CPU1_SA_DQ<14>")
	)
	(segment
		(start 64.472566 -215.61425)
		(end 68.108576 -219.25026)
		(width 0.14478)
		(layer "In2.Cu")
		(net "M_C_CPU1_SA_DQ<14>")
	)
	(segment
		(start 77.639926 -231.410764)
		(end 78.010766 -231.781604)
		(width 0.0889)
		(layer "In2.Cu")
		(net "M_C_CPU1_SA_DQ<14>")
	)
	(segment
		(start 60.503054 -213.06028)
		(end 61.266578 -213.823804)
		(width 0.14478)
		(layer "In2.Cu")
		(net "M_C_CPU1_SA_DQ<14>")
	)
	(segment
		(start 75.771248 -229.331266)
		(end 76.48321 -229.331266)
		(width 0.14478)
		(layer "In2.Cu")
		(net "M_C_CPU1_SA_DQ<14>")
	)
	(segment
		(start 73.786746 -227.346764)
		(end 75.771248 -229.331266)
		(width 0.14478)
		(layer "In2.Cu")
		(net "M_C_CPU1_SA_DQ<14>")
	)
	(segment
		(start 42.372788 -213.74735)
		(end 42.372788 -212.658452)
		(width 0.14478)
		(layer "In2.Cu")
		(net "M_C_CPU1_SA_DQ<14>")
	)
	(segment
		(start 42.535856 -212.495384)
		(end 42.766234 -212.495384)
		(width 0.14478)
		(layer "In2.Cu")
		(net "M_C_CPU1_SA_DQ<14>")
	)
	(segment
		(start 68.108576 -219.25026)
		(end 68.108576 -220.387672)
		(width 0.14478)
		(layer "In2.Cu")
		(net "M_C_CPU1_SA_DQ<14>")
	)
	(segment
		(start 42.929302 -212.658452)
		(end 42.929302 -213.74735)
		(width 0.14478)
		(layer "In2.Cu")
		(net "M_C_CPU1_SA_DQ<14>")
	)
	(segment
		(start 85.74405 -233.63174)
		(end 85.752432 -233.626914)
		(width 0.0889)
		(layer "In2.Cu")
		(net "M_C_CPU1_SA_DQ<14>")
	)
	(segment
		(start 94.141036 -233.66349)
		(end 94.237048 -233.68889)
		(width 0.0889)
		(layer "In2.Cu")
		(net "M_C_CPU1_SA_DQ<14>")
	)
	(segment
		(start 57.139332 -213.910418)
		(end 57.98947 -213.06028)
		(width 0.14478)
		(layer "In2.Cu")
		(net "M_C_CPU1_SA_DQ<14>")
	)
	(segment
		(start 78.47584 -232.929684)
		(end 78.79334 -232.929684)
		(width 0.0889)
		(layer "In2.Cu")
		(net "M_C_CPU1_SA_DQ<14>")
	)
	(segment
		(start 68.108576 -220.387672)
		(end 73.786746 -226.065842)
		(width 0.14478)
		(layer "In2.Cu")
		(net "M_C_CPU1_SA_DQ<14>")
	)
	(segment
		(start 63.2079 -213.823804)
		(end 64.472566 -215.08847)
		(width 0.14478)
		(layer "In2.Cu")
		(net "M_C_CPU1_SA_DQ<14>")
	)
	(segment
		(start 78.010766 -232.46461)
		(end 78.47584 -232.929684)
		(width 0.0889)
		(layer "In2.Cu")
		(net "M_C_CPU1_SA_DQ<14>")
	)
	(segment
		(start 80.46974 -233.626914)
		(end 80.478122 -233.63174)
		(width 0.0889)
		(layer "In2.Cu")
		(net "M_C_CPU1_SA_DQ<14>")
	)
	(segment
		(start 64.472566 -215.08847)
		(end 64.472566 -215.61425)
		(width 0.14478)
		(layer "In2.Cu")
		(net "M_C_CPU1_SA_DQ<14>")
	)
	(segment
		(start 40.23995 -213.485222)
		(end 40.665146 -213.910418)
		(width 0.14478)
		(layer "In2.Cu")
		(net "M_C_CPU1_SA_DQ<14>")
	)
	(segment
		(start 77.639926 -230.12273)
		(end 77.639926 -231.410764)
		(width 0.0889)
		(layer "In2.Cu")
		(net "M_C_CPU1_SA_DQ<14>")
	)
	(segment
		(start 42.929302 -213.74735)
		(end 43.09237 -213.910418)
		(width 0.14478)
		(layer "In2.Cu")
		(net "M_C_CPU1_SA_DQ<14>")
	)
	(segment
		(start 53.111654 -213.06028)
		(end 53.961792 -213.910418)
		(width 0.14478)
		(layer "In2.Cu")
		(net "M_C_CPU1_SA_DQ<14>")
	)
	(segment
		(start 42.372788 -212.658452)
		(end 42.535856 -212.495384)
		(width 0.14478)
		(layer "In2.Cu")
		(net "M_C_CPU1_SA_DQ<14>")
	)
	(segment
		(start 88.929718 -233.626914)
		(end 88.9381 -233.63174)
		(width 0.0889)
		(layer "In2.Cu")
		(net "M_C_CPU1_SA_DQ<14>")
	)
	(segment
		(start 79.587852 -233.659426)
		(end 79.629508 -233.674412)
		(width 0.0889)
		(layer "In2.Cu")
		(net "M_C_CPU1_SA_DQ<14>")
	)
	(segment
		(start 83.289648 -233.626914)
		(end 83.29803 -233.63174)
		(width 0.0889)
		(layer "In2.Cu")
		(net "M_C_CPU1_SA_DQ<14>")
	)
	(segment
		(start 76.848462 -229.331266)
		(end 77.639926 -230.12273)
		(width 0.0889)
		(layer "In2.Cu")
		(net "M_C_CPU1_SA_DQ<14>")
	)
	(segment
		(start 91.749626 -233.626914)
		(end 91.758008 -233.63174)
		(width 0.0889)
		(layer "In2.Cu")
		(net "M_C_CPU1_SA_DQ<14>")
	)
	(segment
		(start 49.640998 -213.910418)
		(end 50.491136 -213.06028)
		(width 0.14478)
		(layer "In2.Cu")
		(net "M_C_CPU1_SA_DQ<14>")
	)
	(segment
		(start 93.263974 -233.63174)
		(end 93.272356 -233.626914)
		(width 0.0889)
		(layer "In2.Cu")
		(net "M_C_CPU1_SA_DQ<14>")
	)
	(segment
		(start 42.20972 -213.910418)
		(end 42.372788 -213.74735)
		(width 0.14478)
		(layer "In2.Cu")
		(net "M_C_CPU1_SA_DQ<14>")
	)
	(segment
		(start 61.266578 -213.823804)
		(end 63.2079 -213.823804)
		(width 0.14478)
		(layer "In2.Cu")
		(net "M_C_CPU1_SA_DQ<14>")
	)
	(segment
		(start 89.504012 -233.63174)
		(end 89.512394 -233.626914)
		(width 0.0889)
		(layer "In2.Cu")
		(net "M_C_CPU1_SA_DQ<14>")
	)
	(segment
		(start 50.491136 -213.06028)
		(end 53.111654 -213.06028)
		(width 0.14478)
		(layer "In2.Cu")
		(net "M_C_CPU1_SA_DQ<14>")
	)
	(segment
		(start 87.989664 -233.626914)
		(end 87.998046 -233.63174)
		(width 0.0889)
		(layer "In2.Cu")
		(net "M_C_CPU1_SA_DQ<14>")
	)
	(segment
		(start 92.68968 -233.626914)
		(end 92.698062 -233.63174)
		(width 0.0889)
		(layer "In2.Cu")
		(net "M_C_CPU1_SA_DQ<14>")
	)
	(segment
		(start 94.237048 -233.68889)
		(end 94.390972 -233.95432)
		(width 0.0889)
		(layer "In2.Cu")
		(net "M_C_CPU1_SA_DQ<14>")
	)
	(segment
		(start 57.98947 -213.06028)
		(end 60.503054 -213.06028)
		(width 0.14478)
		(layer "In2.Cu")
		(net "M_C_CPU1_SA_DQ<14>")
	)
	(segment
		(start 42.766234 -212.495384)
		(end 42.929302 -212.658452)
		(width 0.14478)
		(layer "In2.Cu")
		(net "M_C_CPU1_SA_DQ<14>")
	)
	(segment
		(start 76.48321 -229.331266)
		(end 76.848462 -229.331266)
		(width 0.0889)
		(layer "In2.Cu")
		(net "M_C_CPU1_SA_DQ<14>")
	)
	(segment
		(start 84.803996 -233.63174)
		(end 84.812378 -233.626914)
		(width 0.0889)
		(layer "In2.Cu")
		(net "M_C_CPU1_SA_DQ<14>")
	)
	(segment
		(start 84.229702 -233.626914)
		(end 84.238084 -233.63174)
		(width 0.0889)
		(layer "In2.Cu")
		(net "M_C_CPU1_SA_DQ<14>")
	)
	(segment
		(start 81.044034 -233.63174)
		(end 81.052416 -233.626914)
		(width 0.0889)
		(layer "In2.Cu")
		(net "M_C_CPU1_SA_DQ<14>")
	)
	(segment
		(start 53.961792 -213.910418)
		(end 57.139332 -213.910418)
		(width 0.14478)
		(layer "In2.Cu")
		(net "M_C_CPU1_SA_DQ<14>")
	)
	(segment
		(start 78.010766 -231.781604)
		(end 78.010766 -232.46461)
		(width 0.0889)
		(layer "In2.Cu")
		(net "M_C_CPU1_SA_DQ<14>")
	)
	(arc
		(start 87.057992 -233.63174)
		(mid 87.340948 -233.707917)
		(end 87.623904 -233.63174)
		(width 0.0889)
		(layer "In2.Cu")
		(net "M_C_CPU1_SA_DQ<14>")
	)
	(arc
		(start 87.623904 -233.63174)
		(mid 87.806155 -233.58139)
		(end 87.989664 -233.626914)
		(width 0.0889)
		(layer "In2.Cu")
		(net "M_C_CPU1_SA_DQ<14>")
	)
	(arc
		(start 80.478122 -233.63174)
		(mid 80.761078 -233.707917)
		(end 81.044034 -233.63174)
		(width 0.0889)
		(layer "In2.Cu")
		(net "M_C_CPU1_SA_DQ<14>")
	)
	(arc
		(start 92.698062 -233.63174)
		(mid 92.981018 -233.707917)
		(end 93.263974 -233.63174)
		(width 0.0889)
		(layer "In2.Cu")
		(net "M_C_CPU1_SA_DQ<14>")
	)
	(arc
		(start 92.32392 -233.63174)
		(mid 92.506171 -233.58139)
		(end 92.68968 -233.626914)
		(width 0.0889)
		(layer "In2.Cu")
		(net "M_C_CPU1_SA_DQ<14>")
	)
	(arc
		(start 88.563958 -233.63174)
		(mid 88.746209 -233.58139)
		(end 88.929718 -233.626914)
		(width 0.0889)
		(layer "In2.Cu")
		(net "M_C_CPU1_SA_DQ<14>")
	)
	(arc
		(start 81.418176 -233.63174)
		(mid 81.701132 -233.707917)
		(end 81.984088 -233.63174)
		(width 0.0889)
		(layer "In2.Cu")
		(net "M_C_CPU1_SA_DQ<14>")
	)
	(arc
		(start 93.638116 -233.63174)
		(mid 93.885829 -233.70696)
		(end 94.141036 -233.66349)
		(width 0.0889)
		(layer "In2.Cu")
		(net "M_C_CPU1_SA_DQ<14>")
	)
	(arc
		(start 90.817954 -233.63174)
		(mid 91.10091 -233.707917)
		(end 91.383866 -233.63174)
		(width 0.0889)
		(layer "In2.Cu")
		(net "M_C_CPU1_SA_DQ<14>")
	)
	(arc
		(start 91.383866 -233.63174)
		(mid 91.566117 -233.58139)
		(end 91.749626 -233.626914)
		(width 0.0889)
		(layer "In2.Cu")
		(net "M_C_CPU1_SA_DQ<14>")
	)
	(arc
		(start 90.444066 -233.63174)
		(mid 90.63101 -233.581485)
		(end 90.817954 -233.63174)
		(width 0.0889)
		(layer "In2.Cu")
		(net "M_C_CPU1_SA_DQ<14>")
	)
	(arc
		(start 84.812378 -233.626914)
		(mid 84.995886 -233.58142)
		(end 85.178138 -233.63174)
		(width 0.0889)
		(layer "In2.Cu")
		(net "M_C_CPU1_SA_DQ<14>")
	)
	(arc
		(start 85.752432 -233.626914)
		(mid 85.93594 -233.58142)
		(end 86.118192 -233.63174)
		(width 0.0889)
		(layer "In2.Cu")
		(net "M_C_CPU1_SA_DQ<14>")
	)
	(arc
		(start 89.512394 -233.626914)
		(mid 89.695902 -233.58142)
		(end 89.878154 -233.63174)
		(width 0.0889)
		(layer "In2.Cu")
		(net "M_C_CPU1_SA_DQ<14>")
	)
	(arc
		(start 86.118192 -233.63174)
		(mid 86.401148 -233.707917)
		(end 86.684104 -233.63174)
		(width 0.0889)
		(layer "In2.Cu")
		(net "M_C_CPU1_SA_DQ<14>")
	)
	(arc
		(start 80.10398 -233.63174)
		(mid 80.286231 -233.58139)
		(end 80.46974 -233.626914)
		(width 0.0889)
		(layer "In2.Cu")
		(net "M_C_CPU1_SA_DQ<14>")
	)
	(arc
		(start 93.272356 -233.626914)
		(mid 93.455864 -233.58142)
		(end 93.638116 -233.63174)
		(width 0.0889)
		(layer "In2.Cu")
		(net "M_C_CPU1_SA_DQ<14>")
	)
	(arc
		(start 87.998046 -233.63174)
		(mid 88.281002 -233.707917)
		(end 88.563958 -233.63174)
		(width 0.0889)
		(layer "In2.Cu")
		(net "M_C_CPU1_SA_DQ<14>")
	)
	(arc
		(start 81.984088 -233.63174)
		(mid 82.171032 -233.581485)
		(end 82.357976 -233.63174)
		(width 0.0889)
		(layer "In2.Cu")
		(net "M_C_CPU1_SA_DQ<14>")
	)
	(arc
		(start 91.758008 -233.63174)
		(mid 92.040964 -233.707917)
		(end 92.32392 -233.63174)
		(width 0.0889)
		(layer "In2.Cu")
		(net "M_C_CPU1_SA_DQ<14>")
	)
	(arc
		(start 83.863942 -233.63174)
		(mid 84.046193 -233.58139)
		(end 84.229702 -233.626914)
		(width 0.0889)
		(layer "In2.Cu")
		(net "M_C_CPU1_SA_DQ<14>")
	)
	(arc
		(start 89.878154 -233.63174)
		(mid 90.16111 -233.707917)
		(end 90.444066 -233.63174)
		(width 0.0889)
		(layer "In2.Cu")
		(net "M_C_CPU1_SA_DQ<14>")
	)
	(arc
		(start 79.410052 -233.546396)
		(mid 79.492722 -233.612713)
		(end 79.587852 -233.659426)
		(width 0.0889)
		(layer "In2.Cu")
		(net "M_C_CPU1_SA_DQ<14>")
	)
	(arc
		(start 86.684104 -233.63174)
		(mid 86.871048 -233.581485)
		(end 87.057992 -233.63174)
		(width 0.0889)
		(layer "In2.Cu")
		(net "M_C_CPU1_SA_DQ<14>")
	)
	(arc
		(start 79.629508 -233.674412)
		(mid 79.871479 -233.705684)
		(end 80.10398 -233.63174)
		(width 0.0889)
		(layer "In2.Cu")
		(net "M_C_CPU1_SA_DQ<14>")
	)
	(arc
		(start 88.9381 -233.63174)
		(mid 89.221056 -233.707917)
		(end 89.504012 -233.63174)
		(width 0.0889)
		(layer "In2.Cu")
		(net "M_C_CPU1_SA_DQ<14>")
	)
	(arc
		(start 84.238084 -233.63174)
		(mid 84.52104 -233.707917)
		(end 84.803996 -233.63174)
		(width 0.0889)
		(layer "In2.Cu")
		(net "M_C_CPU1_SA_DQ<14>")
	)
	(arc
		(start 85.178138 -233.63174)
		(mid 85.461094 -233.707917)
		(end 85.74405 -233.63174)
		(width 0.0889)
		(layer "In2.Cu")
		(net "M_C_CPU1_SA_DQ<14>")
	)
	(arc
		(start 81.052416 -233.626914)
		(mid 81.235924 -233.58142)
		(end 81.418176 -233.63174)
		(width 0.0889)
		(layer "In2.Cu")
		(net "M_C_CPU1_SA_DQ<14>")
	)
	(arc
		(start 82.357976 -233.63174)
		(mid 82.640932 -233.707917)
		(end 82.923888 -233.63174)
		(width 0.0889)
		(layer "In2.Cu")
		(net "M_C_CPU1_SA_DQ<14>")
	)
	(arc
		(start 83.29803 -233.63174)
		(mid 83.580986 -233.707917)
		(end 83.863942 -233.63174)
		(width 0.0889)
		(layer "In2.Cu")
		(net "M_C_CPU1_SA_DQ<14>")
	)
	(arc
		(start 82.923888 -233.63174)
		(mid 83.106139 -233.58139)
		(end 83.289648 -233.626914)
		(width 0.0889)
		(layer "In2.Cu")
		(net "M_C_CPU1_SA_DQ<14>")
	)
	(segment
		(start 95.797878 -234.220258)
		(end 95.331026 -233.95432)
		(width 0.10668)
		(layer "F.Cu")
		(net "M_C_CPU1_SA_DQ<13>")
	)
	(segment
		(start 73.332086 -227.552504)
		(end 76.239116 -230.459534)
		(width 0.14478)
		(layer "In2.Cu")
		(net "M_C_CPU1_SA_DQ<13>")
	)
	(segment
		(start 53.096922 -213.910418)
		(end 53.102764 -213.910418)
		(width 0.14478)
		(layer "In2.Cu")
		(net "M_C_CPU1_SA_DQ<13>")
	)
	(segment
		(start 46.627288 -214.532972)
		(end 46.790356 -214.369904)
		(width 0.14478)
		(layer "In2.Cu")
		(net "M_C_CPU1_SA_DQ<13>")
	)
	(segment
		(start 58.27903 -213.74735)
		(end 58.27903 -213.687152)
		(width 0.14478)
		(layer "In2.Cu")
		(net "M_C_CPU1_SA_DQ<13>")
	)
	(segment
		(start 95.462598 -234.303062)
		(end 95.48495 -234.21975)
		(width 0.0889)
		(layer "In2.Cu")
		(net "M_C_CPU1_SA_DQ<13>")
	)
	(segment
		(start 60.330842 -213.524084)
		(end 60.49391 -213.687152)
		(width 0.14478)
		(layer "In2.Cu")
		(net "M_C_CPU1_SA_DQ<13>")
	)
	(segment
		(start 52.37734 -213.74735)
		(end 52.37734 -213.692232)
		(width 0.14478)
		(layer "In2.Cu")
		(net "M_C_CPU1_SA_DQ<13>")
	)
	(segment
		(start 52.37734 -213.692232)
		(end 52.540408 -213.529164)
		(width 0.14478)
		(layer "In2.Cu")
		(net "M_C_CPU1_SA_DQ<13>")
	)
	(segment
		(start 92.68968 -234.281726)
		(end 92.698062 -234.2769)
		(width 0.0889)
		(layer "In2.Cu")
		(net "M_C_CPU1_SA_DQ<13>")
	)
	(segment
		(start 48.394874 -214.538052)
		(end 48.557942 -214.374984)
		(width 0.14478)
		(layer "In2.Cu")
		(net "M_C_CPU1_SA_DQ<13>")
	)
	(segment
		(start 53.952648 -214.760302)
		(end 54.178708 -214.760302)
		(width 0.14478)
		(layer "In2.Cu")
		(net "M_C_CPU1_SA_DQ<13>")
	)
	(segment
		(start 54.735222 -214.374984)
		(end 54.89829 -214.538052)
		(width 0.14478)
		(layer "In2.Cu")
		(net "M_C_CPU1_SA_DQ<13>")
	)
	(segment
		(start 54.504844 -214.374984)
		(end 54.735222 -214.374984)
		(width 0.14478)
		(layer "In2.Cu")
		(net "M_C_CPU1_SA_DQ<13>")
	)
	(segment
		(start 45.351192 -215.152224)
		(end 45.51426 -214.989156)
		(width 0.14478)
		(layer "In2.Cu")
		(net "M_C_CPU1_SA_DQ<13>")
	)
	(segment
		(start 50.277268 -213.910418)
		(end 50.690272 -213.910418)
		(width 0.14478)
		(layer "In2.Cu")
		(net "M_C_CPU1_SA_DQ<13>")
	)
	(segment
		(start 50.85334 -213.74735)
		(end 50.85334 -213.679532)
		(width 0.14478)
		(layer "In2.Cu")
		(net "M_C_CPU1_SA_DQ<13>")
	)
	(segment
		(start 77.418946 -231.108504)
		(end 77.418946 -231.720644)
		(width 0.0889)
		(layer "In2.Cu")
		(net "M_C_CPU1_SA_DQ<13>")
	)
	(segment
		(start 77.700886 -232.589578)
		(end 78.261972 -233.150664)
		(width 0.0889)
		(layer "In2.Cu")
		(net "M_C_CPU1_SA_DQ<13>")
	)
	(segment
		(start 58.672476 -213.524084)
		(end 58.835544 -213.687152)
		(width 0.14478)
		(layer "In2.Cu")
		(net "M_C_CPU1_SA_DQ<13>")
	)
	(segment
		(start 59.937396 -213.74735)
		(end 59.937396 -213.687152)
		(width 0.14478)
		(layer "In2.Cu")
		(net "M_C_CPU1_SA_DQ<13>")
	)
	(segment
		(start 51.409854 -213.679532)
		(end 51.409854 -213.74735)
		(width 0.14478)
		(layer "In2.Cu")
		(net "M_C_CPU1_SA_DQ<13>")
	)
	(segment
		(start 44.795186 -215.002364)
		(end 44.945046 -215.152224)
		(width 0.14478)
		(layer "In2.Cu")
		(net "M_C_CPU1_SA_DQ<13>")
	)
	(segment
		(start 84.803996 -234.2769)
		(end 84.812378 -234.281726)
		(width 0.0889)
		(layer "In2.Cu")
		(net "M_C_CPU1_SA_DQ<13>")
	)
	(segment
		(start 95.48495 -234.21975)
		(end 95.331026 -233.95432)
		(width 0.0889)
		(layer "In2.Cu")
		(net "M_C_CPU1_SA_DQ<13>")
	)
	(segment
		(start 54.89829 -214.538052)
		(end 54.89829 -214.597234)
		(width 0.14478)
		(layer "In2.Cu")
		(net "M_C_CPU1_SA_DQ<13>")
	)
	(segment
		(start 53.102764 -213.910418)
		(end 53.952648 -214.760302)
		(width 0.14478)
		(layer "In2.Cu")
		(net "M_C_CPU1_SA_DQ<13>")
	)
	(segment
		(start 51.246786 -213.516464)
		(end 51.409854 -213.679532)
		(width 0.14478)
		(layer "In2.Cu")
		(net "M_C_CPU1_SA_DQ<13>")
	)
	(segment
		(start 46.233842 -215.16086)
		(end 46.46422 -215.16086)
		(width 0.14478)
		(layer "In2.Cu")
		(net "M_C_CPU1_SA_DQ<13>")
	)
	(segment
		(start 93.263974 -234.2769)
		(end 93.272356 -234.281726)
		(width 0.0889)
		(layer "In2.Cu")
		(net "M_C_CPU1_SA_DQ<13>")
	)
	(segment
		(start 46.46422 -215.16086)
		(end 46.627288 -214.997792)
		(width 0.14478)
		(layer "In2.Cu")
		(net "M_C_CPU1_SA_DQ<13>")
	)
	(segment
		(start 80.46974 -234.281726)
		(end 80.478122 -234.2769)
		(width 0.0889)
		(layer "In2.Cu")
		(net "M_C_CPU1_SA_DQ<13>")
	)
	(segment
		(start 67.638168 -220.560392)
		(end 73.332086 -226.25431)
		(width 0.14478)
		(layer "In2.Cu")
		(net "M_C_CPU1_SA_DQ<13>")
	)
	(segment
		(start 59.774328 -213.910418)
		(end 59.937396 -213.74735)
		(width 0.14478)
		(layer "In2.Cu")
		(net "M_C_CPU1_SA_DQ<13>")
	)
	(segment
		(start 52.540408 -213.529164)
		(end 52.770786 -213.529164)
		(width 0.14478)
		(layer "In2.Cu")
		(net "M_C_CPU1_SA_DQ<13>")
	)
	(segment
		(start 51.572922 -213.910418)
		(end 52.214272 -213.910418)
		(width 0.14478)
		(layer "In2.Cu")
		(net "M_C_CPU1_SA_DQ<13>")
	)
	(segment
		(start 83.289648 -234.281726)
		(end 83.29803 -234.2769)
		(width 0.0889)
		(layer "In2.Cu")
		(net "M_C_CPU1_SA_DQ<13>")
	)
	(segment
		(start 79.311246 -233.963464)
		(end 79.548482 -234.2007)
		(width 0.0889)
		(layer "In2.Cu")
		(net "M_C_CPU1_SA_DQ<13>")
	)
	(segment
		(start 48.231806 -214.760302)
		(end 48.394874 -214.597234)
		(width 0.14478)
		(layer "In2.Cu")
		(net "M_C_CPU1_SA_DQ<13>")
	)
	(segment
		(start 47.020734 -214.369904)
		(end 47.183802 -214.532972)
		(width 0.14478)
		(layer "In2.Cu")
		(net "M_C_CPU1_SA_DQ<13>")
	)
	(segment
		(start 56.950864 -214.760302)
		(end 57.800748 -213.910418)
		(width 0.14478)
		(layer "In2.Cu")
		(net "M_C_CPU1_SA_DQ<13>")
	)
	(segment
		(start 52.770786 -213.529164)
		(end 52.933854 -213.692232)
		(width 0.14478)
		(layer "In2.Cu")
		(net "M_C_CPU1_SA_DQ<13>")
	)
	(segment
		(start 56.293512 -214.369904)
		(end 56.45658 -214.532972)
		(width 0.14478)
		(layer "In2.Cu")
		(net "M_C_CPU1_SA_DQ<13>")
	)
	(segment
		(start 54.341776 -214.597234)
		(end 54.341776 -214.538052)
		(width 0.14478)
		(layer "In2.Cu")
		(net "M_C_CPU1_SA_DQ<13>")
	)
	(segment
		(start 76.239116 -230.459534)
		(end 76.400406 -230.620824)
		(width 0.0889)
		(layer "In2.Cu")
		(net "M_C_CPU1_SA_DQ<13>")
	)
	(segment
		(start 52.933854 -213.692232)
		(end 52.933854 -213.74735)
		(width 0.14478)
		(layer "In2.Cu")
		(net "M_C_CPU1_SA_DQ<13>")
	)
	(segment
		(start 47.183802 -214.597234)
		(end 47.34687 -214.760302)
		(width 0.14478)
		(layer "In2.Cu")
		(net "M_C_CPU1_SA_DQ<13>")
	)
	(segment
		(start 47.183802 -214.532972)
		(end 47.183802 -214.597234)
		(width 0.14478)
		(layer "In2.Cu")
		(net "M_C_CPU1_SA_DQ<13>")
	)
	(segment
		(start 50.690272 -213.910418)
		(end 50.85334 -213.74735)
		(width 0.14478)
		(layer "In2.Cu")
		(net "M_C_CPU1_SA_DQ<13>")
	)
	(segment
		(start 58.27903 -213.687152)
		(end 58.442098 -213.524084)
		(width 0.14478)
		(layer "In2.Cu")
		(net "M_C_CPU1_SA_DQ<13>")
	)
	(segment
		(start 48.951388 -214.597234)
		(end 49.114456 -214.760302)
		(width 0.14478)
		(layer "In2.Cu")
		(net "M_C_CPU1_SA_DQ<13>")
	)
	(segment
		(start 52.214272 -213.910418)
		(end 52.37734 -213.74735)
		(width 0.14478)
		(layer "In2.Cu")
		(net "M_C_CPU1_SA_DQ<13>")
	)
	(segment
		(start 48.951388 -214.538052)
		(end 48.951388 -214.597234)
		(width 0.14478)
		(layer "In2.Cu")
		(net "M_C_CPU1_SA_DQ<13>")
	)
	(segment
		(start 50.85334 -213.679532)
		(end 51.016408 -213.516464)
		(width 0.14478)
		(layer "In2.Cu")
		(net "M_C_CPU1_SA_DQ<13>")
	)
	(segment
		(start 60.49391 -213.74735)
		(end 61.045344 -214.298784)
		(width 0.14478)
		(layer "In2.Cu")
		(net "M_C_CPU1_SA_DQ<13>")
	)
	(segment
		(start 56.45658 -214.597234)
		(end 56.619648 -214.760302)
		(width 0.14478)
		(layer "In2.Cu")
		(net "M_C_CPU1_SA_DQ<13>")
	)
	(segment
		(start 46.070774 -214.532972)
		(end 46.070774 -214.997792)
		(width 0.14478)
		(layer "In2.Cu")
		(net "M_C_CPU1_SA_DQ<13>")
	)
	(segment
		(start 46.627288 -214.997792)
		(end 46.627288 -214.532972)
		(width 0.14478)
		(layer "In2.Cu")
		(net "M_C_CPU1_SA_DQ<13>")
	)
	(segment
		(start 51.016408 -213.516464)
		(end 51.246786 -213.516464)
		(width 0.14478)
		(layer "In2.Cu")
		(net "M_C_CPU1_SA_DQ<13>")
	)
	(segment
		(start 55.900066 -214.597234)
		(end 55.900066 -214.532972)
		(width 0.14478)
		(layer "In2.Cu")
		(net "M_C_CPU1_SA_DQ<13>")
	)
	(segment
		(start 44.945046 -215.152224)
		(end 45.351192 -215.152224)
		(width 0.14478)
		(layer "In2.Cu")
		(net "M_C_CPU1_SA_DQ<13>")
	)
	(segment
		(start 54.341776 -214.538052)
		(end 54.504844 -214.374984)
		(width 0.14478)
		(layer "In2.Cu")
		(net "M_C_CPU1_SA_DQ<13>")
	)
	(segment
		(start 64.005206 -215.28659)
		(end 64.005206 -215.79967)
		(width 0.14478)
		(layer "In2.Cu")
		(net "M_C_CPU1_SA_DQ<13>")
	)
	(segment
		(start 76.931266 -230.620824)
		(end 77.418946 -231.108504)
		(width 0.0889)
		(layer "In2.Cu")
		(net "M_C_CPU1_SA_DQ<13>")
	)
	(segment
		(start 87.989664 -234.281726)
		(end 87.998046 -234.2769)
		(width 0.0889)
		(layer "In2.Cu")
		(net "M_C_CPU1_SA_DQ<13>")
	)
	(segment
		(start 58.835544 -213.687152)
		(end 58.835544 -213.74735)
		(width 0.14478)
		(layer "In2.Cu")
		(net "M_C_CPU1_SA_DQ<13>")
	)
	(segment
		(start 84.229702 -234.281726)
		(end 84.238084 -234.2769)
		(width 0.0889)
		(layer "In2.Cu")
		(net "M_C_CPU1_SA_DQ<13>")
	)
	(segment
		(start 78.261972 -233.150664)
		(end 78.724506 -233.150664)
		(width 0.0889)
		(layer "In2.Cu")
		(net "M_C_CPU1_SA_DQ<13>")
	)
	(segment
		(start 48.557942 -214.374984)
		(end 48.78832 -214.374984)
		(width 0.14478)
		(layer "In2.Cu")
		(net "M_C_CPU1_SA_DQ<13>")
	)
	(segment
		(start 78.724506 -233.150664)
		(end 79.311246 -233.737404)
		(width 0.0889)
		(layer "In2.Cu")
		(net "M_C_CPU1_SA_DQ<13>")
	)
	(segment
		(start 63.0174 -214.298784)
		(end 64.005206 -215.28659)
		(width 0.14478)
		(layer "In2.Cu")
		(net "M_C_CPU1_SA_DQ<13>")
	)
	(segment
		(start 45.907706 -214.369904)
		(end 46.070774 -214.532972)
		(width 0.14478)
		(layer "In2.Cu")
		(net "M_C_CPU1_SA_DQ<13>")
	)
	(segment
		(start 49.427384 -214.760302)
		(end 50.277268 -213.910418)
		(width 0.14478)
		(layer "In2.Cu")
		(net "M_C_CPU1_SA_DQ<13>")
	)
	(segment
		(start 46.070774 -214.997792)
		(end 46.233842 -215.16086)
		(width 0.14478)
		(layer "In2.Cu")
		(net "M_C_CPU1_SA_DQ<13>")
	)
	(segment
		(start 51.409854 -213.74735)
		(end 51.572922 -213.910418)
		(width 0.14478)
		(layer "In2.Cu")
		(net "M_C_CPU1_SA_DQ<13>")
	)
	(segment
		(start 56.45658 -214.532972)
		(end 56.45658 -214.597234)
		(width 0.14478)
		(layer "In2.Cu")
		(net "M_C_CPU1_SA_DQ<13>")
	)
	(segment
		(start 91.749626 -234.281726)
		(end 91.758008 -234.2769)
		(width 0.0889)
		(layer "In2.Cu")
		(net "M_C_CPU1_SA_DQ<13>")
	)
	(segment
		(start 58.442098 -213.524084)
		(end 58.672476 -213.524084)
		(width 0.14478)
		(layer "In2.Cu")
		(net "M_C_CPU1_SA_DQ<13>")
	)
	(segment
		(start 45.677328 -214.369904)
		(end 45.907706 -214.369904)
		(width 0.14478)
		(layer "In2.Cu")
		(net "M_C_CPU1_SA_DQ<13>")
	)
	(segment
		(start 59.937396 -213.687152)
		(end 60.100464 -213.524084)
		(width 0.14478)
		(layer "In2.Cu")
		(net "M_C_CPU1_SA_DQ<13>")
	)
	(segment
		(start 49.114456 -214.760302)
		(end 49.427384 -214.760302)
		(width 0.14478)
		(layer "In2.Cu")
		(net "M_C_CPU1_SA_DQ<13>")
	)
	(segment
		(start 56.063134 -214.369904)
		(end 56.293512 -214.369904)
		(width 0.14478)
		(layer "In2.Cu")
		(net "M_C_CPU1_SA_DQ<13>")
	)
	(segment
		(start 44.795186 -214.790528)
		(end 44.795186 -215.002364)
		(width 0.14478)
		(layer "In2.Cu")
		(net "M_C_CPU1_SA_DQ<13>")
	)
	(segment
		(start 58.998612 -213.910418)
		(end 59.774328 -213.910418)
		(width 0.14478)
		(layer "In2.Cu")
		(net "M_C_CPU1_SA_DQ<13>")
	)
	(segment
		(start 55.900066 -214.532972)
		(end 56.063134 -214.369904)
		(width 0.14478)
		(layer "In2.Cu")
		(net "M_C_CPU1_SA_DQ<13>")
	)
	(segment
		(start 55.061358 -214.760302)
		(end 55.736998 -214.760302)
		(width 0.14478)
		(layer "In2.Cu")
		(net "M_C_CPU1_SA_DQ<13>")
	)
	(segment
		(start 55.736998 -214.760302)
		(end 55.900066 -214.597234)
		(width 0.14478)
		(layer "In2.Cu")
		(net "M_C_CPU1_SA_DQ<13>")
	)
	(segment
		(start 56.619648 -214.760302)
		(end 56.950864 -214.760302)
		(width 0.14478)
		(layer "In2.Cu")
		(net "M_C_CPU1_SA_DQ<13>")
	)
	(segment
		(start 58.115962 -213.910418)
		(end 58.27903 -213.74735)
		(width 0.14478)
		(layer "In2.Cu")
		(net "M_C_CPU1_SA_DQ<13>")
	)
	(segment
		(start 48.394874 -214.597234)
		(end 48.394874 -214.538052)
		(width 0.14478)
		(layer "In2.Cu")
		(net "M_C_CPU1_SA_DQ<13>")
	)
	(segment
		(start 85.74405 -234.2769)
		(end 85.752432 -234.281726)
		(width 0.0889)
		(layer "In2.Cu")
		(net "M_C_CPU1_SA_DQ<13>")
	)
	(segment
		(start 60.100464 -213.524084)
		(end 60.330842 -213.524084)
		(width 0.14478)
		(layer "In2.Cu")
		(net "M_C_CPU1_SA_DQ<13>")
	)
	(segment
		(start 47.34687 -214.760302)
		(end 48.231806 -214.760302)
		(width 0.14478)
		(layer "In2.Cu")
		(net "M_C_CPU1_SA_DQ<13>")
	)
	(segment
		(start 54.178708 -214.760302)
		(end 54.341776 -214.597234)
		(width 0.14478)
		(layer "In2.Cu")
		(net "M_C_CPU1_SA_DQ<13>")
	)
	(segment
		(start 88.929718 -234.281726)
		(end 88.9381 -234.2769)
		(width 0.0889)
		(layer "In2.Cu")
		(net "M_C_CPU1_SA_DQ<13>")
	)
	(segment
		(start 48.78832 -214.374984)
		(end 48.951388 -214.538052)
		(width 0.14478)
		(layer "In2.Cu")
		(net "M_C_CPU1_SA_DQ<13>")
	)
	(segment
		(start 60.49391 -213.687152)
		(end 60.49391 -213.74735)
		(width 0.14478)
		(layer "In2.Cu")
		(net "M_C_CPU1_SA_DQ<13>")
	)
	(segment
		(start 73.332086 -226.25431)
		(end 73.332086 -227.552504)
		(width 0.14478)
		(layer "In2.Cu")
		(net "M_C_CPU1_SA_DQ<13>")
	)
	(segment
		(start 64.005206 -215.79967)
		(end 67.638168 -219.432632)
		(width 0.14478)
		(layer "In2.Cu")
		(net "M_C_CPU1_SA_DQ<13>")
	)
	(segment
		(start 58.835544 -213.74735)
		(end 58.998612 -213.910418)
		(width 0.14478)
		(layer "In2.Cu")
		(net "M_C_CPU1_SA_DQ<13>")
	)
	(segment
		(start 54.89829 -214.597234)
		(end 55.061358 -214.760302)
		(width 0.14478)
		(layer "In2.Cu")
		(net "M_C_CPU1_SA_DQ<13>")
	)
	(segment
		(start 45.51426 -214.532972)
		(end 45.677328 -214.369904)
		(width 0.14478)
		(layer "In2.Cu")
		(net "M_C_CPU1_SA_DQ<13>")
	)
	(segment
		(start 94.204028 -234.2769)
		(end 94.21241 -234.281726)
		(width 0.0889)
		(layer "In2.Cu")
		(net "M_C_CPU1_SA_DQ<13>")
	)
	(segment
		(start 46.790356 -214.369904)
		(end 47.020734 -214.369904)
		(width 0.14478)
		(layer "In2.Cu")
		(net "M_C_CPU1_SA_DQ<13>")
	)
	(segment
		(start 77.418946 -231.720644)
		(end 77.700886 -232.002584)
		(width 0.0889)
		(layer "In2.Cu")
		(net "M_C_CPU1_SA_DQ<13>")
	)
	(segment
		(start 45.51426 -214.989156)
		(end 45.51426 -214.532972)
		(width 0.14478)
		(layer "In2.Cu")
		(net "M_C_CPU1_SA_DQ<13>")
	)
	(segment
		(start 67.638168 -219.432632)
		(end 67.638168 -220.560392)
		(width 0.14478)
		(layer "In2.Cu")
		(net "M_C_CPU1_SA_DQ<13>")
	)
	(segment
		(start 44.340018 -214.33536)
		(end 44.795186 -214.790528)
		(width 0.14478)
		(layer "In2.Cu")
		(net "M_C_CPU1_SA_DQ<13>")
	)
	(segment
		(start 81.044034 -234.2769)
		(end 81.052416 -234.281726)
		(width 0.0889)
		(layer "In2.Cu")
		(net "M_C_CPU1_SA_DQ<13>")
	)
	(segment
		(start 57.800748 -213.910418)
		(end 58.115962 -213.910418)
		(width 0.14478)
		(layer "In2.Cu")
		(net "M_C_CPU1_SA_DQ<13>")
	)
	(segment
		(start 89.504012 -234.2769)
		(end 89.512394 -234.281726)
		(width 0.0889)
		(layer "In2.Cu")
		(net "M_C_CPU1_SA_DQ<13>")
	)
	(segment
		(start 79.311246 -233.737404)
		(end 79.311246 -233.963464)
		(width 0.0889)
		(layer "In2.Cu")
		(net "M_C_CPU1_SA_DQ<13>")
	)
	(segment
		(start 77.700886 -232.002584)
		(end 77.700886 -232.589578)
		(width 0.0889)
		(layer "In2.Cu")
		(net "M_C_CPU1_SA_DQ<13>")
	)
	(segment
		(start 76.400406 -230.620824)
		(end 76.931266 -230.620824)
		(width 0.0889)
		(layer "In2.Cu")
		(net "M_C_CPU1_SA_DQ<13>")
	)
	(segment
		(start 79.548482 -234.2007)
		(end 79.821024 -234.2007)
		(width 0.0889)
		(layer "In2.Cu")
		(net "M_C_CPU1_SA_DQ<13>")
	)
	(segment
		(start 61.045344 -214.298784)
		(end 63.0174 -214.298784)
		(width 0.14478)
		(layer "In2.Cu")
		(net "M_C_CPU1_SA_DQ<13>")
	)
	(segment
		(start 52.933854 -213.74735)
		(end 53.096922 -213.910418)
		(width 0.14478)
		(layer "In2.Cu")
		(net "M_C_CPU1_SA_DQ<13>")
	)
	(arc
		(start 81.052416 -234.281726)
		(mid 81.235924 -234.32722)
		(end 81.418176 -234.2769)
		(width 0.0889)
		(layer "In2.Cu")
		(net "M_C_CPU1_SA_DQ<13>")
	)
	(arc
		(start 88.563958 -234.2769)
		(mid 88.746209 -234.32725)
		(end 88.929718 -234.281726)
		(width 0.0889)
		(layer "In2.Cu")
		(net "M_C_CPU1_SA_DQ<13>")
	)
	(arc
		(start 92.698062 -234.2769)
		(mid 92.981018 -234.200723)
		(end 93.263974 -234.2769)
		(width 0.0889)
		(layer "In2.Cu")
		(net "M_C_CPU1_SA_DQ<13>")
	)
	(arc
		(start 90.444066 -234.2769)
		(mid 90.63101 -234.327155)
		(end 90.817954 -234.2769)
		(width 0.0889)
		(layer "In2.Cu")
		(net "M_C_CPU1_SA_DQ<13>")
	)
	(arc
		(start 93.638116 -234.2769)
		(mid 93.921072 -234.200723)
		(end 94.204028 -234.2769)
		(width 0.0889)
		(layer "In2.Cu")
		(net "M_C_CPU1_SA_DQ<13>")
	)
	(arc
		(start 83.29803 -234.2769)
		(mid 83.580986 -234.200723)
		(end 83.863942 -234.2769)
		(width 0.0889)
		(layer "In2.Cu")
		(net "M_C_CPU1_SA_DQ<13>")
	)
	(arc
		(start 86.684104 -234.2769)
		(mid 86.871048 -234.327155)
		(end 87.057992 -234.2769)
		(width 0.0889)
		(layer "In2.Cu")
		(net "M_C_CPU1_SA_DQ<13>")
	)
	(arc
		(start 89.878154 -234.2769)
		(mid 90.16111 -234.200723)
		(end 90.444066 -234.2769)
		(width 0.0889)
		(layer "In2.Cu")
		(net "M_C_CPU1_SA_DQ<13>")
	)
	(arc
		(start 87.998046 -234.2769)
		(mid 88.281002 -234.200723)
		(end 88.563958 -234.2769)
		(width 0.0889)
		(layer "In2.Cu")
		(net "M_C_CPU1_SA_DQ<13>")
	)
	(arc
		(start 90.817954 -234.2769)
		(mid 91.10091 -234.200723)
		(end 91.383866 -234.2769)
		(width 0.0889)
		(layer "In2.Cu")
		(net "M_C_CPU1_SA_DQ<13>")
	)
	(arc
		(start 84.812378 -234.281726)
		(mid 84.995886 -234.32722)
		(end 85.178138 -234.2769)
		(width 0.0889)
		(layer "In2.Cu")
		(net "M_C_CPU1_SA_DQ<13>")
	)
	(arc
		(start 86.118192 -234.2769)
		(mid 86.401148 -234.200723)
		(end 86.684104 -234.2769)
		(width 0.0889)
		(layer "In2.Cu")
		(net "M_C_CPU1_SA_DQ<13>")
	)
	(arc
		(start 93.272356 -234.281726)
		(mid 93.455864 -234.32722)
		(end 93.638116 -234.2769)
		(width 0.0889)
		(layer "In2.Cu")
		(net "M_C_CPU1_SA_DQ<13>")
	)
	(arc
		(start 88.9381 -234.2769)
		(mid 89.221056 -234.200723)
		(end 89.504012 -234.2769)
		(width 0.0889)
		(layer "In2.Cu")
		(net "M_C_CPU1_SA_DQ<13>")
	)
	(arc
		(start 95.144082 -234.2769)
		(mid 95.300401 -234.325895)
		(end 95.462598 -234.303062)
		(width 0.0889)
		(layer "In2.Cu")
		(net "M_C_CPU1_SA_DQ<13>")
	)
	(arc
		(start 94.21241 -234.281726)
		(mid 94.395918 -234.32722)
		(end 94.57817 -234.2769)
		(width 0.0889)
		(layer "In2.Cu")
		(net "M_C_CPU1_SA_DQ<13>")
	)
	(arc
		(start 79.821024 -234.2007)
		(mid 79.967541 -234.220086)
		(end 80.10398 -234.2769)
		(width 0.0889)
		(layer "In2.Cu")
		(net "M_C_CPU1_SA_DQ<13>")
	)
	(arc
		(start 94.57817 -234.2769)
		(mid 94.861126 -234.200723)
		(end 95.144082 -234.2769)
		(width 0.0889)
		(layer "In2.Cu")
		(net "M_C_CPU1_SA_DQ<13>")
	)
	(arc
		(start 91.758008 -234.2769)
		(mid 92.040964 -234.200723)
		(end 92.32392 -234.2769)
		(width 0.0889)
		(layer "In2.Cu")
		(net "M_C_CPU1_SA_DQ<13>")
	)
	(arc
		(start 80.10398 -234.2769)
		(mid 80.286231 -234.32725)
		(end 80.46974 -234.281726)
		(width 0.0889)
		(layer "In2.Cu")
		(net "M_C_CPU1_SA_DQ<13>")
	)
	(arc
		(start 85.178138 -234.2769)
		(mid 85.461094 -234.200723)
		(end 85.74405 -234.2769)
		(width 0.0889)
		(layer "In2.Cu")
		(net "M_C_CPU1_SA_DQ<13>")
	)
	(arc
		(start 89.512394 -234.281726)
		(mid 89.695902 -234.32722)
		(end 89.878154 -234.2769)
		(width 0.0889)
		(layer "In2.Cu")
		(net "M_C_CPU1_SA_DQ<13>")
	)
	(arc
		(start 84.238084 -234.2769)
		(mid 84.52104 -234.200723)
		(end 84.803996 -234.2769)
		(width 0.0889)
		(layer "In2.Cu")
		(net "M_C_CPU1_SA_DQ<13>")
	)
	(arc
		(start 82.357976 -234.2769)
		(mid 82.640932 -234.200723)
		(end 82.923888 -234.2769)
		(width 0.0889)
		(layer "In2.Cu")
		(net "M_C_CPU1_SA_DQ<13>")
	)
	(arc
		(start 87.057992 -234.2769)
		(mid 87.340948 -234.200723)
		(end 87.623904 -234.2769)
		(width 0.0889)
		(layer "In2.Cu")
		(net "M_C_CPU1_SA_DQ<13>")
	)
	(arc
		(start 92.32392 -234.2769)
		(mid 92.506171 -234.32725)
		(end 92.68968 -234.281726)
		(width 0.0889)
		(layer "In2.Cu")
		(net "M_C_CPU1_SA_DQ<13>")
	)
	(arc
		(start 81.418176 -234.2769)
		(mid 81.701132 -234.200723)
		(end 81.984088 -234.2769)
		(width 0.0889)
		(layer "In2.Cu")
		(net "M_C_CPU1_SA_DQ<13>")
	)
	(arc
		(start 80.478122 -234.2769)
		(mid 80.761078 -234.200723)
		(end 81.044034 -234.2769)
		(width 0.0889)
		(layer "In2.Cu")
		(net "M_C_CPU1_SA_DQ<13>")
	)
	(arc
		(start 91.383866 -234.2769)
		(mid 91.566117 -234.32725)
		(end 91.749626 -234.281726)
		(width 0.0889)
		(layer "In2.Cu")
		(net "M_C_CPU1_SA_DQ<13>")
	)
	(arc
		(start 87.623904 -234.2769)
		(mid 87.806155 -234.32725)
		(end 87.989664 -234.281726)
		(width 0.0889)
		(layer "In2.Cu")
		(net "M_C_CPU1_SA_DQ<13>")
	)
	(arc
		(start 85.752432 -234.281726)
		(mid 85.93594 -234.32722)
		(end 86.118192 -234.2769)
		(width 0.0889)
		(layer "In2.Cu")
		(net "M_C_CPU1_SA_DQ<13>")
	)
	(arc
		(start 81.984088 -234.2769)
		(mid 82.171032 -234.327155)
		(end 82.357976 -234.2769)
		(width 0.0889)
		(layer "In2.Cu")
		(net "M_C_CPU1_SA_DQ<13>")
	)
	(arc
		(start 82.923888 -234.2769)
		(mid 83.106139 -234.32725)
		(end 83.289648 -234.281726)
		(width 0.0889)
		(layer "In2.Cu")
		(net "M_C_CPU1_SA_DQ<13>")
	)
	(arc
		(start 83.863942 -234.2769)
		(mid 84.046193 -234.32725)
		(end 84.229702 -234.281726)
		(width 0.0889)
		(layer "In2.Cu")
		(net "M_C_CPU1_SA_DQ<13>")
	)
	(segment
		(start 94.387924 -233.410252)
		(end 93.921072 -233.144314)
		(width 0.10668)
		(layer "F.Cu")
		(net "M_C_CPU1_SA_DQ<12>")
	)
	(segment
		(start 63.443866 -213.353904)
		(end 65.3923 -215.302338)
		(width 0.14478)
		(layer "In2.Cu")
		(net "M_C_CPU1_SA_DQ<12>")
	)
	(segment
		(start 66.913252 -217.161618)
		(end 66.913252 -217.39225)
		(width 0.14478)
		(layer "In2.Cu")
		(net "M_C_CPU1_SA_DQ<12>")
	)
	(segment
		(start 46.674278 -213.214712)
		(end 46.819058 -213.069932)
		(width 0.14478)
		(layer "In2.Cu")
		(net "M_C_CPU1_SA_DQ<12>")
	)
	(segment
		(start 62.069472 -213.353904)
		(end 62.29985 -213.353904)
		(width 0.14478)
		(layer "In2.Cu")
		(net "M_C_CPU1_SA_DQ<12>")
	)
	(segment
		(start 56.631332 -213.379304)
		(end 56.868822 -213.379304)
		(width 0.14478)
		(layer "In2.Cu")
		(net "M_C_CPU1_SA_DQ<12>")
	)
	(segment
		(start 88.094058 -233.466894)
		(end 88.10244 -233.47172)
		(width 0.0889)
		(layer "In2.Cu")
		(net "M_C_CPU1_SA_DQ<12>")
	)
	(segment
		(start 74.256646 -227.163884)
		(end 75.895708 -228.802946)
		(width 0.14478)
		(layer "In2.Cu")
		(net "M_C_CPU1_SA_DQ<12>")
	)
	(segment
		(start 61.286644 -212.65642)
		(end 61.286644 -212.39734)
		(width 0.14478)
		(layer "In2.Cu")
		(net "M_C_CPU1_SA_DQ<12>")
	)
	(segment
		(start 57.323736 -213.06028)
		(end 58.17362 -212.210396)
		(width 0.14478)
		(layer "In2.Cu")
		(net "M_C_CPU1_SA_DQ<12>")
	)
	(segment
		(start 61.286644 -212.39734)
		(end 61.473588 -212.210396)
		(width 0.14478)
		(layer "In2.Cu")
		(net "M_C_CPU1_SA_DQ<12>")
	)
	(segment
		(start 65.338452 -215.81745)
		(end 65.50152 -215.980518)
		(width 0.14478)
		(layer "In2.Cu")
		(net "M_C_CPU1_SA_DQ<12>")
	)
	(segment
		(start 60.73521 -212.65642)
		(end 60.896754 -212.817964)
		(width 0.14478)
		(layer "In2.Cu")
		(net "M_C_CPU1_SA_DQ<12>")
	)
	(segment
		(start 77.909166 -229.917244)
		(end 77.909166 -231.326944)
		(width 0.0889)
		(layer "In2.Cu")
		(net "M_C_CPU1_SA_DQ<12>")
	)
	(segment
		(start 62.625986 -212.66277)
		(end 62.856364 -212.66277)
		(width 0.14478)
		(layer "In2.Cu")
		(net "M_C_CPU1_SA_DQ<12>")
	)
	(segment
		(start 46.01464 -212.691726)
		(end 46.01464 -213.044024)
		(width 0.14478)
		(layer "In2.Cu")
		(net "M_C_CPU1_SA_DQ<12>")
	)
	(segment
		(start 46.117764 -213.147148)
		(end 46.117764 -213.272116)
		(width 0.14478)
		(layer "In2.Cu")
		(net "M_C_CPU1_SA_DQ<12>")
	)
	(segment
		(start 46.01464 -213.044024)
		(end 46.117764 -213.147148)
		(width 0.14478)
		(layer "In2.Cu")
		(net "M_C_CPU1_SA_DQ<12>")
	)
	(segment
		(start 66.9671 -217.10777)
		(end 66.913252 -217.161618)
		(width 0.14478)
		(layer "In2.Cu")
		(net "M_C_CPU1_SA_DQ<12>")
	)
	(segment
		(start 49.845468 -213.069932)
		(end 50.695352 -212.220048)
		(width 0.14478)
		(layer "In2.Cu")
		(net "M_C_CPU1_SA_DQ<12>")
	)
	(segment
		(start 94.052644 -233.493056)
		(end 94.074996 -233.409744)
		(width 0.0889)
		(layer "In2.Cu")
		(net "M_C_CPU1_SA_DQ<12>")
	)
	(segment
		(start 91.85402 -233.466894)
		(end 91.862402 -233.47172)
		(width 0.0889)
		(layer "In2.Cu")
		(net "M_C_CPU1_SA_DQ<12>")
	)
	(segment
		(start 75.895708 -228.802946)
		(end 76.28763 -228.802946)
		(width 0.14478)
		(layer "In2.Cu")
		(net "M_C_CPU1_SA_DQ<12>")
	)
	(segment
		(start 53.112416 -212.220048)
		(end 53.952648 -213.06028)
		(width 0.14478)
		(layer "In2.Cu")
		(net "M_C_CPU1_SA_DQ<12>")
	)
	(segment
		(start 78.856586 -232.274364)
		(end 78.856586 -232.689654)
		(width 0.0889)
		(layer "In2.Cu")
		(net "M_C_CPU1_SA_DQ<12>")
	)
	(segment
		(start 60.896754 -212.817964)
		(end 61.1251 -212.817964)
		(width 0.14478)
		(layer "In2.Cu")
		(net "M_C_CPU1_SA_DQ<12>")
	)
	(segment
		(start 46.280832 -213.435184)
		(end 46.51121 -213.435184)
		(width 0.14478)
		(layer "In2.Cu")
		(net "M_C_CPU1_SA_DQ<12>")
	)
	(segment
		(start 87.154004 -233.466894)
		(end 87.162386 -233.47172)
		(width 0.0889)
		(layer "In2.Cu")
		(net "M_C_CPU1_SA_DQ<12>")
	)
	(segment
		(start 45.458126 -212.691726)
		(end 45.621194 -212.528658)
		(width 0.14478)
		(layer "In2.Cu")
		(net "M_C_CPU1_SA_DQ<12>")
	)
	(segment
		(start 58.17362 -212.210396)
		(end 60.548266 -212.210396)
		(width 0.14478)
		(layer "In2.Cu")
		(net "M_C_CPU1_SA_DQ<12>")
	)
	(segment
		(start 57.187846 -213.06028)
		(end 57.323736 -213.06028)
		(width 0.14478)
		(layer "In2.Cu")
		(net "M_C_CPU1_SA_DQ<12>")
	)
	(segment
		(start 63.019432 -212.825838)
		(end 63.019432 -213.190836)
		(width 0.14478)
		(layer "In2.Cu")
		(net "M_C_CPU1_SA_DQ<12>")
	)
	(segment
		(start 66.1797 -216.32037)
		(end 66.125852 -216.374218)
		(width 0.14478)
		(layer "In2.Cu")
		(net "M_C_CPU1_SA_DQ<12>")
	)
	(segment
		(start 45.621194 -212.528658)
		(end 45.851572 -212.528658)
		(width 0.14478)
		(layer "In2.Cu")
		(net "M_C_CPU1_SA_DQ<12>")
	)
	(segment
		(start 56.312308 -213.06028)
		(end 56.631332 -213.379304)
		(width 0.14478)
		(layer "In2.Cu")
		(net "M_C_CPU1_SA_DQ<12>")
	)
	(segment
		(start 62.462918 -213.190836)
		(end 62.462918 -212.825838)
		(width 0.14478)
		(layer "In2.Cu")
		(net "M_C_CPU1_SA_DQ<12>")
	)
	(segment
		(start 81.879694 -233.47172)
		(end 81.888076 -233.466894)
		(width 0.0889)
		(layer "In2.Cu")
		(net "M_C_CPU1_SA_DQ<12>")
	)
	(segment
		(start 61.1251 -212.817964)
		(end 61.286644 -212.65642)
		(width 0.14478)
		(layer "In2.Cu")
		(net "M_C_CPU1_SA_DQ<12>")
	)
	(segment
		(start 45.308266 -213.347808)
		(end 45.458126 -213.197948)
		(width 0.14478)
		(layer "In2.Cu")
		(net "M_C_CPU1_SA_DQ<12>")
	)
	(segment
		(start 66.913252 -217.39225)
		(end 67.07632 -217.555318)
		(width 0.14478)
		(layer "In2.Cu")
		(net "M_C_CPU1_SA_DQ<12>")
	)
	(segment
		(start 78.856586 -232.689654)
		(end 79.633826 -233.466894)
		(width 0.0889)
		(layer "In2.Cu")
		(net "M_C_CPU1_SA_DQ<12>")
	)
	(segment
		(start 67.7545 -217.664538)
		(end 67.7545 -217.89517)
		(width 0.14478)
		(layer "In2.Cu")
		(net "M_C_CPU1_SA_DQ<12>")
	)
	(segment
		(start 65.786 -215.92667)
		(end 66.016632 -215.92667)
		(width 0.14478)
		(layer "In2.Cu")
		(net "M_C_CPU1_SA_DQ<12>")
	)
	(segment
		(start 66.28892 -216.767918)
		(end 66.519552 -216.767918)
		(width 0.14478)
		(layer "In2.Cu")
		(net "M_C_CPU1_SA_DQ<12>")
	)
	(segment
		(start 77.909166 -231.326944)
		(end 78.856586 -232.274364)
		(width 0.0889)
		(layer "In2.Cu")
		(net "M_C_CPU1_SA_DQ<12>")
	)
	(segment
		(start 82.453988 -233.466894)
		(end 82.46237 -233.47172)
		(width 0.0889)
		(layer "In2.Cu")
		(net "M_C_CPU1_SA_DQ<12>")
	)
	(segment
		(start 66.1797 -216.089738)
		(end 66.1797 -216.32037)
		(width 0.14478)
		(layer "In2.Cu")
		(net "M_C_CPU1_SA_DQ<12>")
	)
	(segment
		(start 46.51121 -213.435184)
		(end 46.674278 -213.272116)
		(width 0.14478)
		(layer "In2.Cu")
		(net "M_C_CPU1_SA_DQ<12>")
	)
	(segment
		(start 45.458126 -213.197948)
		(end 45.458126 -212.691726)
		(width 0.14478)
		(layer "In2.Cu")
		(net "M_C_CPU1_SA_DQ<12>")
	)
	(segment
		(start 76.794868 -228.802946)
		(end 77.909166 -229.917244)
		(width 0.0889)
		(layer "In2.Cu")
		(net "M_C_CPU1_SA_DQ<12>")
	)
	(segment
		(start 46.117764 -213.272116)
		(end 46.280832 -213.435184)
		(width 0.14478)
		(layer "In2.Cu")
		(net "M_C_CPU1_SA_DQ<12>")
	)
	(segment
		(start 94.074996 -233.409744)
		(end 93.921072 -233.144314)
		(width 0.0889)
		(layer "In2.Cu")
		(net "M_C_CPU1_SA_DQ<12>")
	)
	(segment
		(start 60.548266 -212.210396)
		(end 60.73521 -212.39734)
		(width 0.14478)
		(layer "In2.Cu")
		(net "M_C_CPU1_SA_DQ<12>")
	)
	(segment
		(start 63.019432 -213.190836)
		(end 63.1825 -213.353904)
		(width 0.14478)
		(layer "In2.Cu")
		(net "M_C_CPU1_SA_DQ<12>")
	)
	(segment
		(start 68.378832 -218.28887)
		(end 68.607686 -218.517724)
		(width 0.14478)
		(layer "In2.Cu")
		(net "M_C_CPU1_SA_DQ<12>")
	)
	(segment
		(start 68.094352 -218.342718)
		(end 68.1482 -218.28887)
		(width 0.14478)
		(layer "In2.Cu")
		(net "M_C_CPU1_SA_DQ<12>")
	)
	(segment
		(start 74.256646 -225.871024)
		(end 74.256646 -227.163884)
		(width 0.14478)
		(layer "In2.Cu")
		(net "M_C_CPU1_SA_DQ<12>")
	)
	(segment
		(start 65.3923 -215.302338)
		(end 65.3923 -215.53297)
		(width 0.14478)
		(layer "In2.Cu")
		(net "M_C_CPU1_SA_DQ<12>")
	)
	(segment
		(start 67.07632 -217.555318)
		(end 67.306952 -217.555318)
		(width 0.14478)
		(layer "In2.Cu")
		(net "M_C_CPU1_SA_DQ<12>")
	)
	(segment
		(start 66.5734 -216.71407)
		(end 66.804032 -216.71407)
		(width 0.14478)
		(layer "In2.Cu")
		(net "M_C_CPU1_SA_DQ<12>")
	)
	(segment
		(start 65.338452 -215.586818)
		(end 65.338452 -215.81745)
		(width 0.14478)
		(layer "In2.Cu")
		(net "M_C_CPU1_SA_DQ<12>")
	)
	(segment
		(start 67.306952 -217.555318)
		(end 67.3608 -217.50147)
		(width 0.14478)
		(layer "In2.Cu")
		(net "M_C_CPU1_SA_DQ<12>")
	)
	(segment
		(start 67.7545 -217.89517)
		(end 67.700652 -217.949018)
		(width 0.14478)
		(layer "In2.Cu")
		(net "M_C_CPU1_SA_DQ<12>")
	)
	(segment
		(start 67.3608 -217.50147)
		(end 67.591432 -217.50147)
		(width 0.14478)
		(layer "In2.Cu")
		(net "M_C_CPU1_SA_DQ<12>")
	)
	(segment
		(start 66.125852 -216.60485)
		(end 66.28892 -216.767918)
		(width 0.14478)
		(layer "In2.Cu")
		(net "M_C_CPU1_SA_DQ<12>")
	)
	(segment
		(start 61.906404 -212.434932)
		(end 61.906404 -213.190836)
		(width 0.14478)
		(layer "In2.Cu")
		(net "M_C_CPU1_SA_DQ<12>")
	)
	(segment
		(start 61.473588 -212.210396)
		(end 61.681868 -212.210396)
		(width 0.14478)
		(layer "In2.Cu")
		(net "M_C_CPU1_SA_DQ<12>")
	)
	(segment
		(start 67.700652 -217.949018)
		(end 67.700652 -218.17965)
		(width 0.14478)
		(layer "In2.Cu")
		(net "M_C_CPU1_SA_DQ<12>")
	)
	(segment
		(start 66.125852 -216.374218)
		(end 66.125852 -216.60485)
		(width 0.14478)
		(layer "In2.Cu")
		(net "M_C_CPU1_SA_DQ<12>")
	)
	(segment
		(start 65.3923 -215.53297)
		(end 65.338452 -215.586818)
		(width 0.14478)
		(layer "In2.Cu")
		(net "M_C_CPU1_SA_DQ<12>")
	)
	(segment
		(start 68.1482 -218.28887)
		(end 68.378832 -218.28887)
		(width 0.14478)
		(layer "In2.Cu")
		(net "M_C_CPU1_SA_DQ<12>")
	)
	(segment
		(start 67.591432 -217.50147)
		(end 67.7545 -217.664538)
		(width 0.14478)
		(layer "In2.Cu")
		(net "M_C_CPU1_SA_DQ<12>")
	)
	(segment
		(start 44.340018 -212.635338)
		(end 45.052488 -213.347808)
		(width 0.14478)
		(layer "In2.Cu")
		(net "M_C_CPU1_SA_DQ<12>")
	)
	(segment
		(start 90.339672 -233.47172)
		(end 90.348054 -233.466894)
		(width 0.0889)
		(layer "In2.Cu")
		(net "M_C_CPU1_SA_DQ<12>")
	)
	(segment
		(start 76.28763 -228.802946)
		(end 76.794868 -228.802946)
		(width 0.0889)
		(layer "In2.Cu")
		(net "M_C_CPU1_SA_DQ<12>")
	)
	(segment
		(start 62.29985 -213.353904)
		(end 62.462918 -213.190836)
		(width 0.14478)
		(layer "In2.Cu")
		(net "M_C_CPU1_SA_DQ<12>")
	)
	(segment
		(start 86.57971 -233.47172)
		(end 86.588092 -233.466894)
		(width 0.0889)
		(layer "In2.Cu")
		(net "M_C_CPU1_SA_DQ<12>")
	)
	(segment
		(start 61.906404 -213.190836)
		(end 62.069472 -213.353904)
		(width 0.14478)
		(layer "In2.Cu")
		(net "M_C_CPU1_SA_DQ<12>")
	)
	(segment
		(start 45.851572 -212.528658)
		(end 46.01464 -212.691726)
		(width 0.14478)
		(layer "In2.Cu")
		(net "M_C_CPU1_SA_DQ<12>")
	)
	(segment
		(start 63.1825 -213.353904)
		(end 63.443866 -213.353904)
		(width 0.14478)
		(layer "In2.Cu")
		(net "M_C_CPU1_SA_DQ<12>")
	)
	(segment
		(start 65.732152 -215.980518)
		(end 65.786 -215.92667)
		(width 0.14478)
		(layer "In2.Cu")
		(net "M_C_CPU1_SA_DQ<12>")
	)
	(segment
		(start 83.394042 -233.466894)
		(end 83.402424 -233.47172)
		(width 0.0889)
		(layer "In2.Cu")
		(net "M_C_CPU1_SA_DQ<12>")
	)
	(segment
		(start 53.952648 -213.06028)
		(end 56.312308 -213.06028)
		(width 0.14478)
		(layer "In2.Cu")
		(net "M_C_CPU1_SA_DQ<12>")
	)
	(segment
		(start 85.639656 -233.47172)
		(end 85.648038 -233.466894)
		(width 0.0889)
		(layer "In2.Cu")
		(net "M_C_CPU1_SA_DQ<12>")
	)
	(segment
		(start 66.9671 -216.877138)
		(end 66.9671 -217.10777)
		(width 0.14478)
		(layer "In2.Cu")
		(net "M_C_CPU1_SA_DQ<12>")
	)
	(segment
		(start 67.86372 -218.342718)
		(end 68.094352 -218.342718)
		(width 0.14478)
		(layer "In2.Cu")
		(net "M_C_CPU1_SA_DQ<12>")
	)
	(segment
		(start 45.052488 -213.347808)
		(end 45.308266 -213.347808)
		(width 0.14478)
		(layer "In2.Cu")
		(net "M_C_CPU1_SA_DQ<12>")
	)
	(segment
		(start 60.73521 -212.39734)
		(end 60.73521 -212.65642)
		(width 0.14478)
		(layer "In2.Cu")
		(net "M_C_CPU1_SA_DQ<12>")
	)
	(segment
		(start 56.868822 -213.379304)
		(end 57.187846 -213.06028)
		(width 0.14478)
		(layer "In2.Cu")
		(net "M_C_CPU1_SA_DQ<12>")
	)
	(segment
		(start 66.016632 -215.92667)
		(end 66.1797 -216.089738)
		(width 0.14478)
		(layer "In2.Cu")
		(net "M_C_CPU1_SA_DQ<12>")
	)
	(segment
		(start 46.819058 -213.069932)
		(end 49.845468 -213.069932)
		(width 0.14478)
		(layer "In2.Cu")
		(net "M_C_CPU1_SA_DQ<12>")
	)
	(segment
		(start 68.607686 -218.517724)
		(end 68.607686 -220.222064)
		(width 0.14478)
		(layer "In2.Cu")
		(net "M_C_CPU1_SA_DQ<12>")
	)
	(segment
		(start 90.913966 -233.466894)
		(end 90.922348 -233.47172)
		(width 0.0889)
		(layer "In2.Cu")
		(net "M_C_CPU1_SA_DQ<12>")
	)
	(segment
		(start 66.804032 -216.71407)
		(end 66.9671 -216.877138)
		(width 0.14478)
		(layer "In2.Cu")
		(net "M_C_CPU1_SA_DQ<12>")
	)
	(segment
		(start 65.50152 -215.980518)
		(end 65.732152 -215.980518)
		(width 0.14478)
		(layer "In2.Cu")
		(net "M_C_CPU1_SA_DQ<12>")
	)
	(segment
		(start 50.695352 -212.220048)
		(end 53.112416 -212.220048)
		(width 0.14478)
		(layer "In2.Cu")
		(net "M_C_CPU1_SA_DQ<12>")
	)
	(segment
		(start 46.674278 -213.272116)
		(end 46.674278 -213.214712)
		(width 0.14478)
		(layer "In2.Cu")
		(net "M_C_CPU1_SA_DQ<12>")
	)
	(segment
		(start 62.856364 -212.66277)
		(end 63.019432 -212.825838)
		(width 0.14478)
		(layer "In2.Cu")
		(net "M_C_CPU1_SA_DQ<12>")
	)
	(segment
		(start 67.700652 -218.17965)
		(end 67.86372 -218.342718)
		(width 0.14478)
		(layer "In2.Cu")
		(net "M_C_CPU1_SA_DQ<12>")
	)
	(segment
		(start 61.681868 -212.210396)
		(end 61.906404 -212.434932)
		(width 0.14478)
		(layer "In2.Cu")
		(net "M_C_CPU1_SA_DQ<12>")
	)
	(segment
		(start 62.462918 -212.825838)
		(end 62.625986 -212.66277)
		(width 0.14478)
		(layer "In2.Cu")
		(net "M_C_CPU1_SA_DQ<12>")
	)
	(segment
		(start 66.519552 -216.767918)
		(end 66.5734 -216.71407)
		(width 0.14478)
		(layer "In2.Cu")
		(net "M_C_CPU1_SA_DQ<12>")
	)
	(segment
		(start 68.607686 -220.222064)
		(end 74.256646 -225.871024)
		(width 0.14478)
		(layer "In2.Cu")
		(net "M_C_CPU1_SA_DQ<12>")
	)
	(arc
		(start 92.228162 -233.466894)
		(mid 92.511118 -233.390717)
		(end 92.794074 -233.466894)
		(width 0.0889)
		(layer "In2.Cu")
		(net "M_C_CPU1_SA_DQ<12>")
	)
	(arc
		(start 81.888076 -233.466894)
		(mid 82.171032 -233.390717)
		(end 82.453988 -233.466894)
		(width 0.0889)
		(layer "In2.Cu")
		(net "M_C_CPU1_SA_DQ<12>")
	)
	(arc
		(start 87.528146 -233.466894)
		(mid 87.811102 -233.390717)
		(end 88.094058 -233.466894)
		(width 0.0889)
		(layer "In2.Cu")
		(net "M_C_CPU1_SA_DQ<12>")
	)
	(arc
		(start 82.46237 -233.47172)
		(mid 82.645878 -233.517214)
		(end 82.82813 -233.466894)
		(width 0.0889)
		(layer "In2.Cu")
		(net "M_C_CPU1_SA_DQ<12>")
	)
	(arc
		(start 83.402424 -233.47172)
		(mid 83.585932 -233.517214)
		(end 83.768184 -233.466894)
		(width 0.0889)
		(layer "In2.Cu")
		(net "M_C_CPU1_SA_DQ<12>")
	)
	(arc
		(start 82.82813 -233.466894)
		(mid 83.111086 -233.390717)
		(end 83.394042 -233.466894)
		(width 0.0889)
		(layer "In2.Cu")
		(net "M_C_CPU1_SA_DQ<12>")
	)
	(arc
		(start 80.008222 -233.466894)
		(mid 80.291178 -233.390717)
		(end 80.574134 -233.466894)
		(width 0.0889)
		(layer "In2.Cu")
		(net "M_C_CPU1_SA_DQ<12>")
	)
	(arc
		(start 90.348054 -233.466894)
		(mid 90.63101 -233.390717)
		(end 90.913966 -233.466894)
		(width 0.0889)
		(layer "In2.Cu")
		(net "M_C_CPU1_SA_DQ<12>")
	)
	(arc
		(start 93.733874 -233.466894)
		(mid 93.890312 -233.515865)
		(end 94.052644 -233.493056)
		(width 0.0889)
		(layer "In2.Cu")
		(net "M_C_CPU1_SA_DQ<12>")
	)
	(arc
		(start 88.10244 -233.47172)
		(mid 88.285948 -233.517214)
		(end 88.4682 -233.466894)
		(width 0.0889)
		(layer "In2.Cu")
		(net "M_C_CPU1_SA_DQ<12>")
	)
	(arc
		(start 84.707984 -233.466894)
		(mid 84.99094 -233.390717)
		(end 85.273896 -233.466894)
		(width 0.0889)
		(layer "In2.Cu")
		(net "M_C_CPU1_SA_DQ<12>")
	)
	(arc
		(start 84.334096 -233.466894)
		(mid 84.52104 -233.517149)
		(end 84.707984 -233.466894)
		(width 0.0889)
		(layer "In2.Cu")
		(net "M_C_CPU1_SA_DQ<12>")
	)
	(arc
		(start 91.862402 -233.47172)
		(mid 92.04591 -233.517214)
		(end 92.228162 -233.466894)
		(width 0.0889)
		(layer "In2.Cu")
		(net "M_C_CPU1_SA_DQ<12>")
	)
	(arc
		(start 81.513934 -233.466894)
		(mid 81.696185 -233.517244)
		(end 81.879694 -233.47172)
		(width 0.0889)
		(layer "In2.Cu")
		(net "M_C_CPU1_SA_DQ<12>")
	)
	(arc
		(start 87.162386 -233.47172)
		(mid 87.345894 -233.517214)
		(end 87.528146 -233.466894)
		(width 0.0889)
		(layer "In2.Cu")
		(net "M_C_CPU1_SA_DQ<12>")
	)
	(arc
		(start 86.21395 -233.466894)
		(mid 86.396201 -233.517244)
		(end 86.57971 -233.47172)
		(width 0.0889)
		(layer "In2.Cu")
		(net "M_C_CPU1_SA_DQ<12>")
	)
	(arc
		(start 83.768184 -233.466894)
		(mid 84.05114 -233.390717)
		(end 84.334096 -233.466894)
		(width 0.0889)
		(layer "In2.Cu")
		(net "M_C_CPU1_SA_DQ<12>")
	)
	(arc
		(start 89.973912 -233.466894)
		(mid 90.156163 -233.517244)
		(end 90.339672 -233.47172)
		(width 0.0889)
		(layer "In2.Cu")
		(net "M_C_CPU1_SA_DQ<12>")
	)
	(arc
		(start 93.167962 -233.466894)
		(mid 93.450918 -233.390717)
		(end 93.733874 -233.466894)
		(width 0.0889)
		(layer "In2.Cu")
		(net "M_C_CPU1_SA_DQ<12>")
	)
	(arc
		(start 88.4682 -233.466894)
		(mid 88.751156 -233.390717)
		(end 89.034112 -233.466894)
		(width 0.0889)
		(layer "In2.Cu")
		(net "M_C_CPU1_SA_DQ<12>")
	)
	(arc
		(start 85.648038 -233.466894)
		(mid 85.930994 -233.390717)
		(end 86.21395 -233.466894)
		(width 0.0889)
		(layer "In2.Cu")
		(net "M_C_CPU1_SA_DQ<12>")
	)
	(arc
		(start 91.288108 -233.466894)
		(mid 91.571064 -233.390717)
		(end 91.85402 -233.466894)
		(width 0.0889)
		(layer "In2.Cu")
		(net "M_C_CPU1_SA_DQ<12>")
	)
	(arc
		(start 80.574134 -233.466894)
		(mid 80.761078 -233.517149)
		(end 80.948022 -233.466894)
		(width 0.0889)
		(layer "In2.Cu")
		(net "M_C_CPU1_SA_DQ<12>")
	)
	(arc
		(start 85.273896 -233.466894)
		(mid 85.456147 -233.517244)
		(end 85.639656 -233.47172)
		(width 0.0889)
		(layer "In2.Cu")
		(net "M_C_CPU1_SA_DQ<12>")
	)
	(arc
		(start 90.922348 -233.47172)
		(mid 91.105856 -233.517214)
		(end 91.288108 -233.466894)
		(width 0.0889)
		(layer "In2.Cu")
		(net "M_C_CPU1_SA_DQ<12>")
	)
	(arc
		(start 89.408 -233.466894)
		(mid 89.690956 -233.390717)
		(end 89.973912 -233.466894)
		(width 0.0889)
		(layer "In2.Cu")
		(net "M_C_CPU1_SA_DQ<12>")
	)
	(arc
		(start 86.588092 -233.466894)
		(mid 86.871048 -233.390717)
		(end 87.154004 -233.466894)
		(width 0.0889)
		(layer "In2.Cu")
		(net "M_C_CPU1_SA_DQ<12>")
	)
	(arc
		(start 92.794074 -233.466894)
		(mid 92.981018 -233.517149)
		(end 93.167962 -233.466894)
		(width 0.0889)
		(layer "In2.Cu")
		(net "M_C_CPU1_SA_DQ<12>")
	)
	(arc
		(start 89.034112 -233.466894)
		(mid 89.221056 -233.517149)
		(end 89.408 -233.466894)
		(width 0.0889)
		(layer "In2.Cu")
		(net "M_C_CPU1_SA_DQ<12>")
	)
	(arc
		(start 79.633826 -233.466894)
		(mid 79.821024 -233.517276)
		(end 80.008222 -233.466894)
		(width 0.0889)
		(layer "In2.Cu")
		(net "M_C_CPU1_SA_DQ<12>")
	)
	(arc
		(start 80.948022 -233.466894)
		(mid 81.230978 -233.390717)
		(end 81.513934 -233.466894)
		(width 0.0889)
		(layer "In2.Cu")
		(net "M_C_CPU1_SA_DQ<12>")
	)
	(segment
		(start 96.267778 -231.79024)
		(end 95.800926 -231.524302)
		(width 0.10668)
		(layer "F.Cu")
		(net "M_C_CPU1_SA_DQ<11>")
	)
	(segment
		(start 77.658722 -225.533712)
		(end 77.690218 -225.552)
		(width 0.0889)
		(layer "In2.Cu")
		(net "M_C_CPU1_SA_DQ<11>")
	)
	(segment
		(start 95.647002 -231.258872)
		(end 95.800926 -231.524302)
		(width 0.0889)
		(layer "In2.Cu")
		(net "M_C_CPU1_SA_DQ<11>")
	)
	(segment
		(start 76.514706 -224.771204)
		(end 76.63815 -224.894648)
		(width 0.0889)
		(layer "In2.Cu")
		(net "M_C_CPU1_SA_DQ<11>")
	)
	(segment
		(start 95.039688 -231.19715)
		(end 95.04807 -231.201976)
		(width 0.0889)
		(layer "In2.Cu")
		(net "M_C_CPU1_SA_DQ<11>")
	)
	(segment
		(start 77.616812 -225.509328)
		(end 77.658722 -225.533712)
		(width 0.0889)
		(layer "In2.Cu")
		(net "M_C_CPU1_SA_DQ<11>")
	)
	(segment
		(start 90.913966 -231.201976)
		(end 90.922348 -231.19715)
		(width 0.0889)
		(layer "In2.Cu")
		(net "M_C_CPU1_SA_DQ<11>")
	)
	(segment
		(start 74.449686 -222.706184)
		(end 76.514706 -224.771204)
		(width 0.14478)
		(layer "In2.Cu")
		(net "M_C_CPU1_SA_DQ<11>")
	)
	(segment
		(start 88.094058 -231.201976)
		(end 88.10244 -231.19715)
		(width 0.0889)
		(layer "In2.Cu")
		(net "M_C_CPU1_SA_DQ<11>")
	)
	(segment
		(start 76.63815 -225.254566)
		(end 76.79563 -225.412046)
		(width 0.0889)
		(layer "In2.Cu")
		(net "M_C_CPU1_SA_DQ<11>")
	)
	(segment
		(start 79.9719 -229.560882)
		(end 80.008222 -229.581964)
		(width 0.0889)
		(layer "In2.Cu")
		(net "M_C_CPU1_SA_DQ<11>")
	)
	(segment
		(start 56.778906 -209.66049)
		(end 57.629044 -208.810352)
		(width 0.14478)
		(layer "In2.Cu")
		(net "M_C_CPU1_SA_DQ<11>")
	)
	(segment
		(start 79.029306 -227.940108)
		(end 79.068422 -227.962968)
		(width 0.0889)
		(layer "In2.Cu")
		(net "M_C_CPU1_SA_DQ<11>")
	)
	(segment
		(start 85.639656 -231.19715)
		(end 85.648038 -231.201976)
		(width 0.0889)
		(layer "In2.Cu")
		(net "M_C_CPU1_SA_DQ<11>")
	)
	(segment
		(start 49.11344 -209.650584)
		(end 49.963324 -208.8007)
		(width 0.14478)
		(layer "In2.Cu")
		(net "M_C_CPU1_SA_DQ<11>")
	)
	(segment
		(start 40.23995 -209.235294)
		(end 40.65524 -209.650584)
		(width 0.14478)
		(layer "In2.Cu")
		(net "M_C_CPU1_SA_DQ<11>")
	)
	(segment
		(start 76.63815 -224.894648)
		(end 76.63815 -225.254566)
		(width 0.0889)
		(layer "In2.Cu")
		(net "M_C_CPU1_SA_DQ<11>")
	)
	(segment
		(start 49.963324 -208.8007)
		(end 53.175662 -208.8007)
		(width 0.14478)
		(layer "In2.Cu")
		(net "M_C_CPU1_SA_DQ<11>")
	)
	(segment
		(start 79.068422 -227.962968)
		(end 79.099918 -227.981256)
		(width 0.0889)
		(layer "In2.Cu")
		(net "M_C_CPU1_SA_DQ<11>")
	)
	(segment
		(start 78.10119 -226.3267)
		(end 78.128622 -226.342702)
		(width 0.0889)
		(layer "In2.Cu")
		(net "M_C_CPU1_SA_DQ<11>")
	)
	(segment
		(start 57.629044 -208.810352)
		(end 62.344554 -208.810352)
		(width 0.14478)
		(layer "In2.Cu")
		(net "M_C_CPU1_SA_DQ<11>")
	)
	(segment
		(start 91.85402 -231.201976)
		(end 91.862402 -231.19715)
		(width 0.0889)
		(layer "In2.Cu")
		(net "M_C_CPU1_SA_DQ<11>")
	)
	(segment
		(start 79.503016 -228.751638)
		(end 79.538322 -228.772212)
		(width 0.0889)
		(layer "In2.Cu")
		(net "M_C_CPU1_SA_DQ<11>")
	)
	(segment
		(start 53.175662 -208.8007)
		(end 54.035452 -209.66049)
		(width 0.14478)
		(layer "In2.Cu")
		(net "M_C_CPU1_SA_DQ<11>")
	)
	(segment
		(start 54.035452 -209.66049)
		(end 56.778906 -209.66049)
		(width 0.14478)
		(layer "In2.Cu")
		(net "M_C_CPU1_SA_DQ<11>")
	)
	(segment
		(start 95.551244 -231.233472)
		(end 95.647002 -231.258872)
		(width 0.0889)
		(layer "In2.Cu")
		(net "M_C_CPU1_SA_DQ<11>")
	)
	(segment
		(start 79.538322 -228.772212)
		(end 79.56804 -228.789484)
		(width 0.0889)
		(layer "In2.Cu")
		(net "M_C_CPU1_SA_DQ<11>")
	)
	(segment
		(start 80.9117 -231.180894)
		(end 80.948022 -231.201976)
		(width 0.0889)
		(layer "In2.Cu")
		(net "M_C_CPU1_SA_DQ<11>")
	)
	(segment
		(start 78.128622 -226.342702)
		(end 78.156308 -226.358704)
		(width 0.0889)
		(layer "In2.Cu")
		(net "M_C_CPU1_SA_DQ<11>")
	)
	(segment
		(start 66.491866 -212.398864)
		(end 74.449686 -220.356684)
		(width 0.14478)
		(layer "In2.Cu")
		(net "M_C_CPU1_SA_DQ<11>")
	)
	(segment
		(start 62.344554 -208.810352)
		(end 65.933066 -212.398864)
		(width 0.14478)
		(layer "In2.Cu")
		(net "M_C_CPU1_SA_DQ<11>")
	)
	(segment
		(start 78.598268 -227.152708)
		(end 78.636368 -227.174806)
		(width 0.0889)
		(layer "In2.Cu")
		(net "M_C_CPU1_SA_DQ<11>")
	)
	(segment
		(start 83.394042 -231.201976)
		(end 83.402424 -231.19715)
		(width 0.0889)
		(layer "In2.Cu")
		(net "M_C_CPU1_SA_DQ<11>")
	)
	(segment
		(start 77.381862 -225.412046)
		(end 77.616812 -225.509328)
		(width 0.0889)
		(layer "In2.Cu")
		(net "M_C_CPU1_SA_DQ<11>")
	)
	(segment
		(start 80.008222 -229.581964)
		(end 80.040734 -229.60076)
		(width 0.0889)
		(layer "In2.Cu")
		(net "M_C_CPU1_SA_DQ<11>")
	)
	(segment
		(start 76.79563 -225.412046)
		(end 77.381862 -225.412046)
		(width 0.0889)
		(layer "In2.Cu")
		(net "M_C_CPU1_SA_DQ<11>")
	)
	(segment
		(start 65.933066 -212.398864)
		(end 66.491866 -212.398864)
		(width 0.14478)
		(layer "In2.Cu")
		(net "M_C_CPU1_SA_DQ<11>")
	)
	(segment
		(start 40.65524 -209.650584)
		(end 49.11344 -209.650584)
		(width 0.14478)
		(layer "In2.Cu")
		(net "M_C_CPU1_SA_DQ<11>")
	)
	(segment
		(start 80.478122 -230.39197)
		(end 80.509872 -230.410258)
		(width 0.0889)
		(layer "In2.Cu")
		(net "M_C_CPU1_SA_DQ<11>")
	)
	(segment
		(start 78.558644 -227.129594)
		(end 78.598268 -227.152708)
		(width 0.0889)
		(layer "In2.Cu")
		(net "M_C_CPU1_SA_DQ<11>")
	)
	(segment
		(start 81.879694 -231.19715)
		(end 81.888076 -231.201976)
		(width 0.0889)
		(layer "In2.Cu")
		(net "M_C_CPU1_SA_DQ<11>")
	)
	(segment
		(start 87.154004 -231.201976)
		(end 87.162386 -231.19715)
		(width 0.0889)
		(layer "In2.Cu")
		(net "M_C_CPU1_SA_DQ<11>")
	)
	(segment
		(start 74.449686 -220.356684)
		(end 74.449686 -222.706184)
		(width 0.14478)
		(layer "In2.Cu")
		(net "M_C_CPU1_SA_DQ<11>")
	)
	(segment
		(start 82.453988 -231.201976)
		(end 82.46237 -231.19715)
		(width 0.0889)
		(layer "In2.Cu")
		(net "M_C_CPU1_SA_DQ<11>")
	)
	(segment
		(start 80.441546 -230.370634)
		(end 80.478122 -230.39197)
		(width 0.0889)
		(layer "In2.Cu")
		(net "M_C_CPU1_SA_DQ<11>")
	)
	(segment
		(start 94.099634 -231.19715)
		(end 94.108016 -231.201976)
		(width 0.0889)
		(layer "In2.Cu")
		(net "M_C_CPU1_SA_DQ<11>")
	)
	(segment
		(start 90.339672 -231.19715)
		(end 90.348054 -231.201976)
		(width 0.0889)
		(layer "In2.Cu")
		(net "M_C_CPU1_SA_DQ<11>")
	)
	(segment
		(start 86.57971 -231.19715)
		(end 86.588092 -231.201976)
		(width 0.0889)
		(layer "In2.Cu")
		(net "M_C_CPU1_SA_DQ<11>")
	)
	(arc
		(start 80.040734 -229.60076)
		(mid 80.154663 -229.733907)
		(end 80.195674 -229.90429)
		(width 0.0889)
		(layer "In2.Cu")
		(net "M_C_CPU1_SA_DQ<11>")
	)
	(arc
		(start 92.228162 -231.201976)
		(mid 92.511118 -231.278153)
		(end 92.794074 -231.201976)
		(width 0.0889)
		(layer "In2.Cu")
		(net "M_C_CPU1_SA_DQ<11>")
	)
	(arc
		(start 93.167962 -231.201976)
		(mid 93.450918 -231.278153)
		(end 93.733874 -231.201976)
		(width 0.0889)
		(layer "In2.Cu")
		(net "M_C_CPU1_SA_DQ<11>")
	)
	(arc
		(start 87.162386 -231.19715)
		(mid 87.345894 -231.151625)
		(end 87.528146 -231.201976)
		(width 0.0889)
		(layer "In2.Cu")
		(net "M_C_CPU1_SA_DQ<11>")
	)
	(arc
		(start 91.288108 -231.201976)
		(mid 91.571064 -231.278153)
		(end 91.85402 -231.201976)
		(width 0.0889)
		(layer "In2.Cu")
		(net "M_C_CPU1_SA_DQ<11>")
	)
	(arc
		(start 84.334096 -231.201976)
		(mid 84.52104 -231.151687)
		(end 84.707984 -231.201976)
		(width 0.0889)
		(layer "In2.Cu")
		(net "M_C_CPU1_SA_DQ<11>")
	)
	(arc
		(start 78.636368 -227.174806)
		(mid 78.746588 -227.307136)
		(end 78.785974 -227.47478)
		(width 0.0889)
		(layer "In2.Cu")
		(net "M_C_CPU1_SA_DQ<11>")
	)
	(arc
		(start 84.707984 -231.201976)
		(mid 84.99094 -231.278153)
		(end 85.273896 -231.201976)
		(width 0.0889)
		(layer "In2.Cu")
		(net "M_C_CPU1_SA_DQ<11>")
	)
	(arc
		(start 93.733874 -231.201976)
		(mid 93.916125 -231.151592)
		(end 94.099634 -231.19715)
		(width 0.0889)
		(layer "In2.Cu")
		(net "M_C_CPU1_SA_DQ<11>")
	)
	(arc
		(start 89.973912 -231.201976)
		(mid 90.156163 -231.151592)
		(end 90.339672 -231.19715)
		(width 0.0889)
		(layer "In2.Cu")
		(net "M_C_CPU1_SA_DQ<11>")
	)
	(arc
		(start 86.588092 -231.201976)
		(mid 86.871048 -231.278153)
		(end 87.154004 -231.201976)
		(width 0.0889)
		(layer "In2.Cu")
		(net "M_C_CPU1_SA_DQ<11>")
	)
	(arc
		(start 79.56804 -228.789484)
		(mid 79.684221 -228.923043)
		(end 79.726028 -229.095046)
		(width 0.0889)
		(layer "In2.Cu")
		(net "M_C_CPU1_SA_DQ<11>")
	)
	(arc
		(start 88.10244 -231.19715)
		(mid 88.285948 -231.151625)
		(end 88.4682 -231.201976)
		(width 0.0889)
		(layer "In2.Cu")
		(net "M_C_CPU1_SA_DQ<11>")
	)
	(arc
		(start 81.888076 -231.201976)
		(mid 82.171032 -231.278153)
		(end 82.453988 -231.201976)
		(width 0.0889)
		(layer "In2.Cu")
		(net "M_C_CPU1_SA_DQ<11>")
	)
	(arc
		(start 78.785974 -227.47478)
		(mid 78.850292 -227.737449)
		(end 79.029306 -227.940108)
		(width 0.0889)
		(layer "In2.Cu")
		(net "M_C_CPU1_SA_DQ<11>")
	)
	(arc
		(start 95.04807 -231.201976)
		(mid 95.29593 -231.277059)
		(end 95.551244 -231.233472)
		(width 0.0889)
		(layer "In2.Cu")
		(net "M_C_CPU1_SA_DQ<11>")
	)
	(arc
		(start 80.195674 -229.90429)
		(mid 80.26091 -230.167881)
		(end 80.441546 -230.370634)
		(width 0.0889)
		(layer "In2.Cu")
		(net "M_C_CPU1_SA_DQ<11>")
	)
	(arc
		(start 78.156308 -226.358704)
		(mid 78.273928 -226.49265)
		(end 78.316328 -226.66579)
		(width 0.0889)
		(layer "In2.Cu")
		(net "M_C_CPU1_SA_DQ<11>")
	)
	(arc
		(start 86.21395 -231.201976)
		(mid 86.396201 -231.151592)
		(end 86.57971 -231.19715)
		(width 0.0889)
		(layer "In2.Cu")
		(net "M_C_CPU1_SA_DQ<11>")
	)
	(arc
		(start 85.273896 -231.201976)
		(mid 85.456147 -231.151592)
		(end 85.639656 -231.19715)
		(width 0.0889)
		(layer "In2.Cu")
		(net "M_C_CPU1_SA_DQ<11>")
	)
	(arc
		(start 78.316328 -226.66579)
		(mid 78.380548 -226.927446)
		(end 78.558644 -227.129594)
		(width 0.0889)
		(layer "In2.Cu")
		(net "M_C_CPU1_SA_DQ<11>")
	)
	(arc
		(start 80.948022 -231.201976)
		(mid 81.230978 -231.278153)
		(end 81.513934 -231.201976)
		(width 0.0889)
		(layer "In2.Cu")
		(net "M_C_CPU1_SA_DQ<11>")
	)
	(arc
		(start 77.846174 -225.85553)
		(mid 77.914224 -226.123312)
		(end 78.10119 -226.3267)
		(width 0.0889)
		(layer "In2.Cu")
		(net "M_C_CPU1_SA_DQ<11>")
	)
	(arc
		(start 94.673928 -231.201976)
		(mid 94.856179 -231.151592)
		(end 95.039688 -231.19715)
		(width 0.0889)
		(layer "In2.Cu")
		(net "M_C_CPU1_SA_DQ<11>")
	)
	(arc
		(start 94.108016 -231.201976)
		(mid 94.390972 -231.278153)
		(end 94.673928 -231.201976)
		(width 0.0889)
		(layer "In2.Cu")
		(net "M_C_CPU1_SA_DQ<11>")
	)
	(arc
		(start 90.922348 -231.19715)
		(mid 91.105856 -231.151625)
		(end 91.288108 -231.201976)
		(width 0.0889)
		(layer "In2.Cu")
		(net "M_C_CPU1_SA_DQ<11>")
	)
	(arc
		(start 79.726028 -229.095046)
		(mid 79.791382 -229.358354)
		(end 79.9719 -229.560882)
		(width 0.0889)
		(layer "In2.Cu")
		(net "M_C_CPU1_SA_DQ<11>")
	)
	(arc
		(start 83.768184 -231.201976)
		(mid 84.05114 -231.278153)
		(end 84.334096 -231.201976)
		(width 0.0889)
		(layer "In2.Cu")
		(net "M_C_CPU1_SA_DQ<11>")
	)
	(arc
		(start 79.255874 -228.28504)
		(mid 79.321574 -228.549001)
		(end 79.503016 -228.751638)
		(width 0.0889)
		(layer "In2.Cu")
		(net "M_C_CPU1_SA_DQ<11>")
	)
	(arc
		(start 92.794074 -231.201976)
		(mid 92.981018 -231.151687)
		(end 93.167962 -231.201976)
		(width 0.0889)
		(layer "In2.Cu")
		(net "M_C_CPU1_SA_DQ<11>")
	)
	(arc
		(start 80.665828 -230.71455)
		(mid 80.731064 -230.978141)
		(end 80.9117 -231.180894)
		(width 0.0889)
		(layer "In2.Cu")
		(net "M_C_CPU1_SA_DQ<11>")
	)
	(arc
		(start 90.348054 -231.201976)
		(mid 90.63101 -231.278153)
		(end 90.913966 -231.201976)
		(width 0.0889)
		(layer "In2.Cu")
		(net "M_C_CPU1_SA_DQ<11>")
	)
	(arc
		(start 85.648038 -231.201976)
		(mid 85.930994 -231.278153)
		(end 86.21395 -231.201976)
		(width 0.0889)
		(layer "In2.Cu")
		(net "M_C_CPU1_SA_DQ<11>")
	)
	(arc
		(start 87.528146 -231.201976)
		(mid 87.811102 -231.278153)
		(end 88.094058 -231.201976)
		(width 0.0889)
		(layer "In2.Cu")
		(net "M_C_CPU1_SA_DQ<11>")
	)
	(arc
		(start 89.408 -231.201976)
		(mid 89.690956 -231.278153)
		(end 89.973912 -231.201976)
		(width 0.0889)
		(layer "In2.Cu")
		(net "M_C_CPU1_SA_DQ<11>")
	)
	(arc
		(start 83.402424 -231.19715)
		(mid 83.585932 -231.151625)
		(end 83.768184 -231.201976)
		(width 0.0889)
		(layer "In2.Cu")
		(net "M_C_CPU1_SA_DQ<11>")
	)
	(arc
		(start 81.513934 -231.201976)
		(mid 81.696185 -231.151592)
		(end 81.879694 -231.19715)
		(width 0.0889)
		(layer "In2.Cu")
		(net "M_C_CPU1_SA_DQ<11>")
	)
	(arc
		(start 89.034112 -231.201976)
		(mid 89.221056 -231.151687)
		(end 89.408 -231.201976)
		(width 0.0889)
		(layer "In2.Cu")
		(net "M_C_CPU1_SA_DQ<11>")
	)
	(arc
		(start 91.862402 -231.19715)
		(mid 92.04591 -231.151625)
		(end 92.228162 -231.201976)
		(width 0.0889)
		(layer "In2.Cu")
		(net "M_C_CPU1_SA_DQ<11>")
	)
	(arc
		(start 77.690218 -225.552)
		(mid 77.804778 -225.684965)
		(end 77.846174 -225.85553)
		(width 0.0889)
		(layer "In2.Cu")
		(net "M_C_CPU1_SA_DQ<11>")
	)
	(arc
		(start 80.509872 -230.410258)
		(mid 80.624548 -230.543592)
		(end 80.665828 -230.71455)
		(width 0.0889)
		(layer "In2.Cu")
		(net "M_C_CPU1_SA_DQ<11>")
	)
	(arc
		(start 79.099918 -227.981256)
		(mid 79.214537 -228.114334)
		(end 79.255874 -228.28504)
		(width 0.0889)
		(layer "In2.Cu")
		(net "M_C_CPU1_SA_DQ<11>")
	)
	(arc
		(start 88.4682 -231.201976)
		(mid 88.751156 -231.278153)
		(end 89.034112 -231.201976)
		(width 0.0889)
		(layer "In2.Cu")
		(net "M_C_CPU1_SA_DQ<11>")
	)
	(arc
		(start 82.46237 -231.19715)
		(mid 82.645878 -231.151625)
		(end 82.82813 -231.201976)
		(width 0.0889)
		(layer "In2.Cu")
		(net "M_C_CPU1_SA_DQ<11>")
	)
	(arc
		(start 82.82813 -231.201976)
		(mid 83.111086 -231.278153)
		(end 83.394042 -231.201976)
		(width 0.0889)
		(layer "In2.Cu")
		(net "M_C_CPU1_SA_DQ<11>")
	)
	(segment
		(start 94.857824 -230.980234)
		(end 94.390972 -230.71455)
		(width 0.10668)
		(layer "F.Cu")
		(net "M_C_CPU1_SA_DQ<10>")
	)
	(segment
		(start 42.186098 -207.392524)
		(end 42.416476 -207.392524)
		(width 0.14478)
		(layer "In2.Cu")
		(net "M_C_CPU1_SA_DQ<10>")
	)
	(segment
		(start 42.579544 -207.555592)
		(end 42.579544 -207.7974)
		(width 0.14478)
		(layer "In2.Cu")
		(net "M_C_CPU1_SA_DQ<10>")
	)
	(segment
		(start 80.008222 -227.961952)
		(end 80.038702 -227.979732)
		(width 0.0889)
		(layer "In2.Cu")
		(net "M_C_CPU1_SA_DQ<10>")
	)
	(segment
		(start 76.910946 -223.846644)
		(end 77.532738 -223.846644)
		(width 0.0889)
		(layer "In2.Cu")
		(net "M_C_CPU1_SA_DQ<10>")
	)
	(segment
		(start 78.598014 -225.531934)
		(end 78.631796 -225.551492)
		(width 0.0889)
		(layer "In2.Cu")
		(net "M_C_CPU1_SA_DQ<10>")
	)
	(segment
		(start 87.989664 -230.387144)
		(end 87.998046 -230.39197)
		(width 0.0889)
		(layer "In2.Cu")
		(net "M_C_CPU1_SA_DQ<10>")
	)
	(segment
		(start 94.141036 -230.42372)
		(end 94.237048 -230.44912)
		(width 0.0889)
		(layer "In2.Cu")
		(net "M_C_CPU1_SA_DQ<10>")
	)
	(segment
		(start 41.859962 -207.960468)
		(end 42.02303 -207.7974)
		(width 0.14478)
		(layer "In2.Cu")
		(net "M_C_CPU1_SA_DQ<10>")
	)
	(segment
		(start 79.068676 -226.34067)
		(end 79.09687 -226.356926)
		(width 0.0889)
		(layer "In2.Cu")
		(net "M_C_CPU1_SA_DQ<10>")
	)
	(segment
		(start 83.289648 -230.387144)
		(end 83.29803 -230.39197)
		(width 0.0889)
		(layer "In2.Cu")
		(net "M_C_CPU1_SA_DQ<10>")
	)
	(segment
		(start 49.213262 -207.960468)
		(end 50.0634 -207.11033)
		(width 0.14478)
		(layer "In2.Cu")
		(net "M_C_CPU1_SA_DQ<10>")
	)
	(segment
		(start 85.74405 -230.39197)
		(end 85.752432 -230.387144)
		(width 0.0889)
		(layer "In2.Cu")
		(net "M_C_CPU1_SA_DQ<10>")
	)
	(segment
		(start 53.952648 -207.960468)
		(end 56.751728 -207.960468)
		(width 0.14478)
		(layer "In2.Cu")
		(net "M_C_CPU1_SA_DQ<10>")
	)
	(segment
		(start 42.02303 -207.555592)
		(end 42.186098 -207.392524)
		(width 0.14478)
		(layer "In2.Cu")
		(net "M_C_CPU1_SA_DQ<10>")
	)
	(segment
		(start 92.68968 -230.387144)
		(end 92.698062 -230.39197)
		(width 0.0889)
		(layer "In2.Cu")
		(net "M_C_CPU1_SA_DQ<10>")
	)
	(segment
		(start 91.749626 -230.387144)
		(end 91.758008 -230.39197)
		(width 0.0889)
		(layer "In2.Cu")
		(net "M_C_CPU1_SA_DQ<10>")
	)
	(segment
		(start 53.102764 -207.11033)
		(end 53.952648 -207.960214)
		(width 0.14478)
		(layer "In2.Cu")
		(net "M_C_CPU1_SA_DQ<10>")
	)
	(segment
		(start 89.504012 -230.39197)
		(end 89.512394 -230.387144)
		(width 0.0889)
		(layer "In2.Cu")
		(net "M_C_CPU1_SA_DQ<10>")
	)
	(segment
		(start 40.23995 -207.535272)
		(end 40.665146 -207.960468)
		(width 0.14478)
		(layer "In2.Cu")
		(net "M_C_CPU1_SA_DQ<10>")
	)
	(segment
		(start 66.852546 -211.451444)
		(end 75.374246 -219.973144)
		(width 0.14478)
		(layer "In2.Cu")
		(net "M_C_CPU1_SA_DQ<10>")
	)
	(segment
		(start 42.416476 -207.392524)
		(end 42.579544 -207.555592)
		(width 0.14478)
		(layer "In2.Cu")
		(net "M_C_CPU1_SA_DQ<10>")
	)
	(segment
		(start 42.02303 -207.7974)
		(end 42.02303 -207.555592)
		(width 0.14478)
		(layer "In2.Cu")
		(net "M_C_CPU1_SA_DQ<10>")
	)
	(segment
		(start 79.9719 -227.94087)
		(end 80.008222 -227.961952)
		(width 0.0889)
		(layer "In2.Cu")
		(net "M_C_CPU1_SA_DQ<10>")
	)
	(segment
		(start 80.948022 -229.581964)
		(end 80.98155 -229.601522)
		(width 0.0889)
		(layer "In2.Cu")
		(net "M_C_CPU1_SA_DQ<10>")
	)
	(segment
		(start 61.983366 -207.11033)
		(end 66.32448 -211.451444)
		(width 0.14478)
		(layer "In2.Cu")
		(net "M_C_CPU1_SA_DQ<10>")
	)
	(segment
		(start 93.263974 -230.39197)
		(end 93.272356 -230.387144)
		(width 0.0889)
		(layer "In2.Cu")
		(net "M_C_CPU1_SA_DQ<10>")
	)
	(segment
		(start 66.32448 -211.451444)
		(end 66.852546 -211.451444)
		(width 0.14478)
		(layer "In2.Cu")
		(net "M_C_CPU1_SA_DQ<10>")
	)
	(segment
		(start 84.803996 -230.39197)
		(end 84.812378 -230.387144)
		(width 0.0889)
		(layer "In2.Cu")
		(net "M_C_CPU1_SA_DQ<10>")
	)
	(segment
		(start 50.0634 -207.11033)
		(end 53.102764 -207.11033)
		(width 0.14478)
		(layer "In2.Cu")
		(net "M_C_CPU1_SA_DQ<10>")
	)
	(segment
		(start 80.9117 -229.560882)
		(end 80.948022 -229.581964)
		(width 0.0889)
		(layer "In2.Cu")
		(net "M_C_CPU1_SA_DQ<10>")
	)
	(segment
		(start 78.128368 -224.721166)
		(end 78.166214 -224.74301)
		(width 0.0889)
		(layer "In2.Cu")
		(net "M_C_CPU1_SA_DQ<10>")
	)
	(segment
		(start 75.374246 -219.973144)
		(end 75.374246 -222.309944)
		(width 0.14478)
		(layer "In2.Cu")
		(net "M_C_CPU1_SA_DQ<10>")
	)
	(segment
		(start 56.751728 -207.960468)
		(end 57.601866 -207.11033)
		(width 0.14478)
		(layer "In2.Cu")
		(net "M_C_CPU1_SA_DQ<10>")
	)
	(segment
		(start 78.56474 -225.51263)
		(end 78.598014 -225.531934)
		(width 0.0889)
		(layer "In2.Cu")
		(net "M_C_CPU1_SA_DQ<10>")
	)
	(segment
		(start 80.478122 -228.771958)
		(end 80.509872 -228.790246)
		(width 0.0889)
		(layer "In2.Cu")
		(net "M_C_CPU1_SA_DQ<10>")
	)
	(segment
		(start 94.237048 -230.44912)
		(end 94.390972 -230.71455)
		(width 0.0889)
		(layer "In2.Cu")
		(net "M_C_CPU1_SA_DQ<10>")
	)
	(segment
		(start 42.742612 -207.960468)
		(end 49.213262 -207.960468)
		(width 0.14478)
		(layer "In2.Cu")
		(net "M_C_CPU1_SA_DQ<10>")
	)
	(segment
		(start 76.651104 -223.586802)
		(end 76.910946 -223.846644)
		(width 0.0889)
		(layer "In2.Cu")
		(net "M_C_CPU1_SA_DQ<10>")
	)
	(segment
		(start 81.3816 -230.370634)
		(end 81.418176 -230.39197)
		(width 0.0889)
		(layer "In2.Cu")
		(net "M_C_CPU1_SA_DQ<10>")
	)
	(segment
		(start 79.538322 -227.151438)
		(end 79.573628 -227.172012)
		(width 0.0889)
		(layer "In2.Cu")
		(net "M_C_CPU1_SA_DQ<10>")
	)
	(segment
		(start 57.601866 -207.11033)
		(end 61.983366 -207.11033)
		(width 0.14478)
		(layer "In2.Cu")
		(net "M_C_CPU1_SA_DQ<10>")
	)
	(segment
		(start 79.495904 -227.1268)
		(end 79.538322 -227.151438)
		(width 0.0889)
		(layer "In2.Cu")
		(net "M_C_CPU1_SA_DQ<10>")
	)
	(segment
		(start 78.081632 -224.693988)
		(end 78.128368 -224.721166)
		(width 0.0889)
		(layer "In2.Cu")
		(net "M_C_CPU1_SA_DQ<10>")
	)
	(segment
		(start 75.374246 -222.309944)
		(end 76.651104 -223.586802)
		(width 0.14478)
		(layer "In2.Cu")
		(net "M_C_CPU1_SA_DQ<10>")
	)
	(segment
		(start 40.665146 -207.960468)
		(end 41.859962 -207.960468)
		(width 0.14478)
		(layer "In2.Cu")
		(net "M_C_CPU1_SA_DQ<10>")
	)
	(segment
		(start 53.952648 -207.960214)
		(end 53.952648 -207.960468)
		(width 0.14478)
		(layer "In2.Cu")
		(net "M_C_CPU1_SA_DQ<10>")
	)
	(segment
		(start 88.929718 -230.387144)
		(end 88.9381 -230.39197)
		(width 0.0889)
		(layer "In2.Cu")
		(net "M_C_CPU1_SA_DQ<10>")
	)
	(segment
		(start 84.229702 -230.387144)
		(end 84.238084 -230.39197)
		(width 0.0889)
		(layer "In2.Cu")
		(net "M_C_CPU1_SA_DQ<10>")
	)
	(segment
		(start 77.563726 -223.85528)
		(end 77.660754 -223.913446)
		(width 0.0889)
		(layer "In2.Cu")
		(net "M_C_CPU1_SA_DQ<10>")
	)
	(segment
		(start 80.439006 -228.749098)
		(end 80.478122 -228.771958)
		(width 0.0889)
		(layer "In2.Cu")
		(net "M_C_CPU1_SA_DQ<10>")
	)
	(segment
		(start 42.579544 -207.7974)
		(end 42.742612 -207.960468)
		(width 0.14478)
		(layer "In2.Cu")
		(net "M_C_CPU1_SA_DQ<10>")
	)
	(segment
		(start 79.029052 -226.31781)
		(end 79.068676 -226.34067)
		(width 0.0889)
		(layer "In2.Cu")
		(net "M_C_CPU1_SA_DQ<10>")
	)
	(arc
		(start 80.038702 -227.979732)
		(mid 80.154129 -228.113108)
		(end 80.195674 -228.284532)
		(width 0.0889)
		(layer "In2.Cu")
		(net "M_C_CPU1_SA_DQ<10>")
	)
	(arc
		(start 91.758008 -230.39197)
		(mid 92.040964 -230.468113)
		(end 92.32392 -230.39197)
		(width 0.0889)
		(layer "In2.Cu")
		(net "M_C_CPU1_SA_DQ<10>")
	)
	(arc
		(start 85.752432 -230.387144)
		(mid 85.93594 -230.34165)
		(end 86.118192 -230.39197)
		(width 0.0889)
		(layer "In2.Cu")
		(net "M_C_CPU1_SA_DQ<10>")
	)
	(arc
		(start 92.32392 -230.39197)
		(mid 92.506171 -230.34162)
		(end 92.68968 -230.387144)
		(width 0.0889)
		(layer "In2.Cu")
		(net "M_C_CPU1_SA_DQ<10>")
	)
	(arc
		(start 77.660754 -223.913446)
		(mid 77.796161 -224.049243)
		(end 77.845666 -224.234502)
		(width 0.0889)
		(layer "In2.Cu")
		(net "M_C_CPU1_SA_DQ<10>")
	)
	(arc
		(start 88.563958 -230.39197)
		(mid 88.746209 -230.34162)
		(end 88.929718 -230.387144)
		(width 0.0889)
		(layer "In2.Cu")
		(net "M_C_CPU1_SA_DQ<10>")
	)
	(arc
		(start 78.785974 -225.854006)
		(mid 78.850578 -226.115759)
		(end 79.029052 -226.31781)
		(width 0.0889)
		(layer "In2.Cu")
		(net "M_C_CPU1_SA_DQ<10>")
	)
	(arc
		(start 93.272356 -230.387144)
		(mid 93.455864 -230.34165)
		(end 93.638116 -230.39197)
		(width 0.0889)
		(layer "In2.Cu")
		(net "M_C_CPU1_SA_DQ<10>")
	)
	(arc
		(start 82.357976 -230.39197)
		(mid 82.640932 -230.468113)
		(end 82.923888 -230.39197)
		(width 0.0889)
		(layer "In2.Cu")
		(net "M_C_CPU1_SA_DQ<10>")
	)
	(arc
		(start 86.118192 -230.39197)
		(mid 86.401148 -230.468113)
		(end 86.684104 -230.39197)
		(width 0.0889)
		(layer "In2.Cu")
		(net "M_C_CPU1_SA_DQ<10>")
	)
	(arc
		(start 87.623904 -230.39197)
		(mid 87.806155 -230.34162)
		(end 87.989664 -230.387144)
		(width 0.0889)
		(layer "In2.Cu")
		(net "M_C_CPU1_SA_DQ<10>")
	)
	(arc
		(start 78.166214 -224.74301)
		(mid 78.276707 -224.875386)
		(end 78.316074 -225.043238)
		(width 0.0889)
		(layer "In2.Cu")
		(net "M_C_CPU1_SA_DQ<10>")
	)
	(arc
		(start 91.383866 -230.39197)
		(mid 91.566117 -230.34162)
		(end 91.749626 -230.387144)
		(width 0.0889)
		(layer "In2.Cu")
		(net "M_C_CPU1_SA_DQ<10>")
	)
	(arc
		(start 93.638116 -230.39197)
		(mid 93.885829 -230.467156)
		(end 94.141036 -230.42372)
		(width 0.0889)
		(layer "In2.Cu")
		(net "M_C_CPU1_SA_DQ<10>")
	)
	(arc
		(start 81.418176 -230.39197)
		(mid 81.701132 -230.468113)
		(end 81.984088 -230.39197)
		(width 0.0889)
		(layer "In2.Cu")
		(net "M_C_CPU1_SA_DQ<10>")
	)
	(arc
		(start 83.29803 -230.39197)
		(mid 83.580986 -230.468113)
		(end 83.863942 -230.39197)
		(width 0.0889)
		(layer "In2.Cu")
		(net "M_C_CPU1_SA_DQ<10>")
	)
	(arc
		(start 87.057992 -230.39197)
		(mid 87.340948 -230.468113)
		(end 87.623904 -230.39197)
		(width 0.0889)
		(layer "In2.Cu")
		(net "M_C_CPU1_SA_DQ<10>")
	)
	(arc
		(start 92.698062 -230.39197)
		(mid 92.981018 -230.468113)
		(end 93.263974 -230.39197)
		(width 0.0889)
		(layer "In2.Cu")
		(net "M_C_CPU1_SA_DQ<10>")
	)
	(arc
		(start 89.512394 -230.387144)
		(mid 89.695902 -230.34165)
		(end 89.878154 -230.39197)
		(width 0.0889)
		(layer "In2.Cu")
		(net "M_C_CPU1_SA_DQ<10>")
	)
	(arc
		(start 79.573628 -227.172012)
		(mid 79.685757 -227.30473)
		(end 79.726028 -227.473764)
		(width 0.0889)
		(layer "In2.Cu")
		(net "M_C_CPU1_SA_DQ<10>")
	)
	(arc
		(start 90.444066 -230.39197)
		(mid 90.63101 -230.341715)
		(end 90.817954 -230.39197)
		(width 0.0889)
		(layer "In2.Cu")
		(net "M_C_CPU1_SA_DQ<10>")
	)
	(arc
		(start 79.255874 -226.663504)
		(mid 79.319225 -226.924508)
		(end 79.495904 -227.1268)
		(width 0.0889)
		(layer "In2.Cu")
		(net "M_C_CPU1_SA_DQ<10>")
	)
	(arc
		(start 78.631796 -225.551492)
		(mid 78.745088 -225.684296)
		(end 78.785974 -225.854006)
		(width 0.0889)
		(layer "In2.Cu")
		(net "M_C_CPU1_SA_DQ<10>")
	)
	(arc
		(start 90.817954 -230.39197)
		(mid 91.10091 -230.468113)
		(end 91.383866 -230.39197)
		(width 0.0889)
		(layer "In2.Cu")
		(net "M_C_CPU1_SA_DQ<10>")
	)
	(arc
		(start 80.195674 -228.284532)
		(mid 80.260189 -228.546751)
		(end 80.439006 -228.749098)
		(width 0.0889)
		(layer "In2.Cu")
		(net "M_C_CPU1_SA_DQ<10>")
	)
	(arc
		(start 88.9381 -230.39197)
		(mid 89.221056 -230.468113)
		(end 89.504012 -230.39197)
		(width 0.0889)
		(layer "In2.Cu")
		(net "M_C_CPU1_SA_DQ<10>")
	)
	(arc
		(start 80.98155 -229.601522)
		(mid 81.094957 -229.734411)
		(end 81.135728 -229.90429)
		(width 0.0889)
		(layer "In2.Cu")
		(net "M_C_CPU1_SA_DQ<10>")
	)
	(arc
		(start 77.845666 -224.234502)
		(mid 77.908102 -224.492774)
		(end 78.081632 -224.693988)
		(width 0.0889)
		(layer "In2.Cu")
		(net "M_C_CPU1_SA_DQ<10>")
	)
	(arc
		(start 82.923888 -230.39197)
		(mid 83.106139 -230.34162)
		(end 83.289648 -230.387144)
		(width 0.0889)
		(layer "In2.Cu")
		(net "M_C_CPU1_SA_DQ<10>")
	)
	(arc
		(start 80.665828 -229.094538)
		(mid 80.731064 -229.358129)
		(end 80.9117 -229.560882)
		(width 0.0889)
		(layer "In2.Cu")
		(net "M_C_CPU1_SA_DQ<10>")
	)
	(arc
		(start 79.726028 -227.473764)
		(mid 79.791086 -227.73778)
		(end 79.9719 -227.94087)
		(width 0.0889)
		(layer "In2.Cu")
		(net "M_C_CPU1_SA_DQ<10>")
	)
	(arc
		(start 85.178138 -230.39197)
		(mid 85.461094 -230.468113)
		(end 85.74405 -230.39197)
		(width 0.0889)
		(layer "In2.Cu")
		(net "M_C_CPU1_SA_DQ<10>")
	)
	(arc
		(start 83.863942 -230.39197)
		(mid 84.046193 -230.34162)
		(end 84.229702 -230.387144)
		(width 0.0889)
		(layer "In2.Cu")
		(net "M_C_CPU1_SA_DQ<10>")
	)
	(arc
		(start 78.316074 -225.043238)
		(mid 78.381805 -225.308975)
		(end 78.56474 -225.51263)
		(width 0.0889)
		(layer "In2.Cu")
		(net "M_C_CPU1_SA_DQ<10>")
	)
	(arc
		(start 79.09687 -226.356926)
		(mid 79.213866 -226.490779)
		(end 79.255874 -226.663504)
		(width 0.0889)
		(layer "In2.Cu")
		(net "M_C_CPU1_SA_DQ<10>")
	)
	(arc
		(start 81.135728 -229.90429)
		(mid 81.200964 -230.167881)
		(end 81.3816 -230.370634)
		(width 0.0889)
		(layer "In2.Cu")
		(net "M_C_CPU1_SA_DQ<10>")
	)
	(arc
		(start 81.984088 -230.39197)
		(mid 82.171032 -230.341715)
		(end 82.357976 -230.39197)
		(width 0.0889)
		(layer "In2.Cu")
		(net "M_C_CPU1_SA_DQ<10>")
	)
	(arc
		(start 80.509872 -228.790246)
		(mid 80.624548 -228.92358)
		(end 80.665828 -229.094538)
		(width 0.0889)
		(layer "In2.Cu")
		(net "M_C_CPU1_SA_DQ<10>")
	)
	(arc
		(start 84.238084 -230.39197)
		(mid 84.52104 -230.468113)
		(end 84.803996 -230.39197)
		(width 0.0889)
		(layer "In2.Cu")
		(net "M_C_CPU1_SA_DQ<10>")
	)
	(arc
		(start 86.684104 -230.39197)
		(mid 86.871048 -230.341715)
		(end 87.057992 -230.39197)
		(width 0.0889)
		(layer "In2.Cu")
		(net "M_C_CPU1_SA_DQ<10>")
	)
	(arc
		(start 77.532738 -223.846644)
		(mid 77.548828 -223.848834)
		(end 77.563726 -223.85528)
		(width 0.0889)
		(layer "In2.Cu")
		(net "M_C_CPU1_SA_DQ<10>")
	)
	(arc
		(start 84.812378 -230.387144)
		(mid 84.995886 -230.34165)
		(end 85.178138 -230.39197)
		(width 0.0889)
		(layer "In2.Cu")
		(net "M_C_CPU1_SA_DQ<10>")
	)
	(arc
		(start 89.878154 -230.39197)
		(mid 90.16111 -230.468113)
		(end 90.444066 -230.39197)
		(width 0.0889)
		(layer "In2.Cu")
		(net "M_C_CPU1_SA_DQ<10>")
	)
	(arc
		(start 87.998046 -230.39197)
		(mid 88.281002 -230.468113)
		(end 88.563958 -230.39197)
		(width 0.0889)
		(layer "In2.Cu")
		(net "M_C_CPU1_SA_DQ<10>")
	)
	(segment
		(start 94.387924 -225.310446)
		(end 93.921072 -225.044508)
		(width 0.10668)
		(layer "F.Cu")
		(net "M_C_CPU1_SA_DQ<0>")
	)
	(segment
		(start 94.074996 -225.309938)
		(end 93.921072 -225.044508)
		(width 0.0889)
		(layer "In2.Cu")
		(net "M_C_CPU1_SA_DQ<0>")
	)
	(segment
		(start 84.302346 -225.3488)
		(end 84.334096 -225.367088)
		(width 0.0889)
		(layer "In2.Cu")
		(net "M_C_CPU1_SA_DQ<0>")
	)
	(segment
		(start 90.339672 -225.371914)
		(end 90.348054 -225.367088)
		(width 0.0889)
		(layer "In2.Cu")
		(net "M_C_CPU1_SA_DQ<0>")
	)
	(segment
		(start 50.524918 -196.747384)
		(end 50.687986 -196.910452)
		(width 0.14478)
		(layer "In2.Cu")
		(net "M_C_CPU1_SA_DQ<0>")
	)
	(segment
		(start 48.855376 -196.747384)
		(end 48.855376 -196.379592)
		(width 0.14478)
		(layer "In2.Cu")
		(net "M_C_CPU1_SA_DQ<0>")
	)
	(segment
		(start 56.332374 -196.747384)
		(end 56.332374 -196.232272)
		(width 0.14478)
		(layer "In2.Cu")
		(net "M_C_CPU1_SA_DQ<0>")
	)
	(segment
		(start 77.563726 -211.697824)
		(end 77.563726 -213.404704)
		(width 0.14478)
		(layer "In2.Cu")
		(net "M_C_CPU1_SA_DQ<0>")
	)
	(segment
		(start 49.574958 -196.910452)
		(end 49.805336 -196.910452)
		(width 0.14478)
		(layer "In2.Cu")
		(net "M_C_CPU1_SA_DQ<0>")
	)
	(segment
		(start 83.394042 -223.747076)
		(end 83.433158 -223.769936)
		(width 0.0889)
		(layer "In2.Cu")
		(net "M_C_CPU1_SA_DQ<0>")
	)
	(segment
		(start 45.755306 -196.614034)
		(end 45.918374 -196.450966)
		(width 0.14478)
		(layer "In2.Cu")
		(net "M_C_CPU1_SA_DQ<0>")
	)
	(segment
		(start 57.282334 -196.910452)
		(end 57.445402 -196.747384)
		(width 0.14478)
		(layer "In2.Cu")
		(net "M_C_CPU1_SA_DQ<0>")
	)
	(segment
		(start 57.838848 -196.069204)
		(end 58.001916 -196.232272)
		(width 0.14478)
		(layer "In2.Cu")
		(net "M_C_CPU1_SA_DQ<0>")
	)
	(segment
		(start 82.893408 -222.91929)
		(end 82.923888 -222.93707)
		(width 0.0889)
		(layer "In2.Cu")
		(net "M_C_CPU1_SA_DQ<0>")
	)
	(segment
		(start 56.495442 -196.069204)
		(end 56.72582 -196.069204)
		(width 0.14478)
		(layer "In2.Cu")
		(net "M_C_CPU1_SA_DQ<0>")
	)
	(segment
		(start 90.913966 -225.367088)
		(end 90.922348 -225.371914)
		(width 0.0889)
		(layer "In2.Cu")
		(net "M_C_CPU1_SA_DQ<0>")
	)
	(segment
		(start 56.888888 -196.232272)
		(end 56.888888 -196.747384)
		(width 0.14478)
		(layer "In2.Cu")
		(net "M_C_CPU1_SA_DQ<0>")
	)
	(segment
		(start 49.968404 -196.747384)
		(end 49.968404 -196.379592)
		(width 0.14478)
		(layer "In2.Cu")
		(net "M_C_CPU1_SA_DQ<0>")
	)
	(segment
		(start 82.526886 -221.210124)
		(end 82.526886 -221.375224)
		(width 0.0889)
		(layer "In2.Cu")
		(net "M_C_CPU1_SA_DQ<0>")
	)
	(segment
		(start 46.31182 -196.614034)
		(end 46.31182 -196.747384)
		(width 0.14478)
		(layer "In2.Cu")
		(net "M_C_CPU1_SA_DQ<0>")
	)
	(segment
		(start 58.001916 -196.232272)
		(end 58.001916 -196.747384)
		(width 0.14478)
		(layer "In2.Cu")
		(net "M_C_CPU1_SA_DQ<0>")
	)
	(segment
		(start 82.923888 -222.93707)
		(end 82.963004 -222.95993)
		(width 0.0889)
		(layer "In2.Cu")
		(net "M_C_CPU1_SA_DQ<0>")
	)
	(segment
		(start 57.445402 -196.232272)
		(end 57.60847 -196.069204)
		(width 0.14478)
		(layer "In2.Cu")
		(net "M_C_CPU1_SA_DQ<0>")
	)
	(segment
		(start 82.454242 -222.127064)
		(end 82.491834 -222.148908)
		(width 0.0889)
		(layer "In2.Cu")
		(net "M_C_CPU1_SA_DQ<0>")
	)
	(segment
		(start 46.31182 -196.747384)
		(end 46.474888 -196.910452)
		(width 0.14478)
		(layer "In2.Cu")
		(net "M_C_CPU1_SA_DQ<0>")
	)
	(segment
		(start 58.164984 -196.910452)
		(end 61.745114 -196.910452)
		(width 0.14478)
		(layer "In2.Cu")
		(net "M_C_CPU1_SA_DQ<0>")
	)
	(segment
		(start 88.094058 -225.367088)
		(end 88.10244 -225.371914)
		(width 0.0889)
		(layer "In2.Cu")
		(net "M_C_CPU1_SA_DQ<0>")
	)
	(segment
		(start 57.445402 -196.747384)
		(end 57.445402 -196.232272)
		(width 0.14478)
		(layer "In2.Cu")
		(net "M_C_CPU1_SA_DQ<0>")
	)
	(segment
		(start 56.332374 -196.232272)
		(end 56.495442 -196.069204)
		(width 0.14478)
		(layer "In2.Cu")
		(net "M_C_CPU1_SA_DQ<0>")
	)
	(segment
		(start 45.755306 -196.747384)
		(end 45.755306 -196.614034)
		(width 0.14478)
		(layer "In2.Cu")
		(net "M_C_CPU1_SA_DQ<0>")
	)
	(segment
		(start 48.692308 -196.910452)
		(end 48.855376 -196.747384)
		(width 0.14478)
		(layer "In2.Cu")
		(net "M_C_CPU1_SA_DQ<0>")
	)
	(segment
		(start 82.526886 -221.375224)
		(end 82.248248 -221.653862)
		(width 0.0889)
		(layer "In2.Cu")
		(net "M_C_CPU1_SA_DQ<0>")
	)
	(segment
		(start 83.833462 -224.539302)
		(end 83.863942 -224.557082)
		(width 0.0889)
		(layer "In2.Cu")
		(net "M_C_CPU1_SA_DQ<0>")
	)
	(segment
		(start 50.687986 -196.910452)
		(end 56.169306 -196.910452)
		(width 0.14478)
		(layer "In2.Cu")
		(net "M_C_CPU1_SA_DQ<0>")
	)
	(segment
		(start 74.538586 -208.672684)
		(end 77.563726 -211.697824)
		(width 0.14478)
		(layer "In2.Cu")
		(net "M_C_CPU1_SA_DQ<0>")
	)
	(segment
		(start 48.855376 -196.379592)
		(end 49.018444 -196.216524)
		(width 0.14478)
		(layer "In2.Cu")
		(net "M_C_CPU1_SA_DQ<0>")
	)
	(segment
		(start 91.85402 -225.367088)
		(end 91.862402 -225.371914)
		(width 0.0889)
		(layer "In2.Cu")
		(net "M_C_CPU1_SA_DQ<0>")
	)
	(segment
		(start 50.36185 -196.216524)
		(end 50.524918 -196.379592)
		(width 0.14478)
		(layer "In2.Cu")
		(net "M_C_CPU1_SA_DQ<0>")
	)
	(segment
		(start 82.248248 -221.653862)
		(end 82.248248 -221.92107)
		(width 0.0889)
		(layer "In2.Cu")
		(net "M_C_CPU1_SA_DQ<0>")
	)
	(segment
		(start 77.563726 -213.404704)
		(end 82.526886 -218.367864)
		(width 0.14478)
		(layer "In2.Cu")
		(net "M_C_CPU1_SA_DQ<0>")
	)
	(segment
		(start 49.805336 -196.910452)
		(end 49.968404 -196.747384)
		(width 0.14478)
		(layer "In2.Cu")
		(net "M_C_CPU1_SA_DQ<0>")
	)
	(segment
		(start 83.362292 -223.728788)
		(end 83.394042 -223.747076)
		(width 0.0889)
		(layer "In2.Cu")
		(net "M_C_CPU1_SA_DQ<0>")
	)
	(segment
		(start 56.72582 -196.069204)
		(end 56.888888 -196.232272)
		(width 0.14478)
		(layer "In2.Cu")
		(net "M_C_CPU1_SA_DQ<0>")
	)
	(segment
		(start 87.154004 -225.367088)
		(end 87.162386 -225.371914)
		(width 0.0889)
		(layer "In2.Cu")
		(net "M_C_CPU1_SA_DQ<0>")
	)
	(segment
		(start 85.639656 -225.371914)
		(end 85.648038 -225.367088)
		(width 0.0889)
		(layer "In2.Cu")
		(net "M_C_CPU1_SA_DQ<0>")
	)
	(segment
		(start 86.57971 -225.371914)
		(end 86.588092 -225.367088)
		(width 0.0889)
		(layer "In2.Cu")
		(net "M_C_CPU1_SA_DQ<0>")
	)
	(segment
		(start 44.340018 -197.335394)
		(end 44.76496 -196.910452)
		(width 0.14478)
		(layer "In2.Cu")
		(net "M_C_CPU1_SA_DQ<0>")
	)
	(segment
		(start 49.41189 -196.379592)
		(end 49.41189 -196.747384)
		(width 0.14478)
		(layer "In2.Cu")
		(net "M_C_CPU1_SA_DQ<0>")
	)
	(segment
		(start 46.148752 -196.450966)
		(end 46.31182 -196.614034)
		(width 0.14478)
		(layer "In2.Cu")
		(net "M_C_CPU1_SA_DQ<0>")
	)
	(segment
		(start 50.524918 -196.379592)
		(end 50.524918 -196.747384)
		(width 0.14478)
		(layer "In2.Cu")
		(net "M_C_CPU1_SA_DQ<0>")
	)
	(segment
		(start 58.001916 -196.747384)
		(end 58.164984 -196.910452)
		(width 0.14478)
		(layer "In2.Cu")
		(net "M_C_CPU1_SA_DQ<0>")
	)
	(segment
		(start 82.526886 -218.367864)
		(end 82.526886 -221.210124)
		(width 0.14478)
		(layer "In2.Cu")
		(net "M_C_CPU1_SA_DQ<0>")
	)
	(segment
		(start 73.507346 -208.672684)
		(end 74.538586 -208.672684)
		(width 0.14478)
		(layer "In2.Cu")
		(net "M_C_CPU1_SA_DQ<0>")
	)
	(segment
		(start 49.41189 -196.747384)
		(end 49.574958 -196.910452)
		(width 0.14478)
		(layer "In2.Cu")
		(net "M_C_CPU1_SA_DQ<0>")
	)
	(segment
		(start 56.169306 -196.910452)
		(end 56.332374 -196.747384)
		(width 0.14478)
		(layer "In2.Cu")
		(net "M_C_CPU1_SA_DQ<0>")
	)
	(segment
		(start 56.888888 -196.747384)
		(end 57.051956 -196.910452)
		(width 0.14478)
		(layer "In2.Cu")
		(net "M_C_CPU1_SA_DQ<0>")
	)
	(segment
		(start 44.76496 -196.910452)
		(end 45.592238 -196.910452)
		(width 0.14478)
		(layer "In2.Cu")
		(net "M_C_CPU1_SA_DQ<0>")
	)
	(segment
		(start 61.745114 -196.910452)
		(end 73.507346 -208.672684)
		(width 0.14478)
		(layer "In2.Cu")
		(net "M_C_CPU1_SA_DQ<0>")
	)
	(segment
		(start 94.052644 -225.39325)
		(end 94.074996 -225.309938)
		(width 0.0889)
		(layer "In2.Cu")
		(net "M_C_CPU1_SA_DQ<0>")
	)
	(segment
		(start 45.592238 -196.910452)
		(end 45.755306 -196.747384)
		(width 0.14478)
		(layer "In2.Cu")
		(net "M_C_CPU1_SA_DQ<0>")
	)
	(segment
		(start 49.248822 -196.216524)
		(end 49.41189 -196.379592)
		(width 0.14478)
		(layer "In2.Cu")
		(net "M_C_CPU1_SA_DQ<0>")
	)
	(segment
		(start 45.918374 -196.450966)
		(end 46.148752 -196.450966)
		(width 0.14478)
		(layer "In2.Cu")
		(net "M_C_CPU1_SA_DQ<0>")
	)
	(segment
		(start 57.051956 -196.910452)
		(end 57.282334 -196.910452)
		(width 0.14478)
		(layer "In2.Cu")
		(net "M_C_CPU1_SA_DQ<0>")
	)
	(segment
		(start 50.131472 -196.216524)
		(end 50.36185 -196.216524)
		(width 0.14478)
		(layer "In2.Cu")
		(net "M_C_CPU1_SA_DQ<0>")
	)
	(segment
		(start 83.863942 -224.557082)
		(end 83.903058 -224.579942)
		(width 0.0889)
		(layer "In2.Cu")
		(net "M_C_CPU1_SA_DQ<0>")
	)
	(segment
		(start 49.968404 -196.379592)
		(end 50.131472 -196.216524)
		(width 0.14478)
		(layer "In2.Cu")
		(net "M_C_CPU1_SA_DQ<0>")
	)
	(segment
		(start 46.474888 -196.910452)
		(end 48.692308 -196.910452)
		(width 0.14478)
		(layer "In2.Cu")
		(net "M_C_CPU1_SA_DQ<0>")
	)
	(segment
		(start 49.018444 -196.216524)
		(end 49.248822 -196.216524)
		(width 0.14478)
		(layer "In2.Cu")
		(net "M_C_CPU1_SA_DQ<0>")
	)
	(segment
		(start 82.248248 -221.92107)
		(end 82.454242 -222.127064)
		(width 0.0889)
		(layer "In2.Cu")
		(net "M_C_CPU1_SA_DQ<0>")
	)
	(segment
		(start 57.60847 -196.069204)
		(end 57.838848 -196.069204)
		(width 0.14478)
		(layer "In2.Cu")
		(net "M_C_CPU1_SA_DQ<0>")
	)
	(arc
		(start 90.922348 -225.371914)
		(mid 91.105856 -225.417408)
		(end 91.288108 -225.367088)
		(width 0.0889)
		(layer "In2.Cu")
		(net "M_C_CPU1_SA_DQ<0>")
	)
	(arc
		(start 87.162386 -225.371914)
		(mid 87.345894 -225.417408)
		(end 87.528146 -225.367088)
		(width 0.0889)
		(layer "In2.Cu")
		(net "M_C_CPU1_SA_DQ<0>")
	)
	(arc
		(start 83.67649 -224.234502)
		(mid 83.718039 -224.405924)
		(end 83.833462 -224.539302)
		(width 0.0889)
		(layer "In2.Cu")
		(net "M_C_CPU1_SA_DQ<0>")
	)
	(arc
		(start 82.736436 -222.61449)
		(mid 82.777985 -222.785912)
		(end 82.893408 -222.91929)
		(width 0.0889)
		(layer "In2.Cu")
		(net "M_C_CPU1_SA_DQ<0>")
	)
	(arc
		(start 83.433158 -223.769936)
		(mid 83.611971 -223.972286)
		(end 83.67649 -224.234502)
		(width 0.0889)
		(layer "In2.Cu")
		(net "M_C_CPU1_SA_DQ<0>")
	)
	(arc
		(start 86.21395 -225.367088)
		(mid 86.396201 -225.417438)
		(end 86.57971 -225.371914)
		(width 0.0889)
		(layer "In2.Cu")
		(net "M_C_CPU1_SA_DQ<0>")
	)
	(arc
		(start 92.228162 -225.367088)
		(mid 92.511118 -225.290911)
		(end 92.794074 -225.367088)
		(width 0.0889)
		(layer "In2.Cu")
		(net "M_C_CPU1_SA_DQ<0>")
	)
	(arc
		(start 85.648038 -225.367088)
		(mid 85.930994 -225.290911)
		(end 86.21395 -225.367088)
		(width 0.0889)
		(layer "In2.Cu")
		(net "M_C_CPU1_SA_DQ<0>")
	)
	(arc
		(start 89.408 -225.367088)
		(mid 89.690956 -225.290911)
		(end 89.973912 -225.367088)
		(width 0.0889)
		(layer "In2.Cu")
		(net "M_C_CPU1_SA_DQ<0>")
	)
	(arc
		(start 90.348054 -225.367088)
		(mid 90.63101 -225.290911)
		(end 90.913966 -225.367088)
		(width 0.0889)
		(layer "In2.Cu")
		(net "M_C_CPU1_SA_DQ<0>")
	)
	(arc
		(start 84.334096 -225.367088)
		(mid 84.52104 -225.417343)
		(end 84.707984 -225.367088)
		(width 0.0889)
		(layer "In2.Cu")
		(net "M_C_CPU1_SA_DQ<0>")
	)
	(arc
		(start 92.794074 -225.367088)
		(mid 92.981018 -225.417343)
		(end 93.167962 -225.367088)
		(width 0.0889)
		(layer "In2.Cu")
		(net "M_C_CPU1_SA_DQ<0>")
	)
	(arc
		(start 89.034112 -225.367088)
		(mid 89.221056 -225.417343)
		(end 89.408 -225.367088)
		(width 0.0889)
		(layer "In2.Cu")
		(net "M_C_CPU1_SA_DQ<0>")
	)
	(arc
		(start 84.707984 -225.367088)
		(mid 84.99094 -225.290911)
		(end 85.273896 -225.367088)
		(width 0.0889)
		(layer "In2.Cu")
		(net "M_C_CPU1_SA_DQ<0>")
	)
	(arc
		(start 82.491834 -222.148908)
		(mid 82.671563 -222.351528)
		(end 82.736436 -222.61449)
		(width 0.0889)
		(layer "In2.Cu")
		(net "M_C_CPU1_SA_DQ<0>")
	)
	(arc
		(start 93.167962 -225.367088)
		(mid 93.450918 -225.290911)
		(end 93.733874 -225.367088)
		(width 0.0889)
		(layer "In2.Cu")
		(net "M_C_CPU1_SA_DQ<0>")
	)
	(arc
		(start 87.528146 -225.367088)
		(mid 87.811102 -225.290911)
		(end 88.094058 -225.367088)
		(width 0.0889)
		(layer "In2.Cu")
		(net "M_C_CPU1_SA_DQ<0>")
	)
	(arc
		(start 93.733874 -225.367088)
		(mid 93.890312 -225.416059)
		(end 94.052644 -225.39325)
		(width 0.0889)
		(layer "In2.Cu")
		(net "M_C_CPU1_SA_DQ<0>")
	)
	(arc
		(start 88.4682 -225.367088)
		(mid 88.751156 -225.290911)
		(end 89.034112 -225.367088)
		(width 0.0889)
		(layer "In2.Cu")
		(net "M_C_CPU1_SA_DQ<0>")
	)
	(arc
		(start 89.973912 -225.367088)
		(mid 90.156163 -225.417438)
		(end 90.339672 -225.371914)
		(width 0.0889)
		(layer "In2.Cu")
		(net "M_C_CPU1_SA_DQ<0>")
	)
	(arc
		(start 86.588092 -225.367088)
		(mid 86.871048 -225.290911)
		(end 87.154004 -225.367088)
		(width 0.0889)
		(layer "In2.Cu")
		(net "M_C_CPU1_SA_DQ<0>")
	)
	(arc
		(start 83.206336 -223.424496)
		(mid 83.247591 -223.595467)
		(end 83.362292 -223.728788)
		(width 0.0889)
		(layer "In2.Cu")
		(net "M_C_CPU1_SA_DQ<0>")
	)
	(arc
		(start 91.862402 -225.371914)
		(mid 92.04591 -225.417408)
		(end 92.228162 -225.367088)
		(width 0.0889)
		(layer "In2.Cu")
		(net "M_C_CPU1_SA_DQ<0>")
	)
	(arc
		(start 85.273896 -225.367088)
		(mid 85.456147 -225.417438)
		(end 85.639656 -225.371914)
		(width 0.0889)
		(layer "In2.Cu")
		(net "M_C_CPU1_SA_DQ<0>")
	)
	(arc
		(start 82.963004 -222.95993)
		(mid 83.141817 -223.16228)
		(end 83.206336 -223.424496)
		(width 0.0889)
		(layer "In2.Cu")
		(net "M_C_CPU1_SA_DQ<0>")
	)
	(arc
		(start 88.10244 -225.371914)
		(mid 88.285948 -225.417408)
		(end 88.4682 -225.367088)
		(width 0.0889)
		(layer "In2.Cu")
		(net "M_C_CPU1_SA_DQ<0>")
	)
	(arc
		(start 91.288108 -225.367088)
		(mid 91.571064 -225.290911)
		(end 91.85402 -225.367088)
		(width 0.0889)
		(layer "In2.Cu")
		(net "M_C_CPU1_SA_DQ<0>")
	)
	(arc
		(start 84.14639 -225.044508)
		(mid 84.187645 -225.215479)
		(end 84.302346 -225.3488)
		(width 0.0889)
		(layer "In2.Cu")
		(net "M_C_CPU1_SA_DQ<0>")
	)
	(arc
		(start 83.903058 -224.579942)
		(mid 84.081871 -224.782292)
		(end 84.14639 -225.044508)
		(width 0.0889)
		(layer "In2.Cu")
		(net "M_C_CPU1_SA_DQ<0>")
	)
	(segment
		(start 96.267778 -252.850396)
		(end 95.800926 -252.584458)
		(width 0.10668)
		(layer "F.Cu")
		(net "M_C_CPU1_SA_CS_N<1>")
	)
	(segment
		(start 83.394042 -252.261878)
		(end 83.402424 -252.257052)
		(width 0.0889)
		(layer "In2.Cu")
		(net "M_C_CPU1_SA_CS_N<1>")
	)
	(segment
		(start 91.85402 -252.261878)
		(end 91.862402 -252.257052)
		(width 0.0889)
		(layer "In2.Cu")
		(net "M_C_CPU1_SA_CS_N<1>")
	)
	(segment
		(start 88.094058 -252.261878)
		(end 88.10244 -252.257052)
		(width 0.0889)
		(layer "In2.Cu")
		(net "M_C_CPU1_SA_CS_N<1>")
	)
	(segment
		(start 94.099634 -252.257052)
		(end 94.108016 -252.261878)
		(width 0.0889)
		(layer "In2.Cu")
		(net "M_C_CPU1_SA_CS_N<1>")
	)
	(segment
		(start 40.664892 -247.060212)
		(end 45.146214 -247.060212)
		(width 0.14478)
		(layer "In2.Cu")
		(net "M_C_CPU1_SA_CS_N<1>")
	)
	(segment
		(start 87.154004 -252.261878)
		(end 87.162386 -252.257052)
		(width 0.0889)
		(layer "In2.Cu")
		(net "M_C_CPU1_SA_CS_N<1>")
	)
	(segment
		(start 45.146214 -247.060212)
		(end 46.846236 -248.760234)
		(width 0.14478)
		(layer "In2.Cu")
		(net "M_C_CPU1_SA_CS_N<1>")
	)
	(segment
		(start 72.859646 -251.304044)
		(end 74.010266 -252.454664)
		(width 0.14478)
		(layer "In2.Cu")
		(net "M_C_CPU1_SA_CS_N<1>")
	)
	(segment
		(start 95.647002 -252.319028)
		(end 95.800926 -252.584458)
		(width 0.0889)
		(layer "In2.Cu")
		(net "M_C_CPU1_SA_CS_N<1>")
	)
	(segment
		(start 60.405518 -248.760234)
		(end 63.614554 -251.96927)
		(width 0.14478)
		(layer "In2.Cu")
		(net "M_C_CPU1_SA_CS_N<1>")
	)
	(segment
		(start 86.57971 -252.257052)
		(end 86.588092 -252.261878)
		(width 0.0889)
		(layer "In2.Cu")
		(net "M_C_CPU1_SA_CS_N<1>")
	)
	(segment
		(start 77.655674 -252.32106)
		(end 77.757782 -252.261878)
		(width 0.0889)
		(layer "In2.Cu")
		(net "M_C_CPU1_SA_CS_N<1>")
	)
	(segment
		(start 68.007992 -251.304044)
		(end 72.859646 -251.304044)
		(width 0.14478)
		(layer "In2.Cu")
		(net "M_C_CPU1_SA_CS_N<1>")
	)
	(segment
		(start 79.63535 -252.262132)
		(end 79.658718 -252.24867)
		(width 0.0889)
		(layer "In2.Cu")
		(net "M_C_CPU1_SA_CS_N<1>")
	)
	(segment
		(start 79.609188 -252.277118)
		(end 79.63535 -252.262132)
		(width 0.0889)
		(layer "In2.Cu")
		(net "M_C_CPU1_SA_CS_N<1>")
	)
	(segment
		(start 78.106778 -252.24867)
		(end 78.130146 -252.262132)
		(width 0.0889)
		(layer "In2.Cu")
		(net "M_C_CPU1_SA_CS_N<1>")
	)
	(segment
		(start 95.55099 -252.293628)
		(end 95.647002 -252.319028)
		(width 0.0889)
		(layer "In2.Cu")
		(net "M_C_CPU1_SA_CS_N<1>")
	)
	(segment
		(start 76.557886 -252.454664)
		(end 77.158596 -252.454664)
		(width 0.0889)
		(layer "In2.Cu")
		(net "M_C_CPU1_SA_CS_N<1>")
	)
	(segment
		(start 82.453988 -252.261878)
		(end 82.46237 -252.257052)
		(width 0.0889)
		(layer "In2.Cu")
		(net "M_C_CPU1_SA_CS_N<1>")
	)
	(segment
		(start 46.846236 -248.760234)
		(end 60.405518 -248.760234)
		(width 0.14478)
		(layer "In2.Cu")
		(net "M_C_CPU1_SA_CS_N<1>")
	)
	(segment
		(start 95.039688 -252.257052)
		(end 95.04807 -252.261878)
		(width 0.0889)
		(layer "In2.Cu")
		(net "M_C_CPU1_SA_CS_N<1>")
	)
	(segment
		(start 85.639656 -252.257052)
		(end 85.648038 -252.261878)
		(width 0.0889)
		(layer "In2.Cu")
		(net "M_C_CPU1_SA_CS_N<1>")
	)
	(segment
		(start 81.879694 -252.257052)
		(end 81.888076 -252.261878)
		(width 0.0889)
		(layer "In2.Cu")
		(net "M_C_CPU1_SA_CS_N<1>")
	)
	(segment
		(start 79.050896 -252.24994)
		(end 79.07147 -252.261878)
		(width 0.0889)
		(layer "In2.Cu")
		(net "M_C_CPU1_SA_CS_N<1>")
	)
	(segment
		(start 74.010266 -252.454664)
		(end 76.557886 -252.454664)
		(width 0.14478)
		(layer "In2.Cu")
		(net "M_C_CPU1_SA_CS_N<1>")
	)
	(segment
		(start 90.339672 -252.257052)
		(end 90.348054 -252.261878)
		(width 0.0889)
		(layer "In2.Cu")
		(net "M_C_CPU1_SA_CS_N<1>")
	)
	(segment
		(start 63.614554 -251.96927)
		(end 66.40195 -251.96927)
		(width 0.14478)
		(layer "In2.Cu")
		(net "M_C_CPU1_SA_CS_N<1>")
	)
	(segment
		(start 66.40195 -251.96927)
		(end 68.007992 -251.304044)
		(width 0.14478)
		(layer "In2.Cu")
		(net "M_C_CPU1_SA_CS_N<1>")
	)
	(segment
		(start 90.913966 -252.261878)
		(end 90.922348 -252.257052)
		(width 0.0889)
		(layer "In2.Cu")
		(net "M_C_CPU1_SA_CS_N<1>")
	)
	(segment
		(start 40.23995 -246.63527)
		(end 40.664892 -247.060212)
		(width 0.14478)
		(layer "In2.Cu")
		(net "M_C_CPU1_SA_CS_N<1>")
	)
	(segment
		(start 78.130146 -252.262132)
		(end 78.169516 -252.284992)
		(width 0.0889)
		(layer "In2.Cu")
		(net "M_C_CPU1_SA_CS_N<1>")
	)
	(arc
		(start 95.04807 -252.261878)
		(mid 95.295783 -252.337098)
		(end 95.55099 -252.293628)
		(width 0.0889)
		(layer "In2.Cu")
		(net "M_C_CPU1_SA_CS_N<1>")
	)
	(arc
		(start 84.707984 -252.261878)
		(mid 84.99094 -252.338055)
		(end 85.273896 -252.261878)
		(width 0.0889)
		(layer "In2.Cu")
		(net "M_C_CPU1_SA_CS_N<1>")
	)
	(arc
		(start 91.288108 -252.261878)
		(mid 91.571064 -252.338055)
		(end 91.85402 -252.261878)
		(width 0.0889)
		(layer "In2.Cu")
		(net "M_C_CPU1_SA_CS_N<1>")
	)
	(arc
		(start 80.574134 -252.261878)
		(mid 80.761078 -252.211623)
		(end 80.948022 -252.261878)
		(width 0.0889)
		(layer "In2.Cu")
		(net "M_C_CPU1_SA_CS_N<1>")
	)
	(arc
		(start 81.513934 -252.261878)
		(mid 81.696185 -252.211528)
		(end 81.879694 -252.257052)
		(width 0.0889)
		(layer "In2.Cu")
		(net "M_C_CPU1_SA_CS_N<1>")
	)
	(arc
		(start 90.922348 -252.257052)
		(mid 91.105856 -252.211558)
		(end 91.288108 -252.261878)
		(width 0.0889)
		(layer "In2.Cu")
		(net "M_C_CPU1_SA_CS_N<1>")
	)
	(arc
		(start 77.158596 -252.454664)
		(mid 77.415949 -252.420669)
		(end 77.655674 -252.32106)
		(width 0.0889)
		(layer "In2.Cu")
		(net "M_C_CPU1_SA_CS_N<1>")
	)
	(arc
		(start 91.862402 -252.257052)
		(mid 92.04591 -252.211558)
		(end 92.228162 -252.261878)
		(width 0.0889)
		(layer "In2.Cu")
		(net "M_C_CPU1_SA_CS_N<1>")
	)
	(arc
		(start 89.034112 -252.261878)
		(mid 89.221056 -252.211623)
		(end 89.408 -252.261878)
		(width 0.0889)
		(layer "In2.Cu")
		(net "M_C_CPU1_SA_CS_N<1>")
	)
	(arc
		(start 80.948022 -252.261878)
		(mid 81.230978 -252.338055)
		(end 81.513934 -252.261878)
		(width 0.0889)
		(layer "In2.Cu")
		(net "M_C_CPU1_SA_CS_N<1>")
	)
	(arc
		(start 86.21395 -252.261878)
		(mid 86.396201 -252.211528)
		(end 86.57971 -252.257052)
		(width 0.0889)
		(layer "In2.Cu")
		(net "M_C_CPU1_SA_CS_N<1>")
	)
	(arc
		(start 87.162386 -252.257052)
		(mid 87.345894 -252.211558)
		(end 87.528146 -252.261878)
		(width 0.0889)
		(layer "In2.Cu")
		(net "M_C_CPU1_SA_CS_N<1>")
	)
	(arc
		(start 78.696058 -252.261878)
		(mid 78.871968 -252.211068)
		(end 79.050896 -252.24994)
		(width 0.0889)
		(layer "In2.Cu")
		(net "M_C_CPU1_SA_CS_N<1>")
	)
	(arc
		(start 92.228162 -252.261878)
		(mid 92.511118 -252.338055)
		(end 92.794074 -252.261878)
		(width 0.0889)
		(layer "In2.Cu")
		(net "M_C_CPU1_SA_CS_N<1>")
	)
	(arc
		(start 88.10244 -252.257052)
		(mid 88.285948 -252.211558)
		(end 88.4682 -252.261878)
		(width 0.0889)
		(layer "In2.Cu")
		(net "M_C_CPU1_SA_CS_N<1>")
	)
	(arc
		(start 84.334096 -252.261878)
		(mid 84.52104 -252.211623)
		(end 84.707984 -252.261878)
		(width 0.0889)
		(layer "In2.Cu")
		(net "M_C_CPU1_SA_CS_N<1>")
	)
	(arc
		(start 80.008222 -252.261878)
		(mid 80.291178 -252.338055)
		(end 80.574134 -252.261878)
		(width 0.0889)
		(layer "In2.Cu")
		(net "M_C_CPU1_SA_CS_N<1>")
	)
	(arc
		(start 85.648038 -252.261878)
		(mid 85.930994 -252.338055)
		(end 86.21395 -252.261878)
		(width 0.0889)
		(layer "In2.Cu")
		(net "M_C_CPU1_SA_CS_N<1>")
	)
	(arc
		(start 86.588092 -252.261878)
		(mid 86.871048 -252.338055)
		(end 87.154004 -252.261878)
		(width 0.0889)
		(layer "In2.Cu")
		(net "M_C_CPU1_SA_CS_N<1>")
	)
	(arc
		(start 82.46237 -252.257052)
		(mid 82.645878 -252.211558)
		(end 82.82813 -252.261878)
		(width 0.0889)
		(layer "In2.Cu")
		(net "M_C_CPU1_SA_CS_N<1>")
	)
	(arc
		(start 77.757782 -252.261878)
		(mid 77.930637 -252.211889)
		(end 78.106778 -252.24867)
		(width 0.0889)
		(layer "In2.Cu")
		(net "M_C_CPU1_SA_CS_N<1>")
	)
	(arc
		(start 81.888076 -252.261878)
		(mid 82.171032 -252.338055)
		(end 82.453988 -252.261878)
		(width 0.0889)
		(layer "In2.Cu")
		(net "M_C_CPU1_SA_CS_N<1>")
	)
	(arc
		(start 83.402424 -252.257052)
		(mid 83.585932 -252.211558)
		(end 83.768184 -252.261878)
		(width 0.0889)
		(layer "In2.Cu")
		(net "M_C_CPU1_SA_CS_N<1>")
	)
	(arc
		(start 92.794074 -252.261878)
		(mid 92.981018 -252.211623)
		(end 93.167962 -252.261878)
		(width 0.0889)
		(layer "In2.Cu")
		(net "M_C_CPU1_SA_CS_N<1>")
	)
	(arc
		(start 79.07147 -252.261878)
		(mid 79.3384 -252.337827)
		(end 79.609188 -252.277118)
		(width 0.0889)
		(layer "In2.Cu")
		(net "M_C_CPU1_SA_CS_N<1>")
	)
	(arc
		(start 89.408 -252.261878)
		(mid 89.690956 -252.338055)
		(end 89.973912 -252.261878)
		(width 0.0889)
		(layer "In2.Cu")
		(net "M_C_CPU1_SA_CS_N<1>")
	)
	(arc
		(start 88.4682 -252.261878)
		(mid 88.751156 -252.338055)
		(end 89.034112 -252.261878)
		(width 0.0889)
		(layer "In2.Cu")
		(net "M_C_CPU1_SA_CS_N<1>")
	)
	(arc
		(start 90.348054 -252.261878)
		(mid 90.63101 -252.338055)
		(end 90.913966 -252.261878)
		(width 0.0889)
		(layer "In2.Cu")
		(net "M_C_CPU1_SA_CS_N<1>")
	)
	(arc
		(start 78.169516 -252.284992)
		(mid 78.43564 -252.338598)
		(end 78.696058 -252.261878)
		(width 0.0889)
		(layer "In2.Cu")
		(net "M_C_CPU1_SA_CS_N<1>")
	)
	(arc
		(start 87.528146 -252.261878)
		(mid 87.811102 -252.338055)
		(end 88.094058 -252.261878)
		(width 0.0889)
		(layer "In2.Cu")
		(net "M_C_CPU1_SA_CS_N<1>")
	)
	(arc
		(start 94.673928 -252.261878)
		(mid 94.856179 -252.211528)
		(end 95.039688 -252.257052)
		(width 0.0889)
		(layer "In2.Cu")
		(net "M_C_CPU1_SA_CS_N<1>")
	)
	(arc
		(start 93.167962 -252.261878)
		(mid 93.450918 -252.338055)
		(end 93.733874 -252.261878)
		(width 0.0889)
		(layer "In2.Cu")
		(net "M_C_CPU1_SA_CS_N<1>")
	)
	(arc
		(start 89.973912 -252.261878)
		(mid 90.156163 -252.211528)
		(end 90.339672 -252.257052)
		(width 0.0889)
		(layer "In2.Cu")
		(net "M_C_CPU1_SA_CS_N<1>")
	)
	(arc
		(start 93.733874 -252.261878)
		(mid 93.916125 -252.211528)
		(end 94.099634 -252.257052)
		(width 0.0889)
		(layer "In2.Cu")
		(net "M_C_CPU1_SA_CS_N<1>")
	)
	(arc
		(start 94.108016 -252.261878)
		(mid 94.390972 -252.338055)
		(end 94.673928 -252.261878)
		(width 0.0889)
		(layer "In2.Cu")
		(net "M_C_CPU1_SA_CS_N<1>")
	)
	(arc
		(start 79.658718 -252.24867)
		(mid 79.835113 -252.211767)
		(end 80.008222 -252.261878)
		(width 0.0889)
		(layer "In2.Cu")
		(net "M_C_CPU1_SA_CS_N<1>")
	)
	(arc
		(start 83.768184 -252.261878)
		(mid 84.05114 -252.338055)
		(end 84.334096 -252.261878)
		(width 0.0889)
		(layer "In2.Cu")
		(net "M_C_CPU1_SA_CS_N<1>")
	)
	(arc
		(start 85.273896 -252.261878)
		(mid 85.456147 -252.211528)
		(end 85.639656 -252.257052)
		(width 0.0889)
		(layer "In2.Cu")
		(net "M_C_CPU1_SA_CS_N<1>")
	)
	(arc
		(start 82.82813 -252.261878)
		(mid 83.111086 -252.338055)
		(end 83.394042 -252.261878)
		(width 0.0889)
		(layer "In2.Cu")
		(net "M_C_CPU1_SA_CS_N<1>")
	)
	(segment
		(start 94.857824 -252.04039)
		(end 94.390972 -251.774452)
		(width 0.10668)
		(layer "F.Cu")
		(net "M_C_CPU1_SA_CS_N<0>")
	)
	(segment
		(start 54.04231 -248.301764)
		(end 54.205378 -248.138696)
		(width 0.14478)
		(layer "In2.Cu")
		(net "M_C_CPU1_SA_CS_N<0>")
	)
	(segment
		(start 50.241962 -248.301764)
		(end 50.47234 -248.301764)
		(width 0.14478)
		(layer "In2.Cu")
		(net "M_C_CPU1_SA_CS_N<0>")
	)
	(segment
		(start 66.312288 -251.51969)
		(end 67.930776 -250.849384)
		(width 0.14478)
		(layer "In2.Cu")
		(net "M_C_CPU1_SA_CS_N<0>")
	)
	(segment
		(start 58.250328 -248.131076)
		(end 58.250328 -248.073418)
		(width 0.14478)
		(layer "In2.Cu")
		(net "M_C_CPU1_SA_CS_N<0>")
	)
	(segment
		(start 56.743854 -248.294144)
		(end 56.974232 -248.294144)
		(width 0.14478)
		(layer "In2.Cu")
		(net "M_C_CPU1_SA_CS_N<0>")
	)
	(segment
		(start 79.15783 -251.455428)
		(end 79.163418 -251.452126)
		(width 0.0889)
		(layer "In2.Cu")
		(net "M_C_CPU1_SA_CS_N<0>")
	)
	(segment
		(start 54.205378 -248.073418)
		(end 54.368446 -247.91035)
		(width 0.14478)
		(layer "In2.Cu")
		(net "M_C_CPU1_SA_CS_N<0>")
	)
	(segment
		(start 50.078894 -248.138696)
		(end 50.241962 -248.301764)
		(width 0.14478)
		(layer "In2.Cu")
		(net "M_C_CPU1_SA_CS_N<0>")
	)
	(segment
		(start 57.693814 -248.131076)
		(end 57.856882 -248.294144)
		(width 0.14478)
		(layer "In2.Cu")
		(net "M_C_CPU1_SA_CS_N<0>")
	)
	(segment
		(start 50.47234 -248.301764)
		(end 50.635408 -248.138696)
		(width 0.14478)
		(layer "In2.Cu")
		(net "M_C_CPU1_SA_CS_N<0>")
	)
	(segment
		(start 53.648864 -248.073418)
		(end 53.648864 -248.138696)
		(width 0.14478)
		(layer "In2.Cu")
		(net "M_C_CPU1_SA_CS_N<0>")
	)
	(segment
		(start 63.801244 -251.51969)
		(end 66.312288 -251.51969)
		(width 0.14478)
		(layer "In2.Cu")
		(net "M_C_CPU1_SA_CS_N<0>")
	)
	(segment
		(start 52.535836 -248.073418)
		(end 52.535836 -248.138696)
		(width 0.14478)
		(layer "In2.Cu")
		(net "M_C_CPU1_SA_CS_N<0>")
	)
	(segment
		(start 76.481686 -251.650246)
		(end 76.499466 -251.632466)
		(width 0.0889)
		(layer "In2.Cu")
		(net "M_C_CPU1_SA_CS_N<0>")
	)
	(segment
		(start 52.372768 -247.91035)
		(end 52.535836 -248.073418)
		(width 0.14478)
		(layer "In2.Cu")
		(net "M_C_CPU1_SA_CS_N<0>")
	)
	(segment
		(start 45.056552 -246.206264)
		(end 46.760638 -247.91035)
		(width 0.14478)
		(layer "In2.Cu")
		(net "M_C_CPU1_SA_CS_N<0>")
	)
	(segment
		(start 57.530746 -247.91035)
		(end 57.693814 -248.073418)
		(width 0.14478)
		(layer "In2.Cu")
		(net "M_C_CPU1_SA_CS_N<0>")
	)
	(segment
		(start 92.68968 -251.447046)
		(end 92.698062 -251.451872)
		(width 0.0889)
		(layer "In2.Cu")
		(net "M_C_CPU1_SA_CS_N<0>")
	)
	(segment
		(start 49.359312 -248.301764)
		(end 49.52238 -248.138696)
		(width 0.14478)
		(layer "In2.Cu")
		(net "M_C_CPU1_SA_CS_N<0>")
	)
	(segment
		(start 56.974232 -248.294144)
		(end 57.1373 -248.131076)
		(width 0.14478)
		(layer "In2.Cu")
		(net "M_C_CPU1_SA_CS_N<0>")
	)
	(segment
		(start 94.141036 -251.483622)
		(end 94.237048 -251.509022)
		(width 0.0889)
		(layer "In2.Cu")
		(net "M_C_CPU1_SA_CS_N<0>")
	)
	(segment
		(start 57.300368 -247.91035)
		(end 57.530746 -247.91035)
		(width 0.14478)
		(layer "In2.Cu")
		(net "M_C_CPU1_SA_CS_N<0>")
	)
	(segment
		(start 81.044034 -251.451872)
		(end 81.052416 -251.447046)
		(width 0.0889)
		(layer "In2.Cu")
		(net "M_C_CPU1_SA_CS_N<0>")
	)
	(segment
		(start 49.52238 -248.138696)
		(end 49.52238 -248.073418)
		(width 0.14478)
		(layer "In2.Cu")
		(net "M_C_CPU1_SA_CS_N<0>")
	)
	(segment
		(start 48.965866 -248.073418)
		(end 48.965866 -248.138696)
		(width 0.14478)
		(layer "In2.Cu")
		(net "M_C_CPU1_SA_CS_N<0>")
	)
	(segment
		(start 53.09235 -248.138696)
		(end 53.09235 -248.073418)
		(width 0.14478)
		(layer "In2.Cu")
		(net "M_C_CPU1_SA_CS_N<0>")
	)
	(segment
		(start 52.535836 -248.138696)
		(end 52.698904 -248.301764)
		(width 0.14478)
		(layer "In2.Cu")
		(net "M_C_CPU1_SA_CS_N<0>")
	)
	(segment
		(start 56.580786 -248.073418)
		(end 56.580786 -248.131076)
		(width 0.14478)
		(layer "In2.Cu")
		(net "M_C_CPU1_SA_CS_N<0>")
	)
	(segment
		(start 50.798476 -247.91035)
		(end 52.372768 -247.91035)
		(width 0.14478)
		(layer "In2.Cu")
		(net "M_C_CPU1_SA_CS_N<0>")
	)
	(segment
		(start 49.685448 -247.91035)
		(end 49.915826 -247.91035)
		(width 0.14478)
		(layer "In2.Cu")
		(net "M_C_CPU1_SA_CS_N<0>")
	)
	(segment
		(start 78.58633 -251.445014)
		(end 78.598014 -251.451872)
		(width 0.0889)
		(layer "In2.Cu")
		(net "M_C_CPU1_SA_CS_N<0>")
	)
	(segment
		(start 84.229702 -251.447046)
		(end 84.238084 -251.451872)
		(width 0.0889)
		(layer "In2.Cu")
		(net "M_C_CPU1_SA_CS_N<0>")
	)
	(segment
		(start 50.078894 -248.073418)
		(end 50.078894 -248.138696)
		(width 0.14478)
		(layer "In2.Cu")
		(net "M_C_CPU1_SA_CS_N<0>")
	)
	(segment
		(start 85.74405 -251.451872)
		(end 85.752432 -251.447046)
		(width 0.0889)
		(layer "In2.Cu")
		(net "M_C_CPU1_SA_CS_N<0>")
	)
	(segment
		(start 49.128934 -248.301764)
		(end 49.359312 -248.301764)
		(width 0.14478)
		(layer "In2.Cu")
		(net "M_C_CPU1_SA_CS_N<0>")
	)
	(segment
		(start 49.915826 -247.91035)
		(end 50.078894 -248.073418)
		(width 0.14478)
		(layer "In2.Cu")
		(net "M_C_CPU1_SA_CS_N<0>")
	)
	(segment
		(start 53.485796 -247.91035)
		(end 53.648864 -248.073418)
		(width 0.14478)
		(layer "In2.Cu")
		(net "M_C_CPU1_SA_CS_N<0>")
	)
	(segment
		(start 56.580786 -248.131076)
		(end 56.743854 -248.294144)
		(width 0.14478)
		(layer "In2.Cu")
		(net "M_C_CPU1_SA_CS_N<0>")
	)
	(segment
		(start 46.760638 -247.91035)
		(end 48.802798 -247.91035)
		(width 0.14478)
		(layer "In2.Cu")
		(net "M_C_CPU1_SA_CS_N<0>")
	)
	(segment
		(start 94.237048 -251.509022)
		(end 94.390972 -251.774452)
		(width 0.0889)
		(layer "In2.Cu")
		(net "M_C_CPU1_SA_CS_N<0>")
	)
	(segment
		(start 53.811932 -248.301764)
		(end 54.04231 -248.301764)
		(width 0.14478)
		(layer "In2.Cu")
		(net "M_C_CPU1_SA_CS_N<0>")
	)
	(segment
		(start 58.250328 -248.073418)
		(end 58.413396 -247.91035)
		(width 0.14478)
		(layer "In2.Cu")
		(net "M_C_CPU1_SA_CS_N<0>")
	)
	(segment
		(start 49.52238 -248.073418)
		(end 49.685448 -247.91035)
		(width 0.14478)
		(layer "In2.Cu")
		(net "M_C_CPU1_SA_CS_N<0>")
	)
	(segment
		(start 58.08726 -248.294144)
		(end 58.250328 -248.131076)
		(width 0.14478)
		(layer "In2.Cu")
		(net "M_C_CPU1_SA_CS_N<0>")
	)
	(segment
		(start 80.46974 -251.447046)
		(end 80.478122 -251.451872)
		(width 0.0889)
		(layer "In2.Cu")
		(net "M_C_CPU1_SA_CS_N<0>")
	)
	(segment
		(start 54.205378 -248.138696)
		(end 54.205378 -248.073418)
		(width 0.14478)
		(layer "In2.Cu")
		(net "M_C_CPU1_SA_CS_N<0>")
	)
	(segment
		(start 58.413396 -247.91035)
		(end 60.191904 -247.91035)
		(width 0.14478)
		(layer "In2.Cu")
		(net "M_C_CPU1_SA_CS_N<0>")
	)
	(segment
		(start 54.368446 -247.91035)
		(end 56.417718 -247.91035)
		(width 0.14478)
		(layer "In2.Cu")
		(net "M_C_CPU1_SA_CS_N<0>")
	)
	(segment
		(start 80.089248 -251.460508)
		(end 80.10398 -251.451872)
		(width 0.0889)
		(layer "In2.Cu")
		(net "M_C_CPU1_SA_CS_N<0>")
	)
	(segment
		(start 90.444066 -251.451872)
		(end 90.452448 -251.447046)
		(width 0.0889)
		(layer "In2.Cu")
		(net "M_C_CPU1_SA_CS_N<0>")
	)
	(segment
		(start 84.803996 -251.451872)
		(end 84.812378 -251.447046)
		(width 0.0889)
		(layer "In2.Cu")
		(net "M_C_CPU1_SA_CS_N<0>")
	)
	(segment
		(start 73.048114 -250.849384)
		(end 74.069194 -251.870464)
		(width 0.14478)
		(layer "In2.Cu")
		(net "M_C_CPU1_SA_CS_N<0>")
	)
	(segment
		(start 44.760896 -246.206264)
		(end 45.056552 -246.206264)
		(width 0.14478)
		(layer "In2.Cu")
		(net "M_C_CPU1_SA_CS_N<0>")
	)
	(segment
		(start 76.499466 -251.632466)
		(end 77.852016 -251.632466)
		(width 0.0889)
		(layer "In2.Cu")
		(net "M_C_CPU1_SA_CS_N<0>")
	)
	(segment
		(start 53.09235 -248.073418)
		(end 53.255418 -247.91035)
		(width 0.14478)
		(layer "In2.Cu")
		(net "M_C_CPU1_SA_CS_N<0>")
	)
	(segment
		(start 60.191904 -247.91035)
		(end 63.801244 -251.51969)
		(width 0.14478)
		(layer "In2.Cu")
		(net "M_C_CPU1_SA_CS_N<0>")
	)
	(segment
		(start 67.930776 -250.849384)
		(end 73.048114 -250.849384)
		(width 0.14478)
		(layer "In2.Cu")
		(net "M_C_CPU1_SA_CS_N<0>")
	)
	(segment
		(start 48.802798 -247.91035)
		(end 48.965866 -248.073418)
		(width 0.14478)
		(layer "In2.Cu")
		(net "M_C_CPU1_SA_CS_N<0>")
	)
	(segment
		(start 53.648864 -248.138696)
		(end 53.811932 -248.301764)
		(width 0.14478)
		(layer "In2.Cu")
		(net "M_C_CPU1_SA_CS_N<0>")
	)
	(segment
		(start 89.504012 -251.451872)
		(end 89.512394 -251.447046)
		(width 0.0889)
		(layer "In2.Cu")
		(net "M_C_CPU1_SA_CS_N<0>")
	)
	(segment
		(start 93.263974 -251.451872)
		(end 93.272356 -251.447046)
		(width 0.0889)
		(layer "In2.Cu")
		(net "M_C_CPU1_SA_CS_N<0>")
	)
	(segment
		(start 88.929718 -251.447046)
		(end 88.9381 -251.451872)
		(width 0.0889)
		(layer "In2.Cu")
		(net "M_C_CPU1_SA_CS_N<0>")
	)
	(segment
		(start 57.856882 -248.294144)
		(end 58.08726 -248.294144)
		(width 0.14478)
		(layer "In2.Cu")
		(net "M_C_CPU1_SA_CS_N<0>")
	)
	(segment
		(start 52.698904 -248.301764)
		(end 52.929282 -248.301764)
		(width 0.14478)
		(layer "In2.Cu")
		(net "M_C_CPU1_SA_CS_N<0>")
	)
	(segment
		(start 57.1373 -248.073418)
		(end 57.300368 -247.91035)
		(width 0.14478)
		(layer "In2.Cu")
		(net "M_C_CPU1_SA_CS_N<0>")
	)
	(segment
		(start 74.069194 -251.870464)
		(end 76.261468 -251.870464)
		(width 0.14478)
		(layer "In2.Cu")
		(net "M_C_CPU1_SA_CS_N<0>")
	)
	(segment
		(start 44.340018 -245.785386)
		(end 44.760896 -246.206264)
		(width 0.14478)
		(layer "In2.Cu")
		(net "M_C_CPU1_SA_CS_N<0>")
	)
	(segment
		(start 53.255418 -247.91035)
		(end 53.485796 -247.91035)
		(width 0.14478)
		(layer "In2.Cu")
		(net "M_C_CPU1_SA_CS_N<0>")
	)
	(segment
		(start 76.261468 -251.870464)
		(end 76.481686 -251.650246)
		(width 0.14478)
		(layer "In2.Cu")
		(net "M_C_CPU1_SA_CS_N<0>")
	)
	(segment
		(start 50.635408 -248.073418)
		(end 50.798476 -247.91035)
		(width 0.14478)
		(layer "In2.Cu")
		(net "M_C_CPU1_SA_CS_N<0>")
	)
	(segment
		(start 48.965866 -248.138696)
		(end 49.128934 -248.301764)
		(width 0.14478)
		(layer "In2.Cu")
		(net "M_C_CPU1_SA_CS_N<0>")
	)
	(segment
		(start 56.417718 -247.91035)
		(end 56.580786 -248.073418)
		(width 0.14478)
		(layer "In2.Cu")
		(net "M_C_CPU1_SA_CS_N<0>")
	)
	(segment
		(start 57.1373 -248.131076)
		(end 57.1373 -248.073418)
		(width 0.14478)
		(layer "In2.Cu")
		(net "M_C_CPU1_SA_CS_N<0>")
	)
	(segment
		(start 87.989664 -251.447046)
		(end 87.998046 -251.451872)
		(width 0.0889)
		(layer "In2.Cu")
		(net "M_C_CPU1_SA_CS_N<0>")
	)
	(segment
		(start 57.693814 -248.073418)
		(end 57.693814 -248.131076)
		(width 0.14478)
		(layer "In2.Cu")
		(net "M_C_CPU1_SA_CS_N<0>")
	)
	(segment
		(start 50.635408 -248.138696)
		(end 50.635408 -248.073418)
		(width 0.14478)
		(layer "In2.Cu")
		(net "M_C_CPU1_SA_CS_N<0>")
	)
	(segment
		(start 79.163418 -251.452126)
		(end 79.181706 -251.441712)
		(width 0.0889)
		(layer "In2.Cu")
		(net "M_C_CPU1_SA_CS_N<0>")
	)
	(segment
		(start 83.289648 -251.447046)
		(end 83.29803 -251.451872)
		(width 0.0889)
		(layer "In2.Cu")
		(net "M_C_CPU1_SA_CS_N<0>")
	)
	(segment
		(start 52.929282 -248.301764)
		(end 53.09235 -248.138696)
		(width 0.14478)
		(layer "In2.Cu")
		(net "M_C_CPU1_SA_CS_N<0>")
	)
	(arc
		(start 88.563958 -251.451872)
		(mid 88.746209 -251.401522)
		(end 88.929718 -251.447046)
		(width 0.0889)
		(layer "In2.Cu")
		(net "M_C_CPU1_SA_CS_N<0>")
	)
	(arc
		(start 83.863942 -251.451872)
		(mid 84.046193 -251.401522)
		(end 84.229702 -251.447046)
		(width 0.0889)
		(layer "In2.Cu")
		(net "M_C_CPU1_SA_CS_N<0>")
	)
	(arc
		(start 78.14691 -251.510292)
		(mid 78.183377 -251.478605)
		(end 78.223618 -251.451872)
		(width 0.0889)
		(layer "In2.Cu")
		(net "M_C_CPU1_SA_CS_N<0>")
	)
	(arc
		(start 82.357976 -251.451872)
		(mid 82.640932 -251.528049)
		(end 82.923888 -251.451872)
		(width 0.0889)
		(layer "In2.Cu")
		(net "M_C_CPU1_SA_CS_N<0>")
	)
	(arc
		(start 86.118192 -251.451872)
		(mid 86.401148 -251.528049)
		(end 86.684104 -251.451872)
		(width 0.0889)
		(layer "In2.Cu")
		(net "M_C_CPU1_SA_CS_N<0>")
	)
	(arc
		(start 92.698062 -251.451872)
		(mid 92.981018 -251.528049)
		(end 93.263974 -251.451872)
		(width 0.0889)
		(layer "In2.Cu")
		(net "M_C_CPU1_SA_CS_N<0>")
	)
	(arc
		(start 85.178138 -251.451872)
		(mid 85.461094 -251.528049)
		(end 85.74405 -251.451872)
		(width 0.0889)
		(layer "In2.Cu")
		(net "M_C_CPU1_SA_CS_N<0>")
	)
	(arc
		(start 81.984088 -251.451872)
		(mid 82.171032 -251.401617)
		(end 82.357976 -251.451872)
		(width 0.0889)
		(layer "In2.Cu")
		(net "M_C_CPU1_SA_CS_N<0>")
	)
	(arc
		(start 80.10398 -251.451872)
		(mid 80.286231 -251.401522)
		(end 80.46974 -251.447046)
		(width 0.0889)
		(layer "In2.Cu")
		(net "M_C_CPU1_SA_CS_N<0>")
	)
	(arc
		(start 77.852016 -251.632466)
		(mid 78.011621 -251.600719)
		(end 78.14691 -251.510292)
		(width 0.0889)
		(layer "In2.Cu")
		(net "M_C_CPU1_SA_CS_N<0>")
	)
	(arc
		(start 89.878154 -251.451872)
		(mid 90.16111 -251.528049)
		(end 90.444066 -251.451872)
		(width 0.0889)
		(layer "In2.Cu")
		(net "M_C_CPU1_SA_CS_N<0>")
	)
	(arc
		(start 87.057992 -251.451872)
		(mid 87.340948 -251.528049)
		(end 87.623904 -251.451872)
		(width 0.0889)
		(layer "In2.Cu")
		(net "M_C_CPU1_SA_CS_N<0>")
	)
	(arc
		(start 88.9381 -251.451872)
		(mid 89.221056 -251.528049)
		(end 89.504012 -251.451872)
		(width 0.0889)
		(layer "In2.Cu")
		(net "M_C_CPU1_SA_CS_N<0>")
	)
	(arc
		(start 78.598014 -251.451872)
		(mid 78.877442 -251.528038)
		(end 79.15783 -251.455428)
		(width 0.0889)
		(layer "In2.Cu")
		(net "M_C_CPU1_SA_CS_N<0>")
	)
	(arc
		(start 80.478122 -251.451872)
		(mid 80.761078 -251.528049)
		(end 81.044034 -251.451872)
		(width 0.0889)
		(layer "In2.Cu")
		(net "M_C_CPU1_SA_CS_N<0>")
	)
	(arc
		(start 86.684104 -251.451872)
		(mid 86.871048 -251.401617)
		(end 87.057992 -251.451872)
		(width 0.0889)
		(layer "In2.Cu")
		(net "M_C_CPU1_SA_CS_N<0>")
	)
	(arc
		(start 87.998046 -251.451872)
		(mid 88.281002 -251.528049)
		(end 88.563958 -251.451872)
		(width 0.0889)
		(layer "In2.Cu")
		(net "M_C_CPU1_SA_CS_N<0>")
	)
	(arc
		(start 93.272356 -251.447046)
		(mid 93.455864 -251.401552)
		(end 93.638116 -251.451872)
		(width 0.0889)
		(layer "In2.Cu")
		(net "M_C_CPU1_SA_CS_N<0>")
	)
	(arc
		(start 89.512394 -251.447046)
		(mid 89.695902 -251.401552)
		(end 89.878154 -251.451872)
		(width 0.0889)
		(layer "In2.Cu")
		(net "M_C_CPU1_SA_CS_N<0>")
	)
	(arc
		(start 91.758008 -251.451872)
		(mid 92.040964 -251.528049)
		(end 92.32392 -251.451872)
		(width 0.0889)
		(layer "In2.Cu")
		(net "M_C_CPU1_SA_CS_N<0>")
	)
	(arc
		(start 81.052416 -251.447046)
		(mid 81.235924 -251.401552)
		(end 81.418176 -251.451872)
		(width 0.0889)
		(layer "In2.Cu")
		(net "M_C_CPU1_SA_CS_N<0>")
	)
	(arc
		(start 84.238084 -251.451872)
		(mid 84.52104 -251.528049)
		(end 84.803996 -251.451872)
		(width 0.0889)
		(layer "In2.Cu")
		(net "M_C_CPU1_SA_CS_N<0>")
	)
	(arc
		(start 90.818208 -251.451872)
		(mid 91.101164 -251.528049)
		(end 91.38412 -251.451872)
		(width 0.0889)
		(layer "In2.Cu")
		(net "M_C_CPU1_SA_CS_N<0>")
	)
	(arc
		(start 79.181706 -251.441712)
		(mid 79.360935 -251.401559)
		(end 79.53756 -251.451872)
		(width 0.0889)
		(layer "In2.Cu")
		(net "M_C_CPU1_SA_CS_N<0>")
	)
	(arc
		(start 82.923888 -251.451872)
		(mid 83.106139 -251.401522)
		(end 83.289648 -251.447046)
		(width 0.0889)
		(layer "In2.Cu")
		(net "M_C_CPU1_SA_CS_N<0>")
	)
	(arc
		(start 87.623904 -251.451872)
		(mid 87.806155 -251.401522)
		(end 87.989664 -251.447046)
		(width 0.0889)
		(layer "In2.Cu")
		(net "M_C_CPU1_SA_CS_N<0>")
	)
	(arc
		(start 93.638116 -251.451872)
		(mid 93.885829 -251.527092)
		(end 94.141036 -251.483622)
		(width 0.0889)
		(layer "In2.Cu")
		(net "M_C_CPU1_SA_CS_N<0>")
	)
	(arc
		(start 85.752432 -251.447046)
		(mid 85.93594 -251.401552)
		(end 86.118192 -251.451872)
		(width 0.0889)
		(layer "In2.Cu")
		(net "M_C_CPU1_SA_CS_N<0>")
	)
	(arc
		(start 84.812378 -251.447046)
		(mid 84.995886 -251.401552)
		(end 85.178138 -251.451872)
		(width 0.0889)
		(layer "In2.Cu")
		(net "M_C_CPU1_SA_CS_N<0>")
	)
	(arc
		(start 81.418176 -251.451872)
		(mid 81.701132 -251.528049)
		(end 81.984088 -251.451872)
		(width 0.0889)
		(layer "In2.Cu")
		(net "M_C_CPU1_SA_CS_N<0>")
	)
	(arc
		(start 91.38412 -251.451872)
		(mid 91.571064 -251.401617)
		(end 91.758008 -251.451872)
		(width 0.0889)
		(layer "In2.Cu")
		(net "M_C_CPU1_SA_CS_N<0>")
	)
	(arc
		(start 79.53756 -251.451872)
		(mid 79.812266 -251.528236)
		(end 80.089248 -251.460508)
		(width 0.0889)
		(layer "In2.Cu")
		(net "M_C_CPU1_SA_CS_N<0>")
	)
	(arc
		(start 83.29803 -251.451872)
		(mid 83.580986 -251.528049)
		(end 83.863942 -251.451872)
		(width 0.0889)
		(layer "In2.Cu")
		(net "M_C_CPU1_SA_CS_N<0>")
	)
	(arc
		(start 90.452448 -251.447046)
		(mid 90.635956 -251.401552)
		(end 90.818208 -251.451872)
		(width 0.0889)
		(layer "In2.Cu")
		(net "M_C_CPU1_SA_CS_N<0>")
	)
	(arc
		(start 78.223618 -251.451872)
		(mid 78.404076 -251.401428)
		(end 78.58633 -251.445014)
		(width 0.0889)
		(layer "In2.Cu")
		(net "M_C_CPU1_SA_CS_N<0>")
	)
	(arc
		(start 92.32392 -251.451872)
		(mid 92.506171 -251.401522)
		(end 92.68968 -251.447046)
		(width 0.0889)
		(layer "In2.Cu")
		(net "M_C_CPU1_SA_CS_N<0>")
	)
	(segment
		(start 96.267778 -249.610372)
		(end 95.800926 -249.344434)
		(width 0.10668)
		(layer "F.Cu")
		(net "M_C_CPU1_SA_CB<7>")
	)
	(segment
		(start 60.479178 -243.670074)
		(end 61.41339 -244.604286)
		(width 0.14478)
		(layer "In2.Cu")
		(net "M_C_CPU1_SA_CB<7>")
	)
	(segment
		(start 79.050896 -249.009916)
		(end 79.07147 -249.021854)
		(width 0.0889)
		(layer "In2.Cu")
		(net "M_C_CPU1_SA_CB<7>")
	)
	(segment
		(start 40.23995 -243.235226)
		(end 40.665146 -243.660422)
		(width 0.14478)
		(layer "In2.Cu")
		(net "M_C_CPU1_SA_CB<7>")
	)
	(segment
		(start 90.339672 -249.017028)
		(end 90.348054 -249.021854)
		(width 0.0889)
		(layer "In2.Cu")
		(net "M_C_CPU1_SA_CB<7>")
	)
	(segment
		(start 83.394042 -249.021854)
		(end 83.402424 -249.017028)
		(width 0.0889)
		(layer "In2.Cu")
		(net "M_C_CPU1_SA_CB<7>")
	)
	(segment
		(start 43.076368 -243.660422)
		(end 49.428146 -243.660422)
		(width 0.14478)
		(layer "In2.Cu")
		(net "M_C_CPU1_SA_CB<7>")
	)
	(segment
		(start 42.9133 -243.103654)
		(end 42.9133 -243.497354)
		(width 0.14478)
		(layer "In2.Cu")
		(net "M_C_CPU1_SA_CB<7>")
	)
	(segment
		(start 95.039688 -249.017028)
		(end 95.04807 -249.021854)
		(width 0.0889)
		(layer "In2.Cu")
		(net "M_C_CPU1_SA_CB<7>")
	)
	(segment
		(start 42.750232 -242.940586)
		(end 42.9133 -243.103654)
		(width 0.14478)
		(layer "In2.Cu")
		(net "M_C_CPU1_SA_CB<7>")
	)
	(segment
		(start 42.356786 -243.497354)
		(end 42.356786 -243.103654)
		(width 0.14478)
		(layer "In2.Cu")
		(net "M_C_CPU1_SA_CB<7>")
	)
	(segment
		(start 42.193718 -243.660422)
		(end 42.356786 -243.497354)
		(width 0.14478)
		(layer "In2.Cu")
		(net "M_C_CPU1_SA_CB<7>")
	)
	(segment
		(start 73.842626 -248.931684)
		(end 74.561446 -249.650504)
		(width 0.14478)
		(layer "In2.Cu")
		(net "M_C_CPU1_SA_CB<7>")
	)
	(segment
		(start 91.85402 -249.021854)
		(end 91.862402 -249.017028)
		(width 0.0889)
		(layer "In2.Cu")
		(net "M_C_CPU1_SA_CB<7>")
	)
	(segment
		(start 88.094058 -249.021854)
		(end 88.10244 -249.017028)
		(width 0.0889)
		(layer "In2.Cu")
		(net "M_C_CPU1_SA_CB<7>")
	)
	(segment
		(start 95.647002 -249.079004)
		(end 95.800926 -249.344434)
		(width 0.0889)
		(layer "In2.Cu")
		(net "M_C_CPU1_SA_CB<7>")
	)
	(segment
		(start 76.623926 -249.241564)
		(end 77.949806 -249.241564)
		(width 0.0889)
		(layer "In2.Cu")
		(net "M_C_CPU1_SA_CB<7>")
	)
	(segment
		(start 85.639656 -249.017028)
		(end 85.648038 -249.021854)
		(width 0.0889)
		(layer "In2.Cu")
		(net "M_C_CPU1_SA_CB<7>")
	)
	(segment
		(start 87.154004 -249.021854)
		(end 87.162386 -249.017028)
		(width 0.0889)
		(layer "In2.Cu")
		(net "M_C_CPU1_SA_CB<7>")
	)
	(segment
		(start 94.099634 -249.017028)
		(end 94.108016 -249.021854)
		(width 0.0889)
		(layer "In2.Cu")
		(net "M_C_CPU1_SA_CB<7>")
	)
	(segment
		(start 75.960986 -249.650504)
		(end 76.214986 -249.650504)
		(width 0.0889)
		(layer "In2.Cu")
		(net "M_C_CPU1_SA_CB<7>")
	)
	(segment
		(start 53.045614 -242.810284)
		(end 53.905404 -243.670074)
		(width 0.14478)
		(layer "In2.Cu")
		(net "M_C_CPU1_SA_CB<7>")
	)
	(segment
		(start 90.913966 -249.021854)
		(end 90.922348 -249.017028)
		(width 0.0889)
		(layer "In2.Cu")
		(net "M_C_CPU1_SA_CB<7>")
	)
	(segment
		(start 42.519854 -242.940586)
		(end 42.750232 -242.940586)
		(width 0.14478)
		(layer "In2.Cu")
		(net "M_C_CPU1_SA_CB<7>")
	)
	(segment
		(start 42.356786 -243.103654)
		(end 42.519854 -242.940586)
		(width 0.14478)
		(layer "In2.Cu")
		(net "M_C_CPU1_SA_CB<7>")
	)
	(segment
		(start 64.932306 -248.931684)
		(end 73.842626 -248.931684)
		(width 0.14478)
		(layer "In2.Cu")
		(net "M_C_CPU1_SA_CB<7>")
	)
	(segment
		(start 53.905404 -243.670074)
		(end 60.479178 -243.670074)
		(width 0.14478)
		(layer "In2.Cu")
		(net "M_C_CPU1_SA_CB<7>")
	)
	(segment
		(start 61.41339 -245.412768)
		(end 64.932306 -248.931684)
		(width 0.14478)
		(layer "In2.Cu")
		(net "M_C_CPU1_SA_CB<7>")
	)
	(segment
		(start 61.41339 -244.604286)
		(end 61.41339 -245.412768)
		(width 0.14478)
		(layer "In2.Cu")
		(net "M_C_CPU1_SA_CB<7>")
	)
	(segment
		(start 42.9133 -243.497354)
		(end 43.076368 -243.660422)
		(width 0.14478)
		(layer "In2.Cu")
		(net "M_C_CPU1_SA_CB<7>")
	)
	(segment
		(start 79.609188 -249.037094)
		(end 79.63535 -249.022108)
		(width 0.0889)
		(layer "In2.Cu")
		(net "M_C_CPU1_SA_CB<7>")
	)
	(segment
		(start 50.278284 -242.810284)
		(end 53.045614 -242.810284)
		(width 0.14478)
		(layer "In2.Cu")
		(net "M_C_CPU1_SA_CB<7>")
	)
	(segment
		(start 86.57971 -249.017028)
		(end 86.588092 -249.021854)
		(width 0.0889)
		(layer "In2.Cu")
		(net "M_C_CPU1_SA_CB<7>")
	)
	(segment
		(start 82.453988 -249.021854)
		(end 82.46237 -249.017028)
		(width 0.0889)
		(layer "In2.Cu")
		(net "M_C_CPU1_SA_CB<7>")
	)
	(segment
		(start 95.55099 -249.053604)
		(end 95.647002 -249.079004)
		(width 0.0889)
		(layer "In2.Cu")
		(net "M_C_CPU1_SA_CB<7>")
	)
	(segment
		(start 79.63535 -249.022108)
		(end 79.658718 -249.008646)
		(width 0.0889)
		(layer "In2.Cu")
		(net "M_C_CPU1_SA_CB<7>")
	)
	(segment
		(start 74.561446 -249.650504)
		(end 75.960986 -249.650504)
		(width 0.14478)
		(layer "In2.Cu")
		(net "M_C_CPU1_SA_CB<7>")
	)
	(segment
		(start 40.665146 -243.660422)
		(end 42.193718 -243.660422)
		(width 0.14478)
		(layer "In2.Cu")
		(net "M_C_CPU1_SA_CB<7>")
	)
	(segment
		(start 49.428146 -243.660422)
		(end 50.278284 -242.810284)
		(width 0.14478)
		(layer "In2.Cu")
		(net "M_C_CPU1_SA_CB<7>")
	)
	(segment
		(start 81.879694 -249.017028)
		(end 81.888076 -249.021854)
		(width 0.0889)
		(layer "In2.Cu")
		(net "M_C_CPU1_SA_CB<7>")
	)
	(segment
		(start 76.214986 -249.650504)
		(end 76.623926 -249.241564)
		(width 0.0889)
		(layer "In2.Cu")
		(net "M_C_CPU1_SA_CB<7>")
	)
	(segment
		(start 78.63967 -249.054874)
		(end 78.696058 -249.021854)
		(width 0.0889)
		(layer "In2.Cu")
		(net "M_C_CPU1_SA_CB<7>")
	)
	(arc
		(start 95.04807 -249.021854)
		(mid 95.295783 -249.097074)
		(end 95.55099 -249.053604)
		(width 0.0889)
		(layer "In2.Cu")
		(net "M_C_CPU1_SA_CB<7>")
	)
	(arc
		(start 86.21395 -249.021854)
		(mid 86.396201 -248.971504)
		(end 86.57971 -249.017028)
		(width 0.0889)
		(layer "In2.Cu")
		(net "M_C_CPU1_SA_CB<7>")
	)
	(arc
		(start 84.334096 -249.021854)
		(mid 84.52104 -248.971599)
		(end 84.707984 -249.021854)
		(width 0.0889)
		(layer "In2.Cu")
		(net "M_C_CPU1_SA_CB<7>")
	)
	(arc
		(start 94.673928 -249.021854)
		(mid 94.856179 -248.971504)
		(end 95.039688 -249.017028)
		(width 0.0889)
		(layer "In2.Cu")
		(net "M_C_CPU1_SA_CB<7>")
	)
	(arc
		(start 88.10244 -249.017028)
		(mid 88.285948 -248.971534)
		(end 88.4682 -249.021854)
		(width 0.0889)
		(layer "In2.Cu")
		(net "M_C_CPU1_SA_CB<7>")
	)
	(arc
		(start 93.733874 -249.021854)
		(mid 93.916125 -248.971504)
		(end 94.099634 -249.017028)
		(width 0.0889)
		(layer "In2.Cu")
		(net "M_C_CPU1_SA_CB<7>")
	)
	(arc
		(start 92.228162 -249.021854)
		(mid 92.511118 -249.098031)
		(end 92.794074 -249.021854)
		(width 0.0889)
		(layer "In2.Cu")
		(net "M_C_CPU1_SA_CB<7>")
	)
	(arc
		(start 80.008222 -249.021854)
		(mid 80.291178 -249.098031)
		(end 80.574134 -249.021854)
		(width 0.0889)
		(layer "In2.Cu")
		(net "M_C_CPU1_SA_CB<7>")
	)
	(arc
		(start 92.794074 -249.021854)
		(mid 92.981018 -248.971599)
		(end 93.167962 -249.021854)
		(width 0.0889)
		(layer "In2.Cu")
		(net "M_C_CPU1_SA_CB<7>")
	)
	(arc
		(start 83.768184 -249.021854)
		(mid 84.05114 -249.098031)
		(end 84.334096 -249.021854)
		(width 0.0889)
		(layer "In2.Cu")
		(net "M_C_CPU1_SA_CB<7>")
	)
	(arc
		(start 90.922348 -249.017028)
		(mid 91.105856 -248.971534)
		(end 91.288108 -249.021854)
		(width 0.0889)
		(layer "In2.Cu")
		(net "M_C_CPU1_SA_CB<7>")
	)
	(arc
		(start 86.588092 -249.021854)
		(mid 86.871048 -249.098031)
		(end 87.154004 -249.021854)
		(width 0.0889)
		(layer "In2.Cu")
		(net "M_C_CPU1_SA_CB<7>")
	)
	(arc
		(start 88.4682 -249.021854)
		(mid 88.751156 -249.098031)
		(end 89.034112 -249.021854)
		(width 0.0889)
		(layer "In2.Cu")
		(net "M_C_CPU1_SA_CB<7>")
	)
	(arc
		(start 82.46237 -249.017028)
		(mid 82.645878 -248.971534)
		(end 82.82813 -249.021854)
		(width 0.0889)
		(layer "In2.Cu")
		(net "M_C_CPU1_SA_CB<7>")
	)
	(arc
		(start 91.862402 -249.017028)
		(mid 92.04591 -248.971534)
		(end 92.228162 -249.021854)
		(width 0.0889)
		(layer "In2.Cu")
		(net "M_C_CPU1_SA_CB<7>")
	)
	(arc
		(start 80.948022 -249.021854)
		(mid 81.230978 -249.098031)
		(end 81.513934 -249.021854)
		(width 0.0889)
		(layer "In2.Cu")
		(net "M_C_CPU1_SA_CB<7>")
	)
	(arc
		(start 77.949806 -249.241564)
		(mid 78.307138 -249.194054)
		(end 78.63967 -249.054874)
		(width 0.0889)
		(layer "In2.Cu")
		(net "M_C_CPU1_SA_CB<7>")
	)
	(arc
		(start 85.648038 -249.021854)
		(mid 85.930994 -249.098031)
		(end 86.21395 -249.021854)
		(width 0.0889)
		(layer "In2.Cu")
		(net "M_C_CPU1_SA_CB<7>")
	)
	(arc
		(start 80.574134 -249.021854)
		(mid 80.761078 -248.971599)
		(end 80.948022 -249.021854)
		(width 0.0889)
		(layer "In2.Cu")
		(net "M_C_CPU1_SA_CB<7>")
	)
	(arc
		(start 90.348054 -249.021854)
		(mid 90.63101 -249.098031)
		(end 90.913966 -249.021854)
		(width 0.0889)
		(layer "In2.Cu")
		(net "M_C_CPU1_SA_CB<7>")
	)
	(arc
		(start 83.402424 -249.017028)
		(mid 83.585932 -248.971534)
		(end 83.768184 -249.021854)
		(width 0.0889)
		(layer "In2.Cu")
		(net "M_C_CPU1_SA_CB<7>")
	)
	(arc
		(start 82.82813 -249.021854)
		(mid 83.111086 -249.098031)
		(end 83.394042 -249.021854)
		(width 0.0889)
		(layer "In2.Cu")
		(net "M_C_CPU1_SA_CB<7>")
	)
	(arc
		(start 89.408 -249.021854)
		(mid 89.690956 -249.098031)
		(end 89.973912 -249.021854)
		(width 0.0889)
		(layer "In2.Cu")
		(net "M_C_CPU1_SA_CB<7>")
	)
	(arc
		(start 81.888076 -249.021854)
		(mid 82.171032 -249.098031)
		(end 82.453988 -249.021854)
		(width 0.0889)
		(layer "In2.Cu")
		(net "M_C_CPU1_SA_CB<7>")
	)
	(arc
		(start 87.162386 -249.017028)
		(mid 87.345894 -248.971534)
		(end 87.528146 -249.021854)
		(width 0.0889)
		(layer "In2.Cu")
		(net "M_C_CPU1_SA_CB<7>")
	)
	(arc
		(start 79.07147 -249.021854)
		(mid 79.3384 -249.097803)
		(end 79.609188 -249.037094)
		(width 0.0889)
		(layer "In2.Cu")
		(net "M_C_CPU1_SA_CB<7>")
	)
	(arc
		(start 87.528146 -249.021854)
		(mid 87.811102 -249.098031)
		(end 88.094058 -249.021854)
		(width 0.0889)
		(layer "In2.Cu")
		(net "M_C_CPU1_SA_CB<7>")
	)
	(arc
		(start 84.707984 -249.021854)
		(mid 84.99094 -249.098031)
		(end 85.273896 -249.021854)
		(width 0.0889)
		(layer "In2.Cu")
		(net "M_C_CPU1_SA_CB<7>")
	)
	(arc
		(start 94.108016 -249.021854)
		(mid 94.390972 -249.098031)
		(end 94.673928 -249.021854)
		(width 0.0889)
		(layer "In2.Cu")
		(net "M_C_CPU1_SA_CB<7>")
	)
	(arc
		(start 85.273896 -249.021854)
		(mid 85.456147 -248.971504)
		(end 85.639656 -249.017028)
		(width 0.0889)
		(layer "In2.Cu")
		(net "M_C_CPU1_SA_CB<7>")
	)
	(arc
		(start 89.034112 -249.021854)
		(mid 89.221056 -248.971599)
		(end 89.408 -249.021854)
		(width 0.0889)
		(layer "In2.Cu")
		(net "M_C_CPU1_SA_CB<7>")
	)
	(arc
		(start 89.973912 -249.021854)
		(mid 90.156163 -248.971504)
		(end 90.339672 -249.017028)
		(width 0.0889)
		(layer "In2.Cu")
		(net "M_C_CPU1_SA_CB<7>")
	)
	(arc
		(start 81.513934 -249.021854)
		(mid 81.696185 -248.971504)
		(end 81.879694 -249.017028)
		(width 0.0889)
		(layer "In2.Cu")
		(net "M_C_CPU1_SA_CB<7>")
	)
	(arc
		(start 78.696058 -249.021854)
		(mid 78.871968 -248.971044)
		(end 79.050896 -249.009916)
		(width 0.0889)
		(layer "In2.Cu")
		(net "M_C_CPU1_SA_CB<7>")
	)
	(arc
		(start 91.288108 -249.021854)
		(mid 91.571064 -249.098031)
		(end 91.85402 -249.021854)
		(width 0.0889)
		(layer "In2.Cu")
		(net "M_C_CPU1_SA_CB<7>")
	)
	(arc
		(start 93.167962 -249.021854)
		(mid 93.450918 -249.098031)
		(end 93.733874 -249.021854)
		(width 0.0889)
		(layer "In2.Cu")
		(net "M_C_CPU1_SA_CB<7>")
	)
	(arc
		(start 79.658718 -249.008646)
		(mid 79.835113 -248.971743)
		(end 80.008222 -249.021854)
		(width 0.0889)
		(layer "In2.Cu")
		(net "M_C_CPU1_SA_CB<7>")
	)
	(segment
		(start 94.857824 -248.800366)
		(end 94.390972 -248.534428)
		(width 0.10668)
		(layer "F.Cu")
		(net "M_C_CPU1_SA_CB<6>")
	)
	(segment
		(start 85.74405 -248.211848)
		(end 85.752432 -248.207022)
		(width 0.0889)
		(layer "In2.Cu")
		(net "M_C_CPU1_SA_CB<6>")
	)
	(segment
		(start 80.089248 -248.220484)
		(end 80.10398 -248.211848)
		(width 0.0889)
		(layer "In2.Cu")
		(net "M_C_CPU1_SA_CB<6>")
	)
	(segment
		(start 62.399926 -244.903244)
		(end 63.899288 -246.402606)
		(width 0.14478)
		(layer "In2.Cu")
		(net "M_C_CPU1_SA_CB<6>")
	)
	(segment
		(start 66.871342 -247.993154)
		(end 74.202036 -247.993154)
		(width 0.14478)
		(layer "In2.Cu")
		(net "M_C_CPU1_SA_CB<6>")
	)
	(segment
		(start 77.744066 -248.683018)
		(end 78.187296 -248.239788)
		(width 0.0889)
		(layer "In2.Cu")
		(net "M_C_CPU1_SA_CB<6>")
	)
	(segment
		(start 78.579472 -248.201688)
		(end 78.59776 -248.212102)
		(width 0.0889)
		(layer "In2.Cu")
		(net "M_C_CPU1_SA_CB<6>")
	)
	(segment
		(start 87.989664 -248.207022)
		(end 87.998046 -248.211848)
		(width 0.0889)
		(layer "In2.Cu")
		(net "M_C_CPU1_SA_CB<6>")
	)
	(segment
		(start 49.62271 -241.9604)
		(end 50.472848 -241.110262)
		(width 0.14478)
		(layer "In2.Cu")
		(net "M_C_CPU1_SA_CB<6>")
	)
	(segment
		(start 40.665146 -241.9604)
		(end 42.501312 -241.9604)
		(width 0.14478)
		(layer "In2.Cu")
		(net "M_C_CPU1_SA_CB<6>")
	)
	(segment
		(start 84.229702 -248.207022)
		(end 84.238084 -248.211848)
		(width 0.0889)
		(layer "In2.Cu")
		(net "M_C_CPU1_SA_CB<6>")
	)
	(segment
		(start 92.68968 -248.207022)
		(end 92.698062 -248.211848)
		(width 0.0889)
		(layer "In2.Cu")
		(net "M_C_CPU1_SA_CB<6>")
	)
	(segment
		(start 42.827448 -240.750344)
		(end 43.057826 -240.750344)
		(width 0.14478)
		(layer "In2.Cu")
		(net "M_C_CPU1_SA_CB<6>")
	)
	(segment
		(start 89.504012 -248.211848)
		(end 89.512394 -248.207022)
		(width 0.0889)
		(layer "In2.Cu")
		(net "M_C_CPU1_SA_CB<6>")
	)
	(segment
		(start 91.749626 -248.207022)
		(end 91.758008 -248.211848)
		(width 0.0889)
		(layer "In2.Cu")
		(net "M_C_CPU1_SA_CB<6>")
	)
	(segment
		(start 81.044034 -248.211848)
		(end 81.052416 -248.207022)
		(width 0.0889)
		(layer "In2.Cu")
		(net "M_C_CPU1_SA_CB<6>")
	)
	(segment
		(start 80.46974 -248.207022)
		(end 80.478122 -248.211848)
		(width 0.0889)
		(layer "In2.Cu")
		(net "M_C_CPU1_SA_CB<6>")
	)
	(segment
		(start 53.111654 -241.110262)
		(end 53.961792 -241.9604)
		(width 0.14478)
		(layer "In2.Cu")
		(net "M_C_CPU1_SA_CB<6>")
	)
	(segment
		(start 88.929718 -248.207022)
		(end 88.9381 -248.211848)
		(width 0.0889)
		(layer "In2.Cu")
		(net "M_C_CPU1_SA_CB<6>")
	)
	(segment
		(start 62.399926 -243.991384)
		(end 62.399926 -244.903244)
		(width 0.14478)
		(layer "In2.Cu")
		(net "M_C_CPU1_SA_CB<6>")
	)
	(segment
		(start 43.057826 -240.750344)
		(end 43.220894 -240.913412)
		(width 0.14478)
		(layer "In2.Cu")
		(net "M_C_CPU1_SA_CB<6>")
	)
	(segment
		(start 63.899288 -246.402606)
		(end 65.280794 -246.402606)
		(width 0.14478)
		(layer "In2.Cu")
		(net "M_C_CPU1_SA_CB<6>")
	)
	(segment
		(start 65.280794 -246.402606)
		(end 66.871342 -247.993154)
		(width 0.14478)
		(layer "In2.Cu")
		(net "M_C_CPU1_SA_CB<6>")
	)
	(segment
		(start 75.938126 -248.720864)
		(end 77.652626 -248.720864)
		(width 0.0889)
		(layer "In2.Cu")
		(net "M_C_CPU1_SA_CB<6>")
	)
	(segment
		(start 43.220894 -240.913412)
		(end 43.220894 -241.797332)
		(width 0.14478)
		(layer "In2.Cu")
		(net "M_C_CPU1_SA_CB<6>")
	)
	(segment
		(start 78.59776 -248.212102)
		(end 78.603348 -248.215404)
		(width 0.0889)
		(layer "In2.Cu")
		(net "M_C_CPU1_SA_CB<6>")
	)
	(segment
		(start 42.501312 -241.9604)
		(end 42.66438 -241.797332)
		(width 0.14478)
		(layer "In2.Cu")
		(net "M_C_CPU1_SA_CB<6>")
	)
	(segment
		(start 40.23995 -241.535204)
		(end 40.665146 -241.9604)
		(width 0.14478)
		(layer "In2.Cu")
		(net "M_C_CPU1_SA_CB<6>")
	)
	(segment
		(start 53.961792 -241.9604)
		(end 60.368942 -241.9604)
		(width 0.14478)
		(layer "In2.Cu")
		(net "M_C_CPU1_SA_CB<6>")
	)
	(segment
		(start 43.383962 -241.9604)
		(end 49.62271 -241.9604)
		(width 0.14478)
		(layer "In2.Cu")
		(net "M_C_CPU1_SA_CB<6>")
	)
	(segment
		(start 60.368942 -241.9604)
		(end 62.399926 -243.991384)
		(width 0.14478)
		(layer "In2.Cu")
		(net "M_C_CPU1_SA_CB<6>")
	)
	(segment
		(start 50.472848 -241.110262)
		(end 53.111654 -241.110262)
		(width 0.14478)
		(layer "In2.Cu")
		(net "M_C_CPU1_SA_CB<6>")
	)
	(segment
		(start 42.66438 -241.797332)
		(end 42.66438 -240.913412)
		(width 0.14478)
		(layer "In2.Cu")
		(net "M_C_CPU1_SA_CB<6>")
	)
	(segment
		(start 94.141036 -248.243598)
		(end 94.237048 -248.268998)
		(width 0.0889)
		(layer "In2.Cu")
		(net "M_C_CPU1_SA_CB<6>")
	)
	(segment
		(start 94.237048 -248.268998)
		(end 94.390972 -248.534428)
		(width 0.0889)
		(layer "In2.Cu")
		(net "M_C_CPU1_SA_CB<6>")
	)
	(segment
		(start 83.289648 -248.207022)
		(end 83.29803 -248.211848)
		(width 0.0889)
		(layer "In2.Cu")
		(net "M_C_CPU1_SA_CB<6>")
	)
	(segment
		(start 93.263974 -248.211848)
		(end 93.272356 -248.207022)
		(width 0.0889)
		(layer "In2.Cu")
		(net "M_C_CPU1_SA_CB<6>")
	)
	(segment
		(start 43.220894 -241.797332)
		(end 43.383962 -241.9604)
		(width 0.14478)
		(layer "In2.Cu")
		(net "M_C_CPU1_SA_CB<6>")
	)
	(segment
		(start 79.163164 -248.211848)
		(end 79.174848 -248.20499)
		(width 0.0889)
		(layer "In2.Cu")
		(net "M_C_CPU1_SA_CB<6>")
	)
	(segment
		(start 74.929746 -248.720864)
		(end 75.938126 -248.720864)
		(width 0.14478)
		(layer "In2.Cu")
		(net "M_C_CPU1_SA_CB<6>")
	)
	(segment
		(start 84.803996 -248.211848)
		(end 84.812378 -248.207022)
		(width 0.0889)
		(layer "In2.Cu")
		(net "M_C_CPU1_SA_CB<6>")
	)
	(segment
		(start 74.202036 -247.993154)
		(end 74.929746 -248.720864)
		(width 0.14478)
		(layer "In2.Cu")
		(net "M_C_CPU1_SA_CB<6>")
	)
	(segment
		(start 42.66438 -240.913412)
		(end 42.827448 -240.750344)
		(width 0.14478)
		(layer "In2.Cu")
		(net "M_C_CPU1_SA_CB<6>")
	)
	(arc
		(start 80.478122 -248.211848)
		(mid 80.761078 -248.288025)
		(end 81.044034 -248.211848)
		(width 0.0889)
		(layer "In2.Cu")
		(net "M_C_CPU1_SA_CB<6>")
	)
	(arc
		(start 89.878154 -248.211848)
		(mid 90.16111 -248.288025)
		(end 90.444066 -248.211848)
		(width 0.0889)
		(layer "In2.Cu")
		(net "M_C_CPU1_SA_CB<6>")
	)
	(arc
		(start 82.357976 -248.211848)
		(mid 82.640932 -248.288025)
		(end 82.923888 -248.211848)
		(width 0.0889)
		(layer "In2.Cu")
		(net "M_C_CPU1_SA_CB<6>")
	)
	(arc
		(start 78.187296 -248.239788)
		(mid 78.20455 -248.224639)
		(end 78.223618 -248.211848)
		(width 0.0889)
		(layer "In2.Cu")
		(net "M_C_CPU1_SA_CB<6>")
	)
	(arc
		(start 86.118192 -248.211848)
		(mid 86.401148 -248.288025)
		(end 86.684104 -248.211848)
		(width 0.0889)
		(layer "In2.Cu")
		(net "M_C_CPU1_SA_CB<6>")
	)
	(arc
		(start 88.9381 -248.211848)
		(mid 89.221056 -248.288025)
		(end 89.504012 -248.211848)
		(width 0.0889)
		(layer "In2.Cu")
		(net "M_C_CPU1_SA_CB<6>")
	)
	(arc
		(start 87.998046 -248.211848)
		(mid 88.281002 -248.288025)
		(end 88.563958 -248.211848)
		(width 0.0889)
		(layer "In2.Cu")
		(net "M_C_CPU1_SA_CB<6>")
	)
	(arc
		(start 92.32392 -248.211848)
		(mid 92.506171 -248.161498)
		(end 92.68968 -248.207022)
		(width 0.0889)
		(layer "In2.Cu")
		(net "M_C_CPU1_SA_CB<6>")
	)
	(arc
		(start 79.174848 -248.20499)
		(mid 79.357103 -248.161337)
		(end 79.53756 -248.211848)
		(width 0.0889)
		(layer "In2.Cu")
		(net "M_C_CPU1_SA_CB<6>")
	)
	(arc
		(start 84.238084 -248.211848)
		(mid 84.52104 -248.288025)
		(end 84.803996 -248.211848)
		(width 0.0889)
		(layer "In2.Cu")
		(net "M_C_CPU1_SA_CB<6>")
	)
	(arc
		(start 93.638116 -248.211848)
		(mid 93.885829 -248.287068)
		(end 94.141036 -248.243598)
		(width 0.0889)
		(layer "In2.Cu")
		(net "M_C_CPU1_SA_CB<6>")
	)
	(arc
		(start 87.057992 -248.211848)
		(mid 87.340948 -248.288025)
		(end 87.623904 -248.211848)
		(width 0.0889)
		(layer "In2.Cu")
		(net "M_C_CPU1_SA_CB<6>")
	)
	(arc
		(start 77.652626 -248.720864)
		(mid 77.702102 -248.711023)
		(end 77.744066 -248.683018)
		(width 0.0889)
		(layer "In2.Cu")
		(net "M_C_CPU1_SA_CB<6>")
	)
	(arc
		(start 93.272356 -248.207022)
		(mid 93.455864 -248.161528)
		(end 93.638116 -248.211848)
		(width 0.0889)
		(layer "In2.Cu")
		(net "M_C_CPU1_SA_CB<6>")
	)
	(arc
		(start 87.623904 -248.211848)
		(mid 87.806155 -248.161498)
		(end 87.989664 -248.207022)
		(width 0.0889)
		(layer "In2.Cu")
		(net "M_C_CPU1_SA_CB<6>")
	)
	(arc
		(start 88.563958 -248.211848)
		(mid 88.746209 -248.161498)
		(end 88.929718 -248.207022)
		(width 0.0889)
		(layer "In2.Cu")
		(net "M_C_CPU1_SA_CB<6>")
	)
	(arc
		(start 92.698062 -248.211848)
		(mid 92.981018 -248.288025)
		(end 93.263974 -248.211848)
		(width 0.0889)
		(layer "In2.Cu")
		(net "M_C_CPU1_SA_CB<6>")
	)
	(arc
		(start 81.418176 -248.211848)
		(mid 81.701132 -248.288025)
		(end 81.984088 -248.211848)
		(width 0.0889)
		(layer "In2.Cu")
		(net "M_C_CPU1_SA_CB<6>")
	)
	(arc
		(start 78.603348 -248.215404)
		(mid 78.883737 -248.288073)
		(end 79.163164 -248.211848)
		(width 0.0889)
		(layer "In2.Cu")
		(net "M_C_CPU1_SA_CB<6>")
	)
	(arc
		(start 81.052416 -248.207022)
		(mid 81.235924 -248.161528)
		(end 81.418176 -248.211848)
		(width 0.0889)
		(layer "In2.Cu")
		(net "M_C_CPU1_SA_CB<6>")
	)
	(arc
		(start 90.444066 -248.211848)
		(mid 90.63101 -248.161593)
		(end 90.817954 -248.211848)
		(width 0.0889)
		(layer "In2.Cu")
		(net "M_C_CPU1_SA_CB<6>")
	)
	(arc
		(start 85.178138 -248.211848)
		(mid 85.461094 -248.288025)
		(end 85.74405 -248.211848)
		(width 0.0889)
		(layer "In2.Cu")
		(net "M_C_CPU1_SA_CB<6>")
	)
	(arc
		(start 85.752432 -248.207022)
		(mid 85.93594 -248.161528)
		(end 86.118192 -248.211848)
		(width 0.0889)
		(layer "In2.Cu")
		(net "M_C_CPU1_SA_CB<6>")
	)
	(arc
		(start 90.817954 -248.211848)
		(mid 91.10091 -248.288025)
		(end 91.383866 -248.211848)
		(width 0.0889)
		(layer "In2.Cu")
		(net "M_C_CPU1_SA_CB<6>")
	)
	(arc
		(start 78.223618 -248.211848)
		(mid 78.400246 -248.161615)
		(end 78.579472 -248.201688)
		(width 0.0889)
		(layer "In2.Cu")
		(net "M_C_CPU1_SA_CB<6>")
	)
	(arc
		(start 86.684104 -248.211848)
		(mid 86.871048 -248.161593)
		(end 87.057992 -248.211848)
		(width 0.0889)
		(layer "In2.Cu")
		(net "M_C_CPU1_SA_CB<6>")
	)
	(arc
		(start 79.53756 -248.211848)
		(mid 79.812266 -248.288212)
		(end 80.089248 -248.220484)
		(width 0.0889)
		(layer "In2.Cu")
		(net "M_C_CPU1_SA_CB<6>")
	)
	(arc
		(start 82.923888 -248.211848)
		(mid 83.106139 -248.161498)
		(end 83.289648 -248.207022)
		(width 0.0889)
		(layer "In2.Cu")
		(net "M_C_CPU1_SA_CB<6>")
	)
	(arc
		(start 80.10398 -248.211848)
		(mid 80.286231 -248.161498)
		(end 80.46974 -248.207022)
		(width 0.0889)
		(layer "In2.Cu")
		(net "M_C_CPU1_SA_CB<6>")
	)
	(arc
		(start 91.383866 -248.211848)
		(mid 91.566117 -248.161498)
		(end 91.749626 -248.207022)
		(width 0.0889)
		(layer "In2.Cu")
		(net "M_C_CPU1_SA_CB<6>")
	)
	(arc
		(start 89.512394 -248.207022)
		(mid 89.695902 -248.161528)
		(end 89.878154 -248.211848)
		(width 0.0889)
		(layer "In2.Cu")
		(net "M_C_CPU1_SA_CB<6>")
	)
	(arc
		(start 81.984088 -248.211848)
		(mid 82.171032 -248.161593)
		(end 82.357976 -248.211848)
		(width 0.0889)
		(layer "In2.Cu")
		(net "M_C_CPU1_SA_CB<6>")
	)
	(arc
		(start 91.758008 -248.211848)
		(mid 92.040964 -248.288025)
		(end 92.32392 -248.211848)
		(width 0.0889)
		(layer "In2.Cu")
		(net "M_C_CPU1_SA_CB<6>")
	)
	(arc
		(start 83.29803 -248.211848)
		(mid 83.580986 -248.288025)
		(end 83.863942 -248.211848)
		(width 0.0889)
		(layer "In2.Cu")
		(net "M_C_CPU1_SA_CB<6>")
	)
	(arc
		(start 83.863942 -248.211848)
		(mid 84.046193 -248.161498)
		(end 84.229702 -248.207022)
		(width 0.0889)
		(layer "In2.Cu")
		(net "M_C_CPU1_SA_CB<6>")
	)
	(arc
		(start 84.812378 -248.207022)
		(mid 84.995886 -248.161528)
		(end 85.178138 -248.211848)
		(width 0.0889)
		(layer "In2.Cu")
		(net "M_C_CPU1_SA_CB<6>")
	)
	(segment
		(start 95.797878 -248.800366)
		(end 95.331026 -248.534428)
		(width 0.10668)
		(layer "F.Cu")
		(net "M_C_CPU1_SA_CB<5>")
	)
	(segment
		(start 61.86297 -245.218712)
		(end 64.198246 -247.553988)
		(width 0.14478)
		(layer "In2.Cu")
		(net "M_C_CPU1_SA_CB<5>")
	)
	(segment
		(start 51.335686 -241.733832)
		(end 51.335686 -241.797332)
		(width 0.14478)
		(layer "In2.Cu")
		(net "M_C_CPU1_SA_CB<5>")
	)
	(segment
		(start 54.426104 -242.419124)
		(end 54.656482 -242.419124)
		(width 0.14478)
		(layer "In2.Cu")
		(net "M_C_CPU1_SA_CB<5>")
	)
	(segment
		(start 56.004714 -242.579652)
		(end 56.167782 -242.416584)
		(width 0.14478)
		(layer "In2.Cu")
		(net "M_C_CPU1_SA_CB<5>")
	)
	(segment
		(start 46.414436 -242.587272)
		(end 46.577504 -242.424204)
		(width 0.14478)
		(layer "In2.Cu")
		(net "M_C_CPU1_SA_CB<5>")
	)
	(segment
		(start 50.277268 -241.9604)
		(end 50.616104 -241.9604)
		(width 0.14478)
		(layer "In2.Cu")
		(net "M_C_CPU1_SA_CB<5>")
	)
	(segment
		(start 60.505848 -242.810284)
		(end 61.86297 -244.167406)
		(width 0.14478)
		(layer "In2.Cu")
		(net "M_C_CPU1_SA_CB<5>")
	)
	(segment
		(start 45.857922 -243.030756)
		(end 46.02099 -243.193824)
		(width 0.14478)
		(layer "In2.Cu")
		(net "M_C_CPU1_SA_CB<5>")
	)
	(segment
		(start 50.779172 -241.733832)
		(end 50.94224 -241.570764)
		(width 0.14478)
		(layer "In2.Cu")
		(net "M_C_CPU1_SA_CB<5>")
	)
	(segment
		(start 79.518256 -248.8692)
		(end 79.5401 -248.856754)
		(width 0.0889)
		(layer "In2.Cu")
		(net "M_C_CPU1_SA_CB<5>")
	)
	(segment
		(start 45.708062 -242.810284)
		(end 45.857922 -242.960144)
		(width 0.14478)
		(layer "In2.Cu")
		(net "M_C_CPU1_SA_CB<5>")
	)
	(segment
		(start 57.389014 -242.810284)
		(end 57.550558 -242.64874)
		(width 0.14478)
		(layer "In2.Cu")
		(net "M_C_CPU1_SA_CB<5>")
	)
	(segment
		(start 84.803996 -248.857008)
		(end 84.812378 -248.861834)
		(width 0.0889)
		(layer "In2.Cu")
		(net "M_C_CPU1_SA_CB<5>")
	)
	(segment
		(start 46.97095 -242.647216)
		(end 47.134018 -242.810284)
		(width 0.14478)
		(layer "In2.Cu")
		(net "M_C_CPU1_SA_CB<5>")
	)
	(segment
		(start 50.779172 -241.797332)
		(end 50.779172 -241.733832)
		(width 0.14478)
		(layer "In2.Cu")
		(net "M_C_CPU1_SA_CB<5>")
	)
	(segment
		(start 54.263036 -242.647216)
		(end 54.263036 -242.582192)
		(width 0.14478)
		(layer "In2.Cu")
		(net "M_C_CPU1_SA_CB<5>")
	)
	(segment
		(start 57.550558 -242.57381)
		(end 57.712102 -242.412266)
		(width 0.14478)
		(layer "In2.Cu")
		(net "M_C_CPU1_SA_CB<5>")
	)
	(segment
		(start 54.81955 -242.647216)
		(end 54.982618 -242.810284)
		(width 0.14478)
		(layer "In2.Cu")
		(net "M_C_CPU1_SA_CB<5>")
	)
	(segment
		(start 48.976026 -242.594892)
		(end 48.976026 -242.647216)
		(width 0.14478)
		(layer "In2.Cu")
		(net "M_C_CPU1_SA_CB<5>")
	)
	(segment
		(start 56.167782 -242.416584)
		(end 56.39816 -242.416584)
		(width 0.14478)
		(layer "In2.Cu")
		(net "M_C_CPU1_SA_CB<5>")
	)
	(segment
		(start 83.289648 -248.861834)
		(end 83.29803 -248.857008)
		(width 0.0889)
		(layer "In2.Cu")
		(net "M_C_CPU1_SA_CB<5>")
	)
	(segment
		(start 56.004714 -242.647216)
		(end 56.004714 -242.579652)
		(width 0.14478)
		(layer "In2.Cu")
		(net "M_C_CPU1_SA_CB<5>")
	)
	(segment
		(start 54.982618 -242.810284)
		(end 55.841646 -242.810284)
		(width 0.14478)
		(layer "In2.Cu")
		(net "M_C_CPU1_SA_CB<5>")
	)
	(segment
		(start 61.86297 -244.167406)
		(end 61.86297 -245.218712)
		(width 0.14478)
		(layer "In2.Cu")
		(net "M_C_CPU1_SA_CB<5>")
	)
	(segment
		(start 58.101992 -242.57381)
		(end 58.101992 -242.64874)
		(width 0.14478)
		(layer "In2.Cu")
		(net "M_C_CPU1_SA_CB<5>")
	)
	(segment
		(start 50.94224 -241.570764)
		(end 51.172618 -241.570764)
		(width 0.14478)
		(layer "In2.Cu")
		(net "M_C_CPU1_SA_CB<5>")
	)
	(segment
		(start 57.712102 -242.412266)
		(end 57.940448 -242.412266)
		(width 0.14478)
		(layer "In2.Cu")
		(net "M_C_CPU1_SA_CB<5>")
	)
	(segment
		(start 46.97095 -242.587272)
		(end 46.97095 -242.647216)
		(width 0.14478)
		(layer "In2.Cu")
		(net "M_C_CPU1_SA_CB<5>")
	)
	(segment
		(start 76.438506 -249.023124)
		(end 78.000606 -249.023124)
		(width 0.0889)
		(layer "In2.Cu")
		(net "M_C_CPU1_SA_CB<5>")
	)
	(segment
		(start 79.5401 -248.856754)
		(end 79.566262 -248.841768)
		(width 0.0889)
		(layer "In2.Cu")
		(net "M_C_CPU1_SA_CB<5>")
	)
	(segment
		(start 53.952648 -242.810284)
		(end 54.099968 -242.810284)
		(width 0.14478)
		(layer "In2.Cu")
		(net "M_C_CPU1_SA_CB<5>")
	)
	(segment
		(start 65.186306 -247.574562)
		(end 64.816482 -247.944132)
		(width 0.14478)
		(layer "In2.Cu")
		(net "M_C_CPU1_SA_CB<5>")
	)
	(segment
		(start 58.263536 -242.810284)
		(end 60.505848 -242.810284)
		(width 0.14478)
		(layer "In2.Cu")
		(net "M_C_CPU1_SA_CB<5>")
	)
	(segment
		(start 84.229702 -248.861834)
		(end 84.238084 -248.857008)
		(width 0.0889)
		(layer "In2.Cu")
		(net "M_C_CPU1_SA_CB<5>")
	)
	(segment
		(start 64.426338 -247.553988)
		(end 64.796162 -247.184418)
		(width 0.14478)
		(layer "In2.Cu")
		(net "M_C_CPU1_SA_CB<5>")
	)
	(segment
		(start 64.816482 -248.172224)
		(end 65.113662 -248.469404)
		(width 0.14478)
		(layer "In2.Cu")
		(net "M_C_CPU1_SA_CB<5>")
	)
	(segment
		(start 52.4256 -241.578384)
		(end 52.655978 -241.578384)
		(width 0.14478)
		(layer "In2.Cu")
		(net "M_C_CPU1_SA_CB<5>")
	)
	(segment
		(start 44.340018 -242.385342)
		(end 44.76496 -242.810284)
		(width 0.14478)
		(layer "In2.Cu")
		(net "M_C_CPU1_SA_CB<5>")
	)
	(segment
		(start 46.02099 -243.193824)
		(end 46.251368 -243.193824)
		(width 0.14478)
		(layer "In2.Cu")
		(net "M_C_CPU1_SA_CB<5>")
	)
	(segment
		(start 49.139094 -242.810284)
		(end 49.427384 -242.810284)
		(width 0.14478)
		(layer "In2.Cu")
		(net "M_C_CPU1_SA_CB<5>")
	)
	(segment
		(start 65.024254 -247.184418)
		(end 65.186306 -247.34647)
		(width 0.14478)
		(layer "In2.Cu")
		(net "M_C_CPU1_SA_CB<5>")
	)
	(segment
		(start 56.561228 -242.579652)
		(end 56.561228 -242.647216)
		(width 0.14478)
		(layer "In2.Cu")
		(net "M_C_CPU1_SA_CB<5>")
	)
	(segment
		(start 65.186306 -247.34647)
		(end 65.186306 -247.574562)
		(width 0.14478)
		(layer "In2.Cu")
		(net "M_C_CPU1_SA_CB<5>")
	)
	(segment
		(start 52.099464 -241.9604)
		(end 52.262532 -241.797332)
		(width 0.14478)
		(layer "In2.Cu")
		(net "M_C_CPU1_SA_CB<5>")
	)
	(segment
		(start 50.616104 -241.9604)
		(end 50.779172 -241.797332)
		(width 0.14478)
		(layer "In2.Cu")
		(net "M_C_CPU1_SA_CB<5>")
	)
	(segment
		(start 95.48495 -248.799858)
		(end 95.331026 -248.534428)
		(width 0.0889)
		(layer "In2.Cu")
		(net "M_C_CPU1_SA_CB<5>")
	)
	(segment
		(start 52.262532 -241.741452)
		(end 52.4256 -241.578384)
		(width 0.14478)
		(layer "In2.Cu")
		(net "M_C_CPU1_SA_CB<5>")
	)
	(segment
		(start 75.930506 -249.180604)
		(end 76.281026 -249.180604)
		(width 0.0889)
		(layer "In2.Cu")
		(net "M_C_CPU1_SA_CB<5>")
	)
	(segment
		(start 56.39816 -242.416584)
		(end 56.561228 -242.579652)
		(width 0.14478)
		(layer "In2.Cu")
		(net "M_C_CPU1_SA_CB<5>")
	)
	(segment
		(start 52.819046 -241.741452)
		(end 52.819046 -241.797332)
		(width 0.14478)
		(layer "In2.Cu")
		(net "M_C_CPU1_SA_CB<5>")
	)
	(segment
		(start 52.819046 -241.797332)
		(end 52.982114 -241.9604)
		(width 0.14478)
		(layer "In2.Cu")
		(net "M_C_CPU1_SA_CB<5>")
	)
	(segment
		(start 78.5876 -248.863866)
		(end 78.599538 -248.857008)
		(width 0.0889)
		(layer "In2.Cu")
		(net "M_C_CPU1_SA_CB<5>")
	)
	(segment
		(start 47.134018 -242.810284)
		(end 48.256444 -242.810284)
		(width 0.14478)
		(layer "In2.Cu")
		(net "M_C_CPU1_SA_CB<5>")
	)
	(segment
		(start 51.172618 -241.570764)
		(end 51.335686 -241.733832)
		(width 0.14478)
		(layer "In2.Cu")
		(net "M_C_CPU1_SA_CB<5>")
	)
	(segment
		(start 89.504012 -248.857008)
		(end 89.512394 -248.861834)
		(width 0.0889)
		(layer "In2.Cu")
		(net "M_C_CPU1_SA_CB<5>")
	)
	(segment
		(start 87.989664 -248.861834)
		(end 87.998046 -248.857008)
		(width 0.0889)
		(layer "In2.Cu")
		(net "M_C_CPU1_SA_CB<5>")
	)
	(segment
		(start 92.68968 -248.861834)
		(end 92.698062 -248.857008)
		(width 0.0889)
		(layer "In2.Cu")
		(net "M_C_CPU1_SA_CB<5>")
	)
	(segment
		(start 52.655978 -241.578384)
		(end 52.819046 -241.741452)
		(width 0.14478)
		(layer "In2.Cu")
		(net "M_C_CPU1_SA_CB<5>")
	)
	(segment
		(start 94.204028 -248.857008)
		(end 94.21241 -248.861834)
		(width 0.0889)
		(layer "In2.Cu")
		(net "M_C_CPU1_SA_CB<5>")
	)
	(segment
		(start 79.138018 -248.839736)
		(end 79.167482 -248.857008)
		(width 0.0889)
		(layer "In2.Cu")
		(net "M_C_CPU1_SA_CB<5>")
	)
	(segment
		(start 54.81955 -242.582192)
		(end 54.81955 -242.647216)
		(width 0.14478)
		(layer "In2.Cu")
		(net "M_C_CPU1_SA_CB<5>")
	)
	(segment
		(start 91.749626 -248.861834)
		(end 91.758008 -248.857008)
		(width 0.0889)
		(layer "In2.Cu")
		(net "M_C_CPU1_SA_CB<5>")
	)
	(segment
		(start 85.74405 -248.857008)
		(end 85.752432 -248.861834)
		(width 0.0889)
		(layer "In2.Cu")
		(net "M_C_CPU1_SA_CB<5>")
	)
	(segment
		(start 64.198246 -247.553988)
		(end 64.426338 -247.553988)
		(width 0.14478)
		(layer "In2.Cu")
		(net "M_C_CPU1_SA_CB<5>")
	)
	(segment
		(start 56.561228 -242.647216)
		(end 56.724296 -242.810284)
		(width 0.14478)
		(layer "In2.Cu")
		(net "M_C_CPU1_SA_CB<5>")
	)
	(segment
		(start 80.46974 -248.861834)
		(end 80.478122 -248.857008)
		(width 0.0889)
		(layer "In2.Cu")
		(net "M_C_CPU1_SA_CB<5>")
	)
	(segment
		(start 81.044034 -248.857008)
		(end 81.052416 -248.861834)
		(width 0.0889)
		(layer "In2.Cu")
		(net "M_C_CPU1_SA_CB<5>")
	)
	(segment
		(start 64.816482 -247.944132)
		(end 64.816482 -248.172224)
		(width 0.14478)
		(layer "In2.Cu")
		(net "M_C_CPU1_SA_CB<5>")
	)
	(segment
		(start 48.812958 -242.431824)
		(end 48.976026 -242.594892)
		(width 0.14478)
		(layer "In2.Cu")
		(net "M_C_CPU1_SA_CB<5>")
	)
	(segment
		(start 51.498754 -241.9604)
		(end 52.099464 -241.9604)
		(width 0.14478)
		(layer "In2.Cu")
		(net "M_C_CPU1_SA_CB<5>")
	)
	(segment
		(start 93.263974 -248.857008)
		(end 93.272356 -248.861834)
		(width 0.0889)
		(layer "In2.Cu")
		(net "M_C_CPU1_SA_CB<5>")
	)
	(segment
		(start 48.58258 -242.431824)
		(end 48.812958 -242.431824)
		(width 0.14478)
		(layer "In2.Cu")
		(net "M_C_CPU1_SA_CB<5>")
	)
	(segment
		(start 45.857922 -242.960144)
		(end 45.857922 -243.030756)
		(width 0.14478)
		(layer "In2.Cu")
		(net "M_C_CPU1_SA_CB<5>")
	)
	(segment
		(start 76.281026 -249.180604)
		(end 76.438506 -249.023124)
		(width 0.0889)
		(layer "In2.Cu")
		(net "M_C_CPU1_SA_CB<5>")
	)
	(segment
		(start 52.982114 -241.9604)
		(end 53.102764 -241.9604)
		(width 0.14478)
		(layer "In2.Cu")
		(net "M_C_CPU1_SA_CB<5>")
	)
	(segment
		(start 46.577504 -242.424204)
		(end 46.807882 -242.424204)
		(width 0.14478)
		(layer "In2.Cu")
		(net "M_C_CPU1_SA_CB<5>")
	)
	(segment
		(start 54.656482 -242.419124)
		(end 54.81955 -242.582192)
		(width 0.14478)
		(layer "In2.Cu")
		(net "M_C_CPU1_SA_CB<5>")
	)
	(segment
		(start 53.102764 -241.9604)
		(end 53.952648 -242.810284)
		(width 0.14478)
		(layer "In2.Cu")
		(net "M_C_CPU1_SA_CB<5>")
	)
	(segment
		(start 48.419512 -242.647216)
		(end 48.419512 -242.594892)
		(width 0.14478)
		(layer "In2.Cu")
		(net "M_C_CPU1_SA_CB<5>")
	)
	(segment
		(start 64.796162 -247.184418)
		(end 65.024254 -247.184418)
		(width 0.14478)
		(layer "In2.Cu")
		(net "M_C_CPU1_SA_CB<5>")
	)
	(segment
		(start 51.335686 -241.797332)
		(end 51.498754 -241.9604)
		(width 0.14478)
		(layer "In2.Cu")
		(net "M_C_CPU1_SA_CB<5>")
	)
	(segment
		(start 48.419512 -242.594892)
		(end 48.58258 -242.431824)
		(width 0.14478)
		(layer "In2.Cu")
		(net "M_C_CPU1_SA_CB<5>")
	)
	(segment
		(start 46.414436 -243.030756)
		(end 46.414436 -242.587272)
		(width 0.14478)
		(layer "In2.Cu")
		(net "M_C_CPU1_SA_CB<5>")
	)
	(segment
		(start 58.101992 -242.64874)
		(end 58.263536 -242.810284)
		(width 0.14478)
		(layer "In2.Cu")
		(net "M_C_CPU1_SA_CB<5>")
	)
	(segment
		(start 49.427384 -242.810284)
		(end 50.277268 -241.9604)
		(width 0.14478)
		(layer "In2.Cu")
		(net "M_C_CPU1_SA_CB<5>")
	)
	(segment
		(start 57.550558 -242.64874)
		(end 57.550558 -242.57381)
		(width 0.14478)
		(layer "In2.Cu")
		(net "M_C_CPU1_SA_CB<5>")
	)
	(segment
		(start 54.099968 -242.810284)
		(end 54.263036 -242.647216)
		(width 0.14478)
		(layer "In2.Cu")
		(net "M_C_CPU1_SA_CB<5>")
	)
	(segment
		(start 48.256444 -242.810284)
		(end 48.419512 -242.647216)
		(width 0.14478)
		(layer "In2.Cu")
		(net "M_C_CPU1_SA_CB<5>")
	)
	(segment
		(start 74.741786 -249.180604)
		(end 75.930506 -249.180604)
		(width 0.14478)
		(layer "In2.Cu")
		(net "M_C_CPU1_SA_CB<5>")
	)
	(segment
		(start 88.929718 -248.861834)
		(end 88.9381 -248.857008)
		(width 0.0889)
		(layer "In2.Cu")
		(net "M_C_CPU1_SA_CB<5>")
	)
	(segment
		(start 65.113662 -248.469404)
		(end 74.030586 -248.469404)
		(width 0.14478)
		(layer "In2.Cu")
		(net "M_C_CPU1_SA_CB<5>")
	)
	(segment
		(start 56.724296 -242.810284)
		(end 57.389014 -242.810284)
		(width 0.14478)
		(layer "In2.Cu")
		(net "M_C_CPU1_SA_CB<5>")
	)
	(segment
		(start 46.251368 -243.193824)
		(end 46.414436 -243.030756)
		(width 0.14478)
		(layer "In2.Cu")
		(net "M_C_CPU1_SA_CB<5>")
	)
	(segment
		(start 95.462598 -248.88317)
		(end 95.48495 -248.799858)
		(width 0.0889)
		(layer "In2.Cu")
		(net "M_C_CPU1_SA_CB<5>")
	)
	(segment
		(start 52.262532 -241.797332)
		(end 52.262532 -241.741452)
		(width 0.14478)
		(layer "In2.Cu")
		(net "M_C_CPU1_SA_CB<5>")
	)
	(segment
		(start 54.263036 -242.582192)
		(end 54.426104 -242.419124)
		(width 0.14478)
		(layer "In2.Cu")
		(net "M_C_CPU1_SA_CB<5>")
	)
	(segment
		(start 44.76496 -242.810284)
		(end 45.708062 -242.810284)
		(width 0.14478)
		(layer "In2.Cu")
		(net "M_C_CPU1_SA_CB<5>")
	)
	(segment
		(start 46.807882 -242.424204)
		(end 46.97095 -242.587272)
		(width 0.14478)
		(layer "In2.Cu")
		(net "M_C_CPU1_SA_CB<5>")
	)
	(segment
		(start 55.841646 -242.810284)
		(end 56.004714 -242.647216)
		(width 0.14478)
		(layer "In2.Cu")
		(net "M_C_CPU1_SA_CB<5>")
	)
	(segment
		(start 57.940448 -242.412266)
		(end 58.101992 -242.57381)
		(width 0.14478)
		(layer "In2.Cu")
		(net "M_C_CPU1_SA_CB<5>")
	)
	(segment
		(start 74.030586 -248.469404)
		(end 74.741786 -249.180604)
		(width 0.14478)
		(layer "In2.Cu")
		(net "M_C_CPU1_SA_CB<5>")
	)
	(segment
		(start 48.976026 -242.647216)
		(end 49.139094 -242.810284)
		(width 0.14478)
		(layer "In2.Cu")
		(net "M_C_CPU1_SA_CB<5>")
	)
	(arc
		(start 89.878154 -248.857008)
		(mid 90.16111 -248.780831)
		(end 90.444066 -248.857008)
		(width 0.0889)
		(layer "In2.Cu")
		(net "M_C_CPU1_SA_CB<5>")
	)
	(arc
		(start 79.566262 -248.841768)
		(mid 79.837048 -248.781122)
		(end 80.10398 -248.857008)
		(width 0.0889)
		(layer "In2.Cu")
		(net "M_C_CPU1_SA_CB<5>")
	)
	(arc
		(start 90.817954 -248.857008)
		(mid 91.10091 -248.780831)
		(end 91.383866 -248.857008)
		(width 0.0889)
		(layer "In2.Cu")
		(net "M_C_CPU1_SA_CB<5>")
	)
	(arc
		(start 78.599538 -248.857008)
		(mid 78.866595 -248.779973)
		(end 79.138018 -248.839736)
		(width 0.0889)
		(layer "In2.Cu")
		(net "M_C_CPU1_SA_CB<5>")
	)
	(arc
		(start 93.272356 -248.861834)
		(mid 93.455864 -248.907328)
		(end 93.638116 -248.857008)
		(width 0.0889)
		(layer "In2.Cu")
		(net "M_C_CPU1_SA_CB<5>")
	)
	(arc
		(start 87.057992 -248.857008)
		(mid 87.340948 -248.780831)
		(end 87.623904 -248.857008)
		(width 0.0889)
		(layer "In2.Cu")
		(net "M_C_CPU1_SA_CB<5>")
	)
	(arc
		(start 90.444066 -248.857008)
		(mid 90.63101 -248.907263)
		(end 90.817954 -248.857008)
		(width 0.0889)
		(layer "In2.Cu")
		(net "M_C_CPU1_SA_CB<5>")
	)
	(arc
		(start 91.758008 -248.857008)
		(mid 92.040964 -248.780831)
		(end 92.32392 -248.857008)
		(width 0.0889)
		(layer "In2.Cu")
		(net "M_C_CPU1_SA_CB<5>")
	)
	(arc
		(start 84.812378 -248.861834)
		(mid 84.995886 -248.907328)
		(end 85.178138 -248.857008)
		(width 0.0889)
		(layer "In2.Cu")
		(net "M_C_CPU1_SA_CB<5>")
	)
	(arc
		(start 80.478122 -248.857008)
		(mid 80.761078 -248.780831)
		(end 81.044034 -248.857008)
		(width 0.0889)
		(layer "In2.Cu")
		(net "M_C_CPU1_SA_CB<5>")
	)
	(arc
		(start 85.752432 -248.861834)
		(mid 85.93594 -248.907328)
		(end 86.118192 -248.857008)
		(width 0.0889)
		(layer "In2.Cu")
		(net "M_C_CPU1_SA_CB<5>")
	)
	(arc
		(start 80.10398 -248.857008)
		(mid 80.286231 -248.907358)
		(end 80.46974 -248.861834)
		(width 0.0889)
		(layer "In2.Cu")
		(net "M_C_CPU1_SA_CB<5>")
	)
	(arc
		(start 81.418176 -248.857008)
		(mid 81.701132 -248.780831)
		(end 81.984088 -248.857008)
		(width 0.0889)
		(layer "In2.Cu")
		(net "M_C_CPU1_SA_CB<5>")
	)
	(arc
		(start 87.623904 -248.857008)
		(mid 87.806155 -248.907358)
		(end 87.989664 -248.861834)
		(width 0.0889)
		(layer "In2.Cu")
		(net "M_C_CPU1_SA_CB<5>")
	)
	(arc
		(start 89.512394 -248.861834)
		(mid 89.695902 -248.907328)
		(end 89.878154 -248.857008)
		(width 0.0889)
		(layer "In2.Cu")
		(net "M_C_CPU1_SA_CB<5>")
	)
	(arc
		(start 86.684104 -248.857008)
		(mid 86.871048 -248.907263)
		(end 87.057992 -248.857008)
		(width 0.0889)
		(layer "In2.Cu")
		(net "M_C_CPU1_SA_CB<5>")
	)
	(arc
		(start 94.21241 -248.861834)
		(mid 94.395918 -248.907328)
		(end 94.57817 -248.857008)
		(width 0.0889)
		(layer "In2.Cu")
		(net "M_C_CPU1_SA_CB<5>")
	)
	(arc
		(start 88.9381 -248.857008)
		(mid 89.221056 -248.780831)
		(end 89.504012 -248.857008)
		(width 0.0889)
		(layer "In2.Cu")
		(net "M_C_CPU1_SA_CB<5>")
	)
	(arc
		(start 81.984088 -248.857008)
		(mid 82.171032 -248.907263)
		(end 82.357976 -248.857008)
		(width 0.0889)
		(layer "In2.Cu")
		(net "M_C_CPU1_SA_CB<5>")
	)
	(arc
		(start 95.144082 -248.857008)
		(mid 95.300401 -248.906003)
		(end 95.462598 -248.88317)
		(width 0.0889)
		(layer "In2.Cu")
		(net "M_C_CPU1_SA_CB<5>")
	)
	(arc
		(start 83.863942 -248.857008)
		(mid 84.046193 -248.907358)
		(end 84.229702 -248.861834)
		(width 0.0889)
		(layer "In2.Cu")
		(net "M_C_CPU1_SA_CB<5>")
	)
	(arc
		(start 84.238084 -248.857008)
		(mid 84.52104 -248.780831)
		(end 84.803996 -248.857008)
		(width 0.0889)
		(layer "In2.Cu")
		(net "M_C_CPU1_SA_CB<5>")
	)
	(arc
		(start 91.383866 -248.857008)
		(mid 91.566117 -248.907358)
		(end 91.749626 -248.861834)
		(width 0.0889)
		(layer "In2.Cu")
		(net "M_C_CPU1_SA_CB<5>")
	)
	(arc
		(start 87.998046 -248.857008)
		(mid 88.281002 -248.780831)
		(end 88.563958 -248.857008)
		(width 0.0889)
		(layer "In2.Cu")
		(net "M_C_CPU1_SA_CB<5>")
	)
	(arc
		(start 94.57817 -248.857008)
		(mid 94.861126 -248.780831)
		(end 95.144082 -248.857008)
		(width 0.0889)
		(layer "In2.Cu")
		(net "M_C_CPU1_SA_CB<5>")
	)
	(arc
		(start 92.698062 -248.857008)
		(mid 92.981018 -248.780831)
		(end 93.263974 -248.857008)
		(width 0.0889)
		(layer "In2.Cu")
		(net "M_C_CPU1_SA_CB<5>")
	)
	(arc
		(start 88.563958 -248.857008)
		(mid 88.746209 -248.907358)
		(end 88.929718 -248.861834)
		(width 0.0889)
		(layer "In2.Cu")
		(net "M_C_CPU1_SA_CB<5>")
	)
	(arc
		(start 79.167482 -248.857008)
		(mid 79.341332 -248.906914)
		(end 79.518256 -248.8692)
		(width 0.0889)
		(layer "In2.Cu")
		(net "M_C_CPU1_SA_CB<5>")
	)
	(arc
		(start 78.000606 -249.023124)
		(mid 78.304704 -248.982569)
		(end 78.5876 -248.863866)
		(width 0.0889)
		(layer "In2.Cu")
		(net "M_C_CPU1_SA_CB<5>")
	)
	(arc
		(start 86.118192 -248.857008)
		(mid 86.401148 -248.780831)
		(end 86.684104 -248.857008)
		(width 0.0889)
		(layer "In2.Cu")
		(net "M_C_CPU1_SA_CB<5>")
	)
	(arc
		(start 83.29803 -248.857008)
		(mid 83.580986 -248.780831)
		(end 83.863942 -248.857008)
		(width 0.0889)
		(layer "In2.Cu")
		(net "M_C_CPU1_SA_CB<5>")
	)
	(arc
		(start 93.638116 -248.857008)
		(mid 93.921072 -248.780831)
		(end 94.204028 -248.857008)
		(width 0.0889)
		(layer "In2.Cu")
		(net "M_C_CPU1_SA_CB<5>")
	)
	(arc
		(start 82.923888 -248.857008)
		(mid 83.106139 -248.907358)
		(end 83.289648 -248.861834)
		(width 0.0889)
		(layer "In2.Cu")
		(net "M_C_CPU1_SA_CB<5>")
	)
	(arc
		(start 82.357976 -248.857008)
		(mid 82.640932 -248.780831)
		(end 82.923888 -248.857008)
		(width 0.0889)
		(layer "In2.Cu")
		(net "M_C_CPU1_SA_CB<5>")
	)
	(arc
		(start 92.32392 -248.857008)
		(mid 92.506171 -248.907358)
		(end 92.68968 -248.861834)
		(width 0.0889)
		(layer "In2.Cu")
		(net "M_C_CPU1_SA_CB<5>")
	)
	(arc
		(start 81.052416 -248.861834)
		(mid 81.235924 -248.907328)
		(end 81.418176 -248.857008)
		(width 0.0889)
		(layer "In2.Cu")
		(net "M_C_CPU1_SA_CB<5>")
	)
	(arc
		(start 85.178138 -248.857008)
		(mid 85.461094 -248.780831)
		(end 85.74405 -248.857008)
		(width 0.0889)
		(layer "In2.Cu")
		(net "M_C_CPU1_SA_CB<5>")
	)
	(segment
		(start 94.387924 -247.99036)
		(end 93.921072 -247.724422)
		(width 0.10668)
		(layer "F.Cu")
		(net "M_C_CPU1_SA_CB<4>")
	)
	(segment
		(start 63.71336 -245.165626)
		(end 64.081406 -244.79758)
		(width 0.14478)
		(layer "In2.Cu")
		(net "M_C_CPU1_SA_CB<4>")
	)
	(segment
		(start 46.289214 -241.484404)
		(end 46.519592 -241.484404)
		(width 0.14478)
		(layer "In2.Cu")
		(net "M_C_CPU1_SA_CB<4>")
	)
	(segment
		(start 85.639656 -248.051828)
		(end 85.648038 -248.047002)
		(width 0.0889)
		(layer "In2.Cu")
		(net "M_C_CPU1_SA_CB<4>")
	)
	(segment
		(start 46.68266 -241.321336)
		(end 46.68266 -241.267996)
		(width 0.14478)
		(layer "In2.Cu")
		(net "M_C_CPU1_SA_CB<4>")
	)
	(segment
		(start 45.605446 -240.560352)
		(end 45.835824 -240.560352)
		(width 0.14478)
		(layer "In2.Cu")
		(net "M_C_CPU1_SA_CB<4>")
	)
	(segment
		(start 63.482728 -245.165626)
		(end 63.71336 -245.165626)
		(width 0.14478)
		(layer "In2.Cu")
		(net "M_C_CPU1_SA_CB<4>")
	)
	(segment
		(start 74.388726 -247.524524)
		(end 75.125326 -248.261124)
		(width 0.14478)
		(layer "In2.Cu")
		(net "M_C_CPU1_SA_CB<4>")
	)
	(segment
		(start 46.68266 -241.267996)
		(end 46.830742 -241.119914)
		(width 0.14478)
		(layer "In2.Cu")
		(net "M_C_CPU1_SA_CB<4>")
	)
	(segment
		(start 63.31966 -245.002558)
		(end 63.482728 -245.165626)
		(width 0.14478)
		(layer "In2.Cu")
		(net "M_C_CPU1_SA_CB<4>")
	)
	(segment
		(start 94.074996 -247.989852)
		(end 93.921072 -247.724422)
		(width 0.0889)
		(layer "In2.Cu")
		(net "M_C_CPU1_SA_CB<4>")
	)
	(segment
		(start 64.10706 -245.559326)
		(end 64.10706 -245.789958)
		(width 0.14478)
		(layer "In2.Cu")
		(net "M_C_CPU1_SA_CB<4>")
	)
	(segment
		(start 46.519592 -241.484404)
		(end 46.68266 -241.321336)
		(width 0.14478)
		(layer "In2.Cu")
		(net "M_C_CPU1_SA_CB<4>")
	)
	(segment
		(start 46.126146 -241.087656)
		(end 46.126146 -241.321336)
		(width 0.14478)
		(layer "In2.Cu")
		(net "M_C_CPU1_SA_CB<4>")
	)
	(segment
		(start 44.340018 -240.68532)
		(end 45.036486 -241.381788)
		(width 0.14478)
		(layer "In2.Cu")
		(net "M_C_CPU1_SA_CB<4>")
	)
	(segment
		(start 56.602376 -241.502184)
		(end 56.832754 -241.502184)
		(width 0.14478)
		(layer "In2.Cu")
		(net "M_C_CPU1_SA_CB<4>")
	)
	(segment
		(start 61.845698 -242.725956)
		(end 62.04204 -242.922298)
		(width 0.14478)
		(layer "In2.Cu")
		(net "M_C_CPU1_SA_CB<4>")
	)
	(segment
		(start 91.85402 -248.047002)
		(end 91.862402 -248.051828)
		(width 0.0889)
		(layer "In2.Cu")
		(net "M_C_CPU1_SA_CB<4>")
	)
	(segment
		(start 64.475106 -245.19128)
		(end 64.10706 -245.559326)
		(width 0.14478)
		(layer "In2.Cu")
		(net "M_C_CPU1_SA_CB<4>")
	)
	(segment
		(start 57.50814 -241.110262)
		(end 57.669684 -240.948718)
		(width 0.14478)
		(layer "In2.Cu")
		(net "M_C_CPU1_SA_CB<4>")
	)
	(segment
		(start 45.442378 -240.72342)
		(end 45.605446 -240.560352)
		(width 0.14478)
		(layer "In2.Cu")
		(net "M_C_CPU1_SA_CB<4>")
	)
	(segment
		(start 57.669684 -240.948718)
		(end 57.669684 -240.60023)
		(width 0.14478)
		(layer "In2.Cu")
		(net "M_C_CPU1_SA_CB<4>")
	)
	(segment
		(start 58.221118 -240.948718)
		(end 58.382662 -241.110262)
		(width 0.14478)
		(layer "In2.Cu")
		(net "M_C_CPU1_SA_CB<4>")
	)
	(segment
		(start 79.067152 -248.047002)
		(end 79.081884 -248.038366)
		(width 0.0889)
		(layer "In2.Cu")
		(net "M_C_CPU1_SA_CB<4>")
	)
	(segment
		(start 49.68494 -241.110262)
		(end 49.817528 -241.110262)
		(width 0.14478)
		(layer "In2.Cu")
		(net "M_C_CPU1_SA_CB<4>")
	)
	(segment
		(start 49.128426 -241.492024)
		(end 49.358804 -241.492024)
		(width 0.14478)
		(layer "In2.Cu")
		(net "M_C_CPU1_SA_CB<4>")
	)
	(segment
		(start 64.475106 -244.960648)
		(end 64.475106 -245.19128)
		(width 0.14478)
		(layer "In2.Cu")
		(net "M_C_CPU1_SA_CB<4>")
	)
	(segment
		(start 61.845698 -242.33124)
		(end 61.845698 -242.725956)
		(width 0.14478)
		(layer "In2.Cu")
		(net "M_C_CPU1_SA_CB<4>")
	)
	(segment
		(start 82.453988 -248.047002)
		(end 82.46237 -248.051828)
		(width 0.0889)
		(layer "In2.Cu")
		(net "M_C_CPU1_SA_CB<4>")
	)
	(segment
		(start 58.059574 -240.438686)
		(end 58.221118 -240.60023)
		(width 0.14478)
		(layer "In2.Cu")
		(net "M_C_CPU1_SA_CB<4>")
	)
	(segment
		(start 46.126146 -241.321336)
		(end 46.289214 -241.484404)
		(width 0.14478)
		(layer "In2.Cu")
		(net "M_C_CPU1_SA_CB<4>")
	)
	(segment
		(start 63.31966 -244.771926)
		(end 63.31966 -245.002558)
		(width 0.14478)
		(layer "In2.Cu")
		(net "M_C_CPU1_SA_CB<4>")
	)
	(segment
		(start 64.868806 -245.58498)
		(end 65.099438 -245.58498)
		(width 0.14478)
		(layer "In2.Cu")
		(net "M_C_CPU1_SA_CB<4>")
	)
	(segment
		(start 75.960986 -248.261124)
		(end 76.214986 -248.261124)
		(width 0.0889)
		(layer "In2.Cu")
		(net "M_C_CPU1_SA_CB<4>")
	)
	(segment
		(start 58.382662 -241.110262)
		(end 60.62472 -241.110262)
		(width 0.14478)
		(layer "In2.Cu")
		(net "M_C_CPU1_SA_CB<4>")
	)
	(segment
		(start 62.82944 -243.709698)
		(end 63.224156 -243.709698)
		(width 0.14478)
		(layer "In2.Cu")
		(net "M_C_CPU1_SA_CB<4>")
	)
	(segment
		(start 76.214986 -248.261124)
		(end 76.319126 -248.365264)
		(width 0.0889)
		(layer "In2.Cu")
		(net "M_C_CPU1_SA_CB<4>")
	)
	(segment
		(start 46.830742 -241.119914)
		(end 48.811942 -241.119914)
		(width 0.14478)
		(layer "In2.Cu")
		(net "M_C_CPU1_SA_CB<4>")
	)
	(segment
		(start 48.965358 -241.328956)
		(end 49.128426 -241.492024)
		(width 0.14478)
		(layer "In2.Cu")
		(net "M_C_CPU1_SA_CB<4>")
	)
	(segment
		(start 45.835824 -240.560352)
		(end 45.998892 -240.72342)
		(width 0.14478)
		(layer "In2.Cu")
		(net "M_C_CPU1_SA_CB<4>")
	)
	(segment
		(start 50.65776 -240.27003)
		(end 52.999132 -240.27003)
		(width 0.14478)
		(layer "In2.Cu")
		(net "M_C_CPU1_SA_CB<4>")
	)
	(segment
		(start 94.052644 -248.073164)
		(end 94.074996 -247.989852)
		(width 0.0889)
		(layer "In2.Cu")
		(net "M_C_CPU1_SA_CB<4>")
	)
	(segment
		(start 45.998892 -240.72342)
		(end 45.998892 -240.960402)
		(width 0.14478)
		(layer "In2.Cu")
		(net "M_C_CPU1_SA_CB<4>")
	)
	(segment
		(start 65.099438 -245.58498)
		(end 67.038982 -247.524524)
		(width 0.14478)
		(layer "In2.Cu")
		(net "M_C_CPU1_SA_CB<4>")
	)
	(segment
		(start 64.50076 -245.953026)
		(end 64.868806 -245.58498)
		(width 0.14478)
		(layer "In2.Cu")
		(net "M_C_CPU1_SA_CB<4>")
	)
	(segment
		(start 56.995822 -241.27333)
		(end 57.15889 -241.110262)
		(width 0.14478)
		(layer "In2.Cu")
		(net "M_C_CPU1_SA_CB<4>")
	)
	(segment
		(start 57.669684 -240.60023)
		(end 57.831228 -240.438686)
		(width 0.14478)
		(layer "In2.Cu")
		(net "M_C_CPU1_SA_CB<4>")
	)
	(segment
		(start 78.693518 -248.046748)
		(end 78.707234 -248.054622)
		(width 0.0889)
		(layer "In2.Cu")
		(net "M_C_CPU1_SA_CB<4>")
	)
	(segment
		(start 63.687706 -244.40388)
		(end 63.31966 -244.771926)
		(width 0.14478)
		(layer "In2.Cu")
		(net "M_C_CPU1_SA_CB<4>")
	)
	(segment
		(start 60.62472 -241.110262)
		(end 61.845698 -242.33124)
		(width 0.14478)
		(layer "In2.Cu")
		(net "M_C_CPU1_SA_CB<4>")
	)
	(segment
		(start 57.831228 -240.438686)
		(end 58.059574 -240.438686)
		(width 0.14478)
		(layer "In2.Cu")
		(net "M_C_CPU1_SA_CB<4>")
	)
	(segment
		(start 45.998892 -240.960402)
		(end 46.126146 -241.087656)
		(width 0.14478)
		(layer "In2.Cu")
		(net "M_C_CPU1_SA_CB<4>")
	)
	(segment
		(start 90.339672 -248.051828)
		(end 90.348054 -248.047002)
		(width 0.0889)
		(layer "In2.Cu")
		(net "M_C_CPU1_SA_CB<4>")
	)
	(segment
		(start 48.965358 -241.27333)
		(end 48.965358 -241.328956)
		(width 0.14478)
		(layer "In2.Cu")
		(net "M_C_CPU1_SA_CB<4>")
	)
	(segment
		(start 64.270128 -245.953026)
		(end 64.50076 -245.953026)
		(width 0.14478)
		(layer "In2.Cu")
		(net "M_C_CPU1_SA_CB<4>")
	)
	(segment
		(start 62.633098 -243.513356)
		(end 62.82944 -243.709698)
		(width 0.14478)
		(layer "In2.Cu")
		(net "M_C_CPU1_SA_CB<4>")
	)
	(segment
		(start 45.036486 -241.381788)
		(end 45.292518 -241.381788)
		(width 0.14478)
		(layer "In2.Cu")
		(net "M_C_CPU1_SA_CB<4>")
	)
	(segment
		(start 75.125326 -248.261124)
		(end 75.960986 -248.261124)
		(width 0.14478)
		(layer "In2.Cu")
		(net "M_C_CPU1_SA_CB<4>")
	)
	(segment
		(start 56.439308 -241.27333)
		(end 56.439308 -241.339116)
		(width 0.14478)
		(layer "In2.Cu")
		(net "M_C_CPU1_SA_CB<4>")
	)
	(segment
		(start 81.879694 -248.051828)
		(end 81.888076 -248.047002)
		(width 0.0889)
		(layer "In2.Cu")
		(net "M_C_CPU1_SA_CB<4>")
	)
	(segment
		(start 63.687706 -244.173248)
		(end 63.687706 -244.40388)
		(width 0.14478)
		(layer "In2.Cu")
		(net "M_C_CPU1_SA_CB<4>")
	)
	(segment
		(start 56.995822 -241.339116)
		(end 56.995822 -241.27333)
		(width 0.14478)
		(layer "In2.Cu")
		(net "M_C_CPU1_SA_CB<4>")
	)
	(segment
		(start 56.832754 -241.502184)
		(end 56.995822 -241.339116)
		(width 0.14478)
		(layer "In2.Cu")
		(net "M_C_CPU1_SA_CB<4>")
	)
	(segment
		(start 49.521872 -241.328956)
		(end 49.521872 -241.27333)
		(width 0.14478)
		(layer "In2.Cu")
		(net "M_C_CPU1_SA_CB<4>")
	)
	(segment
		(start 45.292518 -241.381788)
		(end 45.442378 -241.231928)
		(width 0.14478)
		(layer "In2.Cu")
		(net "M_C_CPU1_SA_CB<4>")
	)
	(segment
		(start 62.436756 -242.922298)
		(end 62.633098 -243.11864)
		(width 0.14478)
		(layer "In2.Cu")
		(net "M_C_CPU1_SA_CB<4>")
	)
	(segment
		(start 64.10706 -245.789958)
		(end 64.270128 -245.953026)
		(width 0.14478)
		(layer "In2.Cu")
		(net "M_C_CPU1_SA_CB<4>")
	)
	(segment
		(start 49.521872 -241.27333)
		(end 49.68494 -241.110262)
		(width 0.14478)
		(layer "In2.Cu")
		(net "M_C_CPU1_SA_CB<4>")
	)
	(segment
		(start 90.913966 -248.047002)
		(end 90.922348 -248.051828)
		(width 0.0889)
		(layer "In2.Cu")
		(net "M_C_CPU1_SA_CB<4>")
	)
	(segment
		(start 53.839364 -241.110262)
		(end 56.27624 -241.110262)
		(width 0.14478)
		(layer "In2.Cu")
		(net "M_C_CPU1_SA_CB<4>")
	)
	(segment
		(start 52.999132 -240.27003)
		(end 53.839364 -241.110262)
		(width 0.14478)
		(layer "In2.Cu")
		(net "M_C_CPU1_SA_CB<4>")
	)
	(segment
		(start 62.04204 -242.922298)
		(end 62.436756 -242.922298)
		(width 0.14478)
		(layer "In2.Cu")
		(net "M_C_CPU1_SA_CB<4>")
	)
	(segment
		(start 58.221118 -240.60023)
		(end 58.221118 -240.948718)
		(width 0.14478)
		(layer "In2.Cu")
		(net "M_C_CPU1_SA_CB<4>")
	)
	(segment
		(start 64.312038 -244.79758)
		(end 64.475106 -244.960648)
		(width 0.14478)
		(layer "In2.Cu")
		(net "M_C_CPU1_SA_CB<4>")
	)
	(segment
		(start 86.57971 -248.051828)
		(end 86.588092 -248.047002)
		(width 0.0889)
		(layer "In2.Cu")
		(net "M_C_CPU1_SA_CB<4>")
	)
	(segment
		(start 62.633098 -243.11864)
		(end 62.633098 -243.513356)
		(width 0.14478)
		(layer "In2.Cu")
		(net "M_C_CPU1_SA_CB<4>")
	)
	(segment
		(start 64.081406 -244.79758)
		(end 64.312038 -244.79758)
		(width 0.14478)
		(layer "In2.Cu")
		(net "M_C_CPU1_SA_CB<4>")
	)
	(segment
		(start 67.038982 -247.524524)
		(end 74.388726 -247.524524)
		(width 0.14478)
		(layer "In2.Cu")
		(net "M_C_CPU1_SA_CB<4>")
	)
	(segment
		(start 48.811942 -241.119914)
		(end 48.965358 -241.27333)
		(width 0.14478)
		(layer "In2.Cu")
		(net "M_C_CPU1_SA_CB<4>")
	)
	(segment
		(start 57.15889 -241.110262)
		(end 57.50814 -241.110262)
		(width 0.14478)
		(layer "In2.Cu")
		(net "M_C_CPU1_SA_CB<4>")
	)
	(segment
		(start 79.99984 -248.051828)
		(end 80.008222 -248.047002)
		(width 0.0889)
		(layer "In2.Cu")
		(net "M_C_CPU1_SA_CB<4>")
	)
	(segment
		(start 87.154004 -248.047002)
		(end 87.162386 -248.051828)
		(width 0.0889)
		(layer "In2.Cu")
		(net "M_C_CPU1_SA_CB<4>")
	)
	(segment
		(start 56.27624 -241.110262)
		(end 56.439308 -241.27333)
		(width 0.14478)
		(layer "In2.Cu")
		(net "M_C_CPU1_SA_CB<4>")
	)
	(segment
		(start 78.67777 -248.037604)
		(end 78.693518 -248.046748)
		(width 0.0889)
		(layer "In2.Cu")
		(net "M_C_CPU1_SA_CB<4>")
	)
	(segment
		(start 45.442378 -241.231928)
		(end 45.442378 -240.72342)
		(width 0.14478)
		(layer "In2.Cu")
		(net "M_C_CPU1_SA_CB<4>")
	)
	(segment
		(start 88.094058 -248.047002)
		(end 88.10244 -248.051828)
		(width 0.0889)
		(layer "In2.Cu")
		(net "M_C_CPU1_SA_CB<4>")
	)
	(segment
		(start 83.394042 -248.047002)
		(end 83.402424 -248.051828)
		(width 0.0889)
		(layer "In2.Cu")
		(net "M_C_CPU1_SA_CB<4>")
	)
	(segment
		(start 49.817528 -241.110262)
		(end 50.65776 -240.27003)
		(width 0.14478)
		(layer "In2.Cu")
		(net "M_C_CPU1_SA_CB<4>")
	)
	(segment
		(start 63.224156 -243.709698)
		(end 63.687706 -244.173248)
		(width 0.14478)
		(layer "In2.Cu")
		(net "M_C_CPU1_SA_CB<4>")
	)
	(segment
		(start 56.439308 -241.339116)
		(end 56.602376 -241.502184)
		(width 0.14478)
		(layer "In2.Cu")
		(net "M_C_CPU1_SA_CB<4>")
	)
	(segment
		(start 49.358804 -241.492024)
		(end 49.521872 -241.328956)
		(width 0.14478)
		(layer "In2.Cu")
		(net "M_C_CPU1_SA_CB<4>")
	)
	(segment
		(start 76.319126 -248.365264)
		(end 76.947268 -248.365264)
		(width 0.0889)
		(layer "In2.Cu")
		(net "M_C_CPU1_SA_CB<4>")
	)
	(arc
		(start 82.46237 -248.051828)
		(mid 82.645878 -248.097322)
		(end 82.82813 -248.047002)
		(width 0.0889)
		(layer "In2.Cu")
		(net "M_C_CPU1_SA_CB<4>")
	)
	(arc
		(start 86.21395 -248.047002)
		(mid 86.396201 -248.097352)
		(end 86.57971 -248.051828)
		(width 0.0889)
		(layer "In2.Cu")
		(net "M_C_CPU1_SA_CB<4>")
	)
	(arc
		(start 78.707234 -248.054622)
		(mid 78.888164 -248.0971)
		(end 79.067152 -248.047002)
		(width 0.0889)
		(layer "In2.Cu")
		(net "M_C_CPU1_SA_CB<4>")
	)
	(arc
		(start 83.768184 -248.047002)
		(mid 84.05114 -247.970825)
		(end 84.334096 -248.047002)
		(width 0.0889)
		(layer "In2.Cu")
		(net "M_C_CPU1_SA_CB<4>")
	)
	(arc
		(start 85.273896 -248.047002)
		(mid 85.456147 -248.097352)
		(end 85.639656 -248.051828)
		(width 0.0889)
		(layer "In2.Cu")
		(net "M_C_CPU1_SA_CB<4>")
	)
	(arc
		(start 92.228162 -248.047002)
		(mid 92.511118 -247.970825)
		(end 92.794074 -248.047002)
		(width 0.0889)
		(layer "In2.Cu")
		(net "M_C_CPU1_SA_CB<4>")
	)
	(arc
		(start 92.794074 -248.047002)
		(mid 92.981018 -248.097257)
		(end 93.167962 -248.047002)
		(width 0.0889)
		(layer "In2.Cu")
		(net "M_C_CPU1_SA_CB<4>")
	)
	(arc
		(start 87.528146 -248.047002)
		(mid 87.811102 -247.970825)
		(end 88.094058 -248.047002)
		(width 0.0889)
		(layer "In2.Cu")
		(net "M_C_CPU1_SA_CB<4>")
	)
	(arc
		(start 79.633572 -248.047002)
		(mid 79.816077 -248.097479)
		(end 79.99984 -248.051828)
		(width 0.0889)
		(layer "In2.Cu")
		(net "M_C_CPU1_SA_CB<4>")
	)
	(arc
		(start 89.034112 -248.047002)
		(mid 89.221056 -248.097257)
		(end 89.408 -248.047002)
		(width 0.0889)
		(layer "In2.Cu")
		(net "M_C_CPU1_SA_CB<4>")
	)
	(arc
		(start 80.948022 -248.047002)
		(mid 81.230978 -247.970825)
		(end 81.513934 -248.047002)
		(width 0.0889)
		(layer "In2.Cu")
		(net "M_C_CPU1_SA_CB<4>")
	)
	(arc
		(start 80.008222 -248.047002)
		(mid 80.291178 -247.970825)
		(end 80.574134 -248.047002)
		(width 0.0889)
		(layer "In2.Cu")
		(net "M_C_CPU1_SA_CB<4>")
	)
	(arc
		(start 93.733874 -248.047002)
		(mid 93.890312 -248.095973)
		(end 94.052644 -248.073164)
		(width 0.0889)
		(layer "In2.Cu")
		(net "M_C_CPU1_SA_CB<4>")
	)
	(arc
		(start 91.288108 -248.047002)
		(mid 91.571064 -247.970825)
		(end 91.85402 -248.047002)
		(width 0.0889)
		(layer "In2.Cu")
		(net "M_C_CPU1_SA_CB<4>")
	)
	(arc
		(start 88.10244 -248.051828)
		(mid 88.285948 -248.097322)
		(end 88.4682 -248.047002)
		(width 0.0889)
		(layer "In2.Cu")
		(net "M_C_CPU1_SA_CB<4>")
	)
	(arc
		(start 80.574134 -248.047002)
		(mid 80.761078 -248.097257)
		(end 80.948022 -248.047002)
		(width 0.0889)
		(layer "In2.Cu")
		(net "M_C_CPU1_SA_CB<4>")
	)
	(arc
		(start 91.862402 -248.051828)
		(mid 92.04591 -248.097322)
		(end 92.228162 -248.047002)
		(width 0.0889)
		(layer "In2.Cu")
		(net "M_C_CPU1_SA_CB<4>")
	)
	(arc
		(start 89.973912 -248.047002)
		(mid 90.156163 -248.097352)
		(end 90.339672 -248.051828)
		(width 0.0889)
		(layer "In2.Cu")
		(net "M_C_CPU1_SA_CB<4>")
	)
	(arc
		(start 90.922348 -248.051828)
		(mid 91.105856 -248.097322)
		(end 91.288108 -248.047002)
		(width 0.0889)
		(layer "In2.Cu")
		(net "M_C_CPU1_SA_CB<4>")
	)
	(arc
		(start 79.081884 -248.038366)
		(mid 79.358867 -247.970562)
		(end 79.633572 -248.047002)
		(width 0.0889)
		(layer "In2.Cu")
		(net "M_C_CPU1_SA_CB<4>")
	)
	(arc
		(start 83.402424 -248.051828)
		(mid 83.585932 -248.097322)
		(end 83.768184 -248.047002)
		(width 0.0889)
		(layer "In2.Cu")
		(net "M_C_CPU1_SA_CB<4>")
	)
	(arc
		(start 85.648038 -248.047002)
		(mid 85.930994 -247.970825)
		(end 86.21395 -248.047002)
		(width 0.0889)
		(layer "In2.Cu")
		(net "M_C_CPU1_SA_CB<4>")
	)
	(arc
		(start 88.4682 -248.047002)
		(mid 88.751156 -247.970825)
		(end 89.034112 -248.047002)
		(width 0.0889)
		(layer "In2.Cu")
		(net "M_C_CPU1_SA_CB<4>")
	)
	(arc
		(start 84.707984 -248.047002)
		(mid 84.99094 -247.970825)
		(end 85.273896 -248.047002)
		(width 0.0889)
		(layer "In2.Cu")
		(net "M_C_CPU1_SA_CB<4>")
	)
	(arc
		(start 93.167962 -248.047002)
		(mid 93.450918 -247.970825)
		(end 93.733874 -248.047002)
		(width 0.0889)
		(layer "In2.Cu")
		(net "M_C_CPU1_SA_CB<4>")
	)
	(arc
		(start 81.888076 -248.047002)
		(mid 82.171032 -247.970825)
		(end 82.453988 -248.047002)
		(width 0.0889)
		(layer "In2.Cu")
		(net "M_C_CPU1_SA_CB<4>")
	)
	(arc
		(start 89.408 -248.047002)
		(mid 89.690956 -247.970825)
		(end 89.973912 -248.047002)
		(width 0.0889)
		(layer "In2.Cu")
		(net "M_C_CPU1_SA_CB<4>")
	)
	(arc
		(start 84.334096 -248.047002)
		(mid 84.52104 -248.097257)
		(end 84.707984 -248.047002)
		(width 0.0889)
		(layer "In2.Cu")
		(net "M_C_CPU1_SA_CB<4>")
	)
	(arc
		(start 81.513934 -248.047002)
		(mid 81.696185 -248.097352)
		(end 81.879694 -248.051828)
		(width 0.0889)
		(layer "In2.Cu")
		(net "M_C_CPU1_SA_CB<4>")
	)
	(arc
		(start 86.588092 -248.047002)
		(mid 86.871048 -247.970825)
		(end 87.154004 -248.047002)
		(width 0.0889)
		(layer "In2.Cu")
		(net "M_C_CPU1_SA_CB<4>")
	)
	(arc
		(start 82.82813 -248.047002)
		(mid 83.111086 -247.970825)
		(end 83.394042 -248.047002)
		(width 0.0889)
		(layer "In2.Cu")
		(net "M_C_CPU1_SA_CB<4>")
	)
	(arc
		(start 90.348054 -248.047002)
		(mid 90.63101 -247.970825)
		(end 90.913966 -248.047002)
		(width 0.0889)
		(layer "In2.Cu")
		(net "M_C_CPU1_SA_CB<4>")
	)
	(arc
		(start 87.162386 -248.051828)
		(mid 87.345894 -248.097322)
		(end 87.528146 -248.047002)
		(width 0.0889)
		(layer "In2.Cu")
		(net "M_C_CPU1_SA_CB<4>")
	)
	(arc
		(start 78.127606 -248.047002)
		(mid 78.401461 -247.970652)
		(end 78.67777 -248.037604)
		(width 0.0889)
		(layer "In2.Cu")
		(net "M_C_CPU1_SA_CB<4>")
	)
	(arc
		(start 76.947268 -248.365264)
		(mid 77.558516 -248.284305)
		(end 78.127606 -248.047002)
		(width 0.0889)
		(layer "In2.Cu")
		(net "M_C_CPU1_SA_CB<4>")
	)
	(segment
		(start 96.267778 -246.370348)
		(end 95.800926 -246.10441)
		(width 0.10668)
		(layer "F.Cu")
		(net "M_C_CPU1_SA_CB<3>")
	)
	(segment
		(start 83.394042 -245.78183)
		(end 83.402424 -245.777004)
		(width 0.0889)
		(layer "In2.Cu")
		(net "M_C_CPU1_SA_CB<3>")
	)
	(segment
		(start 50.287936 -236.850682)
		(end 53.15077 -236.850682)
		(width 0.14478)
		(layer "In2.Cu")
		(net "M_C_CPU1_SA_CB<3>")
	)
	(segment
		(start 56.165496 -237.710472)
		(end 57.44718 -237.179612)
		(width 0.14478)
		(layer "In2.Cu")
		(net "M_C_CPU1_SA_CB<3>")
	)
	(segment
		(start 70.11162 -245.152164)
		(end 75.327764 -245.152164)
		(width 0.14478)
		(layer "In2.Cu")
		(net "M_C_CPU1_SA_CB<3>")
	)
	(segment
		(start 78.106778 -245.768622)
		(end 78.169516 -245.804944)
		(width 0.0889)
		(layer "In2.Cu")
		(net "M_C_CPU1_SA_CB<3>")
	)
	(segment
		(start 79.609188 -245.79707)
		(end 79.63535 -245.782084)
		(width 0.0889)
		(layer "In2.Cu")
		(net "M_C_CPU1_SA_CB<3>")
	)
	(segment
		(start 54.01056 -237.710472)
		(end 56.165496 -237.710472)
		(width 0.14478)
		(layer "In2.Cu")
		(net "M_C_CPU1_SA_CB<3>")
	)
	(segment
		(start 86.57971 -245.777004)
		(end 86.588092 -245.78183)
		(width 0.0889)
		(layer "In2.Cu")
		(net "M_C_CPU1_SA_CB<3>")
	)
	(segment
		(start 95.55099 -245.81358)
		(end 95.647002 -245.83898)
		(width 0.0889)
		(layer "In2.Cu")
		(net "M_C_CPU1_SA_CB<3>")
	)
	(segment
		(start 66.83248 -241.873024)
		(end 70.11162 -245.152164)
		(width 0.14478)
		(layer "In2.Cu")
		(net "M_C_CPU1_SA_CB<3>")
	)
	(segment
		(start 79.63535 -245.782084)
		(end 79.658718 -245.768622)
		(width 0.0889)
		(layer "In2.Cu")
		(net "M_C_CPU1_SA_CB<3>")
	)
	(segment
		(start 61.444886 -237.590584)
		(end 61.444886 -238.121444)
		(width 0.14478)
		(layer "In2.Cu")
		(net "M_C_CPU1_SA_CB<3>")
	)
	(segment
		(start 90.339672 -245.777004)
		(end 90.348054 -245.78183)
		(width 0.0889)
		(layer "In2.Cu")
		(net "M_C_CPU1_SA_CB<3>")
	)
	(segment
		(start 65.196466 -241.873024)
		(end 66.83248 -241.873024)
		(width 0.14478)
		(layer "In2.Cu")
		(net "M_C_CPU1_SA_CB<3>")
	)
	(segment
		(start 91.85402 -245.78183)
		(end 91.862402 -245.777004)
		(width 0.0889)
		(layer "In2.Cu")
		(net "M_C_CPU1_SA_CB<3>")
	)
	(segment
		(start 76.00061 -245.787418)
		(end 77.215492 -245.787418)
		(width 0.0889)
		(layer "In2.Cu")
		(net "M_C_CPU1_SA_CB<3>")
	)
	(segment
		(start 87.154004 -245.78183)
		(end 87.162386 -245.777004)
		(width 0.0889)
		(layer "In2.Cu")
		(net "M_C_CPU1_SA_CB<3>")
	)
	(segment
		(start 85.639656 -245.777004)
		(end 85.648038 -245.78183)
		(width 0.0889)
		(layer "In2.Cu")
		(net "M_C_CPU1_SA_CB<3>")
	)
	(segment
		(start 79.050896 -245.769892)
		(end 79.07147 -245.78183)
		(width 0.0889)
		(layer "In2.Cu")
		(net "M_C_CPU1_SA_CB<3>")
	)
	(segment
		(start 95.039688 -245.777004)
		(end 95.04807 -245.78183)
		(width 0.0889)
		(layer "In2.Cu")
		(net "M_C_CPU1_SA_CB<3>")
	)
	(segment
		(start 49.438052 -237.700566)
		(end 50.287936 -236.850682)
		(width 0.14478)
		(layer "In2.Cu")
		(net "M_C_CPU1_SA_CB<3>")
	)
	(segment
		(start 90.913966 -245.78183)
		(end 90.922348 -245.777004)
		(width 0.0889)
		(layer "In2.Cu")
		(net "M_C_CPU1_SA_CB<3>")
	)
	(segment
		(start 40.23995 -237.285276)
		(end 40.65524 -237.700566)
		(width 0.14478)
		(layer "In2.Cu")
		(net "M_C_CPU1_SA_CB<3>")
	)
	(segment
		(start 94.099634 -245.777004)
		(end 94.108016 -245.78183)
		(width 0.0889)
		(layer "In2.Cu")
		(net "M_C_CPU1_SA_CB<3>")
	)
	(segment
		(start 53.15077 -236.850682)
		(end 54.01056 -237.710472)
		(width 0.14478)
		(layer "In2.Cu")
		(net "M_C_CPU1_SA_CB<3>")
	)
	(segment
		(start 60.714636 -236.860334)
		(end 61.444886 -237.590584)
		(width 0.14478)
		(layer "In2.Cu")
		(net "M_C_CPU1_SA_CB<3>")
	)
	(segment
		(start 88.094058 -245.78183)
		(end 88.10244 -245.777004)
		(width 0.0889)
		(layer "In2.Cu")
		(net "M_C_CPU1_SA_CB<3>")
	)
	(segment
		(start 57.766458 -236.860334)
		(end 60.714636 -236.860334)
		(width 0.14478)
		(layer "In2.Cu")
		(net "M_C_CPU1_SA_CB<3>")
	)
	(segment
		(start 82.453988 -245.78183)
		(end 82.46237 -245.777004)
		(width 0.0889)
		(layer "In2.Cu")
		(net "M_C_CPU1_SA_CB<3>")
	)
	(segment
		(start 75.327764 -245.152164)
		(end 75.963018 -245.787418)
		(width 0.14478)
		(layer "In2.Cu")
		(net "M_C_CPU1_SA_CB<3>")
	)
	(segment
		(start 61.444886 -238.121444)
		(end 65.196466 -241.873024)
		(width 0.14478)
		(layer "In2.Cu")
		(net "M_C_CPU1_SA_CB<3>")
	)
	(segment
		(start 81.879694 -245.777004)
		(end 81.888076 -245.78183)
		(width 0.0889)
		(layer "In2.Cu")
		(net "M_C_CPU1_SA_CB<3>")
	)
	(segment
		(start 40.65524 -237.700566)
		(end 49.438052 -237.700566)
		(width 0.14478)
		(layer "In2.Cu")
		(net "M_C_CPU1_SA_CB<3>")
	)
	(segment
		(start 57.44718 -237.179612)
		(end 57.766458 -236.860334)
		(width 0.14478)
		(layer "In2.Cu")
		(net "M_C_CPU1_SA_CB<3>")
	)
	(segment
		(start 95.647002 -245.83898)
		(end 95.800926 -246.10441)
		(width 0.0889)
		(layer "In2.Cu")
		(net "M_C_CPU1_SA_CB<3>")
	)
	(segment
		(start 75.963018 -245.787418)
		(end 76.00061 -245.787418)
		(width 0.14478)
		(layer "In2.Cu")
		(net "M_C_CPU1_SA_CB<3>")
	)
	(arc
		(start 93.733874 -245.78183)
		(mid 93.916125 -245.73148)
		(end 94.099634 -245.777004)
		(width 0.0889)
		(layer "In2.Cu")
		(net "M_C_CPU1_SA_CB<3>")
	)
	(arc
		(start 81.888076 -245.78183)
		(mid 82.171032 -245.858007)
		(end 82.453988 -245.78183)
		(width 0.0889)
		(layer "In2.Cu")
		(net "M_C_CPU1_SA_CB<3>")
	)
	(arc
		(start 91.288108 -245.78183)
		(mid 91.571064 -245.858007)
		(end 91.85402 -245.78183)
		(width 0.0889)
		(layer "In2.Cu")
		(net "M_C_CPU1_SA_CB<3>")
	)
	(arc
		(start 79.658718 -245.768622)
		(mid 79.835113 -245.731719)
		(end 80.008222 -245.78183)
		(width 0.0889)
		(layer "In2.Cu")
		(net "M_C_CPU1_SA_CB<3>")
	)
	(arc
		(start 84.707984 -245.78183)
		(mid 84.99094 -245.858007)
		(end 85.273896 -245.78183)
		(width 0.0889)
		(layer "In2.Cu")
		(net "M_C_CPU1_SA_CB<3>")
	)
	(arc
		(start 86.588092 -245.78183)
		(mid 86.871048 -245.858007)
		(end 87.154004 -245.78183)
		(width 0.0889)
		(layer "In2.Cu")
		(net "M_C_CPU1_SA_CB<3>")
	)
	(arc
		(start 91.862402 -245.777004)
		(mid 92.04591 -245.73151)
		(end 92.228162 -245.78183)
		(width 0.0889)
		(layer "In2.Cu")
		(net "M_C_CPU1_SA_CB<3>")
	)
	(arc
		(start 83.768184 -245.78183)
		(mid 84.05114 -245.858007)
		(end 84.334096 -245.78183)
		(width 0.0889)
		(layer "In2.Cu")
		(net "M_C_CPU1_SA_CB<3>")
	)
	(arc
		(start 90.922348 -245.777004)
		(mid 91.105856 -245.73151)
		(end 91.288108 -245.78183)
		(width 0.0889)
		(layer "In2.Cu")
		(net "M_C_CPU1_SA_CB<3>")
	)
	(arc
		(start 93.167962 -245.78183)
		(mid 93.450918 -245.858007)
		(end 93.733874 -245.78183)
		(width 0.0889)
		(layer "In2.Cu")
		(net "M_C_CPU1_SA_CB<3>")
	)
	(arc
		(start 84.334096 -245.78183)
		(mid 84.52104 -245.731575)
		(end 84.707984 -245.78183)
		(width 0.0889)
		(layer "In2.Cu")
		(net "M_C_CPU1_SA_CB<3>")
	)
	(arc
		(start 90.348054 -245.78183)
		(mid 90.63101 -245.858007)
		(end 90.913966 -245.78183)
		(width 0.0889)
		(layer "In2.Cu")
		(net "M_C_CPU1_SA_CB<3>")
	)
	(arc
		(start 80.008222 -245.78183)
		(mid 80.291178 -245.858007)
		(end 80.574134 -245.78183)
		(width 0.0889)
		(layer "In2.Cu")
		(net "M_C_CPU1_SA_CB<3>")
	)
	(arc
		(start 77.887576 -245.735856)
		(mid 77.999662 -245.735597)
		(end 78.106778 -245.768622)
		(width 0.0889)
		(layer "In2.Cu")
		(net "M_C_CPU1_SA_CB<3>")
	)
	(arc
		(start 89.034112 -245.78183)
		(mid 89.221056 -245.731575)
		(end 89.408 -245.78183)
		(width 0.0889)
		(layer "In2.Cu")
		(net "M_C_CPU1_SA_CB<3>")
	)
	(arc
		(start 77.215492 -245.787418)
		(mid 77.552521 -245.774504)
		(end 77.887576 -245.735856)
		(width 0.0889)
		(layer "In2.Cu")
		(net "M_C_CPU1_SA_CB<3>")
	)
	(arc
		(start 81.513934 -245.78183)
		(mid 81.696185 -245.73148)
		(end 81.879694 -245.777004)
		(width 0.0889)
		(layer "In2.Cu")
		(net "M_C_CPU1_SA_CB<3>")
	)
	(arc
		(start 78.169516 -245.804944)
		(mid 78.43564 -245.85855)
		(end 78.696058 -245.78183)
		(width 0.0889)
		(layer "In2.Cu")
		(net "M_C_CPU1_SA_CB<3>")
	)
	(arc
		(start 85.648038 -245.78183)
		(mid 85.930994 -245.858007)
		(end 86.21395 -245.78183)
		(width 0.0889)
		(layer "In2.Cu")
		(net "M_C_CPU1_SA_CB<3>")
	)
	(arc
		(start 89.973912 -245.78183)
		(mid 90.156163 -245.73148)
		(end 90.339672 -245.777004)
		(width 0.0889)
		(layer "In2.Cu")
		(net "M_C_CPU1_SA_CB<3>")
	)
	(arc
		(start 95.04807 -245.78183)
		(mid 95.295783 -245.85705)
		(end 95.55099 -245.81358)
		(width 0.0889)
		(layer "In2.Cu")
		(net "M_C_CPU1_SA_CB<3>")
	)
	(arc
		(start 86.21395 -245.78183)
		(mid 86.396201 -245.73148)
		(end 86.57971 -245.777004)
		(width 0.0889)
		(layer "In2.Cu")
		(net "M_C_CPU1_SA_CB<3>")
	)
	(arc
		(start 94.673928 -245.78183)
		(mid 94.856179 -245.73148)
		(end 95.039688 -245.777004)
		(width 0.0889)
		(layer "In2.Cu")
		(net "M_C_CPU1_SA_CB<3>")
	)
	(arc
		(start 88.10244 -245.777004)
		(mid 88.285948 -245.73151)
		(end 88.4682 -245.78183)
		(width 0.0889)
		(layer "In2.Cu")
		(net "M_C_CPU1_SA_CB<3>")
	)
	(arc
		(start 83.402424 -245.777004)
		(mid 83.585932 -245.73151)
		(end 83.768184 -245.78183)
		(width 0.0889)
		(layer "In2.Cu")
		(net "M_C_CPU1_SA_CB<3>")
	)
	(arc
		(start 80.948022 -245.78183)
		(mid 81.230978 -245.858007)
		(end 81.513934 -245.78183)
		(width 0.0889)
		(layer "In2.Cu")
		(net "M_C_CPU1_SA_CB<3>")
	)
	(arc
		(start 87.528146 -245.78183)
		(mid 87.811102 -245.858007)
		(end 88.094058 -245.78183)
		(width 0.0889)
		(layer "In2.Cu")
		(net "M_C_CPU1_SA_CB<3>")
	)
	(arc
		(start 92.794074 -245.78183)
		(mid 92.981018 -245.731575)
		(end 93.167962 -245.78183)
		(width 0.0889)
		(layer "In2.Cu")
		(net "M_C_CPU1_SA_CB<3>")
	)
	(arc
		(start 80.574134 -245.78183)
		(mid 80.761078 -245.731575)
		(end 80.948022 -245.78183)
		(width 0.0889)
		(layer "In2.Cu")
		(net "M_C_CPU1_SA_CB<3>")
	)
	(arc
		(start 92.228162 -245.78183)
		(mid 92.511118 -245.858007)
		(end 92.794074 -245.78183)
		(width 0.0889)
		(layer "In2.Cu")
		(net "M_C_CPU1_SA_CB<3>")
	)
	(arc
		(start 85.273896 -245.78183)
		(mid 85.456147 -245.73148)
		(end 85.639656 -245.777004)
		(width 0.0889)
		(layer "In2.Cu")
		(net "M_C_CPU1_SA_CB<3>")
	)
	(arc
		(start 87.162386 -245.777004)
		(mid 87.345894 -245.73151)
		(end 87.528146 -245.78183)
		(width 0.0889)
		(layer "In2.Cu")
		(net "M_C_CPU1_SA_CB<3>")
	)
	(arc
		(start 78.696058 -245.78183)
		(mid 78.871968 -245.73102)
		(end 79.050896 -245.769892)
		(width 0.0889)
		(layer "In2.Cu")
		(net "M_C_CPU1_SA_CB<3>")
	)
	(arc
		(start 79.07147 -245.78183)
		(mid 79.3384 -245.857779)
		(end 79.609188 -245.79707)
		(width 0.0889)
		(layer "In2.Cu")
		(net "M_C_CPU1_SA_CB<3>")
	)
	(arc
		(start 88.4682 -245.78183)
		(mid 88.751156 -245.858007)
		(end 89.034112 -245.78183)
		(width 0.0889)
		(layer "In2.Cu")
		(net "M_C_CPU1_SA_CB<3>")
	)
	(arc
		(start 82.82813 -245.78183)
		(mid 83.111086 -245.858007)
		(end 83.394042 -245.78183)
		(width 0.0889)
		(layer "In2.Cu")
		(net "M_C_CPU1_SA_CB<3>")
	)
	(arc
		(start 82.46237 -245.777004)
		(mid 82.645878 -245.73151)
		(end 82.82813 -245.78183)
		(width 0.0889)
		(layer "In2.Cu")
		(net "M_C_CPU1_SA_CB<3>")
	)
	(arc
		(start 94.108016 -245.78183)
		(mid 94.390972 -245.858007)
		(end 94.673928 -245.78183)
		(width 0.0889)
		(layer "In2.Cu")
		(net "M_C_CPU1_SA_CB<3>")
	)
	(arc
		(start 89.408 -245.78183)
		(mid 89.690956 -245.858007)
		(end 89.973912 -245.78183)
		(width 0.0889)
		(layer "In2.Cu")
		(net "M_C_CPU1_SA_CB<3>")
	)
	(segment
		(start 94.857824 -245.560342)
		(end 94.390972 -245.294404)
		(width 0.10668)
		(layer "F.Cu")
		(net "M_C_CPU1_SA_CB<2>")
	)
	(segment
		(start 85.74405 -244.971824)
		(end 85.752432 -244.966998)
		(width 0.0889)
		(layer "In2.Cu")
		(net "M_C_CPU1_SA_CB<2>")
	)
	(segment
		(start 80.089248 -244.98046)
		(end 80.10398 -244.971824)
		(width 0.0889)
		(layer "In2.Cu")
		(net "M_C_CPU1_SA_CB<2>")
	)
	(segment
		(start 84.803996 -244.971824)
		(end 84.812378 -244.966998)
		(width 0.0889)
		(layer "In2.Cu")
		(net "M_C_CPU1_SA_CB<2>")
	)
	(segment
		(start 91.749626 -244.966998)
		(end 91.758008 -244.971824)
		(width 0.0889)
		(layer "In2.Cu")
		(net "M_C_CPU1_SA_CB<2>")
	)
	(segment
		(start 42.542714 -235.635292)
		(end 42.705782 -235.472224)
		(width 0.14478)
		(layer "In2.Cu")
		(net "M_C_CPU1_SA_CB<2>")
	)
	(segment
		(start 77.210666 -245.218204)
		(end 77.373988 -245.054882)
		(width 0.0889)
		(layer "In2.Cu")
		(net "M_C_CPU1_SA_CB<2>")
	)
	(segment
		(start 53.961792 -236.01045)
		(end 56.91632 -236.01045)
		(width 0.14478)
		(layer "In2.Cu")
		(net "M_C_CPU1_SA_CB<2>")
	)
	(segment
		(start 57.766458 -235.160312)
		(end 60.3377 -235.160312)
		(width 0.14478)
		(layer "In2.Cu")
		(net "M_C_CPU1_SA_CB<2>")
	)
	(segment
		(start 43.099228 -235.847382)
		(end 43.262296 -236.01045)
		(width 0.14478)
		(layer "In2.Cu")
		(net "M_C_CPU1_SA_CB<2>")
	)
	(segment
		(start 40.665146 -236.01045)
		(end 42.379646 -236.01045)
		(width 0.14478)
		(layer "In2.Cu")
		(net "M_C_CPU1_SA_CB<2>")
	)
	(segment
		(start 53.111654 -235.160312)
		(end 53.961792 -236.01045)
		(width 0.14478)
		(layer "In2.Cu")
		(net "M_C_CPU1_SA_CB<2>")
	)
	(segment
		(start 42.93616 -235.472224)
		(end 43.099228 -235.635292)
		(width 0.14478)
		(layer "In2.Cu")
		(net "M_C_CPU1_SA_CB<2>")
	)
	(segment
		(start 62.354206 -237.176818)
		(end 62.354206 -237.702344)
		(width 0.14478)
		(layer "In2.Cu")
		(net "M_C_CPU1_SA_CB<2>")
	)
	(segment
		(start 87.989664 -244.966998)
		(end 87.998046 -244.971824)
		(width 0.0889)
		(layer "In2.Cu")
		(net "M_C_CPU1_SA_CB<2>")
	)
	(segment
		(start 89.504012 -244.971824)
		(end 89.512394 -244.966998)
		(width 0.0889)
		(layer "In2.Cu")
		(net "M_C_CPU1_SA_CB<2>")
	)
	(segment
		(start 65.567306 -240.915444)
		(end 67.179952 -240.915444)
		(width 0.14478)
		(layer "In2.Cu")
		(net "M_C_CPU1_SA_CB<2>")
	)
	(segment
		(start 93.263974 -244.971824)
		(end 93.272356 -244.966998)
		(width 0.0889)
		(layer "In2.Cu")
		(net "M_C_CPU1_SA_CB<2>")
	)
	(segment
		(start 75.722226 -244.237764)
		(end 76.118466 -244.634004)
		(width 0.14478)
		(layer "In2.Cu")
		(net "M_C_CPU1_SA_CB<2>")
	)
	(segment
		(start 43.262296 -236.01045)
		(end 49.428146 -236.01045)
		(width 0.14478)
		(layer "In2.Cu")
		(net "M_C_CPU1_SA_CB<2>")
	)
	(segment
		(start 88.929718 -244.966998)
		(end 88.9381 -244.971824)
		(width 0.0889)
		(layer "In2.Cu")
		(net "M_C_CPU1_SA_CB<2>")
	)
	(segment
		(start 67.179952 -240.915444)
		(end 70.502272 -244.237764)
		(width 0.14478)
		(layer "In2.Cu")
		(net "M_C_CPU1_SA_CB<2>")
	)
	(segment
		(start 92.68968 -244.966998)
		(end 92.698062 -244.971824)
		(width 0.0889)
		(layer "In2.Cu")
		(net "M_C_CPU1_SA_CB<2>")
	)
	(segment
		(start 76.118466 -244.634004)
		(end 76.702666 -245.218204)
		(width 0.0889)
		(layer "In2.Cu")
		(net "M_C_CPU1_SA_CB<2>")
	)
	(segment
		(start 78.579472 -244.961664)
		(end 78.59776 -244.972078)
		(width 0.0889)
		(layer "In2.Cu")
		(net "M_C_CPU1_SA_CB<2>")
	)
	(segment
		(start 40.23995 -235.585254)
		(end 40.665146 -236.01045)
		(width 0.14478)
		(layer "In2.Cu")
		(net "M_C_CPU1_SA_CB<2>")
	)
	(segment
		(start 42.542714 -235.847382)
		(end 42.542714 -235.635292)
		(width 0.14478)
		(layer "In2.Cu")
		(net "M_C_CPU1_SA_CB<2>")
	)
	(segment
		(start 83.289648 -244.966998)
		(end 83.29803 -244.971824)
		(width 0.0889)
		(layer "In2.Cu")
		(net "M_C_CPU1_SA_CB<2>")
	)
	(segment
		(start 50.278284 -235.160312)
		(end 53.111654 -235.160312)
		(width 0.14478)
		(layer "In2.Cu")
		(net "M_C_CPU1_SA_CB<2>")
	)
	(segment
		(start 60.3377 -235.160312)
		(end 62.354206 -237.176818)
		(width 0.14478)
		(layer "In2.Cu")
		(net "M_C_CPU1_SA_CB<2>")
	)
	(segment
		(start 80.46974 -244.966998)
		(end 80.478122 -244.971824)
		(width 0.0889)
		(layer "In2.Cu")
		(net "M_C_CPU1_SA_CB<2>")
	)
	(segment
		(start 79.163164 -244.971824)
		(end 79.174848 -244.964966)
		(width 0.0889)
		(layer "In2.Cu")
		(net "M_C_CPU1_SA_CB<2>")
	)
	(segment
		(start 77.373988 -245.054882)
		(end 77.947266 -245.054882)
		(width 0.0889)
		(layer "In2.Cu")
		(net "M_C_CPU1_SA_CB<2>")
	)
	(segment
		(start 84.229702 -244.966998)
		(end 84.238084 -244.971824)
		(width 0.0889)
		(layer "In2.Cu")
		(net "M_C_CPU1_SA_CB<2>")
	)
	(segment
		(start 70.502272 -244.237764)
		(end 75.722226 -244.237764)
		(width 0.14478)
		(layer "In2.Cu")
		(net "M_C_CPU1_SA_CB<2>")
	)
	(segment
		(start 42.379646 -236.01045)
		(end 42.542714 -235.847382)
		(width 0.14478)
		(layer "In2.Cu")
		(net "M_C_CPU1_SA_CB<2>")
	)
	(segment
		(start 76.702666 -245.218204)
		(end 77.210666 -245.218204)
		(width 0.0889)
		(layer "In2.Cu")
		(net "M_C_CPU1_SA_CB<2>")
	)
	(segment
		(start 94.141036 -245.003574)
		(end 94.237048 -245.028974)
		(width 0.0889)
		(layer "In2.Cu")
		(net "M_C_CPU1_SA_CB<2>")
	)
	(segment
		(start 56.91632 -236.01045)
		(end 57.766458 -235.160312)
		(width 0.14478)
		(layer "In2.Cu")
		(net "M_C_CPU1_SA_CB<2>")
	)
	(segment
		(start 62.354206 -237.702344)
		(end 65.567306 -240.915444)
		(width 0.14478)
		(layer "In2.Cu")
		(net "M_C_CPU1_SA_CB<2>")
	)
	(segment
		(start 78.59776 -244.972078)
		(end 78.603348 -244.97538)
		(width 0.0889)
		(layer "In2.Cu")
		(net "M_C_CPU1_SA_CB<2>")
	)
	(segment
		(start 94.237048 -245.028974)
		(end 94.390972 -245.294404)
		(width 0.0889)
		(layer "In2.Cu")
		(net "M_C_CPU1_SA_CB<2>")
	)
	(segment
		(start 42.705782 -235.472224)
		(end 42.93616 -235.472224)
		(width 0.14478)
		(layer "In2.Cu")
		(net "M_C_CPU1_SA_CB<2>")
	)
	(segment
		(start 81.044034 -244.971824)
		(end 81.052416 -244.966998)
		(width 0.0889)
		(layer "In2.Cu")
		(net "M_C_CPU1_SA_CB<2>")
	)
	(segment
		(start 78.195678 -244.98808)
		(end 78.223618 -244.971824)
		(width 0.0889)
		(layer "In2.Cu")
		(net "M_C_CPU1_SA_CB<2>")
	)
	(segment
		(start 43.099228 -235.635292)
		(end 43.099228 -235.847382)
		(width 0.14478)
		(layer "In2.Cu")
		(net "M_C_CPU1_SA_CB<2>")
	)
	(segment
		(start 49.428146 -236.01045)
		(end 50.278284 -235.160312)
		(width 0.14478)
		(layer "In2.Cu")
		(net "M_C_CPU1_SA_CB<2>")
	)
	(arc
		(start 91.758008 -244.971824)
		(mid 92.040964 -245.048001)
		(end 92.32392 -244.971824)
		(width 0.0889)
		(layer "In2.Cu")
		(net "M_C_CPU1_SA_CB<2>")
	)
	(arc
		(start 86.118192 -244.971824)
		(mid 86.401148 -245.048001)
		(end 86.684104 -244.971824)
		(width 0.0889)
		(layer "In2.Cu")
		(net "M_C_CPU1_SA_CB<2>")
	)
	(arc
		(start 88.9381 -244.971824)
		(mid 89.221056 -245.048001)
		(end 89.504012 -244.971824)
		(width 0.0889)
		(layer "In2.Cu")
		(net "M_C_CPU1_SA_CB<2>")
	)
	(arc
		(start 83.29803 -244.971824)
		(mid 83.580986 -245.048001)
		(end 83.863942 -244.971824)
		(width 0.0889)
		(layer "In2.Cu")
		(net "M_C_CPU1_SA_CB<2>")
	)
	(arc
		(start 81.052416 -244.966998)
		(mid 81.235924 -244.921504)
		(end 81.418176 -244.971824)
		(width 0.0889)
		(layer "In2.Cu")
		(net "M_C_CPU1_SA_CB<2>")
	)
	(arc
		(start 81.418176 -244.971824)
		(mid 81.701132 -245.048001)
		(end 81.984088 -244.971824)
		(width 0.0889)
		(layer "In2.Cu")
		(net "M_C_CPU1_SA_CB<2>")
	)
	(arc
		(start 90.444066 -244.971824)
		(mid 90.63101 -244.921569)
		(end 90.817954 -244.971824)
		(width 0.0889)
		(layer "In2.Cu")
		(net "M_C_CPU1_SA_CB<2>")
	)
	(arc
		(start 80.478122 -244.971824)
		(mid 80.761078 -245.048001)
		(end 81.044034 -244.971824)
		(width 0.0889)
		(layer "In2.Cu")
		(net "M_C_CPU1_SA_CB<2>")
	)
	(arc
		(start 81.984088 -244.971824)
		(mid 82.171032 -244.921569)
		(end 82.357976 -244.971824)
		(width 0.0889)
		(layer "In2.Cu")
		(net "M_C_CPU1_SA_CB<2>")
	)
	(arc
		(start 80.10398 -244.971824)
		(mid 80.286231 -244.921474)
		(end 80.46974 -244.966998)
		(width 0.0889)
		(layer "In2.Cu")
		(net "M_C_CPU1_SA_CB<2>")
	)
	(arc
		(start 82.923888 -244.971824)
		(mid 83.106139 -244.921474)
		(end 83.289648 -244.966998)
		(width 0.0889)
		(layer "In2.Cu")
		(net "M_C_CPU1_SA_CB<2>")
	)
	(arc
		(start 90.817954 -244.971824)
		(mid 91.10091 -245.048001)
		(end 91.383866 -244.971824)
		(width 0.0889)
		(layer "In2.Cu")
		(net "M_C_CPU1_SA_CB<2>")
	)
	(arc
		(start 88.563958 -244.971824)
		(mid 88.746209 -244.921474)
		(end 88.929718 -244.966998)
		(width 0.0889)
		(layer "In2.Cu")
		(net "M_C_CPU1_SA_CB<2>")
	)
	(arc
		(start 87.057992 -244.971824)
		(mid 87.340948 -245.048001)
		(end 87.623904 -244.971824)
		(width 0.0889)
		(layer "In2.Cu")
		(net "M_C_CPU1_SA_CB<2>")
	)
	(arc
		(start 93.272356 -244.966998)
		(mid 93.455864 -244.921504)
		(end 93.638116 -244.971824)
		(width 0.0889)
		(layer "In2.Cu")
		(net "M_C_CPU1_SA_CB<2>")
	)
	(arc
		(start 87.623904 -244.971824)
		(mid 87.806155 -244.921474)
		(end 87.989664 -244.966998)
		(width 0.0889)
		(layer "In2.Cu")
		(net "M_C_CPU1_SA_CB<2>")
	)
	(arc
		(start 79.174848 -244.964966)
		(mid 79.357103 -244.921313)
		(end 79.53756 -244.971824)
		(width 0.0889)
		(layer "In2.Cu")
		(net "M_C_CPU1_SA_CB<2>")
	)
	(arc
		(start 77.947266 -245.054882)
		(mid 78.075881 -245.037883)
		(end 78.195678 -244.98808)
		(width 0.0889)
		(layer "In2.Cu")
		(net "M_C_CPU1_SA_CB<2>")
	)
	(arc
		(start 89.878154 -244.971824)
		(mid 90.16111 -245.048001)
		(end 90.444066 -244.971824)
		(width 0.0889)
		(layer "In2.Cu")
		(net "M_C_CPU1_SA_CB<2>")
	)
	(arc
		(start 79.53756 -244.971824)
		(mid 79.812266 -245.048188)
		(end 80.089248 -244.98046)
		(width 0.0889)
		(layer "In2.Cu")
		(net "M_C_CPU1_SA_CB<2>")
	)
	(arc
		(start 84.812378 -244.966998)
		(mid 84.995886 -244.921504)
		(end 85.178138 -244.971824)
		(width 0.0889)
		(layer "In2.Cu")
		(net "M_C_CPU1_SA_CB<2>")
	)
	(arc
		(start 78.603348 -244.97538)
		(mid 78.883737 -245.048049)
		(end 79.163164 -244.971824)
		(width 0.0889)
		(layer "In2.Cu")
		(net "M_C_CPU1_SA_CB<2>")
	)
	(arc
		(start 82.357976 -244.971824)
		(mid 82.640932 -245.048001)
		(end 82.923888 -244.971824)
		(width 0.0889)
		(layer "In2.Cu")
		(net "M_C_CPU1_SA_CB<2>")
	)
	(arc
		(start 85.178138 -244.971824)
		(mid 85.461094 -245.048001)
		(end 85.74405 -244.971824)
		(width 0.0889)
		(layer "In2.Cu")
		(net "M_C_CPU1_SA_CB<2>")
	)
	(arc
		(start 86.684104 -244.971824)
		(mid 86.871048 -244.921569)
		(end 87.057992 -244.971824)
		(width 0.0889)
		(layer "In2.Cu")
		(net "M_C_CPU1_SA_CB<2>")
	)
	(arc
		(start 93.638116 -244.971824)
		(mid 93.885829 -245.047044)
		(end 94.141036 -245.003574)
		(width 0.0889)
		(layer "In2.Cu")
		(net "M_C_CPU1_SA_CB<2>")
	)
	(arc
		(start 85.752432 -244.966998)
		(mid 85.93594 -244.921504)
		(end 86.118192 -244.971824)
		(width 0.0889)
		(layer "In2.Cu")
		(net "M_C_CPU1_SA_CB<2>")
	)
	(arc
		(start 92.32392 -244.971824)
		(mid 92.506171 -244.921474)
		(end 92.68968 -244.966998)
		(width 0.0889)
		(layer "In2.Cu")
		(net "M_C_CPU1_SA_CB<2>")
	)
	(arc
		(start 87.998046 -244.971824)
		(mid 88.281002 -245.048001)
		(end 88.563958 -244.971824)
		(width 0.0889)
		(layer "In2.Cu")
		(net "M_C_CPU1_SA_CB<2>")
	)
	(arc
		(start 91.383866 -244.971824)
		(mid 91.566117 -244.921474)
		(end 91.749626 -244.966998)
		(width 0.0889)
		(layer "In2.Cu")
		(net "M_C_CPU1_SA_CB<2>")
	)
	(arc
		(start 78.223618 -244.971824)
		(mid 78.400246 -244.921591)
		(end 78.579472 -244.961664)
		(width 0.0889)
		(layer "In2.Cu")
		(net "M_C_CPU1_SA_CB<2>")
	)
	(arc
		(start 84.238084 -244.971824)
		(mid 84.52104 -245.048001)
		(end 84.803996 -244.971824)
		(width 0.0889)
		(layer "In2.Cu")
		(net "M_C_CPU1_SA_CB<2>")
	)
	(arc
		(start 83.863942 -244.971824)
		(mid 84.046193 -244.921474)
		(end 84.229702 -244.966998)
		(width 0.0889)
		(layer "In2.Cu")
		(net "M_C_CPU1_SA_CB<2>")
	)
	(arc
		(start 89.512394 -244.966998)
		(mid 89.695902 -244.921504)
		(end 89.878154 -244.971824)
		(width 0.0889)
		(layer "In2.Cu")
		(net "M_C_CPU1_SA_CB<2>")
	)
	(arc
		(start 92.698062 -244.971824)
		(mid 92.981018 -245.048001)
		(end 93.263974 -244.971824)
		(width 0.0889)
		(layer "In2.Cu")
		(net "M_C_CPU1_SA_CB<2>")
	)
	(segment
		(start 95.797878 -245.560342)
		(end 95.331026 -245.294404)
		(width 0.10668)
		(layer "F.Cu")
		(net "M_C_CPU1_SA_CB<1>")
	)
	(segment
		(start 50.789332 -235.847382)
		(end 50.789332 -235.782612)
		(width 0.14478)
		(layer "In2.Cu")
		(net "M_C_CPU1_SA_CB<1>")
	)
	(segment
		(start 53.102764 -236.01045)
		(end 53.952648 -236.860334)
		(width 0.14478)
		(layer "In2.Cu")
		(net "M_C_CPU1_SA_CB<1>")
	)
	(segment
		(start 81.044034 -245.616984)
		(end 81.052416 -245.62181)
		(width 0.0889)
		(layer "In2.Cu")
		(net "M_C_CPU1_SA_CB<1>")
	)
	(segment
		(start 51.182778 -235.619544)
		(end 51.345846 -235.782612)
		(width 0.14478)
		(layer "In2.Cu")
		(net "M_C_CPU1_SA_CB<1>")
	)
	(segment
		(start 95.48495 -245.559834)
		(end 95.331026 -245.294404)
		(width 0.0889)
		(layer "In2.Cu")
		(net "M_C_CPU1_SA_CB<1>")
	)
	(segment
		(start 49.427384 -236.860334)
		(end 50.277268 -236.01045)
		(width 0.14478)
		(layer "In2.Cu")
		(net "M_C_CPU1_SA_CB<1>")
	)
	(segment
		(start 46.07179 -237.026196)
		(end 46.234858 -237.189264)
		(width 0.14478)
		(layer "In2.Cu")
		(net "M_C_CPU1_SA_CB<1>")
	)
	(segment
		(start 65.374266 -241.385344)
		(end 66.99758 -241.385344)
		(width 0.14478)
		(layer "In2.Cu")
		(net "M_C_CPU1_SA_CB<1>")
	)
	(segment
		(start 51.508914 -236.01045)
		(end 53.102764 -236.01045)
		(width 0.14478)
		(layer "In2.Cu")
		(net "M_C_CPU1_SA_CB<1>")
	)
	(segment
		(start 54.517544 -236.467904)
		(end 54.747922 -236.467904)
		(width 0.14478)
		(layer "In2.Cu")
		(net "M_C_CPU1_SA_CB<1>")
	)
	(segment
		(start 94.204028 -245.616984)
		(end 94.21241 -245.62181)
		(width 0.0889)
		(layer "In2.Cu")
		(net "M_C_CPU1_SA_CB<1>")
	)
	(segment
		(start 50.789332 -235.782612)
		(end 50.9524 -235.619544)
		(width 0.14478)
		(layer "In2.Cu")
		(net "M_C_CPU1_SA_CB<1>")
	)
	(segment
		(start 55.970424 -236.636052)
		(end 56.133492 -236.472984)
		(width 0.14478)
		(layer "In2.Cu")
		(net "M_C_CPU1_SA_CB<1>")
	)
	(segment
		(start 47.02175 -236.480604)
		(end 47.184818 -236.643672)
		(width 0.14478)
		(layer "In2.Cu")
		(net "M_C_CPU1_SA_CB<1>")
	)
	(segment
		(start 46.234858 -237.189264)
		(end 46.465236 -237.189264)
		(width 0.14478)
		(layer "In2.Cu")
		(net "M_C_CPU1_SA_CB<1>")
	)
	(segment
		(start 54.91099 -236.630972)
		(end 54.91099 -236.697266)
		(width 0.14478)
		(layer "In2.Cu")
		(net "M_C_CPU1_SA_CB<1>")
	)
	(segment
		(start 55.074058 -236.860334)
		(end 55.807356 -236.860334)
		(width 0.14478)
		(layer "In2.Cu")
		(net "M_C_CPU1_SA_CB<1>")
	)
	(segment
		(start 76.150216 -245.315994)
		(end 76.308966 -245.474744)
		(width 0.0889)
		(layer "In2.Cu")
		(net "M_C_CPU1_SA_CB<1>")
	)
	(segment
		(start 76.308966 -245.474744)
		(end 77.722222 -245.474744)
		(width 0.0889)
		(layer "In2.Cu")
		(net "M_C_CPU1_SA_CB<1>")
	)
	(segment
		(start 47.347886 -236.860334)
		(end 48.206152 -236.860334)
		(width 0.14478)
		(layer "In2.Cu")
		(net "M_C_CPU1_SA_CB<1>")
	)
	(segment
		(start 84.229702 -245.62181)
		(end 84.238084 -245.616984)
		(width 0.0889)
		(layer "In2.Cu")
		(net "M_C_CPU1_SA_CB<1>")
	)
	(segment
		(start 54.191408 -236.860334)
		(end 54.354476 -236.697266)
		(width 0.14478)
		(layer "In2.Cu")
		(net "M_C_CPU1_SA_CB<1>")
	)
	(segment
		(start 51.345846 -235.782612)
		(end 51.345846 -235.847382)
		(width 0.14478)
		(layer "In2.Cu")
		(net "M_C_CPU1_SA_CB<1>")
	)
	(segment
		(start 87.989664 -245.62181)
		(end 87.998046 -245.616984)
		(width 0.0889)
		(layer "In2.Cu")
		(net "M_C_CPU1_SA_CB<1>")
	)
	(segment
		(start 44.340018 -236.435392)
		(end 44.76496 -236.860334)
		(width 0.14478)
		(layer "In2.Cu")
		(net "M_C_CPU1_SA_CB<1>")
	)
	(segment
		(start 45.515276 -236.643672)
		(end 45.678344 -236.480604)
		(width 0.14478)
		(layer "In2.Cu")
		(net "M_C_CPU1_SA_CB<1>")
	)
	(segment
		(start 58.330338 -235.847382)
		(end 58.330338 -235.790232)
		(width 0.14478)
		(layer "In2.Cu")
		(net "M_C_CPU1_SA_CB<1>")
	)
	(segment
		(start 58.723784 -235.627164)
		(end 58.886852 -235.790232)
		(width 0.14478)
		(layer "In2.Cu")
		(net "M_C_CPU1_SA_CB<1>")
	)
	(segment
		(start 48.206152 -236.860334)
		(end 48.50384 -236.562646)
		(width 0.14478)
		(layer "In2.Cu")
		(net "M_C_CPU1_SA_CB<1>")
	)
	(segment
		(start 91.749626 -245.62181)
		(end 91.758008 -245.616984)
		(width 0.0889)
		(layer "In2.Cu")
		(net "M_C_CPU1_SA_CB<1>")
	)
	(segment
		(start 83.289648 -245.62181)
		(end 83.29803 -245.616984)
		(width 0.0889)
		(layer "In2.Cu")
		(net "M_C_CPU1_SA_CB<1>")
	)
	(segment
		(start 49.055274 -236.860334)
		(end 49.427384 -236.860334)
		(width 0.14478)
		(layer "In2.Cu")
		(net "M_C_CPU1_SA_CB<1>")
	)
	(segment
		(start 60.532518 -236.01045)
		(end 61.899546 -237.377478)
		(width 0.14478)
		(layer "In2.Cu")
		(net "M_C_CPU1_SA_CB<1>")
	)
	(segment
		(start 58.886852 -235.847382)
		(end 59.04992 -236.01045)
		(width 0.14478)
		(layer "In2.Cu")
		(net "M_C_CPU1_SA_CB<1>")
	)
	(segment
		(start 48.757586 -236.562646)
		(end 49.055274 -236.860334)
		(width 0.14478)
		(layer "In2.Cu")
		(net "M_C_CPU1_SA_CB<1>")
	)
	(segment
		(start 58.886852 -235.790232)
		(end 58.886852 -235.847382)
		(width 0.14478)
		(layer "In2.Cu")
		(net "M_C_CPU1_SA_CB<1>")
	)
	(segment
		(start 54.354476 -236.697266)
		(end 54.354476 -236.630972)
		(width 0.14478)
		(layer "In2.Cu")
		(net "M_C_CPU1_SA_CB<1>")
	)
	(segment
		(start 58.330338 -235.790232)
		(end 58.493406 -235.627164)
		(width 0.14478)
		(layer "In2.Cu")
		(net "M_C_CPU1_SA_CB<1>")
	)
	(segment
		(start 66.99758 -241.385344)
		(end 70.3072 -244.694964)
		(width 0.14478)
		(layer "In2.Cu")
		(net "M_C_CPU1_SA_CB<1>")
	)
	(segment
		(start 46.628304 -237.026196)
		(end 46.628304 -236.643672)
		(width 0.14478)
		(layer "In2.Cu")
		(net "M_C_CPU1_SA_CB<1>")
	)
	(segment
		(start 79.5401 -245.61673)
		(end 79.566262 -245.601744)
		(width 0.0889)
		(layer "In2.Cu")
		(net "M_C_CPU1_SA_CB<1>")
	)
	(segment
		(start 46.791372 -236.480604)
		(end 47.02175 -236.480604)
		(width 0.14478)
		(layer "In2.Cu")
		(net "M_C_CPU1_SA_CB<1>")
	)
	(segment
		(start 56.690006 -236.860334)
		(end 56.950864 -236.860334)
		(width 0.14478)
		(layer "In2.Cu")
		(net "M_C_CPU1_SA_CB<1>")
	)
	(segment
		(start 54.747922 -236.467904)
		(end 54.91099 -236.630972)
		(width 0.14478)
		(layer "In2.Cu")
		(net "M_C_CPU1_SA_CB<1>")
	)
	(segment
		(start 45.352208 -236.860334)
		(end 45.515276 -236.697266)
		(width 0.14478)
		(layer "In2.Cu")
		(net "M_C_CPU1_SA_CB<1>")
	)
	(segment
		(start 56.133492 -236.472984)
		(end 56.36387 -236.472984)
		(width 0.14478)
		(layer "In2.Cu")
		(net "M_C_CPU1_SA_CB<1>")
	)
	(segment
		(start 46.07179 -236.643672)
		(end 46.07179 -237.026196)
		(width 0.14478)
		(layer "In2.Cu")
		(net "M_C_CPU1_SA_CB<1>")
	)
	(segment
		(start 56.526938 -236.636052)
		(end 56.526938 -236.697266)
		(width 0.14478)
		(layer "In2.Cu")
		(net "M_C_CPU1_SA_CB<1>")
	)
	(segment
		(start 46.628304 -236.643672)
		(end 46.791372 -236.480604)
		(width 0.14478)
		(layer "In2.Cu")
		(net "M_C_CPU1_SA_CB<1>")
	)
	(segment
		(start 95.462598 -245.643146)
		(end 95.48495 -245.559834)
		(width 0.0889)
		(layer "In2.Cu")
		(net "M_C_CPU1_SA_CB<1>")
	)
	(segment
		(start 70.3072 -244.694964)
		(end 75.529186 -244.694964)
		(width 0.14478)
		(layer "In2.Cu")
		(net "M_C_CPU1_SA_CB<1>")
	)
	(segment
		(start 79.518256 -245.629176)
		(end 79.5401 -245.61673)
		(width 0.0889)
		(layer "In2.Cu")
		(net "M_C_CPU1_SA_CB<1>")
	)
	(segment
		(start 59.04992 -236.01045)
		(end 60.532518 -236.01045)
		(width 0.14478)
		(layer "In2.Cu")
		(net "M_C_CPU1_SA_CB<1>")
	)
	(segment
		(start 46.465236 -237.189264)
		(end 46.628304 -237.026196)
		(width 0.14478)
		(layer "In2.Cu")
		(net "M_C_CPU1_SA_CB<1>")
	)
	(segment
		(start 58.16727 -236.01045)
		(end 58.330338 -235.847382)
		(width 0.14478)
		(layer "In2.Cu")
		(net "M_C_CPU1_SA_CB<1>")
	)
	(segment
		(start 47.184818 -236.643672)
		(end 47.184818 -236.697266)
		(width 0.14478)
		(layer "In2.Cu")
		(net "M_C_CPU1_SA_CB<1>")
	)
	(segment
		(start 44.76496 -236.860334)
		(end 45.352208 -236.860334)
		(width 0.14478)
		(layer "In2.Cu")
		(net "M_C_CPU1_SA_CB<1>")
	)
	(segment
		(start 57.800748 -236.01045)
		(end 58.16727 -236.01045)
		(width 0.14478)
		(layer "In2.Cu")
		(net "M_C_CPU1_SA_CB<1>")
	)
	(segment
		(start 92.68968 -245.62181)
		(end 92.698062 -245.616984)
		(width 0.0889)
		(layer "In2.Cu")
		(net "M_C_CPU1_SA_CB<1>")
	)
	(segment
		(start 58.493406 -235.627164)
		(end 58.723784 -235.627164)
		(width 0.14478)
		(layer "In2.Cu")
		(net "M_C_CPU1_SA_CB<1>")
	)
	(segment
		(start 48.50384 -236.562646)
		(end 48.757586 -236.562646)
		(width 0.14478)
		(layer "In2.Cu")
		(net "M_C_CPU1_SA_CB<1>")
	)
	(segment
		(start 51.345846 -235.847382)
		(end 51.508914 -236.01045)
		(width 0.14478)
		(layer "In2.Cu")
		(net "M_C_CPU1_SA_CB<1>")
	)
	(segment
		(start 47.184818 -236.697266)
		(end 47.347886 -236.860334)
		(width 0.14478)
		(layer "In2.Cu")
		(net "M_C_CPU1_SA_CB<1>")
	)
	(segment
		(start 54.354476 -236.630972)
		(end 54.517544 -236.467904)
		(width 0.14478)
		(layer "In2.Cu")
		(net "M_C_CPU1_SA_CB<1>")
	)
	(segment
		(start 45.515276 -236.697266)
		(end 45.515276 -236.643672)
		(width 0.14478)
		(layer "In2.Cu")
		(net "M_C_CPU1_SA_CB<1>")
	)
	(segment
		(start 56.36387 -236.472984)
		(end 56.526938 -236.636052)
		(width 0.14478)
		(layer "In2.Cu")
		(net "M_C_CPU1_SA_CB<1>")
	)
	(segment
		(start 75.529186 -244.694964)
		(end 76.150216 -245.315994)
		(width 0.14478)
		(layer "In2.Cu")
		(net "M_C_CPU1_SA_CB<1>")
	)
	(segment
		(start 80.46974 -245.62181)
		(end 80.478122 -245.616984)
		(width 0.0889)
		(layer "In2.Cu")
		(net "M_C_CPU1_SA_CB<1>")
	)
	(segment
		(start 54.91099 -236.697266)
		(end 55.074058 -236.860334)
		(width 0.14478)
		(layer "In2.Cu")
		(net "M_C_CPU1_SA_CB<1>")
	)
	(segment
		(start 50.277268 -236.01045)
		(end 50.626264 -236.01045)
		(width 0.14478)
		(layer "In2.Cu")
		(net "M_C_CPU1_SA_CB<1>")
	)
	(segment
		(start 45.678344 -236.480604)
		(end 45.908722 -236.480604)
		(width 0.14478)
		(layer "In2.Cu")
		(net "M_C_CPU1_SA_CB<1>")
	)
	(segment
		(start 56.526938 -236.697266)
		(end 56.690006 -236.860334)
		(width 0.14478)
		(layer "In2.Cu")
		(net "M_C_CPU1_SA_CB<1>")
	)
	(segment
		(start 93.263974 -245.616984)
		(end 93.272356 -245.62181)
		(width 0.0889)
		(layer "In2.Cu")
		(net "M_C_CPU1_SA_CB<1>")
	)
	(segment
		(start 45.908722 -236.480604)
		(end 46.07179 -236.643672)
		(width 0.14478)
		(layer "In2.Cu")
		(net "M_C_CPU1_SA_CB<1>")
	)
	(segment
		(start 85.74405 -245.616984)
		(end 85.752432 -245.62181)
		(width 0.0889)
		(layer "In2.Cu")
		(net "M_C_CPU1_SA_CB<1>")
	)
	(segment
		(start 50.626264 -236.01045)
		(end 50.789332 -235.847382)
		(width 0.14478)
		(layer "In2.Cu")
		(net "M_C_CPU1_SA_CB<1>")
	)
	(segment
		(start 53.952648 -236.860334)
		(end 54.191408 -236.860334)
		(width 0.14478)
		(layer "In2.Cu")
		(net "M_C_CPU1_SA_CB<1>")
	)
	(segment
		(start 50.9524 -235.619544)
		(end 51.182778 -235.619544)
		(width 0.14478)
		(layer "In2.Cu")
		(net "M_C_CPU1_SA_CB<1>")
	)
	(segment
		(start 78.22565 -245.61673)
		(end 78.256892 -245.63451)
		(width 0.0889)
		(layer "In2.Cu")
		(net "M_C_CPU1_SA_CB<1>")
	)
	(segment
		(start 79.138018 -245.599712)
		(end 79.167482 -245.616984)
		(width 0.0889)
		(layer "In2.Cu")
		(net "M_C_CPU1_SA_CB<1>")
	)
	(segment
		(start 61.899546 -237.910624)
		(end 65.374266 -241.385344)
		(width 0.14478)
		(layer "In2.Cu")
		(net "M_C_CPU1_SA_CB<1>")
	)
	(segment
		(start 88.929718 -245.62181)
		(end 88.9381 -245.616984)
		(width 0.0889)
		(layer "In2.Cu")
		(net "M_C_CPU1_SA_CB<1>")
	)
	(segment
		(start 56.950864 -236.860334)
		(end 57.800748 -236.01045)
		(width 0.14478)
		(layer "In2.Cu")
		(net "M_C_CPU1_SA_CB<1>")
	)
	(segment
		(start 55.807356 -236.860334)
		(end 55.970424 -236.697266)
		(width 0.14478)
		(layer "In2.Cu")
		(net "M_C_CPU1_SA_CB<1>")
	)
	(segment
		(start 55.970424 -236.697266)
		(end 55.970424 -236.636052)
		(width 0.14478)
		(layer "In2.Cu")
		(net "M_C_CPU1_SA_CB<1>")
	)
	(segment
		(start 78.199488 -245.601744)
		(end 78.22565 -245.61673)
		(width 0.0889)
		(layer "In2.Cu")
		(net "M_C_CPU1_SA_CB<1>")
	)
	(segment
		(start 84.803996 -245.616984)
		(end 84.812378 -245.62181)
		(width 0.0889)
		(layer "In2.Cu")
		(net "M_C_CPU1_SA_CB<1>")
	)
	(segment
		(start 61.899546 -237.377478)
		(end 61.899546 -237.910624)
		(width 0.14478)
		(layer "In2.Cu")
		(net "M_C_CPU1_SA_CB<1>")
	)
	(segment
		(start 89.504012 -245.616984)
		(end 89.512394 -245.62181)
		(width 0.0889)
		(layer "In2.Cu")
		(net "M_C_CPU1_SA_CB<1>")
	)
	(arc
		(start 78.599538 -245.616984)
		(mid 78.866595 -245.539949)
		(end 79.138018 -245.599712)
		(width 0.0889)
		(layer "In2.Cu")
		(net "M_C_CPU1_SA_CB<1>")
	)
	(arc
		(start 86.684104 -245.616984)
		(mid 86.871048 -245.667239)
		(end 87.057992 -245.616984)
		(width 0.0889)
		(layer "In2.Cu")
		(net "M_C_CPU1_SA_CB<1>")
	)
	(arc
		(start 82.357976 -245.616984)
		(mid 82.640932 -245.540807)
		(end 82.923888 -245.616984)
		(width 0.0889)
		(layer "In2.Cu")
		(net "M_C_CPU1_SA_CB<1>")
	)
	(arc
		(start 89.512394 -245.62181)
		(mid 89.695902 -245.667304)
		(end 89.878154 -245.616984)
		(width 0.0889)
		(layer "In2.Cu")
		(net "M_C_CPU1_SA_CB<1>")
	)
	(arc
		(start 81.984088 -245.616984)
		(mid 82.171032 -245.667239)
		(end 82.357976 -245.616984)
		(width 0.0889)
		(layer "In2.Cu")
		(net "M_C_CPU1_SA_CB<1>")
	)
	(arc
		(start 94.57817 -245.616984)
		(mid 94.861126 -245.540807)
		(end 95.144082 -245.616984)
		(width 0.0889)
		(layer "In2.Cu")
		(net "M_C_CPU1_SA_CB<1>")
	)
	(arc
		(start 81.418176 -245.616984)
		(mid 81.701132 -245.540807)
		(end 81.984088 -245.616984)
		(width 0.0889)
		(layer "In2.Cu")
		(net "M_C_CPU1_SA_CB<1>")
	)
	(arc
		(start 87.998046 -245.616984)
		(mid 88.281002 -245.540807)
		(end 88.563958 -245.616984)
		(width 0.0889)
		(layer "In2.Cu")
		(net "M_C_CPU1_SA_CB<1>")
	)
	(arc
		(start 90.817954 -245.616984)
		(mid 91.10091 -245.540807)
		(end 91.383866 -245.616984)
		(width 0.0889)
		(layer "In2.Cu")
		(net "M_C_CPU1_SA_CB<1>")
	)
	(arc
		(start 80.10398 -245.616984)
		(mid 80.286231 -245.667334)
		(end 80.46974 -245.62181)
		(width 0.0889)
		(layer "In2.Cu")
		(net "M_C_CPU1_SA_CB<1>")
	)
	(arc
		(start 88.563958 -245.616984)
		(mid 88.746209 -245.667334)
		(end 88.929718 -245.62181)
		(width 0.0889)
		(layer "In2.Cu")
		(net "M_C_CPU1_SA_CB<1>")
	)
	(arc
		(start 81.052416 -245.62181)
		(mid 81.235924 -245.667304)
		(end 81.418176 -245.616984)
		(width 0.0889)
		(layer "In2.Cu")
		(net "M_C_CPU1_SA_CB<1>")
	)
	(arc
		(start 83.863942 -245.616984)
		(mid 84.046193 -245.667334)
		(end 84.229702 -245.62181)
		(width 0.0889)
		(layer "In2.Cu")
		(net "M_C_CPU1_SA_CB<1>")
	)
	(arc
		(start 91.758008 -245.616984)
		(mid 92.040964 -245.540807)
		(end 92.32392 -245.616984)
		(width 0.0889)
		(layer "In2.Cu")
		(net "M_C_CPU1_SA_CB<1>")
	)
	(arc
		(start 91.383866 -245.616984)
		(mid 91.566117 -245.667334)
		(end 91.749626 -245.62181)
		(width 0.0889)
		(layer "In2.Cu")
		(net "M_C_CPU1_SA_CB<1>")
	)
	(arc
		(start 88.9381 -245.616984)
		(mid 89.221056 -245.540807)
		(end 89.504012 -245.616984)
		(width 0.0889)
		(layer "In2.Cu")
		(net "M_C_CPU1_SA_CB<1>")
	)
	(arc
		(start 95.144082 -245.616984)
		(mid 95.300401 -245.665979)
		(end 95.462598 -245.643146)
		(width 0.0889)
		(layer "In2.Cu")
		(net "M_C_CPU1_SA_CB<1>")
	)
	(arc
		(start 85.752432 -245.62181)
		(mid 85.93594 -245.667304)
		(end 86.118192 -245.616984)
		(width 0.0889)
		(layer "In2.Cu")
		(net "M_C_CPU1_SA_CB<1>")
	)
	(arc
		(start 80.478122 -245.616984)
		(mid 80.761078 -245.540807)
		(end 81.044034 -245.616984)
		(width 0.0889)
		(layer "In2.Cu")
		(net "M_C_CPU1_SA_CB<1>")
	)
	(arc
		(start 86.118192 -245.616984)
		(mid 86.401148 -245.540807)
		(end 86.684104 -245.616984)
		(width 0.0889)
		(layer "In2.Cu")
		(net "M_C_CPU1_SA_CB<1>")
	)
	(arc
		(start 92.32392 -245.616984)
		(mid 92.506171 -245.667334)
		(end 92.68968 -245.62181)
		(width 0.0889)
		(layer "In2.Cu")
		(net "M_C_CPU1_SA_CB<1>")
	)
	(arc
		(start 84.238084 -245.616984)
		(mid 84.52104 -245.540807)
		(end 84.803996 -245.616984)
		(width 0.0889)
		(layer "In2.Cu")
		(net "M_C_CPU1_SA_CB<1>")
	)
	(arc
		(start 77.722222 -245.474744)
		(mid 77.969156 -245.507042)
		(end 78.199488 -245.601744)
		(width 0.0889)
		(layer "In2.Cu")
		(net "M_C_CPU1_SA_CB<1>")
	)
	(arc
		(start 83.29803 -245.616984)
		(mid 83.580986 -245.540807)
		(end 83.863942 -245.616984)
		(width 0.0889)
		(layer "In2.Cu")
		(net "M_C_CPU1_SA_CB<1>")
	)
	(arc
		(start 84.812378 -245.62181)
		(mid 84.995886 -245.667304)
		(end 85.178138 -245.616984)
		(width 0.0889)
		(layer "In2.Cu")
		(net "M_C_CPU1_SA_CB<1>")
	)
	(arc
		(start 92.698062 -245.616984)
		(mid 92.981018 -245.540807)
		(end 93.263974 -245.616984)
		(width 0.0889)
		(layer "In2.Cu")
		(net "M_C_CPU1_SA_CB<1>")
	)
	(arc
		(start 79.167482 -245.616984)
		(mid 79.341332 -245.66689)
		(end 79.518256 -245.629176)
		(width 0.0889)
		(layer "In2.Cu")
		(net "M_C_CPU1_SA_CB<1>")
	)
	(arc
		(start 79.566262 -245.601744)
		(mid 79.837048 -245.541098)
		(end 80.10398 -245.616984)
		(width 0.0889)
		(layer "In2.Cu")
		(net "M_C_CPU1_SA_CB<1>")
	)
	(arc
		(start 93.638116 -245.616984)
		(mid 93.921072 -245.540807)
		(end 94.204028 -245.616984)
		(width 0.0889)
		(layer "In2.Cu")
		(net "M_C_CPU1_SA_CB<1>")
	)
	(arc
		(start 90.444066 -245.616984)
		(mid 90.63101 -245.667239)
		(end 90.817954 -245.616984)
		(width 0.0889)
		(layer "In2.Cu")
		(net "M_C_CPU1_SA_CB<1>")
	)
	(arc
		(start 82.923888 -245.616984)
		(mid 83.106139 -245.667334)
		(end 83.289648 -245.62181)
		(width 0.0889)
		(layer "In2.Cu")
		(net "M_C_CPU1_SA_CB<1>")
	)
	(arc
		(start 93.272356 -245.62181)
		(mid 93.455864 -245.667304)
		(end 93.638116 -245.616984)
		(width 0.0889)
		(layer "In2.Cu")
		(net "M_C_CPU1_SA_CB<1>")
	)
	(arc
		(start 89.878154 -245.616984)
		(mid 90.16111 -245.540807)
		(end 90.444066 -245.616984)
		(width 0.0889)
		(layer "In2.Cu")
		(net "M_C_CPU1_SA_CB<1>")
	)
	(arc
		(start 85.178138 -245.616984)
		(mid 85.461094 -245.540807)
		(end 85.74405 -245.616984)
		(width 0.0889)
		(layer "In2.Cu")
		(net "M_C_CPU1_SA_CB<1>")
	)
	(arc
		(start 94.21241 -245.62181)
		(mid 94.395918 -245.667304)
		(end 94.57817 -245.616984)
		(width 0.0889)
		(layer "In2.Cu")
		(net "M_C_CPU1_SA_CB<1>")
	)
	(arc
		(start 87.623904 -245.616984)
		(mid 87.806155 -245.667334)
		(end 87.989664 -245.62181)
		(width 0.0889)
		(layer "In2.Cu")
		(net "M_C_CPU1_SA_CB<1>")
	)
	(arc
		(start 78.256892 -245.63451)
		(mid 78.430354 -245.667444)
		(end 78.599538 -245.616984)
		(width 0.0889)
		(layer "In2.Cu")
		(net "M_C_CPU1_SA_CB<1>")
	)
	(arc
		(start 87.057992 -245.616984)
		(mid 87.340948 -245.540807)
		(end 87.623904 -245.616984)
		(width 0.0889)
		(layer "In2.Cu")
		(net "M_C_CPU1_SA_CB<1>")
	)
	(segment
		(start 94.387924 -244.750336)
		(end 93.921072 -244.484398)
		(width 0.10668)
		(layer "F.Cu")
		(net "M_C_CPU1_SA_CB<0>")
	)
	(segment
		(start 55.843932 -235.160312)
		(end 56.125618 -234.878626)
		(width 0.14478)
		(layer "In2.Cu")
		(net "M_C_CPU1_SA_CB<0>")
	)
	(segment
		(start 63.982854 -238.619792)
		(end 64.145922 -238.78286)
		(width 0.14478)
		(layer "In2.Cu")
		(net "M_C_CPU1_SA_CB<0>")
	)
	(segment
		(start 54.703218 -234.904026)
		(end 54.959504 -235.160312)
		(width 0.14478)
		(layer "In2.Cu")
		(net "M_C_CPU1_SA_CB<0>")
	)
	(segment
		(start 58.79465 -234.016804)
		(end 59.088274 -234.310428)
		(width 0.14478)
		(layer "In2.Cu")
		(net "M_C_CPU1_SA_CB<0>")
	)
	(segment
		(start 46.204124 -235.538264)
		(end 46.434502 -235.538264)
		(width 0.14478)
		(layer "In2.Cu")
		(net "M_C_CPU1_SA_CB<0>")
	)
	(segment
		(start 60.299346 -234.310428)
		(end 62.899036 -236.910118)
		(width 0.14478)
		(layer "In2.Cu")
		(net "M_C_CPU1_SA_CB<0>")
	)
	(segment
		(start 76.481686 -244.372384)
		(end 77.045566 -244.372384)
		(width 0.0889)
		(layer "In2.Cu")
		(net "M_C_CPU1_SA_CB<0>")
	)
	(segment
		(start 51.282092 -234.310428)
		(end 53.102764 -234.310428)
		(width 0.14478)
		(layer "In2.Cu")
		(net "M_C_CPU1_SA_CB<0>")
	)
	(segment
		(start 79.067152 -244.806978)
		(end 79.081884 -244.798342)
		(width 0.0889)
		(layer "In2.Cu")
		(net "M_C_CPU1_SA_CB<0>")
	)
	(segment
		(start 83.394042 -244.806978)
		(end 83.402424 -244.811804)
		(width 0.0889)
		(layer "In2.Cu")
		(net "M_C_CPU1_SA_CB<0>")
	)
	(segment
		(start 65.320672 -239.413542)
		(end 65.551304 -239.413542)
		(width 0.14478)
		(layer "In2.Cu")
		(net "M_C_CPU1_SA_CB<0>")
	)
	(segment
		(start 62.899036 -237.535974)
		(end 63.358522 -237.99546)
		(width 0.14478)
		(layer "In2.Cu")
		(net "M_C_CPU1_SA_CB<0>")
	)
	(segment
		(start 45.877988 -234.880404)
		(end 46.041056 -235.043472)
		(width 0.14478)
		(layer "In2.Cu")
		(net "M_C_CPU1_SA_CB<0>")
	)
	(segment
		(start 78.67777 -244.79758)
		(end 78.693518 -244.806724)
		(width 0.0889)
		(layer "In2.Cu")
		(net "M_C_CPU1_SA_CB<0>")
	)
	(segment
		(start 63.589154 -237.99546)
		(end 63.745872 -237.838742)
		(width 0.14478)
		(layer "In2.Cu")
		(net "M_C_CPU1_SA_CB<0>")
	)
	(segment
		(start 64.376554 -238.78286)
		(end 64.533272 -238.626142)
		(width 0.14478)
		(layer "In2.Cu")
		(net "M_C_CPU1_SA_CB<0>")
	)
	(segment
		(start 63.982854 -238.38916)
		(end 63.982854 -238.619792)
		(width 0.14478)
		(layer "In2.Cu")
		(net "M_C_CPU1_SA_CB<0>")
	)
	(segment
		(start 56.125618 -234.878626)
		(end 56.395366 -234.878626)
		(width 0.14478)
		(layer "In2.Cu")
		(net "M_C_CPU1_SA_CB<0>")
	)
	(segment
		(start 67.345306 -240.430304)
		(end 70.695566 -243.780564)
		(width 0.14478)
		(layer "In2.Cu")
		(net "M_C_CPU1_SA_CB<0>")
	)
	(segment
		(start 45.484542 -235.375196)
		(end 45.484542 -235.043472)
		(width 0.14478)
		(layer "In2.Cu")
		(net "M_C_CPU1_SA_CB<0>")
	)
	(segment
		(start 94.074996 -244.749828)
		(end 93.921072 -244.484398)
		(width 0.0889)
		(layer "In2.Cu")
		(net "M_C_CPU1_SA_CB<0>")
	)
	(segment
		(start 94.052644 -244.83314)
		(end 94.074996 -244.749828)
		(width 0.0889)
		(layer "In2.Cu")
		(net "M_C_CPU1_SA_CB<0>")
	)
	(segment
		(start 78.693518 -244.806724)
		(end 78.707234 -244.814598)
		(width 0.0889)
		(layer "In2.Cu")
		(net "M_C_CPU1_SA_CB<0>")
	)
	(segment
		(start 63.976504 -237.838742)
		(end 64.139572 -238.00181)
		(width 0.14478)
		(layer "In2.Cu")
		(net "M_C_CPU1_SA_CB<0>")
	)
	(segment
		(start 49.006252 -234.895644)
		(end 49.27092 -235.160312)
		(width 0.14478)
		(layer "In2.Cu")
		(net "M_C_CPU1_SA_CB<0>")
	)
	(segment
		(start 65.714372 -239.807242)
		(end 65.557654 -239.96396)
		(width 0.14478)
		(layer "In2.Cu")
		(net "M_C_CPU1_SA_CB<0>")
	)
	(segment
		(start 77.524864 -244.851682)
		(end 77.961744 -244.851682)
		(width 0.0889)
		(layer "In2.Cu")
		(net "M_C_CPU1_SA_CB<0>")
	)
	(segment
		(start 79.99984 -244.811804)
		(end 80.008222 -244.806978)
		(width 0.0889)
		(layer "In2.Cu")
		(net "M_C_CPU1_SA_CB<0>")
	)
	(segment
		(start 62.899036 -236.910118)
		(end 62.899036 -237.535974)
		(width 0.14478)
		(layer "In2.Cu")
		(net "M_C_CPU1_SA_CB<0>")
	)
	(segment
		(start 50.730658 -234.045506)
		(end 51.01717 -234.045506)
		(width 0.14478)
		(layer "In2.Cu")
		(net "M_C_CPU1_SA_CB<0>")
	)
	(segment
		(start 64.933322 -239.57026)
		(end 65.163954 -239.57026)
		(width 0.14478)
		(layer "In2.Cu")
		(net "M_C_CPU1_SA_CB<0>")
	)
	(segment
		(start 54.959504 -235.160312)
		(end 55.843932 -235.160312)
		(width 0.14478)
		(layer "In2.Cu")
		(net "M_C_CPU1_SA_CB<0>")
	)
	(segment
		(start 63.358522 -237.99546)
		(end 63.589154 -237.99546)
		(width 0.14478)
		(layer "In2.Cu")
		(net "M_C_CPU1_SA_CB<0>")
	)
	(segment
		(start 45.321474 -235.538264)
		(end 45.484542 -235.375196)
		(width 0.14478)
		(layer "In2.Cu")
		(net "M_C_CPU1_SA_CB<0>")
	)
	(segment
		(start 46.59757 -235.375196)
		(end 46.59757 -235.32338)
		(width 0.14478)
		(layer "In2.Cu")
		(net "M_C_CPU1_SA_CB<0>")
	)
	(segment
		(start 64.926972 -238.78921)
		(end 64.926972 -239.019842)
		(width 0.14478)
		(layer "In2.Cu")
		(net "M_C_CPU1_SA_CB<0>")
	)
	(segment
		(start 44.928028 -235.375196)
		(end 45.091096 -235.538264)
		(width 0.14478)
		(layer "In2.Cu")
		(net "M_C_CPU1_SA_CB<0>")
	)
	(segment
		(start 91.85402 -244.806978)
		(end 91.862402 -244.811804)
		(width 0.0889)
		(layer "In2.Cu")
		(net "M_C_CPU1_SA_CB<0>")
	)
	(segment
		(start 65.551304 -239.413542)
		(end 65.714372 -239.57661)
		(width 0.14478)
		(layer "In2.Cu")
		(net "M_C_CPU1_SA_CB<0>")
	)
	(segment
		(start 65.714372 -239.57661)
		(end 65.714372 -239.807242)
		(width 0.14478)
		(layer "In2.Cu")
		(net "M_C_CPU1_SA_CB<0>")
	)
	(segment
		(start 46.041056 -235.043472)
		(end 46.041056 -235.375196)
		(width 0.14478)
		(layer "In2.Cu")
		(net "M_C_CPU1_SA_CB<0>")
	)
	(segment
		(start 81.879694 -244.811804)
		(end 81.888076 -244.806978)
		(width 0.0889)
		(layer "In2.Cu")
		(net "M_C_CPU1_SA_CB<0>")
	)
	(segment
		(start 58.53176 -234.016804)
		(end 58.79465 -234.016804)
		(width 0.14478)
		(layer "In2.Cu")
		(net "M_C_CPU1_SA_CB<0>")
	)
	(segment
		(start 56.950864 -235.160312)
		(end 57.800748 -234.310428)
		(width 0.14478)
		(layer "In2.Cu")
		(net "M_C_CPU1_SA_CB<0>")
	)
	(segment
		(start 88.094058 -244.806978)
		(end 88.10244 -244.811804)
		(width 0.0889)
		(layer "In2.Cu")
		(net "M_C_CPU1_SA_CB<0>")
	)
	(segment
		(start 50.465736 -234.310428)
		(end 50.730658 -234.045506)
		(width 0.14478)
		(layer "In2.Cu")
		(net "M_C_CPU1_SA_CB<0>")
	)
	(segment
		(start 64.770254 -239.407192)
		(end 64.933322 -239.57026)
		(width 0.14478)
		(layer "In2.Cu")
		(net "M_C_CPU1_SA_CB<0>")
	)
	(segment
		(start 49.27092 -235.160312)
		(end 49.427384 -235.160312)
		(width 0.14478)
		(layer "In2.Cu")
		(net "M_C_CPU1_SA_CB<0>")
	)
	(segment
		(start 64.533272 -238.626142)
		(end 64.763904 -238.626142)
		(width 0.14478)
		(layer "In2.Cu")
		(net "M_C_CPU1_SA_CB<0>")
	)
	(segment
		(start 64.770254 -239.17656)
		(end 64.770254 -239.407192)
		(width 0.14478)
		(layer "In2.Cu")
		(net "M_C_CPU1_SA_CB<0>")
	)
	(segment
		(start 64.145922 -238.78286)
		(end 64.376554 -238.78286)
		(width 0.14478)
		(layer "In2.Cu")
		(net "M_C_CPU1_SA_CB<0>")
	)
	(segment
		(start 56.395366 -234.878626)
		(end 56.677052 -235.160312)
		(width 0.14478)
		(layer "In2.Cu")
		(net "M_C_CPU1_SA_CB<0>")
	)
	(segment
		(start 58.238136 -234.310428)
		(end 58.53176 -234.016804)
		(width 0.14478)
		(layer "In2.Cu")
		(net "M_C_CPU1_SA_CB<0>")
	)
	(segment
		(start 57.800748 -234.310428)
		(end 58.238136 -234.310428)
		(width 0.14478)
		(layer "In2.Cu")
		(net "M_C_CPU1_SA_CB<0>")
	)
	(segment
		(start 46.760638 -235.160312)
		(end 48.449738 -235.160312)
		(width 0.14478)
		(layer "In2.Cu")
		(net "M_C_CPU1_SA_CB<0>")
	)
	(segment
		(start 75.889866 -243.780564)
		(end 76.481686 -244.372384)
		(width 0.0889)
		(layer "In2.Cu")
		(net "M_C_CPU1_SA_CB<0>")
	)
	(segment
		(start 90.913966 -244.806978)
		(end 90.922348 -244.811804)
		(width 0.0889)
		(layer "In2.Cu")
		(net "M_C_CPU1_SA_CB<0>")
	)
	(segment
		(start 63.745872 -237.838742)
		(end 63.976504 -237.838742)
		(width 0.14478)
		(layer "In2.Cu")
		(net "M_C_CPU1_SA_CB<0>")
	)
	(segment
		(start 65.557654 -239.96396)
		(end 65.557654 -240.194592)
		(width 0.14478)
		(layer "In2.Cu")
		(net "M_C_CPU1_SA_CB<0>")
	)
	(segment
		(start 90.339672 -244.811804)
		(end 90.348054 -244.806978)
		(width 0.0889)
		(layer "In2.Cu")
		(net "M_C_CPU1_SA_CB<0>")
	)
	(segment
		(start 85.639656 -244.811804)
		(end 85.648038 -244.806978)
		(width 0.0889)
		(layer "In2.Cu")
		(net "M_C_CPU1_SA_CB<0>")
	)
	(segment
		(start 46.434502 -235.538264)
		(end 46.59757 -235.375196)
		(width 0.14478)
		(layer "In2.Cu")
		(net "M_C_CPU1_SA_CB<0>")
	)
	(segment
		(start 53.102764 -234.310428)
		(end 53.952648 -235.160312)
		(width 0.14478)
		(layer "In2.Cu")
		(net "M_C_CPU1_SA_CB<0>")
	)
	(segment
		(start 65.163954 -239.57026)
		(end 65.320672 -239.413542)
		(width 0.14478)
		(layer "In2.Cu")
		(net "M_C_CPU1_SA_CB<0>")
	)
	(segment
		(start 44.928028 -235.32338)
		(end 44.928028 -235.375196)
		(width 0.14478)
		(layer "In2.Cu")
		(net "M_C_CPU1_SA_CB<0>")
	)
	(segment
		(start 45.091096 -235.538264)
		(end 45.321474 -235.538264)
		(width 0.14478)
		(layer "In2.Cu")
		(net "M_C_CPU1_SA_CB<0>")
	)
	(segment
		(start 46.041056 -235.375196)
		(end 46.204124 -235.538264)
		(width 0.14478)
		(layer "In2.Cu")
		(net "M_C_CPU1_SA_CB<0>")
	)
	(segment
		(start 53.952648 -235.160312)
		(end 54.151784 -235.160312)
		(width 0.14478)
		(layer "In2.Cu")
		(net "M_C_CPU1_SA_CB<0>")
	)
	(segment
		(start 49.427384 -235.160312)
		(end 50.277268 -234.310428)
		(width 0.14478)
		(layer "In2.Cu")
		(net "M_C_CPU1_SA_CB<0>")
	)
	(segment
		(start 86.57971 -244.811804)
		(end 86.588092 -244.806978)
		(width 0.0889)
		(layer "In2.Cu")
		(net "M_C_CPU1_SA_CB<0>")
	)
	(segment
		(start 65.557654 -240.194592)
		(end 65.793366 -240.430304)
		(width 0.14478)
		(layer "In2.Cu")
		(net "M_C_CPU1_SA_CB<0>")
	)
	(segment
		(start 50.277268 -234.310428)
		(end 50.465736 -234.310428)
		(width 0.14478)
		(layer "In2.Cu")
		(net "M_C_CPU1_SA_CB<0>")
	)
	(segment
		(start 51.01717 -234.045506)
		(end 51.282092 -234.310428)
		(width 0.14478)
		(layer "In2.Cu")
		(net "M_C_CPU1_SA_CB<0>")
	)
	(segment
		(start 65.793366 -240.430304)
		(end 67.345306 -240.430304)
		(width 0.14478)
		(layer "In2.Cu")
		(net "M_C_CPU1_SA_CB<0>")
	)
	(segment
		(start 70.695566 -243.780564)
		(end 75.889866 -243.780564)
		(width 0.14478)
		(layer "In2.Cu")
		(net "M_C_CPU1_SA_CB<0>")
	)
	(segment
		(start 64.139572 -238.00181)
		(end 64.139572 -238.232442)
		(width 0.14478)
		(layer "In2.Cu")
		(net "M_C_CPU1_SA_CB<0>")
	)
	(segment
		(start 45.484542 -235.043472)
		(end 45.64761 -234.880404)
		(width 0.14478)
		(layer "In2.Cu")
		(net "M_C_CPU1_SA_CB<0>")
	)
	(segment
		(start 48.449738 -235.160312)
		(end 48.714406 -234.895644)
		(width 0.14478)
		(layer "In2.Cu")
		(net "M_C_CPU1_SA_CB<0>")
	)
	(segment
		(start 54.40807 -234.904026)
		(end 54.703218 -234.904026)
		(width 0.14478)
		(layer "In2.Cu")
		(net "M_C_CPU1_SA_CB<0>")
	)
	(segment
		(start 45.64761 -234.880404)
		(end 45.877988 -234.880404)
		(width 0.14478)
		(layer "In2.Cu")
		(net "M_C_CPU1_SA_CB<0>")
	)
	(segment
		(start 64.926972 -239.019842)
		(end 64.770254 -239.17656)
		(width 0.14478)
		(layer "In2.Cu")
		(net "M_C_CPU1_SA_CB<0>")
	)
	(segment
		(start 77.045566 -244.372384)
		(end 77.524864 -244.851682)
		(width 0.0889)
		(layer "In2.Cu")
		(net "M_C_CPU1_SA_CB<0>")
	)
	(segment
		(start 56.677052 -235.160312)
		(end 56.950864 -235.160312)
		(width 0.14478)
		(layer "In2.Cu")
		(net "M_C_CPU1_SA_CB<0>")
	)
	(segment
		(start 64.763904 -238.626142)
		(end 64.926972 -238.78921)
		(width 0.14478)
		(layer "In2.Cu")
		(net "M_C_CPU1_SA_CB<0>")
	)
	(segment
		(start 44.340018 -234.73537)
		(end 44.928028 -235.32338)
		(width 0.14478)
		(layer "In2.Cu")
		(net "M_C_CPU1_SA_CB<0>")
	)
	(segment
		(start 54.151784 -235.160312)
		(end 54.40807 -234.904026)
		(width 0.14478)
		(layer "In2.Cu")
		(net "M_C_CPU1_SA_CB<0>")
	)
	(segment
		(start 46.59757 -235.32338)
		(end 46.760638 -235.160312)
		(width 0.14478)
		(layer "In2.Cu")
		(net "M_C_CPU1_SA_CB<0>")
	)
	(segment
		(start 64.139572 -238.232442)
		(end 63.982854 -238.38916)
		(width 0.14478)
		(layer "In2.Cu")
		(net "M_C_CPU1_SA_CB<0>")
	)
	(segment
		(start 48.714406 -234.895644)
		(end 49.006252 -234.895644)
		(width 0.14478)
		(layer "In2.Cu")
		(net "M_C_CPU1_SA_CB<0>")
	)
	(segment
		(start 82.453988 -244.806978)
		(end 82.46237 -244.811804)
		(width 0.0889)
		(layer "In2.Cu")
		(net "M_C_CPU1_SA_CB<0>")
	)
	(segment
		(start 87.154004 -244.806978)
		(end 87.162386 -244.811804)
		(width 0.0889)
		(layer "In2.Cu")
		(net "M_C_CPU1_SA_CB<0>")
	)
	(segment
		(start 59.088274 -234.310428)
		(end 60.299346 -234.310428)
		(width 0.14478)
		(layer "In2.Cu")
		(net "M_C_CPU1_SA_CB<0>")
	)
	(arc
		(start 83.768184 -244.806978)
		(mid 84.05114 -244.730801)
		(end 84.334096 -244.806978)
		(width 0.0889)
		(layer "In2.Cu")
		(net "M_C_CPU1_SA_CB<0>")
	)
	(arc
		(start 79.633572 -244.806978)
		(mid 79.816077 -244.857455)
		(end 79.99984 -244.811804)
		(width 0.0889)
		(layer "In2.Cu")
		(net "M_C_CPU1_SA_CB<0>")
	)
	(arc
		(start 90.922348 -244.811804)
		(mid 91.105856 -244.857298)
		(end 91.288108 -244.806978)
		(width 0.0889)
		(layer "In2.Cu")
		(net "M_C_CPU1_SA_CB<0>")
	)
	(arc
		(start 81.888076 -244.806978)
		(mid 82.171032 -244.730801)
		(end 82.453988 -244.806978)
		(width 0.0889)
		(layer "In2.Cu")
		(net "M_C_CPU1_SA_CB<0>")
	)
	(arc
		(start 80.948022 -244.806978)
		(mid 81.230978 -244.730801)
		(end 81.513934 -244.806978)
		(width 0.0889)
		(layer "In2.Cu")
		(net "M_C_CPU1_SA_CB<0>")
	)
	(arc
		(start 83.402424 -244.811804)
		(mid 83.585932 -244.857298)
		(end 83.768184 -244.806978)
		(width 0.0889)
		(layer "In2.Cu")
		(net "M_C_CPU1_SA_CB<0>")
	)
	(arc
		(start 85.648038 -244.806978)
		(mid 85.930994 -244.730801)
		(end 86.21395 -244.806978)
		(width 0.0889)
		(layer "In2.Cu")
		(net "M_C_CPU1_SA_CB<0>")
	)
	(arc
		(start 91.862402 -244.811804)
		(mid 92.04591 -244.857298)
		(end 92.228162 -244.806978)
		(width 0.0889)
		(layer "In2.Cu")
		(net "M_C_CPU1_SA_CB<0>")
	)
	(arc
		(start 82.82813 -244.806978)
		(mid 83.111086 -244.730801)
		(end 83.394042 -244.806978)
		(width 0.0889)
		(layer "In2.Cu")
		(net "M_C_CPU1_SA_CB<0>")
	)
	(arc
		(start 84.707984 -244.806978)
		(mid 84.99094 -244.730801)
		(end 85.273896 -244.806978)
		(width 0.0889)
		(layer "In2.Cu")
		(net "M_C_CPU1_SA_CB<0>")
	)
	(arc
		(start 78.707234 -244.814598)
		(mid 78.888164 -244.857076)
		(end 79.067152 -244.806978)
		(width 0.0889)
		(layer "In2.Cu")
		(net "M_C_CPU1_SA_CB<0>")
	)
	(arc
		(start 88.4682 -244.806978)
		(mid 88.751156 -244.730801)
		(end 89.034112 -244.806978)
		(width 0.0889)
		(layer "In2.Cu")
		(net "M_C_CPU1_SA_CB<0>")
	)
	(arc
		(start 84.334096 -244.806978)
		(mid 84.52104 -244.857233)
		(end 84.707984 -244.806978)
		(width 0.0889)
		(layer "In2.Cu")
		(net "M_C_CPU1_SA_CB<0>")
	)
	(arc
		(start 90.348054 -244.806978)
		(mid 90.63101 -244.730801)
		(end 90.913966 -244.806978)
		(width 0.0889)
		(layer "In2.Cu")
		(net "M_C_CPU1_SA_CB<0>")
	)
	(arc
		(start 78.127606 -244.806978)
		(mid 78.401461 -244.730628)
		(end 78.67777 -244.79758)
		(width 0.0889)
		(layer "In2.Cu")
		(net "M_C_CPU1_SA_CB<0>")
	)
	(arc
		(start 79.081884 -244.798342)
		(mid 79.358867 -244.730538)
		(end 79.633572 -244.806978)
		(width 0.0889)
		(layer "In2.Cu")
		(net "M_C_CPU1_SA_CB<0>")
	)
	(arc
		(start 87.528146 -244.806978)
		(mid 87.811102 -244.730801)
		(end 88.094058 -244.806978)
		(width 0.0889)
		(layer "In2.Cu")
		(net "M_C_CPU1_SA_CB<0>")
	)
	(arc
		(start 89.408 -244.806978)
		(mid 89.690956 -244.730801)
		(end 89.973912 -244.806978)
		(width 0.0889)
		(layer "In2.Cu")
		(net "M_C_CPU1_SA_CB<0>")
	)
	(arc
		(start 89.973912 -244.806978)
		(mid 90.156163 -244.857328)
		(end 90.339672 -244.811804)
		(width 0.0889)
		(layer "In2.Cu")
		(net "M_C_CPU1_SA_CB<0>")
	)
	(arc
		(start 93.167962 -244.806978)
		(mid 93.450918 -244.730801)
		(end 93.733874 -244.806978)
		(width 0.0889)
		(layer "In2.Cu")
		(net "M_C_CPU1_SA_CB<0>")
	)
	(arc
		(start 91.288108 -244.806978)
		(mid 91.571064 -244.730801)
		(end 91.85402 -244.806978)
		(width 0.0889)
		(layer "In2.Cu")
		(net "M_C_CPU1_SA_CB<0>")
	)
	(arc
		(start 92.228162 -244.806978)
		(mid 92.511118 -244.730801)
		(end 92.794074 -244.806978)
		(width 0.0889)
		(layer "In2.Cu")
		(net "M_C_CPU1_SA_CB<0>")
	)
	(arc
		(start 88.10244 -244.811804)
		(mid 88.285948 -244.857298)
		(end 88.4682 -244.806978)
		(width 0.0889)
		(layer "In2.Cu")
		(net "M_C_CPU1_SA_CB<0>")
	)
	(arc
		(start 86.588092 -244.806978)
		(mid 86.871048 -244.730801)
		(end 87.154004 -244.806978)
		(width 0.0889)
		(layer "In2.Cu")
		(net "M_C_CPU1_SA_CB<0>")
	)
	(arc
		(start 85.273896 -244.806978)
		(mid 85.456147 -244.857328)
		(end 85.639656 -244.811804)
		(width 0.0889)
		(layer "In2.Cu")
		(net "M_C_CPU1_SA_CB<0>")
	)
	(arc
		(start 80.574134 -244.806978)
		(mid 80.761078 -244.857233)
		(end 80.948022 -244.806978)
		(width 0.0889)
		(layer "In2.Cu")
		(net "M_C_CPU1_SA_CB<0>")
	)
	(arc
		(start 80.008222 -244.806978)
		(mid 80.291178 -244.730801)
		(end 80.574134 -244.806978)
		(width 0.0889)
		(layer "In2.Cu")
		(net "M_C_CPU1_SA_CB<0>")
	)
	(arc
		(start 89.034112 -244.806978)
		(mid 89.221056 -244.857233)
		(end 89.408 -244.806978)
		(width 0.0889)
		(layer "In2.Cu")
		(net "M_C_CPU1_SA_CB<0>")
	)
	(arc
		(start 93.733874 -244.806978)
		(mid 93.890312 -244.855949)
		(end 94.052644 -244.83314)
		(width 0.0889)
		(layer "In2.Cu")
		(net "M_C_CPU1_SA_CB<0>")
	)
	(arc
		(start 82.46237 -244.811804)
		(mid 82.645878 -244.857298)
		(end 82.82813 -244.806978)
		(width 0.0889)
		(layer "In2.Cu")
		(net "M_C_CPU1_SA_CB<0>")
	)
	(arc
		(start 92.794074 -244.806978)
		(mid 92.981018 -244.857233)
		(end 93.167962 -244.806978)
		(width 0.0889)
		(layer "In2.Cu")
		(net "M_C_CPU1_SA_CB<0>")
	)
	(arc
		(start 77.961744 -244.851682)
		(mid 78.047628 -244.840299)
		(end 78.127606 -244.806978)
		(width 0.0889)
		(layer "In2.Cu")
		(net "M_C_CPU1_SA_CB<0>")
	)
	(arc
		(start 81.513934 -244.806978)
		(mid 81.696185 -244.857328)
		(end 81.879694 -244.811804)
		(width 0.0889)
		(layer "In2.Cu")
		(net "M_C_CPU1_SA_CB<0>")
	)
	(arc
		(start 86.21395 -244.806978)
		(mid 86.396201 -244.857328)
		(end 86.57971 -244.811804)
		(width 0.0889)
		(layer "In2.Cu")
		(net "M_C_CPU1_SA_CB<0>")
	)
	(arc
		(start 87.162386 -244.811804)
		(mid 87.345894 -244.857298)
		(end 87.528146 -244.806978)
		(width 0.0889)
		(layer "In2.Cu")
		(net "M_C_CPU1_SA_CB<0>")
	)
	(segment
		(start 95.797878 -255.280414)
		(end 95.331026 -255.014476)
		(width 0.10668)
		(layer "F.Cu")
		(net "M_C_CPU1_SA_CA<6>")
	)
	(segment
		(start 91.749626 -255.341882)
		(end 91.758008 -255.337056)
		(width 0.0889)
		(layer "In2.Cu")
		(net "M_C_CPU1_SA_CA<6>")
	)
	(segment
		(start 71.477124 -254.486664)
		(end 72.912224 -255.921764)
		(width 0.14478)
		(layer "In2.Cu")
		(net "M_C_CPU1_SA_CA<6>")
	)
	(segment
		(start 50.621438 -254.479552)
		(end 50.621438 -254.54737)
		(width 0.14478)
		(layer "In2.Cu")
		(net "M_C_CPU1_SA_CA<6>")
	)
	(segment
		(start 50.064924 -254.479552)
		(end 50.227992 -254.316484)
		(width 0.14478)
		(layer "In2.Cu")
		(net "M_C_CPU1_SA_CA<6>")
	)
	(segment
		(start 75.960986 -255.921764)
		(end 76.382626 -255.921764)
		(width 0.0889)
		(layer "In2.Cu")
		(net "M_C_CPU1_SA_CA<6>")
	)
	(segment
		(start 81.044034 -255.337056)
		(end 81.052416 -255.341882)
		(width 0.0889)
		(layer "In2.Cu")
		(net "M_C_CPU1_SA_CA<6>")
	)
	(segment
		(start 49.50841 -254.54737)
		(end 49.671478 -254.710438)
		(width 0.14478)
		(layer "In2.Cu")
		(net "M_C_CPU1_SA_CA<6>")
	)
	(segment
		(start 53.311298 -254.54737)
		(end 53.311298 -254.487172)
		(width 0.14478)
		(layer "In2.Cu")
		(net "M_C_CPU1_SA_CA<6>")
	)
	(segment
		(start 76.382626 -255.921764)
		(end 76.674726 -255.629664)
		(width 0.0889)
		(layer "In2.Cu")
		(net "M_C_CPU1_SA_CA<6>")
	)
	(segment
		(start 88.929718 -255.341882)
		(end 88.9381 -255.337056)
		(width 0.0889)
		(layer "In2.Cu")
		(net "M_C_CPU1_SA_CA<6>")
	)
	(segment
		(start 83.289648 -255.341882)
		(end 83.29803 -255.337056)
		(width 0.0889)
		(layer "In2.Cu")
		(net "M_C_CPU1_SA_CA<6>")
	)
	(segment
		(start 57.395872 -254.54737)
		(end 57.55894 -254.710438)
		(width 0.14478)
		(layer "In2.Cu")
		(net "M_C_CPU1_SA_CA<6>")
	)
	(segment
		(start 50.227992 -254.316484)
		(end 50.45837 -254.316484)
		(width 0.14478)
		(layer "In2.Cu")
		(net "M_C_CPU1_SA_CA<6>")
	)
	(segment
		(start 79.138018 -255.319784)
		(end 79.167482 -255.337056)
		(width 0.0889)
		(layer "In2.Cu")
		(net "M_C_CPU1_SA_CA<6>")
	)
	(segment
		(start 94.204028 -255.337056)
		(end 94.21241 -255.341882)
		(width 0.0889)
		(layer "In2.Cu")
		(net "M_C_CPU1_SA_CA<6>")
	)
	(segment
		(start 68.55079 -254.486664)
		(end 71.477124 -254.486664)
		(width 0.14478)
		(layer "In2.Cu")
		(net "M_C_CPU1_SA_CA<6>")
	)
	(segment
		(start 49.671478 -254.710438)
		(end 49.901856 -254.710438)
		(width 0.14478)
		(layer "In2.Cu")
		(net "M_C_CPU1_SA_CA<6>")
	)
	(segment
		(start 48.788828 -254.710438)
		(end 48.951896 -254.54737)
		(width 0.14478)
		(layer "In2.Cu")
		(net "M_C_CPU1_SA_CA<6>")
	)
	(segment
		(start 56.67629 -254.710438)
		(end 56.839358 -254.54737)
		(width 0.14478)
		(layer "In2.Cu")
		(net "M_C_CPU1_SA_CA<6>")
	)
	(segment
		(start 49.50841 -254.479552)
		(end 49.50841 -254.54737)
		(width 0.14478)
		(layer "In2.Cu")
		(net "M_C_CPU1_SA_CA<6>")
	)
	(segment
		(start 92.68968 -255.341882)
		(end 92.698062 -255.337056)
		(width 0.0889)
		(layer "In2.Cu")
		(net "M_C_CPU1_SA_CA<6>")
	)
	(segment
		(start 50.064924 -254.54737)
		(end 50.064924 -254.479552)
		(width 0.14478)
		(layer "In2.Cu")
		(net "M_C_CPU1_SA_CA<6>")
	)
	(segment
		(start 49.901856 -254.710438)
		(end 50.064924 -254.54737)
		(width 0.14478)
		(layer "In2.Cu")
		(net "M_C_CPU1_SA_CA<6>")
	)
	(segment
		(start 78.199488 -255.321816)
		(end 78.22565 -255.336802)
		(width 0.0889)
		(layer "In2.Cu")
		(net "M_C_CPU1_SA_CA<6>")
	)
	(segment
		(start 89.504012 -255.337056)
		(end 89.512394 -255.341882)
		(width 0.0889)
		(layer "In2.Cu")
		(net "M_C_CPU1_SA_CA<6>")
	)
	(segment
		(start 53.311298 -254.487172)
		(end 53.474366 -254.324104)
		(width 0.14478)
		(layer "In2.Cu")
		(net "M_C_CPU1_SA_CA<6>")
	)
	(segment
		(start 48.951896 -254.54737)
		(end 48.951896 -254.479552)
		(width 0.14478)
		(layer "In2.Cu")
		(net "M_C_CPU1_SA_CA<6>")
	)
	(segment
		(start 57.55894 -254.710438)
		(end 59.90209 -254.710438)
		(width 0.14478)
		(layer "In2.Cu")
		(net "M_C_CPU1_SA_CA<6>")
	)
	(segment
		(start 56.839358 -254.479552)
		(end 57.002426 -254.316484)
		(width 0.14478)
		(layer "In2.Cu")
		(net "M_C_CPU1_SA_CA<6>")
	)
	(segment
		(start 44.340018 -252.58522)
		(end 46.465236 -254.710438)
		(width 0.14478)
		(layer "In2.Cu")
		(net "M_C_CPU1_SA_CA<6>")
	)
	(segment
		(start 57.002426 -254.316484)
		(end 57.232804 -254.316484)
		(width 0.14478)
		(layer "In2.Cu")
		(net "M_C_CPU1_SA_CA<6>")
	)
	(segment
		(start 56.839358 -254.54737)
		(end 56.839358 -254.479552)
		(width 0.14478)
		(layer "In2.Cu")
		(net "M_C_CPU1_SA_CA<6>")
	)
	(segment
		(start 53.474366 -254.324104)
		(end 53.704744 -254.324104)
		(width 0.14478)
		(layer "In2.Cu")
		(net "M_C_CPU1_SA_CA<6>")
	)
	(segment
		(start 60.307982 -255.11633)
		(end 67.030346 -255.11633)
		(width 0.14478)
		(layer "In2.Cu")
		(net "M_C_CPU1_SA_CA<6>")
	)
	(segment
		(start 48.951896 -254.479552)
		(end 49.114964 -254.316484)
		(width 0.14478)
		(layer "In2.Cu")
		(net "M_C_CPU1_SA_CA<6>")
	)
	(segment
		(start 67.030346 -255.11633)
		(end 68.55079 -254.486664)
		(width 0.14478)
		(layer "In2.Cu")
		(net "M_C_CPU1_SA_CA<6>")
	)
	(segment
		(start 53.867812 -254.54737)
		(end 54.03088 -254.710438)
		(width 0.14478)
		(layer "In2.Cu")
		(net "M_C_CPU1_SA_CA<6>")
	)
	(segment
		(start 53.867812 -254.487172)
		(end 53.867812 -254.54737)
		(width 0.14478)
		(layer "In2.Cu")
		(net "M_C_CPU1_SA_CA<6>")
	)
	(segment
		(start 50.784506 -254.710438)
		(end 53.14823 -254.710438)
		(width 0.14478)
		(layer "In2.Cu")
		(net "M_C_CPU1_SA_CA<6>")
	)
	(segment
		(start 93.263974 -255.337056)
		(end 93.272356 -255.341882)
		(width 0.0889)
		(layer "In2.Cu")
		(net "M_C_CPU1_SA_CA<6>")
	)
	(segment
		(start 84.803996 -255.337056)
		(end 84.812378 -255.341882)
		(width 0.0889)
		(layer "In2.Cu")
		(net "M_C_CPU1_SA_CA<6>")
	)
	(segment
		(start 54.03088 -254.710438)
		(end 56.67629 -254.710438)
		(width 0.14478)
		(layer "In2.Cu")
		(net "M_C_CPU1_SA_CA<6>")
	)
	(segment
		(start 57.395872 -254.479552)
		(end 57.395872 -254.54737)
		(width 0.14478)
		(layer "In2.Cu")
		(net "M_C_CPU1_SA_CA<6>")
	)
	(segment
		(start 80.46974 -255.341882)
		(end 80.478122 -255.337056)
		(width 0.0889)
		(layer "In2.Cu")
		(net "M_C_CPU1_SA_CA<6>")
	)
	(segment
		(start 95.48495 -255.279906)
		(end 95.331026 -255.014476)
		(width 0.0889)
		(layer "In2.Cu")
		(net "M_C_CPU1_SA_CA<6>")
	)
	(segment
		(start 49.114964 -254.316484)
		(end 49.345342 -254.316484)
		(width 0.14478)
		(layer "In2.Cu")
		(net "M_C_CPU1_SA_CA<6>")
	)
	(segment
		(start 50.621438 -254.54737)
		(end 50.784506 -254.710438)
		(width 0.14478)
		(layer "In2.Cu")
		(net "M_C_CPU1_SA_CA<6>")
	)
	(segment
		(start 57.232804 -254.316484)
		(end 57.395872 -254.479552)
		(width 0.14478)
		(layer "In2.Cu")
		(net "M_C_CPU1_SA_CA<6>")
	)
	(segment
		(start 53.704744 -254.324104)
		(end 53.867812 -254.487172)
		(width 0.14478)
		(layer "In2.Cu")
		(net "M_C_CPU1_SA_CA<6>")
	)
	(segment
		(start 87.989664 -255.341882)
		(end 87.998046 -255.337056)
		(width 0.0889)
		(layer "In2.Cu")
		(net "M_C_CPU1_SA_CA<6>")
	)
	(segment
		(start 79.518256 -255.349248)
		(end 79.5401 -255.336802)
		(width 0.0889)
		(layer "In2.Cu")
		(net "M_C_CPU1_SA_CA<6>")
	)
	(segment
		(start 46.465236 -254.710438)
		(end 48.788828 -254.710438)
		(width 0.14478)
		(layer "In2.Cu")
		(net "M_C_CPU1_SA_CA<6>")
	)
	(segment
		(start 72.912224 -255.921764)
		(end 75.960986 -255.921764)
		(width 0.14478)
		(layer "In2.Cu")
		(net "M_C_CPU1_SA_CA<6>")
	)
	(segment
		(start 49.345342 -254.316484)
		(end 49.50841 -254.479552)
		(width 0.14478)
		(layer "In2.Cu")
		(net "M_C_CPU1_SA_CA<6>")
	)
	(segment
		(start 78.22565 -255.336802)
		(end 78.256892 -255.354582)
		(width 0.0889)
		(layer "In2.Cu")
		(net "M_C_CPU1_SA_CA<6>")
	)
	(segment
		(start 59.90209 -254.710438)
		(end 60.307982 -255.11633)
		(width 0.14478)
		(layer "In2.Cu")
		(net "M_C_CPU1_SA_CA<6>")
	)
	(segment
		(start 79.5401 -255.336802)
		(end 79.566262 -255.321816)
		(width 0.0889)
		(layer "In2.Cu")
		(net "M_C_CPU1_SA_CA<6>")
	)
	(segment
		(start 95.462598 -255.363218)
		(end 95.48495 -255.279906)
		(width 0.0889)
		(layer "In2.Cu")
		(net "M_C_CPU1_SA_CA<6>")
	)
	(segment
		(start 84.229702 -255.341882)
		(end 84.238084 -255.337056)
		(width 0.0889)
		(layer "In2.Cu")
		(net "M_C_CPU1_SA_CA<6>")
	)
	(segment
		(start 50.45837 -254.316484)
		(end 50.621438 -254.479552)
		(width 0.14478)
		(layer "In2.Cu")
		(net "M_C_CPU1_SA_CA<6>")
	)
	(segment
		(start 53.14823 -254.710438)
		(end 53.311298 -254.54737)
		(width 0.14478)
		(layer "In2.Cu")
		(net "M_C_CPU1_SA_CA<6>")
	)
	(segment
		(start 77.57541 -255.387094)
		(end 77.66177 -255.337056)
		(width 0.0889)
		(layer "In2.Cu")
		(net "M_C_CPU1_SA_CA<6>")
	)
	(segment
		(start 85.74405 -255.337056)
		(end 85.752432 -255.341882)
		(width 0.0889)
		(layer "In2.Cu")
		(net "M_C_CPU1_SA_CA<6>")
	)
	(arc
		(start 81.418176 -255.337056)
		(mid 81.701132 -255.260879)
		(end 81.984088 -255.337056)
		(width 0.0889)
		(layer "In2.Cu")
		(net "M_C_CPU1_SA_CA<6>")
	)
	(arc
		(start 78.256892 -255.354582)
		(mid 78.430354 -255.387516)
		(end 78.599538 -255.337056)
		(width 0.0889)
		(layer "In2.Cu")
		(net "M_C_CPU1_SA_CA<6>")
	)
	(arc
		(start 90.444066 -255.337056)
		(mid 90.63101 -255.387311)
		(end 90.817954 -255.337056)
		(width 0.0889)
		(layer "In2.Cu")
		(net "M_C_CPU1_SA_CA<6>")
	)
	(arc
		(start 94.57817 -255.337056)
		(mid 94.861126 -255.260879)
		(end 95.144082 -255.337056)
		(width 0.0889)
		(layer "In2.Cu")
		(net "M_C_CPU1_SA_CA<6>")
	)
	(arc
		(start 91.758008 -255.337056)
		(mid 92.040964 -255.260879)
		(end 92.32392 -255.337056)
		(width 0.0889)
		(layer "In2.Cu")
		(net "M_C_CPU1_SA_CA<6>")
	)
	(arc
		(start 77.66177 -255.337056)
		(mid 77.9287 -255.261107)
		(end 78.199488 -255.321816)
		(width 0.0889)
		(layer "In2.Cu")
		(net "M_C_CPU1_SA_CA<6>")
	)
	(arc
		(start 83.29803 -255.337056)
		(mid 83.580986 -255.260879)
		(end 83.863942 -255.337056)
		(width 0.0889)
		(layer "In2.Cu")
		(net "M_C_CPU1_SA_CA<6>")
	)
	(arc
		(start 82.357976 -255.337056)
		(mid 82.640932 -255.260879)
		(end 82.923888 -255.337056)
		(width 0.0889)
		(layer "In2.Cu")
		(net "M_C_CPU1_SA_CA<6>")
	)
	(arc
		(start 87.623904 -255.337056)
		(mid 87.806155 -255.387406)
		(end 87.989664 -255.341882)
		(width 0.0889)
		(layer "In2.Cu")
		(net "M_C_CPU1_SA_CA<6>")
	)
	(arc
		(start 76.674726 -255.629664)
		(mid 77.141099 -255.567916)
		(end 77.57541 -255.387094)
		(width 0.0889)
		(layer "In2.Cu")
		(net "M_C_CPU1_SA_CA<6>")
	)
	(arc
		(start 88.9381 -255.337056)
		(mid 89.221056 -255.260879)
		(end 89.504012 -255.337056)
		(width 0.0889)
		(layer "In2.Cu")
		(net "M_C_CPU1_SA_CA<6>")
	)
	(arc
		(start 92.698062 -255.337056)
		(mid 92.981018 -255.260879)
		(end 93.263974 -255.337056)
		(width 0.0889)
		(layer "In2.Cu")
		(net "M_C_CPU1_SA_CA<6>")
	)
	(arc
		(start 89.878154 -255.337056)
		(mid 90.16111 -255.260879)
		(end 90.444066 -255.337056)
		(width 0.0889)
		(layer "In2.Cu")
		(net "M_C_CPU1_SA_CA<6>")
	)
	(arc
		(start 94.21241 -255.341882)
		(mid 94.395918 -255.387376)
		(end 94.57817 -255.337056)
		(width 0.0889)
		(layer "In2.Cu")
		(net "M_C_CPU1_SA_CA<6>")
	)
	(arc
		(start 85.178138 -255.337056)
		(mid 85.461094 -255.260879)
		(end 85.74405 -255.337056)
		(width 0.0889)
		(layer "In2.Cu")
		(net "M_C_CPU1_SA_CA<6>")
	)
	(arc
		(start 91.383866 -255.337056)
		(mid 91.566117 -255.387406)
		(end 91.749626 -255.341882)
		(width 0.0889)
		(layer "In2.Cu")
		(net "M_C_CPU1_SA_CA<6>")
	)
	(arc
		(start 79.566262 -255.321816)
		(mid 79.837048 -255.26117)
		(end 80.10398 -255.337056)
		(width 0.0889)
		(layer "In2.Cu")
		(net "M_C_CPU1_SA_CA<6>")
	)
	(arc
		(start 93.638116 -255.337056)
		(mid 93.921072 -255.260879)
		(end 94.204028 -255.337056)
		(width 0.0889)
		(layer "In2.Cu")
		(net "M_C_CPU1_SA_CA<6>")
	)
	(arc
		(start 93.272356 -255.341882)
		(mid 93.455864 -255.387376)
		(end 93.638116 -255.337056)
		(width 0.0889)
		(layer "In2.Cu")
		(net "M_C_CPU1_SA_CA<6>")
	)
	(arc
		(start 81.052416 -255.341882)
		(mid 81.235924 -255.387376)
		(end 81.418176 -255.337056)
		(width 0.0889)
		(layer "In2.Cu")
		(net "M_C_CPU1_SA_CA<6>")
	)
	(arc
		(start 86.118192 -255.337056)
		(mid 86.401148 -255.260879)
		(end 86.684104 -255.337056)
		(width 0.0889)
		(layer "In2.Cu")
		(net "M_C_CPU1_SA_CA<6>")
	)
	(arc
		(start 81.984088 -255.337056)
		(mid 82.171032 -255.387311)
		(end 82.357976 -255.337056)
		(width 0.0889)
		(layer "In2.Cu")
		(net "M_C_CPU1_SA_CA<6>")
	)
	(arc
		(start 78.599538 -255.337056)
		(mid 78.866595 -255.260021)
		(end 79.138018 -255.319784)
		(width 0.0889)
		(layer "In2.Cu")
		(net "M_C_CPU1_SA_CA<6>")
	)
	(arc
		(start 82.923888 -255.337056)
		(mid 83.106139 -255.387406)
		(end 83.289648 -255.341882)
		(width 0.0889)
		(layer "In2.Cu")
		(net "M_C_CPU1_SA_CA<6>")
	)
	(arc
		(start 80.478122 -255.337056)
		(mid 80.761078 -255.260879)
		(end 81.044034 -255.337056)
		(width 0.0889)
		(layer "In2.Cu")
		(net "M_C_CPU1_SA_CA<6>")
	)
	(arc
		(start 95.144082 -255.337056)
		(mid 95.300401 -255.386051)
		(end 95.462598 -255.363218)
		(width 0.0889)
		(layer "In2.Cu")
		(net "M_C_CPU1_SA_CA<6>")
	)
	(arc
		(start 89.512394 -255.341882)
		(mid 89.695902 -255.387376)
		(end 89.878154 -255.337056)
		(width 0.0889)
		(layer "In2.Cu")
		(net "M_C_CPU1_SA_CA<6>")
	)
	(arc
		(start 88.563958 -255.337056)
		(mid 88.746209 -255.387406)
		(end 88.929718 -255.341882)
		(width 0.0889)
		(layer "In2.Cu")
		(net "M_C_CPU1_SA_CA<6>")
	)
	(arc
		(start 87.998046 -255.337056)
		(mid 88.281002 -255.260879)
		(end 88.563958 -255.337056)
		(width 0.0889)
		(layer "In2.Cu")
		(net "M_C_CPU1_SA_CA<6>")
	)
	(arc
		(start 84.812378 -255.341882)
		(mid 84.995886 -255.387376)
		(end 85.178138 -255.337056)
		(width 0.0889)
		(layer "In2.Cu")
		(net "M_C_CPU1_SA_CA<6>")
	)
	(arc
		(start 85.752432 -255.341882)
		(mid 85.93594 -255.387376)
		(end 86.118192 -255.337056)
		(width 0.0889)
		(layer "In2.Cu")
		(net "M_C_CPU1_SA_CA<6>")
	)
	(arc
		(start 83.863942 -255.337056)
		(mid 84.046193 -255.387406)
		(end 84.229702 -255.341882)
		(width 0.0889)
		(layer "In2.Cu")
		(net "M_C_CPU1_SA_CA<6>")
	)
	(arc
		(start 79.167482 -255.337056)
		(mid 79.341332 -255.386962)
		(end 79.518256 -255.349248)
		(width 0.0889)
		(layer "In2.Cu")
		(net "M_C_CPU1_SA_CA<6>")
	)
	(arc
		(start 80.10398 -255.337056)
		(mid 80.286231 -255.387406)
		(end 80.46974 -255.341882)
		(width 0.0889)
		(layer "In2.Cu")
		(net "M_C_CPU1_SA_CA<6>")
	)
	(arc
		(start 86.684104 -255.337056)
		(mid 86.871048 -255.387311)
		(end 87.057992 -255.337056)
		(width 0.0889)
		(layer "In2.Cu")
		(net "M_C_CPU1_SA_CA<6>")
	)
	(arc
		(start 84.238084 -255.337056)
		(mid 84.52104 -255.260879)
		(end 84.803996 -255.337056)
		(width 0.0889)
		(layer "In2.Cu")
		(net "M_C_CPU1_SA_CA<6>")
	)
	(arc
		(start 92.32392 -255.337056)
		(mid 92.506171 -255.387406)
		(end 92.68968 -255.341882)
		(width 0.0889)
		(layer "In2.Cu")
		(net "M_C_CPU1_SA_CA<6>")
	)
	(arc
		(start 87.057992 -255.337056)
		(mid 87.340948 -255.260879)
		(end 87.623904 -255.337056)
		(width 0.0889)
		(layer "In2.Cu")
		(net "M_C_CPU1_SA_CA<6>")
	)
	(arc
		(start 90.817954 -255.337056)
		(mid 91.10091 -255.260879)
		(end 91.383866 -255.337056)
		(width 0.0889)
		(layer "In2.Cu")
		(net "M_C_CPU1_SA_CA<6>")
	)
	(segment
		(start 94.857824 -255.280414)
		(end 94.390972 -255.014476)
		(width 0.10668)
		(layer "F.Cu")
		(net "M_C_CPU1_SA_CA<5>")
	)
	(segment
		(start 89.504012 -254.691896)
		(end 89.512394 -254.68707)
		(width 0.0889)
		(layer "In2.Cu")
		(net "M_C_CPU1_SA_CA<5>")
	)
	(segment
		(start 79.163164 -254.691896)
		(end 79.174848 -254.685038)
		(width 0.0889)
		(layer "In2.Cu")
		(net "M_C_CPU1_SA_CA<5>")
	)
	(segment
		(start 78.59776 -254.69215)
		(end 78.603348 -254.695452)
		(width 0.0889)
		(layer "In2.Cu")
		(net "M_C_CPU1_SA_CA<5>")
	)
	(segment
		(start 83.289648 -254.68707)
		(end 83.29803 -254.691896)
		(width 0.0889)
		(layer "In2.Cu")
		(net "M_C_CPU1_SA_CA<5>")
	)
	(segment
		(start 71.665592 -254.032004)
		(end 73.080372 -255.446784)
		(width 0.14478)
		(layer "In2.Cu")
		(net "M_C_CPU1_SA_CA<5>")
	)
	(segment
		(start 93.263974 -254.691896)
		(end 93.272356 -254.68707)
		(width 0.0889)
		(layer "In2.Cu")
		(net "M_C_CPU1_SA_CA<5>")
	)
	(segment
		(start 66.940684 -254.66675)
		(end 68.47332 -254.032004)
		(width 0.14478)
		(layer "In2.Cu")
		(net "M_C_CPU1_SA_CA<5>")
	)
	(segment
		(start 40.664892 -252.160278)
		(end 45.21454 -252.160278)
		(width 0.14478)
		(layer "In2.Cu")
		(net "M_C_CPU1_SA_CA<5>")
	)
	(segment
		(start 84.803996 -254.691896)
		(end 84.812378 -254.68707)
		(width 0.0889)
		(layer "In2.Cu")
		(net "M_C_CPU1_SA_CA<5>")
	)
	(segment
		(start 77.943456 -254.854456)
		(end 78.223618 -254.691896)
		(width 0.0889)
		(layer "In2.Cu")
		(net "M_C_CPU1_SA_CA<5>")
	)
	(segment
		(start 40.23995 -251.735336)
		(end 40.664892 -252.160278)
		(width 0.14478)
		(layer "In2.Cu")
		(net "M_C_CPU1_SA_CA<5>")
	)
	(segment
		(start 92.68968 -254.68707)
		(end 92.698062 -254.691896)
		(width 0.0889)
		(layer "In2.Cu")
		(net "M_C_CPU1_SA_CA<5>")
	)
	(segment
		(start 75.933046 -255.446784)
		(end 76.220066 -255.446784)
		(width 0.0889)
		(layer "In2.Cu")
		(net "M_C_CPU1_SA_CA<5>")
	)
	(segment
		(start 73.080372 -255.446784)
		(end 75.933046 -255.446784)
		(width 0.14478)
		(layer "In2.Cu")
		(net "M_C_CPU1_SA_CA<5>")
	)
	(segment
		(start 78.579472 -254.681736)
		(end 78.59776 -254.69215)
		(width 0.0889)
		(layer "In2.Cu")
		(net "M_C_CPU1_SA_CA<5>")
	)
	(segment
		(start 76.220066 -255.446784)
		(end 76.532486 -255.134364)
		(width 0.0889)
		(layer "In2.Cu")
		(net "M_C_CPU1_SA_CA<5>")
	)
	(segment
		(start 91.749626 -254.68707)
		(end 91.758008 -254.691896)
		(width 0.0889)
		(layer "In2.Cu")
		(net "M_C_CPU1_SA_CA<5>")
	)
	(segment
		(start 84.229702 -254.68707)
		(end 84.238084 -254.691896)
		(width 0.0889)
		(layer "In2.Cu")
		(net "M_C_CPU1_SA_CA<5>")
	)
	(segment
		(start 80.46974 -254.68707)
		(end 80.478122 -254.691896)
		(width 0.0889)
		(layer "In2.Cu")
		(net "M_C_CPU1_SA_CA<5>")
	)
	(segment
		(start 94.141036 -254.723646)
		(end 94.237048 -254.749046)
		(width 0.0889)
		(layer "In2.Cu")
		(net "M_C_CPU1_SA_CA<5>")
	)
	(segment
		(start 61.302392 -254.66675)
		(end 66.940684 -254.66675)
		(width 0.14478)
		(layer "In2.Cu")
		(net "M_C_CPU1_SA_CA<5>")
	)
	(segment
		(start 81.044034 -254.691896)
		(end 81.052416 -254.68707)
		(width 0.0889)
		(layer "In2.Cu")
		(net "M_C_CPU1_SA_CA<5>")
	)
	(segment
		(start 88.929718 -254.68707)
		(end 88.9381 -254.691896)
		(width 0.0889)
		(layer "In2.Cu")
		(net "M_C_CPU1_SA_CA<5>")
	)
	(segment
		(start 76.532486 -255.134364)
		(end 76.903326 -255.134364)
		(width 0.0889)
		(layer "In2.Cu")
		(net "M_C_CPU1_SA_CA<5>")
	)
	(segment
		(start 85.74405 -254.691896)
		(end 85.752432 -254.68707)
		(width 0.0889)
		(layer "In2.Cu")
		(net "M_C_CPU1_SA_CA<5>")
	)
	(segment
		(start 45.21454 -252.160278)
		(end 46.914562 -253.8603)
		(width 0.14478)
		(layer "In2.Cu")
		(net "M_C_CPU1_SA_CA<5>")
	)
	(segment
		(start 87.989664 -254.68707)
		(end 87.998046 -254.691896)
		(width 0.0889)
		(layer "In2.Cu")
		(net "M_C_CPU1_SA_CA<5>")
	)
	(segment
		(start 68.47332 -254.032004)
		(end 71.665592 -254.032004)
		(width 0.14478)
		(layer "In2.Cu")
		(net "M_C_CPU1_SA_CA<5>")
	)
	(segment
		(start 46.914562 -253.8603)
		(end 60.495942 -253.8603)
		(width 0.14478)
		(layer "In2.Cu")
		(net "M_C_CPU1_SA_CA<5>")
	)
	(segment
		(start 80.089248 -254.700532)
		(end 80.10398 -254.691896)
		(width 0.0889)
		(layer "In2.Cu")
		(net "M_C_CPU1_SA_CA<5>")
	)
	(segment
		(start 60.495942 -253.8603)
		(end 61.302392 -254.66675)
		(width 0.14478)
		(layer "In2.Cu")
		(net "M_C_CPU1_SA_CA<5>")
	)
	(segment
		(start 94.237048 -254.749046)
		(end 94.390972 -255.014476)
		(width 0.0889)
		(layer "In2.Cu")
		(net "M_C_CPU1_SA_CA<5>")
	)
	(arc
		(start 80.478122 -254.691896)
		(mid 80.761078 -254.768073)
		(end 81.044034 -254.691896)
		(width 0.0889)
		(layer "In2.Cu")
		(net "M_C_CPU1_SA_CA<5>")
	)
	(arc
		(start 88.563958 -254.691896)
		(mid 88.746209 -254.641546)
		(end 88.929718 -254.68707)
		(width 0.0889)
		(layer "In2.Cu")
		(net "M_C_CPU1_SA_CA<5>")
	)
	(arc
		(start 79.174848 -254.685038)
		(mid 79.357103 -254.641385)
		(end 79.53756 -254.691896)
		(width 0.0889)
		(layer "In2.Cu")
		(net "M_C_CPU1_SA_CA<5>")
	)
	(arc
		(start 76.903326 -255.134364)
		(mid 77.441891 -255.06316)
		(end 77.943456 -254.854456)
		(width 0.0889)
		(layer "In2.Cu")
		(net "M_C_CPU1_SA_CA<5>")
	)
	(arc
		(start 86.684104 -254.691896)
		(mid 86.871048 -254.641641)
		(end 87.057992 -254.691896)
		(width 0.0889)
		(layer "In2.Cu")
		(net "M_C_CPU1_SA_CA<5>")
	)
	(arc
		(start 90.817954 -254.691896)
		(mid 91.10091 -254.768073)
		(end 91.383866 -254.691896)
		(width 0.0889)
		(layer "In2.Cu")
		(net "M_C_CPU1_SA_CA<5>")
	)
	(arc
		(start 86.118192 -254.691896)
		(mid 86.401148 -254.768073)
		(end 86.684104 -254.691896)
		(width 0.0889)
		(layer "In2.Cu")
		(net "M_C_CPU1_SA_CA<5>")
	)
	(arc
		(start 85.752432 -254.68707)
		(mid 85.93594 -254.641576)
		(end 86.118192 -254.691896)
		(width 0.0889)
		(layer "In2.Cu")
		(net "M_C_CPU1_SA_CA<5>")
	)
	(arc
		(start 93.638116 -254.691896)
		(mid 93.885829 -254.767116)
		(end 94.141036 -254.723646)
		(width 0.0889)
		(layer "In2.Cu")
		(net "M_C_CPU1_SA_CA<5>")
	)
	(arc
		(start 89.512394 -254.68707)
		(mid 89.695902 -254.641576)
		(end 89.878154 -254.691896)
		(width 0.0889)
		(layer "In2.Cu")
		(net "M_C_CPU1_SA_CA<5>")
	)
	(arc
		(start 80.10398 -254.691896)
		(mid 80.286231 -254.641546)
		(end 80.46974 -254.68707)
		(width 0.0889)
		(layer "In2.Cu")
		(net "M_C_CPU1_SA_CA<5>")
	)
	(arc
		(start 83.29803 -254.691896)
		(mid 83.580986 -254.768073)
		(end 83.863942 -254.691896)
		(width 0.0889)
		(layer "In2.Cu")
		(net "M_C_CPU1_SA_CA<5>")
	)
	(arc
		(start 78.603348 -254.695452)
		(mid 78.883737 -254.768121)
		(end 79.163164 -254.691896)
		(width 0.0889)
		(layer "In2.Cu")
		(net "M_C_CPU1_SA_CA<5>")
	)
	(arc
		(start 81.052416 -254.68707)
		(mid 81.235924 -254.641576)
		(end 81.418176 -254.691896)
		(width 0.0889)
		(layer "In2.Cu")
		(net "M_C_CPU1_SA_CA<5>")
	)
	(arc
		(start 84.238084 -254.691896)
		(mid 84.52104 -254.768073)
		(end 84.803996 -254.691896)
		(width 0.0889)
		(layer "In2.Cu")
		(net "M_C_CPU1_SA_CA<5>")
	)
	(arc
		(start 81.984088 -254.691896)
		(mid 82.171032 -254.641641)
		(end 82.357976 -254.691896)
		(width 0.0889)
		(layer "In2.Cu")
		(net "M_C_CPU1_SA_CA<5>")
	)
	(arc
		(start 90.444066 -254.691896)
		(mid 90.63101 -254.641641)
		(end 90.817954 -254.691896)
		(width 0.0889)
		(layer "In2.Cu")
		(net "M_C_CPU1_SA_CA<5>")
	)
	(arc
		(start 87.623904 -254.691896)
		(mid 87.806155 -254.641546)
		(end 87.989664 -254.68707)
		(width 0.0889)
		(layer "In2.Cu")
		(net "M_C_CPU1_SA_CA<5>")
	)
	(arc
		(start 82.923888 -254.691896)
		(mid 83.106139 -254.641546)
		(end 83.289648 -254.68707)
		(width 0.0889)
		(layer "In2.Cu")
		(net "M_C_CPU1_SA_CA<5>")
	)
	(arc
		(start 82.357976 -254.691896)
		(mid 82.640932 -254.768073)
		(end 82.923888 -254.691896)
		(width 0.0889)
		(layer "In2.Cu")
		(net "M_C_CPU1_SA_CA<5>")
	)
	(arc
		(start 87.057992 -254.691896)
		(mid 87.340948 -254.768073)
		(end 87.623904 -254.691896)
		(width 0.0889)
		(layer "In2.Cu")
		(net "M_C_CPU1_SA_CA<5>")
	)
	(arc
		(start 84.812378 -254.68707)
		(mid 84.995886 -254.641576)
		(end 85.178138 -254.691896)
		(width 0.0889)
		(layer "In2.Cu")
		(net "M_C_CPU1_SA_CA<5>")
	)
	(arc
		(start 92.698062 -254.691896)
		(mid 92.981018 -254.768073)
		(end 93.263974 -254.691896)
		(width 0.0889)
		(layer "In2.Cu")
		(net "M_C_CPU1_SA_CA<5>")
	)
	(arc
		(start 93.272356 -254.68707)
		(mid 93.455864 -254.641576)
		(end 93.638116 -254.691896)
		(width 0.0889)
		(layer "In2.Cu")
		(net "M_C_CPU1_SA_CA<5>")
	)
	(arc
		(start 83.863942 -254.691896)
		(mid 84.046193 -254.641546)
		(end 84.229702 -254.68707)
		(width 0.0889)
		(layer "In2.Cu")
		(net "M_C_CPU1_SA_CA<5>")
	)
	(arc
		(start 79.53756 -254.691896)
		(mid 79.812266 -254.76826)
		(end 80.089248 -254.700532)
		(width 0.0889)
		(layer "In2.Cu")
		(net "M_C_CPU1_SA_CA<5>")
	)
	(arc
		(start 85.178138 -254.691896)
		(mid 85.461094 -254.768073)
		(end 85.74405 -254.691896)
		(width 0.0889)
		(layer "In2.Cu")
		(net "M_C_CPU1_SA_CA<5>")
	)
	(arc
		(start 88.9381 -254.691896)
		(mid 89.221056 -254.768073)
		(end 89.504012 -254.691896)
		(width 0.0889)
		(layer "In2.Cu")
		(net "M_C_CPU1_SA_CA<5>")
	)
	(arc
		(start 91.758008 -254.691896)
		(mid 92.040964 -254.768073)
		(end 92.32392 -254.691896)
		(width 0.0889)
		(layer "In2.Cu")
		(net "M_C_CPU1_SA_CA<5>")
	)
	(arc
		(start 87.998046 -254.691896)
		(mid 88.281002 -254.768073)
		(end 88.563958 -254.691896)
		(width 0.0889)
		(layer "In2.Cu")
		(net "M_C_CPU1_SA_CA<5>")
	)
	(arc
		(start 89.878154 -254.691896)
		(mid 90.16111 -254.768073)
		(end 90.444066 -254.691896)
		(width 0.0889)
		(layer "In2.Cu")
		(net "M_C_CPU1_SA_CA<5>")
	)
	(arc
		(start 78.223618 -254.691896)
		(mid 78.400246 -254.641663)
		(end 78.579472 -254.681736)
		(width 0.0889)
		(layer "In2.Cu")
		(net "M_C_CPU1_SA_CA<5>")
	)
	(arc
		(start 91.383866 -254.691896)
		(mid 91.566117 -254.641546)
		(end 91.749626 -254.68707)
		(width 0.0889)
		(layer "In2.Cu")
		(net "M_C_CPU1_SA_CA<5>")
	)
	(arc
		(start 92.32392 -254.691896)
		(mid 92.506171 -254.641546)
		(end 92.68968 -254.68707)
		(width 0.0889)
		(layer "In2.Cu")
		(net "M_C_CPU1_SA_CA<5>")
	)
	(arc
		(start 81.418176 -254.691896)
		(mid 81.701132 -254.768073)
		(end 81.984088 -254.691896)
		(width 0.0889)
		(layer "In2.Cu")
		(net "M_C_CPU1_SA_CA<5>")
	)
	(segment
		(start 94.387924 -254.470408)
		(end 93.921072 -254.20447)
		(width 0.10668)
		(layer "F.Cu")
		(net "M_C_CPU1_SA_CA<4>")
	)
	(segment
		(start 53.527706 -253.010416)
		(end 53.690774 -253.173484)
		(width 0.14478)
		(layer "In2.Cu")
		(net "M_C_CPU1_SA_CA<4>")
	)
	(segment
		(start 50.730912 -253.23546)
		(end 50.730912 -253.173484)
		(width 0.14478)
		(layer "In2.Cu")
		(net "M_C_CPU1_SA_CA<4>")
	)
	(segment
		(start 94.052644 -254.553212)
		(end 94.074996 -254.4699)
		(width 0.0889)
		(layer "In2.Cu")
		(net "M_C_CPU1_SA_CA<4>")
	)
	(segment
		(start 75.933046 -254.943864)
		(end 76.197206 -254.943864)
		(width 0.0889)
		(layer "In2.Cu")
		(net "M_C_CPU1_SA_CA<4>")
	)
	(segment
		(start 88.094058 -254.52705)
		(end 88.10244 -254.531876)
		(width 0.0889)
		(layer "In2.Cu")
		(net "M_C_CPU1_SA_CA<4>")
	)
	(segment
		(start 50.337466 -253.398528)
		(end 50.567844 -253.398528)
		(width 0.14478)
		(layer "In2.Cu")
		(net "M_C_CPU1_SA_CA<4>")
	)
	(segment
		(start 44.763944 -251.309124)
		(end 45.381672 -251.309124)
		(width 0.14478)
		(layer "In2.Cu")
		(net "M_C_CPU1_SA_CA<4>")
	)
	(segment
		(start 81.879694 -254.531876)
		(end 81.888076 -254.52705)
		(width 0.0889)
		(layer "In2.Cu")
		(net "M_C_CPU1_SA_CA<4>")
	)
	(segment
		(start 71.85406 -253.577344)
		(end 73.22058 -254.943864)
		(width 0.14478)
		(layer "In2.Cu")
		(net "M_C_CPU1_SA_CA<4>")
	)
	(segment
		(start 82.453988 -254.52705)
		(end 82.46237 -254.531876)
		(width 0.0889)
		(layer "In2.Cu")
		(net "M_C_CPU1_SA_CA<4>")
	)
	(segment
		(start 53.690774 -253.231396)
		(end 53.853842 -253.394464)
		(width 0.14478)
		(layer "In2.Cu")
		(net "M_C_CPU1_SA_CA<4>")
	)
	(segment
		(start 78.67777 -254.517652)
		(end 78.693518 -254.526796)
		(width 0.0889)
		(layer "In2.Cu")
		(net "M_C_CPU1_SA_CA<4>")
	)
	(segment
		(start 54.410356 -253.010416)
		(end 60.282074 -253.010416)
		(width 0.14478)
		(layer "In2.Cu")
		(net "M_C_CPU1_SA_CA<4>")
	)
	(segment
		(start 49.617884 -253.23546)
		(end 49.617884 -252.785372)
		(width 0.14478)
		(layer "In2.Cu")
		(net "M_C_CPU1_SA_CA<4>")
	)
	(segment
		(start 76.197206 -254.943864)
		(end 76.303886 -254.837184)
		(width 0.0889)
		(layer "In2.Cu")
		(net "M_C_CPU1_SA_CA<4>")
	)
	(segment
		(start 50.174398 -253.23546)
		(end 50.337466 -253.398528)
		(width 0.14478)
		(layer "In2.Cu")
		(net "M_C_CPU1_SA_CA<4>")
	)
	(segment
		(start 50.01133 -252.622304)
		(end 50.174398 -252.785372)
		(width 0.14478)
		(layer "In2.Cu")
		(net "M_C_CPU1_SA_CA<4>")
	)
	(segment
		(start 44.340018 -250.885198)
		(end 44.763944 -251.309124)
		(width 0.14478)
		(layer "In2.Cu")
		(net "M_C_CPU1_SA_CA<4>")
	)
	(segment
		(start 49.780952 -252.622304)
		(end 50.01133 -252.622304)
		(width 0.14478)
		(layer "In2.Cu")
		(net "M_C_CPU1_SA_CA<4>")
	)
	(segment
		(start 79.99984 -254.531876)
		(end 80.008222 -254.52705)
		(width 0.0889)
		(layer "In2.Cu")
		(net "M_C_CPU1_SA_CA<4>")
	)
	(segment
		(start 52.971192 -253.394464)
		(end 53.13426 -253.231396)
		(width 0.14478)
		(layer "In2.Cu")
		(net "M_C_CPU1_SA_CA<4>")
	)
	(segment
		(start 83.394042 -254.52705)
		(end 83.402424 -254.531876)
		(width 0.0889)
		(layer "In2.Cu")
		(net "M_C_CPU1_SA_CA<4>")
	)
	(segment
		(start 90.913966 -254.52705)
		(end 90.922348 -254.531876)
		(width 0.0889)
		(layer "In2.Cu")
		(net "M_C_CPU1_SA_CA<4>")
	)
	(segment
		(start 53.853842 -253.394464)
		(end 54.08422 -253.394464)
		(width 0.14478)
		(layer "In2.Cu")
		(net "M_C_CPU1_SA_CA<4>")
	)
	(segment
		(start 91.85402 -254.52705)
		(end 91.862402 -254.531876)
		(width 0.0889)
		(layer "In2.Cu")
		(net "M_C_CPU1_SA_CA<4>")
	)
	(segment
		(start 52.414678 -253.010416)
		(end 52.577746 -253.173484)
		(width 0.14478)
		(layer "In2.Cu")
		(net "M_C_CPU1_SA_CA<4>")
	)
	(segment
		(start 49.06137 -253.23546)
		(end 49.224438 -253.398528)
		(width 0.14478)
		(layer "In2.Cu")
		(net "M_C_CPU1_SA_CA<4>")
	)
	(segment
		(start 49.617884 -252.785372)
		(end 49.780952 -252.622304)
		(width 0.14478)
		(layer "In2.Cu")
		(net "M_C_CPU1_SA_CA<4>")
	)
	(segment
		(start 54.08422 -253.394464)
		(end 54.247288 -253.231396)
		(width 0.14478)
		(layer "In2.Cu")
		(net "M_C_CPU1_SA_CA<4>")
	)
	(segment
		(start 53.13426 -253.231396)
		(end 53.13426 -253.173484)
		(width 0.14478)
		(layer "In2.Cu")
		(net "M_C_CPU1_SA_CA<4>")
	)
	(segment
		(start 53.297328 -253.010416)
		(end 53.527706 -253.010416)
		(width 0.14478)
		(layer "In2.Cu")
		(net "M_C_CPU1_SA_CA<4>")
	)
	(segment
		(start 48.341788 -253.010416)
		(end 48.504856 -252.847348)
		(width 0.14478)
		(layer "In2.Cu")
		(net "M_C_CPU1_SA_CA<4>")
	)
	(segment
		(start 73.22058 -254.943864)
		(end 75.933046 -254.943864)
		(width 0.14478)
		(layer "In2.Cu")
		(net "M_C_CPU1_SA_CA<4>")
	)
	(segment
		(start 79.067152 -254.52705)
		(end 79.081884 -254.518414)
		(width 0.0889)
		(layer "In2.Cu")
		(net "M_C_CPU1_SA_CA<4>")
	)
	(segment
		(start 48.667924 -252.622304)
		(end 48.898302 -252.622304)
		(width 0.14478)
		(layer "In2.Cu")
		(net "M_C_CPU1_SA_CA<4>")
	)
	(segment
		(start 48.504856 -252.785372)
		(end 48.667924 -252.622304)
		(width 0.14478)
		(layer "In2.Cu")
		(net "M_C_CPU1_SA_CA<4>")
	)
	(segment
		(start 50.174398 -252.785372)
		(end 50.174398 -253.23546)
		(width 0.14478)
		(layer "In2.Cu")
		(net "M_C_CPU1_SA_CA<4>")
	)
	(segment
		(start 49.06137 -252.785372)
		(end 49.06137 -253.23546)
		(width 0.14478)
		(layer "In2.Cu")
		(net "M_C_CPU1_SA_CA<4>")
	)
	(segment
		(start 54.247288 -253.231396)
		(end 54.247288 -253.173484)
		(width 0.14478)
		(layer "In2.Cu")
		(net "M_C_CPU1_SA_CA<4>")
	)
	(segment
		(start 60.282074 -253.010416)
		(end 61.488828 -254.21717)
		(width 0.14478)
		(layer "In2.Cu")
		(net "M_C_CPU1_SA_CA<4>")
	)
	(segment
		(start 61.488828 -254.21717)
		(end 66.851022 -254.21717)
		(width 0.14478)
		(layer "In2.Cu")
		(net "M_C_CPU1_SA_CA<4>")
	)
	(segment
		(start 49.224438 -253.398528)
		(end 49.454816 -253.398528)
		(width 0.14478)
		(layer "In2.Cu")
		(net "M_C_CPU1_SA_CA<4>")
	)
	(segment
		(start 76.303886 -254.837184)
		(end 76.97724 -254.837184)
		(width 0.0889)
		(layer "In2.Cu")
		(net "M_C_CPU1_SA_CA<4>")
	)
	(segment
		(start 90.339672 -254.531876)
		(end 90.348054 -254.52705)
		(width 0.0889)
		(layer "In2.Cu")
		(net "M_C_CPU1_SA_CA<4>")
	)
	(segment
		(start 52.577746 -253.173484)
		(end 52.577746 -253.231396)
		(width 0.14478)
		(layer "In2.Cu")
		(net "M_C_CPU1_SA_CA<4>")
	)
	(segment
		(start 68.39585 -253.577344)
		(end 71.85406 -253.577344)
		(width 0.14478)
		(layer "In2.Cu")
		(net "M_C_CPU1_SA_CA<4>")
	)
	(segment
		(start 48.504856 -252.847348)
		(end 48.504856 -252.785372)
		(width 0.14478)
		(layer "In2.Cu")
		(net "M_C_CPU1_SA_CA<4>")
	)
	(segment
		(start 50.89398 -253.010416)
		(end 52.414678 -253.010416)
		(width 0.14478)
		(layer "In2.Cu")
		(net "M_C_CPU1_SA_CA<4>")
	)
	(segment
		(start 49.454816 -253.398528)
		(end 49.617884 -253.23546)
		(width 0.14478)
		(layer "In2.Cu")
		(net "M_C_CPU1_SA_CA<4>")
	)
	(segment
		(start 53.13426 -253.173484)
		(end 53.297328 -253.010416)
		(width 0.14478)
		(layer "In2.Cu")
		(net "M_C_CPU1_SA_CA<4>")
	)
	(segment
		(start 50.567844 -253.398528)
		(end 50.730912 -253.23546)
		(width 0.14478)
		(layer "In2.Cu")
		(net "M_C_CPU1_SA_CA<4>")
	)
	(segment
		(start 54.247288 -253.173484)
		(end 54.410356 -253.010416)
		(width 0.14478)
		(layer "In2.Cu")
		(net "M_C_CPU1_SA_CA<4>")
	)
	(segment
		(start 50.730912 -253.173484)
		(end 50.89398 -253.010416)
		(width 0.14478)
		(layer "In2.Cu")
		(net "M_C_CPU1_SA_CA<4>")
	)
	(segment
		(start 45.381672 -251.309124)
		(end 47.082964 -253.010416)
		(width 0.14478)
		(layer "In2.Cu")
		(net "M_C_CPU1_SA_CA<4>")
	)
	(segment
		(start 85.639656 -254.531876)
		(end 85.648038 -254.52705)
		(width 0.0889)
		(layer "In2.Cu")
		(net "M_C_CPU1_SA_CA<4>")
	)
	(segment
		(start 53.690774 -253.173484)
		(end 53.690774 -253.231396)
		(width 0.14478)
		(layer "In2.Cu")
		(net "M_C_CPU1_SA_CA<4>")
	)
	(segment
		(start 47.082964 -253.010416)
		(end 48.341788 -253.010416)
		(width 0.14478)
		(layer "In2.Cu")
		(net "M_C_CPU1_SA_CA<4>")
	)
	(segment
		(start 78.693518 -254.526796)
		(end 78.707234 -254.53467)
		(width 0.0889)
		(layer "In2.Cu")
		(net "M_C_CPU1_SA_CA<4>")
	)
	(segment
		(start 52.577746 -253.231396)
		(end 52.740814 -253.394464)
		(width 0.14478)
		(layer "In2.Cu")
		(net "M_C_CPU1_SA_CA<4>")
	)
	(segment
		(start 66.851022 -254.21717)
		(end 68.39585 -253.577344)
		(width 0.14478)
		(layer "In2.Cu")
		(net "M_C_CPU1_SA_CA<4>")
	)
	(segment
		(start 94.074996 -254.4699)
		(end 93.921072 -254.20447)
		(width 0.0889)
		(layer "In2.Cu")
		(net "M_C_CPU1_SA_CA<4>")
	)
	(segment
		(start 86.57971 -254.531876)
		(end 86.588092 -254.52705)
		(width 0.0889)
		(layer "In2.Cu")
		(net "M_C_CPU1_SA_CA<4>")
	)
	(segment
		(start 48.898302 -252.622304)
		(end 49.06137 -252.785372)
		(width 0.14478)
		(layer "In2.Cu")
		(net "M_C_CPU1_SA_CA<4>")
	)
	(segment
		(start 52.740814 -253.394464)
		(end 52.971192 -253.394464)
		(width 0.14478)
		(layer "In2.Cu")
		(net "M_C_CPU1_SA_CA<4>")
	)
	(segment
		(start 87.154004 -254.52705)
		(end 87.162386 -254.531876)
		(width 0.0889)
		(layer "In2.Cu")
		(net "M_C_CPU1_SA_CA<4>")
	)
	(arc
		(start 91.288108 -254.52705)
		(mid 91.571064 -254.450873)
		(end 91.85402 -254.52705)
		(width 0.0889)
		(layer "In2.Cu")
		(net "M_C_CPU1_SA_CA<4>")
	)
	(arc
		(start 80.948022 -254.52705)
		(mid 81.230978 -254.450873)
		(end 81.513934 -254.52705)
		(width 0.0889)
		(layer "In2.Cu")
		(net "M_C_CPU1_SA_CA<4>")
	)
	(arc
		(start 90.922348 -254.531876)
		(mid 91.105856 -254.57737)
		(end 91.288108 -254.52705)
		(width 0.0889)
		(layer "In2.Cu")
		(net "M_C_CPU1_SA_CA<4>")
	)
	(arc
		(start 84.334096 -254.52705)
		(mid 84.52104 -254.577305)
		(end 84.707984 -254.52705)
		(width 0.0889)
		(layer "In2.Cu")
		(net "M_C_CPU1_SA_CA<4>")
	)
	(arc
		(start 85.273896 -254.52705)
		(mid 85.456147 -254.5774)
		(end 85.639656 -254.531876)
		(width 0.0889)
		(layer "In2.Cu")
		(net "M_C_CPU1_SA_CA<4>")
	)
	(arc
		(start 86.21395 -254.52705)
		(mid 86.396201 -254.5774)
		(end 86.57971 -254.531876)
		(width 0.0889)
		(layer "In2.Cu")
		(net "M_C_CPU1_SA_CA<4>")
	)
	(arc
		(start 88.4682 -254.52705)
		(mid 88.751156 -254.450873)
		(end 89.034112 -254.52705)
		(width 0.0889)
		(layer "In2.Cu")
		(net "M_C_CPU1_SA_CA<4>")
	)
	(arc
		(start 87.162386 -254.531876)
		(mid 87.345894 -254.57737)
		(end 87.528146 -254.52705)
		(width 0.0889)
		(layer "In2.Cu")
		(net "M_C_CPU1_SA_CA<4>")
	)
	(arc
		(start 78.707234 -254.53467)
		(mid 78.888164 -254.577148)
		(end 79.067152 -254.52705)
		(width 0.0889)
		(layer "In2.Cu")
		(net "M_C_CPU1_SA_CA<4>")
	)
	(arc
		(start 91.862402 -254.531876)
		(mid 92.04591 -254.57737)
		(end 92.228162 -254.52705)
		(width 0.0889)
		(layer "In2.Cu")
		(net "M_C_CPU1_SA_CA<4>")
	)
	(arc
		(start 82.82813 -254.52705)
		(mid 83.111086 -254.450873)
		(end 83.394042 -254.52705)
		(width 0.0889)
		(layer "In2.Cu")
		(net "M_C_CPU1_SA_CA<4>")
	)
	(arc
		(start 83.768184 -254.52705)
		(mid 84.05114 -254.450873)
		(end 84.334096 -254.52705)
		(width 0.0889)
		(layer "In2.Cu")
		(net "M_C_CPU1_SA_CA<4>")
	)
	(arc
		(start 92.228162 -254.52705)
		(mid 92.511118 -254.450873)
		(end 92.794074 -254.52705)
		(width 0.0889)
		(layer "In2.Cu")
		(net "M_C_CPU1_SA_CA<4>")
	)
	(arc
		(start 90.348054 -254.52705)
		(mid 90.63101 -254.450873)
		(end 90.913966 -254.52705)
		(width 0.0889)
		(layer "In2.Cu")
		(net "M_C_CPU1_SA_CA<4>")
	)
	(arc
		(start 88.10244 -254.531876)
		(mid 88.285948 -254.57737)
		(end 88.4682 -254.52705)
		(width 0.0889)
		(layer "In2.Cu")
		(net "M_C_CPU1_SA_CA<4>")
	)
	(arc
		(start 93.733874 -254.52705)
		(mid 93.890312 -254.576021)
		(end 94.052644 -254.553212)
		(width 0.0889)
		(layer "In2.Cu")
		(net "M_C_CPU1_SA_CA<4>")
	)
	(arc
		(start 89.034112 -254.52705)
		(mid 89.221056 -254.577305)
		(end 89.408 -254.52705)
		(width 0.0889)
		(layer "In2.Cu")
		(net "M_C_CPU1_SA_CA<4>")
	)
	(arc
		(start 80.008222 -254.52705)
		(mid 80.291178 -254.450873)
		(end 80.574134 -254.52705)
		(width 0.0889)
		(layer "In2.Cu")
		(net "M_C_CPU1_SA_CA<4>")
	)
	(arc
		(start 79.081884 -254.518414)
		(mid 79.358867 -254.45061)
		(end 79.633572 -254.52705)
		(width 0.0889)
		(layer "In2.Cu")
		(net "M_C_CPU1_SA_CA<4>")
	)
	(arc
		(start 87.528146 -254.52705)
		(mid 87.811102 -254.450873)
		(end 88.094058 -254.52705)
		(width 0.0889)
		(layer "In2.Cu")
		(net "M_C_CPU1_SA_CA<4>")
	)
	(arc
		(start 78.127606 -254.52705)
		(mid 78.401461 -254.4507)
		(end 78.67777 -254.517652)
		(width 0.0889)
		(layer "In2.Cu")
		(net "M_C_CPU1_SA_CA<4>")
	)
	(arc
		(start 85.648038 -254.52705)
		(mid 85.930994 -254.450873)
		(end 86.21395 -254.52705)
		(width 0.0889)
		(layer "In2.Cu")
		(net "M_C_CPU1_SA_CA<4>")
	)
	(arc
		(start 81.513934 -254.52705)
		(mid 81.696185 -254.5774)
		(end 81.879694 -254.531876)
		(width 0.0889)
		(layer "In2.Cu")
		(net "M_C_CPU1_SA_CA<4>")
	)
	(arc
		(start 79.633572 -254.52705)
		(mid 79.816077 -254.577527)
		(end 79.99984 -254.531876)
		(width 0.0889)
		(layer "In2.Cu")
		(net "M_C_CPU1_SA_CA<4>")
	)
	(arc
		(start 92.794074 -254.52705)
		(mid 92.981018 -254.577305)
		(end 93.167962 -254.52705)
		(width 0.0889)
		(layer "In2.Cu")
		(net "M_C_CPU1_SA_CA<4>")
	)
	(arc
		(start 83.402424 -254.531876)
		(mid 83.585932 -254.57737)
		(end 83.768184 -254.52705)
		(width 0.0889)
		(layer "In2.Cu")
		(net "M_C_CPU1_SA_CA<4>")
	)
	(arc
		(start 84.707984 -254.52705)
		(mid 84.99094 -254.450873)
		(end 85.273896 -254.52705)
		(width 0.0889)
		(layer "In2.Cu")
		(net "M_C_CPU1_SA_CA<4>")
	)
	(arc
		(start 76.97724 -254.837184)
		(mid 77.572975 -254.758336)
		(end 78.127606 -254.52705)
		(width 0.0889)
		(layer "In2.Cu")
		(net "M_C_CPU1_SA_CA<4>")
	)
	(arc
		(start 86.588092 -254.52705)
		(mid 86.871048 -254.450873)
		(end 87.154004 -254.52705)
		(width 0.0889)
		(layer "In2.Cu")
		(net "M_C_CPU1_SA_CA<4>")
	)
	(arc
		(start 89.408 -254.52705)
		(mid 89.690956 -254.450873)
		(end 89.973912 -254.52705)
		(width 0.0889)
		(layer "In2.Cu")
		(net "M_C_CPU1_SA_CA<4>")
	)
	(arc
		(start 80.574134 -254.52705)
		(mid 80.761078 -254.577305)
		(end 80.948022 -254.52705)
		(width 0.0889)
		(layer "In2.Cu")
		(net "M_C_CPU1_SA_CA<4>")
	)
	(arc
		(start 93.167962 -254.52705)
		(mid 93.450918 -254.450873)
		(end 93.733874 -254.52705)
		(width 0.0889)
		(layer "In2.Cu")
		(net "M_C_CPU1_SA_CA<4>")
	)
	(arc
		(start 82.46237 -254.531876)
		(mid 82.645878 -254.57737)
		(end 82.82813 -254.52705)
		(width 0.0889)
		(layer "In2.Cu")
		(net "M_C_CPU1_SA_CA<4>")
	)
	(arc
		(start 89.973912 -254.52705)
		(mid 90.156163 -254.5774)
		(end 90.339672 -254.531876)
		(width 0.0889)
		(layer "In2.Cu")
		(net "M_C_CPU1_SA_CA<4>")
	)
	(arc
		(start 81.888076 -254.52705)
		(mid 82.171032 -254.450873)
		(end 82.453988 -254.52705)
		(width 0.0889)
		(layer "In2.Cu")
		(net "M_C_CPU1_SA_CA<4>")
	)
	(segment
		(start 96.267778 -254.470408)
		(end 95.800926 -254.20447)
		(width 0.10668)
		(layer "F.Cu")
		(net "M_C_CPU1_SA_CA<3>")
	)
	(segment
		(start 47.020226 -252.154944)
		(end 60.447682 -252.154944)
		(width 0.14478)
		(layer "In2.Cu")
		(net "M_C_CPU1_SA_CA<3>")
	)
	(segment
		(start 75.958446 -254.468884)
		(end 76.225146 -254.468884)
		(width 0.0889)
		(layer "In2.Cu")
		(net "M_C_CPU1_SA_CA<3>")
	)
	(segment
		(start 83.394042 -253.88189)
		(end 83.402424 -253.877064)
		(width 0.0889)
		(layer "In2.Cu")
		(net "M_C_CPU1_SA_CA<3>")
	)
	(segment
		(start 40.664892 -250.460256)
		(end 45.325538 -250.460256)
		(width 0.14478)
		(layer "In2.Cu")
		(net "M_C_CPU1_SA_CA<3>")
	)
	(segment
		(start 72.042528 -253.122684)
		(end 73.388728 -254.468884)
		(width 0.14478)
		(layer "In2.Cu")
		(net "M_C_CPU1_SA_CA<3>")
	)
	(segment
		(start 77.629004 -253.956566)
		(end 77.757782 -253.88189)
		(width 0.0889)
		(layer "In2.Cu")
		(net "M_C_CPU1_SA_CA<3>")
	)
	(segment
		(start 91.85402 -253.88189)
		(end 91.862402 -253.877064)
		(width 0.0889)
		(layer "In2.Cu")
		(net "M_C_CPU1_SA_CA<3>")
	)
	(segment
		(start 79.63535 -253.882144)
		(end 79.658718 -253.868682)
		(width 0.0889)
		(layer "In2.Cu")
		(net "M_C_CPU1_SA_CA<3>")
	)
	(segment
		(start 79.609188 -253.89713)
		(end 79.63535 -253.882144)
		(width 0.0889)
		(layer "In2.Cu")
		(net "M_C_CPU1_SA_CA<3>")
	)
	(segment
		(start 66.76136 -253.76759)
		(end 68.31838 -253.122684)
		(width 0.14478)
		(layer "In2.Cu")
		(net "M_C_CPU1_SA_CA<3>")
	)
	(segment
		(start 95.039688 -253.877064)
		(end 95.04807 -253.88189)
		(width 0.0889)
		(layer "In2.Cu")
		(net "M_C_CPU1_SA_CA<3>")
	)
	(segment
		(start 90.913966 -253.88189)
		(end 90.922348 -253.877064)
		(width 0.0889)
		(layer "In2.Cu")
		(net "M_C_CPU1_SA_CA<3>")
	)
	(segment
		(start 81.879694 -253.877064)
		(end 81.888076 -253.88189)
		(width 0.0889)
		(layer "In2.Cu")
		(net "M_C_CPU1_SA_CA<3>")
	)
	(segment
		(start 76.590906 -254.103124)
		(end 77.083666 -254.103124)
		(width 0.0889)
		(layer "In2.Cu")
		(net "M_C_CPU1_SA_CA<3>")
	)
	(segment
		(start 85.639656 -253.877064)
		(end 85.648038 -253.88189)
		(width 0.0889)
		(layer "In2.Cu")
		(net "M_C_CPU1_SA_CA<3>")
	)
	(segment
		(start 45.325538 -250.460256)
		(end 47.020226 -252.154944)
		(width 0.14478)
		(layer "In2.Cu")
		(net "M_C_CPU1_SA_CA<3>")
	)
	(segment
		(start 40.23995 -250.035314)
		(end 40.664892 -250.460256)
		(width 0.14478)
		(layer "In2.Cu")
		(net "M_C_CPU1_SA_CA<3>")
	)
	(segment
		(start 78.106778 -253.868682)
		(end 78.130146 -253.882144)
		(width 0.0889)
		(layer "In2.Cu")
		(net "M_C_CPU1_SA_CA<3>")
	)
	(segment
		(start 79.050896 -253.869952)
		(end 79.07147 -253.88189)
		(width 0.0889)
		(layer "In2.Cu")
		(net "M_C_CPU1_SA_CA<3>")
	)
	(segment
		(start 60.447682 -252.154944)
		(end 62.060328 -253.76759)
		(width 0.14478)
		(layer "In2.Cu")
		(net "M_C_CPU1_SA_CA<3>")
	)
	(segment
		(start 73.388728 -254.468884)
		(end 75.958446 -254.468884)
		(width 0.14478)
		(layer "In2.Cu")
		(net "M_C_CPU1_SA_CA<3>")
	)
	(segment
		(start 68.31838 -253.122684)
		(end 72.042528 -253.122684)
		(width 0.14478)
		(layer "In2.Cu")
		(net "M_C_CPU1_SA_CA<3>")
	)
	(segment
		(start 95.647002 -253.93904)
		(end 95.800926 -254.20447)
		(width 0.0889)
		(layer "In2.Cu")
		(net "M_C_CPU1_SA_CA<3>")
	)
	(segment
		(start 86.57971 -253.877064)
		(end 86.588092 -253.88189)
		(width 0.0889)
		(layer "In2.Cu")
		(net "M_C_CPU1_SA_CA<3>")
	)
	(segment
		(start 90.339672 -253.877064)
		(end 90.348054 -253.88189)
		(width 0.0889)
		(layer "In2.Cu")
		(net "M_C_CPU1_SA_CA<3>")
	)
	(segment
		(start 94.099634 -253.877064)
		(end 94.108016 -253.88189)
		(width 0.0889)
		(layer "In2.Cu")
		(net "M_C_CPU1_SA_CA<3>")
	)
	(segment
		(start 62.060328 -253.76759)
		(end 66.76136 -253.76759)
		(width 0.14478)
		(layer "In2.Cu")
		(net "M_C_CPU1_SA_CA<3>")
	)
	(segment
		(start 95.55099 -253.91364)
		(end 95.647002 -253.93904)
		(width 0.0889)
		(layer "In2.Cu")
		(net "M_C_CPU1_SA_CA<3>")
	)
	(segment
		(start 88.094058 -253.88189)
		(end 88.10244 -253.877064)
		(width 0.0889)
		(layer "In2.Cu")
		(net "M_C_CPU1_SA_CA<3>")
	)
	(segment
		(start 78.130146 -253.882144)
		(end 78.169516 -253.905004)
		(width 0.0889)
		(layer "In2.Cu")
		(net "M_C_CPU1_SA_CA<3>")
	)
	(segment
		(start 82.453988 -253.88189)
		(end 82.46237 -253.877064)
		(width 0.0889)
		(layer "In2.Cu")
		(net "M_C_CPU1_SA_CA<3>")
	)
	(segment
		(start 76.225146 -254.468884)
		(end 76.590906 -254.103124)
		(width 0.0889)
		(layer "In2.Cu")
		(net "M_C_CPU1_SA_CA<3>")
	)
	(segment
		(start 87.154004 -253.88189)
		(end 87.162386 -253.877064)
		(width 0.0889)
		(layer "In2.Cu")
		(net "M_C_CPU1_SA_CA<3>")
	)
	(arc
		(start 78.169516 -253.905004)
		(mid 78.43564 -253.95861)
		(end 78.696058 -253.88189)
		(width 0.0889)
		(layer "In2.Cu")
		(net "M_C_CPU1_SA_CA<3>")
	)
	(arc
		(start 88.4682 -253.88189)
		(mid 88.751156 -253.958067)
		(end 89.034112 -253.88189)
		(width 0.0889)
		(layer "In2.Cu")
		(net "M_C_CPU1_SA_CA<3>")
	)
	(arc
		(start 91.288108 -253.88189)
		(mid 91.571064 -253.958067)
		(end 91.85402 -253.88189)
		(width 0.0889)
		(layer "In2.Cu")
		(net "M_C_CPU1_SA_CA<3>")
	)
	(arc
		(start 82.82813 -253.88189)
		(mid 83.111086 -253.958067)
		(end 83.394042 -253.88189)
		(width 0.0889)
		(layer "In2.Cu")
		(net "M_C_CPU1_SA_CA<3>")
	)
	(arc
		(start 89.408 -253.88189)
		(mid 89.690956 -253.958067)
		(end 89.973912 -253.88189)
		(width 0.0889)
		(layer "In2.Cu")
		(net "M_C_CPU1_SA_CA<3>")
	)
	(arc
		(start 81.513934 -253.88189)
		(mid 81.696185 -253.83154)
		(end 81.879694 -253.877064)
		(width 0.0889)
		(layer "In2.Cu")
		(net "M_C_CPU1_SA_CA<3>")
	)
	(arc
		(start 93.167962 -253.88189)
		(mid 93.450918 -253.958067)
		(end 93.733874 -253.88189)
		(width 0.0889)
		(layer "In2.Cu")
		(net "M_C_CPU1_SA_CA<3>")
	)
	(arc
		(start 78.696058 -253.88189)
		(mid 78.871968 -253.83108)
		(end 79.050896 -253.869952)
		(width 0.0889)
		(layer "In2.Cu")
		(net "M_C_CPU1_SA_CA<3>")
	)
	(arc
		(start 93.733874 -253.88189)
		(mid 93.916125 -253.83154)
		(end 94.099634 -253.877064)
		(width 0.0889)
		(layer "In2.Cu")
		(net "M_C_CPU1_SA_CA<3>")
	)
	(arc
		(start 77.083666 -254.103124)
		(mid 77.366006 -254.065838)
		(end 77.629004 -253.956566)
		(width 0.0889)
		(layer "In2.Cu")
		(net "M_C_CPU1_SA_CA<3>")
	)
	(arc
		(start 86.21395 -253.88189)
		(mid 86.396201 -253.83154)
		(end 86.57971 -253.877064)
		(width 0.0889)
		(layer "In2.Cu")
		(net "M_C_CPU1_SA_CA<3>")
	)
	(arc
		(start 84.334096 -253.88189)
		(mid 84.52104 -253.831635)
		(end 84.707984 -253.88189)
		(width 0.0889)
		(layer "In2.Cu")
		(net "M_C_CPU1_SA_CA<3>")
	)
	(arc
		(start 94.108016 -253.88189)
		(mid 94.390972 -253.958067)
		(end 94.673928 -253.88189)
		(width 0.0889)
		(layer "In2.Cu")
		(net "M_C_CPU1_SA_CA<3>")
	)
	(arc
		(start 87.528146 -253.88189)
		(mid 87.811102 -253.958067)
		(end 88.094058 -253.88189)
		(width 0.0889)
		(layer "In2.Cu")
		(net "M_C_CPU1_SA_CA<3>")
	)
	(arc
		(start 80.948022 -253.88189)
		(mid 81.230978 -253.958067)
		(end 81.513934 -253.88189)
		(width 0.0889)
		(layer "In2.Cu")
		(net "M_C_CPU1_SA_CA<3>")
	)
	(arc
		(start 85.273896 -253.88189)
		(mid 85.456147 -253.83154)
		(end 85.639656 -253.877064)
		(width 0.0889)
		(layer "In2.Cu")
		(net "M_C_CPU1_SA_CA<3>")
	)
	(arc
		(start 94.673928 -253.88189)
		(mid 94.856179 -253.83154)
		(end 95.039688 -253.877064)
		(width 0.0889)
		(layer "In2.Cu")
		(net "M_C_CPU1_SA_CA<3>")
	)
	(arc
		(start 91.862402 -253.877064)
		(mid 92.04591 -253.83157)
		(end 92.228162 -253.88189)
		(width 0.0889)
		(layer "In2.Cu")
		(net "M_C_CPU1_SA_CA<3>")
	)
	(arc
		(start 90.348054 -253.88189)
		(mid 90.63101 -253.958067)
		(end 90.913966 -253.88189)
		(width 0.0889)
		(layer "In2.Cu")
		(net "M_C_CPU1_SA_CA<3>")
	)
	(arc
		(start 80.008222 -253.88189)
		(mid 80.291178 -253.958067)
		(end 80.574134 -253.88189)
		(width 0.0889)
		(layer "In2.Cu")
		(net "M_C_CPU1_SA_CA<3>")
	)
	(arc
		(start 88.10244 -253.877064)
		(mid 88.285948 -253.83157)
		(end 88.4682 -253.88189)
		(width 0.0889)
		(layer "In2.Cu")
		(net "M_C_CPU1_SA_CA<3>")
	)
	(arc
		(start 89.034112 -253.88189)
		(mid 89.221056 -253.831635)
		(end 89.408 -253.88189)
		(width 0.0889)
		(layer "In2.Cu")
		(net "M_C_CPU1_SA_CA<3>")
	)
	(arc
		(start 92.794074 -253.88189)
		(mid 92.981018 -253.831635)
		(end 93.167962 -253.88189)
		(width 0.0889)
		(layer "In2.Cu")
		(net "M_C_CPU1_SA_CA<3>")
	)
	(arc
		(start 83.768184 -253.88189)
		(mid 84.05114 -253.958067)
		(end 84.334096 -253.88189)
		(width 0.0889)
		(layer "In2.Cu")
		(net "M_C_CPU1_SA_CA<3>")
	)
	(arc
		(start 82.46237 -253.877064)
		(mid 82.645878 -253.83157)
		(end 82.82813 -253.88189)
		(width 0.0889)
		(layer "In2.Cu")
		(net "M_C_CPU1_SA_CA<3>")
	)
	(arc
		(start 92.228162 -253.88189)
		(mid 92.511118 -253.958067)
		(end 92.794074 -253.88189)
		(width 0.0889)
		(layer "In2.Cu")
		(net "M_C_CPU1_SA_CA<3>")
	)
	(arc
		(start 95.04807 -253.88189)
		(mid 95.295783 -253.95711)
		(end 95.55099 -253.91364)
		(width 0.0889)
		(layer "In2.Cu")
		(net "M_C_CPU1_SA_CA<3>")
	)
	(arc
		(start 87.162386 -253.877064)
		(mid 87.345894 -253.83157)
		(end 87.528146 -253.88189)
		(width 0.0889)
		(layer "In2.Cu")
		(net "M_C_CPU1_SA_CA<3>")
	)
	(arc
		(start 80.574134 -253.88189)
		(mid 80.761078 -253.831635)
		(end 80.948022 -253.88189)
		(width 0.0889)
		(layer "In2.Cu")
		(net "M_C_CPU1_SA_CA<3>")
	)
	(arc
		(start 79.658718 -253.868682)
		(mid 79.835113 -253.831779)
		(end 80.008222 -253.88189)
		(width 0.0889)
		(layer "In2.Cu")
		(net "M_C_CPU1_SA_CA<3>")
	)
	(arc
		(start 86.588092 -253.88189)
		(mid 86.871048 -253.958067)
		(end 87.154004 -253.88189)
		(width 0.0889)
		(layer "In2.Cu")
		(net "M_C_CPU1_SA_CA<3>")
	)
	(arc
		(start 85.648038 -253.88189)
		(mid 85.930994 -253.958067)
		(end 86.21395 -253.88189)
		(width 0.0889)
		(layer "In2.Cu")
		(net "M_C_CPU1_SA_CA<3>")
	)
	(arc
		(start 83.402424 -253.877064)
		(mid 83.585932 -253.83157)
		(end 83.768184 -253.88189)
		(width 0.0889)
		(layer "In2.Cu")
		(net "M_C_CPU1_SA_CA<3>")
	)
	(arc
		(start 84.707984 -253.88189)
		(mid 84.99094 -253.958067)
		(end 85.273896 -253.88189)
		(width 0.0889)
		(layer "In2.Cu")
		(net "M_C_CPU1_SA_CA<3>")
	)
	(arc
		(start 89.973912 -253.88189)
		(mid 90.156163 -253.83154)
		(end 90.339672 -253.877064)
		(width 0.0889)
		(layer "In2.Cu")
		(net "M_C_CPU1_SA_CA<3>")
	)
	(arc
		(start 79.07147 -253.88189)
		(mid 79.3384 -253.957839)
		(end 79.609188 -253.89713)
		(width 0.0889)
		(layer "In2.Cu")
		(net "M_C_CPU1_SA_CA<3>")
	)
	(arc
		(start 90.922348 -253.877064)
		(mid 91.105856 -253.83157)
		(end 91.288108 -253.88189)
		(width 0.0889)
		(layer "In2.Cu")
		(net "M_C_CPU1_SA_CA<3>")
	)
	(arc
		(start 81.888076 -253.88189)
		(mid 82.171032 -253.958067)
		(end 82.453988 -253.88189)
		(width 0.0889)
		(layer "In2.Cu")
		(net "M_C_CPU1_SA_CA<3>")
	)
	(arc
		(start 77.757782 -253.88189)
		(mid 77.930637 -253.831901)
		(end 78.106778 -253.868682)
		(width 0.0889)
		(layer "In2.Cu")
		(net "M_C_CPU1_SA_CA<3>")
	)
	(segment
		(start 95.797878 -253.660402)
		(end 95.331026 -253.394464)
		(width 0.10668)
		(layer "F.Cu")
		(net "M_C_CPU1_SA_CA<2>")
	)
	(segment
		(start 66.671698 -253.31801)
		(end 68.24091 -252.668024)
		(width 0.14478)
		(layer "In2.Cu")
		(net "M_C_CPU1_SA_CA<2>")
	)
	(segment
		(start 84.229702 -253.72187)
		(end 84.238084 -253.717044)
		(width 0.0889)
		(layer "In2.Cu")
		(net "M_C_CPU1_SA_CA<2>")
	)
	(segment
		(start 50.514504 -251.690124)
		(end 50.677572 -251.527056)
		(width 0.14478)
		(layer "In2.Cu")
		(net "M_C_CPU1_SA_CA<2>")
	)
	(segment
		(start 88.929718 -253.72187)
		(end 88.9381 -253.717044)
		(width 0.0889)
		(layer "In2.Cu")
		(net "M_C_CPU1_SA_CA<2>")
	)
	(segment
		(start 53.839872 -251.473208)
		(end 54.00294 -251.31014)
		(width 0.14478)
		(layer "In2.Cu")
		(net "M_C_CPU1_SA_CA<2>")
	)
	(segment
		(start 49.00803 -251.473208)
		(end 49.00803 -251.527056)
		(width 0.14478)
		(layer "In2.Cu")
		(net "M_C_CPU1_SA_CA<2>")
	)
	(segment
		(start 60.238894 -251.31014)
		(end 62.246764 -253.31801)
		(width 0.14478)
		(layer "In2.Cu")
		(net "M_C_CPU1_SA_CA<2>")
	)
	(segment
		(start 80.46974 -253.72187)
		(end 80.478122 -253.717044)
		(width 0.0889)
		(layer "In2.Cu")
		(net "M_C_CPU1_SA_CA<2>")
	)
	(segment
		(start 72.294242 -252.668024)
		(end 73.609962 -253.983744)
		(width 0.14478)
		(layer "In2.Cu")
		(net "M_C_CPU1_SA_CA<2>")
	)
	(segment
		(start 93.263974 -253.717044)
		(end 93.272356 -253.72187)
		(width 0.0889)
		(layer "In2.Cu")
		(net "M_C_CPU1_SA_CA<2>")
	)
	(segment
		(start 49.727612 -251.31014)
		(end 49.95799 -251.31014)
		(width 0.14478)
		(layer "In2.Cu")
		(net "M_C_CPU1_SA_CA<2>")
	)
	(segment
		(start 79.138018 -253.699772)
		(end 79.167482 -253.717044)
		(width 0.0889)
		(layer "In2.Cu")
		(net "M_C_CPU1_SA_CA<2>")
	)
	(segment
		(start 79.5401 -253.71679)
		(end 79.566262 -253.701804)
		(width 0.0889)
		(layer "In2.Cu")
		(net "M_C_CPU1_SA_CA<2>")
	)
	(segment
		(start 76.413106 -253.823724)
		(end 77.26553 -253.823724)
		(width 0.0889)
		(layer "In2.Cu")
		(net "M_C_CPU1_SA_CA<2>")
	)
	(segment
		(start 50.121058 -251.473208)
		(end 50.121058 -251.527056)
		(width 0.14478)
		(layer "In2.Cu")
		(net "M_C_CPU1_SA_CA<2>")
	)
	(segment
		(start 81.044034 -253.717044)
		(end 81.052416 -253.72187)
		(width 0.0889)
		(layer "In2.Cu")
		(net "M_C_CPU1_SA_CA<2>")
	)
	(segment
		(start 62.246764 -253.31801)
		(end 66.671698 -253.31801)
		(width 0.14478)
		(layer "In2.Cu")
		(net "M_C_CPU1_SA_CA<2>")
	)
	(segment
		(start 75.960986 -253.983744)
		(end 76.253086 -253.983744)
		(width 0.0889)
		(layer "In2.Cu")
		(net "M_C_CPU1_SA_CA<2>")
	)
	(segment
		(start 49.401476 -251.690124)
		(end 49.564544 -251.527056)
		(width 0.14478)
		(layer "In2.Cu")
		(net "M_C_CPU1_SA_CA<2>")
	)
	(segment
		(start 49.564544 -251.527056)
		(end 49.564544 -251.473208)
		(width 0.14478)
		(layer "In2.Cu")
		(net "M_C_CPU1_SA_CA<2>")
	)
	(segment
		(start 50.677572 -251.473208)
		(end 50.84064 -251.31014)
		(width 0.14478)
		(layer "In2.Cu")
		(net "M_C_CPU1_SA_CA<2>")
	)
	(segment
		(start 47.013368 -251.31014)
		(end 48.844962 -251.31014)
		(width 0.14478)
		(layer "In2.Cu")
		(net "M_C_CPU1_SA_CA<2>")
	)
	(segment
		(start 45.308012 -249.604784)
		(end 47.013368 -251.31014)
		(width 0.14478)
		(layer "In2.Cu")
		(net "M_C_CPU1_SA_CA<2>")
	)
	(segment
		(start 50.84064 -251.31014)
		(end 53.12029 -251.31014)
		(width 0.14478)
		(layer "In2.Cu")
		(net "M_C_CPU1_SA_CA<2>")
	)
	(segment
		(start 94.204028 -253.717044)
		(end 94.21241 -253.72187)
		(width 0.0889)
		(layer "In2.Cu")
		(net "M_C_CPU1_SA_CA<2>")
	)
	(segment
		(start 95.48495 -253.659894)
		(end 95.331026 -253.394464)
		(width 0.0889)
		(layer "In2.Cu")
		(net "M_C_CPU1_SA_CA<2>")
	)
	(segment
		(start 49.95799 -251.31014)
		(end 50.121058 -251.473208)
		(width 0.14478)
		(layer "In2.Cu")
		(net "M_C_CPU1_SA_CA<2>")
	)
	(segment
		(start 49.00803 -251.527056)
		(end 49.171098 -251.690124)
		(width 0.14478)
		(layer "In2.Cu")
		(net "M_C_CPU1_SA_CA<2>")
	)
	(segment
		(start 84.803996 -253.717044)
		(end 84.812378 -253.72187)
		(width 0.0889)
		(layer "In2.Cu")
		(net "M_C_CPU1_SA_CA<2>")
	)
	(segment
		(start 68.24091 -252.668024)
		(end 72.294242 -252.668024)
		(width 0.14478)
		(layer "In2.Cu")
		(net "M_C_CPU1_SA_CA<2>")
	)
	(segment
		(start 85.74405 -253.717044)
		(end 85.752432 -253.72187)
		(width 0.0889)
		(layer "In2.Cu")
		(net "M_C_CPU1_SA_CA<2>")
	)
	(segment
		(start 44.759372 -249.604784)
		(end 45.308012 -249.604784)
		(width 0.14478)
		(layer "In2.Cu")
		(net "M_C_CPU1_SA_CA<2>")
	)
	(segment
		(start 48.844962 -251.31014)
		(end 49.00803 -251.473208)
		(width 0.14478)
		(layer "In2.Cu")
		(net "M_C_CPU1_SA_CA<2>")
	)
	(segment
		(start 83.289648 -253.72187)
		(end 83.29803 -253.717044)
		(width 0.0889)
		(layer "In2.Cu")
		(net "M_C_CPU1_SA_CA<2>")
	)
	(segment
		(start 53.283358 -251.534676)
		(end 53.446426 -251.697744)
		(width 0.14478)
		(layer "In2.Cu")
		(net "M_C_CPU1_SA_CA<2>")
	)
	(segment
		(start 76.253086 -253.983744)
		(end 76.413106 -253.823724)
		(width 0.0889)
		(layer "In2.Cu")
		(net "M_C_CPU1_SA_CA<2>")
	)
	(segment
		(start 73.609962 -253.983744)
		(end 75.960986 -253.983744)
		(width 0.14478)
		(layer "In2.Cu")
		(net "M_C_CPU1_SA_CA<2>")
	)
	(segment
		(start 49.171098 -251.690124)
		(end 49.401476 -251.690124)
		(width 0.14478)
		(layer "In2.Cu")
		(net "M_C_CPU1_SA_CA<2>")
	)
	(segment
		(start 53.676804 -251.697744)
		(end 53.839872 -251.534676)
		(width 0.14478)
		(layer "In2.Cu")
		(net "M_C_CPU1_SA_CA<2>")
	)
	(segment
		(start 78.22565 -253.71679)
		(end 78.256892 -253.73457)
		(width 0.0889)
		(layer "In2.Cu")
		(net "M_C_CPU1_SA_CA<2>")
	)
	(segment
		(start 50.121058 -251.527056)
		(end 50.284126 -251.690124)
		(width 0.14478)
		(layer "In2.Cu")
		(net "M_C_CPU1_SA_CA<2>")
	)
	(segment
		(start 53.283358 -251.473208)
		(end 53.283358 -251.534676)
		(width 0.14478)
		(layer "In2.Cu")
		(net "M_C_CPU1_SA_CA<2>")
	)
	(segment
		(start 79.518256 -253.729236)
		(end 79.5401 -253.71679)
		(width 0.0889)
		(layer "In2.Cu")
		(net "M_C_CPU1_SA_CA<2>")
	)
	(segment
		(start 91.749626 -253.72187)
		(end 91.758008 -253.717044)
		(width 0.0889)
		(layer "In2.Cu")
		(net "M_C_CPU1_SA_CA<2>")
	)
	(segment
		(start 53.446426 -251.697744)
		(end 53.676804 -251.697744)
		(width 0.14478)
		(layer "In2.Cu")
		(net "M_C_CPU1_SA_CA<2>")
	)
	(segment
		(start 50.284126 -251.690124)
		(end 50.514504 -251.690124)
		(width 0.14478)
		(layer "In2.Cu")
		(net "M_C_CPU1_SA_CA<2>")
	)
	(segment
		(start 53.839872 -251.534676)
		(end 53.839872 -251.473208)
		(width 0.14478)
		(layer "In2.Cu")
		(net "M_C_CPU1_SA_CA<2>")
	)
	(segment
		(start 95.462598 -253.743206)
		(end 95.48495 -253.659894)
		(width 0.0889)
		(layer "In2.Cu")
		(net "M_C_CPU1_SA_CA<2>")
	)
	(segment
		(start 53.12029 -251.31014)
		(end 53.283358 -251.473208)
		(width 0.14478)
		(layer "In2.Cu")
		(net "M_C_CPU1_SA_CA<2>")
	)
	(segment
		(start 49.564544 -251.473208)
		(end 49.727612 -251.31014)
		(width 0.14478)
		(layer "In2.Cu")
		(net "M_C_CPU1_SA_CA<2>")
	)
	(segment
		(start 92.68968 -253.72187)
		(end 92.698062 -253.717044)
		(width 0.0889)
		(layer "In2.Cu")
		(net "M_C_CPU1_SA_CA<2>")
	)
	(segment
		(start 87.989664 -253.72187)
		(end 87.998046 -253.717044)
		(width 0.0889)
		(layer "In2.Cu")
		(net "M_C_CPU1_SA_CA<2>")
	)
	(segment
		(start 89.504012 -253.717044)
		(end 89.512394 -253.72187)
		(width 0.0889)
		(layer "In2.Cu")
		(net "M_C_CPU1_SA_CA<2>")
	)
	(segment
		(start 50.677572 -251.527056)
		(end 50.677572 -251.473208)
		(width 0.14478)
		(layer "In2.Cu")
		(net "M_C_CPU1_SA_CA<2>")
	)
	(segment
		(start 78.199488 -253.701804)
		(end 78.22565 -253.71679)
		(width 0.0889)
		(layer "In2.Cu")
		(net "M_C_CPU1_SA_CA<2>")
	)
	(segment
		(start 44.340018 -249.18543)
		(end 44.759372 -249.604784)
		(width 0.14478)
		(layer "In2.Cu")
		(net "M_C_CPU1_SA_CA<2>")
	)
	(segment
		(start 54.00294 -251.31014)
		(end 60.238894 -251.31014)
		(width 0.14478)
		(layer "In2.Cu")
		(net "M_C_CPU1_SA_CA<2>")
	)
	(arc
		(start 88.9381 -253.717044)
		(mid 89.221056 -253.640867)
		(end 89.504012 -253.717044)
		(width 0.0889)
		(layer "In2.Cu")
		(net "M_C_CPU1_SA_CA<2>")
	)
	(arc
		(start 92.698062 -253.717044)
		(mid 92.981018 -253.640867)
		(end 93.263974 -253.717044)
		(width 0.0889)
		(layer "In2.Cu")
		(net "M_C_CPU1_SA_CA<2>")
	)
	(arc
		(start 78.256892 -253.73457)
		(mid 78.430354 -253.767504)
		(end 78.599538 -253.717044)
		(width 0.0889)
		(layer "In2.Cu")
		(net "M_C_CPU1_SA_CA<2>")
	)
	(arc
		(start 91.758008 -253.717044)
		(mid 92.040964 -253.640867)
		(end 92.32392 -253.717044)
		(width 0.0889)
		(layer "In2.Cu")
		(net "M_C_CPU1_SA_CA<2>")
	)
	(arc
		(start 87.057992 -253.717044)
		(mid 87.340948 -253.640867)
		(end 87.623904 -253.717044)
		(width 0.0889)
		(layer "In2.Cu")
		(net "M_C_CPU1_SA_CA<2>")
	)
	(arc
		(start 82.357976 -253.717044)
		(mid 82.640932 -253.640867)
		(end 82.923888 -253.717044)
		(width 0.0889)
		(layer "In2.Cu")
		(net "M_C_CPU1_SA_CA<2>")
	)
	(arc
		(start 81.984088 -253.717044)
		(mid 82.171032 -253.767299)
		(end 82.357976 -253.717044)
		(width 0.0889)
		(layer "In2.Cu")
		(net "M_C_CPU1_SA_CA<2>")
	)
	(arc
		(start 86.118192 -253.717044)
		(mid 86.401148 -253.640867)
		(end 86.684104 -253.717044)
		(width 0.0889)
		(layer "In2.Cu")
		(net "M_C_CPU1_SA_CA<2>")
	)
	(arc
		(start 88.563958 -253.717044)
		(mid 88.746209 -253.767394)
		(end 88.929718 -253.72187)
		(width 0.0889)
		(layer "In2.Cu")
		(net "M_C_CPU1_SA_CA<2>")
	)
	(arc
		(start 95.144082 -253.717044)
		(mid 95.300401 -253.766039)
		(end 95.462598 -253.743206)
		(width 0.0889)
		(layer "In2.Cu")
		(net "M_C_CPU1_SA_CA<2>")
	)
	(arc
		(start 79.167482 -253.717044)
		(mid 79.341332 -253.76695)
		(end 79.518256 -253.729236)
		(width 0.0889)
		(layer "In2.Cu")
		(net "M_C_CPU1_SA_CA<2>")
	)
	(arc
		(start 83.29803 -253.717044)
		(mid 83.580986 -253.640867)
		(end 83.863942 -253.717044)
		(width 0.0889)
		(layer "In2.Cu")
		(net "M_C_CPU1_SA_CA<2>")
	)
	(arc
		(start 87.623904 -253.717044)
		(mid 87.806155 -253.767394)
		(end 87.989664 -253.72187)
		(width 0.0889)
		(layer "In2.Cu")
		(net "M_C_CPU1_SA_CA<2>")
	)
	(arc
		(start 84.812378 -253.72187)
		(mid 84.995886 -253.767364)
		(end 85.178138 -253.717044)
		(width 0.0889)
		(layer "In2.Cu")
		(net "M_C_CPU1_SA_CA<2>")
	)
	(arc
		(start 85.178138 -253.717044)
		(mid 85.461094 -253.640867)
		(end 85.74405 -253.717044)
		(width 0.0889)
		(layer "In2.Cu")
		(net "M_C_CPU1_SA_CA<2>")
	)
	(arc
		(start 80.10398 -253.717044)
		(mid 80.286231 -253.767394)
		(end 80.46974 -253.72187)
		(width 0.0889)
		(layer "In2.Cu")
		(net "M_C_CPU1_SA_CA<2>")
	)
	(arc
		(start 87.998046 -253.717044)
		(mid 88.281002 -253.640867)
		(end 88.563958 -253.717044)
		(width 0.0889)
		(layer "In2.Cu")
		(net "M_C_CPU1_SA_CA<2>")
	)
	(arc
		(start 92.32392 -253.717044)
		(mid 92.506171 -253.767394)
		(end 92.68968 -253.72187)
		(width 0.0889)
		(layer "In2.Cu")
		(net "M_C_CPU1_SA_CA<2>")
	)
	(arc
		(start 89.512394 -253.72187)
		(mid 89.695902 -253.767364)
		(end 89.878154 -253.717044)
		(width 0.0889)
		(layer "In2.Cu")
		(net "M_C_CPU1_SA_CA<2>")
	)
	(arc
		(start 89.878154 -253.717044)
		(mid 90.16111 -253.640867)
		(end 90.444066 -253.717044)
		(width 0.0889)
		(layer "In2.Cu")
		(net "M_C_CPU1_SA_CA<2>")
	)
	(arc
		(start 84.238084 -253.717044)
		(mid 84.52104 -253.640867)
		(end 84.803996 -253.717044)
		(width 0.0889)
		(layer "In2.Cu")
		(net "M_C_CPU1_SA_CA<2>")
	)
	(arc
		(start 79.566262 -253.701804)
		(mid 79.837048 -253.641158)
		(end 80.10398 -253.717044)
		(width 0.0889)
		(layer "In2.Cu")
		(net "M_C_CPU1_SA_CA<2>")
	)
	(arc
		(start 90.817954 -253.717044)
		(mid 91.10091 -253.640867)
		(end 91.383866 -253.717044)
		(width 0.0889)
		(layer "In2.Cu")
		(net "M_C_CPU1_SA_CA<2>")
	)
	(arc
		(start 86.684104 -253.717044)
		(mid 86.871048 -253.767299)
		(end 87.057992 -253.717044)
		(width 0.0889)
		(layer "In2.Cu")
		(net "M_C_CPU1_SA_CA<2>")
	)
	(arc
		(start 85.752432 -253.72187)
		(mid 85.93594 -253.767364)
		(end 86.118192 -253.717044)
		(width 0.0889)
		(layer "In2.Cu")
		(net "M_C_CPU1_SA_CA<2>")
	)
	(arc
		(start 93.272356 -253.72187)
		(mid 93.455864 -253.767364)
		(end 93.638116 -253.717044)
		(width 0.0889)
		(layer "In2.Cu")
		(net "M_C_CPU1_SA_CA<2>")
	)
	(arc
		(start 77.26553 -253.823724)
		(mid 77.470704 -253.796586)
		(end 77.66177 -253.717044)
		(width 0.0889)
		(layer "In2.Cu")
		(net "M_C_CPU1_SA_CA<2>")
	)
	(arc
		(start 93.638116 -253.717044)
		(mid 93.921072 -253.640867)
		(end 94.204028 -253.717044)
		(width 0.0889)
		(layer "In2.Cu")
		(net "M_C_CPU1_SA_CA<2>")
	)
	(arc
		(start 94.57817 -253.717044)
		(mid 94.861126 -253.640867)
		(end 95.144082 -253.717044)
		(width 0.0889)
		(layer "In2.Cu")
		(net "M_C_CPU1_SA_CA<2>")
	)
	(arc
		(start 78.599538 -253.717044)
		(mid 78.866595 -253.640009)
		(end 79.138018 -253.699772)
		(width 0.0889)
		(layer "In2.Cu")
		(net "M_C_CPU1_SA_CA<2>")
	)
	(arc
		(start 81.052416 -253.72187)
		(mid 81.235924 -253.767364)
		(end 81.418176 -253.717044)
		(width 0.0889)
		(layer "In2.Cu")
		(net "M_C_CPU1_SA_CA<2>")
	)
	(arc
		(start 82.923888 -253.717044)
		(mid 83.106139 -253.767394)
		(end 83.289648 -253.72187)
		(width 0.0889)
		(layer "In2.Cu")
		(net "M_C_CPU1_SA_CA<2>")
	)
	(arc
		(start 94.21241 -253.72187)
		(mid 94.395918 -253.767364)
		(end 94.57817 -253.717044)
		(width 0.0889)
		(layer "In2.Cu")
		(net "M_C_CPU1_SA_CA<2>")
	)
	(arc
		(start 91.383866 -253.717044)
		(mid 91.566117 -253.767394)
		(end 91.749626 -253.72187)
		(width 0.0889)
		(layer "In2.Cu")
		(net "M_C_CPU1_SA_CA<2>")
	)
	(arc
		(start 80.478122 -253.717044)
		(mid 80.761078 -253.640867)
		(end 81.044034 -253.717044)
		(width 0.0889)
		(layer "In2.Cu")
		(net "M_C_CPU1_SA_CA<2>")
	)
	(arc
		(start 81.418176 -253.717044)
		(mid 81.701132 -253.640867)
		(end 81.984088 -253.717044)
		(width 0.0889)
		(layer "In2.Cu")
		(net "M_C_CPU1_SA_CA<2>")
	)
	(arc
		(start 90.444066 -253.717044)
		(mid 90.63101 -253.767299)
		(end 90.817954 -253.717044)
		(width 0.0889)
		(layer "In2.Cu")
		(net "M_C_CPU1_SA_CA<2>")
	)
	(arc
		(start 83.863942 -253.717044)
		(mid 84.046193 -253.767394)
		(end 84.229702 -253.72187)
		(width 0.0889)
		(layer "In2.Cu")
		(net "M_C_CPU1_SA_CA<2>")
	)
	(arc
		(start 77.66177 -253.717044)
		(mid 77.9287 -253.641095)
		(end 78.199488 -253.701804)
		(width 0.0889)
		(layer "In2.Cu")
		(net "M_C_CPU1_SA_CA<2>")
	)
	(segment
		(start 94.857824 -253.660402)
		(end 94.390972 -253.394464)
		(width 0.10668)
		(layer "F.Cu")
		(net "M_C_CPU1_SA_CA<1>")
	)
	(segment
		(start 75.966066 -253.51232)
		(end 76.895706 -253.51232)
		(width 0.0889)
		(layer "In2.Cu")
		(net "M_C_CPU1_SA_CA<1>")
	)
	(segment
		(start 94.237048 -253.129034)
		(end 94.390972 -253.394464)
		(width 0.0889)
		(layer "In2.Cu")
		(net "M_C_CPU1_SA_CA<1>")
	)
	(segment
		(start 84.229702 -253.067058)
		(end 84.238084 -253.071884)
		(width 0.0889)
		(layer "In2.Cu")
		(net "M_C_CPU1_SA_CA<1>")
	)
	(segment
		(start 73.781666 -253.51232)
		(end 75.966066 -253.51232)
		(width 0.14478)
		(layer "In2.Cu")
		(net "M_C_CPU1_SA_CA<1>")
	)
	(segment
		(start 46.999398 -250.460256)
		(end 60.266834 -250.460256)
		(width 0.14478)
		(layer "In2.Cu")
		(net "M_C_CPU1_SA_CA<1>")
	)
	(segment
		(start 66.581782 -252.86843)
		(end 68.16344 -252.213364)
		(width 0.14478)
		(layer "In2.Cu")
		(net "M_C_CPU1_SA_CA<1>")
	)
	(segment
		(start 45.299376 -248.760234)
		(end 46.999398 -250.460256)
		(width 0.14478)
		(layer "In2.Cu")
		(net "M_C_CPU1_SA_CA<1>")
	)
	(segment
		(start 89.504012 -253.071884)
		(end 89.512394 -253.067058)
		(width 0.0889)
		(layer "In2.Cu")
		(net "M_C_CPU1_SA_CA<1>")
	)
	(segment
		(start 81.044034 -253.071884)
		(end 81.052416 -253.067058)
		(width 0.0889)
		(layer "In2.Cu")
		(net "M_C_CPU1_SA_CA<1>")
	)
	(segment
		(start 83.289648 -253.067058)
		(end 83.29803 -253.071884)
		(width 0.0889)
		(layer "In2.Cu")
		(net "M_C_CPU1_SA_CA<1>")
	)
	(segment
		(start 93.263974 -253.071884)
		(end 93.272356 -253.067058)
		(width 0.0889)
		(layer "In2.Cu")
		(net "M_C_CPU1_SA_CA<1>")
	)
	(segment
		(start 94.141036 -253.103634)
		(end 94.237048 -253.129034)
		(width 0.0889)
		(layer "In2.Cu")
		(net "M_C_CPU1_SA_CA<1>")
	)
	(segment
		(start 60.266834 -250.460256)
		(end 62.675008 -252.86843)
		(width 0.14478)
		(layer "In2.Cu")
		(net "M_C_CPU1_SA_CA<1>")
	)
	(segment
		(start 40.23995 -248.335292)
		(end 40.664892 -248.760234)
		(width 0.14478)
		(layer "In2.Cu")
		(net "M_C_CPU1_SA_CA<1>")
	)
	(segment
		(start 88.929718 -253.067058)
		(end 88.9381 -253.071884)
		(width 0.0889)
		(layer "In2.Cu")
		(net "M_C_CPU1_SA_CA<1>")
	)
	(segment
		(start 79.163164 -253.071884)
		(end 79.174848 -253.065026)
		(width 0.0889)
		(layer "In2.Cu")
		(net "M_C_CPU1_SA_CA<1>")
	)
	(segment
		(start 68.16344 -252.213364)
		(end 72.48271 -252.213364)
		(width 0.14478)
		(layer "In2.Cu")
		(net "M_C_CPU1_SA_CA<1>")
	)
	(segment
		(start 77.955902 -253.227078)
		(end 78.223618 -253.071884)
		(width 0.0889)
		(layer "In2.Cu")
		(net "M_C_CPU1_SA_CA<1>")
	)
	(segment
		(start 91.749626 -253.067058)
		(end 91.758008 -253.071884)
		(width 0.0889)
		(layer "In2.Cu")
		(net "M_C_CPU1_SA_CA<1>")
	)
	(segment
		(start 72.48271 -252.213364)
		(end 73.781666 -253.51232)
		(width 0.14478)
		(layer "In2.Cu")
		(net "M_C_CPU1_SA_CA<1>")
	)
	(segment
		(start 40.664892 -248.760234)
		(end 45.299376 -248.760234)
		(width 0.14478)
		(layer "In2.Cu")
		(net "M_C_CPU1_SA_CA<1>")
	)
	(segment
		(start 80.089248 -253.08052)
		(end 80.10398 -253.071884)
		(width 0.0889)
		(layer "In2.Cu")
		(net "M_C_CPU1_SA_CA<1>")
	)
	(segment
		(start 80.46974 -253.067058)
		(end 80.478122 -253.071884)
		(width 0.0889)
		(layer "In2.Cu")
		(net "M_C_CPU1_SA_CA<1>")
	)
	(segment
		(start 78.59776 -253.072138)
		(end 78.603348 -253.07544)
		(width 0.0889)
		(layer "In2.Cu")
		(net "M_C_CPU1_SA_CA<1>")
	)
	(segment
		(start 78.579472 -253.061724)
		(end 78.59776 -253.072138)
		(width 0.0889)
		(layer "In2.Cu")
		(net "M_C_CPU1_SA_CA<1>")
	)
	(segment
		(start 87.989664 -253.067058)
		(end 87.998046 -253.071884)
		(width 0.0889)
		(layer "In2.Cu")
		(net "M_C_CPU1_SA_CA<1>")
	)
	(segment
		(start 85.74405 -253.071884)
		(end 85.752432 -253.067058)
		(width 0.0889)
		(layer "In2.Cu")
		(net "M_C_CPU1_SA_CA<1>")
	)
	(segment
		(start 62.675008 -252.86843)
		(end 66.581782 -252.86843)
		(width 0.14478)
		(layer "In2.Cu")
		(net "M_C_CPU1_SA_CA<1>")
	)
	(segment
		(start 84.803996 -253.071884)
		(end 84.812378 -253.067058)
		(width 0.0889)
		(layer "In2.Cu")
		(net "M_C_CPU1_SA_CA<1>")
	)
	(segment
		(start 92.68968 -253.067058)
		(end 92.698062 -253.071884)
		(width 0.0889)
		(layer "In2.Cu")
		(net "M_C_CPU1_SA_CA<1>")
	)
	(arc
		(start 81.052416 -253.067058)
		(mid 81.235924 -253.021564)
		(end 81.418176 -253.071884)
		(width 0.0889)
		(layer "In2.Cu")
		(net "M_C_CPU1_SA_CA<1>")
	)
	(arc
		(start 92.32392 -253.071884)
		(mid 92.506171 -253.021534)
		(end 92.68968 -253.067058)
		(width 0.0889)
		(layer "In2.Cu")
		(net "M_C_CPU1_SA_CA<1>")
	)
	(arc
		(start 82.357976 -253.071884)
		(mid 82.640932 -253.148061)
		(end 82.923888 -253.071884)
		(width 0.0889)
		(layer "In2.Cu")
		(net "M_C_CPU1_SA_CA<1>")
	)
	(arc
		(start 86.684104 -253.071884)
		(mid 86.871048 -253.021629)
		(end 87.057992 -253.071884)
		(width 0.0889)
		(layer "In2.Cu")
		(net "M_C_CPU1_SA_CA<1>")
	)
	(arc
		(start 91.758008 -253.071884)
		(mid 92.040964 -253.148061)
		(end 92.32392 -253.071884)
		(width 0.0889)
		(layer "In2.Cu")
		(net "M_C_CPU1_SA_CA<1>")
	)
	(arc
		(start 88.563958 -253.071884)
		(mid 88.746209 -253.021534)
		(end 88.929718 -253.067058)
		(width 0.0889)
		(layer "In2.Cu")
		(net "M_C_CPU1_SA_CA<1>")
	)
	(arc
		(start 93.272356 -253.067058)
		(mid 93.455864 -253.021564)
		(end 93.638116 -253.071884)
		(width 0.0889)
		(layer "In2.Cu")
		(net "M_C_CPU1_SA_CA<1>")
	)
	(arc
		(start 91.383866 -253.071884)
		(mid 91.566117 -253.021534)
		(end 91.749626 -253.067058)
		(width 0.0889)
		(layer "In2.Cu")
		(net "M_C_CPU1_SA_CA<1>")
	)
	(arc
		(start 82.923888 -253.071884)
		(mid 83.106139 -253.021534)
		(end 83.289648 -253.067058)
		(width 0.0889)
		(layer "In2.Cu")
		(net "M_C_CPU1_SA_CA<1>")
	)
	(arc
		(start 92.698062 -253.071884)
		(mid 92.981018 -253.148061)
		(end 93.263974 -253.071884)
		(width 0.0889)
		(layer "In2.Cu")
		(net "M_C_CPU1_SA_CA<1>")
	)
	(arc
		(start 90.444066 -253.071884)
		(mid 90.63101 -253.021629)
		(end 90.817954 -253.071884)
		(width 0.0889)
		(layer "In2.Cu")
		(net "M_C_CPU1_SA_CA<1>")
	)
	(arc
		(start 79.53756 -253.071884)
		(mid 79.812266 -253.148248)
		(end 80.089248 -253.08052)
		(width 0.0889)
		(layer "In2.Cu")
		(net "M_C_CPU1_SA_CA<1>")
	)
	(arc
		(start 78.603348 -253.07544)
		(mid 78.883737 -253.148109)
		(end 79.163164 -253.071884)
		(width 0.0889)
		(layer "In2.Cu")
		(net "M_C_CPU1_SA_CA<1>")
	)
	(arc
		(start 83.29803 -253.071884)
		(mid 83.580986 -253.148061)
		(end 83.863942 -253.071884)
		(width 0.0889)
		(layer "In2.Cu")
		(net "M_C_CPU1_SA_CA<1>")
	)
	(arc
		(start 87.623904 -253.071884)
		(mid 87.806155 -253.021534)
		(end 87.989664 -253.067058)
		(width 0.0889)
		(layer "In2.Cu")
		(net "M_C_CPU1_SA_CA<1>")
	)
	(arc
		(start 93.638116 -253.071884)
		(mid 93.885829 -253.147104)
		(end 94.141036 -253.103634)
		(width 0.0889)
		(layer "In2.Cu")
		(net "M_C_CPU1_SA_CA<1>")
	)
	(arc
		(start 84.812378 -253.067058)
		(mid 84.995886 -253.021564)
		(end 85.178138 -253.071884)
		(width 0.0889)
		(layer "In2.Cu")
		(net "M_C_CPU1_SA_CA<1>")
	)
	(arc
		(start 90.817954 -253.071884)
		(mid 91.10091 -253.148061)
		(end 91.383866 -253.071884)
		(width 0.0889)
		(layer "In2.Cu")
		(net "M_C_CPU1_SA_CA<1>")
	)
	(arc
		(start 81.984088 -253.071884)
		(mid 82.171032 -253.021629)
		(end 82.357976 -253.071884)
		(width 0.0889)
		(layer "In2.Cu")
		(net "M_C_CPU1_SA_CA<1>")
	)
	(arc
		(start 80.10398 -253.071884)
		(mid 80.286231 -253.021534)
		(end 80.46974 -253.067058)
		(width 0.0889)
		(layer "In2.Cu")
		(net "M_C_CPU1_SA_CA<1>")
	)
	(arc
		(start 87.057992 -253.071884)
		(mid 87.340948 -253.148061)
		(end 87.623904 -253.071884)
		(width 0.0889)
		(layer "In2.Cu")
		(net "M_C_CPU1_SA_CA<1>")
	)
	(arc
		(start 86.118192 -253.071884)
		(mid 86.401148 -253.148061)
		(end 86.684104 -253.071884)
		(width 0.0889)
		(layer "In2.Cu")
		(net "M_C_CPU1_SA_CA<1>")
	)
	(arc
		(start 81.418176 -253.071884)
		(mid 81.701132 -253.148061)
		(end 81.984088 -253.071884)
		(width 0.0889)
		(layer "In2.Cu")
		(net "M_C_CPU1_SA_CA<1>")
	)
	(arc
		(start 76.895706 -253.51232)
		(mid 77.444661 -253.439775)
		(end 77.955902 -253.227078)
		(width 0.0889)
		(layer "In2.Cu")
		(net "M_C_CPU1_SA_CA<1>")
	)
	(arc
		(start 89.512394 -253.067058)
		(mid 89.695902 -253.021564)
		(end 89.878154 -253.071884)
		(width 0.0889)
		(layer "In2.Cu")
		(net "M_C_CPU1_SA_CA<1>")
	)
	(arc
		(start 88.9381 -253.071884)
		(mid 89.221056 -253.148061)
		(end 89.504012 -253.071884)
		(width 0.0889)
		(layer "In2.Cu")
		(net "M_C_CPU1_SA_CA<1>")
	)
	(arc
		(start 79.174848 -253.065026)
		(mid 79.357103 -253.021373)
		(end 79.53756 -253.071884)
		(width 0.0889)
		(layer "In2.Cu")
		(net "M_C_CPU1_SA_CA<1>")
	)
	(arc
		(start 78.223618 -253.071884)
		(mid 78.400246 -253.021651)
		(end 78.579472 -253.061724)
		(width 0.0889)
		(layer "In2.Cu")
		(net "M_C_CPU1_SA_CA<1>")
	)
	(arc
		(start 85.752432 -253.067058)
		(mid 85.93594 -253.021564)
		(end 86.118192 -253.071884)
		(width 0.0889)
		(layer "In2.Cu")
		(net "M_C_CPU1_SA_CA<1>")
	)
	(arc
		(start 85.178138 -253.071884)
		(mid 85.461094 -253.148061)
		(end 85.74405 -253.071884)
		(width 0.0889)
		(layer "In2.Cu")
		(net "M_C_CPU1_SA_CA<1>")
	)
	(arc
		(start 80.478122 -253.071884)
		(mid 80.761078 -253.148061)
		(end 81.044034 -253.071884)
		(width 0.0889)
		(layer "In2.Cu")
		(net "M_C_CPU1_SA_CA<1>")
	)
	(arc
		(start 84.238084 -253.071884)
		(mid 84.52104 -253.148061)
		(end 84.803996 -253.071884)
		(width 0.0889)
		(layer "In2.Cu")
		(net "M_C_CPU1_SA_CA<1>")
	)
	(arc
		(start 89.878154 -253.071884)
		(mid 90.16111 -253.148061)
		(end 90.444066 -253.071884)
		(width 0.0889)
		(layer "In2.Cu")
		(net "M_C_CPU1_SA_CA<1>")
	)
	(arc
		(start 87.998046 -253.071884)
		(mid 88.281002 -253.148061)
		(end 88.563958 -253.071884)
		(width 0.0889)
		(layer "In2.Cu")
		(net "M_C_CPU1_SA_CA<1>")
	)
	(arc
		(start 83.863942 -253.071884)
		(mid 84.046193 -253.021534)
		(end 84.229702 -253.067058)
		(width 0.0889)
		(layer "In2.Cu")
		(net "M_C_CPU1_SA_CA<1>")
	)
	(segment
		(start 94.387924 -252.850396)
		(end 93.921072 -252.584458)
		(width 0.10668)
		(layer "F.Cu")
		(net "M_C_CPU1_SA_CA<0>")
	)
	(segment
		(start 56.755538 -249.77344)
		(end 56.755538 -249.837956)
		(width 0.14478)
		(layer "In2.Cu")
		(net "M_C_CPU1_SA_CA<0>")
	)
	(segment
		(start 94.074996 -252.849888)
		(end 93.921072 -252.584458)
		(width 0.0889)
		(layer "In2.Cu")
		(net "M_C_CPU1_SA_CA<0>")
	)
	(segment
		(start 53.227478 -249.610372)
		(end 53.457856 -249.610372)
		(width 0.14478)
		(layer "In2.Cu")
		(net "M_C_CPU1_SA_CA<0>")
	)
	(segment
		(start 78.67777 -252.89764)
		(end 78.693518 -252.906784)
		(width 0.0889)
		(layer "In2.Cu")
		(net "M_C_CPU1_SA_CA<0>")
	)
	(segment
		(start 53.620924 -249.822716)
		(end 53.783992 -249.985784)
		(width 0.14478)
		(layer "In2.Cu")
		(net "M_C_CPU1_SA_CA<0>")
	)
	(segment
		(start 53.620924 -249.77344)
		(end 53.620924 -249.822716)
		(width 0.14478)
		(layer "In2.Cu")
		(net "M_C_CPU1_SA_CA<0>")
	)
	(segment
		(start 58.588148 -249.610372)
		(end 60.052966 -249.610372)
		(width 0.14478)
		(layer "In2.Cu")
		(net "M_C_CPU1_SA_CA<0>")
	)
	(segment
		(start 66.49212 -252.41885)
		(end 68.08597 -251.758704)
		(width 0.14478)
		(layer "In2.Cu")
		(net "M_C_CPU1_SA_CA<0>")
	)
	(segment
		(start 76.530708 -253.21514)
		(end 76.98486 -253.21514)
		(width 0.0889)
		(layer "In2.Cu")
		(net "M_C_CPU1_SA_CA<0>")
	)
	(segment
		(start 52.507896 -249.822716)
		(end 52.670964 -249.985784)
		(width 0.14478)
		(layer "In2.Cu")
		(net "M_C_CPU1_SA_CA<0>")
	)
	(segment
		(start 44.757594 -247.902984)
		(end 45.232066 -247.902984)
		(width 0.14478)
		(layer "In2.Cu")
		(net "M_C_CPU1_SA_CA<0>")
	)
	(segment
		(start 49.045114 -249.993404)
		(end 49.275492 -249.993404)
		(width 0.14478)
		(layer "In2.Cu")
		(net "M_C_CPU1_SA_CA<0>")
	)
	(segment
		(start 44.340018 -247.485408)
		(end 44.757594 -247.902984)
		(width 0.14478)
		(layer "In2.Cu")
		(net "M_C_CPU1_SA_CA<0>")
	)
	(segment
		(start 50.38852 -249.993404)
		(end 50.551588 -249.830336)
		(width 0.14478)
		(layer "In2.Cu")
		(net "M_C_CPU1_SA_CA<0>")
	)
	(segment
		(start 52.670964 -249.985784)
		(end 52.901342 -249.985784)
		(width 0.14478)
		(layer "In2.Cu")
		(net "M_C_CPU1_SA_CA<0>")
	)
	(segment
		(start 48.718978 -249.610372)
		(end 48.882046 -249.77344)
		(width 0.14478)
		(layer "In2.Cu")
		(net "M_C_CPU1_SA_CA<0>")
	)
	(segment
		(start 94.052644 -252.9332)
		(end 94.074996 -252.849888)
		(width 0.0889)
		(layer "In2.Cu")
		(net "M_C_CPU1_SA_CA<0>")
	)
	(segment
		(start 57.868566 -249.77344)
		(end 57.868566 -249.837956)
		(width 0.14478)
		(layer "In2.Cu")
		(net "M_C_CPU1_SA_CA<0>")
	)
	(segment
		(start 57.312052 -249.77344)
		(end 57.47512 -249.610372)
		(width 0.14478)
		(layer "In2.Cu")
		(net "M_C_CPU1_SA_CA<0>")
	)
	(segment
		(start 50.551588 -249.77344)
		(end 50.714656 -249.610372)
		(width 0.14478)
		(layer "In2.Cu")
		(net "M_C_CPU1_SA_CA<0>")
	)
	(segment
		(start 53.06441 -249.822716)
		(end 53.06441 -249.77344)
		(width 0.14478)
		(layer "In2.Cu")
		(net "M_C_CPU1_SA_CA<0>")
	)
	(segment
		(start 58.42508 -249.77344)
		(end 58.588148 -249.610372)
		(width 0.14478)
		(layer "In2.Cu")
		(net "M_C_CPU1_SA_CA<0>")
	)
	(segment
		(start 48.882046 -249.77344)
		(end 48.882046 -249.830336)
		(width 0.14478)
		(layer "In2.Cu")
		(net "M_C_CPU1_SA_CA<0>")
	)
	(segment
		(start 56.918606 -250.001024)
		(end 57.148984 -250.001024)
		(width 0.14478)
		(layer "In2.Cu")
		(net "M_C_CPU1_SA_CA<0>")
	)
	(segment
		(start 75.943206 -253.054104)
		(end 76.369672 -253.054104)
		(width 0.0889)
		(layer "In2.Cu")
		(net "M_C_CPU1_SA_CA<0>")
	)
	(segment
		(start 50.551588 -249.830336)
		(end 50.551588 -249.77344)
		(width 0.14478)
		(layer "In2.Cu")
		(net "M_C_CPU1_SA_CA<0>")
	)
	(segment
		(start 52.344828 -249.610372)
		(end 52.507896 -249.77344)
		(width 0.14478)
		(layer "In2.Cu")
		(net "M_C_CPU1_SA_CA<0>")
	)
	(segment
		(start 46.939454 -249.610372)
		(end 48.718978 -249.610372)
		(width 0.14478)
		(layer "In2.Cu")
		(net "M_C_CPU1_SA_CA<0>")
	)
	(segment
		(start 57.868566 -249.837956)
		(end 58.031634 -250.001024)
		(width 0.14478)
		(layer "In2.Cu")
		(net "M_C_CPU1_SA_CA<0>")
	)
	(segment
		(start 91.85402 -252.907038)
		(end 91.862402 -252.911864)
		(width 0.0889)
		(layer "In2.Cu")
		(net "M_C_CPU1_SA_CA<0>")
	)
	(segment
		(start 57.705498 -249.610372)
		(end 57.868566 -249.77344)
		(width 0.14478)
		(layer "In2.Cu")
		(net "M_C_CPU1_SA_CA<0>")
	)
	(segment
		(start 82.453988 -252.907038)
		(end 82.46237 -252.911864)
		(width 0.0889)
		(layer "In2.Cu")
		(net "M_C_CPU1_SA_CA<0>")
	)
	(segment
		(start 83.394042 -252.907038)
		(end 83.402424 -252.911864)
		(width 0.0889)
		(layer "In2.Cu")
		(net "M_C_CPU1_SA_CA<0>")
	)
	(segment
		(start 53.06441 -249.77344)
		(end 53.227478 -249.610372)
		(width 0.14478)
		(layer "In2.Cu")
		(net "M_C_CPU1_SA_CA<0>")
	)
	(segment
		(start 90.339672 -252.911864)
		(end 90.348054 -252.907038)
		(width 0.0889)
		(layer "In2.Cu")
		(net "M_C_CPU1_SA_CA<0>")
	)
	(segment
		(start 79.99984 -252.911864)
		(end 80.008222 -252.907038)
		(width 0.0889)
		(layer "In2.Cu")
		(net "M_C_CPU1_SA_CA<0>")
	)
	(segment
		(start 81.879694 -252.911864)
		(end 81.888076 -252.907038)
		(width 0.0889)
		(layer "In2.Cu")
		(net "M_C_CPU1_SA_CA<0>")
	)
	(segment
		(start 54.340506 -249.610372)
		(end 56.59247 -249.610372)
		(width 0.14478)
		(layer "In2.Cu")
		(net "M_C_CPU1_SA_CA<0>")
	)
	(segment
		(start 76.369672 -253.054104)
		(end 76.530708 -253.21514)
		(width 0.0889)
		(layer "In2.Cu")
		(net "M_C_CPU1_SA_CA<0>")
	)
	(segment
		(start 87.154004 -252.907038)
		(end 87.162386 -252.911864)
		(width 0.0889)
		(layer "In2.Cu")
		(net "M_C_CPU1_SA_CA<0>")
	)
	(segment
		(start 50.714656 -249.610372)
		(end 52.344828 -249.610372)
		(width 0.14478)
		(layer "In2.Cu")
		(net "M_C_CPU1_SA_CA<0>")
	)
	(segment
		(start 49.995074 -249.77344)
		(end 49.995074 -249.830336)
		(width 0.14478)
		(layer "In2.Cu")
		(net "M_C_CPU1_SA_CA<0>")
	)
	(segment
		(start 50.158142 -249.993404)
		(end 50.38852 -249.993404)
		(width 0.14478)
		(layer "In2.Cu")
		(net "M_C_CPU1_SA_CA<0>")
	)
	(segment
		(start 73.966578 -253.054104)
		(end 75.943206 -253.054104)
		(width 0.14478)
		(layer "In2.Cu")
		(net "M_C_CPU1_SA_CA<0>")
	)
	(segment
		(start 79.067152 -252.907038)
		(end 79.081884 -252.898402)
		(width 0.0889)
		(layer "In2.Cu")
		(net "M_C_CPU1_SA_CA<0>")
	)
	(segment
		(start 57.47512 -249.610372)
		(end 57.705498 -249.610372)
		(width 0.14478)
		(layer "In2.Cu")
		(net "M_C_CPU1_SA_CA<0>")
	)
	(segment
		(start 49.832006 -249.610372)
		(end 49.995074 -249.77344)
		(width 0.14478)
		(layer "In2.Cu")
		(net "M_C_CPU1_SA_CA<0>")
	)
	(segment
		(start 49.995074 -249.830336)
		(end 50.158142 -249.993404)
		(width 0.14478)
		(layer "In2.Cu")
		(net "M_C_CPU1_SA_CA<0>")
	)
	(segment
		(start 86.57971 -252.911864)
		(end 86.588092 -252.907038)
		(width 0.0889)
		(layer "In2.Cu")
		(net "M_C_CPU1_SA_CA<0>")
	)
	(segment
		(start 49.275492 -249.993404)
		(end 49.43856 -249.830336)
		(width 0.14478)
		(layer "In2.Cu")
		(net "M_C_CPU1_SA_CA<0>")
	)
	(segment
		(start 78.693518 -252.906784)
		(end 78.707234 -252.914658)
		(width 0.0889)
		(layer "In2.Cu")
		(net "M_C_CPU1_SA_CA<0>")
	)
	(segment
		(start 54.01437 -249.985784)
		(end 54.177438 -249.822716)
		(width 0.14478)
		(layer "In2.Cu")
		(net "M_C_CPU1_SA_CA<0>")
	)
	(segment
		(start 49.43856 -249.830336)
		(end 49.43856 -249.77344)
		(width 0.14478)
		(layer "In2.Cu")
		(net "M_C_CPU1_SA_CA<0>")
	)
	(segment
		(start 45.232066 -247.902984)
		(end 46.939454 -249.610372)
		(width 0.14478)
		(layer "In2.Cu")
		(net "M_C_CPU1_SA_CA<0>")
	)
	(segment
		(start 58.031634 -250.001024)
		(end 58.262012 -250.001024)
		(width 0.14478)
		(layer "In2.Cu")
		(net "M_C_CPU1_SA_CA<0>")
	)
	(segment
		(start 53.783992 -249.985784)
		(end 54.01437 -249.985784)
		(width 0.14478)
		(layer "In2.Cu")
		(net "M_C_CPU1_SA_CA<0>")
	)
	(segment
		(start 56.59247 -249.610372)
		(end 56.755538 -249.77344)
		(width 0.14478)
		(layer "In2.Cu")
		(net "M_C_CPU1_SA_CA<0>")
	)
	(segment
		(start 62.861444 -252.41885)
		(end 66.49212 -252.41885)
		(width 0.14478)
		(layer "In2.Cu")
		(net "M_C_CPU1_SA_CA<0>")
	)
	(segment
		(start 53.457856 -249.610372)
		(end 53.620924 -249.77344)
		(width 0.14478)
		(layer "In2.Cu")
		(net "M_C_CPU1_SA_CA<0>")
	)
	(segment
		(start 49.601628 -249.610372)
		(end 49.832006 -249.610372)
		(width 0.14478)
		(layer "In2.Cu")
		(net "M_C_CPU1_SA_CA<0>")
	)
	(segment
		(start 57.148984 -250.001024)
		(end 57.312052 -249.837956)
		(width 0.14478)
		(layer "In2.Cu")
		(net "M_C_CPU1_SA_CA<0>")
	)
	(segment
		(start 52.901342 -249.985784)
		(end 53.06441 -249.822716)
		(width 0.14478)
		(layer "In2.Cu")
		(net "M_C_CPU1_SA_CA<0>")
	)
	(segment
		(start 58.262012 -250.001024)
		(end 58.42508 -249.837956)
		(width 0.14478)
		(layer "In2.Cu")
		(net "M_C_CPU1_SA_CA<0>")
	)
	(segment
		(start 72.671178 -251.758704)
		(end 73.966578 -253.054104)
		(width 0.14478)
		(layer "In2.Cu")
		(net "M_C_CPU1_SA_CA<0>")
	)
	(segment
		(start 57.312052 -249.837956)
		(end 57.312052 -249.77344)
		(width 0.14478)
		(layer "In2.Cu")
		(net "M_C_CPU1_SA_CA<0>")
	)
	(segment
		(start 90.913966 -252.907038)
		(end 90.922348 -252.911864)
		(width 0.0889)
		(layer "In2.Cu")
		(net "M_C_CPU1_SA_CA<0>")
	)
	(segment
		(start 49.43856 -249.77344)
		(end 49.601628 -249.610372)
		(width 0.14478)
		(layer "In2.Cu")
		(net "M_C_CPU1_SA_CA<0>")
	)
	(segment
		(start 58.42508 -249.837956)
		(end 58.42508 -249.77344)
		(width 0.14478)
		(layer "In2.Cu")
		(net "M_C_CPU1_SA_CA<0>")
	)
	(segment
		(start 48.882046 -249.830336)
		(end 49.045114 -249.993404)
		(width 0.14478)
		(layer "In2.Cu")
		(net "M_C_CPU1_SA_CA<0>")
	)
	(segment
		(start 88.094058 -252.907038)
		(end 88.10244 -252.911864)
		(width 0.0889)
		(layer "In2.Cu")
		(net "M_C_CPU1_SA_CA<0>")
	)
	(segment
		(start 54.177438 -249.77344)
		(end 54.340506 -249.610372)
		(width 0.14478)
		(layer "In2.Cu")
		(net "M_C_CPU1_SA_CA<0>")
	)
	(segment
		(start 54.177438 -249.822716)
		(end 54.177438 -249.77344)
		(width 0.14478)
		(layer "In2.Cu")
		(net "M_C_CPU1_SA_CA<0>")
	)
	(segment
		(start 68.08597 -251.758704)
		(end 72.671178 -251.758704)
		(width 0.14478)
		(layer "In2.Cu")
		(net "M_C_CPU1_SA_CA<0>")
	)
	(segment
		(start 85.639656 -252.911864)
		(end 85.648038 -252.907038)
		(width 0.0889)
		(layer "In2.Cu")
		(net "M_C_CPU1_SA_CA<0>")
	)
	(segment
		(start 60.052966 -249.610372)
		(end 62.861444 -252.41885)
		(width 0.14478)
		(layer "In2.Cu")
		(net "M_C_CPU1_SA_CA<0>")
	)
	(segment
		(start 56.755538 -249.837956)
		(end 56.918606 -250.001024)
		(width 0.14478)
		(layer "In2.Cu")
		(net "M_C_CPU1_SA_CA<0>")
	)
	(segment
		(start 52.507896 -249.77344)
		(end 52.507896 -249.822716)
		(width 0.14478)
		(layer "In2.Cu")
		(net "M_C_CPU1_SA_CA<0>")
	)
	(arc
		(start 92.228162 -252.907038)
		(mid 92.511118 -252.830861)
		(end 92.794074 -252.907038)
		(width 0.0889)
		(layer "In2.Cu")
		(net "M_C_CPU1_SA_CA<0>")
	)
	(arc
		(start 80.008222 -252.907038)
		(mid 80.291178 -252.830861)
		(end 80.574134 -252.907038)
		(width 0.0889)
		(layer "In2.Cu")
		(net "M_C_CPU1_SA_CA<0>")
	)
	(arc
		(start 91.862402 -252.911864)
		(mid 92.04591 -252.957358)
		(end 92.228162 -252.907038)
		(width 0.0889)
		(layer "In2.Cu")
		(net "M_C_CPU1_SA_CA<0>")
	)
	(arc
		(start 90.348054 -252.907038)
		(mid 90.63101 -252.830861)
		(end 90.913966 -252.907038)
		(width 0.0889)
		(layer "In2.Cu")
		(net "M_C_CPU1_SA_CA<0>")
	)
	(arc
		(start 86.21395 -252.907038)
		(mid 86.396201 -252.957388)
		(end 86.57971 -252.911864)
		(width 0.0889)
		(layer "In2.Cu")
		(net "M_C_CPU1_SA_CA<0>")
	)
	(arc
		(start 89.034112 -252.907038)
		(mid 89.221056 -252.957293)
		(end 89.408 -252.907038)
		(width 0.0889)
		(layer "In2.Cu")
		(net "M_C_CPU1_SA_CA<0>")
	)
	(arc
		(start 85.273896 -252.907038)
		(mid 85.456147 -252.957388)
		(end 85.639656 -252.911864)
		(width 0.0889)
		(layer "In2.Cu")
		(net "M_C_CPU1_SA_CA<0>")
	)
	(arc
		(start 84.707984 -252.907038)
		(mid 84.99094 -252.830861)
		(end 85.273896 -252.907038)
		(width 0.0889)
		(layer "In2.Cu")
		(net "M_C_CPU1_SA_CA<0>")
	)
	(arc
		(start 78.127606 -252.907038)
		(mid 78.401461 -252.830688)
		(end 78.67777 -252.89764)
		(width 0.0889)
		(layer "In2.Cu")
		(net "M_C_CPU1_SA_CA<0>")
	)
	(arc
		(start 87.528146 -252.907038)
		(mid 87.811102 -252.830861)
		(end 88.094058 -252.907038)
		(width 0.0889)
		(layer "In2.Cu")
		(net "M_C_CPU1_SA_CA<0>")
	)
	(arc
		(start 93.733874 -252.907038)
		(mid 93.890312 -252.956009)
		(end 94.052644 -252.9332)
		(width 0.0889)
		(layer "In2.Cu")
		(net "M_C_CPU1_SA_CA<0>")
	)
	(arc
		(start 88.4682 -252.907038)
		(mid 88.751156 -252.830861)
		(end 89.034112 -252.907038)
		(width 0.0889)
		(layer "In2.Cu")
		(net "M_C_CPU1_SA_CA<0>")
	)
	(arc
		(start 83.402424 -252.911864)
		(mid 83.585932 -252.957358)
		(end 83.768184 -252.907038)
		(width 0.0889)
		(layer "In2.Cu")
		(net "M_C_CPU1_SA_CA<0>")
	)
	(arc
		(start 89.408 -252.907038)
		(mid 89.690956 -252.830861)
		(end 89.973912 -252.907038)
		(width 0.0889)
		(layer "In2.Cu")
		(net "M_C_CPU1_SA_CA<0>")
	)
	(arc
		(start 87.162386 -252.911864)
		(mid 87.345894 -252.957358)
		(end 87.528146 -252.907038)
		(width 0.0889)
		(layer "In2.Cu")
		(net "M_C_CPU1_SA_CA<0>")
	)
	(arc
		(start 88.10244 -252.911864)
		(mid 88.285948 -252.957358)
		(end 88.4682 -252.907038)
		(width 0.0889)
		(layer "In2.Cu")
		(net "M_C_CPU1_SA_CA<0>")
	)
	(arc
		(start 89.973912 -252.907038)
		(mid 90.156163 -252.957388)
		(end 90.339672 -252.911864)
		(width 0.0889)
		(layer "In2.Cu")
		(net "M_C_CPU1_SA_CA<0>")
	)
	(arc
		(start 86.588092 -252.907038)
		(mid 86.871048 -252.830861)
		(end 87.154004 -252.907038)
		(width 0.0889)
		(layer "In2.Cu")
		(net "M_C_CPU1_SA_CA<0>")
	)
	(arc
		(start 79.633572 -252.907038)
		(mid 79.816077 -252.957515)
		(end 79.99984 -252.911864)
		(width 0.0889)
		(layer "In2.Cu")
		(net "M_C_CPU1_SA_CA<0>")
	)
	(arc
		(start 85.648038 -252.907038)
		(mid 85.930994 -252.830861)
		(end 86.21395 -252.907038)
		(width 0.0889)
		(layer "In2.Cu")
		(net "M_C_CPU1_SA_CA<0>")
	)
	(arc
		(start 76.98486 -253.21514)
		(mid 77.576632 -253.136757)
		(end 78.127606 -252.907038)
		(width 0.0889)
		(layer "In2.Cu")
		(net "M_C_CPU1_SA_CA<0>")
	)
	(arc
		(start 90.922348 -252.911864)
		(mid 91.105856 -252.957358)
		(end 91.288108 -252.907038)
		(width 0.0889)
		(layer "In2.Cu")
		(net "M_C_CPU1_SA_CA<0>")
	)
	(arc
		(start 79.081884 -252.898402)
		(mid 79.358867 -252.830598)
		(end 79.633572 -252.907038)
		(width 0.0889)
		(layer "In2.Cu")
		(net "M_C_CPU1_SA_CA<0>")
	)
	(arc
		(start 78.707234 -252.914658)
		(mid 78.888164 -252.957136)
		(end 79.067152 -252.907038)
		(width 0.0889)
		(layer "In2.Cu")
		(net "M_C_CPU1_SA_CA<0>")
	)
	(arc
		(start 81.888076 -252.907038)
		(mid 82.171032 -252.830861)
		(end 82.453988 -252.907038)
		(width 0.0889)
		(layer "In2.Cu")
		(net "M_C_CPU1_SA_CA<0>")
	)
	(arc
		(start 92.794074 -252.907038)
		(mid 92.981018 -252.957293)
		(end 93.167962 -252.907038)
		(width 0.0889)
		(layer "In2.Cu")
		(net "M_C_CPU1_SA_CA<0>")
	)
	(arc
		(start 80.574134 -252.907038)
		(mid 80.761078 -252.957293)
		(end 80.948022 -252.907038)
		(width 0.0889)
		(layer "In2.Cu")
		(net "M_C_CPU1_SA_CA<0>")
	)
	(arc
		(start 91.288108 -252.907038)
		(mid 91.571064 -252.830861)
		(end 91.85402 -252.907038)
		(width 0.0889)
		(layer "In2.Cu")
		(net "M_C_CPU1_SA_CA<0>")
	)
	(arc
		(start 82.82813 -252.907038)
		(mid 83.111086 -252.830861)
		(end 83.394042 -252.907038)
		(width 0.0889)
		(layer "In2.Cu")
		(net "M_C_CPU1_SA_CA<0>")
	)
	(arc
		(start 93.167962 -252.907038)
		(mid 93.450918 -252.830861)
		(end 93.733874 -252.907038)
		(width 0.0889)
		(layer "In2.Cu")
		(net "M_C_CPU1_SA_CA<0>")
	)
	(arc
		(start 83.768184 -252.907038)
		(mid 84.05114 -252.830861)
		(end 84.334096 -252.907038)
		(width 0.0889)
		(layer "In2.Cu")
		(net "M_C_CPU1_SA_CA<0>")
	)
	(arc
		(start 82.46237 -252.911864)
		(mid 82.645878 -252.957358)
		(end 82.82813 -252.907038)
		(width 0.0889)
		(layer "In2.Cu")
		(net "M_C_CPU1_SA_CA<0>")
	)
	(arc
		(start 84.334096 -252.907038)
		(mid 84.52104 -252.957293)
		(end 84.707984 -252.907038)
		(width 0.0889)
		(layer "In2.Cu")
		(net "M_C_CPU1_SA_CA<0>")
	)
	(arc
		(start 81.513934 -252.907038)
		(mid 81.696185 -252.957388)
		(end 81.879694 -252.911864)
		(width 0.0889)
		(layer "In2.Cu")
		(net "M_C_CPU1_SA_CA<0>")
	)
	(arc
		(start 80.948022 -252.907038)
		(mid 81.230978 -252.830861)
		(end 81.513934 -252.907038)
		(width 0.0889)
		(layer "In2.Cu")
		(net "M_C_CPU1_SA_CA<0>")
	)
	(segment
		(start 96.267778 -251.230384)
		(end 95.800926 -250.964446)
		(width 0.10668)
		(layer "F.Cu")
		(net "M_C_CPU1_RESET_N")
	)
	(segment
		(start 90.348054 -250.641866)
		(end 90.339672 -250.63704)
		(width 0.0889)
		(layer "In2.Cu")
		(net "M_C_CPU1_RESET_N")
	)
	(segment
		(start 67.783456 -250.108974)
		(end 66.164968 -250.77928)
		(width 0.11684)
		(layer "In2.Cu")
		(net "M_C_CPU1_RESET_N")
	)
	(segment
		(start 74.308208 -251.055124)
		(end 73.362058 -250.108974)
		(width 0.11684)
		(layer "In2.Cu")
		(net "M_C_CPU1_RESET_N")
	)
	(segment
		(start 85.648038 -250.641866)
		(end 85.639656 -250.63704)
		(width 0.0889)
		(layer "In2.Cu")
		(net "M_C_CPU1_RESET_N")
	)
	(segment
		(start 76.545186 -250.851924)
		(end 76.341986 -251.055124)
		(width 0.0889)
		(layer "In2.Cu")
		(net "M_C_CPU1_RESET_N")
	)
	(segment
		(start 64.10833 -250.77928)
		(end 60.388754 -247.059704)
		(width 0.11684)
		(layer "In2.Cu")
		(net "M_C_CPU1_RESET_N")
	)
	(segment
		(start 73.362058 -250.108974)
		(end 67.783456 -250.108974)
		(width 0.11684)
		(layer "In2.Cu")
		(net "M_C_CPU1_RESET_N")
	)
	(segment
		(start 76.070206 -251.055124)
		(end 74.308208 -251.055124)
		(width 0.11684)
		(layer "In2.Cu")
		(net "M_C_CPU1_RESET_N")
	)
	(segment
		(start 88.10244 -250.63704)
		(end 88.094058 -250.641866)
		(width 0.0889)
		(layer "In2.Cu")
		(net "M_C_CPU1_RESET_N")
	)
	(segment
		(start 46.984666 -247.059704)
		(end 45.285152 -245.36019)
		(width 0.11684)
		(layer "In2.Cu")
		(net "M_C_CPU1_RESET_N")
	)
	(segment
		(start 81.888076 -250.641866)
		(end 81.879694 -250.63704)
		(width 0.0889)
		(layer "In2.Cu")
		(net "M_C_CPU1_RESET_N")
	)
	(segment
		(start 95.800926 -250.964446)
		(end 95.647002 -250.699016)
		(width 0.0889)
		(layer "In2.Cu")
		(net "M_C_CPU1_RESET_N")
	)
	(segment
		(start 40.664892 -245.36019)
		(end 40.23995 -244.935248)
		(width 0.11684)
		(layer "In2.Cu")
		(net "M_C_CPU1_RESET_N")
	)
	(segment
		(start 86.588092 -250.641866)
		(end 86.57971 -250.63704)
		(width 0.0889)
		(layer "In2.Cu")
		(net "M_C_CPU1_RESET_N")
	)
	(segment
		(start 94.108016 -250.641866)
		(end 94.099634 -250.63704)
		(width 0.0889)
		(layer "In2.Cu")
		(net "M_C_CPU1_RESET_N")
	)
	(segment
		(start 95.647002 -250.699016)
		(end 95.55099 -250.673616)
		(width 0.0889)
		(layer "In2.Cu")
		(net "M_C_CPU1_RESET_N")
	)
	(segment
		(start 91.288108 -250.641866)
		(end 91.279726 -250.63704)
		(width 0.0889)
		(layer "In2.Cu")
		(net "M_C_CPU1_RESET_N")
	)
	(segment
		(start 83.402424 -250.63704)
		(end 83.394042 -250.641866)
		(width 0.0889)
		(layer "In2.Cu")
		(net "M_C_CPU1_RESET_N")
	)
	(segment
		(start 66.164968 -250.77928)
		(end 64.10833 -250.77928)
		(width 0.11684)
		(layer "In2.Cu")
		(net "M_C_CPU1_RESET_N")
	)
	(segment
		(start 82.46237 -250.63704)
		(end 82.453988 -250.641866)
		(width 0.0889)
		(layer "In2.Cu")
		(net "M_C_CPU1_RESET_N")
	)
	(segment
		(start 76.341986 -251.055124)
		(end 76.070206 -251.055124)
		(width 0.0889)
		(layer "In2.Cu")
		(net "M_C_CPU1_RESET_N")
	)
	(segment
		(start 87.162386 -250.63704)
		(end 87.154004 -250.641866)
		(width 0.0889)
		(layer "In2.Cu")
		(net "M_C_CPU1_RESET_N")
	)
	(segment
		(start 91.862402 -250.63704)
		(end 91.85402 -250.641866)
		(width 0.0889)
		(layer "In2.Cu")
		(net "M_C_CPU1_RESET_N")
	)
	(segment
		(start 95.04807 -250.641866)
		(end 95.039688 -250.63704)
		(width 0.0889)
		(layer "In2.Cu")
		(net "M_C_CPU1_RESET_N")
	)
	(segment
		(start 60.388754 -247.059704)
		(end 46.984666 -247.059704)
		(width 0.11684)
		(layer "In2.Cu")
		(net "M_C_CPU1_RESET_N")
	)
	(segment
		(start 45.285152 -245.36019)
		(end 40.664892 -245.36019)
		(width 0.11684)
		(layer "In2.Cu")
		(net "M_C_CPU1_RESET_N")
	)
	(segment
		(start 79.642462 -250.63704)
		(end 79.63408 -250.641866)
		(width 0.0889)
		(layer "In2.Cu")
		(net "M_C_CPU1_RESET_N")
	)
	(segment
		(start 77.930248 -250.851924)
		(end 76.545186 -250.851924)
		(width 0.0889)
		(layer "In2.Cu")
		(net "M_C_CPU1_RESET_N")
	)
	(arc
		(start 91.85402 -250.641866)
		(mid 91.571064 -250.718043)
		(end 91.288108 -250.641866)
		(width 0.0889)
		(layer "In2.Cu")
		(net "M_C_CPU1_RESET_N")
	)
	(arc
		(start 86.57971 -250.63704)
		(mid 86.396202 -250.591546)
		(end 86.21395 -250.641866)
		(width 0.0889)
		(layer "In2.Cu")
		(net "M_C_CPU1_RESET_N")
	)
	(arc
		(start 88.4682 -250.641866)
		(mid 88.285949 -250.591516)
		(end 88.10244 -250.63704)
		(width 0.0889)
		(layer "In2.Cu")
		(net "M_C_CPU1_RESET_N")
	)
	(arc
		(start 80.574134 -250.641866)
		(mid 80.291178 -250.718043)
		(end 80.008222 -250.641866)
		(width 0.0889)
		(layer "In2.Cu")
		(net "M_C_CPU1_RESET_N")
	)
	(arc
		(start 90.339672 -250.63704)
		(mid 90.156164 -250.591546)
		(end 89.973912 -250.641866)
		(width 0.0889)
		(layer "In2.Cu")
		(net "M_C_CPU1_RESET_N")
	)
	(arc
		(start 79.068168 -250.641866)
		(mid 78.885917 -250.591516)
		(end 78.702408 -250.63704)
		(width 0.0889)
		(layer "In2.Cu")
		(net "M_C_CPU1_RESET_N")
	)
	(arc
		(start 82.453988 -250.641866)
		(mid 82.171032 -250.718043)
		(end 81.888076 -250.641866)
		(width 0.0889)
		(layer "In2.Cu")
		(net "M_C_CPU1_RESET_N")
	)
	(arc
		(start 78.702408 -250.63704)
		(mid 78.330999 -250.7972)
		(end 77.930248 -250.851924)
		(width 0.0889)
		(layer "In2.Cu")
		(net "M_C_CPU1_RESET_N")
	)
	(arc
		(start 95.55099 -250.673616)
		(mid 95.295782 -250.717093)
		(end 95.04807 -250.641866)
		(width 0.0889)
		(layer "In2.Cu")
		(net "M_C_CPU1_RESET_N")
	)
	(arc
		(start 90.913966 -250.641866)
		(mid 90.63101 -250.718043)
		(end 90.348054 -250.641866)
		(width 0.0889)
		(layer "In2.Cu")
		(net "M_C_CPU1_RESET_N")
	)
	(arc
		(start 83.768184 -250.641866)
		(mid 83.585933 -250.591516)
		(end 83.402424 -250.63704)
		(width 0.0889)
		(layer "In2.Cu")
		(net "M_C_CPU1_RESET_N")
	)
	(arc
		(start 86.21395 -250.641866)
		(mid 85.930994 -250.718043)
		(end 85.648038 -250.641866)
		(width 0.0889)
		(layer "In2.Cu")
		(net "M_C_CPU1_RESET_N")
	)
	(arc
		(start 92.794074 -250.641866)
		(mid 92.511118 -250.718043)
		(end 92.228162 -250.641866)
		(width 0.0889)
		(layer "In2.Cu")
		(net "M_C_CPU1_RESET_N")
	)
	(arc
		(start 89.408 -250.641866)
		(mid 89.221056 -250.591611)
		(end 89.034112 -250.641866)
		(width 0.0889)
		(layer "In2.Cu")
		(net "M_C_CPU1_RESET_N")
	)
	(arc
		(start 95.039688 -250.63704)
		(mid 94.85618 -250.591546)
		(end 94.673928 -250.641866)
		(width 0.0889)
		(layer "In2.Cu")
		(net "M_C_CPU1_RESET_N")
	)
	(arc
		(start 87.154004 -250.641866)
		(mid 86.871048 -250.718043)
		(end 86.588092 -250.641866)
		(width 0.0889)
		(layer "In2.Cu")
		(net "M_C_CPU1_RESET_N")
	)
	(arc
		(start 94.673928 -250.641866)
		(mid 94.390972 -250.718043)
		(end 94.108016 -250.641866)
		(width 0.0889)
		(layer "In2.Cu")
		(net "M_C_CPU1_RESET_N")
	)
	(arc
		(start 85.273896 -250.641866)
		(mid 84.99094 -250.718043)
		(end 84.707984 -250.641866)
		(width 0.0889)
		(layer "In2.Cu")
		(net "M_C_CPU1_RESET_N")
	)
	(arc
		(start 92.228162 -250.641866)
		(mid 92.045911 -250.591516)
		(end 91.862402 -250.63704)
		(width 0.0889)
		(layer "In2.Cu")
		(net "M_C_CPU1_RESET_N")
	)
	(arc
		(start 79.63408 -250.641866)
		(mid 79.351124 -250.718043)
		(end 79.068168 -250.641866)
		(width 0.0889)
		(layer "In2.Cu")
		(net "M_C_CPU1_RESET_N")
	)
	(arc
		(start 84.334096 -250.641866)
		(mid 84.05114 -250.718043)
		(end 83.768184 -250.641866)
		(width 0.0889)
		(layer "In2.Cu")
		(net "M_C_CPU1_RESET_N")
	)
	(arc
		(start 85.639656 -250.63704)
		(mid 85.456148 -250.591546)
		(end 85.273896 -250.641866)
		(width 0.0889)
		(layer "In2.Cu")
		(net "M_C_CPU1_RESET_N")
	)
	(arc
		(start 88.094058 -250.641866)
		(mid 87.811102 -250.718043)
		(end 87.528146 -250.641866)
		(width 0.0889)
		(layer "In2.Cu")
		(net "M_C_CPU1_RESET_N")
	)
	(arc
		(start 93.733874 -250.641866)
		(mid 93.450918 -250.718043)
		(end 93.167962 -250.641866)
		(width 0.0889)
		(layer "In2.Cu")
		(net "M_C_CPU1_RESET_N")
	)
	(arc
		(start 83.394042 -250.641866)
		(mid 83.111086 -250.718043)
		(end 82.82813 -250.641866)
		(width 0.0889)
		(layer "In2.Cu")
		(net "M_C_CPU1_RESET_N")
	)
	(arc
		(start 80.948022 -250.641866)
		(mid 80.761078 -250.591611)
		(end 80.574134 -250.641866)
		(width 0.0889)
		(layer "In2.Cu")
		(net "M_C_CPU1_RESET_N")
	)
	(arc
		(start 93.167962 -250.641866)
		(mid 92.981018 -250.591611)
		(end 92.794074 -250.641866)
		(width 0.0889)
		(layer "In2.Cu")
		(net "M_C_CPU1_RESET_N")
	)
	(arc
		(start 89.973912 -250.641866)
		(mid 89.690956 -250.718043)
		(end 89.408 -250.641866)
		(width 0.0889)
		(layer "In2.Cu")
		(net "M_C_CPU1_RESET_N")
	)
	(arc
		(start 94.099634 -250.63704)
		(mid 93.916126 -250.591546)
		(end 93.733874 -250.641866)
		(width 0.0889)
		(layer "In2.Cu")
		(net "M_C_CPU1_RESET_N")
	)
	(arc
		(start 84.707984 -250.641866)
		(mid 84.52104 -250.591611)
		(end 84.334096 -250.641866)
		(width 0.0889)
		(layer "In2.Cu")
		(net "M_C_CPU1_RESET_N")
	)
	(arc
		(start 89.034112 -250.641866)
		(mid 88.751156 -250.718043)
		(end 88.4682 -250.641866)
		(width 0.0889)
		(layer "In2.Cu")
		(net "M_C_CPU1_RESET_N")
	)
	(arc
		(start 80.008222 -250.641866)
		(mid 79.825971 -250.591516)
		(end 79.642462 -250.63704)
		(width 0.0889)
		(layer "In2.Cu")
		(net "M_C_CPU1_RESET_N")
	)
	(arc
		(start 87.528146 -250.641866)
		(mid 87.345895 -250.591516)
		(end 87.162386 -250.63704)
		(width 0.0889)
		(layer "In2.Cu")
		(net "M_C_CPU1_RESET_N")
	)
	(arc
		(start 81.879694 -250.63704)
		(mid 81.696186 -250.591546)
		(end 81.513934 -250.641866)
		(width 0.0889)
		(layer "In2.Cu")
		(net "M_C_CPU1_RESET_N")
	)
	(arc
		(start 91.279726 -250.63704)
		(mid 91.096218 -250.591546)
		(end 90.913966 -250.641866)
		(width 0.0889)
		(layer "In2.Cu")
		(net "M_C_CPU1_RESET_N")
	)
	(arc
		(start 82.82813 -250.641866)
		(mid 82.645879 -250.591516)
		(end 82.46237 -250.63704)
		(width 0.0889)
		(layer "In2.Cu")
		(net "M_C_CPU1_RESET_N")
	)
	(arc
		(start 81.513934 -250.641866)
		(mid 81.230978 -250.718043)
		(end 80.948022 -250.641866)
		(width 0.0889)
		(layer "In2.Cu")
		(net "M_C_CPU1_RESET_N")
	)
	(segment
		(start 94.387924 -256.09042)
		(end 93.921072 -255.824482)
		(width 0.14732)
		(layer "F.Cu")
		(net "M_C_CPU1_CLK_DP<0>")
	)
	(segment
		(start 94.074996 -256.089912)
		(end 93.921072 -255.824482)
		(width 0.09525)
		(layer "In2.Cu")
		(net "M_C_CPU1_CLK_DP<0>")
	)
	(segment
		(start 40.513762 -253.70917)
		(end 41.867836 -253.70917)
		(width 0.16002)
		(layer "In2.Cu")
		(net "M_C_CPU1_CLK_DP<0>")
	)
	(segment
		(start 40.23995 -253.435358)
		(end 40.513762 -253.70917)
		(width 0.16002)
		(layer "In2.Cu")
		(net "M_C_CPU1_CLK_DP<0>")
	)
	(segment
		(start 91.852496 -256.149602)
		(end 91.860878 -256.154428)
		(width 0.09525)
		(layer "In2.Cu")
		(net "M_C_CPU1_CLK_DP<0>")
	)
	(segment
		(start 83.392518 -256.149602)
		(end 83.4009 -256.154428)
		(width 0.09525)
		(layer "In2.Cu")
		(net "M_C_CPU1_CLK_DP<0>")
	)
	(segment
		(start 90.341196 -256.154428)
		(end 90.349578 -256.149602)
		(width 0.09525)
		(layer "In2.Cu")
		(net "M_C_CPU1_CLK_DP<0>")
	)
	(segment
		(start 79.617824 -256.140966)
		(end 79.632556 -256.149602)
		(width 0.09525)
		(layer "In2.Cu")
		(net "M_C_CPU1_CLK_DP<0>")
	)
	(segment
		(start 76.994004 -257.174746)
		(end 77.469746 -256.699004)
		(width 0.16002)
		(layer "In2.Cu")
		(net "M_C_CPU1_CLK_DP<0>")
	)
	(segment
		(start 86.581234 -256.154428)
		(end 86.589616 -256.149602)
		(width 0.09525)
		(layer "In2.Cu")
		(net "M_C_CPU1_CLK_DP<0>")
	)
	(segment
		(start 42.238422 -254.079756)
		(end 42.403522 -254.079756)
		(width 0.16002)
		(layer "In2.Cu")
		(net "M_C_CPU1_CLK_DP<0>")
	)
	(segment
		(start 77.57033 -256.68224)
		(end 78.014576 -256.237994)
		(width 0.09525)
		(layer "In2.Cu")
		(net "M_C_CPU1_CLK_DP<0>")
	)
	(segment
		(start 43.247564 -254.923798)
		(end 43.587416 -255.263396)
		(width 0.16002)
		(layer "In2.Cu")
		(net "M_C_CPU1_CLK_DP<0>")
	)
	(segment
		(start 70.98665 -255.648206)
		(end 72.51319 -257.174746)
		(width 0.16002)
		(layer "In2.Cu")
		(net "M_C_CPU1_CLK_DP<0>")
	)
	(segment
		(start 67.252596 -256.252726)
		(end 68.71208 -255.648206)
		(width 0.16002)
		(layer "In2.Cu")
		(net "M_C_CPU1_CLK_DP<0>")
	)
	(segment
		(start 78.691994 -256.149602)
		(end 78.706472 -256.157984)
		(width 0.09525)
		(layer "In2.Cu")
		(net "M_C_CPU1_CLK_DP<0>")
	)
	(segment
		(start 42.74312 -254.584454)
		(end 43.082464 -254.923798)
		(width 0.16002)
		(layer "In2.Cu")
		(net "M_C_CPU1_CLK_DP<0>")
	)
	(segment
		(start 81.881218 -256.154428)
		(end 81.8896 -256.149602)
		(width 0.09525)
		(layer "In2.Cu")
		(net "M_C_CPU1_CLK_DP<0>")
	)
	(segment
		(start 85.64118 -256.154428)
		(end 85.649562 -256.149602)
		(width 0.09525)
		(layer "In2.Cu")
		(net "M_C_CPU1_CLK_DP<0>")
	)
	(segment
		(start 43.587416 -255.263396)
		(end 43.587416 -255.42875)
		(width 0.16002)
		(layer "In2.Cu")
		(net "M_C_CPU1_CLK_DP<0>")
	)
	(segment
		(start 41.867836 -253.70917)
		(end 42.238422 -254.079756)
		(width 0.16002)
		(layer "In2.Cu")
		(net "M_C_CPU1_CLK_DP<0>")
	)
	(segment
		(start 88.092534 -256.149602)
		(end 88.100916 -256.154428)
		(width 0.09525)
		(layer "In2.Cu")
		(net "M_C_CPU1_CLK_DP<0>")
	)
	(segment
		(start 90.912442 -256.149602)
		(end 90.920824 -256.154428)
		(width 0.09525)
		(layer "In2.Cu")
		(net "M_C_CPU1_CLK_DP<0>")
	)
	(segment
		(start 42.403522 -254.079756)
		(end 42.74312 -254.419354)
		(width 0.16002)
		(layer "In2.Cu")
		(net "M_C_CPU1_CLK_DP<0>")
	)
	(segment
		(start 42.74312 -254.419354)
		(end 42.74312 -254.584454)
		(width 0.16002)
		(layer "In2.Cu")
		(net "M_C_CPU1_CLK_DP<0>")
	)
	(segment
		(start 68.71208 -255.648206)
		(end 70.98665 -255.648206)
		(width 0.16002)
		(layer "In2.Cu")
		(net "M_C_CPU1_CLK_DP<0>")
	)
	(segment
		(start 79.632556 -256.149602)
		(end 79.640938 -256.154428)
		(width 0.09525)
		(layer "In2.Cu")
		(net "M_C_CPU1_CLK_DP<0>")
	)
	(segment
		(start 82.452464 -256.149602)
		(end 82.460846 -256.154428)
		(width 0.09525)
		(layer "In2.Cu")
		(net "M_C_CPU1_CLK_DP<0>")
	)
	(segment
		(start 77.469746 -256.699004)
		(end 77.48651 -256.68224)
		(width 0.09525)
		(layer "In2.Cu")
		(net "M_C_CPU1_CLK_DP<0>")
	)
	(segment
		(start 87.15248 -256.149602)
		(end 87.160862 -256.154428)
		(width 0.09525)
		(layer "In2.Cu")
		(net "M_C_CPU1_CLK_DP<0>")
	)
	(segment
		(start 72.51319 -257.174746)
		(end 76.994004 -257.174746)
		(width 0.16002)
		(layer "In2.Cu")
		(net "M_C_CPU1_CLK_DP<0>")
	)
	(segment
		(start 77.48651 -256.68224)
		(end 77.57033 -256.68224)
		(width 0.09525)
		(layer "In2.Cu")
		(net "M_C_CPU1_CLK_DP<0>")
	)
	(segment
		(start 44.411392 -256.252726)
		(end 67.252596 -256.252726)
		(width 0.16002)
		(layer "In2.Cu")
		(net "M_C_CPU1_CLK_DP<0>")
	)
	(segment
		(start 43.587416 -255.42875)
		(end 44.411392 -256.252726)
		(width 0.16002)
		(layer "In2.Cu")
		(net "M_C_CPU1_CLK_DP<0>")
	)
	(segment
		(start 43.082464 -254.923798)
		(end 43.247564 -254.923798)
		(width 0.16002)
		(layer "In2.Cu")
		(net "M_C_CPU1_CLK_DP<0>")
	)
	(segment
		(start 78.671166 -256.13741)
		(end 78.691994 -256.149602)
		(width 0.09525)
		(layer "In2.Cu")
		(net "M_C_CPU1_CLK_DP<0>")
	)
	(segment
		(start 94.051628 -256.17678)
		(end 94.074996 -256.089912)
		(width 0.09525)
		(layer "In2.Cu")
		(net "M_C_CPU1_CLK_DP<0>")
	)
	(arc
		(start 83.769708 -256.149602)
		(mid 84.05114 -256.073847)
		(end 84.332572 -256.149602)
		(width 0.09525)
		(layer "In2.Cu")
		(net "M_C_CPU1_CLK_DP<0>")
	)
	(arc
		(start 89.972388 -256.149602)
		(mid 90.156163 -256.200374)
		(end 90.341196 -256.154428)
		(width 0.09525)
		(layer "In2.Cu")
		(net "M_C_CPU1_CLK_DP<0>")
	)
	(arc
		(start 83.4009 -256.154428)
		(mid 83.585932 -256.200342)
		(end 83.769708 -256.149602)
		(width 0.09525)
		(layer "In2.Cu")
		(net "M_C_CPU1_CLK_DP<0>")
	)
	(arc
		(start 85.649562 -256.149602)
		(mid 85.930994 -256.073847)
		(end 86.212426 -256.149602)
		(width 0.09525)
		(layer "In2.Cu")
		(net "M_C_CPU1_CLK_DP<0>")
	)
	(arc
		(start 90.349578 -256.149602)
		(mid 90.63101 -256.073847)
		(end 90.912442 -256.149602)
		(width 0.09525)
		(layer "In2.Cu")
		(net "M_C_CPU1_CLK_DP<0>")
	)
	(arc
		(start 78.014576 -256.237994)
		(mid 78.068986 -256.190081)
		(end 78.12913 -256.149602)
		(width 0.09525)
		(layer "In2.Cu")
		(net "M_C_CPU1_CLK_DP<0>")
	)
	(arc
		(start 89.032588 -256.149602)
		(mid 89.221056 -256.200279)
		(end 89.409524 -256.149602)
		(width 0.09525)
		(layer "In2.Cu")
		(net "M_C_CPU1_CLK_DP<0>")
	)
	(arc
		(start 82.460846 -256.154428)
		(mid 82.645878 -256.200342)
		(end 82.829654 -256.149602)
		(width 0.09525)
		(layer "In2.Cu")
		(net "M_C_CPU1_CLK_DP<0>")
	)
	(arc
		(start 85.272372 -256.149602)
		(mid 85.456147 -256.200374)
		(end 85.64118 -256.154428)
		(width 0.09525)
		(layer "In2.Cu")
		(net "M_C_CPU1_CLK_DP<0>")
	)
	(arc
		(start 91.289632 -256.149602)
		(mid 91.571064 -256.073847)
		(end 91.852496 -256.149602)
		(width 0.09525)
		(layer "In2.Cu")
		(net "M_C_CPU1_CLK_DP<0>")
	)
	(arc
		(start 80.57261 -256.149602)
		(mid 80.761078 -256.200279)
		(end 80.949546 -256.149602)
		(width 0.09525)
		(layer "In2.Cu")
		(net "M_C_CPU1_CLK_DP<0>")
	)
	(arc
		(start 84.332572 -256.149602)
		(mid 84.52104 -256.200279)
		(end 84.709508 -256.149602)
		(width 0.09525)
		(layer "In2.Cu")
		(net "M_C_CPU1_CLK_DP<0>")
	)
	(arc
		(start 84.709508 -256.149602)
		(mid 84.99094 -256.073847)
		(end 85.272372 -256.149602)
		(width 0.09525)
		(layer "In2.Cu")
		(net "M_C_CPU1_CLK_DP<0>")
	)
	(arc
		(start 87.160862 -256.154428)
		(mid 87.345894 -256.200342)
		(end 87.52967 -256.149602)
		(width 0.09525)
		(layer "In2.Cu")
		(net "M_C_CPU1_CLK_DP<0>")
	)
	(arc
		(start 88.100916 -256.154428)
		(mid 88.285948 -256.200342)
		(end 88.469724 -256.149602)
		(width 0.09525)
		(layer "In2.Cu")
		(net "M_C_CPU1_CLK_DP<0>")
	)
	(arc
		(start 78.706472 -256.157984)
		(mid 78.888904 -256.200424)
		(end 79.069184 -256.149602)
		(width 0.09525)
		(layer "In2.Cu")
		(net "M_C_CPU1_CLK_DP<0>")
	)
	(arc
		(start 93.73235 -256.149602)
		(mid 93.888948 -256.198891)
		(end 94.051628 -256.17678)
		(width 0.09525)
		(layer "In2.Cu")
		(net "M_C_CPU1_CLK_DP<0>")
	)
	(arc
		(start 81.8896 -256.149602)
		(mid 82.171032 -256.073847)
		(end 82.452464 -256.149602)
		(width 0.09525)
		(layer "In2.Cu")
		(net "M_C_CPU1_CLK_DP<0>")
	)
	(arc
		(start 89.409524 -256.149602)
		(mid 89.690956 -256.073847)
		(end 89.972388 -256.149602)
		(width 0.09525)
		(layer "In2.Cu")
		(net "M_C_CPU1_CLK_DP<0>")
	)
	(arc
		(start 80.949546 -256.149602)
		(mid 81.230978 -256.073847)
		(end 81.51241 -256.149602)
		(width 0.09525)
		(layer "In2.Cu")
		(net "M_C_CPU1_CLK_DP<0>")
	)
	(arc
		(start 86.212426 -256.149602)
		(mid 86.396201 -256.200374)
		(end 86.581234 -256.154428)
		(width 0.09525)
		(layer "In2.Cu")
		(net "M_C_CPU1_CLK_DP<0>")
	)
	(arc
		(start 93.169486 -256.149602)
		(mid 93.450918 -256.073847)
		(end 93.73235 -256.149602)
		(width 0.09525)
		(layer "In2.Cu")
		(net "M_C_CPU1_CLK_DP<0>")
	)
	(arc
		(start 80.009746 -256.149602)
		(mid 80.291178 -256.073847)
		(end 80.57261 -256.149602)
		(width 0.09525)
		(layer "In2.Cu")
		(net "M_C_CPU1_CLK_DP<0>")
	)
	(arc
		(start 88.469724 -256.149602)
		(mid 88.751156 -256.073847)
		(end 89.032588 -256.149602)
		(width 0.09525)
		(layer "In2.Cu")
		(net "M_C_CPU1_CLK_DP<0>")
	)
	(arc
		(start 81.51241 -256.149602)
		(mid 81.696185 -256.200374)
		(end 81.881218 -256.154428)
		(width 0.09525)
		(layer "In2.Cu")
		(net "M_C_CPU1_CLK_DP<0>")
	)
	(arc
		(start 86.589616 -256.149602)
		(mid 86.871048 -256.073847)
		(end 87.15248 -256.149602)
		(width 0.09525)
		(layer "In2.Cu")
		(net "M_C_CPU1_CLK_DP<0>")
	)
	(arc
		(start 79.069184 -256.149602)
		(mid 79.342366 -256.07366)
		(end 79.617824 -256.140966)
		(width 0.09525)
		(layer "In2.Cu")
		(net "M_C_CPU1_CLK_DP<0>")
	)
	(arc
		(start 82.829654 -256.149602)
		(mid 83.111086 -256.073847)
		(end 83.392518 -256.149602)
		(width 0.09525)
		(layer "In2.Cu")
		(net "M_C_CPU1_CLK_DP<0>")
	)
	(arc
		(start 91.860878 -256.154428)
		(mid 92.04591 -256.200342)
		(end 92.229686 -256.149602)
		(width 0.09525)
		(layer "In2.Cu")
		(net "M_C_CPU1_CLK_DP<0>")
	)
	(arc
		(start 92.79255 -256.149602)
		(mid 92.981018 -256.200279)
		(end 93.169486 -256.149602)
		(width 0.09525)
		(layer "In2.Cu")
		(net "M_C_CPU1_CLK_DP<0>")
	)
	(arc
		(start 78.12913 -256.149602)
		(mid 78.398563 -256.073731)
		(end 78.671166 -256.13741)
		(width 0.09525)
		(layer "In2.Cu")
		(net "M_C_CPU1_CLK_DP<0>")
	)
	(arc
		(start 90.920824 -256.154428)
		(mid 91.105856 -256.200342)
		(end 91.289632 -256.149602)
		(width 0.09525)
		(layer "In2.Cu")
		(net "M_C_CPU1_CLK_DP<0>")
	)
	(arc
		(start 87.52967 -256.149602)
		(mid 87.811102 -256.073847)
		(end 88.092534 -256.149602)
		(width 0.09525)
		(layer "In2.Cu")
		(net "M_C_CPU1_CLK_DP<0>")
	)
	(arc
		(start 92.229686 -256.149602)
		(mid 92.511118 -256.073847)
		(end 92.79255 -256.149602)
		(width 0.09525)
		(layer "In2.Cu")
		(net "M_C_CPU1_CLK_DP<0>")
	)
	(arc
		(start 79.640938 -256.154428)
		(mid 79.82597 -256.200342)
		(end 80.009746 -256.149602)
		(width 0.09525)
		(layer "In2.Cu")
		(net "M_C_CPU1_CLK_DP<0>")
	)
	(segment
		(start 94.857824 -256.900426)
		(end 94.390972 -256.634488)
		(width 0.14732)
		(layer "F.Cu")
		(net "M_C_CPU1_CLK_DN<0>")
	)
	(segment
		(start 84.231226 -256.304542)
		(end 84.239608 -256.309368)
		(width 0.09525)
		(layer "In2.Cu")
		(net "M_C_CPU1_CLK_DN<0>")
	)
	(segment
		(start 40.23995 -254.285242)
		(end 40.513762 -254.01143)
		(width 0.16002)
		(layer "In2.Cu")
		(net "M_C_CPU1_CLK_DN<0>")
	)
	(segment
		(start 41.742614 -254.01143)
		(end 44.28617 -256.554986)
		(width 0.16002)
		(layer "In2.Cu")
		(net "M_C_CPU1_CLK_DN<0>")
	)
	(segment
		(start 87.991188 -256.304542)
		(end 87.99957 -256.309368)
		(width 0.09525)
		(layer "In2.Cu")
		(net "M_C_CPU1_CLK_DN<0>")
	)
	(segment
		(start 78.584806 -256.300986)
		(end 78.599284 -256.309368)
		(width 0.09525)
		(layer "In2.Cu")
		(net "M_C_CPU1_CLK_DN<0>")
	)
	(segment
		(start 81.04251 -256.309368)
		(end 81.050892 -256.304542)
		(width 0.09525)
		(layer "In2.Cu")
		(net "M_C_CPU1_CLK_DN<0>")
	)
	(segment
		(start 77.700378 -256.896108)
		(end 77.700378 -256.812796)
		(width 0.09525)
		(layer "In2.Cu")
		(net "M_C_CPU1_CLK_DN<0>")
	)
	(segment
		(start 92.691204 -256.304542)
		(end 92.699586 -256.309368)
		(width 0.09525)
		(layer "In2.Cu")
		(net "M_C_CPU1_CLK_DN<0>")
	)
	(segment
		(start 78.599284 -256.309368)
		(end 78.620112 -256.32156)
		(width 0.09525)
		(layer "In2.Cu")
		(net "M_C_CPU1_CLK_DN<0>")
	)
	(segment
		(start 70.861428 -255.950466)
		(end 72.387968 -257.477006)
		(width 0.16002)
		(layer "In2.Cu")
		(net "M_C_CPU1_CLK_DN<0>")
	)
	(segment
		(start 91.75115 -256.304542)
		(end 91.759532 -256.309368)
		(width 0.09525)
		(layer "In2.Cu")
		(net "M_C_CPU1_CLK_DN<0>")
	)
	(segment
		(start 94.237048 -256.369058)
		(end 94.390972 -256.634488)
		(width 0.09525)
		(layer "In2.Cu")
		(net "M_C_CPU1_CLK_DN<0>")
	)
	(segment
		(start 94.13621 -256.342388)
		(end 94.237048 -256.369058)
		(width 0.09525)
		(layer "In2.Cu")
		(net "M_C_CPU1_CLK_DN<0>")
	)
	(segment
		(start 85.742526 -256.309368)
		(end 85.750908 -256.304542)
		(width 0.09525)
		(layer "In2.Cu")
		(net "M_C_CPU1_CLK_DN<0>")
	)
	(segment
		(start 77.11948 -257.477006)
		(end 77.683614 -256.912872)
		(width 0.16002)
		(layer "In2.Cu")
		(net "M_C_CPU1_CLK_DN<0>")
	)
	(segment
		(start 93.26245 -256.309368)
		(end 93.270832 -256.304542)
		(width 0.09525)
		(layer "In2.Cu")
		(net "M_C_CPU1_CLK_DN<0>")
	)
	(segment
		(start 88.931242 -256.304542)
		(end 88.939624 -256.309368)
		(width 0.09525)
		(layer "In2.Cu")
		(net "M_C_CPU1_CLK_DN<0>")
	)
	(segment
		(start 77.683614 -256.912872)
		(end 77.700378 -256.896108)
		(width 0.09525)
		(layer "In2.Cu")
		(net "M_C_CPU1_CLK_DN<0>")
	)
	(segment
		(start 40.513762 -254.01143)
		(end 41.742614 -254.01143)
		(width 0.16002)
		(layer "In2.Cu")
		(net "M_C_CPU1_CLK_DN<0>")
	)
	(segment
		(start 80.471264 -256.304542)
		(end 80.479646 -256.309368)
		(width 0.09525)
		(layer "In2.Cu")
		(net "M_C_CPU1_CLK_DN<0>")
	)
	(segment
		(start 72.387968 -257.477006)
		(end 77.11948 -257.477006)
		(width 0.16002)
		(layer "In2.Cu")
		(net "M_C_CPU1_CLK_DN<0>")
	)
	(segment
		(start 77.700378 -256.812796)
		(end 78.144878 -256.368296)
		(width 0.09525)
		(layer "In2.Cu")
		(net "M_C_CPU1_CLK_DN<0>")
	)
	(segment
		(start 89.502488 -256.309368)
		(end 89.51087 -256.304542)
		(width 0.09525)
		(layer "In2.Cu")
		(net "M_C_CPU1_CLK_DN<0>")
	)
	(segment
		(start 83.291172 -256.304542)
		(end 83.299554 -256.309368)
		(width 0.09525)
		(layer "In2.Cu")
		(net "M_C_CPU1_CLK_DN<0>")
	)
	(segment
		(start 44.28617 -256.554986)
		(end 67.312794 -256.554986)
		(width 0.16002)
		(layer "In2.Cu")
		(net "M_C_CPU1_CLK_DN<0>")
	)
	(segment
		(start 79.527654 -256.30251)
		(end 79.539592 -256.309368)
		(width 0.09525)
		(layer "In2.Cu")
		(net "M_C_CPU1_CLK_DN<0>")
	)
	(segment
		(start 68.772278 -255.950466)
		(end 70.861428 -255.950466)
		(width 0.16002)
		(layer "In2.Cu")
		(net "M_C_CPU1_CLK_DN<0>")
	)
	(segment
		(start 67.312794 -256.554986)
		(end 68.772278 -255.950466)
		(width 0.16002)
		(layer "In2.Cu")
		(net "M_C_CPU1_CLK_DN<0>")
	)
	(segment
		(start 84.802472 -256.309368)
		(end 84.810854 -256.304542)
		(width 0.09525)
		(layer "In2.Cu")
		(net "M_C_CPU1_CLK_DN<0>")
	)
	(arc
		(start 83.862418 -256.309368)
		(mid 84.046193 -256.258596)
		(end 84.231226 -256.304542)
		(width 0.09525)
		(layer "In2.Cu")
		(net "M_C_CPU1_CLK_DN<0>")
	)
	(arc
		(start 81.050892 -256.304542)
		(mid 81.235924 -256.258628)
		(end 81.4197 -256.309368)
		(width 0.09525)
		(layer "In2.Cu")
		(net "M_C_CPU1_CLK_DN<0>")
	)
	(arc
		(start 78.620112 -256.32156)
		(mid 78.892717 -256.385356)
		(end 79.162148 -256.309368)
		(width 0.09525)
		(layer "In2.Cu")
		(net "M_C_CPU1_CLK_DN<0>")
	)
	(arc
		(start 91.382342 -256.309368)
		(mid 91.566117 -256.258596)
		(end 91.75115 -256.304542)
		(width 0.09525)
		(layer "In2.Cu")
		(net "M_C_CPU1_CLK_DN<0>")
	)
	(arc
		(start 91.759532 -256.309368)
		(mid 92.040964 -256.385123)
		(end 92.322396 -256.309368)
		(width 0.09525)
		(layer "In2.Cu")
		(net "M_C_CPU1_CLK_DN<0>")
	)
	(arc
		(start 88.939624 -256.309368)
		(mid 89.221056 -256.385123)
		(end 89.502488 -256.309368)
		(width 0.09525)
		(layer "In2.Cu")
		(net "M_C_CPU1_CLK_DN<0>")
	)
	(arc
		(start 90.442542 -256.309368)
		(mid 90.63101 -256.258691)
		(end 90.819478 -256.309368)
		(width 0.09525)
		(layer "In2.Cu")
		(net "M_C_CPU1_CLK_DN<0>")
	)
	(arc
		(start 87.99957 -256.309368)
		(mid 88.281002 -256.385123)
		(end 88.562434 -256.309368)
		(width 0.09525)
		(layer "In2.Cu")
		(net "M_C_CPU1_CLK_DN<0>")
	)
	(arc
		(start 84.810854 -256.304542)
		(mid 84.995886 -256.258628)
		(end 85.179662 -256.309368)
		(width 0.09525)
		(layer "In2.Cu")
		(net "M_C_CPU1_CLK_DN<0>")
	)
	(arc
		(start 81.982564 -256.309368)
		(mid 82.171032 -256.258691)
		(end 82.3595 -256.309368)
		(width 0.09525)
		(layer "In2.Cu")
		(net "M_C_CPU1_CLK_DN<0>")
	)
	(arc
		(start 87.62238 -256.309368)
		(mid 87.806155 -256.258596)
		(end 87.991188 -256.304542)
		(width 0.09525)
		(layer "In2.Cu")
		(net "M_C_CPU1_CLK_DN<0>")
	)
	(arc
		(start 79.539592 -256.309368)
		(mid 79.821024 -256.385123)
		(end 80.102456 -256.309368)
		(width 0.09525)
		(layer "In2.Cu")
		(net "M_C_CPU1_CLK_DN<0>")
	)
	(arc
		(start 90.819478 -256.309368)
		(mid 91.10091 -256.385123)
		(end 91.382342 -256.309368)
		(width 0.09525)
		(layer "In2.Cu")
		(net "M_C_CPU1_CLK_DN<0>")
	)
	(arc
		(start 88.562434 -256.309368)
		(mid 88.746209 -256.258596)
		(end 88.931242 -256.304542)
		(width 0.09525)
		(layer "In2.Cu")
		(net "M_C_CPU1_CLK_DN<0>")
	)
	(arc
		(start 89.879678 -256.309368)
		(mid 90.16111 -256.385123)
		(end 90.442542 -256.309368)
		(width 0.09525)
		(layer "In2.Cu")
		(net "M_C_CPU1_CLK_DN<0>")
	)
	(arc
		(start 85.179662 -256.309368)
		(mid 85.461094 -256.385123)
		(end 85.742526 -256.309368)
		(width 0.09525)
		(layer "In2.Cu")
		(net "M_C_CPU1_CLK_DN<0>")
	)
	(arc
		(start 85.750908 -256.304542)
		(mid 85.93594 -256.258628)
		(end 86.119716 -256.309368)
		(width 0.09525)
		(layer "In2.Cu")
		(net "M_C_CPU1_CLK_DN<0>")
	)
	(arc
		(start 87.059516 -256.309368)
		(mid 87.340948 -256.385123)
		(end 87.62238 -256.309368)
		(width 0.09525)
		(layer "In2.Cu")
		(net "M_C_CPU1_CLK_DN<0>")
	)
	(arc
		(start 82.922364 -256.309368)
		(mid 83.106139 -256.258596)
		(end 83.291172 -256.304542)
		(width 0.09525)
		(layer "In2.Cu")
		(net "M_C_CPU1_CLK_DN<0>")
	)
	(arc
		(start 78.222094 -256.309368)
		(mid 78.402373 -256.258537)
		(end 78.584806 -256.300986)
		(width 0.09525)
		(layer "In2.Cu")
		(net "M_C_CPU1_CLK_DN<0>")
	)
	(arc
		(start 94.11589 -256.350262)
		(mid 94.126089 -256.346425)
		(end 94.13621 -256.342388)
		(width 0.09525)
		(layer "In2.Cu")
		(net "M_C_CPU1_CLK_DN<0>")
	)
	(arc
		(start 89.51087 -256.304542)
		(mid 89.695902 -256.258628)
		(end 89.879678 -256.309368)
		(width 0.09525)
		(layer "In2.Cu")
		(net "M_C_CPU1_CLK_DN<0>")
	)
	(arc
		(start 81.4197 -256.309368)
		(mid 81.701132 -256.385123)
		(end 81.982564 -256.309368)
		(width 0.09525)
		(layer "In2.Cu")
		(net "M_C_CPU1_CLK_DN<0>")
	)
	(arc
		(start 80.479646 -256.309368)
		(mid 80.761078 -256.385123)
		(end 81.04251 -256.309368)
		(width 0.09525)
		(layer "In2.Cu")
		(net "M_C_CPU1_CLK_DN<0>")
	)
	(arc
		(start 84.239608 -256.309368)
		(mid 84.52104 -256.385123)
		(end 84.802472 -256.309368)
		(width 0.09525)
		(layer "In2.Cu")
		(net "M_C_CPU1_CLK_DN<0>")
	)
	(arc
		(start 92.699586 -256.309368)
		(mid 92.981018 -256.385123)
		(end 93.26245 -256.309368)
		(width 0.09525)
		(layer "In2.Cu")
		(net "M_C_CPU1_CLK_DN<0>")
	)
	(arc
		(start 86.119716 -256.309368)
		(mid 86.401148 -256.385123)
		(end 86.68258 -256.309368)
		(width 0.09525)
		(layer "In2.Cu")
		(net "M_C_CPU1_CLK_DN<0>")
	)
	(arc
		(start 93.270832 -256.304542)
		(mid 93.455864 -256.258628)
		(end 93.63964 -256.309368)
		(width 0.09525)
		(layer "In2.Cu")
		(net "M_C_CPU1_CLK_DN<0>")
	)
	(arc
		(start 80.102456 -256.309368)
		(mid 80.286231 -256.258596)
		(end 80.471264 -256.304542)
		(width 0.09525)
		(layer "In2.Cu")
		(net "M_C_CPU1_CLK_DN<0>")
	)
	(arc
		(start 78.144878 -256.368296)
		(mid 78.181582 -256.336338)
		(end 78.222094 -256.309368)
		(width 0.09525)
		(layer "In2.Cu")
		(net "M_C_CPU1_CLK_DN<0>")
	)
	(arc
		(start 93.63964 -256.309368)
		(mid 93.873184 -256.383074)
		(end 94.11589 -256.350262)
		(width 0.09525)
		(layer "In2.Cu")
		(net "M_C_CPU1_CLK_DN<0>")
	)
	(arc
		(start 86.68258 -256.309368)
		(mid 86.871048 -256.258691)
		(end 87.059516 -256.309368)
		(width 0.09525)
		(layer "In2.Cu")
		(net "M_C_CPU1_CLK_DN<0>")
	)
	(arc
		(start 82.3595 -256.309368)
		(mid 82.640932 -256.385123)
		(end 82.922364 -256.309368)
		(width 0.09525)
		(layer "In2.Cu")
		(net "M_C_CPU1_CLK_DN<0>")
	)
	(arc
		(start 79.162148 -256.309368)
		(mid 79.344018 -256.258503)
		(end 79.527654 -256.30251)
		(width 0.09525)
		(layer "In2.Cu")
		(net "M_C_CPU1_CLK_DN<0>")
	)
	(arc
		(start 83.299554 -256.309368)
		(mid 83.580986 -256.385123)
		(end 83.862418 -256.309368)
		(width 0.09525)
		(layer "In2.Cu")
		(net "M_C_CPU1_CLK_DN<0>")
	)
	(arc
		(start 92.322396 -256.309368)
		(mid 92.506171 -256.258596)
		(end 92.691204 -256.304542)
		(width 0.09525)
		(layer "In2.Cu")
		(net "M_C_CPU1_CLK_DN<0>")
	)
	(segment
		(start 95.797878 -250.420378)
		(end 95.331026 -250.15444)
		(width 0.10668)
		(layer "F.Cu")
		(net "M_C_CPU1_ALERT_R_N")
	)
	(segment
		(start 83.289648 -250.481846)
		(end 83.29803 -250.47702)
		(width 0.0889)
		(layer "In2.Cu")
		(net "M_C_CPU1_ALERT_R_N")
	)
	(segment
		(start 81.044034 -250.47702)
		(end 81.052416 -250.481846)
		(width 0.0889)
		(layer "In2.Cu")
		(net "M_C_CPU1_ALERT_R_N")
	)
	(segment
		(start 92.68968 -250.481846)
		(end 92.698062 -250.47702)
		(width 0.0889)
		(layer "In2.Cu")
		(net "M_C_CPU1_ALERT_R_N")
	)
	(segment
		(start 66.081656 -250.357386)
		(end 67.711828 -249.682254)
		(width 0.11684)
		(layer "In2.Cu")
		(net "M_C_CPU1_ALERT_R_N")
	)
	(segment
		(start 47.421546 -246.216424)
		(end 60.141866 -246.216424)
		(width 0.11684)
		(layer "In2.Cu")
		(net "M_C_CPU1_ALERT_R_N")
	)
	(segment
		(start 84.803996 -250.47702)
		(end 84.812378 -250.481846)
		(width 0.0889)
		(layer "In2.Cu")
		(net "M_C_CPU1_ALERT_R_N")
	)
	(segment
		(start 80.46974 -250.481846)
		(end 80.478122 -250.47702)
		(width 0.0889)
		(layer "In2.Cu")
		(net "M_C_CPU1_ALERT_R_N")
	)
	(segment
		(start 45.737018 -244.085364)
		(end 45.737018 -244.531896)
		(width 0.11684)
		(layer "In2.Cu")
		(net "M_C_CPU1_ALERT_R_N")
	)
	(segment
		(start 76.434696 -250.403614)
		(end 78.001368 -250.403614)
		(width 0.0889)
		(layer "In2.Cu")
		(net "M_C_CPU1_ALERT_R_N")
	)
	(segment
		(start 76.336906 -250.501404)
		(end 76.434696 -250.403614)
		(width 0.0889)
		(layer "In2.Cu")
		(net "M_C_CPU1_ALERT_R_N")
	)
	(segment
		(start 90.444066 -250.47702)
		(end 90.452448 -250.481846)
		(width 0.0889)
		(layer "In2.Cu")
		(net "M_C_CPU1_ALERT_R_N")
	)
	(segment
		(start 85.74405 -250.47702)
		(end 85.752432 -250.481846)
		(width 0.0889)
		(layer "In2.Cu")
		(net "M_C_CPU1_ALERT_R_N")
	)
	(segment
		(start 45.737018 -244.531896)
		(end 47.421546 -246.216424)
		(width 0.11684)
		(layer "In2.Cu")
		(net "M_C_CPU1_ALERT_R_N")
	)
	(segment
		(start 84.229702 -250.481846)
		(end 84.238084 -250.47702)
		(width 0.0889)
		(layer "In2.Cu")
		(net "M_C_CPU1_ALERT_R_N")
	)
	(segment
		(start 76.060046 -250.501404)
		(end 76.336906 -250.501404)
		(width 0.0889)
		(layer "In2.Cu")
		(net "M_C_CPU1_ALERT_R_N")
	)
	(segment
		(start 74.357992 -250.501404)
		(end 76.060046 -250.501404)
		(width 0.11684)
		(layer "In2.Cu")
		(net "M_C_CPU1_ALERT_R_N")
	)
	(segment
		(start 95.48495 -250.41987)
		(end 95.331026 -250.15444)
		(width 0.0889)
		(layer "In2.Cu")
		(net "M_C_CPU1_ALERT_R_N")
	)
	(segment
		(start 95.462598 -250.503182)
		(end 95.48495 -250.41987)
		(width 0.0889)
		(layer "In2.Cu")
		(net "M_C_CPU1_ALERT_R_N")
	)
	(segment
		(start 60.141866 -246.216424)
		(end 64.282828 -250.357386)
		(width 0.11684)
		(layer "In2.Cu")
		(net "M_C_CPU1_ALERT_R_N")
	)
	(segment
		(start 78.199488 -250.46178)
		(end 78.249018 -250.490228)
		(width 0.0889)
		(layer "In2.Cu")
		(net "M_C_CPU1_ALERT_R_N")
	)
	(segment
		(start 73.538842 -249.682254)
		(end 74.357992 -250.501404)
		(width 0.11684)
		(layer "In2.Cu")
		(net "M_C_CPU1_ALERT_R_N")
	)
	(segment
		(start 88.929718 -250.481846)
		(end 88.9381 -250.47702)
		(width 0.0889)
		(layer "In2.Cu")
		(net "M_C_CPU1_ALERT_R_N")
	)
	(segment
		(start 79.529686 -250.481846)
		(end 79.538068 -250.47702)
		(width 0.0889)
		(layer "In2.Cu")
		(net "M_C_CPU1_ALERT_R_N")
	)
	(segment
		(start 93.263974 -250.47702)
		(end 93.272356 -250.481846)
		(width 0.0889)
		(layer "In2.Cu")
		(net "M_C_CPU1_ALERT_R_N")
	)
	(segment
		(start 94.204028 -250.47702)
		(end 94.21241 -250.481846)
		(width 0.0889)
		(layer "In2.Cu")
		(net "M_C_CPU1_ALERT_R_N")
	)
	(segment
		(start 64.282828 -250.357386)
		(end 66.081656 -250.357386)
		(width 0.11684)
		(layer "In2.Cu")
		(net "M_C_CPU1_ALERT_R_N")
	)
	(segment
		(start 87.989664 -250.481846)
		(end 87.998046 -250.47702)
		(width 0.0889)
		(layer "In2.Cu")
		(net "M_C_CPU1_ALERT_R_N")
	)
	(segment
		(start 89.504012 -250.47702)
		(end 89.512394 -250.481846)
		(width 0.0889)
		(layer "In2.Cu")
		(net "M_C_CPU1_ALERT_R_N")
	)
	(segment
		(start 67.711828 -249.682254)
		(end 73.538842 -249.682254)
		(width 0.11684)
		(layer "In2.Cu")
		(net "M_C_CPU1_ALERT_R_N")
	)
	(arc
		(start 84.812378 -250.481846)
		(mid 84.995886 -250.52734)
		(end 85.178138 -250.47702)
		(width 0.0889)
		(layer "In2.Cu")
		(net "M_C_CPU1_ALERT_R_N")
	)
	(arc
		(start 78.249018 -250.490228)
		(mid 78.42516 -250.52702)
		(end 78.598014 -250.47702)
		(width 0.0889)
		(layer "In2.Cu")
		(net "M_C_CPU1_ALERT_R_N")
	)
	(arc
		(start 92.698062 -250.47702)
		(mid 92.981018 -250.400843)
		(end 93.263974 -250.47702)
		(width 0.0889)
		(layer "In2.Cu")
		(net "M_C_CPU1_ALERT_R_N")
	)
	(arc
		(start 83.29803 -250.47702)
		(mid 83.580986 -250.400843)
		(end 83.863942 -250.47702)
		(width 0.0889)
		(layer "In2.Cu")
		(net "M_C_CPU1_ALERT_R_N")
	)
	(arc
		(start 80.10398 -250.47702)
		(mid 80.286231 -250.52737)
		(end 80.46974 -250.481846)
		(width 0.0889)
		(layer "In2.Cu")
		(net "M_C_CPU1_ALERT_R_N")
	)
	(arc
		(start 79.163926 -250.47702)
		(mid 79.346177 -250.52737)
		(end 79.529686 -250.481846)
		(width 0.0889)
		(layer "In2.Cu")
		(net "M_C_CPU1_ALERT_R_N")
	)
	(arc
		(start 79.538068 -250.47702)
		(mid 79.821024 -250.400843)
		(end 80.10398 -250.47702)
		(width 0.0889)
		(layer "In2.Cu")
		(net "M_C_CPU1_ALERT_R_N")
	)
	(arc
		(start 87.623904 -250.47702)
		(mid 87.806155 -250.52737)
		(end 87.989664 -250.481846)
		(width 0.0889)
		(layer "In2.Cu")
		(net "M_C_CPU1_ALERT_R_N")
	)
	(arc
		(start 80.478122 -250.47702)
		(mid 80.761078 -250.400843)
		(end 81.044034 -250.47702)
		(width 0.0889)
		(layer "In2.Cu")
		(net "M_C_CPU1_ALERT_R_N")
	)
	(arc
		(start 83.863942 -250.47702)
		(mid 84.046193 -250.52737)
		(end 84.229702 -250.481846)
		(width 0.0889)
		(layer "In2.Cu")
		(net "M_C_CPU1_ALERT_R_N")
	)
	(arc
		(start 87.998046 -250.47702)
		(mid 88.281002 -250.400843)
		(end 88.563958 -250.47702)
		(width 0.0889)
		(layer "In2.Cu")
		(net "M_C_CPU1_ALERT_R_N")
	)
	(arc
		(start 93.272356 -250.481846)
		(mid 93.455864 -250.52734)
		(end 93.638116 -250.47702)
		(width 0.0889)
		(layer "In2.Cu")
		(net "M_C_CPU1_ALERT_R_N")
	)
	(arc
		(start 95.144082 -250.47702)
		(mid 95.300401 -250.526015)
		(end 95.462598 -250.503182)
		(width 0.0889)
		(layer "In2.Cu")
		(net "M_C_CPU1_ALERT_R_N")
	)
	(arc
		(start 78.001368 -250.403614)
		(mid 78.103108 -250.423565)
		(end 78.199488 -250.46178)
		(width 0.0889)
		(layer "In2.Cu")
		(net "M_C_CPU1_ALERT_R_N")
	)
	(arc
		(start 88.9381 -250.47702)
		(mid 89.221056 -250.400843)
		(end 89.504012 -250.47702)
		(width 0.0889)
		(layer "In2.Cu")
		(net "M_C_CPU1_ALERT_R_N")
	)
	(arc
		(start 92.32392 -250.47702)
		(mid 92.506171 -250.52737)
		(end 92.68968 -250.481846)
		(width 0.0889)
		(layer "In2.Cu")
		(net "M_C_CPU1_ALERT_R_N")
	)
	(arc
		(start 91.38412 -250.47702)
		(mid 91.571064 -250.527275)
		(end 91.758008 -250.47702)
		(width 0.0889)
		(layer "In2.Cu")
		(net "M_C_CPU1_ALERT_R_N")
	)
	(arc
		(start 85.178138 -250.47702)
		(mid 85.461094 -250.400843)
		(end 85.74405 -250.47702)
		(width 0.0889)
		(layer "In2.Cu")
		(net "M_C_CPU1_ALERT_R_N")
	)
	(arc
		(start 81.984088 -250.47702)
		(mid 82.171032 -250.527275)
		(end 82.357976 -250.47702)
		(width 0.0889)
		(layer "In2.Cu")
		(net "M_C_CPU1_ALERT_R_N")
	)
	(arc
		(start 88.563958 -250.47702)
		(mid 88.746209 -250.52737)
		(end 88.929718 -250.481846)
		(width 0.0889)
		(layer "In2.Cu")
		(net "M_C_CPU1_ALERT_R_N")
	)
	(arc
		(start 84.238084 -250.47702)
		(mid 84.52104 -250.400843)
		(end 84.803996 -250.47702)
		(width 0.0889)
		(layer "In2.Cu")
		(net "M_C_CPU1_ALERT_R_N")
	)
	(arc
		(start 82.923888 -250.47702)
		(mid 83.106139 -250.52737)
		(end 83.289648 -250.481846)
		(width 0.0889)
		(layer "In2.Cu")
		(net "M_C_CPU1_ALERT_R_N")
	)
	(arc
		(start 90.818208 -250.47702)
		(mid 91.101164 -250.400843)
		(end 91.38412 -250.47702)
		(width 0.0889)
		(layer "In2.Cu")
		(net "M_C_CPU1_ALERT_R_N")
	)
	(arc
		(start 81.052416 -250.481846)
		(mid 81.235924 -250.52734)
		(end 81.418176 -250.47702)
		(width 0.0889)
		(layer "In2.Cu")
		(net "M_C_CPU1_ALERT_R_N")
	)
	(arc
		(start 89.512394 -250.481846)
		(mid 89.695902 -250.52734)
		(end 89.878154 -250.47702)
		(width 0.0889)
		(layer "In2.Cu")
		(net "M_C_CPU1_ALERT_R_N")
	)
	(arc
		(start 94.57817 -250.47702)
		(mid 94.861126 -250.400843)
		(end 95.144082 -250.47702)
		(width 0.0889)
		(layer "In2.Cu")
		(net "M_C_CPU1_ALERT_R_N")
	)
	(arc
		(start 91.758008 -250.47702)
		(mid 92.040964 -250.400843)
		(end 92.32392 -250.47702)
		(width 0.0889)
		(layer "In2.Cu")
		(net "M_C_CPU1_ALERT_R_N")
	)
	(arc
		(start 93.638116 -250.47702)
		(mid 93.921072 -250.400843)
		(end 94.204028 -250.47702)
		(width 0.0889)
		(layer "In2.Cu")
		(net "M_C_CPU1_ALERT_R_N")
	)
	(arc
		(start 82.357976 -250.47702)
		(mid 82.640932 -250.400843)
		(end 82.923888 -250.47702)
		(width 0.0889)
		(layer "In2.Cu")
		(net "M_C_CPU1_ALERT_R_N")
	)
	(arc
		(start 86.118192 -250.47702)
		(mid 86.401148 -250.400843)
		(end 86.684104 -250.47702)
		(width 0.0889)
		(layer "In2.Cu")
		(net "M_C_CPU1_ALERT_R_N")
	)
	(arc
		(start 86.684104 -250.47702)
		(mid 86.871048 -250.527275)
		(end 87.057992 -250.47702)
		(width 0.0889)
		(layer "In2.Cu")
		(net "M_C_CPU1_ALERT_R_N")
	)
	(arc
		(start 87.057992 -250.47702)
		(mid 87.340948 -250.400843)
		(end 87.623904 -250.47702)
		(width 0.0889)
		(layer "In2.Cu")
		(net "M_C_CPU1_ALERT_R_N")
	)
	(arc
		(start 94.21241 -250.481846)
		(mid 94.395918 -250.52734)
		(end 94.57817 -250.47702)
		(width 0.0889)
		(layer "In2.Cu")
		(net "M_C_CPU1_ALERT_R_N")
	)
	(arc
		(start 81.418176 -250.47702)
		(mid 81.701132 -250.400843)
		(end 81.984088 -250.47702)
		(width 0.0889)
		(layer "In2.Cu")
		(net "M_C_CPU1_ALERT_R_N")
	)
	(arc
		(start 78.598014 -250.47702)
		(mid 78.88097 -250.400843)
		(end 79.163926 -250.47702)
		(width 0.0889)
		(layer "In2.Cu")
		(net "M_C_CPU1_ALERT_R_N")
	)
	(arc
		(start 90.452448 -250.481846)
		(mid 90.635956 -250.52734)
		(end 90.818208 -250.47702)
		(width 0.0889)
		(layer "In2.Cu")
		(net "M_C_CPU1_ALERT_R_N")
	)
	(arc
		(start 89.878154 -250.47702)
		(mid 90.16111 -250.400843)
		(end 90.444066 -250.47702)
		(width 0.0889)
		(layer "In2.Cu")
		(net "M_C_CPU1_ALERT_R_N")
	)
	(arc
		(start 85.752432 -250.481846)
		(mid 85.93594 -250.52734)
		(end 86.118192 -250.47702)
		(width 0.0889)
		(layer "In2.Cu")
		(net "M_C_CPU1_ALERT_R_N")
	)
	(via
		(at 44.340018 -244.085364)
		(size 0.4826)
		(drill 0.254)
		(layers "F.Cu" "B.Cu")
		(net "M_C_CPU1_ALERT_N")
	)
	(segment
		(start 44.936918 -244.085364)
		(end 44.340018 -244.085364)
		(width 0.10668)
		(layer "B.Cu")
		(net "M_C_CPU1_ALERT_N")
	)
	(segment
		(start 343.097866 -267.34008)
		(end 342.631014 -267.606018)
		(width 0.10668)
		(layer "F.Cu")
		(net "M_C_CPU0_SB_RSP<0>")
	)
	(segment
		(start 342.631014 -267.606018)
		(end 342.48217 -267.862304)
		(width 0.0889)
		(layer "In2.Cu")
		(net "M_C_CPU0_SB_RSP<0>")
	)
	(segment
		(start 303.486566 -270.010128)
		(end 302.677576 -270.010128)
		(width 0.11684)
		(layer "In2.Cu")
		(net "M_C_CPU0_SB_RSP<0>")
	)
	(segment
		(start 324.081394 -266.85113)
		(end 311.269634 -266.85113)
		(width 0.11684)
		(layer "In2.Cu")
		(net "M_C_CPU0_SB_RSP<0>")
	)
	(segment
		(start 293.669212 -269.59941)
		(end 293.514526 -269.754096)
		(width 0.11684)
		(layer "In2.Cu")
		(net "M_C_CPU0_SB_RSP<0>")
	)
	(segment
		(start 305.226212 -269.855442)
		(end 305.226212 -269.741396)
		(width 0.11684)
		(layer "In2.Cu")
		(net "M_C_CPU0_SB_RSP<0>")
	)
	(segment
		(start 301.98949 -269.850362)
		(end 301.834804 -270.005048)
		(width 0.11684)
		(layer "In2.Cu")
		(net "M_C_CPU0_SB_RSP<0>")
	)
	(segment
		(start 297.001692 -270.010128)
		(end 296.782744 -270.010128)
		(width 0.11684)
		(layer "In2.Cu")
		(net "M_C_CPU0_SB_RSP<0>")
	)
	(segment
		(start 306.128166 -269.58671)
		(end 305.909218 -269.58671)
		(width 0.11684)
		(layer "In2.Cu")
		(net "M_C_CPU0_SB_RSP<0>")
	)
	(segment
		(start 298.896024 -270.010128)
		(end 298.741338 -269.855442)
		(width 0.11684)
		(layer "In2.Cu")
		(net "M_C_CPU0_SB_RSP<0>")
	)
	(segment
		(start 294.042846 -269.754096)
		(end 293.88816 -269.59941)
		(width 0.11684)
		(layer "In2.Cu")
		(net "M_C_CPU0_SB_RSP<0>")
	)
	(segment
		(start 306.282852 -269.741396)
		(end 306.128166 -269.58671)
		(width 0.11684)
		(layer "In2.Cu")
		(net "M_C_CPU0_SB_RSP<0>")
	)
	(segment
		(start 338.687156 -267.92301)
		(end 338.676488 -267.916914)
		(width 0.0889)
		(layer "In2.Cu")
		(net "M_C_CPU0_SB_RSP<0>")
	)
	(segment
		(start 301.615856 -270.005048)
		(end 301.46117 -269.850362)
		(width 0.11684)
		(layer "In2.Cu")
		(net "M_C_CPU0_SB_RSP<0>")
	)
	(segment
		(start 306.282852 -269.855442)
		(end 306.282852 -269.741396)
		(width 0.11684)
		(layer "In2.Cu")
		(net "M_C_CPU0_SB_RSP<0>")
	)
	(segment
		(start 302.363124 -269.59433)
		(end 302.144176 -269.59433)
		(width 0.11684)
		(layer "In2.Cu")
		(net "M_C_CPU0_SB_RSP<0>")
	)
	(segment
		(start 294.571166 -269.754096)
		(end 294.571166 -269.868142)
		(width 0.11684)
		(layer "In2.Cu")
		(net "M_C_CPU0_SB_RSP<0>")
	)
	(segment
		(start 335.305654 -267.916914)
		(end 335.294986 -267.92301)
		(width 0.0889)
		(layer "In2.Cu")
		(net "M_C_CPU0_SB_RSP<0>")
	)
	(segment
		(start 294.725852 -269.59941)
		(end 294.571166 -269.754096)
		(width 0.11684)
		(layer "In2.Cu")
		(net "M_C_CPU0_SB_RSP<0>")
	)
	(segment
		(start 304.852578 -269.58671)
		(end 304.697892 -269.741396)
		(width 0.11684)
		(layer "In2.Cu")
		(net "M_C_CPU0_SB_RSP<0>")
	)
	(segment
		(start 324.403974 -267.17371)
		(end 324.081394 -266.85113)
		(width 0.11684)
		(layer "In2.Cu")
		(net "M_C_CPU0_SB_RSP<0>")
	)
	(segment
		(start 327.827894 -267.78331)
		(end 327.431908 -267.78331)
		(width 0.0889)
		(layer "In2.Cu")
		(net "M_C_CPU0_SB_RSP<0>")
	)
	(segment
		(start 293.514526 -269.754096)
		(end 293.514526 -269.868142)
		(width 0.11684)
		(layer "In2.Cu")
		(net "M_C_CPU0_SB_RSP<0>")
	)
	(segment
		(start 301.46117 -269.850362)
		(end 301.46117 -269.736316)
		(width 0.11684)
		(layer "In2.Cu")
		(net "M_C_CPU0_SB_RSP<0>")
	)
	(segment
		(start 296.628058 -269.741396)
		(end 296.473372 -269.58671)
		(width 0.11684)
		(layer "In2.Cu")
		(net "M_C_CPU0_SB_RSP<0>")
	)
	(segment
		(start 294.042846 -269.868142)
		(end 294.042846 -269.754096)
		(width 0.11684)
		(layer "In2.Cu")
		(net "M_C_CPU0_SB_RSP<0>")
	)
	(segment
		(start 303.641252 -269.741396)
		(end 303.641252 -269.855442)
		(width 0.11684)
		(layer "In2.Cu")
		(net "M_C_CPU0_SB_RSP<0>")
	)
	(segment
		(start 295.099486 -269.868142)
		(end 295.099486 -269.754096)
		(width 0.11684)
		(layer "In2.Cu")
		(net "M_C_CPU0_SB_RSP<0>")
	)
	(segment
		(start 297.311064 -269.58671)
		(end 297.156378 -269.741396)
		(width 0.11684)
		(layer "In2.Cu")
		(net "M_C_CPU0_SB_RSP<0>")
	)
	(segment
		(start 304.324258 -270.010128)
		(end 304.169572 -269.855442)
		(width 0.11684)
		(layer "In2.Cu")
		(net "M_C_CPU0_SB_RSP<0>")
	)
	(segment
		(start 293.514526 -269.868142)
		(end 293.37254 -270.010128)
		(width 0.11684)
		(layer "In2.Cu")
		(net "M_C_CPU0_SB_RSP<0>")
	)
	(segment
		(start 298.213018 -269.741396)
		(end 298.213018 -269.855442)
		(width 0.11684)
		(layer "In2.Cu")
		(net "M_C_CPU0_SB_RSP<0>")
	)
	(segment
		(start 296.254424 -269.58671)
		(end 296.099738 -269.741396)
		(width 0.11684)
		(layer "In2.Cu")
		(net "M_C_CPU0_SB_RSP<0>")
	)
	(segment
		(start 292.705028 -270.010128)
		(end 292.280086 -270.43507)
		(width 0.11684)
		(layer "In2.Cu")
		(net "M_C_CPU0_SB_RSP<0>")
	)
	(segment
		(start 304.014886 -269.58671)
		(end 303.795938 -269.58671)
		(width 0.11684)
		(layer "In2.Cu")
		(net "M_C_CPU0_SB_RSP<0>")
	)
	(segment
		(start 339.62721 -267.92301)
		(end 339.616542 -267.916914)
		(width 0.0889)
		(layer "In2.Cu")
		(net "M_C_CPU0_SB_RSP<0>")
	)
	(segment
		(start 293.37254 -270.010128)
		(end 292.705028 -270.010128)
		(width 0.11684)
		(layer "In2.Cu")
		(net "M_C_CPU0_SB_RSP<0>")
	)
	(segment
		(start 296.099738 -269.741396)
		(end 296.099738 -269.855442)
		(width 0.11684)
		(layer "In2.Cu")
		(net "M_C_CPU0_SB_RSP<0>")
	)
	(segment
		(start 298.213018 -269.855442)
		(end 298.058332 -270.010128)
		(width 0.11684)
		(layer "In2.Cu")
		(net "M_C_CPU0_SB_RSP<0>")
	)
	(segment
		(start 298.586652 -269.58671)
		(end 298.367704 -269.58671)
		(width 0.11684)
		(layer "In2.Cu")
		(net "M_C_CPU0_SB_RSP<0>")
	)
	(segment
		(start 297.839384 -270.010128)
		(end 297.684698 -269.855442)
		(width 0.11684)
		(layer "In2.Cu")
		(net "M_C_CPU0_SB_RSP<0>")
	)
	(segment
		(start 297.156378 -269.855442)
		(end 297.001692 -270.010128)
		(width 0.11684)
		(layer "In2.Cu")
		(net "M_C_CPU0_SB_RSP<0>")
	)
	(segment
		(start 294.197532 -270.022828)
		(end 294.042846 -269.868142)
		(width 0.11684)
		(layer "In2.Cu")
		(net "M_C_CPU0_SB_RSP<0>")
	)
	(segment
		(start 301.306484 -269.58163)
		(end 301.087536 -269.58163)
		(width 0.11684)
		(layer "In2.Cu")
		(net "M_C_CPU0_SB_RSP<0>")
	)
	(segment
		(start 293.88816 -269.59941)
		(end 293.669212 -269.59941)
		(width 0.11684)
		(layer "In2.Cu")
		(net "M_C_CPU0_SB_RSP<0>")
	)
	(segment
		(start 306.437538 -270.010128)
		(end 306.282852 -269.855442)
		(width 0.11684)
		(layer "In2.Cu")
		(net "M_C_CPU0_SB_RSP<0>")
	)
	(segment
		(start 304.169572 -269.741396)
		(end 304.014886 -269.58671)
		(width 0.11684)
		(layer "In2.Cu")
		(net "M_C_CPU0_SB_RSP<0>")
	)
	(segment
		(start 327.431908 -267.78331)
		(end 326.822308 -267.17371)
		(width 0.11684)
		(layer "In2.Cu")
		(net "M_C_CPU0_SB_RSP<0>")
	)
	(segment
		(start 296.782744 -270.010128)
		(end 296.628058 -269.855442)
		(width 0.11684)
		(layer "In2.Cu")
		(net "M_C_CPU0_SB_RSP<0>")
	)
	(segment
		(start 305.599846 -270.010128)
		(end 305.380898 -270.010128)
		(width 0.11684)
		(layer "In2.Cu")
		(net "M_C_CPU0_SB_RSP<0>")
	)
	(segment
		(start 298.741338 -269.741396)
		(end 298.586652 -269.58671)
		(width 0.11684)
		(layer "In2.Cu")
		(net "M_C_CPU0_SB_RSP<0>")
	)
	(segment
		(start 308.110636 -270.010128)
		(end 306.437538 -270.010128)
		(width 0.11684)
		(layer "In2.Cu")
		(net "M_C_CPU0_SB_RSP<0>")
	)
	(segment
		(start 295.241472 -270.010128)
		(end 295.099486 -269.868142)
		(width 0.11684)
		(layer "In2.Cu")
		(net "M_C_CPU0_SB_RSP<0>")
	)
	(segment
		(start 340.945724 -267.916914)
		(end 340.935056 -267.92301)
		(width 0.0889)
		(layer "In2.Cu")
		(net "M_C_CPU0_SB_RSP<0>")
	)
	(segment
		(start 298.058332 -270.010128)
		(end 297.839384 -270.010128)
		(width 0.11684)
		(layer "In2.Cu")
		(net "M_C_CPU0_SB_RSP<0>")
	)
	(segment
		(start 297.684698 -269.855442)
		(end 297.684698 -269.741396)
		(width 0.11684)
		(layer "In2.Cu")
		(net "M_C_CPU0_SB_RSP<0>")
	)
	(segment
		(start 302.144176 -269.59433)
		(end 301.98949 -269.749016)
		(width 0.11684)
		(layer "In2.Cu")
		(net "M_C_CPU0_SB_RSP<0>")
	)
	(segment
		(start 305.226212 -269.741396)
		(end 305.071526 -269.58671)
		(width 0.11684)
		(layer "In2.Cu")
		(net "M_C_CPU0_SB_RSP<0>")
	)
	(segment
		(start 301.834804 -270.005048)
		(end 301.615856 -270.005048)
		(width 0.11684)
		(layer "In2.Cu")
		(net "M_C_CPU0_SB_RSP<0>")
	)
	(segment
		(start 294.9448 -269.59941)
		(end 294.725852 -269.59941)
		(width 0.11684)
		(layer "In2.Cu")
		(net "M_C_CPU0_SB_RSP<0>")
	)
	(segment
		(start 303.641252 -269.855442)
		(end 303.486566 -270.010128)
		(width 0.11684)
		(layer "In2.Cu")
		(net "M_C_CPU0_SB_RSP<0>")
	)
	(segment
		(start 336.245708 -267.916914)
		(end 336.23504 -267.92301)
		(width 0.0889)
		(layer "In2.Cu")
		(net "M_C_CPU0_SB_RSP<0>")
	)
	(segment
		(start 294.41648 -270.022828)
		(end 294.197532 -270.022828)
		(width 0.11684)
		(layer "In2.Cu")
		(net "M_C_CPU0_SB_RSP<0>")
	)
	(segment
		(start 298.367704 -269.58671)
		(end 298.213018 -269.741396)
		(width 0.11684)
		(layer "In2.Cu")
		(net "M_C_CPU0_SB_RSP<0>")
	)
	(segment
		(start 302.51781 -269.850362)
		(end 302.51781 -269.749016)
		(width 0.11684)
		(layer "In2.Cu")
		(net "M_C_CPU0_SB_RSP<0>")
	)
	(segment
		(start 305.380898 -270.010128)
		(end 305.226212 -269.855442)
		(width 0.11684)
		(layer "In2.Cu")
		(net "M_C_CPU0_SB_RSP<0>")
	)
	(segment
		(start 300.93285 -269.850362)
		(end 300.773084 -270.010128)
		(width 0.11684)
		(layer "In2.Cu")
		(net "M_C_CPU0_SB_RSP<0>")
	)
	(segment
		(start 304.169572 -269.855442)
		(end 304.169572 -269.741396)
		(width 0.11684)
		(layer "In2.Cu")
		(net "M_C_CPU0_SB_RSP<0>")
	)
	(segment
		(start 295.099486 -269.754096)
		(end 294.9448 -269.59941)
		(width 0.11684)
		(layer "In2.Cu")
		(net "M_C_CPU0_SB_RSP<0>")
	)
	(segment
		(start 296.473372 -269.58671)
		(end 296.254424 -269.58671)
		(width 0.11684)
		(layer "In2.Cu")
		(net "M_C_CPU0_SB_RSP<0>")
	)
	(segment
		(start 301.98949 -269.749016)
		(end 301.98949 -269.850362)
		(width 0.11684)
		(layer "In2.Cu")
		(net "M_C_CPU0_SB_RSP<0>")
	)
	(segment
		(start 295.945052 -270.010128)
		(end 295.241472 -270.010128)
		(width 0.11684)
		(layer "In2.Cu")
		(net "M_C_CPU0_SB_RSP<0>")
	)
	(segment
		(start 330.227178 -267.92301)
		(end 330.21651 -267.916914)
		(width 0.0889)
		(layer "In2.Cu")
		(net "M_C_CPU0_SB_RSP<0>")
	)
	(segment
		(start 298.741338 -269.855442)
		(end 298.741338 -269.741396)
		(width 0.11684)
		(layer "In2.Cu")
		(net "M_C_CPU0_SB_RSP<0>")
	)
	(segment
		(start 305.754532 -269.855442)
		(end 305.599846 -270.010128)
		(width 0.11684)
		(layer "In2.Cu")
		(net "M_C_CPU0_SB_RSP<0>")
	)
	(segment
		(start 311.269634 -266.85113)
		(end 308.110636 -270.010128)
		(width 0.11684)
		(layer "In2.Cu")
		(net "M_C_CPU0_SB_RSP<0>")
	)
	(segment
		(start 301.087536 -269.58163)
		(end 300.93285 -269.736316)
		(width 0.11684)
		(layer "In2.Cu")
		(net "M_C_CPU0_SB_RSP<0>")
	)
	(segment
		(start 340.00567 -267.916914)
		(end 339.995002 -267.92301)
		(width 0.0889)
		(layer "In2.Cu")
		(net "M_C_CPU0_SB_RSP<0>")
	)
	(segment
		(start 334.927194 -267.92301)
		(end 334.916526 -267.916914)
		(width 0.0889)
		(layer "In2.Cu")
		(net "M_C_CPU0_SB_RSP<0>")
	)
	(segment
		(start 297.684698 -269.741396)
		(end 297.530012 -269.58671)
		(width 0.11684)
		(layer "In2.Cu")
		(net "M_C_CPU0_SB_RSP<0>")
	)
	(segment
		(start 304.697892 -269.855442)
		(end 304.543206 -270.010128)
		(width 0.11684)
		(layer "In2.Cu")
		(net "M_C_CPU0_SB_RSP<0>")
	)
	(segment
		(start 303.795938 -269.58671)
		(end 303.641252 -269.741396)
		(width 0.11684)
		(layer "In2.Cu")
		(net "M_C_CPU0_SB_RSP<0>")
	)
	(segment
		(start 302.51781 -269.749016)
		(end 302.363124 -269.59433)
		(width 0.11684)
		(layer "In2.Cu")
		(net "M_C_CPU0_SB_RSP<0>")
	)
	(segment
		(start 296.099738 -269.855442)
		(end 295.945052 -270.010128)
		(width 0.11684)
		(layer "In2.Cu")
		(net "M_C_CPU0_SB_RSP<0>")
	)
	(segment
		(start 300.93285 -269.736316)
		(end 300.93285 -269.850362)
		(width 0.11684)
		(layer "In2.Cu")
		(net "M_C_CPU0_SB_RSP<0>")
	)
	(segment
		(start 330.605638 -267.916914)
		(end 330.59497 -267.92301)
		(width 0.0889)
		(layer "In2.Cu")
		(net "M_C_CPU0_SB_RSP<0>")
	)
	(segment
		(start 301.46117 -269.736316)
		(end 301.306484 -269.58163)
		(width 0.11684)
		(layer "In2.Cu")
		(net "M_C_CPU0_SB_RSP<0>")
	)
	(segment
		(start 302.677576 -270.010128)
		(end 302.51781 -269.850362)
		(width 0.11684)
		(layer "In2.Cu")
		(net "M_C_CPU0_SB_RSP<0>")
	)
	(segment
		(start 297.156378 -269.741396)
		(end 297.156378 -269.855442)
		(width 0.11684)
		(layer "In2.Cu")
		(net "M_C_CPU0_SB_RSP<0>")
	)
	(segment
		(start 305.754532 -269.741396)
		(end 305.754532 -269.855442)
		(width 0.11684)
		(layer "In2.Cu")
		(net "M_C_CPU0_SB_RSP<0>")
	)
	(segment
		(start 304.543206 -270.010128)
		(end 304.324258 -270.010128)
		(width 0.11684)
		(layer "In2.Cu")
		(net "M_C_CPU0_SB_RSP<0>")
	)
	(segment
		(start 305.909218 -269.58671)
		(end 305.754532 -269.741396)
		(width 0.11684)
		(layer "In2.Cu")
		(net "M_C_CPU0_SB_RSP<0>")
	)
	(segment
		(start 342.48217 -267.862304)
		(end 342.379554 -267.889482)
		(width 0.0889)
		(layer "In2.Cu")
		(net "M_C_CPU0_SB_RSP<0>")
	)
	(segment
		(start 297.530012 -269.58671)
		(end 297.311064 -269.58671)
		(width 0.11684)
		(layer "In2.Cu")
		(net "M_C_CPU0_SB_RSP<0>")
	)
	(segment
		(start 326.822308 -267.17371)
		(end 324.403974 -267.17371)
		(width 0.11684)
		(layer "In2.Cu")
		(net "M_C_CPU0_SB_RSP<0>")
	)
	(segment
		(start 331.545692 -267.916914)
		(end 331.535024 -267.92301)
		(width 0.0889)
		(layer "In2.Cu")
		(net "M_C_CPU0_SB_RSP<0>")
	)
	(segment
		(start 305.071526 -269.58671)
		(end 304.852578 -269.58671)
		(width 0.11684)
		(layer "In2.Cu")
		(net "M_C_CPU0_SB_RSP<0>")
	)
	(segment
		(start 333.98714 -267.92301)
		(end 333.976472 -267.916914)
		(width 0.0889)
		(layer "In2.Cu")
		(net "M_C_CPU0_SB_RSP<0>")
	)
	(segment
		(start 304.697892 -269.741396)
		(end 304.697892 -269.855442)
		(width 0.11684)
		(layer "In2.Cu")
		(net "M_C_CPU0_SB_RSP<0>")
	)
	(segment
		(start 294.571166 -269.868142)
		(end 294.41648 -270.022828)
		(width 0.11684)
		(layer "In2.Cu")
		(net "M_C_CPU0_SB_RSP<0>")
	)
	(segment
		(start 300.773084 -270.010128)
		(end 298.896024 -270.010128)
		(width 0.11684)
		(layer "In2.Cu")
		(net "M_C_CPU0_SB_RSP<0>")
	)
	(segment
		(start 296.628058 -269.855442)
		(end 296.628058 -269.741396)
		(width 0.11684)
		(layer "In2.Cu")
		(net "M_C_CPU0_SB_RSP<0>")
	)
	(arc
		(start 341.87511 -267.92301)
		(mid 341.691214 -267.97249)
		(end 341.507318 -267.92301)
		(width 0.0889)
		(layer "In2.Cu")
		(net "M_C_CPU0_SB_RSP<0>")
	)
	(arc
		(start 333.976472 -267.916914)
		(mid 333.694883 -267.84604)
		(end 333.414878 -267.92301)
		(width 0.0889)
		(layer "In2.Cu")
		(net "M_C_CPU0_SB_RSP<0>")
	)
	(arc
		(start 332.107286 -267.92301)
		(mid 331.827282 -267.845965)
		(end 331.545692 -267.916914)
		(width 0.0889)
		(layer "In2.Cu")
		(net "M_C_CPU0_SB_RSP<0>")
	)
	(arc
		(start 336.23504 -267.92301)
		(mid 336.051144 -267.97249)
		(end 335.867248 -267.92301)
		(width 0.0889)
		(layer "In2.Cu")
		(net "M_C_CPU0_SB_RSP<0>")
	)
	(arc
		(start 337.175094 -267.92301)
		(mid 336.991198 -267.97249)
		(end 336.807302 -267.92301)
		(width 0.0889)
		(layer "In2.Cu")
		(net "M_C_CPU0_SB_RSP<0>")
	)
	(arc
		(start 329.654916 -267.92301)
		(mid 329.47102 -267.97249)
		(end 329.287124 -267.92301)
		(width 0.0889)
		(layer "In2.Cu")
		(net "M_C_CPU0_SB_RSP<0>")
	)
	(arc
		(start 338.676488 -267.916914)
		(mid 338.394899 -267.84604)
		(end 338.114894 -267.92301)
		(width 0.0889)
		(layer "In2.Cu")
		(net "M_C_CPU0_SB_RSP<0>")
	)
	(arc
		(start 337.747102 -267.92301)
		(mid 337.461098 -267.846058)
		(end 337.175094 -267.92301)
		(width 0.0889)
		(layer "In2.Cu")
		(net "M_C_CPU0_SB_RSP<0>")
	)
	(arc
		(start 333.047086 -267.92301)
		(mid 332.761082 -267.846058)
		(end 332.475078 -267.92301)
		(width 0.0889)
		(layer "In2.Cu")
		(net "M_C_CPU0_SB_RSP<0>")
	)
	(arc
		(start 338.114894 -267.92301)
		(mid 337.930998 -267.97249)
		(end 337.747102 -267.92301)
		(width 0.0889)
		(layer "In2.Cu")
		(net "M_C_CPU0_SB_RSP<0>")
	)
	(arc
		(start 330.21651 -267.916914)
		(mid 329.934921 -267.84604)
		(end 329.654916 -267.92301)
		(width 0.0889)
		(layer "In2.Cu")
		(net "M_C_CPU0_SB_RSP<0>")
	)
	(arc
		(start 329.287124 -267.92301)
		(mid 329.00112 -267.846058)
		(end 328.715116 -267.92301)
		(width 0.0889)
		(layer "In2.Cu")
		(net "M_C_CPU0_SB_RSP<0>")
	)
	(arc
		(start 330.59497 -267.92301)
		(mid 330.411074 -267.97249)
		(end 330.227178 -267.92301)
		(width 0.0889)
		(layer "In2.Cu")
		(net "M_C_CPU0_SB_RSP<0>")
	)
	(arc
		(start 334.354932 -267.92301)
		(mid 334.171036 -267.97249)
		(end 333.98714 -267.92301)
		(width 0.0889)
		(layer "In2.Cu")
		(net "M_C_CPU0_SB_RSP<0>")
	)
	(arc
		(start 339.616542 -267.916914)
		(mid 339.334953 -267.84604)
		(end 339.054948 -267.92301)
		(width 0.0889)
		(layer "In2.Cu")
		(net "M_C_CPU0_SB_RSP<0>")
	)
	(arc
		(start 328.715116 -267.92301)
		(mid 328.53122 -267.97249)
		(end 328.347324 -267.92301)
		(width 0.0889)
		(layer "In2.Cu")
		(net "M_C_CPU0_SB_RSP<0>")
	)
	(arc
		(start 333.414878 -267.92301)
		(mid 333.230982 -267.97249)
		(end 333.047086 -267.92301)
		(width 0.0889)
		(layer "In2.Cu")
		(net "M_C_CPU0_SB_RSP<0>")
	)
	(arc
		(start 335.867248 -267.92301)
		(mid 335.587244 -267.845965)
		(end 335.305654 -267.916914)
		(width 0.0889)
		(layer "In2.Cu")
		(net "M_C_CPU0_SB_RSP<0>")
	)
	(arc
		(start 328.347324 -267.92301)
		(mid 328.096843 -267.818834)
		(end 327.827894 -267.78331)
		(width 0.0889)
		(layer "In2.Cu")
		(net "M_C_CPU0_SB_RSP<0>")
	)
	(arc
		(start 339.054948 -267.92301)
		(mid 338.871052 -267.97249)
		(end 338.687156 -267.92301)
		(width 0.0889)
		(layer "In2.Cu")
		(net "M_C_CPU0_SB_RSP<0>")
	)
	(arc
		(start 339.995002 -267.92301)
		(mid 339.811106 -267.97249)
		(end 339.62721 -267.92301)
		(width 0.0889)
		(layer "In2.Cu")
		(net "M_C_CPU0_SB_RSP<0>")
	)
	(arc
		(start 332.475078 -267.92301)
		(mid 332.291182 -267.97249)
		(end 332.107286 -267.92301)
		(width 0.0889)
		(layer "In2.Cu")
		(net "M_C_CPU0_SB_RSP<0>")
	)
	(arc
		(start 331.535024 -267.92301)
		(mid 331.351128 -267.97249)
		(end 331.167232 -267.92301)
		(width 0.0889)
		(layer "In2.Cu")
		(net "M_C_CPU0_SB_RSP<0>")
	)
	(arc
		(start 331.167232 -267.92301)
		(mid 330.887228 -267.845965)
		(end 330.605638 -267.916914)
		(width 0.0889)
		(layer "In2.Cu")
		(net "M_C_CPU0_SB_RSP<0>")
	)
	(arc
		(start 336.807302 -267.92301)
		(mid 336.527298 -267.845965)
		(end 336.245708 -267.916914)
		(width 0.0889)
		(layer "In2.Cu")
		(net "M_C_CPU0_SB_RSP<0>")
	)
	(arc
		(start 340.567264 -267.92301)
		(mid 340.28726 -267.845965)
		(end 340.00567 -267.916914)
		(width 0.0889)
		(layer "In2.Cu")
		(net "M_C_CPU0_SB_RSP<0>")
	)
	(arc
		(start 340.935056 -267.92301)
		(mid 340.75116 -267.97249)
		(end 340.567264 -267.92301)
		(width 0.0889)
		(layer "In2.Cu")
		(net "M_C_CPU0_SB_RSP<0>")
	)
	(arc
		(start 341.507318 -267.92301)
		(mid 341.227314 -267.845965)
		(end 340.945724 -267.916914)
		(width 0.0889)
		(layer "In2.Cu")
		(net "M_C_CPU0_SB_RSP<0>")
	)
	(arc
		(start 334.916526 -267.916914)
		(mid 334.634937 -267.84604)
		(end 334.354932 -267.92301)
		(width 0.0889)
		(layer "In2.Cu")
		(net "M_C_CPU0_SB_RSP<0>")
	)
	(arc
		(start 335.294986 -267.92301)
		(mid 335.11109 -267.97249)
		(end 334.927194 -267.92301)
		(width 0.0889)
		(layer "In2.Cu")
		(net "M_C_CPU0_SB_RSP<0>")
	)
	(arc
		(start 342.379554 -267.889482)
		(mid 342.123398 -267.847218)
		(end 341.87511 -267.92301)
		(width 0.0889)
		(layer "In2.Cu")
		(net "M_C_CPU0_SB_RSP<0>")
	)
	(segment
		(start 342.627966 -264.910062)
		(end 342.161114 -265.176)
		(width 0.10668)
		(layer "F.Cu")
		(net "M_C_CPU0_SB_PAR")
	)
	(segment
		(start 289.672522 -265.75131)
		(end 289.509708 -265.914124)
		(width 0.14478)
		(layer "In2.Cu")
		(net "M_C_CPU0_SB_PAR")
	)
	(segment
		(start 326.03313 -264.554462)
		(end 324.879462 -264.554462)
		(width 0.0889)
		(layer "In2.Cu")
		(net "M_C_CPU0_SB_PAR")
	)
	(segment
		(start 289.509708 -266.44727)
		(end 289.346894 -266.610084)
		(width 0.14478)
		(layer "In2.Cu")
		(net "M_C_CPU0_SB_PAR")
	)
	(segment
		(start 331.068172 -264.85342)
		(end 331.05979 -264.848594)
		(width 0.0889)
		(layer "In2.Cu")
		(net "M_C_CPU0_SB_PAR")
	)
	(segment
		(start 333.88808 -264.85342)
		(end 333.879698 -264.848594)
		(width 0.0889)
		(layer "In2.Cu")
		(net "M_C_CPU0_SB_PAR")
	)
	(segment
		(start 290.065968 -266.44727)
		(end 290.065968 -265.914124)
		(width 0.14478)
		(layer "In2.Cu")
		(net "M_C_CPU0_SB_PAR")
	)
	(segment
		(start 324.879462 -264.554462)
		(end 324.359524 -265.0744)
		(width 0.0889)
		(layer "In2.Cu")
		(net "M_C_CPU0_SB_PAR")
	)
	(segment
		(start 326.408034 -264.875518)
		(end 326.320658 -264.825226)
		(width 0.0889)
		(layer "In2.Cu")
		(net "M_C_CPU0_SB_PAR")
	)
	(segment
		(start 341.042498 -264.848594)
		(end 341.034116 -264.85342)
		(width 0.0889)
		(layer "In2.Cu")
		(net "M_C_CPU0_SB_PAR")
	)
	(segment
		(start 289.346894 -266.610084)
		(end 288.60496 -266.610084)
		(width 0.14478)
		(layer "In2.Cu")
		(net "M_C_CPU0_SB_PAR")
	)
	(segment
		(start 339.52815 -264.85342)
		(end 339.519768 -264.848594)
		(width 0.0889)
		(layer "In2.Cu")
		(net "M_C_CPU0_SB_PAR")
	)
	(segment
		(start 327.89876 -264.840212)
		(end 327.875392 -264.853674)
		(width 0.0889)
		(layer "In2.Cu")
		(net "M_C_CPU0_SB_PAR")
	)
	(segment
		(start 327.875392 -264.853674)
		(end 327.851516 -264.867644)
		(width 0.0889)
		(layer "In2.Cu")
		(net "M_C_CPU0_SB_PAR")
	)
	(segment
		(start 340.102444 -264.848594)
		(end 340.094062 -264.85342)
		(width 0.0889)
		(layer "In2.Cu")
		(net "M_C_CPU0_SB_PAR")
	)
	(segment
		(start 338.588096 -264.85342)
		(end 338.579714 -264.848594)
		(width 0.0889)
		(layer "In2.Cu")
		(net "M_C_CPU0_SB_PAR")
	)
	(segment
		(start 308.13248 -266.610084)
		(end 290.228782 -266.610084)
		(width 0.14478)
		(layer "In2.Cu")
		(net "M_C_CPU0_SB_PAR")
	)
	(segment
		(start 326.248014 -264.769346)
		(end 326.03313 -264.554462)
		(width 0.0889)
		(layer "In2.Cu")
		(net "M_C_CPU0_SB_PAR")
	)
	(segment
		(start 335.402428 -264.848594)
		(end 335.394046 -264.85342)
		(width 0.0889)
		(layer "In2.Cu")
		(net "M_C_CPU0_SB_PAR")
	)
	(segment
		(start 336.342482 -264.848594)
		(end 336.3341 -264.85342)
		(width 0.0889)
		(layer "In2.Cu")
		(net "M_C_CPU0_SB_PAR")
	)
	(segment
		(start 327.311258 -264.85342)
		(end 327.290684 -264.841482)
		(width 0.0889)
		(layer "In2.Cu")
		(net "M_C_CPU0_SB_PAR")
	)
	(segment
		(start 288.60496 -266.610084)
		(end 288.180018 -267.035026)
		(width 0.14478)
		(layer "In2.Cu")
		(net "M_C_CPU0_SB_PAR")
	)
	(segment
		(start 309.668164 -265.0744)
		(end 308.13248 -266.610084)
		(width 0.14478)
		(layer "In2.Cu")
		(net "M_C_CPU0_SB_PAR")
	)
	(segment
		(start 331.642466 -264.848594)
		(end 331.634084 -264.85342)
		(width 0.0889)
		(layer "In2.Cu")
		(net "M_C_CPU0_SB_PAR")
	)
	(segment
		(start 289.903154 -265.75131)
		(end 289.672522 -265.75131)
		(width 0.14478)
		(layer "In2.Cu")
		(net "M_C_CPU0_SB_PAR")
	)
	(segment
		(start 323.889624 -265.0744)
		(end 309.668164 -265.0744)
		(width 0.14478)
		(layer "In2.Cu")
		(net "M_C_CPU0_SB_PAR")
	)
	(segment
		(start 342.161114 -265.176)
		(end 342.315038 -264.91057)
		(width 0.0889)
		(layer "In2.Cu")
		(net "M_C_CPU0_SB_PAR")
	)
	(segment
		(start 334.828134 -264.85342)
		(end 334.819752 -264.848594)
		(width 0.0889)
		(layer "In2.Cu")
		(net "M_C_CPU0_SB_PAR")
	)
	(segment
		(start 290.228782 -266.610084)
		(end 290.065968 -266.44727)
		(width 0.14478)
		(layer "In2.Cu")
		(net "M_C_CPU0_SB_PAR")
	)
	(segment
		(start 330.128118 -264.85342)
		(end 330.119736 -264.848594)
		(width 0.0889)
		(layer "In2.Cu")
		(net "M_C_CPU0_SB_PAR")
	)
	(segment
		(start 290.065968 -265.914124)
		(end 289.903154 -265.75131)
		(width 0.14478)
		(layer "In2.Cu")
		(net "M_C_CPU0_SB_PAR")
	)
	(segment
		(start 289.509708 -265.914124)
		(end 289.509708 -266.44727)
		(width 0.14478)
		(layer "In2.Cu")
		(net "M_C_CPU0_SB_PAR")
	)
	(segment
		(start 342.315038 -264.91057)
		(end 342.292686 -264.827258)
		(width 0.0889)
		(layer "In2.Cu")
		(net "M_C_CPU0_SB_PAR")
	)
	(segment
		(start 324.359524 -265.0744)
		(end 323.889624 -265.0744)
		(width 0.0889)
		(layer "In2.Cu")
		(net "M_C_CPU0_SB_PAR")
	)
	(arc
		(start 328.248264 -264.85342)
		(mid 328.075156 -264.803304)
		(end 327.89876 -264.840212)
		(width 0.0889)
		(layer "In2.Cu")
		(net "M_C_CPU0_SB_PAR")
	)
	(arc
		(start 338.579714 -264.848594)
		(mid 338.396206 -264.8031)
		(end 338.213954 -264.85342)
		(width 0.0889)
		(layer "In2.Cu")
		(net "M_C_CPU0_SB_PAR")
	)
	(arc
		(start 341.034116 -264.85342)
		(mid 340.75116 -264.929597)
		(end 340.468204 -264.85342)
		(width 0.0889)
		(layer "In2.Cu")
		(net "M_C_CPU0_SB_PAR")
	)
	(arc
		(start 333.513938 -264.85342)
		(mid 333.230982 -264.929597)
		(end 332.948026 -264.85342)
		(width 0.0889)
		(layer "In2.Cu")
		(net "M_C_CPU0_SB_PAR")
	)
	(arc
		(start 327.851516 -264.867644)
		(mid 327.579579 -264.92947)
		(end 327.311258 -264.85342)
		(width 0.0889)
		(layer "In2.Cu")
		(net "M_C_CPU0_SB_PAR")
	)
	(arc
		(start 326.935846 -264.85342)
		(mid 326.674688 -264.929999)
		(end 326.408034 -264.875518)
		(width 0.0889)
		(layer "In2.Cu")
		(net "M_C_CPU0_SB_PAR")
	)
	(arc
		(start 331.05979 -264.848594)
		(mid 330.876282 -264.8031)
		(end 330.69403 -264.85342)
		(width 0.0889)
		(layer "In2.Cu")
		(net "M_C_CPU0_SB_PAR")
	)
	(arc
		(start 337.274154 -264.85342)
		(mid 336.991198 -264.929597)
		(end 336.708242 -264.85342)
		(width 0.0889)
		(layer "In2.Cu")
		(net "M_C_CPU0_SB_PAR")
	)
	(arc
		(start 340.468204 -264.85342)
		(mid 340.285953 -264.80307)
		(end 340.102444 -264.848594)
		(width 0.0889)
		(layer "In2.Cu")
		(net "M_C_CPU0_SB_PAR")
	)
	(arc
		(start 331.634084 -264.85342)
		(mid 331.351128 -264.929597)
		(end 331.068172 -264.85342)
		(width 0.0889)
		(layer "In2.Cu")
		(net "M_C_CPU0_SB_PAR")
	)
	(arc
		(start 336.3341 -264.85342)
		(mid 336.051144 -264.929597)
		(end 335.768188 -264.85342)
		(width 0.0889)
		(layer "In2.Cu")
		(net "M_C_CPU0_SB_PAR")
	)
	(arc
		(start 341.97417 -264.85342)
		(mid 341.691214 -264.929597)
		(end 341.408258 -264.85342)
		(width 0.0889)
		(layer "In2.Cu")
		(net "M_C_CPU0_SB_PAR")
	)
	(arc
		(start 341.408258 -264.85342)
		(mid 341.226007 -264.80307)
		(end 341.042498 -264.848594)
		(width 0.0889)
		(layer "In2.Cu")
		(net "M_C_CPU0_SB_PAR")
	)
	(arc
		(start 335.394046 -264.85342)
		(mid 335.11109 -264.929597)
		(end 334.828134 -264.85342)
		(width 0.0889)
		(layer "In2.Cu")
		(net "M_C_CPU0_SB_PAR")
	)
	(arc
		(start 339.154008 -264.85342)
		(mid 338.871052 -264.929597)
		(end 338.588096 -264.85342)
		(width 0.0889)
		(layer "In2.Cu")
		(net "M_C_CPU0_SB_PAR")
	)
	(arc
		(start 337.648042 -264.85342)
		(mid 337.461098 -264.803165)
		(end 337.274154 -264.85342)
		(width 0.0889)
		(layer "In2.Cu")
		(net "M_C_CPU0_SB_PAR")
	)
	(arc
		(start 333.879698 -264.848594)
		(mid 333.69619 -264.8031)
		(end 333.513938 -264.85342)
		(width 0.0889)
		(layer "In2.Cu")
		(net "M_C_CPU0_SB_PAR")
	)
	(arc
		(start 328.814176 -264.85342)
		(mid 328.53122 -264.929597)
		(end 328.248264 -264.85342)
		(width 0.0889)
		(layer "In2.Cu")
		(net "M_C_CPU0_SB_PAR")
	)
	(arc
		(start 327.290684 -264.841482)
		(mid 327.111756 -264.802605)
		(end 326.935846 -264.85342)
		(width 0.0889)
		(layer "In2.Cu")
		(net "M_C_CPU0_SB_PAR")
	)
	(arc
		(start 339.519768 -264.848594)
		(mid 339.33626 -264.8031)
		(end 339.154008 -264.85342)
		(width 0.0889)
		(layer "In2.Cu")
		(net "M_C_CPU0_SB_PAR")
	)
	(arc
		(start 340.094062 -264.85342)
		(mid 339.811106 -264.929597)
		(end 339.52815 -264.85342)
		(width 0.0889)
		(layer "In2.Cu")
		(net "M_C_CPU0_SB_PAR")
	)
	(arc
		(start 332.574138 -264.85342)
		(mid 332.291182 -264.929597)
		(end 332.008226 -264.85342)
		(width 0.0889)
		(layer "In2.Cu")
		(net "M_C_CPU0_SB_PAR")
	)
	(arc
		(start 334.453992 -264.85342)
		(mid 334.171036 -264.929597)
		(end 333.88808 -264.85342)
		(width 0.0889)
		(layer "In2.Cu")
		(net "M_C_CPU0_SB_PAR")
	)
	(arc
		(start 335.768188 -264.85342)
		(mid 335.585937 -264.80307)
		(end 335.402428 -264.848594)
		(width 0.0889)
		(layer "In2.Cu")
		(net "M_C_CPU0_SB_PAR")
	)
	(arc
		(start 342.292686 -264.827258)
		(mid 342.130497 -264.804523)
		(end 341.97417 -264.85342)
		(width 0.0889)
		(layer "In2.Cu")
		(net "M_C_CPU0_SB_PAR")
	)
	(arc
		(start 330.119736 -264.848594)
		(mid 329.936228 -264.8031)
		(end 329.753976 -264.85342)
		(width 0.0889)
		(layer "In2.Cu")
		(net "M_C_CPU0_SB_PAR")
	)
	(arc
		(start 338.213954 -264.85342)
		(mid 337.930998 -264.929597)
		(end 337.648042 -264.85342)
		(width 0.0889)
		(layer "In2.Cu")
		(net "M_C_CPU0_SB_PAR")
	)
	(arc
		(start 334.819752 -264.848594)
		(mid 334.636244 -264.8031)
		(end 334.453992 -264.85342)
		(width 0.0889)
		(layer "In2.Cu")
		(net "M_C_CPU0_SB_PAR")
	)
	(arc
		(start 326.320658 -264.825226)
		(mid 326.28251 -264.799661)
		(end 326.248014 -264.769346)
		(width 0.0889)
		(layer "In2.Cu")
		(net "M_C_CPU0_SB_PAR")
	)
	(arc
		(start 336.708242 -264.85342)
		(mid 336.525991 -264.80307)
		(end 336.342482 -264.848594)
		(width 0.0889)
		(layer "In2.Cu")
		(net "M_C_CPU0_SB_PAR")
	)
	(arc
		(start 329.753976 -264.85342)
		(mid 329.47102 -264.929597)
		(end 329.188064 -264.85342)
		(width 0.0889)
		(layer "In2.Cu")
		(net "M_C_CPU0_SB_PAR")
	)
	(arc
		(start 330.69403 -264.85342)
		(mid 330.411074 -264.929597)
		(end 330.128118 -264.85342)
		(width 0.0889)
		(layer "In2.Cu")
		(net "M_C_CPU0_SB_PAR")
	)
	(arc
		(start 329.188064 -264.85342)
		(mid 329.00112 -264.803165)
		(end 328.814176 -264.85342)
		(width 0.0889)
		(layer "In2.Cu")
		(net "M_C_CPU0_SB_PAR")
	)
	(arc
		(start 332.008226 -264.85342)
		(mid 331.825975 -264.80307)
		(end 331.642466 -264.848594)
		(width 0.0889)
		(layer "In2.Cu")
		(net "M_C_CPU0_SB_PAR")
	)
	(arc
		(start 332.948026 -264.85342)
		(mid 332.761082 -264.803165)
		(end 332.574138 -264.85342)
		(width 0.0889)
		(layer "In2.Cu")
		(net "M_C_CPU0_SB_PAR")
	)
	(segment
		(start 343.097866 -270.580104)
		(end 342.631014 -270.846042)
		(width 0.12954)
		(layer "F.Cu")
		(net "M_C_CPU0_SB_DQS_DP<9>")
	)
	(segment
		(start 309.62346 -273.570446)
		(end 309.732172 -273.679158)
		(width 0.16002)
		(layer "In2.Cu")
		(net "M_C_CPU0_SB_DQS_DP<9>")
	)
	(segment
		(start 310.63311 -272.77822)
		(end 310.524398 -272.669508)
		(width 0.16002)
		(layer "In2.Cu")
		(net "M_C_CPU0_SB_DQS_DP<9>")
	)
	(segment
		(start 327.805288 -271.157192)
		(end 327.781412 -271.170908)
		(width 0.09525)
		(layer "In2.Cu")
		(net "M_C_CPU0_SB_DQS_DP<9>")
	)
	(segment
		(start 326.385428 -271.111726)
		(end 325.470012 -270.19631)
		(width 0.09525)
		(layer "In2.Cu")
		(net "M_C_CPU0_SB_DQS_DP<9>")
	)
	(segment
		(start 324.344538 -269.592552)
		(end 323.978778 -269.592552)
		(width 0.09525)
		(layer "In2.Cu")
		(net "M_C_CPU0_SB_DQS_DP<9>")
	)
	(segment
		(start 314.15482 -269.53337)
		(end 313.657234 -270.030956)
		(width 0.16002)
		(layer "In2.Cu")
		(net "M_C_CPU0_SB_DQS_DP<9>")
	)
	(segment
		(start 304.520854 -276.048724)
		(end 303.855882 -275.383752)
		(width 0.16002)
		(layer "In2.Cu")
		(net "M_C_CPU0_SB_DQS_DP<9>")
	)
	(segment
		(start 323.978778 -269.592552)
		(end 323.919596 -269.53337)
		(width 0.09525)
		(layer "In2.Cu")
		(net "M_C_CPU0_SB_DQS_DP<9>")
	)
	(segment
		(start 305.601116 -275.19503)
		(end 304.747422 -276.048724)
		(width 0.16002)
		(layer "In2.Cu")
		(net "M_C_CPU0_SB_DQS_DP<9>")
	)
	(segment
		(start 298.237656 -275.12137)
		(end 297.383708 -275.975318)
		(width 0.16002)
		(layer "In2.Cu")
		(net "M_C_CPU0_SB_DQS_DP<9>")
	)
	(segment
		(start 310.863742 -271.53616)
		(end 310.863742 -272.063464)
		(width 0.16002)
		(layer "In2.Cu")
		(net "M_C_CPU0_SB_DQS_DP<9>")
	)
	(segment
		(start 312.479436 -270.931894)
		(end 312.479436 -271.208754)
		(width 0.16002)
		(layer "In2.Cu")
		(net "M_C_CPU0_SB_DQS_DP<9>")
	)
	(segment
		(start 323.919596 -269.53337)
		(end 323.895974 -269.53337)
		(width 0.09525)
		(layer "In2.Cu")
		(net "M_C_CPU0_SB_DQS_DP<9>")
	)
	(segment
		(start 297.383708 -275.975318)
		(end 296.934128 -275.975318)
		(width 0.16002)
		(layer "In2.Cu")
		(net "M_C_CPU0_SB_DQS_DP<9>")
	)
	(segment
		(start 340.939628 -271.171162)
		(end 340.931246 -271.175988)
		(width 0.09525)
		(layer "In2.Cu")
		(net "M_C_CPU0_SB_DQS_DP<9>")
	)
	(segment
		(start 293.833296 -274.819872)
		(end 293.420038 -275.23313)
		(width 0.16002)
		(layer "In2.Cu")
		(net "M_C_CPU0_SB_DQS_DP<9>")
	)
	(segment
		(start 311.76468 -271.162526)
		(end 311.237376 -271.162526)
		(width 0.16002)
		(layer "In2.Cu")
		(net "M_C_CPU0_SB_DQS_DP<9>")
	)
	(segment
		(start 306.738274 -274.535392)
		(end 306.078636 -275.19503)
		(width 0.16002)
		(layer "In2.Cu")
		(net "M_C_CPU0_SB_DQS_DP<9>")
	)
	(segment
		(start 328.719688 -271.171162)
		(end 328.711306 -271.175988)
		(width 0.09525)
		(layer "In2.Cu")
		(net "M_C_CPU0_SB_DQS_DP<9>")
	)
	(segment
		(start 311.237376 -271.162526)
		(end 310.863742 -271.53616)
		(width 0.16002)
		(layer "In2.Cu")
		(net "M_C_CPU0_SB_DQS_DP<9>")
	)
	(segment
		(start 313.138312 -269.788894)
		(end 312.611008 -269.788894)
		(width 0.16002)
		(layer "In2.Cu")
		(net "M_C_CPU0_SB_DQS_DP<9>")
	)
	(segment
		(start 295.044114 -275.384006)
		(end 294.47998 -274.819872)
		(width 0.16002)
		(layer "In2.Cu")
		(net "M_C_CPU0_SB_DQS_DP<9>")
	)
	(segment
		(start 309.732172 -273.956018)
		(end 309.152798 -274.535392)
		(width 0.16002)
		(layer "In2.Cu")
		(net "M_C_CPU0_SB_DQS_DP<9>")
	)
	(segment
		(start 301.802546 -274.089368)
		(end 301.173642 -274.089368)
		(width 0.16002)
		(layer "In2.Cu")
		(net "M_C_CPU0_SB_DQS_DP<9>")
	)
	(segment
		(start 323.895974 -269.53337)
		(end 314.15482 -269.53337)
		(width 0.16002)
		(layer "In2.Cu")
		(net "M_C_CPU0_SB_DQS_DP<9>")
	)
	(segment
		(start 312.479436 -271.208754)
		(end 312.283602 -271.404588)
		(width 0.16002)
		(layer "In2.Cu")
		(net "M_C_CPU0_SB_DQS_DP<9>")
	)
	(segment
		(start 309.997094 -272.669508)
		(end 309.62346 -273.043142)
		(width 0.16002)
		(layer "In2.Cu")
		(net "M_C_CPU0_SB_DQS_DP<9>")
	)
	(segment
		(start 296.342816 -275.384006)
		(end 295.044114 -275.384006)
		(width 0.16002)
		(layer "In2.Cu")
		(net "M_C_CPU0_SB_DQS_DP<9>")
	)
	(segment
		(start 293.260018 -275.808948)
		(end 292.553898 -275.808948)
		(width 0.16002)
		(layer "In2.Cu")
		(net "M_C_CPU0_SB_DQS_DP<9>")
	)
	(segment
		(start 313.380374 -270.030956)
		(end 313.138312 -269.788894)
		(width 0.16002)
		(layer "In2.Cu")
		(net "M_C_CPU0_SB_DQS_DP<9>")
	)
	(segment
		(start 329.290934 -271.175988)
		(end 329.282552 -271.171162)
		(width 0.09525)
		(layer "In2.Cu")
		(net "M_C_CPU0_SB_DQS_DP<9>")
	)
	(segment
		(start 336.239612 -271.171162)
		(end 336.23123 -271.175988)
		(width 0.09525)
		(layer "In2.Cu")
		(net "M_C_CPU0_SB_DQS_DP<9>")
	)
	(segment
		(start 327.781412 -271.170908)
		(end 327.759568 -271.183354)
		(width 0.09525)
		(layer "In2.Cu")
		(net "M_C_CPU0_SB_DQS_DP<9>")
	)
	(segment
		(start 309.152798 -274.535392)
		(end 306.738274 -274.535392)
		(width 0.16002)
		(layer "In2.Cu")
		(net "M_C_CPU0_SB_DQS_DP<9>")
	)
	(segment
		(start 333.050896 -271.175988)
		(end 333.042514 -271.171162)
		(width 0.09525)
		(layer "In2.Cu")
		(net "M_C_CPU0_SB_DQS_DP<9>")
	)
	(segment
		(start 324.948296 -270.19631)
		(end 324.344538 -269.592552)
		(width 0.09525)
		(layer "In2.Cu")
		(net "M_C_CPU0_SB_DQS_DP<9>")
	)
	(segment
		(start 331.539596 -271.171162)
		(end 331.531214 -271.175988)
		(width 0.09525)
		(layer "In2.Cu")
		(net "M_C_CPU0_SB_DQS_DP<9>")
	)
	(segment
		(start 342.631014 -270.846042)
		(end 342.47709 -271.111472)
		(width 0.09525)
		(layer "In2.Cu")
		(net "M_C_CPU0_SB_DQS_DP<9>")
	)
	(segment
		(start 312.283602 -271.404588)
		(end 312.006742 -271.404588)
		(width 0.16002)
		(layer "In2.Cu")
		(net "M_C_CPU0_SB_DQS_DP<9>")
	)
	(segment
		(start 312.237374 -270.162528)
		(end 312.237374 -270.689832)
		(width 0.16002)
		(layer "In2.Cu")
		(net "M_C_CPU0_SB_DQS_DP<9>")
	)
	(segment
		(start 333.99095 -271.175988)
		(end 333.982568 -271.171162)
		(width 0.09525)
		(layer "In2.Cu")
		(net "M_C_CPU0_SB_DQS_DP<9>")
	)
	(segment
		(start 332.47965 -271.171162)
		(end 332.471268 -271.175988)
		(width 0.09525)
		(layer "In2.Cu")
		(net "M_C_CPU0_SB_DQS_DP<9>")
	)
	(segment
		(start 296.934128 -275.975318)
		(end 296.342816 -275.384006)
		(width 0.16002)
		(layer "In2.Cu")
		(net "M_C_CPU0_SB_DQS_DP<9>")
	)
	(segment
		(start 309.732172 -273.679158)
		(end 309.732172 -273.956018)
		(width 0.16002)
		(layer "In2.Cu")
		(net "M_C_CPU0_SB_DQS_DP<9>")
	)
	(segment
		(start 311.105804 -272.305526)
		(end 311.105804 -272.582386)
		(width 0.16002)
		(layer "In2.Cu")
		(net "M_C_CPU0_SB_DQS_DP<9>")
	)
	(segment
		(start 310.524398 -272.669508)
		(end 309.997094 -272.669508)
		(width 0.16002)
		(layer "In2.Cu")
		(net "M_C_CPU0_SB_DQS_DP<9>")
	)
	(segment
		(start 292.553898 -275.808948)
		(end 292.280086 -275.535136)
		(width 0.16002)
		(layer "In2.Cu")
		(net "M_C_CPU0_SB_DQS_DP<9>")
	)
	(segment
		(start 310.90997 -272.77822)
		(end 310.63311 -272.77822)
		(width 0.16002)
		(layer "In2.Cu")
		(net "M_C_CPU0_SB_DQS_DP<9>")
	)
	(segment
		(start 293.420038 -275.648928)
		(end 293.260018 -275.808948)
		(width 0.16002)
		(layer "In2.Cu")
		(net "M_C_CPU0_SB_DQS_DP<9>")
	)
	(segment
		(start 310.863742 -272.063464)
		(end 311.105804 -272.305526)
		(width 0.16002)
		(layer "In2.Cu")
		(net "M_C_CPU0_SB_DQS_DP<9>")
	)
	(segment
		(start 306.078636 -275.19503)
		(end 305.601116 -275.19503)
		(width 0.16002)
		(layer "In2.Cu")
		(net "M_C_CPU0_SB_DQS_DP<9>")
	)
	(segment
		(start 302.299878 -275.383752)
		(end 302.139858 -275.223732)
		(width 0.16002)
		(layer "In2.Cu")
		(net "M_C_CPU0_SB_DQS_DP<9>")
	)
	(segment
		(start 312.611008 -269.788894)
		(end 312.237374 -270.162528)
		(width 0.16002)
		(layer "In2.Cu")
		(net "M_C_CPU0_SB_DQS_DP<9>")
	)
	(segment
		(start 294.47998 -274.819872)
		(end 293.833296 -274.819872)
		(width 0.16002)
		(layer "In2.Cu")
		(net "M_C_CPU0_SB_DQS_DP<9>")
	)
	(segment
		(start 298.601892 -275.12137)
		(end 298.237656 -275.12137)
		(width 0.16002)
		(layer "In2.Cu")
		(net "M_C_CPU0_SB_DQS_DP<9>")
	)
	(segment
		(start 337.750912 -271.175988)
		(end 337.74253 -271.171162)
		(width 0.09525)
		(layer "In2.Cu")
		(net "M_C_CPU0_SB_DQS_DP<9>")
	)
	(segment
		(start 313.657234 -270.030956)
		(end 313.380374 -270.030956)
		(width 0.16002)
		(layer "In2.Cu")
		(net "M_C_CPU0_SB_DQS_DP<9>")
	)
	(segment
		(start 300.735238 -274.527772)
		(end 299.19549 -274.527772)
		(width 0.16002)
		(layer "In2.Cu")
		(net "M_C_CPU0_SB_DQS_DP<9>")
	)
	(segment
		(start 301.173642 -274.089368)
		(end 300.735238 -274.527772)
		(width 0.16002)
		(layer "In2.Cu")
		(net "M_C_CPU0_SB_DQS_DP<9>")
	)
	(segment
		(start 342.47709 -271.111472)
		(end 342.376252 -271.138142)
		(width 0.09525)
		(layer "In2.Cu")
		(net "M_C_CPU0_SB_DQS_DP<9>")
	)
	(segment
		(start 326.495918 -271.18945)
		(end 326.463914 -271.170908)
		(width 0.09525)
		(layer "In2.Cu")
		(net "M_C_CPU0_SB_DQS_DP<9>")
	)
	(segment
		(start 312.006742 -271.404588)
		(end 311.76468 -271.162526)
		(width 0.16002)
		(layer "In2.Cu")
		(net "M_C_CPU0_SB_DQS_DP<9>")
	)
	(segment
		(start 312.237374 -270.689832)
		(end 312.479436 -270.931894)
		(width 0.16002)
		(layer "In2.Cu")
		(net "M_C_CPU0_SB_DQS_DP<9>")
	)
	(segment
		(start 309.62346 -273.043142)
		(end 309.62346 -273.570446)
		(width 0.16002)
		(layer "In2.Cu")
		(net "M_C_CPU0_SB_DQS_DP<9>")
	)
	(segment
		(start 311.105804 -272.582386)
		(end 310.90997 -272.77822)
		(width 0.16002)
		(layer "In2.Cu")
		(net "M_C_CPU0_SB_DQS_DP<9>")
	)
	(segment
		(start 304.747422 -276.048724)
		(end 304.520854 -276.048724)
		(width 0.16002)
		(layer "In2.Cu")
		(net "M_C_CPU0_SB_DQS_DP<9>")
	)
	(segment
		(start 293.420038 -275.23313)
		(end 293.420038 -275.648928)
		(width 0.16002)
		(layer "In2.Cu")
		(net "M_C_CPU0_SB_DQS_DP<9>")
	)
	(segment
		(start 341.879682 -271.171162)
		(end 341.8713 -271.175988)
		(width 0.09525)
		(layer "In2.Cu")
		(net "M_C_CPU0_SB_DQS_DP<9>")
	)
	(segment
		(start 325.470012 -270.19631)
		(end 324.948296 -270.19631)
		(width 0.09525)
		(layer "In2.Cu")
		(net "M_C_CPU0_SB_DQS_DP<9>")
	)
	(segment
		(start 302.139858 -275.223732)
		(end 302.139858 -274.42668)
		(width 0.16002)
		(layer "In2.Cu")
		(net "M_C_CPU0_SB_DQS_DP<9>")
	)
	(segment
		(start 303.855882 -275.383752)
		(end 302.299878 -275.383752)
		(width 0.16002)
		(layer "In2.Cu")
		(net "M_C_CPU0_SB_DQS_DP<9>")
	)
	(segment
		(start 327.405746 -271.171162)
		(end 327.38187 -271.157192)
		(width 0.09525)
		(layer "In2.Cu")
		(net "M_C_CPU0_SB_DQS_DP<9>")
	)
	(segment
		(start 338.690966 -271.175988)
		(end 338.682584 -271.171162)
		(width 0.09525)
		(layer "In2.Cu")
		(net "M_C_CPU0_SB_DQS_DP<9>")
	)
	(segment
		(start 302.139858 -274.42668)
		(end 301.802546 -274.089368)
		(width 0.16002)
		(layer "In2.Cu")
		(net "M_C_CPU0_SB_DQS_DP<9>")
	)
	(segment
		(start 337.179666 -271.171162)
		(end 337.171284 -271.175988)
		(width 0.09525)
		(layer "In2.Cu")
		(net "M_C_CPU0_SB_DQS_DP<9>")
	)
	(segment
		(start 299.19549 -274.527772)
		(end 298.601892 -275.12137)
		(width 0.16002)
		(layer "In2.Cu")
		(net "M_C_CPU0_SB_DQS_DP<9>")
	)
	(arc
		(start 335.299558 -271.171162)
		(mid 335.11109 -271.221839)
		(end 334.922622 -271.171162)
		(width 0.09525)
		(layer "In2.Cu")
		(net "M_C_CPU0_SB_DQS_DP<9>")
	)
	(arc
		(start 340.562438 -271.171162)
		(mid 340.281006 -271.095407)
		(end 339.999574 -271.171162)
		(width 0.09525)
		(layer "In2.Cu")
		(net "M_C_CPU0_SB_DQS_DP<9>")
	)
	(arc
		(start 336.802476 -271.171162)
		(mid 336.521044 -271.095407)
		(end 336.239612 -271.171162)
		(width 0.09525)
		(layer "In2.Cu")
		(net "M_C_CPU0_SB_DQS_DP<9>")
	)
	(arc
		(start 334.359758 -271.171162)
		(mid 334.175983 -271.221934)
		(end 333.99095 -271.175988)
		(width 0.09525)
		(layer "In2.Cu")
		(net "M_C_CPU0_SB_DQS_DP<9>")
	)
	(arc
		(start 329.282552 -271.171162)
		(mid 329.00112 -271.095407)
		(end 328.719688 -271.171162)
		(width 0.09525)
		(layer "In2.Cu")
		(net "M_C_CPU0_SB_DQS_DP<9>")
	)
	(arc
		(start 333.042514 -271.171162)
		(mid 332.761082 -271.095407)
		(end 332.47965 -271.171162)
		(width 0.09525)
		(layer "In2.Cu")
		(net "M_C_CPU0_SB_DQS_DP<9>")
	)
	(arc
		(start 332.471268 -271.175988)
		(mid 332.286236 -271.221902)
		(end 332.10246 -271.171162)
		(width 0.09525)
		(layer "In2.Cu")
		(net "M_C_CPU0_SB_DQS_DP<9>")
	)
	(arc
		(start 337.171284 -271.175988)
		(mid 336.986252 -271.221902)
		(end 336.802476 -271.171162)
		(width 0.09525)
		(layer "In2.Cu")
		(net "M_C_CPU0_SB_DQS_DP<9>")
	)
	(arc
		(start 326.841104 -271.171416)
		(mid 326.670707 -271.222315)
		(end 326.495918 -271.18945)
		(width 0.09525)
		(layer "In2.Cu")
		(net "M_C_CPU0_SB_DQS_DP<9>")
	)
	(arc
		(start 337.74253 -271.171162)
		(mid 337.461098 -271.095407)
		(end 337.179666 -271.171162)
		(width 0.09525)
		(layer "In2.Cu")
		(net "M_C_CPU0_SB_DQS_DP<9>")
	)
	(arc
		(start 335.862422 -271.171162)
		(mid 335.58099 -271.095407)
		(end 335.299558 -271.171162)
		(width 0.09525)
		(layer "In2.Cu")
		(net "M_C_CPU0_SB_DQS_DP<9>")
	)
	(arc
		(start 338.682584 -271.171162)
		(mid 338.401152 -271.095407)
		(end 338.11972 -271.171162)
		(width 0.09525)
		(layer "In2.Cu")
		(net "M_C_CPU0_SB_DQS_DP<9>")
	)
	(arc
		(start 333.982568 -271.171162)
		(mid 333.701136 -271.095407)
		(end 333.419704 -271.171162)
		(width 0.09525)
		(layer "In2.Cu")
		(net "M_C_CPU0_SB_DQS_DP<9>")
	)
	(arc
		(start 330.222606 -271.171162)
		(mid 329.941174 -271.095407)
		(end 329.659742 -271.171162)
		(width 0.09525)
		(layer "In2.Cu")
		(net "M_C_CPU0_SB_DQS_DP<9>")
	)
	(arc
		(start 326.463914 -271.170908)
		(mid 326.422718 -271.143905)
		(end 326.385428 -271.111726)
		(width 0.09525)
		(layer "In2.Cu")
		(net "M_C_CPU0_SB_DQS_DP<9>")
	)
	(arc
		(start 339.059774 -271.171162)
		(mid 338.875999 -271.221934)
		(end 338.690966 -271.175988)
		(width 0.09525)
		(layer "In2.Cu")
		(net "M_C_CPU0_SB_DQS_DP<9>")
	)
	(arc
		(start 341.502492 -271.171162)
		(mid 341.22106 -271.095407)
		(end 340.939628 -271.171162)
		(width 0.09525)
		(layer "In2.Cu")
		(net "M_C_CPU0_SB_DQS_DP<9>")
	)
	(arc
		(start 332.10246 -271.171162)
		(mid 331.821028 -271.095407)
		(end 331.539596 -271.171162)
		(width 0.09525)
		(layer "In2.Cu")
		(net "M_C_CPU0_SB_DQS_DP<9>")
	)
	(arc
		(start 333.419704 -271.171162)
		(mid 333.235929 -271.221934)
		(end 333.050896 -271.175988)
		(width 0.09525)
		(layer "In2.Cu")
		(net "M_C_CPU0_SB_DQS_DP<9>")
	)
	(arc
		(start 330.599542 -271.171162)
		(mid 330.411074 -271.221839)
		(end 330.222606 -271.171162)
		(width 0.09525)
		(layer "In2.Cu")
		(net "M_C_CPU0_SB_DQS_DP<9>")
	)
	(arc
		(start 327.759568 -271.183354)
		(mid 327.581116 -271.221596)
		(end 327.405746 -271.171162)
		(width 0.09525)
		(layer "In2.Cu")
		(net "M_C_CPU0_SB_DQS_DP<9>")
	)
	(arc
		(start 329.659742 -271.171162)
		(mid 329.475967 -271.221934)
		(end 329.290934 -271.175988)
		(width 0.09525)
		(layer "In2.Cu")
		(net "M_C_CPU0_SB_DQS_DP<9>")
	)
	(arc
		(start 334.922622 -271.171162)
		(mid 334.64119 -271.095407)
		(end 334.359758 -271.171162)
		(width 0.09525)
		(layer "In2.Cu")
		(net "M_C_CPU0_SB_DQS_DP<9>")
	)
	(arc
		(start 341.8713 -271.175988)
		(mid 341.686268 -271.221902)
		(end 341.502492 -271.171162)
		(width 0.09525)
		(layer "In2.Cu")
		(net "M_C_CPU0_SB_DQS_DP<9>")
	)
	(arc
		(start 336.23123 -271.175988)
		(mid 336.046198 -271.221902)
		(end 335.862422 -271.171162)
		(width 0.09525)
		(layer "In2.Cu")
		(net "M_C_CPU0_SB_DQS_DP<9>")
	)
	(arc
		(start 331.531214 -271.175988)
		(mid 331.346182 -271.221902)
		(end 331.162406 -271.171162)
		(width 0.09525)
		(layer "In2.Cu")
		(net "M_C_CPU0_SB_DQS_DP<9>")
	)
	(arc
		(start 327.38187 -271.157192)
		(mid 327.109646 -271.09482)
		(end 326.841104 -271.171416)
		(width 0.09525)
		(layer "In2.Cu")
		(net "M_C_CPU0_SB_DQS_DP<9>")
	)
	(arc
		(start 342.376252 -271.138142)
		(mid 342.124111 -271.096572)
		(end 341.879682 -271.171162)
		(width 0.09525)
		(layer "In2.Cu")
		(net "M_C_CPU0_SB_DQS_DP<9>")
	)
	(arc
		(start 339.622638 -271.171162)
		(mid 339.341206 -271.095407)
		(end 339.059774 -271.171162)
		(width 0.09525)
		(layer "In2.Cu")
		(net "M_C_CPU0_SB_DQS_DP<9>")
	)
	(arc
		(start 331.162406 -271.171162)
		(mid 330.880974 -271.095407)
		(end 330.599542 -271.171162)
		(width 0.09525)
		(layer "In2.Cu")
		(net "M_C_CPU0_SB_DQS_DP<9>")
	)
	(arc
		(start 340.931246 -271.175988)
		(mid 340.746214 -271.221902)
		(end 340.562438 -271.171162)
		(width 0.09525)
		(layer "In2.Cu")
		(net "M_C_CPU0_SB_DQS_DP<9>")
	)
	(arc
		(start 338.11972 -271.171162)
		(mid 337.935945 -271.221934)
		(end 337.750912 -271.175988)
		(width 0.09525)
		(layer "In2.Cu")
		(net "M_C_CPU0_SB_DQS_DP<9>")
	)
	(arc
		(start 339.999574 -271.171162)
		(mid 339.811106 -271.221839)
		(end 339.622638 -271.171162)
		(width 0.09525)
		(layer "In2.Cu")
		(net "M_C_CPU0_SB_DQS_DP<9>")
	)
	(arc
		(start 328.342498 -271.171162)
		(mid 328.075672 -271.095597)
		(end 327.805288 -271.157192)
		(width 0.09525)
		(layer "In2.Cu")
		(net "M_C_CPU0_SB_DQS_DP<9>")
	)
	(arc
		(start 328.711306 -271.175988)
		(mid 328.526274 -271.221902)
		(end 328.342498 -271.171162)
		(width 0.09525)
		(layer "In2.Cu")
		(net "M_C_CPU0_SB_DQS_DP<9>")
	)
	(segment
		(start 344.03792 -291.640006)
		(end 343.571068 -291.905944)
		(width 0.12954)
		(layer "F.Cu")
		(net "M_C_CPU0_SB_DQS_DP<8>")
	)
	(segment
		(start 325.506842 -295.809162)
		(end 325.506842 -300.66361)
		(width 0.16002)
		(layer "In2.Cu")
		(net "M_C_CPU0_SB_DQS_DP<8>")
	)
	(segment
		(start 304.166778 -315.333126)
		(end 302.137318 -315.333126)
		(width 0.16002)
		(layer "In2.Cu")
		(net "M_C_CPU0_SB_DQS_DP<8>")
	)
	(segment
		(start 333.99095 -291.575998)
		(end 333.982568 -291.580824)
		(width 0.09525)
		(layer "In2.Cu")
		(net "M_C_CPU0_SB_DQS_DP<8>")
	)
	(segment
		(start 298.271438 -314.182506)
		(end 297.417998 -315.035946)
		(width 0.16002)
		(layer "In2.Cu")
		(net "M_C_CPU0_SB_DQS_DP<8>")
	)
	(segment
		(start 343.724992 -291.640514)
		(end 343.701624 -291.553646)
		(width 0.09525)
		(layer "In2.Cu")
		(net "M_C_CPU0_SB_DQS_DP<8>")
	)
	(segment
		(start 326.47509 -293.193216)
		(end 326.47509 -293.193724)
		(width 0.09525)
		(layer "In2.Cu")
		(net "M_C_CPU0_SB_DQS_DP<8>")
	)
	(segment
		(start 313.82716 -311.045352)
		(end 310.402986 -314.469526)
		(width 0.16002)
		(layer "In2.Cu")
		(net "M_C_CPU0_SB_DQS_DP<8>")
	)
	(segment
		(start 293.989252 -314.7695)
		(end 291.65423 -314.7695)
		(width 0.16002)
		(layer "In2.Cu")
		(net "M_C_CPU0_SB_DQS_DP<8>")
	)
	(segment
		(start 315.1251 -311.045352)
		(end 313.82716 -311.045352)
		(width 0.16002)
		(layer "In2.Cu")
		(net "M_C_CPU0_SB_DQS_DP<8>")
	)
	(segment
		(start 325.447914 -294.5511)
		(end 325.447914 -295.726612)
		(width 0.09525)
		(layer "In2.Cu")
		(net "M_C_CPU0_SB_DQS_DP<8>")
	)
	(segment
		(start 328.719688 -291.580824)
		(end 328.711306 -291.575998)
		(width 0.09525)
		(layer "In2.Cu")
		(net "M_C_CPU0_SB_DQS_DP<8>")
	)
	(segment
		(start 327.74763 -291.656516)
		(end 327.409048 -291.995098)
		(width 0.09525)
		(layer "In2.Cu")
		(net "M_C_CPU0_SB_DQS_DP<8>")
	)
	(segment
		(start 291.65423 -314.7695)
		(end 291.046916 -314.162186)
		(width 0.16002)
		(layer "In2.Cu")
		(net "M_C_CPU0_SB_DQS_DP<8>")
	)
	(segment
		(start 331.539596 -291.580824)
		(end 331.531214 -291.575998)
		(width 0.09525)
		(layer "In2.Cu")
		(net "M_C_CPU0_SB_DQS_DP<8>")
	)
	(segment
		(start 337.750912 -291.575998)
		(end 337.74253 -291.580824)
		(width 0.09525)
		(layer "In2.Cu")
		(net "M_C_CPU0_SB_DQS_DP<8>")
	)
	(segment
		(start 325.447914 -295.726612)
		(end 325.506842 -295.78554)
		(width 0.09525)
		(layer "In2.Cu")
		(net "M_C_CPU0_SB_DQS_DP<8>")
	)
	(segment
		(start 327.096374 -292.261798)
		(end 326.90689 -292.453314)
		(width 0.09525)
		(layer "In2.Cu")
		(net "M_C_CPU0_SB_DQS_DP<8>")
	)
	(segment
		(start 326.47509 -293.193724)
		(end 326.462644 -293.200836)
		(width 0.09525)
		(layer "In2.Cu")
		(net "M_C_CPU0_SB_DQS_DP<8>")
	)
	(segment
		(start 304.486818 -315.013086)
		(end 304.166778 -315.333126)
		(width 0.16002)
		(layer "In2.Cu")
		(net "M_C_CPU0_SB_DQS_DP<8>")
	)
	(segment
		(start 288.45383 -314.361322)
		(end 288.180018 -314.635134)
		(width 0.16002)
		(layer "In2.Cu")
		(net "M_C_CPU0_SB_DQS_DP<8>")
	)
	(segment
		(start 296.927778 -315.035946)
		(end 296.60342 -315.360304)
		(width 0.16002)
		(layer "In2.Cu")
		(net "M_C_CPU0_SB_DQS_DP<8>")
	)
	(segment
		(start 338.690966 -291.575998)
		(end 338.682584 -291.580824)
		(width 0.09525)
		(layer "In2.Cu")
		(net "M_C_CPU0_SB_DQS_DP<8>")
	)
	(segment
		(start 326.273414 -293.7256)
		(end 325.447914 -294.5511)
		(width 0.09525)
		(layer "In2.Cu")
		(net "M_C_CPU0_SB_DQS_DP<8>")
	)
	(segment
		(start 301.327058 -314.522866)
		(end 298.975018 -314.522866)
		(width 0.16002)
		(layer "In2.Cu")
		(net "M_C_CPU0_SB_DQS_DP<8>")
	)
	(segment
		(start 304.987198 -315.013086)
		(end 304.486818 -315.013086)
		(width 0.16002)
		(layer "In2.Cu")
		(net "M_C_CPU0_SB_DQS_DP<8>")
	)
	(segment
		(start 294.580056 -315.360304)
		(end 293.989252 -314.7695)
		(width 0.16002)
		(layer "In2.Cu")
		(net "M_C_CPU0_SB_DQS_DP<8>")
	)
	(segment
		(start 306.193444 -314.210954)
		(end 305.78933 -314.210954)
		(width 0.16002)
		(layer "In2.Cu")
		(net "M_C_CPU0_SB_DQS_DP<8>")
	)
	(segment
		(start 337.179666 -291.580824)
		(end 337.171284 -291.575998)
		(width 0.09525)
		(layer "In2.Cu")
		(net "M_C_CPU0_SB_DQS_DP<8>")
	)
	(segment
		(start 341.879682 -291.580824)
		(end 341.8713 -291.575998)
		(width 0.09525)
		(layer "In2.Cu")
		(net "M_C_CPU0_SB_DQS_DP<8>")
	)
	(segment
		(start 290.171632 -314.162186)
		(end 289.972496 -314.361322)
		(width 0.16002)
		(layer "In2.Cu")
		(net "M_C_CPU0_SB_DQS_DP<8>")
	)
	(segment
		(start 298.634658 -314.182506)
		(end 298.271438 -314.182506)
		(width 0.16002)
		(layer "In2.Cu")
		(net "M_C_CPU0_SB_DQS_DP<8>")
	)
	(segment
		(start 306.452016 -314.469526)
		(end 306.193444 -314.210954)
		(width 0.16002)
		(layer "In2.Cu")
		(net "M_C_CPU0_SB_DQS_DP<8>")
	)
	(segment
		(start 326.273414 -293.525956)
		(end 326.273414 -293.7256)
		(width 0.09525)
		(layer "In2.Cu")
		(net "M_C_CPU0_SB_DQS_DP<8>")
	)
	(segment
		(start 305.78933 -314.210954)
		(end 304.987198 -315.013086)
		(width 0.16002)
		(layer "In2.Cu")
		(net "M_C_CPU0_SB_DQS_DP<8>")
	)
	(segment
		(start 343.390982 -291.575998)
		(end 343.3826 -291.580824)
		(width 0.09525)
		(layer "In2.Cu")
		(net "M_C_CPU0_SB_DQS_DP<8>")
	)
	(segment
		(start 336.239612 -291.580824)
		(end 336.23123 -291.575998)
		(width 0.09525)
		(layer "In2.Cu")
		(net "M_C_CPU0_SB_DQS_DP<8>")
	)
	(segment
		(start 332.47965 -291.580824)
		(end 332.471268 -291.575998)
		(width 0.09525)
		(layer "In2.Cu")
		(net "M_C_CPU0_SB_DQS_DP<8>")
	)
	(segment
		(start 329.290934 -291.575998)
		(end 329.282552 -291.580824)
		(width 0.09525)
		(layer "In2.Cu")
		(net "M_C_CPU0_SB_DQS_DP<8>")
	)
	(segment
		(start 298.975018 -314.522866)
		(end 298.634658 -314.182506)
		(width 0.16002)
		(layer "In2.Cu")
		(net "M_C_CPU0_SB_DQS_DP<8>")
	)
	(segment
		(start 325.506842 -300.66361)
		(end 315.1251 -311.045352)
		(width 0.16002)
		(layer "In2.Cu")
		(net "M_C_CPU0_SB_DQS_DP<8>")
	)
	(segment
		(start 328.06132 -291.656516)
		(end 327.74763 -291.656516)
		(width 0.09525)
		(layer "In2.Cu")
		(net "M_C_CPU0_SB_DQS_DP<8>")
	)
	(segment
		(start 297.417998 -315.035946)
		(end 296.927778 -315.035946)
		(width 0.16002)
		(layer "In2.Cu")
		(net "M_C_CPU0_SB_DQS_DP<8>")
	)
	(segment
		(start 291.046916 -314.162186)
		(end 290.171632 -314.162186)
		(width 0.16002)
		(layer "In2.Cu")
		(net "M_C_CPU0_SB_DQS_DP<8>")
	)
	(segment
		(start 342.450928 -291.575998)
		(end 342.442546 -291.580824)
		(width 0.09525)
		(layer "In2.Cu")
		(net "M_C_CPU0_SB_DQS_DP<8>")
	)
	(segment
		(start 326.462644 -293.200836)
		(end 326.430132 -293.219632)
		(width 0.09525)
		(layer "In2.Cu")
		(net "M_C_CPU0_SB_DQS_DP<8>")
	)
	(segment
		(start 310.402986 -314.469526)
		(end 306.452016 -314.469526)
		(width 0.16002)
		(layer "In2.Cu")
		(net "M_C_CPU0_SB_DQS_DP<8>")
	)
	(segment
		(start 333.050896 -291.575998)
		(end 333.042514 -291.580824)
		(width 0.09525)
		(layer "In2.Cu")
		(net "M_C_CPU0_SB_DQS_DP<8>")
	)
	(segment
		(start 289.972496 -314.361322)
		(end 288.45383 -314.361322)
		(width 0.16002)
		(layer "In2.Cu")
		(net "M_C_CPU0_SB_DQS_DP<8>")
	)
	(segment
		(start 340.939628 -291.580824)
		(end 340.931246 -291.575998)
		(width 0.09525)
		(layer "In2.Cu")
		(net "M_C_CPU0_SB_DQS_DP<8>")
	)
	(segment
		(start 302.137318 -315.333126)
		(end 301.327058 -314.522866)
		(width 0.16002)
		(layer "In2.Cu")
		(net "M_C_CPU0_SB_DQS_DP<8>")
	)
	(segment
		(start 343.571068 -291.905944)
		(end 343.724992 -291.640514)
		(width 0.09525)
		(layer "In2.Cu")
		(net "M_C_CPU0_SB_DQS_DP<8>")
	)
	(segment
		(start 325.506842 -295.78554)
		(end 325.506842 -295.809162)
		(width 0.09525)
		(layer "In2.Cu")
		(net "M_C_CPU0_SB_DQS_DP<8>")
	)
	(segment
		(start 296.60342 -315.360304)
		(end 294.580056 -315.360304)
		(width 0.16002)
		(layer "In2.Cu")
		(net "M_C_CPU0_SB_DQS_DP<8>")
	)
	(arc
		(start 334.909922 -291.587936)
		(mid 334.633912 -291.656497)
		(end 334.359758 -291.580824)
		(width 0.09525)
		(layer "In2.Cu")
		(net "M_C_CPU0_SB_DQS_DP<8>")
	)
	(arc
		(start 333.419704 -291.580824)
		(mid 333.235929 -291.530052)
		(end 333.050896 -291.575998)
		(width 0.09525)
		(layer "In2.Cu")
		(net "M_C_CPU0_SB_DQS_DP<8>")
	)
	(arc
		(start 333.969614 -291.587936)
		(mid 333.693714 -291.656498)
		(end 333.419704 -291.580824)
		(width 0.09525)
		(layer "In2.Cu")
		(net "M_C_CPU0_SB_DQS_DP<8>")
	)
	(arc
		(start 336.802476 -291.580824)
		(mid 336.521044 -291.656579)
		(end 336.239612 -291.580824)
		(width 0.09525)
		(layer "In2.Cu")
		(net "M_C_CPU0_SB_DQS_DP<8>")
	)
	(arc
		(start 330.222606 -291.580824)
		(mid 330.216278 -291.58442)
		(end 330.209906 -291.587936)
		(width 0.09525)
		(layer "In2.Cu")
		(net "M_C_CPU0_SB_DQS_DP<8>")
	)
	(arc
		(start 326.90689 -292.453314)
		(mid 326.855367 -292.513694)
		(end 326.813418 -292.581076)
		(width 0.09525)
		(layer "In2.Cu")
		(net "M_C_CPU0_SB_DQS_DP<8>")
	)
	(arc
		(start 335.862422 -291.580824)
		(mid 335.58099 -291.656579)
		(end 335.299558 -291.580824)
		(width 0.09525)
		(layer "In2.Cu")
		(net "M_C_CPU0_SB_DQS_DP<8>")
	)
	(arc
		(start 327.409048 -291.995098)
		(mid 327.323201 -292.074376)
		(end 327.231248 -292.146482)
		(width 0.09525)
		(layer "In2.Cu")
		(net "M_C_CPU0_SB_DQS_DP<8>")
	)
	(arc
		(start 338.682584 -291.580824)
		(mid 338.676131 -291.584424)
		(end 338.66963 -291.587936)
		(width 0.09525)
		(layer "In2.Cu")
		(net "M_C_CPU0_SB_DQS_DP<8>")
	)
	(arc
		(start 339.609938 -291.587936)
		(mid 339.333928 -291.656497)
		(end 339.059774 -291.580824)
		(width 0.09525)
		(layer "In2.Cu")
		(net "M_C_CPU0_SB_DQS_DP<8>")
	)
	(arc
		(start 343.3826 -291.580824)
		(mid 343.376147 -291.584424)
		(end 343.369646 -291.587936)
		(width 0.09525)
		(layer "In2.Cu")
		(net "M_C_CPU0_SB_DQS_DP<8>")
	)
	(arc
		(start 339.059774 -291.580824)
		(mid 338.875999 -291.530052)
		(end 338.690966 -291.575998)
		(width 0.09525)
		(layer "In2.Cu")
		(net "M_C_CPU0_SB_DQS_DP<8>")
	)
	(arc
		(start 335.299558 -291.580824)
		(mid 335.11109 -291.530147)
		(end 334.922622 -291.580824)
		(width 0.09525)
		(layer "In2.Cu")
		(net "M_C_CPU0_SB_DQS_DP<8>")
	)
	(arc
		(start 326.813418 -292.581076)
		(mid 326.81098 -292.58589)
		(end 326.808592 -292.590728)
		(width 0.09525)
		(layer "In2.Cu")
		(net "M_C_CPU0_SB_DQS_DP<8>")
	)
	(arc
		(start 326.808592 -292.590728)
		(mid 326.784425 -292.642331)
		(end 326.762364 -292.694868)
		(width 0.09525)
		(layer "In2.Cu")
		(net "M_C_CPU0_SB_DQS_DP<8>")
	)
	(arc
		(start 339.999574 -291.580824)
		(mid 339.811106 -291.530147)
		(end 339.622638 -291.580824)
		(width 0.09525)
		(layer "In2.Cu")
		(net "M_C_CPU0_SB_DQS_DP<8>")
	)
	(arc
		(start 336.23123 -291.575998)
		(mid 336.046198 -291.530084)
		(end 335.862422 -291.580824)
		(width 0.09525)
		(layer "In2.Cu")
		(net "M_C_CPU0_SB_DQS_DP<8>")
	)
	(arc
		(start 327.153778 -292.20795)
		(mid 327.124585 -292.234351)
		(end 327.096374 -292.261798)
		(width 0.09525)
		(layer "In2.Cu")
		(net "M_C_CPU0_SB_DQS_DP<8>")
	)
	(arc
		(start 331.531214 -291.575998)
		(mid 331.346182 -291.530084)
		(end 331.162406 -291.580824)
		(width 0.09525)
		(layer "In2.Cu")
		(net "M_C_CPU0_SB_DQS_DP<8>")
	)
	(arc
		(start 337.74253 -291.580824)
		(mid 337.461098 -291.656579)
		(end 337.179666 -291.580824)
		(width 0.09525)
		(layer "In2.Cu")
		(net "M_C_CPU0_SB_DQS_DP<8>")
	)
	(arc
		(start 339.622638 -291.580824)
		(mid 339.61631 -291.58442)
		(end 339.609938 -291.587936)
		(width 0.09525)
		(layer "In2.Cu")
		(net "M_C_CPU0_SB_DQS_DP<8>")
	)
	(arc
		(start 342.819736 -291.580824)
		(mid 342.635961 -291.530052)
		(end 342.450928 -291.575998)
		(width 0.09525)
		(layer "In2.Cu")
		(net "M_C_CPU0_SB_DQS_DP<8>")
	)
	(arc
		(start 326.589898 -293.101522)
		(mid 326.535763 -293.151462)
		(end 326.47509 -293.193216)
		(width 0.09525)
		(layer "In2.Cu")
		(net "M_C_CPU0_SB_DQS_DP<8>")
	)
	(arc
		(start 338.11972 -291.580824)
		(mid 337.935945 -291.530052)
		(end 337.750912 -291.575998)
		(width 0.09525)
		(layer "In2.Cu")
		(net "M_C_CPU0_SB_DQS_DP<8>")
	)
	(arc
		(start 343.369646 -291.587936)
		(mid 343.093746 -291.656498)
		(end 342.819736 -291.580824)
		(width 0.09525)
		(layer "In2.Cu")
		(net "M_C_CPU0_SB_DQS_DP<8>")
	)
	(arc
		(start 333.982568 -291.580824)
		(mid 333.976115 -291.584424)
		(end 333.969614 -291.587936)
		(width 0.09525)
		(layer "In2.Cu")
		(net "M_C_CPU0_SB_DQS_DP<8>")
	)
	(arc
		(start 330.209906 -291.587936)
		(mid 329.933896 -291.656497)
		(end 329.659742 -291.580824)
		(width 0.09525)
		(layer "In2.Cu")
		(net "M_C_CPU0_SB_DQS_DP<8>")
	)
	(arc
		(start 341.502492 -291.580824)
		(mid 341.22106 -291.656579)
		(end 340.939628 -291.580824)
		(width 0.09525)
		(layer "In2.Cu")
		(net "M_C_CPU0_SB_DQS_DP<8>")
	)
	(arc
		(start 343.701624 -291.553646)
		(mid 343.543874 -291.531127)
		(end 343.390982 -291.575998)
		(width 0.09525)
		(layer "In2.Cu")
		(net "M_C_CPU0_SB_DQS_DP<8>")
	)
	(arc
		(start 329.282552 -291.580824)
		(mid 329.00112 -291.656579)
		(end 328.719688 -291.580824)
		(width 0.09525)
		(layer "In2.Cu")
		(net "M_C_CPU0_SB_DQS_DP<8>")
	)
	(arc
		(start 330.599542 -291.580824)
		(mid 330.411074 -291.530147)
		(end 330.222606 -291.580824)
		(width 0.09525)
		(layer "In2.Cu")
		(net "M_C_CPU0_SB_DQS_DP<8>")
	)
	(arc
		(start 340.931246 -291.575998)
		(mid 340.746214 -291.530084)
		(end 340.562438 -291.580824)
		(width 0.09525)
		(layer "In2.Cu")
		(net "M_C_CPU0_SB_DQS_DP<8>")
	)
	(arc
		(start 328.342498 -291.580824)
		(mid 328.206913 -291.637276)
		(end 328.06132 -291.656516)
		(width 0.09525)
		(layer "In2.Cu")
		(net "M_C_CPU0_SB_DQS_DP<8>")
	)
	(arc
		(start 328.711306 -291.575998)
		(mid 328.526274 -291.530084)
		(end 328.342498 -291.580824)
		(width 0.09525)
		(layer "In2.Cu")
		(net "M_C_CPU0_SB_DQS_DP<8>")
	)
	(arc
		(start 338.66963 -291.587936)
		(mid 338.39373 -291.656498)
		(end 338.11972 -291.580824)
		(width 0.09525)
		(layer "In2.Cu")
		(net "M_C_CPU0_SB_DQS_DP<8>")
	)
	(arc
		(start 341.8713 -291.575998)
		(mid 341.686268 -291.530084)
		(end 341.502492 -291.580824)
		(width 0.09525)
		(layer "In2.Cu")
		(net "M_C_CPU0_SB_DQS_DP<8>")
	)
	(arc
		(start 333.042514 -291.580824)
		(mid 332.761082 -291.656579)
		(end 332.47965 -291.580824)
		(width 0.09525)
		(layer "In2.Cu")
		(net "M_C_CPU0_SB_DQS_DP<8>")
	)
	(arc
		(start 334.922622 -291.580824)
		(mid 334.916294 -291.58442)
		(end 334.909922 -291.587936)
		(width 0.09525)
		(layer "In2.Cu")
		(net "M_C_CPU0_SB_DQS_DP<8>")
	)
	(arc
		(start 326.738742 -292.787324)
		(mid 326.689237 -292.956228)
		(end 326.589898 -293.101522)
		(width 0.09525)
		(layer "In2.Cu")
		(net "M_C_CPU0_SB_DQS_DP<8>")
	)
	(arc
		(start 334.359758 -291.580824)
		(mid 334.175983 -291.530052)
		(end 333.99095 -291.575998)
		(width 0.09525)
		(layer "In2.Cu")
		(net "M_C_CPU0_SB_DQS_DP<8>")
	)
	(arc
		(start 337.171284 -291.575998)
		(mid 336.986252 -291.530084)
		(end 336.802476 -291.580824)
		(width 0.09525)
		(layer "In2.Cu")
		(net "M_C_CPU0_SB_DQS_DP<8>")
	)
	(arc
		(start 326.762364 -292.694868)
		(mid 326.7476 -292.740343)
		(end 326.738742 -292.787324)
		(width 0.09525)
		(layer "In2.Cu")
		(net "M_C_CPU0_SB_DQS_DP<8>")
	)
	(arc
		(start 329.659742 -291.580824)
		(mid 329.475967 -291.530052)
		(end 329.290934 -291.575998)
		(width 0.09525)
		(layer "In2.Cu")
		(net "M_C_CPU0_SB_DQS_DP<8>")
	)
	(arc
		(start 342.442546 -291.580824)
		(mid 342.161114 -291.656579)
		(end 341.879682 -291.580824)
		(width 0.09525)
		(layer "In2.Cu")
		(net "M_C_CPU0_SB_DQS_DP<8>")
	)
	(arc
		(start 340.562438 -291.580824)
		(mid 340.281006 -291.656579)
		(end 339.999574 -291.580824)
		(width 0.09525)
		(layer "In2.Cu")
		(net "M_C_CPU0_SB_DQS_DP<8>")
	)
	(arc
		(start 327.231248 -292.146482)
		(mid 327.191816 -292.176337)
		(end 327.153778 -292.20795)
		(width 0.09525)
		(layer "In2.Cu")
		(net "M_C_CPU0_SB_DQS_DP<8>")
	)
	(arc
		(start 326.430132 -293.219632)
		(mid 326.314858 -293.35391)
		(end 326.273414 -293.525956)
		(width 0.09525)
		(layer "In2.Cu")
		(net "M_C_CPU0_SB_DQS_DP<8>")
	)
	(arc
		(start 332.471268 -291.575998)
		(mid 332.286236 -291.530084)
		(end 332.10246 -291.580824)
		(width 0.09525)
		(layer "In2.Cu")
		(net "M_C_CPU0_SB_DQS_DP<8>")
	)
	(arc
		(start 331.162406 -291.580824)
		(mid 330.880974 -291.656579)
		(end 330.599542 -291.580824)
		(width 0.09525)
		(layer "In2.Cu")
		(net "M_C_CPU0_SB_DQS_DP<8>")
	)
	(arc
		(start 332.10246 -291.580824)
		(mid 331.821028 -291.656579)
		(end 331.539596 -291.580824)
		(width 0.09525)
		(layer "In2.Cu")
		(net "M_C_CPU0_SB_DQS_DP<8>")
	)
	(segment
		(start 344.03792 -286.780224)
		(end 343.571068 -287.045908)
		(width 0.12954)
		(layer "F.Cu")
		(net "M_C_CPU0_SB_DQS_DP<7>")
	)
	(segment
		(start 324.132194 -287.939734)
		(end 324.11543 -287.956498)
		(width 0.09525)
		(layer "In2.Cu")
		(net "M_C_CPU0_SB_DQS_DP<7>")
	)
	(segment
		(start 294.64508 -306.01031)
		(end 293.218616 -305.419506)
		(width 0.16002)
		(layer "In2.Cu")
		(net "M_C_CPU0_SB_DQS_DP<7>")
	)
	(segment
		(start 298.962318 -305.160172)
		(end 298.634658 -304.832512)
		(width 0.16002)
		(layer "In2.Cu")
		(net "M_C_CPU0_SB_DQS_DP<7>")
	)
	(segment
		(start 302.137318 -305.983132)
		(end 301.610268 -305.456082)
		(width 0.16002)
		(layer "In2.Cu")
		(net "M_C_CPU0_SB_DQS_DP<7>")
	)
	(segment
		(start 306.193444 -304.86096)
		(end 305.78933 -304.86096)
		(width 0.16002)
		(layer "In2.Cu")
		(net "M_C_CPU0_SB_DQS_DP<7>")
	)
	(segment
		(start 290.128452 -304.855372)
		(end 289.972496 -305.011328)
		(width 0.16002)
		(layer "In2.Cu")
		(net "M_C_CPU0_SB_DQS_DP<7>")
	)
	(segment
		(start 343.390982 -286.715962)
		(end 343.3826 -286.720788)
		(width 0.09525)
		(layer "In2.Cu")
		(net "M_C_CPU0_SB_DQS_DP<7>")
	)
	(segment
		(start 336.239612 -286.720788)
		(end 336.23123 -286.715962)
		(width 0.09525)
		(layer "In2.Cu")
		(net "M_C_CPU0_SB_DQS_DP<7>")
	)
	(segment
		(start 310.206644 -305.119532)
		(end 306.452016 -305.119532)
		(width 0.16002)
		(layer "In2.Cu")
		(net "M_C_CPU0_SB_DQS_DP<7>")
	)
	(segment
		(start 296.60342 -306.01031)
		(end 294.64508 -306.01031)
		(width 0.16002)
		(layer "In2.Cu")
		(net "M_C_CPU0_SB_DQS_DP<7>")
	)
	(segment
		(start 298.634658 -304.832512)
		(end 298.271438 -304.832512)
		(width 0.16002)
		(layer "In2.Cu")
		(net "M_C_CPU0_SB_DQS_DP<7>")
	)
	(segment
		(start 304.486818 -305.663092)
		(end 304.166778 -305.983132)
		(width 0.16002)
		(layer "In2.Cu")
		(net "M_C_CPU0_SB_DQS_DP<7>")
	)
	(segment
		(start 341.879682 -286.720788)
		(end 341.8713 -286.715962)
		(width 0.09525)
		(layer "In2.Cu")
		(net "M_C_CPU0_SB_DQS_DP<7>")
	)
	(segment
		(start 319.710054 -292.362636)
		(end 319.710054 -295.616122)
		(width 0.16002)
		(layer "In2.Cu")
		(net "M_C_CPU0_SB_DQS_DP<7>")
	)
	(segment
		(start 304.756566 -305.551332)
		(end 304.486818 -305.663092)
		(width 0.16002)
		(layer "In2.Cu")
		(net "M_C_CPU0_SB_DQS_DP<7>")
	)
	(segment
		(start 328.719688 -286.720788)
		(end 328.711306 -286.715962)
		(width 0.09525)
		(layer "In2.Cu")
		(net "M_C_CPU0_SB_DQS_DP<7>")
	)
	(segment
		(start 291.090096 -304.855372)
		(end 290.128452 -304.855372)
		(width 0.16002)
		(layer "In2.Cu")
		(net "M_C_CPU0_SB_DQS_DP<7>")
	)
	(segment
		(start 306.452016 -305.119532)
		(end 306.193444 -304.86096)
		(width 0.16002)
		(layer "In2.Cu")
		(net "M_C_CPU0_SB_DQS_DP<7>")
	)
	(segment
		(start 332.47965 -286.720788)
		(end 332.471268 -286.715962)
		(width 0.09525)
		(layer "In2.Cu")
		(net "M_C_CPU0_SB_DQS_DP<7>")
	)
	(segment
		(start 343.724992 -286.780478)
		(end 343.701624 -286.69361)
		(width 0.09525)
		(layer "In2.Cu")
		(net "M_C_CPU0_SB_DQS_DP<7>")
	)
	(segment
		(start 343.571068 -287.045908)
		(end 343.724992 -286.780478)
		(width 0.09525)
		(layer "In2.Cu")
		(net "M_C_CPU0_SB_DQS_DP<7>")
	)
	(segment
		(start 337.179666 -286.720788)
		(end 337.171284 -286.715962)
		(width 0.09525)
		(layer "In2.Cu")
		(net "M_C_CPU0_SB_DQS_DP<7>")
	)
	(segment
		(start 298.178728 -304.925222)
		(end 297.223688 -305.56327)
		(width 0.16002)
		(layer "In2.Cu")
		(net "M_C_CPU0_SB_DQS_DP<7>")
	)
	(segment
		(start 291.323776 -305.089052)
		(end 291.090096 -304.855372)
		(width 0.16002)
		(layer "In2.Cu")
		(net "M_C_CPU0_SB_DQS_DP<7>")
	)
	(segment
		(start 325.544434 -287.19526)
		(end 324.97903 -287.19526)
		(width 0.09525)
		(layer "In2.Cu")
		(net "M_C_CPU0_SB_DQS_DP<7>")
	)
	(segment
		(start 326.839326 -286.721042)
		(end 326.821038 -286.710628)
		(width 0.09525)
		(layer "In2.Cu")
		(net "M_C_CPU0_SB_DQS_DP<7>")
	)
	(segment
		(start 324.662292 -287.326578)
		(end 324.13194 -287.85693)
		(width 0.09525)
		(layer "In2.Cu")
		(net "M_C_CPU0_SB_DQS_DP<7>")
	)
	(segment
		(start 293.218616 -305.419506)
		(end 292.12159 -305.419506)
		(width 0.16002)
		(layer "In2.Cu")
		(net "M_C_CPU0_SB_DQS_DP<7>")
	)
	(segment
		(start 324.13194 -287.85693)
		(end 324.132194 -287.939734)
		(width 0.09525)
		(layer "In2.Cu")
		(net "M_C_CPU0_SB_DQS_DP<7>")
	)
	(segment
		(start 325.942706 -286.796988)
		(end 325.544434 -287.19526)
		(width 0.09525)
		(layer "In2.Cu")
		(net "M_C_CPU0_SB_DQS_DP<7>")
	)
	(segment
		(start 304.166778 -305.983132)
		(end 302.137318 -305.983132)
		(width 0.16002)
		(layer "In2.Cu")
		(net "M_C_CPU0_SB_DQS_DP<7>")
	)
	(segment
		(start 342.450928 -286.715962)
		(end 342.442546 -286.720788)
		(width 0.09525)
		(layer "In2.Cu")
		(net "M_C_CPU0_SB_DQS_DP<7>")
	)
	(segment
		(start 288.45383 -305.011328)
		(end 288.180018 -305.28514)
		(width 0.16002)
		(layer "In2.Cu")
		(net "M_C_CPU0_SB_DQS_DP<7>")
	)
	(segment
		(start 329.290934 -286.715962)
		(end 329.282552 -286.720788)
		(width 0.09525)
		(layer "In2.Cu")
		(net "M_C_CPU0_SB_DQS_DP<7>")
	)
	(segment
		(start 296.927778 -305.685952)
		(end 296.60342 -306.01031)
		(width 0.16002)
		(layer "In2.Cu")
		(net "M_C_CPU0_SB_DQS_DP<7>")
	)
	(segment
		(start 331.539596 -286.720788)
		(end 331.531214 -286.715962)
		(width 0.09525)
		(layer "In2.Cu")
		(net "M_C_CPU0_SB_DQS_DP<7>")
	)
	(segment
		(start 333.050896 -286.715962)
		(end 333.042514 -286.720788)
		(width 0.09525)
		(layer "In2.Cu")
		(net "M_C_CPU0_SB_DQS_DP<7>")
	)
	(segment
		(start 289.972496 -305.011328)
		(end 288.45383 -305.011328)
		(width 0.16002)
		(layer "In2.Cu")
		(net "M_C_CPU0_SB_DQS_DP<7>")
	)
	(segment
		(start 301.610268 -305.456082)
		(end 300.895766 -305.160172)
		(width 0.16002)
		(layer "In2.Cu")
		(net "M_C_CPU0_SB_DQS_DP<7>")
	)
	(segment
		(start 292.12159 -305.419506)
		(end 291.323776 -305.089052)
		(width 0.16002)
		(layer "In2.Cu")
		(net "M_C_CPU0_SB_DQS_DP<7>")
	)
	(segment
		(start 327.41362 -286.71393)
		(end 327.401682 -286.720788)
		(width 0.09525)
		(layer "In2.Cu")
		(net "M_C_CPU0_SB_DQS_DP<7>")
	)
	(segment
		(start 305.78933 -304.86096)
		(end 304.756566 -305.551332)
		(width 0.16002)
		(layer "In2.Cu")
		(net "M_C_CPU0_SB_DQS_DP<7>")
	)
	(segment
		(start 298.271438 -304.832512)
		(end 298.178728 -304.925222)
		(width 0.16002)
		(layer "In2.Cu")
		(net "M_C_CPU0_SB_DQS_DP<7>")
	)
	(segment
		(start 300.895766 -305.160172)
		(end 298.962318 -305.160172)
		(width 0.16002)
		(layer "In2.Cu")
		(net "M_C_CPU0_SB_DQS_DP<7>")
	)
	(segment
		(start 340.939628 -286.720788)
		(end 340.931246 -286.715962)
		(width 0.09525)
		(layer "In2.Cu")
		(net "M_C_CPU0_SB_DQS_DP<7>")
	)
	(segment
		(start 326.180196 -286.796988)
		(end 325.942706 -286.796988)
		(width 0.09525)
		(layer "In2.Cu")
		(net "M_C_CPU0_SB_DQS_DP<7>")
	)
	(segment
		(start 297.223688 -305.56327)
		(end 296.927778 -305.685952)
		(width 0.16002)
		(layer "In2.Cu")
		(net "M_C_CPU0_SB_DQS_DP<7>")
	)
	(segment
		(start 319.710054 -295.616122)
		(end 310.206644 -305.119532)
		(width 0.16002)
		(layer "In2.Cu")
		(net "M_C_CPU0_SB_DQS_DP<7>")
	)
	(segment
		(start 326.844914 -286.724344)
		(end 326.839326 -286.721042)
		(width 0.09525)
		(layer "In2.Cu")
		(net "M_C_CPU0_SB_DQS_DP<7>")
	)
	(segment
		(start 337.750912 -286.715962)
		(end 337.74253 -286.720788)
		(width 0.09525)
		(layer "In2.Cu")
		(net "M_C_CPU0_SB_DQS_DP<7>")
	)
	(segment
		(start 328.342498 -286.720788)
		(end 328.327766 -286.729424)
		(width 0.09525)
		(layer "In2.Cu")
		(net "M_C_CPU0_SB_DQS_DP<7>")
	)
	(segment
		(start 338.690966 -286.715962)
		(end 338.682584 -286.720788)
		(width 0.09525)
		(layer "In2.Cu")
		(net "M_C_CPU0_SB_DQS_DP<7>")
	)
	(segment
		(start 324.11543 -287.956498)
		(end 319.710054 -292.362636)
		(width 0.16002)
		(layer "In2.Cu")
		(net "M_C_CPU0_SB_DQS_DP<7>")
	)
	(segment
		(start 333.99095 -286.715962)
		(end 333.982568 -286.720788)
		(width 0.09525)
		(layer "In2.Cu")
		(net "M_C_CPU0_SB_DQS_DP<7>")
	)
	(arc
		(start 341.502492 -286.720788)
		(mid 341.22106 -286.796577)
		(end 340.939628 -286.720788)
		(width 0.09525)
		(layer "In2.Cu")
		(net "M_C_CPU0_SB_DQS_DP<7>")
	)
	(arc
		(start 330.222606 -286.720788)
		(mid 329.941174 -286.796577)
		(end 329.659742 -286.720788)
		(width 0.09525)
		(layer "In2.Cu")
		(net "M_C_CPU0_SB_DQS_DP<7>")
	)
	(arc
		(start 328.327766 -286.729424)
		(mid 328.052307 -286.796839)
		(end 327.779126 -286.720788)
		(width 0.09525)
		(layer "In2.Cu")
		(net "M_C_CPU0_SB_DQS_DP<7>")
	)
	(arc
		(start 326.462136 -286.720788)
		(mid 326.326212 -286.777549)
		(end 326.180196 -286.796988)
		(width 0.09525)
		(layer "In2.Cu")
		(net "M_C_CPU0_SB_DQS_DP<7>")
	)
	(arc
		(start 333.419704 -286.720788)
		(mid 333.235929 -286.670016)
		(end 333.050896 -286.715962)
		(width 0.09525)
		(layer "In2.Cu")
		(net "M_C_CPU0_SB_DQS_DP<7>")
	)
	(arc
		(start 342.442546 -286.720788)
		(mid 342.161114 -286.796577)
		(end 341.879682 -286.720788)
		(width 0.09525)
		(layer "In2.Cu")
		(net "M_C_CPU0_SB_DQS_DP<7>")
	)
	(arc
		(start 327.401682 -286.720788)
		(mid 327.123778 -286.796566)
		(end 326.844914 -286.724344)
		(width 0.09525)
		(layer "In2.Cu")
		(net "M_C_CPU0_SB_DQS_DP<7>")
	)
	(arc
		(start 333.982568 -286.720788)
		(mid 333.701136 -286.796577)
		(end 333.419704 -286.720788)
		(width 0.09525)
		(layer "In2.Cu")
		(net "M_C_CPU0_SB_DQS_DP<7>")
	)
	(arc
		(start 339.622638 -286.720788)
		(mid 339.341206 -286.796577)
		(end 339.059774 -286.720788)
		(width 0.09525)
		(layer "In2.Cu")
		(net "M_C_CPU0_SB_DQS_DP<7>")
	)
	(arc
		(start 336.802476 -286.720788)
		(mid 336.521044 -286.796577)
		(end 336.239612 -286.720788)
		(width 0.09525)
		(layer "In2.Cu")
		(net "M_C_CPU0_SB_DQS_DP<7>")
	)
	(arc
		(start 327.779126 -286.720788)
		(mid 327.597256 -286.669923)
		(end 327.41362 -286.71393)
		(width 0.09525)
		(layer "In2.Cu")
		(net "M_C_CPU0_SB_DQS_DP<7>")
	)
	(arc
		(start 342.819736 -286.720788)
		(mid 342.635961 -286.670016)
		(end 342.450928 -286.715962)
		(width 0.09525)
		(layer "In2.Cu")
		(net "M_C_CPU0_SB_DQS_DP<7>")
	)
	(arc
		(start 340.562438 -286.720788)
		(mid 340.281006 -286.796577)
		(end 339.999574 -286.720788)
		(width 0.09525)
		(layer "In2.Cu")
		(net "M_C_CPU0_SB_DQS_DP<7>")
	)
	(arc
		(start 339.059774 -286.720788)
		(mid 338.875999 -286.670016)
		(end 338.690966 -286.715962)
		(width 0.09525)
		(layer "In2.Cu")
		(net "M_C_CPU0_SB_DQS_DP<7>")
	)
	(arc
		(start 338.11972 -286.720788)
		(mid 337.935945 -286.670016)
		(end 337.750912 -286.715962)
		(width 0.09525)
		(layer "In2.Cu")
		(net "M_C_CPU0_SB_DQS_DP<7>")
	)
	(arc
		(start 336.23123 -286.715962)
		(mid 336.046198 -286.670048)
		(end 335.862422 -286.720788)
		(width 0.09525)
		(layer "In2.Cu")
		(net "M_C_CPU0_SB_DQS_DP<7>")
	)
	(arc
		(start 331.531214 -286.715962)
		(mid 331.346182 -286.670048)
		(end 331.162406 -286.720788)
		(width 0.09525)
		(layer "In2.Cu")
		(net "M_C_CPU0_SB_DQS_DP<7>")
	)
	(arc
		(start 337.171284 -286.715962)
		(mid 336.986252 -286.670048)
		(end 336.802476 -286.720788)
		(width 0.09525)
		(layer "In2.Cu")
		(net "M_C_CPU0_SB_DQS_DP<7>")
	)
	(arc
		(start 343.3826 -286.720788)
		(mid 343.101168 -286.796577)
		(end 342.819736 -286.720788)
		(width 0.09525)
		(layer "In2.Cu")
		(net "M_C_CPU0_SB_DQS_DP<7>")
	)
	(arc
		(start 343.701624 -286.69361)
		(mid 343.543874 -286.671091)
		(end 343.390982 -286.715962)
		(width 0.09525)
		(layer "In2.Cu")
		(net "M_C_CPU0_SB_DQS_DP<7>")
	)
	(arc
		(start 333.042514 -286.720788)
		(mid 332.761082 -286.796577)
		(end 332.47965 -286.720788)
		(width 0.09525)
		(layer "In2.Cu")
		(net "M_C_CPU0_SB_DQS_DP<7>")
	)
	(arc
		(start 324.97903 -287.19526)
		(mid 324.80762 -287.229449)
		(end 324.662292 -287.326578)
		(width 0.09525)
		(layer "In2.Cu")
		(net "M_C_CPU0_SB_DQS_DP<7>")
	)
	(arc
		(start 328.711306 -286.715962)
		(mid 328.526274 -286.670048)
		(end 328.342498 -286.720788)
		(width 0.09525)
		(layer "In2.Cu")
		(net "M_C_CPU0_SB_DQS_DP<7>")
	)
	(arc
		(start 341.8713 -286.715962)
		(mid 341.686268 -286.670048)
		(end 341.502492 -286.720788)
		(width 0.09525)
		(layer "In2.Cu")
		(net "M_C_CPU0_SB_DQS_DP<7>")
	)
	(arc
		(start 329.659742 -286.720788)
		(mid 329.475967 -286.670016)
		(end 329.290934 -286.715962)
		(width 0.09525)
		(layer "In2.Cu")
		(net "M_C_CPU0_SB_DQS_DP<7>")
	)
	(arc
		(start 339.999574 -286.720788)
		(mid 339.811106 -286.670111)
		(end 339.622638 -286.720788)
		(width 0.09525)
		(layer "In2.Cu")
		(net "M_C_CPU0_SB_DQS_DP<7>")
	)
	(arc
		(start 326.821038 -286.710628)
		(mid 326.640285 -286.670059)
		(end 326.462136 -286.720788)
		(width 0.09525)
		(layer "In2.Cu")
		(net "M_C_CPU0_SB_DQS_DP<7>")
	)
	(arc
		(start 329.282552 -286.720788)
		(mid 329.00112 -286.796577)
		(end 328.719688 -286.720788)
		(width 0.09525)
		(layer "In2.Cu")
		(net "M_C_CPU0_SB_DQS_DP<7>")
	)
	(arc
		(start 330.599542 -286.720788)
		(mid 330.411074 -286.670111)
		(end 330.222606 -286.720788)
		(width 0.09525)
		(layer "In2.Cu")
		(net "M_C_CPU0_SB_DQS_DP<7>")
	)
	(arc
		(start 337.74253 -286.720788)
		(mid 337.461098 -286.796577)
		(end 337.179666 -286.720788)
		(width 0.09525)
		(layer "In2.Cu")
		(net "M_C_CPU0_SB_DQS_DP<7>")
	)
	(arc
		(start 340.931246 -286.715962)
		(mid 340.746214 -286.670048)
		(end 340.562438 -286.720788)
		(width 0.09525)
		(layer "In2.Cu")
		(net "M_C_CPU0_SB_DQS_DP<7>")
	)
	(arc
		(start 338.682584 -286.720788)
		(mid 338.401152 -286.796577)
		(end 338.11972 -286.720788)
		(width 0.09525)
		(layer "In2.Cu")
		(net "M_C_CPU0_SB_DQS_DP<7>")
	)
	(arc
		(start 332.10246 -286.720788)
		(mid 331.821028 -286.796577)
		(end 331.539596 -286.720788)
		(width 0.09525)
		(layer "In2.Cu")
		(net "M_C_CPU0_SB_DQS_DP<7>")
	)
	(arc
		(start 334.922622 -286.720788)
		(mid 334.64119 -286.796577)
		(end 334.359758 -286.720788)
		(width 0.09525)
		(layer "In2.Cu")
		(net "M_C_CPU0_SB_DQS_DP<7>")
	)
	(arc
		(start 332.471268 -286.715962)
		(mid 332.286236 -286.670048)
		(end 332.10246 -286.720788)
		(width 0.09525)
		(layer "In2.Cu")
		(net "M_C_CPU0_SB_DQS_DP<7>")
	)
	(arc
		(start 335.862422 -286.720788)
		(mid 335.58099 -286.796577)
		(end 335.299558 -286.720788)
		(width 0.09525)
		(layer "In2.Cu")
		(net "M_C_CPU0_SB_DQS_DP<7>")
	)
	(arc
		(start 335.299558 -286.720788)
		(mid 335.11109 -286.670111)
		(end 334.922622 -286.720788)
		(width 0.09525)
		(layer "In2.Cu")
		(net "M_C_CPU0_SB_DQS_DP<7>")
	)
	(arc
		(start 334.359758 -286.720788)
		(mid 334.175983 -286.670016)
		(end 333.99095 -286.715962)
		(width 0.09525)
		(layer "In2.Cu")
		(net "M_C_CPU0_SB_DQS_DP<7>")
	)
	(arc
		(start 331.162406 -286.720788)
		(mid 330.880974 -286.796577)
		(end 330.599542 -286.720788)
		(width 0.09525)
		(layer "In2.Cu")
		(net "M_C_CPU0_SB_DQS_DP<7>")
	)
	(segment
		(start 344.03792 -281.920188)
		(end 343.571068 -282.186126)
		(width 0.12954)
		(layer "F.Cu")
		(net "M_C_CPU0_SB_DQS_DP<6>")
	)
	(segment
		(start 337.179666 -281.861006)
		(end 337.171284 -281.85618)
		(width 0.09525)
		(layer "In2.Cu")
		(net "M_C_CPU0_SB_DQS_DP<6>")
	)
	(segment
		(start 304.166778 -296.633138)
		(end 302.137318 -296.633138)
		(width 0.16002)
		(layer "In2.Cu")
		(net "M_C_CPU0_SB_DQS_DP<6>")
	)
	(segment
		(start 325.921878 -281.915362)
		(end 323.978524 -281.915362)
		(width 0.09525)
		(layer "In2.Cu")
		(net "M_C_CPU0_SB_DQS_DP<6>")
	)
	(segment
		(start 327.59015 -281.809444)
		(end 326.027796 -281.809444)
		(width 0.09525)
		(layer "In2.Cu")
		(net "M_C_CPU0_SB_DQS_DP<6>")
	)
	(segment
		(start 331.539596 -281.861006)
		(end 331.531214 -281.85618)
		(width 0.09525)
		(layer "In2.Cu")
		(net "M_C_CPU0_SB_DQS_DP<6>")
	)
	(segment
		(start 301.728886 -296.224706)
		(end 300.727872 -295.810178)
		(width 0.16002)
		(layer "In2.Cu")
		(net "M_C_CPU0_SB_DQS_DP<6>")
	)
	(segment
		(start 291.09289 -295.508172)
		(end 290.634928 -295.508172)
		(width 0.16002)
		(layer "In2.Cu")
		(net "M_C_CPU0_SB_DQS_DP<6>")
	)
	(segment
		(start 293.218616 -296.069512)
		(end 292.089332 -296.069512)
		(width 0.16002)
		(layer "In2.Cu")
		(net "M_C_CPU0_SB_DQS_DP<6>")
	)
	(segment
		(start 341.879682 -281.861006)
		(end 341.8713 -281.85618)
		(width 0.09525)
		(layer "In2.Cu")
		(net "M_C_CPU0_SB_DQS_DP<6>")
	)
	(segment
		(start 305.78933 -295.510966)
		(end 304.756566 -296.201338)
		(width 0.16002)
		(layer "In2.Cu")
		(net "M_C_CPU0_SB_DQS_DP<6>")
	)
	(segment
		(start 296.60342 -296.660316)
		(end 294.64508 -296.660316)
		(width 0.16002)
		(layer "In2.Cu")
		(net "M_C_CPU0_SB_DQS_DP<6>")
	)
	(segment
		(start 314.227464 -289.840924)
		(end 314.062618 -290.238688)
		(width 0.16002)
		(layer "In2.Cu")
		(net "M_C_CPU0_SB_DQS_DP<6>")
	)
	(segment
		(start 297.10253 -296.263568)
		(end 296.927778 -296.335958)
		(width 0.16002)
		(layer "In2.Cu")
		(net "M_C_CPU0_SB_DQS_DP<6>")
	)
	(segment
		(start 329.290934 -281.85618)
		(end 329.282552 -281.861006)
		(width 0.09525)
		(layer "In2.Cu")
		(net "M_C_CPU0_SB_DQS_DP<6>")
	)
	(segment
		(start 294.64508 -296.660316)
		(end 293.218616 -296.069512)
		(width 0.16002)
		(layer "In2.Cu")
		(net "M_C_CPU0_SB_DQS_DP<6>")
	)
	(segment
		(start 298.271438 -295.482518)
		(end 297.10253 -296.263568)
		(width 0.16002)
		(layer "In2.Cu")
		(net "M_C_CPU0_SB_DQS_DP<6>")
	)
	(segment
		(start 328.719688 -281.861006)
		(end 328.711306 -281.85618)
		(width 0.09525)
		(layer "In2.Cu")
		(net "M_C_CPU0_SB_DQS_DP<6>")
	)
	(segment
		(start 298.634658 -295.482518)
		(end 298.271438 -295.482518)
		(width 0.16002)
		(layer "In2.Cu")
		(net "M_C_CPU0_SB_DQS_DP<6>")
	)
	(segment
		(start 333.050896 -281.85618)
		(end 333.042514 -281.861006)
		(width 0.09525)
		(layer "In2.Cu")
		(net "M_C_CPU0_SB_DQS_DP<6>")
	)
	(segment
		(start 298.962318 -295.810178)
		(end 298.634658 -295.482518)
		(width 0.16002)
		(layer "In2.Cu")
		(net "M_C_CPU0_SB_DQS_DP<6>")
	)
	(segment
		(start 336.239612 -281.861006)
		(end 336.23123 -281.85618)
		(width 0.09525)
		(layer "In2.Cu")
		(net "M_C_CPU0_SB_DQS_DP<6>")
	)
	(segment
		(start 304.756566 -296.201338)
		(end 304.486818 -296.313098)
		(width 0.16002)
		(layer "In2.Cu")
		(net "M_C_CPU0_SB_DQS_DP<6>")
	)
	(segment
		(start 288.45383 -295.661334)
		(end 288.180018 -295.935146)
		(width 0.16002)
		(layer "In2.Cu")
		(net "M_C_CPU0_SB_DQS_DP<6>")
	)
	(segment
		(start 306.193444 -295.510966)
		(end 305.78933 -295.510966)
		(width 0.16002)
		(layer "In2.Cu")
		(net "M_C_CPU0_SB_DQS_DP<6>")
	)
	(segment
		(start 292.089332 -296.069512)
		(end 291.346636 -295.761918)
		(width 0.16002)
		(layer "In2.Cu")
		(net "M_C_CPU0_SB_DQS_DP<6>")
	)
	(segment
		(start 322.094098 -281.97429)
		(end 314.227464 -289.840924)
		(width 0.16002)
		(layer "In2.Cu")
		(net "M_C_CPU0_SB_DQS_DP<6>")
	)
	(segment
		(start 323.919596 -281.97429)
		(end 323.895974 -281.97429)
		(width 0.09525)
		(layer "In2.Cu")
		(net "M_C_CPU0_SB_DQS_DP<6>")
	)
	(segment
		(start 309.656734 -295.769538)
		(end 306.452016 -295.769538)
		(width 0.16002)
		(layer "In2.Cu")
		(net "M_C_CPU0_SB_DQS_DP<6>")
	)
	(segment
		(start 314.062618 -291.363654)
		(end 309.656734 -295.769538)
		(width 0.16002)
		(layer "In2.Cu")
		(net "M_C_CPU0_SB_DQS_DP<6>")
	)
	(segment
		(start 343.571068 -282.186126)
		(end 343.724992 -281.920696)
		(width 0.09525)
		(layer "In2.Cu")
		(net "M_C_CPU0_SB_DQS_DP<6>")
	)
	(segment
		(start 323.895974 -281.97429)
		(end 322.094098 -281.97429)
		(width 0.16002)
		(layer "In2.Cu")
		(net "M_C_CPU0_SB_DQS_DP<6>")
	)
	(segment
		(start 332.47965 -281.861006)
		(end 332.471268 -281.85618)
		(width 0.09525)
		(layer "In2.Cu")
		(net "M_C_CPU0_SB_DQS_DP<6>")
	)
	(segment
		(start 323.978524 -281.915362)
		(end 323.919596 -281.97429)
		(width 0.09525)
		(layer "In2.Cu")
		(net "M_C_CPU0_SB_DQS_DP<6>")
	)
	(segment
		(start 343.390982 -281.85618)
		(end 343.3826 -281.861006)
		(width 0.09525)
		(layer "In2.Cu")
		(net "M_C_CPU0_SB_DQS_DP<6>")
	)
	(segment
		(start 300.727872 -295.810178)
		(end 298.962318 -295.810178)
		(width 0.16002)
		(layer "In2.Cu")
		(net "M_C_CPU0_SB_DQS_DP<6>")
	)
	(segment
		(start 328.342498 -281.861006)
		(end 328.327766 -281.869642)
		(width 0.09525)
		(layer "In2.Cu")
		(net "M_C_CPU0_SB_DQS_DP<6>")
	)
	(segment
		(start 340.939628 -281.861006)
		(end 340.931246 -281.85618)
		(width 0.09525)
		(layer "In2.Cu")
		(net "M_C_CPU0_SB_DQS_DP<6>")
	)
	(segment
		(start 290.634928 -295.508172)
		(end 290.265104 -295.661334)
		(width 0.16002)
		(layer "In2.Cu")
		(net "M_C_CPU0_SB_DQS_DP<6>")
	)
	(segment
		(start 290.265104 -295.661334)
		(end 288.45383 -295.661334)
		(width 0.16002)
		(layer "In2.Cu")
		(net "M_C_CPU0_SB_DQS_DP<6>")
	)
	(segment
		(start 342.450928 -281.85618)
		(end 342.442546 -281.861006)
		(width 0.09525)
		(layer "In2.Cu")
		(net "M_C_CPU0_SB_DQS_DP<6>")
	)
	(segment
		(start 302.137318 -296.633138)
		(end 301.728886 -296.224706)
		(width 0.16002)
		(layer "In2.Cu")
		(net "M_C_CPU0_SB_DQS_DP<6>")
	)
	(segment
		(start 314.062618 -290.238688)
		(end 314.062618 -291.363654)
		(width 0.16002)
		(layer "In2.Cu")
		(net "M_C_CPU0_SB_DQS_DP<6>")
	)
	(segment
		(start 304.486818 -296.313098)
		(end 304.166778 -296.633138)
		(width 0.16002)
		(layer "In2.Cu")
		(net "M_C_CPU0_SB_DQS_DP<6>")
	)
	(segment
		(start 343.724992 -281.920696)
		(end 343.701624 -281.833828)
		(width 0.09525)
		(layer "In2.Cu")
		(net "M_C_CPU0_SB_DQS_DP<6>")
	)
	(segment
		(start 306.452016 -295.769538)
		(end 306.193444 -295.510966)
		(width 0.16002)
		(layer "In2.Cu")
		(net "M_C_CPU0_SB_DQS_DP<6>")
	)
	(segment
		(start 326.027796 -281.809444)
		(end 325.921878 -281.915362)
		(width 0.09525)
		(layer "In2.Cu")
		(net "M_C_CPU0_SB_DQS_DP<6>")
	)
	(segment
		(start 337.750912 -281.85618)
		(end 337.74253 -281.861006)
		(width 0.09525)
		(layer "In2.Cu")
		(net "M_C_CPU0_SB_DQS_DP<6>")
	)
	(segment
		(start 338.690966 -281.85618)
		(end 338.682584 -281.861006)
		(width 0.09525)
		(layer "In2.Cu")
		(net "M_C_CPU0_SB_DQS_DP<6>")
	)
	(segment
		(start 296.927778 -296.335958)
		(end 296.60342 -296.660316)
		(width 0.16002)
		(layer "In2.Cu")
		(net "M_C_CPU0_SB_DQS_DP<6>")
	)
	(segment
		(start 333.99095 -281.85618)
		(end 333.982568 -281.861006)
		(width 0.09525)
		(layer "In2.Cu")
		(net "M_C_CPU0_SB_DQS_DP<6>")
	)
	(segment
		(start 291.346636 -295.761918)
		(end 291.09289 -295.508172)
		(width 0.16002)
		(layer "In2.Cu")
		(net "M_C_CPU0_SB_DQS_DP<6>")
	)
	(arc
		(start 339.059774 -281.861006)
		(mid 338.875999 -281.810234)
		(end 338.690966 -281.85618)
		(width 0.09525)
		(layer "In2.Cu")
		(net "M_C_CPU0_SB_DQS_DP<6>")
	)
	(arc
		(start 331.531214 -281.85618)
		(mid 331.346182 -281.810266)
		(end 331.162406 -281.861006)
		(width 0.09525)
		(layer "In2.Cu")
		(net "M_C_CPU0_SB_DQS_DP<6>")
	)
	(arc
		(start 327.779126 -281.861006)
		(mid 327.688049 -281.822722)
		(end 327.59015 -281.809444)
		(width 0.09525)
		(layer "In2.Cu")
		(net "M_C_CPU0_SB_DQS_DP<6>")
	)
	(arc
		(start 331.162406 -281.861006)
		(mid 330.880974 -281.936761)
		(end 330.599542 -281.861006)
		(width 0.09525)
		(layer "In2.Cu")
		(net "M_C_CPU0_SB_DQS_DP<6>")
	)
	(arc
		(start 328.711306 -281.85618)
		(mid 328.526274 -281.810266)
		(end 328.342498 -281.861006)
		(width 0.09525)
		(layer "In2.Cu")
		(net "M_C_CPU0_SB_DQS_DP<6>")
	)
	(arc
		(start 338.682584 -281.861006)
		(mid 338.401152 -281.936761)
		(end 338.11972 -281.861006)
		(width 0.09525)
		(layer "In2.Cu")
		(net "M_C_CPU0_SB_DQS_DP<6>")
	)
	(arc
		(start 341.502492 -281.861006)
		(mid 341.22106 -281.936761)
		(end 340.939628 -281.861006)
		(width 0.09525)
		(layer "In2.Cu")
		(net "M_C_CPU0_SB_DQS_DP<6>")
	)
	(arc
		(start 329.659742 -281.861006)
		(mid 329.475967 -281.810234)
		(end 329.290934 -281.85618)
		(width 0.09525)
		(layer "In2.Cu")
		(net "M_C_CPU0_SB_DQS_DP<6>")
	)
	(arc
		(start 342.819736 -281.861006)
		(mid 342.635961 -281.810234)
		(end 342.450928 -281.85618)
		(width 0.09525)
		(layer "In2.Cu")
		(net "M_C_CPU0_SB_DQS_DP<6>")
	)
	(arc
		(start 332.10246 -281.861006)
		(mid 331.821028 -281.936761)
		(end 331.539596 -281.861006)
		(width 0.09525)
		(layer "In2.Cu")
		(net "M_C_CPU0_SB_DQS_DP<6>")
	)
	(arc
		(start 335.862422 -281.861006)
		(mid 335.58099 -281.936761)
		(end 335.299558 -281.861006)
		(width 0.09525)
		(layer "In2.Cu")
		(net "M_C_CPU0_SB_DQS_DP<6>")
	)
	(arc
		(start 334.922622 -281.861006)
		(mid 334.64119 -281.936761)
		(end 334.359758 -281.861006)
		(width 0.09525)
		(layer "In2.Cu")
		(net "M_C_CPU0_SB_DQS_DP<6>")
	)
	(arc
		(start 338.11972 -281.861006)
		(mid 337.935945 -281.810234)
		(end 337.750912 -281.85618)
		(width 0.09525)
		(layer "In2.Cu")
		(net "M_C_CPU0_SB_DQS_DP<6>")
	)
	(arc
		(start 337.74253 -281.861006)
		(mid 337.461098 -281.936761)
		(end 337.179666 -281.861006)
		(width 0.09525)
		(layer "In2.Cu")
		(net "M_C_CPU0_SB_DQS_DP<6>")
	)
	(arc
		(start 330.222606 -281.861006)
		(mid 329.941174 -281.936761)
		(end 329.659742 -281.861006)
		(width 0.09525)
		(layer "In2.Cu")
		(net "M_C_CPU0_SB_DQS_DP<6>")
	)
	(arc
		(start 339.622638 -281.861006)
		(mid 339.341206 -281.936761)
		(end 339.059774 -281.861006)
		(width 0.09525)
		(layer "In2.Cu")
		(net "M_C_CPU0_SB_DQS_DP<6>")
	)
	(arc
		(start 343.3826 -281.861006)
		(mid 343.101168 -281.936761)
		(end 342.819736 -281.861006)
		(width 0.09525)
		(layer "In2.Cu")
		(net "M_C_CPU0_SB_DQS_DP<6>")
	)
	(arc
		(start 333.042514 -281.861006)
		(mid 332.761082 -281.936761)
		(end 332.47965 -281.861006)
		(width 0.09525)
		(layer "In2.Cu")
		(net "M_C_CPU0_SB_DQS_DP<6>")
	)
	(arc
		(start 336.802476 -281.861006)
		(mid 336.521044 -281.936761)
		(end 336.239612 -281.861006)
		(width 0.09525)
		(layer "In2.Cu")
		(net "M_C_CPU0_SB_DQS_DP<6>")
	)
	(arc
		(start 340.931246 -281.85618)
		(mid 340.746214 -281.810266)
		(end 340.562438 -281.861006)
		(width 0.09525)
		(layer "In2.Cu")
		(net "M_C_CPU0_SB_DQS_DP<6>")
	)
	(arc
		(start 330.599542 -281.861006)
		(mid 330.411074 -281.810329)
		(end 330.222606 -281.861006)
		(width 0.09525)
		(layer "In2.Cu")
		(net "M_C_CPU0_SB_DQS_DP<6>")
	)
	(arc
		(start 341.8713 -281.85618)
		(mid 341.686268 -281.810266)
		(end 341.502492 -281.861006)
		(width 0.09525)
		(layer "In2.Cu")
		(net "M_C_CPU0_SB_DQS_DP<6>")
	)
	(arc
		(start 336.23123 -281.85618)
		(mid 336.046198 -281.810266)
		(end 335.862422 -281.861006)
		(width 0.09525)
		(layer "In2.Cu")
		(net "M_C_CPU0_SB_DQS_DP<6>")
	)
	(arc
		(start 340.562438 -281.861006)
		(mid 340.281006 -281.936761)
		(end 339.999574 -281.861006)
		(width 0.09525)
		(layer "In2.Cu")
		(net "M_C_CPU0_SB_DQS_DP<6>")
	)
	(arc
		(start 328.327766 -281.869642)
		(mid 328.052307 -281.937027)
		(end 327.779126 -281.861006)
		(width 0.09525)
		(layer "In2.Cu")
		(net "M_C_CPU0_SB_DQS_DP<6>")
	)
	(arc
		(start 335.299558 -281.861006)
		(mid 335.11109 -281.810329)
		(end 334.922622 -281.861006)
		(width 0.09525)
		(layer "In2.Cu")
		(net "M_C_CPU0_SB_DQS_DP<6>")
	)
	(arc
		(start 333.982568 -281.861006)
		(mid 333.701136 -281.936761)
		(end 333.419704 -281.861006)
		(width 0.09525)
		(layer "In2.Cu")
		(net "M_C_CPU0_SB_DQS_DP<6>")
	)
	(arc
		(start 337.171284 -281.85618)
		(mid 336.986252 -281.810266)
		(end 336.802476 -281.861006)
		(width 0.09525)
		(layer "In2.Cu")
		(net "M_C_CPU0_SB_DQS_DP<6>")
	)
	(arc
		(start 343.701624 -281.833828)
		(mid 343.543874 -281.811309)
		(end 343.390982 -281.85618)
		(width 0.09525)
		(layer "In2.Cu")
		(net "M_C_CPU0_SB_DQS_DP<6>")
	)
	(arc
		(start 333.419704 -281.861006)
		(mid 333.235929 -281.810234)
		(end 333.050896 -281.85618)
		(width 0.09525)
		(layer "In2.Cu")
		(net "M_C_CPU0_SB_DQS_DP<6>")
	)
	(arc
		(start 329.282552 -281.861006)
		(mid 329.00112 -281.936761)
		(end 328.719688 -281.861006)
		(width 0.09525)
		(layer "In2.Cu")
		(net "M_C_CPU0_SB_DQS_DP<6>")
	)
	(arc
		(start 334.359758 -281.861006)
		(mid 334.175983 -281.810234)
		(end 333.99095 -281.85618)
		(width 0.09525)
		(layer "In2.Cu")
		(net "M_C_CPU0_SB_DQS_DP<6>")
	)
	(arc
		(start 332.471268 -281.85618)
		(mid 332.286236 -281.810266)
		(end 332.10246 -281.861006)
		(width 0.09525)
		(layer "In2.Cu")
		(net "M_C_CPU0_SB_DQS_DP<6>")
	)
	(arc
		(start 339.999574 -281.861006)
		(mid 339.811106 -281.810329)
		(end 339.622638 -281.861006)
		(width 0.09525)
		(layer "In2.Cu")
		(net "M_C_CPU0_SB_DQS_DP<6>")
	)
	(arc
		(start 342.442546 -281.861006)
		(mid 342.161114 -281.936761)
		(end 341.879682 -281.861006)
		(width 0.09525)
		(layer "In2.Cu")
		(net "M_C_CPU0_SB_DQS_DP<6>")
	)
	(segment
		(start 344.03792 -277.060152)
		(end 343.571068 -277.32609)
		(width 0.12954)
		(layer "F.Cu")
		(net "M_C_CPU0_SB_DQS_DP<5>")
	)
	(segment
		(start 298.271438 -286.132524)
		(end 297.880024 -286.523938)
		(width 0.16002)
		(layer "In2.Cu")
		(net "M_C_CPU0_SB_DQS_DP<5>")
	)
	(segment
		(start 290.511484 -286.160972)
		(end 290.361116 -286.31134)
		(width 0.16002)
		(layer "In2.Cu")
		(net "M_C_CPU0_SB_DQS_DP<5>")
	)
	(segment
		(start 288.45383 -286.31134)
		(end 288.180018 -286.585152)
		(width 0.16002)
		(layer "In2.Cu")
		(net "M_C_CPU0_SB_DQS_DP<5>")
	)
	(segment
		(start 302.137318 -287.283144)
		(end 301.66183 -286.807656)
		(width 0.16002)
		(layer "In2.Cu")
		(net "M_C_CPU0_SB_DQS_DP<5>")
	)
	(segment
		(start 304.756566 -286.851344)
		(end 304.486818 -286.963104)
		(width 0.16002)
		(layer "In2.Cu")
		(net "M_C_CPU0_SB_DQS_DP<5>")
	)
	(segment
		(start 333.99095 -276.996144)
		(end 333.982568 -277.00097)
		(width 0.09525)
		(layer "In2.Cu")
		(net "M_C_CPU0_SB_DQS_DP<5>")
	)
	(segment
		(start 306.452016 -286.419544)
		(end 306.193444 -286.160972)
		(width 0.16002)
		(layer "In2.Cu")
		(net "M_C_CPU0_SB_DQS_DP<5>")
	)
	(segment
		(start 297.880024 -286.523938)
		(end 297.043094 -286.870648)
		(width 0.16002)
		(layer "In2.Cu")
		(net "M_C_CPU0_SB_DQS_DP<5>")
	)
	(segment
		(start 328.342498 -277.00097)
		(end 328.327766 -277.009606)
		(width 0.09525)
		(layer "In2.Cu")
		(net "M_C_CPU0_SB_DQS_DP<5>")
	)
	(segment
		(start 341.879682 -277.00097)
		(end 341.8713 -276.996144)
		(width 0.09525)
		(layer "In2.Cu")
		(net "M_C_CPU0_SB_DQS_DP<5>")
	)
	(segment
		(start 309.878476 -285.902654)
		(end 309.434738 -286.086296)
		(width 0.16002)
		(layer "In2.Cu")
		(net "M_C_CPU0_SB_DQS_DP<5>")
	)
	(segment
		(start 298.634658 -286.132524)
		(end 298.271438 -286.132524)
		(width 0.16002)
		(layer "In2.Cu")
		(net "M_C_CPU0_SB_DQS_DP<5>")
	)
	(segment
		(start 343.390982 -276.996144)
		(end 343.3826 -277.00097)
		(width 0.09525)
		(layer "In2.Cu")
		(net "M_C_CPU0_SB_DQS_DP<5>")
	)
	(segment
		(start 296.60342 -287.310322)
		(end 294.640508 -287.310322)
		(width 0.16002)
		(layer "In2.Cu")
		(net "M_C_CPU0_SB_DQS_DP<5>")
	)
	(segment
		(start 309.282084 -286.02305)
		(end 308.325012 -286.419544)
		(width 0.16002)
		(layer "In2.Cu")
		(net "M_C_CPU0_SB_DQS_DP<5>")
	)
	(segment
		(start 323.895974 -276.35073)
		(end 319.60058 -276.35073)
		(width 0.16002)
		(layer "In2.Cu")
		(net "M_C_CPU0_SB_DQS_DP<5>")
	)
	(segment
		(start 340.939628 -277.00097)
		(end 340.931246 -276.996144)
		(width 0.09525)
		(layer "In2.Cu")
		(net "M_C_CPU0_SB_DQS_DP<5>")
	)
	(segment
		(start 297.043094 -286.870648)
		(end 296.60342 -287.310322)
		(width 0.16002)
		(layer "In2.Cu")
		(net "M_C_CPU0_SB_DQS_DP<5>")
	)
	(segment
		(start 293.80053 -286.719518)
		(end 292.022022 -286.719518)
		(width 0.16002)
		(layer "In2.Cu")
		(net "M_C_CPU0_SB_DQS_DP<5>")
	)
	(segment
		(start 294.640508 -287.310322)
		(end 294.22598 -286.895794)
		(width 0.16002)
		(layer "In2.Cu")
		(net "M_C_CPU0_SB_DQS_DP<5>")
	)
	(segment
		(start 328.719688 -277.00097)
		(end 328.711306 -276.996144)
		(width 0.09525)
		(layer "In2.Cu")
		(net "M_C_CPU0_SB_DQS_DP<5>")
	)
	(segment
		(start 291.095684 -286.160972)
		(end 290.511484 -286.160972)
		(width 0.16002)
		(layer "In2.Cu")
		(net "M_C_CPU0_SB_DQS_DP<5>")
	)
	(segment
		(start 337.179666 -277.00097)
		(end 337.171284 -276.996144)
		(width 0.09525)
		(layer "In2.Cu")
		(net "M_C_CPU0_SB_DQS_DP<5>")
	)
	(segment
		(start 292.022022 -286.719518)
		(end 291.394134 -286.459422)
		(width 0.16002)
		(layer "In2.Cu")
		(net "M_C_CPU0_SB_DQS_DP<5>")
	)
	(segment
		(start 304.166778 -287.283144)
		(end 302.137318 -287.283144)
		(width 0.16002)
		(layer "In2.Cu")
		(net "M_C_CPU0_SB_DQS_DP<5>")
	)
	(segment
		(start 319.60058 -276.35073)
		(end 310.385206 -285.566104)
		(width 0.16002)
		(layer "In2.Cu")
		(net "M_C_CPU0_SB_DQS_DP<5>")
	)
	(segment
		(start 323.919596 -276.35073)
		(end 323.895974 -276.35073)
		(width 0.09525)
		(layer "In2.Cu")
		(net "M_C_CPU0_SB_DQS_DP<5>")
	)
	(segment
		(start 329.290934 -276.996144)
		(end 329.282552 -277.00097)
		(width 0.09525)
		(layer "In2.Cu")
		(net "M_C_CPU0_SB_DQS_DP<5>")
	)
	(segment
		(start 310.385206 -285.566104)
		(end 309.941722 -285.749746)
		(width 0.16002)
		(layer "In2.Cu")
		(net "M_C_CPU0_SB_DQS_DP<5>")
	)
	(segment
		(start 338.690966 -276.996144)
		(end 338.682584 -277.00097)
		(width 0.09525)
		(layer "In2.Cu")
		(net "M_C_CPU0_SB_DQS_DP<5>")
	)
	(segment
		(start 326.651366 -276.949916)
		(end 325.30415 -276.949916)
		(width 0.09525)
		(layer "In2.Cu")
		(net "M_C_CPU0_SB_DQS_DP<5>")
	)
	(segment
		(start 324.260464 -276.291802)
		(end 323.978524 -276.291802)
		(width 0.09525)
		(layer "In2.Cu")
		(net "M_C_CPU0_SB_DQS_DP<5>")
	)
	(segment
		(start 305.78933 -286.160972)
		(end 304.756566 -286.851344)
		(width 0.16002)
		(layer "In2.Cu")
		(net "M_C_CPU0_SB_DQS_DP<5>")
	)
	(segment
		(start 343.724992 -277.06066)
		(end 343.701624 -276.973792)
		(width 0.09525)
		(layer "In2.Cu")
		(net "M_C_CPU0_SB_DQS_DP<5>")
	)
	(segment
		(start 308.325012 -286.419544)
		(end 306.452016 -286.419544)
		(width 0.16002)
		(layer "In2.Cu")
		(net "M_C_CPU0_SB_DQS_DP<5>")
	)
	(segment
		(start 294.22598 -286.895794)
		(end 293.80053 -286.719518)
		(width 0.16002)
		(layer "In2.Cu")
		(net "M_C_CPU0_SB_DQS_DP<5>")
	)
	(segment
		(start 333.050896 -276.996144)
		(end 333.042514 -277.00097)
		(width 0.09525)
		(layer "In2.Cu")
		(net "M_C_CPU0_SB_DQS_DP<5>")
	)
	(segment
		(start 309.941722 -285.749746)
		(end 309.878476 -285.902654)
		(width 0.16002)
		(layer "In2.Cu")
		(net "M_C_CPU0_SB_DQS_DP<5>")
	)
	(segment
		(start 336.239612 -277.00097)
		(end 336.23123 -276.996144)
		(width 0.09525)
		(layer "In2.Cu")
		(net "M_C_CPU0_SB_DQS_DP<5>")
	)
	(segment
		(start 290.361116 -286.31134)
		(end 288.45383 -286.31134)
		(width 0.16002)
		(layer "In2.Cu")
		(net "M_C_CPU0_SB_DQS_DP<5>")
	)
	(segment
		(start 304.486818 -286.963104)
		(end 304.166778 -287.283144)
		(width 0.16002)
		(layer "In2.Cu")
		(net "M_C_CPU0_SB_DQS_DP<5>")
	)
	(segment
		(start 327.41362 -276.994112)
		(end 327.401682 -277.00097)
		(width 0.09525)
		(layer "In2.Cu")
		(net "M_C_CPU0_SB_DQS_DP<5>")
	)
	(segment
		(start 342.450928 -276.996144)
		(end 342.442546 -277.00097)
		(width 0.09525)
		(layer "In2.Cu")
		(net "M_C_CPU0_SB_DQS_DP<5>")
	)
	(segment
		(start 300.822868 -286.460184)
		(end 298.962318 -286.460184)
		(width 0.16002)
		(layer "In2.Cu")
		(net "M_C_CPU0_SB_DQS_DP<5>")
	)
	(segment
		(start 326.842628 -277.002748)
		(end 326.839326 -277.00097)
		(width 0.09525)
		(layer "In2.Cu")
		(net "M_C_CPU0_SB_DQS_DP<5>")
	)
	(segment
		(start 309.434738 -286.086296)
		(end 309.282084 -286.02305)
		(width 0.16002)
		(layer "In2.Cu")
		(net "M_C_CPU0_SB_DQS_DP<5>")
	)
	(segment
		(start 324.646036 -276.677374)
		(end 324.260464 -276.291802)
		(width 0.09525)
		(layer "In2.Cu")
		(net "M_C_CPU0_SB_DQS_DP<5>")
	)
	(segment
		(start 337.750912 -276.996144)
		(end 337.74253 -277.00097)
		(width 0.09525)
		(layer "In2.Cu")
		(net "M_C_CPU0_SB_DQS_DP<5>")
	)
	(segment
		(start 332.47965 -277.00097)
		(end 332.471268 -276.996144)
		(width 0.09525)
		(layer "In2.Cu")
		(net "M_C_CPU0_SB_DQS_DP<5>")
	)
	(segment
		(start 298.962318 -286.460184)
		(end 298.634658 -286.132524)
		(width 0.16002)
		(layer "In2.Cu")
		(net "M_C_CPU0_SB_DQS_DP<5>")
	)
	(segment
		(start 323.978524 -276.291802)
		(end 323.919596 -276.35073)
		(width 0.09525)
		(layer "In2.Cu")
		(net "M_C_CPU0_SB_DQS_DP<5>")
	)
	(segment
		(start 291.394134 -286.459422)
		(end 291.095684 -286.160972)
		(width 0.16002)
		(layer "In2.Cu")
		(net "M_C_CPU0_SB_DQS_DP<5>")
	)
	(segment
		(start 343.571068 -277.32609)
		(end 343.724992 -277.06066)
		(width 0.09525)
		(layer "In2.Cu")
		(net "M_C_CPU0_SB_DQS_DP<5>")
	)
	(segment
		(start 306.193444 -286.160972)
		(end 305.78933 -286.160972)
		(width 0.16002)
		(layer "In2.Cu")
		(net "M_C_CPU0_SB_DQS_DP<5>")
	)
	(segment
		(start 301.66183 -286.807656)
		(end 300.822868 -286.460184)
		(width 0.16002)
		(layer "In2.Cu")
		(net "M_C_CPU0_SB_DQS_DP<5>")
	)
	(segment
		(start 325.30415 -276.949916)
		(end 324.646036 -276.677374)
		(width 0.09525)
		(layer "In2.Cu")
		(net "M_C_CPU0_SB_DQS_DP<5>")
	)
	(segment
		(start 331.539596 -277.00097)
		(end 331.531214 -276.996144)
		(width 0.09525)
		(layer "In2.Cu")
		(net "M_C_CPU0_SB_DQS_DP<5>")
	)
	(segment
		(start 326.854058 -277.009606)
		(end 326.842628 -277.002748)
		(width 0.09525)
		(layer "In2.Cu")
		(net "M_C_CPU0_SB_DQS_DP<5>")
	)
	(arc
		(start 328.327766 -277.009606)
		(mid 328.052307 -277.076991)
		(end 327.779126 -277.00097)
		(width 0.09525)
		(layer "In2.Cu")
		(net "M_C_CPU0_SB_DQS_DP<5>")
	)
	(arc
		(start 333.042514 -277.00097)
		(mid 332.761082 -277.076725)
		(end 332.47965 -277.00097)
		(width 0.09525)
		(layer "In2.Cu")
		(net "M_C_CPU0_SB_DQS_DP<5>")
	)
	(arc
		(start 332.10246 -277.00097)
		(mid 331.821028 -277.076725)
		(end 331.539596 -277.00097)
		(width 0.09525)
		(layer "In2.Cu")
		(net "M_C_CPU0_SB_DQS_DP<5>")
	)
	(arc
		(start 343.701624 -276.973792)
		(mid 343.543874 -276.951273)
		(end 343.390982 -276.996144)
		(width 0.09525)
		(layer "In2.Cu")
		(net "M_C_CPU0_SB_DQS_DP<5>")
	)
	(arc
		(start 335.862422 -277.00097)
		(mid 335.58099 -277.076725)
		(end 335.299558 -277.00097)
		(width 0.09525)
		(layer "In2.Cu")
		(net "M_C_CPU0_SB_DQS_DP<5>")
	)
	(arc
		(start 340.931246 -276.996144)
		(mid 340.746214 -276.95023)
		(end 340.562438 -277.00097)
		(width 0.09525)
		(layer "In2.Cu")
		(net "M_C_CPU0_SB_DQS_DP<5>")
	)
	(arc
		(start 331.162406 -277.00097)
		(mid 330.880974 -277.076725)
		(end 330.599542 -277.00097)
		(width 0.09525)
		(layer "In2.Cu")
		(net "M_C_CPU0_SB_DQS_DP<5>")
	)
	(arc
		(start 336.802476 -277.00097)
		(mid 336.521044 -277.076725)
		(end 336.239612 -277.00097)
		(width 0.09525)
		(layer "In2.Cu")
		(net "M_C_CPU0_SB_DQS_DP<5>")
	)
	(arc
		(start 329.659742 -277.00097)
		(mid 329.475967 -276.950198)
		(end 329.290934 -276.996144)
		(width 0.09525)
		(layer "In2.Cu")
		(net "M_C_CPU0_SB_DQS_DP<5>")
	)
	(arc
		(start 334.922622 -277.00097)
		(mid 334.64119 -277.076725)
		(end 334.359758 -277.00097)
		(width 0.09525)
		(layer "In2.Cu")
		(net "M_C_CPU0_SB_DQS_DP<5>")
	)
	(arc
		(start 334.359758 -277.00097)
		(mid 334.175983 -276.950198)
		(end 333.99095 -276.996144)
		(width 0.09525)
		(layer "In2.Cu")
		(net "M_C_CPU0_SB_DQS_DP<5>")
	)
	(arc
		(start 342.819736 -277.00097)
		(mid 342.635961 -276.950198)
		(end 342.450928 -276.996144)
		(width 0.09525)
		(layer "In2.Cu")
		(net "M_C_CPU0_SB_DQS_DP<5>")
	)
	(arc
		(start 328.711306 -276.996144)
		(mid 328.526274 -276.95023)
		(end 328.342498 -277.00097)
		(width 0.09525)
		(layer "In2.Cu")
		(net "M_C_CPU0_SB_DQS_DP<5>")
	)
	(arc
		(start 331.531214 -276.996144)
		(mid 331.346182 -276.95023)
		(end 331.162406 -277.00097)
		(width 0.09525)
		(layer "In2.Cu")
		(net "M_C_CPU0_SB_DQS_DP<5>")
	)
	(arc
		(start 339.999574 -277.00097)
		(mid 339.811106 -276.950293)
		(end 339.622638 -277.00097)
		(width 0.09525)
		(layer "In2.Cu")
		(net "M_C_CPU0_SB_DQS_DP<5>")
	)
	(arc
		(start 339.622638 -277.00097)
		(mid 339.341206 -277.076725)
		(end 339.059774 -277.00097)
		(width 0.09525)
		(layer "In2.Cu")
		(net "M_C_CPU0_SB_DQS_DP<5>")
	)
	(arc
		(start 338.11972 -277.00097)
		(mid 337.935945 -276.950198)
		(end 337.750912 -276.996144)
		(width 0.09525)
		(layer "In2.Cu")
		(net "M_C_CPU0_SB_DQS_DP<5>")
	)
	(arc
		(start 332.471268 -276.996144)
		(mid 332.286236 -276.95023)
		(end 332.10246 -277.00097)
		(width 0.09525)
		(layer "In2.Cu")
		(net "M_C_CPU0_SB_DQS_DP<5>")
	)
	(arc
		(start 338.682584 -277.00097)
		(mid 338.401152 -277.076725)
		(end 338.11972 -277.00097)
		(width 0.09525)
		(layer "In2.Cu")
		(net "M_C_CPU0_SB_DQS_DP<5>")
	)
	(arc
		(start 327.401682 -277.00097)
		(mid 327.129008 -277.076657)
		(end 326.854058 -277.009606)
		(width 0.09525)
		(layer "In2.Cu")
		(net "M_C_CPU0_SB_DQS_DP<5>")
	)
	(arc
		(start 326.839326 -277.00097)
		(mid 326.748712 -276.96304)
		(end 326.651366 -276.949916)
		(width 0.09525)
		(layer "In2.Cu")
		(net "M_C_CPU0_SB_DQS_DP<5>")
	)
	(arc
		(start 340.562438 -277.00097)
		(mid 340.281006 -277.076725)
		(end 339.999574 -277.00097)
		(width 0.09525)
		(layer "In2.Cu")
		(net "M_C_CPU0_SB_DQS_DP<5>")
	)
	(arc
		(start 333.982568 -277.00097)
		(mid 333.701136 -277.076725)
		(end 333.419704 -277.00097)
		(width 0.09525)
		(layer "In2.Cu")
		(net "M_C_CPU0_SB_DQS_DP<5>")
	)
	(arc
		(start 337.74253 -277.00097)
		(mid 337.461098 -277.076725)
		(end 337.179666 -277.00097)
		(width 0.09525)
		(layer "In2.Cu")
		(net "M_C_CPU0_SB_DQS_DP<5>")
	)
	(arc
		(start 327.779126 -277.00097)
		(mid 327.597256 -276.950105)
		(end 327.41362 -276.994112)
		(width 0.09525)
		(layer "In2.Cu")
		(net "M_C_CPU0_SB_DQS_DP<5>")
	)
	(arc
		(start 341.8713 -276.996144)
		(mid 341.686268 -276.95023)
		(end 341.502492 -277.00097)
		(width 0.09525)
		(layer "In2.Cu")
		(net "M_C_CPU0_SB_DQS_DP<5>")
	)
	(arc
		(start 330.599542 -277.00097)
		(mid 330.411074 -276.950293)
		(end 330.222606 -277.00097)
		(width 0.09525)
		(layer "In2.Cu")
		(net "M_C_CPU0_SB_DQS_DP<5>")
	)
	(arc
		(start 336.23123 -276.996144)
		(mid 336.046198 -276.95023)
		(end 335.862422 -277.00097)
		(width 0.09525)
		(layer "In2.Cu")
		(net "M_C_CPU0_SB_DQS_DP<5>")
	)
	(arc
		(start 335.299558 -277.00097)
		(mid 335.11109 -276.950293)
		(end 334.922622 -277.00097)
		(width 0.09525)
		(layer "In2.Cu")
		(net "M_C_CPU0_SB_DQS_DP<5>")
	)
	(arc
		(start 329.282552 -277.00097)
		(mid 329.00112 -277.076725)
		(end 328.719688 -277.00097)
		(width 0.09525)
		(layer "In2.Cu")
		(net "M_C_CPU0_SB_DQS_DP<5>")
	)
	(arc
		(start 330.222606 -277.00097)
		(mid 329.941174 -277.076725)
		(end 329.659742 -277.00097)
		(width 0.09525)
		(layer "In2.Cu")
		(net "M_C_CPU0_SB_DQS_DP<5>")
	)
	(arc
		(start 342.442546 -277.00097)
		(mid 342.161114 -277.076725)
		(end 341.879682 -277.00097)
		(width 0.09525)
		(layer "In2.Cu")
		(net "M_C_CPU0_SB_DQS_DP<5>")
	)
	(arc
		(start 337.171284 -276.996144)
		(mid 336.986252 -276.95023)
		(end 336.802476 -277.00097)
		(width 0.09525)
		(layer "In2.Cu")
		(net "M_C_CPU0_SB_DQS_DP<5>")
	)
	(arc
		(start 339.059774 -277.00097)
		(mid 338.875999 -276.950198)
		(end 338.690966 -276.996144)
		(width 0.09525)
		(layer "In2.Cu")
		(net "M_C_CPU0_SB_DQS_DP<5>")
	)
	(arc
		(start 341.502492 -277.00097)
		(mid 341.22106 -277.076725)
		(end 340.939628 -277.00097)
		(width 0.09525)
		(layer "In2.Cu")
		(net "M_C_CPU0_SB_DQS_DP<5>")
	)
	(arc
		(start 343.3826 -277.00097)
		(mid 343.101168 -277.076725)
		(end 342.819736 -277.00097)
		(width 0.09525)
		(layer "In2.Cu")
		(net "M_C_CPU0_SB_DQS_DP<5>")
	)
	(arc
		(start 333.419704 -277.00097)
		(mid 333.235929 -276.950198)
		(end 333.050896 -276.996144)
		(width 0.09525)
		(layer "In2.Cu")
		(net "M_C_CPU0_SB_DQS_DP<5>")
	)
	(segment
		(start 344.03792 -272.200116)
		(end 343.571068 -272.466054)
		(width 0.12954)
		(layer "F.Cu")
		(net "M_C_CPU0_SB_DQS_DP<4>")
	)
	(segment
		(start 289.315144 -277.078186)
		(end 289.795204 -277.078186)
		(width 0.16002)
		(layer "In2.Cu")
		(net "M_C_CPU0_SB_DQS_DP<4>")
	)
	(segment
		(start 323.919596 -270.72717)
		(end 323.978524 -270.668242)
		(width 0.09525)
		(layer "In2.Cu")
		(net "M_C_CPU0_SB_DQS_DP<4>")
	)
	(segment
		(start 333.982568 -272.140934)
		(end 333.99095 -272.136108)
		(width 0.09525)
		(layer "In2.Cu")
		(net "M_C_CPU0_SB_DQS_DP<4>")
	)
	(segment
		(start 289.198304 -276.961346)
		(end 289.315144 -277.078186)
		(width 0.16002)
		(layer "In2.Cu")
		(net "M_C_CPU0_SB_DQS_DP<4>")
	)
	(segment
		(start 298.179236 -276.874732)
		(end 298.271438 -276.78253)
		(width 0.16002)
		(layer "In2.Cu")
		(net "M_C_CPU0_SB_DQS_DP<4>")
	)
	(segment
		(start 288.180018 -277.235158)
		(end 288.45383 -276.961346)
		(width 0.16002)
		(layer "In2.Cu")
		(net "M_C_CPU0_SB_DQS_DP<4>")
	)
	(segment
		(start 343.701624 -272.113756)
		(end 343.724992 -272.200624)
		(width 0.09525)
		(layer "In2.Cu")
		(net "M_C_CPU0_SB_DQS_DP<4>")
	)
	(segment
		(start 297.22318 -277.513542)
		(end 298.179236 -276.874732)
		(width 0.16002)
		(layer "In2.Cu")
		(net "M_C_CPU0_SB_DQS_DP<4>")
	)
	(segment
		(start 302.100742 -277.93315)
		(end 304.193702 -277.93315)
		(width 0.16002)
		(layer "In2.Cu")
		(net "M_C_CPU0_SB_DQS_DP<4>")
	)
	(segment
		(start 331.531214 -272.136108)
		(end 331.539596 -272.140934)
		(width 0.09525)
		(layer "In2.Cu")
		(net "M_C_CPU0_SB_DQS_DP<4>")
	)
	(segment
		(start 290.544758 -276.808692)
		(end 291.080698 -276.808692)
		(width 0.16002)
		(layer "In2.Cu")
		(net "M_C_CPU0_SB_DQS_DP<4>")
	)
	(segment
		(start 298.585382 -276.78253)
		(end 298.913042 -277.11019)
		(width 0.16002)
		(layer "In2.Cu")
		(net "M_C_CPU0_SB_DQS_DP<4>")
	)
	(segment
		(start 326.282812 -272.08988)
		(end 326.651112 -272.08988)
		(width 0.09525)
		(layer "In2.Cu")
		(net "M_C_CPU0_SB_DQS_DP<4>")
	)
	(segment
		(start 327.401682 -272.140934)
		(end 327.41362 -272.134076)
		(width 0.09525)
		(layer "In2.Cu")
		(net "M_C_CPU0_SB_DQS_DP<4>")
	)
	(segment
		(start 296.927778 -277.63597)
		(end 297.22318 -277.513542)
		(width 0.16002)
		(layer "In2.Cu")
		(net "M_C_CPU0_SB_DQS_DP<4>")
	)
	(segment
		(start 333.042514 -272.140934)
		(end 333.050896 -272.136108)
		(width 0.09525)
		(layer "In2.Cu")
		(net "M_C_CPU0_SB_DQS_DP<4>")
	)
	(segment
		(start 336.23123 -272.136108)
		(end 336.239612 -272.140934)
		(width 0.09525)
		(layer "In2.Cu")
		(net "M_C_CPU0_SB_DQS_DP<4>")
	)
	(segment
		(start 300.964854 -277.174452)
		(end 302.100742 -277.93315)
		(width 0.16002)
		(layer "In2.Cu")
		(net "M_C_CPU0_SB_DQS_DP<4>")
	)
	(segment
		(start 306.452016 -277.06955)
		(end 308.326282 -277.06955)
		(width 0.16002)
		(layer "In2.Cu")
		(net "M_C_CPU0_SB_DQS_DP<4>")
	)
	(segment
		(start 296.60342 -277.960328)
		(end 296.927778 -277.63597)
		(width 0.16002)
		(layer "In2.Cu")
		(net "M_C_CPU0_SB_DQS_DP<4>")
	)
	(segment
		(start 290.392104 -276.961346)
		(end 290.544758 -276.808692)
		(width 0.16002)
		(layer "In2.Cu")
		(net "M_C_CPU0_SB_DQS_DP<4>")
	)
	(segment
		(start 324.72249 -270.917924)
		(end 325.110856 -270.917924)
		(width 0.09525)
		(layer "In2.Cu")
		(net "M_C_CPU0_SB_DQS_DP<4>")
	)
	(segment
		(start 340.931246 -272.136108)
		(end 340.939628 -272.140934)
		(width 0.09525)
		(layer "In2.Cu")
		(net "M_C_CPU0_SB_DQS_DP<4>")
	)
	(segment
		(start 324.472808 -270.668242)
		(end 324.72249 -270.917924)
		(width 0.09525)
		(layer "In2.Cu")
		(net "M_C_CPU0_SB_DQS_DP<4>")
	)
	(segment
		(start 289.795204 -277.078186)
		(end 289.912044 -276.961346)
		(width 0.16002)
		(layer "In2.Cu")
		(net "M_C_CPU0_SB_DQS_DP<4>")
	)
	(segment
		(start 298.271438 -276.78253)
		(end 298.585382 -276.78253)
		(width 0.16002)
		(layer "In2.Cu")
		(net "M_C_CPU0_SB_DQS_DP<4>")
	)
	(segment
		(start 304.193702 -277.93315)
		(end 304.445162 -277.681944)
		(width 0.16002)
		(layer "In2.Cu")
		(net "M_C_CPU0_SB_DQS_DP<4>")
	)
	(segment
		(start 289.912044 -276.961346)
		(end 290.392104 -276.961346)
		(width 0.16002)
		(layer "In2.Cu")
		(net "M_C_CPU0_SB_DQS_DP<4>")
	)
	(segment
		(start 338.682584 -272.140934)
		(end 338.690966 -272.136108)
		(width 0.09525)
		(layer "In2.Cu")
		(net "M_C_CPU0_SB_DQS_DP<4>")
	)
	(segment
		(start 305.747928 -276.810978)
		(end 306.193444 -276.810978)
		(width 0.16002)
		(layer "In2.Cu")
		(net "M_C_CPU0_SB_DQS_DP<4>")
	)
	(segment
		(start 291.080698 -276.808692)
		(end 291.64153 -277.369524)
		(width 0.16002)
		(layer "In2.Cu")
		(net "M_C_CPU0_SB_DQS_DP<4>")
	)
	(segment
		(start 304.445162 -277.681944)
		(end 305.747928 -276.810978)
		(width 0.16002)
		(layer "In2.Cu")
		(net "M_C_CPU0_SB_DQS_DP<4>")
	)
	(segment
		(start 308.326282 -277.06955)
		(end 314.668662 -270.72717)
		(width 0.16002)
		(layer "In2.Cu")
		(net "M_C_CPU0_SB_DQS_DP<4>")
	)
	(segment
		(start 323.895974 -270.72717)
		(end 323.919596 -270.72717)
		(width 0.09525)
		(layer "In2.Cu")
		(net "M_C_CPU0_SB_DQS_DP<4>")
	)
	(segment
		(start 341.8713 -272.136108)
		(end 341.879682 -272.140934)
		(width 0.09525)
		(layer "In2.Cu")
		(net "M_C_CPU0_SB_DQS_DP<4>")
	)
	(segment
		(start 300.809914 -277.11019)
		(end 300.964854 -277.174452)
		(width 0.16002)
		(layer "In2.Cu")
		(net "M_C_CPU0_SB_DQS_DP<4>")
	)
	(segment
		(start 306.193444 -276.810978)
		(end 306.452016 -277.06955)
		(width 0.16002)
		(layer "In2.Cu")
		(net "M_C_CPU0_SB_DQS_DP<4>")
	)
	(segment
		(start 343.724992 -272.200624)
		(end 343.571068 -272.466054)
		(width 0.09525)
		(layer "In2.Cu")
		(net "M_C_CPU0_SB_DQS_DP<4>")
	)
	(segment
		(start 288.45383 -276.961346)
		(end 289.198304 -276.961346)
		(width 0.16002)
		(layer "In2.Cu")
		(net "M_C_CPU0_SB_DQS_DP<4>")
	)
	(segment
		(start 337.74253 -272.140934)
		(end 337.750912 -272.136108)
		(width 0.09525)
		(layer "In2.Cu")
		(net "M_C_CPU0_SB_DQS_DP<4>")
	)
	(segment
		(start 325.110856 -270.917924)
		(end 326.282812 -272.08988)
		(width 0.09525)
		(layer "In2.Cu")
		(net "M_C_CPU0_SB_DQS_DP<4>")
	)
	(segment
		(start 342.442546 -272.140934)
		(end 342.450928 -272.136108)
		(width 0.09525)
		(layer "In2.Cu")
		(net "M_C_CPU0_SB_DQS_DP<4>")
	)
	(segment
		(start 323.978524 -270.668242)
		(end 324.472808 -270.668242)
		(width 0.09525)
		(layer "In2.Cu")
		(net "M_C_CPU0_SB_DQS_DP<4>")
	)
	(segment
		(start 326.839326 -272.140934)
		(end 326.854058 -272.14957)
		(width 0.09525)
		(layer "In2.Cu")
		(net "M_C_CPU0_SB_DQS_DP<4>")
	)
	(segment
		(start 343.3826 -272.140934)
		(end 343.390982 -272.136108)
		(width 0.09525)
		(layer "In2.Cu")
		(net "M_C_CPU0_SB_DQS_DP<4>")
	)
	(segment
		(start 291.64153 -277.369524)
		(end 293.162736 -277.369524)
		(width 0.16002)
		(layer "In2.Cu")
		(net "M_C_CPU0_SB_DQS_DP<4>")
	)
	(segment
		(start 329.282552 -272.140934)
		(end 329.290934 -272.136108)
		(width 0.09525)
		(layer "In2.Cu")
		(net "M_C_CPU0_SB_DQS_DP<4>")
	)
	(segment
		(start 298.913042 -277.11019)
		(end 300.809914 -277.11019)
		(width 0.16002)
		(layer "In2.Cu")
		(net "M_C_CPU0_SB_DQS_DP<4>")
	)
	(segment
		(start 337.171284 -272.136108)
		(end 337.179666 -272.140934)
		(width 0.09525)
		(layer "In2.Cu")
		(net "M_C_CPU0_SB_DQS_DP<4>")
	)
	(segment
		(start 293.162736 -277.369524)
		(end 294.5892 -277.960328)
		(width 0.16002)
		(layer "In2.Cu")
		(net "M_C_CPU0_SB_DQS_DP<4>")
	)
	(segment
		(start 328.711306 -272.136108)
		(end 328.719688 -272.140934)
		(width 0.09525)
		(layer "In2.Cu")
		(net "M_C_CPU0_SB_DQS_DP<4>")
	)
	(segment
		(start 314.668662 -270.72717)
		(end 323.895974 -270.72717)
		(width 0.16002)
		(layer "In2.Cu")
		(net "M_C_CPU0_SB_DQS_DP<4>")
	)
	(segment
		(start 328.327766 -272.14957)
		(end 328.342498 -272.140934)
		(width 0.09525)
		(layer "In2.Cu")
		(net "M_C_CPU0_SB_DQS_DP<4>")
	)
	(segment
		(start 332.471268 -272.136108)
		(end 332.47965 -272.140934)
		(width 0.09525)
		(layer "In2.Cu")
		(net "M_C_CPU0_SB_DQS_DP<4>")
	)
	(segment
		(start 294.5892 -277.960328)
		(end 296.60342 -277.960328)
		(width 0.16002)
		(layer "In2.Cu")
		(net "M_C_CPU0_SB_DQS_DP<4>")
	)
	(arc
		(start 341.879682 -272.140934)
		(mid 342.161114 -272.216689)
		(end 342.442546 -272.140934)
		(width 0.09525)
		(layer "In2.Cu")
		(net "M_C_CPU0_SB_DQS_DP<4>")
	)
	(arc
		(start 329.659742 -272.140934)
		(mid 329.941174 -272.216689)
		(end 330.222606 -272.140934)
		(width 0.09525)
		(layer "In2.Cu")
		(net "M_C_CPU0_SB_DQS_DP<4>")
	)
	(arc
		(start 338.690966 -272.136108)
		(mid 338.875998 -272.090194)
		(end 339.059774 -272.140934)
		(width 0.09525)
		(layer "In2.Cu")
		(net "M_C_CPU0_SB_DQS_DP<4>")
	)
	(arc
		(start 339.999574 -272.140934)
		(mid 340.281006 -272.216689)
		(end 340.562438 -272.140934)
		(width 0.09525)
		(layer "In2.Cu")
		(net "M_C_CPU0_SB_DQS_DP<4>")
	)
	(arc
		(start 330.222606 -272.140934)
		(mid 330.411074 -272.090257)
		(end 330.599542 -272.140934)
		(width 0.09525)
		(layer "In2.Cu")
		(net "M_C_CPU0_SB_DQS_DP<4>")
	)
	(arc
		(start 336.802476 -272.140934)
		(mid 336.986251 -272.090162)
		(end 337.171284 -272.136108)
		(width 0.09525)
		(layer "In2.Cu")
		(net "M_C_CPU0_SB_DQS_DP<4>")
	)
	(arc
		(start 326.651112 -272.08988)
		(mid 326.74858 -272.103008)
		(end 326.839326 -272.140934)
		(width 0.09525)
		(layer "In2.Cu")
		(net "M_C_CPU0_SB_DQS_DP<4>")
	)
	(arc
		(start 334.359758 -272.140934)
		(mid 334.64119 -272.216689)
		(end 334.922622 -272.140934)
		(width 0.09525)
		(layer "In2.Cu")
		(net "M_C_CPU0_SB_DQS_DP<4>")
	)
	(arc
		(start 331.539596 -272.140934)
		(mid 331.821028 -272.216689)
		(end 332.10246 -272.140934)
		(width 0.09525)
		(layer "In2.Cu")
		(net "M_C_CPU0_SB_DQS_DP<4>")
	)
	(arc
		(start 342.819736 -272.140934)
		(mid 343.101168 -272.216689)
		(end 343.3826 -272.140934)
		(width 0.09525)
		(layer "In2.Cu")
		(net "M_C_CPU0_SB_DQS_DP<4>")
	)
	(arc
		(start 337.179666 -272.140934)
		(mid 337.461098 -272.216689)
		(end 337.74253 -272.140934)
		(width 0.09525)
		(layer "In2.Cu")
		(net "M_C_CPU0_SB_DQS_DP<4>")
	)
	(arc
		(start 339.622638 -272.140934)
		(mid 339.811106 -272.090257)
		(end 339.999574 -272.140934)
		(width 0.09525)
		(layer "In2.Cu")
		(net "M_C_CPU0_SB_DQS_DP<4>")
	)
	(arc
		(start 327.41362 -272.134076)
		(mid 327.597255 -272.090126)
		(end 327.779126 -272.140934)
		(width 0.09525)
		(layer "In2.Cu")
		(net "M_C_CPU0_SB_DQS_DP<4>")
	)
	(arc
		(start 335.862422 -272.140934)
		(mid 336.046197 -272.090162)
		(end 336.23123 -272.136108)
		(width 0.09525)
		(layer "In2.Cu")
		(net "M_C_CPU0_SB_DQS_DP<4>")
	)
	(arc
		(start 327.779126 -272.140934)
		(mid 328.052308 -272.216876)
		(end 328.327766 -272.14957)
		(width 0.09525)
		(layer "In2.Cu")
		(net "M_C_CPU0_SB_DQS_DP<4>")
	)
	(arc
		(start 340.562438 -272.140934)
		(mid 340.746213 -272.090162)
		(end 340.931246 -272.136108)
		(width 0.09525)
		(layer "In2.Cu")
		(net "M_C_CPU0_SB_DQS_DP<4>")
	)
	(arc
		(start 333.050896 -272.136108)
		(mid 333.235928 -272.090194)
		(end 333.419704 -272.140934)
		(width 0.09525)
		(layer "In2.Cu")
		(net "M_C_CPU0_SB_DQS_DP<4>")
	)
	(arc
		(start 333.99095 -272.136108)
		(mid 334.175982 -272.090194)
		(end 334.359758 -272.140934)
		(width 0.09525)
		(layer "In2.Cu")
		(net "M_C_CPU0_SB_DQS_DP<4>")
	)
	(arc
		(start 329.290934 -272.136108)
		(mid 329.475966 -272.090194)
		(end 329.659742 -272.140934)
		(width 0.09525)
		(layer "In2.Cu")
		(net "M_C_CPU0_SB_DQS_DP<4>")
	)
	(arc
		(start 326.854058 -272.14957)
		(mid 327.129009 -272.216713)
		(end 327.401682 -272.140934)
		(width 0.09525)
		(layer "In2.Cu")
		(net "M_C_CPU0_SB_DQS_DP<4>")
	)
	(arc
		(start 339.059774 -272.140934)
		(mid 339.341206 -272.216689)
		(end 339.622638 -272.140934)
		(width 0.09525)
		(layer "In2.Cu")
		(net "M_C_CPU0_SB_DQS_DP<4>")
	)
	(arc
		(start 338.11972 -272.140934)
		(mid 338.401152 -272.216689)
		(end 338.682584 -272.140934)
		(width 0.09525)
		(layer "In2.Cu")
		(net "M_C_CPU0_SB_DQS_DP<4>")
	)
	(arc
		(start 335.299558 -272.140934)
		(mid 335.58099 -272.216689)
		(end 335.862422 -272.140934)
		(width 0.09525)
		(layer "In2.Cu")
		(net "M_C_CPU0_SB_DQS_DP<4>")
	)
	(arc
		(start 340.939628 -272.140934)
		(mid 341.22106 -272.216689)
		(end 341.502492 -272.140934)
		(width 0.09525)
		(layer "In2.Cu")
		(net "M_C_CPU0_SB_DQS_DP<4>")
	)
	(arc
		(start 333.419704 -272.140934)
		(mid 333.701136 -272.216689)
		(end 333.982568 -272.140934)
		(width 0.09525)
		(layer "In2.Cu")
		(net "M_C_CPU0_SB_DQS_DP<4>")
	)
	(arc
		(start 332.47965 -272.140934)
		(mid 332.761082 -272.216689)
		(end 333.042514 -272.140934)
		(width 0.09525)
		(layer "In2.Cu")
		(net "M_C_CPU0_SB_DQS_DP<4>")
	)
	(arc
		(start 332.10246 -272.140934)
		(mid 332.286235 -272.090162)
		(end 332.471268 -272.136108)
		(width 0.09525)
		(layer "In2.Cu")
		(net "M_C_CPU0_SB_DQS_DP<4>")
	)
	(arc
		(start 328.342498 -272.140934)
		(mid 328.526273 -272.090162)
		(end 328.711306 -272.136108)
		(width 0.09525)
		(layer "In2.Cu")
		(net "M_C_CPU0_SB_DQS_DP<4>")
	)
	(arc
		(start 328.719688 -272.140934)
		(mid 329.00112 -272.216689)
		(end 329.282552 -272.140934)
		(width 0.09525)
		(layer "In2.Cu")
		(net "M_C_CPU0_SB_DQS_DP<4>")
	)
	(arc
		(start 334.922622 -272.140934)
		(mid 335.11109 -272.090257)
		(end 335.299558 -272.140934)
		(width 0.09525)
		(layer "In2.Cu")
		(net "M_C_CPU0_SB_DQS_DP<4>")
	)
	(arc
		(start 330.599542 -272.140934)
		(mid 330.880974 -272.216689)
		(end 331.162406 -272.140934)
		(width 0.09525)
		(layer "In2.Cu")
		(net "M_C_CPU0_SB_DQS_DP<4>")
	)
	(arc
		(start 343.390982 -272.136108)
		(mid 343.543877 -272.09128)
		(end 343.701624 -272.113756)
		(width 0.09525)
		(layer "In2.Cu")
		(net "M_C_CPU0_SB_DQS_DP<4>")
	)
	(arc
		(start 342.450928 -272.136108)
		(mid 342.63596 -272.090194)
		(end 342.819736 -272.140934)
		(width 0.09525)
		(layer "In2.Cu")
		(net "M_C_CPU0_SB_DQS_DP<4>")
	)
	(arc
		(start 336.239612 -272.140934)
		(mid 336.521044 -272.216689)
		(end 336.802476 -272.140934)
		(width 0.09525)
		(layer "In2.Cu")
		(net "M_C_CPU0_SB_DQS_DP<4>")
	)
	(arc
		(start 331.162406 -272.140934)
		(mid 331.346181 -272.090162)
		(end 331.531214 -272.136108)
		(width 0.09525)
		(layer "In2.Cu")
		(net "M_C_CPU0_SB_DQS_DP<4>")
	)
	(arc
		(start 337.750912 -272.136108)
		(mid 337.935944 -272.090194)
		(end 338.11972 -272.140934)
		(width 0.09525)
		(layer "In2.Cu")
		(net "M_C_CPU0_SB_DQS_DP<4>")
	)
	(arc
		(start 341.502492 -272.140934)
		(mid 341.686267 -272.090162)
		(end 341.8713 -272.136108)
		(width 0.09525)
		(layer "In2.Cu")
		(net "M_C_CPU0_SB_DQS_DP<4>")
	)
	(segment
		(start 343.097866 -290.019994)
		(end 342.631014 -290.285932)
		(width 0.12954)
		(layer "F.Cu")
		(net "M_C_CPU0_SB_DQS_DP<3>")
	)
	(segment
		(start 337.750912 -290.615878)
		(end 337.74253 -290.611052)
		(width 0.09525)
		(layer "In2.Cu")
		(net "M_C_CPU0_SB_DQS_DP<3>")
	)
	(segment
		(start 341.879682 -290.611052)
		(end 341.8713 -290.615878)
		(width 0.09525)
		(layer "In2.Cu")
		(net "M_C_CPU0_SB_DQS_DP<3>")
	)
	(segment
		(start 340.939628 -290.611052)
		(end 340.931246 -290.615878)
		(width 0.09525)
		(layer "In2.Cu")
		(net "M_C_CPU0_SB_DQS_DP<3>")
	)
	(segment
		(start 304.803556 -313.392566)
		(end 304.46472 -313.392566)
		(width 0.16002)
		(layer "In2.Cu")
		(net "M_C_CPU0_SB_DQS_DP<3>")
	)
	(segment
		(start 314.985146 -309.522876)
		(end 314.78855 -309.719472)
		(width 0.16002)
		(layer "In2.Cu")
		(net "M_C_CPU0_SB_DQS_DP<3>")
	)
	(segment
		(start 325.088504 -293.510462)
		(end 324.801484 -293.510462)
		(width 0.09525)
		(layer "In2.Cu")
		(net "M_C_CPU0_SB_DQS_DP<3>")
	)
	(segment
		(start 293.441882 -313.208924)
		(end 292.553898 -313.208924)
		(width 0.16002)
		(layer "In2.Cu")
		(net "M_C_CPU0_SB_DQS_DP<3>")
	)
	(segment
		(start 315.066934 -308.054756)
		(end 314.694062 -308.427628)
		(width 0.16002)
		(layer "In2.Cu")
		(net "M_C_CPU0_SB_DQS_DP<3>")
	)
	(segment
		(start 316.358778 -308.149244)
		(end 316.162182 -308.34584)
		(width 0.16002)
		(layer "In2.Cu")
		(net "M_C_CPU0_SB_DQS_DP<3>")
	)
	(segment
		(start 316.358778 -307.872384)
		(end 316.358778 -308.149244)
		(width 0.16002)
		(layer "In2.Cu")
		(net "M_C_CPU0_SB_DQS_DP<3>")
	)
	(segment
		(start 319.106042 -305.40198)
		(end 318.909446 -305.598576)
		(width 0.16002)
		(layer "In2.Cu")
		(net "M_C_CPU0_SB_DQS_DP<3>")
	)
	(segment
		(start 296.93362 -313.374786)
		(end 296.61866 -313.059826)
		(width 0.16002)
		(layer "In2.Cu")
		(net "M_C_CPU0_SB_DQS_DP<3>")
	)
	(segment
		(start 324.801484 -293.510462)
		(end 324.35673 -293.955216)
		(width 0.09525)
		(layer "In2.Cu")
		(net "M_C_CPU0_SB_DQS_DP<3>")
	)
	(segment
		(start 313.693302 -309.428388)
		(end 310.877204 -312.244486)
		(width 0.16002)
		(layer "In2.Cu")
		(net "M_C_CPU0_SB_DQS_DP<3>")
	)
	(segment
		(start 326.067928 -292.531038)
		(end 325.088504 -293.510462)
		(width 0.09525)
		(layer "In2.Cu")
		(net "M_C_CPU0_SB_DQS_DP<3>")
	)
	(segment
		(start 333.99095 -290.615878)
		(end 333.982568 -290.611052)
		(width 0.09525)
		(layer "In2.Cu")
		(net "M_C_CPU0_SB_DQS_DP<3>")
	)
	(segment
		(start 318.814958 -304.834036)
		(end 319.106042 -305.12512)
		(width 0.16002)
		(layer "In2.Cu")
		(net "M_C_CPU0_SB_DQS_DP<3>")
	)
	(segment
		(start 317.73241 -306.775612)
		(end 317.535814 -306.972208)
		(width 0.16002)
		(layer "In2.Cu")
		(net "M_C_CPU0_SB_DQS_DP<3>")
	)
	(segment
		(start 317.535814 -306.972208)
		(end 317.258954 -306.972208)
		(width 0.16002)
		(layer "In2.Cu")
		(net "M_C_CPU0_SB_DQS_DP<3>")
	)
	(segment
		(start 314.78855 -309.719472)
		(end 314.51169 -309.719472)
		(width 0.16002)
		(layer "In2.Cu")
		(net "M_C_CPU0_SB_DQS_DP<3>")
	)
	(segment
		(start 298.95546 -312.209942)
		(end 298.644056 -312.521346)
		(width 0.16002)
		(layer "In2.Cu")
		(net "M_C_CPU0_SB_DQS_DP<3>")
	)
	(segment
		(start 320.709798 -303.783492)
		(end 319.338198 -303.783492)
		(width 0.16002)
		(layer "In2.Cu")
		(net "M_C_CPU0_SB_DQS_DP<3>")
	)
	(segment
		(start 317.73241 -306.498752)
		(end 317.73241 -306.775612)
		(width 0.16002)
		(layer "In2.Cu")
		(net "M_C_CPU0_SB_DQS_DP<3>")
	)
	(segment
		(start 329.290934 -290.615878)
		(end 329.282552 -290.611052)
		(width 0.09525)
		(layer "In2.Cu")
		(net "M_C_CPU0_SB_DQS_DP<3>")
	)
	(segment
		(start 332.47965 -290.611052)
		(end 332.471268 -290.615878)
		(width 0.09525)
		(layer "In2.Cu")
		(net "M_C_CPU0_SB_DQS_DP<3>")
	)
	(segment
		(start 316.96787 -306.681124)
		(end 316.440566 -306.681124)
		(width 0.16002)
		(layer "In2.Cu")
		(net "M_C_CPU0_SB_DQS_DP<3>")
	)
	(segment
		(start 297.384216 -313.374786)
		(end 296.93362 -313.374786)
		(width 0.16002)
		(layer "In2.Cu")
		(net "M_C_CPU0_SB_DQS_DP<3>")
	)
	(segment
		(start 306.078636 -312.595006)
		(end 305.601116 -312.595006)
		(width 0.16002)
		(layer "In2.Cu")
		(net "M_C_CPU0_SB_DQS_DP<3>")
	)
	(segment
		(start 309.781956 -312.825638)
		(end 309.586122 -313.021472)
		(width 0.16002)
		(layer "In2.Cu")
		(net "M_C_CPU0_SB_DQS_DP<3>")
	)
	(segment
		(start 338.690966 -290.615878)
		(end 338.682584 -290.611052)
		(width 0.09525)
		(layer "In2.Cu")
		(net "M_C_CPU0_SB_DQS_DP<3>")
	)
	(segment
		(start 327.66508 -290.699952)
		(end 327.410318 -290.954714)
		(width 0.09525)
		(layer "In2.Cu")
		(net "M_C_CPU0_SB_DQS_DP<3>")
	)
	(segment
		(start 331.539596 -290.611052)
		(end 331.531214 -290.615878)
		(width 0.09525)
		(layer "In2.Cu")
		(net "M_C_CPU0_SB_DQS_DP<3>")
	)
	(segment
		(start 309.781956 -312.617358)
		(end 309.781956 -312.825638)
		(width 0.16002)
		(layer "In2.Cu")
		(net "M_C_CPU0_SB_DQS_DP<3>")
	)
	(segment
		(start 317.258954 -306.972208)
		(end 316.96787 -306.681124)
		(width 0.16002)
		(layer "In2.Cu")
		(net "M_C_CPU0_SB_DQS_DP<3>")
	)
	(segment
		(start 309.309516 -313.021472)
		(end 309.113682 -312.825638)
		(width 0.16002)
		(layer "In2.Cu")
		(net "M_C_CPU0_SB_DQS_DP<3>")
	)
	(segment
		(start 306.429156 -312.244486)
		(end 306.078636 -312.595006)
		(width 0.16002)
		(layer "In2.Cu")
		(net "M_C_CPU0_SB_DQS_DP<3>")
	)
	(segment
		(start 308.74081 -312.244486)
		(end 306.429156 -312.244486)
		(width 0.16002)
		(layer "In2.Cu")
		(net "M_C_CPU0_SB_DQS_DP<3>")
	)
	(segment
		(start 314.220606 -309.428388)
		(end 313.693302 -309.428388)
		(width 0.16002)
		(layer "In2.Cu")
		(net "M_C_CPU0_SB_DQS_DP<3>")
	)
	(segment
		(start 316.162182 -308.34584)
		(end 315.885322 -308.34584)
		(width 0.16002)
		(layer "In2.Cu")
		(net "M_C_CPU0_SB_DQS_DP<3>")
	)
	(segment
		(start 292.553898 -313.208924)
		(end 292.280086 -312.935112)
		(width 0.16002)
		(layer "In2.Cu")
		(net "M_C_CPU0_SB_DQS_DP<3>")
	)
	(segment
		(start 319.106042 -305.12512)
		(end 319.106042 -305.40198)
		(width 0.16002)
		(layer "In2.Cu")
		(net "M_C_CPU0_SB_DQS_DP<3>")
	)
	(segment
		(start 309.113682 -312.825638)
		(end 309.113682 -312.617358)
		(width 0.16002)
		(layer "In2.Cu")
		(net "M_C_CPU0_SB_DQS_DP<3>")
	)
	(segment
		(start 324.297548 -300.195742)
		(end 320.709798 -303.783492)
		(width 0.16002)
		(layer "In2.Cu")
		(net "M_C_CPU0_SB_DQS_DP<3>")
	)
	(segment
		(start 342.631014 -290.285932)
		(end 342.47709 -290.551362)
		(width 0.09525)
		(layer "In2.Cu")
		(net "M_C_CPU0_SB_DQS_DP<3>")
	)
	(segment
		(start 314.985146 -309.246016)
		(end 314.985146 -309.522876)
		(width 0.16002)
		(layer "In2.Cu")
		(net "M_C_CPU0_SB_DQS_DP<3>")
	)
	(segment
		(start 315.594238 -308.054756)
		(end 315.066934 -308.054756)
		(width 0.16002)
		(layer "In2.Cu")
		(net "M_C_CPU0_SB_DQS_DP<3>")
	)
	(segment
		(start 342.47709 -290.551362)
		(end 342.376252 -290.578032)
		(width 0.09525)
		(layer "In2.Cu")
		(net "M_C_CPU0_SB_DQS_DP<3>")
	)
	(segment
		(start 316.067694 -307.5813)
		(end 316.358778 -307.872384)
		(width 0.16002)
		(layer "In2.Cu")
		(net "M_C_CPU0_SB_DQS_DP<3>")
	)
	(segment
		(start 324.297548 -295.319704)
		(end 324.297548 -300.195742)
		(width 0.16002)
		(layer "In2.Cu")
		(net "M_C_CPU0_SB_DQS_DP<3>")
	)
	(segment
		(start 318.814958 -304.306732)
		(end 318.814958 -304.834036)
		(width 0.16002)
		(layer "In2.Cu")
		(net "M_C_CPU0_SB_DQS_DP<3>")
	)
	(segment
		(start 336.239612 -290.611052)
		(end 336.23123 -290.615878)
		(width 0.09525)
		(layer "In2.Cu")
		(net "M_C_CPU0_SB_DQS_DP<3>")
	)
	(segment
		(start 301.072296 -312.209942)
		(end 298.95546 -312.209942)
		(width 0.16002)
		(layer "In2.Cu")
		(net "M_C_CPU0_SB_DQS_DP<3>")
	)
	(segment
		(start 318.909446 -305.598576)
		(end 318.632586 -305.598576)
		(width 0.16002)
		(layer "In2.Cu")
		(net "M_C_CPU0_SB_DQS_DP<3>")
	)
	(segment
		(start 304.46472 -313.392566)
		(end 304.17516 -313.103006)
		(width 0.16002)
		(layer "In2.Cu")
		(net "M_C_CPU0_SB_DQS_DP<3>")
	)
	(segment
		(start 333.050896 -290.615878)
		(end 333.042514 -290.611052)
		(width 0.09525)
		(layer "In2.Cu")
		(net "M_C_CPU0_SB_DQS_DP<3>")
	)
	(segment
		(start 327.410318 -290.954714)
		(end 326.291956 -291.41801)
		(width 0.09525)
		(layer "In2.Cu")
		(net "M_C_CPU0_SB_DQS_DP<3>")
	)
	(segment
		(start 310.877204 -312.244486)
		(end 310.154828 -312.244486)
		(width 0.16002)
		(layer "In2.Cu")
		(net "M_C_CPU0_SB_DQS_DP<3>")
	)
	(segment
		(start 324.297548 -295.296082)
		(end 324.297548 -295.319704)
		(width 0.09525)
		(layer "In2.Cu")
		(net "M_C_CPU0_SB_DQS_DP<3>")
	)
	(segment
		(start 305.601116 -312.595006)
		(end 304.803556 -313.392566)
		(width 0.16002)
		(layer "In2.Cu")
		(net "M_C_CPU0_SB_DQS_DP<3>")
	)
	(segment
		(start 328.719688 -290.611052)
		(end 328.711306 -290.615878)
		(width 0.09525)
		(layer "In2.Cu")
		(net "M_C_CPU0_SB_DQS_DP<3>")
	)
	(segment
		(start 317.441326 -306.207668)
		(end 317.73241 -306.498752)
		(width 0.16002)
		(layer "In2.Cu")
		(net "M_C_CPU0_SB_DQS_DP<3>")
	)
	(segment
		(start 298.237656 -312.521346)
		(end 297.384216 -313.374786)
		(width 0.16002)
		(layer "In2.Cu")
		(net "M_C_CPU0_SB_DQS_DP<3>")
	)
	(segment
		(start 309.586122 -313.021472)
		(end 309.309516 -313.021472)
		(width 0.16002)
		(layer "In2.Cu")
		(net "M_C_CPU0_SB_DQS_DP<3>")
	)
	(segment
		(start 293.59098 -313.059826)
		(end 293.441882 -313.208924)
		(width 0.16002)
		(layer "In2.Cu")
		(net "M_C_CPU0_SB_DQS_DP<3>")
	)
	(segment
		(start 337.179666 -290.611052)
		(end 337.171284 -290.615878)
		(width 0.09525)
		(layer "In2.Cu")
		(net "M_C_CPU0_SB_DQS_DP<3>")
	)
	(segment
		(start 318.341502 -305.307492)
		(end 317.814198 -305.307492)
		(width 0.16002)
		(layer "In2.Cu")
		(net "M_C_CPU0_SB_DQS_DP<3>")
	)
	(segment
		(start 319.338198 -303.783492)
		(end 318.814958 -304.306732)
		(width 0.16002)
		(layer "In2.Cu")
		(net "M_C_CPU0_SB_DQS_DP<3>")
	)
	(segment
		(start 304.17516 -313.103006)
		(end 301.96536 -313.103006)
		(width 0.16002)
		(layer "In2.Cu")
		(net "M_C_CPU0_SB_DQS_DP<3>")
	)
	(segment
		(start 314.694062 -308.427628)
		(end 314.694062 -308.954932)
		(width 0.16002)
		(layer "In2.Cu")
		(net "M_C_CPU0_SB_DQS_DP<3>")
	)
	(segment
		(start 314.694062 -308.954932)
		(end 314.985146 -309.246016)
		(width 0.16002)
		(layer "In2.Cu")
		(net "M_C_CPU0_SB_DQS_DP<3>")
	)
	(segment
		(start 326.291956 -291.41801)
		(end 326.067928 -291.642038)
		(width 0.09525)
		(layer "In2.Cu")
		(net "M_C_CPU0_SB_DQS_DP<3>")
	)
	(segment
		(start 324.35673 -293.955216)
		(end 324.35673 -295.2369)
		(width 0.09525)
		(layer "In2.Cu")
		(net "M_C_CPU0_SB_DQS_DP<3>")
	)
	(segment
		(start 316.440566 -306.681124)
		(end 316.067694 -307.053996)
		(width 0.16002)
		(layer "In2.Cu")
		(net "M_C_CPU0_SB_DQS_DP<3>")
	)
	(segment
		(start 315.885322 -308.34584)
		(end 315.594238 -308.054756)
		(width 0.16002)
		(layer "In2.Cu")
		(net "M_C_CPU0_SB_DQS_DP<3>")
	)
	(segment
		(start 314.51169 -309.719472)
		(end 314.220606 -309.428388)
		(width 0.16002)
		(layer "In2.Cu")
		(net "M_C_CPU0_SB_DQS_DP<3>")
	)
	(segment
		(start 317.814198 -305.307492)
		(end 317.441326 -305.680364)
		(width 0.16002)
		(layer "In2.Cu")
		(net "M_C_CPU0_SB_DQS_DP<3>")
	)
	(segment
		(start 324.35673 -295.2369)
		(end 324.297548 -295.296082)
		(width 0.09525)
		(layer "In2.Cu")
		(net "M_C_CPU0_SB_DQS_DP<3>")
	)
	(segment
		(start 317.441326 -305.680364)
		(end 317.441326 -306.207668)
		(width 0.16002)
		(layer "In2.Cu")
		(net "M_C_CPU0_SB_DQS_DP<3>")
	)
	(segment
		(start 318.632586 -305.598576)
		(end 318.341502 -305.307492)
		(width 0.16002)
		(layer "In2.Cu")
		(net "M_C_CPU0_SB_DQS_DP<3>")
	)
	(segment
		(start 310.154828 -312.244486)
		(end 309.781956 -312.617358)
		(width 0.16002)
		(layer "In2.Cu")
		(net "M_C_CPU0_SB_DQS_DP<3>")
	)
	(segment
		(start 316.067694 -307.053996)
		(end 316.067694 -307.5813)
		(width 0.16002)
		(layer "In2.Cu")
		(net "M_C_CPU0_SB_DQS_DP<3>")
	)
	(segment
		(start 327.805288 -290.597082)
		(end 327.781412 -290.610798)
		(width 0.09525)
		(layer "In2.Cu")
		(net "M_C_CPU0_SB_DQS_DP<3>")
	)
	(segment
		(start 301.96536 -313.103006)
		(end 301.072296 -312.209942)
		(width 0.16002)
		(layer "In2.Cu")
		(net "M_C_CPU0_SB_DQS_DP<3>")
	)
	(segment
		(start 296.61866 -313.059826)
		(end 293.59098 -313.059826)
		(width 0.16002)
		(layer "In2.Cu")
		(net "M_C_CPU0_SB_DQS_DP<3>")
	)
	(segment
		(start 309.113682 -312.617358)
		(end 308.74081 -312.244486)
		(width 0.16002)
		(layer "In2.Cu")
		(net "M_C_CPU0_SB_DQS_DP<3>")
	)
	(segment
		(start 298.644056 -312.521346)
		(end 298.237656 -312.521346)
		(width 0.16002)
		(layer "In2.Cu")
		(net "M_C_CPU0_SB_DQS_DP<3>")
	)
	(segment
		(start 326.067928 -291.642038)
		(end 326.067928 -292.531038)
		(width 0.09525)
		(layer "In2.Cu")
		(net "M_C_CPU0_SB_DQS_DP<3>")
	)
	(arc
		(start 333.982568 -290.611052)
		(mid 333.701136 -290.535297)
		(end 333.419704 -290.611052)
		(width 0.09525)
		(layer "In2.Cu")
		(net "M_C_CPU0_SB_DQS_DP<3>")
	)
	(arc
		(start 339.622638 -290.611052)
		(mid 339.341206 -290.535297)
		(end 339.059774 -290.611052)
		(width 0.09525)
		(layer "In2.Cu")
		(net "M_C_CPU0_SB_DQS_DP<3>")
	)
	(arc
		(start 336.802476 -290.611052)
		(mid 336.521044 -290.535297)
		(end 336.239612 -290.611052)
		(width 0.09525)
		(layer "In2.Cu")
		(net "M_C_CPU0_SB_DQS_DP<3>")
	)
	(arc
		(start 341.8713 -290.615878)
		(mid 341.686268 -290.661792)
		(end 341.502492 -290.611052)
		(width 0.09525)
		(layer "In2.Cu")
		(net "M_C_CPU0_SB_DQS_DP<3>")
	)
	(arc
		(start 339.999574 -290.611052)
		(mid 339.811106 -290.661729)
		(end 339.622638 -290.611052)
		(width 0.09525)
		(layer "In2.Cu")
		(net "M_C_CPU0_SB_DQS_DP<3>")
	)
	(arc
		(start 338.11972 -290.611052)
		(mid 337.935945 -290.661824)
		(end 337.750912 -290.615878)
		(width 0.09525)
		(layer "In2.Cu")
		(net "M_C_CPU0_SB_DQS_DP<3>")
	)
	(arc
		(start 331.162406 -290.611052)
		(mid 330.880974 -290.535297)
		(end 330.599542 -290.611052)
		(width 0.09525)
		(layer "In2.Cu")
		(net "M_C_CPU0_SB_DQS_DP<3>")
	)
	(arc
		(start 333.042514 -290.611052)
		(mid 332.761082 -290.535297)
		(end 332.47965 -290.611052)
		(width 0.09525)
		(layer "In2.Cu")
		(net "M_C_CPU0_SB_DQS_DP<3>")
	)
	(arc
		(start 334.359758 -290.611052)
		(mid 334.175983 -290.661824)
		(end 333.99095 -290.615878)
		(width 0.09525)
		(layer "In2.Cu")
		(net "M_C_CPU0_SB_DQS_DP<3>")
	)
	(arc
		(start 340.562438 -290.611052)
		(mid 340.281006 -290.535297)
		(end 339.999574 -290.611052)
		(width 0.09525)
		(layer "In2.Cu")
		(net "M_C_CPU0_SB_DQS_DP<3>")
	)
	(arc
		(start 330.599542 -290.611052)
		(mid 330.411074 -290.661729)
		(end 330.222606 -290.611052)
		(width 0.09525)
		(layer "In2.Cu")
		(net "M_C_CPU0_SB_DQS_DP<3>")
	)
	(arc
		(start 327.781412 -290.610798)
		(mid 327.720329 -290.651567)
		(end 327.66508 -290.699952)
		(width 0.09525)
		(layer "In2.Cu")
		(net "M_C_CPU0_SB_DQS_DP<3>")
	)
	(arc
		(start 336.23123 -290.615878)
		(mid 336.046198 -290.661792)
		(end 335.862422 -290.611052)
		(width 0.09525)
		(layer "In2.Cu")
		(net "M_C_CPU0_SB_DQS_DP<3>")
	)
	(arc
		(start 335.862422 -290.611052)
		(mid 335.58099 -290.535297)
		(end 335.299558 -290.611052)
		(width 0.09525)
		(layer "In2.Cu")
		(net "M_C_CPU0_SB_DQS_DP<3>")
	)
	(arc
		(start 340.931246 -290.615878)
		(mid 340.746214 -290.661792)
		(end 340.562438 -290.611052)
		(width 0.09525)
		(layer "In2.Cu")
		(net "M_C_CPU0_SB_DQS_DP<3>")
	)
	(arc
		(start 329.659742 -290.611052)
		(mid 329.475967 -290.661824)
		(end 329.290934 -290.615878)
		(width 0.09525)
		(layer "In2.Cu")
		(net "M_C_CPU0_SB_DQS_DP<3>")
	)
	(arc
		(start 334.922622 -290.611052)
		(mid 334.64119 -290.535297)
		(end 334.359758 -290.611052)
		(width 0.09525)
		(layer "In2.Cu")
		(net "M_C_CPU0_SB_DQS_DP<3>")
	)
	(arc
		(start 333.419704 -290.611052)
		(mid 333.235929 -290.661824)
		(end 333.050896 -290.615878)
		(width 0.09525)
		(layer "In2.Cu")
		(net "M_C_CPU0_SB_DQS_DP<3>")
	)
	(arc
		(start 341.502492 -290.611052)
		(mid 341.22106 -290.535297)
		(end 340.939628 -290.611052)
		(width 0.09525)
		(layer "In2.Cu")
		(net "M_C_CPU0_SB_DQS_DP<3>")
	)
	(arc
		(start 342.376252 -290.578032)
		(mid 342.124111 -290.536462)
		(end 341.879682 -290.611052)
		(width 0.09525)
		(layer "In2.Cu")
		(net "M_C_CPU0_SB_DQS_DP<3>")
	)
	(arc
		(start 328.711306 -290.615878)
		(mid 328.526274 -290.661792)
		(end 328.342498 -290.611052)
		(width 0.09525)
		(layer "In2.Cu")
		(net "M_C_CPU0_SB_DQS_DP<3>")
	)
	(arc
		(start 331.531214 -290.615878)
		(mid 331.346182 -290.661792)
		(end 331.162406 -290.611052)
		(width 0.09525)
		(layer "In2.Cu")
		(net "M_C_CPU0_SB_DQS_DP<3>")
	)
	(arc
		(start 330.222606 -290.611052)
		(mid 329.941174 -290.535297)
		(end 329.659742 -290.611052)
		(width 0.09525)
		(layer "In2.Cu")
		(net "M_C_CPU0_SB_DQS_DP<3>")
	)
	(arc
		(start 332.10246 -290.611052)
		(mid 331.821028 -290.535297)
		(end 331.539596 -290.611052)
		(width 0.09525)
		(layer "In2.Cu")
		(net "M_C_CPU0_SB_DQS_DP<3>")
	)
	(arc
		(start 328.342498 -290.611052)
		(mid 328.075672 -290.535487)
		(end 327.805288 -290.597082)
		(width 0.09525)
		(layer "In2.Cu")
		(net "M_C_CPU0_SB_DQS_DP<3>")
	)
	(arc
		(start 337.171284 -290.615878)
		(mid 336.986252 -290.661792)
		(end 336.802476 -290.611052)
		(width 0.09525)
		(layer "In2.Cu")
		(net "M_C_CPU0_SB_DQS_DP<3>")
	)
	(arc
		(start 329.282552 -290.611052)
		(mid 329.00112 -290.535297)
		(end 328.719688 -290.611052)
		(width 0.09525)
		(layer "In2.Cu")
		(net "M_C_CPU0_SB_DQS_DP<3>")
	)
	(arc
		(start 338.682584 -290.611052)
		(mid 338.401152 -290.535297)
		(end 338.11972 -290.611052)
		(width 0.09525)
		(layer "In2.Cu")
		(net "M_C_CPU0_SB_DQS_DP<3>")
	)
	(arc
		(start 337.74253 -290.611052)
		(mid 337.461098 -290.535297)
		(end 337.179666 -290.611052)
		(width 0.09525)
		(layer "In2.Cu")
		(net "M_C_CPU0_SB_DQS_DP<3>")
	)
	(arc
		(start 335.299558 -290.611052)
		(mid 335.11109 -290.661729)
		(end 334.922622 -290.611052)
		(width 0.09525)
		(layer "In2.Cu")
		(net "M_C_CPU0_SB_DQS_DP<3>")
	)
	(arc
		(start 339.059774 -290.611052)
		(mid 338.875999 -290.661824)
		(end 338.690966 -290.615878)
		(width 0.09525)
		(layer "In2.Cu")
		(net "M_C_CPU0_SB_DQS_DP<3>")
	)
	(arc
		(start 332.471268 -290.615878)
		(mid 332.286236 -290.661792)
		(end 332.10246 -290.611052)
		(width 0.09525)
		(layer "In2.Cu")
		(net "M_C_CPU0_SB_DQS_DP<3>")
	)
	(segment
		(start 343.097866 -285.160212)
		(end 342.631014 -285.42615)
		(width 0.12954)
		(layer "F.Cu")
		(net "M_C_CPU0_SB_DQS_DP<2>")
	)
	(segment
		(start 313.283854 -300.109382)
		(end 313.05373 -299.879258)
		(width 0.16002)
		(layer "In2.Cu")
		(net "M_C_CPU0_SB_DQS_DP<2>")
	)
	(segment
		(start 312.383424 -301.286164)
		(end 312.186574 -301.483014)
		(width 0.16002)
		(layer "In2.Cu")
		(net "M_C_CPU0_SB_DQS_DP<2>")
	)
	(segment
		(start 306.429156 -302.894492)
		(end 306.078636 -303.245012)
		(width 0.16002)
		(layer "In2.Cu")
		(net "M_C_CPU0_SB_DQS_DP<2>")
	)
	(segment
		(start 297.384216 -304.024792)
		(end 296.93362 -304.024792)
		(width 0.16002)
		(layer "In2.Cu")
		(net "M_C_CPU0_SB_DQS_DP<2>")
	)
	(segment
		(start 312.153554 -300.25213)
		(end 312.153554 -300.779688)
		(width 0.16002)
		(layer "In2.Cu")
		(net "M_C_CPU0_SB_DQS_DP<2>")
	)
	(segment
		(start 304.803556 -304.042572)
		(end 304.46472 -304.042572)
		(width 0.16002)
		(layer "In2.Cu")
		(net "M_C_CPU0_SB_DQS_DP<2>")
	)
	(segment
		(start 298.644056 -303.171352)
		(end 298.237656 -303.171352)
		(width 0.16002)
		(layer "In2.Cu")
		(net "M_C_CPU0_SB_DQS_DP<2>")
	)
	(segment
		(start 327.781412 -285.751016)
		(end 327.759568 -285.763462)
		(width 0.09525)
		(layer "In2.Cu")
		(net "M_C_CPU0_SB_DQS_DP<2>")
	)
	(segment
		(start 296.61866 -303.709832)
		(end 294.778684 -303.709832)
		(width 0.16002)
		(layer "In2.Cu")
		(net "M_C_CPU0_SB_DQS_DP<2>")
	)
	(segment
		(start 324.188328 -286.472122)
		(end 324.129146 -286.41294)
		(width 0.09525)
		(layer "In2.Cu")
		(net "M_C_CPU0_SB_DQS_DP<2>")
	)
	(segment
		(start 331.539596 -285.75127)
		(end 331.531214 -285.756096)
		(width 0.09525)
		(layer "In2.Cu")
		(net "M_C_CPU0_SB_DQS_DP<2>")
	)
	(segment
		(start 328.719688 -285.75127)
		(end 328.711306 -285.756096)
		(width 0.09525)
		(layer "In2.Cu")
		(net "M_C_CPU0_SB_DQS_DP<2>")
	)
	(segment
		(start 309.089806 -303.933352)
		(end 308.893972 -303.737518)
		(width 0.16002)
		(layer "In2.Cu")
		(net "M_C_CPU0_SB_DQS_DP<2>")
	)
	(segment
		(start 301.49546 -304.106072)
		(end 301.329598 -303.94021)
		(width 0.16002)
		(layer "In2.Cu")
		(net "M_C_CPU0_SB_DQS_DP<2>")
	)
	(segment
		(start 309.366412 -303.933352)
		(end 309.089806 -303.933352)
		(width 0.16002)
		(layer "In2.Cu")
		(net "M_C_CPU0_SB_DQS_DP<2>")
	)
	(segment
		(start 301.877476 -304.106072)
		(end 301.49546 -304.106072)
		(width 0.16002)
		(layer "In2.Cu")
		(net "M_C_CPU0_SB_DQS_DP<2>")
	)
	(segment
		(start 318.539114 -295.130474)
		(end 314.933838 -298.73575)
		(width 0.16002)
		(layer "In2.Cu")
		(net "M_C_CPU0_SB_DQS_DP<2>")
	)
	(segment
		(start 337.750912 -285.756096)
		(end 337.74253 -285.75127)
		(width 0.09525)
		(layer "In2.Cu")
		(net "M_C_CPU0_SB_DQS_DP<2>")
	)
	(segment
		(start 313.651646 -299.002958)
		(end 313.651646 -299.530516)
		(width 0.16002)
		(layer "In2.Cu")
		(net "M_C_CPU0_SB_DQS_DP<2>")
	)
	(segment
		(start 310.77535 -302.894492)
		(end 309.935118 -302.894492)
		(width 0.16002)
		(layer "In2.Cu")
		(net "M_C_CPU0_SB_DQS_DP<2>")
	)
	(segment
		(start 324.129146 -286.41294)
		(end 324.105524 -286.41294)
		(width 0.09525)
		(layer "In2.Cu")
		(net "M_C_CPU0_SB_DQS_DP<2>")
	)
	(segment
		(start 327.805288 -285.7373)
		(end 327.781412 -285.751016)
		(width 0.09525)
		(layer "In2.Cu")
		(net "M_C_CPU0_SB_DQS_DP<2>")
	)
	(segment
		(start 310.779922 -301.625762)
		(end 310.779922 -302.15332)
		(width 0.16002)
		(layer "In2.Cu")
		(net "M_C_CPU0_SB_DQS_DP<2>")
	)
	(segment
		(start 304.17516 -303.753012)
		(end 302.230536 -303.753012)
		(width 0.16002)
		(layer "In2.Cu")
		(net "M_C_CPU0_SB_DQS_DP<2>")
	)
	(segment
		(start 312.383424 -301.009558)
		(end 312.383424 -301.286164)
		(width 0.16002)
		(layer "In2.Cu")
		(net "M_C_CPU0_SB_DQS_DP<2>")
	)
	(segment
		(start 311.009792 -302.66005)
		(end 310.77535 -302.894492)
		(width 0.16002)
		(layer "In2.Cu")
		(net "M_C_CPU0_SB_DQS_DP<2>")
	)
	(segment
		(start 323.924676 -286.41294)
		(end 318.539114 -291.798502)
		(width 0.16002)
		(layer "In2.Cu")
		(net "M_C_CPU0_SB_DQS_DP<2>")
	)
	(segment
		(start 308.893972 -303.267364)
		(end 308.5211 -302.894492)
		(width 0.16002)
		(layer "In2.Cu")
		(net "M_C_CPU0_SB_DQS_DP<2>")
	)
	(segment
		(start 342.631014 -285.42615)
		(end 342.47709 -285.69158)
		(width 0.09525)
		(layer "In2.Cu")
		(net "M_C_CPU0_SB_DQS_DP<2>")
	)
	(segment
		(start 311.910222 -301.483014)
		(end 311.680098 -301.25289)
		(width 0.16002)
		(layer "In2.Cu")
		(net "M_C_CPU0_SB_DQS_DP<2>")
	)
	(segment
		(start 309.562246 -303.267364)
		(end 309.562246 -303.737518)
		(width 0.16002)
		(layer "In2.Cu")
		(net "M_C_CPU0_SB_DQS_DP<2>")
	)
	(segment
		(start 341.879682 -285.75127)
		(end 341.8713 -285.756096)
		(width 0.09525)
		(layer "In2.Cu")
		(net "M_C_CPU0_SB_DQS_DP<2>")
	)
	(segment
		(start 337.179666 -285.75127)
		(end 337.171284 -285.756096)
		(width 0.09525)
		(layer "In2.Cu")
		(net "M_C_CPU0_SB_DQS_DP<2>")
	)
	(segment
		(start 313.757056 -299.912532)
		(end 313.560206 -300.109382)
		(width 0.16002)
		(layer "In2.Cu")
		(net "M_C_CPU0_SB_DQS_DP<2>")
	)
	(segment
		(start 324.105524 -286.41294)
		(end 323.924676 -286.41294)
		(width 0.16002)
		(layer "In2.Cu")
		(net "M_C_CPU0_SB_DQS_DP<2>")
	)
	(segment
		(start 306.078636 -303.245012)
		(end 305.601116 -303.245012)
		(width 0.16002)
		(layer "In2.Cu")
		(net "M_C_CPU0_SB_DQS_DP<2>")
	)
	(segment
		(start 336.239612 -285.75127)
		(end 336.23123 -285.756096)
		(width 0.09525)
		(layer "In2.Cu")
		(net "M_C_CPU0_SB_DQS_DP<2>")
	)
	(segment
		(start 300.9392 -302.859948)
		(end 298.95546 -302.859948)
		(width 0.16002)
		(layer "In2.Cu")
		(net "M_C_CPU0_SB_DQS_DP<2>")
	)
	(segment
		(start 342.47709 -285.69158)
		(end 342.376252 -285.71825)
		(width 0.09525)
		(layer "In2.Cu")
		(net "M_C_CPU0_SB_DQS_DP<2>")
	)
	(segment
		(start 309.935118 -302.894492)
		(end 309.562246 -303.267364)
		(width 0.16002)
		(layer "In2.Cu")
		(net "M_C_CPU0_SB_DQS_DP<2>")
	)
	(segment
		(start 314.024518 -298.630086)
		(end 313.651646 -299.002958)
		(width 0.16002)
		(layer "In2.Cu")
		(net "M_C_CPU0_SB_DQS_DP<2>")
	)
	(segment
		(start 311.152794 -301.25289)
		(end 310.779922 -301.625762)
		(width 0.16002)
		(layer "In2.Cu")
		(net "M_C_CPU0_SB_DQS_DP<2>")
	)
	(segment
		(start 314.657486 -298.73575)
		(end 314.551822 -298.630086)
		(width 0.16002)
		(layer "In2.Cu")
		(net "M_C_CPU0_SB_DQS_DP<2>")
	)
	(segment
		(start 313.05373 -299.879258)
		(end 312.526426 -299.879258)
		(width 0.16002)
		(layer "In2.Cu")
		(net "M_C_CPU0_SB_DQS_DP<2>")
	)
	(segment
		(start 310.779922 -302.15332)
		(end 311.009792 -302.38319)
		(width 0.16002)
		(layer "In2.Cu")
		(net "M_C_CPU0_SB_DQS_DP<2>")
	)
	(segment
		(start 309.562246 -303.737518)
		(end 309.366412 -303.933352)
		(width 0.16002)
		(layer "In2.Cu")
		(net "M_C_CPU0_SB_DQS_DP<2>")
	)
	(segment
		(start 292.553898 -303.85893)
		(end 292.280086 -303.585118)
		(width 0.16002)
		(layer "In2.Cu")
		(net "M_C_CPU0_SB_DQS_DP<2>")
	)
	(segment
		(start 326.651112 -285.80334)
		(end 325.943722 -285.80334)
		(width 0.09525)
		(layer "In2.Cu")
		(net "M_C_CPU0_SB_DQS_DP<2>")
	)
	(segment
		(start 308.5211 -302.894492)
		(end 306.429156 -302.894492)
		(width 0.16002)
		(layer "In2.Cu")
		(net "M_C_CPU0_SB_DQS_DP<2>")
	)
	(segment
		(start 313.560206 -300.109382)
		(end 313.283854 -300.109382)
		(width 0.16002)
		(layer "In2.Cu")
		(net "M_C_CPU0_SB_DQS_DP<2>")
	)
	(segment
		(start 308.893972 -303.737518)
		(end 308.893972 -303.267364)
		(width 0.16002)
		(layer "In2.Cu")
		(net "M_C_CPU0_SB_DQS_DP<2>")
	)
	(segment
		(start 304.46472 -304.042572)
		(end 304.17516 -303.753012)
		(width 0.16002)
		(layer "In2.Cu")
		(net "M_C_CPU0_SB_DQS_DP<2>")
	)
	(segment
		(start 313.757056 -299.635926)
		(end 313.757056 -299.912532)
		(width 0.16002)
		(layer "In2.Cu")
		(net "M_C_CPU0_SB_DQS_DP<2>")
	)
	(segment
		(start 313.651646 -299.530516)
		(end 313.757056 -299.635926)
		(width 0.16002)
		(layer "In2.Cu")
		(net "M_C_CPU0_SB_DQS_DP<2>")
	)
	(segment
		(start 329.290934 -285.756096)
		(end 329.282552 -285.75127)
		(width 0.09525)
		(layer "In2.Cu")
		(net "M_C_CPU0_SB_DQS_DP<2>")
	)
	(segment
		(start 298.237656 -303.171352)
		(end 297.384216 -304.024792)
		(width 0.16002)
		(layer "In2.Cu")
		(net "M_C_CPU0_SB_DQS_DP<2>")
	)
	(segment
		(start 314.933838 -298.73575)
		(end 314.657486 -298.73575)
		(width 0.16002)
		(layer "In2.Cu")
		(net "M_C_CPU0_SB_DQS_DP<2>")
	)
	(segment
		(start 301.329598 -303.94021)
		(end 301.329598 -303.250346)
		(width 0.16002)
		(layer "In2.Cu")
		(net "M_C_CPU0_SB_DQS_DP<2>")
	)
	(segment
		(start 311.009792 -302.38319)
		(end 311.009792 -302.66005)
		(width 0.16002)
		(layer "In2.Cu")
		(net "M_C_CPU0_SB_DQS_DP<2>")
	)
	(segment
		(start 296.93362 -304.024792)
		(end 296.61866 -303.709832)
		(width 0.16002)
		(layer "In2.Cu")
		(net "M_C_CPU0_SB_DQS_DP<2>")
	)
	(segment
		(start 318.539114 -291.798502)
		(end 318.539114 -295.130474)
		(width 0.16002)
		(layer "In2.Cu")
		(net "M_C_CPU0_SB_DQS_DP<2>")
	)
	(segment
		(start 332.47965 -285.75127)
		(end 332.471268 -285.756096)
		(width 0.09525)
		(layer "In2.Cu")
		(net "M_C_CPU0_SB_DQS_DP<2>")
	)
	(segment
		(start 333.99095 -285.756096)
		(end 333.982568 -285.75127)
		(width 0.09525)
		(layer "In2.Cu")
		(net "M_C_CPU0_SB_DQS_DP<2>")
	)
	(segment
		(start 298.95546 -302.859948)
		(end 298.644056 -303.171352)
		(width 0.16002)
		(layer "In2.Cu")
		(net "M_C_CPU0_SB_DQS_DP<2>")
	)
	(segment
		(start 294.629586 -303.85893)
		(end 292.553898 -303.85893)
		(width 0.16002)
		(layer "In2.Cu")
		(net "M_C_CPU0_SB_DQS_DP<2>")
	)
	(segment
		(start 340.939628 -285.75127)
		(end 340.931246 -285.756096)
		(width 0.09525)
		(layer "In2.Cu")
		(net "M_C_CPU0_SB_DQS_DP<2>")
	)
	(segment
		(start 338.690966 -285.756096)
		(end 338.682584 -285.75127)
		(width 0.09525)
		(layer "In2.Cu")
		(net "M_C_CPU0_SB_DQS_DP<2>")
	)
	(segment
		(start 305.601116 -303.245012)
		(end 304.803556 -304.042572)
		(width 0.16002)
		(layer "In2.Cu")
		(net "M_C_CPU0_SB_DQS_DP<2>")
	)
	(segment
		(start 314.551822 -298.630086)
		(end 314.024518 -298.630086)
		(width 0.16002)
		(layer "In2.Cu")
		(net "M_C_CPU0_SB_DQS_DP<2>")
	)
	(segment
		(start 294.778684 -303.709832)
		(end 294.629586 -303.85893)
		(width 0.16002)
		(layer "In2.Cu")
		(net "M_C_CPU0_SB_DQS_DP<2>")
	)
	(segment
		(start 327.405746 -285.75127)
		(end 327.38187 -285.7373)
		(width 0.09525)
		(layer "In2.Cu")
		(net "M_C_CPU0_SB_DQS_DP<2>")
	)
	(segment
		(start 301.329598 -303.250346)
		(end 300.9392 -302.859948)
		(width 0.16002)
		(layer "In2.Cu")
		(net "M_C_CPU0_SB_DQS_DP<2>")
	)
	(segment
		(start 312.153554 -300.779688)
		(end 312.383424 -301.009558)
		(width 0.16002)
		(layer "In2.Cu")
		(net "M_C_CPU0_SB_DQS_DP<2>")
	)
	(segment
		(start 333.050896 -285.756096)
		(end 333.042514 -285.75127)
		(width 0.09525)
		(layer "In2.Cu")
		(net "M_C_CPU0_SB_DQS_DP<2>")
	)
	(segment
		(start 302.230536 -303.753012)
		(end 301.877476 -304.106072)
		(width 0.16002)
		(layer "In2.Cu")
		(net "M_C_CPU0_SB_DQS_DP<2>")
	)
	(segment
		(start 312.526426 -299.879258)
		(end 312.153554 -300.25213)
		(width 0.16002)
		(layer "In2.Cu")
		(net "M_C_CPU0_SB_DQS_DP<2>")
	)
	(segment
		(start 325.689214 -285.90875)
		(end 325.314818 -286.283146)
		(width 0.09525)
		(layer "In2.Cu")
		(net "M_C_CPU0_SB_DQS_DP<2>")
	)
	(segment
		(start 324.858634 -286.472122)
		(end 324.188328 -286.472122)
		(width 0.09525)
		(layer "In2.Cu")
		(net "M_C_CPU0_SB_DQS_DP<2>")
	)
	(segment
		(start 312.186574 -301.483014)
		(end 311.910222 -301.483014)
		(width 0.16002)
		(layer "In2.Cu")
		(net "M_C_CPU0_SB_DQS_DP<2>")
	)
	(segment
		(start 311.680098 -301.25289)
		(end 311.152794 -301.25289)
		(width 0.16002)
		(layer "In2.Cu")
		(net "M_C_CPU0_SB_DQS_DP<2>")
	)
	(arc
		(start 340.562438 -285.75127)
		(mid 340.281006 -285.675515)
		(end 339.999574 -285.75127)
		(width 0.09525)
		(layer "In2.Cu")
		(net "M_C_CPU0_SB_DQS_DP<2>")
	)
	(arc
		(start 335.862422 -285.75127)
		(mid 335.58099 -285.675515)
		(end 335.299558 -285.75127)
		(width 0.09525)
		(layer "In2.Cu")
		(net "M_C_CPU0_SB_DQS_DP<2>")
	)
	(arc
		(start 329.282552 -285.75127)
		(mid 329.00112 -285.675515)
		(end 328.719688 -285.75127)
		(width 0.09525)
		(layer "In2.Cu")
		(net "M_C_CPU0_SB_DQS_DP<2>")
	)
	(arc
		(start 325.314818 -286.283146)
		(mid 325.105519 -286.422995)
		(end 324.858634 -286.472122)
		(width 0.09525)
		(layer "In2.Cu")
		(net "M_C_CPU0_SB_DQS_DP<2>")
	)
	(arc
		(start 340.931246 -285.756096)
		(mid 340.746214 -285.80201)
		(end 340.562438 -285.75127)
		(width 0.09525)
		(layer "In2.Cu")
		(net "M_C_CPU0_SB_DQS_DP<2>")
	)
	(arc
		(start 336.802476 -285.75127)
		(mid 336.521044 -285.675515)
		(end 336.239612 -285.75127)
		(width 0.09525)
		(layer "In2.Cu")
		(net "M_C_CPU0_SB_DQS_DP<2>")
	)
	(arc
		(start 335.299558 -285.75127)
		(mid 335.11109 -285.801947)
		(end 334.922622 -285.75127)
		(width 0.09525)
		(layer "In2.Cu")
		(net "M_C_CPU0_SB_DQS_DP<2>")
	)
	(arc
		(start 339.622638 -285.75127)
		(mid 339.341206 -285.675515)
		(end 339.059774 -285.75127)
		(width 0.09525)
		(layer "In2.Cu")
		(net "M_C_CPU0_SB_DQS_DP<2>")
	)
	(arc
		(start 334.359758 -285.75127)
		(mid 334.175983 -285.802042)
		(end 333.99095 -285.756096)
		(width 0.09525)
		(layer "In2.Cu")
		(net "M_C_CPU0_SB_DQS_DP<2>")
	)
	(arc
		(start 339.059774 -285.75127)
		(mid 338.875999 -285.802042)
		(end 338.690966 -285.756096)
		(width 0.09525)
		(layer "In2.Cu")
		(net "M_C_CPU0_SB_DQS_DP<2>")
	)
	(arc
		(start 330.599542 -285.75127)
		(mid 330.411074 -285.801947)
		(end 330.222606 -285.75127)
		(width 0.09525)
		(layer "In2.Cu")
		(net "M_C_CPU0_SB_DQS_DP<2>")
	)
	(arc
		(start 341.8713 -285.756096)
		(mid 341.686268 -285.80201)
		(end 341.502492 -285.75127)
		(width 0.09525)
		(layer "In2.Cu")
		(net "M_C_CPU0_SB_DQS_DP<2>")
	)
	(arc
		(start 336.23123 -285.756096)
		(mid 336.046198 -285.80201)
		(end 335.862422 -285.75127)
		(width 0.09525)
		(layer "In2.Cu")
		(net "M_C_CPU0_SB_DQS_DP<2>")
	)
	(arc
		(start 326.841104 -285.751524)
		(mid 326.749552 -285.790065)
		(end 326.651112 -285.80334)
		(width 0.09525)
		(layer "In2.Cu")
		(net "M_C_CPU0_SB_DQS_DP<2>")
	)
	(arc
		(start 338.11972 -285.75127)
		(mid 337.935945 -285.802042)
		(end 337.750912 -285.756096)
		(width 0.09525)
		(layer "In2.Cu")
		(net "M_C_CPU0_SB_DQS_DP<2>")
	)
	(arc
		(start 333.982568 -285.75127)
		(mid 333.701136 -285.675515)
		(end 333.419704 -285.75127)
		(width 0.09525)
		(layer "In2.Cu")
		(net "M_C_CPU0_SB_DQS_DP<2>")
	)
	(arc
		(start 333.419704 -285.75127)
		(mid 333.235929 -285.802042)
		(end 333.050896 -285.756096)
		(width 0.09525)
		(layer "In2.Cu")
		(net "M_C_CPU0_SB_DQS_DP<2>")
	)
	(arc
		(start 332.10246 -285.75127)
		(mid 331.821028 -285.675515)
		(end 331.539596 -285.75127)
		(width 0.09525)
		(layer "In2.Cu")
		(net "M_C_CPU0_SB_DQS_DP<2>")
	)
	(arc
		(start 330.222606 -285.75127)
		(mid 329.941174 -285.675515)
		(end 329.659742 -285.75127)
		(width 0.09525)
		(layer "In2.Cu")
		(net "M_C_CPU0_SB_DQS_DP<2>")
	)
	(arc
		(start 331.531214 -285.756096)
		(mid 331.346182 -285.80201)
		(end 331.162406 -285.75127)
		(width 0.09525)
		(layer "In2.Cu")
		(net "M_C_CPU0_SB_DQS_DP<2>")
	)
	(arc
		(start 337.74253 -285.75127)
		(mid 337.461098 -285.675515)
		(end 337.179666 -285.75127)
		(width 0.09525)
		(layer "In2.Cu")
		(net "M_C_CPU0_SB_DQS_DP<2>")
	)
	(arc
		(start 334.922622 -285.75127)
		(mid 334.64119 -285.675515)
		(end 334.359758 -285.75127)
		(width 0.09525)
		(layer "In2.Cu")
		(net "M_C_CPU0_SB_DQS_DP<2>")
	)
	(arc
		(start 327.38187 -285.7373)
		(mid 327.109646 -285.674928)
		(end 326.841104 -285.751524)
		(width 0.09525)
		(layer "In2.Cu")
		(net "M_C_CPU0_SB_DQS_DP<2>")
	)
	(arc
		(start 337.171284 -285.756096)
		(mid 336.986252 -285.80201)
		(end 336.802476 -285.75127)
		(width 0.09525)
		(layer "In2.Cu")
		(net "M_C_CPU0_SB_DQS_DP<2>")
	)
	(arc
		(start 342.376252 -285.71825)
		(mid 342.124111 -285.67668)
		(end 341.879682 -285.75127)
		(width 0.09525)
		(layer "In2.Cu")
		(net "M_C_CPU0_SB_DQS_DP<2>")
	)
	(arc
		(start 325.943722 -285.80334)
		(mid 325.805987 -285.830737)
		(end 325.689214 -285.90875)
		(width 0.09525)
		(layer "In2.Cu")
		(net "M_C_CPU0_SB_DQS_DP<2>")
	)
	(arc
		(start 331.162406 -285.75127)
		(mid 330.880974 -285.675515)
		(end 330.599542 -285.75127)
		(width 0.09525)
		(layer "In2.Cu")
		(net "M_C_CPU0_SB_DQS_DP<2>")
	)
	(arc
		(start 339.999574 -285.75127)
		(mid 339.811106 -285.801947)
		(end 339.622638 -285.75127)
		(width 0.09525)
		(layer "In2.Cu")
		(net "M_C_CPU0_SB_DQS_DP<2>")
	)
	(arc
		(start 338.682584 -285.75127)
		(mid 338.401152 -285.675515)
		(end 338.11972 -285.75127)
		(width 0.09525)
		(layer "In2.Cu")
		(net "M_C_CPU0_SB_DQS_DP<2>")
	)
	(arc
		(start 329.659742 -285.75127)
		(mid 329.475967 -285.802042)
		(end 329.290934 -285.756096)
		(width 0.09525)
		(layer "In2.Cu")
		(net "M_C_CPU0_SB_DQS_DP<2>")
	)
	(arc
		(start 341.502492 -285.75127)
		(mid 341.22106 -285.675515)
		(end 340.939628 -285.75127)
		(width 0.09525)
		(layer "In2.Cu")
		(net "M_C_CPU0_SB_DQS_DP<2>")
	)
	(arc
		(start 333.042514 -285.75127)
		(mid 332.761082 -285.675515)
		(end 332.47965 -285.75127)
		(width 0.09525)
		(layer "In2.Cu")
		(net "M_C_CPU0_SB_DQS_DP<2>")
	)
	(arc
		(start 327.759568 -285.763462)
		(mid 327.581116 -285.801704)
		(end 327.405746 -285.75127)
		(width 0.09525)
		(layer "In2.Cu")
		(net "M_C_CPU0_SB_DQS_DP<2>")
	)
	(arc
		(start 332.471268 -285.756096)
		(mid 332.286236 -285.80201)
		(end 332.10246 -285.75127)
		(width 0.09525)
		(layer "In2.Cu")
		(net "M_C_CPU0_SB_DQS_DP<2>")
	)
	(arc
		(start 328.342498 -285.75127)
		(mid 328.075672 -285.675705)
		(end 327.805288 -285.7373)
		(width 0.09525)
		(layer "In2.Cu")
		(net "M_C_CPU0_SB_DQS_DP<2>")
	)
	(arc
		(start 328.711306 -285.756096)
		(mid 328.526274 -285.80201)
		(end 328.342498 -285.75127)
		(width 0.09525)
		(layer "In2.Cu")
		(net "M_C_CPU0_SB_DQS_DP<2>")
	)
	(segment
		(start 343.097866 -280.300176)
		(end 342.631014 -280.566114)
		(width 0.12954)
		(layer "F.Cu")
		(net "M_C_CPU0_SB_DQS_DP<1>")
	)
	(segment
		(start 311.058814 -291.169852)
		(end 311.431686 -290.79698)
		(width 0.16002)
		(layer "In2.Cu")
		(net "M_C_CPU0_SB_DQS_DP<1>")
	)
	(segment
		(start 316.498732 -285.630366)
		(end 316.735968 -285.630366)
		(width 0.16002)
		(layer "In2.Cu")
		(net "M_C_CPU0_SB_DQS_DP<1>")
	)
	(segment
		(start 311.4167 -292.055042)
		(end 311.058814 -291.697156)
		(width 0.16002)
		(layer "In2.Cu")
		(net "M_C_CPU0_SB_DQS_DP<1>")
	)
	(segment
		(start 323.919596 -280.78049)
		(end 323.978778 -280.839672)
		(width 0.09525)
		(layer "In2.Cu")
		(net "M_C_CPU0_SB_DQS_DP<1>")
	)
	(segment
		(start 311.431686 -290.79698)
		(end 311.95899 -290.79698)
		(width 0.16002)
		(layer "In2.Cu")
		(net "M_C_CPU0_SB_DQS_DP<1>")
	)
	(segment
		(start 309.685182 -293.070788)
		(end 309.685182 -292.543484)
		(width 0.16002)
		(layer "In2.Cu")
		(net "M_C_CPU0_SB_DQS_DP<1>")
	)
	(segment
		(start 312.476134 -290.367212)
		(end 312.476134 -289.8902)
		(width 0.16002)
		(layer "In2.Cu")
		(net "M_C_CPU0_SB_DQS_DP<1>")
	)
	(segment
		(start 313.988704 -288.37763)
		(end 314.34278 -288.023554)
		(width 0.16002)
		(layer "In2.Cu")
		(net "M_C_CPU0_SB_DQS_DP<1>")
	)
	(segment
		(start 321.585844 -280.78049)
		(end 323.895974 -280.78049)
		(width 0.16002)
		(layer "In2.Cu")
		(net "M_C_CPU0_SB_DQS_DP<1>")
	)
	(segment
		(start 325.518526 -280.52776)
		(end 325.932546 -280.94178)
		(width 0.09525)
		(layer "In2.Cu")
		(net "M_C_CPU0_SB_DQS_DP<1>")
	)
	(segment
		(start 312.790332 -290.95827)
		(end 312.790332 -290.68141)
		(width 0.16002)
		(layer "In2.Cu")
		(net "M_C_CPU0_SB_DQS_DP<1>")
	)
	(segment
		(start 328.711306 -280.89606)
		(end 328.719688 -280.891234)
		(width 0.09525)
		(layer "In2.Cu")
		(net "M_C_CPU0_SB_DQS_DP<1>")
	)
	(segment
		(start 308.769258 -294.375332)
		(end 308.929278 -294.535352)
		(width 0.16002)
		(layer "In2.Cu")
		(net "M_C_CPU0_SB_DQS_DP<1>")
	)
	(segment
		(start 304.803556 -294.692578)
		(end 305.601116 -293.895018)
		(width 0.16002)
		(layer "In2.Cu")
		(net "M_C_CPU0_SB_DQS_DP<1>")
	)
	(segment
		(start 329.282552 -280.891234)
		(end 329.290934 -280.89606)
		(width 0.09525)
		(layer "In2.Cu")
		(net "M_C_CPU0_SB_DQS_DP<1>")
	)
	(segment
		(start 310.043068 -293.713154)
		(end 310.043068 -293.428674)
		(width 0.16002)
		(layer "In2.Cu")
		(net "M_C_CPU0_SB_DQS_DP<1>")
	)
	(segment
		(start 296.61866 -294.359838)
		(end 296.93362 -294.674798)
		(width 0.16002)
		(layer "In2.Cu")
		(net "M_C_CPU0_SB_DQS_DP<1>")
	)
	(segment
		(start 305.601116 -293.895018)
		(end 306.078636 -293.895018)
		(width 0.16002)
		(layer "In2.Cu")
		(net "M_C_CPU0_SB_DQS_DP<1>")
	)
	(segment
		(start 306.078636 -293.895018)
		(end 306.429156 -293.544498)
		(width 0.16002)
		(layer "In2.Cu")
		(net "M_C_CPU0_SB_DQS_DP<1>")
	)
	(segment
		(start 340.931246 -280.89606)
		(end 340.939628 -280.891234)
		(width 0.09525)
		(layer "In2.Cu")
		(net "M_C_CPU0_SB_DQS_DP<1>")
	)
	(segment
		(start 333.982568 -280.891234)
		(end 333.99095 -280.89606)
		(width 0.09525)
		(layer "In2.Cu")
		(net "M_C_CPU0_SB_DQS_DP<1>")
	)
	(segment
		(start 324.323964 -280.839672)
		(end 324.635876 -280.52776)
		(width 0.09525)
		(layer "In2.Cu")
		(net "M_C_CPU0_SB_DQS_DP<1>")
	)
	(segment
		(start 311.058814 -291.697156)
		(end 311.058814 -291.169852)
		(width 0.16002)
		(layer "In2.Cu")
		(net "M_C_CPU0_SB_DQS_DP<1>")
	)
	(segment
		(start 314.34278 -287.786318)
		(end 315.1251 -287.003998)
		(width 0.16002)
		(layer "In2.Cu")
		(net "M_C_CPU0_SB_DQS_DP<1>")
	)
	(segment
		(start 316.735968 -285.630366)
		(end 321.585844 -280.78049)
		(width 0.16002)
		(layer "In2.Cu")
		(net "M_C_CPU0_SB_DQS_DP<1>")
	)
	(segment
		(start 297.266868 -294.674798)
		(end 298.120308 -293.821358)
		(width 0.16002)
		(layer "In2.Cu")
		(net "M_C_CPU0_SB_DQS_DP<1>")
	)
	(segment
		(start 292.280086 -294.235124)
		(end 292.553898 -294.508936)
		(width 0.16002)
		(layer "In2.Cu")
		(net "M_C_CPU0_SB_DQS_DP<1>")
	)
	(segment
		(start 310.943244 -292.528498)
		(end 311.220104 -292.528498)
		(width 0.16002)
		(layer "In2.Cu")
		(net "M_C_CPU0_SB_DQS_DP<1>")
	)
	(segment
		(start 309.22087 -294.535352)
		(end 310.043068 -293.713154)
		(width 0.16002)
		(layer "In2.Cu")
		(net "M_C_CPU0_SB_DQS_DP<1>")
	)
	(segment
		(start 315.1251 -287.003998)
		(end 315.362336 -287.003998)
		(width 0.16002)
		(layer "In2.Cu")
		(net "M_C_CPU0_SB_DQS_DP<1>")
	)
	(segment
		(start 292.553898 -294.508936)
		(end 293.247826 -294.508936)
		(width 0.16002)
		(layer "In2.Cu")
		(net "M_C_CPU0_SB_DQS_DP<1>")
	)
	(segment
		(start 304.487072 -294.692578)
		(end 304.803556 -294.692578)
		(width 0.16002)
		(layer "In2.Cu")
		(net "M_C_CPU0_SB_DQS_DP<1>")
	)
	(segment
		(start 308.769258 -293.95039)
		(end 308.769258 -294.375332)
		(width 0.16002)
		(layer "In2.Cu")
		(net "M_C_CPU0_SB_DQS_DP<1>")
	)
	(segment
		(start 315.716412 -286.412686)
		(end 316.498732 -285.630366)
		(width 0.16002)
		(layer "In2.Cu")
		(net "M_C_CPU0_SB_DQS_DP<1>")
	)
	(segment
		(start 311.220104 -292.528498)
		(end 311.4167 -292.331902)
		(width 0.16002)
		(layer "In2.Cu")
		(net "M_C_CPU0_SB_DQS_DP<1>")
	)
	(segment
		(start 312.316876 -291.154866)
		(end 312.593736 -291.154866)
		(width 0.16002)
		(layer "In2.Cu")
		(net "M_C_CPU0_SB_DQS_DP<1>")
	)
	(segment
		(start 308.929278 -294.535352)
		(end 309.22087 -294.535352)
		(width 0.16002)
		(layer "In2.Cu")
		(net "M_C_CPU0_SB_DQS_DP<1>")
	)
	(segment
		(start 301.96536 -294.403018)
		(end 304.197512 -294.403018)
		(width 0.16002)
		(layer "In2.Cu")
		(net "M_C_CPU0_SB_DQS_DP<1>")
	)
	(segment
		(start 333.042514 -280.891234)
		(end 333.050896 -280.89606)
		(width 0.09525)
		(layer "In2.Cu")
		(net "M_C_CPU0_SB_DQS_DP<1>")
	)
	(segment
		(start 298.644056 -293.821358)
		(end 298.95546 -293.509954)
		(width 0.16002)
		(layer "In2.Cu")
		(net "M_C_CPU0_SB_DQS_DP<1>")
	)
	(segment
		(start 325.932546 -280.94178)
		(end 327.594214 -280.94178)
		(width 0.09525)
		(layer "In2.Cu")
		(net "M_C_CPU0_SB_DQS_DP<1>")
	)
	(segment
		(start 341.8713 -280.89606)
		(end 341.879682 -280.891234)
		(width 0.09525)
		(layer "In2.Cu")
		(net "M_C_CPU0_SB_DQS_DP<1>")
	)
	(segment
		(start 323.895974 -280.78049)
		(end 323.919596 -280.78049)
		(width 0.09525)
		(layer "In2.Cu")
		(net "M_C_CPU0_SB_DQS_DP<1>")
	)
	(segment
		(start 314.34278 -288.023554)
		(end 314.34278 -287.786318)
		(width 0.16002)
		(layer "In2.Cu")
		(net "M_C_CPU0_SB_DQS_DP<1>")
	)
	(segment
		(start 342.47709 -280.831544)
		(end 342.631014 -280.566114)
		(width 0.09525)
		(layer "In2.Cu")
		(net "M_C_CPU0_SB_DQS_DP<1>")
	)
	(segment
		(start 312.969148 -289.397186)
		(end 312.969148 -289.15995)
		(width 0.16002)
		(layer "In2.Cu")
		(net "M_C_CPU0_SB_DQS_DP<1>")
	)
	(segment
		(start 336.23123 -280.89606)
		(end 336.239612 -280.891234)
		(width 0.09525)
		(layer "In2.Cu")
		(net "M_C_CPU0_SB_DQS_DP<1>")
	)
	(segment
		(start 298.120308 -293.821358)
		(end 298.644056 -293.821358)
		(width 0.16002)
		(layer "In2.Cu")
		(net "M_C_CPU0_SB_DQS_DP<1>")
	)
	(segment
		(start 311.95899 -290.79698)
		(end 312.316876 -291.154866)
		(width 0.16002)
		(layer "In2.Cu")
		(net "M_C_CPU0_SB_DQS_DP<1>")
	)
	(segment
		(start 324.635876 -280.52776)
		(end 325.518526 -280.52776)
		(width 0.09525)
		(layer "In2.Cu")
		(net "M_C_CPU0_SB_DQS_DP<1>")
	)
	(segment
		(start 337.171284 -280.89606)
		(end 337.179666 -280.891234)
		(width 0.09525)
		(layer "In2.Cu")
		(net "M_C_CPU0_SB_DQS_DP<1>")
	)
	(segment
		(start 306.429156 -293.544498)
		(end 308.363366 -293.544498)
		(width 0.16002)
		(layer "In2.Cu")
		(net "M_C_CPU0_SB_DQS_DP<1>")
	)
	(segment
		(start 312.969148 -289.15995)
		(end 313.751468 -288.37763)
		(width 0.16002)
		(layer "In2.Cu")
		(net "M_C_CPU0_SB_DQS_DP<1>")
	)
	(segment
		(start 311.4167 -292.331902)
		(end 311.4167 -292.055042)
		(width 0.16002)
		(layer "In2.Cu")
		(net "M_C_CPU0_SB_DQS_DP<1>")
	)
	(segment
		(start 342.376252 -280.858214)
		(end 342.47709 -280.831544)
		(width 0.09525)
		(layer "In2.Cu")
		(net "M_C_CPU0_SB_DQS_DP<1>")
	)
	(segment
		(start 310.058054 -292.170612)
		(end 310.585358 -292.170612)
		(width 0.16002)
		(layer "In2.Cu")
		(net "M_C_CPU0_SB_DQS_DP<1>")
	)
	(segment
		(start 308.363366 -293.544498)
		(end 308.769258 -293.95039)
		(width 0.16002)
		(layer "In2.Cu")
		(net "M_C_CPU0_SB_DQS_DP<1>")
	)
	(segment
		(start 312.593736 -291.154866)
		(end 312.790332 -290.95827)
		(width 0.16002)
		(layer "In2.Cu")
		(net "M_C_CPU0_SB_DQS_DP<1>")
	)
	(segment
		(start 301.072296 -293.509954)
		(end 301.96536 -294.403018)
		(width 0.16002)
		(layer "In2.Cu")
		(net "M_C_CPU0_SB_DQS_DP<1>")
	)
	(segment
		(start 309.685182 -292.543484)
		(end 310.058054 -292.170612)
		(width 0.16002)
		(layer "In2.Cu")
		(net "M_C_CPU0_SB_DQS_DP<1>")
	)
	(segment
		(start 313.751468 -288.37763)
		(end 313.988704 -288.37763)
		(width 0.16002)
		(layer "In2.Cu")
		(net "M_C_CPU0_SB_DQS_DP<1>")
	)
	(segment
		(start 293.396924 -294.359838)
		(end 296.61866 -294.359838)
		(width 0.16002)
		(layer "In2.Cu")
		(net "M_C_CPU0_SB_DQS_DP<1>")
	)
	(segment
		(start 312.790332 -290.68141)
		(end 312.476134 -290.367212)
		(width 0.16002)
		(layer "In2.Cu")
		(net "M_C_CPU0_SB_DQS_DP<1>")
	)
	(segment
		(start 304.197512 -294.403018)
		(end 304.487072 -294.692578)
		(width 0.16002)
		(layer "In2.Cu")
		(net "M_C_CPU0_SB_DQS_DP<1>")
	)
	(segment
		(start 293.247826 -294.508936)
		(end 293.396924 -294.359838)
		(width 0.16002)
		(layer "In2.Cu")
		(net "M_C_CPU0_SB_DQS_DP<1>")
	)
	(segment
		(start 315.362336 -287.003998)
		(end 315.716412 -286.649922)
		(width 0.16002)
		(layer "In2.Cu")
		(net "M_C_CPU0_SB_DQS_DP<1>")
	)
	(segment
		(start 296.93362 -294.674798)
		(end 297.266868 -294.674798)
		(width 0.16002)
		(layer "In2.Cu")
		(net "M_C_CPU0_SB_DQS_DP<1>")
	)
	(segment
		(start 312.476134 -289.8902)
		(end 312.969148 -289.397186)
		(width 0.16002)
		(layer "In2.Cu")
		(net "M_C_CPU0_SB_DQS_DP<1>")
	)
	(segment
		(start 310.585358 -292.170612)
		(end 310.943244 -292.528498)
		(width 0.16002)
		(layer "In2.Cu")
		(net "M_C_CPU0_SB_DQS_DP<1>")
	)
	(segment
		(start 331.531214 -280.89606)
		(end 331.539596 -280.891234)
		(width 0.09525)
		(layer "In2.Cu")
		(net "M_C_CPU0_SB_DQS_DP<1>")
	)
	(segment
		(start 310.043068 -293.428674)
		(end 309.685182 -293.070788)
		(width 0.16002)
		(layer "In2.Cu")
		(net "M_C_CPU0_SB_DQS_DP<1>")
	)
	(segment
		(start 327.781412 -280.89098)
		(end 327.805288 -280.877264)
		(width 0.09525)
		(layer "In2.Cu")
		(net "M_C_CPU0_SB_DQS_DP<1>")
	)
	(segment
		(start 337.74253 -280.891234)
		(end 337.750912 -280.89606)
		(width 0.09525)
		(layer "In2.Cu")
		(net "M_C_CPU0_SB_DQS_DP<1>")
	)
	(segment
		(start 315.716412 -286.649922)
		(end 315.716412 -286.412686)
		(width 0.16002)
		(layer "In2.Cu")
		(net "M_C_CPU0_SB_DQS_DP<1>")
	)
	(segment
		(start 298.95546 -293.509954)
		(end 301.072296 -293.509954)
		(width 0.16002)
		(layer "In2.Cu")
		(net "M_C_CPU0_SB_DQS_DP<1>")
	)
	(segment
		(start 338.682584 -280.891234)
		(end 338.690966 -280.89606)
		(width 0.09525)
		(layer "In2.Cu")
		(net "M_C_CPU0_SB_DQS_DP<1>")
	)
	(segment
		(start 332.471268 -280.89606)
		(end 332.47965 -280.891234)
		(width 0.09525)
		(layer "In2.Cu")
		(net "M_C_CPU0_SB_DQS_DP<1>")
	)
	(segment
		(start 323.978778 -280.839672)
		(end 324.323964 -280.839672)
		(width 0.09525)
		(layer "In2.Cu")
		(net "M_C_CPU0_SB_DQS_DP<1>")
	)
	(arc
		(start 328.342498 -280.891234)
		(mid 328.526273 -280.942006)
		(end 328.711306 -280.89606)
		(width 0.09525)
		(layer "In2.Cu")
		(net "M_C_CPU0_SB_DQS_DP<1>")
	)
	(arc
		(start 333.99095 -280.89606)
		(mid 334.175982 -280.941974)
		(end 334.359758 -280.891234)
		(width 0.09525)
		(layer "In2.Cu")
		(net "M_C_CPU0_SB_DQS_DP<1>")
	)
	(arc
		(start 341.879682 -280.891234)
		(mid 342.113477 -280.817367)
		(end 342.35644 -280.85034)
		(width 0.09525)
		(layer "In2.Cu")
		(net "M_C_CPU0_SB_DQS_DP<1>")
	)
	(arc
		(start 337.750912 -280.89606)
		(mid 337.935944 -280.941974)
		(end 338.11972 -280.891234)
		(width 0.09525)
		(layer "In2.Cu")
		(net "M_C_CPU0_SB_DQS_DP<1>")
	)
	(arc
		(start 337.179666 -280.891234)
		(mid 337.461098 -280.815479)
		(end 337.74253 -280.891234)
		(width 0.09525)
		(layer "In2.Cu")
		(net "M_C_CPU0_SB_DQS_DP<1>")
	)
	(arc
		(start 330.222606 -280.891234)
		(mid 330.411074 -280.941911)
		(end 330.599542 -280.891234)
		(width 0.09525)
		(layer "In2.Cu")
		(net "M_C_CPU0_SB_DQS_DP<1>")
	)
	(arc
		(start 329.659742 -280.891234)
		(mid 329.941174 -280.815479)
		(end 330.222606 -280.891234)
		(width 0.09525)
		(layer "In2.Cu")
		(net "M_C_CPU0_SB_DQS_DP<1>")
	)
	(arc
		(start 330.599542 -280.891234)
		(mid 330.880974 -280.815479)
		(end 331.162406 -280.891234)
		(width 0.09525)
		(layer "In2.Cu")
		(net "M_C_CPU0_SB_DQS_DP<1>")
	)
	(arc
		(start 332.47965 -280.891234)
		(mid 332.761082 -280.815479)
		(end 333.042514 -280.891234)
		(width 0.09525)
		(layer "In2.Cu")
		(net "M_C_CPU0_SB_DQS_DP<1>")
	)
	(arc
		(start 333.050896 -280.89606)
		(mid 333.235928 -280.941974)
		(end 333.419704 -280.891234)
		(width 0.09525)
		(layer "In2.Cu")
		(net "M_C_CPU0_SB_DQS_DP<1>")
	)
	(arc
		(start 336.239612 -280.891234)
		(mid 336.521044 -280.815479)
		(end 336.802476 -280.891234)
		(width 0.09525)
		(layer "In2.Cu")
		(net "M_C_CPU0_SB_DQS_DP<1>")
	)
	(arc
		(start 338.690966 -280.89606)
		(mid 338.875998 -280.941974)
		(end 339.059774 -280.891234)
		(width 0.09525)
		(layer "In2.Cu")
		(net "M_C_CPU0_SB_DQS_DP<1>")
	)
	(arc
		(start 338.11972 -280.891234)
		(mid 338.401152 -280.815479)
		(end 338.682584 -280.891234)
		(width 0.09525)
		(layer "In2.Cu")
		(net "M_C_CPU0_SB_DQS_DP<1>")
	)
	(arc
		(start 334.922622 -280.891234)
		(mid 335.11109 -280.941911)
		(end 335.299558 -280.891234)
		(width 0.09525)
		(layer "In2.Cu")
		(net "M_C_CPU0_SB_DQS_DP<1>")
	)
	(arc
		(start 329.290934 -280.89606)
		(mid 329.475966 -280.941974)
		(end 329.659742 -280.891234)
		(width 0.09525)
		(layer "In2.Cu")
		(net "M_C_CPU0_SB_DQS_DP<1>")
	)
	(arc
		(start 334.359758 -280.891234)
		(mid 334.64119 -280.815479)
		(end 334.922622 -280.891234)
		(width 0.09525)
		(layer "In2.Cu")
		(net "M_C_CPU0_SB_DQS_DP<1>")
	)
	(arc
		(start 332.10246 -280.891234)
		(mid 332.286235 -280.942006)
		(end 332.471268 -280.89606)
		(width 0.09525)
		(layer "In2.Cu")
		(net "M_C_CPU0_SB_DQS_DP<1>")
	)
	(arc
		(start 327.594214 -280.94178)
		(mid 327.691137 -280.928645)
		(end 327.781412 -280.89098)
		(width 0.09525)
		(layer "In2.Cu")
		(net "M_C_CPU0_SB_DQS_DP<1>")
	)
	(arc
		(start 341.502492 -280.891234)
		(mid 341.686267 -280.942006)
		(end 341.8713 -280.89606)
		(width 0.09525)
		(layer "In2.Cu")
		(net "M_C_CPU0_SB_DQS_DP<1>")
	)
	(arc
		(start 331.539596 -280.891234)
		(mid 331.821028 -280.815479)
		(end 332.10246 -280.891234)
		(width 0.09525)
		(layer "In2.Cu")
		(net "M_C_CPU0_SB_DQS_DP<1>")
	)
	(arc
		(start 328.719688 -280.891234)
		(mid 329.00112 -280.815479)
		(end 329.282552 -280.891234)
		(width 0.09525)
		(layer "In2.Cu")
		(net "M_C_CPU0_SB_DQS_DP<1>")
	)
	(arc
		(start 340.939628 -280.891234)
		(mid 341.22106 -280.815479)
		(end 341.502492 -280.891234)
		(width 0.09525)
		(layer "In2.Cu")
		(net "M_C_CPU0_SB_DQS_DP<1>")
	)
	(arc
		(start 335.862422 -280.891234)
		(mid 336.046197 -280.942006)
		(end 336.23123 -280.89606)
		(width 0.09525)
		(layer "In2.Cu")
		(net "M_C_CPU0_SB_DQS_DP<1>")
	)
	(arc
		(start 331.162406 -280.891234)
		(mid 331.346181 -280.942006)
		(end 331.531214 -280.89606)
		(width 0.09525)
		(layer "In2.Cu")
		(net "M_C_CPU0_SB_DQS_DP<1>")
	)
	(arc
		(start 327.805288 -280.877264)
		(mid 328.075671 -280.815704)
		(end 328.342498 -280.891234)
		(width 0.09525)
		(layer "In2.Cu")
		(net "M_C_CPU0_SB_DQS_DP<1>")
	)
	(arc
		(start 339.059774 -280.891234)
		(mid 339.341206 -280.815479)
		(end 339.622638 -280.891234)
		(width 0.09525)
		(layer "In2.Cu")
		(net "M_C_CPU0_SB_DQS_DP<1>")
	)
	(arc
		(start 333.419704 -280.891234)
		(mid 333.701136 -280.815479)
		(end 333.982568 -280.891234)
		(width 0.09525)
		(layer "In2.Cu")
		(net "M_C_CPU0_SB_DQS_DP<1>")
	)
	(arc
		(start 342.35644 -280.85034)
		(mid 342.366383 -280.854183)
		(end 342.376252 -280.858214)
		(width 0.09525)
		(layer "In2.Cu")
		(net "M_C_CPU0_SB_DQS_DP<1>")
	)
	(arc
		(start 339.622638 -280.891234)
		(mid 339.811106 -280.941911)
		(end 339.999574 -280.891234)
		(width 0.09525)
		(layer "In2.Cu")
		(net "M_C_CPU0_SB_DQS_DP<1>")
	)
	(arc
		(start 339.999574 -280.891234)
		(mid 340.281006 -280.815479)
		(end 340.562438 -280.891234)
		(width 0.09525)
		(layer "In2.Cu")
		(net "M_C_CPU0_SB_DQS_DP<1>")
	)
	(arc
		(start 340.562438 -280.891234)
		(mid 340.746213 -280.942006)
		(end 340.931246 -280.89606)
		(width 0.09525)
		(layer "In2.Cu")
		(net "M_C_CPU0_SB_DQS_DP<1>")
	)
	(arc
		(start 336.802476 -280.891234)
		(mid 336.986251 -280.942006)
		(end 337.171284 -280.89606)
		(width 0.09525)
		(layer "In2.Cu")
		(net "M_C_CPU0_SB_DQS_DP<1>")
	)
	(arc
		(start 335.299558 -280.891234)
		(mid 335.58099 -280.815479)
		(end 335.862422 -280.891234)
		(width 0.09525)
		(layer "In2.Cu")
		(net "M_C_CPU0_SB_DQS_DP<1>")
	)
	(segment
		(start 343.097866 -275.44014)
		(end 342.631014 -275.706078)
		(width 0.12954)
		(layer "F.Cu")
		(net "M_C_CPU0_SB_DQS_DP<0>")
	)
	(segment
		(start 323.919596 -275.15693)
		(end 323.895974 -275.15693)
		(width 0.09525)
		(layer "In2.Cu")
		(net "M_C_CPU0_SB_DQS_DP<0>")
	)
	(segment
		(start 337.750912 -276.036024)
		(end 337.74253 -276.031198)
		(width 0.09525)
		(layer "In2.Cu")
		(net "M_C_CPU0_SB_DQS_DP<0>")
	)
	(segment
		(start 326.651112 -276.081236)
		(end 326.302624 -276.081236)
		(width 0.09525)
		(layer "In2.Cu")
		(net "M_C_CPU0_SB_DQS_DP<0>")
	)
	(segment
		(start 313.645296 -280.124662)
		(end 313.645296 -280.646632)
		(width 0.16002)
		(layer "In2.Cu")
		(net "M_C_CPU0_SB_DQS_DP<0>")
	)
	(segment
		(start 315.533278 -278.23668)
		(end 315.018928 -278.75103)
		(width 0.16002)
		(layer "In2.Cu")
		(net "M_C_CPU0_SB_DQS_DP<0>")
	)
	(segment
		(start 341.879682 -276.031198)
		(end 341.8713 -276.036024)
		(width 0.09525)
		(layer "In2.Cu")
		(net "M_C_CPU0_SB_DQS_DP<0>")
	)
	(segment
		(start 333.050896 -276.036024)
		(end 333.042514 -276.031198)
		(width 0.09525)
		(layer "In2.Cu")
		(net "M_C_CPU0_SB_DQS_DP<0>")
	)
	(segment
		(start 301.892716 -285.401512)
		(end 301.61992 -285.401512)
		(width 0.16002)
		(layer "In2.Cu")
		(net "M_C_CPU0_SB_DQS_DP<0>")
	)
	(segment
		(start 298.935648 -284.15996)
		(end 298.624244 -284.471364)
		(width 0.16002)
		(layer "In2.Cu")
		(net "M_C_CPU0_SB_DQS_DP<0>")
	)
	(segment
		(start 311.39765 -281.352752)
		(end 310.918352 -281.83205)
		(width 0.16002)
		(layer "In2.Cu")
		(net "M_C_CPU0_SB_DQS_DP<0>")
	)
	(segment
		(start 336.239612 -276.031198)
		(end 336.23123 -276.036024)
		(width 0.09525)
		(layer "In2.Cu")
		(net "M_C_CPU0_SB_DQS_DP<0>")
	)
	(segment
		(start 318.80556 -275.489416)
		(end 318.280542 -275.489416)
		(width 0.16002)
		(layer "In2.Cu")
		(net "M_C_CPU0_SB_DQS_DP<0>")
	)
	(segment
		(start 313.645296 -280.646632)
		(end 312.939176 -281.352752)
		(width 0.16002)
		(layer "In2.Cu")
		(net "M_C_CPU0_SB_DQS_DP<0>")
	)
	(segment
		(start 317.431928 -276.863048)
		(end 316.90691 -276.863048)
		(width 0.16002)
		(layer "In2.Cu")
		(net "M_C_CPU0_SB_DQS_DP<0>")
	)
	(segment
		(start 329.290934 -276.036024)
		(end 329.282552 -276.031198)
		(width 0.09525)
		(layer "In2.Cu")
		(net "M_C_CPU0_SB_DQS_DP<0>")
	)
	(segment
		(start 323.895974 -275.15693)
		(end 319.138046 -275.15693)
		(width 0.16002)
		(layer "In2.Cu")
		(net "M_C_CPU0_SB_DQS_DP<0>")
	)
	(segment
		(start 306.078636 -284.545024)
		(end 305.601116 -284.545024)
		(width 0.16002)
		(layer "In2.Cu")
		(net "M_C_CPU0_SB_DQS_DP<0>")
	)
	(segment
		(start 309.423054 -284.545786)
		(end 309.071264 -284.193996)
		(width 0.16002)
		(layer "In2.Cu")
		(net "M_C_CPU0_SB_DQS_DP<0>")
	)
	(segment
		(start 316.39256 -277.377398)
		(end 316.39256 -277.902416)
		(width 0.16002)
		(layer "In2.Cu")
		(net "M_C_CPU0_SB_DQS_DP<0>")
	)
	(segment
		(start 311.073546 -283.172154)
		(end 310.796686 -283.172154)
		(width 0.16002)
		(layer "In2.Cu")
		(net "M_C_CPU0_SB_DQS_DP<0>")
	)
	(segment
		(start 309.512462 -283.161232)
		(end 309.512462 -283.688536)
		(width 0.16002)
		(layer "In2.Cu")
		(net "M_C_CPU0_SB_DQS_DP<0>")
	)
	(segment
		(start 338.690966 -276.036024)
		(end 338.682584 -276.031198)
		(width 0.09525)
		(layer "In2.Cu")
		(net "M_C_CPU0_SB_DQS_DP<0>")
	)
	(segment
		(start 296.61866 -285.009844)
		(end 293.59098 -285.009844)
		(width 0.16002)
		(layer "In2.Cu")
		(net "M_C_CPU0_SB_DQS_DP<0>")
	)
	(segment
		(start 342.47709 -275.971508)
		(end 342.376252 -275.998178)
		(width 0.09525)
		(layer "In2.Cu")
		(net "M_C_CPU0_SB_DQS_DP<0>")
	)
	(segment
		(start 318.280542 -275.489416)
		(end 317.766192 -276.003766)
		(width 0.16002)
		(layer "In2.Cu")
		(net "M_C_CPU0_SB_DQS_DP<0>")
	)
	(segment
		(start 292.553898 -285.158942)
		(end 292.280086 -284.88513)
		(width 0.16002)
		(layer "In2.Cu")
		(net "M_C_CPU0_SB_DQS_DP<0>")
	)
	(segment
		(start 316.39256 -277.902416)
		(end 316.058296 -278.23668)
		(width 0.16002)
		(layer "In2.Cu")
		(net "M_C_CPU0_SB_DQS_DP<0>")
	)
	(segment
		(start 309.89651 -284.348936)
		(end 309.69966 -284.545786)
		(width 0.16002)
		(layer "In2.Cu")
		(net "M_C_CPU0_SB_DQS_DP<0>")
	)
	(segment
		(start 317.766192 -276.528784)
		(end 317.431928 -276.863048)
		(width 0.16002)
		(layer "In2.Cu")
		(net "M_C_CPU0_SB_DQS_DP<0>")
	)
	(segment
		(start 293.441882 -285.158942)
		(end 292.553898 -285.158942)
		(width 0.16002)
		(layer "In2.Cu")
		(net "M_C_CPU0_SB_DQS_DP<0>")
	)
	(segment
		(start 308.668674 -284.194504)
		(end 306.429156 -284.194504)
		(width 0.16002)
		(layer "In2.Cu")
		(net "M_C_CPU0_SB_DQS_DP<0>")
	)
	(segment
		(start 316.058296 -278.23668)
		(end 315.533278 -278.23668)
		(width 0.16002)
		(layer "In2.Cu")
		(net "M_C_CPU0_SB_DQS_DP<0>")
	)
	(segment
		(start 314.159646 -279.610312)
		(end 313.645296 -280.124662)
		(width 0.16002)
		(layer "In2.Cu")
		(net "M_C_CPU0_SB_DQS_DP<0>")
	)
	(segment
		(start 301.072296 -284.15996)
		(end 298.935648 -284.15996)
		(width 0.16002)
		(layer "In2.Cu")
		(net "M_C_CPU0_SB_DQS_DP<0>")
	)
	(segment
		(start 310.918352 -282.347162)
		(end 311.270142 -282.698952)
		(width 0.16002)
		(layer "In2.Cu")
		(net "M_C_CPU0_SB_DQS_DP<0>")
	)
	(segment
		(start 316.90691 -276.863048)
		(end 316.39256 -277.377398)
		(width 0.16002)
		(layer "In2.Cu")
		(net "M_C_CPU0_SB_DQS_DP<0>")
	)
	(segment
		(start 326.302624 -276.081236)
		(end 325.279004 -275.65731)
		(width 0.09525)
		(layer "In2.Cu")
		(net "M_C_CPU0_SB_DQS_DP<0>")
	)
	(segment
		(start 328.342498 -276.031198)
		(end 328.310748 -276.012656)
		(width 0.09525)
		(layer "In2.Cu")
		(net "M_C_CPU0_SB_DQS_DP<0>")
	)
	(segment
		(start 305.601116 -284.545024)
		(end 304.803556 -285.342584)
		(width 0.16002)
		(layer "In2.Cu")
		(net "M_C_CPU0_SB_DQS_DP<0>")
	)
	(segment
		(start 311.270142 -282.975558)
		(end 311.073546 -283.172154)
		(width 0.16002)
		(layer "In2.Cu")
		(net "M_C_CPU0_SB_DQS_DP<0>")
	)
	(segment
		(start 328.719688 -276.031198)
		(end 328.711306 -276.036024)
		(width 0.09525)
		(layer "In2.Cu")
		(net "M_C_CPU0_SB_DQS_DP<0>")
	)
	(segment
		(start 325.279004 -275.65731)
		(end 324.798182 -275.65731)
		(width 0.09525)
		(layer "In2.Cu")
		(net "M_C_CPU0_SB_DQS_DP<0>")
	)
	(segment
		(start 304.803556 -285.342584)
		(end 304.504344 -285.342584)
		(width 0.16002)
		(layer "In2.Cu")
		(net "M_C_CPU0_SB_DQS_DP<0>")
	)
	(segment
		(start 301.410878 -285.19247)
		(end 301.410878 -284.498542)
		(width 0.16002)
		(layer "In2.Cu")
		(net "M_C_CPU0_SB_DQS_DP<0>")
	)
	(segment
		(start 337.179666 -276.031198)
		(end 337.171284 -276.036024)
		(width 0.09525)
		(layer "In2.Cu")
		(net "M_C_CPU0_SB_DQS_DP<0>")
	)
	(segment
		(start 309.071264 -284.193996)
		(end 308.668674 -284.194504)
		(width 0.16002)
		(layer "In2.Cu")
		(net "M_C_CPU0_SB_DQS_DP<0>")
	)
	(segment
		(start 315.018928 -279.276048)
		(end 314.684664 -279.610312)
		(width 0.16002)
		(layer "In2.Cu")
		(net "M_C_CPU0_SB_DQS_DP<0>")
	)
	(segment
		(start 309.512462 -283.688536)
		(end 309.89651 -284.072584)
		(width 0.16002)
		(layer "In2.Cu")
		(net "M_C_CPU0_SB_DQS_DP<0>")
	)
	(segment
		(start 304.504344 -285.342584)
		(end 304.214784 -285.053024)
		(width 0.16002)
		(layer "In2.Cu")
		(net "M_C_CPU0_SB_DQS_DP<0>")
	)
	(segment
		(start 327.42378 -276.046438)
		(end 327.397364 -276.031198)
		(width 0.09525)
		(layer "In2.Cu")
		(net "M_C_CPU0_SB_DQS_DP<0>")
	)
	(segment
		(start 301.410878 -284.498542)
		(end 301.072296 -284.15996)
		(width 0.16002)
		(layer "In2.Cu")
		(net "M_C_CPU0_SB_DQS_DP<0>")
	)
	(segment
		(start 314.684664 -279.610312)
		(end 314.159646 -279.610312)
		(width 0.16002)
		(layer "In2.Cu")
		(net "M_C_CPU0_SB_DQS_DP<0>")
	)
	(segment
		(start 332.47965 -276.031198)
		(end 332.471268 -276.036024)
		(width 0.09525)
		(layer "In2.Cu")
		(net "M_C_CPU0_SB_DQS_DP<0>")
	)
	(segment
		(start 296.93362 -285.324804)
		(end 296.61866 -285.009844)
		(width 0.16002)
		(layer "In2.Cu")
		(net "M_C_CPU0_SB_DQS_DP<0>")
	)
	(segment
		(start 309.89651 -284.072584)
		(end 309.89651 -284.348936)
		(width 0.16002)
		(layer "In2.Cu")
		(net "M_C_CPU0_SB_DQS_DP<0>")
	)
	(segment
		(start 298.624244 -284.471364)
		(end 298.237656 -284.471364)
		(width 0.16002)
		(layer "In2.Cu")
		(net "M_C_CPU0_SB_DQS_DP<0>")
	)
	(segment
		(start 293.59098 -285.009844)
		(end 293.441882 -285.158942)
		(width 0.16002)
		(layer "In2.Cu")
		(net "M_C_CPU0_SB_DQS_DP<0>")
	)
	(segment
		(start 310.796686 -283.172154)
		(end 310.412892 -282.78836)
		(width 0.16002)
		(layer "In2.Cu")
		(net "M_C_CPU0_SB_DQS_DP<0>")
	)
	(segment
		(start 342.631014 -275.706078)
		(end 342.47709 -275.971508)
		(width 0.09525)
		(layer "In2.Cu")
		(net "M_C_CPU0_SB_DQS_DP<0>")
	)
	(segment
		(start 333.99095 -276.036024)
		(end 333.982568 -276.031198)
		(width 0.09525)
		(layer "In2.Cu")
		(net "M_C_CPU0_SB_DQS_DP<0>")
	)
	(segment
		(start 311.270142 -282.698952)
		(end 311.270142 -282.975558)
		(width 0.16002)
		(layer "In2.Cu")
		(net "M_C_CPU0_SB_DQS_DP<0>")
	)
	(segment
		(start 319.138046 -275.15693)
		(end 318.80556 -275.489416)
		(width 0.16002)
		(layer "In2.Cu")
		(net "M_C_CPU0_SB_DQS_DP<0>")
	)
	(segment
		(start 297.384216 -285.324804)
		(end 296.93362 -285.324804)
		(width 0.16002)
		(layer "In2.Cu")
		(net "M_C_CPU0_SB_DQS_DP<0>")
	)
	(segment
		(start 302.241204 -285.053024)
		(end 301.892716 -285.401512)
		(width 0.16002)
		(layer "In2.Cu")
		(net "M_C_CPU0_SB_DQS_DP<0>")
	)
	(segment
		(start 298.237656 -284.471364)
		(end 297.384216 -285.324804)
		(width 0.16002)
		(layer "In2.Cu")
		(net "M_C_CPU0_SB_DQS_DP<0>")
	)
	(segment
		(start 340.939628 -276.031198)
		(end 340.931246 -276.036024)
		(width 0.09525)
		(layer "In2.Cu")
		(net "M_C_CPU0_SB_DQS_DP<0>")
	)
	(segment
		(start 310.412892 -282.78836)
		(end 309.885334 -282.78836)
		(width 0.16002)
		(layer "In2.Cu")
		(net "M_C_CPU0_SB_DQS_DP<0>")
	)
	(segment
		(start 317.766192 -276.003766)
		(end 317.766192 -276.528784)
		(width 0.16002)
		(layer "In2.Cu")
		(net "M_C_CPU0_SB_DQS_DP<0>")
	)
	(segment
		(start 312.939176 -281.352752)
		(end 311.39765 -281.352752)
		(width 0.16002)
		(layer "In2.Cu")
		(net "M_C_CPU0_SB_DQS_DP<0>")
	)
	(segment
		(start 324.798182 -275.65731)
		(end 324.356984 -275.216112)
		(width 0.09525)
		(layer "In2.Cu")
		(net "M_C_CPU0_SB_DQS_DP<0>")
	)
	(segment
		(start 306.429156 -284.194504)
		(end 306.078636 -284.545024)
		(width 0.16002)
		(layer "In2.Cu")
		(net "M_C_CPU0_SB_DQS_DP<0>")
	)
	(segment
		(start 304.214784 -285.053024)
		(end 302.241204 -285.053024)
		(width 0.16002)
		(layer "In2.Cu")
		(net "M_C_CPU0_SB_DQS_DP<0>")
	)
	(segment
		(start 326.870822 -276.011894)
		(end 326.837548 -276.030944)
		(width 0.09525)
		(layer "In2.Cu")
		(net "M_C_CPU0_SB_DQS_DP<0>")
	)
	(segment
		(start 309.69966 -284.545786)
		(end 309.423054 -284.545786)
		(width 0.16002)
		(layer "In2.Cu")
		(net "M_C_CPU0_SB_DQS_DP<0>")
	)
	(segment
		(start 301.61992 -285.401512)
		(end 301.410878 -285.19247)
		(width 0.16002)
		(layer "In2.Cu")
		(net "M_C_CPU0_SB_DQS_DP<0>")
	)
	(segment
		(start 309.885334 -282.78836)
		(end 309.512462 -283.161232)
		(width 0.16002)
		(layer "In2.Cu")
		(net "M_C_CPU0_SB_DQS_DP<0>")
	)
	(segment
		(start 310.918352 -281.83205)
		(end 310.918352 -282.347162)
		(width 0.16002)
		(layer "In2.Cu")
		(net "M_C_CPU0_SB_DQS_DP<0>")
	)
	(segment
		(start 331.539596 -276.031198)
		(end 331.531214 -276.036024)
		(width 0.09525)
		(layer "In2.Cu")
		(net "M_C_CPU0_SB_DQS_DP<0>")
	)
	(segment
		(start 323.978778 -275.216112)
		(end 323.919596 -275.15693)
		(width 0.09525)
		(layer "In2.Cu")
		(net "M_C_CPU0_SB_DQS_DP<0>")
	)
	(segment
		(start 324.356984 -275.216112)
		(end 323.978778 -275.216112)
		(width 0.09525)
		(layer "In2.Cu")
		(net "M_C_CPU0_SB_DQS_DP<0>")
	)
	(segment
		(start 315.018928 -278.75103)
		(end 315.018928 -279.276048)
		(width 0.16002)
		(layer "In2.Cu")
		(net "M_C_CPU0_SB_DQS_DP<0>")
	)
	(arc
		(start 333.419704 -276.031198)
		(mid 333.235929 -276.08197)
		(end 333.050896 -276.036024)
		(width 0.09525)
		(layer "In2.Cu")
		(net "M_C_CPU0_SB_DQS_DP<0>")
	)
	(arc
		(start 338.682584 -276.031198)
		(mid 338.401152 -275.955443)
		(end 338.11972 -276.031198)
		(width 0.09525)
		(layer "In2.Cu")
		(net "M_C_CPU0_SB_DQS_DP<0>")
	)
	(arc
		(start 326.837548 -276.030944)
		(mid 326.74762 -276.068272)
		(end 326.651112 -276.081236)
		(width 0.09525)
		(layer "In2.Cu")
		(net "M_C_CPU0_SB_DQS_DP<0>")
	)
	(arc
		(start 340.562438 -276.031198)
		(mid 340.281006 -275.955443)
		(end 339.999574 -276.031198)
		(width 0.09525)
		(layer "In2.Cu")
		(net "M_C_CPU0_SB_DQS_DP<0>")
	)
	(arc
		(start 336.23123 -276.036024)
		(mid 336.046198 -276.081938)
		(end 335.862422 -276.031198)
		(width 0.09525)
		(layer "In2.Cu")
		(net "M_C_CPU0_SB_DQS_DP<0>")
	)
	(arc
		(start 339.999574 -276.031198)
		(mid 339.811106 -276.081875)
		(end 339.622638 -276.031198)
		(width 0.09525)
		(layer "In2.Cu")
		(net "M_C_CPU0_SB_DQS_DP<0>")
	)
	(arc
		(start 333.982568 -276.031198)
		(mid 333.701136 -275.955443)
		(end 333.419704 -276.031198)
		(width 0.09525)
		(layer "In2.Cu")
		(net "M_C_CPU0_SB_DQS_DP<0>")
	)
	(arc
		(start 336.802476 -276.031198)
		(mid 336.521044 -275.955443)
		(end 336.239612 -276.031198)
		(width 0.09525)
		(layer "In2.Cu")
		(net "M_C_CPU0_SB_DQS_DP<0>")
	)
	(arc
		(start 331.162406 -276.031198)
		(mid 330.880974 -275.955443)
		(end 330.599542 -276.031198)
		(width 0.09525)
		(layer "In2.Cu")
		(net "M_C_CPU0_SB_DQS_DP<0>")
	)
	(arc
		(start 339.622638 -276.031198)
		(mid 339.341206 -275.955443)
		(end 339.059774 -276.031198)
		(width 0.09525)
		(layer "In2.Cu")
		(net "M_C_CPU0_SB_DQS_DP<0>")
	)
	(arc
		(start 332.471268 -276.036024)
		(mid 332.286236 -276.081938)
		(end 332.10246 -276.031198)
		(width 0.09525)
		(layer "In2.Cu")
		(net "M_C_CPU0_SB_DQS_DP<0>")
	)
	(arc
		(start 328.711306 -276.036024)
		(mid 328.526274 -276.081938)
		(end 328.342498 -276.031198)
		(width 0.09525)
		(layer "In2.Cu")
		(net "M_C_CPU0_SB_DQS_DP<0>")
	)
	(arc
		(start 337.74253 -276.031198)
		(mid 337.461098 -275.955443)
		(end 337.179666 -276.031198)
		(width 0.09525)
		(layer "In2.Cu")
		(net "M_C_CPU0_SB_DQS_DP<0>")
	)
	(arc
		(start 341.8713 -276.036024)
		(mid 341.686268 -276.081938)
		(end 341.502492 -276.031198)
		(width 0.09525)
		(layer "In2.Cu")
		(net "M_C_CPU0_SB_DQS_DP<0>")
	)
	(arc
		(start 331.531214 -276.036024)
		(mid 331.346182 -276.081938)
		(end 331.162406 -276.031198)
		(width 0.09525)
		(layer "In2.Cu")
		(net "M_C_CPU0_SB_DQS_DP<0>")
	)
	(arc
		(start 342.376252 -275.998178)
		(mid 342.124111 -275.956608)
		(end 341.879682 -276.031198)
		(width 0.09525)
		(layer "In2.Cu")
		(net "M_C_CPU0_SB_DQS_DP<0>")
	)
	(arc
		(start 332.10246 -276.031198)
		(mid 331.821028 -275.955443)
		(end 331.539596 -276.031198)
		(width 0.09525)
		(layer "In2.Cu")
		(net "M_C_CPU0_SB_DQS_DP<0>")
	)
	(arc
		(start 327.77684 -276.031452)
		(mid 327.602165 -276.082903)
		(end 327.42378 -276.046438)
		(width 0.09525)
		(layer "In2.Cu")
		(net "M_C_CPU0_SB_DQS_DP<0>")
	)
	(arc
		(start 341.502492 -276.031198)
		(mid 341.22106 -275.955443)
		(end 340.939628 -276.031198)
		(width 0.09525)
		(layer "In2.Cu")
		(net "M_C_CPU0_SB_DQS_DP<0>")
	)
	(arc
		(start 330.222606 -276.031198)
		(mid 329.941174 -275.955443)
		(end 329.659742 -276.031198)
		(width 0.09525)
		(layer "In2.Cu")
		(net "M_C_CPU0_SB_DQS_DP<0>")
	)
	(arc
		(start 338.11972 -276.031198)
		(mid 337.935945 -276.08197)
		(end 337.750912 -276.036024)
		(width 0.09525)
		(layer "In2.Cu")
		(net "M_C_CPU0_SB_DQS_DP<0>")
	)
	(arc
		(start 337.171284 -276.036024)
		(mid 336.986252 -276.081938)
		(end 336.802476 -276.031198)
		(width 0.09525)
		(layer "In2.Cu")
		(net "M_C_CPU0_SB_DQS_DP<0>")
	)
	(arc
		(start 334.922622 -276.031198)
		(mid 334.64119 -275.955443)
		(end 334.359758 -276.031198)
		(width 0.09525)
		(layer "In2.Cu")
		(net "M_C_CPU0_SB_DQS_DP<0>")
	)
	(arc
		(start 329.282552 -276.031198)
		(mid 329.00112 -275.955443)
		(end 328.719688 -276.031198)
		(width 0.09525)
		(layer "In2.Cu")
		(net "M_C_CPU0_SB_DQS_DP<0>")
	)
	(arc
		(start 335.862422 -276.031198)
		(mid 335.58099 -275.955443)
		(end 335.299558 -276.031198)
		(width 0.09525)
		(layer "In2.Cu")
		(net "M_C_CPU0_SB_DQS_DP<0>")
	)
	(arc
		(start 339.059774 -276.031198)
		(mid 338.875999 -276.08197)
		(end 338.690966 -276.036024)
		(width 0.09525)
		(layer "In2.Cu")
		(net "M_C_CPU0_SB_DQS_DP<0>")
	)
	(arc
		(start 329.659742 -276.031198)
		(mid 329.475967 -276.08197)
		(end 329.290934 -276.036024)
		(width 0.09525)
		(layer "In2.Cu")
		(net "M_C_CPU0_SB_DQS_DP<0>")
	)
	(arc
		(start 328.310748 -276.012656)
		(mid 328.041401 -275.954484)
		(end 327.77684 -276.031452)
		(width 0.09525)
		(layer "In2.Cu")
		(net "M_C_CPU0_SB_DQS_DP<0>")
	)
	(arc
		(start 327.397364 -276.031198)
		(mid 327.136499 -275.95582)
		(end 326.870822 -276.011894)
		(width 0.09525)
		(layer "In2.Cu")
		(net "M_C_CPU0_SB_DQS_DP<0>")
	)
	(arc
		(start 333.042514 -276.031198)
		(mid 332.761082 -275.955443)
		(end 332.47965 -276.031198)
		(width 0.09525)
		(layer "In2.Cu")
		(net "M_C_CPU0_SB_DQS_DP<0>")
	)
	(arc
		(start 340.931246 -276.036024)
		(mid 340.746214 -276.081938)
		(end 340.562438 -276.031198)
		(width 0.09525)
		(layer "In2.Cu")
		(net "M_C_CPU0_SB_DQS_DP<0>")
	)
	(arc
		(start 335.299558 -276.031198)
		(mid 335.11109 -276.081875)
		(end 334.922622 -276.031198)
		(width 0.09525)
		(layer "In2.Cu")
		(net "M_C_CPU0_SB_DQS_DP<0>")
	)
	(arc
		(start 334.359758 -276.031198)
		(mid 334.175983 -276.08197)
		(end 333.99095 -276.036024)
		(width 0.09525)
		(layer "In2.Cu")
		(net "M_C_CPU0_SB_DQS_DP<0>")
	)
	(arc
		(start 330.599542 -276.031198)
		(mid 330.411074 -276.081875)
		(end 330.222606 -276.031198)
		(width 0.09525)
		(layer "In2.Cu")
		(net "M_C_CPU0_SB_DQS_DP<0>")
	)
	(segment
		(start 342.627966 -271.39011)
		(end 342.161114 -271.656048)
		(width 0.12954)
		(layer "F.Cu")
		(net "M_C_CPU0_SB_DQS_DN<9>")
	)
	(segment
		(start 294.918892 -275.686266)
		(end 294.354758 -275.122132)
		(width 0.16002)
		(layer "In2.Cu")
		(net "M_C_CPU0_SB_DQS_DN<9>")
	)
	(segment
		(start 310.034432 -273.553936)
		(end 310.034432 -274.08124)
		(width 0.16002)
		(layer "In2.Cu")
		(net "M_C_CPU0_SB_DQS_DN<9>")
	)
	(segment
		(start 308.68112 -274.954492)
		(end 308.20106 -274.954492)
		(width 0.16002)
		(layer "In2.Cu")
		(net "M_C_CPU0_SB_DQS_DN<9>")
	)
	(segment
		(start 342.161114 -271.656048)
		(end 342.315038 -271.390618)
		(width 0.09525)
		(layer "In2.Cu")
		(net "M_C_CPU0_SB_DQS_DN<9>")
	)
	(segment
		(start 309.92572 -273.445224)
		(end 310.034432 -273.553936)
		(width 0.16002)
		(layer "In2.Cu")
		(net "M_C_CPU0_SB_DQS_DN<9>")
	)
	(segment
		(start 326.25538 -271.242536)
		(end 325.393558 -270.38046)
		(width 0.09525)
		(layer "In2.Cu")
		(net "M_C_CPU0_SB_DQS_DN<9>")
	)
	(segment
		(start 311.408064 -272.707608)
		(end 311.035192 -273.08048)
		(width 0.16002)
		(layer "In2.Cu")
		(net "M_C_CPU0_SB_DQS_DN<9>")
	)
	(segment
		(start 303.73066 -275.686012)
		(end 302.174656 -275.686012)
		(width 0.16002)
		(layer "In2.Cu")
		(net "M_C_CPU0_SB_DQS_DN<9>")
	)
	(segment
		(start 312.539634 -270.56461)
		(end 312.781696 -270.806672)
		(width 0.16002)
		(layer "In2.Cu")
		(net "M_C_CPU0_SB_DQS_DN<9>")
	)
	(segment
		(start 311.166002 -271.661382)
		(end 311.166002 -271.938242)
		(width 0.16002)
		(layer "In2.Cu")
		(net "M_C_CPU0_SB_DQS_DN<9>")
	)
	(segment
		(start 327.873868 -271.331182)
		(end 327.849992 -271.344898)
		(width 0.09525)
		(layer "In2.Cu")
		(net "M_C_CPU0_SB_DQS_DN<9>")
	)
	(segment
		(start 339.529674 -271.330928)
		(end 339.521292 -271.326102)
		(width 0.09525)
		(layer "In2.Cu")
		(net "M_C_CPU0_SB_DQS_DN<9>")
	)
	(segment
		(start 311.035192 -273.08048)
		(end 310.507888 -273.08048)
		(width 0.16002)
		(layer "In2.Cu")
		(net "M_C_CPU0_SB_DQS_DN<9>")
	)
	(segment
		(start 309.92572 -273.168364)
		(end 309.92572 -273.445224)
		(width 0.16002)
		(layer "In2.Cu")
		(net "M_C_CPU0_SB_DQS_DN<9>")
	)
	(segment
		(start 336.340958 -271.326102)
		(end 336.332576 -271.330928)
		(width 0.09525)
		(layer "In2.Cu")
		(net "M_C_CPU0_SB_DQS_DN<9>")
	)
	(segment
		(start 292.553898 -276.111208)
		(end 292.280086 -276.38502)
		(width 0.16002)
		(layer "In2.Cu")
		(net "M_C_CPU0_SB_DQS_DN<9>")
	)
	(segment
		(start 312.408824 -271.706848)
		(end 311.88152 -271.706848)
		(width 0.16002)
		(layer "In2.Cu")
		(net "M_C_CPU0_SB_DQS_DN<9>")
	)
	(segment
		(start 310.034432 -274.08124)
		(end 309.27802 -274.837652)
		(width 0.16002)
		(layer "In2.Cu")
		(net "M_C_CPU0_SB_DQS_DN<9>")
	)
	(segment
		(start 308.79796 -274.837652)
		(end 308.68112 -274.954492)
		(width 0.16002)
		(layer "In2.Cu")
		(net "M_C_CPU0_SB_DQS_DN<9>")
	)
	(segment
		(start 326.407018 -271.351502)
		(end 326.371712 -271.331182)
		(width 0.09525)
		(layer "In2.Cu")
		(net "M_C_CPU0_SB_DQS_DN<9>")
	)
	(segment
		(start 310.122316 -272.971768)
		(end 309.92572 -273.168364)
		(width 0.16002)
		(layer "In2.Cu")
		(net "M_C_CPU0_SB_DQS_DN<9>")
	)
	(segment
		(start 311.408064 -272.180304)
		(end 311.408064 -272.707608)
		(width 0.16002)
		(layer "In2.Cu")
		(net "M_C_CPU0_SB_DQS_DN<9>")
	)
	(segment
		(start 301.298864 -274.391628)
		(end 300.86046 -274.830032)
		(width 0.16002)
		(layer "In2.Cu")
		(net "M_C_CPU0_SB_DQS_DN<9>")
	)
	(segment
		(start 311.166002 -271.938242)
		(end 311.408064 -272.180304)
		(width 0.16002)
		(layer "In2.Cu")
		(net "M_C_CPU0_SB_DQS_DN<9>")
	)
	(segment
		(start 334.829658 -271.330928)
		(end 334.821276 -271.326102)
		(width 0.09525)
		(layer "In2.Cu")
		(net "M_C_CPU0_SB_DQS_DN<9>")
	)
	(segment
		(start 311.639458 -271.464786)
		(end 311.362598 -271.464786)
		(width 0.16002)
		(layer "In2.Cu")
		(net "M_C_CPU0_SB_DQS_DN<9>")
	)
	(segment
		(start 293.38524 -276.111208)
		(end 292.553898 -276.111208)
		(width 0.16002)
		(layer "In2.Cu")
		(net "M_C_CPU0_SB_DQS_DN<9>")
	)
	(segment
		(start 301.837598 -275.348954)
		(end 301.837598 -274.551902)
		(width 0.16002)
		(layer "In2.Cu")
		(net "M_C_CPU0_SB_DQS_DN<9>")
	)
	(segment
		(start 300.86046 -274.830032)
		(end 299.320712 -274.830032)
		(width 0.16002)
		(layer "In2.Cu")
		(net "M_C_CPU0_SB_DQS_DN<9>")
	)
	(segment
		(start 302.174656 -275.686012)
		(end 301.837598 -275.348954)
		(width 0.16002)
		(layer "In2.Cu")
		(net "M_C_CPU0_SB_DQS_DN<9>")
	)
	(segment
		(start 313.255152 -270.333216)
		(end 313.01309 -270.091154)
		(width 0.16002)
		(layer "In2.Cu")
		(net "M_C_CPU0_SB_DQS_DN<9>")
	)
	(segment
		(start 310.507888 -273.08048)
		(end 310.399176 -272.971768)
		(width 0.16002)
		(layer "In2.Cu")
		(net "M_C_CPU0_SB_DQS_DN<9>")
	)
	(segment
		(start 293.722298 -275.358352)
		(end 293.722298 -275.77415)
		(width 0.16002)
		(layer "In2.Cu")
		(net "M_C_CPU0_SB_DQS_DN<9>")
	)
	(segment
		(start 296.217594 -275.686266)
		(end 294.918892 -275.686266)
		(width 0.16002)
		(layer "In2.Cu")
		(net "M_C_CPU0_SB_DQS_DN<9>")
	)
	(segment
		(start 308.08422 -274.837652)
		(end 306.863496 -274.837652)
		(width 0.16002)
		(layer "In2.Cu")
		(net "M_C_CPU0_SB_DQS_DN<9>")
	)
	(segment
		(start 299.320712 -274.830032)
		(end 298.727114 -275.42363)
		(width 0.16002)
		(layer "In2.Cu")
		(net "M_C_CPU0_SB_DQS_DN<9>")
	)
	(segment
		(start 312.781696 -270.806672)
		(end 312.781696 -271.333976)
		(width 0.16002)
		(layer "In2.Cu")
		(net "M_C_CPU0_SB_DQS_DN<9>")
	)
	(segment
		(start 312.73623 -270.091154)
		(end 312.539634 -270.28775)
		(width 0.16002)
		(layer "In2.Cu")
		(net "M_C_CPU0_SB_DQS_DN<9>")
	)
	(segment
		(start 294.354758 -275.122132)
		(end 293.958518 -275.122132)
		(width 0.16002)
		(layer "In2.Cu")
		(net "M_C_CPU0_SB_DQS_DN<9>")
	)
	(segment
		(start 314.280042 -269.83563)
		(end 313.782456 -270.333216)
		(width 0.16002)
		(layer "In2.Cu")
		(net "M_C_CPU0_SB_DQS_DN<9>")
	)
	(segment
		(start 323.919596 -269.83563)
		(end 323.895974 -269.83563)
		(width 0.09525)
		(layer "In2.Cu")
		(net "M_C_CPU0_SB_DQS_DN<9>")
	)
	(segment
		(start 335.400904 -271.326102)
		(end 335.392522 -271.330928)
		(width 0.09525)
		(layer "In2.Cu")
		(net "M_C_CPU0_SB_DQS_DN<9>")
	)
	(segment
		(start 327.312782 -271.330928)
		(end 327.289414 -271.317466)
		(width 0.09525)
		(layer "In2.Cu")
		(net "M_C_CPU0_SB_DQS_DN<9>")
	)
	(segment
		(start 340.10092 -271.326102)
		(end 340.092538 -271.330928)
		(width 0.09525)
		(layer "In2.Cu")
		(net "M_C_CPU0_SB_DQS_DN<9>")
	)
	(segment
		(start 325.393558 -270.38046)
		(end 324.871842 -270.38046)
		(width 0.09525)
		(layer "In2.Cu")
		(net "M_C_CPU0_SB_DQS_DN<9>")
	)
	(segment
		(start 313.782456 -270.333216)
		(end 313.255152 -270.333216)
		(width 0.16002)
		(layer "In2.Cu")
		(net "M_C_CPU0_SB_DQS_DN<9>")
	)
	(segment
		(start 308.20106 -274.954492)
		(end 308.08422 -274.837652)
		(width 0.16002)
		(layer "In2.Cu")
		(net "M_C_CPU0_SB_DQS_DN<9>")
	)
	(segment
		(start 298.362878 -275.42363)
		(end 297.50893 -276.277578)
		(width 0.16002)
		(layer "In2.Cu")
		(net "M_C_CPU0_SB_DQS_DN<9>")
	)
	(segment
		(start 293.722298 -275.77415)
		(end 293.38524 -276.111208)
		(width 0.16002)
		(layer "In2.Cu")
		(net "M_C_CPU0_SB_DQS_DN<9>")
	)
	(segment
		(start 310.399176 -272.971768)
		(end 310.122316 -272.971768)
		(width 0.16002)
		(layer "In2.Cu")
		(net "M_C_CPU0_SB_DQS_DN<9>")
	)
	(segment
		(start 306.863496 -274.837652)
		(end 306.203858 -275.49729)
		(width 0.16002)
		(layer "In2.Cu")
		(net "M_C_CPU0_SB_DQS_DN<9>")
	)
	(segment
		(start 331.640942 -271.326102)
		(end 331.63256 -271.330928)
		(width 0.09525)
		(layer "In2.Cu")
		(net "M_C_CPU0_SB_DQS_DN<9>")
	)
	(segment
		(start 323.978524 -269.776702)
		(end 323.919596 -269.83563)
		(width 0.09525)
		(layer "In2.Cu")
		(net "M_C_CPU0_SB_DQS_DN<9>")
	)
	(segment
		(start 312.539634 -270.28775)
		(end 312.539634 -270.56461)
		(width 0.16002)
		(layer "In2.Cu")
		(net "M_C_CPU0_SB_DQS_DN<9>")
	)
	(segment
		(start 338.58962 -271.330928)
		(end 338.581238 -271.326102)
		(width 0.09525)
		(layer "In2.Cu")
		(net "M_C_CPU0_SB_DQS_DN<9>")
	)
	(segment
		(start 330.700888 -271.326102)
		(end 330.692506 -271.330928)
		(width 0.09525)
		(layer "In2.Cu")
		(net "M_C_CPU0_SB_DQS_DN<9>")
	)
	(segment
		(start 311.362598 -271.464786)
		(end 311.166002 -271.661382)
		(width 0.16002)
		(layer "In2.Cu")
		(net "M_C_CPU0_SB_DQS_DN<9>")
	)
	(segment
		(start 297.50893 -276.277578)
		(end 296.808906 -276.277578)
		(width 0.16002)
		(layer "In2.Cu")
		(net "M_C_CPU0_SB_DQS_DN<9>")
	)
	(segment
		(start 333.889604 -271.330928)
		(end 333.881222 -271.326102)
		(width 0.09525)
		(layer "In2.Cu")
		(net "M_C_CPU0_SB_DQS_DN<9>")
	)
	(segment
		(start 313.01309 -270.091154)
		(end 312.73623 -270.091154)
		(width 0.16002)
		(layer "In2.Cu")
		(net "M_C_CPU0_SB_DQS_DN<9>")
	)
	(segment
		(start 341.040974 -271.326102)
		(end 341.032592 -271.330928)
		(width 0.09525)
		(layer "In2.Cu")
		(net "M_C_CPU0_SB_DQS_DN<9>")
	)
	(segment
		(start 312.781696 -271.333976)
		(end 312.408824 -271.706848)
		(width 0.16002)
		(layer "In2.Cu")
		(net "M_C_CPU0_SB_DQS_DN<9>")
	)
	(segment
		(start 296.808906 -276.277578)
		(end 296.217594 -275.686266)
		(width 0.16002)
		(layer "In2.Cu")
		(net "M_C_CPU0_SB_DQS_DN<9>")
	)
	(segment
		(start 327.897236 -271.31772)
		(end 327.873868 -271.331182)
		(width 0.09525)
		(layer "In2.Cu")
		(net "M_C_CPU0_SB_DQS_DN<9>")
	)
	(segment
		(start 309.27802 -274.837652)
		(end 308.79796 -274.837652)
		(width 0.16002)
		(layer "In2.Cu")
		(net "M_C_CPU0_SB_DQS_DN<9>")
	)
	(segment
		(start 301.677324 -274.391628)
		(end 301.298864 -274.391628)
		(width 0.16002)
		(layer "In2.Cu")
		(net "M_C_CPU0_SB_DQS_DN<9>")
	)
	(segment
		(start 323.895974 -269.83563)
		(end 314.280042 -269.83563)
		(width 0.16002)
		(layer "In2.Cu")
		(net "M_C_CPU0_SB_DQS_DN<9>")
	)
	(segment
		(start 301.837598 -274.551902)
		(end 301.677324 -274.391628)
		(width 0.16002)
		(layer "In2.Cu")
		(net "M_C_CPU0_SB_DQS_DN<9>")
	)
	(segment
		(start 298.727114 -275.42363)
		(end 298.362878 -275.42363)
		(width 0.16002)
		(layer "In2.Cu")
		(net "M_C_CPU0_SB_DQS_DN<9>")
	)
	(segment
		(start 305.726338 -275.49729)
		(end 304.872644 -276.350984)
		(width 0.16002)
		(layer "In2.Cu")
		(net "M_C_CPU0_SB_DQS_DN<9>")
	)
	(segment
		(start 304.872644 -276.350984)
		(end 304.395632 -276.350984)
		(width 0.16002)
		(layer "In2.Cu")
		(net "M_C_CPU0_SB_DQS_DN<9>")
	)
	(segment
		(start 342.315038 -271.390618)
		(end 342.291924 -271.304004)
		(width 0.09525)
		(layer "In2.Cu")
		(net "M_C_CPU0_SB_DQS_DN<9>")
	)
	(segment
		(start 304.395632 -276.350984)
		(end 303.73066 -275.686012)
		(width 0.16002)
		(layer "In2.Cu")
		(net "M_C_CPU0_SB_DQS_DN<9>")
	)
	(segment
		(start 324.268084 -269.776702)
		(end 323.978524 -269.776702)
		(width 0.09525)
		(layer "In2.Cu")
		(net "M_C_CPU0_SB_DQS_DN<9>")
	)
	(segment
		(start 293.958518 -275.122132)
		(end 293.722298 -275.358352)
		(width 0.16002)
		(layer "In2.Cu")
		(net "M_C_CPU0_SB_DQS_DN<9>")
	)
	(segment
		(start 306.203858 -275.49729)
		(end 305.726338 -275.49729)
		(width 0.16002)
		(layer "In2.Cu")
		(net "M_C_CPU0_SB_DQS_DN<9>")
	)
	(segment
		(start 324.871842 -270.38046)
		(end 324.268084 -269.776702)
		(width 0.09525)
		(layer "In2.Cu")
		(net "M_C_CPU0_SB_DQS_DN<9>")
	)
	(segment
		(start 311.88152 -271.706848)
		(end 311.639458 -271.464786)
		(width 0.16002)
		(layer "In2.Cu")
		(net "M_C_CPU0_SB_DQS_DN<9>")
	)
	(segment
		(start 330.129642 -271.330928)
		(end 330.12126 -271.326102)
		(width 0.09525)
		(layer "In2.Cu")
		(net "M_C_CPU0_SB_DQS_DN<9>")
	)
	(arc
		(start 339.152484 -271.330928)
		(mid 338.871052 -271.406683)
		(end 338.58962 -271.330928)
		(width 0.09525)
		(layer "In2.Cu")
		(net "M_C_CPU0_SB_DQS_DN<9>")
	)
	(arc
		(start 341.972646 -271.330928)
		(mid 341.691214 -271.406683)
		(end 341.409782 -271.330928)
		(width 0.09525)
		(layer "In2.Cu")
		(net "M_C_CPU0_SB_DQS_DN<9>")
	)
	(arc
		(start 332.572614 -271.330928)
		(mid 332.291182 -271.406683)
		(end 332.00975 -271.330928)
		(width 0.09525)
		(layer "In2.Cu")
		(net "M_C_CPU0_SB_DQS_DN<9>")
	)
	(arc
		(start 333.881222 -271.326102)
		(mid 333.69619 -271.280188)
		(end 333.512414 -271.330928)
		(width 0.09525)
		(layer "In2.Cu")
		(net "M_C_CPU0_SB_DQS_DN<9>")
	)
	(arc
		(start 340.092538 -271.330928)
		(mid 339.811106 -271.406683)
		(end 339.529674 -271.330928)
		(width 0.09525)
		(layer "In2.Cu")
		(net "M_C_CPU0_SB_DQS_DN<9>")
	)
	(arc
		(start 337.27263 -271.330928)
		(mid 336.991198 -271.406683)
		(end 336.709766 -271.330928)
		(width 0.09525)
		(layer "In2.Cu")
		(net "M_C_CPU0_SB_DQS_DN<9>")
	)
	(arc
		(start 335.392522 -271.330928)
		(mid 335.11109 -271.406683)
		(end 334.829658 -271.330928)
		(width 0.09525)
		(layer "In2.Cu")
		(net "M_C_CPU0_SB_DQS_DN<9>")
	)
	(arc
		(start 329.189588 -271.330928)
		(mid 329.00112 -271.280251)
		(end 328.812652 -271.330928)
		(width 0.09525)
		(layer "In2.Cu")
		(net "M_C_CPU0_SB_DQS_DN<9>")
	)
	(arc
		(start 326.371712 -271.331182)
		(mid 326.330491 -271.304984)
		(end 326.291702 -271.275302)
		(width 0.09525)
		(layer "In2.Cu")
		(net "M_C_CPU0_SB_DQS_DN<9>")
	)
	(arc
		(start 335.769712 -271.330928)
		(mid 335.585937 -271.280156)
		(end 335.400904 -271.326102)
		(width 0.09525)
		(layer "In2.Cu")
		(net "M_C_CPU0_SB_DQS_DN<9>")
	)
	(arc
		(start 332.00975 -271.330928)
		(mid 331.825975 -271.280156)
		(end 331.640942 -271.326102)
		(width 0.09525)
		(layer "In2.Cu")
		(net "M_C_CPU0_SB_DQS_DN<9>")
	)
	(arc
		(start 334.821276 -271.326102)
		(mid 334.636244 -271.280188)
		(end 334.452468 -271.330928)
		(width 0.09525)
		(layer "In2.Cu")
		(net "M_C_CPU0_SB_DQS_DN<9>")
	)
	(arc
		(start 327.849992 -271.344898)
		(mid 327.579609 -271.406458)
		(end 327.312782 -271.330928)
		(width 0.09525)
		(layer "In2.Cu")
		(net "M_C_CPU0_SB_DQS_DN<9>")
	)
	(arc
		(start 327.289414 -271.317466)
		(mid 327.110226 -271.279621)
		(end 326.934322 -271.330674)
		(width 0.09525)
		(layer "In2.Cu")
		(net "M_C_CPU0_SB_DQS_DN<9>")
	)
	(arc
		(start 331.63256 -271.330928)
		(mid 331.351128 -271.406683)
		(end 331.069696 -271.330928)
		(width 0.09525)
		(layer "In2.Cu")
		(net "M_C_CPU0_SB_DQS_DN<9>")
	)
	(arc
		(start 330.12126 -271.326102)
		(mid 329.936228 -271.280188)
		(end 329.752452 -271.330928)
		(width 0.09525)
		(layer "In2.Cu")
		(net "M_C_CPU0_SB_DQS_DN<9>")
	)
	(arc
		(start 329.752452 -271.330928)
		(mid 329.47102 -271.406683)
		(end 329.189588 -271.330928)
		(width 0.09525)
		(layer "In2.Cu")
		(net "M_C_CPU0_SB_DQS_DN<9>")
	)
	(arc
		(start 326.291702 -271.275302)
		(mid 326.273183 -271.259316)
		(end 326.25538 -271.242536)
		(width 0.09525)
		(layer "In2.Cu")
		(net "M_C_CPU0_SB_DQS_DN<9>")
	)
	(arc
		(start 341.409782 -271.330928)
		(mid 341.226007 -271.280156)
		(end 341.040974 -271.326102)
		(width 0.09525)
		(layer "In2.Cu")
		(net "M_C_CPU0_SB_DQS_DN<9>")
	)
	(arc
		(start 333.512414 -271.330928)
		(mid 333.230982 -271.406683)
		(end 332.94955 -271.330928)
		(width 0.09525)
		(layer "In2.Cu")
		(net "M_C_CPU0_SB_DQS_DN<9>")
	)
	(arc
		(start 328.249788 -271.330928)
		(mid 328.075156 -271.280388)
		(end 327.897236 -271.31772)
		(width 0.09525)
		(layer "In2.Cu")
		(net "M_C_CPU0_SB_DQS_DN<9>")
	)
	(arc
		(start 332.94955 -271.330928)
		(mid 332.761082 -271.280251)
		(end 332.572614 -271.330928)
		(width 0.09525)
		(layer "In2.Cu")
		(net "M_C_CPU0_SB_DQS_DN<9>")
	)
	(arc
		(start 338.581238 -271.326102)
		(mid 338.396206 -271.280188)
		(end 338.21243 -271.330928)
		(width 0.09525)
		(layer "In2.Cu")
		(net "M_C_CPU0_SB_DQS_DN<9>")
	)
	(arc
		(start 340.469728 -271.330928)
		(mid 340.285953 -271.280156)
		(end 340.10092 -271.326102)
		(width 0.09525)
		(layer "In2.Cu")
		(net "M_C_CPU0_SB_DQS_DN<9>")
	)
	(arc
		(start 342.291924 -271.304004)
		(mid 342.129273 -271.281744)
		(end 341.972646 -271.330928)
		(width 0.09525)
		(layer "In2.Cu")
		(net "M_C_CPU0_SB_DQS_DN<9>")
	)
	(arc
		(start 328.812652 -271.330928)
		(mid 328.53122 -271.406683)
		(end 328.249788 -271.330928)
		(width 0.09525)
		(layer "In2.Cu")
		(net "M_C_CPU0_SB_DQS_DN<9>")
	)
	(arc
		(start 341.032592 -271.330928)
		(mid 340.75116 -271.406683)
		(end 340.469728 -271.330928)
		(width 0.09525)
		(layer "In2.Cu")
		(net "M_C_CPU0_SB_DQS_DN<9>")
	)
	(arc
		(start 337.649566 -271.330928)
		(mid 337.461098 -271.280251)
		(end 337.27263 -271.330928)
		(width 0.09525)
		(layer "In2.Cu")
		(net "M_C_CPU0_SB_DQS_DN<9>")
	)
	(arc
		(start 330.692506 -271.330928)
		(mid 330.411074 -271.406683)
		(end 330.129642 -271.330928)
		(width 0.09525)
		(layer "In2.Cu")
		(net "M_C_CPU0_SB_DQS_DN<9>")
	)
	(arc
		(start 338.21243 -271.330928)
		(mid 337.930998 -271.406683)
		(end 337.649566 -271.330928)
		(width 0.09525)
		(layer "In2.Cu")
		(net "M_C_CPU0_SB_DQS_DN<9>")
	)
	(arc
		(start 336.709766 -271.330928)
		(mid 336.525991 -271.280156)
		(end 336.340958 -271.326102)
		(width 0.09525)
		(layer "In2.Cu")
		(net "M_C_CPU0_SB_DQS_DN<9>")
	)
	(arc
		(start 326.934322 -271.330674)
		(mid 326.67327 -271.406921)
		(end 326.407018 -271.351502)
		(width 0.09525)
		(layer "In2.Cu")
		(net "M_C_CPU0_SB_DQS_DN<9>")
	)
	(arc
		(start 336.332576 -271.330928)
		(mid 336.051144 -271.406683)
		(end 335.769712 -271.330928)
		(width 0.09525)
		(layer "In2.Cu")
		(net "M_C_CPU0_SB_DQS_DN<9>")
	)
	(arc
		(start 331.069696 -271.330928)
		(mid 330.885921 -271.280156)
		(end 330.700888 -271.326102)
		(width 0.09525)
		(layer "In2.Cu")
		(net "M_C_CPU0_SB_DQS_DN<9>")
	)
	(arc
		(start 339.521292 -271.326102)
		(mid 339.33626 -271.280188)
		(end 339.152484 -271.330928)
		(width 0.09525)
		(layer "In2.Cu")
		(net "M_C_CPU0_SB_DQS_DN<9>")
	)
	(arc
		(start 334.452468 -271.330928)
		(mid 334.171036 -271.406683)
		(end 333.889604 -271.330928)
		(width 0.09525)
		(layer "In2.Cu")
		(net "M_C_CPU0_SB_DQS_DN<9>")
	)
	(segment
		(start 344.508074 -290.83)
		(end 344.041222 -291.095938)
		(width 0.12954)
		(layer "F.Cu")
		(net "M_C_CPU0_SB_DQS_DN<8>")
	)
	(segment
		(start 320.608198 -304.93716)
		(end 320.268346 -305.277012)
		(width 0.16002)
		(layer "In2.Cu")
		(net "M_C_CPU0_SB_DQS_DN<8>")
	)
	(segment
		(start 306.577238 -314.167266)
		(end 306.318666 -313.908694)
		(width 0.16002)
		(layer "In2.Cu")
		(net "M_C_CPU0_SB_DQS_DN<8>")
	)
	(segment
		(start 344.041222 -291.095938)
		(end 343.887298 -291.361368)
		(width 0.09525)
		(layer "In2.Cu")
		(net "M_C_CPU0_SB_DQS_DN<8>")
	)
	(segment
		(start 334.829658 -291.421058)
		(end 334.821276 -291.425884)
		(width 0.09525)
		(layer "In2.Cu")
		(net "M_C_CPU0_SB_DQS_DN<8>")
	)
	(segment
		(start 325.263764 -294.474646)
		(end 325.263764 -295.726358)
		(width 0.09525)
		(layer "In2.Cu")
		(net "M_C_CPU0_SB_DQS_DN<8>")
	)
	(segment
		(start 327.671176 -291.472366)
		(end 327.278746 -291.864796)
		(width 0.09525)
		(layer "In2.Cu")
		(net "M_C_CPU0_SB_DQS_DN<8>")
	)
	(segment
		(start 338.58962 -291.421058)
		(end 338.581238 -291.425884)
		(width 0.09525)
		(layer "In2.Cu")
		(net "M_C_CPU0_SB_DQS_DN<8>")
	)
	(segment
		(start 296.802556 -314.733686)
		(end 296.478198 -315.058044)
		(width 0.16002)
		(layer "In2.Cu")
		(net "M_C_CPU0_SB_DQS_DN<8>")
	)
	(segment
		(start 320.80581 -304.93716)
		(end 320.608198 -304.93716)
		(width 0.16002)
		(layer "In2.Cu")
		(net "M_C_CPU0_SB_DQS_DN<8>")
	)
	(segment
		(start 298.146216 -313.880246)
		(end 297.292776 -314.733686)
		(width 0.16002)
		(layer "In2.Cu")
		(net "M_C_CPU0_SB_DQS_DN<8>")
	)
	(segment
		(start 289.847274 -314.059062)
		(end 288.454084 -314.059062)
		(width 0.16002)
		(layer "In2.Cu")
		(net "M_C_CPU0_SB_DQS_DN<8>")
	)
	(segment
		(start 325.204582 -295.78554)
		(end 325.204582 -295.809162)
		(width 0.09525)
		(layer "In2.Cu")
		(net "M_C_CPU0_SB_DQS_DN<8>")
	)
	(segment
		(start 326.332596 -293.062914)
		(end 326.330564 -293.064184)
		(width 0.09525)
		(layer "In2.Cu")
		(net "M_C_CPU0_SB_DQS_DN<8>")
	)
	(segment
		(start 320.268346 -305.474624)
		(end 314.999878 -310.743092)
		(width 0.16002)
		(layer "In2.Cu")
		(net "M_C_CPU0_SB_DQS_DN<8>")
	)
	(segment
		(start 325.204582 -300.538388)
		(end 320.80581 -304.93716)
		(width 0.16002)
		(layer "In2.Cu")
		(net "M_C_CPU0_SB_DQS_DN<8>")
	)
	(segment
		(start 294.114474 -314.46724)
		(end 291.779452 -314.46724)
		(width 0.16002)
		(layer "In2.Cu")
		(net "M_C_CPU0_SB_DQS_DN<8>")
	)
	(segment
		(start 339.529674 -291.421058)
		(end 339.521292 -291.425884)
		(width 0.09525)
		(layer "In2.Cu")
		(net "M_C_CPU0_SB_DQS_DN<8>")
	)
	(segment
		(start 331.640942 -291.425884)
		(end 331.63256 -291.421058)
		(width 0.09525)
		(layer "In2.Cu")
		(net "M_C_CPU0_SB_DQS_DN<8>")
	)
	(segment
		(start 304.041556 -315.030866)
		(end 302.26254 -315.030866)
		(width 0.16002)
		(layer "In2.Cu")
		(net "M_C_CPU0_SB_DQS_DN<8>")
	)
	(segment
		(start 290.04641 -313.859926)
		(end 289.847274 -314.059062)
		(width 0.16002)
		(layer "In2.Cu")
		(net "M_C_CPU0_SB_DQS_DN<8>")
	)
	(segment
		(start 343.289636 -291.421058)
		(end 343.281254 -291.425884)
		(width 0.09525)
		(layer "In2.Cu")
		(net "M_C_CPU0_SB_DQS_DN<8>")
	)
	(segment
		(start 296.478198 -315.058044)
		(end 294.705278 -315.058044)
		(width 0.16002)
		(layer "In2.Cu")
		(net "M_C_CPU0_SB_DQS_DN<8>")
	)
	(segment
		(start 343.887298 -291.361368)
		(end 343.78646 -291.388038)
		(width 0.09525)
		(layer "In2.Cu")
		(net "M_C_CPU0_SB_DQS_DN<8>")
	)
	(segment
		(start 313.701938 -310.743092)
		(end 310.277764 -314.167266)
		(width 0.16002)
		(layer "In2.Cu")
		(net "M_C_CPU0_SB_DQS_DN<8>")
	)
	(segment
		(start 340.10092 -291.425884)
		(end 340.092538 -291.421058)
		(width 0.09525)
		(layer "In2.Cu")
		(net "M_C_CPU0_SB_DQS_DN<8>")
	)
	(segment
		(start 325.263764 -295.726358)
		(end 325.204582 -295.78554)
		(width 0.09525)
		(layer "In2.Cu")
		(net "M_C_CPU0_SB_DQS_DN<8>")
	)
	(segment
		(start 326.96531 -292.132004)
		(end 326.775826 -292.32352)
		(width 0.09525)
		(layer "In2.Cu")
		(net "M_C_CPU0_SB_DQS_DN<8>")
	)
	(segment
		(start 291.172138 -313.859926)
		(end 290.04641 -313.859926)
		(width 0.16002)
		(layer "In2.Cu")
		(net "M_C_CPU0_SB_DQS_DN<8>")
	)
	(segment
		(start 301.45228 -314.220606)
		(end 299.10024 -314.220606)
		(width 0.16002)
		(layer "In2.Cu")
		(net "M_C_CPU0_SB_DQS_DN<8>")
	)
	(segment
		(start 320.268346 -305.277012)
		(end 320.268346 -305.474624)
		(width 0.16002)
		(layer "In2.Cu")
		(net "M_C_CPU0_SB_DQS_DN<8>")
	)
	(segment
		(start 304.861976 -314.710826)
		(end 304.361596 -314.710826)
		(width 0.16002)
		(layer "In2.Cu")
		(net "M_C_CPU0_SB_DQS_DN<8>")
	)
	(segment
		(start 302.26254 -315.030866)
		(end 301.45228 -314.220606)
		(width 0.16002)
		(layer "In2.Cu")
		(net "M_C_CPU0_SB_DQS_DN<8>")
	)
	(segment
		(start 294.705278 -315.058044)
		(end 294.114474 -314.46724)
		(width 0.16002)
		(layer "In2.Cu")
		(net "M_C_CPU0_SB_DQS_DN<8>")
	)
	(segment
		(start 326.089264 -293.649146)
		(end 325.263764 -294.474646)
		(width 0.09525)
		(layer "In2.Cu")
		(net "M_C_CPU0_SB_DQS_DN<8>")
	)
	(segment
		(start 333.889604 -291.421058)
		(end 333.881222 -291.425884)
		(width 0.09525)
		(layer "In2.Cu")
		(net "M_C_CPU0_SB_DQS_DN<8>")
	)
	(segment
		(start 335.400904 -291.425884)
		(end 335.392522 -291.421058)
		(width 0.09525)
		(layer "In2.Cu")
		(net "M_C_CPU0_SB_DQS_DN<8>")
	)
	(segment
		(start 325.204582 -295.809162)
		(end 325.204582 -300.538388)
		(width 0.16002)
		(layer "In2.Cu")
		(net "M_C_CPU0_SB_DQS_DN<8>")
	)
	(segment
		(start 304.361596 -314.710826)
		(end 304.041556 -315.030866)
		(width 0.16002)
		(layer "In2.Cu")
		(net "M_C_CPU0_SB_DQS_DN<8>")
	)
	(segment
		(start 330.700888 -291.425884)
		(end 330.692506 -291.421058)
		(width 0.09525)
		(layer "In2.Cu")
		(net "M_C_CPU0_SB_DQS_DN<8>")
	)
	(segment
		(start 328.061066 -291.472366)
		(end 327.671176 -291.472366)
		(width 0.09525)
		(layer "In2.Cu")
		(net "M_C_CPU0_SB_DQS_DN<8>")
	)
	(segment
		(start 299.10024 -314.220606)
		(end 298.75988 -313.880246)
		(width 0.16002)
		(layer "In2.Cu")
		(net "M_C_CPU0_SB_DQS_DN<8>")
	)
	(segment
		(start 326.089264 -293.525956)
		(end 326.089264 -293.649146)
		(width 0.09525)
		(layer "In2.Cu")
		(net "M_C_CPU0_SB_DQS_DN<8>")
	)
	(segment
		(start 310.277764 -314.167266)
		(end 306.577238 -314.167266)
		(width 0.16002)
		(layer "In2.Cu")
		(net "M_C_CPU0_SB_DQS_DN<8>")
	)
	(segment
		(start 341.040974 -291.425884)
		(end 341.032592 -291.421058)
		(width 0.09525)
		(layer "In2.Cu")
		(net "M_C_CPU0_SB_DQS_DN<8>")
	)
	(segment
		(start 298.75988 -313.880246)
		(end 298.146216 -313.880246)
		(width 0.16002)
		(layer "In2.Cu")
		(net "M_C_CPU0_SB_DQS_DN<8>")
	)
	(segment
		(start 330.129642 -291.421058)
		(end 330.12126 -291.425884)
		(width 0.09525)
		(layer "In2.Cu")
		(net "M_C_CPU0_SB_DQS_DN<8>")
	)
	(segment
		(start 291.779452 -314.46724)
		(end 291.172138 -313.859926)
		(width 0.16002)
		(layer "In2.Cu")
		(net "M_C_CPU0_SB_DQS_DN<8>")
	)
	(segment
		(start 336.340958 -291.425884)
		(end 336.332576 -291.421058)
		(width 0.09525)
		(layer "In2.Cu")
		(net "M_C_CPU0_SB_DQS_DN<8>")
	)
	(segment
		(start 305.664108 -313.908694)
		(end 304.861976 -314.710826)
		(width 0.16002)
		(layer "In2.Cu")
		(net "M_C_CPU0_SB_DQS_DN<8>")
	)
	(segment
		(start 314.999878 -310.743092)
		(end 313.701938 -310.743092)
		(width 0.16002)
		(layer "In2.Cu")
		(net "M_C_CPU0_SB_DQS_DN<8>")
	)
	(segment
		(start 326.38111 -293.03472)
		(end 326.334628 -293.061644)
		(width 0.09525)
		(layer "In2.Cu")
		(net "M_C_CPU0_SB_DQS_DN<8>")
	)
	(segment
		(start 288.454084 -314.059062)
		(end 288.180018 -313.784996)
		(width 0.16002)
		(layer "In2.Cu")
		(net "M_C_CPU0_SB_DQS_DN<8>")
	)
	(segment
		(start 297.292776 -314.733686)
		(end 296.802556 -314.733686)
		(width 0.16002)
		(layer "In2.Cu")
		(net "M_C_CPU0_SB_DQS_DN<8>")
	)
	(segment
		(start 306.318666 -313.908694)
		(end 305.664108 -313.908694)
		(width 0.16002)
		(layer "In2.Cu")
		(net "M_C_CPU0_SB_DQS_DN<8>")
	)
	(arc
		(start 343.765886 -291.37991)
		(mid 343.523144 -291.34714)
		(end 343.289636 -291.421058)
		(width 0.09525)
		(layer "In2.Cu")
		(net "M_C_CPU0_SB_DQS_DN<8>")
	)
	(arc
		(start 326.334628 -293.061644)
		(mid 326.333611 -293.062278)
		(end 326.332596 -293.062914)
		(width 0.09525)
		(layer "In2.Cu")
		(net "M_C_CPU0_SB_DQS_DN<8>")
	)
	(arc
		(start 327.278746 -291.864796)
		(mid 327.203682 -291.933966)
		(end 327.123298 -291.996876)
		(width 0.09525)
		(layer "In2.Cu")
		(net "M_C_CPU0_SB_DQS_DN<8>")
	)
	(arc
		(start 336.332576 -291.421058)
		(mid 336.326123 -291.417458)
		(end 336.319622 -291.413946)
		(width 0.09525)
		(layer "In2.Cu")
		(net "M_C_CPU0_SB_DQS_DN<8>")
	)
	(arc
		(start 332.559914 -291.413946)
		(mid 332.283904 -291.345385)
		(end 332.00975 -291.421058)
		(width 0.09525)
		(layer "In2.Cu")
		(net "M_C_CPU0_SB_DQS_DN<8>")
	)
	(arc
		(start 337.662266 -291.413946)
		(mid 337.655892 -291.417459)
		(end 337.649566 -291.421058)
		(width 0.09525)
		(layer "In2.Cu")
		(net "M_C_CPU0_SB_DQS_DN<8>")
	)
	(arc
		(start 332.572614 -291.421058)
		(mid 332.566286 -291.417462)
		(end 332.559914 -291.413946)
		(width 0.09525)
		(layer "In2.Cu")
		(net "M_C_CPU0_SB_DQS_DN<8>")
	)
	(arc
		(start 327.03262 -292.069012)
		(mid 326.998392 -292.099896)
		(end 326.96531 -292.132004)
		(width 0.09525)
		(layer "In2.Cu")
		(net "M_C_CPU0_SB_DQS_DN<8>")
	)
	(arc
		(start 326.555862 -292.763448)
		(mid 326.522651 -292.877313)
		(end 326.455786 -292.975284)
		(width 0.09525)
		(layer "In2.Cu")
		(net "M_C_CPU0_SB_DQS_DN<8>")
	)
	(arc
		(start 334.452468 -291.421058)
		(mid 334.178457 -291.345476)
		(end 333.902558 -291.413946)
		(width 0.09525)
		(layer "In2.Cu")
		(net "M_C_CPU0_SB_DQS_DN<8>")
	)
	(arc
		(start 333.512414 -291.421058)
		(mid 333.23826 -291.34535)
		(end 332.96225 -291.413946)
		(width 0.09525)
		(layer "In2.Cu")
		(net "M_C_CPU0_SB_DQS_DN<8>")
	)
	(arc
		(start 326.591168 -292.626796)
		(mid 326.569214 -292.69401)
		(end 326.555862 -292.763448)
		(width 0.09525)
		(layer "In2.Cu")
		(net "M_C_CPU0_SB_DQS_DN<8>")
	)
	(arc
		(start 333.902558 -291.413946)
		(mid 333.896059 -291.417461)
		(end 333.889604 -291.421058)
		(width 0.09525)
		(layer "In2.Cu")
		(net "M_C_CPU0_SB_DQS_DN<8>")
	)
	(arc
		(start 341.409782 -291.421058)
		(mid 341.226007 -291.47183)
		(end 341.040974 -291.425884)
		(width 0.09525)
		(layer "In2.Cu")
		(net "M_C_CPU0_SB_DQS_DN<8>")
	)
	(arc
		(start 331.069696 -291.421058)
		(mid 330.885921 -291.47183)
		(end 330.700888 -291.425884)
		(width 0.09525)
		(layer "In2.Cu")
		(net "M_C_CPU0_SB_DQS_DN<8>")
	)
	(arc
		(start 341.972646 -291.421058)
		(mid 341.966318 -291.417462)
		(end 341.959946 -291.413946)
		(width 0.09525)
		(layer "In2.Cu")
		(net "M_C_CPU0_SB_DQS_DN<8>")
	)
	(arc
		(start 336.319622 -291.413946)
		(mid 336.043722 -291.345384)
		(end 335.769712 -291.421058)
		(width 0.09525)
		(layer "In2.Cu")
		(net "M_C_CPU0_SB_DQS_DN<8>")
	)
	(arc
		(start 326.455786 -292.975284)
		(mid 326.420593 -293.007699)
		(end 326.38111 -293.03472)
		(width 0.09525)
		(layer "In2.Cu")
		(net "M_C_CPU0_SB_DQS_DN<8>")
	)
	(arc
		(start 337.27263 -291.421058)
		(mid 337.266302 -291.417462)
		(end 337.25993 -291.413946)
		(width 0.09525)
		(layer "In2.Cu")
		(net "M_C_CPU0_SB_DQS_DN<8>")
	)
	(arc
		(start 338.581238 -291.425884)
		(mid 338.396206 -291.471798)
		(end 338.21243 -291.421058)
		(width 0.09525)
		(layer "In2.Cu")
		(net "M_C_CPU0_SB_DQS_DN<8>")
	)
	(arc
		(start 334.821276 -291.425884)
		(mid 334.636244 -291.471798)
		(end 334.452468 -291.421058)
		(width 0.09525)
		(layer "In2.Cu")
		(net "M_C_CPU0_SB_DQS_DN<8>")
	)
	(arc
		(start 331.619606 -291.413946)
		(mid 331.343706 -291.345384)
		(end 331.069696 -291.421058)
		(width 0.09525)
		(layer "In2.Cu")
		(net "M_C_CPU0_SB_DQS_DN<8>")
	)
	(arc
		(start 328.799698 -291.413946)
		(mid 328.523798 -291.345384)
		(end 328.249788 -291.421058)
		(width 0.09525)
		(layer "In2.Cu")
		(net "M_C_CPU0_SB_DQS_DN<8>")
	)
	(arc
		(start 338.21243 -291.421058)
		(mid 337.938276 -291.34535)
		(end 337.662266 -291.413946)
		(width 0.09525)
		(layer "In2.Cu")
		(net "M_C_CPU0_SB_DQS_DN<8>")
	)
	(arc
		(start 332.00975 -291.421058)
		(mid 331.825975 -291.47183)
		(end 331.640942 -291.425884)
		(width 0.09525)
		(layer "In2.Cu")
		(net "M_C_CPU0_SB_DQS_DN<8>")
	)
	(arc
		(start 332.94955 -291.421058)
		(mid 332.761082 -291.471735)
		(end 332.572614 -291.421058)
		(width 0.09525)
		(layer "In2.Cu")
		(net "M_C_CPU0_SB_DQS_DN<8>")
	)
	(arc
		(start 340.469728 -291.421058)
		(mid 340.285953 -291.47183)
		(end 340.10092 -291.425884)
		(width 0.09525)
		(layer "In2.Cu")
		(net "M_C_CPU0_SB_DQS_DN<8>")
	)
	(arc
		(start 332.96225 -291.413946)
		(mid 332.955876 -291.417459)
		(end 332.94955 -291.421058)
		(width 0.09525)
		(layer "In2.Cu")
		(net "M_C_CPU0_SB_DQS_DN<8>")
	)
	(arc
		(start 342.362282 -291.413946)
		(mid 342.355908 -291.417459)
		(end 342.349582 -291.421058)
		(width 0.09525)
		(layer "In2.Cu")
		(net "M_C_CPU0_SB_DQS_DN<8>")
	)
	(arc
		(start 327.123298 -291.996876)
		(mid 327.077135 -292.031909)
		(end 327.03262 -292.069012)
		(width 0.09525)
		(layer "In2.Cu")
		(net "M_C_CPU0_SB_DQS_DN<8>")
	)
	(arc
		(start 341.019638 -291.413946)
		(mid 340.743738 -291.345384)
		(end 340.469728 -291.421058)
		(width 0.09525)
		(layer "In2.Cu")
		(net "M_C_CPU0_SB_DQS_DN<8>")
	)
	(arc
		(start 339.521292 -291.425884)
		(mid 339.33626 -291.471798)
		(end 339.152484 -291.421058)
		(width 0.09525)
		(layer "In2.Cu")
		(net "M_C_CPU0_SB_DQS_DN<8>")
	)
	(arc
		(start 342.349582 -291.421058)
		(mid 342.161114 -291.471735)
		(end 341.972646 -291.421058)
		(width 0.09525)
		(layer "In2.Cu")
		(net "M_C_CPU0_SB_DQS_DN<8>")
	)
	(arc
		(start 326.775826 -292.32352)
		(mid 326.706544 -292.404807)
		(end 326.650096 -292.495478)
		(width 0.09525)
		(layer "In2.Cu")
		(net "M_C_CPU0_SB_DQS_DN<8>")
	)
	(arc
		(start 337.25993 -291.413946)
		(mid 336.98392 -291.345385)
		(end 336.709766 -291.421058)
		(width 0.09525)
		(layer "In2.Cu")
		(net "M_C_CPU0_SB_DQS_DN<8>")
	)
	(arc
		(start 337.649566 -291.421058)
		(mid 337.461098 -291.471735)
		(end 337.27263 -291.421058)
		(width 0.09525)
		(layer "In2.Cu")
		(net "M_C_CPU0_SB_DQS_DN<8>")
	)
	(arc
		(start 342.912446 -291.421058)
		(mid 342.638292 -291.34535)
		(end 342.362282 -291.413946)
		(width 0.09525)
		(layer "In2.Cu")
		(net "M_C_CPU0_SB_DQS_DN<8>")
	)
	(arc
		(start 329.752452 -291.421058)
		(mid 329.478441 -291.345476)
		(end 329.202542 -291.413946)
		(width 0.09525)
		(layer "In2.Cu")
		(net "M_C_CPU0_SB_DQS_DN<8>")
	)
	(arc
		(start 340.092538 -291.421058)
		(mid 339.811106 -291.345303)
		(end 339.529674 -291.421058)
		(width 0.09525)
		(layer "In2.Cu")
		(net "M_C_CPU0_SB_DQS_DN<8>")
	)
	(arc
		(start 343.78646 -291.388038)
		(mid 343.776212 -291.383875)
		(end 343.765886 -291.37991)
		(width 0.09525)
		(layer "In2.Cu")
		(net "M_C_CPU0_SB_DQS_DN<8>")
	)
	(arc
		(start 335.769712 -291.421058)
		(mid 335.585937 -291.47183)
		(end 335.400904 -291.425884)
		(width 0.09525)
		(layer "In2.Cu")
		(net "M_C_CPU0_SB_DQS_DN<8>")
	)
	(arc
		(start 329.189588 -291.421058)
		(mid 329.00112 -291.471735)
		(end 328.812652 -291.421058)
		(width 0.09525)
		(layer "In2.Cu")
		(net "M_C_CPU0_SB_DQS_DN<8>")
	)
	(arc
		(start 339.152484 -291.421058)
		(mid 338.878473 -291.345476)
		(end 338.602574 -291.413946)
		(width 0.09525)
		(layer "In2.Cu")
		(net "M_C_CPU0_SB_DQS_DN<8>")
	)
	(arc
		(start 331.63256 -291.421058)
		(mid 331.626107 -291.417458)
		(end 331.619606 -291.413946)
		(width 0.09525)
		(layer "In2.Cu")
		(net "M_C_CPU0_SB_DQS_DN<8>")
	)
	(arc
		(start 333.881222 -291.425884)
		(mid 333.69619 -291.471798)
		(end 333.512414 -291.421058)
		(width 0.09525)
		(layer "In2.Cu")
		(net "M_C_CPU0_SB_DQS_DN<8>")
	)
	(arc
		(start 326.650096 -292.495478)
		(mid 326.619149 -292.560472)
		(end 326.591168 -292.626796)
		(width 0.09525)
		(layer "In2.Cu")
		(net "M_C_CPU0_SB_DQS_DN<8>")
	)
	(arc
		(start 341.959946 -291.413946)
		(mid 341.683936 -291.345385)
		(end 341.409782 -291.421058)
		(width 0.09525)
		(layer "In2.Cu")
		(net "M_C_CPU0_SB_DQS_DN<8>")
	)
	(arc
		(start 330.692506 -291.421058)
		(mid 330.411074 -291.345303)
		(end 330.129642 -291.421058)
		(width 0.09525)
		(layer "In2.Cu")
		(net "M_C_CPU0_SB_DQS_DN<8>")
	)
	(arc
		(start 329.202542 -291.413946)
		(mid 329.196043 -291.417461)
		(end 329.189588 -291.421058)
		(width 0.09525)
		(layer "In2.Cu")
		(net "M_C_CPU0_SB_DQS_DN<8>")
	)
	(arc
		(start 328.812652 -291.421058)
		(mid 328.806199 -291.417458)
		(end 328.799698 -291.413946)
		(width 0.09525)
		(layer "In2.Cu")
		(net "M_C_CPU0_SB_DQS_DN<8>")
	)
	(arc
		(start 326.330564 -293.064184)
		(mid 326.153199 -293.265428)
		(end 326.089264 -293.525956)
		(width 0.09525)
		(layer "In2.Cu")
		(net "M_C_CPU0_SB_DQS_DN<8>")
	)
	(arc
		(start 343.281254 -291.425884)
		(mid 343.096222 -291.471798)
		(end 342.912446 -291.421058)
		(width 0.09525)
		(layer "In2.Cu")
		(net "M_C_CPU0_SB_DQS_DN<8>")
	)
	(arc
		(start 335.392522 -291.421058)
		(mid 335.11109 -291.345303)
		(end 334.829658 -291.421058)
		(width 0.09525)
		(layer "In2.Cu")
		(net "M_C_CPU0_SB_DQS_DN<8>")
	)
	(arc
		(start 336.709766 -291.421058)
		(mid 336.525991 -291.47183)
		(end 336.340958 -291.425884)
		(width 0.09525)
		(layer "In2.Cu")
		(net "M_C_CPU0_SB_DQS_DN<8>")
	)
	(arc
		(start 341.032592 -291.421058)
		(mid 341.026139 -291.417458)
		(end 341.019638 -291.413946)
		(width 0.09525)
		(layer "In2.Cu")
		(net "M_C_CPU0_SB_DQS_DN<8>")
	)
	(arc
		(start 338.602574 -291.413946)
		(mid 338.596075 -291.417461)
		(end 338.58962 -291.421058)
		(width 0.09525)
		(layer "In2.Cu")
		(net "M_C_CPU0_SB_DQS_DN<8>")
	)
	(arc
		(start 328.249788 -291.421058)
		(mid 328.158822 -291.459211)
		(end 328.061066 -291.472366)
		(width 0.09525)
		(layer "In2.Cu")
		(net "M_C_CPU0_SB_DQS_DN<8>")
	)
	(arc
		(start 330.12126 -291.425884)
		(mid 329.936228 -291.471798)
		(end 329.752452 -291.421058)
		(width 0.09525)
		(layer "In2.Cu")
		(net "M_C_CPU0_SB_DQS_DN<8>")
	)
	(segment
		(start 344.508074 -285.970218)
		(end 344.041222 -286.236156)
		(width 0.12954)
		(layer "F.Cu")
		(net "M_C_CPU0_SB_DQS_DN<7>")
	)
	(segment
		(start 338.58962 -286.561276)
		(end 338.581238 -286.566102)
		(width 0.09525)
		(layer "In2.Cu")
		(net "M_C_CPU0_SB_DQS_DN<7>")
	)
	(segment
		(start 343.887298 -286.501586)
		(end 343.78646 -286.528256)
		(width 0.09525)
		(layer "In2.Cu")
		(net "M_C_CPU0_SB_DQS_DN<7>")
	)
	(segment
		(start 306.318666 -304.5587)
		(end 305.697382 -304.5587)
		(width 0.16002)
		(layer "In2.Cu")
		(net "M_C_CPU0_SB_DQS_DN<7>")
	)
	(segment
		(start 323.901816 -287.74263)
		(end 319.407794 -292.237414)
		(width 0.16002)
		(layer "In2.Cu")
		(net "M_C_CPU0_SB_DQS_DN<7>")
	)
	(segment
		(start 304.61331 -305.283362)
		(end 304.315622 -305.406806)
		(width 0.16002)
		(layer "In2.Cu")
		(net "M_C_CPU0_SB_DQS_DN<7>")
	)
	(segment
		(start 336.340958 -286.566102)
		(end 336.332576 -286.561276)
		(width 0.09525)
		(layer "In2.Cu")
		(net "M_C_CPU0_SB_DQS_DN<7>")
	)
	(segment
		(start 326.946006 -286.568896)
		(end 326.932036 -286.561022)
		(width 0.09525)
		(layer "In2.Cu")
		(net "M_C_CPU0_SB_DQS_DN<7>")
	)
	(segment
		(start 343.289636 -286.561276)
		(end 343.281254 -286.566102)
		(width 0.09525)
		(layer "In2.Cu")
		(net "M_C_CPU0_SB_DQS_DN<7>")
	)
	(segment
		(start 319.407794 -295.4909)
		(end 310.081422 -304.817272)
		(width 0.16002)
		(layer "In2.Cu")
		(net "M_C_CPU0_SB_DQS_DN<7>")
	)
	(segment
		(start 296.756582 -305.429666)
		(end 296.478198 -305.70805)
		(width 0.16002)
		(layer "In2.Cu")
		(net "M_C_CPU0_SB_DQS_DN<7>")
	)
	(segment
		(start 300.955964 -304.857912)
		(end 299.08754 -304.857912)
		(width 0.16002)
		(layer "In2.Cu")
		(net "M_C_CPU0_SB_DQS_DN<7>")
	)
	(segment
		(start 297.080432 -305.2953)
		(end 296.756582 -305.429666)
		(width 0.16002)
		(layer "In2.Cu")
		(net "M_C_CPU0_SB_DQS_DN<7>")
	)
	(segment
		(start 291.215318 -304.553112)
		(end 290.00323 -304.553112)
		(width 0.16002)
		(layer "In2.Cu")
		(net "M_C_CPU0_SB_DQS_DN<7>")
	)
	(segment
		(start 325.866252 -286.612838)
		(end 325.46798 -287.01111)
		(width 0.09525)
		(layer "In2.Cu")
		(net "M_C_CPU0_SB_DQS_DN<7>")
	)
	(segment
		(start 306.577238 -304.817272)
		(end 306.318666 -304.5587)
		(width 0.16002)
		(layer "In2.Cu")
		(net "M_C_CPU0_SB_DQS_DN<7>")
	)
	(segment
		(start 292.181788 -305.117246)
		(end 291.494972 -304.832766)
		(width 0.16002)
		(layer "In2.Cu")
		(net "M_C_CPU0_SB_DQS_DN<7>")
	)
	(segment
		(start 289.847274 -304.709068)
		(end 288.454084 -304.709068)
		(width 0.16002)
		(layer "In2.Cu")
		(net "M_C_CPU0_SB_DQS_DN<7>")
	)
	(segment
		(start 339.529674 -286.561276)
		(end 339.521292 -286.566102)
		(width 0.09525)
		(layer "In2.Cu")
		(net "M_C_CPU0_SB_DQS_DN<7>")
	)
	(segment
		(start 293.278814 -305.117246)
		(end 292.181788 -305.117246)
		(width 0.16002)
		(layer "In2.Cu")
		(net "M_C_CPU0_SB_DQS_DN<7>")
	)
	(segment
		(start 288.454084 -304.709068)
		(end 288.180018 -304.435002)
		(width 0.16002)
		(layer "In2.Cu")
		(net "M_C_CPU0_SB_DQS_DN<7>")
	)
	(segment
		(start 319.407794 -292.237414)
		(end 319.407794 -295.4909)
		(width 0.16002)
		(layer "In2.Cu")
		(net "M_C_CPU0_SB_DQS_DN<7>")
	)
	(segment
		(start 324.0024 -287.725866)
		(end 323.91858 -287.725866)
		(width 0.09525)
		(layer "In2.Cu")
		(net "M_C_CPU0_SB_DQS_DN<7>")
	)
	(segment
		(start 296.478198 -305.70805)
		(end 294.705278 -305.70805)
		(width 0.16002)
		(layer "In2.Cu")
		(net "M_C_CPU0_SB_DQS_DN<7>")
	)
	(segment
		(start 290.00323 -304.553112)
		(end 289.847274 -304.709068)
		(width 0.16002)
		(layer "In2.Cu")
		(net "M_C_CPU0_SB_DQS_DN<7>")
	)
	(segment
		(start 327.32345 -286.55264)
		(end 327.308718 -286.561276)
		(width 0.09525)
		(layer "In2.Cu")
		(net "M_C_CPU0_SB_DQS_DN<7>")
	)
	(segment
		(start 335.400904 -286.566102)
		(end 335.392522 -286.561276)
		(width 0.09525)
		(layer "In2.Cu")
		(net "M_C_CPU0_SB_DQS_DN<7>")
	)
	(segment
		(start 324.53199 -287.196276)
		(end 324.0024 -287.725866)
		(width 0.09525)
		(layer "In2.Cu")
		(net "M_C_CPU0_SB_DQS_DN<7>")
	)
	(segment
		(start 341.040974 -286.566102)
		(end 341.032592 -286.561276)
		(width 0.09525)
		(layer "In2.Cu")
		(net "M_C_CPU0_SB_DQS_DN<7>")
	)
	(segment
		(start 323.91858 -287.725866)
		(end 323.901816 -287.74263)
		(width 0.09525)
		(layer "In2.Cu")
		(net "M_C_CPU0_SB_DQS_DN<7>")
	)
	(segment
		(start 330.700888 -286.566102)
		(end 330.692506 -286.561276)
		(width 0.09525)
		(layer "In2.Cu")
		(net "M_C_CPU0_SB_DQS_DN<7>")
	)
	(segment
		(start 310.081422 -304.817272)
		(end 306.577238 -304.817272)
		(width 0.16002)
		(layer "In2.Cu")
		(net "M_C_CPU0_SB_DQS_DN<7>")
	)
	(segment
		(start 326.932036 -286.561022)
		(end 326.916288 -286.551878)
		(width 0.09525)
		(layer "In2.Cu")
		(net "M_C_CPU0_SB_DQS_DN<7>")
	)
	(segment
		(start 302.26254 -305.680872)
		(end 301.781464 -305.199796)
		(width 0.16002)
		(layer "In2.Cu")
		(net "M_C_CPU0_SB_DQS_DN<7>")
	)
	(segment
		(start 340.10092 -286.566102)
		(end 340.092538 -286.561276)
		(width 0.09525)
		(layer "In2.Cu")
		(net "M_C_CPU0_SB_DQS_DN<7>")
	)
	(segment
		(start 299.08754 -304.857912)
		(end 298.75988 -304.530252)
		(width 0.16002)
		(layer "In2.Cu")
		(net "M_C_CPU0_SB_DQS_DN<7>")
	)
	(segment
		(start 304.315622 -305.406806)
		(end 304.041556 -305.680872)
		(width 0.16002)
		(layer "In2.Cu")
		(net "M_C_CPU0_SB_DQS_DN<7>")
	)
	(segment
		(start 304.041556 -305.680872)
		(end 302.26254 -305.680872)
		(width 0.16002)
		(layer "In2.Cu")
		(net "M_C_CPU0_SB_DQS_DN<7>")
	)
	(segment
		(start 305.697382 -304.5587)
		(end 304.61331 -305.283362)
		(width 0.16002)
		(layer "In2.Cu")
		(net "M_C_CPU0_SB_DQS_DN<7>")
	)
	(segment
		(start 325.46798 -287.01111)
		(end 324.97903 -287.01111)
		(width 0.09525)
		(layer "In2.Cu")
		(net "M_C_CPU0_SB_DQS_DN<7>")
	)
	(segment
		(start 291.494972 -304.832766)
		(end 291.215318 -304.553112)
		(width 0.16002)
		(layer "In2.Cu")
		(net "M_C_CPU0_SB_DQS_DN<7>")
	)
	(segment
		(start 331.640942 -286.566102)
		(end 331.63256 -286.561276)
		(width 0.09525)
		(layer "In2.Cu")
		(net "M_C_CPU0_SB_DQS_DN<7>")
	)
	(segment
		(start 330.129642 -286.561276)
		(end 330.12126 -286.566102)
		(width 0.09525)
		(layer "In2.Cu")
		(net "M_C_CPU0_SB_DQS_DN<7>")
	)
	(segment
		(start 334.829658 -286.561276)
		(end 334.821276 -286.566102)
		(width 0.09525)
		(layer "In2.Cu")
		(net "M_C_CPU0_SB_DQS_DN<7>")
	)
	(segment
		(start 328.249788 -286.561276)
		(end 328.241406 -286.566102)
		(width 0.09525)
		(layer "In2.Cu")
		(net "M_C_CPU0_SB_DQS_DN<7>")
	)
	(segment
		(start 301.781464 -305.199796)
		(end 300.955964 -304.857912)
		(width 0.16002)
		(layer "In2.Cu")
		(net "M_C_CPU0_SB_DQS_DN<7>")
	)
	(segment
		(start 294.705278 -305.70805)
		(end 293.278814 -305.117246)
		(width 0.16002)
		(layer "In2.Cu")
		(net "M_C_CPU0_SB_DQS_DN<7>")
	)
	(segment
		(start 297.985942 -304.690272)
		(end 297.080432 -305.2953)
		(width 0.16002)
		(layer "In2.Cu")
		(net "M_C_CPU0_SB_DQS_DN<7>")
	)
	(segment
		(start 298.146216 -304.530252)
		(end 297.985942 -304.690272)
		(width 0.16002)
		(layer "In2.Cu")
		(net "M_C_CPU0_SB_DQS_DN<7>")
	)
	(segment
		(start 344.041222 -286.236156)
		(end 343.887298 -286.501586)
		(width 0.09525)
		(layer "In2.Cu")
		(net "M_C_CPU0_SB_DQS_DN<7>")
	)
	(segment
		(start 326.179942 -286.612838)
		(end 325.866252 -286.612838)
		(width 0.09525)
		(layer "In2.Cu")
		(net "M_C_CPU0_SB_DQS_DN<7>")
	)
	(segment
		(start 298.75988 -304.530252)
		(end 298.146216 -304.530252)
		(width 0.16002)
		(layer "In2.Cu")
		(net "M_C_CPU0_SB_DQS_DN<7>")
	)
	(segment
		(start 333.889604 -286.561276)
		(end 333.881222 -286.566102)
		(width 0.09525)
		(layer "In2.Cu")
		(net "M_C_CPU0_SB_DQS_DN<7>")
	)
	(arc
		(start 341.409782 -286.561276)
		(mid 341.226007 -286.612048)
		(end 341.040974 -286.566102)
		(width 0.09525)
		(layer "In2.Cu")
		(net "M_C_CPU0_SB_DQS_DN<7>")
	)
	(arc
		(start 329.752452 -286.561276)
		(mid 329.47102 -286.485487)
		(end 329.189588 -286.561276)
		(width 0.09525)
		(layer "In2.Cu")
		(net "M_C_CPU0_SB_DQS_DN<7>")
	)
	(arc
		(start 343.78646 -286.528256)
		(mid 343.534177 -286.486543)
		(end 343.289636 -286.561276)
		(width 0.09525)
		(layer "In2.Cu")
		(net "M_C_CPU0_SB_DQS_DN<7>")
	)
	(arc
		(start 343.281254 -286.566102)
		(mid 343.096222 -286.612016)
		(end 342.912446 -286.561276)
		(width 0.09525)
		(layer "In2.Cu")
		(net "M_C_CPU0_SB_DQS_DN<7>")
	)
	(arc
		(start 331.069696 -286.561276)
		(mid 330.885921 -286.612048)
		(end 330.700888 -286.566102)
		(width 0.09525)
		(layer "In2.Cu")
		(net "M_C_CPU0_SB_DQS_DN<7>")
	)
	(arc
		(start 331.63256 -286.561276)
		(mid 331.351128 -286.485487)
		(end 331.069696 -286.561276)
		(width 0.09525)
		(layer "In2.Cu")
		(net "M_C_CPU0_SB_DQS_DN<7>")
	)
	(arc
		(start 332.00975 -286.561276)
		(mid 331.825975 -286.612048)
		(end 331.640942 -286.566102)
		(width 0.09525)
		(layer "In2.Cu")
		(net "M_C_CPU0_SB_DQS_DN<7>")
	)
	(arc
		(start 328.812652 -286.561276)
		(mid 328.53122 -286.485487)
		(end 328.249788 -286.561276)
		(width 0.09525)
		(layer "In2.Cu")
		(net "M_C_CPU0_SB_DQS_DN<7>")
	)
	(arc
		(start 338.581238 -286.566102)
		(mid 338.396206 -286.612016)
		(end 338.21243 -286.561276)
		(width 0.09525)
		(layer "In2.Cu")
		(net "M_C_CPU0_SB_DQS_DN<7>")
	)
	(arc
		(start 337.27263 -286.561276)
		(mid 336.991198 -286.485487)
		(end 336.709766 -286.561276)
		(width 0.09525)
		(layer "In2.Cu")
		(net "M_C_CPU0_SB_DQS_DN<7>")
	)
	(arc
		(start 336.332576 -286.561276)
		(mid 336.051144 -286.485487)
		(end 335.769712 -286.561276)
		(width 0.09525)
		(layer "In2.Cu")
		(net "M_C_CPU0_SB_DQS_DN<7>")
	)
	(arc
		(start 337.649566 -286.561276)
		(mid 337.461098 -286.611953)
		(end 337.27263 -286.561276)
		(width 0.09525)
		(layer "In2.Cu")
		(net "M_C_CPU0_SB_DQS_DN<7>")
	)
	(arc
		(start 332.94955 -286.561276)
		(mid 332.761082 -286.611953)
		(end 332.572614 -286.561276)
		(width 0.09525)
		(layer "In2.Cu")
		(net "M_C_CPU0_SB_DQS_DN<7>")
	)
	(arc
		(start 341.972646 -286.561276)
		(mid 341.691214 -286.485487)
		(end 341.409782 -286.561276)
		(width 0.09525)
		(layer "In2.Cu")
		(net "M_C_CPU0_SB_DQS_DN<7>")
	)
	(arc
		(start 339.521292 -286.566102)
		(mid 339.33626 -286.612016)
		(end 339.152484 -286.561276)
		(width 0.09525)
		(layer "In2.Cu")
		(net "M_C_CPU0_SB_DQS_DN<7>")
	)
	(arc
		(start 332.572614 -286.561276)
		(mid 332.291182 -286.485487)
		(end 332.00975 -286.561276)
		(width 0.09525)
		(layer "In2.Cu")
		(net "M_C_CPU0_SB_DQS_DN<7>")
	)
	(arc
		(start 336.709766 -286.561276)
		(mid 336.525991 -286.612048)
		(end 336.340958 -286.566102)
		(width 0.09525)
		(layer "In2.Cu")
		(net "M_C_CPU0_SB_DQS_DN<7>")
	)
	(arc
		(start 334.821276 -286.566102)
		(mid 334.636244 -286.612016)
		(end 334.452468 -286.561276)
		(width 0.09525)
		(layer "In2.Cu")
		(net "M_C_CPU0_SB_DQS_DN<7>")
	)
	(arc
		(start 333.881222 -286.566102)
		(mid 333.69619 -286.612016)
		(end 333.512414 -286.561276)
		(width 0.09525)
		(layer "In2.Cu")
		(net "M_C_CPU0_SB_DQS_DN<7>")
	)
	(arc
		(start 333.512414 -286.561276)
		(mid 333.230982 -286.485487)
		(end 332.94955 -286.561276)
		(width 0.09525)
		(layer "In2.Cu")
		(net "M_C_CPU0_SB_DQS_DN<7>")
	)
	(arc
		(start 330.12126 -286.566102)
		(mid 329.936228 -286.612016)
		(end 329.752452 -286.561276)
		(width 0.09525)
		(layer "In2.Cu")
		(net "M_C_CPU0_SB_DQS_DN<7>")
	)
	(arc
		(start 335.769712 -286.561276)
		(mid 335.585937 -286.612048)
		(end 335.400904 -286.566102)
		(width 0.09525)
		(layer "In2.Cu")
		(net "M_C_CPU0_SB_DQS_DN<7>")
	)
	(arc
		(start 340.469728 -286.561276)
		(mid 340.285953 -286.612048)
		(end 340.10092 -286.566102)
		(width 0.09525)
		(layer "In2.Cu")
		(net "M_C_CPU0_SB_DQS_DN<7>")
	)
	(arc
		(start 335.392522 -286.561276)
		(mid 335.11109 -286.485487)
		(end 334.829658 -286.561276)
		(width 0.09525)
		(layer "In2.Cu")
		(net "M_C_CPU0_SB_DQS_DN<7>")
	)
	(arc
		(start 334.452468 -286.561276)
		(mid 334.171036 -286.485487)
		(end 333.889604 -286.561276)
		(width 0.09525)
		(layer "In2.Cu")
		(net "M_C_CPU0_SB_DQS_DN<7>")
	)
	(arc
		(start 326.369172 -286.561276)
		(mid 326.277977 -286.599618)
		(end 326.179942 -286.612838)
		(width 0.09525)
		(layer "In2.Cu")
		(net "M_C_CPU0_SB_DQS_DN<7>")
	)
	(arc
		(start 338.21243 -286.561276)
		(mid 337.930998 -286.485487)
		(end 337.649566 -286.561276)
		(width 0.09525)
		(layer "In2.Cu")
		(net "M_C_CPU0_SB_DQS_DN<7>")
	)
	(arc
		(start 330.692506 -286.561276)
		(mid 330.411074 -286.485487)
		(end 330.129642 -286.561276)
		(width 0.09525)
		(layer "In2.Cu")
		(net "M_C_CPU0_SB_DQS_DN<7>")
	)
	(arc
		(start 324.97903 -287.01111)
		(mid 324.737095 -287.059234)
		(end 324.53199 -287.196276)
		(width 0.09525)
		(layer "In2.Cu")
		(net "M_C_CPU0_SB_DQS_DN<7>")
	)
	(arc
		(start 326.916288 -286.551878)
		(mid 326.641503 -286.485291)
		(end 326.369172 -286.561276)
		(width 0.09525)
		(layer "In2.Cu")
		(net "M_C_CPU0_SB_DQS_DN<7>")
	)
	(arc
		(start 327.308718 -286.561276)
		(mid 327.128349 -286.611744)
		(end 326.946006 -286.568896)
		(width 0.09525)
		(layer "In2.Cu")
		(net "M_C_CPU0_SB_DQS_DN<7>")
	)
	(arc
		(start 339.152484 -286.561276)
		(mid 338.871052 -286.485487)
		(end 338.58962 -286.561276)
		(width 0.09525)
		(layer "In2.Cu")
		(net "M_C_CPU0_SB_DQS_DN<7>")
	)
	(arc
		(start 327.87209 -286.561276)
		(mid 327.598908 -286.4853)
		(end 327.32345 -286.55264)
		(width 0.09525)
		(layer "In2.Cu")
		(net "M_C_CPU0_SB_DQS_DN<7>")
	)
	(arc
		(start 329.189588 -286.561276)
		(mid 329.00112 -286.611953)
		(end 328.812652 -286.561276)
		(width 0.09525)
		(layer "In2.Cu")
		(net "M_C_CPU0_SB_DQS_DN<7>")
	)
	(arc
		(start 341.032592 -286.561276)
		(mid 340.75116 -286.485487)
		(end 340.469728 -286.561276)
		(width 0.09525)
		(layer "In2.Cu")
		(net "M_C_CPU0_SB_DQS_DN<7>")
	)
	(arc
		(start 342.912446 -286.561276)
		(mid 342.631014 -286.485487)
		(end 342.349582 -286.561276)
		(width 0.09525)
		(layer "In2.Cu")
		(net "M_C_CPU0_SB_DQS_DN<7>")
	)
	(arc
		(start 340.092538 -286.561276)
		(mid 339.811106 -286.485487)
		(end 339.529674 -286.561276)
		(width 0.09525)
		(layer "In2.Cu")
		(net "M_C_CPU0_SB_DQS_DN<7>")
	)
	(arc
		(start 342.349582 -286.561276)
		(mid 342.161114 -286.611953)
		(end 341.972646 -286.561276)
		(width 0.09525)
		(layer "In2.Cu")
		(net "M_C_CPU0_SB_DQS_DN<7>")
	)
	(arc
		(start 328.241406 -286.566102)
		(mid 328.05612 -286.612138)
		(end 327.87209 -286.561276)
		(width 0.09525)
		(layer "In2.Cu")
		(net "M_C_CPU0_SB_DQS_DN<7>")
	)
	(segment
		(start 344.508074 -281.110182)
		(end 344.041222 -281.37612)
		(width 0.12954)
		(layer "F.Cu")
		(net "M_C_CPU0_SB_DQS_DN<6>")
	)
	(segment
		(start 313.971178 -289.669728)
		(end 313.760358 -290.17849)
		(width 0.16002)
		(layer "In2.Cu")
		(net "M_C_CPU0_SB_DQS_DN<6>")
	)
	(segment
		(start 291.517832 -295.505632)
		(end 291.218112 -295.205912)
		(width 0.16002)
		(layer "In2.Cu")
		(net "M_C_CPU0_SB_DQS_DN<6>")
	)
	(segment
		(start 290.57473 -295.205912)
		(end 290.204906 -295.359074)
		(width 0.16002)
		(layer "In2.Cu")
		(net "M_C_CPU0_SB_DQS_DN<6>")
	)
	(segment
		(start 306.577238 -295.467278)
		(end 306.318666 -295.208706)
		(width 0.16002)
		(layer "In2.Cu")
		(net "M_C_CPU0_SB_DQS_DN<6>")
	)
	(segment
		(start 343.289636 -281.70124)
		(end 343.281254 -281.706066)
		(width 0.09525)
		(layer "In2.Cu")
		(net "M_C_CPU0_SB_DQS_DN<6>")
	)
	(segment
		(start 304.041556 -296.330878)
		(end 302.26254 -296.330878)
		(width 0.16002)
		(layer "In2.Cu")
		(net "M_C_CPU0_SB_DQS_DN<6>")
	)
	(segment
		(start 343.887298 -281.64155)
		(end 343.78646 -281.66822)
		(width 0.09525)
		(layer "In2.Cu")
		(net "M_C_CPU0_SB_DQS_DN<6>")
	)
	(segment
		(start 304.315622 -296.056812)
		(end 304.041556 -296.330878)
		(width 0.16002)
		(layer "In2.Cu")
		(net "M_C_CPU0_SB_DQS_DN<6>")
	)
	(segment
		(start 328.249788 -281.70124)
		(end 328.241406 -281.706066)
		(width 0.09525)
		(layer "In2.Cu")
		(net "M_C_CPU0_SB_DQS_DN<6>")
	)
	(segment
		(start 299.08754 -295.507918)
		(end 298.75988 -295.180258)
		(width 0.16002)
		(layer "In2.Cu")
		(net "M_C_CPU0_SB_DQS_DN<6>")
	)
	(segment
		(start 293.278814 -295.767252)
		(end 292.14953 -295.767252)
		(width 0.16002)
		(layer "In2.Cu")
		(net "M_C_CPU0_SB_DQS_DN<6>")
	)
	(segment
		(start 323.895974 -281.67203)
		(end 321.968876 -281.67203)
		(width 0.16002)
		(layer "In2.Cu")
		(net "M_C_CPU0_SB_DQS_DN<6>")
	)
	(segment
		(start 309.531512 -295.467278)
		(end 306.577238 -295.467278)
		(width 0.16002)
		(layer "In2.Cu")
		(net "M_C_CPU0_SB_DQS_DN<6>")
	)
	(segment
		(start 304.61331 -295.933368)
		(end 304.315622 -296.056812)
		(width 0.16002)
		(layer "In2.Cu")
		(net "M_C_CPU0_SB_DQS_DN<6>")
	)
	(segment
		(start 298.75988 -295.180258)
		(end 298.179744 -295.180258)
		(width 0.16002)
		(layer "In2.Cu")
		(net "M_C_CPU0_SB_DQS_DN<6>")
	)
	(segment
		(start 292.14953 -295.767252)
		(end 291.517832 -295.505632)
		(width 0.16002)
		(layer "In2.Cu")
		(net "M_C_CPU0_SB_DQS_DN<6>")
	)
	(segment
		(start 296.959274 -295.995598)
		(end 296.756582 -296.079672)
		(width 0.16002)
		(layer "In2.Cu")
		(net "M_C_CPU0_SB_DQS_DN<6>")
	)
	(segment
		(start 321.968876 -281.67203)
		(end 313.971178 -289.669728)
		(width 0.16002)
		(layer "In2.Cu")
		(net "M_C_CPU0_SB_DQS_DN<6>")
	)
	(segment
		(start 323.978778 -281.731212)
		(end 323.919596 -281.67203)
		(width 0.09525)
		(layer "In2.Cu")
		(net "M_C_CPU0_SB_DQS_DN<6>")
	)
	(segment
		(start 340.10092 -281.706066)
		(end 340.092538 -281.70124)
		(width 0.09525)
		(layer "In2.Cu")
		(net "M_C_CPU0_SB_DQS_DN<6>")
	)
	(segment
		(start 336.340958 -281.706066)
		(end 336.332576 -281.70124)
		(width 0.09525)
		(layer "In2.Cu")
		(net "M_C_CPU0_SB_DQS_DN<6>")
	)
	(segment
		(start 302.26254 -296.330878)
		(end 301.900082 -295.96842)
		(width 0.16002)
		(layer "In2.Cu")
		(net "M_C_CPU0_SB_DQS_DN<6>")
	)
	(segment
		(start 313.760358 -291.238432)
		(end 309.531512 -295.467278)
		(width 0.16002)
		(layer "In2.Cu")
		(net "M_C_CPU0_SB_DQS_DN<6>")
	)
	(segment
		(start 301.900082 -295.96842)
		(end 300.78807 -295.507918)
		(width 0.16002)
		(layer "In2.Cu")
		(net "M_C_CPU0_SB_DQS_DN<6>")
	)
	(segment
		(start 296.756582 -296.079672)
		(end 296.478198 -296.358056)
		(width 0.16002)
		(layer "In2.Cu")
		(net "M_C_CPU0_SB_DQS_DN<6>")
	)
	(segment
		(start 330.700888 -281.706066)
		(end 330.692506 -281.70124)
		(width 0.09525)
		(layer "In2.Cu")
		(net "M_C_CPU0_SB_DQS_DN<6>")
	)
	(segment
		(start 300.78807 -295.507918)
		(end 299.08754 -295.507918)
		(width 0.16002)
		(layer "In2.Cu")
		(net "M_C_CPU0_SB_DQS_DN<6>")
	)
	(segment
		(start 335.400904 -281.706066)
		(end 335.392522 -281.70124)
		(width 0.09525)
		(layer "In2.Cu")
		(net "M_C_CPU0_SB_DQS_DN<6>")
	)
	(segment
		(start 291.218112 -295.205912)
		(end 290.57473 -295.205912)
		(width 0.16002)
		(layer "In2.Cu")
		(net "M_C_CPU0_SB_DQS_DN<6>")
	)
	(segment
		(start 344.041222 -281.37612)
		(end 343.887298 -281.64155)
		(width 0.09525)
		(layer "In2.Cu")
		(net "M_C_CPU0_SB_DQS_DN<6>")
	)
	(segment
		(start 306.318666 -295.208706)
		(end 305.697382 -295.208706)
		(width 0.16002)
		(layer "In2.Cu")
		(net "M_C_CPU0_SB_DQS_DN<6>")
	)
	(segment
		(start 325.845424 -281.731212)
		(end 323.978778 -281.731212)
		(width 0.09525)
		(layer "In2.Cu")
		(net "M_C_CPU0_SB_DQS_DN<6>")
	)
	(segment
		(start 325.951342 -281.625294)
		(end 325.845424 -281.731212)
		(width 0.09525)
		(layer "In2.Cu")
		(net "M_C_CPU0_SB_DQS_DN<6>")
	)
	(segment
		(start 327.59015 -281.625294)
		(end 325.951342 -281.625294)
		(width 0.09525)
		(layer "In2.Cu")
		(net "M_C_CPU0_SB_DQS_DN<6>")
	)
	(segment
		(start 331.640942 -281.706066)
		(end 331.63256 -281.70124)
		(width 0.09525)
		(layer "In2.Cu")
		(net "M_C_CPU0_SB_DQS_DN<6>")
	)
	(segment
		(start 333.889604 -281.70124)
		(end 333.881222 -281.706066)
		(width 0.09525)
		(layer "In2.Cu")
		(net "M_C_CPU0_SB_DQS_DN<6>")
	)
	(segment
		(start 294.705278 -296.358056)
		(end 293.278814 -295.767252)
		(width 0.16002)
		(layer "In2.Cu")
		(net "M_C_CPU0_SB_DQS_DN<6>")
	)
	(segment
		(start 290.204906 -295.359074)
		(end 288.454084 -295.359074)
		(width 0.16002)
		(layer "In2.Cu")
		(net "M_C_CPU0_SB_DQS_DN<6>")
	)
	(segment
		(start 288.454084 -295.359074)
		(end 288.180018 -295.085008)
		(width 0.16002)
		(layer "In2.Cu")
		(net "M_C_CPU0_SB_DQS_DN<6>")
	)
	(segment
		(start 330.129642 -281.70124)
		(end 330.12126 -281.706066)
		(width 0.09525)
		(layer "In2.Cu")
		(net "M_C_CPU0_SB_DQS_DN<6>")
	)
	(segment
		(start 339.529674 -281.70124)
		(end 339.521292 -281.706066)
		(width 0.09525)
		(layer "In2.Cu")
		(net "M_C_CPU0_SB_DQS_DN<6>")
	)
	(segment
		(start 341.040974 -281.706066)
		(end 341.032592 -281.70124)
		(width 0.09525)
		(layer "In2.Cu")
		(net "M_C_CPU0_SB_DQS_DN<6>")
	)
	(segment
		(start 305.697382 -295.208706)
		(end 304.61331 -295.933368)
		(width 0.16002)
		(layer "In2.Cu")
		(net "M_C_CPU0_SB_DQS_DN<6>")
	)
	(segment
		(start 296.478198 -296.358056)
		(end 294.705278 -296.358056)
		(width 0.16002)
		(layer "In2.Cu")
		(net "M_C_CPU0_SB_DQS_DN<6>")
	)
	(segment
		(start 338.58962 -281.70124)
		(end 338.581238 -281.706066)
		(width 0.09525)
		(layer "In2.Cu")
		(net "M_C_CPU0_SB_DQS_DN<6>")
	)
	(segment
		(start 334.829658 -281.70124)
		(end 334.821276 -281.706066)
		(width 0.09525)
		(layer "In2.Cu")
		(net "M_C_CPU0_SB_DQS_DN<6>")
	)
	(segment
		(start 313.760358 -290.17849)
		(end 313.760358 -291.238432)
		(width 0.16002)
		(layer "In2.Cu")
		(net "M_C_CPU0_SB_DQS_DN<6>")
	)
	(segment
		(start 323.919596 -281.67203)
		(end 323.895974 -281.67203)
		(width 0.09525)
		(layer "In2.Cu")
		(net "M_C_CPU0_SB_DQS_DN<6>")
	)
	(segment
		(start 298.179744 -295.180258)
		(end 296.959274 -295.995598)
		(width 0.16002)
		(layer "In2.Cu")
		(net "M_C_CPU0_SB_DQS_DN<6>")
	)
	(arc
		(start 340.469728 -281.70124)
		(mid 340.285953 -281.752012)
		(end 340.10092 -281.706066)
		(width 0.09525)
		(layer "In2.Cu")
		(net "M_C_CPU0_SB_DQS_DN<6>")
	)
	(arc
		(start 327.87209 -281.70124)
		(mid 327.736144 -281.644616)
		(end 327.59015 -281.625294)
		(width 0.09525)
		(layer "In2.Cu")
		(net "M_C_CPU0_SB_DQS_DN<6>")
	)
	(arc
		(start 332.94955 -281.70124)
		(mid 332.761082 -281.751917)
		(end 332.572614 -281.70124)
		(width 0.09525)
		(layer "In2.Cu")
		(net "M_C_CPU0_SB_DQS_DN<6>")
	)
	(arc
		(start 332.00975 -281.70124)
		(mid 331.825975 -281.752012)
		(end 331.640942 -281.706066)
		(width 0.09525)
		(layer "In2.Cu")
		(net "M_C_CPU0_SB_DQS_DN<6>")
	)
	(arc
		(start 338.581238 -281.706066)
		(mid 338.396206 -281.75198)
		(end 338.21243 -281.70124)
		(width 0.09525)
		(layer "In2.Cu")
		(net "M_C_CPU0_SB_DQS_DN<6>")
	)
	(arc
		(start 340.092538 -281.70124)
		(mid 339.811106 -281.625485)
		(end 339.529674 -281.70124)
		(width 0.09525)
		(layer "In2.Cu")
		(net "M_C_CPU0_SB_DQS_DN<6>")
	)
	(arc
		(start 335.769712 -281.70124)
		(mid 335.585937 -281.752012)
		(end 335.400904 -281.706066)
		(width 0.09525)
		(layer "In2.Cu")
		(net "M_C_CPU0_SB_DQS_DN<6>")
	)
	(arc
		(start 336.709766 -281.70124)
		(mid 336.525991 -281.752012)
		(end 336.340958 -281.706066)
		(width 0.09525)
		(layer "In2.Cu")
		(net "M_C_CPU0_SB_DQS_DN<6>")
	)
	(arc
		(start 339.521292 -281.706066)
		(mid 339.33626 -281.75198)
		(end 339.152484 -281.70124)
		(width 0.09525)
		(layer "In2.Cu")
		(net "M_C_CPU0_SB_DQS_DN<6>")
	)
	(arc
		(start 341.972646 -281.70124)
		(mid 341.691214 -281.625485)
		(end 341.409782 -281.70124)
		(width 0.09525)
		(layer "In2.Cu")
		(net "M_C_CPU0_SB_DQS_DN<6>")
	)
	(arc
		(start 332.572614 -281.70124)
		(mid 332.291182 -281.625485)
		(end 332.00975 -281.70124)
		(width 0.09525)
		(layer "In2.Cu")
		(net "M_C_CPU0_SB_DQS_DN<6>")
	)
	(arc
		(start 343.281254 -281.706066)
		(mid 343.096222 -281.75198)
		(end 342.912446 -281.70124)
		(width 0.09525)
		(layer "In2.Cu")
		(net "M_C_CPU0_SB_DQS_DN<6>")
	)
	(arc
		(start 338.21243 -281.70124)
		(mid 337.930998 -281.625485)
		(end 337.649566 -281.70124)
		(width 0.09525)
		(layer "In2.Cu")
		(net "M_C_CPU0_SB_DQS_DN<6>")
	)
	(arc
		(start 341.032592 -281.70124)
		(mid 340.75116 -281.625485)
		(end 340.469728 -281.70124)
		(width 0.09525)
		(layer "In2.Cu")
		(net "M_C_CPU0_SB_DQS_DN<6>")
	)
	(arc
		(start 329.752452 -281.70124)
		(mid 329.47102 -281.625485)
		(end 329.189588 -281.70124)
		(width 0.09525)
		(layer "In2.Cu")
		(net "M_C_CPU0_SB_DQS_DN<6>")
	)
	(arc
		(start 339.152484 -281.70124)
		(mid 338.871052 -281.625485)
		(end 338.58962 -281.70124)
		(width 0.09525)
		(layer "In2.Cu")
		(net "M_C_CPU0_SB_DQS_DN<6>")
	)
	(arc
		(start 333.512414 -281.70124)
		(mid 333.230982 -281.625485)
		(end 332.94955 -281.70124)
		(width 0.09525)
		(layer "In2.Cu")
		(net "M_C_CPU0_SB_DQS_DN<6>")
	)
	(arc
		(start 328.812652 -281.70124)
		(mid 328.53122 -281.625485)
		(end 328.249788 -281.70124)
		(width 0.09525)
		(layer "In2.Cu")
		(net "M_C_CPU0_SB_DQS_DN<6>")
	)
	(arc
		(start 328.241406 -281.706066)
		(mid 328.05612 -281.752102)
		(end 327.87209 -281.70124)
		(width 0.09525)
		(layer "In2.Cu")
		(net "M_C_CPU0_SB_DQS_DN<6>")
	)
	(arc
		(start 330.692506 -281.70124)
		(mid 330.411074 -281.625485)
		(end 330.129642 -281.70124)
		(width 0.09525)
		(layer "In2.Cu")
		(net "M_C_CPU0_SB_DQS_DN<6>")
	)
	(arc
		(start 334.452468 -281.70124)
		(mid 334.171036 -281.625485)
		(end 333.889604 -281.70124)
		(width 0.09525)
		(layer "In2.Cu")
		(net "M_C_CPU0_SB_DQS_DN<6>")
	)
	(arc
		(start 335.392522 -281.70124)
		(mid 335.11109 -281.625485)
		(end 334.829658 -281.70124)
		(width 0.09525)
		(layer "In2.Cu")
		(net "M_C_CPU0_SB_DQS_DN<6>")
	)
	(arc
		(start 333.881222 -281.706066)
		(mid 333.69619 -281.75198)
		(end 333.512414 -281.70124)
		(width 0.09525)
		(layer "In2.Cu")
		(net "M_C_CPU0_SB_DQS_DN<6>")
	)
	(arc
		(start 343.78646 -281.66822)
		(mid 343.534176 -281.626526)
		(end 343.289636 -281.70124)
		(width 0.09525)
		(layer "In2.Cu")
		(net "M_C_CPU0_SB_DQS_DN<6>")
	)
	(arc
		(start 342.912446 -281.70124)
		(mid 342.631014 -281.625485)
		(end 342.349582 -281.70124)
		(width 0.09525)
		(layer "In2.Cu")
		(net "M_C_CPU0_SB_DQS_DN<6>")
	)
	(arc
		(start 331.069696 -281.70124)
		(mid 330.885921 -281.752012)
		(end 330.700888 -281.706066)
		(width 0.09525)
		(layer "In2.Cu")
		(net "M_C_CPU0_SB_DQS_DN<6>")
	)
	(arc
		(start 342.349582 -281.70124)
		(mid 342.161114 -281.751917)
		(end 341.972646 -281.70124)
		(width 0.09525)
		(layer "In2.Cu")
		(net "M_C_CPU0_SB_DQS_DN<6>")
	)
	(arc
		(start 334.821276 -281.706066)
		(mid 334.636244 -281.75198)
		(end 334.452468 -281.70124)
		(width 0.09525)
		(layer "In2.Cu")
		(net "M_C_CPU0_SB_DQS_DN<6>")
	)
	(arc
		(start 337.27263 -281.70124)
		(mid 336.991198 -281.625485)
		(end 336.709766 -281.70124)
		(width 0.09525)
		(layer "In2.Cu")
		(net "M_C_CPU0_SB_DQS_DN<6>")
	)
	(arc
		(start 330.12126 -281.706066)
		(mid 329.936228 -281.75198)
		(end 329.752452 -281.70124)
		(width 0.09525)
		(layer "In2.Cu")
		(net "M_C_CPU0_SB_DQS_DN<6>")
	)
	(arc
		(start 329.189588 -281.70124)
		(mid 329.00112 -281.751917)
		(end 328.812652 -281.70124)
		(width 0.09525)
		(layer "In2.Cu")
		(net "M_C_CPU0_SB_DQS_DN<6>")
	)
	(arc
		(start 336.332576 -281.70124)
		(mid 336.051144 -281.625485)
		(end 335.769712 -281.70124)
		(width 0.09525)
		(layer "In2.Cu")
		(net "M_C_CPU0_SB_DQS_DN<6>")
	)
	(arc
		(start 337.649566 -281.70124)
		(mid 337.461098 -281.751917)
		(end 337.27263 -281.70124)
		(width 0.09525)
		(layer "In2.Cu")
		(net "M_C_CPU0_SB_DQS_DN<6>")
	)
	(arc
		(start 341.409782 -281.70124)
		(mid 341.226007 -281.752012)
		(end 341.040974 -281.706066)
		(width 0.09525)
		(layer "In2.Cu")
		(net "M_C_CPU0_SB_DQS_DN<6>")
	)
	(arc
		(start 331.63256 -281.70124)
		(mid 331.351128 -281.625485)
		(end 331.069696 -281.70124)
		(width 0.09525)
		(layer "In2.Cu")
		(net "M_C_CPU0_SB_DQS_DN<6>")
	)
	(segment
		(start 344.508074 -276.250146)
		(end 344.041222 -276.516084)
		(width 0.12954)
		(layer "F.Cu")
		(net "M_C_CPU0_SB_DQS_DN<5>")
	)
	(segment
		(start 300.883066 -286.157924)
		(end 299.08754 -286.157924)
		(width 0.16002)
		(layer "In2.Cu")
		(net "M_C_CPU0_SB_DQS_DN<5>")
	)
	(segment
		(start 292.08222 -286.417258)
		(end 291.56533 -286.203136)
		(width 0.16002)
		(layer "In2.Cu")
		(net "M_C_CPU0_SB_DQS_DN<5>")
	)
	(segment
		(start 326.940418 -276.84603)
		(end 326.932036 -276.841204)
		(width 0.09525)
		(layer "In2.Cu")
		(net "M_C_CPU0_SB_DQS_DN<5>")
	)
	(segment
		(start 306.318666 -285.858712)
		(end 305.697382 -285.858712)
		(width 0.16002)
		(layer "In2.Cu")
		(net "M_C_CPU0_SB_DQS_DN<5>")
	)
	(segment
		(start 343.289636 -276.841204)
		(end 343.281254 -276.84603)
		(width 0.09525)
		(layer "In2.Cu")
		(net "M_C_CPU0_SB_DQS_DN<5>")
	)
	(segment
		(start 328.249788 -276.841204)
		(end 328.241406 -276.84603)
		(width 0.09525)
		(layer "In2.Cu")
		(net "M_C_CPU0_SB_DQS_DN<5>")
	)
	(segment
		(start 297.708828 -286.267652)
		(end 296.871898 -286.614362)
		(width 0.16002)
		(layer "In2.Cu")
		(net "M_C_CPU0_SB_DQS_DN<5>")
	)
	(segment
		(start 288.454084 -286.00908)
		(end 288.180018 -285.735014)
		(width 0.16002)
		(layer "In2.Cu")
		(net "M_C_CPU0_SB_DQS_DN<5>")
	)
	(segment
		(start 305.697382 -285.858712)
		(end 304.61331 -286.583374)
		(width 0.16002)
		(layer "In2.Cu")
		(net "M_C_CPU0_SB_DQS_DN<5>")
	)
	(segment
		(start 325.34098 -276.765766)
		(end 324.75043 -276.521164)
		(width 0.09525)
		(layer "In2.Cu")
		(net "M_C_CPU0_SB_DQS_DN<5>")
	)
	(segment
		(start 293.860728 -286.417258)
		(end 292.08222 -286.417258)
		(width 0.16002)
		(layer "In2.Cu")
		(net "M_C_CPU0_SB_DQS_DN<5>")
	)
	(segment
		(start 323.978778 -276.107652)
		(end 323.919596 -276.04847)
		(width 0.09525)
		(layer "In2.Cu")
		(net "M_C_CPU0_SB_DQS_DN<5>")
	)
	(segment
		(start 306.577238 -286.117284)
		(end 306.318666 -285.858712)
		(width 0.16002)
		(layer "In2.Cu")
		(net "M_C_CPU0_SB_DQS_DN<5>")
	)
	(segment
		(start 323.895974 -276.04847)
		(end 319.475358 -276.04847)
		(width 0.16002)
		(layer "In2.Cu")
		(net "M_C_CPU0_SB_DQS_DN<5>")
	)
	(segment
		(start 324.336918 -276.107652)
		(end 323.978778 -276.107652)
		(width 0.09525)
		(layer "In2.Cu")
		(net "M_C_CPU0_SB_DQS_DN<5>")
	)
	(segment
		(start 290.235894 -286.00908)
		(end 288.454084 -286.00908)
		(width 0.16002)
		(layer "In2.Cu")
		(net "M_C_CPU0_SB_DQS_DN<5>")
	)
	(segment
		(start 333.889604 -276.841204)
		(end 333.881222 -276.84603)
		(width 0.09525)
		(layer "In2.Cu")
		(net "M_C_CPU0_SB_DQS_DN<5>")
	)
	(segment
		(start 302.26254 -286.980884)
		(end 301.833026 -286.55137)
		(width 0.16002)
		(layer "In2.Cu")
		(net "M_C_CPU0_SB_DQS_DN<5>")
	)
	(segment
		(start 339.529674 -276.841204)
		(end 339.521292 -276.84603)
		(width 0.09525)
		(layer "In2.Cu")
		(net "M_C_CPU0_SB_DQS_DN<5>")
	)
	(segment
		(start 330.700888 -276.84603)
		(end 330.692506 -276.841204)
		(width 0.09525)
		(layer "In2.Cu")
		(net "M_C_CPU0_SB_DQS_DN<5>")
	)
	(segment
		(start 327.32345 -276.832568)
		(end 327.308718 -276.841204)
		(width 0.09525)
		(layer "In2.Cu")
		(net "M_C_CPU0_SB_DQS_DN<5>")
	)
	(segment
		(start 294.397176 -286.639508)
		(end 293.860728 -286.417258)
		(width 0.16002)
		(layer "In2.Cu")
		(net "M_C_CPU0_SB_DQS_DN<5>")
	)
	(segment
		(start 310.21401 -285.309818)
		(end 308.264814 -286.117284)
		(width 0.16002)
		(layer "In2.Cu")
		(net "M_C_CPU0_SB_DQS_DN<5>")
	)
	(segment
		(start 330.129642 -276.841204)
		(end 330.12126 -276.84603)
		(width 0.09525)
		(layer "In2.Cu")
		(net "M_C_CPU0_SB_DQS_DN<5>")
	)
	(segment
		(start 291.56533 -286.203136)
		(end 291.220906 -285.858712)
		(width 0.16002)
		(layer "In2.Cu")
		(net "M_C_CPU0_SB_DQS_DN<5>")
	)
	(segment
		(start 334.829658 -276.841204)
		(end 334.821276 -276.84603)
		(width 0.09525)
		(layer "In2.Cu")
		(net "M_C_CPU0_SB_DQS_DN<5>")
	)
	(segment
		(start 304.61331 -286.583374)
		(end 304.315622 -286.706818)
		(width 0.16002)
		(layer "In2.Cu")
		(net "M_C_CPU0_SB_DQS_DN<5>")
	)
	(segment
		(start 344.041222 -276.516084)
		(end 343.887298 -276.781514)
		(width 0.09525)
		(layer "In2.Cu")
		(net "M_C_CPU0_SB_DQS_DN<5>")
	)
	(segment
		(start 298.146216 -285.830264)
		(end 297.708828 -286.267652)
		(width 0.16002)
		(layer "In2.Cu")
		(net "M_C_CPU0_SB_DQS_DN<5>")
	)
	(segment
		(start 299.08754 -286.157924)
		(end 298.75988 -285.830264)
		(width 0.16002)
		(layer "In2.Cu")
		(net "M_C_CPU0_SB_DQS_DN<5>")
	)
	(segment
		(start 304.041556 -286.980884)
		(end 302.26254 -286.980884)
		(width 0.16002)
		(layer "In2.Cu")
		(net "M_C_CPU0_SB_DQS_DN<5>")
	)
	(segment
		(start 298.75988 -285.830264)
		(end 298.146216 -285.830264)
		(width 0.16002)
		(layer "In2.Cu")
		(net "M_C_CPU0_SB_DQS_DN<5>")
	)
	(segment
		(start 326.651112 -276.765766)
		(end 325.34098 -276.765766)
		(width 0.09525)
		(layer "In2.Cu")
		(net "M_C_CPU0_SB_DQS_DN<5>")
	)
	(segment
		(start 294.76573 -287.008062)
		(end 294.397176 -286.639508)
		(width 0.16002)
		(layer "In2.Cu")
		(net "M_C_CPU0_SB_DQS_DN<5>")
	)
	(segment
		(start 308.264814 -286.117284)
		(end 306.577238 -286.117284)
		(width 0.16002)
		(layer "In2.Cu")
		(net "M_C_CPU0_SB_DQS_DN<5>")
	)
	(segment
		(start 319.475358 -276.04847)
		(end 310.21401 -285.309818)
		(width 0.16002)
		(layer "In2.Cu")
		(net "M_C_CPU0_SB_DQS_DN<5>")
	)
	(segment
		(start 290.386262 -285.858712)
		(end 290.235894 -286.00908)
		(width 0.16002)
		(layer "In2.Cu")
		(net "M_C_CPU0_SB_DQS_DN<5>")
	)
	(segment
		(start 324.75043 -276.521164)
		(end 324.336918 -276.107652)
		(width 0.09525)
		(layer "In2.Cu")
		(net "M_C_CPU0_SB_DQS_DN<5>")
	)
	(segment
		(start 341.040974 -276.84603)
		(end 341.032592 -276.841204)
		(width 0.09525)
		(layer "In2.Cu")
		(net "M_C_CPU0_SB_DQS_DN<5>")
	)
	(segment
		(start 301.833026 -286.55137)
		(end 300.883066 -286.157924)
		(width 0.16002)
		(layer "In2.Cu")
		(net "M_C_CPU0_SB_DQS_DN<5>")
	)
	(segment
		(start 335.400904 -276.84603)
		(end 335.392522 -276.841204)
		(width 0.09525)
		(layer "In2.Cu")
		(net "M_C_CPU0_SB_DQS_DN<5>")
	)
	(segment
		(start 331.640942 -276.84603)
		(end 331.63256 -276.841204)
		(width 0.09525)
		(layer "In2.Cu")
		(net "M_C_CPU0_SB_DQS_DN<5>")
	)
	(segment
		(start 296.871898 -286.614362)
		(end 296.478198 -287.008062)
		(width 0.16002)
		(layer "In2.Cu")
		(net "M_C_CPU0_SB_DQS_DN<5>")
	)
	(segment
		(start 323.919596 -276.04847)
		(end 323.895974 -276.04847)
		(width 0.09525)
		(layer "In2.Cu")
		(net "M_C_CPU0_SB_DQS_DN<5>")
	)
	(segment
		(start 343.887298 -276.781514)
		(end 343.78646 -276.808184)
		(width 0.09525)
		(layer "In2.Cu")
		(net "M_C_CPU0_SB_DQS_DN<5>")
	)
	(segment
		(start 336.340958 -276.84603)
		(end 336.332576 -276.841204)
		(width 0.09525)
		(layer "In2.Cu")
		(net "M_C_CPU0_SB_DQS_DN<5>")
	)
	(segment
		(start 296.478198 -287.008062)
		(end 294.76573 -287.008062)
		(width 0.16002)
		(layer "In2.Cu")
		(net "M_C_CPU0_SB_DQS_DN<5>")
	)
	(segment
		(start 291.220906 -285.858712)
		(end 290.386262 -285.858712)
		(width 0.16002)
		(layer "In2.Cu")
		(net "M_C_CPU0_SB_DQS_DN<5>")
	)
	(segment
		(start 304.315622 -286.706818)
		(end 304.041556 -286.980884)
		(width 0.16002)
		(layer "In2.Cu")
		(net "M_C_CPU0_SB_DQS_DN<5>")
	)
	(segment
		(start 338.58962 -276.841204)
		(end 338.581238 -276.84603)
		(width 0.09525)
		(layer "In2.Cu")
		(net "M_C_CPU0_SB_DQS_DN<5>")
	)
	(segment
		(start 340.10092 -276.84603)
		(end 340.092538 -276.841204)
		(width 0.09525)
		(layer "In2.Cu")
		(net "M_C_CPU0_SB_DQS_DN<5>")
	)
	(arc
		(start 333.512414 -276.841204)
		(mid 333.230982 -276.765449)
		(end 332.94955 -276.841204)
		(width 0.09525)
		(layer "In2.Cu")
		(net "M_C_CPU0_SB_DQS_DN<5>")
	)
	(arc
		(start 337.649566 -276.841204)
		(mid 337.461098 -276.891881)
		(end 337.27263 -276.841204)
		(width 0.09525)
		(layer "In2.Cu")
		(net "M_C_CPU0_SB_DQS_DN<5>")
	)
	(arc
		(start 327.87209 -276.841204)
		(mid 327.598908 -276.765262)
		(end 327.32345 -276.832568)
		(width 0.09525)
		(layer "In2.Cu")
		(net "M_C_CPU0_SB_DQS_DN<5>")
	)
	(arc
		(start 335.392522 -276.841204)
		(mid 335.11109 -276.765449)
		(end 334.829658 -276.841204)
		(width 0.09525)
		(layer "In2.Cu")
		(net "M_C_CPU0_SB_DQS_DN<5>")
	)
	(arc
		(start 336.332576 -276.841204)
		(mid 336.051144 -276.765449)
		(end 335.769712 -276.841204)
		(width 0.09525)
		(layer "In2.Cu")
		(net "M_C_CPU0_SB_DQS_DN<5>")
	)
	(arc
		(start 336.709766 -276.841204)
		(mid 336.525991 -276.891976)
		(end 336.340958 -276.84603)
		(width 0.09525)
		(layer "In2.Cu")
		(net "M_C_CPU0_SB_DQS_DN<5>")
	)
	(arc
		(start 342.912446 -276.841204)
		(mid 342.631014 -276.765449)
		(end 342.349582 -276.841204)
		(width 0.09525)
		(layer "In2.Cu")
		(net "M_C_CPU0_SB_DQS_DN<5>")
	)
	(arc
		(start 343.281254 -276.84603)
		(mid 343.096222 -276.891944)
		(end 342.912446 -276.841204)
		(width 0.09525)
		(layer "In2.Cu")
		(net "M_C_CPU0_SB_DQS_DN<5>")
	)
	(arc
		(start 329.189588 -276.841204)
		(mid 329.00112 -276.891881)
		(end 328.812652 -276.841204)
		(width 0.09525)
		(layer "In2.Cu")
		(net "M_C_CPU0_SB_DQS_DN<5>")
	)
	(arc
		(start 340.092538 -276.841204)
		(mid 339.811106 -276.765449)
		(end 339.529674 -276.841204)
		(width 0.09525)
		(layer "In2.Cu")
		(net "M_C_CPU0_SB_DQS_DN<5>")
	)
	(arc
		(start 326.932036 -276.841204)
		(mid 326.796558 -276.784908)
		(end 326.651112 -276.765766)
		(width 0.09525)
		(layer "In2.Cu")
		(net "M_C_CPU0_SB_DQS_DN<5>")
	)
	(arc
		(start 338.21243 -276.841204)
		(mid 337.930998 -276.765449)
		(end 337.649566 -276.841204)
		(width 0.09525)
		(layer "In2.Cu")
		(net "M_C_CPU0_SB_DQS_DN<5>")
	)
	(arc
		(start 328.812652 -276.841204)
		(mid 328.53122 -276.765449)
		(end 328.249788 -276.841204)
		(width 0.09525)
		(layer "In2.Cu")
		(net "M_C_CPU0_SB_DQS_DN<5>")
	)
	(arc
		(start 334.821276 -276.84603)
		(mid 334.636244 -276.891944)
		(end 334.452468 -276.841204)
		(width 0.09525)
		(layer "In2.Cu")
		(net "M_C_CPU0_SB_DQS_DN<5>")
	)
	(arc
		(start 333.881222 -276.84603)
		(mid 333.69619 -276.891944)
		(end 333.512414 -276.841204)
		(width 0.09525)
		(layer "In2.Cu")
		(net "M_C_CPU0_SB_DQS_DN<5>")
	)
	(arc
		(start 330.12126 -276.84603)
		(mid 329.936228 -276.891944)
		(end 329.752452 -276.841204)
		(width 0.09525)
		(layer "In2.Cu")
		(net "M_C_CPU0_SB_DQS_DN<5>")
	)
	(arc
		(start 327.308718 -276.841204)
		(mid 327.125197 -276.891848)
		(end 326.940418 -276.84603)
		(width 0.09525)
		(layer "In2.Cu")
		(net "M_C_CPU0_SB_DQS_DN<5>")
	)
	(arc
		(start 337.27263 -276.841204)
		(mid 336.991198 -276.765449)
		(end 336.709766 -276.841204)
		(width 0.09525)
		(layer "In2.Cu")
		(net "M_C_CPU0_SB_DQS_DN<5>")
	)
	(arc
		(start 332.94955 -276.841204)
		(mid 332.761082 -276.891881)
		(end 332.572614 -276.841204)
		(width 0.09525)
		(layer "In2.Cu")
		(net "M_C_CPU0_SB_DQS_DN<5>")
	)
	(arc
		(start 339.152484 -276.841204)
		(mid 338.871052 -276.765449)
		(end 338.58962 -276.841204)
		(width 0.09525)
		(layer "In2.Cu")
		(net "M_C_CPU0_SB_DQS_DN<5>")
	)
	(arc
		(start 335.769712 -276.841204)
		(mid 335.585937 -276.891976)
		(end 335.400904 -276.84603)
		(width 0.09525)
		(layer "In2.Cu")
		(net "M_C_CPU0_SB_DQS_DN<5>")
	)
	(arc
		(start 332.572614 -276.841204)
		(mid 332.291182 -276.765449)
		(end 332.00975 -276.841204)
		(width 0.09525)
		(layer "In2.Cu")
		(net "M_C_CPU0_SB_DQS_DN<5>")
	)
	(arc
		(start 342.349582 -276.841204)
		(mid 342.161114 -276.891881)
		(end 341.972646 -276.841204)
		(width 0.09525)
		(layer "In2.Cu")
		(net "M_C_CPU0_SB_DQS_DN<5>")
	)
	(arc
		(start 338.581238 -276.84603)
		(mid 338.396206 -276.891944)
		(end 338.21243 -276.841204)
		(width 0.09525)
		(layer "In2.Cu")
		(net "M_C_CPU0_SB_DQS_DN<5>")
	)
	(arc
		(start 331.069696 -276.841204)
		(mid 330.885921 -276.891976)
		(end 330.700888 -276.84603)
		(width 0.09525)
		(layer "In2.Cu")
		(net "M_C_CPU0_SB_DQS_DN<5>")
	)
	(arc
		(start 329.752452 -276.841204)
		(mid 329.47102 -276.765449)
		(end 329.189588 -276.841204)
		(width 0.09525)
		(layer "In2.Cu")
		(net "M_C_CPU0_SB_DQS_DN<5>")
	)
	(arc
		(start 343.78646 -276.808184)
		(mid 343.534176 -276.76649)
		(end 343.289636 -276.841204)
		(width 0.09525)
		(layer "In2.Cu")
		(net "M_C_CPU0_SB_DQS_DN<5>")
	)
	(arc
		(start 341.409782 -276.841204)
		(mid 341.226007 -276.891976)
		(end 341.040974 -276.84603)
		(width 0.09525)
		(layer "In2.Cu")
		(net "M_C_CPU0_SB_DQS_DN<5>")
	)
	(arc
		(start 341.032592 -276.841204)
		(mid 340.75116 -276.765449)
		(end 340.469728 -276.841204)
		(width 0.09525)
		(layer "In2.Cu")
		(net "M_C_CPU0_SB_DQS_DN<5>")
	)
	(arc
		(start 332.00975 -276.841204)
		(mid 331.825975 -276.891976)
		(end 331.640942 -276.84603)
		(width 0.09525)
		(layer "In2.Cu")
		(net "M_C_CPU0_SB_DQS_DN<5>")
	)
	(arc
		(start 341.972646 -276.841204)
		(mid 341.691214 -276.765449)
		(end 341.409782 -276.841204)
		(width 0.09525)
		(layer "In2.Cu")
		(net "M_C_CPU0_SB_DQS_DN<5>")
	)
	(arc
		(start 339.521292 -276.84603)
		(mid 339.33626 -276.891944)
		(end 339.152484 -276.841204)
		(width 0.09525)
		(layer "In2.Cu")
		(net "M_C_CPU0_SB_DQS_DN<5>")
	)
	(arc
		(start 334.452468 -276.841204)
		(mid 334.171036 -276.765449)
		(end 333.889604 -276.841204)
		(width 0.09525)
		(layer "In2.Cu")
		(net "M_C_CPU0_SB_DQS_DN<5>")
	)
	(arc
		(start 328.241406 -276.84603)
		(mid 328.05612 -276.892066)
		(end 327.87209 -276.841204)
		(width 0.09525)
		(layer "In2.Cu")
		(net "M_C_CPU0_SB_DQS_DN<5>")
	)
	(arc
		(start 331.63256 -276.841204)
		(mid 331.351128 -276.765449)
		(end 331.069696 -276.841204)
		(width 0.09525)
		(layer "In2.Cu")
		(net "M_C_CPU0_SB_DQS_DN<5>")
	)
	(arc
		(start 340.469728 -276.841204)
		(mid 340.285953 -276.891976)
		(end 340.10092 -276.84603)
		(width 0.09525)
		(layer "In2.Cu")
		(net "M_C_CPU0_SB_DQS_DN<5>")
	)
	(arc
		(start 330.692506 -276.841204)
		(mid 330.411074 -276.765449)
		(end 330.129642 -276.841204)
		(width 0.09525)
		(layer "In2.Cu")
		(net "M_C_CPU0_SB_DQS_DN<5>")
	)
	(segment
		(start 344.508074 -271.39011)
		(end 344.041222 -271.656048)
		(width 0.12954)
		(layer "F.Cu")
		(net "M_C_CPU0_SB_DQS_DN<4>")
	)
	(segment
		(start 300.870366 -276.80793)
		(end 299.038264 -276.80793)
		(width 0.16002)
		(layer "In2.Cu")
		(net "M_C_CPU0_SB_DQS_DN<4>")
	)
	(segment
		(start 290.266882 -276.659086)
		(end 288.454084 -276.659086)
		(width 0.16002)
		(layer "In2.Cu")
		(net "M_C_CPU0_SB_DQS_DN<4>")
	)
	(segment
		(start 297.079924 -277.245572)
		(end 296.756582 -277.379684)
		(width 0.16002)
		(layer "In2.Cu")
		(net "M_C_CPU0_SB_DQS_DN<4>")
	)
	(segment
		(start 323.978778 -270.484092)
		(end 323.919596 -270.42491)
		(width 0.09525)
		(layer "In2.Cu")
		(net "M_C_CPU0_SB_DQS_DN<4>")
	)
	(segment
		(start 302.192436 -277.63089)
		(end 301.10811 -276.906482)
		(width 0.16002)
		(layer "In2.Cu")
		(net "M_C_CPU0_SB_DQS_DN<4>")
	)
	(segment
		(start 293.222934 -277.067264)
		(end 291.766752 -277.067264)
		(width 0.16002)
		(layer "In2.Cu")
		(net "M_C_CPU0_SB_DQS_DN<4>")
	)
	(segment
		(start 327.32345 -271.972532)
		(end 327.308718 -271.981168)
		(width 0.09525)
		(layer "In2.Cu")
		(net "M_C_CPU0_SB_DQS_DN<4>")
	)
	(segment
		(start 340.10092 -271.985994)
		(end 340.092538 -271.981168)
		(width 0.09525)
		(layer "In2.Cu")
		(net "M_C_CPU0_SB_DQS_DN<4>")
	)
	(segment
		(start 301.10811 -276.906482)
		(end 300.870366 -276.80793)
		(width 0.16002)
		(layer "In2.Cu")
		(net "M_C_CPU0_SB_DQS_DN<4>")
	)
	(segment
		(start 325.18731 -270.733774)
		(end 324.798944 -270.733774)
		(width 0.09525)
		(layer "In2.Cu")
		(net "M_C_CPU0_SB_DQS_DN<4>")
	)
	(segment
		(start 323.895974 -270.42491)
		(end 314.54344 -270.42491)
		(width 0.16002)
		(layer "In2.Cu")
		(net "M_C_CPU0_SB_DQS_DN<4>")
	)
	(segment
		(start 308.20106 -276.76729)
		(end 306.577238 -276.76729)
		(width 0.16002)
		(layer "In2.Cu")
		(net "M_C_CPU0_SB_DQS_DN<4>")
	)
	(segment
		(start 291.20592 -276.506432)
		(end 290.419536 -276.506432)
		(width 0.16002)
		(layer "In2.Cu")
		(net "M_C_CPU0_SB_DQS_DN<4>")
	)
	(segment
		(start 330.129642 -271.981168)
		(end 330.12126 -271.985994)
		(width 0.09525)
		(layer "In2.Cu")
		(net "M_C_CPU0_SB_DQS_DN<4>")
	)
	(segment
		(start 306.318666 -276.508718)
		(end 305.65598 -276.508718)
		(width 0.16002)
		(layer "In2.Cu")
		(net "M_C_CPU0_SB_DQS_DN<4>")
	)
	(segment
		(start 336.340958 -271.985994)
		(end 336.332576 -271.981168)
		(width 0.09525)
		(layer "In2.Cu")
		(net "M_C_CPU0_SB_DQS_DN<4>")
	)
	(segment
		(start 335.400904 -271.985994)
		(end 335.392522 -271.981168)
		(width 0.09525)
		(layer "In2.Cu")
		(net "M_C_CPU0_SB_DQS_DN<4>")
	)
	(segment
		(start 328.249788 -271.981168)
		(end 328.241406 -271.985994)
		(width 0.09525)
		(layer "In2.Cu")
		(net "M_C_CPU0_SB_DQS_DN<4>")
	)
	(segment
		(start 334.829658 -271.981168)
		(end 334.821276 -271.985994)
		(width 0.09525)
		(layer "In2.Cu")
		(net "M_C_CPU0_SB_DQS_DN<4>")
	)
	(segment
		(start 338.58962 -271.981168)
		(end 338.581238 -271.985994)
		(width 0.09525)
		(layer "In2.Cu")
		(net "M_C_CPU0_SB_DQS_DN<4>")
	)
	(segment
		(start 304.252376 -277.446994)
		(end 304.06848 -277.63089)
		(width 0.16002)
		(layer "In2.Cu")
		(net "M_C_CPU0_SB_DQS_DN<4>")
	)
	(segment
		(start 297.98645 -276.639782)
		(end 297.079924 -277.245572)
		(width 0.16002)
		(layer "In2.Cu")
		(net "M_C_CPU0_SB_DQS_DN<4>")
	)
	(segment
		(start 304.06848 -277.63089)
		(end 302.192436 -277.63089)
		(width 0.16002)
		(layer "In2.Cu")
		(net "M_C_CPU0_SB_DQS_DN<4>")
	)
	(segment
		(start 299.038264 -276.80793)
		(end 298.710604 -276.48027)
		(width 0.16002)
		(layer "In2.Cu")
		(net "M_C_CPU0_SB_DQS_DN<4>")
	)
	(segment
		(start 298.710604 -276.48027)
		(end 298.146216 -276.48027)
		(width 0.16002)
		(layer "In2.Cu")
		(net "M_C_CPU0_SB_DQS_DN<4>")
	)
	(segment
		(start 330.700888 -271.985994)
		(end 330.692506 -271.981168)
		(width 0.09525)
		(layer "In2.Cu")
		(net "M_C_CPU0_SB_DQS_DN<4>")
	)
	(segment
		(start 331.640942 -271.985994)
		(end 331.63256 -271.981168)
		(width 0.09525)
		(layer "In2.Cu")
		(net "M_C_CPU0_SB_DQS_DN<4>")
	)
	(segment
		(start 314.54344 -270.42491)
		(end 308.20106 -276.76729)
		(width 0.16002)
		(layer "In2.Cu")
		(net "M_C_CPU0_SB_DQS_DN<4>")
	)
	(segment
		(start 341.040974 -271.985994)
		(end 341.032592 -271.981168)
		(width 0.09525)
		(layer "In2.Cu")
		(net "M_C_CPU0_SB_DQS_DN<4>")
	)
	(segment
		(start 326.940418 -271.985994)
		(end 326.932036 -271.981168)
		(width 0.09525)
		(layer "In2.Cu")
		(net "M_C_CPU0_SB_DQS_DN<4>")
	)
	(segment
		(start 344.041222 -271.656048)
		(end 343.887298 -271.921478)
		(width 0.09525)
		(layer "In2.Cu")
		(net "M_C_CPU0_SB_DQS_DN<4>")
	)
	(segment
		(start 296.756582 -277.379684)
		(end 296.478198 -277.658068)
		(width 0.16002)
		(layer "In2.Cu")
		(net "M_C_CPU0_SB_DQS_DN<4>")
	)
	(segment
		(start 343.289636 -271.981168)
		(end 343.281254 -271.985994)
		(width 0.09525)
		(layer "In2.Cu")
		(net "M_C_CPU0_SB_DQS_DN<4>")
	)
	(segment
		(start 324.549262 -270.484092)
		(end 323.978778 -270.484092)
		(width 0.09525)
		(layer "In2.Cu")
		(net "M_C_CPU0_SB_DQS_DN<4>")
	)
	(segment
		(start 326.651112 -271.90573)
		(end 326.359266 -271.90573)
		(width 0.09525)
		(layer "In2.Cu")
		(net "M_C_CPU0_SB_DQS_DN<4>")
	)
	(segment
		(start 324.798944 -270.733774)
		(end 324.549262 -270.484092)
		(width 0.09525)
		(layer "In2.Cu")
		(net "M_C_CPU0_SB_DQS_DN<4>")
	)
	(segment
		(start 298.146216 -276.48027)
		(end 297.98645 -276.639782)
		(width 0.16002)
		(layer "In2.Cu")
		(net "M_C_CPU0_SB_DQS_DN<4>")
	)
	(segment
		(start 290.419536 -276.506432)
		(end 290.266882 -276.659086)
		(width 0.16002)
		(layer "In2.Cu")
		(net "M_C_CPU0_SB_DQS_DN<4>")
	)
	(segment
		(start 291.766752 -277.067264)
		(end 291.20592 -276.506432)
		(width 0.16002)
		(layer "In2.Cu")
		(net "M_C_CPU0_SB_DQS_DN<4>")
	)
	(segment
		(start 305.65598 -276.508718)
		(end 304.252376 -277.446994)
		(width 0.16002)
		(layer "In2.Cu")
		(net "M_C_CPU0_SB_DQS_DN<4>")
	)
	(segment
		(start 294.649652 -277.658068)
		(end 293.222934 -277.067264)
		(width 0.16002)
		(layer "In2.Cu")
		(net "M_C_CPU0_SB_DQS_DN<4>")
	)
	(segment
		(start 323.919596 -270.42491)
		(end 323.895974 -270.42491)
		(width 0.09525)
		(layer "In2.Cu")
		(net "M_C_CPU0_SB_DQS_DN<4>")
	)
	(segment
		(start 339.529674 -271.981168)
		(end 339.521292 -271.985994)
		(width 0.09525)
		(layer "In2.Cu")
		(net "M_C_CPU0_SB_DQS_DN<4>")
	)
	(segment
		(start 296.478198 -277.658068)
		(end 294.649652 -277.658068)
		(width 0.16002)
		(layer "In2.Cu")
		(net "M_C_CPU0_SB_DQS_DN<4>")
	)
	(segment
		(start 343.887298 -271.921478)
		(end 343.78646 -271.948148)
		(width 0.09525)
		(layer "In2.Cu")
		(net "M_C_CPU0_SB_DQS_DN<4>")
	)
	(segment
		(start 333.889604 -271.981168)
		(end 333.881222 -271.985994)
		(width 0.09525)
		(layer "In2.Cu")
		(net "M_C_CPU0_SB_DQS_DN<4>")
	)
	(segment
		(start 288.454084 -276.659086)
		(end 288.180018 -276.38502)
		(width 0.16002)
		(layer "In2.Cu")
		(net "M_C_CPU0_SB_DQS_DN<4>")
	)
	(segment
		(start 326.359266 -271.90573)
		(end 325.18731 -270.733774)
		(width 0.09525)
		(layer "In2.Cu")
		(net "M_C_CPU0_SB_DQS_DN<4>")
	)
	(segment
		(start 306.577238 -276.76729)
		(end 306.318666 -276.508718)
		(width 0.16002)
		(layer "In2.Cu")
		(net "M_C_CPU0_SB_DQS_DN<4>")
	)
	(arc
		(start 333.881222 -271.985994)
		(mid 333.69619 -272.031908)
		(end 333.512414 -271.981168)
		(width 0.09525)
		(layer "In2.Cu")
		(net "M_C_CPU0_SB_DQS_DN<4>")
	)
	(arc
		(start 336.332576 -271.981168)
		(mid 336.051144 -271.905413)
		(end 335.769712 -271.981168)
		(width 0.09525)
		(layer "In2.Cu")
		(net "M_C_CPU0_SB_DQS_DN<4>")
	)
	(arc
		(start 342.349582 -271.981168)
		(mid 342.161114 -272.031845)
		(end 341.972646 -271.981168)
		(width 0.09525)
		(layer "In2.Cu")
		(net "M_C_CPU0_SB_DQS_DN<4>")
	)
	(arc
		(start 332.00975 -271.981168)
		(mid 331.825975 -272.03194)
		(end 331.640942 -271.985994)
		(width 0.09525)
		(layer "In2.Cu")
		(net "M_C_CPU0_SB_DQS_DN<4>")
	)
	(arc
		(start 326.932036 -271.981168)
		(mid 326.796558 -271.924872)
		(end 326.651112 -271.90573)
		(width 0.09525)
		(layer "In2.Cu")
		(net "M_C_CPU0_SB_DQS_DN<4>")
	)
	(arc
		(start 337.649566 -271.981168)
		(mid 337.461098 -272.031845)
		(end 337.27263 -271.981168)
		(width 0.09525)
		(layer "In2.Cu")
		(net "M_C_CPU0_SB_DQS_DN<4>")
	)
	(arc
		(start 334.452468 -271.981168)
		(mid 334.171036 -271.905413)
		(end 333.889604 -271.981168)
		(width 0.09525)
		(layer "In2.Cu")
		(net "M_C_CPU0_SB_DQS_DN<4>")
	)
	(arc
		(start 329.752452 -271.981168)
		(mid 329.47102 -271.905413)
		(end 329.189588 -271.981168)
		(width 0.09525)
		(layer "In2.Cu")
		(net "M_C_CPU0_SB_DQS_DN<4>")
	)
	(arc
		(start 340.092538 -271.981168)
		(mid 339.811106 -271.905413)
		(end 339.529674 -271.981168)
		(width 0.09525)
		(layer "In2.Cu")
		(net "M_C_CPU0_SB_DQS_DN<4>")
	)
	(arc
		(start 338.581238 -271.985994)
		(mid 338.396206 -272.031908)
		(end 338.21243 -271.981168)
		(width 0.09525)
		(layer "In2.Cu")
		(net "M_C_CPU0_SB_DQS_DN<4>")
	)
	(arc
		(start 341.409782 -271.981168)
		(mid 341.226007 -272.03194)
		(end 341.040974 -271.985994)
		(width 0.09525)
		(layer "In2.Cu")
		(net "M_C_CPU0_SB_DQS_DN<4>")
	)
	(arc
		(start 336.709766 -271.981168)
		(mid 336.525991 -272.03194)
		(end 336.340958 -271.985994)
		(width 0.09525)
		(layer "In2.Cu")
		(net "M_C_CPU0_SB_DQS_DN<4>")
	)
	(arc
		(start 343.765886 -271.94002)
		(mid 343.523144 -271.90725)
		(end 343.289636 -271.981168)
		(width 0.09525)
		(layer "In2.Cu")
		(net "M_C_CPU0_SB_DQS_DN<4>")
	)
	(arc
		(start 337.27263 -271.981168)
		(mid 336.991198 -271.905413)
		(end 336.709766 -271.981168)
		(width 0.09525)
		(layer "In2.Cu")
		(net "M_C_CPU0_SB_DQS_DN<4>")
	)
	(arc
		(start 331.069696 -271.981168)
		(mid 330.885921 -272.03194)
		(end 330.700888 -271.985994)
		(width 0.09525)
		(layer "In2.Cu")
		(net "M_C_CPU0_SB_DQS_DN<4>")
	)
	(arc
		(start 332.94955 -271.981168)
		(mid 332.761082 -272.031845)
		(end 332.572614 -271.981168)
		(width 0.09525)
		(layer "In2.Cu")
		(net "M_C_CPU0_SB_DQS_DN<4>")
	)
	(arc
		(start 343.281254 -271.985994)
		(mid 343.096222 -272.031908)
		(end 342.912446 -271.981168)
		(width 0.09525)
		(layer "In2.Cu")
		(net "M_C_CPU0_SB_DQS_DN<4>")
	)
	(arc
		(start 343.78646 -271.948148)
		(mid 343.776212 -271.943985)
		(end 343.765886 -271.94002)
		(width 0.09525)
		(layer "In2.Cu")
		(net "M_C_CPU0_SB_DQS_DN<4>")
	)
	(arc
		(start 330.12126 -271.985994)
		(mid 329.936228 -272.031908)
		(end 329.752452 -271.981168)
		(width 0.09525)
		(layer "In2.Cu")
		(net "M_C_CPU0_SB_DQS_DN<4>")
	)
	(arc
		(start 332.572614 -271.981168)
		(mid 332.291182 -271.905413)
		(end 332.00975 -271.981168)
		(width 0.09525)
		(layer "In2.Cu")
		(net "M_C_CPU0_SB_DQS_DN<4>")
	)
	(arc
		(start 338.21243 -271.981168)
		(mid 337.930998 -271.905413)
		(end 337.649566 -271.981168)
		(width 0.09525)
		(layer "In2.Cu")
		(net "M_C_CPU0_SB_DQS_DN<4>")
	)
	(arc
		(start 342.912446 -271.981168)
		(mid 342.631014 -271.905413)
		(end 342.349582 -271.981168)
		(width 0.09525)
		(layer "In2.Cu")
		(net "M_C_CPU0_SB_DQS_DN<4>")
	)
	(arc
		(start 328.241406 -271.985994)
		(mid 328.05612 -272.03203)
		(end 327.87209 -271.981168)
		(width 0.09525)
		(layer "In2.Cu")
		(net "M_C_CPU0_SB_DQS_DN<4>")
	)
	(arc
		(start 327.308718 -271.981168)
		(mid 327.125197 -272.031812)
		(end 326.940418 -271.985994)
		(width 0.09525)
		(layer "In2.Cu")
		(net "M_C_CPU0_SB_DQS_DN<4>")
	)
	(arc
		(start 341.972646 -271.981168)
		(mid 341.691214 -271.905413)
		(end 341.409782 -271.981168)
		(width 0.09525)
		(layer "In2.Cu")
		(net "M_C_CPU0_SB_DQS_DN<4>")
	)
	(arc
		(start 333.512414 -271.981168)
		(mid 333.230982 -271.905413)
		(end 332.94955 -271.981168)
		(width 0.09525)
		(layer "In2.Cu")
		(net "M_C_CPU0_SB_DQS_DN<4>")
	)
	(arc
		(start 328.812652 -271.981168)
		(mid 328.53122 -271.905413)
		(end 328.249788 -271.981168)
		(width 0.09525)
		(layer "In2.Cu")
		(net "M_C_CPU0_SB_DQS_DN<4>")
	)
	(arc
		(start 331.63256 -271.981168)
		(mid 331.351128 -271.905413)
		(end 331.069696 -271.981168)
		(width 0.09525)
		(layer "In2.Cu")
		(net "M_C_CPU0_SB_DQS_DN<4>")
	)
	(arc
		(start 327.87209 -271.981168)
		(mid 327.598908 -271.905226)
		(end 327.32345 -271.972532)
		(width 0.09525)
		(layer "In2.Cu")
		(net "M_C_CPU0_SB_DQS_DN<4>")
	)
	(arc
		(start 339.152484 -271.981168)
		(mid 338.871052 -271.905413)
		(end 338.58962 -271.981168)
		(width 0.09525)
		(layer "In2.Cu")
		(net "M_C_CPU0_SB_DQS_DN<4>")
	)
	(arc
		(start 335.769712 -271.981168)
		(mid 335.585937 -272.03194)
		(end 335.400904 -271.985994)
		(width 0.09525)
		(layer "In2.Cu")
		(net "M_C_CPU0_SB_DQS_DN<4>")
	)
	(arc
		(start 330.692506 -271.981168)
		(mid 330.411074 -271.905413)
		(end 330.129642 -271.981168)
		(width 0.09525)
		(layer "In2.Cu")
		(net "M_C_CPU0_SB_DQS_DN<4>")
	)
	(arc
		(start 334.821276 -271.985994)
		(mid 334.636244 -272.031908)
		(end 334.452468 -271.981168)
		(width 0.09525)
		(layer "In2.Cu")
		(net "M_C_CPU0_SB_DQS_DN<4>")
	)
	(arc
		(start 339.521292 -271.985994)
		(mid 339.33626 -272.031908)
		(end 339.152484 -271.981168)
		(width 0.09525)
		(layer "In2.Cu")
		(net "M_C_CPU0_SB_DQS_DN<4>")
	)
	(arc
		(start 329.189588 -271.981168)
		(mid 329.00112 -272.031845)
		(end 328.812652 -271.981168)
		(width 0.09525)
		(layer "In2.Cu")
		(net "M_C_CPU0_SB_DQS_DN<4>")
	)
	(arc
		(start 335.392522 -271.981168)
		(mid 335.11109 -271.905413)
		(end 334.829658 -271.981168)
		(width 0.09525)
		(layer "In2.Cu")
		(net "M_C_CPU0_SB_DQS_DN<4>")
	)
	(arc
		(start 340.469728 -271.981168)
		(mid 340.285953 -272.03194)
		(end 340.10092 -271.985994)
		(width 0.09525)
		(layer "In2.Cu")
		(net "M_C_CPU0_SB_DQS_DN<4>")
	)
	(arc
		(start 341.032592 -271.981168)
		(mid 340.75116 -271.905413)
		(end 340.469728 -271.981168)
		(width 0.09525)
		(layer "In2.Cu")
		(net "M_C_CPU0_SB_DQS_DN<4>")
	)
	(segment
		(start 342.627966 -290.83)
		(end 342.161114 -291.095938)
		(width 0.12954)
		(layer "F.Cu")
		(net "M_C_CPU0_SB_DQS_DN<3>")
	)
	(segment
		(start 333.889604 -290.770818)
		(end 333.881222 -290.765992)
		(width 0.09525)
		(layer "In2.Cu")
		(net "M_C_CPU0_SB_DQS_DN<3>")
	)
	(segment
		(start 342.315038 -290.830508)
		(end 342.291924 -290.743894)
		(width 0.09525)
		(layer "In2.Cu")
		(net "M_C_CPU0_SB_DQS_DN<3>")
	)
	(segment
		(start 308.811422 -312.95086)
		(end 308.811422 -312.74258)
		(width 0.16002)
		(layer "In2.Cu")
		(net "M_C_CPU0_SB_DQS_DN<3>")
	)
	(segment
		(start 310.084216 -312.95086)
		(end 309.711344 -313.323732)
		(width 0.16002)
		(layer "In2.Cu")
		(net "M_C_CPU0_SB_DQS_DN<3>")
	)
	(segment
		(start 304.049938 -313.405266)
		(end 301.840138 -313.405266)
		(width 0.16002)
		(layer "In2.Cu")
		(net "M_C_CPU0_SB_DQS_DN<3>")
	)
	(segment
		(start 342.161114 -291.095938)
		(end 342.315038 -290.830508)
		(width 0.09525)
		(layer "In2.Cu")
		(net "M_C_CPU0_SB_DQS_DN<3>")
	)
	(segment
		(start 336.340958 -290.765992)
		(end 336.332576 -290.770818)
		(width 0.09525)
		(layer "In2.Cu")
		(net "M_C_CPU0_SB_DQS_DN<3>")
	)
	(segment
		(start 338.58962 -290.770818)
		(end 338.581238 -290.765992)
		(width 0.09525)
		(layer "In2.Cu")
		(net "M_C_CPU0_SB_DQS_DN<3>")
	)
	(segment
		(start 327.897236 -290.75761)
		(end 327.88352 -290.764722)
		(width 0.09525)
		(layer "In2.Cu")
		(net "M_C_CPU0_SB_DQS_DN<3>")
	)
	(segment
		(start 311.002426 -312.546746)
		(end 310.28005 -312.546746)
		(width 0.16002)
		(layer "In2.Cu")
		(net "M_C_CPU0_SB_DQS_DN<3>")
	)
	(segment
		(start 310.084216 -312.74258)
		(end 310.084216 -312.95086)
		(width 0.16002)
		(layer "In2.Cu")
		(net "M_C_CPU0_SB_DQS_DN<3>")
	)
	(segment
		(start 314.996322 -308.82971)
		(end 315.287406 -309.120794)
		(width 0.16002)
		(layer "In2.Cu")
		(net "M_C_CPU0_SB_DQS_DN<3>")
	)
	(segment
		(start 326.39635 -291.57422)
		(end 326.252078 -291.718492)
		(width 0.09525)
		(layer "In2.Cu")
		(net "M_C_CPU0_SB_DQS_DN<3>")
	)
	(segment
		(start 324.54088 -295.237154)
		(end 324.599808 -295.296082)
		(width 0.09525)
		(layer "In2.Cu")
		(net "M_C_CPU0_SB_DQS_DN<3>")
	)
	(segment
		(start 314.095384 -309.730648)
		(end 313.818524 -309.730648)
		(width 0.16002)
		(layer "In2.Cu")
		(net "M_C_CPU0_SB_DQS_DN<3>")
	)
	(segment
		(start 316.565788 -306.983384)
		(end 316.369954 -307.179218)
		(width 0.16002)
		(layer "In2.Cu")
		(net "M_C_CPU0_SB_DQS_DN<3>")
	)
	(segment
		(start 334.829658 -290.770818)
		(end 334.821276 -290.765992)
		(width 0.09525)
		(layer "In2.Cu")
		(net "M_C_CPU0_SB_DQS_DN<3>")
	)
	(segment
		(start 335.400904 -290.765992)
		(end 335.392522 -290.770818)
		(width 0.09525)
		(layer "In2.Cu")
		(net "M_C_CPU0_SB_DQS_DN<3>")
	)
	(segment
		(start 327.514712 -291.110924)
		(end 326.39635 -291.57422)
		(width 0.09525)
		(layer "In2.Cu")
		(net "M_C_CPU0_SB_DQS_DN<3>")
	)
	(segment
		(start 339.529674 -290.770818)
		(end 339.521292 -290.765992)
		(width 0.09525)
		(layer "In2.Cu")
		(net "M_C_CPU0_SB_DQS_DN<3>")
	)
	(segment
		(start 306.203858 -312.897266)
		(end 305.726338 -312.897266)
		(width 0.16002)
		(layer "In2.Cu")
		(net "M_C_CPU0_SB_DQS_DN<3>")
	)
	(segment
		(start 316.287404 -308.6481)
		(end 315.7601 -308.6481)
		(width 0.16002)
		(layer "In2.Cu")
		(net "M_C_CPU0_SB_DQS_DN<3>")
	)
	(segment
		(start 327.88352 -290.764722)
		(end 327.872852 -290.770818)
		(width 0.09525)
		(layer "In2.Cu")
		(net "M_C_CPU0_SB_DQS_DN<3>")
	)
	(segment
		(start 319.408302 -305.527202)
		(end 319.034668 -305.900836)
		(width 0.16002)
		(layer "In2.Cu")
		(net "M_C_CPU0_SB_DQS_DN<3>")
	)
	(segment
		(start 319.034668 -305.900836)
		(end 318.507364 -305.900836)
		(width 0.16002)
		(layer "In2.Cu")
		(net "M_C_CPU0_SB_DQS_DN<3>")
	)
	(segment
		(start 316.369954 -307.179218)
		(end 316.369954 -307.456078)
		(width 0.16002)
		(layer "In2.Cu")
		(net "M_C_CPU0_SB_DQS_DN<3>")
	)
	(segment
		(start 326.252078 -291.718492)
		(end 326.252078 -292.607492)
		(width 0.09525)
		(layer "In2.Cu")
		(net "M_C_CPU0_SB_DQS_DN<3>")
	)
	(segment
		(start 305.726338 -312.897266)
		(end 304.928778 -313.694826)
		(width 0.16002)
		(layer "In2.Cu")
		(net "M_C_CPU0_SB_DQS_DN<3>")
	)
	(segment
		(start 324.877938 -293.694612)
		(end 324.54088 -294.03167)
		(width 0.09525)
		(layer "In2.Cu")
		(net "M_C_CPU0_SB_DQS_DN<3>")
	)
	(segment
		(start 316.369954 -307.456078)
		(end 316.661038 -307.747162)
		(width 0.16002)
		(layer "In2.Cu")
		(net "M_C_CPU0_SB_DQS_DN<3>")
	)
	(segment
		(start 304.928778 -313.694826)
		(end 304.339498 -313.694826)
		(width 0.16002)
		(layer "In2.Cu")
		(net "M_C_CPU0_SB_DQS_DN<3>")
	)
	(segment
		(start 324.599808 -300.320964)
		(end 320.83502 -304.085752)
		(width 0.16002)
		(layer "In2.Cu")
		(net "M_C_CPU0_SB_DQS_DN<3>")
	)
	(segment
		(start 308.615588 -312.546746)
		(end 306.554378 -312.546746)
		(width 0.16002)
		(layer "In2.Cu")
		(net "M_C_CPU0_SB_DQS_DN<3>")
	)
	(segment
		(start 319.117218 -304.431954)
		(end 319.117218 -304.708814)
		(width 0.16002)
		(layer "In2.Cu")
		(net "M_C_CPU0_SB_DQS_DN<3>")
	)
	(segment
		(start 324.599808 -295.296082)
		(end 324.599808 -295.319704)
		(width 0.09525)
		(layer "In2.Cu")
		(net "M_C_CPU0_SB_DQS_DN<3>")
	)
	(segment
		(start 315.469016 -308.357016)
		(end 315.192156 -308.357016)
		(width 0.16002)
		(layer "In2.Cu")
		(net "M_C_CPU0_SB_DQS_DN<3>")
	)
	(segment
		(start 297.509438 -313.677046)
		(end 296.808398 -313.677046)
		(width 0.16002)
		(layer "In2.Cu")
		(net "M_C_CPU0_SB_DQS_DN<3>")
	)
	(segment
		(start 304.143918 -313.498992)
		(end 304.049938 -313.405266)
		(width 0.16002)
		(layer "In2.Cu")
		(net "M_C_CPU0_SB_DQS_DN<3>")
	)
	(segment
		(start 318.03467 -306.37353)
		(end 318.03467 -306.900834)
		(width 0.16002)
		(layer "In2.Cu")
		(net "M_C_CPU0_SB_DQS_DN<3>")
	)
	(segment
		(start 317.743586 -306.082446)
		(end 318.03467 -306.37353)
		(width 0.16002)
		(layer "In2.Cu")
		(net "M_C_CPU0_SB_DQS_DN<3>")
	)
	(segment
		(start 331.640942 -290.765992)
		(end 331.63256 -290.770818)
		(width 0.09525)
		(layer "In2.Cu")
		(net "M_C_CPU0_SB_DQS_DN<3>")
	)
	(segment
		(start 316.842648 -306.983384)
		(end 316.565788 -306.983384)
		(width 0.16002)
		(layer "In2.Cu")
		(net "M_C_CPU0_SB_DQS_DN<3>")
	)
	(segment
		(start 317.93942 -305.609752)
		(end 317.743586 -305.805586)
		(width 0.16002)
		(layer "In2.Cu")
		(net "M_C_CPU0_SB_DQS_DN<3>")
	)
	(segment
		(start 313.818524 -309.730648)
		(end 311.002426 -312.546746)
		(width 0.16002)
		(layer "In2.Cu")
		(net "M_C_CPU0_SB_DQS_DN<3>")
	)
	(segment
		(start 315.287406 -309.120794)
		(end 315.287406 -309.648098)
		(width 0.16002)
		(layer "In2.Cu")
		(net "M_C_CPU0_SB_DQS_DN<3>")
	)
	(segment
		(start 340.10092 -290.765992)
		(end 340.092538 -290.770818)
		(width 0.09525)
		(layer "In2.Cu")
		(net "M_C_CPU0_SB_DQS_DN<3>")
	)
	(segment
		(start 298.362878 -312.823606)
		(end 297.509438 -313.677046)
		(width 0.16002)
		(layer "In2.Cu")
		(net "M_C_CPU0_SB_DQS_DN<3>")
	)
	(segment
		(start 316.661038 -307.747162)
		(end 316.661038 -308.274466)
		(width 0.16002)
		(layer "In2.Cu")
		(net "M_C_CPU0_SB_DQS_DN<3>")
	)
	(segment
		(start 296.808398 -313.677046)
		(end 296.493438 -313.362086)
		(width 0.16002)
		(layer "In2.Cu")
		(net "M_C_CPU0_SB_DQS_DN<3>")
	)
	(segment
		(start 316.661038 -308.274466)
		(end 316.287404 -308.6481)
		(width 0.16002)
		(layer "In2.Cu")
		(net "M_C_CPU0_SB_DQS_DN<3>")
	)
	(segment
		(start 293.716202 -313.362086)
		(end 293.567104 -313.511184)
		(width 0.16002)
		(layer "In2.Cu")
		(net "M_C_CPU0_SB_DQS_DN<3>")
	)
	(segment
		(start 298.769278 -312.823606)
		(end 298.362878 -312.823606)
		(width 0.16002)
		(layer "In2.Cu")
		(net "M_C_CPU0_SB_DQS_DN<3>")
	)
	(segment
		(start 315.7601 -308.6481)
		(end 315.469016 -308.357016)
		(width 0.16002)
		(layer "In2.Cu")
		(net "M_C_CPU0_SB_DQS_DN<3>")
	)
	(segment
		(start 330.129642 -290.770818)
		(end 330.12126 -290.765992)
		(width 0.09525)
		(layer "In2.Cu")
		(net "M_C_CPU0_SB_DQS_DN<3>")
	)
	(segment
		(start 317.661036 -307.274468)
		(end 317.133732 -307.274468)
		(width 0.16002)
		(layer "In2.Cu")
		(net "M_C_CPU0_SB_DQS_DN<3>")
	)
	(segment
		(start 319.408302 -304.999898)
		(end 319.408302 -305.527202)
		(width 0.16002)
		(layer "In2.Cu")
		(net "M_C_CPU0_SB_DQS_DN<3>")
	)
	(segment
		(start 293.567104 -313.511184)
		(end 292.553898 -313.511184)
		(width 0.16002)
		(layer "In2.Cu")
		(net "M_C_CPU0_SB_DQS_DN<3>")
	)
	(segment
		(start 299.080682 -312.512202)
		(end 298.769278 -312.823606)
		(width 0.16002)
		(layer "In2.Cu")
		(net "M_C_CPU0_SB_DQS_DN<3>")
	)
	(segment
		(start 326.252078 -292.607492)
		(end 325.164958 -293.694612)
		(width 0.09525)
		(layer "In2.Cu")
		(net "M_C_CPU0_SB_DQS_DN<3>")
	)
	(segment
		(start 301.840138 -313.405266)
		(end 300.947074 -312.512202)
		(width 0.16002)
		(layer "In2.Cu")
		(net "M_C_CPU0_SB_DQS_DN<3>")
	)
	(segment
		(start 314.913772 -310.021732)
		(end 314.386468 -310.021732)
		(width 0.16002)
		(layer "In2.Cu")
		(net "M_C_CPU0_SB_DQS_DN<3>")
	)
	(segment
		(start 310.28005 -312.546746)
		(end 310.084216 -312.74258)
		(width 0.16002)
		(layer "In2.Cu")
		(net "M_C_CPU0_SB_DQS_DN<3>")
	)
	(segment
		(start 327.795382 -290.830254)
		(end 327.514712 -291.110924)
		(width 0.09525)
		(layer "In2.Cu")
		(net "M_C_CPU0_SB_DQS_DN<3>")
	)
	(segment
		(start 319.46342 -304.085752)
		(end 319.117218 -304.431954)
		(width 0.16002)
		(layer "In2.Cu")
		(net "M_C_CPU0_SB_DQS_DN<3>")
	)
	(segment
		(start 292.553898 -313.511184)
		(end 292.280086 -313.784996)
		(width 0.16002)
		(layer "In2.Cu")
		(net "M_C_CPU0_SB_DQS_DN<3>")
	)
	(segment
		(start 296.493438 -313.362086)
		(end 293.716202 -313.362086)
		(width 0.16002)
		(layer "In2.Cu")
		(net "M_C_CPU0_SB_DQS_DN<3>")
	)
	(segment
		(start 314.996322 -308.55285)
		(end 314.996322 -308.82971)
		(width 0.16002)
		(layer "In2.Cu")
		(net "M_C_CPU0_SB_DQS_DN<3>")
	)
	(segment
		(start 330.700888 -290.765992)
		(end 330.692506 -290.770818)
		(width 0.09525)
		(layer "In2.Cu")
		(net "M_C_CPU0_SB_DQS_DN<3>")
	)
	(segment
		(start 324.599808 -295.319704)
		(end 324.599808 -300.320964)
		(width 0.16002)
		(layer "In2.Cu")
		(net "M_C_CPU0_SB_DQS_DN<3>")
	)
	(segment
		(start 309.711344 -313.323732)
		(end 309.184294 -313.323732)
		(width 0.16002)
		(layer "In2.Cu")
		(net "M_C_CPU0_SB_DQS_DN<3>")
	)
	(segment
		(start 317.743586 -305.805586)
		(end 317.743586 -306.082446)
		(width 0.16002)
		(layer "In2.Cu")
		(net "M_C_CPU0_SB_DQS_DN<3>")
	)
	(segment
		(start 315.192156 -308.357016)
		(end 314.996322 -308.55285)
		(width 0.16002)
		(layer "In2.Cu")
		(net "M_C_CPU0_SB_DQS_DN<3>")
	)
	(segment
		(start 300.947074 -312.512202)
		(end 299.080682 -312.512202)
		(width 0.16002)
		(layer "In2.Cu")
		(net "M_C_CPU0_SB_DQS_DN<3>")
	)
	(segment
		(start 304.339498 -313.694826)
		(end 304.143918 -313.498992)
		(width 0.16002)
		(layer "In2.Cu")
		(net "M_C_CPU0_SB_DQS_DN<3>")
	)
	(segment
		(start 308.811422 -312.74258)
		(end 308.615588 -312.546746)
		(width 0.16002)
		(layer "In2.Cu")
		(net "M_C_CPU0_SB_DQS_DN<3>")
	)
	(segment
		(start 309.184294 -313.323732)
		(end 308.811422 -312.95086)
		(width 0.16002)
		(layer "In2.Cu")
		(net "M_C_CPU0_SB_DQS_DN<3>")
	)
	(segment
		(start 324.54088 -294.03167)
		(end 324.54088 -295.237154)
		(width 0.09525)
		(layer "In2.Cu")
		(net "M_C_CPU0_SB_DQS_DN<3>")
	)
	(segment
		(start 318.03467 -306.900834)
		(end 317.661036 -307.274468)
		(width 0.16002)
		(layer "In2.Cu")
		(net "M_C_CPU0_SB_DQS_DN<3>")
	)
	(segment
		(start 318.21628 -305.609752)
		(end 317.93942 -305.609752)
		(width 0.16002)
		(layer "In2.Cu")
		(net "M_C_CPU0_SB_DQS_DN<3>")
	)
	(segment
		(start 318.507364 -305.900836)
		(end 318.21628 -305.609752)
		(width 0.16002)
		(layer "In2.Cu")
		(net "M_C_CPU0_SB_DQS_DN<3>")
	)
	(segment
		(start 317.133732 -307.274468)
		(end 316.842648 -306.983384)
		(width 0.16002)
		(layer "In2.Cu")
		(net "M_C_CPU0_SB_DQS_DN<3>")
	)
	(segment
		(start 325.164958 -293.694612)
		(end 324.877938 -293.694612)
		(width 0.09525)
		(layer "In2.Cu")
		(net "M_C_CPU0_SB_DQS_DN<3>")
	)
	(segment
		(start 341.040974 -290.765992)
		(end 341.032592 -290.770818)
		(width 0.09525)
		(layer "In2.Cu")
		(net "M_C_CPU0_SB_DQS_DN<3>")
	)
	(segment
		(start 314.386468 -310.021732)
		(end 314.095384 -309.730648)
		(width 0.16002)
		(layer "In2.Cu")
		(net "M_C_CPU0_SB_DQS_DN<3>")
	)
	(segment
		(start 319.117218 -304.708814)
		(end 319.408302 -304.999898)
		(width 0.16002)
		(layer "In2.Cu")
		(net "M_C_CPU0_SB_DQS_DN<3>")
	)
	(segment
		(start 320.83502 -304.085752)
		(end 319.46342 -304.085752)
		(width 0.16002)
		(layer "In2.Cu")
		(net "M_C_CPU0_SB_DQS_DN<3>")
	)
	(segment
		(start 306.554378 -312.546746)
		(end 306.203858 -312.897266)
		(width 0.16002)
		(layer "In2.Cu")
		(net "M_C_CPU0_SB_DQS_DN<3>")
	)
	(segment
		(start 315.287406 -309.648098)
		(end 314.913772 -310.021732)
		(width 0.16002)
		(layer "In2.Cu")
		(net "M_C_CPU0_SB_DQS_DN<3>")
	)
	(arc
		(start 332.572614 -290.770818)
		(mid 332.291182 -290.846573)
		(end 332.00975 -290.770818)
		(width 0.09525)
		(layer "In2.Cu")
		(net "M_C_CPU0_SB_DQS_DN<3>")
	)
	(arc
		(start 341.032592 -290.770818)
		(mid 340.75116 -290.846573)
		(end 340.469728 -290.770818)
		(width 0.09525)
		(layer "In2.Cu")
		(net "M_C_CPU0_SB_DQS_DN<3>")
	)
	(arc
		(start 334.452468 -290.770818)
		(mid 334.171036 -290.846573)
		(end 333.889604 -290.770818)
		(width 0.09525)
		(layer "In2.Cu")
		(net "M_C_CPU0_SB_DQS_DN<3>")
	)
	(arc
		(start 335.392522 -290.770818)
		(mid 335.11109 -290.846573)
		(end 334.829658 -290.770818)
		(width 0.09525)
		(layer "In2.Cu")
		(net "M_C_CPU0_SB_DQS_DN<3>")
	)
	(arc
		(start 333.512414 -290.770818)
		(mid 333.230982 -290.846573)
		(end 332.94955 -290.770818)
		(width 0.09525)
		(layer "In2.Cu")
		(net "M_C_CPU0_SB_DQS_DN<3>")
	)
	(arc
		(start 341.409782 -290.770818)
		(mid 341.226007 -290.720046)
		(end 341.040974 -290.765992)
		(width 0.09525)
		(layer "In2.Cu")
		(net "M_C_CPU0_SB_DQS_DN<3>")
	)
	(arc
		(start 339.152484 -290.770818)
		(mid 338.871052 -290.846573)
		(end 338.58962 -290.770818)
		(width 0.09525)
		(layer "In2.Cu")
		(net "M_C_CPU0_SB_DQS_DN<3>")
	)
	(arc
		(start 333.881222 -290.765992)
		(mid 333.69619 -290.720078)
		(end 333.512414 -290.770818)
		(width 0.09525)
		(layer "In2.Cu")
		(net "M_C_CPU0_SB_DQS_DN<3>")
	)
	(arc
		(start 330.12126 -290.765992)
		(mid 329.936228 -290.720078)
		(end 329.752452 -290.770818)
		(width 0.09525)
		(layer "In2.Cu")
		(net "M_C_CPU0_SB_DQS_DN<3>")
	)
	(arc
		(start 339.521292 -290.765992)
		(mid 339.33626 -290.720078)
		(end 339.152484 -290.770818)
		(width 0.09525)
		(layer "In2.Cu")
		(net "M_C_CPU0_SB_DQS_DN<3>")
	)
	(arc
		(start 332.94955 -290.770818)
		(mid 332.761082 -290.720141)
		(end 332.572614 -290.770818)
		(width 0.09525)
		(layer "In2.Cu")
		(net "M_C_CPU0_SB_DQS_DN<3>")
	)
	(arc
		(start 340.469728 -290.770818)
		(mid 340.285953 -290.720046)
		(end 340.10092 -290.765992)
		(width 0.09525)
		(layer "In2.Cu")
		(net "M_C_CPU0_SB_DQS_DN<3>")
	)
	(arc
		(start 340.092538 -290.770818)
		(mid 339.811106 -290.846573)
		(end 339.529674 -290.770818)
		(width 0.09525)
		(layer "In2.Cu")
		(net "M_C_CPU0_SB_DQS_DN<3>")
	)
	(arc
		(start 336.709766 -290.770818)
		(mid 336.525991 -290.720046)
		(end 336.340958 -290.765992)
		(width 0.09525)
		(layer "In2.Cu")
		(net "M_C_CPU0_SB_DQS_DN<3>")
	)
	(arc
		(start 332.00975 -290.770818)
		(mid 331.825975 -290.720046)
		(end 331.640942 -290.765992)
		(width 0.09525)
		(layer "In2.Cu")
		(net "M_C_CPU0_SB_DQS_DN<3>")
	)
	(arc
		(start 331.63256 -290.770818)
		(mid 331.351128 -290.846573)
		(end 331.069696 -290.770818)
		(width 0.09525)
		(layer "In2.Cu")
		(net "M_C_CPU0_SB_DQS_DN<3>")
	)
	(arc
		(start 327.872852 -290.770818)
		(mid 327.832169 -290.797998)
		(end 327.795382 -290.830254)
		(width 0.09525)
		(layer "In2.Cu")
		(net "M_C_CPU0_SB_DQS_DN<3>")
	)
	(arc
		(start 329.752452 -290.770818)
		(mid 329.47102 -290.846573)
		(end 329.189588 -290.770818)
		(width 0.09525)
		(layer "In2.Cu")
		(net "M_C_CPU0_SB_DQS_DN<3>")
	)
	(arc
		(start 338.21243 -290.770818)
		(mid 337.930998 -290.846573)
		(end 337.649566 -290.770818)
		(width 0.09525)
		(layer "In2.Cu")
		(net "M_C_CPU0_SB_DQS_DN<3>")
	)
	(arc
		(start 338.581238 -290.765992)
		(mid 338.396206 -290.720078)
		(end 338.21243 -290.770818)
		(width 0.09525)
		(layer "In2.Cu")
		(net "M_C_CPU0_SB_DQS_DN<3>")
	)
	(arc
		(start 329.189588 -290.770818)
		(mid 329.00112 -290.720141)
		(end 328.812652 -290.770818)
		(width 0.09525)
		(layer "In2.Cu")
		(net "M_C_CPU0_SB_DQS_DN<3>")
	)
	(arc
		(start 328.249788 -290.770818)
		(mid 328.075156 -290.720278)
		(end 327.897236 -290.75761)
		(width 0.09525)
		(layer "In2.Cu")
		(net "M_C_CPU0_SB_DQS_DN<3>")
	)
	(arc
		(start 337.27263 -290.770818)
		(mid 336.991198 -290.846573)
		(end 336.709766 -290.770818)
		(width 0.09525)
		(layer "In2.Cu")
		(net "M_C_CPU0_SB_DQS_DN<3>")
	)
	(arc
		(start 341.972646 -290.770818)
		(mid 341.691214 -290.846573)
		(end 341.409782 -290.770818)
		(width 0.09525)
		(layer "In2.Cu")
		(net "M_C_CPU0_SB_DQS_DN<3>")
	)
	(arc
		(start 337.649566 -290.770818)
		(mid 337.461098 -290.720141)
		(end 337.27263 -290.770818)
		(width 0.09525)
		(layer "In2.Cu")
		(net "M_C_CPU0_SB_DQS_DN<3>")
	)
	(arc
		(start 334.821276 -290.765992)
		(mid 334.636244 -290.720078)
		(end 334.452468 -290.770818)
		(width 0.09525)
		(layer "In2.Cu")
		(net "M_C_CPU0_SB_DQS_DN<3>")
	)
	(arc
		(start 335.769712 -290.770818)
		(mid 335.585937 -290.720046)
		(end 335.400904 -290.765992)
		(width 0.09525)
		(layer "In2.Cu")
		(net "M_C_CPU0_SB_DQS_DN<3>")
	)
	(arc
		(start 328.812652 -290.770818)
		(mid 328.53122 -290.846573)
		(end 328.249788 -290.770818)
		(width 0.09525)
		(layer "In2.Cu")
		(net "M_C_CPU0_SB_DQS_DN<3>")
	)
	(arc
		(start 331.069696 -290.770818)
		(mid 330.885921 -290.720046)
		(end 330.700888 -290.765992)
		(width 0.09525)
		(layer "In2.Cu")
		(net "M_C_CPU0_SB_DQS_DN<3>")
	)
	(arc
		(start 330.692506 -290.770818)
		(mid 330.411074 -290.846573)
		(end 330.129642 -290.770818)
		(width 0.09525)
		(layer "In2.Cu")
		(net "M_C_CPU0_SB_DQS_DN<3>")
	)
	(arc
		(start 342.291924 -290.743894)
		(mid 342.129273 -290.721634)
		(end 341.972646 -290.770818)
		(width 0.09525)
		(layer "In2.Cu")
		(net "M_C_CPU0_SB_DQS_DN<3>")
	)
	(arc
		(start 336.332576 -290.770818)
		(mid 336.051144 -290.846573)
		(end 335.769712 -290.770818)
		(width 0.09525)
		(layer "In2.Cu")
		(net "M_C_CPU0_SB_DQS_DN<3>")
	)
	(segment
		(start 342.627966 -285.970218)
		(end 342.161114 -286.236156)
		(width 0.12954)
		(layer "F.Cu")
		(net "M_C_CPU0_SB_DQS_DN<2>")
	)
	(segment
		(start 314.4266 -298.932346)
		(end 314.14974 -298.932346)
		(width 0.16002)
		(layer "In2.Cu")
		(net "M_C_CPU0_SB_DQS_DN<2>")
	)
	(segment
		(start 333.889604 -285.911036)
		(end 333.881222 -285.90621)
		(width 0.09525)
		(layer "In2.Cu")
		(net "M_C_CPU0_SB_DQS_DN<2>")
	)
	(segment
		(start 314.532264 -299.03801)
		(end 314.4266 -298.932346)
		(width 0.16002)
		(layer "In2.Cu")
		(net "M_C_CPU0_SB_DQS_DN<2>")
	)
	(segment
		(start 340.10092 -285.90621)
		(end 340.092538 -285.911036)
		(width 0.09525)
		(layer "In2.Cu")
		(net "M_C_CPU0_SB_DQS_DN<2>")
	)
	(segment
		(start 313.685428 -300.411896)
		(end 313.158632 -300.411642)
		(width 0.16002)
		(layer "In2.Cu")
		(net "M_C_CPU0_SB_DQS_DN<2>")
	)
	(segment
		(start 304.339498 -304.344832)
		(end 304.049938 -304.055272)
		(width 0.16002)
		(layer "In2.Cu")
		(net "M_C_CPU0_SB_DQS_DN<2>")
	)
	(segment
		(start 342.315038 -285.970726)
		(end 342.291924 -285.884112)
		(width 0.09525)
		(layer "In2.Cu")
		(net "M_C_CPU0_SB_DQS_DN<2>")
	)
	(segment
		(start 311.082182 -301.750984)
		(end 311.082182 -302.027844)
		(width 0.16002)
		(layer "In2.Cu")
		(net "M_C_CPU0_SB_DQS_DN<2>")
	)
	(segment
		(start 310.06034 -303.196752)
		(end 309.864506 -303.392586)
		(width 0.16002)
		(layer "In2.Cu")
		(net "M_C_CPU0_SB_DQS_DN<2>")
	)
	(segment
		(start 308.591712 -303.86274)
		(end 308.591712 -303.392586)
		(width 0.16002)
		(layer "In2.Cu")
		(net "M_C_CPU0_SB_DQS_DN<2>")
	)
	(segment
		(start 314.059316 -300.037754)
		(end 313.685428 -300.411896)
		(width 0.16002)
		(layer "In2.Cu")
		(net "M_C_CPU0_SB_DQS_DN<2>")
	)
	(segment
		(start 294.754808 -304.16119)
		(end 294.229028 -304.16119)
		(width 0.16002)
		(layer "In2.Cu")
		(net "M_C_CPU0_SB_DQS_DN<2>")
	)
	(segment
		(start 330.700888 -285.90621)
		(end 330.692506 -285.911036)
		(width 0.09525)
		(layer "In2.Cu")
		(net "M_C_CPU0_SB_DQS_DN<2>")
	)
	(segment
		(start 297.509438 -304.327052)
		(end 296.808398 -304.327052)
		(width 0.16002)
		(layer "In2.Cu")
		(net "M_C_CPU0_SB_DQS_DN<2>")
	)
	(segment
		(start 325.819516 -286.039052)
		(end 325.44512 -286.413448)
		(width 0.09525)
		(layer "In2.Cu")
		(net "M_C_CPU0_SB_DQS_DN<2>")
	)
	(segment
		(start 296.493438 -304.012092)
		(end 294.903906 -304.012092)
		(width 0.16002)
		(layer "In2.Cu")
		(net "M_C_CPU0_SB_DQS_DN<2>")
	)
	(segment
		(start 298.362878 -303.473612)
		(end 297.509438 -304.327052)
		(width 0.16002)
		(layer "In2.Cu")
		(net "M_C_CPU0_SB_DQS_DN<2>")
	)
	(segment
		(start 301.370238 -304.408332)
		(end 301.027338 -304.065432)
		(width 0.16002)
		(layer "In2.Cu")
		(net "M_C_CPU0_SB_DQS_DN<2>")
	)
	(segment
		(start 302.002698 -304.408332)
		(end 301.370238 -304.408332)
		(width 0.16002)
		(layer "In2.Cu")
		(net "M_C_CPU0_SB_DQS_DN<2>")
	)
	(segment
		(start 318.841374 -295.25595)
		(end 318.753236 -295.344088)
		(width 0.16002)
		(layer "In2.Cu")
		(net "M_C_CPU0_SB_DQS_DN<2>")
	)
	(segment
		(start 294.112188 -304.27803)
		(end 293.632128 -304.27803)
		(width 0.16002)
		(layer "In2.Cu")
		(net "M_C_CPU0_SB_DQS_DN<2>")
	)
	(segment
		(start 293.632128 -304.27803)
		(end 293.515288 -304.16119)
		(width 0.16002)
		(layer "In2.Cu")
		(net "M_C_CPU0_SB_DQS_DN<2>")
	)
	(segment
		(start 292.553898 -304.16119)
		(end 292.280086 -304.435002)
		(width 0.16002)
		(layer "In2.Cu")
		(net "M_C_CPU0_SB_DQS_DN<2>")
	)
	(segment
		(start 313.953906 -299.12818)
		(end 313.953906 -299.405294)
		(width 0.16002)
		(layer "In2.Cu")
		(net "M_C_CPU0_SB_DQS_DN<2>")
	)
	(segment
		(start 308.591712 -303.392586)
		(end 308.395878 -303.196752)
		(width 0.16002)
		(layer "In2.Cu")
		(net "M_C_CPU0_SB_DQS_DN<2>")
	)
	(segment
		(start 309.864506 -303.392586)
		(end 309.864506 -303.86274)
		(width 0.16002)
		(layer "In2.Cu")
		(net "M_C_CPU0_SB_DQS_DN<2>")
	)
	(segment
		(start 312.311796 -301.785528)
		(end 311.785 -301.785274)
		(width 0.16002)
		(layer "In2.Cu")
		(net "M_C_CPU0_SB_DQS_DN<2>")
	)
	(segment
		(start 341.040974 -285.90621)
		(end 341.032592 -285.911036)
		(width 0.09525)
		(layer "In2.Cu")
		(net "M_C_CPU0_SB_DQS_DN<2>")
	)
	(segment
		(start 318.752982 -295.344088)
		(end 315.05906 -299.03801)
		(width 0.16002)
		(layer "In2.Cu")
		(net "M_C_CPU0_SB_DQS_DN<2>")
	)
	(segment
		(start 327.873868 -285.91129)
		(end 327.849992 -285.925006)
		(width 0.09525)
		(layer "In2.Cu")
		(net "M_C_CPU0_SB_DQS_DN<2>")
	)
	(segment
		(start 324.129146 -286.7152)
		(end 324.105524 -286.7152)
		(width 0.09525)
		(layer "In2.Cu")
		(net "M_C_CPU0_SB_DQS_DN<2>")
	)
	(segment
		(start 315.05906 -299.03801)
		(end 314.532264 -299.03801)
		(width 0.16002)
		(layer "In2.Cu")
		(net "M_C_CPU0_SB_DQS_DN<2>")
	)
	(segment
		(start 311.082182 -302.027844)
		(end 311.312306 -302.257968)
		(width 0.16002)
		(layer "In2.Cu")
		(net "M_C_CPU0_SB_DQS_DN<2>")
	)
	(segment
		(start 327.897236 -285.897828)
		(end 327.873868 -285.91129)
		(width 0.09525)
		(layer "In2.Cu")
		(net "M_C_CPU0_SB_DQS_DN<2>")
	)
	(segment
		(start 309.864506 -303.86274)
		(end 309.491634 -304.235612)
		(width 0.16002)
		(layer "In2.Cu")
		(net "M_C_CPU0_SB_DQS_DN<2>")
	)
	(segment
		(start 293.515288 -304.16119)
		(end 292.553898 -304.16119)
		(width 0.16002)
		(layer "In2.Cu")
		(net "M_C_CPU0_SB_DQS_DN<2>")
	)
	(segment
		(start 296.808398 -304.327052)
		(end 296.493438 -304.012092)
		(width 0.16002)
		(layer "In2.Cu")
		(net "M_C_CPU0_SB_DQS_DN<2>")
	)
	(segment
		(start 330.129642 -285.911036)
		(end 330.12126 -285.90621)
		(width 0.09525)
		(layer "In2.Cu")
		(net "M_C_CPU0_SB_DQS_DN<2>")
	)
	(segment
		(start 311.312052 -302.785272)
		(end 310.900572 -303.196752)
		(width 0.16002)
		(layer "In2.Cu")
		(net "M_C_CPU0_SB_DQS_DN<2>")
	)
	(segment
		(start 335.400904 -285.90621)
		(end 335.392522 -285.911036)
		(width 0.09525)
		(layer "In2.Cu")
		(net "M_C_CPU0_SB_DQS_DN<2>")
	)
	(segment
		(start 311.554876 -301.55515)
		(end 311.278016 -301.55515)
		(width 0.16002)
		(layer "In2.Cu")
		(net "M_C_CPU0_SB_DQS_DN<2>")
	)
	(segment
		(start 313.158632 -300.411642)
		(end 312.928508 -300.181518)
		(width 0.16002)
		(layer "In2.Cu")
		(net "M_C_CPU0_SB_DQS_DN<2>")
	)
	(segment
		(start 339.529674 -285.911036)
		(end 339.521292 -285.90621)
		(width 0.09525)
		(layer "In2.Cu")
		(net "M_C_CPU0_SB_DQS_DN<2>")
	)
	(segment
		(start 311.278016 -301.55515)
		(end 311.082182 -301.750984)
		(width 0.16002)
		(layer "In2.Cu")
		(net "M_C_CPU0_SB_DQS_DN<2>")
	)
	(segment
		(start 306.554378 -303.196752)
		(end 306.203858 -303.547272)
		(width 0.16002)
		(layer "In2.Cu")
		(net "M_C_CPU0_SB_DQS_DN<2>")
	)
	(segment
		(start 301.027338 -304.065432)
		(end 301.027338 -303.375568)
		(width 0.16002)
		(layer "In2.Cu")
		(net "M_C_CPU0_SB_DQS_DN<2>")
	)
	(segment
		(start 309.491634 -304.235612)
		(end 308.964584 -304.235612)
		(width 0.16002)
		(layer "In2.Cu")
		(net "M_C_CPU0_SB_DQS_DN<2>")
	)
	(segment
		(start 327.312782 -285.911036)
		(end 327.289414 -285.897574)
		(width 0.09525)
		(layer "In2.Cu")
		(net "M_C_CPU0_SB_DQS_DN<2>")
	)
	(segment
		(start 324.188074 -286.656272)
		(end 324.129146 -286.7152)
		(width 0.09525)
		(layer "In2.Cu")
		(net "M_C_CPU0_SB_DQS_DN<2>")
	)
	(segment
		(start 324.049898 -286.7152)
		(end 318.841374 -291.923724)
		(width 0.16002)
		(layer "In2.Cu")
		(net "M_C_CPU0_SB_DQS_DN<2>")
	)
	(segment
		(start 300.813978 -303.162208)
		(end 299.080682 -303.162208)
		(width 0.16002)
		(layer "In2.Cu")
		(net "M_C_CPU0_SB_DQS_DN<2>")
	)
	(segment
		(start 331.640942 -285.90621)
		(end 331.63256 -285.911036)
		(width 0.09525)
		(layer "In2.Cu")
		(net "M_C_CPU0_SB_DQS_DN<2>")
	)
	(segment
		(start 324.858634 -286.656272)
		(end 324.188074 -286.656272)
		(width 0.09525)
		(layer "In2.Cu")
		(net "M_C_CPU0_SB_DQS_DN<2>")
	)
	(segment
		(start 334.829658 -285.911036)
		(end 334.821276 -285.90621)
		(width 0.09525)
		(layer "In2.Cu")
		(net "M_C_CPU0_SB_DQS_DN<2>")
	)
	(segment
		(start 308.395878 -303.196752)
		(end 306.554378 -303.196752)
		(width 0.16002)
		(layer "In2.Cu")
		(net "M_C_CPU0_SB_DQS_DN<2>")
	)
	(segment
		(start 302.355758 -304.055272)
		(end 302.002698 -304.408332)
		(width 0.16002)
		(layer "In2.Cu")
		(net "M_C_CPU0_SB_DQS_DN<2>")
	)
	(segment
		(start 298.769278 -303.473612)
		(end 298.362878 -303.473612)
		(width 0.16002)
		(layer "In2.Cu")
		(net "M_C_CPU0_SB_DQS_DN<2>")
	)
	(segment
		(start 338.58962 -285.911036)
		(end 338.581238 -285.90621)
		(width 0.09525)
		(layer "In2.Cu")
		(net "M_C_CPU0_SB_DQS_DN<2>")
	)
	(segment
		(start 312.685938 -300.884336)
		(end 312.685684 -301.41164)
		(width 0.16002)
		(layer "In2.Cu")
		(net "M_C_CPU0_SB_DQS_DN<2>")
	)
	(segment
		(start 342.161114 -286.236156)
		(end 342.315038 -285.970726)
		(width 0.09525)
		(layer "In2.Cu")
		(net "M_C_CPU0_SB_DQS_DN<2>")
	)
	(segment
		(start 305.726338 -303.547272)
		(end 304.928778 -304.344832)
		(width 0.16002)
		(layer "In2.Cu")
		(net "M_C_CPU0_SB_DQS_DN<2>")
	)
	(segment
		(start 312.455814 -300.377352)
		(end 312.455814 -300.654212)
		(width 0.16002)
		(layer "In2.Cu")
		(net "M_C_CPU0_SB_DQS_DN<2>")
	)
	(segment
		(start 311.312306 -302.257968)
		(end 311.312052 -302.785272)
		(width 0.16002)
		(layer "In2.Cu")
		(net "M_C_CPU0_SB_DQS_DN<2>")
	)
	(segment
		(start 326.651366 -285.98749)
		(end 325.943722 -285.98749)
		(width 0.09525)
		(layer "In2.Cu")
		(net "M_C_CPU0_SB_DQS_DN<2>")
	)
	(segment
		(start 312.928508 -300.181518)
		(end 312.651648 -300.181518)
		(width 0.16002)
		(layer "In2.Cu")
		(net "M_C_CPU0_SB_DQS_DN<2>")
	)
	(segment
		(start 318.753236 -295.344088)
		(end 318.752982 -295.344088)
		(width 0.16002)
		(layer "In2.Cu")
		(net "M_C_CPU0_SB_DQS_DN<2>")
	)
	(segment
		(start 312.651648 -300.181518)
		(end 312.455814 -300.377352)
		(width 0.16002)
		(layer "In2.Cu")
		(net "M_C_CPU0_SB_DQS_DN<2>")
	)
	(segment
		(start 312.455814 -300.654212)
		(end 312.685938 -300.884336)
		(width 0.16002)
		(layer "In2.Cu")
		(net "M_C_CPU0_SB_DQS_DN<2>")
	)
	(segment
		(start 314.14974 -298.932346)
		(end 313.953906 -299.12818)
		(width 0.16002)
		(layer "In2.Cu")
		(net "M_C_CPU0_SB_DQS_DN<2>")
	)
	(segment
		(start 313.953906 -299.405294)
		(end 314.059316 -299.510704)
		(width 0.16002)
		(layer "In2.Cu")
		(net "M_C_CPU0_SB_DQS_DN<2>")
	)
	(segment
		(start 294.903906 -304.012092)
		(end 294.754808 -304.16119)
		(width 0.16002)
		(layer "In2.Cu")
		(net "M_C_CPU0_SB_DQS_DN<2>")
	)
	(segment
		(start 294.229028 -304.16119)
		(end 294.112188 -304.27803)
		(width 0.16002)
		(layer "In2.Cu")
		(net "M_C_CPU0_SB_DQS_DN<2>")
	)
	(segment
		(start 299.080682 -303.162208)
		(end 298.769278 -303.473612)
		(width 0.16002)
		(layer "In2.Cu")
		(net "M_C_CPU0_SB_DQS_DN<2>")
	)
	(segment
		(start 314.059316 -299.510704)
		(end 314.059316 -300.037754)
		(width 0.16002)
		(layer "In2.Cu")
		(net "M_C_CPU0_SB_DQS_DN<2>")
	)
	(segment
		(start 308.964584 -304.235612)
		(end 308.591712 -303.86274)
		(width 0.16002)
		(layer "In2.Cu")
		(net "M_C_CPU0_SB_DQS_DN<2>")
	)
	(segment
		(start 304.928778 -304.344832)
		(end 304.339498 -304.344832)
		(width 0.16002)
		(layer "In2.Cu")
		(net "M_C_CPU0_SB_DQS_DN<2>")
	)
	(segment
		(start 318.841374 -291.923724)
		(end 318.841374 -295.25595)
		(width 0.16002)
		(layer "In2.Cu")
		(net "M_C_CPU0_SB_DQS_DN<2>")
	)
	(segment
		(start 324.105524 -286.7152)
		(end 324.049898 -286.7152)
		(width 0.16002)
		(layer "In2.Cu")
		(net "M_C_CPU0_SB_DQS_DN<2>")
	)
	(segment
		(start 311.785 -301.785274)
		(end 311.554876 -301.55515)
		(width 0.16002)
		(layer "In2.Cu")
		(net "M_C_CPU0_SB_DQS_DN<2>")
	)
	(segment
		(start 310.900572 -303.196752)
		(end 310.06034 -303.196752)
		(width 0.16002)
		(layer "In2.Cu")
		(net "M_C_CPU0_SB_DQS_DN<2>")
	)
	(segment
		(start 304.049938 -304.055272)
		(end 302.355758 -304.055272)
		(width 0.16002)
		(layer "In2.Cu")
		(net "M_C_CPU0_SB_DQS_DN<2>")
	)
	(segment
		(start 306.203858 -303.547272)
		(end 305.726338 -303.547272)
		(width 0.16002)
		(layer "In2.Cu")
		(net "M_C_CPU0_SB_DQS_DN<2>")
	)
	(segment
		(start 312.685684 -301.41164)
		(end 312.311796 -301.785528)
		(width 0.16002)
		(layer "In2.Cu")
		(net "M_C_CPU0_SB_DQS_DN<2>")
	)
	(segment
		(start 336.340958 -285.90621)
		(end 336.332576 -285.911036)
		(width 0.09525)
		(layer "In2.Cu")
		(net "M_C_CPU0_SB_DQS_DN<2>")
	)
	(segment
		(start 301.027338 -303.375568)
		(end 300.813978 -303.162208)
		(width 0.16002)
		(layer "In2.Cu")
		(net "M_C_CPU0_SB_DQS_DN<2>")
	)
	(arc
		(start 326.934322 -285.910782)
		(mid 326.797943 -285.967949)
		(end 326.651366 -285.98749)
		(width 0.09525)
		(layer "In2.Cu")
		(net "M_C_CPU0_SB_DQS_DN<2>")
	)
	(arc
		(start 328.812652 -285.911036)
		(mid 328.53122 -285.986791)
		(end 328.249788 -285.911036)
		(width 0.09525)
		(layer "In2.Cu")
		(net "M_C_CPU0_SB_DQS_DN<2>")
	)
	(arc
		(start 327.849992 -285.925006)
		(mid 327.579609 -285.986566)
		(end 327.312782 -285.911036)
		(width 0.09525)
		(layer "In2.Cu")
		(net "M_C_CPU0_SB_DQS_DN<2>")
	)
	(arc
		(start 331.069696 -285.911036)
		(mid 330.885921 -285.860264)
		(end 330.700888 -285.90621)
		(width 0.09525)
		(layer "In2.Cu")
		(net "M_C_CPU0_SB_DQS_DN<2>")
	)
	(arc
		(start 332.572614 -285.911036)
		(mid 332.291182 -285.986791)
		(end 332.00975 -285.911036)
		(width 0.09525)
		(layer "In2.Cu")
		(net "M_C_CPU0_SB_DQS_DN<2>")
	)
	(arc
		(start 338.581238 -285.90621)
		(mid 338.396206 -285.860296)
		(end 338.21243 -285.911036)
		(width 0.09525)
		(layer "In2.Cu")
		(net "M_C_CPU0_SB_DQS_DN<2>")
	)
	(arc
		(start 325.943722 -285.98749)
		(mid 325.876512 -286.000952)
		(end 325.819516 -286.039052)
		(width 0.09525)
		(layer "In2.Cu")
		(net "M_C_CPU0_SB_DQS_DN<2>")
	)
	(arc
		(start 327.289414 -285.897574)
		(mid 327.110226 -285.859729)
		(end 326.934322 -285.910782)
		(width 0.09525)
		(layer "In2.Cu")
		(net "M_C_CPU0_SB_DQS_DN<2>")
	)
	(arc
		(start 329.752452 -285.911036)
		(mid 329.47102 -285.986791)
		(end 329.189588 -285.911036)
		(width 0.09525)
		(layer "In2.Cu")
		(net "M_C_CPU0_SB_DQS_DN<2>")
	)
	(arc
		(start 339.152484 -285.911036)
		(mid 338.871052 -285.986791)
		(end 338.58962 -285.911036)
		(width 0.09525)
		(layer "In2.Cu")
		(net "M_C_CPU0_SB_DQS_DN<2>")
	)
	(arc
		(start 334.452468 -285.911036)
		(mid 334.171036 -285.986791)
		(end 333.889604 -285.911036)
		(width 0.09525)
		(layer "In2.Cu")
		(net "M_C_CPU0_SB_DQS_DN<2>")
	)
	(arc
		(start 328.249788 -285.911036)
		(mid 328.075156 -285.860496)
		(end 327.897236 -285.897828)
		(width 0.09525)
		(layer "In2.Cu")
		(net "M_C_CPU0_SB_DQS_DN<2>")
	)
	(arc
		(start 332.94955 -285.911036)
		(mid 332.761082 -285.860359)
		(end 332.572614 -285.911036)
		(width 0.09525)
		(layer "In2.Cu")
		(net "M_C_CPU0_SB_DQS_DN<2>")
	)
	(arc
		(start 329.189588 -285.911036)
		(mid 329.00112 -285.860359)
		(end 328.812652 -285.911036)
		(width 0.09525)
		(layer "In2.Cu")
		(net "M_C_CPU0_SB_DQS_DN<2>")
	)
	(arc
		(start 337.649566 -285.911036)
		(mid 337.461098 -285.860359)
		(end 337.27263 -285.911036)
		(width 0.09525)
		(layer "In2.Cu")
		(net "M_C_CPU0_SB_DQS_DN<2>")
	)
	(arc
		(start 334.821276 -285.90621)
		(mid 334.636244 -285.860296)
		(end 334.452468 -285.911036)
		(width 0.09525)
		(layer "In2.Cu")
		(net "M_C_CPU0_SB_DQS_DN<2>")
	)
	(arc
		(start 336.332576 -285.911036)
		(mid 336.051144 -285.986791)
		(end 335.769712 -285.911036)
		(width 0.09525)
		(layer "In2.Cu")
		(net "M_C_CPU0_SB_DQS_DN<2>")
	)
	(arc
		(start 335.392522 -285.911036)
		(mid 335.11109 -285.986791)
		(end 334.829658 -285.911036)
		(width 0.09525)
		(layer "In2.Cu")
		(net "M_C_CPU0_SB_DQS_DN<2>")
	)
	(arc
		(start 330.692506 -285.911036)
		(mid 330.411074 -285.986791)
		(end 330.129642 -285.911036)
		(width 0.09525)
		(layer "In2.Cu")
		(net "M_C_CPU0_SB_DQS_DN<2>")
	)
	(arc
		(start 341.972646 -285.911036)
		(mid 341.691214 -285.986791)
		(end 341.409782 -285.911036)
		(width 0.09525)
		(layer "In2.Cu")
		(net "M_C_CPU0_SB_DQS_DN<2>")
	)
	(arc
		(start 331.63256 -285.911036)
		(mid 331.351128 -285.986791)
		(end 331.069696 -285.911036)
		(width 0.09525)
		(layer "In2.Cu")
		(net "M_C_CPU0_SB_DQS_DN<2>")
	)
	(arc
		(start 325.44512 -286.413448)
		(mid 325.176023 -286.59316)
		(end 324.858634 -286.656272)
		(width 0.09525)
		(layer "In2.Cu")
		(net "M_C_CPU0_SB_DQS_DN<2>")
	)
	(arc
		(start 332.00975 -285.911036)
		(mid 331.825975 -285.860264)
		(end 331.640942 -285.90621)
		(width 0.09525)
		(layer "In2.Cu")
		(net "M_C_CPU0_SB_DQS_DN<2>")
	)
	(arc
		(start 333.881222 -285.90621)
		(mid 333.69619 -285.860296)
		(end 333.512414 -285.911036)
		(width 0.09525)
		(layer "In2.Cu")
		(net "M_C_CPU0_SB_DQS_DN<2>")
	)
	(arc
		(start 330.12126 -285.90621)
		(mid 329.936228 -285.860296)
		(end 329.752452 -285.911036)
		(width 0.09525)
		(layer "In2.Cu")
		(net "M_C_CPU0_SB_DQS_DN<2>")
	)
	(arc
		(start 337.27263 -285.911036)
		(mid 336.991198 -285.986791)
		(end 336.709766 -285.911036)
		(width 0.09525)
		(layer "In2.Cu")
		(net "M_C_CPU0_SB_DQS_DN<2>")
	)
	(arc
		(start 342.291924 -285.884112)
		(mid 342.129273 -285.861852)
		(end 341.972646 -285.911036)
		(width 0.09525)
		(layer "In2.Cu")
		(net "M_C_CPU0_SB_DQS_DN<2>")
	)
	(arc
		(start 340.469728 -285.911036)
		(mid 340.285953 -285.860264)
		(end 340.10092 -285.90621)
		(width 0.09525)
		(layer "In2.Cu")
		(net "M_C_CPU0_SB_DQS_DN<2>")
	)
	(arc
		(start 340.092538 -285.911036)
		(mid 339.811106 -285.986791)
		(end 339.529674 -285.911036)
		(width 0.09525)
		(layer "In2.Cu")
		(net "M_C_CPU0_SB_DQS_DN<2>")
	)
	(arc
		(start 338.21243 -285.911036)
		(mid 337.930998 -285.986791)
		(end 337.649566 -285.911036)
		(width 0.09525)
		(layer "In2.Cu")
		(net "M_C_CPU0_SB_DQS_DN<2>")
	)
	(arc
		(start 335.769712 -285.911036)
		(mid 335.585937 -285.860264)
		(end 335.400904 -285.90621)
		(width 0.09525)
		(layer "In2.Cu")
		(net "M_C_CPU0_SB_DQS_DN<2>")
	)
	(arc
		(start 341.032592 -285.911036)
		(mid 340.75116 -285.986791)
		(end 340.469728 -285.911036)
		(width 0.09525)
		(layer "In2.Cu")
		(net "M_C_CPU0_SB_DQS_DN<2>")
	)
	(arc
		(start 333.512414 -285.911036)
		(mid 333.230982 -285.986791)
		(end 332.94955 -285.911036)
		(width 0.09525)
		(layer "In2.Cu")
		(net "M_C_CPU0_SB_DQS_DN<2>")
	)
	(arc
		(start 339.521292 -285.90621)
		(mid 339.33626 -285.860296)
		(end 339.152484 -285.911036)
		(width 0.09525)
		(layer "In2.Cu")
		(net "M_C_CPU0_SB_DQS_DN<2>")
	)
	(arc
		(start 336.709766 -285.911036)
		(mid 336.525991 -285.860264)
		(end 336.340958 -285.90621)
		(width 0.09525)
		(layer "In2.Cu")
		(net "M_C_CPU0_SB_DQS_DN<2>")
	)
	(arc
		(start 341.409782 -285.911036)
		(mid 341.226007 -285.860264)
		(end 341.040974 -285.90621)
		(width 0.09525)
		(layer "In2.Cu")
		(net "M_C_CPU0_SB_DQS_DN<2>")
	)
	(segment
		(start 342.627966 -281.110182)
		(end 342.161114 -281.37612)
		(width 0.12954)
		(layer "F.Cu")
		(net "M_C_CPU0_SB_DQS_DN<1>")
	)
	(segment
		(start 304.07229 -294.705278)
		(end 301.840138 -294.705278)
		(width 0.16002)
		(layer "In2.Cu")
		(net "M_C_CPU0_SB_DQS_DN<1>")
	)
	(segment
		(start 308.466998 -294.500554)
		(end 308.466998 -294.075612)
		(width 0.16002)
		(layer "In2.Cu")
		(net "M_C_CPU0_SB_DQS_DN<1>")
	)
	(segment
		(start 315.250322 -287.306258)
		(end 314.64504 -287.91154)
		(width 0.16002)
		(layer "In2.Cu")
		(net "M_C_CPU0_SB_DQS_DN<1>")
	)
	(segment
		(start 292.553898 -294.811196)
		(end 292.280086 -295.085008)
		(width 0.16002)
		(layer "In2.Cu")
		(net "M_C_CPU0_SB_DQS_DN<1>")
	)
	(segment
		(start 293.522146 -294.662098)
		(end 293.373048 -294.811196)
		(width 0.16002)
		(layer "In2.Cu")
		(net "M_C_CPU0_SB_DQS_DN<1>")
	)
	(segment
		(start 296.808398 -294.977058)
		(end 296.493438 -294.662098)
		(width 0.16002)
		(layer "In2.Cu")
		(net "M_C_CPU0_SB_DQS_DN<1>")
	)
	(segment
		(start 331.640942 -281.046174)
		(end 331.63256 -281.051)
		(width 0.09525)
		(layer "In2.Cu")
		(net "M_C_CPU0_SB_DQS_DN<1>")
	)
	(segment
		(start 310.460136 -292.472872)
		(end 310.183276 -292.472872)
		(width 0.16002)
		(layer "In2.Cu")
		(net "M_C_CPU0_SB_DQS_DN<1>")
	)
	(segment
		(start 299.080682 -293.812214)
		(end 298.769278 -294.123618)
		(width 0.16002)
		(layer "In2.Cu")
		(net "M_C_CPU0_SB_DQS_DN<1>")
	)
	(segment
		(start 310.818022 -292.830758)
		(end 310.460136 -292.472872)
		(width 0.16002)
		(layer "In2.Cu")
		(net "M_C_CPU0_SB_DQS_DN<1>")
	)
	(segment
		(start 323.978524 -281.023822)
		(end 323.919596 -281.08275)
		(width 0.09525)
		(layer "In2.Cu")
		(net "M_C_CPU0_SB_DQS_DN<1>")
	)
	(segment
		(start 315.487558 -287.306258)
		(end 315.250322 -287.306258)
		(width 0.16002)
		(layer "In2.Cu")
		(net "M_C_CPU0_SB_DQS_DN<1>")
	)
	(segment
		(start 339.529674 -281.051)
		(end 339.521292 -281.046174)
		(width 0.09525)
		(layer "In2.Cu")
		(net "M_C_CPU0_SB_DQS_DN<1>")
	)
	(segment
		(start 341.040974 -281.046174)
		(end 341.032592 -281.051)
		(width 0.09525)
		(layer "In2.Cu")
		(net "M_C_CPU0_SB_DQS_DN<1>")
	)
	(segment
		(start 314.64504 -287.91154)
		(end 314.64504 -288.148776)
		(width 0.16002)
		(layer "In2.Cu")
		(net "M_C_CPU0_SB_DQS_DN<1>")
	)
	(segment
		(start 298.769278 -294.123618)
		(end 298.24553 -294.123618)
		(width 0.16002)
		(layer "In2.Cu")
		(net "M_C_CPU0_SB_DQS_DN<1>")
	)
	(segment
		(start 314.113926 -288.67989)
		(end 313.87669 -288.67989)
		(width 0.16002)
		(layer "In2.Cu")
		(net "M_C_CPU0_SB_DQS_DN<1>")
	)
	(segment
		(start 294.002206 -294.662098)
		(end 293.522146 -294.662098)
		(width 0.16002)
		(layer "In2.Cu")
		(net "M_C_CPU0_SB_DQS_DN<1>")
	)
	(segment
		(start 296.493438 -294.662098)
		(end 294.715946 -294.662098)
		(width 0.16002)
		(layer "In2.Cu")
		(net "M_C_CPU0_SB_DQS_DN<1>")
	)
	(segment
		(start 300.947074 -293.812214)
		(end 299.080682 -293.812214)
		(width 0.16002)
		(layer "In2.Cu")
		(net "M_C_CPU0_SB_DQS_DN<1>")
	)
	(segment
		(start 340.10092 -281.046174)
		(end 340.092538 -281.051)
		(width 0.09525)
		(layer "In2.Cu")
		(net "M_C_CPU0_SB_DQS_DN<1>")
	)
	(segment
		(start 311.361074 -291.295074)
		(end 311.361074 -291.571934)
		(width 0.16002)
		(layer "In2.Cu")
		(net "M_C_CPU0_SB_DQS_DN<1>")
	)
	(segment
		(start 330.700888 -281.046174)
		(end 330.692506 -281.051)
		(width 0.09525)
		(layer "In2.Cu")
		(net "M_C_CPU0_SB_DQS_DN<1>")
	)
	(segment
		(start 309.987442 -292.945566)
		(end 310.345328 -293.303452)
		(width 0.16002)
		(layer "In2.Cu")
		(net "M_C_CPU0_SB_DQS_DN<1>")
	)
	(segment
		(start 293.373048 -294.811196)
		(end 292.553898 -294.811196)
		(width 0.16002)
		(layer "In2.Cu")
		(net "M_C_CPU0_SB_DQS_DN<1>")
	)
	(segment
		(start 314.64504 -288.148776)
		(end 314.113926 -288.67989)
		(width 0.16002)
		(layer "In2.Cu")
		(net "M_C_CPU0_SB_DQS_DN<1>")
	)
	(segment
		(start 294.715946 -294.662098)
		(end 294.599106 -294.778938)
		(width 0.16002)
		(layer "In2.Cu")
		(net "M_C_CPU0_SB_DQS_DN<1>")
	)
	(segment
		(start 313.271408 -289.522408)
		(end 312.778394 -290.015422)
		(width 0.16002)
		(layer "In2.Cu")
		(net "M_C_CPU0_SB_DQS_DN<1>")
	)
	(segment
		(start 323.919596 -281.08275)
		(end 323.895974 -281.08275)
		(width 0.09525)
		(layer "In2.Cu")
		(net "M_C_CPU0_SB_DQS_DN<1>")
	)
	(segment
		(start 308.466998 -294.075612)
		(end 308.238144 -293.846758)
		(width 0.16002)
		(layer "In2.Cu")
		(net "M_C_CPU0_SB_DQS_DN<1>")
	)
	(segment
		(start 313.87669 -288.67989)
		(end 313.271408 -289.285172)
		(width 0.16002)
		(layer "In2.Cu")
		(net "M_C_CPU0_SB_DQS_DN<1>")
	)
	(segment
		(start 316.623954 -285.932626)
		(end 316.018672 -286.537908)
		(width 0.16002)
		(layer "In2.Cu")
		(net "M_C_CPU0_SB_DQS_DN<1>")
	)
	(segment
		(start 298.24553 -294.123618)
		(end 297.39209 -294.977058)
		(width 0.16002)
		(layer "In2.Cu")
		(net "M_C_CPU0_SB_DQS_DN<1>")
	)
	(segment
		(start 338.58962 -281.051)
		(end 338.581238 -281.046174)
		(width 0.09525)
		(layer "In2.Cu")
		(net "M_C_CPU0_SB_DQS_DN<1>")
	)
	(segment
		(start 333.889604 -281.051)
		(end 333.881222 -281.046174)
		(width 0.09525)
		(layer "In2.Cu")
		(net "M_C_CPU0_SB_DQS_DN<1>")
	)
	(segment
		(start 310.345328 -293.303452)
		(end 310.345328 -293.838376)
		(width 0.16002)
		(layer "In2.Cu")
		(net "M_C_CPU0_SB_DQS_DN<1>")
	)
	(segment
		(start 324.71233 -280.71191)
		(end 324.400418 -281.023822)
		(width 0.09525)
		(layer "In2.Cu")
		(net "M_C_CPU0_SB_DQS_DN<1>")
	)
	(segment
		(start 297.39209 -294.977058)
		(end 296.808398 -294.977058)
		(width 0.16002)
		(layer "In2.Cu")
		(net "M_C_CPU0_SB_DQS_DN<1>")
	)
	(segment
		(start 311.361074 -291.571934)
		(end 311.71896 -291.92982)
		(width 0.16002)
		(layer "In2.Cu")
		(net "M_C_CPU0_SB_DQS_DN<1>")
	)
	(segment
		(start 312.191654 -291.457126)
		(end 311.833768 -291.09924)
		(width 0.16002)
		(layer "In2.Cu")
		(net "M_C_CPU0_SB_DQS_DN<1>")
	)
	(segment
		(start 312.778394 -290.24199)
		(end 313.092592 -290.556188)
		(width 0.16002)
		(layer "In2.Cu")
		(net "M_C_CPU0_SB_DQS_DN<1>")
	)
	(segment
		(start 316.018672 -286.775144)
		(end 315.487558 -287.306258)
		(width 0.16002)
		(layer "In2.Cu")
		(net "M_C_CPU0_SB_DQS_DN<1>")
	)
	(segment
		(start 327.897236 -281.037792)
		(end 327.873868 -281.051254)
		(width 0.09525)
		(layer "In2.Cu")
		(net "M_C_CPU0_SB_DQS_DN<1>")
	)
	(segment
		(start 306.203858 -294.197278)
		(end 305.726338 -294.197278)
		(width 0.16002)
		(layer "In2.Cu")
		(net "M_C_CPU0_SB_DQS_DN<1>")
	)
	(segment
		(start 310.345328 -293.838376)
		(end 309.346092 -294.837612)
		(width 0.16002)
		(layer "In2.Cu")
		(net "M_C_CPU0_SB_DQS_DN<1>")
	)
	(segment
		(start 311.833768 -291.09924)
		(end 311.556908 -291.09924)
		(width 0.16002)
		(layer "In2.Cu")
		(net "M_C_CPU0_SB_DQS_DN<1>")
	)
	(segment
		(start 313.092592 -291.083492)
		(end 312.718958 -291.457126)
		(width 0.16002)
		(layer "In2.Cu")
		(net "M_C_CPU0_SB_DQS_DN<1>")
	)
	(segment
		(start 311.71896 -291.92982)
		(end 311.71896 -292.457124)
		(width 0.16002)
		(layer "In2.Cu")
		(net "M_C_CPU0_SB_DQS_DN<1>")
	)
	(segment
		(start 316.018672 -286.537908)
		(end 316.018672 -286.775144)
		(width 0.16002)
		(layer "In2.Cu")
		(net "M_C_CPU0_SB_DQS_DN<1>")
	)
	(segment
		(start 294.119046 -294.778938)
		(end 294.002206 -294.662098)
		(width 0.16002)
		(layer "In2.Cu")
		(net "M_C_CPU0_SB_DQS_DN<1>")
	)
	(segment
		(start 330.129642 -281.051)
		(end 330.12126 -281.046174)
		(width 0.09525)
		(layer "In2.Cu")
		(net "M_C_CPU0_SB_DQS_DN<1>")
	)
	(segment
		(start 324.400418 -281.023822)
		(end 323.978524 -281.023822)
		(width 0.09525)
		(layer "In2.Cu")
		(net "M_C_CPU0_SB_DQS_DN<1>")
	)
	(segment
		(start 311.345326 -292.830758)
		(end 310.818022 -292.830758)
		(width 0.16002)
		(layer "In2.Cu")
		(net "M_C_CPU0_SB_DQS_DN<1>")
	)
	(segment
		(start 310.183276 -292.472872)
		(end 309.987442 -292.668706)
		(width 0.16002)
		(layer "In2.Cu")
		(net "M_C_CPU0_SB_DQS_DN<1>")
	)
	(segment
		(start 313.271408 -289.285172)
		(end 313.271408 -289.522408)
		(width 0.16002)
		(layer "In2.Cu")
		(net "M_C_CPU0_SB_DQS_DN<1>")
	)
	(segment
		(start 304.928778 -294.994838)
		(end 304.36185 -294.994838)
		(width 0.16002)
		(layer "In2.Cu")
		(net "M_C_CPU0_SB_DQS_DN<1>")
	)
	(segment
		(start 311.71896 -292.457124)
		(end 311.345326 -292.830758)
		(width 0.16002)
		(layer "In2.Cu")
		(net "M_C_CPU0_SB_DQS_DN<1>")
	)
	(segment
		(start 308.804056 -294.837612)
		(end 308.466998 -294.500554)
		(width 0.16002)
		(layer "In2.Cu")
		(net "M_C_CPU0_SB_DQS_DN<1>")
	)
	(segment
		(start 305.726338 -294.197278)
		(end 304.928778 -294.994838)
		(width 0.16002)
		(layer "In2.Cu")
		(net "M_C_CPU0_SB_DQS_DN<1>")
	)
	(segment
		(start 309.346092 -294.837612)
		(end 308.804056 -294.837612)
		(width 0.16002)
		(layer "In2.Cu")
		(net "M_C_CPU0_SB_DQS_DN<1>")
	)
	(segment
		(start 321.711066 -281.08275)
		(end 316.86119 -285.932626)
		(width 0.16002)
		(layer "In2.Cu")
		(net "M_C_CPU0_SB_DQS_DN<1>")
	)
	(segment
		(start 335.400904 -281.046174)
		(end 335.392522 -281.051)
		(width 0.09525)
		(layer "In2.Cu")
		(net "M_C_CPU0_SB_DQS_DN<1>")
	)
	(segment
		(start 334.829658 -281.051)
		(end 334.821276 -281.046174)
		(width 0.09525)
		(layer "In2.Cu")
		(net "M_C_CPU0_SB_DQS_DN<1>")
	)
	(segment
		(start 312.778394 -290.015422)
		(end 312.778394 -290.24199)
		(width 0.16002)
		(layer "In2.Cu")
		(net "M_C_CPU0_SB_DQS_DN<1>")
	)
	(segment
		(start 323.895974 -281.08275)
		(end 321.711066 -281.08275)
		(width 0.16002)
		(layer "In2.Cu")
		(net "M_C_CPU0_SB_DQS_DN<1>")
	)
	(segment
		(start 325.442072 -280.71191)
		(end 324.71233 -280.71191)
		(width 0.09525)
		(layer "In2.Cu")
		(net "M_C_CPU0_SB_DQS_DN<1>")
	)
	(segment
		(start 325.856092 -281.12593)
		(end 325.442072 -280.71191)
		(width 0.09525)
		(layer "In2.Cu")
		(net "M_C_CPU0_SB_DQS_DN<1>")
	)
	(segment
		(start 308.238144 -293.846758)
		(end 306.554378 -293.846758)
		(width 0.16002)
		(layer "In2.Cu")
		(net "M_C_CPU0_SB_DQS_DN<1>")
	)
	(segment
		(start 312.718958 -291.457126)
		(end 312.191654 -291.457126)
		(width 0.16002)
		(layer "In2.Cu")
		(net "M_C_CPU0_SB_DQS_DN<1>")
	)
	(segment
		(start 342.315038 -281.11069)
		(end 342.291924 -281.024076)
		(width 0.09525)
		(layer "In2.Cu")
		(net "M_C_CPU0_SB_DQS_DN<1>")
	)
	(segment
		(start 313.092592 -290.556188)
		(end 313.092592 -291.083492)
		(width 0.16002)
		(layer "In2.Cu")
		(net "M_C_CPU0_SB_DQS_DN<1>")
	)
	(segment
		(start 327.594214 -281.12593)
		(end 325.856092 -281.12593)
		(width 0.09525)
		(layer "In2.Cu")
		(net "M_C_CPU0_SB_DQS_DN<1>")
	)
	(segment
		(start 301.840138 -294.705278)
		(end 300.947074 -293.812214)
		(width 0.16002)
		(layer "In2.Cu")
		(net "M_C_CPU0_SB_DQS_DN<1>")
	)
	(segment
		(start 336.340958 -281.046174)
		(end 336.332576 -281.051)
		(width 0.09525)
		(layer "In2.Cu")
		(net "M_C_CPU0_SB_DQS_DN<1>")
	)
	(segment
		(start 342.161114 -281.37612)
		(end 342.315038 -281.11069)
		(width 0.09525)
		(layer "In2.Cu")
		(net "M_C_CPU0_SB_DQS_DN<1>")
	)
	(segment
		(start 306.554378 -293.846758)
		(end 306.203858 -294.197278)
		(width 0.16002)
		(layer "In2.Cu")
		(net "M_C_CPU0_SB_DQS_DN<1>")
	)
	(segment
		(start 304.36185 -294.994838)
		(end 304.07229 -294.705278)
		(width 0.16002)
		(layer "In2.Cu")
		(net "M_C_CPU0_SB_DQS_DN<1>")
	)
	(segment
		(start 311.556908 -291.09924)
		(end 311.361074 -291.295074)
		(width 0.16002)
		(layer "In2.Cu")
		(net "M_C_CPU0_SB_DQS_DN<1>")
	)
	(segment
		(start 316.86119 -285.932626)
		(end 316.623954 -285.932626)
		(width 0.16002)
		(layer "In2.Cu")
		(net "M_C_CPU0_SB_DQS_DN<1>")
	)
	(segment
		(start 294.599106 -294.778938)
		(end 294.119046 -294.778938)
		(width 0.16002)
		(layer "In2.Cu")
		(net "M_C_CPU0_SB_DQS_DN<1>")
	)
	(segment
		(start 309.987442 -292.668706)
		(end 309.987442 -292.945566)
		(width 0.16002)
		(layer "In2.Cu")
		(net "M_C_CPU0_SB_DQS_DN<1>")
	)
	(arc
		(start 332.572614 -281.051)
		(mid 332.291182 -281.126755)
		(end 332.00975 -281.051)
		(width 0.09525)
		(layer "In2.Cu")
		(net "M_C_CPU0_SB_DQS_DN<1>")
	)
	(arc
		(start 336.709766 -281.051)
		(mid 336.525991 -281.000228)
		(end 336.340958 -281.046174)
		(width 0.09525)
		(layer "In2.Cu")
		(net "M_C_CPU0_SB_DQS_DN<1>")
	)
	(arc
		(start 334.821276 -281.046174)
		(mid 334.636244 -281.00026)
		(end 334.452468 -281.051)
		(width 0.09525)
		(layer "In2.Cu")
		(net "M_C_CPU0_SB_DQS_DN<1>")
	)
	(arc
		(start 335.392522 -281.051)
		(mid 335.11109 -281.126755)
		(end 334.829658 -281.051)
		(width 0.09525)
		(layer "In2.Cu")
		(net "M_C_CPU0_SB_DQS_DN<1>")
	)
	(arc
		(start 330.12126 -281.046174)
		(mid 329.936228 -281.00026)
		(end 329.752452 -281.051)
		(width 0.09525)
		(layer "In2.Cu")
		(net "M_C_CPU0_SB_DQS_DN<1>")
	)
	(arc
		(start 341.409782 -281.051)
		(mid 341.226007 -281.000228)
		(end 341.040974 -281.046174)
		(width 0.09525)
		(layer "In2.Cu")
		(net "M_C_CPU0_SB_DQS_DN<1>")
	)
	(arc
		(start 338.21243 -281.051)
		(mid 337.930998 -281.126755)
		(end 337.649566 -281.051)
		(width 0.09525)
		(layer "In2.Cu")
		(net "M_C_CPU0_SB_DQS_DN<1>")
	)
	(arc
		(start 335.769712 -281.051)
		(mid 335.585937 -281.000228)
		(end 335.400904 -281.046174)
		(width 0.09525)
		(layer "In2.Cu")
		(net "M_C_CPU0_SB_DQS_DN<1>")
	)
	(arc
		(start 341.032592 -281.051)
		(mid 340.75116 -281.126755)
		(end 340.469728 -281.051)
		(width 0.09525)
		(layer "In2.Cu")
		(net "M_C_CPU0_SB_DQS_DN<1>")
	)
	(arc
		(start 330.692506 -281.051)
		(mid 330.411074 -281.126755)
		(end 330.129642 -281.051)
		(width 0.09525)
		(layer "In2.Cu")
		(net "M_C_CPU0_SB_DQS_DN<1>")
	)
	(arc
		(start 331.63256 -281.051)
		(mid 331.351128 -281.126755)
		(end 331.069696 -281.051)
		(width 0.09525)
		(layer "In2.Cu")
		(net "M_C_CPU0_SB_DQS_DN<1>")
	)
	(arc
		(start 334.452468 -281.051)
		(mid 334.171036 -281.126755)
		(end 333.889604 -281.051)
		(width 0.09525)
		(layer "In2.Cu")
		(net "M_C_CPU0_SB_DQS_DN<1>")
	)
	(arc
		(start 333.881222 -281.046174)
		(mid 333.69619 -281.00026)
		(end 333.512414 -281.051)
		(width 0.09525)
		(layer "In2.Cu")
		(net "M_C_CPU0_SB_DQS_DN<1>")
	)
	(arc
		(start 337.27263 -281.051)
		(mid 336.991198 -281.126755)
		(end 336.709766 -281.051)
		(width 0.09525)
		(layer "In2.Cu")
		(net "M_C_CPU0_SB_DQS_DN<1>")
	)
	(arc
		(start 329.752452 -281.051)
		(mid 329.47102 -281.126755)
		(end 329.189588 -281.051)
		(width 0.09525)
		(layer "In2.Cu")
		(net "M_C_CPU0_SB_DQS_DN<1>")
	)
	(arc
		(start 339.152484 -281.051)
		(mid 338.871052 -281.126755)
		(end 338.58962 -281.051)
		(width 0.09525)
		(layer "In2.Cu")
		(net "M_C_CPU0_SB_DQS_DN<1>")
	)
	(arc
		(start 332.00975 -281.051)
		(mid 331.825975 -281.000228)
		(end 331.640942 -281.046174)
		(width 0.09525)
		(layer "In2.Cu")
		(net "M_C_CPU0_SB_DQS_DN<1>")
	)
	(arc
		(start 341.972646 -281.051)
		(mid 341.691214 -281.126755)
		(end 341.409782 -281.051)
		(width 0.09525)
		(layer "In2.Cu")
		(net "M_C_CPU0_SB_DQS_DN<1>")
	)
	(arc
		(start 329.189588 -281.051)
		(mid 329.00112 -281.000323)
		(end 328.812652 -281.051)
		(width 0.09525)
		(layer "In2.Cu")
		(net "M_C_CPU0_SB_DQS_DN<1>")
	)
	(arc
		(start 328.812652 -281.051)
		(mid 328.53122 -281.126755)
		(end 328.249788 -281.051)
		(width 0.09525)
		(layer "In2.Cu")
		(net "M_C_CPU0_SB_DQS_DN<1>")
	)
	(arc
		(start 342.291924 -281.024076)
		(mid 342.129273 -281.001816)
		(end 341.972646 -281.051)
		(width 0.09525)
		(layer "In2.Cu")
		(net "M_C_CPU0_SB_DQS_DN<1>")
	)
	(arc
		(start 331.069696 -281.051)
		(mid 330.885921 -281.000228)
		(end 330.700888 -281.046174)
		(width 0.09525)
		(layer "In2.Cu")
		(net "M_C_CPU0_SB_DQS_DN<1>")
	)
	(arc
		(start 337.649566 -281.051)
		(mid 337.461098 -281.000323)
		(end 337.27263 -281.051)
		(width 0.09525)
		(layer "In2.Cu")
		(net "M_C_CPU0_SB_DQS_DN<1>")
	)
	(arc
		(start 328.249788 -281.051)
		(mid 328.075156 -281.00046)
		(end 327.897236 -281.037792)
		(width 0.09525)
		(layer "In2.Cu")
		(net "M_C_CPU0_SB_DQS_DN<1>")
	)
	(arc
		(start 339.521292 -281.046174)
		(mid 339.33626 -281.00026)
		(end 339.152484 -281.051)
		(width 0.09525)
		(layer "In2.Cu")
		(net "M_C_CPU0_SB_DQS_DN<1>")
	)
	(arc
		(start 333.512414 -281.051)
		(mid 333.230982 -281.126755)
		(end 332.94955 -281.051)
		(width 0.09525)
		(layer "In2.Cu")
		(net "M_C_CPU0_SB_DQS_DN<1>")
	)
	(arc
		(start 340.469728 -281.051)
		(mid 340.285953 -281.000228)
		(end 340.10092 -281.046174)
		(width 0.09525)
		(layer "In2.Cu")
		(net "M_C_CPU0_SB_DQS_DN<1>")
	)
	(arc
		(start 340.092538 -281.051)
		(mid 339.811106 -281.126755)
		(end 339.529674 -281.051)
		(width 0.09525)
		(layer "In2.Cu")
		(net "M_C_CPU0_SB_DQS_DN<1>")
	)
	(arc
		(start 327.873868 -281.051254)
		(mid 327.738948 -281.106967)
		(end 327.594214 -281.12593)
		(width 0.09525)
		(layer "In2.Cu")
		(net "M_C_CPU0_SB_DQS_DN<1>")
	)
	(arc
		(start 338.581238 -281.046174)
		(mid 338.396206 -281.00026)
		(end 338.21243 -281.051)
		(width 0.09525)
		(layer "In2.Cu")
		(net "M_C_CPU0_SB_DQS_DN<1>")
	)
	(arc
		(start 332.94955 -281.051)
		(mid 332.761082 -281.000323)
		(end 332.572614 -281.051)
		(width 0.09525)
		(layer "In2.Cu")
		(net "M_C_CPU0_SB_DQS_DN<1>")
	)
	(arc
		(start 336.332576 -281.051)
		(mid 336.051144 -281.126755)
		(end 335.769712 -281.051)
		(width 0.09525)
		(layer "In2.Cu")
		(net "M_C_CPU0_SB_DQS_DN<1>")
	)
	(segment
		(start 342.627966 -276.250146)
		(end 342.161114 -276.516084)
		(width 0.12954)
		(layer "F.Cu")
		(net "M_C_CPU0_SB_DQS_DN<0>")
	)
	(segment
		(start 292.553898 -285.461202)
		(end 292.280086 -285.735014)
		(width 0.16002)
		(layer "In2.Cu")
		(net "M_C_CPU0_SB_DQS_DN<0>")
	)
	(segment
		(start 296.493438 -285.312104)
		(end 293.716202 -285.312104)
		(width 0.16002)
		(layer "In2.Cu")
		(net "M_C_CPU0_SB_DQS_DN<0>")
	)
	(segment
		(start 310.010556 -283.09062)
		(end 309.814722 -283.286454)
		(width 0.16002)
		(layer "In2.Cu")
		(net "M_C_CPU0_SB_DQS_DN<0>")
	)
	(segment
		(start 310.28767 -283.09062)
		(end 310.010556 -283.09062)
		(width 0.16002)
		(layer "In2.Cu")
		(net "M_C_CPU0_SB_DQS_DN<0>")
	)
	(segment
		(start 298.749466 -284.773624)
		(end 298.362878 -284.773624)
		(width 0.16002)
		(layer "In2.Cu")
		(net "M_C_CPU0_SB_DQS_DN<0>")
	)
	(segment
		(start 310.19877 -283.947362)
		(end 310.19877 -284.21076)
		(width 0.16002)
		(layer "In2.Cu")
		(net "M_C_CPU0_SB_DQS_DN<0>")
	)
	(segment
		(start 340.10092 -276.186138)
		(end 340.092538 -276.190964)
		(width 0.09525)
		(layer "In2.Cu")
		(net "M_C_CPU0_SB_DQS_DN<0>")
	)
	(segment
		(start 299.06087 -284.46222)
		(end 298.749466 -284.773624)
		(width 0.16002)
		(layer "In2.Cu")
		(net "M_C_CPU0_SB_DQS_DN<0>")
	)
	(segment
		(start 310.671464 -283.474414)
		(end 310.28767 -283.09062)
		(width 0.16002)
		(layer "In2.Cu")
		(net "M_C_CPU0_SB_DQS_DN<0>")
	)
	(segment
		(start 309.814722 -283.286454)
		(end 309.814722 -283.563314)
		(width 0.16002)
		(layer "In2.Cu")
		(net "M_C_CPU0_SB_DQS_DN<0>")
	)
	(segment
		(start 309.814722 -283.563314)
		(end 310.19877 -283.947362)
		(width 0.16002)
		(layer "In2.Cu")
		(net "M_C_CPU0_SB_DQS_DN<0>")
	)
	(segment
		(start 304.379122 -285.644844)
		(end 304.089562 -285.355284)
		(width 0.16002)
		(layer "In2.Cu")
		(net "M_C_CPU0_SB_DQS_DN<0>")
	)
	(segment
		(start 336.340958 -276.186138)
		(end 336.332576 -276.190964)
		(width 0.09525)
		(layer "In2.Cu")
		(net "M_C_CPU0_SB_DQS_DN<0>")
	)
	(segment
		(start 302.017938 -285.703772)
		(end 301.494698 -285.703772)
		(width 0.16002)
		(layer "In2.Cu")
		(net "M_C_CPU0_SB_DQS_DN<0>")
	)
	(segment
		(start 312.599832 -281.771852)
		(end 312.119772 -281.771852)
		(width 0.16002)
		(layer "In2.Cu")
		(net "M_C_CPU0_SB_DQS_DN<0>")
	)
	(segment
		(start 301.108618 -285.317692)
		(end 301.108618 -284.623764)
		(width 0.16002)
		(layer "In2.Cu")
		(net "M_C_CPU0_SB_DQS_DN<0>")
	)
	(segment
		(start 315.321188 -279.40127)
		(end 314.809886 -279.912572)
		(width 0.16002)
		(layer "In2.Cu")
		(net "M_C_CPU0_SB_DQS_DN<0>")
	)
	(segment
		(start 323.978524 -275.400262)
		(end 323.919596 -275.45919)
		(width 0.09525)
		(layer "In2.Cu")
		(net "M_C_CPU0_SB_DQS_DN<0>")
	)
	(segment
		(start 293.567104 -285.461202)
		(end 292.553898 -285.461202)
		(width 0.16002)
		(layer "In2.Cu")
		(net "M_C_CPU0_SB_DQS_DN<0>")
	)
	(segment
		(start 318.930782 -275.791676)
		(end 318.405764 -275.791676)
		(width 0.16002)
		(layer "In2.Cu")
		(net "M_C_CPU0_SB_DQS_DN<0>")
	)
	(segment
		(start 317.55715 -277.165308)
		(end 317.032132 -277.165308)
		(width 0.16002)
		(layer "In2.Cu")
		(net "M_C_CPU0_SB_DQS_DN<0>")
	)
	(segment
		(start 326.265794 -276.265386)
		(end 325.242174 -275.84146)
		(width 0.09525)
		(layer "In2.Cu")
		(net "M_C_CPU0_SB_DQS_DN<0>")
	)
	(segment
		(start 327.336404 -276.209506)
		(end 327.304654 -276.190964)
		(width 0.09525)
		(layer "In2.Cu")
		(net "M_C_CPU0_SB_DQS_DN<0>")
	)
	(segment
		(start 311.198768 -283.474414)
		(end 310.671464 -283.474414)
		(width 0.16002)
		(layer "In2.Cu")
		(net "M_C_CPU0_SB_DQS_DN<0>")
	)
	(segment
		(start 330.129642 -276.190964)
		(end 330.12126 -276.186138)
		(width 0.09525)
		(layer "In2.Cu")
		(net "M_C_CPU0_SB_DQS_DN<0>")
	)
	(segment
		(start 341.040974 -276.186138)
		(end 341.032592 -276.190964)
		(width 0.09525)
		(layer "In2.Cu")
		(net "M_C_CPU0_SB_DQS_DN<0>")
	)
	(segment
		(start 314.284868 -279.912572)
		(end 313.947556 -280.249884)
		(width 0.16002)
		(layer "In2.Cu")
		(net "M_C_CPU0_SB_DQS_DN<0>")
	)
	(segment
		(start 308.668928 -284.496764)
		(end 306.554378 -284.496764)
		(width 0.16002)
		(layer "In2.Cu")
		(net "M_C_CPU0_SB_DQS_DN<0>")
	)
	(segment
		(start 325.242174 -275.84146)
		(end 324.721728 -275.84146)
		(width 0.09525)
		(layer "In2.Cu")
		(net "M_C_CPU0_SB_DQS_DN<0>")
	)
	(segment
		(start 316.69482 -278.027638)
		(end 316.183518 -278.53894)
		(width 0.16002)
		(layer "In2.Cu")
		(net "M_C_CPU0_SB_DQS_DN<0>")
	)
	(segment
		(start 306.554378 -284.496764)
		(end 306.203858 -284.847284)
		(width 0.16002)
		(layer "In2.Cu")
		(net "M_C_CPU0_SB_DQS_DN<0>")
	)
	(segment
		(start 310.19877 -284.21076)
		(end 310.199024 -284.474158)
		(width 0.16002)
		(layer "In2.Cu")
		(net "M_C_CPU0_SB_DQS_DN<0>")
	)
	(segment
		(start 326.957182 -276.17547)
		(end 326.943466 -276.18309)
		(width 0.09525)
		(layer "In2.Cu")
		(net "M_C_CPU0_SB_DQS_DN<0>")
	)
	(segment
		(start 311.220612 -281.957272)
		(end 311.220612 -282.22194)
		(width 0.16002)
		(layer "In2.Cu")
		(net "M_C_CPU0_SB_DQS_DN<0>")
	)
	(segment
		(start 304.928778 -285.644844)
		(end 304.379122 -285.644844)
		(width 0.16002)
		(layer "In2.Cu")
		(net "M_C_CPU0_SB_DQS_DN<0>")
	)
	(segment
		(start 309.297832 -284.8483)
		(end 308.946042 -284.49651)
		(width 0.16002)
		(layer "In2.Cu")
		(net "M_C_CPU0_SB_DQS_DN<0>")
	)
	(segment
		(start 298.362878 -284.773624)
		(end 297.509438 -285.627064)
		(width 0.16002)
		(layer "In2.Cu")
		(net "M_C_CPU0_SB_DQS_DN<0>")
	)
	(segment
		(start 323.919596 -275.45919)
		(end 323.895974 -275.45919)
		(width 0.09525)
		(layer "In2.Cu")
		(net "M_C_CPU0_SB_DQS_DN<0>")
	)
	(segment
		(start 312.716672 -281.655012)
		(end 312.599832 -281.771852)
		(width 0.16002)
		(layer "In2.Cu")
		(net "M_C_CPU0_SB_DQS_DN<0>")
	)
	(segment
		(start 326.942958 -276.182836)
		(end 326.929242 -276.19071)
		(width 0.09525)
		(layer "In2.Cu")
		(net "M_C_CPU0_SB_DQS_DN<0>")
	)
	(segment
		(start 331.640942 -276.186138)
		(end 331.63256 -276.190964)
		(width 0.09525)
		(layer "In2.Cu")
		(net "M_C_CPU0_SB_DQS_DN<0>")
	)
	(segment
		(start 312.119772 -281.771852)
		(end 312.002932 -281.655012)
		(width 0.16002)
		(layer "In2.Cu")
		(net "M_C_CPU0_SB_DQS_DN<0>")
	)
	(segment
		(start 342.161114 -276.516084)
		(end 342.315038 -276.250654)
		(width 0.09525)
		(layer "In2.Cu")
		(net "M_C_CPU0_SB_DQS_DN<0>")
	)
	(segment
		(start 302.366426 -285.355284)
		(end 302.017938 -285.703772)
		(width 0.16002)
		(layer "In2.Cu")
		(net "M_C_CPU0_SB_DQS_DN<0>")
	)
	(segment
		(start 311.220612 -282.22194)
		(end 311.572402 -282.57373)
		(width 0.16002)
		(layer "In2.Cu")
		(net "M_C_CPU0_SB_DQS_DN<0>")
	)
	(segment
		(start 334.829658 -276.190964)
		(end 334.821276 -276.186138)
		(width 0.09525)
		(layer "In2.Cu")
		(net "M_C_CPU0_SB_DQS_DN<0>")
	)
	(segment
		(start 335.400904 -276.186138)
		(end 335.392522 -276.190964)
		(width 0.09525)
		(layer "In2.Cu")
		(net "M_C_CPU0_SB_DQS_DN<0>")
	)
	(segment
		(start 339.529674 -276.190964)
		(end 339.521292 -276.186138)
		(width 0.09525)
		(layer "In2.Cu")
		(net "M_C_CPU0_SB_DQS_DN<0>")
	)
	(segment
		(start 319.263268 -275.45919)
		(end 318.930782 -275.791676)
		(width 0.16002)
		(layer "In2.Cu")
		(net "M_C_CPU0_SB_DQS_DN<0>")
	)
	(segment
		(start 315.321188 -278.876252)
		(end 315.321188 -279.40127)
		(width 0.16002)
		(layer "In2.Cu")
		(net "M_C_CPU0_SB_DQS_DN<0>")
	)
	(segment
		(start 313.947556 -280.249884)
		(end 313.947556 -280.771854)
		(width 0.16002)
		(layer "In2.Cu")
		(net "M_C_CPU0_SB_DQS_DN<0>")
	)
	(segment
		(start 318.068452 -276.654006)
		(end 317.55715 -277.165308)
		(width 0.16002)
		(layer "In2.Cu")
		(net "M_C_CPU0_SB_DQS_DN<0>")
	)
	(segment
		(start 312.002932 -281.655012)
		(end 311.522872 -281.655012)
		(width 0.16002)
		(layer "In2.Cu")
		(net "M_C_CPU0_SB_DQS_DN<0>")
	)
	(segment
		(start 338.58962 -276.190964)
		(end 338.581238 -276.186138)
		(width 0.09525)
		(layer "In2.Cu")
		(net "M_C_CPU0_SB_DQS_DN<0>")
	)
	(segment
		(start 324.28053 -275.400262)
		(end 323.978524 -275.400262)
		(width 0.09525)
		(layer "In2.Cu")
		(net "M_C_CPU0_SB_DQS_DN<0>")
	)
	(segment
		(start 311.572402 -283.10078)
		(end 311.198768 -283.474414)
		(width 0.16002)
		(layer "In2.Cu")
		(net "M_C_CPU0_SB_DQS_DN<0>")
	)
	(segment
		(start 310.199024 -284.474158)
		(end 309.825136 -284.848046)
		(width 0.16002)
		(layer "In2.Cu")
		(net "M_C_CPU0_SB_DQS_DN<0>")
	)
	(segment
		(start 297.509438 -285.627064)
		(end 296.808398 -285.627064)
		(width 0.16002)
		(layer "In2.Cu")
		(net "M_C_CPU0_SB_DQS_DN<0>")
	)
	(segment
		(start 301.494698 -285.703772)
		(end 301.108618 -285.317692)
		(width 0.16002)
		(layer "In2.Cu")
		(net "M_C_CPU0_SB_DQS_DN<0>")
	)
	(segment
		(start 330.700888 -276.186138)
		(end 330.692506 -276.190964)
		(width 0.09525)
		(layer "In2.Cu")
		(net "M_C_CPU0_SB_DQS_DN<0>")
	)
	(segment
		(start 324.721728 -275.84146)
		(end 324.28053 -275.400262)
		(width 0.09525)
		(layer "In2.Cu")
		(net "M_C_CPU0_SB_DQS_DN<0>")
	)
	(segment
		(start 318.068452 -276.128988)
		(end 318.068452 -276.654006)
		(width 0.16002)
		(layer "In2.Cu")
		(net "M_C_CPU0_SB_DQS_DN<0>")
	)
	(segment
		(start 326.651366 -276.265386)
		(end 326.265794 -276.265386)
		(width 0.09525)
		(layer "In2.Cu")
		(net "M_C_CPU0_SB_DQS_DN<0>")
	)
	(segment
		(start 306.203858 -284.847284)
		(end 305.726338 -284.847284)
		(width 0.16002)
		(layer "In2.Cu")
		(net "M_C_CPU0_SB_DQS_DN<0>")
	)
	(segment
		(start 313.947556 -280.771854)
		(end 313.064398 -281.655012)
		(width 0.16002)
		(layer "In2.Cu")
		(net "M_C_CPU0_SB_DQS_DN<0>")
	)
	(segment
		(start 326.943466 -276.18309)
		(end 326.942958 -276.182836)
		(width 0.09525)
		(layer "In2.Cu")
		(net "M_C_CPU0_SB_DQS_DN<0>")
	)
	(segment
		(start 316.183518 -278.53894)
		(end 315.6585 -278.53894)
		(width 0.16002)
		(layer "In2.Cu")
		(net "M_C_CPU0_SB_DQS_DN<0>")
	)
	(segment
		(start 313.064398 -281.655012)
		(end 312.716672 -281.655012)
		(width 0.16002)
		(layer "In2.Cu")
		(net "M_C_CPU0_SB_DQS_DN<0>")
	)
	(segment
		(start 315.6585 -278.53894)
		(end 315.321188 -278.876252)
		(width 0.16002)
		(layer "In2.Cu")
		(net "M_C_CPU0_SB_DQS_DN<0>")
	)
	(segment
		(start 317.032132 -277.165308)
		(end 316.69482 -277.50262)
		(width 0.16002)
		(layer "In2.Cu")
		(net "M_C_CPU0_SB_DQS_DN<0>")
	)
	(segment
		(start 318.405764 -275.791676)
		(end 318.068452 -276.128988)
		(width 0.16002)
		(layer "In2.Cu")
		(net "M_C_CPU0_SB_DQS_DN<0>")
	)
	(segment
		(start 296.808398 -285.627064)
		(end 296.493438 -285.312104)
		(width 0.16002)
		(layer "In2.Cu")
		(net "M_C_CPU0_SB_DQS_DN<0>")
	)
	(segment
		(start 301.108618 -284.623764)
		(end 300.947074 -284.46222)
		(width 0.16002)
		(layer "In2.Cu")
		(net "M_C_CPU0_SB_DQS_DN<0>")
	)
	(segment
		(start 309.825136 -284.848046)
		(end 309.297832 -284.8483)
		(width 0.16002)
		(layer "In2.Cu")
		(net "M_C_CPU0_SB_DQS_DN<0>")
	)
	(segment
		(start 311.522872 -281.655012)
		(end 311.220612 -281.957272)
		(width 0.16002)
		(layer "In2.Cu")
		(net "M_C_CPU0_SB_DQS_DN<0>")
	)
	(segment
		(start 300.947074 -284.46222)
		(end 299.06087 -284.46222)
		(width 0.16002)
		(layer "In2.Cu")
		(net "M_C_CPU0_SB_DQS_DN<0>")
	)
	(segment
		(start 333.889604 -276.190964)
		(end 333.881222 -276.186138)
		(width 0.09525)
		(layer "In2.Cu")
		(net "M_C_CPU0_SB_DQS_DN<0>")
	)
	(segment
		(start 342.315038 -276.250654)
		(end 342.291924 -276.16404)
		(width 0.09525)
		(layer "In2.Cu")
		(net "M_C_CPU0_SB_DQS_DN<0>")
	)
	(segment
		(start 314.809886 -279.912572)
		(end 314.284868 -279.912572)
		(width 0.16002)
		(layer "In2.Cu")
		(net "M_C_CPU0_SB_DQS_DN<0>")
	)
	(segment
		(start 311.572402 -282.57373)
		(end 311.572402 -283.10078)
		(width 0.16002)
		(layer "In2.Cu")
		(net "M_C_CPU0_SB_DQS_DN<0>")
	)
	(segment
		(start 316.69482 -277.50262)
		(end 316.69482 -278.027638)
		(width 0.16002)
		(layer "In2.Cu")
		(net "M_C_CPU0_SB_DQS_DN<0>")
	)
	(segment
		(start 308.946042 -284.49651)
		(end 308.668928 -284.496764)
		(width 0.16002)
		(layer "In2.Cu")
		(net "M_C_CPU0_SB_DQS_DN<0>")
	)
	(segment
		(start 323.895974 -275.45919)
		(end 319.263268 -275.45919)
		(width 0.16002)
		(layer "In2.Cu")
		(net "M_C_CPU0_SB_DQS_DN<0>")
	)
	(segment
		(start 328.249788 -276.190964)
		(end 328.223372 -276.175724)
		(width 0.09525)
		(layer "In2.Cu")
		(net "M_C_CPU0_SB_DQS_DN<0>")
	)
	(segment
		(start 293.716202 -285.312104)
		(end 293.567104 -285.461202)
		(width 0.16002)
		(layer "In2.Cu")
		(net "M_C_CPU0_SB_DQS_DN<0>")
	)
	(segment
		(start 305.726338 -284.847284)
		(end 304.928778 -285.644844)
		(width 0.16002)
		(layer "In2.Cu")
		(net "M_C_CPU0_SB_DQS_DN<0>")
	)
	(segment
		(start 304.089562 -285.355284)
		(end 302.366426 -285.355284)
		(width 0.16002)
		(layer "In2.Cu")
		(net "M_C_CPU0_SB_DQS_DN<0>")
	)
	(arc
		(start 334.452468 -276.190964)
		(mid 334.171036 -276.266719)
		(end 333.889604 -276.190964)
		(width 0.09525)
		(layer "In2.Cu")
		(net "M_C_CPU0_SB_DQS_DN<0>")
	)
	(arc
		(start 334.821276 -276.186138)
		(mid 334.636244 -276.140224)
		(end 334.452468 -276.190964)
		(width 0.09525)
		(layer "In2.Cu")
		(net "M_C_CPU0_SB_DQS_DN<0>")
	)
	(arc
		(start 331.63256 -276.190964)
		(mid 331.351128 -276.266719)
		(end 331.069696 -276.190964)
		(width 0.09525)
		(layer "In2.Cu")
		(net "M_C_CPU0_SB_DQS_DN<0>")
	)
	(arc
		(start 327.304654 -276.190964)
		(mid 327.132828 -276.140656)
		(end 326.957182 -276.17547)
		(width 0.09525)
		(layer "In2.Cu")
		(net "M_C_CPU0_SB_DQS_DN<0>")
	)
	(arc
		(start 340.092538 -276.190964)
		(mid 339.811106 -276.266719)
		(end 339.529674 -276.190964)
		(width 0.09525)
		(layer "In2.Cu")
		(net "M_C_CPU0_SB_DQS_DN<0>")
	)
	(arc
		(start 328.812652 -276.190964)
		(mid 328.53122 -276.266719)
		(end 328.249788 -276.190964)
		(width 0.09525)
		(layer "In2.Cu")
		(net "M_C_CPU0_SB_DQS_DN<0>")
	)
	(arc
		(start 332.00975 -276.190964)
		(mid 331.825975 -276.140192)
		(end 331.640942 -276.186138)
		(width 0.09525)
		(layer "In2.Cu")
		(net "M_C_CPU0_SB_DQS_DN<0>")
	)
	(arc
		(start 342.291924 -276.16404)
		(mid 342.129273 -276.14178)
		(end 341.972646 -276.190964)
		(width 0.09525)
		(layer "In2.Cu")
		(net "M_C_CPU0_SB_DQS_DN<0>")
	)
	(arc
		(start 339.521292 -276.186138)
		(mid 339.33626 -276.140224)
		(end 339.152484 -276.190964)
		(width 0.09525)
		(layer "In2.Cu")
		(net "M_C_CPU0_SB_DQS_DN<0>")
	)
	(arc
		(start 332.94955 -276.190964)
		(mid 332.761082 -276.140287)
		(end 332.572614 -276.190964)
		(width 0.09525)
		(layer "In2.Cu")
		(net "M_C_CPU0_SB_DQS_DN<0>")
	)
	(arc
		(start 336.332576 -276.190964)
		(mid 336.051144 -276.266719)
		(end 335.769712 -276.190964)
		(width 0.09525)
		(layer "In2.Cu")
		(net "M_C_CPU0_SB_DQS_DN<0>")
	)
	(arc
		(start 333.512414 -276.190964)
		(mid 333.230982 -276.266719)
		(end 332.94955 -276.190964)
		(width 0.09525)
		(layer "In2.Cu")
		(net "M_C_CPU0_SB_DQS_DN<0>")
	)
	(arc
		(start 335.769712 -276.190964)
		(mid 335.585937 -276.140192)
		(end 335.400904 -276.186138)
		(width 0.09525)
		(layer "In2.Cu")
		(net "M_C_CPU0_SB_DQS_DN<0>")
	)
	(arc
		(start 337.27263 -276.190964)
		(mid 336.991198 -276.266719)
		(end 336.709766 -276.190964)
		(width 0.09525)
		(layer "In2.Cu")
		(net "M_C_CPU0_SB_DQS_DN<0>")
	)
	(arc
		(start 341.409782 -276.190964)
		(mid 341.226007 -276.140192)
		(end 341.040974 -276.186138)
		(width 0.09525)
		(layer "In2.Cu")
		(net "M_C_CPU0_SB_DQS_DN<0>")
	)
	(arc
		(start 329.752452 -276.190964)
		(mid 329.47102 -276.266719)
		(end 329.189588 -276.190964)
		(width 0.09525)
		(layer "In2.Cu")
		(net "M_C_CPU0_SB_DQS_DN<0>")
	)
	(arc
		(start 330.692506 -276.190964)
		(mid 330.411074 -276.266719)
		(end 330.129642 -276.190964)
		(width 0.09525)
		(layer "In2.Cu")
		(net "M_C_CPU0_SB_DQS_DN<0>")
	)
	(arc
		(start 340.469728 -276.190964)
		(mid 340.285953 -276.140192)
		(end 340.10092 -276.186138)
		(width 0.09525)
		(layer "In2.Cu")
		(net "M_C_CPU0_SB_DQS_DN<0>")
	)
	(arc
		(start 330.12126 -276.186138)
		(mid 329.936228 -276.140224)
		(end 329.752452 -276.190964)
		(width 0.09525)
		(layer "In2.Cu")
		(net "M_C_CPU0_SB_DQS_DN<0>")
	)
	(arc
		(start 335.392522 -276.190964)
		(mid 335.11109 -276.266719)
		(end 334.829658 -276.190964)
		(width 0.09525)
		(layer "In2.Cu")
		(net "M_C_CPU0_SB_DQS_DN<0>")
	)
	(arc
		(start 341.972646 -276.190964)
		(mid 341.691214 -276.266719)
		(end 341.409782 -276.190964)
		(width 0.09525)
		(layer "In2.Cu")
		(net "M_C_CPU0_SB_DQS_DN<0>")
	)
	(arc
		(start 327.870312 -276.19071)
		(mid 327.605747 -276.267564)
		(end 327.336404 -276.209506)
		(width 0.09525)
		(layer "In2.Cu")
		(net "M_C_CPU0_SB_DQS_DN<0>")
	)
	(arc
		(start 329.189588 -276.190964)
		(mid 329.00112 -276.140287)
		(end 328.812652 -276.190964)
		(width 0.09525)
		(layer "In2.Cu")
		(net "M_C_CPU0_SB_DQS_DN<0>")
	)
	(arc
		(start 337.649566 -276.190964)
		(mid 337.461098 -276.140287)
		(end 337.27263 -276.190964)
		(width 0.09525)
		(layer "In2.Cu")
		(net "M_C_CPU0_SB_DQS_DN<0>")
	)
	(arc
		(start 326.929242 -276.19071)
		(mid 326.795191 -276.246232)
		(end 326.651366 -276.265386)
		(width 0.09525)
		(layer "In2.Cu")
		(net "M_C_CPU0_SB_DQS_DN<0>")
	)
	(arc
		(start 332.572614 -276.190964)
		(mid 332.291182 -276.266719)
		(end 332.00975 -276.190964)
		(width 0.09525)
		(layer "In2.Cu")
		(net "M_C_CPU0_SB_DQS_DN<0>")
	)
	(arc
		(start 338.21243 -276.190964)
		(mid 337.930998 -276.266719)
		(end 337.649566 -276.190964)
		(width 0.09525)
		(layer "In2.Cu")
		(net "M_C_CPU0_SB_DQS_DN<0>")
	)
	(arc
		(start 328.223372 -276.175724)
		(mid 328.044991 -276.139348)
		(end 327.870312 -276.19071)
		(width 0.09525)
		(layer "In2.Cu")
		(net "M_C_CPU0_SB_DQS_DN<0>")
	)
	(arc
		(start 336.709766 -276.190964)
		(mid 336.525991 -276.140192)
		(end 336.340958 -276.186138)
		(width 0.09525)
		(layer "In2.Cu")
		(net "M_C_CPU0_SB_DQS_DN<0>")
	)
	(arc
		(start 338.581238 -276.186138)
		(mid 338.396206 -276.140224)
		(end 338.21243 -276.190964)
		(width 0.09525)
		(layer "In2.Cu")
		(net "M_C_CPU0_SB_DQS_DN<0>")
	)
	(arc
		(start 331.069696 -276.190964)
		(mid 330.885921 -276.140192)
		(end 330.700888 -276.186138)
		(width 0.09525)
		(layer "In2.Cu")
		(net "M_C_CPU0_SB_DQS_DN<0>")
	)
	(arc
		(start 333.881222 -276.186138)
		(mid 333.69619 -276.140224)
		(end 333.512414 -276.190964)
		(width 0.09525)
		(layer "In2.Cu")
		(net "M_C_CPU0_SB_DQS_DN<0>")
	)
	(arc
		(start 339.152484 -276.190964)
		(mid 338.871052 -276.266719)
		(end 338.58962 -276.190964)
		(width 0.09525)
		(layer "In2.Cu")
		(net "M_C_CPU0_SB_DQS_DN<0>")
	)
	(arc
		(start 341.032592 -276.190964)
		(mid 340.75116 -276.266719)
		(end 340.469728 -276.190964)
		(width 0.09525)
		(layer "In2.Cu")
		(net "M_C_CPU0_SB_DQS_DN<0>")
	)
	(segment
		(start 344.508074 -279.49017)
		(end 344.041222 -279.756108)
		(width 0.10668)
		(layer "F.Cu")
		(net "M_C_CPU0_SB_DQ<9>")
	)
	(segment
		(start 307.131466 -292.109906)
		(end 306.75707 -291.73551)
		(width 0.14478)
		(layer "In2.Cu")
		(net "M_C_CPU0_SB_DQ<9>")
	)
	(segment
		(start 308.132226 -291.713412)
		(end 307.90388 -291.713412)
		(width 0.14478)
		(layer "In2.Cu")
		(net "M_C_CPU0_SB_DQ<9>")
	)
	(segment
		(start 316.43066 -284.50921)
		(end 316.192916 -284.50921)
		(width 0.14478)
		(layer "In2.Cu")
		(net "M_C_CPU0_SB_DQ<9>")
	)
	(segment
		(start 300.597316 -291.73551)
		(end 300.366684 -291.73551)
		(width 0.14478)
		(layer "In2.Cu")
		(net "M_C_CPU0_SB_DQ<9>")
	)
	(segment
		(start 297.99661 -292.495986)
		(end 297.532552 -292.960044)
		(width 0.14478)
		(layer "In2.Cu")
		(net "M_C_CPU0_SB_DQ<9>")
	)
	(segment
		(start 294.13962 -293.172896)
		(end 294.13962 -292.736524)
		(width 0.14478)
		(layer "In2.Cu")
		(net "M_C_CPU0_SB_DQ<9>")
	)
	(segment
		(start 324.732142 -279.996138)
		(end 324.489064 -279.75306)
		(width 0.0889)
		(layer "In2.Cu")
		(net "M_C_CPU0_SB_DQ<9>")
	)
	(segment
		(start 305.690778 -292.21811)
		(end 305.428396 -292.21811)
		(width 0.14478)
		(layer "In2.Cu")
		(net "M_C_CPU0_SB_DQ<9>")
	)
	(segment
		(start 338.588096 -280.078688)
		(end 338.579714 -280.083514)
		(width 0.0889)
		(layer "In2.Cu")
		(net "M_C_CPU0_SB_DQ<9>")
	)
	(segment
		(start 294.13962 -292.736524)
		(end 293.976806 -292.57371)
		(width 0.14478)
		(layer "In2.Cu")
		(net "M_C_CPU0_SB_DQ<9>")
	)
	(segment
		(start 295.47566 -292.960044)
		(end 295.089326 -292.57371)
		(width 0.14478)
		(layer "In2.Cu")
		(net "M_C_CPU0_SB_DQ<9>")
	)
	(segment
		(start 327.311766 -280.078688)
		(end 327.289414 -280.091642)
		(width 0.0889)
		(layer "In2.Cu")
		(net "M_C_CPU0_SB_DQ<9>")
	)
	(segment
		(start 307.583332 -292.109906)
		(end 307.131466 -292.109906)
		(width 0.14478)
		(layer "In2.Cu")
		(net "M_C_CPU0_SB_DQ<9>")
	)
	(segment
		(start 321.18681 -279.75306)
		(end 316.43066 -284.50921)
		(width 0.14478)
		(layer "In2.Cu")
		(net "M_C_CPU0_SB_DQ<9>")
	)
	(segment
		(start 330.128118 -280.078688)
		(end 330.119736 -280.083514)
		(width 0.0889)
		(layer "In2.Cu")
		(net "M_C_CPU0_SB_DQ<9>")
	)
	(segment
		(start 297.532552 -292.960044)
		(end 295.47566 -292.960044)
		(width 0.14478)
		(layer "In2.Cu")
		(net "M_C_CPU0_SB_DQ<9>")
	)
	(segment
		(start 300.366684 -291.73551)
		(end 299.992288 -292.109906)
		(width 0.14478)
		(layer "In2.Cu")
		(net "M_C_CPU0_SB_DQ<9>")
	)
	(segment
		(start 293.420546 -293.33571)
		(end 293.189914 -293.33571)
		(width 0.14478)
		(layer "In2.Cu")
		(net "M_C_CPU0_SB_DQ<9>")
	)
	(segment
		(start 304.686462 -292.960044)
		(end 302.084486 -292.960044)
		(width 0.14478)
		(layer "In2.Cu")
		(net "M_C_CPU0_SB_DQ<9>")
	)
	(segment
		(start 336.342482 -280.083514)
		(end 336.3341 -280.078688)
		(width 0.0889)
		(layer "In2.Cu")
		(net "M_C_CPU0_SB_DQ<9>")
	)
	(segment
		(start 294.69588 -293.172896)
		(end 294.533066 -293.33571)
		(width 0.14478)
		(layer "In2.Cu")
		(net "M_C_CPU0_SB_DQ<9>")
	)
	(segment
		(start 327.875646 -280.078434)
		(end 327.849484 -280.063448)
		(width 0.0889)
		(layer "In2.Cu")
		(net "M_C_CPU0_SB_DQ<9>")
	)
	(segment
		(start 306.526438 -291.73551)
		(end 306.363624 -291.898324)
		(width 0.14478)
		(layer "In2.Cu")
		(net "M_C_CPU0_SB_DQ<9>")
	)
	(segment
		(start 293.58336 -292.736524)
		(end 293.58336 -293.172896)
		(width 0.14478)
		(layer "In2.Cu")
		(net "M_C_CPU0_SB_DQ<9>")
	)
	(segment
		(start 330.702412 -280.083514)
		(end 330.69403 -280.078688)
		(width 0.0889)
		(layer "In2.Cu")
		(net "M_C_CPU0_SB_DQ<9>")
	)
	(segment
		(start 301.820326 -292.235636)
		(end 301.72406 -292.13937)
		(width 0.14478)
		(layer "In2.Cu")
		(net "M_C_CPU0_SB_DQ<9>")
	)
	(segment
		(start 299.524166 -292.109906)
		(end 299.17517 -291.76091)
		(width 0.14478)
		(layer "In2.Cu")
		(net "M_C_CPU0_SB_DQ<9>")
	)
	(segment
		(start 300.922944 -292.49751)
		(end 300.76013 -292.334696)
		(width 0.14478)
		(layer "In2.Cu")
		(net "M_C_CPU0_SB_DQ<9>")
	)
	(segment
		(start 293.189914 -293.33571)
		(end 292.814248 -292.960044)
		(width 0.14478)
		(layer "In2.Cu")
		(net "M_C_CPU0_SB_DQ<9>")
	)
	(segment
		(start 339.52815 -280.078688)
		(end 339.519768 -280.083514)
		(width 0.0889)
		(layer "In2.Cu")
		(net "M_C_CPU0_SB_DQ<9>")
	)
	(segment
		(start 294.302434 -293.33571)
		(end 294.13962 -293.172896)
		(width 0.14478)
		(layer "In2.Cu")
		(net "M_C_CPU0_SB_DQ<9>")
	)
	(segment
		(start 335.402428 -280.083514)
		(end 335.394046 -280.078688)
		(width 0.0889)
		(layer "In2.Cu")
		(net "M_C_CPU0_SB_DQ<9>")
	)
	(segment
		(start 306.20081 -292.49751)
		(end 305.970178 -292.49751)
		(width 0.14478)
		(layer "In2.Cu")
		(net "M_C_CPU0_SB_DQ<9>")
	)
	(segment
		(start 299.992288 -292.109906)
		(end 299.524166 -292.109906)
		(width 0.14478)
		(layer "In2.Cu")
		(net "M_C_CPU0_SB_DQ<9>")
	)
	(segment
		(start 300.76013 -291.898324)
		(end 300.597316 -291.73551)
		(width 0.14478)
		(layer "In2.Cu")
		(net "M_C_CPU0_SB_DQ<9>")
	)
	(segment
		(start 295.089326 -292.57371)
		(end 294.858694 -292.57371)
		(width 0.14478)
		(layer "In2.Cu")
		(net "M_C_CPU0_SB_DQ<9>")
	)
	(segment
		(start 306.363624 -291.898324)
		(end 306.363624 -292.334696)
		(width 0.14478)
		(layer "In2.Cu")
		(net "M_C_CPU0_SB_DQ<9>")
	)
	(segment
		(start 294.69588 -292.736524)
		(end 294.69588 -293.172896)
		(width 0.14478)
		(layer "In2.Cu")
		(net "M_C_CPU0_SB_DQ<9>")
	)
	(segment
		(start 301.153576 -292.49751)
		(end 300.922944 -292.49751)
		(width 0.14478)
		(layer "In2.Cu")
		(net "M_C_CPU0_SB_DQ<9>")
	)
	(segment
		(start 298.73321 -291.902388)
		(end 298.73321 -292.337236)
		(width 0.14478)
		(layer "In2.Cu")
		(net "M_C_CPU0_SB_DQ<9>")
	)
	(segment
		(start 340.102444 -280.083514)
		(end 340.094062 -280.078688)
		(width 0.0889)
		(layer "In2.Cu")
		(net "M_C_CPU0_SB_DQ<9>")
	)
	(segment
		(start 308.749954 -291.952172)
		(end 308.370986 -291.952172)
		(width 0.14478)
		(layer "In2.Cu")
		(net "M_C_CPU0_SB_DQ<9>")
	)
	(segment
		(start 300.76013 -292.334696)
		(end 300.76013 -291.898324)
		(width 0.14478)
		(layer "In2.Cu")
		(net "M_C_CPU0_SB_DQ<9>")
	)
	(segment
		(start 301.820326 -292.695884)
		(end 301.820326 -292.235636)
		(width 0.14478)
		(layer "In2.Cu")
		(net "M_C_CPU0_SB_DQ<9>")
	)
	(segment
		(start 298.73321 -292.337236)
		(end 298.57446 -292.495986)
		(width 0.14478)
		(layer "In2.Cu")
		(net "M_C_CPU0_SB_DQ<9>")
	)
	(segment
		(start 305.428396 -292.21811)
		(end 304.686462 -292.960044)
		(width 0.14478)
		(layer "In2.Cu")
		(net "M_C_CPU0_SB_DQ<9>")
	)
	(segment
		(start 293.976806 -292.57371)
		(end 293.746174 -292.57371)
		(width 0.14478)
		(layer "In2.Cu")
		(net "M_C_CPU0_SB_DQ<9>")
	)
	(segment
		(start 294.858694 -292.57371)
		(end 294.69588 -292.736524)
		(width 0.14478)
		(layer "In2.Cu")
		(net "M_C_CPU0_SB_DQ<9>")
	)
	(segment
		(start 299.17517 -291.76091)
		(end 298.874688 -291.76091)
		(width 0.14478)
		(layer "In2.Cu")
		(net "M_C_CPU0_SB_DQ<9>")
	)
	(segment
		(start 298.874688 -291.76091)
		(end 298.73321 -291.902388)
		(width 0.14478)
		(layer "In2.Cu")
		(net "M_C_CPU0_SB_DQ<9>")
	)
	(segment
		(start 331.642466 -280.083514)
		(end 331.634084 -280.078688)
		(width 0.0889)
		(layer "In2.Cu")
		(net "M_C_CPU0_SB_DQ<9>")
	)
	(segment
		(start 308.370986 -291.952172)
		(end 308.132226 -291.713412)
		(width 0.14478)
		(layer "In2.Cu")
		(net "M_C_CPU0_SB_DQ<9>")
	)
	(segment
		(start 307.742336 -291.874956)
		(end 307.742336 -291.950902)
		(width 0.14478)
		(layer "In2.Cu")
		(net "M_C_CPU0_SB_DQ<9>")
	)
	(segment
		(start 327.900538 -280.092658)
		(end 327.875646 -280.078434)
		(width 0.0889)
		(layer "In2.Cu")
		(net "M_C_CPU0_SB_DQ<9>")
	)
	(segment
		(start 334.828134 -280.078688)
		(end 334.819752 -280.083514)
		(width 0.0889)
		(layer "In2.Cu")
		(net "M_C_CPU0_SB_DQ<9>")
	)
	(segment
		(start 305.970178 -292.49751)
		(end 305.690778 -292.21811)
		(width 0.14478)
		(layer "In2.Cu")
		(net "M_C_CPU0_SB_DQ<9>")
	)
	(segment
		(start 298.57446 -292.495986)
		(end 297.99661 -292.495986)
		(width 0.14478)
		(layer "In2.Cu")
		(net "M_C_CPU0_SB_DQ<9>")
	)
	(segment
		(start 323.903594 -279.75306)
		(end 321.18681 -279.75306)
		(width 0.14478)
		(layer "In2.Cu")
		(net "M_C_CPU0_SB_DQ<9>")
	)
	(segment
		(start 326.9361 -280.078688)
		(end 326.919082 -280.068782)
		(width 0.0889)
		(layer "In2.Cu")
		(net "M_C_CPU0_SB_DQ<9>")
	)
	(segment
		(start 301.72406 -292.13937)
		(end 301.511716 -292.13937)
		(width 0.14478)
		(layer "In2.Cu")
		(net "M_C_CPU0_SB_DQ<9>")
	)
	(segment
		(start 344.041222 -279.756108)
		(end 343.887044 -280.021538)
		(width 0.0889)
		(layer "In2.Cu")
		(net "M_C_CPU0_SB_DQ<9>")
	)
	(segment
		(start 294.533066 -293.33571)
		(end 294.302434 -293.33571)
		(width 0.14478)
		(layer "In2.Cu")
		(net "M_C_CPU0_SB_DQ<9>")
	)
	(segment
		(start 343.288112 -280.078688)
		(end 343.27973 -280.083514)
		(width 0.0889)
		(layer "In2.Cu")
		(net "M_C_CPU0_SB_DQ<9>")
	)
	(segment
		(start 302.084486 -292.960044)
		(end 301.820326 -292.695884)
		(width 0.14478)
		(layer "In2.Cu")
		(net "M_C_CPU0_SB_DQ<9>")
	)
	(segment
		(start 301.511716 -292.13937)
		(end 301.153576 -292.49751)
		(width 0.14478)
		(layer "In2.Cu")
		(net "M_C_CPU0_SB_DQ<9>")
	)
	(segment
		(start 307.90388 -291.713412)
		(end 307.742336 -291.874956)
		(width 0.14478)
		(layer "In2.Cu")
		(net "M_C_CPU0_SB_DQ<9>")
	)
	(segment
		(start 333.88808 -280.078688)
		(end 333.879698 -280.083514)
		(width 0.0889)
		(layer "In2.Cu")
		(net "M_C_CPU0_SB_DQ<9>")
	)
	(segment
		(start 293.58336 -293.172896)
		(end 293.420546 -293.33571)
		(width 0.14478)
		(layer "In2.Cu")
		(net "M_C_CPU0_SB_DQ<9>")
	)
	(segment
		(start 292.705028 -292.960044)
		(end 292.280086 -292.535102)
		(width 0.14478)
		(layer "In2.Cu")
		(net "M_C_CPU0_SB_DQ<9>")
	)
	(segment
		(start 306.75707 -291.73551)
		(end 306.526438 -291.73551)
		(width 0.14478)
		(layer "In2.Cu")
		(net "M_C_CPU0_SB_DQ<9>")
	)
	(segment
		(start 324.489064 -279.75306)
		(end 323.903594 -279.75306)
		(width 0.0889)
		(layer "In2.Cu")
		(net "M_C_CPU0_SB_DQ<9>")
	)
	(segment
		(start 343.887044 -280.021538)
		(end 343.790778 -280.046938)
		(width 0.0889)
		(layer "In2.Cu")
		(net "M_C_CPU0_SB_DQ<9>")
	)
	(segment
		(start 292.814248 -292.960044)
		(end 292.705028 -292.960044)
		(width 0.14478)
		(layer "In2.Cu")
		(net "M_C_CPU0_SB_DQ<9>")
	)
	(segment
		(start 307.742336 -291.950902)
		(end 307.583332 -292.109906)
		(width 0.14478)
		(layer "In2.Cu")
		(net "M_C_CPU0_SB_DQ<9>")
	)
	(segment
		(start 306.363624 -292.334696)
		(end 306.20081 -292.49751)
		(width 0.14478)
		(layer "In2.Cu")
		(net "M_C_CPU0_SB_DQ<9>")
	)
	(segment
		(start 316.192916 -284.50921)
		(end 308.749954 -291.952172)
		(width 0.14478)
		(layer "In2.Cu")
		(net "M_C_CPU0_SB_DQ<9>")
	)
	(segment
		(start 341.042498 -280.083514)
		(end 341.034116 -280.078688)
		(width 0.0889)
		(layer "In2.Cu")
		(net "M_C_CPU0_SB_DQ<9>")
	)
	(segment
		(start 293.746174 -292.57371)
		(end 293.58336 -292.736524)
		(width 0.14478)
		(layer "In2.Cu")
		(net "M_C_CPU0_SB_DQ<9>")
	)
	(segment
		(start 326.651112 -279.996138)
		(end 324.732142 -279.996138)
		(width 0.0889)
		(layer "In2.Cu")
		(net "M_C_CPU0_SB_DQ<9>")
	)
	(arc
		(start 343.27973 -280.083514)
		(mid 343.096222 -280.129008)
		(end 342.91397 -280.078688)
		(width 0.0889)
		(layer "In2.Cu")
		(net "M_C_CPU0_SB_DQ<9>")
	)
	(arc
		(start 332.574138 -280.078688)
		(mid 332.291182 -280.002511)
		(end 332.008226 -280.078688)
		(width 0.0889)
		(layer "In2.Cu")
		(net "M_C_CPU0_SB_DQ<9>")
	)
	(arc
		(start 327.289414 -280.091642)
		(mid 327.111128 -280.129586)
		(end 326.9361 -280.078688)
		(width 0.0889)
		(layer "In2.Cu")
		(net "M_C_CPU0_SB_DQ<9>")
	)
	(arc
		(start 341.034116 -280.078688)
		(mid 340.75116 -280.002511)
		(end 340.468204 -280.078688)
		(width 0.0889)
		(layer "In2.Cu")
		(net "M_C_CPU0_SB_DQ<9>")
	)
	(arc
		(start 334.819752 -280.083514)
		(mid 334.636244 -280.129008)
		(end 334.453992 -280.078688)
		(width 0.0889)
		(layer "In2.Cu")
		(net "M_C_CPU0_SB_DQ<9>")
	)
	(arc
		(start 338.579714 -280.083514)
		(mid 338.396206 -280.129008)
		(end 338.213954 -280.078688)
		(width 0.0889)
		(layer "In2.Cu")
		(net "M_C_CPU0_SB_DQ<9>")
	)
	(arc
		(start 343.790778 -280.046938)
		(mid 343.535713 -280.003587)
		(end 343.288112 -280.078688)
		(width 0.0889)
		(layer "In2.Cu")
		(net "M_C_CPU0_SB_DQ<9>")
	)
	(arc
		(start 331.634084 -280.078688)
		(mid 331.351128 -280.002511)
		(end 331.068172 -280.078688)
		(width 0.0889)
		(layer "In2.Cu")
		(net "M_C_CPU0_SB_DQ<9>")
	)
	(arc
		(start 326.919082 -280.068782)
		(mid 326.789928 -280.01465)
		(end 326.651112 -279.996138)
		(width 0.0889)
		(layer "In2.Cu")
		(net "M_C_CPU0_SB_DQ<9>")
	)
	(arc
		(start 328.248264 -280.078688)
		(mid 328.076121 -280.128766)
		(end 327.900538 -280.092658)
		(width 0.0889)
		(layer "In2.Cu")
		(net "M_C_CPU0_SB_DQ<9>")
	)
	(arc
		(start 338.213954 -280.078688)
		(mid 337.930998 -280.002511)
		(end 337.648042 -280.078688)
		(width 0.0889)
		(layer "In2.Cu")
		(net "M_C_CPU0_SB_DQ<9>")
	)
	(arc
		(start 339.519768 -280.083514)
		(mid 339.33626 -280.129008)
		(end 339.154008 -280.078688)
		(width 0.0889)
		(layer "In2.Cu")
		(net "M_C_CPU0_SB_DQ<9>")
	)
	(arc
		(start 342.348058 -280.078688)
		(mid 342.161114 -280.128943)
		(end 341.97417 -280.078688)
		(width 0.0889)
		(layer "In2.Cu")
		(net "M_C_CPU0_SB_DQ<9>")
	)
	(arc
		(start 334.453992 -280.078688)
		(mid 334.171036 -280.002511)
		(end 333.88808 -280.078688)
		(width 0.0889)
		(layer "In2.Cu")
		(net "M_C_CPU0_SB_DQ<9>")
	)
	(arc
		(start 327.849484 -280.063448)
		(mid 327.578698 -280.002802)
		(end 327.311766 -280.078688)
		(width 0.0889)
		(layer "In2.Cu")
		(net "M_C_CPU0_SB_DQ<9>")
	)
	(arc
		(start 342.91397 -280.078688)
		(mid 342.631014 -280.002511)
		(end 342.348058 -280.078688)
		(width 0.0889)
		(layer "In2.Cu")
		(net "M_C_CPU0_SB_DQ<9>")
	)
	(arc
		(start 332.948026 -280.078688)
		(mid 332.761082 -280.128943)
		(end 332.574138 -280.078688)
		(width 0.0889)
		(layer "In2.Cu")
		(net "M_C_CPU0_SB_DQ<9>")
	)
	(arc
		(start 340.468204 -280.078688)
		(mid 340.285953 -280.129038)
		(end 340.102444 -280.083514)
		(width 0.0889)
		(layer "In2.Cu")
		(net "M_C_CPU0_SB_DQ<9>")
	)
	(arc
		(start 341.408258 -280.078688)
		(mid 341.226007 -280.129038)
		(end 341.042498 -280.083514)
		(width 0.0889)
		(layer "In2.Cu")
		(net "M_C_CPU0_SB_DQ<9>")
	)
	(arc
		(start 330.69403 -280.078688)
		(mid 330.411074 -280.002511)
		(end 330.128118 -280.078688)
		(width 0.0889)
		(layer "In2.Cu")
		(net "M_C_CPU0_SB_DQ<9>")
	)
	(arc
		(start 336.708242 -280.078688)
		(mid 336.525991 -280.129038)
		(end 336.342482 -280.083514)
		(width 0.0889)
		(layer "In2.Cu")
		(net "M_C_CPU0_SB_DQ<9>")
	)
	(arc
		(start 333.513938 -280.078688)
		(mid 333.230982 -280.002511)
		(end 332.948026 -280.078688)
		(width 0.0889)
		(layer "In2.Cu")
		(net "M_C_CPU0_SB_DQ<9>")
	)
	(arc
		(start 340.094062 -280.078688)
		(mid 339.811106 -280.002511)
		(end 339.52815 -280.078688)
		(width 0.0889)
		(layer "In2.Cu")
		(net "M_C_CPU0_SB_DQ<9>")
	)
	(arc
		(start 339.154008 -280.078688)
		(mid 338.871052 -280.002511)
		(end 338.588096 -280.078688)
		(width 0.0889)
		(layer "In2.Cu")
		(net "M_C_CPU0_SB_DQ<9>")
	)
	(arc
		(start 335.394046 -280.078688)
		(mid 335.11109 -280.002511)
		(end 334.828134 -280.078688)
		(width 0.0889)
		(layer "In2.Cu")
		(net "M_C_CPU0_SB_DQ<9>")
	)
	(arc
		(start 341.97417 -280.078688)
		(mid 341.691214 -280.002511)
		(end 341.408258 -280.078688)
		(width 0.0889)
		(layer "In2.Cu")
		(net "M_C_CPU0_SB_DQ<9>")
	)
	(arc
		(start 328.814176 -280.078688)
		(mid 328.53122 -280.002511)
		(end 328.248264 -280.078688)
		(width 0.0889)
		(layer "In2.Cu")
		(net "M_C_CPU0_SB_DQ<9>")
	)
	(arc
		(start 333.879698 -280.083514)
		(mid 333.69619 -280.129008)
		(end 333.513938 -280.078688)
		(width 0.0889)
		(layer "In2.Cu")
		(net "M_C_CPU0_SB_DQ<9>")
	)
	(arc
		(start 337.648042 -280.078688)
		(mid 337.461098 -280.128943)
		(end 337.274154 -280.078688)
		(width 0.0889)
		(layer "In2.Cu")
		(net "M_C_CPU0_SB_DQ<9>")
	)
	(arc
		(start 331.068172 -280.078688)
		(mid 330.885921 -280.129038)
		(end 330.702412 -280.083514)
		(width 0.0889)
		(layer "In2.Cu")
		(net "M_C_CPU0_SB_DQ<9>")
	)
	(arc
		(start 329.188064 -280.078688)
		(mid 329.00112 -280.128943)
		(end 328.814176 -280.078688)
		(width 0.0889)
		(layer "In2.Cu")
		(net "M_C_CPU0_SB_DQ<9>")
	)
	(arc
		(start 330.119736 -280.083514)
		(mid 329.936228 -280.129008)
		(end 329.753976 -280.078688)
		(width 0.0889)
		(layer "In2.Cu")
		(net "M_C_CPU0_SB_DQ<9>")
	)
	(arc
		(start 337.274154 -280.078688)
		(mid 336.991198 -280.002511)
		(end 336.708242 -280.078688)
		(width 0.0889)
		(layer "In2.Cu")
		(net "M_C_CPU0_SB_DQ<9>")
	)
	(arc
		(start 332.008226 -280.078688)
		(mid 331.825975 -280.129038)
		(end 331.642466 -280.083514)
		(width 0.0889)
		(layer "In2.Cu")
		(net "M_C_CPU0_SB_DQ<9>")
	)
	(arc
		(start 336.3341 -280.078688)
		(mid 336.051144 -280.002511)
		(end 335.768188 -280.078688)
		(width 0.0889)
		(layer "In2.Cu")
		(net "M_C_CPU0_SB_DQ<9>")
	)
	(arc
		(start 335.768188 -280.078688)
		(mid 335.585937 -280.129038)
		(end 335.402428 -280.083514)
		(width 0.0889)
		(layer "In2.Cu")
		(net "M_C_CPU0_SB_DQ<9>")
	)
	(arc
		(start 329.753976 -280.078688)
		(mid 329.47102 -280.002511)
		(end 329.188064 -280.078688)
		(width 0.0889)
		(layer "In2.Cu")
		(net "M_C_CPU0_SB_DQ<9>")
	)
	(segment
		(start 343.097866 -278.680164)
		(end 342.631014 -278.946102)
		(width 0.10668)
		(layer "F.Cu")
		(net "M_C_CPU0_SB_DQ<8>")
	)
	(segment
		(start 305.968654 -290.821364)
		(end 305.740308 -291.04971)
		(width 0.14478)
		(layer "In2.Cu")
		(net "M_C_CPU0_SB_DQ<8>")
	)
	(segment
		(start 301.157132 -291.0078)
		(end 301.157132 -290.777422)
		(width 0.14478)
		(layer "In2.Cu")
		(net "M_C_CPU0_SB_DQ<8>")
	)
	(segment
		(start 297.327828 -291.423344)
		(end 297.327828 -291.883084)
		(width 0.14478)
		(layer "In2.Cu")
		(net "M_C_CPU0_SB_DQ<8>")
	)
	(segment
		(start 302.761904 -290.967414)
		(end 302.531018 -290.967414)
		(width 0.14478)
		(layer "In2.Cu")
		(net "M_C_CPU0_SB_DQ<8>")
	)
	(segment
		(start 297.327828 -291.883084)
		(end 297.16476 -292.046152)
		(width 0.14478)
		(layer "In2.Cu")
		(net "M_C_CPU0_SB_DQ<8>")
	)
	(segment
		(start 306.791614 -290.16071)
		(end 306.19954 -290.16071)
		(width 0.14478)
		(layer "In2.Cu")
		(net "M_C_CPU0_SB_DQ<8>")
	)
	(segment
		(start 319.923668 -279.742392)
		(end 319.687448 -279.742392)
		(width 0.14478)
		(layer "In2.Cu")
		(net "M_C_CPU0_SB_DQ<8>")
	)
	(segment
		(start 294.044878 -291.15258)
		(end 293.882064 -290.989766)
		(width 0.14478)
		(layer "In2.Cu")
		(net "M_C_CPU0_SB_DQ<8>")
	)
	(segment
		(start 317.854838 -281.811222)
		(end 317.582804 -282.083256)
		(width 0.14478)
		(layer "In2.Cu")
		(net "M_C_CPU0_SB_DQ<8>")
	)
	(segment
		(start 333.992474 -279.273508)
		(end 333.984092 -279.268682)
		(width 0.0889)
		(layer "In2.Cu")
		(net "M_C_CPU0_SB_DQ<8>")
	)
	(segment
		(start 301.550578 -291.171122)
		(end 301.320454 -291.171122)
		(width 0.14478)
		(layer "In2.Cu")
		(net "M_C_CPU0_SB_DQ<8>")
	)
	(segment
		(start 305.31054 -291.04971)
		(end 304.791364 -291.568886)
		(width 0.14478)
		(layer "In2.Cu")
		(net "M_C_CPU0_SB_DQ<8>")
	)
	(segment
		(start 304.429414 -291.22243)
		(end 304.205894 -290.99891)
		(width 0.14478)
		(layer "In2.Cu")
		(net "M_C_CPU0_SB_DQ<8>")
	)
	(segment
		(start 299.255688 -290.13531)
		(end 298.831254 -290.13531)
		(width 0.14478)
		(layer "In2.Cu")
		(net "M_C_CPU0_SB_DQ<8>")
	)
	(segment
		(start 302.290988 -291.207444)
		(end 302.089058 -291.207444)
		(width 0.14478)
		(layer "In2.Cu")
		(net "M_C_CPU0_SB_DQ<8>")
	)
	(segment
		(start 318.90716 -280.52268)
		(end 318.635126 -280.794714)
		(width 0.14478)
		(layer "In2.Cu")
		(net "M_C_CPU0_SB_DQ<8>")
	)
	(segment
		(start 326.676258 -279.312878)
		(end 326.651112 -279.312878)
		(width 0.0889)
		(layer "In2.Cu")
		(net "M_C_CPU0_SB_DQ<8>")
	)
	(segment
		(start 317.346584 -282.083256)
		(end 317.07455 -282.35529)
		(width 0.14478)
		(layer "In2.Cu")
		(net "M_C_CPU0_SB_DQ<8>")
	)
	(segment
		(start 317.854838 -281.575002)
		(end 317.854838 -281.811222)
		(width 0.14478)
		(layer "In2.Cu")
		(net "M_C_CPU0_SB_DQ<8>")
	)
	(segment
		(start 303.587912 -291.273484)
		(end 303.067974 -291.273484)
		(width 0.14478)
		(layer "In2.Cu")
		(net "M_C_CPU0_SB_DQ<8>")
	)
	(segment
		(start 294.438324 -291.650166)
		(end 294.207692 -291.650166)
		(width 0.14478)
		(layer "In2.Cu")
		(net "M_C_CPU0_SB_DQ<8>")
	)
	(segment
		(start 297.70578 -291.260276)
		(end 297.490896 -291.260276)
		(width 0.14478)
		(layer "In2.Cu")
		(net "M_C_CPU0_SB_DQ<8>")
	)
	(segment
		(start 319.687448 -279.742392)
		(end 319.415414 -280.014426)
		(width 0.14478)
		(layer "In2.Cu")
		(net "M_C_CPU0_SB_DQ<8>")
	)
	(segment
		(start 305.968654 -290.391596)
		(end 305.968654 -290.821364)
		(width 0.14478)
		(layer "In2.Cu")
		(net "M_C_CPU0_SB_DQ<8>")
	)
	(segment
		(start 327.803764 -279.254458)
		(end 327.779888 -279.268428)
		(width 0.0889)
		(layer "In2.Cu")
		(net "M_C_CPU0_SB_DQ<8>")
	)
	(segment
		(start 329.292458 -279.273508)
		(end 329.284076 -279.268682)
		(width 0.0889)
		(layer "In2.Cu")
		(net "M_C_CPU0_SB_DQ<8>")
	)
	(segment
		(start 333.05242 -279.273508)
		(end 333.044038 -279.268682)
		(width 0.0889)
		(layer "In2.Cu")
		(net "M_C_CPU0_SB_DQ<8>")
	)
	(segment
		(start 296.934382 -292.046152)
		(end 296.771314 -291.883084)
		(width 0.14478)
		(layer "In2.Cu")
		(net "M_C_CPU0_SB_DQ<8>")
	)
	(segment
		(start 301.686722 -291.034978)
		(end 301.550578 -291.171122)
		(width 0.14478)
		(layer "In2.Cu")
		(net "M_C_CPU0_SB_DQ<8>")
	)
	(segment
		(start 306.19954 -290.16071)
		(end 305.968654 -290.391596)
		(width 0.14478)
		(layer "In2.Cu")
		(net "M_C_CPU0_SB_DQ<8>")
	)
	(segment
		(start 293.095172 -291.650166)
		(end 292.280086 -290.83508)
		(width 0.14478)
		(layer "In2.Cu")
		(net "M_C_CPU0_SB_DQ<8>")
	)
	(segment
		(start 342.631014 -278.946102)
		(end 342.47709 -279.211532)
		(width 0.0889)
		(layer "In2.Cu")
		(net "M_C_CPU0_SB_DQ<8>")
	)
	(segment
		(start 301.016924 -290.13531)
		(end 300.64075 -290.13531)
		(width 0.14478)
		(layer "In2.Cu")
		(net "M_C_CPU0_SB_DQ<8>")
	)
	(segment
		(start 293.882064 -290.989766)
		(end 293.651432 -290.989766)
		(width 0.14478)
		(layer "In2.Cu")
		(net "M_C_CPU0_SB_DQ<8>")
	)
	(segment
		(start 307.812186 -290.410138)
		(end 307.041042 -290.410138)
		(width 0.14478)
		(layer "In2.Cu")
		(net "M_C_CPU0_SB_DQ<8>")
	)
	(segment
		(start 341.878158 -279.268682)
		(end 341.869776 -279.273508)
		(width 0.0889)
		(layer "In2.Cu")
		(net "M_C_CPU0_SB_DQ<8>")
	)
	(segment
		(start 301.157132 -290.777422)
		(end 301.293022 -290.641532)
		(width 0.14478)
		(layer "In2.Cu")
		(net "M_C_CPU0_SB_DQ<8>")
	)
	(segment
		(start 295.948354 -291.260276)
		(end 295.435274 -291.260276)
		(width 0.14478)
		(layer "In2.Cu")
		(net "M_C_CPU0_SB_DQ<8>")
	)
	(segment
		(start 332.478126 -279.268682)
		(end 332.469744 -279.273508)
		(width 0.0889)
		(layer "In2.Cu")
		(net "M_C_CPU0_SB_DQ<8>")
	)
	(segment
		(start 317.582804 -282.083256)
		(end 317.346584 -282.083256)
		(width 0.14478)
		(layer "In2.Cu")
		(net "M_C_CPU0_SB_DQ<8>")
	)
	(segment
		(start 298.681394 -290.64585)
		(end 298.531534 -290.79571)
		(width 0.14478)
		(layer "In2.Cu")
		(net "M_C_CPU0_SB_DQ<8>")
	)
	(segment
		(start 294.207692 -291.650166)
		(end 294.044878 -291.487352)
		(width 0.14478)
		(layer "In2.Cu")
		(net "M_C_CPU0_SB_DQ<8>")
	)
	(segment
		(start 296.236898 -290.971732)
		(end 295.948354 -291.260276)
		(width 0.14478)
		(layer "In2.Cu")
		(net "M_C_CPU0_SB_DQ<8>")
	)
	(segment
		(start 301.320454 -291.171122)
		(end 301.157132 -291.0078)
		(width 0.14478)
		(layer "In2.Cu")
		(net "M_C_CPU0_SB_DQ<8>")
	)
	(segment
		(start 293.488618 -291.487352)
		(end 293.325804 -291.650166)
		(width 0.14478)
		(layer "In2.Cu")
		(net "M_C_CPU0_SB_DQ<8>")
	)
	(segment
		(start 316.566296 -282.863544)
		(end 309.29453 -290.13531)
		(width 0.14478)
		(layer "In2.Cu")
		(net "M_C_CPU0_SB_DQ<8>")
	)
	(segment
		(start 298.831254 -290.13531)
		(end 298.681394 -290.28517)
		(width 0.14478)
		(layer "In2.Cu")
		(net "M_C_CPU0_SB_DQ<8>")
	)
	(segment
		(start 301.293022 -290.411408)
		(end 301.016924 -290.13531)
		(width 0.14478)
		(layer "In2.Cu")
		(net "M_C_CPU0_SB_DQ<8>")
	)
	(segment
		(start 297.706034 -291.26053)
		(end 297.70578 -291.260276)
		(width 0.14478)
		(layer "In2.Cu")
		(net "M_C_CPU0_SB_DQ<8>")
	)
	(segment
		(start 340.938104 -279.268682)
		(end 340.929722 -279.273508)
		(width 0.0889)
		(layer "In2.Cu")
		(net "M_C_CPU0_SB_DQ<8>")
	)
	(segment
		(start 300.365922 -290.410138)
		(end 299.530516 -290.410138)
		(width 0.14478)
		(layer "In2.Cu")
		(net "M_C_CPU0_SB_DQ<8>")
	)
	(segment
		(start 304.429414 -291.419026)
		(end 304.429414 -291.22243)
		(width 0.14478)
		(layer "In2.Cu")
		(net "M_C_CPU0_SB_DQ<8>")
	)
	(segment
		(start 293.325804 -291.650166)
		(end 293.095172 -291.650166)
		(width 0.14478)
		(layer "In2.Cu")
		(net "M_C_CPU0_SB_DQ<8>")
	)
	(segment
		(start 320.195702 -279.470358)
		(end 319.923668 -279.742392)
		(width 0.14478)
		(layer "In2.Cu")
		(net "M_C_CPU0_SB_DQ<8>")
	)
	(segment
		(start 316.802516 -282.863544)
		(end 316.566296 -282.863544)
		(width 0.14478)
		(layer "In2.Cu")
		(net "M_C_CPU0_SB_DQ<8>")
	)
	(segment
		(start 337.178142 -279.268682)
		(end 337.16976 -279.273508)
		(width 0.0889)
		(layer "In2.Cu")
		(net "M_C_CPU0_SB_DQ<8>")
	)
	(segment
		(start 299.530516 -290.410138)
		(end 299.255688 -290.13531)
		(width 0.14478)
		(layer "In2.Cu")
		(net "M_C_CPU0_SB_DQ<8>")
	)
	(segment
		(start 331.538072 -279.268682)
		(end 331.52969 -279.273508)
		(width 0.0889)
		(layer "In2.Cu")
		(net "M_C_CPU0_SB_DQ<8>")
	)
	(segment
		(start 318.635126 -280.794714)
		(end 318.635126 -281.030934)
		(width 0.14478)
		(layer "In2.Cu")
		(net "M_C_CPU0_SB_DQ<8>")
	)
	(segment
		(start 294.044878 -291.487352)
		(end 294.044878 -291.15258)
		(width 0.14478)
		(layer "In2.Cu")
		(net "M_C_CPU0_SB_DQ<8>")
	)
	(segment
		(start 303.067974 -291.273484)
		(end 302.761904 -290.967414)
		(width 0.14478)
		(layer "In2.Cu")
		(net "M_C_CPU0_SB_DQ<8>")
	)
	(segment
		(start 336.238088 -279.268682)
		(end 336.229706 -279.273508)
		(width 0.0889)
		(layer "In2.Cu")
		(net "M_C_CPU0_SB_DQ<8>")
	)
	(segment
		(start 318.363092 -281.302968)
		(end 318.126872 -281.302968)
		(width 0.14478)
		(layer "In2.Cu")
		(net "M_C_CPU0_SB_DQ<8>")
	)
	(segment
		(start 294.601138 -291.15258)
		(end 294.601138 -291.487352)
		(width 0.14478)
		(layer "In2.Cu")
		(net "M_C_CPU0_SB_DQ<8>")
	)
	(segment
		(start 317.07455 -282.59151)
		(end 316.802516 -282.863544)
		(width 0.14478)
		(layer "In2.Cu")
		(net "M_C_CPU0_SB_DQ<8>")
	)
	(segment
		(start 296.771314 -291.158168)
		(end 296.584878 -290.971732)
		(width 0.14478)
		(layer "In2.Cu")
		(net "M_C_CPU0_SB_DQ<8>")
	)
	(segment
		(start 293.651432 -290.989766)
		(end 293.488618 -291.15258)
		(width 0.14478)
		(layer "In2.Cu")
		(net "M_C_CPU0_SB_DQ<8>")
	)
	(segment
		(start 307.041042 -290.410138)
		(end 306.791614 -290.16071)
		(width 0.14478)
		(layer "In2.Cu")
		(net "M_C_CPU0_SB_DQ<8>")
	)
	(segment
		(start 297.16476 -292.046152)
		(end 296.934382 -292.046152)
		(width 0.14478)
		(layer "In2.Cu")
		(net "M_C_CPU0_SB_DQ<8>")
	)
	(segment
		(start 308.087014 -290.13531)
		(end 307.812186 -290.410138)
		(width 0.14478)
		(layer "In2.Cu")
		(net "M_C_CPU0_SB_DQ<8>")
	)
	(segment
		(start 319.415414 -280.014426)
		(end 319.415414 -280.250646)
		(width 0.14478)
		(layer "In2.Cu")
		(net "M_C_CPU0_SB_DQ<8>")
	)
	(segment
		(start 298.170854 -290.79571)
		(end 297.706034 -291.26053)
		(width 0.14478)
		(layer "In2.Cu")
		(net "M_C_CPU0_SB_DQ<8>")
	)
	(segment
		(start 294.601138 -291.487352)
		(end 294.438324 -291.650166)
		(width 0.14478)
		(layer "In2.Cu")
		(net "M_C_CPU0_SB_DQ<8>")
	)
	(segment
		(start 319.415414 -280.250646)
		(end 319.14338 -280.52268)
		(width 0.14478)
		(layer "In2.Cu")
		(net "M_C_CPU0_SB_DQ<8>")
	)
	(segment
		(start 318.126872 -281.302968)
		(end 317.854838 -281.575002)
		(width 0.14478)
		(layer "In2.Cu")
		(net "M_C_CPU0_SB_DQ<8>")
	)
	(segment
		(start 337.752436 -279.273508)
		(end 337.744054 -279.268682)
		(width 0.0889)
		(layer "In2.Cu")
		(net "M_C_CPU0_SB_DQ<8>")
	)
	(segment
		(start 293.488618 -291.15258)
		(end 293.488618 -291.487352)
		(width 0.14478)
		(layer "In2.Cu")
		(net "M_C_CPU0_SB_DQ<8>")
	)
	(segment
		(start 328.718164 -279.268682)
		(end 328.709782 -279.273508)
		(width 0.0889)
		(layer "In2.Cu")
		(net "M_C_CPU0_SB_DQ<8>")
	)
	(segment
		(start 317.07455 -282.35529)
		(end 317.07455 -282.59151)
		(width 0.14478)
		(layer "In2.Cu")
		(net "M_C_CPU0_SB_DQ<8>")
	)
	(segment
		(start 296.771314 -291.883084)
		(end 296.771314 -291.158168)
		(width 0.14478)
		(layer "In2.Cu")
		(net "M_C_CPU0_SB_DQ<8>")
	)
	(segment
		(start 323.982334 -278.84374)
		(end 320.5861 -278.84374)
		(width 0.14478)
		(layer "In2.Cu")
		(net "M_C_CPU0_SB_DQ<8>")
	)
	(segment
		(start 294.780208 -290.97351)
		(end 294.601138 -291.15258)
		(width 0.14478)
		(layer "In2.Cu")
		(net "M_C_CPU0_SB_DQ<8>")
	)
	(segment
		(start 303.862486 -290.99891)
		(end 303.587912 -291.273484)
		(width 0.14478)
		(layer "In2.Cu")
		(net "M_C_CPU0_SB_DQ<8>")
	)
	(segment
		(start 301.916592 -291.034978)
		(end 301.686722 -291.034978)
		(width 0.14478)
		(layer "In2.Cu")
		(net "M_C_CPU0_SB_DQ<8>")
	)
	(segment
		(start 302.089058 -291.207444)
		(end 301.916592 -291.034978)
		(width 0.14478)
		(layer "In2.Cu")
		(net "M_C_CPU0_SB_DQ<8>")
	)
	(segment
		(start 304.791364 -291.568886)
		(end 304.579274 -291.568886)
		(width 0.14478)
		(layer "In2.Cu")
		(net "M_C_CPU0_SB_DQ<8>")
	)
	(segment
		(start 309.29453 -290.13531)
		(end 308.087014 -290.13531)
		(width 0.14478)
		(layer "In2.Cu")
		(net "M_C_CPU0_SB_DQ<8>")
	)
	(segment
		(start 304.579274 -291.568886)
		(end 304.429414 -291.419026)
		(width 0.14478)
		(layer "In2.Cu")
		(net "M_C_CPU0_SB_DQ<8>")
	)
	(segment
		(start 302.531018 -290.967414)
		(end 302.290988 -291.207444)
		(width 0.14478)
		(layer "In2.Cu")
		(net "M_C_CPU0_SB_DQ<8>")
	)
	(segment
		(start 298.681394 -290.28517)
		(end 298.681394 -290.64585)
		(width 0.14478)
		(layer "In2.Cu")
		(net "M_C_CPU0_SB_DQ<8>")
	)
	(segment
		(start 338.69249 -279.273508)
		(end 338.684108 -279.268682)
		(width 0.0889)
		(layer "In2.Cu")
		(net "M_C_CPU0_SB_DQ<8>")
	)
	(segment
		(start 325.540116 -278.84374)
		(end 323.982334 -278.84374)
		(width 0.0889)
		(layer "In2.Cu")
		(net "M_C_CPU0_SB_DQ<8>")
	)
	(segment
		(start 342.47709 -279.211532)
		(end 342.381078 -279.236932)
		(width 0.0889)
		(layer "In2.Cu")
		(net "M_C_CPU0_SB_DQ<8>")
	)
	(segment
		(start 304.205894 -290.99891)
		(end 303.862486 -290.99891)
		(width 0.14478)
		(layer "In2.Cu")
		(net "M_C_CPU0_SB_DQ<8>")
	)
	(segment
		(start 326.202294 -279.12695)
		(end 326.187054 -279.11171)
		(width 0.0889)
		(layer "In2.Cu")
		(net "M_C_CPU0_SB_DQ<8>")
	)
	(segment
		(start 327.40727 -279.268682)
		(end 327.379584 -279.25268)
		(width 0.0889)
		(layer "In2.Cu")
		(net "M_C_CPU0_SB_DQ<8>")
	)
	(segment
		(start 300.64075 -290.13531)
		(end 300.365922 -290.410138)
		(width 0.14478)
		(layer "In2.Cu")
		(net "M_C_CPU0_SB_DQ<8>")
	)
	(segment
		(start 295.435274 -291.260276)
		(end 295.148508 -290.97351)
		(width 0.14478)
		(layer "In2.Cu")
		(net "M_C_CPU0_SB_DQ<8>")
	)
	(segment
		(start 327.779888 -279.268428)
		(end 327.758044 -279.280874)
		(width 0.0889)
		(layer "In2.Cu")
		(net "M_C_CPU0_SB_DQ<8>")
	)
	(segment
		(start 305.740308 -291.04971)
		(end 305.31054 -291.04971)
		(width 0.14478)
		(layer "In2.Cu")
		(net "M_C_CPU0_SB_DQ<8>")
	)
	(segment
		(start 297.490896 -291.260276)
		(end 297.327828 -291.423344)
		(width 0.14478)
		(layer "In2.Cu")
		(net "M_C_CPU0_SB_DQ<8>")
	)
	(segment
		(start 298.531534 -290.79571)
		(end 298.170854 -290.79571)
		(width 0.14478)
		(layer "In2.Cu")
		(net "M_C_CPU0_SB_DQ<8>")
	)
	(segment
		(start 320.5861 -278.84374)
		(end 320.195702 -279.234138)
		(width 0.14478)
		(layer "In2.Cu")
		(net "M_C_CPU0_SB_DQ<8>")
	)
	(segment
		(start 301.293022 -290.641532)
		(end 301.293022 -290.411408)
		(width 0.14478)
		(layer "In2.Cu")
		(net "M_C_CPU0_SB_DQ<8>")
	)
	(segment
		(start 319.14338 -280.52268)
		(end 318.90716 -280.52268)
		(width 0.14478)
		(layer "In2.Cu")
		(net "M_C_CPU0_SB_DQ<8>")
	)
	(segment
		(start 295.148508 -290.97351)
		(end 294.780208 -290.97351)
		(width 0.14478)
		(layer "In2.Cu")
		(net "M_C_CPU0_SB_DQ<8>")
	)
	(segment
		(start 318.635126 -281.030934)
		(end 318.363092 -281.302968)
		(width 0.14478)
		(layer "In2.Cu")
		(net "M_C_CPU0_SB_DQ<8>")
	)
	(segment
		(start 320.195702 -279.234138)
		(end 320.195702 -279.470358)
		(width 0.14478)
		(layer "In2.Cu")
		(net "M_C_CPU0_SB_DQ<8>")
	)
	(segment
		(start 296.584878 -290.971732)
		(end 296.236898 -290.971732)
		(width 0.14478)
		(layer "In2.Cu")
		(net "M_C_CPU0_SB_DQ<8>")
	)
	(arc
		(start 329.284076 -279.268682)
		(mid 329.00112 -279.192505)
		(end 328.718164 -279.268682)
		(width 0.0889)
		(layer "In2.Cu")
		(net "M_C_CPU0_SB_DQ<8>")
	)
	(arc
		(start 329.658218 -279.268682)
		(mid 329.475967 -279.319032)
		(end 329.292458 -279.273508)
		(width 0.0889)
		(layer "In2.Cu")
		(net "M_C_CPU0_SB_DQ<8>")
	)
	(arc
		(start 336.804 -279.268682)
		(mid 336.521044 -279.192505)
		(end 336.238088 -279.268682)
		(width 0.0889)
		(layer "In2.Cu")
		(net "M_C_CPU0_SB_DQ<8>")
	)
	(arc
		(start 340.563962 -279.268682)
		(mid 340.281006 -279.192505)
		(end 339.99805 -279.268682)
		(width 0.0889)
		(layer "In2.Cu")
		(net "M_C_CPU0_SB_DQ<8>")
	)
	(arc
		(start 333.044038 -279.268682)
		(mid 332.761082 -279.192505)
		(end 332.478126 -279.268682)
		(width 0.0889)
		(layer "In2.Cu")
		(net "M_C_CPU0_SB_DQ<8>")
	)
	(arc
		(start 340.929722 -279.273508)
		(mid 340.746214 -279.319002)
		(end 340.563962 -279.268682)
		(width 0.0889)
		(layer "In2.Cu")
		(net "M_C_CPU0_SB_DQ<8>")
	)
	(arc
		(start 339.99805 -279.268682)
		(mid 339.811106 -279.318937)
		(end 339.624162 -279.268682)
		(width 0.0889)
		(layer "In2.Cu")
		(net "M_C_CPU0_SB_DQ<8>")
	)
	(arc
		(start 335.298034 -279.268682)
		(mid 335.11109 -279.318937)
		(end 334.924146 -279.268682)
		(width 0.0889)
		(layer "In2.Cu")
		(net "M_C_CPU0_SB_DQ<8>")
	)
	(arc
		(start 326.187054 -279.11171)
		(mid 325.890236 -278.913383)
		(end 325.540116 -278.84374)
		(width 0.0889)
		(layer "In2.Cu")
		(net "M_C_CPU0_SB_DQ<8>")
	)
	(arc
		(start 338.118196 -279.268682)
		(mid 337.935945 -279.319032)
		(end 337.752436 -279.273508)
		(width 0.0889)
		(layer "In2.Cu")
		(net "M_C_CPU0_SB_DQ<8>")
	)
	(arc
		(start 341.504016 -279.268682)
		(mid 341.22106 -279.192505)
		(end 340.938104 -279.268682)
		(width 0.0889)
		(layer "In2.Cu")
		(net "M_C_CPU0_SB_DQ<8>")
	)
	(arc
		(start 335.863946 -279.268682)
		(mid 335.58099 -279.192505)
		(end 335.298034 -279.268682)
		(width 0.0889)
		(layer "In2.Cu")
		(net "M_C_CPU0_SB_DQ<8>")
	)
	(arc
		(start 328.344022 -279.268682)
		(mid 328.075702 -279.192574)
		(end 327.803764 -279.254458)
		(width 0.0889)
		(layer "In2.Cu")
		(net "M_C_CPU0_SB_DQ<8>")
	)
	(arc
		(start 341.869776 -279.273508)
		(mid 341.686268 -279.319002)
		(end 341.504016 -279.268682)
		(width 0.0889)
		(layer "In2.Cu")
		(net "M_C_CPU0_SB_DQ<8>")
	)
	(arc
		(start 328.709782 -279.273508)
		(mid 328.526274 -279.319002)
		(end 328.344022 -279.268682)
		(width 0.0889)
		(layer "In2.Cu")
		(net "M_C_CPU0_SB_DQ<8>")
	)
	(arc
		(start 342.381078 -279.236932)
		(mid 342.12587 -279.193455)
		(end 341.878158 -279.268682)
		(width 0.0889)
		(layer "In2.Cu")
		(net "M_C_CPU0_SB_DQ<8>")
	)
	(arc
		(start 332.469744 -279.273508)
		(mid 332.286236 -279.319002)
		(end 332.103984 -279.268682)
		(width 0.0889)
		(layer "In2.Cu")
		(net "M_C_CPU0_SB_DQ<8>")
	)
	(arc
		(start 326.651112 -279.312878)
		(mid 326.408205 -279.264561)
		(end 326.202294 -279.12695)
		(width 0.0889)
		(layer "In2.Cu")
		(net "M_C_CPU0_SB_DQ<8>")
	)
	(arc
		(start 339.05825 -279.268682)
		(mid 338.875999 -279.319032)
		(end 338.69249 -279.273508)
		(width 0.0889)
		(layer "In2.Cu")
		(net "M_C_CPU0_SB_DQ<8>")
	)
	(arc
		(start 334.924146 -279.268682)
		(mid 334.64119 -279.192505)
		(end 334.358234 -279.268682)
		(width 0.0889)
		(layer "In2.Cu")
		(net "M_C_CPU0_SB_DQ<8>")
	)
	(arc
		(start 336.229706 -279.273508)
		(mid 336.046198 -279.319002)
		(end 335.863946 -279.268682)
		(width 0.0889)
		(layer "In2.Cu")
		(net "M_C_CPU0_SB_DQ<8>")
	)
	(arc
		(start 331.16393 -279.268682)
		(mid 330.880974 -279.192505)
		(end 330.598018 -279.268682)
		(width 0.0889)
		(layer "In2.Cu")
		(net "M_C_CPU0_SB_DQ<8>")
	)
	(arc
		(start 330.22413 -279.268682)
		(mid 329.941174 -279.192505)
		(end 329.658218 -279.268682)
		(width 0.0889)
		(layer "In2.Cu")
		(net "M_C_CPU0_SB_DQ<8>")
	)
	(arc
		(start 338.684108 -279.268682)
		(mid 338.401152 -279.192505)
		(end 338.118196 -279.268682)
		(width 0.0889)
		(layer "In2.Cu")
		(net "M_C_CPU0_SB_DQ<8>")
	)
	(arc
		(start 337.16976 -279.273508)
		(mid 336.986252 -279.319002)
		(end 336.804 -279.268682)
		(width 0.0889)
		(layer "In2.Cu")
		(net "M_C_CPU0_SB_DQ<8>")
	)
	(arc
		(start 333.984092 -279.268682)
		(mid 333.701136 -279.192505)
		(end 333.41818 -279.268682)
		(width 0.0889)
		(layer "In2.Cu")
		(net "M_C_CPU0_SB_DQ<8>")
	)
	(arc
		(start 337.744054 -279.268682)
		(mid 337.461098 -279.192505)
		(end 337.178142 -279.268682)
		(width 0.0889)
		(layer "In2.Cu")
		(net "M_C_CPU0_SB_DQ<8>")
	)
	(arc
		(start 333.41818 -279.268682)
		(mid 333.235929 -279.319032)
		(end 333.05242 -279.273508)
		(width 0.0889)
		(layer "In2.Cu")
		(net "M_C_CPU0_SB_DQ<8>")
	)
	(arc
		(start 331.52969 -279.273508)
		(mid 331.346182 -279.319002)
		(end 331.16393 -279.268682)
		(width 0.0889)
		(layer "In2.Cu")
		(net "M_C_CPU0_SB_DQ<8>")
	)
	(arc
		(start 330.598018 -279.268682)
		(mid 330.411074 -279.318937)
		(end 330.22413 -279.268682)
		(width 0.0889)
		(layer "In2.Cu")
		(net "M_C_CPU0_SB_DQ<8>")
	)
	(arc
		(start 339.624162 -279.268682)
		(mid 339.341206 -279.192505)
		(end 339.05825 -279.268682)
		(width 0.0889)
		(layer "In2.Cu")
		(net "M_C_CPU0_SB_DQ<8>")
	)
	(arc
		(start 332.103984 -279.268682)
		(mid 331.821028 -279.192505)
		(end 331.538072 -279.268682)
		(width 0.0889)
		(layer "In2.Cu")
		(net "M_C_CPU0_SB_DQ<8>")
	)
	(arc
		(start 334.358234 -279.268682)
		(mid 334.175983 -279.319032)
		(end 333.992474 -279.273508)
		(width 0.0889)
		(layer "In2.Cu")
		(net "M_C_CPU0_SB_DQ<8>")
	)
	(arc
		(start 327.379584 -279.25268)
		(mid 327.10755 -279.191908)
		(end 326.83958 -279.268682)
		(width 0.0889)
		(layer "In2.Cu")
		(net "M_C_CPU0_SB_DQ<8>")
	)
	(arc
		(start 327.758044 -279.280874)
		(mid 327.581116 -279.318702)
		(end 327.40727 -279.268682)
		(width 0.0889)
		(layer "In2.Cu")
		(net "M_C_CPU0_SB_DQ<8>")
	)
	(arc
		(start 326.83958 -279.268682)
		(mid 326.760861 -279.301661)
		(end 326.676258 -279.312878)
		(width 0.0889)
		(layer "In2.Cu")
		(net "M_C_CPU0_SB_DQ<8>")
	)
	(segment
		(start 344.03792 -278.680164)
		(end 343.571068 -278.946102)
		(width 0.10668)
		(layer "F.Cu")
		(net "M_C_CPU0_SB_DQ<7>")
	)
	(segment
		(start 327.41489 -278.616664)
		(end 327.403206 -278.623522)
		(width 0.0889)
		(layer "In2.Cu")
		(net "M_C_CPU0_SB_DQ<7>")
	)
	(segment
		(start 297.768518 -290.410138)
		(end 288.60496 -290.410138)
		(width 0.14478)
		(layer "In2.Cu")
		(net "M_C_CPU0_SB_DQ<7>")
	)
	(segment
		(start 302.078898 -290.410138)
		(end 301.22876 -289.56)
		(width 0.14478)
		(layer "In2.Cu")
		(net "M_C_CPU0_SB_DQ<7>")
	)
	(segment
		(start 331.538072 -278.623522)
		(end 331.52969 -278.618696)
		(width 0.0889)
		(layer "In2.Cu")
		(net "M_C_CPU0_SB_DQ<7>")
	)
	(segment
		(start 332.478126 -278.623522)
		(end 332.469744 -278.618696)
		(width 0.0889)
		(layer "In2.Cu")
		(net "M_C_CPU0_SB_DQ<7>")
	)
	(segment
		(start 337.752436 -278.618696)
		(end 337.744054 -278.623522)
		(width 0.0889)
		(layer "In2.Cu")
		(net "M_C_CPU0_SB_DQ<7>")
	)
	(segment
		(start 301.22876 -289.56)
		(end 298.618656 -289.56)
		(width 0.14478)
		(layer "In2.Cu")
		(net "M_C_CPU0_SB_DQ<7>")
	)
	(segment
		(start 324.354444 -278.28748)
		(end 323.897244 -278.28748)
		(width 0.0889)
		(layer "In2.Cu")
		(net "M_C_CPU0_SB_DQ<7>")
	)
	(segment
		(start 333.05242 -278.618696)
		(end 333.044038 -278.623522)
		(width 0.0889)
		(layer "In2.Cu")
		(net "M_C_CPU0_SB_DQ<7>")
	)
	(segment
		(start 343.571068 -278.946102)
		(end 343.725246 -278.680672)
		(width 0.0889)
		(layer "In2.Cu")
		(net "M_C_CPU0_SB_DQ<7>")
	)
	(segment
		(start 333.992474 -278.618696)
		(end 333.984092 -278.623522)
		(width 0.0889)
		(layer "In2.Cu")
		(net "M_C_CPU0_SB_DQ<7>")
	)
	(segment
		(start 340.938104 -278.623522)
		(end 340.929722 -278.618696)
		(width 0.0889)
		(layer "In2.Cu")
		(net "M_C_CPU0_SB_DQ<7>")
	)
	(segment
		(start 338.69249 -278.618696)
		(end 338.684108 -278.623522)
		(width 0.0889)
		(layer "In2.Cu")
		(net "M_C_CPU0_SB_DQ<7>")
	)
	(segment
		(start 288.60496 -290.410138)
		(end 288.180018 -289.985196)
		(width 0.14478)
		(layer "In2.Cu")
		(net "M_C_CPU0_SB_DQ<7>")
	)
	(segment
		(start 328.344022 -278.623522)
		(end 328.32929 -278.632158)
		(width 0.0889)
		(layer "In2.Cu")
		(net "M_C_CPU0_SB_DQ<7>")
	)
	(segment
		(start 298.618656 -289.56)
		(end 297.768518 -290.410138)
		(width 0.14478)
		(layer "In2.Cu")
		(net "M_C_CPU0_SB_DQ<7>")
	)
	(segment
		(start 326.207882 -278.451564)
		(end 324.518528 -278.451564)
		(width 0.0889)
		(layer "In2.Cu")
		(net "M_C_CPU0_SB_DQ<7>")
	)
	(segment
		(start 336.238088 -278.623522)
		(end 336.229706 -278.618696)
		(width 0.0889)
		(layer "In2.Cu")
		(net "M_C_CPU0_SB_DQ<7>")
	)
	(segment
		(start 323.897244 -278.28748)
		(end 320.362834 -278.28748)
		(width 0.14478)
		(layer "In2.Cu")
		(net "M_C_CPU0_SB_DQ<7>")
	)
	(segment
		(start 309.090314 -289.56)
		(end 306.013104 -289.56)
		(width 0.14478)
		(layer "In2.Cu")
		(net "M_C_CPU0_SB_DQ<7>")
	)
	(segment
		(start 324.518528 -278.451564)
		(end 324.354444 -278.28748)
		(width 0.0889)
		(layer "In2.Cu")
		(net "M_C_CPU0_SB_DQ<7>")
	)
	(segment
		(start 337.178142 -278.623522)
		(end 337.16976 -278.618696)
		(width 0.0889)
		(layer "In2.Cu")
		(net "M_C_CPU0_SB_DQ<7>")
	)
	(segment
		(start 305.162966 -290.410138)
		(end 302.078898 -290.410138)
		(width 0.14478)
		(layer "In2.Cu")
		(net "M_C_CPU0_SB_DQ<7>")
	)
	(segment
		(start 306.013104 -289.56)
		(end 305.162966 -290.410138)
		(width 0.14478)
		(layer "In2.Cu")
		(net "M_C_CPU0_SB_DQ<7>")
	)
	(segment
		(start 320.362834 -278.28748)
		(end 309.090314 -289.56)
		(width 0.14478)
		(layer "In2.Cu")
		(net "M_C_CPU0_SB_DQ<7>")
	)
	(segment
		(start 328.718164 -278.623522)
		(end 328.709782 -278.618696)
		(width 0.0889)
		(layer "In2.Cu")
		(net "M_C_CPU0_SB_DQ<7>")
	)
	(segment
		(start 326.84339 -278.627078)
		(end 326.837802 -278.623776)
		(width 0.0889)
		(layer "In2.Cu")
		(net "M_C_CPU0_SB_DQ<7>")
	)
	(segment
		(start 329.292458 -278.618696)
		(end 329.284076 -278.623522)
		(width 0.0889)
		(layer "In2.Cu")
		(net "M_C_CPU0_SB_DQ<7>")
	)
	(segment
		(start 343.392506 -278.618696)
		(end 343.384124 -278.623522)
		(width 0.0889)
		(layer "In2.Cu")
		(net "M_C_CPU0_SB_DQ<7>")
	)
	(segment
		(start 341.878158 -278.623522)
		(end 341.869776 -278.618696)
		(width 0.0889)
		(layer "In2.Cu")
		(net "M_C_CPU0_SB_DQ<7>")
	)
	(segment
		(start 342.452452 -278.618696)
		(end 342.44407 -278.623522)
		(width 0.0889)
		(layer "In2.Cu")
		(net "M_C_CPU0_SB_DQ<7>")
	)
	(segment
		(start 343.725246 -278.680672)
		(end 343.702894 -278.59736)
		(width 0.0889)
		(layer "In2.Cu")
		(net "M_C_CPU0_SB_DQ<7>")
	)
	(arc
		(start 338.118196 -278.623522)
		(mid 337.935945 -278.573172)
		(end 337.752436 -278.618696)
		(width 0.0889)
		(layer "In2.Cu")
		(net "M_C_CPU0_SB_DQ<7>")
	)
	(arc
		(start 336.229706 -278.618696)
		(mid 336.046198 -278.573202)
		(end 335.863946 -278.623522)
		(width 0.0889)
		(layer "In2.Cu")
		(net "M_C_CPU0_SB_DQ<7>")
	)
	(arc
		(start 333.984092 -278.623522)
		(mid 333.701136 -278.699699)
		(end 333.41818 -278.623522)
		(width 0.0889)
		(layer "In2.Cu")
		(net "M_C_CPU0_SB_DQ<7>")
	)
	(arc
		(start 341.869776 -278.618696)
		(mid 341.686268 -278.573202)
		(end 341.504016 -278.623522)
		(width 0.0889)
		(layer "In2.Cu")
		(net "M_C_CPU0_SB_DQ<7>")
	)
	(arc
		(start 330.598018 -278.623522)
		(mid 330.411074 -278.573267)
		(end 330.22413 -278.623522)
		(width 0.0889)
		(layer "In2.Cu")
		(net "M_C_CPU0_SB_DQ<7>")
	)
	(arc
		(start 343.702894 -278.59736)
		(mid 343.545384 -278.574162)
		(end 343.392506 -278.618696)
		(width 0.0889)
		(layer "In2.Cu")
		(net "M_C_CPU0_SB_DQ<7>")
	)
	(arc
		(start 330.22413 -278.623522)
		(mid 329.941174 -278.699699)
		(end 329.658218 -278.623522)
		(width 0.0889)
		(layer "In2.Cu")
		(net "M_C_CPU0_SB_DQ<7>")
	)
	(arc
		(start 328.32929 -278.632158)
		(mid 328.052307 -278.699962)
		(end 327.777602 -278.623522)
		(width 0.0889)
		(layer "In2.Cu")
		(net "M_C_CPU0_SB_DQ<7>")
	)
	(arc
		(start 327.777602 -278.623522)
		(mid 327.597144 -278.573078)
		(end 327.41489 -278.616664)
		(width 0.0889)
		(layer "In2.Cu")
		(net "M_C_CPU0_SB_DQ<7>")
	)
	(arc
		(start 328.709782 -278.618696)
		(mid 328.526274 -278.573202)
		(end 328.344022 -278.623522)
		(width 0.0889)
		(layer "In2.Cu")
		(net "M_C_CPU0_SB_DQ<7>")
	)
	(arc
		(start 341.504016 -278.623522)
		(mid 341.22106 -278.699699)
		(end 340.938104 -278.623522)
		(width 0.0889)
		(layer "In2.Cu")
		(net "M_C_CPU0_SB_DQ<7>")
	)
	(arc
		(start 326.837802 -278.623776)
		(mid 326.534399 -278.495401)
		(end 326.207882 -278.451564)
		(width 0.0889)
		(layer "In2.Cu")
		(net "M_C_CPU0_SB_DQ<7>")
	)
	(arc
		(start 342.44407 -278.623522)
		(mid 342.161114 -278.699699)
		(end 341.878158 -278.623522)
		(width 0.0889)
		(layer "In2.Cu")
		(net "M_C_CPU0_SB_DQ<7>")
	)
	(arc
		(start 342.818212 -278.623522)
		(mid 342.635961 -278.573172)
		(end 342.452452 -278.618696)
		(width 0.0889)
		(layer "In2.Cu")
		(net "M_C_CPU0_SB_DQ<7>")
	)
	(arc
		(start 337.16976 -278.618696)
		(mid 336.986252 -278.573202)
		(end 336.804 -278.623522)
		(width 0.0889)
		(layer "In2.Cu")
		(net "M_C_CPU0_SB_DQ<7>")
	)
	(arc
		(start 329.284076 -278.623522)
		(mid 329.00112 -278.699699)
		(end 328.718164 -278.623522)
		(width 0.0889)
		(layer "In2.Cu")
		(net "M_C_CPU0_SB_DQ<7>")
	)
	(arc
		(start 340.929722 -278.618696)
		(mid 340.746214 -278.573202)
		(end 340.563962 -278.623522)
		(width 0.0889)
		(layer "In2.Cu")
		(net "M_C_CPU0_SB_DQ<7>")
	)
	(arc
		(start 333.044038 -278.623522)
		(mid 332.761082 -278.699699)
		(end 332.478126 -278.623522)
		(width 0.0889)
		(layer "In2.Cu")
		(net "M_C_CPU0_SB_DQ<7>")
	)
	(arc
		(start 334.358234 -278.623522)
		(mid 334.175983 -278.573172)
		(end 333.992474 -278.618696)
		(width 0.0889)
		(layer "In2.Cu")
		(net "M_C_CPU0_SB_DQ<7>")
	)
	(arc
		(start 329.658218 -278.623522)
		(mid 329.475967 -278.573172)
		(end 329.292458 -278.618696)
		(width 0.0889)
		(layer "In2.Cu")
		(net "M_C_CPU0_SB_DQ<7>")
	)
	(arc
		(start 339.624162 -278.623522)
		(mid 339.341206 -278.699699)
		(end 339.05825 -278.623522)
		(width 0.0889)
		(layer "In2.Cu")
		(net "M_C_CPU0_SB_DQ<7>")
	)
	(arc
		(start 335.863946 -278.623522)
		(mid 335.58099 -278.699699)
		(end 335.298034 -278.623522)
		(width 0.0889)
		(layer "In2.Cu")
		(net "M_C_CPU0_SB_DQ<7>")
	)
	(arc
		(start 331.16393 -278.623522)
		(mid 330.880974 -278.699699)
		(end 330.598018 -278.623522)
		(width 0.0889)
		(layer "In2.Cu")
		(net "M_C_CPU0_SB_DQ<7>")
	)
	(arc
		(start 333.41818 -278.623522)
		(mid 333.235929 -278.573172)
		(end 333.05242 -278.618696)
		(width 0.0889)
		(layer "In2.Cu")
		(net "M_C_CPU0_SB_DQ<7>")
	)
	(arc
		(start 327.403206 -278.623522)
		(mid 327.123778 -278.699688)
		(end 326.84339 -278.627078)
		(width 0.0889)
		(layer "In2.Cu")
		(net "M_C_CPU0_SB_DQ<7>")
	)
	(arc
		(start 343.384124 -278.623522)
		(mid 343.101168 -278.699699)
		(end 342.818212 -278.623522)
		(width 0.0889)
		(layer "In2.Cu")
		(net "M_C_CPU0_SB_DQ<7>")
	)
	(arc
		(start 340.563962 -278.623522)
		(mid 340.281006 -278.699699)
		(end 339.99805 -278.623522)
		(width 0.0889)
		(layer "In2.Cu")
		(net "M_C_CPU0_SB_DQ<7>")
	)
	(arc
		(start 335.298034 -278.623522)
		(mid 335.11109 -278.573267)
		(end 334.924146 -278.623522)
		(width 0.0889)
		(layer "In2.Cu")
		(net "M_C_CPU0_SB_DQ<7>")
	)
	(arc
		(start 334.924146 -278.623522)
		(mid 334.64119 -278.699699)
		(end 334.358234 -278.623522)
		(width 0.0889)
		(layer "In2.Cu")
		(net "M_C_CPU0_SB_DQ<7>")
	)
	(arc
		(start 332.103984 -278.623522)
		(mid 331.821028 -278.699699)
		(end 331.538072 -278.623522)
		(width 0.0889)
		(layer "In2.Cu")
		(net "M_C_CPU0_SB_DQ<7>")
	)
	(arc
		(start 332.469744 -278.618696)
		(mid 332.286236 -278.573202)
		(end 332.103984 -278.623522)
		(width 0.0889)
		(layer "In2.Cu")
		(net "M_C_CPU0_SB_DQ<7>")
	)
	(arc
		(start 339.05825 -278.623522)
		(mid 338.875999 -278.573172)
		(end 338.69249 -278.618696)
		(width 0.0889)
		(layer "In2.Cu")
		(net "M_C_CPU0_SB_DQ<7>")
	)
	(arc
		(start 336.804 -278.623522)
		(mid 336.521044 -278.699699)
		(end 336.238088 -278.623522)
		(width 0.0889)
		(layer "In2.Cu")
		(net "M_C_CPU0_SB_DQ<7>")
	)
	(arc
		(start 337.744054 -278.623522)
		(mid 337.461098 -278.699699)
		(end 337.178142 -278.623522)
		(width 0.0889)
		(layer "In2.Cu")
		(net "M_C_CPU0_SB_DQ<7>")
	)
	(arc
		(start 339.99805 -278.623522)
		(mid 339.811106 -278.573267)
		(end 339.624162 -278.623522)
		(width 0.0889)
		(layer "In2.Cu")
		(net "M_C_CPU0_SB_DQ<7>")
	)
	(arc
		(start 331.52969 -278.618696)
		(mid 331.346182 -278.573202)
		(end 331.16393 -278.623522)
		(width 0.0889)
		(layer "In2.Cu")
		(net "M_C_CPU0_SB_DQ<7>")
	)
	(arc
		(start 338.684108 -278.623522)
		(mid 338.401152 -278.699699)
		(end 338.118196 -278.623522)
		(width 0.0889)
		(layer "In2.Cu")
		(net "M_C_CPU0_SB_DQ<7>")
	)
	(segment
		(start 342.627966 -277.870158)
		(end 342.161114 -278.136096)
		(width 0.10668)
		(layer "F.Cu")
		(net "M_C_CPU0_SB_DQ<6>")
	)
	(segment
		(start 340.102444 -277.80869)
		(end 340.094062 -277.813516)
		(width 0.0889)
		(layer "In2.Cu")
		(net "M_C_CPU0_SB_DQ<6>")
	)
	(segment
		(start 290.430712 -287.809432)
		(end 290.267898 -287.972246)
		(width 0.14478)
		(layer "In2.Cu")
		(net "M_C_CPU0_SB_DQ<6>")
	)
	(segment
		(start 299.028612 -287.859978)
		(end 297.781218 -289.107372)
		(width 0.14478)
		(layer "In2.Cu")
		(net "M_C_CPU0_SB_DQ<6>")
	)
	(segment
		(start 290.267898 -288.547302)
		(end 290.105084 -288.710116)
		(width 0.14478)
		(layer "In2.Cu")
		(net "M_C_CPU0_SB_DQ<6>")
	)
	(segment
		(start 288.60496 -288.710116)
		(end 288.180018 -288.285174)
		(width 0.14478)
		(layer "In2.Cu")
		(net "M_C_CPU0_SB_DQ<6>")
	)
	(segment
		(start 323.894704 -277.37816)
		(end 319.999868 -277.37816)
		(width 0.14478)
		(layer "In2.Cu")
		(net "M_C_CPU0_SB_DQ<6>")
	)
	(segment
		(start 308.230778 -287.859978)
		(end 306.426616 -287.859978)
		(width 0.14478)
		(layer "In2.Cu")
		(net "M_C_CPU0_SB_DQ<6>")
	)
	(segment
		(start 290.986972 -288.710116)
		(end 290.824158 -288.547302)
		(width 0.14478)
		(layer "In2.Cu")
		(net "M_C_CPU0_SB_DQ<6>")
	)
	(segment
		(start 331.642466 -277.80869)
		(end 331.634084 -277.813516)
		(width 0.0889)
		(layer "In2.Cu")
		(net "M_C_CPU0_SB_DQ<6>")
	)
	(segment
		(start 309.911496 -287.466532)
		(end 308.624224 -287.466532)
		(width 0.14478)
		(layer "In2.Cu")
		(net "M_C_CPU0_SB_DQ<6>")
	)
	(segment
		(start 324.562216 -277.501858)
		(end 324.438518 -277.37816)
		(width 0.0889)
		(layer "In2.Cu")
		(net "M_C_CPU0_SB_DQ<6>")
	)
	(segment
		(start 300.815248 -287.859978)
		(end 299.028612 -287.859978)
		(width 0.14478)
		(layer "In2.Cu")
		(net "M_C_CPU0_SB_DQ<6>")
	)
	(segment
		(start 338.588096 -277.813516)
		(end 338.579714 -277.80869)
		(width 0.0889)
		(layer "In2.Cu")
		(net "M_C_CPU0_SB_DQ<6>")
	)
	(segment
		(start 296.536618 -289.107372)
		(end 296.139362 -288.710116)
		(width 0.14478)
		(layer "In2.Cu")
		(net "M_C_CPU0_SB_DQ<6>")
	)
	(segment
		(start 333.88808 -277.813516)
		(end 333.879698 -277.80869)
		(width 0.0889)
		(layer "In2.Cu")
		(net "M_C_CPU0_SB_DQ<6>")
	)
	(segment
		(start 326.651112 -277.896066)
		(end 326.140826 -277.896066)
		(width 0.0889)
		(layer "In2.Cu")
		(net "M_C_CPU0_SB_DQ<6>")
	)
	(segment
		(start 326.140826 -277.896066)
		(end 325.746618 -277.501858)
		(width 0.0889)
		(layer "In2.Cu")
		(net "M_C_CPU0_SB_DQ<6>")
	)
	(segment
		(start 330.702412 -277.80869)
		(end 330.69403 -277.813516)
		(width 0.0889)
		(layer "In2.Cu")
		(net "M_C_CPU0_SB_DQ<6>")
	)
	(segment
		(start 330.128118 -277.813516)
		(end 330.119736 -277.80869)
		(width 0.0889)
		(layer "In2.Cu")
		(net "M_C_CPU0_SB_DQ<6>")
	)
	(segment
		(start 305.576478 -288.710116)
		(end 301.665386 -288.710116)
		(width 0.14478)
		(layer "In2.Cu")
		(net "M_C_CPU0_SB_DQ<6>")
	)
	(segment
		(start 319.999868 -277.37816)
		(end 309.911496 -287.466532)
		(width 0.14478)
		(layer "In2.Cu")
		(net "M_C_CPU0_SB_DQ<6>")
	)
	(segment
		(start 334.828134 -277.813516)
		(end 334.819752 -277.80869)
		(width 0.0889)
		(layer "In2.Cu")
		(net "M_C_CPU0_SB_DQ<6>")
	)
	(segment
		(start 290.105084 -288.710116)
		(end 288.60496 -288.710116)
		(width 0.14478)
		(layer "In2.Cu")
		(net "M_C_CPU0_SB_DQ<6>")
	)
	(segment
		(start 326.958452 -277.798022)
		(end 326.906128 -277.827994)
		(width 0.0889)
		(layer "In2.Cu")
		(net "M_C_CPU0_SB_DQ<6>")
	)
	(segment
		(start 342.315038 -277.870666)
		(end 342.292686 -277.787354)
		(width 0.0889)
		(layer "In2.Cu")
		(net "M_C_CPU0_SB_DQ<6>")
	)
	(segment
		(start 336.342482 -277.80869)
		(end 336.3341 -277.813516)
		(width 0.0889)
		(layer "In2.Cu")
		(net "M_C_CPU0_SB_DQ<6>")
	)
	(segment
		(start 325.746618 -277.501858)
		(end 324.562216 -277.501858)
		(width 0.0889)
		(layer "In2.Cu")
		(net "M_C_CPU0_SB_DQ<6>")
	)
	(segment
		(start 328.248264 -277.813516)
		(end 328.222102 -277.798276)
		(width 0.0889)
		(layer "In2.Cu")
		(net "M_C_CPU0_SB_DQ<6>")
	)
	(segment
		(start 297.781218 -289.107372)
		(end 296.536618 -289.107372)
		(width 0.14478)
		(layer "In2.Cu")
		(net "M_C_CPU0_SB_DQ<6>")
	)
	(segment
		(start 327.33488 -277.832058)
		(end 327.30313 -277.813516)
		(width 0.0889)
		(layer "In2.Cu")
		(net "M_C_CPU0_SB_DQ<6>")
	)
	(segment
		(start 290.661344 -287.809432)
		(end 290.430712 -287.809432)
		(width 0.14478)
		(layer "In2.Cu")
		(net "M_C_CPU0_SB_DQ<6>")
	)
	(segment
		(start 290.267898 -287.972246)
		(end 290.267898 -288.547302)
		(width 0.14478)
		(layer "In2.Cu")
		(net "M_C_CPU0_SB_DQ<6>")
	)
	(segment
		(start 306.426616 -287.859978)
		(end 305.576478 -288.710116)
		(width 0.14478)
		(layer "In2.Cu")
		(net "M_C_CPU0_SB_DQ<6>")
	)
	(segment
		(start 290.824158 -288.547302)
		(end 290.824158 -287.972246)
		(width 0.14478)
		(layer "In2.Cu")
		(net "M_C_CPU0_SB_DQ<6>")
	)
	(segment
		(start 308.624224 -287.466532)
		(end 308.230778 -287.859978)
		(width 0.14478)
		(layer "In2.Cu")
		(net "M_C_CPU0_SB_DQ<6>")
	)
	(segment
		(start 296.139362 -288.710116)
		(end 290.986972 -288.710116)
		(width 0.14478)
		(layer "In2.Cu")
		(net "M_C_CPU0_SB_DQ<6>")
	)
	(segment
		(start 324.438518 -277.37816)
		(end 323.894704 -277.37816)
		(width 0.0889)
		(layer "In2.Cu")
		(net "M_C_CPU0_SB_DQ<6>")
	)
	(segment
		(start 341.042498 -277.80869)
		(end 341.034116 -277.813516)
		(width 0.0889)
		(layer "In2.Cu")
		(net "M_C_CPU0_SB_DQ<6>")
	)
	(segment
		(start 290.824158 -287.972246)
		(end 290.661344 -287.809432)
		(width 0.14478)
		(layer "In2.Cu")
		(net "M_C_CPU0_SB_DQ<6>")
	)
	(segment
		(start 335.402428 -277.80869)
		(end 335.394046 -277.813516)
		(width 0.0889)
		(layer "In2.Cu")
		(net "M_C_CPU0_SB_DQ<6>")
	)
	(segment
		(start 301.665386 -288.710116)
		(end 300.815248 -287.859978)
		(width 0.14478)
		(layer "In2.Cu")
		(net "M_C_CPU0_SB_DQ<6>")
	)
	(segment
		(start 342.161114 -278.136096)
		(end 342.315038 -277.870666)
		(width 0.0889)
		(layer "In2.Cu")
		(net "M_C_CPU0_SB_DQ<6>")
	)
	(segment
		(start 339.52815 -277.813516)
		(end 339.519768 -277.80869)
		(width 0.0889)
		(layer "In2.Cu")
		(net "M_C_CPU0_SB_DQ<6>")
	)
	(arc
		(start 329.753976 -277.813516)
		(mid 329.47102 -277.889693)
		(end 329.188064 -277.813516)
		(width 0.0889)
		(layer "In2.Cu")
		(net "M_C_CPU0_SB_DQ<6>")
	)
	(arc
		(start 329.188064 -277.813516)
		(mid 329.00112 -277.763261)
		(end 328.814176 -277.813516)
		(width 0.0889)
		(layer "In2.Cu")
		(net "M_C_CPU0_SB_DQ<6>")
	)
	(arc
		(start 330.69403 -277.813516)
		(mid 330.411074 -277.889693)
		(end 330.128118 -277.813516)
		(width 0.0889)
		(layer "In2.Cu")
		(net "M_C_CPU0_SB_DQ<6>")
	)
	(arc
		(start 338.579714 -277.80869)
		(mid 338.396206 -277.763196)
		(end 338.213954 -277.813516)
		(width 0.0889)
		(layer "In2.Cu")
		(net "M_C_CPU0_SB_DQ<6>")
	)
	(arc
		(start 328.814176 -277.813516)
		(mid 328.53122 -277.889693)
		(end 328.248264 -277.813516)
		(width 0.0889)
		(layer "In2.Cu")
		(net "M_C_CPU0_SB_DQ<6>")
	)
	(arc
		(start 342.292686 -277.787354)
		(mid 342.130497 -277.764619)
		(end 341.97417 -277.813516)
		(width 0.0889)
		(layer "In2.Cu")
		(net "M_C_CPU0_SB_DQ<6>")
	)
	(arc
		(start 328.222102 -277.798276)
		(mid 328.045101 -277.762198)
		(end 327.871836 -277.813262)
		(width 0.0889)
		(layer "In2.Cu")
		(net "M_C_CPU0_SB_DQ<6>")
	)
	(arc
		(start 337.274154 -277.813516)
		(mid 336.991198 -277.889693)
		(end 336.708242 -277.813516)
		(width 0.0889)
		(layer "In2.Cu")
		(net "M_C_CPU0_SB_DQ<6>")
	)
	(arc
		(start 330.119736 -277.80869)
		(mid 329.936228 -277.763196)
		(end 329.753976 -277.813516)
		(width 0.0889)
		(layer "In2.Cu")
		(net "M_C_CPU0_SB_DQ<6>")
	)
	(arc
		(start 335.394046 -277.813516)
		(mid 335.11109 -277.889693)
		(end 334.828134 -277.813516)
		(width 0.0889)
		(layer "In2.Cu")
		(net "M_C_CPU0_SB_DQ<6>")
	)
	(arc
		(start 326.906128 -277.827994)
		(mid 326.783079 -277.878721)
		(end 326.651112 -277.896066)
		(width 0.0889)
		(layer "In2.Cu")
		(net "M_C_CPU0_SB_DQ<6>")
	)
	(arc
		(start 339.519768 -277.80869)
		(mid 339.33626 -277.763196)
		(end 339.154008 -277.813516)
		(width 0.0889)
		(layer "In2.Cu")
		(net "M_C_CPU0_SB_DQ<6>")
	)
	(arc
		(start 333.513938 -277.813516)
		(mid 333.230982 -277.889693)
		(end 332.948026 -277.813516)
		(width 0.0889)
		(layer "In2.Cu")
		(net "M_C_CPU0_SB_DQ<6>")
	)
	(arc
		(start 336.708242 -277.813516)
		(mid 336.525991 -277.763166)
		(end 336.342482 -277.80869)
		(width 0.0889)
		(layer "In2.Cu")
		(net "M_C_CPU0_SB_DQ<6>")
	)
	(arc
		(start 334.819752 -277.80869)
		(mid 334.636244 -277.763196)
		(end 334.453992 -277.813516)
		(width 0.0889)
		(layer "In2.Cu")
		(net "M_C_CPU0_SB_DQ<6>")
	)
	(arc
		(start 340.094062 -277.813516)
		(mid 339.811106 -277.889693)
		(end 339.52815 -277.813516)
		(width 0.0889)
		(layer "In2.Cu")
		(net "M_C_CPU0_SB_DQ<6>")
	)
	(arc
		(start 337.648042 -277.813516)
		(mid 337.461098 -277.763261)
		(end 337.274154 -277.813516)
		(width 0.0889)
		(layer "In2.Cu")
		(net "M_C_CPU0_SB_DQ<6>")
	)
	(arc
		(start 327.871836 -277.813262)
		(mid 327.605747 -277.890539)
		(end 327.33488 -277.832058)
		(width 0.0889)
		(layer "In2.Cu")
		(net "M_C_CPU0_SB_DQ<6>")
	)
	(arc
		(start 331.068172 -277.813516)
		(mid 330.885921 -277.763166)
		(end 330.702412 -277.80869)
		(width 0.0889)
		(layer "In2.Cu")
		(net "M_C_CPU0_SB_DQ<6>")
	)
	(arc
		(start 340.468204 -277.813516)
		(mid 340.285953 -277.763166)
		(end 340.102444 -277.80869)
		(width 0.0889)
		(layer "In2.Cu")
		(net "M_C_CPU0_SB_DQ<6>")
	)
	(arc
		(start 332.008226 -277.813516)
		(mid 331.825975 -277.763166)
		(end 331.642466 -277.80869)
		(width 0.0889)
		(layer "In2.Cu")
		(net "M_C_CPU0_SB_DQ<6>")
	)
	(arc
		(start 327.30313 -277.813516)
		(mid 327.132689 -277.76351)
		(end 326.958452 -277.798022)
		(width 0.0889)
		(layer "In2.Cu")
		(net "M_C_CPU0_SB_DQ<6>")
	)
	(arc
		(start 331.634084 -277.813516)
		(mid 331.351128 -277.889693)
		(end 331.068172 -277.813516)
		(width 0.0889)
		(layer "In2.Cu")
		(net "M_C_CPU0_SB_DQ<6>")
	)
	(arc
		(start 336.3341 -277.813516)
		(mid 336.051144 -277.889693)
		(end 335.768188 -277.813516)
		(width 0.0889)
		(layer "In2.Cu")
		(net "M_C_CPU0_SB_DQ<6>")
	)
	(arc
		(start 335.768188 -277.813516)
		(mid 335.585937 -277.763166)
		(end 335.402428 -277.80869)
		(width 0.0889)
		(layer "In2.Cu")
		(net "M_C_CPU0_SB_DQ<6>")
	)
	(arc
		(start 338.213954 -277.813516)
		(mid 337.930998 -277.889693)
		(end 337.648042 -277.813516)
		(width 0.0889)
		(layer "In2.Cu")
		(net "M_C_CPU0_SB_DQ<6>")
	)
	(arc
		(start 332.574138 -277.813516)
		(mid 332.291182 -277.889693)
		(end 332.008226 -277.813516)
		(width 0.0889)
		(layer "In2.Cu")
		(net "M_C_CPU0_SB_DQ<6>")
	)
	(arc
		(start 341.408258 -277.813516)
		(mid 341.226007 -277.763166)
		(end 341.042498 -277.80869)
		(width 0.0889)
		(layer "In2.Cu")
		(net "M_C_CPU0_SB_DQ<6>")
	)
	(arc
		(start 339.154008 -277.813516)
		(mid 338.871052 -277.889693)
		(end 338.588096 -277.813516)
		(width 0.0889)
		(layer "In2.Cu")
		(net "M_C_CPU0_SB_DQ<6>")
	)
	(arc
		(start 332.948026 -277.813516)
		(mid 332.761082 -277.763261)
		(end 332.574138 -277.813516)
		(width 0.0889)
		(layer "In2.Cu")
		(net "M_C_CPU0_SB_DQ<6>")
	)
	(arc
		(start 333.879698 -277.80869)
		(mid 333.69619 -277.763196)
		(end 333.513938 -277.813516)
		(width 0.0889)
		(layer "In2.Cu")
		(net "M_C_CPU0_SB_DQ<6>")
	)
	(arc
		(start 341.97417 -277.813516)
		(mid 341.691214 -277.889693)
		(end 341.408258 -277.813516)
		(width 0.0889)
		(layer "In2.Cu")
		(net "M_C_CPU0_SB_DQ<6>")
	)
	(arc
		(start 341.034116 -277.813516)
		(mid 340.75116 -277.889693)
		(end 340.468204 -277.813516)
		(width 0.0889)
		(layer "In2.Cu")
		(net "M_C_CPU0_SB_DQ<6>")
	)
	(arc
		(start 334.453992 -277.813516)
		(mid 334.171036 -277.889693)
		(end 333.88808 -277.813516)
		(width 0.0889)
		(layer "In2.Cu")
		(net "M_C_CPU0_SB_DQ<6>")
	)
	(segment
		(start 344.508074 -277.870158)
		(end 344.041222 -278.136096)
		(width 0.10668)
		(layer "F.Cu")
		(net "M_C_CPU0_SB_DQ<5>")
	)
	(segment
		(start 302.029876 -289.521392)
		(end 301.83328 -289.521392)
		(width 0.14478)
		(layer "In2.Cu")
		(net "M_C_CPU0_SB_DQ<5>")
	)
	(segment
		(start 331.642466 -278.463502)
		(end 331.634084 -278.458676)
		(width 0.0889)
		(layer "In2.Cu")
		(net "M_C_CPU0_SB_DQ<5>")
	)
	(segment
		(start 308.407308 -288.548572)
		(end 308.245764 -288.710116)
		(width 0.14478)
		(layer "In2.Cu")
		(net "M_C_CPU0_SB_DQ<5>")
	)
	(segment
		(start 297.268392 -289.88131)
		(end 296.947336 -289.560254)
		(width 0.14478)
		(layer "In2.Cu")
		(net "M_C_CPU0_SB_DQ<5>")
	)
	(segment
		(start 304.693574 -289.93211)
		(end 304.543714 -289.78225)
		(width 0.14478)
		(layer "In2.Cu")
		(net "M_C_CPU0_SB_DQ<5>")
	)
	(segment
		(start 293.49065 -289.789362)
		(end 293.327836 -289.952176)
		(width 0.14478)
		(layer "In2.Cu")
		(net "M_C_CPU0_SB_DQ<5>")
	)
	(segment
		(start 304.393854 -289.17011)
		(end 304.137314 -289.17011)
		(width 0.14478)
		(layer "In2.Cu")
		(net "M_C_CPU0_SB_DQ<5>")
	)
	(segment
		(start 338.588096 -278.458676)
		(end 338.579714 -278.463502)
		(width 0.0889)
		(layer "In2.Cu")
		(net "M_C_CPU0_SB_DQ<5>")
	)
	(segment
		(start 327.321926 -278.45004)
		(end 327.307194 -278.458676)
		(width 0.0889)
		(layer "In2.Cu")
		(net "M_C_CPU0_SB_DQ<5>")
	)
	(segment
		(start 309.31485 -288.699448)
		(end 309.109618 -288.699448)
		(width 0.14478)
		(layer "In2.Cu")
		(net "M_C_CPU0_SB_DQ<5>")
	)
	(segment
		(start 326.947276 -278.466296)
		(end 326.90689 -278.443182)
		(width 0.0889)
		(layer "In2.Cu")
		(net "M_C_CPU0_SB_DQ<5>")
	)
	(segment
		(start 336.342482 -278.463502)
		(end 336.3341 -278.458676)
		(width 0.0889)
		(layer "In2.Cu")
		(net "M_C_CPU0_SB_DQ<5>")
	)
	(segment
		(start 308.568852 -288.182812)
		(end 308.407308 -288.344356)
		(width 0.14478)
		(layer "In2.Cu")
		(net "M_C_CPU0_SB_DQ<5>")
	)
	(segment
		(start 294.19677 -289.83813)
		(end 294.04691 -289.68827)
		(width 0.14478)
		(layer "In2.Cu")
		(net "M_C_CPU0_SB_DQ<5>")
	)
	(segment
		(start 330.128118 -278.458676)
		(end 330.119736 -278.463502)
		(width 0.0889)
		(layer "In2.Cu")
		(net "M_C_CPU0_SB_DQ<5>")
	)
	(segment
		(start 294.409114 -289.83813)
		(end 294.19677 -289.83813)
		(width 0.14478)
		(layer "In2.Cu")
		(net "M_C_CPU0_SB_DQ<5>")
	)
	(segment
		(start 304.543714 -289.78225)
		(end 304.543714 -289.31997)
		(width 0.14478)
		(layer "In2.Cu")
		(net "M_C_CPU0_SB_DQ<5>")
	)
	(segment
		(start 309.109618 -288.699448)
		(end 308.958742 -288.548572)
		(width 0.14478)
		(layer "In2.Cu")
		(net "M_C_CPU0_SB_DQ<5>")
	)
	(segment
		(start 294.04691 -289.68827)
		(end 294.04691 -289.35299)
		(width 0.14478)
		(layer "In2.Cu")
		(net "M_C_CPU0_SB_DQ<5>")
	)
	(segment
		(start 293.097204 -289.952176)
		(end 292.280086 -289.135058)
		(width 0.14478)
		(layer "In2.Cu")
		(net "M_C_CPU0_SB_DQ<5>")
	)
	(segment
		(start 320.181478 -277.83282)
		(end 309.31485 -288.699448)
		(width 0.14478)
		(layer "In2.Cu")
		(net "M_C_CPU0_SB_DQ<5>")
	)
	(segment
		(start 334.828134 -278.458676)
		(end 334.819752 -278.463502)
		(width 0.0889)
		(layer "In2.Cu")
		(net "M_C_CPU0_SB_DQ<5>")
	)
	(segment
		(start 304.137314 -289.17011)
		(end 303.74717 -289.560254)
		(width 0.14478)
		(layer "In2.Cu")
		(net "M_C_CPU0_SB_DQ<5>")
	)
	(segment
		(start 330.702412 -278.463502)
		(end 330.69403 -278.458676)
		(width 0.0889)
		(layer "In2.Cu")
		(net "M_C_CPU0_SB_DQ<5>")
	)
	(segment
		(start 304.543714 -289.31997)
		(end 304.393854 -289.17011)
		(width 0.14478)
		(layer "In2.Cu")
		(net "M_C_CPU0_SB_DQ<5>")
	)
	(segment
		(start 324.456044 -277.83282)
		(end 323.906134 -277.83282)
		(width 0.0889)
		(layer "In2.Cu")
		(net "M_C_CPU0_SB_DQ<5>")
	)
	(segment
		(start 308.407308 -288.344356)
		(end 308.407308 -288.548572)
		(width 0.14478)
		(layer "In2.Cu")
		(net "M_C_CPU0_SB_DQ<5>")
	)
	(segment
		(start 294.04691 -289.35299)
		(end 293.884096 -289.190176)
		(width 0.14478)
		(layer "In2.Cu")
		(net "M_C_CPU0_SB_DQ<5>")
	)
	(segment
		(start 341.042498 -278.463502)
		(end 341.034116 -278.458676)
		(width 0.0889)
		(layer "In2.Cu")
		(net "M_C_CPU0_SB_DQ<5>")
	)
	(segment
		(start 304.997866 -289.93211)
		(end 304.693574 -289.93211)
		(width 0.14478)
		(layer "In2.Cu")
		(net "M_C_CPU0_SB_DQ<5>")
	)
	(segment
		(start 326.175624 -278.24811)
		(end 324.871334 -278.24811)
		(width 0.0889)
		(layer "In2.Cu")
		(net "M_C_CPU0_SB_DQ<5>")
	)
	(segment
		(start 308.958742 -288.344356)
		(end 308.797198 -288.182812)
		(width 0.14478)
		(layer "In2.Cu")
		(net "M_C_CPU0_SB_DQ<5>")
	)
	(segment
		(start 306.21986 -288.710116)
		(end 304.997866 -289.93211)
		(width 0.14478)
		(layer "In2.Cu")
		(net "M_C_CPU0_SB_DQ<5>")
	)
	(segment
		(start 302.637698 -289.17011)
		(end 302.381158 -289.17011)
		(width 0.14478)
		(layer "In2.Cu")
		(net "M_C_CPU0_SB_DQ<5>")
	)
	(segment
		(start 339.52815 -278.458676)
		(end 339.519768 -278.463502)
		(width 0.0889)
		(layer "In2.Cu")
		(net "M_C_CPU0_SB_DQ<5>")
	)
	(segment
		(start 302.381158 -289.17011)
		(end 302.029876 -289.521392)
		(width 0.14478)
		(layer "In2.Cu")
		(net "M_C_CPU0_SB_DQ<5>")
	)
	(segment
		(start 344.041222 -278.136096)
		(end 343.887044 -278.401526)
		(width 0.0889)
		(layer "In2.Cu")
		(net "M_C_CPU0_SB_DQ<5>")
	)
	(segment
		(start 308.958742 -288.548572)
		(end 308.958742 -288.344356)
		(width 0.14478)
		(layer "In2.Cu")
		(net "M_C_CPU0_SB_DQ<5>")
	)
	(segment
		(start 308.245764 -288.710116)
		(end 306.21986 -288.710116)
		(width 0.14478)
		(layer "In2.Cu")
		(net "M_C_CPU0_SB_DQ<5>")
	)
	(segment
		(start 293.884096 -289.190176)
		(end 293.653464 -289.190176)
		(width 0.14478)
		(layer "In2.Cu")
		(net "M_C_CPU0_SB_DQ<5>")
	)
	(segment
		(start 343.288112 -278.458676)
		(end 343.27973 -278.463502)
		(width 0.0889)
		(layer "In2.Cu")
		(net "M_C_CPU0_SB_DQ<5>")
	)
	(segment
		(start 324.871334 -278.24811)
		(end 324.456044 -277.83282)
		(width 0.0889)
		(layer "In2.Cu")
		(net "M_C_CPU0_SB_DQ<5>")
	)
	(segment
		(start 296.947336 -289.560254)
		(end 294.68699 -289.560254)
		(width 0.14478)
		(layer "In2.Cu")
		(net "M_C_CPU0_SB_DQ<5>")
	)
	(segment
		(start 303.74717 -289.560254)
		(end 303.027842 -289.560254)
		(width 0.14478)
		(layer "In2.Cu")
		(net "M_C_CPU0_SB_DQ<5>")
	)
	(segment
		(start 328.248264 -278.458676)
		(end 328.239882 -278.463502)
		(width 0.0889)
		(layer "In2.Cu")
		(net "M_C_CPU0_SB_DQ<5>")
	)
	(segment
		(start 335.402428 -278.463502)
		(end 335.394046 -278.458676)
		(width 0.0889)
		(layer "In2.Cu")
		(net "M_C_CPU0_SB_DQ<5>")
	)
	(segment
		(start 301.83328 -289.521392)
		(end 301.022004 -288.710116)
		(width 0.14478)
		(layer "In2.Cu")
		(net "M_C_CPU0_SB_DQ<5>")
	)
	(segment
		(start 343.887044 -278.401526)
		(end 343.790778 -278.426926)
		(width 0.0889)
		(layer "In2.Cu")
		(net "M_C_CPU0_SB_DQ<5>")
	)
	(segment
		(start 333.88808 -278.458676)
		(end 333.879698 -278.463502)
		(width 0.0889)
		(layer "In2.Cu")
		(net "M_C_CPU0_SB_DQ<5>")
	)
	(segment
		(start 297.650154 -289.88131)
		(end 297.268392 -289.88131)
		(width 0.14478)
		(layer "In2.Cu")
		(net "M_C_CPU0_SB_DQ<5>")
	)
	(segment
		(start 298.821348 -288.710116)
		(end 297.650154 -289.88131)
		(width 0.14478)
		(layer "In2.Cu")
		(net "M_C_CPU0_SB_DQ<5>")
	)
	(segment
		(start 323.906134 -277.83282)
		(end 320.181478 -277.83282)
		(width 0.14478)
		(layer "In2.Cu")
		(net "M_C_CPU0_SB_DQ<5>")
	)
	(segment
		(start 293.49065 -289.35299)
		(end 293.49065 -289.789362)
		(width 0.14478)
		(layer "In2.Cu")
		(net "M_C_CPU0_SB_DQ<5>")
	)
	(segment
		(start 340.102444 -278.463502)
		(end 340.094062 -278.458676)
		(width 0.0889)
		(layer "In2.Cu")
		(net "M_C_CPU0_SB_DQ<5>")
	)
	(segment
		(start 308.797198 -288.182812)
		(end 308.568852 -288.182812)
		(width 0.14478)
		(layer "In2.Cu")
		(net "M_C_CPU0_SB_DQ<5>")
	)
	(segment
		(start 303.027842 -289.560254)
		(end 302.637698 -289.17011)
		(width 0.14478)
		(layer "In2.Cu")
		(net "M_C_CPU0_SB_DQ<5>")
	)
	(segment
		(start 294.68699 -289.560254)
		(end 294.409114 -289.83813)
		(width 0.14478)
		(layer "In2.Cu")
		(net "M_C_CPU0_SB_DQ<5>")
	)
	(segment
		(start 293.327836 -289.952176)
		(end 293.097204 -289.952176)
		(width 0.14478)
		(layer "In2.Cu")
		(net "M_C_CPU0_SB_DQ<5>")
	)
	(segment
		(start 301.022004 -288.710116)
		(end 298.821348 -288.710116)
		(width 0.14478)
		(layer "In2.Cu")
		(net "M_C_CPU0_SB_DQ<5>")
	)
	(segment
		(start 293.653464 -289.190176)
		(end 293.49065 -289.35299)
		(width 0.14478)
		(layer "In2.Cu")
		(net "M_C_CPU0_SB_DQ<5>")
	)
	(arc
		(start 328.239882 -278.463502)
		(mid 328.05612 -278.509118)
		(end 327.873614 -278.458676)
		(width 0.0889)
		(layer "In2.Cu")
		(net "M_C_CPU0_SB_DQ<5>")
	)
	(arc
		(start 331.634084 -278.458676)
		(mid 331.351128 -278.382499)
		(end 331.068172 -278.458676)
		(width 0.0889)
		(layer "In2.Cu")
		(net "M_C_CPU0_SB_DQ<5>")
	)
	(arc
		(start 342.91397 -278.458676)
		(mid 342.631014 -278.382499)
		(end 342.348058 -278.458676)
		(width 0.0889)
		(layer "In2.Cu")
		(net "M_C_CPU0_SB_DQ<5>")
	)
	(arc
		(start 330.69403 -278.458676)
		(mid 330.411074 -278.382499)
		(end 330.128118 -278.458676)
		(width 0.0889)
		(layer "In2.Cu")
		(net "M_C_CPU0_SB_DQ<5>")
	)
	(arc
		(start 326.90689 -278.443182)
		(mid 326.554035 -278.29776)
		(end 326.175624 -278.24811)
		(width 0.0889)
		(layer "In2.Cu")
		(net "M_C_CPU0_SB_DQ<5>")
	)
	(arc
		(start 341.97417 -278.458676)
		(mid 341.691214 -278.382499)
		(end 341.408258 -278.458676)
		(width 0.0889)
		(layer "In2.Cu")
		(net "M_C_CPU0_SB_DQ<5>")
	)
	(arc
		(start 331.068172 -278.458676)
		(mid 330.885921 -278.509026)
		(end 330.702412 -278.463502)
		(width 0.0889)
		(layer "In2.Cu")
		(net "M_C_CPU0_SB_DQ<5>")
	)
	(arc
		(start 328.814176 -278.458676)
		(mid 328.53122 -278.382499)
		(end 328.248264 -278.458676)
		(width 0.0889)
		(layer "In2.Cu")
		(net "M_C_CPU0_SB_DQ<5>")
	)
	(arc
		(start 329.753976 -278.458676)
		(mid 329.47102 -278.382499)
		(end 329.188064 -278.458676)
		(width 0.0889)
		(layer "In2.Cu")
		(net "M_C_CPU0_SB_DQ<5>")
	)
	(arc
		(start 335.768188 -278.458676)
		(mid 335.585937 -278.509026)
		(end 335.402428 -278.463502)
		(width 0.0889)
		(layer "In2.Cu")
		(net "M_C_CPU0_SB_DQ<5>")
	)
	(arc
		(start 327.873614 -278.458676)
		(mid 327.598908 -278.382312)
		(end 327.321926 -278.45004)
		(width 0.0889)
		(layer "In2.Cu")
		(net "M_C_CPU0_SB_DQ<5>")
	)
	(arc
		(start 337.648042 -278.458676)
		(mid 337.461098 -278.508931)
		(end 337.274154 -278.458676)
		(width 0.0889)
		(layer "In2.Cu")
		(net "M_C_CPU0_SB_DQ<5>")
	)
	(arc
		(start 340.094062 -278.458676)
		(mid 339.811106 -278.382499)
		(end 339.52815 -278.458676)
		(width 0.0889)
		(layer "In2.Cu")
		(net "M_C_CPU0_SB_DQ<5>")
	)
	(arc
		(start 333.513938 -278.458676)
		(mid 333.230982 -278.382499)
		(end 332.948026 -278.458676)
		(width 0.0889)
		(layer "In2.Cu")
		(net "M_C_CPU0_SB_DQ<5>")
	)
	(arc
		(start 338.579714 -278.463502)
		(mid 338.396206 -278.508996)
		(end 338.213954 -278.458676)
		(width 0.0889)
		(layer "In2.Cu")
		(net "M_C_CPU0_SB_DQ<5>")
	)
	(arc
		(start 334.453992 -278.458676)
		(mid 334.171036 -278.382499)
		(end 333.88808 -278.458676)
		(width 0.0889)
		(layer "In2.Cu")
		(net "M_C_CPU0_SB_DQ<5>")
	)
	(arc
		(start 333.879698 -278.463502)
		(mid 333.69619 -278.508996)
		(end 333.513938 -278.458676)
		(width 0.0889)
		(layer "In2.Cu")
		(net "M_C_CPU0_SB_DQ<5>")
	)
	(arc
		(start 343.790778 -278.426926)
		(mid 343.535713 -278.383575)
		(end 343.288112 -278.458676)
		(width 0.0889)
		(layer "In2.Cu")
		(net "M_C_CPU0_SB_DQ<5>")
	)
	(arc
		(start 327.307194 -278.458676)
		(mid 327.128207 -278.508846)
		(end 326.947276 -278.466296)
		(width 0.0889)
		(layer "In2.Cu")
		(net "M_C_CPU0_SB_DQ<5>")
	)
	(arc
		(start 332.574138 -278.458676)
		(mid 332.291182 -278.382499)
		(end 332.008226 -278.458676)
		(width 0.0889)
		(layer "In2.Cu")
		(net "M_C_CPU0_SB_DQ<5>")
	)
	(arc
		(start 343.27973 -278.463502)
		(mid 343.096222 -278.508996)
		(end 342.91397 -278.458676)
		(width 0.0889)
		(layer "In2.Cu")
		(net "M_C_CPU0_SB_DQ<5>")
	)
	(arc
		(start 342.348058 -278.458676)
		(mid 342.161114 -278.508931)
		(end 341.97417 -278.458676)
		(width 0.0889)
		(layer "In2.Cu")
		(net "M_C_CPU0_SB_DQ<5>")
	)
	(arc
		(start 341.034116 -278.458676)
		(mid 340.75116 -278.382499)
		(end 340.468204 -278.458676)
		(width 0.0889)
		(layer "In2.Cu")
		(net "M_C_CPU0_SB_DQ<5>")
	)
	(arc
		(start 341.408258 -278.458676)
		(mid 341.226007 -278.509026)
		(end 341.042498 -278.463502)
		(width 0.0889)
		(layer "In2.Cu")
		(net "M_C_CPU0_SB_DQ<5>")
	)
	(arc
		(start 338.213954 -278.458676)
		(mid 337.930998 -278.382499)
		(end 337.648042 -278.458676)
		(width 0.0889)
		(layer "In2.Cu")
		(net "M_C_CPU0_SB_DQ<5>")
	)
	(arc
		(start 339.154008 -278.458676)
		(mid 338.871052 -278.382499)
		(end 338.588096 -278.458676)
		(width 0.0889)
		(layer "In2.Cu")
		(net "M_C_CPU0_SB_DQ<5>")
	)
	(arc
		(start 339.519768 -278.463502)
		(mid 339.33626 -278.508996)
		(end 339.154008 -278.458676)
		(width 0.0889)
		(layer "In2.Cu")
		(net "M_C_CPU0_SB_DQ<5>")
	)
	(arc
		(start 337.274154 -278.458676)
		(mid 336.991198 -278.382499)
		(end 336.708242 -278.458676)
		(width 0.0889)
		(layer "In2.Cu")
		(net "M_C_CPU0_SB_DQ<5>")
	)
	(arc
		(start 336.708242 -278.458676)
		(mid 336.525991 -278.509026)
		(end 336.342482 -278.463502)
		(width 0.0889)
		(layer "In2.Cu")
		(net "M_C_CPU0_SB_DQ<5>")
	)
	(arc
		(start 330.119736 -278.463502)
		(mid 329.936228 -278.508996)
		(end 329.753976 -278.458676)
		(width 0.0889)
		(layer "In2.Cu")
		(net "M_C_CPU0_SB_DQ<5>")
	)
	(arc
		(start 329.188064 -278.458676)
		(mid 329.00112 -278.508931)
		(end 328.814176 -278.458676)
		(width 0.0889)
		(layer "In2.Cu")
		(net "M_C_CPU0_SB_DQ<5>")
	)
	(arc
		(start 332.948026 -278.458676)
		(mid 332.761082 -278.508931)
		(end 332.574138 -278.458676)
		(width 0.0889)
		(layer "In2.Cu")
		(net "M_C_CPU0_SB_DQ<5>")
	)
	(arc
		(start 340.468204 -278.458676)
		(mid 340.285953 -278.509026)
		(end 340.102444 -278.463502)
		(width 0.0889)
		(layer "In2.Cu")
		(net "M_C_CPU0_SB_DQ<5>")
	)
	(arc
		(start 332.008226 -278.458676)
		(mid 331.825975 -278.509026)
		(end 331.642466 -278.463502)
		(width 0.0889)
		(layer "In2.Cu")
		(net "M_C_CPU0_SB_DQ<5>")
	)
	(arc
		(start 334.819752 -278.463502)
		(mid 334.636244 -278.508996)
		(end 334.453992 -278.458676)
		(width 0.0889)
		(layer "In2.Cu")
		(net "M_C_CPU0_SB_DQ<5>")
	)
	(arc
		(start 335.394046 -278.458676)
		(mid 335.11109 -278.382499)
		(end 334.828134 -278.458676)
		(width 0.0889)
		(layer "In2.Cu")
		(net "M_C_CPU0_SB_DQ<5>")
	)
	(arc
		(start 336.3341 -278.458676)
		(mid 336.051144 -278.382499)
		(end 335.768188 -278.458676)
		(width 0.0889)
		(layer "In2.Cu")
		(net "M_C_CPU0_SB_DQ<5>")
	)
	(segment
		(start 343.097866 -277.060152)
		(end 342.631014 -277.32609)
		(width 0.10668)
		(layer "F.Cu")
		(net "M_C_CPU0_SB_DQ<4>")
	)
	(segment
		(start 294.361108 -288.24555)
		(end 294.193468 -288.24555)
		(width 0.14478)
		(layer "In2.Cu")
		(net "M_C_CPU0_SB_DQ<4>")
	)
	(segment
		(start 297.349418 -288.650172)
		(end 297.06189 -288.650172)
		(width 0.14478)
		(layer "In2.Cu")
		(net "M_C_CPU0_SB_DQ<4>")
	)
	(segment
		(start 309.731918 -287.010094)
		(end 309.48503 -287.010094)
		(width 0.14478)
		(layer "In2.Cu")
		(net "M_C_CPU0_SB_DQ<4>")
	)
	(segment
		(start 293.636954 -287.35909)
		(end 293.473886 -287.522158)
		(width 0.14478)
		(layer "In2.Cu")
		(net "M_C_CPU0_SB_DQ<4>")
	)
	(segment
		(start 294.0304 -288.082482)
		(end 294.0304 -287.522158)
		(width 0.14478)
		(layer "In2.Cu")
		(net "M_C_CPU0_SB_DQ<4>")
	)
	(segment
		(start 298.830238 -287.019746)
		(end 298.396914 -287.45307)
		(width 0.14478)
		(layer "In2.Cu")
		(net "M_C_CPU0_SB_DQ<4>")
	)
	(segment
		(start 328.344022 -277.64867)
		(end 328.312272 -277.630128)
		(width 0.0889)
		(layer "In2.Cu")
		(net "M_C_CPU0_SB_DQ<4>")
	)
	(segment
		(start 296.869358 -288.022792)
		(end 296.71645 -287.869884)
		(width 0.14478)
		(layer "In2.Cu")
		(net "M_C_CPU0_SB_DQ<4>")
	)
	(segment
		(start 301.980854 -288.12871)
		(end 301.752 -288.12871)
		(width 0.14478)
		(layer "In2.Cu")
		(net "M_C_CPU0_SB_DQ<4>")
	)
	(segment
		(start 297.06189 -288.650172)
		(end 296.869358 -288.45764)
		(width 0.14478)
		(layer "In2.Cu")
		(net "M_C_CPU0_SB_DQ<4>")
	)
	(segment
		(start 332.478126 -277.64867)
		(end 332.469744 -277.653496)
		(width 0.0889)
		(layer "In2.Cu")
		(net "M_C_CPU0_SB_DQ<4>")
	)
	(segment
		(start 305.745896 -287.894268)
		(end 305.582574 -288.05759)
		(width 0.14478)
		(layer "In2.Cu")
		(net "M_C_CPU0_SB_DQ<4>")
	)
	(segment
		(start 319.818512 -276.9235)
		(end 309.731918 -287.010094)
		(width 0.14478)
		(layer "In2.Cu")
		(net "M_C_CPU0_SB_DQ<4>")
	)
	(segment
		(start 308.699154 -287.010094)
		(end 305.82235 -287.010094)
		(width 0.14478)
		(layer "In2.Cu")
		(net "M_C_CPU0_SB_DQ<4>")
	)
	(segment
		(start 308.933596 -286.775652)
		(end 308.699154 -287.010094)
		(width 0.14478)
		(layer "In2.Cu")
		(net "M_C_CPU0_SB_DQ<4>")
	)
	(segment
		(start 301.533814 -287.910524)
		(end 301.533814 -287.47847)
		(width 0.14478)
		(layer "In2.Cu")
		(net "M_C_CPU0_SB_DQ<4>")
	)
	(segment
		(start 297.53941 -288.46018)
		(end 297.349418 -288.650172)
		(width 0.14478)
		(layer "In2.Cu")
		(net "M_C_CPU0_SB_DQ<4>")
	)
	(segment
		(start 337.178142 -277.64867)
		(end 337.16976 -277.653496)
		(width 0.0889)
		(layer "In2.Cu")
		(net "M_C_CPU0_SB_DQ<4>")
	)
	(segment
		(start 293.310818 -288.24555)
		(end 293.0906 -288.24555)
		(width 0.14478)
		(layer "In2.Cu")
		(net "M_C_CPU0_SB_DQ<4>")
	)
	(segment
		(start 337.752436 -277.653496)
		(end 337.744054 -277.64867)
		(width 0.0889)
		(layer "In2.Cu")
		(net "M_C_CPU0_SB_DQ<4>")
	)
	(segment
		(start 304.93589 -287.896554)
		(end 304.724816 -288.107628)
		(width 0.14478)
		(layer "In2.Cu")
		(net "M_C_CPU0_SB_DQ<4>")
	)
	(segment
		(start 338.69249 -277.653496)
		(end 338.684108 -277.64867)
		(width 0.0889)
		(layer "In2.Cu")
		(net "M_C_CPU0_SB_DQ<4>")
	)
	(segment
		(start 328.718164 -277.64867)
		(end 328.709782 -277.653496)
		(width 0.0889)
		(layer "In2.Cu")
		(net "M_C_CPU0_SB_DQ<4>")
	)
	(segment
		(start 336.238088 -277.64867)
		(end 336.229706 -277.653496)
		(width 0.0889)
		(layer "In2.Cu")
		(net "M_C_CPU0_SB_DQ<4>")
	)
	(segment
		(start 296.869358 -288.45764)
		(end 296.869358 -288.022792)
		(width 0.14478)
		(layer "In2.Cu")
		(net "M_C_CPU0_SB_DQ<4>")
	)
	(segment
		(start 333.05242 -277.653496)
		(end 333.044038 -277.64867)
		(width 0.0889)
		(layer "In2.Cu")
		(net "M_C_CPU0_SB_DQ<4>")
	)
	(segment
		(start 305.35245 -288.05759)
		(end 305.191414 -287.896554)
		(width 0.14478)
		(layer "In2.Cu")
		(net "M_C_CPU0_SB_DQ<4>")
	)
	(segment
		(start 324.354444 -276.9235)
		(end 323.897244 -276.9235)
		(width 0.0889)
		(layer "In2.Cu")
		(net "M_C_CPU0_SB_DQ<4>")
	)
	(segment
		(start 293.867332 -287.35909)
		(end 293.636954 -287.35909)
		(width 0.14478)
		(layer "In2.Cu")
		(net "M_C_CPU0_SB_DQ<4>")
	)
	(segment
		(start 293.0906 -288.24555)
		(end 292.280086 -287.435036)
		(width 0.14478)
		(layer "In2.Cu")
		(net "M_C_CPU0_SB_DQ<4>")
	)
	(segment
		(start 323.897244 -276.9235)
		(end 319.818512 -276.9235)
		(width 0.14478)
		(layer "In2.Cu")
		(net "M_C_CPU0_SB_DQ<4>")
	)
	(segment
		(start 326.670924 -277.692866)
		(end 326.276208 -277.692866)
		(width 0.0889)
		(layer "In2.Cu")
		(net "M_C_CPU0_SB_DQ<4>")
	)
	(segment
		(start 305.82235 -287.010094)
		(end 305.58486 -287.247584)
		(width 0.14478)
		(layer "In2.Cu")
		(net "M_C_CPU0_SB_DQ<4>")
	)
	(segment
		(start 325.8947 -277.311358)
		(end 324.742302 -277.311358)
		(width 0.0889)
		(layer "In2.Cu")
		(net "M_C_CPU0_SB_DQ<4>")
	)
	(segment
		(start 305.582574 -288.05759)
		(end 305.35245 -288.05759)
		(width 0.14478)
		(layer "In2.Cu")
		(net "M_C_CPU0_SB_DQ<4>")
	)
	(segment
		(start 305.745896 -287.664144)
		(end 305.745896 -287.894268)
		(width 0.14478)
		(layer "In2.Cu")
		(net "M_C_CPU0_SB_DQ<4>")
	)
	(segment
		(start 293.473886 -287.522158)
		(end 293.473886 -288.082482)
		(width 0.14478)
		(layer "In2.Cu")
		(net "M_C_CPU0_SB_DQ<4>")
	)
	(segment
		(start 304.724816 -288.107628)
		(end 304.512726 -288.107628)
		(width 0.14478)
		(layer "In2.Cu")
		(net "M_C_CPU0_SB_DQ<4>")
	)
	(segment
		(start 342.47709 -277.59152)
		(end 342.381078 -277.61692)
		(width 0.0889)
		(layer "In2.Cu")
		(net "M_C_CPU0_SB_DQ<4>")
	)
	(segment
		(start 324.742302 -277.311358)
		(end 324.354444 -276.9235)
		(width 0.0889)
		(layer "In2.Cu")
		(net "M_C_CPU0_SB_DQ<4>")
	)
	(segment
		(start 300.961044 -287.286954)
		(end 300.693836 -287.019746)
		(width 0.14478)
		(layer "In2.Cu")
		(net "M_C_CPU0_SB_DQ<4>")
	)
	(segment
		(start 326.276208 -277.692866)
		(end 325.8947 -277.311358)
		(width 0.0889)
		(layer "In2.Cu")
		(net "M_C_CPU0_SB_DQ<4>")
	)
	(segment
		(start 305.191414 -287.896554)
		(end 304.93589 -287.896554)
		(width 0.14478)
		(layer "In2.Cu")
		(net "M_C_CPU0_SB_DQ<4>")
	)
	(segment
		(start 341.878158 -277.64867)
		(end 341.869776 -277.653496)
		(width 0.0889)
		(layer "In2.Cu")
		(net "M_C_CPU0_SB_DQ<4>")
	)
	(segment
		(start 297.68927 -287.21431)
		(end 297.53941 -287.36417)
		(width 0.14478)
		(layer "In2.Cu")
		(net "M_C_CPU0_SB_DQ<4>")
	)
	(segment
		(start 304.512726 -288.107628)
		(end 304.26533 -287.860232)
		(width 0.14478)
		(layer "In2.Cu")
		(net "M_C_CPU0_SB_DQ<4>")
	)
	(segment
		(start 298.396914 -287.45307)
		(end 298.18457 -287.45307)
		(width 0.14478)
		(layer "In2.Cu")
		(net "M_C_CPU0_SB_DQ<4>")
	)
	(segment
		(start 294.193468 -288.24555)
		(end 294.0304 -288.082482)
		(width 0.14478)
		(layer "In2.Cu")
		(net "M_C_CPU0_SB_DQ<4>")
	)
	(segment
		(start 300.693836 -287.019746)
		(end 298.830238 -287.019746)
		(width 0.14478)
		(layer "In2.Cu")
		(net "M_C_CPU0_SB_DQ<4>")
	)
	(segment
		(start 305.58486 -287.503108)
		(end 305.745896 -287.664144)
		(width 0.14478)
		(layer "In2.Cu")
		(net "M_C_CPU0_SB_DQ<4>")
	)
	(segment
		(start 297.53941 -287.36417)
		(end 297.53941 -288.46018)
		(width 0.14478)
		(layer "In2.Cu")
		(net "M_C_CPU0_SB_DQ<4>")
	)
	(segment
		(start 301.342298 -287.286954)
		(end 300.961044 -287.286954)
		(width 0.14478)
		(layer "In2.Cu")
		(net "M_C_CPU0_SB_DQ<4>")
	)
	(segment
		(start 342.631014 -277.32609)
		(end 342.47709 -277.59152)
		(width 0.0889)
		(layer "In2.Cu")
		(net "M_C_CPU0_SB_DQ<4>")
	)
	(segment
		(start 305.58486 -287.247584)
		(end 305.58486 -287.503108)
		(width 0.14478)
		(layer "In2.Cu")
		(net "M_C_CPU0_SB_DQ<4>")
	)
	(segment
		(start 301.752 -288.12871)
		(end 301.533814 -287.910524)
		(width 0.14478)
		(layer "In2.Cu")
		(net "M_C_CPU0_SB_DQ<4>")
	)
	(segment
		(start 329.292458 -277.653496)
		(end 329.284076 -277.64867)
		(width 0.0889)
		(layer "In2.Cu")
		(net "M_C_CPU0_SB_DQ<4>")
	)
	(segment
		(start 331.538072 -277.64867)
		(end 331.52969 -277.653496)
		(width 0.0889)
		(layer "In2.Cu")
		(net "M_C_CPU0_SB_DQ<4>")
	)
	(segment
		(start 333.992474 -277.653496)
		(end 333.984092 -277.64867)
		(width 0.0889)
		(layer "In2.Cu")
		(net "M_C_CPU0_SB_DQ<4>")
	)
	(segment
		(start 326.869298 -277.629112)
		(end 326.836024 -277.648416)
		(width 0.0889)
		(layer "In2.Cu")
		(net "M_C_CPU0_SB_DQ<4>")
	)
	(segment
		(start 327.42505 -277.66391)
		(end 327.398888 -277.64867)
		(width 0.0889)
		(layer "In2.Cu")
		(net "M_C_CPU0_SB_DQ<4>")
	)
	(segment
		(start 298.18457 -287.45307)
		(end 297.94581 -287.21431)
		(width 0.14478)
		(layer "In2.Cu")
		(net "M_C_CPU0_SB_DQ<4>")
	)
	(segment
		(start 297.94581 -287.21431)
		(end 297.68927 -287.21431)
		(width 0.14478)
		(layer "In2.Cu")
		(net "M_C_CPU0_SB_DQ<4>")
	)
	(segment
		(start 296.71645 -287.869884)
		(end 294.736774 -287.869884)
		(width 0.14478)
		(layer "In2.Cu")
		(net "M_C_CPU0_SB_DQ<4>")
	)
	(segment
		(start 302.249332 -287.860232)
		(end 301.980854 -288.12871)
		(width 0.14478)
		(layer "In2.Cu")
		(net "M_C_CPU0_SB_DQ<4>")
	)
	(segment
		(start 304.26533 -287.860232)
		(end 302.249332 -287.860232)
		(width 0.14478)
		(layer "In2.Cu")
		(net "M_C_CPU0_SB_DQ<4>")
	)
	(segment
		(start 293.473886 -288.082482)
		(end 293.310818 -288.24555)
		(width 0.14478)
		(layer "In2.Cu")
		(net "M_C_CPU0_SB_DQ<4>")
	)
	(segment
		(start 301.533814 -287.47847)
		(end 301.342298 -287.286954)
		(width 0.14478)
		(layer "In2.Cu")
		(net "M_C_CPU0_SB_DQ<4>")
	)
	(segment
		(start 294.736774 -287.869884)
		(end 294.361108 -288.24555)
		(width 0.14478)
		(layer "In2.Cu")
		(net "M_C_CPU0_SB_DQ<4>")
	)
	(segment
		(start 309.48503 -287.010094)
		(end 309.250588 -286.775652)
		(width 0.14478)
		(layer "In2.Cu")
		(net "M_C_CPU0_SB_DQ<4>")
	)
	(segment
		(start 294.0304 -287.522158)
		(end 293.867332 -287.35909)
		(width 0.14478)
		(layer "In2.Cu")
		(net "M_C_CPU0_SB_DQ<4>")
	)
	(segment
		(start 309.250588 -286.775652)
		(end 308.933596 -286.775652)
		(width 0.14478)
		(layer "In2.Cu")
		(net "M_C_CPU0_SB_DQ<4>")
	)
	(segment
		(start 340.938104 -277.64867)
		(end 340.929722 -277.653496)
		(width 0.0889)
		(layer "In2.Cu")
		(net "M_C_CPU0_SB_DQ<4>")
	)
	(arc
		(start 334.924146 -277.64867)
		(mid 334.64119 -277.572493)
		(end 334.358234 -277.64867)
		(width 0.0889)
		(layer "In2.Cu")
		(net "M_C_CPU0_SB_DQ<4>")
	)
	(arc
		(start 329.284076 -277.64867)
		(mid 329.00112 -277.572493)
		(end 328.718164 -277.64867)
		(width 0.0889)
		(layer "In2.Cu")
		(net "M_C_CPU0_SB_DQ<4>")
	)
	(arc
		(start 328.312272 -277.630128)
		(mid 328.041401 -277.571542)
		(end 327.775316 -277.648924)
		(width 0.0889)
		(layer "In2.Cu")
		(net "M_C_CPU0_SB_DQ<4>")
	)
	(arc
		(start 333.41818 -277.64867)
		(mid 333.235929 -277.69902)
		(end 333.05242 -277.653496)
		(width 0.0889)
		(layer "In2.Cu")
		(net "M_C_CPU0_SB_DQ<4>")
	)
	(arc
		(start 328.709782 -277.653496)
		(mid 328.526274 -277.69899)
		(end 328.344022 -277.64867)
		(width 0.0889)
		(layer "In2.Cu")
		(net "M_C_CPU0_SB_DQ<4>")
	)
	(arc
		(start 330.22413 -277.64867)
		(mid 329.941174 -277.572493)
		(end 329.658218 -277.64867)
		(width 0.0889)
		(layer "In2.Cu")
		(net "M_C_CPU0_SB_DQ<4>")
	)
	(arc
		(start 339.05825 -277.64867)
		(mid 338.875999 -277.69902)
		(end 338.69249 -277.653496)
		(width 0.0889)
		(layer "In2.Cu")
		(net "M_C_CPU0_SB_DQ<4>")
	)
	(arc
		(start 335.863946 -277.64867)
		(mid 335.58099 -277.572493)
		(end 335.298034 -277.64867)
		(width 0.0889)
		(layer "In2.Cu")
		(net "M_C_CPU0_SB_DQ<4>")
	)
	(arc
		(start 330.598018 -277.64867)
		(mid 330.411074 -277.698925)
		(end 330.22413 -277.64867)
		(width 0.0889)
		(layer "In2.Cu")
		(net "M_C_CPU0_SB_DQ<4>")
	)
	(arc
		(start 333.984092 -277.64867)
		(mid 333.701136 -277.572493)
		(end 333.41818 -277.64867)
		(width 0.0889)
		(layer "In2.Cu")
		(net "M_C_CPU0_SB_DQ<4>")
	)
	(arc
		(start 339.99805 -277.64867)
		(mid 339.811106 -277.698925)
		(end 339.624162 -277.64867)
		(width 0.0889)
		(layer "In2.Cu")
		(net "M_C_CPU0_SB_DQ<4>")
	)
	(arc
		(start 326.836024 -277.648416)
		(mid 326.756407 -277.681525)
		(end 326.670924 -277.692866)
		(width 0.0889)
		(layer "In2.Cu")
		(net "M_C_CPU0_SB_DQ<4>")
	)
	(arc
		(start 338.684108 -277.64867)
		(mid 338.401152 -277.572493)
		(end 338.118196 -277.64867)
		(width 0.0889)
		(layer "In2.Cu")
		(net "M_C_CPU0_SB_DQ<4>")
	)
	(arc
		(start 339.624162 -277.64867)
		(mid 339.341206 -277.572493)
		(end 339.05825 -277.64867)
		(width 0.0889)
		(layer "In2.Cu")
		(net "M_C_CPU0_SB_DQ<4>")
	)
	(arc
		(start 331.16393 -277.64867)
		(mid 330.880974 -277.572493)
		(end 330.598018 -277.64867)
		(width 0.0889)
		(layer "In2.Cu")
		(net "M_C_CPU0_SB_DQ<4>")
	)
	(arc
		(start 340.563962 -277.64867)
		(mid 340.281006 -277.572493)
		(end 339.99805 -277.64867)
		(width 0.0889)
		(layer "In2.Cu")
		(net "M_C_CPU0_SB_DQ<4>")
	)
	(arc
		(start 332.469744 -277.653496)
		(mid 332.286236 -277.69899)
		(end 332.103984 -277.64867)
		(width 0.0889)
		(layer "In2.Cu")
		(net "M_C_CPU0_SB_DQ<4>")
	)
	(arc
		(start 336.804 -277.64867)
		(mid 336.521044 -277.572493)
		(end 336.238088 -277.64867)
		(width 0.0889)
		(layer "In2.Cu")
		(net "M_C_CPU0_SB_DQ<4>")
	)
	(arc
		(start 337.744054 -277.64867)
		(mid 337.461098 -277.572493)
		(end 337.178142 -277.64867)
		(width 0.0889)
		(layer "In2.Cu")
		(net "M_C_CPU0_SB_DQ<4>")
	)
	(arc
		(start 337.16976 -277.653496)
		(mid 336.986252 -277.69899)
		(end 336.804 -277.64867)
		(width 0.0889)
		(layer "In2.Cu")
		(net "M_C_CPU0_SB_DQ<4>")
	)
	(arc
		(start 335.298034 -277.64867)
		(mid 335.11109 -277.698925)
		(end 334.924146 -277.64867)
		(width 0.0889)
		(layer "In2.Cu")
		(net "M_C_CPU0_SB_DQ<4>")
	)
	(arc
		(start 334.358234 -277.64867)
		(mid 334.175983 -277.69902)
		(end 333.992474 -277.653496)
		(width 0.0889)
		(layer "In2.Cu")
		(net "M_C_CPU0_SB_DQ<4>")
	)
	(arc
		(start 341.869776 -277.653496)
		(mid 341.686268 -277.69899)
		(end 341.504016 -277.64867)
		(width 0.0889)
		(layer "In2.Cu")
		(net "M_C_CPU0_SB_DQ<4>")
	)
	(arc
		(start 327.775316 -277.648924)
		(mid 327.60205 -277.699955)
		(end 327.42505 -277.66391)
		(width 0.0889)
		(layer "In2.Cu")
		(net "M_C_CPU0_SB_DQ<4>")
	)
	(arc
		(start 333.044038 -277.64867)
		(mid 332.761082 -277.572493)
		(end 332.478126 -277.64867)
		(width 0.0889)
		(layer "In2.Cu")
		(net "M_C_CPU0_SB_DQ<4>")
	)
	(arc
		(start 342.381078 -277.61692)
		(mid 342.12587 -277.573443)
		(end 341.878158 -277.64867)
		(width 0.0889)
		(layer "In2.Cu")
		(net "M_C_CPU0_SB_DQ<4>")
	)
	(arc
		(start 340.929722 -277.653496)
		(mid 340.746214 -277.69899)
		(end 340.563962 -277.64867)
		(width 0.0889)
		(layer "In2.Cu")
		(net "M_C_CPU0_SB_DQ<4>")
	)
	(arc
		(start 327.398888 -277.64867)
		(mid 327.136529 -277.572751)
		(end 326.869298 -277.629112)
		(width 0.0889)
		(layer "In2.Cu")
		(net "M_C_CPU0_SB_DQ<4>")
	)
	(arc
		(start 331.52969 -277.653496)
		(mid 331.346182 -277.69899)
		(end 331.16393 -277.64867)
		(width 0.0889)
		(layer "In2.Cu")
		(net "M_C_CPU0_SB_DQ<4>")
	)
	(arc
		(start 336.229706 -277.653496)
		(mid 336.046198 -277.69899)
		(end 335.863946 -277.64867)
		(width 0.0889)
		(layer "In2.Cu")
		(net "M_C_CPU0_SB_DQ<4>")
	)
	(arc
		(start 329.658218 -277.64867)
		(mid 329.475967 -277.69902)
		(end 329.292458 -277.653496)
		(width 0.0889)
		(layer "In2.Cu")
		(net "M_C_CPU0_SB_DQ<4>")
	)
	(arc
		(start 341.504016 -277.64867)
		(mid 341.22106 -277.572493)
		(end 340.938104 -277.64867)
		(width 0.0889)
		(layer "In2.Cu")
		(net "M_C_CPU0_SB_DQ<4>")
	)
	(arc
		(start 338.118196 -277.64867)
		(mid 337.935945 -277.69902)
		(end 337.752436 -277.653496)
		(width 0.0889)
		(layer "In2.Cu")
		(net "M_C_CPU0_SB_DQ<4>")
	)
	(arc
		(start 332.103984 -277.64867)
		(mid 331.821028 -277.572493)
		(end 331.538072 -277.64867)
		(width 0.0889)
		(layer "In2.Cu")
		(net "M_C_CPU0_SB_DQ<4>")
	)
	(segment
		(start 344.03792 -275.44014)
		(end 343.571068 -275.706078)
		(width 0.10668)
		(layer "F.Cu")
		(net "M_C_CPU0_SB_DQ<3>")
	)
	(segment
		(start 288.605214 -284.460188)
		(end 288.180018 -284.034992)
		(width 0.14478)
		(layer "In2.Cu")
		(net "M_C_CPU0_SB_DQ<3>")
	)
	(segment
		(start 289.512756 -284.059884)
		(end 289.512756 -284.297374)
		(width 0.14478)
		(layer "In2.Cu")
		(net "M_C_CPU0_SB_DQ<3>")
	)
	(segment
		(start 301.323756 -283.600398)
		(end 297.66006 -283.600398)
		(width 0.14478)
		(layer "In2.Cu")
		(net "M_C_CPU0_SB_DQ<3>")
	)
	(segment
		(start 333.992474 -275.378672)
		(end 333.984092 -275.383498)
		(width 0.0889)
		(layer "In2.Cu")
		(net "M_C_CPU0_SB_DQ<3>")
	)
	(segment
		(start 297.66006 -283.600398)
		(end 296.810176 -284.450282)
		(width 0.14478)
		(layer "In2.Cu")
		(net "M_C_CPU0_SB_DQ<3>")
	)
	(segment
		(start 337.178142 -275.383498)
		(end 337.16976 -275.378672)
		(width 0.0889)
		(layer "In2.Cu")
		(net "M_C_CPU0_SB_DQ<3>")
	)
	(segment
		(start 308.272942 -283.61005)
		(end 305.737768 -283.61005)
		(width 0.14478)
		(layer "In2.Cu")
		(net "M_C_CPU0_SB_DQ<3>")
	)
	(segment
		(start 290.069016 -284.297374)
		(end 290.069016 -284.059884)
		(width 0.14478)
		(layer "In2.Cu")
		(net "M_C_CPU0_SB_DQ<3>")
	)
	(segment
		(start 342.452452 -275.378672)
		(end 342.44407 -275.383498)
		(width 0.0889)
		(layer "In2.Cu")
		(net "M_C_CPU0_SB_DQ<3>")
	)
	(segment
		(start 318.394588 -274.58416)
		(end 312.192416 -280.786332)
		(width 0.14478)
		(layer "In2.Cu")
		(net "M_C_CPU0_SB_DQ<3>")
	)
	(segment
		(start 343.392506 -275.378672)
		(end 343.384124 -275.383498)
		(width 0.0889)
		(layer "In2.Cu")
		(net "M_C_CPU0_SB_DQ<3>")
	)
	(segment
		(start 296.810176 -284.450282)
		(end 290.221924 -284.450282)
		(width 0.14478)
		(layer "In2.Cu")
		(net "M_C_CPU0_SB_DQ<3>")
	)
	(segment
		(start 304.88763 -284.460188)
		(end 302.183546 -284.460188)
		(width 0.14478)
		(layer "In2.Cu")
		(net "M_C_CPU0_SB_DQ<3>")
	)
	(segment
		(start 302.183546 -284.460188)
		(end 301.323756 -283.600398)
		(width 0.14478)
		(layer "In2.Cu")
		(net "M_C_CPU0_SB_DQ<3>")
	)
	(segment
		(start 289.906202 -283.89707)
		(end 289.67557 -283.89707)
		(width 0.14478)
		(layer "In2.Cu")
		(net "M_C_CPU0_SB_DQ<3>")
	)
	(segment
		(start 338.69249 -275.378672)
		(end 338.684108 -275.383498)
		(width 0.0889)
		(layer "In2.Cu")
		(net "M_C_CPU0_SB_DQ<3>")
	)
	(segment
		(start 341.878158 -275.383498)
		(end 341.869776 -275.378672)
		(width 0.0889)
		(layer "In2.Cu")
		(net "M_C_CPU0_SB_DQ<3>")
	)
	(segment
		(start 328.344022 -275.383498)
		(end 328.32929 -275.392134)
		(width 0.0889)
		(layer "In2.Cu")
		(net "M_C_CPU0_SB_DQ<3>")
	)
	(segment
		(start 331.538072 -275.383498)
		(end 331.52969 -275.378672)
		(width 0.0889)
		(layer "In2.Cu")
		(net "M_C_CPU0_SB_DQ<3>")
	)
	(segment
		(start 343.571068 -275.706078)
		(end 343.725246 -275.440648)
		(width 0.0889)
		(layer "In2.Cu")
		(net "M_C_CPU0_SB_DQ<3>")
	)
	(segment
		(start 333.05242 -275.378672)
		(end 333.044038 -275.383498)
		(width 0.0889)
		(layer "In2.Cu")
		(net "M_C_CPU0_SB_DQ<3>")
	)
	(segment
		(start 323.880734 -274.58416)
		(end 318.394588 -274.58416)
		(width 0.14478)
		(layer "In2.Cu")
		(net "M_C_CPU0_SB_DQ<3>")
	)
	(segment
		(start 328.718164 -275.383498)
		(end 328.709782 -275.378672)
		(width 0.0889)
		(layer "In2.Cu")
		(net "M_C_CPU0_SB_DQ<3>")
	)
	(segment
		(start 326.84339 -275.387054)
		(end 326.837802 -275.383752)
		(width 0.0889)
		(layer "In2.Cu")
		(net "M_C_CPU0_SB_DQ<3>")
	)
	(segment
		(start 312.192416 -280.786332)
		(end 311.09666 -280.786332)
		(width 0.14478)
		(layer "In2.Cu")
		(net "M_C_CPU0_SB_DQ<3>")
	)
	(segment
		(start 289.349942 -284.460188)
		(end 288.605214 -284.460188)
		(width 0.14478)
		(layer "In2.Cu")
		(net "M_C_CPU0_SB_DQ<3>")
	)
	(segment
		(start 343.725246 -275.440648)
		(end 343.702894 -275.357336)
		(width 0.0889)
		(layer "In2.Cu")
		(net "M_C_CPU0_SB_DQ<3>")
	)
	(segment
		(start 289.512756 -284.297374)
		(end 289.349942 -284.460188)
		(width 0.14478)
		(layer "In2.Cu")
		(net "M_C_CPU0_SB_DQ<3>")
	)
	(segment
		(start 332.478126 -275.383498)
		(end 332.469744 -275.378672)
		(width 0.0889)
		(layer "In2.Cu")
		(net "M_C_CPU0_SB_DQ<3>")
	)
	(segment
		(start 324.450964 -274.58416)
		(end 323.880734 -274.58416)
		(width 0.0889)
		(layer "In2.Cu")
		(net "M_C_CPU0_SB_DQ<3>")
	)
	(segment
		(start 340.938104 -275.383498)
		(end 340.929722 -275.378672)
		(width 0.0889)
		(layer "In2.Cu")
		(net "M_C_CPU0_SB_DQ<3>")
	)
	(segment
		(start 326.675242 -275.339302)
		(end 325.206106 -275.339302)
		(width 0.0889)
		(layer "In2.Cu")
		(net "M_C_CPU0_SB_DQ<3>")
	)
	(segment
		(start 311.09666 -280.786332)
		(end 308.272942 -283.61005)
		(width 0.14478)
		(layer "In2.Cu")
		(net "M_C_CPU0_SB_DQ<3>")
	)
	(segment
		(start 290.221924 -284.450282)
		(end 290.069016 -284.297374)
		(width 0.14478)
		(layer "In2.Cu")
		(net "M_C_CPU0_SB_DQ<3>")
	)
	(segment
		(start 329.292458 -275.378672)
		(end 329.284076 -275.383498)
		(width 0.0889)
		(layer "In2.Cu")
		(net "M_C_CPU0_SB_DQ<3>")
	)
	(segment
		(start 336.238088 -275.383498)
		(end 336.229706 -275.378672)
		(width 0.0889)
		(layer "In2.Cu")
		(net "M_C_CPU0_SB_DQ<3>")
	)
	(segment
		(start 325.206106 -275.339302)
		(end 324.450964 -274.58416)
		(width 0.0889)
		(layer "In2.Cu")
		(net "M_C_CPU0_SB_DQ<3>")
	)
	(segment
		(start 290.069016 -284.059884)
		(end 289.906202 -283.89707)
		(width 0.14478)
		(layer "In2.Cu")
		(net "M_C_CPU0_SB_DQ<3>")
	)
	(segment
		(start 327.41489 -275.37664)
		(end 327.403206 -275.383498)
		(width 0.0889)
		(layer "In2.Cu")
		(net "M_C_CPU0_SB_DQ<3>")
	)
	(segment
		(start 289.67557 -283.89707)
		(end 289.512756 -284.059884)
		(width 0.14478)
		(layer "In2.Cu")
		(net "M_C_CPU0_SB_DQ<3>")
	)
	(segment
		(start 337.752436 -275.378672)
		(end 337.744054 -275.383498)
		(width 0.0889)
		(layer "In2.Cu")
		(net "M_C_CPU0_SB_DQ<3>")
	)
	(segment
		(start 305.737768 -283.61005)
		(end 304.88763 -284.460188)
		(width 0.14478)
		(layer "In2.Cu")
		(net "M_C_CPU0_SB_DQ<3>")
	)
	(arc
		(start 329.284076 -275.383498)
		(mid 329.00112 -275.459675)
		(end 328.718164 -275.383498)
		(width 0.0889)
		(layer "In2.Cu")
		(net "M_C_CPU0_SB_DQ<3>")
	)
	(arc
		(start 339.05825 -275.383498)
		(mid 338.875999 -275.333148)
		(end 338.69249 -275.378672)
		(width 0.0889)
		(layer "In2.Cu")
		(net "M_C_CPU0_SB_DQ<3>")
	)
	(arc
		(start 329.658218 -275.383498)
		(mid 329.475967 -275.333148)
		(end 329.292458 -275.378672)
		(width 0.0889)
		(layer "In2.Cu")
		(net "M_C_CPU0_SB_DQ<3>")
	)
	(arc
		(start 336.229706 -275.378672)
		(mid 336.046198 -275.333178)
		(end 335.863946 -275.383498)
		(width 0.0889)
		(layer "In2.Cu")
		(net "M_C_CPU0_SB_DQ<3>")
	)
	(arc
		(start 341.869776 -275.378672)
		(mid 341.686268 -275.333178)
		(end 341.504016 -275.383498)
		(width 0.0889)
		(layer "In2.Cu")
		(net "M_C_CPU0_SB_DQ<3>")
	)
	(arc
		(start 327.777602 -275.383498)
		(mid 327.597144 -275.333054)
		(end 327.41489 -275.37664)
		(width 0.0889)
		(layer "In2.Cu")
		(net "M_C_CPU0_SB_DQ<3>")
	)
	(arc
		(start 341.504016 -275.383498)
		(mid 341.22106 -275.459675)
		(end 340.938104 -275.383498)
		(width 0.0889)
		(layer "In2.Cu")
		(net "M_C_CPU0_SB_DQ<3>")
	)
	(arc
		(start 332.469744 -275.378672)
		(mid 332.286236 -275.333178)
		(end 332.103984 -275.383498)
		(width 0.0889)
		(layer "In2.Cu")
		(net "M_C_CPU0_SB_DQ<3>")
	)
	(arc
		(start 342.818212 -275.383498)
		(mid 342.635961 -275.333148)
		(end 342.452452 -275.378672)
		(width 0.0889)
		(layer "In2.Cu")
		(net "M_C_CPU0_SB_DQ<3>")
	)
	(arc
		(start 328.709782 -275.378672)
		(mid 328.526274 -275.333178)
		(end 328.344022 -275.383498)
		(width 0.0889)
		(layer "In2.Cu")
		(net "M_C_CPU0_SB_DQ<3>")
	)
	(arc
		(start 337.744054 -275.383498)
		(mid 337.461098 -275.459675)
		(end 337.178142 -275.383498)
		(width 0.0889)
		(layer "In2.Cu")
		(net "M_C_CPU0_SB_DQ<3>")
	)
	(arc
		(start 333.044038 -275.383498)
		(mid 332.761082 -275.459675)
		(end 332.478126 -275.383498)
		(width 0.0889)
		(layer "In2.Cu")
		(net "M_C_CPU0_SB_DQ<3>")
	)
	(arc
		(start 331.52969 -275.378672)
		(mid 331.346182 -275.333178)
		(end 331.16393 -275.383498)
		(width 0.0889)
		(layer "In2.Cu")
		(net "M_C_CPU0_SB_DQ<3>")
	)
	(arc
		(start 340.929722 -275.378672)
		(mid 340.746214 -275.333178)
		(end 340.563962 -275.383498)
		(width 0.0889)
		(layer "In2.Cu")
		(net "M_C_CPU0_SB_DQ<3>")
	)
	(arc
		(start 338.118196 -275.383498)
		(mid 337.935945 -275.333148)
		(end 337.752436 -275.378672)
		(width 0.0889)
		(layer "In2.Cu")
		(net "M_C_CPU0_SB_DQ<3>")
	)
	(arc
		(start 330.598018 -275.383498)
		(mid 330.411074 -275.333243)
		(end 330.22413 -275.383498)
		(width 0.0889)
		(layer "In2.Cu")
		(net "M_C_CPU0_SB_DQ<3>")
	)
	(arc
		(start 336.804 -275.383498)
		(mid 336.521044 -275.459675)
		(end 336.238088 -275.383498)
		(width 0.0889)
		(layer "In2.Cu")
		(net "M_C_CPU0_SB_DQ<3>")
	)
	(arc
		(start 326.837802 -275.383752)
		(mid 326.759505 -275.35062)
		(end 326.675242 -275.339302)
		(width 0.0889)
		(layer "In2.Cu")
		(net "M_C_CPU0_SB_DQ<3>")
	)
	(arc
		(start 330.22413 -275.383498)
		(mid 329.941174 -275.459675)
		(end 329.658218 -275.383498)
		(width 0.0889)
		(layer "In2.Cu")
		(net "M_C_CPU0_SB_DQ<3>")
	)
	(arc
		(start 327.403206 -275.383498)
		(mid 327.123778 -275.459664)
		(end 326.84339 -275.387054)
		(width 0.0889)
		(layer "In2.Cu")
		(net "M_C_CPU0_SB_DQ<3>")
	)
	(arc
		(start 339.624162 -275.383498)
		(mid 339.341206 -275.459675)
		(end 339.05825 -275.383498)
		(width 0.0889)
		(layer "In2.Cu")
		(net "M_C_CPU0_SB_DQ<3>")
	)
	(arc
		(start 335.298034 -275.383498)
		(mid 335.11109 -275.333243)
		(end 334.924146 -275.383498)
		(width 0.0889)
		(layer "In2.Cu")
		(net "M_C_CPU0_SB_DQ<3>")
	)
	(arc
		(start 343.702894 -275.357336)
		(mid 343.545384 -275.334138)
		(end 343.392506 -275.378672)
		(width 0.0889)
		(layer "In2.Cu")
		(net "M_C_CPU0_SB_DQ<3>")
	)
	(arc
		(start 333.984092 -275.383498)
		(mid 333.701136 -275.459675)
		(end 333.41818 -275.383498)
		(width 0.0889)
		(layer "In2.Cu")
		(net "M_C_CPU0_SB_DQ<3>")
	)
	(arc
		(start 342.44407 -275.383498)
		(mid 342.161114 -275.459675)
		(end 341.878158 -275.383498)
		(width 0.0889)
		(layer "In2.Cu")
		(net "M_C_CPU0_SB_DQ<3>")
	)
	(arc
		(start 334.358234 -275.383498)
		(mid 334.175983 -275.333148)
		(end 333.992474 -275.378672)
		(width 0.0889)
		(layer "In2.Cu")
		(net "M_C_CPU0_SB_DQ<3>")
	)
	(arc
		(start 334.924146 -275.383498)
		(mid 334.64119 -275.459675)
		(end 334.358234 -275.383498)
		(width 0.0889)
		(layer "In2.Cu")
		(net "M_C_CPU0_SB_DQ<3>")
	)
	(arc
		(start 333.41818 -275.383498)
		(mid 333.235929 -275.333148)
		(end 333.05242 -275.378672)
		(width 0.0889)
		(layer "In2.Cu")
		(net "M_C_CPU0_SB_DQ<3>")
	)
	(arc
		(start 343.384124 -275.383498)
		(mid 343.101168 -275.459675)
		(end 342.818212 -275.383498)
		(width 0.0889)
		(layer "In2.Cu")
		(net "M_C_CPU0_SB_DQ<3>")
	)
	(arc
		(start 337.16976 -275.378672)
		(mid 336.986252 -275.333178)
		(end 336.804 -275.383498)
		(width 0.0889)
		(layer "In2.Cu")
		(net "M_C_CPU0_SB_DQ<3>")
	)
	(arc
		(start 328.32929 -275.392134)
		(mid 328.052307 -275.459938)
		(end 327.777602 -275.383498)
		(width 0.0889)
		(layer "In2.Cu")
		(net "M_C_CPU0_SB_DQ<3>")
	)
	(arc
		(start 331.16393 -275.383498)
		(mid 330.880974 -275.459675)
		(end 330.598018 -275.383498)
		(width 0.0889)
		(layer "In2.Cu")
		(net "M_C_CPU0_SB_DQ<3>")
	)
	(arc
		(start 338.684108 -275.383498)
		(mid 338.401152 -275.459675)
		(end 338.118196 -275.383498)
		(width 0.0889)
		(layer "In2.Cu")
		(net "M_C_CPU0_SB_DQ<3>")
	)
	(arc
		(start 335.863946 -275.383498)
		(mid 335.58099 -275.459675)
		(end 335.298034 -275.383498)
		(width 0.0889)
		(layer "In2.Cu")
		(net "M_C_CPU0_SB_DQ<3>")
	)
	(arc
		(start 339.99805 -275.383498)
		(mid 339.811106 -275.333243)
		(end 339.624162 -275.383498)
		(width 0.0889)
		(layer "In2.Cu")
		(net "M_C_CPU0_SB_DQ<3>")
	)
	(arc
		(start 332.103984 -275.383498)
		(mid 331.821028 -275.459675)
		(end 331.538072 -275.383498)
		(width 0.0889)
		(layer "In2.Cu")
		(net "M_C_CPU0_SB_DQ<3>")
	)
	(arc
		(start 340.563962 -275.383498)
		(mid 340.281006 -275.459675)
		(end 339.99805 -275.383498)
		(width 0.0889)
		(layer "In2.Cu")
		(net "M_C_CPU0_SB_DQ<3>")
	)
	(segment
		(start 344.03792 -293.260018)
		(end 343.571068 -293.525956)
		(width 0.10668)
		(layer "F.Cu")
		(net "M_C_CPU0_SB_DQ<31>")
	)
	(segment
		(start 342.44407 -293.203376)
		(end 342.452452 -293.19855)
		(width 0.0889)
		(layer "In2.Cu")
		(net "M_C_CPU0_SB_DQ<31>")
	)
	(segment
		(start 328.34961 -300.558962)
		(end 328.34961 -296.462196)
		(width 0.14478)
		(layer "In2.Cu")
		(net "M_C_CPU0_SB_DQ<31>")
	)
	(segment
		(start 337.744054 -293.203376)
		(end 337.752436 -293.19855)
		(width 0.0889)
		(layer "In2.Cu")
		(net "M_C_CPU0_SB_DQ<31>")
	)
	(segment
		(start 289.229546 -318.46012)
		(end 289.38982 -318.299846)
		(width 0.14478)
		(layer "In2.Cu")
		(net "M_C_CPU0_SB_DQ<31>")
	)
	(segment
		(start 337.16976 -293.19855)
		(end 337.178142 -293.203376)
		(width 0.0889)
		(layer "In2.Cu")
		(net "M_C_CPU0_SB_DQ<31>")
	)
	(segment
		(start 329.753976 -294.013382)
		(end 329.793092 -293.990522)
		(width 0.0889)
		(layer "In2.Cu")
		(net "M_C_CPU0_SB_DQ<31>")
	)
	(segment
		(start 328.81443 -295.633394)
		(end 328.850752 -295.612312)
		(width 0.0889)
		(layer "In2.Cu")
		(net "M_C_CPU0_SB_DQ<31>")
	)
	(segment
		(start 328.391266 -296.42054)
		(end 328.464672 -296.347134)
		(width 0.0889)
		(layer "In2.Cu")
		(net "M_C_CPU0_SB_DQ<31>")
	)
	(segment
		(start 288.60496 -318.46012)
		(end 289.229546 -318.46012)
		(width 0.14478)
		(layer "In2.Cu")
		(net "M_C_CPU0_SB_DQ<31>")
	)
	(segment
		(start 289.38982 -317.834264)
		(end 289.552634 -317.67145)
		(width 0.14478)
		(layer "In2.Cu")
		(net "M_C_CPU0_SB_DQ<31>")
	)
	(segment
		(start 322.244466 -306.664106)
		(end 328.34961 -300.558962)
		(width 0.14478)
		(layer "In2.Cu")
		(net "M_C_CPU0_SB_DQ<31>")
	)
	(segment
		(start 310.448452 -318.46012)
		(end 317.216282 -311.69229)
		(width 0.14478)
		(layer "In2.Cu")
		(net "M_C_CPU0_SB_DQ<31>")
	)
	(segment
		(start 340.929722 -293.19855)
		(end 340.938104 -293.203376)
		(width 0.0889)
		(layer "In2.Cu")
		(net "M_C_CPU0_SB_DQ<31>")
	)
	(segment
		(start 289.552634 -317.67145)
		(end 289.783266 -317.67145)
		(width 0.14478)
		(layer "In2.Cu")
		(net "M_C_CPU0_SB_DQ<31>")
	)
	(segment
		(start 290.106354 -318.46012)
		(end 310.448452 -318.46012)
		(width 0.14478)
		(layer "In2.Cu")
		(net "M_C_CPU0_SB_DQ<31>")
	)
	(segment
		(start 332.469744 -293.19855)
		(end 332.478126 -293.203376)
		(width 0.0889)
		(layer "In2.Cu")
		(net "M_C_CPU0_SB_DQ<31>")
	)
	(segment
		(start 322.244466 -307.763926)
		(end 322.244466 -306.664106)
		(width 0.14478)
		(layer "In2.Cu")
		(net "M_C_CPU0_SB_DQ<31>")
	)
	(segment
		(start 318.316102 -311.69229)
		(end 322.244466 -307.763926)
		(width 0.14478)
		(layer "In2.Cu")
		(net "M_C_CPU0_SB_DQ<31>")
	)
	(segment
		(start 343.384124 -293.203376)
		(end 343.392506 -293.19855)
		(width 0.0889)
		(layer "In2.Cu")
		(net "M_C_CPU0_SB_DQ<31>")
	)
	(segment
		(start 329.723496 -294.031162)
		(end 329.753976 -294.013382)
		(width 0.0889)
		(layer "In2.Cu")
		(net "M_C_CPU0_SB_DQ<31>")
	)
	(segment
		(start 289.38982 -318.299846)
		(end 289.38982 -317.834264)
		(width 0.14478)
		(layer "In2.Cu")
		(net "M_C_CPU0_SB_DQ<31>")
	)
	(segment
		(start 341.869776 -293.19855)
		(end 341.878158 -293.203376)
		(width 0.0889)
		(layer "In2.Cu")
		(net "M_C_CPU0_SB_DQ<31>")
	)
	(segment
		(start 289.783266 -317.67145)
		(end 289.94608 -317.834264)
		(width 0.14478)
		(layer "In2.Cu")
		(net "M_C_CPU0_SB_DQ<31>")
	)
	(segment
		(start 328.78268 -295.651682)
		(end 328.81443 -295.633394)
		(width 0.0889)
		(layer "In2.Cu")
		(net "M_C_CPU0_SB_DQ<31>")
	)
	(segment
		(start 329.284076 -294.823388)
		(end 329.323192 -294.800528)
		(width 0.0889)
		(layer "In2.Cu")
		(net "M_C_CPU0_SB_DQ<31>")
	)
	(segment
		(start 343.725246 -293.260526)
		(end 343.571068 -293.525956)
		(width 0.0889)
		(layer "In2.Cu")
		(net "M_C_CPU0_SB_DQ<31>")
	)
	(segment
		(start 288.180018 -318.035178)
		(end 288.60496 -318.46012)
		(width 0.14478)
		(layer "In2.Cu")
		(net "M_C_CPU0_SB_DQ<31>")
	)
	(segment
		(start 338.684108 -293.203376)
		(end 338.69249 -293.19855)
		(width 0.0889)
		(layer "In2.Cu")
		(net "M_C_CPU0_SB_DQ<31>")
	)
	(segment
		(start 333.984092 -293.203376)
		(end 333.992474 -293.19855)
		(width 0.0889)
		(layer "In2.Cu")
		(net "M_C_CPU0_SB_DQ<31>")
	)
	(segment
		(start 330.221336 -293.205154)
		(end 330.22413 -293.203376)
		(width 0.0889)
		(layer "In2.Cu")
		(net "M_C_CPU0_SB_DQ<31>")
	)
	(segment
		(start 336.229706 -293.19855)
		(end 336.238088 -293.203376)
		(width 0.0889)
		(layer "In2.Cu")
		(net "M_C_CPU0_SB_DQ<31>")
	)
	(segment
		(start 289.94608 -317.834264)
		(end 289.94608 -318.299846)
		(width 0.14478)
		(layer "In2.Cu")
		(net "M_C_CPU0_SB_DQ<31>")
	)
	(segment
		(start 317.216282 -311.69229)
		(end 318.316102 -311.69229)
		(width 0.14478)
		(layer "In2.Cu")
		(net "M_C_CPU0_SB_DQ<31>")
	)
	(segment
		(start 289.94608 -318.299846)
		(end 290.106354 -318.46012)
		(width 0.14478)
		(layer "In2.Cu")
		(net "M_C_CPU0_SB_DQ<31>")
	)
	(segment
		(start 328.34961 -296.462196)
		(end 328.391266 -296.42054)
		(width 0.14478)
		(layer "In2.Cu")
		(net "M_C_CPU0_SB_DQ<31>")
	)
	(segment
		(start 343.702894 -293.177214)
		(end 343.725246 -293.260526)
		(width 0.0889)
		(layer "In2.Cu")
		(net "M_C_CPU0_SB_DQ<31>")
	)
	(segment
		(start 329.254612 -294.840406)
		(end 329.284076 -294.823388)
		(width 0.0889)
		(layer "In2.Cu")
		(net "M_C_CPU0_SB_DQ<31>")
	)
	(segment
		(start 331.52969 -293.19855)
		(end 331.538072 -293.203376)
		(width 0.0889)
		(layer "In2.Cu")
		(net "M_C_CPU0_SB_DQ<31>")
	)
	(segment
		(start 333.044038 -293.203376)
		(end 333.05242 -293.19855)
		(width 0.0889)
		(layer "In2.Cu")
		(net "M_C_CPU0_SB_DQ<31>")
	)
	(arc
		(start 337.752436 -293.19855)
		(mid 337.935944 -293.153056)
		(end 338.118196 -293.203376)
		(width 0.0889)
		(layer "In2.Cu")
		(net "M_C_CPU0_SB_DQ<31>")
	)
	(arc
		(start 336.804 -293.203376)
		(mid 336.986251 -293.153026)
		(end 337.16976 -293.19855)
		(width 0.0889)
		(layer "In2.Cu")
		(net "M_C_CPU0_SB_DQ<31>")
	)
	(arc
		(start 330.22413 -293.203376)
		(mid 330.411074 -293.153121)
		(end 330.598018 -293.203376)
		(width 0.0889)
		(layer "In2.Cu")
		(net "M_C_CPU0_SB_DQ<31>")
	)
	(arc
		(start 337.178142 -293.203376)
		(mid 337.461098 -293.279553)
		(end 337.744054 -293.203376)
		(width 0.0889)
		(layer "In2.Cu")
		(net "M_C_CPU0_SB_DQ<31>")
	)
	(arc
		(start 333.41818 -293.203376)
		(mid 333.701136 -293.279553)
		(end 333.984092 -293.203376)
		(width 0.0889)
		(layer "In2.Cu")
		(net "M_C_CPU0_SB_DQ<31>")
	)
	(arc
		(start 341.878158 -293.203376)
		(mid 342.161114 -293.279553)
		(end 342.44407 -293.203376)
		(width 0.0889)
		(layer "In2.Cu")
		(net "M_C_CPU0_SB_DQ<31>")
	)
	(arc
		(start 328.850752 -295.612312)
		(mid 329.031404 -295.409567)
		(end 329.096624 -295.145968)
		(width 0.0889)
		(layer "In2.Cu")
		(net "M_C_CPU0_SB_DQ<31>")
	)
	(arc
		(start 339.05825 -293.203376)
		(mid 339.341206 -293.279553)
		(end 339.624162 -293.203376)
		(width 0.0889)
		(layer "In2.Cu")
		(net "M_C_CPU0_SB_DQ<31>")
	)
	(arc
		(start 341.504016 -293.203376)
		(mid 341.686267 -293.153026)
		(end 341.869776 -293.19855)
		(width 0.0889)
		(layer "In2.Cu")
		(net "M_C_CPU0_SB_DQ<31>")
	)
	(arc
		(start 340.563962 -293.203376)
		(mid 340.746213 -293.153026)
		(end 340.929722 -293.19855)
		(width 0.0889)
		(layer "In2.Cu")
		(net "M_C_CPU0_SB_DQ<31>")
	)
	(arc
		(start 331.16393 -293.203376)
		(mid 331.346181 -293.153026)
		(end 331.52969 -293.19855)
		(width 0.0889)
		(layer "In2.Cu")
		(net "M_C_CPU0_SB_DQ<31>")
	)
	(arc
		(start 340.938104 -293.203376)
		(mid 341.22106 -293.279553)
		(end 341.504016 -293.203376)
		(width 0.0889)
		(layer "In2.Cu")
		(net "M_C_CPU0_SB_DQ<31>")
	)
	(arc
		(start 332.103984 -293.203376)
		(mid 332.286235 -293.153026)
		(end 332.469744 -293.19855)
		(width 0.0889)
		(layer "In2.Cu")
		(net "M_C_CPU0_SB_DQ<31>")
	)
	(arc
		(start 339.99805 -293.203376)
		(mid 340.281006 -293.279553)
		(end 340.563962 -293.203376)
		(width 0.0889)
		(layer "In2.Cu")
		(net "M_C_CPU0_SB_DQ<31>")
	)
	(arc
		(start 338.69249 -293.19855)
		(mid 338.875998 -293.153056)
		(end 339.05825 -293.203376)
		(width 0.0889)
		(layer "In2.Cu")
		(net "M_C_CPU0_SB_DQ<31>")
	)
	(arc
		(start 329.323192 -294.800528)
		(mid 329.502005 -294.598178)
		(end 329.566524 -294.335962)
		(width 0.0889)
		(layer "In2.Cu")
		(net "M_C_CPU0_SB_DQ<31>")
	)
	(arc
		(start 330.036424 -293.525956)
		(mid 330.085953 -293.340803)
		(end 330.221336 -293.205154)
		(width 0.0889)
		(layer "In2.Cu")
		(net "M_C_CPU0_SB_DQ<31>")
	)
	(arc
		(start 339.624162 -293.203376)
		(mid 339.811106 -293.153121)
		(end 339.99805 -293.203376)
		(width 0.0889)
		(layer "In2.Cu")
		(net "M_C_CPU0_SB_DQ<31>")
	)
	(arc
		(start 330.598018 -293.203376)
		(mid 330.880974 -293.279553)
		(end 331.16393 -293.203376)
		(width 0.0889)
		(layer "In2.Cu")
		(net "M_C_CPU0_SB_DQ<31>")
	)
	(arc
		(start 335.298034 -293.203376)
		(mid 335.58099 -293.279553)
		(end 335.863946 -293.203376)
		(width 0.0889)
		(layer "In2.Cu")
		(net "M_C_CPU0_SB_DQ<31>")
	)
	(arc
		(start 334.358234 -293.203376)
		(mid 334.64119 -293.279553)
		(end 334.924146 -293.203376)
		(width 0.0889)
		(layer "In2.Cu")
		(net "M_C_CPU0_SB_DQ<31>")
	)
	(arc
		(start 329.566524 -294.335962)
		(mid 329.608073 -294.16454)
		(end 329.723496 -294.031162)
		(width 0.0889)
		(layer "In2.Cu")
		(net "M_C_CPU0_SB_DQ<31>")
	)
	(arc
		(start 336.238088 -293.203376)
		(mid 336.521044 -293.279553)
		(end 336.804 -293.203376)
		(width 0.0889)
		(layer "In2.Cu")
		(net "M_C_CPU0_SB_DQ<31>")
	)
	(arc
		(start 329.793092 -293.990522)
		(mid 329.971905 -293.788172)
		(end 330.036424 -293.525956)
		(width 0.0889)
		(layer "In2.Cu")
		(net "M_C_CPU0_SB_DQ<31>")
	)
	(arc
		(start 333.992474 -293.19855)
		(mid 334.175982 -293.153056)
		(end 334.358234 -293.203376)
		(width 0.0889)
		(layer "In2.Cu")
		(net "M_C_CPU0_SB_DQ<31>")
	)
	(arc
		(start 342.452452 -293.19855)
		(mid 342.63596 -293.153056)
		(end 342.818212 -293.203376)
		(width 0.0889)
		(layer "In2.Cu")
		(net "M_C_CPU0_SB_DQ<31>")
	)
	(arc
		(start 342.818212 -293.203376)
		(mid 343.101168 -293.279553)
		(end 343.384124 -293.203376)
		(width 0.0889)
		(layer "In2.Cu")
		(net "M_C_CPU0_SB_DQ<31>")
	)
	(arc
		(start 329.096624 -295.145968)
		(mid 329.138464 -294.973982)
		(end 329.254612 -294.840406)
		(width 0.0889)
		(layer "In2.Cu")
		(net "M_C_CPU0_SB_DQ<31>")
	)
	(arc
		(start 333.05242 -293.19855)
		(mid 333.235928 -293.153056)
		(end 333.41818 -293.203376)
		(width 0.0889)
		(layer "In2.Cu")
		(net "M_C_CPU0_SB_DQ<31>")
	)
	(arc
		(start 343.392506 -293.19855)
		(mid 343.545376 -293.153909)
		(end 343.702894 -293.177214)
		(width 0.0889)
		(layer "In2.Cu")
		(net "M_C_CPU0_SB_DQ<31>")
	)
	(arc
		(start 328.626724 -295.955974)
		(mid 328.667979 -295.785003)
		(end 328.78268 -295.651682)
		(width 0.0889)
		(layer "In2.Cu")
		(net "M_C_CPU0_SB_DQ<31>")
	)
	(arc
		(start 334.924146 -293.203376)
		(mid 335.11109 -293.153121)
		(end 335.298034 -293.203376)
		(width 0.0889)
		(layer "In2.Cu")
		(net "M_C_CPU0_SB_DQ<31>")
	)
	(arc
		(start 338.118196 -293.203376)
		(mid 338.401152 -293.279553)
		(end 338.684108 -293.203376)
		(width 0.0889)
		(layer "In2.Cu")
		(net "M_C_CPU0_SB_DQ<31>")
	)
	(arc
		(start 331.538072 -293.203376)
		(mid 331.821028 -293.279553)
		(end 332.103984 -293.203376)
		(width 0.0889)
		(layer "In2.Cu")
		(net "M_C_CPU0_SB_DQ<31>")
	)
	(arc
		(start 328.464672 -296.347134)
		(mid 328.584587 -296.167668)
		(end 328.626724 -295.955974)
		(width 0.0889)
		(layer "In2.Cu")
		(net "M_C_CPU0_SB_DQ<31>")
	)
	(arc
		(start 335.863946 -293.203376)
		(mid 336.046197 -293.153026)
		(end 336.229706 -293.19855)
		(width 0.0889)
		(layer "In2.Cu")
		(net "M_C_CPU0_SB_DQ<31>")
	)
	(arc
		(start 332.478126 -293.203376)
		(mid 332.761082 -293.279553)
		(end 333.044038 -293.203376)
		(width 0.0889)
		(layer "In2.Cu")
		(net "M_C_CPU0_SB_DQ<31>")
	)
	(segment
		(start 342.627966 -292.450012)
		(end 342.161114 -292.71595)
		(width 0.10668)
		(layer "F.Cu")
		(net "M_C_CPU0_SB_DQ<30>")
	)
	(segment
		(start 289.185096 -316.760098)
		(end 288.60496 -316.760098)
		(width 0.14478)
		(layer "In2.Cu")
		(net "M_C_CPU0_SB_DQ<30>")
	)
	(segment
		(start 289.34791 -316.256924)
		(end 289.34791 -316.597284)
		(width 0.14478)
		(layer "In2.Cu")
		(net "M_C_CPU0_SB_DQ<30>")
	)
	(segment
		(start 290.971224 -315.67501)
		(end 290.740592 -315.67501)
		(width 0.14478)
		(layer "In2.Cu")
		(net "M_C_CPU0_SB_DQ<30>")
	)
	(segment
		(start 335.402428 -292.388544)
		(end 335.394046 -292.39337)
		(width 0.0889)
		(layer "In2.Cu")
		(net "M_C_CPU0_SB_DQ<30>")
	)
	(segment
		(start 310.860694 -316.760098)
		(end 291.296852 -316.760098)
		(width 0.14478)
		(layer "In2.Cu")
		(net "M_C_CPU0_SB_DQ<30>")
	)
	(segment
		(start 289.741356 -316.09411)
		(end 289.510724 -316.09411)
		(width 0.14478)
		(layer "In2.Cu")
		(net "M_C_CPU0_SB_DQ<30>")
	)
	(segment
		(start 333.88808 -292.39337)
		(end 333.879698 -292.388544)
		(width 0.0889)
		(layer "In2.Cu")
		(net "M_C_CPU0_SB_DQ<30>")
	)
	(segment
		(start 341.042498 -292.388544)
		(end 341.034116 -292.39337)
		(width 0.0889)
		(layer "In2.Cu")
		(net "M_C_CPU0_SB_DQ<30>")
	)
	(segment
		(start 328.383138 -293.180516)
		(end 328.344022 -293.203376)
		(width 0.0889)
		(layer "In2.Cu")
		(net "M_C_CPU0_SB_DQ<30>")
	)
	(segment
		(start 331.642466 -292.388544)
		(end 331.634084 -292.39337)
		(width 0.0889)
		(layer "In2.Cu")
		(net "M_C_CPU0_SB_DQ<30>")
	)
	(segment
		(start 290.577778 -316.597284)
		(end 290.414964 -316.760098)
		(width 0.14478)
		(layer "In2.Cu")
		(net "M_C_CPU0_SB_DQ<30>")
	)
	(segment
		(start 289.34791 -316.597284)
		(end 289.185096 -316.760098)
		(width 0.14478)
		(layer "In2.Cu")
		(net "M_C_CPU0_SB_DQ<30>")
	)
	(segment
		(start 327.440798 -294.802306)
		(end 327.404476 -294.823388)
		(width 0.0889)
		(layer "In2.Cu")
		(net "M_C_CPU0_SB_DQ<30>")
	)
	(segment
		(start 326.921114 -295.637204)
		(end 326.549004 -296.009314)
		(width 0.0889)
		(layer "In2.Cu")
		(net "M_C_CPU0_SB_DQ<30>")
	)
	(segment
		(start 336.342482 -292.388544)
		(end 336.3341 -292.39337)
		(width 0.0889)
		(layer "In2.Cu")
		(net "M_C_CPU0_SB_DQ<30>")
	)
	(segment
		(start 327.404476 -294.823388)
		(end 327.372726 -294.841676)
		(width 0.0889)
		(layer "In2.Cu")
		(net "M_C_CPU0_SB_DQ<30>")
	)
	(segment
		(start 330.128118 -292.39337)
		(end 330.119736 -292.388544)
		(width 0.0889)
		(layer "In2.Cu")
		(net "M_C_CPU0_SB_DQ<30>")
	)
	(segment
		(start 289.90417 -316.597284)
		(end 289.90417 -316.256924)
		(width 0.14478)
		(layer "In2.Cu")
		(net "M_C_CPU0_SB_DQ<30>")
	)
	(segment
		(start 290.066984 -316.760098)
		(end 289.90417 -316.597284)
		(width 0.14478)
		(layer "In2.Cu")
		(net "M_C_CPU0_SB_DQ<30>")
	)
	(segment
		(start 340.102444 -292.388544)
		(end 340.094062 -292.39337)
		(width 0.0889)
		(layer "In2.Cu")
		(net "M_C_CPU0_SB_DQ<30>")
	)
	(segment
		(start 290.740592 -315.67501)
		(end 290.577778 -315.837824)
		(width 0.14478)
		(layer "In2.Cu")
		(net "M_C_CPU0_SB_DQ<30>")
	)
	(segment
		(start 342.161114 -292.71595)
		(end 342.315038 -292.45052)
		(width 0.0889)
		(layer "In2.Cu")
		(net "M_C_CPU0_SB_DQ<30>")
	)
	(segment
		(start 327.874122 -294.013382)
		(end 327.844658 -294.0304)
		(width 0.0889)
		(layer "In2.Cu")
		(net "M_C_CPU0_SB_DQ<30>")
	)
	(segment
		(start 326.549004 -301.071788)
		(end 310.860694 -316.760098)
		(width 0.14478)
		(layer "In2.Cu")
		(net "M_C_CPU0_SB_DQ<30>")
	)
	(segment
		(start 339.52815 -292.39337)
		(end 339.519768 -292.388544)
		(width 0.0889)
		(layer "In2.Cu")
		(net "M_C_CPU0_SB_DQ<30>")
	)
	(segment
		(start 327.078594 -295.479978)
		(end 326.921114 -295.637204)
		(width 0.0889)
		(layer "In2.Cu")
		(net "M_C_CPU0_SB_DQ<30>")
	)
	(segment
		(start 290.414964 -316.760098)
		(end 290.066984 -316.760098)
		(width 0.14478)
		(layer "In2.Cu")
		(net "M_C_CPU0_SB_DQ<30>")
	)
	(segment
		(start 288.60496 -316.760098)
		(end 288.180018 -316.335156)
		(width 0.14478)
		(layer "In2.Cu")
		(net "M_C_CPU0_SB_DQ<30>")
	)
	(segment
		(start 342.315038 -292.45052)
		(end 342.292686 -292.367208)
		(width 0.0889)
		(layer "In2.Cu")
		(net "M_C_CPU0_SB_DQ<30>")
	)
	(segment
		(start 289.510724 -316.09411)
		(end 289.34791 -316.256924)
		(width 0.14478)
		(layer "In2.Cu")
		(net "M_C_CPU0_SB_DQ<30>")
	)
	(segment
		(start 326.549004 -296.009314)
		(end 326.549004 -301.071788)
		(width 0.14478)
		(layer "In2.Cu")
		(net "M_C_CPU0_SB_DQ<30>")
	)
	(segment
		(start 327.913238 -293.990522)
		(end 327.874122 -294.013382)
		(width 0.0889)
		(layer "In2.Cu")
		(net "M_C_CPU0_SB_DQ<30>")
	)
	(segment
		(start 289.90417 -316.256924)
		(end 289.741356 -316.09411)
		(width 0.14478)
		(layer "In2.Cu")
		(net "M_C_CPU0_SB_DQ<30>")
	)
	(segment
		(start 334.828134 -292.39337)
		(end 334.819752 -292.388544)
		(width 0.0889)
		(layer "In2.Cu")
		(net "M_C_CPU0_SB_DQ<30>")
	)
	(segment
		(start 291.134038 -316.597284)
		(end 291.134038 -315.837824)
		(width 0.14478)
		(layer "In2.Cu")
		(net "M_C_CPU0_SB_DQ<30>")
	)
	(segment
		(start 291.134038 -315.837824)
		(end 290.971224 -315.67501)
		(width 0.14478)
		(layer "In2.Cu")
		(net "M_C_CPU0_SB_DQ<30>")
	)
	(segment
		(start 290.577778 -315.837824)
		(end 290.577778 -316.597284)
		(width 0.14478)
		(layer "In2.Cu")
		(net "M_C_CPU0_SB_DQ<30>")
	)
	(segment
		(start 328.344022 -293.203376)
		(end 328.313542 -293.221156)
		(width 0.0889)
		(layer "In2.Cu")
		(net "M_C_CPU0_SB_DQ<30>")
	)
	(segment
		(start 328.814176 -292.39337)
		(end 328.811382 -292.395148)
		(width 0.0889)
		(layer "In2.Cu")
		(net "M_C_CPU0_SB_DQ<30>")
	)
	(segment
		(start 330.702412 -292.388544)
		(end 330.69403 -292.39337)
		(width 0.0889)
		(layer "In2.Cu")
		(net "M_C_CPU0_SB_DQ<30>")
	)
	(segment
		(start 291.296852 -316.760098)
		(end 291.134038 -316.597284)
		(width 0.14478)
		(layer "In2.Cu")
		(net "M_C_CPU0_SB_DQ<30>")
	)
	(segment
		(start 338.588096 -292.39337)
		(end 338.579714 -292.388544)
		(width 0.0889)
		(layer "In2.Cu")
		(net "M_C_CPU0_SB_DQ<30>")
	)
	(arc
		(start 339.519768 -292.388544)
		(mid 339.33626 -292.34305)
		(end 339.154008 -292.39337)
		(width 0.0889)
		(layer "In2.Cu")
		(net "M_C_CPU0_SB_DQ<30>")
	)
	(arc
		(start 330.69403 -292.39337)
		(mid 330.411074 -292.469547)
		(end 330.128118 -292.39337)
		(width 0.0889)
		(layer "In2.Cu")
		(net "M_C_CPU0_SB_DQ<30>")
	)
	(arc
		(start 334.819752 -292.388544)
		(mid 334.636244 -292.34305)
		(end 334.453992 -292.39337)
		(width 0.0889)
		(layer "In2.Cu")
		(net "M_C_CPU0_SB_DQ<30>")
	)
	(arc
		(start 331.068172 -292.39337)
		(mid 330.885921 -292.34302)
		(end 330.702412 -292.388544)
		(width 0.0889)
		(layer "In2.Cu")
		(net "M_C_CPU0_SB_DQ<30>")
	)
	(arc
		(start 338.213954 -292.39337)
		(mid 337.930998 -292.469547)
		(end 337.648042 -292.39337)
		(width 0.0889)
		(layer "In2.Cu")
		(net "M_C_CPU0_SB_DQ<30>")
	)
	(arc
		(start 328.811382 -292.395148)
		(mid 328.676045 -292.530824)
		(end 328.62647 -292.71595)
		(width 0.0889)
		(layer "In2.Cu")
		(net "M_C_CPU0_SB_DQ<30>")
	)
	(arc
		(start 336.708242 -292.39337)
		(mid 336.525991 -292.34302)
		(end 336.342482 -292.388544)
		(width 0.0889)
		(layer "In2.Cu")
		(net "M_C_CPU0_SB_DQ<30>")
	)
	(arc
		(start 340.468204 -292.39337)
		(mid 340.285953 -292.34302)
		(end 340.102444 -292.388544)
		(width 0.0889)
		(layer "In2.Cu")
		(net "M_C_CPU0_SB_DQ<30>")
	)
	(arc
		(start 327.844658 -294.0304)
		(mid 327.728477 -294.163959)
		(end 327.68667 -294.335962)
		(width 0.0889)
		(layer "In2.Cu")
		(net "M_C_CPU0_SB_DQ<30>")
	)
	(arc
		(start 332.574138 -292.39337)
		(mid 332.291182 -292.469547)
		(end 332.008226 -292.39337)
		(width 0.0889)
		(layer "In2.Cu")
		(net "M_C_CPU0_SB_DQ<30>")
	)
	(arc
		(start 327.68667 -294.335962)
		(mid 327.621434 -294.599553)
		(end 327.440798 -294.802306)
		(width 0.0889)
		(layer "In2.Cu")
		(net "M_C_CPU0_SB_DQ<30>")
	)
	(arc
		(start 341.97417 -292.39337)
		(mid 341.691214 -292.469547)
		(end 341.408258 -292.39337)
		(width 0.0889)
		(layer "In2.Cu")
		(net "M_C_CPU0_SB_DQ<30>")
	)
	(arc
		(start 329.188064 -292.39337)
		(mid 329.00112 -292.343115)
		(end 328.814176 -292.39337)
		(width 0.0889)
		(layer "In2.Cu")
		(net "M_C_CPU0_SB_DQ<30>")
	)
	(arc
		(start 328.15657 -293.525956)
		(mid 328.092055 -293.788175)
		(end 327.913238 -293.990522)
		(width 0.0889)
		(layer "In2.Cu")
		(net "M_C_CPU0_SB_DQ<30>")
	)
	(arc
		(start 331.634084 -292.39337)
		(mid 331.351128 -292.469547)
		(end 331.068172 -292.39337)
		(width 0.0889)
		(layer "In2.Cu")
		(net "M_C_CPU0_SB_DQ<30>")
	)
	(arc
		(start 340.094062 -292.39337)
		(mid 339.811106 -292.469547)
		(end 339.52815 -292.39337)
		(width 0.0889)
		(layer "In2.Cu")
		(net "M_C_CPU0_SB_DQ<30>")
	)
	(arc
		(start 337.648042 -292.39337)
		(mid 337.461098 -292.343115)
		(end 337.274154 -292.39337)
		(width 0.0889)
		(layer "In2.Cu")
		(net "M_C_CPU0_SB_DQ<30>")
	)
	(arc
		(start 342.292686 -292.367208)
		(mid 342.130497 -292.344473)
		(end 341.97417 -292.39337)
		(width 0.0889)
		(layer "In2.Cu")
		(net "M_C_CPU0_SB_DQ<30>")
	)
	(arc
		(start 341.034116 -292.39337)
		(mid 340.75116 -292.469547)
		(end 340.468204 -292.39337)
		(width 0.0889)
		(layer "In2.Cu")
		(net "M_C_CPU0_SB_DQ<30>")
	)
	(arc
		(start 332.008226 -292.39337)
		(mid 331.825975 -292.34302)
		(end 331.642466 -292.388544)
		(width 0.0889)
		(layer "In2.Cu")
		(net "M_C_CPU0_SB_DQ<30>")
	)
	(arc
		(start 335.768188 -292.39337)
		(mid 335.585937 -292.34302)
		(end 335.402428 -292.388544)
		(width 0.0889)
		(layer "In2.Cu")
		(net "M_C_CPU0_SB_DQ<30>")
	)
	(arc
		(start 328.62647 -292.71595)
		(mid 328.561955 -292.978169)
		(end 328.383138 -293.180516)
		(width 0.0889)
		(layer "In2.Cu")
		(net "M_C_CPU0_SB_DQ<30>")
	)
	(arc
		(start 337.274154 -292.39337)
		(mid 336.991198 -292.469547)
		(end 336.708242 -292.39337)
		(width 0.0889)
		(layer "In2.Cu")
		(net "M_C_CPU0_SB_DQ<30>")
	)
	(arc
		(start 341.408258 -292.39337)
		(mid 341.226007 -292.34302)
		(end 341.042498 -292.388544)
		(width 0.0889)
		(layer "In2.Cu")
		(net "M_C_CPU0_SB_DQ<30>")
	)
	(arc
		(start 338.579714 -292.388544)
		(mid 338.396206 -292.34305)
		(end 338.213954 -292.39337)
		(width 0.0889)
		(layer "In2.Cu")
		(net "M_C_CPU0_SB_DQ<30>")
	)
	(arc
		(start 330.119736 -292.388544)
		(mid 329.936228 -292.34305)
		(end 329.753976 -292.39337)
		(width 0.0889)
		(layer "In2.Cu")
		(net "M_C_CPU0_SB_DQ<30>")
	)
	(arc
		(start 329.753976 -292.39337)
		(mid 329.47102 -292.469547)
		(end 329.188064 -292.39337)
		(width 0.0889)
		(layer "In2.Cu")
		(net "M_C_CPU0_SB_DQ<30>")
	)
	(arc
		(start 328.313542 -293.221156)
		(mid 328.198115 -293.354532)
		(end 328.15657 -293.525956)
		(width 0.0889)
		(layer "In2.Cu")
		(net "M_C_CPU0_SB_DQ<30>")
	)
	(arc
		(start 335.394046 -292.39337)
		(mid 335.11109 -292.469547)
		(end 334.828134 -292.39337)
		(width 0.0889)
		(layer "In2.Cu")
		(net "M_C_CPU0_SB_DQ<30>")
	)
	(arc
		(start 333.879698 -292.388544)
		(mid 333.69619 -292.34305)
		(end 333.513938 -292.39337)
		(width 0.0889)
		(layer "In2.Cu")
		(net "M_C_CPU0_SB_DQ<30>")
	)
	(arc
		(start 332.948026 -292.39337)
		(mid 332.761082 -292.343115)
		(end 332.574138 -292.39337)
		(width 0.0889)
		(layer "In2.Cu")
		(net "M_C_CPU0_SB_DQ<30>")
	)
	(arc
		(start 333.513938 -292.39337)
		(mid 333.230982 -292.469547)
		(end 332.948026 -292.39337)
		(width 0.0889)
		(layer "In2.Cu")
		(net "M_C_CPU0_SB_DQ<30>")
	)
	(arc
		(start 334.453992 -292.39337)
		(mid 334.171036 -292.469547)
		(end 333.88808 -292.39337)
		(width 0.0889)
		(layer "In2.Cu")
		(net "M_C_CPU0_SB_DQ<30>")
	)
	(arc
		(start 327.372726 -294.841676)
		(mid 327.25805 -294.97501)
		(end 327.21677 -295.145968)
		(width 0.0889)
		(layer "In2.Cu")
		(net "M_C_CPU0_SB_DQ<30>")
	)
	(arc
		(start 327.21677 -295.145968)
		(mid 327.18091 -295.326719)
		(end 327.078594 -295.479978)
		(width 0.0889)
		(layer "In2.Cu")
		(net "M_C_CPU0_SB_DQ<30>")
	)
	(arc
		(start 336.3341 -292.39337)
		(mid 336.051144 -292.469547)
		(end 335.768188 -292.39337)
		(width 0.0889)
		(layer "In2.Cu")
		(net "M_C_CPU0_SB_DQ<30>")
	)
	(arc
		(start 339.154008 -292.39337)
		(mid 338.871052 -292.469547)
		(end 338.588096 -292.39337)
		(width 0.0889)
		(layer "In2.Cu")
		(net "M_C_CPU0_SB_DQ<30>")
	)
	(segment
		(start 342.627966 -274.630134)
		(end 342.161114 -274.896072)
		(width 0.10668)
		(layer "F.Cu")
		(net "M_C_CPU0_SB_DQ<2>")
	)
	(segment
		(start 331.642466 -274.568666)
		(end 331.634084 -274.573492)
		(width 0.0889)
		(layer "In2.Cu")
		(net "M_C_CPU0_SB_DQ<2>")
	)
	(segment
		(start 340.102444 -274.568666)
		(end 340.094062 -274.573492)
		(width 0.0889)
		(layer "In2.Cu")
		(net "M_C_CPU0_SB_DQ<2>")
	)
	(segment
		(start 289.303968 -282.597352)
		(end 289.141154 -282.760166)
		(width 0.14478)
		(layer "In2.Cu")
		(net "M_C_CPU0_SB_DQ<2>")
	)
	(segment
		(start 291.135562 -282.760166)
		(end 290.972748 -282.597352)
		(width 0.14478)
		(layer "In2.Cu")
		(net "M_C_CPU0_SB_DQ<2>")
	)
	(segment
		(start 325.525892 -273.78533)
		(end 324.508114 -273.78533)
		(width 0.0889)
		(layer "In2.Cu")
		(net "M_C_CPU0_SB_DQ<2>")
	)
	(segment
		(start 298.06392 -281.910028)
		(end 297.213782 -282.760166)
		(width 0.14478)
		(layer "In2.Cu")
		(net "M_C_CPU0_SB_DQ<2>")
	)
	(segment
		(start 290.809934 -281.94381)
		(end 290.579302 -281.94381)
		(width 0.14478)
		(layer "In2.Cu")
		(net "M_C_CPU0_SB_DQ<2>")
	)
	(segment
		(start 318.017652 -273.67484)
		(end 313.655964 -278.036528)
		(width 0.14478)
		(layer "In2.Cu")
		(net "M_C_CPU0_SB_DQ<2>")
	)
	(segment
		(start 289.860228 -282.597352)
		(end 289.860228 -282.106624)
		(width 0.14478)
		(layer "In2.Cu")
		(net "M_C_CPU0_SB_DQ<2>")
	)
	(segment
		(start 289.141154 -282.760166)
		(end 288.605214 -282.760166)
		(width 0.14478)
		(layer "In2.Cu")
		(net "M_C_CPU0_SB_DQ<2>")
	)
	(segment
		(start 289.303968 -282.106624)
		(end 289.303968 -282.597352)
		(width 0.14478)
		(layer "In2.Cu")
		(net "M_C_CPU0_SB_DQ<2>")
	)
	(segment
		(start 290.416488 -282.106624)
		(end 290.416488 -282.597352)
		(width 0.14478)
		(layer "In2.Cu")
		(net "M_C_CPU0_SB_DQ<2>")
	)
	(segment
		(start 324.508114 -273.78533)
		(end 324.397624 -273.67484)
		(width 0.0889)
		(layer "In2.Cu")
		(net "M_C_CPU0_SB_DQ<2>")
	)
	(segment
		(start 288.605214 -282.760166)
		(end 288.180018 -282.33497)
		(width 0.14478)
		(layer "In2.Cu")
		(net "M_C_CPU0_SB_DQ<2>")
	)
	(segment
		(start 290.972748 -282.597352)
		(end 290.972748 -282.106624)
		(width 0.14478)
		(layer "In2.Cu")
		(net "M_C_CPU0_SB_DQ<2>")
	)
	(segment
		(start 327.875392 -274.573746)
		(end 327.851516 -274.587716)
		(width 0.0889)
		(layer "In2.Cu")
		(net "M_C_CPU0_SB_DQ<2>")
	)
	(segment
		(start 290.416488 -282.597352)
		(end 290.253674 -282.760166)
		(width 0.14478)
		(layer "In2.Cu")
		(net "M_C_CPU0_SB_DQ<2>")
	)
	(segment
		(start 336.342482 -274.568666)
		(end 336.3341 -274.573492)
		(width 0.0889)
		(layer "In2.Cu")
		(net "M_C_CPU0_SB_DQ<2>")
	)
	(segment
		(start 301.85741 -282.760166)
		(end 301.007272 -281.910028)
		(width 0.14478)
		(layer "In2.Cu")
		(net "M_C_CPU0_SB_DQ<2>")
	)
	(segment
		(start 312.574432 -278.036528)
		(end 308.700932 -281.910028)
		(width 0.14478)
		(layer "In2.Cu")
		(net "M_C_CPU0_SB_DQ<2>")
	)
	(segment
		(start 342.161114 -274.896072)
		(end 342.315038 -274.630642)
		(width 0.0889)
		(layer "In2.Cu")
		(net "M_C_CPU0_SB_DQ<2>")
	)
	(segment
		(start 338.588096 -274.573492)
		(end 338.579714 -274.568666)
		(width 0.0889)
		(layer "In2.Cu")
		(net "M_C_CPU0_SB_DQ<2>")
	)
	(segment
		(start 290.023042 -282.760166)
		(end 289.860228 -282.597352)
		(width 0.14478)
		(layer "In2.Cu")
		(net "M_C_CPU0_SB_DQ<2>")
	)
	(segment
		(start 290.253674 -282.760166)
		(end 290.023042 -282.760166)
		(width 0.14478)
		(layer "In2.Cu")
		(net "M_C_CPU0_SB_DQ<2>")
	)
	(segment
		(start 289.466782 -281.94381)
		(end 289.303968 -282.106624)
		(width 0.14478)
		(layer "In2.Cu")
		(net "M_C_CPU0_SB_DQ<2>")
	)
	(segment
		(start 304.597054 -282.760166)
		(end 301.85741 -282.760166)
		(width 0.14478)
		(layer "In2.Cu")
		(net "M_C_CPU0_SB_DQ<2>")
	)
	(segment
		(start 290.972748 -282.106624)
		(end 290.809934 -281.94381)
		(width 0.14478)
		(layer "In2.Cu")
		(net "M_C_CPU0_SB_DQ<2>")
	)
	(segment
		(start 335.402428 -274.568666)
		(end 335.394046 -274.573492)
		(width 0.0889)
		(layer "In2.Cu")
		(net "M_C_CPU0_SB_DQ<2>")
	)
	(segment
		(start 339.52815 -274.573492)
		(end 339.519768 -274.568666)
		(width 0.0889)
		(layer "In2.Cu")
		(net "M_C_CPU0_SB_DQ<2>")
	)
	(segment
		(start 326.22109 -274.480528)
		(end 325.525892 -273.78533)
		(width 0.0889)
		(layer "In2.Cu")
		(net "M_C_CPU0_SB_DQ<2>")
	)
	(segment
		(start 324.397624 -273.67484)
		(end 323.876924 -273.67484)
		(width 0.0889)
		(layer "In2.Cu")
		(net "M_C_CPU0_SB_DQ<2>")
	)
	(segment
		(start 290.579302 -281.94381)
		(end 290.416488 -282.106624)
		(width 0.14478)
		(layer "In2.Cu")
		(net "M_C_CPU0_SB_DQ<2>")
	)
	(segment
		(start 313.655964 -278.036528)
		(end 312.574432 -278.036528)
		(width 0.14478)
		(layer "In2.Cu")
		(net "M_C_CPU0_SB_DQ<2>")
	)
	(segment
		(start 327.311258 -274.573492)
		(end 327.290684 -274.561554)
		(width 0.0889)
		(layer "In2.Cu")
		(net "M_C_CPU0_SB_DQ<2>")
	)
	(segment
		(start 289.860228 -282.106624)
		(end 289.697414 -281.94381)
		(width 0.14478)
		(layer "In2.Cu")
		(net "M_C_CPU0_SB_DQ<2>")
	)
	(segment
		(start 333.88808 -274.573492)
		(end 333.879698 -274.568666)
		(width 0.0889)
		(layer "In2.Cu")
		(net "M_C_CPU0_SB_DQ<2>")
	)
	(segment
		(start 330.702412 -274.568666)
		(end 330.69403 -274.573492)
		(width 0.0889)
		(layer "In2.Cu")
		(net "M_C_CPU0_SB_DQ<2>")
	)
	(segment
		(start 289.697414 -281.94381)
		(end 289.466782 -281.94381)
		(width 0.14478)
		(layer "In2.Cu")
		(net "M_C_CPU0_SB_DQ<2>")
	)
	(segment
		(start 326.935846 -274.573492)
		(end 326.91832 -274.583652)
		(width 0.0889)
		(layer "In2.Cu")
		(net "M_C_CPU0_SB_DQ<2>")
	)
	(segment
		(start 327.89876 -274.560284)
		(end 327.875392 -274.573746)
		(width 0.0889)
		(layer "In2.Cu")
		(net "M_C_CPU0_SB_DQ<2>")
	)
	(segment
		(start 330.128118 -274.573492)
		(end 330.119736 -274.568666)
		(width 0.0889)
		(layer "In2.Cu")
		(net "M_C_CPU0_SB_DQ<2>")
	)
	(segment
		(start 342.315038 -274.630642)
		(end 342.292686 -274.54733)
		(width 0.0889)
		(layer "In2.Cu")
		(net "M_C_CPU0_SB_DQ<2>")
	)
	(segment
		(start 305.447192 -281.910028)
		(end 304.597054 -282.760166)
		(width 0.14478)
		(layer "In2.Cu")
		(net "M_C_CPU0_SB_DQ<2>")
	)
	(segment
		(start 334.828134 -274.573492)
		(end 334.819752 -274.568666)
		(width 0.0889)
		(layer "In2.Cu")
		(net "M_C_CPU0_SB_DQ<2>")
	)
	(segment
		(start 308.700932 -281.910028)
		(end 305.447192 -281.910028)
		(width 0.14478)
		(layer "In2.Cu")
		(net "M_C_CPU0_SB_DQ<2>")
	)
	(segment
		(start 326.651112 -274.656042)
		(end 326.644762 -274.656042)
		(width 0.0889)
		(layer "In2.Cu")
		(net "M_C_CPU0_SB_DQ<2>")
	)
	(segment
		(start 323.876924 -273.67484)
		(end 318.017652 -273.67484)
		(width 0.14478)
		(layer "In2.Cu")
		(net "M_C_CPU0_SB_DQ<2>")
	)
	(segment
		(start 301.007272 -281.910028)
		(end 298.06392 -281.910028)
		(width 0.14478)
		(layer "In2.Cu")
		(net "M_C_CPU0_SB_DQ<2>")
	)
	(segment
		(start 297.213782 -282.760166)
		(end 291.135562 -282.760166)
		(width 0.14478)
		(layer "In2.Cu")
		(net "M_C_CPU0_SB_DQ<2>")
	)
	(segment
		(start 341.042498 -274.568666)
		(end 341.034116 -274.573492)
		(width 0.0889)
		(layer "In2.Cu")
		(net "M_C_CPU0_SB_DQ<2>")
	)
	(arc
		(start 330.69403 -274.573492)
		(mid 330.411074 -274.649669)
		(end 330.128118 -274.573492)
		(width 0.0889)
		(layer "In2.Cu")
		(net "M_C_CPU0_SB_DQ<2>")
	)
	(arc
		(start 327.290684 -274.561554)
		(mid 327.111756 -274.522677)
		(end 326.935846 -274.573492)
		(width 0.0889)
		(layer "In2.Cu")
		(net "M_C_CPU0_SB_DQ<2>")
	)
	(arc
		(start 328.814176 -274.573492)
		(mid 328.53122 -274.649669)
		(end 328.248264 -274.573492)
		(width 0.0889)
		(layer "In2.Cu")
		(net "M_C_CPU0_SB_DQ<2>")
	)
	(arc
		(start 337.274154 -274.573492)
		(mid 336.991198 -274.649669)
		(end 336.708242 -274.573492)
		(width 0.0889)
		(layer "In2.Cu")
		(net "M_C_CPU0_SB_DQ<2>")
	)
	(arc
		(start 341.034116 -274.573492)
		(mid 340.75116 -274.649669)
		(end 340.468204 -274.573492)
		(width 0.0889)
		(layer "In2.Cu")
		(net "M_C_CPU0_SB_DQ<2>")
	)
	(arc
		(start 338.213954 -274.573492)
		(mid 337.930998 -274.649669)
		(end 337.648042 -274.573492)
		(width 0.0889)
		(layer "In2.Cu")
		(net "M_C_CPU0_SB_DQ<2>")
	)
	(arc
		(start 329.753976 -274.573492)
		(mid 329.47102 -274.649669)
		(end 329.188064 -274.573492)
		(width 0.0889)
		(layer "In2.Cu")
		(net "M_C_CPU0_SB_DQ<2>")
	)
	(arc
		(start 334.453992 -274.573492)
		(mid 334.171036 -274.649669)
		(end 333.88808 -274.573492)
		(width 0.0889)
		(layer "In2.Cu")
		(net "M_C_CPU0_SB_DQ<2>")
	)
	(arc
		(start 342.292686 -274.54733)
		(mid 342.130497 -274.524595)
		(end 341.97417 -274.573492)
		(width 0.0889)
		(layer "In2.Cu")
		(net "M_C_CPU0_SB_DQ<2>")
	)
	(arc
		(start 332.574138 -274.573492)
		(mid 332.291182 -274.649669)
		(end 332.008226 -274.573492)
		(width 0.0889)
		(layer "In2.Cu")
		(net "M_C_CPU0_SB_DQ<2>")
	)
	(arc
		(start 338.579714 -274.568666)
		(mid 338.396206 -274.523172)
		(end 338.213954 -274.573492)
		(width 0.0889)
		(layer "In2.Cu")
		(net "M_C_CPU0_SB_DQ<2>")
	)
	(arc
		(start 334.819752 -274.568666)
		(mid 334.636244 -274.523172)
		(end 334.453992 -274.573492)
		(width 0.0889)
		(layer "In2.Cu")
		(net "M_C_CPU0_SB_DQ<2>")
	)
	(arc
		(start 327.851516 -274.587716)
		(mid 327.579579 -274.649542)
		(end 327.311258 -274.573492)
		(width 0.0889)
		(layer "In2.Cu")
		(net "M_C_CPU0_SB_DQ<2>")
	)
	(arc
		(start 332.008226 -274.573492)
		(mid 331.825975 -274.523142)
		(end 331.642466 -274.568666)
		(width 0.0889)
		(layer "In2.Cu")
		(net "M_C_CPU0_SB_DQ<2>")
	)
	(arc
		(start 336.3341 -274.573492)
		(mid 336.051144 -274.649669)
		(end 335.768188 -274.573492)
		(width 0.0889)
		(layer "In2.Cu")
		(net "M_C_CPU0_SB_DQ<2>")
	)
	(arc
		(start 329.188064 -274.573492)
		(mid 329.00112 -274.523237)
		(end 328.814176 -274.573492)
		(width 0.0889)
		(layer "In2.Cu")
		(net "M_C_CPU0_SB_DQ<2>")
	)
	(arc
		(start 331.068172 -274.573492)
		(mid 330.885921 -274.523142)
		(end 330.702412 -274.568666)
		(width 0.0889)
		(layer "In2.Cu")
		(net "M_C_CPU0_SB_DQ<2>")
	)
	(arc
		(start 341.97417 -274.573492)
		(mid 341.691214 -274.649669)
		(end 341.408258 -274.573492)
		(width 0.0889)
		(layer "In2.Cu")
		(net "M_C_CPU0_SB_DQ<2>")
	)
	(arc
		(start 335.768188 -274.573492)
		(mid 335.585937 -274.523142)
		(end 335.402428 -274.568666)
		(width 0.0889)
		(layer "In2.Cu")
		(net "M_C_CPU0_SB_DQ<2>")
	)
	(arc
		(start 332.948026 -274.573492)
		(mid 332.761082 -274.523237)
		(end 332.574138 -274.573492)
		(width 0.0889)
		(layer "In2.Cu")
		(net "M_C_CPU0_SB_DQ<2>")
	)
	(arc
		(start 335.394046 -274.573492)
		(mid 335.11109 -274.649669)
		(end 334.828134 -274.573492)
		(width 0.0889)
		(layer "In2.Cu")
		(net "M_C_CPU0_SB_DQ<2>")
	)
	(arc
		(start 337.648042 -274.573492)
		(mid 337.461098 -274.523237)
		(end 337.274154 -274.573492)
		(width 0.0889)
		(layer "In2.Cu")
		(net "M_C_CPU0_SB_DQ<2>")
	)
	(arc
		(start 340.094062 -274.573492)
		(mid 339.811106 -274.649669)
		(end 339.52815 -274.573492)
		(width 0.0889)
		(layer "In2.Cu")
		(net "M_C_CPU0_SB_DQ<2>")
	)
	(arc
		(start 326.644762 -274.656042)
		(mid 326.415463 -274.610432)
		(end 326.22109 -274.480528)
		(width 0.0889)
		(layer "In2.Cu")
		(net "M_C_CPU0_SB_DQ<2>")
	)
	(arc
		(start 341.408258 -274.573492)
		(mid 341.226007 -274.523142)
		(end 341.042498 -274.568666)
		(width 0.0889)
		(layer "In2.Cu")
		(net "M_C_CPU0_SB_DQ<2>")
	)
	(arc
		(start 333.879698 -274.568666)
		(mid 333.69619 -274.523172)
		(end 333.513938 -274.573492)
		(width 0.0889)
		(layer "In2.Cu")
		(net "M_C_CPU0_SB_DQ<2>")
	)
	(arc
		(start 339.154008 -274.573492)
		(mid 338.871052 -274.649669)
		(end 338.588096 -274.573492)
		(width 0.0889)
		(layer "In2.Cu")
		(net "M_C_CPU0_SB_DQ<2>")
	)
	(arc
		(start 339.519768 -274.568666)
		(mid 339.33626 -274.523172)
		(end 339.154008 -274.573492)
		(width 0.0889)
		(layer "In2.Cu")
		(net "M_C_CPU0_SB_DQ<2>")
	)
	(arc
		(start 328.248264 -274.573492)
		(mid 328.075156 -274.523376)
		(end 327.89876 -274.560284)
		(width 0.0889)
		(layer "In2.Cu")
		(net "M_C_CPU0_SB_DQ<2>")
	)
	(arc
		(start 330.119736 -274.568666)
		(mid 329.936228 -274.523172)
		(end 329.753976 -274.573492)
		(width 0.0889)
		(layer "In2.Cu")
		(net "M_C_CPU0_SB_DQ<2>")
	)
	(arc
		(start 331.634084 -274.573492)
		(mid 331.351128 -274.649669)
		(end 331.068172 -274.573492)
		(width 0.0889)
		(layer "In2.Cu")
		(net "M_C_CPU0_SB_DQ<2>")
	)
	(arc
		(start 326.91832 -274.583652)
		(mid 326.789523 -274.637575)
		(end 326.651112 -274.656042)
		(width 0.0889)
		(layer "In2.Cu")
		(net "M_C_CPU0_SB_DQ<2>")
	)
	(arc
		(start 340.468204 -274.573492)
		(mid 340.285953 -274.523142)
		(end 340.102444 -274.568666)
		(width 0.0889)
		(layer "In2.Cu")
		(net "M_C_CPU0_SB_DQ<2>")
	)
	(arc
		(start 333.513938 -274.573492)
		(mid 333.230982 -274.649669)
		(end 332.948026 -274.573492)
		(width 0.0889)
		(layer "In2.Cu")
		(net "M_C_CPU0_SB_DQ<2>")
	)
	(arc
		(start 336.708242 -274.573492)
		(mid 336.525991 -274.523142)
		(end 336.342482 -274.568666)
		(width 0.0889)
		(layer "In2.Cu")
		(net "M_C_CPU0_SB_DQ<2>")
	)
	(segment
		(start 344.508074 -292.450012)
		(end 344.041222 -292.71595)
		(width 0.10668)
		(layer "F.Cu")
		(net "M_C_CPU0_SB_DQ<29>")
	)
	(segment
		(start 318.1223 -310.14162)
		(end 318.1223 -310.371744)
		(width 0.14478)
		(layer "In2.Cu")
		(net "M_C_CPU0_SB_DQ<29>")
	)
	(segment
		(start 328.278744 -294.640762)
		(end 328.248264 -294.658542)
		(width 0.0889)
		(layer "In2.Cu")
		(net "M_C_CPU0_SB_DQ<29>")
	)
	(segment
		(start 339.52815 -293.03853)
		(end 339.519768 -293.043356)
		(width 0.0889)
		(layer "In2.Cu")
		(net "M_C_CPU0_SB_DQ<29>")
	)
	(segment
		(start 321.269868 -306.995322)
		(end 321.269868 -307.224176)
		(width 0.14478)
		(layer "In2.Cu")
		(net "M_C_CPU0_SB_DQ<29>")
	)
	(segment
		(start 327.307448 -296.40911)
		(end 327.307448 -300.957742)
		(width 0.14478)
		(layer "In2.Cu")
		(net "M_C_CPU0_SB_DQ<29>")
	)
	(segment
		(start 318.515746 -309.978298)
		(end 318.285622 -309.978298)
		(width 0.14478)
		(layer "In2.Cu")
		(net "M_C_CPU0_SB_DQ<29>")
	)
	(segment
		(start 318.836294 -310.298846)
		(end 318.515746 -309.978298)
		(width 0.14478)
		(layer "In2.Cu")
		(net "M_C_CPU0_SB_DQ<29>")
	)
	(segment
		(start 319.623186 -309.511954)
		(end 319.302638 -309.191406)
		(width 0.14478)
		(layer "In2.Cu")
		(net "M_C_CPU0_SB_DQ<29>")
	)
	(segment
		(start 318.442848 -310.692292)
		(end 318.442848 -310.922416)
		(width 0.14478)
		(layer "In2.Cu")
		(net "M_C_CPU0_SB_DQ<29>")
	)
	(segment
		(start 343.288112 -293.03853)
		(end 343.27973 -293.043356)
		(width 0.0889)
		(layer "In2.Cu")
		(net "M_C_CPU0_SB_DQ<29>")
	)
	(segment
		(start 319.22974 -310.135524)
		(end 319.066418 -310.298846)
		(width 0.14478)
		(layer "In2.Cu")
		(net "M_C_CPU0_SB_DQ<29>")
	)
	(segment
		(start 319.696084 -308.567836)
		(end 319.696084 -308.79796)
		(width 0.14478)
		(layer "In2.Cu")
		(net "M_C_CPU0_SB_DQ<29>")
	)
	(segment
		(start 343.887044 -292.98138)
		(end 343.790778 -293.00678)
		(width 0.0889)
		(layer "In2.Cu")
		(net "M_C_CPU0_SB_DQ<29>")
	)
	(segment
		(start 318.442848 -310.922416)
		(end 318.279526 -311.085738)
		(width 0.14478)
		(layer "In2.Cu")
		(net "M_C_CPU0_SB_DQ<29>")
	)
	(segment
		(start 320.640202 -308.725062)
		(end 320.410078 -308.725062)
		(width 0.14478)
		(layer "In2.Cu")
		(net "M_C_CPU0_SB_DQ<29>")
	)
	(segment
		(start 334.828134 -293.03853)
		(end 334.819752 -293.043356)
		(width 0.0889)
		(layer "In2.Cu")
		(net "M_C_CPU0_SB_DQ<29>")
	)
	(segment
		(start 320.803524 -308.331616)
		(end 320.803524 -308.56174)
		(width 0.14478)
		(layer "In2.Cu")
		(net "M_C_CPU0_SB_DQ<29>")
	)
	(segment
		(start 344.041222 -292.71595)
		(end 343.887044 -292.98138)
		(width 0.0889)
		(layer "In2.Cu")
		(net "M_C_CPU0_SB_DQ<29>")
	)
	(segment
		(start 328.718164 -293.848536)
		(end 328.679048 -293.871396)
		(width 0.0889)
		(layer "In2.Cu")
		(net "M_C_CPU0_SB_DQ<29>")
	)
	(segment
		(start 329.188064 -293.03853)
		(end 329.186032 -293.0398)
		(width 0.0889)
		(layer "In2.Cu")
		(net "M_C_CPU0_SB_DQ<29>")
	)
	(segment
		(start 327.810114 -295.45026)
		(end 327.778364 -295.468548)
		(width 0.0889)
		(layer "In2.Cu")
		(net "M_C_CPU0_SB_DQ<29>")
	)
	(segment
		(start 327.307448 -300.957742)
		(end 321.269868 -306.995322)
		(width 0.14478)
		(layer "In2.Cu")
		(net "M_C_CPU0_SB_DQ<29>")
	)
	(segment
		(start 328.248264 -294.658542)
		(end 328.211942 -294.679624)
		(width 0.0889)
		(layer "In2.Cu")
		(net "M_C_CPU0_SB_DQ<29>")
	)
	(segment
		(start 330.702412 -293.043356)
		(end 330.69403 -293.03853)
		(width 0.0889)
		(layer "In2.Cu")
		(net "M_C_CPU0_SB_DQ<29>")
	)
	(segment
		(start 321.427094 -307.93817)
		(end 321.19697 -307.93817)
		(width 0.14478)
		(layer "In2.Cu")
		(net "M_C_CPU0_SB_DQ<29>")
	)
	(segment
		(start 320.016632 -309.348632)
		(end 319.85331 -309.511954)
		(width 0.14478)
		(layer "In2.Cu")
		(net "M_C_CPU0_SB_DQ<29>")
	)
	(segment
		(start 341.042498 -293.043356)
		(end 341.034116 -293.03853)
		(width 0.0889)
		(layer "In2.Cu")
		(net "M_C_CPU0_SB_DQ<29>")
	)
	(segment
		(start 321.590416 -307.544724)
		(end 321.590416 -307.774848)
		(width 0.14478)
		(layer "In2.Cu")
		(net "M_C_CPU0_SB_DQ<29>")
	)
	(segment
		(start 327.778364 -295.468548)
		(end 327.739248 -295.491408)
		(width 0.0889)
		(layer "In2.Cu")
		(net "M_C_CPU0_SB_DQ<29>")
	)
	(segment
		(start 318.1223 -310.371744)
		(end 318.442848 -310.692292)
		(width 0.14478)
		(layer "In2.Cu")
		(net "M_C_CPU0_SB_DQ<29>")
	)
	(segment
		(start 320.482976 -308.011068)
		(end 320.803524 -308.331616)
		(width 0.14478)
		(layer "In2.Cu")
		(net "M_C_CPU0_SB_DQ<29>")
	)
	(segment
		(start 340.102444 -293.043356)
		(end 340.094062 -293.03853)
		(width 0.0889)
		(layer "In2.Cu")
		(net "M_C_CPU0_SB_DQ<29>")
	)
	(segment
		(start 336.342482 -293.043356)
		(end 336.3341 -293.03853)
		(width 0.0889)
		(layer "In2.Cu")
		(net "M_C_CPU0_SB_DQ<29>")
	)
	(segment
		(start 331.642466 -293.043356)
		(end 331.634084 -293.03853)
		(width 0.0889)
		(layer "In2.Cu")
		(net "M_C_CPU0_SB_DQ<29>")
	)
	(segment
		(start 321.19697 -307.93817)
		(end 320.876422 -307.617622)
		(width 0.14478)
		(layer "In2.Cu")
		(net "M_C_CPU0_SB_DQ<29>")
	)
	(segment
		(start 320.803524 -308.56174)
		(end 320.640202 -308.725062)
		(width 0.14478)
		(layer "In2.Cu")
		(net "M_C_CPU0_SB_DQ<29>")
	)
	(segment
		(start 321.590416 -307.774848)
		(end 321.427094 -307.93817)
		(width 0.14478)
		(layer "In2.Cu")
		(net "M_C_CPU0_SB_DQ<29>")
	)
	(segment
		(start 328.749914 -293.830248)
		(end 328.718164 -293.848536)
		(width 0.0889)
		(layer "In2.Cu")
		(net "M_C_CPU0_SB_DQ<29>")
	)
	(segment
		(start 318.279526 -311.085738)
		(end 318.049402 -311.085738)
		(width 0.14478)
		(layer "In2.Cu")
		(net "M_C_CPU0_SB_DQ<29>")
	)
	(segment
		(start 319.22974 -309.9054)
		(end 319.22974 -310.135524)
		(width 0.14478)
		(layer "In2.Cu")
		(net "M_C_CPU0_SB_DQ<29>")
	)
	(segment
		(start 320.08953 -308.404514)
		(end 319.859406 -308.404514)
		(width 0.14478)
		(layer "In2.Cu")
		(net "M_C_CPU0_SB_DQ<29>")
	)
	(segment
		(start 317.728854 -310.76519)
		(end 317.5 -310.76519)
		(width 0.14478)
		(layer "In2.Cu")
		(net "M_C_CPU0_SB_DQ<29>")
	)
	(segment
		(start 327.406254 -296.172382)
		(end 327.307448 -296.271188)
		(width 0.0889)
		(layer "In2.Cu")
		(net "M_C_CPU0_SB_DQ<29>")
	)
	(segment
		(start 320.876422 -307.617622)
		(end 320.646298 -307.617622)
		(width 0.14478)
		(layer "In2.Cu")
		(net "M_C_CPU0_SB_DQ<29>")
	)
	(segment
		(start 319.696084 -308.79796)
		(end 320.016632 -309.118508)
		(width 0.14478)
		(layer "In2.Cu")
		(net "M_C_CPU0_SB_DQ<29>")
	)
	(segment
		(start 333.88808 -293.03853)
		(end 333.879698 -293.043356)
		(width 0.0889)
		(layer "In2.Cu")
		(net "M_C_CPU0_SB_DQ<29>")
	)
	(segment
		(start 319.85331 -309.511954)
		(end 319.623186 -309.511954)
		(width 0.14478)
		(layer "In2.Cu")
		(net "M_C_CPU0_SB_DQ<29>")
	)
	(segment
		(start 318.909192 -309.584852)
		(end 319.22974 -309.9054)
		(width 0.14478)
		(layer "In2.Cu")
		(net "M_C_CPU0_SB_DQ<29>")
	)
	(segment
		(start 320.410078 -308.725062)
		(end 320.08953 -308.404514)
		(width 0.14478)
		(layer "In2.Cu")
		(net "M_C_CPU0_SB_DQ<29>")
	)
	(segment
		(start 330.128118 -293.03853)
		(end 330.127864 -293.03853)
		(width 0.0889)
		(layer "In2.Cu")
		(net "M_C_CPU0_SB_DQ<29>")
	)
	(segment
		(start 338.588096 -293.03853)
		(end 338.579714 -293.043356)
		(width 0.0889)
		(layer "In2.Cu")
		(net "M_C_CPU0_SB_DQ<29>")
	)
	(segment
		(start 327.307448 -296.271188)
		(end 327.307448 -296.40911)
		(width 0.0889)
		(layer "In2.Cu")
		(net "M_C_CPU0_SB_DQ<29>")
	)
	(segment
		(start 320.482976 -307.780944)
		(end 320.482976 -308.011068)
		(width 0.14478)
		(layer "In2.Cu")
		(net "M_C_CPU0_SB_DQ<29>")
	)
	(segment
		(start 318.909192 -309.354728)
		(end 318.909192 -309.584852)
		(width 0.14478)
		(layer "In2.Cu")
		(net "M_C_CPU0_SB_DQ<29>")
	)
	(segment
		(start 317.5 -310.76519)
		(end 310.654954 -317.610236)
		(width 0.14478)
		(layer "In2.Cu")
		(net "M_C_CPU0_SB_DQ<29>")
	)
	(segment
		(start 335.402428 -293.043356)
		(end 335.394046 -293.03853)
		(width 0.0889)
		(layer "In2.Cu")
		(net "M_C_CPU0_SB_DQ<29>")
	)
	(segment
		(start 292.705282 -317.610236)
		(end 292.280086 -317.18504)
		(width 0.14478)
		(layer "In2.Cu")
		(net "M_C_CPU0_SB_DQ<29>")
	)
	(segment
		(start 319.859406 -308.404514)
		(end 319.696084 -308.567836)
		(width 0.14478)
		(layer "In2.Cu")
		(net "M_C_CPU0_SB_DQ<29>")
	)
	(segment
		(start 320.646298 -307.617622)
		(end 320.482976 -307.780944)
		(width 0.14478)
		(layer "In2.Cu")
		(net "M_C_CPU0_SB_DQ<29>")
	)
	(segment
		(start 318.049402 -311.085738)
		(end 317.728854 -310.76519)
		(width 0.14478)
		(layer "In2.Cu")
		(net "M_C_CPU0_SB_DQ<29>")
	)
	(segment
		(start 319.302638 -309.191406)
		(end 319.072514 -309.191406)
		(width 0.14478)
		(layer "In2.Cu")
		(net "M_C_CPU0_SB_DQ<29>")
	)
	(segment
		(start 320.016632 -309.118508)
		(end 320.016632 -309.348632)
		(width 0.14478)
		(layer "In2.Cu")
		(net "M_C_CPU0_SB_DQ<29>")
	)
	(segment
		(start 319.072514 -309.191406)
		(end 318.909192 -309.354728)
		(width 0.14478)
		(layer "In2.Cu")
		(net "M_C_CPU0_SB_DQ<29>")
	)
	(segment
		(start 319.066418 -310.298846)
		(end 318.836294 -310.298846)
		(width 0.14478)
		(layer "In2.Cu")
		(net "M_C_CPU0_SB_DQ<29>")
	)
	(segment
		(start 321.269868 -307.224176)
		(end 321.590416 -307.544724)
		(width 0.14478)
		(layer "In2.Cu")
		(net "M_C_CPU0_SB_DQ<29>")
	)
	(segment
		(start 310.654954 -317.610236)
		(end 292.705282 -317.610236)
		(width 0.14478)
		(layer "In2.Cu")
		(net "M_C_CPU0_SB_DQ<29>")
	)
	(segment
		(start 318.285622 -309.978298)
		(end 318.1223 -310.14162)
		(width 0.14478)
		(layer "In2.Cu")
		(net "M_C_CPU0_SB_DQ<29>")
	)
	(arc
		(start 328.679048 -293.871396)
		(mid 328.500235 -294.073746)
		(end 328.435716 -294.335962)
		(width 0.0889)
		(layer "In2.Cu")
		(net "M_C_CPU0_SB_DQ<29>")
	)
	(arc
		(start 330.69403 -293.03853)
		(mid 330.411074 -292.962353)
		(end 330.128118 -293.03853)
		(width 0.0889)
		(layer "In2.Cu")
		(net "M_C_CPU0_SB_DQ<29>")
	)
	(arc
		(start 333.879698 -293.043356)
		(mid 333.69619 -293.08885)
		(end 333.513938 -293.03853)
		(width 0.0889)
		(layer "In2.Cu")
		(net "M_C_CPU0_SB_DQ<29>")
	)
	(arc
		(start 340.094062 -293.03853)
		(mid 339.811106 -292.962353)
		(end 339.52815 -293.03853)
		(width 0.0889)
		(layer "In2.Cu")
		(net "M_C_CPU0_SB_DQ<29>")
	)
	(arc
		(start 336.3341 -293.03853)
		(mid 336.051144 -292.962353)
		(end 335.768188 -293.03853)
		(width 0.0889)
		(layer "In2.Cu")
		(net "M_C_CPU0_SB_DQ<29>")
	)
	(arc
		(start 331.634084 -293.03853)
		(mid 331.351128 -292.962353)
		(end 331.068172 -293.03853)
		(width 0.0889)
		(layer "In2.Cu")
		(net "M_C_CPU0_SB_DQ<29>")
	)
	(arc
		(start 330.127864 -293.03853)
		(mid 329.94092 -293.088854)
		(end 329.753976 -293.03853)
		(width 0.0889)
		(layer "In2.Cu")
		(net "M_C_CPU0_SB_DQ<29>")
	)
	(arc
		(start 328.90587 -293.525956)
		(mid 328.864615 -293.696927)
		(end 328.749914 -293.830248)
		(width 0.0889)
		(layer "In2.Cu")
		(net "M_C_CPU0_SB_DQ<29>")
	)
	(arc
		(start 335.768188 -293.03853)
		(mid 335.585937 -293.08888)
		(end 335.402428 -293.043356)
		(width 0.0889)
		(layer "In2.Cu")
		(net "M_C_CPU0_SB_DQ<29>")
	)
	(arc
		(start 332.008226 -293.03853)
		(mid 331.825975 -293.08888)
		(end 331.642466 -293.043356)
		(width 0.0889)
		(layer "In2.Cu")
		(net "M_C_CPU0_SB_DQ<29>")
	)
	(arc
		(start 337.274154 -293.03853)
		(mid 336.991198 -292.962353)
		(end 336.708242 -293.03853)
		(width 0.0889)
		(layer "In2.Cu")
		(net "M_C_CPU0_SB_DQ<29>")
	)
	(arc
		(start 328.435716 -294.335962)
		(mid 328.394167 -294.507384)
		(end 328.278744 -294.640762)
		(width 0.0889)
		(layer "In2.Cu")
		(net "M_C_CPU0_SB_DQ<29>")
	)
	(arc
		(start 328.211942 -294.679624)
		(mid 328.03129 -294.882369)
		(end 327.96607 -295.145968)
		(width 0.0889)
		(layer "In2.Cu")
		(net "M_C_CPU0_SB_DQ<29>")
	)
	(arc
		(start 336.708242 -293.03853)
		(mid 336.525991 -293.08888)
		(end 336.342482 -293.043356)
		(width 0.0889)
		(layer "In2.Cu")
		(net "M_C_CPU0_SB_DQ<29>")
	)
	(arc
		(start 332.948026 -293.03853)
		(mid 332.761082 -293.088785)
		(end 332.574138 -293.03853)
		(width 0.0889)
		(layer "In2.Cu")
		(net "M_C_CPU0_SB_DQ<29>")
	)
	(arc
		(start 337.648042 -293.03853)
		(mid 337.461098 -293.088785)
		(end 337.274154 -293.03853)
		(width 0.0889)
		(layer "In2.Cu")
		(net "M_C_CPU0_SB_DQ<29>")
	)
	(arc
		(start 341.97417 -293.03853)
		(mid 341.691214 -292.962353)
		(end 341.408258 -293.03853)
		(width 0.0889)
		(layer "In2.Cu")
		(net "M_C_CPU0_SB_DQ<29>")
	)
	(arc
		(start 333.513938 -293.03853)
		(mid 333.230982 -292.962353)
		(end 332.948026 -293.03853)
		(width 0.0889)
		(layer "In2.Cu")
		(net "M_C_CPU0_SB_DQ<29>")
	)
	(arc
		(start 332.574138 -293.03853)
		(mid 332.291182 -292.962353)
		(end 332.008226 -293.03853)
		(width 0.0889)
		(layer "In2.Cu")
		(net "M_C_CPU0_SB_DQ<29>")
	)
	(arc
		(start 339.519768 -293.043356)
		(mid 339.33626 -293.08885)
		(end 339.154008 -293.03853)
		(width 0.0889)
		(layer "In2.Cu")
		(net "M_C_CPU0_SB_DQ<29>")
	)
	(arc
		(start 341.408258 -293.03853)
		(mid 341.226007 -293.08888)
		(end 341.042498 -293.043356)
		(width 0.0889)
		(layer "In2.Cu")
		(net "M_C_CPU0_SB_DQ<29>")
	)
	(arc
		(start 342.348058 -293.03853)
		(mid 342.161114 -293.088785)
		(end 341.97417 -293.03853)
		(width 0.0889)
		(layer "In2.Cu")
		(net "M_C_CPU0_SB_DQ<29>")
	)
	(arc
		(start 335.394046 -293.03853)
		(mid 335.11109 -292.962353)
		(end 334.828134 -293.03853)
		(width 0.0889)
		(layer "In2.Cu")
		(net "M_C_CPU0_SB_DQ<29>")
	)
	(arc
		(start 338.579714 -293.043356)
		(mid 338.396206 -293.08885)
		(end 338.213954 -293.03853)
		(width 0.0889)
		(layer "In2.Cu")
		(net "M_C_CPU0_SB_DQ<29>")
	)
	(arc
		(start 334.453992 -293.03853)
		(mid 334.171036 -292.962353)
		(end 333.88808 -293.03853)
		(width 0.0889)
		(layer "In2.Cu")
		(net "M_C_CPU0_SB_DQ<29>")
	)
	(arc
		(start 334.819752 -293.043356)
		(mid 334.636244 -293.08885)
		(end 334.453992 -293.03853)
		(width 0.0889)
		(layer "In2.Cu")
		(net "M_C_CPU0_SB_DQ<29>")
	)
	(arc
		(start 341.034116 -293.03853)
		(mid 340.75116 -292.962353)
		(end 340.468204 -293.03853)
		(width 0.0889)
		(layer "In2.Cu")
		(net "M_C_CPU0_SB_DQ<29>")
	)
	(arc
		(start 343.790778 -293.00678)
		(mid 343.535713 -292.963429)
		(end 343.288112 -293.03853)
		(width 0.0889)
		(layer "In2.Cu")
		(net "M_C_CPU0_SB_DQ<29>")
	)
	(arc
		(start 329.753976 -293.03853)
		(mid 329.47102 -292.962353)
		(end 329.188064 -293.03853)
		(width 0.0889)
		(layer "In2.Cu")
		(net "M_C_CPU0_SB_DQ<29>")
	)
	(arc
		(start 329.186032 -293.0398)
		(mid 328.98091 -293.245399)
		(end 328.90587 -293.525956)
		(width 0.0889)
		(layer "In2.Cu")
		(net "M_C_CPU0_SB_DQ<29>")
	)
	(arc
		(start 331.068172 -293.03853)
		(mid 330.885921 -293.08888)
		(end 330.702412 -293.043356)
		(width 0.0889)
		(layer "In2.Cu")
		(net "M_C_CPU0_SB_DQ<29>")
	)
	(arc
		(start 342.91397 -293.03853)
		(mid 342.631014 -292.962353)
		(end 342.348058 -293.03853)
		(width 0.0889)
		(layer "In2.Cu")
		(net "M_C_CPU0_SB_DQ<29>")
	)
	(arc
		(start 327.495916 -295.955974)
		(mid 327.472618 -296.073102)
		(end 327.406254 -296.172382)
		(width 0.0889)
		(layer "In2.Cu")
		(net "M_C_CPU0_SB_DQ<29>")
	)
	(arc
		(start 343.27973 -293.043356)
		(mid 343.096222 -293.08885)
		(end 342.91397 -293.03853)
		(width 0.0889)
		(layer "In2.Cu")
		(net "M_C_CPU0_SB_DQ<29>")
	)
	(arc
		(start 338.213954 -293.03853)
		(mid 337.930998 -292.962353)
		(end 337.648042 -293.03853)
		(width 0.0889)
		(layer "In2.Cu")
		(net "M_C_CPU0_SB_DQ<29>")
	)
	(arc
		(start 339.154008 -293.03853)
		(mid 338.871052 -292.962353)
		(end 338.588096 -293.03853)
		(width 0.0889)
		(layer "In2.Cu")
		(net "M_C_CPU0_SB_DQ<29>")
	)
	(arc
		(start 327.739248 -295.491408)
		(mid 327.560435 -295.693758)
		(end 327.495916 -295.955974)
		(width 0.0889)
		(layer "In2.Cu")
		(net "M_C_CPU0_SB_DQ<29>")
	)
	(arc
		(start 327.96607 -295.145968)
		(mid 327.924815 -295.316939)
		(end 327.810114 -295.45026)
		(width 0.0889)
		(layer "In2.Cu")
		(net "M_C_CPU0_SB_DQ<29>")
	)
	(arc
		(start 340.468204 -293.03853)
		(mid 340.285953 -293.08888)
		(end 340.102444 -293.043356)
		(width 0.0889)
		(layer "In2.Cu")
		(net "M_C_CPU0_SB_DQ<29>")
	)
	(segment
		(start 343.097866 -291.640006)
		(end 342.631014 -291.905944)
		(width 0.10668)
		(layer "F.Cu")
		(net "M_C_CPU0_SB_DQ<28>")
	)
	(segment
		(start 341.869776 -292.23335)
		(end 341.878158 -292.228524)
		(width 0.0889)
		(layer "In2.Cu")
		(net "M_C_CPU0_SB_DQ<28>")
	)
	(segment
		(start 312.564272 -314.070492)
		(end 312.197496 -313.703716)
		(width 0.14478)
		(layer "In2.Cu")
		(net "M_C_CPU0_SB_DQ<28>")
	)
	(segment
		(start 313.77128 -311.899808)
		(end 313.934602 -311.736486)
		(width 0.14478)
		(layer "In2.Cu")
		(net "M_C_CPU0_SB_DQ<28>")
	)
	(segment
		(start 312.957718 -313.677046)
		(end 313.187842 -313.677046)
		(width 0.14478)
		(layer "In2.Cu")
		(net "M_C_CPU0_SB_DQ<28>")
	)
	(segment
		(start 292.280086 -315.485018)
		(end 292.714934 -315.919866)
		(width 0.14478)
		(layer "In2.Cu")
		(net "M_C_CPU0_SB_DQ<28>")
	)
	(segment
		(start 313.934602 -311.736486)
		(end 314.164726 -311.736486)
		(width 0.14478)
		(layer "In2.Cu")
		(net "M_C_CPU0_SB_DQ<28>")
	)
	(segment
		(start 311.410604 -314.490608)
		(end 311.410604 -314.260484)
		(width 0.14478)
		(layer "In2.Cu")
		(net "M_C_CPU0_SB_DQ<28>")
	)
	(segment
		(start 326.243188 -294.747188)
		(end 326.306434 -294.683942)
		(width 0.0889)
		(layer "In2.Cu")
		(net "M_C_CPU0_SB_DQ<28>")
	)
	(segment
		(start 314.138056 -312.726832)
		(end 314.138056 -312.496708)
		(width 0.14478)
		(layer "In2.Cu")
		(net "M_C_CPU0_SB_DQ<28>")
	)
	(segment
		(start 310.623712 -315.2775)
		(end 310.623712 -315.047376)
		(width 0.14478)
		(layer "In2.Cu")
		(net "M_C_CPU0_SB_DQ<28>")
	)
	(segment
		(start 311.017158 -314.884054)
		(end 311.383934 -315.25083)
		(width 0.14478)
		(layer "In2.Cu")
		(net "M_C_CPU0_SB_DQ<28>")
	)
	(segment
		(start 327.778364 -292.228524)
		(end 327.788778 -292.222428)
		(width 0.0889)
		(layer "In2.Cu")
		(net "M_C_CPU0_SB_DQ<28>")
	)
	(segment
		(start 311.77738 -314.857384)
		(end 311.410604 -314.490608)
		(width 0.14478)
		(layer "In2.Cu")
		(net "M_C_CPU0_SB_DQ<28>")
	)
	(segment
		(start 314.164726 -311.736486)
		(end 314.531502 -312.103262)
		(width 0.14478)
		(layer "In2.Cu")
		(net "M_C_CPU0_SB_DQ<28>")
	)
	(segment
		(start 314.531502 -312.103262)
		(end 314.874402 -312.103262)
		(width 0.14478)
		(layer "In2.Cu")
		(net "M_C_CPU0_SB_DQ<28>")
	)
	(segment
		(start 312.197496 -313.473592)
		(end 312.360818 -313.31027)
		(width 0.14478)
		(layer "In2.Cu")
		(net "M_C_CPU0_SB_DQ<28>")
	)
	(segment
		(start 331.52969 -292.23335)
		(end 331.538072 -292.228524)
		(width 0.0889)
		(layer "In2.Cu")
		(net "M_C_CPU0_SB_DQ<28>")
	)
	(segment
		(start 312.984388 -312.6867)
		(end 313.14771 -312.523378)
		(width 0.14478)
		(layer "In2.Cu")
		(net "M_C_CPU0_SB_DQ<28>")
	)
	(segment
		(start 312.564272 -314.300616)
		(end 312.564272 -314.070492)
		(width 0.14478)
		(layer "In2.Cu")
		(net "M_C_CPU0_SB_DQ<28>")
	)
	(segment
		(start 340.929722 -292.23335)
		(end 340.938104 -292.228524)
		(width 0.0889)
		(layer "In2.Cu")
		(net "M_C_CPU0_SB_DQ<28>")
	)
	(segment
		(start 333.044038 -292.228524)
		(end 333.05242 -292.23335)
		(width 0.0889)
		(layer "In2.Cu")
		(net "M_C_CPU0_SB_DQ<28>")
	)
	(segment
		(start 313.74461 -312.890154)
		(end 313.974734 -312.890154)
		(width 0.14478)
		(layer "In2.Cu")
		(net "M_C_CPU0_SB_DQ<28>")
	)
	(segment
		(start 314.874402 -312.103262)
		(end 326.079612 -300.898052)
		(width 0.14478)
		(layer "In2.Cu")
		(net "M_C_CPU0_SB_DQ<28>")
	)
	(segment
		(start 310.787034 -314.884054)
		(end 311.017158 -314.884054)
		(width 0.14478)
		(layer "In2.Cu")
		(net "M_C_CPU0_SB_DQ<28>")
	)
	(segment
		(start 313.14771 -312.523378)
		(end 313.377834 -312.523378)
		(width 0.14478)
		(layer "In2.Cu")
		(net "M_C_CPU0_SB_DQ<28>")
	)
	(segment
		(start 292.714934 -315.919866)
		(end 310.714644 -315.919866)
		(width 0.14478)
		(layer "In2.Cu")
		(net "M_C_CPU0_SB_DQ<28>")
	)
	(segment
		(start 342.47709 -292.171374)
		(end 342.631014 -291.905944)
		(width 0.0889)
		(layer "In2.Cu")
		(net "M_C_CPU0_SB_DQ<28>")
	)
	(segment
		(start 313.351164 -313.513724)
		(end 313.351164 -313.2836)
		(width 0.14478)
		(layer "In2.Cu")
		(net "M_C_CPU0_SB_DQ<28>")
	)
	(segment
		(start 310.623712 -315.047376)
		(end 310.787034 -314.884054)
		(width 0.14478)
		(layer "In2.Cu")
		(net "M_C_CPU0_SB_DQ<28>")
	)
	(segment
		(start 312.984388 -312.916824)
		(end 312.984388 -312.6867)
		(width 0.14478)
		(layer "In2.Cu")
		(net "M_C_CPU0_SB_DQ<28>")
	)
	(segment
		(start 337.744054 -292.228524)
		(end 337.752436 -292.23335)
		(width 0.0889)
		(layer "In2.Cu")
		(net "M_C_CPU0_SB_DQ<28>")
	)
	(segment
		(start 333.984092 -292.228524)
		(end 333.992474 -292.23335)
		(width 0.0889)
		(layer "In2.Cu")
		(net "M_C_CPU0_SB_DQ<28>")
	)
	(segment
		(start 312.197496 -313.703716)
		(end 312.197496 -313.473592)
		(width 0.14478)
		(layer "In2.Cu")
		(net "M_C_CPU0_SB_DQ<28>")
	)
	(segment
		(start 313.974734 -312.890154)
		(end 314.138056 -312.726832)
		(width 0.14478)
		(layer "In2.Cu")
		(net "M_C_CPU0_SB_DQ<28>")
	)
	(segment
		(start 312.590942 -313.31027)
		(end 312.957718 -313.677046)
		(width 0.14478)
		(layer "In2.Cu")
		(net "M_C_CPU0_SB_DQ<28>")
	)
	(segment
		(start 314.138056 -312.496708)
		(end 313.77128 -312.129932)
		(width 0.14478)
		(layer "In2.Cu")
		(net "M_C_CPU0_SB_DQ<28>")
	)
	(segment
		(start 342.381078 -292.196774)
		(end 342.47709 -292.171374)
		(width 0.0889)
		(layer "In2.Cu")
		(net "M_C_CPU0_SB_DQ<28>")
	)
	(segment
		(start 313.377834 -312.523378)
		(end 313.74461 -312.890154)
		(width 0.14478)
		(layer "In2.Cu")
		(net "M_C_CPU0_SB_DQ<28>")
	)
	(segment
		(start 311.80405 -314.097162)
		(end 312.170826 -314.463938)
		(width 0.14478)
		(layer "In2.Cu")
		(net "M_C_CPU0_SB_DQ<28>")
	)
	(segment
		(start 337.16976 -292.23335)
		(end 337.178142 -292.228524)
		(width 0.0889)
		(layer "In2.Cu")
		(net "M_C_CPU0_SB_DQ<28>")
	)
	(segment
		(start 336.229706 -292.23335)
		(end 336.238088 -292.228524)
		(width 0.0889)
		(layer "In2.Cu")
		(net "M_C_CPU0_SB_DQ<28>")
	)
	(segment
		(start 332.469744 -292.23335)
		(end 332.478126 -292.228524)
		(width 0.0889)
		(layer "In2.Cu")
		(net "M_C_CPU0_SB_DQ<28>")
	)
	(segment
		(start 312.170826 -314.463938)
		(end 312.40095 -314.463938)
		(width 0.14478)
		(layer "In2.Cu")
		(net "M_C_CPU0_SB_DQ<28>")
	)
	(segment
		(start 326.80021 -293.87038)
		(end 326.838056 -293.848536)
		(width 0.0889)
		(layer "In2.Cu")
		(net "M_C_CPU0_SB_DQ<28>")
	)
	(segment
		(start 329.284076 -292.228524)
		(end 329.292458 -292.23335)
		(width 0.0889)
		(layer "In2.Cu")
		(net "M_C_CPU0_SB_DQ<28>")
	)
	(segment
		(start 327.30821 -293.03853)
		(end 327.33869 -293.02075)
		(width 0.0889)
		(layer "In2.Cu")
		(net "M_C_CPU0_SB_DQ<28>")
	)
	(segment
		(start 310.714644 -315.919866)
		(end 310.884316 -315.750194)
		(width 0.14478)
		(layer "In2.Cu")
		(net "M_C_CPU0_SB_DQ<28>")
	)
	(segment
		(start 311.573926 -314.097162)
		(end 311.80405 -314.097162)
		(width 0.14478)
		(layer "In2.Cu")
		(net "M_C_CPU0_SB_DQ<28>")
	)
	(segment
		(start 313.187842 -313.677046)
		(end 313.351164 -313.513724)
		(width 0.14478)
		(layer "In2.Cu")
		(net "M_C_CPU0_SB_DQ<28>")
	)
	(segment
		(start 326.367902 -294.658542)
		(end 326.398636 -294.640762)
		(width 0.0889)
		(layer "In2.Cu")
		(net "M_C_CPU0_SB_DQ<28>")
	)
	(segment
		(start 312.360818 -313.31027)
		(end 312.590942 -313.31027)
		(width 0.14478)
		(layer "In2.Cu")
		(net "M_C_CPU0_SB_DQ<28>")
	)
	(segment
		(start 310.884316 -315.750194)
		(end 310.884316 -315.538104)
		(width 0.14478)
		(layer "In2.Cu")
		(net "M_C_CPU0_SB_DQ<28>")
	)
	(segment
		(start 326.838056 -293.848536)
		(end 326.869806 -293.830248)
		(width 0.0889)
		(layer "In2.Cu")
		(net "M_C_CPU0_SB_DQ<28>")
	)
	(segment
		(start 310.884316 -315.538104)
		(end 310.623712 -315.2775)
		(width 0.14478)
		(layer "In2.Cu")
		(net "M_C_CPU0_SB_DQ<28>")
	)
	(segment
		(start 311.614058 -315.25083)
		(end 311.77738 -315.087508)
		(width 0.14478)
		(layer "In2.Cu")
		(net "M_C_CPU0_SB_DQ<28>")
	)
	(segment
		(start 312.40095 -314.463938)
		(end 312.564272 -314.300616)
		(width 0.14478)
		(layer "In2.Cu")
		(net "M_C_CPU0_SB_DQ<28>")
	)
	(segment
		(start 327.77557 -292.230302)
		(end 327.778364 -292.228524)
		(width 0.0889)
		(layer "In2.Cu")
		(net "M_C_CPU0_SB_DQ<28>")
	)
	(segment
		(start 328.71791 -292.228524)
		(end 328.718164 -292.228524)
		(width 0.0889)
		(layer "In2.Cu")
		(net "M_C_CPU0_SB_DQ<28>")
	)
	(segment
		(start 311.410604 -314.260484)
		(end 311.573926 -314.097162)
		(width 0.14478)
		(layer "In2.Cu")
		(net "M_C_CPU0_SB_DQ<28>")
	)
	(segment
		(start 313.351164 -313.2836)
		(end 312.984388 -312.916824)
		(width 0.14478)
		(layer "In2.Cu")
		(net "M_C_CPU0_SB_DQ<28>")
	)
	(segment
		(start 326.079612 -295.170352)
		(end 326.079612 -295.142158)
		(width 0.0889)
		(layer "In2.Cu")
		(net "M_C_CPU0_SB_DQ<28>")
	)
	(segment
		(start 327.269094 -293.06139)
		(end 327.30821 -293.03853)
		(width 0.0889)
		(layer "In2.Cu")
		(net "M_C_CPU0_SB_DQ<28>")
	)
	(segment
		(start 311.383934 -315.25083)
		(end 311.614058 -315.25083)
		(width 0.14478)
		(layer "In2.Cu")
		(net "M_C_CPU0_SB_DQ<28>")
	)
	(segment
		(start 313.77128 -312.129932)
		(end 313.77128 -311.899808)
		(width 0.14478)
		(layer "In2.Cu")
		(net "M_C_CPU0_SB_DQ<28>")
	)
	(segment
		(start 311.77738 -315.087508)
		(end 311.77738 -314.857384)
		(width 0.14478)
		(layer "In2.Cu")
		(net "M_C_CPU0_SB_DQ<28>")
	)
	(segment
		(start 326.079612 -300.898052)
		(end 326.079612 -295.170352)
		(width 0.14478)
		(layer "In2.Cu")
		(net "M_C_CPU0_SB_DQ<28>")
	)
	(segment
		(start 338.684108 -292.228524)
		(end 338.69249 -292.23335)
		(width 0.0889)
		(layer "In2.Cu")
		(net "M_C_CPU0_SB_DQ<28>")
	)
	(arc
		(start 327.33869 -293.02075)
		(mid 327.454117 -292.887374)
		(end 327.495662 -292.71595)
		(width 0.0889)
		(layer "In2.Cu")
		(net "M_C_CPU0_SB_DQ<28>")
	)
	(arc
		(start 337.178142 -292.228524)
		(mid 337.461098 -292.152347)
		(end 337.744054 -292.228524)
		(width 0.0889)
		(layer "In2.Cu")
		(net "M_C_CPU0_SB_DQ<28>")
	)
	(arc
		(start 333.05242 -292.23335)
		(mid 333.235928 -292.278844)
		(end 333.41818 -292.228524)
		(width 0.0889)
		(layer "In2.Cu")
		(net "M_C_CPU0_SB_DQ<28>")
	)
	(arc
		(start 329.658218 -292.228524)
		(mid 329.941174 -292.152347)
		(end 330.22413 -292.228524)
		(width 0.0889)
		(layer "In2.Cu")
		(net "M_C_CPU0_SB_DQ<28>")
	)
	(arc
		(start 341.504016 -292.228524)
		(mid 341.686267 -292.278874)
		(end 341.869776 -292.23335)
		(width 0.0889)
		(layer "In2.Cu")
		(net "M_C_CPU0_SB_DQ<28>")
	)
	(arc
		(start 326.869806 -293.830248)
		(mid 326.984482 -293.696914)
		(end 327.025762 -293.525956)
		(width 0.0889)
		(layer "In2.Cu")
		(net "M_C_CPU0_SB_DQ<28>")
	)
	(arc
		(start 331.16393 -292.228524)
		(mid 331.346181 -292.278874)
		(end 331.52969 -292.23335)
		(width 0.0889)
		(layer "In2.Cu")
		(net "M_C_CPU0_SB_DQ<28>")
	)
	(arc
		(start 328.718164 -292.228524)
		(mid 329.00112 -292.152347)
		(end 329.284076 -292.228524)
		(width 0.0889)
		(layer "In2.Cu")
		(net "M_C_CPU0_SB_DQ<28>")
	)
	(arc
		(start 340.563962 -292.228524)
		(mid 340.746213 -292.278874)
		(end 340.929722 -292.23335)
		(width 0.0889)
		(layer "In2.Cu")
		(net "M_C_CPU0_SB_DQ<28>")
	)
	(arc
		(start 332.478126 -292.228524)
		(mid 332.761082 -292.152347)
		(end 333.044038 -292.228524)
		(width 0.0889)
		(layer "In2.Cu")
		(net "M_C_CPU0_SB_DQ<28>")
	)
	(arc
		(start 338.69249 -292.23335)
		(mid 338.875998 -292.278844)
		(end 339.05825 -292.228524)
		(width 0.0889)
		(layer "In2.Cu")
		(net "M_C_CPU0_SB_DQ<28>")
	)
	(arc
		(start 336.804 -292.228524)
		(mid 336.986251 -292.278874)
		(end 337.16976 -292.23335)
		(width 0.0889)
		(layer "In2.Cu")
		(net "M_C_CPU0_SB_DQ<28>")
	)
	(arc
		(start 327.788778 -292.222428)
		(mid 328.06721 -292.15233)
		(end 328.344022 -292.228524)
		(width 0.0889)
		(layer "In2.Cu")
		(net "M_C_CPU0_SB_DQ<28>")
	)
	(arc
		(start 335.298034 -292.228524)
		(mid 335.58099 -292.152347)
		(end 335.863946 -292.228524)
		(width 0.0889)
		(layer "In2.Cu")
		(net "M_C_CPU0_SB_DQ<28>")
	)
	(arc
		(start 337.752436 -292.23335)
		(mid 337.935944 -292.278844)
		(end 338.118196 -292.228524)
		(width 0.0889)
		(layer "In2.Cu")
		(net "M_C_CPU0_SB_DQ<28>")
	)
	(arc
		(start 339.05825 -292.228524)
		(mid 339.341206 -292.152347)
		(end 339.624162 -292.228524)
		(width 0.0889)
		(layer "In2.Cu")
		(net "M_C_CPU0_SB_DQ<28>")
	)
	(arc
		(start 334.924146 -292.228524)
		(mid 335.11109 -292.278779)
		(end 335.298034 -292.228524)
		(width 0.0889)
		(layer "In2.Cu")
		(net "M_C_CPU0_SB_DQ<28>")
	)
	(arc
		(start 326.555608 -294.335962)
		(mid 326.62048 -294.072999)
		(end 326.80021 -293.87038)
		(width 0.0889)
		(layer "In2.Cu")
		(net "M_C_CPU0_SB_DQ<28>")
	)
	(arc
		(start 327.495662 -292.71595)
		(mid 327.570716 -292.435728)
		(end 327.77557 -292.230302)
		(width 0.0889)
		(layer "In2.Cu")
		(net "M_C_CPU0_SB_DQ<28>")
	)
	(arc
		(start 338.118196 -292.228524)
		(mid 338.401152 -292.152347)
		(end 338.684108 -292.228524)
		(width 0.0889)
		(layer "In2.Cu")
		(net "M_C_CPU0_SB_DQ<28>")
	)
	(arc
		(start 336.238088 -292.228524)
		(mid 336.521044 -292.152347)
		(end 336.804 -292.228524)
		(width 0.0889)
		(layer "In2.Cu")
		(net "M_C_CPU0_SB_DQ<28>")
	)
	(arc
		(start 334.358234 -292.228524)
		(mid 334.64119 -292.152347)
		(end 334.924146 -292.228524)
		(width 0.0889)
		(layer "In2.Cu")
		(net "M_C_CPU0_SB_DQ<28>")
	)
	(arc
		(start 335.863946 -292.228524)
		(mid 336.046197 -292.278874)
		(end 336.229706 -292.23335)
		(width 0.0889)
		(layer "In2.Cu")
		(net "M_C_CPU0_SB_DQ<28>")
	)
	(arc
		(start 341.878158 -292.228524)
		(mid 342.125871 -292.153304)
		(end 342.381078 -292.196774)
		(width 0.0889)
		(layer "In2.Cu")
		(net "M_C_CPU0_SB_DQ<28>")
	)
	(arc
		(start 331.538072 -292.228524)
		(mid 331.821028 -292.152347)
		(end 332.103984 -292.228524)
		(width 0.0889)
		(layer "In2.Cu")
		(net "M_C_CPU0_SB_DQ<28>")
	)
	(arc
		(start 340.938104 -292.228524)
		(mid 341.22106 -292.152347)
		(end 341.504016 -292.228524)
		(width 0.0889)
		(layer "In2.Cu")
		(net "M_C_CPU0_SB_DQ<28>")
	)
	(arc
		(start 333.41818 -292.228524)
		(mid 333.701136 -292.152347)
		(end 333.984092 -292.228524)
		(width 0.0889)
		(layer "In2.Cu")
		(net "M_C_CPU0_SB_DQ<28>")
	)
	(arc
		(start 326.398636 -294.640762)
		(mid 326.514063 -294.507386)
		(end 326.555608 -294.335962)
		(width 0.0889)
		(layer "In2.Cu")
		(net "M_C_CPU0_SB_DQ<28>")
	)
	(arc
		(start 339.99805 -292.228524)
		(mid 340.281006 -292.152347)
		(end 340.563962 -292.228524)
		(width 0.0889)
		(layer "In2.Cu")
		(net "M_C_CPU0_SB_DQ<28>")
	)
	(arc
		(start 332.103984 -292.228524)
		(mid 332.286235 -292.278874)
		(end 332.469744 -292.23335)
		(width 0.0889)
		(layer "In2.Cu")
		(net "M_C_CPU0_SB_DQ<28>")
	)
	(arc
		(start 326.306434 -294.683942)
		(mid 326.33465 -294.665152)
		(end 326.367902 -294.658542)
		(width 0.0889)
		(layer "In2.Cu")
		(net "M_C_CPU0_SB_DQ<28>")
	)
	(arc
		(start 328.344022 -292.228524)
		(mid 328.530966 -292.278848)
		(end 328.71791 -292.228524)
		(width 0.0889)
		(layer "In2.Cu")
		(net "M_C_CPU0_SB_DQ<28>")
	)
	(arc
		(start 327.025762 -293.525956)
		(mid 327.090277 -293.263737)
		(end 327.269094 -293.06139)
		(width 0.0889)
		(layer "In2.Cu")
		(net "M_C_CPU0_SB_DQ<28>")
	)
	(arc
		(start 333.992474 -292.23335)
		(mid 334.175982 -292.278844)
		(end 334.358234 -292.228524)
		(width 0.0889)
		(layer "In2.Cu")
		(net "M_C_CPU0_SB_DQ<28>")
	)
	(arc
		(start 330.598018 -292.228524)
		(mid 330.880974 -292.152347)
		(end 331.16393 -292.228524)
		(width 0.0889)
		(layer "In2.Cu")
		(net "M_C_CPU0_SB_DQ<28>")
	)
	(arc
		(start 339.624162 -292.228524)
		(mid 339.811106 -292.278779)
		(end 339.99805 -292.228524)
		(width 0.0889)
		(layer "In2.Cu")
		(net "M_C_CPU0_SB_DQ<28>")
	)
	(arc
		(start 326.079612 -295.142158)
		(mid 326.122129 -294.928412)
		(end 326.243188 -294.747188)
		(width 0.0889)
		(layer "In2.Cu")
		(net "M_C_CPU0_SB_DQ<28>")
	)
	(arc
		(start 329.292458 -292.23335)
		(mid 329.475966 -292.278844)
		(end 329.658218 -292.228524)
		(width 0.0889)
		(layer "In2.Cu")
		(net "M_C_CPU0_SB_DQ<28>")
	)
	(arc
		(start 330.22413 -292.228524)
		(mid 330.411074 -292.278779)
		(end 330.598018 -292.228524)
		(width 0.0889)
		(layer "In2.Cu")
		(net "M_C_CPU0_SB_DQ<28>")
	)
	(segment
		(start 344.03792 -290.019994)
		(end 343.571068 -290.285932)
		(width 0.10668)
		(layer "F.Cu")
		(net "M_C_CPU0_SB_DQ<27>")
	)
	(segment
		(start 305.329844 -311.660032)
		(end 304.479706 -312.51017)
		(width 0.14478)
		(layer "In2.Cu")
		(net "M_C_CPU0_SB_DQ<27>")
	)
	(segment
		(start 288.605214 -312.51017)
		(end 288.180018 -312.084974)
		(width 0.14478)
		(layer "In2.Cu")
		(net "M_C_CPU0_SB_DQ<27>")
	)
	(segment
		(start 343.392506 -289.958526)
		(end 343.384124 -289.963352)
		(width 0.0889)
		(layer "In2.Cu")
		(net "M_C_CPU0_SB_DQ<27>")
	)
	(segment
		(start 324.911212 -292.884352)
		(end 324.277482 -293.518082)
		(width 0.0889)
		(layer "In2.Cu")
		(net "M_C_CPU0_SB_DQ<27>")
	)
	(segment
		(start 333.05242 -289.958526)
		(end 333.044038 -289.963352)
		(width 0.0889)
		(layer "In2.Cu")
		(net "M_C_CPU0_SB_DQ<27>")
	)
	(segment
		(start 326.917812 -290.862512)
		(end 326.424798 -290.862512)
		(width 0.0889)
		(layer "In2.Cu")
		(net "M_C_CPU0_SB_DQ<27>")
	)
	(segment
		(start 332.478126 -289.963352)
		(end 332.469744 -289.958526)
		(width 0.0889)
		(layer "In2.Cu")
		(net "M_C_CPU0_SB_DQ<27>")
	)
	(segment
		(start 327.398126 -290.382198)
		(end 326.917812 -290.862512)
		(width 0.0889)
		(layer "In2.Cu")
		(net "M_C_CPU0_SB_DQ<27>")
	)
	(segment
		(start 328.718164 -289.963352)
		(end 328.709782 -289.958526)
		(width 0.0889)
		(layer "In2.Cu")
		(net "M_C_CPU0_SB_DQ<27>")
	)
	(segment
		(start 297.821096 -311.65038)
		(end 296.971212 -312.500264)
		(width 0.14478)
		(layer "In2.Cu")
		(net "M_C_CPU0_SB_DQ<27>")
	)
	(segment
		(start 301.453804 -311.65038)
		(end 297.821096 -311.65038)
		(width 0.14478)
		(layer "In2.Cu")
		(net "M_C_CPU0_SB_DQ<27>")
	)
	(segment
		(start 326.424798 -290.862512)
		(end 325.492618 -291.794692)
		(width 0.0889)
		(layer "In2.Cu")
		(net "M_C_CPU0_SB_DQ<27>")
	)
	(segment
		(start 319.11036 -303.21885)
		(end 310.669178 -311.660032)
		(width 0.14478)
		(layer "In2.Cu")
		(net "M_C_CPU0_SB_DQ<27>")
	)
	(segment
		(start 304.479706 -312.51017)
		(end 302.313594 -312.51017)
		(width 0.14478)
		(layer "In2.Cu")
		(net "M_C_CPU0_SB_DQ<27>")
	)
	(segment
		(start 320.449448 -303.21885)
		(end 319.11036 -303.21885)
		(width 0.14478)
		(layer "In2.Cu")
		(net "M_C_CPU0_SB_DQ<27>")
	)
	(segment
		(start 329.292458 -289.958526)
		(end 329.284076 -289.963352)
		(width 0.0889)
		(layer "In2.Cu")
		(net "M_C_CPU0_SB_DQ<27>")
	)
	(segment
		(start 289.9918 -312.131964)
		(end 289.828986 -311.96915)
		(width 0.14478)
		(layer "In2.Cu")
		(net "M_C_CPU0_SB_DQ<27>")
	)
	(segment
		(start 338.69249 -289.958526)
		(end 338.684108 -289.963352)
		(width 0.0889)
		(layer "In2.Cu")
		(net "M_C_CPU0_SB_DQ<27>")
	)
	(segment
		(start 310.669178 -311.660032)
		(end 305.329844 -311.660032)
		(width 0.14478)
		(layer "In2.Cu")
		(net "M_C_CPU0_SB_DQ<27>")
	)
	(segment
		(start 340.938104 -289.963352)
		(end 340.929722 -289.958526)
		(width 0.0889)
		(layer "In2.Cu")
		(net "M_C_CPU0_SB_DQ<27>")
	)
	(segment
		(start 289.43554 -312.131964)
		(end 289.43554 -312.352436)
		(width 0.14478)
		(layer "In2.Cu")
		(net "M_C_CPU0_SB_DQ<27>")
	)
	(segment
		(start 289.828986 -311.96915)
		(end 289.598354 -311.96915)
		(width 0.14478)
		(layer "In2.Cu")
		(net "M_C_CPU0_SB_DQ<27>")
	)
	(segment
		(start 296.971212 -312.500264)
		(end 290.139628 -312.500264)
		(width 0.14478)
		(layer "In2.Cu")
		(net "M_C_CPU0_SB_DQ<27>")
	)
	(segment
		(start 341.878158 -289.963352)
		(end 341.869776 -289.958526)
		(width 0.0889)
		(layer "In2.Cu")
		(net "M_C_CPU0_SB_DQ<27>")
	)
	(segment
		(start 328.267314 -290.022026)
		(end 327.398126 -290.382198)
		(width 0.0889)
		(layer "In2.Cu")
		(net "M_C_CPU0_SB_DQ<27>")
	)
	(segment
		(start 342.452452 -289.958526)
		(end 342.44407 -289.963352)
		(width 0.0889)
		(layer "In2.Cu")
		(net "M_C_CPU0_SB_DQ<27>")
	)
	(segment
		(start 343.725246 -290.020502)
		(end 343.702894 -289.93719)
		(width 0.0889)
		(layer "In2.Cu")
		(net "M_C_CPU0_SB_DQ<27>")
	)
	(segment
		(start 289.598354 -311.96915)
		(end 289.43554 -312.131964)
		(width 0.14478)
		(layer "In2.Cu")
		(net "M_C_CPU0_SB_DQ<27>")
	)
	(segment
		(start 289.43554 -312.352436)
		(end 289.277806 -312.51017)
		(width 0.14478)
		(layer "In2.Cu")
		(net "M_C_CPU0_SB_DQ<27>")
	)
	(segment
		(start 323.553074 -300.115224)
		(end 320.449448 -303.21885)
		(width 0.14478)
		(layer "In2.Cu")
		(net "M_C_CPU0_SB_DQ<27>")
	)
	(segment
		(start 290.139628 -312.500264)
		(end 289.9918 -312.352436)
		(width 0.14478)
		(layer "In2.Cu")
		(net "M_C_CPU0_SB_DQ<27>")
	)
	(segment
		(start 331.538072 -289.963352)
		(end 331.52969 -289.958526)
		(width 0.0889)
		(layer "In2.Cu")
		(net "M_C_CPU0_SB_DQ<27>")
	)
	(segment
		(start 325.492618 -292.551612)
		(end 325.159878 -292.884352)
		(width 0.0889)
		(layer "In2.Cu")
		(net "M_C_CPU0_SB_DQ<27>")
	)
	(segment
		(start 289.277806 -312.51017)
		(end 288.605214 -312.51017)
		(width 0.14478)
		(layer "In2.Cu")
		(net "M_C_CPU0_SB_DQ<27>")
	)
	(segment
		(start 289.9918 -312.352436)
		(end 289.9918 -312.131964)
		(width 0.14478)
		(layer "In2.Cu")
		(net "M_C_CPU0_SB_DQ<27>")
	)
	(segment
		(start 323.553074 -294.24249)
		(end 323.553074 -300.115224)
		(width 0.14478)
		(layer "In2.Cu")
		(net "M_C_CPU0_SB_DQ<27>")
	)
	(segment
		(start 302.313594 -312.51017)
		(end 301.453804 -311.65038)
		(width 0.14478)
		(layer "In2.Cu")
		(net "M_C_CPU0_SB_DQ<27>")
	)
	(segment
		(start 337.178142 -289.963352)
		(end 337.16976 -289.958526)
		(width 0.0889)
		(layer "In2.Cu")
		(net "M_C_CPU0_SB_DQ<27>")
	)
	(segment
		(start 324.277482 -293.518082)
		(end 323.553074 -294.24249)
		(width 0.14478)
		(layer "In2.Cu")
		(net "M_C_CPU0_SB_DQ<27>")
	)
	(segment
		(start 333.992474 -289.958526)
		(end 333.984092 -289.963352)
		(width 0.0889)
		(layer "In2.Cu")
		(net "M_C_CPU0_SB_DQ<27>")
	)
	(segment
		(start 337.752436 -289.958526)
		(end 337.744054 -289.963352)
		(width 0.0889)
		(layer "In2.Cu")
		(net "M_C_CPU0_SB_DQ<27>")
	)
	(segment
		(start 325.159878 -292.884352)
		(end 324.911212 -292.884352)
		(width 0.0889)
		(layer "In2.Cu")
		(net "M_C_CPU0_SB_DQ<27>")
	)
	(segment
		(start 343.571068 -290.285932)
		(end 343.725246 -290.020502)
		(width 0.0889)
		(layer "In2.Cu")
		(net "M_C_CPU0_SB_DQ<27>")
	)
	(segment
		(start 336.238088 -289.963352)
		(end 336.229706 -289.958526)
		(width 0.0889)
		(layer "In2.Cu")
		(net "M_C_CPU0_SB_DQ<27>")
	)
	(segment
		(start 325.492618 -291.794692)
		(end 325.492618 -292.551612)
		(width 0.0889)
		(layer "In2.Cu")
		(net "M_C_CPU0_SB_DQ<27>")
	)
	(arc
		(start 339.99805 -289.963352)
		(mid 339.811106 -289.913097)
		(end 339.624162 -289.963352)
		(width 0.0889)
		(layer "In2.Cu")
		(net "M_C_CPU0_SB_DQ<27>")
	)
	(arc
		(start 334.358234 -289.963352)
		(mid 334.175983 -289.913002)
		(end 333.992474 -289.958526)
		(width 0.0889)
		(layer "In2.Cu")
		(net "M_C_CPU0_SB_DQ<27>")
	)
	(arc
		(start 341.869776 -289.958526)
		(mid 341.686268 -289.913032)
		(end 341.504016 -289.963352)
		(width 0.0889)
		(layer "In2.Cu")
		(net "M_C_CPU0_SB_DQ<27>")
	)
	(arc
		(start 338.118196 -289.963352)
		(mid 337.935945 -289.913002)
		(end 337.752436 -289.958526)
		(width 0.0889)
		(layer "In2.Cu")
		(net "M_C_CPU0_SB_DQ<27>")
	)
	(arc
		(start 329.658218 -289.963352)
		(mid 329.475967 -289.913002)
		(end 329.292458 -289.958526)
		(width 0.0889)
		(layer "In2.Cu")
		(net "M_C_CPU0_SB_DQ<27>")
	)
	(arc
		(start 334.924146 -289.963352)
		(mid 334.64119 -290.039529)
		(end 334.358234 -289.963352)
		(width 0.0889)
		(layer "In2.Cu")
		(net "M_C_CPU0_SB_DQ<27>")
	)
	(arc
		(start 336.804 -289.963352)
		(mid 336.521044 -290.039529)
		(end 336.238088 -289.963352)
		(width 0.0889)
		(layer "In2.Cu")
		(net "M_C_CPU0_SB_DQ<27>")
	)
	(arc
		(start 337.16976 -289.958526)
		(mid 336.986252 -289.913032)
		(end 336.804 -289.963352)
		(width 0.0889)
		(layer "In2.Cu")
		(net "M_C_CPU0_SB_DQ<27>")
	)
	(arc
		(start 332.103984 -289.963352)
		(mid 331.821028 -290.039529)
		(end 331.538072 -289.963352)
		(width 0.0889)
		(layer "In2.Cu")
		(net "M_C_CPU0_SB_DQ<27>")
	)
	(arc
		(start 333.044038 -289.963352)
		(mid 332.761082 -290.039529)
		(end 332.478126 -289.963352)
		(width 0.0889)
		(layer "In2.Cu")
		(net "M_C_CPU0_SB_DQ<27>")
	)
	(arc
		(start 340.929722 -289.958526)
		(mid 340.746214 -289.913032)
		(end 340.563962 -289.963352)
		(width 0.0889)
		(layer "In2.Cu")
		(net "M_C_CPU0_SB_DQ<27>")
	)
	(arc
		(start 335.863946 -289.963352)
		(mid 335.58099 -290.039529)
		(end 335.298034 -289.963352)
		(width 0.0889)
		(layer "In2.Cu")
		(net "M_C_CPU0_SB_DQ<27>")
	)
	(arc
		(start 343.384124 -289.963352)
		(mid 343.101168 -290.039529)
		(end 342.818212 -289.963352)
		(width 0.0889)
		(layer "In2.Cu")
		(net "M_C_CPU0_SB_DQ<27>")
	)
	(arc
		(start 328.709782 -289.958526)
		(mid 328.526274 -289.913032)
		(end 328.344022 -289.963352)
		(width 0.0889)
		(layer "In2.Cu")
		(net "M_C_CPU0_SB_DQ<27>")
	)
	(arc
		(start 331.52969 -289.958526)
		(mid 331.346182 -289.913032)
		(end 331.16393 -289.963352)
		(width 0.0889)
		(layer "In2.Cu")
		(net "M_C_CPU0_SB_DQ<27>")
	)
	(arc
		(start 337.744054 -289.963352)
		(mid 337.461098 -290.039529)
		(end 337.178142 -289.963352)
		(width 0.0889)
		(layer "In2.Cu")
		(net "M_C_CPU0_SB_DQ<27>")
	)
	(arc
		(start 342.818212 -289.963352)
		(mid 342.635961 -289.913002)
		(end 342.452452 -289.958526)
		(width 0.0889)
		(layer "In2.Cu")
		(net "M_C_CPU0_SB_DQ<27>")
	)
	(arc
		(start 333.984092 -289.963352)
		(mid 333.701136 -290.039529)
		(end 333.41818 -289.963352)
		(width 0.0889)
		(layer "In2.Cu")
		(net "M_C_CPU0_SB_DQ<27>")
	)
	(arc
		(start 330.22413 -289.963352)
		(mid 329.941174 -290.039529)
		(end 329.658218 -289.963352)
		(width 0.0889)
		(layer "In2.Cu")
		(net "M_C_CPU0_SB_DQ<27>")
	)
	(arc
		(start 336.229706 -289.958526)
		(mid 336.046198 -289.913032)
		(end 335.863946 -289.963352)
		(width 0.0889)
		(layer "In2.Cu")
		(net "M_C_CPU0_SB_DQ<27>")
	)
	(arc
		(start 342.44407 -289.963352)
		(mid 342.161114 -290.039529)
		(end 341.878158 -289.963352)
		(width 0.0889)
		(layer "In2.Cu")
		(net "M_C_CPU0_SB_DQ<27>")
	)
	(arc
		(start 332.469744 -289.958526)
		(mid 332.286236 -289.913032)
		(end 332.103984 -289.963352)
		(width 0.0889)
		(layer "In2.Cu")
		(net "M_C_CPU0_SB_DQ<27>")
	)
	(arc
		(start 335.298034 -289.963352)
		(mid 335.11109 -289.913097)
		(end 334.924146 -289.963352)
		(width 0.0889)
		(layer "In2.Cu")
		(net "M_C_CPU0_SB_DQ<27>")
	)
	(arc
		(start 343.702894 -289.93719)
		(mid 343.545384 -289.913992)
		(end 343.392506 -289.958526)
		(width 0.0889)
		(layer "In2.Cu")
		(net "M_C_CPU0_SB_DQ<27>")
	)
	(arc
		(start 330.598018 -289.963352)
		(mid 330.411074 -289.913097)
		(end 330.22413 -289.963352)
		(width 0.0889)
		(layer "In2.Cu")
		(net "M_C_CPU0_SB_DQ<27>")
	)
	(arc
		(start 329.284076 -289.963352)
		(mid 329.00112 -290.039529)
		(end 328.718164 -289.963352)
		(width 0.0889)
		(layer "In2.Cu")
		(net "M_C_CPU0_SB_DQ<27>")
	)
	(arc
		(start 333.41818 -289.963352)
		(mid 333.235929 -289.913002)
		(end 333.05242 -289.958526)
		(width 0.0889)
		(layer "In2.Cu")
		(net "M_C_CPU0_SB_DQ<27>")
	)
	(arc
		(start 331.16393 -289.963352)
		(mid 330.880974 -290.039529)
		(end 330.598018 -289.963352)
		(width 0.0889)
		(layer "In2.Cu")
		(net "M_C_CPU0_SB_DQ<27>")
	)
	(arc
		(start 341.504016 -289.963352)
		(mid 341.22106 -290.039529)
		(end 340.938104 -289.963352)
		(width 0.0889)
		(layer "In2.Cu")
		(net "M_C_CPU0_SB_DQ<27>")
	)
	(arc
		(start 340.563962 -289.963352)
		(mid 340.281006 -290.039529)
		(end 339.99805 -289.963352)
		(width 0.0889)
		(layer "In2.Cu")
		(net "M_C_CPU0_SB_DQ<27>")
	)
	(arc
		(start 338.684108 -289.963352)
		(mid 338.401152 -290.039529)
		(end 338.118196 -289.963352)
		(width 0.0889)
		(layer "In2.Cu")
		(net "M_C_CPU0_SB_DQ<27>")
	)
	(arc
		(start 339.05825 -289.963352)
		(mid 338.875999 -289.913002)
		(end 338.69249 -289.958526)
		(width 0.0889)
		(layer "In2.Cu")
		(net "M_C_CPU0_SB_DQ<27>")
	)
	(arc
		(start 339.624162 -289.963352)
		(mid 339.341206 -290.039529)
		(end 339.05825 -289.963352)
		(width 0.0889)
		(layer "In2.Cu")
		(net "M_C_CPU0_SB_DQ<27>")
	)
	(arc
		(start 328.344022 -289.963352)
		(mid 328.303768 -289.990204)
		(end 328.267314 -290.022026)
		(width 0.0889)
		(layer "In2.Cu")
		(net "M_C_CPU0_SB_DQ<27>")
	)
	(segment
		(start 342.627966 -289.209988)
		(end 342.161114 -289.475926)
		(width 0.10668)
		(layer "F.Cu")
		(net "M_C_CPU0_SB_DQ<26>")
	)
	(segment
		(start 322.643754 -298.38269)
		(end 311.066434 -309.96001)
		(width 0.14478)
		(layer "In2.Cu")
		(net "M_C_CPU0_SB_DQ<26>")
	)
	(segment
		(start 297.374818 -310.810148)
		(end 291.184076 -310.810148)
		(width 0.14478)
		(layer "In2.Cu")
		(net "M_C_CPU0_SB_DQ<26>")
	)
	(segment
		(start 289.515296 -309.69331)
		(end 289.352482 -309.856124)
		(width 0.14478)
		(layer "In2.Cu")
		(net "M_C_CPU0_SB_DQ<26>")
	)
	(segment
		(start 291.021262 -309.856124)
		(end 290.858448 -309.69331)
		(width 0.14478)
		(layer "In2.Cu")
		(net "M_C_CPU0_SB_DQ<26>")
	)
	(segment
		(start 304.893218 -310.810148)
		(end 301.962058 -310.810148)
		(width 0.14478)
		(layer "In2.Cu")
		(net "M_C_CPU0_SB_DQ<26>")
	)
	(segment
		(start 339.52815 -289.153346)
		(end 339.519768 -289.14852)
		(width 0.0889)
		(layer "In2.Cu")
		(net "M_C_CPU0_SB_DQ<26>")
	)
	(segment
		(start 334.828134 -289.153346)
		(end 334.819752 -289.14852)
		(width 0.0889)
		(layer "In2.Cu")
		(net "M_C_CPU0_SB_DQ<26>")
	)
	(segment
		(start 341.042498 -289.14852)
		(end 341.034116 -289.153346)
		(width 0.0889)
		(layer "In2.Cu")
		(net "M_C_CPU0_SB_DQ<26>")
	)
	(segment
		(start 342.315038 -289.210496)
		(end 342.292686 -289.127184)
		(width 0.0889)
		(layer "In2.Cu")
		(net "M_C_CPU0_SB_DQ<26>")
	)
	(segment
		(start 323.888862 -292.620192)
		(end 322.643754 -293.8653)
		(width 0.14478)
		(layer "In2.Cu")
		(net "M_C_CPU0_SB_DQ<26>")
	)
	(segment
		(start 301.11192 -309.96001)
		(end 298.224956 -309.96001)
		(width 0.14478)
		(layer "In2.Cu")
		(net "M_C_CPU0_SB_DQ<26>")
	)
	(segment
		(start 340.102444 -289.14852)
		(end 340.094062 -289.153346)
		(width 0.0889)
		(layer "In2.Cu")
		(net "M_C_CPU0_SB_DQ<26>")
	)
	(segment
		(start 301.962058 -310.810148)
		(end 301.11192 -309.96001)
		(width 0.14478)
		(layer "In2.Cu")
		(net "M_C_CPU0_SB_DQ<26>")
	)
	(segment
		(start 290.071556 -310.810148)
		(end 289.908742 -310.647334)
		(width 0.14478)
		(layer "In2.Cu")
		(net "M_C_CPU0_SB_DQ<26>")
	)
	(segment
		(start 288.605214 -310.810148)
		(end 288.180018 -310.384952)
		(width 0.14478)
		(layer "In2.Cu")
		(net "M_C_CPU0_SB_DQ<26>")
	)
	(segment
		(start 330.702412 -289.14852)
		(end 330.69403 -289.153346)
		(width 0.0889)
		(layer "In2.Cu")
		(net "M_C_CPU0_SB_DQ<26>")
	)
	(segment
		(start 290.627816 -309.69331)
		(end 290.465002 -309.856124)
		(width 0.14478)
		(layer "In2.Cu")
		(net "M_C_CPU0_SB_DQ<26>")
	)
	(segment
		(start 290.465002 -309.856124)
		(end 290.465002 -310.647334)
		(width 0.14478)
		(layer "In2.Cu")
		(net "M_C_CPU0_SB_DQ<26>")
	)
	(segment
		(start 324.474078 -292.034976)
		(end 323.888862 -292.620192)
		(width 0.0889)
		(layer "In2.Cu")
		(net "M_C_CPU0_SB_DQ<26>")
	)
	(segment
		(start 327.155302 -289.230308)
		(end 324.561454 -291.824156)
		(width 0.0889)
		(layer "In2.Cu")
		(net "M_C_CPU0_SB_DQ<26>")
	)
	(segment
		(start 342.161114 -289.475926)
		(end 342.315038 -289.210496)
		(width 0.0889)
		(layer "In2.Cu")
		(net "M_C_CPU0_SB_DQ<26>")
	)
	(segment
		(start 291.184076 -310.810148)
		(end 291.021262 -310.647334)
		(width 0.14478)
		(layer "In2.Cu")
		(net "M_C_CPU0_SB_DQ<26>")
	)
	(segment
		(start 290.465002 -310.647334)
		(end 290.302188 -310.810148)
		(width 0.14478)
		(layer "In2.Cu")
		(net "M_C_CPU0_SB_DQ<26>")
	)
	(segment
		(start 289.908742 -309.856124)
		(end 289.745928 -309.69331)
		(width 0.14478)
		(layer "In2.Cu")
		(net "M_C_CPU0_SB_DQ<26>")
	)
	(segment
		(start 289.352482 -310.647334)
		(end 289.189668 -310.810148)
		(width 0.14478)
		(layer "In2.Cu")
		(net "M_C_CPU0_SB_DQ<26>")
	)
	(segment
		(start 335.402428 -289.14852)
		(end 335.394046 -289.153346)
		(width 0.0889)
		(layer "In2.Cu")
		(net "M_C_CPU0_SB_DQ<26>")
	)
	(segment
		(start 322.643754 -293.8653)
		(end 322.643754 -298.38269)
		(width 0.14478)
		(layer "In2.Cu")
		(net "M_C_CPU0_SB_DQ<26>")
	)
	(segment
		(start 298.224956 -309.96001)
		(end 297.374818 -310.810148)
		(width 0.14478)
		(layer "In2.Cu")
		(net "M_C_CPU0_SB_DQ<26>")
	)
	(segment
		(start 289.908742 -310.647334)
		(end 289.908742 -309.856124)
		(width 0.14478)
		(layer "In2.Cu")
		(net "M_C_CPU0_SB_DQ<26>")
	)
	(segment
		(start 311.066434 -309.96001)
		(end 305.743356 -309.96001)
		(width 0.14478)
		(layer "In2.Cu")
		(net "M_C_CPU0_SB_DQ<26>")
	)
	(segment
		(start 330.128118 -289.153346)
		(end 330.119736 -289.14852)
		(width 0.0889)
		(layer "In2.Cu")
		(net "M_C_CPU0_SB_DQ<26>")
	)
	(segment
		(start 338.588096 -289.153346)
		(end 338.579714 -289.14852)
		(width 0.0889)
		(layer "In2.Cu")
		(net "M_C_CPU0_SB_DQ<26>")
	)
	(segment
		(start 336.342482 -289.14852)
		(end 336.3341 -289.153346)
		(width 0.0889)
		(layer "In2.Cu")
		(net "M_C_CPU0_SB_DQ<26>")
	)
	(segment
		(start 331.642466 -289.14852)
		(end 331.634084 -289.153346)
		(width 0.0889)
		(layer "In2.Cu")
		(net "M_C_CPU0_SB_DQ<26>")
	)
	(segment
		(start 324.561454 -291.824156)
		(end 324.474078 -292.034976)
		(width 0.0889)
		(layer "In2.Cu")
		(net "M_C_CPU0_SB_DQ<26>")
	)
	(segment
		(start 305.743356 -309.96001)
		(end 304.893218 -310.810148)
		(width 0.14478)
		(layer "In2.Cu")
		(net "M_C_CPU0_SB_DQ<26>")
	)
	(segment
		(start 289.189668 -310.810148)
		(end 288.605214 -310.810148)
		(width 0.14478)
		(layer "In2.Cu")
		(net "M_C_CPU0_SB_DQ<26>")
	)
	(segment
		(start 289.745928 -309.69331)
		(end 289.515296 -309.69331)
		(width 0.14478)
		(layer "In2.Cu")
		(net "M_C_CPU0_SB_DQ<26>")
	)
	(segment
		(start 290.302188 -310.810148)
		(end 290.071556 -310.810148)
		(width 0.14478)
		(layer "In2.Cu")
		(net "M_C_CPU0_SB_DQ<26>")
	)
	(segment
		(start 333.88808 -289.153346)
		(end 333.879698 -289.14852)
		(width 0.0889)
		(layer "In2.Cu")
		(net "M_C_CPU0_SB_DQ<26>")
	)
	(segment
		(start 289.352482 -309.856124)
		(end 289.352482 -310.647334)
		(width 0.14478)
		(layer "In2.Cu")
		(net "M_C_CPU0_SB_DQ<26>")
	)
	(segment
		(start 290.858448 -309.69331)
		(end 290.627816 -309.69331)
		(width 0.14478)
		(layer "In2.Cu")
		(net "M_C_CPU0_SB_DQ<26>")
	)
	(segment
		(start 291.021262 -310.647334)
		(end 291.021262 -309.856124)
		(width 0.14478)
		(layer "In2.Cu")
		(net "M_C_CPU0_SB_DQ<26>")
	)
	(segment
		(start 327.591166 -289.230308)
		(end 327.155302 -289.230308)
		(width 0.0889)
		(layer "In2.Cu")
		(net "M_C_CPU0_SB_DQ<26>")
	)
	(segment
		(start 327.89876 -289.140138)
		(end 327.875392 -289.1536)
		(width 0.0889)
		(layer "In2.Cu")
		(net "M_C_CPU0_SB_DQ<26>")
	)
	(arc
		(start 338.213954 -289.153346)
		(mid 337.930998 -289.229523)
		(end 337.648042 -289.153346)
		(width 0.0889)
		(layer "In2.Cu")
		(net "M_C_CPU0_SB_DQ<26>")
	)
	(arc
		(start 336.708242 -289.153346)
		(mid 336.525991 -289.102996)
		(end 336.342482 -289.14852)
		(width 0.0889)
		(layer "In2.Cu")
		(net "M_C_CPU0_SB_DQ<26>")
	)
	(arc
		(start 332.948026 -289.153346)
		(mid 332.761082 -289.103091)
		(end 332.574138 -289.153346)
		(width 0.0889)
		(layer "In2.Cu")
		(net "M_C_CPU0_SB_DQ<26>")
	)
	(arc
		(start 328.248264 -289.153346)
		(mid 328.075156 -289.10323)
		(end 327.89876 -289.140138)
		(width 0.0889)
		(layer "In2.Cu")
		(net "M_C_CPU0_SB_DQ<26>")
	)
	(arc
		(start 333.513938 -289.153346)
		(mid 333.230982 -289.229523)
		(end 332.948026 -289.153346)
		(width 0.0889)
		(layer "In2.Cu")
		(net "M_C_CPU0_SB_DQ<26>")
	)
	(arc
		(start 340.468204 -289.153346)
		(mid 340.285953 -289.102996)
		(end 340.102444 -289.14852)
		(width 0.0889)
		(layer "In2.Cu")
		(net "M_C_CPU0_SB_DQ<26>")
	)
	(arc
		(start 339.519768 -289.14852)
		(mid 339.33626 -289.103026)
		(end 339.154008 -289.153346)
		(width 0.0889)
		(layer "In2.Cu")
		(net "M_C_CPU0_SB_DQ<26>")
	)
	(arc
		(start 330.119736 -289.14852)
		(mid 329.936228 -289.103026)
		(end 329.753976 -289.153346)
		(width 0.0889)
		(layer "In2.Cu")
		(net "M_C_CPU0_SB_DQ<26>")
	)
	(arc
		(start 334.819752 -289.14852)
		(mid 334.636244 -289.103026)
		(end 334.453992 -289.153346)
		(width 0.0889)
		(layer "In2.Cu")
		(net "M_C_CPU0_SB_DQ<26>")
	)
	(arc
		(start 332.574138 -289.153346)
		(mid 332.291182 -289.229523)
		(end 332.008226 -289.153346)
		(width 0.0889)
		(layer "In2.Cu")
		(net "M_C_CPU0_SB_DQ<26>")
	)
	(arc
		(start 341.408258 -289.153346)
		(mid 341.226007 -289.102996)
		(end 341.042498 -289.14852)
		(width 0.0889)
		(layer "In2.Cu")
		(net "M_C_CPU0_SB_DQ<26>")
	)
	(arc
		(start 339.154008 -289.153346)
		(mid 338.871052 -289.229523)
		(end 338.588096 -289.153346)
		(width 0.0889)
		(layer "In2.Cu")
		(net "M_C_CPU0_SB_DQ<26>")
	)
	(arc
		(start 329.753976 -289.153346)
		(mid 329.47102 -289.229523)
		(end 329.188064 -289.153346)
		(width 0.0889)
		(layer "In2.Cu")
		(net "M_C_CPU0_SB_DQ<26>")
	)
	(arc
		(start 335.768188 -289.153346)
		(mid 335.585937 -289.102996)
		(end 335.402428 -289.14852)
		(width 0.0889)
		(layer "In2.Cu")
		(net "M_C_CPU0_SB_DQ<26>")
	)
	(arc
		(start 340.094062 -289.153346)
		(mid 339.811106 -289.229523)
		(end 339.52815 -289.153346)
		(width 0.0889)
		(layer "In2.Cu")
		(net "M_C_CPU0_SB_DQ<26>")
	)
	(arc
		(start 331.068172 -289.153346)
		(mid 330.885921 -289.102996)
		(end 330.702412 -289.14852)
		(width 0.0889)
		(layer "In2.Cu")
		(net "M_C_CPU0_SB_DQ<26>")
	)
	(arc
		(start 332.008226 -289.153346)
		(mid 331.825975 -289.102996)
		(end 331.642466 -289.14852)
		(width 0.0889)
		(layer "In2.Cu")
		(net "M_C_CPU0_SB_DQ<26>")
	)
	(arc
		(start 330.69403 -289.153346)
		(mid 330.411074 -289.229523)
		(end 330.128118 -289.153346)
		(width 0.0889)
		(layer "In2.Cu")
		(net "M_C_CPU0_SB_DQ<26>")
	)
	(arc
		(start 327.875392 -289.1536)
		(mid 327.738365 -289.210786)
		(end 327.591166 -289.230308)
		(width 0.0889)
		(layer "In2.Cu")
		(net "M_C_CPU0_SB_DQ<26>")
	)
	(arc
		(start 328.814176 -289.153346)
		(mid 328.53122 -289.229523)
		(end 328.248264 -289.153346)
		(width 0.0889)
		(layer "In2.Cu")
		(net "M_C_CPU0_SB_DQ<26>")
	)
	(arc
		(start 341.034116 -289.153346)
		(mid 340.75116 -289.229523)
		(end 340.468204 -289.153346)
		(width 0.0889)
		(layer "In2.Cu")
		(net "M_C_CPU0_SB_DQ<26>")
	)
	(arc
		(start 333.879698 -289.14852)
		(mid 333.69619 -289.103026)
		(end 333.513938 -289.153346)
		(width 0.0889)
		(layer "In2.Cu")
		(net "M_C_CPU0_SB_DQ<26>")
	)
	(arc
		(start 329.188064 -289.153346)
		(mid 329.00112 -289.103091)
		(end 328.814176 -289.153346)
		(width 0.0889)
		(layer "In2.Cu")
		(net "M_C_CPU0_SB_DQ<26>")
	)
	(arc
		(start 338.579714 -289.14852)
		(mid 338.396206 -289.103026)
		(end 338.213954 -289.153346)
		(width 0.0889)
		(layer "In2.Cu")
		(net "M_C_CPU0_SB_DQ<26>")
	)
	(arc
		(start 331.634084 -289.153346)
		(mid 331.351128 -289.229523)
		(end 331.068172 -289.153346)
		(width 0.0889)
		(layer "In2.Cu")
		(net "M_C_CPU0_SB_DQ<26>")
	)
	(arc
		(start 342.292686 -289.127184)
		(mid 342.130497 -289.104449)
		(end 341.97417 -289.153346)
		(width 0.0889)
		(layer "In2.Cu")
		(net "M_C_CPU0_SB_DQ<26>")
	)
	(arc
		(start 341.97417 -289.153346)
		(mid 341.691214 -289.229523)
		(end 341.408258 -289.153346)
		(width 0.0889)
		(layer "In2.Cu")
		(net "M_C_CPU0_SB_DQ<26>")
	)
	(arc
		(start 337.274154 -289.153346)
		(mid 336.991198 -289.229523)
		(end 336.708242 -289.153346)
		(width 0.0889)
		(layer "In2.Cu")
		(net "M_C_CPU0_SB_DQ<26>")
	)
	(arc
		(start 336.3341 -289.153346)
		(mid 336.051144 -289.229523)
		(end 335.768188 -289.153346)
		(width 0.0889)
		(layer "In2.Cu")
		(net "M_C_CPU0_SB_DQ<26>")
	)
	(arc
		(start 334.453992 -289.153346)
		(mid 334.171036 -289.229523)
		(end 333.88808 -289.153346)
		(width 0.0889)
		(layer "In2.Cu")
		(net "M_C_CPU0_SB_DQ<26>")
	)
	(arc
		(start 335.394046 -289.153346)
		(mid 335.11109 -289.229523)
		(end 334.828134 -289.153346)
		(width 0.0889)
		(layer "In2.Cu")
		(net "M_C_CPU0_SB_DQ<26>")
	)
	(arc
		(start 337.648042 -289.153346)
		(mid 337.461098 -289.103091)
		(end 337.274154 -289.153346)
		(width 0.0889)
		(layer "In2.Cu")
		(net "M_C_CPU0_SB_DQ<26>")
	)
	(segment
		(start 344.508074 -289.209988)
		(end 344.041222 -289.475926)
		(width 0.10668)
		(layer "F.Cu")
		(net "M_C_CPU0_SB_DQ<25>")
	)
	(segment
		(start 319.71742 -302.18253)
		(end 319.487296 -302.18253)
		(width 0.14478)
		(layer "In2.Cu")
		(net "M_C_CPU0_SB_DQ<25>")
	)
	(segment
		(start 322.132198 -300.892718)
		(end 321.968876 -301.05604)
		(width 0.14478)
		(layer "In2.Cu")
		(net "M_C_CPU0_SB_DQ<25>")
	)
	(segment
		(start 340.102444 -289.803332)
		(end 340.094062 -289.798506)
		(width 0.0889)
		(layer "In2.Cu")
		(net "M_C_CPU0_SB_DQ<25>")
	)
	(segment
		(start 335.402428 -289.803332)
		(end 335.394046 -289.798506)
		(width 0.0889)
		(layer "In2.Cu")
		(net "M_C_CPU0_SB_DQ<25>")
	)
	(segment
		(start 343.887044 -289.741356)
		(end 343.790778 -289.766756)
		(width 0.0889)
		(layer "In2.Cu")
		(net "M_C_CPU0_SB_DQ<25>")
	)
	(segment
		(start 321.968876 -301.05604)
		(end 321.738498 -301.05604)
		(width 0.14478)
		(layer "In2.Cu")
		(net "M_C_CPU0_SB_DQ<25>")
	)
	(segment
		(start 305.5366 -310.809894)
		(end 304.686462 -311.660032)
		(width 0.14478)
		(layer "In2.Cu")
		(net "M_C_CPU0_SB_DQ<25>")
	)
	(segment
		(start 298.0182 -310.809894)
		(end 297.168062 -311.660032)
		(width 0.14478)
		(layer "In2.Cu")
		(net "M_C_CPU0_SB_DQ<25>")
	)
	(segment
		(start 310.859932 -310.809894)
		(end 305.5366 -310.809894)
		(width 0.14478)
		(layer "In2.Cu")
		(net "M_C_CPU0_SB_DQ<25>")
	)
	(segment
		(start 320.558414 -302.466502)
		(end 320.395092 -302.629824)
		(width 0.14478)
		(layer "In2.Cu")
		(net "M_C_CPU0_SB_DQ<25>")
	)
	(segment
		(start 326.838818 -290.672012)
		(end 326.160892 -290.672012)
		(width 0.0889)
		(layer "In2.Cu")
		(net "M_C_CPU0_SB_DQ<25>")
	)
	(segment
		(start 320.504312 -301.395638)
		(end 320.274188 -301.395638)
		(width 0.14478)
		(layer "In2.Cu")
		(net "M_C_CPU0_SB_DQ<25>")
	)
	(segment
		(start 333.88808 -289.798506)
		(end 333.879698 -289.803332)
		(width 0.0889)
		(layer "In2.Cu")
		(net "M_C_CPU0_SB_DQ<25>")
	)
	(segment
		(start 343.288112 -289.798506)
		(end 343.27973 -289.803332)
		(width 0.0889)
		(layer "In2.Cu")
		(net "M_C_CPU0_SB_DQ<25>")
	)
	(segment
		(start 328.061066 -289.856926)
		(end 327.975976 -289.873944)
		(width 0.0889)
		(layer "In2.Cu")
		(net "M_C_CPU0_SB_DQ<25>")
	)
	(segment
		(start 323.098414 -294.054022)
		(end 323.098414 -298.571412)
		(width 0.14478)
		(layer "In2.Cu")
		(net "M_C_CPU0_SB_DQ<25>")
	)
	(segment
		(start 341.042498 -289.803332)
		(end 341.034116 -289.798506)
		(width 0.0889)
		(layer "In2.Cu")
		(net "M_C_CPU0_SB_DQ<25>")
	)
	(segment
		(start 320.110866 -301.78883)
		(end 320.558414 -302.236378)
		(width 0.14478)
		(layer "In2.Cu")
		(net "M_C_CPU0_SB_DQ<25>")
	)
	(segment
		(start 321.345306 -301.67961)
		(end 321.181984 -301.842932)
		(width 0.14478)
		(layer "In2.Cu")
		(net "M_C_CPU0_SB_DQ<25>")
	)
	(segment
		(start 323.098414 -298.571412)
		(end 322.471542 -299.198284)
		(width 0.14478)
		(layer "In2.Cu")
		(net "M_C_CPU0_SB_DQ<25>")
	)
	(segment
		(start 320.897758 -300.772068)
		(end 320.897758 -301.001938)
		(width 0.14478)
		(layer "In2.Cu")
		(net "M_C_CPU0_SB_DQ<25>")
	)
	(segment
		(start 320.897758 -301.001938)
		(end 321.345306 -301.449486)
		(width 0.14478)
		(layer "In2.Cu")
		(net "M_C_CPU0_SB_DQ<25>")
	)
	(segment
		(start 344.041222 -289.475926)
		(end 343.887044 -289.741356)
		(width 0.0889)
		(layer "In2.Cu")
		(net "M_C_CPU0_SB_DQ<25>")
	)
	(segment
		(start 320.395092 -302.629824)
		(end 320.164714 -302.629824)
		(width 0.14478)
		(layer "In2.Cu")
		(net "M_C_CPU0_SB_DQ<25>")
	)
	(segment
		(start 321.68465 -299.985176)
		(end 321.68465 -300.215046)
		(width 0.14478)
		(layer "In2.Cu")
		(net "M_C_CPU0_SB_DQ<25>")
	)
	(segment
		(start 319.487296 -302.18253)
		(end 310.859932 -310.809894)
		(width 0.14478)
		(layer "In2.Cu")
		(net "M_C_CPU0_SB_DQ<25>")
	)
	(segment
		(start 334.828134 -289.798506)
		(end 334.819752 -289.803332)
		(width 0.0889)
		(layer "In2.Cu")
		(net "M_C_CPU0_SB_DQ<25>")
	)
	(segment
		(start 330.128118 -289.798506)
		(end 330.119736 -289.803332)
		(width 0.0889)
		(layer "In2.Cu")
		(net "M_C_CPU0_SB_DQ<25>")
	)
	(segment
		(start 336.342482 -289.803332)
		(end 336.3341 -289.798506)
		(width 0.0889)
		(layer "In2.Cu")
		(net "M_C_CPU0_SB_DQ<25>")
	)
	(segment
		(start 320.558414 -302.236378)
		(end 320.558414 -302.466502)
		(width 0.14478)
		(layer "In2.Cu")
		(net "M_C_CPU0_SB_DQ<25>")
	)
	(segment
		(start 322.91909 -300.105826)
		(end 322.755768 -300.269148)
		(width 0.14478)
		(layer "In2.Cu")
		(net "M_C_CPU0_SB_DQ<25>")
	)
	(segment
		(start 339.52815 -289.798506)
		(end 339.519768 -289.803332)
		(width 0.0889)
		(layer "In2.Cu")
		(net "M_C_CPU0_SB_DQ<25>")
	)
	(segment
		(start 320.274188 -301.395638)
		(end 320.110866 -301.55896)
		(width 0.14478)
		(layer "In2.Cu")
		(net "M_C_CPU0_SB_DQ<25>")
	)
	(segment
		(start 327.975976 -289.873944)
		(end 327.396856 -290.113974)
		(width 0.0889)
		(layer "In2.Cu")
		(net "M_C_CPU0_SB_DQ<25>")
	)
	(segment
		(start 292.705028 -311.660032)
		(end 292.280086 -311.23509)
		(width 0.14478)
		(layer "In2.Cu")
		(net "M_C_CPU0_SB_DQ<25>")
	)
	(segment
		(start 322.471542 -299.428154)
		(end 322.91909 -299.875702)
		(width 0.14478)
		(layer "In2.Cu")
		(net "M_C_CPU0_SB_DQ<25>")
	)
	(segment
		(start 324.771766 -292.061138)
		(end 324.545706 -292.60673)
		(width 0.0889)
		(layer "In2.Cu")
		(net "M_C_CPU0_SB_DQ<25>")
	)
	(segment
		(start 322.471542 -299.198284)
		(end 322.471542 -299.428154)
		(width 0.14478)
		(layer "In2.Cu")
		(net "M_C_CPU0_SB_DQ<25>")
	)
	(segment
		(start 323.94271 -293.209726)
		(end 323.098414 -294.054022)
		(width 0.14478)
		(layer "In2.Cu")
		(net "M_C_CPU0_SB_DQ<25>")
	)
	(segment
		(start 321.345306 -301.449486)
		(end 321.345306 -301.67961)
		(width 0.14478)
		(layer "In2.Cu")
		(net "M_C_CPU0_SB_DQ<25>")
	)
	(segment
		(start 322.52539 -300.269148)
		(end 322.078096 -299.821854)
		(width 0.14478)
		(layer "In2.Cu")
		(net "M_C_CPU0_SB_DQ<25>")
	)
	(segment
		(start 320.951606 -301.842932)
		(end 320.504312 -301.395638)
		(width 0.14478)
		(layer "In2.Cu")
		(net "M_C_CPU0_SB_DQ<25>")
	)
	(segment
		(start 322.91909 -299.875702)
		(end 322.91909 -300.105826)
		(width 0.14478)
		(layer "In2.Cu")
		(net "M_C_CPU0_SB_DQ<25>")
	)
	(segment
		(start 297.168062 -311.660032)
		(end 292.705028 -311.660032)
		(width 0.14478)
		(layer "In2.Cu")
		(net "M_C_CPU0_SB_DQ<25>")
	)
	(segment
		(start 338.588096 -289.798506)
		(end 338.579714 -289.803332)
		(width 0.0889)
		(layer "In2.Cu")
		(net "M_C_CPU0_SB_DQ<25>")
	)
	(segment
		(start 322.755768 -300.269148)
		(end 322.52539 -300.269148)
		(width 0.14478)
		(layer "In2.Cu")
		(net "M_C_CPU0_SB_DQ<25>")
	)
	(segment
		(start 304.686462 -311.660032)
		(end 302.13427 -311.660032)
		(width 0.14478)
		(layer "In2.Cu")
		(net "M_C_CPU0_SB_DQ<25>")
	)
	(segment
		(start 327.396856 -290.113974)
		(end 326.838818 -290.672012)
		(width 0.0889)
		(layer "In2.Cu")
		(net "M_C_CPU0_SB_DQ<25>")
	)
	(segment
		(start 320.164714 -302.629824)
		(end 319.71742 -302.18253)
		(width 0.14478)
		(layer "In2.Cu")
		(net "M_C_CPU0_SB_DQ<25>")
	)
	(segment
		(start 326.160892 -290.672012)
		(end 324.771766 -292.061138)
		(width 0.0889)
		(layer "In2.Cu")
		(net "M_C_CPU0_SB_DQ<25>")
	)
	(segment
		(start 330.702412 -289.803332)
		(end 330.69403 -289.798506)
		(width 0.0889)
		(layer "In2.Cu")
		(net "M_C_CPU0_SB_DQ<25>")
	)
	(segment
		(start 321.181984 -301.842932)
		(end 320.951606 -301.842932)
		(width 0.14478)
		(layer "In2.Cu")
		(net "M_C_CPU0_SB_DQ<25>")
	)
	(segment
		(start 331.642466 -289.803332)
		(end 331.634084 -289.798506)
		(width 0.0889)
		(layer "In2.Cu")
		(net "M_C_CPU0_SB_DQ<25>")
	)
	(segment
		(start 321.06108 -300.608746)
		(end 320.897758 -300.772068)
		(width 0.14478)
		(layer "In2.Cu")
		(net "M_C_CPU0_SB_DQ<25>")
	)
	(segment
		(start 322.132198 -300.662594)
		(end 322.132198 -300.892718)
		(width 0.14478)
		(layer "In2.Cu")
		(net "M_C_CPU0_SB_DQ<25>")
	)
	(segment
		(start 322.078096 -299.821854)
		(end 321.847972 -299.821854)
		(width 0.14478)
		(layer "In2.Cu")
		(net "M_C_CPU0_SB_DQ<25>")
	)
	(segment
		(start 321.68465 -300.215046)
		(end 322.132198 -300.662594)
		(width 0.14478)
		(layer "In2.Cu")
		(net "M_C_CPU0_SB_DQ<25>")
	)
	(segment
		(start 301.284132 -310.809894)
		(end 298.0182 -310.809894)
		(width 0.14478)
		(layer "In2.Cu")
		(net "M_C_CPU0_SB_DQ<25>")
	)
	(segment
		(start 302.13427 -311.660032)
		(end 301.284132 -310.809894)
		(width 0.14478)
		(layer "In2.Cu")
		(net "M_C_CPU0_SB_DQ<25>")
	)
	(segment
		(start 321.847972 -299.821854)
		(end 321.68465 -299.985176)
		(width 0.14478)
		(layer "In2.Cu")
		(net "M_C_CPU0_SB_DQ<25>")
	)
	(segment
		(start 324.545706 -292.60673)
		(end 323.94271 -293.209726)
		(width 0.0889)
		(layer "In2.Cu")
		(net "M_C_CPU0_SB_DQ<25>")
	)
	(segment
		(start 321.738498 -301.05604)
		(end 321.291204 -300.608746)
		(width 0.14478)
		(layer "In2.Cu")
		(net "M_C_CPU0_SB_DQ<25>")
	)
	(segment
		(start 321.291204 -300.608746)
		(end 321.06108 -300.608746)
		(width 0.14478)
		(layer "In2.Cu")
		(net "M_C_CPU0_SB_DQ<25>")
	)
	(segment
		(start 320.110866 -301.55896)
		(end 320.110866 -301.78883)
		(width 0.14478)
		(layer "In2.Cu")
		(net "M_C_CPU0_SB_DQ<25>")
	)
	(arc
		(start 332.948026 -289.798506)
		(mid 332.761082 -289.848761)
		(end 332.574138 -289.798506)
		(width 0.0889)
		(layer "In2.Cu")
		(net "M_C_CPU0_SB_DQ<25>")
	)
	(arc
		(start 341.034116 -289.798506)
		(mid 340.75116 -289.722329)
		(end 340.468204 -289.798506)
		(width 0.0889)
		(layer "In2.Cu")
		(net "M_C_CPU0_SB_DQ<25>")
	)
	(arc
		(start 337.274154 -289.798506)
		(mid 336.991198 -289.722329)
		(end 336.708242 -289.798506)
		(width 0.0889)
		(layer "In2.Cu")
		(net "M_C_CPU0_SB_DQ<25>")
	)
	(arc
		(start 333.879698 -289.803332)
		(mid 333.69619 -289.848826)
		(end 333.513938 -289.798506)
		(width 0.0889)
		(layer "In2.Cu")
		(net "M_C_CPU0_SB_DQ<25>")
	)
	(arc
		(start 342.91397 -289.798506)
		(mid 342.631014 -289.722329)
		(end 342.348058 -289.798506)
		(width 0.0889)
		(layer "In2.Cu")
		(net "M_C_CPU0_SB_DQ<25>")
	)
	(arc
		(start 338.579714 -289.803332)
		(mid 338.396206 -289.848826)
		(end 338.213954 -289.798506)
		(width 0.0889)
		(layer "In2.Cu")
		(net "M_C_CPU0_SB_DQ<25>")
	)
	(arc
		(start 335.394046 -289.798506)
		(mid 335.11109 -289.722329)
		(end 334.828134 -289.798506)
		(width 0.0889)
		(layer "In2.Cu")
		(net "M_C_CPU0_SB_DQ<25>")
	)
	(arc
		(start 329.188064 -289.798506)
		(mid 329.00112 -289.848761)
		(end 328.814176 -289.798506)
		(width 0.0889)
		(layer "In2.Cu")
		(net "M_C_CPU0_SB_DQ<25>")
	)
	(arc
		(start 341.408258 -289.798506)
		(mid 341.226007 -289.848856)
		(end 341.042498 -289.803332)
		(width 0.0889)
		(layer "In2.Cu")
		(net "M_C_CPU0_SB_DQ<25>")
	)
	(arc
		(start 339.154008 -289.798506)
		(mid 338.871052 -289.722329)
		(end 338.588096 -289.798506)
		(width 0.0889)
		(layer "In2.Cu")
		(net "M_C_CPU0_SB_DQ<25>")
	)
	(arc
		(start 328.197464 -289.83178)
		(mid 328.130419 -289.850616)
		(end 328.061066 -289.856926)
		(width 0.0889)
		(layer "In2.Cu")
		(net "M_C_CPU0_SB_DQ<25>")
	)
	(arc
		(start 336.3341 -289.798506)
		(mid 336.051144 -289.722329)
		(end 335.768188 -289.798506)
		(width 0.0889)
		(layer "In2.Cu")
		(net "M_C_CPU0_SB_DQ<25>")
	)
	(arc
		(start 343.790778 -289.766756)
		(mid 343.535713 -289.723405)
		(end 343.288112 -289.798506)
		(width 0.0889)
		(layer "In2.Cu")
		(net "M_C_CPU0_SB_DQ<25>")
	)
	(arc
		(start 335.768188 -289.798506)
		(mid 335.585937 -289.848856)
		(end 335.402428 -289.803332)
		(width 0.0889)
		(layer "In2.Cu")
		(net "M_C_CPU0_SB_DQ<25>")
	)
	(arc
		(start 331.634084 -289.798506)
		(mid 331.351128 -289.722329)
		(end 331.068172 -289.798506)
		(width 0.0889)
		(layer "In2.Cu")
		(net "M_C_CPU0_SB_DQ<25>")
	)
	(arc
		(start 331.068172 -289.798506)
		(mid 330.885921 -289.848856)
		(end 330.702412 -289.803332)
		(width 0.0889)
		(layer "In2.Cu")
		(net "M_C_CPU0_SB_DQ<25>")
	)
	(arc
		(start 342.348058 -289.798506)
		(mid 342.161114 -289.848761)
		(end 341.97417 -289.798506)
		(width 0.0889)
		(layer "In2.Cu")
		(net "M_C_CPU0_SB_DQ<25>")
	)
	(arc
		(start 334.819752 -289.803332)
		(mid 334.636244 -289.848826)
		(end 334.453992 -289.798506)
		(width 0.0889)
		(layer "In2.Cu")
		(net "M_C_CPU0_SB_DQ<25>")
	)
	(arc
		(start 330.119736 -289.803332)
		(mid 329.936228 -289.848826)
		(end 329.753976 -289.798506)
		(width 0.0889)
		(layer "In2.Cu")
		(net "M_C_CPU0_SB_DQ<25>")
	)
	(arc
		(start 332.574138 -289.798506)
		(mid 332.291182 -289.722329)
		(end 332.008226 -289.798506)
		(width 0.0889)
		(layer "In2.Cu")
		(net "M_C_CPU0_SB_DQ<25>")
	)
	(arc
		(start 340.094062 -289.798506)
		(mid 339.811106 -289.722329)
		(end 339.52815 -289.798506)
		(width 0.0889)
		(layer "In2.Cu")
		(net "M_C_CPU0_SB_DQ<25>")
	)
	(arc
		(start 330.69403 -289.798506)
		(mid 330.411074 -289.722329)
		(end 330.128118 -289.798506)
		(width 0.0889)
		(layer "In2.Cu")
		(net "M_C_CPU0_SB_DQ<25>")
	)
	(arc
		(start 333.513938 -289.798506)
		(mid 333.230982 -289.722329)
		(end 332.948026 -289.798506)
		(width 0.0889)
		(layer "In2.Cu")
		(net "M_C_CPU0_SB_DQ<25>")
	)
	(arc
		(start 337.648042 -289.798506)
		(mid 337.461098 -289.848761)
		(end 337.274154 -289.798506)
		(width 0.0889)
		(layer "In2.Cu")
		(net "M_C_CPU0_SB_DQ<25>")
	)
	(arc
		(start 343.27973 -289.803332)
		(mid 343.096222 -289.848826)
		(end 342.91397 -289.798506)
		(width 0.0889)
		(layer "In2.Cu")
		(net "M_C_CPU0_SB_DQ<25>")
	)
	(arc
		(start 332.008226 -289.798506)
		(mid 331.825975 -289.848856)
		(end 331.642466 -289.803332)
		(width 0.0889)
		(layer "In2.Cu")
		(net "M_C_CPU0_SB_DQ<25>")
	)
	(arc
		(start 328.814176 -289.798506)
		(mid 328.500856 -289.723148)
		(end 328.197464 -289.83178)
		(width 0.0889)
		(layer "In2.Cu")
		(net "M_C_CPU0_SB_DQ<25>")
	)
	(arc
		(start 334.453992 -289.798506)
		(mid 334.171036 -289.722329)
		(end 333.88808 -289.798506)
		(width 0.0889)
		(layer "In2.Cu")
		(net "M_C_CPU0_SB_DQ<25>")
	)
	(arc
		(start 329.753976 -289.798506)
		(mid 329.47102 -289.722329)
		(end 329.188064 -289.798506)
		(width 0.0889)
		(layer "In2.Cu")
		(net "M_C_CPU0_SB_DQ<25>")
	)
	(arc
		(start 341.97417 -289.798506)
		(mid 341.691214 -289.722329)
		(end 341.408258 -289.798506)
		(width 0.0889)
		(layer "In2.Cu")
		(net "M_C_CPU0_SB_DQ<25>")
	)
	(arc
		(start 336.708242 -289.798506)
		(mid 336.525991 -289.848856)
		(end 336.342482 -289.803332)
		(width 0.0889)
		(layer "In2.Cu")
		(net "M_C_CPU0_SB_DQ<25>")
	)
	(arc
		(start 340.468204 -289.798506)
		(mid 340.285953 -289.848856)
		(end 340.102444 -289.803332)
		(width 0.0889)
		(layer "In2.Cu")
		(net "M_C_CPU0_SB_DQ<25>")
	)
	(arc
		(start 339.519768 -289.803332)
		(mid 339.33626 -289.848826)
		(end 339.154008 -289.798506)
		(width 0.0889)
		(layer "In2.Cu")
		(net "M_C_CPU0_SB_DQ<25>")
	)
	(arc
		(start 338.213954 -289.798506)
		(mid 337.930998 -289.722329)
		(end 337.648042 -289.798506)
		(width 0.0889)
		(layer "In2.Cu")
		(net "M_C_CPU0_SB_DQ<25>")
	)
	(segment
		(start 343.097866 -288.399982)
		(end 342.631014 -288.66592)
		(width 0.10668)
		(layer "F.Cu")
		(net "M_C_CPU0_SB_DQ<24>")
	)
	(segment
		(start 327.567036 -289.026092)
		(end 326.893428 -289.026092)
		(width 0.0889)
		(layer "In2.Cu")
		(net "M_C_CPU0_SB_DQ<24>")
	)
	(segment
		(start 300.958504 -309.110126)
		(end 298.888912 -309.110126)
		(width 0.14478)
		(layer "In2.Cu")
		(net "M_C_CPU0_SB_DQ<24>")
	)
	(segment
		(start 324.685914 -291.180012)
		(end 323.875654 -291.990272)
		(width 0.0889)
		(layer "In2.Cu")
		(net "M_C_CPU0_SB_DQ<24>")
	)
	(segment
		(start 319.153286 -301.047658)
		(end 318.989964 -301.21098)
		(width 0.14478)
		(layer "In2.Cu")
		(net "M_C_CPU0_SB_DQ<24>")
	)
	(segment
		(start 331.538072 -288.9885)
		(end 331.52969 -288.993326)
		(width 0.0889)
		(layer "In2.Cu")
		(net "M_C_CPU0_SB_DQ<24>")
	)
	(segment
		(start 322.189094 -296.704258)
		(end 321.09029 -297.803062)
		(width 0.14478)
		(layer "In2.Cu")
		(net "M_C_CPU0_SB_DQ<24>")
	)
	(segment
		(start 318.729614 -300.393862)
		(end 319.153286 -300.817534)
		(width 0.14478)
		(layer "In2.Cu")
		(net "M_C_CPU0_SB_DQ<24>")
	)
	(segment
		(start 320.303398 -298.820078)
		(end 320.72707 -299.24375)
		(width 0.14478)
		(layer "In2.Cu")
		(net "M_C_CPU0_SB_DQ<24>")
	)
	(segment
		(start 338.69249 -288.993326)
		(end 338.684108 -288.9885)
		(width 0.0889)
		(layer "In2.Cu")
		(net "M_C_CPU0_SB_DQ<24>")
	)
	(segment
		(start 319.776856 -300.424088)
		(end 319.546732 -300.424088)
		(width 0.14478)
		(layer "In2.Cu")
		(net "M_C_CPU0_SB_DQ<24>")
	)
	(segment
		(start 340.938104 -288.9885)
		(end 340.929722 -288.993326)
		(width 0.0889)
		(layer "In2.Cu")
		(net "M_C_CPU0_SB_DQ<24>")
	)
	(segment
		(start 321.513962 -298.456858)
		(end 321.513962 -298.686982)
		(width 0.14478)
		(layer "In2.Cu")
		(net "M_C_CPU0_SB_DQ<24>")
	)
	(segment
		(start 337.752436 -288.993326)
		(end 337.744054 -288.9885)
		(width 0.0889)
		(layer "In2.Cu")
		(net "M_C_CPU0_SB_DQ<24>")
	)
	(segment
		(start 317.549276 -301.5742)
		(end 317.319152 -301.5742)
		(width 0.14478)
		(layer "In2.Cu")
		(net "M_C_CPU0_SB_DQ<24>")
	)
	(segment
		(start 297.581574 -309.960264)
		(end 292.705282 -309.960264)
		(width 0.14478)
		(layer "In2.Cu")
		(net "M_C_CPU0_SB_DQ<24>")
	)
	(segment
		(start 318.366394 -301.83455)
		(end 318.203072 -301.997872)
		(width 0.14478)
		(layer "In2.Cu")
		(net "M_C_CPU0_SB_DQ<24>")
	)
	(segment
		(start 333.992474 -288.993326)
		(end 333.984092 -288.9885)
		(width 0.0889)
		(layer "In2.Cu")
		(net "M_C_CPU0_SB_DQ<24>")
	)
	(segment
		(start 320.696844 -298.426632)
		(end 320.46672 -298.426632)
		(width 0.14478)
		(layer "In2.Cu")
		(net "M_C_CPU0_SB_DQ<24>")
	)
	(segment
		(start 322.189094 -293.676832)
		(end 322.189094 -296.704258)
		(width 0.14478)
		(layer "In2.Cu")
		(net "M_C_CPU0_SB_DQ<24>")
	)
	(segment
		(start 317.579248 -302.803814)
		(end 311.272936 -309.110126)
		(width 0.14478)
		(layer "In2.Cu")
		(net "M_C_CPU0_SB_DQ<24>")
	)
	(segment
		(start 317.086234 -302.080676)
		(end 317.579248 -302.57369)
		(width 0.14478)
		(layer "In2.Cu")
		(net "M_C_CPU0_SB_DQ<24>")
	)
	(segment
		(start 323.875654 -291.990272)
		(end 322.189094 -293.676832)
		(width 0.14478)
		(layer "In2.Cu")
		(net "M_C_CPU0_SB_DQ<24>")
	)
	(segment
		(start 320.333624 -299.637196)
		(end 319.909952 -299.213524)
		(width 0.14478)
		(layer "In2.Cu")
		(net "M_C_CPU0_SB_DQ<24>")
	)
	(segment
		(start 318.892936 -300.000416)
		(end 318.729614 -300.163738)
		(width 0.14478)
		(layer "In2.Cu")
		(net "M_C_CPU0_SB_DQ<24>")
	)
	(segment
		(start 320.72707 -299.24375)
		(end 320.72707 -299.473874)
		(width 0.14478)
		(layer "In2.Cu")
		(net "M_C_CPU0_SB_DQ<24>")
	)
	(segment
		(start 317.579248 -302.57369)
		(end 317.579248 -302.803814)
		(width 0.14478)
		(layer "In2.Cu")
		(net "M_C_CPU0_SB_DQ<24>")
	)
	(segment
		(start 319.940178 -300.260766)
		(end 319.776856 -300.424088)
		(width 0.14478)
		(layer "In2.Cu")
		(net "M_C_CPU0_SB_DQ<24>")
	)
	(segment
		(start 337.178142 -288.9885)
		(end 337.16976 -288.993326)
		(width 0.0889)
		(layer "In2.Cu")
		(net "M_C_CPU0_SB_DQ<24>")
	)
	(segment
		(start 319.679828 -299.213524)
		(end 319.516506 -299.376846)
		(width 0.14478)
		(layer "In2.Cu")
		(net "M_C_CPU0_SB_DQ<24>")
	)
	(segment
		(start 298.595288 -309.40375)
		(end 298.138088 -309.40375)
		(width 0.14478)
		(layer "In2.Cu")
		(net "M_C_CPU0_SB_DQ<24>")
	)
	(segment
		(start 319.12306 -300.000416)
		(end 318.892936 -300.000416)
		(width 0.14478)
		(layer "In2.Cu")
		(net "M_C_CPU0_SB_DQ<24>")
	)
	(segment
		(start 321.513962 -298.686982)
		(end 321.35064 -298.850304)
		(width 0.14478)
		(layer "In2.Cu")
		(net "M_C_CPU0_SB_DQ<24>")
	)
	(segment
		(start 318.729614 -300.163738)
		(end 318.729614 -300.393862)
		(width 0.14478)
		(layer "In2.Cu")
		(net "M_C_CPU0_SB_DQ<24>")
	)
	(segment
		(start 319.153286 -300.817534)
		(end 319.153286 -301.047658)
		(width 0.14478)
		(layer "In2.Cu")
		(net "M_C_CPU0_SB_DQ<24>")
	)
	(segment
		(start 317.942722 -300.95063)
		(end 317.942722 -301.180754)
		(width 0.14478)
		(layer "In2.Cu")
		(net "M_C_CPU0_SB_DQ<24>")
	)
	(segment
		(start 336.238088 -288.9885)
		(end 336.229706 -288.993326)
		(width 0.0889)
		(layer "In2.Cu")
		(net "M_C_CPU0_SB_DQ<24>")
	)
	(segment
		(start 318.203072 -301.997872)
		(end 317.972948 -301.997872)
		(width 0.14478)
		(layer "In2.Cu")
		(net "M_C_CPU0_SB_DQ<24>")
	)
	(segment
		(start 325.989442 -289.313112)
		(end 324.685914 -290.61664)
		(width 0.0889)
		(layer "In2.Cu")
		(net "M_C_CPU0_SB_DQ<24>")
	)
	(segment
		(start 319.516506 -299.60697)
		(end 319.940178 -300.030642)
		(width 0.14478)
		(layer "In2.Cu")
		(net "M_C_CPU0_SB_DQ<24>")
	)
	(segment
		(start 320.46672 -298.426632)
		(end 320.303398 -298.589954)
		(width 0.14478)
		(layer "In2.Cu")
		(net "M_C_CPU0_SB_DQ<24>")
	)
	(segment
		(start 326.813164 -289.059366)
		(end 326.559418 -289.313112)
		(width 0.0889)
		(layer "In2.Cu")
		(net "M_C_CPU0_SB_DQ<24>")
	)
	(segment
		(start 319.516506 -299.376846)
		(end 319.516506 -299.60697)
		(width 0.14478)
		(layer "In2.Cu")
		(net "M_C_CPU0_SB_DQ<24>")
	)
	(segment
		(start 305.950112 -309.110126)
		(end 305.099974 -309.960264)
		(width 0.14478)
		(layer "In2.Cu")
		(net "M_C_CPU0_SB_DQ<24>")
	)
	(segment
		(start 321.09029 -297.803062)
		(end 321.09029 -298.033186)
		(width 0.14478)
		(layer "In2.Cu")
		(net "M_C_CPU0_SB_DQ<24>")
	)
	(segment
		(start 321.35064 -298.850304)
		(end 321.120516 -298.850304)
		(width 0.14478)
		(layer "In2.Cu")
		(net "M_C_CPU0_SB_DQ<24>")
	)
	(segment
		(start 324.685914 -290.61664)
		(end 324.685914 -291.180012)
		(width 0.0889)
		(layer "In2.Cu")
		(net "M_C_CPU0_SB_DQ<24>")
	)
	(segment
		(start 318.75984 -301.21098)
		(end 318.336168 -300.787308)
		(width 0.14478)
		(layer "In2.Cu")
		(net "M_C_CPU0_SB_DQ<24>")
	)
	(segment
		(start 317.942722 -301.180754)
		(end 318.366394 -301.604426)
		(width 0.14478)
		(layer "In2.Cu")
		(net "M_C_CPU0_SB_DQ<24>")
	)
	(segment
		(start 317.086234 -301.807118)
		(end 317.086234 -302.080676)
		(width 0.14478)
		(layer "In2.Cu")
		(net "M_C_CPU0_SB_DQ<24>")
	)
	(segment
		(start 326.559418 -289.313112)
		(end 325.989442 -289.313112)
		(width 0.0889)
		(layer "In2.Cu")
		(net "M_C_CPU0_SB_DQ<24>")
	)
	(segment
		(start 305.099974 -309.960264)
		(end 301.808642 -309.960264)
		(width 0.14478)
		(layer "In2.Cu")
		(net "M_C_CPU0_SB_DQ<24>")
	)
	(segment
		(start 320.563748 -299.637196)
		(end 320.333624 -299.637196)
		(width 0.14478)
		(layer "In2.Cu")
		(net "M_C_CPU0_SB_DQ<24>")
	)
	(segment
		(start 318.366394 -301.604426)
		(end 318.366394 -301.83455)
		(width 0.14478)
		(layer "In2.Cu")
		(net "M_C_CPU0_SB_DQ<24>")
	)
	(segment
		(start 342.631014 -288.66592)
		(end 342.47709 -288.93135)
		(width 0.0889)
		(layer "In2.Cu")
		(net "M_C_CPU0_SB_DQ<24>")
	)
	(segment
		(start 342.47709 -288.93135)
		(end 342.381078 -288.95675)
		(width 0.0889)
		(layer "In2.Cu")
		(net "M_C_CPU0_SB_DQ<24>")
	)
	(segment
		(start 319.940178 -300.030642)
		(end 319.940178 -300.260766)
		(width 0.14478)
		(layer "In2.Cu")
		(net "M_C_CPU0_SB_DQ<24>")
	)
	(segment
		(start 321.09029 -298.033186)
		(end 321.513962 -298.456858)
		(width 0.14478)
		(layer "In2.Cu")
		(net "M_C_CPU0_SB_DQ<24>")
	)
	(segment
		(start 318.989964 -301.21098)
		(end 318.75984 -301.21098)
		(width 0.14478)
		(layer "In2.Cu")
		(net "M_C_CPU0_SB_DQ<24>")
	)
	(segment
		(start 320.72707 -299.473874)
		(end 320.563748 -299.637196)
		(width 0.14478)
		(layer "In2.Cu")
		(net "M_C_CPU0_SB_DQ<24>")
	)
	(segment
		(start 298.888912 -309.110126)
		(end 298.595288 -309.40375)
		(width 0.14478)
		(layer "In2.Cu")
		(net "M_C_CPU0_SB_DQ<24>")
	)
	(segment
		(start 321.120516 -298.850304)
		(end 320.696844 -298.426632)
		(width 0.14478)
		(layer "In2.Cu")
		(net "M_C_CPU0_SB_DQ<24>")
	)
	(segment
		(start 328.718164 -288.9885)
		(end 328.709782 -288.993326)
		(width 0.0889)
		(layer "In2.Cu")
		(net "M_C_CPU0_SB_DQ<24>")
	)
	(segment
		(start 332.478126 -288.9885)
		(end 332.469744 -288.993326)
		(width 0.0889)
		(layer "In2.Cu")
		(net "M_C_CPU0_SB_DQ<24>")
	)
	(segment
		(start 333.05242 -288.993326)
		(end 333.044038 -288.9885)
		(width 0.0889)
		(layer "In2.Cu")
		(net "M_C_CPU0_SB_DQ<24>")
	)
	(segment
		(start 292.705282 -309.960264)
		(end 292.280086 -309.535068)
		(width 0.14478)
		(layer "In2.Cu")
		(net "M_C_CPU0_SB_DQ<24>")
	)
	(segment
		(start 311.272936 -309.110126)
		(end 305.950112 -309.110126)
		(width 0.14478)
		(layer "In2.Cu")
		(net "M_C_CPU0_SB_DQ<24>")
	)
	(segment
		(start 318.336168 -300.787308)
		(end 318.106044 -300.787308)
		(width 0.14478)
		(layer "In2.Cu")
		(net "M_C_CPU0_SB_DQ<24>")
	)
	(segment
		(start 301.808642 -309.960264)
		(end 300.958504 -309.110126)
		(width 0.14478)
		(layer "In2.Cu")
		(net "M_C_CPU0_SB_DQ<24>")
	)
	(segment
		(start 318.106044 -300.787308)
		(end 317.942722 -300.95063)
		(width 0.14478)
		(layer "In2.Cu")
		(net "M_C_CPU0_SB_DQ<24>")
	)
	(segment
		(start 329.292458 -288.993326)
		(end 329.284076 -288.9885)
		(width 0.0889)
		(layer "In2.Cu")
		(net "M_C_CPU0_SB_DQ<24>")
	)
	(segment
		(start 317.972948 -301.997872)
		(end 317.549276 -301.5742)
		(width 0.14478)
		(layer "In2.Cu")
		(net "M_C_CPU0_SB_DQ<24>")
	)
	(segment
		(start 341.878158 -288.9885)
		(end 341.869776 -288.993326)
		(width 0.0889)
		(layer "In2.Cu")
		(net "M_C_CPU0_SB_DQ<24>")
	)
	(segment
		(start 320.303398 -298.589954)
		(end 320.303398 -298.820078)
		(width 0.14478)
		(layer "In2.Cu")
		(net "M_C_CPU0_SB_DQ<24>")
	)
	(segment
		(start 298.138088 -309.40375)
		(end 297.581574 -309.960264)
		(width 0.14478)
		(layer "In2.Cu")
		(net "M_C_CPU0_SB_DQ<24>")
	)
	(segment
		(start 317.319152 -301.5742)
		(end 317.086234 -301.807118)
		(width 0.14478)
		(layer "In2.Cu")
		(net "M_C_CPU0_SB_DQ<24>")
	)
	(segment
		(start 319.546732 -300.424088)
		(end 319.12306 -300.000416)
		(width 0.14478)
		(layer "In2.Cu")
		(net "M_C_CPU0_SB_DQ<24>")
	)
	(segment
		(start 319.909952 -299.213524)
		(end 319.679828 -299.213524)
		(width 0.14478)
		(layer "In2.Cu")
		(net "M_C_CPU0_SB_DQ<24>")
	)
	(arc
		(start 329.658218 -288.9885)
		(mid 329.475967 -289.03885)
		(end 329.292458 -288.993326)
		(width 0.0889)
		(layer "In2.Cu")
		(net "M_C_CPU0_SB_DQ<24>")
	)
	(arc
		(start 338.118196 -288.9885)
		(mid 337.935945 -289.03885)
		(end 337.752436 -288.993326)
		(width 0.0889)
		(layer "In2.Cu")
		(net "M_C_CPU0_SB_DQ<24>")
	)
	(arc
		(start 332.469744 -288.993326)
		(mid 332.286236 -289.03882)
		(end 332.103984 -288.9885)
		(width 0.0889)
		(layer "In2.Cu")
		(net "M_C_CPU0_SB_DQ<24>")
	)
	(arc
		(start 334.924146 -288.9885)
		(mid 334.64119 -288.912323)
		(end 334.358234 -288.9885)
		(width 0.0889)
		(layer "In2.Cu")
		(net "M_C_CPU0_SB_DQ<24>")
	)
	(arc
		(start 327.813924 -288.968942)
		(mid 327.693736 -289.011593)
		(end 327.567036 -289.026092)
		(width 0.0889)
		(layer "In2.Cu")
		(net "M_C_CPU0_SB_DQ<24>")
	)
	(arc
		(start 330.22413 -288.9885)
		(mid 329.941174 -288.912323)
		(end 329.658218 -288.9885)
		(width 0.0889)
		(layer "In2.Cu")
		(net "M_C_CPU0_SB_DQ<24>")
	)
	(arc
		(start 333.984092 -288.9885)
		(mid 333.701136 -288.912323)
		(end 333.41818 -288.9885)
		(width 0.0889)
		(layer "In2.Cu")
		(net "M_C_CPU0_SB_DQ<24>")
	)
	(arc
		(start 342.381078 -288.95675)
		(mid 342.12587 -288.913273)
		(end 341.878158 -288.9885)
		(width 0.0889)
		(layer "In2.Cu")
		(net "M_C_CPU0_SB_DQ<24>")
	)
	(arc
		(start 333.41818 -288.9885)
		(mid 333.235929 -289.03885)
		(end 333.05242 -288.993326)
		(width 0.0889)
		(layer "In2.Cu")
		(net "M_C_CPU0_SB_DQ<24>")
	)
	(arc
		(start 341.504016 -288.9885)
		(mid 341.22106 -288.912323)
		(end 340.938104 -288.9885)
		(width 0.0889)
		(layer "In2.Cu")
		(net "M_C_CPU0_SB_DQ<24>")
	)
	(arc
		(start 341.869776 -288.993326)
		(mid 341.686268 -289.03882)
		(end 341.504016 -288.9885)
		(width 0.0889)
		(layer "In2.Cu")
		(net "M_C_CPU0_SB_DQ<24>")
	)
	(arc
		(start 339.99805 -288.9885)
		(mid 339.811106 -289.038755)
		(end 339.624162 -288.9885)
		(width 0.0889)
		(layer "In2.Cu")
		(net "M_C_CPU0_SB_DQ<24>")
	)
	(arc
		(start 339.05825 -288.9885)
		(mid 338.875999 -289.03885)
		(end 338.69249 -288.993326)
		(width 0.0889)
		(layer "In2.Cu")
		(net "M_C_CPU0_SB_DQ<24>")
	)
	(arc
		(start 331.52969 -288.993326)
		(mid 331.346182 -289.03882)
		(end 331.16393 -288.9885)
		(width 0.0889)
		(layer "In2.Cu")
		(net "M_C_CPU0_SB_DQ<24>")
	)
	(arc
		(start 340.563962 -288.9885)
		(mid 340.281006 -288.912323)
		(end 339.99805 -288.9885)
		(width 0.0889)
		(layer "In2.Cu")
		(net "M_C_CPU0_SB_DQ<24>")
	)
	(arc
		(start 332.103984 -288.9885)
		(mid 331.821028 -288.912323)
		(end 331.538072 -288.9885)
		(width 0.0889)
		(layer "In2.Cu")
		(net "M_C_CPU0_SB_DQ<24>")
	)
	(arc
		(start 336.229706 -288.993326)
		(mid 336.046198 -289.03882)
		(end 335.863946 -288.9885)
		(width 0.0889)
		(layer "In2.Cu")
		(net "M_C_CPU0_SB_DQ<24>")
	)
	(arc
		(start 339.624162 -288.9885)
		(mid 339.341206 -288.912323)
		(end 339.05825 -288.9885)
		(width 0.0889)
		(layer "In2.Cu")
		(net "M_C_CPU0_SB_DQ<24>")
	)
	(arc
		(start 328.344022 -288.9885)
		(mid 328.08141 -288.912454)
		(end 327.813924 -288.968942)
		(width 0.0889)
		(layer "In2.Cu")
		(net "M_C_CPU0_SB_DQ<24>")
	)
	(arc
		(start 340.929722 -288.993326)
		(mid 340.746214 -289.03882)
		(end 340.563962 -288.9885)
		(width 0.0889)
		(layer "In2.Cu")
		(net "M_C_CPU0_SB_DQ<24>")
	)
	(arc
		(start 331.16393 -288.9885)
		(mid 330.880974 -288.912323)
		(end 330.598018 -288.9885)
		(width 0.0889)
		(layer "In2.Cu")
		(net "M_C_CPU0_SB_DQ<24>")
	)
	(arc
		(start 330.598018 -288.9885)
		(mid 330.411074 -289.038755)
		(end 330.22413 -288.9885)
		(width 0.0889)
		(layer "In2.Cu")
		(net "M_C_CPU0_SB_DQ<24>")
	)
	(arc
		(start 337.744054 -288.9885)
		(mid 337.461098 -288.912323)
		(end 337.178142 -288.9885)
		(width 0.0889)
		(layer "In2.Cu")
		(net "M_C_CPU0_SB_DQ<24>")
	)
	(arc
		(start 333.044038 -288.9885)
		(mid 332.761082 -288.912323)
		(end 332.478126 -288.9885)
		(width 0.0889)
		(layer "In2.Cu")
		(net "M_C_CPU0_SB_DQ<24>")
	)
	(arc
		(start 338.684108 -288.9885)
		(mid 338.401152 -288.912323)
		(end 338.118196 -288.9885)
		(width 0.0889)
		(layer "In2.Cu")
		(net "M_C_CPU0_SB_DQ<24>")
	)
	(arc
		(start 335.863946 -288.9885)
		(mid 335.58099 -288.912323)
		(end 335.298034 -288.9885)
		(width 0.0889)
		(layer "In2.Cu")
		(net "M_C_CPU0_SB_DQ<24>")
	)
	(arc
		(start 328.709782 -288.993326)
		(mid 328.526274 -289.03882)
		(end 328.344022 -288.9885)
		(width 0.0889)
		(layer "In2.Cu")
		(net "M_C_CPU0_SB_DQ<24>")
	)
	(arc
		(start 326.893428 -289.026092)
		(mid 326.849993 -289.03475)
		(end 326.813164 -289.059366)
		(width 0.0889)
		(layer "In2.Cu")
		(net "M_C_CPU0_SB_DQ<24>")
	)
	(arc
		(start 337.16976 -288.993326)
		(mid 336.986252 -289.03882)
		(end 336.804 -288.9885)
		(width 0.0889)
		(layer "In2.Cu")
		(net "M_C_CPU0_SB_DQ<24>")
	)
	(arc
		(start 335.298034 -288.9885)
		(mid 335.11109 -289.038755)
		(end 334.924146 -288.9885)
		(width 0.0889)
		(layer "In2.Cu")
		(net "M_C_CPU0_SB_DQ<24>")
	)
	(arc
		(start 334.358234 -288.9885)
		(mid 334.175983 -289.03885)
		(end 333.992474 -288.993326)
		(width 0.0889)
		(layer "In2.Cu")
		(net "M_C_CPU0_SB_DQ<24>")
	)
	(arc
		(start 336.804 -288.9885)
		(mid 336.521044 -288.912323)
		(end 336.238088 -288.9885)
		(width 0.0889)
		(layer "In2.Cu")
		(net "M_C_CPU0_SB_DQ<24>")
	)
	(arc
		(start 329.284076 -288.9885)
		(mid 329.00112 -288.912323)
		(end 328.718164 -288.9885)
		(width 0.0889)
		(layer "In2.Cu")
		(net "M_C_CPU0_SB_DQ<24>")
	)
	(segment
		(start 344.03792 -288.399982)
		(end 343.571068 -288.66592)
		(width 0.10668)
		(layer "F.Cu")
		(net "M_C_CPU0_SB_DQ<23>")
	)
	(segment
		(start 299.056552 -308.386988)
		(end 296.672762 -309.110126)
		(width 0.14478)
		(layer "In2.Cu")
		(net "M_C_CPU0_SB_DQ<23>")
	)
	(segment
		(start 288.60496 -309.110126)
		(end 288.180018 -308.685184)
		(width 0.14478)
		(layer "In2.Cu")
		(net "M_C_CPU0_SB_DQ<23>")
	)
	(segment
		(start 326.387206 -288.402014)
		(end 324.424294 -290.364926)
		(width 0.0889)
		(layer "In2.Cu")
		(net "M_C_CPU0_SB_DQ<23>")
	)
	(segment
		(start 307.249576 -308.259988)
		(end 305.970432 -308.514496)
		(width 0.14478)
		(layer "In2.Cu")
		(net "M_C_CPU0_SB_DQ<23>")
	)
	(segment
		(start 337.752436 -288.338768)
		(end 337.744054 -288.343594)
		(width 0.0889)
		(layer "In2.Cu")
		(net "M_C_CPU0_SB_DQ<23>")
	)
	(segment
		(start 299.694346 -308.259988)
		(end 299.056552 -308.386988)
		(width 0.14478)
		(layer "In2.Cu")
		(net "M_C_CPU0_SB_DQ<23>")
	)
	(segment
		(start 305.317144 -308.712616)
		(end 304.530252 -309.038752)
		(width 0.14478)
		(layer "In2.Cu")
		(net "M_C_CPU0_SB_DQ<23>")
	)
	(segment
		(start 309.01767 -308.259988)
		(end 307.249576 -308.259988)
		(width 0.14478)
		(layer "In2.Cu")
		(net "M_C_CPU0_SB_DQ<23>")
	)
	(segment
		(start 342.452452 -288.338768)
		(end 342.44407 -288.343594)
		(width 0.0889)
		(layer "In2.Cu")
		(net "M_C_CPU0_SB_DQ<23>")
	)
	(segment
		(start 321.632834 -296.473372)
		(end 316.529974 -301.576232)
		(width 0.14478)
		(layer "In2.Cu")
		(net "M_C_CPU0_SB_DQ<23>")
	)
	(segment
		(start 324.424294 -290.364926)
		(end 324.424294 -290.635436)
		(width 0.0889)
		(layer "In2.Cu")
		(net "M_C_CPU0_SB_DQ<23>")
	)
	(segment
		(start 331.538072 -288.343594)
		(end 331.52969 -288.338768)
		(width 0.0889)
		(layer "In2.Cu")
		(net "M_C_CPU0_SB_DQ<23>")
	)
	(segment
		(start 316.158372 -303.082198)
		(end 311.426606 -307.813964)
		(width 0.14478)
		(layer "In2.Cu")
		(net "M_C_CPU0_SB_DQ<23>")
	)
	(segment
		(start 304.171096 -309.110126)
		(end 302.186594 -309.110126)
		(width 0.14478)
		(layer "In2.Cu")
		(net "M_C_CPU0_SB_DQ<23>")
	)
	(segment
		(start 321.632834 -293.426896)
		(end 321.632834 -296.473372)
		(width 0.14478)
		(layer "In2.Cu")
		(net "M_C_CPU0_SB_DQ<23>")
	)
	(segment
		(start 300.770544 -308.421532)
		(end 299.957998 -308.259988)
		(width 0.14478)
		(layer "In2.Cu")
		(net "M_C_CPU0_SB_DQ<23>")
	)
	(segment
		(start 316.529974 -302.18507)
		(end 316.158372 -303.082198)
		(width 0.14478)
		(layer "In2.Cu")
		(net "M_C_CPU0_SB_DQ<23>")
	)
	(segment
		(start 305.970432 -308.514496)
		(end 305.317144 -308.712616)
		(width 0.14478)
		(layer "In2.Cu")
		(net "M_C_CPU0_SB_DQ<23>")
	)
	(segment
		(start 343.725246 -288.40049)
		(end 343.703148 -288.317432)
		(width 0.0889)
		(layer "In2.Cu")
		(net "M_C_CPU0_SB_DQ<23>")
	)
	(segment
		(start 329.292458 -288.338768)
		(end 329.284076 -288.343594)
		(width 0.0889)
		(layer "In2.Cu")
		(net "M_C_CPU0_SB_DQ<23>")
	)
	(segment
		(start 324.424294 -290.635436)
		(end 323.88937 -291.17036)
		(width 0.0889)
		(layer "In2.Cu")
		(net "M_C_CPU0_SB_DQ<23>")
	)
	(segment
		(start 343.392506 -288.338768)
		(end 343.384124 -288.343594)
		(width 0.0889)
		(layer "In2.Cu")
		(net "M_C_CPU0_SB_DQ<23>")
	)
	(segment
		(start 341.878158 -288.343594)
		(end 341.869776 -288.338768)
		(width 0.0889)
		(layer "In2.Cu")
		(net "M_C_CPU0_SB_DQ<23>")
	)
	(segment
		(start 333.05242 -288.338768)
		(end 333.044038 -288.343594)
		(width 0.0889)
		(layer "In2.Cu")
		(net "M_C_CPU0_SB_DQ<23>")
	)
	(segment
		(start 343.571068 -288.66592)
		(end 343.725246 -288.40049)
		(width 0.0889)
		(layer "In2.Cu")
		(net "M_C_CPU0_SB_DQ<23>")
	)
	(segment
		(start 304.530252 -309.038752)
		(end 304.171096 -309.110126)
		(width 0.14478)
		(layer "In2.Cu")
		(net "M_C_CPU0_SB_DQ<23>")
	)
	(segment
		(start 326.838056 -288.343594)
		(end 326.826372 -288.336736)
		(width 0.0889)
		(layer "In2.Cu")
		(net "M_C_CPU0_SB_DQ<23>")
	)
	(segment
		(start 316.529974 -301.576232)
		(end 316.529974 -302.18507)
		(width 0.14478)
		(layer "In2.Cu")
		(net "M_C_CPU0_SB_DQ<23>")
	)
	(segment
		(start 299.957998 -308.259988)
		(end 299.694346 -308.259988)
		(width 0.14478)
		(layer "In2.Cu")
		(net "M_C_CPU0_SB_DQ<23>")
	)
	(segment
		(start 301.338234 -308.656736)
		(end 300.770544 -308.421532)
		(width 0.14478)
		(layer "In2.Cu")
		(net "M_C_CPU0_SB_DQ<23>")
	)
	(segment
		(start 337.178142 -288.343594)
		(end 337.16976 -288.338768)
		(width 0.0889)
		(layer "In2.Cu")
		(net "M_C_CPU0_SB_DQ<23>")
	)
	(segment
		(start 310.869584 -308.077362)
		(end 309.01767 -308.259988)
		(width 0.14478)
		(layer "In2.Cu")
		(net "M_C_CPU0_SB_DQ<23>")
	)
	(segment
		(start 333.992474 -288.338768)
		(end 333.984092 -288.343594)
		(width 0.0889)
		(layer "In2.Cu")
		(net "M_C_CPU0_SB_DQ<23>")
	)
	(segment
		(start 338.69249 -288.338768)
		(end 338.684108 -288.343594)
		(width 0.0889)
		(layer "In2.Cu")
		(net "M_C_CPU0_SB_DQ<23>")
	)
	(segment
		(start 311.426606 -307.813964)
		(end 310.869584 -308.077362)
		(width 0.14478)
		(layer "In2.Cu")
		(net "M_C_CPU0_SB_DQ<23>")
	)
	(segment
		(start 340.938104 -288.343594)
		(end 340.929722 -288.338768)
		(width 0.0889)
		(layer "In2.Cu")
		(net "M_C_CPU0_SB_DQ<23>")
	)
	(segment
		(start 323.88937 -291.17036)
		(end 321.632834 -293.426896)
		(width 0.14478)
		(layer "In2.Cu")
		(net "M_C_CPU0_SB_DQ<23>")
	)
	(segment
		(start 327.77811 -288.343594)
		(end 327.769728 -288.338768)
		(width 0.0889)
		(layer "In2.Cu")
		(net "M_C_CPU0_SB_DQ<23>")
	)
	(segment
		(start 302.186594 -309.110126)
		(end 301.338234 -308.656736)
		(width 0.14478)
		(layer "In2.Cu")
		(net "M_C_CPU0_SB_DQ<23>")
	)
	(segment
		(start 336.238088 -288.343594)
		(end 336.229706 -288.338768)
		(width 0.0889)
		(layer "In2.Cu")
		(net "M_C_CPU0_SB_DQ<23>")
	)
	(segment
		(start 332.478126 -288.343594)
		(end 332.469744 -288.338768)
		(width 0.0889)
		(layer "In2.Cu")
		(net "M_C_CPU0_SB_DQ<23>")
	)
	(segment
		(start 296.672762 -309.110126)
		(end 288.60496 -309.110126)
		(width 0.14478)
		(layer "In2.Cu")
		(net "M_C_CPU0_SB_DQ<23>")
	)
	(segment
		(start 328.718164 -288.343594)
		(end 328.709782 -288.338768)
		(width 0.0889)
		(layer "In2.Cu")
		(net "M_C_CPU0_SB_DQ<23>")
	)
	(arc
		(start 340.563962 -288.343594)
		(mid 340.281006 -288.419771)
		(end 339.99805 -288.343594)
		(width 0.0889)
		(layer "In2.Cu")
		(net "M_C_CPU0_SB_DQ<23>")
	)
	(arc
		(start 334.358234 -288.343594)
		(mid 334.175983 -288.29321)
		(end 333.992474 -288.338768)
		(width 0.0889)
		(layer "In2.Cu")
		(net "M_C_CPU0_SB_DQ<23>")
	)
	(arc
		(start 337.16976 -288.338768)
		(mid 336.986252 -288.293243)
		(end 336.804 -288.343594)
		(width 0.0889)
		(layer "In2.Cu")
		(net "M_C_CPU0_SB_DQ<23>")
	)
	(arc
		(start 343.703148 -288.317432)
		(mid 343.545497 -288.29412)
		(end 343.392506 -288.338768)
		(width 0.0889)
		(layer "In2.Cu")
		(net "M_C_CPU0_SB_DQ<23>")
	)
	(arc
		(start 332.103984 -288.343594)
		(mid 331.821028 -288.419771)
		(end 331.538072 -288.343594)
		(width 0.0889)
		(layer "In2.Cu")
		(net "M_C_CPU0_SB_DQ<23>")
	)
	(arc
		(start 328.709782 -288.338768)
		(mid 328.526274 -288.293243)
		(end 328.344022 -288.343594)
		(width 0.0889)
		(layer "In2.Cu")
		(net "M_C_CPU0_SB_DQ<23>")
	)
	(arc
		(start 339.624162 -288.343594)
		(mid 339.341206 -288.419771)
		(end 339.05825 -288.343594)
		(width 0.0889)
		(layer "In2.Cu")
		(net "M_C_CPU0_SB_DQ<23>")
	)
	(arc
		(start 334.924146 -288.343594)
		(mid 334.64119 -288.419771)
		(end 334.358234 -288.343594)
		(width 0.0889)
		(layer "In2.Cu")
		(net "M_C_CPU0_SB_DQ<23>")
	)
	(arc
		(start 331.52969 -288.338768)
		(mid 331.346182 -288.293243)
		(end 331.16393 -288.343594)
		(width 0.0889)
		(layer "In2.Cu")
		(net "M_C_CPU0_SB_DQ<23>")
	)
	(arc
		(start 339.99805 -288.343594)
		(mid 339.811106 -288.293305)
		(end 339.624162 -288.343594)
		(width 0.0889)
		(layer "In2.Cu")
		(net "M_C_CPU0_SB_DQ<23>")
	)
	(arc
		(start 333.41818 -288.343594)
		(mid 333.235929 -288.29321)
		(end 333.05242 -288.338768)
		(width 0.0889)
		(layer "In2.Cu")
		(net "M_C_CPU0_SB_DQ<23>")
	)
	(arc
		(start 338.684108 -288.343594)
		(mid 338.401152 -288.419771)
		(end 338.118196 -288.343594)
		(width 0.0889)
		(layer "In2.Cu")
		(net "M_C_CPU0_SB_DQ<23>")
	)
	(arc
		(start 337.744054 -288.343594)
		(mid 337.461098 -288.419771)
		(end 337.178142 -288.343594)
		(width 0.0889)
		(layer "In2.Cu")
		(net "M_C_CPU0_SB_DQ<23>")
	)
	(arc
		(start 327.403968 -288.343594)
		(mid 327.121012 -288.419771)
		(end 326.838056 -288.343594)
		(width 0.0889)
		(layer "In2.Cu")
		(net "M_C_CPU0_SB_DQ<23>")
	)
	(arc
		(start 343.384124 -288.343594)
		(mid 343.101168 -288.419771)
		(end 342.818212 -288.343594)
		(width 0.0889)
		(layer "In2.Cu")
		(net "M_C_CPU0_SB_DQ<23>")
	)
	(arc
		(start 328.344022 -288.343594)
		(mid 328.061066 -288.419771)
		(end 327.77811 -288.343594)
		(width 0.0889)
		(layer "In2.Cu")
		(net "M_C_CPU0_SB_DQ<23>")
	)
	(arc
		(start 339.05825 -288.343594)
		(mid 338.875999 -288.29321)
		(end 338.69249 -288.338768)
		(width 0.0889)
		(layer "In2.Cu")
		(net "M_C_CPU0_SB_DQ<23>")
	)
	(arc
		(start 342.44407 -288.343594)
		(mid 342.161114 -288.419771)
		(end 341.878158 -288.343594)
		(width 0.0889)
		(layer "In2.Cu")
		(net "M_C_CPU0_SB_DQ<23>")
	)
	(arc
		(start 340.929722 -288.338768)
		(mid 340.746214 -288.293243)
		(end 340.563962 -288.343594)
		(width 0.0889)
		(layer "In2.Cu")
		(net "M_C_CPU0_SB_DQ<23>")
	)
	(arc
		(start 336.229706 -288.338768)
		(mid 336.046198 -288.293243)
		(end 335.863946 -288.343594)
		(width 0.0889)
		(layer "In2.Cu")
		(net "M_C_CPU0_SB_DQ<23>")
	)
	(arc
		(start 333.984092 -288.343594)
		(mid 333.701136 -288.419771)
		(end 333.41818 -288.343594)
		(width 0.0889)
		(layer "In2.Cu")
		(net "M_C_CPU0_SB_DQ<23>")
	)
	(arc
		(start 330.22413 -288.343594)
		(mid 329.941174 -288.419771)
		(end 329.658218 -288.343594)
		(width 0.0889)
		(layer "In2.Cu")
		(net "M_C_CPU0_SB_DQ<23>")
	)
	(arc
		(start 331.16393 -288.343594)
		(mid 330.880974 -288.419771)
		(end 330.598018 -288.343594)
		(width 0.0889)
		(layer "In2.Cu")
		(net "M_C_CPU0_SB_DQ<23>")
	)
	(arc
		(start 336.804 -288.343594)
		(mid 336.521044 -288.419771)
		(end 336.238088 -288.343594)
		(width 0.0889)
		(layer "In2.Cu")
		(net "M_C_CPU0_SB_DQ<23>")
	)
	(arc
		(start 327.769728 -288.338768)
		(mid 327.58622 -288.293243)
		(end 327.403968 -288.343594)
		(width 0.0889)
		(layer "In2.Cu")
		(net "M_C_CPU0_SB_DQ<23>")
	)
	(arc
		(start 335.298034 -288.343594)
		(mid 335.11109 -288.293305)
		(end 334.924146 -288.343594)
		(width 0.0889)
		(layer "In2.Cu")
		(net "M_C_CPU0_SB_DQ<23>")
	)
	(arc
		(start 338.118196 -288.343594)
		(mid 337.935945 -288.29321)
		(end 337.752436 -288.338768)
		(width 0.0889)
		(layer "In2.Cu")
		(net "M_C_CPU0_SB_DQ<23>")
	)
	(arc
		(start 341.504016 -288.343594)
		(mid 341.22106 -288.419771)
		(end 340.938104 -288.343594)
		(width 0.0889)
		(layer "In2.Cu")
		(net "M_C_CPU0_SB_DQ<23>")
	)
	(arc
		(start 342.818212 -288.343594)
		(mid 342.635961 -288.29321)
		(end 342.452452 -288.338768)
		(width 0.0889)
		(layer "In2.Cu")
		(net "M_C_CPU0_SB_DQ<23>")
	)
	(arc
		(start 330.598018 -288.343594)
		(mid 330.411074 -288.293305)
		(end 330.22413 -288.343594)
		(width 0.0889)
		(layer "In2.Cu")
		(net "M_C_CPU0_SB_DQ<23>")
	)
	(arc
		(start 326.826372 -288.336736)
		(mid 326.644117 -288.293054)
		(end 326.46366 -288.343594)
		(width 0.0889)
		(layer "In2.Cu")
		(net "M_C_CPU0_SB_DQ<23>")
	)
	(arc
		(start 329.658218 -288.343594)
		(mid 329.475967 -288.29321)
		(end 329.292458 -288.338768)
		(width 0.0889)
		(layer "In2.Cu")
		(net "M_C_CPU0_SB_DQ<23>")
	)
	(arc
		(start 332.469744 -288.338768)
		(mid 332.286236 -288.293243)
		(end 332.103984 -288.343594)
		(width 0.0889)
		(layer "In2.Cu")
		(net "M_C_CPU0_SB_DQ<23>")
	)
	(arc
		(start 341.869776 -288.338768)
		(mid 341.686268 -288.293243)
		(end 341.504016 -288.343594)
		(width 0.0889)
		(layer "In2.Cu")
		(net "M_C_CPU0_SB_DQ<23>")
	)
	(arc
		(start 333.044038 -288.343594)
		(mid 332.761082 -288.419771)
		(end 332.478126 -288.343594)
		(width 0.0889)
		(layer "In2.Cu")
		(net "M_C_CPU0_SB_DQ<23>")
	)
	(arc
		(start 335.863946 -288.343594)
		(mid 335.58099 -288.419771)
		(end 335.298034 -288.343594)
		(width 0.0889)
		(layer "In2.Cu")
		(net "M_C_CPU0_SB_DQ<23>")
	)
	(arc
		(start 326.46366 -288.343594)
		(mid 326.423549 -288.370337)
		(end 326.387206 -288.402014)
		(width 0.0889)
		(layer "In2.Cu")
		(net "M_C_CPU0_SB_DQ<23>")
	)
	(arc
		(start 329.284076 -288.343594)
		(mid 329.00112 -288.419771)
		(end 328.718164 -288.343594)
		(width 0.0889)
		(layer "In2.Cu")
		(net "M_C_CPU0_SB_DQ<23>")
	)
	(segment
		(start 342.627966 -287.59023)
		(end 342.161114 -287.856168)
		(width 0.10668)
		(layer "F.Cu")
		(net "M_C_CPU0_SB_DQ<22>")
	)
	(segment
		(start 335.402428 -287.528762)
		(end 335.394046 -287.533588)
		(width 0.0889)
		(layer "In2.Cu")
		(net "M_C_CPU0_SB_DQ<22>")
	)
	(segment
		(start 330.702412 -287.528762)
		(end 330.69403 -287.533588)
		(width 0.0889)
		(layer "In2.Cu")
		(net "M_C_CPU0_SB_DQ<22>")
	)
	(segment
		(start 289.677094 -307.22443)
		(end 289.49142 -307.410104)
		(width 0.14478)
		(layer "In2.Cu")
		(net "M_C_CPU0_SB_DQ<22>")
	)
	(segment
		(start 326.935846 -287.533334)
		(end 326.872854 -287.570164)
		(width 0.0889)
		(layer "In2.Cu")
		(net "M_C_CPU0_SB_DQ<22>")
	)
	(segment
		(start 334.828134 -287.533588)
		(end 334.819752 -287.528762)
		(width 0.0889)
		(layer "In2.Cu")
		(net "M_C_CPU0_SB_DQ<22>")
	)
	(segment
		(start 305.124866 -307.410104)
		(end 301.665386 -307.410104)
		(width 0.14478)
		(layer "In2.Cu")
		(net "M_C_CPU0_SB_DQ<22>")
	)
	(segment
		(start 327.895966 -287.521904)
		(end 327.875392 -287.533588)
		(width 0.0889)
		(layer "In2.Cu")
		(net "M_C_CPU0_SB_DQ<22>")
	)
	(segment
		(start 320.723514 -292.921944)
		(end 320.723514 -296.07891)
		(width 0.14478)
		(layer "In2.Cu")
		(net "M_C_CPU0_SB_DQ<22>")
	)
	(segment
		(start 314.395358 -303.558194)
		(end 311.393586 -306.559966)
		(width 0.14478)
		(layer "In2.Cu")
		(net "M_C_CPU0_SB_DQ<22>")
	)
	(segment
		(start 327.875392 -287.533588)
		(end 327.847706 -287.54959)
		(width 0.0889)
		(layer "In2.Cu")
		(net "M_C_CPU0_SB_DQ<22>")
	)
	(segment
		(start 342.161114 -287.856168)
		(end 342.315038 -287.590738)
		(width 0.0889)
		(layer "In2.Cu")
		(net "M_C_CPU0_SB_DQ<22>")
	)
	(segment
		(start 290.05784 -307.22443)
		(end 289.677094 -307.22443)
		(width 0.14478)
		(layer "In2.Cu")
		(net "M_C_CPU0_SB_DQ<22>")
	)
	(segment
		(start 297.388534 -307.410104)
		(end 290.243514 -307.410104)
		(width 0.14478)
		(layer "In2.Cu")
		(net "M_C_CPU0_SB_DQ<22>")
	)
	(segment
		(start 339.52815 -287.533588)
		(end 339.519768 -287.528762)
		(width 0.0889)
		(layer "In2.Cu")
		(net "M_C_CPU0_SB_DQ<22>")
	)
	(segment
		(start 314.395358 -302.407066)
		(end 314.395358 -303.558194)
		(width 0.14478)
		(layer "In2.Cu")
		(net "M_C_CPU0_SB_DQ<22>")
	)
	(segment
		(start 323.897244 -289.5473)
		(end 323.897244 -289.748214)
		(width 0.0889)
		(layer "In2.Cu")
		(net "M_C_CPU0_SB_DQ<22>")
	)
	(segment
		(start 327.311258 -287.533588)
		(end 327.28789 -287.520126)
		(width 0.0889)
		(layer "In2.Cu")
		(net "M_C_CPU0_SB_DQ<22>")
	)
	(segment
		(start 325.79437 -287.843722)
		(end 325.331582 -288.30651)
		(width 0.0889)
		(layer "In2.Cu")
		(net "M_C_CPU0_SB_DQ<22>")
	)
	(segment
		(start 301.665386 -307.410104)
		(end 300.815248 -306.559966)
		(width 0.14478)
		(layer "In2.Cu")
		(net "M_C_CPU0_SB_DQ<22>")
	)
	(segment
		(start 311.393586 -306.559966)
		(end 305.975004 -306.559966)
		(width 0.14478)
		(layer "In2.Cu")
		(net "M_C_CPU0_SB_DQ<22>")
	)
	(segment
		(start 305.975004 -306.559966)
		(end 305.124866 -307.410104)
		(width 0.14478)
		(layer "In2.Cu")
		(net "M_C_CPU0_SB_DQ<22>")
	)
	(segment
		(start 325.138034 -288.30651)
		(end 323.897244 -289.5473)
		(width 0.0889)
		(layer "In2.Cu")
		(net "M_C_CPU0_SB_DQ<22>")
	)
	(segment
		(start 331.642466 -287.528762)
		(end 331.634084 -287.533588)
		(width 0.0889)
		(layer "In2.Cu")
		(net "M_C_CPU0_SB_DQ<22>")
	)
	(segment
		(start 336.342482 -287.528762)
		(end 336.3341 -287.533588)
		(width 0.0889)
		(layer "In2.Cu")
		(net "M_C_CPU0_SB_DQ<22>")
	)
	(segment
		(start 323.897244 -289.748214)
		(end 320.723514 -292.921944)
		(width 0.14478)
		(layer "In2.Cu")
		(net "M_C_CPU0_SB_DQ<22>")
	)
	(segment
		(start 288.60496 -307.410104)
		(end 288.180018 -306.985162)
		(width 0.14478)
		(layer "In2.Cu")
		(net "M_C_CPU0_SB_DQ<22>")
	)
	(segment
		(start 333.88808 -287.533588)
		(end 333.879698 -287.528762)
		(width 0.0889)
		(layer "In2.Cu")
		(net "M_C_CPU0_SB_DQ<22>")
	)
	(segment
		(start 298.238672 -306.559966)
		(end 297.388534 -307.410104)
		(width 0.14478)
		(layer "In2.Cu")
		(net "M_C_CPU0_SB_DQ<22>")
	)
	(segment
		(start 340.102444 -287.528762)
		(end 340.094062 -287.533588)
		(width 0.0889)
		(layer "In2.Cu")
		(net "M_C_CPU0_SB_DQ<22>")
	)
	(segment
		(start 338.588096 -287.533588)
		(end 338.579714 -287.528762)
		(width 0.0889)
		(layer "In2.Cu")
		(net "M_C_CPU0_SB_DQ<22>")
	)
	(segment
		(start 326.715882 -287.612582)
		(end 326.352408 -287.612582)
		(width 0.0889)
		(layer "In2.Cu")
		(net "M_C_CPU0_SB_DQ<22>")
	)
	(segment
		(start 300.815248 -306.559966)
		(end 298.238672 -306.559966)
		(width 0.14478)
		(layer "In2.Cu")
		(net "M_C_CPU0_SB_DQ<22>")
	)
	(segment
		(start 325.331582 -288.30651)
		(end 325.138034 -288.30651)
		(width 0.0889)
		(layer "In2.Cu")
		(net "M_C_CPU0_SB_DQ<22>")
	)
	(segment
		(start 330.128118 -287.533588)
		(end 330.119736 -287.528762)
		(width 0.0889)
		(layer "In2.Cu")
		(net "M_C_CPU0_SB_DQ<22>")
	)
	(segment
		(start 320.723514 -296.07891)
		(end 314.395358 -302.407066)
		(width 0.14478)
		(layer "In2.Cu")
		(net "M_C_CPU0_SB_DQ<22>")
	)
	(segment
		(start 290.243514 -307.410104)
		(end 290.05784 -307.22443)
		(width 0.14478)
		(layer "In2.Cu")
		(net "M_C_CPU0_SB_DQ<22>")
	)
	(segment
		(start 289.49142 -307.410104)
		(end 288.60496 -307.410104)
		(width 0.14478)
		(layer "In2.Cu")
		(net "M_C_CPU0_SB_DQ<22>")
	)
	(segment
		(start 341.042498 -287.528762)
		(end 341.034116 -287.533588)
		(width 0.0889)
		(layer "In2.Cu")
		(net "M_C_CPU0_SB_DQ<22>")
	)
	(segment
		(start 342.315038 -287.590738)
		(end 342.292686 -287.507426)
		(width 0.0889)
		(layer "In2.Cu")
		(net "M_C_CPU0_SB_DQ<22>")
	)
	(arc
		(start 336.708242 -287.533588)
		(mid 336.525991 -287.483238)
		(end 336.342482 -287.528762)
		(width 0.0889)
		(layer "In2.Cu")
		(net "M_C_CPU0_SB_DQ<22>")
	)
	(arc
		(start 326.872854 -287.570164)
		(mid 326.797188 -287.601816)
		(end 326.715882 -287.612582)
		(width 0.0889)
		(layer "In2.Cu")
		(net "M_C_CPU0_SB_DQ<22>")
	)
	(arc
		(start 332.948026 -287.533588)
		(mid 332.761082 -287.483333)
		(end 332.574138 -287.533588)
		(width 0.0889)
		(layer "In2.Cu")
		(net "M_C_CPU0_SB_DQ<22>")
	)
	(arc
		(start 331.634084 -287.533588)
		(mid 331.351128 -287.609731)
		(end 331.068172 -287.533588)
		(width 0.0889)
		(layer "In2.Cu")
		(net "M_C_CPU0_SB_DQ<22>")
	)
	(arc
		(start 338.579714 -287.528762)
		(mid 338.396206 -287.483268)
		(end 338.213954 -287.533588)
		(width 0.0889)
		(layer "In2.Cu")
		(net "M_C_CPU0_SB_DQ<22>")
	)
	(arc
		(start 340.094062 -287.533588)
		(mid 339.811106 -287.609731)
		(end 339.52815 -287.533588)
		(width 0.0889)
		(layer "In2.Cu")
		(net "M_C_CPU0_SB_DQ<22>")
	)
	(arc
		(start 336.3341 -287.533588)
		(mid 336.051144 -287.609731)
		(end 335.768188 -287.533588)
		(width 0.0889)
		(layer "In2.Cu")
		(net "M_C_CPU0_SB_DQ<22>")
	)
	(arc
		(start 333.879698 -287.528762)
		(mid 333.69619 -287.483268)
		(end 333.513938 -287.533588)
		(width 0.0889)
		(layer "In2.Cu")
		(net "M_C_CPU0_SB_DQ<22>")
	)
	(arc
		(start 337.274154 -287.533588)
		(mid 336.991198 -287.609731)
		(end 336.708242 -287.533588)
		(width 0.0889)
		(layer "In2.Cu")
		(net "M_C_CPU0_SB_DQ<22>")
	)
	(arc
		(start 327.28789 -287.520126)
		(mid 327.110226 -287.482694)
		(end 326.935846 -287.533334)
		(width 0.0889)
		(layer "In2.Cu")
		(net "M_C_CPU0_SB_DQ<22>")
	)
	(arc
		(start 339.154008 -287.533588)
		(mid 338.871052 -287.609731)
		(end 338.588096 -287.533588)
		(width 0.0889)
		(layer "In2.Cu")
		(net "M_C_CPU0_SB_DQ<22>")
	)
	(arc
		(start 341.408258 -287.533588)
		(mid 341.226007 -287.483238)
		(end 341.042498 -287.528762)
		(width 0.0889)
		(layer "In2.Cu")
		(net "M_C_CPU0_SB_DQ<22>")
	)
	(arc
		(start 341.97417 -287.533588)
		(mid 341.691214 -287.609731)
		(end 341.408258 -287.533588)
		(width 0.0889)
		(layer "In2.Cu")
		(net "M_C_CPU0_SB_DQ<22>")
	)
	(arc
		(start 329.753976 -287.533588)
		(mid 329.47102 -287.609731)
		(end 329.188064 -287.533588)
		(width 0.0889)
		(layer "In2.Cu")
		(net "M_C_CPU0_SB_DQ<22>")
	)
	(arc
		(start 342.292686 -287.507426)
		(mid 342.130497 -287.484691)
		(end 341.97417 -287.533588)
		(width 0.0889)
		(layer "In2.Cu")
		(net "M_C_CPU0_SB_DQ<22>")
	)
	(arc
		(start 340.468204 -287.533588)
		(mid 340.285953 -287.483238)
		(end 340.102444 -287.528762)
		(width 0.0889)
		(layer "In2.Cu")
		(net "M_C_CPU0_SB_DQ<22>")
	)
	(arc
		(start 332.008226 -287.533588)
		(mid 331.825975 -287.483238)
		(end 331.642466 -287.528762)
		(width 0.0889)
		(layer "In2.Cu")
		(net "M_C_CPU0_SB_DQ<22>")
	)
	(arc
		(start 341.034116 -287.533588)
		(mid 340.75116 -287.609731)
		(end 340.468204 -287.533588)
		(width 0.0889)
		(layer "In2.Cu")
		(net "M_C_CPU0_SB_DQ<22>")
	)
	(arc
		(start 338.213954 -287.533588)
		(mid 337.930998 -287.609731)
		(end 337.648042 -287.533588)
		(width 0.0889)
		(layer "In2.Cu")
		(net "M_C_CPU0_SB_DQ<22>")
	)
	(arc
		(start 333.513938 -287.533588)
		(mid 333.230982 -287.609731)
		(end 332.948026 -287.533588)
		(width 0.0889)
		(layer "In2.Cu")
		(net "M_C_CPU0_SB_DQ<22>")
	)
	(arc
		(start 335.394046 -287.533588)
		(mid 335.11109 -287.609731)
		(end 334.828134 -287.533588)
		(width 0.0889)
		(layer "In2.Cu")
		(net "M_C_CPU0_SB_DQ<22>")
	)
	(arc
		(start 332.574138 -287.533588)
		(mid 332.291182 -287.609731)
		(end 332.008226 -287.533588)
		(width 0.0889)
		(layer "In2.Cu")
		(net "M_C_CPU0_SB_DQ<22>")
	)
	(arc
		(start 328.248264 -287.533588)
		(mid 328.073593 -287.483535)
		(end 327.895966 -287.521904)
		(width 0.0889)
		(layer "In2.Cu")
		(net "M_C_CPU0_SB_DQ<22>")
	)
	(arc
		(start 334.819752 -287.528762)
		(mid 334.636244 -287.483268)
		(end 334.453992 -287.533588)
		(width 0.0889)
		(layer "In2.Cu")
		(net "M_C_CPU0_SB_DQ<22>")
	)
	(arc
		(start 327.847706 -287.54959)
		(mid 327.577449 -287.609533)
		(end 327.311258 -287.533588)
		(width 0.0889)
		(layer "In2.Cu")
		(net "M_C_CPU0_SB_DQ<22>")
	)
	(arc
		(start 335.768188 -287.533588)
		(mid 335.585937 -287.483238)
		(end 335.402428 -287.528762)
		(width 0.0889)
		(layer "In2.Cu")
		(net "M_C_CPU0_SB_DQ<22>")
	)
	(arc
		(start 337.648042 -287.533588)
		(mid 337.461098 -287.483333)
		(end 337.274154 -287.533588)
		(width 0.0889)
		(layer "In2.Cu")
		(net "M_C_CPU0_SB_DQ<22>")
	)
	(arc
		(start 328.814176 -287.533588)
		(mid 328.53122 -287.609731)
		(end 328.248264 -287.533588)
		(width 0.0889)
		(layer "In2.Cu")
		(net "M_C_CPU0_SB_DQ<22>")
	)
	(arc
		(start 330.69403 -287.533588)
		(mid 330.411074 -287.609731)
		(end 330.128118 -287.533588)
		(width 0.0889)
		(layer "In2.Cu")
		(net "M_C_CPU0_SB_DQ<22>")
	)
	(arc
		(start 326.352408 -287.612582)
		(mid 326.050403 -287.672655)
		(end 325.79437 -287.843722)
		(width 0.0889)
		(layer "In2.Cu")
		(net "M_C_CPU0_SB_DQ<22>")
	)
	(arc
		(start 329.188064 -287.533588)
		(mid 329.00112 -287.483333)
		(end 328.814176 -287.533588)
		(width 0.0889)
		(layer "In2.Cu")
		(net "M_C_CPU0_SB_DQ<22>")
	)
	(arc
		(start 334.453992 -287.533588)
		(mid 334.171036 -287.609731)
		(end 333.88808 -287.533588)
		(width 0.0889)
		(layer "In2.Cu")
		(net "M_C_CPU0_SB_DQ<22>")
	)
	(arc
		(start 339.519768 -287.528762)
		(mid 339.33626 -287.483268)
		(end 339.154008 -287.533588)
		(width 0.0889)
		(layer "In2.Cu")
		(net "M_C_CPU0_SB_DQ<22>")
	)
	(arc
		(start 331.068172 -287.533588)
		(mid 330.885921 -287.483238)
		(end 330.702412 -287.528762)
		(width 0.0889)
		(layer "In2.Cu")
		(net "M_C_CPU0_SB_DQ<22>")
	)
	(arc
		(start 330.119736 -287.528762)
		(mid 329.936228 -287.483268)
		(end 329.753976 -287.533588)
		(width 0.0889)
		(layer "In2.Cu")
		(net "M_C_CPU0_SB_DQ<22>")
	)
	(segment
		(start 344.508074 -287.59023)
		(end 344.041222 -287.856168)
		(width 0.10668)
		(layer "F.Cu")
		(net "M_C_CPU0_SB_DQ<21>")
	)
	(segment
		(start 294.154098 -308.021736)
		(end 293.992554 -307.860192)
		(width 0.14478)
		(layer "In2.Cu")
		(net "M_C_CPU0_SB_DQ<21>")
	)
	(segment
		(start 343.887044 -288.121598)
		(end 343.791286 -288.146998)
		(width 0.0889)
		(layer "In2.Cu")
		(net "M_C_CPU0_SB_DQ<21>")
	)
	(segment
		(start 326.94245 -288.18332)
		(end 326.934068 -288.178494)
		(width 0.0889)
		(layer "In2.Cu")
		(net "M_C_CPU0_SB_DQ<21>")
	)
	(segment
		(start 298.16806 -307.410104)
		(end 297.317922 -308.260242)
		(width 0.14478)
		(layer "In2.Cu")
		(net "M_C_CPU0_SB_DQ<21>")
	)
	(segment
		(start 309.90159 -307.410104)
		(end 309.656988 -307.410104)
		(width 0.14478)
		(layer "In2.Cu")
		(net "M_C_CPU0_SB_DQ<21>")
	)
	(segment
		(start 309.105554 -307.103272)
		(end 308.798722 -307.410104)
		(width 0.14478)
		(layer "In2.Cu")
		(net "M_C_CPU0_SB_DQ<21>")
	)
	(segment
		(start 324.459854 -289.29457)
		(end 324.459854 -289.88639)
		(width 0.0889)
		(layer "In2.Cu")
		(net "M_C_CPU0_SB_DQ<21>")
	)
	(segment
		(start 315.477144 -302.745648)
		(end 315.243464 -302.511968)
		(width 0.14478)
		(layer "In2.Cu")
		(net "M_C_CPU0_SB_DQ<21>")
	)
	(segment
		(start 314.850018 -302.905414)
		(end 315.157612 -303.213008)
		(width 0.14478)
		(layer "In2.Cu")
		(net "M_C_CPU0_SB_DQ<21>")
	)
	(segment
		(start 308.002686 -307.103272)
		(end 307.695854 -307.410104)
		(width 0.14478)
		(layer "In2.Cu")
		(net "M_C_CPU0_SB_DQ<21>")
	)
	(segment
		(start 333.88808 -288.178494)
		(end 333.879698 -288.18332)
		(width 0.0889)
		(layer "In2.Cu")
		(net "M_C_CPU0_SB_DQ<21>")
	)
	(segment
		(start 339.52815 -288.178494)
		(end 339.519768 -288.18332)
		(width 0.0889)
		(layer "In2.Cu")
		(net "M_C_CPU0_SB_DQ<21>")
	)
	(segment
		(start 310.496458 -307.146452)
		(end 310.453024 -307.103272)
		(width 0.14478)
		(layer "In2.Cu")
		(net "M_C_CPU0_SB_DQ<21>")
	)
	(segment
		(start 308.247288 -307.103272)
		(end 308.002686 -307.103272)
		(width 0.14478)
		(layer "In2.Cu")
		(net "M_C_CPU0_SB_DQ<21>")
	)
	(segment
		(start 310.759856 -307.410104)
		(end 310.496458 -307.146452)
		(width 0.14478)
		(layer "In2.Cu")
		(net "M_C_CPU0_SB_DQ<21>")
	)
	(segment
		(start 315.63691 -302.118522)
		(end 315.87059 -302.352202)
		(width 0.14478)
		(layer "In2.Cu")
		(net "M_C_CPU0_SB_DQ<21>")
	)
	(segment
		(start 311.186576 -307.410104)
		(end 310.759856 -307.410104)
		(width 0.14478)
		(layer "In2.Cu")
		(net "M_C_CPU0_SB_DQ<21>")
	)
	(segment
		(start 301.022004 -307.410104)
		(end 298.16806 -307.410104)
		(width 0.14478)
		(layer "In2.Cu")
		(net "M_C_CPU0_SB_DQ<21>")
	)
	(segment
		(start 315.707268 -302.745648)
		(end 315.477144 -302.745648)
		(width 0.14478)
		(layer "In2.Cu")
		(net "M_C_CPU0_SB_DQ<21>")
	)
	(segment
		(start 293.44112 -308.260242)
		(end 292.705282 -308.260242)
		(width 0.14478)
		(layer "In2.Cu")
		(net "M_C_CPU0_SB_DQ<21>")
	)
	(segment
		(start 315.87059 -302.352202)
		(end 315.87059 -302.582326)
		(width 0.14478)
		(layer "In2.Cu")
		(net "M_C_CPU0_SB_DQ<21>")
	)
	(segment
		(start 305.009042 -308.260242)
		(end 301.872142 -308.260242)
		(width 0.14478)
		(layer "In2.Cu")
		(net "M_C_CPU0_SB_DQ<21>")
	)
	(segment
		(start 309.350156 -307.103272)
		(end 309.105554 -307.103272)
		(width 0.14478)
		(layer "In2.Cu")
		(net "M_C_CPU0_SB_DQ<21>")
	)
	(segment
		(start 309.656988 -307.410104)
		(end 309.350156 -307.103272)
		(width 0.14478)
		(layer "In2.Cu")
		(net "M_C_CPU0_SB_DQ<21>")
	)
	(segment
		(start 338.588096 -288.178494)
		(end 338.579714 -288.18332)
		(width 0.0889)
		(layer "In2.Cu")
		(net "M_C_CPU0_SB_DQ<21>")
	)
	(segment
		(start 293.992554 -307.860192)
		(end 293.764208 -307.860192)
		(width 0.14478)
		(layer "In2.Cu")
		(net "M_C_CPU0_SB_DQ<21>")
	)
	(segment
		(start 314.850018 -302.67529)
		(end 314.850018 -302.905414)
		(width 0.14478)
		(layer "In2.Cu")
		(net "M_C_CPU0_SB_DQ<21>")
	)
	(segment
		(start 340.102444 -288.18332)
		(end 340.094062 -288.178494)
		(width 0.0889)
		(layer "In2.Cu")
		(net "M_C_CPU0_SB_DQ<21>")
	)
	(segment
		(start 310.208422 -307.103272)
		(end 309.90159 -307.410104)
		(width 0.14478)
		(layer "In2.Cu")
		(net "M_C_CPU0_SB_DQ<21>")
	)
	(segment
		(start 293.602664 -308.021736)
		(end 293.602664 -308.098698)
		(width 0.14478)
		(layer "In2.Cu")
		(net "M_C_CPU0_SB_DQ<21>")
	)
	(segment
		(start 325.882762 -288.63671)
		(end 325.117714 -288.63671)
		(width 0.0889)
		(layer "In2.Cu")
		(net "M_C_CPU0_SB_DQ<21>")
	)
	(segment
		(start 321.178174 -296.28465)
		(end 315.63691 -301.825914)
		(width 0.14478)
		(layer "In2.Cu")
		(net "M_C_CPU0_SB_DQ<21>")
	)
	(segment
		(start 321.178174 -293.16807)
		(end 321.178174 -296.28465)
		(width 0.14478)
		(layer "In2.Cu")
		(net "M_C_CPU0_SB_DQ<21>")
	)
	(segment
		(start 315.63691 -301.825914)
		(end 315.63691 -302.118522)
		(width 0.14478)
		(layer "In2.Cu")
		(net "M_C_CPU0_SB_DQ<21>")
	)
	(segment
		(start 297.317922 -308.260242)
		(end 294.315642 -308.260242)
		(width 0.14478)
		(layer "In2.Cu")
		(net "M_C_CPU0_SB_DQ<21>")
	)
	(segment
		(start 330.702412 -288.18332)
		(end 330.69403 -288.178494)
		(width 0.0889)
		(layer "In2.Cu")
		(net "M_C_CPU0_SB_DQ<21>")
	)
	(segment
		(start 315.157612 -303.213008)
		(end 315.157612 -303.439068)
		(width 0.14478)
		(layer "In2.Cu")
		(net "M_C_CPU0_SB_DQ<21>")
	)
	(segment
		(start 344.041222 -287.856168)
		(end 343.887044 -288.121598)
		(width 0.0889)
		(layer "In2.Cu")
		(net "M_C_CPU0_SB_DQ<21>")
	)
	(segment
		(start 330.128118 -288.178494)
		(end 330.119736 -288.18332)
		(width 0.0889)
		(layer "In2.Cu")
		(net "M_C_CPU0_SB_DQ<21>")
	)
	(segment
		(start 315.157612 -303.439068)
		(end 311.186576 -307.410104)
		(width 0.14478)
		(layer "In2.Cu")
		(net "M_C_CPU0_SB_DQ<21>")
	)
	(segment
		(start 326.252586 -288.266886)
		(end 325.882762 -288.63671)
		(width 0.0889)
		(layer "In2.Cu")
		(net "M_C_CPU0_SB_DQ<21>")
	)
	(segment
		(start 325.117714 -288.63671)
		(end 324.459854 -289.29457)
		(width 0.0889)
		(layer "In2.Cu")
		(net "M_C_CPU0_SB_DQ<21>")
	)
	(segment
		(start 341.042498 -288.18332)
		(end 341.034116 -288.178494)
		(width 0.0889)
		(layer "In2.Cu")
		(net "M_C_CPU0_SB_DQ<21>")
	)
	(segment
		(start 308.55412 -307.410104)
		(end 308.247288 -307.103272)
		(width 0.14478)
		(layer "In2.Cu")
		(net "M_C_CPU0_SB_DQ<21>")
	)
	(segment
		(start 294.315642 -308.260242)
		(end 294.154098 -308.098698)
		(width 0.14478)
		(layer "In2.Cu")
		(net "M_C_CPU0_SB_DQ<21>")
	)
	(segment
		(start 292.705282 -308.260242)
		(end 292.280086 -307.835046)
		(width 0.14478)
		(layer "In2.Cu")
		(net "M_C_CPU0_SB_DQ<21>")
	)
	(segment
		(start 308.798722 -307.410104)
		(end 308.55412 -307.410104)
		(width 0.14478)
		(layer "In2.Cu")
		(net "M_C_CPU0_SB_DQ<21>")
	)
	(segment
		(start 324.459854 -289.88639)
		(end 323.868034 -290.47821)
		(width 0.0889)
		(layer "In2.Cu")
		(net "M_C_CPU0_SB_DQ<21>")
	)
	(segment
		(start 293.764208 -307.860192)
		(end 293.602664 -308.021736)
		(width 0.14478)
		(layer "In2.Cu")
		(net "M_C_CPU0_SB_DQ<21>")
	)
	(segment
		(start 315.243464 -302.511968)
		(end 315.01334 -302.511968)
		(width 0.14478)
		(layer "In2.Cu")
		(net "M_C_CPU0_SB_DQ<21>")
	)
	(segment
		(start 331.642466 -288.18332)
		(end 331.634084 -288.178494)
		(width 0.0889)
		(layer "In2.Cu")
		(net "M_C_CPU0_SB_DQ<21>")
	)
	(segment
		(start 315.87059 -302.582326)
		(end 315.707268 -302.745648)
		(width 0.14478)
		(layer "In2.Cu")
		(net "M_C_CPU0_SB_DQ<21>")
	)
	(segment
		(start 310.453024 -307.103272)
		(end 310.208422 -307.103272)
		(width 0.14478)
		(layer "In2.Cu")
		(net "M_C_CPU0_SB_DQ<21>")
	)
	(segment
		(start 335.402428 -288.18332)
		(end 335.394046 -288.178494)
		(width 0.0889)
		(layer "In2.Cu")
		(net "M_C_CPU0_SB_DQ<21>")
	)
	(segment
		(start 294.154098 -308.098698)
		(end 294.154098 -308.021736)
		(width 0.14478)
		(layer "In2.Cu")
		(net "M_C_CPU0_SB_DQ<21>")
	)
	(segment
		(start 301.872142 -308.260242)
		(end 301.022004 -307.410104)
		(width 0.14478)
		(layer "In2.Cu")
		(net "M_C_CPU0_SB_DQ<21>")
	)
	(segment
		(start 307.695854 -307.410104)
		(end 305.85918 -307.410104)
		(width 0.14478)
		(layer "In2.Cu")
		(net "M_C_CPU0_SB_DQ<21>")
	)
	(segment
		(start 343.288112 -288.178494)
		(end 343.27973 -288.18332)
		(width 0.0889)
		(layer "In2.Cu")
		(net "M_C_CPU0_SB_DQ<21>")
	)
	(segment
		(start 334.828134 -288.178494)
		(end 334.819752 -288.18332)
		(width 0.0889)
		(layer "In2.Cu")
		(net "M_C_CPU0_SB_DQ<21>")
	)
	(segment
		(start 323.868034 -290.47821)
		(end 321.178174 -293.16807)
		(width 0.14478)
		(layer "In2.Cu")
		(net "M_C_CPU0_SB_DQ<21>")
	)
	(segment
		(start 315.01334 -302.511968)
		(end 314.850018 -302.67529)
		(width 0.14478)
		(layer "In2.Cu")
		(net "M_C_CPU0_SB_DQ<21>")
	)
	(segment
		(start 336.342482 -288.18332)
		(end 336.3341 -288.178494)
		(width 0.0889)
		(layer "In2.Cu")
		(net "M_C_CPU0_SB_DQ<21>")
	)
	(segment
		(start 293.602664 -308.098698)
		(end 293.44112 -308.260242)
		(width 0.14478)
		(layer "In2.Cu")
		(net "M_C_CPU0_SB_DQ<21>")
	)
	(segment
		(start 326.934068 -288.178494)
		(end 326.919336 -288.169858)
		(width 0.0889)
		(layer "In2.Cu")
		(net "M_C_CPU0_SB_DQ<21>")
	)
	(segment
		(start 305.85918 -307.410104)
		(end 305.009042 -308.260242)
		(width 0.14478)
		(layer "In2.Cu")
		(net "M_C_CPU0_SB_DQ<21>")
	)
	(segment
		(start 327.882504 -288.18332)
		(end 327.874122 -288.178494)
		(width 0.0889)
		(layer "In2.Cu")
		(net "M_C_CPU0_SB_DQ<21>")
	)
	(arc
		(start 335.394046 -288.178494)
		(mid 335.11109 -288.102317)
		(end 334.828134 -288.178494)
		(width 0.0889)
		(layer "In2.Cu")
		(net "M_C_CPU0_SB_DQ<21>")
	)
	(arc
		(start 326.271382 -288.248852)
		(mid 326.261881 -288.257762)
		(end 326.252586 -288.266886)
		(width 0.0889)
		(layer "In2.Cu")
		(net "M_C_CPU0_SB_DQ<21>")
	)
	(arc
		(start 340.094062 -288.178494)
		(mid 339.811106 -288.102317)
		(end 339.52815 -288.178494)
		(width 0.0889)
		(layer "In2.Cu")
		(net "M_C_CPU0_SB_DQ<21>")
	)
	(arc
		(start 340.468204 -288.178494)
		(mid 340.285953 -288.228878)
		(end 340.102444 -288.18332)
		(width 0.0889)
		(layer "In2.Cu")
		(net "M_C_CPU0_SB_DQ<21>")
	)
	(arc
		(start 335.768188 -288.178494)
		(mid 335.585937 -288.228878)
		(end 335.402428 -288.18332)
		(width 0.0889)
		(layer "In2.Cu")
		(net "M_C_CPU0_SB_DQ<21>")
	)
	(arc
		(start 331.068172 -288.178494)
		(mid 330.885921 -288.228878)
		(end 330.702412 -288.18332)
		(width 0.0889)
		(layer "In2.Cu")
		(net "M_C_CPU0_SB_DQ<21>")
	)
	(arc
		(start 337.648042 -288.178494)
		(mid 337.461098 -288.228783)
		(end 337.274154 -288.178494)
		(width 0.0889)
		(layer "In2.Cu")
		(net "M_C_CPU0_SB_DQ<21>")
	)
	(arc
		(start 333.879698 -288.18332)
		(mid 333.69619 -288.228845)
		(end 333.513938 -288.178494)
		(width 0.0889)
		(layer "In2.Cu")
		(net "M_C_CPU0_SB_DQ<21>")
	)
	(arc
		(start 338.213954 -288.178494)
		(mid 337.930998 -288.102317)
		(end 337.648042 -288.178494)
		(width 0.0889)
		(layer "In2.Cu")
		(net "M_C_CPU0_SB_DQ<21>")
	)
	(arc
		(start 336.3341 -288.178494)
		(mid 336.051144 -288.102317)
		(end 335.768188 -288.178494)
		(width 0.0889)
		(layer "In2.Cu")
		(net "M_C_CPU0_SB_DQ<21>")
	)
	(arc
		(start 339.519768 -288.18332)
		(mid 339.33626 -288.228845)
		(end 339.154008 -288.178494)
		(width 0.0889)
		(layer "In2.Cu")
		(net "M_C_CPU0_SB_DQ<21>")
	)
	(arc
		(start 341.408258 -288.178494)
		(mid 341.226007 -288.228878)
		(end 341.042498 -288.18332)
		(width 0.0889)
		(layer "In2.Cu")
		(net "M_C_CPU0_SB_DQ<21>")
	)
	(arc
		(start 334.453992 -288.178494)
		(mid 334.171036 -288.102317)
		(end 333.88808 -288.178494)
		(width 0.0889)
		(layer "In2.Cu")
		(net "M_C_CPU0_SB_DQ<21>")
	)
	(arc
		(start 342.91397 -288.178494)
		(mid 342.631014 -288.102317)
		(end 342.348058 -288.178494)
		(width 0.0889)
		(layer "In2.Cu")
		(net "M_C_CPU0_SB_DQ<21>")
	)
	(arc
		(start 327.30821 -288.178494)
		(mid 327.125959 -288.228878)
		(end 326.94245 -288.18332)
		(width 0.0889)
		(layer "In2.Cu")
		(net "M_C_CPU0_SB_DQ<21>")
	)
	(arc
		(start 332.948026 -288.178494)
		(mid 332.761082 -288.228783)
		(end 332.574138 -288.178494)
		(width 0.0889)
		(layer "In2.Cu")
		(net "M_C_CPU0_SB_DQ<21>")
	)
	(arc
		(start 333.513938 -288.178494)
		(mid 333.230982 -288.102317)
		(end 332.948026 -288.178494)
		(width 0.0889)
		(layer "In2.Cu")
		(net "M_C_CPU0_SB_DQ<21>")
	)
	(arc
		(start 326.367648 -288.178494)
		(mid 326.317646 -288.211117)
		(end 326.271382 -288.248852)
		(width 0.0889)
		(layer "In2.Cu")
		(net "M_C_CPU0_SB_DQ<21>")
	)
	(arc
		(start 326.919336 -288.169858)
		(mid 326.642353 -288.102054)
		(end 326.367648 -288.178494)
		(width 0.0889)
		(layer "In2.Cu")
		(net "M_C_CPU0_SB_DQ<21>")
	)
	(arc
		(start 330.69403 -288.178494)
		(mid 330.411074 -288.102317)
		(end 330.128118 -288.178494)
		(width 0.0889)
		(layer "In2.Cu")
		(net "M_C_CPU0_SB_DQ<21>")
	)
	(arc
		(start 337.274154 -288.178494)
		(mid 336.991198 -288.102317)
		(end 336.708242 -288.178494)
		(width 0.0889)
		(layer "In2.Cu")
		(net "M_C_CPU0_SB_DQ<21>")
	)
	(arc
		(start 343.27973 -288.18332)
		(mid 343.096222 -288.228845)
		(end 342.91397 -288.178494)
		(width 0.0889)
		(layer "In2.Cu")
		(net "M_C_CPU0_SB_DQ<21>")
	)
	(arc
		(start 332.008226 -288.178494)
		(mid 331.825975 -288.228878)
		(end 331.642466 -288.18332)
		(width 0.0889)
		(layer "In2.Cu")
		(net "M_C_CPU0_SB_DQ<21>")
	)
	(arc
		(start 331.634084 -288.178494)
		(mid 331.351128 -288.102317)
		(end 331.068172 -288.178494)
		(width 0.0889)
		(layer "In2.Cu")
		(net "M_C_CPU0_SB_DQ<21>")
	)
	(arc
		(start 328.814176 -288.178494)
		(mid 328.53122 -288.102317)
		(end 328.248264 -288.178494)
		(width 0.0889)
		(layer "In2.Cu")
		(net "M_C_CPU0_SB_DQ<21>")
	)
	(arc
		(start 329.188064 -288.178494)
		(mid 329.00112 -288.228783)
		(end 328.814176 -288.178494)
		(width 0.0889)
		(layer "In2.Cu")
		(net "M_C_CPU0_SB_DQ<21>")
	)
	(arc
		(start 330.119736 -288.18332)
		(mid 329.936228 -288.228845)
		(end 329.753976 -288.178494)
		(width 0.0889)
		(layer "In2.Cu")
		(net "M_C_CPU0_SB_DQ<21>")
	)
	(arc
		(start 341.97417 -288.178494)
		(mid 341.691214 -288.102317)
		(end 341.408258 -288.178494)
		(width 0.0889)
		(layer "In2.Cu")
		(net "M_C_CPU0_SB_DQ<21>")
	)
	(arc
		(start 336.708242 -288.178494)
		(mid 336.525991 -288.228878)
		(end 336.342482 -288.18332)
		(width 0.0889)
		(layer "In2.Cu")
		(net "M_C_CPU0_SB_DQ<21>")
	)
	(arc
		(start 327.874122 -288.178494)
		(mid 327.591166 -288.102317)
		(end 327.30821 -288.178494)
		(width 0.0889)
		(layer "In2.Cu")
		(net "M_C_CPU0_SB_DQ<21>")
	)
	(arc
		(start 334.819752 -288.18332)
		(mid 334.636244 -288.228845)
		(end 334.453992 -288.178494)
		(width 0.0889)
		(layer "In2.Cu")
		(net "M_C_CPU0_SB_DQ<21>")
	)
	(arc
		(start 329.753976 -288.178494)
		(mid 329.47102 -288.102317)
		(end 329.188064 -288.178494)
		(width 0.0889)
		(layer "In2.Cu")
		(net "M_C_CPU0_SB_DQ<21>")
	)
	(arc
		(start 332.574138 -288.178494)
		(mid 332.291182 -288.102317)
		(end 332.008226 -288.178494)
		(width 0.0889)
		(layer "In2.Cu")
		(net "M_C_CPU0_SB_DQ<21>")
	)
	(arc
		(start 341.034116 -288.178494)
		(mid 340.75116 -288.102317)
		(end 340.468204 -288.178494)
		(width 0.0889)
		(layer "In2.Cu")
		(net "M_C_CPU0_SB_DQ<21>")
	)
	(arc
		(start 342.348058 -288.178494)
		(mid 342.161114 -288.228783)
		(end 341.97417 -288.178494)
		(width 0.0889)
		(layer "In2.Cu")
		(net "M_C_CPU0_SB_DQ<21>")
	)
	(arc
		(start 343.791286 -288.146998)
		(mid 343.535964 -288.103298)
		(end 343.288112 -288.178494)
		(width 0.0889)
		(layer "In2.Cu")
		(net "M_C_CPU0_SB_DQ<21>")
	)
	(arc
		(start 338.579714 -288.18332)
		(mid 338.396206 -288.228845)
		(end 338.213954 -288.178494)
		(width 0.0889)
		(layer "In2.Cu")
		(net "M_C_CPU0_SB_DQ<21>")
	)
	(arc
		(start 328.248264 -288.178494)
		(mid 328.066013 -288.228878)
		(end 327.882504 -288.18332)
		(width 0.0889)
		(layer "In2.Cu")
		(net "M_C_CPU0_SB_DQ<21>")
	)
	(arc
		(start 339.154008 -288.178494)
		(mid 338.871052 -288.102317)
		(end 338.588096 -288.178494)
		(width 0.0889)
		(layer "In2.Cu")
		(net "M_C_CPU0_SB_DQ<21>")
	)
	(segment
		(start 343.097866 -286.780224)
		(end 342.631014 -287.045908)
		(width 0.10668)
		(layer "F.Cu")
		(net "M_C_CPU0_SB_DQ<20>")
	)
	(segment
		(start 323.926454 -288.974276)
		(end 320.268854 -292.631876)
		(width 0.14478)
		(layer "In2.Cu")
		(net "M_C_CPU0_SB_DQ<20>")
	)
	(segment
		(start 336.238088 -287.368488)
		(end 336.229706 -287.373314)
		(width 0.0889)
		(layer "In2.Cu")
		(net "M_C_CPU0_SB_DQ<20>")
	)
	(segment
		(start 305.30927 -306.56022)
		(end 301.62627 -306.56022)
		(width 0.14478)
		(layer "In2.Cu")
		(net "M_C_CPU0_SB_DQ<20>")
	)
	(segment
		(start 338.69249 -287.373314)
		(end 338.684108 -287.368488)
		(width 0.0889)
		(layer "In2.Cu")
		(net "M_C_CPU0_SB_DQ<20>")
	)
	(segment
		(start 311.580022 -305.500278)
		(end 311.580022 -305.730402)
		(width 0.14478)
		(layer "In2.Cu")
		(net "M_C_CPU0_SB_DQ<20>")
	)
	(segment
		(start 313.940698 -303.369726)
		(end 313.777376 -303.533048)
		(width 0.14478)
		(layer "In2.Cu")
		(net "M_C_CPU0_SB_DQ<20>")
	)
	(segment
		(start 329.292458 -287.373314)
		(end 329.284076 -287.368488)
		(width 0.0889)
		(layer "In2.Cu")
		(net "M_C_CPU0_SB_DQ<20>")
	)
	(segment
		(start 342.47709 -287.311338)
		(end 342.381078 -287.336738)
		(width 0.0889)
		(layer "In2.Cu")
		(net "M_C_CPU0_SB_DQ<20>")
	)
	(segment
		(start 333.992474 -287.373314)
		(end 333.984092 -287.368488)
		(width 0.0889)
		(layer "In2.Cu")
		(net "M_C_CPU0_SB_DQ<20>")
	)
	(segment
		(start 328.718164 -287.368488)
		(end 328.709782 -287.373314)
		(width 0.0889)
		(layer "In2.Cu")
		(net "M_C_CPU0_SB_DQ<20>")
	)
	(segment
		(start 341.878158 -287.368488)
		(end 341.869776 -287.373314)
		(width 0.0889)
		(layer "In2.Cu")
		(net "M_C_CPU0_SB_DQ<20>")
	)
	(segment
		(start 320.268854 -295.84777)
		(end 313.573922 -302.542702)
		(width 0.14478)
		(layer "In2.Cu")
		(net "M_C_CPU0_SB_DQ<20>")
	)
	(segment
		(start 313.180476 -303.166272)
		(end 312.950352 -303.166272)
		(width 0.14478)
		(layer "In2.Cu")
		(net "M_C_CPU0_SB_DQ<20>")
	)
	(segment
		(start 325.247254 -288.10331)
		(end 324.79742 -288.10331)
		(width 0.0889)
		(layer "In2.Cu")
		(net "M_C_CPU0_SB_DQ<20>")
	)
	(segment
		(start 311.606692 -304.740056)
		(end 311.376568 -304.740056)
		(width 0.14478)
		(layer "In2.Cu")
		(net "M_C_CPU0_SB_DQ<20>")
	)
	(segment
		(start 311.373774 -305.93665)
		(end 309.150258 -305.93665)
		(width 0.14478)
		(layer "In2.Cu")
		(net "M_C_CPU0_SB_DQ<20>")
	)
	(segment
		(start 308.92369 -305.710082)
		(end 306.159408 -305.710082)
		(width 0.14478)
		(layer "In2.Cu")
		(net "M_C_CPU0_SB_DQ<20>")
	)
	(segment
		(start 312.76036 -304.31994)
		(end 312.393584 -303.953164)
		(width 0.14478)
		(layer "In2.Cu")
		(net "M_C_CPU0_SB_DQ<20>")
	)
	(segment
		(start 297.535346 -306.569872)
		(end 292.714934 -306.569872)
		(width 0.14478)
		(layer "In2.Cu")
		(net "M_C_CPU0_SB_DQ<20>")
	)
	(segment
		(start 298.385484 -305.719734)
		(end 297.535346 -306.569872)
		(width 0.14478)
		(layer "In2.Cu")
		(net "M_C_CPU0_SB_DQ<20>")
	)
	(segment
		(start 331.538072 -287.368488)
		(end 331.52969 -287.373314)
		(width 0.0889)
		(layer "In2.Cu")
		(net "M_C_CPU0_SB_DQ<20>")
	)
	(segment
		(start 300.785784 -305.719734)
		(end 298.385484 -305.719734)
		(width 0.14478)
		(layer "In2.Cu")
		(net "M_C_CPU0_SB_DQ<20>")
	)
	(segment
		(start 292.714934 -306.569872)
		(end 292.280086 -306.135024)
		(width 0.14478)
		(layer "In2.Cu")
		(net "M_C_CPU0_SB_DQ<20>")
	)
	(segment
		(start 333.05242 -287.373314)
		(end 333.044038 -287.368488)
		(width 0.0889)
		(layer "In2.Cu")
		(net "M_C_CPU0_SB_DQ<20>")
	)
	(segment
		(start 312.000138 -304.34661)
		(end 312.366914 -304.713386)
		(width 0.14478)
		(layer "In2.Cu")
		(net "M_C_CPU0_SB_DQ<20>")
	)
	(segment
		(start 311.973468 -305.106832)
		(end 311.606692 -304.740056)
		(width 0.14478)
		(layer "In2.Cu")
		(net "M_C_CPU0_SB_DQ<20>")
	)
	(segment
		(start 312.203592 -305.106832)
		(end 311.973468 -305.106832)
		(width 0.14478)
		(layer "In2.Cu")
		(net "M_C_CPU0_SB_DQ<20>")
	)
	(segment
		(start 340.938104 -287.368488)
		(end 340.929722 -287.373314)
		(width 0.0889)
		(layer "In2.Cu")
		(net "M_C_CPU0_SB_DQ<20>")
	)
	(segment
		(start 313.153806 -304.156618)
		(end 312.990484 -304.31994)
		(width 0.14478)
		(layer "In2.Cu")
		(net "M_C_CPU0_SB_DQ<20>")
	)
	(segment
		(start 313.777376 -303.533048)
		(end 313.547252 -303.533048)
		(width 0.14478)
		(layer "In2.Cu")
		(net "M_C_CPU0_SB_DQ<20>")
	)
	(segment
		(start 327.779888 -287.368488)
		(end 327.761092 -287.379156)
		(width 0.0889)
		(layer "In2.Cu")
		(net "M_C_CPU0_SB_DQ<20>")
	)
	(segment
		(start 332.478126 -287.368488)
		(end 332.469744 -287.373314)
		(width 0.0889)
		(layer "In2.Cu")
		(net "M_C_CPU0_SB_DQ<20>")
	)
	(segment
		(start 311.213246 -304.903378)
		(end 311.213246 -305.133502)
		(width 0.14478)
		(layer "In2.Cu")
		(net "M_C_CPU0_SB_DQ<20>")
	)
	(segment
		(start 313.547252 -303.533048)
		(end 313.180476 -303.166272)
		(width 0.14478)
		(layer "In2.Cu")
		(net "M_C_CPU0_SB_DQ<20>")
	)
	(segment
		(start 313.573922 -302.772826)
		(end 313.940698 -303.139602)
		(width 0.14478)
		(layer "In2.Cu")
		(net "M_C_CPU0_SB_DQ<20>")
	)
	(segment
		(start 312.78703 -303.329594)
		(end 312.78703 -303.559718)
		(width 0.14478)
		(layer "In2.Cu")
		(net "M_C_CPU0_SB_DQ<20>")
	)
	(segment
		(start 309.150258 -305.93665)
		(end 308.92369 -305.710082)
		(width 0.14478)
		(layer "In2.Cu")
		(net "M_C_CPU0_SB_DQ<20>")
	)
	(segment
		(start 311.213246 -305.133502)
		(end 311.580022 -305.500278)
		(width 0.14478)
		(layer "In2.Cu")
		(net "M_C_CPU0_SB_DQ<20>")
	)
	(segment
		(start 337.752436 -287.373314)
		(end 337.744054 -287.368488)
		(width 0.0889)
		(layer "In2.Cu")
		(net "M_C_CPU0_SB_DQ<20>")
	)
	(segment
		(start 301.62627 -306.56022)
		(end 300.785784 -305.719734)
		(width 0.14478)
		(layer "In2.Cu")
		(net "M_C_CPU0_SB_DQ<20>")
	)
	(segment
		(start 306.159408 -305.710082)
		(end 305.30927 -306.56022)
		(width 0.14478)
		(layer "In2.Cu")
		(net "M_C_CPU0_SB_DQ<20>")
	)
	(segment
		(start 325.727314 -287.62325)
		(end 325.247254 -288.10331)
		(width 0.0889)
		(layer "In2.Cu")
		(net "M_C_CPU0_SB_DQ<20>")
	)
	(segment
		(start 313.573922 -302.542702)
		(end 313.573922 -302.772826)
		(width 0.14478)
		(layer "In2.Cu")
		(net "M_C_CPU0_SB_DQ<20>")
	)
	(segment
		(start 312.366914 -304.713386)
		(end 312.366914 -304.94351)
		(width 0.14478)
		(layer "In2.Cu")
		(net "M_C_CPU0_SB_DQ<20>")
	)
	(segment
		(start 313.940698 -303.139602)
		(end 313.940698 -303.369726)
		(width 0.14478)
		(layer "In2.Cu")
		(net "M_C_CPU0_SB_DQ<20>")
	)
	(segment
		(start 327.807574 -287.352486)
		(end 327.779888 -287.368488)
		(width 0.0889)
		(layer "In2.Cu")
		(net "M_C_CPU0_SB_DQ<20>")
	)
	(segment
		(start 312.950352 -303.166272)
		(end 312.78703 -303.329594)
		(width 0.14478)
		(layer "In2.Cu")
		(net "M_C_CPU0_SB_DQ<20>")
	)
	(segment
		(start 320.268854 -292.631876)
		(end 320.268854 -295.84777)
		(width 0.14478)
		(layer "In2.Cu")
		(net "M_C_CPU0_SB_DQ<20>")
	)
	(segment
		(start 312.000138 -304.116486)
		(end 312.000138 -304.34661)
		(width 0.14478)
		(layer "In2.Cu")
		(net "M_C_CPU0_SB_DQ<20>")
	)
	(segment
		(start 311.580022 -305.730402)
		(end 311.373774 -305.93665)
		(width 0.14478)
		(layer "In2.Cu")
		(net "M_C_CPU0_SB_DQ<20>")
	)
	(segment
		(start 311.376568 -304.740056)
		(end 311.213246 -304.903378)
		(width 0.14478)
		(layer "In2.Cu")
		(net "M_C_CPU0_SB_DQ<20>")
	)
	(segment
		(start 337.178142 -287.368488)
		(end 337.16976 -287.373314)
		(width 0.0889)
		(layer "In2.Cu")
		(net "M_C_CPU0_SB_DQ<20>")
	)
	(segment
		(start 312.366914 -304.94351)
		(end 312.203592 -305.106832)
		(width 0.14478)
		(layer "In2.Cu")
		(net "M_C_CPU0_SB_DQ<20>")
	)
	(segment
		(start 342.631014 -287.045908)
		(end 342.47709 -287.311338)
		(width 0.0889)
		(layer "In2.Cu")
		(net "M_C_CPU0_SB_DQ<20>")
	)
	(segment
		(start 312.78703 -303.559718)
		(end 313.153806 -303.926494)
		(width 0.14478)
		(layer "In2.Cu")
		(net "M_C_CPU0_SB_DQ<20>")
	)
	(segment
		(start 326.676258 -287.412938)
		(end 326.23506 -287.412938)
		(width 0.0889)
		(layer "In2.Cu")
		(net "M_C_CPU0_SB_DQ<20>")
	)
	(segment
		(start 313.153806 -303.926494)
		(end 313.153806 -304.156618)
		(width 0.14478)
		(layer "In2.Cu")
		(net "M_C_CPU0_SB_DQ<20>")
	)
	(segment
		(start 312.990484 -304.31994)
		(end 312.76036 -304.31994)
		(width 0.14478)
		(layer "In2.Cu")
		(net "M_C_CPU0_SB_DQ<20>")
	)
	(segment
		(start 312.16346 -303.953164)
		(end 312.000138 -304.116486)
		(width 0.14478)
		(layer "In2.Cu")
		(net "M_C_CPU0_SB_DQ<20>")
	)
	(segment
		(start 327.40727 -287.368488)
		(end 327.383394 -287.354518)
		(width 0.0889)
		(layer "In2.Cu")
		(net "M_C_CPU0_SB_DQ<20>")
	)
	(segment
		(start 312.393584 -303.953164)
		(end 312.16346 -303.953164)
		(width 0.14478)
		(layer "In2.Cu")
		(net "M_C_CPU0_SB_DQ<20>")
	)
	(segment
		(start 324.79742 -288.10331)
		(end 323.926454 -288.974276)
		(width 0.0889)
		(layer "In2.Cu")
		(net "M_C_CPU0_SB_DQ<20>")
	)
	(arc
		(start 326.23506 -287.412938)
		(mid 325.960271 -287.467597)
		(end 325.727314 -287.62325)
		(width 0.0889)
		(layer "In2.Cu")
		(net "M_C_CPU0_SB_DQ<20>")
	)
	(arc
		(start 336.229706 -287.373314)
		(mid 336.046198 -287.418808)
		(end 335.863946 -287.368488)
		(width 0.0889)
		(layer "In2.Cu")
		(net "M_C_CPU0_SB_DQ<20>")
	)
	(arc
		(start 342.381078 -287.336738)
		(mid 342.12587 -287.293281)
		(end 341.878158 -287.368488)
		(width 0.0889)
		(layer "In2.Cu")
		(net "M_C_CPU0_SB_DQ<20>")
	)
	(arc
		(start 333.044038 -287.368488)
		(mid 332.761082 -287.292345)
		(end 332.478126 -287.368488)
		(width 0.0889)
		(layer "In2.Cu")
		(net "M_C_CPU0_SB_DQ<20>")
	)
	(arc
		(start 329.658218 -287.368488)
		(mid 329.475967 -287.418838)
		(end 329.292458 -287.373314)
		(width 0.0889)
		(layer "In2.Cu")
		(net "M_C_CPU0_SB_DQ<20>")
	)
	(arc
		(start 333.984092 -287.368488)
		(mid 333.701136 -287.292345)
		(end 333.41818 -287.368488)
		(width 0.0889)
		(layer "In2.Cu")
		(net "M_C_CPU0_SB_DQ<20>")
	)
	(arc
		(start 340.929722 -287.373314)
		(mid 340.746214 -287.418808)
		(end 340.563962 -287.368488)
		(width 0.0889)
		(layer "In2.Cu")
		(net "M_C_CPU0_SB_DQ<20>")
	)
	(arc
		(start 336.804 -287.368488)
		(mid 336.521044 -287.292345)
		(end 336.238088 -287.368488)
		(width 0.0889)
		(layer "In2.Cu")
		(net "M_C_CPU0_SB_DQ<20>")
	)
	(arc
		(start 334.924146 -287.368488)
		(mid 334.64119 -287.292345)
		(end 334.358234 -287.368488)
		(width 0.0889)
		(layer "In2.Cu")
		(net "M_C_CPU0_SB_DQ<20>")
	)
	(arc
		(start 338.118196 -287.368488)
		(mid 337.935945 -287.418838)
		(end 337.752436 -287.373314)
		(width 0.0889)
		(layer "In2.Cu")
		(net "M_C_CPU0_SB_DQ<20>")
	)
	(arc
		(start 332.469744 -287.373314)
		(mid 332.286236 -287.418808)
		(end 332.103984 -287.368488)
		(width 0.0889)
		(layer "In2.Cu")
		(net "M_C_CPU0_SB_DQ<20>")
	)
	(arc
		(start 337.16976 -287.373314)
		(mid 336.986252 -287.418808)
		(end 336.804 -287.368488)
		(width 0.0889)
		(layer "In2.Cu")
		(net "M_C_CPU0_SB_DQ<20>")
	)
	(arc
		(start 339.624162 -287.368488)
		(mid 339.341206 -287.292345)
		(end 339.05825 -287.368488)
		(width 0.0889)
		(layer "In2.Cu")
		(net "M_C_CPU0_SB_DQ<20>")
	)
	(arc
		(start 331.52969 -287.373314)
		(mid 331.346182 -287.418808)
		(end 331.16393 -287.368488)
		(width 0.0889)
		(layer "In2.Cu")
		(net "M_C_CPU0_SB_DQ<20>")
	)
	(arc
		(start 341.869776 -287.373314)
		(mid 341.686268 -287.418808)
		(end 341.504016 -287.368488)
		(width 0.0889)
		(layer "In2.Cu")
		(net "M_C_CPU0_SB_DQ<20>")
	)
	(arc
		(start 331.16393 -287.368488)
		(mid 330.880974 -287.292345)
		(end 330.598018 -287.368488)
		(width 0.0889)
		(layer "In2.Cu")
		(net "M_C_CPU0_SB_DQ<20>")
	)
	(arc
		(start 338.684108 -287.368488)
		(mid 338.401152 -287.292345)
		(end 338.118196 -287.368488)
		(width 0.0889)
		(layer "In2.Cu")
		(net "M_C_CPU0_SB_DQ<20>")
	)
	(arc
		(start 339.05825 -287.368488)
		(mid 338.875999 -287.418838)
		(end 338.69249 -287.373314)
		(width 0.0889)
		(layer "In2.Cu")
		(net "M_C_CPU0_SB_DQ<20>")
	)
	(arc
		(start 328.709782 -287.373314)
		(mid 328.526274 -287.418808)
		(end 328.344022 -287.368488)
		(width 0.0889)
		(layer "In2.Cu")
		(net "M_C_CPU0_SB_DQ<20>")
	)
	(arc
		(start 326.83958 -287.368742)
		(mid 326.760861 -287.401721)
		(end 326.676258 -287.412938)
		(width 0.0889)
		(layer "In2.Cu")
		(net "M_C_CPU0_SB_DQ<20>")
	)
	(arc
		(start 333.41818 -287.368488)
		(mid 333.235929 -287.418838)
		(end 333.05242 -287.373314)
		(width 0.0889)
		(layer "In2.Cu")
		(net "M_C_CPU0_SB_DQ<20>")
	)
	(arc
		(start 334.358234 -287.368488)
		(mid 334.175983 -287.418838)
		(end 333.992474 -287.373314)
		(width 0.0889)
		(layer "In2.Cu")
		(net "M_C_CPU0_SB_DQ<20>")
	)
	(arc
		(start 339.99805 -287.368488)
		(mid 339.811106 -287.418743)
		(end 339.624162 -287.368488)
		(width 0.0889)
		(layer "In2.Cu")
		(net "M_C_CPU0_SB_DQ<20>")
	)
	(arc
		(start 337.744054 -287.368488)
		(mid 337.461098 -287.292345)
		(end 337.178142 -287.368488)
		(width 0.0889)
		(layer "In2.Cu")
		(net "M_C_CPU0_SB_DQ<20>")
	)
	(arc
		(start 335.298034 -287.368488)
		(mid 335.11109 -287.418743)
		(end 334.924146 -287.368488)
		(width 0.0889)
		(layer "In2.Cu")
		(net "M_C_CPU0_SB_DQ<20>")
	)
	(arc
		(start 340.563962 -287.368488)
		(mid 340.281006 -287.292345)
		(end 339.99805 -287.368488)
		(width 0.0889)
		(layer "In2.Cu")
		(net "M_C_CPU0_SB_DQ<20>")
	)
	(arc
		(start 327.383394 -287.354518)
		(mid 327.109646 -287.291757)
		(end 326.83958 -287.368742)
		(width 0.0889)
		(layer "In2.Cu")
		(net "M_C_CPU0_SB_DQ<20>")
	)
	(arc
		(start 330.22413 -287.368488)
		(mid 329.941174 -287.292345)
		(end 329.658218 -287.368488)
		(width 0.0889)
		(layer "In2.Cu")
		(net "M_C_CPU0_SB_DQ<20>")
	)
	(arc
		(start 335.863946 -287.368488)
		(mid 335.58099 -287.292345)
		(end 335.298034 -287.368488)
		(width 0.0889)
		(layer "In2.Cu")
		(net "M_C_CPU0_SB_DQ<20>")
	)
	(arc
		(start 332.103984 -287.368488)
		(mid 331.821028 -287.292345)
		(end 331.538072 -287.368488)
		(width 0.0889)
		(layer "In2.Cu")
		(net "M_C_CPU0_SB_DQ<20>")
	)
	(arc
		(start 341.504016 -287.368488)
		(mid 341.22106 -287.292345)
		(end 340.938104 -287.368488)
		(width 0.0889)
		(layer "In2.Cu")
		(net "M_C_CPU0_SB_DQ<20>")
	)
	(arc
		(start 327.761092 -287.379156)
		(mid 327.582819 -287.418552)
		(end 327.40727 -287.368488)
		(width 0.0889)
		(layer "In2.Cu")
		(net "M_C_CPU0_SB_DQ<20>")
	)
	(arc
		(start 329.284076 -287.368488)
		(mid 329.00112 -287.292345)
		(end 328.718164 -287.368488)
		(width 0.0889)
		(layer "In2.Cu")
		(net "M_C_CPU0_SB_DQ<20>")
	)
	(arc
		(start 330.598018 -287.368488)
		(mid 330.411074 -287.418743)
		(end 330.22413 -287.368488)
		(width 0.0889)
		(layer "In2.Cu")
		(net "M_C_CPU0_SB_DQ<20>")
	)
	(arc
		(start 328.344022 -287.368488)
		(mid 328.07783 -287.292595)
		(end 327.807574 -287.352486)
		(width 0.0889)
		(layer "In2.Cu")
		(net "M_C_CPU0_SB_DQ<20>")
	)
	(segment
		(start 344.508074 -274.630134)
		(end 344.041222 -274.896072)
		(width 0.10668)
		(layer "F.Cu")
		(net "M_C_CPU0_SB_DQ<1>")
	)
	(segment
		(start 328.248264 -275.218652)
		(end 328.239882 -275.223478)
		(width 0.0889)
		(layer "In2.Cu")
		(net "M_C_CPU0_SB_DQ<1>")
	)
	(segment
		(start 304.747168 -283.61005)
		(end 304.564288 -283.61005)
		(width 0.14478)
		(layer "In2.Cu")
		(net "M_C_CPU0_SB_DQ<1>")
	)
	(segment
		(start 294.010588 -283.805376)
		(end 294.010588 -283.394404)
		(width 0.14478)
		(layer "In2.Cu")
		(net "M_C_CPU0_SB_DQ<1>")
	)
	(segment
		(start 302.003714 -283.61005)
		(end 301.153576 -282.759912)
		(width 0.14478)
		(layer "In2.Cu")
		(net "M_C_CPU0_SB_DQ<1>")
	)
	(segment
		(start 312.621676 -278.646636)
		(end 312.621676 -278.877268)
		(width 0.14478)
		(layer "In2.Cu")
		(net "M_C_CPU0_SB_DQ<1>")
	)
	(segment
		(start 304.007774 -283.30779)
		(end 303.705514 -283.61005)
		(width 0.14478)
		(layer "In2.Cu")
		(net "M_C_CPU0_SB_DQ<1>")
	)
	(segment
		(start 326.651112 -275.136102)
		(end 326.321166 -275.136102)
		(width 0.0889)
		(layer "In2.Cu")
		(net "M_C_CPU0_SB_DQ<1>")
	)
	(segment
		(start 297.857164 -282.759912)
		(end 297.007026 -283.61005)
		(width 0.14478)
		(layer "In2.Cu")
		(net "M_C_CPU0_SB_DQ<1>")
	)
	(segment
		(start 336.342482 -275.223478)
		(end 336.3341 -275.218652)
		(width 0.0889)
		(layer "In2.Cu")
		(net "M_C_CPU0_SB_DQ<1>")
	)
	(segment
		(start 298.880022 -282.50515)
		(end 298.57827 -282.50515)
		(width 0.14478)
		(layer "In2.Cu")
		(net "M_C_CPU0_SB_DQ<1>")
	)
	(segment
		(start 312.621676 -278.877268)
		(end 312.89625 -279.151842)
		(width 0.14478)
		(layer "In2.Cu")
		(net "M_C_CPU0_SB_DQ<1>")
	)
	(segment
		(start 318.20612 -274.1295)
		(end 313.844432 -278.491188)
		(width 0.14478)
		(layer "In2.Cu")
		(net "M_C_CPU0_SB_DQ<1>")
	)
	(segment
		(start 294.404034 -283.96819)
		(end 294.173402 -283.96819)
		(width 0.14478)
		(layer "In2.Cu")
		(net "M_C_CPU0_SB_DQ<1>")
	)
	(segment
		(start 324.354444 -274.1295)
		(end 323.893434 -274.1295)
		(width 0.0889)
		(layer "In2.Cu")
		(net "M_C_CPU0_SB_DQ<1>")
	)
	(segment
		(start 327.321926 -275.210016)
		(end 327.307194 -275.218652)
		(width 0.0889)
		(layer "In2.Cu")
		(net "M_C_CPU0_SB_DQ<1>")
	)
	(segment
		(start 311.440576 -280.058368)
		(end 311.188608 -280.058368)
		(width 0.14478)
		(layer "In2.Cu")
		(net "M_C_CPU0_SB_DQ<1>")
	)
	(segment
		(start 295.338754 -283.61005)
		(end 294.960294 -283.23159)
		(width 0.14478)
		(layer "In2.Cu")
		(net "M_C_CPU0_SB_DQ<1>")
	)
	(segment
		(start 340.102444 -275.223478)
		(end 340.094062 -275.218652)
		(width 0.0889)
		(layer "In2.Cu")
		(net "M_C_CPU0_SB_DQ<1>")
	)
	(segment
		(start 294.010588 -283.394404)
		(end 293.847774 -283.23159)
		(width 0.14478)
		(layer "In2.Cu")
		(net "M_C_CPU0_SB_DQ<1>")
	)
	(segment
		(start 298.57827 -282.50515)
		(end 298.323508 -282.759912)
		(width 0.14478)
		(layer "In2.Cu")
		(net "M_C_CPU0_SB_DQ<1>")
	)
	(segment
		(start 330.128118 -275.218652)
		(end 330.119736 -275.223478)
		(width 0.0889)
		(layer "In2.Cu")
		(net "M_C_CPU0_SB_DQ<1>")
	)
	(segment
		(start 294.173402 -283.96819)
		(end 294.010588 -283.805376)
		(width 0.14478)
		(layer "In2.Cu")
		(net "M_C_CPU0_SB_DQ<1>")
	)
	(segment
		(start 293.847774 -283.23159)
		(end 293.617142 -283.23159)
		(width 0.14478)
		(layer "In2.Cu")
		(net "M_C_CPU0_SB_DQ<1>")
	)
	(segment
		(start 312.733182 -279.545542)
		(end 312.50255 -279.545542)
		(width 0.14478)
		(layer "In2.Cu")
		(net "M_C_CPU0_SB_DQ<1>")
	)
	(segment
		(start 298.323508 -282.759912)
		(end 297.857164 -282.759912)
		(width 0.14478)
		(layer "In2.Cu")
		(net "M_C_CPU0_SB_DQ<1>")
	)
	(segment
		(start 306.303172 -282.45181)
		(end 305.99507 -282.759912)
		(width 0.14478)
		(layer "In2.Cu")
		(net "M_C_CPU0_SB_DQ<1>")
	)
	(segment
		(start 343.288112 -275.218652)
		(end 343.27973 -275.223478)
		(width 0.0889)
		(layer "In2.Cu")
		(net "M_C_CPU0_SB_DQ<1>")
	)
	(segment
		(start 311.71515 -280.332942)
		(end 311.440576 -280.058368)
		(width 0.14478)
		(layer "In2.Cu")
		(net "M_C_CPU0_SB_DQ<1>")
	)
	(segment
		(start 311.834276 -279.434036)
		(end 311.834276 -279.664668)
		(width 0.14478)
		(layer "In2.Cu")
		(net "M_C_CPU0_SB_DQ<1>")
	)
	(segment
		(start 331.642466 -275.223478)
		(end 331.634084 -275.218652)
		(width 0.0889)
		(layer "In2.Cu")
		(net "M_C_CPU0_SB_DQ<1>")
	)
	(segment
		(start 326.947276 -275.226272)
		(end 326.910954 -275.205444)
		(width 0.0889)
		(layer "In2.Cu")
		(net "M_C_CPU0_SB_DQ<1>")
	)
	(segment
		(start 304.564288 -283.61005)
		(end 304.262028 -283.30779)
		(width 0.14478)
		(layer "In2.Cu")
		(net "M_C_CPU0_SB_DQ<1>")
	)
	(segment
		(start 311.945782 -280.332942)
		(end 311.71515 -280.332942)
		(width 0.14478)
		(layer "In2.Cu")
		(net "M_C_CPU0_SB_DQ<1>")
	)
	(segment
		(start 294.960294 -283.23159)
		(end 294.729662 -283.23159)
		(width 0.14478)
		(layer "In2.Cu")
		(net "M_C_CPU0_SB_DQ<1>")
	)
	(segment
		(start 304.262028 -283.30779)
		(end 304.007774 -283.30779)
		(width 0.14478)
		(layer "In2.Cu")
		(net "M_C_CPU0_SB_DQ<1>")
	)
	(segment
		(start 312.777124 -278.491188)
		(end 312.621676 -278.646636)
		(width 0.14478)
		(layer "In2.Cu")
		(net "M_C_CPU0_SB_DQ<1>")
	)
	(segment
		(start 326.321166 -275.136102)
		(end 325.442834 -274.25777)
		(width 0.0889)
		(layer "In2.Cu")
		(net "M_C_CPU0_SB_DQ<1>")
	)
	(segment
		(start 311.997344 -279.270968)
		(end 311.834276 -279.434036)
		(width 0.14478)
		(layer "In2.Cu")
		(net "M_C_CPU0_SB_DQ<1>")
	)
	(segment
		(start 293.267638 -283.581094)
		(end 292.676072 -283.581094)
		(width 0.14478)
		(layer "In2.Cu")
		(net "M_C_CPU0_SB_DQ<1>")
	)
	(segment
		(start 343.887044 -275.161502)
		(end 343.790778 -275.186902)
		(width 0.0889)
		(layer "In2.Cu")
		(net "M_C_CPU0_SB_DQ<1>")
	)
	(segment
		(start 312.89625 -279.151842)
		(end 312.89625 -279.382474)
		(width 0.14478)
		(layer "In2.Cu")
		(net "M_C_CPU0_SB_DQ<1>")
	)
	(segment
		(start 306.551584 -282.45181)
		(end 306.303172 -282.45181)
		(width 0.14478)
		(layer "In2.Cu")
		(net "M_C_CPU0_SB_DQ<1>")
	)
	(segment
		(start 338.588096 -275.218652)
		(end 338.579714 -275.223478)
		(width 0.0889)
		(layer "In2.Cu")
		(net "M_C_CPU0_SB_DQ<1>")
	)
	(segment
		(start 311.834276 -279.664668)
		(end 312.10885 -279.939242)
		(width 0.14478)
		(layer "In2.Cu")
		(net "M_C_CPU0_SB_DQ<1>")
	)
	(segment
		(start 323.893434 -274.1295)
		(end 318.20612 -274.1295)
		(width 0.14478)
		(layer "In2.Cu")
		(net "M_C_CPU0_SB_DQ<1>")
	)
	(segment
		(start 311.188608 -280.058368)
		(end 308.487064 -282.759912)
		(width 0.14478)
		(layer "In2.Cu")
		(net "M_C_CPU0_SB_DQ<1>")
	)
	(segment
		(start 335.402428 -275.223478)
		(end 335.394046 -275.218652)
		(width 0.0889)
		(layer "In2.Cu")
		(net "M_C_CPU0_SB_DQ<1>")
	)
	(segment
		(start 305.597306 -282.759912)
		(end 304.747168 -283.61005)
		(width 0.14478)
		(layer "In2.Cu")
		(net "M_C_CPU0_SB_DQ<1>")
	)
	(segment
		(start 293.617142 -283.23159)
		(end 293.267638 -283.581094)
		(width 0.14478)
		(layer "In2.Cu")
		(net "M_C_CPU0_SB_DQ<1>")
	)
	(segment
		(start 313.844432 -278.491188)
		(end 312.777124 -278.491188)
		(width 0.14478)
		(layer "In2.Cu")
		(net "M_C_CPU0_SB_DQ<1>")
	)
	(segment
		(start 294.729662 -283.23159)
		(end 294.566848 -283.394404)
		(width 0.14478)
		(layer "In2.Cu")
		(net "M_C_CPU0_SB_DQ<1>")
	)
	(segment
		(start 303.705514 -283.61005)
		(end 302.003714 -283.61005)
		(width 0.14478)
		(layer "In2.Cu")
		(net "M_C_CPU0_SB_DQ<1>")
	)
	(segment
		(start 344.041222 -274.896072)
		(end 343.887044 -275.161502)
		(width 0.0889)
		(layer "In2.Cu")
		(net "M_C_CPU0_SB_DQ<1>")
	)
	(segment
		(start 312.50255 -279.545542)
		(end 312.227976 -279.270968)
		(width 0.14478)
		(layer "In2.Cu")
		(net "M_C_CPU0_SB_DQ<1>")
	)
	(segment
		(start 325.442834 -274.25777)
		(end 324.482714 -274.25777)
		(width 0.0889)
		(layer "In2.Cu")
		(net "M_C_CPU0_SB_DQ<1>")
	)
	(segment
		(start 341.042498 -275.223478)
		(end 341.034116 -275.218652)
		(width 0.0889)
		(layer "In2.Cu")
		(net "M_C_CPU0_SB_DQ<1>")
	)
	(segment
		(start 333.88808 -275.218652)
		(end 333.879698 -275.223478)
		(width 0.0889)
		(layer "In2.Cu")
		(net "M_C_CPU0_SB_DQ<1>")
	)
	(segment
		(start 294.566848 -283.394404)
		(end 294.566848 -283.805376)
		(width 0.14478)
		(layer "In2.Cu")
		(net "M_C_CPU0_SB_DQ<1>")
	)
	(segment
		(start 297.007026 -283.61005)
		(end 295.338754 -283.61005)
		(width 0.14478)
		(layer "In2.Cu")
		(net "M_C_CPU0_SB_DQ<1>")
	)
	(segment
		(start 312.10885 -279.939242)
		(end 312.10885 -280.169874)
		(width 0.14478)
		(layer "In2.Cu")
		(net "M_C_CPU0_SB_DQ<1>")
	)
	(segment
		(start 312.10885 -280.169874)
		(end 311.945782 -280.332942)
		(width 0.14478)
		(layer "In2.Cu")
		(net "M_C_CPU0_SB_DQ<1>")
	)
	(segment
		(start 312.89625 -279.382474)
		(end 312.733182 -279.545542)
		(width 0.14478)
		(layer "In2.Cu")
		(net "M_C_CPU0_SB_DQ<1>")
	)
	(segment
		(start 324.482714 -274.25777)
		(end 324.354444 -274.1295)
		(width 0.0889)
		(layer "In2.Cu")
		(net "M_C_CPU0_SB_DQ<1>")
	)
	(segment
		(start 312.227976 -279.270968)
		(end 311.997344 -279.270968)
		(width 0.14478)
		(layer "In2.Cu")
		(net "M_C_CPU0_SB_DQ<1>")
	)
	(segment
		(start 294.566848 -283.805376)
		(end 294.404034 -283.96819)
		(width 0.14478)
		(layer "In2.Cu")
		(net "M_C_CPU0_SB_DQ<1>")
	)
	(segment
		(start 334.828134 -275.218652)
		(end 334.819752 -275.223478)
		(width 0.0889)
		(layer "In2.Cu")
		(net "M_C_CPU0_SB_DQ<1>")
	)
	(segment
		(start 308.487064 -282.759912)
		(end 306.859686 -282.759912)
		(width 0.14478)
		(layer "In2.Cu")
		(net "M_C_CPU0_SB_DQ<1>")
	)
	(segment
		(start 292.676072 -283.581094)
		(end 292.280086 -283.185108)
		(width 0.14478)
		(layer "In2.Cu")
		(net "M_C_CPU0_SB_DQ<1>")
	)
	(segment
		(start 305.99507 -282.759912)
		(end 305.597306 -282.759912)
		(width 0.14478)
		(layer "In2.Cu")
		(net "M_C_CPU0_SB_DQ<1>")
	)
	(segment
		(start 301.153576 -282.759912)
		(end 299.134784 -282.759912)
		(width 0.14478)
		(layer "In2.Cu")
		(net "M_C_CPU0_SB_DQ<1>")
	)
	(segment
		(start 299.134784 -282.759912)
		(end 298.880022 -282.50515)
		(width 0.14478)
		(layer "In2.Cu")
		(net "M_C_CPU0_SB_DQ<1>")
	)
	(segment
		(start 306.859686 -282.759912)
		(end 306.551584 -282.45181)
		(width 0.14478)
		(layer "In2.Cu")
		(net "M_C_CPU0_SB_DQ<1>")
	)
	(segment
		(start 339.52815 -275.218652)
		(end 339.519768 -275.223478)
		(width 0.0889)
		(layer "In2.Cu")
		(net "M_C_CPU0_SB_DQ<1>")
	)
	(segment
		(start 330.702412 -275.223478)
		(end 330.69403 -275.218652)
		(width 0.0889)
		(layer "In2.Cu")
		(net "M_C_CPU0_SB_DQ<1>")
	)
	(arc
		(start 330.69403 -275.218652)
		(mid 330.411074 -275.142475)
		(end 330.128118 -275.218652)
		(width 0.0889)
		(layer "In2.Cu")
		(net "M_C_CPU0_SB_DQ<1>")
	)
	(arc
		(start 342.91397 -275.218652)
		(mid 342.631014 -275.142475)
		(end 342.348058 -275.218652)
		(width 0.0889)
		(layer "In2.Cu")
		(net "M_C_CPU0_SB_DQ<1>")
	)
	(arc
		(start 339.519768 -275.223478)
		(mid 339.33626 -275.268972)
		(end 339.154008 -275.218652)
		(width 0.0889)
		(layer "In2.Cu")
		(net "M_C_CPU0_SB_DQ<1>")
	)
	(arc
		(start 332.574138 -275.218652)
		(mid 332.291182 -275.142475)
		(end 332.008226 -275.218652)
		(width 0.0889)
		(layer "In2.Cu")
		(net "M_C_CPU0_SB_DQ<1>")
	)
	(arc
		(start 329.753976 -275.218652)
		(mid 329.47102 -275.142475)
		(end 329.188064 -275.218652)
		(width 0.0889)
		(layer "In2.Cu")
		(net "M_C_CPU0_SB_DQ<1>")
	)
	(arc
		(start 327.873614 -275.218652)
		(mid 327.598908 -275.142288)
		(end 327.321926 -275.210016)
		(width 0.0889)
		(layer "In2.Cu")
		(net "M_C_CPU0_SB_DQ<1>")
	)
	(arc
		(start 332.008226 -275.218652)
		(mid 331.825975 -275.269002)
		(end 331.642466 -275.223478)
		(width 0.0889)
		(layer "In2.Cu")
		(net "M_C_CPU0_SB_DQ<1>")
	)
	(arc
		(start 327.307194 -275.218652)
		(mid 327.128207 -275.268822)
		(end 326.947276 -275.226272)
		(width 0.0889)
		(layer "In2.Cu")
		(net "M_C_CPU0_SB_DQ<1>")
	)
	(arc
		(start 341.97417 -275.218652)
		(mid 341.691214 -275.142475)
		(end 341.408258 -275.218652)
		(width 0.0889)
		(layer "In2.Cu")
		(net "M_C_CPU0_SB_DQ<1>")
	)
	(arc
		(start 335.768188 -275.218652)
		(mid 335.585937 -275.269002)
		(end 335.402428 -275.223478)
		(width 0.0889)
		(layer "In2.Cu")
		(net "M_C_CPU0_SB_DQ<1>")
	)
	(arc
		(start 336.708242 -275.218652)
		(mid 336.525991 -275.269002)
		(end 336.342482 -275.223478)
		(width 0.0889)
		(layer "In2.Cu")
		(net "M_C_CPU0_SB_DQ<1>")
	)
	(arc
		(start 341.408258 -275.218652)
		(mid 341.226007 -275.269002)
		(end 341.042498 -275.223478)
		(width 0.0889)
		(layer "In2.Cu")
		(net "M_C_CPU0_SB_DQ<1>")
	)
	(arc
		(start 331.068172 -275.218652)
		(mid 330.885921 -275.269002)
		(end 330.702412 -275.223478)
		(width 0.0889)
		(layer "In2.Cu")
		(net "M_C_CPU0_SB_DQ<1>")
	)
	(arc
		(start 336.3341 -275.218652)
		(mid 336.051144 -275.142475)
		(end 335.768188 -275.218652)
		(width 0.0889)
		(layer "In2.Cu")
		(net "M_C_CPU0_SB_DQ<1>")
	)
	(arc
		(start 331.634084 -275.218652)
		(mid 331.351128 -275.142475)
		(end 331.068172 -275.218652)
		(width 0.0889)
		(layer "In2.Cu")
		(net "M_C_CPU0_SB_DQ<1>")
	)
	(arc
		(start 341.034116 -275.218652)
		(mid 340.75116 -275.142475)
		(end 340.468204 -275.218652)
		(width 0.0889)
		(layer "In2.Cu")
		(net "M_C_CPU0_SB_DQ<1>")
	)
	(arc
		(start 340.468204 -275.218652)
		(mid 340.285953 -275.269002)
		(end 340.102444 -275.223478)
		(width 0.0889)
		(layer "In2.Cu")
		(net "M_C_CPU0_SB_DQ<1>")
	)
	(arc
		(start 333.513938 -275.218652)
		(mid 333.230982 -275.142475)
		(end 332.948026 -275.218652)
		(width 0.0889)
		(layer "In2.Cu")
		(net "M_C_CPU0_SB_DQ<1>")
	)
	(arc
		(start 335.394046 -275.218652)
		(mid 335.11109 -275.142475)
		(end 334.828134 -275.218652)
		(width 0.0889)
		(layer "In2.Cu")
		(net "M_C_CPU0_SB_DQ<1>")
	)
	(arc
		(start 337.648042 -275.218652)
		(mid 337.461098 -275.268907)
		(end 337.274154 -275.218652)
		(width 0.0889)
		(layer "In2.Cu")
		(net "M_C_CPU0_SB_DQ<1>")
	)
	(arc
		(start 339.154008 -275.218652)
		(mid 338.871052 -275.142475)
		(end 338.588096 -275.218652)
		(width 0.0889)
		(layer "In2.Cu")
		(net "M_C_CPU0_SB_DQ<1>")
	)
	(arc
		(start 334.819752 -275.223478)
		(mid 334.636244 -275.268972)
		(end 334.453992 -275.218652)
		(width 0.0889)
		(layer "In2.Cu")
		(net "M_C_CPU0_SB_DQ<1>")
	)
	(arc
		(start 340.094062 -275.218652)
		(mid 339.811106 -275.142475)
		(end 339.52815 -275.218652)
		(width 0.0889)
		(layer "In2.Cu")
		(net "M_C_CPU0_SB_DQ<1>")
	)
	(arc
		(start 343.27973 -275.223478)
		(mid 343.096222 -275.268972)
		(end 342.91397 -275.218652)
		(width 0.0889)
		(layer "In2.Cu")
		(net "M_C_CPU0_SB_DQ<1>")
	)
	(arc
		(start 342.348058 -275.218652)
		(mid 342.161114 -275.268907)
		(end 341.97417 -275.218652)
		(width 0.0889)
		(layer "In2.Cu")
		(net "M_C_CPU0_SB_DQ<1>")
	)
	(arc
		(start 334.453992 -275.218652)
		(mid 334.171036 -275.142475)
		(end 333.88808 -275.218652)
		(width 0.0889)
		(layer "In2.Cu")
		(net "M_C_CPU0_SB_DQ<1>")
	)
	(arc
		(start 337.274154 -275.218652)
		(mid 336.991198 -275.142475)
		(end 336.708242 -275.218652)
		(width 0.0889)
		(layer "In2.Cu")
		(net "M_C_CPU0_SB_DQ<1>")
	)
	(arc
		(start 338.213954 -275.218652)
		(mid 337.930998 -275.142475)
		(end 337.648042 -275.218652)
		(width 0.0889)
		(layer "In2.Cu")
		(net "M_C_CPU0_SB_DQ<1>")
	)
	(arc
		(start 326.910954 -275.205444)
		(mid 326.785576 -275.153755)
		(end 326.651112 -275.136102)
		(width 0.0889)
		(layer "In2.Cu")
		(net "M_C_CPU0_SB_DQ<1>")
	)
	(arc
		(start 328.814176 -275.218652)
		(mid 328.53122 -275.142475)
		(end 328.248264 -275.218652)
		(width 0.0889)
		(layer "In2.Cu")
		(net "M_C_CPU0_SB_DQ<1>")
	)
	(arc
		(start 329.188064 -275.218652)
		(mid 329.00112 -275.268907)
		(end 328.814176 -275.218652)
		(width 0.0889)
		(layer "In2.Cu")
		(net "M_C_CPU0_SB_DQ<1>")
	)
	(arc
		(start 333.879698 -275.223478)
		(mid 333.69619 -275.268972)
		(end 333.513938 -275.218652)
		(width 0.0889)
		(layer "In2.Cu")
		(net "M_C_CPU0_SB_DQ<1>")
	)
	(arc
		(start 332.948026 -275.218652)
		(mid 332.761082 -275.268907)
		(end 332.574138 -275.218652)
		(width 0.0889)
		(layer "In2.Cu")
		(net "M_C_CPU0_SB_DQ<1>")
	)
	(arc
		(start 330.119736 -275.223478)
		(mid 329.936228 -275.268972)
		(end 329.753976 -275.218652)
		(width 0.0889)
		(layer "In2.Cu")
		(net "M_C_CPU0_SB_DQ<1>")
	)
	(arc
		(start 338.579714 -275.223478)
		(mid 338.396206 -275.268972)
		(end 338.213954 -275.218652)
		(width 0.0889)
		(layer "In2.Cu")
		(net "M_C_CPU0_SB_DQ<1>")
	)
	(arc
		(start 328.239882 -275.223478)
		(mid 328.05612 -275.269094)
		(end 327.873614 -275.218652)
		(width 0.0889)
		(layer "In2.Cu")
		(net "M_C_CPU0_SB_DQ<1>")
	)
	(arc
		(start 343.790778 -275.186902)
		(mid 343.535713 -275.143551)
		(end 343.288112 -275.218652)
		(width 0.0889)
		(layer "In2.Cu")
		(net "M_C_CPU0_SB_DQ<1>")
	)
	(segment
		(start 344.03792 -285.160212)
		(end 343.571068 -285.42615)
		(width 0.10668)
		(layer "F.Cu")
		(net "M_C_CPU0_SB_DQ<19>")
	)
	(segment
		(start 333.05242 -285.098744)
		(end 333.044038 -285.10357)
		(width 0.0889)
		(layer "In2.Cu")
		(net "M_C_CPU0_SB_DQ<19>")
	)
	(segment
		(start 328.718164 -285.10357)
		(end 328.709782 -285.098744)
		(width 0.0889)
		(layer "In2.Cu")
		(net "M_C_CPU0_SB_DQ<19>")
	)
	(segment
		(start 337.178142 -285.10357)
		(end 337.16976 -285.098744)
		(width 0.0889)
		(layer "In2.Cu")
		(net "M_C_CPU0_SB_DQ<19>")
	)
	(segment
		(start 326.651112 -285.05277)
		(end 326.60336 -285.05277)
		(width 0.0889)
		(layer "In2.Cu")
		(net "M_C_CPU0_SB_DQ<19>")
	)
	(segment
		(start 333.992474 -285.098744)
		(end 333.984092 -285.10357)
		(width 0.0889)
		(layer "In2.Cu")
		(net "M_C_CPU0_SB_DQ<19>")
	)
	(segment
		(start 304.699162 -303.160176)
		(end 302.241966 -303.160176)
		(width 0.14478)
		(layer "In2.Cu")
		(net "M_C_CPU0_SB_DQ<19>")
	)
	(segment
		(start 298.198032 -302.300386)
		(end 297.348148 -303.15027)
		(width 0.14478)
		(layer "In2.Cu")
		(net "M_C_CPU0_SB_DQ<19>")
	)
	(segment
		(start 326.517508 -285.072836)
		(end 325.426832 -285.61411)
		(width 0.0889)
		(layer "In2.Cu")
		(net "M_C_CPU0_SB_DQ<19>")
	)
	(segment
		(start 314.810648 -298.068492)
		(end 313.538108 -298.068492)
		(width 0.14478)
		(layer "In2.Cu")
		(net "M_C_CPU0_SB_DQ<19>")
	)
	(segment
		(start 325.426832 -285.61411)
		(end 324.609714 -285.61411)
		(width 0.0889)
		(layer "In2.Cu")
		(net "M_C_CPU0_SB_DQ<19>")
	)
	(segment
		(start 289.826192 -302.828452)
		(end 289.59556 -302.828452)
		(width 0.14478)
		(layer "In2.Cu")
		(net "M_C_CPU0_SB_DQ<19>")
	)
	(segment
		(start 332.478126 -285.10357)
		(end 332.469744 -285.098744)
		(width 0.0889)
		(layer "In2.Cu")
		(net "M_C_CPU0_SB_DQ<19>")
	)
	(segment
		(start 289.59556 -302.828452)
		(end 289.263836 -303.160176)
		(width 0.14478)
		(layer "In2.Cu")
		(net "M_C_CPU0_SB_DQ<19>")
	)
	(segment
		(start 336.238088 -285.10357)
		(end 336.229706 -285.098744)
		(width 0.0889)
		(layer "In2.Cu")
		(net "M_C_CPU0_SB_DQ<19>")
	)
	(segment
		(start 327.41489 -285.096712)
		(end 327.403206 -285.10357)
		(width 0.0889)
		(layer "In2.Cu")
		(net "M_C_CPU0_SB_DQ<19>")
	)
	(segment
		(start 317.980314 -294.898826)
		(end 314.810648 -298.068492)
		(width 0.14478)
		(layer "In2.Cu")
		(net "M_C_CPU0_SB_DQ<19>")
	)
	(segment
		(start 305.5493 -302.310038)
		(end 304.699162 -303.160176)
		(width 0.14478)
		(layer "In2.Cu")
		(net "M_C_CPU0_SB_DQ<19>")
	)
	(segment
		(start 343.725246 -285.16072)
		(end 343.702894 -285.077408)
		(width 0.0889)
		(layer "In2.Cu")
		(net "M_C_CPU0_SB_DQ<19>")
	)
	(segment
		(start 341.878158 -285.10357)
		(end 341.869776 -285.098744)
		(width 0.0889)
		(layer "In2.Cu")
		(net "M_C_CPU0_SB_DQ<19>")
	)
	(segment
		(start 342.452452 -285.098744)
		(end 342.44407 -285.10357)
		(width 0.0889)
		(layer "In2.Cu")
		(net "M_C_CPU0_SB_DQ<19>")
	)
	(segment
		(start 288.605214 -303.160176)
		(end 288.180018 -302.73498)
		(width 0.14478)
		(layer "In2.Cu")
		(net "M_C_CPU0_SB_DQ<19>")
	)
	(segment
		(start 301.382176 -302.300386)
		(end 298.198032 -302.300386)
		(width 0.14478)
		(layer "In2.Cu")
		(net "M_C_CPU0_SB_DQ<19>")
	)
	(segment
		(start 328.344022 -285.10357)
		(end 328.32929 -285.112206)
		(width 0.0889)
		(layer "In2.Cu")
		(net "M_C_CPU0_SB_DQ<19>")
	)
	(segment
		(start 329.292458 -285.098744)
		(end 329.284076 -285.10357)
		(width 0.0889)
		(layer "In2.Cu")
		(net "M_C_CPU0_SB_DQ<19>")
	)
	(segment
		(start 290.14801 -303.15027)
		(end 289.826192 -302.828452)
		(width 0.14478)
		(layer "In2.Cu")
		(net "M_C_CPU0_SB_DQ<19>")
	)
	(segment
		(start 309.296562 -302.310038)
		(end 305.5493 -302.310038)
		(width 0.14478)
		(layer "In2.Cu")
		(net "M_C_CPU0_SB_DQ<19>")
	)
	(segment
		(start 338.69249 -285.098744)
		(end 338.684108 -285.10357)
		(width 0.0889)
		(layer "In2.Cu")
		(net "M_C_CPU0_SB_DQ<19>")
	)
	(segment
		(start 317.980314 -291.549582)
		(end 317.980314 -294.898826)
		(width 0.14478)
		(layer "In2.Cu")
		(net "M_C_CPU0_SB_DQ<19>")
	)
	(segment
		(start 323.893434 -285.83763)
		(end 323.692266 -285.83763)
		(width 0.14478)
		(layer "In2.Cu")
		(net "M_C_CPU0_SB_DQ<19>")
	)
	(segment
		(start 324.386194 -285.83763)
		(end 323.893434 -285.83763)
		(width 0.0889)
		(layer "In2.Cu")
		(net "M_C_CPU0_SB_DQ<19>")
	)
	(segment
		(start 343.392506 -285.098744)
		(end 343.384124 -285.10357)
		(width 0.0889)
		(layer "In2.Cu")
		(net "M_C_CPU0_SB_DQ<19>")
	)
	(segment
		(start 343.571068 -285.42615)
		(end 343.725246 -285.16072)
		(width 0.0889)
		(layer "In2.Cu")
		(net "M_C_CPU0_SB_DQ<19>")
	)
	(segment
		(start 331.538072 -285.10357)
		(end 331.52969 -285.098744)
		(width 0.0889)
		(layer "In2.Cu")
		(net "M_C_CPU0_SB_DQ<19>")
	)
	(segment
		(start 302.241966 -303.160176)
		(end 301.382176 -302.300386)
		(width 0.14478)
		(layer "In2.Cu")
		(net "M_C_CPU0_SB_DQ<19>")
	)
	(segment
		(start 323.692266 -285.83763)
		(end 317.980314 -291.549582)
		(width 0.14478)
		(layer "In2.Cu")
		(net "M_C_CPU0_SB_DQ<19>")
	)
	(segment
		(start 313.538108 -298.068492)
		(end 309.296562 -302.310038)
		(width 0.14478)
		(layer "In2.Cu")
		(net "M_C_CPU0_SB_DQ<19>")
	)
	(segment
		(start 289.263836 -303.160176)
		(end 288.605214 -303.160176)
		(width 0.14478)
		(layer "In2.Cu")
		(net "M_C_CPU0_SB_DQ<19>")
	)
	(segment
		(start 297.348148 -303.15027)
		(end 290.14801 -303.15027)
		(width 0.14478)
		(layer "In2.Cu")
		(net "M_C_CPU0_SB_DQ<19>")
	)
	(segment
		(start 337.752436 -285.098744)
		(end 337.744054 -285.10357)
		(width 0.0889)
		(layer "In2.Cu")
		(net "M_C_CPU0_SB_DQ<19>")
	)
	(segment
		(start 340.938104 -285.10357)
		(end 340.929722 -285.098744)
		(width 0.0889)
		(layer "In2.Cu")
		(net "M_C_CPU0_SB_DQ<19>")
	)
	(segment
		(start 324.609714 -285.61411)
		(end 324.386194 -285.83763)
		(width 0.0889)
		(layer "In2.Cu")
		(net "M_C_CPU0_SB_DQ<19>")
	)
	(arc
		(start 338.118196 -285.10357)
		(mid 337.935945 -285.05322)
		(end 337.752436 -285.098744)
		(width 0.0889)
		(layer "In2.Cu")
		(net "M_C_CPU0_SB_DQ<19>")
	)
	(arc
		(start 328.32929 -285.112206)
		(mid 328.052307 -285.18001)
		(end 327.777602 -285.10357)
		(width 0.0889)
		(layer "In2.Cu")
		(net "M_C_CPU0_SB_DQ<19>")
	)
	(arc
		(start 342.818212 -285.10357)
		(mid 342.635961 -285.05322)
		(end 342.452452 -285.098744)
		(width 0.0889)
		(layer "In2.Cu")
		(net "M_C_CPU0_SB_DQ<19>")
	)
	(arc
		(start 343.384124 -285.10357)
		(mid 343.101168 -285.179747)
		(end 342.818212 -285.10357)
		(width 0.0889)
		(layer "In2.Cu")
		(net "M_C_CPU0_SB_DQ<19>")
	)
	(arc
		(start 339.99805 -285.10357)
		(mid 339.811106 -285.053315)
		(end 339.624162 -285.10357)
		(width 0.0889)
		(layer "In2.Cu")
		(net "M_C_CPU0_SB_DQ<19>")
	)
	(arc
		(start 326.60336 -285.05277)
		(mid 326.559271 -285.057826)
		(end 326.517508 -285.072836)
		(width 0.0889)
		(layer "In2.Cu")
		(net "M_C_CPU0_SB_DQ<19>")
	)
	(arc
		(start 331.16393 -285.10357)
		(mid 330.880974 -285.179747)
		(end 330.598018 -285.10357)
		(width 0.0889)
		(layer "In2.Cu")
		(net "M_C_CPU0_SB_DQ<19>")
	)
	(arc
		(start 332.469744 -285.098744)
		(mid 332.286236 -285.05325)
		(end 332.103984 -285.10357)
		(width 0.0889)
		(layer "In2.Cu")
		(net "M_C_CPU0_SB_DQ<19>")
	)
	(arc
		(start 327.403206 -285.10357)
		(mid 327.123778 -285.179736)
		(end 326.84339 -285.107126)
		(width 0.0889)
		(layer "In2.Cu")
		(net "M_C_CPU0_SB_DQ<19>")
	)
	(arc
		(start 335.863946 -285.10357)
		(mid 335.58099 -285.179747)
		(end 335.298034 -285.10357)
		(width 0.0889)
		(layer "In2.Cu")
		(net "M_C_CPU0_SB_DQ<19>")
	)
	(arc
		(start 340.929722 -285.098744)
		(mid 340.746214 -285.05325)
		(end 340.563962 -285.10357)
		(width 0.0889)
		(layer "In2.Cu")
		(net "M_C_CPU0_SB_DQ<19>")
	)
	(arc
		(start 334.358234 -285.10357)
		(mid 334.175983 -285.05322)
		(end 333.992474 -285.098744)
		(width 0.0889)
		(layer "In2.Cu")
		(net "M_C_CPU0_SB_DQ<19>")
	)
	(arc
		(start 341.504016 -285.10357)
		(mid 341.22106 -285.179747)
		(end 340.938104 -285.10357)
		(width 0.0889)
		(layer "In2.Cu")
		(net "M_C_CPU0_SB_DQ<19>")
	)
	(arc
		(start 336.229706 -285.098744)
		(mid 336.046198 -285.05325)
		(end 335.863946 -285.10357)
		(width 0.0889)
		(layer "In2.Cu")
		(net "M_C_CPU0_SB_DQ<19>")
	)
	(arc
		(start 334.924146 -285.10357)
		(mid 334.64119 -285.179747)
		(end 334.358234 -285.10357)
		(width 0.0889)
		(layer "In2.Cu")
		(net "M_C_CPU0_SB_DQ<19>")
	)
	(arc
		(start 330.22413 -285.10357)
		(mid 329.941174 -285.179747)
		(end 329.658218 -285.10357)
		(width 0.0889)
		(layer "In2.Cu")
		(net "M_C_CPU0_SB_DQ<19>")
	)
	(arc
		(start 337.744054 -285.10357)
		(mid 337.461098 -285.179747)
		(end 337.178142 -285.10357)
		(width 0.0889)
		(layer "In2.Cu")
		(net "M_C_CPU0_SB_DQ<19>")
	)
	(arc
		(start 338.684108 -285.10357)
		(mid 338.401152 -285.179747)
		(end 338.118196 -285.10357)
		(width 0.0889)
		(layer "In2.Cu")
		(net "M_C_CPU0_SB_DQ<19>")
	)
	(arc
		(start 343.702894 -285.077408)
		(mid 343.545384 -285.05421)
		(end 343.392506 -285.098744)
		(width 0.0889)
		(layer "In2.Cu")
		(net "M_C_CPU0_SB_DQ<19>")
	)
	(arc
		(start 333.044038 -285.10357)
		(mid 332.761082 -285.179747)
		(end 332.478126 -285.10357)
		(width 0.0889)
		(layer "In2.Cu")
		(net "M_C_CPU0_SB_DQ<19>")
	)
	(arc
		(start 333.41818 -285.10357)
		(mid 333.235929 -285.05322)
		(end 333.05242 -285.098744)
		(width 0.0889)
		(layer "In2.Cu")
		(net "M_C_CPU0_SB_DQ<19>")
	)
	(arc
		(start 331.52969 -285.098744)
		(mid 331.346182 -285.05325)
		(end 331.16393 -285.10357)
		(width 0.0889)
		(layer "In2.Cu")
		(net "M_C_CPU0_SB_DQ<19>")
	)
	(arc
		(start 335.298034 -285.10357)
		(mid 335.11109 -285.053315)
		(end 334.924146 -285.10357)
		(width 0.0889)
		(layer "In2.Cu")
		(net "M_C_CPU0_SB_DQ<19>")
	)
	(arc
		(start 339.624162 -285.10357)
		(mid 339.341206 -285.179747)
		(end 339.05825 -285.10357)
		(width 0.0889)
		(layer "In2.Cu")
		(net "M_C_CPU0_SB_DQ<19>")
	)
	(arc
		(start 327.777602 -285.10357)
		(mid 327.597144 -285.053126)
		(end 327.41489 -285.096712)
		(width 0.0889)
		(layer "In2.Cu")
		(net "M_C_CPU0_SB_DQ<19>")
	)
	(arc
		(start 328.709782 -285.098744)
		(mid 328.526274 -285.05325)
		(end 328.344022 -285.10357)
		(width 0.0889)
		(layer "In2.Cu")
		(net "M_C_CPU0_SB_DQ<19>")
	)
	(arc
		(start 337.16976 -285.098744)
		(mid 336.986252 -285.05325)
		(end 336.804 -285.10357)
		(width 0.0889)
		(layer "In2.Cu")
		(net "M_C_CPU0_SB_DQ<19>")
	)
	(arc
		(start 341.869776 -285.098744)
		(mid 341.686268 -285.05325)
		(end 341.504016 -285.10357)
		(width 0.0889)
		(layer "In2.Cu")
		(net "M_C_CPU0_SB_DQ<19>")
	)
	(arc
		(start 336.804 -285.10357)
		(mid 336.521044 -285.179747)
		(end 336.238088 -285.10357)
		(width 0.0889)
		(layer "In2.Cu")
		(net "M_C_CPU0_SB_DQ<19>")
	)
	(arc
		(start 339.05825 -285.10357)
		(mid 338.875999 -285.05322)
		(end 338.69249 -285.098744)
		(width 0.0889)
		(layer "In2.Cu")
		(net "M_C_CPU0_SB_DQ<19>")
	)
	(arc
		(start 332.103984 -285.10357)
		(mid 331.821028 -285.179747)
		(end 331.538072 -285.10357)
		(width 0.0889)
		(layer "In2.Cu")
		(net "M_C_CPU0_SB_DQ<19>")
	)
	(arc
		(start 333.984092 -285.10357)
		(mid 333.701136 -285.179747)
		(end 333.41818 -285.10357)
		(width 0.0889)
		(layer "In2.Cu")
		(net "M_C_CPU0_SB_DQ<19>")
	)
	(arc
		(start 329.658218 -285.10357)
		(mid 329.475967 -285.05322)
		(end 329.292458 -285.098744)
		(width 0.0889)
		(layer "In2.Cu")
		(net "M_C_CPU0_SB_DQ<19>")
	)
	(arc
		(start 329.284076 -285.10357)
		(mid 329.00112 -285.179747)
		(end 328.718164 -285.10357)
		(width 0.0889)
		(layer "In2.Cu")
		(net "M_C_CPU0_SB_DQ<19>")
	)
	(arc
		(start 340.563962 -285.10357)
		(mid 340.281006 -285.179747)
		(end 339.99805 -285.10357)
		(width 0.0889)
		(layer "In2.Cu")
		(net "M_C_CPU0_SB_DQ<19>")
	)
	(arc
		(start 330.598018 -285.10357)
		(mid 330.411074 -285.053315)
		(end 330.22413 -285.10357)
		(width 0.0889)
		(layer "In2.Cu")
		(net "M_C_CPU0_SB_DQ<19>")
	)
	(arc
		(start 326.84339 -285.107126)
		(mid 326.750958 -285.066844)
		(end 326.651112 -285.05277)
		(width 0.0889)
		(layer "In2.Cu")
		(net "M_C_CPU0_SB_DQ<19>")
	)
	(arc
		(start 342.44407 -285.10357)
		(mid 342.161114 -285.179747)
		(end 341.878158 -285.10357)
		(width 0.0889)
		(layer "In2.Cu")
		(net "M_C_CPU0_SB_DQ<19>")
	)
	(segment
		(start 342.627966 -284.350206)
		(end 342.161114 -284.616144)
		(width 0.10668)
		(layer "F.Cu")
		(net "M_C_CPU0_SB_DQ<18>")
	)
	(segment
		(start 326.935846 -284.293564)
		(end 326.917558 -284.304232)
		(width 0.0889)
		(layer "In2.Cu")
		(net "M_C_CPU0_SB_DQ<18>")
	)
	(segment
		(start 290.015422 -300.892464)
		(end 289.852608 -300.72965)
		(width 0.14478)
		(layer "In2.Cu")
		(net "M_C_CPU0_SB_DQ<18>")
	)
	(segment
		(start 326.338438 -284.505908)
		(end 326.248522 -284.595824)
		(width 0.0889)
		(layer "In2.Cu")
		(net "M_C_CPU0_SB_DQ<18>")
	)
	(segment
		(start 338.588096 -284.293564)
		(end 338.579714 -284.288738)
		(width 0.0889)
		(layer "In2.Cu")
		(net "M_C_CPU0_SB_DQ<18>")
	)
	(segment
		(start 313.978798 -296.322496)
		(end 309.691278 -300.610016)
		(width 0.14478)
		(layer "In2.Cu")
		(net "M_C_CPU0_SB_DQ<18>")
	)
	(segment
		(start 330.702412 -284.288738)
		(end 330.69403 -284.293564)
		(width 0.0889)
		(layer "In2.Cu")
		(net "M_C_CPU0_SB_DQ<18>")
	)
	(segment
		(start 340.102444 -284.288738)
		(end 340.094062 -284.293564)
		(width 0.0889)
		(layer "In2.Cu")
		(net "M_C_CPU0_SB_DQ<18>")
	)
	(segment
		(start 335.402428 -284.288738)
		(end 335.394046 -284.293564)
		(width 0.0889)
		(layer "In2.Cu")
		(net "M_C_CPU0_SB_DQ<18>")
	)
	(segment
		(start 323.29501 -284.92323)
		(end 317.070994 -291.147246)
		(width 0.14478)
		(layer "In2.Cu")
		(net "M_C_CPU0_SB_DQ<18>")
	)
	(segment
		(start 289.459162 -301.29734)
		(end 289.296348 -301.460154)
		(width 0.14478)
		(layer "In2.Cu")
		(net "M_C_CPU0_SB_DQ<18>")
	)
	(segment
		(start 291.290756 -301.460154)
		(end 291.127942 -301.29734)
		(width 0.14478)
		(layer "In2.Cu")
		(net "M_C_CPU0_SB_DQ<18>")
	)
	(segment
		(start 290.408868 -301.460154)
		(end 290.178236 -301.460154)
		(width 0.14478)
		(layer "In2.Cu")
		(net "M_C_CPU0_SB_DQ<18>")
	)
	(segment
		(start 331.642466 -284.288738)
		(end 331.634084 -284.293564)
		(width 0.0889)
		(layer "In2.Cu")
		(net "M_C_CPU0_SB_DQ<18>")
	)
	(segment
		(start 297.751754 -301.460154)
		(end 291.290756 -301.460154)
		(width 0.14478)
		(layer "In2.Cu")
		(net "M_C_CPU0_SB_DQ<18>")
	)
	(segment
		(start 333.88808 -284.293564)
		(end 333.879698 -284.288738)
		(width 0.0889)
		(layer "In2.Cu")
		(net "M_C_CPU0_SB_DQ<18>")
	)
	(segment
		(start 317.070994 -291.147246)
		(end 317.070994 -294.53586)
		(width 0.14478)
		(layer "In2.Cu")
		(net "M_C_CPU0_SB_DQ<18>")
	)
	(segment
		(start 291.127942 -300.892464)
		(end 290.965128 -300.72965)
		(width 0.14478)
		(layer "In2.Cu")
		(net "M_C_CPU0_SB_DQ<18>")
	)
	(segment
		(start 301.03318 -300.610016)
		(end 298.601892 -300.610016)
		(width 0.14478)
		(layer "In2.Cu")
		(net "M_C_CPU0_SB_DQ<18>")
	)
	(segment
		(start 290.571682 -300.892464)
		(end 290.571682 -301.29734)
		(width 0.14478)
		(layer "In2.Cu")
		(net "M_C_CPU0_SB_DQ<18>")
	)
	(segment
		(start 289.296348 -301.460154)
		(end 288.605214 -301.460154)
		(width 0.14478)
		(layer "In2.Cu")
		(net "M_C_CPU0_SB_DQ<18>")
	)
	(segment
		(start 342.315038 -284.350714)
		(end 342.292686 -284.267402)
		(width 0.0889)
		(layer "In2.Cu")
		(net "M_C_CPU0_SB_DQ<18>")
	)
	(segment
		(start 336.342482 -284.288738)
		(end 336.3341 -284.293564)
		(width 0.0889)
		(layer "In2.Cu")
		(net "M_C_CPU0_SB_DQ<18>")
	)
	(segment
		(start 290.015422 -301.29734)
		(end 290.015422 -300.892464)
		(width 0.14478)
		(layer "In2.Cu")
		(net "M_C_CPU0_SB_DQ<18>")
	)
	(segment
		(start 288.605214 -301.460154)
		(end 288.180018 -301.034958)
		(width 0.14478)
		(layer "In2.Cu")
		(net "M_C_CPU0_SB_DQ<18>")
	)
	(segment
		(start 327.89876 -284.280356)
		(end 327.875392 -284.293818)
		(width 0.0889)
		(layer "In2.Cu")
		(net "M_C_CPU0_SB_DQ<18>")
	)
	(segment
		(start 325.458074 -284.92323)
		(end 323.871844 -284.92323)
		(width 0.0889)
		(layer "In2.Cu")
		(net "M_C_CPU0_SB_DQ<18>")
	)
	(segment
		(start 334.828134 -284.293564)
		(end 334.819752 -284.288738)
		(width 0.0889)
		(layer "In2.Cu")
		(net "M_C_CPU0_SB_DQ<18>")
	)
	(segment
		(start 298.601892 -300.610016)
		(end 297.751754 -301.460154)
		(width 0.14478)
		(layer "In2.Cu")
		(net "M_C_CPU0_SB_DQ<18>")
	)
	(segment
		(start 309.691278 -300.610016)
		(end 305.902868 -300.610016)
		(width 0.14478)
		(layer "In2.Cu")
		(net "M_C_CPU0_SB_DQ<18>")
	)
	(segment
		(start 305.05273 -301.460154)
		(end 301.883318 -301.460154)
		(width 0.14478)
		(layer "In2.Cu")
		(net "M_C_CPU0_SB_DQ<18>")
	)
	(segment
		(start 341.042498 -284.288738)
		(end 341.034116 -284.293564)
		(width 0.0889)
		(layer "In2.Cu")
		(net "M_C_CPU0_SB_DQ<18>")
	)
	(segment
		(start 317.070994 -294.53586)
		(end 315.284358 -296.322496)
		(width 0.14478)
		(layer "In2.Cu")
		(net "M_C_CPU0_SB_DQ<18>")
	)
	(segment
		(start 301.883318 -301.460154)
		(end 301.03318 -300.610016)
		(width 0.14478)
		(layer "In2.Cu")
		(net "M_C_CPU0_SB_DQ<18>")
	)
	(segment
		(start 289.459162 -300.892464)
		(end 289.459162 -301.29734)
		(width 0.14478)
		(layer "In2.Cu")
		(net "M_C_CPU0_SB_DQ<18>")
	)
	(segment
		(start 342.161114 -284.616144)
		(end 342.315038 -284.350714)
		(width 0.0889)
		(layer "In2.Cu")
		(net "M_C_CPU0_SB_DQ<18>")
	)
	(segment
		(start 290.178236 -301.460154)
		(end 290.015422 -301.29734)
		(width 0.14478)
		(layer "In2.Cu")
		(net "M_C_CPU0_SB_DQ<18>")
	)
	(segment
		(start 291.127942 -301.29734)
		(end 291.127942 -300.892464)
		(width 0.14478)
		(layer "In2.Cu")
		(net "M_C_CPU0_SB_DQ<18>")
	)
	(segment
		(start 290.734496 -300.72965)
		(end 290.571682 -300.892464)
		(width 0.14478)
		(layer "In2.Cu")
		(net "M_C_CPU0_SB_DQ<18>")
	)
	(segment
		(start 315.284358 -296.322496)
		(end 313.978798 -296.322496)
		(width 0.14478)
		(layer "In2.Cu")
		(net "M_C_CPU0_SB_DQ<18>")
	)
	(segment
		(start 289.621976 -300.72965)
		(end 289.459162 -300.892464)
		(width 0.14478)
		(layer "In2.Cu")
		(net "M_C_CPU0_SB_DQ<18>")
	)
	(segment
		(start 305.902868 -300.610016)
		(end 305.05273 -301.460154)
		(width 0.14478)
		(layer "In2.Cu")
		(net "M_C_CPU0_SB_DQ<18>")
	)
	(segment
		(start 289.852608 -300.72965)
		(end 289.621976 -300.72965)
		(width 0.14478)
		(layer "In2.Cu")
		(net "M_C_CPU0_SB_DQ<18>")
	)
	(segment
		(start 327.875392 -284.293818)
		(end 327.851516 -284.307788)
		(width 0.0889)
		(layer "In2.Cu")
		(net "M_C_CPU0_SB_DQ<18>")
	)
	(segment
		(start 339.52815 -284.293564)
		(end 339.519768 -284.288738)
		(width 0.0889)
		(layer "In2.Cu")
		(net "M_C_CPU0_SB_DQ<18>")
	)
	(segment
		(start 327.311258 -284.293564)
		(end 327.290684 -284.281626)
		(width 0.0889)
		(layer "In2.Cu")
		(net "M_C_CPU0_SB_DQ<18>")
	)
	(segment
		(start 290.571682 -301.29734)
		(end 290.408868 -301.460154)
		(width 0.14478)
		(layer "In2.Cu")
		(net "M_C_CPU0_SB_DQ<18>")
	)
	(segment
		(start 330.128118 -284.293564)
		(end 330.119736 -284.288738)
		(width 0.0889)
		(layer "In2.Cu")
		(net "M_C_CPU0_SB_DQ<18>")
	)
	(segment
		(start 290.965128 -300.72965)
		(end 290.734496 -300.72965)
		(width 0.14478)
		(layer "In2.Cu")
		(net "M_C_CPU0_SB_DQ<18>")
	)
	(segment
		(start 323.871844 -284.92323)
		(end 323.29501 -284.92323)
		(width 0.14478)
		(layer "In2.Cu")
		(net "M_C_CPU0_SB_DQ<18>")
	)
	(arc
		(start 326.917558 -284.304232)
		(mid 326.789128 -284.357998)
		(end 326.651112 -284.376368)
		(width 0.0889)
		(layer "In2.Cu")
		(net "M_C_CPU0_SB_DQ<18>")
	)
	(arc
		(start 336.708242 -284.293564)
		(mid 336.525991 -284.243214)
		(end 336.342482 -284.288738)
		(width 0.0889)
		(layer "In2.Cu")
		(net "M_C_CPU0_SB_DQ<18>")
	)
	(arc
		(start 334.819752 -284.288738)
		(mid 334.636244 -284.243244)
		(end 334.453992 -284.293564)
		(width 0.0889)
		(layer "In2.Cu")
		(net "M_C_CPU0_SB_DQ<18>")
	)
	(arc
		(start 342.292686 -284.267402)
		(mid 342.130497 -284.244667)
		(end 341.97417 -284.293564)
		(width 0.0889)
		(layer "In2.Cu")
		(net "M_C_CPU0_SB_DQ<18>")
	)
	(arc
		(start 338.213954 -284.293564)
		(mid 337.930998 -284.369741)
		(end 337.648042 -284.293564)
		(width 0.0889)
		(layer "In2.Cu")
		(net "M_C_CPU0_SB_DQ<18>")
	)
	(arc
		(start 328.814176 -284.293564)
		(mid 328.53122 -284.369741)
		(end 328.248264 -284.293564)
		(width 0.0889)
		(layer "In2.Cu")
		(net "M_C_CPU0_SB_DQ<18>")
	)
	(arc
		(start 333.513938 -284.293564)
		(mid 333.230982 -284.369741)
		(end 332.948026 -284.293564)
		(width 0.0889)
		(layer "In2.Cu")
		(net "M_C_CPU0_SB_DQ<18>")
	)
	(arc
		(start 340.094062 -284.293564)
		(mid 339.811106 -284.369741)
		(end 339.52815 -284.293564)
		(width 0.0889)
		(layer "In2.Cu")
		(net "M_C_CPU0_SB_DQ<18>")
	)
	(arc
		(start 335.768188 -284.293564)
		(mid 335.585937 -284.243214)
		(end 335.402428 -284.288738)
		(width 0.0889)
		(layer "In2.Cu")
		(net "M_C_CPU0_SB_DQ<18>")
	)
	(arc
		(start 328.248264 -284.293564)
		(mid 328.075156 -284.243448)
		(end 327.89876 -284.280356)
		(width 0.0889)
		(layer "In2.Cu")
		(net "M_C_CPU0_SB_DQ<18>")
	)
	(arc
		(start 341.97417 -284.293564)
		(mid 341.691214 -284.369741)
		(end 341.408258 -284.293564)
		(width 0.0889)
		(layer "In2.Cu")
		(net "M_C_CPU0_SB_DQ<18>")
	)
	(arc
		(start 332.008226 -284.293564)
		(mid 331.825975 -284.243214)
		(end 331.642466 -284.288738)
		(width 0.0889)
		(layer "In2.Cu")
		(net "M_C_CPU0_SB_DQ<18>")
	)
	(arc
		(start 339.154008 -284.293564)
		(mid 338.871052 -284.369741)
		(end 338.588096 -284.293564)
		(width 0.0889)
		(layer "In2.Cu")
		(net "M_C_CPU0_SB_DQ<18>")
	)
	(arc
		(start 330.119736 -284.288738)
		(mid 329.936228 -284.243244)
		(end 329.753976 -284.293564)
		(width 0.0889)
		(layer "In2.Cu")
		(net "M_C_CPU0_SB_DQ<18>")
	)
	(arc
		(start 326.651112 -284.376368)
		(mid 326.481884 -284.41003)
		(end 326.338438 -284.505908)
		(width 0.0889)
		(layer "In2.Cu")
		(net "M_C_CPU0_SB_DQ<18>")
	)
	(arc
		(start 341.408258 -284.293564)
		(mid 341.226007 -284.243214)
		(end 341.042498 -284.288738)
		(width 0.0889)
		(layer "In2.Cu")
		(net "M_C_CPU0_SB_DQ<18>")
	)
	(arc
		(start 340.468204 -284.293564)
		(mid 340.285953 -284.243214)
		(end 340.102444 -284.288738)
		(width 0.0889)
		(layer "In2.Cu")
		(net "M_C_CPU0_SB_DQ<18>")
	)
	(arc
		(start 335.394046 -284.293564)
		(mid 335.11109 -284.369741)
		(end 334.828134 -284.293564)
		(width 0.0889)
		(layer "In2.Cu")
		(net "M_C_CPU0_SB_DQ<18>")
	)
	(arc
		(start 341.034116 -284.293564)
		(mid 340.75116 -284.369741)
		(end 340.468204 -284.293564)
		(width 0.0889)
		(layer "In2.Cu")
		(net "M_C_CPU0_SB_DQ<18>")
	)
	(arc
		(start 334.453992 -284.293564)
		(mid 334.171036 -284.369741)
		(end 333.88808 -284.293564)
		(width 0.0889)
		(layer "In2.Cu")
		(net "M_C_CPU0_SB_DQ<18>")
	)
	(arc
		(start 333.879698 -284.288738)
		(mid 333.69619 -284.243244)
		(end 333.513938 -284.293564)
		(width 0.0889)
		(layer "In2.Cu")
		(net "M_C_CPU0_SB_DQ<18>")
	)
	(arc
		(start 337.274154 -284.293564)
		(mid 336.991198 -284.369741)
		(end 336.708242 -284.293564)
		(width 0.0889)
		(layer "In2.Cu")
		(net "M_C_CPU0_SB_DQ<18>")
	)
	(arc
		(start 332.574138 -284.293564)
		(mid 332.291182 -284.369741)
		(end 332.008226 -284.293564)
		(width 0.0889)
		(layer "In2.Cu")
		(net "M_C_CPU0_SB_DQ<18>")
	)
	(arc
		(start 329.188064 -284.293564)
		(mid 329.00112 -284.243309)
		(end 328.814176 -284.293564)
		(width 0.0889)
		(layer "In2.Cu")
		(net "M_C_CPU0_SB_DQ<18>")
	)
	(arc
		(start 331.634084 -284.293564)
		(mid 331.351128 -284.369741)
		(end 331.068172 -284.293564)
		(width 0.0889)
		(layer "In2.Cu")
		(net "M_C_CPU0_SB_DQ<18>")
	)
	(arc
		(start 336.3341 -284.293564)
		(mid 336.051144 -284.369741)
		(end 335.768188 -284.293564)
		(width 0.0889)
		(layer "In2.Cu")
		(net "M_C_CPU0_SB_DQ<18>")
	)
	(arc
		(start 331.068172 -284.293564)
		(mid 330.885921 -284.243214)
		(end 330.702412 -284.288738)
		(width 0.0889)
		(layer "In2.Cu")
		(net "M_C_CPU0_SB_DQ<18>")
	)
	(arc
		(start 327.290684 -284.281626)
		(mid 327.111756 -284.242749)
		(end 326.935846 -284.293564)
		(width 0.0889)
		(layer "In2.Cu")
		(net "M_C_CPU0_SB_DQ<18>")
	)
	(arc
		(start 330.69403 -284.293564)
		(mid 330.411074 -284.369741)
		(end 330.128118 -284.293564)
		(width 0.0889)
		(layer "In2.Cu")
		(net "M_C_CPU0_SB_DQ<18>")
	)
	(arc
		(start 338.579714 -284.288738)
		(mid 338.396206 -284.243244)
		(end 338.213954 -284.293564)
		(width 0.0889)
		(layer "In2.Cu")
		(net "M_C_CPU0_SB_DQ<18>")
	)
	(arc
		(start 337.648042 -284.293564)
		(mid 337.461098 -284.243309)
		(end 337.274154 -284.293564)
		(width 0.0889)
		(layer "In2.Cu")
		(net "M_C_CPU0_SB_DQ<18>")
	)
	(arc
		(start 332.948026 -284.293564)
		(mid 332.761082 -284.243309)
		(end 332.574138 -284.293564)
		(width 0.0889)
		(layer "In2.Cu")
		(net "M_C_CPU0_SB_DQ<18>")
	)
	(arc
		(start 326.248522 -284.595824)
		(mid 325.885861 -284.838146)
		(end 325.458074 -284.92323)
		(width 0.0889)
		(layer "In2.Cu")
		(net "M_C_CPU0_SB_DQ<18>")
	)
	(arc
		(start 339.519768 -284.288738)
		(mid 339.33626 -284.243244)
		(end 339.154008 -284.293564)
		(width 0.0889)
		(layer "In2.Cu")
		(net "M_C_CPU0_SB_DQ<18>")
	)
	(arc
		(start 327.851516 -284.307788)
		(mid 327.579579 -284.369614)
		(end 327.311258 -284.293564)
		(width 0.0889)
		(layer "In2.Cu")
		(net "M_C_CPU0_SB_DQ<18>")
	)
	(arc
		(start 329.753976 -284.293564)
		(mid 329.47102 -284.369741)
		(end 329.188064 -284.293564)
		(width 0.0889)
		(layer "In2.Cu")
		(net "M_C_CPU0_SB_DQ<18>")
	)
	(segment
		(start 344.508074 -284.350206)
		(end 344.041222 -284.616144)
		(width 0.10668)
		(layer "F.Cu")
		(net "M_C_CPU0_SB_DQ<17>")
	)
	(segment
		(start 331.642466 -284.94355)
		(end 331.634084 -284.938724)
		(width 0.0889)
		(layer "In2.Cu")
		(net "M_C_CPU0_SB_DQ<17>")
	)
	(segment
		(start 317.525654 -294.717216)
		(end 315.469778 -296.773092)
		(width 0.14478)
		(layer "In2.Cu")
		(net "M_C_CPU0_SB_DQ<17>")
	)
	(segment
		(start 307.00472 -301.4599)
		(end 306.843176 -301.298356)
		(width 0.14478)
		(layer "In2.Cu")
		(net "M_C_CPU0_SB_DQ<17>")
	)
	(segment
		(start 294.379396 -302.688498)
		(end 294.148764 -302.688498)
		(width 0.14478)
		(layer "In2.Cu")
		(net "M_C_CPU0_SB_DQ<17>")
	)
	(segment
		(start 296.850054 -302.493172)
		(end 296.850054 -302.210724)
		(width 0.14478)
		(layer "In2.Cu")
		(net "M_C_CPU0_SB_DQ<17>")
	)
	(segment
		(start 338.588096 -284.938724)
		(end 338.579714 -284.94355)
		(width 0.0889)
		(layer "In2.Cu")
		(net "M_C_CPU0_SB_DQ<17>")
	)
	(segment
		(start 293.42969 -302.522636)
		(end 293.27983 -302.672496)
		(width 0.14478)
		(layer "In2.Cu")
		(net "M_C_CPU0_SB_DQ<17>")
	)
	(segment
		(start 343.887044 -284.881574)
		(end 343.790778 -284.906974)
		(width 0.0889)
		(layer "In2.Cu")
		(net "M_C_CPU0_SB_DQ<17>")
	)
	(segment
		(start 327.321926 -284.930088)
		(end 327.307194 -284.938724)
		(width 0.0889)
		(layer "In2.Cu")
		(net "M_C_CPU0_SB_DQ<17>")
	)
	(segment
		(start 300.320964 -301.232316)
		(end 300.320964 -301.298356)
		(width 0.14478)
		(layer "In2.Cu")
		(net "M_C_CPU0_SB_DQ<17>")
	)
	(segment
		(start 306.453286 -301.070772)
		(end 306.291742 -301.232316)
		(width 0.14478)
		(layer "In2.Cu")
		(net "M_C_CPU0_SB_DQ<17>")
	)
	(segment
		(start 333.88808 -284.938724)
		(end 333.879698 -284.94355)
		(width 0.0889)
		(layer "In2.Cu")
		(net "M_C_CPU0_SB_DQ<17>")
	)
	(segment
		(start 301.033942 -301.4599)
		(end 300.872398 -301.298356)
		(width 0.14478)
		(layer "In2.Cu")
		(net "M_C_CPU0_SB_DQ<17>")
	)
	(segment
		(start 336.342482 -284.94355)
		(end 336.3341 -284.938724)
		(width 0.0889)
		(layer "In2.Cu")
		(net "M_C_CPU0_SB_DQ<17>")
	)
	(segment
		(start 294.148764 -302.688498)
		(end 293.98595 -302.525684)
		(width 0.14478)
		(layer "In2.Cu")
		(net "M_C_CPU0_SB_DQ<17>")
	)
	(segment
		(start 297.212004 -302.643032)
		(end 296.999914 -302.643032)
		(width 0.14478)
		(layer "In2.Cu")
		(net "M_C_CPU0_SB_DQ<17>")
	)
	(segment
		(start 304.498502 -302.310038)
		(end 304.188114 -301.99965)
		(width 0.14478)
		(layer "In2.Cu")
		(net "M_C_CPU0_SB_DQ<17>")
	)
	(segment
		(start 300.482508 -301.070772)
		(end 300.320964 -301.232316)
		(width 0.14478)
		(layer "In2.Cu")
		(net "M_C_CPU0_SB_DQ<17>")
	)
	(segment
		(start 294.54221 -302.114712)
		(end 294.54221 -302.525684)
		(width 0.14478)
		(layer "In2.Cu")
		(net "M_C_CPU0_SB_DQ<17>")
	)
	(segment
		(start 308.490112 -301.234856)
		(end 308.490112 -301.298356)
		(width 0.14478)
		(layer "In2.Cu")
		(net "M_C_CPU0_SB_DQ<17>")
	)
	(segment
		(start 303.941988 -301.99965)
		(end 303.6316 -302.310038)
		(width 0.14478)
		(layer "In2.Cu")
		(net "M_C_CPU0_SB_DQ<17>")
	)
	(segment
		(start 309.041546 -301.298356)
		(end 309.041546 -301.234856)
		(width 0.14478)
		(layer "In2.Cu")
		(net "M_C_CPU0_SB_DQ<17>")
	)
	(segment
		(start 317.525654 -291.34181)
		(end 317.525654 -294.717216)
		(width 0.14478)
		(layer "In2.Cu")
		(net "M_C_CPU0_SB_DQ<17>")
	)
	(segment
		(start 343.288112 -284.938724)
		(end 343.27973 -284.94355)
		(width 0.0889)
		(layer "In2.Cu")
		(net "M_C_CPU0_SB_DQ<17>")
	)
	(segment
		(start 304.188114 -301.99965)
		(end 303.941988 -301.99965)
		(width 0.14478)
		(layer "In2.Cu")
		(net "M_C_CPU0_SB_DQ<17>")
	)
	(segment
		(start 309.20309 -301.4599)
		(end 309.041546 -301.298356)
		(width 0.14478)
		(layer "In2.Cu")
		(net "M_C_CPU0_SB_DQ<17>")
	)
	(segment
		(start 308.490112 -301.298356)
		(end 308.328568 -301.4599)
		(width 0.14478)
		(layer "In2.Cu")
		(net "M_C_CPU0_SB_DQ<17>")
	)
	(segment
		(start 300.15942 -301.4599)
		(end 298.395136 -301.4599)
		(width 0.14478)
		(layer "In2.Cu")
		(net "M_C_CPU0_SB_DQ<17>")
	)
	(segment
		(start 293.98595 -302.089312)
		(end 293.823136 -301.926498)
		(width 0.14478)
		(layer "In2.Cu")
		(net "M_C_CPU0_SB_DQ<17>")
	)
	(segment
		(start 309.041546 -301.234856)
		(end 308.880002 -301.073312)
		(width 0.14478)
		(layer "In2.Cu")
		(net "M_C_CPU0_SB_DQ<17>")
	)
	(segment
		(start 300.872398 -301.232316)
		(end 300.710854 -301.070772)
		(width 0.14478)
		(layer "In2.Cu")
		(net "M_C_CPU0_SB_DQ<17>")
	)
	(segment
		(start 330.702412 -284.94355)
		(end 330.69403 -284.938724)
		(width 0.0889)
		(layer "In2.Cu")
		(net "M_C_CPU0_SB_DQ<17>")
	)
	(segment
		(start 296.850054 -302.210724)
		(end 296.56024 -301.92091)
		(width 0.14478)
		(layer "In2.Cu")
		(net "M_C_CPU0_SB_DQ<17>")
	)
	(segment
		(start 313.673236 -297.511978)
		(end 313.445144 -297.51147)
		(width 0.14478)
		(layer "In2.Cu")
		(net "M_C_CPU0_SB_DQ<17>")
	)
	(segment
		(start 293.27983 -302.672496)
		(end 293.067486 -302.672496)
		(width 0.14478)
		(layer "In2.Cu")
		(net "M_C_CPU0_SB_DQ<17>")
	)
	(segment
		(start 308.328568 -301.4599)
		(end 307.00472 -301.4599)
		(width 0.14478)
		(layer "In2.Cu")
		(net "M_C_CPU0_SB_DQ<17>")
	)
	(segment
		(start 304.865786 -302.310038)
		(end 304.498502 -302.310038)
		(width 0.14478)
		(layer "In2.Cu")
		(net "M_C_CPU0_SB_DQ<17>")
	)
	(segment
		(start 300.872398 -301.298356)
		(end 300.872398 -301.232316)
		(width 0.14478)
		(layer "In2.Cu")
		(net "M_C_CPU0_SB_DQ<17>")
	)
	(segment
		(start 306.681632 -301.070772)
		(end 306.453286 -301.070772)
		(width 0.14478)
		(layer "In2.Cu")
		(net "M_C_CPU0_SB_DQ<17>")
	)
	(segment
		(start 344.041222 -284.616144)
		(end 343.887044 -284.881574)
		(width 0.0889)
		(layer "In2.Cu")
		(net "M_C_CPU0_SB_DQ<17>")
	)
	(segment
		(start 293.98595 -302.525684)
		(end 293.98595 -302.089312)
		(width 0.14478)
		(layer "In2.Cu")
		(net "M_C_CPU0_SB_DQ<17>")
	)
	(segment
		(start 340.102444 -284.94355)
		(end 340.094062 -284.938724)
		(width 0.0889)
		(layer "In2.Cu")
		(net "M_C_CPU0_SB_DQ<17>")
	)
	(segment
		(start 328.248264 -284.938724)
		(end 328.239882 -284.94355)
		(width 0.0889)
		(layer "In2.Cu")
		(net "M_C_CPU0_SB_DQ<17>")
	)
	(segment
		(start 306.291742 -301.298356)
		(end 306.130198 -301.4599)
		(width 0.14478)
		(layer "In2.Cu")
		(net "M_C_CPU0_SB_DQ<17>")
	)
	(segment
		(start 296.56024 -301.92091)
		(end 296.329608 -301.92091)
		(width 0.14478)
		(layer "In2.Cu")
		(net "M_C_CPU0_SB_DQ<17>")
	)
	(segment
		(start 295.535858 -302.310038)
		(end 295.17213 -301.94631)
		(width 0.14478)
		(layer "In2.Cu")
		(net "M_C_CPU0_SB_DQ<17>")
	)
	(segment
		(start 315.469778 -296.773092)
		(end 314.186062 -296.773092)
		(width 0.14478)
		(layer "In2.Cu")
		(net "M_C_CPU0_SB_DQ<17>")
	)
	(segment
		(start 301.197264 -301.4599)
		(end 301.033942 -301.4599)
		(width 0.14478)
		(layer "In2.Cu")
		(net "M_C_CPU0_SB_DQ<17>")
	)
	(segment
		(start 341.042498 -284.94355)
		(end 341.034116 -284.938724)
		(width 0.0889)
		(layer "In2.Cu")
		(net "M_C_CPU0_SB_DQ<17>")
	)
	(segment
		(start 314.165742 -297.453558)
		(end 314.00369 -297.615102)
		(width 0.14478)
		(layer "In2.Cu")
		(net "M_C_CPU0_SB_DQ<17>")
	)
	(segment
		(start 323.942964 -285.37789)
		(end 323.489574 -285.37789)
		(width 0.14478)
		(layer "In2.Cu")
		(net "M_C_CPU0_SB_DQ<17>")
	)
	(segment
		(start 314.186062 -296.773092)
		(end 314.064396 -296.89425)
		(width 0.14478)
		(layer "In2.Cu")
		(net "M_C_CPU0_SB_DQ<17>")
	)
	(segment
		(start 326.432672 -284.902148)
		(end 325.473314 -285.37789)
		(width 0.0889)
		(layer "In2.Cu")
		(net "M_C_CPU0_SB_DQ<17>")
	)
	(segment
		(start 313.775598 -297.614594)
		(end 313.673236 -297.511978)
		(width 0.14478)
		(layer "In2.Cu")
		(net "M_C_CPU0_SB_DQ<17>")
	)
	(segment
		(start 306.843176 -301.298356)
		(end 306.843176 -301.232316)
		(width 0.14478)
		(layer "In2.Cu")
		(net "M_C_CPU0_SB_DQ<17>")
	)
	(segment
		(start 302.047402 -302.310038)
		(end 301.197264 -301.4599)
		(width 0.14478)
		(layer "In2.Cu")
		(net "M_C_CPU0_SB_DQ<17>")
	)
	(segment
		(start 295.94048 -302.310038)
		(end 295.535858 -302.310038)
		(width 0.14478)
		(layer "In2.Cu")
		(net "M_C_CPU0_SB_DQ<17>")
	)
	(segment
		(start 293.823136 -301.926498)
		(end 293.592504 -301.926498)
		(width 0.14478)
		(layer "In2.Cu")
		(net "M_C_CPU0_SB_DQ<17>")
	)
	(segment
		(start 293.592504 -301.926498)
		(end 293.42969 -302.089312)
		(width 0.14478)
		(layer "In2.Cu")
		(net "M_C_CPU0_SB_DQ<17>")
	)
	(segment
		(start 314.16625 -297.225212)
		(end 314.165742 -297.453558)
		(width 0.14478)
		(layer "In2.Cu")
		(net "M_C_CPU0_SB_DQ<17>")
	)
	(segment
		(start 330.128118 -284.938724)
		(end 330.119736 -284.94355)
		(width 0.0889)
		(layer "In2.Cu")
		(net "M_C_CPU0_SB_DQ<17>")
	)
	(segment
		(start 296.329608 -301.92091)
		(end 295.94048 -302.310038)
		(width 0.14478)
		(layer "In2.Cu")
		(net "M_C_CPU0_SB_DQ<17>")
	)
	(segment
		(start 309.48249 -301.4599)
		(end 309.20309 -301.4599)
		(width 0.14478)
		(layer "In2.Cu")
		(net "M_C_CPU0_SB_DQ<17>")
	)
	(segment
		(start 308.880002 -301.073312)
		(end 308.651656 -301.073312)
		(width 0.14478)
		(layer "In2.Cu")
		(net "M_C_CPU0_SB_DQ<17>")
	)
	(segment
		(start 314.063888 -297.122596)
		(end 314.16625 -297.225212)
		(width 0.14478)
		(layer "In2.Cu")
		(net "M_C_CPU0_SB_DQ<17>")
	)
	(segment
		(start 306.291742 -301.232316)
		(end 306.291742 -301.298356)
		(width 0.14478)
		(layer "In2.Cu")
		(net "M_C_CPU0_SB_DQ<17>")
	)
	(segment
		(start 308.651656 -301.073312)
		(end 308.490112 -301.234856)
		(width 0.14478)
		(layer "In2.Cu")
		(net "M_C_CPU0_SB_DQ<17>")
	)
	(segment
		(start 296.999914 -302.643032)
		(end 296.850054 -302.493172)
		(width 0.14478)
		(layer "In2.Cu")
		(net "M_C_CPU0_SB_DQ<17>")
	)
	(segment
		(start 293.067486 -302.672496)
		(end 292.280086 -301.885096)
		(width 0.14478)
		(layer "In2.Cu")
		(net "M_C_CPU0_SB_DQ<17>")
	)
	(segment
		(start 326.65162 -284.86227)
		(end 326.60336 -284.86227)
		(width 0.0889)
		(layer "In2.Cu")
		(net "M_C_CPU0_SB_DQ<17>")
	)
	(segment
		(start 303.6316 -302.310038)
		(end 302.047402 -302.310038)
		(width 0.14478)
		(layer "In2.Cu")
		(net "M_C_CPU0_SB_DQ<17>")
	)
	(segment
		(start 305.715924 -301.4599)
		(end 304.865786 -302.310038)
		(width 0.14478)
		(layer "In2.Cu")
		(net "M_C_CPU0_SB_DQ<17>")
	)
	(segment
		(start 314.00369 -297.615102)
		(end 313.775598 -297.614594)
		(width 0.14478)
		(layer "In2.Cu")
		(net "M_C_CPU0_SB_DQ<17>")
	)
	(segment
		(start 300.320964 -301.298356)
		(end 300.15942 -301.4599)
		(width 0.14478)
		(layer "In2.Cu")
		(net "M_C_CPU0_SB_DQ<17>")
	)
	(segment
		(start 339.52815 -284.938724)
		(end 339.519768 -284.94355)
		(width 0.0889)
		(layer "In2.Cu")
		(net "M_C_CPU0_SB_DQ<17>")
	)
	(segment
		(start 306.843176 -301.232316)
		(end 306.681632 -301.070772)
		(width 0.14478)
		(layer "In2.Cu")
		(net "M_C_CPU0_SB_DQ<17>")
	)
	(segment
		(start 335.402428 -284.94355)
		(end 335.394046 -284.938724)
		(width 0.0889)
		(layer "In2.Cu")
		(net "M_C_CPU0_SB_DQ<17>")
	)
	(segment
		(start 298.395136 -301.4599)
		(end 297.212004 -302.643032)
		(width 0.14478)
		(layer "In2.Cu")
		(net "M_C_CPU0_SB_DQ<17>")
	)
	(segment
		(start 294.54221 -302.525684)
		(end 294.379396 -302.688498)
		(width 0.14478)
		(layer "In2.Cu")
		(net "M_C_CPU0_SB_DQ<17>")
	)
	(segment
		(start 295.17213 -301.94631)
		(end 294.710612 -301.94631)
		(width 0.14478)
		(layer "In2.Cu")
		(net "M_C_CPU0_SB_DQ<17>")
	)
	(segment
		(start 306.130198 -301.4599)
		(end 305.715924 -301.4599)
		(width 0.14478)
		(layer "In2.Cu")
		(net "M_C_CPU0_SB_DQ<17>")
	)
	(segment
		(start 294.710612 -301.94631)
		(end 294.54221 -302.114712)
		(width 0.14478)
		(layer "In2.Cu")
		(net "M_C_CPU0_SB_DQ<17>")
	)
	(segment
		(start 325.473314 -285.37789)
		(end 323.942964 -285.37789)
		(width 0.0889)
		(layer "In2.Cu")
		(net "M_C_CPU0_SB_DQ<17>")
	)
	(segment
		(start 314.064396 -296.89425)
		(end 314.063888 -297.122596)
		(width 0.14478)
		(layer "In2.Cu")
		(net "M_C_CPU0_SB_DQ<17>")
	)
	(segment
		(start 334.828134 -284.938724)
		(end 334.819752 -284.94355)
		(width 0.0889)
		(layer "In2.Cu")
		(net "M_C_CPU0_SB_DQ<17>")
	)
	(segment
		(start 323.489574 -285.37789)
		(end 317.525654 -291.34181)
		(width 0.14478)
		(layer "In2.Cu")
		(net "M_C_CPU0_SB_DQ<17>")
	)
	(segment
		(start 293.42969 -302.089312)
		(end 293.42969 -302.522636)
		(width 0.14478)
		(layer "In2.Cu")
		(net "M_C_CPU0_SB_DQ<17>")
	)
	(segment
		(start 313.445144 -297.51147)
		(end 309.48249 -301.4599)
		(width 0.14478)
		(layer "In2.Cu")
		(net "M_C_CPU0_SB_DQ<17>")
	)
	(segment
		(start 300.710854 -301.070772)
		(end 300.482508 -301.070772)
		(width 0.14478)
		(layer "In2.Cu")
		(net "M_C_CPU0_SB_DQ<17>")
	)
	(arc
		(start 326.60336 -284.86227)
		(mid 326.515705 -284.872315)
		(end 326.432672 -284.902148)
		(width 0.0889)
		(layer "In2.Cu")
		(net "M_C_CPU0_SB_DQ<17>")
	)
	(arc
		(start 337.648042 -284.938724)
		(mid 337.461098 -284.988979)
		(end 337.274154 -284.938724)
		(width 0.0889)
		(layer "In2.Cu")
		(net "M_C_CPU0_SB_DQ<17>")
	)
	(arc
		(start 336.708242 -284.938724)
		(mid 336.525991 -284.989074)
		(end 336.342482 -284.94355)
		(width 0.0889)
		(layer "In2.Cu")
		(net "M_C_CPU0_SB_DQ<17>")
	)
	(arc
		(start 342.348058 -284.938724)
		(mid 342.161114 -284.988979)
		(end 341.97417 -284.938724)
		(width 0.0889)
		(layer "In2.Cu")
		(net "M_C_CPU0_SB_DQ<17>")
	)
	(arc
		(start 327.873614 -284.938724)
		(mid 327.598908 -284.86236)
		(end 327.321926 -284.930088)
		(width 0.0889)
		(layer "In2.Cu")
		(net "M_C_CPU0_SB_DQ<17>")
	)
	(arc
		(start 333.513938 -284.938724)
		(mid 333.230982 -284.862547)
		(end 332.948026 -284.938724)
		(width 0.0889)
		(layer "In2.Cu")
		(net "M_C_CPU0_SB_DQ<17>")
	)
	(arc
		(start 327.307194 -284.938724)
		(mid 327.128207 -284.988894)
		(end 326.947276 -284.946344)
		(width 0.0889)
		(layer "In2.Cu")
		(net "M_C_CPU0_SB_DQ<17>")
	)
	(arc
		(start 339.154008 -284.938724)
		(mid 338.871052 -284.862547)
		(end 338.588096 -284.938724)
		(width 0.0889)
		(layer "In2.Cu")
		(net "M_C_CPU0_SB_DQ<17>")
	)
	(arc
		(start 341.97417 -284.938724)
		(mid 341.691214 -284.862547)
		(end 341.408258 -284.938724)
		(width 0.0889)
		(layer "In2.Cu")
		(net "M_C_CPU0_SB_DQ<17>")
	)
	(arc
		(start 334.453992 -284.938724)
		(mid 334.171036 -284.862547)
		(end 333.88808 -284.938724)
		(width 0.0889)
		(layer "In2.Cu")
		(net "M_C_CPU0_SB_DQ<17>")
	)
	(arc
		(start 331.068172 -284.938724)
		(mid 330.885921 -284.989074)
		(end 330.702412 -284.94355)
		(width 0.0889)
		(layer "In2.Cu")
		(net "M_C_CPU0_SB_DQ<17>")
	)
	(arc
		(start 332.948026 -284.938724)
		(mid 332.761082 -284.988979)
		(end 332.574138 -284.938724)
		(width 0.0889)
		(layer "In2.Cu")
		(net "M_C_CPU0_SB_DQ<17>")
	)
	(arc
		(start 329.188064 -284.938724)
		(mid 329.00112 -284.988979)
		(end 328.814176 -284.938724)
		(width 0.0889)
		(layer "In2.Cu")
		(net "M_C_CPU0_SB_DQ<17>")
	)
	(arc
		(start 339.519768 -284.94355)
		(mid 339.33626 -284.989044)
		(end 339.154008 -284.938724)
		(width 0.0889)
		(layer "In2.Cu")
		(net "M_C_CPU0_SB_DQ<17>")
	)
	(arc
		(start 326.663812 -284.86227)
		(mid 326.657716 -284.862237)
		(end 326.65162 -284.86227)
		(width 0.0889)
		(layer "In2.Cu")
		(net "M_C_CPU0_SB_DQ<17>")
	)
	(arc
		(start 334.819752 -284.94355)
		(mid 334.636244 -284.989044)
		(end 334.453992 -284.938724)
		(width 0.0889)
		(layer "In2.Cu")
		(net "M_C_CPU0_SB_DQ<17>")
	)
	(arc
		(start 342.91397 -284.938724)
		(mid 342.631014 -284.862547)
		(end 342.348058 -284.938724)
		(width 0.0889)
		(layer "In2.Cu")
		(net "M_C_CPU0_SB_DQ<17>")
	)
	(arc
		(start 332.008226 -284.938724)
		(mid 331.825975 -284.989074)
		(end 331.642466 -284.94355)
		(width 0.0889)
		(layer "In2.Cu")
		(net "M_C_CPU0_SB_DQ<17>")
	)
	(arc
		(start 338.213954 -284.938724)
		(mid 337.930998 -284.862547)
		(end 337.648042 -284.938724)
		(width 0.0889)
		(layer "In2.Cu")
		(net "M_C_CPU0_SB_DQ<17>")
	)
	(arc
		(start 341.034116 -284.938724)
		(mid 340.75116 -284.862547)
		(end 340.468204 -284.938724)
		(width 0.0889)
		(layer "In2.Cu")
		(net "M_C_CPU0_SB_DQ<17>")
	)
	(arc
		(start 335.394046 -284.938724)
		(mid 335.11109 -284.862547)
		(end 334.828134 -284.938724)
		(width 0.0889)
		(layer "In2.Cu")
		(net "M_C_CPU0_SB_DQ<17>")
	)
	(arc
		(start 338.579714 -284.94355)
		(mid 338.396206 -284.989044)
		(end 338.213954 -284.938724)
		(width 0.0889)
		(layer "In2.Cu")
		(net "M_C_CPU0_SB_DQ<17>")
	)
	(arc
		(start 328.814176 -284.938724)
		(mid 328.53122 -284.862547)
		(end 328.248264 -284.938724)
		(width 0.0889)
		(layer "In2.Cu")
		(net "M_C_CPU0_SB_DQ<17>")
	)
	(arc
		(start 330.119736 -284.94355)
		(mid 329.936228 -284.989044)
		(end 329.753976 -284.938724)
		(width 0.0889)
		(layer "In2.Cu")
		(net "M_C_CPU0_SB_DQ<17>")
	)
	(arc
		(start 341.408258 -284.938724)
		(mid 341.226007 -284.989074)
		(end 341.042498 -284.94355)
		(width 0.0889)
		(layer "In2.Cu")
		(net "M_C_CPU0_SB_DQ<17>")
	)
	(arc
		(start 343.27973 -284.94355)
		(mid 343.096222 -284.989044)
		(end 342.91397 -284.938724)
		(width 0.0889)
		(layer "In2.Cu")
		(net "M_C_CPU0_SB_DQ<17>")
	)
	(arc
		(start 333.879698 -284.94355)
		(mid 333.69619 -284.989044)
		(end 333.513938 -284.938724)
		(width 0.0889)
		(layer "In2.Cu")
		(net "M_C_CPU0_SB_DQ<17>")
	)
	(arc
		(start 328.239882 -284.94355)
		(mid 328.05612 -284.989166)
		(end 327.873614 -284.938724)
		(width 0.0889)
		(layer "In2.Cu")
		(net "M_C_CPU0_SB_DQ<17>")
	)
	(arc
		(start 337.274154 -284.938724)
		(mid 336.991198 -284.862547)
		(end 336.708242 -284.938724)
		(width 0.0889)
		(layer "In2.Cu")
		(net "M_C_CPU0_SB_DQ<17>")
	)
	(arc
		(start 330.69403 -284.938724)
		(mid 330.411074 -284.862547)
		(end 330.128118 -284.938724)
		(width 0.0889)
		(layer "In2.Cu")
		(net "M_C_CPU0_SB_DQ<17>")
	)
	(arc
		(start 340.468204 -284.938724)
		(mid 340.285953 -284.989074)
		(end 340.102444 -284.94355)
		(width 0.0889)
		(layer "In2.Cu")
		(net "M_C_CPU0_SB_DQ<17>")
	)
	(arc
		(start 331.634084 -284.938724)
		(mid 331.351128 -284.862547)
		(end 331.068172 -284.938724)
		(width 0.0889)
		(layer "In2.Cu")
		(net "M_C_CPU0_SB_DQ<17>")
	)
	(arc
		(start 326.947276 -284.946344)
		(mid 326.811148 -284.885424)
		(end 326.663812 -284.86227)
		(width 0.0889)
		(layer "In2.Cu")
		(net "M_C_CPU0_SB_DQ<17>")
	)
	(arc
		(start 343.790778 -284.906974)
		(mid 343.535713 -284.863623)
		(end 343.288112 -284.938724)
		(width 0.0889)
		(layer "In2.Cu")
		(net "M_C_CPU0_SB_DQ<17>")
	)
	(arc
		(start 329.753976 -284.938724)
		(mid 329.47102 -284.862547)
		(end 329.188064 -284.938724)
		(width 0.0889)
		(layer "In2.Cu")
		(net "M_C_CPU0_SB_DQ<17>")
	)
	(arc
		(start 336.3341 -284.938724)
		(mid 336.051144 -284.862547)
		(end 335.768188 -284.938724)
		(width 0.0889)
		(layer "In2.Cu")
		(net "M_C_CPU0_SB_DQ<17>")
	)
	(arc
		(start 332.574138 -284.938724)
		(mid 332.291182 -284.862547)
		(end 332.008226 -284.938724)
		(width 0.0889)
		(layer "In2.Cu")
		(net "M_C_CPU0_SB_DQ<17>")
	)
	(arc
		(start 340.094062 -284.938724)
		(mid 339.811106 -284.862547)
		(end 339.52815 -284.938724)
		(width 0.0889)
		(layer "In2.Cu")
		(net "M_C_CPU0_SB_DQ<17>")
	)
	(arc
		(start 335.768188 -284.938724)
		(mid 335.585937 -284.989074)
		(end 335.402428 -284.94355)
		(width 0.0889)
		(layer "In2.Cu")
		(net "M_C_CPU0_SB_DQ<17>")
	)
	(segment
		(start 343.097866 -283.5402)
		(end 342.631014 -283.806138)
		(width 0.10668)
		(layer "F.Cu")
		(net "M_C_CPU0_SB_DQ<16>")
	)
	(segment
		(start 315.198506 -294.652446)
		(end 314.970414 -294.652446)
		(width 0.14478)
		(layer "In2.Cu")
		(net "M_C_CPU0_SB_DQ<16>")
	)
	(segment
		(start 324.655434 -284.708346)
		(end 324.415658 -284.46857)
		(width 0.0889)
		(layer "In2.Cu")
		(net "M_C_CPU0_SB_DQ<16>")
	)
	(segment
		(start 337.178142 -284.128718)
		(end 337.16976 -284.133544)
		(width 0.0889)
		(layer "In2.Cu")
		(net "M_C_CPU0_SB_DQ<16>")
	)
	(segment
		(start 328.718164 -284.128718)
		(end 328.709782 -284.133544)
		(width 0.0889)
		(layer "In2.Cu")
		(net "M_C_CPU0_SB_DQ<16>")
	)
	(segment
		(start 294.14343 -300.98111)
		(end 293.980616 -300.818296)
		(width 0.14478)
		(layer "In2.Cu")
		(net "M_C_CPU0_SB_DQ<16>")
	)
	(segment
		(start 341.878158 -284.128718)
		(end 341.869776 -284.133544)
		(width 0.0889)
		(layer "In2.Cu")
		(net "M_C_CPU0_SB_DQ<16>")
	)
	(segment
		(start 297.313858 -301.007272)
		(end 297.085512 -301.007272)
		(width 0.14478)
		(layer "In2.Cu")
		(net "M_C_CPU0_SB_DQ<16>")
	)
	(segment
		(start 294.69969 -300.32071)
		(end 294.536876 -300.483524)
		(width 0.14478)
		(layer "In2.Cu")
		(net "M_C_CPU0_SB_DQ<16>")
	)
	(segment
		(start 305.242214 -300.61027)
		(end 305.097434 -300.61027)
		(width 0.14478)
		(layer "In2.Cu")
		(net "M_C_CPU0_SB_DQ<16>")
	)
	(segment
		(start 314.418218 -295.432734)
		(end 314.190126 -295.432734)
		(width 0.14478)
		(layer "In2.Cu")
		(net "M_C_CPU0_SB_DQ<16>")
	)
	(segment
		(start 304.93589 -300.845728)
		(end 304.774346 -301.007272)
		(width 0.14478)
		(layer "In2.Cu")
		(net "M_C_CPU0_SB_DQ<16>")
	)
	(segment
		(start 337.752436 -284.133544)
		(end 337.744054 -284.128718)
		(width 0.0889)
		(layer "In2.Cu")
		(net "M_C_CPU0_SB_DQ<16>")
	)
	(segment
		(start 314.190126 -295.432734)
		(end 309.862728 -299.760132)
		(width 0.14478)
		(layer "In2.Cu")
		(net "M_C_CPU0_SB_DQ<16>")
	)
	(segment
		(start 309.063644 -300.156372)
		(end 308.835298 -300.156372)
		(width 0.14478)
		(layer "In2.Cu")
		(net "M_C_CPU0_SB_DQ<16>")
	)
	(segment
		(start 293.424356 -300.81728)
		(end 293.274496 -300.96714)
		(width 0.14478)
		(layer "In2.Cu")
		(net "M_C_CPU0_SB_DQ<16>")
	)
	(segment
		(start 332.478126 -284.128718)
		(end 332.469744 -284.133544)
		(width 0.0889)
		(layer "In2.Cu")
		(net "M_C_CPU0_SB_DQ<16>")
	)
	(segment
		(start 308.673754 -299.921676)
		(end 308.51221 -299.760132)
		(width 0.14478)
		(layer "In2.Cu")
		(net "M_C_CPU0_SB_DQ<16>")
	)
	(segment
		(start 314.808362 -294.814498)
		(end 314.808362 -295.04259)
		(width 0.14478)
		(layer "In2.Cu")
		(net "M_C_CPU0_SB_DQ<16>")
	)
	(segment
		(start 308.51221 -299.760132)
		(end 306.092352 -299.760132)
		(width 0.14478)
		(layer "In2.Cu")
		(net "M_C_CPU0_SB_DQ<16>")
	)
	(segment
		(start 329.292458 -284.133544)
		(end 329.284076 -284.128718)
		(width 0.0889)
		(layer "In2.Cu")
		(net "M_C_CPU0_SB_DQ<16>")
	)
	(segment
		(start 316.368938 -293.482014)
		(end 316.621414 -293.73449)
		(width 0.14478)
		(layer "In2.Cu")
		(net "M_C_CPU0_SB_DQ<16>")
	)
	(segment
		(start 294.536876 -300.818296)
		(end 294.374062 -300.98111)
		(width 0.14478)
		(layer "In2.Cu")
		(net "M_C_CPU0_SB_DQ<16>")
	)
	(segment
		(start 325.358506 -284.708346)
		(end 324.655434 -284.708346)
		(width 0.0889)
		(layer "In2.Cu")
		(net "M_C_CPU0_SB_DQ<16>")
	)
	(segment
		(start 293.424356 -300.483524)
		(end 293.424356 -300.81728)
		(width 0.14478)
		(layer "In2.Cu")
		(net "M_C_CPU0_SB_DQ<16>")
	)
	(segment
		(start 315.979048 -293.872158)
		(end 315.750702 -293.872158)
		(width 0.14478)
		(layer "In2.Cu")
		(net "M_C_CPU0_SB_DQ<16>")
	)
	(segment
		(start 293.817802 -300.32071)
		(end 293.58717 -300.32071)
		(width 0.14478)
		(layer "In2.Cu")
		(net "M_C_CPU0_SB_DQ<16>")
	)
	(segment
		(start 297.085512 -301.007272)
		(end 296.923968 -300.845728)
		(width 0.14478)
		(layer "In2.Cu")
		(net "M_C_CPU0_SB_DQ<16>")
	)
	(segment
		(start 327.779888 -284.128464)
		(end 327.758044 -284.14091)
		(width 0.0889)
		(layer "In2.Cu")
		(net "M_C_CPU0_SB_DQ<16>")
	)
	(segment
		(start 342.47709 -284.071568)
		(end 342.381078 -284.096968)
		(width 0.0889)
		(layer "In2.Cu")
		(net "M_C_CPU0_SB_DQ<16>")
	)
	(segment
		(start 314.970414 -294.652446)
		(end 314.808362 -294.814498)
		(width 0.14478)
		(layer "In2.Cu")
		(net "M_C_CPU0_SB_DQ<16>")
	)
	(segment
		(start 294.374062 -300.98111)
		(end 294.14343 -300.98111)
		(width 0.14478)
		(layer "In2.Cu")
		(net "M_C_CPU0_SB_DQ<16>")
	)
	(segment
		(start 297.636946 -300.610016)
		(end 297.475402 -300.77156)
		(width 0.14478)
		(layer "In2.Cu")
		(net "M_C_CPU0_SB_DQ<16>")
	)
	(segment
		(start 294.930322 -300.32071)
		(end 294.69969 -300.32071)
		(width 0.14478)
		(layer "In2.Cu")
		(net "M_C_CPU0_SB_DQ<16>")
	)
	(segment
		(start 333.992474 -284.133544)
		(end 333.984092 -284.128718)
		(width 0.0889)
		(layer "In2.Cu")
		(net "M_C_CPU0_SB_DQ<16>")
	)
	(segment
		(start 309.225188 -299.921676)
		(end 309.225188 -299.994828)
		(width 0.14478)
		(layer "In2.Cu")
		(net "M_C_CPU0_SB_DQ<16>")
	)
	(segment
		(start 296.923968 -300.845728)
		(end 296.923968 -300.77156)
		(width 0.14478)
		(layer "In2.Cu")
		(net "M_C_CPU0_SB_DQ<16>")
	)
	(segment
		(start 314.858654 -295.872916)
		(end 314.418218 -295.432734)
		(width 0.14478)
		(layer "In2.Cu")
		(net "M_C_CPU0_SB_DQ<16>")
	)
	(segment
		(start 331.538072 -284.128718)
		(end 331.52969 -284.133544)
		(width 0.0889)
		(layer "In2.Cu")
		(net "M_C_CPU0_SB_DQ<16>")
	)
	(segment
		(start 308.673754 -299.994828)
		(end 308.673754 -299.921676)
		(width 0.14478)
		(layer "In2.Cu")
		(net "M_C_CPU0_SB_DQ<16>")
	)
	(segment
		(start 304.384456 -300.845728)
		(end 304.384456 -300.771814)
		(width 0.14478)
		(layer "In2.Cu")
		(net "M_C_CPU0_SB_DQ<16>")
	)
	(segment
		(start 315.58865 -294.262302)
		(end 316.029086 -294.702484)
		(width 0.14478)
		(layer "In2.Cu")
		(net "M_C_CPU0_SB_DQ<16>")
	)
	(segment
		(start 301.838614 -300.61027)
		(end 300.988476 -299.760132)
		(width 0.14478)
		(layer "In2.Cu")
		(net "M_C_CPU0_SB_DQ<16>")
	)
	(segment
		(start 293.58717 -300.32071)
		(end 293.424356 -300.483524)
		(width 0.14478)
		(layer "In2.Cu")
		(net "M_C_CPU0_SB_DQ<16>")
	)
	(segment
		(start 315.58865 -294.03421)
		(end 315.58865 -294.262302)
		(width 0.14478)
		(layer "In2.Cu")
		(net "M_C_CPU0_SB_DQ<16>")
	)
	(segment
		(start 300.988476 -299.760132)
		(end 298.629832 -299.760132)
		(width 0.14478)
		(layer "In2.Cu")
		(net "M_C_CPU0_SB_DQ<16>")
	)
	(segment
		(start 304.93589 -300.771814)
		(end 304.93589 -300.845728)
		(width 0.14478)
		(layer "In2.Cu")
		(net "M_C_CPU0_SB_DQ<16>")
	)
	(segment
		(start 297.475402 -300.77156)
		(end 297.475402 -300.845728)
		(width 0.14478)
		(layer "In2.Cu")
		(net "M_C_CPU0_SB_DQ<16>")
	)
	(segment
		(start 324.415658 -284.46857)
		(end 323.901054 -284.46857)
		(width 0.0889)
		(layer "In2.Cu")
		(net "M_C_CPU0_SB_DQ<16>")
	)
	(segment
		(start 327.803764 -284.114494)
		(end 327.779888 -284.128464)
		(width 0.0889)
		(layer "In2.Cu")
		(net "M_C_CPU0_SB_DQ<16>")
	)
	(segment
		(start 309.386732 -299.760132)
		(end 309.225188 -299.921676)
		(width 0.14478)
		(layer "In2.Cu")
		(net "M_C_CPU0_SB_DQ<16>")
	)
	(segment
		(start 315.248798 -295.482772)
		(end 315.248798 -295.710864)
		(width 0.14478)
		(layer "In2.Cu")
		(net "M_C_CPU0_SB_DQ<16>")
	)
	(segment
		(start 304.222912 -300.61027)
		(end 301.838614 -300.61027)
		(width 0.14478)
		(layer "In2.Cu")
		(net "M_C_CPU0_SB_DQ<16>")
	)
	(segment
		(start 294.536876 -300.483524)
		(end 294.536876 -300.818296)
		(width 0.14478)
		(layer "In2.Cu")
		(net "M_C_CPU0_SB_DQ<16>")
	)
	(segment
		(start 316.621414 -293.73449)
		(end 316.621414 -293.962328)
		(width 0.14478)
		(layer "In2.Cu")
		(net "M_C_CPU0_SB_DQ<16>")
	)
	(segment
		(start 293.980616 -300.818296)
		(end 293.980616 -300.483524)
		(width 0.14478)
		(layer "In2.Cu")
		(net "M_C_CPU0_SB_DQ<16>")
	)
	(segment
		(start 338.69249 -284.133544)
		(end 338.684108 -284.128718)
		(width 0.0889)
		(layer "In2.Cu")
		(net "M_C_CPU0_SB_DQ<16>")
	)
	(segment
		(start 342.631014 -283.806138)
		(end 342.47709 -284.071568)
		(width 0.0889)
		(layer "In2.Cu")
		(net "M_C_CPU0_SB_DQ<16>")
	)
	(segment
		(start 316.616334 -293.006526)
		(end 316.368938 -293.253922)
		(width 0.14478)
		(layer "In2.Cu")
		(net "M_C_CPU0_SB_DQ<16>")
	)
	(segment
		(start 297.779948 -300.610016)
		(end 297.636946 -300.610016)
		(width 0.14478)
		(layer "In2.Cu")
		(net "M_C_CPU0_SB_DQ<16>")
	)
	(segment
		(start 298.629832 -299.760132)
		(end 297.779948 -300.610016)
		(width 0.14478)
		(layer "In2.Cu")
		(net "M_C_CPU0_SB_DQ<16>")
	)
	(segment
		(start 316.368938 -293.253922)
		(end 316.368938 -293.482014)
		(width 0.14478)
		(layer "In2.Cu")
		(net "M_C_CPU0_SB_DQ<16>")
	)
	(segment
		(start 293.274496 -300.96714)
		(end 293.062152 -300.96714)
		(width 0.14478)
		(layer "In2.Cu")
		(net "M_C_CPU0_SB_DQ<16>")
	)
	(segment
		(start 336.238088 -284.128718)
		(end 336.229706 -284.133544)
		(width 0.0889)
		(layer "In2.Cu")
		(net "M_C_CPU0_SB_DQ<16>")
	)
	(segment
		(start 333.05242 -284.133544)
		(end 333.044038 -284.128718)
		(width 0.0889)
		(layer "In2.Cu")
		(net "M_C_CPU0_SB_DQ<16>")
	)
	(segment
		(start 309.862728 -299.760132)
		(end 309.386732 -299.760132)
		(width 0.14478)
		(layer "In2.Cu")
		(net "M_C_CPU0_SB_DQ<16>")
	)
	(segment
		(start 315.248798 -295.710864)
		(end 315.086746 -295.872916)
		(width 0.14478)
		(layer "In2.Cu")
		(net "M_C_CPU0_SB_DQ<16>")
	)
	(segment
		(start 316.23127 -294.12438)
		(end 315.979048 -293.872158)
		(width 0.14478)
		(layer "In2.Cu")
		(net "M_C_CPU0_SB_DQ<16>")
	)
	(segment
		(start 315.086746 -295.872916)
		(end 314.858654 -295.872916)
		(width 0.14478)
		(layer "In2.Cu")
		(net "M_C_CPU0_SB_DQ<16>")
	)
	(segment
		(start 315.867034 -295.092628)
		(end 315.638942 -295.092628)
		(width 0.14478)
		(layer "In2.Cu")
		(net "M_C_CPU0_SB_DQ<16>")
	)
	(segment
		(start 297.475402 -300.845728)
		(end 297.313858 -301.007272)
		(width 0.14478)
		(layer "In2.Cu")
		(net "M_C_CPU0_SB_DQ<16>")
	)
	(segment
		(start 293.062152 -300.96714)
		(end 292.280086 -300.185074)
		(width 0.14478)
		(layer "In2.Cu")
		(net "M_C_CPU0_SB_DQ<16>")
	)
	(segment
		(start 316.459362 -294.12438)
		(end 316.23127 -294.12438)
		(width 0.14478)
		(layer "In2.Cu")
		(net "M_C_CPU0_SB_DQ<16>")
	)
	(segment
		(start 327.40727 -284.128718)
		(end 327.379584 -284.112716)
		(width 0.0889)
		(layer "In2.Cu")
		(net "M_C_CPU0_SB_DQ<16>")
	)
	(segment
		(start 323.901054 -284.46857)
		(end 323.106542 -284.46857)
		(width 0.14478)
		(layer "In2.Cu")
		(net "M_C_CPU0_SB_DQ<16>")
	)
	(segment
		(start 295.219628 -300.610016)
		(end 294.930322 -300.32071)
		(width 0.14478)
		(layer "In2.Cu")
		(net "M_C_CPU0_SB_DQ<16>")
	)
	(segment
		(start 326.676258 -284.172914)
		(end 326.651112 -284.172914)
		(width 0.0889)
		(layer "In2.Cu")
		(net "M_C_CPU0_SB_DQ<16>")
	)
	(segment
		(start 316.621414 -293.962328)
		(end 316.459362 -294.12438)
		(width 0.14478)
		(layer "In2.Cu")
		(net "M_C_CPU0_SB_DQ<16>")
	)
	(segment
		(start 309.225188 -299.994828)
		(end 309.063644 -300.156372)
		(width 0.14478)
		(layer "In2.Cu")
		(net "M_C_CPU0_SB_DQ<16>")
	)
	(segment
		(start 304.774346 -301.007272)
		(end 304.546 -301.007272)
		(width 0.14478)
		(layer "In2.Cu")
		(net "M_C_CPU0_SB_DQ<16>")
	)
	(segment
		(start 315.750702 -293.872158)
		(end 315.58865 -294.03421)
		(width 0.14478)
		(layer "In2.Cu")
		(net "M_C_CPU0_SB_DQ<16>")
	)
	(segment
		(start 316.029086 -294.702484)
		(end 316.029086 -294.930576)
		(width 0.14478)
		(layer "In2.Cu")
		(net "M_C_CPU0_SB_DQ<16>")
	)
	(segment
		(start 308.835298 -300.156372)
		(end 308.673754 -299.994828)
		(width 0.14478)
		(layer "In2.Cu")
		(net "M_C_CPU0_SB_DQ<16>")
	)
	(segment
		(start 304.546 -301.007272)
		(end 304.384456 -300.845728)
		(width 0.14478)
		(layer "In2.Cu")
		(net "M_C_CPU0_SB_DQ<16>")
	)
	(segment
		(start 296.923968 -300.77156)
		(end 296.762424 -300.610016)
		(width 0.14478)
		(layer "In2.Cu")
		(net "M_C_CPU0_SB_DQ<16>")
	)
	(segment
		(start 316.616334 -290.958778)
		(end 316.616334 -293.006526)
		(width 0.14478)
		(layer "In2.Cu")
		(net "M_C_CPU0_SB_DQ<16>")
	)
	(segment
		(start 305.097434 -300.61027)
		(end 304.93589 -300.771814)
		(width 0.14478)
		(layer "In2.Cu")
		(net "M_C_CPU0_SB_DQ<16>")
	)
	(segment
		(start 316.029086 -294.930576)
		(end 315.867034 -295.092628)
		(width 0.14478)
		(layer "In2.Cu")
		(net "M_C_CPU0_SB_DQ<16>")
	)
	(segment
		(start 306.092352 -299.760132)
		(end 305.242214 -300.61027)
		(width 0.14478)
		(layer "In2.Cu")
		(net "M_C_CPU0_SB_DQ<16>")
	)
	(segment
		(start 304.384456 -300.771814)
		(end 304.222912 -300.61027)
		(width 0.14478)
		(layer "In2.Cu")
		(net "M_C_CPU0_SB_DQ<16>")
	)
	(segment
		(start 296.762424 -300.610016)
		(end 295.219628 -300.610016)
		(width 0.14478)
		(layer "In2.Cu")
		(net "M_C_CPU0_SB_DQ<16>")
	)
	(segment
		(start 323.106542 -284.46857)
		(end 316.616334 -290.958778)
		(width 0.14478)
		(layer "In2.Cu")
		(net "M_C_CPU0_SB_DQ<16>")
	)
	(segment
		(start 315.638942 -295.092628)
		(end 315.198506 -294.652446)
		(width 0.14478)
		(layer "In2.Cu")
		(net "M_C_CPU0_SB_DQ<16>")
	)
	(segment
		(start 314.808362 -295.04259)
		(end 315.248798 -295.482772)
		(width 0.14478)
		(layer "In2.Cu")
		(net "M_C_CPU0_SB_DQ<16>")
	)
	(segment
		(start 340.938104 -284.128718)
		(end 340.929722 -284.133544)
		(width 0.0889)
		(layer "In2.Cu")
		(net "M_C_CPU0_SB_DQ<16>")
	)
	(segment
		(start 293.980616 -300.483524)
		(end 293.817802 -300.32071)
		(width 0.14478)
		(layer "In2.Cu")
		(net "M_C_CPU0_SB_DQ<16>")
	)
	(arc
		(start 334.358234 -284.128718)
		(mid 334.175983 -284.179068)
		(end 333.992474 -284.133544)
		(width 0.0889)
		(layer "In2.Cu")
		(net "M_C_CPU0_SB_DQ<16>")
	)
	(arc
		(start 329.658218 -284.128718)
		(mid 329.475967 -284.179068)
		(end 329.292458 -284.133544)
		(width 0.0889)
		(layer "In2.Cu")
		(net "M_C_CPU0_SB_DQ<16>")
	)
	(arc
		(start 326.194928 -284.36189)
		(mid 325.811174 -284.618306)
		(end 325.358506 -284.708346)
		(width 0.0889)
		(layer "In2.Cu")
		(net "M_C_CPU0_SB_DQ<16>")
	)
	(arc
		(start 340.563962 -284.128718)
		(mid 340.281006 -284.052541)
		(end 339.99805 -284.128718)
		(width 0.0889)
		(layer "In2.Cu")
		(net "M_C_CPU0_SB_DQ<16>")
	)
	(arc
		(start 332.103984 -284.128718)
		(mid 331.821028 -284.052541)
		(end 331.538072 -284.128718)
		(width 0.0889)
		(layer "In2.Cu")
		(net "M_C_CPU0_SB_DQ<16>")
	)
	(arc
		(start 326.651112 -284.172914)
		(mid 326.40422 -284.222024)
		(end 326.194928 -284.36189)
		(width 0.0889)
		(layer "In2.Cu")
		(net "M_C_CPU0_SB_DQ<16>")
	)
	(arc
		(start 336.804 -284.128718)
		(mid 336.521044 -284.052541)
		(end 336.238088 -284.128718)
		(width 0.0889)
		(layer "In2.Cu")
		(net "M_C_CPU0_SB_DQ<16>")
	)
	(arc
		(start 333.984092 -284.128718)
		(mid 333.701136 -284.052541)
		(end 333.41818 -284.128718)
		(width 0.0889)
		(layer "In2.Cu")
		(net "M_C_CPU0_SB_DQ<16>")
	)
	(arc
		(start 341.869776 -284.133544)
		(mid 341.686268 -284.179038)
		(end 341.504016 -284.128718)
		(width 0.0889)
		(layer "In2.Cu")
		(net "M_C_CPU0_SB_DQ<16>")
	)
	(arc
		(start 335.863946 -284.128718)
		(mid 335.58099 -284.052541)
		(end 335.298034 -284.128718)
		(width 0.0889)
		(layer "In2.Cu")
		(net "M_C_CPU0_SB_DQ<16>")
	)
	(arc
		(start 340.929722 -284.133544)
		(mid 340.746214 -284.179038)
		(end 340.563962 -284.128718)
		(width 0.0889)
		(layer "In2.Cu")
		(net "M_C_CPU0_SB_DQ<16>")
	)
	(arc
		(start 333.41818 -284.128718)
		(mid 333.235929 -284.179068)
		(end 333.05242 -284.133544)
		(width 0.0889)
		(layer "In2.Cu")
		(net "M_C_CPU0_SB_DQ<16>")
	)
	(arc
		(start 327.758044 -284.14091)
		(mid 327.581116 -284.178738)
		(end 327.40727 -284.128718)
		(width 0.0889)
		(layer "In2.Cu")
		(net "M_C_CPU0_SB_DQ<16>")
	)
	(arc
		(start 339.624162 -284.128718)
		(mid 339.341206 -284.052541)
		(end 339.05825 -284.128718)
		(width 0.0889)
		(layer "In2.Cu")
		(net "M_C_CPU0_SB_DQ<16>")
	)
	(arc
		(start 331.16393 -284.128718)
		(mid 330.880974 -284.052541)
		(end 330.598018 -284.128718)
		(width 0.0889)
		(layer "In2.Cu")
		(net "M_C_CPU0_SB_DQ<16>")
	)
	(arc
		(start 332.469744 -284.133544)
		(mid 332.286236 -284.179038)
		(end 332.103984 -284.128718)
		(width 0.0889)
		(layer "In2.Cu")
		(net "M_C_CPU0_SB_DQ<16>")
	)
	(arc
		(start 337.744054 -284.128718)
		(mid 337.461098 -284.052541)
		(end 337.178142 -284.128718)
		(width 0.0889)
		(layer "In2.Cu")
		(net "M_C_CPU0_SB_DQ<16>")
	)
	(arc
		(start 341.504016 -284.128718)
		(mid 341.22106 -284.052541)
		(end 340.938104 -284.128718)
		(width 0.0889)
		(layer "In2.Cu")
		(net "M_C_CPU0_SB_DQ<16>")
	)
	(arc
		(start 335.298034 -284.128718)
		(mid 335.11109 -284.178973)
		(end 334.924146 -284.128718)
		(width 0.0889)
		(layer "In2.Cu")
		(net "M_C_CPU0_SB_DQ<16>")
	)
	(arc
		(start 342.381078 -284.096968)
		(mid 342.12587 -284.053491)
		(end 341.878158 -284.128718)
		(width 0.0889)
		(layer "In2.Cu")
		(net "M_C_CPU0_SB_DQ<16>")
	)
	(arc
		(start 337.16976 -284.133544)
		(mid 336.986252 -284.179038)
		(end 336.804 -284.128718)
		(width 0.0889)
		(layer "In2.Cu")
		(net "M_C_CPU0_SB_DQ<16>")
	)
	(arc
		(start 338.118196 -284.128718)
		(mid 337.935945 -284.179068)
		(end 337.752436 -284.133544)
		(width 0.0889)
		(layer "In2.Cu")
		(net "M_C_CPU0_SB_DQ<16>")
	)
	(arc
		(start 328.709782 -284.133544)
		(mid 328.526274 -284.179038)
		(end 328.344022 -284.128718)
		(width 0.0889)
		(layer "In2.Cu")
		(net "M_C_CPU0_SB_DQ<16>")
	)
	(arc
		(start 339.05825 -284.128718)
		(mid 338.875999 -284.179068)
		(end 338.69249 -284.133544)
		(width 0.0889)
		(layer "In2.Cu")
		(net "M_C_CPU0_SB_DQ<16>")
	)
	(arc
		(start 329.284076 -284.128718)
		(mid 329.00112 -284.052541)
		(end 328.718164 -284.128718)
		(width 0.0889)
		(layer "In2.Cu")
		(net "M_C_CPU0_SB_DQ<16>")
	)
	(arc
		(start 338.684108 -284.128718)
		(mid 338.401152 -284.052541)
		(end 338.118196 -284.128718)
		(width 0.0889)
		(layer "In2.Cu")
		(net "M_C_CPU0_SB_DQ<16>")
	)
	(arc
		(start 330.598018 -284.128718)
		(mid 330.411074 -284.178973)
		(end 330.22413 -284.128718)
		(width 0.0889)
		(layer "In2.Cu")
		(net "M_C_CPU0_SB_DQ<16>")
	)
	(arc
		(start 327.379584 -284.112716)
		(mid 327.10755 -284.051944)
		(end 326.83958 -284.128718)
		(width 0.0889)
		(layer "In2.Cu")
		(net "M_C_CPU0_SB_DQ<16>")
	)
	(arc
		(start 334.924146 -284.128718)
		(mid 334.64119 -284.052541)
		(end 334.358234 -284.128718)
		(width 0.0889)
		(layer "In2.Cu")
		(net "M_C_CPU0_SB_DQ<16>")
	)
	(arc
		(start 328.344022 -284.128718)
		(mid 328.075702 -284.05261)
		(end 327.803764 -284.114494)
		(width 0.0889)
		(layer "In2.Cu")
		(net "M_C_CPU0_SB_DQ<16>")
	)
	(arc
		(start 326.83958 -284.128718)
		(mid 326.760861 -284.161697)
		(end 326.676258 -284.172914)
		(width 0.0889)
		(layer "In2.Cu")
		(net "M_C_CPU0_SB_DQ<16>")
	)
	(arc
		(start 336.229706 -284.133544)
		(mid 336.046198 -284.179038)
		(end 335.863946 -284.128718)
		(width 0.0889)
		(layer "In2.Cu")
		(net "M_C_CPU0_SB_DQ<16>")
	)
	(arc
		(start 331.52969 -284.133544)
		(mid 331.346182 -284.179038)
		(end 331.16393 -284.128718)
		(width 0.0889)
		(layer "In2.Cu")
		(net "M_C_CPU0_SB_DQ<16>")
	)
	(arc
		(start 339.99805 -284.128718)
		(mid 339.811106 -284.178973)
		(end 339.624162 -284.128718)
		(width 0.0889)
		(layer "In2.Cu")
		(net "M_C_CPU0_SB_DQ<16>")
	)
	(arc
		(start 333.044038 -284.128718)
		(mid 332.761082 -284.052541)
		(end 332.478126 -284.128718)
		(width 0.0889)
		(layer "In2.Cu")
		(net "M_C_CPU0_SB_DQ<16>")
	)
	(arc
		(start 330.22413 -284.128718)
		(mid 329.941174 -284.052541)
		(end 329.658218 -284.128718)
		(width 0.0889)
		(layer "In2.Cu")
		(net "M_C_CPU0_SB_DQ<16>")
	)
	(segment
		(start 344.03792 -283.5402)
		(end 343.571068 -283.806138)
		(width 0.10668)
		(layer "F.Cu")
		(net "M_C_CPU0_SB_DQ<15>")
	)
	(segment
		(start 340.938104 -283.483558)
		(end 340.929722 -283.478732)
		(width 0.0889)
		(layer "In2.Cu")
		(net "M_C_CPU0_SB_DQ<15>")
	)
	(segment
		(start 332.478126 -283.483558)
		(end 332.469744 -283.478732)
		(width 0.0889)
		(layer "In2.Cu")
		(net "M_C_CPU0_SB_DQ<15>")
	)
	(segment
		(start 343.392506 -283.478732)
		(end 343.384124 -283.483558)
		(width 0.0889)
		(layer "In2.Cu")
		(net "M_C_CPU0_SB_DQ<15>")
	)
	(segment
		(start 333.05242 -283.478732)
		(end 333.044038 -283.483558)
		(width 0.0889)
		(layer "In2.Cu")
		(net "M_C_CPU0_SB_DQ<15>")
	)
	(segment
		(start 310.323484 -298.512484)
		(end 308.32552 -298.909994)
		(width 0.14478)
		(layer "In2.Cu")
		(net "M_C_CPU0_SB_DQ<15>")
	)
	(segment
		(start 343.725246 -283.540708)
		(end 343.702894 -283.457396)
		(width 0.0889)
		(layer "In2.Cu")
		(net "M_C_CPU0_SB_DQ<15>")
	)
	(segment
		(start 336.238088 -283.483558)
		(end 336.229706 -283.478732)
		(width 0.0889)
		(layer "In2.Cu")
		(net "M_C_CPU0_SB_DQ<15>")
	)
	(segment
		(start 331.538072 -283.483558)
		(end 331.52969 -283.478732)
		(width 0.0889)
		(layer "In2.Cu")
		(net "M_C_CPU0_SB_DQ<15>")
	)
	(segment
		(start 323.977254 -283.91231)
		(end 322.87591 -283.91231)
		(width 0.14478)
		(layer "In2.Cu")
		(net "M_C_CPU0_SB_DQ<15>")
	)
	(segment
		(start 325.86549 -283.91231)
		(end 323.977254 -283.91231)
		(width 0.0889)
		(layer "In2.Cu")
		(net "M_C_CPU0_SB_DQ<15>")
	)
	(segment
		(start 338.69249 -283.478732)
		(end 338.684108 -283.483558)
		(width 0.0889)
		(layer "In2.Cu")
		(net "M_C_CPU0_SB_DQ<15>")
	)
	(segment
		(start 316.065154 -292.770814)
		(end 310.323484 -298.512484)
		(width 0.14478)
		(layer "In2.Cu")
		(net "M_C_CPU0_SB_DQ<15>")
	)
	(segment
		(start 302.238156 -299.760132)
		(end 301.01286 -299.10532)
		(width 0.14478)
		(layer "In2.Cu")
		(net "M_C_CPU0_SB_DQ<15>")
	)
	(segment
		(start 343.571068 -283.806138)
		(end 343.725246 -283.540708)
		(width 0.0889)
		(layer "In2.Cu")
		(net "M_C_CPU0_SB_DQ<15>")
	)
	(segment
		(start 304.903886 -299.760132)
		(end 302.238156 -299.760132)
		(width 0.14478)
		(layer "In2.Cu")
		(net "M_C_CPU0_SB_DQ<15>")
	)
	(segment
		(start 301.01286 -299.10532)
		(end 300.232826 -298.909994)
		(width 0.14478)
		(layer "In2.Cu")
		(net "M_C_CPU0_SB_DQ<15>")
	)
	(segment
		(start 300.232826 -298.909994)
		(end 299.205904 -298.909994)
		(width 0.14478)
		(layer "In2.Cu")
		(net "M_C_CPU0_SB_DQ<15>")
	)
	(segment
		(start 337.178142 -283.483558)
		(end 337.16976 -283.478732)
		(width 0.0889)
		(layer "In2.Cu")
		(net "M_C_CPU0_SB_DQ<15>")
	)
	(segment
		(start 306.493926 -298.909994)
		(end 304.903886 -299.760132)
		(width 0.14478)
		(layer "In2.Cu")
		(net "M_C_CPU0_SB_DQ<15>")
	)
	(segment
		(start 326.369426 -283.551884)
		(end 326.110346 -283.810964)
		(width 0.0889)
		(layer "In2.Cu")
		(net "M_C_CPU0_SB_DQ<15>")
	)
	(segment
		(start 337.752436 -283.478732)
		(end 337.744054 -283.483558)
		(width 0.0889)
		(layer "In2.Cu")
		(net "M_C_CPU0_SB_DQ<15>")
	)
	(segment
		(start 333.992474 -283.478732)
		(end 333.984092 -283.483558)
		(width 0.0889)
		(layer "In2.Cu")
		(net "M_C_CPU0_SB_DQ<15>")
	)
	(segment
		(start 328.718164 -283.483558)
		(end 328.709782 -283.478732)
		(width 0.0889)
		(layer "In2.Cu")
		(net "M_C_CPU0_SB_DQ<15>")
	)
	(segment
		(start 328.344022 -283.483558)
		(end 328.32929 -283.492194)
		(width 0.0889)
		(layer "In2.Cu")
		(net "M_C_CPU0_SB_DQ<15>")
	)
	(segment
		(start 299.205904 -298.909994)
		(end 297.991784 -299.412914)
		(width 0.14478)
		(layer "In2.Cu")
		(net "M_C_CPU0_SB_DQ<15>")
	)
	(segment
		(start 322.87591 -283.91231)
		(end 316.065154 -290.723066)
		(width 0.14478)
		(layer "In2.Cu")
		(net "M_C_CPU0_SB_DQ<15>")
	)
	(segment
		(start 316.065154 -290.723066)
		(end 316.065154 -292.770814)
		(width 0.14478)
		(layer "In2.Cu")
		(net "M_C_CPU0_SB_DQ<15>")
	)
	(segment
		(start 327.41489 -283.4767)
		(end 327.403206 -283.483558)
		(width 0.0889)
		(layer "In2.Cu")
		(net "M_C_CPU0_SB_DQ<15>")
	)
	(segment
		(start 297.644566 -299.760132)
		(end 288.60496 -299.760132)
		(width 0.14478)
		(layer "In2.Cu")
		(net "M_C_CPU0_SB_DQ<15>")
	)
	(segment
		(start 297.991784 -299.412914)
		(end 297.644566 -299.760132)
		(width 0.14478)
		(layer "In2.Cu")
		(net "M_C_CPU0_SB_DQ<15>")
	)
	(segment
		(start 341.878158 -283.483558)
		(end 341.869776 -283.478732)
		(width 0.0889)
		(layer "In2.Cu")
		(net "M_C_CPU0_SB_DQ<15>")
	)
	(segment
		(start 288.60496 -299.760132)
		(end 288.180018 -299.33519)
		(width 0.14478)
		(layer "In2.Cu")
		(net "M_C_CPU0_SB_DQ<15>")
	)
	(segment
		(start 342.452452 -283.478732)
		(end 342.44407 -283.483558)
		(width 0.0889)
		(layer "In2.Cu")
		(net "M_C_CPU0_SB_DQ<15>")
	)
	(segment
		(start 308.32552 -298.909994)
		(end 306.493926 -298.909994)
		(width 0.14478)
		(layer "In2.Cu")
		(net "M_C_CPU0_SB_DQ<15>")
	)
	(segment
		(start 329.292458 -283.478732)
		(end 329.284076 -283.483558)
		(width 0.0889)
		(layer "In2.Cu")
		(net "M_C_CPU0_SB_DQ<15>")
	)
	(arc
		(start 327.777602 -283.483558)
		(mid 327.597144 -283.433114)
		(end 327.41489 -283.4767)
		(width 0.0889)
		(layer "In2.Cu")
		(net "M_C_CPU0_SB_DQ<15>")
	)
	(arc
		(start 331.16393 -283.483558)
		(mid 330.880974 -283.559735)
		(end 330.598018 -283.483558)
		(width 0.0889)
		(layer "In2.Cu")
		(net "M_C_CPU0_SB_DQ<15>")
	)
	(arc
		(start 339.624162 -283.483558)
		(mid 339.341206 -283.559735)
		(end 339.05825 -283.483558)
		(width 0.0889)
		(layer "In2.Cu")
		(net "M_C_CPU0_SB_DQ<15>")
	)
	(arc
		(start 334.358234 -283.483558)
		(mid 334.175983 -283.433208)
		(end 333.992474 -283.478732)
		(width 0.0889)
		(layer "In2.Cu")
		(net "M_C_CPU0_SB_DQ<15>")
	)
	(arc
		(start 327.403206 -283.483558)
		(mid 327.123778 -283.559724)
		(end 326.84339 -283.487114)
		(width 0.0889)
		(layer "In2.Cu")
		(net "M_C_CPU0_SB_DQ<15>")
	)
	(arc
		(start 328.32929 -283.492194)
		(mid 328.052307 -283.559998)
		(end 327.777602 -283.483558)
		(width 0.0889)
		(layer "In2.Cu")
		(net "M_C_CPU0_SB_DQ<15>")
	)
	(arc
		(start 342.818212 -283.483558)
		(mid 342.635961 -283.433208)
		(end 342.452452 -283.478732)
		(width 0.0889)
		(layer "In2.Cu")
		(net "M_C_CPU0_SB_DQ<15>")
	)
	(arc
		(start 340.563962 -283.483558)
		(mid 340.281006 -283.559735)
		(end 339.99805 -283.483558)
		(width 0.0889)
		(layer "In2.Cu")
		(net "M_C_CPU0_SB_DQ<15>")
	)
	(arc
		(start 333.41818 -283.483558)
		(mid 333.235929 -283.433208)
		(end 333.05242 -283.478732)
		(width 0.0889)
		(layer "In2.Cu")
		(net "M_C_CPU0_SB_DQ<15>")
	)
	(arc
		(start 343.702894 -283.457396)
		(mid 343.545384 -283.434198)
		(end 343.392506 -283.478732)
		(width 0.0889)
		(layer "In2.Cu")
		(net "M_C_CPU0_SB_DQ<15>")
	)
	(arc
		(start 328.709782 -283.478732)
		(mid 328.526274 -283.433238)
		(end 328.344022 -283.483558)
		(width 0.0889)
		(layer "In2.Cu")
		(net "M_C_CPU0_SB_DQ<15>")
	)
	(arc
		(start 329.284076 -283.483558)
		(mid 329.00112 -283.559735)
		(end 328.718164 -283.483558)
		(width 0.0889)
		(layer "In2.Cu")
		(net "M_C_CPU0_SB_DQ<15>")
	)
	(arc
		(start 339.05825 -283.483558)
		(mid 338.875999 -283.433208)
		(end 338.69249 -283.478732)
		(width 0.0889)
		(layer "In2.Cu")
		(net "M_C_CPU0_SB_DQ<15>")
	)
	(arc
		(start 332.469744 -283.478732)
		(mid 332.286236 -283.433238)
		(end 332.103984 -283.483558)
		(width 0.0889)
		(layer "In2.Cu")
		(net "M_C_CPU0_SB_DQ<15>")
	)
	(arc
		(start 337.16976 -283.478732)
		(mid 336.986252 -283.433238)
		(end 336.804 -283.483558)
		(width 0.0889)
		(layer "In2.Cu")
		(net "M_C_CPU0_SB_DQ<15>")
	)
	(arc
		(start 331.52969 -283.478732)
		(mid 331.346182 -283.433238)
		(end 331.16393 -283.483558)
		(width 0.0889)
		(layer "In2.Cu")
		(net "M_C_CPU0_SB_DQ<15>")
	)
	(arc
		(start 342.44407 -283.483558)
		(mid 342.161114 -283.559735)
		(end 341.878158 -283.483558)
		(width 0.0889)
		(layer "In2.Cu")
		(net "M_C_CPU0_SB_DQ<15>")
	)
	(arc
		(start 339.99805 -283.483558)
		(mid 339.811106 -283.433303)
		(end 339.624162 -283.483558)
		(width 0.0889)
		(layer "In2.Cu")
		(net "M_C_CPU0_SB_DQ<15>")
	)
	(arc
		(start 337.744054 -283.483558)
		(mid 337.461098 -283.559735)
		(end 337.178142 -283.483558)
		(width 0.0889)
		(layer "In2.Cu")
		(net "M_C_CPU0_SB_DQ<15>")
	)
	(arc
		(start 333.044038 -283.483558)
		(mid 332.761082 -283.559735)
		(end 332.478126 -283.483558)
		(width 0.0889)
		(layer "In2.Cu")
		(net "M_C_CPU0_SB_DQ<15>")
	)
	(arc
		(start 335.863946 -283.483558)
		(mid 335.58099 -283.559735)
		(end 335.298034 -283.483558)
		(width 0.0889)
		(layer "In2.Cu")
		(net "M_C_CPU0_SB_DQ<15>")
	)
	(arc
		(start 326.84339 -283.487114)
		(mid 326.595513 -283.439728)
		(end 326.369426 -283.551884)
		(width 0.0889)
		(layer "In2.Cu")
		(net "M_C_CPU0_SB_DQ<15>")
	)
	(arc
		(start 341.869776 -283.478732)
		(mid 341.686268 -283.433238)
		(end 341.504016 -283.483558)
		(width 0.0889)
		(layer "In2.Cu")
		(net "M_C_CPU0_SB_DQ<15>")
	)
	(arc
		(start 335.298034 -283.483558)
		(mid 335.11109 -283.433303)
		(end 334.924146 -283.483558)
		(width 0.0889)
		(layer "In2.Cu")
		(net "M_C_CPU0_SB_DQ<15>")
	)
	(arc
		(start 333.984092 -283.483558)
		(mid 333.701136 -283.559735)
		(end 333.41818 -283.483558)
		(width 0.0889)
		(layer "In2.Cu")
		(net "M_C_CPU0_SB_DQ<15>")
	)
	(arc
		(start 330.598018 -283.483558)
		(mid 330.411074 -283.433303)
		(end 330.22413 -283.483558)
		(width 0.0889)
		(layer "In2.Cu")
		(net "M_C_CPU0_SB_DQ<15>")
	)
	(arc
		(start 332.103984 -283.483558)
		(mid 331.821028 -283.559735)
		(end 331.538072 -283.483558)
		(width 0.0889)
		(layer "In2.Cu")
		(net "M_C_CPU0_SB_DQ<15>")
	)
	(arc
		(start 330.22413 -283.483558)
		(mid 329.941174 -283.559735)
		(end 329.658218 -283.483558)
		(width 0.0889)
		(layer "In2.Cu")
		(net "M_C_CPU0_SB_DQ<15>")
	)
	(arc
		(start 336.804 -283.483558)
		(mid 336.521044 -283.559735)
		(end 336.238088 -283.483558)
		(width 0.0889)
		(layer "In2.Cu")
		(net "M_C_CPU0_SB_DQ<15>")
	)
	(arc
		(start 343.384124 -283.483558)
		(mid 343.101168 -283.559735)
		(end 342.818212 -283.483558)
		(width 0.0889)
		(layer "In2.Cu")
		(net "M_C_CPU0_SB_DQ<15>")
	)
	(arc
		(start 338.118196 -283.483558)
		(mid 337.935945 -283.433208)
		(end 337.752436 -283.478732)
		(width 0.0889)
		(layer "In2.Cu")
		(net "M_C_CPU0_SB_DQ<15>")
	)
	(arc
		(start 329.658218 -283.483558)
		(mid 329.475967 -283.433208)
		(end 329.292458 -283.478732)
		(width 0.0889)
		(layer "In2.Cu")
		(net "M_C_CPU0_SB_DQ<15>")
	)
	(arc
		(start 338.684108 -283.483558)
		(mid 338.401152 -283.559735)
		(end 338.118196 -283.483558)
		(width 0.0889)
		(layer "In2.Cu")
		(net "M_C_CPU0_SB_DQ<15>")
	)
	(arc
		(start 340.929722 -283.478732)
		(mid 340.746214 -283.433238)
		(end 340.563962 -283.483558)
		(width 0.0889)
		(layer "In2.Cu")
		(net "M_C_CPU0_SB_DQ<15>")
	)
	(arc
		(start 334.924146 -283.483558)
		(mid 334.64119 -283.559735)
		(end 334.358234 -283.483558)
		(width 0.0889)
		(layer "In2.Cu")
		(net "M_C_CPU0_SB_DQ<15>")
	)
	(arc
		(start 326.110346 -283.810964)
		(mid 325.997991 -283.885974)
		(end 325.86549 -283.91231)
		(width 0.0889)
		(layer "In2.Cu")
		(net "M_C_CPU0_SB_DQ<15>")
	)
	(arc
		(start 341.504016 -283.483558)
		(mid 341.22106 -283.559735)
		(end 340.938104 -283.483558)
		(width 0.0889)
		(layer "In2.Cu")
		(net "M_C_CPU0_SB_DQ<15>")
	)
	(arc
		(start 336.229706 -283.478732)
		(mid 336.046198 -283.433238)
		(end 335.863946 -283.483558)
		(width 0.0889)
		(layer "In2.Cu")
		(net "M_C_CPU0_SB_DQ<15>")
	)
	(segment
		(start 342.627966 -282.730194)
		(end 342.161114 -282.996132)
		(width 0.10668)
		(layer "F.Cu")
		(net "M_C_CPU0_SB_DQ<14>")
	)
	(segment
		(start 334.828134 -282.673552)
		(end 334.819752 -282.668726)
		(width 0.0889)
		(layer "In2.Cu")
		(net "M_C_CPU0_SB_DQ<14>")
	)
	(segment
		(start 290.769548 -297.897296)
		(end 290.769548 -297.671744)
		(width 0.14478)
		(layer "In2.Cu")
		(net "M_C_CPU0_SB_DQ<14>")
	)
	(segment
		(start 326.935846 -282.673552)
		(end 326.91832 -282.683712)
		(width 0.0889)
		(layer "In2.Cu")
		(net "M_C_CPU0_SB_DQ<14>")
	)
	(segment
		(start 339.52815 -282.673552)
		(end 339.519768 -282.668726)
		(width 0.0889)
		(layer "In2.Cu")
		(net "M_C_CPU0_SB_DQ<14>")
	)
	(segment
		(start 315.155834 -290.34613)
		(end 315.155834 -292.393878)
		(width 0.14478)
		(layer "In2.Cu")
		(net "M_C_CPU0_SB_DQ<14>")
	)
	(segment
		(start 322.500244 -283.00172)
		(end 315.155834 -290.34613)
		(width 0.14478)
		(layer "In2.Cu")
		(net "M_C_CPU0_SB_DQ<14>")
	)
	(segment
		(start 306.21986 -297.209972)
		(end 305.369722 -298.06011)
		(width 0.14478)
		(layer "In2.Cu")
		(net "M_C_CPU0_SB_DQ<14>")
	)
	(segment
		(start 336.342482 -282.668726)
		(end 336.3341 -282.673552)
		(width 0.0889)
		(layer "In2.Cu")
		(net "M_C_CPU0_SB_DQ<14>")
	)
	(segment
		(start 333.88808 -282.673552)
		(end 333.879698 -282.668726)
		(width 0.0889)
		(layer "In2.Cu")
		(net "M_C_CPU0_SB_DQ<14>")
	)
	(segment
		(start 288.60496 -298.06011)
		(end 288.180018 -297.635168)
		(width 0.14478)
		(layer "In2.Cu")
		(net "M_C_CPU0_SB_DQ<14>")
	)
	(segment
		(start 324.787768 -283.15031)
		(end 324.639178 -283.00172)
		(width 0.0889)
		(layer "In2.Cu")
		(net "M_C_CPU0_SB_DQ<14>")
	)
	(segment
		(start 301.665386 -298.06011)
		(end 300.815248 -297.209972)
		(width 0.14478)
		(layer "In2.Cu")
		(net "M_C_CPU0_SB_DQ<14>")
	)
	(segment
		(start 331.642466 -282.668726)
		(end 331.634084 -282.673552)
		(width 0.0889)
		(layer "In2.Cu")
		(net "M_C_CPU0_SB_DQ<14>")
	)
	(segment
		(start 290.769548 -297.671744)
		(end 290.606734 -297.50893)
		(width 0.14478)
		(layer "In2.Cu")
		(net "M_C_CPU0_SB_DQ<14>")
	)
	(segment
		(start 298.058078 -298.06011)
		(end 290.932362 -298.06011)
		(width 0.14478)
		(layer "In2.Cu")
		(net "M_C_CPU0_SB_DQ<14>")
	)
	(segment
		(start 326.651112 -282.756102)
		(end 326.073008 -282.756102)
		(width 0.0889)
		(layer "In2.Cu")
		(net "M_C_CPU0_SB_DQ<14>")
	)
	(segment
		(start 342.315038 -282.730702)
		(end 342.292686 -282.64739)
		(width 0.0889)
		(layer "In2.Cu")
		(net "M_C_CPU0_SB_DQ<14>")
	)
	(segment
		(start 290.932362 -298.06011)
		(end 290.769548 -297.897296)
		(width 0.14478)
		(layer "In2.Cu")
		(net "M_C_CPU0_SB_DQ<14>")
	)
	(segment
		(start 327.89876 -282.660344)
		(end 327.875392 -282.673806)
		(width 0.0889)
		(layer "In2.Cu")
		(net "M_C_CPU0_SB_DQ<14>")
	)
	(segment
		(start 338.588096 -282.673552)
		(end 338.579714 -282.668726)
		(width 0.0889)
		(layer "In2.Cu")
		(net "M_C_CPU0_SB_DQ<14>")
	)
	(segment
		(start 290.376102 -297.50893)
		(end 290.213288 -297.671744)
		(width 0.14478)
		(layer "In2.Cu")
		(net "M_C_CPU0_SB_DQ<14>")
	)
	(segment
		(start 290.213288 -297.671744)
		(end 290.213288 -297.897296)
		(width 0.14478)
		(layer "In2.Cu")
		(net "M_C_CPU0_SB_DQ<14>")
	)
	(segment
		(start 290.050474 -298.06011)
		(end 288.60496 -298.06011)
		(width 0.14478)
		(layer "In2.Cu")
		(net "M_C_CPU0_SB_DQ<14>")
	)
	(segment
		(start 341.042498 -282.668726)
		(end 341.034116 -282.673552)
		(width 0.0889)
		(layer "In2.Cu")
		(net "M_C_CPU0_SB_DQ<14>")
	)
	(segment
		(start 330.128118 -282.673552)
		(end 330.119736 -282.668726)
		(width 0.0889)
		(layer "In2.Cu")
		(net "M_C_CPU0_SB_DQ<14>")
	)
	(segment
		(start 290.606734 -297.50893)
		(end 290.376102 -297.50893)
		(width 0.14478)
		(layer "In2.Cu")
		(net "M_C_CPU0_SB_DQ<14>")
	)
	(segment
		(start 300.815248 -297.209972)
		(end 298.908216 -297.209972)
		(width 0.14478)
		(layer "In2.Cu")
		(net "M_C_CPU0_SB_DQ<14>")
	)
	(segment
		(start 327.311258 -282.673552)
		(end 327.290684 -282.661614)
		(width 0.0889)
		(layer "In2.Cu")
		(net "M_C_CPU0_SB_DQ<14>")
	)
	(segment
		(start 330.702412 -282.668726)
		(end 330.69403 -282.673552)
		(width 0.0889)
		(layer "In2.Cu")
		(net "M_C_CPU0_SB_DQ<14>")
	)
	(segment
		(start 327.875392 -282.673806)
		(end 327.851516 -282.687776)
		(width 0.0889)
		(layer "In2.Cu")
		(net "M_C_CPU0_SB_DQ<14>")
	)
	(segment
		(start 342.161114 -282.996132)
		(end 342.315038 -282.730702)
		(width 0.0889)
		(layer "In2.Cu")
		(net "M_C_CPU0_SB_DQ<14>")
	)
	(segment
		(start 325.560182 -283.15031)
		(end 324.787768 -283.15031)
		(width 0.0889)
		(layer "In2.Cu")
		(net "M_C_CPU0_SB_DQ<14>")
	)
	(segment
		(start 290.213288 -297.897296)
		(end 290.050474 -298.06011)
		(width 0.14478)
		(layer "In2.Cu")
		(net "M_C_CPU0_SB_DQ<14>")
	)
	(segment
		(start 298.908216 -297.209972)
		(end 298.058078 -298.06011)
		(width 0.14478)
		(layer "In2.Cu")
		(net "M_C_CPU0_SB_DQ<14>")
	)
	(segment
		(start 310.33974 -297.209972)
		(end 306.21986 -297.209972)
		(width 0.14478)
		(layer "In2.Cu")
		(net "M_C_CPU0_SB_DQ<14>")
	)
	(segment
		(start 325.87057 -282.839922)
		(end 325.560182 -283.15031)
		(width 0.0889)
		(layer "In2.Cu")
		(net "M_C_CPU0_SB_DQ<14>")
	)
	(segment
		(start 323.876924 -283.00172)
		(end 322.500244 -283.00172)
		(width 0.14478)
		(layer "In2.Cu")
		(net "M_C_CPU0_SB_DQ<14>")
	)
	(segment
		(start 305.369722 -298.06011)
		(end 301.665386 -298.06011)
		(width 0.14478)
		(layer "In2.Cu")
		(net "M_C_CPU0_SB_DQ<14>")
	)
	(segment
		(start 324.639178 -283.00172)
		(end 323.876924 -283.00172)
		(width 0.0889)
		(layer "In2.Cu")
		(net "M_C_CPU0_SB_DQ<14>")
	)
	(segment
		(start 340.102444 -282.668726)
		(end 340.094062 -282.673552)
		(width 0.0889)
		(layer "In2.Cu")
		(net "M_C_CPU0_SB_DQ<14>")
	)
	(segment
		(start 335.402428 -282.668726)
		(end 335.394046 -282.673552)
		(width 0.0889)
		(layer "In2.Cu")
		(net "M_C_CPU0_SB_DQ<14>")
	)
	(segment
		(start 315.155834 -292.393878)
		(end 310.33974 -297.209972)
		(width 0.14478)
		(layer "In2.Cu")
		(net "M_C_CPU0_SB_DQ<14>")
	)
	(arc
		(start 337.648042 -282.673552)
		(mid 337.461098 -282.623297)
		(end 337.274154 -282.673552)
		(width 0.0889)
		(layer "In2.Cu")
		(net "M_C_CPU0_SB_DQ<14>")
	)
	(arc
		(start 331.068172 -282.673552)
		(mid 330.885921 -282.623202)
		(end 330.702412 -282.668726)
		(width 0.0889)
		(layer "In2.Cu")
		(net "M_C_CPU0_SB_DQ<14>")
	)
	(arc
		(start 328.814176 -282.673552)
		(mid 328.53122 -282.749729)
		(end 328.248264 -282.673552)
		(width 0.0889)
		(layer "In2.Cu")
		(net "M_C_CPU0_SB_DQ<14>")
	)
	(arc
		(start 332.948026 -282.673552)
		(mid 332.761082 -282.623297)
		(end 332.574138 -282.673552)
		(width 0.0889)
		(layer "In2.Cu")
		(net "M_C_CPU0_SB_DQ<14>")
	)
	(arc
		(start 333.879698 -282.668726)
		(mid 333.69619 -282.623232)
		(end 333.513938 -282.673552)
		(width 0.0889)
		(layer "In2.Cu")
		(net "M_C_CPU0_SB_DQ<14>")
	)
	(arc
		(start 330.119736 -282.668726)
		(mid 329.936228 -282.623232)
		(end 329.753976 -282.673552)
		(width 0.0889)
		(layer "In2.Cu")
		(net "M_C_CPU0_SB_DQ<14>")
	)
	(arc
		(start 327.290684 -282.661614)
		(mid 327.111756 -282.622737)
		(end 326.935846 -282.673552)
		(width 0.0889)
		(layer "In2.Cu")
		(net "M_C_CPU0_SB_DQ<14>")
	)
	(arc
		(start 334.819752 -282.668726)
		(mid 334.636244 -282.623232)
		(end 334.453992 -282.673552)
		(width 0.0889)
		(layer "In2.Cu")
		(net "M_C_CPU0_SB_DQ<14>")
	)
	(arc
		(start 332.574138 -282.673552)
		(mid 332.291182 -282.749729)
		(end 332.008226 -282.673552)
		(width 0.0889)
		(layer "In2.Cu")
		(net "M_C_CPU0_SB_DQ<14>")
	)
	(arc
		(start 338.213954 -282.673552)
		(mid 337.930998 -282.749729)
		(end 337.648042 -282.673552)
		(width 0.0889)
		(layer "In2.Cu")
		(net "M_C_CPU0_SB_DQ<14>")
	)
	(arc
		(start 326.91832 -282.683712)
		(mid 326.789523 -282.737635)
		(end 326.651112 -282.756102)
		(width 0.0889)
		(layer "In2.Cu")
		(net "M_C_CPU0_SB_DQ<14>")
	)
	(arc
		(start 335.768188 -282.673552)
		(mid 335.585937 -282.623202)
		(end 335.402428 -282.668726)
		(width 0.0889)
		(layer "In2.Cu")
		(net "M_C_CPU0_SB_DQ<14>")
	)
	(arc
		(start 328.248264 -282.673552)
		(mid 328.075156 -282.623436)
		(end 327.89876 -282.660344)
		(width 0.0889)
		(layer "In2.Cu")
		(net "M_C_CPU0_SB_DQ<14>")
	)
	(arc
		(start 327.851516 -282.687776)
		(mid 327.579579 -282.749602)
		(end 327.311258 -282.673552)
		(width 0.0889)
		(layer "In2.Cu")
		(net "M_C_CPU0_SB_DQ<14>")
	)
	(arc
		(start 342.292686 -282.64739)
		(mid 342.130497 -282.624655)
		(end 341.97417 -282.673552)
		(width 0.0889)
		(layer "In2.Cu")
		(net "M_C_CPU0_SB_DQ<14>")
	)
	(arc
		(start 341.97417 -282.673552)
		(mid 341.691214 -282.749729)
		(end 341.408258 -282.673552)
		(width 0.0889)
		(layer "In2.Cu")
		(net "M_C_CPU0_SB_DQ<14>")
	)
	(arc
		(start 339.519768 -282.668726)
		(mid 339.33626 -282.623232)
		(end 339.154008 -282.673552)
		(width 0.0889)
		(layer "In2.Cu")
		(net "M_C_CPU0_SB_DQ<14>")
	)
	(arc
		(start 330.69403 -282.673552)
		(mid 330.411074 -282.749729)
		(end 330.128118 -282.673552)
		(width 0.0889)
		(layer "In2.Cu")
		(net "M_C_CPU0_SB_DQ<14>")
	)
	(arc
		(start 329.188064 -282.673552)
		(mid 329.00112 -282.623297)
		(end 328.814176 -282.673552)
		(width 0.0889)
		(layer "In2.Cu")
		(net "M_C_CPU0_SB_DQ<14>")
	)
	(arc
		(start 340.094062 -282.673552)
		(mid 339.811106 -282.749729)
		(end 339.52815 -282.673552)
		(width 0.0889)
		(layer "In2.Cu")
		(net "M_C_CPU0_SB_DQ<14>")
	)
	(arc
		(start 336.3341 -282.673552)
		(mid 336.051144 -282.749729)
		(end 335.768188 -282.673552)
		(width 0.0889)
		(layer "In2.Cu")
		(net "M_C_CPU0_SB_DQ<14>")
	)
	(arc
		(start 337.274154 -282.673552)
		(mid 336.991198 -282.749729)
		(end 336.708242 -282.673552)
		(width 0.0889)
		(layer "In2.Cu")
		(net "M_C_CPU0_SB_DQ<14>")
	)
	(arc
		(start 334.453992 -282.673552)
		(mid 334.171036 -282.749729)
		(end 333.88808 -282.673552)
		(width 0.0889)
		(layer "In2.Cu")
		(net "M_C_CPU0_SB_DQ<14>")
	)
	(arc
		(start 332.008226 -282.673552)
		(mid 331.825975 -282.623202)
		(end 331.642466 -282.668726)
		(width 0.0889)
		(layer "In2.Cu")
		(net "M_C_CPU0_SB_DQ<14>")
	)
	(arc
		(start 341.408258 -282.673552)
		(mid 341.226007 -282.623202)
		(end 341.042498 -282.668726)
		(width 0.0889)
		(layer "In2.Cu")
		(net "M_C_CPU0_SB_DQ<14>")
	)
	(arc
		(start 335.394046 -282.673552)
		(mid 335.11109 -282.749729)
		(end 334.828134 -282.673552)
		(width 0.0889)
		(layer "In2.Cu")
		(net "M_C_CPU0_SB_DQ<14>")
	)
	(arc
		(start 336.708242 -282.673552)
		(mid 336.525991 -282.623202)
		(end 336.342482 -282.668726)
		(width 0.0889)
		(layer "In2.Cu")
		(net "M_C_CPU0_SB_DQ<14>")
	)
	(arc
		(start 341.034116 -282.673552)
		(mid 340.75116 -282.749729)
		(end 340.468204 -282.673552)
		(width 0.0889)
		(layer "In2.Cu")
		(net "M_C_CPU0_SB_DQ<14>")
	)
	(arc
		(start 338.579714 -282.668726)
		(mid 338.396206 -282.623232)
		(end 338.213954 -282.673552)
		(width 0.0889)
		(layer "In2.Cu")
		(net "M_C_CPU0_SB_DQ<14>")
	)
	(arc
		(start 340.468204 -282.673552)
		(mid 340.285953 -282.623202)
		(end 340.102444 -282.668726)
		(width 0.0889)
		(layer "In2.Cu")
		(net "M_C_CPU0_SB_DQ<14>")
	)
	(arc
		(start 329.753976 -282.673552)
		(mid 329.47102 -282.749729)
		(end 329.188064 -282.673552)
		(width 0.0889)
		(layer "In2.Cu")
		(net "M_C_CPU0_SB_DQ<14>")
	)
	(arc
		(start 331.634084 -282.673552)
		(mid 331.351128 -282.749729)
		(end 331.068172 -282.673552)
		(width 0.0889)
		(layer "In2.Cu")
		(net "M_C_CPU0_SB_DQ<14>")
	)
	(arc
		(start 339.154008 -282.673552)
		(mid 338.871052 -282.749729)
		(end 338.588096 -282.673552)
		(width 0.0889)
		(layer "In2.Cu")
		(net "M_C_CPU0_SB_DQ<14>")
	)
	(arc
		(start 326.073008 -282.756102)
		(mid 325.963462 -282.777892)
		(end 325.87057 -282.839922)
		(width 0.0889)
		(layer "In2.Cu")
		(net "M_C_CPU0_SB_DQ<14>")
	)
	(arc
		(start 333.513938 -282.673552)
		(mid 333.230982 -282.749729)
		(end 332.948026 -282.673552)
		(width 0.0889)
		(layer "In2.Cu")
		(net "M_C_CPU0_SB_DQ<14>")
	)
	(segment
		(start 344.508074 -282.730194)
		(end 344.041222 -282.996132)
		(width 0.10668)
		(layer "F.Cu")
		(net "M_C_CPU0_SB_DQ<13>")
	)
	(segment
		(start 304.817526 -299.27423)
		(end 304.586894 -299.27423)
		(width 0.14478)
		(layer "In2.Cu")
		(net "M_C_CPU0_SB_DQ<13>")
	)
	(segment
		(start 305.181508 -298.910248)
		(end 304.817526 -299.27423)
		(width 0.14478)
		(layer "In2.Cu")
		(net "M_C_CPU0_SB_DQ<13>")
	)
	(segment
		(start 305.369722 -298.910248)
		(end 305.181508 -298.910248)
		(width 0.14478)
		(layer "In2.Cu")
		(net "M_C_CPU0_SB_DQ<13>")
	)
	(segment
		(start 304.27422 -298.51731)
		(end 303.911254 -298.51731)
		(width 0.14478)
		(layer "In2.Cu")
		(net "M_C_CPU0_SB_DQ<13>")
	)
	(segment
		(start 325.835772 -283.70911)
		(end 324.739254 -283.70911)
		(width 0.0889)
		(layer "In2.Cu")
		(net "M_C_CPU0_SB_DQ<13>")
	)
	(segment
		(start 294.008048 -298.741084)
		(end 293.845234 -298.57827)
		(width 0.14478)
		(layer "In2.Cu")
		(net "M_C_CPU0_SB_DQ<13>")
	)
	(segment
		(start 315.610494 -290.534598)
		(end 315.610494 -292.582346)
		(width 0.14478)
		(layer "In2.Cu")
		(net "M_C_CPU0_SB_DQ<13>")
	)
	(segment
		(start 323.908674 -283.45638)
		(end 322.688712 -283.45638)
		(width 0.14478)
		(layer "In2.Cu")
		(net "M_C_CPU0_SB_DQ<13>")
	)
	(segment
		(start 338.588096 -283.318712)
		(end 338.579714 -283.323538)
		(width 0.0889)
		(layer "In2.Cu")
		(net "M_C_CPU0_SB_DQ<13>")
	)
	(segment
		(start 303.518316 -298.910248)
		(end 301.872142 -298.910248)
		(width 0.14478)
		(layer "In2.Cu")
		(net "M_C_CPU0_SB_DQ<13>")
	)
	(segment
		(start 293.451788 -299.100494)
		(end 293.288974 -299.263308)
		(width 0.14478)
		(layer "In2.Cu")
		(net "M_C_CPU0_SB_DQ<13>")
	)
	(segment
		(start 294.170862 -299.263308)
		(end 294.008048 -299.100494)
		(width 0.14478)
		(layer "In2.Cu")
		(net "M_C_CPU0_SB_DQ<13>")
	)
	(segment
		(start 330.128118 -283.318712)
		(end 330.119736 -283.323538)
		(width 0.0889)
		(layer "In2.Cu")
		(net "M_C_CPU0_SB_DQ<13>")
	)
	(segment
		(start 327.321926 -283.310076)
		(end 327.307194 -283.318712)
		(width 0.0889)
		(layer "In2.Cu")
		(net "M_C_CPU0_SB_DQ<13>")
	)
	(segment
		(start 293.614602 -298.57827)
		(end 293.451788 -298.741084)
		(width 0.14478)
		(layer "In2.Cu")
		(net "M_C_CPU0_SB_DQ<13>")
	)
	(segment
		(start 297.4975 -299.26407)
		(end 296.9895 -299.26407)
		(width 0.14478)
		(layer "In2.Cu")
		(net "M_C_CPU0_SB_DQ<13>")
	)
	(segment
		(start 296.635678 -298.910248)
		(end 294.754554 -298.910248)
		(width 0.14478)
		(layer "In2.Cu")
		(net "M_C_CPU0_SB_DQ<13>")
	)
	(segment
		(start 334.828134 -283.318712)
		(end 334.819752 -283.323538)
		(width 0.0889)
		(layer "In2.Cu")
		(net "M_C_CPU0_SB_DQ<13>")
	)
	(segment
		(start 331.642466 -283.323538)
		(end 331.634084 -283.318712)
		(width 0.0889)
		(layer "In2.Cu")
		(net "M_C_CPU0_SB_DQ<13>")
	)
	(segment
		(start 293.451788 -298.741084)
		(end 293.451788 -299.100494)
		(width 0.14478)
		(layer "In2.Cu")
		(net "M_C_CPU0_SB_DQ<13>")
	)
	(segment
		(start 296.9895 -299.26407)
		(end 296.635678 -298.910248)
		(width 0.14478)
		(layer "In2.Cu")
		(net "M_C_CPU0_SB_DQ<13>")
	)
	(segment
		(start 293.058342 -299.263308)
		(end 292.280086 -298.485052)
		(width 0.14478)
		(layer "In2.Cu")
		(net "M_C_CPU0_SB_DQ<13>")
	)
	(segment
		(start 333.88808 -283.318712)
		(end 333.879698 -283.323538)
		(width 0.0889)
		(layer "In2.Cu")
		(net "M_C_CPU0_SB_DQ<13>")
	)
	(segment
		(start 336.342482 -283.323538)
		(end 336.3341 -283.318712)
		(width 0.0889)
		(layer "In2.Cu")
		(net "M_C_CPU0_SB_DQ<13>")
	)
	(segment
		(start 326.21601 -283.400754)
		(end 325.958454 -283.65831)
		(width 0.0889)
		(layer "In2.Cu")
		(net "M_C_CPU0_SB_DQ<13>")
	)
	(segment
		(start 343.288112 -283.318712)
		(end 343.27973 -283.323538)
		(width 0.0889)
		(layer "In2.Cu")
		(net "M_C_CPU0_SB_DQ<13>")
	)
	(segment
		(start 304.42408 -299.111416)
		(end 304.42408 -298.66717)
		(width 0.14478)
		(layer "In2.Cu")
		(net "M_C_CPU0_SB_DQ<13>")
	)
	(segment
		(start 304.42408 -298.66717)
		(end 304.27422 -298.51731)
		(width 0.14478)
		(layer "In2.Cu")
		(net "M_C_CPU0_SB_DQ<13>")
	)
	(segment
		(start 310.13273 -298.06011)
		(end 306.21986 -298.06011)
		(width 0.14478)
		(layer "In2.Cu")
		(net "M_C_CPU0_SB_DQ<13>")
	)
	(segment
		(start 293.845234 -298.57827)
		(end 293.614602 -298.57827)
		(width 0.14478)
		(layer "In2.Cu")
		(net "M_C_CPU0_SB_DQ<13>")
	)
	(segment
		(start 298.70146 -298.06011)
		(end 297.4975 -299.26407)
		(width 0.14478)
		(layer "In2.Cu")
		(net "M_C_CPU0_SB_DQ<13>")
	)
	(segment
		(start 306.21986 -298.06011)
		(end 305.369722 -298.910248)
		(width 0.14478)
		(layer "In2.Cu")
		(net "M_C_CPU0_SB_DQ<13>")
	)
	(segment
		(start 341.042498 -283.323538)
		(end 341.034116 -283.318712)
		(width 0.0889)
		(layer "In2.Cu")
		(net "M_C_CPU0_SB_DQ<13>")
	)
	(segment
		(start 315.610494 -292.582346)
		(end 310.13273 -298.06011)
		(width 0.14478)
		(layer "In2.Cu")
		(net "M_C_CPU0_SB_DQ<13>")
	)
	(segment
		(start 344.041222 -282.996132)
		(end 343.887044 -283.261562)
		(width 0.0889)
		(layer "In2.Cu")
		(net "M_C_CPU0_SB_DQ<13>")
	)
	(segment
		(start 326.93356 -283.318458)
		(end 326.917812 -283.309314)
		(width 0.0889)
		(layer "In2.Cu")
		(net "M_C_CPU0_SB_DQ<13>")
	)
	(segment
		(start 294.754554 -298.910248)
		(end 294.401494 -299.263308)
		(width 0.14478)
		(layer "In2.Cu")
		(net "M_C_CPU0_SB_DQ<13>")
	)
	(segment
		(start 340.102444 -283.323538)
		(end 340.094062 -283.318712)
		(width 0.0889)
		(layer "In2.Cu")
		(net "M_C_CPU0_SB_DQ<13>")
	)
	(segment
		(start 322.688712 -283.45638)
		(end 315.610494 -290.534598)
		(width 0.14478)
		(layer "In2.Cu")
		(net "M_C_CPU0_SB_DQ<13>")
	)
	(segment
		(start 293.288974 -299.263308)
		(end 293.058342 -299.263308)
		(width 0.14478)
		(layer "In2.Cu")
		(net "M_C_CPU0_SB_DQ<13>")
	)
	(segment
		(start 303.911254 -298.51731)
		(end 303.518316 -298.910248)
		(width 0.14478)
		(layer "In2.Cu")
		(net "M_C_CPU0_SB_DQ<13>")
	)
	(segment
		(start 324.739254 -283.70911)
		(end 324.486524 -283.45638)
		(width 0.0889)
		(layer "In2.Cu")
		(net "M_C_CPU0_SB_DQ<13>")
	)
	(segment
		(start 335.402428 -283.323538)
		(end 335.394046 -283.318712)
		(width 0.0889)
		(layer "In2.Cu")
		(net "M_C_CPU0_SB_DQ<13>")
	)
	(segment
		(start 328.248264 -283.318712)
		(end 328.239882 -283.323538)
		(width 0.0889)
		(layer "In2.Cu")
		(net "M_C_CPU0_SB_DQ<13>")
	)
	(segment
		(start 301.872142 -298.910248)
		(end 301.022004 -298.06011)
		(width 0.14478)
		(layer "In2.Cu")
		(net "M_C_CPU0_SB_DQ<13>")
	)
	(segment
		(start 326.947276 -283.326332)
		(end 326.93356 -283.318458)
		(width 0.0889)
		(layer "In2.Cu")
		(net "M_C_CPU0_SB_DQ<13>")
	)
	(segment
		(start 324.486524 -283.45638)
		(end 323.908674 -283.45638)
		(width 0.0889)
		(layer "In2.Cu")
		(net "M_C_CPU0_SB_DQ<13>")
	)
	(segment
		(start 294.401494 -299.263308)
		(end 294.170862 -299.263308)
		(width 0.14478)
		(layer "In2.Cu")
		(net "M_C_CPU0_SB_DQ<13>")
	)
	(segment
		(start 304.586894 -299.27423)
		(end 304.42408 -299.111416)
		(width 0.14478)
		(layer "In2.Cu")
		(net "M_C_CPU0_SB_DQ<13>")
	)
	(segment
		(start 301.022004 -298.06011)
		(end 298.70146 -298.06011)
		(width 0.14478)
		(layer "In2.Cu")
		(net "M_C_CPU0_SB_DQ<13>")
	)
	(segment
		(start 339.52815 -283.318712)
		(end 339.519768 -283.323538)
		(width 0.0889)
		(layer "In2.Cu")
		(net "M_C_CPU0_SB_DQ<13>")
	)
	(segment
		(start 343.887044 -283.261562)
		(end 343.790778 -283.286962)
		(width 0.0889)
		(layer "In2.Cu")
		(net "M_C_CPU0_SB_DQ<13>")
	)
	(segment
		(start 330.702412 -283.323538)
		(end 330.69403 -283.318712)
		(width 0.0889)
		(layer "In2.Cu")
		(net "M_C_CPU0_SB_DQ<13>")
	)
	(segment
		(start 294.008048 -299.100494)
		(end 294.008048 -298.741084)
		(width 0.14478)
		(layer "In2.Cu")
		(net "M_C_CPU0_SB_DQ<13>")
	)
	(arc
		(start 332.008226 -283.318712)
		(mid 331.825975 -283.369062)
		(end 331.642466 -283.323538)
		(width 0.0889)
		(layer "In2.Cu")
		(net "M_C_CPU0_SB_DQ<13>")
	)
	(arc
		(start 325.958454 -283.65831)
		(mid 325.902167 -283.69592)
		(end 325.835772 -283.70911)
		(width 0.0889)
		(layer "In2.Cu")
		(net "M_C_CPU0_SB_DQ<13>")
	)
	(arc
		(start 342.348058 -283.318712)
		(mid 342.161114 -283.368967)
		(end 341.97417 -283.318712)
		(width 0.0889)
		(layer "In2.Cu")
		(net "M_C_CPU0_SB_DQ<13>")
	)
	(arc
		(start 343.27973 -283.323538)
		(mid 343.096222 -283.369032)
		(end 342.91397 -283.318712)
		(width 0.0889)
		(layer "In2.Cu")
		(net "M_C_CPU0_SB_DQ<13>")
	)
	(arc
		(start 339.154008 -283.318712)
		(mid 338.871052 -283.242535)
		(end 338.588096 -283.318712)
		(width 0.0889)
		(layer "In2.Cu")
		(net "M_C_CPU0_SB_DQ<13>")
	)
	(arc
		(start 333.513938 -283.318712)
		(mid 333.230982 -283.242535)
		(end 332.948026 -283.318712)
		(width 0.0889)
		(layer "In2.Cu")
		(net "M_C_CPU0_SB_DQ<13>")
	)
	(arc
		(start 328.239882 -283.323538)
		(mid 328.05612 -283.369154)
		(end 327.873614 -283.318712)
		(width 0.0889)
		(layer "In2.Cu")
		(net "M_C_CPU0_SB_DQ<13>")
	)
	(arc
		(start 334.819752 -283.323538)
		(mid 334.636244 -283.369032)
		(end 334.453992 -283.318712)
		(width 0.0889)
		(layer "In2.Cu")
		(net "M_C_CPU0_SB_DQ<13>")
	)
	(arc
		(start 340.468204 -283.318712)
		(mid 340.285953 -283.369062)
		(end 340.102444 -283.323538)
		(width 0.0889)
		(layer "In2.Cu")
		(net "M_C_CPU0_SB_DQ<13>")
	)
	(arc
		(start 327.307194 -283.318712)
		(mid 327.128207 -283.368882)
		(end 326.947276 -283.326332)
		(width 0.0889)
		(layer "In2.Cu")
		(net "M_C_CPU0_SB_DQ<13>")
	)
	(arc
		(start 332.574138 -283.318712)
		(mid 332.291182 -283.242535)
		(end 332.008226 -283.318712)
		(width 0.0889)
		(layer "In2.Cu")
		(net "M_C_CPU0_SB_DQ<13>")
	)
	(arc
		(start 336.708242 -283.318712)
		(mid 336.525991 -283.369062)
		(end 336.342482 -283.323538)
		(width 0.0889)
		(layer "In2.Cu")
		(net "M_C_CPU0_SB_DQ<13>")
	)
	(arc
		(start 330.69403 -283.318712)
		(mid 330.411074 -283.242535)
		(end 330.128118 -283.318712)
		(width 0.0889)
		(layer "In2.Cu")
		(net "M_C_CPU0_SB_DQ<13>")
	)
	(arc
		(start 335.768188 -283.318712)
		(mid 335.585937 -283.369062)
		(end 335.402428 -283.323538)
		(width 0.0889)
		(layer "In2.Cu")
		(net "M_C_CPU0_SB_DQ<13>")
	)
	(arc
		(start 329.188064 -283.318712)
		(mid 329.00112 -283.368967)
		(end 328.814176 -283.318712)
		(width 0.0889)
		(layer "In2.Cu")
		(net "M_C_CPU0_SB_DQ<13>")
	)
	(arc
		(start 341.408258 -283.318712)
		(mid 341.226007 -283.369062)
		(end 341.042498 -283.323538)
		(width 0.0889)
		(layer "In2.Cu")
		(net "M_C_CPU0_SB_DQ<13>")
	)
	(arc
		(start 326.917812 -283.309314)
		(mid 326.551397 -283.235763)
		(end 326.21601 -283.400754)
		(width 0.0889)
		(layer "In2.Cu")
		(net "M_C_CPU0_SB_DQ<13>")
	)
	(arc
		(start 337.648042 -283.318712)
		(mid 337.461098 -283.368967)
		(end 337.274154 -283.318712)
		(width 0.0889)
		(layer "In2.Cu")
		(net "M_C_CPU0_SB_DQ<13>")
	)
	(arc
		(start 340.094062 -283.318712)
		(mid 339.811106 -283.242535)
		(end 339.52815 -283.318712)
		(width 0.0889)
		(layer "In2.Cu")
		(net "M_C_CPU0_SB_DQ<13>")
	)
	(arc
		(start 331.068172 -283.318712)
		(mid 330.885921 -283.369062)
		(end 330.702412 -283.323538)
		(width 0.0889)
		(layer "In2.Cu")
		(net "M_C_CPU0_SB_DQ<13>")
	)
	(arc
		(start 343.790778 -283.286962)
		(mid 343.535713 -283.243611)
		(end 343.288112 -283.318712)
		(width 0.0889)
		(layer "In2.Cu")
		(net "M_C_CPU0_SB_DQ<13>")
	)
	(arc
		(start 327.873614 -283.318712)
		(mid 327.598908 -283.242348)
		(end 327.321926 -283.310076)
		(width 0.0889)
		(layer "In2.Cu")
		(net "M_C_CPU0_SB_DQ<13>")
	)
	(arc
		(start 341.034116 -283.318712)
		(mid 340.75116 -283.242535)
		(end 340.468204 -283.318712)
		(width 0.0889)
		(layer "In2.Cu")
		(net "M_C_CPU0_SB_DQ<13>")
	)
	(arc
		(start 337.274154 -283.318712)
		(mid 336.991198 -283.242535)
		(end 336.708242 -283.318712)
		(width 0.0889)
		(layer "In2.Cu")
		(net "M_C_CPU0_SB_DQ<13>")
	)
	(arc
		(start 338.213954 -283.318712)
		(mid 337.930998 -283.242535)
		(end 337.648042 -283.318712)
		(width 0.0889)
		(layer "In2.Cu")
		(net "M_C_CPU0_SB_DQ<13>")
	)
	(arc
		(start 339.519768 -283.323538)
		(mid 339.33626 -283.369032)
		(end 339.154008 -283.318712)
		(width 0.0889)
		(layer "In2.Cu")
		(net "M_C_CPU0_SB_DQ<13>")
	)
	(arc
		(start 333.879698 -283.323538)
		(mid 333.69619 -283.369032)
		(end 333.513938 -283.318712)
		(width 0.0889)
		(layer "In2.Cu")
		(net "M_C_CPU0_SB_DQ<13>")
	)
	(arc
		(start 335.394046 -283.318712)
		(mid 335.11109 -283.242535)
		(end 334.828134 -283.318712)
		(width 0.0889)
		(layer "In2.Cu")
		(net "M_C_CPU0_SB_DQ<13>")
	)
	(arc
		(start 332.948026 -283.318712)
		(mid 332.761082 -283.368967)
		(end 332.574138 -283.318712)
		(width 0.0889)
		(layer "In2.Cu")
		(net "M_C_CPU0_SB_DQ<13>")
	)
	(arc
		(start 328.814176 -283.318712)
		(mid 328.53122 -283.242535)
		(end 328.248264 -283.318712)
		(width 0.0889)
		(layer "In2.Cu")
		(net "M_C_CPU0_SB_DQ<13>")
	)
	(arc
		(start 342.91397 -283.318712)
		(mid 342.631014 -283.242535)
		(end 342.348058 -283.318712)
		(width 0.0889)
		(layer "In2.Cu")
		(net "M_C_CPU0_SB_DQ<13>")
	)
	(arc
		(start 341.97417 -283.318712)
		(mid 341.691214 -283.242535)
		(end 341.408258 -283.318712)
		(width 0.0889)
		(layer "In2.Cu")
		(net "M_C_CPU0_SB_DQ<13>")
	)
	(arc
		(start 334.453992 -283.318712)
		(mid 334.171036 -283.242535)
		(end 333.88808 -283.318712)
		(width 0.0889)
		(layer "In2.Cu")
		(net "M_C_CPU0_SB_DQ<13>")
	)
	(arc
		(start 331.634084 -283.318712)
		(mid 331.351128 -283.242535)
		(end 331.068172 -283.318712)
		(width 0.0889)
		(layer "In2.Cu")
		(net "M_C_CPU0_SB_DQ<13>")
	)
	(arc
		(start 329.753976 -283.318712)
		(mid 329.47102 -283.242535)
		(end 329.188064 -283.318712)
		(width 0.0889)
		(layer "In2.Cu")
		(net "M_C_CPU0_SB_DQ<13>")
	)
	(arc
		(start 330.119736 -283.323538)
		(mid 329.936228 -283.369032)
		(end 329.753976 -283.318712)
		(width 0.0889)
		(layer "In2.Cu")
		(net "M_C_CPU0_SB_DQ<13>")
	)
	(arc
		(start 336.3341 -283.318712)
		(mid 336.051144 -283.242535)
		(end 335.768188 -283.318712)
		(width 0.0889)
		(layer "In2.Cu")
		(net "M_C_CPU0_SB_DQ<13>")
	)
	(arc
		(start 338.579714 -283.323538)
		(mid 338.396206 -283.369032)
		(end 338.213954 -283.318712)
		(width 0.0889)
		(layer "In2.Cu")
		(net "M_C_CPU0_SB_DQ<13>")
	)
	(segment
		(start 343.097866 -281.920188)
		(end 342.631014 -282.186126)
		(width 0.10668)
		(layer "F.Cu")
		(net "M_C_CPU0_SB_DQ<12>")
	)
	(segment
		(start 337.752436 -282.513532)
		(end 337.744054 -282.508706)
		(width 0.0889)
		(layer "In2.Cu")
		(net "M_C_CPU0_SB_DQ<12>")
	)
	(segment
		(start 305.57597 -297.210226)
		(end 305.273964 -297.210226)
		(width 0.14478)
		(layer "In2.Cu")
		(net "M_C_CPU0_SB_DQ<12>")
	)
	(segment
		(start 292.705282 -297.210226)
		(end 292.280086 -296.78503)
		(width 0.14478)
		(layer "In2.Cu")
		(net "M_C_CPU0_SB_DQ<12>")
	)
	(segment
		(start 311.71134 -294.736012)
		(end 311.825386 -294.850058)
		(width 0.14478)
		(layer "In2.Cu")
		(net "M_C_CPU0_SB_DQ<12>")
	)
	(segment
		(start 327.803764 -282.494482)
		(end 327.779888 -282.508452)
		(width 0.0889)
		(layer "In2.Cu")
		(net "M_C_CPU0_SB_DQ<12>")
	)
	(segment
		(start 310.644286 -296.031158)
		(end 310.53024 -295.917112)
		(width 0.14478)
		(layer "In2.Cu")
		(net "M_C_CPU0_SB_DQ<12>")
	)
	(segment
		(start 313.237118 -293.668958)
		(end 313.006486 -293.668958)
		(width 0.14478)
		(layer "In2.Cu")
		(net "M_C_CPU0_SB_DQ<12>")
	)
	(segment
		(start 304.391314 -297.210226)
		(end 301.45863 -297.210226)
		(width 0.14478)
		(layer "In2.Cu")
		(net "M_C_CPU0_SB_DQ<12>")
	)
	(segment
		(start 314.187586 -292.71849)
		(end 314.024518 -292.881558)
		(width 0.14478)
		(layer "In2.Cu")
		(net "M_C_CPU0_SB_DQ<12>")
	)
	(segment
		(start 311.874408 -294.342312)
		(end 311.71134 -294.50538)
		(width 0.14478)
		(layer "In2.Cu")
		(net "M_C_CPU0_SB_DQ<12>")
	)
	(segment
		(start 337.178142 -282.508706)
		(end 337.16976 -282.513532)
		(width 0.0889)
		(layer "In2.Cu")
		(net "M_C_CPU0_SB_DQ<12>")
	)
	(segment
		(start 311.037986 -295.86809)
		(end 310.874918 -296.031158)
		(width 0.14478)
		(layer "In2.Cu")
		(net "M_C_CPU0_SB_DQ<12>")
	)
	(segment
		(start 326.676258 -282.552902)
		(end 326.0344 -282.552902)
		(width 0.0889)
		(layer "In2.Cu")
		(net "M_C_CPU0_SB_DQ<12>")
	)
	(segment
		(start 312.612786 -294.29329)
		(end 312.449718 -294.456358)
		(width 0.14478)
		(layer "In2.Cu")
		(net "M_C_CPU0_SB_DQ<12>")
	)
	(segment
		(start 308.64937 -296.591228)
		(end 308.64937 -296.521632)
		(width 0.14478)
		(layer "In2.Cu")
		(net "M_C_CPU0_SB_DQ<12>")
	)
	(segment
		(start 311.662318 -295.243758)
		(end 311.431686 -295.243758)
		(width 0.14478)
		(layer "In2.Cu")
		(net "M_C_CPU0_SB_DQ<12>")
	)
	(segment
		(start 294.949118 -297.219878)
		(end 294.566086 -297.60291)
		(width 0.14478)
		(layer "In2.Cu")
		(net "M_C_CPU0_SB_DQ<12>")
	)
	(segment
		(start 311.037986 -295.637458)
		(end 311.037986 -295.86809)
		(width 0.14478)
		(layer "In2.Cu")
		(net "M_C_CPU0_SB_DQ<12>")
	)
	(segment
		(start 309.362348 -296.360088)
		(end 309.200804 -296.521632)
		(width 0.14478)
		(layer "In2.Cu")
		(net "M_C_CPU0_SB_DQ<12>")
	)
	(segment
		(start 338.69249 -282.513532)
		(end 338.684108 -282.508706)
		(width 0.0889)
		(layer "In2.Cu")
		(net "M_C_CPU0_SB_DQ<12>")
	)
	(segment
		(start 309.200804 -296.521632)
		(end 309.200804 -296.591228)
		(width 0.14478)
		(layer "In2.Cu")
		(net "M_C_CPU0_SB_DQ<12>")
	)
	(segment
		(start 304.695098 -297.51401)
		(end 304.391314 -297.210226)
		(width 0.14478)
		(layer "In2.Cu")
		(net "M_C_CPU0_SB_DQ<12>")
	)
	(segment
		(start 313.400186 -293.275258)
		(end 313.400186 -293.50589)
		(width 0.14478)
		(layer "In2.Cu")
		(net "M_C_CPU0_SB_DQ<12>")
	)
	(segment
		(start 341.878158 -282.508706)
		(end 341.869776 -282.513532)
		(width 0.0889)
		(layer "In2.Cu")
		(net "M_C_CPU0_SB_DQ<12>")
	)
	(segment
		(start 293.518336 -297.439842)
		(end 293.355268 -297.60291)
		(width 0.14478)
		(layer "In2.Cu")
		(net "M_C_CPU0_SB_DQ<12>")
	)
	(segment
		(start 322.311776 -282.54706)
		(end 314.701174 -290.157662)
		(width 0.14478)
		(layer "In2.Cu")
		(net "M_C_CPU0_SB_DQ<12>")
	)
	(segment
		(start 333.05242 -282.513532)
		(end 333.044038 -282.508706)
		(width 0.0889)
		(layer "In2.Cu")
		(net "M_C_CPU0_SB_DQ<12>")
	)
	(segment
		(start 311.31764 -295.129712)
		(end 311.087008 -295.129712)
		(width 0.14478)
		(layer "In2.Cu")
		(net "M_C_CPU0_SB_DQ<12>")
	)
	(segment
		(start 312.661808 -293.554912)
		(end 312.49874 -293.71798)
		(width 0.14478)
		(layer "In2.Cu")
		(net "M_C_CPU0_SB_DQ<12>")
	)
	(segment
		(start 308.64937 -296.521632)
		(end 308.487826 -296.360088)
		(width 0.14478)
		(layer "In2.Cu")
		(net "M_C_CPU0_SB_DQ<12>")
	)
	(segment
		(start 310.92394 -295.29278)
		(end 310.92394 -295.523412)
		(width 0.14478)
		(layer "In2.Cu")
		(net "M_C_CPU0_SB_DQ<12>")
	)
	(segment
		(start 314.187586 -292.487858)
		(end 314.187586 -292.71849)
		(width 0.14478)
		(layer "In2.Cu")
		(net "M_C_CPU0_SB_DQ<12>")
	)
	(segment
		(start 311.087008 -295.129712)
		(end 310.92394 -295.29278)
		(width 0.14478)
		(layer "In2.Cu")
		(net "M_C_CPU0_SB_DQ<12>")
	)
	(segment
		(start 312.10504 -294.342312)
		(end 311.874408 -294.342312)
		(width 0.14478)
		(layer "In2.Cu")
		(net "M_C_CPU0_SB_DQ<12>")
	)
	(segment
		(start 340.938104 -282.508706)
		(end 340.929722 -282.513532)
		(width 0.0889)
		(layer "In2.Cu")
		(net "M_C_CPU0_SB_DQ<12>")
	)
	(segment
		(start 313.28614 -293.161212)
		(end 313.400186 -293.275258)
		(width 0.14478)
		(layer "In2.Cu")
		(net "M_C_CPU0_SB_DQ<12>")
	)
	(segment
		(start 310.53024 -295.917112)
		(end 310.299608 -295.917112)
		(width 0.14478)
		(layer "In2.Cu")
		(net "M_C_CPU0_SB_DQ<12>")
	)
	(segment
		(start 297.156886 -297.51401)
		(end 296.862754 -297.219878)
		(width 0.14478)
		(layer "In2.Cu")
		(net "M_C_CPU0_SB_DQ<12>")
	)
	(segment
		(start 313.006486 -293.668958)
		(end 312.89244 -293.554912)
		(width 0.14478)
		(layer "In2.Cu")
		(net "M_C_CPU0_SB_DQ<12>")
	)
	(segment
		(start 311.431686 -295.243758)
		(end 311.31764 -295.129712)
		(width 0.14478)
		(layer "In2.Cu")
		(net "M_C_CPU0_SB_DQ<12>")
	)
	(segment
		(start 298.898564 -296.36974)
		(end 298.058078 -297.210226)
		(width 0.14478)
		(layer "In2.Cu")
		(net "M_C_CPU0_SB_DQ<12>")
	)
	(segment
		(start 297.735752 -297.210226)
		(end 297.431968 -297.51401)
		(width 0.14478)
		(layer "In2.Cu")
		(net "M_C_CPU0_SB_DQ<12>")
	)
	(segment
		(start 312.49874 -293.948612)
		(end 312.612786 -294.062658)
		(width 0.14478)
		(layer "In2.Cu")
		(net "M_C_CPU0_SB_DQ<12>")
	)
	(segment
		(start 311.825386 -294.850058)
		(end 311.825386 -295.08069)
		(width 0.14478)
		(layer "In2.Cu")
		(net "M_C_CPU0_SB_DQ<12>")
	)
	(segment
		(start 309.856632 -296.360088)
		(end 309.362348 -296.360088)
		(width 0.14478)
		(layer "In2.Cu")
		(net "M_C_CPU0_SB_DQ<12>")
	)
	(segment
		(start 297.431968 -297.51401)
		(end 297.156886 -297.51401)
		(width 0.14478)
		(layer "In2.Cu")
		(net "M_C_CPU0_SB_DQ<12>")
	)
	(segment
		(start 313.67984 -292.767512)
		(end 313.449208 -292.767512)
		(width 0.14478)
		(layer "In2.Cu")
		(net "M_C_CPU0_SB_DQ<12>")
	)
	(segment
		(start 296.862754 -297.219878)
		(end 294.949118 -297.219878)
		(width 0.14478)
		(layer "In2.Cu")
		(net "M_C_CPU0_SB_DQ<12>")
	)
	(segment
		(start 313.449208 -292.767512)
		(end 313.28614 -292.93058)
		(width 0.14478)
		(layer "In2.Cu")
		(net "M_C_CPU0_SB_DQ<12>")
	)
	(segment
		(start 329.292458 -282.513532)
		(end 329.284076 -282.508706)
		(width 0.0889)
		(layer "In2.Cu")
		(net "M_C_CPU0_SB_DQ<12>")
	)
	(segment
		(start 342.631014 -282.186126)
		(end 342.47709 -282.451556)
		(width 0.0889)
		(layer "In2.Cu")
		(net "M_C_CPU0_SB_DQ<12>")
	)
	(segment
		(start 294.07485 -297.439842)
		(end 294.07485 -297.184318)
		(width 0.14478)
		(layer "In2.Cu")
		(net "M_C_CPU0_SB_DQ<12>")
	)
	(segment
		(start 324.061074 -282.36291)
		(end 323.876924 -282.54706)
		(width 0.0889)
		(layer "In2.Cu")
		(net "M_C_CPU0_SB_DQ<12>")
	)
	(segment
		(start 328.718164 -282.508706)
		(end 328.709782 -282.513532)
		(width 0.0889)
		(layer "In2.Cu")
		(net "M_C_CPU0_SB_DQ<12>")
	)
	(segment
		(start 331.538072 -282.508706)
		(end 331.52969 -282.513532)
		(width 0.0889)
		(layer "In2.Cu")
		(net "M_C_CPU0_SB_DQ<12>")
	)
	(segment
		(start 305.273964 -297.210226)
		(end 304.97018 -297.51401)
		(width 0.14478)
		(layer "In2.Cu")
		(net "M_C_CPU0_SB_DQ<12>")
	)
	(segment
		(start 325.755254 -282.36291)
		(end 324.061074 -282.36291)
		(width 0.0889)
		(layer "In2.Cu")
		(net "M_C_CPU0_SB_DQ<12>")
	)
	(segment
		(start 310.299608 -295.917112)
		(end 309.856632 -296.360088)
		(width 0.14478)
		(layer "In2.Cu")
		(net "M_C_CPU0_SB_DQ<12>")
	)
	(segment
		(start 312.612786 -294.062658)
		(end 312.612786 -294.29329)
		(width 0.14478)
		(layer "In2.Cu")
		(net "M_C_CPU0_SB_DQ<12>")
	)
	(segment
		(start 293.681404 -297.02125)
		(end 293.518336 -297.184318)
		(width 0.14478)
		(layer "In2.Cu")
		(net "M_C_CPU0_SB_DQ<12>")
	)
	(segment
		(start 308.487826 -296.360088)
		(end 306.426616 -296.360088)
		(width 0.14478)
		(layer "In2.Cu")
		(net "M_C_CPU0_SB_DQ<12>")
	)
	(segment
		(start 294.07485 -297.184318)
		(end 293.911782 -297.02125)
		(width 0.14478)
		(layer "In2.Cu")
		(net "M_C_CPU0_SB_DQ<12>")
	)
	(segment
		(start 342.47709 -282.451556)
		(end 342.381078 -282.476956)
		(width 0.0889)
		(layer "In2.Cu")
		(net "M_C_CPU0_SB_DQ<12>")
	)
	(segment
		(start 327.779888 -282.508452)
		(end 327.758044 -282.520898)
		(width 0.0889)
		(layer "In2.Cu")
		(net "M_C_CPU0_SB_DQ<12>")
	)
	(segment
		(start 311.825386 -295.08069)
		(end 311.662318 -295.243758)
		(width 0.14478)
		(layer "In2.Cu")
		(net "M_C_CPU0_SB_DQ<12>")
	)
	(segment
		(start 312.89244 -293.554912)
		(end 312.661808 -293.554912)
		(width 0.14478)
		(layer "In2.Cu")
		(net "M_C_CPU0_SB_DQ<12>")
	)
	(segment
		(start 294.566086 -297.60291)
		(end 294.237918 -297.60291)
		(width 0.14478)
		(layer "In2.Cu")
		(net "M_C_CPU0_SB_DQ<12>")
	)
	(segment
		(start 336.238088 -282.508706)
		(end 336.229706 -282.513532)
		(width 0.0889)
		(layer "In2.Cu")
		(net "M_C_CPU0_SB_DQ<12>")
	)
	(segment
		(start 325.882254 -282.48991)
		(end 325.755254 -282.36291)
		(width 0.0889)
		(layer "In2.Cu")
		(net "M_C_CPU0_SB_DQ<12>")
	)
	(segment
		(start 293.518336 -297.184318)
		(end 293.518336 -297.439842)
		(width 0.14478)
		(layer "In2.Cu")
		(net "M_C_CPU0_SB_DQ<12>")
	)
	(segment
		(start 313.400186 -293.50589)
		(end 313.237118 -293.668958)
		(width 0.14478)
		(layer "In2.Cu")
		(net "M_C_CPU0_SB_DQ<12>")
	)
	(segment
		(start 300.618144 -296.36974)
		(end 298.898564 -296.36974)
		(width 0.14478)
		(layer "In2.Cu")
		(net "M_C_CPU0_SB_DQ<12>")
	)
	(segment
		(start 311.71134 -294.50538)
		(end 311.71134 -294.736012)
		(width 0.14478)
		(layer "In2.Cu")
		(net "M_C_CPU0_SB_DQ<12>")
	)
	(segment
		(start 312.219086 -294.456358)
		(end 312.10504 -294.342312)
		(width 0.14478)
		(layer "In2.Cu")
		(net "M_C_CPU0_SB_DQ<12>")
	)
	(segment
		(start 327.40727 -282.508706)
		(end 327.379584 -282.492704)
		(width 0.0889)
		(layer "In2.Cu")
		(net "M_C_CPU0_SB_DQ<12>")
	)
	(segment
		(start 304.97018 -297.51401)
		(end 304.695098 -297.51401)
		(width 0.14478)
		(layer "In2.Cu")
		(net "M_C_CPU0_SB_DQ<12>")
	)
	(segment
		(start 309.03926 -296.752772)
		(end 308.810914 -296.752772)
		(width 0.14478)
		(layer "In2.Cu")
		(net "M_C_CPU0_SB_DQ<12>")
	)
	(segment
		(start 310.92394 -295.523412)
		(end 311.037986 -295.637458)
		(width 0.14478)
		(layer "In2.Cu")
		(net "M_C_CPU0_SB_DQ<12>")
	)
	(segment
		(start 314.07354 -292.373812)
		(end 314.187586 -292.487858)
		(width 0.14478)
		(layer "In2.Cu")
		(net "M_C_CPU0_SB_DQ<12>")
	)
	(segment
		(start 292.705282 -297.210734)
		(end 292.705282 -297.210226)
		(width 0.14478)
		(layer "In2.Cu")
		(net "M_C_CPU0_SB_DQ<12>")
	)
	(segment
		(start 332.478126 -282.508706)
		(end 332.469744 -282.513532)
		(width 0.0889)
		(layer "In2.Cu")
		(net "M_C_CPU0_SB_DQ<12>")
	)
	(segment
		(start 294.237918 -297.60291)
		(end 294.07485 -297.439842)
		(width 0.14478)
		(layer "In2.Cu")
		(net "M_C_CPU0_SB_DQ<12>")
	)
	(segment
		(start 293.911782 -297.02125)
		(end 293.681404 -297.02125)
		(width 0.14478)
		(layer "In2.Cu")
		(net "M_C_CPU0_SB_DQ<12>")
	)
	(segment
		(start 313.793886 -292.881558)
		(end 313.67984 -292.767512)
		(width 0.14478)
		(layer "In2.Cu")
		(net "M_C_CPU0_SB_DQ<12>")
	)
	(segment
		(start 301.45863 -297.210226)
		(end 300.618144 -296.36974)
		(width 0.14478)
		(layer "In2.Cu")
		(net "M_C_CPU0_SB_DQ<12>")
	)
	(segment
		(start 293.355268 -297.60291)
		(end 293.097458 -297.60291)
		(width 0.14478)
		(layer "In2.Cu")
		(net "M_C_CPU0_SB_DQ<12>")
	)
	(segment
		(start 306.426616 -296.360088)
		(end 305.576732 -297.209972)
		(width 0.14478)
		(layer "In2.Cu")
		(net "M_C_CPU0_SB_DQ<12>")
	)
	(segment
		(start 298.058078 -297.210226)
		(end 297.735752 -297.210226)
		(width 0.14478)
		(layer "In2.Cu")
		(net "M_C_CPU0_SB_DQ<12>")
	)
	(segment
		(start 308.810914 -296.752772)
		(end 308.64937 -296.591228)
		(width 0.14478)
		(layer "In2.Cu")
		(net "M_C_CPU0_SB_DQ<12>")
	)
	(segment
		(start 310.874918 -296.031158)
		(end 310.644286 -296.031158)
		(width 0.14478)
		(layer "In2.Cu")
		(net "M_C_CPU0_SB_DQ<12>")
	)
	(segment
		(start 314.07354 -292.14318)
		(end 314.07354 -292.373812)
		(width 0.14478)
		(layer "In2.Cu")
		(net "M_C_CPU0_SB_DQ<12>")
	)
	(segment
		(start 314.701174 -291.515546)
		(end 314.07354 -292.14318)
		(width 0.14478)
		(layer "In2.Cu")
		(net "M_C_CPU0_SB_DQ<12>")
	)
	(segment
		(start 313.28614 -292.93058)
		(end 313.28614 -293.161212)
		(width 0.14478)
		(layer "In2.Cu")
		(net "M_C_CPU0_SB_DQ<12>")
	)
	(segment
		(start 314.701174 -290.157662)
		(end 314.701174 -291.515546)
		(width 0.14478)
		(layer "In2.Cu")
		(net "M_C_CPU0_SB_DQ<12>")
	)
	(segment
		(start 333.992474 -282.513532)
		(end 333.984092 -282.508706)
		(width 0.0889)
		(layer "In2.Cu")
		(net "M_C_CPU0_SB_DQ<12>")
	)
	(segment
		(start 323.876924 -282.54706)
		(end 322.311776 -282.54706)
		(width 0.14478)
		(layer "In2.Cu")
		(net "M_C_CPU0_SB_DQ<12>")
	)
	(segment
		(start 312.449718 -294.456358)
		(end 312.219086 -294.456358)
		(width 0.14478)
		(layer "In2.Cu")
		(net "M_C_CPU0_SB_DQ<12>")
	)
	(segment
		(start 305.576732 -297.209972)
		(end 305.57597 -297.210226)
		(width 0.14478)
		(layer "In2.Cu")
		(net "M_C_CPU0_SB_DQ<12>")
	)
	(segment
		(start 314.024518 -292.881558)
		(end 313.793886 -292.881558)
		(width 0.14478)
		(layer "In2.Cu")
		(net "M_C_CPU0_SB_DQ<12>")
	)
	(segment
		(start 309.200804 -296.591228)
		(end 309.03926 -296.752772)
		(width 0.14478)
		(layer "In2.Cu")
		(net "M_C_CPU0_SB_DQ<12>")
	)
	(segment
		(start 312.49874 -293.71798)
		(end 312.49874 -293.948612)
		(width 0.14478)
		(layer "In2.Cu")
		(net "M_C_CPU0_SB_DQ<12>")
	)
	(segment
		(start 293.097458 -297.60291)
		(end 292.705282 -297.210734)
		(width 0.14478)
		(layer "In2.Cu")
		(net "M_C_CPU0_SB_DQ<12>")
	)
	(arc
		(start 340.929722 -282.513532)
		(mid 340.746214 -282.559026)
		(end 340.563962 -282.508706)
		(width 0.0889)
		(layer "In2.Cu")
		(net "M_C_CPU0_SB_DQ<12>")
	)
	(arc
		(start 335.863946 -282.508706)
		(mid 335.58099 -282.432529)
		(end 335.298034 -282.508706)
		(width 0.0889)
		(layer "In2.Cu")
		(net "M_C_CPU0_SB_DQ<12>")
	)
	(arc
		(start 332.469744 -282.513532)
		(mid 332.286236 -282.559026)
		(end 332.103984 -282.508706)
		(width 0.0889)
		(layer "In2.Cu")
		(net "M_C_CPU0_SB_DQ<12>")
	)
	(arc
		(start 341.504016 -282.508706)
		(mid 341.22106 -282.432529)
		(end 340.938104 -282.508706)
		(width 0.0889)
		(layer "In2.Cu")
		(net "M_C_CPU0_SB_DQ<12>")
	)
	(arc
		(start 341.869776 -282.513532)
		(mid 341.686268 -282.559026)
		(end 341.504016 -282.508706)
		(width 0.0889)
		(layer "In2.Cu")
		(net "M_C_CPU0_SB_DQ<12>")
	)
	(arc
		(start 329.658218 -282.508706)
		(mid 329.475967 -282.559056)
		(end 329.292458 -282.513532)
		(width 0.0889)
		(layer "In2.Cu")
		(net "M_C_CPU0_SB_DQ<12>")
	)
	(arc
		(start 331.52969 -282.513532)
		(mid 331.346182 -282.559026)
		(end 331.16393 -282.508706)
		(width 0.0889)
		(layer "In2.Cu")
		(net "M_C_CPU0_SB_DQ<12>")
	)
	(arc
		(start 339.624162 -282.508706)
		(mid 339.341206 -282.432529)
		(end 339.05825 -282.508706)
		(width 0.0889)
		(layer "In2.Cu")
		(net "M_C_CPU0_SB_DQ<12>")
	)
	(arc
		(start 327.379584 -282.492704)
		(mid 327.10755 -282.431932)
		(end 326.83958 -282.508706)
		(width 0.0889)
		(layer "In2.Cu")
		(net "M_C_CPU0_SB_DQ<12>")
	)
	(arc
		(start 327.758044 -282.520898)
		(mid 327.581116 -282.558726)
		(end 327.40727 -282.508706)
		(width 0.0889)
		(layer "In2.Cu")
		(net "M_C_CPU0_SB_DQ<12>")
	)
	(arc
		(start 338.684108 -282.508706)
		(mid 338.401152 -282.432529)
		(end 338.118196 -282.508706)
		(width 0.0889)
		(layer "In2.Cu")
		(net "M_C_CPU0_SB_DQ<12>")
	)
	(arc
		(start 326.0344 -282.552902)
		(mid 325.95207 -282.536526)
		(end 325.882254 -282.48991)
		(width 0.0889)
		(layer "In2.Cu")
		(net "M_C_CPU0_SB_DQ<12>")
	)
	(arc
		(start 334.358234 -282.508706)
		(mid 334.175983 -282.559056)
		(end 333.992474 -282.513532)
		(width 0.0889)
		(layer "In2.Cu")
		(net "M_C_CPU0_SB_DQ<12>")
	)
	(arc
		(start 326.83958 -282.508706)
		(mid 326.760861 -282.541685)
		(end 326.676258 -282.552902)
		(width 0.0889)
		(layer "In2.Cu")
		(net "M_C_CPU0_SB_DQ<12>")
	)
	(arc
		(start 328.709782 -282.513532)
		(mid 328.526274 -282.559026)
		(end 328.344022 -282.508706)
		(width 0.0889)
		(layer "In2.Cu")
		(net "M_C_CPU0_SB_DQ<12>")
	)
	(arc
		(start 333.41818 -282.508706)
		(mid 333.235929 -282.559056)
		(end 333.05242 -282.513532)
		(width 0.0889)
		(layer "In2.Cu")
		(net "M_C_CPU0_SB_DQ<12>")
	)
	(arc
		(start 330.598018 -282.508706)
		(mid 330.411074 -282.558961)
		(end 330.22413 -282.508706)
		(width 0.0889)
		(layer "In2.Cu")
		(net "M_C_CPU0_SB_DQ<12>")
	)
	(arc
		(start 329.284076 -282.508706)
		(mid 329.00112 -282.432529)
		(end 328.718164 -282.508706)
		(width 0.0889)
		(layer "In2.Cu")
		(net "M_C_CPU0_SB_DQ<12>")
	)
	(arc
		(start 342.381078 -282.476956)
		(mid 342.12587 -282.433479)
		(end 341.878158 -282.508706)
		(width 0.0889)
		(layer "In2.Cu")
		(net "M_C_CPU0_SB_DQ<12>")
	)
	(arc
		(start 333.984092 -282.508706)
		(mid 333.701136 -282.432529)
		(end 333.41818 -282.508706)
		(width 0.0889)
		(layer "In2.Cu")
		(net "M_C_CPU0_SB_DQ<12>")
	)
	(arc
		(start 331.16393 -282.508706)
		(mid 330.880974 -282.432529)
		(end 330.598018 -282.508706)
		(width 0.0889)
		(layer "In2.Cu")
		(net "M_C_CPU0_SB_DQ<12>")
	)
	(arc
		(start 334.924146 -282.508706)
		(mid 334.64119 -282.432529)
		(end 334.358234 -282.508706)
		(width 0.0889)
		(layer "In2.Cu")
		(net "M_C_CPU0_SB_DQ<12>")
	)
	(arc
		(start 337.16976 -282.513532)
		(mid 336.986252 -282.559026)
		(end 336.804 -282.508706)
		(width 0.0889)
		(layer "In2.Cu")
		(net "M_C_CPU0_SB_DQ<12>")
	)
	(arc
		(start 337.744054 -282.508706)
		(mid 337.461098 -282.432529)
		(end 337.178142 -282.508706)
		(width 0.0889)
		(layer "In2.Cu")
		(net "M_C_CPU0_SB_DQ<12>")
	)
	(arc
		(start 339.99805 -282.508706)
		(mid 339.811106 -282.558961)
		(end 339.624162 -282.508706)
		(width 0.0889)
		(layer "In2.Cu")
		(net "M_C_CPU0_SB_DQ<12>")
	)
	(arc
		(start 336.229706 -282.513532)
		(mid 336.046198 -282.559026)
		(end 335.863946 -282.508706)
		(width 0.0889)
		(layer "In2.Cu")
		(net "M_C_CPU0_SB_DQ<12>")
	)
	(arc
		(start 340.563962 -282.508706)
		(mid 340.281006 -282.432529)
		(end 339.99805 -282.508706)
		(width 0.0889)
		(layer "In2.Cu")
		(net "M_C_CPU0_SB_DQ<12>")
	)
	(arc
		(start 339.05825 -282.508706)
		(mid 338.875999 -282.559056)
		(end 338.69249 -282.513532)
		(width 0.0889)
		(layer "In2.Cu")
		(net "M_C_CPU0_SB_DQ<12>")
	)
	(arc
		(start 332.103984 -282.508706)
		(mid 331.821028 -282.432529)
		(end 331.538072 -282.508706)
		(width 0.0889)
		(layer "In2.Cu")
		(net "M_C_CPU0_SB_DQ<12>")
	)
	(arc
		(start 330.22413 -282.508706)
		(mid 329.941174 -282.432529)
		(end 329.658218 -282.508706)
		(width 0.0889)
		(layer "In2.Cu")
		(net "M_C_CPU0_SB_DQ<12>")
	)
	(arc
		(start 328.344022 -282.508706)
		(mid 328.075702 -282.432598)
		(end 327.803764 -282.494482)
		(width 0.0889)
		(layer "In2.Cu")
		(net "M_C_CPU0_SB_DQ<12>")
	)
	(arc
		(start 338.118196 -282.508706)
		(mid 337.935945 -282.559056)
		(end 337.752436 -282.513532)
		(width 0.0889)
		(layer "In2.Cu")
		(net "M_C_CPU0_SB_DQ<12>")
	)
	(arc
		(start 335.298034 -282.508706)
		(mid 335.11109 -282.558961)
		(end 334.924146 -282.508706)
		(width 0.0889)
		(layer "In2.Cu")
		(net "M_C_CPU0_SB_DQ<12>")
	)
	(arc
		(start 333.044038 -282.508706)
		(mid 332.761082 -282.432529)
		(end 332.478126 -282.508706)
		(width 0.0889)
		(layer "In2.Cu")
		(net "M_C_CPU0_SB_DQ<12>")
	)
	(arc
		(start 336.804 -282.508706)
		(mid 336.521044 -282.432529)
		(end 336.238088 -282.508706)
		(width 0.0889)
		(layer "In2.Cu")
		(net "M_C_CPU0_SB_DQ<12>")
	)
	(segment
		(start 344.03792 -280.300176)
		(end 343.571068 -280.566114)
		(width 0.10668)
		(layer "F.Cu")
		(net "M_C_CPU0_SB_DQ<11>")
	)
	(segment
		(start 297.34256 -293.800276)
		(end 290.296854 -293.800276)
		(width 0.14478)
		(layer "In2.Cu")
		(net "M_C_CPU0_SB_DQ<11>")
	)
	(segment
		(start 316.50432 -285.071566)
		(end 316.266576 -285.071566)
		(width 0.14478)
		(layer "In2.Cu")
		(net "M_C_CPU0_SB_DQ<11>")
	)
	(segment
		(start 301.407576 -292.950392)
		(end 298.192444 -292.950392)
		(width 0.14478)
		(layer "In2.Cu")
		(net "M_C_CPU0_SB_DQ<11>")
	)
	(segment
		(start 337.752436 -280.238708)
		(end 337.744054 -280.243534)
		(width 0.0889)
		(layer "In2.Cu")
		(net "M_C_CPU0_SB_DQ<11>")
	)
	(segment
		(start 289.587686 -293.127684)
		(end 289.587686 -293.647368)
		(width 0.14478)
		(layer "In2.Cu")
		(net "M_C_CPU0_SB_DQ<11>")
	)
	(segment
		(start 327.407778 -280.243534)
		(end 327.378314 -280.260806)
		(width 0.0889)
		(layer "In2.Cu")
		(net "M_C_CPU0_SB_DQ<11>")
	)
	(segment
		(start 289.424872 -293.810182)
		(end 288.605214 -293.810182)
		(width 0.14478)
		(layer "In2.Cu")
		(net "M_C_CPU0_SB_DQ<11>")
	)
	(segment
		(start 321.368166 -280.20772)
		(end 316.50432 -285.071566)
		(width 0.14478)
		(layer "In2.Cu")
		(net "M_C_CPU0_SB_DQ<11>")
	)
	(segment
		(start 289.7505 -292.96487)
		(end 289.587686 -293.127684)
		(width 0.14478)
		(layer "In2.Cu")
		(net "M_C_CPU0_SB_DQ<11>")
	)
	(segment
		(start 290.296854 -293.800276)
		(end 290.143946 -293.647368)
		(width 0.14478)
		(layer "In2.Cu")
		(net "M_C_CPU0_SB_DQ<11>")
	)
	(segment
		(start 333.05242 -280.238708)
		(end 333.044038 -280.243534)
		(width 0.0889)
		(layer "In2.Cu")
		(net "M_C_CPU0_SB_DQ<11>")
	)
	(segment
		(start 298.192444 -292.950392)
		(end 297.34256 -293.800276)
		(width 0.14478)
		(layer "In2.Cu")
		(net "M_C_CPU0_SB_DQ<11>")
	)
	(segment
		(start 290.143946 -293.647368)
		(end 290.143946 -293.127684)
		(width 0.14478)
		(layer "In2.Cu")
		(net "M_C_CPU0_SB_DQ<11>")
	)
	(segment
		(start 305.329844 -292.960044)
		(end 304.479706 -293.810182)
		(width 0.14478)
		(layer "In2.Cu")
		(net "M_C_CPU0_SB_DQ<11>")
	)
	(segment
		(start 342.452452 -280.238708)
		(end 342.44407 -280.243534)
		(width 0.0889)
		(layer "In2.Cu")
		(net "M_C_CPU0_SB_DQ<11>")
	)
	(segment
		(start 340.938104 -280.243534)
		(end 340.929722 -280.238708)
		(width 0.0889)
		(layer "In2.Cu")
		(net "M_C_CPU0_SB_DQ<11>")
	)
	(segment
		(start 289.587686 -293.647368)
		(end 289.424872 -293.810182)
		(width 0.14478)
		(layer "In2.Cu")
		(net "M_C_CPU0_SB_DQ<11>")
	)
	(segment
		(start 323.953124 -280.20772)
		(end 321.368166 -280.20772)
		(width 0.14478)
		(layer "In2.Cu")
		(net "M_C_CPU0_SB_DQ<11>")
	)
	(segment
		(start 337.178142 -280.243534)
		(end 337.16976 -280.238708)
		(width 0.0889)
		(layer "In2.Cu")
		(net "M_C_CPU0_SB_DQ<11>")
	)
	(segment
		(start 288.605214 -293.810182)
		(end 288.180018 -293.384986)
		(width 0.14478)
		(layer "In2.Cu")
		(net "M_C_CPU0_SB_DQ<11>")
	)
	(segment
		(start 341.878158 -280.243534)
		(end 341.869776 -280.238708)
		(width 0.0889)
		(layer "In2.Cu")
		(net "M_C_CPU0_SB_DQ<11>")
	)
	(segment
		(start 328.718164 -280.243534)
		(end 328.709782 -280.238708)
		(width 0.0889)
		(layer "In2.Cu")
		(net "M_C_CPU0_SB_DQ<11>")
	)
	(segment
		(start 327.806304 -280.258774)
		(end 327.780142 -280.243788)
		(width 0.0889)
		(layer "In2.Cu")
		(net "M_C_CPU0_SB_DQ<11>")
	)
	(segment
		(start 333.992474 -280.238708)
		(end 333.984092 -280.243534)
		(width 0.0889)
		(layer "In2.Cu")
		(net "M_C_CPU0_SB_DQ<11>")
	)
	(segment
		(start 316.266576 -285.071566)
		(end 308.378098 -292.960044)
		(width 0.14478)
		(layer "In2.Cu")
		(net "M_C_CPU0_SB_DQ<11>")
	)
	(segment
		(start 343.725246 -280.300684)
		(end 343.702894 -280.217372)
		(width 0.0889)
		(layer "In2.Cu")
		(net "M_C_CPU0_SB_DQ<11>")
	)
	(segment
		(start 343.392506 -280.238708)
		(end 343.384124 -280.243534)
		(width 0.0889)
		(layer "In2.Cu")
		(net "M_C_CPU0_SB_DQ<11>")
	)
	(segment
		(start 304.479706 -293.810182)
		(end 302.267366 -293.810182)
		(width 0.14478)
		(layer "In2.Cu")
		(net "M_C_CPU0_SB_DQ<11>")
	)
	(segment
		(start 327.780142 -280.243788)
		(end 327.756774 -280.230326)
		(width 0.0889)
		(layer "In2.Cu")
		(net "M_C_CPU0_SB_DQ<11>")
	)
	(segment
		(start 289.981132 -292.96487)
		(end 289.7505 -292.96487)
		(width 0.14478)
		(layer "In2.Cu")
		(net "M_C_CPU0_SB_DQ<11>")
	)
	(segment
		(start 302.267366 -293.810182)
		(end 301.407576 -292.950392)
		(width 0.14478)
		(layer "In2.Cu")
		(net "M_C_CPU0_SB_DQ<11>")
	)
	(segment
		(start 290.143946 -293.127684)
		(end 289.981132 -292.96487)
		(width 0.14478)
		(layer "In2.Cu")
		(net "M_C_CPU0_SB_DQ<11>")
	)
	(segment
		(start 336.238088 -280.243534)
		(end 336.229706 -280.238708)
		(width 0.0889)
		(layer "In2.Cu")
		(net "M_C_CPU0_SB_DQ<11>")
	)
	(segment
		(start 326.707754 -280.20772)
		(end 323.953124 -280.20772)
		(width 0.0889)
		(layer "In2.Cu")
		(net "M_C_CPU0_SB_DQ<11>")
	)
	(segment
		(start 338.69249 -280.238708)
		(end 338.684108 -280.243534)
		(width 0.0889)
		(layer "In2.Cu")
		(net "M_C_CPU0_SB_DQ<11>")
	)
	(segment
		(start 331.538072 -280.243534)
		(end 331.52969 -280.238708)
		(width 0.0889)
		(layer "In2.Cu")
		(net "M_C_CPU0_SB_DQ<11>")
	)
	(segment
		(start 329.292458 -280.238708)
		(end 329.284076 -280.243534)
		(width 0.0889)
		(layer "In2.Cu")
		(net "M_C_CPU0_SB_DQ<11>")
	)
	(segment
		(start 332.478126 -280.243534)
		(end 332.469744 -280.238708)
		(width 0.0889)
		(layer "In2.Cu")
		(net "M_C_CPU0_SB_DQ<11>")
	)
	(segment
		(start 308.378098 -292.960044)
		(end 305.329844 -292.960044)
		(width 0.14478)
		(layer "In2.Cu")
		(net "M_C_CPU0_SB_DQ<11>")
	)
	(segment
		(start 343.571068 -280.566114)
		(end 343.725246 -280.300684)
		(width 0.0889)
		(layer "In2.Cu")
		(net "M_C_CPU0_SB_DQ<11>")
	)
	(arc
		(start 329.284076 -280.243534)
		(mid 329.00112 -280.319711)
		(end 328.718164 -280.243534)
		(width 0.0889)
		(layer "In2.Cu")
		(net "M_C_CPU0_SB_DQ<11>")
	)
	(arc
		(start 339.99805 -280.243534)
		(mid 339.811106 -280.193279)
		(end 339.624162 -280.243534)
		(width 0.0889)
		(layer "In2.Cu")
		(net "M_C_CPU0_SB_DQ<11>")
	)
	(arc
		(start 340.563962 -280.243534)
		(mid 340.281006 -280.319711)
		(end 339.99805 -280.243534)
		(width 0.0889)
		(layer "In2.Cu")
		(net "M_C_CPU0_SB_DQ<11>")
	)
	(arc
		(start 336.229706 -280.238708)
		(mid 336.046198 -280.193214)
		(end 335.863946 -280.243534)
		(width 0.0889)
		(layer "In2.Cu")
		(net "M_C_CPU0_SB_DQ<11>")
	)
	(arc
		(start 342.44407 -280.243534)
		(mid 342.161114 -280.319711)
		(end 341.878158 -280.243534)
		(width 0.0889)
		(layer "In2.Cu")
		(net "M_C_CPU0_SB_DQ<11>")
	)
	(arc
		(start 330.22413 -280.243534)
		(mid 329.941174 -280.319711)
		(end 329.658218 -280.243534)
		(width 0.0889)
		(layer "In2.Cu")
		(net "M_C_CPU0_SB_DQ<11>")
	)
	(arc
		(start 333.044038 -280.243534)
		(mid 332.761082 -280.319711)
		(end 332.478126 -280.243534)
		(width 0.0889)
		(layer "In2.Cu")
		(net "M_C_CPU0_SB_DQ<11>")
	)
	(arc
		(start 334.358234 -280.243534)
		(mid 334.175983 -280.193184)
		(end 333.992474 -280.238708)
		(width 0.0889)
		(layer "In2.Cu")
		(net "M_C_CPU0_SB_DQ<11>")
	)
	(arc
		(start 338.118196 -280.243534)
		(mid 337.935945 -280.193184)
		(end 337.752436 -280.238708)
		(width 0.0889)
		(layer "In2.Cu")
		(net "M_C_CPU0_SB_DQ<11>")
	)
	(arc
		(start 333.984092 -280.243534)
		(mid 333.701136 -280.319711)
		(end 333.41818 -280.243534)
		(width 0.0889)
		(layer "In2.Cu")
		(net "M_C_CPU0_SB_DQ<11>")
	)
	(arc
		(start 341.869776 -280.238708)
		(mid 341.686268 -280.193214)
		(end 341.504016 -280.243534)
		(width 0.0889)
		(layer "In2.Cu")
		(net "M_C_CPU0_SB_DQ<11>")
	)
	(arc
		(start 336.804 -280.243534)
		(mid 336.521044 -280.319711)
		(end 336.238088 -280.243534)
		(width 0.0889)
		(layer "In2.Cu")
		(net "M_C_CPU0_SB_DQ<11>")
	)
	(arc
		(start 326.839834 -280.243534)
		(mid 326.776176 -280.216849)
		(end 326.707754 -280.20772)
		(width 0.0889)
		(layer "In2.Cu")
		(net "M_C_CPU0_SB_DQ<11>")
	)
	(arc
		(start 331.52969 -280.238708)
		(mid 331.346182 -280.193214)
		(end 331.16393 -280.243534)
		(width 0.0889)
		(layer "In2.Cu")
		(net "M_C_CPU0_SB_DQ<11>")
	)
	(arc
		(start 343.702894 -280.217372)
		(mid 343.545384 -280.194174)
		(end 343.392506 -280.238708)
		(width 0.0889)
		(layer "In2.Cu")
		(net "M_C_CPU0_SB_DQ<11>")
	)
	(arc
		(start 341.504016 -280.243534)
		(mid 341.22106 -280.319711)
		(end 340.938104 -280.243534)
		(width 0.0889)
		(layer "In2.Cu")
		(net "M_C_CPU0_SB_DQ<11>")
	)
	(arc
		(start 328.344022 -280.243534)
		(mid 328.077092 -280.319483)
		(end 327.806304 -280.258774)
		(width 0.0889)
		(layer "In2.Cu")
		(net "M_C_CPU0_SB_DQ<11>")
	)
	(arc
		(start 340.929722 -280.238708)
		(mid 340.746214 -280.193214)
		(end 340.563962 -280.243534)
		(width 0.0889)
		(layer "In2.Cu")
		(net "M_C_CPU0_SB_DQ<11>")
	)
	(arc
		(start 332.469744 -280.238708)
		(mid 332.286236 -280.193214)
		(end 332.103984 -280.243534)
		(width 0.0889)
		(layer "In2.Cu")
		(net "M_C_CPU0_SB_DQ<11>")
	)
	(arc
		(start 342.818212 -280.243534)
		(mid 342.635961 -280.193184)
		(end 342.452452 -280.238708)
		(width 0.0889)
		(layer "In2.Cu")
		(net "M_C_CPU0_SB_DQ<11>")
	)
	(arc
		(start 333.41818 -280.243534)
		(mid 333.235929 -280.193184)
		(end 333.05242 -280.238708)
		(width 0.0889)
		(layer "In2.Cu")
		(net "M_C_CPU0_SB_DQ<11>")
	)
	(arc
		(start 335.298034 -280.243534)
		(mid 335.11109 -280.193279)
		(end 334.924146 -280.243534)
		(width 0.0889)
		(layer "In2.Cu")
		(net "M_C_CPU0_SB_DQ<11>")
	)
	(arc
		(start 337.16976 -280.238708)
		(mid 336.986252 -280.193214)
		(end 336.804 -280.243534)
		(width 0.0889)
		(layer "In2.Cu")
		(net "M_C_CPU0_SB_DQ<11>")
	)
	(arc
		(start 339.05825 -280.243534)
		(mid 338.875999 -280.193184)
		(end 338.69249 -280.238708)
		(width 0.0889)
		(layer "In2.Cu")
		(net "M_C_CPU0_SB_DQ<11>")
	)
	(arc
		(start 328.709782 -280.238708)
		(mid 328.526274 -280.193214)
		(end 328.344022 -280.243534)
		(width 0.0889)
		(layer "In2.Cu")
		(net "M_C_CPU0_SB_DQ<11>")
	)
	(arc
		(start 331.16393 -280.243534)
		(mid 330.880974 -280.319711)
		(end 330.598018 -280.243534)
		(width 0.0889)
		(layer "In2.Cu")
		(net "M_C_CPU0_SB_DQ<11>")
	)
	(arc
		(start 332.103984 -280.243534)
		(mid 331.821028 -280.319711)
		(end 331.538072 -280.243534)
		(width 0.0889)
		(layer "In2.Cu")
		(net "M_C_CPU0_SB_DQ<11>")
	)
	(arc
		(start 327.378314 -280.260806)
		(mid 327.106894 -280.320483)
		(end 326.839834 -280.243534)
		(width 0.0889)
		(layer "In2.Cu")
		(net "M_C_CPU0_SB_DQ<11>")
	)
	(arc
		(start 334.924146 -280.243534)
		(mid 334.64119 -280.319711)
		(end 334.358234 -280.243534)
		(width 0.0889)
		(layer "In2.Cu")
		(net "M_C_CPU0_SB_DQ<11>")
	)
	(arc
		(start 327.756774 -280.230326)
		(mid 327.580632 -280.193534)
		(end 327.407778 -280.243534)
		(width 0.0889)
		(layer "In2.Cu")
		(net "M_C_CPU0_SB_DQ<11>")
	)
	(arc
		(start 335.863946 -280.243534)
		(mid 335.58099 -280.319711)
		(end 335.298034 -280.243534)
		(width 0.0889)
		(layer "In2.Cu")
		(net "M_C_CPU0_SB_DQ<11>")
	)
	(arc
		(start 329.658218 -280.243534)
		(mid 329.475967 -280.193184)
		(end 329.292458 -280.238708)
		(width 0.0889)
		(layer "In2.Cu")
		(net "M_C_CPU0_SB_DQ<11>")
	)
	(arc
		(start 337.744054 -280.243534)
		(mid 337.461098 -280.319711)
		(end 337.178142 -280.243534)
		(width 0.0889)
		(layer "In2.Cu")
		(net "M_C_CPU0_SB_DQ<11>")
	)
	(arc
		(start 330.598018 -280.243534)
		(mid 330.411074 -280.193279)
		(end 330.22413 -280.243534)
		(width 0.0889)
		(layer "In2.Cu")
		(net "M_C_CPU0_SB_DQ<11>")
	)
	(arc
		(start 339.624162 -280.243534)
		(mid 339.341206 -280.319711)
		(end 339.05825 -280.243534)
		(width 0.0889)
		(layer "In2.Cu")
		(net "M_C_CPU0_SB_DQ<11>")
	)
	(arc
		(start 338.684108 -280.243534)
		(mid 338.401152 -280.319711)
		(end 338.118196 -280.243534)
		(width 0.0889)
		(layer "In2.Cu")
		(net "M_C_CPU0_SB_DQ<11>")
	)
	(arc
		(start 343.384124 -280.243534)
		(mid 343.101168 -280.319711)
		(end 342.818212 -280.243534)
		(width 0.0889)
		(layer "In2.Cu")
		(net "M_C_CPU0_SB_DQ<11>")
	)
	(segment
		(start 342.627966 -279.49017)
		(end 342.161114 -279.756108)
		(width 0.10668)
		(layer "F.Cu")
		(net "M_C_CPU0_SB_DQ<10>")
	)
	(segment
		(start 297.349926 -292.505892)
		(end 296.495978 -292.505892)
		(width 0.14478)
		(layer "In2.Cu")
		(net "M_C_CPU0_SB_DQ<10>")
	)
	(segment
		(start 323.903594 -279.2984)
		(end 321.00393 -279.2984)
		(width 0.14478)
		(layer "In2.Cu")
		(net "M_C_CPU0_SB_DQ<10>")
	)
	(segment
		(start 326.935846 -279.433528)
		(end 326.91832 -279.443688)
		(width 0.0889)
		(layer "In2.Cu")
		(net "M_C_CPU0_SB_DQ<10>")
	)
	(segment
		(start 308.805834 -291.260022)
		(end 306.342796 -291.260022)
		(width 0.14478)
		(layer "In2.Cu")
		(net "M_C_CPU0_SB_DQ<10>")
	)
	(segment
		(start 335.402428 -279.428702)
		(end 335.394046 -279.433528)
		(width 0.0889)
		(layer "In2.Cu")
		(net "M_C_CPU0_SB_DQ<10>")
	)
	(segment
		(start 290.263834 -292.11016)
		(end 290.10102 -291.947346)
		(width 0.14478)
		(layer "In2.Cu")
		(net "M_C_CPU0_SB_DQ<10>")
	)
	(segment
		(start 326.651112 -279.516078)
		(end 326.650858 -279.516078)
		(width 0.0889)
		(layer "In2.Cu")
		(net "M_C_CPU0_SB_DQ<10>")
	)
	(segment
		(start 290.10102 -291.352224)
		(end 289.938206 -291.18941)
		(width 0.14478)
		(layer "In2.Cu")
		(net "M_C_CPU0_SB_DQ<10>")
	)
	(segment
		(start 288.605214 -292.11016)
		(end 288.180018 -291.684964)
		(width 0.14478)
		(layer "In2.Cu")
		(net "M_C_CPU0_SB_DQ<10>")
	)
	(segment
		(start 290.65728 -291.947346)
		(end 290.494466 -292.11016)
		(width 0.14478)
		(layer "In2.Cu")
		(net "M_C_CPU0_SB_DQ<10>")
	)
	(segment
		(start 333.88808 -279.433528)
		(end 333.879698 -279.428702)
		(width 0.0889)
		(layer "In2.Cu")
		(net "M_C_CPU0_SB_DQ<10>")
	)
	(segment
		(start 305.364134 -291.639244)
		(end 304.893218 -292.11016)
		(width 0.14478)
		(layer "In2.Cu")
		(net "M_C_CPU0_SB_DQ<10>")
	)
	(segment
		(start 298.595796 -291.260022)
		(end 297.349926 -292.505892)
		(width 0.14478)
		(layer "In2.Cu")
		(net "M_C_CPU0_SB_DQ<10>")
	)
	(segment
		(start 289.707574 -291.18941)
		(end 289.54476 -291.352224)
		(width 0.14478)
		(layer "In2.Cu")
		(net "M_C_CPU0_SB_DQ<10>")
	)
	(segment
		(start 302.348646 -292.11016)
		(end 301.923196 -291.68471)
		(width 0.14478)
		(layer "In2.Cu")
		(net "M_C_CPU0_SB_DQ<10>")
	)
	(segment
		(start 289.54476 -291.352224)
		(end 289.54476 -291.947346)
		(width 0.14478)
		(layer "In2.Cu")
		(net "M_C_CPU0_SB_DQ<10>")
	)
	(segment
		(start 340.102444 -279.428702)
		(end 340.094062 -279.433528)
		(width 0.0889)
		(layer "In2.Cu")
		(net "M_C_CPU0_SB_DQ<10>")
	)
	(segment
		(start 300.768766 -291.260022)
		(end 298.595796 -291.260022)
		(width 0.14478)
		(layer "In2.Cu")
		(net "M_C_CPU0_SB_DQ<10>")
	)
	(segment
		(start 290.10102 -291.947346)
		(end 290.10102 -291.352224)
		(width 0.14478)
		(layer "In2.Cu")
		(net "M_C_CPU0_SB_DQ<10>")
	)
	(segment
		(start 290.494466 -292.11016)
		(end 290.263834 -292.11016)
		(width 0.14478)
		(layer "In2.Cu")
		(net "M_C_CPU0_SB_DQ<10>")
	)
	(segment
		(start 327.875392 -279.433782)
		(end 327.851516 -279.447752)
		(width 0.0889)
		(layer "In2.Cu")
		(net "M_C_CPU0_SB_DQ<10>")
	)
	(segment
		(start 304.893218 -292.11016)
		(end 302.348646 -292.11016)
		(width 0.14478)
		(layer "In2.Cu")
		(net "M_C_CPU0_SB_DQ<10>")
	)
	(segment
		(start 290.820094 -291.18941)
		(end 290.65728 -291.352224)
		(width 0.14478)
		(layer "In2.Cu")
		(net "M_C_CPU0_SB_DQ<10>")
	)
	(segment
		(start 342.315038 -279.490678)
		(end 342.292686 -279.407366)
		(width 0.0889)
		(layer "In2.Cu")
		(net "M_C_CPU0_SB_DQ<10>")
	)
	(segment
		(start 289.54476 -291.947346)
		(end 289.381946 -292.11016)
		(width 0.14478)
		(layer "In2.Cu")
		(net "M_C_CPU0_SB_DQ<10>")
	)
	(segment
		(start 305.963574 -291.639244)
		(end 305.364134 -291.639244)
		(width 0.14478)
		(layer "In2.Cu")
		(net "M_C_CPU0_SB_DQ<10>")
	)
	(segment
		(start 342.161114 -279.756108)
		(end 342.315038 -279.490678)
		(width 0.0889)
		(layer "In2.Cu")
		(net "M_C_CPU0_SB_DQ<10>")
	)
	(segment
		(start 341.042498 -279.428702)
		(end 341.034116 -279.433528)
		(width 0.0889)
		(layer "In2.Cu")
		(net "M_C_CPU0_SB_DQ<10>")
	)
	(segment
		(start 296.495978 -292.505892)
		(end 296.100246 -292.11016)
		(width 0.14478)
		(layer "In2.Cu")
		(net "M_C_CPU0_SB_DQ<10>")
	)
	(segment
		(start 336.342482 -279.428702)
		(end 336.3341 -279.433528)
		(width 0.0889)
		(layer "In2.Cu")
		(net "M_C_CPU0_SB_DQ<10>")
	)
	(segment
		(start 289.381946 -292.11016)
		(end 288.605214 -292.11016)
		(width 0.14478)
		(layer "In2.Cu")
		(net "M_C_CPU0_SB_DQ<10>")
	)
	(segment
		(start 324.481444 -279.2984)
		(end 323.903594 -279.2984)
		(width 0.0889)
		(layer "In2.Cu")
		(net "M_C_CPU0_SB_DQ<10>")
	)
	(segment
		(start 325.634858 -279.08631)
		(end 324.693534 -279.08631)
		(width 0.0889)
		(layer "In2.Cu")
		(net "M_C_CPU0_SB_DQ<10>")
	)
	(segment
		(start 316.371732 -283.930598)
		(end 316.135258 -283.930598)
		(width 0.14478)
		(layer "In2.Cu")
		(net "M_C_CPU0_SB_DQ<10>")
	)
	(segment
		(start 316.135258 -283.930598)
		(end 308.805834 -291.260022)
		(width 0.14478)
		(layer "In2.Cu")
		(net "M_C_CPU0_SB_DQ<10>")
	)
	(segment
		(start 321.00393 -279.2984)
		(end 316.371732 -283.930598)
		(width 0.14478)
		(layer "In2.Cu")
		(net "M_C_CPU0_SB_DQ<10>")
	)
	(segment
		(start 291.21354 -291.947346)
		(end 291.21354 -291.352224)
		(width 0.14478)
		(layer "In2.Cu")
		(net "M_C_CPU0_SB_DQ<10>")
	)
	(segment
		(start 330.128118 -279.433528)
		(end 330.119736 -279.428702)
		(width 0.0889)
		(layer "In2.Cu")
		(net "M_C_CPU0_SB_DQ<10>")
	)
	(segment
		(start 338.588096 -279.433528)
		(end 338.579714 -279.428702)
		(width 0.0889)
		(layer "In2.Cu")
		(net "M_C_CPU0_SB_DQ<10>")
	)
	(segment
		(start 324.693534 -279.08631)
		(end 324.481444 -279.2984)
		(width 0.0889)
		(layer "In2.Cu")
		(net "M_C_CPU0_SB_DQ<10>")
	)
	(segment
		(start 326.05853 -279.270714)
		(end 326.04329 -279.255474)
		(width 0.0889)
		(layer "In2.Cu")
		(net "M_C_CPU0_SB_DQ<10>")
	)
	(segment
		(start 291.376354 -292.11016)
		(end 291.21354 -291.947346)
		(width 0.14478)
		(layer "In2.Cu")
		(net "M_C_CPU0_SB_DQ<10>")
	)
	(segment
		(start 296.100246 -292.11016)
		(end 291.376354 -292.11016)
		(width 0.14478)
		(layer "In2.Cu")
		(net "M_C_CPU0_SB_DQ<10>")
	)
	(segment
		(start 327.311258 -279.433528)
		(end 327.290684 -279.42159)
		(width 0.0889)
		(layer "In2.Cu")
		(net "M_C_CPU0_SB_DQ<10>")
	)
	(segment
		(start 301.193454 -291.68471)
		(end 300.768766 -291.260022)
		(width 0.14478)
		(layer "In2.Cu")
		(net "M_C_CPU0_SB_DQ<10>")
	)
	(segment
		(start 289.938206 -291.18941)
		(end 289.707574 -291.18941)
		(width 0.14478)
		(layer "In2.Cu")
		(net "M_C_CPU0_SB_DQ<10>")
	)
	(segment
		(start 334.828134 -279.433528)
		(end 334.819752 -279.428702)
		(width 0.0889)
		(layer "In2.Cu")
		(net "M_C_CPU0_SB_DQ<10>")
	)
	(segment
		(start 327.89876 -279.42032)
		(end 327.875392 -279.433782)
		(width 0.0889)
		(layer "In2.Cu")
		(net "M_C_CPU0_SB_DQ<10>")
	)
	(segment
		(start 290.65728 -291.352224)
		(end 290.65728 -291.947346)
		(width 0.14478)
		(layer "In2.Cu")
		(net "M_C_CPU0_SB_DQ<10>")
	)
	(segment
		(start 306.342796 -291.260022)
		(end 305.963574 -291.639244)
		(width 0.14478)
		(layer "In2.Cu")
		(net "M_C_CPU0_SB_DQ<10>")
	)
	(segment
		(start 291.050726 -291.18941)
		(end 290.820094 -291.18941)
		(width 0.14478)
		(layer "In2.Cu")
		(net "M_C_CPU0_SB_DQ<10>")
	)
	(segment
		(start 330.702412 -279.428702)
		(end 330.69403 -279.433528)
		(width 0.0889)
		(layer "In2.Cu")
		(net "M_C_CPU0_SB_DQ<10>")
	)
	(segment
		(start 291.21354 -291.352224)
		(end 291.050726 -291.18941)
		(width 0.14478)
		(layer "In2.Cu")
		(net "M_C_CPU0_SB_DQ<10>")
	)
	(segment
		(start 331.642466 -279.428702)
		(end 331.634084 -279.433528)
		(width 0.0889)
		(layer "In2.Cu")
		(net "M_C_CPU0_SB_DQ<10>")
	)
	(segment
		(start 301.923196 -291.68471)
		(end 301.193454 -291.68471)
		(width 0.14478)
		(layer "In2.Cu")
		(net "M_C_CPU0_SB_DQ<10>")
	)
	(segment
		(start 339.52815 -279.433528)
		(end 339.519768 -279.428702)
		(width 0.0889)
		(layer "In2.Cu")
		(net "M_C_CPU0_SB_DQ<10>")
	)
	(arc
		(start 328.814176 -279.433528)
		(mid 328.53122 -279.509705)
		(end 328.248264 -279.433528)
		(width 0.0889)
		(layer "In2.Cu")
		(net "M_C_CPU0_SB_DQ<10>")
	)
	(arc
		(start 339.154008 -279.433528)
		(mid 338.871052 -279.509705)
		(end 338.588096 -279.433528)
		(width 0.0889)
		(layer "In2.Cu")
		(net "M_C_CPU0_SB_DQ<10>")
	)
	(arc
		(start 327.851516 -279.447752)
		(mid 327.579579 -279.509578)
		(end 327.311258 -279.433528)
		(width 0.0889)
		(layer "In2.Cu")
		(net "M_C_CPU0_SB_DQ<10>")
	)
	(arc
		(start 330.119736 -279.428702)
		(mid 329.936228 -279.383208)
		(end 329.753976 -279.433528)
		(width 0.0889)
		(layer "In2.Cu")
		(net "M_C_CPU0_SB_DQ<10>")
	)
	(arc
		(start 328.248264 -279.433528)
		(mid 328.075156 -279.383412)
		(end 327.89876 -279.42032)
		(width 0.0889)
		(layer "In2.Cu")
		(net "M_C_CPU0_SB_DQ<10>")
	)
	(arc
		(start 327.290684 -279.42159)
		(mid 327.111756 -279.382713)
		(end 326.935846 -279.433528)
		(width 0.0889)
		(layer "In2.Cu")
		(net "M_C_CPU0_SB_DQ<10>")
	)
	(arc
		(start 331.634084 -279.433528)
		(mid 331.351128 -279.509705)
		(end 331.068172 -279.433528)
		(width 0.0889)
		(layer "In2.Cu")
		(net "M_C_CPU0_SB_DQ<10>")
	)
	(arc
		(start 332.008226 -279.433528)
		(mid 331.825975 -279.383178)
		(end 331.642466 -279.428702)
		(width 0.0889)
		(layer "In2.Cu")
		(net "M_C_CPU0_SB_DQ<10>")
	)
	(arc
		(start 342.292686 -279.407366)
		(mid 342.130497 -279.384631)
		(end 341.97417 -279.433528)
		(width 0.0889)
		(layer "In2.Cu")
		(net "M_C_CPU0_SB_DQ<10>")
	)
	(arc
		(start 339.519768 -279.428702)
		(mid 339.33626 -279.383208)
		(end 339.154008 -279.433528)
		(width 0.0889)
		(layer "In2.Cu")
		(net "M_C_CPU0_SB_DQ<10>")
	)
	(arc
		(start 326.650858 -279.516078)
		(mid 326.330287 -279.452312)
		(end 326.05853 -279.270714)
		(width 0.0889)
		(layer "In2.Cu")
		(net "M_C_CPU0_SB_DQ<10>")
	)
	(arc
		(start 335.394046 -279.433528)
		(mid 335.11109 -279.509705)
		(end 334.828134 -279.433528)
		(width 0.0889)
		(layer "In2.Cu")
		(net "M_C_CPU0_SB_DQ<10>")
	)
	(arc
		(start 329.188064 -279.433528)
		(mid 329.00112 -279.383273)
		(end 328.814176 -279.433528)
		(width 0.0889)
		(layer "In2.Cu")
		(net "M_C_CPU0_SB_DQ<10>")
	)
	(arc
		(start 340.094062 -279.433528)
		(mid 339.811106 -279.509705)
		(end 339.52815 -279.433528)
		(width 0.0889)
		(layer "In2.Cu")
		(net "M_C_CPU0_SB_DQ<10>")
	)
	(arc
		(start 329.753976 -279.433528)
		(mid 329.47102 -279.509705)
		(end 329.188064 -279.433528)
		(width 0.0889)
		(layer "In2.Cu")
		(net "M_C_CPU0_SB_DQ<10>")
	)
	(arc
		(start 333.879698 -279.428702)
		(mid 333.69619 -279.383208)
		(end 333.513938 -279.433528)
		(width 0.0889)
		(layer "In2.Cu")
		(net "M_C_CPU0_SB_DQ<10>")
	)
	(arc
		(start 337.648042 -279.433528)
		(mid 337.461098 -279.383273)
		(end 337.274154 -279.433528)
		(width 0.0889)
		(layer "In2.Cu")
		(net "M_C_CPU0_SB_DQ<10>")
	)
	(arc
		(start 336.708242 -279.433528)
		(mid 336.525991 -279.383178)
		(end 336.342482 -279.428702)
		(width 0.0889)
		(layer "In2.Cu")
		(net "M_C_CPU0_SB_DQ<10>")
	)
	(arc
		(start 330.69403 -279.433528)
		(mid 330.411074 -279.509705)
		(end 330.128118 -279.433528)
		(width 0.0889)
		(layer "In2.Cu")
		(net "M_C_CPU0_SB_DQ<10>")
	)
	(arc
		(start 340.468204 -279.433528)
		(mid 340.285953 -279.383178)
		(end 340.102444 -279.428702)
		(width 0.0889)
		(layer "In2.Cu")
		(net "M_C_CPU0_SB_DQ<10>")
	)
	(arc
		(start 334.453992 -279.433528)
		(mid 334.171036 -279.509705)
		(end 333.88808 -279.433528)
		(width 0.0889)
		(layer "In2.Cu")
		(net "M_C_CPU0_SB_DQ<10>")
	)
	(arc
		(start 332.948026 -279.433528)
		(mid 332.761082 -279.383273)
		(end 332.574138 -279.433528)
		(width 0.0889)
		(layer "In2.Cu")
		(net "M_C_CPU0_SB_DQ<10>")
	)
	(arc
		(start 341.408258 -279.433528)
		(mid 341.226007 -279.383178)
		(end 341.042498 -279.428702)
		(width 0.0889)
		(layer "In2.Cu")
		(net "M_C_CPU0_SB_DQ<10>")
	)
	(arc
		(start 332.574138 -279.433528)
		(mid 332.291182 -279.509705)
		(end 332.008226 -279.433528)
		(width 0.0889)
		(layer "In2.Cu")
		(net "M_C_CPU0_SB_DQ<10>")
	)
	(arc
		(start 334.819752 -279.428702)
		(mid 334.636244 -279.383208)
		(end 334.453992 -279.433528)
		(width 0.0889)
		(layer "In2.Cu")
		(net "M_C_CPU0_SB_DQ<10>")
	)
	(arc
		(start 341.97417 -279.433528)
		(mid 341.691214 -279.509705)
		(end 341.408258 -279.433528)
		(width 0.0889)
		(layer "In2.Cu")
		(net "M_C_CPU0_SB_DQ<10>")
	)
	(arc
		(start 326.91832 -279.443688)
		(mid 326.789523 -279.497611)
		(end 326.651112 -279.516078)
		(width 0.0889)
		(layer "In2.Cu")
		(net "M_C_CPU0_SB_DQ<10>")
	)
	(arc
		(start 337.274154 -279.433528)
		(mid 336.991198 -279.509705)
		(end 336.708242 -279.433528)
		(width 0.0889)
		(layer "In2.Cu")
		(net "M_C_CPU0_SB_DQ<10>")
	)
	(arc
		(start 331.068172 -279.433528)
		(mid 330.885921 -279.383178)
		(end 330.702412 -279.428702)
		(width 0.0889)
		(layer "In2.Cu")
		(net "M_C_CPU0_SB_DQ<10>")
	)
	(arc
		(start 338.213954 -279.433528)
		(mid 337.930998 -279.509705)
		(end 337.648042 -279.433528)
		(width 0.0889)
		(layer "In2.Cu")
		(net "M_C_CPU0_SB_DQ<10>")
	)
	(arc
		(start 333.513938 -279.433528)
		(mid 333.230982 -279.509705)
		(end 332.948026 -279.433528)
		(width 0.0889)
		(layer "In2.Cu")
		(net "M_C_CPU0_SB_DQ<10>")
	)
	(arc
		(start 338.579714 -279.428702)
		(mid 338.396206 -279.383208)
		(end 338.213954 -279.433528)
		(width 0.0889)
		(layer "In2.Cu")
		(net "M_C_CPU0_SB_DQ<10>")
	)
	(arc
		(start 336.3341 -279.433528)
		(mid 336.051144 -279.509705)
		(end 335.768188 -279.433528)
		(width 0.0889)
		(layer "In2.Cu")
		(net "M_C_CPU0_SB_DQ<10>")
	)
	(arc
		(start 335.768188 -279.433528)
		(mid 335.585937 -279.383178)
		(end 335.402428 -279.428702)
		(width 0.0889)
		(layer "In2.Cu")
		(net "M_C_CPU0_SB_DQ<10>")
	)
	(arc
		(start 341.034116 -279.433528)
		(mid 340.75116 -279.509705)
		(end 340.468204 -279.433528)
		(width 0.0889)
		(layer "In2.Cu")
		(net "M_C_CPU0_SB_DQ<10>")
	)
	(arc
		(start 326.04329 -279.255474)
		(mid 325.8559 -279.130264)
		(end 325.634858 -279.08631)
		(width 0.0889)
		(layer "In2.Cu")
		(net "M_C_CPU0_SB_DQ<10>")
	)
	(segment
		(start 343.097866 -273.820128)
		(end 342.631014 -274.086066)
		(width 0.10668)
		(layer "F.Cu")
		(net "M_C_CPU0_SB_DQ<0>")
	)
	(segment
		(start 312.787792 -277.424388)
		(end 312.550556 -277.424388)
		(width 0.14478)
		(layer "In2.Cu")
		(net "M_C_CPU0_SB_DQ<0>")
	)
	(segment
		(start 294.00754 -282.1178)
		(end 294.00754 -281.783028)
		(width 0.14478)
		(layer "In2.Cu")
		(net "M_C_CPU0_SB_DQ<0>")
	)
	(segment
		(start 301.787306 -281.910028)
		(end 300.937168 -281.05989)
		(width 0.14478)
		(layer "In2.Cu")
		(net "M_C_CPU0_SB_DQ<0>")
	)
	(segment
		(start 316.328806 -273.65325)
		(end 316.328806 -273.883374)
		(width 0.14478)
		(layer "In2.Cu")
		(net "M_C_CPU0_SB_DQ<0>")
	)
	(segment
		(start 340.938104 -274.408646)
		(end 340.929722 -274.413472)
		(width 0.0889)
		(layer "In2.Cu")
		(net "M_C_CPU0_SB_DQ<0>")
	)
	(segment
		(start 342.631014 -274.086066)
		(end 342.47709 -274.351496)
		(width 0.0889)
		(layer "In2.Cu")
		(net "M_C_CPU0_SB_DQ<0>")
	)
	(segment
		(start 331.538072 -274.408646)
		(end 331.52969 -274.413472)
		(width 0.0889)
		(layer "In2.Cu")
		(net "M_C_CPU0_SB_DQ<0>")
	)
	(segment
		(start 316.632336 -274.417028)
		(end 316.469014 -274.58035)
		(width 0.14478)
		(layer "In2.Cu")
		(net "M_C_CPU0_SB_DQ<0>")
	)
	(segment
		(start 293.45128 -281.783028)
		(end 293.45128 -282.1178)
		(width 0.14478)
		(layer "In2.Cu")
		(net "M_C_CPU0_SB_DQ<0>")
	)
	(segment
		(start 326.677274 -274.452588)
		(end 326.645016 -274.452588)
		(width 0.0889)
		(layer "In2.Cu")
		(net "M_C_CPU0_SB_DQ<0>")
	)
	(segment
		(start 314.755022 -275.457158)
		(end 315.058552 -275.760688)
		(width 0.14478)
		(layer "In2.Cu")
		(net "M_C_CPU0_SB_DQ<0>")
	)
	(segment
		(start 326.364854 -274.33651)
		(end 325.425054 -273.39671)
		(width 0.0889)
		(layer "In2.Cu")
		(net "M_C_CPU0_SB_DQ<0>")
	)
	(segment
		(start 313.96813 -276.013926)
		(end 313.96813 -276.24405)
		(width 0.14478)
		(layer "In2.Cu")
		(net "M_C_CPU0_SB_DQ<0>")
	)
	(segment
		(start 316.23889 -274.58035)
		(end 315.93536 -274.27682)
		(width 0.14478)
		(layer "In2.Cu")
		(net "M_C_CPU0_SB_DQ<0>")
	)
	(segment
		(start 308.915054 -281.05989)
		(end 305.653948 -281.05989)
		(width 0.14478)
		(layer "In2.Cu")
		(net "M_C_CPU0_SB_DQ<0>")
	)
	(segment
		(start 315.541914 -274.670266)
		(end 315.845444 -274.973796)
		(width 0.14478)
		(layer "In2.Cu")
		(net "M_C_CPU0_SB_DQ<0>")
	)
	(segment
		(start 324.489064 -273.22018)
		(end 323.906134 -273.22018)
		(width 0.0889)
		(layer "In2.Cu")
		(net "M_C_CPU0_SB_DQ<0>")
	)
	(segment
		(start 313.574684 -276.637496)
		(end 313.34456 -276.637496)
		(width 0.14478)
		(layer "In2.Cu")
		(net "M_C_CPU0_SB_DQ<0>")
	)
	(segment
		(start 333.05242 -274.413472)
		(end 333.044038 -274.408646)
		(width 0.0889)
		(layer "In2.Cu")
		(net "M_C_CPU0_SB_DQ<0>")
	)
	(segment
		(start 314.89523 -276.154134)
		(end 314.665106 -276.154134)
		(width 0.14478)
		(layer "In2.Cu")
		(net "M_C_CPU0_SB_DQ<0>")
	)
	(segment
		(start 337.752436 -274.413472)
		(end 337.744054 -274.408646)
		(width 0.0889)
		(layer "In2.Cu")
		(net "M_C_CPU0_SB_DQ<0>")
	)
	(segment
		(start 313.157616 -277.581868)
		(end 312.945272 -277.581868)
		(width 0.14478)
		(layer "In2.Cu")
		(net "M_C_CPU0_SB_DQ<0>")
	)
	(segment
		(start 316.328806 -273.883374)
		(end 316.632336 -274.186904)
		(width 0.14478)
		(layer "In2.Cu")
		(net "M_C_CPU0_SB_DQ<0>")
	)
	(segment
		(start 328.718164 -274.408646)
		(end 328.709782 -274.413472)
		(width 0.0889)
		(layer "In2.Cu")
		(net "M_C_CPU0_SB_DQ<0>")
	)
	(segment
		(start 293.075614 -282.280614)
		(end 292.280086 -281.485086)
		(width 0.14478)
		(layer "In2.Cu")
		(net "M_C_CPU0_SB_DQ<0>")
	)
	(segment
		(start 325.425054 -273.39671)
		(end 324.665594 -273.39671)
		(width 0.0889)
		(layer "In2.Cu")
		(net "M_C_CPU0_SB_DQ<0>")
	)
	(segment
		(start 315.845444 -275.20392)
		(end 315.682122 -275.367242)
		(width 0.14478)
		(layer "In2.Cu")
		(net "M_C_CPU0_SB_DQ<0>")
	)
	(segment
		(start 314.27166 -276.777704)
		(end 314.108338 -276.941026)
		(width 0.14478)
		(layer "In2.Cu")
		(net "M_C_CPU0_SB_DQ<0>")
	)
	(segment
		(start 313.181238 -277.030942)
		(end 313.338718 -277.188422)
		(width 0.14478)
		(layer "In2.Cu")
		(net "M_C_CPU0_SB_DQ<0>")
	)
	(segment
		(start 323.906134 -273.22018)
		(end 316.761876 -273.22018)
		(width 0.14478)
		(layer "In2.Cu")
		(net "M_C_CPU0_SB_DQ<0>")
	)
	(segment
		(start 313.338718 -277.188422)
		(end 313.338718 -277.400766)
		(width 0.14478)
		(layer "In2.Cu")
		(net "M_C_CPU0_SB_DQ<0>")
	)
	(segment
		(start 314.27166 -276.54758)
		(end 314.27166 -276.777704)
		(width 0.14478)
		(layer "In2.Cu")
		(net "M_C_CPU0_SB_DQ<0>")
	)
	(segment
		(start 316.761876 -273.22018)
		(end 316.328806 -273.65325)
		(width 0.14478)
		(layer "In2.Cu")
		(net "M_C_CPU0_SB_DQ<0>")
	)
	(segment
		(start 314.361576 -275.850604)
		(end 314.131452 -275.850604)
		(width 0.14478)
		(layer "In2.Cu")
		(net "M_C_CPU0_SB_DQ<0>")
	)
	(segment
		(start 294.00754 -281.783028)
		(end 293.844726 -281.620214)
		(width 0.14478)
		(layer "In2.Cu")
		(net "M_C_CPU0_SB_DQ<0>")
	)
	(segment
		(start 314.755022 -275.227034)
		(end 314.755022 -275.457158)
		(width 0.14478)
		(layer "In2.Cu")
		(net "M_C_CPU0_SB_DQ<0>")
	)
	(segment
		(start 315.148468 -275.063712)
		(end 314.918344 -275.063712)
		(width 0.14478)
		(layer "In2.Cu")
		(net "M_C_CPU0_SB_DQ<0>")
	)
	(segment
		(start 315.058552 -275.990812)
		(end 314.89523 -276.154134)
		(width 0.14478)
		(layer "In2.Cu")
		(net "M_C_CPU0_SB_DQ<0>")
	)
	(segment
		(start 293.614094 -281.620214)
		(end 293.45128 -281.783028)
		(width 0.14478)
		(layer "In2.Cu")
		(net "M_C_CPU0_SB_DQ<0>")
	)
	(segment
		(start 315.682122 -275.367242)
		(end 315.451998 -275.367242)
		(width 0.14478)
		(layer "In2.Cu")
		(net "M_C_CPU0_SB_DQ<0>")
	)
	(segment
		(start 316.632336 -274.186904)
		(end 316.632336 -274.417028)
		(width 0.14478)
		(layer "In2.Cu")
		(net "M_C_CPU0_SB_DQ<0>")
	)
	(segment
		(start 329.292458 -274.413472)
		(end 329.284076 -274.408646)
		(width 0.0889)
		(layer "In2.Cu")
		(net "M_C_CPU0_SB_DQ<0>")
	)
	(segment
		(start 315.93536 -274.27682)
		(end 315.705236 -274.27682)
		(width 0.14478)
		(layer "In2.Cu")
		(net "M_C_CPU0_SB_DQ<0>")
	)
	(segment
		(start 312.550556 -277.424388)
		(end 308.915054 -281.05989)
		(width 0.14478)
		(layer "In2.Cu")
		(net "M_C_CPU0_SB_DQ<0>")
	)
	(segment
		(start 324.665594 -273.39671)
		(end 324.489064 -273.22018)
		(width 0.0889)
		(layer "In2.Cu")
		(net "M_C_CPU0_SB_DQ<0>")
	)
	(segment
		(start 316.469014 -274.58035)
		(end 316.23889 -274.58035)
		(width 0.14478)
		(layer "In2.Cu")
		(net "M_C_CPU0_SB_DQ<0>")
	)
	(segment
		(start 294.775636 -281.910028)
		(end 294.40505 -282.280614)
		(width 0.14478)
		(layer "In2.Cu")
		(net "M_C_CPU0_SB_DQ<0>")
	)
	(segment
		(start 315.845444 -274.973796)
		(end 315.845444 -275.20392)
		(width 0.14478)
		(layer "In2.Cu")
		(net "M_C_CPU0_SB_DQ<0>")
	)
	(segment
		(start 336.238088 -274.408646)
		(end 336.229706 -274.413472)
		(width 0.0889)
		(layer "In2.Cu")
		(net "M_C_CPU0_SB_DQ<0>")
	)
	(segment
		(start 332.478126 -274.408646)
		(end 332.469744 -274.413472)
		(width 0.0889)
		(layer "In2.Cu")
		(net "M_C_CPU0_SB_DQ<0>")
	)
	(segment
		(start 327.803764 -274.394422)
		(end 327.779888 -274.408392)
		(width 0.0889)
		(layer "In2.Cu")
		(net "M_C_CPU0_SB_DQ<0>")
	)
	(segment
		(start 315.705236 -274.27682)
		(end 315.541914 -274.440142)
		(width 0.14478)
		(layer "In2.Cu")
		(net "M_C_CPU0_SB_DQ<0>")
	)
	(segment
		(start 315.058552 -275.760688)
		(end 315.058552 -275.990812)
		(width 0.14478)
		(layer "In2.Cu")
		(net "M_C_CPU0_SB_DQ<0>")
	)
	(segment
		(start 313.338718 -277.400766)
		(end 313.157616 -277.581868)
		(width 0.14478)
		(layer "In2.Cu")
		(net "M_C_CPU0_SB_DQ<0>")
	)
	(segment
		(start 314.665106 -276.154134)
		(end 314.361576 -275.850604)
		(width 0.14478)
		(layer "In2.Cu")
		(net "M_C_CPU0_SB_DQ<0>")
	)
	(segment
		(start 313.96813 -276.24405)
		(end 314.27166 -276.54758)
		(width 0.14478)
		(layer "In2.Cu")
		(net "M_C_CPU0_SB_DQ<0>")
	)
	(segment
		(start 293.844726 -281.620214)
		(end 293.614094 -281.620214)
		(width 0.14478)
		(layer "In2.Cu")
		(net "M_C_CPU0_SB_DQ<0>")
	)
	(segment
		(start 297.360594 -281.910028)
		(end 294.775636 -281.910028)
		(width 0.14478)
		(layer "In2.Cu")
		(net "M_C_CPU0_SB_DQ<0>")
	)
	(segment
		(start 298.210732 -281.05989)
		(end 297.360594 -281.910028)
		(width 0.14478)
		(layer "In2.Cu")
		(net "M_C_CPU0_SB_DQ<0>")
	)
	(segment
		(start 312.945272 -277.581868)
		(end 312.787792 -277.424388)
		(width 0.14478)
		(layer "In2.Cu")
		(net "M_C_CPU0_SB_DQ<0>")
	)
	(segment
		(start 313.878214 -276.941026)
		(end 313.574684 -276.637496)
		(width 0.14478)
		(layer "In2.Cu")
		(net "M_C_CPU0_SB_DQ<0>")
	)
	(segment
		(start 337.178142 -274.408646)
		(end 337.16976 -274.413472)
		(width 0.0889)
		(layer "In2.Cu")
		(net "M_C_CPU0_SB_DQ<0>")
	)
	(segment
		(start 305.653948 -281.05989)
		(end 304.80381 -281.910028)
		(width 0.14478)
		(layer "In2.Cu")
		(net "M_C_CPU0_SB_DQ<0>")
	)
	(segment
		(start 313.181238 -276.800818)
		(end 313.181238 -277.030942)
		(width 0.14478)
		(layer "In2.Cu")
		(net "M_C_CPU0_SB_DQ<0>")
	)
	(segment
		(start 333.992474 -274.413472)
		(end 333.984092 -274.408646)
		(width 0.0889)
		(layer "In2.Cu")
		(net "M_C_CPU0_SB_DQ<0>")
	)
	(segment
		(start 327.40727 -274.408646)
		(end 327.379584 -274.392644)
		(width 0.0889)
		(layer "In2.Cu")
		(net "M_C_CPU0_SB_DQ<0>")
	)
	(segment
		(start 314.131452 -275.850604)
		(end 313.96813 -276.013926)
		(width 0.14478)
		(layer "In2.Cu")
		(net "M_C_CPU0_SB_DQ<0>")
	)
	(segment
		(start 314.108338 -276.941026)
		(end 313.878214 -276.941026)
		(width 0.14478)
		(layer "In2.Cu")
		(net "M_C_CPU0_SB_DQ<0>")
	)
	(segment
		(start 313.34456 -276.637496)
		(end 313.181238 -276.800818)
		(width 0.14478)
		(layer "In2.Cu")
		(net "M_C_CPU0_SB_DQ<0>")
	)
	(segment
		(start 293.288466 -282.280614)
		(end 293.075614 -282.280614)
		(width 0.14478)
		(layer "In2.Cu")
		(net "M_C_CPU0_SB_DQ<0>")
	)
	(segment
		(start 314.918344 -275.063712)
		(end 314.755022 -275.227034)
		(width 0.14478)
		(layer "In2.Cu")
		(net "M_C_CPU0_SB_DQ<0>")
	)
	(segment
		(start 294.40505 -282.280614)
		(end 294.170354 -282.280614)
		(width 0.14478)
		(layer "In2.Cu")
		(net "M_C_CPU0_SB_DQ<0>")
	)
	(segment
		(start 315.541914 -274.440142)
		(end 315.541914 -274.670266)
		(width 0.14478)
		(layer "In2.Cu")
		(net "M_C_CPU0_SB_DQ<0>")
	)
	(segment
		(start 304.80381 -281.910028)
		(end 301.787306 -281.910028)
		(width 0.14478)
		(layer "In2.Cu")
		(net "M_C_CPU0_SB_DQ<0>")
	)
	(segment
		(start 341.878158 -274.408646)
		(end 341.869776 -274.413472)
		(width 0.0889)
		(layer "In2.Cu")
		(net "M_C_CPU0_SB_DQ<0>")
	)
	(segment
		(start 342.47709 -274.351496)
		(end 342.381078 -274.376896)
		(width 0.0889)
		(layer "In2.Cu")
		(net "M_C_CPU0_SB_DQ<0>")
	)
	(segment
		(start 327.779888 -274.408392)
		(end 327.758044 -274.420838)
		(width 0.0889)
		(layer "In2.Cu")
		(net "M_C_CPU0_SB_DQ<0>")
	)
	(segment
		(start 294.170354 -282.280614)
		(end 294.00754 -282.1178)
		(width 0.14478)
		(layer "In2.Cu")
		(net "M_C_CPU0_SB_DQ<0>")
	)
	(segment
		(start 300.937168 -281.05989)
		(end 298.210732 -281.05989)
		(width 0.14478)
		(layer "In2.Cu")
		(net "M_C_CPU0_SB_DQ<0>")
	)
	(segment
		(start 315.451998 -275.367242)
		(end 315.148468 -275.063712)
		(width 0.14478)
		(layer "In2.Cu")
		(net "M_C_CPU0_SB_DQ<0>")
	)
	(segment
		(start 338.69249 -274.413472)
		(end 338.684108 -274.408646)
		(width 0.0889)
		(layer "In2.Cu")
		(net "M_C_CPU0_SB_DQ<0>")
	)
	(segment
		(start 293.45128 -282.1178)
		(end 293.288466 -282.280614)
		(width 0.14478)
		(layer "In2.Cu")
		(net "M_C_CPU0_SB_DQ<0>")
	)
	(arc
		(start 333.984092 -274.408646)
		(mid 333.701136 -274.332469)
		(end 333.41818 -274.408646)
		(width 0.0889)
		(layer "In2.Cu")
		(net "M_C_CPU0_SB_DQ<0>")
	)
	(arc
		(start 326.83958 -274.408646)
		(mid 326.761347 -274.441399)
		(end 326.677274 -274.452588)
		(width 0.0889)
		(layer "In2.Cu")
		(net "M_C_CPU0_SB_DQ<0>")
	)
	(arc
		(start 339.624162 -274.408646)
		(mid 339.341206 -274.332469)
		(end 339.05825 -274.408646)
		(width 0.0889)
		(layer "In2.Cu")
		(net "M_C_CPU0_SB_DQ<0>")
	)
	(arc
		(start 331.16393 -274.408646)
		(mid 330.880974 -274.332469)
		(end 330.598018 -274.408646)
		(width 0.0889)
		(layer "In2.Cu")
		(net "M_C_CPU0_SB_DQ<0>")
	)
	(arc
		(start 336.804 -274.408646)
		(mid 336.521044 -274.332469)
		(end 336.238088 -274.408646)
		(width 0.0889)
		(layer "In2.Cu")
		(net "M_C_CPU0_SB_DQ<0>")
	)
	(arc
		(start 338.118196 -274.408646)
		(mid 337.935945 -274.458996)
		(end 337.752436 -274.413472)
		(width 0.0889)
		(layer "In2.Cu")
		(net "M_C_CPU0_SB_DQ<0>")
	)
	(arc
		(start 341.869776 -274.413472)
		(mid 341.686268 -274.458966)
		(end 341.504016 -274.408646)
		(width 0.0889)
		(layer "In2.Cu")
		(net "M_C_CPU0_SB_DQ<0>")
	)
	(arc
		(start 339.99805 -274.408646)
		(mid 339.811106 -274.458901)
		(end 339.624162 -274.408646)
		(width 0.0889)
		(layer "In2.Cu")
		(net "M_C_CPU0_SB_DQ<0>")
	)
	(arc
		(start 341.504016 -274.408646)
		(mid 341.22106 -274.332469)
		(end 340.938104 -274.408646)
		(width 0.0889)
		(layer "In2.Cu")
		(net "M_C_CPU0_SB_DQ<0>")
	)
	(arc
		(start 328.709782 -274.413472)
		(mid 328.526274 -274.458966)
		(end 328.344022 -274.408646)
		(width 0.0889)
		(layer "In2.Cu")
		(net "M_C_CPU0_SB_DQ<0>")
	)
	(arc
		(start 336.229706 -274.413472)
		(mid 336.046198 -274.458966)
		(end 335.863946 -274.408646)
		(width 0.0889)
		(layer "In2.Cu")
		(net "M_C_CPU0_SB_DQ<0>")
	)
	(arc
		(start 330.598018 -274.408646)
		(mid 330.411074 -274.458901)
		(end 330.22413 -274.408646)
		(width 0.0889)
		(layer "In2.Cu")
		(net "M_C_CPU0_SB_DQ<0>")
	)
	(arc
		(start 332.469744 -274.413472)
		(mid 332.286236 -274.458966)
		(end 332.103984 -274.408646)
		(width 0.0889)
		(layer "In2.Cu")
		(net "M_C_CPU0_SB_DQ<0>")
	)
	(arc
		(start 337.744054 -274.408646)
		(mid 337.461098 -274.332469)
		(end 337.178142 -274.408646)
		(width 0.0889)
		(layer "In2.Cu")
		(net "M_C_CPU0_SB_DQ<0>")
	)
	(arc
		(start 330.22413 -274.408646)
		(mid 329.941174 -274.332469)
		(end 329.658218 -274.408646)
		(width 0.0889)
		(layer "In2.Cu")
		(net "M_C_CPU0_SB_DQ<0>")
	)
	(arc
		(start 342.381078 -274.376896)
		(mid 342.12587 -274.333419)
		(end 341.878158 -274.408646)
		(width 0.0889)
		(layer "In2.Cu")
		(net "M_C_CPU0_SB_DQ<0>")
	)
	(arc
		(start 340.563962 -274.408646)
		(mid 340.281006 -274.332469)
		(end 339.99805 -274.408646)
		(width 0.0889)
		(layer "In2.Cu")
		(net "M_C_CPU0_SB_DQ<0>")
	)
	(arc
		(start 334.924146 -274.408646)
		(mid 334.64119 -274.332469)
		(end 334.358234 -274.408646)
		(width 0.0889)
		(layer "In2.Cu")
		(net "M_C_CPU0_SB_DQ<0>")
	)
	(arc
		(start 335.298034 -274.408646)
		(mid 335.11109 -274.458901)
		(end 334.924146 -274.408646)
		(width 0.0889)
		(layer "In2.Cu")
		(net "M_C_CPU0_SB_DQ<0>")
	)
	(arc
		(start 337.16976 -274.413472)
		(mid 336.986252 -274.458966)
		(end 336.804 -274.408646)
		(width 0.0889)
		(layer "In2.Cu")
		(net "M_C_CPU0_SB_DQ<0>")
	)
	(arc
		(start 334.358234 -274.408646)
		(mid 334.175983 -274.458996)
		(end 333.992474 -274.413472)
		(width 0.0889)
		(layer "In2.Cu")
		(net "M_C_CPU0_SB_DQ<0>")
	)
	(arc
		(start 328.344022 -274.408646)
		(mid 328.075702 -274.332538)
		(end 327.803764 -274.394422)
		(width 0.0889)
		(layer "In2.Cu")
		(net "M_C_CPU0_SB_DQ<0>")
	)
	(arc
		(start 326.645016 -274.452588)
		(mid 326.493382 -274.422426)
		(end 326.364854 -274.33651)
		(width 0.0889)
		(layer "In2.Cu")
		(net "M_C_CPU0_SB_DQ<0>")
	)
	(arc
		(start 329.658218 -274.408646)
		(mid 329.475967 -274.458996)
		(end 329.292458 -274.413472)
		(width 0.0889)
		(layer "In2.Cu")
		(net "M_C_CPU0_SB_DQ<0>")
	)
	(arc
		(start 327.379584 -274.392644)
		(mid 327.10755 -274.331872)
		(end 326.83958 -274.408646)
		(width 0.0889)
		(layer "In2.Cu")
		(net "M_C_CPU0_SB_DQ<0>")
	)
	(arc
		(start 339.05825 -274.408646)
		(mid 338.875999 -274.458996)
		(end 338.69249 -274.413472)
		(width 0.0889)
		(layer "In2.Cu")
		(net "M_C_CPU0_SB_DQ<0>")
	)
	(arc
		(start 335.863946 -274.408646)
		(mid 335.58099 -274.332469)
		(end 335.298034 -274.408646)
		(width 0.0889)
		(layer "In2.Cu")
		(net "M_C_CPU0_SB_DQ<0>")
	)
	(arc
		(start 340.929722 -274.413472)
		(mid 340.746214 -274.458966)
		(end 340.563962 -274.408646)
		(width 0.0889)
		(layer "In2.Cu")
		(net "M_C_CPU0_SB_DQ<0>")
	)
	(arc
		(start 331.52969 -274.413472)
		(mid 331.346182 -274.458966)
		(end 331.16393 -274.408646)
		(width 0.0889)
		(layer "In2.Cu")
		(net "M_C_CPU0_SB_DQ<0>")
	)
	(arc
		(start 329.284076 -274.408646)
		(mid 329.00112 -274.332469)
		(end 328.718164 -274.408646)
		(width 0.0889)
		(layer "In2.Cu")
		(net "M_C_CPU0_SB_DQ<0>")
	)
	(arc
		(start 333.41818 -274.408646)
		(mid 333.235929 -274.458996)
		(end 333.05242 -274.413472)
		(width 0.0889)
		(layer "In2.Cu")
		(net "M_C_CPU0_SB_DQ<0>")
	)
	(arc
		(start 332.103984 -274.408646)
		(mid 331.821028 -274.332469)
		(end 331.538072 -274.408646)
		(width 0.0889)
		(layer "In2.Cu")
		(net "M_C_CPU0_SB_DQ<0>")
	)
	(arc
		(start 333.044038 -274.408646)
		(mid 332.761082 -274.332469)
		(end 332.478126 -274.408646)
		(width 0.0889)
		(layer "In2.Cu")
		(net "M_C_CPU0_SB_DQ<0>")
	)
	(arc
		(start 327.758044 -274.420838)
		(mid 327.581116 -274.458666)
		(end 327.40727 -274.408646)
		(width 0.0889)
		(layer "In2.Cu")
		(net "M_C_CPU0_SB_DQ<0>")
	)
	(arc
		(start 338.684108 -274.408646)
		(mid 338.401152 -274.332469)
		(end 338.118196 -274.408646)
		(width 0.0889)
		(layer "In2.Cu")
		(net "M_C_CPU0_SB_DQ<0>")
	)
	(segment
		(start 342.627966 -266.530074)
		(end 342.161114 -266.796012)
		(width 0.10668)
		(layer "F.Cu")
		(net "M_C_CPU0_SB_CS_N<1>")
	)
	(segment
		(start 289.363404 -268.147292)
		(end 289.20059 -268.310106)
		(width 0.14478)
		(layer "In2.Cu")
		(net "M_C_CPU0_SB_CS_N<1>")
	)
	(segment
		(start 338.588096 -266.473432)
		(end 338.579714 -266.468606)
		(width 0.0889)
		(layer "In2.Cu")
		(net "M_C_CPU0_SB_CS_N<1>")
	)
	(segment
		(start 339.52815 -266.473432)
		(end 339.519768 -266.468606)
		(width 0.0889)
		(layer "In2.Cu")
		(net "M_C_CPU0_SB_CS_N<1>")
	)
	(segment
		(start 330.702412 -266.468606)
		(end 330.69403 -266.473432)
		(width 0.0889)
		(layer "In2.Cu")
		(net "M_C_CPU0_SB_CS_N<1>")
	)
	(segment
		(start 289.919664 -267.438124)
		(end 289.75685 -267.27531)
		(width 0.14478)
		(layer "In2.Cu")
		(net "M_C_CPU0_SB_CS_N<1>")
	)
	(segment
		(start 325.200264 -265.98372)
		(end 323.897244 -265.98372)
		(width 0.0889)
		(layer "In2.Cu")
		(net "M_C_CPU0_SB_CS_N<1>")
	)
	(segment
		(start 310.511444 -265.98372)
		(end 308.185058 -268.310106)
		(width 0.14478)
		(layer "In2.Cu")
		(net "M_C_CPU0_SB_CS_N<1>")
	)
	(segment
		(start 334.828134 -266.473432)
		(end 334.819752 -266.468606)
		(width 0.0889)
		(layer "In2.Cu")
		(net "M_C_CPU0_SB_CS_N<1>")
	)
	(segment
		(start 342.315038 -266.530582)
		(end 342.292686 -266.44727)
		(width 0.0889)
		(layer "In2.Cu")
		(net "M_C_CPU0_SB_CS_N<1>")
	)
	(segment
		(start 289.20059 -268.310106)
		(end 288.60496 -268.310106)
		(width 0.14478)
		(layer "In2.Cu")
		(net "M_C_CPU0_SB_CS_N<1>")
	)
	(segment
		(start 327.89876 -266.460224)
		(end 327.875392 -266.473686)
		(width 0.0889)
		(layer "In2.Cu")
		(net "M_C_CPU0_SB_CS_N<1>")
	)
	(segment
		(start 330.128118 -266.473432)
		(end 330.119736 -266.468606)
		(width 0.0889)
		(layer "In2.Cu")
		(net "M_C_CPU0_SB_CS_N<1>")
	)
	(segment
		(start 342.161114 -266.796012)
		(end 342.315038 -266.530582)
		(width 0.0889)
		(layer "In2.Cu")
		(net "M_C_CPU0_SB_CS_N<1>")
	)
	(segment
		(start 289.526218 -267.27531)
		(end 289.363404 -267.438124)
		(width 0.14478)
		(layer "In2.Cu")
		(net "M_C_CPU0_SB_CS_N<1>")
	)
	(segment
		(start 308.185058 -268.310106)
		(end 290.082478 -268.310106)
		(width 0.14478)
		(layer "In2.Cu")
		(net "M_C_CPU0_SB_CS_N<1>")
	)
	(segment
		(start 289.919664 -268.147292)
		(end 289.919664 -267.438124)
		(width 0.14478)
		(layer "In2.Cu")
		(net "M_C_CPU0_SB_CS_N<1>")
	)
	(segment
		(start 288.60496 -268.310106)
		(end 288.180018 -268.735048)
		(width 0.14478)
		(layer "In2.Cu")
		(net "M_C_CPU0_SB_CS_N<1>")
	)
	(segment
		(start 326.408034 -266.49553)
		(end 325.799196 -266.144248)
		(width 0.0889)
		(layer "In2.Cu")
		(net "M_C_CPU0_SB_CS_N<1>")
	)
	(segment
		(start 333.88808 -266.473432)
		(end 333.879698 -266.468606)
		(width 0.0889)
		(layer "In2.Cu")
		(net "M_C_CPU0_SB_CS_N<1>")
	)
	(segment
		(start 331.642466 -266.468606)
		(end 331.634084 -266.473432)
		(width 0.0889)
		(layer "In2.Cu")
		(net "M_C_CPU0_SB_CS_N<1>")
	)
	(segment
		(start 340.102444 -266.468606)
		(end 340.094062 -266.473432)
		(width 0.0889)
		(layer "In2.Cu")
		(net "M_C_CPU0_SB_CS_N<1>")
	)
	(segment
		(start 323.897244 -265.98372)
		(end 310.511444 -265.98372)
		(width 0.14478)
		(layer "In2.Cu")
		(net "M_C_CPU0_SB_CS_N<1>")
	)
	(segment
		(start 289.75685 -267.27531)
		(end 289.526218 -267.27531)
		(width 0.14478)
		(layer "In2.Cu")
		(net "M_C_CPU0_SB_CS_N<1>")
	)
	(segment
		(start 335.402428 -266.468606)
		(end 335.394046 -266.473432)
		(width 0.0889)
		(layer "In2.Cu")
		(net "M_C_CPU0_SB_CS_N<1>")
	)
	(segment
		(start 327.875392 -266.473686)
		(end 327.851516 -266.487656)
		(width 0.0889)
		(layer "In2.Cu")
		(net "M_C_CPU0_SB_CS_N<1>")
	)
	(segment
		(start 289.363404 -267.438124)
		(end 289.363404 -268.147292)
		(width 0.14478)
		(layer "In2.Cu")
		(net "M_C_CPU0_SB_CS_N<1>")
	)
	(segment
		(start 327.311258 -266.473432)
		(end 327.290684 -266.461494)
		(width 0.0889)
		(layer "In2.Cu")
		(net "M_C_CPU0_SB_CS_N<1>")
	)
	(segment
		(start 336.342482 -266.468606)
		(end 336.3341 -266.473432)
		(width 0.0889)
		(layer "In2.Cu")
		(net "M_C_CPU0_SB_CS_N<1>")
	)
	(segment
		(start 290.082478 -268.310106)
		(end 289.919664 -268.147292)
		(width 0.14478)
		(layer "In2.Cu")
		(net "M_C_CPU0_SB_CS_N<1>")
	)
	(segment
		(start 341.042498 -266.468606)
		(end 341.034116 -266.473432)
		(width 0.0889)
		(layer "In2.Cu")
		(net "M_C_CPU0_SB_CS_N<1>")
	)
	(arc
		(start 341.408258 -266.473432)
		(mid 341.226007 -266.423082)
		(end 341.042498 -266.468606)
		(width 0.0889)
		(layer "In2.Cu")
		(net "M_C_CPU0_SB_CS_N<1>")
	)
	(arc
		(start 332.008226 -266.473432)
		(mid 331.825975 -266.423082)
		(end 331.642466 -266.468606)
		(width 0.0889)
		(layer "In2.Cu")
		(net "M_C_CPU0_SB_CS_N<1>")
	)
	(arc
		(start 341.034116 -266.473432)
		(mid 340.75116 -266.549609)
		(end 340.468204 -266.473432)
		(width 0.0889)
		(layer "In2.Cu")
		(net "M_C_CPU0_SB_CS_N<1>")
	)
	(arc
		(start 331.068172 -266.473432)
		(mid 330.885921 -266.423082)
		(end 330.702412 -266.468606)
		(width 0.0889)
		(layer "In2.Cu")
		(net "M_C_CPU0_SB_CS_N<1>")
	)
	(arc
		(start 334.453992 -266.473432)
		(mid 334.171036 -266.549609)
		(end 333.88808 -266.473432)
		(width 0.0889)
		(layer "In2.Cu")
		(net "M_C_CPU0_SB_CS_N<1>")
	)
	(arc
		(start 335.768188 -266.473432)
		(mid 335.585937 -266.423082)
		(end 335.402428 -266.468606)
		(width 0.0889)
		(layer "In2.Cu")
		(net "M_C_CPU0_SB_CS_N<1>")
	)
	(arc
		(start 336.708242 -266.473432)
		(mid 336.525991 -266.423082)
		(end 336.342482 -266.468606)
		(width 0.0889)
		(layer "In2.Cu")
		(net "M_C_CPU0_SB_CS_N<1>")
	)
	(arc
		(start 325.799196 -266.144248)
		(mid 325.510298 -266.02454)
		(end 325.200264 -265.98372)
		(width 0.0889)
		(layer "In2.Cu")
		(net "M_C_CPU0_SB_CS_N<1>")
	)
	(arc
		(start 337.648042 -266.473432)
		(mid 337.461098 -266.423177)
		(end 337.274154 -266.473432)
		(width 0.0889)
		(layer "In2.Cu")
		(net "M_C_CPU0_SB_CS_N<1>")
	)
	(arc
		(start 333.513938 -266.473432)
		(mid 333.230982 -266.549609)
		(end 332.948026 -266.473432)
		(width 0.0889)
		(layer "In2.Cu")
		(net "M_C_CPU0_SB_CS_N<1>")
	)
	(arc
		(start 340.094062 -266.473432)
		(mid 339.811106 -266.549609)
		(end 339.52815 -266.473432)
		(width 0.0889)
		(layer "In2.Cu")
		(net "M_C_CPU0_SB_CS_N<1>")
	)
	(arc
		(start 334.819752 -266.468606)
		(mid 334.636244 -266.423112)
		(end 334.453992 -266.473432)
		(width 0.0889)
		(layer "In2.Cu")
		(net "M_C_CPU0_SB_CS_N<1>")
	)
	(arc
		(start 329.188064 -266.473432)
		(mid 329.00112 -266.423177)
		(end 328.814176 -266.473432)
		(width 0.0889)
		(layer "In2.Cu")
		(net "M_C_CPU0_SB_CS_N<1>")
	)
	(arc
		(start 340.468204 -266.473432)
		(mid 340.285953 -266.423082)
		(end 340.102444 -266.468606)
		(width 0.0889)
		(layer "In2.Cu")
		(net "M_C_CPU0_SB_CS_N<1>")
	)
	(arc
		(start 328.814176 -266.473432)
		(mid 328.53122 -266.549609)
		(end 328.248264 -266.473432)
		(width 0.0889)
		(layer "In2.Cu")
		(net "M_C_CPU0_SB_CS_N<1>")
	)
	(arc
		(start 338.579714 -266.468606)
		(mid 338.396206 -266.423112)
		(end 338.213954 -266.473432)
		(width 0.0889)
		(layer "In2.Cu")
		(net "M_C_CPU0_SB_CS_N<1>")
	)
	(arc
		(start 327.851516 -266.487656)
		(mid 327.579579 -266.549482)
		(end 327.311258 -266.473432)
		(width 0.0889)
		(layer "In2.Cu")
		(net "M_C_CPU0_SB_CS_N<1>")
	)
	(arc
		(start 331.634084 -266.473432)
		(mid 331.351128 -266.549609)
		(end 331.068172 -266.473432)
		(width 0.0889)
		(layer "In2.Cu")
		(net "M_C_CPU0_SB_CS_N<1>")
	)
	(arc
		(start 330.69403 -266.473432)
		(mid 330.411074 -266.549609)
		(end 330.128118 -266.473432)
		(width 0.0889)
		(layer "In2.Cu")
		(net "M_C_CPU0_SB_CS_N<1>")
	)
	(arc
		(start 326.935846 -266.473432)
		(mid 326.674688 -266.550011)
		(end 326.408034 -266.49553)
		(width 0.0889)
		(layer "In2.Cu")
		(net "M_C_CPU0_SB_CS_N<1>")
	)
	(arc
		(start 332.948026 -266.473432)
		(mid 332.761082 -266.423177)
		(end 332.574138 -266.473432)
		(width 0.0889)
		(layer "In2.Cu")
		(net "M_C_CPU0_SB_CS_N<1>")
	)
	(arc
		(start 341.97417 -266.473432)
		(mid 341.691214 -266.549609)
		(end 341.408258 -266.473432)
		(width 0.0889)
		(layer "In2.Cu")
		(net "M_C_CPU0_SB_CS_N<1>")
	)
	(arc
		(start 327.290684 -266.461494)
		(mid 327.111756 -266.422617)
		(end 326.935846 -266.473432)
		(width 0.0889)
		(layer "In2.Cu")
		(net "M_C_CPU0_SB_CS_N<1>")
	)
	(arc
		(start 330.119736 -266.468606)
		(mid 329.936228 -266.423112)
		(end 329.753976 -266.473432)
		(width 0.0889)
		(layer "In2.Cu")
		(net "M_C_CPU0_SB_CS_N<1>")
	)
	(arc
		(start 342.292686 -266.44727)
		(mid 342.130497 -266.424535)
		(end 341.97417 -266.473432)
		(width 0.0889)
		(layer "In2.Cu")
		(net "M_C_CPU0_SB_CS_N<1>")
	)
	(arc
		(start 339.519768 -266.468606)
		(mid 339.33626 -266.423112)
		(end 339.154008 -266.473432)
		(width 0.0889)
		(layer "In2.Cu")
		(net "M_C_CPU0_SB_CS_N<1>")
	)
	(arc
		(start 328.248264 -266.473432)
		(mid 328.075156 -266.423316)
		(end 327.89876 -266.460224)
		(width 0.0889)
		(layer "In2.Cu")
		(net "M_C_CPU0_SB_CS_N<1>")
	)
	(arc
		(start 338.213954 -266.473432)
		(mid 337.930998 -266.549609)
		(end 337.648042 -266.473432)
		(width 0.0889)
		(layer "In2.Cu")
		(net "M_C_CPU0_SB_CS_N<1>")
	)
	(arc
		(start 333.879698 -266.468606)
		(mid 333.69619 -266.423112)
		(end 333.513938 -266.473432)
		(width 0.0889)
		(layer "In2.Cu")
		(net "M_C_CPU0_SB_CS_N<1>")
	)
	(arc
		(start 329.753976 -266.473432)
		(mid 329.47102 -266.549609)
		(end 329.188064 -266.473432)
		(width 0.0889)
		(layer "In2.Cu")
		(net "M_C_CPU0_SB_CS_N<1>")
	)
	(arc
		(start 337.274154 -266.473432)
		(mid 336.991198 -266.549609)
		(end 336.708242 -266.473432)
		(width 0.0889)
		(layer "In2.Cu")
		(net "M_C_CPU0_SB_CS_N<1>")
	)
	(arc
		(start 336.3341 -266.473432)
		(mid 336.051144 -266.549609)
		(end 335.768188 -266.473432)
		(width 0.0889)
		(layer "In2.Cu")
		(net "M_C_CPU0_SB_CS_N<1>")
	)
	(arc
		(start 339.154008 -266.473432)
		(mid 338.871052 -266.549609)
		(end 338.588096 -266.473432)
		(width 0.0889)
		(layer "In2.Cu")
		(net "M_C_CPU0_SB_CS_N<1>")
	)
	(arc
		(start 332.574138 -266.473432)
		(mid 332.291182 -266.549609)
		(end 332.008226 -266.473432)
		(width 0.0889)
		(layer "In2.Cu")
		(net "M_C_CPU0_SB_CS_N<1>")
	)
	(arc
		(start 335.394046 -266.473432)
		(mid 335.11109 -266.549609)
		(end 334.828134 -266.473432)
		(width 0.0889)
		(layer "In2.Cu")
		(net "M_C_CPU0_SB_CS_N<1>")
	)
	(segment
		(start 344.03792 -265.720068)
		(end 343.571068 -265.986006)
		(width 0.10668)
		(layer "F.Cu")
		(net "M_C_CPU0_SB_CS_N<0>")
	)
	(segment
		(start 293.081964 -267.083286)
		(end 292.280086 -267.885164)
		(width 0.14478)
		(layer "In2.Cu")
		(net "M_C_CPU0_SB_CS_N<0>")
	)
	(segment
		(start 327.41489 -265.656568)
		(end 327.403206 -265.663426)
		(width 0.0889)
		(layer "In2.Cu")
		(net "M_C_CPU0_SB_CS_N<0>")
	)
	(segment
		(start 298.633388 -267.460222)
		(end 298.264834 -267.828776)
		(width 0.14478)
		(layer "In2.Cu")
		(net "M_C_CPU0_SB_CS_N<0>")
	)
	(segment
		(start 294.78351 -267.460222)
		(end 294.39362 -267.070332)
		(width 0.14478)
		(layer "In2.Cu")
		(net "M_C_CPU0_SB_CS_N<0>")
	)
	(segment
		(start 325.911972 -265.672062)
		(end 325.89724 -265.663426)
		(width 0.0889)
		(layer "In2.Cu")
		(net "M_C_CPU0_SB_CS_N<0>")
	)
	(segment
		(start 297.152314 -267.828776)
		(end 296.258742 -267.828776)
		(width 0.14478)
		(layer "In2.Cu")
		(net "M_C_CPU0_SB_CS_N<0>")
	)
	(segment
		(start 294.000174 -267.683742)
		(end 293.83736 -267.846556)
		(width 0.14478)
		(layer "In2.Cu")
		(net "M_C_CPU0_SB_CS_N<0>")
	)
	(segment
		(start 333.05242 -265.6586)
		(end 333.044038 -265.663426)
		(width 0.0889)
		(layer "In2.Cu")
		(net "M_C_CPU0_SB_CS_N<0>")
	)
	(segment
		(start 338.69249 -265.6586)
		(end 338.684108 -265.663426)
		(width 0.0889)
		(layer "In2.Cu")
		(net "M_C_CPU0_SB_CS_N<0>")
	)
	(segment
		(start 297.708574 -267.081)
		(end 297.477942 -267.081)
		(width 0.14478)
		(layer "In2.Cu")
		(net "M_C_CPU0_SB_CS_N<0>")
	)
	(segment
		(start 302.52797 -267.83411)
		(end 302.297338 -267.83411)
		(width 0.14478)
		(layer "In2.Cu")
		(net "M_C_CPU0_SB_CS_N<0>")
	)
	(segment
		(start 343.392506 -265.6586)
		(end 343.384124 -265.663426)
		(width 0.0889)
		(layer "In2.Cu")
		(net "M_C_CPU0_SB_CS_N<0>")
	)
	(segment
		(start 293.443914 -267.233146)
		(end 293.294054 -267.083286)
		(width 0.14478)
		(layer "In2.Cu")
		(net "M_C_CPU0_SB_CS_N<0>")
	)
	(segment
		(start 310.077104 -265.52906)
		(end 308.145942 -267.460222)
		(width 0.14478)
		(layer "In2.Cu")
		(net "M_C_CPU0_SB_CS_N<0>")
	)
	(segment
		(start 337.752436 -265.6586)
		(end 337.744054 -265.663426)
		(width 0.0889)
		(layer "In2.Cu")
		(net "M_C_CPU0_SB_CS_N<0>")
	)
	(segment
		(start 341.878158 -265.663426)
		(end 341.869776 -265.6586)
		(width 0.0889)
		(layer "In2.Cu")
		(net "M_C_CPU0_SB_CS_N<0>")
	)
	(segment
		(start 323.880734 -265.52906)
		(end 310.077104 -265.52906)
		(width 0.14478)
		(layer "In2.Cu")
		(net "M_C_CPU0_SB_CS_N<0>")
	)
	(segment
		(start 333.992474 -265.6586)
		(end 333.984092 -265.663426)
		(width 0.0889)
		(layer "In2.Cu")
		(net "M_C_CPU0_SB_CS_N<0>")
	)
	(segment
		(start 294.162988 -267.070332)
		(end 294.000174 -267.233146)
		(width 0.14478)
		(layer "In2.Cu")
		(net "M_C_CPU0_SB_CS_N<0>")
	)
	(segment
		(start 343.571068 -265.986006)
		(end 343.725246 -265.720576)
		(width 0.0889)
		(layer "In2.Cu")
		(net "M_C_CPU0_SB_CS_N<0>")
	)
	(segment
		(start 342.452452 -265.6586)
		(end 342.44407 -265.663426)
		(width 0.0889)
		(layer "In2.Cu")
		(net "M_C_CPU0_SB_CS_N<0>")
	)
	(segment
		(start 295.890188 -267.460222)
		(end 294.78351 -267.460222)
		(width 0.14478)
		(layer "In2.Cu")
		(net "M_C_CPU0_SB_CS_N<0>")
	)
	(segment
		(start 298.034202 -267.828776)
		(end 297.871388 -267.665962)
		(width 0.14478)
		(layer "In2.Cu")
		(net "M_C_CPU0_SB_CS_N<0>")
	)
	(segment
		(start 337.178142 -265.663426)
		(end 337.16976 -265.6586)
		(width 0.0889)
		(layer "In2.Cu")
		(net "M_C_CPU0_SB_CS_N<0>")
	)
	(segment
		(start 301.741078 -267.086334)
		(end 301.578264 -267.249148)
		(width 0.14478)
		(layer "In2.Cu")
		(net "M_C_CPU0_SB_CS_N<0>")
	)
	(segment
		(start 293.606728 -267.846556)
		(end 293.443914 -267.683742)
		(width 0.14478)
		(layer "In2.Cu")
		(net "M_C_CPU0_SB_CS_N<0>")
	)
	(segment
		(start 328.718164 -265.663426)
		(end 328.709782 -265.6586)
		(width 0.0889)
		(layer "In2.Cu")
		(net "M_C_CPU0_SB_CS_N<0>")
	)
	(segment
		(start 302.134524 -267.671296)
		(end 302.134524 -267.249148)
		(width 0.14478)
		(layer "In2.Cu")
		(net "M_C_CPU0_SB_CS_N<0>")
	)
	(segment
		(start 297.871388 -267.243814)
		(end 297.708574 -267.081)
		(width 0.14478)
		(layer "In2.Cu")
		(net "M_C_CPU0_SB_CS_N<0>")
	)
	(segment
		(start 297.315128 -267.665962)
		(end 297.152314 -267.828776)
		(width 0.14478)
		(layer "In2.Cu")
		(net "M_C_CPU0_SB_CS_N<0>")
	)
	(segment
		(start 293.443914 -267.683742)
		(end 293.443914 -267.233146)
		(width 0.14478)
		(layer "In2.Cu")
		(net "M_C_CPU0_SB_CS_N<0>")
	)
	(segment
		(start 343.725246 -265.720576)
		(end 343.702894 -265.637264)
		(width 0.0889)
		(layer "In2.Cu")
		(net "M_C_CPU0_SB_CS_N<0>")
	)
	(segment
		(start 301.578264 -267.249148)
		(end 301.578264 -267.671296)
		(width 0.14478)
		(layer "In2.Cu")
		(net "M_C_CPU0_SB_CS_N<0>")
	)
	(segment
		(start 302.297338 -267.83411)
		(end 302.134524 -267.671296)
		(width 0.14478)
		(layer "In2.Cu")
		(net "M_C_CPU0_SB_CS_N<0>")
	)
	(segment
		(start 325.402194 -265.52906)
		(end 323.880734 -265.52906)
		(width 0.0889)
		(layer "In2.Cu")
		(net "M_C_CPU0_SB_CS_N<0>")
	)
	(segment
		(start 326.84339 -265.666982)
		(end 326.837802 -265.66368)
		(width 0.0889)
		(layer "In2.Cu")
		(net "M_C_CPU0_SB_CS_N<0>")
	)
	(segment
		(start 301.41545 -267.83411)
		(end 301.184818 -267.83411)
		(width 0.14478)
		(layer "In2.Cu")
		(net "M_C_CPU0_SB_CS_N<0>")
	)
	(segment
		(start 297.871388 -267.665962)
		(end 297.871388 -267.243814)
		(width 0.14478)
		(layer "In2.Cu")
		(net "M_C_CPU0_SB_CS_N<0>")
	)
	(segment
		(start 293.83736 -267.846556)
		(end 293.606728 -267.846556)
		(width 0.14478)
		(layer "In2.Cu")
		(net "M_C_CPU0_SB_CS_N<0>")
	)
	(segment
		(start 293.294054 -267.083286)
		(end 293.081964 -267.083286)
		(width 0.14478)
		(layer "In2.Cu")
		(net "M_C_CPU0_SB_CS_N<0>")
	)
	(segment
		(start 332.478126 -265.663426)
		(end 332.469744 -265.6586)
		(width 0.0889)
		(layer "In2.Cu")
		(net "M_C_CPU0_SB_CS_N<0>")
	)
	(segment
		(start 301.97171 -267.086334)
		(end 301.741078 -267.086334)
		(width 0.14478)
		(layer "In2.Cu")
		(net "M_C_CPU0_SB_CS_N<0>")
	)
	(segment
		(start 340.938104 -265.663426)
		(end 340.929722 -265.6586)
		(width 0.0889)
		(layer "In2.Cu")
		(net "M_C_CPU0_SB_CS_N<0>")
	)
	(segment
		(start 308.145942 -267.460222)
		(end 302.901858 -267.460222)
		(width 0.14478)
		(layer "In2.Cu")
		(net "M_C_CPU0_SB_CS_N<0>")
	)
	(segment
		(start 296.258742 -267.828776)
		(end 295.890188 -267.460222)
		(width 0.14478)
		(layer "In2.Cu")
		(net "M_C_CPU0_SB_CS_N<0>")
	)
	(segment
		(start 294.000174 -267.233146)
		(end 294.000174 -267.683742)
		(width 0.14478)
		(layer "In2.Cu")
		(net "M_C_CPU0_SB_CS_N<0>")
	)
	(segment
		(start 297.477942 -267.081)
		(end 297.315128 -267.243814)
		(width 0.14478)
		(layer "In2.Cu")
		(net "M_C_CPU0_SB_CS_N<0>")
	)
	(segment
		(start 330.232512 -265.6586)
		(end 330.22413 -265.663426)
		(width 0.0889)
		(layer "In2.Cu")
		(net "M_C_CPU0_SB_CS_N<0>")
	)
	(segment
		(start 301.184818 -267.83411)
		(end 300.81093 -267.460222)
		(width 0.14478)
		(layer "In2.Cu")
		(net "M_C_CPU0_SB_CS_N<0>")
	)
	(segment
		(start 328.344022 -265.663426)
		(end 328.32929 -265.672062)
		(width 0.0889)
		(layer "In2.Cu")
		(net "M_C_CPU0_SB_CS_N<0>")
	)
	(segment
		(start 297.315128 -267.243814)
		(end 297.315128 -267.665962)
		(width 0.14478)
		(layer "In2.Cu")
		(net "M_C_CPU0_SB_CS_N<0>")
	)
	(segment
		(start 298.264834 -267.828776)
		(end 298.034202 -267.828776)
		(width 0.14478)
		(layer "In2.Cu")
		(net "M_C_CPU0_SB_CS_N<0>")
	)
	(segment
		(start 300.81093 -267.460222)
		(end 298.633388 -267.460222)
		(width 0.14478)
		(layer "In2.Cu")
		(net "M_C_CPU0_SB_CS_N<0>")
	)
	(segment
		(start 294.39362 -267.070332)
		(end 294.162988 -267.070332)
		(width 0.14478)
		(layer "In2.Cu")
		(net "M_C_CPU0_SB_CS_N<0>")
	)
	(segment
		(start 301.578264 -267.671296)
		(end 301.41545 -267.83411)
		(width 0.14478)
		(layer "In2.Cu")
		(net "M_C_CPU0_SB_CS_N<0>")
	)
	(segment
		(start 336.238088 -265.663426)
		(end 336.229706 -265.6586)
		(width 0.0889)
		(layer "In2.Cu")
		(net "M_C_CPU0_SB_CS_N<0>")
	)
	(segment
		(start 302.901858 -267.460222)
		(end 302.52797 -267.83411)
		(width 0.14478)
		(layer "In2.Cu")
		(net "M_C_CPU0_SB_CS_N<0>")
	)
	(segment
		(start 326.837802 -265.66368)
		(end 326.819514 -265.653266)
		(width 0.0889)
		(layer "In2.Cu")
		(net "M_C_CPU0_SB_CS_N<0>")
	)
	(segment
		(start 302.134524 -267.249148)
		(end 301.97171 -267.086334)
		(width 0.14478)
		(layer "In2.Cu")
		(net "M_C_CPU0_SB_CS_N<0>")
	)
	(segment
		(start 329.292458 -265.6586)
		(end 329.284076 -265.663426)
		(width 0.0889)
		(layer "In2.Cu")
		(net "M_C_CPU0_SB_CS_N<0>")
	)
	(arc
		(start 338.684108 -265.663426)
		(mid 338.401152 -265.739603)
		(end 338.118196 -265.663426)
		(width 0.0889)
		(layer "In2.Cu")
		(net "M_C_CPU0_SB_CS_N<0>")
	)
	(arc
		(start 334.924146 -265.663426)
		(mid 334.64119 -265.739603)
		(end 334.358234 -265.663426)
		(width 0.0889)
		(layer "In2.Cu")
		(net "M_C_CPU0_SB_CS_N<0>")
	)
	(arc
		(start 328.709782 -265.6586)
		(mid 328.526274 -265.613106)
		(end 328.344022 -265.663426)
		(width 0.0889)
		(layer "In2.Cu")
		(net "M_C_CPU0_SB_CS_N<0>")
	)
	(arc
		(start 325.89724 -265.663426)
		(mid 325.658673 -265.563263)
		(end 325.402194 -265.52906)
		(width 0.0889)
		(layer "In2.Cu")
		(net "M_C_CPU0_SB_CS_N<0>")
	)
	(arc
		(start 341.504016 -265.663426)
		(mid 341.22106 -265.739603)
		(end 340.938104 -265.663426)
		(width 0.0889)
		(layer "In2.Cu")
		(net "M_C_CPU0_SB_CS_N<0>")
	)
	(arc
		(start 343.384124 -265.663426)
		(mid 343.101168 -265.739603)
		(end 342.818212 -265.663426)
		(width 0.0889)
		(layer "In2.Cu")
		(net "M_C_CPU0_SB_CS_N<0>")
	)
	(arc
		(start 329.284076 -265.663426)
		(mid 329.00112 -265.739603)
		(end 328.718164 -265.663426)
		(width 0.0889)
		(layer "In2.Cu")
		(net "M_C_CPU0_SB_CS_N<0>")
	)
	(arc
		(start 336.804 -265.663426)
		(mid 336.521044 -265.739603)
		(end 336.238088 -265.663426)
		(width 0.0889)
		(layer "In2.Cu")
		(net "M_C_CPU0_SB_CS_N<0>")
	)
	(arc
		(start 336.229706 -265.6586)
		(mid 336.046198 -265.613106)
		(end 335.863946 -265.663426)
		(width 0.0889)
		(layer "In2.Cu")
		(net "M_C_CPU0_SB_CS_N<0>")
	)
	(arc
		(start 341.869776 -265.6586)
		(mid 341.686268 -265.613106)
		(end 341.504016 -265.663426)
		(width 0.0889)
		(layer "In2.Cu")
		(net "M_C_CPU0_SB_CS_N<0>")
	)
	(arc
		(start 338.118196 -265.663426)
		(mid 337.935945 -265.613076)
		(end 337.752436 -265.6586)
		(width 0.0889)
		(layer "In2.Cu")
		(net "M_C_CPU0_SB_CS_N<0>")
	)
	(arc
		(start 334.358234 -265.663426)
		(mid 334.175983 -265.613076)
		(end 333.992474 -265.6586)
		(width 0.0889)
		(layer "In2.Cu")
		(net "M_C_CPU0_SB_CS_N<0>")
	)
	(arc
		(start 339.99805 -265.663426)
		(mid 339.811106 -265.613171)
		(end 339.624162 -265.663426)
		(width 0.0889)
		(layer "In2.Cu")
		(net "M_C_CPU0_SB_CS_N<0>")
	)
	(arc
		(start 342.44407 -265.663426)
		(mid 342.161114 -265.739603)
		(end 341.878158 -265.663426)
		(width 0.0889)
		(layer "In2.Cu")
		(net "M_C_CPU0_SB_CS_N<0>")
	)
	(arc
		(start 327.777602 -265.663426)
		(mid 327.597144 -265.612982)
		(end 327.41489 -265.656568)
		(width 0.0889)
		(layer "In2.Cu")
		(net "M_C_CPU0_SB_CS_N<0>")
	)
	(arc
		(start 339.624162 -265.663426)
		(mid 339.341206 -265.739603)
		(end 339.05825 -265.663426)
		(width 0.0889)
		(layer "In2.Cu")
		(net "M_C_CPU0_SB_CS_N<0>")
	)
	(arc
		(start 328.32929 -265.672062)
		(mid 328.052307 -265.739866)
		(end 327.777602 -265.663426)
		(width 0.0889)
		(layer "In2.Cu")
		(net "M_C_CPU0_SB_CS_N<0>")
	)
	(arc
		(start 342.818212 -265.663426)
		(mid 342.635961 -265.613076)
		(end 342.452452 -265.6586)
		(width 0.0889)
		(layer "In2.Cu")
		(net "M_C_CPU0_SB_CS_N<0>")
	)
	(arc
		(start 329.658218 -265.663426)
		(mid 329.475967 -265.613076)
		(end 329.292458 -265.6586)
		(width 0.0889)
		(layer "In2.Cu")
		(net "M_C_CPU0_SB_CS_N<0>")
	)
	(arc
		(start 327.403206 -265.663426)
		(mid 327.123778 -265.739592)
		(end 326.84339 -265.666982)
		(width 0.0889)
		(layer "In2.Cu")
		(net "M_C_CPU0_SB_CS_N<0>")
	)
	(arc
		(start 343.702894 -265.637264)
		(mid 343.545384 -265.614066)
		(end 343.392506 -265.6586)
		(width 0.0889)
		(layer "In2.Cu")
		(net "M_C_CPU0_SB_CS_N<0>")
	)
	(arc
		(start 335.298034 -265.663426)
		(mid 335.11109 -265.613171)
		(end 334.924146 -265.663426)
		(width 0.0889)
		(layer "In2.Cu")
		(net "M_C_CPU0_SB_CS_N<0>")
	)
	(arc
		(start 337.744054 -265.663426)
		(mid 337.461098 -265.739603)
		(end 337.178142 -265.663426)
		(width 0.0889)
		(layer "In2.Cu")
		(net "M_C_CPU0_SB_CS_N<0>")
	)
	(arc
		(start 340.563962 -265.663426)
		(mid 340.281006 -265.739603)
		(end 339.99805 -265.663426)
		(width 0.0889)
		(layer "In2.Cu")
		(net "M_C_CPU0_SB_CS_N<0>")
	)
	(arc
		(start 330.598272 -265.663426)
		(mid 330.416021 -265.613076)
		(end 330.232512 -265.6586)
		(width 0.0889)
		(layer "In2.Cu")
		(net "M_C_CPU0_SB_CS_N<0>")
	)
	(arc
		(start 331.538072 -265.663426)
		(mid 331.351128 -265.613171)
		(end 331.164184 -265.663426)
		(width 0.0889)
		(layer "In2.Cu")
		(net "M_C_CPU0_SB_CS_N<0>")
	)
	(arc
		(start 339.05825 -265.663426)
		(mid 338.875999 -265.613076)
		(end 338.69249 -265.6586)
		(width 0.0889)
		(layer "In2.Cu")
		(net "M_C_CPU0_SB_CS_N<0>")
	)
	(arc
		(start 326.46366 -265.663426)
		(mid 326.188954 -265.73979)
		(end 325.911972 -265.672062)
		(width 0.0889)
		(layer "In2.Cu")
		(net "M_C_CPU0_SB_CS_N<0>")
	)
	(arc
		(start 335.863946 -265.663426)
		(mid 335.58099 -265.739603)
		(end 335.298034 -265.663426)
		(width 0.0889)
		(layer "In2.Cu")
		(net "M_C_CPU0_SB_CS_N<0>")
	)
	(arc
		(start 333.984092 -265.663426)
		(mid 333.701136 -265.739603)
		(end 333.41818 -265.663426)
		(width 0.0889)
		(layer "In2.Cu")
		(net "M_C_CPU0_SB_CS_N<0>")
	)
	(arc
		(start 337.16976 -265.6586)
		(mid 336.986252 -265.613106)
		(end 336.804 -265.663426)
		(width 0.0889)
		(layer "In2.Cu")
		(net "M_C_CPU0_SB_CS_N<0>")
	)
	(arc
		(start 326.819514 -265.653266)
		(mid 326.640285 -265.613113)
		(end 326.46366 -265.663426)
		(width 0.0889)
		(layer "In2.Cu")
		(net "M_C_CPU0_SB_CS_N<0>")
	)
	(arc
		(start 330.22413 -265.663426)
		(mid 329.941174 -265.739603)
		(end 329.658218 -265.663426)
		(width 0.0889)
		(layer "In2.Cu")
		(net "M_C_CPU0_SB_CS_N<0>")
	)
	(arc
		(start 333.41818 -265.663426)
		(mid 333.235929 -265.613076)
		(end 333.05242 -265.6586)
		(width 0.0889)
		(layer "In2.Cu")
		(net "M_C_CPU0_SB_CS_N<0>")
	)
	(arc
		(start 333.044038 -265.663426)
		(mid 332.761082 -265.739603)
		(end 332.478126 -265.663426)
		(width 0.0889)
		(layer "In2.Cu")
		(net "M_C_CPU0_SB_CS_N<0>")
	)
	(arc
		(start 332.469744 -265.6586)
		(mid 332.286236 -265.613106)
		(end 332.103984 -265.663426)
		(width 0.0889)
		(layer "In2.Cu")
		(net "M_C_CPU0_SB_CS_N<0>")
	)
	(arc
		(start 332.103984 -265.663426)
		(mid 331.821028 -265.739603)
		(end 331.538072 -265.663426)
		(width 0.0889)
		(layer "In2.Cu")
		(net "M_C_CPU0_SB_CS_N<0>")
	)
	(arc
		(start 340.929722 -265.6586)
		(mid 340.746214 -265.613106)
		(end 340.563962 -265.663426)
		(width 0.0889)
		(layer "In2.Cu")
		(net "M_C_CPU0_SB_CS_N<0>")
	)
	(arc
		(start 331.164184 -265.663426)
		(mid 330.881228 -265.739603)
		(end 330.598272 -265.663426)
		(width 0.0889)
		(layer "In2.Cu")
		(net "M_C_CPU0_SB_CS_N<0>")
	)
	(segment
		(start 344.03792 -270.580104)
		(end 343.571068 -270.846042)
		(width 0.10668)
		(layer "F.Cu")
		(net "M_C_CPU0_SB_CB<7>")
	)
	(segment
		(start 328.718164 -270.523462)
		(end 328.709782 -270.518636)
		(width 0.0889)
		(layer "In2.Cu")
		(net "M_C_CPU0_SB_CB<7>")
	)
	(segment
		(start 308.199282 -273.410172)
		(end 306.409598 -273.410172)
		(width 0.14478)
		(layer "In2.Cu")
		(net "M_C_CPU0_SB_CB<7>")
	)
	(segment
		(start 288.60496 -274.260056)
		(end 288.180018 -274.684998)
		(width 0.14478)
		(layer "In2.Cu")
		(net "M_C_CPU0_SB_CB<7>")
	)
	(segment
		(start 327.649586 -270.488918)
		(end 326.327262 -270.488918)
		(width 0.0889)
		(layer "In2.Cu")
		(net "M_C_CPU0_SB_CB<7>")
	)
	(segment
		(start 312.648854 -268.9606)
		(end 308.199282 -273.410172)
		(width 0.14478)
		(layer "In2.Cu")
		(net "M_C_CPU0_SB_CB<7>")
	)
	(segment
		(start 337.752436 -270.518636)
		(end 337.744054 -270.523462)
		(width 0.0889)
		(layer "In2.Cu")
		(net "M_C_CPU0_SB_CB<7>")
	)
	(segment
		(start 328.344022 -270.523462)
		(end 328.32929 -270.532098)
		(width 0.0889)
		(layer "In2.Cu")
		(net "M_C_CPU0_SB_CB<7>")
	)
	(segment
		(start 329.292458 -270.518636)
		(end 329.284076 -270.523462)
		(width 0.0889)
		(layer "In2.Cu")
		(net "M_C_CPU0_SB_CB<7>")
	)
	(segment
		(start 324.381114 -269.20571)
		(end 324.136004 -268.9606)
		(width 0.0889)
		(layer "In2.Cu")
		(net "M_C_CPU0_SB_CB<7>")
	)
	(segment
		(start 306.409598 -273.410172)
		(end 305.559714 -274.260056)
		(width 0.14478)
		(layer "In2.Cu")
		(net "M_C_CPU0_SB_CB<7>")
	)
	(segment
		(start 323.856604 -268.9606)
		(end 312.648854 -268.9606)
		(width 0.14478)
		(layer "In2.Cu")
		(net "M_C_CPU0_SB_CB<7>")
	)
	(segment
		(start 289.324034 -274.097242)
		(end 289.16122 -274.260056)
		(width 0.14478)
		(layer "In2.Cu")
		(net "M_C_CPU0_SB_CB<7>")
	)
	(segment
		(start 340.938104 -270.523462)
		(end 340.929722 -270.518636)
		(width 0.0889)
		(layer "In2.Cu")
		(net "M_C_CPU0_SB_CB<7>")
	)
	(segment
		(start 336.238088 -270.523462)
		(end 336.229706 -270.518636)
		(width 0.0889)
		(layer "In2.Cu")
		(net "M_C_CPU0_SB_CB<7>")
	)
	(segment
		(start 290.044124 -274.261072)
		(end 289.880294 -274.097242)
		(width 0.14478)
		(layer "In2.Cu")
		(net "M_C_CPU0_SB_CB<7>")
	)
	(segment
		(start 298.093892 -274.261072)
		(end 290.044124 -274.261072)
		(width 0.14478)
		(layer "In2.Cu")
		(net "M_C_CPU0_SB_CB<7>")
	)
	(segment
		(start 341.878158 -270.523462)
		(end 341.869776 -270.518636)
		(width 0.0889)
		(layer "In2.Cu")
		(net "M_C_CPU0_SB_CB<7>")
	)
	(segment
		(start 289.880294 -274.097242)
		(end 289.880294 -273.661124)
		(width 0.14478)
		(layer "In2.Cu")
		(net "M_C_CPU0_SB_CB<7>")
	)
	(segment
		(start 332.478126 -270.523462)
		(end 332.469744 -270.518636)
		(width 0.0889)
		(layer "In2.Cu")
		(net "M_C_CPU0_SB_CB<7>")
	)
	(segment
		(start 298.944792 -273.410172)
		(end 298.093892 -274.261072)
		(width 0.14478)
		(layer "In2.Cu")
		(net "M_C_CPU0_SB_CB<7>")
	)
	(segment
		(start 324.136004 -268.9606)
		(end 323.856604 -268.9606)
		(width 0.0889)
		(layer "In2.Cu")
		(net "M_C_CPU0_SB_CB<7>")
	)
	(segment
		(start 302.786542 -274.260056)
		(end 301.936658 -273.410172)
		(width 0.14478)
		(layer "In2.Cu")
		(net "M_C_CPU0_SB_CB<7>")
	)
	(segment
		(start 343.725246 -270.580612)
		(end 343.702894 -270.4973)
		(width 0.0889)
		(layer "In2.Cu")
		(net "M_C_CPU0_SB_CB<7>")
	)
	(segment
		(start 289.486848 -273.49831)
		(end 289.324034 -273.661124)
		(width 0.14478)
		(layer "In2.Cu")
		(net "M_C_CPU0_SB_CB<7>")
	)
	(segment
		(start 289.324034 -273.661124)
		(end 289.324034 -274.097242)
		(width 0.14478)
		(layer "In2.Cu")
		(net "M_C_CPU0_SB_CB<7>")
	)
	(segment
		(start 326.327262 -270.488918)
		(end 325.044054 -269.20571)
		(width 0.0889)
		(layer "In2.Cu")
		(net "M_C_CPU0_SB_CB<7>")
	)
	(segment
		(start 343.392506 -270.518636)
		(end 343.384124 -270.523462)
		(width 0.0889)
		(layer "In2.Cu")
		(net "M_C_CPU0_SB_CB<7>")
	)
	(segment
		(start 333.05242 -270.518636)
		(end 333.044038 -270.523462)
		(width 0.0889)
		(layer "In2.Cu")
		(net "M_C_CPU0_SB_CB<7>")
	)
	(segment
		(start 305.559714 -274.260056)
		(end 302.786542 -274.260056)
		(width 0.14478)
		(layer "In2.Cu")
		(net "M_C_CPU0_SB_CB<7>")
	)
	(segment
		(start 301.936658 -273.410172)
		(end 298.944792 -273.410172)
		(width 0.14478)
		(layer "In2.Cu")
		(net "M_C_CPU0_SB_CB<7>")
	)
	(segment
		(start 342.452452 -270.518636)
		(end 342.44407 -270.523462)
		(width 0.0889)
		(layer "In2.Cu")
		(net "M_C_CPU0_SB_CB<7>")
	)
	(segment
		(start 331.538072 -270.523462)
		(end 331.52969 -270.518636)
		(width 0.0889)
		(layer "In2.Cu")
		(net "M_C_CPU0_SB_CB<7>")
	)
	(segment
		(start 325.044054 -269.20571)
		(end 324.381114 -269.20571)
		(width 0.0889)
		(layer "In2.Cu")
		(net "M_C_CPU0_SB_CB<7>")
	)
	(segment
		(start 289.71748 -273.49831)
		(end 289.486848 -273.49831)
		(width 0.14478)
		(layer "In2.Cu")
		(net "M_C_CPU0_SB_CB<7>")
	)
	(segment
		(start 289.16122 -274.260056)
		(end 288.60496 -274.260056)
		(width 0.14478)
		(layer "In2.Cu")
		(net "M_C_CPU0_SB_CB<7>")
	)
	(segment
		(start 343.571068 -270.846042)
		(end 343.725246 -270.580612)
		(width 0.0889)
		(layer "In2.Cu")
		(net "M_C_CPU0_SB_CB<7>")
	)
	(segment
		(start 289.880294 -273.661124)
		(end 289.71748 -273.49831)
		(width 0.14478)
		(layer "In2.Cu")
		(net "M_C_CPU0_SB_CB<7>")
	)
	(segment
		(start 333.992474 -270.518636)
		(end 333.984092 -270.523462)
		(width 0.0889)
		(layer "In2.Cu")
		(net "M_C_CPU0_SB_CB<7>")
	)
	(segment
		(start 338.69249 -270.518636)
		(end 338.684108 -270.523462)
		(width 0.0889)
		(layer "In2.Cu")
		(net "M_C_CPU0_SB_CB<7>")
	)
	(segment
		(start 337.178142 -270.523462)
		(end 337.16976 -270.518636)
		(width 0.0889)
		(layer "In2.Cu")
		(net "M_C_CPU0_SB_CB<7>")
	)
	(arc
		(start 340.563962 -270.523462)
		(mid 340.281006 -270.599639)
		(end 339.99805 -270.523462)
		(width 0.0889)
		(layer "In2.Cu")
		(net "M_C_CPU0_SB_CB<7>")
	)
	(arc
		(start 332.469744 -270.518636)
		(mid 332.286236 -270.473142)
		(end 332.103984 -270.523462)
		(width 0.0889)
		(layer "In2.Cu")
		(net "M_C_CPU0_SB_CB<7>")
	)
	(arc
		(start 332.103984 -270.523462)
		(mid 331.821028 -270.599639)
		(end 331.538072 -270.523462)
		(width 0.0889)
		(layer "In2.Cu")
		(net "M_C_CPU0_SB_CB<7>")
	)
	(arc
		(start 336.804 -270.523462)
		(mid 336.521044 -270.599639)
		(end 336.238088 -270.523462)
		(width 0.0889)
		(layer "In2.Cu")
		(net "M_C_CPU0_SB_CB<7>")
	)
	(arc
		(start 333.984092 -270.523462)
		(mid 333.701136 -270.599639)
		(end 333.41818 -270.523462)
		(width 0.0889)
		(layer "In2.Cu")
		(net "M_C_CPU0_SB_CB<7>")
	)
	(arc
		(start 331.16393 -270.523462)
		(mid 330.880974 -270.599639)
		(end 330.598018 -270.523462)
		(width 0.0889)
		(layer "In2.Cu")
		(net "M_C_CPU0_SB_CB<7>")
	)
	(arc
		(start 339.05825 -270.523462)
		(mid 338.875999 -270.473112)
		(end 338.69249 -270.518636)
		(width 0.0889)
		(layer "In2.Cu")
		(net "M_C_CPU0_SB_CB<7>")
	)
	(arc
		(start 341.504016 -270.523462)
		(mid 341.22106 -270.599639)
		(end 340.938104 -270.523462)
		(width 0.0889)
		(layer "In2.Cu")
		(net "M_C_CPU0_SB_CB<7>")
	)
	(arc
		(start 328.709782 -270.518636)
		(mid 328.526274 -270.473142)
		(end 328.344022 -270.523462)
		(width 0.0889)
		(layer "In2.Cu")
		(net "M_C_CPU0_SB_CB<7>")
	)
	(arc
		(start 338.684108 -270.523462)
		(mid 338.401152 -270.599639)
		(end 338.118196 -270.523462)
		(width 0.0889)
		(layer "In2.Cu")
		(net "M_C_CPU0_SB_CB<7>")
	)
	(arc
		(start 339.99805 -270.523462)
		(mid 339.811106 -270.473207)
		(end 339.624162 -270.523462)
		(width 0.0889)
		(layer "In2.Cu")
		(net "M_C_CPU0_SB_CB<7>")
	)
	(arc
		(start 337.16976 -270.518636)
		(mid 336.986252 -270.473142)
		(end 336.804 -270.523462)
		(width 0.0889)
		(layer "In2.Cu")
		(net "M_C_CPU0_SB_CB<7>")
	)
	(arc
		(start 334.924146 -270.523462)
		(mid 334.64119 -270.599639)
		(end 334.358234 -270.523462)
		(width 0.0889)
		(layer "In2.Cu")
		(net "M_C_CPU0_SB_CB<7>")
	)
	(arc
		(start 338.118196 -270.523462)
		(mid 337.935945 -270.473112)
		(end 337.752436 -270.518636)
		(width 0.0889)
		(layer "In2.Cu")
		(net "M_C_CPU0_SB_CB<7>")
	)
	(arc
		(start 343.702894 -270.4973)
		(mid 343.545384 -270.474102)
		(end 343.392506 -270.518636)
		(width 0.0889)
		(layer "In2.Cu")
		(net "M_C_CPU0_SB_CB<7>")
	)
	(arc
		(start 333.41818 -270.523462)
		(mid 333.235929 -270.473112)
		(end 333.05242 -270.518636)
		(width 0.0889)
		(layer "In2.Cu")
		(net "M_C_CPU0_SB_CB<7>")
	)
	(arc
		(start 331.52969 -270.518636)
		(mid 331.346182 -270.473142)
		(end 331.16393 -270.523462)
		(width 0.0889)
		(layer "In2.Cu")
		(net "M_C_CPU0_SB_CB<7>")
	)
	(arc
		(start 342.818212 -270.523462)
		(mid 342.635961 -270.473112)
		(end 342.452452 -270.518636)
		(width 0.0889)
		(layer "In2.Cu")
		(net "M_C_CPU0_SB_CB<7>")
	)
	(arc
		(start 327.777602 -270.523462)
		(mid 327.715878 -270.497734)
		(end 327.649586 -270.488918)
		(width 0.0889)
		(layer "In2.Cu")
		(net "M_C_CPU0_SB_CB<7>")
	)
	(arc
		(start 335.863946 -270.523462)
		(mid 335.58099 -270.599639)
		(end 335.298034 -270.523462)
		(width 0.0889)
		(layer "In2.Cu")
		(net "M_C_CPU0_SB_CB<7>")
	)
	(arc
		(start 333.044038 -270.523462)
		(mid 332.761082 -270.599639)
		(end 332.478126 -270.523462)
		(width 0.0889)
		(layer "In2.Cu")
		(net "M_C_CPU0_SB_CB<7>")
	)
	(arc
		(start 341.869776 -270.518636)
		(mid 341.686268 -270.473142)
		(end 341.504016 -270.523462)
		(width 0.0889)
		(layer "In2.Cu")
		(net "M_C_CPU0_SB_CB<7>")
	)
	(arc
		(start 340.929722 -270.518636)
		(mid 340.746214 -270.473142)
		(end 340.563962 -270.523462)
		(width 0.0889)
		(layer "In2.Cu")
		(net "M_C_CPU0_SB_CB<7>")
	)
	(arc
		(start 334.358234 -270.523462)
		(mid 334.175983 -270.473112)
		(end 333.992474 -270.518636)
		(width 0.0889)
		(layer "In2.Cu")
		(net "M_C_CPU0_SB_CB<7>")
	)
	(arc
		(start 330.22413 -270.523462)
		(mid 329.941174 -270.599639)
		(end 329.658218 -270.523462)
		(width 0.0889)
		(layer "In2.Cu")
		(net "M_C_CPU0_SB_CB<7>")
	)
	(arc
		(start 335.298034 -270.523462)
		(mid 335.11109 -270.473207)
		(end 334.924146 -270.523462)
		(width 0.0889)
		(layer "In2.Cu")
		(net "M_C_CPU0_SB_CB<7>")
	)
	(arc
		(start 329.284076 -270.523462)
		(mid 329.00112 -270.599639)
		(end 328.718164 -270.523462)
		(width 0.0889)
		(layer "In2.Cu")
		(net "M_C_CPU0_SB_CB<7>")
	)
	(arc
		(start 329.658218 -270.523462)
		(mid 329.475967 -270.473112)
		(end 329.292458 -270.518636)
		(width 0.0889)
		(layer "In2.Cu")
		(net "M_C_CPU0_SB_CB<7>")
	)
	(arc
		(start 337.744054 -270.523462)
		(mid 337.461098 -270.599639)
		(end 337.178142 -270.523462)
		(width 0.0889)
		(layer "In2.Cu")
		(net "M_C_CPU0_SB_CB<7>")
	)
	(arc
		(start 328.32929 -270.532098)
		(mid 328.052307 -270.599902)
		(end 327.777602 -270.523462)
		(width 0.0889)
		(layer "In2.Cu")
		(net "M_C_CPU0_SB_CB<7>")
	)
	(arc
		(start 343.384124 -270.523462)
		(mid 343.101168 -270.599639)
		(end 342.818212 -270.523462)
		(width 0.0889)
		(layer "In2.Cu")
		(net "M_C_CPU0_SB_CB<7>")
	)
	(arc
		(start 339.624162 -270.523462)
		(mid 339.341206 -270.599639)
		(end 339.05825 -270.523462)
		(width 0.0889)
		(layer "In2.Cu")
		(net "M_C_CPU0_SB_CB<7>")
	)
	(arc
		(start 342.44407 -270.523462)
		(mid 342.161114 -270.599639)
		(end 341.878158 -270.523462)
		(width 0.0889)
		(layer "In2.Cu")
		(net "M_C_CPU0_SB_CB<7>")
	)
	(arc
		(start 336.229706 -270.518636)
		(mid 336.046198 -270.473142)
		(end 335.863946 -270.523462)
		(width 0.0889)
		(layer "In2.Cu")
		(net "M_C_CPU0_SB_CB<7>")
	)
	(arc
		(start 330.598018 -270.523462)
		(mid 330.411074 -270.473207)
		(end 330.22413 -270.523462)
		(width 0.0889)
		(layer "In2.Cu")
		(net "M_C_CPU0_SB_CB<7>")
	)
	(segment
		(start 342.627966 -269.770098)
		(end 342.161114 -270.036036)
		(width 0.10668)
		(layer "F.Cu")
		(net "M_C_CPU0_SB_CB<6>")
	)
	(segment
		(start 342.161114 -270.036036)
		(end 342.315038 -269.770606)
		(width 0.0889)
		(layer "In2.Cu")
		(net "M_C_CPU0_SB_CB<6>")
	)
	(segment
		(start 327.333864 -269.72768)
		(end 327.309988 -269.71371)
		(width 0.0889)
		(layer "In2.Cu")
		(net "M_C_CPU0_SB_CB<6>")
	)
	(segment
		(start 338.588096 -269.713456)
		(end 338.579714 -269.70863)
		(width 0.0889)
		(layer "In2.Cu")
		(net "M_C_CPU0_SB_CB<6>")
	)
	(segment
		(start 290.992814 -271.708626)
		(end 290.83 -271.545812)
		(width 0.14478)
		(layer "In2.Cu")
		(net "M_C_CPU0_SB_CB<6>")
	)
	(segment
		(start 336.342482 -269.70863)
		(end 336.3341 -269.713456)
		(width 0.0889)
		(layer "In2.Cu")
		(net "M_C_CPU0_SB_CB<6>")
	)
	(segment
		(start 325.23176 -268.64691)
		(end 324.828154 -268.64691)
		(width 0.0889)
		(layer "In2.Cu")
		(net "M_C_CPU0_SB_CB<6>")
	)
	(segment
		(start 308.52237 -271.71015)
		(end 298.968414 -271.71015)
		(width 0.14478)
		(layer "In2.Cu")
		(net "M_C_CPU0_SB_CB<6>")
	)
	(segment
		(start 330.702412 -269.70863)
		(end 330.69403 -269.713456)
		(width 0.0889)
		(layer "In2.Cu")
		(net "M_C_CPU0_SB_CB<6>")
	)
	(segment
		(start 330.128118 -269.713456)
		(end 330.119736 -269.70863)
		(width 0.0889)
		(layer "In2.Cu")
		(net "M_C_CPU0_SB_CB<6>")
	)
	(segment
		(start 290.27374 -272.560034)
		(end 290.043108 -272.560034)
		(width 0.14478)
		(layer "In2.Cu")
		(net "M_C_CPU0_SB_CB<6>")
	)
	(segment
		(start 289.324034 -272.39722)
		(end 289.16122 -272.560034)
		(width 0.14478)
		(layer "In2.Cu")
		(net "M_C_CPU0_SB_CB<6>")
	)
	(segment
		(start 333.88808 -269.713456)
		(end 333.879698 -269.70863)
		(width 0.0889)
		(layer "In2.Cu")
		(net "M_C_CPU0_SB_CB<6>")
	)
	(segment
		(start 290.992814 -272.39722)
		(end 290.992814 -271.708626)
		(width 0.14478)
		(layer "In2.Cu")
		(net "M_C_CPU0_SB_CB<6>")
	)
	(segment
		(start 334.828134 -269.713456)
		(end 334.819752 -269.70863)
		(width 0.0889)
		(layer "In2.Cu")
		(net "M_C_CPU0_SB_CB<6>")
	)
	(segment
		(start 291.155628 -272.560034)
		(end 290.992814 -272.39722)
		(width 0.14478)
		(layer "In2.Cu")
		(net "M_C_CPU0_SB_CB<6>")
	)
	(segment
		(start 290.83 -271.545812)
		(end 290.599368 -271.545812)
		(width 0.14478)
		(layer "In2.Cu")
		(net "M_C_CPU0_SB_CB<6>")
	)
	(segment
		(start 312.18124 -268.05128)
		(end 308.52237 -271.71015)
		(width 0.14478)
		(layer "In2.Cu")
		(net "M_C_CPU0_SB_CB<6>")
	)
	(segment
		(start 326.20077 -269.61592)
		(end 325.23176 -268.64691)
		(width 0.0889)
		(layer "In2.Cu")
		(net "M_C_CPU0_SB_CB<6>")
	)
	(segment
		(start 289.71748 -271.33931)
		(end 289.486848 -271.33931)
		(width 0.14478)
		(layer "In2.Cu")
		(net "M_C_CPU0_SB_CB<6>")
	)
	(segment
		(start 290.436554 -271.708626)
		(end 290.436554 -272.39722)
		(width 0.14478)
		(layer "In2.Cu")
		(net "M_C_CPU0_SB_CB<6>")
	)
	(segment
		(start 339.52815 -269.713456)
		(end 339.519768 -269.70863)
		(width 0.0889)
		(layer "In2.Cu")
		(net "M_C_CPU0_SB_CB<6>")
	)
	(segment
		(start 289.16122 -272.560034)
		(end 288.60496 -272.560034)
		(width 0.14478)
		(layer "In2.Cu")
		(net "M_C_CPU0_SB_CB<6>")
	)
	(segment
		(start 326.408034 -269.735554)
		(end 326.20077 -269.61592)
		(width 0.0889)
		(layer "In2.Cu")
		(net "M_C_CPU0_SB_CB<6>")
	)
	(segment
		(start 324.828154 -268.64691)
		(end 324.232524 -268.05128)
		(width 0.0889)
		(layer "In2.Cu")
		(net "M_C_CPU0_SB_CB<6>")
	)
	(segment
		(start 288.60496 -272.560034)
		(end 288.180018 -272.984976)
		(width 0.14478)
		(layer "In2.Cu")
		(net "M_C_CPU0_SB_CB<6>")
	)
	(segment
		(start 290.599368 -271.545812)
		(end 290.436554 -271.708626)
		(width 0.14478)
		(layer "In2.Cu")
		(net "M_C_CPU0_SB_CB<6>")
	)
	(segment
		(start 324.232524 -268.05128)
		(end 323.913754 -268.05128)
		(width 0.0889)
		(layer "In2.Cu")
		(net "M_C_CPU0_SB_CB<6>")
	)
	(segment
		(start 327.882504 -269.70863)
		(end 327.874122 -269.713456)
		(width 0.0889)
		(layer "In2.Cu")
		(net "M_C_CPU0_SB_CB<6>")
	)
	(segment
		(start 298.11853 -272.560034)
		(end 291.155628 -272.560034)
		(width 0.14478)
		(layer "In2.Cu")
		(net "M_C_CPU0_SB_CB<6>")
	)
	(segment
		(start 289.880294 -272.39722)
		(end 289.880294 -271.502124)
		(width 0.14478)
		(layer "In2.Cu")
		(net "M_C_CPU0_SB_CB<6>")
	)
	(segment
		(start 341.042498 -269.70863)
		(end 341.034116 -269.713456)
		(width 0.0889)
		(layer "In2.Cu")
		(net "M_C_CPU0_SB_CB<6>")
	)
	(segment
		(start 289.324034 -271.502124)
		(end 289.324034 -272.39722)
		(width 0.14478)
		(layer "In2.Cu")
		(net "M_C_CPU0_SB_CB<6>")
	)
	(segment
		(start 323.913754 -268.05128)
		(end 312.18124 -268.05128)
		(width 0.14478)
		(layer "In2.Cu")
		(net "M_C_CPU0_SB_CB<6>")
	)
	(segment
		(start 335.402428 -269.70863)
		(end 335.394046 -269.713456)
		(width 0.0889)
		(layer "In2.Cu")
		(net "M_C_CPU0_SB_CB<6>")
	)
	(segment
		(start 289.880294 -271.502124)
		(end 289.71748 -271.33931)
		(width 0.14478)
		(layer "In2.Cu")
		(net "M_C_CPU0_SB_CB<6>")
	)
	(segment
		(start 298.968414 -271.71015)
		(end 298.11853 -272.560034)
		(width 0.14478)
		(layer "In2.Cu")
		(net "M_C_CPU0_SB_CB<6>")
	)
	(segment
		(start 289.486848 -271.33931)
		(end 289.324034 -271.502124)
		(width 0.14478)
		(layer "In2.Cu")
		(net "M_C_CPU0_SB_CB<6>")
	)
	(segment
		(start 331.642466 -269.70863)
		(end 331.634084 -269.713456)
		(width 0.0889)
		(layer "In2.Cu")
		(net "M_C_CPU0_SB_CB<6>")
	)
	(segment
		(start 327.309988 -269.71371)
		(end 327.280016 -269.696438)
		(width 0.0889)
		(layer "In2.Cu")
		(net "M_C_CPU0_SB_CB<6>")
	)
	(segment
		(start 342.315038 -269.770606)
		(end 342.292686 -269.687294)
		(width 0.0889)
		(layer "In2.Cu")
		(net "M_C_CPU0_SB_CB<6>")
	)
	(segment
		(start 290.043108 -272.560034)
		(end 289.880294 -272.39722)
		(width 0.14478)
		(layer "In2.Cu")
		(net "M_C_CPU0_SB_CB<6>")
	)
	(segment
		(start 290.436554 -272.39722)
		(end 290.27374 -272.560034)
		(width 0.14478)
		(layer "In2.Cu")
		(net "M_C_CPU0_SB_CB<6>")
	)
	(segment
		(start 340.102444 -269.70863)
		(end 340.094062 -269.713456)
		(width 0.0889)
		(layer "In2.Cu")
		(net "M_C_CPU0_SB_CB<6>")
	)
	(arc
		(start 328.814176 -269.713456)
		(mid 328.53122 -269.789633)
		(end 328.248264 -269.713456)
		(width 0.0889)
		(layer "In2.Cu")
		(net "M_C_CPU0_SB_CB<6>")
	)
	(arc
		(start 333.513938 -269.713456)
		(mid 333.230982 -269.789633)
		(end 332.948026 -269.713456)
		(width 0.0889)
		(layer "In2.Cu")
		(net "M_C_CPU0_SB_CB<6>")
	)
	(arc
		(start 329.188064 -269.713456)
		(mid 329.00112 -269.663201)
		(end 328.814176 -269.713456)
		(width 0.0889)
		(layer "In2.Cu")
		(net "M_C_CPU0_SB_CB<6>")
	)
	(arc
		(start 335.768188 -269.713456)
		(mid 335.585937 -269.663106)
		(end 335.402428 -269.70863)
		(width 0.0889)
		(layer "In2.Cu")
		(net "M_C_CPU0_SB_CB<6>")
	)
	(arc
		(start 341.034116 -269.713456)
		(mid 340.75116 -269.789633)
		(end 340.468204 -269.713456)
		(width 0.0889)
		(layer "In2.Cu")
		(net "M_C_CPU0_SB_CB<6>")
	)
	(arc
		(start 337.648042 -269.713456)
		(mid 337.461098 -269.663201)
		(end 337.274154 -269.713456)
		(width 0.0889)
		(layer "In2.Cu")
		(net "M_C_CPU0_SB_CB<6>")
	)
	(arc
		(start 336.708242 -269.713456)
		(mid 336.525991 -269.663106)
		(end 336.342482 -269.70863)
		(width 0.0889)
		(layer "In2.Cu")
		(net "M_C_CPU0_SB_CB<6>")
	)
	(arc
		(start 332.008226 -269.713456)
		(mid 331.825975 -269.663106)
		(end 331.642466 -269.70863)
		(width 0.0889)
		(layer "In2.Cu")
		(net "M_C_CPU0_SB_CB<6>")
	)
	(arc
		(start 329.753976 -269.713456)
		(mid 329.47102 -269.789633)
		(end 329.188064 -269.713456)
		(width 0.0889)
		(layer "In2.Cu")
		(net "M_C_CPU0_SB_CB<6>")
	)
	(arc
		(start 327.280016 -269.696438)
		(mid 327.105853 -269.662902)
		(end 326.935846 -269.713456)
		(width 0.0889)
		(layer "In2.Cu")
		(net "M_C_CPU0_SB_CB<6>")
	)
	(arc
		(start 331.068172 -269.713456)
		(mid 330.885921 -269.663106)
		(end 330.702412 -269.70863)
		(width 0.0889)
		(layer "In2.Cu")
		(net "M_C_CPU0_SB_CB<6>")
	)
	(arc
		(start 334.819752 -269.70863)
		(mid 334.636244 -269.663136)
		(end 334.453992 -269.713456)
		(width 0.0889)
		(layer "In2.Cu")
		(net "M_C_CPU0_SB_CB<6>")
	)
	(arc
		(start 340.468204 -269.713456)
		(mid 340.285953 -269.663106)
		(end 340.102444 -269.70863)
		(width 0.0889)
		(layer "In2.Cu")
		(net "M_C_CPU0_SB_CB<6>")
	)
	(arc
		(start 326.935846 -269.713456)
		(mid 326.674688 -269.790035)
		(end 326.408034 -269.735554)
		(width 0.0889)
		(layer "In2.Cu")
		(net "M_C_CPU0_SB_CB<6>")
	)
	(arc
		(start 337.274154 -269.713456)
		(mid 336.991198 -269.789633)
		(end 336.708242 -269.713456)
		(width 0.0889)
		(layer "In2.Cu")
		(net "M_C_CPU0_SB_CB<6>")
	)
	(arc
		(start 331.634084 -269.713456)
		(mid 331.351128 -269.789633)
		(end 331.068172 -269.713456)
		(width 0.0889)
		(layer "In2.Cu")
		(net "M_C_CPU0_SB_CB<6>")
	)
	(arc
		(start 339.154008 -269.713456)
		(mid 338.871052 -269.789633)
		(end 338.588096 -269.713456)
		(width 0.0889)
		(layer "In2.Cu")
		(net "M_C_CPU0_SB_CB<6>")
	)
	(arc
		(start 333.879698 -269.70863)
		(mid 333.69619 -269.663136)
		(end 333.513938 -269.713456)
		(width 0.0889)
		(layer "In2.Cu")
		(net "M_C_CPU0_SB_CB<6>")
	)
	(arc
		(start 332.574138 -269.713456)
		(mid 332.291182 -269.789633)
		(end 332.008226 -269.713456)
		(width 0.0889)
		(layer "In2.Cu")
		(net "M_C_CPU0_SB_CB<6>")
	)
	(arc
		(start 330.69403 -269.713456)
		(mid 330.411074 -269.789633)
		(end 330.128118 -269.713456)
		(width 0.0889)
		(layer "In2.Cu")
		(net "M_C_CPU0_SB_CB<6>")
	)
	(arc
		(start 338.213954 -269.713456)
		(mid 337.930998 -269.789633)
		(end 337.648042 -269.713456)
		(width 0.0889)
		(layer "In2.Cu")
		(net "M_C_CPU0_SB_CB<6>")
	)
	(arc
		(start 335.394046 -269.713456)
		(mid 335.11109 -269.789633)
		(end 334.828134 -269.713456)
		(width 0.0889)
		(layer "In2.Cu")
		(net "M_C_CPU0_SB_CB<6>")
	)
	(arc
		(start 342.292686 -269.687294)
		(mid 342.130497 -269.664559)
		(end 341.97417 -269.713456)
		(width 0.0889)
		(layer "In2.Cu")
		(net "M_C_CPU0_SB_CB<6>")
	)
	(arc
		(start 338.579714 -269.70863)
		(mid 338.396206 -269.663136)
		(end 338.213954 -269.713456)
		(width 0.0889)
		(layer "In2.Cu")
		(net "M_C_CPU0_SB_CB<6>")
	)
	(arc
		(start 330.119736 -269.70863)
		(mid 329.936228 -269.663136)
		(end 329.753976 -269.713456)
		(width 0.0889)
		(layer "In2.Cu")
		(net "M_C_CPU0_SB_CB<6>")
	)
	(arc
		(start 339.519768 -269.70863)
		(mid 339.33626 -269.663136)
		(end 339.154008 -269.713456)
		(width 0.0889)
		(layer "In2.Cu")
		(net "M_C_CPU0_SB_CB<6>")
	)
	(arc
		(start 341.408258 -269.713456)
		(mid 341.226007 -269.663106)
		(end 341.042498 -269.70863)
		(width 0.0889)
		(layer "In2.Cu")
		(net "M_C_CPU0_SB_CB<6>")
	)
	(arc
		(start 334.453992 -269.713456)
		(mid 334.171036 -269.789633)
		(end 333.88808 -269.713456)
		(width 0.0889)
		(layer "In2.Cu")
		(net "M_C_CPU0_SB_CB<6>")
	)
	(arc
		(start 332.948026 -269.713456)
		(mid 332.761082 -269.663201)
		(end 332.574138 -269.713456)
		(width 0.0889)
		(layer "In2.Cu")
		(net "M_C_CPU0_SB_CB<6>")
	)
	(arc
		(start 341.97417 -269.713456)
		(mid 341.691214 -269.789633)
		(end 341.408258 -269.713456)
		(width 0.0889)
		(layer "In2.Cu")
		(net "M_C_CPU0_SB_CB<6>")
	)
	(arc
		(start 336.3341 -269.713456)
		(mid 336.051144 -269.789633)
		(end 335.768188 -269.713456)
		(width 0.0889)
		(layer "In2.Cu")
		(net "M_C_CPU0_SB_CB<6>")
	)
	(arc
		(start 328.248264 -269.713456)
		(mid 328.066013 -269.663106)
		(end 327.882504 -269.70863)
		(width 0.0889)
		(layer "In2.Cu")
		(net "M_C_CPU0_SB_CB<6>")
	)
	(arc
		(start 340.094062 -269.713456)
		(mid 339.811106 -269.789633)
		(end 339.52815 -269.713456)
		(width 0.0889)
		(layer "In2.Cu")
		(net "M_C_CPU0_SB_CB<6>")
	)
	(arc
		(start 327.874122 -269.713456)
		(mid 327.605802 -269.789564)
		(end 327.333864 -269.72768)
		(width 0.0889)
		(layer "In2.Cu")
		(net "M_C_CPU0_SB_CB<6>")
	)
	(segment
		(start 344.508074 -269.770098)
		(end 344.041222 -270.036036)
		(width 0.10668)
		(layer "F.Cu")
		(net "M_C_CPU0_SB_CB<5>")
	)
	(segment
		(start 336.342482 -270.363442)
		(end 336.3341 -270.358616)
		(width 0.0889)
		(layer "In2.Cu")
		(net "M_C_CPU0_SB_CB<5>")
	)
	(segment
		(start 293.89324 -273.70659)
		(end 293.596822 -273.410172)
		(width 0.14478)
		(layer "In2.Cu")
		(net "M_C_CPU0_SB_CB<5>")
	)
	(segment
		(start 304.352452 -272.17751)
		(end 304.074576 -272.17751)
		(width 0.14478)
		(layer "In2.Cu")
		(net "M_C_CPU0_SB_CB<5>")
	)
	(segment
		(start 302.660558 -272.180558)
		(end 302.379634 -272.180558)
		(width 0.14478)
		(layer "In2.Cu")
		(net "M_C_CPU0_SB_CB<5>")
	)
	(segment
		(start 341.042498 -270.363442)
		(end 341.034116 -270.358616)
		(width 0.0889)
		(layer "In2.Cu")
		(net "M_C_CPU0_SB_CB<5>")
	)
	(segment
		(start 308.308502 -272.560034)
		(end 306.716176 -272.560034)
		(width 0.14478)
		(layer "In2.Cu")
		(net "M_C_CPU0_SB_CB<5>")
	)
	(segment
		(start 324.128384 -268.50594)
		(end 323.857874 -268.50594)
		(width 0.0889)
		(layer "In2.Cu")
		(net "M_C_CPU0_SB_CB<5>")
	)
	(segment
		(start 343.887044 -270.301466)
		(end 343.790778 -270.326866)
		(width 0.0889)
		(layer "In2.Cu")
		(net "M_C_CPU0_SB_CB<5>")
	)
	(segment
		(start 335.402428 -270.363442)
		(end 335.394046 -270.358616)
		(width 0.0889)
		(layer "In2.Cu")
		(net "M_C_CPU0_SB_CB<5>")
	)
	(segment
		(start 304.074576 -272.17751)
		(end 303.692052 -272.560034)
		(width 0.14478)
		(layer "In2.Cu")
		(net "M_C_CPU0_SB_CB<5>")
	)
	(segment
		(start 333.88808 -270.358616)
		(end 333.879698 -270.363442)
		(width 0.0889)
		(layer "In2.Cu")
		(net "M_C_CPU0_SB_CB<5>")
	)
	(segment
		(start 304.543714 -273.619214)
		(end 304.543714 -272.368772)
		(width 0.14478)
		(layer "In2.Cu")
		(net "M_C_CPU0_SB_CB<5>")
	)
	(segment
		(start 324.539356 -268.916912)
		(end 324.128384 -268.50594)
		(width 0.0889)
		(layer "In2.Cu")
		(net "M_C_CPU0_SB_CB<5>")
	)
	(segment
		(start 334.828134 -270.358616)
		(end 334.819752 -270.363442)
		(width 0.0889)
		(layer "In2.Cu")
		(net "M_C_CPU0_SB_CB<5>")
	)
	(segment
		(start 302.130714 -272.429478)
		(end 302.130714 -272.58137)
		(width 0.14478)
		(layer "In2.Cu")
		(net "M_C_CPU0_SB_CB<5>")
	)
	(segment
		(start 294.153336 -273.70659)
		(end 293.89324 -273.70659)
		(width 0.14478)
		(layer "In2.Cu")
		(net "M_C_CPU0_SB_CB<5>")
	)
	(segment
		(start 300.954694 -272.55089)
		(end 300.954694 -272.664174)
		(width 0.14478)
		(layer "In2.Cu")
		(net "M_C_CPU0_SB_CB<5>")
	)
	(segment
		(start 301.980854 -272.73123)
		(end 301.669958 -272.73123)
		(width 0.14478)
		(layer "In2.Cu")
		(net "M_C_CPU0_SB_CB<5>")
	)
	(segment
		(start 298.956476 -272.560034)
		(end 298.106338 -273.410172)
		(width 0.14478)
		(layer "In2.Cu")
		(net "M_C_CPU0_SB_CB<5>")
	)
	(segment
		(start 331.642466 -270.363442)
		(end 331.634084 -270.358616)
		(width 0.0889)
		(layer "In2.Cu")
		(net "M_C_CPU0_SB_CB<5>")
	)
	(segment
		(start 340.102444 -270.363442)
		(end 340.094062 -270.358616)
		(width 0.0889)
		(layer "In2.Cu")
		(net "M_C_CPU0_SB_CB<5>")
	)
	(segment
		(start 305.395376 -272.17751)
		(end 305.204114 -272.368772)
		(width 0.14478)
		(layer "In2.Cu")
		(net "M_C_CPU0_SB_CB<5>")
	)
	(segment
		(start 306.333652 -272.942558)
		(end 306.055776 -272.942558)
		(width 0.14478)
		(layer "In2.Cu")
		(net "M_C_CPU0_SB_CB<5>")
	)
	(segment
		(start 297.109388 -273.70151)
		(end 296.81805 -273.410172)
		(width 0.14478)
		(layer "In2.Cu")
		(net "M_C_CPU0_SB_CB<5>")
	)
	(segment
		(start 305.204114 -273.619214)
		(end 305.012852 -273.810476)
		(width 0.14478)
		(layer "In2.Cu")
		(net "M_C_CPU0_SB_CB<5>")
	)
	(segment
		(start 312.362596 -268.50594)
		(end 308.308502 -272.560034)
		(width 0.14478)
		(layer "In2.Cu")
		(net "M_C_CPU0_SB_CB<5>")
	)
	(segment
		(start 294.449754 -273.410172)
		(end 294.153336 -273.70659)
		(width 0.14478)
		(layer "In2.Cu")
		(net "M_C_CPU0_SB_CB<5>")
	)
	(segment
		(start 301.104554 -272.40103)
		(end 300.954694 -272.55089)
		(width 0.14478)
		(layer "In2.Cu")
		(net "M_C_CPU0_SB_CB<5>")
	)
	(segment
		(start 302.130714 -272.58137)
		(end 301.980854 -272.73123)
		(width 0.14478)
		(layer "In2.Cu")
		(net "M_C_CPU0_SB_CB<5>")
	)
	(segment
		(start 330.702412 -270.363442)
		(end 330.69403 -270.358616)
		(width 0.0889)
		(layer "In2.Cu")
		(net "M_C_CPU0_SB_CB<5>")
	)
	(segment
		(start 296.81805 -273.410172)
		(end 294.449754 -273.410172)
		(width 0.14478)
		(layer "In2.Cu")
		(net "M_C_CPU0_SB_CB<5>")
	)
	(segment
		(start 328.248264 -270.358616)
		(end 328.239882 -270.363442)
		(width 0.0889)
		(layer "In2.Cu")
		(net "M_C_CPU0_SB_CB<5>")
	)
	(segment
		(start 327.873614 -270.358616)
		(end 327.869042 -270.356076)
		(width 0.0889)
		(layer "In2.Cu")
		(net "M_C_CPU0_SB_CB<5>")
	)
	(segment
		(start 297.374564 -273.70151)
		(end 297.109388 -273.70151)
		(width 0.14478)
		(layer "In2.Cu")
		(net "M_C_CPU0_SB_CB<5>")
	)
	(segment
		(start 301.339758 -272.40103)
		(end 301.104554 -272.40103)
		(width 0.14478)
		(layer "In2.Cu")
		(net "M_C_CPU0_SB_CB<5>")
	)
	(segment
		(start 305.012852 -273.810476)
		(end 304.734976 -273.810476)
		(width 0.14478)
		(layer "In2.Cu")
		(net "M_C_CPU0_SB_CB<5>")
	)
	(segment
		(start 325.060056 -268.916912)
		(end 324.539356 -268.916912)
		(width 0.0889)
		(layer "In2.Cu")
		(net "M_C_CPU0_SB_CB<5>")
	)
	(segment
		(start 297.665902 -273.410172)
		(end 297.374564 -273.70151)
		(width 0.14478)
		(layer "In2.Cu")
		(net "M_C_CPU0_SB_CB<5>")
	)
	(segment
		(start 304.734976 -273.810476)
		(end 304.543714 -273.619214)
		(width 0.14478)
		(layer "In2.Cu")
		(net "M_C_CPU0_SB_CB<5>")
	)
	(segment
		(start 300.679358 -272.93951)
		(end 300.398434 -272.93951)
		(width 0.14478)
		(layer "In2.Cu")
		(net "M_C_CPU0_SB_CB<5>")
	)
	(segment
		(start 302.379634 -272.180558)
		(end 302.130714 -272.429478)
		(width 0.14478)
		(layer "In2.Cu")
		(net "M_C_CPU0_SB_CB<5>")
	)
	(segment
		(start 330.128118 -270.358616)
		(end 330.119736 -270.363442)
		(width 0.0889)
		(layer "In2.Cu")
		(net "M_C_CPU0_SB_CB<5>")
	)
	(segment
		(start 343.288112 -270.358616)
		(end 343.27973 -270.363442)
		(width 0.0889)
		(layer "In2.Cu")
		(net "M_C_CPU0_SB_CB<5>")
	)
	(segment
		(start 305.673252 -272.17751)
		(end 305.395376 -272.17751)
		(width 0.14478)
		(layer "In2.Cu")
		(net "M_C_CPU0_SB_CB<5>")
	)
	(segment
		(start 339.52815 -270.358616)
		(end 339.519768 -270.363442)
		(width 0.0889)
		(layer "In2.Cu")
		(net "M_C_CPU0_SB_CB<5>")
	)
	(segment
		(start 298.106338 -273.410172)
		(end 297.665902 -273.410172)
		(width 0.14478)
		(layer "In2.Cu")
		(net "M_C_CPU0_SB_CB<5>")
	)
	(segment
		(start 306.055776 -272.942558)
		(end 305.864514 -272.751296)
		(width 0.14478)
		(layer "In2.Cu")
		(net "M_C_CPU0_SB_CB<5>")
	)
	(segment
		(start 301.669958 -272.73123)
		(end 301.339758 -272.40103)
		(width 0.14478)
		(layer "In2.Cu")
		(net "M_C_CPU0_SB_CB<5>")
	)
	(segment
		(start 304.543714 -272.368772)
		(end 304.352452 -272.17751)
		(width 0.14478)
		(layer "In2.Cu")
		(net "M_C_CPU0_SB_CB<5>")
	)
	(segment
		(start 292.705028 -273.410172)
		(end 292.280086 -273.835114)
		(width 0.14478)
		(layer "In2.Cu")
		(net "M_C_CPU0_SB_CB<5>")
	)
	(segment
		(start 300.398434 -272.93951)
		(end 300.018958 -272.560034)
		(width 0.14478)
		(layer "In2.Cu")
		(net "M_C_CPU0_SB_CB<5>")
	)
	(segment
		(start 306.716176 -272.560034)
		(end 306.333652 -272.942558)
		(width 0.14478)
		(layer "In2.Cu")
		(net "M_C_CPU0_SB_CB<5>")
	)
	(segment
		(start 293.596822 -273.410172)
		(end 292.705028 -273.410172)
		(width 0.14478)
		(layer "In2.Cu")
		(net "M_C_CPU0_SB_CB<5>")
	)
	(segment
		(start 327.608438 -270.285718)
		(end 326.428862 -270.285718)
		(width 0.0889)
		(layer "In2.Cu")
		(net "M_C_CPU0_SB_CB<5>")
	)
	(segment
		(start 344.041222 -270.036036)
		(end 343.887044 -270.301466)
		(width 0.0889)
		(layer "In2.Cu")
		(net "M_C_CPU0_SB_CB<5>")
	)
	(segment
		(start 305.864514 -272.368772)
		(end 305.673252 -272.17751)
		(width 0.14478)
		(layer "In2.Cu")
		(net "M_C_CPU0_SB_CB<5>")
	)
	(segment
		(start 303.040034 -272.560034)
		(end 302.660558 -272.180558)
		(width 0.14478)
		(layer "In2.Cu")
		(net "M_C_CPU0_SB_CB<5>")
	)
	(segment
		(start 305.204114 -272.368772)
		(end 305.204114 -273.619214)
		(width 0.14478)
		(layer "In2.Cu")
		(net "M_C_CPU0_SB_CB<5>")
	)
	(segment
		(start 326.428862 -270.285718)
		(end 325.060056 -268.916912)
		(width 0.0889)
		(layer "In2.Cu")
		(net "M_C_CPU0_SB_CB<5>")
	)
	(segment
		(start 305.864514 -272.751296)
		(end 305.864514 -272.368772)
		(width 0.14478)
		(layer "In2.Cu")
		(net "M_C_CPU0_SB_CB<5>")
	)
	(segment
		(start 300.018958 -272.560034)
		(end 298.956476 -272.560034)
		(width 0.14478)
		(layer "In2.Cu")
		(net "M_C_CPU0_SB_CB<5>")
	)
	(segment
		(start 323.857874 -268.50594)
		(end 312.362596 -268.50594)
		(width 0.14478)
		(layer "In2.Cu")
		(net "M_C_CPU0_SB_CB<5>")
	)
	(segment
		(start 303.692052 -272.560034)
		(end 303.040034 -272.560034)
		(width 0.14478)
		(layer "In2.Cu")
		(net "M_C_CPU0_SB_CB<5>")
	)
	(segment
		(start 338.588096 -270.358616)
		(end 338.579714 -270.363442)
		(width 0.0889)
		(layer "In2.Cu")
		(net "M_C_CPU0_SB_CB<5>")
	)
	(segment
		(start 300.954694 -272.664174)
		(end 300.679358 -272.93951)
		(width 0.14478)
		(layer "In2.Cu")
		(net "M_C_CPU0_SB_CB<5>")
	)
	(arc
		(start 331.068172 -270.358616)
		(mid 330.885921 -270.408966)
		(end 330.702412 -270.363442)
		(width 0.0889)
		(layer "In2.Cu")
		(net "M_C_CPU0_SB_CB<5>")
	)
	(arc
		(start 332.948026 -270.358616)
		(mid 332.761082 -270.408871)
		(end 332.574138 -270.358616)
		(width 0.0889)
		(layer "In2.Cu")
		(net "M_C_CPU0_SB_CB<5>")
	)
	(arc
		(start 336.3341 -270.358616)
		(mid 336.051144 -270.282439)
		(end 335.768188 -270.358616)
		(width 0.0889)
		(layer "In2.Cu")
		(net "M_C_CPU0_SB_CB<5>")
	)
	(arc
		(start 335.768188 -270.358616)
		(mid 335.585937 -270.408966)
		(end 335.402428 -270.363442)
		(width 0.0889)
		(layer "In2.Cu")
		(net "M_C_CPU0_SB_CB<5>")
	)
	(arc
		(start 333.513938 -270.358616)
		(mid 333.230982 -270.282439)
		(end 332.948026 -270.358616)
		(width 0.0889)
		(layer "In2.Cu")
		(net "M_C_CPU0_SB_CB<5>")
	)
	(arc
		(start 343.27973 -270.363442)
		(mid 343.096222 -270.408936)
		(end 342.91397 -270.358616)
		(width 0.0889)
		(layer "In2.Cu")
		(net "M_C_CPU0_SB_CB<5>")
	)
	(arc
		(start 329.753976 -270.358616)
		(mid 329.47102 -270.282439)
		(end 329.188064 -270.358616)
		(width 0.0889)
		(layer "In2.Cu")
		(net "M_C_CPU0_SB_CB<5>")
	)
	(arc
		(start 332.008226 -270.358616)
		(mid 331.825975 -270.408966)
		(end 331.642466 -270.363442)
		(width 0.0889)
		(layer "In2.Cu")
		(net "M_C_CPU0_SB_CB<5>")
	)
	(arc
		(start 341.034116 -270.358616)
		(mid 340.75116 -270.282439)
		(end 340.468204 -270.358616)
		(width 0.0889)
		(layer "In2.Cu")
		(net "M_C_CPU0_SB_CB<5>")
	)
	(arc
		(start 340.468204 -270.358616)
		(mid 340.285953 -270.408966)
		(end 340.102444 -270.363442)
		(width 0.0889)
		(layer "In2.Cu")
		(net "M_C_CPU0_SB_CB<5>")
	)
	(arc
		(start 328.814176 -270.358616)
		(mid 328.53122 -270.282439)
		(end 328.248264 -270.358616)
		(width 0.0889)
		(layer "In2.Cu")
		(net "M_C_CPU0_SB_CB<5>")
	)
	(arc
		(start 337.648042 -270.358616)
		(mid 337.461098 -270.408871)
		(end 337.274154 -270.358616)
		(width 0.0889)
		(layer "In2.Cu")
		(net "M_C_CPU0_SB_CB<5>")
	)
	(arc
		(start 340.094062 -270.358616)
		(mid 339.811106 -270.282439)
		(end 339.52815 -270.358616)
		(width 0.0889)
		(layer "In2.Cu")
		(net "M_C_CPU0_SB_CB<5>")
	)
	(arc
		(start 339.154008 -270.358616)
		(mid 338.871052 -270.282439)
		(end 338.588096 -270.358616)
		(width 0.0889)
		(layer "In2.Cu")
		(net "M_C_CPU0_SB_CB<5>")
	)
	(arc
		(start 330.69403 -270.358616)
		(mid 330.411074 -270.282439)
		(end 330.128118 -270.358616)
		(width 0.0889)
		(layer "In2.Cu")
		(net "M_C_CPU0_SB_CB<5>")
	)
	(arc
		(start 341.408258 -270.358616)
		(mid 341.226007 -270.408966)
		(end 341.042498 -270.363442)
		(width 0.0889)
		(layer "In2.Cu")
		(net "M_C_CPU0_SB_CB<5>")
	)
	(arc
		(start 343.790778 -270.326866)
		(mid 343.535713 -270.283515)
		(end 343.288112 -270.358616)
		(width 0.0889)
		(layer "In2.Cu")
		(net "M_C_CPU0_SB_CB<5>")
	)
	(arc
		(start 335.394046 -270.358616)
		(mid 335.11109 -270.282439)
		(end 334.828134 -270.358616)
		(width 0.0889)
		(layer "In2.Cu")
		(net "M_C_CPU0_SB_CB<5>")
	)
	(arc
		(start 331.634084 -270.358616)
		(mid 331.351128 -270.282439)
		(end 331.068172 -270.358616)
		(width 0.0889)
		(layer "In2.Cu")
		(net "M_C_CPU0_SB_CB<5>")
	)
	(arc
		(start 337.274154 -270.358616)
		(mid 336.991198 -270.282439)
		(end 336.708242 -270.358616)
		(width 0.0889)
		(layer "In2.Cu")
		(net "M_C_CPU0_SB_CB<5>")
	)
	(arc
		(start 329.188064 -270.358616)
		(mid 329.00112 -270.408871)
		(end 328.814176 -270.358616)
		(width 0.0889)
		(layer "In2.Cu")
		(net "M_C_CPU0_SB_CB<5>")
	)
	(arc
		(start 336.708242 -270.358616)
		(mid 336.525991 -270.408966)
		(end 336.342482 -270.363442)
		(width 0.0889)
		(layer "In2.Cu")
		(net "M_C_CPU0_SB_CB<5>")
	)
	(arc
		(start 330.119736 -270.363442)
		(mid 329.936228 -270.408936)
		(end 329.753976 -270.358616)
		(width 0.0889)
		(layer "In2.Cu")
		(net "M_C_CPU0_SB_CB<5>")
	)
	(arc
		(start 328.239882 -270.363442)
		(mid 328.05612 -270.409058)
		(end 327.873614 -270.358616)
		(width 0.0889)
		(layer "In2.Cu")
		(net "M_C_CPU0_SB_CB<5>")
	)
	(arc
		(start 327.869042 -270.356076)
		(mid 327.743398 -270.303641)
		(end 327.608438 -270.285718)
		(width 0.0889)
		(layer "In2.Cu")
		(net "M_C_CPU0_SB_CB<5>")
	)
	(arc
		(start 334.453992 -270.358616)
		(mid 334.171036 -270.282439)
		(end 333.88808 -270.358616)
		(width 0.0889)
		(layer "In2.Cu")
		(net "M_C_CPU0_SB_CB<5>")
	)
	(arc
		(start 338.579714 -270.363442)
		(mid 338.396206 -270.408936)
		(end 338.213954 -270.358616)
		(width 0.0889)
		(layer "In2.Cu")
		(net "M_C_CPU0_SB_CB<5>")
	)
	(arc
		(start 342.91397 -270.358616)
		(mid 342.631014 -270.282439)
		(end 342.348058 -270.358616)
		(width 0.0889)
		(layer "In2.Cu")
		(net "M_C_CPU0_SB_CB<5>")
	)
	(arc
		(start 339.519768 -270.363442)
		(mid 339.33626 -270.408936)
		(end 339.154008 -270.358616)
		(width 0.0889)
		(layer "In2.Cu")
		(net "M_C_CPU0_SB_CB<5>")
	)
	(arc
		(start 338.213954 -270.358616)
		(mid 337.930998 -270.282439)
		(end 337.648042 -270.358616)
		(width 0.0889)
		(layer "In2.Cu")
		(net "M_C_CPU0_SB_CB<5>")
	)
	(arc
		(start 341.97417 -270.358616)
		(mid 341.691214 -270.282439)
		(end 341.408258 -270.358616)
		(width 0.0889)
		(layer "In2.Cu")
		(net "M_C_CPU0_SB_CB<5>")
	)
	(arc
		(start 342.348058 -270.358616)
		(mid 342.161114 -270.408871)
		(end 341.97417 -270.358616)
		(width 0.0889)
		(layer "In2.Cu")
		(net "M_C_CPU0_SB_CB<5>")
	)
	(arc
		(start 334.819752 -270.363442)
		(mid 334.636244 -270.408936)
		(end 334.453992 -270.358616)
		(width 0.0889)
		(layer "In2.Cu")
		(net "M_C_CPU0_SB_CB<5>")
	)
	(arc
		(start 333.879698 -270.363442)
		(mid 333.69619 -270.408936)
		(end 333.513938 -270.358616)
		(width 0.0889)
		(layer "In2.Cu")
		(net "M_C_CPU0_SB_CB<5>")
	)
	(arc
		(start 332.574138 -270.358616)
		(mid 332.291182 -270.282439)
		(end 332.008226 -270.358616)
		(width 0.0889)
		(layer "In2.Cu")
		(net "M_C_CPU0_SB_CB<5>")
	)
	(segment
		(start 343.097866 -268.960092)
		(end 342.631014 -269.22603)
		(width 0.10668)
		(layer "F.Cu")
		(net "M_C_CPU0_SB_CB<4>")
	)
	(segment
		(start 311.999884 -267.59662)
		(end 311.519824 -268.07668)
		(width 0.14478)
		(layer "In2.Cu")
		(net "M_C_CPU0_SB_CB<4>")
	)
	(segment
		(start 293.378382 -270.916908)
		(end 293.378382 -271.516602)
		(width 0.14478)
		(layer "In2.Cu")
		(net "M_C_CPU0_SB_CB<4>")
	)
	(segment
		(start 332.478126 -269.54861)
		(end 332.469744 -269.553436)
		(width 0.0889)
		(layer "In2.Cu")
		(net "M_C_CPU0_SB_CB<4>")
	)
	(segment
		(start 294.898826 -271.71015)
		(end 294.503602 -272.105374)
		(width 0.14478)
		(layer "In2.Cu")
		(net "M_C_CPU0_SB_CB<4>")
	)
	(segment
		(start 292.705028 -271.71015)
		(end 292.280086 -272.135092)
		(width 0.14478)
		(layer "In2.Cu")
		(net "M_C_CPU0_SB_CB<4>")
	)
	(segment
		(start 296.745914 -272.105374)
		(end 296.47261 -272.105374)
		(width 0.14478)
		(layer "In2.Cu")
		(net "M_C_CPU0_SB_CB<4>")
	)
	(segment
		(start 297.404282 -270.755618)
		(end 297.130978 -270.755618)
		(width 0.14478)
		(layer "In2.Cu")
		(net "M_C_CPU0_SB_CB<4>")
	)
	(segment
		(start 305.201574 -270.860012)
		(end 304.823876 -271.23771)
		(width 0.14478)
		(layer "In2.Cu")
		(net "M_C_CPU0_SB_CB<4>")
	)
	(segment
		(start 304.541174 -271.23771)
		(end 304.163476 -270.860012)
		(width 0.14478)
		(layer "In2.Cu")
		(net "M_C_CPU0_SB_CB<4>")
	)
	(segment
		(start 304.163476 -270.860012)
		(end 302.485552 -270.860012)
		(width 0.14478)
		(layer "In2.Cu")
		(net "M_C_CPU0_SB_CB<4>")
	)
	(segment
		(start 296.077386 -271.71015)
		(end 294.898826 -271.71015)
		(width 0.14478)
		(layer "In2.Cu")
		(net "M_C_CPU0_SB_CB<4>")
	)
	(segment
		(start 297.130978 -270.755618)
		(end 296.93743 -270.949166)
		(width 0.14478)
		(layer "In2.Cu")
		(net "M_C_CPU0_SB_CB<4>")
	)
	(segment
		(start 305.861974 -271.23771)
		(end 305.484276 -270.860012)
		(width 0.14478)
		(layer "In2.Cu")
		(net "M_C_CPU0_SB_CB<4>")
	)
	(segment
		(start 309.531512 -269.637256)
		(end 309.355236 -269.813532)
		(width 0.14478)
		(layer "In2.Cu")
		(net "M_C_CPU0_SB_CB<4>")
	)
	(segment
		(start 310.135524 -269.46098)
		(end 309.959248 -269.637256)
		(width 0.14478)
		(layer "In2.Cu")
		(net "M_C_CPU0_SB_CB<4>")
	)
	(segment
		(start 297.59783 -270.949166)
		(end 297.404282 -270.755618)
		(width 0.14478)
		(layer "In2.Cu")
		(net "M_C_CPU0_SB_CB<4>")
	)
	(segment
		(start 329.292458 -269.553436)
		(end 329.284076 -269.54861)
		(width 0.0889)
		(layer "In2.Cu")
		(net "M_C_CPU0_SB_CB<4>")
	)
	(segment
		(start 300.504352 -271.23771)
		(end 300.126654 -270.860012)
		(width 0.14478)
		(layer "In2.Cu")
		(net "M_C_CPU0_SB_CB<4>")
	)
	(segment
		(start 306.144676 -271.23771)
		(end 305.861974 -271.23771)
		(width 0.14478)
		(layer "In2.Cu")
		(net "M_C_CPU0_SB_CB<4>")
	)
	(segment
		(start 293.845234 -270.72336)
		(end 293.57193 -270.72336)
		(width 0.14478)
		(layer "In2.Cu")
		(net "M_C_CPU0_SB_CB<4>")
	)
	(segment
		(start 294.230298 -272.105374)
		(end 294.038782 -271.913858)
		(width 0.14478)
		(layer "In2.Cu")
		(net "M_C_CPU0_SB_CB<4>")
	)
	(segment
		(start 342.47709 -269.49146)
		(end 342.381078 -269.51686)
		(width 0.0889)
		(layer "In2.Cu")
		(net "M_C_CPU0_SB_CB<4>")
	)
	(segment
		(start 333.992474 -269.553436)
		(end 333.984092 -269.54861)
		(width 0.0889)
		(layer "In2.Cu")
		(net "M_C_CPU0_SB_CB<4>")
	)
	(segment
		(start 341.878158 -269.54861)
		(end 341.869776 -269.553436)
		(width 0.0889)
		(layer "In2.Cu")
		(net "M_C_CPU0_SB_CB<4>")
	)
	(segment
		(start 310.739536 -268.856968)
		(end 310.3118 -268.856968)
		(width 0.14478)
		(layer "In2.Cu")
		(net "M_C_CPU0_SB_CB<4>")
	)
	(segment
		(start 294.503602 -272.105374)
		(end 294.230298 -272.105374)
		(width 0.14478)
		(layer "In2.Cu")
		(net "M_C_CPU0_SB_CB<4>")
	)
	(segment
		(start 326.49541 -269.565628)
		(end 326.341486 -269.476982)
		(width 0.0889)
		(layer "In2.Cu")
		(net "M_C_CPU0_SB_CB<4>")
	)
	(segment
		(start 340.938104 -269.54861)
		(end 340.929722 -269.553436)
		(width 0.0889)
		(layer "In2.Cu")
		(net "M_C_CPU0_SB_CB<4>")
	)
	(segment
		(start 338.69249 -269.553436)
		(end 338.684108 -269.54861)
		(width 0.0889)
		(layer "In2.Cu")
		(net "M_C_CPU0_SB_CB<4>")
	)
	(segment
		(start 325.171054 -267.59662)
		(end 323.909944 -267.59662)
		(width 0.0889)
		(layer "In2.Cu")
		(net "M_C_CPU0_SB_CB<4>")
	)
	(segment
		(start 336.238088 -269.54861)
		(end 336.229706 -269.553436)
		(width 0.0889)
		(layer "In2.Cu")
		(net "M_C_CPU0_SB_CB<4>")
	)
	(segment
		(start 293.184834 -271.71015)
		(end 292.705028 -271.71015)
		(width 0.14478)
		(layer "In2.Cu")
		(net "M_C_CPU0_SB_CB<4>")
	)
	(segment
		(start 306.522374 -270.860012)
		(end 306.144676 -271.23771)
		(width 0.14478)
		(layer "In2.Cu")
		(net "M_C_CPU0_SB_CB<4>")
	)
	(segment
		(start 310.915812 -268.680692)
		(end 310.739536 -268.856968)
		(width 0.14478)
		(layer "In2.Cu")
		(net "M_C_CPU0_SB_CB<4>")
	)
	(segment
		(start 297.758866 -272.061686)
		(end 297.59783 -271.90065)
		(width 0.14478)
		(layer "In2.Cu")
		(net "M_C_CPU0_SB_CB<4>")
	)
	(segment
		(start 325.561198 -267.986764)
		(end 325.171054 -267.59662)
		(width 0.0889)
		(layer "In2.Cu")
		(net "M_C_CPU0_SB_CB<4>")
	)
	(segment
		(start 293.57193 -270.72336)
		(end 293.378382 -270.916908)
		(width 0.14478)
		(layer "In2.Cu")
		(net "M_C_CPU0_SB_CB<4>")
	)
	(segment
		(start 310.3118 -268.856968)
		(end 310.135524 -269.033244)
		(width 0.14478)
		(layer "In2.Cu")
		(net "M_C_CPU0_SB_CB<4>")
	)
	(segment
		(start 308.736492 -270.860012)
		(end 306.522374 -270.860012)
		(width 0.14478)
		(layer "In2.Cu")
		(net "M_C_CPU0_SB_CB<4>")
	)
	(segment
		(start 304.823876 -271.23771)
		(end 304.541174 -271.23771)
		(width 0.14478)
		(layer "In2.Cu")
		(net "M_C_CPU0_SB_CB<4>")
	)
	(segment
		(start 333.05242 -269.553436)
		(end 333.044038 -269.54861)
		(width 0.0889)
		(layer "In2.Cu")
		(net "M_C_CPU0_SB_CB<4>")
	)
	(segment
		(start 309.355236 -269.813532)
		(end 309.355236 -270.241268)
		(width 0.14478)
		(layer "In2.Cu")
		(net "M_C_CPU0_SB_CB<4>")
	)
	(segment
		(start 323.909944 -267.59662)
		(end 311.999884 -267.59662)
		(width 0.14478)
		(layer "In2.Cu")
		(net "M_C_CPU0_SB_CB<4>")
	)
	(segment
		(start 299.182536 -270.860012)
		(end 297.980862 -272.061686)
		(width 0.14478)
		(layer "In2.Cu")
		(net "M_C_CPU0_SB_CB<4>")
	)
	(segment
		(start 300.126654 -270.860012)
		(end 299.182536 -270.860012)
		(width 0.14478)
		(layer "In2.Cu")
		(net "M_C_CPU0_SB_CB<4>")
	)
	(segment
		(start 301.825152 -271.23771)
		(end 301.447454 -270.860012)
		(width 0.14478)
		(layer "In2.Cu")
		(net "M_C_CPU0_SB_CB<4>")
	)
	(segment
		(start 297.59783 -271.90065)
		(end 297.59783 -270.949166)
		(width 0.14478)
		(layer "In2.Cu")
		(net "M_C_CPU0_SB_CB<4>")
	)
	(segment
		(start 311.519824 -268.07668)
		(end 311.092088 -268.07668)
		(width 0.14478)
		(layer "In2.Cu")
		(net "M_C_CPU0_SB_CB<4>")
	)
	(segment
		(start 302.107854 -271.23771)
		(end 301.825152 -271.23771)
		(width 0.14478)
		(layer "In2.Cu")
		(net "M_C_CPU0_SB_CB<4>")
	)
	(segment
		(start 337.178142 -269.54861)
		(end 337.16976 -269.553436)
		(width 0.0889)
		(layer "In2.Cu")
		(net "M_C_CPU0_SB_CB<4>")
	)
	(segment
		(start 296.47261 -272.105374)
		(end 296.077386 -271.71015)
		(width 0.14478)
		(layer "In2.Cu")
		(net "M_C_CPU0_SB_CB<4>")
	)
	(segment
		(start 302.485552 -270.860012)
		(end 302.107854 -271.23771)
		(width 0.14478)
		(layer "In2.Cu")
		(net "M_C_CPU0_SB_CB<4>")
	)
	(segment
		(start 327.427336 -269.560802)
		(end 327.405492 -269.548356)
		(width 0.0889)
		(layer "In2.Cu")
		(net "M_C_CPU0_SB_CB<4>")
	)
	(segment
		(start 310.915812 -268.252956)
		(end 310.915812 -268.680692)
		(width 0.14478)
		(layer "In2.Cu")
		(net "M_C_CPU0_SB_CB<4>")
	)
	(segment
		(start 309.355236 -270.241268)
		(end 308.736492 -270.860012)
		(width 0.14478)
		(layer "In2.Cu")
		(net "M_C_CPU0_SB_CB<4>")
	)
	(segment
		(start 301.164752 -270.860012)
		(end 300.787054 -271.23771)
		(width 0.14478)
		(layer "In2.Cu")
		(net "M_C_CPU0_SB_CB<4>")
	)
	(segment
		(start 342.631014 -269.22603)
		(end 342.47709 -269.49146)
		(width 0.0889)
		(layer "In2.Cu")
		(net "M_C_CPU0_SB_CB<4>")
	)
	(segment
		(start 294.038782 -271.913858)
		(end 294.038782 -270.916908)
		(width 0.14478)
		(layer "In2.Cu")
		(net "M_C_CPU0_SB_CB<4>")
	)
	(segment
		(start 294.038782 -270.916908)
		(end 293.845234 -270.72336)
		(width 0.14478)
		(layer "In2.Cu")
		(net "M_C_CPU0_SB_CB<4>")
	)
	(segment
		(start 325.561198 -268.696694)
		(end 325.561198 -267.986764)
		(width 0.0889)
		(layer "In2.Cu")
		(net "M_C_CPU0_SB_CB<4>")
	)
	(segment
		(start 296.93743 -271.913858)
		(end 296.745914 -272.105374)
		(width 0.14478)
		(layer "In2.Cu")
		(net "M_C_CPU0_SB_CB<4>")
	)
	(segment
		(start 311.092088 -268.07668)
		(end 310.915812 -268.252956)
		(width 0.14478)
		(layer "In2.Cu")
		(net "M_C_CPU0_SB_CB<4>")
	)
	(segment
		(start 326.341486 -269.476982)
		(end 325.561198 -268.696694)
		(width 0.0889)
		(layer "In2.Cu")
		(net "M_C_CPU0_SB_CB<4>")
	)
	(segment
		(start 296.93743 -270.949166)
		(end 296.93743 -271.913858)
		(width 0.14478)
		(layer "In2.Cu")
		(net "M_C_CPU0_SB_CB<4>")
	)
	(segment
		(start 297.980862 -272.061686)
		(end 297.758866 -272.061686)
		(width 0.14478)
		(layer "In2.Cu")
		(net "M_C_CPU0_SB_CB<4>")
	)
	(segment
		(start 300.787054 -271.23771)
		(end 300.504352 -271.23771)
		(width 0.14478)
		(layer "In2.Cu")
		(net "M_C_CPU0_SB_CB<4>")
	)
	(segment
		(start 331.538072 -269.54861)
		(end 331.52969 -269.553436)
		(width 0.0889)
		(layer "In2.Cu")
		(net "M_C_CPU0_SB_CB<4>")
	)
	(segment
		(start 327.405492 -269.548356)
		(end 327.368916 -269.527274)
		(width 0.0889)
		(layer "In2.Cu")
		(net "M_C_CPU0_SB_CB<4>")
	)
	(segment
		(start 293.378382 -271.516602)
		(end 293.184834 -271.71015)
		(width 0.14478)
		(layer "In2.Cu")
		(net "M_C_CPU0_SB_CB<4>")
	)
	(segment
		(start 328.718164 -269.54861)
		(end 328.709782 -269.553436)
		(width 0.0889)
		(layer "In2.Cu")
		(net "M_C_CPU0_SB_CB<4>")
	)
	(segment
		(start 305.484276 -270.860012)
		(end 305.201574 -270.860012)
		(width 0.14478)
		(layer "In2.Cu")
		(net "M_C_CPU0_SB_CB<4>")
	)
	(segment
		(start 301.447454 -270.860012)
		(end 301.164752 -270.860012)
		(width 0.14478)
		(layer "In2.Cu")
		(net "M_C_CPU0_SB_CB<4>")
	)
	(segment
		(start 309.959248 -269.637256)
		(end 309.531512 -269.637256)
		(width 0.14478)
		(layer "In2.Cu")
		(net "M_C_CPU0_SB_CB<4>")
	)
	(segment
		(start 337.752436 -269.553436)
		(end 337.744054 -269.54861)
		(width 0.0889)
		(layer "In2.Cu")
		(net "M_C_CPU0_SB_CB<4>")
	)
	(segment
		(start 310.135524 -269.033244)
		(end 310.135524 -269.46098)
		(width 0.14478)
		(layer "In2.Cu")
		(net "M_C_CPU0_SB_CB<4>")
	)
	(arc
		(start 334.924146 -269.54861)
		(mid 334.64119 -269.472433)
		(end 334.358234 -269.54861)
		(width 0.0889)
		(layer "In2.Cu")
		(net "M_C_CPU0_SB_CB<4>")
	)
	(arc
		(start 335.863946 -269.54861)
		(mid 335.58099 -269.472433)
		(end 335.298034 -269.54861)
		(width 0.0889)
		(layer "In2.Cu")
		(net "M_C_CPU0_SB_CB<4>")
	)
	(arc
		(start 331.16393 -269.54861)
		(mid 330.880974 -269.472433)
		(end 330.598018 -269.54861)
		(width 0.0889)
		(layer "In2.Cu")
		(net "M_C_CPU0_SB_CB<4>")
	)
	(arc
		(start 327.77811 -269.54861)
		(mid 327.60426 -269.598516)
		(end 327.427336 -269.560802)
		(width 0.0889)
		(layer "In2.Cu")
		(net "M_C_CPU0_SB_CB<4>")
	)
	(arc
		(start 327.368916 -269.527274)
		(mid 327.101588 -269.471986)
		(end 326.83958 -269.54861)
		(width 0.0889)
		(layer "In2.Cu")
		(net "M_C_CPU0_SB_CB<4>")
	)
	(arc
		(start 336.229706 -269.553436)
		(mid 336.046198 -269.59893)
		(end 335.863946 -269.54861)
		(width 0.0889)
		(layer "In2.Cu")
		(net "M_C_CPU0_SB_CB<4>")
	)
	(arc
		(start 330.598018 -269.54861)
		(mid 330.411074 -269.598865)
		(end 330.22413 -269.54861)
		(width 0.0889)
		(layer "In2.Cu")
		(net "M_C_CPU0_SB_CB<4>")
	)
	(arc
		(start 338.118196 -269.54861)
		(mid 337.935945 -269.59896)
		(end 337.752436 -269.553436)
		(width 0.0889)
		(layer "In2.Cu")
		(net "M_C_CPU0_SB_CB<4>")
	)
	(arc
		(start 342.381078 -269.51686)
		(mid 342.12587 -269.473383)
		(end 341.878158 -269.54861)
		(width 0.0889)
		(layer "In2.Cu")
		(net "M_C_CPU0_SB_CB<4>")
	)
	(arc
		(start 328.344022 -269.54861)
		(mid 328.061066 -269.472433)
		(end 327.77811 -269.54861)
		(width 0.0889)
		(layer "In2.Cu")
		(net "M_C_CPU0_SB_CB<4>")
	)
	(arc
		(start 337.744054 -269.54861)
		(mid 337.461098 -269.472433)
		(end 337.178142 -269.54861)
		(width 0.0889)
		(layer "In2.Cu")
		(net "M_C_CPU0_SB_CB<4>")
	)
	(arc
		(start 341.504016 -269.54861)
		(mid 341.22106 -269.472433)
		(end 340.938104 -269.54861)
		(width 0.0889)
		(layer "In2.Cu")
		(net "M_C_CPU0_SB_CB<4>")
	)
	(arc
		(start 328.709782 -269.553436)
		(mid 328.526274 -269.59893)
		(end 328.344022 -269.54861)
		(width 0.0889)
		(layer "In2.Cu")
		(net "M_C_CPU0_SB_CB<4>")
	)
	(arc
		(start 340.929722 -269.553436)
		(mid 340.746214 -269.59893)
		(end 340.563962 -269.54861)
		(width 0.0889)
		(layer "In2.Cu")
		(net "M_C_CPU0_SB_CB<4>")
	)
	(arc
		(start 333.044038 -269.54861)
		(mid 332.761082 -269.472433)
		(end 332.478126 -269.54861)
		(width 0.0889)
		(layer "In2.Cu")
		(net "M_C_CPU0_SB_CB<4>")
	)
	(arc
		(start 333.984092 -269.54861)
		(mid 333.701136 -269.472433)
		(end 333.41818 -269.54861)
		(width 0.0889)
		(layer "In2.Cu")
		(net "M_C_CPU0_SB_CB<4>")
	)
	(arc
		(start 326.83958 -269.54861)
		(mid 326.669573 -269.599175)
		(end 326.49541 -269.565628)
		(width 0.0889)
		(layer "In2.Cu")
		(net "M_C_CPU0_SB_CB<4>")
	)
	(arc
		(start 332.103984 -269.54861)
		(mid 331.821028 -269.472433)
		(end 331.538072 -269.54861)
		(width 0.0889)
		(layer "In2.Cu")
		(net "M_C_CPU0_SB_CB<4>")
	)
	(arc
		(start 340.563962 -269.54861)
		(mid 340.281006 -269.472433)
		(end 339.99805 -269.54861)
		(width 0.0889)
		(layer "In2.Cu")
		(net "M_C_CPU0_SB_CB<4>")
	)
	(arc
		(start 339.624162 -269.54861)
		(mid 339.341206 -269.472433)
		(end 339.05825 -269.54861)
		(width 0.0889)
		(layer "In2.Cu")
		(net "M_C_CPU0_SB_CB<4>")
	)
	(arc
		(start 338.684108 -269.54861)
		(mid 338.401152 -269.472433)
		(end 338.118196 -269.54861)
		(width 0.0889)
		(layer "In2.Cu")
		(net "M_C_CPU0_SB_CB<4>")
	)
	(arc
		(start 341.869776 -269.553436)
		(mid 341.686268 -269.59893)
		(end 341.504016 -269.54861)
		(width 0.0889)
		(layer "In2.Cu")
		(net "M_C_CPU0_SB_CB<4>")
	)
	(arc
		(start 333.41818 -269.54861)
		(mid 333.235929 -269.59896)
		(end 333.05242 -269.553436)
		(width 0.0889)
		(layer "In2.Cu")
		(net "M_C_CPU0_SB_CB<4>")
	)
	(arc
		(start 339.05825 -269.54861)
		(mid 338.875999 -269.59896)
		(end 338.69249 -269.553436)
		(width 0.0889)
		(layer "In2.Cu")
		(net "M_C_CPU0_SB_CB<4>")
	)
	(arc
		(start 332.469744 -269.553436)
		(mid 332.286236 -269.59893)
		(end 332.103984 -269.54861)
		(width 0.0889)
		(layer "In2.Cu")
		(net "M_C_CPU0_SB_CB<4>")
	)
	(arc
		(start 329.658218 -269.54861)
		(mid 329.475967 -269.59896)
		(end 329.292458 -269.553436)
		(width 0.0889)
		(layer "In2.Cu")
		(net "M_C_CPU0_SB_CB<4>")
	)
	(arc
		(start 334.358234 -269.54861)
		(mid 334.175983 -269.59896)
		(end 333.992474 -269.553436)
		(width 0.0889)
		(layer "In2.Cu")
		(net "M_C_CPU0_SB_CB<4>")
	)
	(arc
		(start 331.52969 -269.553436)
		(mid 331.346182 -269.59893)
		(end 331.16393 -269.54861)
		(width 0.0889)
		(layer "In2.Cu")
		(net "M_C_CPU0_SB_CB<4>")
	)
	(arc
		(start 329.284076 -269.54861)
		(mid 329.00112 -269.472433)
		(end 328.718164 -269.54861)
		(width 0.0889)
		(layer "In2.Cu")
		(net "M_C_CPU0_SB_CB<4>")
	)
	(arc
		(start 336.804 -269.54861)
		(mid 336.521044 -269.472433)
		(end 336.238088 -269.54861)
		(width 0.0889)
		(layer "In2.Cu")
		(net "M_C_CPU0_SB_CB<4>")
	)
	(arc
		(start 339.99805 -269.54861)
		(mid 339.811106 -269.598865)
		(end 339.624162 -269.54861)
		(width 0.0889)
		(layer "In2.Cu")
		(net "M_C_CPU0_SB_CB<4>")
	)
	(arc
		(start 335.298034 -269.54861)
		(mid 335.11109 -269.598865)
		(end 334.924146 -269.54861)
		(width 0.0889)
		(layer "In2.Cu")
		(net "M_C_CPU0_SB_CB<4>")
	)
	(arc
		(start 330.22413 -269.54861)
		(mid 329.941174 -269.472433)
		(end 329.658218 -269.54861)
		(width 0.0889)
		(layer "In2.Cu")
		(net "M_C_CPU0_SB_CB<4>")
	)
	(arc
		(start 337.16976 -269.553436)
		(mid 336.986252 -269.59893)
		(end 336.804 -269.54861)
		(width 0.0889)
		(layer "In2.Cu")
		(net "M_C_CPU0_SB_CB<4>")
	)
	(segment
		(start 344.03792 -273.820128)
		(end 343.571068 -274.086066)
		(width 0.10668)
		(layer "F.Cu")
		(net "M_C_CPU0_SB_CB<3>")
	)
	(segment
		(start 304.866802 -281.060144)
		(end 301.717202 -281.060144)
		(width 0.14478)
		(layer "In2.Cu")
		(net "M_C_CPU0_SB_CB<3>")
	)
	(segment
		(start 333.992474 -273.75866)
		(end 333.984092 -273.763486)
		(width 0.0889)
		(layer "In2.Cu")
		(net "M_C_CPU0_SB_CB<3>")
	)
	(segment
		(start 340.938104 -273.763486)
		(end 340.929722 -273.75866)
		(width 0.0889)
		(layer "In2.Cu")
		(net "M_C_CPU0_SB_CB<3>")
	)
	(segment
		(start 331.538072 -273.763486)
		(end 331.52969 -273.75866)
		(width 0.0889)
		(layer "In2.Cu")
		(net "M_C_CPU0_SB_CB<3>")
	)
	(segment
		(start 298.273724 -280.210006)
		(end 297.423586 -281.060144)
		(width 0.14478)
		(layer "In2.Cu")
		(net "M_C_CPU0_SB_CB<3>")
	)
	(segment
		(start 323.925184 -272.66392)
		(end 316.531244 -272.66392)
		(width 0.14478)
		(layer "In2.Cu")
		(net "M_C_CPU0_SB_CB<3>")
	)
	(segment
		(start 343.392506 -273.75866)
		(end 343.384124 -273.763486)
		(width 0.0889)
		(layer "In2.Cu")
		(net "M_C_CPU0_SB_CB<3>")
	)
	(segment
		(start 297.423586 -281.060144)
		(end 288.605214 -281.060144)
		(width 0.14478)
		(layer "In2.Cu")
		(net "M_C_CPU0_SB_CB<3>")
	)
	(segment
		(start 337.178142 -273.763486)
		(end 337.16976 -273.75866)
		(width 0.0889)
		(layer "In2.Cu")
		(net "M_C_CPU0_SB_CB<3>")
	)
	(segment
		(start 324.238112 -272.600928)
		(end 324.17512 -272.66392)
		(width 0.0889)
		(layer "In2.Cu")
		(net "M_C_CPU0_SB_CB<3>")
	)
	(segment
		(start 316.531244 -272.66392)
		(end 308.985158 -280.210006)
		(width 0.14478)
		(layer "In2.Cu")
		(net "M_C_CPU0_SB_CB<3>")
	)
	(segment
		(start 337.752436 -273.75866)
		(end 337.744054 -273.763486)
		(width 0.0889)
		(layer "In2.Cu")
		(net "M_C_CPU0_SB_CB<3>")
	)
	(segment
		(start 336.238088 -273.763486)
		(end 336.229706 -273.75866)
		(width 0.0889)
		(layer "In2.Cu")
		(net "M_C_CPU0_SB_CB<3>")
	)
	(segment
		(start 341.878158 -273.763486)
		(end 341.869776 -273.75866)
		(width 0.0889)
		(layer "In2.Cu")
		(net "M_C_CPU0_SB_CB<3>")
	)
	(segment
		(start 343.571068 -274.086066)
		(end 343.725246 -273.820636)
		(width 0.0889)
		(layer "In2.Cu")
		(net "M_C_CPU0_SB_CB<3>")
	)
	(segment
		(start 325.180198 -272.600928)
		(end 324.238112 -272.600928)
		(width 0.0889)
		(layer "In2.Cu")
		(net "M_C_CPU0_SB_CB<3>")
	)
	(segment
		(start 328.718164 -273.763486)
		(end 328.709782 -273.75866)
		(width 0.0889)
		(layer "In2.Cu")
		(net "M_C_CPU0_SB_CB<3>")
	)
	(segment
		(start 332.478126 -273.763486)
		(end 332.469744 -273.75866)
		(width 0.0889)
		(layer "In2.Cu")
		(net "M_C_CPU0_SB_CB<3>")
	)
	(segment
		(start 327.407778 -273.763486)
		(end 327.378314 -273.780758)
		(width 0.0889)
		(layer "In2.Cu")
		(net "M_C_CPU0_SB_CB<3>")
	)
	(segment
		(start 305.71694 -280.210006)
		(end 304.866802 -281.060144)
		(width 0.14478)
		(layer "In2.Cu")
		(net "M_C_CPU0_SB_CB<3>")
	)
	(segment
		(start 288.605214 -281.060144)
		(end 288.180018 -280.634948)
		(width 0.14478)
		(layer "In2.Cu")
		(net "M_C_CPU0_SB_CB<3>")
	)
	(segment
		(start 300.867064 -280.210006)
		(end 298.273724 -280.210006)
		(width 0.14478)
		(layer "In2.Cu")
		(net "M_C_CPU0_SB_CB<3>")
	)
	(segment
		(start 343.725246 -273.820636)
		(end 343.702894 -273.737324)
		(width 0.0889)
		(layer "In2.Cu")
		(net "M_C_CPU0_SB_CB<3>")
	)
	(segment
		(start 342.452452 -273.75866)
		(end 342.44407 -273.763486)
		(width 0.0889)
		(layer "In2.Cu")
		(net "M_C_CPU0_SB_CB<3>")
	)
	(segment
		(start 326.29856 -273.71929)
		(end 325.180198 -272.600928)
		(width 0.0889)
		(layer "In2.Cu")
		(net "M_C_CPU0_SB_CB<3>")
	)
	(segment
		(start 327.780142 -273.76374)
		(end 327.756774 -273.750278)
		(width 0.0889)
		(layer "In2.Cu")
		(net "M_C_CPU0_SB_CB<3>")
	)
	(segment
		(start 329.292458 -273.75866)
		(end 329.284076 -273.763486)
		(width 0.0889)
		(layer "In2.Cu")
		(net "M_C_CPU0_SB_CB<3>")
	)
	(segment
		(start 338.69249 -273.75866)
		(end 338.684108 -273.763486)
		(width 0.0889)
		(layer "In2.Cu")
		(net "M_C_CPU0_SB_CB<3>")
	)
	(segment
		(start 326.676766 -273.71929)
		(end 326.29856 -273.71929)
		(width 0.0889)
		(layer "In2.Cu")
		(net "M_C_CPU0_SB_CB<3>")
	)
	(segment
		(start 327.806304 -273.778726)
		(end 327.780142 -273.76374)
		(width 0.0889)
		(layer "In2.Cu")
		(net "M_C_CPU0_SB_CB<3>")
	)
	(segment
		(start 333.05242 -273.75866)
		(end 333.044038 -273.763486)
		(width 0.0889)
		(layer "In2.Cu")
		(net "M_C_CPU0_SB_CB<3>")
	)
	(segment
		(start 324.17512 -272.66392)
		(end 323.925184 -272.66392)
		(width 0.0889)
		(layer "In2.Cu")
		(net "M_C_CPU0_SB_CB<3>")
	)
	(segment
		(start 308.985158 -280.210006)
		(end 305.71694 -280.210006)
		(width 0.14478)
		(layer "In2.Cu")
		(net "M_C_CPU0_SB_CB<3>")
	)
	(segment
		(start 301.717202 -281.060144)
		(end 300.867064 -280.210006)
		(width 0.14478)
		(layer "In2.Cu")
		(net "M_C_CPU0_SB_CB<3>")
	)
	(arc
		(start 338.118196 -273.763486)
		(mid 337.935945 -273.713136)
		(end 337.752436 -273.75866)
		(width 0.0889)
		(layer "In2.Cu")
		(net "M_C_CPU0_SB_CB<3>")
	)
	(arc
		(start 341.869776 -273.75866)
		(mid 341.686268 -273.713166)
		(end 341.504016 -273.763486)
		(width 0.0889)
		(layer "In2.Cu")
		(net "M_C_CPU0_SB_CB<3>")
	)
	(arc
		(start 337.744054 -273.763486)
		(mid 337.461098 -273.839663)
		(end 337.178142 -273.763486)
		(width 0.0889)
		(layer "In2.Cu")
		(net "M_C_CPU0_SB_CB<3>")
	)
	(arc
		(start 338.684108 -273.763486)
		(mid 338.401152 -273.839663)
		(end 338.118196 -273.763486)
		(width 0.0889)
		(layer "In2.Cu")
		(net "M_C_CPU0_SB_CB<3>")
	)
	(arc
		(start 343.384124 -273.763486)
		(mid 343.101168 -273.839663)
		(end 342.818212 -273.763486)
		(width 0.0889)
		(layer "In2.Cu")
		(net "M_C_CPU0_SB_CB<3>")
	)
	(arc
		(start 331.16393 -273.763486)
		(mid 330.880974 -273.839663)
		(end 330.598018 -273.763486)
		(width 0.0889)
		(layer "In2.Cu")
		(net "M_C_CPU0_SB_CB<3>")
	)
	(arc
		(start 332.469744 -273.75866)
		(mid 332.286236 -273.713166)
		(end 332.103984 -273.763486)
		(width 0.0889)
		(layer "In2.Cu")
		(net "M_C_CPU0_SB_CB<3>")
	)
	(arc
		(start 328.344022 -273.763486)
		(mid 328.077092 -273.839435)
		(end 327.806304 -273.778726)
		(width 0.0889)
		(layer "In2.Cu")
		(net "M_C_CPU0_SB_CB<3>")
	)
	(arc
		(start 334.358234 -273.763486)
		(mid 334.175983 -273.713136)
		(end 333.992474 -273.75866)
		(width 0.0889)
		(layer "In2.Cu")
		(net "M_C_CPU0_SB_CB<3>")
	)
	(arc
		(start 328.709782 -273.75866)
		(mid 328.526274 -273.713166)
		(end 328.344022 -273.763486)
		(width 0.0889)
		(layer "In2.Cu")
		(net "M_C_CPU0_SB_CB<3>")
	)
	(arc
		(start 340.929722 -273.75866)
		(mid 340.746214 -273.713166)
		(end 340.563962 -273.763486)
		(width 0.0889)
		(layer "In2.Cu")
		(net "M_C_CPU0_SB_CB<3>")
	)
	(arc
		(start 336.804 -273.763486)
		(mid 336.521044 -273.839663)
		(end 336.238088 -273.763486)
		(width 0.0889)
		(layer "In2.Cu")
		(net "M_C_CPU0_SB_CB<3>")
	)
	(arc
		(start 336.229706 -273.75866)
		(mid 336.046198 -273.713166)
		(end 335.863946 -273.763486)
		(width 0.0889)
		(layer "In2.Cu")
		(net "M_C_CPU0_SB_CB<3>")
	)
	(arc
		(start 335.298034 -273.763486)
		(mid 335.11109 -273.713231)
		(end 334.924146 -273.763486)
		(width 0.0889)
		(layer "In2.Cu")
		(net "M_C_CPU0_SB_CB<3>")
	)
	(arc
		(start 333.984092 -273.763486)
		(mid 333.701136 -273.839663)
		(end 333.41818 -273.763486)
		(width 0.0889)
		(layer "In2.Cu")
		(net "M_C_CPU0_SB_CB<3>")
	)
	(arc
		(start 339.624162 -273.763486)
		(mid 339.341206 -273.839663)
		(end 339.05825 -273.763486)
		(width 0.0889)
		(layer "In2.Cu")
		(net "M_C_CPU0_SB_CB<3>")
	)
	(arc
		(start 337.16976 -273.75866)
		(mid 336.986252 -273.713166)
		(end 336.804 -273.763486)
		(width 0.0889)
		(layer "In2.Cu")
		(net "M_C_CPU0_SB_CB<3>")
	)
	(arc
		(start 329.658218 -273.763486)
		(mid 329.475967 -273.713136)
		(end 329.292458 -273.75866)
		(width 0.0889)
		(layer "In2.Cu")
		(net "M_C_CPU0_SB_CB<3>")
	)
	(arc
		(start 341.504016 -273.763486)
		(mid 341.22106 -273.839663)
		(end 340.938104 -273.763486)
		(width 0.0889)
		(layer "In2.Cu")
		(net "M_C_CPU0_SB_CB<3>")
	)
	(arc
		(start 335.863946 -273.763486)
		(mid 335.58099 -273.839663)
		(end 335.298034 -273.763486)
		(width 0.0889)
		(layer "In2.Cu")
		(net "M_C_CPU0_SB_CB<3>")
	)
	(arc
		(start 342.818212 -273.763486)
		(mid 342.635961 -273.713136)
		(end 342.452452 -273.75866)
		(width 0.0889)
		(layer "In2.Cu")
		(net "M_C_CPU0_SB_CB<3>")
	)
	(arc
		(start 340.563962 -273.763486)
		(mid 340.281006 -273.839663)
		(end 339.99805 -273.763486)
		(width 0.0889)
		(layer "In2.Cu")
		(net "M_C_CPU0_SB_CB<3>")
	)
	(arc
		(start 330.598018 -273.763486)
		(mid 330.411074 -273.713231)
		(end 330.22413 -273.763486)
		(width 0.0889)
		(layer "In2.Cu")
		(net "M_C_CPU0_SB_CB<3>")
	)
	(arc
		(start 333.41818 -273.763486)
		(mid 333.235929 -273.713136)
		(end 333.05242 -273.75866)
		(width 0.0889)
		(layer "In2.Cu")
		(net "M_C_CPU0_SB_CB<3>")
	)
	(arc
		(start 326.839834 -273.763486)
		(mid 326.761243 -273.730525)
		(end 326.676766 -273.71929)
		(width 0.0889)
		(layer "In2.Cu")
		(net "M_C_CPU0_SB_CB<3>")
	)
	(arc
		(start 339.05825 -273.763486)
		(mid 338.875999 -273.713136)
		(end 338.69249 -273.75866)
		(width 0.0889)
		(layer "In2.Cu")
		(net "M_C_CPU0_SB_CB<3>")
	)
	(arc
		(start 334.924146 -273.763486)
		(mid 334.64119 -273.839663)
		(end 334.358234 -273.763486)
		(width 0.0889)
		(layer "In2.Cu")
		(net "M_C_CPU0_SB_CB<3>")
	)
	(arc
		(start 332.103984 -273.763486)
		(mid 331.821028 -273.839663)
		(end 331.538072 -273.763486)
		(width 0.0889)
		(layer "In2.Cu")
		(net "M_C_CPU0_SB_CB<3>")
	)
	(arc
		(start 329.284076 -273.763486)
		(mid 329.00112 -273.839663)
		(end 328.718164 -273.763486)
		(width 0.0889)
		(layer "In2.Cu")
		(net "M_C_CPU0_SB_CB<3>")
	)
	(arc
		(start 343.702894 -273.737324)
		(mid 343.545384 -273.714126)
		(end 343.392506 -273.75866)
		(width 0.0889)
		(layer "In2.Cu")
		(net "M_C_CPU0_SB_CB<3>")
	)
	(arc
		(start 330.22413 -273.763486)
		(mid 329.941174 -273.839663)
		(end 329.658218 -273.763486)
		(width 0.0889)
		(layer "In2.Cu")
		(net "M_C_CPU0_SB_CB<3>")
	)
	(arc
		(start 327.756774 -273.750278)
		(mid 327.580632 -273.713486)
		(end 327.407778 -273.763486)
		(width 0.0889)
		(layer "In2.Cu")
		(net "M_C_CPU0_SB_CB<3>")
	)
	(arc
		(start 327.378314 -273.780758)
		(mid 327.106894 -273.840435)
		(end 326.839834 -273.763486)
		(width 0.0889)
		(layer "In2.Cu")
		(net "M_C_CPU0_SB_CB<3>")
	)
	(arc
		(start 331.52969 -273.75866)
		(mid 331.346182 -273.713166)
		(end 331.16393 -273.763486)
		(width 0.0889)
		(layer "In2.Cu")
		(net "M_C_CPU0_SB_CB<3>")
	)
	(arc
		(start 339.99805 -273.763486)
		(mid 339.811106 -273.713231)
		(end 339.624162 -273.763486)
		(width 0.0889)
		(layer "In2.Cu")
		(net "M_C_CPU0_SB_CB<3>")
	)
	(arc
		(start 333.044038 -273.763486)
		(mid 332.761082 -273.839663)
		(end 332.478126 -273.763486)
		(width 0.0889)
		(layer "In2.Cu")
		(net "M_C_CPU0_SB_CB<3>")
	)
	(arc
		(start 342.44407 -273.763486)
		(mid 342.161114 -273.839663)
		(end 341.878158 -273.763486)
		(width 0.0889)
		(layer "In2.Cu")
		(net "M_C_CPU0_SB_CB<3>")
	)
	(segment
		(start 342.627966 -273.010122)
		(end 342.161114 -273.27606)
		(width 0.10668)
		(layer "F.Cu")
		(net "M_C_CPU0_SB_CB<2>")
	)
	(segment
		(start 306.130452 -278.509984)
		(end 305.280314 -279.360122)
		(width 0.14478)
		(layer "In2.Cu")
		(net "M_C_CPU0_SB_CB<2>")
	)
	(segment
		(start 290.5379 -278.868124)
		(end 290.5379 -279.197308)
		(width 0.14478)
		(layer "In2.Cu")
		(net "M_C_CPU0_SB_CB<2>")
	)
	(segment
		(start 340.102444 -272.948654)
		(end 340.094062 -272.95348)
		(width 0.0889)
		(layer "In2.Cu")
		(net "M_C_CPU0_SB_CB<2>")
	)
	(segment
		(start 315.197236 -271.7546)
		(end 312.974736 -273.9771)
		(width 0.14478)
		(layer "In2.Cu")
		(net "M_C_CPU0_SB_CB<2>")
	)
	(segment
		(start 324.736714 -272.06575)
		(end 324.425564 -271.7546)
		(width 0.0889)
		(layer "In2.Cu")
		(net "M_C_CPU0_SB_CB<2>")
	)
	(segment
		(start 333.88808 -272.95348)
		(end 333.879698 -272.948654)
		(width 0.0889)
		(layer "In2.Cu")
		(net "M_C_CPU0_SB_CB<2>")
	)
	(segment
		(start 331.642466 -272.948654)
		(end 331.634084 -272.95348)
		(width 0.0889)
		(layer "In2.Cu")
		(net "M_C_CPU0_SB_CB<2>")
	)
	(segment
		(start 290.5379 -279.197308)
		(end 290.375086 -279.360122)
		(width 0.14478)
		(layer "In2.Cu")
		(net "M_C_CPU0_SB_CB<2>")
	)
	(segment
		(start 338.588096 -272.95348)
		(end 338.579714 -272.948654)
		(width 0.0889)
		(layer "In2.Cu")
		(net "M_C_CPU0_SB_CB<2>")
	)
	(segment
		(start 327.33488 -272.972022)
		(end 327.30313 -272.95348)
		(width 0.0889)
		(layer "In2.Cu")
		(net "M_C_CPU0_SB_CB<2>")
	)
	(segment
		(start 326.25157 -272.865596)
		(end 325.451724 -272.06575)
		(width 0.0889)
		(layer "In2.Cu")
		(net "M_C_CPU0_SB_CB<2>")
	)
	(segment
		(start 300.491652 -278.509984)
		(end 298.687236 -278.509984)
		(width 0.14478)
		(layer "In2.Cu")
		(net "M_C_CPU0_SB_CB<2>")
	)
	(segment
		(start 341.042498 -272.948654)
		(end 341.034116 -272.95348)
		(width 0.0889)
		(layer "In2.Cu")
		(net "M_C_CPU0_SB_CB<2>")
	)
	(segment
		(start 335.402428 -272.948654)
		(end 335.394046 -272.95348)
		(width 0.0889)
		(layer "In2.Cu")
		(net "M_C_CPU0_SB_CB<2>")
	)
	(segment
		(start 290.931346 -278.70531)
		(end 290.700714 -278.70531)
		(width 0.14478)
		(layer "In2.Cu")
		(net "M_C_CPU0_SB_CB<2>")
	)
	(segment
		(start 291.09416 -278.868124)
		(end 290.931346 -278.70531)
		(width 0.14478)
		(layer "In2.Cu")
		(net "M_C_CPU0_SB_CB<2>")
	)
	(segment
		(start 334.828134 -272.95348)
		(end 334.819752 -272.948654)
		(width 0.0889)
		(layer "In2.Cu")
		(net "M_C_CPU0_SB_CB<2>")
	)
	(segment
		(start 325.451724 -272.06575)
		(end 324.736714 -272.06575)
		(width 0.0889)
		(layer "In2.Cu")
		(net "M_C_CPU0_SB_CB<2>")
	)
	(segment
		(start 305.280314 -279.360122)
		(end 301.34179 -279.360122)
		(width 0.14478)
		(layer "In2.Cu")
		(net "M_C_CPU0_SB_CB<2>")
	)
	(segment
		(start 312.974736 -274.934172)
		(end 309.398924 -278.509984)
		(width 0.14478)
		(layer "In2.Cu")
		(net "M_C_CPU0_SB_CB<2>")
	)
	(segment
		(start 324.425564 -271.7546)
		(end 323.906134 -271.7546)
		(width 0.0889)
		(layer "In2.Cu")
		(net "M_C_CPU0_SB_CB<2>")
	)
	(segment
		(start 339.52815 -272.95348)
		(end 339.519768 -272.948654)
		(width 0.0889)
		(layer "In2.Cu")
		(net "M_C_CPU0_SB_CB<2>")
	)
	(segment
		(start 326.93102 -272.953734)
		(end 326.883776 -272.980912)
		(width 0.0889)
		(layer "In2.Cu")
		(net "M_C_CPU0_SB_CB<2>")
	)
	(segment
		(start 330.702412 -272.948654)
		(end 330.69403 -272.95348)
		(width 0.0889)
		(layer "In2.Cu")
		(net "M_C_CPU0_SB_CB<2>")
	)
	(segment
		(start 326.958452 -272.937986)
		(end 326.93102 -272.953734)
		(width 0.0889)
		(layer "In2.Cu")
		(net "M_C_CPU0_SB_CB<2>")
	)
	(segment
		(start 312.974736 -273.9771)
		(end 312.974736 -274.934172)
		(width 0.14478)
		(layer "In2.Cu")
		(net "M_C_CPU0_SB_CB<2>")
	)
	(segment
		(start 291.09416 -279.197308)
		(end 291.09416 -278.868124)
		(width 0.14478)
		(layer "In2.Cu")
		(net "M_C_CPU0_SB_CB<2>")
	)
	(segment
		(start 309.398924 -278.509984)
		(end 306.130452 -278.509984)
		(width 0.14478)
		(layer "In2.Cu")
		(net "M_C_CPU0_SB_CB<2>")
	)
	(segment
		(start 291.256974 -279.360122)
		(end 291.09416 -279.197308)
		(width 0.14478)
		(layer "In2.Cu")
		(net "M_C_CPU0_SB_CB<2>")
	)
	(segment
		(start 297.837098 -279.360122)
		(end 291.256974 -279.360122)
		(width 0.14478)
		(layer "In2.Cu")
		(net "M_C_CPU0_SB_CB<2>")
	)
	(segment
		(start 288.60496 -279.360122)
		(end 288.180018 -278.93518)
		(width 0.14478)
		(layer "In2.Cu")
		(net "M_C_CPU0_SB_CB<2>")
	)
	(segment
		(start 336.342482 -272.948654)
		(end 336.3341 -272.95348)
		(width 0.0889)
		(layer "In2.Cu")
		(net "M_C_CPU0_SB_CB<2>")
	)
	(segment
		(start 328.248264 -272.95348)
		(end 328.222102 -272.93824)
		(width 0.0889)
		(layer "In2.Cu")
		(net "M_C_CPU0_SB_CB<2>")
	)
	(segment
		(start 298.687236 -278.509984)
		(end 297.837098 -279.360122)
		(width 0.14478)
		(layer "In2.Cu")
		(net "M_C_CPU0_SB_CB<2>")
	)
	(segment
		(start 301.34179 -279.360122)
		(end 300.491652 -278.509984)
		(width 0.14478)
		(layer "In2.Cu")
		(net "M_C_CPU0_SB_CB<2>")
	)
	(segment
		(start 342.315038 -273.01063)
		(end 342.292686 -272.927318)
		(width 0.0889)
		(layer "In2.Cu")
		(net "M_C_CPU0_SB_CB<2>")
	)
	(segment
		(start 290.700714 -278.70531)
		(end 290.5379 -278.868124)
		(width 0.14478)
		(layer "In2.Cu")
		(net "M_C_CPU0_SB_CB<2>")
	)
	(segment
		(start 323.906134 -271.7546)
		(end 315.197236 -271.7546)
		(width 0.14478)
		(layer "In2.Cu")
		(net "M_C_CPU0_SB_CB<2>")
	)
	(segment
		(start 290.375086 -279.360122)
		(end 288.60496 -279.360122)
		(width 0.14478)
		(layer "In2.Cu")
		(net "M_C_CPU0_SB_CB<2>")
	)
	(segment
		(start 342.161114 -273.27606)
		(end 342.315038 -273.01063)
		(width 0.0889)
		(layer "In2.Cu")
		(net "M_C_CPU0_SB_CB<2>")
	)
	(segment
		(start 330.128118 -272.95348)
		(end 330.119736 -272.948654)
		(width 0.0889)
		(layer "In2.Cu")
		(net "M_C_CPU0_SB_CB<2>")
	)
	(arc
		(start 332.574138 -272.95348)
		(mid 332.291182 -273.029657)
		(end 332.008226 -272.95348)
		(width 0.0889)
		(layer "In2.Cu")
		(net "M_C_CPU0_SB_CB<2>")
	)
	(arc
		(start 329.753976 -272.95348)
		(mid 329.47102 -273.029657)
		(end 329.188064 -272.95348)
		(width 0.0889)
		(layer "In2.Cu")
		(net "M_C_CPU0_SB_CB<2>")
	)
	(arc
		(start 336.3341 -272.95348)
		(mid 336.051144 -273.029657)
		(end 335.768188 -272.95348)
		(width 0.0889)
		(layer "In2.Cu")
		(net "M_C_CPU0_SB_CB<2>")
	)
	(arc
		(start 331.634084 -272.95348)
		(mid 331.351128 -273.029657)
		(end 331.068172 -272.95348)
		(width 0.0889)
		(layer "In2.Cu")
		(net "M_C_CPU0_SB_CB<2>")
	)
	(arc
		(start 334.819752 -272.948654)
		(mid 334.636244 -272.90316)
		(end 334.453992 -272.95348)
		(width 0.0889)
		(layer "In2.Cu")
		(net "M_C_CPU0_SB_CB<2>")
	)
	(arc
		(start 335.768188 -272.95348)
		(mid 335.585937 -272.90313)
		(end 335.402428 -272.948654)
		(width 0.0889)
		(layer "In2.Cu")
		(net "M_C_CPU0_SB_CB<2>")
	)
	(arc
		(start 327.871836 -272.953226)
		(mid 327.605747 -273.030503)
		(end 327.33488 -272.972022)
		(width 0.0889)
		(layer "In2.Cu")
		(net "M_C_CPU0_SB_CB<2>")
	)
	(arc
		(start 332.008226 -272.95348)
		(mid 331.825975 -272.90313)
		(end 331.642466 -272.948654)
		(width 0.0889)
		(layer "In2.Cu")
		(net "M_C_CPU0_SB_CB<2>")
	)
	(arc
		(start 331.068172 -272.95348)
		(mid 330.885921 -272.90313)
		(end 330.702412 -272.948654)
		(width 0.0889)
		(layer "In2.Cu")
		(net "M_C_CPU0_SB_CB<2>")
	)
	(arc
		(start 330.69403 -272.95348)
		(mid 330.411074 -273.029657)
		(end 330.128118 -272.95348)
		(width 0.0889)
		(layer "In2.Cu")
		(net "M_C_CPU0_SB_CB<2>")
	)
	(arc
		(start 341.408258 -272.95348)
		(mid 341.226007 -272.90313)
		(end 341.042498 -272.948654)
		(width 0.0889)
		(layer "In2.Cu")
		(net "M_C_CPU0_SB_CB<2>")
	)
	(arc
		(start 337.274154 -272.95348)
		(mid 336.991198 -273.029657)
		(end 336.708242 -272.95348)
		(width 0.0889)
		(layer "In2.Cu")
		(net "M_C_CPU0_SB_CB<2>")
	)
	(arc
		(start 339.154008 -272.95348)
		(mid 338.871052 -273.029657)
		(end 338.588096 -272.95348)
		(width 0.0889)
		(layer "In2.Cu")
		(net "M_C_CPU0_SB_CB<2>")
	)
	(arc
		(start 326.365108 -272.953226)
		(mid 326.305556 -272.913018)
		(end 326.25157 -272.865596)
		(width 0.0889)
		(layer "In2.Cu")
		(net "M_C_CPU0_SB_CB<2>")
	)
	(arc
		(start 340.468204 -272.95348)
		(mid 340.285953 -272.90313)
		(end 340.102444 -272.948654)
		(width 0.0889)
		(layer "In2.Cu")
		(net "M_C_CPU0_SB_CB<2>")
	)
	(arc
		(start 326.883776 -272.980912)
		(mid 326.621062 -273.030242)
		(end 326.365108 -272.953226)
		(width 0.0889)
		(layer "In2.Cu")
		(net "M_C_CPU0_SB_CB<2>")
	)
	(arc
		(start 337.648042 -272.95348)
		(mid 337.461098 -272.903225)
		(end 337.274154 -272.95348)
		(width 0.0889)
		(layer "In2.Cu")
		(net "M_C_CPU0_SB_CB<2>")
	)
	(arc
		(start 328.222102 -272.93824)
		(mid 328.045101 -272.902162)
		(end 327.871836 -272.953226)
		(width 0.0889)
		(layer "In2.Cu")
		(net "M_C_CPU0_SB_CB<2>")
	)
	(arc
		(start 335.394046 -272.95348)
		(mid 335.11109 -273.029657)
		(end 334.828134 -272.95348)
		(width 0.0889)
		(layer "In2.Cu")
		(net "M_C_CPU0_SB_CB<2>")
	)
	(arc
		(start 332.948026 -272.95348)
		(mid 332.761082 -272.903225)
		(end 332.574138 -272.95348)
		(width 0.0889)
		(layer "In2.Cu")
		(net "M_C_CPU0_SB_CB<2>")
	)
	(arc
		(start 341.034116 -272.95348)
		(mid 340.75116 -273.029657)
		(end 340.468204 -272.95348)
		(width 0.0889)
		(layer "In2.Cu")
		(net "M_C_CPU0_SB_CB<2>")
	)
	(arc
		(start 333.513938 -272.95348)
		(mid 333.230982 -273.029657)
		(end 332.948026 -272.95348)
		(width 0.0889)
		(layer "In2.Cu")
		(net "M_C_CPU0_SB_CB<2>")
	)
	(arc
		(start 341.97417 -272.95348)
		(mid 341.691214 -273.029657)
		(end 341.408258 -272.95348)
		(width 0.0889)
		(layer "In2.Cu")
		(net "M_C_CPU0_SB_CB<2>")
	)
	(arc
		(start 338.213954 -272.95348)
		(mid 337.930998 -273.029657)
		(end 337.648042 -272.95348)
		(width 0.0889)
		(layer "In2.Cu")
		(net "M_C_CPU0_SB_CB<2>")
	)
	(arc
		(start 330.119736 -272.948654)
		(mid 329.936228 -272.90316)
		(end 329.753976 -272.95348)
		(width 0.0889)
		(layer "In2.Cu")
		(net "M_C_CPU0_SB_CB<2>")
	)
	(arc
		(start 338.579714 -272.948654)
		(mid 338.396206 -272.90316)
		(end 338.213954 -272.95348)
		(width 0.0889)
		(layer "In2.Cu")
		(net "M_C_CPU0_SB_CB<2>")
	)
	(arc
		(start 329.188064 -272.95348)
		(mid 329.00112 -272.903225)
		(end 328.814176 -272.95348)
		(width 0.0889)
		(layer "In2.Cu")
		(net "M_C_CPU0_SB_CB<2>")
	)
	(arc
		(start 340.094062 -272.95348)
		(mid 339.811106 -273.029657)
		(end 339.52815 -272.95348)
		(width 0.0889)
		(layer "In2.Cu")
		(net "M_C_CPU0_SB_CB<2>")
	)
	(arc
		(start 328.814176 -272.95348)
		(mid 328.53122 -273.029657)
		(end 328.248264 -272.95348)
		(width 0.0889)
		(layer "In2.Cu")
		(net "M_C_CPU0_SB_CB<2>")
	)
	(arc
		(start 336.708242 -272.95348)
		(mid 336.525991 -272.90313)
		(end 336.342482 -272.948654)
		(width 0.0889)
		(layer "In2.Cu")
		(net "M_C_CPU0_SB_CB<2>")
	)
	(arc
		(start 342.292686 -272.927318)
		(mid 342.130497 -272.904583)
		(end 341.97417 -272.95348)
		(width 0.0889)
		(layer "In2.Cu")
		(net "M_C_CPU0_SB_CB<2>")
	)
	(arc
		(start 339.519768 -272.948654)
		(mid 339.33626 -272.90316)
		(end 339.154008 -272.95348)
		(width 0.0889)
		(layer "In2.Cu")
		(net "M_C_CPU0_SB_CB<2>")
	)
	(arc
		(start 334.453992 -272.95348)
		(mid 334.171036 -273.029657)
		(end 333.88808 -272.95348)
		(width 0.0889)
		(layer "In2.Cu")
		(net "M_C_CPU0_SB_CB<2>")
	)
	(arc
		(start 333.879698 -272.948654)
		(mid 333.69619 -272.90316)
		(end 333.513938 -272.95348)
		(width 0.0889)
		(layer "In2.Cu")
		(net "M_C_CPU0_SB_CB<2>")
	)
	(arc
		(start 327.30313 -272.95348)
		(mid 327.132689 -272.903474)
		(end 326.958452 -272.937986)
		(width 0.0889)
		(layer "In2.Cu")
		(net "M_C_CPU0_SB_CB<2>")
	)
	(segment
		(start 344.508074 -273.010122)
		(end 344.041222 -273.27606)
		(width 0.10668)
		(layer "F.Cu")
		(net "M_C_CPU0_SB_CB<1>")
	)
	(segment
		(start 294.45458 -279.82291)
		(end 294.223948 -279.82291)
		(width 0.14478)
		(layer "In2.Cu")
		(net "M_C_CPU0_SB_CB<1>")
	)
	(segment
		(start 315.00318 -272.591784)
		(end 315.00318 -272.821908)
		(width 0.14478)
		(layer "In2.Cu")
		(net "M_C_CPU0_SB_CB<1>")
	)
	(segment
		(start 326.651112 -273.51609)
		(end 326.46874 -273.51609)
		(width 0.0889)
		(layer "In2.Cu")
		(net "M_C_CPU0_SB_CB<1>")
	)
	(segment
		(start 327.900538 -273.61261)
		(end 327.875646 -273.598386)
		(width 0.0889)
		(layer "In2.Cu")
		(net "M_C_CPU0_SB_CB<1>")
	)
	(segment
		(start 334.828134 -273.59864)
		(end 334.819752 -273.603466)
		(width 0.0889)
		(layer "In2.Cu")
		(net "M_C_CPU0_SB_CB<1>")
	)
	(segment
		(start 314.071254 -274.250658)
		(end 313.822842 -274.002246)
		(width 0.14478)
		(layer "In2.Cu")
		(net "M_C_CPU0_SB_CB<1>")
	)
	(segment
		(start 326.9361 -273.59864)
		(end 326.919082 -273.588734)
		(width 0.0889)
		(layer "In2.Cu")
		(net "M_C_CPU0_SB_CB<1>")
	)
	(segment
		(start 343.887044 -273.54149)
		(end 343.790778 -273.56689)
		(width 0.0889)
		(layer "In2.Cu")
		(net "M_C_CPU0_SB_CB<1>")
	)
	(segment
		(start 331.642466 -273.603466)
		(end 331.634084 -273.59864)
		(width 0.0889)
		(layer "In2.Cu")
		(net "M_C_CPU0_SB_CB<1>")
	)
	(segment
		(start 313.677808 -274.874228)
		(end 309.192168 -279.359868)
		(width 0.14478)
		(layer "In2.Cu")
		(net "M_C_CPU0_SB_CB<1>")
	)
	(segment
		(start 298.48048 -279.359868)
		(end 297.630342 -280.210006)
		(width 0.14478)
		(layer "In2.Cu")
		(net "M_C_CPU0_SB_CB<1>")
	)
	(segment
		(start 341.042498 -273.603466)
		(end 341.034116 -273.59864)
		(width 0.0889)
		(layer "In2.Cu")
		(net "M_C_CPU0_SB_CB<1>")
	)
	(segment
		(start 316.342776 -272.20926)
		(end 315.875162 -272.676874)
		(width 0.14478)
		(layer "In2.Cu")
		(net "M_C_CPU0_SB_CB<1>")
	)
	(segment
		(start 326.46874 -273.51609)
		(end 325.32066 -272.36801)
		(width 0.0889)
		(layer "In2.Cu")
		(net "M_C_CPU0_SB_CB<1>")
	)
	(segment
		(start 333.88808 -273.59864)
		(end 333.879698 -273.603466)
		(width 0.0889)
		(layer "In2.Cu")
		(net "M_C_CPU0_SB_CB<1>")
	)
	(segment
		(start 292.705028 -280.210006)
		(end 292.280086 -279.785064)
		(width 0.14478)
		(layer "In2.Cu")
		(net "M_C_CPU0_SB_CB<1>")
	)
	(segment
		(start 314.609734 -273.215354)
		(end 314.37961 -273.215354)
		(width 0.14478)
		(layer "In2.Cu")
		(net "M_C_CPU0_SB_CB<1>")
	)
	(segment
		(start 313.429396 -274.395692)
		(end 313.677808 -274.644104)
		(width 0.14478)
		(layer "In2.Cu")
		(net "M_C_CPU0_SB_CB<1>")
	)
	(segment
		(start 313.592718 -274.002246)
		(end 313.429396 -274.165568)
		(width 0.14478)
		(layer "In2.Cu")
		(net "M_C_CPU0_SB_CB<1>")
	)
	(segment
		(start 315.396626 -272.428462)
		(end 315.166502 -272.428462)
		(width 0.14478)
		(layer "In2.Cu")
		(net "M_C_CPU0_SB_CB<1>")
	)
	(segment
		(start 339.52815 -273.59864)
		(end 339.519768 -273.603466)
		(width 0.0889)
		(layer "In2.Cu")
		(net "M_C_CPU0_SB_CB<1>")
	)
	(segment
		(start 343.288112 -273.59864)
		(end 343.27973 -273.603466)
		(width 0.0889)
		(layer "In2.Cu")
		(net "M_C_CPU0_SB_CB<1>")
	)
	(segment
		(start 315.251592 -273.300444)
		(end 315.08827 -273.463766)
		(width 0.14478)
		(layer "In2.Cu")
		(net "M_C_CPU0_SB_CB<1>")
	)
	(segment
		(start 314.858146 -273.463766)
		(end 314.609734 -273.215354)
		(width 0.14478)
		(layer "In2.Cu")
		(net "M_C_CPU0_SB_CB<1>")
	)
	(segment
		(start 336.342482 -273.603466)
		(end 336.3341 -273.59864)
		(width 0.0889)
		(layer "In2.Cu")
		(net "M_C_CPU0_SB_CB<1>")
	)
	(segment
		(start 324.500494 -272.36801)
		(end 324.341744 -272.20926)
		(width 0.0889)
		(layer "In2.Cu")
		(net "M_C_CPU0_SB_CB<1>")
	)
	(segment
		(start 315.251592 -273.07032)
		(end 315.251592 -273.300444)
		(width 0.14478)
		(layer "In2.Cu")
		(net "M_C_CPU0_SB_CB<1>")
	)
	(segment
		(start 313.429396 -274.165568)
		(end 313.429396 -274.395692)
		(width 0.14478)
		(layer "In2.Cu")
		(net "M_C_CPU0_SB_CB<1>")
	)
	(segment
		(start 324.341744 -272.20926)
		(end 323.889624 -272.20926)
		(width 0.0889)
		(layer "In2.Cu")
		(net "M_C_CPU0_SB_CB<1>")
	)
	(segment
		(start 314.4647 -274.087336)
		(end 314.301378 -274.250658)
		(width 0.14478)
		(layer "In2.Cu")
		(net "M_C_CPU0_SB_CB<1>")
	)
	(segment
		(start 305.923696 -279.359868)
		(end 305.073558 -280.210006)
		(width 0.14478)
		(layer "In2.Cu")
		(net "M_C_CPU0_SB_CB<1>")
	)
	(segment
		(start 315.645038 -272.676874)
		(end 315.396626 -272.428462)
		(width 0.14478)
		(layer "In2.Cu")
		(net "M_C_CPU0_SB_CB<1>")
	)
	(segment
		(start 327.311766 -273.59864)
		(end 327.289414 -273.611594)
		(width 0.0889)
		(layer "In2.Cu")
		(net "M_C_CPU0_SB_CB<1>")
	)
	(segment
		(start 340.102444 -273.603466)
		(end 340.094062 -273.59864)
		(width 0.0889)
		(layer "In2.Cu")
		(net "M_C_CPU0_SB_CB<1>")
	)
	(segment
		(start 314.301378 -274.250658)
		(end 314.071254 -274.250658)
		(width 0.14478)
		(layer "In2.Cu")
		(net "M_C_CPU0_SB_CB<1>")
	)
	(segment
		(start 335.402428 -273.603466)
		(end 335.394046 -273.59864)
		(width 0.0889)
		(layer "In2.Cu")
		(net "M_C_CPU0_SB_CB<1>")
	)
	(segment
		(start 330.128118 -273.59864)
		(end 330.119736 -273.603466)
		(width 0.0889)
		(layer "In2.Cu")
		(net "M_C_CPU0_SB_CB<1>")
	)
	(segment
		(start 314.216288 -273.378676)
		(end 314.216288 -273.6088)
		(width 0.14478)
		(layer "In2.Cu")
		(net "M_C_CPU0_SB_CB<1>")
	)
	(segment
		(start 301.555658 -280.210006)
		(end 300.70552 -279.359868)
		(width 0.14478)
		(layer "In2.Cu")
		(net "M_C_CPU0_SB_CB<1>")
	)
	(segment
		(start 300.70552 -279.359868)
		(end 298.48048 -279.359868)
		(width 0.14478)
		(layer "In2.Cu")
		(net "M_C_CPU0_SB_CB<1>")
	)
	(segment
		(start 314.216288 -273.6088)
		(end 314.4647 -273.857212)
		(width 0.14478)
		(layer "In2.Cu")
		(net "M_C_CPU0_SB_CB<1>")
	)
	(segment
		(start 293.292784 -280.210006)
		(end 292.705028 -280.210006)
		(width 0.14478)
		(layer "In2.Cu")
		(net "M_C_CPU0_SB_CB<1>")
	)
	(segment
		(start 293.89832 -280.58491)
		(end 293.667688 -280.58491)
		(width 0.14478)
		(layer "In2.Cu")
		(net "M_C_CPU0_SB_CB<1>")
	)
	(segment
		(start 315.166502 -272.428462)
		(end 315.00318 -272.591784)
		(width 0.14478)
		(layer "In2.Cu")
		(net "M_C_CPU0_SB_CB<1>")
	)
	(segment
		(start 315.00318 -272.821908)
		(end 315.251592 -273.07032)
		(width 0.14478)
		(layer "In2.Cu")
		(net "M_C_CPU0_SB_CB<1>")
	)
	(segment
		(start 330.702412 -273.603466)
		(end 330.69403 -273.59864)
		(width 0.0889)
		(layer "In2.Cu")
		(net "M_C_CPU0_SB_CB<1>")
	)
	(segment
		(start 294.061134 -280.422096)
		(end 293.89832 -280.58491)
		(width 0.14478)
		(layer "In2.Cu")
		(net "M_C_CPU0_SB_CB<1>")
	)
	(segment
		(start 309.192168 -279.359868)
		(end 305.923696 -279.359868)
		(width 0.14478)
		(layer "In2.Cu")
		(net "M_C_CPU0_SB_CB<1>")
	)
	(segment
		(start 294.223948 -279.82291)
		(end 294.061134 -279.985724)
		(width 0.14478)
		(layer "In2.Cu")
		(net "M_C_CPU0_SB_CB<1>")
	)
	(segment
		(start 314.4647 -273.857212)
		(end 314.4647 -274.087336)
		(width 0.14478)
		(layer "In2.Cu")
		(net "M_C_CPU0_SB_CB<1>")
	)
	(segment
		(start 313.677808 -274.644104)
		(end 313.677808 -274.874228)
		(width 0.14478)
		(layer "In2.Cu")
		(net "M_C_CPU0_SB_CB<1>")
	)
	(segment
		(start 325.32066 -272.36801)
		(end 324.500494 -272.36801)
		(width 0.0889)
		(layer "In2.Cu")
		(net "M_C_CPU0_SB_CB<1>")
	)
	(segment
		(start 338.588096 -273.59864)
		(end 338.579714 -273.603466)
		(width 0.0889)
		(layer "In2.Cu")
		(net "M_C_CPU0_SB_CB<1>")
	)
	(segment
		(start 313.822842 -274.002246)
		(end 313.592718 -274.002246)
		(width 0.14478)
		(layer "In2.Cu")
		(net "M_C_CPU0_SB_CB<1>")
	)
	(segment
		(start 315.08827 -273.463766)
		(end 314.858146 -273.463766)
		(width 0.14478)
		(layer "In2.Cu")
		(net "M_C_CPU0_SB_CB<1>")
	)
	(segment
		(start 305.073558 -280.210006)
		(end 301.555658 -280.210006)
		(width 0.14478)
		(layer "In2.Cu")
		(net "M_C_CPU0_SB_CB<1>")
	)
	(segment
		(start 327.875646 -273.598386)
		(end 327.849484 -273.5834)
		(width 0.0889)
		(layer "In2.Cu")
		(net "M_C_CPU0_SB_CB<1>")
	)
	(segment
		(start 314.37961 -273.215354)
		(end 314.216288 -273.378676)
		(width 0.14478)
		(layer "In2.Cu")
		(net "M_C_CPU0_SB_CB<1>")
	)
	(segment
		(start 344.041222 -273.27606)
		(end 343.887044 -273.54149)
		(width 0.0889)
		(layer "In2.Cu")
		(net "M_C_CPU0_SB_CB<1>")
	)
	(segment
		(start 315.875162 -272.676874)
		(end 315.645038 -272.676874)
		(width 0.14478)
		(layer "In2.Cu")
		(net "M_C_CPU0_SB_CB<1>")
	)
	(segment
		(start 294.061134 -279.985724)
		(end 294.061134 -280.422096)
		(width 0.14478)
		(layer "In2.Cu")
		(net "M_C_CPU0_SB_CB<1>")
	)
	(segment
		(start 297.630342 -280.210006)
		(end 294.841676 -280.210006)
		(width 0.14478)
		(layer "In2.Cu")
		(net "M_C_CPU0_SB_CB<1>")
	)
	(segment
		(start 323.889624 -272.20926)
		(end 316.342776 -272.20926)
		(width 0.14478)
		(layer "In2.Cu")
		(net "M_C_CPU0_SB_CB<1>")
	)
	(segment
		(start 294.841676 -280.210006)
		(end 294.45458 -279.82291)
		(width 0.14478)
		(layer "In2.Cu")
		(net "M_C_CPU0_SB_CB<1>")
	)
	(segment
		(start 293.667688 -280.58491)
		(end 293.292784 -280.210006)
		(width 0.14478)
		(layer "In2.Cu")
		(net "M_C_CPU0_SB_CB<1>")
	)
	(arc
		(start 327.849484 -273.5834)
		(mid 327.578698 -273.522754)
		(end 327.311766 -273.59864)
		(width 0.0889)
		(layer "In2.Cu")
		(net "M_C_CPU0_SB_CB<1>")
	)
	(arc
		(start 335.768188 -273.59864)
		(mid 335.585937 -273.64899)
		(end 335.402428 -273.603466)
		(width 0.0889)
		(layer "In2.Cu")
		(net "M_C_CPU0_SB_CB<1>")
	)
	(arc
		(start 335.394046 -273.59864)
		(mid 335.11109 -273.522463)
		(end 334.828134 -273.59864)
		(width 0.0889)
		(layer "In2.Cu")
		(net "M_C_CPU0_SB_CB<1>")
	)
	(arc
		(start 341.034116 -273.59864)
		(mid 340.75116 -273.522463)
		(end 340.468204 -273.59864)
		(width 0.0889)
		(layer "In2.Cu")
		(net "M_C_CPU0_SB_CB<1>")
	)
	(arc
		(start 333.879698 -273.603466)
		(mid 333.69619 -273.64896)
		(end 333.513938 -273.59864)
		(width 0.0889)
		(layer "In2.Cu")
		(net "M_C_CPU0_SB_CB<1>")
	)
	(arc
		(start 340.468204 -273.59864)
		(mid 340.285953 -273.64899)
		(end 340.102444 -273.603466)
		(width 0.0889)
		(layer "In2.Cu")
		(net "M_C_CPU0_SB_CB<1>")
	)
	(arc
		(start 333.513938 -273.59864)
		(mid 333.230982 -273.522463)
		(end 332.948026 -273.59864)
		(width 0.0889)
		(layer "In2.Cu")
		(net "M_C_CPU0_SB_CB<1>")
	)
	(arc
		(start 336.3341 -273.59864)
		(mid 336.051144 -273.522463)
		(end 335.768188 -273.59864)
		(width 0.0889)
		(layer "In2.Cu")
		(net "M_C_CPU0_SB_CB<1>")
	)
	(arc
		(start 328.248264 -273.59864)
		(mid 328.076121 -273.648718)
		(end 327.900538 -273.61261)
		(width 0.0889)
		(layer "In2.Cu")
		(net "M_C_CPU0_SB_CB<1>")
	)
	(arc
		(start 342.91397 -273.59864)
		(mid 342.631014 -273.522463)
		(end 342.348058 -273.59864)
		(width 0.0889)
		(layer "In2.Cu")
		(net "M_C_CPU0_SB_CB<1>")
	)
	(arc
		(start 337.274154 -273.59864)
		(mid 336.991198 -273.522463)
		(end 336.708242 -273.59864)
		(width 0.0889)
		(layer "In2.Cu")
		(net "M_C_CPU0_SB_CB<1>")
	)
	(arc
		(start 332.948026 -273.59864)
		(mid 332.761082 -273.648895)
		(end 332.574138 -273.59864)
		(width 0.0889)
		(layer "In2.Cu")
		(net "M_C_CPU0_SB_CB<1>")
	)
	(arc
		(start 338.579714 -273.603466)
		(mid 338.396206 -273.64896)
		(end 338.213954 -273.59864)
		(width 0.0889)
		(layer "In2.Cu")
		(net "M_C_CPU0_SB_CB<1>")
	)
	(arc
		(start 342.348058 -273.59864)
		(mid 342.161114 -273.648895)
		(end 341.97417 -273.59864)
		(width 0.0889)
		(layer "In2.Cu")
		(net "M_C_CPU0_SB_CB<1>")
	)
	(arc
		(start 326.919082 -273.588734)
		(mid 326.789928 -273.534602)
		(end 326.651112 -273.51609)
		(width 0.0889)
		(layer "In2.Cu")
		(net "M_C_CPU0_SB_CB<1>")
	)
	(arc
		(start 337.648042 -273.59864)
		(mid 337.461098 -273.648895)
		(end 337.274154 -273.59864)
		(width 0.0889)
		(layer "In2.Cu")
		(net "M_C_CPU0_SB_CB<1>")
	)
	(arc
		(start 336.708242 -273.59864)
		(mid 336.525991 -273.64899)
		(end 336.342482 -273.603466)
		(width 0.0889)
		(layer "In2.Cu")
		(net "M_C_CPU0_SB_CB<1>")
	)
	(arc
		(start 341.97417 -273.59864)
		(mid 341.691214 -273.522463)
		(end 341.408258 -273.59864)
		(width 0.0889)
		(layer "In2.Cu")
		(net "M_C_CPU0_SB_CB<1>")
	)
	(arc
		(start 343.27973 -273.603466)
		(mid 343.096222 -273.64896)
		(end 342.91397 -273.59864)
		(width 0.0889)
		(layer "In2.Cu")
		(net "M_C_CPU0_SB_CB<1>")
	)
	(arc
		(start 327.289414 -273.611594)
		(mid 327.111128 -273.649538)
		(end 326.9361 -273.59864)
		(width 0.0889)
		(layer "In2.Cu")
		(net "M_C_CPU0_SB_CB<1>")
	)
	(arc
		(start 339.519768 -273.603466)
		(mid 339.33626 -273.64896)
		(end 339.154008 -273.59864)
		(width 0.0889)
		(layer "In2.Cu")
		(net "M_C_CPU0_SB_CB<1>")
	)
	(arc
		(start 330.69403 -273.59864)
		(mid 330.411074 -273.522463)
		(end 330.128118 -273.59864)
		(width 0.0889)
		(layer "In2.Cu")
		(net "M_C_CPU0_SB_CB<1>")
	)
	(arc
		(start 331.634084 -273.59864)
		(mid 331.351128 -273.522463)
		(end 331.068172 -273.59864)
		(width 0.0889)
		(layer "In2.Cu")
		(net "M_C_CPU0_SB_CB<1>")
	)
	(arc
		(start 332.008226 -273.59864)
		(mid 331.825975 -273.64899)
		(end 331.642466 -273.603466)
		(width 0.0889)
		(layer "In2.Cu")
		(net "M_C_CPU0_SB_CB<1>")
	)
	(arc
		(start 334.819752 -273.603466)
		(mid 334.636244 -273.64896)
		(end 334.453992 -273.59864)
		(width 0.0889)
		(layer "In2.Cu")
		(net "M_C_CPU0_SB_CB<1>")
	)
	(arc
		(start 332.574138 -273.59864)
		(mid 332.291182 -273.522463)
		(end 332.008226 -273.59864)
		(width 0.0889)
		(layer "In2.Cu")
		(net "M_C_CPU0_SB_CB<1>")
	)
	(arc
		(start 341.408258 -273.59864)
		(mid 341.226007 -273.64899)
		(end 341.042498 -273.603466)
		(width 0.0889)
		(layer "In2.Cu")
		(net "M_C_CPU0_SB_CB<1>")
	)
	(arc
		(start 340.094062 -273.59864)
		(mid 339.811106 -273.522463)
		(end 339.52815 -273.59864)
		(width 0.0889)
		(layer "In2.Cu")
		(net "M_C_CPU0_SB_CB<1>")
	)
	(arc
		(start 331.068172 -273.59864)
		(mid 330.885921 -273.64899)
		(end 330.702412 -273.603466)
		(width 0.0889)
		(layer "In2.Cu")
		(net "M_C_CPU0_SB_CB<1>")
	)
	(arc
		(start 330.119736 -273.603466)
		(mid 329.936228 -273.64896)
		(end 329.753976 -273.59864)
		(width 0.0889)
		(layer "In2.Cu")
		(net "M_C_CPU0_SB_CB<1>")
	)
	(arc
		(start 343.790778 -273.56689)
		(mid 343.535713 -273.523539)
		(end 343.288112 -273.59864)
		(width 0.0889)
		(layer "In2.Cu")
		(net "M_C_CPU0_SB_CB<1>")
	)
	(arc
		(start 334.453992 -273.59864)
		(mid 334.171036 -273.522463)
		(end 333.88808 -273.59864)
		(width 0.0889)
		(layer "In2.Cu")
		(net "M_C_CPU0_SB_CB<1>")
	)
	(arc
		(start 339.154008 -273.59864)
		(mid 338.871052 -273.522463)
		(end 338.588096 -273.59864)
		(width 0.0889)
		(layer "In2.Cu")
		(net "M_C_CPU0_SB_CB<1>")
	)
	(arc
		(start 329.753976 -273.59864)
		(mid 329.47102 -273.522463)
		(end 329.188064 -273.59864)
		(width 0.0889)
		(layer "In2.Cu")
		(net "M_C_CPU0_SB_CB<1>")
	)
	(arc
		(start 328.814176 -273.59864)
		(mid 328.53122 -273.522463)
		(end 328.248264 -273.59864)
		(width 0.0889)
		(layer "In2.Cu")
		(net "M_C_CPU0_SB_CB<1>")
	)
	(arc
		(start 338.213954 -273.59864)
		(mid 337.930998 -273.522463)
		(end 337.648042 -273.59864)
		(width 0.0889)
		(layer "In2.Cu")
		(net "M_C_CPU0_SB_CB<1>")
	)
	(arc
		(start 329.188064 -273.59864)
		(mid 329.00112 -273.648895)
		(end 328.814176 -273.59864)
		(width 0.0889)
		(layer "In2.Cu")
		(net "M_C_CPU0_SB_CB<1>")
	)
	(segment
		(start 343.097866 -272.200116)
		(end 342.631014 -272.466054)
		(width 0.10668)
		(layer "F.Cu")
		(net "M_C_CPU0_SB_CB<0>")
	)
	(segment
		(start 311.612534 -274.804378)
		(end 311.921906 -275.11375)
		(width 0.14478)
		(layer "In2.Cu")
		(net "M_C_CPU0_SB_CB<0>")
	)
	(segment
		(start 310.348122 -276.687534)
		(end 310.578246 -276.687534)
		(width 0.14478)
		(layer "In2.Cu")
		(net "M_C_CPU0_SB_CB<0>")
	)
	(segment
		(start 312.05805 -274.463002)
		(end 312.05805 -274.250658)
		(width 0.14478)
		(layer "In2.Cu")
		(net "M_C_CPU0_SB_CB<0>")
	)
	(segment
		(start 337.744054 -272.788634)
		(end 337.752436 -272.79346)
		(width 0.0889)
		(layer "In2.Cu")
		(net "M_C_CPU0_SB_CB<0>")
	)
	(segment
		(start 311.38241 -274.804378)
		(end 311.612534 -274.804378)
		(width 0.14478)
		(layer "In2.Cu")
		(net "M_C_CPU0_SB_CB<0>")
	)
	(segment
		(start 309.64505 -276.771354)
		(end 309.64505 -276.54123)
		(width 0.14478)
		(layer "In2.Cu")
		(net "M_C_CPU0_SB_CB<0>")
	)
	(segment
		(start 309.94604 -277.302468)
		(end 309.94604 -277.072344)
		(width 0.14478)
		(layer "In2.Cu")
		(net "M_C_CPU0_SB_CB<0>")
	)
	(segment
		(start 311.52846 -275.73732)
		(end 311.52846 -275.507196)
		(width 0.14478)
		(layer "In2.Cu")
		(net "M_C_CPU0_SB_CB<0>")
	)
	(segment
		(start 326.836024 -272.78838)
		(end 326.869298 -272.769076)
		(width 0.0889)
		(layer "In2.Cu")
		(net "M_C_CPU0_SB_CB<0>")
	)
	(segment
		(start 331.52969 -272.79346)
		(end 331.538072 -272.788634)
		(width 0.0889)
		(layer "In2.Cu")
		(net "M_C_CPU0_SB_CB<0>")
	)
	(segment
		(start 310.595264 -275.591016)
		(end 310.825388 -275.591016)
		(width 0.14478)
		(layer "In2.Cu")
		(net "M_C_CPU0_SB_CB<0>")
	)
	(segment
		(start 336.229706 -272.79346)
		(end 336.238088 -272.788634)
		(width 0.0889)
		(layer "In2.Cu")
		(net "M_C_CPU0_SB_CB<0>")
	)
	(segment
		(start 324.45325 -271.29994)
		(end 324.9168 -271.76349)
		(width 0.0889)
		(layer "In2.Cu")
		(net "M_C_CPU0_SB_CB<0>")
	)
	(segment
		(start 301.540418 -278.510238)
		(end 304.289206 -278.510238)
		(width 0.14478)
		(layer "In2.Cu")
		(net "M_C_CPU0_SB_CB<0>")
	)
	(segment
		(start 297.479974 -278.80691)
		(end 297.776646 -278.510238)
		(width 0.14478)
		(layer "In2.Cu")
		(net "M_C_CPU0_SB_CB<0>")
	)
	(segment
		(start 309.808372 -276.377908)
		(end 310.038496 -276.377908)
		(width 0.14478)
		(layer "In2.Cu")
		(net "M_C_CPU0_SB_CB<0>")
	)
	(segment
		(start 333.044038 -272.788634)
		(end 333.05242 -272.79346)
		(width 0.0889)
		(layer "In2.Cu")
		(net "M_C_CPU0_SB_CB<0>")
	)
	(segment
		(start 304.585878 -278.80691)
		(end 304.845466 -278.80691)
		(width 0.14478)
		(layer "In2.Cu")
		(net "M_C_CPU0_SB_CB<0>")
	)
	(segment
		(start 312.15203 -275.11375)
		(end 312.315352 -274.950428)
		(width 0.14478)
		(layer "In2.Cu")
		(net "M_C_CPU0_SB_CB<0>")
	)
	(segment
		(start 341.869776 -272.79346)
		(end 341.878158 -272.788634)
		(width 0.0889)
		(layer "In2.Cu")
		(net "M_C_CPU0_SB_CB<0>")
	)
	(segment
		(start 297.776646 -278.510238)
		(end 298.043854 -278.510238)
		(width 0.14478)
		(layer "In2.Cu")
		(net "M_C_CPU0_SB_CB<0>")
	)
	(segment
		(start 305.142138 -278.510238)
		(end 305.350926 -278.510238)
		(width 0.14478)
		(layer "In2.Cu")
		(net "M_C_CPU0_SB_CB<0>")
	)
	(segment
		(start 312.315352 -274.720304)
		(end 312.05805 -274.463002)
		(width 0.14478)
		(layer "In2.Cu")
		(net "M_C_CPU0_SB_CB<0>")
	)
	(segment
		(start 294.556434 -278.51989)
		(end 296.801794 -278.51989)
		(width 0.14478)
		(layer "In2.Cu")
		(net "M_C_CPU0_SB_CB<0>")
	)
	(segment
		(start 315.008768 -271.29994)
		(end 323.906134 -271.29994)
		(width 0.14478)
		(layer "In2.Cu")
		(net "M_C_CPU0_SB_CB<0>")
	)
	(segment
		(start 293.687754 -278.510238)
		(end 294.009826 -278.83231)
		(width 0.14478)
		(layer "In2.Cu")
		(net "M_C_CPU0_SB_CB<0>")
	)
	(segment
		(start 300.699932 -277.669752)
		(end 301.540418 -278.510238)
		(width 0.14478)
		(layer "In2.Cu")
		(net "M_C_CPU0_SB_CB<0>")
	)
	(segment
		(start 332.469744 -272.79346)
		(end 332.478126 -272.788634)
		(width 0.0889)
		(layer "In2.Cu")
		(net "M_C_CPU0_SB_CB<0>")
	)
	(segment
		(start 311.219088 -274.9677)
		(end 311.38241 -274.804378)
		(width 0.14478)
		(layer "In2.Cu")
		(net "M_C_CPU0_SB_CB<0>")
	)
	(segment
		(start 337.16976 -272.79346)
		(end 337.178142 -272.788634)
		(width 0.0889)
		(layer "In2.Cu")
		(net "M_C_CPU0_SB_CB<0>")
	)
	(segment
		(start 308.450996 -277.811992)
		(end 308.998366 -277.811992)
		(width 0.14478)
		(layer "In2.Cu")
		(net "M_C_CPU0_SB_CB<0>")
	)
	(segment
		(start 309.150258 -277.6601)
		(end 309.588408 -277.6601)
		(width 0.14478)
		(layer "In2.Cu")
		(net "M_C_CPU0_SB_CB<0>")
	)
	(segment
		(start 310.431942 -275.984462)
		(end 310.431942 -275.754338)
		(width 0.14478)
		(layer "In2.Cu")
		(net "M_C_CPU0_SB_CB<0>")
	)
	(segment
		(start 328.312272 -272.770092)
		(end 328.344022 -272.788634)
		(width 0.0889)
		(layer "In2.Cu")
		(net "M_C_CPU0_SB_CB<0>")
	)
	(segment
		(start 333.984092 -272.788634)
		(end 333.992474 -272.79346)
		(width 0.0889)
		(layer "In2.Cu")
		(net "M_C_CPU0_SB_CB<0>")
	)
	(segment
		(start 308.299104 -277.6601)
		(end 308.450996 -277.811992)
		(width 0.14478)
		(layer "In2.Cu")
		(net "M_C_CPU0_SB_CB<0>")
	)
	(segment
		(start 310.825388 -275.591016)
		(end 311.135014 -275.900642)
		(width 0.14478)
		(layer "In2.Cu")
		(net "M_C_CPU0_SB_CB<0>")
	)
	(segment
		(start 296.801794 -278.51989)
		(end 297.088814 -278.80691)
		(width 0.14478)
		(layer "In2.Cu")
		(net "M_C_CPU0_SB_CB<0>")
	)
	(segment
		(start 297.088814 -278.80691)
		(end 297.479974 -278.80691)
		(width 0.14478)
		(layer "In2.Cu")
		(net "M_C_CPU0_SB_CB<0>")
	)
	(segment
		(start 298.88434 -277.669752)
		(end 300.699932 -277.669752)
		(width 0.14478)
		(layer "In2.Cu")
		(net "M_C_CPU0_SB_CB<0>")
	)
	(segment
		(start 340.929722 -272.79346)
		(end 340.938104 -272.788634)
		(width 0.0889)
		(layer "In2.Cu")
		(net "M_C_CPU0_SB_CB<0>")
	)
	(segment
		(start 304.289206 -278.510238)
		(end 304.585878 -278.80691)
		(width 0.14478)
		(layer "In2.Cu")
		(net "M_C_CPU0_SB_CB<0>")
	)
	(segment
		(start 306.201064 -277.6601)
		(end 308.299104 -277.6601)
		(width 0.14478)
		(layer "In2.Cu")
		(net "M_C_CPU0_SB_CB<0>")
	)
	(segment
		(start 323.906134 -271.29994)
		(end 324.45325 -271.29994)
		(width 0.0889)
		(layer "In2.Cu")
		(net "M_C_CPU0_SB_CB<0>")
	)
	(segment
		(start 292.705282 -278.510238)
		(end 293.687754 -278.510238)
		(width 0.14478)
		(layer "In2.Cu")
		(net "M_C_CPU0_SB_CB<0>")
	)
	(segment
		(start 305.350926 -278.510238)
		(end 306.201064 -277.6601)
		(width 0.14478)
		(layer "In2.Cu")
		(net "M_C_CPU0_SB_CB<0>")
	)
	(segment
		(start 311.921906 -275.11375)
		(end 312.15203 -275.11375)
		(width 0.14478)
		(layer "In2.Cu")
		(net "M_C_CPU0_SB_CB<0>")
	)
	(segment
		(start 304.845466 -278.80691)
		(end 305.142138 -278.510238)
		(width 0.14478)
		(layer "In2.Cu")
		(net "M_C_CPU0_SB_CB<0>")
	)
	(segment
		(start 329.284076 -272.788634)
		(end 329.292458 -272.79346)
		(width 0.0889)
		(layer "In2.Cu")
		(net "M_C_CPU0_SB_CB<0>")
	)
	(segment
		(start 311.219088 -275.197824)
		(end 311.219088 -274.9677)
		(width 0.14478)
		(layer "In2.Cu")
		(net "M_C_CPU0_SB_CB<0>")
	)
	(segment
		(start 309.94604 -277.072344)
		(end 309.64505 -276.771354)
		(width 0.14478)
		(layer "In2.Cu")
		(net "M_C_CPU0_SB_CB<0>")
	)
	(segment
		(start 309.64505 -276.54123)
		(end 309.808372 -276.377908)
		(width 0.14478)
		(layer "In2.Cu")
		(net "M_C_CPU0_SB_CB<0>")
	)
	(segment
		(start 309.588408 -277.6601)
		(end 309.94604 -277.302468)
		(width 0.14478)
		(layer "In2.Cu")
		(net "M_C_CPU0_SB_CB<0>")
	)
	(segment
		(start 324.9168 -271.76349)
		(end 325.418958 -271.76349)
		(width 0.0889)
		(layer "In2.Cu")
		(net "M_C_CPU0_SB_CB<0>")
	)
	(segment
		(start 312.315352 -274.950428)
		(end 312.315352 -274.720304)
		(width 0.14478)
		(layer "In2.Cu")
		(net "M_C_CPU0_SB_CB<0>")
	)
	(segment
		(start 311.365138 -275.900642)
		(end 311.52846 -275.73732)
		(width 0.14478)
		(layer "In2.Cu")
		(net "M_C_CPU0_SB_CB<0>")
	)
	(segment
		(start 326.796908 -272.810732)
		(end 326.836024 -272.78838)
		(width 0.0889)
		(layer "In2.Cu")
		(net "M_C_CPU0_SB_CB<0>")
	)
	(segment
		(start 312.05805 -274.250658)
		(end 315.008768 -271.29994)
		(width 0.14478)
		(layer "In2.Cu")
		(net "M_C_CPU0_SB_CB<0>")
	)
	(segment
		(start 342.47709 -272.731484)
		(end 342.631014 -272.466054)
		(width 0.0889)
		(layer "In2.Cu")
		(net "M_C_CPU0_SB_CB<0>")
	)
	(segment
		(start 298.043854 -278.510238)
		(end 298.88434 -277.669752)
		(width 0.14478)
		(layer "In2.Cu")
		(net "M_C_CPU0_SB_CB<0>")
	)
	(segment
		(start 308.998366 -277.811992)
		(end 309.150258 -277.6601)
		(width 0.14478)
		(layer "In2.Cu")
		(net "M_C_CPU0_SB_CB<0>")
	)
	(segment
		(start 327.398888 -272.788634)
		(end 327.42505 -272.803874)
		(width 0.0889)
		(layer "In2.Cu")
		(net "M_C_CPU0_SB_CB<0>")
	)
	(segment
		(start 310.741568 -276.524212)
		(end 310.741568 -276.294088)
		(width 0.14478)
		(layer "In2.Cu")
		(net "M_C_CPU0_SB_CB<0>")
	)
	(segment
		(start 310.038496 -276.377908)
		(end 310.348122 -276.687534)
		(width 0.14478)
		(layer "In2.Cu")
		(net "M_C_CPU0_SB_CB<0>")
	)
	(segment
		(start 311.52846 -275.507196)
		(end 311.219088 -275.197824)
		(width 0.14478)
		(layer "In2.Cu")
		(net "M_C_CPU0_SB_CB<0>")
	)
	(segment
		(start 310.578246 -276.687534)
		(end 310.741568 -276.524212)
		(width 0.14478)
		(layer "In2.Cu")
		(net "M_C_CPU0_SB_CB<0>")
	)
	(segment
		(start 311.135014 -275.900642)
		(end 311.365138 -275.900642)
		(width 0.14478)
		(layer "In2.Cu")
		(net "M_C_CPU0_SB_CB<0>")
	)
	(segment
		(start 310.741568 -276.294088)
		(end 310.431942 -275.984462)
		(width 0.14478)
		(layer "In2.Cu")
		(net "M_C_CPU0_SB_CB<0>")
	)
	(segment
		(start 325.418958 -271.76349)
		(end 326.38619 -272.730722)
		(width 0.0889)
		(layer "In2.Cu")
		(net "M_C_CPU0_SB_CB<0>")
	)
	(segment
		(start 294.009826 -278.83231)
		(end 294.244014 -278.83231)
		(width 0.14478)
		(layer "In2.Cu")
		(net "M_C_CPU0_SB_CB<0>")
	)
	(segment
		(start 310.431942 -275.754338)
		(end 310.595264 -275.591016)
		(width 0.14478)
		(layer "In2.Cu")
		(net "M_C_CPU0_SB_CB<0>")
	)
	(segment
		(start 294.244014 -278.83231)
		(end 294.556434 -278.51989)
		(width 0.14478)
		(layer "In2.Cu")
		(net "M_C_CPU0_SB_CB<0>")
	)
	(segment
		(start 328.709782 -272.79346)
		(end 328.718164 -272.788634)
		(width 0.0889)
		(layer "In2.Cu")
		(net "M_C_CPU0_SB_CB<0>")
	)
	(segment
		(start 338.684108 -272.788634)
		(end 338.69249 -272.79346)
		(width 0.0889)
		(layer "In2.Cu")
		(net "M_C_CPU0_SB_CB<0>")
	)
	(segment
		(start 342.381078 -272.756884)
		(end 342.47709 -272.731484)
		(width 0.0889)
		(layer "In2.Cu")
		(net "M_C_CPU0_SB_CB<0>")
	)
	(segment
		(start 292.280086 -278.085042)
		(end 292.705282 -278.510238)
		(width 0.14478)
		(layer "In2.Cu")
		(net "M_C_CPU0_SB_CB<0>")
	)
	(arc
		(start 339.99805 -272.788634)
		(mid 340.281006 -272.712457)
		(end 340.563962 -272.788634)
		(width 0.0889)
		(layer "In2.Cu")
		(net "M_C_CPU0_SB_CB<0>")
	)
	(arc
		(start 329.658218 -272.788634)
		(mid 329.941174 -272.712457)
		(end 330.22413 -272.788634)
		(width 0.0889)
		(layer "In2.Cu")
		(net "M_C_CPU0_SB_CB<0>")
	)
	(arc
		(start 326.869298 -272.769076)
		(mid 327.136528 -272.712765)
		(end 327.398888 -272.788634)
		(width 0.0889)
		(layer "In2.Cu")
		(net "M_C_CPU0_SB_CB<0>")
	)
	(arc
		(start 328.344022 -272.788634)
		(mid 328.526273 -272.838984)
		(end 328.709782 -272.79346)
		(width 0.0889)
		(layer "In2.Cu")
		(net "M_C_CPU0_SB_CB<0>")
	)
	(arc
		(start 338.69249 -272.79346)
		(mid 338.875998 -272.838954)
		(end 339.05825 -272.788634)
		(width 0.0889)
		(layer "In2.Cu")
		(net "M_C_CPU0_SB_CB<0>")
	)
	(arc
		(start 329.292458 -272.79346)
		(mid 329.475966 -272.838954)
		(end 329.658218 -272.788634)
		(width 0.0889)
		(layer "In2.Cu")
		(net "M_C_CPU0_SB_CB<0>")
	)
	(arc
		(start 336.804 -272.788634)
		(mid 336.986251 -272.838984)
		(end 337.16976 -272.79346)
		(width 0.0889)
		(layer "In2.Cu")
		(net "M_C_CPU0_SB_CB<0>")
	)
	(arc
		(start 330.598018 -272.788634)
		(mid 330.880974 -272.712457)
		(end 331.16393 -272.788634)
		(width 0.0889)
		(layer "In2.Cu")
		(net "M_C_CPU0_SB_CB<0>")
	)
	(arc
		(start 333.992474 -272.79346)
		(mid 334.175982 -272.838954)
		(end 334.358234 -272.788634)
		(width 0.0889)
		(layer "In2.Cu")
		(net "M_C_CPU0_SB_CB<0>")
	)
	(arc
		(start 331.16393 -272.788634)
		(mid 331.346181 -272.838984)
		(end 331.52969 -272.79346)
		(width 0.0889)
		(layer "In2.Cu")
		(net "M_C_CPU0_SB_CB<0>")
	)
	(arc
		(start 335.863946 -272.788634)
		(mid 336.046197 -272.838984)
		(end 336.229706 -272.79346)
		(width 0.0889)
		(layer "In2.Cu")
		(net "M_C_CPU0_SB_CB<0>")
	)
	(arc
		(start 337.178142 -272.788634)
		(mid 337.461098 -272.712457)
		(end 337.744054 -272.788634)
		(width 0.0889)
		(layer "In2.Cu")
		(net "M_C_CPU0_SB_CB<0>")
	)
	(arc
		(start 339.624162 -272.788634)
		(mid 339.811106 -272.838889)
		(end 339.99805 -272.788634)
		(width 0.0889)
		(layer "In2.Cu")
		(net "M_C_CPU0_SB_CB<0>")
	)
	(arc
		(start 337.752436 -272.79346)
		(mid 337.935944 -272.838954)
		(end 338.118196 -272.788634)
		(width 0.0889)
		(layer "In2.Cu")
		(net "M_C_CPU0_SB_CB<0>")
	)
	(arc
		(start 331.538072 -272.788634)
		(mid 331.821028 -272.712457)
		(end 332.103984 -272.788634)
		(width 0.0889)
		(layer "In2.Cu")
		(net "M_C_CPU0_SB_CB<0>")
	)
	(arc
		(start 336.238088 -272.788634)
		(mid 336.521044 -272.712457)
		(end 336.804 -272.788634)
		(width 0.0889)
		(layer "In2.Cu")
		(net "M_C_CPU0_SB_CB<0>")
	)
	(arc
		(start 335.298034 -272.788634)
		(mid 335.58099 -272.712457)
		(end 335.863946 -272.788634)
		(width 0.0889)
		(layer "In2.Cu")
		(net "M_C_CPU0_SB_CB<0>")
	)
	(arc
		(start 341.878158 -272.788634)
		(mid 342.125871 -272.713414)
		(end 342.381078 -272.756884)
		(width 0.0889)
		(layer "In2.Cu")
		(net "M_C_CPU0_SB_CB<0>")
	)
	(arc
		(start 338.118196 -272.788634)
		(mid 338.401152 -272.712457)
		(end 338.684108 -272.788634)
		(width 0.0889)
		(layer "In2.Cu")
		(net "M_C_CPU0_SB_CB<0>")
	)
	(arc
		(start 333.05242 -272.79346)
		(mid 333.235928 -272.838954)
		(end 333.41818 -272.788634)
		(width 0.0889)
		(layer "In2.Cu")
		(net "M_C_CPU0_SB_CB<0>")
	)
	(arc
		(start 326.461628 -272.788888)
		(mid 326.626687 -272.83959)
		(end 326.796908 -272.810732)
		(width 0.0889)
		(layer "In2.Cu")
		(net "M_C_CPU0_SB_CB<0>")
	)
	(arc
		(start 332.103984 -272.788634)
		(mid 332.286235 -272.838984)
		(end 332.469744 -272.79346)
		(width 0.0889)
		(layer "In2.Cu")
		(net "M_C_CPU0_SB_CB<0>")
	)
	(arc
		(start 328.718164 -272.788634)
		(mid 329.00112 -272.712457)
		(end 329.284076 -272.788634)
		(width 0.0889)
		(layer "In2.Cu")
		(net "M_C_CPU0_SB_CB<0>")
	)
	(arc
		(start 330.22413 -272.788634)
		(mid 330.411074 -272.838889)
		(end 330.598018 -272.788634)
		(width 0.0889)
		(layer "In2.Cu")
		(net "M_C_CPU0_SB_CB<0>")
	)
	(arc
		(start 340.563962 -272.788634)
		(mid 340.746213 -272.838984)
		(end 340.929722 -272.79346)
		(width 0.0889)
		(layer "In2.Cu")
		(net "M_C_CPU0_SB_CB<0>")
	)
	(arc
		(start 332.478126 -272.788634)
		(mid 332.761082 -272.712457)
		(end 333.044038 -272.788634)
		(width 0.0889)
		(layer "In2.Cu")
		(net "M_C_CPU0_SB_CB<0>")
	)
	(arc
		(start 334.358234 -272.788634)
		(mid 334.64119 -272.712457)
		(end 334.924146 -272.788634)
		(width 0.0889)
		(layer "In2.Cu")
		(net "M_C_CPU0_SB_CB<0>")
	)
	(arc
		(start 339.05825 -272.788634)
		(mid 339.341206 -272.712457)
		(end 339.624162 -272.788634)
		(width 0.0889)
		(layer "In2.Cu")
		(net "M_C_CPU0_SB_CB<0>")
	)
	(arc
		(start 327.775316 -272.788888)
		(mid 328.041405 -272.711611)
		(end 328.312272 -272.770092)
		(width 0.0889)
		(layer "In2.Cu")
		(net "M_C_CPU0_SB_CB<0>")
	)
	(arc
		(start 326.38619 -272.730722)
		(mid 326.422063 -272.762197)
		(end 326.461628 -272.788888)
		(width 0.0889)
		(layer "In2.Cu")
		(net "M_C_CPU0_SB_CB<0>")
	)
	(arc
		(start 340.938104 -272.788634)
		(mid 341.22106 -272.712457)
		(end 341.504016 -272.788634)
		(width 0.0889)
		(layer "In2.Cu")
		(net "M_C_CPU0_SB_CB<0>")
	)
	(arc
		(start 333.41818 -272.788634)
		(mid 333.701136 -272.712457)
		(end 333.984092 -272.788634)
		(width 0.0889)
		(layer "In2.Cu")
		(net "M_C_CPU0_SB_CB<0>")
	)
	(arc
		(start 334.924146 -272.788634)
		(mid 335.11109 -272.838889)
		(end 335.298034 -272.788634)
		(width 0.0889)
		(layer "In2.Cu")
		(net "M_C_CPU0_SB_CB<0>")
	)
	(arc
		(start 327.42505 -272.803874)
		(mid 327.602051 -272.839952)
		(end 327.775316 -272.788888)
		(width 0.0889)
		(layer "In2.Cu")
		(net "M_C_CPU0_SB_CB<0>")
	)
	(arc
		(start 341.504016 -272.788634)
		(mid 341.686267 -272.838984)
		(end 341.869776 -272.79346)
		(width 0.0889)
		(layer "In2.Cu")
		(net "M_C_CPU0_SB_CB<0>")
	)
	(segment
		(start 343.097866 -264.100056)
		(end 342.631014 -264.365994)
		(width 0.10668)
		(layer "F.Cu")
		(net "M_C_CPU0_SB_CA<6>")
	)
	(segment
		(start 298.15155 -265.38809)
		(end 297.988736 -265.550904)
		(width 0.14478)
		(layer "In2.Cu")
		(net "M_C_CPU0_SB_CA<6>")
	)
	(segment
		(start 298.754292 -265.7602)
		(end 298.382182 -265.38809)
		(width 0.14478)
		(layer "In2.Cu")
		(net "M_C_CPU0_SB_CA<6>")
	)
	(segment
		(start 301.12716 -266.15009)
		(end 300.964346 -265.987276)
		(width 0.14478)
		(layer "In2.Cu")
		(net "M_C_CPU0_SB_CA<6>")
	)
	(segment
		(start 294.207438 -265.37031)
		(end 294.044624 -265.533124)
		(width 0.14478)
		(layer "In2.Cu")
		(net "M_C_CPU0_SB_CA<6>")
	)
	(segment
		(start 327.779888 -264.68832)
		(end 327.758044 -264.700766)
		(width 0.0889)
		(layer "In2.Cu")
		(net "M_C_CPU0_SB_CA<6>")
	)
	(segment
		(start 301.520606 -265.533124)
		(end 301.520606 -265.987276)
		(width 0.14478)
		(layer "In2.Cu")
		(net "M_C_CPU0_SB_CA<6>")
	)
	(segment
		(start 297.825922 -266.13231)
		(end 297.59529 -266.13231)
		(width 0.14478)
		(layer "In2.Cu")
		(net "M_C_CPU0_SB_CA<6>")
	)
	(segment
		(start 296.876216 -265.969496)
		(end 296.713402 -266.13231)
		(width 0.14478)
		(layer "In2.Cu")
		(net "M_C_CPU0_SB_CA<6>")
	)
	(segment
		(start 327.803764 -264.67435)
		(end 327.779888 -264.68832)
		(width 0.0889)
		(layer "In2.Cu")
		(net "M_C_CPU0_SB_CA<6>")
	)
	(segment
		(start 337.178142 -264.688574)
		(end 337.16976 -264.6934)
		(width 0.0889)
		(layer "In2.Cu")
		(net "M_C_CPU0_SB_CA<6>")
	)
	(segment
		(start 301.357792 -266.15009)
		(end 301.12716 -266.15009)
		(width 0.14478)
		(layer "In2.Cu")
		(net "M_C_CPU0_SB_CA<6>")
	)
	(segment
		(start 298.382182 -265.38809)
		(end 298.15155 -265.38809)
		(width 0.14478)
		(layer "In2.Cu")
		(net "M_C_CPU0_SB_CA<6>")
	)
	(segment
		(start 342.631014 -264.365994)
		(end 342.47709 -264.631424)
		(width 0.0889)
		(layer "In2.Cu")
		(net "M_C_CPU0_SB_CA<6>")
	)
	(segment
		(start 300.964346 -265.987276)
		(end 300.964346 -265.533124)
		(width 0.14478)
		(layer "In2.Cu")
		(net "M_C_CPU0_SB_CA<6>")
	)
	(segment
		(start 297.988736 -265.550904)
		(end 297.988736 -265.969496)
		(width 0.14478)
		(layer "In2.Cu")
		(net "M_C_CPU0_SB_CA<6>")
	)
	(segment
		(start 337.752436 -264.6934)
		(end 337.744054 -264.688574)
		(width 0.0889)
		(layer "In2.Cu")
		(net "M_C_CPU0_SB_CA<6>")
	)
	(segment
		(start 300.18101 -265.7602)
		(end 298.754292 -265.7602)
		(width 0.14478)
		(layer "In2.Cu")
		(net "M_C_CPU0_SB_CA<6>")
	)
	(segment
		(start 329.292458 -264.6934)
		(end 329.284076 -264.688574)
		(width 0.0889)
		(layer "In2.Cu")
		(net "M_C_CPU0_SB_CA<6>")
	)
	(segment
		(start 295.38422 -265.7602)
		(end 294.99433 -266.15009)
		(width 0.14478)
		(layer "In2.Cu")
		(net "M_C_CPU0_SB_CA<6>")
	)
	(segment
		(start 333.992474 -264.6934)
		(end 333.984092 -264.688574)
		(width 0.0889)
		(layer "In2.Cu")
		(net "M_C_CPU0_SB_CA<6>")
	)
	(segment
		(start 342.47709 -264.631424)
		(end 342.381078 -264.656824)
		(width 0.0889)
		(layer "In2.Cu")
		(net "M_C_CPU0_SB_CA<6>")
	)
	(segment
		(start 302.303942 -265.7602)
		(end 301.914052 -265.37031)
		(width 0.14478)
		(layer "In2.Cu")
		(net "M_C_CPU0_SB_CA<6>")
	)
	(segment
		(start 294.044624 -265.987276)
		(end 293.88181 -266.15009)
		(width 0.14478)
		(layer "In2.Cu")
		(net "M_C_CPU0_SB_CA<6>")
	)
	(segment
		(start 294.600884 -265.987276)
		(end 294.600884 -265.533124)
		(width 0.14478)
		(layer "In2.Cu")
		(net "M_C_CPU0_SB_CA<6>")
	)
	(segment
		(start 294.044624 -265.533124)
		(end 294.044624 -265.987276)
		(width 0.14478)
		(layer "In2.Cu")
		(net "M_C_CPU0_SB_CA<6>")
	)
	(segment
		(start 300.964346 -265.533124)
		(end 300.801532 -265.37031)
		(width 0.14478)
		(layer "In2.Cu")
		(net "M_C_CPU0_SB_CA<6>")
	)
	(segment
		(start 326.09536 -264.32891)
		(end 324.637654 -264.32891)
		(width 0.0889)
		(layer "In2.Cu")
		(net "M_C_CPU0_SB_CA<6>")
	)
	(segment
		(start 297.432476 -265.550904)
		(end 297.269662 -265.38809)
		(width 0.14478)
		(layer "In2.Cu")
		(net "M_C_CPU0_SB_CA<6>")
	)
	(segment
		(start 294.763698 -266.15009)
		(end 294.600884 -265.987276)
		(width 0.14478)
		(layer "In2.Cu")
		(net "M_C_CPU0_SB_CA<6>")
	)
	(segment
		(start 324.637654 -264.32891)
		(end 324.346824 -264.61974)
		(width 0.0889)
		(layer "In2.Cu")
		(net "M_C_CPU0_SB_CA<6>")
	)
	(segment
		(start 301.520606 -265.987276)
		(end 301.357792 -266.15009)
		(width 0.14478)
		(layer "In2.Cu")
		(net "M_C_CPU0_SB_CA<6>")
	)
	(segment
		(start 294.600884 -265.533124)
		(end 294.43807 -265.37031)
		(width 0.14478)
		(layer "In2.Cu")
		(net "M_C_CPU0_SB_CA<6>")
	)
	(segment
		(start 297.59529 -266.13231)
		(end 297.432476 -265.969496)
		(width 0.14478)
		(layer "In2.Cu")
		(net "M_C_CPU0_SB_CA<6>")
	)
	(segment
		(start 293.88181 -266.15009)
		(end 293.651178 -266.15009)
		(width 0.14478)
		(layer "In2.Cu")
		(net "M_C_CPU0_SB_CA<6>")
	)
	(segment
		(start 338.69249 -264.6934)
		(end 338.684108 -264.688574)
		(width 0.0889)
		(layer "In2.Cu")
		(net "M_C_CPU0_SB_CA<6>")
	)
	(segment
		(start 326.419718 -264.653268)
		(end 326.09536 -264.32891)
		(width 0.0889)
		(layer "In2.Cu")
		(net "M_C_CPU0_SB_CA<6>")
	)
	(segment
		(start 327.40727 -264.688574)
		(end 327.379584 -264.672572)
		(width 0.0889)
		(layer "In2.Cu")
		(net "M_C_CPU0_SB_CA<6>")
	)
	(segment
		(start 293.488364 -265.987276)
		(end 293.488364 -265.533124)
		(width 0.14478)
		(layer "In2.Cu")
		(net "M_C_CPU0_SB_CA<6>")
	)
	(segment
		(start 336.238088 -264.688574)
		(end 336.229706 -264.6934)
		(width 0.0889)
		(layer "In2.Cu")
		(net "M_C_CPU0_SB_CA<6>")
	)
	(segment
		(start 330.232512 -264.6934)
		(end 330.22413 -264.688574)
		(width 0.0889)
		(layer "In2.Cu")
		(net "M_C_CPU0_SB_CA<6>")
	)
	(segment
		(start 294.99433 -266.15009)
		(end 294.763698 -266.15009)
		(width 0.14478)
		(layer "In2.Cu")
		(net "M_C_CPU0_SB_CA<6>")
	)
	(segment
		(start 326.49541 -264.705592)
		(end 326.465438 -264.68832)
		(width 0.0889)
		(layer "In2.Cu")
		(net "M_C_CPU0_SB_CA<6>")
	)
	(segment
		(start 300.801532 -265.37031)
		(end 300.5709 -265.37031)
		(width 0.14478)
		(layer "In2.Cu")
		(net "M_C_CPU0_SB_CA<6>")
	)
	(segment
		(start 340.938104 -264.688574)
		(end 340.929722 -264.6934)
		(width 0.0889)
		(layer "In2.Cu")
		(net "M_C_CPU0_SB_CA<6>")
	)
	(segment
		(start 301.68342 -265.37031)
		(end 301.520606 -265.533124)
		(width 0.14478)
		(layer "In2.Cu")
		(net "M_C_CPU0_SB_CA<6>")
	)
	(segment
		(start 300.5709 -265.37031)
		(end 300.18101 -265.7602)
		(width 0.14478)
		(layer "In2.Cu")
		(net "M_C_CPU0_SB_CA<6>")
	)
	(segment
		(start 297.432476 -265.969496)
		(end 297.432476 -265.550904)
		(width 0.14478)
		(layer "In2.Cu")
		(net "M_C_CPU0_SB_CA<6>")
	)
	(segment
		(start 323.884544 -264.61974)
		(end 309.233824 -264.61974)
		(width 0.14478)
		(layer "In2.Cu")
		(net "M_C_CPU0_SB_CA<6>")
	)
	(segment
		(start 296.713402 -266.13231)
		(end 296.33799 -266.13231)
		(width 0.14478)
		(layer "In2.Cu")
		(net "M_C_CPU0_SB_CA<6>")
	)
	(segment
		(start 295.96588 -265.7602)
		(end 295.38422 -265.7602)
		(width 0.14478)
		(layer "In2.Cu")
		(net "M_C_CPU0_SB_CA<6>")
	)
	(segment
		(start 296.33799 -266.13231)
		(end 295.96588 -265.7602)
		(width 0.14478)
		(layer "In2.Cu")
		(net "M_C_CPU0_SB_CA<6>")
	)
	(segment
		(start 296.876216 -265.550904)
		(end 296.876216 -265.969496)
		(width 0.14478)
		(layer "In2.Cu")
		(net "M_C_CPU0_SB_CA<6>")
	)
	(segment
		(start 333.05242 -264.6934)
		(end 333.044038 -264.688574)
		(width 0.0889)
		(layer "In2.Cu")
		(net "M_C_CPU0_SB_CA<6>")
	)
	(segment
		(start 328.718164 -264.688574)
		(end 328.709782 -264.6934)
		(width 0.0889)
		(layer "In2.Cu")
		(net "M_C_CPU0_SB_CA<6>")
	)
	(segment
		(start 293.32555 -265.37031)
		(end 293.094918 -265.37031)
		(width 0.14478)
		(layer "In2.Cu")
		(net "M_C_CPU0_SB_CA<6>")
	)
	(segment
		(start 293.094918 -265.37031)
		(end 292.280086 -266.185142)
		(width 0.14478)
		(layer "In2.Cu")
		(net "M_C_CPU0_SB_CA<6>")
	)
	(segment
		(start 293.488364 -265.533124)
		(end 293.32555 -265.37031)
		(width 0.14478)
		(layer "In2.Cu")
		(net "M_C_CPU0_SB_CA<6>")
	)
	(segment
		(start 297.03903 -265.38809)
		(end 296.876216 -265.550904)
		(width 0.14478)
		(layer "In2.Cu")
		(net "M_C_CPU0_SB_CA<6>")
	)
	(segment
		(start 293.651178 -266.15009)
		(end 293.488364 -265.987276)
		(width 0.14478)
		(layer "In2.Cu")
		(net "M_C_CPU0_SB_CA<6>")
	)
	(segment
		(start 297.988736 -265.969496)
		(end 297.825922 -266.13231)
		(width 0.14478)
		(layer "In2.Cu")
		(net "M_C_CPU0_SB_CA<6>")
	)
	(segment
		(start 341.878158 -264.688574)
		(end 341.869776 -264.6934)
		(width 0.0889)
		(layer "In2.Cu")
		(net "M_C_CPU0_SB_CA<6>")
	)
	(segment
		(start 324.346824 -264.61974)
		(end 323.884544 -264.61974)
		(width 0.0889)
		(layer "In2.Cu")
		(net "M_C_CPU0_SB_CA<6>")
	)
	(segment
		(start 294.43807 -265.37031)
		(end 294.207438 -265.37031)
		(width 0.14478)
		(layer "In2.Cu")
		(net "M_C_CPU0_SB_CA<6>")
	)
	(segment
		(start 297.269662 -265.38809)
		(end 297.03903 -265.38809)
		(width 0.14478)
		(layer "In2.Cu")
		(net "M_C_CPU0_SB_CA<6>")
	)
	(segment
		(start 309.233824 -264.61974)
		(end 308.093364 -265.7602)
		(width 0.14478)
		(layer "In2.Cu")
		(net "M_C_CPU0_SB_CA<6>")
	)
	(segment
		(start 308.093364 -265.7602)
		(end 302.303942 -265.7602)
		(width 0.14478)
		(layer "In2.Cu")
		(net "M_C_CPU0_SB_CA<6>")
	)
	(segment
		(start 301.914052 -265.37031)
		(end 301.68342 -265.37031)
		(width 0.14478)
		(layer "In2.Cu")
		(net "M_C_CPU0_SB_CA<6>")
	)
	(segment
		(start 332.478126 -264.688574)
		(end 332.469744 -264.6934)
		(width 0.0889)
		(layer "In2.Cu")
		(net "M_C_CPU0_SB_CA<6>")
	)
	(arc
		(start 333.41818 -264.688574)
		(mid 333.235929 -264.738924)
		(end 333.05242 -264.6934)
		(width 0.0889)
		(layer "In2.Cu")
		(net "M_C_CPU0_SB_CA<6>")
	)
	(arc
		(start 335.298034 -264.688574)
		(mid 335.11109 -264.738829)
		(end 334.924146 -264.688574)
		(width 0.0889)
		(layer "In2.Cu")
		(net "M_C_CPU0_SB_CA<6>")
	)
	(arc
		(start 334.358234 -264.688574)
		(mid 334.175983 -264.738924)
		(end 333.992474 -264.6934)
		(width 0.0889)
		(layer "In2.Cu")
		(net "M_C_CPU0_SB_CA<6>")
	)
	(arc
		(start 329.658218 -264.688574)
		(mid 329.475967 -264.738924)
		(end 329.292458 -264.6934)
		(width 0.0889)
		(layer "In2.Cu")
		(net "M_C_CPU0_SB_CA<6>")
	)
	(arc
		(start 337.744054 -264.688574)
		(mid 337.461098 -264.612397)
		(end 337.178142 -264.688574)
		(width 0.0889)
		(layer "In2.Cu")
		(net "M_C_CPU0_SB_CA<6>")
	)
	(arc
		(start 327.379584 -264.672572)
		(mid 327.10755 -264.6118)
		(end 326.83958 -264.688574)
		(width 0.0889)
		(layer "In2.Cu")
		(net "M_C_CPU0_SB_CA<6>")
	)
	(arc
		(start 329.284076 -264.688574)
		(mid 329.00112 -264.612397)
		(end 328.718164 -264.688574)
		(width 0.0889)
		(layer "In2.Cu")
		(net "M_C_CPU0_SB_CA<6>")
	)
	(arc
		(start 341.869776 -264.6934)
		(mid 341.686268 -264.738894)
		(end 341.504016 -264.688574)
		(width 0.0889)
		(layer "In2.Cu")
		(net "M_C_CPU0_SB_CA<6>")
	)
	(arc
		(start 328.344022 -264.688574)
		(mid 328.075702 -264.612466)
		(end 327.803764 -264.67435)
		(width 0.0889)
		(layer "In2.Cu")
		(net "M_C_CPU0_SB_CA<6>")
	)
	(arc
		(start 327.758044 -264.700766)
		(mid 327.581116 -264.738594)
		(end 327.40727 -264.688574)
		(width 0.0889)
		(layer "In2.Cu")
		(net "M_C_CPU0_SB_CA<6>")
	)
	(arc
		(start 330.598272 -264.688574)
		(mid 330.416021 -264.738924)
		(end 330.232512 -264.6934)
		(width 0.0889)
		(layer "In2.Cu")
		(net "M_C_CPU0_SB_CA<6>")
	)
	(arc
		(start 332.469744 -264.6934)
		(mid 332.286236 -264.738894)
		(end 332.103984 -264.688574)
		(width 0.0889)
		(layer "In2.Cu")
		(net "M_C_CPU0_SB_CA<6>")
	)
	(arc
		(start 332.103984 -264.688574)
		(mid 331.821028 -264.612397)
		(end 331.538072 -264.688574)
		(width 0.0889)
		(layer "In2.Cu")
		(net "M_C_CPU0_SB_CA<6>")
	)
	(arc
		(start 333.984092 -264.688574)
		(mid 333.701136 -264.612397)
		(end 333.41818 -264.688574)
		(width 0.0889)
		(layer "In2.Cu")
		(net "M_C_CPU0_SB_CA<6>")
	)
	(arc
		(start 339.05825 -264.688574)
		(mid 338.875999 -264.738924)
		(end 338.69249 -264.6934)
		(width 0.0889)
		(layer "In2.Cu")
		(net "M_C_CPU0_SB_CA<6>")
	)
	(arc
		(start 341.504016 -264.688574)
		(mid 341.22106 -264.612397)
		(end 340.938104 -264.688574)
		(width 0.0889)
		(layer "In2.Cu")
		(net "M_C_CPU0_SB_CA<6>")
	)
	(arc
		(start 328.709782 -264.6934)
		(mid 328.526274 -264.738894)
		(end 328.344022 -264.688574)
		(width 0.0889)
		(layer "In2.Cu")
		(net "M_C_CPU0_SB_CA<6>")
	)
	(arc
		(start 337.16976 -264.6934)
		(mid 336.986252 -264.738894)
		(end 336.804 -264.688574)
		(width 0.0889)
		(layer "In2.Cu")
		(net "M_C_CPU0_SB_CA<6>")
	)
	(arc
		(start 333.044038 -264.688574)
		(mid 332.761082 -264.612397)
		(end 332.478126 -264.688574)
		(width 0.0889)
		(layer "In2.Cu")
		(net "M_C_CPU0_SB_CA<6>")
	)
	(arc
		(start 331.538072 -264.688574)
		(mid 331.351128 -264.738829)
		(end 331.164184 -264.688574)
		(width 0.0889)
		(layer "In2.Cu")
		(net "M_C_CPU0_SB_CA<6>")
	)
	(arc
		(start 326.83958 -264.688574)
		(mid 326.669573 -264.739139)
		(end 326.49541 -264.705592)
		(width 0.0889)
		(layer "In2.Cu")
		(net "M_C_CPU0_SB_CA<6>")
	)
	(arc
		(start 338.118196 -264.688574)
		(mid 337.935945 -264.738924)
		(end 337.752436 -264.6934)
		(width 0.0889)
		(layer "In2.Cu")
		(net "M_C_CPU0_SB_CA<6>")
	)
	(arc
		(start 340.929722 -264.6934)
		(mid 340.746214 -264.738894)
		(end 340.563962 -264.688574)
		(width 0.0889)
		(layer "In2.Cu")
		(net "M_C_CPU0_SB_CA<6>")
	)
	(arc
		(start 339.624162 -264.688574)
		(mid 339.341206 -264.612397)
		(end 339.05825 -264.688574)
		(width 0.0889)
		(layer "In2.Cu")
		(net "M_C_CPU0_SB_CA<6>")
	)
	(arc
		(start 330.22413 -264.688574)
		(mid 329.941174 -264.612397)
		(end 329.658218 -264.688574)
		(width 0.0889)
		(layer "In2.Cu")
		(net "M_C_CPU0_SB_CA<6>")
	)
	(arc
		(start 340.563962 -264.688574)
		(mid 340.281006 -264.612397)
		(end 339.99805 -264.688574)
		(width 0.0889)
		(layer "In2.Cu")
		(net "M_C_CPU0_SB_CA<6>")
	)
	(arc
		(start 339.99805 -264.688574)
		(mid 339.811106 -264.738829)
		(end 339.624162 -264.688574)
		(width 0.0889)
		(layer "In2.Cu")
		(net "M_C_CPU0_SB_CA<6>")
	)
	(arc
		(start 342.381078 -264.656824)
		(mid 342.12587 -264.613347)
		(end 341.878158 -264.688574)
		(width 0.0889)
		(layer "In2.Cu")
		(net "M_C_CPU0_SB_CA<6>")
	)
	(arc
		(start 326.465438 -264.68832)
		(mid 326.441423 -264.6723)
		(end 326.419718 -264.653268)
		(width 0.0889)
		(layer "In2.Cu")
		(net "M_C_CPU0_SB_CA<6>")
	)
	(arc
		(start 336.804 -264.688574)
		(mid 336.521044 -264.612397)
		(end 336.238088 -264.688574)
		(width 0.0889)
		(layer "In2.Cu")
		(net "M_C_CPU0_SB_CA<6>")
	)
	(arc
		(start 334.924146 -264.688574)
		(mid 334.64119 -264.612397)
		(end 334.358234 -264.688574)
		(width 0.0889)
		(layer "In2.Cu")
		(net "M_C_CPU0_SB_CA<6>")
	)
	(arc
		(start 335.863946 -264.688574)
		(mid 335.58099 -264.612397)
		(end 335.298034 -264.688574)
		(width 0.0889)
		(layer "In2.Cu")
		(net "M_C_CPU0_SB_CA<6>")
	)
	(arc
		(start 338.684108 -264.688574)
		(mid 338.401152 -264.612397)
		(end 338.118196 -264.688574)
		(width 0.0889)
		(layer "In2.Cu")
		(net "M_C_CPU0_SB_CA<6>")
	)
	(arc
		(start 336.229706 -264.6934)
		(mid 336.046198 -264.738894)
		(end 335.863946 -264.688574)
		(width 0.0889)
		(layer "In2.Cu")
		(net "M_C_CPU0_SB_CA<6>")
	)
	(arc
		(start 331.164184 -264.688574)
		(mid 330.881228 -264.612397)
		(end 330.598272 -264.688574)
		(width 0.0889)
		(layer "In2.Cu")
		(net "M_C_CPU0_SB_CA<6>")
	)
	(segment
		(start 344.03792 -264.100056)
		(end 343.571068 -264.365994)
		(width 0.10668)
		(layer "F.Cu")
		(net "M_C_CPU0_SB_CA<5>")
	)
	(segment
		(start 289.630358 -264.390124)
		(end 289.630358 -264.747248)
		(width 0.14478)
		(layer "In2.Cu")
		(net "M_C_CPU0_SB_CA<5>")
	)
	(segment
		(start 340.938104 -264.043414)
		(end 340.929722 -264.038588)
		(width 0.0889)
		(layer "In2.Cu")
		(net "M_C_CPU0_SB_CA<5>")
	)
	(segment
		(start 290.186618 -264.747248)
		(end 290.186618 -264.390124)
		(width 0.14478)
		(layer "In2.Cu")
		(net "M_C_CPU0_SB_CA<5>")
	)
	(segment
		(start 288.60496 -264.910062)
		(end 288.180018 -265.335004)
		(width 0.14478)
		(layer "In2.Cu")
		(net "M_C_CPU0_SB_CA<5>")
	)
	(segment
		(start 331.538072 -264.043414)
		(end 331.52969 -264.038588)
		(width 0.0889)
		(layer "In2.Cu")
		(net "M_C_CPU0_SB_CA<5>")
	)
	(segment
		(start 343.725246 -264.100564)
		(end 343.702894 -264.017252)
		(width 0.0889)
		(layer "In2.Cu")
		(net "M_C_CPU0_SB_CA<5>")
	)
	(segment
		(start 289.793172 -264.22731)
		(end 289.630358 -264.390124)
		(width 0.14478)
		(layer "In2.Cu")
		(net "M_C_CPU0_SB_CA<5>")
	)
	(segment
		(start 332.478126 -264.043414)
		(end 332.469744 -264.038588)
		(width 0.0889)
		(layer "In2.Cu")
		(net "M_C_CPU0_SB_CA<5>")
	)
	(segment
		(start 333.05242 -264.038588)
		(end 333.044038 -264.043414)
		(width 0.0889)
		(layer "In2.Cu")
		(net "M_C_CPU0_SB_CA<5>")
	)
	(segment
		(start 333.992474 -264.038588)
		(end 333.984092 -264.043414)
		(width 0.0889)
		(layer "In2.Cu")
		(net "M_C_CPU0_SB_CA<5>")
	)
	(segment
		(start 341.878158 -264.043414)
		(end 341.869776 -264.038588)
		(width 0.0889)
		(layer "In2.Cu")
		(net "M_C_CPU0_SB_CA<5>")
	)
	(segment
		(start 327.780142 -264.043668)
		(end 327.756774 -264.030206)
		(width 0.0889)
		(layer "In2.Cu")
		(net "M_C_CPU0_SB_CA<5>")
	)
	(segment
		(start 343.392506 -264.038588)
		(end 343.384124 -264.043414)
		(width 0.0889)
		(layer "In2.Cu")
		(net "M_C_CPU0_SB_CA<5>")
	)
	(segment
		(start 336.238088 -264.043414)
		(end 336.229706 -264.038588)
		(width 0.0889)
		(layer "In2.Cu")
		(net "M_C_CPU0_SB_CA<5>")
	)
	(segment
		(start 337.752436 -264.038588)
		(end 337.744054 -264.043414)
		(width 0.0889)
		(layer "In2.Cu")
		(net "M_C_CPU0_SB_CA<5>")
	)
	(segment
		(start 324.232524 -264.16508)
		(end 323.887084 -264.16508)
		(width 0.0889)
		(layer "In2.Cu")
		(net "M_C_CPU0_SB_CA<5>")
	)
	(segment
		(start 327.806304 -264.058654)
		(end 327.780142 -264.043668)
		(width 0.0889)
		(layer "In2.Cu")
		(net "M_C_CPU0_SB_CA<5>")
	)
	(segment
		(start 289.467544 -264.910062)
		(end 288.60496 -264.910062)
		(width 0.14478)
		(layer "In2.Cu")
		(net "M_C_CPU0_SB_CA<5>")
	)
	(segment
		(start 290.349432 -264.910062)
		(end 290.186618 -264.747248)
		(width 0.14478)
		(layer "In2.Cu")
		(net "M_C_CPU0_SB_CA<5>")
	)
	(segment
		(start 328.718164 -264.043414)
		(end 328.709782 -264.038588)
		(width 0.0889)
		(layer "In2.Cu")
		(net "M_C_CPU0_SB_CA<5>")
	)
	(segment
		(start 308.143148 -264.910062)
		(end 290.349432 -264.910062)
		(width 0.14478)
		(layer "In2.Cu")
		(net "M_C_CPU0_SB_CA<5>")
	)
	(segment
		(start 308.88813 -264.16508)
		(end 308.143148 -264.910062)
		(width 0.14478)
		(layer "In2.Cu")
		(net "M_C_CPU0_SB_CA<5>")
	)
	(segment
		(start 289.630358 -264.747248)
		(end 289.467544 -264.910062)
		(width 0.14478)
		(layer "In2.Cu")
		(net "M_C_CPU0_SB_CA<5>")
	)
	(segment
		(start 343.571068 -264.365994)
		(end 343.725246 -264.100564)
		(width 0.0889)
		(layer "In2.Cu")
		(net "M_C_CPU0_SB_CA<5>")
	)
	(segment
		(start 337.178142 -264.043414)
		(end 337.16976 -264.038588)
		(width 0.0889)
		(layer "In2.Cu")
		(net "M_C_CPU0_SB_CA<5>")
	)
	(segment
		(start 342.452452 -264.038588)
		(end 342.44407 -264.043414)
		(width 0.0889)
		(layer "In2.Cu")
		(net "M_C_CPU0_SB_CA<5>")
	)
	(segment
		(start 290.023804 -264.22731)
		(end 289.793172 -264.22731)
		(width 0.14478)
		(layer "In2.Cu")
		(net "M_C_CPU0_SB_CA<5>")
	)
	(segment
		(start 324.449186 -263.948418)
		(end 324.232524 -264.16508)
		(width 0.0889)
		(layer "In2.Cu")
		(net "M_C_CPU0_SB_CA<5>")
	)
	(segment
		(start 326.489568 -263.948418)
		(end 324.449186 -263.948418)
		(width 0.0889)
		(layer "In2.Cu")
		(net "M_C_CPU0_SB_CA<5>")
	)
	(segment
		(start 323.887084 -264.16508)
		(end 308.88813 -264.16508)
		(width 0.14478)
		(layer "In2.Cu")
		(net "M_C_CPU0_SB_CA<5>")
	)
	(segment
		(start 329.292458 -264.038588)
		(end 329.284076 -264.043414)
		(width 0.0889)
		(layer "In2.Cu")
		(net "M_C_CPU0_SB_CA<5>")
	)
	(segment
		(start 290.186618 -264.390124)
		(end 290.023804 -264.22731)
		(width 0.14478)
		(layer "In2.Cu")
		(net "M_C_CPU0_SB_CA<5>")
	)
	(segment
		(start 327.407778 -264.043414)
		(end 327.378314 -264.060686)
		(width 0.0889)
		(layer "In2.Cu")
		(net "M_C_CPU0_SB_CA<5>")
	)
	(segment
		(start 338.69249 -264.038588)
		(end 338.684108 -264.043414)
		(width 0.0889)
		(layer "In2.Cu")
		(net "M_C_CPU0_SB_CA<5>")
	)
	(arc
		(start 338.118196 -264.043414)
		(mid 337.935945 -263.993064)
		(end 337.752436 -264.038588)
		(width 0.0889)
		(layer "In2.Cu")
		(net "M_C_CPU0_SB_CA<5>")
	)
	(arc
		(start 327.378314 -264.060686)
		(mid 327.106894 -264.120363)
		(end 326.839834 -264.043414)
		(width 0.0889)
		(layer "In2.Cu")
		(net "M_C_CPU0_SB_CA<5>")
	)
	(arc
		(start 332.469744 -264.038588)
		(mid 332.286236 -263.993094)
		(end 332.103984 -264.043414)
		(width 0.0889)
		(layer "In2.Cu")
		(net "M_C_CPU0_SB_CA<5>")
	)
	(arc
		(start 341.869776 -264.038588)
		(mid 341.686268 -263.993094)
		(end 341.504016 -264.043414)
		(width 0.0889)
		(layer "In2.Cu")
		(net "M_C_CPU0_SB_CA<5>")
	)
	(arc
		(start 336.804 -264.043414)
		(mid 336.521044 -264.119591)
		(end 336.238088 -264.043414)
		(width 0.0889)
		(layer "In2.Cu")
		(net "M_C_CPU0_SB_CA<5>")
	)
	(arc
		(start 331.52969 -264.038588)
		(mid 331.346182 -263.993094)
		(end 331.16393 -264.043414)
		(width 0.0889)
		(layer "In2.Cu")
		(net "M_C_CPU0_SB_CA<5>")
	)
	(arc
		(start 329.284076 -264.043414)
		(mid 329.00112 -264.119591)
		(end 328.718164 -264.043414)
		(width 0.0889)
		(layer "In2.Cu")
		(net "M_C_CPU0_SB_CA<5>")
	)
	(arc
		(start 337.744054 -264.043414)
		(mid 337.461098 -264.119591)
		(end 337.178142 -264.043414)
		(width 0.0889)
		(layer "In2.Cu")
		(net "M_C_CPU0_SB_CA<5>")
	)
	(arc
		(start 336.229706 -264.038588)
		(mid 336.046198 -263.993094)
		(end 335.863946 -264.043414)
		(width 0.0889)
		(layer "In2.Cu")
		(net "M_C_CPU0_SB_CA<5>")
	)
	(arc
		(start 335.863946 -264.043414)
		(mid 335.58099 -264.119591)
		(end 335.298034 -264.043414)
		(width 0.0889)
		(layer "In2.Cu")
		(net "M_C_CPU0_SB_CA<5>")
	)
	(arc
		(start 337.16976 -264.038588)
		(mid 336.986252 -263.993094)
		(end 336.804 -264.043414)
		(width 0.0889)
		(layer "In2.Cu")
		(net "M_C_CPU0_SB_CA<5>")
	)
	(arc
		(start 339.05825 -264.043414)
		(mid 338.875999 -263.993064)
		(end 338.69249 -264.038588)
		(width 0.0889)
		(layer "In2.Cu")
		(net "M_C_CPU0_SB_CA<5>")
	)
	(arc
		(start 330.22413 -264.043414)
		(mid 329.941174 -264.119591)
		(end 329.658218 -264.043414)
		(width 0.0889)
		(layer "In2.Cu")
		(net "M_C_CPU0_SB_CA<5>")
	)
	(arc
		(start 332.103984 -264.043414)
		(mid 331.821028 -264.119591)
		(end 331.538072 -264.043414)
		(width 0.0889)
		(layer "In2.Cu")
		(net "M_C_CPU0_SB_CA<5>")
	)
	(arc
		(start 327.756774 -264.030206)
		(mid 327.580632 -263.993414)
		(end 327.407778 -264.043414)
		(width 0.0889)
		(layer "In2.Cu")
		(net "M_C_CPU0_SB_CA<5>")
	)
	(arc
		(start 339.99805 -264.043414)
		(mid 339.811106 -263.993159)
		(end 339.624162 -264.043414)
		(width 0.0889)
		(layer "In2.Cu")
		(net "M_C_CPU0_SB_CA<5>")
	)
	(arc
		(start 342.818212 -264.043414)
		(mid 342.635961 -263.993064)
		(end 342.452452 -264.038588)
		(width 0.0889)
		(layer "In2.Cu")
		(net "M_C_CPU0_SB_CA<5>")
	)
	(arc
		(start 329.658218 -264.043414)
		(mid 329.475967 -263.993064)
		(end 329.292458 -264.038588)
		(width 0.0889)
		(layer "In2.Cu")
		(net "M_C_CPU0_SB_CA<5>")
	)
	(arc
		(start 343.702894 -264.017252)
		(mid 343.545384 -263.994054)
		(end 343.392506 -264.038588)
		(width 0.0889)
		(layer "In2.Cu")
		(net "M_C_CPU0_SB_CA<5>")
	)
	(arc
		(start 330.598018 -264.043414)
		(mid 330.411074 -263.993159)
		(end 330.22413 -264.043414)
		(width 0.0889)
		(layer "In2.Cu")
		(net "M_C_CPU0_SB_CA<5>")
	)
	(arc
		(start 334.924146 -264.043414)
		(mid 334.64119 -264.119591)
		(end 334.358234 -264.043414)
		(width 0.0889)
		(layer "In2.Cu")
		(net "M_C_CPU0_SB_CA<5>")
	)
	(arc
		(start 333.044038 -264.043414)
		(mid 332.761082 -264.119591)
		(end 332.478126 -264.043414)
		(width 0.0889)
		(layer "In2.Cu")
		(net "M_C_CPU0_SB_CA<5>")
	)
	(arc
		(start 339.624162 -264.043414)
		(mid 339.341206 -264.119591)
		(end 339.05825 -264.043414)
		(width 0.0889)
		(layer "In2.Cu")
		(net "M_C_CPU0_SB_CA<5>")
	)
	(arc
		(start 334.358234 -264.043414)
		(mid 334.175983 -263.993064)
		(end 333.992474 -264.038588)
		(width 0.0889)
		(layer "In2.Cu")
		(net "M_C_CPU0_SB_CA<5>")
	)
	(arc
		(start 328.344022 -264.043414)
		(mid 328.077092 -264.119363)
		(end 327.806304 -264.058654)
		(width 0.0889)
		(layer "In2.Cu")
		(net "M_C_CPU0_SB_CA<5>")
	)
	(arc
		(start 342.44407 -264.043414)
		(mid 342.161114 -264.119591)
		(end 341.878158 -264.043414)
		(width 0.0889)
		(layer "In2.Cu")
		(net "M_C_CPU0_SB_CA<5>")
	)
	(arc
		(start 340.929722 -264.038588)
		(mid 340.746214 -263.993094)
		(end 340.563962 -264.043414)
		(width 0.0889)
		(layer "In2.Cu")
		(net "M_C_CPU0_SB_CA<5>")
	)
	(arc
		(start 333.984092 -264.043414)
		(mid 333.701136 -264.119591)
		(end 333.41818 -264.043414)
		(width 0.0889)
		(layer "In2.Cu")
		(net "M_C_CPU0_SB_CA<5>")
	)
	(arc
		(start 343.384124 -264.043414)
		(mid 343.101168 -264.119591)
		(end 342.818212 -264.043414)
		(width 0.0889)
		(layer "In2.Cu")
		(net "M_C_CPU0_SB_CA<5>")
	)
	(arc
		(start 338.684108 -264.043414)
		(mid 338.401152 -264.119591)
		(end 338.118196 -264.043414)
		(width 0.0889)
		(layer "In2.Cu")
		(net "M_C_CPU0_SB_CA<5>")
	)
	(arc
		(start 335.298034 -264.043414)
		(mid 335.11109 -263.993159)
		(end 334.924146 -264.043414)
		(width 0.0889)
		(layer "In2.Cu")
		(net "M_C_CPU0_SB_CA<5>")
	)
	(arc
		(start 341.504016 -264.043414)
		(mid 341.22106 -264.119591)
		(end 340.938104 -264.043414)
		(width 0.0889)
		(layer "In2.Cu")
		(net "M_C_CPU0_SB_CA<5>")
	)
	(arc
		(start 340.563962 -264.043414)
		(mid 340.281006 -264.119591)
		(end 339.99805 -264.043414)
		(width 0.0889)
		(layer "In2.Cu")
		(net "M_C_CPU0_SB_CA<5>")
	)
	(arc
		(start 326.839834 -264.043414)
		(mid 326.67102 -263.972632)
		(end 326.489568 -263.948418)
		(width 0.0889)
		(layer "In2.Cu")
		(net "M_C_CPU0_SB_CA<5>")
	)
	(arc
		(start 328.709782 -264.038588)
		(mid 328.526274 -263.993094)
		(end 328.344022 -264.043414)
		(width 0.0889)
		(layer "In2.Cu")
		(net "M_C_CPU0_SB_CA<5>")
	)
	(arc
		(start 331.16393 -264.043414)
		(mid 330.880974 -264.119591)
		(end 330.598018 -264.043414)
		(width 0.0889)
		(layer "In2.Cu")
		(net "M_C_CPU0_SB_CA<5>")
	)
	(arc
		(start 333.41818 -264.043414)
		(mid 333.235929 -263.993064)
		(end 333.05242 -264.038588)
		(width 0.0889)
		(layer "In2.Cu")
		(net "M_C_CPU0_SB_CA<5>")
	)
	(segment
		(start 344.508074 -263.29005)
		(end 344.041222 -263.555988)
		(width 0.10668)
		(layer "F.Cu")
		(net "M_C_CPU0_SB_CA<4>")
	)
	(segment
		(start 297.033442 -264.43051)
		(end 297.196256 -264.267696)
		(width 0.14478)
		(layer "In2.Cu")
		(net "M_C_CPU0_SB_CA<4>")
	)
	(segment
		(start 298.47159 -263.689338)
		(end 298.702222 -263.689338)
		(width 0.14478)
		(layer "In2.Cu")
		(net "M_C_CPU0_SB_CA<4>")
	)
	(segment
		(start 297.752516 -264.267696)
		(end 297.91533 -264.43051)
		(width 0.14478)
		(layer "In2.Cu")
		(net "M_C_CPU0_SB_CA<4>")
	)
	(segment
		(start 292.280086 -264.48512)
		(end 293.083742 -263.681464)
		(width 0.14478)
		(layer "In2.Cu")
		(net "M_C_CPU0_SB_CA<4>")
	)
	(segment
		(start 299.072808 -264.059924)
		(end 300.193964 -264.059924)
		(width 0.14478)
		(layer "In2.Cu")
		(net "M_C_CPU0_SB_CA<4>")
	)
	(segment
		(start 293.839138 -264.451338)
		(end 294.001952 -264.288524)
		(width 0.14478)
		(layer "In2.Cu")
		(net "M_C_CPU0_SB_CA<4>")
	)
	(segment
		(start 301.92853 -263.66851)
		(end 302.091344 -263.831324)
		(width 0.14478)
		(layer "In2.Cu")
		(net "M_C_CPU0_SB_CA<4>")
	)
	(segment
		(start 343.27973 -263.883394)
		(end 343.288112 -263.878568)
		(width 0.0889)
		(layer "In2.Cu")
		(net "M_C_CPU0_SB_CA<4>")
	)
	(segment
		(start 294.001952 -264.288524)
		(end 294.001952 -263.831324)
		(width 0.14478)
		(layer "In2.Cu")
		(net "M_C_CPU0_SB_CA<4>")
	)
	(segment
		(start 302.091344 -264.288524)
		(end 302.254158 -264.451338)
		(width 0.14478)
		(layer "In2.Cu")
		(net "M_C_CPU0_SB_CA<4>")
	)
	(segment
		(start 327.875646 -263.878314)
		(end 327.900538 -263.892538)
		(width 0.0889)
		(layer "In2.Cu")
		(net "M_C_CPU0_SB_CA<4>")
	)
	(segment
		(start 327.849484 -263.863328)
		(end 327.875646 -263.878314)
		(width 0.0889)
		(layer "In2.Cu")
		(net "M_C_CPU0_SB_CA<4>")
	)
	(segment
		(start 334.819752 -263.883394)
		(end 334.828134 -263.878568)
		(width 0.0889)
		(layer "In2.Cu")
		(net "M_C_CPU0_SB_CA<4>")
	)
	(segment
		(start 294.164766 -263.66851)
		(end 294.395398 -263.66851)
		(width 0.14478)
		(layer "In2.Cu")
		(net "M_C_CPU0_SB_CA<4>")
	)
	(segment
		(start 301.141638 -264.451338)
		(end 301.37227 -264.451338)
		(width 0.14478)
		(layer "In2.Cu")
		(net "M_C_CPU0_SB_CA<4>")
	)
	(segment
		(start 301.697898 -263.66851)
		(end 301.92853 -263.66851)
		(width 0.14478)
		(layer "In2.Cu")
		(net "M_C_CPU0_SB_CA<4>")
	)
	(segment
		(start 298.308776 -264.267696)
		(end 298.308776 -263.852152)
		(width 0.14478)
		(layer "In2.Cu")
		(net "M_C_CPU0_SB_CA<4>")
	)
	(segment
		(start 296.432224 -264.059924)
		(end 296.80281 -264.43051)
		(width 0.14478)
		(layer "In2.Cu")
		(net "M_C_CPU0_SB_CA<4>")
	)
	(segment
		(start 333.879698 -263.883394)
		(end 333.88808 -263.878568)
		(width 0.0889)
		(layer "In2.Cu")
		(net "M_C_CPU0_SB_CA<4>")
	)
	(segment
		(start 303.046384 -264.059924)
		(end 308.208426 -264.059924)
		(width 0.14478)
		(layer "In2.Cu")
		(net "M_C_CPU0_SB_CA<4>")
	)
	(segment
		(start 343.790778 -263.846818)
		(end 343.887044 -263.821418)
		(width 0.0889)
		(layer "In2.Cu")
		(net "M_C_CPU0_SB_CA<4>")
	)
	(segment
		(start 302.091344 -263.831324)
		(end 302.091344 -264.288524)
		(width 0.14478)
		(layer "In2.Cu")
		(net "M_C_CPU0_SB_CA<4>")
	)
	(segment
		(start 323.893434 -263.71042)
		(end 326.544686 -263.71042)
		(width 0.0889)
		(layer "In2.Cu")
		(net "M_C_CPU0_SB_CA<4>")
	)
	(segment
		(start 301.535084 -264.288524)
		(end 301.535084 -263.831324)
		(width 0.14478)
		(layer "In2.Cu")
		(net "M_C_CPU0_SB_CA<4>")
	)
	(segment
		(start 300.585378 -263.66851)
		(end 300.81601 -263.66851)
		(width 0.14478)
		(layer "In2.Cu")
		(net "M_C_CPU0_SB_CA<4>")
	)
	(segment
		(start 343.887044 -263.821418)
		(end 344.041222 -263.555988)
		(width 0.0889)
		(layer "In2.Cu")
		(net "M_C_CPU0_SB_CA<4>")
	)
	(segment
		(start 326.925686 -263.868408)
		(end 326.9361 -263.878568)
		(width 0.0889)
		(layer "In2.Cu")
		(net "M_C_CPU0_SB_CA<4>")
	)
	(segment
		(start 301.37227 -264.451338)
		(end 301.535084 -264.288524)
		(width 0.14478)
		(layer "In2.Cu")
		(net "M_C_CPU0_SB_CA<4>")
	)
	(segment
		(start 297.35907 -263.689338)
		(end 297.589702 -263.689338)
		(width 0.14478)
		(layer "In2.Cu")
		(net "M_C_CPU0_SB_CA<4>")
	)
	(segment
		(start 300.978824 -263.831324)
		(end 300.978824 -264.288524)
		(width 0.14478)
		(layer "In2.Cu")
		(net "M_C_CPU0_SB_CA<4>")
	)
	(segment
		(start 297.196256 -264.267696)
		(end 297.196256 -263.852152)
		(width 0.14478)
		(layer "In2.Cu")
		(net "M_C_CPU0_SB_CA<4>")
	)
	(segment
		(start 338.579714 -263.883394)
		(end 338.588096 -263.878568)
		(width 0.0889)
		(layer "In2.Cu")
		(net "M_C_CPU0_SB_CA<4>")
	)
	(segment
		(start 297.752516 -263.852152)
		(end 297.752516 -264.267696)
		(width 0.14478)
		(layer "In2.Cu")
		(net "M_C_CPU0_SB_CA<4>")
	)
	(segment
		(start 294.786812 -264.059924)
		(end 296.432224 -264.059924)
		(width 0.14478)
		(layer "In2.Cu")
		(net "M_C_CPU0_SB_CA<4>")
	)
	(segment
		(start 330.69403 -263.878568)
		(end 330.702412 -263.883394)
		(width 0.0889)
		(layer "In2.Cu")
		(net "M_C_CPU0_SB_CA<4>")
	)
	(segment
		(start 336.3341 -263.878568)
		(end 336.342482 -263.883394)
		(width 0.0889)
		(layer "In2.Cu")
		(net "M_C_CPU0_SB_CA<4>")
	)
	(segment
		(start 340.094062 -263.878568)
		(end 340.102444 -263.883394)
		(width 0.0889)
		(layer "In2.Cu")
		(net "M_C_CPU0_SB_CA<4>")
	)
	(segment
		(start 296.80281 -264.43051)
		(end 297.033442 -264.43051)
		(width 0.14478)
		(layer "In2.Cu")
		(net "M_C_CPU0_SB_CA<4>")
	)
	(segment
		(start 298.145962 -264.43051)
		(end 298.308776 -264.267696)
		(width 0.14478)
		(layer "In2.Cu")
		(net "M_C_CPU0_SB_CA<4>")
	)
	(segment
		(start 302.65497 -264.451338)
		(end 303.046384 -264.059924)
		(width 0.14478)
		(layer "In2.Cu")
		(net "M_C_CPU0_SB_CA<4>")
	)
	(segment
		(start 339.519768 -263.883394)
		(end 339.52815 -263.878568)
		(width 0.0889)
		(layer "In2.Cu")
		(net "M_C_CPU0_SB_CA<4>")
	)
	(segment
		(start 297.196256 -263.852152)
		(end 297.35907 -263.689338)
		(width 0.14478)
		(layer "In2.Cu")
		(net "M_C_CPU0_SB_CA<4>")
	)
	(segment
		(start 300.978824 -264.288524)
		(end 301.141638 -264.451338)
		(width 0.14478)
		(layer "In2.Cu")
		(net "M_C_CPU0_SB_CA<4>")
	)
	(segment
		(start 327.289414 -263.891522)
		(end 327.311766 -263.878568)
		(width 0.0889)
		(layer "In2.Cu")
		(net "M_C_CPU0_SB_CA<4>")
	)
	(segment
		(start 301.535084 -263.831324)
		(end 301.697898 -263.66851)
		(width 0.14478)
		(layer "In2.Cu")
		(net "M_C_CPU0_SB_CA<4>")
	)
	(segment
		(start 297.589702 -263.689338)
		(end 297.752516 -263.852152)
		(width 0.14478)
		(layer "In2.Cu")
		(net "M_C_CPU0_SB_CA<4>")
	)
	(segment
		(start 297.91533 -264.43051)
		(end 298.145962 -264.43051)
		(width 0.14478)
		(layer "In2.Cu")
		(net "M_C_CPU0_SB_CA<4>")
	)
	(segment
		(start 298.702222 -263.689338)
		(end 299.072808 -264.059924)
		(width 0.14478)
		(layer "In2.Cu")
		(net "M_C_CPU0_SB_CA<4>")
	)
	(segment
		(start 331.634084 -263.878568)
		(end 331.642466 -263.883394)
		(width 0.0889)
		(layer "In2.Cu")
		(net "M_C_CPU0_SB_CA<4>")
	)
	(segment
		(start 300.81601 -263.66851)
		(end 300.978824 -263.831324)
		(width 0.14478)
		(layer "In2.Cu")
		(net "M_C_CPU0_SB_CA<4>")
	)
	(segment
		(start 293.295832 -263.681464)
		(end 293.445692 -263.831324)
		(width 0.14478)
		(layer "In2.Cu")
		(net "M_C_CPU0_SB_CA<4>")
	)
	(segment
		(start 293.083742 -263.681464)
		(end 293.295832 -263.681464)
		(width 0.14478)
		(layer "In2.Cu")
		(net "M_C_CPU0_SB_CA<4>")
	)
	(segment
		(start 330.119736 -263.883394)
		(end 330.128118 -263.878568)
		(width 0.0889)
		(layer "In2.Cu")
		(net "M_C_CPU0_SB_CA<4>")
	)
	(segment
		(start 308.208426 -264.059924)
		(end 308.55793 -263.71042)
		(width 0.14478)
		(layer "In2.Cu")
		(net "M_C_CPU0_SB_CA<4>")
	)
	(segment
		(start 294.001952 -263.831324)
		(end 294.164766 -263.66851)
		(width 0.14478)
		(layer "In2.Cu")
		(net "M_C_CPU0_SB_CA<4>")
	)
	(segment
		(start 341.034116 -263.878568)
		(end 341.042498 -263.883394)
		(width 0.0889)
		(layer "In2.Cu")
		(net "M_C_CPU0_SB_CA<4>")
	)
	(segment
		(start 335.394046 -263.878568)
		(end 335.402428 -263.883394)
		(width 0.0889)
		(layer "In2.Cu")
		(net "M_C_CPU0_SB_CA<4>")
	)
	(segment
		(start 300.193964 -264.059924)
		(end 300.585378 -263.66851)
		(width 0.14478)
		(layer "In2.Cu")
		(net "M_C_CPU0_SB_CA<4>")
	)
	(segment
		(start 302.254158 -264.451338)
		(end 302.65497 -264.451338)
		(width 0.14478)
		(layer "In2.Cu")
		(net "M_C_CPU0_SB_CA<4>")
	)
	(segment
		(start 294.395398 -263.66851)
		(end 294.786812 -264.059924)
		(width 0.14478)
		(layer "In2.Cu")
		(net "M_C_CPU0_SB_CA<4>")
	)
	(segment
		(start 308.55793 -263.71042)
		(end 323.893434 -263.71042)
		(width 0.14478)
		(layer "In2.Cu")
		(net "M_C_CPU0_SB_CA<4>")
	)
	(segment
		(start 298.308776 -263.852152)
		(end 298.47159 -263.689338)
		(width 0.14478)
		(layer "In2.Cu")
		(net "M_C_CPU0_SB_CA<4>")
	)
	(segment
		(start 293.608506 -264.451338)
		(end 293.839138 -264.451338)
		(width 0.14478)
		(layer "In2.Cu")
		(net "M_C_CPU0_SB_CA<4>")
	)
	(segment
		(start 293.445692 -264.288524)
		(end 293.608506 -264.451338)
		(width 0.14478)
		(layer "In2.Cu")
		(net "M_C_CPU0_SB_CA<4>")
	)
	(segment
		(start 293.445692 -263.831324)
		(end 293.445692 -264.288524)
		(width 0.14478)
		(layer "In2.Cu")
		(net "M_C_CPU0_SB_CA<4>")
	)
	(arc
		(start 329.753976 -263.878568)
		(mid 329.936227 -263.928918)
		(end 330.119736 -263.883394)
		(width 0.0889)
		(layer "In2.Cu")
		(net "M_C_CPU0_SB_CA<4>")
	)
	(arc
		(start 334.828134 -263.878568)
		(mid 335.11109 -263.802391)
		(end 335.394046 -263.878568)
		(width 0.0889)
		(layer "In2.Cu")
		(net "M_C_CPU0_SB_CA<4>")
	)
	(arc
		(start 341.408258 -263.878568)
		(mid 341.691214 -263.802391)
		(end 341.97417 -263.878568)
		(width 0.0889)
		(layer "In2.Cu")
		(net "M_C_CPU0_SB_CA<4>")
	)
	(arc
		(start 332.574138 -263.878568)
		(mid 332.761082 -263.928823)
		(end 332.948026 -263.878568)
		(width 0.0889)
		(layer "In2.Cu")
		(net "M_C_CPU0_SB_CA<4>")
	)
	(arc
		(start 342.348058 -263.878568)
		(mid 342.631014 -263.802391)
		(end 342.91397 -263.878568)
		(width 0.0889)
		(layer "In2.Cu")
		(net "M_C_CPU0_SB_CA<4>")
	)
	(arc
		(start 331.642466 -263.883394)
		(mid 331.825974 -263.928888)
		(end 332.008226 -263.878568)
		(width 0.0889)
		(layer "In2.Cu")
		(net "M_C_CPU0_SB_CA<4>")
	)
	(arc
		(start 340.102444 -263.883394)
		(mid 340.285952 -263.928888)
		(end 340.468204 -263.878568)
		(width 0.0889)
		(layer "In2.Cu")
		(net "M_C_CPU0_SB_CA<4>")
	)
	(arc
		(start 342.91397 -263.878568)
		(mid 343.096221 -263.928918)
		(end 343.27973 -263.883394)
		(width 0.0889)
		(layer "In2.Cu")
		(net "M_C_CPU0_SB_CA<4>")
	)
	(arc
		(start 329.188064 -263.878568)
		(mid 329.47102 -263.802391)
		(end 329.753976 -263.878568)
		(width 0.0889)
		(layer "In2.Cu")
		(net "M_C_CPU0_SB_CA<4>")
	)
	(arc
		(start 335.768188 -263.878568)
		(mid 336.051144 -263.802391)
		(end 336.3341 -263.878568)
		(width 0.0889)
		(layer "In2.Cu")
		(net "M_C_CPU0_SB_CA<4>")
	)
	(arc
		(start 338.588096 -263.878568)
		(mid 338.871052 -263.802391)
		(end 339.154008 -263.878568)
		(width 0.0889)
		(layer "In2.Cu")
		(net "M_C_CPU0_SB_CA<4>")
	)
	(arc
		(start 339.154008 -263.878568)
		(mid 339.336259 -263.928918)
		(end 339.519768 -263.883394)
		(width 0.0889)
		(layer "In2.Cu")
		(net "M_C_CPU0_SB_CA<4>")
	)
	(arc
		(start 332.008226 -263.878568)
		(mid 332.291182 -263.802391)
		(end 332.574138 -263.878568)
		(width 0.0889)
		(layer "In2.Cu")
		(net "M_C_CPU0_SB_CA<4>")
	)
	(arc
		(start 332.948026 -263.878568)
		(mid 333.230982 -263.802391)
		(end 333.513938 -263.878568)
		(width 0.0889)
		(layer "In2.Cu")
		(net "M_C_CPU0_SB_CA<4>")
	)
	(arc
		(start 335.402428 -263.883394)
		(mid 335.585936 -263.928888)
		(end 335.768188 -263.878568)
		(width 0.0889)
		(layer "In2.Cu")
		(net "M_C_CPU0_SB_CA<4>")
	)
	(arc
		(start 326.544686 -263.71042)
		(mid 326.750894 -263.751531)
		(end 326.925686 -263.868408)
		(width 0.0889)
		(layer "In2.Cu")
		(net "M_C_CPU0_SB_CA<4>")
	)
	(arc
		(start 333.88808 -263.878568)
		(mid 334.171036 -263.802391)
		(end 334.453992 -263.878568)
		(width 0.0889)
		(layer "In2.Cu")
		(net "M_C_CPU0_SB_CA<4>")
	)
	(arc
		(start 334.453992 -263.878568)
		(mid 334.636243 -263.928918)
		(end 334.819752 -263.883394)
		(width 0.0889)
		(layer "In2.Cu")
		(net "M_C_CPU0_SB_CA<4>")
	)
	(arc
		(start 326.9361 -263.878568)
		(mid 327.111128 -263.929467)
		(end 327.289414 -263.891522)
		(width 0.0889)
		(layer "In2.Cu")
		(net "M_C_CPU0_SB_CA<4>")
	)
	(arc
		(start 339.52815 -263.878568)
		(mid 339.811106 -263.802391)
		(end 340.094062 -263.878568)
		(width 0.0889)
		(layer "In2.Cu")
		(net "M_C_CPU0_SB_CA<4>")
	)
	(arc
		(start 341.042498 -263.883394)
		(mid 341.226006 -263.928888)
		(end 341.408258 -263.878568)
		(width 0.0889)
		(layer "In2.Cu")
		(net "M_C_CPU0_SB_CA<4>")
	)
	(arc
		(start 333.513938 -263.878568)
		(mid 333.696189 -263.928918)
		(end 333.879698 -263.883394)
		(width 0.0889)
		(layer "In2.Cu")
		(net "M_C_CPU0_SB_CA<4>")
	)
	(arc
		(start 338.213954 -263.878568)
		(mid 338.396205 -263.928918)
		(end 338.579714 -263.883394)
		(width 0.0889)
		(layer "In2.Cu")
		(net "M_C_CPU0_SB_CA<4>")
	)
	(arc
		(start 343.288112 -263.878568)
		(mid 343.535708 -263.80339)
		(end 343.790778 -263.846818)
		(width 0.0889)
		(layer "In2.Cu")
		(net "M_C_CPU0_SB_CA<4>")
	)
	(arc
		(start 341.97417 -263.878568)
		(mid 342.161114 -263.928823)
		(end 342.348058 -263.878568)
		(width 0.0889)
		(layer "In2.Cu")
		(net "M_C_CPU0_SB_CA<4>")
	)
	(arc
		(start 328.248264 -263.878568)
		(mid 328.53122 -263.802391)
		(end 328.814176 -263.878568)
		(width 0.0889)
		(layer "In2.Cu")
		(net "M_C_CPU0_SB_CA<4>")
	)
	(arc
		(start 327.311766 -263.878568)
		(mid 327.578696 -263.802619)
		(end 327.849484 -263.863328)
		(width 0.0889)
		(layer "In2.Cu")
		(net "M_C_CPU0_SB_CA<4>")
	)
	(arc
		(start 330.128118 -263.878568)
		(mid 330.411074 -263.802391)
		(end 330.69403 -263.878568)
		(width 0.0889)
		(layer "In2.Cu")
		(net "M_C_CPU0_SB_CA<4>")
	)
	(arc
		(start 336.708242 -263.878568)
		(mid 336.991198 -263.802391)
		(end 337.274154 -263.878568)
		(width 0.0889)
		(layer "In2.Cu")
		(net "M_C_CPU0_SB_CA<4>")
	)
	(arc
		(start 331.068172 -263.878568)
		(mid 331.351128 -263.802391)
		(end 331.634084 -263.878568)
		(width 0.0889)
		(layer "In2.Cu")
		(net "M_C_CPU0_SB_CA<4>")
	)
	(arc
		(start 340.468204 -263.878568)
		(mid 340.75116 -263.802391)
		(end 341.034116 -263.878568)
		(width 0.0889)
		(layer "In2.Cu")
		(net "M_C_CPU0_SB_CA<4>")
	)
	(arc
		(start 337.274154 -263.878568)
		(mid 337.461098 -263.928823)
		(end 337.648042 -263.878568)
		(width 0.0889)
		(layer "In2.Cu")
		(net "M_C_CPU0_SB_CA<4>")
	)
	(arc
		(start 327.900538 -263.892538)
		(mid 328.076118 -263.928558)
		(end 328.248264 -263.878568)
		(width 0.0889)
		(layer "In2.Cu")
		(net "M_C_CPU0_SB_CA<4>")
	)
	(arc
		(start 330.702412 -263.883394)
		(mid 330.88592 -263.928888)
		(end 331.068172 -263.878568)
		(width 0.0889)
		(layer "In2.Cu")
		(net "M_C_CPU0_SB_CA<4>")
	)
	(arc
		(start 336.342482 -263.883394)
		(mid 336.52599 -263.928888)
		(end 336.708242 -263.878568)
		(width 0.0889)
		(layer "In2.Cu")
		(net "M_C_CPU0_SB_CA<4>")
	)
	(arc
		(start 337.648042 -263.878568)
		(mid 337.930998 -263.802391)
		(end 338.213954 -263.878568)
		(width 0.0889)
		(layer "In2.Cu")
		(net "M_C_CPU0_SB_CA<4>")
	)
	(arc
		(start 328.814176 -263.878568)
		(mid 329.00112 -263.928823)
		(end 329.188064 -263.878568)
		(width 0.0889)
		(layer "In2.Cu")
		(net "M_C_CPU0_SB_CA<4>")
	)
	(segment
		(start 342.627966 -263.29005)
		(end 342.161114 -263.555988)
		(width 0.10668)
		(layer "F.Cu")
		(net "M_C_CPU0_SB_CA<3>")
	)
	(segment
		(start 335.402428 -263.228582)
		(end 335.394046 -263.233408)
		(width 0.0889)
		(layer "In2.Cu")
		(net "M_C_CPU0_SB_CA<3>")
	)
	(segment
		(start 342.315038 -263.290558)
		(end 342.292686 -263.207246)
		(width 0.0889)
		(layer "In2.Cu")
		(net "M_C_CPU0_SB_CA<3>")
	)
	(segment
		(start 333.88808 -263.233408)
		(end 333.879698 -263.228582)
		(width 0.0889)
		(layer "In2.Cu")
		(net "M_C_CPU0_SB_CA<3>")
	)
	(segment
		(start 324.177914 -263.21004)
		(end 323.906134 -263.21004)
		(width 0.0889)
		(layer "In2.Cu")
		(net "M_C_CPU0_SB_CA<3>")
	)
	(segment
		(start 325.970646 -262.884158)
		(end 324.503796 -262.884158)
		(width 0.0889)
		(layer "In2.Cu")
		(net "M_C_CPU0_SB_CA<3>")
	)
	(segment
		(start 339.52815 -263.233408)
		(end 339.519768 -263.228582)
		(width 0.0889)
		(layer "In2.Cu")
		(net "M_C_CPU0_SB_CA<3>")
	)
	(segment
		(start 330.702412 -263.228582)
		(end 330.69403 -263.233408)
		(width 0.0889)
		(layer "In2.Cu")
		(net "M_C_CPU0_SB_CA<3>")
	)
	(segment
		(start 323.906134 -263.21004)
		(end 288.60496 -263.21004)
		(width 0.14478)
		(layer "In2.Cu")
		(net "M_C_CPU0_SB_CA<3>")
	)
	(segment
		(start 326.404986 -263.253982)
		(end 326.251316 -263.164828)
		(width 0.0889)
		(layer "In2.Cu")
		(net "M_C_CPU0_SB_CA<3>")
	)
	(segment
		(start 327.875138 -263.233662)
		(end 327.853548 -263.246108)
		(width 0.0889)
		(layer "In2.Cu")
		(net "M_C_CPU0_SB_CA<3>")
	)
	(segment
		(start 336.342482 -263.228582)
		(end 336.3341 -263.233408)
		(width 0.0889)
		(layer "In2.Cu")
		(net "M_C_CPU0_SB_CA<3>")
	)
	(segment
		(start 327.896982 -263.221216)
		(end 327.875138 -263.233662)
		(width 0.0889)
		(layer "In2.Cu")
		(net "M_C_CPU0_SB_CA<3>")
	)
	(segment
		(start 342.161114 -263.555988)
		(end 342.315038 -263.290558)
		(width 0.0889)
		(layer "In2.Cu")
		(net "M_C_CPU0_SB_CA<3>")
	)
	(segment
		(start 327.31075 -263.233408)
		(end 327.291954 -263.222486)
		(width 0.0889)
		(layer "In2.Cu")
		(net "M_C_CPU0_SB_CA<3>")
	)
	(segment
		(start 324.503796 -262.884158)
		(end 324.177914 -263.21004)
		(width 0.0889)
		(layer "In2.Cu")
		(net "M_C_CPU0_SB_CA<3>")
	)
	(segment
		(start 326.251316 -263.164828)
		(end 325.970646 -262.884158)
		(width 0.0889)
		(layer "In2.Cu")
		(net "M_C_CPU0_SB_CA<3>")
	)
	(segment
		(start 330.128118 -263.233408)
		(end 330.119736 -263.228582)
		(width 0.0889)
		(layer "In2.Cu")
		(net "M_C_CPU0_SB_CA<3>")
	)
	(segment
		(start 288.60496 -263.21004)
		(end 288.180018 -263.634982)
		(width 0.14478)
		(layer "In2.Cu")
		(net "M_C_CPU0_SB_CA<3>")
	)
	(segment
		(start 338.588096 -263.233408)
		(end 338.579714 -263.228582)
		(width 0.0889)
		(layer "In2.Cu")
		(net "M_C_CPU0_SB_CA<3>")
	)
	(segment
		(start 334.828134 -263.233408)
		(end 334.819752 -263.228582)
		(width 0.0889)
		(layer "In2.Cu")
		(net "M_C_CPU0_SB_CA<3>")
	)
	(segment
		(start 341.042498 -263.228582)
		(end 341.034116 -263.233408)
		(width 0.0889)
		(layer "In2.Cu")
		(net "M_C_CPU0_SB_CA<3>")
	)
	(segment
		(start 331.642466 -263.228582)
		(end 331.634084 -263.233408)
		(width 0.0889)
		(layer "In2.Cu")
		(net "M_C_CPU0_SB_CA<3>")
	)
	(segment
		(start 340.102444 -263.228582)
		(end 340.094062 -263.233408)
		(width 0.0889)
		(layer "In2.Cu")
		(net "M_C_CPU0_SB_CA<3>")
	)
	(arc
		(start 328.248264 -263.233408)
		(mid 328.07416 -263.183374)
		(end 327.896982 -263.221216)
		(width 0.0889)
		(layer "In2.Cu")
		(net "M_C_CPU0_SB_CA<3>")
	)
	(arc
		(start 329.753976 -263.233408)
		(mid 329.47102 -263.309585)
		(end 329.188064 -263.233408)
		(width 0.0889)
		(layer "In2.Cu")
		(net "M_C_CPU0_SB_CA<3>")
	)
	(arc
		(start 330.69403 -263.233408)
		(mid 330.411074 -263.309585)
		(end 330.128118 -263.233408)
		(width 0.0889)
		(layer "In2.Cu")
		(net "M_C_CPU0_SB_CA<3>")
	)
	(arc
		(start 326.935592 -263.233408)
		(mid 326.672872 -263.309932)
		(end 326.404986 -263.253982)
		(width 0.0889)
		(layer "In2.Cu")
		(net "M_C_CPU0_SB_CA<3>")
	)
	(arc
		(start 333.879698 -263.228582)
		(mid 333.69619 -263.183088)
		(end 333.513938 -263.233408)
		(width 0.0889)
		(layer "In2.Cu")
		(net "M_C_CPU0_SB_CA<3>")
	)
	(arc
		(start 327.291954 -263.222486)
		(mid 327.112383 -263.182669)
		(end 326.935592 -263.233408)
		(width 0.0889)
		(layer "In2.Cu")
		(net "M_C_CPU0_SB_CA<3>")
	)
	(arc
		(start 339.519768 -263.228582)
		(mid 339.33626 -263.183088)
		(end 339.154008 -263.233408)
		(width 0.0889)
		(layer "In2.Cu")
		(net "M_C_CPU0_SB_CA<3>")
	)
	(arc
		(start 335.768188 -263.233408)
		(mid 335.585937 -263.183058)
		(end 335.402428 -263.228582)
		(width 0.0889)
		(layer "In2.Cu")
		(net "M_C_CPU0_SB_CA<3>")
	)
	(arc
		(start 327.853548 -263.246108)
		(mid 327.580519 -263.309427)
		(end 327.31075 -263.233408)
		(width 0.0889)
		(layer "In2.Cu")
		(net "M_C_CPU0_SB_CA<3>")
	)
	(arc
		(start 334.453992 -263.233408)
		(mid 334.171036 -263.309585)
		(end 333.88808 -263.233408)
		(width 0.0889)
		(layer "In2.Cu")
		(net "M_C_CPU0_SB_CA<3>")
	)
	(arc
		(start 340.468204 -263.233408)
		(mid 340.285953 -263.183058)
		(end 340.102444 -263.228582)
		(width 0.0889)
		(layer "In2.Cu")
		(net "M_C_CPU0_SB_CA<3>")
	)
	(arc
		(start 339.154008 -263.233408)
		(mid 338.871052 -263.309585)
		(end 338.588096 -263.233408)
		(width 0.0889)
		(layer "In2.Cu")
		(net "M_C_CPU0_SB_CA<3>")
	)
	(arc
		(start 332.008226 -263.233408)
		(mid 331.825975 -263.183058)
		(end 331.642466 -263.228582)
		(width 0.0889)
		(layer "In2.Cu")
		(net "M_C_CPU0_SB_CA<3>")
	)
	(arc
		(start 332.948026 -263.233408)
		(mid 332.761082 -263.183153)
		(end 332.574138 -263.233408)
		(width 0.0889)
		(layer "In2.Cu")
		(net "M_C_CPU0_SB_CA<3>")
	)
	(arc
		(start 336.3341 -263.233408)
		(mid 336.051144 -263.309585)
		(end 335.768188 -263.233408)
		(width 0.0889)
		(layer "In2.Cu")
		(net "M_C_CPU0_SB_CA<3>")
	)
	(arc
		(start 333.513938 -263.233408)
		(mid 333.230982 -263.309585)
		(end 332.948026 -263.233408)
		(width 0.0889)
		(layer "In2.Cu")
		(net "M_C_CPU0_SB_CA<3>")
	)
	(arc
		(start 341.97417 -263.233408)
		(mid 341.691214 -263.309585)
		(end 341.408258 -263.233408)
		(width 0.0889)
		(layer "In2.Cu")
		(net "M_C_CPU0_SB_CA<3>")
	)
	(arc
		(start 342.292686 -263.207246)
		(mid 342.130497 -263.184511)
		(end 341.97417 -263.233408)
		(width 0.0889)
		(layer "In2.Cu")
		(net "M_C_CPU0_SB_CA<3>")
	)
	(arc
		(start 337.648042 -263.233408)
		(mid 337.461098 -263.183153)
		(end 337.274154 -263.233408)
		(width 0.0889)
		(layer "In2.Cu")
		(net "M_C_CPU0_SB_CA<3>")
	)
	(arc
		(start 337.274154 -263.233408)
		(mid 336.991198 -263.309585)
		(end 336.708242 -263.233408)
		(width 0.0889)
		(layer "In2.Cu")
		(net "M_C_CPU0_SB_CA<3>")
	)
	(arc
		(start 336.708242 -263.233408)
		(mid 336.525991 -263.183058)
		(end 336.342482 -263.228582)
		(width 0.0889)
		(layer "In2.Cu")
		(net "M_C_CPU0_SB_CA<3>")
	)
	(arc
		(start 330.119736 -263.228582)
		(mid 329.936228 -263.183088)
		(end 329.753976 -263.233408)
		(width 0.0889)
		(layer "In2.Cu")
		(net "M_C_CPU0_SB_CA<3>")
	)
	(arc
		(start 329.188064 -263.233408)
		(mid 329.00112 -263.183153)
		(end 328.814176 -263.233408)
		(width 0.0889)
		(layer "In2.Cu")
		(net "M_C_CPU0_SB_CA<3>")
	)
	(arc
		(start 332.574138 -263.233408)
		(mid 332.291182 -263.309585)
		(end 332.008226 -263.233408)
		(width 0.0889)
		(layer "In2.Cu")
		(net "M_C_CPU0_SB_CA<3>")
	)
	(arc
		(start 328.814176 -263.233408)
		(mid 328.53122 -263.309585)
		(end 328.248264 -263.233408)
		(width 0.0889)
		(layer "In2.Cu")
		(net "M_C_CPU0_SB_CA<3>")
	)
	(arc
		(start 340.094062 -263.233408)
		(mid 339.811106 -263.309585)
		(end 339.52815 -263.233408)
		(width 0.0889)
		(layer "In2.Cu")
		(net "M_C_CPU0_SB_CA<3>")
	)
	(arc
		(start 331.068172 -263.233408)
		(mid 330.885921 -263.183058)
		(end 330.702412 -263.228582)
		(width 0.0889)
		(layer "In2.Cu")
		(net "M_C_CPU0_SB_CA<3>")
	)
	(arc
		(start 335.394046 -263.233408)
		(mid 335.11109 -263.309585)
		(end 334.828134 -263.233408)
		(width 0.0889)
		(layer "In2.Cu")
		(net "M_C_CPU0_SB_CA<3>")
	)
	(arc
		(start 338.213954 -263.233408)
		(mid 337.930998 -263.309585)
		(end 337.648042 -263.233408)
		(width 0.0889)
		(layer "In2.Cu")
		(net "M_C_CPU0_SB_CA<3>")
	)
	(arc
		(start 341.408258 -263.233408)
		(mid 341.226007 -263.183058)
		(end 341.042498 -263.228582)
		(width 0.0889)
		(layer "In2.Cu")
		(net "M_C_CPU0_SB_CA<3>")
	)
	(arc
		(start 338.579714 -263.228582)
		(mid 338.396206 -263.183088)
		(end 338.213954 -263.233408)
		(width 0.0889)
		(layer "In2.Cu")
		(net "M_C_CPU0_SB_CA<3>")
	)
	(arc
		(start 331.634084 -263.233408)
		(mid 331.351128 -263.309585)
		(end 331.068172 -263.233408)
		(width 0.0889)
		(layer "In2.Cu")
		(net "M_C_CPU0_SB_CA<3>")
	)
	(arc
		(start 341.034116 -263.233408)
		(mid 340.75116 -263.309585)
		(end 340.468204 -263.233408)
		(width 0.0889)
		(layer "In2.Cu")
		(net "M_C_CPU0_SB_CA<3>")
	)
	(arc
		(start 334.819752 -263.228582)
		(mid 334.636244 -263.183088)
		(end 334.453992 -263.233408)
		(width 0.0889)
		(layer "In2.Cu")
		(net "M_C_CPU0_SB_CA<3>")
	)
	(segment
		(start 343.097866 -262.480044)
		(end 342.631014 -262.745982)
		(width 0.10668)
		(layer "F.Cu")
		(net "M_C_CPU0_SB_CA<2>")
	)
	(segment
		(start 301.95901 -262.579612)
		(end 301.95901 -262.154924)
		(width 0.14478)
		(layer "In2.Cu")
		(net "M_C_CPU0_SB_CA<2>")
	)
	(segment
		(start 297.777662 -262.14324)
		(end 297.614848 -261.980426)
		(width 0.14478)
		(layer "In2.Cu")
		(net "M_C_CPU0_SB_CA<2>")
	)
	(segment
		(start 294.566848 -262.167116)
		(end 294.404034 -262.004302)
		(width 0.14478)
		(layer "In2.Cu")
		(net "M_C_CPU0_SB_CA<2>")
	)
	(segment
		(start 300.077886 -262.367268)
		(end 299.11421 -262.367268)
		(width 0.14478)
		(layer "In2.Cu")
		(net "M_C_CPU0_SB_CA<2>")
	)
	(segment
		(start 293.060882 -262.004302)
		(end 292.280086 -262.785098)
		(width 0.14478)
		(layer "In2.Cu")
		(net "M_C_CPU0_SB_CA<2>")
	)
	(segment
		(start 294.010588 -262.167116)
		(end 294.010588 -262.591804)
		(width 0.14478)
		(layer "In2.Cu")
		(net "M_C_CPU0_SB_CA<2>")
	)
	(segment
		(start 324.248526 -262.619998)
		(end 324.113398 -262.755126)
		(width 0.0889)
		(layer "In2.Cu")
		(net "M_C_CPU0_SB_CA<2>")
	)
	(segment
		(start 328.718164 -263.068562)
		(end 328.709782 -263.073388)
		(width 0.0889)
		(layer "In2.Cu")
		(net "M_C_CPU0_SB_CA<2>")
	)
	(segment
		(start 304.794666 -261.980426)
		(end 304.407824 -262.367268)
		(width 0.14478)
		(layer "In2.Cu")
		(net "M_C_CPU0_SB_CA<2>")
	)
	(segment
		(start 293.291514 -262.004302)
		(end 293.060882 -262.004302)
		(width 0.14478)
		(layer "In2.Cu")
		(net "M_C_CPU0_SB_CA<2>")
	)
	(segment
		(start 300.84649 -262.579612)
		(end 300.84649 -262.154924)
		(width 0.14478)
		(layer "In2.Cu")
		(net "M_C_CPU0_SB_CA<2>")
	)
	(segment
		(start 326.492616 -263.084056)
		(end 326.465184 -263.068308)
		(width 0.0889)
		(layer "In2.Cu")
		(net "M_C_CPU0_SB_CA<2>")
	)
	(segment
		(start 300.683676 -261.99211)
		(end 300.453044 -261.99211)
		(width 0.14478)
		(layer "In2.Cu")
		(net "M_C_CPU0_SB_CA<2>")
	)
	(segment
		(start 342.47709 -263.011412)
		(end 342.381078 -263.036812)
		(width 0.0889)
		(layer "In2.Cu")
		(net "M_C_CPU0_SB_CA<2>")
	)
	(segment
		(start 301.40275 -262.579612)
		(end 301.239936 -262.742426)
		(width 0.14478)
		(layer "In2.Cu")
		(net "M_C_CPU0_SB_CA<2>")
	)
	(segment
		(start 298.496736 -261.980426)
		(end 298.333922 -262.14324)
		(width 0.14478)
		(layer "In2.Cu")
		(net "M_C_CPU0_SB_CA<2>")
	)
	(segment
		(start 327.779634 -263.068308)
		(end 327.759568 -263.079738)
		(width 0.0889)
		(layer "In2.Cu")
		(net "M_C_CPU0_SB_CA<2>")
	)
	(segment
		(start 298.333922 -262.591296)
		(end 298.171108 -262.75411)
		(width 0.14478)
		(layer "In2.Cu")
		(net "M_C_CPU0_SB_CA<2>")
	)
	(segment
		(start 296.441114 -262.367268)
		(end 295.347644 -262.367268)
		(width 0.14478)
		(layer "In2.Cu")
		(net "M_C_CPU0_SB_CA<2>")
	)
	(segment
		(start 294.566848 -262.591804)
		(end 294.566848 -262.167116)
		(width 0.14478)
		(layer "In2.Cu")
		(net "M_C_CPU0_SB_CA<2>")
	)
	(segment
		(start 333.05242 -263.073388)
		(end 333.044038 -263.068562)
		(width 0.0889)
		(layer "In2.Cu")
		(net "M_C_CPU0_SB_CA<2>")
	)
	(segment
		(start 305.9684 -262.367268)
		(end 305.581558 -262.75411)
		(width 0.14478)
		(layer "In2.Cu")
		(net "M_C_CPU0_SB_CA<2>")
	)
	(segment
		(start 341.878158 -263.068562)
		(end 341.869776 -263.073388)
		(width 0.0889)
		(layer "In2.Cu")
		(net "M_C_CPU0_SB_CA<2>")
	)
	(segment
		(start 293.617142 -262.754618)
		(end 293.454328 -262.591804)
		(width 0.14478)
		(layer "In2.Cu")
		(net "M_C_CPU0_SB_CA<2>")
	)
	(segment
		(start 338.69249 -263.073388)
		(end 338.684108 -263.068562)
		(width 0.0889)
		(layer "In2.Cu")
		(net "M_C_CPU0_SB_CA<2>")
	)
	(segment
		(start 342.631014 -262.745982)
		(end 342.47709 -263.011412)
		(width 0.0889)
		(layer "In2.Cu")
		(net "M_C_CPU0_SB_CA<2>")
	)
	(segment
		(start 327.406762 -263.068562)
		(end 327.381108 -263.053576)
		(width 0.0889)
		(layer "In2.Cu")
		(net "M_C_CPU0_SB_CA<2>")
	)
	(segment
		(start 294.010588 -262.591804)
		(end 293.847774 -262.754618)
		(width 0.14478)
		(layer "In2.Cu")
		(net "M_C_CPU0_SB_CA<2>")
	)
	(segment
		(start 301.239936 -262.742426)
		(end 301.009304 -262.742426)
		(width 0.14478)
		(layer "In2.Cu")
		(net "M_C_CPU0_SB_CA<2>")
	)
	(segment
		(start 301.796196 -261.99211)
		(end 301.565564 -261.99211)
		(width 0.14478)
		(layer "In2.Cu")
		(net "M_C_CPU0_SB_CA<2>")
	)
	(segment
		(start 323.906134 -262.755126)
		(end 314.529216 -262.755126)
		(width 0.14478)
		(layer "In2.Cu")
		(net "M_C_CPU0_SB_CA<2>")
	)
	(segment
		(start 293.454328 -262.167116)
		(end 293.291514 -262.004302)
		(width 0.14478)
		(layer "In2.Cu")
		(net "M_C_CPU0_SB_CA<2>")
	)
	(segment
		(start 297.058588 -262.75411)
		(end 296.827956 -262.75411)
		(width 0.14478)
		(layer "In2.Cu")
		(net "M_C_CPU0_SB_CA<2>")
	)
	(segment
		(start 297.221402 -262.14324)
		(end 297.221402 -262.591296)
		(width 0.14478)
		(layer "In2.Cu")
		(net "M_C_CPU0_SB_CA<2>")
	)
	(segment
		(start 327.801224 -263.055862)
		(end 327.779634 -263.068308)
		(width 0.0889)
		(layer "In2.Cu")
		(net "M_C_CPU0_SB_CA<2>")
	)
	(segment
		(start 304.407824 -262.367268)
		(end 302.727614 -262.367268)
		(width 0.14478)
		(layer "In2.Cu")
		(net "M_C_CPU0_SB_CA<2>")
	)
	(segment
		(start 298.333922 -262.14324)
		(end 298.333922 -262.591296)
		(width 0.14478)
		(layer "In2.Cu")
		(net "M_C_CPU0_SB_CA<2>")
	)
	(segment
		(start 297.384216 -261.980426)
		(end 297.221402 -262.14324)
		(width 0.14478)
		(layer "In2.Cu")
		(net "M_C_CPU0_SB_CA<2>")
	)
	(segment
		(start 299.11421 -262.367268)
		(end 298.727368 -261.980426)
		(width 0.14478)
		(layer "In2.Cu")
		(net "M_C_CPU0_SB_CA<2>")
	)
	(segment
		(start 305.025298 -261.980426)
		(end 304.794666 -261.980426)
		(width 0.14478)
		(layer "In2.Cu")
		(net "M_C_CPU0_SB_CA<2>")
	)
	(segment
		(start 294.960294 -262.754618)
		(end 294.729662 -262.754618)
		(width 0.14478)
		(layer "In2.Cu")
		(net "M_C_CPU0_SB_CA<2>")
	)
	(segment
		(start 305.350926 -262.75411)
		(end 305.188112 -262.591296)
		(width 0.14478)
		(layer "In2.Cu")
		(net "M_C_CPU0_SB_CA<2>")
	)
	(segment
		(start 296.827956 -262.75411)
		(end 296.441114 -262.367268)
		(width 0.14478)
		(layer "In2.Cu")
		(net "M_C_CPU0_SB_CA<2>")
	)
	(segment
		(start 314.141358 -262.367268)
		(end 305.9684 -262.367268)
		(width 0.14478)
		(layer "In2.Cu")
		(net "M_C_CPU0_SB_CA<2>")
	)
	(segment
		(start 294.173402 -262.004302)
		(end 294.010588 -262.167116)
		(width 0.14478)
		(layer "In2.Cu")
		(net "M_C_CPU0_SB_CA<2>")
	)
	(segment
		(start 301.95901 -262.154924)
		(end 301.796196 -261.99211)
		(width 0.14478)
		(layer "In2.Cu")
		(net "M_C_CPU0_SB_CA<2>")
	)
	(segment
		(start 300.84649 -262.154924)
		(end 300.683676 -261.99211)
		(width 0.14478)
		(layer "In2.Cu")
		(net "M_C_CPU0_SB_CA<2>")
	)
	(segment
		(start 305.188112 -262.591296)
		(end 305.188112 -262.14324)
		(width 0.14478)
		(layer "In2.Cu")
		(net "M_C_CPU0_SB_CA<2>")
	)
	(segment
		(start 297.614848 -261.980426)
		(end 297.384216 -261.980426)
		(width 0.14478)
		(layer "In2.Cu")
		(net "M_C_CPU0_SB_CA<2>")
	)
	(segment
		(start 298.171108 -262.75411)
		(end 297.940476 -262.75411)
		(width 0.14478)
		(layer "In2.Cu")
		(net "M_C_CPU0_SB_CA<2>")
	)
	(segment
		(start 302.121824 -262.742426)
		(end 301.95901 -262.579612)
		(width 0.14478)
		(layer "In2.Cu")
		(net "M_C_CPU0_SB_CA<2>")
	)
	(segment
		(start 298.727368 -261.980426)
		(end 298.496736 -261.980426)
		(width 0.14478)
		(layer "In2.Cu")
		(net "M_C_CPU0_SB_CA<2>")
	)
	(segment
		(start 314.529216 -262.755126)
		(end 314.141358 -262.367268)
		(width 0.14478)
		(layer "In2.Cu")
		(net "M_C_CPU0_SB_CA<2>")
	)
	(segment
		(start 293.454328 -262.591804)
		(end 293.454328 -262.167116)
		(width 0.14478)
		(layer "In2.Cu")
		(net "M_C_CPU0_SB_CA<2>")
	)
	(segment
		(start 332.478126 -263.068562)
		(end 332.469744 -263.073388)
		(width 0.0889)
		(layer "In2.Cu")
		(net "M_C_CPU0_SB_CA<2>")
	)
	(segment
		(start 305.581558 -262.75411)
		(end 305.350926 -262.75411)
		(width 0.14478)
		(layer "In2.Cu")
		(net "M_C_CPU0_SB_CA<2>")
	)
	(segment
		(start 301.40275 -262.154924)
		(end 301.40275 -262.579612)
		(width 0.14478)
		(layer "In2.Cu")
		(net "M_C_CPU0_SB_CA<2>")
	)
	(segment
		(start 302.727614 -262.367268)
		(end 302.352456 -262.742426)
		(width 0.14478)
		(layer "In2.Cu")
		(net "M_C_CPU0_SB_CA<2>")
	)
	(segment
		(start 340.938104 -263.068562)
		(end 340.929722 -263.073388)
		(width 0.0889)
		(layer "In2.Cu")
		(net "M_C_CPU0_SB_CA<2>")
	)
	(segment
		(start 305.188112 -262.14324)
		(end 305.025298 -261.980426)
		(width 0.14478)
		(layer "In2.Cu")
		(net "M_C_CPU0_SB_CA<2>")
	)
	(segment
		(start 301.009304 -262.742426)
		(end 300.84649 -262.579612)
		(width 0.14478)
		(layer "In2.Cu")
		(net "M_C_CPU0_SB_CA<2>")
	)
	(segment
		(start 337.752436 -263.073388)
		(end 337.744054 -263.068562)
		(width 0.0889)
		(layer "In2.Cu")
		(net "M_C_CPU0_SB_CA<2>")
	)
	(segment
		(start 329.292458 -263.073388)
		(end 329.284076 -263.068562)
		(width 0.0889)
		(layer "In2.Cu")
		(net "M_C_CPU0_SB_CA<2>")
	)
	(segment
		(start 297.221402 -262.591296)
		(end 297.058588 -262.75411)
		(width 0.14478)
		(layer "In2.Cu")
		(net "M_C_CPU0_SB_CA<2>")
	)
	(segment
		(start 333.992474 -263.073388)
		(end 333.984092 -263.068562)
		(width 0.0889)
		(layer "In2.Cu")
		(net "M_C_CPU0_SB_CA<2>")
	)
	(segment
		(start 336.238088 -263.068562)
		(end 336.229706 -263.073388)
		(width 0.0889)
		(layer "In2.Cu")
		(net "M_C_CPU0_SB_CA<2>")
	)
	(segment
		(start 297.940476 -262.75411)
		(end 297.777662 -262.591296)
		(width 0.14478)
		(layer "In2.Cu")
		(net "M_C_CPU0_SB_CA<2>")
	)
	(segment
		(start 294.729662 -262.754618)
		(end 294.566848 -262.591804)
		(width 0.14478)
		(layer "In2.Cu")
		(net "M_C_CPU0_SB_CA<2>")
	)
	(segment
		(start 337.178142 -263.068562)
		(end 337.16976 -263.073388)
		(width 0.0889)
		(layer "In2.Cu")
		(net "M_C_CPU0_SB_CA<2>")
	)
	(segment
		(start 293.847774 -262.754618)
		(end 293.617142 -262.754618)
		(width 0.14478)
		(layer "In2.Cu")
		(net "M_C_CPU0_SB_CA<2>")
	)
	(segment
		(start 295.347644 -262.367268)
		(end 294.960294 -262.754618)
		(width 0.14478)
		(layer "In2.Cu")
		(net "M_C_CPU0_SB_CA<2>")
	)
	(segment
		(start 300.453044 -261.99211)
		(end 300.077886 -262.367268)
		(width 0.14478)
		(layer "In2.Cu")
		(net "M_C_CPU0_SB_CA<2>")
	)
	(segment
		(start 302.352456 -262.742426)
		(end 302.121824 -262.742426)
		(width 0.14478)
		(layer "In2.Cu")
		(net "M_C_CPU0_SB_CA<2>")
	)
	(segment
		(start 326.016874 -262.619998)
		(end 324.248526 -262.619998)
		(width 0.0889)
		(layer "In2.Cu")
		(net "M_C_CPU0_SB_CA<2>")
	)
	(segment
		(start 301.565564 -261.99211)
		(end 301.40275 -262.154924)
		(width 0.14478)
		(layer "In2.Cu")
		(net "M_C_CPU0_SB_CA<2>")
	)
	(segment
		(start 326.465184 -263.068308)
		(end 326.016874 -262.619998)
		(width 0.0889)
		(layer "In2.Cu")
		(net "M_C_CPU0_SB_CA<2>")
	)
	(segment
		(start 294.404034 -262.004302)
		(end 294.173402 -262.004302)
		(width 0.14478)
		(layer "In2.Cu")
		(net "M_C_CPU0_SB_CA<2>")
	)
	(segment
		(start 297.777662 -262.591296)
		(end 297.777662 -262.14324)
		(width 0.14478)
		(layer "In2.Cu")
		(net "M_C_CPU0_SB_CA<2>")
	)
	(segment
		(start 324.113398 -262.755126)
		(end 323.906134 -262.755126)
		(width 0.0889)
		(layer "In2.Cu")
		(net "M_C_CPU0_SB_CA<2>")
	)
	(segment
		(start 331.538072 -263.068562)
		(end 331.52969 -263.073388)
		(width 0.0889)
		(layer "In2.Cu")
		(net "M_C_CPU0_SB_CA<2>")
	)
	(arc
		(start 336.229706 -263.073388)
		(mid 336.046198 -263.118882)
		(end 335.863946 -263.068562)
		(width 0.0889)
		(layer "In2.Cu")
		(net "M_C_CPU0_SB_CA<2>")
	)
	(arc
		(start 342.381078 -263.036812)
		(mid 342.12587 -262.993335)
		(end 341.878158 -263.068562)
		(width 0.0889)
		(layer "In2.Cu")
		(net "M_C_CPU0_SB_CA<2>")
	)
	(arc
		(start 330.598018 -263.068562)
		(mid 330.411074 -263.118817)
		(end 330.22413 -263.068562)
		(width 0.0889)
		(layer "In2.Cu")
		(net "M_C_CPU0_SB_CA<2>")
	)
	(arc
		(start 332.469744 -263.073388)
		(mid 332.286236 -263.118882)
		(end 332.103984 -263.068562)
		(width 0.0889)
		(layer "In2.Cu")
		(net "M_C_CPU0_SB_CA<2>")
	)
	(arc
		(start 340.563962 -263.068562)
		(mid 340.281006 -262.992385)
		(end 339.99805 -263.068562)
		(width 0.0889)
		(layer "In2.Cu")
		(net "M_C_CPU0_SB_CA<2>")
	)
	(arc
		(start 326.839326 -263.068562)
		(mid 326.667871 -263.119079)
		(end 326.492616 -263.084056)
		(width 0.0889)
		(layer "In2.Cu")
		(net "M_C_CPU0_SB_CA<2>")
	)
	(arc
		(start 337.744054 -263.068562)
		(mid 337.461098 -262.992385)
		(end 337.178142 -263.068562)
		(width 0.0889)
		(layer "In2.Cu")
		(net "M_C_CPU0_SB_CA<2>")
	)
	(arc
		(start 339.99805 -263.068562)
		(mid 339.811106 -263.118817)
		(end 339.624162 -263.068562)
		(width 0.0889)
		(layer "In2.Cu")
		(net "M_C_CPU0_SB_CA<2>")
	)
	(arc
		(start 341.504016 -263.068562)
		(mid 341.22106 -262.992385)
		(end 340.938104 -263.068562)
		(width 0.0889)
		(layer "In2.Cu")
		(net "M_C_CPU0_SB_CA<2>")
	)
	(arc
		(start 327.759568 -263.079738)
		(mid 327.581744 -263.118609)
		(end 327.406762 -263.068562)
		(width 0.0889)
		(layer "In2.Cu")
		(net "M_C_CPU0_SB_CA<2>")
	)
	(arc
		(start 338.118196 -263.068562)
		(mid 337.935945 -263.118912)
		(end 337.752436 -263.073388)
		(width 0.0889)
		(layer "In2.Cu")
		(net "M_C_CPU0_SB_CA<2>")
	)
	(arc
		(start 329.284076 -263.068562)
		(mid 329.00112 -262.992385)
		(end 328.718164 -263.068562)
		(width 0.0889)
		(layer "In2.Cu")
		(net "M_C_CPU0_SB_CA<2>")
	)
	(arc
		(start 339.05825 -263.068562)
		(mid 338.875999 -263.118912)
		(end 338.69249 -263.073388)
		(width 0.0889)
		(layer "In2.Cu")
		(net "M_C_CPU0_SB_CA<2>")
	)
	(arc
		(start 330.22413 -263.068562)
		(mid 329.941174 -262.992385)
		(end 329.658218 -263.068562)
		(width 0.0889)
		(layer "In2.Cu")
		(net "M_C_CPU0_SB_CA<2>")
	)
	(arc
		(start 336.804 -263.068562)
		(mid 336.521044 -262.992385)
		(end 336.238088 -263.068562)
		(width 0.0889)
		(layer "In2.Cu")
		(net "M_C_CPU0_SB_CA<2>")
	)
	(arc
		(start 331.52969 -263.073388)
		(mid 331.346182 -263.118882)
		(end 331.16393 -263.068562)
		(width 0.0889)
		(layer "In2.Cu")
		(net "M_C_CPU0_SB_CA<2>")
	)
	(arc
		(start 337.16976 -263.073388)
		(mid 336.986252 -263.118882)
		(end 336.804 -263.068562)
		(width 0.0889)
		(layer "In2.Cu")
		(net "M_C_CPU0_SB_CA<2>")
	)
	(arc
		(start 327.381108 -263.053576)
		(mid 327.108287 -262.991735)
		(end 326.839326 -263.068562)
		(width 0.0889)
		(layer "In2.Cu")
		(net "M_C_CPU0_SB_CA<2>")
	)
	(arc
		(start 335.863946 -263.068562)
		(mid 335.58099 -262.992385)
		(end 335.298034 -263.068562)
		(width 0.0889)
		(layer "In2.Cu")
		(net "M_C_CPU0_SB_CA<2>")
	)
	(arc
		(start 340.929722 -263.073388)
		(mid 340.746214 -263.118882)
		(end 340.563962 -263.068562)
		(width 0.0889)
		(layer "In2.Cu")
		(net "M_C_CPU0_SB_CA<2>")
	)
	(arc
		(start 331.16393 -263.068562)
		(mid 330.880974 -262.992385)
		(end 330.598018 -263.068562)
		(width 0.0889)
		(layer "In2.Cu")
		(net "M_C_CPU0_SB_CA<2>")
	)
	(arc
		(start 333.044038 -263.068562)
		(mid 332.761082 -262.992385)
		(end 332.478126 -263.068562)
		(width 0.0889)
		(layer "In2.Cu")
		(net "M_C_CPU0_SB_CA<2>")
	)
	(arc
		(start 328.344022 -263.068562)
		(mid 328.074253 -262.992539)
		(end 327.801224 -263.055862)
		(width 0.0889)
		(layer "In2.Cu")
		(net "M_C_CPU0_SB_CA<2>")
	)
	(arc
		(start 339.624162 -263.068562)
		(mid 339.341206 -262.992385)
		(end 339.05825 -263.068562)
		(width 0.0889)
		(layer "In2.Cu")
		(net "M_C_CPU0_SB_CA<2>")
	)
	(arc
		(start 333.41818 -263.068562)
		(mid 333.235929 -263.118912)
		(end 333.05242 -263.073388)
		(width 0.0889)
		(layer "In2.Cu")
		(net "M_C_CPU0_SB_CA<2>")
	)
	(arc
		(start 329.658218 -263.068562)
		(mid 329.475967 -263.118912)
		(end 329.292458 -263.073388)
		(width 0.0889)
		(layer "In2.Cu")
		(net "M_C_CPU0_SB_CA<2>")
	)
	(arc
		(start 333.984092 -263.068562)
		(mid 333.701136 -262.992385)
		(end 333.41818 -263.068562)
		(width 0.0889)
		(layer "In2.Cu")
		(net "M_C_CPU0_SB_CA<2>")
	)
	(arc
		(start 341.869776 -263.073388)
		(mid 341.686268 -263.118882)
		(end 341.504016 -263.068562)
		(width 0.0889)
		(layer "In2.Cu")
		(net "M_C_CPU0_SB_CA<2>")
	)
	(arc
		(start 335.298034 -263.068562)
		(mid 335.11109 -263.118817)
		(end 334.924146 -263.068562)
		(width 0.0889)
		(layer "In2.Cu")
		(net "M_C_CPU0_SB_CA<2>")
	)
	(arc
		(start 328.709782 -263.073388)
		(mid 328.526274 -263.118882)
		(end 328.344022 -263.068562)
		(width 0.0889)
		(layer "In2.Cu")
		(net "M_C_CPU0_SB_CA<2>")
	)
	(arc
		(start 332.103984 -263.068562)
		(mid 331.821028 -262.992385)
		(end 331.538072 -263.068562)
		(width 0.0889)
		(layer "In2.Cu")
		(net "M_C_CPU0_SB_CA<2>")
	)
	(arc
		(start 334.924146 -263.068562)
		(mid 334.64119 -262.992385)
		(end 334.358234 -263.068562)
		(width 0.0889)
		(layer "In2.Cu")
		(net "M_C_CPU0_SB_CA<2>")
	)
	(arc
		(start 334.358234 -263.068562)
		(mid 334.175983 -263.118912)
		(end 333.992474 -263.073388)
		(width 0.0889)
		(layer "In2.Cu")
		(net "M_C_CPU0_SB_CA<2>")
	)
	(arc
		(start 338.684108 -263.068562)
		(mid 338.401152 -262.992385)
		(end 338.118196 -263.068562)
		(width 0.0889)
		(layer "In2.Cu")
		(net "M_C_CPU0_SB_CA<2>")
	)
	(segment
		(start 344.03792 -262.480044)
		(end 343.571068 -262.745982)
		(width 0.10668)
		(layer "F.Cu")
		(net "M_C_CPU0_SB_CA<1>")
	)
	(segment
		(start 332.478126 -262.423402)
		(end 332.469744 -262.418576)
		(width 0.0889)
		(layer "In2.Cu")
		(net "M_C_CPU0_SB_CA<1>")
	)
	(segment
		(start 333.992474 -262.418576)
		(end 333.984092 -262.423402)
		(width 0.0889)
		(layer "In2.Cu")
		(net "M_C_CPU0_SB_CA<1>")
	)
	(segment
		(start 289.830256 -261.510018)
		(end 288.60496 -261.510018)
		(width 0.14478)
		(layer "In2.Cu")
		(net "M_C_CPU0_SB_CA<1>")
	)
	(segment
		(start 340.938104 -262.423402)
		(end 340.929722 -262.418576)
		(width 0.0889)
		(layer "In2.Cu")
		(net "M_C_CPU0_SB_CA<1>")
	)
	(segment
		(start 289.99307 -261.672832)
		(end 289.830256 -261.510018)
		(width 0.14478)
		(layer "In2.Cu")
		(net "M_C_CPU0_SB_CA<1>")
	)
	(segment
		(start 323.926454 -262.24611)
		(end 314.909454 -262.24611)
		(width 0.14478)
		(layer "In2.Cu")
		(net "M_C_CPU0_SB_CA<1>")
	)
	(segment
		(start 290.54933 -261.672832)
		(end 290.54933 -261.956296)
		(width 0.14478)
		(layer "In2.Cu")
		(net "M_C_CPU0_SB_CA<1>")
	)
	(segment
		(start 337.752436 -262.418576)
		(end 337.744054 -262.423402)
		(width 0.0889)
		(layer "In2.Cu")
		(net "M_C_CPU0_SB_CA<1>")
	)
	(segment
		(start 290.712144 -261.510018)
		(end 290.54933 -261.672832)
		(width 0.14478)
		(layer "In2.Cu")
		(net "M_C_CPU0_SB_CA<1>")
	)
	(segment
		(start 327.119996 -262.24611)
		(end 323.926454 -262.24611)
		(width 0.0889)
		(layer "In2.Cu")
		(net "M_C_CPU0_SB_CA<1>")
	)
	(segment
		(start 288.60496 -261.510018)
		(end 288.180018 -261.93496)
		(width 0.14478)
		(layer "In2.Cu")
		(net "M_C_CPU0_SB_CA<1>")
	)
	(segment
		(start 290.54933 -261.956296)
		(end 290.386516 -262.11911)
		(width 0.14478)
		(layer "In2.Cu")
		(net "M_C_CPU0_SB_CA<1>")
	)
	(segment
		(start 314.909454 -262.24611)
		(end 314.173362 -261.510018)
		(width 0.14478)
		(layer "In2.Cu")
		(net "M_C_CPU0_SB_CA<1>")
	)
	(segment
		(start 290.386516 -262.11911)
		(end 290.155884 -262.11911)
		(width 0.14478)
		(layer "In2.Cu")
		(net "M_C_CPU0_SB_CA<1>")
	)
	(segment
		(start 329.292458 -262.418576)
		(end 329.284076 -262.423402)
		(width 0.0889)
		(layer "In2.Cu")
		(net "M_C_CPU0_SB_CA<1>")
	)
	(segment
		(start 338.69249 -262.418576)
		(end 338.684108 -262.423402)
		(width 0.0889)
		(layer "In2.Cu")
		(net "M_C_CPU0_SB_CA<1>")
	)
	(segment
		(start 328.344022 -262.423402)
		(end 328.32929 -262.432038)
		(width 0.0889)
		(layer "In2.Cu")
		(net "M_C_CPU0_SB_CA<1>")
	)
	(segment
		(start 328.718164 -262.423402)
		(end 328.709782 -262.418576)
		(width 0.0889)
		(layer "In2.Cu")
		(net "M_C_CPU0_SB_CA<1>")
	)
	(segment
		(start 336.238088 -262.423402)
		(end 336.229706 -262.418576)
		(width 0.0889)
		(layer "In2.Cu")
		(net "M_C_CPU0_SB_CA<1>")
	)
	(segment
		(start 290.155884 -262.11911)
		(end 289.99307 -261.956296)
		(width 0.14478)
		(layer "In2.Cu")
		(net "M_C_CPU0_SB_CA<1>")
	)
	(segment
		(start 331.538072 -262.423402)
		(end 331.52969 -262.418576)
		(width 0.0889)
		(layer "In2.Cu")
		(net "M_C_CPU0_SB_CA<1>")
	)
	(segment
		(start 333.05242 -262.418576)
		(end 333.044038 -262.423402)
		(width 0.0889)
		(layer "In2.Cu")
		(net "M_C_CPU0_SB_CA<1>")
	)
	(segment
		(start 289.99307 -261.956296)
		(end 289.99307 -261.672832)
		(width 0.14478)
		(layer "In2.Cu")
		(net "M_C_CPU0_SB_CA<1>")
	)
	(segment
		(start 343.392506 -262.418576)
		(end 343.384124 -262.423402)
		(width 0.0889)
		(layer "In2.Cu")
		(net "M_C_CPU0_SB_CA<1>")
	)
	(segment
		(start 314.173362 -261.510018)
		(end 290.712144 -261.510018)
		(width 0.14478)
		(layer "In2.Cu")
		(net "M_C_CPU0_SB_CA<1>")
	)
	(segment
		(start 343.571068 -262.745982)
		(end 343.725246 -262.480552)
		(width 0.0889)
		(layer "In2.Cu")
		(net "M_C_CPU0_SB_CA<1>")
	)
	(segment
		(start 343.725246 -262.480552)
		(end 343.702894 -262.39724)
		(width 0.0889)
		(layer "In2.Cu")
		(net "M_C_CPU0_SB_CA<1>")
	)
	(segment
		(start 337.178142 -262.423402)
		(end 337.16976 -262.418576)
		(width 0.0889)
		(layer "In2.Cu")
		(net "M_C_CPU0_SB_CA<1>")
	)
	(segment
		(start 341.878158 -262.423402)
		(end 341.869776 -262.418576)
		(width 0.0889)
		(layer "In2.Cu")
		(net "M_C_CPU0_SB_CA<1>")
	)
	(segment
		(start 342.452452 -262.418576)
		(end 342.44407 -262.423402)
		(width 0.0889)
		(layer "In2.Cu")
		(net "M_C_CPU0_SB_CA<1>")
	)
	(arc
		(start 330.598018 -262.423402)
		(mid 330.411074 -262.373147)
		(end 330.22413 -262.423402)
		(width 0.0889)
		(layer "In2.Cu")
		(net "M_C_CPU0_SB_CA<1>")
	)
	(arc
		(start 336.229706 -262.418576)
		(mid 336.046198 -262.373082)
		(end 335.863946 -262.423402)
		(width 0.0889)
		(layer "In2.Cu")
		(net "M_C_CPU0_SB_CA<1>")
	)
	(arc
		(start 336.804 -262.423402)
		(mid 336.521044 -262.499579)
		(end 336.238088 -262.423402)
		(width 0.0889)
		(layer "In2.Cu")
		(net "M_C_CPU0_SB_CA<1>")
	)
	(arc
		(start 342.818212 -262.423402)
		(mid 342.635961 -262.373052)
		(end 342.452452 -262.418576)
		(width 0.0889)
		(layer "In2.Cu")
		(net "M_C_CPU0_SB_CA<1>")
	)
	(arc
		(start 330.22413 -262.423402)
		(mid 329.941174 -262.499579)
		(end 329.658218 -262.423402)
		(width 0.0889)
		(layer "In2.Cu")
		(net "M_C_CPU0_SB_CA<1>")
	)
	(arc
		(start 343.384124 -262.423402)
		(mid 343.101168 -262.499579)
		(end 342.818212 -262.423402)
		(width 0.0889)
		(layer "In2.Cu")
		(net "M_C_CPU0_SB_CA<1>")
	)
	(arc
		(start 333.41818 -262.423402)
		(mid 333.235929 -262.373052)
		(end 333.05242 -262.418576)
		(width 0.0889)
		(layer "In2.Cu")
		(net "M_C_CPU0_SB_CA<1>")
	)
	(arc
		(start 335.298034 -262.423402)
		(mid 335.11109 -262.373147)
		(end 334.924146 -262.423402)
		(width 0.0889)
		(layer "In2.Cu")
		(net "M_C_CPU0_SB_CA<1>")
	)
	(arc
		(start 328.709782 -262.418576)
		(mid 328.526274 -262.373082)
		(end 328.344022 -262.423402)
		(width 0.0889)
		(layer "In2.Cu")
		(net "M_C_CPU0_SB_CA<1>")
	)
	(arc
		(start 338.684108 -262.423402)
		(mid 338.401152 -262.499579)
		(end 338.118196 -262.423402)
		(width 0.0889)
		(layer "In2.Cu")
		(net "M_C_CPU0_SB_CA<1>")
	)
	(arc
		(start 334.924146 -262.423402)
		(mid 334.64119 -262.499579)
		(end 334.358234 -262.423402)
		(width 0.0889)
		(layer "In2.Cu")
		(net "M_C_CPU0_SB_CA<1>")
	)
	(arc
		(start 339.05825 -262.423402)
		(mid 338.875999 -262.373052)
		(end 338.69249 -262.418576)
		(width 0.0889)
		(layer "In2.Cu")
		(net "M_C_CPU0_SB_CA<1>")
	)
	(arc
		(start 339.99805 -262.423402)
		(mid 339.811106 -262.373147)
		(end 339.624162 -262.423402)
		(width 0.0889)
		(layer "In2.Cu")
		(net "M_C_CPU0_SB_CA<1>")
	)
	(arc
		(start 331.52969 -262.418576)
		(mid 331.346182 -262.373082)
		(end 331.16393 -262.423402)
		(width 0.0889)
		(layer "In2.Cu")
		(net "M_C_CPU0_SB_CA<1>")
	)
	(arc
		(start 333.044038 -262.423402)
		(mid 332.761082 -262.499579)
		(end 332.478126 -262.423402)
		(width 0.0889)
		(layer "In2.Cu")
		(net "M_C_CPU0_SB_CA<1>")
	)
	(arc
		(start 341.869776 -262.418576)
		(mid 341.686268 -262.373082)
		(end 341.504016 -262.423402)
		(width 0.0889)
		(layer "In2.Cu")
		(net "M_C_CPU0_SB_CA<1>")
	)
	(arc
		(start 327.777602 -262.423402)
		(mid 327.460546 -262.291172)
		(end 327.119996 -262.24611)
		(width 0.0889)
		(layer "In2.Cu")
		(net "M_C_CPU0_SB_CA<1>")
	)
	(arc
		(start 332.469744 -262.418576)
		(mid 332.286236 -262.373082)
		(end 332.103984 -262.423402)
		(width 0.0889)
		(layer "In2.Cu")
		(net "M_C_CPU0_SB_CA<1>")
	)
	(arc
		(start 337.16976 -262.418576)
		(mid 336.986252 -262.373082)
		(end 336.804 -262.423402)
		(width 0.0889)
		(layer "In2.Cu")
		(net "M_C_CPU0_SB_CA<1>")
	)
	(arc
		(start 329.284076 -262.423402)
		(mid 329.00112 -262.499579)
		(end 328.718164 -262.423402)
		(width 0.0889)
		(layer "In2.Cu")
		(net "M_C_CPU0_SB_CA<1>")
	)
	(arc
		(start 340.929722 -262.418576)
		(mid 340.746214 -262.373082)
		(end 340.563962 -262.423402)
		(width 0.0889)
		(layer "In2.Cu")
		(net "M_C_CPU0_SB_CA<1>")
	)
	(arc
		(start 342.44407 -262.423402)
		(mid 342.161114 -262.499579)
		(end 341.878158 -262.423402)
		(width 0.0889)
		(layer "In2.Cu")
		(net "M_C_CPU0_SB_CA<1>")
	)
	(arc
		(start 339.624162 -262.423402)
		(mid 339.341206 -262.499579)
		(end 339.05825 -262.423402)
		(width 0.0889)
		(layer "In2.Cu")
		(net "M_C_CPU0_SB_CA<1>")
	)
	(arc
		(start 333.984092 -262.423402)
		(mid 333.701136 -262.499579)
		(end 333.41818 -262.423402)
		(width 0.0889)
		(layer "In2.Cu")
		(net "M_C_CPU0_SB_CA<1>")
	)
	(arc
		(start 331.16393 -262.423402)
		(mid 330.880974 -262.499579)
		(end 330.598018 -262.423402)
		(width 0.0889)
		(layer "In2.Cu")
		(net "M_C_CPU0_SB_CA<1>")
	)
	(arc
		(start 343.702894 -262.39724)
		(mid 343.545384 -262.374042)
		(end 343.392506 -262.418576)
		(width 0.0889)
		(layer "In2.Cu")
		(net "M_C_CPU0_SB_CA<1>")
	)
	(arc
		(start 335.863946 -262.423402)
		(mid 335.58099 -262.499579)
		(end 335.298034 -262.423402)
		(width 0.0889)
		(layer "In2.Cu")
		(net "M_C_CPU0_SB_CA<1>")
	)
	(arc
		(start 337.744054 -262.423402)
		(mid 337.461098 -262.499579)
		(end 337.178142 -262.423402)
		(width 0.0889)
		(layer "In2.Cu")
		(net "M_C_CPU0_SB_CA<1>")
	)
	(arc
		(start 328.32929 -262.432038)
		(mid 328.052307 -262.499842)
		(end 327.777602 -262.423402)
		(width 0.0889)
		(layer "In2.Cu")
		(net "M_C_CPU0_SB_CA<1>")
	)
	(arc
		(start 341.504016 -262.423402)
		(mid 341.22106 -262.499579)
		(end 340.938104 -262.423402)
		(width 0.0889)
		(layer "In2.Cu")
		(net "M_C_CPU0_SB_CA<1>")
	)
	(arc
		(start 340.563962 -262.423402)
		(mid 340.281006 -262.499579)
		(end 339.99805 -262.423402)
		(width 0.0889)
		(layer "In2.Cu")
		(net "M_C_CPU0_SB_CA<1>")
	)
	(arc
		(start 329.658218 -262.423402)
		(mid 329.475967 -262.373052)
		(end 329.292458 -262.418576)
		(width 0.0889)
		(layer "In2.Cu")
		(net "M_C_CPU0_SB_CA<1>")
	)
	(arc
		(start 334.358234 -262.423402)
		(mid 334.175983 -262.373052)
		(end 333.992474 -262.418576)
		(width 0.0889)
		(layer "In2.Cu")
		(net "M_C_CPU0_SB_CA<1>")
	)
	(arc
		(start 338.118196 -262.423402)
		(mid 337.935945 -262.373052)
		(end 337.752436 -262.418576)
		(width 0.0889)
		(layer "In2.Cu")
		(net "M_C_CPU0_SB_CA<1>")
	)
	(arc
		(start 332.103984 -262.423402)
		(mid 331.821028 -262.499579)
		(end 331.538072 -262.423402)
		(width 0.0889)
		(layer "In2.Cu")
		(net "M_C_CPU0_SB_CA<1>")
	)
	(segment
		(start 344.508074 -261.670038)
		(end 344.041222 -261.935976)
		(width 0.10668)
		(layer "F.Cu")
		(net "M_C_CPU0_SB_CA<0>")
	)
	(segment
		(start 309.808118 -260.267958)
		(end 309.577486 -260.267958)
		(width 0.14478)
		(layer "In2.Cu")
		(net "M_C_CPU0_SB_CA<0>")
	)
	(segment
		(start 311.476898 -261.05231)
		(end 311.246266 -261.05231)
		(width 0.14478)
		(layer "In2.Cu")
		(net "M_C_CPU0_SB_CA<0>")
	)
	(segment
		(start 312.752232 -260.430772)
		(end 312.752232 -260.889496)
		(width 0.14478)
		(layer "In2.Cu")
		(net "M_C_CPU0_SB_CA<0>")
	)
	(segment
		(start 309.970932 -260.430772)
		(end 309.808118 -260.267958)
		(width 0.14478)
		(layer "In2.Cu")
		(net "M_C_CPU0_SB_CA<0>")
	)
	(segment
		(start 323.888354 -261.775956)
		(end 315.6077 -261.775956)
		(width 0.14478)
		(layer "In2.Cu")
		(net "M_C_CPU0_SB_CA<0>")
	)
	(segment
		(start 344.041222 -261.935976)
		(end 343.887044 -262.201406)
		(width 0.0889)
		(layer "In2.Cu")
		(net "M_C_CPU0_SB_CA<0>")
	)
	(segment
		(start 312.915046 -260.267958)
		(end 312.752232 -260.430772)
		(width 0.14478)
		(layer "In2.Cu")
		(net "M_C_CPU0_SB_CA<0>")
	)
	(segment
		(start 340.102444 -262.263382)
		(end 340.094062 -262.258556)
		(width 0.0889)
		(layer "In2.Cu")
		(net "M_C_CPU0_SB_CA<0>")
	)
	(segment
		(start 311.802526 -260.267958)
		(end 311.639712 -260.430772)
		(width 0.14478)
		(layer "In2.Cu")
		(net "M_C_CPU0_SB_CA<0>")
	)
	(segment
		(start 339.52815 -262.258556)
		(end 339.519768 -262.263382)
		(width 0.0889)
		(layer "In2.Cu")
		(net "M_C_CPU0_SB_CA<0>")
	)
	(segment
		(start 312.195972 -260.430772)
		(end 312.033158 -260.267958)
		(width 0.14478)
		(layer "In2.Cu")
		(net "M_C_CPU0_SB_CA<0>")
	)
	(segment
		(start 327.07326 -262.04291)
		(end 324.59168 -262.04291)
		(width 0.0889)
		(layer "In2.Cu")
		(net "M_C_CPU0_SB_CA<0>")
	)
	(segment
		(start 310.527192 -260.889496)
		(end 310.364378 -261.05231)
		(width 0.14478)
		(layer "In2.Cu")
		(net "M_C_CPU0_SB_CA<0>")
	)
	(segment
		(start 310.920638 -260.267958)
		(end 310.690006 -260.267958)
		(width 0.14478)
		(layer "In2.Cu")
		(net "M_C_CPU0_SB_CA<0>")
	)
	(segment
		(start 312.033158 -260.267958)
		(end 311.802526 -260.267958)
		(width 0.14478)
		(layer "In2.Cu")
		(net "M_C_CPU0_SB_CA<0>")
	)
	(segment
		(start 309.414672 -260.430772)
		(end 309.414672 -260.889496)
		(width 0.14478)
		(layer "In2.Cu")
		(net "M_C_CPU0_SB_CA<0>")
	)
	(segment
		(start 312.752232 -260.889496)
		(end 312.589418 -261.05231)
		(width 0.14478)
		(layer "In2.Cu")
		(net "M_C_CPU0_SB_CA<0>")
	)
	(segment
		(start 309.251858 -261.05231)
		(end 309.05831 -261.05231)
		(width 0.14478)
		(layer "In2.Cu")
		(net "M_C_CPU0_SB_CA<0>")
	)
	(segment
		(start 313.145678 -260.267958)
		(end 312.915046 -260.267958)
		(width 0.14478)
		(layer "In2.Cu")
		(net "M_C_CPU0_SB_CA<0>")
	)
	(segment
		(start 310.527192 -260.430772)
		(end 310.527192 -260.889496)
		(width 0.14478)
		(layer "In2.Cu")
		(net "M_C_CPU0_SB_CA<0>")
	)
	(segment
		(start 292.705028 -260.660134)
		(end 292.280086 -261.085076)
		(width 0.14478)
		(layer "In2.Cu")
		(net "M_C_CPU0_SB_CA<0>")
	)
	(segment
		(start 313.471306 -261.05231)
		(end 313.308492 -260.889496)
		(width 0.14478)
		(layer "In2.Cu")
		(net "M_C_CPU0_SB_CA<0>")
	)
	(segment
		(start 309.970932 -260.889496)
		(end 309.970932 -260.430772)
		(width 0.14478)
		(layer "In2.Cu")
		(net "M_C_CPU0_SB_CA<0>")
	)
	(segment
		(start 328.248264 -262.258556)
		(end 328.239882 -262.263382)
		(width 0.0889)
		(layer "In2.Cu")
		(net "M_C_CPU0_SB_CA<0>")
	)
	(segment
		(start 311.639712 -260.430772)
		(end 311.639712 -260.889496)
		(width 0.14478)
		(layer "In2.Cu")
		(net "M_C_CPU0_SB_CA<0>")
	)
	(segment
		(start 315.6077 -261.775956)
		(end 314.491878 -260.660134)
		(width 0.14478)
		(layer "In2.Cu")
		(net "M_C_CPU0_SB_CA<0>")
	)
	(segment
		(start 312.195972 -260.889496)
		(end 312.195972 -260.430772)
		(width 0.14478)
		(layer "In2.Cu")
		(net "M_C_CPU0_SB_CA<0>")
	)
	(segment
		(start 312.358786 -261.05231)
		(end 312.195972 -260.889496)
		(width 0.14478)
		(layer "In2.Cu")
		(net "M_C_CPU0_SB_CA<0>")
	)
	(segment
		(start 336.342482 -262.263382)
		(end 336.3341 -262.258556)
		(width 0.0889)
		(layer "In2.Cu")
		(net "M_C_CPU0_SB_CA<0>")
	)
	(segment
		(start 310.133746 -261.05231)
		(end 309.970932 -260.889496)
		(width 0.14478)
		(layer "In2.Cu")
		(net "M_C_CPU0_SB_CA<0>")
	)
	(segment
		(start 313.308492 -260.889496)
		(end 313.308492 -260.430772)
		(width 0.14478)
		(layer "In2.Cu")
		(net "M_C_CPU0_SB_CA<0>")
	)
	(segment
		(start 324.59168 -262.04291)
		(end 324.324726 -261.775956)
		(width 0.0889)
		(layer "In2.Cu")
		(net "M_C_CPU0_SB_CA<0>")
	)
	(segment
		(start 311.083452 -260.889496)
		(end 311.083452 -260.430772)
		(width 0.14478)
		(layer "In2.Cu")
		(net "M_C_CPU0_SB_CA<0>")
	)
	(segment
		(start 338.588096 -262.258556)
		(end 338.579714 -262.263382)
		(width 0.0889)
		(layer "In2.Cu")
		(net "M_C_CPU0_SB_CA<0>")
	)
	(segment
		(start 312.589418 -261.05231)
		(end 312.358786 -261.05231)
		(width 0.14478)
		(layer "In2.Cu")
		(net "M_C_CPU0_SB_CA<0>")
	)
	(segment
		(start 330.128118 -262.258556)
		(end 330.119736 -262.263382)
		(width 0.0889)
		(layer "In2.Cu")
		(net "M_C_CPU0_SB_CA<0>")
	)
	(segment
		(start 324.324726 -261.775956)
		(end 323.888354 -261.775956)
		(width 0.0889)
		(layer "In2.Cu")
		(net "M_C_CPU0_SB_CA<0>")
	)
	(segment
		(start 311.639712 -260.889496)
		(end 311.476898 -261.05231)
		(width 0.14478)
		(layer "In2.Cu")
		(net "M_C_CPU0_SB_CA<0>")
	)
	(segment
		(start 343.288112 -262.258556)
		(end 343.27973 -262.263382)
		(width 0.0889)
		(layer "In2.Cu")
		(net "M_C_CPU0_SB_CA<0>")
	)
	(segment
		(start 341.042498 -262.263382)
		(end 341.034116 -262.258556)
		(width 0.0889)
		(layer "In2.Cu")
		(net "M_C_CPU0_SB_CA<0>")
	)
	(segment
		(start 308.666134 -260.660134)
		(end 292.705028 -260.660134)
		(width 0.14478)
		(layer "In2.Cu")
		(net "M_C_CPU0_SB_CA<0>")
	)
	(segment
		(start 330.702412 -262.263382)
		(end 330.69403 -262.258556)
		(width 0.0889)
		(layer "In2.Cu")
		(net "M_C_CPU0_SB_CA<0>")
	)
	(segment
		(start 314.491878 -260.660134)
		(end 314.094114 -260.660134)
		(width 0.14478)
		(layer "In2.Cu")
		(net "M_C_CPU0_SB_CA<0>")
	)
	(segment
		(start 309.414672 -260.889496)
		(end 309.251858 -261.05231)
		(width 0.14478)
		(layer "In2.Cu")
		(net "M_C_CPU0_SB_CA<0>")
	)
	(segment
		(start 333.88808 -262.258556)
		(end 333.879698 -262.263382)
		(width 0.0889)
		(layer "In2.Cu")
		(net "M_C_CPU0_SB_CA<0>")
	)
	(segment
		(start 309.577486 -260.267958)
		(end 309.414672 -260.430772)
		(width 0.14478)
		(layer "In2.Cu")
		(net "M_C_CPU0_SB_CA<0>")
	)
	(segment
		(start 334.828134 -262.258556)
		(end 334.819752 -262.263382)
		(width 0.0889)
		(layer "In2.Cu")
		(net "M_C_CPU0_SB_CA<0>")
	)
	(segment
		(start 311.083452 -260.430772)
		(end 310.920638 -260.267958)
		(width 0.14478)
		(layer "In2.Cu")
		(net "M_C_CPU0_SB_CA<0>")
	)
	(segment
		(start 310.364378 -261.05231)
		(end 310.133746 -261.05231)
		(width 0.14478)
		(layer "In2.Cu")
		(net "M_C_CPU0_SB_CA<0>")
	)
	(segment
		(start 313.308492 -260.430772)
		(end 313.145678 -260.267958)
		(width 0.14478)
		(layer "In2.Cu")
		(net "M_C_CPU0_SB_CA<0>")
	)
	(segment
		(start 309.05831 -261.05231)
		(end 308.666134 -260.660134)
		(width 0.14478)
		(layer "In2.Cu")
		(net "M_C_CPU0_SB_CA<0>")
	)
	(segment
		(start 310.690006 -260.267958)
		(end 310.527192 -260.430772)
		(width 0.14478)
		(layer "In2.Cu")
		(net "M_C_CPU0_SB_CA<0>")
	)
	(segment
		(start 335.402428 -262.263382)
		(end 335.394046 -262.258556)
		(width 0.0889)
		(layer "In2.Cu")
		(net "M_C_CPU0_SB_CA<0>")
	)
	(segment
		(start 331.642466 -262.263382)
		(end 331.634084 -262.258556)
		(width 0.0889)
		(layer "In2.Cu")
		(net "M_C_CPU0_SB_CA<0>")
	)
	(segment
		(start 343.887044 -262.201406)
		(end 343.790778 -262.226806)
		(width 0.0889)
		(layer "In2.Cu")
		(net "M_C_CPU0_SB_CA<0>")
	)
	(segment
		(start 314.094114 -260.660134)
		(end 313.701938 -261.05231)
		(width 0.14478)
		(layer "In2.Cu")
		(net "M_C_CPU0_SB_CA<0>")
	)
	(segment
		(start 311.246266 -261.05231)
		(end 311.083452 -260.889496)
		(width 0.14478)
		(layer "In2.Cu")
		(net "M_C_CPU0_SB_CA<0>")
	)
	(segment
		(start 313.701938 -261.05231)
		(end 313.471306 -261.05231)
		(width 0.14478)
		(layer "In2.Cu")
		(net "M_C_CPU0_SB_CA<0>")
	)
	(arc
		(start 329.753976 -262.258556)
		(mid 329.47102 -262.182379)
		(end 329.188064 -262.258556)
		(width 0.0889)
		(layer "In2.Cu")
		(net "M_C_CPU0_SB_CA<0>")
	)
	(arc
		(start 340.468204 -262.258556)
		(mid 340.285953 -262.308906)
		(end 340.102444 -262.263382)
		(width 0.0889)
		(layer "In2.Cu")
		(net "M_C_CPU0_SB_CA<0>")
	)
	(arc
		(start 340.094062 -262.258556)
		(mid 339.811106 -262.182379)
		(end 339.52815 -262.258556)
		(width 0.0889)
		(layer "In2.Cu")
		(net "M_C_CPU0_SB_CA<0>")
	)
	(arc
		(start 339.154008 -262.258556)
		(mid 338.871052 -262.182379)
		(end 338.588096 -262.258556)
		(width 0.0889)
		(layer "In2.Cu")
		(net "M_C_CPU0_SB_CA<0>")
	)
	(arc
		(start 331.068172 -262.258556)
		(mid 330.885921 -262.308906)
		(end 330.702412 -262.263382)
		(width 0.0889)
		(layer "In2.Cu")
		(net "M_C_CPU0_SB_CA<0>")
	)
	(arc
		(start 332.948026 -262.258556)
		(mid 332.761082 -262.308811)
		(end 332.574138 -262.258556)
		(width 0.0889)
		(layer "In2.Cu")
		(net "M_C_CPU0_SB_CA<0>")
	)
	(arc
		(start 329.188064 -262.258556)
		(mid 329.00112 -262.308811)
		(end 328.814176 -262.258556)
		(width 0.0889)
		(layer "In2.Cu")
		(net "M_C_CPU0_SB_CA<0>")
	)
	(arc
		(start 332.574138 -262.258556)
		(mid 332.291182 -262.182379)
		(end 332.008226 -262.258556)
		(width 0.0889)
		(layer "In2.Cu")
		(net "M_C_CPU0_SB_CA<0>")
	)
	(arc
		(start 343.790778 -262.226806)
		(mid 343.535713 -262.183455)
		(end 343.288112 -262.258556)
		(width 0.0889)
		(layer "In2.Cu")
		(net "M_C_CPU0_SB_CA<0>")
	)
	(arc
		(start 333.513938 -262.258556)
		(mid 333.230982 -262.182379)
		(end 332.948026 -262.258556)
		(width 0.0889)
		(layer "In2.Cu")
		(net "M_C_CPU0_SB_CA<0>")
	)
	(arc
		(start 333.879698 -262.263382)
		(mid 333.69619 -262.308876)
		(end 333.513938 -262.258556)
		(width 0.0889)
		(layer "In2.Cu")
		(net "M_C_CPU0_SB_CA<0>")
	)
	(arc
		(start 341.97417 -262.258556)
		(mid 341.691214 -262.182379)
		(end 341.408258 -262.258556)
		(width 0.0889)
		(layer "In2.Cu")
		(net "M_C_CPU0_SB_CA<0>")
	)
	(arc
		(start 328.239882 -262.263382)
		(mid 328.05612 -262.308998)
		(end 327.873614 -262.258556)
		(width 0.0889)
		(layer "In2.Cu")
		(net "M_C_CPU0_SB_CA<0>")
	)
	(arc
		(start 342.91397 -262.258556)
		(mid 342.631014 -262.182379)
		(end 342.348058 -262.258556)
		(width 0.0889)
		(layer "In2.Cu")
		(net "M_C_CPU0_SB_CA<0>")
	)
	(arc
		(start 339.519768 -262.263382)
		(mid 339.33626 -262.308876)
		(end 339.154008 -262.258556)
		(width 0.0889)
		(layer "In2.Cu")
		(net "M_C_CPU0_SB_CA<0>")
	)
	(arc
		(start 328.814176 -262.258556)
		(mid 328.53122 -262.182379)
		(end 328.248264 -262.258556)
		(width 0.0889)
		(layer "In2.Cu")
		(net "M_C_CPU0_SB_CA<0>")
	)
	(arc
		(start 341.034116 -262.258556)
		(mid 340.75116 -262.182379)
		(end 340.468204 -262.258556)
		(width 0.0889)
		(layer "In2.Cu")
		(net "M_C_CPU0_SB_CA<0>")
	)
	(arc
		(start 335.394046 -262.258556)
		(mid 335.11109 -262.182379)
		(end 334.828134 -262.258556)
		(width 0.0889)
		(layer "In2.Cu")
		(net "M_C_CPU0_SB_CA<0>")
	)
	(arc
		(start 338.213954 -262.258556)
		(mid 337.930998 -262.182379)
		(end 337.648042 -262.258556)
		(width 0.0889)
		(layer "In2.Cu")
		(net "M_C_CPU0_SB_CA<0>")
	)
	(arc
		(start 342.348058 -262.258556)
		(mid 342.161114 -262.308811)
		(end 341.97417 -262.258556)
		(width 0.0889)
		(layer "In2.Cu")
		(net "M_C_CPU0_SB_CA<0>")
	)
	(arc
		(start 336.708242 -262.258556)
		(mid 336.525991 -262.308906)
		(end 336.342482 -262.263382)
		(width 0.0889)
		(layer "In2.Cu")
		(net "M_C_CPU0_SB_CA<0>")
	)
	(arc
		(start 343.27973 -262.263382)
		(mid 343.096222 -262.308876)
		(end 342.91397 -262.258556)
		(width 0.0889)
		(layer "In2.Cu")
		(net "M_C_CPU0_SB_CA<0>")
	)
	(arc
		(start 335.768188 -262.258556)
		(mid 335.585937 -262.308906)
		(end 335.402428 -262.263382)
		(width 0.0889)
		(layer "In2.Cu")
		(net "M_C_CPU0_SB_CA<0>")
	)
	(arc
		(start 331.634084 -262.258556)
		(mid 331.351128 -262.182379)
		(end 331.068172 -262.258556)
		(width 0.0889)
		(layer "In2.Cu")
		(net "M_C_CPU0_SB_CA<0>")
	)
	(arc
		(start 334.819752 -262.263382)
		(mid 334.636244 -262.308876)
		(end 334.453992 -262.258556)
		(width 0.0889)
		(layer "In2.Cu")
		(net "M_C_CPU0_SB_CA<0>")
	)
	(arc
		(start 327.873614 -262.258556)
		(mid 327.487712 -262.097744)
		(end 327.07326 -262.04291)
		(width 0.0889)
		(layer "In2.Cu")
		(net "M_C_CPU0_SB_CA<0>")
	)
	(arc
		(start 330.69403 -262.258556)
		(mid 330.411074 -262.182379)
		(end 330.128118 -262.258556)
		(width 0.0889)
		(layer "In2.Cu")
		(net "M_C_CPU0_SB_CA<0>")
	)
	(arc
		(start 330.119736 -262.263382)
		(mid 329.936228 -262.308876)
		(end 329.753976 -262.258556)
		(width 0.0889)
		(layer "In2.Cu")
		(net "M_C_CPU0_SB_CA<0>")
	)
	(arc
		(start 337.274154 -262.258556)
		(mid 336.991198 -262.182379)
		(end 336.708242 -262.258556)
		(width 0.0889)
		(layer "In2.Cu")
		(net "M_C_CPU0_SB_CA<0>")
	)
	(arc
		(start 341.408258 -262.258556)
		(mid 341.226007 -262.308906)
		(end 341.042498 -262.263382)
		(width 0.0889)
		(layer "In2.Cu")
		(net "M_C_CPU0_SB_CA<0>")
	)
	(arc
		(start 337.648042 -262.258556)
		(mid 337.461098 -262.308811)
		(end 337.274154 -262.258556)
		(width 0.0889)
		(layer "In2.Cu")
		(net "M_C_CPU0_SB_CA<0>")
	)
	(arc
		(start 336.3341 -262.258556)
		(mid 336.051144 -262.182379)
		(end 335.768188 -262.258556)
		(width 0.0889)
		(layer "In2.Cu")
		(net "M_C_CPU0_SB_CA<0>")
	)
	(arc
		(start 334.453992 -262.258556)
		(mid 334.171036 -262.182379)
		(end 333.88808 -262.258556)
		(width 0.0889)
		(layer "In2.Cu")
		(net "M_C_CPU0_SB_CA<0>")
	)
	(arc
		(start 338.579714 -262.263382)
		(mid 338.396206 -262.308876)
		(end 338.213954 -262.258556)
		(width 0.0889)
		(layer "In2.Cu")
		(net "M_C_CPU0_SB_CA<0>")
	)
	(arc
		(start 332.008226 -262.258556)
		(mid 331.825975 -262.308906)
		(end 331.642466 -262.263382)
		(width 0.0889)
		(layer "In2.Cu")
		(net "M_C_CPU0_SB_CA<0>")
	)
	(segment
		(start 344.508074 -266.530074)
		(end 344.041222 -266.796012)
		(width 0.10668)
		(layer "F.Cu")
		(net "M_C_CPU0_SA_RSP<0>")
	)
	(segment
		(start 302.193198 -269.15999)
		(end 302.033432 -269.000224)
		(width 0.11684)
		(layer "In2.Cu")
		(net "M_C_CPU0_SA_RSP<0>")
	)
	(segment
		(start 296.81043 -269.005304)
		(end 296.655744 -269.15999)
		(width 0.11684)
		(layer "In2.Cu")
		(net "M_C_CPU0_SA_RSP<0>")
	)
	(segment
		(start 294.083486 -268.928596)
		(end 294.083486 -269.005304)
		(width 0.11684)
		(layer "In2.Cu")
		(net "M_C_CPU0_SA_RSP<0>")
	)
	(segment
		(start 338.595716 -267.106908)
		(end 338.585048 -267.113004)
		(width 0.0889)
		(layer "In2.Cu")
		(net "M_C_CPU0_SA_RSP<0>")
	)
	(segment
		(start 304.351944 -268.928596)
		(end 304.351944 -269.005304)
		(width 0.11684)
		(layer "In2.Cu")
		(net "M_C_CPU0_SA_RSP<0>")
	)
	(segment
		(start 305.936904 -268.928596)
		(end 305.782218 -268.77391)
		(width 0.11684)
		(layer "In2.Cu")
		(net "M_C_CPU0_SA_RSP<0>")
	)
	(segment
		(start 324.871334 -266.91971)
		(end 324.376034 -266.42441)
		(width 0.0889)
		(layer "In2.Cu")
		(net "M_C_CPU0_SA_RSP<0>")
	)
	(segment
		(start 341.977218 -267.113004)
		(end 341.96655 -267.106908)
		(width 0.0889)
		(layer "In2.Cu")
		(net "M_C_CPU0_SA_RSP<0>")
	)
	(segment
		(start 296.81043 -268.928596)
		(end 296.81043 -269.005304)
		(width 0.11684)
		(layer "In2.Cu")
		(net "M_C_CPU0_SA_RSP<0>")
	)
	(segment
		(start 327.358502 -267.151612)
		(end 327.1266 -266.91971)
		(width 0.0889)
		(layer "In2.Cu")
		(net "M_C_CPU0_SA_RSP<0>")
	)
	(segment
		(start 328.244962 -267.113004)
		(end 328.236834 -267.11783)
		(width 0.0889)
		(layer "In2.Cu")
		(net "M_C_CPU0_SA_RSP<0>")
	)
	(segment
		(start 297.33875 -268.928596)
		(end 297.184064 -268.77391)
		(width 0.11684)
		(layer "In2.Cu")
		(net "M_C_CPU0_SA_RSP<0>")
	)
	(segment
		(start 298.550076 -269.15999)
		(end 298.39539 -269.005304)
		(width 0.11684)
		(layer "In2.Cu")
		(net "M_C_CPU0_SA_RSP<0>")
	)
	(segment
		(start 294.083486 -269.005304)
		(end 293.9288 -269.15999)
		(width 0.11684)
		(layer "In2.Cu")
		(net "M_C_CPU0_SA_RSP<0>")
	)
	(segment
		(start 298.021756 -268.77391)
		(end 297.86707 -268.928596)
		(width 0.11684)
		(layer "In2.Cu")
		(net "M_C_CPU0_SA_RSP<0>")
	)
	(segment
		(start 304.725578 -268.77391)
		(end 304.50663 -268.77391)
		(width 0.11684)
		(layer "In2.Cu")
		(net "M_C_CPU0_SA_RSP<0>")
	)
	(segment
		(start 294.238172 -268.77391)
		(end 294.083486 -268.928596)
		(width 0.11684)
		(layer "In2.Cu")
		(net "M_C_CPU0_SA_RSP<0>")
	)
	(segment
		(start 300.976792 -268.923516)
		(end 300.822106 -268.76883)
		(width 0.11684)
		(layer "In2.Cu")
		(net "M_C_CPU0_SA_RSP<0>")
	)
	(segment
		(start 301.350426 -269.15491)
		(end 301.131478 -269.15491)
		(width 0.11684)
		(layer "In2.Cu")
		(net "M_C_CPU0_SA_RSP<0>")
	)
	(segment
		(start 329.195684 -267.106908)
		(end 329.185016 -267.113004)
		(width 0.0889)
		(layer "In2.Cu")
		(net "M_C_CPU0_SA_RSP<0>")
	)
	(segment
		(start 300.288706 -269.15999)
		(end 299.606716 -269.15999)
		(width 0.11684)
		(layer "In2.Cu")
		(net "M_C_CPU0_SA_RSP<0>")
	)
	(segment
		(start 306.09159 -269.15999)
		(end 305.936904 -269.005304)
		(width 0.11684)
		(layer "In2.Cu")
		(net "M_C_CPU0_SA_RSP<0>")
	)
	(segment
		(start 343.295732 -267.106908)
		(end 343.285064 -267.113004)
		(width 0.0889)
		(layer "In2.Cu")
		(net "M_C_CPU0_SA_RSP<0>")
	)
	(segment
		(start 298.39539 -269.005304)
		(end 298.39539 -268.928596)
		(width 0.11684)
		(layer "In2.Cu")
		(net "M_C_CPU0_SA_RSP<0>")
	)
	(segment
		(start 306.61991 -268.77391)
		(end 306.465224 -268.928596)
		(width 0.11684)
		(layer "In2.Cu")
		(net "M_C_CPU0_SA_RSP<0>")
	)
	(segment
		(start 331.637132 -267.113004)
		(end 331.626464 -267.106908)
		(width 0.0889)
		(layer "In2.Cu")
		(net "M_C_CPU0_SA_RSP<0>")
	)
	(segment
		(start 297.86707 -269.005304)
		(end 297.712384 -269.15999)
		(width 0.11684)
		(layer "In2.Cu")
		(net "M_C_CPU0_SA_RSP<0>")
	)
	(segment
		(start 293.555166 -269.005304)
		(end 293.555166 -268.928596)
		(width 0.11684)
		(layer "In2.Cu")
		(net "M_C_CPU0_SA_RSP<0>")
	)
	(segment
		(start 306.993544 -268.928596)
		(end 306.838858 -268.77391)
		(width 0.11684)
		(layer "In2.Cu")
		(net "M_C_CPU0_SA_RSP<0>")
	)
	(segment
		(start 306.993544 -269.005304)
		(end 306.993544 -268.928596)
		(width 0.11684)
		(layer "In2.Cu")
		(net "M_C_CPU0_SA_RSP<0>")
	)
	(segment
		(start 294.611806 -268.928596)
		(end 294.45712 -268.77391)
		(width 0.11684)
		(layer "In2.Cu")
		(net "M_C_CPU0_SA_RSP<0>")
	)
	(segment
		(start 293.9288 -269.15999)
		(end 293.709852 -269.15999)
		(width 0.11684)
		(layer "In2.Cu")
		(net "M_C_CPU0_SA_RSP<0>")
	)
	(segment
		(start 306.465224 -268.928596)
		(end 306.465224 -269.005304)
		(width 0.11684)
		(layer "In2.Cu")
		(net "M_C_CPU0_SA_RSP<0>")
	)
	(segment
		(start 298.769024 -269.15999)
		(end 298.550076 -269.15999)
		(width 0.11684)
		(layer "In2.Cu")
		(net "M_C_CPU0_SA_RSP<0>")
	)
	(segment
		(start 308.046374 -269.15999)
		(end 307.14823 -269.15999)
		(width 0.11684)
		(layer "In2.Cu")
		(net "M_C_CPU0_SA_RSP<0>")
	)
	(segment
		(start 293.709852 -269.15999)
		(end 293.555166 -269.005304)
		(width 0.11684)
		(layer "In2.Cu")
		(net "M_C_CPU0_SA_RSP<0>")
	)
	(segment
		(start 293.181532 -268.77391)
		(end 293.026846 -268.928596)
		(width 0.11684)
		(layer "In2.Cu")
		(net "M_C_CPU0_SA_RSP<0>")
	)
	(segment
		(start 328.113644 -267.151612)
		(end 327.358502 -267.151612)
		(width 0.0889)
		(layer "In2.Cu")
		(net "M_C_CPU0_SA_RSP<0>")
	)
	(segment
		(start 292.705282 -269.15999)
		(end 292.280086 -269.585186)
		(width 0.11684)
		(layer "In2.Cu")
		(net "M_C_CPU0_SA_RSP<0>")
	)
	(segment
		(start 297.33875 -269.005304)
		(end 297.33875 -268.928596)
		(width 0.11684)
		(layer "In2.Cu")
		(net "M_C_CPU0_SA_RSP<0>")
	)
	(segment
		(start 293.026846 -269.005304)
		(end 292.87216 -269.15999)
		(width 0.11684)
		(layer "In2.Cu")
		(net "M_C_CPU0_SA_RSP<0>")
	)
	(segment
		(start 300.822106 -268.76883)
		(end 300.603158 -268.76883)
		(width 0.11684)
		(layer "In2.Cu")
		(net "M_C_CPU0_SA_RSP<0>")
	)
	(segment
		(start 301.659798 -268.76883)
		(end 301.505112 -268.923516)
		(width 0.11684)
		(layer "In2.Cu")
		(net "M_C_CPU0_SA_RSP<0>")
	)
	(segment
		(start 293.40048 -268.77391)
		(end 293.181532 -268.77391)
		(width 0.11684)
		(layer "In2.Cu")
		(net "M_C_CPU0_SA_RSP<0>")
	)
	(segment
		(start 341.037164 -267.113004)
		(end 341.026496 -267.106908)
		(width 0.0889)
		(layer "In2.Cu")
		(net "M_C_CPU0_SA_RSP<0>")
	)
	(segment
		(start 299.45203 -269.005304)
		(end 299.45203 -268.928596)
		(width 0.11684)
		(layer "In2.Cu")
		(net "M_C_CPU0_SA_RSP<0>")
	)
	(segment
		(start 299.297344 -268.77391)
		(end 299.078396 -268.77391)
		(width 0.11684)
		(layer "In2.Cu")
		(net "M_C_CPU0_SA_RSP<0>")
	)
	(segment
		(start 304.197258 -269.15999)
		(end 302.193198 -269.15999)
		(width 0.11684)
		(layer "In2.Cu")
		(net "M_C_CPU0_SA_RSP<0>")
	)
	(segment
		(start 327.1266 -266.91971)
		(end 324.871334 -266.91971)
		(width 0.0889)
		(layer "In2.Cu")
		(net "M_C_CPU0_SA_RSP<0>")
	)
	(segment
		(start 300.603158 -268.76883)
		(end 300.448472 -268.923516)
		(width 0.11684)
		(layer "In2.Cu")
		(net "M_C_CPU0_SA_RSP<0>")
	)
	(segment
		(start 298.39539 -268.928596)
		(end 298.240704 -268.77391)
		(width 0.11684)
		(layer "In2.Cu")
		(net "M_C_CPU0_SA_RSP<0>")
	)
	(segment
		(start 336.337148 -267.113004)
		(end 336.32648 -267.106908)
		(width 0.0889)
		(layer "In2.Cu")
		(net "M_C_CPU0_SA_RSP<0>")
	)
	(segment
		(start 305.782218 -268.77391)
		(end 305.56327 -268.77391)
		(width 0.11684)
		(layer "In2.Cu")
		(net "M_C_CPU0_SA_RSP<0>")
	)
	(segment
		(start 304.880264 -268.928596)
		(end 304.725578 -268.77391)
		(width 0.11684)
		(layer "In2.Cu")
		(net "M_C_CPU0_SA_RSP<0>")
	)
	(segment
		(start 298.240704 -268.77391)
		(end 298.021756 -268.77391)
		(width 0.11684)
		(layer "In2.Cu")
		(net "M_C_CPU0_SA_RSP<0>")
	)
	(segment
		(start 305.03495 -269.15999)
		(end 304.880264 -269.005304)
		(width 0.11684)
		(layer "In2.Cu")
		(net "M_C_CPU0_SA_RSP<0>")
	)
	(segment
		(start 305.408584 -269.005304)
		(end 305.253898 -269.15999)
		(width 0.11684)
		(layer "In2.Cu")
		(net "M_C_CPU0_SA_RSP<0>")
	)
	(segment
		(start 307.14823 -269.15999)
		(end 306.993544 -269.005304)
		(width 0.11684)
		(layer "In2.Cu")
		(net "M_C_CPU0_SA_RSP<0>")
	)
	(segment
		(start 306.838858 -268.77391)
		(end 306.61991 -268.77391)
		(width 0.11684)
		(layer "In2.Cu")
		(net "M_C_CPU0_SA_RSP<0>")
	)
	(segment
		(start 337.277202 -267.113004)
		(end 337.266534 -267.106908)
		(width 0.0889)
		(layer "In2.Cu")
		(net "M_C_CPU0_SA_RSP<0>")
	)
	(segment
		(start 332.577186 -267.113004)
		(end 332.566518 -267.106908)
		(width 0.0889)
		(layer "In2.Cu")
		(net "M_C_CPU0_SA_RSP<0>")
	)
	(segment
		(start 302.033432 -268.923516)
		(end 301.878746 -268.76883)
		(width 0.11684)
		(layer "In2.Cu")
		(net "M_C_CPU0_SA_RSP<0>")
	)
	(segment
		(start 300.976792 -269.000224)
		(end 300.976792 -268.923516)
		(width 0.11684)
		(layer "In2.Cu")
		(net "M_C_CPU0_SA_RSP<0>")
	)
	(segment
		(start 301.878746 -268.76883)
		(end 301.659798 -268.76883)
		(width 0.11684)
		(layer "In2.Cu")
		(net "M_C_CPU0_SA_RSP<0>")
	)
	(segment
		(start 337.655662 -267.106908)
		(end 337.644994 -267.113004)
		(width 0.0889)
		(layer "In2.Cu")
		(net "M_C_CPU0_SA_RSP<0>")
	)
	(segment
		(start 301.505112 -269.000224)
		(end 301.350426 -269.15491)
		(width 0.11684)
		(layer "In2.Cu")
		(net "M_C_CPU0_SA_RSP<0>")
	)
	(segment
		(start 342.355678 -267.106908)
		(end 342.34501 -267.113004)
		(width 0.0889)
		(layer "In2.Cu")
		(net "M_C_CPU0_SA_RSP<0>")
	)
	(segment
		(start 296.655744 -269.15999)
		(end 294.766492 -269.15999)
		(width 0.11684)
		(layer "In2.Cu")
		(net "M_C_CPU0_SA_RSP<0>")
	)
	(segment
		(start 299.45203 -268.928596)
		(end 299.297344 -268.77391)
		(width 0.11684)
		(layer "In2.Cu")
		(net "M_C_CPU0_SA_RSP<0>")
	)
	(segment
		(start 305.56327 -268.77391)
		(end 305.408584 -268.928596)
		(width 0.11684)
		(layer "In2.Cu")
		(net "M_C_CPU0_SA_RSP<0>")
	)
	(segment
		(start 297.86707 -268.928596)
		(end 297.86707 -269.005304)
		(width 0.11684)
		(layer "In2.Cu")
		(net "M_C_CPU0_SA_RSP<0>")
	)
	(segment
		(start 293.026846 -268.928596)
		(end 293.026846 -269.005304)
		(width 0.11684)
		(layer "In2.Cu")
		(net "M_C_CPU0_SA_RSP<0>")
	)
	(segment
		(start 305.408584 -268.928596)
		(end 305.408584 -269.005304)
		(width 0.11684)
		(layer "In2.Cu")
		(net "M_C_CPU0_SA_RSP<0>")
	)
	(segment
		(start 300.448472 -268.923516)
		(end 300.448472 -269.000224)
		(width 0.11684)
		(layer "In2.Cu")
		(net "M_C_CPU0_SA_RSP<0>")
	)
	(segment
		(start 344.041222 -266.796012)
		(end 343.892378 -267.052298)
		(width 0.0889)
		(layer "In2.Cu")
		(net "M_C_CPU0_SA_RSP<0>")
	)
	(segment
		(start 333.8957 -267.106908)
		(end 333.885032 -267.113004)
		(width 0.0889)
		(layer "In2.Cu")
		(net "M_C_CPU0_SA_RSP<0>")
	)
	(segment
		(start 302.033432 -269.000224)
		(end 302.033432 -268.923516)
		(width 0.11684)
		(layer "In2.Cu")
		(net "M_C_CPU0_SA_RSP<0>")
	)
	(segment
		(start 296.965116 -268.77391)
		(end 296.81043 -268.928596)
		(width 0.11684)
		(layer "In2.Cu")
		(net "M_C_CPU0_SA_RSP<0>")
	)
	(segment
		(start 305.253898 -269.15999)
		(end 305.03495 -269.15999)
		(width 0.11684)
		(layer "In2.Cu")
		(net "M_C_CPU0_SA_RSP<0>")
	)
	(segment
		(start 299.606716 -269.15999)
		(end 299.45203 -269.005304)
		(width 0.11684)
		(layer "In2.Cu")
		(net "M_C_CPU0_SA_RSP<0>")
	)
	(segment
		(start 328.817224 -267.113004)
		(end 328.806556 -267.106908)
		(width 0.0889)
		(layer "In2.Cu")
		(net "M_C_CPU0_SA_RSP<0>")
	)
	(segment
		(start 304.50663 -268.77391)
		(end 304.351944 -268.928596)
		(width 0.11684)
		(layer "In2.Cu")
		(net "M_C_CPU0_SA_RSP<0>")
	)
	(segment
		(start 304.351944 -269.005304)
		(end 304.197258 -269.15999)
		(width 0.11684)
		(layer "In2.Cu")
		(net "M_C_CPU0_SA_RSP<0>")
	)
	(segment
		(start 297.493436 -269.15999)
		(end 297.33875 -269.005304)
		(width 0.11684)
		(layer "In2.Cu")
		(net "M_C_CPU0_SA_RSP<0>")
	)
	(segment
		(start 294.45712 -268.77391)
		(end 294.238172 -268.77391)
		(width 0.11684)
		(layer "In2.Cu")
		(net "M_C_CPU0_SA_RSP<0>")
	)
	(segment
		(start 294.766492 -269.15999)
		(end 294.611806 -269.005304)
		(width 0.11684)
		(layer "In2.Cu")
		(net "M_C_CPU0_SA_RSP<0>")
	)
	(segment
		(start 292.87216 -269.15999)
		(end 292.705282 -269.15999)
		(width 0.11684)
		(layer "In2.Cu")
		(net "M_C_CPU0_SA_RSP<0>")
	)
	(segment
		(start 304.880264 -269.005304)
		(end 304.880264 -268.928596)
		(width 0.11684)
		(layer "In2.Cu")
		(net "M_C_CPU0_SA_RSP<0>")
	)
	(segment
		(start 294.611806 -269.005304)
		(end 294.611806 -268.928596)
		(width 0.11684)
		(layer "In2.Cu")
		(net "M_C_CPU0_SA_RSP<0>")
	)
	(segment
		(start 298.92371 -269.005304)
		(end 298.769024 -269.15999)
		(width 0.11684)
		(layer "In2.Cu")
		(net "M_C_CPU0_SA_RSP<0>")
	)
	(segment
		(start 310.781954 -266.42441)
		(end 308.046374 -269.15999)
		(width 0.11684)
		(layer "In2.Cu")
		(net "M_C_CPU0_SA_RSP<0>")
	)
	(segment
		(start 300.448472 -269.000224)
		(end 300.288706 -269.15999)
		(width 0.11684)
		(layer "In2.Cu")
		(net "M_C_CPU0_SA_RSP<0>")
	)
	(segment
		(start 301.131478 -269.15491)
		(end 300.976792 -269.000224)
		(width 0.11684)
		(layer "In2.Cu")
		(net "M_C_CPU0_SA_RSP<0>")
	)
	(segment
		(start 332.955646 -267.106908)
		(end 332.944978 -267.113004)
		(width 0.0889)
		(layer "In2.Cu")
		(net "M_C_CPU0_SA_RSP<0>")
	)
	(segment
		(start 306.465224 -269.005304)
		(end 306.310538 -269.15999)
		(width 0.11684)
		(layer "In2.Cu")
		(net "M_C_CPU0_SA_RSP<0>")
	)
	(segment
		(start 297.712384 -269.15999)
		(end 297.493436 -269.15999)
		(width 0.11684)
		(layer "In2.Cu")
		(net "M_C_CPU0_SA_RSP<0>")
	)
	(segment
		(start 305.936904 -269.005304)
		(end 305.936904 -268.928596)
		(width 0.11684)
		(layer "In2.Cu")
		(net "M_C_CPU0_SA_RSP<0>")
	)
	(segment
		(start 343.892378 -267.052298)
		(end 343.789762 -267.079476)
		(width 0.0889)
		(layer "In2.Cu")
		(net "M_C_CPU0_SA_RSP<0>")
	)
	(segment
		(start 306.310538 -269.15999)
		(end 306.09159 -269.15999)
		(width 0.11684)
		(layer "In2.Cu")
		(net "M_C_CPU0_SA_RSP<0>")
	)
	(segment
		(start 324.376034 -266.42441)
		(end 310.781954 -266.42441)
		(width 0.11684)
		(layer "In2.Cu")
		(net "M_C_CPU0_SA_RSP<0>")
	)
	(segment
		(start 293.555166 -268.928596)
		(end 293.40048 -268.77391)
		(width 0.11684)
		(layer "In2.Cu")
		(net "M_C_CPU0_SA_RSP<0>")
	)
	(segment
		(start 298.92371 -268.928596)
		(end 298.92371 -269.005304)
		(width 0.11684)
		(layer "In2.Cu")
		(net "M_C_CPU0_SA_RSP<0>")
	)
	(segment
		(start 301.505112 -268.923516)
		(end 301.505112 -269.000224)
		(width 0.11684)
		(layer "In2.Cu")
		(net "M_C_CPU0_SA_RSP<0>")
	)
	(segment
		(start 299.078396 -268.77391)
		(end 298.92371 -268.928596)
		(width 0.11684)
		(layer "In2.Cu")
		(net "M_C_CPU0_SA_RSP<0>")
	)
	(segment
		(start 297.184064 -268.77391)
		(end 296.965116 -268.77391)
		(width 0.11684)
		(layer "In2.Cu")
		(net "M_C_CPU0_SA_RSP<0>")
	)
	(arc
		(start 336.32648 -267.106908)
		(mid 336.044891 -267.036034)
		(end 335.764886 -267.113004)
		(width 0.0889)
		(layer "In2.Cu")
		(net "M_C_CPU0_SA_RSP<0>")
	)
	(arc
		(start 328.806556 -267.106908)
		(mid 328.524967 -267.036034)
		(end 328.244962 -267.113004)
		(width 0.0889)
		(layer "In2.Cu")
		(net "M_C_CPU0_SA_RSP<0>")
	)
	(arc
		(start 341.96655 -267.106908)
		(mid 341.684961 -267.036034)
		(end 341.404956 -267.113004)
		(width 0.0889)
		(layer "In2.Cu")
		(net "M_C_CPU0_SA_RSP<0>")
	)
	(arc
		(start 338.585048 -267.113004)
		(mid 338.401152 -267.162484)
		(end 338.217256 -267.113004)
		(width 0.0889)
		(layer "In2.Cu")
		(net "M_C_CPU0_SA_RSP<0>")
	)
	(arc
		(start 341.404956 -267.113004)
		(mid 341.22106 -267.162484)
		(end 341.037164 -267.113004)
		(width 0.0889)
		(layer "In2.Cu")
		(net "M_C_CPU0_SA_RSP<0>")
	)
	(arc
		(start 343.789762 -267.079476)
		(mid 343.539628 -267.036845)
		(end 343.295732 -267.106908)
		(width 0.0889)
		(layer "In2.Cu")
		(net "M_C_CPU0_SA_RSP<0>")
	)
	(arc
		(start 329.185016 -267.113004)
		(mid 329.00112 -267.162484)
		(end 328.817224 -267.113004)
		(width 0.0889)
		(layer "In2.Cu")
		(net "M_C_CPU0_SA_RSP<0>")
	)
	(arc
		(start 338.217256 -267.113004)
		(mid 337.937252 -267.035959)
		(end 337.655662 -267.106908)
		(width 0.0889)
		(layer "In2.Cu")
		(net "M_C_CPU0_SA_RSP<0>")
	)
	(arc
		(start 342.917272 -267.113004)
		(mid 342.637268 -267.035959)
		(end 342.355678 -267.106908)
		(width 0.0889)
		(layer "In2.Cu")
		(net "M_C_CPU0_SA_RSP<0>")
	)
	(arc
		(start 335.764886 -267.113004)
		(mid 335.58099 -267.162484)
		(end 335.397094 -267.113004)
		(width 0.0889)
		(layer "In2.Cu")
		(net "M_C_CPU0_SA_RSP<0>")
	)
	(arc
		(start 335.397094 -267.113004)
		(mid 335.11109 -267.036052)
		(end 334.825086 -267.113004)
		(width 0.0889)
		(layer "In2.Cu")
		(net "M_C_CPU0_SA_RSP<0>")
	)
	(arc
		(start 330.12507 -267.113004)
		(mid 329.941174 -267.162484)
		(end 329.757278 -267.113004)
		(width 0.0889)
		(layer "In2.Cu")
		(net "M_C_CPU0_SA_RSP<0>")
	)
	(arc
		(start 339.525102 -267.113004)
		(mid 339.341206 -267.162484)
		(end 339.15731 -267.113004)
		(width 0.0889)
		(layer "In2.Cu")
		(net "M_C_CPU0_SA_RSP<0>")
	)
	(arc
		(start 334.457294 -267.113004)
		(mid 334.17729 -267.035959)
		(end 333.8957 -267.106908)
		(width 0.0889)
		(layer "In2.Cu")
		(net "M_C_CPU0_SA_RSP<0>")
	)
	(arc
		(start 334.825086 -267.113004)
		(mid 334.64119 -267.162484)
		(end 334.457294 -267.113004)
		(width 0.0889)
		(layer "In2.Cu")
		(net "M_C_CPU0_SA_RSP<0>")
	)
	(arc
		(start 339.15731 -267.113004)
		(mid 338.877306 -267.035959)
		(end 338.595716 -267.106908)
		(width 0.0889)
		(layer "In2.Cu")
		(net "M_C_CPU0_SA_RSP<0>")
	)
	(arc
		(start 332.944978 -267.113004)
		(mid 332.761082 -267.162484)
		(end 332.577186 -267.113004)
		(width 0.0889)
		(layer "In2.Cu")
		(net "M_C_CPU0_SA_RSP<0>")
	)
	(arc
		(start 331.06487 -267.113004)
		(mid 330.880974 -267.162484)
		(end 330.697078 -267.113004)
		(width 0.0889)
		(layer "In2.Cu")
		(net "M_C_CPU0_SA_RSP<0>")
	)
	(arc
		(start 340.464902 -267.113004)
		(mid 340.281006 -267.162484)
		(end 340.09711 -267.113004)
		(width 0.0889)
		(layer "In2.Cu")
		(net "M_C_CPU0_SA_RSP<0>")
	)
	(arc
		(start 342.34501 -267.113004)
		(mid 342.161114 -267.162484)
		(end 341.977218 -267.113004)
		(width 0.0889)
		(layer "In2.Cu")
		(net "M_C_CPU0_SA_RSP<0>")
	)
	(arc
		(start 337.644994 -267.113004)
		(mid 337.461098 -267.162484)
		(end 337.277202 -267.113004)
		(width 0.0889)
		(layer "In2.Cu")
		(net "M_C_CPU0_SA_RSP<0>")
	)
	(arc
		(start 333.51724 -267.113004)
		(mid 333.237236 -267.035959)
		(end 332.955646 -267.106908)
		(width 0.0889)
		(layer "In2.Cu")
		(net "M_C_CPU0_SA_RSP<0>")
	)
	(arc
		(start 332.004924 -267.113004)
		(mid 331.821028 -267.162484)
		(end 331.637132 -267.113004)
		(width 0.0889)
		(layer "In2.Cu")
		(net "M_C_CPU0_SA_RSP<0>")
	)
	(arc
		(start 332.566518 -267.106908)
		(mid 332.284929 -267.036034)
		(end 332.004924 -267.113004)
		(width 0.0889)
		(layer "In2.Cu")
		(net "M_C_CPU0_SA_RSP<0>")
	)
	(arc
		(start 328.236834 -267.11783)
		(mid 328.177522 -267.143061)
		(end 328.113644 -267.151612)
		(width 0.0889)
		(layer "In2.Cu")
		(net "M_C_CPU0_SA_RSP<0>")
	)
	(arc
		(start 329.757278 -267.113004)
		(mid 329.477274 -267.035959)
		(end 329.195684 -267.106908)
		(width 0.0889)
		(layer "In2.Cu")
		(net "M_C_CPU0_SA_RSP<0>")
	)
	(arc
		(start 343.285064 -267.113004)
		(mid 343.101168 -267.162484)
		(end 342.917272 -267.113004)
		(width 0.0889)
		(layer "In2.Cu")
		(net "M_C_CPU0_SA_RSP<0>")
	)
	(arc
		(start 337.266534 -267.106908)
		(mid 336.984945 -267.036034)
		(end 336.70494 -267.113004)
		(width 0.0889)
		(layer "In2.Cu")
		(net "M_C_CPU0_SA_RSP<0>")
	)
	(arc
		(start 330.697078 -267.113004)
		(mid 330.411074 -267.036052)
		(end 330.12507 -267.113004)
		(width 0.0889)
		(layer "In2.Cu")
		(net "M_C_CPU0_SA_RSP<0>")
	)
	(arc
		(start 341.026496 -267.106908)
		(mid 340.744907 -267.036034)
		(end 340.464902 -267.113004)
		(width 0.0889)
		(layer "In2.Cu")
		(net "M_C_CPU0_SA_RSP<0>")
	)
	(arc
		(start 331.626464 -267.106908)
		(mid 331.344875 -267.036034)
		(end 331.06487 -267.113004)
		(width 0.0889)
		(layer "In2.Cu")
		(net "M_C_CPU0_SA_RSP<0>")
	)
	(arc
		(start 333.885032 -267.113004)
		(mid 333.701136 -267.162484)
		(end 333.51724 -267.113004)
		(width 0.0889)
		(layer "In2.Cu")
		(net "M_C_CPU0_SA_RSP<0>")
	)
	(arc
		(start 336.70494 -267.113004)
		(mid 336.521044 -267.162484)
		(end 336.337148 -267.113004)
		(width 0.0889)
		(layer "In2.Cu")
		(net "M_C_CPU0_SA_RSP<0>")
	)
	(arc
		(start 340.09711 -267.113004)
		(mid 339.811106 -267.036052)
		(end 339.525102 -267.113004)
		(width 0.0889)
		(layer "In2.Cu")
		(net "M_C_CPU0_SA_RSP<0>")
	)
	(segment
		(start 344.207846 -256.090166)
		(end 343.740994 -255.824228)
		(width 0.10668)
		(layer "F.Cu")
		(net "M_C_CPU0_SA_PAR")
	)
	(segment
		(start 343.58707 -255.558798)
		(end 343.491058 -255.533398)
		(width 0.0889)
		(layer "In2.Cu")
		(net "M_C_CPU0_SA_PAR")
	)
	(segment
		(start 296.836592 -255.17221)
		(end 296.606214 -255.17221)
		(width 0.14478)
		(layer "In2.Cu")
		(net "M_C_CPU0_SA_PAR")
	)
	(segment
		(start 342.988138 -255.501648)
		(end 342.979756 -255.496822)
		(width 0.0889)
		(layer "In2.Cu")
		(net "M_C_CPU0_SA_PAR")
	)
	(segment
		(start 296.99966 -255.335278)
		(end 296.836592 -255.17221)
		(width 0.14478)
		(layer "In2.Cu")
		(net "M_C_CPU0_SA_PAR")
	)
	(segment
		(start 301.800768 -255.350518)
		(end 301.6377 -255.18745)
		(width 0.14478)
		(layer "In2.Cu")
		(net "M_C_CPU0_SA_PAR")
	)
	(segment
		(start 319.228724 -254.94107)
		(end 316.568328 -254.94107)
		(width 0.14478)
		(layer "In2.Cu")
		(net "M_C_CPU0_SA_PAR")
	)
	(segment
		(start 301.244254 -255.350518)
		(end 301.244254 -255.402588)
		(width 0.14478)
		(layer "In2.Cu")
		(net "M_C_CPU0_SA_PAR")
	)
	(segment
		(start 298.112688 -255.402588)
		(end 298.112688 -255.335278)
		(width 0.14478)
		(layer "In2.Cu")
		(net "M_C_CPU0_SA_PAR")
	)
	(segment
		(start 301.081186 -255.565656)
		(end 299.388784 -255.565656)
		(width 0.14478)
		(layer "In2.Cu")
		(net "M_C_CPU0_SA_PAR")
	)
	(segment
		(start 333.588106 -255.501648)
		(end 333.579724 -255.496822)
		(width 0.0889)
		(layer "In2.Cu")
		(net "M_C_CPU0_SA_PAR")
	)
	(segment
		(start 331.342492 -255.496822)
		(end 331.33411 -255.501648)
		(width 0.0889)
		(layer "In2.Cu")
		(net "M_C_CPU0_SA_PAR")
	)
	(segment
		(start 298.83227 -255.17221)
		(end 298.669202 -255.335278)
		(width 0.14478)
		(layer "In2.Cu")
		(net "M_C_CPU0_SA_PAR")
	)
	(segment
		(start 297.556174 -255.335278)
		(end 297.556174 -255.402588)
		(width 0.14478)
		(layer "In2.Cu")
		(net "M_C_CPU0_SA_PAR")
	)
	(segment
		(start 299.225716 -255.335278)
		(end 299.062648 -255.17221)
		(width 0.14478)
		(layer "In2.Cu")
		(net "M_C_CPU0_SA_PAR")
	)
	(segment
		(start 325.031862 -256.49555)
		(end 324.025514 -256.49555)
		(width 0.0889)
		(layer "In2.Cu")
		(net "M_C_CPU0_SA_PAR")
	)
	(segment
		(start 326.110854 -255.65989)
		(end 325.867522 -255.65989)
		(width 0.0889)
		(layer "In2.Cu")
		(net "M_C_CPU0_SA_PAR")
	)
	(segment
		(start 297.556174 -255.402588)
		(end 297.393106 -255.565656)
		(width 0.14478)
		(layer "In2.Cu")
		(net "M_C_CPU0_SA_PAR")
	)
	(segment
		(start 320.783204 -256.49555)
		(end 319.228724 -254.94107)
		(width 0.14478)
		(layer "In2.Cu")
		(net "M_C_CPU0_SA_PAR")
	)
	(segment
		(start 338.862416 -255.496822)
		(end 338.854034 -255.501648)
		(width 0.0889)
		(layer "In2.Cu")
		(net "M_C_CPU0_SA_PAR")
	)
	(segment
		(start 342.048084 -255.501648)
		(end 342.039702 -255.496822)
		(width 0.0889)
		(layer "In2.Cu")
		(net "M_C_CPU0_SA_PAR")
	)
	(segment
		(start 297.393106 -255.565656)
		(end 297.162728 -255.565656)
		(width 0.14478)
		(layer "In2.Cu")
		(net "M_C_CPU0_SA_PAR")
	)
	(segment
		(start 316.568328 -254.94107)
		(end 315.060076 -255.565656)
		(width 0.14478)
		(layer "In2.Cu")
		(net "M_C_CPU0_SA_PAR")
	)
	(segment
		(start 330.402438 -255.496822)
		(end 330.394056 -255.501648)
		(width 0.0889)
		(layer "In2.Cu")
		(net "M_C_CPU0_SA_PAR")
	)
	(segment
		(start 296.443146 -255.335278)
		(end 296.443146 -255.402588)
		(width 0.14478)
		(layer "In2.Cu")
		(net "M_C_CPU0_SA_PAR")
	)
	(segment
		(start 293.989506 -255.565656)
		(end 293.13378 -254.70993)
		(width 0.14478)
		(layer "In2.Cu")
		(net "M_C_CPU0_SA_PAR")
	)
	(segment
		(start 299.062648 -255.17221)
		(end 298.83227 -255.17221)
		(width 0.14478)
		(layer "In2.Cu")
		(net "M_C_CPU0_SA_PAR")
	)
	(segment
		(start 296.606214 -255.17221)
		(end 296.443146 -255.335278)
		(width 0.14478)
		(layer "In2.Cu")
		(net "M_C_CPU0_SA_PAR")
	)
	(segment
		(start 327.598786 -255.48844)
		(end 327.575418 -255.501902)
		(width 0.0889)
		(layer "In2.Cu")
		(net "M_C_CPU0_SA_PAR")
	)
	(segment
		(start 298.112688 -255.335278)
		(end 297.94962 -255.17221)
		(width 0.14478)
		(layer "In2.Cu")
		(net "M_C_CPU0_SA_PAR")
	)
	(segment
		(start 301.963836 -255.565656)
		(end 301.800768 -255.402588)
		(width 0.14478)
		(layer "In2.Cu")
		(net "M_C_CPU0_SA_PAR")
	)
	(segment
		(start 299.225716 -255.402588)
		(end 299.225716 -255.335278)
		(width 0.14478)
		(layer "In2.Cu")
		(net "M_C_CPU0_SA_PAR")
	)
	(segment
		(start 301.407322 -255.18745)
		(end 301.244254 -255.350518)
		(width 0.14478)
		(layer "In2.Cu")
		(net "M_C_CPU0_SA_PAR")
	)
	(segment
		(start 327.011538 -255.501648)
		(end 326.990964 -255.48971)
		(width 0.0889)
		(layer "In2.Cu")
		(net "M_C_CPU0_SA_PAR")
	)
	(segment
		(start 296.99966 -255.402588)
		(end 296.99966 -255.335278)
		(width 0.14478)
		(layer "In2.Cu")
		(net "M_C_CPU0_SA_PAR")
	)
	(segment
		(start 327.575418 -255.501902)
		(end 327.549256 -255.516888)
		(width 0.0889)
		(layer "In2.Cu")
		(net "M_C_CPU0_SA_PAR")
	)
	(segment
		(start 301.244254 -255.402588)
		(end 301.081186 -255.565656)
		(width 0.14478)
		(layer "In2.Cu")
		(net "M_C_CPU0_SA_PAR")
	)
	(segment
		(start 301.6377 -255.18745)
		(end 301.407322 -255.18745)
		(width 0.14478)
		(layer "In2.Cu")
		(net "M_C_CPU0_SA_PAR")
	)
	(segment
		(start 334.52816 -255.501648)
		(end 334.519778 -255.496822)
		(width 0.0889)
		(layer "In2.Cu")
		(net "M_C_CPU0_SA_PAR")
	)
	(segment
		(start 298.275756 -255.565656)
		(end 298.112688 -255.402588)
		(width 0.14478)
		(layer "In2.Cu")
		(net "M_C_CPU0_SA_PAR")
	)
	(segment
		(start 297.719242 -255.17221)
		(end 297.556174 -255.335278)
		(width 0.14478)
		(layer "In2.Cu")
		(net "M_C_CPU0_SA_PAR")
	)
	(segment
		(start 297.162728 -255.565656)
		(end 296.99966 -255.402588)
		(width 0.14478)
		(layer "In2.Cu")
		(net "M_C_CPU0_SA_PAR")
	)
	(segment
		(start 335.102454 -255.496822)
		(end 335.094072 -255.501648)
		(width 0.0889)
		(layer "In2.Cu")
		(net "M_C_CPU0_SA_PAR")
	)
	(segment
		(start 296.443146 -255.402588)
		(end 296.280078 -255.565656)
		(width 0.14478)
		(layer "In2.Cu")
		(net "M_C_CPU0_SA_PAR")
	)
	(segment
		(start 325.867522 -255.65989)
		(end 325.031862 -256.49555)
		(width 0.0889)
		(layer "In2.Cu")
		(net "M_C_CPU0_SA_PAR")
	)
	(segment
		(start 339.80247 -255.496822)
		(end 339.794088 -255.501648)
		(width 0.0889)
		(layer "In2.Cu")
		(net "M_C_CPU0_SA_PAR")
	)
	(segment
		(start 338.288122 -255.501648)
		(end 338.27974 -255.496822)
		(width 0.0889)
		(layer "In2.Cu")
		(net "M_C_CPU0_SA_PAR")
	)
	(segment
		(start 329.828144 -255.501648)
		(end 329.819762 -255.496822)
		(width 0.0889)
		(layer "In2.Cu")
		(net "M_C_CPU0_SA_PAR")
	)
	(segment
		(start 292.705028 -254.70993)
		(end 292.280086 -254.284988)
		(width 0.14478)
		(layer "In2.Cu")
		(net "M_C_CPU0_SA_PAR")
	)
	(segment
		(start 326.636126 -255.501648)
		(end 326.585072 -255.53162)
		(width 0.0889)
		(layer "In2.Cu")
		(net "M_C_CPU0_SA_PAR")
	)
	(segment
		(start 324.025514 -256.49555)
		(end 320.783204 -256.49555)
		(width 0.14478)
		(layer "In2.Cu")
		(net "M_C_CPU0_SA_PAR")
	)
	(segment
		(start 296.280078 -255.565656)
		(end 293.989506 -255.565656)
		(width 0.14478)
		(layer "In2.Cu")
		(net "M_C_CPU0_SA_PAR")
	)
	(segment
		(start 298.669202 -255.402588)
		(end 298.506134 -255.565656)
		(width 0.14478)
		(layer "In2.Cu")
		(net "M_C_CPU0_SA_PAR")
	)
	(segment
		(start 298.506134 -255.565656)
		(end 298.275756 -255.565656)
		(width 0.14478)
		(layer "In2.Cu")
		(net "M_C_CPU0_SA_PAR")
	)
	(segment
		(start 343.740994 -255.824228)
		(end 343.58707 -255.558798)
		(width 0.0889)
		(layer "In2.Cu")
		(net "M_C_CPU0_SA_PAR")
	)
	(segment
		(start 315.060076 -255.565656)
		(end 301.963836 -255.565656)
		(width 0.14478)
		(layer "In2.Cu")
		(net "M_C_CPU0_SA_PAR")
	)
	(segment
		(start 301.800768 -255.402588)
		(end 301.800768 -255.350518)
		(width 0.14478)
		(layer "In2.Cu")
		(net "M_C_CPU0_SA_PAR")
	)
	(segment
		(start 336.042508 -255.496822)
		(end 336.034126 -255.501648)
		(width 0.0889)
		(layer "In2.Cu")
		(net "M_C_CPU0_SA_PAR")
	)
	(segment
		(start 297.94962 -255.17221)
		(end 297.719242 -255.17221)
		(width 0.14478)
		(layer "In2.Cu")
		(net "M_C_CPU0_SA_PAR")
	)
	(segment
		(start 298.669202 -255.335278)
		(end 298.669202 -255.402588)
		(width 0.14478)
		(layer "In2.Cu")
		(net "M_C_CPU0_SA_PAR")
	)
	(segment
		(start 293.13378 -254.70993)
		(end 292.705028 -254.70993)
		(width 0.14478)
		(layer "In2.Cu")
		(net "M_C_CPU0_SA_PAR")
	)
	(segment
		(start 299.388784 -255.565656)
		(end 299.225716 -255.402588)
		(width 0.14478)
		(layer "In2.Cu")
		(net "M_C_CPU0_SA_PAR")
	)
	(arc
		(start 341.10803 -255.501648)
		(mid 340.921086 -255.451393)
		(end 340.734142 -255.501648)
		(width 0.0889)
		(layer "In2.Cu")
		(net "M_C_CPU0_SA_PAR")
	)
	(arc
		(start 327.94829 -255.501648)
		(mid 327.775182 -255.451532)
		(end 327.598786 -255.48844)
		(width 0.0889)
		(layer "In2.Cu")
		(net "M_C_CPU0_SA_PAR")
	)
	(arc
		(start 335.468214 -255.501648)
		(mid 335.285963 -255.451298)
		(end 335.102454 -255.496822)
		(width 0.0889)
		(layer "In2.Cu")
		(net "M_C_CPU0_SA_PAR")
	)
	(arc
		(start 338.27974 -255.496822)
		(mid 338.096232 -255.451328)
		(end 337.91398 -255.501648)
		(width 0.0889)
		(layer "In2.Cu")
		(net "M_C_CPU0_SA_PAR")
	)
	(arc
		(start 342.039702 -255.496822)
		(mid 341.856194 -255.451328)
		(end 341.673942 -255.501648)
		(width 0.0889)
		(layer "In2.Cu")
		(net "M_C_CPU0_SA_PAR")
	)
	(arc
		(start 330.768198 -255.501648)
		(mid 330.585947 -255.451298)
		(end 330.402438 -255.496822)
		(width 0.0889)
		(layer "In2.Cu")
		(net "M_C_CPU0_SA_PAR")
	)
	(arc
		(start 336.97418 -255.501648)
		(mid 336.691224 -255.577825)
		(end 336.408268 -255.501648)
		(width 0.0889)
		(layer "In2.Cu")
		(net "M_C_CPU0_SA_PAR")
	)
	(arc
		(start 342.979756 -255.496822)
		(mid 342.796248 -255.451328)
		(end 342.613996 -255.501648)
		(width 0.0889)
		(layer "In2.Cu")
		(net "M_C_CPU0_SA_PAR")
	)
	(arc
		(start 337.348068 -255.501648)
		(mid 337.161124 -255.451393)
		(end 336.97418 -255.501648)
		(width 0.0889)
		(layer "In2.Cu")
		(net "M_C_CPU0_SA_PAR")
	)
	(arc
		(start 328.514202 -255.501648)
		(mid 328.231246 -255.577825)
		(end 327.94829 -255.501648)
		(width 0.0889)
		(layer "In2.Cu")
		(net "M_C_CPU0_SA_PAR")
	)
	(arc
		(start 342.613996 -255.501648)
		(mid 342.33104 -255.577825)
		(end 342.048084 -255.501648)
		(width 0.0889)
		(layer "In2.Cu")
		(net "M_C_CPU0_SA_PAR")
	)
	(arc
		(start 341.673942 -255.501648)
		(mid 341.390986 -255.577825)
		(end 341.10803 -255.501648)
		(width 0.0889)
		(layer "In2.Cu")
		(net "M_C_CPU0_SA_PAR")
	)
	(arc
		(start 329.819762 -255.496822)
		(mid 329.636254 -255.451328)
		(end 329.454002 -255.501648)
		(width 0.0889)
		(layer "In2.Cu")
		(net "M_C_CPU0_SA_PAR")
	)
	(arc
		(start 333.213964 -255.501648)
		(mid 332.931008 -255.577825)
		(end 332.648052 -255.501648)
		(width 0.0889)
		(layer "In2.Cu")
		(net "M_C_CPU0_SA_PAR")
	)
	(arc
		(start 332.274164 -255.501648)
		(mid 331.991208 -255.577825)
		(end 331.708252 -255.501648)
		(width 0.0889)
		(layer "In2.Cu")
		(net "M_C_CPU0_SA_PAR")
	)
	(arc
		(start 329.454002 -255.501648)
		(mid 329.171046 -255.577825)
		(end 328.88809 -255.501648)
		(width 0.0889)
		(layer "In2.Cu")
		(net "M_C_CPU0_SA_PAR")
	)
	(arc
		(start 326.585072 -255.53162)
		(mid 326.356492 -255.627289)
		(end 326.110854 -255.65989)
		(width 0.0889)
		(layer "In2.Cu")
		(net "M_C_CPU0_SA_PAR")
	)
	(arc
		(start 330.394056 -255.501648)
		(mid 330.1111 -255.577825)
		(end 329.828144 -255.501648)
		(width 0.0889)
		(layer "In2.Cu")
		(net "M_C_CPU0_SA_PAR")
	)
	(arc
		(start 331.33411 -255.501648)
		(mid 331.051154 -255.577825)
		(end 330.768198 -255.501648)
		(width 0.0889)
		(layer "In2.Cu")
		(net "M_C_CPU0_SA_PAR")
	)
	(arc
		(start 334.154018 -255.501648)
		(mid 333.871062 -255.577825)
		(end 333.588106 -255.501648)
		(width 0.0889)
		(layer "In2.Cu")
		(net "M_C_CPU0_SA_PAR")
	)
	(arc
		(start 327.549256 -255.516888)
		(mid 327.27847 -255.577534)
		(end 327.011538 -255.501648)
		(width 0.0889)
		(layer "In2.Cu")
		(net "M_C_CPU0_SA_PAR")
	)
	(arc
		(start 343.491058 -255.533398)
		(mid 343.23585 -255.576875)
		(end 342.988138 -255.501648)
		(width 0.0889)
		(layer "In2.Cu")
		(net "M_C_CPU0_SA_PAR")
	)
	(arc
		(start 336.034126 -255.501648)
		(mid 335.75117 -255.577825)
		(end 335.468214 -255.501648)
		(width 0.0889)
		(layer "In2.Cu")
		(net "M_C_CPU0_SA_PAR")
	)
	(arc
		(start 328.88809 -255.501648)
		(mid 328.701146 -255.451393)
		(end 328.514202 -255.501648)
		(width 0.0889)
		(layer "In2.Cu")
		(net "M_C_CPU0_SA_PAR")
	)
	(arc
		(start 339.228176 -255.501648)
		(mid 339.045925 -255.451298)
		(end 338.862416 -255.496822)
		(width 0.0889)
		(layer "In2.Cu")
		(net "M_C_CPU0_SA_PAR")
	)
	(arc
		(start 338.854034 -255.501648)
		(mid 338.571078 -255.577825)
		(end 338.288122 -255.501648)
		(width 0.0889)
		(layer "In2.Cu")
		(net "M_C_CPU0_SA_PAR")
	)
	(arc
		(start 335.094072 -255.501648)
		(mid 334.811116 -255.577825)
		(end 334.52816 -255.501648)
		(width 0.0889)
		(layer "In2.Cu")
		(net "M_C_CPU0_SA_PAR")
	)
	(arc
		(start 339.794088 -255.501648)
		(mid 339.511132 -255.577825)
		(end 339.228176 -255.501648)
		(width 0.0889)
		(layer "In2.Cu")
		(net "M_C_CPU0_SA_PAR")
	)
	(arc
		(start 336.408268 -255.501648)
		(mid 336.226017 -255.451298)
		(end 336.042508 -255.496822)
		(width 0.0889)
		(layer "In2.Cu")
		(net "M_C_CPU0_SA_PAR")
	)
	(arc
		(start 340.16823 -255.501648)
		(mid 339.985979 -255.451298)
		(end 339.80247 -255.496822)
		(width 0.0889)
		(layer "In2.Cu")
		(net "M_C_CPU0_SA_PAR")
	)
	(arc
		(start 326.990964 -255.48971)
		(mid 326.812036 -255.450833)
		(end 326.636126 -255.501648)
		(width 0.0889)
		(layer "In2.Cu")
		(net "M_C_CPU0_SA_PAR")
	)
	(arc
		(start 331.708252 -255.501648)
		(mid 331.526001 -255.451298)
		(end 331.342492 -255.496822)
		(width 0.0889)
		(layer "In2.Cu")
		(net "M_C_CPU0_SA_PAR")
	)
	(arc
		(start 340.734142 -255.501648)
		(mid 340.451186 -255.577825)
		(end 340.16823 -255.501648)
		(width 0.0889)
		(layer "In2.Cu")
		(net "M_C_CPU0_SA_PAR")
	)
	(arc
		(start 332.648052 -255.501648)
		(mid 332.461108 -255.451393)
		(end 332.274164 -255.501648)
		(width 0.0889)
		(layer "In2.Cu")
		(net "M_C_CPU0_SA_PAR")
	)
	(arc
		(start 337.91398 -255.501648)
		(mid 337.631024 -255.577825)
		(end 337.348068 -255.501648)
		(width 0.0889)
		(layer "In2.Cu")
		(net "M_C_CPU0_SA_PAR")
	)
	(arc
		(start 334.519778 -255.496822)
		(mid 334.33627 -255.451328)
		(end 334.154018 -255.501648)
		(width 0.0889)
		(layer "In2.Cu")
		(net "M_C_CPU0_SA_PAR")
	)
	(arc
		(start 333.579724 -255.496822)
		(mid 333.396216 -255.451328)
		(end 333.213964 -255.501648)
		(width 0.0889)
		(layer "In2.Cu")
		(net "M_C_CPU0_SA_PAR")
	)
	(segment
		(start 344.207846 -247.990106)
		(end 343.740994 -247.724168)
		(width 0.12954)
		(layer "F.Cu")
		(net "M_C_CPU0_SA_DQS_DP<9>")
	)
	(segment
		(start 342.041226 -247.394222)
		(end 342.049608 -247.399048)
		(width 0.09525)
		(layer "In2.Cu")
		(net "M_C_CPU0_SA_DQS_DP<9>")
	)
	(segment
		(start 326.071738 -247.399302)
		(end 326.108568 -247.420638)
		(width 0.09525)
		(layer "In2.Cu")
		(net "M_C_CPU0_SA_DQS_DP<9>")
	)
	(segment
		(start 327.547986 -247.414288)
		(end 327.573894 -247.399302)
		(width 0.09525)
		(layer "In2.Cu")
		(net "M_C_CPU0_SA_DQS_DP<9>")
	)
	(segment
		(start 326.04837 -247.38584)
		(end 326.071738 -247.399302)
		(width 0.09525)
		(layer "In2.Cu")
		(net "M_C_CPU0_SA_DQS_DP<9>")
	)
	(segment
		(start 305.80203 -239.411002)
		(end 306.193444 -239.411002)
		(width 0.16002)
		(layer "In2.Cu")
		(net "M_C_CPU0_SA_DQS_DP<9>")
	)
	(segment
		(start 298.962318 -239.710214)
		(end 301.314358 -239.710214)
		(width 0.16002)
		(layer "In2.Cu")
		(net "M_C_CPU0_SA_DQS_DP<9>")
	)
	(segment
		(start 326.989694 -247.385586)
		(end 327.013062 -247.399048)
		(width 0.09525)
		(layer "In2.Cu")
		(net "M_C_CPU0_SA_DQS_DP<9>")
	)
	(segment
		(start 291.65423 -239.969548)
		(end 293.989252 -239.969548)
		(width 0.16002)
		(layer "In2.Cu")
		(net "M_C_CPU0_SA_DQS_DP<9>")
	)
	(segment
		(start 315.191394 -246.945912)
		(end 322.58127 -246.945912)
		(width 0.16002)
		(layer "In2.Cu")
		(net "M_C_CPU0_SA_DQS_DP<9>")
	)
	(segment
		(start 304.999898 -240.213134)
		(end 305.80203 -239.411002)
		(width 0.16002)
		(layer "In2.Cu")
		(net "M_C_CPU0_SA_DQS_DP<9>")
	)
	(segment
		(start 298.271438 -239.382554)
		(end 298.634658 -239.382554)
		(width 0.16002)
		(layer "In2.Cu")
		(net "M_C_CPU0_SA_DQS_DP<9>")
	)
	(segment
		(start 306.452016 -239.669574)
		(end 307.915056 -239.669574)
		(width 0.16002)
		(layer "In2.Cu")
		(net "M_C_CPU0_SA_DQS_DP<9>")
	)
	(segment
		(start 330.392532 -247.399048)
		(end 330.400914 -247.394222)
		(width 0.09525)
		(layer "In2.Cu")
		(net "M_C_CPU0_SA_DQS_DP<9>")
	)
	(segment
		(start 296.60342 -240.560352)
		(end 296.927778 -240.235994)
		(width 0.16002)
		(layer "In2.Cu")
		(net "M_C_CPU0_SA_DQS_DP<9>")
	)
	(segment
		(start 291.046916 -239.362234)
		(end 291.65423 -239.969548)
		(width 0.16002)
		(layer "In2.Cu")
		(net "M_C_CPU0_SA_DQS_DP<9>")
	)
	(segment
		(start 336.032602 -247.399048)
		(end 336.040984 -247.394222)
		(width 0.09525)
		(layer "In2.Cu")
		(net "M_C_CPU0_SA_DQS_DP<9>")
	)
	(segment
		(start 333.581248 -247.394222)
		(end 333.58963 -247.399048)
		(width 0.09525)
		(layer "In2.Cu")
		(net "M_C_CPU0_SA_DQS_DP<9>")
	)
	(segment
		(start 288.45383 -239.56137)
		(end 289.972496 -239.56137)
		(width 0.16002)
		(layer "In2.Cu")
		(net "M_C_CPU0_SA_DQS_DP<9>")
	)
	(segment
		(start 343.58707 -247.458738)
		(end 343.740994 -247.724168)
		(width 0.09525)
		(layer "In2.Cu")
		(net "M_C_CPU0_SA_DQS_DP<9>")
	)
	(segment
		(start 304.486818 -240.213134)
		(end 304.999898 -240.213134)
		(width 0.16002)
		(layer "In2.Cu")
		(net "M_C_CPU0_SA_DQS_DP<9>")
	)
	(segment
		(start 342.98128 -247.394222)
		(end 342.989662 -247.399048)
		(width 0.09525)
		(layer "In2.Cu")
		(net "M_C_CPU0_SA_DQS_DP<9>")
	)
	(segment
		(start 293.989252 -239.969548)
		(end 294.580056 -240.560352)
		(width 0.16002)
		(layer "In2.Cu")
		(net "M_C_CPU0_SA_DQS_DP<9>")
	)
	(segment
		(start 290.171632 -239.362234)
		(end 291.046916 -239.362234)
		(width 0.16002)
		(layer "In2.Cu")
		(net "M_C_CPU0_SA_DQS_DP<9>")
	)
	(segment
		(start 306.193444 -239.411002)
		(end 306.452016 -239.669574)
		(width 0.16002)
		(layer "In2.Cu")
		(net "M_C_CPU0_SA_DQS_DP<9>")
	)
	(segment
		(start 334.521302 -247.394222)
		(end 334.529684 -247.399048)
		(width 0.09525)
		(layer "In2.Cu")
		(net "M_C_CPU0_SA_DQS_DP<9>")
	)
	(segment
		(start 324.090792 -247.534176)
		(end 324.122034 -247.502934)
		(width 0.09525)
		(layer "In2.Cu")
		(net "M_C_CPU0_SA_DQS_DP<9>")
	)
	(segment
		(start 307.915056 -239.669574)
		(end 315.191394 -246.945912)
		(width 0.16002)
		(layer "In2.Cu")
		(net "M_C_CPU0_SA_DQS_DP<9>")
	)
	(segment
		(start 302.137318 -240.533174)
		(end 304.166778 -240.533174)
		(width 0.16002)
		(layer "In2.Cu")
		(net "M_C_CPU0_SA_DQS_DP<9>")
	)
	(segment
		(start 298.634658 -239.382554)
		(end 298.962318 -239.710214)
		(width 0.16002)
		(layer "In2.Cu")
		(net "M_C_CPU0_SA_DQS_DP<9>")
	)
	(segment
		(start 324.06717 -247.534176)
		(end 324.090792 -247.534176)
		(width 0.09525)
		(layer "In2.Cu")
		(net "M_C_CPU0_SA_DQS_DP<9>")
	)
	(segment
		(start 288.180018 -239.835182)
		(end 288.45383 -239.56137)
		(width 0.16002)
		(layer "In2.Cu")
		(net "M_C_CPU0_SA_DQS_DP<9>")
	)
	(segment
		(start 296.927778 -240.235994)
		(end 297.417998 -240.235994)
		(width 0.16002)
		(layer "In2.Cu")
		(net "M_C_CPU0_SA_DQS_DP<9>")
	)
	(segment
		(start 338.85251 -247.399048)
		(end 338.860892 -247.394222)
		(width 0.09525)
		(layer "In2.Cu")
		(net "M_C_CPU0_SA_DQS_DP<9>")
	)
	(segment
		(start 297.417998 -240.235994)
		(end 298.271438 -239.382554)
		(width 0.16002)
		(layer "In2.Cu")
		(net "M_C_CPU0_SA_DQS_DP<9>")
	)
	(segment
		(start 289.972496 -239.56137)
		(end 290.171632 -239.362234)
		(width 0.16002)
		(layer "In2.Cu")
		(net "M_C_CPU0_SA_DQS_DP<9>")
	)
	(segment
		(start 335.092548 -247.399048)
		(end 335.10093 -247.394222)
		(width 0.09525)
		(layer "In2.Cu")
		(net "M_C_CPU0_SA_DQS_DP<9>")
	)
	(segment
		(start 324.189344 -247.474994)
		(end 325.41464 -247.474994)
		(width 0.09525)
		(layer "In2.Cu")
		(net "M_C_CPU0_SA_DQS_DP<9>")
	)
	(segment
		(start 327.573894 -247.399302)
		(end 327.597262 -247.38584)
		(width 0.09525)
		(layer "In2.Cu")
		(net "M_C_CPU0_SA_DQS_DP<9>")
	)
	(segment
		(start 343.486232 -247.432068)
		(end 343.58707 -247.458738)
		(width 0.09525)
		(layer "In2.Cu")
		(net "M_C_CPU0_SA_DQS_DP<9>")
	)
	(segment
		(start 323.169534 -247.534176)
		(end 324.06717 -247.534176)
		(width 0.16002)
		(layer "In2.Cu")
		(net "M_C_CPU0_SA_DQS_DP<9>")
	)
	(segment
		(start 294.580056 -240.560352)
		(end 296.60342 -240.560352)
		(width 0.16002)
		(layer "In2.Cu")
		(net "M_C_CPU0_SA_DQS_DP<9>")
	)
	(segment
		(start 338.281264 -247.394222)
		(end 338.289646 -247.399048)
		(width 0.09525)
		(layer "In2.Cu")
		(net "M_C_CPU0_SA_DQS_DP<9>")
	)
	(segment
		(start 301.314358 -239.710214)
		(end 302.137318 -240.533174)
		(width 0.16002)
		(layer "In2.Cu")
		(net "M_C_CPU0_SA_DQS_DP<9>")
	)
	(segment
		(start 331.332586 -247.399048)
		(end 331.340968 -247.394222)
		(width 0.09525)
		(layer "In2.Cu")
		(net "M_C_CPU0_SA_DQS_DP<9>")
	)
	(segment
		(start 322.58127 -246.945912)
		(end 323.169534 -247.534176)
		(width 0.16002)
		(layer "In2.Cu")
		(net "M_C_CPU0_SA_DQS_DP<9>")
	)
	(segment
		(start 329.821286 -247.394222)
		(end 329.829668 -247.399048)
		(width 0.09525)
		(layer "In2.Cu")
		(net "M_C_CPU0_SA_DQS_DP<9>")
	)
	(segment
		(start 339.792564 -247.399048)
		(end 339.800946 -247.394222)
		(width 0.09525)
		(layer "In2.Cu")
		(net "M_C_CPU0_SA_DQS_DP<9>")
	)
	(segment
		(start 304.166778 -240.533174)
		(end 304.486818 -240.213134)
		(width 0.16002)
		(layer "In2.Cu")
		(net "M_C_CPU0_SA_DQS_DP<9>")
	)
	(arc
		(start 328.512678 -247.399048)
		(mid 328.701146 -247.348371)
		(end 328.889614 -247.399048)
		(width 0.09525)
		(layer "In2.Cu")
		(net "M_C_CPU0_SA_DQS_DP<9>")
	)
	(arc
		(start 325.41464 -247.474994)
		(mid 325.56052 -247.455689)
		(end 325.696326 -247.399048)
		(width 0.09525)
		(layer "In2.Cu")
		(net "M_C_CPU0_SA_DQS_DP<9>")
	)
	(arc
		(start 338.289646 -247.399048)
		(mid 338.571078 -247.474803)
		(end 338.85251 -247.399048)
		(width 0.09525)
		(layer "In2.Cu")
		(net "M_C_CPU0_SA_DQS_DP<9>")
	)
	(arc
		(start 339.800946 -247.394222)
		(mid 339.985978 -247.348308)
		(end 340.169754 -247.399048)
		(width 0.09525)
		(layer "In2.Cu")
		(net "M_C_CPU0_SA_DQS_DP<9>")
	)
	(arc
		(start 330.769722 -247.399048)
		(mid 331.051154 -247.474803)
		(end 331.332586 -247.399048)
		(width 0.09525)
		(layer "In2.Cu")
		(net "M_C_CPU0_SA_DQS_DP<9>")
	)
	(arc
		(start 340.169754 -247.399048)
		(mid 340.451186 -247.474803)
		(end 340.732618 -247.399048)
		(width 0.09525)
		(layer "In2.Cu")
		(net "M_C_CPU0_SA_DQS_DP<9>")
	)
	(arc
		(start 331.340968 -247.394222)
		(mid 331.526 -247.348308)
		(end 331.709776 -247.399048)
		(width 0.09525)
		(layer "In2.Cu")
		(net "M_C_CPU0_SA_DQS_DP<9>")
	)
	(arc
		(start 339.2297 -247.399048)
		(mid 339.511132 -247.474803)
		(end 339.792564 -247.399048)
		(width 0.09525)
		(layer "In2.Cu")
		(net "M_C_CPU0_SA_DQS_DP<9>")
	)
	(arc
		(start 342.989662 -247.399048)
		(mid 343.223457 -247.472915)
		(end 343.46642 -247.439942)
		(width 0.09525)
		(layer "In2.Cu")
		(net "M_C_CPU0_SA_DQS_DP<9>")
	)
	(arc
		(start 336.409792 -247.399048)
		(mid 336.691224 -247.474803)
		(end 336.972656 -247.399048)
		(width 0.09525)
		(layer "In2.Cu")
		(net "M_C_CPU0_SA_DQS_DP<9>")
	)
	(arc
		(start 333.21244 -247.399048)
		(mid 333.396215 -247.348276)
		(end 333.581248 -247.394222)
		(width 0.09525)
		(layer "In2.Cu")
		(net "M_C_CPU0_SA_DQS_DP<9>")
	)
	(arc
		(start 334.529684 -247.399048)
		(mid 334.811116 -247.474803)
		(end 335.092548 -247.399048)
		(width 0.09525)
		(layer "In2.Cu")
		(net "M_C_CPU0_SA_DQS_DP<9>")
	)
	(arc
		(start 329.829668 -247.399048)
		(mid 330.1111 -247.474803)
		(end 330.392532 -247.399048)
		(width 0.09525)
		(layer "In2.Cu")
		(net "M_C_CPU0_SA_DQS_DP<9>")
	)
	(arc
		(start 326.634602 -247.398794)
		(mid 326.810503 -247.347649)
		(end 326.989694 -247.385586)
		(width 0.09525)
		(layer "In2.Cu")
		(net "M_C_CPU0_SA_DQS_DP<9>")
	)
	(arc
		(start 342.612472 -247.399048)
		(mid 342.796247 -247.348276)
		(end 342.98128 -247.394222)
		(width 0.09525)
		(layer "In2.Cu")
		(net "M_C_CPU0_SA_DQS_DP<9>")
	)
	(arc
		(start 332.649576 -247.399048)
		(mid 332.931008 -247.474803)
		(end 333.21244 -247.399048)
		(width 0.09525)
		(layer "In2.Cu")
		(net "M_C_CPU0_SA_DQS_DP<9>")
	)
	(arc
		(start 336.040984 -247.394222)
		(mid 336.226016 -247.348308)
		(end 336.409792 -247.399048)
		(width 0.09525)
		(layer "In2.Cu")
		(net "M_C_CPU0_SA_DQS_DP<9>")
	)
	(arc
		(start 327.013062 -247.399048)
		(mid 327.278582 -247.474577)
		(end 327.547986 -247.414288)
		(width 0.09525)
		(layer "In2.Cu")
		(net "M_C_CPU0_SA_DQS_DP<9>")
	)
	(arc
		(start 332.27264 -247.399048)
		(mid 332.461108 -247.348371)
		(end 332.649576 -247.399048)
		(width 0.09525)
		(layer "In2.Cu")
		(net "M_C_CPU0_SA_DQS_DP<9>")
	)
	(arc
		(start 340.732618 -247.399048)
		(mid 340.921086 -247.348371)
		(end 341.109554 -247.399048)
		(width 0.09525)
		(layer "In2.Cu")
		(net "M_C_CPU0_SA_DQS_DP<9>")
	)
	(arc
		(start 327.949814 -247.399048)
		(mid 328.231246 -247.474803)
		(end 328.512678 -247.399048)
		(width 0.09525)
		(layer "In2.Cu")
		(net "M_C_CPU0_SA_DQS_DP<9>")
	)
	(arc
		(start 324.122034 -247.502934)
		(mid 324.152902 -247.482245)
		(end 324.189344 -247.474994)
		(width 0.09525)
		(layer "In2.Cu")
		(net "M_C_CPU0_SA_DQS_DP<9>")
	)
	(arc
		(start 335.10093 -247.394222)
		(mid 335.285962 -247.348308)
		(end 335.469738 -247.399048)
		(width 0.09525)
		(layer "In2.Cu")
		(net "M_C_CPU0_SA_DQS_DP<9>")
	)
	(arc
		(start 331.709776 -247.399048)
		(mid 331.991208 -247.474803)
		(end 332.27264 -247.399048)
		(width 0.09525)
		(layer "In2.Cu")
		(net "M_C_CPU0_SA_DQS_DP<9>")
	)
	(arc
		(start 338.860892 -247.394222)
		(mid 339.045924 -247.348308)
		(end 339.2297 -247.399048)
		(width 0.09525)
		(layer "In2.Cu")
		(net "M_C_CPU0_SA_DQS_DP<9>")
	)
	(arc
		(start 326.108568 -247.420638)
		(mid 326.374287 -247.475132)
		(end 326.634602 -247.398794)
		(width 0.09525)
		(layer "In2.Cu")
		(net "M_C_CPU0_SA_DQS_DP<9>")
	)
	(arc
		(start 336.972656 -247.399048)
		(mid 337.161124 -247.348371)
		(end 337.349592 -247.399048)
		(width 0.09525)
		(layer "In2.Cu")
		(net "M_C_CPU0_SA_DQS_DP<9>")
	)
	(arc
		(start 328.889614 -247.399048)
		(mid 329.171046 -247.474803)
		(end 329.452478 -247.399048)
		(width 0.09525)
		(layer "In2.Cu")
		(net "M_C_CPU0_SA_DQS_DP<9>")
	)
	(arc
		(start 337.349592 -247.399048)
		(mid 337.631024 -247.474803)
		(end 337.912456 -247.399048)
		(width 0.09525)
		(layer "In2.Cu")
		(net "M_C_CPU0_SA_DQS_DP<9>")
	)
	(arc
		(start 341.672418 -247.399048)
		(mid 341.856193 -247.348276)
		(end 342.041226 -247.394222)
		(width 0.09525)
		(layer "In2.Cu")
		(net "M_C_CPU0_SA_DQS_DP<9>")
	)
	(arc
		(start 341.109554 -247.399048)
		(mid 341.390986 -247.474803)
		(end 341.672418 -247.399048)
		(width 0.09525)
		(layer "In2.Cu")
		(net "M_C_CPU0_SA_DQS_DP<9>")
	)
	(arc
		(start 337.912456 -247.399048)
		(mid 338.096231 -247.348276)
		(end 338.281264 -247.394222)
		(width 0.09525)
		(layer "In2.Cu")
		(net "M_C_CPU0_SA_DQS_DP<9>")
	)
	(arc
		(start 327.597262 -247.38584)
		(mid 327.775181 -247.348525)
		(end 327.949814 -247.399048)
		(width 0.09525)
		(layer "In2.Cu")
		(net "M_C_CPU0_SA_DQS_DP<9>")
	)
	(arc
		(start 333.58963 -247.399048)
		(mid 333.871062 -247.474803)
		(end 334.152494 -247.399048)
		(width 0.09525)
		(layer "In2.Cu")
		(net "M_C_CPU0_SA_DQS_DP<9>")
	)
	(arc
		(start 329.452478 -247.399048)
		(mid 329.636253 -247.348276)
		(end 329.821286 -247.394222)
		(width 0.09525)
		(layer "In2.Cu")
		(net "M_C_CPU0_SA_DQS_DP<9>")
	)
	(arc
		(start 334.152494 -247.399048)
		(mid 334.336269 -247.348276)
		(end 334.521302 -247.394222)
		(width 0.09525)
		(layer "In2.Cu")
		(net "M_C_CPU0_SA_DQS_DP<9>")
	)
	(arc
		(start 325.696326 -247.399048)
		(mid 325.870704 -247.348635)
		(end 326.04837 -247.38584)
		(width 0.09525)
		(layer "In2.Cu")
		(net "M_C_CPU0_SA_DQS_DP<9>")
	)
	(arc
		(start 342.049608 -247.399048)
		(mid 342.33104 -247.474803)
		(end 342.612472 -247.399048)
		(width 0.09525)
		(layer "In2.Cu")
		(net "M_C_CPU0_SA_DQS_DP<9>")
	)
	(arc
		(start 343.46642 -247.439942)
		(mid 343.476363 -247.436099)
		(end 343.486232 -247.432068)
		(width 0.09525)
		(layer "In2.Cu")
		(net "M_C_CPU0_SA_DQS_DP<9>")
	)
	(arc
		(start 330.400914 -247.394222)
		(mid 330.585946 -247.348308)
		(end 330.769722 -247.399048)
		(width 0.09525)
		(layer "In2.Cu")
		(net "M_C_CPU0_SA_DQS_DP<9>")
	)
	(arc
		(start 335.469738 -247.399048)
		(mid 335.75117 -247.474803)
		(end 336.032602 -247.399048)
		(width 0.09525)
		(layer "In2.Cu")
		(net "M_C_CPU0_SA_DQS_DP<9>")
	)
	(segment
		(start 344.207846 -243.13007)
		(end 343.740994 -242.864132)
		(width 0.12954)
		(layer "F.Cu")
		(net "M_C_CPU0_SA_DQS_DP<8>")
	)
	(segment
		(start 334.521302 -242.534186)
		(end 334.529684 -242.539012)
		(width 0.09525)
		(layer "In2.Cu")
		(net "M_C_CPU0_SA_DQS_DP<8>")
	)
	(segment
		(start 319.776094 -241.25555)
		(end 323.895974 -241.25555)
		(width 0.16002)
		(layer "In2.Cu")
		(net "M_C_CPU0_SA_DQS_DP<8>")
	)
	(segment
		(start 323.895974 -241.25555)
		(end 323.919596 -241.25555)
		(width 0.09525)
		(layer "In2.Cu")
		(net "M_C_CPU0_SA_DQS_DP<8>")
	)
	(segment
		(start 335.092548 -242.539012)
		(end 335.10093 -242.534186)
		(width 0.09525)
		(layer "In2.Cu")
		(net "M_C_CPU0_SA_DQS_DP<8>")
	)
	(segment
		(start 324.202806 -241.196622)
		(end 324.302628 -241.0968)
		(width 0.09525)
		(layer "In2.Cu")
		(net "M_C_CPU0_SA_DQS_DP<8>")
	)
	(segment
		(start 294.580056 -231.210358)
		(end 296.60342 -231.210358)
		(width 0.16002)
		(layer "In2.Cu")
		(net "M_C_CPU0_SA_DQS_DP<8>")
	)
	(segment
		(start 298.922186 -230.36022)
		(end 301.314358 -230.36022)
		(width 0.16002)
		(layer "In2.Cu")
		(net "M_C_CPU0_SA_DQS_DP<8>")
	)
	(segment
		(start 326.979788 -242.520724)
		(end 327.011792 -242.539266)
		(width 0.09525)
		(layer "In2.Cu")
		(net "M_C_CPU0_SA_DQS_DP<8>")
	)
	(segment
		(start 325.195184 -241.690144)
		(end 325.955152 -242.450112)
		(width 0.09525)
		(layer "In2.Cu")
		(net "M_C_CPU0_SA_DQS_DP<8>")
	)
	(segment
		(start 342.041226 -242.534186)
		(end 342.049608 -242.539012)
		(width 0.09525)
		(layer "In2.Cu")
		(net "M_C_CPU0_SA_DQS_DP<8>")
	)
	(segment
		(start 326.071738 -242.539266)
		(end 326.108568 -242.560602)
		(width 0.09525)
		(layer "In2.Cu")
		(net "M_C_CPU0_SA_DQS_DP<8>")
	)
	(segment
		(start 327.572624 -242.539012)
		(end 327.581006 -242.534186)
		(width 0.09525)
		(layer "In2.Cu")
		(net "M_C_CPU0_SA_DQS_DP<8>")
	)
	(segment
		(start 325.195184 -241.422174)
		(end 325.195184 -241.690144)
		(width 0.09525)
		(layer "In2.Cu")
		(net "M_C_CPU0_SA_DQS_DP<8>")
	)
	(segment
		(start 290.171632 -230.01224)
		(end 291.046916 -230.01224)
		(width 0.16002)
		(layer "In2.Cu")
		(net "M_C_CPU0_SA_DQS_DP<8>")
	)
	(segment
		(start 304.980086 -230.86314)
		(end 305.782218 -230.061008)
		(width 0.16002)
		(layer "In2.Cu")
		(net "M_C_CPU0_SA_DQS_DP<8>")
	)
	(segment
		(start 324.86981 -241.0968)
		(end 325.195184 -241.422174)
		(width 0.09525)
		(layer "In2.Cu")
		(net "M_C_CPU0_SA_DQS_DP<8>")
	)
	(segment
		(start 296.927778 -230.886)
		(end 297.417998 -230.886)
		(width 0.16002)
		(layer "In2.Cu")
		(net "M_C_CPU0_SA_DQS_DP<8>")
	)
	(segment
		(start 338.85251 -242.539012)
		(end 338.860892 -242.534186)
		(width 0.09525)
		(layer "In2.Cu")
		(net "M_C_CPU0_SA_DQS_DP<8>")
	)
	(segment
		(start 342.98128 -242.534186)
		(end 342.989662 -242.539012)
		(width 0.09525)
		(layer "In2.Cu")
		(net "M_C_CPU0_SA_DQS_DP<8>")
	)
	(segment
		(start 291.65423 -230.619554)
		(end 293.989252 -230.619554)
		(width 0.16002)
		(layer "In2.Cu")
		(net "M_C_CPU0_SA_DQS_DP<8>")
	)
	(segment
		(start 323.978524 -241.196622)
		(end 324.202806 -241.196622)
		(width 0.09525)
		(layer "In2.Cu")
		(net "M_C_CPU0_SA_DQS_DP<8>")
	)
	(segment
		(start 302.137318 -231.18318)
		(end 304.185066 -231.18318)
		(width 0.16002)
		(layer "In2.Cu")
		(net "M_C_CPU0_SA_DQS_DP<8>")
	)
	(segment
		(start 324.302628 -241.0968)
		(end 324.86981 -241.0968)
		(width 0.09525)
		(layer "In2.Cu")
		(net "M_C_CPU0_SA_DQS_DP<8>")
	)
	(segment
		(start 305.782218 -230.061008)
		(end 306.193444 -230.061008)
		(width 0.16002)
		(layer "In2.Cu")
		(net "M_C_CPU0_SA_DQS_DP<8>")
	)
	(segment
		(start 301.314358 -230.36022)
		(end 302.137318 -231.18318)
		(width 0.16002)
		(layer "In2.Cu")
		(net "M_C_CPU0_SA_DQS_DP<8>")
	)
	(segment
		(start 333.581248 -242.534186)
		(end 333.58963 -242.539012)
		(width 0.09525)
		(layer "In2.Cu")
		(net "M_C_CPU0_SA_DQS_DP<8>")
	)
	(segment
		(start 304.505106 -230.86314)
		(end 304.980086 -230.86314)
		(width 0.16002)
		(layer "In2.Cu")
		(net "M_C_CPU0_SA_DQS_DP<8>")
	)
	(segment
		(start 330.392532 -242.539012)
		(end 330.400914 -242.534186)
		(width 0.09525)
		(layer "In2.Cu")
		(net "M_C_CPU0_SA_DQS_DP<8>")
	)
	(segment
		(start 298.271438 -230.03256)
		(end 298.594526 -230.03256)
		(width 0.16002)
		(layer "In2.Cu")
		(net "M_C_CPU0_SA_DQS_DP<8>")
	)
	(segment
		(start 343.486232 -242.572032)
		(end 343.58707 -242.598702)
		(width 0.09525)
		(layer "In2.Cu")
		(net "M_C_CPU0_SA_DQS_DP<8>")
	)
	(segment
		(start 296.60342 -231.210358)
		(end 296.927778 -230.886)
		(width 0.16002)
		(layer "In2.Cu")
		(net "M_C_CPU0_SA_DQS_DP<8>")
	)
	(segment
		(start 308.840124 -230.31958)
		(end 319.776094 -241.25555)
		(width 0.16002)
		(layer "In2.Cu")
		(net "M_C_CPU0_SA_DQS_DP<8>")
	)
	(segment
		(start 304.185066 -231.18318)
		(end 304.505106 -230.86314)
		(width 0.16002)
		(layer "In2.Cu")
		(net "M_C_CPU0_SA_DQS_DP<8>")
	)
	(segment
		(start 288.180018 -230.485188)
		(end 288.45383 -230.211376)
		(width 0.16002)
		(layer "In2.Cu")
		(net "M_C_CPU0_SA_DQS_DP<8>")
	)
	(segment
		(start 343.58707 -242.598702)
		(end 343.740994 -242.864132)
		(width 0.09525)
		(layer "In2.Cu")
		(net "M_C_CPU0_SA_DQS_DP<8>")
	)
	(segment
		(start 336.032602 -242.539012)
		(end 336.040984 -242.534186)
		(width 0.09525)
		(layer "In2.Cu")
		(net "M_C_CPU0_SA_DQS_DP<8>")
	)
	(segment
		(start 293.989252 -230.619554)
		(end 294.580056 -231.210358)
		(width 0.16002)
		(layer "In2.Cu")
		(net "M_C_CPU0_SA_DQS_DP<8>")
	)
	(segment
		(start 297.417998 -230.886)
		(end 298.271438 -230.03256)
		(width 0.16002)
		(layer "In2.Cu")
		(net "M_C_CPU0_SA_DQS_DP<8>")
	)
	(segment
		(start 331.332586 -242.539012)
		(end 331.340968 -242.534186)
		(width 0.09525)
		(layer "In2.Cu")
		(net "M_C_CPU0_SA_DQS_DP<8>")
	)
	(segment
		(start 329.821286 -242.534186)
		(end 329.829668 -242.539012)
		(width 0.09525)
		(layer "In2.Cu")
		(net "M_C_CPU0_SA_DQS_DP<8>")
	)
	(segment
		(start 298.594526 -230.03256)
		(end 298.922186 -230.36022)
		(width 0.16002)
		(layer "In2.Cu")
		(net "M_C_CPU0_SA_DQS_DP<8>")
	)
	(segment
		(start 339.792564 -242.539012)
		(end 339.800946 -242.534186)
		(width 0.09525)
		(layer "In2.Cu")
		(net "M_C_CPU0_SA_DQS_DP<8>")
	)
	(segment
		(start 288.45383 -230.211376)
		(end 289.972496 -230.211376)
		(width 0.16002)
		(layer "In2.Cu")
		(net "M_C_CPU0_SA_DQS_DP<8>")
	)
	(segment
		(start 327.011792 -242.539266)
		(end 327.0377 -242.554252)
		(width 0.09525)
		(layer "In2.Cu")
		(net "M_C_CPU0_SA_DQS_DP<8>")
	)
	(segment
		(start 289.972496 -230.211376)
		(end 290.171632 -230.01224)
		(width 0.16002)
		(layer "In2.Cu")
		(net "M_C_CPU0_SA_DQS_DP<8>")
	)
	(segment
		(start 323.919596 -241.25555)
		(end 323.978524 -241.196622)
		(width 0.09525)
		(layer "In2.Cu")
		(net "M_C_CPU0_SA_DQS_DP<8>")
	)
	(segment
		(start 338.281264 -242.534186)
		(end 338.289646 -242.539012)
		(width 0.09525)
		(layer "In2.Cu")
		(net "M_C_CPU0_SA_DQS_DP<8>")
	)
	(segment
		(start 306.452016 -230.31958)
		(end 308.840124 -230.31958)
		(width 0.16002)
		(layer "In2.Cu")
		(net "M_C_CPU0_SA_DQS_DP<8>")
	)
	(segment
		(start 291.046916 -230.01224)
		(end 291.65423 -230.619554)
		(width 0.16002)
		(layer "In2.Cu")
		(net "M_C_CPU0_SA_DQS_DP<8>")
	)
	(segment
		(start 306.193444 -230.061008)
		(end 306.452016 -230.31958)
		(width 0.16002)
		(layer "In2.Cu")
		(net "M_C_CPU0_SA_DQS_DP<8>")
	)
	(arc
		(start 328.512678 -242.539012)
		(mid 328.701146 -242.488335)
		(end 328.889614 -242.539012)
		(width 0.09525)
		(layer "In2.Cu")
		(net "M_C_CPU0_SA_DQS_DP<8>")
	)
	(arc
		(start 335.469738 -242.539012)
		(mid 335.75117 -242.614767)
		(end 336.032602 -242.539012)
		(width 0.09525)
		(layer "In2.Cu")
		(net "M_C_CPU0_SA_DQS_DP<8>")
	)
	(arc
		(start 333.21244 -242.539012)
		(mid 333.396215 -242.48824)
		(end 333.581248 -242.534186)
		(width 0.09525)
		(layer "In2.Cu")
		(net "M_C_CPU0_SA_DQS_DP<8>")
	)
	(arc
		(start 337.912456 -242.539012)
		(mid 338.096231 -242.48824)
		(end 338.281264 -242.534186)
		(width 0.09525)
		(layer "In2.Cu")
		(net "M_C_CPU0_SA_DQS_DP<8>")
	)
	(arc
		(start 336.972656 -242.539012)
		(mid 337.161124 -242.488335)
		(end 337.349592 -242.539012)
		(width 0.09525)
		(layer "In2.Cu")
		(net "M_C_CPU0_SA_DQS_DP<8>")
	)
	(arc
		(start 339.800946 -242.534186)
		(mid 339.985978 -242.488272)
		(end 340.169754 -242.539012)
		(width 0.09525)
		(layer "In2.Cu")
		(net "M_C_CPU0_SA_DQS_DP<8>")
	)
	(arc
		(start 338.860892 -242.534186)
		(mid 339.045924 -242.488272)
		(end 339.2297 -242.539012)
		(width 0.09525)
		(layer "In2.Cu")
		(net "M_C_CPU0_SA_DQS_DP<8>")
	)
	(arc
		(start 341.672418 -242.539012)
		(mid 341.856193 -242.48824)
		(end 342.041226 -242.534186)
		(width 0.09525)
		(layer "In2.Cu")
		(net "M_C_CPU0_SA_DQS_DP<8>")
	)
	(arc
		(start 342.049608 -242.539012)
		(mid 342.33104 -242.614767)
		(end 342.612472 -242.539012)
		(width 0.09525)
		(layer "In2.Cu")
		(net "M_C_CPU0_SA_DQS_DP<8>")
	)
	(arc
		(start 325.955152 -242.450112)
		(mid 326.010505 -242.498534)
		(end 326.071738 -242.539266)
		(width 0.09525)
		(layer "In2.Cu")
		(net "M_C_CPU0_SA_DQS_DP<8>")
	)
	(arc
		(start 337.349592 -242.539012)
		(mid 337.631024 -242.614767)
		(end 337.912456 -242.539012)
		(width 0.09525)
		(layer "In2.Cu")
		(net "M_C_CPU0_SA_DQS_DP<8>")
	)
	(arc
		(start 343.46642 -242.579906)
		(mid 343.476363 -242.576063)
		(end 343.486232 -242.572032)
		(width 0.09525)
		(layer "In2.Cu")
		(net "M_C_CPU0_SA_DQS_DP<8>")
	)
	(arc
		(start 330.769722 -242.539012)
		(mid 331.051154 -242.614767)
		(end 331.332586 -242.539012)
		(width 0.09525)
		(layer "In2.Cu")
		(net "M_C_CPU0_SA_DQS_DP<8>")
	)
	(arc
		(start 341.109554 -242.539012)
		(mid 341.390986 -242.614767)
		(end 341.672418 -242.539012)
		(width 0.09525)
		(layer "In2.Cu")
		(net "M_C_CPU0_SA_DQS_DP<8>")
	)
	(arc
		(start 342.989662 -242.539012)
		(mid 343.223457 -242.612879)
		(end 343.46642 -242.579906)
		(width 0.09525)
		(layer "In2.Cu")
		(net "M_C_CPU0_SA_DQS_DP<8>")
	)
	(arc
		(start 333.58963 -242.539012)
		(mid 333.871062 -242.614767)
		(end 334.152494 -242.539012)
		(width 0.09525)
		(layer "In2.Cu")
		(net "M_C_CPU0_SA_DQS_DP<8>")
	)
	(arc
		(start 342.612472 -242.539012)
		(mid 342.796247 -242.48824)
		(end 342.98128 -242.534186)
		(width 0.09525)
		(layer "In2.Cu")
		(net "M_C_CPU0_SA_DQS_DP<8>")
	)
	(arc
		(start 334.529684 -242.539012)
		(mid 334.811116 -242.614767)
		(end 335.092548 -242.539012)
		(width 0.09525)
		(layer "In2.Cu")
		(net "M_C_CPU0_SA_DQS_DP<8>")
	)
	(arc
		(start 338.289646 -242.539012)
		(mid 338.571078 -242.614767)
		(end 338.85251 -242.539012)
		(width 0.09525)
		(layer "In2.Cu")
		(net "M_C_CPU0_SA_DQS_DP<8>")
	)
	(arc
		(start 340.732618 -242.539012)
		(mid 340.921086 -242.488335)
		(end 341.109554 -242.539012)
		(width 0.09525)
		(layer "In2.Cu")
		(net "M_C_CPU0_SA_DQS_DP<8>")
	)
	(arc
		(start 327.581006 -242.534186)
		(mid 327.766038 -242.488272)
		(end 327.949814 -242.539012)
		(width 0.09525)
		(layer "In2.Cu")
		(net "M_C_CPU0_SA_DQS_DP<8>")
	)
	(arc
		(start 330.400914 -242.534186)
		(mid 330.585946 -242.488272)
		(end 330.769722 -242.539012)
		(width 0.09525)
		(layer "In2.Cu")
		(net "M_C_CPU0_SA_DQS_DP<8>")
	)
	(arc
		(start 332.27264 -242.539012)
		(mid 332.461108 -242.488335)
		(end 332.649576 -242.539012)
		(width 0.09525)
		(layer "In2.Cu")
		(net "M_C_CPU0_SA_DQS_DP<8>")
	)
	(arc
		(start 339.2297 -242.539012)
		(mid 339.511132 -242.614767)
		(end 339.792564 -242.539012)
		(width 0.09525)
		(layer "In2.Cu")
		(net "M_C_CPU0_SA_DQS_DP<8>")
	)
	(arc
		(start 328.889614 -242.539012)
		(mid 329.171046 -242.614767)
		(end 329.452478 -242.539012)
		(width 0.09525)
		(layer "In2.Cu")
		(net "M_C_CPU0_SA_DQS_DP<8>")
	)
	(arc
		(start 332.649576 -242.539012)
		(mid 332.931008 -242.614767)
		(end 333.21244 -242.539012)
		(width 0.09525)
		(layer "In2.Cu")
		(net "M_C_CPU0_SA_DQS_DP<8>")
	)
	(arc
		(start 329.452478 -242.539012)
		(mid 329.636253 -242.48824)
		(end 329.821286 -242.534186)
		(width 0.09525)
		(layer "In2.Cu")
		(net "M_C_CPU0_SA_DQS_DP<8>")
	)
	(arc
		(start 335.10093 -242.534186)
		(mid 335.285962 -242.488272)
		(end 335.469738 -242.539012)
		(width 0.09525)
		(layer "In2.Cu")
		(net "M_C_CPU0_SA_DQS_DP<8>")
	)
	(arc
		(start 327.949814 -242.539012)
		(mid 328.231246 -242.614767)
		(end 328.512678 -242.539012)
		(width 0.09525)
		(layer "In2.Cu")
		(net "M_C_CPU0_SA_DQS_DP<8>")
	)
	(arc
		(start 331.709776 -242.539012)
		(mid 331.991208 -242.614767)
		(end 332.27264 -242.539012)
		(width 0.09525)
		(layer "In2.Cu")
		(net "M_C_CPU0_SA_DQS_DP<8>")
	)
	(arc
		(start 340.169754 -242.539012)
		(mid 340.451186 -242.614767)
		(end 340.732618 -242.539012)
		(width 0.09525)
		(layer "In2.Cu")
		(net "M_C_CPU0_SA_DQS_DP<8>")
	)
	(arc
		(start 336.409792 -242.539012)
		(mid 336.691224 -242.614767)
		(end 336.972656 -242.539012)
		(width 0.09525)
		(layer "In2.Cu")
		(net "M_C_CPU0_SA_DQS_DP<8>")
	)
	(arc
		(start 331.340968 -242.534186)
		(mid 331.526 -242.488272)
		(end 331.709776 -242.539012)
		(width 0.09525)
		(layer "In2.Cu")
		(net "M_C_CPU0_SA_DQS_DP<8>")
	)
	(arc
		(start 327.0377 -242.554252)
		(mid 327.307106 -242.6146)
		(end 327.572624 -242.539012)
		(width 0.09525)
		(layer "In2.Cu")
		(net "M_C_CPU0_SA_DQS_DP<8>")
	)
	(arc
		(start 336.040984 -242.534186)
		(mid 336.226016 -242.488272)
		(end 336.409792 -242.539012)
		(width 0.09525)
		(layer "In2.Cu")
		(net "M_C_CPU0_SA_DQS_DP<8>")
	)
	(arc
		(start 326.108568 -242.560602)
		(mid 326.374287 -242.615096)
		(end 326.634602 -242.538758)
		(width 0.09525)
		(layer "In2.Cu")
		(net "M_C_CPU0_SA_DQS_DP<8>")
	)
	(arc
		(start 326.634602 -242.538758)
		(mid 326.804999 -242.487859)
		(end 326.979788 -242.520724)
		(width 0.09525)
		(layer "In2.Cu")
		(net "M_C_CPU0_SA_DQS_DP<8>")
	)
	(arc
		(start 329.829668 -242.539012)
		(mid 330.1111 -242.614767)
		(end 330.392532 -242.539012)
		(width 0.09525)
		(layer "In2.Cu")
		(net "M_C_CPU0_SA_DQS_DP<8>")
	)
	(arc
		(start 334.152494 -242.539012)
		(mid 334.336269 -242.48824)
		(end 334.521302 -242.534186)
		(width 0.09525)
		(layer "In2.Cu")
		(net "M_C_CPU0_SA_DQS_DP<8>")
	)
	(segment
		(start 344.207846 -238.270034)
		(end 343.740994 -238.004096)
		(width 0.12954)
		(layer "F.Cu")
		(net "M_C_CPU0_SA_DQS_DP<7>")
	)
	(segment
		(start 294.579802 -221.86011)
		(end 296.616882 -221.86011)
		(width 0.16002)
		(layer "In2.Cu")
		(net "M_C_CPU0_SA_DQS_DP<7>")
	)
	(segment
		(start 336.032602 -237.678976)
		(end 336.040984 -237.67415)
		(width 0.09525)
		(layer "In2.Cu")
		(net "M_C_CPU0_SA_DQS_DP<7>")
	)
	(segment
		(start 324.338188 -235.526072)
		(end 324.442836 -235.63072)
		(width 0.09525)
		(layer "In2.Cu")
		(net "M_C_CPU0_SA_DQS_DP<7>")
	)
	(segment
		(start 306.452016 -220.969586)
		(end 309.843678 -220.969586)
		(width 0.16002)
		(layer "In2.Cu")
		(net "M_C_CPU0_SA_DQS_DP<7>")
	)
	(segment
		(start 338.281264 -237.67415)
		(end 338.289646 -237.678976)
		(width 0.09525)
		(layer "In2.Cu")
		(net "M_C_CPU0_SA_DQS_DP<7>")
	)
	(segment
		(start 301.55388 -221.249748)
		(end 302.137318 -221.833186)
		(width 0.16002)
		(layer "In2.Cu")
		(net "M_C_CPU0_SA_DQS_DP<7>")
	)
	(segment
		(start 329.821286 -237.67415)
		(end 329.829668 -237.678976)
		(width 0.09525)
		(layer "In2.Cu")
		(net "M_C_CPU0_SA_DQS_DP<7>")
	)
	(segment
		(start 291.65423 -221.26956)
		(end 293.736014 -221.26956)
		(width 0.16002)
		(layer "In2.Cu")
		(net "M_C_CPU0_SA_DQS_DP<7>")
	)
	(segment
		(start 298.271438 -220.682566)
		(end 298.634658 -220.682566)
		(width 0.16002)
		(layer "In2.Cu")
		(net "M_C_CPU0_SA_DQS_DP<7>")
	)
	(segment
		(start 296.950384 -221.526608)
		(end 297.764708 -221.189296)
		(width 0.16002)
		(layer "In2.Cu")
		(net "M_C_CPU0_SA_DQS_DP<7>")
	)
	(segment
		(start 317.057278 -230.144066)
		(end 322.498212 -235.585)
		(width 0.16002)
		(layer "In2.Cu")
		(net "M_C_CPU0_SA_DQS_DP<7>")
	)
	(segment
		(start 290.598606 -220.707712)
		(end 291.092382 -220.707712)
		(width 0.16002)
		(layer "In2.Cu")
		(net "M_C_CPU0_SA_DQS_DP<7>")
	)
	(segment
		(start 293.736014 -221.26956)
		(end 294.168068 -221.448376)
		(width 0.16002)
		(layer "In2.Cu")
		(net "M_C_CPU0_SA_DQS_DP<7>")
	)
	(segment
		(start 342.041226 -237.67415)
		(end 342.049608 -237.678976)
		(width 0.09525)
		(layer "In2.Cu")
		(net "M_C_CPU0_SA_DQS_DP<7>")
	)
	(segment
		(start 304.166778 -221.833186)
		(end 304.583084 -221.41688)
		(width 0.16002)
		(layer "In2.Cu")
		(net "M_C_CPU0_SA_DQS_DP<7>")
	)
	(segment
		(start 323.919596 -235.585)
		(end 323.978524 -235.526072)
		(width 0.09525)
		(layer "In2.Cu")
		(net "M_C_CPU0_SA_DQS_DP<7>")
	)
	(segment
		(start 288.180018 -221.13494)
		(end 288.453576 -220.861382)
		(width 0.16002)
		(layer "In2.Cu")
		(net "M_C_CPU0_SA_DQS_DP<7>")
	)
	(segment
		(start 296.616882 -221.86011)
		(end 296.950384 -221.526608)
		(width 0.16002)
		(layer "In2.Cu")
		(net "M_C_CPU0_SA_DQS_DP<7>")
	)
	(segment
		(start 297.764708 -221.189296)
		(end 298.271438 -220.682566)
		(width 0.16002)
		(layer "In2.Cu")
		(net "M_C_CPU0_SA_DQS_DP<7>")
	)
	(segment
		(start 298.634658 -220.682566)
		(end 298.962318 -221.010226)
		(width 0.16002)
		(layer "In2.Cu")
		(net "M_C_CPU0_SA_DQS_DP<7>")
	)
	(segment
		(start 309.843678 -220.969586)
		(end 317.057278 -228.183186)
		(width 0.16002)
		(layer "In2.Cu")
		(net "M_C_CPU0_SA_DQS_DP<7>")
	)
	(segment
		(start 343.58707 -237.738666)
		(end 343.740994 -238.004096)
		(width 0.09525)
		(layer "In2.Cu")
		(net "M_C_CPU0_SA_DQS_DP<7>")
	)
	(segment
		(start 298.962318 -221.010226)
		(end 300.975522 -221.010226)
		(width 0.16002)
		(layer "In2.Cu")
		(net "M_C_CPU0_SA_DQS_DP<7>")
	)
	(segment
		(start 327.335642 -237.627668)
		(end 327.761092 -237.627668)
		(width 0.09525)
		(layer "In2.Cu")
		(net "M_C_CPU0_SA_DQS_DP<7>")
	)
	(segment
		(start 317.057278 -228.183186)
		(end 317.057278 -230.144066)
		(width 0.16002)
		(layer "In2.Cu")
		(net "M_C_CPU0_SA_DQS_DP<7>")
	)
	(segment
		(start 335.092548 -237.678976)
		(end 335.10093 -237.67415)
		(width 0.09525)
		(layer "In2.Cu")
		(net "M_C_CPU0_SA_DQS_DP<7>")
	)
	(segment
		(start 304.583084 -221.41688)
		(end 304.973482 -221.255082)
		(width 0.16002)
		(layer "In2.Cu")
		(net "M_C_CPU0_SA_DQS_DP<7>")
	)
	(segment
		(start 300.975522 -221.010226)
		(end 301.55388 -221.249748)
		(width 0.16002)
		(layer "In2.Cu")
		(net "M_C_CPU0_SA_DQS_DP<7>")
	)
	(segment
		(start 343.486232 -237.711996)
		(end 343.58707 -237.738666)
		(width 0.09525)
		(layer "In2.Cu")
		(net "M_C_CPU0_SA_DQS_DP<7>")
	)
	(segment
		(start 304.973482 -221.255082)
		(end 305.792632 -220.707712)
		(width 0.16002)
		(layer "In2.Cu")
		(net "M_C_CPU0_SA_DQS_DP<7>")
	)
	(segment
		(start 324.442836 -235.63072)
		(end 324.932294 -235.63072)
		(width 0.09525)
		(layer "In2.Cu")
		(net "M_C_CPU0_SA_DQS_DP<7>")
	)
	(segment
		(start 326.528176 -236.820202)
		(end 327.335642 -237.627668)
		(width 0.09525)
		(layer "In2.Cu")
		(net "M_C_CPU0_SA_DQS_DP<7>")
	)
	(segment
		(start 323.978524 -235.526072)
		(end 324.338188 -235.526072)
		(width 0.09525)
		(layer "In2.Cu")
		(net "M_C_CPU0_SA_DQS_DP<7>")
	)
	(segment
		(start 305.792632 -220.707712)
		(end 306.190142 -220.707712)
		(width 0.16002)
		(layer "In2.Cu")
		(net "M_C_CPU0_SA_DQS_DP<7>")
	)
	(segment
		(start 302.137318 -221.833186)
		(end 304.166778 -221.833186)
		(width 0.16002)
		(layer "In2.Cu")
		(net "M_C_CPU0_SA_DQS_DP<7>")
	)
	(segment
		(start 324.932294 -235.63072)
		(end 326.077834 -236.77626)
		(width 0.09525)
		(layer "In2.Cu")
		(net "M_C_CPU0_SA_DQS_DP<7>")
	)
	(segment
		(start 333.581248 -237.67415)
		(end 333.58963 -237.678976)
		(width 0.09525)
		(layer "In2.Cu")
		(net "M_C_CPU0_SA_DQS_DP<7>")
	)
	(segment
		(start 338.85251 -237.678976)
		(end 338.860892 -237.67415)
		(width 0.09525)
		(layer "In2.Cu")
		(net "M_C_CPU0_SA_DQS_DP<7>")
	)
	(segment
		(start 330.392532 -237.678976)
		(end 330.400914 -237.67415)
		(width 0.09525)
		(layer "In2.Cu")
		(net "M_C_CPU0_SA_DQS_DP<7>")
	)
	(segment
		(start 331.332586 -237.678976)
		(end 331.340968 -237.67415)
		(width 0.09525)
		(layer "In2.Cu")
		(net "M_C_CPU0_SA_DQS_DP<7>")
	)
	(segment
		(start 291.092382 -220.707712)
		(end 291.65423 -221.26956)
		(width 0.16002)
		(layer "In2.Cu")
		(net "M_C_CPU0_SA_DQS_DP<7>")
	)
	(segment
		(start 322.498212 -235.585)
		(end 323.895974 -235.585)
		(width 0.16002)
		(layer "In2.Cu")
		(net "M_C_CPU0_SA_DQS_DP<7>")
	)
	(segment
		(start 323.895974 -235.585)
		(end 323.919596 -235.585)
		(width 0.09525)
		(layer "In2.Cu")
		(net "M_C_CPU0_SA_DQS_DP<7>")
	)
	(segment
		(start 342.98128 -237.67415)
		(end 342.989662 -237.678976)
		(width 0.09525)
		(layer "In2.Cu")
		(net "M_C_CPU0_SA_DQS_DP<7>")
	)
	(segment
		(start 339.792564 -237.678976)
		(end 339.800946 -237.67415)
		(width 0.09525)
		(layer "In2.Cu")
		(net "M_C_CPU0_SA_DQS_DP<7>")
	)
	(segment
		(start 306.190142 -220.707712)
		(end 306.452016 -220.969586)
		(width 0.16002)
		(layer "In2.Cu")
		(net "M_C_CPU0_SA_DQS_DP<7>")
	)
	(segment
		(start 294.168068 -221.448376)
		(end 294.579802 -221.86011)
		(width 0.16002)
		(layer "In2.Cu")
		(net "M_C_CPU0_SA_DQS_DP<7>")
	)
	(segment
		(start 290.444936 -220.861382)
		(end 290.598606 -220.707712)
		(width 0.16002)
		(layer "In2.Cu")
		(net "M_C_CPU0_SA_DQS_DP<7>")
	)
	(segment
		(start 334.521302 -237.67415)
		(end 334.529684 -237.678976)
		(width 0.09525)
		(layer "In2.Cu")
		(net "M_C_CPU0_SA_DQS_DP<7>")
	)
	(segment
		(start 288.453576 -220.861382)
		(end 290.444936 -220.861382)
		(width 0.16002)
		(layer "In2.Cu")
		(net "M_C_CPU0_SA_DQS_DP<7>")
	)
	(segment
		(start 326.077834 -236.77626)
		(end 326.422512 -236.77626)
		(width 0.09525)
		(layer "In2.Cu")
		(net "M_C_CPU0_SA_DQS_DP<7>")
	)
	(arc
		(start 342.049608 -237.678976)
		(mid 342.33104 -237.754731)
		(end 342.612472 -237.678976)
		(width 0.09525)
		(layer "In2.Cu")
		(net "M_C_CPU0_SA_DQS_DP<7>")
	)
	(arc
		(start 337.912456 -237.678976)
		(mid 338.096231 -237.628204)
		(end 338.281264 -237.67415)
		(width 0.09525)
		(layer "In2.Cu")
		(net "M_C_CPU0_SA_DQS_DP<7>")
	)
	(arc
		(start 332.649576 -237.678976)
		(mid 332.931008 -237.754731)
		(end 333.21244 -237.678976)
		(width 0.09525)
		(layer "In2.Cu")
		(net "M_C_CPU0_SA_DQS_DP<7>")
	)
	(arc
		(start 331.340968 -237.67415)
		(mid 331.526 -237.628236)
		(end 331.709776 -237.678976)
		(width 0.09525)
		(layer "In2.Cu")
		(net "M_C_CPU0_SA_DQS_DP<7>")
	)
	(arc
		(start 329.452478 -237.678976)
		(mid 329.636253 -237.628204)
		(end 329.821286 -237.67415)
		(width 0.09525)
		(layer "In2.Cu")
		(net "M_C_CPU0_SA_DQS_DP<7>")
	)
	(arc
		(start 342.989662 -237.678976)
		(mid 343.223457 -237.752843)
		(end 343.46642 -237.71987)
		(width 0.09525)
		(layer "In2.Cu")
		(net "M_C_CPU0_SA_DQS_DP<7>")
	)
	(arc
		(start 341.109554 -237.678976)
		(mid 341.390986 -237.754731)
		(end 341.672418 -237.678976)
		(width 0.09525)
		(layer "In2.Cu")
		(net "M_C_CPU0_SA_DQS_DP<7>")
	)
	(arc
		(start 338.289646 -237.678976)
		(mid 338.571078 -237.754731)
		(end 338.85251 -237.678976)
		(width 0.09525)
		(layer "In2.Cu")
		(net "M_C_CPU0_SA_DQS_DP<7>")
	)
	(arc
		(start 342.612472 -237.678976)
		(mid 342.796247 -237.628204)
		(end 342.98128 -237.67415)
		(width 0.09525)
		(layer "In2.Cu")
		(net "M_C_CPU0_SA_DQS_DP<7>")
	)
	(arc
		(start 328.512678 -237.678976)
		(mid 328.701146 -237.628299)
		(end 328.889614 -237.678976)
		(width 0.09525)
		(layer "In2.Cu")
		(net "M_C_CPU0_SA_DQS_DP<7>")
	)
	(arc
		(start 334.529684 -237.678976)
		(mid 334.811116 -237.754731)
		(end 335.092548 -237.678976)
		(width 0.09525)
		(layer "In2.Cu")
		(net "M_C_CPU0_SA_DQS_DP<7>")
	)
	(arc
		(start 341.672418 -237.678976)
		(mid 341.856193 -237.628204)
		(end 342.041226 -237.67415)
		(width 0.09525)
		(layer "In2.Cu")
		(net "M_C_CPU0_SA_DQS_DP<7>")
	)
	(arc
		(start 340.169754 -237.678976)
		(mid 340.451186 -237.754731)
		(end 340.732618 -237.678976)
		(width 0.09525)
		(layer "In2.Cu")
		(net "M_C_CPU0_SA_DQS_DP<7>")
	)
	(arc
		(start 336.972656 -237.678976)
		(mid 337.161124 -237.628299)
		(end 337.349592 -237.678976)
		(width 0.09525)
		(layer "In2.Cu")
		(net "M_C_CPU0_SA_DQS_DP<7>")
	)
	(arc
		(start 335.469738 -237.678976)
		(mid 335.75117 -237.754731)
		(end 336.032602 -237.678976)
		(width 0.09525)
		(layer "In2.Cu")
		(net "M_C_CPU0_SA_DQS_DP<7>")
	)
	(arc
		(start 336.040984 -237.67415)
		(mid 336.226016 -237.628236)
		(end 336.409792 -237.678976)
		(width 0.09525)
		(layer "In2.Cu")
		(net "M_C_CPU0_SA_DQS_DP<7>")
	)
	(arc
		(start 338.860892 -237.67415)
		(mid 339.045924 -237.628236)
		(end 339.2297 -237.678976)
		(width 0.09525)
		(layer "In2.Cu")
		(net "M_C_CPU0_SA_DQS_DP<7>")
	)
	(arc
		(start 336.409792 -237.678976)
		(mid 336.691224 -237.754731)
		(end 336.972656 -237.678976)
		(width 0.09525)
		(layer "In2.Cu")
		(net "M_C_CPU0_SA_DQS_DP<7>")
	)
	(arc
		(start 340.732618 -237.678976)
		(mid 340.921086 -237.628299)
		(end 341.109554 -237.678976)
		(width 0.09525)
		(layer "In2.Cu")
		(net "M_C_CPU0_SA_DQS_DP<7>")
	)
	(arc
		(start 333.21244 -237.678976)
		(mid 333.396215 -237.628204)
		(end 333.581248 -237.67415)
		(width 0.09525)
		(layer "In2.Cu")
		(net "M_C_CPU0_SA_DQS_DP<7>")
	)
	(arc
		(start 343.46642 -237.71987)
		(mid 343.476363 -237.716027)
		(end 343.486232 -237.711996)
		(width 0.09525)
		(layer "In2.Cu")
		(net "M_C_CPU0_SA_DQS_DP<7>")
	)
	(arc
		(start 329.829668 -237.678976)
		(mid 330.1111 -237.754731)
		(end 330.392532 -237.678976)
		(width 0.09525)
		(layer "In2.Cu")
		(net "M_C_CPU0_SA_DQS_DP<7>")
	)
	(arc
		(start 334.152494 -237.678976)
		(mid 334.336269 -237.628204)
		(end 334.521302 -237.67415)
		(width 0.09525)
		(layer "In2.Cu")
		(net "M_C_CPU0_SA_DQS_DP<7>")
	)
	(arc
		(start 335.10093 -237.67415)
		(mid 335.285962 -237.628236)
		(end 335.469738 -237.678976)
		(width 0.09525)
		(layer "In2.Cu")
		(net "M_C_CPU0_SA_DQS_DP<7>")
	)
	(arc
		(start 337.349592 -237.678976)
		(mid 337.631024 -237.754731)
		(end 337.912456 -237.678976)
		(width 0.09525)
		(layer "In2.Cu")
		(net "M_C_CPU0_SA_DQS_DP<7>")
	)
	(arc
		(start 330.400914 -237.67415)
		(mid 330.585946 -237.628236)
		(end 330.769722 -237.678976)
		(width 0.09525)
		(layer "In2.Cu")
		(net "M_C_CPU0_SA_DQS_DP<7>")
	)
	(arc
		(start 326.422512 -236.77626)
		(mid 326.479696 -236.787746)
		(end 326.528176 -236.820202)
		(width 0.09525)
		(layer "In2.Cu")
		(net "M_C_CPU0_SA_DQS_DP<7>")
	)
	(arc
		(start 330.769722 -237.678976)
		(mid 331.051154 -237.754731)
		(end 331.332586 -237.678976)
		(width 0.09525)
		(layer "In2.Cu")
		(net "M_C_CPU0_SA_DQS_DP<7>")
	)
	(arc
		(start 339.2297 -237.678976)
		(mid 339.511132 -237.754731)
		(end 339.792564 -237.678976)
		(width 0.09525)
		(layer "In2.Cu")
		(net "M_C_CPU0_SA_DQS_DP<7>")
	)
	(arc
		(start 327.761092 -237.627668)
		(mid 327.858838 -237.640863)
		(end 327.949814 -237.678976)
		(width 0.09525)
		(layer "In2.Cu")
		(net "M_C_CPU0_SA_DQS_DP<7>")
	)
	(arc
		(start 332.27264 -237.678976)
		(mid 332.461108 -237.628299)
		(end 332.649576 -237.678976)
		(width 0.09525)
		(layer "In2.Cu")
		(net "M_C_CPU0_SA_DQS_DP<7>")
	)
	(arc
		(start 328.889614 -237.678976)
		(mid 329.171046 -237.754731)
		(end 329.452478 -237.678976)
		(width 0.09525)
		(layer "In2.Cu")
		(net "M_C_CPU0_SA_DQS_DP<7>")
	)
	(arc
		(start 327.949814 -237.678976)
		(mid 328.231246 -237.754731)
		(end 328.512678 -237.678976)
		(width 0.09525)
		(layer "In2.Cu")
		(net "M_C_CPU0_SA_DQS_DP<7>")
	)
	(arc
		(start 333.58963 -237.678976)
		(mid 333.871062 -237.754731)
		(end 334.152494 -237.678976)
		(width 0.09525)
		(layer "In2.Cu")
		(net "M_C_CPU0_SA_DQS_DP<7>")
	)
	(arc
		(start 331.709776 -237.678976)
		(mid 331.991208 -237.754731)
		(end 332.27264 -237.678976)
		(width 0.09525)
		(layer "In2.Cu")
		(net "M_C_CPU0_SA_DQS_DP<7>")
	)
	(arc
		(start 339.800946 -237.67415)
		(mid 339.985978 -237.628236)
		(end 340.169754 -237.678976)
		(width 0.09525)
		(layer "In2.Cu")
		(net "M_C_CPU0_SA_DQS_DP<7>")
	)
	(segment
		(start 344.207846 -233.409998)
		(end 343.740994 -233.14406)
		(width 0.12954)
		(layer "F.Cu")
		(net "M_C_CPU0_SA_DQS_DP<6>")
	)
	(segment
		(start 293.989252 -211.919566)
		(end 294.579802 -212.510116)
		(width 0.16002)
		(layer "In2.Cu")
		(net "M_C_CPU0_SA_DQS_DP<6>")
	)
	(segment
		(start 326.971914 -231.17683)
		(end 327.010014 -231.198928)
		(width 0.09525)
		(layer "In2.Cu")
		(net "M_C_CPU0_SA_DQS_DP<6>")
	)
	(segment
		(start 338.85251 -232.81894)
		(end 338.860892 -232.814114)
		(width 0.09525)
		(layer "In2.Cu")
		(net "M_C_CPU0_SA_DQS_DP<6>")
	)
	(segment
		(start 288.180018 -211.784946)
		(end 288.453576 -211.511388)
		(width 0.16002)
		(layer "In2.Cu")
		(net "M_C_CPU0_SA_DQS_DP<6>")
	)
	(segment
		(start 326.53986 -230.388922)
		(end 326.57161 -230.40721)
		(width 0.09525)
		(layer "In2.Cu")
		(net "M_C_CPU0_SA_DQS_DP<6>")
	)
	(segment
		(start 324.967092 -227.790502)
		(end 325.218806 -228.04247)
		(width 0.09525)
		(layer "In2.Cu")
		(net "M_C_CPU0_SA_DQS_DP<6>")
	)
	(segment
		(start 325.624952 -228.782118)
		(end 325.629524 -228.785674)
		(width 0.09525)
		(layer "In2.Cu")
		(net "M_C_CPU0_SA_DQS_DP<6>")
	)
	(segment
		(start 291.046916 -211.312252)
		(end 291.65423 -211.919566)
		(width 0.16002)
		(layer "In2.Cu")
		(net "M_C_CPU0_SA_DQS_DP<6>")
	)
	(segment
		(start 302.137318 -212.483192)
		(end 304.166778 -212.483192)
		(width 0.16002)
		(layer "In2.Cu")
		(net "M_C_CPU0_SA_DQS_DP<6>")
	)
	(segment
		(start 333.581248 -232.814114)
		(end 333.58963 -232.81894)
		(width 0.09525)
		(layer "In2.Cu")
		(net "M_C_CPU0_SA_DQS_DP<6>")
	)
	(segment
		(start 327.911714 -232.796842)
		(end 327.949814 -232.81894)
		(width 0.09525)
		(layer "In2.Cu")
		(net "M_C_CPU0_SA_DQS_DP<6>")
	)
	(segment
		(start 343.486232 -232.85196)
		(end 343.58707 -232.87863)
		(width 0.09525)
		(layer "In2.Cu")
		(net "M_C_CPU0_SA_DQS_DP<6>")
	)
	(segment
		(start 327.47966 -232.008934)
		(end 327.512172 -232.02773)
		(width 0.09525)
		(layer "In2.Cu")
		(net "M_C_CPU0_SA_DQS_DP<6>")
	)
	(segment
		(start 296.927778 -212.186012)
		(end 297.417998 -212.186012)
		(width 0.16002)
		(layer "In2.Cu")
		(net "M_C_CPU0_SA_DQS_DP<6>")
	)
	(segment
		(start 331.332586 -232.81894)
		(end 331.340968 -232.814114)
		(width 0.09525)
		(layer "In2.Cu")
		(net "M_C_CPU0_SA_DQS_DP<6>")
	)
	(segment
		(start 305.78933 -211.36102)
		(end 306.193444 -211.36102)
		(width 0.16002)
		(layer "In2.Cu")
		(net "M_C_CPU0_SA_DQS_DP<6>")
	)
	(segment
		(start 298.271438 -211.332572)
		(end 298.634658 -211.332572)
		(width 0.16002)
		(layer "In2.Cu")
		(net "M_C_CPU0_SA_DQS_DP<6>")
	)
	(segment
		(start 298.634658 -211.332572)
		(end 298.962318 -211.660232)
		(width 0.16002)
		(layer "In2.Cu")
		(net "M_C_CPU0_SA_DQS_DP<6>")
	)
	(segment
		(start 334.521302 -232.814114)
		(end 334.529684 -232.81894)
		(width 0.09525)
		(layer "In2.Cu")
		(net "M_C_CPU0_SA_DQS_DP<6>")
	)
	(segment
		(start 342.98128 -232.814114)
		(end 342.989662 -232.81894)
		(width 0.09525)
		(layer "In2.Cu")
		(net "M_C_CPU0_SA_DQS_DP<6>")
	)
	(segment
		(start 306.452016 -211.619592)
		(end 310.543956 -211.619592)
		(width 0.16002)
		(layer "In2.Cu")
		(net "M_C_CPU0_SA_DQS_DP<6>")
	)
	(segment
		(start 304.486818 -212.163152)
		(end 304.987198 -212.163152)
		(width 0.16002)
		(layer "In2.Cu")
		(net "M_C_CPU0_SA_DQS_DP<6>")
	)
	(segment
		(start 288.453576 -211.511388)
		(end 289.972496 -211.511388)
		(width 0.16002)
		(layer "In2.Cu")
		(net "M_C_CPU0_SA_DQS_DP<6>")
	)
	(segment
		(start 335.092548 -232.81894)
		(end 335.10093 -232.814114)
		(width 0.09525)
		(layer "In2.Cu")
		(net "M_C_CPU0_SA_DQS_DP<6>")
	)
	(segment
		(start 326.06996 -229.57917)
		(end 326.104504 -229.598982)
		(width 0.09525)
		(layer "In2.Cu")
		(net "M_C_CPU0_SA_DQS_DP<6>")
	)
	(segment
		(start 290.171632 -211.312252)
		(end 291.046916 -211.312252)
		(width 0.16002)
		(layer "In2.Cu")
		(net "M_C_CPU0_SA_DQS_DP<6>")
	)
	(segment
		(start 342.041226 -232.814114)
		(end 342.049608 -232.81894)
		(width 0.09525)
		(layer "In2.Cu")
		(net "M_C_CPU0_SA_DQS_DP<6>")
	)
	(segment
		(start 322.784978 -225.633534)
		(end 322.784978 -226.768914)
		(width 0.16002)
		(layer "In2.Cu")
		(net "M_C_CPU0_SA_DQS_DP<6>")
	)
	(segment
		(start 291.65423 -211.919566)
		(end 293.989252 -211.919566)
		(width 0.16002)
		(layer "In2.Cu")
		(net "M_C_CPU0_SA_DQS_DP<6>")
	)
	(segment
		(start 326.033384 -229.557834)
		(end 326.06996 -229.57917)
		(width 0.09525)
		(layer "In2.Cu")
		(net "M_C_CPU0_SA_DQS_DP<6>")
	)
	(segment
		(start 343.58707 -232.87863)
		(end 343.740994 -233.14406)
		(width 0.09525)
		(layer "In2.Cu")
		(net "M_C_CPU0_SA_DQS_DP<6>")
	)
	(segment
		(start 339.792564 -232.81894)
		(end 339.800946 -232.814114)
		(width 0.09525)
		(layer "In2.Cu")
		(net "M_C_CPU0_SA_DQS_DP<6>")
	)
	(segment
		(start 289.972496 -211.511388)
		(end 290.171632 -211.312252)
		(width 0.16002)
		(layer "In2.Cu")
		(net "M_C_CPU0_SA_DQS_DP<6>")
	)
	(segment
		(start 301.314358 -211.660232)
		(end 302.137318 -212.483192)
		(width 0.16002)
		(layer "In2.Cu")
		(net "M_C_CPU0_SA_DQS_DP<6>")
	)
	(segment
		(start 322.784978 -226.768914)
		(end 323.865748 -227.849684)
		(width 0.16002)
		(layer "In2.Cu")
		(net "M_C_CPU0_SA_DQS_DP<6>")
	)
	(segment
		(start 327.010014 -231.198928)
		(end 327.04151 -231.217216)
		(width 0.09525)
		(layer "In2.Cu")
		(net "M_C_CPU0_SA_DQS_DP<6>")
	)
	(segment
		(start 338.281264 -232.814114)
		(end 338.289646 -232.81894)
		(width 0.09525)
		(layer "In2.Cu")
		(net "M_C_CPU0_SA_DQS_DP<6>")
	)
	(segment
		(start 317.115698 -218.191334)
		(end 317.115698 -219.964254)
		(width 0.16002)
		(layer "In2.Cu")
		(net "M_C_CPU0_SA_DQS_DP<6>")
	)
	(segment
		(start 304.166778 -212.483192)
		(end 304.486818 -212.163152)
		(width 0.16002)
		(layer "In2.Cu")
		(net "M_C_CPU0_SA_DQS_DP<6>")
	)
	(segment
		(start 336.032602 -232.81894)
		(end 336.040984 -232.814114)
		(width 0.09525)
		(layer "In2.Cu")
		(net "M_C_CPU0_SA_DQS_DP<6>")
	)
	(segment
		(start 296.603674 -212.510116)
		(end 296.927778 -212.186012)
		(width 0.16002)
		(layer "In2.Cu")
		(net "M_C_CPU0_SA_DQS_DP<6>")
	)
	(segment
		(start 327.444608 -231.98836)
		(end 327.44664 -231.98963)
		(width 0.09525)
		(layer "In2.Cu")
		(net "M_C_CPU0_SA_DQS_DP<6>")
	)
	(segment
		(start 317.115698 -219.964254)
		(end 322.784978 -225.633534)
		(width 0.16002)
		(layer "In2.Cu")
		(net "M_C_CPU0_SA_DQS_DP<6>")
	)
	(segment
		(start 304.987198 -212.163152)
		(end 305.78933 -211.36102)
		(width 0.16002)
		(layer "In2.Cu")
		(net "M_C_CPU0_SA_DQS_DP<6>")
	)
	(segment
		(start 325.317866 -228.255576)
		(end 325.31812 -228.255576)
		(width 0.09525)
		(layer "In2.Cu")
		(net "M_C_CPU0_SA_DQS_DP<6>")
	)
	(segment
		(start 327.44664 -231.98963)
		(end 327.47966 -232.008934)
		(width 0.09525)
		(layer "In2.Cu")
		(net "M_C_CPU0_SA_DQS_DP<6>")
	)
	(segment
		(start 324.514718 -227.849684)
		(end 324.5739 -227.790502)
		(width 0.09525)
		(layer "In2.Cu")
		(net "M_C_CPU0_SA_DQS_DP<6>")
	)
	(segment
		(start 324.491096 -227.849684)
		(end 324.514718 -227.849684)
		(width 0.09525)
		(layer "In2.Cu")
		(net "M_C_CPU0_SA_DQS_DP<6>")
	)
	(segment
		(start 297.417998 -212.186012)
		(end 298.271438 -211.332572)
		(width 0.16002)
		(layer "In2.Cu")
		(net "M_C_CPU0_SA_DQS_DP<6>")
	)
	(segment
		(start 310.543956 -211.619592)
		(end 317.115698 -218.191334)
		(width 0.16002)
		(layer "In2.Cu")
		(net "M_C_CPU0_SA_DQS_DP<6>")
	)
	(segment
		(start 294.579802 -212.510116)
		(end 296.603674 -212.510116)
		(width 0.16002)
		(layer "In2.Cu")
		(net "M_C_CPU0_SA_DQS_DP<6>")
	)
	(segment
		(start 330.392532 -232.81894)
		(end 330.400914 -232.814114)
		(width 0.09525)
		(layer "In2.Cu")
		(net "M_C_CPU0_SA_DQS_DP<6>")
	)
	(segment
		(start 323.865748 -227.849684)
		(end 324.491096 -227.849684)
		(width 0.16002)
		(layer "In2.Cu")
		(net "M_C_CPU0_SA_DQS_DP<6>")
	)
	(segment
		(start 324.5739 -227.790502)
		(end 324.967092 -227.790502)
		(width 0.09525)
		(layer "In2.Cu")
		(net "M_C_CPU0_SA_DQS_DP<6>")
	)
	(segment
		(start 329.821286 -232.814114)
		(end 329.829668 -232.81894)
		(width 0.09525)
		(layer "In2.Cu")
		(net "M_C_CPU0_SA_DQS_DP<6>")
	)
	(segment
		(start 326.503284 -230.367586)
		(end 326.53986 -230.388922)
		(width 0.09525)
		(layer "In2.Cu")
		(net "M_C_CPU0_SA_DQS_DP<6>")
	)
	(segment
		(start 298.962318 -211.660232)
		(end 301.314358 -211.660232)
		(width 0.16002)
		(layer "In2.Cu")
		(net "M_C_CPU0_SA_DQS_DP<6>")
	)
	(segment
		(start 306.193444 -211.36102)
		(end 306.452016 -211.619592)
		(width 0.16002)
		(layer "In2.Cu")
		(net "M_C_CPU0_SA_DQS_DP<6>")
	)
	(arc
		(start 336.972656 -232.81894)
		(mid 337.161124 -232.768263)
		(end 337.349592 -232.81894)
		(width 0.09525)
		(layer "In2.Cu")
		(net "M_C_CPU0_SA_DQS_DP<6>")
	)
	(arc
		(start 327.949814 -232.81894)
		(mid 328.231246 -232.894695)
		(end 328.512678 -232.81894)
		(width 0.09525)
		(layer "In2.Cu")
		(net "M_C_CPU0_SA_DQS_DP<6>")
	)
	(arc
		(start 334.152494 -232.81894)
		(mid 334.336269 -232.768168)
		(end 334.521302 -232.814114)
		(width 0.09525)
		(layer "In2.Cu")
		(net "M_C_CPU0_SA_DQS_DP<6>")
	)
	(arc
		(start 337.912456 -232.81894)
		(mid 338.096231 -232.768168)
		(end 338.281264 -232.814114)
		(width 0.09525)
		(layer "In2.Cu")
		(net "M_C_CPU0_SA_DQS_DP<6>")
	)
	(arc
		(start 334.529684 -232.81894)
		(mid 334.811116 -232.894695)
		(end 335.092548 -232.81894)
		(width 0.09525)
		(layer "In2.Cu")
		(net "M_C_CPU0_SA_DQS_DP<6>")
	)
	(arc
		(start 341.109554 -232.81894)
		(mid 341.390986 -232.894695)
		(end 341.672418 -232.81894)
		(width 0.09525)
		(layer "In2.Cu")
		(net "M_C_CPU0_SA_DQS_DP<6>")
	)
	(arc
		(start 333.58963 -232.81894)
		(mid 333.871062 -232.894695)
		(end 334.152494 -232.81894)
		(width 0.09525)
		(layer "In2.Cu")
		(net "M_C_CPU0_SA_DQS_DP<6>")
	)
	(arc
		(start 335.10093 -232.814114)
		(mid 335.285962 -232.7682)
		(end 335.469738 -232.81894)
		(width 0.09525)
		(layer "In2.Cu")
		(net "M_C_CPU0_SA_DQS_DP<6>")
	)
	(arc
		(start 336.040984 -232.814114)
		(mid 336.226016 -232.7682)
		(end 336.409792 -232.81894)
		(width 0.09525)
		(layer "In2.Cu")
		(net "M_C_CPU0_SA_DQS_DP<6>")
	)
	(arc
		(start 327.04151 -231.217216)
		(mid 327.157308 -231.35161)
		(end 327.19899 -231.524048)
		(width 0.09525)
		(layer "In2.Cu")
		(net "M_C_CPU0_SA_DQS_DP<6>")
	)
	(arc
		(start 328.512678 -232.81894)
		(mid 328.701146 -232.768263)
		(end 328.889614 -232.81894)
		(width 0.09525)
		(layer "In2.Cu")
		(net "M_C_CPU0_SA_DQS_DP<6>")
	)
	(arc
		(start 329.829668 -232.81894)
		(mid 330.1111 -232.894695)
		(end 330.392532 -232.81894)
		(width 0.09525)
		(layer "In2.Cu")
		(net "M_C_CPU0_SA_DQS_DP<6>")
	)
	(arc
		(start 330.769722 -232.81894)
		(mid 331.051154 -232.894695)
		(end 331.332586 -232.81894)
		(width 0.09525)
		(layer "In2.Cu")
		(net "M_C_CPU0_SA_DQS_DP<6>")
	)
	(arc
		(start 340.169754 -232.81894)
		(mid 340.451186 -232.894695)
		(end 340.732618 -232.81894)
		(width 0.09525)
		(layer "In2.Cu")
		(net "M_C_CPU0_SA_DQS_DP<6>")
	)
	(arc
		(start 339.800946 -232.814114)
		(mid 339.985978 -232.7682)
		(end 340.169754 -232.81894)
		(width 0.09525)
		(layer "In2.Cu")
		(net "M_C_CPU0_SA_DQS_DP<6>")
	)
	(arc
		(start 326.25919 -229.904036)
		(mid 326.32395 -230.165971)
		(end 326.503284 -230.367586)
		(width 0.09525)
		(layer "In2.Cu")
		(net "M_C_CPU0_SA_DQS_DP<6>")
	)
	(arc
		(start 335.469738 -232.81894)
		(mid 335.75117 -232.894695)
		(end 336.032602 -232.81894)
		(width 0.09525)
		(layer "In2.Cu")
		(net "M_C_CPU0_SA_DQS_DP<6>")
	)
	(arc
		(start 330.400914 -232.814114)
		(mid 330.585946 -232.7682)
		(end 330.769722 -232.81894)
		(width 0.09525)
		(layer "In2.Cu")
		(net "M_C_CPU0_SA_DQS_DP<6>")
	)
	(arc
		(start 336.409792 -232.81894)
		(mid 336.691224 -232.894695)
		(end 336.972656 -232.81894)
		(width 0.09525)
		(layer "In2.Cu")
		(net "M_C_CPU0_SA_DQS_DP<6>")
	)
	(arc
		(start 326.104504 -229.598982)
		(mid 326.218345 -229.732998)
		(end 326.25919 -229.904036)
		(width 0.09525)
		(layer "In2.Cu")
		(net "M_C_CPU0_SA_DQS_DP<6>")
	)
	(arc
		(start 333.21244 -232.81894)
		(mid 333.396215 -232.768168)
		(end 333.581248 -232.814114)
		(width 0.09525)
		(layer "In2.Cu")
		(net "M_C_CPU0_SA_DQS_DP<6>")
	)
	(arc
		(start 326.57161 -230.40721)
		(mid 326.687408 -230.541746)
		(end 326.72909 -230.714296)
		(width 0.09525)
		(layer "In2.Cu")
		(net "M_C_CPU0_SA_DQS_DP<6>")
	)
	(arc
		(start 331.709776 -232.81894)
		(mid 331.991208 -232.894695)
		(end 332.27264 -232.81894)
		(width 0.09525)
		(layer "In2.Cu")
		(net "M_C_CPU0_SA_DQS_DP<6>")
	)
	(arc
		(start 332.649576 -232.81894)
		(mid 332.931008 -232.894695)
		(end 333.21244 -232.81894)
		(width 0.09525)
		(layer "In2.Cu")
		(net "M_C_CPU0_SA_DQS_DP<6>")
	)
	(arc
		(start 342.049608 -232.81894)
		(mid 342.33104 -232.894695)
		(end 342.612472 -232.81894)
		(width 0.09525)
		(layer "In2.Cu")
		(net "M_C_CPU0_SA_DQS_DP<6>")
	)
	(arc
		(start 343.46642 -232.859834)
		(mid 343.476363 -232.855991)
		(end 343.486232 -232.85196)
		(width 0.09525)
		(layer "In2.Cu")
		(net "M_C_CPU0_SA_DQS_DP<6>")
	)
	(arc
		(start 325.31812 -228.255576)
		(mid 325.412241 -228.55339)
		(end 325.624952 -228.782118)
		(width 0.09525)
		(layer "In2.Cu")
		(net "M_C_CPU0_SA_DQS_DP<6>")
	)
	(arc
		(start 325.789036 -229.09403)
		(mid 325.853786 -229.356199)
		(end 326.033384 -229.557834)
		(width 0.09525)
		(layer "In2.Cu")
		(net "M_C_CPU0_SA_DQS_DP<6>")
	)
	(arc
		(start 328.889614 -232.81894)
		(mid 329.171046 -232.894695)
		(end 329.452478 -232.81894)
		(width 0.09525)
		(layer "In2.Cu")
		(net "M_C_CPU0_SA_DQS_DP<6>")
	)
	(arc
		(start 338.860892 -232.814114)
		(mid 339.045924 -232.7682)
		(end 339.2297 -232.81894)
		(width 0.09525)
		(layer "In2.Cu")
		(net "M_C_CPU0_SA_DQS_DP<6>")
	)
	(arc
		(start 326.72909 -230.714296)
		(mid 326.793546 -230.975461)
		(end 326.971914 -231.17683)
		(width 0.09525)
		(layer "In2.Cu")
		(net "M_C_CPU0_SA_DQS_DP<6>")
	)
	(arc
		(start 332.27264 -232.81894)
		(mid 332.461108 -232.768263)
		(end 332.649576 -232.81894)
		(width 0.09525)
		(layer "In2.Cu")
		(net "M_C_CPU0_SA_DQS_DP<6>")
	)
	(arc
		(start 342.612472 -232.81894)
		(mid 342.796247 -232.768168)
		(end 342.98128 -232.814114)
		(width 0.09525)
		(layer "In2.Cu")
		(net "M_C_CPU0_SA_DQS_DP<6>")
	)
	(arc
		(start 327.66889 -232.334054)
		(mid 327.733287 -232.59536)
		(end 327.911714 -232.796842)
		(width 0.09525)
		(layer "In2.Cu")
		(net "M_C_CPU0_SA_DQS_DP<6>")
	)
	(arc
		(start 331.340968 -232.814114)
		(mid 331.526 -232.7682)
		(end 331.709776 -232.81894)
		(width 0.09525)
		(layer "In2.Cu")
		(net "M_C_CPU0_SA_DQS_DP<6>")
	)
	(arc
		(start 339.2297 -232.81894)
		(mid 339.511132 -232.894695)
		(end 339.792564 -232.81894)
		(width 0.09525)
		(layer "In2.Cu")
		(net "M_C_CPU0_SA_DQS_DP<6>")
	)
	(arc
		(start 338.289646 -232.81894)
		(mid 338.571078 -232.894695)
		(end 338.85251 -232.81894)
		(width 0.09525)
		(layer "In2.Cu")
		(net "M_C_CPU0_SA_DQS_DP<6>")
	)
	(arc
		(start 340.732618 -232.81894)
		(mid 340.921086 -232.768263)
		(end 341.109554 -232.81894)
		(width 0.09525)
		(layer "In2.Cu")
		(net "M_C_CPU0_SA_DQS_DP<6>")
	)
	(arc
		(start 337.349592 -232.81894)
		(mid 337.631024 -232.894695)
		(end 337.912456 -232.81894)
		(width 0.09525)
		(layer "In2.Cu")
		(net "M_C_CPU0_SA_DQS_DP<6>")
	)
	(arc
		(start 342.989662 -232.81894)
		(mid 343.223457 -232.892807)
		(end 343.46642 -232.859834)
		(width 0.09525)
		(layer "In2.Cu")
		(net "M_C_CPU0_SA_DQS_DP<6>")
	)
	(arc
		(start 329.452478 -232.81894)
		(mid 329.636253 -232.768168)
		(end 329.821286 -232.814114)
		(width 0.09525)
		(layer "In2.Cu")
		(net "M_C_CPU0_SA_DQS_DP<6>")
	)
	(arc
		(start 325.629524 -228.785674)
		(mid 325.746828 -228.920435)
		(end 325.789036 -229.09403)
		(width 0.09525)
		(layer "In2.Cu")
		(net "M_C_CPU0_SA_DQS_DP<6>")
	)
	(arc
		(start 327.19899 -231.524048)
		(mid 327.264183 -231.786677)
		(end 327.444608 -231.98836)
		(width 0.09525)
		(layer "In2.Cu")
		(net "M_C_CPU0_SA_DQS_DP<6>")
	)
	(arc
		(start 325.218806 -228.04247)
		(mid 325.287233 -228.140244)
		(end 325.317866 -228.255576)
		(width 0.09525)
		(layer "In2.Cu")
		(net "M_C_CPU0_SA_DQS_DP<6>")
	)
	(arc
		(start 327.512172 -232.02773)
		(mid 327.627446 -232.162008)
		(end 327.66889 -232.334054)
		(width 0.09525)
		(layer "In2.Cu")
		(net "M_C_CPU0_SA_DQS_DP<6>")
	)
	(arc
		(start 341.672418 -232.81894)
		(mid 341.856193 -232.768168)
		(end 342.041226 -232.814114)
		(width 0.09525)
		(layer "In2.Cu")
		(net "M_C_CPU0_SA_DQS_DP<6>")
	)
	(segment
		(start 344.207846 -228.550216)
		(end 343.740994 -228.284278)
		(width 0.12954)
		(layer "F.Cu")
		(net "M_C_CPU0_SA_DQS_DP<5>")
	)
	(segment
		(start 327.34885 -222.165926)
		(end 327.442068 -222.259652)
		(width 0.09525)
		(layer "In2.Cu")
		(net "M_C_CPU0_SA_DQS_DP<5>")
	)
	(segment
		(start 336.032602 -227.959158)
		(end 336.040984 -227.954332)
		(width 0.09525)
		(layer "In2.Cu")
		(net "M_C_CPU0_SA_DQS_DP<5>")
	)
	(segment
		(start 333.581248 -227.954332)
		(end 333.58963 -227.959158)
		(width 0.09525)
		(layer "In2.Cu")
		(net "M_C_CPU0_SA_DQS_DP<5>")
	)
	(segment
		(start 328.384662 -223.888554)
		(end 328.419714 -223.909128)
		(width 0.09525)
		(layer "In2.Cu")
		(net "M_C_CPU0_SA_DQS_DP<5>")
	)
	(segment
		(start 304.486818 -202.813158)
		(end 304.987198 -202.813158)
		(width 0.16002)
		(layer "In2.Cu")
		(net "M_C_CPU0_SA_DQS_DP<5>")
	)
	(segment
		(start 290.171632 -201.962258)
		(end 291.046916 -201.962258)
		(width 0.16002)
		(layer "In2.Cu")
		(net "M_C_CPU0_SA_DQS_DP<5>")
	)
	(segment
		(start 291.046916 -201.962258)
		(end 291.65423 -202.569572)
		(width 0.16002)
		(layer "In2.Cu")
		(net "M_C_CPU0_SA_DQS_DP<5>")
	)
	(segment
		(start 327.199244 -221.257114)
		(end 327.199244 -221.80423)
		(width 0.09525)
		(layer "In2.Cu")
		(net "M_C_CPU0_SA_DQS_DP<5>")
	)
	(segment
		(start 330.731622 -227.93706)
		(end 330.769722 -227.959158)
		(width 0.09525)
		(layer "In2.Cu")
		(net "M_C_CPU0_SA_DQS_DP<5>")
	)
	(segment
		(start 296.603674 -203.160122)
		(end 296.927778 -202.836018)
		(width 0.16002)
		(layer "In2.Cu")
		(net "M_C_CPU0_SA_DQS_DP<5>")
	)
	(segment
		(start 298.634658 -201.982578)
		(end 298.962318 -202.310238)
		(width 0.16002)
		(layer "In2.Cu")
		(net "M_C_CPU0_SA_DQS_DP<5>")
	)
	(segment
		(start 328.854562 -224.69856)
		(end 328.889614 -224.719134)
		(width 0.09525)
		(layer "In2.Cu")
		(net "M_C_CPU0_SA_DQS_DP<5>")
	)
	(segment
		(start 289.972496 -202.161394)
		(end 290.171632 -201.962258)
		(width 0.16002)
		(layer "In2.Cu")
		(net "M_C_CPU0_SA_DQS_DP<5>")
	)
	(segment
		(start 319.744852 -211.516214)
		(end 319.744852 -212.173566)
		(width 0.16002)
		(layer "In2.Cu")
		(net "M_C_CPU0_SA_DQS_DP<5>")
	)
	(segment
		(start 309.531004 -203.42225)
		(end 311.650888 -203.42225)
		(width 0.16002)
		(layer "In2.Cu")
		(net "M_C_CPU0_SA_DQS_DP<5>")
	)
	(segment
		(start 317.405766 -209.356706)
		(end 317.585344 -209.356706)
		(width 0.16002)
		(layer "In2.Cu")
		(net "M_C_CPU0_SA_DQS_DP<5>")
	)
	(segment
		(start 298.271438 -201.982578)
		(end 298.634658 -201.982578)
		(width 0.16002)
		(layer "In2.Cu")
		(net "M_C_CPU0_SA_DQS_DP<5>")
	)
	(segment
		(start 343.486232 -227.992178)
		(end 343.58707 -228.018848)
		(width 0.09525)
		(layer "In2.Cu")
		(net "M_C_CPU0_SA_DQS_DP<5>")
	)
	(segment
		(start 327.140062 -221.17431)
		(end 327.140062 -221.197932)
		(width 0.09525)
		(layer "In2.Cu")
		(net "M_C_CPU0_SA_DQS_DP<5>")
	)
	(segment
		(start 343.58707 -228.018848)
		(end 343.740994 -228.284278)
		(width 0.09525)
		(layer "In2.Cu")
		(net "M_C_CPU0_SA_DQS_DP<5>")
	)
	(segment
		(start 329.359768 -225.52914)
		(end 329.391264 -225.547428)
		(width 0.09525)
		(layer "In2.Cu")
		(net "M_C_CPU0_SA_DQS_DP<5>")
	)
	(segment
		(start 330.299568 -227.149152)
		(end 330.33208 -227.167948)
		(width 0.09525)
		(layer "In2.Cu")
		(net "M_C_CPU0_SA_DQS_DP<5>")
	)
	(segment
		(start 308.378352 -202.269598)
		(end 309.531004 -203.42225)
		(width 0.16002)
		(layer "In2.Cu")
		(net "M_C_CPU0_SA_DQS_DP<5>")
	)
	(segment
		(start 291.65423 -202.569572)
		(end 293.933372 -202.569572)
		(width 0.16002)
		(layer "In2.Cu")
		(net "M_C_CPU0_SA_DQS_DP<5>")
	)
	(segment
		(start 331.332586 -227.959158)
		(end 331.340968 -227.954332)
		(width 0.09525)
		(layer "In2.Cu")
		(net "M_C_CPU0_SA_DQS_DP<5>")
	)
	(segment
		(start 328.889614 -224.719134)
		(end 328.922126 -224.73793)
		(width 0.09525)
		(layer "In2.Cu")
		(net "M_C_CPU0_SA_DQS_DP<5>")
	)
	(segment
		(start 306.452016 -202.269598)
		(end 308.378352 -202.269598)
		(width 0.16002)
		(layer "In2.Cu")
		(net "M_C_CPU0_SA_DQS_DP<5>")
	)
	(segment
		(start 304.166778 -203.133198)
		(end 304.486818 -202.813158)
		(width 0.16002)
		(layer "In2.Cu")
		(net "M_C_CPU0_SA_DQS_DP<5>")
	)
	(segment
		(start 311.650888 -203.42225)
		(end 317.082424 -208.853786)
		(width 0.16002)
		(layer "In2.Cu")
		(net "M_C_CPU0_SA_DQS_DP<5>")
	)
	(segment
		(start 327.479914 -222.288608)
		(end 327.479914 -222.289116)
		(width 0.09525)
		(layer "In2.Cu")
		(net "M_C_CPU0_SA_DQS_DP<5>")
	)
	(segment
		(start 327.950068 -223.099122)
		(end 327.981564 -223.11741)
		(width 0.09525)
		(layer "In2.Cu")
		(net "M_C_CPU0_SA_DQS_DP<5>")
	)
	(segment
		(start 319.744852 -212.173566)
		(end 327.140062 -219.568776)
		(width 0.16002)
		(layer "In2.Cu")
		(net "M_C_CPU0_SA_DQS_DP<5>")
	)
	(segment
		(start 317.082424 -208.853786)
		(end 317.082424 -209.033364)
		(width 0.16002)
		(layer "In2.Cu")
		(net "M_C_CPU0_SA_DQS_DP<5>")
	)
	(segment
		(start 298.962318 -202.310238)
		(end 301.314358 -202.310238)
		(width 0.16002)
		(layer "In2.Cu")
		(net "M_C_CPU0_SA_DQS_DP<5>")
	)
	(segment
		(start 329.829668 -226.339146)
		(end 329.86218 -226.357942)
		(width 0.09525)
		(layer "In2.Cu")
		(net "M_C_CPU0_SA_DQS_DP<5>")
	)
	(segment
		(start 288.180018 -202.434952)
		(end 288.453576 -202.161394)
		(width 0.16002)
		(layer "In2.Cu")
		(net "M_C_CPU0_SA_DQS_DP<5>")
	)
	(segment
		(start 293.933372 -202.569572)
		(end 294.523922 -203.160122)
		(width 0.16002)
		(layer "In2.Cu")
		(net "M_C_CPU0_SA_DQS_DP<5>")
	)
	(segment
		(start 297.417998 -202.836018)
		(end 298.271438 -201.982578)
		(width 0.16002)
		(layer "In2.Cu")
		(net "M_C_CPU0_SA_DQS_DP<5>")
	)
	(segment
		(start 317.082424 -209.033364)
		(end 317.405766 -209.356706)
		(width 0.16002)
		(layer "In2.Cu")
		(net "M_C_CPU0_SA_DQS_DP<5>")
	)
	(segment
		(start 305.78933 -202.011026)
		(end 306.193444 -202.011026)
		(width 0.16002)
		(layer "In2.Cu")
		(net "M_C_CPU0_SA_DQS_DP<5>")
	)
	(segment
		(start 338.85251 -227.959158)
		(end 338.860892 -227.954332)
		(width 0.09525)
		(layer "In2.Cu")
		(net "M_C_CPU0_SA_DQS_DP<5>")
	)
	(segment
		(start 335.092548 -227.959158)
		(end 335.10093 -227.954332)
		(width 0.09525)
		(layer "In2.Cu")
		(net "M_C_CPU0_SA_DQS_DP<5>")
	)
	(segment
		(start 306.193444 -202.011026)
		(end 306.452016 -202.269598)
		(width 0.16002)
		(layer "In2.Cu")
		(net "M_C_CPU0_SA_DQS_DP<5>")
	)
	(segment
		(start 342.98128 -227.954332)
		(end 342.989662 -227.959158)
		(width 0.09525)
		(layer "In2.Cu")
		(net "M_C_CPU0_SA_DQS_DP<5>")
	)
	(segment
		(start 288.453576 -202.161394)
		(end 289.972496 -202.161394)
		(width 0.16002)
		(layer "In2.Cu")
		(net "M_C_CPU0_SA_DQS_DP<5>")
	)
	(segment
		(start 304.987198 -202.813158)
		(end 305.78933 -202.011026)
		(width 0.16002)
		(layer "In2.Cu")
		(net "M_C_CPU0_SA_DQS_DP<5>")
	)
	(segment
		(start 327.913492 -223.077786)
		(end 327.950068 -223.099122)
		(width 0.09525)
		(layer "In2.Cu")
		(net "M_C_CPU0_SA_DQS_DP<5>")
	)
	(segment
		(start 339.792564 -227.959158)
		(end 339.800946 -227.954332)
		(width 0.09525)
		(layer "In2.Cu")
		(net "M_C_CPU0_SA_DQS_DP<5>")
	)
	(segment
		(start 296.927778 -202.836018)
		(end 297.417998 -202.836018)
		(width 0.16002)
		(layer "In2.Cu")
		(net "M_C_CPU0_SA_DQS_DP<5>")
	)
	(segment
		(start 334.521302 -227.954332)
		(end 334.529684 -227.959158)
		(width 0.09525)
		(layer "In2.Cu")
		(net "M_C_CPU0_SA_DQS_DP<5>")
	)
	(segment
		(start 342.041226 -227.954332)
		(end 342.049608 -227.959158)
		(width 0.09525)
		(layer "In2.Cu")
		(net "M_C_CPU0_SA_DQS_DP<5>")
	)
	(segment
		(start 294.523922 -203.160122)
		(end 296.603674 -203.160122)
		(width 0.16002)
		(layer "In2.Cu")
		(net "M_C_CPU0_SA_DQS_DP<5>")
	)
	(segment
		(start 317.585344 -209.356706)
		(end 319.744852 -211.516214)
		(width 0.16002)
		(layer "In2.Cu")
		(net "M_C_CPU0_SA_DQS_DP<5>")
	)
	(segment
		(start 327.140062 -221.197932)
		(end 327.199244 -221.257114)
		(width 0.09525)
		(layer "In2.Cu")
		(net "M_C_CPU0_SA_DQS_DP<5>")
	)
	(segment
		(start 301.314358 -202.310238)
		(end 302.137318 -203.133198)
		(width 0.16002)
		(layer "In2.Cu")
		(net "M_C_CPU0_SA_DQS_DP<5>")
	)
	(segment
		(start 302.137318 -203.133198)
		(end 304.166778 -203.133198)
		(width 0.16002)
		(layer "In2.Cu")
		(net "M_C_CPU0_SA_DQS_DP<5>")
	)
	(segment
		(start 338.281264 -227.954332)
		(end 338.289646 -227.959158)
		(width 0.09525)
		(layer "In2.Cu")
		(net "M_C_CPU0_SA_DQS_DP<5>")
	)
	(segment
		(start 328.419714 -223.909128)
		(end 328.452226 -223.927924)
		(width 0.09525)
		(layer "In2.Cu")
		(net "M_C_CPU0_SA_DQS_DP<5>")
	)
	(segment
		(start 327.140062 -219.568776)
		(end 327.140062 -221.17431)
		(width 0.16002)
		(layer "In2.Cu")
		(net "M_C_CPU0_SA_DQS_DP<5>")
	)
	(segment
		(start 330.264516 -227.128578)
		(end 330.299568 -227.149152)
		(width 0.09525)
		(layer "In2.Cu")
		(net "M_C_CPU0_SA_DQS_DP<5>")
	)
	(segment
		(start 329.321668 -225.507042)
		(end 329.359768 -225.52914)
		(width 0.09525)
		(layer "In2.Cu")
		(net "M_C_CPU0_SA_DQS_DP<5>")
	)
	(segment
		(start 327.479914 -222.289116)
		(end 327.514712 -222.309182)
		(width 0.09525)
		(layer "In2.Cu")
		(net "M_C_CPU0_SA_DQS_DP<5>")
	)
	(segment
		(start 329.791568 -226.317048)
		(end 329.829668 -226.339146)
		(width 0.09525)
		(layer "In2.Cu")
		(net "M_C_CPU0_SA_DQS_DP<5>")
	)
	(arc
		(start 328.452226 -223.927924)
		(mid 328.5675 -224.062202)
		(end 328.608944 -224.234248)
		(width 0.09525)
		(layer "In2.Cu")
		(net "M_C_CPU0_SA_DQS_DP<5>")
	)
	(arc
		(start 338.860892 -227.954332)
		(mid 339.045924 -227.908418)
		(end 339.2297 -227.959158)
		(width 0.09525)
		(layer "In2.Cu")
		(net "M_C_CPU0_SA_DQS_DP<5>")
	)
	(arc
		(start 327.199244 -221.80423)
		(mid 327.238225 -221.999889)
		(end 327.34885 -222.165926)
		(width 0.09525)
		(layer "In2.Cu")
		(net "M_C_CPU0_SA_DQS_DP<5>")
	)
	(arc
		(start 330.33208 -227.167948)
		(mid 330.447354 -227.302226)
		(end 330.488798 -227.474272)
		(width 0.09525)
		(layer "In2.Cu")
		(net "M_C_CPU0_SA_DQS_DP<5>")
	)
	(arc
		(start 342.989662 -227.959158)
		(mid 343.234088 -228.033801)
		(end 343.486232 -227.992178)
		(width 0.09525)
		(layer "In2.Cu")
		(net "M_C_CPU0_SA_DQS_DP<5>")
	)
	(arc
		(start 336.040984 -227.954332)
		(mid 336.226016 -227.908418)
		(end 336.409792 -227.959158)
		(width 0.09525)
		(layer "In2.Cu")
		(net "M_C_CPU0_SA_DQS_DP<5>")
	)
	(arc
		(start 332.649576 -227.959158)
		(mid 332.931008 -228.034913)
		(end 333.21244 -227.959158)
		(width 0.09525)
		(layer "In2.Cu")
		(net "M_C_CPU0_SA_DQS_DP<5>")
	)
	(arc
		(start 332.27264 -227.959158)
		(mid 332.461108 -227.908481)
		(end 332.649576 -227.959158)
		(width 0.09525)
		(layer "In2.Cu")
		(net "M_C_CPU0_SA_DQS_DP<5>")
	)
	(arc
		(start 330.488798 -227.474272)
		(mid 330.553195 -227.735578)
		(end 330.731622 -227.93706)
		(width 0.09525)
		(layer "In2.Cu")
		(net "M_C_CPU0_SA_DQS_DP<5>")
	)
	(arc
		(start 334.529684 -227.959158)
		(mid 334.811116 -228.034913)
		(end 335.092548 -227.959158)
		(width 0.09525)
		(layer "In2.Cu")
		(net "M_C_CPU0_SA_DQS_DP<5>")
	)
	(arc
		(start 327.514712 -222.309182)
		(mid 327.628497 -222.443226)
		(end 327.669398 -222.614236)
		(width 0.09525)
		(layer "In2.Cu")
		(net "M_C_CPU0_SA_DQS_DP<5>")
	)
	(arc
		(start 335.469738 -227.959158)
		(mid 335.75117 -228.034913)
		(end 336.032602 -227.959158)
		(width 0.09525)
		(layer "In2.Cu")
		(net "M_C_CPU0_SA_DQS_DP<5>")
	)
	(arc
		(start 328.922126 -224.73793)
		(mid 329.0374 -224.872208)
		(end 329.078844 -225.044254)
		(width 0.09525)
		(layer "In2.Cu")
		(net "M_C_CPU0_SA_DQS_DP<5>")
	)
	(arc
		(start 329.391264 -225.547428)
		(mid 329.507062 -225.681822)
		(end 329.548744 -225.85426)
		(width 0.09525)
		(layer "In2.Cu")
		(net "M_C_CPU0_SA_DQS_DP<5>")
	)
	(arc
		(start 333.21244 -227.959158)
		(mid 333.396215 -227.908386)
		(end 333.581248 -227.954332)
		(width 0.09525)
		(layer "In2.Cu")
		(net "M_C_CPU0_SA_DQS_DP<5>")
	)
	(arc
		(start 328.608944 -224.234248)
		(mid 328.674137 -224.496877)
		(end 328.854562 -224.69856)
		(width 0.09525)
		(layer "In2.Cu")
		(net "M_C_CPU0_SA_DQS_DP<5>")
	)
	(arc
		(start 329.548744 -225.85426)
		(mid 329.613141 -226.115566)
		(end 329.791568 -226.317048)
		(width 0.09525)
		(layer "In2.Cu")
		(net "M_C_CPU0_SA_DQS_DP<5>")
	)
	(arc
		(start 329.078844 -225.044254)
		(mid 329.143241 -225.30556)
		(end 329.321668 -225.507042)
		(width 0.09525)
		(layer "In2.Cu")
		(net "M_C_CPU0_SA_DQS_DP<5>")
	)
	(arc
		(start 327.669398 -222.614236)
		(mid 327.734158 -222.876171)
		(end 327.913492 -223.077786)
		(width 0.09525)
		(layer "In2.Cu")
		(net "M_C_CPU0_SA_DQS_DP<5>")
	)
	(arc
		(start 342.612472 -227.959158)
		(mid 342.796247 -227.908386)
		(end 342.98128 -227.954332)
		(width 0.09525)
		(layer "In2.Cu")
		(net "M_C_CPU0_SA_DQS_DP<5>")
	)
	(arc
		(start 336.972656 -227.959158)
		(mid 337.161124 -227.908481)
		(end 337.349592 -227.959158)
		(width 0.09525)
		(layer "In2.Cu")
		(net "M_C_CPU0_SA_DQS_DP<5>")
	)
	(arc
		(start 327.442068 -222.259652)
		(mid 327.460032 -222.275384)
		(end 327.479914 -222.288608)
		(width 0.09525)
		(layer "In2.Cu")
		(net "M_C_CPU0_SA_DQS_DP<5>")
	)
	(arc
		(start 334.152494 -227.959158)
		(mid 334.336269 -227.908386)
		(end 334.521302 -227.954332)
		(width 0.09525)
		(layer "In2.Cu")
		(net "M_C_CPU0_SA_DQS_DP<5>")
	)
	(arc
		(start 341.672418 -227.959158)
		(mid 341.856193 -227.908386)
		(end 342.041226 -227.954332)
		(width 0.09525)
		(layer "In2.Cu")
		(net "M_C_CPU0_SA_DQS_DP<5>")
	)
	(arc
		(start 341.109554 -227.959158)
		(mid 341.390986 -228.034913)
		(end 341.672418 -227.959158)
		(width 0.09525)
		(layer "In2.Cu")
		(net "M_C_CPU0_SA_DQS_DP<5>")
	)
	(arc
		(start 337.912456 -227.959158)
		(mid 338.096231 -227.908386)
		(end 338.281264 -227.954332)
		(width 0.09525)
		(layer "In2.Cu")
		(net "M_C_CPU0_SA_DQS_DP<5>")
	)
	(arc
		(start 339.800946 -227.954332)
		(mid 339.985978 -227.908418)
		(end 340.169754 -227.959158)
		(width 0.09525)
		(layer "In2.Cu")
		(net "M_C_CPU0_SA_DQS_DP<5>")
	)
	(arc
		(start 340.169754 -227.959158)
		(mid 340.451186 -228.034913)
		(end 340.732618 -227.959158)
		(width 0.09525)
		(layer "In2.Cu")
		(net "M_C_CPU0_SA_DQS_DP<5>")
	)
	(arc
		(start 339.2297 -227.959158)
		(mid 339.511132 -228.034913)
		(end 339.792564 -227.959158)
		(width 0.09525)
		(layer "In2.Cu")
		(net "M_C_CPU0_SA_DQS_DP<5>")
	)
	(arc
		(start 333.58963 -227.959158)
		(mid 333.871062 -228.034913)
		(end 334.152494 -227.959158)
		(width 0.09525)
		(layer "In2.Cu")
		(net "M_C_CPU0_SA_DQS_DP<5>")
	)
	(arc
		(start 331.709776 -227.959158)
		(mid 331.991208 -228.034913)
		(end 332.27264 -227.959158)
		(width 0.09525)
		(layer "In2.Cu")
		(net "M_C_CPU0_SA_DQS_DP<5>")
	)
	(arc
		(start 340.732618 -227.959158)
		(mid 340.921086 -227.908481)
		(end 341.109554 -227.959158)
		(width 0.09525)
		(layer "In2.Cu")
		(net "M_C_CPU0_SA_DQS_DP<5>")
	)
	(arc
		(start 330.769722 -227.959158)
		(mid 331.051154 -228.034913)
		(end 331.332586 -227.959158)
		(width 0.09525)
		(layer "In2.Cu")
		(net "M_C_CPU0_SA_DQS_DP<5>")
	)
	(arc
		(start 329.86218 -226.357942)
		(mid 329.977454 -226.49222)
		(end 330.018898 -226.664266)
		(width 0.09525)
		(layer "In2.Cu")
		(net "M_C_CPU0_SA_DQS_DP<5>")
	)
	(arc
		(start 335.10093 -227.954332)
		(mid 335.285962 -227.908418)
		(end 335.469738 -227.959158)
		(width 0.09525)
		(layer "In2.Cu")
		(net "M_C_CPU0_SA_DQS_DP<5>")
	)
	(arc
		(start 336.409792 -227.959158)
		(mid 336.691224 -228.034913)
		(end 336.972656 -227.959158)
		(width 0.09525)
		(layer "In2.Cu")
		(net "M_C_CPU0_SA_DQS_DP<5>")
	)
	(arc
		(start 342.049608 -227.959158)
		(mid 342.33104 -228.034913)
		(end 342.612472 -227.959158)
		(width 0.09525)
		(layer "In2.Cu")
		(net "M_C_CPU0_SA_DQS_DP<5>")
	)
	(arc
		(start 328.139044 -223.424242)
		(mid 328.204237 -223.686871)
		(end 328.384662 -223.888554)
		(width 0.09525)
		(layer "In2.Cu")
		(net "M_C_CPU0_SA_DQS_DP<5>")
	)
	(arc
		(start 327.981564 -223.11741)
		(mid 328.097362 -223.251804)
		(end 328.139044 -223.424242)
		(width 0.09525)
		(layer "In2.Cu")
		(net "M_C_CPU0_SA_DQS_DP<5>")
	)
	(arc
		(start 337.349592 -227.959158)
		(mid 337.631024 -228.034913)
		(end 337.912456 -227.959158)
		(width 0.09525)
		(layer "In2.Cu")
		(net "M_C_CPU0_SA_DQS_DP<5>")
	)
	(arc
		(start 330.018898 -226.664266)
		(mid 330.084091 -226.926895)
		(end 330.264516 -227.128578)
		(width 0.09525)
		(layer "In2.Cu")
		(net "M_C_CPU0_SA_DQS_DP<5>")
	)
	(arc
		(start 331.340968 -227.954332)
		(mid 331.526 -227.908418)
		(end 331.709776 -227.959158)
		(width 0.09525)
		(layer "In2.Cu")
		(net "M_C_CPU0_SA_DQS_DP<5>")
	)
	(arc
		(start 338.289646 -227.959158)
		(mid 338.571078 -228.034913)
		(end 338.85251 -227.959158)
		(width 0.09525)
		(layer "In2.Cu")
		(net "M_C_CPU0_SA_DQS_DP<5>")
	)
	(segment
		(start 342.327992 -246.370094)
		(end 341.86114 -246.104156)
		(width 0.12954)
		(layer "F.Cu")
		(net "M_C_CPU0_SA_DQS_DP<4>")
	)
	(segment
		(start 304.46472 -238.592614)
		(end 304.17516 -238.303054)
		(width 0.16002)
		(layer "In2.Cu")
		(net "M_C_CPU0_SA_DQS_DP<4>")
	)
	(segment
		(start 342.015064 -246.369586)
		(end 341.991696 -246.456454)
		(width 0.09525)
		(layer "In2.Cu")
		(net "M_C_CPU0_SA_DQS_DP<4>")
	)
	(segment
		(start 315.681106 -245.276878)
		(end 315.681106 -245.000018)
		(width 0.16002)
		(layer "In2.Cu")
		(net "M_C_CPU0_SA_DQS_DP<4>")
	)
	(segment
		(start 336.040984 -246.434102)
		(end 336.032602 -246.429276)
		(width 0.09525)
		(layer "In2.Cu")
		(net "M_C_CPU0_SA_DQS_DP<4>")
	)
	(segment
		(start 314.579508 -242.827048)
		(end 314.205874 -242.453414)
		(width 0.16002)
		(layer "In2.Cu")
		(net "M_C_CPU0_SA_DQS_DP<4>")
	)
	(segment
		(start 313.67857 -242.453414)
		(end 313.415934 -242.71605)
		(width 0.16002)
		(layer "In2.Cu")
		(net "M_C_CPU0_SA_DQS_DP<4>")
	)
	(segment
		(start 314.579508 -243.354352)
		(end 314.579508 -242.827048)
		(width 0.16002)
		(layer "In2.Cu")
		(net "M_C_CPU0_SA_DQS_DP<4>")
	)
	(segment
		(start 309.946802 -239.473486)
		(end 309.395114 -239.473486)
		(width 0.16002)
		(layer "In2.Cu")
		(net "M_C_CPU0_SA_DQS_DP<4>")
	)
	(segment
		(start 315.23051 -243.648738)
		(end 314.528962 -244.350286)
		(width 0.16002)
		(layer "In2.Cu")
		(net "M_C_CPU0_SA_DQS_DP<4>")
	)
	(segment
		(start 315.681106 -245.000018)
		(end 316.131448 -244.549676)
		(width 0.16002)
		(layer "In2.Cu")
		(net "M_C_CPU0_SA_DQS_DP<4>")
	)
	(segment
		(start 314.205874 -242.453414)
		(end 313.67857 -242.453414)
		(width 0.16002)
		(layer "In2.Cu")
		(net "M_C_CPU0_SA_DQS_DP<4>")
	)
	(segment
		(start 324.213474 -246.398542)
		(end 323.978778 -246.398542)
		(width 0.09525)
		(layer "In2.Cu")
		(net "M_C_CPU0_SA_DQS_DP<4>")
	)
	(segment
		(start 312.694066 -242.22075)
		(end 312.142378 -242.22075)
		(width 0.16002)
		(layer "In2.Cu")
		(net "M_C_CPU0_SA_DQS_DP<4>")
	)
	(segment
		(start 316.641734 -245.757446)
		(end 316.161674 -245.757446)
		(width 0.16002)
		(layer "In2.Cu")
		(net "M_C_CPU0_SA_DQS_DP<4>")
	)
	(segment
		(start 326.640444 -246.434102)
		(end 326.632062 -246.429276)
		(width 0.09525)
		(layer "In2.Cu")
		(net "M_C_CPU0_SA_DQS_DP<4>")
	)
	(segment
		(start 313.189366 -242.71605)
		(end 312.694066 -242.22075)
		(width 0.16002)
		(layer "In2.Cu")
		(net "M_C_CPU0_SA_DQS_DP<4>")
	)
	(segment
		(start 325.59625 -246.76481)
		(end 324.579742 -246.76481)
		(width 0.09525)
		(layer "In2.Cu")
		(net "M_C_CPU0_SA_DQS_DP<4>")
	)
	(segment
		(start 329.829668 -246.429276)
		(end 329.821286 -246.434102)
		(width 0.09525)
		(layer "In2.Cu")
		(net "M_C_CPU0_SA_DQS_DP<4>")
	)
	(segment
		(start 339.800946 -246.434102)
		(end 339.792564 -246.429276)
		(width 0.09525)
		(layer "In2.Cu")
		(net "M_C_CPU0_SA_DQS_DP<4>")
	)
	(segment
		(start 311.819544 -241.897916)
		(end 311.819544 -241.346228)
		(width 0.16002)
		(layer "In2.Cu")
		(net "M_C_CPU0_SA_DQS_DP<4>")
	)
	(segment
		(start 341.86114 -246.104156)
		(end 342.015064 -246.369586)
		(width 0.09525)
		(layer "In2.Cu")
		(net "M_C_CPU0_SA_DQS_DP<4>")
	)
	(segment
		(start 308.797198 -238.323882)
		(end 308.797198 -237.89259)
		(width 0.16002)
		(layer "In2.Cu")
		(net "M_C_CPU0_SA_DQS_DP<4>")
	)
	(segment
		(start 311.819544 -241.346228)
		(end 311.320434 -240.847118)
		(width 0.16002)
		(layer "In2.Cu")
		(net "M_C_CPU0_SA_DQS_DP<4>")
	)
	(segment
		(start 316.758574 -245.640606)
		(end 316.641734 -245.757446)
		(width 0.16002)
		(layer "In2.Cu")
		(net "M_C_CPU0_SA_DQS_DP<4>")
	)
	(segment
		(start 309.07228 -239.150652)
		(end 309.07228 -238.598964)
		(width 0.16002)
		(layer "In2.Cu")
		(net "M_C_CPU0_SA_DQS_DP<4>")
	)
	(segment
		(start 310.768746 -240.847118)
		(end 310.445912 -240.524284)
		(width 0.16002)
		(layer "In2.Cu")
		(net "M_C_CPU0_SA_DQS_DP<4>")
	)
	(segment
		(start 298.237656 -237.721394)
		(end 297.384216 -238.574834)
		(width 0.16002)
		(layer "In2.Cu")
		(net "M_C_CPU0_SA_DQS_DP<4>")
	)
	(segment
		(start 296.61866 -238.259874)
		(end 293.59098 -238.259874)
		(width 0.16002)
		(layer "In2.Cu")
		(net "M_C_CPU0_SA_DQS_DP<4>")
	)
	(segment
		(start 327.949814 -246.429276)
		(end 327.941432 -246.434102)
		(width 0.09525)
		(layer "In2.Cu")
		(net "M_C_CPU0_SA_DQS_DP<4>")
	)
	(segment
		(start 310.445912 -239.972596)
		(end 309.946802 -239.473486)
		(width 0.16002)
		(layer "In2.Cu")
		(net "M_C_CPU0_SA_DQS_DP<4>")
	)
	(segment
		(start 323.657468 -246.33936)
		(end 323.075554 -245.757446)
		(width 0.16002)
		(layer "In2.Cu")
		(net "M_C_CPU0_SA_DQS_DP<4>")
	)
	(segment
		(start 314.252102 -244.350286)
		(end 314.056268 -244.154452)
		(width 0.16002)
		(layer "In2.Cu")
		(net "M_C_CPU0_SA_DQS_DP<4>")
	)
	(segment
		(start 338.289646 -246.429276)
		(end 338.281264 -246.434102)
		(width 0.09525)
		(layer "In2.Cu")
		(net "M_C_CPU0_SA_DQS_DP<4>")
	)
	(segment
		(start 326.632062 -246.429276)
		(end 326.611234 -246.417084)
		(width 0.09525)
		(layer "In2.Cu")
		(net "M_C_CPU0_SA_DQS_DP<4>")
	)
	(segment
		(start 323.895974 -246.33936)
		(end 323.657468 -246.33936)
		(width 0.16002)
		(layer "In2.Cu")
		(net "M_C_CPU0_SA_DQS_DP<4>")
	)
	(segment
		(start 338.860892 -246.434102)
		(end 338.85251 -246.429276)
		(width 0.09525)
		(layer "In2.Cu")
		(net "M_C_CPU0_SA_DQS_DP<4>")
	)
	(segment
		(start 306.429156 -237.444534)
		(end 306.078636 -237.795054)
		(width 0.16002)
		(layer "In2.Cu")
		(net "M_C_CPU0_SA_DQS_DP<4>")
	)
	(segment
		(start 312.142378 -242.22075)
		(end 311.819544 -241.897916)
		(width 0.16002)
		(layer "In2.Cu")
		(net "M_C_CPU0_SA_DQS_DP<4>")
	)
	(segment
		(start 301.732696 -238.303054)
		(end 300.839632 -237.40999)
		(width 0.16002)
		(layer "In2.Cu")
		(net "M_C_CPU0_SA_DQS_DP<4>")
	)
	(segment
		(start 315.757814 -243.648738)
		(end 315.23051 -243.648738)
		(width 0.16002)
		(layer "In2.Cu")
		(net "M_C_CPU0_SA_DQS_DP<4>")
	)
	(segment
		(start 333.58963 -246.429276)
		(end 333.581248 -246.434102)
		(width 0.09525)
		(layer "In2.Cu")
		(net "M_C_CPU0_SA_DQS_DP<4>")
	)
	(segment
		(start 310.445912 -240.524284)
		(end 310.445912 -239.972596)
		(width 0.16002)
		(layer "In2.Cu")
		(net "M_C_CPU0_SA_DQS_DP<4>")
	)
	(segment
		(start 300.839632 -237.40999)
		(end 298.95546 -237.40999)
		(width 0.16002)
		(layer "In2.Cu")
		(net "M_C_CPU0_SA_DQS_DP<4>")
	)
	(segment
		(start 309.07228 -238.598964)
		(end 308.797198 -238.323882)
		(width 0.16002)
		(layer "In2.Cu")
		(net "M_C_CPU0_SA_DQS_DP<4>")
	)
	(segment
		(start 305.601116 -237.795054)
		(end 304.803556 -238.592614)
		(width 0.16002)
		(layer "In2.Cu")
		(net "M_C_CPU0_SA_DQS_DP<4>")
	)
	(segment
		(start 327.023476 -246.42064)
		(end 327.008744 -246.429276)
		(width 0.09525)
		(layer "In2.Cu")
		(net "M_C_CPU0_SA_DQS_DP<4>")
	)
	(segment
		(start 314.528962 -244.350286)
		(end 314.252102 -244.350286)
		(width 0.16002)
		(layer "In2.Cu")
		(net "M_C_CPU0_SA_DQS_DP<4>")
	)
	(segment
		(start 313.415934 -242.71605)
		(end 313.189366 -242.71605)
		(width 0.16002)
		(layer "In2.Cu")
		(net "M_C_CPU0_SA_DQS_DP<4>")
	)
	(segment
		(start 317.238634 -245.640606)
		(end 316.758574 -245.640606)
		(width 0.16002)
		(layer "In2.Cu")
		(net "M_C_CPU0_SA_DQS_DP<4>")
	)
	(segment
		(start 335.10093 -246.434102)
		(end 335.092548 -246.429276)
		(width 0.09525)
		(layer "In2.Cu")
		(net "M_C_CPU0_SA_DQS_DP<4>")
	)
	(segment
		(start 316.131448 -244.549676)
		(end 316.131448 -244.022372)
		(width 0.16002)
		(layer "In2.Cu")
		(net "M_C_CPU0_SA_DQS_DP<4>")
	)
	(segment
		(start 292.553898 -238.408972)
		(end 292.280086 -238.13516)
		(width 0.16002)
		(layer "In2.Cu")
		(net "M_C_CPU0_SA_DQS_DP<4>")
	)
	(segment
		(start 308.797198 -237.89259)
		(end 308.349142 -237.444534)
		(width 0.16002)
		(layer "In2.Cu")
		(net "M_C_CPU0_SA_DQS_DP<4>")
	)
	(segment
		(start 325.879968 -246.481092)
		(end 325.59625 -246.76481)
		(width 0.09525)
		(layer "In2.Cu")
		(net "M_C_CPU0_SA_DQS_DP<4>")
	)
	(segment
		(start 298.95546 -237.40999)
		(end 298.644056 -237.721394)
		(width 0.16002)
		(layer "In2.Cu")
		(net "M_C_CPU0_SA_DQS_DP<4>")
	)
	(segment
		(start 331.340968 -246.434102)
		(end 331.332586 -246.429276)
		(width 0.09525)
		(layer "In2.Cu")
		(net "M_C_CPU0_SA_DQS_DP<4>")
	)
	(segment
		(start 293.441882 -238.408972)
		(end 292.553898 -238.408972)
		(width 0.16002)
		(layer "In2.Cu")
		(net "M_C_CPU0_SA_DQS_DP<4>")
	)
	(segment
		(start 311.320434 -240.847118)
		(end 310.768746 -240.847118)
		(width 0.16002)
		(layer "In2.Cu")
		(net "M_C_CPU0_SA_DQS_DP<4>")
	)
	(segment
		(start 298.644056 -237.721394)
		(end 298.237656 -237.721394)
		(width 0.16002)
		(layer "In2.Cu")
		(net "M_C_CPU0_SA_DQS_DP<4>")
	)
	(segment
		(start 323.075554 -245.757446)
		(end 317.355474 -245.757446)
		(width 0.16002)
		(layer "In2.Cu")
		(net "M_C_CPU0_SA_DQS_DP<4>")
	)
	(segment
		(start 323.978778 -246.398542)
		(end 323.919596 -246.33936)
		(width 0.09525)
		(layer "In2.Cu")
		(net "M_C_CPU0_SA_DQS_DP<4>")
	)
	(segment
		(start 297.384216 -238.574834)
		(end 296.93362 -238.574834)
		(width 0.16002)
		(layer "In2.Cu")
		(net "M_C_CPU0_SA_DQS_DP<4>")
	)
	(segment
		(start 304.803556 -238.592614)
		(end 304.46472 -238.592614)
		(width 0.16002)
		(layer "In2.Cu")
		(net "M_C_CPU0_SA_DQS_DP<4>")
	)
	(segment
		(start 316.161674 -245.757446)
		(end 315.681106 -245.276878)
		(width 0.16002)
		(layer "In2.Cu")
		(net "M_C_CPU0_SA_DQS_DP<4>")
	)
	(segment
		(start 296.93362 -238.574834)
		(end 296.61866 -238.259874)
		(width 0.16002)
		(layer "In2.Cu")
		(net "M_C_CPU0_SA_DQS_DP<4>")
	)
	(segment
		(start 330.400914 -246.434102)
		(end 330.392532 -246.429276)
		(width 0.09525)
		(layer "In2.Cu")
		(net "M_C_CPU0_SA_DQS_DP<4>")
	)
	(segment
		(start 316.131448 -244.022372)
		(end 315.757814 -243.648738)
		(width 0.16002)
		(layer "In2.Cu")
		(net "M_C_CPU0_SA_DQS_DP<4>")
	)
	(segment
		(start 306.078636 -237.795054)
		(end 305.601116 -237.795054)
		(width 0.16002)
		(layer "In2.Cu")
		(net "M_C_CPU0_SA_DQS_DP<4>")
	)
	(segment
		(start 304.17516 -238.303054)
		(end 301.732696 -238.303054)
		(width 0.16002)
		(layer "In2.Cu")
		(net "M_C_CPU0_SA_DQS_DP<4>")
	)
	(segment
		(start 323.919596 -246.33936)
		(end 323.895974 -246.33936)
		(width 0.09525)
		(layer "In2.Cu")
		(net "M_C_CPU0_SA_DQS_DP<4>")
	)
	(segment
		(start 309.395114 -239.473486)
		(end 309.07228 -239.150652)
		(width 0.16002)
		(layer "In2.Cu")
		(net "M_C_CPU0_SA_DQS_DP<4>")
	)
	(segment
		(start 317.355474 -245.757446)
		(end 317.238634 -245.640606)
		(width 0.16002)
		(layer "In2.Cu")
		(net "M_C_CPU0_SA_DQS_DP<4>")
	)
	(segment
		(start 314.056268 -243.877592)
		(end 314.579508 -243.354352)
		(width 0.16002)
		(layer "In2.Cu")
		(net "M_C_CPU0_SA_DQS_DP<4>")
	)
	(segment
		(start 308.349142 -237.444534)
		(end 306.429156 -237.444534)
		(width 0.16002)
		(layer "In2.Cu")
		(net "M_C_CPU0_SA_DQS_DP<4>")
	)
	(segment
		(start 324.579742 -246.76481)
		(end 324.213474 -246.398542)
		(width 0.09525)
		(layer "In2.Cu")
		(net "M_C_CPU0_SA_DQS_DP<4>")
	)
	(segment
		(start 314.056268 -244.154452)
		(end 314.056268 -243.877592)
		(width 0.16002)
		(layer "In2.Cu")
		(net "M_C_CPU0_SA_DQS_DP<4>")
	)
	(segment
		(start 293.59098 -238.259874)
		(end 293.441882 -238.408972)
		(width 0.16002)
		(layer "In2.Cu")
		(net "M_C_CPU0_SA_DQS_DP<4>")
	)
	(segment
		(start 334.529684 -246.429276)
		(end 334.521302 -246.434102)
		(width 0.09525)
		(layer "In2.Cu")
		(net "M_C_CPU0_SA_DQS_DP<4>")
	)
	(arc
		(start 330.769722 -246.429276)
		(mid 330.585947 -246.480048)
		(end 330.400914 -246.434102)
		(width 0.09525)
		(layer "In2.Cu")
		(net "M_C_CPU0_SA_DQS_DP<4>")
	)
	(arc
		(start 329.821286 -246.434102)
		(mid 329.636254 -246.480016)
		(end 329.452478 -246.429276)
		(width 0.09525)
		(layer "In2.Cu")
		(net "M_C_CPU0_SA_DQS_DP<4>")
	)
	(arc
		(start 326.611234 -246.417084)
		(mid 326.338629 -246.353288)
		(end 326.069198 -246.429276)
		(width 0.09525)
		(layer "In2.Cu")
		(net "M_C_CPU0_SA_DQS_DP<4>")
	)
	(arc
		(start 340.169754 -246.429276)
		(mid 339.985979 -246.480048)
		(end 339.800946 -246.434102)
		(width 0.09525)
		(layer "In2.Cu")
		(net "M_C_CPU0_SA_DQS_DP<4>")
	)
	(arc
		(start 328.889614 -246.429276)
		(mid 328.701146 -246.479953)
		(end 328.512678 -246.429276)
		(width 0.09525)
		(layer "In2.Cu")
		(net "M_C_CPU0_SA_DQS_DP<4>")
	)
	(arc
		(start 335.092548 -246.429276)
		(mid 334.811116 -246.353521)
		(end 334.529684 -246.429276)
		(width 0.09525)
		(layer "In2.Cu")
		(net "M_C_CPU0_SA_DQS_DP<4>")
	)
	(arc
		(start 334.521302 -246.434102)
		(mid 334.33627 -246.480016)
		(end 334.152494 -246.429276)
		(width 0.09525)
		(layer "In2.Cu")
		(net "M_C_CPU0_SA_DQS_DP<4>")
	)
	(arc
		(start 330.392532 -246.429276)
		(mid 330.1111 -246.353521)
		(end 329.829668 -246.429276)
		(width 0.09525)
		(layer "In2.Cu")
		(net "M_C_CPU0_SA_DQS_DP<4>")
	)
	(arc
		(start 333.581248 -246.434102)
		(mid 333.396216 -246.480016)
		(end 333.21244 -246.429276)
		(width 0.09525)
		(layer "In2.Cu")
		(net "M_C_CPU0_SA_DQS_DP<4>")
	)
	(arc
		(start 327.572116 -246.429276)
		(mid 327.298934 -246.353334)
		(end 327.023476 -246.42064)
		(width 0.09525)
		(layer "In2.Cu")
		(net "M_C_CPU0_SA_DQS_DP<4>")
	)
	(arc
		(start 341.109554 -246.429276)
		(mid 340.921086 -246.479953)
		(end 340.732618 -246.429276)
		(width 0.09525)
		(layer "In2.Cu")
		(net "M_C_CPU0_SA_DQS_DP<4>")
	)
	(arc
		(start 331.332586 -246.429276)
		(mid 331.051154 -246.353521)
		(end 330.769722 -246.429276)
		(width 0.09525)
		(layer "In2.Cu")
		(net "M_C_CPU0_SA_DQS_DP<4>")
	)
	(arc
		(start 336.032602 -246.429276)
		(mid 335.75117 -246.353521)
		(end 335.469738 -246.429276)
		(width 0.09525)
		(layer "In2.Cu")
		(net "M_C_CPU0_SA_DQS_DP<4>")
	)
	(arc
		(start 338.281264 -246.434102)
		(mid 338.096232 -246.480016)
		(end 337.912456 -246.429276)
		(width 0.09525)
		(layer "In2.Cu")
		(net "M_C_CPU0_SA_DQS_DP<4>")
	)
	(arc
		(start 327.941432 -246.434102)
		(mid 327.756146 -246.480138)
		(end 327.572116 -246.429276)
		(width 0.09525)
		(layer "In2.Cu")
		(net "M_C_CPU0_SA_DQS_DP<4>")
	)
	(arc
		(start 327.008744 -246.429276)
		(mid 326.825223 -246.47992)
		(end 326.640444 -246.434102)
		(width 0.09525)
		(layer "In2.Cu")
		(net "M_C_CPU0_SA_DQS_DP<4>")
	)
	(arc
		(start 331.709776 -246.429276)
		(mid 331.526001 -246.480048)
		(end 331.340968 -246.434102)
		(width 0.09525)
		(layer "In2.Cu")
		(net "M_C_CPU0_SA_DQS_DP<4>")
	)
	(arc
		(start 336.409792 -246.429276)
		(mid 336.226017 -246.480048)
		(end 336.040984 -246.434102)
		(width 0.09525)
		(layer "In2.Cu")
		(net "M_C_CPU0_SA_DQS_DP<4>")
	)
	(arc
		(start 341.991696 -246.456454)
		(mid 341.829014 -246.478586)
		(end 341.672418 -246.429276)
		(width 0.09525)
		(layer "In2.Cu")
		(net "M_C_CPU0_SA_DQS_DP<4>")
	)
	(arc
		(start 341.672418 -246.429276)
		(mid 341.390986 -246.353521)
		(end 341.109554 -246.429276)
		(width 0.09525)
		(layer "In2.Cu")
		(net "M_C_CPU0_SA_DQS_DP<4>")
	)
	(arc
		(start 332.649576 -246.429276)
		(mid 332.461108 -246.479953)
		(end 332.27264 -246.429276)
		(width 0.09525)
		(layer "In2.Cu")
		(net "M_C_CPU0_SA_DQS_DP<4>")
	)
	(arc
		(start 326.069198 -246.429276)
		(mid 325.978023 -246.467767)
		(end 325.879968 -246.481092)
		(width 0.09525)
		(layer "In2.Cu")
		(net "M_C_CPU0_SA_DQS_DP<4>")
	)
	(arc
		(start 329.452478 -246.429276)
		(mid 329.171046 -246.353521)
		(end 328.889614 -246.429276)
		(width 0.09525)
		(layer "In2.Cu")
		(net "M_C_CPU0_SA_DQS_DP<4>")
	)
	(arc
		(start 340.732618 -246.429276)
		(mid 340.451186 -246.353521)
		(end 340.169754 -246.429276)
		(width 0.09525)
		(layer "In2.Cu")
		(net "M_C_CPU0_SA_DQS_DP<4>")
	)
	(arc
		(start 339.792564 -246.429276)
		(mid 339.511132 -246.353521)
		(end 339.2297 -246.429276)
		(width 0.09525)
		(layer "In2.Cu")
		(net "M_C_CPU0_SA_DQS_DP<4>")
	)
	(arc
		(start 339.2297 -246.429276)
		(mid 339.045925 -246.480048)
		(end 338.860892 -246.434102)
		(width 0.09525)
		(layer "In2.Cu")
		(net "M_C_CPU0_SA_DQS_DP<4>")
	)
	(arc
		(start 332.27264 -246.429276)
		(mid 331.991208 -246.353521)
		(end 331.709776 -246.429276)
		(width 0.09525)
		(layer "In2.Cu")
		(net "M_C_CPU0_SA_DQS_DP<4>")
	)
	(arc
		(start 335.469738 -246.429276)
		(mid 335.285963 -246.480048)
		(end 335.10093 -246.434102)
		(width 0.09525)
		(layer "In2.Cu")
		(net "M_C_CPU0_SA_DQS_DP<4>")
	)
	(arc
		(start 333.21244 -246.429276)
		(mid 332.931008 -246.353521)
		(end 332.649576 -246.429276)
		(width 0.09525)
		(layer "In2.Cu")
		(net "M_C_CPU0_SA_DQS_DP<4>")
	)
	(arc
		(start 334.152494 -246.429276)
		(mid 333.871062 -246.353521)
		(end 333.58963 -246.429276)
		(width 0.09525)
		(layer "In2.Cu")
		(net "M_C_CPU0_SA_DQS_DP<4>")
	)
	(arc
		(start 328.512678 -246.429276)
		(mid 328.231246 -246.353521)
		(end 327.949814 -246.429276)
		(width 0.09525)
		(layer "In2.Cu")
		(net "M_C_CPU0_SA_DQS_DP<4>")
	)
	(arc
		(start 338.85251 -246.429276)
		(mid 338.571078 -246.353521)
		(end 338.289646 -246.429276)
		(width 0.09525)
		(layer "In2.Cu")
		(net "M_C_CPU0_SA_DQS_DP<4>")
	)
	(arc
		(start 336.972656 -246.429276)
		(mid 336.691224 -246.353521)
		(end 336.409792 -246.429276)
		(width 0.09525)
		(layer "In2.Cu")
		(net "M_C_CPU0_SA_DQS_DP<4>")
	)
	(arc
		(start 337.912456 -246.429276)
		(mid 337.631024 -246.353521)
		(end 337.349592 -246.429276)
		(width 0.09525)
		(layer "In2.Cu")
		(net "M_C_CPU0_SA_DQS_DP<4>")
	)
	(arc
		(start 337.349592 -246.429276)
		(mid 337.161124 -246.479953)
		(end 336.972656 -246.429276)
		(width 0.09525)
		(layer "In2.Cu")
		(net "M_C_CPU0_SA_DQS_DP<4>")
	)
	(segment
		(start 342.327992 -241.510058)
		(end 341.86114 -241.24412)
		(width 0.12954)
		(layer "F.Cu")
		(net "M_C_CPU0_SA_DQS_DP<3>")
	)
	(segment
		(start 342.015064 -241.50955)
		(end 341.991696 -241.596418)
		(width 0.09525)
		(layer "In2.Cu")
		(net "M_C_CPU0_SA_DQS_DP<3>")
	)
	(segment
		(start 296.61866 -228.90988)
		(end 294.758364 -228.90988)
		(width 0.16002)
		(layer "In2.Cu")
		(net "M_C_CPU0_SA_DQS_DP<3>")
	)
	(segment
		(start 324.415404 -240.117884)
		(end 324.069202 -240.117884)
		(width 0.09525)
		(layer "In2.Cu")
		(net "M_C_CPU0_SA_DQS_DP<3>")
	)
	(segment
		(start 341.86114 -241.24412)
		(end 342.015064 -241.50955)
		(width 0.09525)
		(layer "In2.Cu")
		(net "M_C_CPU0_SA_DQS_DP<3>")
	)
	(segment
		(start 305.601116 -228.44506)
		(end 304.760376 -229.2858)
		(width 0.16002)
		(layer "In2.Cu")
		(net "M_C_CPU0_SA_DQS_DP<3>")
	)
	(segment
		(start 309.38089 -229.096062)
		(end 308.379368 -228.09454)
		(width 0.16002)
		(layer "In2.Cu")
		(net "M_C_CPU0_SA_DQS_DP<3>")
	)
	(segment
		(start 312.54954 -230.702612)
		(end 312.549794 -230.175816)
		(width 0.16002)
		(layer "In2.Cu")
		(net "M_C_CPU0_SA_DQS_DP<3>")
	)
	(segment
		(start 308.379368 -228.09454)
		(end 306.429156 -228.09454)
		(width 0.16002)
		(layer "In2.Cu")
		(net "M_C_CPU0_SA_DQS_DP<3>")
	)
	(segment
		(start 311.254394 -228.723952)
		(end 310.880506 -228.350064)
		(width 0.16002)
		(layer "In2.Cu")
		(net "M_C_CPU0_SA_DQS_DP<3>")
	)
	(segment
		(start 320.26479 -240.058702)
		(end 311.86755 -231.661462)
		(width 0.16002)
		(layer "In2.Cu")
		(net "M_C_CPU0_SA_DQS_DP<3>")
	)
	(segment
		(start 293.532306 -228.942138)
		(end 293.415466 -229.058978)
		(width 0.16002)
		(layer "In2.Cu")
		(net "M_C_CPU0_SA_DQS_DP<3>")
	)
	(segment
		(start 324.994016 -240.29035)
		(end 324.58787 -240.29035)
		(width 0.09525)
		(layer "In2.Cu")
		(net "M_C_CPU0_SA_DQS_DP<3>")
	)
	(segment
		(start 312.549794 -230.175816)
		(end 312.175906 -229.801928)
		(width 0.16002)
		(layer "In2.Cu")
		(net "M_C_CPU0_SA_DQS_DP<3>")
	)
	(segment
		(start 294.129206 -229.058978)
		(end 294.012366 -228.942138)
		(width 0.16002)
		(layer "In2.Cu")
		(net "M_C_CPU0_SA_DQS_DP<3>")
	)
	(segment
		(start 331.340968 -241.574066)
		(end 331.332586 -241.56924)
		(width 0.09525)
		(layer "In2.Cu")
		(net "M_C_CPU0_SA_DQS_DP<3>")
	)
	(segment
		(start 300.830488 -228.059996)
		(end 298.927012 -228.059996)
		(width 0.16002)
		(layer "In2.Cu")
		(net "M_C_CPU0_SA_DQS_DP<3>")
	)
	(segment
		(start 294.758364 -228.90988)
		(end 294.609266 -229.058978)
		(width 0.16002)
		(layer "In2.Cu")
		(net "M_C_CPU0_SA_DQS_DP<3>")
	)
	(segment
		(start 329.829668 -241.56924)
		(end 329.821286 -241.574066)
		(width 0.09525)
		(layer "In2.Cu")
		(net "M_C_CPU0_SA_DQS_DP<3>")
	)
	(segment
		(start 330.400914 -241.574066)
		(end 330.392532 -241.56924)
		(width 0.09525)
		(layer "In2.Cu")
		(net "M_C_CPU0_SA_DQS_DP<3>")
	)
	(segment
		(start 311.25414 -229.250748)
		(end 311.254394 -228.723952)
		(width 0.16002)
		(layer "In2.Cu")
		(net "M_C_CPU0_SA_DQS_DP<3>")
	)
	(segment
		(start 310.353202 -228.350064)
		(end 309.607204 -229.096062)
		(width 0.16002)
		(layer "In2.Cu")
		(net "M_C_CPU0_SA_DQS_DP<3>")
	)
	(segment
		(start 292.553898 -229.058978)
		(end 292.280086 -228.785166)
		(width 0.16002)
		(layer "In2.Cu")
		(net "M_C_CPU0_SA_DQS_DP<3>")
	)
	(segment
		(start 304.760376 -229.2858)
		(end 304.533808 -229.2858)
		(width 0.16002)
		(layer "In2.Cu")
		(net "M_C_CPU0_SA_DQS_DP<3>")
	)
	(segment
		(start 311.648602 -229.801674)
		(end 310.966612 -230.483664)
		(width 0.16002)
		(layer "In2.Cu")
		(net "M_C_CPU0_SA_DQS_DP<3>")
	)
	(segment
		(start 298.237656 -228.3714)
		(end 297.272202 -229.336854)
		(width 0.16002)
		(layer "In2.Cu")
		(net "M_C_CPU0_SA_DQS_DP<3>")
	)
	(segment
		(start 297.272202 -229.336854)
		(end 297.045634 -229.336854)
		(width 0.16002)
		(layer "In2.Cu")
		(net "M_C_CPU0_SA_DQS_DP<3>")
	)
	(segment
		(start 335.10093 -241.574066)
		(end 335.092548 -241.56924)
		(width 0.09525)
		(layer "In2.Cu")
		(net "M_C_CPU0_SA_DQS_DP<3>")
	)
	(segment
		(start 333.58963 -241.56924)
		(end 333.581248 -241.574066)
		(width 0.09525)
		(layer "In2.Cu")
		(net "M_C_CPU0_SA_DQS_DP<3>")
	)
	(segment
		(start 306.078636 -228.44506)
		(end 305.601116 -228.44506)
		(width 0.16002)
		(layer "In2.Cu")
		(net "M_C_CPU0_SA_DQS_DP<3>")
	)
	(segment
		(start 336.040984 -241.574066)
		(end 336.032602 -241.56924)
		(width 0.09525)
		(layer "In2.Cu")
		(net "M_C_CPU0_SA_DQS_DP<3>")
	)
	(segment
		(start 327.581006 -241.574066)
		(end 327.572624 -241.56924)
		(width 0.09525)
		(layer "In2.Cu")
		(net "M_C_CPU0_SA_DQS_DP<3>")
	)
	(segment
		(start 324.069202 -240.117884)
		(end 324.01002 -240.058702)
		(width 0.09525)
		(layer "In2.Cu")
		(net "M_C_CPU0_SA_DQS_DP<3>")
	)
	(segment
		(start 309.607204 -229.096062)
		(end 309.38089 -229.096062)
		(width 0.16002)
		(layer "In2.Cu")
		(net "M_C_CPU0_SA_DQS_DP<3>")
	)
	(segment
		(start 338.860892 -241.574066)
		(end 338.85251 -241.56924)
		(width 0.09525)
		(layer "In2.Cu")
		(net "M_C_CPU0_SA_DQS_DP<3>")
	)
	(segment
		(start 338.289646 -241.56924)
		(end 338.281264 -241.574066)
		(width 0.09525)
		(layer "In2.Cu")
		(net "M_C_CPU0_SA_DQS_DP<3>")
	)
	(segment
		(start 323.986398 -240.058702)
		(end 320.26479 -240.058702)
		(width 0.16002)
		(layer "In2.Cu")
		(net "M_C_CPU0_SA_DQS_DP<3>")
	)
	(segment
		(start 310.493918 -230.01097)
		(end 311.25414 -229.250748)
		(width 0.16002)
		(layer "In2.Cu")
		(net "M_C_CPU0_SA_DQS_DP<3>")
	)
	(segment
		(start 310.689752 -230.483664)
		(end 310.493918 -230.28783)
		(width 0.16002)
		(layer "In2.Cu")
		(net "M_C_CPU0_SA_DQS_DP<3>")
	)
	(segment
		(start 297.045634 -229.336854)
		(end 296.61866 -228.90988)
		(width 0.16002)
		(layer "In2.Cu")
		(net "M_C_CPU0_SA_DQS_DP<3>")
	)
	(segment
		(start 294.609266 -229.058978)
		(end 294.129206 -229.058978)
		(width 0.16002)
		(layer "In2.Cu")
		(net "M_C_CPU0_SA_DQS_DP<3>")
	)
	(segment
		(start 301.723552 -228.95306)
		(end 300.830488 -228.059996)
		(width 0.16002)
		(layer "In2.Cu")
		(net "M_C_CPU0_SA_DQS_DP<3>")
	)
	(segment
		(start 304.533808 -229.2858)
		(end 304.201068 -228.95306)
		(width 0.16002)
		(layer "In2.Cu")
		(net "M_C_CPU0_SA_DQS_DP<3>")
	)
	(segment
		(start 293.415466 -229.058978)
		(end 292.553898 -229.058978)
		(width 0.16002)
		(layer "In2.Cu")
		(net "M_C_CPU0_SA_DQS_DP<3>")
	)
	(segment
		(start 298.927012 -228.059996)
		(end 298.615608 -228.3714)
		(width 0.16002)
		(layer "In2.Cu")
		(net "M_C_CPU0_SA_DQS_DP<3>")
	)
	(segment
		(start 310.966612 -230.483664)
		(end 310.689752 -230.483664)
		(width 0.16002)
		(layer "In2.Cu")
		(net "M_C_CPU0_SA_DQS_DP<3>")
	)
	(segment
		(start 310.880506 -228.350064)
		(end 310.353202 -228.350064)
		(width 0.16002)
		(layer "In2.Cu")
		(net "M_C_CPU0_SA_DQS_DP<3>")
	)
	(segment
		(start 326.197214 -241.493548)
		(end 324.994016 -240.29035)
		(width 0.09525)
		(layer "In2.Cu")
		(net "M_C_CPU0_SA_DQS_DP<3>")
	)
	(segment
		(start 306.429156 -228.09454)
		(end 306.078636 -228.44506)
		(width 0.16002)
		(layer "In2.Cu")
		(net "M_C_CPU0_SA_DQS_DP<3>")
	)
	(segment
		(start 324.58787 -240.29035)
		(end 324.415404 -240.117884)
		(width 0.09525)
		(layer "In2.Cu")
		(net "M_C_CPU0_SA_DQS_DP<3>")
	)
	(segment
		(start 311.86755 -231.384602)
		(end 312.54954 -230.702612)
		(width 0.16002)
		(layer "In2.Cu")
		(net "M_C_CPU0_SA_DQS_DP<3>")
	)
	(segment
		(start 326.351138 -241.493548)
		(end 326.197214 -241.493548)
		(width 0.09525)
		(layer "In2.Cu")
		(net "M_C_CPU0_SA_DQS_DP<3>")
	)
	(segment
		(start 304.201068 -228.95306)
		(end 301.723552 -228.95306)
		(width 0.16002)
		(layer "In2.Cu")
		(net "M_C_CPU0_SA_DQS_DP<3>")
	)
	(segment
		(start 334.529684 -241.56924)
		(end 334.521302 -241.574066)
		(width 0.09525)
		(layer "In2.Cu")
		(net "M_C_CPU0_SA_DQS_DP<3>")
	)
	(segment
		(start 324.01002 -240.058702)
		(end 323.986398 -240.058702)
		(width 0.09525)
		(layer "In2.Cu")
		(net "M_C_CPU0_SA_DQS_DP<3>")
	)
	(segment
		(start 294.012366 -228.942138)
		(end 293.532306 -228.942138)
		(width 0.16002)
		(layer "In2.Cu")
		(net "M_C_CPU0_SA_DQS_DP<3>")
	)
	(segment
		(start 310.493918 -230.28783)
		(end 310.493918 -230.01097)
		(width 0.16002)
		(layer "In2.Cu")
		(net "M_C_CPU0_SA_DQS_DP<3>")
	)
	(segment
		(start 312.175906 -229.801928)
		(end 311.648602 -229.801674)
		(width 0.16002)
		(layer "In2.Cu")
		(net "M_C_CPU0_SA_DQS_DP<3>")
	)
	(segment
		(start 311.86755 -231.661462)
		(end 311.86755 -231.384602)
		(width 0.16002)
		(layer "In2.Cu")
		(net "M_C_CPU0_SA_DQS_DP<3>")
	)
	(segment
		(start 339.800946 -241.574066)
		(end 339.792564 -241.56924)
		(width 0.09525)
		(layer "In2.Cu")
		(net "M_C_CPU0_SA_DQS_DP<3>")
	)
	(segment
		(start 298.615608 -228.3714)
		(end 298.237656 -228.3714)
		(width 0.16002)
		(layer "In2.Cu")
		(net "M_C_CPU0_SA_DQS_DP<3>")
	)
	(segment
		(start 326.640952 -241.574066)
		(end 326.63257 -241.56924)
		(width 0.09525)
		(layer "In2.Cu")
		(net "M_C_CPU0_SA_DQS_DP<3>")
	)
	(arc
		(start 337.349592 -241.56924)
		(mid 337.161124 -241.619917)
		(end 336.972656 -241.56924)
		(width 0.09525)
		(layer "In2.Cu")
		(net "M_C_CPU0_SA_DQS_DP<3>")
	)
	(arc
		(start 341.109554 -241.56924)
		(mid 340.921086 -241.619917)
		(end 340.732618 -241.56924)
		(width 0.09525)
		(layer "In2.Cu")
		(net "M_C_CPU0_SA_DQS_DP<3>")
	)
	(arc
		(start 328.889614 -241.56924)
		(mid 328.701146 -241.619917)
		(end 328.512678 -241.56924)
		(width 0.09525)
		(layer "In2.Cu")
		(net "M_C_CPU0_SA_DQS_DP<3>")
	)
	(arc
		(start 332.649576 -241.56924)
		(mid 332.461108 -241.619917)
		(end 332.27264 -241.56924)
		(width 0.09525)
		(layer "In2.Cu")
		(net "M_C_CPU0_SA_DQS_DP<3>")
	)
	(arc
		(start 339.792564 -241.56924)
		(mid 339.511132 -241.493485)
		(end 339.2297 -241.56924)
		(width 0.09525)
		(layer "In2.Cu")
		(net "M_C_CPU0_SA_DQS_DP<3>")
	)
	(arc
		(start 329.821286 -241.574066)
		(mid 329.636254 -241.61998)
		(end 329.452478 -241.56924)
		(width 0.09525)
		(layer "In2.Cu")
		(net "M_C_CPU0_SA_DQS_DP<3>")
	)
	(arc
		(start 327.572624 -241.56924)
		(mid 327.291192 -241.493485)
		(end 327.00976 -241.56924)
		(width 0.09525)
		(layer "In2.Cu")
		(net "M_C_CPU0_SA_DQS_DP<3>")
	)
	(arc
		(start 328.512678 -241.56924)
		(mid 328.231246 -241.493485)
		(end 327.949814 -241.56924)
		(width 0.09525)
		(layer "In2.Cu")
		(net "M_C_CPU0_SA_DQS_DP<3>")
	)
	(arc
		(start 339.2297 -241.56924)
		(mid 339.045925 -241.620012)
		(end 338.860892 -241.574066)
		(width 0.09525)
		(layer "In2.Cu")
		(net "M_C_CPU0_SA_DQS_DP<3>")
	)
	(arc
		(start 331.332586 -241.56924)
		(mid 331.051154 -241.493485)
		(end 330.769722 -241.56924)
		(width 0.09525)
		(layer "In2.Cu")
		(net "M_C_CPU0_SA_DQS_DP<3>")
	)
	(arc
		(start 341.991696 -241.596418)
		(mid 341.829014 -241.61855)
		(end 341.672418 -241.56924)
		(width 0.09525)
		(layer "In2.Cu")
		(net "M_C_CPU0_SA_DQS_DP<3>")
	)
	(arc
		(start 335.092548 -241.56924)
		(mid 334.811116 -241.493485)
		(end 334.529684 -241.56924)
		(width 0.09525)
		(layer "In2.Cu")
		(net "M_C_CPU0_SA_DQS_DP<3>")
	)
	(arc
		(start 336.972656 -241.56924)
		(mid 336.691224 -241.493485)
		(end 336.409792 -241.56924)
		(width 0.09525)
		(layer "In2.Cu")
		(net "M_C_CPU0_SA_DQS_DP<3>")
	)
	(arc
		(start 334.152494 -241.56924)
		(mid 333.871062 -241.493485)
		(end 333.58963 -241.56924)
		(width 0.09525)
		(layer "In2.Cu")
		(net "M_C_CPU0_SA_DQS_DP<3>")
	)
	(arc
		(start 330.392532 -241.56924)
		(mid 330.1111 -241.493485)
		(end 329.829668 -241.56924)
		(width 0.09525)
		(layer "In2.Cu")
		(net "M_C_CPU0_SA_DQS_DP<3>")
	)
	(arc
		(start 337.912456 -241.56924)
		(mid 337.631024 -241.493485)
		(end 337.349592 -241.56924)
		(width 0.09525)
		(layer "In2.Cu")
		(net "M_C_CPU0_SA_DQS_DP<3>")
	)
	(arc
		(start 334.521302 -241.574066)
		(mid 334.33627 -241.61998)
		(end 334.152494 -241.56924)
		(width 0.09525)
		(layer "In2.Cu")
		(net "M_C_CPU0_SA_DQS_DP<3>")
	)
	(arc
		(start 335.469738 -241.56924)
		(mid 335.285963 -241.620012)
		(end 335.10093 -241.574066)
		(width 0.09525)
		(layer "In2.Cu")
		(net "M_C_CPU0_SA_DQS_DP<3>")
	)
	(arc
		(start 330.769722 -241.56924)
		(mid 330.585947 -241.620012)
		(end 330.400914 -241.574066)
		(width 0.09525)
		(layer "In2.Cu")
		(net "M_C_CPU0_SA_DQS_DP<3>")
	)
	(arc
		(start 333.581248 -241.574066)
		(mid 333.396216 -241.61998)
		(end 333.21244 -241.56924)
		(width 0.09525)
		(layer "In2.Cu")
		(net "M_C_CPU0_SA_DQS_DP<3>")
	)
	(arc
		(start 340.732618 -241.56924)
		(mid 340.451186 -241.493485)
		(end 340.169754 -241.56924)
		(width 0.09525)
		(layer "In2.Cu")
		(net "M_C_CPU0_SA_DQS_DP<3>")
	)
	(arc
		(start 333.21244 -241.56924)
		(mid 332.931008 -241.493485)
		(end 332.649576 -241.56924)
		(width 0.09525)
		(layer "In2.Cu")
		(net "M_C_CPU0_SA_DQS_DP<3>")
	)
	(arc
		(start 327.949814 -241.56924)
		(mid 327.766039 -241.620012)
		(end 327.581006 -241.574066)
		(width 0.09525)
		(layer "In2.Cu")
		(net "M_C_CPU0_SA_DQS_DP<3>")
	)
	(arc
		(start 327.00976 -241.56924)
		(mid 326.825985 -241.620012)
		(end 326.640952 -241.574066)
		(width 0.09525)
		(layer "In2.Cu")
		(net "M_C_CPU0_SA_DQS_DP<3>")
	)
	(arc
		(start 340.169754 -241.56924)
		(mid 339.985979 -241.620012)
		(end 339.800946 -241.574066)
		(width 0.09525)
		(layer "In2.Cu")
		(net "M_C_CPU0_SA_DQS_DP<3>")
	)
	(arc
		(start 329.452478 -241.56924)
		(mid 329.171046 -241.493485)
		(end 328.889614 -241.56924)
		(width 0.09525)
		(layer "In2.Cu")
		(net "M_C_CPU0_SA_DQS_DP<3>")
	)
	(arc
		(start 338.281264 -241.574066)
		(mid 338.096232 -241.61998)
		(end 337.912456 -241.56924)
		(width 0.09525)
		(layer "In2.Cu")
		(net "M_C_CPU0_SA_DQS_DP<3>")
	)
	(arc
		(start 332.27264 -241.56924)
		(mid 331.991208 -241.493485)
		(end 331.709776 -241.56924)
		(width 0.09525)
		(layer "In2.Cu")
		(net "M_C_CPU0_SA_DQS_DP<3>")
	)
	(arc
		(start 338.85251 -241.56924)
		(mid 338.571078 -241.493485)
		(end 338.289646 -241.56924)
		(width 0.09525)
		(layer "In2.Cu")
		(net "M_C_CPU0_SA_DQS_DP<3>")
	)
	(arc
		(start 331.709776 -241.56924)
		(mid 331.526001 -241.620012)
		(end 331.340968 -241.574066)
		(width 0.09525)
		(layer "In2.Cu")
		(net "M_C_CPU0_SA_DQS_DP<3>")
	)
	(arc
		(start 336.032602 -241.56924)
		(mid 335.75117 -241.493485)
		(end 335.469738 -241.56924)
		(width 0.09525)
		(layer "In2.Cu")
		(net "M_C_CPU0_SA_DQS_DP<3>")
	)
	(arc
		(start 336.409792 -241.56924)
		(mid 336.226017 -241.620012)
		(end 336.040984 -241.574066)
		(width 0.09525)
		(layer "In2.Cu")
		(net "M_C_CPU0_SA_DQS_DP<3>")
	)
	(arc
		(start 341.672418 -241.56924)
		(mid 341.390986 -241.493485)
		(end 341.109554 -241.56924)
		(width 0.09525)
		(layer "In2.Cu")
		(net "M_C_CPU0_SA_DQS_DP<3>")
	)
	(arc
		(start 326.63257 -241.56924)
		(mid 326.496863 -241.512755)
		(end 326.351138 -241.493548)
		(width 0.09525)
		(layer "In2.Cu")
		(net "M_C_CPU0_SA_DQS_DP<3>")
	)
	(segment
		(start 342.327992 -236.650022)
		(end 341.86114 -236.384084)
		(width 0.12954)
		(layer "F.Cu")
		(net "M_C_CPU0_SA_DQS_DP<2>")
	)
	(segment
		(start 306.429156 -218.744546)
		(end 306.078636 -219.095066)
		(width 0.16002)
		(layer "In2.Cu")
		(net "M_C_CPU0_SA_DQS_DP<2>")
	)
	(segment
		(start 312.15838 -221.300294)
		(end 312.438288 -221.020386)
		(width 0.16002)
		(layer "In2.Cu")
		(net "M_C_CPU0_SA_DQS_DP<2>")
	)
	(segment
		(start 319.021206 -229.81158)
		(end 318.381126 -229.81158)
		(width 0.16002)
		(layer "In2.Cu")
		(net "M_C_CPU0_SA_DQS_DP<2>")
	)
	(segment
		(start 326.875394 -236.03077)
		(end 326.255634 -236.03077)
		(width 0.09525)
		(layer "In2.Cu")
		(net "M_C_CPU0_SA_DQS_DP<2>")
	)
	(segment
		(start 322.224146 -233.01452)
		(end 321.76847 -232.558844)
		(width 0.16002)
		(layer "In2.Cu")
		(net "M_C_CPU0_SA_DQS_DP<2>")
	)
	(segment
		(start 293.397686 -219.708984)
		(end 292.553898 -219.708984)
		(width 0.16002)
		(layer "In2.Cu")
		(net "M_C_CPU0_SA_DQS_DP<2>")
	)
	(segment
		(start 312.064654 -220.119448)
		(end 311.53735 -220.119448)
		(width 0.16002)
		(layer "In2.Cu")
		(net "M_C_CPU0_SA_DQS_DP<2>")
	)
	(segment
		(start 310.689752 -218.744546)
		(end 309.83555 -218.744546)
		(width 0.16002)
		(layer "In2.Cu")
		(net "M_C_CPU0_SA_DQS_DP<2>")
	)
	(segment
		(start 321.12839 -232.558844)
		(end 320.850514 -232.280968)
		(width 0.16002)
		(layer "In2.Cu")
		(net "M_C_CPU0_SA_DQS_DP<2>")
	)
	(segment
		(start 327.949814 -236.709204)
		(end 327.941432 -236.71403)
		(width 0.09525)
		(layer "In2.Cu")
		(net "M_C_CPU0_SA_DQS_DP<2>")
	)
	(segment
		(start 325.387208 -234.82808)
		(end 324.999096 -234.439968)
		(width 0.09525)
		(layer "In2.Cu")
		(net "M_C_CPU0_SA_DQS_DP<2>")
	)
	(segment
		(start 310.784748 -219.926662)
		(end 311.064656 -219.646754)
		(width 0.16002)
		(layer "In2.Cu")
		(net "M_C_CPU0_SA_DQS_DP<2>")
	)
	(segment
		(start 338.860892 -236.71403)
		(end 338.85251 -236.709204)
		(width 0.09525)
		(layer "In2.Cu")
		(net "M_C_CPU0_SA_DQS_DP<2>")
	)
	(segment
		(start 318.381126 -229.81158)
		(end 318.256158 -229.686612)
		(width 0.16002)
		(layer "In2.Cu")
		(net "M_C_CPU0_SA_DQS_DP<2>")
	)
	(segment
		(start 304.17516 -219.603066)
		(end 301.729648 -219.603066)
		(width 0.16002)
		(layer "In2.Cu")
		(net "M_C_CPU0_SA_DQS_DP<2>")
	)
	(segment
		(start 320.850514 -232.280968)
		(end 320.850514 -231.640888)
		(width 0.16002)
		(layer "In2.Cu")
		(net "M_C_CPU0_SA_DQS_DP<2>")
	)
	(segment
		(start 312.438288 -221.020386)
		(end 312.438288 -220.493082)
		(width 0.16002)
		(layer "In2.Cu")
		(net "M_C_CPU0_SA_DQS_DP<2>")
	)
	(segment
		(start 336.040984 -236.71403)
		(end 336.032602 -236.709204)
		(width 0.09525)
		(layer "In2.Cu")
		(net "M_C_CPU0_SA_DQS_DP<2>")
	)
	(segment
		(start 310.980582 -220.399356)
		(end 310.784748 -220.203522)
		(width 0.16002)
		(layer "In2.Cu")
		(net "M_C_CPU0_SA_DQS_DP<2>")
	)
	(segment
		(start 319.476882 -230.267256)
		(end 319.021206 -229.81158)
		(width 0.16002)
		(layer "In2.Cu")
		(net "M_C_CPU0_SA_DQS_DP<2>")
	)
	(segment
		(start 297.384216 -219.874846)
		(end 296.93362 -219.874846)
		(width 0.16002)
		(layer "In2.Cu")
		(net "M_C_CPU0_SA_DQS_DP<2>")
	)
	(segment
		(start 326.255634 -236.03077)
		(end 325.387208 -235.162344)
		(width 0.09525)
		(layer "In2.Cu")
		(net "M_C_CPU0_SA_DQS_DP<2>")
	)
	(segment
		(start 311.53735 -220.119448)
		(end 311.257442 -220.399356)
		(width 0.16002)
		(layer "In2.Cu")
		(net "M_C_CPU0_SA_DQS_DP<2>")
	)
	(segment
		(start 296.93362 -219.874846)
		(end 296.61866 -219.559886)
		(width 0.16002)
		(layer "In2.Cu")
		(net "M_C_CPU0_SA_DQS_DP<2>")
	)
	(segment
		(start 298.237656 -219.021406)
		(end 297.384216 -219.874846)
		(width 0.16002)
		(layer "In2.Cu")
		(net "M_C_CPU0_SA_DQS_DP<2>")
	)
	(segment
		(start 341.86114 -236.384084)
		(end 342.015064 -236.649514)
		(width 0.09525)
		(layer "In2.Cu")
		(net "M_C_CPU0_SA_DQS_DP<2>")
	)
	(segment
		(start 334.529684 -236.709204)
		(end 334.521302 -236.71403)
		(width 0.09525)
		(layer "In2.Cu")
		(net "M_C_CPU0_SA_DQS_DP<2>")
	)
	(segment
		(start 311.064656 -219.11945)
		(end 310.689752 -218.744546)
		(width 0.16002)
		(layer "In2.Cu")
		(net "M_C_CPU0_SA_DQS_DP<2>")
	)
	(segment
		(start 311.257442 -220.399356)
		(end 310.980582 -220.399356)
		(width 0.16002)
		(layer "In2.Cu")
		(net "M_C_CPU0_SA_DQS_DP<2>")
	)
	(segment
		(start 319.754758 -231.185212)
		(end 319.476882 -230.907336)
		(width 0.16002)
		(layer "In2.Cu")
		(net "M_C_CPU0_SA_DQS_DP<2>")
	)
	(segment
		(start 329.829668 -236.709204)
		(end 329.821286 -236.71403)
		(width 0.09525)
		(layer "In2.Cu")
		(net "M_C_CPU0_SA_DQS_DP<2>")
	)
	(segment
		(start 318.256158 -229.686612)
		(end 318.256158 -227.674932)
		(width 0.16002)
		(layer "In2.Cu")
		(net "M_C_CPU0_SA_DQS_DP<2>")
	)
	(segment
		(start 294.591486 -219.708984)
		(end 294.111426 -219.708984)
		(width 0.16002)
		(layer "In2.Cu")
		(net "M_C_CPU0_SA_DQS_DP<2>")
	)
	(segment
		(start 306.078636 -219.095066)
		(end 305.601116 -219.095066)
		(width 0.16002)
		(layer "In2.Cu")
		(net "M_C_CPU0_SA_DQS_DP<2>")
	)
	(segment
		(start 318.256158 -227.674932)
		(end 312.15838 -221.577154)
		(width 0.16002)
		(layer "In2.Cu")
		(net "M_C_CPU0_SA_DQS_DP<2>")
	)
	(segment
		(start 331.340968 -236.71403)
		(end 331.332586 -236.709204)
		(width 0.09525)
		(layer "In2.Cu")
		(net "M_C_CPU0_SA_DQS_DP<2>")
	)
	(segment
		(start 300.836584 -218.710002)
		(end 298.95546 -218.710002)
		(width 0.16002)
		(layer "In2.Cu")
		(net "M_C_CPU0_SA_DQS_DP<2>")
	)
	(segment
		(start 312.15838 -221.577154)
		(end 312.15838 -221.300294)
		(width 0.16002)
		(layer "In2.Cu")
		(net "M_C_CPU0_SA_DQS_DP<2>")
	)
	(segment
		(start 309.266844 -219.772992)
		(end 308.990238 -219.772992)
		(width 0.16002)
		(layer "In2.Cu")
		(net "M_C_CPU0_SA_DQS_DP<2>")
	)
	(segment
		(start 327.4949 -236.650276)
		(end 326.875394 -236.03077)
		(width 0.09525)
		(layer "In2.Cu")
		(net "M_C_CPU0_SA_DQS_DP<2>")
	)
	(segment
		(start 338.289646 -236.709204)
		(end 338.281264 -236.71403)
		(width 0.09525)
		(layer "In2.Cu")
		(net "M_C_CPU0_SA_DQS_DP<2>")
	)
	(segment
		(start 339.800946 -236.71403)
		(end 339.792564 -236.709204)
		(width 0.09525)
		(layer "In2.Cu")
		(net "M_C_CPU0_SA_DQS_DP<2>")
	)
	(segment
		(start 322.950586 -234.38104)
		(end 322.224146 -233.6546)
		(width 0.16002)
		(layer "In2.Cu")
		(net "M_C_CPU0_SA_DQS_DP<2>")
	)
	(segment
		(start 301.729648 -219.603066)
		(end 300.836584 -218.710002)
		(width 0.16002)
		(layer "In2.Cu")
		(net "M_C_CPU0_SA_DQS_DP<2>")
	)
	(segment
		(start 333.58963 -236.709204)
		(end 333.581248 -236.71403)
		(width 0.09525)
		(layer "In2.Cu")
		(net "M_C_CPU0_SA_DQS_DP<2>")
	)
	(segment
		(start 323.978524 -234.439968)
		(end 323.919596 -234.38104)
		(width 0.09525)
		(layer "In2.Cu")
		(net "M_C_CPU0_SA_DQS_DP<2>")
	)
	(segment
		(start 296.61866 -219.559886)
		(end 294.740584 -219.559886)
		(width 0.16002)
		(layer "In2.Cu")
		(net "M_C_CPU0_SA_DQS_DP<2>")
	)
	(segment
		(start 311.064656 -219.646754)
		(end 311.064656 -219.11945)
		(width 0.16002)
		(layer "In2.Cu")
		(net "M_C_CPU0_SA_DQS_DP<2>")
	)
	(segment
		(start 308.794404 -219.117418)
		(end 308.421532 -218.744546)
		(width 0.16002)
		(layer "In2.Cu")
		(net "M_C_CPU0_SA_DQS_DP<2>")
	)
	(segment
		(start 304.46472 -219.892626)
		(end 304.17516 -219.603066)
		(width 0.16002)
		(layer "In2.Cu")
		(net "M_C_CPU0_SA_DQS_DP<2>")
	)
	(segment
		(start 294.111426 -219.708984)
		(end 293.994586 -219.592144)
		(width 0.16002)
		(layer "In2.Cu")
		(net "M_C_CPU0_SA_DQS_DP<2>")
	)
	(segment
		(start 298.95546 -218.710002)
		(end 298.644056 -219.021406)
		(width 0.16002)
		(layer "In2.Cu")
		(net "M_C_CPU0_SA_DQS_DP<2>")
	)
	(segment
		(start 342.015064 -236.649514)
		(end 341.991696 -236.736382)
		(width 0.09525)
		(layer "In2.Cu")
		(net "M_C_CPU0_SA_DQS_DP<2>")
	)
	(segment
		(start 304.803556 -219.892626)
		(end 304.46472 -219.892626)
		(width 0.16002)
		(layer "In2.Cu")
		(net "M_C_CPU0_SA_DQS_DP<2>")
	)
	(segment
		(start 305.601116 -219.095066)
		(end 304.803556 -219.892626)
		(width 0.16002)
		(layer "In2.Cu")
		(net "M_C_CPU0_SA_DQS_DP<2>")
	)
	(segment
		(start 293.994586 -219.592144)
		(end 293.514526 -219.592144)
		(width 0.16002)
		(layer "In2.Cu")
		(net "M_C_CPU0_SA_DQS_DP<2>")
	)
	(segment
		(start 309.83555 -218.744546)
		(end 309.462678 -219.117418)
		(width 0.16002)
		(layer "In2.Cu")
		(net "M_C_CPU0_SA_DQS_DP<2>")
	)
	(segment
		(start 319.476882 -230.907336)
		(end 319.476882 -230.267256)
		(width 0.16002)
		(layer "In2.Cu")
		(net "M_C_CPU0_SA_DQS_DP<2>")
	)
	(segment
		(start 335.10093 -236.71403)
		(end 335.092548 -236.709204)
		(width 0.09525)
		(layer "In2.Cu")
		(net "M_C_CPU0_SA_DQS_DP<2>")
	)
	(segment
		(start 293.514526 -219.592144)
		(end 293.397686 -219.708984)
		(width 0.16002)
		(layer "In2.Cu")
		(net "M_C_CPU0_SA_DQS_DP<2>")
	)
	(segment
		(start 298.644056 -219.021406)
		(end 298.237656 -219.021406)
		(width 0.16002)
		(layer "In2.Cu")
		(net "M_C_CPU0_SA_DQS_DP<2>")
	)
	(segment
		(start 320.850514 -231.640888)
		(end 320.394838 -231.185212)
		(width 0.16002)
		(layer "In2.Cu")
		(net "M_C_CPU0_SA_DQS_DP<2>")
	)
	(segment
		(start 309.462678 -219.577158)
		(end 309.266844 -219.772992)
		(width 0.16002)
		(layer "In2.Cu")
		(net "M_C_CPU0_SA_DQS_DP<2>")
	)
	(segment
		(start 320.394838 -231.185212)
		(end 319.754758 -231.185212)
		(width 0.16002)
		(layer "In2.Cu")
		(net "M_C_CPU0_SA_DQS_DP<2>")
	)
	(segment
		(start 312.438288 -220.493082)
		(end 312.064654 -220.119448)
		(width 0.16002)
		(layer "In2.Cu")
		(net "M_C_CPU0_SA_DQS_DP<2>")
	)
	(segment
		(start 308.421532 -218.744546)
		(end 306.429156 -218.744546)
		(width 0.16002)
		(layer "In2.Cu")
		(net "M_C_CPU0_SA_DQS_DP<2>")
	)
	(segment
		(start 323.919596 -234.38104)
		(end 323.895974 -234.38104)
		(width 0.09525)
		(layer "In2.Cu")
		(net "M_C_CPU0_SA_DQS_DP<2>")
	)
	(segment
		(start 310.784748 -220.203522)
		(end 310.784748 -219.926662)
		(width 0.16002)
		(layer "In2.Cu")
		(net "M_C_CPU0_SA_DQS_DP<2>")
	)
	(segment
		(start 309.462678 -219.117418)
		(end 309.462678 -219.577158)
		(width 0.16002)
		(layer "In2.Cu")
		(net "M_C_CPU0_SA_DQS_DP<2>")
	)
	(segment
		(start 330.400914 -236.71403)
		(end 330.392532 -236.709204)
		(width 0.09525)
		(layer "In2.Cu")
		(net "M_C_CPU0_SA_DQS_DP<2>")
	)
	(segment
		(start 322.224146 -233.6546)
		(end 322.224146 -233.01452)
		(width 0.16002)
		(layer "In2.Cu")
		(net "M_C_CPU0_SA_DQS_DP<2>")
	)
	(segment
		(start 308.794404 -219.577158)
		(end 308.794404 -219.117418)
		(width 0.16002)
		(layer "In2.Cu")
		(net "M_C_CPU0_SA_DQS_DP<2>")
	)
	(segment
		(start 321.76847 -232.558844)
		(end 321.12839 -232.558844)
		(width 0.16002)
		(layer "In2.Cu")
		(net "M_C_CPU0_SA_DQS_DP<2>")
	)
	(segment
		(start 292.553898 -219.708984)
		(end 292.280086 -219.435172)
		(width 0.16002)
		(layer "In2.Cu")
		(net "M_C_CPU0_SA_DQS_DP<2>")
	)
	(segment
		(start 294.740584 -219.559886)
		(end 294.591486 -219.708984)
		(width 0.16002)
		(layer "In2.Cu")
		(net "M_C_CPU0_SA_DQS_DP<2>")
	)
	(segment
		(start 308.990238 -219.772992)
		(end 308.794404 -219.577158)
		(width 0.16002)
		(layer "In2.Cu")
		(net "M_C_CPU0_SA_DQS_DP<2>")
	)
	(segment
		(start 323.895974 -234.38104)
		(end 322.950586 -234.38104)
		(width 0.16002)
		(layer "In2.Cu")
		(net "M_C_CPU0_SA_DQS_DP<2>")
	)
	(segment
		(start 325.387208 -235.162344)
		(end 325.387208 -234.82808)
		(width 0.09525)
		(layer "In2.Cu")
		(net "M_C_CPU0_SA_DQS_DP<2>")
	)
	(segment
		(start 324.999096 -234.439968)
		(end 323.978524 -234.439968)
		(width 0.09525)
		(layer "In2.Cu")
		(net "M_C_CPU0_SA_DQS_DP<2>")
	)
	(arc
		(start 333.21244 -236.709204)
		(mid 332.931008 -236.633449)
		(end 332.649576 -236.709204)
		(width 0.09525)
		(layer "In2.Cu")
		(net "M_C_CPU0_SA_DQS_DP<2>")
	)
	(arc
		(start 336.032602 -236.709204)
		(mid 335.75117 -236.633449)
		(end 335.469738 -236.709204)
		(width 0.09525)
		(layer "In2.Cu")
		(net "M_C_CPU0_SA_DQS_DP<2>")
	)
	(arc
		(start 330.392532 -236.709204)
		(mid 330.1111 -236.633449)
		(end 329.829668 -236.709204)
		(width 0.09525)
		(layer "In2.Cu")
		(net "M_C_CPU0_SA_DQS_DP<2>")
	)
	(arc
		(start 334.521302 -236.71403)
		(mid 334.33627 -236.759944)
		(end 334.152494 -236.709204)
		(width 0.09525)
		(layer "In2.Cu")
		(net "M_C_CPU0_SA_DQS_DP<2>")
	)
	(arc
		(start 328.512678 -236.709204)
		(mid 328.231246 -236.633449)
		(end 327.949814 -236.709204)
		(width 0.09525)
		(layer "In2.Cu")
		(net "M_C_CPU0_SA_DQS_DP<2>")
	)
	(arc
		(start 339.2297 -236.709204)
		(mid 339.045925 -236.759976)
		(end 338.860892 -236.71403)
		(width 0.09525)
		(layer "In2.Cu")
		(net "M_C_CPU0_SA_DQS_DP<2>")
	)
	(arc
		(start 335.092548 -236.709204)
		(mid 334.811116 -236.633449)
		(end 334.529684 -236.709204)
		(width 0.09525)
		(layer "In2.Cu")
		(net "M_C_CPU0_SA_DQS_DP<2>")
	)
	(arc
		(start 337.349592 -236.709204)
		(mid 337.161124 -236.759881)
		(end 336.972656 -236.709204)
		(width 0.09525)
		(layer "In2.Cu")
		(net "M_C_CPU0_SA_DQS_DP<2>")
	)
	(arc
		(start 341.672418 -236.709204)
		(mid 341.390986 -236.633449)
		(end 341.109554 -236.709204)
		(width 0.09525)
		(layer "In2.Cu")
		(net "M_C_CPU0_SA_DQS_DP<2>")
	)
	(arc
		(start 334.152494 -236.709204)
		(mid 333.871062 -236.633449)
		(end 333.58963 -236.709204)
		(width 0.09525)
		(layer "In2.Cu")
		(net "M_C_CPU0_SA_DQS_DP<2>")
	)
	(arc
		(start 329.452478 -236.709204)
		(mid 329.171046 -236.633449)
		(end 328.889614 -236.709204)
		(width 0.09525)
		(layer "In2.Cu")
		(net "M_C_CPU0_SA_DQS_DP<2>")
	)
	(arc
		(start 328.889614 -236.709204)
		(mid 328.701146 -236.759881)
		(end 328.512678 -236.709204)
		(width 0.09525)
		(layer "In2.Cu")
		(net "M_C_CPU0_SA_DQS_DP<2>")
	)
	(arc
		(start 327.572116 -236.709204)
		(mid 327.531592 -236.682249)
		(end 327.4949 -236.650276)
		(width 0.09525)
		(layer "In2.Cu")
		(net "M_C_CPU0_SA_DQS_DP<2>")
	)
	(arc
		(start 341.991696 -236.736382)
		(mid 341.829014 -236.758514)
		(end 341.672418 -236.709204)
		(width 0.09525)
		(layer "In2.Cu")
		(net "M_C_CPU0_SA_DQS_DP<2>")
	)
	(arc
		(start 338.85251 -236.709204)
		(mid 338.571078 -236.633449)
		(end 338.289646 -236.709204)
		(width 0.09525)
		(layer "In2.Cu")
		(net "M_C_CPU0_SA_DQS_DP<2>")
	)
	(arc
		(start 340.732618 -236.709204)
		(mid 340.451186 -236.633449)
		(end 340.169754 -236.709204)
		(width 0.09525)
		(layer "In2.Cu")
		(net "M_C_CPU0_SA_DQS_DP<2>")
	)
	(arc
		(start 332.27264 -236.709204)
		(mid 331.991208 -236.633449)
		(end 331.709776 -236.709204)
		(width 0.09525)
		(layer "In2.Cu")
		(net "M_C_CPU0_SA_DQS_DP<2>")
	)
	(arc
		(start 329.821286 -236.71403)
		(mid 329.636254 -236.759944)
		(end 329.452478 -236.709204)
		(width 0.09525)
		(layer "In2.Cu")
		(net "M_C_CPU0_SA_DQS_DP<2>")
	)
	(arc
		(start 341.109554 -236.709204)
		(mid 340.921086 -236.759881)
		(end 340.732618 -236.709204)
		(width 0.09525)
		(layer "In2.Cu")
		(net "M_C_CPU0_SA_DQS_DP<2>")
	)
	(arc
		(start 331.332586 -236.709204)
		(mid 331.051154 -236.633449)
		(end 330.769722 -236.709204)
		(width 0.09525)
		(layer "In2.Cu")
		(net "M_C_CPU0_SA_DQS_DP<2>")
	)
	(arc
		(start 335.469738 -236.709204)
		(mid 335.285963 -236.759976)
		(end 335.10093 -236.71403)
		(width 0.09525)
		(layer "In2.Cu")
		(net "M_C_CPU0_SA_DQS_DP<2>")
	)
	(arc
		(start 340.169754 -236.709204)
		(mid 339.985979 -236.759976)
		(end 339.800946 -236.71403)
		(width 0.09525)
		(layer "In2.Cu")
		(net "M_C_CPU0_SA_DQS_DP<2>")
	)
	(arc
		(start 337.912456 -236.709204)
		(mid 337.631024 -236.633449)
		(end 337.349592 -236.709204)
		(width 0.09525)
		(layer "In2.Cu")
		(net "M_C_CPU0_SA_DQS_DP<2>")
	)
	(arc
		(start 330.769722 -236.709204)
		(mid 330.585947 -236.759976)
		(end 330.400914 -236.71403)
		(width 0.09525)
		(layer "In2.Cu")
		(net "M_C_CPU0_SA_DQS_DP<2>")
	)
	(arc
		(start 333.581248 -236.71403)
		(mid 333.396216 -236.759944)
		(end 333.21244 -236.709204)
		(width 0.09525)
		(layer "In2.Cu")
		(net "M_C_CPU0_SA_DQS_DP<2>")
	)
	(arc
		(start 331.709776 -236.709204)
		(mid 331.526001 -236.759976)
		(end 331.340968 -236.71403)
		(width 0.09525)
		(layer "In2.Cu")
		(net "M_C_CPU0_SA_DQS_DP<2>")
	)
	(arc
		(start 327.941432 -236.71403)
		(mid 327.756146 -236.760066)
		(end 327.572116 -236.709204)
		(width 0.09525)
		(layer "In2.Cu")
		(net "M_C_CPU0_SA_DQS_DP<2>")
	)
	(arc
		(start 339.792564 -236.709204)
		(mid 339.511132 -236.633449)
		(end 339.2297 -236.709204)
		(width 0.09525)
		(layer "In2.Cu")
		(net "M_C_CPU0_SA_DQS_DP<2>")
	)
	(arc
		(start 332.649576 -236.709204)
		(mid 332.461108 -236.759881)
		(end 332.27264 -236.709204)
		(width 0.09525)
		(layer "In2.Cu")
		(net "M_C_CPU0_SA_DQS_DP<2>")
	)
	(arc
		(start 336.972656 -236.709204)
		(mid 336.691224 -236.633449)
		(end 336.409792 -236.709204)
		(width 0.09525)
		(layer "In2.Cu")
		(net "M_C_CPU0_SA_DQS_DP<2>")
	)
	(arc
		(start 338.281264 -236.71403)
		(mid 338.096232 -236.759944)
		(end 337.912456 -236.709204)
		(width 0.09525)
		(layer "In2.Cu")
		(net "M_C_CPU0_SA_DQS_DP<2>")
	)
	(arc
		(start 336.409792 -236.709204)
		(mid 336.226017 -236.759976)
		(end 336.040984 -236.71403)
		(width 0.09525)
		(layer "In2.Cu")
		(net "M_C_CPU0_SA_DQS_DP<2>")
	)
	(segment
		(start 342.327992 -231.789986)
		(end 341.86114 -231.524048)
		(width 0.12954)
		(layer "F.Cu")
		(net "M_C_CPU0_SA_DQS_DP<1>")
	)
	(segment
		(start 342.015064 -231.789478)
		(end 341.991696 -231.876346)
		(width 0.09525)
		(layer "In2.Cu")
		(net "M_C_CPU0_SA_DQS_DP<1>")
	)
	(segment
		(start 294.738044 -210.209892)
		(end 294.588946 -210.35899)
		(width 0.16002)
		(layer "In2.Cu")
		(net "M_C_CPU0_SA_DQS_DP<1>")
	)
	(segment
		(start 330.400914 -231.853994)
		(end 330.392532 -231.849168)
		(width 0.09525)
		(layer "In2.Cu")
		(net "M_C_CPU0_SA_DQS_DP<1>")
	)
	(segment
		(start 325.692516 -226.989386)
		(end 325.66102 -226.971098)
		(width 0.09525)
		(layer "In2.Cu")
		(net "M_C_CPU0_SA_DQS_DP<1>")
	)
	(segment
		(start 324.517258 -226.107752)
		(end 324.458076 -226.04857)
		(width 0.09525)
		(layer "In2.Cu")
		(net "M_C_CPU0_SA_DQS_DP<1>")
	)
	(segment
		(start 293.511986 -210.24215)
		(end 293.395146 -210.35899)
		(width 0.16002)
		(layer "In2.Cu")
		(net "M_C_CPU0_SA_DQS_DP<1>")
	)
	(segment
		(start 310.013858 -209.394552)
		(end 306.429156 -209.394552)
		(width 0.16002)
		(layer "In2.Cu")
		(net "M_C_CPU0_SA_DQS_DP<1>")
	)
	(segment
		(start 320.930016 -220.472254)
		(end 320.243708 -221.158562)
		(width 0.16002)
		(layer "In2.Cu")
		(net "M_C_CPU0_SA_DQS_DP<1>")
	)
	(segment
		(start 319.771014 -220.962728)
		(end 319.771014 -220.685868)
		(width 0.16002)
		(layer "In2.Cu")
		(net "M_C_CPU0_SA_DQS_DP<1>")
	)
	(segment
		(start 301.74184 -210.253072)
		(end 300.848776 -209.360008)
		(width 0.16002)
		(layer "In2.Cu")
		(net "M_C_CPU0_SA_DQS_DP<1>")
	)
	(segment
		(start 306.429156 -209.394552)
		(end 306.078636 -209.745072)
		(width 0.16002)
		(layer "In2.Cu")
		(net "M_C_CPU0_SA_DQS_DP<1>")
	)
	(segment
		(start 324.047358 -225.239072)
		(end 321.144646 -222.33636)
		(width 0.16002)
		(layer "In2.Cu")
		(net "M_C_CPU0_SA_DQS_DP<1>")
	)
	(segment
		(start 304.803556 -210.542632)
		(end 304.46472 -210.542632)
		(width 0.16002)
		(layer "In2.Cu")
		(net "M_C_CPU0_SA_DQS_DP<1>")
	)
	(segment
		(start 325.50354 -226.664266)
		(end 325.50354 -226.592892)
		(width 0.09525)
		(layer "In2.Cu")
		(net "M_C_CPU0_SA_DQS_DP<1>")
	)
	(segment
		(start 318.870076 -219.78493)
		(end 318.593216 -219.78493)
		(width 0.16002)
		(layer "In2.Cu")
		(net "M_C_CPU0_SA_DQS_DP<1>")
	)
	(segment
		(start 339.800946 -231.853994)
		(end 339.792564 -231.849168)
		(width 0.09525)
		(layer "In2.Cu")
		(net "M_C_CPU0_SA_DQS_DP<1>")
	)
	(segment
		(start 341.86114 -231.524048)
		(end 342.015064 -231.789478)
		(width 0.09525)
		(layer "In2.Cu")
		(net "M_C_CPU0_SA_DQS_DP<1>")
	)
	(segment
		(start 334.529684 -231.849168)
		(end 334.521302 -231.853994)
		(width 0.09525)
		(layer "In2.Cu")
		(net "M_C_CPU0_SA_DQS_DP<1>")
	)
	(segment
		(start 297.384216 -210.524852)
		(end 296.93362 -210.524852)
		(width 0.16002)
		(layer "In2.Cu")
		(net "M_C_CPU0_SA_DQS_DP<1>")
	)
	(segment
		(start 320.203068 -218.979242)
		(end 319.675764 -218.979242)
		(width 0.16002)
		(layer "In2.Cu")
		(net "M_C_CPU0_SA_DQS_DP<1>")
	)
	(segment
		(start 320.576702 -219.352876)
		(end 320.203068 -218.979242)
		(width 0.16002)
		(layer "In2.Cu")
		(net "M_C_CPU0_SA_DQS_DP<1>")
	)
	(segment
		(start 328.042524 -231.039416)
		(end 328.011028 -231.021128)
		(width 0.09525)
		(layer "In2.Cu")
		(net "M_C_CPU0_SA_DQS_DP<1>")
	)
	(segment
		(start 293.992046 -210.24215)
		(end 293.511986 -210.24215)
		(width 0.16002)
		(layer "In2.Cu")
		(net "M_C_CPU0_SA_DQS_DP<1>")
	)
	(segment
		(start 326.1995 -227.820474)
		(end 326.162924 -227.799138)
		(width 0.09525)
		(layer "In2.Cu")
		(net "M_C_CPU0_SA_DQS_DP<1>")
	)
	(segment
		(start 324.434454 -226.04857)
		(end 324.20814 -226.04857)
		(width 0.16002)
		(layer "In2.Cu")
		(net "M_C_CPU0_SA_DQS_DP<1>")
	)
	(segment
		(start 328.08291 -231.063038)
		(end 328.042524 -231.039416)
		(width 0.09525)
		(layer "In2.Cu")
		(net "M_C_CPU0_SA_DQS_DP<1>")
	)
	(segment
		(start 327.572624 -230.229156)
		(end 327.542398 -230.21163)
		(width 0.09525)
		(layer "In2.Cu")
		(net "M_C_CPU0_SA_DQS_DP<1>")
	)
	(segment
		(start 327.102978 -229.41915)
		(end 327.06818 -229.399084)
		(width 0.09525)
		(layer "In2.Cu")
		(net "M_C_CPU0_SA_DQS_DP<1>")
	)
	(segment
		(start 324.20814 -226.04857)
		(end 324.047358 -225.887788)
		(width 0.16002)
		(layer "In2.Cu")
		(net "M_C_CPU0_SA_DQS_DP<1>")
	)
	(segment
		(start 321.830954 -221.373192)
		(end 321.830954 -220.845888)
		(width 0.16002)
		(layer "In2.Cu")
		(net "M_C_CPU0_SA_DQS_DP<1>")
	)
	(segment
		(start 296.61866 -210.209892)
		(end 294.738044 -210.209892)
		(width 0.16002)
		(layer "In2.Cu")
		(net "M_C_CPU0_SA_DQS_DP<1>")
	)
	(segment
		(start 336.040984 -231.853994)
		(end 336.032602 -231.849168)
		(width 0.09525)
		(layer "In2.Cu")
		(net "M_C_CPU0_SA_DQS_DP<1>")
	)
	(segment
		(start 298.95546 -209.360008)
		(end 298.644056 -209.671412)
		(width 0.16002)
		(layer "In2.Cu")
		(net "M_C_CPU0_SA_DQS_DP<1>")
	)
	(segment
		(start 321.830954 -220.845888)
		(end 321.45732 -220.472254)
		(width 0.16002)
		(layer "In2.Cu")
		(net "M_C_CPU0_SA_DQS_DP<1>")
	)
	(segment
		(start 304.17516 -210.253072)
		(end 301.74184 -210.253072)
		(width 0.16002)
		(layer "In2.Cu")
		(net "M_C_CPU0_SA_DQS_DP<1>")
	)
	(segment
		(start 324.047358 -225.887788)
		(end 324.047358 -225.239072)
		(width 0.16002)
		(layer "In2.Cu")
		(net "M_C_CPU0_SA_DQS_DP<1>")
	)
	(segment
		(start 320.243708 -221.158562)
		(end 319.966848 -221.158562)
		(width 0.16002)
		(layer "In2.Cu")
		(net "M_C_CPU0_SA_DQS_DP<1>")
	)
	(segment
		(start 321.144646 -222.0595)
		(end 321.830954 -221.373192)
		(width 0.16002)
		(layer "In2.Cu")
		(net "M_C_CPU0_SA_DQS_DP<1>")
	)
	(segment
		(start 298.237656 -209.671412)
		(end 297.384216 -210.524852)
		(width 0.16002)
		(layer "In2.Cu")
		(net "M_C_CPU0_SA_DQS_DP<1>")
	)
	(segment
		(start 335.10093 -231.853994)
		(end 335.092548 -231.849168)
		(width 0.09525)
		(layer "In2.Cu")
		(net "M_C_CPU0_SA_DQS_DP<1>")
	)
	(segment
		(start 325.730616 -227.011484)
		(end 325.692516 -226.989386)
		(width 0.09525)
		(layer "In2.Cu")
		(net "M_C_CPU0_SA_DQS_DP<1>")
	)
	(segment
		(start 333.58963 -231.849168)
		(end 333.581248 -231.853994)
		(width 0.09525)
		(layer "In2.Cu")
		(net "M_C_CPU0_SA_DQS_DP<1>")
	)
	(segment
		(start 318.593216 -219.78493)
		(end 318.436498 -219.628212)
		(width 0.16002)
		(layer "In2.Cu")
		(net "M_C_CPU0_SA_DQS_DP<1>")
	)
	(segment
		(start 304.46472 -210.542632)
		(end 304.17516 -210.253072)
		(width 0.16002)
		(layer "In2.Cu")
		(net "M_C_CPU0_SA_DQS_DP<1>")
	)
	(segment
		(start 294.108886 -210.35899)
		(end 293.992046 -210.24215)
		(width 0.16002)
		(layer "In2.Cu")
		(net "M_C_CPU0_SA_DQS_DP<1>")
	)
	(segment
		(start 328.512678 -231.849168)
		(end 328.480166 -231.830372)
		(width 0.09525)
		(layer "In2.Cu")
		(net "M_C_CPU0_SA_DQS_DP<1>")
	)
	(segment
		(start 319.966848 -221.158562)
		(end 319.771014 -220.962728)
		(width 0.16002)
		(layer "In2.Cu")
		(net "M_C_CPU0_SA_DQS_DP<1>")
	)
	(segment
		(start 326.162924 -227.799138)
		(end 326.162416 -227.799392)
		(width 0.09525)
		(layer "In2.Cu")
		(net "M_C_CPU0_SA_DQS_DP<1>")
	)
	(segment
		(start 293.395146 -210.35899)
		(end 292.553898 -210.35899)
		(width 0.16002)
		(layer "In2.Cu")
		(net "M_C_CPU0_SA_DQS_DP<1>")
	)
	(segment
		(start 319.675764 -218.979242)
		(end 318.870076 -219.78493)
		(width 0.16002)
		(layer "In2.Cu")
		(net "M_C_CPU0_SA_DQS_DP<1>")
	)
	(segment
		(start 338.289646 -231.849168)
		(end 338.281264 -231.853994)
		(width 0.09525)
		(layer "In2.Cu")
		(net "M_C_CPU0_SA_DQS_DP<1>")
	)
	(segment
		(start 327.13803 -229.439724)
		(end 327.102978 -229.41915)
		(width 0.09525)
		(layer "In2.Cu")
		(net "M_C_CPU0_SA_DQS_DP<1>")
	)
	(segment
		(start 294.588946 -210.35899)
		(end 294.108886 -210.35899)
		(width 0.16002)
		(layer "In2.Cu")
		(net "M_C_CPU0_SA_DQS_DP<1>")
	)
	(segment
		(start 306.078636 -209.745072)
		(end 305.601116 -209.745072)
		(width 0.16002)
		(layer "In2.Cu")
		(net "M_C_CPU0_SA_DQS_DP<1>")
	)
	(segment
		(start 300.848776 -209.360008)
		(end 298.95546 -209.360008)
		(width 0.16002)
		(layer "In2.Cu")
		(net "M_C_CPU0_SA_DQS_DP<1>")
	)
	(segment
		(start 319.771014 -220.685868)
		(end 320.576702 -219.88018)
		(width 0.16002)
		(layer "In2.Cu")
		(net "M_C_CPU0_SA_DQS_DP<1>")
	)
	(segment
		(start 298.644056 -209.671412)
		(end 298.237656 -209.671412)
		(width 0.16002)
		(layer "In2.Cu")
		(net "M_C_CPU0_SA_DQS_DP<1>")
	)
	(segment
		(start 321.144646 -222.33636)
		(end 321.144646 -222.0595)
		(width 0.16002)
		(layer "In2.Cu")
		(net "M_C_CPU0_SA_DQS_DP<1>")
	)
	(segment
		(start 338.860892 -231.853994)
		(end 338.85251 -231.849168)
		(width 0.09525)
		(layer "In2.Cu")
		(net "M_C_CPU0_SA_DQS_DP<1>")
	)
	(segment
		(start 321.45732 -220.472254)
		(end 320.930016 -220.472254)
		(width 0.16002)
		(layer "In2.Cu")
		(net "M_C_CPU0_SA_DQS_DP<1>")
	)
	(segment
		(start 331.340968 -231.853994)
		(end 331.332586 -231.849168)
		(width 0.09525)
		(layer "In2.Cu")
		(net "M_C_CPU0_SA_DQS_DP<1>")
	)
	(segment
		(start 325.392796 -226.325176)
		(end 325.340472 -226.273106)
		(width 0.09525)
		(layer "In2.Cu")
		(net "M_C_CPU0_SA_DQS_DP<1>")
	)
	(segment
		(start 318.436498 -217.817192)
		(end 310.013858 -209.394552)
		(width 0.16002)
		(layer "In2.Cu")
		(net "M_C_CPU0_SA_DQS_DP<1>")
	)
	(segment
		(start 320.576702 -219.88018)
		(end 320.576702 -219.352876)
		(width 0.16002)
		(layer "In2.Cu")
		(net "M_C_CPU0_SA_DQS_DP<1>")
	)
	(segment
		(start 292.553898 -210.35899)
		(end 292.280086 -210.085178)
		(width 0.16002)
		(layer "In2.Cu")
		(net "M_C_CPU0_SA_DQS_DP<1>")
	)
	(segment
		(start 326.632824 -228.609398)
		(end 326.60336 -228.59238)
		(width 0.09525)
		(layer "In2.Cu")
		(net "M_C_CPU0_SA_DQS_DP<1>")
	)
	(segment
		(start 305.601116 -209.745072)
		(end 304.803556 -210.542632)
		(width 0.16002)
		(layer "In2.Cu")
		(net "M_C_CPU0_SA_DQS_DP<1>")
	)
	(segment
		(start 324.940676 -226.107752)
		(end 324.517258 -226.107752)
		(width 0.09525)
		(layer "In2.Cu")
		(net "M_C_CPU0_SA_DQS_DP<1>")
	)
	(segment
		(start 296.93362 -210.524852)
		(end 296.61866 -210.209892)
		(width 0.16002)
		(layer "In2.Cu")
		(net "M_C_CPU0_SA_DQS_DP<1>")
	)
	(segment
		(start 329.829668 -231.849168)
		(end 329.821286 -231.853994)
		(width 0.09525)
		(layer "In2.Cu")
		(net "M_C_CPU0_SA_DQS_DP<1>")
	)
	(segment
		(start 327.6092 -230.250492)
		(end 327.572624 -230.229156)
		(width 0.09525)
		(layer "In2.Cu")
		(net "M_C_CPU0_SA_DQS_DP<1>")
	)
	(segment
		(start 326.162416 -227.799392)
		(end 326.13092 -227.781104)
		(width 0.09525)
		(layer "In2.Cu")
		(net "M_C_CPU0_SA_DQS_DP<1>")
	)
	(segment
		(start 326.6694 -228.630734)
		(end 326.632824 -228.609398)
		(width 0.09525)
		(layer "In2.Cu")
		(net "M_C_CPU0_SA_DQS_DP<1>")
	)
	(segment
		(start 318.436498 -219.628212)
		(end 318.436498 -217.817192)
		(width 0.16002)
		(layer "In2.Cu")
		(net "M_C_CPU0_SA_DQS_DP<1>")
	)
	(segment
		(start 324.458076 -226.04857)
		(end 324.434454 -226.04857)
		(width 0.09525)
		(layer "In2.Cu")
		(net "M_C_CPU0_SA_DQS_DP<1>")
	)
	(arc
		(start 341.991696 -231.876346)
		(mid 341.829014 -231.898478)
		(end 341.672418 -231.849168)
		(width 0.09525)
		(layer "In2.Cu")
		(net "M_C_CPU0_SA_DQS_DP<1>")
	)
	(arc
		(start 333.581248 -231.853994)
		(mid 333.396216 -231.899908)
		(end 333.21244 -231.849168)
		(width 0.09525)
		(layer "In2.Cu")
		(net "M_C_CPU0_SA_DQS_DP<1>")
	)
	(arc
		(start 331.332586 -231.849168)
		(mid 331.051154 -231.773413)
		(end 330.769722 -231.849168)
		(width 0.09525)
		(layer "In2.Cu")
		(net "M_C_CPU0_SA_DQS_DP<1>")
	)
	(arc
		(start 337.912456 -231.849168)
		(mid 337.631024 -231.773413)
		(end 337.349592 -231.849168)
		(width 0.09525)
		(layer "In2.Cu")
		(net "M_C_CPU0_SA_DQS_DP<1>")
	)
	(arc
		(start 340.169754 -231.849168)
		(mid 339.985979 -231.89994)
		(end 339.800946 -231.853994)
		(width 0.09525)
		(layer "In2.Cu")
		(net "M_C_CPU0_SA_DQS_DP<1>")
	)
	(arc
		(start 327.853548 -230.714296)
		(mid 327.788798 -230.452127)
		(end 327.6092 -230.250492)
		(width 0.09525)
		(layer "In2.Cu")
		(net "M_C_CPU0_SA_DQS_DP<1>")
	)
	(arc
		(start 325.50354 -226.592892)
		(mid 325.474814 -226.448008)
		(end 325.392796 -226.325176)
		(width 0.09525)
		(layer "In2.Cu")
		(net "M_C_CPU0_SA_DQS_DP<1>")
	)
	(arc
		(start 325.66102 -226.971098)
		(mid 325.545222 -226.836704)
		(end 325.50354 -226.664266)
		(width 0.09525)
		(layer "In2.Cu")
		(net "M_C_CPU0_SA_DQS_DP<1>")
	)
	(arc
		(start 326.13092 -227.781104)
		(mid 326.015122 -227.64671)
		(end 325.97344 -227.474272)
		(width 0.09525)
		(layer "In2.Cu")
		(net "M_C_CPU0_SA_DQS_DP<1>")
	)
	(arc
		(start 326.443848 -228.284024)
		(mid 326.379019 -228.022022)
		(end 326.1995 -227.820474)
		(width 0.09525)
		(layer "In2.Cu")
		(net "M_C_CPU0_SA_DQS_DP<1>")
	)
	(arc
		(start 335.469738 -231.849168)
		(mid 335.285963 -231.89994)
		(end 335.10093 -231.853994)
		(width 0.09525)
		(layer "In2.Cu")
		(net "M_C_CPU0_SA_DQS_DP<1>")
	)
	(arc
		(start 332.27264 -231.849168)
		(mid 331.991208 -231.773413)
		(end 331.709776 -231.849168)
		(width 0.09525)
		(layer "In2.Cu")
		(net "M_C_CPU0_SA_DQS_DP<1>")
	)
	(arc
		(start 336.409792 -231.849168)
		(mid 336.226017 -231.89994)
		(end 336.040984 -231.853994)
		(width 0.09525)
		(layer "In2.Cu")
		(net "M_C_CPU0_SA_DQS_DP<1>")
	)
	(arc
		(start 336.972656 -231.849168)
		(mid 336.691224 -231.773413)
		(end 336.409792 -231.849168)
		(width 0.09525)
		(layer "In2.Cu")
		(net "M_C_CPU0_SA_DQS_DP<1>")
	)
	(arc
		(start 330.392532 -231.849168)
		(mid 330.1111 -231.773413)
		(end 329.829668 -231.849168)
		(width 0.09525)
		(layer "In2.Cu")
		(net "M_C_CPU0_SA_DQS_DP<1>")
	)
	(arc
		(start 325.340472 -226.273106)
		(mid 325.157028 -226.150656)
		(end 324.940676 -226.107752)
		(width 0.09525)
		(layer "In2.Cu")
		(net "M_C_CPU0_SA_DQS_DP<1>")
	)
	(arc
		(start 328.480166 -231.830372)
		(mid 328.364892 -231.696094)
		(end 328.323448 -231.524048)
		(width 0.09525)
		(layer "In2.Cu")
		(net "M_C_CPU0_SA_DQS_DP<1>")
	)
	(arc
		(start 333.21244 -231.849168)
		(mid 332.931008 -231.773413)
		(end 332.649576 -231.849168)
		(width 0.09525)
		(layer "In2.Cu")
		(net "M_C_CPU0_SA_DQS_DP<1>")
	)
	(arc
		(start 341.672418 -231.849168)
		(mid 341.390986 -231.773413)
		(end 341.109554 -231.849168)
		(width 0.09525)
		(layer "In2.Cu")
		(net "M_C_CPU0_SA_DQS_DP<1>")
	)
	(arc
		(start 337.349592 -231.849168)
		(mid 337.161124 -231.899845)
		(end 336.972656 -231.849168)
		(width 0.09525)
		(layer "In2.Cu")
		(net "M_C_CPU0_SA_DQS_DP<1>")
	)
	(arc
		(start 328.011028 -231.021128)
		(mid 327.89523 -230.886734)
		(end 327.853548 -230.714296)
		(width 0.09525)
		(layer "In2.Cu")
		(net "M_C_CPU0_SA_DQS_DP<1>")
	)
	(arc
		(start 329.821286 -231.853994)
		(mid 329.636254 -231.899908)
		(end 329.452478 -231.849168)
		(width 0.09525)
		(layer "In2.Cu")
		(net "M_C_CPU0_SA_DQS_DP<1>")
	)
	(arc
		(start 334.521302 -231.853994)
		(mid 334.33627 -231.899908)
		(end 334.152494 -231.849168)
		(width 0.09525)
		(layer "In2.Cu")
		(net "M_C_CPU0_SA_DQS_DP<1>")
	)
	(arc
		(start 325.97344 -227.474272)
		(mid 325.909043 -227.212966)
		(end 325.730616 -227.011484)
		(width 0.09525)
		(layer "In2.Cu")
		(net "M_C_CPU0_SA_DQS_DP<1>")
	)
	(arc
		(start 329.452478 -231.849168)
		(mid 329.171046 -231.773413)
		(end 328.889614 -231.849168)
		(width 0.09525)
		(layer "In2.Cu")
		(net "M_C_CPU0_SA_DQS_DP<1>")
	)
	(arc
		(start 341.109554 -231.849168)
		(mid 340.921086 -231.899845)
		(end 340.732618 -231.849168)
		(width 0.09525)
		(layer "In2.Cu")
		(net "M_C_CPU0_SA_DQS_DP<1>")
	)
	(arc
		(start 338.281264 -231.853994)
		(mid 338.096232 -231.899908)
		(end 337.912456 -231.849168)
		(width 0.09525)
		(layer "In2.Cu")
		(net "M_C_CPU0_SA_DQS_DP<1>")
	)
	(arc
		(start 340.732618 -231.849168)
		(mid 340.451186 -231.773413)
		(end 340.169754 -231.849168)
		(width 0.09525)
		(layer "In2.Cu")
		(net "M_C_CPU0_SA_DQS_DP<1>")
	)
	(arc
		(start 334.152494 -231.849168)
		(mid 333.871062 -231.773413)
		(end 333.58963 -231.849168)
		(width 0.09525)
		(layer "In2.Cu")
		(net "M_C_CPU0_SA_DQS_DP<1>")
	)
	(arc
		(start 327.542398 -230.21163)
		(mid 327.425697 -230.077101)
		(end 327.383648 -229.904036)
		(width 0.09525)
		(layer "In2.Cu")
		(net "M_C_CPU0_SA_DQS_DP<1>")
	)
	(arc
		(start 326.913494 -229.09403)
		(mid 326.848694 -228.832211)
		(end 326.6694 -228.630734)
		(width 0.09525)
		(layer "In2.Cu")
		(net "M_C_CPU0_SA_DQS_DP<1>")
	)
	(arc
		(start 339.2297 -231.849168)
		(mid 339.045925 -231.89994)
		(end 338.860892 -231.853994)
		(width 0.09525)
		(layer "In2.Cu")
		(net "M_C_CPU0_SA_DQS_DP<1>")
	)
	(arc
		(start 335.092548 -231.849168)
		(mid 334.811116 -231.773413)
		(end 334.529684 -231.849168)
		(width 0.09525)
		(layer "In2.Cu")
		(net "M_C_CPU0_SA_DQS_DP<1>")
	)
	(arc
		(start 328.323448 -231.524048)
		(mid 328.259702 -231.264048)
		(end 328.08291 -231.063038)
		(width 0.09525)
		(layer "In2.Cu")
		(net "M_C_CPU0_SA_DQS_DP<1>")
	)
	(arc
		(start 332.649576 -231.849168)
		(mid 332.461108 -231.899845)
		(end 332.27264 -231.849168)
		(width 0.09525)
		(layer "In2.Cu")
		(net "M_C_CPU0_SA_DQS_DP<1>")
	)
	(arc
		(start 330.769722 -231.849168)
		(mid 330.585947 -231.89994)
		(end 330.400914 -231.853994)
		(width 0.09525)
		(layer "In2.Cu")
		(net "M_C_CPU0_SA_DQS_DP<1>")
	)
	(arc
		(start 328.889614 -231.849168)
		(mid 328.701146 -231.899845)
		(end 328.512678 -231.849168)
		(width 0.09525)
		(layer "In2.Cu")
		(net "M_C_CPU0_SA_DQS_DP<1>")
	)
	(arc
		(start 338.85251 -231.849168)
		(mid 338.571078 -231.773413)
		(end 338.289646 -231.849168)
		(width 0.09525)
		(layer "In2.Cu")
		(net "M_C_CPU0_SA_DQS_DP<1>")
	)
	(arc
		(start 336.032602 -231.849168)
		(mid 335.75117 -231.773413)
		(end 335.469738 -231.849168)
		(width 0.09525)
		(layer "In2.Cu")
		(net "M_C_CPU0_SA_DQS_DP<1>")
	)
	(arc
		(start 327.06818 -229.399084)
		(mid 326.954395 -229.26504)
		(end 326.913494 -229.09403)
		(width 0.09525)
		(layer "In2.Cu")
		(net "M_C_CPU0_SA_DQS_DP<1>")
	)
	(arc
		(start 326.60336 -228.59238)
		(mid 326.486056 -228.457619)
		(end 326.443848 -228.284024)
		(width 0.09525)
		(layer "In2.Cu")
		(net "M_C_CPU0_SA_DQS_DP<1>")
	)
	(arc
		(start 327.383648 -229.904036)
		(mid 327.318455 -229.641407)
		(end 327.13803 -229.439724)
		(width 0.09525)
		(layer "In2.Cu")
		(net "M_C_CPU0_SA_DQS_DP<1>")
	)
	(arc
		(start 339.792564 -231.849168)
		(mid 339.511132 -231.773413)
		(end 339.2297 -231.849168)
		(width 0.09525)
		(layer "In2.Cu")
		(net "M_C_CPU0_SA_DQS_DP<1>")
	)
	(arc
		(start 331.709776 -231.849168)
		(mid 331.526001 -231.89994)
		(end 331.340968 -231.853994)
		(width 0.09525)
		(layer "In2.Cu")
		(net "M_C_CPU0_SA_DQS_DP<1>")
	)
	(segment
		(start 342.327992 -226.930204)
		(end 341.86114 -226.664266)
		(width 0.12954)
		(layer "F.Cu")
		(net "M_C_CPU0_SA_DQS_DP<0>")
	)
	(segment
		(start 338.289646 -226.989386)
		(end 338.281264 -226.994212)
		(width 0.09525)
		(layer "In2.Cu")
		(net "M_C_CPU0_SA_DQS_DP<0>")
	)
	(segment
		(start 322.051934 -211.546186)
		(end 322.05168 -211.018882)
		(width 0.16002)
		(layer "In2.Cu")
		(net "M_C_CPU0_SA_DQS_DP<0>")
	)
	(segment
		(start 334.529684 -226.989386)
		(end 334.521302 -226.994212)
		(width 0.09525)
		(layer "In2.Cu")
		(net "M_C_CPU0_SA_DQS_DP<0>")
	)
	(segment
		(start 329.020678 -222.961454)
		(end 328.982578 -222.939356)
		(width 0.09525)
		(layer "In2.Cu")
		(net "M_C_CPU0_SA_DQS_DP<0>")
	)
	(segment
		(start 321.767708 -212.49894)
		(end 321.571874 -212.303106)
		(width 0.16002)
		(layer "In2.Cu")
		(net "M_C_CPU0_SA_DQS_DP<0>")
	)
	(segment
		(start 309.958486 -200.044558)
		(end 306.429156 -200.044558)
		(width 0.16002)
		(layer "In2.Cu")
		(net "M_C_CPU0_SA_DQS_DP<0>")
	)
	(segment
		(start 342.015064 -226.929696)
		(end 341.991696 -227.016564)
		(width 0.09525)
		(layer "In2.Cu")
		(net "M_C_CPU0_SA_DQS_DP<0>")
	)
	(segment
		(start 330.392532 -225.369374)
		(end 330.36002 -225.350578)
		(width 0.09525)
		(layer "In2.Cu")
		(net "M_C_CPU0_SA_DQS_DP<0>")
	)
	(segment
		(start 296.93362 -201.174858)
		(end 296.342816 -200.584054)
		(width 0.16002)
		(layer "In2.Cu")
		(net "M_C_CPU0_SA_DQS_DP<0>")
	)
	(segment
		(start 298.95546 -200.010014)
		(end 298.644056 -200.321418)
		(width 0.16002)
		(layer "In2.Cu")
		(net "M_C_CPU0_SA_DQS_DP<0>")
	)
	(segment
		(start 298.237656 -200.321418)
		(end 297.384216 -201.174858)
		(width 0.16002)
		(layer "In2.Cu")
		(net "M_C_CPU0_SA_DQS_DP<0>")
	)
	(segment
		(start 310.27878 -202.226672)
		(end 310.00192 -202.226672)
		(width 0.16002)
		(layer "In2.Cu")
		(net "M_C_CPU0_SA_DQS_DP<0>")
	)
	(segment
		(start 328.982578 -222.939356)
		(end 328.952352 -222.92183)
		(width 0.09525)
		(layer "In2.Cu")
		(net "M_C_CPU0_SA_DQS_DP<0>")
	)
	(segment
		(start 329.922632 -224.559368)
		(end 329.89012 -224.540572)
		(width 0.09525)
		(layer "In2.Cu")
		(net "M_C_CPU0_SA_DQS_DP<0>")
	)
	(segment
		(start 321.150996 -210.645248)
		(end 320.96837 -210.827874)
		(width 0.16002)
		(layer "In2.Cu")
		(net "M_C_CPU0_SA_DQS_DP<0>")
	)
	(segment
		(start 328.513948 -222.129858)
		(end 328.513186 -222.12935)
		(width 0.09525)
		(layer "In2.Cu")
		(net "M_C_CPU0_SA_DQS_DP<0>")
	)
	(segment
		(start 303.856136 -200.584054)
		(end 301.646336 -200.584054)
		(width 0.16002)
		(layer "In2.Cu")
		(net "M_C_CPU0_SA_DQS_DP<0>")
	)
	(segment
		(start 329.957684 -224.579942)
		(end 329.922632 -224.559368)
		(width 0.09525)
		(layer "In2.Cu")
		(net "M_C_CPU0_SA_DQS_DP<0>")
	)
	(segment
		(start 323.051424 -212.018626)
		(end 322.524628 -212.01888)
		(width 0.16002)
		(layer "In2.Cu")
		(net "M_C_CPU0_SA_DQS_DP<0>")
	)
	(segment
		(start 310.472582 -201.085958)
		(end 310.472582 -200.558654)
		(width 0.16002)
		(layer "In2.Cu")
		(net "M_C_CPU0_SA_DQS_DP<0>")
	)
	(segment
		(start 328.382122 -219.113354)
		(end 322.945506 -213.676738)
		(width 0.16002)
		(layer "In2.Cu")
		(net "M_C_CPU0_SA_DQS_DP<0>")
	)
	(segment
		(start 306.078636 -200.395078)
		(end 305.601116 -200.395078)
		(width 0.16002)
		(layer "In2.Cu")
		(net "M_C_CPU0_SA_DQS_DP<0>")
	)
	(segment
		(start 329.452478 -223.749362)
		(end 329.420982 -223.731074)
		(width 0.09525)
		(layer "In2.Cu")
		(net "M_C_CPU0_SA_DQS_DP<0>")
	)
	(segment
		(start 336.040984 -226.994212)
		(end 336.032602 -226.989386)
		(width 0.09525)
		(layer "In2.Cu")
		(net "M_C_CPU0_SA_DQS_DP<0>")
	)
	(segment
		(start 310.946038 -201.559414)
		(end 310.27878 -202.226672)
		(width 0.16002)
		(layer "In2.Cu")
		(net "M_C_CPU0_SA_DQS_DP<0>")
	)
	(segment
		(start 296.342816 -200.584054)
		(end 293.866824 -200.584054)
		(width 0.16002)
		(layer "In2.Cu")
		(net "M_C_CPU0_SA_DQS_DP<0>")
	)
	(segment
		(start 320.741802 -210.827874)
		(end 311.473342 -201.559414)
		(width 0.16002)
		(layer "In2.Cu")
		(net "M_C_CPU0_SA_DQS_DP<0>")
	)
	(segment
		(start 292.553898 -201.008996)
		(end 292.280086 -200.735184)
		(width 0.16002)
		(layer "In2.Cu")
		(net "M_C_CPU0_SA_DQS_DP<0>")
	)
	(segment
		(start 322.524628 -212.01888)
		(end 322.044568 -212.49894)
		(width 0.16002)
		(layer "In2.Cu")
		(net "M_C_CPU0_SA_DQS_DP<0>")
	)
	(segment
		(start 321.571874 -212.303106)
		(end 321.571874 -212.026246)
		(width 0.16002)
		(layer "In2.Cu")
		(net "M_C_CPU0_SA_DQS_DP<0>")
	)
	(segment
		(start 309.805324 -202.030076)
		(end 309.805324 -201.753216)
		(width 0.16002)
		(layer "In2.Cu")
		(net "M_C_CPU0_SA_DQS_DP<0>")
	)
	(segment
		(start 329.490578 -223.77146)
		(end 329.452478 -223.749362)
		(width 0.09525)
		(layer "In2.Cu")
		(net "M_C_CPU0_SA_DQS_DP<0>")
	)
	(segment
		(start 293.866824 -200.584054)
		(end 293.441882 -201.008996)
		(width 0.16002)
		(layer "In2.Cu")
		(net "M_C_CPU0_SA_DQS_DP<0>")
	)
	(segment
		(start 293.441882 -201.008996)
		(end 292.553898 -201.008996)
		(width 0.16002)
		(layer "In2.Cu")
		(net "M_C_CPU0_SA_DQS_DP<0>")
	)
	(segment
		(start 301.646336 -200.584054)
		(end 301.072296 -200.010014)
		(width 0.16002)
		(layer "In2.Cu")
		(net "M_C_CPU0_SA_DQS_DP<0>")
	)
	(segment
		(start 323.425566 -212.919818)
		(end 323.425312 -212.392514)
		(width 0.16002)
		(layer "In2.Cu")
		(net "M_C_CPU0_SA_DQS_DP<0>")
	)
	(segment
		(start 330.430632 -225.391472)
		(end 330.392532 -225.369374)
		(width 0.09525)
		(layer "In2.Cu")
		(net "M_C_CPU0_SA_DQS_DP<0>")
	)
	(segment
		(start 341.86114 -226.664266)
		(end 342.015064 -226.929696)
		(width 0.09525)
		(layer "In2.Cu")
		(net "M_C_CPU0_SA_DQS_DP<0>")
	)
	(segment
		(start 322.044568 -212.49894)
		(end 321.767708 -212.49894)
		(width 0.16002)
		(layer "In2.Cu")
		(net "M_C_CPU0_SA_DQS_DP<0>")
	)
	(segment
		(start 328.32294 -221.257114)
		(end 328.382122 -221.197932)
		(width 0.09525)
		(layer "In2.Cu")
		(net "M_C_CPU0_SA_DQS_DP<0>")
	)
	(segment
		(start 330.900532 -226.201478)
		(end 330.862432 -226.17938)
		(width 0.09525)
		(layer "In2.Cu")
		(net "M_C_CPU0_SA_DQS_DP<0>")
	)
	(segment
		(start 328.54519 -222.147892)
		(end 328.513948 -222.129858)
		(width 0.09525)
		(layer "In2.Cu")
		(net "M_C_CPU0_SA_DQS_DP<0>")
	)
	(segment
		(start 311.473342 -201.559414)
		(end 310.946038 -201.559414)
		(width 0.16002)
		(layer "In2.Cu")
		(net "M_C_CPU0_SA_DQS_DP<0>")
	)
	(segment
		(start 297.384216 -201.174858)
		(end 296.93362 -201.174858)
		(width 0.16002)
		(layer "In2.Cu")
		(net "M_C_CPU0_SA_DQS_DP<0>")
	)
	(segment
		(start 304.803556 -201.192638)
		(end 304.46472 -201.192638)
		(width 0.16002)
		(layer "In2.Cu")
		(net "M_C_CPU0_SA_DQS_DP<0>")
	)
	(segment
		(start 322.945506 -213.676738)
		(end 322.945506 -213.399878)
		(width 0.16002)
		(layer "In2.Cu")
		(net "M_C_CPU0_SA_DQS_DP<0>")
	)
	(segment
		(start 310.00192 -202.226672)
		(end 309.805324 -202.030076)
		(width 0.16002)
		(layer "In2.Cu")
		(net "M_C_CPU0_SA_DQS_DP<0>")
	)
	(segment
		(start 301.072296 -200.010014)
		(end 298.95546 -200.010014)
		(width 0.16002)
		(layer "In2.Cu")
		(net "M_C_CPU0_SA_DQS_DP<0>")
	)
	(segment
		(start 330.862432 -226.17938)
		(end 330.830936 -226.161092)
		(width 0.09525)
		(layer "In2.Cu")
		(net "M_C_CPU0_SA_DQS_DP<0>")
	)
	(segment
		(start 331.340968 -226.994212)
		(end 331.332586 -226.989386)
		(width 0.09525)
		(layer "In2.Cu")
		(net "M_C_CPU0_SA_DQS_DP<0>")
	)
	(segment
		(start 339.800946 -226.994212)
		(end 339.792564 -226.989386)
		(width 0.09525)
		(layer "In2.Cu")
		(net "M_C_CPU0_SA_DQS_DP<0>")
	)
	(segment
		(start 321.678046 -210.645248)
		(end 321.150996 -210.645248)
		(width 0.16002)
		(layer "In2.Cu")
		(net "M_C_CPU0_SA_DQS_DP<0>")
	)
	(segment
		(start 298.644056 -200.321418)
		(end 298.237656 -200.321418)
		(width 0.16002)
		(layer "In2.Cu")
		(net "M_C_CPU0_SA_DQS_DP<0>")
	)
	(segment
		(start 305.601116 -200.395078)
		(end 304.803556 -201.192638)
		(width 0.16002)
		(layer "In2.Cu")
		(net "M_C_CPU0_SA_DQS_DP<0>")
	)
	(segment
		(start 304.46472 -201.192638)
		(end 303.856136 -200.584054)
		(width 0.16002)
		(layer "In2.Cu")
		(net "M_C_CPU0_SA_DQS_DP<0>")
	)
	(segment
		(start 335.10093 -226.994212)
		(end 335.092548 -226.989386)
		(width 0.09525)
		(layer "In2.Cu")
		(net "M_C_CPU0_SA_DQS_DP<0>")
	)
	(segment
		(start 338.860892 -226.994212)
		(end 338.85251 -226.989386)
		(width 0.09525)
		(layer "In2.Cu")
		(net "M_C_CPU0_SA_DQS_DP<0>")
	)
	(segment
		(start 323.425312 -212.392514)
		(end 323.051424 -212.018626)
		(width 0.16002)
		(layer "In2.Cu")
		(net "M_C_CPU0_SA_DQS_DP<0>")
	)
	(segment
		(start 320.96837 -210.827874)
		(end 320.741802 -210.827874)
		(width 0.16002)
		(layer "In2.Cu")
		(net "M_C_CPU0_SA_DQS_DP<0>")
	)
	(segment
		(start 306.429156 -200.044558)
		(end 306.078636 -200.395078)
		(width 0.16002)
		(layer "In2.Cu")
		(net "M_C_CPU0_SA_DQS_DP<0>")
	)
	(segment
		(start 322.05168 -211.018882)
		(end 321.678046 -210.645248)
		(width 0.16002)
		(layer "In2.Cu")
		(net "M_C_CPU0_SA_DQS_DP<0>")
	)
	(segment
		(start 322.945506 -213.399878)
		(end 323.425566 -212.919818)
		(width 0.16002)
		(layer "In2.Cu")
		(net "M_C_CPU0_SA_DQS_DP<0>")
	)
	(segment
		(start 309.805324 -201.753216)
		(end 310.472582 -201.085958)
		(width 0.16002)
		(layer "In2.Cu")
		(net "M_C_CPU0_SA_DQS_DP<0>")
	)
	(segment
		(start 333.58963 -226.989386)
		(end 333.581248 -226.994212)
		(width 0.09525)
		(layer "In2.Cu")
		(net "M_C_CPU0_SA_DQS_DP<0>")
	)
	(segment
		(start 328.382122 -221.17431)
		(end 328.382122 -219.113354)
		(width 0.16002)
		(layer "In2.Cu")
		(net "M_C_CPU0_SA_DQS_DP<0>")
	)
	(segment
		(start 328.32294 -221.803976)
		(end 328.32294 -221.257114)
		(width 0.09525)
		(layer "In2.Cu")
		(net "M_C_CPU0_SA_DQS_DP<0>")
	)
	(segment
		(start 328.513186 -222.12935)
		(end 328.418444 -222.034354)
		(width 0.09525)
		(layer "In2.Cu")
		(net "M_C_CPU0_SA_DQS_DP<0>")
	)
	(segment
		(start 331.332586 -226.989386)
		(end 331.300074 -226.97059)
		(width 0.09525)
		(layer "In2.Cu")
		(net "M_C_CPU0_SA_DQS_DP<0>")
	)
	(segment
		(start 310.472582 -200.558654)
		(end 309.958486 -200.044558)
		(width 0.16002)
		(layer "In2.Cu")
		(net "M_C_CPU0_SA_DQS_DP<0>")
	)
	(segment
		(start 328.382122 -221.197932)
		(end 328.382122 -221.17431)
		(width 0.09525)
		(layer "In2.Cu")
		(net "M_C_CPU0_SA_DQS_DP<0>")
	)
	(segment
		(start 321.571874 -212.026246)
		(end 322.051934 -211.546186)
		(width 0.16002)
		(layer "In2.Cu")
		(net "M_C_CPU0_SA_DQS_DP<0>")
	)
	(arc
		(start 340.732618 -226.989386)
		(mid 340.451186 -226.913631)
		(end 340.169754 -226.989386)
		(width 0.09525)
		(layer "In2.Cu")
		(net "M_C_CPU0_SA_DQS_DP<0>")
	)
	(arc
		(start 333.581248 -226.994212)
		(mid 333.396216 -227.040126)
		(end 333.21244 -226.989386)
		(width 0.09525)
		(layer "In2.Cu")
		(net "M_C_CPU0_SA_DQS_DP<0>")
	)
	(arc
		(start 328.952352 -222.92183)
		(mid 328.835651 -222.787301)
		(end 328.793602 -222.614236)
		(width 0.09525)
		(layer "In2.Cu")
		(net "M_C_CPU0_SA_DQS_DP<0>")
	)
	(arc
		(start 341.109554 -226.989386)
		(mid 340.921086 -227.040063)
		(end 340.732618 -226.989386)
		(width 0.09525)
		(layer "In2.Cu")
		(net "M_C_CPU0_SA_DQS_DP<0>")
	)
	(arc
		(start 339.792564 -226.989386)
		(mid 339.511132 -226.913631)
		(end 339.2297 -226.989386)
		(width 0.09525)
		(layer "In2.Cu")
		(net "M_C_CPU0_SA_DQS_DP<0>")
	)
	(arc
		(start 337.912456 -226.989386)
		(mid 337.631024 -226.913631)
		(end 337.349592 -226.989386)
		(width 0.09525)
		(layer "In2.Cu")
		(net "M_C_CPU0_SA_DQS_DP<0>")
	)
	(arc
		(start 331.300074 -226.97059)
		(mid 331.1848 -226.836312)
		(end 331.143356 -226.664266)
		(width 0.09525)
		(layer "In2.Cu")
		(net "M_C_CPU0_SA_DQS_DP<0>")
	)
	(arc
		(start 339.2297 -226.989386)
		(mid 339.045925 -227.040158)
		(end 338.860892 -226.994212)
		(width 0.09525)
		(layer "In2.Cu")
		(net "M_C_CPU0_SA_DQS_DP<0>")
	)
	(arc
		(start 338.85251 -226.989386)
		(mid 338.571078 -226.913631)
		(end 338.289646 -226.989386)
		(width 0.09525)
		(layer "In2.Cu")
		(net "M_C_CPU0_SA_DQS_DP<0>")
	)
	(arc
		(start 341.672418 -226.989386)
		(mid 341.390986 -226.913631)
		(end 341.109554 -226.989386)
		(width 0.09525)
		(layer "In2.Cu")
		(net "M_C_CPU0_SA_DQS_DP<0>")
	)
	(arc
		(start 331.709776 -226.989386)
		(mid 331.526001 -227.040158)
		(end 331.340968 -226.994212)
		(width 0.09525)
		(layer "In2.Cu")
		(net "M_C_CPU0_SA_DQS_DP<0>")
	)
	(arc
		(start 330.203302 -225.044254)
		(mid 330.138109 -224.781625)
		(end 329.957684 -224.579942)
		(width 0.09525)
		(layer "In2.Cu")
		(net "M_C_CPU0_SA_DQS_DP<0>")
	)
	(arc
		(start 332.649576 -226.989386)
		(mid 332.461108 -227.040063)
		(end 332.27264 -226.989386)
		(width 0.09525)
		(layer "In2.Cu")
		(net "M_C_CPU0_SA_DQS_DP<0>")
	)
	(arc
		(start 335.469738 -226.989386)
		(mid 335.285963 -227.040158)
		(end 335.10093 -226.994212)
		(width 0.09525)
		(layer "In2.Cu")
		(net "M_C_CPU0_SA_DQS_DP<0>")
	)
	(arc
		(start 337.349592 -226.989386)
		(mid 337.161124 -227.040063)
		(end 336.972656 -226.989386)
		(width 0.09525)
		(layer "In2.Cu")
		(net "M_C_CPU0_SA_DQS_DP<0>")
	)
	(arc
		(start 334.152494 -226.989386)
		(mid 333.871062 -226.913631)
		(end 333.58963 -226.989386)
		(width 0.09525)
		(layer "In2.Cu")
		(net "M_C_CPU0_SA_DQS_DP<0>")
	)
	(arc
		(start 330.830936 -226.161092)
		(mid 330.715138 -226.026698)
		(end 330.673456 -225.85426)
		(width 0.09525)
		(layer "In2.Cu")
		(net "M_C_CPU0_SA_DQS_DP<0>")
	)
	(arc
		(start 329.89012 -224.540572)
		(mid 329.774846 -224.406294)
		(end 329.733402 -224.234248)
		(width 0.09525)
		(layer "In2.Cu")
		(net "M_C_CPU0_SA_DQS_DP<0>")
	)
	(arc
		(start 336.032602 -226.989386)
		(mid 335.75117 -226.913631)
		(end 335.469738 -226.989386)
		(width 0.09525)
		(layer "In2.Cu")
		(net "M_C_CPU0_SA_DQS_DP<0>")
	)
	(arc
		(start 338.281264 -226.994212)
		(mid 338.096232 -227.040126)
		(end 337.912456 -226.989386)
		(width 0.09525)
		(layer "In2.Cu")
		(net "M_C_CPU0_SA_DQS_DP<0>")
	)
	(arc
		(start 328.793602 -222.614236)
		(mid 328.727619 -222.350056)
		(end 328.54519 -222.147892)
		(width 0.09525)
		(layer "In2.Cu")
		(net "M_C_CPU0_SA_DQS_DP<0>")
	)
	(arc
		(start 336.409792 -226.989386)
		(mid 336.226017 -227.040158)
		(end 336.040984 -226.994212)
		(width 0.09525)
		(layer "In2.Cu")
		(net "M_C_CPU0_SA_DQS_DP<0>")
	)
	(arc
		(start 332.27264 -226.989386)
		(mid 331.991208 -226.913631)
		(end 331.709776 -226.989386)
		(width 0.09525)
		(layer "In2.Cu")
		(net "M_C_CPU0_SA_DQS_DP<0>")
	)
	(arc
		(start 341.991696 -227.016564)
		(mid 341.829014 -227.038696)
		(end 341.672418 -226.989386)
		(width 0.09525)
		(layer "In2.Cu")
		(net "M_C_CPU0_SA_DQS_DP<0>")
	)
	(arc
		(start 335.092548 -226.989386)
		(mid 334.811116 -226.913631)
		(end 334.529684 -226.989386)
		(width 0.09525)
		(layer "In2.Cu")
		(net "M_C_CPU0_SA_DQS_DP<0>")
	)
	(arc
		(start 330.36002 -225.350578)
		(mid 330.244746 -225.2163)
		(end 330.203302 -225.044254)
		(width 0.09525)
		(layer "In2.Cu")
		(net "M_C_CPU0_SA_DQS_DP<0>")
	)
	(arc
		(start 334.521302 -226.994212)
		(mid 334.33627 -227.040126)
		(end 334.152494 -226.989386)
		(width 0.09525)
		(layer "In2.Cu")
		(net "M_C_CPU0_SA_DQS_DP<0>")
	)
	(arc
		(start 329.263502 -223.424242)
		(mid 329.199105 -223.162936)
		(end 329.020678 -222.961454)
		(width 0.09525)
		(layer "In2.Cu")
		(net "M_C_CPU0_SA_DQS_DP<0>")
	)
	(arc
		(start 336.972656 -226.989386)
		(mid 336.691224 -226.913631)
		(end 336.409792 -226.989386)
		(width 0.09525)
		(layer "In2.Cu")
		(net "M_C_CPU0_SA_DQS_DP<0>")
	)
	(arc
		(start 331.143356 -226.664266)
		(mid 331.078959 -226.40296)
		(end 330.900532 -226.201478)
		(width 0.09525)
		(layer "In2.Cu")
		(net "M_C_CPU0_SA_DQS_DP<0>")
	)
	(arc
		(start 340.169754 -226.989386)
		(mid 339.985979 -227.040158)
		(end 339.800946 -226.994212)
		(width 0.09525)
		(layer "In2.Cu")
		(net "M_C_CPU0_SA_DQS_DP<0>")
	)
	(arc
		(start 329.420982 -223.731074)
		(mid 329.305184 -223.59668)
		(end 329.263502 -223.424242)
		(width 0.09525)
		(layer "In2.Cu")
		(net "M_C_CPU0_SA_DQS_DP<0>")
	)
	(arc
		(start 330.673456 -225.85426)
		(mid 330.609059 -225.592954)
		(end 330.430632 -225.391472)
		(width 0.09525)
		(layer "In2.Cu")
		(net "M_C_CPU0_SA_DQS_DP<0>")
	)
	(arc
		(start 329.733402 -224.234248)
		(mid 329.669005 -223.972942)
		(end 329.490578 -223.77146)
		(width 0.09525)
		(layer "In2.Cu")
		(net "M_C_CPU0_SA_DQS_DP<0>")
	)
	(arc
		(start 333.21244 -226.989386)
		(mid 332.931008 -226.913631)
		(end 332.649576 -226.989386)
		(width 0.09525)
		(layer "In2.Cu")
		(net "M_C_CPU0_SA_DQS_DP<0>")
	)
	(arc
		(start 328.418444 -222.034354)
		(mid 328.347867 -221.928629)
		(end 328.32294 -221.803976)
		(width 0.09525)
		(layer "In2.Cu")
		(net "M_C_CPU0_SA_DQS_DP<0>")
	)
	(segment
		(start 343.737946 -247.1801)
		(end 343.271094 -246.914162)
		(width 0.12954)
		(layer "F.Cu")
		(net "M_C_CPU0_SA_DQS_DN<9>")
	)
	(segment
		(start 291.779452 -239.667288)
		(end 291.172138 -239.059974)
		(width 0.16002)
		(layer "In2.Cu")
		(net "M_C_CPU0_SA_DQS_DN<9>")
	)
	(segment
		(start 306.318666 -239.108742)
		(end 305.676808 -239.108742)
		(width 0.16002)
		(layer "In2.Cu")
		(net "M_C_CPU0_SA_DQS_DN<9>")
	)
	(segment
		(start 288.454084 -239.25911)
		(end 288.180018 -238.985044)
		(width 0.16002)
		(layer "In2.Cu")
		(net "M_C_CPU0_SA_DQS_DN<9>")
	)
	(segment
		(start 324.12178 -247.262904)
		(end 324.090792 -247.231916)
		(width 0.09525)
		(layer "In2.Cu")
		(net "M_C_CPU0_SA_DQS_DN<9>")
	)
	(segment
		(start 315.316616 -246.643652)
		(end 314.868306 -246.195342)
		(width 0.16002)
		(layer "In2.Cu")
		(net "M_C_CPU0_SA_DQS_DN<9>")
	)
	(segment
		(start 306.577238 -239.367314)
		(end 306.318666 -239.108742)
		(width 0.16002)
		(layer "In2.Cu")
		(net "M_C_CPU0_SA_DQS_DN<9>")
	)
	(segment
		(start 304.041556 -240.230914)
		(end 302.26254 -240.230914)
		(width 0.16002)
		(layer "In2.Cu")
		(net "M_C_CPU0_SA_DQS_DN<9>")
	)
	(segment
		(start 343.425018 -247.179592)
		(end 343.401904 -247.266206)
		(width 0.09525)
		(layer "In2.Cu")
		(net "M_C_CPU0_SA_DQS_DN<9>")
	)
	(segment
		(start 302.26254 -240.230914)
		(end 301.43958 -239.407954)
		(width 0.16002)
		(layer "In2.Cu")
		(net "M_C_CPU0_SA_DQS_DN<9>")
	)
	(segment
		(start 326.164194 -247.239028)
		(end 326.138286 -247.224042)
		(width 0.09525)
		(layer "In2.Cu")
		(net "M_C_CPU0_SA_DQS_DN<9>")
	)
	(segment
		(start 328.419714 -247.239282)
		(end 328.411332 -247.244108)
		(width 0.09525)
		(layer "In2.Cu")
		(net "M_C_CPU0_SA_DQS_DN<9>")
	)
	(segment
		(start 294.114474 -239.667288)
		(end 291.779452 -239.667288)
		(width 0.16002)
		(layer "In2.Cu")
		(net "M_C_CPU0_SA_DQS_DN<9>")
	)
	(segment
		(start 331.239622 -247.239282)
		(end 331.23124 -247.244108)
		(width 0.09525)
		(layer "In2.Cu")
		(net "M_C_CPU0_SA_DQS_DN<9>")
	)
	(segment
		(start 326.197468 -247.258078)
		(end 326.164194 -247.239028)
		(width 0.09525)
		(layer "In2.Cu")
		(net "M_C_CPU0_SA_DQS_DN<9>")
	)
	(segment
		(start 322.706492 -246.643652)
		(end 315.316616 -246.643652)
		(width 0.16002)
		(layer "In2.Cu")
		(net "M_C_CPU0_SA_DQS_DN<9>")
	)
	(segment
		(start 324.06717 -247.231916)
		(end 323.294756 -247.231916)
		(width 0.16002)
		(layer "In2.Cu")
		(net "M_C_CPU0_SA_DQS_DN<9>")
	)
	(segment
		(start 333.690976 -247.244108)
		(end 333.682594 -247.239282)
		(width 0.09525)
		(layer "In2.Cu")
		(net "M_C_CPU0_SA_DQS_DN<9>")
	)
	(segment
		(start 291.172138 -239.059974)
		(end 290.04641 -239.059974)
		(width 0.16002)
		(layer "In2.Cu")
		(net "M_C_CPU0_SA_DQS_DN<9>")
	)
	(segment
		(start 305.676808 -239.108742)
		(end 304.874676 -239.910874)
		(width 0.16002)
		(layer "In2.Cu")
		(net "M_C_CPU0_SA_DQS_DN<9>")
	)
	(segment
		(start 296.478198 -240.258092)
		(end 294.705278 -240.258092)
		(width 0.16002)
		(layer "In2.Cu")
		(net "M_C_CPU0_SA_DQS_DN<9>")
	)
	(segment
		(start 335.939638 -247.239282)
		(end 335.931256 -247.244108)
		(width 0.09525)
		(layer "In2.Cu")
		(net "M_C_CPU0_SA_DQS_DN<9>")
	)
	(segment
		(start 314.363608 -245.690644)
		(end 308.040278 -239.367314)
		(width 0.16002)
		(layer "In2.Cu")
		(net "M_C_CPU0_SA_DQS_DN<9>")
	)
	(segment
		(start 327.5076 -247.224042)
		(end 327.481692 -247.239028)
		(width 0.09525)
		(layer "In2.Cu")
		(net "M_C_CPU0_SA_DQS_DN<9>")
	)
	(segment
		(start 289.847274 -239.25911)
		(end 288.454084 -239.25911)
		(width 0.16002)
		(layer "In2.Cu")
		(net "M_C_CPU0_SA_DQS_DN<9>")
	)
	(segment
		(start 308.040278 -239.367314)
		(end 306.577238 -239.367314)
		(width 0.16002)
		(layer "In2.Cu")
		(net "M_C_CPU0_SA_DQS_DN<9>")
	)
	(segment
		(start 297.292776 -239.933734)
		(end 296.802556 -239.933734)
		(width 0.16002)
		(layer "In2.Cu")
		(net "M_C_CPU0_SA_DQS_DN<9>")
	)
	(segment
		(start 290.04641 -239.059974)
		(end 289.847274 -239.25911)
		(width 0.16002)
		(layer "In2.Cu")
		(net "M_C_CPU0_SA_DQS_DN<9>")
	)
	(segment
		(start 328.99096 -247.244108)
		(end 328.982578 -247.239282)
		(width 0.09525)
		(layer "In2.Cu")
		(net "M_C_CPU0_SA_DQS_DN<9>")
	)
	(segment
		(start 339.6996 -247.239282)
		(end 339.691218 -247.244108)
		(width 0.09525)
		(layer "In2.Cu")
		(net "M_C_CPU0_SA_DQS_DN<9>")
	)
	(segment
		(start 336.879692 -247.239282)
		(end 336.87131 -247.244108)
		(width 0.09525)
		(layer "In2.Cu")
		(net "M_C_CPU0_SA_DQS_DN<9>")
	)
	(segment
		(start 304.874676 -239.910874)
		(end 304.361596 -239.910874)
		(width 0.16002)
		(layer "In2.Cu")
		(net "M_C_CPU0_SA_DQS_DN<9>")
	)
	(segment
		(start 341.2109 -247.244108)
		(end 341.202518 -247.239282)
		(width 0.09525)
		(layer "In2.Cu")
		(net "M_C_CPU0_SA_DQS_DN<9>")
	)
	(segment
		(start 325.41464 -247.290844)
		(end 324.18909 -247.290844)
		(width 0.09525)
		(layer "In2.Cu")
		(net "M_C_CPU0_SA_DQS_DN<9>")
	)
	(segment
		(start 343.271094 -246.914162)
		(end 343.425018 -247.179592)
		(width 0.09525)
		(layer "In2.Cu")
		(net "M_C_CPU0_SA_DQS_DN<9>")
	)
	(segment
		(start 332.179676 -247.239282)
		(end 332.171294 -247.244108)
		(width 0.09525)
		(layer "In2.Cu")
		(net "M_C_CPU0_SA_DQS_DN<9>")
	)
	(segment
		(start 323.294756 -247.231916)
		(end 322.706492 -246.643652)
		(width 0.16002)
		(layer "In2.Cu")
		(net "M_C_CPU0_SA_DQS_DN<9>")
	)
	(segment
		(start 340.639654 -247.239282)
		(end 340.631272 -247.244108)
		(width 0.09525)
		(layer "In2.Cu")
		(net "M_C_CPU0_SA_DQS_DN<9>")
	)
	(segment
		(start 342.150954 -247.244108)
		(end 342.142572 -247.239282)
		(width 0.09525)
		(layer "In2.Cu")
		(net "M_C_CPU0_SA_DQS_DN<9>")
	)
	(segment
		(start 296.802556 -239.933734)
		(end 296.478198 -240.258092)
		(width 0.16002)
		(layer "In2.Cu")
		(net "M_C_CPU0_SA_DQS_DN<9>")
	)
	(segment
		(start 294.705278 -240.258092)
		(end 294.114474 -239.667288)
		(width 0.16002)
		(layer "In2.Cu")
		(net "M_C_CPU0_SA_DQS_DN<9>")
	)
	(segment
		(start 327.106026 -247.239282)
		(end 327.079864 -247.224042)
		(width 0.09525)
		(layer "In2.Cu")
		(net "M_C_CPU0_SA_DQS_DN<9>")
	)
	(segment
		(start 301.43958 -239.407954)
		(end 299.08754 -239.407954)
		(width 0.16002)
		(layer "In2.Cu")
		(net "M_C_CPU0_SA_DQS_DN<9>")
	)
	(segment
		(start 314.528708 -245.690644)
		(end 314.363608 -245.690644)
		(width 0.16002)
		(layer "In2.Cu")
		(net "M_C_CPU0_SA_DQS_DN<9>")
	)
	(segment
		(start 298.75988 -239.080294)
		(end 298.146216 -239.080294)
		(width 0.16002)
		(layer "In2.Cu")
		(net "M_C_CPU0_SA_DQS_DN<9>")
	)
	(segment
		(start 314.868306 -246.030242)
		(end 314.528708 -245.690644)
		(width 0.16002)
		(layer "In2.Cu")
		(net "M_C_CPU0_SA_DQS_DN<9>")
	)
	(segment
		(start 299.08754 -239.407954)
		(end 298.75988 -239.080294)
		(width 0.16002)
		(layer "In2.Cu")
		(net "M_C_CPU0_SA_DQS_DN<9>")
	)
	(segment
		(start 337.450938 -247.244108)
		(end 337.442556 -247.239282)
		(width 0.09525)
		(layer "In2.Cu")
		(net "M_C_CPU0_SA_DQS_DN<9>")
	)
	(segment
		(start 304.361596 -239.910874)
		(end 304.041556 -240.230914)
		(width 0.16002)
		(layer "In2.Cu")
		(net "M_C_CPU0_SA_DQS_DN<9>")
	)
	(segment
		(start 327.481692 -247.239028)
		(end 327.459848 -247.251474)
		(width 0.09525)
		(layer "In2.Cu")
		(net "M_C_CPU0_SA_DQS_DN<9>")
	)
	(segment
		(start 332.750922 -247.244108)
		(end 332.74254 -247.239282)
		(width 0.09525)
		(layer "In2.Cu")
		(net "M_C_CPU0_SA_DQS_DN<9>")
	)
	(segment
		(start 298.146216 -239.080294)
		(end 297.292776 -239.933734)
		(width 0.16002)
		(layer "In2.Cu")
		(net "M_C_CPU0_SA_DQS_DN<9>")
	)
	(segment
		(start 324.090792 -247.231916)
		(end 324.06717 -247.231916)
		(width 0.09525)
		(layer "In2.Cu")
		(net "M_C_CPU0_SA_DQS_DN<9>")
	)
	(segment
		(start 314.868306 -246.195342)
		(end 314.868306 -246.030242)
		(width 0.16002)
		(layer "In2.Cu")
		(net "M_C_CPU0_SA_DQS_DN<9>")
	)
	(arc
		(start 337.442556 -247.239282)
		(mid 337.161124 -247.163527)
		(end 336.879692 -247.239282)
		(width 0.09525)
		(layer "In2.Cu")
		(net "M_C_CPU0_SA_DQS_DN<9>")
	)
	(arc
		(start 329.359768 -247.239282)
		(mid 329.175993 -247.290054)
		(end 328.99096 -247.244108)
		(width 0.09525)
		(layer "In2.Cu")
		(net "M_C_CPU0_SA_DQS_DN<9>")
	)
	(arc
		(start 333.682594 -247.239282)
		(mid 333.401162 -247.163527)
		(end 333.11973 -247.239282)
		(width 0.09525)
		(layer "In2.Cu")
		(net "M_C_CPU0_SA_DQS_DN<9>")
	)
	(arc
		(start 341.202518 -247.239282)
		(mid 340.921086 -247.163527)
		(end 340.639654 -247.239282)
		(width 0.09525)
		(layer "In2.Cu")
		(net "M_C_CPU0_SA_DQS_DN<9>")
	)
	(arc
		(start 338.759546 -247.239282)
		(mid 338.571078 -247.289959)
		(end 338.38261 -247.239282)
		(width 0.09525)
		(layer "In2.Cu")
		(net "M_C_CPU0_SA_DQS_DN<9>")
	)
	(arc
		(start 335.931256 -247.244108)
		(mid 335.746224 -247.290022)
		(end 335.562448 -247.239282)
		(width 0.09525)
		(layer "In2.Cu")
		(net "M_C_CPU0_SA_DQS_DN<9>")
	)
	(arc
		(start 338.38261 -247.239282)
		(mid 338.101178 -247.163527)
		(end 337.819746 -247.239282)
		(width 0.09525)
		(layer "In2.Cu")
		(net "M_C_CPU0_SA_DQS_DN<9>")
	)
	(arc
		(start 326.54113 -247.239536)
		(mid 326.371531 -247.290392)
		(end 326.197468 -247.258078)
		(width 0.09525)
		(layer "In2.Cu")
		(net "M_C_CPU0_SA_DQS_DN<9>")
	)
	(arc
		(start 330.299568 -247.239282)
		(mid 330.1111 -247.289959)
		(end 329.922632 -247.239282)
		(width 0.09525)
		(layer "In2.Cu")
		(net "M_C_CPU0_SA_DQS_DN<9>")
	)
	(arc
		(start 335.562448 -247.239282)
		(mid 335.281016 -247.163527)
		(end 334.999584 -247.239282)
		(width 0.09525)
		(layer "In2.Cu")
		(net "M_C_CPU0_SA_DQS_DN<9>")
	)
	(arc
		(start 342.142572 -247.239282)
		(mid 341.86114 -247.163527)
		(end 341.579708 -247.239282)
		(width 0.09525)
		(layer "In2.Cu")
		(net "M_C_CPU0_SA_DQS_DN<9>")
	)
	(arc
		(start 332.74254 -247.239282)
		(mid 332.461108 -247.163527)
		(end 332.179676 -247.239282)
		(width 0.09525)
		(layer "In2.Cu")
		(net "M_C_CPU0_SA_DQS_DN<9>")
	)
	(arc
		(start 327.079864 -247.224042)
		(mid 326.808508 -247.162893)
		(end 326.54113 -247.239536)
		(width 0.09525)
		(layer "In2.Cu")
		(net "M_C_CPU0_SA_DQS_DN<9>")
	)
	(arc
		(start 336.87131 -247.244108)
		(mid 336.686278 -247.290022)
		(end 336.502502 -247.239282)
		(width 0.09525)
		(layer "In2.Cu")
		(net "M_C_CPU0_SA_DQS_DN<9>")
	)
	(arc
		(start 332.171294 -247.244108)
		(mid 331.986262 -247.290022)
		(end 331.802486 -247.239282)
		(width 0.09525)
		(layer "In2.Cu")
		(net "M_C_CPU0_SA_DQS_DN<9>")
	)
	(arc
		(start 330.862432 -247.239282)
		(mid 330.581 -247.163527)
		(end 330.299568 -247.239282)
		(width 0.09525)
		(layer "In2.Cu")
		(net "M_C_CPU0_SA_DQS_DN<9>")
	)
	(arc
		(start 325.603362 -247.239282)
		(mid 325.512416 -247.277583)
		(end 325.41464 -247.290844)
		(width 0.09525)
		(layer "In2.Cu")
		(net "M_C_CPU0_SA_DQS_DN<9>")
	)
	(arc
		(start 339.32241 -247.239282)
		(mid 339.040978 -247.163527)
		(end 338.759546 -247.239282)
		(width 0.09525)
		(layer "In2.Cu")
		(net "M_C_CPU0_SA_DQS_DN<9>")
	)
	(arc
		(start 343.401904 -247.266206)
		(mid 343.239253 -247.288466)
		(end 343.082626 -247.239282)
		(width 0.09525)
		(layer "In2.Cu")
		(net "M_C_CPU0_SA_DQS_DN<9>")
	)
	(arc
		(start 334.622648 -247.239282)
		(mid 334.341216 -247.163527)
		(end 334.059784 -247.239282)
		(width 0.09525)
		(layer "In2.Cu")
		(net "M_C_CPU0_SA_DQS_DN<9>")
	)
	(arc
		(start 343.082626 -247.239282)
		(mid 342.801194 -247.163527)
		(end 342.519762 -247.239282)
		(width 0.09525)
		(layer "In2.Cu")
		(net "M_C_CPU0_SA_DQS_DN<9>")
	)
	(arc
		(start 331.23124 -247.244108)
		(mid 331.046208 -247.290022)
		(end 330.862432 -247.239282)
		(width 0.09525)
		(layer "In2.Cu")
		(net "M_C_CPU0_SA_DQS_DN<9>")
	)
	(arc
		(start 324.18909 -247.290844)
		(mid 324.152654 -247.283578)
		(end 324.12178 -247.262904)
		(width 0.09525)
		(layer "In2.Cu")
		(net "M_C_CPU0_SA_DQS_DN<9>")
	)
	(arc
		(start 331.802486 -247.239282)
		(mid 331.521054 -247.163527)
		(end 331.239622 -247.239282)
		(width 0.09525)
		(layer "In2.Cu")
		(net "M_C_CPU0_SA_DQS_DN<9>")
	)
	(arc
		(start 341.579708 -247.239282)
		(mid 341.395933 -247.290054)
		(end 341.2109 -247.244108)
		(width 0.09525)
		(layer "In2.Cu")
		(net "M_C_CPU0_SA_DQS_DN<9>")
	)
	(arc
		(start 337.819746 -247.239282)
		(mid 337.635971 -247.290054)
		(end 337.450938 -247.244108)
		(width 0.09525)
		(layer "In2.Cu")
		(net "M_C_CPU0_SA_DQS_DN<9>")
	)
	(arc
		(start 334.059784 -247.239282)
		(mid 333.876009 -247.290054)
		(end 333.690976 -247.244108)
		(width 0.09525)
		(layer "In2.Cu")
		(net "M_C_CPU0_SA_DQS_DN<9>")
	)
	(arc
		(start 327.459848 -247.251474)
		(mid 327.281396 -247.289716)
		(end 327.106026 -247.239282)
		(width 0.09525)
		(layer "In2.Cu")
		(net "M_C_CPU0_SA_DQS_DN<9>")
	)
	(arc
		(start 328.411332 -247.244108)
		(mid 328.2263 -247.290022)
		(end 328.042524 -247.239282)
		(width 0.09525)
		(layer "In2.Cu")
		(net "M_C_CPU0_SA_DQS_DN<9>")
	)
	(arc
		(start 329.922632 -247.239282)
		(mid 329.6412 -247.163527)
		(end 329.359768 -247.239282)
		(width 0.09525)
		(layer "In2.Cu")
		(net "M_C_CPU0_SA_DQS_DN<9>")
	)
	(arc
		(start 342.519762 -247.239282)
		(mid 342.335987 -247.290054)
		(end 342.150954 -247.244108)
		(width 0.09525)
		(layer "In2.Cu")
		(net "M_C_CPU0_SA_DQS_DN<9>")
	)
	(arc
		(start 326.138286 -247.224042)
		(mid 325.86888 -247.163694)
		(end 325.603362 -247.239282)
		(width 0.09525)
		(layer "In2.Cu")
		(net "M_C_CPU0_SA_DQS_DN<9>")
	)
	(arc
		(start 333.11973 -247.239282)
		(mid 332.935955 -247.290054)
		(end 332.750922 -247.244108)
		(width 0.09525)
		(layer "In2.Cu")
		(net "M_C_CPU0_SA_DQS_DN<9>")
	)
	(arc
		(start 328.042524 -247.239282)
		(mid 327.777004 -247.163753)
		(end 327.5076 -247.224042)
		(width 0.09525)
		(layer "In2.Cu")
		(net "M_C_CPU0_SA_DQS_DN<9>")
	)
	(arc
		(start 340.631272 -247.244108)
		(mid 340.44624 -247.290022)
		(end 340.262464 -247.239282)
		(width 0.09525)
		(layer "In2.Cu")
		(net "M_C_CPU0_SA_DQS_DN<9>")
	)
	(arc
		(start 328.982578 -247.239282)
		(mid 328.701146 -247.163527)
		(end 328.419714 -247.239282)
		(width 0.09525)
		(layer "In2.Cu")
		(net "M_C_CPU0_SA_DQS_DN<9>")
	)
	(arc
		(start 340.262464 -247.239282)
		(mid 339.981032 -247.163527)
		(end 339.6996 -247.239282)
		(width 0.09525)
		(layer "In2.Cu")
		(net "M_C_CPU0_SA_DQS_DN<9>")
	)
	(arc
		(start 334.999584 -247.239282)
		(mid 334.811116 -247.289959)
		(end 334.622648 -247.239282)
		(width 0.09525)
		(layer "In2.Cu")
		(net "M_C_CPU0_SA_DQS_DN<9>")
	)
	(arc
		(start 336.502502 -247.239282)
		(mid 336.22107 -247.163527)
		(end 335.939638 -247.239282)
		(width 0.09525)
		(layer "In2.Cu")
		(net "M_C_CPU0_SA_DQS_DN<9>")
	)
	(arc
		(start 339.691218 -247.244108)
		(mid 339.506186 -247.290022)
		(end 339.32241 -247.239282)
		(width 0.09525)
		(layer "In2.Cu")
		(net "M_C_CPU0_SA_DQS_DN<9>")
	)
	(segment
		(start 343.737946 -242.320064)
		(end 343.271094 -242.054126)
		(width 0.12954)
		(layer "F.Cu")
		(net "M_C_CPU0_SA_DQS_DN<8>")
	)
	(segment
		(start 337.450938 -242.384072)
		(end 337.442556 -242.379246)
		(width 0.09525)
		(layer "In2.Cu")
		(net "M_C_CPU0_SA_DQS_DN<8>")
	)
	(segment
		(start 333.690976 -242.384072)
		(end 333.682594 -242.379246)
		(width 0.09525)
		(layer "In2.Cu")
		(net "M_C_CPU0_SA_DQS_DN<8>")
	)
	(segment
		(start 296.802556 -230.58374)
		(end 296.478198 -230.908098)
		(width 0.16002)
		(layer "In2.Cu")
		(net "M_C_CPU0_SA_DQS_DN<8>")
	)
	(segment
		(start 332.750922 -242.384072)
		(end 332.74254 -242.379246)
		(width 0.09525)
		(layer "In2.Cu")
		(net "M_C_CPU0_SA_DQS_DN<8>")
	)
	(segment
		(start 332.179676 -242.379246)
		(end 332.171294 -242.384072)
		(width 0.09525)
		(layer "In2.Cu")
		(net "M_C_CPU0_SA_DQS_DN<8>")
	)
	(segment
		(start 291.172138 -229.70998)
		(end 290.04641 -229.70998)
		(width 0.16002)
		(layer "In2.Cu")
		(net "M_C_CPU0_SA_DQS_DN<8>")
	)
	(segment
		(start 301.43958 -230.05796)
		(end 299.047408 -230.05796)
		(width 0.16002)
		(layer "In2.Cu")
		(net "M_C_CPU0_SA_DQS_DN<8>")
	)
	(segment
		(start 328.419714 -242.379246)
		(end 328.411332 -242.384072)
		(width 0.09525)
		(layer "In2.Cu")
		(net "M_C_CPU0_SA_DQS_DN<8>")
	)
	(segment
		(start 331.239622 -242.379246)
		(end 331.23124 -242.384072)
		(width 0.09525)
		(layer "In2.Cu")
		(net "M_C_CPU0_SA_DQS_DN<8>")
	)
	(segment
		(start 339.6996 -242.379246)
		(end 339.691218 -242.384072)
		(width 0.09525)
		(layer "In2.Cu")
		(net "M_C_CPU0_SA_DQS_DN<8>")
	)
	(segment
		(start 323.978778 -241.012472)
		(end 323.919596 -240.95329)
		(width 0.09525)
		(layer "In2.Cu")
		(net "M_C_CPU0_SA_DQS_DN<8>")
	)
	(segment
		(start 323.919596 -240.95329)
		(end 323.895974 -240.95329)
		(width 0.09525)
		(layer "In2.Cu")
		(net "M_C_CPU0_SA_DQS_DN<8>")
	)
	(segment
		(start 305.656996 -229.758748)
		(end 304.854864 -230.56088)
		(width 0.16002)
		(layer "In2.Cu")
		(net "M_C_CPU0_SA_DQS_DN<8>")
	)
	(segment
		(start 290.04641 -229.70998)
		(end 289.847274 -229.909116)
		(width 0.16002)
		(layer "In2.Cu")
		(net "M_C_CPU0_SA_DQS_DN<8>")
	)
	(segment
		(start 306.577238 -230.01732)
		(end 306.318666 -229.758748)
		(width 0.16002)
		(layer "In2.Cu")
		(net "M_C_CPU0_SA_DQS_DN<8>")
	)
	(segment
		(start 341.2109 -242.384072)
		(end 341.202518 -242.379246)
		(width 0.09525)
		(layer "In2.Cu")
		(net "M_C_CPU0_SA_DQS_DN<8>")
	)
	(segment
		(start 319.901316 -240.95329)
		(end 308.965346 -230.01732)
		(width 0.16002)
		(layer "In2.Cu")
		(net "M_C_CPU0_SA_DQS_DN<8>")
	)
	(segment
		(start 294.705278 -230.908098)
		(end 294.114474 -230.317294)
		(width 0.16002)
		(layer "In2.Cu")
		(net "M_C_CPU0_SA_DQS_DN<8>")
	)
	(segment
		(start 327.103994 -242.378992)
		(end 327.067164 -242.357656)
		(width 0.09525)
		(layer "In2.Cu")
		(net "M_C_CPU0_SA_DQS_DN<8>")
	)
	(segment
		(start 304.854864 -230.56088)
		(end 304.379884 -230.56088)
		(width 0.16002)
		(layer "In2.Cu")
		(net "M_C_CPU0_SA_DQS_DN<8>")
	)
	(segment
		(start 289.847274 -229.909116)
		(end 288.454084 -229.909116)
		(width 0.16002)
		(layer "In2.Cu")
		(net "M_C_CPU0_SA_DQS_DN<8>")
	)
	(segment
		(start 336.879692 -242.379246)
		(end 336.87131 -242.384072)
		(width 0.09525)
		(layer "In2.Cu")
		(net "M_C_CPU0_SA_DQS_DN<8>")
	)
	(segment
		(start 323.895974 -240.95329)
		(end 319.901316 -240.95329)
		(width 0.16002)
		(layer "In2.Cu")
		(net "M_C_CPU0_SA_DQS_DN<8>")
	)
	(segment
		(start 288.454084 -229.909116)
		(end 288.180018 -229.63505)
		(width 0.16002)
		(layer "In2.Cu")
		(net "M_C_CPU0_SA_DQS_DN<8>")
	)
	(segment
		(start 343.425018 -242.319556)
		(end 343.401904 -242.40617)
		(width 0.09525)
		(layer "In2.Cu")
		(net "M_C_CPU0_SA_DQS_DN<8>")
	)
	(segment
		(start 298.146216 -229.7303)
		(end 297.292776 -230.58374)
		(width 0.16002)
		(layer "In2.Cu")
		(net "M_C_CPU0_SA_DQS_DN<8>")
	)
	(segment
		(start 324.226174 -240.91265)
		(end 324.126352 -241.012472)
		(width 0.09525)
		(layer "In2.Cu")
		(net "M_C_CPU0_SA_DQS_DN<8>")
	)
	(segment
		(start 325.379334 -241.34572)
		(end 324.946264 -240.91265)
		(width 0.09525)
		(layer "In2.Cu")
		(net "M_C_CPU0_SA_DQS_DN<8>")
	)
	(segment
		(start 304.379884 -230.56088)
		(end 304.059844 -230.88092)
		(width 0.16002)
		(layer "In2.Cu")
		(net "M_C_CPU0_SA_DQS_DN<8>")
	)
	(segment
		(start 308.965346 -230.01732)
		(end 306.577238 -230.01732)
		(width 0.16002)
		(layer "In2.Cu")
		(net "M_C_CPU0_SA_DQS_DN<8>")
	)
	(segment
		(start 342.150954 -242.384072)
		(end 342.142572 -242.379246)
		(width 0.09525)
		(layer "In2.Cu")
		(net "M_C_CPU0_SA_DQS_DN<8>")
	)
	(segment
		(start 292.920674 -230.317294)
		(end 291.779452 -230.317294)
		(width 0.16002)
		(layer "In2.Cu")
		(net "M_C_CPU0_SA_DQS_DN<8>")
	)
	(segment
		(start 297.292776 -230.58374)
		(end 296.802556 -230.58374)
		(width 0.16002)
		(layer "In2.Cu")
		(net "M_C_CPU0_SA_DQS_DN<8>")
	)
	(segment
		(start 302.26254 -230.88092)
		(end 301.43958 -230.05796)
		(width 0.16002)
		(layer "In2.Cu")
		(net "M_C_CPU0_SA_DQS_DN<8>")
	)
	(segment
		(start 304.059844 -230.88092)
		(end 302.26254 -230.88092)
		(width 0.16002)
		(layer "In2.Cu")
		(net "M_C_CPU0_SA_DQS_DN<8>")
	)
	(segment
		(start 326.197468 -242.398042)
		(end 326.164194 -242.378992)
		(width 0.09525)
		(layer "In2.Cu")
		(net "M_C_CPU0_SA_DQS_DN<8>")
	)
	(segment
		(start 291.779452 -230.317294)
		(end 291.172138 -229.70998)
		(width 0.16002)
		(layer "In2.Cu")
		(net "M_C_CPU0_SA_DQS_DN<8>")
	)
	(segment
		(start 324.126352 -241.012472)
		(end 323.978778 -241.012472)
		(width 0.09525)
		(layer "In2.Cu")
		(net "M_C_CPU0_SA_DQS_DN<8>")
	)
	(segment
		(start 328.99096 -242.384072)
		(end 328.982578 -242.379246)
		(width 0.09525)
		(layer "In2.Cu")
		(net "M_C_CPU0_SA_DQS_DN<8>")
	)
	(segment
		(start 293.517574 -230.200454)
		(end 293.037514 -230.200454)
		(width 0.16002)
		(layer "In2.Cu")
		(net "M_C_CPU0_SA_DQS_DN<8>")
	)
	(segment
		(start 294.114474 -230.317294)
		(end 293.634414 -230.317294)
		(width 0.16002)
		(layer "In2.Cu")
		(net "M_C_CPU0_SA_DQS_DN<8>")
	)
	(segment
		(start 327.125838 -242.391438)
		(end 327.103994 -242.378992)
		(width 0.09525)
		(layer "In2.Cu")
		(net "M_C_CPU0_SA_DQS_DN<8>")
	)
	(segment
		(start 296.478198 -230.908098)
		(end 294.705278 -230.908098)
		(width 0.16002)
		(layer "In2.Cu")
		(net "M_C_CPU0_SA_DQS_DN<8>")
	)
	(segment
		(start 324.946264 -240.91265)
		(end 324.226174 -240.91265)
		(width 0.09525)
		(layer "In2.Cu")
		(net "M_C_CPU0_SA_DQS_DN<8>")
	)
	(segment
		(start 335.939638 -242.379246)
		(end 335.931256 -242.384072)
		(width 0.09525)
		(layer "In2.Cu")
		(net "M_C_CPU0_SA_DQS_DN<8>")
	)
	(segment
		(start 298.719748 -229.7303)
		(end 298.146216 -229.7303)
		(width 0.16002)
		(layer "In2.Cu")
		(net "M_C_CPU0_SA_DQS_DN<8>")
	)
	(segment
		(start 299.047408 -230.05796)
		(end 298.719748 -229.7303)
		(width 0.16002)
		(layer "In2.Cu")
		(net "M_C_CPU0_SA_DQS_DN<8>")
	)
	(segment
		(start 306.318666 -229.758748)
		(end 305.656996 -229.758748)
		(width 0.16002)
		(layer "In2.Cu")
		(net "M_C_CPU0_SA_DQS_DN<8>")
	)
	(segment
		(start 326.085454 -242.31981)
		(end 325.379334 -241.61369)
		(width 0.09525)
		(layer "In2.Cu")
		(net "M_C_CPU0_SA_DQS_DN<8>")
	)
	(segment
		(start 293.634414 -230.317294)
		(end 293.517574 -230.200454)
		(width 0.16002)
		(layer "In2.Cu")
		(net "M_C_CPU0_SA_DQS_DN<8>")
	)
	(segment
		(start 325.379334 -241.61369)
		(end 325.379334 -241.34572)
		(width 0.09525)
		(layer "In2.Cu")
		(net "M_C_CPU0_SA_DQS_DN<8>")
	)
	(segment
		(start 340.639654 -242.379246)
		(end 340.631272 -242.384072)
		(width 0.09525)
		(layer "In2.Cu")
		(net "M_C_CPU0_SA_DQS_DN<8>")
	)
	(segment
		(start 293.037514 -230.200454)
		(end 292.920674 -230.317294)
		(width 0.16002)
		(layer "In2.Cu")
		(net "M_C_CPU0_SA_DQS_DN<8>")
	)
	(segment
		(start 343.271094 -242.054126)
		(end 343.425018 -242.319556)
		(width 0.09525)
		(layer "In2.Cu")
		(net "M_C_CPU0_SA_DQS_DN<8>")
	)
	(arc
		(start 327.47966 -242.379246)
		(mid 327.304286 -242.429576)
		(end 327.125838 -242.391438)
		(width 0.09525)
		(layer "In2.Cu")
		(net "M_C_CPU0_SA_DQS_DN<8>")
	)
	(arc
		(start 343.082626 -242.379246)
		(mid 342.801194 -242.303491)
		(end 342.519762 -242.379246)
		(width 0.09525)
		(layer "In2.Cu")
		(net "M_C_CPU0_SA_DQS_DN<8>")
	)
	(arc
		(start 342.519762 -242.379246)
		(mid 342.335987 -242.430018)
		(end 342.150954 -242.384072)
		(width 0.09525)
		(layer "In2.Cu")
		(net "M_C_CPU0_SA_DQS_DN<8>")
	)
	(arc
		(start 338.759546 -242.379246)
		(mid 338.571078 -242.429923)
		(end 338.38261 -242.379246)
		(width 0.09525)
		(layer "In2.Cu")
		(net "M_C_CPU0_SA_DQS_DN<8>")
	)
	(arc
		(start 331.23124 -242.384072)
		(mid 331.046208 -242.429986)
		(end 330.862432 -242.379246)
		(width 0.09525)
		(layer "In2.Cu")
		(net "M_C_CPU0_SA_DQS_DN<8>")
	)
	(arc
		(start 326.164194 -242.378992)
		(mid 326.122878 -242.351991)
		(end 326.085454 -242.31981)
		(width 0.09525)
		(layer "In2.Cu")
		(net "M_C_CPU0_SA_DQS_DN<8>")
	)
	(arc
		(start 329.359768 -242.379246)
		(mid 329.175993 -242.430018)
		(end 328.99096 -242.384072)
		(width 0.09525)
		(layer "In2.Cu")
		(net "M_C_CPU0_SA_DQS_DN<8>")
	)
	(arc
		(start 328.042524 -242.379246)
		(mid 327.761092 -242.303491)
		(end 327.47966 -242.379246)
		(width 0.09525)
		(layer "In2.Cu")
		(net "M_C_CPU0_SA_DQS_DN<8>")
	)
	(arc
		(start 339.691218 -242.384072)
		(mid 339.506186 -242.429986)
		(end 339.32241 -242.379246)
		(width 0.09525)
		(layer "In2.Cu")
		(net "M_C_CPU0_SA_DQS_DN<8>")
	)
	(arc
		(start 334.999584 -242.379246)
		(mid 334.811116 -242.429923)
		(end 334.622648 -242.379246)
		(width 0.09525)
		(layer "In2.Cu")
		(net "M_C_CPU0_SA_DQS_DN<8>")
	)
	(arc
		(start 331.802486 -242.379246)
		(mid 331.521054 -242.303491)
		(end 331.239622 -242.379246)
		(width 0.09525)
		(layer "In2.Cu")
		(net "M_C_CPU0_SA_DQS_DN<8>")
	)
	(arc
		(start 334.622648 -242.379246)
		(mid 334.341216 -242.303491)
		(end 334.059784 -242.379246)
		(width 0.09525)
		(layer "In2.Cu")
		(net "M_C_CPU0_SA_DQS_DN<8>")
	)
	(arc
		(start 337.819746 -242.379246)
		(mid 337.635971 -242.430018)
		(end 337.450938 -242.384072)
		(width 0.09525)
		(layer "In2.Cu")
		(net "M_C_CPU0_SA_DQS_DN<8>")
	)
	(arc
		(start 340.631272 -242.384072)
		(mid 340.44624 -242.429986)
		(end 340.262464 -242.379246)
		(width 0.09525)
		(layer "In2.Cu")
		(net "M_C_CPU0_SA_DQS_DN<8>")
	)
	(arc
		(start 330.299568 -242.379246)
		(mid 330.1111 -242.429923)
		(end 329.922632 -242.379246)
		(width 0.09525)
		(layer "In2.Cu")
		(net "M_C_CPU0_SA_DQS_DN<8>")
	)
	(arc
		(start 336.502502 -242.379246)
		(mid 336.22107 -242.303491)
		(end 335.939638 -242.379246)
		(width 0.09525)
		(layer "In2.Cu")
		(net "M_C_CPU0_SA_DQS_DN<8>")
	)
	(arc
		(start 334.059784 -242.379246)
		(mid 333.876009 -242.430018)
		(end 333.690976 -242.384072)
		(width 0.09525)
		(layer "In2.Cu")
		(net "M_C_CPU0_SA_DQS_DN<8>")
	)
	(arc
		(start 327.067164 -242.357656)
		(mid 326.801445 -242.303162)
		(end 326.54113 -242.3795)
		(width 0.09525)
		(layer "In2.Cu")
		(net "M_C_CPU0_SA_DQS_DN<8>")
	)
	(arc
		(start 332.74254 -242.379246)
		(mid 332.461108 -242.303491)
		(end 332.179676 -242.379246)
		(width 0.09525)
		(layer "In2.Cu")
		(net "M_C_CPU0_SA_DQS_DN<8>")
	)
	(arc
		(start 343.401904 -242.40617)
		(mid 343.239253 -242.42843)
		(end 343.082626 -242.379246)
		(width 0.09525)
		(layer "In2.Cu")
		(net "M_C_CPU0_SA_DQS_DN<8>")
	)
	(arc
		(start 332.171294 -242.384072)
		(mid 331.986262 -242.429986)
		(end 331.802486 -242.379246)
		(width 0.09525)
		(layer "In2.Cu")
		(net "M_C_CPU0_SA_DQS_DN<8>")
	)
	(arc
		(start 328.982578 -242.379246)
		(mid 328.701146 -242.303491)
		(end 328.419714 -242.379246)
		(width 0.09525)
		(layer "In2.Cu")
		(net "M_C_CPU0_SA_DQS_DN<8>")
	)
	(arc
		(start 336.87131 -242.384072)
		(mid 336.686278 -242.429986)
		(end 336.502502 -242.379246)
		(width 0.09525)
		(layer "In2.Cu")
		(net "M_C_CPU0_SA_DQS_DN<8>")
	)
	(arc
		(start 339.32241 -242.379246)
		(mid 339.040978 -242.303491)
		(end 338.759546 -242.379246)
		(width 0.09525)
		(layer "In2.Cu")
		(net "M_C_CPU0_SA_DQS_DN<8>")
	)
	(arc
		(start 340.262464 -242.379246)
		(mid 339.981032 -242.303491)
		(end 339.6996 -242.379246)
		(width 0.09525)
		(layer "In2.Cu")
		(net "M_C_CPU0_SA_DQS_DN<8>")
	)
	(arc
		(start 333.682594 -242.379246)
		(mid 333.401162 -242.303491)
		(end 333.11973 -242.379246)
		(width 0.09525)
		(layer "In2.Cu")
		(net "M_C_CPU0_SA_DQS_DN<8>")
	)
	(arc
		(start 337.442556 -242.379246)
		(mid 337.161124 -242.303491)
		(end 336.879692 -242.379246)
		(width 0.09525)
		(layer "In2.Cu")
		(net "M_C_CPU0_SA_DQS_DN<8>")
	)
	(arc
		(start 328.411332 -242.384072)
		(mid 328.2263 -242.429986)
		(end 328.042524 -242.379246)
		(width 0.09525)
		(layer "In2.Cu")
		(net "M_C_CPU0_SA_DQS_DN<8>")
	)
	(arc
		(start 335.562448 -242.379246)
		(mid 335.281016 -242.303491)
		(end 334.999584 -242.379246)
		(width 0.09525)
		(layer "In2.Cu")
		(net "M_C_CPU0_SA_DQS_DN<8>")
	)
	(arc
		(start 333.11973 -242.379246)
		(mid 332.935955 -242.430018)
		(end 332.750922 -242.384072)
		(width 0.09525)
		(layer "In2.Cu")
		(net "M_C_CPU0_SA_DQS_DN<8>")
	)
	(arc
		(start 330.862432 -242.379246)
		(mid 330.581 -242.303491)
		(end 330.299568 -242.379246)
		(width 0.09525)
		(layer "In2.Cu")
		(net "M_C_CPU0_SA_DQS_DN<8>")
	)
	(arc
		(start 326.54113 -242.3795)
		(mid 326.371531 -242.430356)
		(end 326.197468 -242.398042)
		(width 0.09525)
		(layer "In2.Cu")
		(net "M_C_CPU0_SA_DQS_DN<8>")
	)
	(arc
		(start 329.922632 -242.379246)
		(mid 329.6412 -242.303491)
		(end 329.359768 -242.379246)
		(width 0.09525)
		(layer "In2.Cu")
		(net "M_C_CPU0_SA_DQS_DN<8>")
	)
	(arc
		(start 335.931256 -242.384072)
		(mid 335.746224 -242.429986)
		(end 335.562448 -242.379246)
		(width 0.09525)
		(layer "In2.Cu")
		(net "M_C_CPU0_SA_DQS_DN<8>")
	)
	(arc
		(start 342.142572 -242.379246)
		(mid 341.86114 -242.303491)
		(end 341.579708 -242.379246)
		(width 0.09525)
		(layer "In2.Cu")
		(net "M_C_CPU0_SA_DQS_DN<8>")
	)
	(arc
		(start 341.202518 -242.379246)
		(mid 340.921086 -242.303491)
		(end 340.639654 -242.379246)
		(width 0.09525)
		(layer "In2.Cu")
		(net "M_C_CPU0_SA_DQS_DN<8>")
	)
	(arc
		(start 338.38261 -242.379246)
		(mid 338.101178 -242.303491)
		(end 337.819746 -242.379246)
		(width 0.09525)
		(layer "In2.Cu")
		(net "M_C_CPU0_SA_DQS_DN<8>")
	)
	(arc
		(start 341.579708 -242.379246)
		(mid 341.395933 -242.430018)
		(end 341.2109 -242.384072)
		(width 0.09525)
		(layer "In2.Cu")
		(net "M_C_CPU0_SA_DQS_DN<8>")
	)
	(segment
		(start 343.737946 -237.460028)
		(end 343.271094 -237.19409)
		(width 0.12954)
		(layer "F.Cu")
		(net "M_C_CPU0_SA_DQS_DN<7>")
	)
	(segment
		(start 324.51929 -235.44657)
		(end 324.414642 -235.341922)
		(width 0.09525)
		(layer "In2.Cu")
		(net "M_C_CPU0_SA_DQS_DN<7>")
	)
	(segment
		(start 325.008748 -235.44657)
		(end 324.51929 -235.44657)
		(width 0.09525)
		(layer "In2.Cu")
		(net "M_C_CPU0_SA_DQS_DN<7>")
	)
	(segment
		(start 299.08754 -220.707966)
		(end 298.75988 -220.380306)
		(width 0.16002)
		(layer "In2.Cu")
		(net "M_C_CPU0_SA_DQS_DN<7>")
	)
	(segment
		(start 323.919596 -235.28274)
		(end 323.895974 -235.28274)
		(width 0.09525)
		(layer "In2.Cu")
		(net "M_C_CPU0_SA_DQS_DN<7>")
	)
	(segment
		(start 288.454084 -220.559122)
		(end 288.180018 -220.285056)
		(width 0.16002)
		(layer "In2.Cu")
		(net "M_C_CPU0_SA_DQS_DN<7>")
	)
	(segment
		(start 290.319714 -220.559122)
		(end 288.454084 -220.559122)
		(width 0.16002)
		(layer "In2.Cu")
		(net "M_C_CPU0_SA_DQS_DN<7>")
	)
	(segment
		(start 326.422512 -236.59211)
		(end 326.154288 -236.59211)
		(width 0.09525)
		(layer "In2.Cu")
		(net "M_C_CPU0_SA_DQS_DN<7>")
	)
	(segment
		(start 304.830226 -220.987112)
		(end 304.411888 -221.160594)
		(width 0.16002)
		(layer "In2.Cu")
		(net "M_C_CPU0_SA_DQS_DN<7>")
	)
	(segment
		(start 328.99096 -237.524036)
		(end 328.982578 -237.51921)
		(width 0.09525)
		(layer "In2.Cu")
		(net "M_C_CPU0_SA_DQS_DN<7>")
	)
	(segment
		(start 317.359538 -228.057964)
		(end 311.203848 -221.902274)
		(width 0.16002)
		(layer "In2.Cu")
		(net "M_C_CPU0_SA_DQS_DN<7>")
	)
	(segment
		(start 310.698896 -221.397322)
		(end 309.9689 -220.667326)
		(width 0.16002)
		(layer "In2.Cu")
		(net "M_C_CPU0_SA_DQS_DN<7>")
	)
	(segment
		(start 309.9689 -220.667326)
		(end 306.577238 -220.667326)
		(width 0.16002)
		(layer "In2.Cu")
		(net "M_C_CPU0_SA_DQS_DN<7>")
	)
	(segment
		(start 333.690976 -237.524036)
		(end 333.682594 -237.51921)
		(width 0.09525)
		(layer "In2.Cu")
		(net "M_C_CPU0_SA_DQS_DN<7>")
	)
	(segment
		(start 311.203848 -221.902274)
		(end 311.203848 -221.73692)
		(width 0.16002)
		(layer "In2.Cu")
		(net "M_C_CPU0_SA_DQS_DN<7>")
	)
	(segment
		(start 298.75988 -220.380306)
		(end 298.146216 -220.380306)
		(width 0.16002)
		(layer "In2.Cu")
		(net "M_C_CPU0_SA_DQS_DN<7>")
	)
	(segment
		(start 293.796212 -220.9673)
		(end 291.779452 -220.9673)
		(width 0.16002)
		(layer "In2.Cu")
		(net "M_C_CPU0_SA_DQS_DN<7>")
	)
	(segment
		(start 311.203848 -221.73692)
		(end 310.86425 -221.397322)
		(width 0.16002)
		(layer "In2.Cu")
		(net "M_C_CPU0_SA_DQS_DN<7>")
	)
	(segment
		(start 323.978778 -235.341922)
		(end 323.919596 -235.28274)
		(width 0.09525)
		(layer "In2.Cu")
		(net "M_C_CPU0_SA_DQS_DN<7>")
	)
	(segment
		(start 306.577238 -220.667326)
		(end 306.315364 -220.405452)
		(width 0.16002)
		(layer "In2.Cu")
		(net "M_C_CPU0_SA_DQS_DN<7>")
	)
	(segment
		(start 328.419714 -237.51921)
		(end 328.411332 -237.524036)
		(width 0.09525)
		(layer "In2.Cu")
		(net "M_C_CPU0_SA_DQS_DN<7>")
	)
	(segment
		(start 296.779188 -221.270322)
		(end 296.49166 -221.55785)
		(width 0.16002)
		(layer "In2.Cu")
		(net "M_C_CPU0_SA_DQS_DN<7>")
	)
	(segment
		(start 341.2109 -237.524036)
		(end 341.202518 -237.51921)
		(width 0.09525)
		(layer "In2.Cu")
		(net "M_C_CPU0_SA_DQS_DN<7>")
	)
	(segment
		(start 310.86425 -221.397322)
		(end 310.698896 -221.397322)
		(width 0.16002)
		(layer "In2.Cu")
		(net "M_C_CPU0_SA_DQS_DN<7>")
	)
	(segment
		(start 290.473384 -220.405452)
		(end 290.319714 -220.559122)
		(width 0.16002)
		(layer "In2.Cu")
		(net "M_C_CPU0_SA_DQS_DN<7>")
	)
	(segment
		(start 332.179676 -237.51921)
		(end 332.171294 -237.524036)
		(width 0.09525)
		(layer "In2.Cu")
		(net "M_C_CPU0_SA_DQS_DN<7>")
	)
	(segment
		(start 323.895974 -235.28274)
		(end 322.623434 -235.28274)
		(width 0.16002)
		(layer "In2.Cu")
		(net "M_C_CPU0_SA_DQS_DN<7>")
	)
	(segment
		(start 342.150954 -237.524036)
		(end 342.142572 -237.51921)
		(width 0.09525)
		(layer "In2.Cu")
		(net "M_C_CPU0_SA_DQS_DN<7>")
	)
	(segment
		(start 335.939638 -237.51921)
		(end 335.931256 -237.524036)
		(width 0.09525)
		(layer "In2.Cu")
		(net "M_C_CPU0_SA_DQS_DN<7>")
	)
	(segment
		(start 326.154288 -236.59211)
		(end 325.008748 -235.44657)
		(width 0.09525)
		(layer "In2.Cu")
		(net "M_C_CPU0_SA_DQS_DN<7>")
	)
	(segment
		(start 343.425018 -237.45952)
		(end 343.401904 -237.546134)
		(width 0.09525)
		(layer "In2.Cu")
		(net "M_C_CPU0_SA_DQS_DN<7>")
	)
	(segment
		(start 317.359538 -230.018844)
		(end 317.359538 -228.057964)
		(width 0.16002)
		(layer "In2.Cu")
		(net "M_C_CPU0_SA_DQS_DN<7>")
	)
	(segment
		(start 301.725076 -220.993462)
		(end 301.03572 -220.707966)
		(width 0.16002)
		(layer "In2.Cu")
		(net "M_C_CPU0_SA_DQS_DN<7>")
	)
	(segment
		(start 296.49166 -221.55785)
		(end 294.705024 -221.55785)
		(width 0.16002)
		(layer "In2.Cu")
		(net "M_C_CPU0_SA_DQS_DN<7>")
	)
	(segment
		(start 294.339264 -221.19209)
		(end 293.796212 -220.9673)
		(width 0.16002)
		(layer "In2.Cu")
		(net "M_C_CPU0_SA_DQS_DN<7>")
	)
	(segment
		(start 332.750922 -237.524036)
		(end 332.74254 -237.51921)
		(width 0.09525)
		(layer "In2.Cu")
		(net "M_C_CPU0_SA_DQS_DN<7>")
	)
	(segment
		(start 301.03572 -220.707966)
		(end 299.08754 -220.707966)
		(width 0.16002)
		(layer "In2.Cu")
		(net "M_C_CPU0_SA_DQS_DN<7>")
	)
	(segment
		(start 343.271094 -237.19409)
		(end 343.425018 -237.45952)
		(width 0.09525)
		(layer "In2.Cu")
		(net "M_C_CPU0_SA_DQS_DN<7>")
	)
	(segment
		(start 294.705024 -221.55785)
		(end 294.339264 -221.19209)
		(width 0.16002)
		(layer "In2.Cu")
		(net "M_C_CPU0_SA_DQS_DN<7>")
	)
	(segment
		(start 291.779452 -220.9673)
		(end 291.217604 -220.405452)
		(width 0.16002)
		(layer "In2.Cu")
		(net "M_C_CPU0_SA_DQS_DN<7>")
	)
	(segment
		(start 327.761092 -237.443518)
		(end 327.412096 -237.443518)
		(width 0.09525)
		(layer "In2.Cu")
		(net "M_C_CPU0_SA_DQS_DN<7>")
	)
	(segment
		(start 306.315364 -220.405452)
		(end 305.700938 -220.405452)
		(width 0.16002)
		(layer "In2.Cu")
		(net "M_C_CPU0_SA_DQS_DN<7>")
	)
	(segment
		(start 324.414642 -235.341922)
		(end 323.978778 -235.341922)
		(width 0.09525)
		(layer "In2.Cu")
		(net "M_C_CPU0_SA_DQS_DN<7>")
	)
	(segment
		(start 331.239622 -237.51921)
		(end 331.23124 -237.524036)
		(width 0.09525)
		(layer "In2.Cu")
		(net "M_C_CPU0_SA_DQS_DN<7>")
	)
	(segment
		(start 302.26254 -221.530926)
		(end 301.725076 -220.993462)
		(width 0.16002)
		(layer "In2.Cu")
		(net "M_C_CPU0_SA_DQS_DN<7>")
	)
	(segment
		(start 291.217604 -220.405452)
		(end 290.473384 -220.405452)
		(width 0.16002)
		(layer "In2.Cu")
		(net "M_C_CPU0_SA_DQS_DN<7>")
	)
	(segment
		(start 304.041556 -221.530926)
		(end 302.26254 -221.530926)
		(width 0.16002)
		(layer "In2.Cu")
		(net "M_C_CPU0_SA_DQS_DN<7>")
	)
	(segment
		(start 339.6996 -237.51921)
		(end 339.691218 -237.524036)
		(width 0.09525)
		(layer "In2.Cu")
		(net "M_C_CPU0_SA_DQS_DN<7>")
	)
	(segment
		(start 305.700938 -220.405452)
		(end 304.830226 -220.987112)
		(width 0.16002)
		(layer "In2.Cu")
		(net "M_C_CPU0_SA_DQS_DN<7>")
	)
	(segment
		(start 297.593512 -220.93301)
		(end 296.779188 -221.270322)
		(width 0.16002)
		(layer "In2.Cu")
		(net "M_C_CPU0_SA_DQS_DN<7>")
	)
	(segment
		(start 336.879692 -237.51921)
		(end 336.87131 -237.524036)
		(width 0.09525)
		(layer "In2.Cu")
		(net "M_C_CPU0_SA_DQS_DN<7>")
	)
	(segment
		(start 327.412096 -237.443518)
		(end 326.658478 -236.6899)
		(width 0.09525)
		(layer "In2.Cu")
		(net "M_C_CPU0_SA_DQS_DN<7>")
	)
	(segment
		(start 304.411888 -221.160594)
		(end 304.041556 -221.530926)
		(width 0.16002)
		(layer "In2.Cu")
		(net "M_C_CPU0_SA_DQS_DN<7>")
	)
	(segment
		(start 337.450938 -237.524036)
		(end 337.442556 -237.51921)
		(width 0.09525)
		(layer "In2.Cu")
		(net "M_C_CPU0_SA_DQS_DN<7>")
	)
	(segment
		(start 298.146216 -220.380306)
		(end 297.593512 -220.93301)
		(width 0.16002)
		(layer "In2.Cu")
		(net "M_C_CPU0_SA_DQS_DN<7>")
	)
	(segment
		(start 340.639654 -237.51921)
		(end 340.631272 -237.524036)
		(width 0.09525)
		(layer "In2.Cu")
		(net "M_C_CPU0_SA_DQS_DN<7>")
	)
	(segment
		(start 322.623434 -235.28274)
		(end 317.359538 -230.018844)
		(width 0.16002)
		(layer "In2.Cu")
		(net "M_C_CPU0_SA_DQS_DN<7>")
	)
	(arc
		(start 332.74254 -237.51921)
		(mid 332.461108 -237.443455)
		(end 332.179676 -237.51921)
		(width 0.09525)
		(layer "In2.Cu")
		(net "M_C_CPU0_SA_DQS_DN<7>")
	)
	(arc
		(start 337.819746 -237.51921)
		(mid 337.635971 -237.569982)
		(end 337.450938 -237.524036)
		(width 0.09525)
		(layer "In2.Cu")
		(net "M_C_CPU0_SA_DQS_DN<7>")
	)
	(arc
		(start 341.579708 -237.51921)
		(mid 341.395933 -237.569982)
		(end 341.2109 -237.524036)
		(width 0.09525)
		(layer "In2.Cu")
		(net "M_C_CPU0_SA_DQS_DN<7>")
	)
	(arc
		(start 334.059784 -237.51921)
		(mid 333.876009 -237.569982)
		(end 333.690976 -237.524036)
		(width 0.09525)
		(layer "In2.Cu")
		(net "M_C_CPU0_SA_DQS_DN<7>")
	)
	(arc
		(start 339.32241 -237.51921)
		(mid 339.040978 -237.443455)
		(end 338.759546 -237.51921)
		(width 0.09525)
		(layer "In2.Cu")
		(net "M_C_CPU0_SA_DQS_DN<7>")
	)
	(arc
		(start 328.982578 -237.51921)
		(mid 328.701146 -237.443455)
		(end 328.419714 -237.51921)
		(width 0.09525)
		(layer "In2.Cu")
		(net "M_C_CPU0_SA_DQS_DN<7>")
	)
	(arc
		(start 328.042524 -237.51921)
		(mid 327.906817 -237.462725)
		(end 327.761092 -237.443518)
		(width 0.09525)
		(layer "In2.Cu")
		(net "M_C_CPU0_SA_DQS_DN<7>")
	)
	(arc
		(start 340.631272 -237.524036)
		(mid 340.44624 -237.56995)
		(end 340.262464 -237.51921)
		(width 0.09525)
		(layer "In2.Cu")
		(net "M_C_CPU0_SA_DQS_DN<7>")
	)
	(arc
		(start 334.622648 -237.51921)
		(mid 334.341216 -237.443455)
		(end 334.059784 -237.51921)
		(width 0.09525)
		(layer "In2.Cu")
		(net "M_C_CPU0_SA_DQS_DN<7>")
	)
	(arc
		(start 326.658478 -236.6899)
		(mid 326.55023 -236.617508)
		(end 326.422512 -236.59211)
		(width 0.09525)
		(layer "In2.Cu")
		(net "M_C_CPU0_SA_DQS_DN<7>")
	)
	(arc
		(start 336.502502 -237.51921)
		(mid 336.22107 -237.443455)
		(end 335.939638 -237.51921)
		(width 0.09525)
		(layer "In2.Cu")
		(net "M_C_CPU0_SA_DQS_DN<7>")
	)
	(arc
		(start 331.802486 -237.51921)
		(mid 331.521054 -237.443455)
		(end 331.239622 -237.51921)
		(width 0.09525)
		(layer "In2.Cu")
		(net "M_C_CPU0_SA_DQS_DN<7>")
	)
	(arc
		(start 342.519762 -237.51921)
		(mid 342.335987 -237.569982)
		(end 342.150954 -237.524036)
		(width 0.09525)
		(layer "In2.Cu")
		(net "M_C_CPU0_SA_DQS_DN<7>")
	)
	(arc
		(start 331.23124 -237.524036)
		(mid 331.046208 -237.56995)
		(end 330.862432 -237.51921)
		(width 0.09525)
		(layer "In2.Cu")
		(net "M_C_CPU0_SA_DQS_DN<7>")
	)
	(arc
		(start 333.11973 -237.51921)
		(mid 332.935955 -237.569982)
		(end 332.750922 -237.524036)
		(width 0.09525)
		(layer "In2.Cu")
		(net "M_C_CPU0_SA_DQS_DN<7>")
	)
	(arc
		(start 336.87131 -237.524036)
		(mid 336.686278 -237.56995)
		(end 336.502502 -237.51921)
		(width 0.09525)
		(layer "In2.Cu")
		(net "M_C_CPU0_SA_DQS_DN<7>")
	)
	(arc
		(start 338.38261 -237.51921)
		(mid 338.101178 -237.443455)
		(end 337.819746 -237.51921)
		(width 0.09525)
		(layer "In2.Cu")
		(net "M_C_CPU0_SA_DQS_DN<7>")
	)
	(arc
		(start 335.931256 -237.524036)
		(mid 335.746224 -237.56995)
		(end 335.562448 -237.51921)
		(width 0.09525)
		(layer "In2.Cu")
		(net "M_C_CPU0_SA_DQS_DN<7>")
	)
	(arc
		(start 330.299568 -237.51921)
		(mid 330.1111 -237.569887)
		(end 329.922632 -237.51921)
		(width 0.09525)
		(layer "In2.Cu")
		(net "M_C_CPU0_SA_DQS_DN<7>")
	)
	(arc
		(start 330.862432 -237.51921)
		(mid 330.581 -237.443455)
		(end 330.299568 -237.51921)
		(width 0.09525)
		(layer "In2.Cu")
		(net "M_C_CPU0_SA_DQS_DN<7>")
	)
	(arc
		(start 333.682594 -237.51921)
		(mid 333.401162 -237.443455)
		(end 333.11973 -237.51921)
		(width 0.09525)
		(layer "In2.Cu")
		(net "M_C_CPU0_SA_DQS_DN<7>")
	)
	(arc
		(start 328.411332 -237.524036)
		(mid 328.2263 -237.56995)
		(end 328.042524 -237.51921)
		(width 0.09525)
		(layer "In2.Cu")
		(net "M_C_CPU0_SA_DQS_DN<7>")
	)
	(arc
		(start 335.562448 -237.51921)
		(mid 335.281016 -237.443455)
		(end 334.999584 -237.51921)
		(width 0.09525)
		(layer "In2.Cu")
		(net "M_C_CPU0_SA_DQS_DN<7>")
	)
	(arc
		(start 329.922632 -237.51921)
		(mid 329.6412 -237.443455)
		(end 329.359768 -237.51921)
		(width 0.09525)
		(layer "In2.Cu")
		(net "M_C_CPU0_SA_DQS_DN<7>")
	)
	(arc
		(start 343.401904 -237.546134)
		(mid 343.239253 -237.568394)
		(end 343.082626 -237.51921)
		(width 0.09525)
		(layer "In2.Cu")
		(net "M_C_CPU0_SA_DQS_DN<7>")
	)
	(arc
		(start 338.759546 -237.51921)
		(mid 338.571078 -237.569887)
		(end 338.38261 -237.51921)
		(width 0.09525)
		(layer "In2.Cu")
		(net "M_C_CPU0_SA_DQS_DN<7>")
	)
	(arc
		(start 337.442556 -237.51921)
		(mid 337.161124 -237.443455)
		(end 336.879692 -237.51921)
		(width 0.09525)
		(layer "In2.Cu")
		(net "M_C_CPU0_SA_DQS_DN<7>")
	)
	(arc
		(start 342.142572 -237.51921)
		(mid 341.86114 -237.443455)
		(end 341.579708 -237.51921)
		(width 0.09525)
		(layer "In2.Cu")
		(net "M_C_CPU0_SA_DQS_DN<7>")
	)
	(arc
		(start 332.171294 -237.524036)
		(mid 331.986262 -237.56995)
		(end 331.802486 -237.51921)
		(width 0.09525)
		(layer "In2.Cu")
		(net "M_C_CPU0_SA_DQS_DN<7>")
	)
	(arc
		(start 341.202518 -237.51921)
		(mid 340.921086 -237.443455)
		(end 340.639654 -237.51921)
		(width 0.09525)
		(layer "In2.Cu")
		(net "M_C_CPU0_SA_DQS_DN<7>")
	)
	(arc
		(start 339.691218 -237.524036)
		(mid 339.506186 -237.56995)
		(end 339.32241 -237.51921)
		(width 0.09525)
		(layer "In2.Cu")
		(net "M_C_CPU0_SA_DQS_DN<7>")
	)
	(arc
		(start 343.082626 -237.51921)
		(mid 342.801194 -237.443455)
		(end 342.519762 -237.51921)
		(width 0.09525)
		(layer "In2.Cu")
		(net "M_C_CPU0_SA_DQS_DN<7>")
	)
	(arc
		(start 334.999584 -237.51921)
		(mid 334.811116 -237.569887)
		(end 334.622648 -237.51921)
		(width 0.09525)
		(layer "In2.Cu")
		(net "M_C_CPU0_SA_DQS_DN<7>")
	)
	(arc
		(start 329.359768 -237.51921)
		(mid 329.175993 -237.569982)
		(end 328.99096 -237.524036)
		(width 0.09525)
		(layer "In2.Cu")
		(net "M_C_CPU0_SA_DQS_DN<7>")
	)
	(arc
		(start 340.262464 -237.51921)
		(mid 339.981032 -237.443455)
		(end 339.6996 -237.51921)
		(width 0.09525)
		(layer "In2.Cu")
		(net "M_C_CPU0_SA_DQS_DN<7>")
	)
	(segment
		(start 343.737946 -232.599992)
		(end 343.271094 -232.334054)
		(width 0.12954)
		(layer "F.Cu")
		(net "M_C_CPU0_SA_DQS_DN<6>")
	)
	(segment
		(start 290.04641 -211.009992)
		(end 289.847274 -211.209128)
		(width 0.16002)
		(layer "In2.Cu")
		(net "M_C_CPU0_SA_DQS_DN<6>")
	)
	(segment
		(start 309.072788 -211.200492)
		(end 308.955948 -211.317332)
		(width 0.16002)
		(layer "In2.Cu")
		(net "M_C_CPU0_SA_DQS_DN<6>")
	)
	(segment
		(start 294.705024 -212.207856)
		(end 294.114474 -211.617306)
		(width 0.16002)
		(layer "In2.Cu")
		(net "M_C_CPU0_SA_DQS_DN<6>")
	)
	(segment
		(start 324.514718 -227.547424)
		(end 324.491096 -227.547424)
		(width 0.09525)
		(layer "In2.Cu")
		(net "M_C_CPU0_SA_DQS_DN<6>")
	)
	(segment
		(start 327.102724 -231.039162)
		(end 327.068942 -231.019604)
		(width 0.09525)
		(layer "In2.Cu")
		(net "M_C_CPU0_SA_DQS_DN<6>")
	)
	(segment
		(start 324.491096 -227.547424)
		(end 323.99097 -227.547424)
		(width 0.16002)
		(layer "In2.Cu")
		(net "M_C_CPU0_SA_DQS_DN<6>")
	)
	(segment
		(start 296.478452 -212.207856)
		(end 294.705024 -212.207856)
		(width 0.16002)
		(layer "In2.Cu")
		(net "M_C_CPU0_SA_DQS_DN<6>")
	)
	(segment
		(start 294.114474 -211.617306)
		(end 291.779452 -211.617306)
		(width 0.16002)
		(layer "In2.Cu")
		(net "M_C_CPU0_SA_DQS_DN<6>")
	)
	(segment
		(start 301.43958 -211.357972)
		(end 299.08754 -211.357972)
		(width 0.16002)
		(layer "In2.Cu")
		(net "M_C_CPU0_SA_DQS_DN<6>")
	)
	(segment
		(start 326.6694 -230.250746)
		(end 326.632824 -230.22941)
		(width 0.09525)
		(layer "In2.Cu")
		(net "M_C_CPU0_SA_DQS_DN<6>")
	)
	(segment
		(start 332.179676 -232.659174)
		(end 332.171294 -232.664)
		(width 0.09525)
		(layer "In2.Cu")
		(net "M_C_CPU0_SA_DQS_DN<6>")
	)
	(segment
		(start 323.087238 -225.508312)
		(end 317.417958 -219.839032)
		(width 0.16002)
		(layer "In2.Cu")
		(net "M_C_CPU0_SA_DQS_DN<6>")
	)
	(segment
		(start 305.664108 -211.05876)
		(end 304.861976 -211.860892)
		(width 0.16002)
		(layer "In2.Cu")
		(net "M_C_CPU0_SA_DQS_DN<6>")
	)
	(segment
		(start 327.572624 -231.849168)
		(end 327.540112 -231.830372)
		(width 0.09525)
		(layer "In2.Cu")
		(net "M_C_CPU0_SA_DQS_DN<6>")
	)
	(segment
		(start 341.2109 -232.664)
		(end 341.202518 -232.659174)
		(width 0.09525)
		(layer "In2.Cu")
		(net "M_C_CPU0_SA_DQS_DN<6>")
	)
	(segment
		(start 317.417958 -219.839032)
		(end 317.417958 -218.066112)
		(width 0.16002)
		(layer "In2.Cu")
		(net "M_C_CPU0_SA_DQS_DN<6>")
	)
	(segment
		(start 326.20204 -229.44201)
		(end 326.16267 -229.41915)
		(width 0.09525)
		(layer "In2.Cu")
		(net "M_C_CPU0_SA_DQS_DN<6>")
	)
	(segment
		(start 317.417958 -218.066112)
		(end 310.669178 -211.317332)
		(width 0.16002)
		(layer "In2.Cu")
		(net "M_C_CPU0_SA_DQS_DN<6>")
	)
	(segment
		(start 323.087238 -226.643692)
		(end 323.087238 -225.508312)
		(width 0.16002)
		(layer "In2.Cu")
		(net "M_C_CPU0_SA_DQS_DN<6>")
	)
	(segment
		(start 331.239622 -232.659174)
		(end 331.23124 -232.664)
		(width 0.09525)
		(layer "In2.Cu")
		(net "M_C_CPU0_SA_DQS_DN<6>")
	)
	(segment
		(start 336.879692 -232.659174)
		(end 336.87131 -232.664)
		(width 0.09525)
		(layer "In2.Cu")
		(net "M_C_CPU0_SA_DQS_DN<6>")
	)
	(segment
		(start 343.271094 -232.334054)
		(end 343.425018 -232.599484)
		(width 0.09525)
		(layer "In2.Cu")
		(net "M_C_CPU0_SA_DQS_DN<6>")
	)
	(segment
		(start 310.669178 -211.317332)
		(end 309.669688 -211.317332)
		(width 0.16002)
		(layer "In2.Cu")
		(net "M_C_CPU0_SA_DQS_DN<6>")
	)
	(segment
		(start 299.08754 -211.357972)
		(end 298.75988 -211.030312)
		(width 0.16002)
		(layer "In2.Cu")
		(net "M_C_CPU0_SA_DQS_DN<6>")
	)
	(segment
		(start 327.610724 -231.871266)
		(end 327.572624 -231.849168)
		(width 0.09525)
		(layer "In2.Cu")
		(net "M_C_CPU0_SA_DQS_DN<6>")
	)
	(segment
		(start 297.292776 -211.883752)
		(end 296.802556 -211.883752)
		(width 0.16002)
		(layer "In2.Cu")
		(net "M_C_CPU0_SA_DQS_DN<6>")
	)
	(segment
		(start 291.779452 -211.617306)
		(end 291.172138 -211.009992)
		(width 0.16002)
		(layer "In2.Cu")
		(net "M_C_CPU0_SA_DQS_DN<6>")
	)
	(segment
		(start 340.639654 -232.659174)
		(end 340.631272 -232.664)
		(width 0.09525)
		(layer "In2.Cu")
		(net "M_C_CPU0_SA_DQS_DN<6>")
	)
	(segment
		(start 302.26254 -212.180932)
		(end 301.43958 -211.357972)
		(width 0.16002)
		(layer "In2.Cu")
		(net "M_C_CPU0_SA_DQS_DN<6>")
	)
	(segment
		(start 304.041556 -212.180932)
		(end 302.26254 -212.180932)
		(width 0.16002)
		(layer "In2.Cu")
		(net "M_C_CPU0_SA_DQS_DN<6>")
	)
	(segment
		(start 323.99097 -227.547424)
		(end 323.087238 -226.643692)
		(width 0.16002)
		(layer "In2.Cu")
		(net "M_C_CPU0_SA_DQS_DN<6>")
	)
	(segment
		(start 289.847274 -211.209128)
		(end 288.454084 -211.209128)
		(width 0.16002)
		(layer "In2.Cu")
		(net "M_C_CPU0_SA_DQS_DN<6>")
	)
	(segment
		(start 326.632824 -230.22941)
		(end 326.60336 -230.212392)
		(width 0.09525)
		(layer "In2.Cu")
		(net "M_C_CPU0_SA_DQS_DN<6>")
	)
	(segment
		(start 309.552848 -211.200492)
		(end 309.072788 -211.200492)
		(width 0.16002)
		(layer "In2.Cu")
		(net "M_C_CPU0_SA_DQS_DN<6>")
	)
	(segment
		(start 298.75988 -211.030312)
		(end 298.146216 -211.030312)
		(width 0.16002)
		(layer "In2.Cu")
		(net "M_C_CPU0_SA_DQS_DN<6>")
	)
	(segment
		(start 291.172138 -211.009992)
		(end 290.04641 -211.009992)
		(width 0.16002)
		(layer "In2.Cu")
		(net "M_C_CPU0_SA_DQS_DN<6>")
	)
	(segment
		(start 325.349108 -227.912168)
		(end 325.043546 -227.606352)
		(width 0.09525)
		(layer "In2.Cu")
		(net "M_C_CPU0_SA_DQS_DN<6>")
	)
	(segment
		(start 342.150954 -232.664)
		(end 342.142572 -232.659174)
		(width 0.09525)
		(layer "In2.Cu")
		(net "M_C_CPU0_SA_DQS_DN<6>")
	)
	(segment
		(start 306.318666 -211.05876)
		(end 305.664108 -211.05876)
		(width 0.16002)
		(layer "In2.Cu")
		(net "M_C_CPU0_SA_DQS_DN<6>")
	)
	(segment
		(start 309.669688 -211.317332)
		(end 309.552848 -211.200492)
		(width 0.16002)
		(layer "In2.Cu")
		(net "M_C_CPU0_SA_DQS_DN<6>")
	)
	(segment
		(start 337.450938 -232.664)
		(end 337.442556 -232.659174)
		(width 0.09525)
		(layer "In2.Cu")
		(net "M_C_CPU0_SA_DQS_DN<6>")
	)
	(segment
		(start 308.955948 -211.317332)
		(end 306.577238 -211.317332)
		(width 0.16002)
		(layer "In2.Cu")
		(net "M_C_CPU0_SA_DQS_DN<6>")
	)
	(segment
		(start 328.419714 -232.659174)
		(end 328.411332 -232.664)
		(width 0.09525)
		(layer "In2.Cu")
		(net "M_C_CPU0_SA_DQS_DN<6>")
	)
	(segment
		(start 343.425018 -232.599484)
		(end 343.401904 -232.686098)
		(width 0.09525)
		(layer "In2.Cu")
		(net "M_C_CPU0_SA_DQS_DN<6>")
	)
	(segment
		(start 288.454084 -211.209128)
		(end 288.180018 -210.935062)
		(width 0.16002)
		(layer "In2.Cu")
		(net "M_C_CPU0_SA_DQS_DN<6>")
	)
	(segment
		(start 298.146216 -211.030312)
		(end 297.292776 -211.883752)
		(width 0.16002)
		(layer "In2.Cu")
		(net "M_C_CPU0_SA_DQS_DN<6>")
	)
	(segment
		(start 335.939638 -232.659174)
		(end 335.931256 -232.664)
		(width 0.09525)
		(layer "In2.Cu")
		(net "M_C_CPU0_SA_DQS_DN<6>")
	)
	(segment
		(start 332.750922 -232.664)
		(end 332.74254 -232.659174)
		(width 0.09525)
		(layer "In2.Cu")
		(net "M_C_CPU0_SA_DQS_DN<6>")
	)
	(segment
		(start 296.802556 -211.883752)
		(end 296.478452 -212.207856)
		(width 0.16002)
		(layer "In2.Cu")
		(net "M_C_CPU0_SA_DQS_DN<6>")
	)
	(segment
		(start 304.861976 -211.860892)
		(end 304.361596 -211.860892)
		(width 0.16002)
		(layer "In2.Cu")
		(net "M_C_CPU0_SA_DQS_DN<6>")
	)
	(segment
		(start 304.361596 -211.860892)
		(end 304.041556 -212.180932)
		(width 0.16002)
		(layer "In2.Cu")
		(net "M_C_CPU0_SA_DQS_DN<6>")
	)
	(segment
		(start 326.16267 -229.41915)
		(end 326.130412 -229.400354)
		(width 0.09525)
		(layer "In2.Cu")
		(net "M_C_CPU0_SA_DQS_DN<6>")
	)
	(segment
		(start 339.6996 -232.659174)
		(end 339.691218 -232.664)
		(width 0.09525)
		(layer "In2.Cu")
		(net "M_C_CPU0_SA_DQS_DN<6>")
	)
	(segment
		(start 306.577238 -211.317332)
		(end 306.318666 -211.05876)
		(width 0.16002)
		(layer "In2.Cu")
		(net "M_C_CPU0_SA_DQS_DN<6>")
	)
	(segment
		(start 328.99096 -232.664)
		(end 328.982578 -232.659174)
		(width 0.09525)
		(layer "In2.Cu")
		(net "M_C_CPU0_SA_DQS_DN<6>")
	)
	(segment
		(start 327.137776 -231.059736)
		(end 327.102724 -231.039162)
		(width 0.09525)
		(layer "In2.Cu")
		(net "M_C_CPU0_SA_DQS_DN<6>")
	)
	(segment
		(start 324.573646 -227.606352)
		(end 324.514718 -227.547424)
		(width 0.09525)
		(layer "In2.Cu")
		(net "M_C_CPU0_SA_DQS_DN<6>")
	)
	(segment
		(start 333.690976 -232.664)
		(end 333.682594 -232.659174)
		(width 0.09525)
		(layer "In2.Cu")
		(net "M_C_CPU0_SA_DQS_DN<6>")
	)
	(segment
		(start 325.043546 -227.606352)
		(end 324.573646 -227.606352)
		(width 0.09525)
		(layer "In2.Cu")
		(net "M_C_CPU0_SA_DQS_DN<6>")
	)
	(segment
		(start 328.042524 -232.659174)
		(end 328.011028 -232.640886)
		(width 0.09525)
		(layer "In2.Cu")
		(net "M_C_CPU0_SA_DQS_DN<6>")
	)
	(arc
		(start 325.973694 -229.094284)
		(mid 325.908862 -228.831959)
		(end 325.729092 -228.630226)
		(width 0.09525)
		(layer "In2.Cu")
		(net "M_C_CPU0_SA_DQS_DN<6>")
	)
	(arc
		(start 331.23124 -232.664)
		(mid 331.046208 -232.709914)
		(end 330.862432 -232.659174)
		(width 0.09525)
		(layer "In2.Cu")
		(net "M_C_CPU0_SA_DQS_DN<6>")
	)
	(arc
		(start 327.853548 -232.334054)
		(mid 327.789151 -232.072748)
		(end 327.610724 -231.871266)
		(width 0.09525)
		(layer "In2.Cu")
		(net "M_C_CPU0_SA_DQS_DN<6>")
	)
	(arc
		(start 328.411332 -232.664)
		(mid 328.2263 -232.709914)
		(end 328.042524 -232.659174)
		(width 0.09525)
		(layer "In2.Cu")
		(net "M_C_CPU0_SA_DQS_DN<6>")
	)
	(arc
		(start 331.802486 -232.659174)
		(mid 331.521054 -232.583419)
		(end 331.239622 -232.659174)
		(width 0.09525)
		(layer "In2.Cu")
		(net "M_C_CPU0_SA_DQS_DN<6>")
	)
	(arc
		(start 334.999584 -232.659174)
		(mid 334.811116 -232.709851)
		(end 334.622648 -232.659174)
		(width 0.09525)
		(layer "In2.Cu")
		(net "M_C_CPU0_SA_DQS_DN<6>")
	)
	(arc
		(start 334.622648 -232.659174)
		(mid 334.341216 -232.583419)
		(end 334.059784 -232.659174)
		(width 0.09525)
		(layer "In2.Cu")
		(net "M_C_CPU0_SA_DQS_DN<6>")
	)
	(arc
		(start 336.87131 -232.664)
		(mid 336.686278 -232.709914)
		(end 336.502502 -232.659174)
		(width 0.09525)
		(layer "In2.Cu")
		(net "M_C_CPU0_SA_DQS_DN<6>")
	)
	(arc
		(start 336.502502 -232.659174)
		(mid 336.22107 -232.583419)
		(end 335.939638 -232.659174)
		(width 0.09525)
		(layer "In2.Cu")
		(net "M_C_CPU0_SA_DQS_DN<6>")
	)
	(arc
		(start 337.442556 -232.659174)
		(mid 337.161124 -232.583419)
		(end 336.879692 -232.659174)
		(width 0.09525)
		(layer "In2.Cu")
		(net "M_C_CPU0_SA_DQS_DN<6>")
	)
	(arc
		(start 330.862432 -232.659174)
		(mid 330.581 -232.583419)
		(end 330.299568 -232.659174)
		(width 0.09525)
		(layer "In2.Cu")
		(net "M_C_CPU0_SA_DQS_DN<6>")
	)
	(arc
		(start 329.922632 -232.659174)
		(mid 329.6412 -232.583419)
		(end 329.359768 -232.659174)
		(width 0.09525)
		(layer "In2.Cu")
		(net "M_C_CPU0_SA_DQS_DN<6>")
	)
	(arc
		(start 329.359768 -232.659174)
		(mid 329.175993 -232.709946)
		(end 328.99096 -232.664)
		(width 0.09525)
		(layer "In2.Cu")
		(net "M_C_CPU0_SA_DQS_DN<6>")
	)
	(arc
		(start 340.262464 -232.659174)
		(mid 339.981032 -232.583419)
		(end 339.6996 -232.659174)
		(width 0.09525)
		(layer "In2.Cu")
		(net "M_C_CPU0_SA_DQS_DN<6>")
	)
	(arc
		(start 327.383394 -231.524048)
		(mid 327.318201 -231.261419)
		(end 327.137776 -231.059736)
		(width 0.09525)
		(layer "In2.Cu")
		(net "M_C_CPU0_SA_DQS_DN<6>")
	)
	(arc
		(start 325.729092 -228.630226)
		(mid 325.571436 -228.460785)
		(end 325.501762 -228.240082)
		(width 0.09525)
		(layer "In2.Cu")
		(net "M_C_CPU0_SA_DQS_DN<6>")
	)
	(arc
		(start 333.11973 -232.659174)
		(mid 332.935955 -232.709946)
		(end 332.750922 -232.664)
		(width 0.09525)
		(layer "In2.Cu")
		(net "M_C_CPU0_SA_DQS_DN<6>")
	)
	(arc
		(start 338.759546 -232.659174)
		(mid 338.571078 -232.709851)
		(end 338.38261 -232.659174)
		(width 0.09525)
		(layer "In2.Cu")
		(net "M_C_CPU0_SA_DQS_DN<6>")
	)
	(arc
		(start 328.982578 -232.659174)
		(mid 328.701146 -232.583419)
		(end 328.419714 -232.659174)
		(width 0.09525)
		(layer "In2.Cu")
		(net "M_C_CPU0_SA_DQS_DN<6>")
	)
	(arc
		(start 342.142572 -232.659174)
		(mid 341.86114 -232.583419)
		(end 341.579708 -232.659174)
		(width 0.09525)
		(layer "In2.Cu")
		(net "M_C_CPU0_SA_DQS_DN<6>")
	)
	(arc
		(start 343.401904 -232.686098)
		(mid 343.239253 -232.708358)
		(end 343.082626 -232.659174)
		(width 0.09525)
		(layer "In2.Cu")
		(net "M_C_CPU0_SA_DQS_DN<6>")
	)
	(arc
		(start 326.130412 -229.400354)
		(mid 326.015138 -229.266218)
		(end 325.973694 -229.094284)
		(width 0.09525)
		(layer "In2.Cu")
		(net "M_C_CPU0_SA_DQS_DN<6>")
	)
	(arc
		(start 340.631272 -232.664)
		(mid 340.44624 -232.709914)
		(end 340.262464 -232.659174)
		(width 0.09525)
		(layer "In2.Cu")
		(net "M_C_CPU0_SA_DQS_DN<6>")
	)
	(arc
		(start 342.519762 -232.659174)
		(mid 342.335987 -232.709946)
		(end 342.150954 -232.664)
		(width 0.09525)
		(layer "In2.Cu")
		(net "M_C_CPU0_SA_DQS_DN<6>")
	)
	(arc
		(start 325.501762 -228.240082)
		(mid 325.454478 -228.062606)
		(end 325.349108 -227.912168)
		(width 0.09525)
		(layer "In2.Cu")
		(net "M_C_CPU0_SA_DQS_DN<6>")
	)
	(arc
		(start 343.082626 -232.659174)
		(mid 342.801194 -232.583419)
		(end 342.519762 -232.659174)
		(width 0.09525)
		(layer "In2.Cu")
		(net "M_C_CPU0_SA_DQS_DN<6>")
	)
	(arc
		(start 332.171294 -232.664)
		(mid 331.986262 -232.709914)
		(end 331.802486 -232.659174)
		(width 0.09525)
		(layer "In2.Cu")
		(net "M_C_CPU0_SA_DQS_DN<6>")
	)
	(arc
		(start 335.931256 -232.664)
		(mid 335.746224 -232.709914)
		(end 335.562448 -232.659174)
		(width 0.09525)
		(layer "In2.Cu")
		(net "M_C_CPU0_SA_DQS_DN<6>")
	)
	(arc
		(start 327.068942 -231.019604)
		(mid 326.954563 -230.885465)
		(end 326.913494 -230.714042)
		(width 0.09525)
		(layer "In2.Cu")
		(net "M_C_CPU0_SA_DQS_DN<6>")
	)
	(arc
		(start 326.443848 -229.904036)
		(mid 326.379746 -229.643292)
		(end 326.20204 -229.44201)
		(width 0.09525)
		(layer "In2.Cu")
		(net "M_C_CPU0_SA_DQS_DN<6>")
	)
	(arc
		(start 327.540112 -231.830372)
		(mid 327.424838 -231.696094)
		(end 327.383394 -231.524048)
		(width 0.09525)
		(layer "In2.Cu")
		(net "M_C_CPU0_SA_DQS_DN<6>")
	)
	(arc
		(start 338.38261 -232.659174)
		(mid 338.101178 -232.583419)
		(end 337.819746 -232.659174)
		(width 0.09525)
		(layer "In2.Cu")
		(net "M_C_CPU0_SA_DQS_DN<6>")
	)
	(arc
		(start 334.059784 -232.659174)
		(mid 333.876009 -232.709946)
		(end 333.690976 -232.664)
		(width 0.09525)
		(layer "In2.Cu")
		(net "M_C_CPU0_SA_DQS_DN<6>")
	)
	(arc
		(start 341.579708 -232.659174)
		(mid 341.395933 -232.709946)
		(end 341.2109 -232.664)
		(width 0.09525)
		(layer "In2.Cu")
		(net "M_C_CPU0_SA_DQS_DN<6>")
	)
	(arc
		(start 330.299568 -232.659174)
		(mid 330.1111 -232.709851)
		(end 329.922632 -232.659174)
		(width 0.09525)
		(layer "In2.Cu")
		(net "M_C_CPU0_SA_DQS_DN<6>")
	)
	(arc
		(start 339.691218 -232.664)
		(mid 339.506186 -232.709914)
		(end 339.32241 -232.659174)
		(width 0.09525)
		(layer "In2.Cu")
		(net "M_C_CPU0_SA_DQS_DN<6>")
	)
	(arc
		(start 339.32241 -232.659174)
		(mid 339.040978 -232.583419)
		(end 338.759546 -232.659174)
		(width 0.09525)
		(layer "In2.Cu")
		(net "M_C_CPU0_SA_DQS_DN<6>")
	)
	(arc
		(start 333.682594 -232.659174)
		(mid 333.401162 -232.583419)
		(end 333.11973 -232.659174)
		(width 0.09525)
		(layer "In2.Cu")
		(net "M_C_CPU0_SA_DQS_DN<6>")
	)
	(arc
		(start 332.74254 -232.659174)
		(mid 332.461108 -232.583419)
		(end 332.179676 -232.659174)
		(width 0.09525)
		(layer "In2.Cu")
		(net "M_C_CPU0_SA_DQS_DN<6>")
	)
	(arc
		(start 335.562448 -232.659174)
		(mid 335.281016 -232.583419)
		(end 334.999584 -232.659174)
		(width 0.09525)
		(layer "In2.Cu")
		(net "M_C_CPU0_SA_DQS_DN<6>")
	)
	(arc
		(start 326.60336 -230.212392)
		(mid 326.486056 -230.077631)
		(end 326.443848 -229.904036)
		(width 0.09525)
		(layer "In2.Cu")
		(net "M_C_CPU0_SA_DQS_DN<6>")
	)
	(arc
		(start 341.202518 -232.659174)
		(mid 340.921086 -232.583419)
		(end 340.639654 -232.659174)
		(width 0.09525)
		(layer "In2.Cu")
		(net "M_C_CPU0_SA_DQS_DN<6>")
	)
	(arc
		(start 328.011028 -232.640886)
		(mid 327.89523 -232.506492)
		(end 327.853548 -232.334054)
		(width 0.09525)
		(layer "In2.Cu")
		(net "M_C_CPU0_SA_DQS_DN<6>")
	)
	(arc
		(start 326.913494 -230.714042)
		(mid 326.848694 -230.452223)
		(end 326.6694 -230.250746)
		(width 0.09525)
		(layer "In2.Cu")
		(net "M_C_CPU0_SA_DQS_DN<6>")
	)
	(arc
		(start 337.819746 -232.659174)
		(mid 337.635971 -232.709946)
		(end 337.450938 -232.664)
		(width 0.09525)
		(layer "In2.Cu")
		(net "M_C_CPU0_SA_DQS_DN<6>")
	)
	(segment
		(start 343.737946 -227.74021)
		(end 343.271094 -227.474272)
		(width 0.12954)
		(layer "F.Cu")
		(net "M_C_CPU0_SA_DQS_DN<5>")
	)
	(segment
		(start 288.454084 -201.859134)
		(end 289.847274 -201.859134)
		(width 0.16002)
		(layer "In2.Cu")
		(net "M_C_CPU0_SA_DQS_DN<5>")
	)
	(segment
		(start 304.041556 -202.830938)
		(end 304.361596 -202.510898)
		(width 0.16002)
		(layer "In2.Cu")
		(net "M_C_CPU0_SA_DQS_DN<5>")
	)
	(segment
		(start 329.922632 -226.17938)
		(end 329.957684 -226.199954)
		(width 0.09525)
		(layer "In2.Cu")
		(net "M_C_CPU0_SA_DQS_DN<5>")
	)
	(segment
		(start 332.74254 -227.799392)
		(end 332.750922 -227.804218)
		(width 0.09525)
		(layer "In2.Cu")
		(net "M_C_CPU0_SA_DQS_DN<5>")
	)
	(segment
		(start 328.043032 -222.939356)
		(end 328.07656 -222.958914)
		(width 0.09525)
		(layer "In2.Cu")
		(net "M_C_CPU0_SA_DQS_DN<5>")
	)
	(segment
		(start 288.180018 -201.585068)
		(end 288.454084 -201.859134)
		(width 0.16002)
		(layer "In2.Cu")
		(net "M_C_CPU0_SA_DQS_DN<5>")
	)
	(segment
		(start 320.047112 -211.390992)
		(end 320.047112 -212.048344)
		(width 0.16002)
		(layer "In2.Cu")
		(net "M_C_CPU0_SA_DQS_DN<5>")
	)
	(segment
		(start 311.77611 -203.11999)
		(end 320.047112 -211.390992)
		(width 0.16002)
		(layer "In2.Cu")
		(net "M_C_CPU0_SA_DQS_DN<5>")
	)
	(segment
		(start 329.452478 -225.369374)
		(end 329.490578 -225.391472)
		(width 0.09525)
		(layer "In2.Cu")
		(net "M_C_CPU0_SA_DQS_DN<5>")
	)
	(segment
		(start 327.572624 -222.12935)
		(end 327.611994 -222.15221)
		(width 0.09525)
		(layer "In2.Cu")
		(net "M_C_CPU0_SA_DQS_DN<5>")
	)
	(segment
		(start 291.172138 -201.659998)
		(end 291.779452 -202.267312)
		(width 0.16002)
		(layer "In2.Cu")
		(net "M_C_CPU0_SA_DQS_DN<5>")
	)
	(segment
		(start 304.861976 -202.510898)
		(end 305.664108 -201.708766)
		(width 0.16002)
		(layer "In2.Cu")
		(net "M_C_CPU0_SA_DQS_DN<5>")
	)
	(segment
		(start 342.142572 -227.799392)
		(end 342.150954 -227.804218)
		(width 0.09525)
		(layer "In2.Cu")
		(net "M_C_CPU0_SA_DQS_DN<5>")
	)
	(segment
		(start 343.401904 -227.826316)
		(end 343.425018 -227.739702)
		(width 0.09525)
		(layer "In2.Cu")
		(net "M_C_CPU0_SA_DQS_DN<5>")
	)
	(segment
		(start 327.442322 -221.17431)
		(end 327.442322 -221.197932)
		(width 0.09525)
		(layer "In2.Cu")
		(net "M_C_CPU0_SA_DQS_DN<5>")
	)
	(segment
		(start 299.08754 -202.007978)
		(end 301.43958 -202.007978)
		(width 0.16002)
		(layer "In2.Cu")
		(net "M_C_CPU0_SA_DQS_DN<5>")
	)
	(segment
		(start 308.503574 -201.967338)
		(end 309.656226 -203.11999)
		(width 0.16002)
		(layer "In2.Cu")
		(net "M_C_CPU0_SA_DQS_DN<5>")
	)
	(segment
		(start 306.577238 -201.967338)
		(end 308.503574 -201.967338)
		(width 0.16002)
		(layer "In2.Cu")
		(net "M_C_CPU0_SA_DQS_DN<5>")
	)
	(segment
		(start 340.631272 -227.804218)
		(end 340.639654 -227.799392)
		(width 0.09525)
		(layer "In2.Cu")
		(net "M_C_CPU0_SA_DQS_DN<5>")
	)
	(segment
		(start 330.830936 -227.781104)
		(end 330.862432 -227.799392)
		(width 0.09525)
		(layer "In2.Cu")
		(net "M_C_CPU0_SA_DQS_DN<5>")
	)
	(segment
		(start 327.442322 -219.443554)
		(end 327.442322 -221.17431)
		(width 0.16002)
		(layer "In2.Cu")
		(net "M_C_CPU0_SA_DQS_DN<5>")
	)
	(segment
		(start 298.75988 -201.680318)
		(end 299.08754 -202.007978)
		(width 0.16002)
		(layer "In2.Cu")
		(net "M_C_CPU0_SA_DQS_DN<5>")
	)
	(segment
		(start 290.04641 -201.659998)
		(end 291.172138 -201.659998)
		(width 0.16002)
		(layer "In2.Cu")
		(net "M_C_CPU0_SA_DQS_DN<5>")
	)
	(segment
		(start 332.171294 -227.804218)
		(end 332.179676 -227.799392)
		(width 0.09525)
		(layer "In2.Cu")
		(net "M_C_CPU0_SA_DQS_DN<5>")
	)
	(segment
		(start 294.058594 -202.267312)
		(end 294.649144 -202.857862)
		(width 0.16002)
		(layer "In2.Cu")
		(net "M_C_CPU0_SA_DQS_DN<5>")
	)
	(segment
		(start 327.383394 -221.25686)
		(end 327.383394 -221.803976)
		(width 0.09525)
		(layer "In2.Cu")
		(net "M_C_CPU0_SA_DQS_DN<5>")
	)
	(segment
		(start 296.802556 -202.533758)
		(end 297.292776 -202.533758)
		(width 0.16002)
		(layer "In2.Cu")
		(net "M_C_CPU0_SA_DQS_DN<5>")
	)
	(segment
		(start 297.292776 -202.533758)
		(end 298.146216 -201.680318)
		(width 0.16002)
		(layer "In2.Cu")
		(net "M_C_CPU0_SA_DQS_DN<5>")
	)
	(segment
		(start 330.392532 -226.989386)
		(end 330.430632 -227.011484)
		(width 0.09525)
		(layer "In2.Cu")
		(net "M_C_CPU0_SA_DQS_DN<5>")
	)
	(segment
		(start 298.146216 -201.680318)
		(end 298.75988 -201.680318)
		(width 0.16002)
		(layer "In2.Cu")
		(net "M_C_CPU0_SA_DQS_DN<5>")
	)
	(segment
		(start 320.047112 -212.048344)
		(end 327.442322 -219.443554)
		(width 0.16002)
		(layer "In2.Cu")
		(net "M_C_CPU0_SA_DQS_DN<5>")
	)
	(segment
		(start 337.442556 -227.799392)
		(end 337.450938 -227.804218)
		(width 0.09525)
		(layer "In2.Cu")
		(net "M_C_CPU0_SA_DQS_DN<5>")
	)
	(segment
		(start 302.26254 -202.830938)
		(end 304.041556 -202.830938)
		(width 0.16002)
		(layer "In2.Cu")
		(net "M_C_CPU0_SA_DQS_DN<5>")
	)
	(segment
		(start 301.43958 -202.007978)
		(end 302.26254 -202.830938)
		(width 0.16002)
		(layer "In2.Cu")
		(net "M_C_CPU0_SA_DQS_DN<5>")
	)
	(segment
		(start 328.512678 -223.749362)
		(end 328.54773 -223.769936)
		(width 0.09525)
		(layer "In2.Cu")
		(net "M_C_CPU0_SA_DQS_DN<5>")
	)
	(segment
		(start 329.420982 -225.351086)
		(end 329.452478 -225.369374)
		(width 0.09525)
		(layer "In2.Cu")
		(net "M_C_CPU0_SA_DQS_DN<5>")
	)
	(segment
		(start 328.950066 -224.540572)
		(end 328.982578 -224.559368)
		(width 0.09525)
		(layer "In2.Cu")
		(net "M_C_CPU0_SA_DQS_DN<5>")
	)
	(segment
		(start 294.649144 -202.857862)
		(end 296.478452 -202.857862)
		(width 0.16002)
		(layer "In2.Cu")
		(net "M_C_CPU0_SA_DQS_DN<5>")
	)
	(segment
		(start 328.480166 -223.730566)
		(end 328.512678 -223.749362)
		(width 0.09525)
		(layer "In2.Cu")
		(net "M_C_CPU0_SA_DQS_DN<5>")
	)
	(segment
		(start 327.442322 -221.197932)
		(end 327.383394 -221.25686)
		(width 0.09525)
		(layer "In2.Cu")
		(net "M_C_CPU0_SA_DQS_DN<5>")
	)
	(segment
		(start 329.89012 -226.160584)
		(end 329.922632 -226.17938)
		(width 0.09525)
		(layer "In2.Cu")
		(net "M_C_CPU0_SA_DQS_DN<5>")
	)
	(segment
		(start 336.87131 -227.804218)
		(end 336.879692 -227.799392)
		(width 0.09525)
		(layer "In2.Cu")
		(net "M_C_CPU0_SA_DQS_DN<5>")
	)
	(segment
		(start 327.47966 -222.035878)
		(end 327.572624 -222.12935)
		(width 0.09525)
		(layer "In2.Cu")
		(net "M_C_CPU0_SA_DQS_DN<5>")
	)
	(segment
		(start 335.931256 -227.804218)
		(end 335.939638 -227.799392)
		(width 0.09525)
		(layer "In2.Cu")
		(net "M_C_CPU0_SA_DQS_DN<5>")
	)
	(segment
		(start 291.779452 -202.267312)
		(end 294.058594 -202.267312)
		(width 0.16002)
		(layer "In2.Cu")
		(net "M_C_CPU0_SA_DQS_DN<5>")
	)
	(segment
		(start 328.00925 -222.919798)
		(end 328.043032 -222.939356)
		(width 0.09525)
		(layer "In2.Cu")
		(net "M_C_CPU0_SA_DQS_DN<5>")
	)
	(segment
		(start 328.982578 -224.559368)
		(end 329.020678 -224.581466)
		(width 0.09525)
		(layer "In2.Cu")
		(net "M_C_CPU0_SA_DQS_DN<5>")
	)
	(segment
		(start 309.656226 -203.11999)
		(end 311.77611 -203.11999)
		(width 0.16002)
		(layer "In2.Cu")
		(net "M_C_CPU0_SA_DQS_DN<5>")
	)
	(segment
		(start 330.36002 -226.97059)
		(end 330.392532 -226.989386)
		(width 0.09525)
		(layer "In2.Cu")
		(net "M_C_CPU0_SA_DQS_DN<5>")
	)
	(segment
		(start 296.478452 -202.857862)
		(end 296.802556 -202.533758)
		(width 0.16002)
		(layer "In2.Cu")
		(net "M_C_CPU0_SA_DQS_DN<5>")
	)
	(segment
		(start 331.23124 -227.804218)
		(end 331.239622 -227.799392)
		(width 0.09525)
		(layer "In2.Cu")
		(net "M_C_CPU0_SA_DQS_DN<5>")
	)
	(segment
		(start 305.664108 -201.708766)
		(end 306.318666 -201.708766)
		(width 0.16002)
		(layer "In2.Cu")
		(net "M_C_CPU0_SA_DQS_DN<5>")
	)
	(segment
		(start 333.682594 -227.799392)
		(end 333.690976 -227.804218)
		(width 0.09525)
		(layer "In2.Cu")
		(net "M_C_CPU0_SA_DQS_DN<5>")
	)
	(segment
		(start 341.202518 -227.799392)
		(end 341.2109 -227.804218)
		(width 0.09525)
		(layer "In2.Cu")
		(net "M_C_CPU0_SA_DQS_DN<5>")
	)
	(segment
		(start 289.847274 -201.859134)
		(end 290.04641 -201.659998)
		(width 0.16002)
		(layer "In2.Cu")
		(net "M_C_CPU0_SA_DQS_DN<5>")
	)
	(segment
		(start 306.318666 -201.708766)
		(end 306.577238 -201.967338)
		(width 0.16002)
		(layer "In2.Cu")
		(net "M_C_CPU0_SA_DQS_DN<5>")
	)
	(segment
		(start 327.479406 -222.035878)
		(end 327.47966 -222.035878)
		(width 0.09525)
		(layer "In2.Cu")
		(net "M_C_CPU0_SA_DQS_DN<5>")
	)
	(segment
		(start 304.361596 -202.510898)
		(end 304.861976 -202.510898)
		(width 0.16002)
		(layer "In2.Cu")
		(net "M_C_CPU0_SA_DQS_DN<5>")
	)
	(segment
		(start 339.691218 -227.804218)
		(end 339.6996 -227.799392)
		(width 0.09525)
		(layer "In2.Cu")
		(net "M_C_CPU0_SA_DQS_DN<5>")
	)
	(segment
		(start 343.425018 -227.739702)
		(end 343.271094 -227.474272)
		(width 0.09525)
		(layer "In2.Cu")
		(net "M_C_CPU0_SA_DQS_DN<5>")
	)
	(arc
		(start 338.38261 -227.799392)
		(mid 338.571078 -227.850069)
		(end 338.759546 -227.799392)
		(width 0.09525)
		(layer "In2.Cu")
		(net "M_C_CPU0_SA_DQS_DN<5>")
	)
	(arc
		(start 340.639654 -227.799392)
		(mid 340.921086 -227.723637)
		(end 341.202518 -227.799392)
		(width 0.09525)
		(layer "In2.Cu")
		(net "M_C_CPU0_SA_DQS_DN<5>")
	)
	(arc
		(start 328.793348 -224.234248)
		(mid 328.834805 -224.406288)
		(end 328.950066 -224.540572)
		(width 0.09525)
		(layer "In2.Cu")
		(net "M_C_CPU0_SA_DQS_DN<5>")
	)
	(arc
		(start 337.819746 -227.799392)
		(mid 338.101178 -227.723637)
		(end 338.38261 -227.799392)
		(width 0.09525)
		(layer "In2.Cu")
		(net "M_C_CPU0_SA_DQS_DN<5>")
	)
	(arc
		(start 330.862432 -227.799392)
		(mid 331.046207 -227.850164)
		(end 331.23124 -227.804218)
		(width 0.09525)
		(layer "In2.Cu")
		(net "M_C_CPU0_SA_DQS_DN<5>")
	)
	(arc
		(start 333.11973 -227.799392)
		(mid 333.401162 -227.723637)
		(end 333.682594 -227.799392)
		(width 0.09525)
		(layer "In2.Cu")
		(net "M_C_CPU0_SA_DQS_DN<5>")
	)
	(arc
		(start 331.239622 -227.799392)
		(mid 331.521054 -227.723637)
		(end 331.802486 -227.799392)
		(width 0.09525)
		(layer "In2.Cu")
		(net "M_C_CPU0_SA_DQS_DN<5>")
	)
	(arc
		(start 329.263502 -225.044254)
		(mid 329.305167 -225.216701)
		(end 329.420982 -225.351086)
		(width 0.09525)
		(layer "In2.Cu")
		(net "M_C_CPU0_SA_DQS_DN<5>")
	)
	(arc
		(start 332.750922 -227.804218)
		(mid 332.935954 -227.850132)
		(end 333.11973 -227.799392)
		(width 0.09525)
		(layer "In2.Cu")
		(net "M_C_CPU0_SA_DQS_DN<5>")
	)
	(arc
		(start 342.519762 -227.799392)
		(mid 342.801194 -227.723637)
		(end 343.082626 -227.799392)
		(width 0.09525)
		(layer "In2.Cu")
		(net "M_C_CPU0_SA_DQS_DN<5>")
	)
	(arc
		(start 338.759546 -227.799392)
		(mid 339.040978 -227.723637)
		(end 339.32241 -227.799392)
		(width 0.09525)
		(layer "In2.Cu")
		(net "M_C_CPU0_SA_DQS_DN<5>")
	)
	(arc
		(start 328.54773 -223.769936)
		(mid 328.728185 -223.971602)
		(end 328.793348 -224.234248)
		(width 0.09525)
		(layer "In2.Cu")
		(net "M_C_CPU0_SA_DQS_DN<5>")
	)
	(arc
		(start 327.853802 -222.614236)
		(mid 327.894904 -222.785642)
		(end 328.00925 -222.919798)
		(width 0.09525)
		(layer "In2.Cu")
		(net "M_C_CPU0_SA_DQS_DN<5>")
	)
	(arc
		(start 341.2109 -227.804218)
		(mid 341.395932 -227.850132)
		(end 341.579708 -227.799392)
		(width 0.09525)
		(layer "In2.Cu")
		(net "M_C_CPU0_SA_DQS_DN<5>")
	)
	(arc
		(start 330.430632 -227.011484)
		(mid 330.609082 -227.212954)
		(end 330.673456 -227.474272)
		(width 0.09525)
		(layer "In2.Cu")
		(net "M_C_CPU0_SA_DQS_DN<5>")
	)
	(arc
		(start 343.082626 -227.799392)
		(mid 343.239253 -227.848578)
		(end 343.401904 -227.826316)
		(width 0.09525)
		(layer "In2.Cu")
		(net "M_C_CPU0_SA_DQS_DN<5>")
	)
	(arc
		(start 333.690976 -227.804218)
		(mid 333.876008 -227.850132)
		(end 334.059784 -227.799392)
		(width 0.09525)
		(layer "In2.Cu")
		(net "M_C_CPU0_SA_DQS_DN<5>")
	)
	(arc
		(start 340.262464 -227.799392)
		(mid 340.446239 -227.850164)
		(end 340.631272 -227.804218)
		(width 0.09525)
		(layer "In2.Cu")
		(net "M_C_CPU0_SA_DQS_DN<5>")
	)
	(arc
		(start 336.879692 -227.799392)
		(mid 337.161124 -227.723637)
		(end 337.442556 -227.799392)
		(width 0.09525)
		(layer "In2.Cu")
		(net "M_C_CPU0_SA_DQS_DN<5>")
	)
	(arc
		(start 329.490578 -225.391472)
		(mid 329.669028 -225.592942)
		(end 329.733402 -225.85426)
		(width 0.09525)
		(layer "In2.Cu")
		(net "M_C_CPU0_SA_DQS_DN<5>")
	)
	(arc
		(start 328.07656 -222.958914)
		(mid 328.257939 -223.160846)
		(end 328.323448 -223.424242)
		(width 0.09525)
		(layer "In2.Cu")
		(net "M_C_CPU0_SA_DQS_DN<5>")
	)
	(arc
		(start 329.020678 -224.581466)
		(mid 329.199128 -224.782936)
		(end 329.263502 -225.044254)
		(width 0.09525)
		(layer "In2.Cu")
		(net "M_C_CPU0_SA_DQS_DN<5>")
	)
	(arc
		(start 334.059784 -227.799392)
		(mid 334.341216 -227.723637)
		(end 334.622648 -227.799392)
		(width 0.09525)
		(layer "In2.Cu")
		(net "M_C_CPU0_SA_DQS_DN<5>")
	)
	(arc
		(start 332.179676 -227.799392)
		(mid 332.461108 -227.723637)
		(end 332.74254 -227.799392)
		(width 0.09525)
		(layer "In2.Cu")
		(net "M_C_CPU0_SA_DQS_DN<5>")
	)
	(arc
		(start 342.150954 -227.804218)
		(mid 342.335986 -227.850132)
		(end 342.519762 -227.799392)
		(width 0.09525)
		(layer "In2.Cu")
		(net "M_C_CPU0_SA_DQS_DN<5>")
	)
	(arc
		(start 337.450938 -227.804218)
		(mid 337.63597 -227.850132)
		(end 337.819746 -227.799392)
		(width 0.09525)
		(layer "In2.Cu")
		(net "M_C_CPU0_SA_DQS_DN<5>")
	)
	(arc
		(start 339.6996 -227.799392)
		(mid 339.981032 -227.723637)
		(end 340.262464 -227.799392)
		(width 0.09525)
		(layer "In2.Cu")
		(net "M_C_CPU0_SA_DQS_DN<5>")
	)
	(arc
		(start 334.622648 -227.799392)
		(mid 334.811116 -227.850069)
		(end 334.999584 -227.799392)
		(width 0.09525)
		(layer "In2.Cu")
		(net "M_C_CPU0_SA_DQS_DN<5>")
	)
	(arc
		(start 329.733402 -225.85426)
		(mid 329.774859 -226.0263)
		(end 329.89012 -226.160584)
		(width 0.09525)
		(layer "In2.Cu")
		(net "M_C_CPU0_SA_DQS_DN<5>")
	)
	(arc
		(start 331.802486 -227.799392)
		(mid 331.986261 -227.850164)
		(end 332.171294 -227.804218)
		(width 0.09525)
		(layer "In2.Cu")
		(net "M_C_CPU0_SA_DQS_DN<5>")
	)
	(arc
		(start 335.562448 -227.799392)
		(mid 335.746223 -227.850164)
		(end 335.931256 -227.804218)
		(width 0.09525)
		(layer "In2.Cu")
		(net "M_C_CPU0_SA_DQS_DN<5>")
	)
	(arc
		(start 339.32241 -227.799392)
		(mid 339.506185 -227.850164)
		(end 339.691218 -227.804218)
		(width 0.09525)
		(layer "In2.Cu")
		(net "M_C_CPU0_SA_DQS_DN<5>")
	)
	(arc
		(start 330.203302 -226.664266)
		(mid 330.244759 -226.836306)
		(end 330.36002 -226.97059)
		(width 0.09525)
		(layer "In2.Cu")
		(net "M_C_CPU0_SA_DQS_DN<5>")
	)
	(arc
		(start 327.611994 -222.15221)
		(mid 327.78968 -222.353502)
		(end 327.853802 -222.614236)
		(width 0.09525)
		(layer "In2.Cu")
		(net "M_C_CPU0_SA_DQS_DN<5>")
	)
	(arc
		(start 328.323448 -223.424242)
		(mid 328.364905 -223.596282)
		(end 328.480166 -223.730566)
		(width 0.09525)
		(layer "In2.Cu")
		(net "M_C_CPU0_SA_DQS_DN<5>")
	)
	(arc
		(start 334.999584 -227.799392)
		(mid 335.281016 -227.723637)
		(end 335.562448 -227.799392)
		(width 0.09525)
		(layer "In2.Cu")
		(net "M_C_CPU0_SA_DQS_DN<5>")
	)
	(arc
		(start 330.673456 -227.474272)
		(mid 330.715121 -227.646719)
		(end 330.830936 -227.781104)
		(width 0.09525)
		(layer "In2.Cu")
		(net "M_C_CPU0_SA_DQS_DN<5>")
	)
	(arc
		(start 327.383394 -221.803976)
		(mid 327.408378 -221.929466)
		(end 327.479406 -222.035878)
		(width 0.09525)
		(layer "In2.Cu")
		(net "M_C_CPU0_SA_DQS_DN<5>")
	)
	(arc
		(start 329.957684 -226.199954)
		(mid 330.138139 -226.40162)
		(end 330.203302 -226.664266)
		(width 0.09525)
		(layer "In2.Cu")
		(net "M_C_CPU0_SA_DQS_DN<5>")
	)
	(arc
		(start 341.579708 -227.799392)
		(mid 341.86114 -227.723637)
		(end 342.142572 -227.799392)
		(width 0.09525)
		(layer "In2.Cu")
		(net "M_C_CPU0_SA_DQS_DN<5>")
	)
	(arc
		(start 336.502502 -227.799392)
		(mid 336.686277 -227.850164)
		(end 336.87131 -227.804218)
		(width 0.09525)
		(layer "In2.Cu")
		(net "M_C_CPU0_SA_DQS_DN<5>")
	)
	(arc
		(start 335.939638 -227.799392)
		(mid 336.22107 -227.723637)
		(end 336.502502 -227.799392)
		(width 0.09525)
		(layer "In2.Cu")
		(net "M_C_CPU0_SA_DQS_DN<5>")
	)
	(segment
		(start 342.797892 -247.1801)
		(end 342.33104 -246.914162)
		(width 0.12954)
		(layer "F.Cu")
		(net "M_C_CPU0_SA_DQS_DN<4>")
	)
	(segment
		(start 328.042524 -246.589042)
		(end 328.027792 -246.597678)
		(width 0.09525)
		(layer "In2.Cu")
		(net "M_C_CPU0_SA_DQS_DN<4>")
	)
	(segment
		(start 312.017156 -242.52301)
		(end 311.517284 -242.023138)
		(width 0.16002)
		(layer "In2.Cu")
		(net "M_C_CPU0_SA_DQS_DN<4>")
	)
	(segment
		(start 316.036452 -246.059706)
		(end 315.378846 -245.4021)
		(width 0.16002)
		(layer "In2.Cu")
		(net "M_C_CPU0_SA_DQS_DN<4>")
	)
	(segment
		(start 296.493438 -238.562134)
		(end 293.716202 -238.562134)
		(width 0.16002)
		(layer "In2.Cu")
		(net "M_C_CPU0_SA_DQS_DN<4>")
	)
	(segment
		(start 309.269892 -239.775746)
		(end 308.77002 -239.275874)
		(width 0.16002)
		(layer "In2.Cu")
		(net "M_C_CPU0_SA_DQS_DN<4>")
	)
	(segment
		(start 328.99096 -246.584216)
		(end 328.982578 -246.589042)
		(width 0.09525)
		(layer "In2.Cu")
		(net "M_C_CPU0_SA_DQS_DN<4>")
	)
	(segment
		(start 308.494938 -238.449104)
		(end 308.494938 -238.017812)
		(width 0.16002)
		(layer "In2.Cu")
		(net "M_C_CPU0_SA_DQS_DN<4>")
	)
	(segment
		(start 325.672704 -246.94896)
		(end 324.503288 -246.94896)
		(width 0.09525)
		(layer "In2.Cu")
		(net "M_C_CPU0_SA_DQS_DN<4>")
	)
	(segment
		(start 305.726338 -238.097314)
		(end 304.928778 -238.894874)
		(width 0.16002)
		(layer "In2.Cu")
		(net "M_C_CPU0_SA_DQS_DN<4>")
	)
	(segment
		(start 328.419714 -246.589042)
		(end 328.411332 -246.584216)
		(width 0.09525)
		(layer "In2.Cu")
		(net "M_C_CPU0_SA_DQS_DN<4>")
	)
	(segment
		(start 324.13702 -246.582692)
		(end 323.978524 -246.582692)
		(width 0.09525)
		(layer "In2.Cu")
		(net "M_C_CPU0_SA_DQS_DN<4>")
	)
	(segment
		(start 304.928778 -238.894874)
		(end 304.339498 -238.894874)
		(width 0.16002)
		(layer "In2.Cu")
		(net "M_C_CPU0_SA_DQS_DN<4>")
	)
	(segment
		(start 326.539352 -246.589042)
		(end 326.524874 -246.58066)
		(width 0.09525)
		(layer "In2.Cu")
		(net "M_C_CPU0_SA_DQS_DN<4>")
	)
	(segment
		(start 324.503288 -246.94896)
		(end 324.13702 -246.582692)
		(width 0.09525)
		(layer "In2.Cu")
		(net "M_C_CPU0_SA_DQS_DN<4>")
	)
	(segment
		(start 336.879692 -246.589042)
		(end 336.87131 -246.584216)
		(width 0.09525)
		(layer "In2.Cu")
		(net "M_C_CPU0_SA_DQS_DN<4>")
	)
	(segment
		(start 311.517284 -241.47145)
		(end 311.195212 -241.149378)
		(width 0.16002)
		(layer "In2.Cu")
		(net "M_C_CPU0_SA_DQS_DN<4>")
	)
	(segment
		(start 315.632592 -243.950998)
		(end 315.355732 -243.950998)
		(width 0.16002)
		(layer "In2.Cu")
		(net "M_C_CPU0_SA_DQS_DN<4>")
	)
	(segment
		(start 325.962518 -246.659146)
		(end 325.672704 -246.94896)
		(width 0.09525)
		(layer "In2.Cu")
		(net "M_C_CPU0_SA_DQS_DN<4>")
	)
	(segment
		(start 298.769278 -238.023654)
		(end 298.362878 -238.023654)
		(width 0.16002)
		(layer "In2.Cu")
		(net "M_C_CPU0_SA_DQS_DN<4>")
	)
	(segment
		(start 308.77002 -238.724186)
		(end 308.494938 -238.449104)
		(width 0.16002)
		(layer "In2.Cu")
		(net "M_C_CPU0_SA_DQS_DN<4>")
	)
	(segment
		(start 314.277248 -243.22913)
		(end 314.277248 -242.95227)
		(width 0.16002)
		(layer "In2.Cu")
		(net "M_C_CPU0_SA_DQS_DN<4>")
	)
	(segment
		(start 341.2109 -246.584216)
		(end 341.202518 -246.589042)
		(width 0.09525)
		(layer "In2.Cu")
		(net "M_C_CPU0_SA_DQS_DN<4>")
	)
	(segment
		(start 311.195212 -241.149378)
		(end 310.643524 -241.149378)
		(width 0.16002)
		(layer "In2.Cu")
		(net "M_C_CPU0_SA_DQS_DN<4>")
	)
	(segment
		(start 306.203858 -238.097314)
		(end 305.726338 -238.097314)
		(width 0.16002)
		(layer "In2.Cu")
		(net "M_C_CPU0_SA_DQS_DN<4>")
	)
	(segment
		(start 337.450938 -246.584216)
		(end 337.442556 -246.589042)
		(width 0.09525)
		(layer "In2.Cu")
		(net "M_C_CPU0_SA_DQS_DN<4>")
	)
	(segment
		(start 300.71441 -237.71225)
		(end 299.080682 -237.71225)
		(width 0.16002)
		(layer "In2.Cu")
		(net "M_C_CPU0_SA_DQS_DN<4>")
	)
	(segment
		(start 292.553898 -238.711232)
		(end 292.280086 -238.985044)
		(width 0.16002)
		(layer "In2.Cu")
		(net "M_C_CPU0_SA_DQS_DN<4>")
	)
	(segment
		(start 296.808398 -238.877094)
		(end 296.493438 -238.562134)
		(width 0.16002)
		(layer "In2.Cu")
		(net "M_C_CPU0_SA_DQS_DN<4>")
	)
	(segment
		(start 314.654184 -244.652546)
		(end 314.12688 -244.652546)
		(width 0.16002)
		(layer "In2.Cu")
		(net "M_C_CPU0_SA_DQS_DN<4>")
	)
	(segment
		(start 308.494938 -238.017812)
		(end 308.22392 -237.746794)
		(width 0.16002)
		(layer "In2.Cu")
		(net "M_C_CPU0_SA_DQS_DN<4>")
	)
	(segment
		(start 335.939638 -246.589042)
		(end 335.931256 -246.584216)
		(width 0.09525)
		(layer "In2.Cu")
		(net "M_C_CPU0_SA_DQS_DN<4>")
	)
	(segment
		(start 322.950332 -246.059706)
		(end 316.036452 -246.059706)
		(width 0.16002)
		(layer "In2.Cu")
		(net "M_C_CPU0_SA_DQS_DN<4>")
	)
	(segment
		(start 308.22392 -237.746794)
		(end 306.554378 -237.746794)
		(width 0.16002)
		(layer "In2.Cu")
		(net "M_C_CPU0_SA_DQS_DN<4>")
	)
	(segment
		(start 310.643524 -241.149378)
		(end 310.143652 -240.649506)
		(width 0.16002)
		(layer "In2.Cu")
		(net "M_C_CPU0_SA_DQS_DN<4>")
	)
	(segment
		(start 315.355732 -243.950998)
		(end 314.654184 -244.652546)
		(width 0.16002)
		(layer "In2.Cu")
		(net "M_C_CPU0_SA_DQS_DN<4>")
	)
	(segment
		(start 298.362878 -238.023654)
		(end 297.509438 -238.877094)
		(width 0.16002)
		(layer "In2.Cu")
		(net "M_C_CPU0_SA_DQS_DN<4>")
	)
	(segment
		(start 313.064144 -243.01831)
		(end 312.568844 -242.52301)
		(width 0.16002)
		(layer "In2.Cu")
		(net "M_C_CPU0_SA_DQS_DN<4>")
	)
	(segment
		(start 293.567104 -238.711232)
		(end 292.553898 -238.711232)
		(width 0.16002)
		(layer "In2.Cu")
		(net "M_C_CPU0_SA_DQS_DN<4>")
	)
	(segment
		(start 309.82158 -239.775746)
		(end 309.269892 -239.775746)
		(width 0.16002)
		(layer "In2.Cu")
		(net "M_C_CPU0_SA_DQS_DN<4>")
	)
	(segment
		(start 315.378846 -245.4021)
		(end 315.378846 -244.874796)
		(width 0.16002)
		(layer "In2.Cu")
		(net "M_C_CPU0_SA_DQS_DN<4>")
	)
	(segment
		(start 333.690976 -246.584216)
		(end 333.682594 -246.589042)
		(width 0.09525)
		(layer "In2.Cu")
		(net "M_C_CPU0_SA_DQS_DN<4>")
	)
	(segment
		(start 332.750922 -246.584216)
		(end 332.74254 -246.589042)
		(width 0.09525)
		(layer "In2.Cu")
		(net "M_C_CPU0_SA_DQS_DN<4>")
	)
	(segment
		(start 327.113646 -246.582184)
		(end 327.101708 -246.589042)
		(width 0.09525)
		(layer "In2.Cu")
		(net "M_C_CPU0_SA_DQS_DN<4>")
	)
	(segment
		(start 332.179676 -246.589042)
		(end 332.171294 -246.584216)
		(width 0.09525)
		(layer "In2.Cu")
		(net "M_C_CPU0_SA_DQS_DN<4>")
	)
	(segment
		(start 315.829188 -244.424454)
		(end 315.829188 -244.147594)
		(width 0.16002)
		(layer "In2.Cu")
		(net "M_C_CPU0_SA_DQS_DN<4>")
	)
	(segment
		(start 340.639654 -246.589042)
		(end 340.631272 -246.584216)
		(width 0.09525)
		(layer "In2.Cu")
		(net "M_C_CPU0_SA_DQS_DN<4>")
	)
	(segment
		(start 311.517284 -242.023138)
		(end 311.517284 -241.47145)
		(width 0.16002)
		(layer "In2.Cu")
		(net "M_C_CPU0_SA_DQS_DN<4>")
	)
	(segment
		(start 301.607474 -238.605314)
		(end 300.71441 -237.71225)
		(width 0.16002)
		(layer "In2.Cu")
		(net "M_C_CPU0_SA_DQS_DN<4>")
	)
	(segment
		(start 315.829188 -244.147594)
		(end 315.632592 -243.950998)
		(width 0.16002)
		(layer "In2.Cu")
		(net "M_C_CPU0_SA_DQS_DN<4>")
	)
	(segment
		(start 331.239622 -246.589042)
		(end 331.23124 -246.584216)
		(width 0.09525)
		(layer "In2.Cu")
		(net "M_C_CPU0_SA_DQS_DN<4>")
	)
	(segment
		(start 313.541156 -243.01831)
		(end 313.064144 -243.01831)
		(width 0.16002)
		(layer "In2.Cu")
		(net "M_C_CPU0_SA_DQS_DN<4>")
	)
	(segment
		(start 313.803792 -242.755674)
		(end 313.541156 -243.01831)
		(width 0.16002)
		(layer "In2.Cu")
		(net "M_C_CPU0_SA_DQS_DN<4>")
	)
	(segment
		(start 314.080652 -242.755674)
		(end 313.803792 -242.755674)
		(width 0.16002)
		(layer "In2.Cu")
		(net "M_C_CPU0_SA_DQS_DN<4>")
	)
	(segment
		(start 326.554084 -246.597678)
		(end 326.539352 -246.589042)
		(width 0.09525)
		(layer "In2.Cu")
		(net "M_C_CPU0_SA_DQS_DN<4>")
	)
	(segment
		(start 323.532246 -246.64162)
		(end 322.950332 -246.059706)
		(width 0.16002)
		(layer "In2.Cu")
		(net "M_C_CPU0_SA_DQS_DN<4>")
	)
	(segment
		(start 308.77002 -239.275874)
		(end 308.77002 -238.724186)
		(width 0.16002)
		(layer "In2.Cu")
		(net "M_C_CPU0_SA_DQS_DN<4>")
	)
	(segment
		(start 304.049938 -238.605314)
		(end 301.607474 -238.605314)
		(width 0.16002)
		(layer "In2.Cu")
		(net "M_C_CPU0_SA_DQS_DN<4>")
	)
	(segment
		(start 323.919596 -246.64162)
		(end 323.895974 -246.64162)
		(width 0.09525)
		(layer "In2.Cu")
		(net "M_C_CPU0_SA_DQS_DN<4>")
	)
	(segment
		(start 313.754008 -244.279674)
		(end 313.754008 -243.75237)
		(width 0.16002)
		(layer "In2.Cu")
		(net "M_C_CPU0_SA_DQS_DN<4>")
	)
	(segment
		(start 304.339498 -238.894874)
		(end 304.049938 -238.605314)
		(width 0.16002)
		(layer "In2.Cu")
		(net "M_C_CPU0_SA_DQS_DN<4>")
	)
	(segment
		(start 312.568844 -242.52301)
		(end 312.017156 -242.52301)
		(width 0.16002)
		(layer "In2.Cu")
		(net "M_C_CPU0_SA_DQS_DN<4>")
	)
	(segment
		(start 314.12688 -244.652546)
		(end 313.754008 -244.279674)
		(width 0.16002)
		(layer "In2.Cu")
		(net "M_C_CPU0_SA_DQS_DN<4>")
	)
	(segment
		(start 314.277248 -242.95227)
		(end 314.080652 -242.755674)
		(width 0.16002)
		(layer "In2.Cu")
		(net "M_C_CPU0_SA_DQS_DN<4>")
	)
	(segment
		(start 297.509438 -238.877094)
		(end 296.808398 -238.877094)
		(width 0.16002)
		(layer "In2.Cu")
		(net "M_C_CPU0_SA_DQS_DN<4>")
	)
	(segment
		(start 310.143652 -240.097818)
		(end 309.82158 -239.775746)
		(width 0.16002)
		(layer "In2.Cu")
		(net "M_C_CPU0_SA_DQS_DN<4>")
	)
	(segment
		(start 323.895974 -246.64162)
		(end 323.532246 -246.64162)
		(width 0.16002)
		(layer "In2.Cu")
		(net "M_C_CPU0_SA_DQS_DN<4>")
	)
	(segment
		(start 342.177116 -246.648732)
		(end 342.076278 -246.622062)
		(width 0.09525)
		(layer "In2.Cu")
		(net "M_C_CPU0_SA_DQS_DN<4>")
	)
	(segment
		(start 299.080682 -237.71225)
		(end 298.769278 -238.023654)
		(width 0.16002)
		(layer "In2.Cu")
		(net "M_C_CPU0_SA_DQS_DN<4>")
	)
	(segment
		(start 339.6996 -246.589042)
		(end 339.691218 -246.584216)
		(width 0.09525)
		(layer "In2.Cu")
		(net "M_C_CPU0_SA_DQS_DN<4>")
	)
	(segment
		(start 323.978524 -246.582692)
		(end 323.919596 -246.64162)
		(width 0.09525)
		(layer "In2.Cu")
		(net "M_C_CPU0_SA_DQS_DN<4>")
	)
	(segment
		(start 342.33104 -246.914162)
		(end 342.177116 -246.648732)
		(width 0.09525)
		(layer "In2.Cu")
		(net "M_C_CPU0_SA_DQS_DN<4>")
	)
	(segment
		(start 313.754008 -243.75237)
		(end 314.277248 -243.22913)
		(width 0.16002)
		(layer "In2.Cu")
		(net "M_C_CPU0_SA_DQS_DN<4>")
	)
	(segment
		(start 310.143652 -240.649506)
		(end 310.143652 -240.097818)
		(width 0.16002)
		(layer "In2.Cu")
		(net "M_C_CPU0_SA_DQS_DN<4>")
	)
	(segment
		(start 306.554378 -237.746794)
		(end 306.203858 -238.097314)
		(width 0.16002)
		(layer "In2.Cu")
		(net "M_C_CPU0_SA_DQS_DN<4>")
	)
	(segment
		(start 293.716202 -238.562134)
		(end 293.567104 -238.711232)
		(width 0.16002)
		(layer "In2.Cu")
		(net "M_C_CPU0_SA_DQS_DN<4>")
	)
	(segment
		(start 315.378846 -244.874796)
		(end 315.829188 -244.424454)
		(width 0.16002)
		(layer "In2.Cu")
		(net "M_C_CPU0_SA_DQS_DN<4>")
	)
	(arc
		(start 337.819746 -246.589042)
		(mid 337.635971 -246.53827)
		(end 337.450938 -246.584216)
		(width 0.09525)
		(layer "In2.Cu")
		(net "M_C_CPU0_SA_DQS_DN<4>")
	)
	(arc
		(start 338.38261 -246.589042)
		(mid 338.101178 -246.664797)
		(end 337.819746 -246.589042)
		(width 0.09525)
		(layer "In2.Cu")
		(net "M_C_CPU0_SA_DQS_DN<4>")
	)
	(arc
		(start 332.74254 -246.589042)
		(mid 332.461108 -246.664797)
		(end 332.179676 -246.589042)
		(width 0.09525)
		(layer "In2.Cu")
		(net "M_C_CPU0_SA_DQS_DN<4>")
	)
	(arc
		(start 338.759546 -246.589042)
		(mid 338.571078 -246.538365)
		(end 338.38261 -246.589042)
		(width 0.09525)
		(layer "In2.Cu")
		(net "M_C_CPU0_SA_DQS_DN<4>")
	)
	(arc
		(start 334.999584 -246.589042)
		(mid 334.811116 -246.538365)
		(end 334.622648 -246.589042)
		(width 0.09525)
		(layer "In2.Cu")
		(net "M_C_CPU0_SA_DQS_DN<4>")
	)
	(arc
		(start 342.076278 -246.622062)
		(mid 342.066156 -246.626097)
		(end 342.055958 -246.629936)
		(width 0.09525)
		(layer "In2.Cu")
		(net "M_C_CPU0_SA_DQS_DN<4>")
	)
	(arc
		(start 328.027792 -246.597678)
		(mid 327.752333 -246.665063)
		(end 327.479152 -246.589042)
		(width 0.09525)
		(layer "In2.Cu")
		(net "M_C_CPU0_SA_DQS_DN<4>")
	)
	(arc
		(start 326.162162 -246.589042)
		(mid 326.065676 -246.633598)
		(end 325.962518 -246.659146)
		(width 0.09525)
		(layer "In2.Cu")
		(net "M_C_CPU0_SA_DQS_DN<4>")
	)
	(arc
		(start 337.442556 -246.589042)
		(mid 337.161124 -246.664797)
		(end 336.879692 -246.589042)
		(width 0.09525)
		(layer "In2.Cu")
		(net "M_C_CPU0_SA_DQS_DN<4>")
	)
	(arc
		(start 340.262464 -246.589042)
		(mid 339.981032 -246.664797)
		(end 339.6996 -246.589042)
		(width 0.09525)
		(layer "In2.Cu")
		(net "M_C_CPU0_SA_DQS_DN<4>")
	)
	(arc
		(start 329.359768 -246.589042)
		(mid 329.175993 -246.53827)
		(end 328.99096 -246.584216)
		(width 0.09525)
		(layer "In2.Cu")
		(net "M_C_CPU0_SA_DQS_DN<4>")
	)
	(arc
		(start 335.931256 -246.584216)
		(mid 335.746224 -246.538302)
		(end 335.562448 -246.589042)
		(width 0.09525)
		(layer "In2.Cu")
		(net "M_C_CPU0_SA_DQS_DN<4>")
	)
	(arc
		(start 331.23124 -246.584216)
		(mid 331.046208 -246.538302)
		(end 330.862432 -246.589042)
		(width 0.09525)
		(layer "In2.Cu")
		(net "M_C_CPU0_SA_DQS_DN<4>")
	)
	(arc
		(start 328.982578 -246.589042)
		(mid 328.701146 -246.664797)
		(end 328.419714 -246.589042)
		(width 0.09525)
		(layer "In2.Cu")
		(net "M_C_CPU0_SA_DQS_DN<4>")
	)
	(arc
		(start 331.802486 -246.589042)
		(mid 331.521054 -246.664797)
		(end 331.239622 -246.589042)
		(width 0.09525)
		(layer "In2.Cu")
		(net "M_C_CPU0_SA_DQS_DN<4>")
	)
	(arc
		(start 333.11973 -246.589042)
		(mid 332.935955 -246.53827)
		(end 332.750922 -246.584216)
		(width 0.09525)
		(layer "In2.Cu")
		(net "M_C_CPU0_SA_DQS_DN<4>")
	)
	(arc
		(start 328.411332 -246.584216)
		(mid 328.2263 -246.538302)
		(end 328.042524 -246.589042)
		(width 0.09525)
		(layer "In2.Cu")
		(net "M_C_CPU0_SA_DQS_DN<4>")
	)
	(arc
		(start 327.479152 -246.589042)
		(mid 327.297282 -246.538177)
		(end 327.113646 -246.582184)
		(width 0.09525)
		(layer "In2.Cu")
		(net "M_C_CPU0_SA_DQS_DN<4>")
	)
	(arc
		(start 334.622648 -246.589042)
		(mid 334.341216 -246.664797)
		(end 334.059784 -246.589042)
		(width 0.09525)
		(layer "In2.Cu")
		(net "M_C_CPU0_SA_DQS_DN<4>")
	)
	(arc
		(start 339.32241 -246.589042)
		(mid 339.040978 -246.664797)
		(end 338.759546 -246.589042)
		(width 0.09525)
		(layer "In2.Cu")
		(net "M_C_CPU0_SA_DQS_DN<4>")
	)
	(arc
		(start 329.922632 -246.589042)
		(mid 329.6412 -246.664797)
		(end 329.359768 -246.589042)
		(width 0.09525)
		(layer "In2.Cu")
		(net "M_C_CPU0_SA_DQS_DN<4>")
	)
	(arc
		(start 339.691218 -246.584216)
		(mid 339.506186 -246.538302)
		(end 339.32241 -246.589042)
		(width 0.09525)
		(layer "In2.Cu")
		(net "M_C_CPU0_SA_DQS_DN<4>")
	)
	(arc
		(start 327.101708 -246.589042)
		(mid 326.829034 -246.664729)
		(end 326.554084 -246.597678)
		(width 0.09525)
		(layer "In2.Cu")
		(net "M_C_CPU0_SA_DQS_DN<4>")
	)
	(arc
		(start 330.299568 -246.589042)
		(mid 330.1111 -246.538365)
		(end 329.922632 -246.589042)
		(width 0.09525)
		(layer "In2.Cu")
		(net "M_C_CPU0_SA_DQS_DN<4>")
	)
	(arc
		(start 342.055958 -246.629936)
		(mid 341.813246 -246.662819)
		(end 341.579708 -246.589042)
		(width 0.09525)
		(layer "In2.Cu")
		(net "M_C_CPU0_SA_DQS_DN<4>")
	)
	(arc
		(start 326.524874 -246.58066)
		(mid 326.342442 -246.53822)
		(end 326.162162 -246.589042)
		(width 0.09525)
		(layer "In2.Cu")
		(net "M_C_CPU0_SA_DQS_DN<4>")
	)
	(arc
		(start 341.579708 -246.589042)
		(mid 341.395933 -246.53827)
		(end 341.2109 -246.584216)
		(width 0.09525)
		(layer "In2.Cu")
		(net "M_C_CPU0_SA_DQS_DN<4>")
	)
	(arc
		(start 333.682594 -246.589042)
		(mid 333.401162 -246.664797)
		(end 333.11973 -246.589042)
		(width 0.09525)
		(layer "In2.Cu")
		(net "M_C_CPU0_SA_DQS_DN<4>")
	)
	(arc
		(start 336.87131 -246.584216)
		(mid 336.686278 -246.538302)
		(end 336.502502 -246.589042)
		(width 0.09525)
		(layer "In2.Cu")
		(net "M_C_CPU0_SA_DQS_DN<4>")
	)
	(arc
		(start 336.502502 -246.589042)
		(mid 336.22107 -246.664797)
		(end 335.939638 -246.589042)
		(width 0.09525)
		(layer "In2.Cu")
		(net "M_C_CPU0_SA_DQS_DN<4>")
	)
	(arc
		(start 332.171294 -246.584216)
		(mid 331.986262 -246.538302)
		(end 331.802486 -246.589042)
		(width 0.09525)
		(layer "In2.Cu")
		(net "M_C_CPU0_SA_DQS_DN<4>")
	)
	(arc
		(start 340.631272 -246.584216)
		(mid 340.44624 -246.538302)
		(end 340.262464 -246.589042)
		(width 0.09525)
		(layer "In2.Cu")
		(net "M_C_CPU0_SA_DQS_DN<4>")
	)
	(arc
		(start 334.059784 -246.589042)
		(mid 333.876009 -246.53827)
		(end 333.690976 -246.584216)
		(width 0.09525)
		(layer "In2.Cu")
		(net "M_C_CPU0_SA_DQS_DN<4>")
	)
	(arc
		(start 330.862432 -246.589042)
		(mid 330.581 -246.664797)
		(end 330.299568 -246.589042)
		(width 0.09525)
		(layer "In2.Cu")
		(net "M_C_CPU0_SA_DQS_DN<4>")
	)
	(arc
		(start 341.202518 -246.589042)
		(mid 340.921086 -246.664797)
		(end 340.639654 -246.589042)
		(width 0.09525)
		(layer "In2.Cu")
		(net "M_C_CPU0_SA_DQS_DN<4>")
	)
	(arc
		(start 335.562448 -246.589042)
		(mid 335.281016 -246.664797)
		(end 334.999584 -246.589042)
		(width 0.09525)
		(layer "In2.Cu")
		(net "M_C_CPU0_SA_DQS_DN<4>")
	)
	(segment
		(start 342.797892 -242.320064)
		(end 342.33104 -242.054126)
		(width 0.12954)
		(layer "F.Cu")
		(net "M_C_CPU0_SA_DQS_DN<3>")
	)
	(segment
		(start 298.362878 -228.67366)
		(end 298.74083 -228.67366)
		(width 0.16002)
		(layer "In2.Cu")
		(net "M_C_CPU0_SA_DQS_DN<3>")
	)
	(segment
		(start 304.075846 -229.25532)
		(end 304.408586 -229.58806)
		(width 0.16002)
		(layer "In2.Cu")
		(net "M_C_CPU0_SA_DQS_DN<3>")
	)
	(segment
		(start 324.511416 -240.4745)
		(end 324.917562 -240.4745)
		(width 0.09525)
		(layer "In2.Cu")
		(net "M_C_CPU0_SA_DQS_DN<3>")
	)
	(segment
		(start 324.068948 -240.302034)
		(end 324.33895 -240.302034)
		(width 0.09525)
		(layer "In2.Cu")
		(net "M_C_CPU0_SA_DQS_DN<3>")
	)
	(segment
		(start 312.24728 -230.57739)
		(end 311.56529 -231.25938)
		(width 0.16002)
		(layer "In2.Cu")
		(net "M_C_CPU0_SA_DQS_DN<3>")
	)
	(segment
		(start 311.56529 -231.786684)
		(end 320.139568 -240.360962)
		(width 0.16002)
		(layer "In2.Cu")
		(net "M_C_CPU0_SA_DQS_DN<3>")
	)
	(segment
		(start 308.254146 -228.3968)
		(end 309.255668 -229.398322)
		(width 0.16002)
		(layer "In2.Cu")
		(net "M_C_CPU0_SA_DQS_DN<3>")
	)
	(segment
		(start 292.553898 -229.361238)
		(end 294.734488 -229.361238)
		(width 0.16002)
		(layer "In2.Cu")
		(net "M_C_CPU0_SA_DQS_DN<3>")
	)
	(segment
		(start 300.705266 -228.362256)
		(end 301.59833 -229.25532)
		(width 0.16002)
		(layer "In2.Cu")
		(net "M_C_CPU0_SA_DQS_DN<3>")
	)
	(segment
		(start 335.931256 -241.72418)
		(end 335.939638 -241.729006)
		(width 0.09525)
		(layer "In2.Cu")
		(net "M_C_CPU0_SA_DQS_DN<3>")
	)
	(segment
		(start 310.191658 -230.413052)
		(end 310.56453 -230.785924)
		(width 0.16002)
		(layer "In2.Cu")
		(net "M_C_CPU0_SA_DQS_DN<3>")
	)
	(segment
		(start 332.74254 -241.729006)
		(end 332.750922 -241.72418)
		(width 0.09525)
		(layer "In2.Cu")
		(net "M_C_CPU0_SA_DQS_DN<3>")
	)
	(segment
		(start 342.177116 -241.788696)
		(end 342.33104 -242.054126)
		(width 0.09525)
		(layer "In2.Cu")
		(net "M_C_CPU0_SA_DQS_DN<3>")
	)
	(segment
		(start 306.203858 -228.74732)
		(end 306.554378 -228.3968)
		(width 0.16002)
		(layer "In2.Cu")
		(net "M_C_CPU0_SA_DQS_DN<3>")
	)
	(segment
		(start 310.755284 -228.652324)
		(end 310.95188 -228.84892)
		(width 0.16002)
		(layer "In2.Cu")
		(net "M_C_CPU0_SA_DQS_DN<3>")
	)
	(segment
		(start 324.01002 -240.360962)
		(end 324.068948 -240.302034)
		(width 0.09525)
		(layer "In2.Cu")
		(net "M_C_CPU0_SA_DQS_DN<3>")
	)
	(segment
		(start 340.631272 -241.72418)
		(end 340.639654 -241.729006)
		(width 0.09525)
		(layer "In2.Cu")
		(net "M_C_CPU0_SA_DQS_DN<3>")
	)
	(segment
		(start 310.95188 -229.125526)
		(end 310.191658 -229.885748)
		(width 0.16002)
		(layer "In2.Cu")
		(net "M_C_CPU0_SA_DQS_DN<3>")
	)
	(segment
		(start 310.191658 -229.885748)
		(end 310.191658 -230.413052)
		(width 0.16002)
		(layer "In2.Cu")
		(net "M_C_CPU0_SA_DQS_DN<3>")
	)
	(segment
		(start 299.052234 -228.362256)
		(end 300.705266 -228.362256)
		(width 0.16002)
		(layer "In2.Cu")
		(net "M_C_CPU0_SA_DQS_DN<3>")
	)
	(segment
		(start 310.478424 -228.652324)
		(end 310.755284 -228.652324)
		(width 0.16002)
		(layer "In2.Cu")
		(net "M_C_CPU0_SA_DQS_DN<3>")
	)
	(segment
		(start 337.442556 -241.729006)
		(end 337.450938 -241.72418)
		(width 0.09525)
		(layer "In2.Cu")
		(net "M_C_CPU0_SA_DQS_DN<3>")
	)
	(segment
		(start 309.255668 -229.398322)
		(end 309.732426 -229.398322)
		(width 0.16002)
		(layer "In2.Cu")
		(net "M_C_CPU0_SA_DQS_DN<3>")
	)
	(segment
		(start 327.471278 -241.72418)
		(end 327.47966 -241.729006)
		(width 0.09525)
		(layer "In2.Cu")
		(net "M_C_CPU0_SA_DQS_DN<3>")
	)
	(segment
		(start 309.732426 -229.398322)
		(end 310.478424 -228.652324)
		(width 0.16002)
		(layer "In2.Cu")
		(net "M_C_CPU0_SA_DQS_DN<3>")
	)
	(segment
		(start 305.726338 -228.74732)
		(end 306.203858 -228.74732)
		(width 0.16002)
		(layer "In2.Cu")
		(net "M_C_CPU0_SA_DQS_DN<3>")
	)
	(segment
		(start 332.171294 -241.72418)
		(end 332.179676 -241.729006)
		(width 0.09525)
		(layer "In2.Cu")
		(net "M_C_CPU0_SA_DQS_DN<3>")
	)
	(segment
		(start 298.74083 -228.67366)
		(end 299.052234 -228.362256)
		(width 0.16002)
		(layer "In2.Cu")
		(net "M_C_CPU0_SA_DQS_DN<3>")
	)
	(segment
		(start 312.05043 -230.104188)
		(end 312.24728 -230.301038)
		(width 0.16002)
		(layer "In2.Cu")
		(net "M_C_CPU0_SA_DQS_DN<3>")
	)
	(segment
		(start 310.95188 -228.84892)
		(end 310.95188 -229.125526)
		(width 0.16002)
		(layer "In2.Cu")
		(net "M_C_CPU0_SA_DQS_DN<3>")
	)
	(segment
		(start 306.554378 -228.3968)
		(end 308.254146 -228.3968)
		(width 0.16002)
		(layer "In2.Cu")
		(net "M_C_CPU0_SA_DQS_DN<3>")
	)
	(segment
		(start 304.885598 -229.58806)
		(end 305.726338 -228.74732)
		(width 0.16002)
		(layer "In2.Cu")
		(net "M_C_CPU0_SA_DQS_DN<3>")
	)
	(segment
		(start 312.24728 -230.301038)
		(end 312.24728 -230.57739)
		(width 0.16002)
		(layer "In2.Cu")
		(net "M_C_CPU0_SA_DQS_DN<3>")
	)
	(segment
		(start 328.411332 -241.72418)
		(end 328.419714 -241.729006)
		(width 0.09525)
		(layer "In2.Cu")
		(net "M_C_CPU0_SA_DQS_DN<3>")
	)
	(segment
		(start 296.493438 -229.21214)
		(end 296.920412 -229.639114)
		(width 0.16002)
		(layer "In2.Cu")
		(net "M_C_CPU0_SA_DQS_DN<3>")
	)
	(segment
		(start 342.076278 -241.762026)
		(end 342.177116 -241.788696)
		(width 0.09525)
		(layer "In2.Cu")
		(net "M_C_CPU0_SA_DQS_DN<3>")
	)
	(segment
		(start 292.280086 -229.63505)
		(end 292.553898 -229.361238)
		(width 0.16002)
		(layer "In2.Cu")
		(net "M_C_CPU0_SA_DQS_DN<3>")
	)
	(segment
		(start 296.920412 -229.639114)
		(end 297.397424 -229.639114)
		(width 0.16002)
		(layer "In2.Cu")
		(net "M_C_CPU0_SA_DQS_DN<3>")
	)
	(segment
		(start 323.986398 -240.360962)
		(end 324.01002 -240.360962)
		(width 0.09525)
		(layer "In2.Cu")
		(net "M_C_CPU0_SA_DQS_DN<3>")
	)
	(segment
		(start 341.202518 -241.729006)
		(end 341.2109 -241.72418)
		(width 0.09525)
		(layer "In2.Cu")
		(net "M_C_CPU0_SA_DQS_DN<3>")
	)
	(segment
		(start 339.691218 -241.72418)
		(end 339.6996 -241.729006)
		(width 0.09525)
		(layer "In2.Cu")
		(net "M_C_CPU0_SA_DQS_DN<3>")
	)
	(segment
		(start 310.56453 -230.785924)
		(end 311.092088 -230.785924)
		(width 0.16002)
		(layer "In2.Cu")
		(net "M_C_CPU0_SA_DQS_DN<3>")
	)
	(segment
		(start 324.917562 -240.4745)
		(end 326.12076 -241.677698)
		(width 0.09525)
		(layer "In2.Cu")
		(net "M_C_CPU0_SA_DQS_DN<3>")
	)
	(segment
		(start 333.682594 -241.729006)
		(end 333.690976 -241.72418)
		(width 0.09525)
		(layer "In2.Cu")
		(net "M_C_CPU0_SA_DQS_DN<3>")
	)
	(segment
		(start 311.773824 -230.104188)
		(end 312.05043 -230.104188)
		(width 0.16002)
		(layer "In2.Cu")
		(net "M_C_CPU0_SA_DQS_DN<3>")
	)
	(segment
		(start 331.23124 -241.72418)
		(end 331.239622 -241.729006)
		(width 0.09525)
		(layer "In2.Cu")
		(net "M_C_CPU0_SA_DQS_DN<3>")
	)
	(segment
		(start 294.883586 -229.21214)
		(end 296.493438 -229.21214)
		(width 0.16002)
		(layer "In2.Cu")
		(net "M_C_CPU0_SA_DQS_DN<3>")
	)
	(segment
		(start 320.139568 -240.360962)
		(end 323.986398 -240.360962)
		(width 0.16002)
		(layer "In2.Cu")
		(net "M_C_CPU0_SA_DQS_DN<3>")
	)
	(segment
		(start 294.734488 -229.361238)
		(end 294.883586 -229.21214)
		(width 0.16002)
		(layer "In2.Cu")
		(net "M_C_CPU0_SA_DQS_DN<3>")
	)
	(segment
		(start 328.982578 -241.729006)
		(end 328.99096 -241.72418)
		(width 0.09525)
		(layer "In2.Cu")
		(net "M_C_CPU0_SA_DQS_DN<3>")
	)
	(segment
		(start 324.33895 -240.302034)
		(end 324.511416 -240.4745)
		(width 0.09525)
		(layer "In2.Cu")
		(net "M_C_CPU0_SA_DQS_DN<3>")
	)
	(segment
		(start 297.397424 -229.639114)
		(end 298.362878 -228.67366)
		(width 0.16002)
		(layer "In2.Cu")
		(net "M_C_CPU0_SA_DQS_DN<3>")
	)
	(segment
		(start 311.56529 -231.25938)
		(end 311.56529 -231.786684)
		(width 0.16002)
		(layer "In2.Cu")
		(net "M_C_CPU0_SA_DQS_DN<3>")
	)
	(segment
		(start 301.59833 -229.25532)
		(end 304.075846 -229.25532)
		(width 0.16002)
		(layer "In2.Cu")
		(net "M_C_CPU0_SA_DQS_DN<3>")
	)
	(segment
		(start 304.408586 -229.58806)
		(end 304.885598 -229.58806)
		(width 0.16002)
		(layer "In2.Cu")
		(net "M_C_CPU0_SA_DQS_DN<3>")
	)
	(segment
		(start 336.87131 -241.72418)
		(end 336.879692 -241.729006)
		(width 0.09525)
		(layer "In2.Cu")
		(net "M_C_CPU0_SA_DQS_DN<3>")
	)
	(segment
		(start 311.092088 -230.785924)
		(end 311.773824 -230.104188)
		(width 0.16002)
		(layer "In2.Cu")
		(net "M_C_CPU0_SA_DQS_DN<3>")
	)
	(segment
		(start 326.12076 -241.677698)
		(end 326.351138 -241.677698)
		(width 0.09525)
		(layer "In2.Cu")
		(net "M_C_CPU0_SA_DQS_DN<3>")
	)
	(arc
		(start 337.819746 -241.729006)
		(mid 338.101178 -241.804761)
		(end 338.38261 -241.729006)
		(width 0.09525)
		(layer "In2.Cu")
		(net "M_C_CPU0_SA_DQS_DN<3>")
	)
	(arc
		(start 334.622648 -241.729006)
		(mid 334.811116 -241.678329)
		(end 334.999584 -241.729006)
		(width 0.09525)
		(layer "In2.Cu")
		(net "M_C_CPU0_SA_DQS_DN<3>")
	)
	(arc
		(start 333.11973 -241.729006)
		(mid 333.401162 -241.804761)
		(end 333.682594 -241.729006)
		(width 0.09525)
		(layer "In2.Cu")
		(net "M_C_CPU0_SA_DQS_DN<3>")
	)
	(arc
		(start 330.862432 -241.729006)
		(mid 331.046207 -241.678234)
		(end 331.23124 -241.72418)
		(width 0.09525)
		(layer "In2.Cu")
		(net "M_C_CPU0_SA_DQS_DN<3>")
	)
	(arc
		(start 340.262464 -241.729006)
		(mid 340.446239 -241.678234)
		(end 340.631272 -241.72418)
		(width 0.09525)
		(layer "In2.Cu")
		(net "M_C_CPU0_SA_DQS_DN<3>")
	)
	(arc
		(start 328.419714 -241.729006)
		(mid 328.701146 -241.804761)
		(end 328.982578 -241.729006)
		(width 0.09525)
		(layer "In2.Cu")
		(net "M_C_CPU0_SA_DQS_DN<3>")
	)
	(arc
		(start 331.802486 -241.729006)
		(mid 331.986261 -241.678234)
		(end 332.171294 -241.72418)
		(width 0.09525)
		(layer "In2.Cu")
		(net "M_C_CPU0_SA_DQS_DN<3>")
	)
	(arc
		(start 337.450938 -241.72418)
		(mid 337.63597 -241.678266)
		(end 337.819746 -241.729006)
		(width 0.09525)
		(layer "In2.Cu")
		(net "M_C_CPU0_SA_DQS_DN<3>")
	)
	(arc
		(start 334.059784 -241.729006)
		(mid 334.341216 -241.804761)
		(end 334.622648 -241.729006)
		(width 0.09525)
		(layer "In2.Cu")
		(net "M_C_CPU0_SA_DQS_DN<3>")
	)
	(arc
		(start 334.999584 -241.729006)
		(mid 335.281016 -241.804761)
		(end 335.562448 -241.729006)
		(width 0.09525)
		(layer "In2.Cu")
		(net "M_C_CPU0_SA_DQS_DN<3>")
	)
	(arc
		(start 338.38261 -241.729006)
		(mid 338.571078 -241.678329)
		(end 338.759546 -241.729006)
		(width 0.09525)
		(layer "In2.Cu")
		(net "M_C_CPU0_SA_DQS_DN<3>")
	)
	(arc
		(start 332.179676 -241.729006)
		(mid 332.461108 -241.804761)
		(end 332.74254 -241.729006)
		(width 0.09525)
		(layer "In2.Cu")
		(net "M_C_CPU0_SA_DQS_DN<3>")
	)
	(arc
		(start 338.759546 -241.729006)
		(mid 339.040978 -241.804761)
		(end 339.32241 -241.729006)
		(width 0.09525)
		(layer "In2.Cu")
		(net "M_C_CPU0_SA_DQS_DN<3>")
	)
	(arc
		(start 341.579708 -241.729006)
		(mid 341.813252 -241.802712)
		(end 342.055958 -241.7699)
		(width 0.09525)
		(layer "In2.Cu")
		(net "M_C_CPU0_SA_DQS_DN<3>")
	)
	(arc
		(start 329.922632 -241.729006)
		(mid 330.1111 -241.678329)
		(end 330.299568 -241.729006)
		(width 0.09525)
		(layer "In2.Cu")
		(net "M_C_CPU0_SA_DQS_DN<3>")
	)
	(arc
		(start 328.99096 -241.72418)
		(mid 329.175992 -241.678266)
		(end 329.359768 -241.729006)
		(width 0.09525)
		(layer "In2.Cu")
		(net "M_C_CPU0_SA_DQS_DN<3>")
	)
	(arc
		(start 342.055958 -241.7699)
		(mid 342.066157 -241.766063)
		(end 342.076278 -241.762026)
		(width 0.09525)
		(layer "In2.Cu")
		(net "M_C_CPU0_SA_DQS_DN<3>")
	)
	(arc
		(start 326.539606 -241.729006)
		(mid 326.821038 -241.804761)
		(end 327.10247 -241.729006)
		(width 0.09525)
		(layer "In2.Cu")
		(net "M_C_CPU0_SA_DQS_DN<3>")
	)
	(arc
		(start 326.351138 -241.677698)
		(mid 326.448752 -241.690925)
		(end 326.539606 -241.729006)
		(width 0.09525)
		(layer "In2.Cu")
		(net "M_C_CPU0_SA_DQS_DN<3>")
	)
	(arc
		(start 331.239622 -241.729006)
		(mid 331.521054 -241.804761)
		(end 331.802486 -241.729006)
		(width 0.09525)
		(layer "In2.Cu")
		(net "M_C_CPU0_SA_DQS_DN<3>")
	)
	(arc
		(start 327.47966 -241.729006)
		(mid 327.761092 -241.804761)
		(end 328.042524 -241.729006)
		(width 0.09525)
		(layer "In2.Cu")
		(net "M_C_CPU0_SA_DQS_DN<3>")
	)
	(arc
		(start 332.750922 -241.72418)
		(mid 332.935954 -241.678266)
		(end 333.11973 -241.729006)
		(width 0.09525)
		(layer "In2.Cu")
		(net "M_C_CPU0_SA_DQS_DN<3>")
	)
	(arc
		(start 335.562448 -241.729006)
		(mid 335.746223 -241.678234)
		(end 335.931256 -241.72418)
		(width 0.09525)
		(layer "In2.Cu")
		(net "M_C_CPU0_SA_DQS_DN<3>")
	)
	(arc
		(start 335.939638 -241.729006)
		(mid 336.22107 -241.804761)
		(end 336.502502 -241.729006)
		(width 0.09525)
		(layer "In2.Cu")
		(net "M_C_CPU0_SA_DQS_DN<3>")
	)
	(arc
		(start 333.690976 -241.72418)
		(mid 333.876008 -241.678266)
		(end 334.059784 -241.729006)
		(width 0.09525)
		(layer "In2.Cu")
		(net "M_C_CPU0_SA_DQS_DN<3>")
	)
	(arc
		(start 339.6996 -241.729006)
		(mid 339.981032 -241.804761)
		(end 340.262464 -241.729006)
		(width 0.09525)
		(layer "In2.Cu")
		(net "M_C_CPU0_SA_DQS_DN<3>")
	)
	(arc
		(start 340.639654 -241.729006)
		(mid 340.921086 -241.804761)
		(end 341.202518 -241.729006)
		(width 0.09525)
		(layer "In2.Cu")
		(net "M_C_CPU0_SA_DQS_DN<3>")
	)
	(arc
		(start 336.879692 -241.729006)
		(mid 337.161124 -241.804761)
		(end 337.442556 -241.729006)
		(width 0.09525)
		(layer "In2.Cu")
		(net "M_C_CPU0_SA_DQS_DN<3>")
	)
	(arc
		(start 327.10247 -241.729006)
		(mid 327.286245 -241.678234)
		(end 327.471278 -241.72418)
		(width 0.09525)
		(layer "In2.Cu")
		(net "M_C_CPU0_SA_DQS_DN<3>")
	)
	(arc
		(start 336.502502 -241.729006)
		(mid 336.686277 -241.678234)
		(end 336.87131 -241.72418)
		(width 0.09525)
		(layer "In2.Cu")
		(net "M_C_CPU0_SA_DQS_DN<3>")
	)
	(arc
		(start 329.359768 -241.729006)
		(mid 329.6412 -241.804761)
		(end 329.922632 -241.729006)
		(width 0.09525)
		(layer "In2.Cu")
		(net "M_C_CPU0_SA_DQS_DN<3>")
	)
	(arc
		(start 330.299568 -241.729006)
		(mid 330.581 -241.804761)
		(end 330.862432 -241.729006)
		(width 0.09525)
		(layer "In2.Cu")
		(net "M_C_CPU0_SA_DQS_DN<3>")
	)
	(arc
		(start 341.2109 -241.72418)
		(mid 341.395932 -241.678266)
		(end 341.579708 -241.729006)
		(width 0.09525)
		(layer "In2.Cu")
		(net "M_C_CPU0_SA_DQS_DN<3>")
	)
	(arc
		(start 328.042524 -241.729006)
		(mid 328.226299 -241.678234)
		(end 328.411332 -241.72418)
		(width 0.09525)
		(layer "In2.Cu")
		(net "M_C_CPU0_SA_DQS_DN<3>")
	)
	(arc
		(start 339.32241 -241.729006)
		(mid 339.506185 -241.678234)
		(end 339.691218 -241.72418)
		(width 0.09525)
		(layer "In2.Cu")
		(net "M_C_CPU0_SA_DQS_DN<3>")
	)
	(segment
		(start 342.797892 -237.460028)
		(end 342.33104 -237.19409)
		(width 0.12954)
		(layer "F.Cu")
		(net "M_C_CPU0_SA_DQS_DN<2>")
	)
	(segment
		(start 320.269616 -231.487472)
		(end 320.548254 -231.76611)
		(width 0.16002)
		(layer "In2.Cu")
		(net "M_C_CPU0_SA_DQS_DN<2>")
	)
	(segment
		(start 311.939432 -220.421708)
		(end 312.136028 -220.618304)
		(width 0.16002)
		(layer "In2.Cu")
		(net "M_C_CPU0_SA_DQS_DN<2>")
	)
	(segment
		(start 299.080682 -219.012262)
		(end 300.711362 -219.012262)
		(width 0.16002)
		(layer "In2.Cu")
		(net "M_C_CPU0_SA_DQS_DN<2>")
	)
	(segment
		(start 318.895984 -230.11384)
		(end 319.174622 -230.392478)
		(width 0.16002)
		(layer "In2.Cu")
		(net "M_C_CPU0_SA_DQS_DN<2>")
	)
	(segment
		(start 332.171294 -236.864144)
		(end 332.179676 -236.86897)
		(width 0.09525)
		(layer "In2.Cu")
		(net "M_C_CPU0_SA_DQS_DN<2>")
	)
	(segment
		(start 337.442556 -236.86897)
		(end 337.450938 -236.864144)
		(width 0.09525)
		(layer "In2.Cu")
		(net "M_C_CPU0_SA_DQS_DN<2>")
	)
	(segment
		(start 319.629536 -231.487472)
		(end 320.269616 -231.487472)
		(width 0.16002)
		(layer "In2.Cu")
		(net "M_C_CPU0_SA_DQS_DN<2>")
	)
	(segment
		(start 310.56453 -219.046806)
		(end 310.762396 -219.244672)
		(width 0.16002)
		(layer "In2.Cu")
		(net "M_C_CPU0_SA_DQS_DN<2>")
	)
	(segment
		(start 297.509438 -220.177106)
		(end 298.362878 -219.323666)
		(width 0.16002)
		(layer "In2.Cu")
		(net "M_C_CPU0_SA_DQS_DN<2>")
	)
	(segment
		(start 325.203058 -234.904534)
		(end 325.203058 -235.238798)
		(width 0.09525)
		(layer "In2.Cu")
		(net "M_C_CPU0_SA_DQS_DN<2>")
	)
	(segment
		(start 304.339498 -220.194886)
		(end 304.928778 -220.194886)
		(width 0.16002)
		(layer "In2.Cu")
		(net "M_C_CPU0_SA_DQS_DN<2>")
	)
	(segment
		(start 308.29631 -219.046806)
		(end 308.492144 -219.24264)
		(width 0.16002)
		(layer "In2.Cu")
		(net "M_C_CPU0_SA_DQS_DN<2>")
	)
	(segment
		(start 328.411332 -236.864144)
		(end 328.419714 -236.86897)
		(width 0.09525)
		(layer "In2.Cu")
		(net "M_C_CPU0_SA_DQS_DN<2>")
	)
	(segment
		(start 319.174622 -231.032558)
		(end 319.629536 -231.487472)
		(width 0.16002)
		(layer "In2.Cu")
		(net "M_C_CPU0_SA_DQS_DN<2>")
	)
	(segment
		(start 340.631272 -236.864144)
		(end 340.639654 -236.86897)
		(width 0.09525)
		(layer "In2.Cu")
		(net "M_C_CPU0_SA_DQS_DN<2>")
	)
	(segment
		(start 306.554378 -219.046806)
		(end 308.29631 -219.046806)
		(width 0.16002)
		(layer "In2.Cu")
		(net "M_C_CPU0_SA_DQS_DN<2>")
	)
	(segment
		(start 310.482488 -220.328744)
		(end 310.85536 -220.701616)
		(width 0.16002)
		(layer "In2.Cu")
		(net "M_C_CPU0_SA_DQS_DN<2>")
	)
	(segment
		(start 308.865016 -220.075252)
		(end 309.392066 -220.075252)
		(width 0.16002)
		(layer "In2.Cu")
		(net "M_C_CPU0_SA_DQS_DN<2>")
	)
	(segment
		(start 320.548254 -231.76611)
		(end 320.548254 -232.40619)
		(width 0.16002)
		(layer "In2.Cu")
		(net "M_C_CPU0_SA_DQS_DN<2>")
	)
	(segment
		(start 292.280086 -220.285056)
		(end 292.553898 -220.011244)
		(width 0.16002)
		(layer "In2.Cu")
		(net "M_C_CPU0_SA_DQS_DN<2>")
	)
	(segment
		(start 328.027792 -236.877606)
		(end 328.042524 -236.86897)
		(width 0.09525)
		(layer "In2.Cu")
		(net "M_C_CPU0_SA_DQS_DN<2>")
	)
	(segment
		(start 312.136028 -220.895164)
		(end 311.85612 -221.175072)
		(width 0.16002)
		(layer "In2.Cu")
		(net "M_C_CPU0_SA_DQS_DN<2>")
	)
	(segment
		(start 336.87131 -236.864144)
		(end 336.879692 -236.86897)
		(width 0.09525)
		(layer "In2.Cu")
		(net "M_C_CPU0_SA_DQS_DN<2>")
	)
	(segment
		(start 323.978778 -234.624118)
		(end 324.922642 -234.624118)
		(width 0.09525)
		(layer "In2.Cu")
		(net "M_C_CPU0_SA_DQS_DN<2>")
	)
	(segment
		(start 311.382664 -220.701616)
		(end 311.662572 -220.421708)
		(width 0.16002)
		(layer "In2.Cu")
		(net "M_C_CPU0_SA_DQS_DN<2>")
	)
	(segment
		(start 317.953898 -229.811834)
		(end 318.255904 -230.11384)
		(width 0.16002)
		(layer "In2.Cu")
		(net "M_C_CPU0_SA_DQS_DN<2>")
	)
	(segment
		(start 310.762396 -219.521532)
		(end 310.482488 -219.80144)
		(width 0.16002)
		(layer "In2.Cu")
		(net "M_C_CPU0_SA_DQS_DN<2>")
	)
	(segment
		(start 294.716708 -220.011244)
		(end 294.865806 -219.862146)
		(width 0.16002)
		(layer "In2.Cu")
		(net "M_C_CPU0_SA_DQS_DN<2>")
	)
	(segment
		(start 326.79894 -236.21492)
		(end 327.364598 -236.780578)
		(width 0.09525)
		(layer "In2.Cu")
		(net "M_C_CPU0_SA_DQS_DN<2>")
	)
	(segment
		(start 308.492144 -219.70238)
		(end 308.865016 -220.075252)
		(width 0.16002)
		(layer "In2.Cu")
		(net "M_C_CPU0_SA_DQS_DN<2>")
	)
	(segment
		(start 332.74254 -236.86897)
		(end 332.750922 -236.864144)
		(width 0.09525)
		(layer "In2.Cu")
		(net "M_C_CPU0_SA_DQS_DN<2>")
	)
	(segment
		(start 341.202518 -236.86897)
		(end 341.2109 -236.864144)
		(width 0.09525)
		(layer "In2.Cu")
		(net "M_C_CPU0_SA_DQS_DN<2>")
	)
	(segment
		(start 325.203058 -235.238798)
		(end 326.17918 -236.21492)
		(width 0.09525)
		(layer "In2.Cu")
		(net "M_C_CPU0_SA_DQS_DN<2>")
	)
	(segment
		(start 304.049938 -219.905326)
		(end 304.339498 -220.194886)
		(width 0.16002)
		(layer "In2.Cu")
		(net "M_C_CPU0_SA_DQS_DN<2>")
	)
	(segment
		(start 323.919596 -234.6833)
		(end 323.978778 -234.624118)
		(width 0.09525)
		(layer "In2.Cu")
		(net "M_C_CPU0_SA_DQS_DN<2>")
	)
	(segment
		(start 298.362878 -219.323666)
		(end 298.769278 -219.323666)
		(width 0.16002)
		(layer "In2.Cu")
		(net "M_C_CPU0_SA_DQS_DN<2>")
	)
	(segment
		(start 305.726338 -219.397326)
		(end 306.203858 -219.397326)
		(width 0.16002)
		(layer "In2.Cu")
		(net "M_C_CPU0_SA_DQS_DN<2>")
	)
	(segment
		(start 310.85536 -220.701616)
		(end 311.382664 -220.701616)
		(width 0.16002)
		(layer "In2.Cu")
		(net "M_C_CPU0_SA_DQS_DN<2>")
	)
	(segment
		(start 326.17918 -236.21492)
		(end 326.79894 -236.21492)
		(width 0.09525)
		(layer "In2.Cu")
		(net "M_C_CPU0_SA_DQS_DN<2>")
	)
	(segment
		(start 317.953898 -227.800154)
		(end 317.953898 -229.811834)
		(width 0.16002)
		(layer "In2.Cu")
		(net "M_C_CPU0_SA_DQS_DN<2>")
	)
	(segment
		(start 342.177116 -236.92866)
		(end 342.33104 -237.19409)
		(width 0.09525)
		(layer "In2.Cu")
		(net "M_C_CPU0_SA_DQS_DN<2>")
	)
	(segment
		(start 309.764938 -219.24264)
		(end 309.960772 -219.046806)
		(width 0.16002)
		(layer "In2.Cu")
		(net "M_C_CPU0_SA_DQS_DN<2>")
	)
	(segment
		(start 322.825364 -234.6833)
		(end 323.895974 -234.6833)
		(width 0.16002)
		(layer "In2.Cu")
		(net "M_C_CPU0_SA_DQS_DN<2>")
	)
	(segment
		(start 306.203858 -219.397326)
		(end 306.554378 -219.046806)
		(width 0.16002)
		(layer "In2.Cu")
		(net "M_C_CPU0_SA_DQS_DN<2>")
	)
	(segment
		(start 296.808398 -220.177106)
		(end 297.509438 -220.177106)
		(width 0.16002)
		(layer "In2.Cu")
		(net "M_C_CPU0_SA_DQS_DN<2>")
	)
	(segment
		(start 308.492144 -219.24264)
		(end 308.492144 -219.70238)
		(width 0.16002)
		(layer "In2.Cu")
		(net "M_C_CPU0_SA_DQS_DN<2>")
	)
	(segment
		(start 304.928778 -220.194886)
		(end 305.726338 -219.397326)
		(width 0.16002)
		(layer "In2.Cu")
		(net "M_C_CPU0_SA_DQS_DN<2>")
	)
	(segment
		(start 323.895974 -234.6833)
		(end 323.919596 -234.6833)
		(width 0.09525)
		(layer "In2.Cu")
		(net "M_C_CPU0_SA_DQS_DN<2>")
	)
	(segment
		(start 301.604426 -219.905326)
		(end 304.049938 -219.905326)
		(width 0.16002)
		(layer "In2.Cu")
		(net "M_C_CPU0_SA_DQS_DN<2>")
	)
	(segment
		(start 298.769278 -219.323666)
		(end 299.080682 -219.012262)
		(width 0.16002)
		(layer "In2.Cu")
		(net "M_C_CPU0_SA_DQS_DN<2>")
	)
	(segment
		(start 328.982578 -236.86897)
		(end 328.99096 -236.864144)
		(width 0.09525)
		(layer "In2.Cu")
		(net "M_C_CPU0_SA_DQS_DN<2>")
	)
	(segment
		(start 310.762396 -219.244672)
		(end 310.762396 -219.521532)
		(width 0.16002)
		(layer "In2.Cu")
		(net "M_C_CPU0_SA_DQS_DN<2>")
	)
	(segment
		(start 321.921886 -233.779822)
		(end 322.825364 -234.6833)
		(width 0.16002)
		(layer "In2.Cu")
		(net "M_C_CPU0_SA_DQS_DN<2>")
	)
	(segment
		(start 331.23124 -236.864144)
		(end 331.239622 -236.86897)
		(width 0.09525)
		(layer "In2.Cu")
		(net "M_C_CPU0_SA_DQS_DN<2>")
	)
	(segment
		(start 321.921886 -233.139742)
		(end 321.921886 -233.779822)
		(width 0.16002)
		(layer "In2.Cu")
		(net "M_C_CPU0_SA_DQS_DN<2>")
	)
	(segment
		(start 309.960772 -219.046806)
		(end 310.56453 -219.046806)
		(width 0.16002)
		(layer "In2.Cu")
		(net "M_C_CPU0_SA_DQS_DN<2>")
	)
	(segment
		(start 320.548254 -232.40619)
		(end 321.003168 -232.861104)
		(width 0.16002)
		(layer "In2.Cu")
		(net "M_C_CPU0_SA_DQS_DN<2>")
	)
	(segment
		(start 321.003168 -232.861104)
		(end 321.643248 -232.861104)
		(width 0.16002)
		(layer "In2.Cu")
		(net "M_C_CPU0_SA_DQS_DN<2>")
	)
	(segment
		(start 311.85612 -221.175072)
		(end 311.85612 -221.702376)
		(width 0.16002)
		(layer "In2.Cu")
		(net "M_C_CPU0_SA_DQS_DN<2>")
	)
	(segment
		(start 309.764938 -219.70238)
		(end 309.764938 -219.24264)
		(width 0.16002)
		(layer "In2.Cu")
		(net "M_C_CPU0_SA_DQS_DN<2>")
	)
	(segment
		(start 321.643248 -232.861104)
		(end 321.921886 -233.139742)
		(width 0.16002)
		(layer "In2.Cu")
		(net "M_C_CPU0_SA_DQS_DN<2>")
	)
	(segment
		(start 294.865806 -219.862146)
		(end 296.493438 -219.862146)
		(width 0.16002)
		(layer "In2.Cu")
		(net "M_C_CPU0_SA_DQS_DN<2>")
	)
	(segment
		(start 312.136028 -220.618304)
		(end 312.136028 -220.895164)
		(width 0.16002)
		(layer "In2.Cu")
		(net "M_C_CPU0_SA_DQS_DN<2>")
	)
	(segment
		(start 311.85612 -221.702376)
		(end 317.953898 -227.800154)
		(width 0.16002)
		(layer "In2.Cu")
		(net "M_C_CPU0_SA_DQS_DN<2>")
	)
	(segment
		(start 300.711362 -219.012262)
		(end 301.604426 -219.905326)
		(width 0.16002)
		(layer "In2.Cu")
		(net "M_C_CPU0_SA_DQS_DN<2>")
	)
	(segment
		(start 292.553898 -220.011244)
		(end 294.716708 -220.011244)
		(width 0.16002)
		(layer "In2.Cu")
		(net "M_C_CPU0_SA_DQS_DN<2>")
	)
	(segment
		(start 309.392066 -220.075252)
		(end 309.764938 -219.70238)
		(width 0.16002)
		(layer "In2.Cu")
		(net "M_C_CPU0_SA_DQS_DN<2>")
	)
	(segment
		(start 311.662572 -220.421708)
		(end 311.939432 -220.421708)
		(width 0.16002)
		(layer "In2.Cu")
		(net "M_C_CPU0_SA_DQS_DN<2>")
	)
	(segment
		(start 318.255904 -230.11384)
		(end 318.895984 -230.11384)
		(width 0.16002)
		(layer "In2.Cu")
		(net "M_C_CPU0_SA_DQS_DN<2>")
	)
	(segment
		(start 319.174622 -230.392478)
		(end 319.174622 -231.032558)
		(width 0.16002)
		(layer "In2.Cu")
		(net "M_C_CPU0_SA_DQS_DN<2>")
	)
	(segment
		(start 333.682594 -236.86897)
		(end 333.690976 -236.864144)
		(width 0.09525)
		(layer "In2.Cu")
		(net "M_C_CPU0_SA_DQS_DN<2>")
	)
	(segment
		(start 342.076278 -236.90199)
		(end 342.177116 -236.92866)
		(width 0.09525)
		(layer "In2.Cu")
		(net "M_C_CPU0_SA_DQS_DN<2>")
	)
	(segment
		(start 339.691218 -236.864144)
		(end 339.6996 -236.86897)
		(width 0.09525)
		(layer "In2.Cu")
		(net "M_C_CPU0_SA_DQS_DN<2>")
	)
	(segment
		(start 310.482488 -219.80144)
		(end 310.482488 -220.328744)
		(width 0.16002)
		(layer "In2.Cu")
		(net "M_C_CPU0_SA_DQS_DN<2>")
	)
	(segment
		(start 324.922642 -234.624118)
		(end 325.203058 -234.904534)
		(width 0.09525)
		(layer "In2.Cu")
		(net "M_C_CPU0_SA_DQS_DN<2>")
	)
	(segment
		(start 296.493438 -219.862146)
		(end 296.808398 -220.177106)
		(width 0.16002)
		(layer "In2.Cu")
		(net "M_C_CPU0_SA_DQS_DN<2>")
	)
	(segment
		(start 335.931256 -236.864144)
		(end 335.939638 -236.86897)
		(width 0.09525)
		(layer "In2.Cu")
		(net "M_C_CPU0_SA_DQS_DN<2>")
	)
	(arc
		(start 338.759546 -236.86897)
		(mid 339.040978 -236.944725)
		(end 339.32241 -236.86897)
		(width 0.09525)
		(layer "In2.Cu")
		(net "M_C_CPU0_SA_DQS_DN<2>")
	)
	(arc
		(start 327.479152 -236.86897)
		(mid 327.752334 -236.944912)
		(end 328.027792 -236.877606)
		(width 0.09525)
		(layer "In2.Cu")
		(net "M_C_CPU0_SA_DQS_DN<2>")
	)
	(arc
		(start 342.055958 -236.909864)
		(mid 342.066157 -236.906027)
		(end 342.076278 -236.90199)
		(width 0.09525)
		(layer "In2.Cu")
		(net "M_C_CPU0_SA_DQS_DN<2>")
	)
	(arc
		(start 331.802486 -236.86897)
		(mid 331.986261 -236.818198)
		(end 332.171294 -236.864144)
		(width 0.09525)
		(layer "In2.Cu")
		(net "M_C_CPU0_SA_DQS_DN<2>")
	)
	(arc
		(start 341.2109 -236.864144)
		(mid 341.395932 -236.81823)
		(end 341.579708 -236.86897)
		(width 0.09525)
		(layer "In2.Cu")
		(net "M_C_CPU0_SA_DQS_DN<2>")
	)
	(arc
		(start 327.364598 -236.780578)
		(mid 327.419008 -236.828491)
		(end 327.479152 -236.86897)
		(width 0.09525)
		(layer "In2.Cu")
		(net "M_C_CPU0_SA_DQS_DN<2>")
	)
	(arc
		(start 339.6996 -236.86897)
		(mid 339.981032 -236.944725)
		(end 340.262464 -236.86897)
		(width 0.09525)
		(layer "In2.Cu")
		(net "M_C_CPU0_SA_DQS_DN<2>")
	)
	(arc
		(start 336.879692 -236.86897)
		(mid 337.161124 -236.944725)
		(end 337.442556 -236.86897)
		(width 0.09525)
		(layer "In2.Cu")
		(net "M_C_CPU0_SA_DQS_DN<2>")
	)
	(arc
		(start 329.922632 -236.86897)
		(mid 330.1111 -236.818293)
		(end 330.299568 -236.86897)
		(width 0.09525)
		(layer "In2.Cu")
		(net "M_C_CPU0_SA_DQS_DN<2>")
	)
	(arc
		(start 341.579708 -236.86897)
		(mid 341.813252 -236.942676)
		(end 342.055958 -236.909864)
		(width 0.09525)
		(layer "In2.Cu")
		(net "M_C_CPU0_SA_DQS_DN<2>")
	)
	(arc
		(start 328.419714 -236.86897)
		(mid 328.701146 -236.944725)
		(end 328.982578 -236.86897)
		(width 0.09525)
		(layer "In2.Cu")
		(net "M_C_CPU0_SA_DQS_DN<2>")
	)
	(arc
		(start 332.750922 -236.864144)
		(mid 332.935954 -236.81823)
		(end 333.11973 -236.86897)
		(width 0.09525)
		(layer "In2.Cu")
		(net "M_C_CPU0_SA_DQS_DN<2>")
	)
	(arc
		(start 334.999584 -236.86897)
		(mid 335.281016 -236.944725)
		(end 335.562448 -236.86897)
		(width 0.09525)
		(layer "In2.Cu")
		(net "M_C_CPU0_SA_DQS_DN<2>")
	)
	(arc
		(start 330.299568 -236.86897)
		(mid 330.581 -236.944725)
		(end 330.862432 -236.86897)
		(width 0.09525)
		(layer "In2.Cu")
		(net "M_C_CPU0_SA_DQS_DN<2>")
	)
	(arc
		(start 334.059784 -236.86897)
		(mid 334.341216 -236.944725)
		(end 334.622648 -236.86897)
		(width 0.09525)
		(layer "In2.Cu")
		(net "M_C_CPU0_SA_DQS_DN<2>")
	)
	(arc
		(start 338.38261 -236.86897)
		(mid 338.571078 -236.818293)
		(end 338.759546 -236.86897)
		(width 0.09525)
		(layer "In2.Cu")
		(net "M_C_CPU0_SA_DQS_DN<2>")
	)
	(arc
		(start 334.622648 -236.86897)
		(mid 334.811116 -236.818293)
		(end 334.999584 -236.86897)
		(width 0.09525)
		(layer "In2.Cu")
		(net "M_C_CPU0_SA_DQS_DN<2>")
	)
	(arc
		(start 328.042524 -236.86897)
		(mid 328.226299 -236.818198)
		(end 328.411332 -236.864144)
		(width 0.09525)
		(layer "In2.Cu")
		(net "M_C_CPU0_SA_DQS_DN<2>")
	)
	(arc
		(start 335.562448 -236.86897)
		(mid 335.746223 -236.818198)
		(end 335.931256 -236.864144)
		(width 0.09525)
		(layer "In2.Cu")
		(net "M_C_CPU0_SA_DQS_DN<2>")
	)
	(arc
		(start 337.819746 -236.86897)
		(mid 338.101178 -236.944725)
		(end 338.38261 -236.86897)
		(width 0.09525)
		(layer "In2.Cu")
		(net "M_C_CPU0_SA_DQS_DN<2>")
	)
	(arc
		(start 333.11973 -236.86897)
		(mid 333.401162 -236.944725)
		(end 333.682594 -236.86897)
		(width 0.09525)
		(layer "In2.Cu")
		(net "M_C_CPU0_SA_DQS_DN<2>")
	)
	(arc
		(start 333.690976 -236.864144)
		(mid 333.876008 -236.81823)
		(end 334.059784 -236.86897)
		(width 0.09525)
		(layer "In2.Cu")
		(net "M_C_CPU0_SA_DQS_DN<2>")
	)
	(arc
		(start 332.179676 -236.86897)
		(mid 332.461108 -236.944725)
		(end 332.74254 -236.86897)
		(width 0.09525)
		(layer "In2.Cu")
		(net "M_C_CPU0_SA_DQS_DN<2>")
	)
	(arc
		(start 336.502502 -236.86897)
		(mid 336.686277 -236.818198)
		(end 336.87131 -236.864144)
		(width 0.09525)
		(layer "In2.Cu")
		(net "M_C_CPU0_SA_DQS_DN<2>")
	)
	(arc
		(start 330.862432 -236.86897)
		(mid 331.046207 -236.818198)
		(end 331.23124 -236.864144)
		(width 0.09525)
		(layer "In2.Cu")
		(net "M_C_CPU0_SA_DQS_DN<2>")
	)
	(arc
		(start 335.939638 -236.86897)
		(mid 336.22107 -236.944725)
		(end 336.502502 -236.86897)
		(width 0.09525)
		(layer "In2.Cu")
		(net "M_C_CPU0_SA_DQS_DN<2>")
	)
	(arc
		(start 328.99096 -236.864144)
		(mid 329.175992 -236.81823)
		(end 329.359768 -236.86897)
		(width 0.09525)
		(layer "In2.Cu")
		(net "M_C_CPU0_SA_DQS_DN<2>")
	)
	(arc
		(start 337.450938 -236.864144)
		(mid 337.63597 -236.81823)
		(end 337.819746 -236.86897)
		(width 0.09525)
		(layer "In2.Cu")
		(net "M_C_CPU0_SA_DQS_DN<2>")
	)
	(arc
		(start 340.262464 -236.86897)
		(mid 340.446239 -236.818198)
		(end 340.631272 -236.864144)
		(width 0.09525)
		(layer "In2.Cu")
		(net "M_C_CPU0_SA_DQS_DN<2>")
	)
	(arc
		(start 340.639654 -236.86897)
		(mid 340.921086 -236.944725)
		(end 341.202518 -236.86897)
		(width 0.09525)
		(layer "In2.Cu")
		(net "M_C_CPU0_SA_DQS_DN<2>")
	)
	(arc
		(start 331.239622 -236.86897)
		(mid 331.521054 -236.944725)
		(end 331.802486 -236.86897)
		(width 0.09525)
		(layer "In2.Cu")
		(net "M_C_CPU0_SA_DQS_DN<2>")
	)
	(arc
		(start 339.32241 -236.86897)
		(mid 339.506185 -236.818198)
		(end 339.691218 -236.864144)
		(width 0.09525)
		(layer "In2.Cu")
		(net "M_C_CPU0_SA_DQS_DN<2>")
	)
	(arc
		(start 329.359768 -236.86897)
		(mid 329.6412 -236.944725)
		(end 329.922632 -236.86897)
		(width 0.09525)
		(layer "In2.Cu")
		(net "M_C_CPU0_SA_DQS_DN<2>")
	)
	(segment
		(start 342.797892 -232.599992)
		(end 342.33104 -232.334054)
		(width 0.12954)
		(layer "F.Cu")
		(net "M_C_CPU0_SA_DQS_DN<1>")
	)
	(segment
		(start 335.931256 -232.004108)
		(end 335.939638 -232.008934)
		(width 0.09525)
		(layer "In2.Cu")
		(net "M_C_CPU0_SA_DQS_DN<1>")
	)
	(segment
		(start 320.274442 -219.754958)
		(end 319.468754 -220.560646)
		(width 0.16002)
		(layer "In2.Cu")
		(net "M_C_CPU0_SA_DQS_DN<1>")
	)
	(segment
		(start 326.53986 -228.76891)
		(end 326.57161 -228.787198)
		(width 0.09525)
		(layer "In2.Cu")
		(net "M_C_CPU0_SA_DQS_DN<1>")
	)
	(segment
		(start 321.055238 -220.774514)
		(end 321.332098 -220.774514)
		(width 0.16002)
		(layer "In2.Cu")
		(net "M_C_CPU0_SA_DQS_DN<1>")
	)
	(segment
		(start 336.87131 -232.004108)
		(end 336.879692 -232.008934)
		(width 0.09525)
		(layer "In2.Cu")
		(net "M_C_CPU0_SA_DQS_DN<1>")
	)
	(segment
		(start 327.010014 -229.578916)
		(end 327.04024 -229.596442)
		(width 0.09525)
		(layer "In2.Cu")
		(net "M_C_CPU0_SA_DQS_DN<1>")
	)
	(segment
		(start 305.726338 -210.047332)
		(end 306.203858 -210.047332)
		(width 0.16002)
		(layer "In2.Cu")
		(net "M_C_CPU0_SA_DQS_DN<1>")
	)
	(segment
		(start 319.468754 -221.08795)
		(end 319.841626 -221.460822)
		(width 0.16002)
		(layer "In2.Cu")
		(net "M_C_CPU0_SA_DQS_DN<1>")
	)
	(segment
		(start 318.467994 -220.08719)
		(end 318.995298 -220.08719)
		(width 0.16002)
		(layer "In2.Cu")
		(net "M_C_CPU0_SA_DQS_DN<1>")
	)
	(segment
		(start 326.069706 -227.959158)
		(end 326.06996 -227.959158)
		(width 0.09525)
		(layer "In2.Cu")
		(net "M_C_CPU0_SA_DQS_DN<1>")
	)
	(segment
		(start 321.528694 -220.97111)
		(end 321.528694 -221.24797)
		(width 0.16002)
		(layer "In2.Cu")
		(net "M_C_CPU0_SA_DQS_DN<1>")
	)
	(segment
		(start 320.077846 -219.281502)
		(end 320.274442 -219.478098)
		(width 0.16002)
		(layer "In2.Cu")
		(net "M_C_CPU0_SA_DQS_DN<1>")
	)
	(segment
		(start 304.049938 -210.555332)
		(end 304.339498 -210.844892)
		(width 0.16002)
		(layer "In2.Cu")
		(net "M_C_CPU0_SA_DQS_DN<1>")
	)
	(segment
		(start 341.202518 -232.008934)
		(end 341.2109 -232.004108)
		(width 0.09525)
		(layer "In2.Cu")
		(net "M_C_CPU0_SA_DQS_DN<1>")
	)
	(segment
		(start 320.842386 -221.934278)
		(end 320.842386 -222.461582)
		(width 0.16002)
		(layer "In2.Cu")
		(net "M_C_CPU0_SA_DQS_DN<1>")
	)
	(segment
		(start 298.362878 -209.973672)
		(end 298.769278 -209.973672)
		(width 0.16002)
		(layer "In2.Cu")
		(net "M_C_CPU0_SA_DQS_DN<1>")
	)
	(segment
		(start 324.517004 -226.291902)
		(end 324.94093 -226.291902)
		(width 0.09525)
		(layer "In2.Cu")
		(net "M_C_CPU0_SA_DQS_DN<1>")
	)
	(segment
		(start 320.36893 -221.460822)
		(end 321.055238 -220.774514)
		(width 0.16002)
		(layer "In2.Cu")
		(net "M_C_CPU0_SA_DQS_DN<1>")
	)
	(segment
		(start 321.332098 -220.774514)
		(end 321.528694 -220.97111)
		(width 0.16002)
		(layer "In2.Cu")
		(net "M_C_CPU0_SA_DQS_DN<1>")
	)
	(segment
		(start 327.949814 -231.198928)
		(end 327.98131 -231.217216)
		(width 0.09525)
		(layer "In2.Cu")
		(net "M_C_CPU0_SA_DQS_DN<1>")
	)
	(segment
		(start 318.134238 -219.753434)
		(end 318.467994 -220.08719)
		(width 0.16002)
		(layer "In2.Cu")
		(net "M_C_CPU0_SA_DQS_DN<1>")
	)
	(segment
		(start 301.616618 -210.555332)
		(end 304.049938 -210.555332)
		(width 0.16002)
		(layer "In2.Cu")
		(net "M_C_CPU0_SA_DQS_DN<1>")
	)
	(segment
		(start 325.31939 -226.663758)
		(end 325.318882 -226.664266)
		(width 0.09525)
		(layer "In2.Cu")
		(net "M_C_CPU0_SA_DQS_DN<1>")
	)
	(segment
		(start 323.745098 -225.364294)
		(end 323.745098 -226.01301)
		(width 0.16002)
		(layer "In2.Cu")
		(net "M_C_CPU0_SA_DQS_DN<1>")
	)
	(segment
		(start 331.23124 -232.004108)
		(end 331.239622 -232.008934)
		(width 0.09525)
		(layer "In2.Cu")
		(net "M_C_CPU0_SA_DQS_DN<1>")
	)
	(segment
		(start 325.319136 -226.592892)
		(end 325.31939 -226.592638)
		(width 0.09525)
		(layer "In2.Cu")
		(net "M_C_CPU0_SA_DQS_DN<1>")
	)
	(segment
		(start 327.443338 -230.367586)
		(end 327.479914 -230.388922)
		(width 0.09525)
		(layer "In2.Cu")
		(net "M_C_CPU0_SA_DQS_DN<1>")
	)
	(segment
		(start 323.745098 -226.01301)
		(end 324.082918 -226.35083)
		(width 0.16002)
		(layer "In2.Cu")
		(net "M_C_CPU0_SA_DQS_DN<1>")
	)
	(segment
		(start 326.506332 -228.749352)
		(end 326.53986 -228.76891)
		(width 0.09525)
		(layer "In2.Cu")
		(net "M_C_CPU0_SA_DQS_DN<1>")
	)
	(segment
		(start 320.274442 -219.478098)
		(end 320.274442 -219.754958)
		(width 0.16002)
		(layer "In2.Cu")
		(net "M_C_CPU0_SA_DQS_DN<1>")
	)
	(segment
		(start 337.442556 -232.008934)
		(end 337.450938 -232.004108)
		(width 0.09525)
		(layer "In2.Cu")
		(net "M_C_CPU0_SA_DQS_DN<1>")
	)
	(segment
		(start 321.528694 -221.24797)
		(end 320.842386 -221.934278)
		(width 0.16002)
		(layer "In2.Cu")
		(net "M_C_CPU0_SA_DQS_DN<1>")
	)
	(segment
		(start 332.74254 -232.008934)
		(end 332.750922 -232.004108)
		(width 0.09525)
		(layer "In2.Cu")
		(net "M_C_CPU0_SA_DQS_DN<1>")
	)
	(segment
		(start 292.280086 -210.935062)
		(end 292.553898 -210.66125)
		(width 0.16002)
		(layer "In2.Cu")
		(net "M_C_CPU0_SA_DQS_DN<1>")
	)
	(segment
		(start 328.982578 -232.008934)
		(end 328.99096 -232.004108)
		(width 0.09525)
		(layer "In2.Cu")
		(net "M_C_CPU0_SA_DQS_DN<1>")
	)
	(segment
		(start 324.458076 -226.35083)
		(end 324.517004 -226.291902)
		(width 0.09525)
		(layer "In2.Cu")
		(net "M_C_CPU0_SA_DQS_DN<1>")
	)
	(segment
		(start 296.493438 -210.512152)
		(end 296.808398 -210.827112)
		(width 0.16002)
		(layer "In2.Cu")
		(net "M_C_CPU0_SA_DQS_DN<1>")
	)
	(segment
		(start 297.509438 -210.827112)
		(end 298.362878 -209.973672)
		(width 0.16002)
		(layer "In2.Cu")
		(net "M_C_CPU0_SA_DQS_DN<1>")
	)
	(segment
		(start 324.434454 -226.35083)
		(end 324.458076 -226.35083)
		(width 0.09525)
		(layer "In2.Cu")
		(net "M_C_CPU0_SA_DQS_DN<1>")
	)
	(segment
		(start 319.841626 -221.460822)
		(end 320.36893 -221.460822)
		(width 0.16002)
		(layer "In2.Cu")
		(net "M_C_CPU0_SA_DQS_DN<1>")
	)
	(segment
		(start 294.863266 -210.512152)
		(end 296.493438 -210.512152)
		(width 0.16002)
		(layer "In2.Cu")
		(net "M_C_CPU0_SA_DQS_DN<1>")
	)
	(segment
		(start 326.031606 -227.93706)
		(end 326.069706 -227.959158)
		(width 0.09525)
		(layer "In2.Cu")
		(net "M_C_CPU0_SA_DQS_DN<1>")
	)
	(segment
		(start 326.971914 -229.556818)
		(end 327.010014 -229.578916)
		(width 0.09525)
		(layer "In2.Cu")
		(net "M_C_CPU0_SA_DQS_DN<1>")
	)
	(segment
		(start 300.723554 -209.662268)
		(end 301.616618 -210.555332)
		(width 0.16002)
		(layer "In2.Cu")
		(net "M_C_CPU0_SA_DQS_DN<1>")
	)
	(segment
		(start 327.912222 -231.177084)
		(end 327.949814 -231.198928)
		(width 0.09525)
		(layer "In2.Cu")
		(net "M_C_CPU0_SA_DQS_DN<1>")
	)
	(segment
		(start 299.080682 -209.662268)
		(end 300.723554 -209.662268)
		(width 0.16002)
		(layer "In2.Cu")
		(net "M_C_CPU0_SA_DQS_DN<1>")
	)
	(segment
		(start 318.134238 -217.942414)
		(end 318.134238 -219.753434)
		(width 0.16002)
		(layer "In2.Cu")
		(net "M_C_CPU0_SA_DQS_DN<1>")
	)
	(segment
		(start 306.554378 -209.696812)
		(end 309.888636 -209.696812)
		(width 0.16002)
		(layer "In2.Cu")
		(net "M_C_CPU0_SA_DQS_DN<1>")
	)
	(segment
		(start 328.381614 -231.986836)
		(end 328.419714 -232.008934)
		(width 0.09525)
		(layer "In2.Cu")
		(net "M_C_CPU0_SA_DQS_DN<1>")
	)
	(segment
		(start 342.177116 -232.068624)
		(end 342.33104 -232.334054)
		(width 0.09525)
		(layer "In2.Cu")
		(net "M_C_CPU0_SA_DQS_DN<1>")
	)
	(segment
		(start 298.769278 -209.973672)
		(end 299.080682 -209.662268)
		(width 0.16002)
		(layer "In2.Cu")
		(net "M_C_CPU0_SA_DQS_DN<1>")
	)
	(segment
		(start 296.808398 -210.827112)
		(end 297.509438 -210.827112)
		(width 0.16002)
		(layer "In2.Cu")
		(net "M_C_CPU0_SA_DQS_DN<1>")
	)
	(segment
		(start 294.714168 -210.66125)
		(end 294.863266 -210.512152)
		(width 0.16002)
		(layer "In2.Cu")
		(net "M_C_CPU0_SA_DQS_DN<1>")
	)
	(segment
		(start 332.171294 -232.004108)
		(end 332.179676 -232.008934)
		(width 0.09525)
		(layer "In2.Cu")
		(net "M_C_CPU0_SA_DQS_DN<1>")
	)
	(segment
		(start 327.479914 -230.388922)
		(end 327.512426 -230.407718)
		(width 0.09525)
		(layer "In2.Cu")
		(net "M_C_CPU0_SA_DQS_DN<1>")
	)
	(segment
		(start 292.553898 -210.66125)
		(end 294.714168 -210.66125)
		(width 0.16002)
		(layer "In2.Cu")
		(net "M_C_CPU0_SA_DQS_DN<1>")
	)
	(segment
		(start 324.082918 -226.35083)
		(end 324.434454 -226.35083)
		(width 0.16002)
		(layer "In2.Cu")
		(net "M_C_CPU0_SA_DQS_DN<1>")
	)
	(segment
		(start 325.21017 -226.403408)
		(end 325.262494 -226.455732)
		(width 0.09525)
		(layer "In2.Cu")
		(net "M_C_CPU0_SA_DQS_DN<1>")
	)
	(segment
		(start 318.995298 -220.08719)
		(end 319.800986 -219.281502)
		(width 0.16002)
		(layer "In2.Cu")
		(net "M_C_CPU0_SA_DQS_DN<1>")
	)
	(segment
		(start 342.076278 -232.041954)
		(end 342.177116 -232.068624)
		(width 0.09525)
		(layer "In2.Cu")
		(net "M_C_CPU0_SA_DQS_DN<1>")
	)
	(segment
		(start 326.06996 -227.959158)
		(end 326.10552 -227.979732)
		(width 0.09525)
		(layer "In2.Cu")
		(net "M_C_CPU0_SA_DQS_DN<1>")
	)
	(segment
		(start 325.31939 -226.592638)
		(end 325.31939 -226.663758)
		(width 0.09525)
		(layer "In2.Cu")
		(net "M_C_CPU0_SA_DQS_DN<1>")
	)
	(segment
		(start 304.339498 -210.844892)
		(end 304.928778 -210.844892)
		(width 0.16002)
		(layer "In2.Cu")
		(net "M_C_CPU0_SA_DQS_DN<1>")
	)
	(segment
		(start 325.561706 -227.127054)
		(end 325.599806 -227.149152)
		(width 0.09525)
		(layer "In2.Cu")
		(net "M_C_CPU0_SA_DQS_DN<1>")
	)
	(segment
		(start 340.631272 -232.004108)
		(end 340.639654 -232.008934)
		(width 0.09525)
		(layer "In2.Cu")
		(net "M_C_CPU0_SA_DQS_DN<1>")
	)
	(segment
		(start 306.203858 -210.047332)
		(end 306.554378 -209.696812)
		(width 0.16002)
		(layer "In2.Cu")
		(net "M_C_CPU0_SA_DQS_DN<1>")
	)
	(segment
		(start 319.468754 -220.560646)
		(end 319.468754 -221.08795)
		(width 0.16002)
		(layer "In2.Cu")
		(net "M_C_CPU0_SA_DQS_DN<1>")
	)
	(segment
		(start 339.691218 -232.004108)
		(end 339.6996 -232.008934)
		(width 0.09525)
		(layer "In2.Cu")
		(net "M_C_CPU0_SA_DQS_DN<1>")
	)
	(segment
		(start 320.842386 -222.461582)
		(end 323.745098 -225.364294)
		(width 0.16002)
		(layer "In2.Cu")
		(net "M_C_CPU0_SA_DQS_DN<1>")
	)
	(segment
		(start 319.800986 -219.281502)
		(end 320.077846 -219.281502)
		(width 0.16002)
		(layer "In2.Cu")
		(net "M_C_CPU0_SA_DQS_DN<1>")
	)
	(segment
		(start 309.888636 -209.696812)
		(end 318.134238 -217.942414)
		(width 0.16002)
		(layer "In2.Cu")
		(net "M_C_CPU0_SA_DQS_DN<1>")
	)
	(segment
		(start 325.599806 -227.149152)
		(end 325.631302 -227.16744)
		(width 0.09525)
		(layer "In2.Cu")
		(net "M_C_CPU0_SA_DQS_DN<1>")
	)
	(segment
		(start 333.682594 -232.008934)
		(end 333.690976 -232.004108)
		(width 0.09525)
		(layer "In2.Cu")
		(net "M_C_CPU0_SA_DQS_DN<1>")
	)
	(segment
		(start 304.928778 -210.844892)
		(end 305.726338 -210.047332)
		(width 0.16002)
		(layer "In2.Cu")
		(net "M_C_CPU0_SA_DQS_DN<1>")
	)
	(arc
		(start 341.579708 -232.008934)
		(mid 341.813252 -232.08264)
		(end 342.055958 -232.049828)
		(width 0.09525)
		(layer "In2.Cu")
		(net "M_C_CPU0_SA_DQS_DN<1>")
	)
	(arc
		(start 325.788782 -227.474272)
		(mid 325.853179 -227.735578)
		(end 326.031606 -227.93706)
		(width 0.09525)
		(layer "In2.Cu")
		(net "M_C_CPU0_SA_DQS_DN<1>")
	)
	(arc
		(start 326.259444 -228.284024)
		(mid 326.324997 -228.547396)
		(end 326.506332 -228.749352)
		(width 0.09525)
		(layer "In2.Cu")
		(net "M_C_CPU0_SA_DQS_DN<1>")
	)
	(arc
		(start 325.318882 -226.664266)
		(mid 325.383279 -226.925572)
		(end 325.561706 -227.127054)
		(width 0.09525)
		(layer "In2.Cu")
		(net "M_C_CPU0_SA_DQS_DN<1>")
	)
	(arc
		(start 330.299568 -232.008934)
		(mid 330.581 -232.084689)
		(end 330.862432 -232.008934)
		(width 0.09525)
		(layer "In2.Cu")
		(net "M_C_CPU0_SA_DQS_DN<1>")
	)
	(arc
		(start 328.419714 -232.008934)
		(mid 328.701146 -232.084689)
		(end 328.982578 -232.008934)
		(width 0.09525)
		(layer "In2.Cu")
		(net "M_C_CPU0_SA_DQS_DN<1>")
	)
	(arc
		(start 328.99096 -232.004108)
		(mid 329.175992 -231.958194)
		(end 329.359768 -232.008934)
		(width 0.09525)
		(layer "In2.Cu")
		(net "M_C_CPU0_SA_DQS_DN<1>")
	)
	(arc
		(start 324.94093 -226.291902)
		(mid 325.086635 -226.320885)
		(end 325.21017 -226.403408)
		(width 0.09525)
		(layer "In2.Cu")
		(net "M_C_CPU0_SA_DQS_DN<1>")
	)
	(arc
		(start 329.922632 -232.008934)
		(mid 330.1111 -231.958257)
		(end 330.299568 -232.008934)
		(width 0.09525)
		(layer "In2.Cu")
		(net "M_C_CPU0_SA_DQS_DN<1>")
	)
	(arc
		(start 335.939638 -232.008934)
		(mid 336.22107 -232.084689)
		(end 336.502502 -232.008934)
		(width 0.09525)
		(layer "In2.Cu")
		(net "M_C_CPU0_SA_DQS_DN<1>")
	)
	(arc
		(start 330.862432 -232.008934)
		(mid 331.046207 -231.958162)
		(end 331.23124 -232.004108)
		(width 0.09525)
		(layer "In2.Cu")
		(net "M_C_CPU0_SA_DQS_DN<1>")
	)
	(arc
		(start 326.72909 -229.094284)
		(mid 326.793546 -229.355449)
		(end 326.971914 -229.556818)
		(width 0.09525)
		(layer "In2.Cu")
		(net "M_C_CPU0_SA_DQS_DN<1>")
	)
	(arc
		(start 338.38261 -232.008934)
		(mid 338.571078 -231.958257)
		(end 338.759546 -232.008934)
		(width 0.09525)
		(layer "In2.Cu")
		(net "M_C_CPU0_SA_DQS_DN<1>")
	)
	(arc
		(start 333.11973 -232.008934)
		(mid 333.401162 -232.084689)
		(end 333.682594 -232.008934)
		(width 0.09525)
		(layer "In2.Cu")
		(net "M_C_CPU0_SA_DQS_DN<1>")
	)
	(arc
		(start 329.359768 -232.008934)
		(mid 329.6412 -232.084689)
		(end 329.922632 -232.008934)
		(width 0.09525)
		(layer "In2.Cu")
		(net "M_C_CPU0_SA_DQS_DN<1>")
	)
	(arc
		(start 328.13879 -231.524048)
		(mid 328.203187 -231.785354)
		(end 328.381614 -231.986836)
		(width 0.09525)
		(layer "In2.Cu")
		(net "M_C_CPU0_SA_DQS_DN<1>")
	)
	(arc
		(start 334.622648 -232.008934)
		(mid 334.811116 -231.958257)
		(end 334.999584 -232.008934)
		(width 0.09525)
		(layer "In2.Cu")
		(net "M_C_CPU0_SA_DQS_DN<1>")
	)
	(arc
		(start 327.512426 -230.407718)
		(mid 327.6277 -230.541996)
		(end 327.669144 -230.714042)
		(width 0.09525)
		(layer "In2.Cu")
		(net "M_C_CPU0_SA_DQS_DN<1>")
	)
	(arc
		(start 336.502502 -232.008934)
		(mid 336.686277 -231.958162)
		(end 336.87131 -232.004108)
		(width 0.09525)
		(layer "In2.Cu")
		(net "M_C_CPU0_SA_DQS_DN<1>")
	)
	(arc
		(start 326.10552 -227.979732)
		(mid 326.218785 -228.113516)
		(end 326.259444 -228.284024)
		(width 0.09525)
		(layer "In2.Cu")
		(net "M_C_CPU0_SA_DQS_DN<1>")
	)
	(arc
		(start 327.04024 -229.596442)
		(mid 327.156941 -229.730971)
		(end 327.19899 -229.904036)
		(width 0.09525)
		(layer "In2.Cu")
		(net "M_C_CPU0_SA_DQS_DN<1>")
	)
	(arc
		(start 325.631302 -227.16744)
		(mid 325.7471 -227.301834)
		(end 325.788782 -227.474272)
		(width 0.09525)
		(layer "In2.Cu")
		(net "M_C_CPU0_SA_DQS_DN<1>")
	)
	(arc
		(start 341.2109 -232.004108)
		(mid 341.395932 -231.958194)
		(end 341.579708 -232.008934)
		(width 0.09525)
		(layer "In2.Cu")
		(net "M_C_CPU0_SA_DQS_DN<1>")
	)
	(arc
		(start 338.759546 -232.008934)
		(mid 339.040978 -232.084689)
		(end 339.32241 -232.008934)
		(width 0.09525)
		(layer "In2.Cu")
		(net "M_C_CPU0_SA_DQS_DN<1>")
	)
	(arc
		(start 327.98131 -231.217216)
		(mid 328.097108 -231.35161)
		(end 328.13879 -231.524048)
		(width 0.09525)
		(layer "In2.Cu")
		(net "M_C_CPU0_SA_DQS_DN<1>")
	)
	(arc
		(start 334.059784 -232.008934)
		(mid 334.341216 -232.084689)
		(end 334.622648 -232.008934)
		(width 0.09525)
		(layer "In2.Cu")
		(net "M_C_CPU0_SA_DQS_DN<1>")
	)
	(arc
		(start 331.239622 -232.008934)
		(mid 331.521054 -232.084689)
		(end 331.802486 -232.008934)
		(width 0.09525)
		(layer "In2.Cu")
		(net "M_C_CPU0_SA_DQS_DN<1>")
	)
	(arc
		(start 327.19899 -229.904036)
		(mid 327.263819 -230.166038)
		(end 327.443338 -230.367586)
		(width 0.09525)
		(layer "In2.Cu")
		(net "M_C_CPU0_SA_DQS_DN<1>")
	)
	(arc
		(start 326.57161 -228.787198)
		(mid 326.687408 -228.921734)
		(end 326.72909 -229.094284)
		(width 0.09525)
		(layer "In2.Cu")
		(net "M_C_CPU0_SA_DQS_DN<1>")
	)
	(arc
		(start 327.669144 -230.714042)
		(mid 327.73355 -230.975557)
		(end 327.912222 -231.177084)
		(width 0.09525)
		(layer "In2.Cu")
		(net "M_C_CPU0_SA_DQS_DN<1>")
	)
	(arc
		(start 342.055958 -232.049828)
		(mid 342.066157 -232.045991)
		(end 342.076278 -232.041954)
		(width 0.09525)
		(layer "In2.Cu")
		(net "M_C_CPU0_SA_DQS_DN<1>")
	)
	(arc
		(start 332.750922 -232.004108)
		(mid 332.935954 -231.958194)
		(end 333.11973 -232.008934)
		(width 0.09525)
		(layer "In2.Cu")
		(net "M_C_CPU0_SA_DQS_DN<1>")
	)
	(arc
		(start 336.879692 -232.008934)
		(mid 337.161124 -232.084689)
		(end 337.442556 -232.008934)
		(width 0.09525)
		(layer "In2.Cu")
		(net "M_C_CPU0_SA_DQS_DN<1>")
	)
	(arc
		(start 339.32241 -232.008934)
		(mid 339.506185 -231.958162)
		(end 339.691218 -232.004108)
		(width 0.09525)
		(layer "In2.Cu")
		(net "M_C_CPU0_SA_DQS_DN<1>")
	)
	(arc
		(start 335.562448 -232.008934)
		(mid 335.746223 -231.958162)
		(end 335.931256 -232.004108)
		(width 0.09525)
		(layer "In2.Cu")
		(net "M_C_CPU0_SA_DQS_DN<1>")
	)
	(arc
		(start 340.262464 -232.008934)
		(mid 340.446239 -231.958162)
		(end 340.631272 -232.004108)
		(width 0.09525)
		(layer "In2.Cu")
		(net "M_C_CPU0_SA_DQS_DN<1>")
	)
	(arc
		(start 332.179676 -232.008934)
		(mid 332.461108 -232.084689)
		(end 332.74254 -232.008934)
		(width 0.09525)
		(layer "In2.Cu")
		(net "M_C_CPU0_SA_DQS_DN<1>")
	)
	(arc
		(start 337.819746 -232.008934)
		(mid 338.101178 -232.084689)
		(end 338.38261 -232.008934)
		(width 0.09525)
		(layer "In2.Cu")
		(net "M_C_CPU0_SA_DQS_DN<1>")
	)
	(arc
		(start 340.639654 -232.008934)
		(mid 340.921086 -232.084689)
		(end 341.202518 -232.008934)
		(width 0.09525)
		(layer "In2.Cu")
		(net "M_C_CPU0_SA_DQS_DN<1>")
	)
	(arc
		(start 334.999584 -232.008934)
		(mid 335.281016 -232.084689)
		(end 335.562448 -232.008934)
		(width 0.09525)
		(layer "In2.Cu")
		(net "M_C_CPU0_SA_DQS_DN<1>")
	)
	(arc
		(start 337.450938 -232.004108)
		(mid 337.63597 -231.958194)
		(end 337.819746 -232.008934)
		(width 0.09525)
		(layer "In2.Cu")
		(net "M_C_CPU0_SA_DQS_DN<1>")
	)
	(arc
		(start 333.690976 -232.004108)
		(mid 333.876008 -231.958194)
		(end 334.059784 -232.008934)
		(width 0.09525)
		(layer "In2.Cu")
		(net "M_C_CPU0_SA_DQS_DN<1>")
	)
	(arc
		(start 331.802486 -232.008934)
		(mid 331.986261 -231.958162)
		(end 332.171294 -232.004108)
		(width 0.09525)
		(layer "In2.Cu")
		(net "M_C_CPU0_SA_DQS_DN<1>")
	)
	(arc
		(start 339.6996 -232.008934)
		(mid 339.981032 -232.084689)
		(end 340.262464 -232.008934)
		(width 0.09525)
		(layer "In2.Cu")
		(net "M_C_CPU0_SA_DQS_DN<1>")
	)
	(arc
		(start 325.262494 -226.455732)
		(mid 325.304435 -226.51869)
		(end 325.319136 -226.592892)
		(width 0.09525)
		(layer "In2.Cu")
		(net "M_C_CPU0_SA_DQS_DN<1>")
	)
	(segment
		(start 342.797892 -227.74021)
		(end 342.33104 -227.474272)
		(width 0.12954)
		(layer "F.Cu")
		(net "M_C_CPU0_SA_DQS_DN<0>")
	)
	(segment
		(start 342.177116 -227.208842)
		(end 342.076278 -227.182172)
		(width 0.09525)
		(layer "In2.Cu")
		(net "M_C_CPU0_SA_DQS_DN<0>")
	)
	(segment
		(start 300.947074 -200.312274)
		(end 299.080682 -200.312274)
		(width 0.16002)
		(layer "In2.Cu")
		(net "M_C_CPU0_SA_DQS_DN<0>")
	)
	(segment
		(start 304.928778 -201.494898)
		(end 304.339498 -201.494898)
		(width 0.16002)
		(layer "In2.Cu")
		(net "M_C_CPU0_SA_DQS_DN<0>")
	)
	(segment
		(start 340.639654 -227.149152)
		(end 340.631272 -227.144326)
		(width 0.09525)
		(layer "In2.Cu")
		(net "M_C_CPU0_SA_DQS_DN<0>")
	)
	(segment
		(start 304.339498 -201.494898)
		(end 303.730914 -200.886314)
		(width 0.16002)
		(layer "In2.Cu")
		(net "M_C_CPU0_SA_DQS_DN<0>")
	)
	(segment
		(start 296.217594 -200.886314)
		(end 293.992046 -200.886314)
		(width 0.16002)
		(layer "In2.Cu")
		(net "M_C_CPU0_SA_DQS_DN<0>")
	)
	(segment
		(start 310.170322 -200.960736)
		(end 310.170322 -200.683876)
		(width 0.16002)
		(layer "In2.Cu")
		(net "M_C_CPU0_SA_DQS_DN<0>")
	)
	(segment
		(start 309.503064 -201.627994)
		(end 310.170322 -200.960736)
		(width 0.16002)
		(layer "In2.Cu")
		(net "M_C_CPU0_SA_DQS_DN<0>")
	)
	(segment
		(start 310.170322 -200.683876)
		(end 309.833264 -200.346818)
		(width 0.16002)
		(layer "In2.Cu")
		(net "M_C_CPU0_SA_DQS_DN<0>")
	)
	(segment
		(start 329.829668 -224.719134)
		(end 329.791568 -224.697036)
		(width 0.09525)
		(layer "In2.Cu")
		(net "M_C_CPU0_SA_DQS_DN<0>")
	)
	(segment
		(start 321.74942 -211.144104)
		(end 321.552824 -210.947508)
		(width 0.16002)
		(layer "In2.Cu")
		(net "M_C_CPU0_SA_DQS_DN<0>")
	)
	(segment
		(start 311.34812 -201.861674)
		(end 311.07126 -201.861674)
		(width 0.16002)
		(layer "In2.Cu")
		(net "M_C_CPU0_SA_DQS_DN<0>")
	)
	(segment
		(start 333.690976 -227.144326)
		(end 333.682594 -227.149152)
		(width 0.09525)
		(layer "In2.Cu")
		(net "M_C_CPU0_SA_DQS_DN<0>")
	)
	(segment
		(start 328.922126 -223.117918)
		(end 328.889614 -223.099122)
		(width 0.09525)
		(layer "In2.Cu")
		(net "M_C_CPU0_SA_DQS_DN<0>")
	)
	(segment
		(start 309.503064 -202.155298)
		(end 309.503064 -201.627994)
		(width 0.16002)
		(layer "In2.Cu")
		(net "M_C_CPU0_SA_DQS_DN<0>")
	)
	(segment
		(start 321.269614 -211.90077)
		(end 321.74942 -211.420964)
		(width 0.16002)
		(layer "In2.Cu")
		(net "M_C_CPU0_SA_DQS_DN<0>")
	)
	(segment
		(start 309.142638 -200.346818)
		(end 309.015638 -200.473818)
		(width 0.16002)
		(layer "In2.Cu")
		(net "M_C_CPU0_SA_DQS_DN<0>")
	)
	(segment
		(start 322.16979 -212.8012)
		(end 321.642486 -212.8012)
		(width 0.16002)
		(layer "In2.Cu")
		(net "M_C_CPU0_SA_DQS_DN<0>")
	)
	(segment
		(start 320.61658 -211.130134)
		(end 311.34812 -201.861674)
		(width 0.16002)
		(layer "In2.Cu")
		(net "M_C_CPU0_SA_DQS_DN<0>")
	)
	(segment
		(start 323.123052 -212.794596)
		(end 323.123052 -212.51799)
		(width 0.16002)
		(layer "In2.Cu")
		(net "M_C_CPU0_SA_DQS_DN<0>")
	)
	(segment
		(start 322.643246 -213.80196)
		(end 322.643246 -213.274402)
		(width 0.16002)
		(layer "In2.Cu")
		(net "M_C_CPU0_SA_DQS_DN<0>")
	)
	(segment
		(start 339.6996 -227.149152)
		(end 339.691218 -227.144326)
		(width 0.09525)
		(layer "In2.Cu")
		(net "M_C_CPU0_SA_DQS_DN<0>")
	)
	(segment
		(start 309.833264 -200.346818)
		(end 309.142638 -200.346818)
		(width 0.16002)
		(layer "In2.Cu")
		(net "M_C_CPU0_SA_DQS_DN<0>")
	)
	(segment
		(start 329.86218 -224.73793)
		(end 329.829668 -224.719134)
		(width 0.09525)
		(layer "In2.Cu")
		(net "M_C_CPU0_SA_DQS_DN<0>")
	)
	(segment
		(start 336.879692 -227.149152)
		(end 336.87131 -227.144326)
		(width 0.09525)
		(layer "In2.Cu")
		(net "M_C_CPU0_SA_DQS_DN<0>")
	)
	(segment
		(start 305.726338 -200.697338)
		(end 304.928778 -201.494898)
		(width 0.16002)
		(layer "In2.Cu")
		(net "M_C_CPU0_SA_DQS_DN<0>")
	)
	(segment
		(start 306.554378 -200.346818)
		(end 306.203858 -200.697338)
		(width 0.16002)
		(layer "In2.Cu")
		(net "M_C_CPU0_SA_DQS_DN<0>")
	)
	(segment
		(start 328.449686 -222.30588)
		(end 328.421238 -222.289624)
		(width 0.09525)
		(layer "In2.Cu")
		(net "M_C_CPU0_SA_DQS_DN<0>")
	)
	(segment
		(start 293.992046 -200.886314)
		(end 293.567104 -201.311256)
		(width 0.16002)
		(layer "In2.Cu")
		(net "M_C_CPU0_SA_DQS_DN<0>")
	)
	(segment
		(start 330.33208 -225.547936)
		(end 330.299568 -225.52914)
		(width 0.09525)
		(layer "In2.Cu")
		(net "M_C_CPU0_SA_DQS_DN<0>")
	)
	(segment
		(start 329.359768 -223.909128)
		(end 329.321668 -223.88703)
		(width 0.09525)
		(layer "In2.Cu")
		(net "M_C_CPU0_SA_DQS_DN<0>")
	)
	(segment
		(start 296.808398 -201.477118)
		(end 296.217594 -200.886314)
		(width 0.16002)
		(layer "In2.Cu")
		(net "M_C_CPU0_SA_DQS_DN<0>")
	)
	(segment
		(start 328.889614 -223.099122)
		(end 328.85761 -223.08058)
		(width 0.09525)
		(layer "In2.Cu")
		(net "M_C_CPU0_SA_DQS_DN<0>")
	)
	(segment
		(start 328.079862 -221.17431)
		(end 328.079862 -219.238576)
		(width 0.16002)
		(layer "In2.Cu")
		(net "M_C_CPU0_SA_DQS_DN<0>")
	)
	(segment
		(start 330.801218 -226.357434)
		(end 330.769722 -226.339146)
		(width 0.09525)
		(layer "In2.Cu")
		(net "M_C_CPU0_SA_DQS_DN<0>")
	)
	(segment
		(start 308.558438 -200.473818)
		(end 308.431438 -200.346818)
		(width 0.16002)
		(layer "In2.Cu")
		(net "M_C_CPU0_SA_DQS_DN<0>")
	)
	(segment
		(start 309.876698 -202.528932)
		(end 309.503064 -202.155298)
		(width 0.16002)
		(layer "In2.Cu")
		(net "M_C_CPU0_SA_DQS_DN<0>")
	)
	(segment
		(start 298.362878 -200.623678)
		(end 297.509438 -201.477118)
		(width 0.16002)
		(layer "In2.Cu")
		(net "M_C_CPU0_SA_DQS_DN<0>")
	)
	(segment
		(start 332.179676 -227.149152)
		(end 332.171294 -227.144326)
		(width 0.09525)
		(layer "In2.Cu")
		(net "M_C_CPU0_SA_DQS_DN<0>")
	)
	(segment
		(start 297.509438 -201.477118)
		(end 296.808398 -201.477118)
		(width 0.16002)
		(layer "In2.Cu")
		(net "M_C_CPU0_SA_DQS_DN<0>")
	)
	(segment
		(start 311.07126 -201.861674)
		(end 310.404002 -202.528932)
		(width 0.16002)
		(layer "In2.Cu")
		(net "M_C_CPU0_SA_DQS_DN<0>")
	)
	(segment
		(start 303.730914 -200.886314)
		(end 301.521114 -200.886314)
		(width 0.16002)
		(layer "In2.Cu")
		(net "M_C_CPU0_SA_DQS_DN<0>")
	)
	(segment
		(start 328.13879 -221.80423)
		(end 328.13879 -221.25686)
		(width 0.09525)
		(layer "In2.Cu")
		(net "M_C_CPU0_SA_DQS_DN<0>")
	)
	(segment
		(start 328.420476 -222.289116)
		(end 328.395584 -222.272606)
		(width 0.09525)
		(layer "In2.Cu")
		(net "M_C_CPU0_SA_DQS_DN<0>")
	)
	(segment
		(start 306.203858 -200.697338)
		(end 305.726338 -200.697338)
		(width 0.16002)
		(layer "In2.Cu")
		(net "M_C_CPU0_SA_DQS_DN<0>")
	)
	(segment
		(start 328.395584 -222.272606)
		(end 328.287888 -222.164402)
		(width 0.09525)
		(layer "In2.Cu")
		(net "M_C_CPU0_SA_DQS_DN<0>")
	)
	(segment
		(start 321.093592 -211.130134)
		(end 320.61658 -211.130134)
		(width 0.16002)
		(layer "In2.Cu")
		(net "M_C_CPU0_SA_DQS_DN<0>")
	)
	(segment
		(start 321.74942 -211.420964)
		(end 321.74942 -211.144104)
		(width 0.16002)
		(layer "In2.Cu")
		(net "M_C_CPU0_SA_DQS_DN<0>")
	)
	(segment
		(start 323.123052 -212.51799)
		(end 322.926202 -212.32114)
		(width 0.16002)
		(layer "In2.Cu")
		(net "M_C_CPU0_SA_DQS_DN<0>")
	)
	(segment
		(start 321.276218 -210.947508)
		(end 321.093592 -211.130134)
		(width 0.16002)
		(layer "In2.Cu")
		(net "M_C_CPU0_SA_DQS_DN<0>")
	)
	(segment
		(start 321.552824 -210.947508)
		(end 321.276218 -210.947508)
		(width 0.16002)
		(layer "In2.Cu")
		(net "M_C_CPU0_SA_DQS_DN<0>")
	)
	(segment
		(start 328.421238 -222.289624)
		(end 328.420476 -222.289116)
		(width 0.09525)
		(layer "In2.Cu")
		(net "M_C_CPU0_SA_DQS_DN<0>")
	)
	(segment
		(start 342.33104 -227.474272)
		(end 342.177116 -227.208842)
		(width 0.09525)
		(layer "In2.Cu")
		(net "M_C_CPU0_SA_DQS_DN<0>")
	)
	(segment
		(start 331.239622 -227.149152)
		(end 331.201522 -227.127054)
		(width 0.09525)
		(layer "In2.Cu")
		(net "M_C_CPU0_SA_DQS_DN<0>")
	)
	(segment
		(start 328.079862 -221.197932)
		(end 328.079862 -221.17431)
		(width 0.09525)
		(layer "In2.Cu")
		(net "M_C_CPU0_SA_DQS_DN<0>")
	)
	(segment
		(start 293.567104 -201.311256)
		(end 292.553898 -201.311256)
		(width 0.16002)
		(layer "In2.Cu")
		(net "M_C_CPU0_SA_DQS_DN<0>")
	)
	(segment
		(start 322.643246 -213.274402)
		(end 323.123052 -212.794596)
		(width 0.16002)
		(layer "In2.Cu")
		(net "M_C_CPU0_SA_DQS_DN<0>")
	)
	(segment
		(start 321.269614 -212.428328)
		(end 321.269614 -211.90077)
		(width 0.16002)
		(layer "In2.Cu")
		(net "M_C_CPU0_SA_DQS_DN<0>")
	)
	(segment
		(start 329.391264 -223.927416)
		(end 329.359768 -223.909128)
		(width 0.09525)
		(layer "In2.Cu")
		(net "M_C_CPU0_SA_DQS_DN<0>")
	)
	(segment
		(start 328.079862 -219.238576)
		(end 322.643246 -213.80196)
		(width 0.16002)
		(layer "In2.Cu")
		(net "M_C_CPU0_SA_DQS_DN<0>")
	)
	(segment
		(start 332.750922 -227.144326)
		(end 332.74254 -227.149152)
		(width 0.09525)
		(layer "In2.Cu")
		(net "M_C_CPU0_SA_DQS_DN<0>")
	)
	(segment
		(start 308.431438 -200.346818)
		(end 306.554378 -200.346818)
		(width 0.16002)
		(layer "In2.Cu")
		(net "M_C_CPU0_SA_DQS_DN<0>")
	)
	(segment
		(start 298.769278 -200.623678)
		(end 298.362878 -200.623678)
		(width 0.16002)
		(layer "In2.Cu")
		(net "M_C_CPU0_SA_DQS_DN<0>")
	)
	(segment
		(start 330.769722 -226.339146)
		(end 330.731622 -226.317048)
		(width 0.09525)
		(layer "In2.Cu")
		(net "M_C_CPU0_SA_DQS_DN<0>")
	)
	(segment
		(start 322.926202 -212.32114)
		(end 322.64985 -212.32114)
		(width 0.16002)
		(layer "In2.Cu")
		(net "M_C_CPU0_SA_DQS_DN<0>")
	)
	(segment
		(start 301.521114 -200.886314)
		(end 300.947074 -200.312274)
		(width 0.16002)
		(layer "In2.Cu")
		(net "M_C_CPU0_SA_DQS_DN<0>")
	)
	(segment
		(start 337.450938 -227.144326)
		(end 337.442556 -227.149152)
		(width 0.09525)
		(layer "In2.Cu")
		(net "M_C_CPU0_SA_DQS_DN<0>")
	)
	(segment
		(start 335.939638 -227.149152)
		(end 335.931256 -227.144326)
		(width 0.09525)
		(layer "In2.Cu")
		(net "M_C_CPU0_SA_DQS_DN<0>")
	)
	(segment
		(start 309.015638 -200.473818)
		(end 308.558438 -200.473818)
		(width 0.16002)
		(layer "In2.Cu")
		(net "M_C_CPU0_SA_DQS_DN<0>")
	)
	(segment
		(start 292.553898 -201.311256)
		(end 292.280086 -201.585068)
		(width 0.16002)
		(layer "In2.Cu")
		(net "M_C_CPU0_SA_DQS_DN<0>")
	)
	(segment
		(start 321.642486 -212.8012)
		(end 321.269614 -212.428328)
		(width 0.16002)
		(layer "In2.Cu")
		(net "M_C_CPU0_SA_DQS_DN<0>")
	)
	(segment
		(start 328.13879 -221.25686)
		(end 328.079862 -221.197932)
		(width 0.09525)
		(layer "In2.Cu")
		(net "M_C_CPU0_SA_DQS_DN<0>")
	)
	(segment
		(start 299.080682 -200.312274)
		(end 298.769278 -200.623678)
		(width 0.16002)
		(layer "In2.Cu")
		(net "M_C_CPU0_SA_DQS_DN<0>")
	)
	(segment
		(start 310.404002 -202.528932)
		(end 309.876698 -202.528932)
		(width 0.16002)
		(layer "In2.Cu")
		(net "M_C_CPU0_SA_DQS_DN<0>")
	)
	(segment
		(start 330.299568 -225.52914)
		(end 330.264516 -225.508566)
		(width 0.09525)
		(layer "In2.Cu")
		(net "M_C_CPU0_SA_DQS_DN<0>")
	)
	(segment
		(start 341.2109 -227.144326)
		(end 341.202518 -227.149152)
		(width 0.09525)
		(layer "In2.Cu")
		(net "M_C_CPU0_SA_DQS_DN<0>")
	)
	(segment
		(start 322.64985 -212.32114)
		(end 322.16979 -212.8012)
		(width 0.16002)
		(layer "In2.Cu")
		(net "M_C_CPU0_SA_DQS_DN<0>")
	)
	(arc
		(start 332.74254 -227.149152)
		(mid 332.461108 -227.224907)
		(end 332.179676 -227.149152)
		(width 0.09525)
		(layer "In2.Cu")
		(net "M_C_CPU0_SA_DQS_DN<0>")
	)
	(arc
		(start 329.548744 -224.234248)
		(mid 329.507079 -224.061801)
		(end 329.391264 -223.927416)
		(width 0.09525)
		(layer "In2.Cu")
		(net "M_C_CPU0_SA_DQS_DN<0>")
	)
	(arc
		(start 328.85761 -223.08058)
		(mid 328.675145 -222.878435)
		(end 328.609198 -222.614236)
		(width 0.09525)
		(layer "In2.Cu")
		(net "M_C_CPU0_SA_DQS_DN<0>")
	)
	(arc
		(start 333.682594 -227.149152)
		(mid 333.401162 -227.224907)
		(end 333.11973 -227.149152)
		(width 0.09525)
		(layer "In2.Cu")
		(net "M_C_CPU0_SA_DQS_DN<0>")
	)
	(arc
		(start 333.11973 -227.149152)
		(mid 332.935955 -227.09838)
		(end 332.750922 -227.144326)
		(width 0.09525)
		(layer "In2.Cu")
		(net "M_C_CPU0_SA_DQS_DN<0>")
	)
	(arc
		(start 338.759546 -227.149152)
		(mid 338.571078 -227.098475)
		(end 338.38261 -227.149152)
		(width 0.09525)
		(layer "In2.Cu")
		(net "M_C_CPU0_SA_DQS_DN<0>")
	)
	(arc
		(start 340.262464 -227.149152)
		(mid 339.981032 -227.224907)
		(end 339.6996 -227.149152)
		(width 0.09525)
		(layer "In2.Cu")
		(net "M_C_CPU0_SA_DQS_DN<0>")
	)
	(arc
		(start 332.171294 -227.144326)
		(mid 331.986262 -227.098412)
		(end 331.802486 -227.149152)
		(width 0.09525)
		(layer "In2.Cu")
		(net "M_C_CPU0_SA_DQS_DN<0>")
	)
	(arc
		(start 340.631272 -227.144326)
		(mid 340.44624 -227.098412)
		(end 340.262464 -227.149152)
		(width 0.09525)
		(layer "In2.Cu")
		(net "M_C_CPU0_SA_DQS_DN<0>")
	)
	(arc
		(start 329.321668 -223.88703)
		(mid 329.143218 -223.68556)
		(end 329.078844 -223.424242)
		(width 0.09525)
		(layer "In2.Cu")
		(net "M_C_CPU0_SA_DQS_DN<0>")
	)
	(arc
		(start 330.488798 -225.85426)
		(mid 330.447341 -225.68222)
		(end 330.33208 -225.547936)
		(width 0.09525)
		(layer "In2.Cu")
		(net "M_C_CPU0_SA_DQS_DN<0>")
	)
	(arc
		(start 331.201522 -227.127054)
		(mid 331.023072 -226.925584)
		(end 330.958698 -226.664266)
		(width 0.09525)
		(layer "In2.Cu")
		(net "M_C_CPU0_SA_DQS_DN<0>")
	)
	(arc
		(start 330.731622 -226.317048)
		(mid 330.553172 -226.115578)
		(end 330.488798 -225.85426)
		(width 0.09525)
		(layer "In2.Cu")
		(net "M_C_CPU0_SA_DQS_DN<0>")
	)
	(arc
		(start 335.562448 -227.149152)
		(mid 335.281016 -227.224907)
		(end 334.999584 -227.149152)
		(width 0.09525)
		(layer "In2.Cu")
		(net "M_C_CPU0_SA_DQS_DN<0>")
	)
	(arc
		(start 328.287888 -222.164402)
		(mid 328.177682 -221.999084)
		(end 328.13879 -221.80423)
		(width 0.09525)
		(layer "In2.Cu")
		(net "M_C_CPU0_SA_DQS_DN<0>")
	)
	(arc
		(start 329.078844 -223.424242)
		(mid 329.037387 -223.252202)
		(end 328.922126 -223.117918)
		(width 0.09525)
		(layer "In2.Cu")
		(net "M_C_CPU0_SA_DQS_DN<0>")
	)
	(arc
		(start 330.264516 -225.508566)
		(mid 330.084061 -225.3069)
		(end 330.018898 -225.044254)
		(width 0.09525)
		(layer "In2.Cu")
		(net "M_C_CPU0_SA_DQS_DN<0>")
	)
	(arc
		(start 336.502502 -227.149152)
		(mid 336.22107 -227.224907)
		(end 335.939638 -227.149152)
		(width 0.09525)
		(layer "In2.Cu")
		(net "M_C_CPU0_SA_DQS_DN<0>")
	)
	(arc
		(start 341.579708 -227.149152)
		(mid 341.395933 -227.09838)
		(end 341.2109 -227.144326)
		(width 0.09525)
		(layer "In2.Cu")
		(net "M_C_CPU0_SA_DQS_DN<0>")
	)
	(arc
		(start 334.059784 -227.149152)
		(mid 333.876009 -227.09838)
		(end 333.690976 -227.144326)
		(width 0.09525)
		(layer "In2.Cu")
		(net "M_C_CPU0_SA_DQS_DN<0>")
	)
	(arc
		(start 341.202518 -227.149152)
		(mid 340.921086 -227.224907)
		(end 340.639654 -227.149152)
		(width 0.09525)
		(layer "In2.Cu")
		(net "M_C_CPU0_SA_DQS_DN<0>")
	)
	(arc
		(start 338.38261 -227.149152)
		(mid 338.101178 -227.224907)
		(end 337.819746 -227.149152)
		(width 0.09525)
		(layer "In2.Cu")
		(net "M_C_CPU0_SA_DQS_DN<0>")
	)
	(arc
		(start 339.32241 -227.149152)
		(mid 339.040978 -227.224907)
		(end 338.759546 -227.149152)
		(width 0.09525)
		(layer "In2.Cu")
		(net "M_C_CPU0_SA_DQS_DN<0>")
	)
	(arc
		(start 342.076278 -227.182172)
		(mid 341.824137 -227.223742)
		(end 341.579708 -227.149152)
		(width 0.09525)
		(layer "In2.Cu")
		(net "M_C_CPU0_SA_DQS_DN<0>")
	)
	(arc
		(start 328.609198 -222.614236)
		(mid 328.566951 -222.440661)
		(end 328.449686 -222.30588)
		(width 0.09525)
		(layer "In2.Cu")
		(net "M_C_CPU0_SA_DQS_DN<0>")
	)
	(arc
		(start 330.018898 -225.044254)
		(mid 329.977441 -224.872214)
		(end 329.86218 -224.73793)
		(width 0.09525)
		(layer "In2.Cu")
		(net "M_C_CPU0_SA_DQS_DN<0>")
	)
	(arc
		(start 335.931256 -227.144326)
		(mid 335.746224 -227.098412)
		(end 335.562448 -227.149152)
		(width 0.09525)
		(layer "In2.Cu")
		(net "M_C_CPU0_SA_DQS_DN<0>")
	)
	(arc
		(start 339.691218 -227.144326)
		(mid 339.506186 -227.098412)
		(end 339.32241 -227.149152)
		(width 0.09525)
		(layer "In2.Cu")
		(net "M_C_CPU0_SA_DQS_DN<0>")
	)
	(arc
		(start 330.958698 -226.664266)
		(mid 330.917033 -226.491819)
		(end 330.801218 -226.357434)
		(width 0.09525)
		(layer "In2.Cu")
		(net "M_C_CPU0_SA_DQS_DN<0>")
	)
	(arc
		(start 337.442556 -227.149152)
		(mid 337.161124 -227.224907)
		(end 336.879692 -227.149152)
		(width 0.09525)
		(layer "In2.Cu")
		(net "M_C_CPU0_SA_DQS_DN<0>")
	)
	(arc
		(start 334.622648 -227.149152)
		(mid 334.341216 -227.224907)
		(end 334.059784 -227.149152)
		(width 0.09525)
		(layer "In2.Cu")
		(net "M_C_CPU0_SA_DQS_DN<0>")
	)
	(arc
		(start 331.802486 -227.149152)
		(mid 331.521054 -227.224907)
		(end 331.239622 -227.149152)
		(width 0.09525)
		(layer "In2.Cu")
		(net "M_C_CPU0_SA_DQS_DN<0>")
	)
	(arc
		(start 334.999584 -227.149152)
		(mid 334.811116 -227.098475)
		(end 334.622648 -227.149152)
		(width 0.09525)
		(layer "In2.Cu")
		(net "M_C_CPU0_SA_DQS_DN<0>")
	)
	(arc
		(start 329.791568 -224.697036)
		(mid 329.613118 -224.495566)
		(end 329.548744 -224.234248)
		(width 0.09525)
		(layer "In2.Cu")
		(net "M_C_CPU0_SA_DQS_DN<0>")
	)
	(arc
		(start 337.819746 -227.149152)
		(mid 337.635971 -227.09838)
		(end 337.450938 -227.144326)
		(width 0.09525)
		(layer "In2.Cu")
		(net "M_C_CPU0_SA_DQS_DN<0>")
	)
	(arc
		(start 336.87131 -227.144326)
		(mid 336.686278 -227.098412)
		(end 336.502502 -227.149152)
		(width 0.09525)
		(layer "In2.Cu")
		(net "M_C_CPU0_SA_DQS_DN<0>")
	)
	(segment
		(start 343.737946 -230.97998)
		(end 343.271094 -230.714296)
		(width 0.10668)
		(layer "F.Cu")
		(net "M_C_CPU0_SA_DQ<9>")
	)
	(segment
		(start 327.574148 -228.607112)
		(end 327.54697 -228.591364)
		(width 0.0889)
		(layer "In2.Cu")
		(net "M_C_CPU0_SA_DQ<9>")
	)
	(segment
		(start 310.095138 -207.960214)
		(end 309.55869 -207.960214)
		(width 0.14478)
		(layer "In2.Cu")
		(net "M_C_CPU0_SA_DQ<9>")
	)
	(segment
		(start 308.294278 -207.79867)
		(end 308.132734 -207.960214)
		(width 0.14478)
		(layer "In2.Cu")
		(net "M_C_CPU0_SA_DQ<9>")
	)
	(segment
		(start 333.6925 -231.041448)
		(end 333.684118 -231.036622)
		(width 0.0889)
		(layer "In2.Cu")
		(net "M_C_CPU0_SA_DQ<9>")
	)
	(segment
		(start 325.225918 -224.558098)
		(end 325.22414 -224.556828)
		(width 0.0889)
		(layer "In2.Cu")
		(net "M_C_CPU0_SA_DQ<9>")
	)
	(segment
		(start 328.514202 -230.226616)
		(end 328.482452 -230.208328)
		(width 0.0889)
		(layer "In2.Cu")
		(net "M_C_CPU0_SA_DQ<9>")
	)
	(segment
		(start 301.042832 -207.960214)
		(end 299.480986 -207.960214)
		(width 0.14478)
		(layer "In2.Cu")
		(net "M_C_CPU0_SA_DQ<9>")
	)
	(segment
		(start 309.007256 -208.326736)
		(end 308.845712 -208.165192)
		(width 0.14478)
		(layer "In2.Cu")
		(net "M_C_CPU0_SA_DQ<9>")
	)
	(segment
		(start 293.544244 -208.64703)
		(end 293.381176 -208.810098)
		(width 0.14478)
		(layer "In2.Cu")
		(net "M_C_CPU0_SA_DQ<9>")
	)
	(segment
		(start 301.892716 -208.810098)
		(end 301.042832 -207.960214)
		(width 0.14478)
		(layer "In2.Cu")
		(net "M_C_CPU0_SA_DQ<9>")
	)
	(segment
		(start 322.844414 -222.51289)
		(end 322.844414 -220.162374)
		(width 0.14478)
		(layer "In2.Cu")
		(net "M_C_CPU0_SA_DQ<9>")
	)
	(segment
		(start 296.344086 -208.41843)
		(end 296.181018 -208.581498)
		(width 0.14478)
		(layer "In2.Cu")
		(net "M_C_CPU0_SA_DQ<9>")
	)
	(segment
		(start 328.54773 -230.246174)
		(end 328.514202 -230.226616)
		(width 0.0889)
		(layer "In2.Cu")
		(net "M_C_CPU0_SA_DQ<9>")
	)
	(segment
		(start 306.180744 -207.728058)
		(end 306.180744 -207.797146)
		(width 0.14478)
		(layer "In2.Cu")
		(net "M_C_CPU0_SA_DQ<9>")
	)
	(segment
		(start 306.180744 -207.797146)
		(end 306.017676 -207.960214)
		(width 0.14478)
		(layer "In2.Cu")
		(net "M_C_CPU0_SA_DQ<9>")
	)
	(segment
		(start 314.59297 -211.91093)
		(end 314.045854 -211.91093)
		(width 0.14478)
		(layer "In2.Cu")
		(net "M_C_CPU0_SA_DQ<9>")
	)
	(segment
		(start 294.100758 -208.594198)
		(end 293.93769 -208.43113)
		(width 0.14478)
		(layer "In2.Cu")
		(net "M_C_CPU0_SA_DQ<9>")
	)
	(segment
		(start 324.712076 -224.380552)
		(end 324.447154 -224.11563)
		(width 0.0889)
		(layer "In2.Cu")
		(net "M_C_CPU0_SA_DQ<9>")
	)
	(segment
		(start 295.376854 -208.810098)
		(end 295.213786 -208.64703)
		(width 0.14478)
		(layer "In2.Cu")
		(net "M_C_CPU0_SA_DQ<9>")
	)
	(segment
		(start 309.235602 -208.326736)
		(end 309.007256 -208.326736)
		(width 0.14478)
		(layer "In2.Cu")
		(net "M_C_CPU0_SA_DQ<9>")
	)
	(segment
		(start 306.343812 -207.56499)
		(end 306.180744 -207.728058)
		(width 0.14478)
		(layer "In2.Cu")
		(net "M_C_CPU0_SA_DQ<9>")
	)
	(segment
		(start 308.455822 -207.593692)
		(end 308.294278 -207.755236)
		(width 0.14478)
		(layer "In2.Cu")
		(net "M_C_CPU0_SA_DQ<9>")
	)
	(segment
		(start 327.140824 -227.818696)
		(end 327.104502 -227.797614)
		(width 0.0889)
		(layer "In2.Cu")
		(net "M_C_CPU0_SA_DQ<9>")
	)
	(segment
		(start 298.924472 -207.56499)
		(end 298.761404 -207.728058)
		(width 0.14478)
		(layer "In2.Cu")
		(net "M_C_CPU0_SA_DQ<9>")
	)
	(segment
		(start 337.452462 -231.041448)
		(end 337.44408 -231.036622)
		(width 0.0889)
		(layer "In2.Cu")
		(net "M_C_CPU0_SA_DQ<9>")
	)
	(segment
		(start 309.397146 -208.165192)
		(end 309.235602 -208.326736)
		(width 0.14478)
		(layer "In2.Cu")
		(net "M_C_CPU0_SA_DQ<9>")
	)
	(segment
		(start 293.93769 -208.43113)
		(end 293.707312 -208.43113)
		(width 0.14478)
		(layer "In2.Cu")
		(net "M_C_CPU0_SA_DQ<9>")
	)
	(segment
		(start 325.694802 -225.368358)
		(end 325.659242 -225.347784)
		(width 0.0889)
		(layer "In2.Cu")
		(net "M_C_CPU0_SA_DQ<9>")
	)
	(segment
		(start 314.045854 -211.91093)
		(end 310.095138 -207.960214)
		(width 0.14478)
		(layer "In2.Cu")
		(net "M_C_CPU0_SA_DQ<9>")
	)
	(segment
		(start 331.238098 -231.036622)
		(end 331.229716 -231.041448)
		(width 0.0889)
		(layer "In2.Cu")
		(net "M_C_CPU0_SA_DQ<9>")
	)
	(segment
		(start 299.317918 -207.728058)
		(end 299.15485 -207.56499)
		(width 0.14478)
		(layer "In2.Cu")
		(net "M_C_CPU0_SA_DQ<9>")
	)
	(segment
		(start 299.480986 -207.960214)
		(end 299.317918 -207.797146)
		(width 0.14478)
		(layer "In2.Cu")
		(net "M_C_CPU0_SA_DQ<9>")
	)
	(segment
		(start 298.761404 -207.797146)
		(end 298.598336 -207.960214)
		(width 0.14478)
		(layer "In2.Cu")
		(net "M_C_CPU0_SA_DQ<9>")
	)
	(segment
		(start 298.598336 -207.960214)
		(end 297.922696 -207.960214)
		(width 0.14478)
		(layer "In2.Cu")
		(net "M_C_CPU0_SA_DQ<9>")
	)
	(segment
		(start 324.945502 -224.380552)
		(end 324.712076 -224.380552)
		(width 0.0889)
		(layer "In2.Cu")
		(net "M_C_CPU0_SA_DQ<9>")
	)
	(segment
		(start 326.634348 -226.987354)
		(end 326.59828 -226.966526)
		(width 0.0889)
		(layer "In2.Cu")
		(net "M_C_CPU0_SA_DQ<9>")
	)
	(segment
		(start 332.178152 -231.036622)
		(end 332.16977 -231.041448)
		(width 0.0889)
		(layer "In2.Cu")
		(net "M_C_CPU0_SA_DQ<9>")
	)
	(segment
		(start 324.447154 -224.11563)
		(end 322.844414 -222.51289)
		(width 0.14478)
		(layer "In2.Cu")
		(net "M_C_CPU0_SA_DQ<9>")
	)
	(segment
		(start 308.684168 -207.593692)
		(end 308.455822 -207.593692)
		(width 0.14478)
		(layer "In2.Cu")
		(net "M_C_CPU0_SA_DQ<9>")
	)
	(segment
		(start 304.48758 -208.810098)
		(end 301.892716 -208.810098)
		(width 0.14478)
		(layer "In2.Cu")
		(net "M_C_CPU0_SA_DQ<9>")
	)
	(segment
		(start 296.737532 -208.64703)
		(end 296.737532 -208.581498)
		(width 0.14478)
		(layer "In2.Cu")
		(net "M_C_CPU0_SA_DQ<9>")
	)
	(segment
		(start 294.263826 -209.20075)
		(end 294.100758 -209.037682)
		(width 0.14478)
		(layer "In2.Cu")
		(net "M_C_CPU0_SA_DQ<9>")
	)
	(segment
		(start 308.845712 -208.165192)
		(end 308.845712 -207.755236)
		(width 0.14478)
		(layer "In2.Cu")
		(net "M_C_CPU0_SA_DQ<9>")
	)
	(segment
		(start 328.044048 -229.41661)
		(end 328.011536 -229.397814)
		(width 0.0889)
		(layer "In2.Cu")
		(net "M_C_CPU0_SA_DQ<9>")
	)
	(segment
		(start 297.922696 -207.960214)
		(end 297.072812 -208.810098)
		(width 0.14478)
		(layer "In2.Cu")
		(net "M_C_CPU0_SA_DQ<9>")
	)
	(segment
		(start 294.82034 -208.43113)
		(end 294.657272 -208.594198)
		(width 0.14478)
		(layer "In2.Cu")
		(net "M_C_CPU0_SA_DQ<9>")
	)
	(segment
		(start 305.337464 -207.960214)
		(end 304.48758 -208.810098)
		(width 0.14478)
		(layer "In2.Cu")
		(net "M_C_CPU0_SA_DQ<9>")
	)
	(segment
		(start 296.01795 -208.810098)
		(end 295.376854 -208.810098)
		(width 0.14478)
		(layer "In2.Cu")
		(net "M_C_CPU0_SA_DQ<9>")
	)
	(segment
		(start 328.992484 -231.041448)
		(end 328.984102 -231.036622)
		(width 0.0889)
		(layer "In2.Cu")
		(net "M_C_CPU0_SA_DQ<9>")
	)
	(segment
		(start 294.100758 -209.037682)
		(end 294.100758 -208.594198)
		(width 0.14478)
		(layer "In2.Cu")
		(net "M_C_CPU0_SA_DQ<9>")
	)
	(segment
		(start 343.271094 -230.714296)
		(end 343.425018 -230.979726)
		(width 0.0889)
		(layer "In2.Cu")
		(net "M_C_CPU0_SA_DQ<9>")
	)
	(segment
		(start 295.050718 -208.43113)
		(end 294.82034 -208.43113)
		(width 0.14478)
		(layer "In2.Cu")
		(net "M_C_CPU0_SA_DQ<9>")
	)
	(segment
		(start 340.63813 -231.036622)
		(end 340.629748 -231.041448)
		(width 0.0889)
		(layer "In2.Cu")
		(net "M_C_CPU0_SA_DQ<9>")
	)
	(segment
		(start 294.657272 -209.037682)
		(end 294.494204 -209.20075)
		(width 0.14478)
		(layer "In2.Cu")
		(net "M_C_CPU0_SA_DQ<9>")
	)
	(segment
		(start 293.707312 -208.43113)
		(end 293.544244 -208.594198)
		(width 0.14478)
		(layer "In2.Cu")
		(net "M_C_CPU0_SA_DQ<9>")
	)
	(segment
		(start 306.57419 -207.56499)
		(end 306.343812 -207.56499)
		(width 0.14478)
		(layer "In2.Cu")
		(net "M_C_CPU0_SA_DQ<9>")
	)
	(segment
		(start 295.213786 -208.64703)
		(end 295.213786 -208.594198)
		(width 0.14478)
		(layer "In2.Cu")
		(net "M_C_CPU0_SA_DQ<9>")
	)
	(segment
		(start 306.017676 -207.960214)
		(end 305.337464 -207.960214)
		(width 0.14478)
		(layer "In2.Cu")
		(net "M_C_CPU0_SA_DQ<9>")
	)
	(segment
		(start 293.381176 -208.810098)
		(end 292.705028 -208.810098)
		(width 0.14478)
		(layer "In2.Cu")
		(net "M_C_CPU0_SA_DQ<9>")
	)
	(segment
		(start 326.676766 -227.011992)
		(end 326.634348 -226.987354)
		(width 0.0889)
		(layer "In2.Cu")
		(net "M_C_CPU0_SA_DQ<9>")
	)
	(segment
		(start 343.425018 -230.979726)
		(end 343.40292 -231.062784)
		(width 0.0889)
		(layer "In2.Cu")
		(net "M_C_CPU0_SA_DQ<9>")
	)
	(segment
		(start 294.494204 -209.20075)
		(end 294.263826 -209.20075)
		(width 0.14478)
		(layer "In2.Cu")
		(net "M_C_CPU0_SA_DQ<9>")
	)
	(segment
		(start 294.657272 -208.594198)
		(end 294.657272 -209.037682)
		(width 0.14478)
		(layer "In2.Cu")
		(net "M_C_CPU0_SA_DQ<9>")
	)
	(segment
		(start 326.164194 -226.177348)
		(end 326.139302 -226.16287)
		(width 0.0889)
		(layer "In2.Cu")
		(net "M_C_CPU0_SA_DQ<9>")
	)
	(segment
		(start 326.195436 -226.195382)
		(end 326.164194 -226.177348)
		(width 0.0889)
		(layer "In2.Cu")
		(net "M_C_CPU0_SA_DQ<9>")
	)
	(segment
		(start 292.705028 -208.810098)
		(end 292.280086 -208.385156)
		(width 0.14478)
		(layer "In2.Cu")
		(net "M_C_CPU0_SA_DQ<9>")
	)
	(segment
		(start 335.938114 -231.036622)
		(end 335.929732 -231.041448)
		(width 0.0889)
		(layer "In2.Cu")
		(net "M_C_CPU0_SA_DQ<9>")
	)
	(segment
		(start 299.15485 -207.56499)
		(end 298.924472 -207.56499)
		(width 0.14478)
		(layer "In2.Cu")
		(net "M_C_CPU0_SA_DQ<9>")
	)
	(segment
		(start 322.844414 -220.162374)
		(end 314.59297 -211.91093)
		(width 0.14478)
		(layer "In2.Cu")
		(net "M_C_CPU0_SA_DQ<9>")
	)
	(segment
		(start 308.845712 -207.755236)
		(end 308.684168 -207.593692)
		(width 0.14478)
		(layer "In2.Cu")
		(net "M_C_CPU0_SA_DQ<9>")
	)
	(segment
		(start 297.072812 -208.810098)
		(end 296.9006 -208.810098)
		(width 0.14478)
		(layer "In2.Cu")
		(net "M_C_CPU0_SA_DQ<9>")
	)
	(segment
		(start 328.083164 -229.43947)
		(end 328.044048 -229.41661)
		(width 0.0889)
		(layer "In2.Cu")
		(net "M_C_CPU0_SA_DQ<9>")
	)
	(segment
		(start 306.737258 -207.797146)
		(end 306.737258 -207.728058)
		(width 0.14478)
		(layer "In2.Cu")
		(net "M_C_CPU0_SA_DQ<9>")
	)
	(segment
		(start 296.9006 -208.810098)
		(end 296.737532 -208.64703)
		(width 0.14478)
		(layer "In2.Cu")
		(net "M_C_CPU0_SA_DQ<9>")
	)
	(segment
		(start 339.698076 -231.036622)
		(end 339.689694 -231.041448)
		(width 0.0889)
		(layer "In2.Cu")
		(net "M_C_CPU0_SA_DQ<9>")
	)
	(segment
		(start 296.737532 -208.581498)
		(end 296.574464 -208.41843)
		(width 0.14478)
		(layer "In2.Cu")
		(net "M_C_CPU0_SA_DQ<9>")
	)
	(segment
		(start 328.984102 -231.036622)
		(end 328.950574 -231.017064)
		(width 0.0889)
		(layer "In2.Cu")
		(net "M_C_CPU0_SA_DQ<9>")
	)
	(segment
		(start 327.104502 -227.797614)
		(end 327.068942 -227.77704)
		(width 0.0889)
		(layer "In2.Cu")
		(net "M_C_CPU0_SA_DQ<9>")
	)
	(segment
		(start 296.574464 -208.41843)
		(end 296.344086 -208.41843)
		(width 0.14478)
		(layer "In2.Cu")
		(net "M_C_CPU0_SA_DQ<9>")
	)
	(segment
		(start 327.609454 -228.627686)
		(end 327.574148 -228.607112)
		(width 0.0889)
		(layer "In2.Cu")
		(net "M_C_CPU0_SA_DQ<9>")
	)
	(segment
		(start 336.878168 -231.036622)
		(end 336.869786 -231.041448)
		(width 0.0889)
		(layer "In2.Cu")
		(net "M_C_CPU0_SA_DQ<9>")
	)
	(segment
		(start 332.752446 -231.041448)
		(end 332.744064 -231.036622)
		(width 0.0889)
		(layer "In2.Cu")
		(net "M_C_CPU0_SA_DQ<9>")
	)
	(segment
		(start 308.132734 -207.960214)
		(end 306.900326 -207.960214)
		(width 0.14478)
		(layer "In2.Cu")
		(net "M_C_CPU0_SA_DQ<9>")
	)
	(segment
		(start 306.900326 -207.960214)
		(end 306.737258 -207.797146)
		(width 0.14478)
		(layer "In2.Cu")
		(net "M_C_CPU0_SA_DQ<9>")
	)
	(segment
		(start 309.55869 -207.960214)
		(end 309.397146 -208.121758)
		(width 0.14478)
		(layer "In2.Cu")
		(net "M_C_CPU0_SA_DQ<9>")
	)
	(segment
		(start 306.737258 -207.728058)
		(end 306.57419 -207.56499)
		(width 0.14478)
		(layer "In2.Cu")
		(net "M_C_CPU0_SA_DQ<9>")
	)
	(segment
		(start 325.728076 -225.387662)
		(end 325.694802 -225.368358)
		(width 0.0889)
		(layer "In2.Cu")
		(net "M_C_CPU0_SA_DQ<9>")
	)
	(segment
		(start 295.213786 -208.594198)
		(end 295.050718 -208.43113)
		(width 0.14478)
		(layer "In2.Cu")
		(net "M_C_CPU0_SA_DQ<9>")
	)
	(segment
		(start 299.317918 -207.797146)
		(end 299.317918 -207.728058)
		(width 0.14478)
		(layer "In2.Cu")
		(net "M_C_CPU0_SA_DQ<9>")
	)
	(segment
		(start 308.294278 -207.755236)
		(end 308.294278 -207.79867)
		(width 0.14478)
		(layer "In2.Cu")
		(net "M_C_CPU0_SA_DQ<9>")
	)
	(segment
		(start 296.181018 -208.64703)
		(end 296.01795 -208.810098)
		(width 0.14478)
		(layer "In2.Cu")
		(net "M_C_CPU0_SA_DQ<9>")
	)
	(segment
		(start 293.544244 -208.594198)
		(end 293.544244 -208.64703)
		(width 0.14478)
		(layer "In2.Cu")
		(net "M_C_CPU0_SA_DQ<9>")
	)
	(segment
		(start 342.152478 -231.041448)
		(end 342.144096 -231.036622)
		(width 0.0889)
		(layer "In2.Cu")
		(net "M_C_CPU0_SA_DQ<9>")
	)
	(segment
		(start 309.397146 -208.121758)
		(end 309.397146 -208.165192)
		(width 0.14478)
		(layer "In2.Cu")
		(net "M_C_CPU0_SA_DQ<9>")
	)
	(segment
		(start 341.212424 -231.041448)
		(end 341.204042 -231.036622)
		(width 0.0889)
		(layer "In2.Cu")
		(net "M_C_CPU0_SA_DQ<9>")
	)
	(segment
		(start 296.181018 -208.581498)
		(end 296.181018 -208.64703)
		(width 0.14478)
		(layer "In2.Cu")
		(net "M_C_CPU0_SA_DQ<9>")
	)
	(segment
		(start 298.761404 -207.728058)
		(end 298.761404 -207.797146)
		(width 0.14478)
		(layer "In2.Cu")
		(net "M_C_CPU0_SA_DQ<9>")
	)
	(arc
		(start 338.384134 -231.036622)
		(mid 338.101178 -230.960445)
		(end 337.818222 -231.036622)
		(width 0.0889)
		(layer "In2.Cu")
		(net "M_C_CPU0_SA_DQ<9>")
	)
	(arc
		(start 342.518238 -231.036622)
		(mid 342.335987 -231.087006)
		(end 342.152478 -231.041448)
		(width 0.0889)
		(layer "In2.Cu")
		(net "M_C_CPU0_SA_DQ<9>")
	)
	(arc
		(start 328.950574 -231.017064)
		(mid 328.837167 -230.884175)
		(end 328.796396 -230.714296)
		(width 0.0889)
		(layer "In2.Cu")
		(net "M_C_CPU0_SA_DQ<9>")
	)
	(arc
		(start 334.99806 -231.036622)
		(mid 334.811116 -231.086911)
		(end 334.624172 -231.036622)
		(width 0.0889)
		(layer "In2.Cu")
		(net "M_C_CPU0_SA_DQ<9>")
	)
	(arc
		(start 325.028306 -224.413064)
		(mid 324.989972 -224.388982)
		(end 324.945502 -224.380552)
		(width 0.0889)
		(layer "In2.Cu")
		(net "M_C_CPU0_SA_DQ<9>")
	)
	(arc
		(start 335.563972 -231.036622)
		(mid 335.281016 -230.960445)
		(end 334.99806 -231.036622)
		(width 0.0889)
		(layer "In2.Cu")
		(net "M_C_CPU0_SA_DQ<9>")
	)
	(arc
		(start 334.624172 -231.036622)
		(mid 334.341216 -230.960445)
		(end 334.05826 -231.036622)
		(width 0.0889)
		(layer "In2.Cu")
		(net "M_C_CPU0_SA_DQ<9>")
	)
	(arc
		(start 334.05826 -231.036622)
		(mid 333.876009 -231.087006)
		(end 333.6925 -231.041448)
		(width 0.0889)
		(layer "In2.Cu")
		(net "M_C_CPU0_SA_DQ<9>")
	)
	(arc
		(start 343.40292 -231.062784)
		(mid 343.240589 -231.085633)
		(end 343.08415 -231.036622)
		(width 0.0889)
		(layer "In2.Cu")
		(net "M_C_CPU0_SA_DQ<9>")
	)
	(arc
		(start 328.326496 -229.904036)
		(mid 328.261981 -229.641817)
		(end 328.083164 -229.43947)
		(width 0.0889)
		(layer "In2.Cu")
		(net "M_C_CPU0_SA_DQ<9>")
	)
	(arc
		(start 337.818222 -231.036622)
		(mid 337.635971 -231.087006)
		(end 337.452462 -231.041448)
		(width 0.0889)
		(layer "In2.Cu")
		(net "M_C_CPU0_SA_DQ<9>")
	)
	(arc
		(start 343.08415 -231.036622)
		(mid 342.801194 -230.960445)
		(end 342.518238 -231.036622)
		(width 0.0889)
		(layer "In2.Cu")
		(net "M_C_CPU0_SA_DQ<9>")
	)
	(arc
		(start 329.924156 -231.036622)
		(mid 329.6412 -230.960445)
		(end 329.358244 -231.036622)
		(width 0.0889)
		(layer "In2.Cu")
		(net "M_C_CPU0_SA_DQ<9>")
	)
	(arc
		(start 329.358244 -231.036622)
		(mid 329.175993 -231.087006)
		(end 328.992484 -231.041448)
		(width 0.0889)
		(layer "In2.Cu")
		(net "M_C_CPU0_SA_DQ<9>")
	)
	(arc
		(start 333.684118 -231.036622)
		(mid 333.401162 -230.960445)
		(end 333.118206 -231.036622)
		(width 0.0889)
		(layer "In2.Cu")
		(net "M_C_CPU0_SA_DQ<9>")
	)
	(arc
		(start 327.068942 -227.77704)
		(mid 326.956738 -227.644204)
		(end 326.916542 -227.475034)
		(width 0.0889)
		(layer "In2.Cu")
		(net "M_C_CPU0_SA_DQ<9>")
	)
	(arc
		(start 340.629748 -231.041448)
		(mid 340.44624 -231.086973)
		(end 340.263988 -231.036622)
		(width 0.0889)
		(layer "In2.Cu")
		(net "M_C_CPU0_SA_DQ<9>")
	)
	(arc
		(start 330.863956 -231.036622)
		(mid 330.581 -230.960445)
		(end 330.298044 -231.036622)
		(width 0.0889)
		(layer "In2.Cu")
		(net "M_C_CPU0_SA_DQ<9>")
	)
	(arc
		(start 330.298044 -231.036622)
		(mid 330.1111 -231.086911)
		(end 329.924156 -231.036622)
		(width 0.0889)
		(layer "In2.Cu")
		(net "M_C_CPU0_SA_DQ<9>")
	)
	(arc
		(start 335.929732 -231.041448)
		(mid 335.746224 -231.086973)
		(end 335.563972 -231.036622)
		(width 0.0889)
		(layer "In2.Cu")
		(net "M_C_CPU0_SA_DQ<9>")
	)
	(arc
		(start 326.916542 -227.475034)
		(mid 326.853199 -227.214239)
		(end 326.676766 -227.011992)
		(width 0.0889)
		(layer "In2.Cu")
		(net "M_C_CPU0_SA_DQ<9>")
	)
	(arc
		(start 327.386696 -228.284532)
		(mid 327.321342 -228.021224)
		(end 327.140824 -227.818696)
		(width 0.0889)
		(layer "In2.Cu")
		(net "M_C_CPU0_SA_DQ<9>")
	)
	(arc
		(start 328.796396 -230.714296)
		(mid 328.730366 -230.449268)
		(end 328.54773 -230.246174)
		(width 0.0889)
		(layer "In2.Cu")
		(net "M_C_CPU0_SA_DQ<9>")
	)
	(arc
		(start 328.482452 -230.208328)
		(mid 328.367776 -230.074994)
		(end 328.326496 -229.904036)
		(width 0.0889)
		(layer "In2.Cu")
		(net "M_C_CPU0_SA_DQ<9>")
	)
	(arc
		(start 326.139302 -226.16287)
		(mid 326.02004 -226.02887)
		(end 325.976742 -225.854768)
		(width 0.0889)
		(layer "In2.Cu")
		(net "M_C_CPU0_SA_DQ<9>")
	)
	(arc
		(start 338.758022 -231.036622)
		(mid 338.571078 -231.086911)
		(end 338.384134 -231.036622)
		(width 0.0889)
		(layer "In2.Cu")
		(net "M_C_CPU0_SA_DQ<9>")
	)
	(arc
		(start 327.54697 -228.591364)
		(mid 327.429255 -228.457581)
		(end 327.386696 -228.284532)
		(width 0.0889)
		(layer "In2.Cu")
		(net "M_C_CPU0_SA_DQ<9>")
	)
	(arc
		(start 339.323934 -231.036622)
		(mid 339.040978 -230.960445)
		(end 338.758022 -231.036622)
		(width 0.0889)
		(layer "In2.Cu")
		(net "M_C_CPU0_SA_DQ<9>")
	)
	(arc
		(start 326.446896 -226.665536)
		(mid 326.380074 -226.398959)
		(end 326.195436 -226.195382)
		(width 0.0889)
		(layer "In2.Cu")
		(net "M_C_CPU0_SA_DQ<9>")
	)
	(arc
		(start 332.744064 -231.036622)
		(mid 332.461108 -230.960445)
		(end 332.178152 -231.036622)
		(width 0.0889)
		(layer "In2.Cu")
		(net "M_C_CPU0_SA_DQ<9>")
	)
	(arc
		(start 332.16977 -231.041448)
		(mid 331.986262 -231.086973)
		(end 331.80401 -231.036622)
		(width 0.0889)
		(layer "In2.Cu")
		(net "M_C_CPU0_SA_DQ<9>")
	)
	(arc
		(start 341.204042 -231.036622)
		(mid 340.921086 -230.960445)
		(end 340.63813 -231.036622)
		(width 0.0889)
		(layer "In2.Cu")
		(net "M_C_CPU0_SA_DQ<9>")
	)
	(arc
		(start 331.80401 -231.036622)
		(mid 331.521054 -230.960445)
		(end 331.238098 -231.036622)
		(width 0.0889)
		(layer "In2.Cu")
		(net "M_C_CPU0_SA_DQ<9>")
	)
	(arc
		(start 325.506842 -225.045524)
		(mid 325.431514 -224.764282)
		(end 325.225918 -224.558098)
		(width 0.0889)
		(layer "In2.Cu")
		(net "M_C_CPU0_SA_DQ<9>")
	)
	(arc
		(start 341.578184 -231.036622)
		(mid 341.395933 -231.087006)
		(end 341.212424 -231.041448)
		(width 0.0889)
		(layer "In2.Cu")
		(net "M_C_CPU0_SA_DQ<9>")
	)
	(arc
		(start 325.22414 -224.556828)
		(mid 325.122294 -224.490299)
		(end 325.028306 -224.413064)
		(width 0.0889)
		(layer "In2.Cu")
		(net "M_C_CPU0_SA_DQ<9>")
	)
	(arc
		(start 339.689694 -231.041448)
		(mid 339.506186 -231.086973)
		(end 339.323934 -231.036622)
		(width 0.0889)
		(layer "In2.Cu")
		(net "M_C_CPU0_SA_DQ<9>")
	)
	(arc
		(start 325.976742 -225.854768)
		(mid 325.910475 -225.590307)
		(end 325.728076 -225.387662)
		(width 0.0889)
		(layer "In2.Cu")
		(net "M_C_CPU0_SA_DQ<9>")
	)
	(arc
		(start 337.44408 -231.036622)
		(mid 337.161124 -230.960445)
		(end 336.878168 -231.036622)
		(width 0.0889)
		(layer "In2.Cu")
		(net "M_C_CPU0_SA_DQ<9>")
	)
	(arc
		(start 328.011536 -229.397814)
		(mid 327.897607 -229.264667)
		(end 327.856596 -229.094284)
		(width 0.0889)
		(layer "In2.Cu")
		(net "M_C_CPU0_SA_DQ<9>")
	)
	(arc
		(start 336.504026 -231.036622)
		(mid 336.22107 -230.960445)
		(end 335.938114 -231.036622)
		(width 0.0889)
		(layer "In2.Cu")
		(net "M_C_CPU0_SA_DQ<9>")
	)
	(arc
		(start 331.229716 -231.041448)
		(mid 331.046208 -231.086973)
		(end 330.863956 -231.036622)
		(width 0.0889)
		(layer "In2.Cu")
		(net "M_C_CPU0_SA_DQ<9>")
	)
	(arc
		(start 325.659242 -225.347784)
		(mid 325.54698 -225.214835)
		(end 325.506842 -225.045524)
		(width 0.0889)
		(layer "In2.Cu")
		(net "M_C_CPU0_SA_DQ<9>")
	)
	(arc
		(start 333.118206 -231.036622)
		(mid 332.935955 -231.087006)
		(end 332.752446 -231.041448)
		(width 0.0889)
		(layer "In2.Cu")
		(net "M_C_CPU0_SA_DQ<9>")
	)
	(arc
		(start 326.59828 -226.966526)
		(mid 326.48687 -226.833995)
		(end 326.446896 -226.665536)
		(width 0.0889)
		(layer "In2.Cu")
		(net "M_C_CPU0_SA_DQ<9>")
	)
	(arc
		(start 336.869786 -231.041448)
		(mid 336.686278 -231.086973)
		(end 336.504026 -231.036622)
		(width 0.0889)
		(layer "In2.Cu")
		(net "M_C_CPU0_SA_DQ<9>")
	)
	(arc
		(start 340.263988 -231.036622)
		(mid 339.981032 -230.960445)
		(end 339.698076 -231.036622)
		(width 0.0889)
		(layer "In2.Cu")
		(net "M_C_CPU0_SA_DQ<9>")
	)
	(arc
		(start 327.856596 -229.094284)
		(mid 327.790896 -228.830323)
		(end 327.609454 -228.627686)
		(width 0.0889)
		(layer "In2.Cu")
		(net "M_C_CPU0_SA_DQ<9>")
	)
	(arc
		(start 342.144096 -231.036622)
		(mid 341.86114 -230.960445)
		(end 341.578184 -231.036622)
		(width 0.0889)
		(layer "In2.Cu")
		(net "M_C_CPU0_SA_DQ<9>")
	)
	(segment
		(start 342.327992 -230.169974)
		(end 341.86114 -229.904036)
		(width 0.10668)
		(layer "F.Cu")
		(net "M_C_CPU0_SA_DQ<8>")
	)
	(segment
		(start 312.008266 -207.526128)
		(end 311.845198 -207.36306)
		(width 0.14478)
		(layer "In2.Cu")
		(net "M_C_CPU0_SA_DQ<8>")
	)
	(segment
		(start 329.828144 -230.226616)
		(end 329.819762 -230.231442)
		(width 0.0889)
		(layer "In2.Cu")
		(net "M_C_CPU0_SA_DQ<8>")
	)
	(segment
		(start 339.80247 -230.231442)
		(end 339.794088 -230.226616)
		(width 0.0889)
		(layer "In2.Cu")
		(net "M_C_CPU0_SA_DQ<8>")
	)
	(segment
		(start 310.322976 -206.849218)
		(end 310.093614 -206.619856)
		(width 0.14478)
		(layer "In2.Cu")
		(net "M_C_CPU0_SA_DQ<8>")
	)
	(segment
		(start 314.096908 -210.62315)
		(end 314.096908 -210.392518)
		(width 0.14478)
		(layer "In2.Cu")
		(net "M_C_CPU0_SA_DQ<8>")
	)
	(segment
		(start 313.189366 -208.93786)
		(end 312.915808 -209.211418)
		(width 0.14478)
		(layer "In2.Cu")
		(net "M_C_CPU0_SA_DQ<8>")
	)
	(segment
		(start 313.583066 -209.100928)
		(end 313.419998 -208.93786)
		(width 0.14478)
		(layer "In2.Cu")
		(net "M_C_CPU0_SA_DQ<8>")
	)
	(segment
		(start 328.550524 -228.62794)
		(end 328.514202 -228.606858)
		(width 0.0889)
		(layer "In2.Cu")
		(net "M_C_CPU0_SA_DQ<8>")
	)
	(segment
		(start 327.574148 -226.986338)
		(end 327.540874 -226.967034)
		(width 0.0889)
		(layer "In2.Cu")
		(net "M_C_CPU0_SA_DQ<8>")
	)
	(segment
		(start 311.734708 -208.030318)
		(end 312.008266 -207.75676)
		(width 0.14478)
		(layer "In2.Cu")
		(net "M_C_CPU0_SA_DQ<8>")
	)
	(segment
		(start 311.110376 -207.636618)
		(end 310.947308 -207.47355)
		(width 0.14478)
		(layer "In2.Cu")
		(net "M_C_CPU0_SA_DQ<8>")
	)
	(segment
		(start 325.447914 -223.34601)
		(end 323.789294 -221.68739)
		(width 0.14478)
		(layer "In2.Cu")
		(net "M_C_CPU0_SA_DQ<8>")
	)
	(segment
		(start 327.13803 -226.194874)
		(end 327.104502 -226.175316)
		(width 0.0889)
		(layer "In2.Cu")
		(net "M_C_CPU0_SA_DQ<8>")
	)
	(segment
		(start 323.789294 -219.79509)
		(end 314.957714 -210.96351)
		(width 0.14478)
		(layer "In2.Cu")
		(net "M_C_CPU0_SA_DQ<8>")
	)
	(segment
		(start 313.309508 -209.605118)
		(end 313.583066 -209.33156)
		(width 0.14478)
		(layer "In2.Cu")
		(net "M_C_CPU0_SA_DQ<8>")
	)
	(segment
		(start 310.947308 -207.47355)
		(end 310.947308 -207.242918)
		(width 0.14478)
		(layer "In2.Cu")
		(net "M_C_CPU0_SA_DQ<8>")
	)
	(segment
		(start 297.353228 -207.110076)
		(end 292.705028 -207.110076)
		(width 0.14478)
		(layer "In2.Cu")
		(net "M_C_CPU0_SA_DQ<8>")
	)
	(segment
		(start 313.309508 -209.83575)
		(end 313.309508 -209.605118)
		(width 0.14478)
		(layer "In2.Cu")
		(net "M_C_CPU0_SA_DQ<8>")
	)
	(segment
		(start 338.288122 -230.226616)
		(end 338.27974 -230.231442)
		(width 0.0889)
		(layer "In2.Cu")
		(net "M_C_CPU0_SA_DQ<8>")
	)
	(segment
		(start 312.915808 -209.211418)
		(end 312.685176 -209.211418)
		(width 0.14478)
		(layer "In2.Cu")
		(net "M_C_CPU0_SA_DQ<8>")
	)
	(segment
		(start 308.570122 -206.619856)
		(end 308.210458 -206.260192)
		(width 0.14478)
		(layer "In2.Cu")
		(net "M_C_CPU0_SA_DQ<8>")
	)
	(segment
		(start 328.514202 -228.606858)
		(end 328.482452 -228.58857)
		(width 0.0889)
		(layer "In2.Cu")
		(net "M_C_CPU0_SA_DQ<8>")
	)
	(segment
		(start 312.795666 -208.313528)
		(end 312.632598 -208.15046)
		(width 0.14478)
		(layer "In2.Cu")
		(net "M_C_CPU0_SA_DQ<8>")
	)
	(segment
		(start 301.042832 -206.260192)
		(end 298.203112 -206.260192)
		(width 0.14478)
		(layer "In2.Cu")
		(net "M_C_CPU0_SA_DQ<8>")
	)
	(segment
		(start 323.789294 -221.68739)
		(end 323.789294 -219.79509)
		(width 0.14478)
		(layer "In2.Cu")
		(net "M_C_CPU0_SA_DQ<8>")
	)
	(segment
		(start 310.093614 -206.619856)
		(end 308.570122 -206.619856)
		(width 0.14478)
		(layer "In2.Cu")
		(net "M_C_CPU0_SA_DQ<8>")
	)
	(segment
		(start 329.023218 -229.43947)
		(end 328.984102 -229.41661)
		(width 0.0889)
		(layer "In2.Cu")
		(net "M_C_CPU0_SA_DQ<8>")
	)
	(segment
		(start 314.370466 -209.888328)
		(end 314.207398 -209.72526)
		(width 0.14478)
		(layer "In2.Cu")
		(net "M_C_CPU0_SA_DQ<8>")
	)
	(segment
		(start 333.588106 -230.226616)
		(end 333.579724 -230.231442)
		(width 0.0889)
		(layer "In2.Cu")
		(net "M_C_CPU0_SA_DQ<8>")
	)
	(segment
		(start 342.015064 -230.169466)
		(end 341.992712 -230.252778)
		(width 0.0889)
		(layer "In2.Cu")
		(net "M_C_CPU0_SA_DQ<8>")
	)
	(segment
		(start 326.634094 -225.366834)
		(end 326.60463 -225.349816)
		(width 0.0889)
		(layer "In2.Cu")
		(net "M_C_CPU0_SA_DQ<8>")
	)
	(segment
		(start 325.735188 -223.770444)
		(end 325.447914 -223.48317)
		(width 0.0889)
		(layer "In2.Cu")
		(net "M_C_CPU0_SA_DQ<8>")
	)
	(segment
		(start 329.454002 -230.226616)
		(end 329.423522 -230.208836)
		(width 0.0889)
		(layer "In2.Cu")
		(net "M_C_CPU0_SA_DQ<8>")
	)
	(segment
		(start 312.795666 -208.54416)
		(end 312.795666 -208.313528)
		(width 0.14478)
		(layer "In2.Cu")
		(net "M_C_CPU0_SA_DQ<8>")
	)
	(segment
		(start 310.827166 -206.57566)
		(end 310.553608 -206.849218)
		(width 0.14478)
		(layer "In2.Cu")
		(net "M_C_CPU0_SA_DQ<8>")
	)
	(segment
		(start 325.447914 -223.48317)
		(end 325.447914 -223.34601)
		(width 0.0889)
		(layer "In2.Cu")
		(net "M_C_CPU0_SA_DQ<8>")
	)
	(segment
		(start 314.096908 -210.392518)
		(end 314.370466 -210.11896)
		(width 0.14478)
		(layer "In2.Cu")
		(net "M_C_CPU0_SA_DQ<8>")
	)
	(segment
		(start 313.703208 -209.998818)
		(end 313.472576 -209.998818)
		(width 0.14478)
		(layer "In2.Cu")
		(net "M_C_CPU0_SA_DQ<8>")
	)
	(segment
		(start 330.402438 -230.231442)
		(end 330.394056 -230.226616)
		(width 0.0889)
		(layer "In2.Cu")
		(net "M_C_CPU0_SA_DQ<8>")
	)
	(segment
		(start 311.614566 -207.36306)
		(end 311.341008 -207.636618)
		(width 0.14478)
		(layer "In2.Cu")
		(net "M_C_CPU0_SA_DQ<8>")
	)
	(segment
		(start 312.401966 -208.15046)
		(end 312.128408 -208.424018)
		(width 0.14478)
		(layer "In2.Cu")
		(net "M_C_CPU0_SA_DQ<8>")
	)
	(segment
		(start 312.128408 -208.424018)
		(end 311.897776 -208.424018)
		(width 0.14478)
		(layer "In2.Cu")
		(net "M_C_CPU0_SA_DQ<8>")
	)
	(segment
		(start 292.705028 -207.110076)
		(end 292.280086 -206.685134)
		(width 0.14478)
		(layer "In2.Cu")
		(net "M_C_CPU0_SA_DQ<8>")
	)
	(segment
		(start 312.632598 -208.15046)
		(end 312.401966 -208.15046)
		(width 0.14478)
		(layer "In2.Cu")
		(net "M_C_CPU0_SA_DQ<8>")
	)
	(segment
		(start 314.437268 -210.96351)
		(end 314.096908 -210.62315)
		(width 0.14478)
		(layer "In2.Cu")
		(net "M_C_CPU0_SA_DQ<8>")
	)
	(segment
		(start 314.207398 -209.72526)
		(end 313.976766 -209.72526)
		(width 0.14478)
		(layer "In2.Cu")
		(net "M_C_CPU0_SA_DQ<8>")
	)
	(segment
		(start 298.203112 -206.260192)
		(end 297.353228 -207.110076)
		(width 0.14478)
		(layer "In2.Cu")
		(net "M_C_CPU0_SA_DQ<8>")
	)
	(segment
		(start 336.042508 -230.231442)
		(end 336.034126 -230.226616)
		(width 0.0889)
		(layer "In2.Cu")
		(net "M_C_CPU0_SA_DQ<8>")
	)
	(segment
		(start 311.734708 -208.26095)
		(end 311.734708 -208.030318)
		(width 0.14478)
		(layer "In2.Cu")
		(net "M_C_CPU0_SA_DQ<8>")
	)
	(segment
		(start 305.740816 -206.260192)
		(end 304.890932 -207.110076)
		(width 0.14478)
		(layer "In2.Cu")
		(net "M_C_CPU0_SA_DQ<8>")
	)
	(segment
		(start 311.057798 -206.57566)
		(end 310.827166 -206.57566)
		(width 0.14478)
		(layer "In2.Cu")
		(net "M_C_CPU0_SA_DQ<8>")
	)
	(segment
		(start 326.206358 -224.580196)
		(end 326.164448 -224.555812)
		(width 0.0889)
		(layer "In2.Cu")
		(net "M_C_CPU0_SA_DQ<8>")
	)
	(segment
		(start 335.102454 -230.231442)
		(end 335.094072 -230.226616)
		(width 0.0889)
		(layer "In2.Cu")
		(net "M_C_CPU0_SA_DQ<8>")
	)
	(segment
		(start 313.976766 -209.72526)
		(end 313.703208 -209.998818)
		(width 0.14478)
		(layer "In2.Cu")
		(net "M_C_CPU0_SA_DQ<8>")
	)
	(segment
		(start 341.86114 -229.904036)
		(end 342.015064 -230.169466)
		(width 0.0889)
		(layer "In2.Cu")
		(net "M_C_CPU0_SA_DQ<8>")
	)
	(segment
		(start 311.897776 -208.424018)
		(end 311.734708 -208.26095)
		(width 0.14478)
		(layer "In2.Cu")
		(net "M_C_CPU0_SA_DQ<8>")
	)
	(segment
		(start 313.583066 -209.33156)
		(end 313.583066 -209.100928)
		(width 0.14478)
		(layer "In2.Cu")
		(net "M_C_CPU0_SA_DQ<8>")
	)
	(segment
		(start 311.220866 -206.96936)
		(end 311.220866 -206.738728)
		(width 0.14478)
		(layer "In2.Cu")
		(net "M_C_CPU0_SA_DQ<8>")
	)
	(segment
		(start 326.676004 -225.391218)
		(end 326.634094 -225.366834)
		(width 0.0889)
		(layer "In2.Cu")
		(net "M_C_CPU0_SA_DQ<8>")
	)
	(segment
		(start 334.52816 -230.226616)
		(end 334.519778 -230.231442)
		(width 0.0889)
		(layer "In2.Cu")
		(net "M_C_CPU0_SA_DQ<8>")
	)
	(segment
		(start 313.472576 -209.998818)
		(end 313.309508 -209.83575)
		(width 0.14478)
		(layer "In2.Cu")
		(net "M_C_CPU0_SA_DQ<8>")
	)
	(segment
		(start 312.522108 -209.04835)
		(end 312.522108 -208.817718)
		(width 0.14478)
		(layer "In2.Cu")
		(net "M_C_CPU0_SA_DQ<8>")
	)
	(segment
		(start 312.685176 -209.211418)
		(end 312.522108 -209.04835)
		(width 0.14478)
		(layer "In2.Cu")
		(net "M_C_CPU0_SA_DQ<8>")
	)
	(segment
		(start 327.616566 -227.010976)
		(end 327.574148 -226.986338)
		(width 0.0889)
		(layer "In2.Cu")
		(net "M_C_CPU0_SA_DQ<8>")
	)
	(segment
		(start 328.984102 -229.41661)
		(end 328.950574 -229.397052)
		(width 0.0889)
		(layer "In2.Cu")
		(net "M_C_CPU0_SA_DQ<8>")
	)
	(segment
		(start 311.845198 -207.36306)
		(end 311.614566 -207.36306)
		(width 0.14478)
		(layer "In2.Cu")
		(net "M_C_CPU0_SA_DQ<8>")
	)
	(segment
		(start 311.220866 -206.738728)
		(end 311.057798 -206.57566)
		(width 0.14478)
		(layer "In2.Cu")
		(net "M_C_CPU0_SA_DQ<8>")
	)
	(segment
		(start 308.210458 -206.260192)
		(end 305.740816 -206.260192)
		(width 0.14478)
		(layer "In2.Cu")
		(net "M_C_CPU0_SA_DQ<8>")
	)
	(segment
		(start 331.342492 -230.231442)
		(end 331.33411 -230.226616)
		(width 0.0889)
		(layer "In2.Cu")
		(net "M_C_CPU0_SA_DQ<8>")
	)
	(segment
		(start 326.164448 -224.555812)
		(end 326.124824 -224.532952)
		(width 0.0889)
		(layer "In2.Cu")
		(net "M_C_CPU0_SA_DQ<8>")
	)
	(segment
		(start 311.341008 -207.636618)
		(end 311.110376 -207.636618)
		(width 0.14478)
		(layer "In2.Cu")
		(net "M_C_CPU0_SA_DQ<8>")
	)
	(segment
		(start 328.083164 -227.819712)
		(end 328.044048 -227.796852)
		(width 0.0889)
		(layer "In2.Cu")
		(net "M_C_CPU0_SA_DQ<8>")
	)
	(segment
		(start 314.957714 -210.96351)
		(end 314.437268 -210.96351)
		(width 0.14478)
		(layer "In2.Cu")
		(net "M_C_CPU0_SA_DQ<8>")
	)
	(segment
		(start 328.044048 -227.796852)
		(end 328.013568 -227.779072)
		(width 0.0889)
		(layer "In2.Cu")
		(net "M_C_CPU0_SA_DQ<8>")
	)
	(segment
		(start 304.890932 -207.110076)
		(end 301.892716 -207.110076)
		(width 0.14478)
		(layer "In2.Cu")
		(net "M_C_CPU0_SA_DQ<8>")
	)
	(segment
		(start 310.947308 -207.242918)
		(end 311.220866 -206.96936)
		(width 0.14478)
		(layer "In2.Cu")
		(net "M_C_CPU0_SA_DQ<8>")
	)
	(segment
		(start 312.008266 -207.75676)
		(end 312.008266 -207.526128)
		(width 0.14478)
		(layer "In2.Cu")
		(net "M_C_CPU0_SA_DQ<8>")
	)
	(segment
		(start 301.892716 -207.110076)
		(end 301.042832 -206.260192)
		(width 0.14478)
		(layer "In2.Cu")
		(net "M_C_CPU0_SA_DQ<8>")
	)
	(segment
		(start 312.522108 -208.817718)
		(end 312.795666 -208.54416)
		(width 0.14478)
		(layer "In2.Cu")
		(net "M_C_CPU0_SA_DQ<8>")
	)
	(segment
		(start 313.419998 -208.93786)
		(end 313.189366 -208.93786)
		(width 0.14478)
		(layer "In2.Cu")
		(net "M_C_CPU0_SA_DQ<8>")
	)
	(segment
		(start 327.104502 -226.175316)
		(end 327.071736 -226.156266)
		(width 0.0889)
		(layer "In2.Cu")
		(net "M_C_CPU0_SA_DQ<8>")
	)
	(segment
		(start 310.553608 -206.849218)
		(end 310.322976 -206.849218)
		(width 0.14478)
		(layer "In2.Cu")
		(net "M_C_CPU0_SA_DQ<8>")
	)
	(segment
		(start 338.862416 -230.231442)
		(end 338.854034 -230.226616)
		(width 0.0889)
		(layer "In2.Cu")
		(net "M_C_CPU0_SA_DQ<8>")
	)
	(segment
		(start 325.976488 -224.234248)
		(end 325.976488 -224.209356)
		(width 0.0889)
		(layer "In2.Cu")
		(net "M_C_CPU0_SA_DQ<8>")
	)
	(segment
		(start 314.370466 -210.11896)
		(end 314.370466 -209.888328)
		(width 0.14478)
		(layer "In2.Cu")
		(net "M_C_CPU0_SA_DQ<8>")
	)
	(arc
		(start 341.10803 -230.226616)
		(mid 340.921086 -230.276871)
		(end 340.734142 -230.226616)
		(width 0.0889)
		(layer "In2.Cu")
		(net "M_C_CPU0_SA_DQ<8>")
	)
	(arc
		(start 328.013568 -227.779072)
		(mid 327.898158 -227.645559)
		(end 327.856596 -227.474018)
		(width 0.0889)
		(layer "In2.Cu")
		(net "M_C_CPU0_SA_DQ<8>")
	)
	(arc
		(start 331.33411 -230.226616)
		(mid 331.051154 -230.150473)
		(end 330.768198 -230.226616)
		(width 0.0889)
		(layer "In2.Cu")
		(net "M_C_CPU0_SA_DQ<8>")
	)
	(arc
		(start 326.60463 -225.349816)
		(mid 326.488332 -225.216031)
		(end 326.446642 -225.043746)
		(width 0.0889)
		(layer "In2.Cu")
		(net "M_C_CPU0_SA_DQ<8>")
	)
	(arc
		(start 328.950574 -229.397052)
		(mid 328.837167 -229.264163)
		(end 328.796396 -229.094284)
		(width 0.0889)
		(layer "In2.Cu")
		(net "M_C_CPU0_SA_DQ<8>")
	)
	(arc
		(start 327.071736 -226.156266)
		(mid 326.957923 -226.023345)
		(end 326.916796 -225.853244)
		(width 0.0889)
		(layer "In2.Cu")
		(net "M_C_CPU0_SA_DQ<8>")
	)
	(arc
		(start 334.154018 -230.226616)
		(mid 333.871062 -230.150473)
		(end 333.588106 -230.226616)
		(width 0.0889)
		(layer "In2.Cu")
		(net "M_C_CPU0_SA_DQ<8>")
	)
	(arc
		(start 326.916796 -225.853244)
		(mid 326.85277 -225.59285)
		(end 326.676004 -225.391218)
		(width 0.0889)
		(layer "In2.Cu")
		(net "M_C_CPU0_SA_DQ<8>")
	)
	(arc
		(start 330.394056 -230.226616)
		(mid 330.1111 -230.150473)
		(end 329.828144 -230.226616)
		(width 0.0889)
		(layer "In2.Cu")
		(net "M_C_CPU0_SA_DQ<8>")
	)
	(arc
		(start 335.468214 -230.226616)
		(mid 335.285963 -230.276966)
		(end 335.102454 -230.231442)
		(width 0.0889)
		(layer "In2.Cu")
		(net "M_C_CPU0_SA_DQ<8>")
	)
	(arc
		(start 325.976488 -224.209356)
		(mid 325.912195 -223.958909)
		(end 325.735188 -223.770444)
		(width 0.0889)
		(layer "In2.Cu")
		(net "M_C_CPU0_SA_DQ<8>")
	)
	(arc
		(start 332.274164 -230.226616)
		(mid 331.991208 -230.150473)
		(end 331.708252 -230.226616)
		(width 0.0889)
		(layer "In2.Cu")
		(net "M_C_CPU0_SA_DQ<8>")
	)
	(arc
		(start 327.856596 -227.474018)
		(mid 327.793186 -227.213156)
		(end 327.616566 -227.010976)
		(width 0.0889)
		(layer "In2.Cu")
		(net "M_C_CPU0_SA_DQ<8>")
	)
	(arc
		(start 336.034126 -230.226616)
		(mid 335.75117 -230.150473)
		(end 335.468214 -230.226616)
		(width 0.0889)
		(layer "In2.Cu")
		(net "M_C_CPU0_SA_DQ<8>")
	)
	(arc
		(start 326.446642 -225.043746)
		(mid 326.383283 -224.782533)
		(end 326.206358 -224.580196)
		(width 0.0889)
		(layer "In2.Cu")
		(net "M_C_CPU0_SA_DQ<8>")
	)
	(arc
		(start 335.094072 -230.226616)
		(mid 334.811116 -230.150473)
		(end 334.52816 -230.226616)
		(width 0.0889)
		(layer "In2.Cu")
		(net "M_C_CPU0_SA_DQ<8>")
	)
	(arc
		(start 333.579724 -230.231442)
		(mid 333.396216 -230.276936)
		(end 333.213964 -230.226616)
		(width 0.0889)
		(layer "In2.Cu")
		(net "M_C_CPU0_SA_DQ<8>")
	)
	(arc
		(start 338.854034 -230.226616)
		(mid 338.571078 -230.150473)
		(end 338.288122 -230.226616)
		(width 0.0889)
		(layer "In2.Cu")
		(net "M_C_CPU0_SA_DQ<8>")
	)
	(arc
		(start 341.673942 -230.226616)
		(mid 341.390986 -230.150473)
		(end 341.10803 -230.226616)
		(width 0.0889)
		(layer "In2.Cu")
		(net "M_C_CPU0_SA_DQ<8>")
	)
	(arc
		(start 340.16823 -230.226616)
		(mid 339.985979 -230.276966)
		(end 339.80247 -230.231442)
		(width 0.0889)
		(layer "In2.Cu")
		(net "M_C_CPU0_SA_DQ<8>")
	)
	(arc
		(start 328.482452 -228.58857)
		(mid 328.367776 -228.455236)
		(end 328.326496 -228.284278)
		(width 0.0889)
		(layer "In2.Cu")
		(net "M_C_CPU0_SA_DQ<8>")
	)
	(arc
		(start 329.819762 -230.231442)
		(mid 329.636254 -230.276936)
		(end 329.454002 -230.226616)
		(width 0.0889)
		(layer "In2.Cu")
		(net "M_C_CPU0_SA_DQ<8>")
	)
	(arc
		(start 339.228176 -230.226616)
		(mid 339.045925 -230.276966)
		(end 338.862416 -230.231442)
		(width 0.0889)
		(layer "In2.Cu")
		(net "M_C_CPU0_SA_DQ<8>")
	)
	(arc
		(start 337.91398 -230.226616)
		(mid 337.631024 -230.150473)
		(end 337.348068 -230.226616)
		(width 0.0889)
		(layer "In2.Cu")
		(net "M_C_CPU0_SA_DQ<8>")
	)
	(arc
		(start 328.326496 -228.284278)
		(mid 328.261981 -228.022059)
		(end 328.083164 -227.819712)
		(width 0.0889)
		(layer "In2.Cu")
		(net "M_C_CPU0_SA_DQ<8>")
	)
	(arc
		(start 328.796396 -229.094284)
		(mid 328.73116 -228.830693)
		(end 328.550524 -228.62794)
		(width 0.0889)
		(layer "In2.Cu")
		(net "M_C_CPU0_SA_DQ<8>")
	)
	(arc
		(start 326.124824 -224.532952)
		(mid 326.01561 -224.401003)
		(end 325.976488 -224.234248)
		(width 0.0889)
		(layer "In2.Cu")
		(net "M_C_CPU0_SA_DQ<8>")
	)
	(arc
		(start 333.213964 -230.226616)
		(mid 332.931008 -230.150473)
		(end 332.648052 -230.226616)
		(width 0.0889)
		(layer "In2.Cu")
		(net "M_C_CPU0_SA_DQ<8>")
	)
	(arc
		(start 336.97418 -230.226616)
		(mid 336.691224 -230.150473)
		(end 336.408268 -230.226616)
		(width 0.0889)
		(layer "In2.Cu")
		(net "M_C_CPU0_SA_DQ<8>")
	)
	(arc
		(start 339.794088 -230.226616)
		(mid 339.511132 -230.150473)
		(end 339.228176 -230.226616)
		(width 0.0889)
		(layer "In2.Cu")
		(net "M_C_CPU0_SA_DQ<8>")
	)
	(arc
		(start 332.648052 -230.226616)
		(mid 332.461108 -230.276871)
		(end 332.274164 -230.226616)
		(width 0.0889)
		(layer "In2.Cu")
		(net "M_C_CPU0_SA_DQ<8>")
	)
	(arc
		(start 329.423522 -230.208836)
		(mid 329.308095 -230.07546)
		(end 329.26655 -229.904036)
		(width 0.0889)
		(layer "In2.Cu")
		(net "M_C_CPU0_SA_DQ<8>")
	)
	(arc
		(start 331.708252 -230.226616)
		(mid 331.526001 -230.276966)
		(end 331.342492 -230.231442)
		(width 0.0889)
		(layer "In2.Cu")
		(net "M_C_CPU0_SA_DQ<8>")
	)
	(arc
		(start 334.519778 -230.231442)
		(mid 334.33627 -230.276936)
		(end 334.154018 -230.226616)
		(width 0.0889)
		(layer "In2.Cu")
		(net "M_C_CPU0_SA_DQ<8>")
	)
	(arc
		(start 337.348068 -230.226616)
		(mid 337.161124 -230.276871)
		(end 336.97418 -230.226616)
		(width 0.0889)
		(layer "In2.Cu")
		(net "M_C_CPU0_SA_DQ<8>")
	)
	(arc
		(start 330.768198 -230.226616)
		(mid 330.585947 -230.276966)
		(end 330.402438 -230.231442)
		(width 0.0889)
		(layer "In2.Cu")
		(net "M_C_CPU0_SA_DQ<8>")
	)
	(arc
		(start 329.26655 -229.904036)
		(mid 329.202035 -229.641817)
		(end 329.023218 -229.43947)
		(width 0.0889)
		(layer "In2.Cu")
		(net "M_C_CPU0_SA_DQ<8>")
	)
	(arc
		(start 327.540874 -226.967034)
		(mid 327.42741 -226.834032)
		(end 327.386696 -226.664012)
		(width 0.0889)
		(layer "In2.Cu")
		(net "M_C_CPU0_SA_DQ<8>")
	)
	(arc
		(start 341.992712 -230.252778)
		(mid 341.83038 -230.275596)
		(end 341.673942 -230.226616)
		(width 0.0889)
		(layer "In2.Cu")
		(net "M_C_CPU0_SA_DQ<8>")
	)
	(arc
		(start 336.408268 -230.226616)
		(mid 336.226017 -230.276966)
		(end 336.042508 -230.231442)
		(width 0.0889)
		(layer "In2.Cu")
		(net "M_C_CPU0_SA_DQ<8>")
	)
	(arc
		(start 327.386696 -226.664012)
		(mid 327.320925 -226.39839)
		(end 327.13803 -226.194874)
		(width 0.0889)
		(layer "In2.Cu")
		(net "M_C_CPU0_SA_DQ<8>")
	)
	(arc
		(start 340.734142 -230.226616)
		(mid 340.451186 -230.150473)
		(end 340.16823 -230.226616)
		(width 0.0889)
		(layer "In2.Cu")
		(net "M_C_CPU0_SA_DQ<8>")
	)
	(arc
		(start 338.27974 -230.231442)
		(mid 338.096232 -230.276936)
		(end 337.91398 -230.226616)
		(width 0.0889)
		(layer "In2.Cu")
		(net "M_C_CPU0_SA_DQ<8>")
	)
	(segment
		(start 344.207846 -230.169974)
		(end 343.740994 -229.904036)
		(width 0.10668)
		(layer "F.Cu")
		(net "M_C_CPU0_SA_DQ<7>")
	)
	(segment
		(start 297.368214 -206.260192)
		(end 298.218352 -205.410054)
		(width 0.14478)
		(layer "In2.Cu")
		(net "M_C_CPU0_SA_DQ<7>")
	)
	(segment
		(start 326.962516 -224.695766)
		(end 327.008236 -224.722436)
		(width 0.0889)
		(layer "In2.Cu")
		(net "M_C_CPU0_SA_DQ<7>")
	)
	(segment
		(start 324.345554 -221.44863)
		(end 325.527416 -222.630492)
		(width 0.14478)
		(layer "In2.Cu")
		(net "M_C_CPU0_SA_DQ<7>")
	)
	(segment
		(start 324.345554 -219.561156)
		(end 324.345554 -221.44863)
		(width 0.14478)
		(layer "In2.Cu")
		(net "M_C_CPU0_SA_DQ<7>")
	)
	(segment
		(start 329.358244 -228.771704)
		(end 329.388724 -228.789484)
		(width 0.0889)
		(layer "In2.Cu")
		(net "M_C_CPU0_SA_DQ<7>")
	)
	(segment
		(start 328.379074 -227.128832)
		(end 328.41819 -227.151692)
		(width 0.0889)
		(layer "In2.Cu")
		(net "M_C_CPU0_SA_DQ<7>")
	)
	(segment
		(start 330.394056 -229.58171)
		(end 330.402438 -229.576884)
		(width 0.0889)
		(layer "In2.Cu")
		(net "M_C_CPU0_SA_DQ<7>")
	)
	(segment
		(start 314.983114 -210.198716)
		(end 324.345554 -219.561156)
		(width 0.14478)
		(layer "In2.Cu")
		(net "M_C_CPU0_SA_DQ<7>")
	)
	(segment
		(start 328.88809 -227.961698)
		(end 328.91984 -227.979986)
		(width 0.0889)
		(layer "In2.Cu")
		(net "M_C_CPU0_SA_DQ<7>")
	)
	(segment
		(start 333.579724 -229.576884)
		(end 333.588106 -229.58171)
		(width 0.0889)
		(layer "In2.Cu")
		(net "M_C_CPU0_SA_DQ<7>")
	)
	(segment
		(start 314.983114 -209.713576)
		(end 314.983114 -210.198716)
		(width 0.14478)
		(layer "In2.Cu")
		(net "M_C_CPU0_SA_DQ<7>")
	)
	(segment
		(start 290.577524 -206.097124)
		(end 290.740592 -206.260192)
		(width 0.14478)
		(layer "In2.Cu")
		(net "M_C_CPU0_SA_DQ<7>")
	)
	(segment
		(start 308.188614 -205.410054)
		(end 308.769766 -205.991206)
		(width 0.14478)
		(layer "In2.Cu")
		(net "M_C_CPU0_SA_DQ<7>")
	)
	(segment
		(start 336.034126 -229.58171)
		(end 336.042508 -229.576884)
		(width 0.0889)
		(layer "In2.Cu")
		(net "M_C_CPU0_SA_DQ<7>")
	)
	(segment
		(start 290.740592 -206.260192)
		(end 297.368214 -206.260192)
		(width 0.14478)
		(layer "In2.Cu")
		(net "M_C_CPU0_SA_DQ<7>")
	)
	(segment
		(start 304.890932 -206.259938)
		(end 305.740816 -205.410054)
		(width 0.14478)
		(layer "In2.Cu")
		(net "M_C_CPU0_SA_DQ<7>")
	)
	(segment
		(start 342.039702 -229.576884)
		(end 342.048084 -229.58171)
		(width 0.0889)
		(layer "In2.Cu")
		(net "M_C_CPU0_SA_DQ<7>")
	)
	(segment
		(start 338.854034 -229.58171)
		(end 338.862416 -229.576884)
		(width 0.0889)
		(layer "In2.Cu")
		(net "M_C_CPU0_SA_DQ<7>")
	)
	(segment
		(start 311.260744 -205.991206)
		(end 314.983114 -209.713576)
		(width 0.14478)
		(layer "In2.Cu")
		(net "M_C_CPU0_SA_DQ<7>")
	)
	(segment
		(start 325.527416 -222.630492)
		(end 325.879206 -222.982282)
		(width 0.0889)
		(layer "In2.Cu")
		(net "M_C_CPU0_SA_DQ<7>")
	)
	(segment
		(start 327.478644 -225.532442)
		(end 327.505822 -225.54819)
		(width 0.0889)
		(layer "In2.Cu")
		(net "M_C_CPU0_SA_DQ<7>")
	)
	(segment
		(start 290.184078 -205.216252)
		(end 290.414456 -205.216252)
		(width 0.14478)
		(layer "In2.Cu")
		(net "M_C_CPU0_SA_DQ<7>")
	)
	(segment
		(start 326.538082 -223.911668)
		(end 326.571864 -223.931226)
		(width 0.0889)
		(layer "In2.Cu")
		(net "M_C_CPU0_SA_DQ<7>")
	)
	(segment
		(start 301.042832 -205.410054)
		(end 301.892716 -206.259938)
		(width 0.14478)
		(layer "In2.Cu")
		(net "M_C_CPU0_SA_DQ<7>")
	)
	(segment
		(start 343.491312 -229.613206)
		(end 343.58707 -229.638606)
		(width 0.0889)
		(layer "In2.Cu")
		(net "M_C_CPU0_SA_DQ<7>")
	)
	(segment
		(start 290.577524 -205.37932)
		(end 290.577524 -206.097124)
		(width 0.14478)
		(layer "In2.Cu")
		(net "M_C_CPU0_SA_DQ<7>")
	)
	(segment
		(start 342.979756 -229.576884)
		(end 342.988138 -229.58171)
		(width 0.0889)
		(layer "In2.Cu")
		(net "M_C_CPU0_SA_DQ<7>")
	)
	(segment
		(start 327.008236 -224.722436)
		(end 327.044304 -224.743264)
		(width 0.0889)
		(layer "In2.Cu")
		(net "M_C_CPU0_SA_DQ<7>")
	)
	(segment
		(start 327.94829 -226.341686)
		(end 327.97877 -226.359466)
		(width 0.0889)
		(layer "In2.Cu")
		(net "M_C_CPU0_SA_DQ<7>")
	)
	(segment
		(start 305.740816 -205.410054)
		(end 308.188614 -205.410054)
		(width 0.14478)
		(layer "In2.Cu")
		(net "M_C_CPU0_SA_DQ<7>")
	)
	(segment
		(start 290.414456 -205.216252)
		(end 290.577524 -205.37932)
		(width 0.14478)
		(layer "In2.Cu")
		(net "M_C_CPU0_SA_DQ<7>")
	)
	(segment
		(start 288.605214 -206.260192)
		(end 289.857942 -206.260192)
		(width 0.14478)
		(layer "In2.Cu")
		(net "M_C_CPU0_SA_DQ<7>")
	)
	(segment
		(start 335.094072 -229.58171)
		(end 335.102454 -229.576884)
		(width 0.0889)
		(layer "In2.Cu")
		(net "M_C_CPU0_SA_DQ<7>")
	)
	(segment
		(start 334.519778 -229.576884)
		(end 334.52816 -229.58171)
		(width 0.0889)
		(layer "In2.Cu")
		(net "M_C_CPU0_SA_DQ<7>")
	)
	(segment
		(start 325.949564 -223.035876)
		(end 326.070214 -223.104964)
		(width 0.0889)
		(layer "In2.Cu")
		(net "M_C_CPU0_SA_DQ<7>")
	)
	(segment
		(start 298.218352 -205.410054)
		(end 301.042832 -205.410054)
		(width 0.14478)
		(layer "In2.Cu")
		(net "M_C_CPU0_SA_DQ<7>")
	)
	(segment
		(start 288.180018 -205.834996)
		(end 288.605214 -206.260192)
		(width 0.14478)
		(layer "In2.Cu")
		(net "M_C_CPU0_SA_DQ<7>")
	)
	(segment
		(start 289.857942 -206.260192)
		(end 290.02101 -206.097124)
		(width 0.14478)
		(layer "In2.Cu")
		(net "M_C_CPU0_SA_DQ<7>")
	)
	(segment
		(start 290.02101 -206.097124)
		(end 290.02101 -205.37932)
		(width 0.14478)
		(layer "In2.Cu")
		(net "M_C_CPU0_SA_DQ<7>")
	)
	(segment
		(start 301.892716 -206.260192)
		(end 304.890932 -206.260192)
		(width 0.14478)
		(layer "In2.Cu")
		(net "M_C_CPU0_SA_DQ<7>")
	)
	(segment
		(start 290.02101 -205.37932)
		(end 290.184078 -205.216252)
		(width 0.14478)
		(layer "In2.Cu")
		(net "M_C_CPU0_SA_DQ<7>")
	)
	(segment
		(start 327.911968 -226.320604)
		(end 327.94829 -226.341686)
		(width 0.0889)
		(layer "In2.Cu")
		(net "M_C_CPU0_SA_DQ<7>")
	)
	(segment
		(start 304.890932 -206.260192)
		(end 304.890932 -206.259938)
		(width 0.14478)
		(layer "In2.Cu")
		(net "M_C_CPU0_SA_DQ<7>")
	)
	(segment
		(start 331.33411 -229.58171)
		(end 331.342492 -229.576884)
		(width 0.0889)
		(layer "In2.Cu")
		(net "M_C_CPU0_SA_DQ<7>")
	)
	(segment
		(start 301.892716 -206.259938)
		(end 301.892716 -206.260192)
		(width 0.14478)
		(layer "In2.Cu")
		(net "M_C_CPU0_SA_DQ<7>")
	)
	(segment
		(start 339.794088 -229.58171)
		(end 339.80247 -229.576884)
		(width 0.0889)
		(layer "In2.Cu")
		(net "M_C_CPU0_SA_DQ<7>")
	)
	(segment
		(start 329.319128 -228.748844)
		(end 329.358244 -228.771704)
		(width 0.0889)
		(layer "In2.Cu")
		(net "M_C_CPU0_SA_DQ<7>")
	)
	(segment
		(start 328.851768 -227.940616)
		(end 328.88809 -227.961698)
		(width 0.0889)
		(layer "In2.Cu")
		(net "M_C_CPU0_SA_DQ<7>")
	)
	(segment
		(start 343.58707 -229.638606)
		(end 343.740994 -229.904036)
		(width 0.0889)
		(layer "In2.Cu")
		(net "M_C_CPU0_SA_DQ<7>")
	)
	(segment
		(start 327.4441 -225.512376)
		(end 327.478644 -225.532442)
		(width 0.0889)
		(layer "In2.Cu")
		(net "M_C_CPU0_SA_DQ<7>")
	)
	(segment
		(start 329.789028 -229.55885)
		(end 329.828144 -229.58171)
		(width 0.0889)
		(layer "In2.Cu")
		(net "M_C_CPU0_SA_DQ<7>")
	)
	(segment
		(start 338.27974 -229.576884)
		(end 338.288122 -229.58171)
		(width 0.0889)
		(layer "In2.Cu")
		(net "M_C_CPU0_SA_DQ<7>")
	)
	(segment
		(start 328.41819 -227.151692)
		(end 328.44994 -227.16998)
		(width 0.0889)
		(layer "In2.Cu")
		(net "M_C_CPU0_SA_DQ<7>")
	)
	(segment
		(start 326.504808 -223.892364)
		(end 326.538082 -223.911668)
		(width 0.0889)
		(layer "In2.Cu")
		(net "M_C_CPU0_SA_DQ<7>")
	)
	(segment
		(start 308.769766 -205.991206)
		(end 311.260744 -205.991206)
		(width 0.14478)
		(layer "In2.Cu")
		(net "M_C_CPU0_SA_DQ<7>")
	)
	(arc
		(start 338.288122 -229.58171)
		(mid 338.571078 -229.657887)
		(end 338.854034 -229.58171)
		(width 0.0889)
		(layer "In2.Cu")
		(net "M_C_CPU0_SA_DQ<7>")
	)
	(arc
		(start 333.213964 -229.58171)
		(mid 333.396215 -229.531326)
		(end 333.579724 -229.576884)
		(width 0.0889)
		(layer "In2.Cu")
		(net "M_C_CPU0_SA_DQ<7>")
	)
	(arc
		(start 337.348068 -229.58171)
		(mid 337.631024 -229.657887)
		(end 337.91398 -229.58171)
		(width 0.0889)
		(layer "In2.Cu")
		(net "M_C_CPU0_SA_DQ<7>")
	)
	(arc
		(start 327.044304 -224.743264)
		(mid 327.155714 -224.875795)
		(end 327.195688 -225.044254)
		(width 0.0889)
		(layer "In2.Cu")
		(net "M_C_CPU0_SA_DQ<7>")
	)
	(arc
		(start 331.708252 -229.58171)
		(mid 331.991208 -229.657887)
		(end 332.274164 -229.58171)
		(width 0.0889)
		(layer "In2.Cu")
		(net "M_C_CPU0_SA_DQ<7>")
	)
	(arc
		(start 334.52816 -229.58171)
		(mid 334.811116 -229.657887)
		(end 335.094072 -229.58171)
		(width 0.0889)
		(layer "In2.Cu")
		(net "M_C_CPU0_SA_DQ<7>")
	)
	(arc
		(start 326.070214 -223.104964)
		(mid 326.206195 -223.240264)
		(end 326.256142 -223.425512)
		(width 0.0889)
		(layer "In2.Cu")
		(net "M_C_CPU0_SA_DQ<7>")
	)
	(arc
		(start 342.048084 -229.58171)
		(mid 342.33104 -229.657887)
		(end 342.613996 -229.58171)
		(width 0.0889)
		(layer "In2.Cu")
		(net "M_C_CPU0_SA_DQ<7>")
	)
	(arc
		(start 329.545696 -229.094284)
		(mid 329.610211 -229.356503)
		(end 329.789028 -229.55885)
		(width 0.0889)
		(layer "In2.Cu")
		(net "M_C_CPU0_SA_DQ<7>")
	)
	(arc
		(start 341.673942 -229.58171)
		(mid 341.856193 -229.531326)
		(end 342.039702 -229.576884)
		(width 0.0889)
		(layer "In2.Cu")
		(net "M_C_CPU0_SA_DQ<7>")
	)
	(arc
		(start 327.505822 -225.54819)
		(mid 327.623537 -225.681973)
		(end 327.666096 -225.855022)
		(width 0.0889)
		(layer "In2.Cu")
		(net "M_C_CPU0_SA_DQ<7>")
	)
	(arc
		(start 329.388724 -228.789484)
		(mid 329.504151 -228.92286)
		(end 329.545696 -229.094284)
		(width 0.0889)
		(layer "In2.Cu")
		(net "M_C_CPU0_SA_DQ<7>")
	)
	(arc
		(start 327.666096 -225.855022)
		(mid 327.731509 -226.118188)
		(end 327.911968 -226.320604)
		(width 0.0889)
		(layer "In2.Cu")
		(net "M_C_CPU0_SA_DQ<7>")
	)
	(arc
		(start 333.588106 -229.58171)
		(mid 333.871062 -229.657887)
		(end 334.154018 -229.58171)
		(width 0.0889)
		(layer "In2.Cu")
		(net "M_C_CPU0_SA_DQ<7>")
	)
	(arc
		(start 336.408268 -229.58171)
		(mid 336.691224 -229.657887)
		(end 336.97418 -229.58171)
		(width 0.0889)
		(layer "In2.Cu")
		(net "M_C_CPU0_SA_DQ<7>")
	)
	(arc
		(start 335.102454 -229.576884)
		(mid 335.285962 -229.531359)
		(end 335.468214 -229.58171)
		(width 0.0889)
		(layer "In2.Cu")
		(net "M_C_CPU0_SA_DQ<7>")
	)
	(arc
		(start 330.768198 -229.58171)
		(mid 331.051154 -229.657887)
		(end 331.33411 -229.58171)
		(width 0.0889)
		(layer "In2.Cu")
		(net "M_C_CPU0_SA_DQ<7>")
	)
	(arc
		(start 325.879206 -222.982282)
		(mid 325.912615 -223.0114)
		(end 325.949564 -223.035876)
		(width 0.0889)
		(layer "In2.Cu")
		(net "M_C_CPU0_SA_DQ<7>")
	)
	(arc
		(start 338.862416 -229.576884)
		(mid 339.045924 -229.531359)
		(end 339.228176 -229.58171)
		(width 0.0889)
		(layer "In2.Cu")
		(net "M_C_CPU0_SA_DQ<7>")
	)
	(arc
		(start 334.154018 -229.58171)
		(mid 334.336269 -229.531326)
		(end 334.519778 -229.576884)
		(width 0.0889)
		(layer "In2.Cu")
		(net "M_C_CPU0_SA_DQ<7>")
	)
	(arc
		(start 328.135742 -226.664266)
		(mid 328.200257 -226.926485)
		(end 328.379074 -227.128832)
		(width 0.0889)
		(layer "In2.Cu")
		(net "M_C_CPU0_SA_DQ<7>")
	)
	(arc
		(start 336.042508 -229.576884)
		(mid 336.226016 -229.531359)
		(end 336.408268 -229.58171)
		(width 0.0889)
		(layer "In2.Cu")
		(net "M_C_CPU0_SA_DQ<7>")
	)
	(arc
		(start 336.97418 -229.58171)
		(mid 337.161124 -229.531421)
		(end 337.348068 -229.58171)
		(width 0.0889)
		(layer "In2.Cu")
		(net "M_C_CPU0_SA_DQ<7>")
	)
	(arc
		(start 342.988138 -229.58171)
		(mid 343.235998 -229.656793)
		(end 343.491312 -229.613206)
		(width 0.0889)
		(layer "In2.Cu")
		(net "M_C_CPU0_SA_DQ<7>")
	)
	(arc
		(start 339.80247 -229.576884)
		(mid 339.985978 -229.531359)
		(end 340.16823 -229.58171)
		(width 0.0889)
		(layer "In2.Cu")
		(net "M_C_CPU0_SA_DQ<7>")
	)
	(arc
		(start 326.571864 -223.931226)
		(mid 326.685386 -224.064483)
		(end 326.726042 -224.234756)
		(width 0.0889)
		(layer "In2.Cu")
		(net "M_C_CPU0_SA_DQ<7>")
	)
	(arc
		(start 335.468214 -229.58171)
		(mid 335.75117 -229.657887)
		(end 336.034126 -229.58171)
		(width 0.0889)
		(layer "In2.Cu")
		(net "M_C_CPU0_SA_DQ<7>")
	)
	(arc
		(start 339.228176 -229.58171)
		(mid 339.511132 -229.657887)
		(end 339.794088 -229.58171)
		(width 0.0889)
		(layer "In2.Cu")
		(net "M_C_CPU0_SA_DQ<7>")
	)
	(arc
		(start 328.44994 -227.16998)
		(mid 328.564616 -227.303314)
		(end 328.605896 -227.474272)
		(width 0.0889)
		(layer "In2.Cu")
		(net "M_C_CPU0_SA_DQ<7>")
	)
	(arc
		(start 329.828144 -229.58171)
		(mid 330.1111 -229.657887)
		(end 330.394056 -229.58171)
		(width 0.0889)
		(layer "In2.Cu")
		(net "M_C_CPU0_SA_DQ<7>")
	)
	(arc
		(start 332.274164 -229.58171)
		(mid 332.461108 -229.531421)
		(end 332.648052 -229.58171)
		(width 0.0889)
		(layer "In2.Cu")
		(net "M_C_CPU0_SA_DQ<7>")
	)
	(arc
		(start 328.91984 -227.979986)
		(mid 329.034516 -228.11332)
		(end 329.075796 -228.284278)
		(width 0.0889)
		(layer "In2.Cu")
		(net "M_C_CPU0_SA_DQ<7>")
	)
	(arc
		(start 327.97877 -226.359466)
		(mid 328.094197 -226.492842)
		(end 328.135742 -226.664266)
		(width 0.0889)
		(layer "In2.Cu")
		(net "M_C_CPU0_SA_DQ<7>")
	)
	(arc
		(start 342.613996 -229.58171)
		(mid 342.796247 -229.531326)
		(end 342.979756 -229.576884)
		(width 0.0889)
		(layer "In2.Cu")
		(net "M_C_CPU0_SA_DQ<7>")
	)
	(arc
		(start 340.734142 -229.58171)
		(mid 340.921086 -229.531421)
		(end 341.10803 -229.58171)
		(width 0.0889)
		(layer "In2.Cu")
		(net "M_C_CPU0_SA_DQ<7>")
	)
	(arc
		(start 326.256142 -223.425512)
		(mid 326.322468 -223.689831)
		(end 326.504808 -223.892364)
		(width 0.0889)
		(layer "In2.Cu")
		(net "M_C_CPU0_SA_DQ<7>")
	)
	(arc
		(start 340.16823 -229.58171)
		(mid 340.451186 -229.657887)
		(end 340.734142 -229.58171)
		(width 0.0889)
		(layer "In2.Cu")
		(net "M_C_CPU0_SA_DQ<7>")
	)
	(arc
		(start 331.342492 -229.576884)
		(mid 331.526 -229.531359)
		(end 331.708252 -229.58171)
		(width 0.0889)
		(layer "In2.Cu")
		(net "M_C_CPU0_SA_DQ<7>")
	)
	(arc
		(start 326.726042 -224.234756)
		(mid 326.788388 -224.493932)
		(end 326.962516 -224.695766)
		(width 0.0889)
		(layer "In2.Cu")
		(net "M_C_CPU0_SA_DQ<7>")
	)
	(arc
		(start 330.402438 -229.576884)
		(mid 330.585946 -229.531359)
		(end 330.768198 -229.58171)
		(width 0.0889)
		(layer "In2.Cu")
		(net "M_C_CPU0_SA_DQ<7>")
	)
	(arc
		(start 328.605896 -227.474272)
		(mid 328.671132 -227.737863)
		(end 328.851768 -227.940616)
		(width 0.0889)
		(layer "In2.Cu")
		(net "M_C_CPU0_SA_DQ<7>")
	)
	(arc
		(start 337.91398 -229.58171)
		(mid 338.096231 -229.531326)
		(end 338.27974 -229.576884)
		(width 0.0889)
		(layer "In2.Cu")
		(net "M_C_CPU0_SA_DQ<7>")
	)
	(arc
		(start 332.648052 -229.58171)
		(mid 332.931008 -229.657887)
		(end 333.213964 -229.58171)
		(width 0.0889)
		(layer "In2.Cu")
		(net "M_C_CPU0_SA_DQ<7>")
	)
	(arc
		(start 341.10803 -229.58171)
		(mid 341.390986 -229.657887)
		(end 341.673942 -229.58171)
		(width 0.0889)
		(layer "In2.Cu")
		(net "M_C_CPU0_SA_DQ<7>")
	)
	(arc
		(start 329.075796 -228.284278)
		(mid 329.140311 -228.546497)
		(end 329.319128 -228.748844)
		(width 0.0889)
		(layer "In2.Cu")
		(net "M_C_CPU0_SA_DQ<7>")
	)
	(arc
		(start 327.195688 -225.044254)
		(mid 327.261629 -225.309241)
		(end 327.4441 -225.512376)
		(width 0.0889)
		(layer "In2.Cu")
		(net "M_C_CPU0_SA_DQ<7>")
	)
	(segment
		(start 342.797892 -229.360222)
		(end 342.33104 -229.094284)
		(width 0.10668)
		(layer "F.Cu")
		(net "M_C_CPU0_SA_DQ<6>")
	)
	(segment
		(start 308.018942 -203.710032)
		(end 309.3339 -205.02499)
		(width 0.14478)
		(layer "In2.Cu")
		(net "M_C_CPU0_SA_DQ<6>")
	)
	(segment
		(start 290.950142 -204.56017)
		(end 297.589194 -204.56017)
		(width 0.14478)
		(layer "In2.Cu")
		(net "M_C_CPU0_SA_DQ<6>")
	)
	(segment
		(start 290.23056 -204.397102)
		(end 290.23056 -203.336398)
		(width 0.14478)
		(layer "In2.Cu")
		(net "M_C_CPU0_SA_DQ<6>")
	)
	(segment
		(start 332.744064 -228.771704)
		(end 332.752446 -228.766878)
		(width 0.0889)
		(layer "In2.Cu")
		(net "M_C_CPU0_SA_DQ<6>")
	)
	(segment
		(start 331.229716 -228.766878)
		(end 331.238098 -228.771704)
		(width 0.0889)
		(layer "In2.Cu")
		(net "M_C_CPU0_SA_DQ<6>")
	)
	(segment
		(start 327.478644 -223.911668)
		(end 327.508108 -223.928686)
		(width 0.0889)
		(layer "In2.Cu")
		(net "M_C_CPU0_SA_DQ<6>")
	)
	(segment
		(start 301.051722 -203.710032)
		(end 301.90186 -204.56017)
		(width 0.14478)
		(layer "In2.Cu")
		(net "M_C_CPU0_SA_DQ<6>")
	)
	(segment
		(start 340.629748 -228.766878)
		(end 340.63813 -228.771704)
		(width 0.0889)
		(layer "In2.Cu")
		(net "M_C_CPU0_SA_DQ<6>")
	)
	(segment
		(start 301.90186 -204.56017)
		(end 305.283108 -204.56017)
		(width 0.14478)
		(layer "In2.Cu")
		(net "M_C_CPU0_SA_DQ<6>")
	)
	(segment
		(start 329.789028 -227.938838)
		(end 329.828144 -227.961698)
		(width 0.0889)
		(layer "In2.Cu")
		(net "M_C_CPU0_SA_DQ<6>")
	)
	(segment
		(start 311.737248 -205.02499)
		(end 315.950854 -209.238596)
		(width 0.14478)
		(layer "In2.Cu")
		(net "M_C_CPU0_SA_DQ<6>")
	)
	(segment
		(start 305.283108 -204.56017)
		(end 306.133246 -203.710032)
		(width 0.14478)
		(layer "In2.Cu")
		(net "M_C_CPU0_SA_DQ<6>")
	)
	(segment
		(start 342.081104 -228.803454)
		(end 342.177116 -228.828854)
		(width 0.0889)
		(layer "In2.Cu")
		(net "M_C_CPU0_SA_DQ<6>")
	)
	(segment
		(start 315.950854 -209.238596)
		(end 315.950854 -209.869024)
		(width 0.14478)
		(layer "In2.Cu")
		(net "M_C_CPU0_SA_DQ<6>")
	)
	(segment
		(start 290.787074 -203.336398)
		(end 290.787074 -204.397102)
		(width 0.14478)
		(layer "In2.Cu")
		(net "M_C_CPU0_SA_DQ<6>")
	)
	(segment
		(start 315.950854 -209.869024)
		(end 325.292974 -219.211144)
		(width 0.14478)
		(layer "In2.Cu")
		(net "M_C_CPU0_SA_DQ<6>")
	)
	(segment
		(start 329.828144 -227.961698)
		(end 329.859894 -227.979986)
		(width 0.0889)
		(layer "In2.Cu")
		(net "M_C_CPU0_SA_DQ<6>")
	)
	(segment
		(start 328.88809 -226.341686)
		(end 328.91984 -226.359974)
		(width 0.0889)
		(layer "In2.Cu")
		(net "M_C_CPU0_SA_DQ<6>")
	)
	(segment
		(start 329.358244 -227.151692)
		(end 329.388724 -227.169472)
		(width 0.0889)
		(layer "In2.Cu")
		(net "M_C_CPU0_SA_DQ<6>")
	)
	(segment
		(start 341.204042 -228.771704)
		(end 341.212424 -228.766878)
		(width 0.0889)
		(layer "In2.Cu")
		(net "M_C_CPU0_SA_DQ<6>")
	)
	(segment
		(start 290.393628 -203.17333)
		(end 290.624006 -203.17333)
		(width 0.14478)
		(layer "In2.Cu")
		(net "M_C_CPU0_SA_DQ<6>")
	)
	(segment
		(start 309.3339 -205.02499)
		(end 311.737248 -205.02499)
		(width 0.14478)
		(layer "In2.Cu")
		(net "M_C_CPU0_SA_DQ<6>")
	)
	(segment
		(start 328.41819 -225.53168)
		(end 328.44994 -225.549968)
		(width 0.0889)
		(layer "In2.Cu")
		(net "M_C_CPU0_SA_DQ<6>")
	)
	(segment
		(start 327.438258 -223.888046)
		(end 327.478644 -223.911668)
		(width 0.0889)
		(layer "In2.Cu")
		(net "M_C_CPU0_SA_DQ<6>")
	)
	(segment
		(start 337.44408 -228.771704)
		(end 337.452462 -228.766878)
		(width 0.0889)
		(layer "In2.Cu")
		(net "M_C_CPU0_SA_DQ<6>")
	)
	(segment
		(start 336.869786 -228.766878)
		(end 336.878168 -228.771704)
		(width 0.0889)
		(layer "In2.Cu")
		(net "M_C_CPU0_SA_DQ<6>")
	)
	(segment
		(start 332.16977 -228.766878)
		(end 332.178152 -228.771704)
		(width 0.0889)
		(layer "In2.Cu")
		(net "M_C_CPU0_SA_DQ<6>")
	)
	(segment
		(start 290.787074 -204.397102)
		(end 290.950142 -204.56017)
		(width 0.14478)
		(layer "In2.Cu")
		(net "M_C_CPU0_SA_DQ<6>")
	)
	(segment
		(start 339.689694 -228.766878)
		(end 339.698076 -228.771704)
		(width 0.0889)
		(layer "In2.Cu")
		(net "M_C_CPU0_SA_DQ<6>")
	)
	(segment
		(start 290.23056 -203.336398)
		(end 290.393628 -203.17333)
		(width 0.14478)
		(layer "In2.Cu")
		(net "M_C_CPU0_SA_DQ<6>")
	)
	(segment
		(start 290.067492 -204.56017)
		(end 290.23056 -204.397102)
		(width 0.14478)
		(layer "In2.Cu")
		(net "M_C_CPU0_SA_DQ<6>")
	)
	(segment
		(start 325.292974 -219.211144)
		(end 325.292974 -221.10065)
		(width 0.14478)
		(layer "In2.Cu")
		(net "M_C_CPU0_SA_DQ<6>")
	)
	(segment
		(start 342.177116 -228.828854)
		(end 342.33104 -229.094284)
		(width 0.0889)
		(layer "In2.Cu")
		(net "M_C_CPU0_SA_DQ<6>")
	)
	(segment
		(start 327.94829 -224.721674)
		(end 327.97877 -224.739454)
		(width 0.0889)
		(layer "In2.Cu")
		(net "M_C_CPU0_SA_DQ<6>")
	)
	(segment
		(start 328.851768 -226.320604)
		(end 328.88809 -226.341686)
		(width 0.0889)
		(layer "In2.Cu")
		(net "M_C_CPU0_SA_DQ<6>")
	)
	(segment
		(start 327.008236 -223.101662)
		(end 327.041002 -223.120712)
		(width 0.0889)
		(layer "In2.Cu")
		(net "M_C_CPU0_SA_DQ<6>")
	)
	(segment
		(start 327.911968 -224.700592)
		(end 327.94829 -224.721674)
		(width 0.0889)
		(layer "In2.Cu")
		(net "M_C_CPU0_SA_DQ<6>")
	)
	(segment
		(start 288.180018 -204.134974)
		(end 288.605214 -204.56017)
		(width 0.14478)
		(layer "In2.Cu")
		(net "M_C_CPU0_SA_DQ<6>")
	)
	(segment
		(start 326.027034 -221.83471)
		(end 326.419972 -222.227648)
		(width 0.0889)
		(layer "In2.Cu")
		(net "M_C_CPU0_SA_DQ<6>")
	)
	(segment
		(start 306.133246 -203.710032)
		(end 308.018942 -203.710032)
		(width 0.14478)
		(layer "In2.Cu")
		(net "M_C_CPU0_SA_DQ<6>")
	)
	(segment
		(start 297.589194 -204.56017)
		(end 298.439332 -203.710032)
		(width 0.14478)
		(layer "In2.Cu")
		(net "M_C_CPU0_SA_DQ<6>")
	)
	(segment
		(start 335.929732 -228.766878)
		(end 335.938114 -228.771704)
		(width 0.0889)
		(layer "In2.Cu")
		(net "M_C_CPU0_SA_DQ<6>")
	)
	(segment
		(start 329.319128 -227.128832)
		(end 329.358244 -227.151692)
		(width 0.0889)
		(layer "In2.Cu")
		(net "M_C_CPU0_SA_DQ<6>")
	)
	(segment
		(start 288.605214 -204.56017)
		(end 290.067492 -204.56017)
		(width 0.14478)
		(layer "In2.Cu")
		(net "M_C_CPU0_SA_DQ<6>")
	)
	(segment
		(start 325.292974 -221.10065)
		(end 326.027034 -221.83471)
		(width 0.14478)
		(layer "In2.Cu")
		(net "M_C_CPU0_SA_DQ<6>")
	)
	(segment
		(start 328.379074 -225.50882)
		(end 328.41819 -225.53168)
		(width 0.0889)
		(layer "In2.Cu")
		(net "M_C_CPU0_SA_DQ<6>")
	)
	(segment
		(start 290.624006 -203.17333)
		(end 290.787074 -203.336398)
		(width 0.14478)
		(layer "In2.Cu")
		(net "M_C_CPU0_SA_DQ<6>")
	)
	(segment
		(start 330.261722 -228.750622)
		(end 330.298044 -228.771704)
		(width 0.0889)
		(layer "In2.Cu")
		(net "M_C_CPU0_SA_DQ<6>")
	)
	(segment
		(start 326.438514 -222.241872)
		(end 326.548242 -222.305372)
		(width 0.0889)
		(layer "In2.Cu")
		(net "M_C_CPU0_SA_DQ<6>")
	)
	(segment
		(start 298.439332 -203.710032)
		(end 301.051722 -203.710032)
		(width 0.14478)
		(layer "In2.Cu")
		(net "M_C_CPU0_SA_DQ<6>")
	)
	(segment
		(start 333.684118 -228.771704)
		(end 333.6925 -228.766878)
		(width 0.0889)
		(layer "In2.Cu")
		(net "M_C_CPU0_SA_DQ<6>")
	)
	(segment
		(start 326.973438 -223.081342)
		(end 327.008236 -223.101662)
		(width 0.0889)
		(layer "In2.Cu")
		(net "M_C_CPU0_SA_DQ<6>")
	)
	(arc
		(start 328.135742 -225.044254)
		(mid 328.200257 -225.306473)
		(end 328.379074 -225.50882)
		(width 0.0889)
		(layer "In2.Cu")
		(net "M_C_CPU0_SA_DQ<6>")
	)
	(arc
		(start 329.075796 -226.664266)
		(mid 329.140311 -226.926485)
		(end 329.319128 -227.128832)
		(width 0.0889)
		(layer "In2.Cu")
		(net "M_C_CPU0_SA_DQ<6>")
	)
	(arc
		(start 337.818222 -228.771704)
		(mid 338.101178 -228.847881)
		(end 338.384134 -228.771704)
		(width 0.0889)
		(layer "In2.Cu")
		(net "M_C_CPU0_SA_DQ<6>")
	)
	(arc
		(start 329.388724 -227.169472)
		(mid 329.504151 -227.302848)
		(end 329.545696 -227.474272)
		(width 0.0889)
		(layer "In2.Cu")
		(net "M_C_CPU0_SA_DQ<6>")
	)
	(arc
		(start 331.80401 -228.771704)
		(mid 331.986261 -228.721354)
		(end 332.16977 -228.766878)
		(width 0.0889)
		(layer "In2.Cu")
		(net "M_C_CPU0_SA_DQ<6>")
	)
	(arc
		(start 334.05826 -228.771704)
		(mid 334.341216 -228.847881)
		(end 334.624172 -228.771704)
		(width 0.0889)
		(layer "In2.Cu")
		(net "M_C_CPU0_SA_DQ<6>")
	)
	(arc
		(start 327.666096 -224.234248)
		(mid 327.731332 -224.497839)
		(end 327.911968 -224.700592)
		(width 0.0889)
		(layer "In2.Cu")
		(net "M_C_CPU0_SA_DQ<6>")
	)
	(arc
		(start 341.578184 -228.771704)
		(mid 341.825897 -228.846924)
		(end 342.081104 -228.803454)
		(width 0.0889)
		(layer "In2.Cu")
		(net "M_C_CPU0_SA_DQ<6>")
	)
	(arc
		(start 329.859894 -227.979986)
		(mid 329.97457 -228.11332)
		(end 330.01585 -228.284278)
		(width 0.0889)
		(layer "In2.Cu")
		(net "M_C_CPU0_SA_DQ<6>")
	)
	(arc
		(start 332.752446 -228.766878)
		(mid 332.935954 -228.721384)
		(end 333.118206 -228.771704)
		(width 0.0889)
		(layer "In2.Cu")
		(net "M_C_CPU0_SA_DQ<6>")
	)
	(arc
		(start 336.504026 -228.771704)
		(mid 336.686277 -228.721354)
		(end 336.869786 -228.766878)
		(width 0.0889)
		(layer "In2.Cu")
		(net "M_C_CPU0_SA_DQ<6>")
	)
	(arc
		(start 333.6925 -228.766878)
		(mid 333.876008 -228.721384)
		(end 334.05826 -228.771704)
		(width 0.0889)
		(layer "In2.Cu")
		(net "M_C_CPU0_SA_DQ<6>")
	)
	(arc
		(start 330.01585 -228.284278)
		(mid 330.081086 -228.547869)
		(end 330.261722 -228.750622)
		(width 0.0889)
		(layer "In2.Cu")
		(net "M_C_CPU0_SA_DQ<6>")
	)
	(arc
		(start 338.384134 -228.771704)
		(mid 338.571078 -228.721449)
		(end 338.758022 -228.771704)
		(width 0.0889)
		(layer "In2.Cu")
		(net "M_C_CPU0_SA_DQ<6>")
	)
	(arc
		(start 331.238098 -228.771704)
		(mid 331.521054 -228.847881)
		(end 331.80401 -228.771704)
		(width 0.0889)
		(layer "In2.Cu")
		(net "M_C_CPU0_SA_DQ<6>")
	)
	(arc
		(start 334.99806 -228.771704)
		(mid 335.281016 -228.847881)
		(end 335.563972 -228.771704)
		(width 0.0889)
		(layer "In2.Cu")
		(net "M_C_CPU0_SA_DQ<6>")
	)
	(arc
		(start 333.118206 -228.771704)
		(mid 333.401162 -228.847881)
		(end 333.684118 -228.771704)
		(width 0.0889)
		(layer "In2.Cu")
		(net "M_C_CPU0_SA_DQ<6>")
	)
	(arc
		(start 332.178152 -228.771704)
		(mid 332.461108 -228.847881)
		(end 332.744064 -228.771704)
		(width 0.0889)
		(layer "In2.Cu")
		(net "M_C_CPU0_SA_DQ<6>")
	)
	(arc
		(start 339.323934 -228.771704)
		(mid 339.506185 -228.721354)
		(end 339.689694 -228.766878)
		(width 0.0889)
		(layer "In2.Cu")
		(net "M_C_CPU0_SA_DQ<6>")
	)
	(arc
		(start 335.938114 -228.771704)
		(mid 336.22107 -228.847881)
		(end 336.504026 -228.771704)
		(width 0.0889)
		(layer "In2.Cu")
		(net "M_C_CPU0_SA_DQ<6>")
	)
	(arc
		(start 341.212424 -228.766878)
		(mid 341.395932 -228.721384)
		(end 341.578184 -228.771704)
		(width 0.0889)
		(layer "In2.Cu")
		(net "M_C_CPU0_SA_DQ<6>")
	)
	(arc
		(start 326.419972 -222.227648)
		(mid 326.428775 -222.235371)
		(end 326.438514 -222.241872)
		(width 0.0889)
		(layer "In2.Cu")
		(net "M_C_CPU0_SA_DQ<6>")
	)
	(arc
		(start 328.44994 -225.549968)
		(mid 328.564616 -225.683302)
		(end 328.605896 -225.85426)
		(width 0.0889)
		(layer "In2.Cu")
		(net "M_C_CPU0_SA_DQ<6>")
	)
	(arc
		(start 330.863956 -228.771704)
		(mid 331.046207 -228.721354)
		(end 331.229716 -228.766878)
		(width 0.0889)
		(layer "In2.Cu")
		(net "M_C_CPU0_SA_DQ<6>")
	)
	(arc
		(start 334.624172 -228.771704)
		(mid 334.811116 -228.721449)
		(end 334.99806 -228.771704)
		(width 0.0889)
		(layer "In2.Cu")
		(net "M_C_CPU0_SA_DQ<6>")
	)
	(arc
		(start 339.698076 -228.771704)
		(mid 339.981032 -228.847881)
		(end 340.263988 -228.771704)
		(width 0.0889)
		(layer "In2.Cu")
		(net "M_C_CPU0_SA_DQ<6>")
	)
	(arc
		(start 330.298044 -228.771704)
		(mid 330.581 -228.847881)
		(end 330.863956 -228.771704)
		(width 0.0889)
		(layer "In2.Cu")
		(net "M_C_CPU0_SA_DQ<6>")
	)
	(arc
		(start 340.263988 -228.771704)
		(mid 340.446239 -228.721354)
		(end 340.629748 -228.766878)
		(width 0.0889)
		(layer "In2.Cu")
		(net "M_C_CPU0_SA_DQ<6>")
	)
	(arc
		(start 340.63813 -228.771704)
		(mid 340.921086 -228.847881)
		(end 341.204042 -228.771704)
		(width 0.0889)
		(layer "In2.Cu")
		(net "M_C_CPU0_SA_DQ<6>")
	)
	(arc
		(start 327.508108 -223.928686)
		(mid 327.624289 -224.062245)
		(end 327.666096 -224.234248)
		(width 0.0889)
		(layer "In2.Cu")
		(net "M_C_CPU0_SA_DQ<6>")
	)
	(arc
		(start 338.758022 -228.771704)
		(mid 339.040978 -228.847881)
		(end 339.323934 -228.771704)
		(width 0.0889)
		(layer "In2.Cu")
		(net "M_C_CPU0_SA_DQ<6>")
	)
	(arc
		(start 329.545696 -227.474272)
		(mid 329.610211 -227.736491)
		(end 329.789028 -227.938838)
		(width 0.0889)
		(layer "In2.Cu")
		(net "M_C_CPU0_SA_DQ<6>")
	)
	(arc
		(start 328.91984 -226.359974)
		(mid 329.034516 -226.493308)
		(end 329.075796 -226.664266)
		(width 0.0889)
		(layer "In2.Cu")
		(net "M_C_CPU0_SA_DQ<6>")
	)
	(arc
		(start 327.041002 -223.120712)
		(mid 327.154931 -223.253859)
		(end 327.195942 -223.424242)
		(width 0.0889)
		(layer "In2.Cu")
		(net "M_C_CPU0_SA_DQ<6>")
	)
	(arc
		(start 335.563972 -228.771704)
		(mid 335.746223 -228.721354)
		(end 335.929732 -228.766878)
		(width 0.0889)
		(layer "In2.Cu")
		(net "M_C_CPU0_SA_DQ<6>")
	)
	(arc
		(start 326.548242 -222.305372)
		(mid 326.678611 -222.435975)
		(end 326.726296 -222.614236)
		(width 0.0889)
		(layer "In2.Cu")
		(net "M_C_CPU0_SA_DQ<6>")
	)
	(arc
		(start 327.195942 -223.424242)
		(mid 327.260235 -223.685847)
		(end 327.438258 -223.888046)
		(width 0.0889)
		(layer "In2.Cu")
		(net "M_C_CPU0_SA_DQ<6>")
	)
	(arc
		(start 326.726296 -222.614236)
		(mid 326.791897 -222.878455)
		(end 326.973438 -223.081342)
		(width 0.0889)
		(layer "In2.Cu")
		(net "M_C_CPU0_SA_DQ<6>")
	)
	(arc
		(start 336.878168 -228.771704)
		(mid 337.161124 -228.847881)
		(end 337.44408 -228.771704)
		(width 0.0889)
		(layer "In2.Cu")
		(net "M_C_CPU0_SA_DQ<6>")
	)
	(arc
		(start 337.452462 -228.766878)
		(mid 337.63597 -228.721384)
		(end 337.818222 -228.771704)
		(width 0.0889)
		(layer "In2.Cu")
		(net "M_C_CPU0_SA_DQ<6>")
	)
	(arc
		(start 327.97877 -224.739454)
		(mid 328.094197 -224.87283)
		(end 328.135742 -225.044254)
		(width 0.0889)
		(layer "In2.Cu")
		(net "M_C_CPU0_SA_DQ<6>")
	)
	(arc
		(start 328.605896 -225.85426)
		(mid 328.671132 -226.117851)
		(end 328.851768 -226.320604)
		(width 0.0889)
		(layer "In2.Cu")
		(net "M_C_CPU0_SA_DQ<6>")
	)
	(segment
		(start 343.737946 -229.360222)
		(end 343.271094 -229.094284)
		(width 0.10668)
		(layer "F.Cu")
		(net "M_C_CPU0_SA_DQ<5>")
	)
	(segment
		(start 305.093116 -205.410054)
		(end 304.57013 -205.410054)
		(width 0.14478)
		(layer "In2.Cu")
		(net "M_C_CPU0_SA_DQ<5>")
	)
	(segment
		(start 302.512222 -205.04531)
		(end 302.349154 -205.208378)
		(width 0.14478)
		(layer "In2.Cu")
		(net "M_C_CPU0_SA_DQ<5>")
	)
	(segment
		(start 343.271094 -229.094284)
		(end 343.425018 -229.359714)
		(width 0.0889)
		(layer "In2.Cu")
		(net "M_C_CPU0_SA_DQ<5>")
	)
	(segment
		(start 301.94123 -205.410054)
		(end 300.928278 -204.397102)
		(width 0.14478)
		(layer "In2.Cu")
		(net "M_C_CPU0_SA_DQ<5>")
	)
	(segment
		(start 328.083164 -226.1997)
		(end 328.044048 -226.17684)
		(width 0.0889)
		(layer "In2.Cu")
		(net "M_C_CPU0_SA_DQ<5>")
	)
	(segment
		(start 328.044048 -226.17684)
		(end 328.015854 -226.160584)
		(width 0.0889)
		(layer "In2.Cu")
		(net "M_C_CPU0_SA_DQ<5>")
	)
	(segment
		(start 324.833234 -221.284038)
		(end 324.833234 -219.403676)
		(width 0.14478)
		(layer "In2.Cu")
		(net "M_C_CPU0_SA_DQ<5>")
	)
	(segment
		(start 294.073326 -205.634082)
		(end 294.073326 -205.182978)
		(width 0.14478)
		(layer "In2.Cu")
		(net "M_C_CPU0_SA_DQ<5>")
	)
	(segment
		(start 335.938114 -229.41661)
		(end 335.929732 -229.421436)
		(width 0.0889)
		(layer "In2.Cu")
		(net "M_C_CPU0_SA_DQ<5>")
	)
	(segment
		(start 294.62984 -205.634082)
		(end 294.466772 -205.79715)
		(width 0.14478)
		(layer "In2.Cu")
		(net "M_C_CPU0_SA_DQ<5>")
	)
	(segment
		(start 296.32529 -205.246986)
		(end 296.162222 -205.410054)
		(width 0.14478)
		(layer "In2.Cu")
		(net "M_C_CPU0_SA_DQ<5>")
	)
	(segment
		(start 306.54244 -204.19187)
		(end 306.379372 -204.354938)
		(width 0.14478)
		(layer "In2.Cu")
		(net "M_C_CPU0_SA_DQ<5>")
	)
	(segment
		(start 306.935886 -204.397102)
		(end 306.935886 -204.354938)
		(width 0.14478)
		(layer "In2.Cu")
		(net "M_C_CPU0_SA_DQ<5>")
	)
	(segment
		(start 296.162222 -205.410054)
		(end 295.349422 -205.410054)
		(width 0.14478)
		(layer "In2.Cu")
		(net "M_C_CPU0_SA_DQ<5>")
	)
	(segment
		(start 295.023286 -205.01991)
		(end 294.792908 -205.01991)
		(width 0.14478)
		(layer "In2.Cu")
		(net "M_C_CPU0_SA_DQ<5>")
	)
	(segment
		(start 298.941236 -204.16647)
		(end 298.778168 -204.329538)
		(width 0.14478)
		(layer "In2.Cu")
		(net "M_C_CPU0_SA_DQ<5>")
	)
	(segment
		(start 315.463174 -210.033616)
		(end 315.463174 -209.416396)
		(width 0.14478)
		(layer "In2.Cu")
		(net "M_C_CPU0_SA_DQ<5>")
	)
	(segment
		(start 324.833234 -219.403676)
		(end 315.463174 -210.033616)
		(width 0.14478)
		(layer "In2.Cu")
		(net "M_C_CPU0_SA_DQ<5>")
	)
	(segment
		(start 292.902386 -205.800452)
		(end 292.757606 -205.655672)
		(width 0.14478)
		(layer "In2.Cu")
		(net "M_C_CPU0_SA_DQ<5>")
	)
	(segment
		(start 302.186086 -205.410054)
		(end 301.94123 -205.410054)
		(width 0.14478)
		(layer "In2.Cu")
		(net "M_C_CPU0_SA_DQ<5>")
	)
	(segment
		(start 298.6151 -204.56017)
		(end 298.234608 -204.56017)
		(width 0.14478)
		(layer "In2.Cu")
		(net "M_C_CPU0_SA_DQ<5>")
	)
	(segment
		(start 296.881804 -205.246986)
		(end 296.881804 -205.180438)
		(width 0.14478)
		(layer "In2.Cu")
		(net "M_C_CPU0_SA_DQ<5>")
	)
	(segment
		(start 342.152478 -229.421436)
		(end 342.144096 -229.41661)
		(width 0.0889)
		(layer "In2.Cu")
		(net "M_C_CPU0_SA_DQ<5>")
	)
	(segment
		(start 328.514202 -226.986846)
		(end 328.482452 -226.968558)
		(width 0.0889)
		(layer "In2.Cu")
		(net "M_C_CPU0_SA_DQ<5>")
	)
	(segment
		(start 294.466772 -205.79715)
		(end 294.236394 -205.79715)
		(width 0.14478)
		(layer "In2.Cu")
		(net "M_C_CPU0_SA_DQ<5>")
	)
	(segment
		(start 339.698076 -229.41661)
		(end 339.689694 -229.421436)
		(width 0.0889)
		(layer "In2.Cu")
		(net "M_C_CPU0_SA_DQ<5>")
	)
	(segment
		(start 300.928278 -204.397102)
		(end 300.928278 -204.332078)
		(width 0.14478)
		(layer "In2.Cu")
		(net "M_C_CPU0_SA_DQ<5>")
	)
	(segment
		(start 293.910258 -205.01991)
		(end 293.67988 -205.01991)
		(width 0.14478)
		(layer "In2.Cu")
		(net "M_C_CPU0_SA_DQ<5>")
	)
	(segment
		(start 292.757606 -205.655672)
		(end 292.757606 -205.462632)
		(width 0.14478)
		(layer "In2.Cu")
		(net "M_C_CPU0_SA_DQ<5>")
	)
	(segment
		(start 302.905668 -205.208378)
		(end 302.7426 -205.04531)
		(width 0.14478)
		(layer "In2.Cu")
		(net "M_C_CPU0_SA_DQ<5>")
	)
	(segment
		(start 326.19823 -222.957898)
		(end 326.164956 -222.938594)
		(width 0.0889)
		(layer "In2.Cu")
		(net "M_C_CPU0_SA_DQ<5>")
	)
	(segment
		(start 300.534832 -204.16901)
		(end 300.371764 -204.332078)
		(width 0.14478)
		(layer "In2.Cu")
		(net "M_C_CPU0_SA_DQ<5>")
	)
	(segment
		(start 292.757606 -205.462632)
		(end 292.280086 -204.985112)
		(width 0.14478)
		(layer "In2.Cu")
		(net "M_C_CPU0_SA_DQ<5>")
	)
	(segment
		(start 300.76521 -204.16901)
		(end 300.534832 -204.16901)
		(width 0.14478)
		(layer "In2.Cu")
		(net "M_C_CPU0_SA_DQ<5>")
	)
	(segment
		(start 298.778168 -204.397102)
		(end 298.6151 -204.56017)
		(width 0.14478)
		(layer "In2.Cu")
		(net "M_C_CPU0_SA_DQ<5>")
	)
	(segment
		(start 303.850548 -205.246986)
		(end 303.68748 -205.410054)
		(width 0.14478)
		(layer "In2.Cu")
		(net "M_C_CPU0_SA_DQ<5>")
	)
	(segment
		(start 305.943 -204.56017)
		(end 305.093116 -205.410054)
		(width 0.14478)
		(layer "In2.Cu")
		(net "M_C_CPU0_SA_DQ<5>")
	)
	(segment
		(start 294.62984 -205.182978)
		(end 294.62984 -205.634082)
		(width 0.14478)
		(layer "In2.Cu")
		(net "M_C_CPU0_SA_DQ<5>")
	)
	(segment
		(start 293.67988 -205.01991)
		(end 293.516812 -205.182978)
		(width 0.14478)
		(layer "In2.Cu")
		(net "M_C_CPU0_SA_DQ<5>")
	)
	(segment
		(start 327.147682 -224.582736)
		(end 327.104502 -224.55759)
		(width 0.0889)
		(layer "In2.Cu")
		(net "M_C_CPU0_SA_DQ<5>")
	)
	(segment
		(start 326.088248 -222.87992)
		(end 325.943214 -222.734886)
		(width 0.0889)
		(layer "In2.Cu")
		(net "M_C_CPU0_SA_DQ<5>")
	)
	(segment
		(start 296.881804 -205.180438)
		(end 296.718736 -205.01737)
		(width 0.14478)
		(layer "In2.Cu")
		(net "M_C_CPU0_SA_DQ<5>")
	)
	(segment
		(start 306.935886 -204.354938)
		(end 306.772818 -204.19187)
		(width 0.14478)
		(layer "In2.Cu")
		(net "M_C_CPU0_SA_DQ<5>")
	)
	(segment
		(start 332.752446 -229.421436)
		(end 332.744064 -229.41661)
		(width 0.0889)
		(layer "In2.Cu")
		(net "M_C_CPU0_SA_DQ<5>")
	)
	(segment
		(start 300.928278 -204.332078)
		(end 300.76521 -204.16901)
		(width 0.14478)
		(layer "In2.Cu")
		(net "M_C_CPU0_SA_DQ<5>")
	)
	(segment
		(start 293.516812 -205.637384)
		(end 293.353744 -205.800452)
		(width 0.14478)
		(layer "In2.Cu")
		(net "M_C_CPU0_SA_DQ<5>")
	)
	(segment
		(start 311.546748 -205.49997)
		(end 309.10911 -205.49997)
		(width 0.14478)
		(layer "In2.Cu")
		(net "M_C_CPU0_SA_DQ<5>")
	)
	(segment
		(start 306.216304 -204.56017)
		(end 305.943 -204.56017)
		(width 0.14478)
		(layer "In2.Cu")
		(net "M_C_CPU0_SA_DQ<5>")
	)
	(segment
		(start 296.718736 -205.01737)
		(end 296.488358 -205.01737)
		(width 0.14478)
		(layer "In2.Cu")
		(net "M_C_CPU0_SA_DQ<5>")
	)
	(segment
		(start 303.68748 -205.410054)
		(end 303.068736 -205.410054)
		(width 0.14478)
		(layer "In2.Cu")
		(net "M_C_CPU0_SA_DQ<5>")
	)
	(segment
		(start 298.778168 -204.329538)
		(end 298.778168 -204.397102)
		(width 0.14478)
		(layer "In2.Cu")
		(net "M_C_CPU0_SA_DQ<5>")
	)
	(segment
		(start 294.236394 -205.79715)
		(end 294.073326 -205.634082)
		(width 0.14478)
		(layer "In2.Cu")
		(net "M_C_CPU0_SA_DQ<5>")
	)
	(segment
		(start 331.238098 -229.41661)
		(end 331.229716 -229.421436)
		(width 0.0889)
		(layer "In2.Cu")
		(net "M_C_CPU0_SA_DQ<5>")
	)
	(segment
		(start 303.850548 -205.185518)
		(end 303.850548 -205.246986)
		(width 0.14478)
		(layer "In2.Cu")
		(net "M_C_CPU0_SA_DQ<5>")
	)
	(segment
		(start 303.068736 -205.410054)
		(end 302.905668 -205.246986)
		(width 0.14478)
		(layer "In2.Cu")
		(net "M_C_CPU0_SA_DQ<5>")
	)
	(segment
		(start 325.943214 -222.734886)
		(end 325.943214 -222.394018)
		(width 0.0889)
		(layer "In2.Cu")
		(net "M_C_CPU0_SA_DQ<5>")
	)
	(segment
		(start 299.171614 -204.16647)
		(end 298.941236 -204.16647)
		(width 0.14478)
		(layer "In2.Cu")
		(net "M_C_CPU0_SA_DQ<5>")
	)
	(segment
		(start 302.349154 -205.246986)
		(end 302.186086 -205.410054)
		(width 0.14478)
		(layer "In2.Cu")
		(net "M_C_CPU0_SA_DQ<5>")
	)
	(segment
		(start 308.16931 -204.56017)
		(end 307.098954 -204.56017)
		(width 0.14478)
		(layer "In2.Cu")
		(net "M_C_CPU0_SA_DQ<5>")
	)
	(segment
		(start 302.349154 -205.208378)
		(end 302.349154 -205.246986)
		(width 0.14478)
		(layer "In2.Cu")
		(net "M_C_CPU0_SA_DQ<5>")
	)
	(segment
		(start 304.013616 -205.02245)
		(end 303.850548 -205.185518)
		(width 0.14478)
		(layer "In2.Cu")
		(net "M_C_CPU0_SA_DQ<5>")
	)
	(segment
		(start 343.425018 -229.359714)
		(end 343.40292 -229.442772)
		(width 0.0889)
		(layer "In2.Cu")
		(net "M_C_CPU0_SA_DQ<5>")
	)
	(segment
		(start 295.186354 -205.182978)
		(end 295.023286 -205.01991)
		(width 0.14478)
		(layer "In2.Cu")
		(net "M_C_CPU0_SA_DQ<5>")
	)
	(segment
		(start 329.493118 -228.629718)
		(end 329.454002 -228.606858)
		(width 0.0889)
		(layer "In2.Cu")
		(net "M_C_CPU0_SA_DQ<5>")
	)
	(segment
		(start 333.6925 -229.421436)
		(end 333.684118 -229.41661)
		(width 0.0889)
		(layer "In2.Cu")
		(net "M_C_CPU0_SA_DQ<5>")
	)
	(segment
		(start 295.186354 -205.246986)
		(end 295.186354 -205.182978)
		(width 0.14478)
		(layer "In2.Cu")
		(net "M_C_CPU0_SA_DQ<5>")
	)
	(segment
		(start 299.334682 -204.329538)
		(end 299.171614 -204.16647)
		(width 0.14478)
		(layer "In2.Cu")
		(net "M_C_CPU0_SA_DQ<5>")
	)
	(segment
		(start 306.379372 -204.354938)
		(end 306.379372 -204.397102)
		(width 0.14478)
		(layer "In2.Cu")
		(net "M_C_CPU0_SA_DQ<5>")
	)
	(segment
		(start 304.407062 -205.246986)
		(end 304.407062 -205.185518)
		(width 0.14478)
		(layer "In2.Cu")
		(net "M_C_CPU0_SA_DQ<5>")
	)
	(segment
		(start 293.516812 -205.182978)
		(end 293.516812 -205.637384)
		(width 0.14478)
		(layer "In2.Cu")
		(net "M_C_CPU0_SA_DQ<5>")
	)
	(segment
		(start 306.379372 -204.397102)
		(end 306.216304 -204.56017)
		(width 0.14478)
		(layer "In2.Cu")
		(net "M_C_CPU0_SA_DQ<5>")
	)
	(segment
		(start 304.57013 -205.410054)
		(end 304.407062 -205.246986)
		(width 0.14478)
		(layer "In2.Cu")
		(net "M_C_CPU0_SA_DQ<5>")
	)
	(segment
		(start 340.63813 -229.41661)
		(end 340.629748 -229.421436)
		(width 0.0889)
		(layer "In2.Cu")
		(net "M_C_CPU0_SA_DQ<5>")
	)
	(segment
		(start 328.984102 -227.796852)
		(end 328.952352 -227.778564)
		(width 0.0889)
		(layer "In2.Cu")
		(net "M_C_CPU0_SA_DQ<5>")
	)
	(segment
		(start 329.454002 -228.606858)
		(end 329.423522 -228.589078)
		(width 0.0889)
		(layer "In2.Cu")
		(net "M_C_CPU0_SA_DQ<5>")
	)
	(segment
		(start 327.574148 -225.367088)
		(end 327.54443 -225.349816)
		(width 0.0889)
		(layer "In2.Cu")
		(net "M_C_CPU0_SA_DQ<5>")
	)
	(segment
		(start 299.49775 -204.56017)
		(end 299.334682 -204.397102)
		(width 0.14478)
		(layer "In2.Cu")
		(net "M_C_CPU0_SA_DQ<5>")
	)
	(segment
		(start 327.104502 -224.55759)
		(end 327.066402 -224.535492)
		(width 0.0889)
		(layer "In2.Cu")
		(net "M_C_CPU0_SA_DQ<5>")
	)
	(segment
		(start 293.353744 -205.800452)
		(end 292.902386 -205.800452)
		(width 0.14478)
		(layer "In2.Cu")
		(net "M_C_CPU0_SA_DQ<5>")
	)
	(segment
		(start 300.371764 -204.332078)
		(end 300.371764 -204.397102)
		(width 0.14478)
		(layer "In2.Cu")
		(net "M_C_CPU0_SA_DQ<5>")
	)
	(segment
		(start 298.234608 -204.56017)
		(end 297.384724 -205.410054)
		(width 0.14478)
		(layer "In2.Cu")
		(net "M_C_CPU0_SA_DQ<5>")
	)
	(segment
		(start 326.634094 -223.746822)
		(end 326.60717 -223.731328)
		(width 0.0889)
		(layer "In2.Cu")
		(net "M_C_CPU0_SA_DQ<5>")
	)
	(segment
		(start 306.772818 -204.19187)
		(end 306.54244 -204.19187)
		(width 0.14478)
		(layer "In2.Cu")
		(net "M_C_CPU0_SA_DQ<5>")
	)
	(segment
		(start 307.098954 -204.56017)
		(end 306.935886 -204.397102)
		(width 0.14478)
		(layer "In2.Cu")
		(net "M_C_CPU0_SA_DQ<5>")
	)
	(segment
		(start 297.044872 -205.410054)
		(end 296.881804 -205.246986)
		(width 0.14478)
		(layer "In2.Cu")
		(net "M_C_CPU0_SA_DQ<5>")
	)
	(segment
		(start 337.452462 -229.421436)
		(end 337.44408 -229.41661)
		(width 0.0889)
		(layer "In2.Cu")
		(net "M_C_CPU0_SA_DQ<5>")
	)
	(segment
		(start 332.178152 -229.41661)
		(end 332.16977 -229.421436)
		(width 0.0889)
		(layer "In2.Cu")
		(net "M_C_CPU0_SA_DQ<5>")
	)
	(segment
		(start 309.10911 -205.49997)
		(end 308.16931 -204.56017)
		(width 0.14478)
		(layer "In2.Cu")
		(net "M_C_CPU0_SA_DQ<5>")
	)
	(segment
		(start 302.905668 -205.246986)
		(end 302.905668 -205.208378)
		(width 0.14478)
		(layer "In2.Cu")
		(net "M_C_CPU0_SA_DQ<5>")
	)
	(segment
		(start 336.878168 -229.41661)
		(end 336.869786 -229.421436)
		(width 0.0889)
		(layer "In2.Cu")
		(net "M_C_CPU0_SA_DQ<5>")
	)
	(segment
		(start 300.371764 -204.397102)
		(end 300.208696 -204.56017)
		(width 0.14478)
		(layer "In2.Cu")
		(net "M_C_CPU0_SA_DQ<5>")
	)
	(segment
		(start 326.676004 -223.771206)
		(end 326.634094 -223.746822)
		(width 0.0889)
		(layer "In2.Cu")
		(net "M_C_CPU0_SA_DQ<5>")
	)
	(segment
		(start 315.463174 -209.416396)
		(end 311.546748 -205.49997)
		(width 0.14478)
		(layer "In2.Cu")
		(net "M_C_CPU0_SA_DQ<5>")
	)
	(segment
		(start 294.073326 -205.182978)
		(end 293.910258 -205.01991)
		(width 0.14478)
		(layer "In2.Cu")
		(net "M_C_CPU0_SA_DQ<5>")
	)
	(segment
		(start 341.212424 -229.421436)
		(end 341.204042 -229.41661)
		(width 0.0889)
		(layer "In2.Cu")
		(net "M_C_CPU0_SA_DQ<5>")
	)
	(segment
		(start 329.924156 -229.41661)
		(end 329.890628 -229.397052)
		(width 0.0889)
		(layer "In2.Cu")
		(net "M_C_CPU0_SA_DQ<5>")
	)
	(segment
		(start 296.488358 -205.01737)
		(end 296.32529 -205.180438)
		(width 0.14478)
		(layer "In2.Cu")
		(net "M_C_CPU0_SA_DQ<5>")
	)
	(segment
		(start 327.60539 -225.385122)
		(end 327.574148 -225.367088)
		(width 0.0889)
		(layer "In2.Cu")
		(net "M_C_CPU0_SA_DQ<5>")
	)
	(segment
		(start 296.32529 -205.180438)
		(end 296.32529 -205.246986)
		(width 0.14478)
		(layer "In2.Cu")
		(net "M_C_CPU0_SA_DQ<5>")
	)
	(segment
		(start 325.943214 -222.394018)
		(end 324.833234 -221.284038)
		(width 0.14478)
		(layer "In2.Cu")
		(net "M_C_CPU0_SA_DQ<5>")
	)
	(segment
		(start 302.7426 -205.04531)
		(end 302.512222 -205.04531)
		(width 0.14478)
		(layer "In2.Cu")
		(net "M_C_CPU0_SA_DQ<5>")
	)
	(segment
		(start 304.243994 -205.02245)
		(end 304.013616 -205.02245)
		(width 0.14478)
		(layer "In2.Cu")
		(net "M_C_CPU0_SA_DQ<5>")
	)
	(segment
		(start 295.349422 -205.410054)
		(end 295.186354 -205.246986)
		(width 0.14478)
		(layer "In2.Cu")
		(net "M_C_CPU0_SA_DQ<5>")
	)
	(segment
		(start 329.023218 -227.819712)
		(end 328.984102 -227.796852)
		(width 0.0889)
		(layer "In2.Cu")
		(net "M_C_CPU0_SA_DQ<5>")
	)
	(segment
		(start 304.407062 -205.185518)
		(end 304.243994 -205.02245)
		(width 0.14478)
		(layer "In2.Cu")
		(net "M_C_CPU0_SA_DQ<5>")
	)
	(segment
		(start 328.550524 -227.007928)
		(end 328.514202 -226.986846)
		(width 0.0889)
		(layer "In2.Cu")
		(net "M_C_CPU0_SA_DQ<5>")
	)
	(segment
		(start 300.208696 -204.56017)
		(end 299.49775 -204.56017)
		(width 0.14478)
		(layer "In2.Cu")
		(net "M_C_CPU0_SA_DQ<5>")
	)
	(segment
		(start 294.792908 -205.01991)
		(end 294.62984 -205.182978)
		(width 0.14478)
		(layer "In2.Cu")
		(net "M_C_CPU0_SA_DQ<5>")
	)
	(segment
		(start 299.334682 -204.397102)
		(end 299.334682 -204.329538)
		(width 0.14478)
		(layer "In2.Cu")
		(net "M_C_CPU0_SA_DQ<5>")
	)
	(segment
		(start 297.384724 -205.410054)
		(end 297.044872 -205.410054)
		(width 0.14478)
		(layer "In2.Cu")
		(net "M_C_CPU0_SA_DQ<5>")
	)
	(arc
		(start 328.952352 -227.778564)
		(mid 328.837676 -227.64523)
		(end 328.796396 -227.474272)
		(width 0.0889)
		(layer "In2.Cu")
		(net "M_C_CPU0_SA_DQ<5>")
	)
	(arc
		(start 343.08415 -229.41661)
		(mid 342.801194 -229.340433)
		(end 342.518238 -229.41661)
		(width 0.0889)
		(layer "In2.Cu")
		(net "M_C_CPU0_SA_DQ<5>")
	)
	(arc
		(start 327.066402 -224.535492)
		(mid 326.956126 -224.403048)
		(end 326.916796 -224.235264)
		(width 0.0889)
		(layer "In2.Cu")
		(net "M_C_CPU0_SA_DQ<5>")
	)
	(arc
		(start 335.929732 -229.421436)
		(mid 335.746224 -229.466961)
		(end 335.563972 -229.41661)
		(width 0.0889)
		(layer "In2.Cu")
		(net "M_C_CPU0_SA_DQ<5>")
	)
	(arc
		(start 341.204042 -229.41661)
		(mid 340.921086 -229.340433)
		(end 340.63813 -229.41661)
		(width 0.0889)
		(layer "In2.Cu")
		(net "M_C_CPU0_SA_DQ<5>")
	)
	(arc
		(start 338.384134 -229.41661)
		(mid 338.101178 -229.340433)
		(end 337.818222 -229.41661)
		(width 0.0889)
		(layer "In2.Cu")
		(net "M_C_CPU0_SA_DQ<5>")
	)
	(arc
		(start 336.504026 -229.41661)
		(mid 336.22107 -229.340433)
		(end 335.938114 -229.41661)
		(width 0.0889)
		(layer "In2.Cu")
		(net "M_C_CPU0_SA_DQ<5>")
	)
	(arc
		(start 327.85685 -225.854514)
		(mid 327.789849 -225.588363)
		(end 327.60539 -225.385122)
		(width 0.0889)
		(layer "In2.Cu")
		(net "M_C_CPU0_SA_DQ<5>")
	)
	(arc
		(start 326.916796 -224.235264)
		(mid 326.853239 -223.973739)
		(end 326.676004 -223.771206)
		(width 0.0889)
		(layer "In2.Cu")
		(net "M_C_CPU0_SA_DQ<5>")
	)
	(arc
		(start 333.118206 -229.41661)
		(mid 332.935955 -229.466994)
		(end 332.752446 -229.421436)
		(width 0.0889)
		(layer "In2.Cu")
		(net "M_C_CPU0_SA_DQ<5>")
	)
	(arc
		(start 326.446896 -223.42475)
		(mid 326.38057 -223.160431)
		(end 326.19823 -222.957898)
		(width 0.0889)
		(layer "In2.Cu")
		(net "M_C_CPU0_SA_DQ<5>")
	)
	(arc
		(start 329.890628 -229.397052)
		(mid 329.777221 -229.264163)
		(end 329.73645 -229.094284)
		(width 0.0889)
		(layer "In2.Cu")
		(net "M_C_CPU0_SA_DQ<5>")
	)
	(arc
		(start 333.684118 -229.41661)
		(mid 333.401162 -229.340433)
		(end 333.118206 -229.41661)
		(width 0.0889)
		(layer "In2.Cu")
		(net "M_C_CPU0_SA_DQ<5>")
	)
	(arc
		(start 329.26655 -228.284278)
		(mid 329.202035 -228.022059)
		(end 329.023218 -227.819712)
		(width 0.0889)
		(layer "In2.Cu")
		(net "M_C_CPU0_SA_DQ<5>")
	)
	(arc
		(start 327.386442 -225.044254)
		(mid 327.323215 -224.784447)
		(end 327.147682 -224.582736)
		(width 0.0889)
		(layer "In2.Cu")
		(net "M_C_CPU0_SA_DQ<5>")
	)
	(arc
		(start 342.144096 -229.41661)
		(mid 341.86114 -229.340433)
		(end 341.578184 -229.41661)
		(width 0.0889)
		(layer "In2.Cu")
		(net "M_C_CPU0_SA_DQ<5>")
	)
	(arc
		(start 332.16977 -229.421436)
		(mid 331.986262 -229.466961)
		(end 331.80401 -229.41661)
		(width 0.0889)
		(layer "In2.Cu")
		(net "M_C_CPU0_SA_DQ<5>")
	)
	(arc
		(start 329.73645 -229.094284)
		(mid 329.671935 -228.832065)
		(end 329.493118 -228.629718)
		(width 0.0889)
		(layer "In2.Cu")
		(net "M_C_CPU0_SA_DQ<5>")
	)
	(arc
		(start 329.423522 -228.589078)
		(mid 329.308095 -228.455702)
		(end 329.26655 -228.284278)
		(width 0.0889)
		(layer "In2.Cu")
		(net "M_C_CPU0_SA_DQ<5>")
	)
	(arc
		(start 334.05826 -229.41661)
		(mid 333.876009 -229.466994)
		(end 333.6925 -229.421436)
		(width 0.0889)
		(layer "In2.Cu")
		(net "M_C_CPU0_SA_DQ<5>")
	)
	(arc
		(start 326.60717 -223.731328)
		(mid 326.489436 -223.597683)
		(end 326.446896 -223.42475)
		(width 0.0889)
		(layer "In2.Cu")
		(net "M_C_CPU0_SA_DQ<5>")
	)
	(arc
		(start 341.578184 -229.41661)
		(mid 341.395933 -229.466994)
		(end 341.212424 -229.421436)
		(width 0.0889)
		(layer "In2.Cu")
		(net "M_C_CPU0_SA_DQ<5>")
	)
	(arc
		(start 328.015854 -226.160584)
		(mid 327.898975 -226.026956)
		(end 327.85685 -225.854514)
		(width 0.0889)
		(layer "In2.Cu")
		(net "M_C_CPU0_SA_DQ<5>")
	)
	(arc
		(start 328.326496 -226.664266)
		(mid 328.261981 -226.402047)
		(end 328.083164 -226.1997)
		(width 0.0889)
		(layer "In2.Cu")
		(net "M_C_CPU0_SA_DQ<5>")
	)
	(arc
		(start 330.863956 -229.41661)
		(mid 330.581 -229.340433)
		(end 330.298044 -229.41661)
		(width 0.0889)
		(layer "In2.Cu")
		(net "M_C_CPU0_SA_DQ<5>")
	)
	(arc
		(start 331.80401 -229.41661)
		(mid 331.521054 -229.340433)
		(end 331.238098 -229.41661)
		(width 0.0889)
		(layer "In2.Cu")
		(net "M_C_CPU0_SA_DQ<5>")
	)
	(arc
		(start 330.298044 -229.41661)
		(mid 330.1111 -229.466899)
		(end 329.924156 -229.41661)
		(width 0.0889)
		(layer "In2.Cu")
		(net "M_C_CPU0_SA_DQ<5>")
	)
	(arc
		(start 328.482452 -226.968558)
		(mid 328.367776 -226.835224)
		(end 328.326496 -226.664266)
		(width 0.0889)
		(layer "In2.Cu")
		(net "M_C_CPU0_SA_DQ<5>")
	)
	(arc
		(start 326.164956 -222.938594)
		(mid 326.124696 -222.911749)
		(end 326.088248 -222.87992)
		(width 0.0889)
		(layer "In2.Cu")
		(net "M_C_CPU0_SA_DQ<5>")
	)
	(arc
		(start 339.323934 -229.41661)
		(mid 339.040978 -229.340433)
		(end 338.758022 -229.41661)
		(width 0.0889)
		(layer "In2.Cu")
		(net "M_C_CPU0_SA_DQ<5>")
	)
	(arc
		(start 336.869786 -229.421436)
		(mid 336.686278 -229.466961)
		(end 336.504026 -229.41661)
		(width 0.0889)
		(layer "In2.Cu")
		(net "M_C_CPU0_SA_DQ<5>")
	)
	(arc
		(start 334.99806 -229.41661)
		(mid 334.811116 -229.466899)
		(end 334.624172 -229.41661)
		(width 0.0889)
		(layer "In2.Cu")
		(net "M_C_CPU0_SA_DQ<5>")
	)
	(arc
		(start 327.54443 -225.349816)
		(mid 327.428249 -225.216257)
		(end 327.386442 -225.044254)
		(width 0.0889)
		(layer "In2.Cu")
		(net "M_C_CPU0_SA_DQ<5>")
	)
	(arc
		(start 342.518238 -229.41661)
		(mid 342.335987 -229.466994)
		(end 342.152478 -229.421436)
		(width 0.0889)
		(layer "In2.Cu")
		(net "M_C_CPU0_SA_DQ<5>")
	)
	(arc
		(start 340.263988 -229.41661)
		(mid 339.981032 -229.340433)
		(end 339.698076 -229.41661)
		(width 0.0889)
		(layer "In2.Cu")
		(net "M_C_CPU0_SA_DQ<5>")
	)
	(arc
		(start 337.44408 -229.41661)
		(mid 337.161124 -229.340433)
		(end 336.878168 -229.41661)
		(width 0.0889)
		(layer "In2.Cu")
		(net "M_C_CPU0_SA_DQ<5>")
	)
	(arc
		(start 334.624172 -229.41661)
		(mid 334.341216 -229.340433)
		(end 334.05826 -229.41661)
		(width 0.0889)
		(layer "In2.Cu")
		(net "M_C_CPU0_SA_DQ<5>")
	)
	(arc
		(start 343.40292 -229.442772)
		(mid 343.240589 -229.465621)
		(end 343.08415 -229.41661)
		(width 0.0889)
		(layer "In2.Cu")
		(net "M_C_CPU0_SA_DQ<5>")
	)
	(arc
		(start 335.563972 -229.41661)
		(mid 335.281016 -229.340433)
		(end 334.99806 -229.41661)
		(width 0.0889)
		(layer "In2.Cu")
		(net "M_C_CPU0_SA_DQ<5>")
	)
	(arc
		(start 332.744064 -229.41661)
		(mid 332.461108 -229.340433)
		(end 332.178152 -229.41661)
		(width 0.0889)
		(layer "In2.Cu")
		(net "M_C_CPU0_SA_DQ<5>")
	)
	(arc
		(start 340.629748 -229.421436)
		(mid 340.44624 -229.466961)
		(end 340.263988 -229.41661)
		(width 0.0889)
		(layer "In2.Cu")
		(net "M_C_CPU0_SA_DQ<5>")
	)
	(arc
		(start 331.229716 -229.421436)
		(mid 331.046208 -229.466961)
		(end 330.863956 -229.41661)
		(width 0.0889)
		(layer "In2.Cu")
		(net "M_C_CPU0_SA_DQ<5>")
	)
	(arc
		(start 339.689694 -229.421436)
		(mid 339.506186 -229.466961)
		(end 339.323934 -229.41661)
		(width 0.0889)
		(layer "In2.Cu")
		(net "M_C_CPU0_SA_DQ<5>")
	)
	(arc
		(start 338.758022 -229.41661)
		(mid 338.571078 -229.466899)
		(end 338.384134 -229.41661)
		(width 0.0889)
		(layer "In2.Cu")
		(net "M_C_CPU0_SA_DQ<5>")
	)
	(arc
		(start 337.818222 -229.41661)
		(mid 337.635971 -229.466994)
		(end 337.452462 -229.421436)
		(width 0.0889)
		(layer "In2.Cu")
		(net "M_C_CPU0_SA_DQ<5>")
	)
	(arc
		(start 328.796396 -227.474272)
		(mid 328.73116 -227.210681)
		(end 328.550524 -227.007928)
		(width 0.0889)
		(layer "In2.Cu")
		(net "M_C_CPU0_SA_DQ<5>")
	)
	(segment
		(start 342.327992 -228.550216)
		(end 341.86114 -228.284278)
		(width 0.10668)
		(layer "F.Cu")
		(net "M_C_CPU0_SA_DQ<4>")
	)
	(segment
		(start 293.49319 -203.180696)
		(end 293.723568 -203.180696)
		(width 0.14478)
		(layer "In2.Cu")
		(net "M_C_CPU0_SA_DQ<4>")
	)
	(segment
		(start 309.889144 -204.144118)
		(end 310.052212 -203.98105)
		(width 0.14478)
		(layer "In2.Cu")
		(net "M_C_CPU0_SA_DQ<4>")
	)
	(segment
		(start 325.826374 -220.724222)
		(end 325.826374 -220.95079)
		(width 0.14478)
		(layer "In2.Cu")
		(net "M_C_CPU0_SA_DQ<4>")
	)
	(segment
		(start 317.217552 -210.06816)
		(end 317.448184 -210.06816)
		(width 0.14478)
		(layer "In2.Cu")
		(net "M_C_CPU0_SA_DQ<4>")
	)
	(segment
		(start 311.366154 -203.98105)
		(end 316.425834 -209.04073)
		(width 0.14478)
		(layer "In2.Cu")
		(net "M_C_CPU0_SA_DQ<4>")
	)
	(segment
		(start 327.574402 -223.746822)
		(end 327.612248 -223.768666)
		(width 0.0889)
		(layer "In2.Cu")
		(net "M_C_CPU0_SA_DQ<4>")
	)
	(segment
		(start 329.454002 -226.986846)
		(end 329.493118 -227.009706)
		(width 0.0889)
		(layer "In2.Cu")
		(net "M_C_CPU0_SA_DQ<4>")
	)
	(segment
		(start 304.19421 -203.710032)
		(end 304.357278 -203.8731)
		(width 0.14478)
		(layer "In2.Cu")
		(net "M_C_CPU0_SA_DQ<4>")
	)
	(segment
		(start 325.826374 -219.08897)
		(end 325.826374 -219.841572)
		(width 0.14478)
		(layer "In2.Cu")
		(net "M_C_CPU0_SA_DQ<4>")
	)
	(segment
		(start 297.498262 -203.710032)
		(end 297.794172 -203.710032)
		(width 0.14478)
		(layer "In2.Cu")
		(net "M_C_CPU0_SA_DQ<4>")
	)
	(segment
		(start 301.892716 -203.710032)
		(end 304.19421 -203.710032)
		(width 0.14478)
		(layer "In2.Cu")
		(net "M_C_CPU0_SA_DQ<4>")
	)
	(segment
		(start 316.425834 -209.04073)
		(end 316.425834 -209.68843)
		(width 0.14478)
		(layer "In2.Cu")
		(net "M_C_CPU0_SA_DQ<4>")
	)
	(segment
		(start 293.723568 -203.180696)
		(end 293.886636 -203.343764)
		(width 0.14478)
		(layer "In2.Cu")
		(net "M_C_CPU0_SA_DQ<4>")
	)
	(segment
		(start 334.519778 -228.611684)
		(end 334.52816 -228.606858)
		(width 0.0889)
		(layer "In2.Cu")
		(net "M_C_CPU0_SA_DQ<4>")
	)
	(segment
		(start 296.77868 -203.8731)
		(end 296.77868 -203.942442)
		(width 0.14478)
		(layer "In2.Cu")
		(net "M_C_CPU0_SA_DQ<4>")
	)
	(segment
		(start 317.914274 -210.946238)
		(end 318.004952 -210.85556)
		(width 0.14478)
		(layer "In2.Cu")
		(net "M_C_CPU0_SA_DQ<4>")
	)
	(segment
		(start 341.992712 -228.63302)
		(end 342.015064 -228.549708)
		(width 0.0889)
		(layer "In2.Cu")
		(net "M_C_CPU0_SA_DQ<4>")
	)
	(segment
		(start 297.335194 -203.8731)
		(end 297.498262 -203.710032)
		(width 0.14478)
		(layer "In2.Cu")
		(net "M_C_CPU0_SA_DQ<4>")
	)
	(segment
		(start 292.889686 -204.106272)
		(end 293.180262 -204.106272)
		(width 0.14478)
		(layer "In2.Cu")
		(net "M_C_CPU0_SA_DQ<4>")
	)
	(segment
		(start 301.052484 -202.8698)
		(end 301.892716 -203.710032)
		(width 0.14478)
		(layer "In2.Cu")
		(net "M_C_CPU0_SA_DQ<4>")
	)
	(segment
		(start 330.362306 -228.58857)
		(end 330.394056 -228.606858)
		(width 0.0889)
		(layer "In2.Cu")
		(net "M_C_CPU0_SA_DQ<4>")
	)
	(segment
		(start 297.335194 -203.942442)
		(end 297.335194 -203.8731)
		(width 0.14478)
		(layer "In2.Cu")
		(net "M_C_CPU0_SA_DQ<4>")
	)
	(segment
		(start 296.77868 -203.942442)
		(end 296.941748 -204.10551)
		(width 0.14478)
		(layer "In2.Cu")
		(net "M_C_CPU0_SA_DQ<4>")
	)
	(segment
		(start 292.744906 -203.74991)
		(end 292.744906 -203.961492)
		(width 0.14478)
		(layer "In2.Cu")
		(net "M_C_CPU0_SA_DQ<4>")
	)
	(segment
		(start 326.344534 -220.398086)
		(end 326.181466 -220.561154)
		(width 0.14478)
		(layer "In2.Cu")
		(net "M_C_CPU0_SA_DQ<4>")
	)
	(segment
		(start 296.941748 -204.10551)
		(end 297.172126 -204.10551)
		(width 0.14478)
		(layer "In2.Cu")
		(net "M_C_CPU0_SA_DQ<4>")
	)
	(segment
		(start 329.924156 -227.796852)
		(end 329.960478 -227.817934)
		(width 0.0889)
		(layer "In2.Cu")
		(net "M_C_CPU0_SA_DQ<4>")
	)
	(segment
		(start 333.579724 -228.611684)
		(end 333.588106 -228.606858)
		(width 0.0889)
		(layer "In2.Cu")
		(net "M_C_CPU0_SA_DQ<4>")
	)
	(segment
		(start 328.514202 -225.366834)
		(end 328.550524 -225.387916)
		(width 0.0889)
		(layer "In2.Cu")
		(net "M_C_CPU0_SA_DQ<4>")
	)
	(segment
		(start 304.357278 -203.8731)
		(end 304.357278 -203.939902)
		(width 0.14478)
		(layer "In2.Cu")
		(net "M_C_CPU0_SA_DQ<4>")
	)
	(segment
		(start 326.181466 -220.561154)
		(end 325.989442 -220.561154)
		(width 0.14478)
		(layer "In2.Cu")
		(net "M_C_CPU0_SA_DQ<4>")
	)
	(segment
		(start 311.002172 -204.144118)
		(end 311.16524 -203.98105)
		(width 0.14478)
		(layer "In2.Cu")
		(net "M_C_CPU0_SA_DQ<4>")
	)
	(segment
		(start 327.076054 -222.92056)
		(end 327.104248 -222.936816)
		(width 0.0889)
		(layer "In2.Cu")
		(net "M_C_CPU0_SA_DQ<4>")
	)
	(segment
		(start 319.095374 -212.127338)
		(end 319.095374 -212.35797)
		(width 0.14478)
		(layer "In2.Cu")
		(net "M_C_CPU0_SA_DQ<4>")
	)
	(segment
		(start 309.169562 -203.98105)
		(end 309.33263 -204.144118)
		(width 0.14478)
		(layer "In2.Cu")
		(net "M_C_CPU0_SA_DQ<4>")
	)
	(segment
		(start 305.439572 -203.710032)
		(end 306.289456 -202.860148)
		(width 0.14478)
		(layer "In2.Cu")
		(net "M_C_CPU0_SA_DQ<4>")
	)
	(segment
		(start 304.357278 -203.939902)
		(end 304.520346 -204.10297)
		(width 0.14478)
		(layer "In2.Cu")
		(net "M_C_CPU0_SA_DQ<4>")
	)
	(segment
		(start 308.880002 -203.83627)
		(end 309.024782 -203.98105)
		(width 0.14478)
		(layer "In2.Cu")
		(net "M_C_CPU0_SA_DQ<4>")
	)
	(segment
		(start 292.744906 -203.961492)
		(end 292.889686 -204.106272)
		(width 0.14478)
		(layer "In2.Cu")
		(net "M_C_CPU0_SA_DQ<4>")
	)
	(segment
		(start 311.16524 -203.98105)
		(end 311.366154 -203.98105)
		(width 0.14478)
		(layer "In2.Cu")
		(net "M_C_CPU0_SA_DQ<4>")
	)
	(segment
		(start 304.913792 -203.8731)
		(end 305.07686 -203.710032)
		(width 0.14478)
		(layer "In2.Cu")
		(net "M_C_CPU0_SA_DQ<4>")
	)
	(segment
		(start 318.307974 -211.339938)
		(end 318.307974 -211.57057)
		(width 0.14478)
		(layer "In2.Cu")
		(net "M_C_CPU0_SA_DQ<4>")
	)
	(segment
		(start 329.892406 -227.778564)
		(end 329.924156 -227.796852)
		(width 0.0889)
		(layer "In2.Cu")
		(net "M_C_CPU0_SA_DQ<4>")
	)
	(segment
		(start 325.989442 -220.00464)
		(end 326.181466 -220.00464)
		(width 0.14478)
		(layer "In2.Cu")
		(net "M_C_CPU0_SA_DQ<4>")
	)
	(segment
		(start 297.794172 -203.710032)
		(end 298.634404 -202.8698)
		(width 0.14478)
		(layer "In2.Cu")
		(net "M_C_CPU0_SA_DQ<4>")
	)
	(segment
		(start 293.886636 -203.58608)
		(end 294.122856 -203.8223)
		(width 0.14478)
		(layer "In2.Cu")
		(net "M_C_CPU0_SA_DQ<4>")
	)
	(segment
		(start 326.344534 -220.167708)
		(end 326.344534 -220.398086)
		(width 0.14478)
		(layer "In2.Cu")
		(net "M_C_CPU0_SA_DQ<4>")
	)
	(segment
		(start 325.989442 -220.561154)
		(end 325.826374 -220.724222)
		(width 0.14478)
		(layer "In2.Cu")
		(net "M_C_CPU0_SA_DQ<4>")
	)
	(segment
		(start 308.178454 -202.860148)
		(end 308.880002 -203.561696)
		(width 0.14478)
		(layer "In2.Cu")
		(net "M_C_CPU0_SA_DQ<4>")
	)
	(segment
		(start 294.516302 -204.10043)
		(end 294.67937 -203.937362)
		(width 0.14478)
		(layer "In2.Cu")
		(net "M_C_CPU0_SA_DQ<4>")
	)
	(segment
		(start 294.67937 -203.937362)
		(end 294.67937 -203.8731)
		(width 0.14478)
		(layer "In2.Cu")
		(net "M_C_CPU0_SA_DQ<4>")
	)
	(segment
		(start 318.398652 -211.018628)
		(end 318.398652 -211.24926)
		(width 0.14478)
		(layer "In2.Cu")
		(net "M_C_CPU0_SA_DQ<4>")
	)
	(segment
		(start 296.625264 -203.719684)
		(end 296.77868 -203.8731)
		(width 0.14478)
		(layer "In2.Cu")
		(net "M_C_CPU0_SA_DQ<4>")
	)
	(segment
		(start 328.482452 -225.348546)
		(end 328.514202 -225.366834)
		(width 0.0889)
		(layer "In2.Cu")
		(net "M_C_CPU0_SA_DQ<4>")
	)
	(segment
		(start 330.394056 -228.606858)
		(end 330.402438 -228.611684)
		(width 0.0889)
		(layer "In2.Cu")
		(net "M_C_CPU0_SA_DQ<4>")
	)
	(segment
		(start 309.33263 -204.144118)
		(end 309.33263 -204.267562)
		(width 0.14478)
		(layer "In2.Cu")
		(net "M_C_CPU0_SA_DQ<4>")
	)
	(segment
		(start 310.445658 -204.144118)
		(end 310.445658 -204.412342)
		(width 0.14478)
		(layer "In2.Cu")
		(net "M_C_CPU0_SA_DQ<4>")
	)
	(segment
		(start 318.307974 -211.57057)
		(end 318.471042 -211.733638)
		(width 0.14478)
		(layer "In2.Cu")
		(net "M_C_CPU0_SA_DQ<4>")
	)
	(segment
		(start 319.095374 -212.35797)
		(end 325.826374 -219.08897)
		(width 0.14478)
		(layer "In2.Cu")
		(net "M_C_CPU0_SA_DQ<4>")
	)
	(segment
		(start 310.839104 -204.57541)
		(end 311.002172 -204.412342)
		(width 0.14478)
		(layer "In2.Cu")
		(net "M_C_CPU0_SA_DQ<4>")
	)
	(segment
		(start 326.634348 -222.126556)
		(end 326.670924 -222.147892)
		(width 0.0889)
		(layer "In2.Cu")
		(net "M_C_CPU0_SA_DQ<4>")
	)
	(segment
		(start 304.913792 -203.939902)
		(end 304.913792 -203.8731)
		(width 0.14478)
		(layer "In2.Cu")
		(net "M_C_CPU0_SA_DQ<4>")
	)
	(segment
		(start 317.683642 -210.946238)
		(end 317.914274 -210.946238)
		(width 0.14478)
		(layer "In2.Cu")
		(net "M_C_CPU0_SA_DQ<4>")
	)
	(segment
		(start 319.186052 -212.03666)
		(end 319.095374 -212.127338)
		(width 0.14478)
		(layer "In2.Cu")
		(net "M_C_CPU0_SA_DQ<4>")
	)
	(segment
		(start 294.122856 -203.937362)
		(end 294.285924 -204.10043)
		(width 0.14478)
		(layer "In2.Cu")
		(net "M_C_CPU0_SA_DQ<4>")
	)
	(segment
		(start 310.608726 -204.57541)
		(end 310.839104 -204.57541)
		(width 0.14478)
		(layer "In2.Cu")
		(net "M_C_CPU0_SA_DQ<4>")
	)
	(segment
		(start 294.67937 -203.8731)
		(end 294.832786 -203.719684)
		(width 0.14478)
		(layer "In2.Cu")
		(net "M_C_CPU0_SA_DQ<4>")
	)
	(segment
		(start 304.750724 -204.10297)
		(end 304.913792 -203.939902)
		(width 0.14478)
		(layer "In2.Cu")
		(net "M_C_CPU0_SA_DQ<4>")
	)
	(segment
		(start 310.28259 -203.98105)
		(end 310.445658 -204.144118)
		(width 0.14478)
		(layer "In2.Cu")
		(net "M_C_CPU0_SA_DQ<4>")
	)
	(segment
		(start 328.015854 -224.540572)
		(end 328.044048 -224.556828)
		(width 0.0889)
		(layer "In2.Cu")
		(net "M_C_CPU0_SA_DQ<4>")
	)
	(segment
		(start 317.448184 -210.06816)
		(end 317.611252 -210.231228)
		(width 0.14478)
		(layer "In2.Cu")
		(net "M_C_CPU0_SA_DQ<4>")
	)
	(segment
		(start 342.015064 -228.549708)
		(end 341.86114 -228.284278)
		(width 0.0889)
		(layer "In2.Cu")
		(net "M_C_CPU0_SA_DQ<4>")
	)
	(segment
		(start 309.889144 -204.267562)
		(end 309.889144 -204.144118)
		(width 0.14478)
		(layer "In2.Cu")
		(net "M_C_CPU0_SA_DQ<4>")
	)
	(segment
		(start 335.094072 -228.606858)
		(end 335.102454 -228.611684)
		(width 0.0889)
		(layer "In2.Cu")
		(net "M_C_CPU0_SA_DQ<4>")
	)
	(segment
		(start 309.726076 -204.43063)
		(end 309.889144 -204.267562)
		(width 0.14478)
		(layer "In2.Cu")
		(net "M_C_CPU0_SA_DQ<4>")
	)
	(segment
		(start 310.052212 -203.98105)
		(end 310.28259 -203.98105)
		(width 0.14478)
		(layer "In2.Cu")
		(net "M_C_CPU0_SA_DQ<4>")
	)
	(segment
		(start 319.186052 -211.806028)
		(end 319.186052 -212.03666)
		(width 0.14478)
		(layer "In2.Cu")
		(net "M_C_CPU0_SA_DQ<4>")
	)
	(segment
		(start 305.07686 -203.710032)
		(end 305.439572 -203.710032)
		(width 0.14478)
		(layer "In2.Cu")
		(net "M_C_CPU0_SA_DQ<4>")
	)
	(segment
		(start 327.104248 -222.936816)
		(end 327.14184 -222.95866)
		(width 0.0889)
		(layer "In2.Cu")
		(net "M_C_CPU0_SA_DQ<4>")
	)
	(segment
		(start 317.520574 -210.552538)
		(end 317.520574 -210.78317)
		(width 0.14478)
		(layer "In2.Cu")
		(net "M_C_CPU0_SA_DQ<4>")
	)
	(segment
		(start 317.611252 -210.46186)
		(end 317.520574 -210.552538)
		(width 0.14478)
		(layer "In2.Cu")
		(net "M_C_CPU0_SA_DQ<4>")
	)
	(segment
		(start 339.794088 -228.606858)
		(end 339.80247 -228.611684)
		(width 0.0889)
		(layer "In2.Cu")
		(net "M_C_CPU0_SA_DQ<4>")
	)
	(segment
		(start 316.425834 -209.68843)
		(end 316.896242 -210.158838)
		(width 0.14478)
		(layer "In2.Cu")
		(net "M_C_CPU0_SA_DQ<4>")
	)
	(segment
		(start 308.880002 -203.561696)
		(end 308.880002 -203.83627)
		(width 0.14478)
		(layer "In2.Cu")
		(net "M_C_CPU0_SA_DQ<4>")
	)
	(segment
		(start 293.886636 -203.343764)
		(end 293.886636 -203.58608)
		(width 0.14478)
		(layer "In2.Cu")
		(net "M_C_CPU0_SA_DQ<4>")
	)
	(segment
		(start 318.471042 -211.733638)
		(end 318.701674 -211.733638)
		(width 0.14478)
		(layer "In2.Cu")
		(net "M_C_CPU0_SA_DQ<4>")
	)
	(segment
		(start 294.285924 -204.10043)
		(end 294.516302 -204.10043)
		(width 0.14478)
		(layer "In2.Cu")
		(net "M_C_CPU0_SA_DQ<4>")
	)
	(segment
		(start 328.952352 -226.158552)
		(end 328.984102 -226.17684)
		(width 0.0889)
		(layer "In2.Cu")
		(net "M_C_CPU0_SA_DQ<4>")
	)
	(segment
		(start 294.122856 -203.8223)
		(end 294.122856 -203.937362)
		(width 0.14478)
		(layer "In2.Cu")
		(net "M_C_CPU0_SA_DQ<4>")
	)
	(segment
		(start 309.33263 -204.267562)
		(end 309.495698 -204.43063)
		(width 0.14478)
		(layer "In2.Cu")
		(net "M_C_CPU0_SA_DQ<4>")
	)
	(segment
		(start 292.280086 -203.28509)
		(end 292.744906 -203.74991)
		(width 0.14478)
		(layer "In2.Cu")
		(net "M_C_CPU0_SA_DQ<4>")
	)
	(segment
		(start 309.024782 -203.98105)
		(end 309.169562 -203.98105)
		(width 0.14478)
		(layer "In2.Cu")
		(net "M_C_CPU0_SA_DQ<4>")
	)
	(segment
		(start 316.896242 -210.158838)
		(end 317.126874 -210.158838)
		(width 0.14478)
		(layer "In2.Cu")
		(net "M_C_CPU0_SA_DQ<4>")
	)
	(segment
		(start 318.792352 -211.64296)
		(end 319.022984 -211.64296)
		(width 0.14478)
		(layer "In2.Cu")
		(net "M_C_CPU0_SA_DQ<4>")
	)
	(segment
		(start 297.172126 -204.10551)
		(end 297.335194 -203.942442)
		(width 0.14478)
		(layer "In2.Cu")
		(net "M_C_CPU0_SA_DQ<4>")
	)
	(segment
		(start 318.701674 -211.733638)
		(end 318.792352 -211.64296)
		(width 0.14478)
		(layer "In2.Cu")
		(net "M_C_CPU0_SA_DQ<4>")
	)
	(segment
		(start 317.520574 -210.78317)
		(end 317.683642 -210.946238)
		(width 0.14478)
		(layer "In2.Cu")
		(net "M_C_CPU0_SA_DQ<4>")
	)
	(segment
		(start 304.520346 -204.10297)
		(end 304.750724 -204.10297)
		(width 0.14478)
		(layer "In2.Cu")
		(net "M_C_CPU0_SA_DQ<4>")
	)
	(segment
		(start 318.235584 -210.85556)
		(end 318.398652 -211.018628)
		(width 0.14478)
		(layer "In2.Cu")
		(net "M_C_CPU0_SA_DQ<4>")
	)
	(segment
		(start 331.33411 -228.606858)
		(end 331.342492 -228.611684)
		(width 0.0889)
		(layer "In2.Cu")
		(net "M_C_CPU0_SA_DQ<4>")
	)
	(segment
		(start 328.044048 -224.556828)
		(end 328.083164 -224.579688)
		(width 0.0889)
		(layer "In2.Cu")
		(net "M_C_CPU0_SA_DQ<4>")
	)
	(segment
		(start 293.330122 -203.343764)
		(end 293.49319 -203.180696)
		(width 0.14478)
		(layer "In2.Cu")
		(net "M_C_CPU0_SA_DQ<4>")
	)
	(segment
		(start 326.181466 -220.00464)
		(end 326.344534 -220.167708)
		(width 0.14478)
		(layer "In2.Cu")
		(net "M_C_CPU0_SA_DQ<4>")
	)
	(segment
		(start 317.611252 -210.231228)
		(end 317.611252 -210.46186)
		(width 0.14478)
		(layer "In2.Cu")
		(net "M_C_CPU0_SA_DQ<4>")
	)
	(segment
		(start 338.27974 -228.611684)
		(end 338.288122 -228.606858)
		(width 0.0889)
		(layer "In2.Cu")
		(net "M_C_CPU0_SA_DQ<4>")
	)
	(segment
		(start 319.022984 -211.64296)
		(end 319.186052 -211.806028)
		(width 0.14478)
		(layer "In2.Cu")
		(net "M_C_CPU0_SA_DQ<4>")
	)
	(segment
		(start 338.854034 -228.606858)
		(end 338.862416 -228.611684)
		(width 0.0889)
		(layer "In2.Cu")
		(net "M_C_CPU0_SA_DQ<4>")
	)
	(segment
		(start 293.180262 -204.106272)
		(end 293.330122 -203.956412)
		(width 0.14478)
		(layer "In2.Cu")
		(net "M_C_CPU0_SA_DQ<4>")
	)
	(segment
		(start 325.826374 -219.841572)
		(end 325.989442 -220.00464)
		(width 0.14478)
		(layer "In2.Cu")
		(net "M_C_CPU0_SA_DQ<4>")
	)
	(segment
		(start 336.034126 -228.606858)
		(end 336.042508 -228.611684)
		(width 0.0889)
		(layer "In2.Cu")
		(net "M_C_CPU0_SA_DQ<4>")
	)
	(segment
		(start 294.832786 -203.719684)
		(end 296.625264 -203.719684)
		(width 0.14478)
		(layer "In2.Cu")
		(net "M_C_CPU0_SA_DQ<4>")
	)
	(segment
		(start 327.54062 -223.727264)
		(end 327.574402 -223.746822)
		(width 0.0889)
		(layer "In2.Cu")
		(net "M_C_CPU0_SA_DQ<4>")
	)
	(segment
		(start 310.445658 -204.412342)
		(end 310.608726 -204.57541)
		(width 0.14478)
		(layer "In2.Cu")
		(net "M_C_CPU0_SA_DQ<4>")
	)
	(segment
		(start 318.398652 -211.24926)
		(end 318.307974 -211.339938)
		(width 0.14478)
		(layer "In2.Cu")
		(net "M_C_CPU0_SA_DQ<4>")
	)
	(segment
		(start 318.004952 -210.85556)
		(end 318.235584 -210.85556)
		(width 0.14478)
		(layer "In2.Cu")
		(net "M_C_CPU0_SA_DQ<4>")
	)
	(segment
		(start 317.126874 -210.158838)
		(end 317.217552 -210.06816)
		(width 0.14478)
		(layer "In2.Cu")
		(net "M_C_CPU0_SA_DQ<4>")
	)
	(segment
		(start 329.423522 -226.969066)
		(end 329.454002 -226.986846)
		(width 0.0889)
		(layer "In2.Cu")
		(net "M_C_CPU0_SA_DQ<4>")
	)
	(segment
		(start 293.330122 -203.956412)
		(end 293.330122 -203.343764)
		(width 0.14478)
		(layer "In2.Cu")
		(net "M_C_CPU0_SA_DQ<4>")
	)
	(segment
		(start 306.289456 -202.860148)
		(end 308.178454 -202.860148)
		(width 0.14478)
		(layer "In2.Cu")
		(net "M_C_CPU0_SA_DQ<4>")
	)
	(segment
		(start 328.984102 -226.17684)
		(end 329.023218 -226.1997)
		(width 0.0889)
		(layer "In2.Cu")
		(net "M_C_CPU0_SA_DQ<4>")
	)
	(segment
		(start 325.826374 -220.95079)
		(end 326.452738 -221.577154)
		(width 0.14478)
		(layer "In2.Cu")
		(net "M_C_CPU0_SA_DQ<4>")
	)
	(segment
		(start 309.495698 -204.43063)
		(end 309.726076 -204.43063)
		(width 0.14478)
		(layer "In2.Cu")
		(net "M_C_CPU0_SA_DQ<4>")
	)
	(segment
		(start 326.452738 -221.577154)
		(end 326.452738 -221.815152)
		(width 0.0889)
		(layer "In2.Cu")
		(net "M_C_CPU0_SA_DQ<4>")
	)
	(segment
		(start 311.002172 -204.412342)
		(end 311.002172 -204.144118)
		(width 0.14478)
		(layer "In2.Cu")
		(net "M_C_CPU0_SA_DQ<4>")
	)
	(segment
		(start 298.634404 -202.8698)
		(end 301.052484 -202.8698)
		(width 0.14478)
		(layer "In2.Cu")
		(net "M_C_CPU0_SA_DQ<4>")
	)
	(arc
		(start 329.023218 -226.1997)
		(mid 329.202031 -226.40205)
		(end 329.26655 -226.664266)
		(width 0.0889)
		(layer "In2.Cu")
		(net "M_C_CPU0_SA_DQ<4>")
	)
	(arc
		(start 338.288122 -228.606858)
		(mid 338.571078 -228.530681)
		(end 338.854034 -228.606858)
		(width 0.0889)
		(layer "In2.Cu")
		(net "M_C_CPU0_SA_DQ<4>")
	)
	(arc
		(start 335.468214 -228.606858)
		(mid 335.75117 -228.530681)
		(end 336.034126 -228.606858)
		(width 0.0889)
		(layer "In2.Cu")
		(net "M_C_CPU0_SA_DQ<4>")
	)
	(arc
		(start 341.10803 -228.606858)
		(mid 341.390986 -228.530681)
		(end 341.673942 -228.606858)
		(width 0.0889)
		(layer "In2.Cu")
		(net "M_C_CPU0_SA_DQ<4>")
	)
	(arc
		(start 326.452738 -221.815152)
		(mid 326.479942 -221.951915)
		(end 326.557386 -222.067882)
		(width 0.0889)
		(layer "In2.Cu")
		(net "M_C_CPU0_SA_DQ<4>")
	)
	(arc
		(start 332.274164 -228.606858)
		(mid 332.461108 -228.657113)
		(end 332.648052 -228.606858)
		(width 0.0889)
		(layer "In2.Cu")
		(net "M_C_CPU0_SA_DQ<4>")
	)
	(arc
		(start 336.408268 -228.606858)
		(mid 336.691224 -228.530681)
		(end 336.97418 -228.606858)
		(width 0.0889)
		(layer "In2.Cu")
		(net "M_C_CPU0_SA_DQ<4>")
	)
	(arc
		(start 339.228176 -228.606858)
		(mid 339.511132 -228.530681)
		(end 339.794088 -228.606858)
		(width 0.0889)
		(layer "In2.Cu")
		(net "M_C_CPU0_SA_DQ<4>")
	)
	(arc
		(start 326.670924 -222.147892)
		(mid 326.851733 -222.350585)
		(end 326.91705 -222.614236)
		(width 0.0889)
		(layer "In2.Cu")
		(net "M_C_CPU0_SA_DQ<4>")
	)
	(arc
		(start 334.52816 -228.606858)
		(mid 334.811116 -228.530681)
		(end 335.094072 -228.606858)
		(width 0.0889)
		(layer "In2.Cu")
		(net "M_C_CPU0_SA_DQ<4>")
	)
	(arc
		(start 328.550524 -225.387916)
		(mid 328.731176 -225.590661)
		(end 328.796396 -225.85426)
		(width 0.0889)
		(layer "In2.Cu")
		(net "M_C_CPU0_SA_DQ<4>")
	)
	(arc
		(start 330.402438 -228.611684)
		(mid 330.585946 -228.657178)
		(end 330.768198 -228.606858)
		(width 0.0889)
		(layer "In2.Cu")
		(net "M_C_CPU0_SA_DQ<4>")
	)
	(arc
		(start 337.91398 -228.606858)
		(mid 338.096231 -228.657208)
		(end 338.27974 -228.611684)
		(width 0.0889)
		(layer "In2.Cu")
		(net "M_C_CPU0_SA_DQ<4>")
	)
	(arc
		(start 340.734142 -228.606858)
		(mid 340.921086 -228.657113)
		(end 341.10803 -228.606858)
		(width 0.0889)
		(layer "In2.Cu")
		(net "M_C_CPU0_SA_DQ<4>")
	)
	(arc
		(start 333.588106 -228.606858)
		(mid 333.871062 -228.530681)
		(end 334.154018 -228.606858)
		(width 0.0889)
		(layer "In2.Cu")
		(net "M_C_CPU0_SA_DQ<4>")
	)
	(arc
		(start 338.862416 -228.611684)
		(mid 339.045924 -228.657178)
		(end 339.228176 -228.606858)
		(width 0.0889)
		(layer "In2.Cu")
		(net "M_C_CPU0_SA_DQ<4>")
	)
	(arc
		(start 329.493118 -227.009706)
		(mid 329.671931 -227.212056)
		(end 329.73645 -227.474272)
		(width 0.0889)
		(layer "In2.Cu")
		(net "M_C_CPU0_SA_DQ<4>")
	)
	(arc
		(start 328.083164 -224.579688)
		(mid 328.261977 -224.782038)
		(end 328.326496 -225.044254)
		(width 0.0889)
		(layer "In2.Cu")
		(net "M_C_CPU0_SA_DQ<4>")
	)
	(arc
		(start 329.73645 -227.474272)
		(mid 329.777705 -227.645243)
		(end 329.892406 -227.778564)
		(width 0.0889)
		(layer "In2.Cu")
		(net "M_C_CPU0_SA_DQ<4>")
	)
	(arc
		(start 334.154018 -228.606858)
		(mid 334.336269 -228.657208)
		(end 334.519778 -228.611684)
		(width 0.0889)
		(layer "In2.Cu")
		(net "M_C_CPU0_SA_DQ<4>")
	)
	(arc
		(start 328.326496 -225.044254)
		(mid 328.367751 -225.215225)
		(end 328.482452 -225.348546)
		(width 0.0889)
		(layer "In2.Cu")
		(net "M_C_CPU0_SA_DQ<4>")
	)
	(arc
		(start 340.16823 -228.606858)
		(mid 340.451186 -228.530681)
		(end 340.734142 -228.606858)
		(width 0.0889)
		(layer "In2.Cu")
		(net "M_C_CPU0_SA_DQ<4>")
	)
	(arc
		(start 327.612248 -223.768666)
		(mid 327.791977 -223.971286)
		(end 327.85685 -224.234248)
		(width 0.0889)
		(layer "In2.Cu")
		(net "M_C_CPU0_SA_DQ<4>")
	)
	(arc
		(start 326.91705 -222.614236)
		(mid 326.959163 -222.78681)
		(end 327.076054 -222.92056)
		(width 0.0889)
		(layer "In2.Cu")
		(net "M_C_CPU0_SA_DQ<4>")
	)
	(arc
		(start 341.673942 -228.606858)
		(mid 341.83038 -228.655829)
		(end 341.992712 -228.63302)
		(width 0.0889)
		(layer "In2.Cu")
		(net "M_C_CPU0_SA_DQ<4>")
	)
	(arc
		(start 333.213964 -228.606858)
		(mid 333.396215 -228.657208)
		(end 333.579724 -228.611684)
		(width 0.0889)
		(layer "In2.Cu")
		(net "M_C_CPU0_SA_DQ<4>")
	)
	(arc
		(start 329.960478 -227.817934)
		(mid 330.14113 -228.020679)
		(end 330.20635 -228.284278)
		(width 0.0889)
		(layer "In2.Cu")
		(net "M_C_CPU0_SA_DQ<4>")
	)
	(arc
		(start 336.97418 -228.606858)
		(mid 337.161124 -228.657113)
		(end 337.348068 -228.606858)
		(width 0.0889)
		(layer "In2.Cu")
		(net "M_C_CPU0_SA_DQ<4>")
	)
	(arc
		(start 327.85685 -224.234248)
		(mid 327.898963 -224.406822)
		(end 328.015854 -224.540572)
		(width 0.0889)
		(layer "In2.Cu")
		(net "M_C_CPU0_SA_DQ<4>")
	)
	(arc
		(start 330.768198 -228.606858)
		(mid 331.051154 -228.530681)
		(end 331.33411 -228.606858)
		(width 0.0889)
		(layer "In2.Cu")
		(net "M_C_CPU0_SA_DQ<4>")
	)
	(arc
		(start 332.648052 -228.606858)
		(mid 332.931008 -228.530681)
		(end 333.213964 -228.606858)
		(width 0.0889)
		(layer "In2.Cu")
		(net "M_C_CPU0_SA_DQ<4>")
	)
	(arc
		(start 327.386442 -223.424242)
		(mid 327.4272 -223.59424)
		(end 327.54062 -223.727264)
		(width 0.0889)
		(layer "In2.Cu")
		(net "M_C_CPU0_SA_DQ<4>")
	)
	(arc
		(start 339.80247 -228.611684)
		(mid 339.985978 -228.657178)
		(end 340.16823 -228.606858)
		(width 0.0889)
		(layer "In2.Cu")
		(net "M_C_CPU0_SA_DQ<4>")
	)
	(arc
		(start 328.796396 -225.85426)
		(mid 328.837651 -226.025231)
		(end 328.952352 -226.158552)
		(width 0.0889)
		(layer "In2.Cu")
		(net "M_C_CPU0_SA_DQ<4>")
	)
	(arc
		(start 330.20635 -228.284278)
		(mid 330.247605 -228.455249)
		(end 330.362306 -228.58857)
		(width 0.0889)
		(layer "In2.Cu")
		(net "M_C_CPU0_SA_DQ<4>")
	)
	(arc
		(start 335.102454 -228.611684)
		(mid 335.285962 -228.657178)
		(end 335.468214 -228.606858)
		(width 0.0889)
		(layer "In2.Cu")
		(net "M_C_CPU0_SA_DQ<4>")
	)
	(arc
		(start 331.342492 -228.611684)
		(mid 331.526 -228.657178)
		(end 331.708252 -228.606858)
		(width 0.0889)
		(layer "In2.Cu")
		(net "M_C_CPU0_SA_DQ<4>")
	)
	(arc
		(start 329.26655 -226.664266)
		(mid 329.308099 -226.835688)
		(end 329.423522 -226.969066)
		(width 0.0889)
		(layer "In2.Cu")
		(net "M_C_CPU0_SA_DQ<4>")
	)
	(arc
		(start 326.557386 -222.067882)
		(mid 326.593942 -222.099746)
		(end 326.634348 -222.126556)
		(width 0.0889)
		(layer "In2.Cu")
		(net "M_C_CPU0_SA_DQ<4>")
	)
	(arc
		(start 331.708252 -228.606858)
		(mid 331.991208 -228.530681)
		(end 332.274164 -228.606858)
		(width 0.0889)
		(layer "In2.Cu")
		(net "M_C_CPU0_SA_DQ<4>")
	)
	(arc
		(start 327.14184 -222.95866)
		(mid 327.321569 -223.16128)
		(end 327.386442 -223.424242)
		(width 0.0889)
		(layer "In2.Cu")
		(net "M_C_CPU0_SA_DQ<4>")
	)
	(arc
		(start 337.348068 -228.606858)
		(mid 337.631024 -228.530681)
		(end 337.91398 -228.606858)
		(width 0.0889)
		(layer "In2.Cu")
		(net "M_C_CPU0_SA_DQ<4>")
	)
	(arc
		(start 336.042508 -228.611684)
		(mid 336.226016 -228.657178)
		(end 336.408268 -228.606858)
		(width 0.0889)
		(layer "In2.Cu")
		(net "M_C_CPU0_SA_DQ<4>")
	)
	(segment
		(start 344.207846 -226.930204)
		(end 343.740994 -226.664266)
		(width 0.10668)
		(layer "F.Cu")
		(net "M_C_CPU0_SA_DQ<3>")
	)
	(segment
		(start 329.071986 -221.96933)
		(end 329.071986 -221.21495)
		(width 0.0889)
		(layer "In2.Cu")
		(net "M_C_CPU0_SA_DQ<3>")
	)
	(segment
		(start 321.892422 -210.054444)
		(end 320.828162 -210.054444)
		(width 0.14478)
		(layer "In2.Cu")
		(net "M_C_CPU0_SA_DQ<3>")
	)
	(segment
		(start 329.071986 -221.21495)
		(end 329.071986 -218.973908)
		(width 0.14478)
		(layer "In2.Cu")
		(net "M_C_CPU0_SA_DQ<3>")
	)
	(segment
		(start 342.048084 -226.341686)
		(end 342.039702 -226.33686)
		(width 0.0889)
		(layer "In2.Cu")
		(net "M_C_CPU0_SA_DQ<3>")
	)
	(segment
		(start 338.862416 -226.33686)
		(end 338.854034 -226.341686)
		(width 0.0889)
		(layer "In2.Cu")
		(net "M_C_CPU0_SA_DQ<3>")
	)
	(segment
		(start 329.545696 -222.44304)
		(end 329.071986 -221.96933)
		(width 0.0889)
		(layer "In2.Cu")
		(net "M_C_CPU0_SA_DQ<3>")
	)
	(segment
		(start 331.708252 -226.341686)
		(end 331.669136 -226.318826)
		(width 0.0889)
		(layer "In2.Cu")
		(net "M_C_CPU0_SA_DQ<3>")
	)
	(segment
		(start 333.588106 -226.341686)
		(end 333.579724 -226.33686)
		(width 0.0889)
		(layer "In2.Cu")
		(net "M_C_CPU0_SA_DQ<3>")
	)
	(segment
		(start 329.545696 -222.614236)
		(end 329.545696 -222.44304)
		(width 0.0889)
		(layer "In2.Cu")
		(net "M_C_CPU0_SA_DQ<3>")
	)
	(segment
		(start 336.042508 -226.33686)
		(end 336.034126 -226.341686)
		(width 0.0889)
		(layer "In2.Cu")
		(net "M_C_CPU0_SA_DQ<3>")
	)
	(segment
		(start 338.288122 -226.341686)
		(end 338.27974 -226.33686)
		(width 0.0889)
		(layer "In2.Cu")
		(net "M_C_CPU0_SA_DQ<3>")
	)
	(segment
		(start 310.22417 -199.450452)
		(end 290.58743 -199.450452)
		(width 0.14478)
		(layer "In2.Cu")
		(net "M_C_CPU0_SA_DQ<3>")
	)
	(segment
		(start 289.714432 -199.460104)
		(end 288.60496 -199.460104)
		(width 0.14478)
		(layer "In2.Cu")
		(net "M_C_CPU0_SA_DQ<3>")
	)
	(segment
		(start 339.80247 -226.33686)
		(end 339.794088 -226.341686)
		(width 0.0889)
		(layer "In2.Cu")
		(net "M_C_CPU0_SA_DQ<3>")
	)
	(segment
		(start 330.798678 -224.739454)
		(end 330.768198 -224.721674)
		(width 0.0889)
		(layer "In2.Cu")
		(net "M_C_CPU0_SA_DQ<3>")
	)
	(segment
		(start 324.08876 -213.990682)
		(end 324.08876 -212.250782)
		(width 0.14478)
		(layer "In2.Cu")
		(net "M_C_CPU0_SA_DQ<3>")
	)
	(segment
		(start 330.768198 -224.721674)
		(end 330.729082 -224.698814)
		(width 0.0889)
		(layer "In2.Cu")
		(net "M_C_CPU0_SA_DQ<3>")
	)
	(segment
		(start 290.434014 -199.297036)
		(end 290.434014 -198.99884)
		(width 0.14478)
		(layer "In2.Cu")
		(net "M_C_CPU0_SA_DQ<3>")
	)
	(segment
		(start 320.828162 -210.054444)
		(end 310.22417 -199.450452)
		(width 0.14478)
		(layer "In2.Cu")
		(net "M_C_CPU0_SA_DQ<3>")
	)
	(segment
		(start 329.071986 -218.973908)
		(end 324.08876 -213.990682)
		(width 0.14478)
		(layer "In2.Cu")
		(net "M_C_CPU0_SA_DQ<3>")
	)
	(segment
		(start 288.60496 -199.460104)
		(end 288.180018 -199.885046)
		(width 0.14478)
		(layer "In2.Cu")
		(net "M_C_CPU0_SA_DQ<3>")
	)
	(segment
		(start 331.238098 -225.53168)
		(end 331.198982 -225.50882)
		(width 0.0889)
		(layer "In2.Cu")
		(net "M_C_CPU0_SA_DQ<3>")
	)
	(segment
		(start 289.8775 -198.99884)
		(end 289.8775 -199.297036)
		(width 0.14478)
		(layer "In2.Cu")
		(net "M_C_CPU0_SA_DQ<3>")
	)
	(segment
		(start 334.52816 -226.341686)
		(end 334.519778 -226.33686)
		(width 0.0889)
		(layer "In2.Cu")
		(net "M_C_CPU0_SA_DQ<3>")
	)
	(segment
		(start 330.329794 -223.929956)
		(end 330.298044 -223.911668)
		(width 0.0889)
		(layer "In2.Cu")
		(net "M_C_CPU0_SA_DQ<3>")
	)
	(segment
		(start 290.434014 -198.99884)
		(end 290.270946 -198.835772)
		(width 0.14478)
		(layer "In2.Cu")
		(net "M_C_CPU0_SA_DQ<3>")
	)
	(segment
		(start 324.08876 -212.250782)
		(end 321.892422 -210.054444)
		(width 0.14478)
		(layer "In2.Cu")
		(net "M_C_CPU0_SA_DQ<3>")
	)
	(segment
		(start 343.740994 -226.664266)
		(end 343.58707 -226.398836)
		(width 0.0889)
		(layer "In2.Cu")
		(net "M_C_CPU0_SA_DQ<3>")
	)
	(segment
		(start 290.58743 -199.450452)
		(end 290.434014 -199.297036)
		(width 0.14478)
		(layer "In2.Cu")
		(net "M_C_CPU0_SA_DQ<3>")
	)
	(segment
		(start 329.828144 -223.101662)
		(end 329.789028 -223.078802)
		(width 0.0889)
		(layer "In2.Cu")
		(net "M_C_CPU0_SA_DQ<3>")
	)
	(segment
		(start 343.58707 -226.398836)
		(end 343.491058 -226.373436)
		(width 0.0889)
		(layer "In2.Cu")
		(net "M_C_CPU0_SA_DQ<3>")
	)
	(segment
		(start 330.298044 -223.911668)
		(end 330.261722 -223.890586)
		(width 0.0889)
		(layer "In2.Cu")
		(net "M_C_CPU0_SA_DQ<3>")
	)
	(segment
		(start 289.8775 -199.297036)
		(end 289.714432 -199.460104)
		(width 0.14478)
		(layer "In2.Cu")
		(net "M_C_CPU0_SA_DQ<3>")
	)
	(segment
		(start 290.040568 -198.835772)
		(end 289.8775 -198.99884)
		(width 0.14478)
		(layer "In2.Cu")
		(net "M_C_CPU0_SA_DQ<3>")
	)
	(segment
		(start 290.270946 -198.835772)
		(end 290.040568 -198.835772)
		(width 0.14478)
		(layer "In2.Cu")
		(net "M_C_CPU0_SA_DQ<3>")
	)
	(segment
		(start 342.988138 -226.341686)
		(end 342.979756 -226.33686)
		(width 0.0889)
		(layer "In2.Cu")
		(net "M_C_CPU0_SA_DQ<3>")
	)
	(segment
		(start 335.102454 -226.33686)
		(end 335.094072 -226.341686)
		(width 0.0889)
		(layer "In2.Cu")
		(net "M_C_CPU0_SA_DQ<3>")
	)
	(segment
		(start 329.859894 -223.11995)
		(end 329.828144 -223.101662)
		(width 0.0889)
		(layer "In2.Cu")
		(net "M_C_CPU0_SA_DQ<3>")
	)
	(segment
		(start 331.269848 -225.549968)
		(end 331.238098 -225.53168)
		(width 0.0889)
		(layer "In2.Cu")
		(net "M_C_CPU0_SA_DQ<3>")
	)
	(arc
		(start 333.213964 -226.341686)
		(mid 332.931008 -226.417863)
		(end 332.648052 -226.341686)
		(width 0.0889)
		(layer "In2.Cu")
		(net "M_C_CPU0_SA_DQ<3>")
	)
	(arc
		(start 331.198982 -225.50882)
		(mid 331.020169 -225.30647)
		(end 330.95565 -225.044254)
		(width 0.0889)
		(layer "In2.Cu")
		(net "M_C_CPU0_SA_DQ<3>")
	)
	(arc
		(start 341.673942 -226.341686)
		(mid 341.390986 -226.417863)
		(end 341.10803 -226.341686)
		(width 0.0889)
		(layer "In2.Cu")
		(net "M_C_CPU0_SA_DQ<3>")
	)
	(arc
		(start 329.789028 -223.078802)
		(mid 329.610215 -222.876452)
		(end 329.545696 -222.614236)
		(width 0.0889)
		(layer "In2.Cu")
		(net "M_C_CPU0_SA_DQ<3>")
	)
	(arc
		(start 333.579724 -226.33686)
		(mid 333.396216 -226.291366)
		(end 333.213964 -226.341686)
		(width 0.0889)
		(layer "In2.Cu")
		(net "M_C_CPU0_SA_DQ<3>")
	)
	(arc
		(start 337.91398 -226.341686)
		(mid 337.631024 -226.417863)
		(end 337.348068 -226.341686)
		(width 0.0889)
		(layer "In2.Cu")
		(net "M_C_CPU0_SA_DQ<3>")
	)
	(arc
		(start 342.613996 -226.341686)
		(mid 342.33104 -226.417863)
		(end 342.048084 -226.341686)
		(width 0.0889)
		(layer "In2.Cu")
		(net "M_C_CPU0_SA_DQ<3>")
	)
	(arc
		(start 336.97418 -226.341686)
		(mid 336.691224 -226.417863)
		(end 336.408268 -226.341686)
		(width 0.0889)
		(layer "In2.Cu")
		(net "M_C_CPU0_SA_DQ<3>")
	)
	(arc
		(start 335.094072 -226.341686)
		(mid 334.811116 -226.417863)
		(end 334.52816 -226.341686)
		(width 0.0889)
		(layer "In2.Cu")
		(net "M_C_CPU0_SA_DQ<3>")
	)
	(arc
		(start 341.10803 -226.341686)
		(mid 340.921086 -226.291431)
		(end 340.734142 -226.341686)
		(width 0.0889)
		(layer "In2.Cu")
		(net "M_C_CPU0_SA_DQ<3>")
	)
	(arc
		(start 337.348068 -226.341686)
		(mid 337.161124 -226.291431)
		(end 336.97418 -226.341686)
		(width 0.0889)
		(layer "In2.Cu")
		(net "M_C_CPU0_SA_DQ<3>")
	)
	(arc
		(start 335.468214 -226.341686)
		(mid 335.285963 -226.291336)
		(end 335.102454 -226.33686)
		(width 0.0889)
		(layer "In2.Cu")
		(net "M_C_CPU0_SA_DQ<3>")
	)
	(arc
		(start 336.034126 -226.341686)
		(mid 335.75117 -226.417863)
		(end 335.468214 -226.341686)
		(width 0.0889)
		(layer "In2.Cu")
		(net "M_C_CPU0_SA_DQ<3>")
	)
	(arc
		(start 332.648052 -226.341686)
		(mid 332.461108 -226.291431)
		(end 332.274164 -226.341686)
		(width 0.0889)
		(layer "In2.Cu")
		(net "M_C_CPU0_SA_DQ<3>")
	)
	(arc
		(start 331.669136 -226.318826)
		(mid 331.490323 -226.116476)
		(end 331.425804 -225.85426)
		(width 0.0889)
		(layer "In2.Cu")
		(net "M_C_CPU0_SA_DQ<3>")
	)
	(arc
		(start 331.425804 -225.85426)
		(mid 331.384549 -225.683289)
		(end 331.269848 -225.549968)
		(width 0.0889)
		(layer "In2.Cu")
		(net "M_C_CPU0_SA_DQ<3>")
	)
	(arc
		(start 338.854034 -226.341686)
		(mid 338.571078 -226.417863)
		(end 338.288122 -226.341686)
		(width 0.0889)
		(layer "In2.Cu")
		(net "M_C_CPU0_SA_DQ<3>")
	)
	(arc
		(start 340.734142 -226.341686)
		(mid 340.451186 -226.417863)
		(end 340.16823 -226.341686)
		(width 0.0889)
		(layer "In2.Cu")
		(net "M_C_CPU0_SA_DQ<3>")
	)
	(arc
		(start 330.261722 -223.890586)
		(mid 330.08107 -223.687841)
		(end 330.01585 -223.424242)
		(width 0.0889)
		(layer "In2.Cu")
		(net "M_C_CPU0_SA_DQ<3>")
	)
	(arc
		(start 338.27974 -226.33686)
		(mid 338.096232 -226.291366)
		(end 337.91398 -226.341686)
		(width 0.0889)
		(layer "In2.Cu")
		(net "M_C_CPU0_SA_DQ<3>")
	)
	(arc
		(start 336.408268 -226.341686)
		(mid 336.226017 -226.291336)
		(end 336.042508 -226.33686)
		(width 0.0889)
		(layer "In2.Cu")
		(net "M_C_CPU0_SA_DQ<3>")
	)
	(arc
		(start 340.16823 -226.341686)
		(mid 339.985979 -226.291336)
		(end 339.80247 -226.33686)
		(width 0.0889)
		(layer "In2.Cu")
		(net "M_C_CPU0_SA_DQ<3>")
	)
	(arc
		(start 339.228176 -226.341686)
		(mid 339.045925 -226.291336)
		(end 338.862416 -226.33686)
		(width 0.0889)
		(layer "In2.Cu")
		(net "M_C_CPU0_SA_DQ<3>")
	)
	(arc
		(start 332.274164 -226.341686)
		(mid 331.991208 -226.417863)
		(end 331.708252 -226.341686)
		(width 0.0889)
		(layer "In2.Cu")
		(net "M_C_CPU0_SA_DQ<3>")
	)
	(arc
		(start 339.794088 -226.341686)
		(mid 339.511132 -226.417863)
		(end 339.228176 -226.341686)
		(width 0.0889)
		(layer "In2.Cu")
		(net "M_C_CPU0_SA_DQ<3>")
	)
	(arc
		(start 343.491058 -226.373436)
		(mid 343.23585 -226.416913)
		(end 342.988138 -226.341686)
		(width 0.0889)
		(layer "In2.Cu")
		(net "M_C_CPU0_SA_DQ<3>")
	)
	(arc
		(start 330.729082 -224.698814)
		(mid 330.550269 -224.496464)
		(end 330.48575 -224.234248)
		(width 0.0889)
		(layer "In2.Cu")
		(net "M_C_CPU0_SA_DQ<3>")
	)
	(arc
		(start 330.95565 -225.044254)
		(mid 330.914101 -224.872832)
		(end 330.798678 -224.739454)
		(width 0.0889)
		(layer "In2.Cu")
		(net "M_C_CPU0_SA_DQ<3>")
	)
	(arc
		(start 330.48575 -224.234248)
		(mid 330.444495 -224.063277)
		(end 330.329794 -223.929956)
		(width 0.0889)
		(layer "In2.Cu")
		(net "M_C_CPU0_SA_DQ<3>")
	)
	(arc
		(start 330.01585 -223.424242)
		(mid 329.974595 -223.253271)
		(end 329.859894 -223.11995)
		(width 0.0889)
		(layer "In2.Cu")
		(net "M_C_CPU0_SA_DQ<3>")
	)
	(arc
		(start 334.154018 -226.341686)
		(mid 333.871062 -226.417863)
		(end 333.588106 -226.341686)
		(width 0.0889)
		(layer "In2.Cu")
		(net "M_C_CPU0_SA_DQ<3>")
	)
	(arc
		(start 342.979756 -226.33686)
		(mid 342.796248 -226.291366)
		(end 342.613996 -226.341686)
		(width 0.0889)
		(layer "In2.Cu")
		(net "M_C_CPU0_SA_DQ<3>")
	)
	(arc
		(start 334.519778 -226.33686)
		(mid 334.33627 -226.291366)
		(end 334.154018 -226.341686)
		(width 0.0889)
		(layer "In2.Cu")
		(net "M_C_CPU0_SA_DQ<3>")
	)
	(arc
		(start 342.039702 -226.33686)
		(mid 341.856194 -226.291366)
		(end 341.673942 -226.341686)
		(width 0.0889)
		(layer "In2.Cu")
		(net "M_C_CPU0_SA_DQ<3>")
	)
	(segment
		(start 344.207846 -244.750082)
		(end 343.740994 -244.484144)
		(width 0.10668)
		(layer "F.Cu")
		(net "M_C_CPU0_SA_DQ<31>")
	)
	(segment
		(start 342.048084 -244.161564)
		(end 342.039702 -244.156738)
		(width 0.0889)
		(layer "In2.Cu")
		(net "M_C_CPU0_SA_DQ<31>")
	)
	(segment
		(start 318.882268 -243.22405)
		(end 315.516768 -239.85855)
		(width 0.14478)
		(layer "In2.Cu")
		(net "M_C_CPU0_SA_DQ<31>")
	)
	(segment
		(start 323.893434 -243.22405)
		(end 318.882268 -243.22405)
		(width 0.14478)
		(layer "In2.Cu")
		(net "M_C_CPU0_SA_DQ<31>")
	)
	(segment
		(start 326.109584 -244.184678)
		(end 326.070214 -244.161818)
		(width 0.0889)
		(layer "In2.Cu")
		(net "M_C_CPU0_SA_DQ<31>")
	)
	(segment
		(start 327.575418 -244.161818)
		(end 327.549256 -244.176804)
		(width 0.0889)
		(layer "In2.Cu")
		(net "M_C_CPU0_SA_DQ<31>")
	)
	(segment
		(start 298.218352 -233.460036)
		(end 297.368214 -234.310174)
		(width 0.14478)
		(layer "In2.Cu")
		(net "M_C_CPU0_SA_DQ<31>")
	)
	(segment
		(start 290.293044 -233.506518)
		(end 290.129976 -233.34345)
		(width 0.14478)
		(layer "In2.Cu")
		(net "M_C_CPU0_SA_DQ<31>")
	)
	(segment
		(start 327.011538 -244.161564)
		(end 326.990964 -244.149626)
		(width 0.0889)
		(layer "In2.Cu")
		(net "M_C_CPU0_SA_DQ<31>")
	)
	(segment
		(start 314.716414 -239.85855)
		(end 308.3179 -233.460036)
		(width 0.14478)
		(layer "In2.Cu")
		(net "M_C_CPU0_SA_DQ<31>")
	)
	(segment
		(start 315.516768 -239.85855)
		(end 314.716414 -239.85855)
		(width 0.14478)
		(layer "In2.Cu")
		(net "M_C_CPU0_SA_DQ<31>")
	)
	(segment
		(start 289.573462 -234.310174)
		(end 288.605214 -234.310174)
		(width 0.14478)
		(layer "In2.Cu")
		(net "M_C_CPU0_SA_DQ<31>")
	)
	(segment
		(start 336.042508 -244.156738)
		(end 336.034126 -244.161564)
		(width 0.0889)
		(layer "In2.Cu")
		(net "M_C_CPU0_SA_DQ<31>")
	)
	(segment
		(start 324.787514 -244.11813)
		(end 323.893434 -243.22405)
		(width 0.0889)
		(layer "In2.Cu")
		(net "M_C_CPU0_SA_DQ<31>")
	)
	(segment
		(start 329.828144 -244.161564)
		(end 329.819762 -244.156738)
		(width 0.0889)
		(layer "In2.Cu")
		(net "M_C_CPU0_SA_DQ<31>")
	)
	(segment
		(start 301.90186 -234.310174)
		(end 301.051722 -233.460036)
		(width 0.14478)
		(layer "In2.Cu")
		(net "M_C_CPU0_SA_DQ<31>")
	)
	(segment
		(start 288.605214 -234.310174)
		(end 288.180018 -233.884978)
		(width 0.14478)
		(layer "In2.Cu")
		(net "M_C_CPU0_SA_DQ<31>")
	)
	(segment
		(start 343.58707 -244.218714)
		(end 343.491058 -244.193314)
		(width 0.0889)
		(layer "In2.Cu")
		(net "M_C_CPU0_SA_DQ<31>")
	)
	(segment
		(start 290.293044 -234.147106)
		(end 290.293044 -233.506518)
		(width 0.14478)
		(layer "In2.Cu")
		(net "M_C_CPU0_SA_DQ<31>")
	)
	(segment
		(start 338.288122 -244.161564)
		(end 338.27974 -244.156738)
		(width 0.0889)
		(layer "In2.Cu")
		(net "M_C_CPU0_SA_DQ<31>")
	)
	(segment
		(start 289.73653 -233.506518)
		(end 289.73653 -234.147106)
		(width 0.14478)
		(layer "In2.Cu")
		(net "M_C_CPU0_SA_DQ<31>")
	)
	(segment
		(start 331.342492 -244.156738)
		(end 331.33411 -244.161564)
		(width 0.0889)
		(layer "In2.Cu")
		(net "M_C_CPU0_SA_DQ<31>")
	)
	(segment
		(start 333.588106 -244.161564)
		(end 333.579724 -244.156738)
		(width 0.0889)
		(layer "In2.Cu")
		(net "M_C_CPU0_SA_DQ<31>")
	)
	(segment
		(start 342.988138 -244.161564)
		(end 342.979756 -244.156738)
		(width 0.0889)
		(layer "In2.Cu")
		(net "M_C_CPU0_SA_DQ<31>")
	)
	(segment
		(start 338.862416 -244.156738)
		(end 338.854034 -244.161564)
		(width 0.0889)
		(layer "In2.Cu")
		(net "M_C_CPU0_SA_DQ<31>")
	)
	(segment
		(start 327.598786 -244.148356)
		(end 327.575418 -244.161818)
		(width 0.0889)
		(layer "In2.Cu")
		(net "M_C_CPU0_SA_DQ<31>")
	)
	(segment
		(start 289.73653 -234.147106)
		(end 289.573462 -234.310174)
		(width 0.14478)
		(layer "In2.Cu")
		(net "M_C_CPU0_SA_DQ<31>")
	)
	(segment
		(start 343.740994 -244.484144)
		(end 343.58707 -244.218714)
		(width 0.0889)
		(layer "In2.Cu")
		(net "M_C_CPU0_SA_DQ<31>")
	)
	(segment
		(start 297.368214 -234.310174)
		(end 290.456112 -234.310174)
		(width 0.14478)
		(layer "In2.Cu")
		(net "M_C_CPU0_SA_DQ<31>")
	)
	(segment
		(start 305.706526 -233.460036)
		(end 304.856388 -234.310174)
		(width 0.14478)
		(layer "In2.Cu")
		(net "M_C_CPU0_SA_DQ<31>")
	)
	(segment
		(start 301.051722 -233.460036)
		(end 298.218352 -233.460036)
		(width 0.14478)
		(layer "In2.Cu")
		(net "M_C_CPU0_SA_DQ<31>")
	)
	(segment
		(start 308.3179 -233.460036)
		(end 305.706526 -233.460036)
		(width 0.14478)
		(layer "In2.Cu")
		(net "M_C_CPU0_SA_DQ<31>")
	)
	(segment
		(start 289.899598 -233.34345)
		(end 289.73653 -233.506518)
		(width 0.14478)
		(layer "In2.Cu")
		(net "M_C_CPU0_SA_DQ<31>")
	)
	(segment
		(start 330.402438 -244.156738)
		(end 330.394056 -244.161564)
		(width 0.0889)
		(layer "In2.Cu")
		(net "M_C_CPU0_SA_DQ<31>")
	)
	(segment
		(start 325.907908 -244.11813)
		(end 324.787514 -244.11813)
		(width 0.0889)
		(layer "In2.Cu")
		(net "M_C_CPU0_SA_DQ<31>")
	)
	(segment
		(start 335.102454 -244.156738)
		(end 335.094072 -244.161564)
		(width 0.0889)
		(layer "In2.Cu")
		(net "M_C_CPU0_SA_DQ<31>")
	)
	(segment
		(start 339.80247 -244.156738)
		(end 339.794088 -244.161564)
		(width 0.0889)
		(layer "In2.Cu")
		(net "M_C_CPU0_SA_DQ<31>")
	)
	(segment
		(start 334.52816 -244.161564)
		(end 334.519778 -244.156738)
		(width 0.0889)
		(layer "In2.Cu")
		(net "M_C_CPU0_SA_DQ<31>")
	)
	(segment
		(start 290.456112 -234.310174)
		(end 290.293044 -234.147106)
		(width 0.14478)
		(layer "In2.Cu")
		(net "M_C_CPU0_SA_DQ<31>")
	)
	(segment
		(start 290.129976 -233.34345)
		(end 289.899598 -233.34345)
		(width 0.14478)
		(layer "In2.Cu")
		(net "M_C_CPU0_SA_DQ<31>")
	)
	(segment
		(start 304.856388 -234.310174)
		(end 301.90186 -234.310174)
		(width 0.14478)
		(layer "In2.Cu")
		(net "M_C_CPU0_SA_DQ<31>")
	)
	(arc
		(start 328.514202 -244.161564)
		(mid 328.231246 -244.237741)
		(end 327.94829 -244.161564)
		(width 0.0889)
		(layer "In2.Cu")
		(net "M_C_CPU0_SA_DQ<31>")
	)
	(arc
		(start 337.348068 -244.161564)
		(mid 337.161124 -244.111309)
		(end 336.97418 -244.161564)
		(width 0.0889)
		(layer "In2.Cu")
		(net "M_C_CPU0_SA_DQ<31>")
	)
	(arc
		(start 335.094072 -244.161564)
		(mid 334.811116 -244.237741)
		(end 334.52816 -244.161564)
		(width 0.0889)
		(layer "In2.Cu")
		(net "M_C_CPU0_SA_DQ<31>")
	)
	(arc
		(start 340.734142 -244.161564)
		(mid 340.451186 -244.237741)
		(end 340.16823 -244.161564)
		(width 0.0889)
		(layer "In2.Cu")
		(net "M_C_CPU0_SA_DQ<31>")
	)
	(arc
		(start 335.468214 -244.161564)
		(mid 335.285963 -244.111214)
		(end 335.102454 -244.156738)
		(width 0.0889)
		(layer "In2.Cu")
		(net "M_C_CPU0_SA_DQ<31>")
	)
	(arc
		(start 326.636126 -244.161564)
		(mid 326.375711 -244.238346)
		(end 326.109584 -244.184678)
		(width 0.0889)
		(layer "In2.Cu")
		(net "M_C_CPU0_SA_DQ<31>")
	)
	(arc
		(start 326.070214 -244.161818)
		(mid 325.991954 -244.129218)
		(end 325.907908 -244.11813)
		(width 0.0889)
		(layer "In2.Cu")
		(net "M_C_CPU0_SA_DQ<31>")
	)
	(arc
		(start 342.979756 -244.156738)
		(mid 342.796248 -244.111244)
		(end 342.613996 -244.161564)
		(width 0.0889)
		(layer "In2.Cu")
		(net "M_C_CPU0_SA_DQ<31>")
	)
	(arc
		(start 331.33411 -244.161564)
		(mid 331.051154 -244.237741)
		(end 330.768198 -244.161564)
		(width 0.0889)
		(layer "In2.Cu")
		(net "M_C_CPU0_SA_DQ<31>")
	)
	(arc
		(start 333.579724 -244.156738)
		(mid 333.396216 -244.111244)
		(end 333.213964 -244.161564)
		(width 0.0889)
		(layer "In2.Cu")
		(net "M_C_CPU0_SA_DQ<31>")
	)
	(arc
		(start 332.648052 -244.161564)
		(mid 332.461108 -244.111309)
		(end 332.274164 -244.161564)
		(width 0.0889)
		(layer "In2.Cu")
		(net "M_C_CPU0_SA_DQ<31>")
	)
	(arc
		(start 327.549256 -244.176804)
		(mid 327.27847 -244.23745)
		(end 327.011538 -244.161564)
		(width 0.0889)
		(layer "In2.Cu")
		(net "M_C_CPU0_SA_DQ<31>")
	)
	(arc
		(start 332.274164 -244.161564)
		(mid 331.991208 -244.237741)
		(end 331.708252 -244.161564)
		(width 0.0889)
		(layer "In2.Cu")
		(net "M_C_CPU0_SA_DQ<31>")
	)
	(arc
		(start 339.228176 -244.161564)
		(mid 339.045925 -244.111214)
		(end 338.862416 -244.156738)
		(width 0.0889)
		(layer "In2.Cu")
		(net "M_C_CPU0_SA_DQ<31>")
	)
	(arc
		(start 337.91398 -244.161564)
		(mid 337.631024 -244.237741)
		(end 337.348068 -244.161564)
		(width 0.0889)
		(layer "In2.Cu")
		(net "M_C_CPU0_SA_DQ<31>")
	)
	(arc
		(start 327.94829 -244.161564)
		(mid 327.775182 -244.111448)
		(end 327.598786 -244.148356)
		(width 0.0889)
		(layer "In2.Cu")
		(net "M_C_CPU0_SA_DQ<31>")
	)
	(arc
		(start 330.768198 -244.161564)
		(mid 330.585947 -244.111214)
		(end 330.402438 -244.156738)
		(width 0.0889)
		(layer "In2.Cu")
		(net "M_C_CPU0_SA_DQ<31>")
	)
	(arc
		(start 330.394056 -244.161564)
		(mid 330.1111 -244.237741)
		(end 329.828144 -244.161564)
		(width 0.0889)
		(layer "In2.Cu")
		(net "M_C_CPU0_SA_DQ<31>")
	)
	(arc
		(start 342.613996 -244.161564)
		(mid 342.33104 -244.237741)
		(end 342.048084 -244.161564)
		(width 0.0889)
		(layer "In2.Cu")
		(net "M_C_CPU0_SA_DQ<31>")
	)
	(arc
		(start 334.519778 -244.156738)
		(mid 334.33627 -244.111244)
		(end 334.154018 -244.161564)
		(width 0.0889)
		(layer "In2.Cu")
		(net "M_C_CPU0_SA_DQ<31>")
	)
	(arc
		(start 341.10803 -244.161564)
		(mid 340.921086 -244.111309)
		(end 340.734142 -244.161564)
		(width 0.0889)
		(layer "In2.Cu")
		(net "M_C_CPU0_SA_DQ<31>")
	)
	(arc
		(start 334.154018 -244.161564)
		(mid 333.871062 -244.237741)
		(end 333.588106 -244.161564)
		(width 0.0889)
		(layer "In2.Cu")
		(net "M_C_CPU0_SA_DQ<31>")
	)
	(arc
		(start 338.27974 -244.156738)
		(mid 338.096232 -244.111244)
		(end 337.91398 -244.161564)
		(width 0.0889)
		(layer "In2.Cu")
		(net "M_C_CPU0_SA_DQ<31>")
	)
	(arc
		(start 329.819762 -244.156738)
		(mid 329.636254 -244.111244)
		(end 329.454002 -244.161564)
		(width 0.0889)
		(layer "In2.Cu")
		(net "M_C_CPU0_SA_DQ<31>")
	)
	(arc
		(start 341.673942 -244.161564)
		(mid 341.390986 -244.237741)
		(end 341.10803 -244.161564)
		(width 0.0889)
		(layer "In2.Cu")
		(net "M_C_CPU0_SA_DQ<31>")
	)
	(arc
		(start 342.039702 -244.156738)
		(mid 341.856194 -244.111244)
		(end 341.673942 -244.161564)
		(width 0.0889)
		(layer "In2.Cu")
		(net "M_C_CPU0_SA_DQ<31>")
	)
	(arc
		(start 333.213964 -244.161564)
		(mid 332.931008 -244.237741)
		(end 332.648052 -244.161564)
		(width 0.0889)
		(layer "In2.Cu")
		(net "M_C_CPU0_SA_DQ<31>")
	)
	(arc
		(start 331.708252 -244.161564)
		(mid 331.526001 -244.111214)
		(end 331.342492 -244.156738)
		(width 0.0889)
		(layer "In2.Cu")
		(net "M_C_CPU0_SA_DQ<31>")
	)
	(arc
		(start 339.794088 -244.161564)
		(mid 339.511132 -244.237741)
		(end 339.228176 -244.161564)
		(width 0.0889)
		(layer "In2.Cu")
		(net "M_C_CPU0_SA_DQ<31>")
	)
	(arc
		(start 328.88809 -244.161564)
		(mid 328.701146 -244.111309)
		(end 328.514202 -244.161564)
		(width 0.0889)
		(layer "In2.Cu")
		(net "M_C_CPU0_SA_DQ<31>")
	)
	(arc
		(start 329.454002 -244.161564)
		(mid 329.171046 -244.237741)
		(end 328.88809 -244.161564)
		(width 0.0889)
		(layer "In2.Cu")
		(net "M_C_CPU0_SA_DQ<31>")
	)
	(arc
		(start 343.491058 -244.193314)
		(mid 343.23585 -244.236791)
		(end 342.988138 -244.161564)
		(width 0.0889)
		(layer "In2.Cu")
		(net "M_C_CPU0_SA_DQ<31>")
	)
	(arc
		(start 326.990964 -244.149626)
		(mid 326.812036 -244.110749)
		(end 326.636126 -244.161564)
		(width 0.0889)
		(layer "In2.Cu")
		(net "M_C_CPU0_SA_DQ<31>")
	)
	(arc
		(start 336.97418 -244.161564)
		(mid 336.691224 -244.237741)
		(end 336.408268 -244.161564)
		(width 0.0889)
		(layer "In2.Cu")
		(net "M_C_CPU0_SA_DQ<31>")
	)
	(arc
		(start 336.408268 -244.161564)
		(mid 336.226017 -244.111214)
		(end 336.042508 -244.156738)
		(width 0.0889)
		(layer "In2.Cu")
		(net "M_C_CPU0_SA_DQ<31>")
	)
	(arc
		(start 336.034126 -244.161564)
		(mid 335.75117 -244.237741)
		(end 335.468214 -244.161564)
		(width 0.0889)
		(layer "In2.Cu")
		(net "M_C_CPU0_SA_DQ<31>")
	)
	(arc
		(start 340.16823 -244.161564)
		(mid 339.985979 -244.111214)
		(end 339.80247 -244.156738)
		(width 0.0889)
		(layer "In2.Cu")
		(net "M_C_CPU0_SA_DQ<31>")
	)
	(arc
		(start 338.854034 -244.161564)
		(mid 338.571078 -244.237741)
		(end 338.288122 -244.161564)
		(width 0.0889)
		(layer "In2.Cu")
		(net "M_C_CPU0_SA_DQ<31>")
	)
	(segment
		(start 342.797892 -243.940076)
		(end 342.33104 -243.674138)
		(width 0.10668)
		(layer "F.Cu")
		(net "M_C_CPU0_SA_DQ<30>")
	)
	(segment
		(start 290.551616 -231.776778)
		(end 290.551616 -232.447084)
		(width 0.14478)
		(layer "In2.Cu")
		(net "M_C_CPU0_SA_DQ<30>")
	)
	(segment
		(start 328.992484 -243.346732)
		(end 328.984102 -243.351558)
		(width 0.0889)
		(layer "In2.Cu")
		(net "M_C_CPU0_SA_DQ<30>")
	)
	(segment
		(start 289.438588 -232.099358)
		(end 289.438588 -232.447084)
		(width 0.14478)
		(layer "In2.Cu")
		(net "M_C_CPU0_SA_DQ<30>")
	)
	(segment
		(start 328.41819 -243.351558)
		(end 328.409808 -243.346732)
		(width 0.0889)
		(layer "In2.Cu")
		(net "M_C_CPU0_SA_DQ<30>")
	)
	(segment
		(start 289.601656 -231.93629)
		(end 289.438588 -232.099358)
		(width 0.14478)
		(layer "In2.Cu")
		(net "M_C_CPU0_SA_DQ<30>")
	)
	(segment
		(start 315.282326 -238.90859)
		(end 309.119778 -232.746042)
		(width 0.14478)
		(layer "In2.Cu")
		(net "M_C_CPU0_SA_DQ<30>")
	)
	(segment
		(start 291.10813 -231.776778)
		(end 290.945062 -231.61371)
		(width 0.14478)
		(layer "In2.Cu")
		(net "M_C_CPU0_SA_DQ<30>")
	)
	(segment
		(start 326.341994 -243.307362)
		(end 325.434706 -243.307362)
		(width 0.0889)
		(layer "In2.Cu")
		(net "M_C_CPU0_SA_DQ<30>")
	)
	(segment
		(start 291.10813 -232.447084)
		(end 291.10813 -231.776778)
		(width 0.14478)
		(layer "In2.Cu")
		(net "M_C_CPU0_SA_DQ<30>")
	)
	(segment
		(start 342.177116 -243.408708)
		(end 342.081104 -243.383308)
		(width 0.0889)
		(layer "In2.Cu")
		(net "M_C_CPU0_SA_DQ<30>")
	)
	(segment
		(start 288.605214 -232.610152)
		(end 288.180018 -232.184956)
		(width 0.14478)
		(layer "In2.Cu")
		(net "M_C_CPU0_SA_DQ<30>")
	)
	(segment
		(start 290.388548 -232.610152)
		(end 290.15817 -232.610152)
		(width 0.14478)
		(layer "In2.Cu")
		(net "M_C_CPU0_SA_DQ<30>")
	)
	(segment
		(start 342.33104 -243.674138)
		(end 342.177116 -243.408708)
		(width 0.0889)
		(layer "In2.Cu")
		(net "M_C_CPU0_SA_DQ<30>")
	)
	(segment
		(start 309.119778 -232.746042)
		(end 309.119778 -232.213658)
		(width 0.14478)
		(layer "In2.Cu")
		(net "M_C_CPU0_SA_DQ<30>")
	)
	(segment
		(start 336.878168 -243.351558)
		(end 336.869786 -243.346732)
		(width 0.0889)
		(layer "In2.Cu")
		(net "M_C_CPU0_SA_DQ<30>")
	)
	(segment
		(start 301.051722 -231.760014)
		(end 298.218352 -231.760014)
		(width 0.14478)
		(layer "In2.Cu")
		(net "M_C_CPU0_SA_DQ<30>")
	)
	(segment
		(start 331.238098 -243.351558)
		(end 331.229716 -243.346732)
		(width 0.0889)
		(layer "In2.Cu")
		(net "M_C_CPU0_SA_DQ<30>")
	)
	(segment
		(start 324.434454 -242.30711)
		(end 323.898514 -242.30711)
		(width 0.0889)
		(layer "In2.Cu")
		(net "M_C_CPU0_SA_DQ<30>")
	)
	(segment
		(start 325.434706 -243.307362)
		(end 324.434454 -242.30711)
		(width 0.0889)
		(layer "In2.Cu")
		(net "M_C_CPU0_SA_DQ<30>")
	)
	(segment
		(start 323.898514 -242.30711)
		(end 319.296034 -242.30711)
		(width 0.14478)
		(layer "In2.Cu")
		(net "M_C_CPU0_SA_DQ<30>")
	)
	(segment
		(start 290.15817 -232.610152)
		(end 289.995102 -232.447084)
		(width 0.14478)
		(layer "In2.Cu")
		(net "M_C_CPU0_SA_DQ<30>")
	)
	(segment
		(start 290.551616 -232.447084)
		(end 290.388548 -232.610152)
		(width 0.14478)
		(layer "In2.Cu")
		(net "M_C_CPU0_SA_DQ<30>")
	)
	(segment
		(start 289.438588 -232.447084)
		(end 289.27552 -232.610152)
		(width 0.14478)
		(layer "In2.Cu")
		(net "M_C_CPU0_SA_DQ<30>")
	)
	(segment
		(start 289.27552 -232.610152)
		(end 288.605214 -232.610152)
		(width 0.14478)
		(layer "In2.Cu")
		(net "M_C_CPU0_SA_DQ<30>")
	)
	(segment
		(start 291.271198 -232.610152)
		(end 291.10813 -232.447084)
		(width 0.14478)
		(layer "In2.Cu")
		(net "M_C_CPU0_SA_DQ<30>")
	)
	(segment
		(start 332.752446 -243.346732)
		(end 332.744064 -243.351558)
		(width 0.0889)
		(layer "In2.Cu")
		(net "M_C_CPU0_SA_DQ<30>")
	)
	(segment
		(start 290.945062 -231.61371)
		(end 290.714684 -231.61371)
		(width 0.14478)
		(layer "In2.Cu")
		(net "M_C_CPU0_SA_DQ<30>")
	)
	(segment
		(start 315.897514 -238.90859)
		(end 315.282326 -238.90859)
		(width 0.14478)
		(layer "In2.Cu")
		(net "M_C_CPU0_SA_DQ<30>")
	)
	(segment
		(start 340.63813 -243.351558)
		(end 340.629748 -243.346732)
		(width 0.0889)
		(layer "In2.Cu")
		(net "M_C_CPU0_SA_DQ<30>")
	)
	(segment
		(start 289.995102 -232.099358)
		(end 289.832034 -231.93629)
		(width 0.14478)
		(layer "In2.Cu")
		(net "M_C_CPU0_SA_DQ<30>")
	)
	(segment
		(start 319.296034 -242.30711)
		(end 315.897514 -238.90859)
		(width 0.14478)
		(layer "In2.Cu")
		(net "M_C_CPU0_SA_DQ<30>")
	)
	(segment
		(start 337.452462 -243.346732)
		(end 337.44408 -243.351558)
		(width 0.0889)
		(layer "In2.Cu")
		(net "M_C_CPU0_SA_DQ<30>")
	)
	(segment
		(start 308.666134 -231.760014)
		(end 305.94427 -231.760014)
		(width 0.14478)
		(layer "In2.Cu")
		(net "M_C_CPU0_SA_DQ<30>")
	)
	(segment
		(start 332.178152 -243.351558)
		(end 332.16977 -243.346732)
		(width 0.0889)
		(layer "In2.Cu")
		(net "M_C_CPU0_SA_DQ<30>")
	)
	(segment
		(start 305.94427 -231.760014)
		(end 305.094132 -232.610152)
		(width 0.14478)
		(layer "In2.Cu")
		(net "M_C_CPU0_SA_DQ<30>")
	)
	(segment
		(start 297.368214 -232.610152)
		(end 291.271198 -232.610152)
		(width 0.14478)
		(layer "In2.Cu")
		(net "M_C_CPU0_SA_DQ<30>")
	)
	(segment
		(start 298.218352 -231.760014)
		(end 297.368214 -232.610152)
		(width 0.14478)
		(layer "In2.Cu")
		(net "M_C_CPU0_SA_DQ<30>")
	)
	(segment
		(start 290.714684 -231.61371)
		(end 290.551616 -231.776778)
		(width 0.14478)
		(layer "In2.Cu")
		(net "M_C_CPU0_SA_DQ<30>")
	)
	(segment
		(start 289.995102 -232.447084)
		(end 289.995102 -232.099358)
		(width 0.14478)
		(layer "In2.Cu")
		(net "M_C_CPU0_SA_DQ<30>")
	)
	(segment
		(start 339.698076 -243.351558)
		(end 339.689694 -243.346732)
		(width 0.0889)
		(layer "In2.Cu")
		(net "M_C_CPU0_SA_DQ<30>")
	)
	(segment
		(start 327.114916 -243.3447)
		(end 327.103232 -243.351558)
		(width 0.0889)
		(layer "In2.Cu")
		(net "M_C_CPU0_SA_DQ<30>")
	)
	(segment
		(start 305.094132 -232.610152)
		(end 301.90186 -232.610152)
		(width 0.14478)
		(layer "In2.Cu")
		(net "M_C_CPU0_SA_DQ<30>")
	)
	(segment
		(start 301.90186 -232.610152)
		(end 301.051722 -231.760014)
		(width 0.14478)
		(layer "In2.Cu")
		(net "M_C_CPU0_SA_DQ<30>")
	)
	(segment
		(start 335.938114 -243.351558)
		(end 335.929732 -243.346732)
		(width 0.0889)
		(layer "In2.Cu")
		(net "M_C_CPU0_SA_DQ<30>")
	)
	(segment
		(start 328.044048 -243.351558)
		(end 328.029316 -243.360194)
		(width 0.0889)
		(layer "In2.Cu")
		(net "M_C_CPU0_SA_DQ<30>")
	)
	(segment
		(start 341.212424 -243.346732)
		(end 341.204042 -243.351558)
		(width 0.0889)
		(layer "In2.Cu")
		(net "M_C_CPU0_SA_DQ<30>")
	)
	(segment
		(start 309.119778 -232.213658)
		(end 308.666134 -231.760014)
		(width 0.14478)
		(layer "In2.Cu")
		(net "M_C_CPU0_SA_DQ<30>")
	)
	(segment
		(start 333.6925 -243.346732)
		(end 333.684118 -243.351558)
		(width 0.0889)
		(layer "In2.Cu")
		(net "M_C_CPU0_SA_DQ<30>")
	)
	(segment
		(start 289.832034 -231.93629)
		(end 289.601656 -231.93629)
		(width 0.14478)
		(layer "In2.Cu")
		(net "M_C_CPU0_SA_DQ<30>")
	)
	(arc
		(start 334.624172 -243.351558)
		(mid 334.341216 -243.427735)
		(end 334.05826 -243.351558)
		(width 0.0889)
		(layer "In2.Cu")
		(net "M_C_CPU0_SA_DQ<30>")
	)
	(arc
		(start 334.99806 -243.351558)
		(mid 334.811116 -243.301303)
		(end 334.624172 -243.351558)
		(width 0.0889)
		(layer "In2.Cu")
		(net "M_C_CPU0_SA_DQ<30>")
	)
	(arc
		(start 337.818222 -243.351558)
		(mid 337.635971 -243.301208)
		(end 337.452462 -243.346732)
		(width 0.0889)
		(layer "In2.Cu")
		(net "M_C_CPU0_SA_DQ<30>")
	)
	(arc
		(start 341.578184 -243.351558)
		(mid 341.395933 -243.301208)
		(end 341.212424 -243.346732)
		(width 0.0889)
		(layer "In2.Cu")
		(net "M_C_CPU0_SA_DQ<30>")
	)
	(arc
		(start 341.204042 -243.351558)
		(mid 340.921086 -243.427735)
		(end 340.63813 -243.351558)
		(width 0.0889)
		(layer "In2.Cu")
		(net "M_C_CPU0_SA_DQ<30>")
	)
	(arc
		(start 327.103232 -243.351558)
		(mid 326.823804 -243.427724)
		(end 326.543416 -243.355114)
		(width 0.0889)
		(layer "In2.Cu")
		(net "M_C_CPU0_SA_DQ<30>")
	)
	(arc
		(start 330.863956 -243.351558)
		(mid 330.581 -243.427735)
		(end 330.298044 -243.351558)
		(width 0.0889)
		(layer "In2.Cu")
		(net "M_C_CPU0_SA_DQ<30>")
	)
	(arc
		(start 342.081104 -243.383308)
		(mid 341.825896 -243.426785)
		(end 341.578184 -243.351558)
		(width 0.0889)
		(layer "In2.Cu")
		(net "M_C_CPU0_SA_DQ<30>")
	)
	(arc
		(start 331.229716 -243.346732)
		(mid 331.046208 -243.301238)
		(end 330.863956 -243.351558)
		(width 0.0889)
		(layer "In2.Cu")
		(net "M_C_CPU0_SA_DQ<30>")
	)
	(arc
		(start 335.563972 -243.351558)
		(mid 335.281016 -243.427735)
		(end 334.99806 -243.351558)
		(width 0.0889)
		(layer "In2.Cu")
		(net "M_C_CPU0_SA_DQ<30>")
	)
	(arc
		(start 326.543416 -243.355114)
		(mid 326.488321 -243.332411)
		(end 326.430894 -243.316506)
		(width 0.0889)
		(layer "In2.Cu")
		(net "M_C_CPU0_SA_DQ<30>")
	)
	(arc
		(start 327.477628 -243.351558)
		(mid 327.29717 -243.301114)
		(end 327.114916 -243.3447)
		(width 0.0889)
		(layer "In2.Cu")
		(net "M_C_CPU0_SA_DQ<30>")
	)
	(arc
		(start 329.924156 -243.351558)
		(mid 329.6412 -243.427735)
		(end 329.358244 -243.351558)
		(width 0.0889)
		(layer "In2.Cu")
		(net "M_C_CPU0_SA_DQ<30>")
	)
	(arc
		(start 328.409808 -243.346732)
		(mid 328.2263 -243.301238)
		(end 328.044048 -243.351558)
		(width 0.0889)
		(layer "In2.Cu")
		(net "M_C_CPU0_SA_DQ<30>")
	)
	(arc
		(start 336.504026 -243.351558)
		(mid 336.22107 -243.427735)
		(end 335.938114 -243.351558)
		(width 0.0889)
		(layer "In2.Cu")
		(net "M_C_CPU0_SA_DQ<30>")
	)
	(arc
		(start 334.05826 -243.351558)
		(mid 333.876009 -243.301208)
		(end 333.6925 -243.346732)
		(width 0.0889)
		(layer "In2.Cu")
		(net "M_C_CPU0_SA_DQ<30>")
	)
	(arc
		(start 340.263988 -243.351558)
		(mid 339.981032 -243.427735)
		(end 339.698076 -243.351558)
		(width 0.0889)
		(layer "In2.Cu")
		(net "M_C_CPU0_SA_DQ<30>")
	)
	(arc
		(start 332.744064 -243.351558)
		(mid 332.461108 -243.427735)
		(end 332.178152 -243.351558)
		(width 0.0889)
		(layer "In2.Cu")
		(net "M_C_CPU0_SA_DQ<30>")
	)
	(arc
		(start 339.689694 -243.346732)
		(mid 339.506186 -243.301238)
		(end 339.323934 -243.351558)
		(width 0.0889)
		(layer "In2.Cu")
		(net "M_C_CPU0_SA_DQ<30>")
	)
	(arc
		(start 330.298044 -243.351558)
		(mid 330.1111 -243.301303)
		(end 329.924156 -243.351558)
		(width 0.0889)
		(layer "In2.Cu")
		(net "M_C_CPU0_SA_DQ<30>")
	)
	(arc
		(start 337.44408 -243.351558)
		(mid 337.161124 -243.427735)
		(end 336.878168 -243.351558)
		(width 0.0889)
		(layer "In2.Cu")
		(net "M_C_CPU0_SA_DQ<30>")
	)
	(arc
		(start 328.984102 -243.351558)
		(mid 328.701146 -243.427735)
		(end 328.41819 -243.351558)
		(width 0.0889)
		(layer "In2.Cu")
		(net "M_C_CPU0_SA_DQ<30>")
	)
	(arc
		(start 333.118206 -243.351558)
		(mid 332.935955 -243.301208)
		(end 332.752446 -243.346732)
		(width 0.0889)
		(layer "In2.Cu")
		(net "M_C_CPU0_SA_DQ<30>")
	)
	(arc
		(start 336.869786 -243.346732)
		(mid 336.686278 -243.301238)
		(end 336.504026 -243.351558)
		(width 0.0889)
		(layer "In2.Cu")
		(net "M_C_CPU0_SA_DQ<30>")
	)
	(arc
		(start 332.16977 -243.346732)
		(mid 331.986262 -243.301238)
		(end 331.80401 -243.351558)
		(width 0.0889)
		(layer "In2.Cu")
		(net "M_C_CPU0_SA_DQ<30>")
	)
	(arc
		(start 338.384134 -243.351558)
		(mid 338.101178 -243.427735)
		(end 337.818222 -243.351558)
		(width 0.0889)
		(layer "In2.Cu")
		(net "M_C_CPU0_SA_DQ<30>")
	)
	(arc
		(start 333.684118 -243.351558)
		(mid 333.401162 -243.427735)
		(end 333.118206 -243.351558)
		(width 0.0889)
		(layer "In2.Cu")
		(net "M_C_CPU0_SA_DQ<30>")
	)
	(arc
		(start 331.80401 -243.351558)
		(mid 331.521054 -243.427735)
		(end 331.238098 -243.351558)
		(width 0.0889)
		(layer "In2.Cu")
		(net "M_C_CPU0_SA_DQ<30>")
	)
	(arc
		(start 326.430894 -243.316506)
		(mid 326.386683 -243.309615)
		(end 326.341994 -243.307362)
		(width 0.0889)
		(layer "In2.Cu")
		(net "M_C_CPU0_SA_DQ<30>")
	)
	(arc
		(start 340.629748 -243.346732)
		(mid 340.44624 -243.301238)
		(end 340.263988 -243.351558)
		(width 0.0889)
		(layer "In2.Cu")
		(net "M_C_CPU0_SA_DQ<30>")
	)
	(arc
		(start 335.929732 -243.346732)
		(mid 335.746224 -243.301238)
		(end 335.563972 -243.351558)
		(width 0.0889)
		(layer "In2.Cu")
		(net "M_C_CPU0_SA_DQ<30>")
	)
	(arc
		(start 339.323934 -243.351558)
		(mid 339.040978 -243.427735)
		(end 338.758022 -243.351558)
		(width 0.0889)
		(layer "In2.Cu")
		(net "M_C_CPU0_SA_DQ<30>")
	)
	(arc
		(start 329.358244 -243.351558)
		(mid 329.175993 -243.301208)
		(end 328.992484 -243.346732)
		(width 0.0889)
		(layer "In2.Cu")
		(net "M_C_CPU0_SA_DQ<30>")
	)
	(arc
		(start 338.758022 -243.351558)
		(mid 338.571078 -243.301303)
		(end 338.384134 -243.351558)
		(width 0.0889)
		(layer "In2.Cu")
		(net "M_C_CPU0_SA_DQ<30>")
	)
	(arc
		(start 328.029316 -243.360194)
		(mid 327.752333 -243.427998)
		(end 327.477628 -243.351558)
		(width 0.0889)
		(layer "In2.Cu")
		(net "M_C_CPU0_SA_DQ<30>")
	)
	(segment
		(start 342.797892 -226.120198)
		(end 342.33104 -225.85426)
		(width 0.10668)
		(layer "F.Cu")
		(net "M_C_CPU0_SA_DQ<2>")
	)
	(segment
		(start 290.356544 -196.826632)
		(end 290.126166 -196.826632)
		(width 0.14478)
		(layer "In2.Cu")
		(net "M_C_CPU0_SA_DQ<2>")
	)
	(segment
		(start 337.452462 -225.526854)
		(end 337.44408 -225.53168)
		(width 0.0889)
		(layer "In2.Cu")
		(net "M_C_CPU0_SA_DQ<2>")
	)
	(segment
		(start 321.267074 -209.13979)
		(end 309.887366 -197.760082)
		(width 0.14478)
		(layer "In2.Cu")
		(net "M_C_CPU0_SA_DQ<2>")
	)
	(segment
		(start 289.963098 -196.9897)
		(end 289.963098 -197.597014)
		(width 0.14478)
		(layer "In2.Cu")
		(net "M_C_CPU0_SA_DQ<2>")
	)
	(segment
		(start 290.68268 -197.760082)
		(end 290.519612 -197.597014)
		(width 0.14478)
		(layer "In2.Cu")
		(net "M_C_CPU0_SA_DQ<2>")
	)
	(segment
		(start 289.80003 -197.760082)
		(end 288.60496 -197.760082)
		(width 0.14478)
		(layer "In2.Cu")
		(net "M_C_CPU0_SA_DQ<2>")
	)
	(segment
		(start 332.752446 -225.526854)
		(end 332.744064 -225.53168)
		(width 0.0889)
		(layer "In2.Cu")
		(net "M_C_CPU0_SA_DQ<2>")
	)
	(segment
		(start 342.33104 -225.85426)
		(end 342.177116 -225.58883)
		(width 0.0889)
		(layer "In2.Cu")
		(net "M_C_CPU0_SA_DQ<2>")
	)
	(segment
		(start 331.238098 -223.911668)
		(end 331.198982 -223.888808)
		(width 0.0889)
		(layer "In2.Cu")
		(net "M_C_CPU0_SA_DQ<2>")
	)
	(segment
		(start 331.708252 -224.721674)
		(end 331.669136 -224.698814)
		(width 0.0889)
		(layer "In2.Cu")
		(net "M_C_CPU0_SA_DQ<2>")
	)
	(segment
		(start 329.991974 -218.54033)
		(end 325.045832 -213.594188)
		(width 0.14478)
		(layer "In2.Cu")
		(net "M_C_CPU0_SA_DQ<2>")
	)
	(segment
		(start 331.269848 -223.929956)
		(end 331.238098 -223.911668)
		(width 0.0889)
		(layer "In2.Cu")
		(net "M_C_CPU0_SA_DQ<2>")
	)
	(segment
		(start 309.887366 -197.760082)
		(end 290.68268 -197.760082)
		(width 0.14478)
		(layer "In2.Cu")
		(net "M_C_CPU0_SA_DQ<2>")
	)
	(segment
		(start 289.963098 -197.597014)
		(end 289.80003 -197.760082)
		(width 0.14478)
		(layer "In2.Cu")
		(net "M_C_CPU0_SA_DQ<2>")
	)
	(segment
		(start 341.212424 -225.526854)
		(end 341.204042 -225.53168)
		(width 0.0889)
		(layer "In2.Cu")
		(net "M_C_CPU0_SA_DQ<2>")
	)
	(segment
		(start 340.63813 -225.53168)
		(end 340.629748 -225.526854)
		(width 0.0889)
		(layer "In2.Cu")
		(net "M_C_CPU0_SA_DQ<2>")
	)
	(segment
		(start 330.230734 -222.252286)
		(end 330.115672 -222.252286)
		(width 0.0889)
		(layer "In2.Cu")
		(net "M_C_CPU0_SA_DQ<2>")
	)
	(segment
		(start 332.178152 -225.53168)
		(end 332.139036 -225.50882)
		(width 0.0889)
		(layer "In2.Cu")
		(net "M_C_CPU0_SA_DQ<2>")
	)
	(segment
		(start 339.698076 -225.53168)
		(end 339.689694 -225.526854)
		(width 0.0889)
		(layer "In2.Cu")
		(net "M_C_CPU0_SA_DQ<2>")
	)
	(segment
		(start 330.328778 -222.309436)
		(end 330.230734 -222.252286)
		(width 0.0889)
		(layer "In2.Cu")
		(net "M_C_CPU0_SA_DQ<2>")
	)
	(segment
		(start 342.177116 -225.58883)
		(end 342.081104 -225.56343)
		(width 0.0889)
		(layer "In2.Cu")
		(net "M_C_CPU0_SA_DQ<2>")
	)
	(segment
		(start 329.991974 -221.21749)
		(end 329.991974 -218.54033)
		(width 0.14478)
		(layer "In2.Cu")
		(net "M_C_CPU0_SA_DQ<2>")
	)
	(segment
		(start 325.045832 -213.594188)
		(end 325.045832 -211.894928)
		(width 0.14478)
		(layer "In2.Cu")
		(net "M_C_CPU0_SA_DQ<2>")
	)
	(segment
		(start 290.126166 -196.826632)
		(end 289.963098 -196.9897)
		(width 0.14478)
		(layer "In2.Cu")
		(net "M_C_CPU0_SA_DQ<2>")
	)
	(segment
		(start 288.60496 -197.760082)
		(end 288.180018 -198.185024)
		(width 0.14478)
		(layer "In2.Cu")
		(net "M_C_CPU0_SA_DQ<2>")
	)
	(segment
		(start 329.854814 -221.991428)
		(end 329.854814 -221.59341)
		(width 0.0889)
		(layer "In2.Cu")
		(net "M_C_CPU0_SA_DQ<2>")
	)
	(segment
		(start 329.991974 -221.45625)
		(end 329.991974 -221.21749)
		(width 0.0889)
		(layer "In2.Cu")
		(net "M_C_CPU0_SA_DQ<2>")
	)
	(segment
		(start 322.290694 -209.13979)
		(end 321.267074 -209.13979)
		(width 0.14478)
		(layer "In2.Cu")
		(net "M_C_CPU0_SA_DQ<2>")
	)
	(segment
		(start 331.738732 -224.739454)
		(end 331.708252 -224.721674)
		(width 0.0889)
		(layer "In2.Cu")
		(net "M_C_CPU0_SA_DQ<2>")
	)
	(segment
		(start 336.878168 -225.53168)
		(end 336.869786 -225.526854)
		(width 0.0889)
		(layer "In2.Cu")
		(net "M_C_CPU0_SA_DQ<2>")
	)
	(segment
		(start 290.519612 -197.597014)
		(end 290.519612 -196.9897)
		(width 0.14478)
		(layer "In2.Cu")
		(net "M_C_CPU0_SA_DQ<2>")
	)
	(segment
		(start 335.938114 -225.53168)
		(end 335.929732 -225.526854)
		(width 0.0889)
		(layer "In2.Cu")
		(net "M_C_CPU0_SA_DQ<2>")
	)
	(segment
		(start 325.045832 -211.894928)
		(end 322.290694 -209.13979)
		(width 0.14478)
		(layer "In2.Cu")
		(net "M_C_CPU0_SA_DQ<2>")
	)
	(segment
		(start 330.115672 -222.252286)
		(end 329.854814 -221.991428)
		(width 0.0889)
		(layer "In2.Cu")
		(net "M_C_CPU0_SA_DQ<2>")
	)
	(segment
		(start 330.798678 -223.119442)
		(end 330.768198 -223.101662)
		(width 0.0889)
		(layer "In2.Cu")
		(net "M_C_CPU0_SA_DQ<2>")
	)
	(segment
		(start 330.768198 -223.101662)
		(end 330.729082 -223.078802)
		(width 0.0889)
		(layer "In2.Cu")
		(net "M_C_CPU0_SA_DQ<2>")
	)
	(segment
		(start 329.854814 -221.59341)
		(end 329.991974 -221.45625)
		(width 0.0889)
		(layer "In2.Cu")
		(net "M_C_CPU0_SA_DQ<2>")
	)
	(segment
		(start 333.6925 -225.526854)
		(end 333.684118 -225.53168)
		(width 0.0889)
		(layer "In2.Cu")
		(net "M_C_CPU0_SA_DQ<2>")
	)
	(segment
		(start 290.519612 -196.9897)
		(end 290.356544 -196.826632)
		(width 0.14478)
		(layer "In2.Cu")
		(net "M_C_CPU0_SA_DQ<2>")
	)
	(arc
		(start 334.05826 -225.53168)
		(mid 333.876009 -225.48133)
		(end 333.6925 -225.526854)
		(width 0.0889)
		(layer "In2.Cu")
		(net "M_C_CPU0_SA_DQ<2>")
	)
	(arc
		(start 330.48575 -222.614236)
		(mid 330.444201 -222.442814)
		(end 330.328778 -222.309436)
		(width 0.0889)
		(layer "In2.Cu")
		(net "M_C_CPU0_SA_DQ<2>")
	)
	(arc
		(start 339.323934 -225.53168)
		(mid 339.040978 -225.607857)
		(end 338.758022 -225.53168)
		(width 0.0889)
		(layer "In2.Cu")
		(net "M_C_CPU0_SA_DQ<2>")
	)
	(arc
		(start 333.684118 -225.53168)
		(mid 333.401162 -225.607857)
		(end 333.118206 -225.53168)
		(width 0.0889)
		(layer "In2.Cu")
		(net "M_C_CPU0_SA_DQ<2>")
	)
	(arc
		(start 330.729082 -223.078802)
		(mid 330.550269 -222.876452)
		(end 330.48575 -222.614236)
		(width 0.0889)
		(layer "In2.Cu")
		(net "M_C_CPU0_SA_DQ<2>")
	)
	(arc
		(start 339.689694 -225.526854)
		(mid 339.506186 -225.48136)
		(end 339.323934 -225.53168)
		(width 0.0889)
		(layer "In2.Cu")
		(net "M_C_CPU0_SA_DQ<2>")
	)
	(arc
		(start 331.895704 -225.044254)
		(mid 331.854155 -224.872832)
		(end 331.738732 -224.739454)
		(width 0.0889)
		(layer "In2.Cu")
		(net "M_C_CPU0_SA_DQ<2>")
	)
	(arc
		(start 336.869786 -225.526854)
		(mid 336.686278 -225.48136)
		(end 336.504026 -225.53168)
		(width 0.0889)
		(layer "In2.Cu")
		(net "M_C_CPU0_SA_DQ<2>")
	)
	(arc
		(start 331.669136 -224.698814)
		(mid 331.490323 -224.496464)
		(end 331.425804 -224.234248)
		(width 0.0889)
		(layer "In2.Cu")
		(net "M_C_CPU0_SA_DQ<2>")
	)
	(arc
		(start 333.118206 -225.53168)
		(mid 332.935955 -225.48133)
		(end 332.752446 -225.526854)
		(width 0.0889)
		(layer "In2.Cu")
		(net "M_C_CPU0_SA_DQ<2>")
	)
	(arc
		(start 341.578184 -225.53168)
		(mid 341.395933 -225.48133)
		(end 341.212424 -225.526854)
		(width 0.0889)
		(layer "In2.Cu")
		(net "M_C_CPU0_SA_DQ<2>")
	)
	(arc
		(start 340.629748 -225.526854)
		(mid 340.44624 -225.48136)
		(end 340.263988 -225.53168)
		(width 0.0889)
		(layer "In2.Cu")
		(net "M_C_CPU0_SA_DQ<2>")
	)
	(arc
		(start 334.624172 -225.53168)
		(mid 334.341216 -225.607857)
		(end 334.05826 -225.53168)
		(width 0.0889)
		(layer "In2.Cu")
		(net "M_C_CPU0_SA_DQ<2>")
	)
	(arc
		(start 342.081104 -225.56343)
		(mid 341.825896 -225.606907)
		(end 341.578184 -225.53168)
		(width 0.0889)
		(layer "In2.Cu")
		(net "M_C_CPU0_SA_DQ<2>")
	)
	(arc
		(start 335.929732 -225.526854)
		(mid 335.746224 -225.48136)
		(end 335.563972 -225.53168)
		(width 0.0889)
		(layer "In2.Cu")
		(net "M_C_CPU0_SA_DQ<2>")
	)
	(arc
		(start 338.384134 -225.53168)
		(mid 338.101178 -225.607857)
		(end 337.818222 -225.53168)
		(width 0.0889)
		(layer "In2.Cu")
		(net "M_C_CPU0_SA_DQ<2>")
	)
	(arc
		(start 330.95565 -223.424242)
		(mid 330.914101 -223.25282)
		(end 330.798678 -223.119442)
		(width 0.0889)
		(layer "In2.Cu")
		(net "M_C_CPU0_SA_DQ<2>")
	)
	(arc
		(start 341.204042 -225.53168)
		(mid 340.921086 -225.607857)
		(end 340.63813 -225.53168)
		(width 0.0889)
		(layer "In2.Cu")
		(net "M_C_CPU0_SA_DQ<2>")
	)
	(arc
		(start 332.744064 -225.53168)
		(mid 332.461108 -225.607857)
		(end 332.178152 -225.53168)
		(width 0.0889)
		(layer "In2.Cu")
		(net "M_C_CPU0_SA_DQ<2>")
	)
	(arc
		(start 331.198982 -223.888808)
		(mid 331.020169 -223.686458)
		(end 330.95565 -223.424242)
		(width 0.0889)
		(layer "In2.Cu")
		(net "M_C_CPU0_SA_DQ<2>")
	)
	(arc
		(start 337.44408 -225.53168)
		(mid 337.161124 -225.607857)
		(end 336.878168 -225.53168)
		(width 0.0889)
		(layer "In2.Cu")
		(net "M_C_CPU0_SA_DQ<2>")
	)
	(arc
		(start 331.425804 -224.234248)
		(mid 331.384549 -224.063277)
		(end 331.269848 -223.929956)
		(width 0.0889)
		(layer "In2.Cu")
		(net "M_C_CPU0_SA_DQ<2>")
	)
	(arc
		(start 336.504026 -225.53168)
		(mid 336.22107 -225.607857)
		(end 335.938114 -225.53168)
		(width 0.0889)
		(layer "In2.Cu")
		(net "M_C_CPU0_SA_DQ<2>")
	)
	(arc
		(start 332.139036 -225.50882)
		(mid 331.960223 -225.30647)
		(end 331.895704 -225.044254)
		(width 0.0889)
		(layer "In2.Cu")
		(net "M_C_CPU0_SA_DQ<2>")
	)
	(arc
		(start 335.563972 -225.53168)
		(mid 335.281016 -225.607857)
		(end 334.99806 -225.53168)
		(width 0.0889)
		(layer "In2.Cu")
		(net "M_C_CPU0_SA_DQ<2>")
	)
	(arc
		(start 340.263988 -225.53168)
		(mid 339.981032 -225.607857)
		(end 339.698076 -225.53168)
		(width 0.0889)
		(layer "In2.Cu")
		(net "M_C_CPU0_SA_DQ<2>")
	)
	(arc
		(start 337.818222 -225.53168)
		(mid 337.635971 -225.48133)
		(end 337.452462 -225.526854)
		(width 0.0889)
		(layer "In2.Cu")
		(net "M_C_CPU0_SA_DQ<2>")
	)
	(arc
		(start 338.758022 -225.53168)
		(mid 338.571078 -225.481425)
		(end 338.384134 -225.53168)
		(width 0.0889)
		(layer "In2.Cu")
		(net "M_C_CPU0_SA_DQ<2>")
	)
	(arc
		(start 334.99806 -225.53168)
		(mid 334.811116 -225.481425)
		(end 334.624172 -225.53168)
		(width 0.0889)
		(layer "In2.Cu")
		(net "M_C_CPU0_SA_DQ<2>")
	)
	(segment
		(start 343.737946 -243.940076)
		(end 343.271094 -243.674138)
		(width 0.10668)
		(layer "F.Cu")
		(net "M_C_CPU0_SA_DQ<29>")
	)
	(segment
		(start 336.878168 -243.996718)
		(end 336.869786 -244.001544)
		(width 0.0889)
		(layer "In2.Cu")
		(net "M_C_CPU0_SA_DQ<29>")
	)
	(segment
		(start 313.719718 -238.225584)
		(end 313.45124 -237.957106)
		(width 0.14478)
		(layer "In2.Cu")
		(net "M_C_CPU0_SA_DQ<29>")
	)
	(segment
		(start 306.296314 -232.378758)
		(end 306.296314 -232.447084)
		(width 0.14478)
		(layer "In2.Cu")
		(net "M_C_CPU0_SA_DQ<29>")
	)
	(segment
		(start 296.433494 -233.296968)
		(end 296.270426 -233.460036)
		(width 0.14478)
		(layer "In2.Cu")
		(net "M_C_CPU0_SA_DQ<29>")
	)
	(segment
		(start 306.459382 -232.21569)
		(end 306.296314 -232.378758)
		(width 0.14478)
		(layer "In2.Cu")
		(net "M_C_CPU0_SA_DQ<29>")
	)
	(segment
		(start 314.231782 -238.494062)
		(end 313.963304 -238.225584)
		(width 0.14478)
		(layer "In2.Cu")
		(net "M_C_CPU0_SA_DQ<29>")
	)
	(segment
		(start 292.705028 -233.460036)
		(end 292.280086 -233.035094)
		(width 0.14478)
		(layer "In2.Cu")
		(net "M_C_CPU0_SA_DQ<29>")
	)
	(segment
		(start 307.015896 -232.610152)
		(end 306.852828 -232.447084)
		(width 0.14478)
		(layer "In2.Cu")
		(net "M_C_CPU0_SA_DQ<29>")
	)
	(segment
		(start 314.743592 -239.005872)
		(end 314.500006 -239.005872)
		(width 0.14478)
		(layer "In2.Cu")
		(net "M_C_CPU0_SA_DQ<29>")
	)
	(segment
		(start 304.345594 -233.07421)
		(end 304.115216 -233.07421)
		(width 0.14478)
		(layer "In2.Cu")
		(net "M_C_CPU0_SA_DQ<29>")
	)
	(segment
		(start 310.330342 -234.592622)
		(end 310.061864 -234.324144)
		(width 0.14478)
		(layer "In2.Cu")
		(net "M_C_CPU0_SA_DQ<29>")
	)
	(segment
		(start 304.67173 -233.460036)
		(end 304.508662 -233.296968)
		(width 0.14478)
		(layer "In2.Cu")
		(net "M_C_CPU0_SA_DQ<29>")
	)
	(segment
		(start 303.952148 -233.237278)
		(end 303.952148 -233.296968)
		(width 0.14478)
		(layer "In2.Cu")
		(net "M_C_CPU0_SA_DQ<29>")
	)
	(segment
		(start 293.478204 -233.296968)
		(end 293.315136 -233.460036)
		(width 0.14478)
		(layer "In2.Cu")
		(net "M_C_CPU0_SA_DQ<29>")
	)
	(segment
		(start 299.256958 -232.447084)
		(end 299.256958 -232.383838)
		(width 0.14478)
		(layer "In2.Cu")
		(net "M_C_CPU0_SA_DQ<29>")
	)
	(segment
		(start 335.938114 -243.996718)
		(end 335.929732 -244.001544)
		(width 0.0889)
		(layer "In2.Cu")
		(net "M_C_CPU0_SA_DQ<29>")
	)
	(segment
		(start 294.7543 -233.07167)
		(end 294.591232 -233.234738)
		(width 0.14478)
		(layer "In2.Cu")
		(net "M_C_CPU0_SA_DQ<29>")
	)
	(segment
		(start 295.310814 -233.460036)
		(end 295.147746 -233.296968)
		(width 0.14478)
		(layer "In2.Cu")
		(net "M_C_CPU0_SA_DQ<29>")
	)
	(segment
		(start 297.367452 -233.460036)
		(end 297.153076 -233.460036)
		(width 0.14478)
		(layer "In2.Cu")
		(net "M_C_CPU0_SA_DQ<29>")
	)
	(segment
		(start 310.842152 -235.104432)
		(end 310.598566 -235.104432)
		(width 0.14478)
		(layer "In2.Cu")
		(net "M_C_CPU0_SA_DQ<29>")
	)
	(segment
		(start 324.396354 -243.30787)
		(end 324.396354 -243.08435)
		(width 0.0889)
		(layer "In2.Cu")
		(net "M_C_CPU0_SA_DQ<29>")
	)
	(segment
		(start 313.451494 -237.713774)
		(end 313.183016 -237.445296)
		(width 0.14478)
		(layer "In2.Cu")
		(net "M_C_CPU0_SA_DQ<29>")
	)
	(segment
		(start 332.178152 -243.996718)
		(end 332.16977 -244.001544)
		(width 0.0889)
		(layer "In2.Cu")
		(net "M_C_CPU0_SA_DQ<29>")
	)
	(segment
		(start 301.731934 -233.460036)
		(end 300.563788 -232.29189)
		(width 0.14478)
		(layer "In2.Cu")
		(net "M_C_CPU0_SA_DQ<29>")
	)
	(segment
		(start 324.078854 -242.76685)
		(end 323.906134 -242.76685)
		(width 0.0889)
		(layer "In2.Cu")
		(net "M_C_CPU0_SA_DQ<29>")
	)
	(segment
		(start 299.09389 -232.22077)
		(end 298.863512 -232.22077)
		(width 0.14478)
		(layer "In2.Cu")
		(net "M_C_CPU0_SA_DQ<29>")
	)
	(segment
		(start 315.13399 -239.39627)
		(end 314.743592 -239.005872)
		(width 0.14478)
		(layer "In2.Cu")
		(net "M_C_CPU0_SA_DQ<29>")
	)
	(segment
		(start 340.63813 -243.996718)
		(end 340.629748 -244.001544)
		(width 0.0889)
		(layer "In2.Cu")
		(net "M_C_CPU0_SA_DQ<29>")
	)
	(segment
		(start 312.671206 -236.933486)
		(end 312.402728 -236.665008)
		(width 0.14478)
		(layer "In2.Cu")
		(net "M_C_CPU0_SA_DQ<29>")
	)
	(segment
		(start 298.700444 -232.383838)
		(end 298.700444 -232.447084)
		(width 0.14478)
		(layer "In2.Cu")
		(net "M_C_CPU0_SA_DQ<29>")
	)
	(segment
		(start 294.197786 -233.860594)
		(end 294.034718 -233.697526)
		(width 0.14478)
		(layer "In2.Cu")
		(net "M_C_CPU0_SA_DQ<29>")
	)
	(segment
		(start 313.183016 -237.445296)
		(end 312.93943 -237.445296)
		(width 0.14478)
		(layer "In2.Cu")
		(net "M_C_CPU0_SA_DQ<29>")
	)
	(segment
		(start 306.852828 -232.447084)
		(end 306.852828 -232.378758)
		(width 0.14478)
		(layer "In2.Cu")
		(net "M_C_CPU0_SA_DQ<29>")
	)
	(segment
		(start 294.034718 -233.2228)
		(end 293.87165 -233.059732)
		(width 0.14478)
		(layer "In2.Cu")
		(net "M_C_CPU0_SA_DQ<29>")
	)
	(segment
		(start 304.508662 -233.237278)
		(end 304.345594 -233.07421)
		(width 0.14478)
		(layer "In2.Cu")
		(net "M_C_CPU0_SA_DQ<29>")
	)
	(segment
		(start 327.480168 -243.996464)
		(end 327.458324 -244.00891)
		(width 0.0889)
		(layer "In2.Cu")
		(net "M_C_CPU0_SA_DQ<29>")
	)
	(segment
		(start 312.670952 -236.948726)
		(end 312.671206 -236.933486)
		(width 0.14478)
		(layer "In2.Cu")
		(net "M_C_CPU0_SA_DQ<29>")
	)
	(segment
		(start 304.890932 -233.460036)
		(end 304.67173 -233.460036)
		(width 0.14478)
		(layer "In2.Cu")
		(net "M_C_CPU0_SA_DQ<29>")
	)
	(segment
		(start 308.442868 -232.381298)
		(end 308.2798 -232.21823)
		(width 0.14478)
		(layer "In2.Cu")
		(net "M_C_CPU0_SA_DQ<29>")
	)
	(segment
		(start 331.238098 -243.996718)
		(end 331.229716 -244.001544)
		(width 0.0889)
		(layer "In2.Cu")
		(net "M_C_CPU0_SA_DQ<29>")
	)
	(segment
		(start 309.818278 -234.324144)
		(end 309.5498 -234.055666)
		(width 0.14478)
		(layer "In2.Cu")
		(net "M_C_CPU0_SA_DQ<29>")
	)
	(segment
		(start 296.433494 -233.237278)
		(end 296.433494 -233.296968)
		(width 0.14478)
		(layer "In2.Cu")
		(net "M_C_CPU0_SA_DQ<29>")
	)
	(segment
		(start 307.886354 -232.381298)
		(end 307.886354 -232.447084)
		(width 0.14478)
		(layer "In2.Cu")
		(net "M_C_CPU0_SA_DQ<29>")
	)
	(segment
		(start 311.378854 -235.88472)
		(end 311.110376 -235.616242)
		(width 0.14478)
		(layer "In2.Cu")
		(net "M_C_CPU0_SA_DQ<29>")
	)
	(segment
		(start 342.152478 -244.001544)
		(end 342.144096 -243.996718)
		(width 0.0889)
		(layer "In2.Cu")
		(net "M_C_CPU0_SA_DQ<29>")
	)
	(segment
		(start 311.110376 -235.38815)
		(end 311.11063 -235.37291)
		(width 0.14478)
		(layer "In2.Cu")
		(net "M_C_CPU0_SA_DQ<29>")
	)
	(segment
		(start 298.217336 -232.610152)
		(end 297.367452 -233.460036)
		(width 0.14478)
		(layer "In2.Cu")
		(net "M_C_CPU0_SA_DQ<29>")
	)
	(segment
		(start 300.563788 -232.29189)
		(end 300.325536 -232.29189)
		(width 0.14478)
		(layer "In2.Cu")
		(net "M_C_CPU0_SA_DQ<29>")
	)
	(segment
		(start 310.061864 -234.324144)
		(end 309.818278 -234.324144)
		(width 0.14478)
		(layer "In2.Cu")
		(net "M_C_CPU0_SA_DQ<29>")
	)
	(segment
		(start 314.500006 -239.005872)
		(end 314.231528 -238.737394)
		(width 0.14478)
		(layer "In2.Cu")
		(net "M_C_CPU0_SA_DQ<29>")
	)
	(segment
		(start 309.5498 -233.827574)
		(end 309.550054 -233.812334)
		(width 0.14478)
		(layer "In2.Cu")
		(net "M_C_CPU0_SA_DQ<29>")
	)
	(segment
		(start 311.110376 -235.616242)
		(end 311.110376 -235.38815)
		(width 0.14478)
		(layer "In2.Cu")
		(net "M_C_CPU0_SA_DQ<29>")
	)
	(segment
		(start 311.890918 -236.153198)
		(end 311.62244 -235.88472)
		(width 0.14478)
		(layer "In2.Cu")
		(net "M_C_CPU0_SA_DQ<29>")
	)
	(segment
		(start 337.452462 -244.001544)
		(end 337.44408 -243.996718)
		(width 0.0889)
		(layer "In2.Cu")
		(net "M_C_CPU0_SA_DQ<29>")
	)
	(segment
		(start 310.330088 -234.835954)
		(end 310.330088 -234.607862)
		(width 0.14478)
		(layer "In2.Cu")
		(net "M_C_CPU0_SA_DQ<29>")
	)
	(segment
		(start 296.82694 -233.07421)
		(end 296.596562 -233.07421)
		(width 0.14478)
		(layer "In2.Cu")
		(net "M_C_CPU0_SA_DQ<29>")
	)
	(segment
		(start 293.87165 -233.059732)
		(end 293.641272 -233.059732)
		(width 0.14478)
		(layer "In2.Cu")
		(net "M_C_CPU0_SA_DQ<29>")
	)
	(segment
		(start 311.890664 -236.168438)
		(end 311.890918 -236.153198)
		(width 0.14478)
		(layer "In2.Cu")
		(net "M_C_CPU0_SA_DQ<29>")
	)
	(segment
		(start 299.256958 -232.383838)
		(end 299.09389 -232.22077)
		(width 0.14478)
		(layer "In2.Cu")
		(net "M_C_CPU0_SA_DQ<29>")
	)
	(segment
		(start 308.666134 -232.928414)
		(end 308.666134 -232.67035)
		(width 0.14478)
		(layer "In2.Cu")
		(net "M_C_CPU0_SA_DQ<29>")
	)
	(segment
		(start 304.115216 -233.07421)
		(end 303.952148 -233.237278)
		(width 0.14478)
		(layer "In2.Cu")
		(net "M_C_CPU0_SA_DQ<29>")
	)
	(segment
		(start 325.88454 -243.91493)
		(end 325.003414 -243.91493)
		(width 0.0889)
		(layer "In2.Cu")
		(net "M_C_CPU0_SA_DQ<29>")
	)
	(segment
		(start 343.271094 -243.674138)
		(end 343.425018 -243.939568)
		(width 0.0889)
		(layer "In2.Cu")
		(net "M_C_CPU0_SA_DQ<29>")
	)
	(segment
		(start 294.034718 -233.697526)
		(end 294.034718 -233.2228)
		(width 0.14478)
		(layer "In2.Cu")
		(net "M_C_CPU0_SA_DQ<29>")
	)
	(segment
		(start 302.003206 -233.460036)
		(end 301.731934 -233.460036)
		(width 0.14478)
		(layer "In2.Cu")
		(net "M_C_CPU0_SA_DQ<29>")
	)
	(segment
		(start 304.508662 -233.296968)
		(end 304.508662 -233.237278)
		(width 0.14478)
		(layer "In2.Cu")
		(net "M_C_CPU0_SA_DQ<29>")
	)
	(segment
		(start 332.752446 -244.001544)
		(end 332.744064 -243.996718)
		(width 0.0889)
		(layer "In2.Cu")
		(net "M_C_CPU0_SA_DQ<29>")
	)
	(segment
		(start 294.428164 -233.860594)
		(end 294.197786 -233.860594)
		(width 0.14478)
		(layer "In2.Cu")
		(net "M_C_CPU0_SA_DQ<29>")
	)
	(segment
		(start 296.990008 -233.296968)
		(end 296.990008 -233.237278)
		(width 0.14478)
		(layer "In2.Cu")
		(net "M_C_CPU0_SA_DQ<29>")
	)
	(segment
		(start 294.591232 -233.697526)
		(end 294.428164 -233.860594)
		(width 0.14478)
		(layer "In2.Cu")
		(net "M_C_CPU0_SA_DQ<29>")
	)
	(segment
		(start 302.55972 -233.08183)
		(end 302.329342 -233.08183)
		(width 0.14478)
		(layer "In2.Cu")
		(net "M_C_CPU0_SA_DQ<29>")
	)
	(segment
		(start 311.11063 -235.37291)
		(end 310.842152 -235.104432)
		(width 0.14478)
		(layer "In2.Cu")
		(net "M_C_CPU0_SA_DQ<29>")
	)
	(segment
		(start 306.68976 -232.21569)
		(end 306.459382 -232.21569)
		(width 0.14478)
		(layer "In2.Cu")
		(net "M_C_CPU0_SA_DQ<29>")
	)
	(segment
		(start 323.906134 -242.76685)
		(end 319.11036 -242.76685)
		(width 0.14478)
		(layer "In2.Cu")
		(net "M_C_CPU0_SA_DQ<29>")
	)
	(segment
		(start 315.73978 -239.39627)
		(end 315.13399 -239.39627)
		(width 0.14478)
		(layer "In2.Cu")
		(net "M_C_CPU0_SA_DQ<29>")
	)
	(segment
		(start 303.952148 -233.296968)
		(end 303.78908 -233.460036)
		(width 0.14478)
		(layer "In2.Cu")
		(net "M_C_CPU0_SA_DQ<29>")
	)
	(segment
		(start 341.212424 -244.001544)
		(end 341.204042 -243.996718)
		(width 0.0889)
		(layer "In2.Cu")
		(net "M_C_CPU0_SA_DQ<29>")
	)
	(segment
		(start 302.722788 -233.244898)
		(end 302.55972 -233.08183)
		(width 0.14478)
		(layer "In2.Cu")
		(net "M_C_CPU0_SA_DQ<29>")
	)
	(segment
		(start 296.596562 -233.07421)
		(end 296.433494 -233.237278)
		(width 0.14478)
		(layer "In2.Cu")
		(net "M_C_CPU0_SA_DQ<29>")
	)
	(segment
		(start 314.231528 -238.737394)
		(end 314.231528 -238.509302)
		(width 0.14478)
		(layer "In2.Cu")
		(net "M_C_CPU0_SA_DQ<29>")
	)
	(segment
		(start 293.641272 -233.059732)
		(end 293.478204 -233.2228)
		(width 0.14478)
		(layer "In2.Cu")
		(net "M_C_CPU0_SA_DQ<29>")
	)
	(segment
		(start 302.885856 -233.460036)
		(end 302.722788 -233.296968)
		(width 0.14478)
		(layer "In2.Cu")
		(net "M_C_CPU0_SA_DQ<29>")
	)
	(segment
		(start 312.159142 -236.665008)
		(end 311.890664 -236.39653)
		(width 0.14478)
		(layer "In2.Cu")
		(net "M_C_CPU0_SA_DQ<29>")
	)
	(segment
		(start 312.402728 -236.665008)
		(end 312.159142 -236.665008)
		(width 0.14478)
		(layer "In2.Cu")
		(net "M_C_CPU0_SA_DQ<29>")
	)
	(segment
		(start 298.863512 -232.22077)
		(end 298.700444 -232.383838)
		(width 0.14478)
		(layer "In2.Cu")
		(net "M_C_CPU0_SA_DQ<29>")
	)
	(segment
		(start 294.984678 -233.07167)
		(end 294.7543 -233.07167)
		(width 0.14478)
		(layer "In2.Cu")
		(net "M_C_CPU0_SA_DQ<29>")
	)
	(segment
		(start 326.19696 -244.014244)
		(end 326.14235 -243.983256)
		(width 0.0889)
		(layer "In2.Cu")
		(net "M_C_CPU0_SA_DQ<29>")
	)
	(segment
		(start 333.6925 -244.001544)
		(end 333.684118 -243.996718)
		(width 0.0889)
		(layer "In2.Cu")
		(net "M_C_CPU0_SA_DQ<29>")
	)
	(segment
		(start 324.396354 -243.08435)
		(end 324.078854 -242.76685)
		(width 0.0889)
		(layer "In2.Cu")
		(net "M_C_CPU0_SA_DQ<29>")
	)
	(segment
		(start 293.315136 -233.460036)
		(end 292.705028 -233.460036)
		(width 0.14478)
		(layer "In2.Cu")
		(net "M_C_CPU0_SA_DQ<29>")
	)
	(segment
		(start 293.478204 -233.2228)
		(end 293.478204 -233.296968)
		(width 0.14478)
		(layer "In2.Cu")
		(net "M_C_CPU0_SA_DQ<29>")
	)
	(segment
		(start 343.425018 -243.939568)
		(end 343.402666 -244.02288)
		(width 0.0889)
		(layer "In2.Cu")
		(net "M_C_CPU0_SA_DQ<29>")
	)
	(segment
		(start 314.231528 -238.509302)
		(end 314.231782 -238.494062)
		(width 0.14478)
		(layer "In2.Cu")
		(net "M_C_CPU0_SA_DQ<29>")
	)
	(segment
		(start 300.325536 -232.29189)
		(end 300.007274 -232.610152)
		(width 0.14478)
		(layer "In2.Cu")
		(net "M_C_CPU0_SA_DQ<29>")
	)
	(segment
		(start 310.330088 -234.607862)
		(end 310.330342 -234.592622)
		(width 0.14478)
		(layer "In2.Cu")
		(net "M_C_CPU0_SA_DQ<29>")
	)
	(segment
		(start 306.296314 -232.447084)
		(end 306.133246 -232.610152)
		(width 0.14478)
		(layer "In2.Cu")
		(net "M_C_CPU0_SA_DQ<29>")
	)
	(segment
		(start 296.270426 -233.460036)
		(end 295.310814 -233.460036)
		(width 0.14478)
		(layer "In2.Cu")
		(net "M_C_CPU0_SA_DQ<29>")
	)
	(segment
		(start 339.698076 -243.996718)
		(end 339.689694 -244.001544)
		(width 0.0889)
		(layer "In2.Cu")
		(net "M_C_CPU0_SA_DQ<29>")
	)
	(segment
		(start 308.2798 -232.21823)
		(end 308.049422 -232.21823)
		(width 0.14478)
		(layer "In2.Cu")
		(net "M_C_CPU0_SA_DQ<29>")
	)
	(segment
		(start 295.147746 -233.296968)
		(end 295.147746 -233.234738)
		(width 0.14478)
		(layer "In2.Cu")
		(net "M_C_CPU0_SA_DQ<29>")
	)
	(segment
		(start 307.723286 -232.610152)
		(end 307.015896 -232.610152)
		(width 0.14478)
		(layer "In2.Cu")
		(net "M_C_CPU0_SA_DQ<29>")
	)
	(segment
		(start 302.329342 -233.08183)
		(end 302.166274 -233.244898)
		(width 0.14478)
		(layer "In2.Cu")
		(net "M_C_CPU0_SA_DQ<29>")
	)
	(segment
		(start 298.700444 -232.447084)
		(end 298.537376 -232.610152)
		(width 0.14478)
		(layer "In2.Cu")
		(net "M_C_CPU0_SA_DQ<29>")
	)
	(segment
		(start 313.45124 -237.957106)
		(end 313.45124 -237.729014)
		(width 0.14478)
		(layer "In2.Cu")
		(net "M_C_CPU0_SA_DQ<29>")
	)
	(segment
		(start 302.166274 -233.296968)
		(end 302.003206 -233.460036)
		(width 0.14478)
		(layer "In2.Cu")
		(net "M_C_CPU0_SA_DQ<29>")
	)
	(segment
		(start 312.670952 -237.176818)
		(end 312.670952 -236.948726)
		(width 0.14478)
		(layer "In2.Cu")
		(net "M_C_CPU0_SA_DQ<29>")
	)
	(segment
		(start 302.166274 -233.244898)
		(end 302.166274 -233.296968)
		(width 0.14478)
		(layer "In2.Cu")
		(net "M_C_CPU0_SA_DQ<29>")
	)
	(segment
		(start 313.45124 -237.729014)
		(end 313.451494 -237.713774)
		(width 0.14478)
		(layer "In2.Cu")
		(net "M_C_CPU0_SA_DQ<29>")
	)
	(segment
		(start 312.93943 -237.445296)
		(end 312.670952 -237.176818)
		(width 0.14478)
		(layer "In2.Cu")
		(net "M_C_CPU0_SA_DQ<29>")
	)
	(segment
		(start 327.50633 -243.981478)
		(end 327.480168 -243.996464)
		(width 0.0889)
		(layer "In2.Cu")
		(net "M_C_CPU0_SA_DQ<29>")
	)
	(segment
		(start 296.990008 -233.237278)
		(end 296.82694 -233.07421)
		(width 0.14478)
		(layer "In2.Cu")
		(net "M_C_CPU0_SA_DQ<29>")
	)
	(segment
		(start 299.420026 -232.610152)
		(end 299.256958 -232.447084)
		(width 0.14478)
		(layer "In2.Cu")
		(net "M_C_CPU0_SA_DQ<29>")
	)
	(segment
		(start 311.62244 -235.88472)
		(end 311.378854 -235.88472)
		(width 0.14478)
		(layer "In2.Cu")
		(net "M_C_CPU0_SA_DQ<29>")
	)
	(segment
		(start 297.153076 -233.460036)
		(end 296.990008 -233.296968)
		(width 0.14478)
		(layer "In2.Cu")
		(net "M_C_CPU0_SA_DQ<29>")
	)
	(segment
		(start 309.5498 -234.055666)
		(end 309.5498 -233.827574)
		(width 0.14478)
		(layer "In2.Cu")
		(net "M_C_CPU0_SA_DQ<29>")
	)
	(segment
		(start 313.963304 -238.225584)
		(end 313.719718 -238.225584)
		(width 0.14478)
		(layer "In2.Cu")
		(net "M_C_CPU0_SA_DQ<29>")
	)
	(segment
		(start 300.007274 -232.610152)
		(end 299.420026 -232.610152)
		(width 0.14478)
		(layer "In2.Cu")
		(net "M_C_CPU0_SA_DQ<29>")
	)
	(segment
		(start 295.147746 -233.234738)
		(end 294.984678 -233.07167)
		(width 0.14478)
		(layer "In2.Cu")
		(net "M_C_CPU0_SA_DQ<29>")
	)
	(segment
		(start 325.003414 -243.91493)
		(end 324.396354 -243.30787)
		(width 0.0889)
		(layer "In2.Cu")
		(net "M_C_CPU0_SA_DQ<29>")
	)
	(segment
		(start 305.740816 -232.610152)
		(end 304.890932 -233.460036)
		(width 0.14478)
		(layer "In2.Cu")
		(net "M_C_CPU0_SA_DQ<29>")
	)
	(segment
		(start 294.591232 -233.234738)
		(end 294.591232 -233.697526)
		(width 0.14478)
		(layer "In2.Cu")
		(net "M_C_CPU0_SA_DQ<29>")
	)
	(segment
		(start 308.442868 -232.447084)
		(end 308.442868 -232.381298)
		(width 0.14478)
		(layer "In2.Cu")
		(net "M_C_CPU0_SA_DQ<29>")
	)
	(segment
		(start 306.852828 -232.378758)
		(end 306.68976 -232.21569)
		(width 0.14478)
		(layer "In2.Cu")
		(net "M_C_CPU0_SA_DQ<29>")
	)
	(segment
		(start 311.890664 -236.39653)
		(end 311.890664 -236.168438)
		(width 0.14478)
		(layer "In2.Cu")
		(net "M_C_CPU0_SA_DQ<29>")
	)
	(segment
		(start 302.722788 -233.296968)
		(end 302.722788 -233.244898)
		(width 0.14478)
		(layer "In2.Cu")
		(net "M_C_CPU0_SA_DQ<29>")
	)
	(segment
		(start 303.78908 -233.460036)
		(end 302.885856 -233.460036)
		(width 0.14478)
		(layer "In2.Cu")
		(net "M_C_CPU0_SA_DQ<29>")
	)
	(segment
		(start 308.049422 -232.21823)
		(end 307.886354 -232.381298)
		(width 0.14478)
		(layer "In2.Cu")
		(net "M_C_CPU0_SA_DQ<29>")
	)
	(segment
		(start 307.886354 -232.447084)
		(end 307.723286 -232.610152)
		(width 0.14478)
		(layer "In2.Cu")
		(net "M_C_CPU0_SA_DQ<29>")
	)
	(segment
		(start 328.41819 -243.996718)
		(end 328.409808 -244.001544)
		(width 0.0889)
		(layer "In2.Cu")
		(net "M_C_CPU0_SA_DQ<29>")
	)
	(segment
		(start 306.133246 -232.610152)
		(end 305.740816 -232.610152)
		(width 0.14478)
		(layer "In2.Cu")
		(net "M_C_CPU0_SA_DQ<29>")
	)
	(segment
		(start 310.598566 -235.104432)
		(end 310.330088 -234.835954)
		(width 0.14478)
		(layer "In2.Cu")
		(net "M_C_CPU0_SA_DQ<29>")
	)
	(segment
		(start 328.992484 -244.001544)
		(end 328.984102 -243.996718)
		(width 0.0889)
		(layer "In2.Cu")
		(net "M_C_CPU0_SA_DQ<29>")
	)
	(segment
		(start 298.537376 -232.610152)
		(end 298.217336 -232.610152)
		(width 0.14478)
		(layer "In2.Cu")
		(net "M_C_CPU0_SA_DQ<29>")
	)
	(segment
		(start 308.666134 -232.67035)
		(end 308.442868 -232.447084)
		(width 0.14478)
		(layer "In2.Cu")
		(net "M_C_CPU0_SA_DQ<29>")
	)
	(segment
		(start 319.11036 -242.76685)
		(end 315.73978 -239.39627)
		(width 0.14478)
		(layer "In2.Cu")
		(net "M_C_CPU0_SA_DQ<29>")
	)
	(segment
		(start 327.10755 -243.996718)
		(end 327.078086 -243.979446)
		(width 0.0889)
		(layer "In2.Cu")
		(net "M_C_CPU0_SA_DQ<29>")
	)
	(segment
		(start 309.550054 -233.812334)
		(end 308.666134 -232.928414)
		(width 0.14478)
		(layer "In2.Cu")
		(net "M_C_CPU0_SA_DQ<29>")
	)
	(arc
		(start 343.402666 -244.02288)
		(mid 343.240477 -244.045615)
		(end 343.08415 -243.996718)
		(width 0.0889)
		(layer "In2.Cu")
		(net "M_C_CPU0_SA_DQ<29>")
	)
	(arc
		(start 343.08415 -243.996718)
		(mid 342.801194 -243.920541)
		(end 342.518238 -243.996718)
		(width 0.0889)
		(layer "In2.Cu")
		(net "M_C_CPU0_SA_DQ<29>")
	)
	(arc
		(start 331.229716 -244.001544)
		(mid 331.046208 -244.047038)
		(end 330.863956 -243.996718)
		(width 0.0889)
		(layer "In2.Cu")
		(net "M_C_CPU0_SA_DQ<29>")
	)
	(arc
		(start 330.863956 -243.996718)
		(mid 330.581 -243.920541)
		(end 330.298044 -243.996718)
		(width 0.0889)
		(layer "In2.Cu")
		(net "M_C_CPU0_SA_DQ<29>")
	)
	(arc
		(start 327.458324 -244.00891)
		(mid 327.281396 -244.046738)
		(end 327.10755 -243.996718)
		(width 0.0889)
		(layer "In2.Cu")
		(net "M_C_CPU0_SA_DQ<29>")
	)
	(arc
		(start 328.984102 -243.996718)
		(mid 328.701146 -243.920541)
		(end 328.41819 -243.996718)
		(width 0.0889)
		(layer "In2.Cu")
		(net "M_C_CPU0_SA_DQ<29>")
	)
	(arc
		(start 327.078086 -243.979446)
		(mid 326.806666 -243.919769)
		(end 326.539606 -243.996718)
		(width 0.0889)
		(layer "In2.Cu")
		(net "M_C_CPU0_SA_DQ<29>")
	)
	(arc
		(start 332.16977 -244.001544)
		(mid 331.986262 -244.047038)
		(end 331.80401 -243.996718)
		(width 0.0889)
		(layer "In2.Cu")
		(net "M_C_CPU0_SA_DQ<29>")
	)
	(arc
		(start 326.14235 -243.983256)
		(mid 326.017892 -243.932304)
		(end 325.88454 -243.91493)
		(width 0.0889)
		(layer "In2.Cu")
		(net "M_C_CPU0_SA_DQ<29>")
	)
	(arc
		(start 334.05826 -243.996718)
		(mid 333.876009 -244.047068)
		(end 333.6925 -244.001544)
		(width 0.0889)
		(layer "In2.Cu")
		(net "M_C_CPU0_SA_DQ<29>")
	)
	(arc
		(start 331.80401 -243.996718)
		(mid 331.521054 -243.920541)
		(end 331.238098 -243.996718)
		(width 0.0889)
		(layer "In2.Cu")
		(net "M_C_CPU0_SA_DQ<29>")
	)
	(arc
		(start 334.99806 -243.996718)
		(mid 334.811116 -244.046973)
		(end 334.624172 -243.996718)
		(width 0.0889)
		(layer "In2.Cu")
		(net "M_C_CPU0_SA_DQ<29>")
	)
	(arc
		(start 334.624172 -243.996718)
		(mid 334.341216 -243.920541)
		(end 334.05826 -243.996718)
		(width 0.0889)
		(layer "In2.Cu")
		(net "M_C_CPU0_SA_DQ<29>")
	)
	(arc
		(start 328.409808 -244.001544)
		(mid 328.2263 -244.047038)
		(end 328.044048 -243.996718)
		(width 0.0889)
		(layer "In2.Cu")
		(net "M_C_CPU0_SA_DQ<29>")
	)
	(arc
		(start 338.384134 -243.996718)
		(mid 338.101178 -243.920541)
		(end 337.818222 -243.996718)
		(width 0.0889)
		(layer "In2.Cu")
		(net "M_C_CPU0_SA_DQ<29>")
	)
	(arc
		(start 333.684118 -243.996718)
		(mid 333.401162 -243.920541)
		(end 333.118206 -243.996718)
		(width 0.0889)
		(layer "In2.Cu")
		(net "M_C_CPU0_SA_DQ<29>")
	)
	(arc
		(start 340.629748 -244.001544)
		(mid 340.44624 -244.047038)
		(end 340.263988 -243.996718)
		(width 0.0889)
		(layer "In2.Cu")
		(net "M_C_CPU0_SA_DQ<29>")
	)
	(arc
		(start 342.144096 -243.996718)
		(mid 341.86114 -243.920541)
		(end 341.578184 -243.996718)
		(width 0.0889)
		(layer "In2.Cu")
		(net "M_C_CPU0_SA_DQ<29>")
	)
	(arc
		(start 330.298044 -243.996718)
		(mid 330.1111 -244.046973)
		(end 329.924156 -243.996718)
		(width 0.0889)
		(layer "In2.Cu")
		(net "M_C_CPU0_SA_DQ<29>")
	)
	(arc
		(start 339.689694 -244.001544)
		(mid 339.506186 -244.047038)
		(end 339.323934 -243.996718)
		(width 0.0889)
		(layer "In2.Cu")
		(net "M_C_CPU0_SA_DQ<29>")
	)
	(arc
		(start 342.518238 -243.996718)
		(mid 342.335987 -244.047068)
		(end 342.152478 -244.001544)
		(width 0.0889)
		(layer "In2.Cu")
		(net "M_C_CPU0_SA_DQ<29>")
	)
	(arc
		(start 326.539606 -243.996718)
		(mid 326.370419 -244.047126)
		(end 326.19696 -244.014244)
		(width 0.0889)
		(layer "In2.Cu")
		(net "M_C_CPU0_SA_DQ<29>")
	)
	(arc
		(start 341.204042 -243.996718)
		(mid 340.921086 -243.920541)
		(end 340.63813 -243.996718)
		(width 0.0889)
		(layer "In2.Cu")
		(net "M_C_CPU0_SA_DQ<29>")
	)
	(arc
		(start 335.929732 -244.001544)
		(mid 335.746224 -244.047038)
		(end 335.563972 -243.996718)
		(width 0.0889)
		(layer "In2.Cu")
		(net "M_C_CPU0_SA_DQ<29>")
	)
	(arc
		(start 340.263988 -243.996718)
		(mid 339.981032 -243.920541)
		(end 339.698076 -243.996718)
		(width 0.0889)
		(layer "In2.Cu")
		(net "M_C_CPU0_SA_DQ<29>")
	)
	(arc
		(start 328.044048 -243.996718)
		(mid 327.777118 -243.920769)
		(end 327.50633 -243.981478)
		(width 0.0889)
		(layer "In2.Cu")
		(net "M_C_CPU0_SA_DQ<29>")
	)
	(arc
		(start 336.504026 -243.996718)
		(mid 336.22107 -243.920541)
		(end 335.938114 -243.996718)
		(width 0.0889)
		(layer "In2.Cu")
		(net "M_C_CPU0_SA_DQ<29>")
	)
	(arc
		(start 339.323934 -243.996718)
		(mid 339.040978 -243.920541)
		(end 338.758022 -243.996718)
		(width 0.0889)
		(layer "In2.Cu")
		(net "M_C_CPU0_SA_DQ<29>")
	)
	(arc
		(start 333.118206 -243.996718)
		(mid 332.935955 -244.047068)
		(end 332.752446 -244.001544)
		(width 0.0889)
		(layer "In2.Cu")
		(net "M_C_CPU0_SA_DQ<29>")
	)
	(arc
		(start 335.563972 -243.996718)
		(mid 335.281016 -243.920541)
		(end 334.99806 -243.996718)
		(width 0.0889)
		(layer "In2.Cu")
		(net "M_C_CPU0_SA_DQ<29>")
	)
	(arc
		(start 329.924156 -243.996718)
		(mid 329.6412 -243.920541)
		(end 329.358244 -243.996718)
		(width 0.0889)
		(layer "In2.Cu")
		(net "M_C_CPU0_SA_DQ<29>")
	)
	(arc
		(start 341.578184 -243.996718)
		(mid 341.395933 -244.047068)
		(end 341.212424 -244.001544)
		(width 0.0889)
		(layer "In2.Cu")
		(net "M_C_CPU0_SA_DQ<29>")
	)
	(arc
		(start 337.44408 -243.996718)
		(mid 337.161124 -243.920541)
		(end 336.878168 -243.996718)
		(width 0.0889)
		(layer "In2.Cu")
		(net "M_C_CPU0_SA_DQ<29>")
	)
	(arc
		(start 338.758022 -243.996718)
		(mid 338.571078 -244.046973)
		(end 338.384134 -243.996718)
		(width 0.0889)
		(layer "In2.Cu")
		(net "M_C_CPU0_SA_DQ<29>")
	)
	(arc
		(start 337.818222 -243.996718)
		(mid 337.635971 -244.047068)
		(end 337.452462 -244.001544)
		(width 0.0889)
		(layer "In2.Cu")
		(net "M_C_CPU0_SA_DQ<29>")
	)
	(arc
		(start 329.358244 -243.996718)
		(mid 329.175993 -244.047068)
		(end 328.992484 -244.001544)
		(width 0.0889)
		(layer "In2.Cu")
		(net "M_C_CPU0_SA_DQ<29>")
	)
	(arc
		(start 332.744064 -243.996718)
		(mid 332.461108 -243.920541)
		(end 332.178152 -243.996718)
		(width 0.0889)
		(layer "In2.Cu")
		(net "M_C_CPU0_SA_DQ<29>")
	)
	(arc
		(start 336.869786 -244.001544)
		(mid 336.686278 -244.047038)
		(end 336.504026 -243.996718)
		(width 0.0889)
		(layer "In2.Cu")
		(net "M_C_CPU0_SA_DQ<29>")
	)
	(segment
		(start 342.327992 -243.13007)
		(end 341.86114 -242.864132)
		(width 0.10668)
		(layer "F.Cu")
		(net "M_C_CPU0_SA_DQ<28>")
	)
	(segment
		(start 313.999626 -236.588046)
		(end 313.914028 -236.673644)
		(width 0.14478)
		(layer "In2.Cu")
		(net "M_C_CPU0_SA_DQ<28>")
	)
	(segment
		(start 310.533796 -233.524044)
		(end 310.370474 -233.360722)
		(width 0.14478)
		(layer "In2.Cu")
		(net "M_C_CPU0_SA_DQ<28>")
	)
	(segment
		(start 330.402438 -243.191538)
		(end 330.394056 -243.186712)
		(width 0.0889)
		(layer "In2.Cu")
		(net "M_C_CPU0_SA_DQ<28>")
	)
	(segment
		(start 310.370474 -233.360722)
		(end 310.370728 -233.130598)
		(width 0.14478)
		(layer "In2.Cu")
		(net "M_C_CPU0_SA_DQ<28>")
	)
	(segment
		(start 333.588106 -243.186712)
		(end 333.579724 -243.191538)
		(width 0.0889)
		(layer "In2.Cu")
		(net "M_C_CPU0_SA_DQ<28>")
	)
	(segment
		(start 312.732674 -235.722922)
		(end 312.732928 -235.492798)
		(width 0.14478)
		(layer "In2.Cu")
		(net "M_C_CPU0_SA_DQ<28>")
	)
	(segment
		(start 310.456326 -233.045)
		(end 310.456326 -232.814368)
		(width 0.14478)
		(layer "In2.Cu")
		(net "M_C_CPU0_SA_DQ<28>")
	)
	(segment
		(start 331.342492 -243.191538)
		(end 331.33411 -243.186712)
		(width 0.0889)
		(layer "In2.Cu")
		(net "M_C_CPU0_SA_DQ<28>")
	)
	(segment
		(start 315.094874 -238.085122)
		(end 315.095128 -237.854998)
		(width 0.14478)
		(layer "In2.Cu")
		(net "M_C_CPU0_SA_DQ<28>")
	)
	(segment
		(start 313.605926 -235.963968)
		(end 313.442858 -235.8009)
		(width 0.14478)
		(layer "In2.Cu")
		(net "M_C_CPU0_SA_DQ<28>")
	)
	(segment
		(start 314.701428 -237.461044)
		(end 314.470796 -237.461044)
		(width 0.14478)
		(layer "In2.Cu")
		(net "M_C_CPU0_SA_DQ<28>")
	)
	(segment
		(start 309.668926 -232.026968)
		(end 308.552088 -230.91013)
		(width 0.14478)
		(layer "In2.Cu")
		(net "M_C_CPU0_SA_DQ<28>")
	)
	(segment
		(start 313.914028 -236.673644)
		(end 313.683396 -236.673644)
		(width 0.14478)
		(layer "In2.Cu")
		(net "M_C_CPU0_SA_DQ<28>")
	)
	(segment
		(start 304.365914 -231.976422)
		(end 304.365914 -231.923082)
		(width 0.14478)
		(layer "In2.Cu")
		(net "M_C_CPU0_SA_DQ<28>")
	)
	(segment
		(start 329.828144 -243.186712)
		(end 329.819762 -243.191538)
		(width 0.0889)
		(layer "In2.Cu")
		(net "M_C_CPU0_SA_DQ<28>")
	)
	(segment
		(start 313.126628 -235.886244)
		(end 312.895996 -235.886244)
		(width 0.14478)
		(layer "In2.Cu")
		(net "M_C_CPU0_SA_DQ<28>")
	)
	(segment
		(start 294.363648 -232.14457)
		(end 294.13327 -232.14457)
		(width 0.14478)
		(layer "In2.Cu")
		(net "M_C_CPU0_SA_DQ<28>")
	)
	(segment
		(start 315.017658 -237.3757)
		(end 314.787026 -237.375446)
		(width 0.14478)
		(layer "In2.Cu")
		(net "M_C_CPU0_SA_DQ<28>")
	)
	(segment
		(start 298.412916 -230.919782)
		(end 297.310048 -232.02265)
		(width 0.14478)
		(layer "In2.Cu")
		(net "M_C_CPU0_SA_DQ<28>")
	)
	(segment
		(start 312.108596 -235.098844)
		(end 311.945274 -234.935522)
		(width 0.14478)
		(layer "In2.Cu")
		(net "M_C_CPU0_SA_DQ<28>")
	)
	(segment
		(start 309.746396 -232.736644)
		(end 309.583074 -232.573322)
		(width 0.14478)
		(layer "In2.Cu")
		(net "M_C_CPU0_SA_DQ<28>")
	)
	(segment
		(start 314.393326 -236.982)
		(end 314.393326 -236.751368)
		(width 0.14478)
		(layer "In2.Cu")
		(net "M_C_CPU0_SA_DQ<28>")
	)
	(segment
		(start 326.029574 -242.98783)
		(end 325.656194 -242.98783)
		(width 0.0889)
		(layer "In2.Cu")
		(net "M_C_CPU0_SA_DQ<28>")
	)
	(segment
		(start 311.945528 -234.705398)
		(end 312.031126 -234.6198)
		(width 0.14478)
		(layer "In2.Cu")
		(net "M_C_CPU0_SA_DQ<28>")
	)
	(segment
		(start 312.655458 -235.0135)
		(end 312.424826 -235.013246)
		(width 0.14478)
		(layer "In2.Cu")
		(net "M_C_CPU0_SA_DQ<28>")
	)
	(segment
		(start 294.526716 -231.918002)
		(end 294.526716 -231.981502)
		(width 0.14478)
		(layer "In2.Cu")
		(net "M_C_CPU0_SA_DQ<28>")
	)
	(segment
		(start 310.293258 -232.6513)
		(end 310.062626 -232.651046)
		(width 0.14478)
		(layer "In2.Cu")
		(net "M_C_CPU0_SA_DQ<28>")
	)
	(segment
		(start 311.637426 -234.225846)
		(end 311.551828 -234.311444)
		(width 0.14478)
		(layer "In2.Cu")
		(net "M_C_CPU0_SA_DQ<28>")
	)
	(segment
		(start 315.180726 -237.538768)
		(end 315.017658 -237.3757)
		(width 0.14478)
		(layer "In2.Cu")
		(net "M_C_CPU0_SA_DQ<28>")
	)
	(segment
		(start 312.732928 -235.492798)
		(end 312.818526 -235.4072)
		(width 0.14478)
		(layer "In2.Cu")
		(net "M_C_CPU0_SA_DQ<28>")
	)
	(segment
		(start 294.13327 -232.14457)
		(end 293.970202 -231.981502)
		(width 0.14478)
		(layer "In2.Cu")
		(net "M_C_CPU0_SA_DQ<28>")
	)
	(segment
		(start 334.52816 -243.186712)
		(end 334.519778 -243.191538)
		(width 0.0889)
		(layer "In2.Cu")
		(net "M_C_CPU0_SA_DQ<28>")
	)
	(segment
		(start 312.339228 -235.098844)
		(end 312.108596 -235.098844)
		(width 0.14478)
		(layer "In2.Cu")
		(net "M_C_CPU0_SA_DQ<28>")
	)
	(segment
		(start 315.488828 -238.248444)
		(end 315.258196 -238.248444)
		(width 0.14478)
		(layer "In2.Cu")
		(net "M_C_CPU0_SA_DQ<28>")
	)
	(segment
		(start 315.095128 -237.854998)
		(end 315.180726 -237.7694)
		(width 0.14478)
		(layer "In2.Cu")
		(net "M_C_CPU0_SA_DQ<28>")
	)
	(segment
		(start 338.288122 -243.186712)
		(end 338.27974 -243.191538)
		(width 0.0889)
		(layer "In2.Cu")
		(net "M_C_CPU0_SA_DQ<28>")
	)
	(segment
		(start 312.818526 -235.176568)
		(end 312.655458 -235.0135)
		(width 0.14478)
		(layer "In2.Cu")
		(net "M_C_CPU0_SA_DQ<28>")
	)
	(segment
		(start 293.970202 -231.593898)
		(end 293.807134 -231.43083)
		(width 0.14478)
		(layer "In2.Cu")
		(net "M_C_CPU0_SA_DQ<28>")
	)
	(segment
		(start 335.102454 -243.191538)
		(end 335.094072 -243.186712)
		(width 0.0889)
		(layer "In2.Cu")
		(net "M_C_CPU0_SA_DQ<28>")
	)
	(segment
		(start 326.145906 -243.104162)
		(end 326.029574 -242.98783)
		(width 0.0889)
		(layer "In2.Cu")
		(net "M_C_CPU0_SA_DQ<28>")
	)
	(segment
		(start 315.574426 -238.162846)
		(end 315.488828 -238.248444)
		(width 0.14478)
		(layer "In2.Cu")
		(net "M_C_CPU0_SA_DQ<28>")
	)
	(segment
		(start 311.551828 -234.311444)
		(end 311.321196 -234.311444)
		(width 0.14478)
		(layer "In2.Cu")
		(net "M_C_CPU0_SA_DQ<28>")
	)
	(segment
		(start 293.020242 -232.14457)
		(end 292.857174 -231.981502)
		(width 0.14478)
		(layer "In2.Cu")
		(net "M_C_CPU0_SA_DQ<28>")
	)
	(segment
		(start 312.895996 -235.886244)
		(end 312.732674 -235.722922)
		(width 0.14478)
		(layer "In2.Cu")
		(net "M_C_CPU0_SA_DQ<28>")
	)
	(segment
		(start 312.031126 -234.389168)
		(end 311.868058 -234.2261)
		(width 0.14478)
		(layer "In2.Cu")
		(net "M_C_CPU0_SA_DQ<28>")
	)
	(segment
		(start 315.258196 -238.248444)
		(end 315.094874 -238.085122)
		(width 0.14478)
		(layer "In2.Cu")
		(net "M_C_CPU0_SA_DQ<28>")
	)
	(segment
		(start 294.526716 -231.981502)
		(end 294.363648 -232.14457)
		(width 0.14478)
		(layer "In2.Cu")
		(net "M_C_CPU0_SA_DQ<28>")
	)
	(segment
		(start 308.552088 -230.91013)
		(end 306.13604 -230.91013)
		(width 0.14478)
		(layer "In2.Cu")
		(net "M_C_CPU0_SA_DQ<28>")
	)
	(segment
		(start 314.787026 -237.375446)
		(end 314.701428 -237.461044)
		(width 0.14478)
		(layer "In2.Cu")
		(net "M_C_CPU0_SA_DQ<28>")
	)
	(segment
		(start 315.805058 -238.1631)
		(end 315.574426 -238.162846)
		(width 0.14478)
		(layer "In2.Cu")
		(net "M_C_CPU0_SA_DQ<28>")
	)
	(segment
		(start 341.86114 -242.864132)
		(end 342.015064 -243.129562)
		(width 0.0889)
		(layer "In2.Cu")
		(net "M_C_CPU0_SA_DQ<28>")
	)
	(segment
		(start 309.583074 -232.573322)
		(end 309.583328 -232.343198)
		(width 0.14478)
		(layer "In2.Cu")
		(net "M_C_CPU0_SA_DQ<28>")
	)
	(segment
		(start 310.764428 -233.524044)
		(end 310.533796 -233.524044)
		(width 0.14478)
		(layer "In2.Cu")
		(net "M_C_CPU0_SA_DQ<28>")
	)
	(segment
		(start 314.393326 -236.751368)
		(end 314.230258 -236.5883)
		(width 0.14478)
		(layer "In2.Cu")
		(net "M_C_CPU0_SA_DQ<28>")
	)
	(segment
		(start 304.75936 -232.13949)
		(end 304.528982 -232.13949)
		(width 0.14478)
		(layer "In2.Cu")
		(net "M_C_CPU0_SA_DQ<28>")
	)
	(segment
		(start 326.647302 -243.194332)
		(end 326.585072 -243.16182)
		(width 0.0889)
		(layer "In2.Cu")
		(net "M_C_CPU0_SA_DQ<28>")
	)
	(segment
		(start 313.442858 -235.8009)
		(end 313.212226 -235.800646)
		(width 0.14478)
		(layer "In2.Cu")
		(net "M_C_CPU0_SA_DQ<28>")
	)
	(segment
		(start 323.895974 -241.82959)
		(end 319.471548 -241.82959)
		(width 0.14478)
		(layer "In2.Cu")
		(net "M_C_CPU0_SA_DQ<28>")
	)
	(segment
		(start 313.520074 -236.510322)
		(end 313.520328 -236.280198)
		(width 0.14478)
		(layer "In2.Cu")
		(net "M_C_CPU0_SA_DQ<28>")
	)
	(segment
		(start 314.307728 -237.067598)
		(end 314.393326 -236.982)
		(width 0.14478)
		(layer "In2.Cu")
		(net "M_C_CPU0_SA_DQ<28>")
	)
	(segment
		(start 327.021952 -243.178076)
		(end 327.00722 -243.186712)
		(width 0.0889)
		(layer "In2.Cu")
		(net "M_C_CPU0_SA_DQ<28>")
	)
	(segment
		(start 309.583328 -232.343198)
		(end 309.668926 -232.2576)
		(width 0.14478)
		(layer "In2.Cu")
		(net "M_C_CPU0_SA_DQ<28>")
	)
	(segment
		(start 311.321196 -234.311444)
		(end 311.157874 -234.148122)
		(width 0.14478)
		(layer "In2.Cu")
		(net "M_C_CPU0_SA_DQ<28>")
	)
	(segment
		(start 311.868058 -234.2261)
		(end 311.637426 -234.225846)
		(width 0.14478)
		(layer "In2.Cu")
		(net "M_C_CPU0_SA_DQ<28>")
	)
	(segment
		(start 310.370728 -233.130598)
		(end 310.456326 -233.045)
		(width 0.14478)
		(layer "In2.Cu")
		(net "M_C_CPU0_SA_DQ<28>")
	)
	(segment
		(start 314.307474 -237.297722)
		(end 314.307728 -237.067598)
		(width 0.14478)
		(layer "In2.Cu")
		(net "M_C_CPU0_SA_DQ<28>")
	)
	(segment
		(start 293.576756 -231.43083)
		(end 293.413688 -231.593898)
		(width 0.14478)
		(layer "In2.Cu")
		(net "M_C_CPU0_SA_DQ<28>")
	)
	(segment
		(start 300.928532 -230.919782)
		(end 298.412916 -230.919782)
		(width 0.14478)
		(layer "In2.Cu")
		(net "M_C_CPU0_SA_DQ<28>")
	)
	(segment
		(start 305.085496 -231.760014)
		(end 304.922428 -231.923082)
		(width 0.14478)
		(layer "In2.Cu")
		(net "M_C_CPU0_SA_DQ<28>")
	)
	(segment
		(start 342.015064 -243.129562)
		(end 341.992712 -243.212874)
		(width 0.0889)
		(layer "In2.Cu")
		(net "M_C_CPU0_SA_DQ<28>")
	)
	(segment
		(start 311.945274 -234.935522)
		(end 311.945528 -234.705398)
		(width 0.14478)
		(layer "In2.Cu")
		(net "M_C_CPU0_SA_DQ<28>")
	)
	(segment
		(start 293.25062 -232.14457)
		(end 293.020242 -232.14457)
		(width 0.14478)
		(layer "In2.Cu")
		(net "M_C_CPU0_SA_DQ<28>")
	)
	(segment
		(start 313.605926 -236.1946)
		(end 313.605926 -235.963968)
		(width 0.14478)
		(layer "In2.Cu")
		(net "M_C_CPU0_SA_DQ<28>")
	)
	(segment
		(start 311.243726 -233.601768)
		(end 311.080658 -233.4387)
		(width 0.14478)
		(layer "In2.Cu")
		(net "M_C_CPU0_SA_DQ<28>")
	)
	(segment
		(start 293.807134 -231.43083)
		(end 293.576756 -231.43083)
		(width 0.14478)
		(layer "In2.Cu")
		(net "M_C_CPU0_SA_DQ<28>")
	)
	(segment
		(start 311.158128 -233.917998)
		(end 311.243726 -233.8324)
		(width 0.14478)
		(layer "In2.Cu")
		(net "M_C_CPU0_SA_DQ<28>")
	)
	(segment
		(start 296.827194 -231.769666)
		(end 294.675052 -231.769666)
		(width 0.14478)
		(layer "In2.Cu")
		(net "M_C_CPU0_SA_DQ<28>")
	)
	(segment
		(start 304.528982 -232.13949)
		(end 304.365914 -231.976422)
		(width 0.14478)
		(layer "In2.Cu")
		(net "M_C_CPU0_SA_DQ<28>")
	)
	(segment
		(start 297.310048 -232.02265)
		(end 297.080178 -232.02265)
		(width 0.14478)
		(layer "In2.Cu")
		(net "M_C_CPU0_SA_DQ<28>")
	)
	(segment
		(start 297.080178 -232.02265)
		(end 296.827194 -231.769666)
		(width 0.14478)
		(layer "In2.Cu")
		(net "M_C_CPU0_SA_DQ<28>")
	)
	(segment
		(start 293.413688 -231.981502)
		(end 293.25062 -232.14457)
		(width 0.14478)
		(layer "In2.Cu")
		(net "M_C_CPU0_SA_DQ<28>")
	)
	(segment
		(start 309.977028 -232.736644)
		(end 309.746396 -232.736644)
		(width 0.14478)
		(layer "In2.Cu")
		(net "M_C_CPU0_SA_DQ<28>")
	)
	(segment
		(start 326.351138 -243.104162)
		(end 326.145906 -243.104162)
		(width 0.0889)
		(layer "In2.Cu")
		(net "M_C_CPU0_SA_DQ<28>")
	)
	(segment
		(start 292.857174 -231.981502)
		(end 292.857174 -231.91216)
		(width 0.14478)
		(layer "In2.Cu")
		(net "M_C_CPU0_SA_DQ<28>")
	)
	(segment
		(start 311.080658 -233.4387)
		(end 310.850026 -233.438446)
		(width 0.14478)
		(layer "In2.Cu")
		(net "M_C_CPU0_SA_DQ<28>")
	)
	(segment
		(start 306.13604 -230.91013)
		(end 305.286156 -231.760014)
		(width 0.14478)
		(layer "In2.Cu")
		(net "M_C_CPU0_SA_DQ<28>")
	)
	(segment
		(start 304.922428 -231.976422)
		(end 304.75936 -232.13949)
		(width 0.14478)
		(layer "In2.Cu")
		(net "M_C_CPU0_SA_DQ<28>")
	)
	(segment
		(start 313.520328 -236.280198)
		(end 313.605926 -236.1946)
		(width 0.14478)
		(layer "In2.Cu")
		(net "M_C_CPU0_SA_DQ<28>")
	)
	(segment
		(start 315.180726 -237.7694)
		(end 315.180726 -237.538768)
		(width 0.14478)
		(layer "In2.Cu")
		(net "M_C_CPU0_SA_DQ<28>")
	)
	(segment
		(start 309.668926 -232.2576)
		(end 309.668926 -232.026968)
		(width 0.14478)
		(layer "In2.Cu")
		(net "M_C_CPU0_SA_DQ<28>")
	)
	(segment
		(start 305.286156 -231.760014)
		(end 305.085496 -231.760014)
		(width 0.14478)
		(layer "In2.Cu")
		(net "M_C_CPU0_SA_DQ<28>")
	)
	(segment
		(start 304.202846 -231.760014)
		(end 301.768764 -231.760014)
		(width 0.14478)
		(layer "In2.Cu")
		(net "M_C_CPU0_SA_DQ<28>")
	)
	(segment
		(start 310.456326 -232.814368)
		(end 310.293258 -232.6513)
		(width 0.14478)
		(layer "In2.Cu")
		(net "M_C_CPU0_SA_DQ<28>")
	)
	(segment
		(start 312.818526 -235.4072)
		(end 312.818526 -235.176568)
		(width 0.14478)
		(layer "In2.Cu")
		(net "M_C_CPU0_SA_DQ<28>")
	)
	(segment
		(start 311.157874 -234.148122)
		(end 311.158128 -233.917998)
		(width 0.14478)
		(layer "In2.Cu")
		(net "M_C_CPU0_SA_DQ<28>")
	)
	(segment
		(start 338.862416 -243.191538)
		(end 338.854034 -243.186712)
		(width 0.0889)
		(layer "In2.Cu")
		(net "M_C_CPU0_SA_DQ<28>")
	)
	(segment
		(start 314.230258 -236.5883)
		(end 313.999626 -236.588046)
		(width 0.14478)
		(layer "In2.Cu")
		(net "M_C_CPU0_SA_DQ<28>")
	)
	(segment
		(start 294.675052 -231.769666)
		(end 294.526716 -231.918002)
		(width 0.14478)
		(layer "In2.Cu")
		(net "M_C_CPU0_SA_DQ<28>")
	)
	(segment
		(start 312.424826 -235.013246)
		(end 312.339228 -235.098844)
		(width 0.14478)
		(layer "In2.Cu")
		(net "M_C_CPU0_SA_DQ<28>")
	)
	(segment
		(start 310.850026 -233.438446)
		(end 310.764428 -233.524044)
		(width 0.14478)
		(layer "In2.Cu")
		(net "M_C_CPU0_SA_DQ<28>")
	)
	(segment
		(start 311.243726 -233.8324)
		(end 311.243726 -233.601768)
		(width 0.14478)
		(layer "In2.Cu")
		(net "M_C_CPU0_SA_DQ<28>")
	)
	(segment
		(start 293.970202 -231.981502)
		(end 293.970202 -231.593898)
		(width 0.14478)
		(layer "In2.Cu")
		(net "M_C_CPU0_SA_DQ<28>")
	)
	(segment
		(start 312.031126 -234.6198)
		(end 312.031126 -234.389168)
		(width 0.14478)
		(layer "In2.Cu")
		(net "M_C_CPU0_SA_DQ<28>")
	)
	(segment
		(start 292.857174 -231.91216)
		(end 292.280086 -231.335072)
		(width 0.14478)
		(layer "In2.Cu")
		(net "M_C_CPU0_SA_DQ<28>")
	)
	(segment
		(start 327.94829 -243.186712)
		(end 327.939908 -243.191538)
		(width 0.0889)
		(layer "In2.Cu")
		(net "M_C_CPU0_SA_DQ<28>")
	)
	(segment
		(start 304.365914 -231.923082)
		(end 304.202846 -231.760014)
		(width 0.14478)
		(layer "In2.Cu")
		(net "M_C_CPU0_SA_DQ<28>")
	)
	(segment
		(start 310.062626 -232.651046)
		(end 309.977028 -232.736644)
		(width 0.14478)
		(layer "In2.Cu")
		(net "M_C_CPU0_SA_DQ<28>")
	)
	(segment
		(start 301.768764 -231.760014)
		(end 300.928532 -230.919782)
		(width 0.14478)
		(layer "In2.Cu")
		(net "M_C_CPU0_SA_DQ<28>")
	)
	(segment
		(start 313.212226 -235.800646)
		(end 313.126628 -235.886244)
		(width 0.14478)
		(layer "In2.Cu")
		(net "M_C_CPU0_SA_DQ<28>")
	)
	(segment
		(start 314.470796 -237.461044)
		(end 314.307474 -237.297722)
		(width 0.14478)
		(layer "In2.Cu")
		(net "M_C_CPU0_SA_DQ<28>")
	)
	(segment
		(start 325.656194 -242.98783)
		(end 324.497954 -241.82959)
		(width 0.0889)
		(layer "In2.Cu")
		(net "M_C_CPU0_SA_DQ<28>")
	)
	(segment
		(start 324.497954 -241.82959)
		(end 323.895974 -241.82959)
		(width 0.0889)
		(layer "In2.Cu")
		(net "M_C_CPU0_SA_DQ<28>")
	)
	(segment
		(start 313.683396 -236.673644)
		(end 313.520074 -236.510322)
		(width 0.14478)
		(layer "In2.Cu")
		(net "M_C_CPU0_SA_DQ<28>")
	)
	(segment
		(start 319.471548 -241.82959)
		(end 315.805058 -238.1631)
		(width 0.14478)
		(layer "In2.Cu")
		(net "M_C_CPU0_SA_DQ<28>")
	)
	(segment
		(start 304.922428 -231.923082)
		(end 304.922428 -231.976422)
		(width 0.14478)
		(layer "In2.Cu")
		(net "M_C_CPU0_SA_DQ<28>")
	)
	(segment
		(start 336.042508 -243.191538)
		(end 336.034126 -243.186712)
		(width 0.0889)
		(layer "In2.Cu")
		(net "M_C_CPU0_SA_DQ<28>")
	)
	(segment
		(start 339.80247 -243.191538)
		(end 339.794088 -243.186712)
		(width 0.0889)
		(layer "In2.Cu")
		(net "M_C_CPU0_SA_DQ<28>")
	)
	(segment
		(start 293.413688 -231.593898)
		(end 293.413688 -231.981502)
		(width 0.14478)
		(layer "In2.Cu")
		(net "M_C_CPU0_SA_DQ<28>")
	)
	(arc
		(start 341.10803 -243.186712)
		(mid 340.921086 -243.236967)
		(end 340.734142 -243.186712)
		(width 0.0889)
		(layer "In2.Cu")
		(net "M_C_CPU0_SA_DQ<28>")
	)
	(arc
		(start 332.648052 -243.186712)
		(mid 332.461108 -243.236967)
		(end 332.274164 -243.186712)
		(width 0.0889)
		(layer "In2.Cu")
		(net "M_C_CPU0_SA_DQ<28>")
	)
	(arc
		(start 339.794088 -243.186712)
		(mid 339.511132 -243.110535)
		(end 339.228176 -243.186712)
		(width 0.0889)
		(layer "In2.Cu")
		(net "M_C_CPU0_SA_DQ<28>")
	)
	(arc
		(start 327.939908 -243.191538)
		(mid 327.756146 -243.237154)
		(end 327.57364 -243.186712)
		(width 0.0889)
		(layer "In2.Cu")
		(net "M_C_CPU0_SA_DQ<28>")
	)
	(arc
		(start 329.454002 -243.186712)
		(mid 329.171046 -243.110535)
		(end 328.88809 -243.186712)
		(width 0.0889)
		(layer "In2.Cu")
		(net "M_C_CPU0_SA_DQ<28>")
	)
	(arc
		(start 335.094072 -243.186712)
		(mid 334.811116 -243.110535)
		(end 334.52816 -243.186712)
		(width 0.0889)
		(layer "In2.Cu")
		(net "M_C_CPU0_SA_DQ<28>")
	)
	(arc
		(start 336.408268 -243.186712)
		(mid 336.226017 -243.237062)
		(end 336.042508 -243.191538)
		(width 0.0889)
		(layer "In2.Cu")
		(net "M_C_CPU0_SA_DQ<28>")
	)
	(arc
		(start 330.768198 -243.186712)
		(mid 330.585947 -243.237062)
		(end 330.402438 -243.191538)
		(width 0.0889)
		(layer "In2.Cu")
		(net "M_C_CPU0_SA_DQ<28>")
	)
	(arc
		(start 333.579724 -243.191538)
		(mid 333.396216 -243.237032)
		(end 333.213964 -243.186712)
		(width 0.0889)
		(layer "In2.Cu")
		(net "M_C_CPU0_SA_DQ<28>")
	)
	(arc
		(start 340.734142 -243.186712)
		(mid 340.451186 -243.110535)
		(end 340.16823 -243.186712)
		(width 0.0889)
		(layer "In2.Cu")
		(net "M_C_CPU0_SA_DQ<28>")
	)
	(arc
		(start 328.514202 -243.186712)
		(mid 328.231246 -243.110535)
		(end 327.94829 -243.186712)
		(width 0.0889)
		(layer "In2.Cu")
		(net "M_C_CPU0_SA_DQ<28>")
	)
	(arc
		(start 331.708252 -243.186712)
		(mid 331.526001 -243.237062)
		(end 331.342492 -243.191538)
		(width 0.0889)
		(layer "In2.Cu")
		(net "M_C_CPU0_SA_DQ<28>")
	)
	(arc
		(start 338.27974 -243.191538)
		(mid 338.096232 -243.237032)
		(end 337.91398 -243.186712)
		(width 0.0889)
		(layer "In2.Cu")
		(net "M_C_CPU0_SA_DQ<28>")
	)
	(arc
		(start 334.154018 -243.186712)
		(mid 333.871062 -243.110535)
		(end 333.588106 -243.186712)
		(width 0.0889)
		(layer "In2.Cu")
		(net "M_C_CPU0_SA_DQ<28>")
	)
	(arc
		(start 337.91398 -243.186712)
		(mid 337.631024 -243.110535)
		(end 337.348068 -243.186712)
		(width 0.0889)
		(layer "In2.Cu")
		(net "M_C_CPU0_SA_DQ<28>")
	)
	(arc
		(start 339.228176 -243.186712)
		(mid 339.045925 -243.237062)
		(end 338.862416 -243.191538)
		(width 0.0889)
		(layer "In2.Cu")
		(net "M_C_CPU0_SA_DQ<28>")
	)
	(arc
		(start 341.992712 -243.212874)
		(mid 341.83038 -243.235692)
		(end 341.673942 -243.186712)
		(width 0.0889)
		(layer "In2.Cu")
		(net "M_C_CPU0_SA_DQ<28>")
	)
	(arc
		(start 332.274164 -243.186712)
		(mid 331.991208 -243.110535)
		(end 331.708252 -243.186712)
		(width 0.0889)
		(layer "In2.Cu")
		(net "M_C_CPU0_SA_DQ<28>")
	)
	(arc
		(start 326.585072 -243.16182)
		(mid 326.471601 -243.118799)
		(end 326.351138 -243.104162)
		(width 0.0889)
		(layer "In2.Cu")
		(net "M_C_CPU0_SA_DQ<28>")
	)
	(arc
		(start 330.394056 -243.186712)
		(mid 330.1111 -243.110535)
		(end 329.828144 -243.186712)
		(width 0.0889)
		(layer "In2.Cu")
		(net "M_C_CPU0_SA_DQ<28>")
	)
	(arc
		(start 328.88809 -243.186712)
		(mid 328.701146 -243.236967)
		(end 328.514202 -243.186712)
		(width 0.0889)
		(layer "In2.Cu")
		(net "M_C_CPU0_SA_DQ<28>")
	)
	(arc
		(start 334.519778 -243.191538)
		(mid 334.33627 -243.237032)
		(end 334.154018 -243.186712)
		(width 0.0889)
		(layer "In2.Cu")
		(net "M_C_CPU0_SA_DQ<28>")
	)
	(arc
		(start 336.034126 -243.186712)
		(mid 335.75117 -243.110535)
		(end 335.468214 -243.186712)
		(width 0.0889)
		(layer "In2.Cu")
		(net "M_C_CPU0_SA_DQ<28>")
	)
	(arc
		(start 336.97418 -243.186712)
		(mid 336.691224 -243.110535)
		(end 336.408268 -243.186712)
		(width 0.0889)
		(layer "In2.Cu")
		(net "M_C_CPU0_SA_DQ<28>")
	)
	(arc
		(start 340.16823 -243.186712)
		(mid 339.985979 -243.237062)
		(end 339.80247 -243.191538)
		(width 0.0889)
		(layer "In2.Cu")
		(net "M_C_CPU0_SA_DQ<28>")
	)
	(arc
		(start 331.33411 -243.186712)
		(mid 331.051154 -243.110535)
		(end 330.768198 -243.186712)
		(width 0.0889)
		(layer "In2.Cu")
		(net "M_C_CPU0_SA_DQ<28>")
	)
	(arc
		(start 338.854034 -243.186712)
		(mid 338.571078 -243.110535)
		(end 338.288122 -243.186712)
		(width 0.0889)
		(layer "In2.Cu")
		(net "M_C_CPU0_SA_DQ<28>")
	)
	(arc
		(start 341.673942 -243.186712)
		(mid 341.390986 -243.110535)
		(end 341.10803 -243.186712)
		(width 0.0889)
		(layer "In2.Cu")
		(net "M_C_CPU0_SA_DQ<28>")
	)
	(arc
		(start 329.819762 -243.191538)
		(mid 329.636254 -243.237032)
		(end 329.454002 -243.186712)
		(width 0.0889)
		(layer "In2.Cu")
		(net "M_C_CPU0_SA_DQ<28>")
	)
	(arc
		(start 327.00722 -243.186712)
		(mid 326.828233 -243.236882)
		(end 326.647302 -243.194332)
		(width 0.0889)
		(layer "In2.Cu")
		(net "M_C_CPU0_SA_DQ<28>")
	)
	(arc
		(start 333.213964 -243.186712)
		(mid 332.931008 -243.110535)
		(end 332.648052 -243.186712)
		(width 0.0889)
		(layer "In2.Cu")
		(net "M_C_CPU0_SA_DQ<28>")
	)
	(arc
		(start 335.468214 -243.186712)
		(mid 335.285963 -243.237062)
		(end 335.102454 -243.191538)
		(width 0.0889)
		(layer "In2.Cu")
		(net "M_C_CPU0_SA_DQ<28>")
	)
	(arc
		(start 327.57364 -243.186712)
		(mid 327.298934 -243.110348)
		(end 327.021952 -243.178076)
		(width 0.0889)
		(layer "In2.Cu")
		(net "M_C_CPU0_SA_DQ<28>")
	)
	(arc
		(start 337.348068 -243.186712)
		(mid 337.161124 -243.236967)
		(end 336.97418 -243.186712)
		(width 0.0889)
		(layer "In2.Cu")
		(net "M_C_CPU0_SA_DQ<28>")
	)
	(segment
		(start 344.207846 -241.510058)
		(end 343.740994 -241.24412)
		(width 0.10668)
		(layer "F.Cu")
		(net "M_C_CPU0_SA_DQ<27>")
	)
	(segment
		(start 335.102454 -240.916714)
		(end 335.094072 -240.92154)
		(width 0.0889)
		(layer "In2.Cu")
		(net "M_C_CPU0_SA_DQ<27>")
	)
	(segment
		(start 338.288122 -240.92154)
		(end 338.27974 -240.916714)
		(width 0.0889)
		(layer "In2.Cu")
		(net "M_C_CPU0_SA_DQ<27>")
	)
	(segment
		(start 308.377844 -227.510086)
		(end 305.70043 -227.510086)
		(width 0.14478)
		(layer "In2.Cu")
		(net "M_C_CPU0_SA_DQ<27>")
	)
	(segment
		(start 323.916294 -239.47755)
		(end 320.735452 -239.47755)
		(width 0.14478)
		(layer "In2.Cu")
		(net "M_C_CPU0_SA_DQ<27>")
	)
	(segment
		(start 334.52816 -240.92154)
		(end 334.519778 -240.916714)
		(width 0.0889)
		(layer "In2.Cu")
		(net "M_C_CPU0_SA_DQ<27>")
	)
	(segment
		(start 327.575418 -240.921794)
		(end 327.549256 -240.93678)
		(width 0.0889)
		(layer "In2.Cu")
		(net "M_C_CPU0_SA_DQ<27>")
	)
	(segment
		(start 343.58707 -240.97869)
		(end 343.491058 -240.95329)
		(width 0.0889)
		(layer "In2.Cu")
		(net "M_C_CPU0_SA_DQ<27>")
	)
	(segment
		(start 302.404018 -228.360224)
		(end 302.154336 -228.256846)
		(width 0.14478)
		(layer "In2.Cu")
		(net "M_C_CPU0_SA_DQ<27>")
	)
	(segment
		(start 308.995318 -227.69703)
		(end 308.377844 -227.510086)
		(width 0.14478)
		(layer "In2.Cu")
		(net "M_C_CPU0_SA_DQ<27>")
	)
	(segment
		(start 311.197752 -227.876608)
		(end 310.764428 -227.69703)
		(width 0.14478)
		(layer "In2.Cu")
		(net "M_C_CPU0_SA_DQ<27>")
	)
	(segment
		(start 313.141614 -231.89819)
		(end 313.141614 -230.143812)
		(width 0.14478)
		(layer "In2.Cu")
		(net "M_C_CPU0_SA_DQ<27>")
	)
	(segment
		(start 331.342492 -240.916714)
		(end 331.33411 -240.92154)
		(width 0.0889)
		(layer "In2.Cu")
		(net "M_C_CPU0_SA_DQ<27>")
	)
	(segment
		(start 339.80247 -240.916714)
		(end 339.794088 -240.92154)
		(width 0.0889)
		(layer "In2.Cu")
		(net "M_C_CPU0_SA_DQ<27>")
	)
	(segment
		(start 313.224164 -232.09758)
		(end 313.141614 -231.89819)
		(width 0.14478)
		(layer "In2.Cu")
		(net "M_C_CPU0_SA_DQ<27>")
	)
	(segment
		(start 298.228004 -227.500434)
		(end 297.517058 -227.975414)
		(width 0.14478)
		(layer "In2.Cu")
		(net "M_C_CPU0_SA_DQ<27>")
	)
	(segment
		(start 327.011538 -240.92154)
		(end 326.990964 -240.909602)
		(width 0.0889)
		(layer "In2.Cu")
		(net "M_C_CPU0_SA_DQ<27>")
	)
	(segment
		(start 320.511424 -239.38484)
		(end 313.224164 -232.09758)
		(width 0.14478)
		(layer "In2.Cu")
		(net "M_C_CPU0_SA_DQ<27>")
	)
	(segment
		(start 325.948802 -240.837212)
		(end 325.130414 -240.019078)
		(width 0.0889)
		(layer "In2.Cu")
		(net "M_C_CPU0_SA_DQ<27>")
	)
	(segment
		(start 333.588106 -240.92154)
		(end 333.579724 -240.916714)
		(width 0.0889)
		(layer "In2.Cu")
		(net "M_C_CPU0_SA_DQ<27>")
	)
	(segment
		(start 338.862416 -240.916714)
		(end 338.854034 -240.92154)
		(width 0.0889)
		(layer "In2.Cu")
		(net "M_C_CPU0_SA_DQ<27>")
	)
	(segment
		(start 310.764428 -227.69703)
		(end 308.995318 -227.69703)
		(width 0.14478)
		(layer "In2.Cu")
		(net "M_C_CPU0_SA_DQ<27>")
	)
	(segment
		(start 329.828144 -240.92154)
		(end 329.819762 -240.916714)
		(width 0.0889)
		(layer "In2.Cu")
		(net "M_C_CPU0_SA_DQ<27>")
	)
	(segment
		(start 297.517058 -227.975414)
		(end 296.611294 -228.350318)
		(width 0.14478)
		(layer "In2.Cu")
		(net "M_C_CPU0_SA_DQ<27>")
	)
	(segment
		(start 325.130414 -240.01857)
		(end 325.130414 -239.71885)
		(width 0.0889)
		(layer "In2.Cu")
		(net "M_C_CPU0_SA_DQ<27>")
	)
	(segment
		(start 327.598786 -240.908332)
		(end 327.575418 -240.921794)
		(width 0.0889)
		(layer "In2.Cu")
		(net "M_C_CPU0_SA_DQ<27>")
	)
	(segment
		(start 342.048084 -240.92154)
		(end 342.039702 -240.916714)
		(width 0.0889)
		(layer "In2.Cu")
		(net "M_C_CPU0_SA_DQ<27>")
	)
	(segment
		(start 313.141614 -230.143812)
		(end 312.913014 -229.59187)
		(width 0.14478)
		(layer "In2.Cu")
		(net "M_C_CPU0_SA_DQ<27>")
	)
	(segment
		(start 301.022512 -227.500434)
		(end 298.228004 -227.500434)
		(width 0.14478)
		(layer "In2.Cu")
		(net "M_C_CPU0_SA_DQ<27>")
	)
	(segment
		(start 304.13452 -228.360224)
		(end 302.404018 -228.360224)
		(width 0.14478)
		(layer "In2.Cu")
		(net "M_C_CPU0_SA_DQ<27>")
	)
	(segment
		(start 288.595308 -228.350318)
		(end 288.180018 -227.935028)
		(width 0.14478)
		(layer "In2.Cu")
		(net "M_C_CPU0_SA_DQ<27>")
	)
	(segment
		(start 342.988138 -240.92154)
		(end 342.979756 -240.916714)
		(width 0.0889)
		(layer "In2.Cu")
		(net "M_C_CPU0_SA_DQ<27>")
	)
	(segment
		(start 320.735452 -239.47755)
		(end 320.511424 -239.38484)
		(width 0.14478)
		(layer "In2.Cu")
		(net "M_C_CPU0_SA_DQ<27>")
	)
	(segment
		(start 312.913014 -229.59187)
		(end 311.197752 -227.876608)
		(width 0.14478)
		(layer "In2.Cu")
		(net "M_C_CPU0_SA_DQ<27>")
	)
	(segment
		(start 304.552604 -228.277166)
		(end 304.13452 -228.360224)
		(width 0.14478)
		(layer "In2.Cu")
		(net "M_C_CPU0_SA_DQ<27>")
	)
	(segment
		(start 325.130414 -239.71885)
		(end 324.889114 -239.47755)
		(width 0.0889)
		(layer "In2.Cu")
		(net "M_C_CPU0_SA_DQ<27>")
	)
	(segment
		(start 326.109584 -240.944654)
		(end 326.023478 -240.894616)
		(width 0.0889)
		(layer "In2.Cu")
		(net "M_C_CPU0_SA_DQ<27>")
	)
	(segment
		(start 330.402438 -240.916714)
		(end 330.394056 -240.92154)
		(width 0.0889)
		(layer "In2.Cu")
		(net "M_C_CPU0_SA_DQ<27>")
	)
	(segment
		(start 343.740994 -241.24412)
		(end 343.58707 -240.97869)
		(width 0.0889)
		(layer "In2.Cu")
		(net "M_C_CPU0_SA_DQ<27>")
	)
	(segment
		(start 324.889114 -239.47755)
		(end 323.916294 -239.47755)
		(width 0.0889)
		(layer "In2.Cu")
		(net "M_C_CPU0_SA_DQ<27>")
	)
	(segment
		(start 302.154336 -228.256846)
		(end 301.022512 -227.500434)
		(width 0.14478)
		(layer "In2.Cu")
		(net "M_C_CPU0_SA_DQ<27>")
	)
	(segment
		(start 296.611294 -228.350318)
		(end 288.595308 -228.350318)
		(width 0.14478)
		(layer "In2.Cu")
		(net "M_C_CPU0_SA_DQ<27>")
	)
	(segment
		(start 305.70043 -227.510086)
		(end 304.552604 -228.277166)
		(width 0.14478)
		(layer "In2.Cu")
		(net "M_C_CPU0_SA_DQ<27>")
	)
	(segment
		(start 336.042508 -240.916714)
		(end 336.034126 -240.92154)
		(width 0.0889)
		(layer "In2.Cu")
		(net "M_C_CPU0_SA_DQ<27>")
	)
	(arc
		(start 341.10803 -240.92154)
		(mid 340.921086 -240.871285)
		(end 340.734142 -240.92154)
		(width 0.0889)
		(layer "In2.Cu")
		(net "M_C_CPU0_SA_DQ<27>")
	)
	(arc
		(start 339.794088 -240.92154)
		(mid 339.511132 -240.997717)
		(end 339.228176 -240.92154)
		(width 0.0889)
		(layer "In2.Cu")
		(net "M_C_CPU0_SA_DQ<27>")
	)
	(arc
		(start 336.408268 -240.92154)
		(mid 336.226017 -240.87119)
		(end 336.042508 -240.916714)
		(width 0.0889)
		(layer "In2.Cu")
		(net "M_C_CPU0_SA_DQ<27>")
	)
	(arc
		(start 332.274164 -240.92154)
		(mid 331.991208 -240.997717)
		(end 331.708252 -240.92154)
		(width 0.0889)
		(layer "In2.Cu")
		(net "M_C_CPU0_SA_DQ<27>")
	)
	(arc
		(start 331.33411 -240.92154)
		(mid 331.051154 -240.997717)
		(end 330.768198 -240.92154)
		(width 0.0889)
		(layer "In2.Cu")
		(net "M_C_CPU0_SA_DQ<27>")
	)
	(arc
		(start 326.023478 -240.894616)
		(mid 325.984288 -240.868325)
		(end 325.948802 -240.837212)
		(width 0.0889)
		(layer "In2.Cu")
		(net "M_C_CPU0_SA_DQ<27>")
	)
	(arc
		(start 342.039702 -240.916714)
		(mid 341.856194 -240.87122)
		(end 341.673942 -240.92154)
		(width 0.0889)
		(layer "In2.Cu")
		(net "M_C_CPU0_SA_DQ<27>")
	)
	(arc
		(start 340.16823 -240.92154)
		(mid 339.985979 -240.87119)
		(end 339.80247 -240.916714)
		(width 0.0889)
		(layer "In2.Cu")
		(net "M_C_CPU0_SA_DQ<27>")
	)
	(arc
		(start 334.154018 -240.92154)
		(mid 333.871062 -240.997717)
		(end 333.588106 -240.92154)
		(width 0.0889)
		(layer "In2.Cu")
		(net "M_C_CPU0_SA_DQ<27>")
	)
	(arc
		(start 327.549256 -240.93678)
		(mid 327.27847 -240.997426)
		(end 327.011538 -240.92154)
		(width 0.0889)
		(layer "In2.Cu")
		(net "M_C_CPU0_SA_DQ<27>")
	)
	(arc
		(start 326.990964 -240.909602)
		(mid 326.812036 -240.870725)
		(end 326.636126 -240.92154)
		(width 0.0889)
		(layer "In2.Cu")
		(net "M_C_CPU0_SA_DQ<27>")
	)
	(arc
		(start 328.514202 -240.92154)
		(mid 328.231246 -240.997717)
		(end 327.94829 -240.92154)
		(width 0.0889)
		(layer "In2.Cu")
		(net "M_C_CPU0_SA_DQ<27>")
	)
	(arc
		(start 336.97418 -240.92154)
		(mid 336.691224 -240.997717)
		(end 336.408268 -240.92154)
		(width 0.0889)
		(layer "In2.Cu")
		(net "M_C_CPU0_SA_DQ<27>")
	)
	(arc
		(start 333.579724 -240.916714)
		(mid 333.396216 -240.87122)
		(end 333.213964 -240.92154)
		(width 0.0889)
		(layer "In2.Cu")
		(net "M_C_CPU0_SA_DQ<27>")
	)
	(arc
		(start 338.27974 -240.916714)
		(mid 338.096232 -240.87122)
		(end 337.91398 -240.92154)
		(width 0.0889)
		(layer "In2.Cu")
		(net "M_C_CPU0_SA_DQ<27>")
	)
	(arc
		(start 337.348068 -240.92154)
		(mid 337.161124 -240.871285)
		(end 336.97418 -240.92154)
		(width 0.0889)
		(layer "In2.Cu")
		(net "M_C_CPU0_SA_DQ<27>")
	)
	(arc
		(start 341.673942 -240.92154)
		(mid 341.390986 -240.997717)
		(end 341.10803 -240.92154)
		(width 0.0889)
		(layer "In2.Cu")
		(net "M_C_CPU0_SA_DQ<27>")
	)
	(arc
		(start 335.094072 -240.92154)
		(mid 334.811116 -240.997717)
		(end 334.52816 -240.92154)
		(width 0.0889)
		(layer "In2.Cu")
		(net "M_C_CPU0_SA_DQ<27>")
	)
	(arc
		(start 337.91398 -240.92154)
		(mid 337.631024 -240.997717)
		(end 337.348068 -240.92154)
		(width 0.0889)
		(layer "In2.Cu")
		(net "M_C_CPU0_SA_DQ<27>")
	)
	(arc
		(start 333.213964 -240.92154)
		(mid 332.931008 -240.997717)
		(end 332.648052 -240.92154)
		(width 0.0889)
		(layer "In2.Cu")
		(net "M_C_CPU0_SA_DQ<27>")
	)
	(arc
		(start 339.228176 -240.92154)
		(mid 339.045925 -240.87119)
		(end 338.862416 -240.916714)
		(width 0.0889)
		(layer "In2.Cu")
		(net "M_C_CPU0_SA_DQ<27>")
	)
	(arc
		(start 340.734142 -240.92154)
		(mid 340.451186 -240.997717)
		(end 340.16823 -240.92154)
		(width 0.0889)
		(layer "In2.Cu")
		(net "M_C_CPU0_SA_DQ<27>")
	)
	(arc
		(start 330.768198 -240.92154)
		(mid 330.585947 -240.87119)
		(end 330.402438 -240.916714)
		(width 0.0889)
		(layer "In2.Cu")
		(net "M_C_CPU0_SA_DQ<27>")
	)
	(arc
		(start 327.94829 -240.92154)
		(mid 327.775182 -240.871424)
		(end 327.598786 -240.908332)
		(width 0.0889)
		(layer "In2.Cu")
		(net "M_C_CPU0_SA_DQ<27>")
	)
	(arc
		(start 342.613996 -240.92154)
		(mid 342.33104 -240.997717)
		(end 342.048084 -240.92154)
		(width 0.0889)
		(layer "In2.Cu")
		(net "M_C_CPU0_SA_DQ<27>")
	)
	(arc
		(start 336.034126 -240.92154)
		(mid 335.75117 -240.997717)
		(end 335.468214 -240.92154)
		(width 0.0889)
		(layer "In2.Cu")
		(net "M_C_CPU0_SA_DQ<27>")
	)
	(arc
		(start 329.819762 -240.916714)
		(mid 329.636254 -240.87122)
		(end 329.454002 -240.92154)
		(width 0.0889)
		(layer "In2.Cu")
		(net "M_C_CPU0_SA_DQ<27>")
	)
	(arc
		(start 334.519778 -240.916714)
		(mid 334.33627 -240.87122)
		(end 334.154018 -240.92154)
		(width 0.0889)
		(layer "In2.Cu")
		(net "M_C_CPU0_SA_DQ<27>")
	)
	(arc
		(start 343.491058 -240.95329)
		(mid 343.23585 -240.996767)
		(end 342.988138 -240.92154)
		(width 0.0889)
		(layer "In2.Cu")
		(net "M_C_CPU0_SA_DQ<27>")
	)
	(arc
		(start 325.130414 -240.019078)
		(mid 325.130354 -240.018824)
		(end 325.130414 -240.01857)
		(width 0.0889)
		(layer "In2.Cu")
		(net "M_C_CPU0_SA_DQ<27>")
	)
	(arc
		(start 332.648052 -240.92154)
		(mid 332.461108 -240.871285)
		(end 332.274164 -240.92154)
		(width 0.0889)
		(layer "In2.Cu")
		(net "M_C_CPU0_SA_DQ<27>")
	)
	(arc
		(start 331.708252 -240.92154)
		(mid 331.526001 -240.87119)
		(end 331.342492 -240.916714)
		(width 0.0889)
		(layer "In2.Cu")
		(net "M_C_CPU0_SA_DQ<27>")
	)
	(arc
		(start 328.88809 -240.92154)
		(mid 328.701146 -240.871285)
		(end 328.514202 -240.92154)
		(width 0.0889)
		(layer "In2.Cu")
		(net "M_C_CPU0_SA_DQ<27>")
	)
	(arc
		(start 330.394056 -240.92154)
		(mid 330.1111 -240.997717)
		(end 329.828144 -240.92154)
		(width 0.0889)
		(layer "In2.Cu")
		(net "M_C_CPU0_SA_DQ<27>")
	)
	(arc
		(start 335.468214 -240.92154)
		(mid 335.285963 -240.87119)
		(end 335.102454 -240.916714)
		(width 0.0889)
		(layer "In2.Cu")
		(net "M_C_CPU0_SA_DQ<27>")
	)
	(arc
		(start 326.636126 -240.92154)
		(mid 326.375711 -240.998322)
		(end 326.109584 -240.944654)
		(width 0.0889)
		(layer "In2.Cu")
		(net "M_C_CPU0_SA_DQ<27>")
	)
	(arc
		(start 338.854034 -240.92154)
		(mid 338.571078 -240.997717)
		(end 338.288122 -240.92154)
		(width 0.0889)
		(layer "In2.Cu")
		(net "M_C_CPU0_SA_DQ<27>")
	)
	(arc
		(start 342.979756 -240.916714)
		(mid 342.796248 -240.87122)
		(end 342.613996 -240.92154)
		(width 0.0889)
		(layer "In2.Cu")
		(net "M_C_CPU0_SA_DQ<27>")
	)
	(arc
		(start 329.454002 -240.92154)
		(mid 329.171046 -240.997717)
		(end 328.88809 -240.92154)
		(width 0.0889)
		(layer "In2.Cu")
		(net "M_C_CPU0_SA_DQ<27>")
	)
	(segment
		(start 342.797892 -240.700052)
		(end 342.33104 -240.434114)
		(width 0.10668)
		(layer "F.Cu")
		(net "M_C_CPU0_SA_DQ<26>")
	)
	(segment
		(start 326.371712 -240.067592)
		(end 326.243696 -240.067592)
		(width 0.0889)
		(layer "In2.Cu")
		(net "M_C_CPU0_SA_DQ<26>")
	)
	(segment
		(start 333.6925 -240.106708)
		(end 333.684118 -240.111534)
		(width 0.0889)
		(layer "In2.Cu")
		(net "M_C_CPU0_SA_DQ<26>")
	)
	(segment
		(start 341.212424 -240.106708)
		(end 341.204042 -240.111534)
		(width 0.0889)
		(layer "In2.Cu")
		(net "M_C_CPU0_SA_DQ<26>")
	)
	(segment
		(start 297.538902 -226.660202)
		(end 288.605214 -226.660202)
		(width 0.14478)
		(layer "In2.Cu")
		(net "M_C_CPU0_SA_DQ<26>")
	)
	(segment
		(start 305.943254 -225.810064)
		(end 305.093116 -226.660202)
		(width 0.14478)
		(layer "In2.Cu")
		(net "M_C_CPU0_SA_DQ<26>")
	)
	(segment
		(start 311.434734 -226.78009)
		(end 309.23992 -226.78009)
		(width 0.14478)
		(layer "In2.Cu")
		(net "M_C_CPU0_SA_DQ<26>")
	)
	(segment
		(start 339.698076 -240.111534)
		(end 339.689694 -240.106708)
		(width 0.0889)
		(layer "In2.Cu")
		(net "M_C_CPU0_SA_DQ<26>")
	)
	(segment
		(start 335.938114 -240.111534)
		(end 335.929732 -240.106708)
		(width 0.0889)
		(layer "In2.Cu")
		(net "M_C_CPU0_SA_DQ<26>")
	)
	(segment
		(start 305.093116 -226.660202)
		(end 301.90186 -226.660202)
		(width 0.14478)
		(layer "In2.Cu")
		(net "M_C_CPU0_SA_DQ<26>")
	)
	(segment
		(start 340.63813 -240.111534)
		(end 340.629748 -240.106708)
		(width 0.0889)
		(layer "In2.Cu")
		(net "M_C_CPU0_SA_DQ<26>")
	)
	(segment
		(start 308.553358 -225.810064)
		(end 305.943254 -225.810064)
		(width 0.14478)
		(layer "In2.Cu")
		(net "M_C_CPU0_SA_DQ<26>")
	)
	(segment
		(start 308.883558 -226.423728)
		(end 308.883558 -226.140264)
		(width 0.14478)
		(layer "In2.Cu")
		(net "M_C_CPU0_SA_DQ<26>")
	)
	(segment
		(start 328.41819 -240.111534)
		(end 328.409808 -240.106708)
		(width 0.0889)
		(layer "In2.Cu")
		(net "M_C_CPU0_SA_DQ<26>")
	)
	(segment
		(start 314.053474 -231.63403)
		(end 314.053474 -229.39883)
		(width 0.14478)
		(layer "In2.Cu")
		(net "M_C_CPU0_SA_DQ<26>")
	)
	(segment
		(start 342.177116 -240.168684)
		(end 342.081104 -240.143284)
		(width 0.0889)
		(layer "In2.Cu")
		(net "M_C_CPU0_SA_DQ<26>")
	)
	(segment
		(start 324.089014 -238.55299)
		(end 323.862954 -238.55299)
		(width 0.0889)
		(layer "In2.Cu")
		(net "M_C_CPU0_SA_DQ<26>")
	)
	(segment
		(start 298.38904 -225.810064)
		(end 297.538902 -226.660202)
		(width 0.14478)
		(layer "In2.Cu")
		(net "M_C_CPU0_SA_DQ<26>")
	)
	(segment
		(start 324.452234 -238.91621)
		(end 324.089014 -238.55299)
		(width 0.0889)
		(layer "In2.Cu")
		(net "M_C_CPU0_SA_DQ<26>")
	)
	(segment
		(start 326.243696 -240.067592)
		(end 325.092314 -238.91621)
		(width 0.0889)
		(layer "In2.Cu")
		(net "M_C_CPU0_SA_DQ<26>")
	)
	(segment
		(start 337.452462 -240.106708)
		(end 337.44408 -240.111534)
		(width 0.0889)
		(layer "In2.Cu")
		(net "M_C_CPU0_SA_DQ<26>")
	)
	(segment
		(start 301.051722 -225.810064)
		(end 298.38904 -225.810064)
		(width 0.14478)
		(layer "In2.Cu")
		(net "M_C_CPU0_SA_DQ<26>")
	)
	(segment
		(start 327.125076 -240.096294)
		(end 327.098914 -240.111534)
		(width 0.0889)
		(layer "In2.Cu")
		(net "M_C_CPU0_SA_DQ<26>")
	)
	(segment
		(start 331.238098 -240.111534)
		(end 331.229716 -240.106708)
		(width 0.0889)
		(layer "In2.Cu")
		(net "M_C_CPU0_SA_DQ<26>")
	)
	(segment
		(start 326.569324 -240.131092)
		(end 326.53605 -240.111788)
		(width 0.0889)
		(layer "In2.Cu")
		(net "M_C_CPU0_SA_DQ<26>")
	)
	(segment
		(start 336.878168 -240.111534)
		(end 336.869786 -240.106708)
		(width 0.0889)
		(layer "In2.Cu")
		(net "M_C_CPU0_SA_DQ<26>")
	)
	(segment
		(start 320.972434 -238.55299)
		(end 314.053474 -231.63403)
		(width 0.14478)
		(layer "In2.Cu")
		(net "M_C_CPU0_SA_DQ<26>")
	)
	(segment
		(start 301.90186 -226.660202)
		(end 301.051722 -225.810064)
		(width 0.14478)
		(layer "In2.Cu")
		(net "M_C_CPU0_SA_DQ<26>")
	)
	(segment
		(start 332.752446 -240.106708)
		(end 332.744064 -240.111534)
		(width 0.0889)
		(layer "In2.Cu")
		(net "M_C_CPU0_SA_DQ<26>")
	)
	(segment
		(start 309.23992 -226.78009)
		(end 308.883558 -226.423728)
		(width 0.14478)
		(layer "In2.Cu")
		(net "M_C_CPU0_SA_DQ<26>")
	)
	(segment
		(start 314.053474 -229.39883)
		(end 311.434734 -226.78009)
		(width 0.14478)
		(layer "In2.Cu")
		(net "M_C_CPU0_SA_DQ<26>")
	)
	(segment
		(start 323.862954 -238.55299)
		(end 320.972434 -238.55299)
		(width 0.14478)
		(layer "In2.Cu")
		(net "M_C_CPU0_SA_DQ<26>")
	)
	(segment
		(start 325.092314 -238.91621)
		(end 324.452234 -238.91621)
		(width 0.0889)
		(layer "In2.Cu")
		(net "M_C_CPU0_SA_DQ<26>")
	)
	(segment
		(start 332.178152 -240.111534)
		(end 332.16977 -240.106708)
		(width 0.0889)
		(layer "In2.Cu")
		(net "M_C_CPU0_SA_DQ<26>")
	)
	(segment
		(start 328.044048 -240.111534)
		(end 328.012298 -240.130076)
		(width 0.0889)
		(layer "In2.Cu")
		(net "M_C_CPU0_SA_DQ<26>")
	)
	(segment
		(start 342.33104 -240.434114)
		(end 342.177116 -240.168684)
		(width 0.0889)
		(layer "In2.Cu")
		(net "M_C_CPU0_SA_DQ<26>")
	)
	(segment
		(start 328.992484 -240.106708)
		(end 328.984102 -240.111534)
		(width 0.0889)
		(layer "In2.Cu")
		(net "M_C_CPU0_SA_DQ<26>")
	)
	(segment
		(start 288.605214 -226.660202)
		(end 288.180018 -226.235006)
		(width 0.14478)
		(layer "In2.Cu")
		(net "M_C_CPU0_SA_DQ<26>")
	)
	(segment
		(start 308.883558 -226.140264)
		(end 308.553358 -225.810064)
		(width 0.14478)
		(layer "In2.Cu")
		(net "M_C_CPU0_SA_DQ<26>")
	)
	(arc
		(start 336.869786 -240.106708)
		(mid 336.686278 -240.061214)
		(end 336.504026 -240.111534)
		(width 0.0889)
		(layer "In2.Cu")
		(net "M_C_CPU0_SA_DQ<26>")
	)
	(arc
		(start 336.504026 -240.111534)
		(mid 336.22107 -240.187711)
		(end 335.938114 -240.111534)
		(width 0.0889)
		(layer "In2.Cu")
		(net "M_C_CPU0_SA_DQ<26>")
	)
	(arc
		(start 329.358244 -240.111534)
		(mid 329.175993 -240.061184)
		(end 328.992484 -240.106708)
		(width 0.0889)
		(layer "In2.Cu")
		(net "M_C_CPU0_SA_DQ<26>")
	)
	(arc
		(start 333.118206 -240.111534)
		(mid 332.935955 -240.061184)
		(end 332.752446 -240.106708)
		(width 0.0889)
		(layer "In2.Cu")
		(net "M_C_CPU0_SA_DQ<26>")
	)
	(arc
		(start 331.80401 -240.111534)
		(mid 331.521054 -240.187711)
		(end 331.238098 -240.111534)
		(width 0.0889)
		(layer "In2.Cu")
		(net "M_C_CPU0_SA_DQ<26>")
	)
	(arc
		(start 330.298044 -240.111534)
		(mid 330.1111 -240.061279)
		(end 329.924156 -240.111534)
		(width 0.0889)
		(layer "In2.Cu")
		(net "M_C_CPU0_SA_DQ<26>")
	)
	(arc
		(start 331.229716 -240.106708)
		(mid 331.046208 -240.061214)
		(end 330.863956 -240.111534)
		(width 0.0889)
		(layer "In2.Cu")
		(net "M_C_CPU0_SA_DQ<26>")
	)
	(arc
		(start 340.629748 -240.106708)
		(mid 340.44624 -240.061214)
		(end 340.263988 -240.111534)
		(width 0.0889)
		(layer "In2.Cu")
		(net "M_C_CPU0_SA_DQ<26>")
	)
	(arc
		(start 327.475342 -240.11128)
		(mid 327.302076 -240.060249)
		(end 327.125076 -240.096294)
		(width 0.0889)
		(layer "In2.Cu")
		(net "M_C_CPU0_SA_DQ<26>")
	)
	(arc
		(start 341.578184 -240.111534)
		(mid 341.395933 -240.061184)
		(end 341.212424 -240.106708)
		(width 0.0889)
		(layer "In2.Cu")
		(net "M_C_CPU0_SA_DQ<26>")
	)
	(arc
		(start 328.012298 -240.130076)
		(mid 327.741427 -240.188662)
		(end 327.475342 -240.11128)
		(width 0.0889)
		(layer "In2.Cu")
		(net "M_C_CPU0_SA_DQ<26>")
	)
	(arc
		(start 326.53605 -240.111788)
		(mid 326.456805 -240.078811)
		(end 326.371712 -240.067592)
		(width 0.0889)
		(layer "In2.Cu")
		(net "M_C_CPU0_SA_DQ<26>")
	)
	(arc
		(start 329.924156 -240.111534)
		(mid 329.6412 -240.187711)
		(end 329.358244 -240.111534)
		(width 0.0889)
		(layer "In2.Cu")
		(net "M_C_CPU0_SA_DQ<26>")
	)
	(arc
		(start 340.263988 -240.111534)
		(mid 339.981032 -240.187711)
		(end 339.698076 -240.111534)
		(width 0.0889)
		(layer "In2.Cu")
		(net "M_C_CPU0_SA_DQ<26>")
	)
	(arc
		(start 338.384134 -240.111534)
		(mid 338.101178 -240.187711)
		(end 337.818222 -240.111534)
		(width 0.0889)
		(layer "In2.Cu")
		(net "M_C_CPU0_SA_DQ<26>")
	)
	(arc
		(start 335.563972 -240.111534)
		(mid 335.281016 -240.187711)
		(end 334.99806 -240.111534)
		(width 0.0889)
		(layer "In2.Cu")
		(net "M_C_CPU0_SA_DQ<26>")
	)
	(arc
		(start 337.44408 -240.111534)
		(mid 337.161124 -240.187711)
		(end 336.878168 -240.111534)
		(width 0.0889)
		(layer "In2.Cu")
		(net "M_C_CPU0_SA_DQ<26>")
	)
	(arc
		(start 339.689694 -240.106708)
		(mid 339.506186 -240.061214)
		(end 339.323934 -240.111534)
		(width 0.0889)
		(layer "In2.Cu")
		(net "M_C_CPU0_SA_DQ<26>")
	)
	(arc
		(start 333.684118 -240.111534)
		(mid 333.401162 -240.187711)
		(end 333.118206 -240.111534)
		(width 0.0889)
		(layer "In2.Cu")
		(net "M_C_CPU0_SA_DQ<26>")
	)
	(arc
		(start 327.098914 -240.111534)
		(mid 326.836555 -240.187453)
		(end 326.569324 -240.131092)
		(width 0.0889)
		(layer "In2.Cu")
		(net "M_C_CPU0_SA_DQ<26>")
	)
	(arc
		(start 334.99806 -240.111534)
		(mid 334.811116 -240.061279)
		(end 334.624172 -240.111534)
		(width 0.0889)
		(layer "In2.Cu")
		(net "M_C_CPU0_SA_DQ<26>")
	)
	(arc
		(start 339.323934 -240.111534)
		(mid 339.040978 -240.187711)
		(end 338.758022 -240.111534)
		(width 0.0889)
		(layer "In2.Cu")
		(net "M_C_CPU0_SA_DQ<26>")
	)
	(arc
		(start 328.984102 -240.111534)
		(mid 328.701146 -240.187711)
		(end 328.41819 -240.111534)
		(width 0.0889)
		(layer "In2.Cu")
		(net "M_C_CPU0_SA_DQ<26>")
	)
	(arc
		(start 332.744064 -240.111534)
		(mid 332.461108 -240.187711)
		(end 332.178152 -240.111534)
		(width 0.0889)
		(layer "In2.Cu")
		(net "M_C_CPU0_SA_DQ<26>")
	)
	(arc
		(start 334.05826 -240.111534)
		(mid 333.876009 -240.061184)
		(end 333.6925 -240.106708)
		(width 0.0889)
		(layer "In2.Cu")
		(net "M_C_CPU0_SA_DQ<26>")
	)
	(arc
		(start 332.16977 -240.106708)
		(mid 331.986262 -240.061214)
		(end 331.80401 -240.111534)
		(width 0.0889)
		(layer "In2.Cu")
		(net "M_C_CPU0_SA_DQ<26>")
	)
	(arc
		(start 341.204042 -240.111534)
		(mid 340.921086 -240.187711)
		(end 340.63813 -240.111534)
		(width 0.0889)
		(layer "In2.Cu")
		(net "M_C_CPU0_SA_DQ<26>")
	)
	(arc
		(start 334.624172 -240.111534)
		(mid 334.341216 -240.187711)
		(end 334.05826 -240.111534)
		(width 0.0889)
		(layer "In2.Cu")
		(net "M_C_CPU0_SA_DQ<26>")
	)
	(arc
		(start 338.758022 -240.111534)
		(mid 338.571078 -240.061279)
		(end 338.384134 -240.111534)
		(width 0.0889)
		(layer "In2.Cu")
		(net "M_C_CPU0_SA_DQ<26>")
	)
	(arc
		(start 328.409808 -240.106708)
		(mid 328.2263 -240.061214)
		(end 328.044048 -240.111534)
		(width 0.0889)
		(layer "In2.Cu")
		(net "M_C_CPU0_SA_DQ<26>")
	)
	(arc
		(start 330.863956 -240.111534)
		(mid 330.581 -240.187711)
		(end 330.298044 -240.111534)
		(width 0.0889)
		(layer "In2.Cu")
		(net "M_C_CPU0_SA_DQ<26>")
	)
	(arc
		(start 335.929732 -240.106708)
		(mid 335.746224 -240.061214)
		(end 335.563972 -240.111534)
		(width 0.0889)
		(layer "In2.Cu")
		(net "M_C_CPU0_SA_DQ<26>")
	)
	(arc
		(start 337.818222 -240.111534)
		(mid 337.635971 -240.061184)
		(end 337.452462 -240.106708)
		(width 0.0889)
		(layer "In2.Cu")
		(net "M_C_CPU0_SA_DQ<26>")
	)
	(arc
		(start 342.081104 -240.143284)
		(mid 341.825896 -240.186761)
		(end 341.578184 -240.111534)
		(width 0.0889)
		(layer "In2.Cu")
		(net "M_C_CPU0_SA_DQ<26>")
	)
	(segment
		(start 343.737946 -240.700052)
		(end 343.271094 -240.434114)
		(width 0.10668)
		(layer "F.Cu")
		(net "M_C_CPU0_SA_DQ<25>")
	)
	(segment
		(start 304.890932 -227.510086)
		(end 304.71364 -227.510086)
		(width 0.14478)
		(layer "In2.Cu")
		(net "M_C_CPU0_SA_DQ<25>")
	)
	(segment
		(start 333.6925 -240.76152)
		(end 333.684118 -240.756694)
		(width 0.0889)
		(layer "In2.Cu")
		(net "M_C_CPU0_SA_DQ<25>")
	)
	(segment
		(start 303.994058 -227.286058)
		(end 303.994058 -227.347018)
		(width 0.14478)
		(layer "In2.Cu")
		(net "M_C_CPU0_SA_DQ<25>")
	)
	(segment
		(start 299.500036 -226.660202)
		(end 299.336968 -226.497134)
		(width 0.14478)
		(layer "In2.Cu")
		(net "M_C_CPU0_SA_DQ<25>")
	)
	(segment
		(start 340.63813 -240.756694)
		(end 340.629748 -240.76152)
		(width 0.0889)
		(layer "In2.Cu")
		(net "M_C_CPU0_SA_DQ<25>")
	)
	(segment
		(start 305.740816 -226.660202)
		(end 304.890932 -227.510086)
		(width 0.14478)
		(layer "In2.Cu")
		(net "M_C_CPU0_SA_DQ<25>")
	)
	(segment
		(start 327.480168 -240.75644)
		(end 327.458324 -240.768886)
		(width 0.0889)
		(layer "In2.Cu")
		(net "M_C_CPU0_SA_DQ<25>")
	)
	(segment
		(start 300.373542 -226.28479)
		(end 300.210474 -226.447858)
		(width 0.14478)
		(layer "In2.Cu")
		(net "M_C_CPU0_SA_DQ<25>")
	)
	(segment
		(start 325.384414 -239.57661)
		(end 325.000874 -239.19307)
		(width 0.0889)
		(layer "In2.Cu")
		(net "M_C_CPU0_SA_DQ<25>")
	)
	(segment
		(start 298.943522 -226.27717)
		(end 298.780454 -226.440238)
		(width 0.14478)
		(layer "In2.Cu")
		(net "M_C_CPU0_SA_DQ<25>")
	)
	(segment
		(start 296.465498 -227.347018)
		(end 296.30243 -227.510086)
		(width 0.14478)
		(layer "In2.Cu")
		(net "M_C_CPU0_SA_DQ<25>")
	)
	(segment
		(start 302.099472 -227.510086)
		(end 301.892716 -227.510086)
		(width 0.14478)
		(layer "In2.Cu")
		(net "M_C_CPU0_SA_DQ<25>")
	)
	(segment
		(start 296.858944 -227.13061)
		(end 296.628566 -227.13061)
		(width 0.14478)
		(layer "In2.Cu")
		(net "M_C_CPU0_SA_DQ<25>")
	)
	(segment
		(start 304.550572 -227.286058)
		(end 304.387504 -227.12299)
		(width 0.14478)
		(layer "In2.Cu")
		(net "M_C_CPU0_SA_DQ<25>")
	)
	(segment
		(start 323.878194 -239.01019)
		(end 320.781934 -239.01019)
		(width 0.14478)
		(layer "In2.Cu")
		(net "M_C_CPU0_SA_DQ<25>")
	)
	(segment
		(start 304.550572 -227.347018)
		(end 304.550572 -227.286058)
		(width 0.14478)
		(layer "In2.Cu")
		(net "M_C_CPU0_SA_DQ<25>")
	)
	(segment
		(start 297.022012 -227.293678)
		(end 296.858944 -227.13061)
		(width 0.14478)
		(layer "In2.Cu")
		(net "M_C_CPU0_SA_DQ<25>")
	)
	(segment
		(start 296.30243 -227.510086)
		(end 292.705028 -227.510086)
		(width 0.14478)
		(layer "In2.Cu")
		(net "M_C_CPU0_SA_DQ<25>")
	)
	(segment
		(start 326.19696 -240.77422)
		(end 326.165718 -240.75644)
		(width 0.0889)
		(layer "In2.Cu")
		(net "M_C_CPU0_SA_DQ<25>")
	)
	(segment
		(start 327.10755 -240.756694)
		(end 327.078086 -240.739422)
		(width 0.0889)
		(layer "In2.Cu")
		(net "M_C_CPU0_SA_DQ<25>")
	)
	(segment
		(start 320.781934 -239.01019)
		(end 313.598814 -231.82707)
		(width 0.14478)
		(layer "In2.Cu")
		(net "M_C_CPU0_SA_DQ<25>")
	)
	(segment
		(start 343.425018 -240.699544)
		(end 343.402666 -240.782856)
		(width 0.0889)
		(layer "In2.Cu")
		(net "M_C_CPU0_SA_DQ<25>")
	)
	(segment
		(start 332.752446 -240.76152)
		(end 332.744064 -240.756694)
		(width 0.0889)
		(layer "In2.Cu")
		(net "M_C_CPU0_SA_DQ<25>")
	)
	(segment
		(start 313.598814 -229.62489)
		(end 311.213754 -227.23983)
		(width 0.14478)
		(layer "In2.Cu")
		(net "M_C_CPU0_SA_DQ<25>")
	)
	(segment
		(start 306.328064 -226.497134)
		(end 306.164996 -226.660202)
		(width 0.14478)
		(layer "In2.Cu")
		(net "M_C_CPU0_SA_DQ<25>")
	)
	(segment
		(start 325.384414 -239.985042)
		(end 325.384414 -239.57661)
		(width 0.0889)
		(layer "In2.Cu")
		(net "M_C_CPU0_SA_DQ<25>")
	)
	(segment
		(start 304.71364 -227.510086)
		(end 304.550572 -227.347018)
		(width 0.14478)
		(layer "In2.Cu")
		(net "M_C_CPU0_SA_DQ<25>")
	)
	(segment
		(start 306.884578 -226.497134)
		(end 306.884578 -226.435158)
		(width 0.14478)
		(layer "In2.Cu")
		(net "M_C_CPU0_SA_DQ<25>")
	)
	(segment
		(start 304.157126 -227.12299)
		(end 303.994058 -227.286058)
		(width 0.14478)
		(layer "In2.Cu")
		(net "M_C_CPU0_SA_DQ<25>")
	)
	(segment
		(start 336.878168 -240.756694)
		(end 336.869786 -240.76152)
		(width 0.0889)
		(layer "In2.Cu")
		(net "M_C_CPU0_SA_DQ<25>")
	)
	(segment
		(start 302.655986 -227.12299)
		(end 302.425608 -227.12299)
		(width 0.14478)
		(layer "In2.Cu")
		(net "M_C_CPU0_SA_DQ<25>")
	)
	(segment
		(start 327.50633 -240.741454)
		(end 327.480168 -240.75644)
		(width 0.0889)
		(layer "In2.Cu")
		(net "M_C_CPU0_SA_DQ<25>")
	)
	(segment
		(start 332.178152 -240.756694)
		(end 332.16977 -240.76152)
		(width 0.0889)
		(layer "In2.Cu")
		(net "M_C_CPU0_SA_DQ<25>")
	)
	(segment
		(start 324.261734 -239.19307)
		(end 324.078854 -239.01019)
		(width 0.0889)
		(layer "In2.Cu")
		(net "M_C_CPU0_SA_DQ<25>")
	)
	(segment
		(start 301.892716 -227.510086)
		(end 301.042832 -226.660202)
		(width 0.14478)
		(layer "In2.Cu")
		(net "M_C_CPU0_SA_DQ<25>")
	)
	(segment
		(start 311.213754 -227.23983)
		(end 309.037482 -227.23983)
		(width 0.14478)
		(layer "In2.Cu")
		(net "M_C_CPU0_SA_DQ<25>")
	)
	(segment
		(start 296.465498 -227.293678)
		(end 296.465498 -227.347018)
		(width 0.14478)
		(layer "In2.Cu")
		(net "M_C_CPU0_SA_DQ<25>")
	)
	(segment
		(start 300.930056 -226.660202)
		(end 300.766988 -226.497134)
		(width 0.14478)
		(layer "In2.Cu")
		(net "M_C_CPU0_SA_DQ<25>")
	)
	(segment
		(start 296.628566 -227.13061)
		(end 296.465498 -227.293678)
		(width 0.14478)
		(layer "In2.Cu")
		(net "M_C_CPU0_SA_DQ<25>")
	)
	(segment
		(start 300.210474 -226.447858)
		(end 300.210474 -226.497134)
		(width 0.14478)
		(layer "In2.Cu")
		(net "M_C_CPU0_SA_DQ<25>")
	)
	(segment
		(start 299.336968 -226.497134)
		(end 299.336968 -226.440238)
		(width 0.14478)
		(layer "In2.Cu")
		(net "M_C_CPU0_SA_DQ<25>")
	)
	(segment
		(start 299.1739 -226.27717)
		(end 298.943522 -226.27717)
		(width 0.14478)
		(layer "In2.Cu")
		(net "M_C_CPU0_SA_DQ<25>")
	)
	(segment
		(start 300.60392 -226.28479)
		(end 300.373542 -226.28479)
		(width 0.14478)
		(layer "In2.Cu")
		(net "M_C_CPU0_SA_DQ<25>")
	)
	(segment
		(start 313.598814 -231.82707)
		(end 313.598814 -229.62489)
		(width 0.14478)
		(layer "In2.Cu")
		(net "M_C_CPU0_SA_DQ<25>")
	)
	(segment
		(start 331.238098 -240.756694)
		(end 331.229716 -240.76152)
		(width 0.0889)
		(layer "In2.Cu")
		(net "M_C_CPU0_SA_DQ<25>")
	)
	(segment
		(start 298.617386 -226.660202)
		(end 298.217336 -226.660202)
		(width 0.14478)
		(layer "In2.Cu")
		(net "M_C_CPU0_SA_DQ<25>")
	)
	(segment
		(start 307.047646 -226.660202)
		(end 306.884578 -226.497134)
		(width 0.14478)
		(layer "In2.Cu")
		(net "M_C_CPU0_SA_DQ<25>")
	)
	(segment
		(start 328.41819 -240.756694)
		(end 328.409808 -240.76152)
		(width 0.0889)
		(layer "In2.Cu")
		(net "M_C_CPU0_SA_DQ<25>")
	)
	(segment
		(start 298.780454 -226.497134)
		(end 298.617386 -226.660202)
		(width 0.14478)
		(layer "In2.Cu")
		(net "M_C_CPU0_SA_DQ<25>")
	)
	(segment
		(start 298.217336 -226.660202)
		(end 297.367452 -227.510086)
		(width 0.14478)
		(layer "In2.Cu")
		(net "M_C_CPU0_SA_DQ<25>")
	)
	(segment
		(start 300.766988 -226.447858)
		(end 300.60392 -226.28479)
		(width 0.14478)
		(layer "In2.Cu")
		(net "M_C_CPU0_SA_DQ<25>")
	)
	(segment
		(start 297.022012 -227.347018)
		(end 297.022012 -227.293678)
		(width 0.14478)
		(layer "In2.Cu")
		(net "M_C_CPU0_SA_DQ<25>")
	)
	(segment
		(start 292.705028 -227.510086)
		(end 292.280086 -227.085144)
		(width 0.14478)
		(layer "In2.Cu")
		(net "M_C_CPU0_SA_DQ<25>")
	)
	(segment
		(start 302.819054 -227.347018)
		(end 302.819054 -227.286058)
		(width 0.14478)
		(layer "In2.Cu")
		(net "M_C_CPU0_SA_DQ<25>")
	)
	(segment
		(start 303.994058 -227.347018)
		(end 303.83099 -227.510086)
		(width 0.14478)
		(layer "In2.Cu")
		(net "M_C_CPU0_SA_DQ<25>")
	)
	(segment
		(start 301.042832 -226.660202)
		(end 300.930056 -226.660202)
		(width 0.14478)
		(layer "In2.Cu")
		(net "M_C_CPU0_SA_DQ<25>")
	)
	(segment
		(start 306.164996 -226.660202)
		(end 305.740816 -226.660202)
		(width 0.14478)
		(layer "In2.Cu")
		(net "M_C_CPU0_SA_DQ<25>")
	)
	(segment
		(start 304.387504 -227.12299)
		(end 304.157126 -227.12299)
		(width 0.14478)
		(layer "In2.Cu")
		(net "M_C_CPU0_SA_DQ<25>")
	)
	(segment
		(start 302.425608 -227.12299)
		(end 302.26254 -227.286058)
		(width 0.14478)
		(layer "In2.Cu")
		(net "M_C_CPU0_SA_DQ<25>")
	)
	(segment
		(start 326.124062 -240.72469)
		(end 325.384414 -239.985042)
		(width 0.0889)
		(layer "In2.Cu")
		(net "M_C_CPU0_SA_DQ<25>")
	)
	(segment
		(start 308.457854 -226.660202)
		(end 307.047646 -226.660202)
		(width 0.14478)
		(layer "In2.Cu")
		(net "M_C_CPU0_SA_DQ<25>")
	)
	(segment
		(start 300.210474 -226.497134)
		(end 300.047406 -226.660202)
		(width 0.14478)
		(layer "In2.Cu")
		(net "M_C_CPU0_SA_DQ<25>")
	)
	(segment
		(start 324.078854 -239.01019)
		(end 323.878194 -239.01019)
		(width 0.0889)
		(layer "In2.Cu")
		(net "M_C_CPU0_SA_DQ<25>")
	)
	(segment
		(start 306.72151 -226.27209)
		(end 306.491132 -226.27209)
		(width 0.14478)
		(layer "In2.Cu")
		(net "M_C_CPU0_SA_DQ<25>")
	)
	(segment
		(start 297.367452 -227.510086)
		(end 297.18508 -227.510086)
		(width 0.14478)
		(layer "In2.Cu")
		(net "M_C_CPU0_SA_DQ<25>")
	)
	(segment
		(start 343.271094 -240.434114)
		(end 343.425018 -240.699544)
		(width 0.0889)
		(layer "In2.Cu")
		(net "M_C_CPU0_SA_DQ<25>")
	)
	(segment
		(start 328.992484 -240.76152)
		(end 328.984102 -240.756694)
		(width 0.0889)
		(layer "In2.Cu")
		(net "M_C_CPU0_SA_DQ<25>")
	)
	(segment
		(start 302.26254 -227.286058)
		(end 302.26254 -227.347018)
		(width 0.14478)
		(layer "In2.Cu")
		(net "M_C_CPU0_SA_DQ<25>")
	)
	(segment
		(start 325.000874 -239.19307)
		(end 324.261734 -239.19307)
		(width 0.0889)
		(layer "In2.Cu")
		(net "M_C_CPU0_SA_DQ<25>")
	)
	(segment
		(start 302.819054 -227.286058)
		(end 302.655986 -227.12299)
		(width 0.14478)
		(layer "In2.Cu")
		(net "M_C_CPU0_SA_DQ<25>")
	)
	(segment
		(start 342.152478 -240.76152)
		(end 342.144096 -240.756694)
		(width 0.0889)
		(layer "In2.Cu")
		(net "M_C_CPU0_SA_DQ<25>")
	)
	(segment
		(start 309.037482 -227.23983)
		(end 308.457854 -226.660202)
		(width 0.14478)
		(layer "In2.Cu")
		(net "M_C_CPU0_SA_DQ<25>")
	)
	(segment
		(start 299.336968 -226.440238)
		(end 299.1739 -226.27717)
		(width 0.14478)
		(layer "In2.Cu")
		(net "M_C_CPU0_SA_DQ<25>")
	)
	(segment
		(start 303.83099 -227.510086)
		(end 302.982122 -227.510086)
		(width 0.14478)
		(layer "In2.Cu")
		(net "M_C_CPU0_SA_DQ<25>")
	)
	(segment
		(start 306.328064 -226.435158)
		(end 306.328064 -226.497134)
		(width 0.14478)
		(layer "In2.Cu")
		(net "M_C_CPU0_SA_DQ<25>")
	)
	(segment
		(start 341.212424 -240.76152)
		(end 341.204042 -240.756694)
		(width 0.0889)
		(layer "In2.Cu")
		(net "M_C_CPU0_SA_DQ<25>")
	)
	(segment
		(start 298.780454 -226.440238)
		(end 298.780454 -226.497134)
		(width 0.14478)
		(layer "In2.Cu")
		(net "M_C_CPU0_SA_DQ<25>")
	)
	(segment
		(start 306.491132 -226.27209)
		(end 306.328064 -226.435158)
		(width 0.14478)
		(layer "In2.Cu")
		(net "M_C_CPU0_SA_DQ<25>")
	)
	(segment
		(start 306.884578 -226.435158)
		(end 306.72151 -226.27209)
		(width 0.14478)
		(layer "In2.Cu")
		(net "M_C_CPU0_SA_DQ<25>")
	)
	(segment
		(start 339.698076 -240.756694)
		(end 339.689694 -240.76152)
		(width 0.0889)
		(layer "In2.Cu")
		(net "M_C_CPU0_SA_DQ<25>")
	)
	(segment
		(start 302.982122 -227.510086)
		(end 302.819054 -227.347018)
		(width 0.14478)
		(layer "In2.Cu")
		(net "M_C_CPU0_SA_DQ<25>")
	)
	(segment
		(start 297.18508 -227.510086)
		(end 297.022012 -227.347018)
		(width 0.14478)
		(layer "In2.Cu")
		(net "M_C_CPU0_SA_DQ<25>")
	)
	(segment
		(start 335.938114 -240.756694)
		(end 335.929732 -240.76152)
		(width 0.0889)
		(layer "In2.Cu")
		(net "M_C_CPU0_SA_DQ<25>")
	)
	(segment
		(start 337.452462 -240.76152)
		(end 337.44408 -240.756694)
		(width 0.0889)
		(layer "In2.Cu")
		(net "M_C_CPU0_SA_DQ<25>")
	)
	(segment
		(start 300.766988 -226.497134)
		(end 300.766988 -226.447858)
		(width 0.14478)
		(layer "In2.Cu")
		(net "M_C_CPU0_SA_DQ<25>")
	)
	(segment
		(start 302.26254 -227.347018)
		(end 302.099472 -227.510086)
		(width 0.14478)
		(layer "In2.Cu")
		(net "M_C_CPU0_SA_DQ<25>")
	)
	(segment
		(start 300.047406 -226.660202)
		(end 299.500036 -226.660202)
		(width 0.14478)
		(layer "In2.Cu")
		(net "M_C_CPU0_SA_DQ<25>")
	)
	(arc
		(start 330.863956 -240.756694)
		(mid 330.581 -240.680517)
		(end 330.298044 -240.756694)
		(width 0.0889)
		(layer "In2.Cu")
		(net "M_C_CPU0_SA_DQ<25>")
	)
	(arc
		(start 336.869786 -240.76152)
		(mid 336.686278 -240.807014)
		(end 336.504026 -240.756694)
		(width 0.0889)
		(layer "In2.Cu")
		(net "M_C_CPU0_SA_DQ<25>")
	)
	(arc
		(start 326.165718 -240.75644)
		(mid 326.143829 -240.741958)
		(end 326.124062 -240.72469)
		(width 0.0889)
		(layer "In2.Cu")
		(net "M_C_CPU0_SA_DQ<25>")
	)
	(arc
		(start 327.078086 -240.739422)
		(mid 326.806666 -240.679745)
		(end 326.539606 -240.756694)
		(width 0.0889)
		(layer "In2.Cu")
		(net "M_C_CPU0_SA_DQ<25>")
	)
	(arc
		(start 340.629748 -240.76152)
		(mid 340.44624 -240.807014)
		(end 340.263988 -240.756694)
		(width 0.0889)
		(layer "In2.Cu")
		(net "M_C_CPU0_SA_DQ<25>")
	)
	(arc
		(start 334.05826 -240.756694)
		(mid 333.876009 -240.807044)
		(end 333.6925 -240.76152)
		(width 0.0889)
		(layer "In2.Cu")
		(net "M_C_CPU0_SA_DQ<25>")
	)
	(arc
		(start 329.358244 -240.756694)
		(mid 329.175993 -240.807044)
		(end 328.992484 -240.76152)
		(width 0.0889)
		(layer "In2.Cu")
		(net "M_C_CPU0_SA_DQ<25>")
	)
	(arc
		(start 331.80401 -240.756694)
		(mid 331.521054 -240.680517)
		(end 331.238098 -240.756694)
		(width 0.0889)
		(layer "In2.Cu")
		(net "M_C_CPU0_SA_DQ<25>")
	)
	(arc
		(start 343.08415 -240.756694)
		(mid 342.801194 -240.680517)
		(end 342.518238 -240.756694)
		(width 0.0889)
		(layer "In2.Cu")
		(net "M_C_CPU0_SA_DQ<25>")
	)
	(arc
		(start 328.409808 -240.76152)
		(mid 328.2263 -240.807014)
		(end 328.044048 -240.756694)
		(width 0.0889)
		(layer "In2.Cu")
		(net "M_C_CPU0_SA_DQ<25>")
	)
	(arc
		(start 341.204042 -240.756694)
		(mid 340.921086 -240.680517)
		(end 340.63813 -240.756694)
		(width 0.0889)
		(layer "In2.Cu")
		(net "M_C_CPU0_SA_DQ<25>")
	)
	(arc
		(start 338.384134 -240.756694)
		(mid 338.101178 -240.680517)
		(end 337.818222 -240.756694)
		(width 0.0889)
		(layer "In2.Cu")
		(net "M_C_CPU0_SA_DQ<25>")
	)
	(arc
		(start 327.458324 -240.768886)
		(mid 327.281396 -240.806714)
		(end 327.10755 -240.756694)
		(width 0.0889)
		(layer "In2.Cu")
		(net "M_C_CPU0_SA_DQ<25>")
	)
	(arc
		(start 328.984102 -240.756694)
		(mid 328.701146 -240.680517)
		(end 328.41819 -240.756694)
		(width 0.0889)
		(layer "In2.Cu")
		(net "M_C_CPU0_SA_DQ<25>")
	)
	(arc
		(start 338.758022 -240.756694)
		(mid 338.571078 -240.806949)
		(end 338.384134 -240.756694)
		(width 0.0889)
		(layer "In2.Cu")
		(net "M_C_CPU0_SA_DQ<25>")
	)
	(arc
		(start 341.578184 -240.756694)
		(mid 341.395933 -240.807044)
		(end 341.212424 -240.76152)
		(width 0.0889)
		(layer "In2.Cu")
		(net "M_C_CPU0_SA_DQ<25>")
	)
	(arc
		(start 340.263988 -240.756694)
		(mid 339.981032 -240.680517)
		(end 339.698076 -240.756694)
		(width 0.0889)
		(layer "In2.Cu")
		(net "M_C_CPU0_SA_DQ<25>")
	)
	(arc
		(start 333.118206 -240.756694)
		(mid 332.935955 -240.807044)
		(end 332.752446 -240.76152)
		(width 0.0889)
		(layer "In2.Cu")
		(net "M_C_CPU0_SA_DQ<25>")
	)
	(arc
		(start 334.624172 -240.756694)
		(mid 334.341216 -240.680517)
		(end 334.05826 -240.756694)
		(width 0.0889)
		(layer "In2.Cu")
		(net "M_C_CPU0_SA_DQ<25>")
	)
	(arc
		(start 335.563972 -240.756694)
		(mid 335.281016 -240.680517)
		(end 334.99806 -240.756694)
		(width 0.0889)
		(layer "In2.Cu")
		(net "M_C_CPU0_SA_DQ<25>")
	)
	(arc
		(start 343.402666 -240.782856)
		(mid 343.240477 -240.805591)
		(end 343.08415 -240.756694)
		(width 0.0889)
		(layer "In2.Cu")
		(net "M_C_CPU0_SA_DQ<25>")
	)
	(arc
		(start 342.518238 -240.756694)
		(mid 342.335987 -240.807044)
		(end 342.152478 -240.76152)
		(width 0.0889)
		(layer "In2.Cu")
		(net "M_C_CPU0_SA_DQ<25>")
	)
	(arc
		(start 326.539606 -240.756694)
		(mid 326.370419 -240.807102)
		(end 326.19696 -240.77422)
		(width 0.0889)
		(layer "In2.Cu")
		(net "M_C_CPU0_SA_DQ<25>")
	)
	(arc
		(start 339.689694 -240.76152)
		(mid 339.506186 -240.807014)
		(end 339.323934 -240.756694)
		(width 0.0889)
		(layer "In2.Cu")
		(net "M_C_CPU0_SA_DQ<25>")
	)
	(arc
		(start 330.298044 -240.756694)
		(mid 330.1111 -240.806949)
		(end 329.924156 -240.756694)
		(width 0.0889)
		(layer "In2.Cu")
		(net "M_C_CPU0_SA_DQ<25>")
	)
	(arc
		(start 335.929732 -240.76152)
		(mid 335.746224 -240.807014)
		(end 335.563972 -240.756694)
		(width 0.0889)
		(layer "In2.Cu")
		(net "M_C_CPU0_SA_DQ<25>")
	)
	(arc
		(start 337.44408 -240.756694)
		(mid 337.161124 -240.680517)
		(end 336.878168 -240.756694)
		(width 0.0889)
		(layer "In2.Cu")
		(net "M_C_CPU0_SA_DQ<25>")
	)
	(arc
		(start 333.684118 -240.756694)
		(mid 333.401162 -240.680517)
		(end 333.118206 -240.756694)
		(width 0.0889)
		(layer "In2.Cu")
		(net "M_C_CPU0_SA_DQ<25>")
	)
	(arc
		(start 332.16977 -240.76152)
		(mid 331.986262 -240.807014)
		(end 331.80401 -240.756694)
		(width 0.0889)
		(layer "In2.Cu")
		(net "M_C_CPU0_SA_DQ<25>")
	)
	(arc
		(start 342.144096 -240.756694)
		(mid 341.86114 -240.680517)
		(end 341.578184 -240.756694)
		(width 0.0889)
		(layer "In2.Cu")
		(net "M_C_CPU0_SA_DQ<25>")
	)
	(arc
		(start 329.924156 -240.756694)
		(mid 329.6412 -240.680517)
		(end 329.358244 -240.756694)
		(width 0.0889)
		(layer "In2.Cu")
		(net "M_C_CPU0_SA_DQ<25>")
	)
	(arc
		(start 331.229716 -240.76152)
		(mid 331.046208 -240.807014)
		(end 330.863956 -240.756694)
		(width 0.0889)
		(layer "In2.Cu")
		(net "M_C_CPU0_SA_DQ<25>")
	)
	(arc
		(start 336.504026 -240.756694)
		(mid 336.22107 -240.680517)
		(end 335.938114 -240.756694)
		(width 0.0889)
		(layer "In2.Cu")
		(net "M_C_CPU0_SA_DQ<25>")
	)
	(arc
		(start 334.99806 -240.756694)
		(mid 334.811116 -240.806949)
		(end 334.624172 -240.756694)
		(width 0.0889)
		(layer "In2.Cu")
		(net "M_C_CPU0_SA_DQ<25>")
	)
	(arc
		(start 328.044048 -240.756694)
		(mid 327.777118 -240.680745)
		(end 327.50633 -240.741454)
		(width 0.0889)
		(layer "In2.Cu")
		(net "M_C_CPU0_SA_DQ<25>")
	)
	(arc
		(start 339.323934 -240.756694)
		(mid 339.040978 -240.680517)
		(end 338.758022 -240.756694)
		(width 0.0889)
		(layer "In2.Cu")
		(net "M_C_CPU0_SA_DQ<25>")
	)
	(arc
		(start 332.744064 -240.756694)
		(mid 332.461108 -240.680517)
		(end 332.178152 -240.756694)
		(width 0.0889)
		(layer "In2.Cu")
		(net "M_C_CPU0_SA_DQ<25>")
	)
	(arc
		(start 337.818222 -240.756694)
		(mid 337.635971 -240.807044)
		(end 337.452462 -240.76152)
		(width 0.0889)
		(layer "In2.Cu")
		(net "M_C_CPU0_SA_DQ<25>")
	)
	(segment
		(start 342.327992 -239.890046)
		(end 341.86114 -239.624108)
		(width 0.10668)
		(layer "F.Cu")
		(net "M_C_CPU0_SA_DQ<24>")
	)
	(segment
		(start 329.819762 -239.951514)
		(end 329.828144 -239.946688)
		(width 0.0889)
		(layer "In2.Cu")
		(net "M_C_CPU0_SA_DQ<24>")
	)
	(segment
		(start 309.358538 -226.133152)
		(end 309.543196 -226.31781)
		(width 0.14478)
		(layer "In2.Cu")
		(net "M_C_CPU0_SA_DQ<24>")
	)
	(segment
		(start 294.534336 -226.0346)
		(end 294.534336 -225.96983)
		(width 0.14478)
		(layer "In2.Cu")
		(net "M_C_CPU0_SA_DQ<24>")
	)
	(segment
		(start 330.394056 -239.946688)
		(end 330.402438 -239.951514)
		(width 0.0889)
		(layer "In2.Cu")
		(net "M_C_CPU0_SA_DQ<24>")
	)
	(segment
		(start 310.61406 -225.30943)
		(end 310.806846 -225.502216)
		(width 0.14478)
		(layer "In2.Cu")
		(net "M_C_CPU0_SA_DQ<24>")
	)
	(segment
		(start 326.404986 -239.70869)
		(end 326.658478 -239.962182)
		(width 0.0889)
		(layer "In2.Cu")
		(net "M_C_CPU0_SA_DQ<24>")
	)
	(segment
		(start 293.027862 -226.197668)
		(end 293.25824 -226.197668)
		(width 0.14478)
		(layer "In2.Cu")
		(net "M_C_CPU0_SA_DQ<24>")
	)
	(segment
		(start 297.106848 -226.18573)
		(end 297.269916 -226.022662)
		(width 0.14478)
		(layer "In2.Cu")
		(net "M_C_CPU0_SA_DQ<24>")
	)
	(segment
		(start 304.33391 -226.030282)
		(end 304.496978 -226.19335)
		(width 0.14478)
		(layer "In2.Cu")
		(net "M_C_CPU0_SA_DQ<24>")
	)
	(segment
		(start 293.814754 -225.55073)
		(end 293.977822 -225.713798)
		(width 0.14478)
		(layer "In2.Cu")
		(net "M_C_CPU0_SA_DQ<24>")
	)
	(segment
		(start 293.977822 -225.713798)
		(end 293.977822 -226.0346)
		(width 0.14478)
		(layer "In2.Cu")
		(net "M_C_CPU0_SA_DQ<24>")
	)
	(segment
		(start 301.892716 -225.810064)
		(end 304.170842 -225.810064)
		(width 0.14478)
		(layer "In2.Cu")
		(net "M_C_CPU0_SA_DQ<24>")
	)
	(segment
		(start 294.534336 -225.96983)
		(end 294.694102 -225.810064)
		(width 0.14478)
		(layer "In2.Cu")
		(net "M_C_CPU0_SA_DQ<24>")
	)
	(segment
		(start 297.269916 -226.022662)
		(end 297.269916 -225.973132)
		(width 0.14478)
		(layer "In2.Cu")
		(net "M_C_CPU0_SA_DQ<24>")
	)
	(segment
		(start 326.29729 -239.70869)
		(end 326.404986 -239.70869)
		(width 0.0889)
		(layer "In2.Cu")
		(net "M_C_CPU0_SA_DQ<24>")
	)
	(segment
		(start 325.22287 -238.63427)
		(end 326.29729 -239.70869)
		(width 0.0889)
		(layer "In2.Cu")
		(net "M_C_CPU0_SA_DQ<24>")
	)
	(segment
		(start 294.371268 -226.197668)
		(end 294.534336 -226.0346)
		(width 0.14478)
		(layer "In2.Cu")
		(net "M_C_CPU0_SA_DQ<24>")
	)
	(segment
		(start 305.27752 -225.810064)
		(end 306.127404 -224.96018)
		(width 0.14478)
		(layer "In2.Cu")
		(net "M_C_CPU0_SA_DQ<24>")
	)
	(segment
		(start 309.358538 -225.741992)
		(end 309.358538 -226.133152)
		(width 0.14478)
		(layer "In2.Cu")
		(net "M_C_CPU0_SA_DQ<24>")
	)
	(segment
		(start 331.33411 -239.946688)
		(end 331.342492 -239.951514)
		(width 0.0889)
		(layer "In2.Cu")
		(net "M_C_CPU0_SA_DQ<24>")
	)
	(segment
		(start 310.806846 -226.125024)
		(end 310.999632 -226.31781)
		(width 0.14478)
		(layer "In2.Cu")
		(net "M_C_CPU0_SA_DQ<24>")
	)
	(segment
		(start 292.280086 -225.385122)
		(end 292.864794 -225.96983)
		(width 0.14478)
		(layer "In2.Cu")
		(net "M_C_CPU0_SA_DQ<24>")
	)
	(segment
		(start 309.543196 -226.31781)
		(end 309.955946 -226.31781)
		(width 0.14478)
		(layer "In2.Cu")
		(net "M_C_CPU0_SA_DQ<24>")
	)
	(segment
		(start 310.148732 -226.125024)
		(end 310.148732 -225.502216)
		(width 0.14478)
		(layer "In2.Cu")
		(net "M_C_CPU0_SA_DQ<24>")
	)
	(segment
		(start 321.173094 -238.09833)
		(end 323.898514 -238.09833)
		(width 0.14478)
		(layer "In2.Cu")
		(net "M_C_CPU0_SA_DQ<24>")
	)
	(segment
		(start 294.14089 -226.197668)
		(end 294.371268 -226.197668)
		(width 0.14478)
		(layer "In2.Cu")
		(net "M_C_CPU0_SA_DQ<24>")
	)
	(segment
		(start 293.421308 -226.0346)
		(end 293.421308 -225.713798)
		(width 0.14478)
		(layer "In2.Cu")
		(net "M_C_CPU0_SA_DQ<24>")
	)
	(segment
		(start 341.992712 -239.97285)
		(end 342.015064 -239.889538)
		(width 0.0889)
		(layer "In2.Cu")
		(net "M_C_CPU0_SA_DQ<24>")
	)
	(segment
		(start 314.515754 -229.19563)
		(end 314.515754 -231.44099)
		(width 0.14478)
		(layer "In2.Cu")
		(net "M_C_CPU0_SA_DQ<24>")
	)
	(segment
		(start 310.148732 -225.502216)
		(end 310.341518 -225.30943)
		(width 0.14478)
		(layer "In2.Cu")
		(net "M_C_CPU0_SA_DQ<24>")
	)
	(segment
		(start 335.094072 -239.946688)
		(end 335.102454 -239.951514)
		(width 0.0889)
		(layer "In2.Cu")
		(net "M_C_CPU0_SA_DQ<24>")
	)
	(segment
		(start 294.694102 -225.810064)
		(end 296.550334 -225.810064)
		(width 0.14478)
		(layer "In2.Cu")
		(net "M_C_CPU0_SA_DQ<24>")
	)
	(segment
		(start 338.27974 -239.951514)
		(end 338.288122 -239.946688)
		(width 0.0889)
		(layer "In2.Cu")
		(net "M_C_CPU0_SA_DQ<24>")
	)
	(segment
		(start 339.794088 -239.946688)
		(end 339.80247 -239.951514)
		(width 0.0889)
		(layer "In2.Cu")
		(net "M_C_CPU0_SA_DQ<24>")
	)
	(segment
		(start 296.87647 -226.18573)
		(end 297.106848 -226.18573)
		(width 0.14478)
		(layer "In2.Cu")
		(net "M_C_CPU0_SA_DQ<24>")
	)
	(segment
		(start 306.127404 -224.96018)
		(end 308.576726 -224.96018)
		(width 0.14478)
		(layer "In2.Cu")
		(net "M_C_CPU0_SA_DQ<24>")
	)
	(segment
		(start 293.977822 -226.0346)
		(end 294.14089 -226.197668)
		(width 0.14478)
		(layer "In2.Cu")
		(net "M_C_CPU0_SA_DQ<24>")
	)
	(segment
		(start 311.637934 -226.31781)
		(end 314.515754 -229.19563)
		(width 0.14478)
		(layer "In2.Cu")
		(net "M_C_CPU0_SA_DQ<24>")
	)
	(segment
		(start 310.341518 -225.30943)
		(end 310.61406 -225.30943)
		(width 0.14478)
		(layer "In2.Cu")
		(net "M_C_CPU0_SA_DQ<24>")
	)
	(segment
		(start 314.515754 -231.44099)
		(end 321.173094 -238.09833)
		(width 0.14478)
		(layer "In2.Cu")
		(net "M_C_CPU0_SA_DQ<24>")
	)
	(segment
		(start 297.432984 -225.810064)
		(end 297.74388 -225.810064)
		(width 0.14478)
		(layer "In2.Cu")
		(net "M_C_CPU0_SA_DQ<24>")
	)
	(segment
		(start 304.890424 -225.973132)
		(end 305.053492 -225.810064)
		(width 0.14478)
		(layer "In2.Cu")
		(net "M_C_CPU0_SA_DQ<24>")
	)
	(segment
		(start 308.576726 -224.96018)
		(end 309.358538 -225.741992)
		(width 0.14478)
		(layer "In2.Cu")
		(net "M_C_CPU0_SA_DQ<24>")
	)
	(segment
		(start 336.034126 -239.946688)
		(end 336.042508 -239.951514)
		(width 0.0889)
		(layer "In2.Cu")
		(net "M_C_CPU0_SA_DQ<24>")
	)
	(segment
		(start 293.584376 -225.55073)
		(end 293.814754 -225.55073)
		(width 0.14478)
		(layer "In2.Cu")
		(net "M_C_CPU0_SA_DQ<24>")
	)
	(segment
		(start 297.269916 -225.973132)
		(end 297.432984 -225.810064)
		(width 0.14478)
		(layer "In2.Cu")
		(net "M_C_CPU0_SA_DQ<24>")
	)
	(segment
		(start 304.727356 -226.19335)
		(end 304.890424 -226.030282)
		(width 0.14478)
		(layer "In2.Cu")
		(net "M_C_CPU0_SA_DQ<24>")
	)
	(segment
		(start 333.579724 -239.951514)
		(end 333.588106 -239.946688)
		(width 0.0889)
		(layer "In2.Cu")
		(net "M_C_CPU0_SA_DQ<24>")
	)
	(segment
		(start 296.713402 -225.973132)
		(end 296.713402 -226.022662)
		(width 0.14478)
		(layer "In2.Cu")
		(net "M_C_CPU0_SA_DQ<24>")
	)
	(segment
		(start 334.519778 -239.951514)
		(end 334.52816 -239.946688)
		(width 0.0889)
		(layer "In2.Cu")
		(net "M_C_CPU0_SA_DQ<24>")
	)
	(segment
		(start 305.053492 -225.810064)
		(end 305.27752 -225.810064)
		(width 0.14478)
		(layer "In2.Cu")
		(net "M_C_CPU0_SA_DQ<24>")
	)
	(segment
		(start 297.74388 -225.810064)
		(end 298.593764 -224.96018)
		(width 0.14478)
		(layer "In2.Cu")
		(net "M_C_CPU0_SA_DQ<24>")
	)
	(segment
		(start 296.713402 -226.022662)
		(end 296.87647 -226.18573)
		(width 0.14478)
		(layer "In2.Cu")
		(net "M_C_CPU0_SA_DQ<24>")
	)
	(segment
		(start 296.550334 -225.810064)
		(end 296.713402 -225.973132)
		(width 0.14478)
		(layer "In2.Cu")
		(net "M_C_CPU0_SA_DQ<24>")
	)
	(segment
		(start 292.864794 -226.0346)
		(end 293.027862 -226.197668)
		(width 0.14478)
		(layer "In2.Cu")
		(net "M_C_CPU0_SA_DQ<24>")
	)
	(segment
		(start 323.898514 -238.09833)
		(end 324.048374 -238.09833)
		(width 0.0889)
		(layer "In2.Cu")
		(net "M_C_CPU0_SA_DQ<24>")
	)
	(segment
		(start 338.854034 -239.946688)
		(end 338.862416 -239.951514)
		(width 0.0889)
		(layer "In2.Cu")
		(net "M_C_CPU0_SA_DQ<24>")
	)
	(segment
		(start 304.33391 -225.973132)
		(end 304.33391 -226.030282)
		(width 0.14478)
		(layer "In2.Cu")
		(net "M_C_CPU0_SA_DQ<24>")
	)
	(segment
		(start 293.421308 -225.713798)
		(end 293.584376 -225.55073)
		(width 0.14478)
		(layer "In2.Cu")
		(net "M_C_CPU0_SA_DQ<24>")
	)
	(segment
		(start 298.593764 -224.96018)
		(end 301.042832 -224.96018)
		(width 0.14478)
		(layer "In2.Cu")
		(net "M_C_CPU0_SA_DQ<24>")
	)
	(segment
		(start 304.170842 -225.810064)
		(end 304.33391 -225.973132)
		(width 0.14478)
		(layer "In2.Cu")
		(net "M_C_CPU0_SA_DQ<24>")
	)
	(segment
		(start 301.042832 -224.96018)
		(end 301.892716 -225.810064)
		(width 0.14478)
		(layer "In2.Cu")
		(net "M_C_CPU0_SA_DQ<24>")
	)
	(segment
		(start 304.496978 -226.19335)
		(end 304.727356 -226.19335)
		(width 0.14478)
		(layer "In2.Cu")
		(net "M_C_CPU0_SA_DQ<24>")
	)
	(segment
		(start 324.048374 -238.09833)
		(end 324.584314 -238.63427)
		(width 0.0889)
		(layer "In2.Cu")
		(net "M_C_CPU0_SA_DQ<24>")
	)
	(segment
		(start 310.999632 -226.31781)
		(end 311.637934 -226.31781)
		(width 0.14478)
		(layer "In2.Cu")
		(net "M_C_CPU0_SA_DQ<24>")
	)
	(segment
		(start 327.922128 -239.961928)
		(end 327.94829 -239.946688)
		(width 0.0889)
		(layer "In2.Cu")
		(net "M_C_CPU0_SA_DQ<24>")
	)
	(segment
		(start 309.955946 -226.31781)
		(end 310.148732 -226.125024)
		(width 0.14478)
		(layer "In2.Cu")
		(net "M_C_CPU0_SA_DQ<24>")
	)
	(segment
		(start 342.015064 -239.889538)
		(end 341.86114 -239.624108)
		(width 0.0889)
		(layer "In2.Cu")
		(net "M_C_CPU0_SA_DQ<24>")
	)
	(segment
		(start 324.584314 -238.63427)
		(end 325.22287 -238.63427)
		(width 0.0889)
		(layer "In2.Cu")
		(net "M_C_CPU0_SA_DQ<24>")
	)
	(segment
		(start 304.890424 -226.030282)
		(end 304.890424 -225.973132)
		(width 0.14478)
		(layer "In2.Cu")
		(net "M_C_CPU0_SA_DQ<24>")
	)
	(segment
		(start 292.864794 -225.96983)
		(end 292.864794 -226.0346)
		(width 0.14478)
		(layer "In2.Cu")
		(net "M_C_CPU0_SA_DQ<24>")
	)
	(segment
		(start 293.25824 -226.197668)
		(end 293.421308 -226.0346)
		(width 0.14478)
		(layer "In2.Cu")
		(net "M_C_CPU0_SA_DQ<24>")
	)
	(segment
		(start 327.003156 -239.946688)
		(end 327.034906 -239.928146)
		(width 0.0889)
		(layer "In2.Cu")
		(net "M_C_CPU0_SA_DQ<24>")
	)
	(segment
		(start 310.806846 -225.502216)
		(end 310.806846 -226.125024)
		(width 0.14478)
		(layer "In2.Cu")
		(net "M_C_CPU0_SA_DQ<24>")
	)
	(arc
		(start 331.708252 -239.946688)
		(mid 331.991208 -239.870511)
		(end 332.274164 -239.946688)
		(width 0.0889)
		(layer "In2.Cu")
		(net "M_C_CPU0_SA_DQ<24>")
	)
	(arc
		(start 330.402438 -239.951514)
		(mid 330.585946 -239.997008)
		(end 330.768198 -239.946688)
		(width 0.0889)
		(layer "In2.Cu")
		(net "M_C_CPU0_SA_DQ<24>")
	)
	(arc
		(start 336.042508 -239.951514)
		(mid 336.226016 -239.997008)
		(end 336.408268 -239.946688)
		(width 0.0889)
		(layer "In2.Cu")
		(net "M_C_CPU0_SA_DQ<24>")
	)
	(arc
		(start 341.673942 -239.946688)
		(mid 341.83038 -239.995659)
		(end 341.992712 -239.97285)
		(width 0.0889)
		(layer "In2.Cu")
		(net "M_C_CPU0_SA_DQ<24>")
	)
	(arc
		(start 340.734142 -239.946688)
		(mid 340.921086 -239.996943)
		(end 341.10803 -239.946688)
		(width 0.0889)
		(layer "In2.Cu")
		(net "M_C_CPU0_SA_DQ<24>")
	)
	(arc
		(start 337.348068 -239.946688)
		(mid 337.631024 -239.870511)
		(end 337.91398 -239.946688)
		(width 0.0889)
		(layer "In2.Cu")
		(net "M_C_CPU0_SA_DQ<24>")
	)
	(arc
		(start 328.88809 -239.946688)
		(mid 329.171046 -239.870511)
		(end 329.454002 -239.946688)
		(width 0.0889)
		(layer "In2.Cu")
		(net "M_C_CPU0_SA_DQ<24>")
	)
	(arc
		(start 332.274164 -239.946688)
		(mid 332.461108 -239.996943)
		(end 332.648052 -239.946688)
		(width 0.0889)
		(layer "In2.Cu")
		(net "M_C_CPU0_SA_DQ<24>")
	)
	(arc
		(start 338.862416 -239.951514)
		(mid 339.045924 -239.997008)
		(end 339.228176 -239.946688)
		(width 0.0889)
		(layer "In2.Cu")
		(net "M_C_CPU0_SA_DQ<24>")
	)
	(arc
		(start 327.034906 -239.928146)
		(mid 327.305777 -239.86956)
		(end 327.571862 -239.946942)
		(width 0.0889)
		(layer "In2.Cu")
		(net "M_C_CPU0_SA_DQ<24>")
	)
	(arc
		(start 331.342492 -239.951514)
		(mid 331.526 -239.997008)
		(end 331.708252 -239.946688)
		(width 0.0889)
		(layer "In2.Cu")
		(net "M_C_CPU0_SA_DQ<24>")
	)
	(arc
		(start 334.52816 -239.946688)
		(mid 334.811116 -239.870511)
		(end 335.094072 -239.946688)
		(width 0.0889)
		(layer "In2.Cu")
		(net "M_C_CPU0_SA_DQ<24>")
	)
	(arc
		(start 329.454002 -239.946688)
		(mid 329.636253 -239.997038)
		(end 329.819762 -239.951514)
		(width 0.0889)
		(layer "In2.Cu")
		(net "M_C_CPU0_SA_DQ<24>")
	)
	(arc
		(start 340.16823 -239.946688)
		(mid 340.451186 -239.870511)
		(end 340.734142 -239.946688)
		(width 0.0889)
		(layer "In2.Cu")
		(net "M_C_CPU0_SA_DQ<24>")
	)
	(arc
		(start 336.408268 -239.946688)
		(mid 336.691224 -239.870511)
		(end 336.97418 -239.946688)
		(width 0.0889)
		(layer "In2.Cu")
		(net "M_C_CPU0_SA_DQ<24>")
	)
	(arc
		(start 341.10803 -239.946688)
		(mid 341.390986 -239.870511)
		(end 341.673942 -239.946688)
		(width 0.0889)
		(layer "In2.Cu")
		(net "M_C_CPU0_SA_DQ<24>")
	)
	(arc
		(start 336.97418 -239.946688)
		(mid 337.161124 -239.996943)
		(end 337.348068 -239.946688)
		(width 0.0889)
		(layer "In2.Cu")
		(net "M_C_CPU0_SA_DQ<24>")
	)
	(arc
		(start 337.91398 -239.946688)
		(mid 338.096231 -239.997038)
		(end 338.27974 -239.951514)
		(width 0.0889)
		(layer "In2.Cu")
		(net "M_C_CPU0_SA_DQ<24>")
	)
	(arc
		(start 326.658478 -239.962182)
		(mid 326.832715 -239.996684)
		(end 327.003156 -239.946688)
		(width 0.0889)
		(layer "In2.Cu")
		(net "M_C_CPU0_SA_DQ<24>")
	)
	(arc
		(start 332.648052 -239.946688)
		(mid 332.931008 -239.870511)
		(end 333.213964 -239.946688)
		(width 0.0889)
		(layer "In2.Cu")
		(net "M_C_CPU0_SA_DQ<24>")
	)
	(arc
		(start 339.228176 -239.946688)
		(mid 339.511132 -239.870511)
		(end 339.794088 -239.946688)
		(width 0.0889)
		(layer "In2.Cu")
		(net "M_C_CPU0_SA_DQ<24>")
	)
	(arc
		(start 328.514202 -239.946688)
		(mid 328.701146 -239.996943)
		(end 328.88809 -239.946688)
		(width 0.0889)
		(layer "In2.Cu")
		(net "M_C_CPU0_SA_DQ<24>")
	)
	(arc
		(start 333.213964 -239.946688)
		(mid 333.396215 -239.997038)
		(end 333.579724 -239.951514)
		(width 0.0889)
		(layer "In2.Cu")
		(net "M_C_CPU0_SA_DQ<24>")
	)
	(arc
		(start 339.80247 -239.951514)
		(mid 339.985978 -239.997008)
		(end 340.16823 -239.946688)
		(width 0.0889)
		(layer "In2.Cu")
		(net "M_C_CPU0_SA_DQ<24>")
	)
	(arc
		(start 327.571862 -239.946942)
		(mid 327.745128 -239.997973)
		(end 327.922128 -239.961928)
		(width 0.0889)
		(layer "In2.Cu")
		(net "M_C_CPU0_SA_DQ<24>")
	)
	(arc
		(start 338.288122 -239.946688)
		(mid 338.571078 -239.870511)
		(end 338.854034 -239.946688)
		(width 0.0889)
		(layer "In2.Cu")
		(net "M_C_CPU0_SA_DQ<24>")
	)
	(arc
		(start 335.102454 -239.951514)
		(mid 335.285962 -239.997008)
		(end 335.468214 -239.946688)
		(width 0.0889)
		(layer "In2.Cu")
		(net "M_C_CPU0_SA_DQ<24>")
	)
	(arc
		(start 327.94829 -239.946688)
		(mid 328.231246 -239.870511)
		(end 328.514202 -239.946688)
		(width 0.0889)
		(layer "In2.Cu")
		(net "M_C_CPU0_SA_DQ<24>")
	)
	(arc
		(start 329.828144 -239.946688)
		(mid 330.1111 -239.870511)
		(end 330.394056 -239.946688)
		(width 0.0889)
		(layer "In2.Cu")
		(net "M_C_CPU0_SA_DQ<24>")
	)
	(arc
		(start 330.768198 -239.946688)
		(mid 331.051154 -239.870511)
		(end 331.33411 -239.946688)
		(width 0.0889)
		(layer "In2.Cu")
		(net "M_C_CPU0_SA_DQ<24>")
	)
	(arc
		(start 334.154018 -239.946688)
		(mid 334.336269 -239.997038)
		(end 334.519778 -239.951514)
		(width 0.0889)
		(layer "In2.Cu")
		(net "M_C_CPU0_SA_DQ<24>")
	)
	(arc
		(start 335.468214 -239.946688)
		(mid 335.75117 -239.870511)
		(end 336.034126 -239.946688)
		(width 0.0889)
		(layer "In2.Cu")
		(net "M_C_CPU0_SA_DQ<24>")
	)
	(arc
		(start 333.588106 -239.946688)
		(mid 333.871062 -239.870511)
		(end 334.154018 -239.946688)
		(width 0.0889)
		(layer "In2.Cu")
		(net "M_C_CPU0_SA_DQ<24>")
	)
	(segment
		(start 344.207846 -239.890046)
		(end 343.740994 -239.624108)
		(width 0.10668)
		(layer "F.Cu")
		(net "M_C_CPU0_SA_DQ<23>")
	)
	(segment
		(start 288.605214 -224.96018)
		(end 288.180018 -224.534984)
		(width 0.14478)
		(layer "In2.Cu")
		(net "M_C_CPU0_SA_DQ<23>")
	)
	(segment
		(start 339.80247 -239.296702)
		(end 339.794088 -239.301528)
		(width 0.0889)
		(layer "In2.Cu")
		(net "M_C_CPU0_SA_DQ<23>")
	)
	(segment
		(start 301.90186 -224.96018)
		(end 301.051722 -224.110042)
		(width 0.14478)
		(layer "In2.Cu")
		(net "M_C_CPU0_SA_DQ<23>")
	)
	(segment
		(start 342.988138 -239.301528)
		(end 342.979756 -239.296702)
		(width 0.0889)
		(layer "In2.Cu")
		(net "M_C_CPU0_SA_DQ<23>")
	)
	(segment
		(start 334.52816 -239.301528)
		(end 334.519778 -239.296702)
		(width 0.0889)
		(layer "In2.Cu")
		(net "M_C_CPU0_SA_DQ<23>")
	)
	(segment
		(start 301.051722 -224.110042)
		(end 298.218352 -224.110042)
		(width 0.14478)
		(layer "In2.Cu")
		(net "M_C_CPU0_SA_DQ<23>")
	)
	(segment
		(start 327.575418 -239.301782)
		(end 327.57491 -239.30229)
		(width 0.0889)
		(layer "In2.Cu")
		(net "M_C_CPU0_SA_DQ<23>")
	)
	(segment
		(start 315.086238 -231.21366)
		(end 315.086238 -228.958394)
		(width 0.14478)
		(layer "In2.Cu")
		(net "M_C_CPU0_SA_DQ<23>")
	)
	(segment
		(start 327.57491 -239.30229)
		(end 326.308974 -239.30229)
		(width 0.0889)
		(layer "In2.Cu")
		(net "M_C_CPU0_SA_DQ<23>")
	)
	(segment
		(start 338.862416 -239.296702)
		(end 338.854034 -239.301528)
		(width 0.0889)
		(layer "In2.Cu")
		(net "M_C_CPU0_SA_DQ<23>")
	)
	(segment
		(start 329.828144 -239.301528)
		(end 329.819762 -239.296702)
		(width 0.0889)
		(layer "In2.Cu")
		(net "M_C_CPU0_SA_DQ<23>")
	)
	(segment
		(start 298.218352 -224.110042)
		(end 297.368214 -224.96018)
		(width 0.14478)
		(layer "In2.Cu")
		(net "M_C_CPU0_SA_DQ<23>")
	)
	(segment
		(start 308.52237 -224.110042)
		(end 305.706526 -224.110042)
		(width 0.14478)
		(layer "In2.Cu")
		(net "M_C_CPU0_SA_DQ<23>")
	)
	(segment
		(start 336.042508 -239.296702)
		(end 336.034126 -239.301528)
		(width 0.0889)
		(layer "In2.Cu")
		(net "M_C_CPU0_SA_DQ<23>")
	)
	(segment
		(start 290.02228 -224.56394)
		(end 290.02228 -224.797112)
		(width 0.14478)
		(layer "In2.Cu")
		(net "M_C_CPU0_SA_DQ<23>")
	)
	(segment
		(start 310.865774 -224.73793)
		(end 309.150258 -224.73793)
		(width 0.14478)
		(layer "In2.Cu")
		(net "M_C_CPU0_SA_DQ<23>")
	)
	(segment
		(start 330.402438 -239.296702)
		(end 330.394056 -239.301528)
		(width 0.0889)
		(layer "In2.Cu")
		(net "M_C_CPU0_SA_DQ<23>")
	)
	(segment
		(start 304.856388 -224.96018)
		(end 301.90186 -224.96018)
		(width 0.14478)
		(layer "In2.Cu")
		(net "M_C_CPU0_SA_DQ<23>")
	)
	(segment
		(start 323.906134 -237.53953)
		(end 321.412108 -237.53953)
		(width 0.14478)
		(layer "In2.Cu")
		(net "M_C_CPU0_SA_DQ<23>")
	)
	(segment
		(start 315.086238 -228.958394)
		(end 310.865774 -224.73793)
		(width 0.14478)
		(layer "In2.Cu")
		(net "M_C_CPU0_SA_DQ<23>")
	)
	(segment
		(start 290.185348 -224.400872)
		(end 290.02228 -224.56394)
		(width 0.14478)
		(layer "In2.Cu")
		(net "M_C_CPU0_SA_DQ<23>")
	)
	(segment
		(start 335.102454 -239.296702)
		(end 335.094072 -239.301528)
		(width 0.0889)
		(layer "In2.Cu")
		(net "M_C_CPU0_SA_DQ<23>")
	)
	(segment
		(start 290.578794 -224.56394)
		(end 290.415726 -224.400872)
		(width 0.14478)
		(layer "In2.Cu")
		(net "M_C_CPU0_SA_DQ<23>")
	)
	(segment
		(start 342.048084 -239.301528)
		(end 342.039702 -239.296702)
		(width 0.0889)
		(layer "In2.Cu")
		(net "M_C_CPU0_SA_DQ<23>")
	)
	(segment
		(start 290.741862 -224.96018)
		(end 290.578794 -224.797112)
		(width 0.14478)
		(layer "In2.Cu")
		(net "M_C_CPU0_SA_DQ<23>")
	)
	(segment
		(start 343.740994 -239.624108)
		(end 343.58707 -239.358678)
		(width 0.0889)
		(layer "In2.Cu")
		(net "M_C_CPU0_SA_DQ<23>")
	)
	(segment
		(start 290.415726 -224.400872)
		(end 290.185348 -224.400872)
		(width 0.14478)
		(layer "In2.Cu")
		(net "M_C_CPU0_SA_DQ<23>")
	)
	(segment
		(start 338.288122 -239.301528)
		(end 338.27974 -239.296702)
		(width 0.0889)
		(layer "In2.Cu")
		(net "M_C_CPU0_SA_DQ<23>")
	)
	(segment
		(start 309.150258 -224.73793)
		(end 308.52237 -224.110042)
		(width 0.14478)
		(layer "In2.Cu")
		(net "M_C_CPU0_SA_DQ<23>")
	)
	(segment
		(start 305.706526 -224.110042)
		(end 304.856388 -224.96018)
		(width 0.14478)
		(layer "In2.Cu")
		(net "M_C_CPU0_SA_DQ<23>")
	)
	(segment
		(start 290.578794 -224.797112)
		(end 290.578794 -224.56394)
		(width 0.14478)
		(layer "In2.Cu")
		(net "M_C_CPU0_SA_DQ<23>")
	)
	(segment
		(start 289.859212 -224.96018)
		(end 288.605214 -224.96018)
		(width 0.14478)
		(layer "In2.Cu")
		(net "M_C_CPU0_SA_DQ<23>")
	)
	(segment
		(start 327.598786 -239.28832)
		(end 327.575418 -239.301782)
		(width 0.0889)
		(layer "In2.Cu")
		(net "M_C_CPU0_SA_DQ<23>")
	)
	(segment
		(start 331.342492 -239.296702)
		(end 331.33411 -239.301528)
		(width 0.0889)
		(layer "In2.Cu")
		(net "M_C_CPU0_SA_DQ<23>")
	)
	(segment
		(start 321.412108 -237.53953)
		(end 315.086238 -231.21366)
		(width 0.14478)
		(layer "In2.Cu")
		(net "M_C_CPU0_SA_DQ<23>")
	)
	(segment
		(start 326.308974 -239.30229)
		(end 324.546214 -237.53953)
		(width 0.0889)
		(layer "In2.Cu")
		(net "M_C_CPU0_SA_DQ<23>")
	)
	(segment
		(start 343.58707 -239.358678)
		(end 343.491058 -239.333278)
		(width 0.0889)
		(layer "In2.Cu")
		(net "M_C_CPU0_SA_DQ<23>")
	)
	(segment
		(start 324.546214 -237.53953)
		(end 323.906134 -237.53953)
		(width 0.0889)
		(layer "In2.Cu")
		(net "M_C_CPU0_SA_DQ<23>")
	)
	(segment
		(start 333.588106 -239.301528)
		(end 333.579724 -239.296702)
		(width 0.0889)
		(layer "In2.Cu")
		(net "M_C_CPU0_SA_DQ<23>")
	)
	(segment
		(start 290.02228 -224.797112)
		(end 289.859212 -224.96018)
		(width 0.14478)
		(layer "In2.Cu")
		(net "M_C_CPU0_SA_DQ<23>")
	)
	(segment
		(start 297.368214 -224.96018)
		(end 290.741862 -224.96018)
		(width 0.14478)
		(layer "In2.Cu")
		(net "M_C_CPU0_SA_DQ<23>")
	)
	(arc
		(start 333.213964 -239.301528)
		(mid 332.931008 -239.377705)
		(end 332.648052 -239.301528)
		(width 0.0889)
		(layer "In2.Cu")
		(net "M_C_CPU0_SA_DQ<23>")
	)
	(arc
		(start 340.734142 -239.301528)
		(mid 340.451186 -239.377705)
		(end 340.16823 -239.301528)
		(width 0.0889)
		(layer "In2.Cu")
		(net "M_C_CPU0_SA_DQ<23>")
	)
	(arc
		(start 340.16823 -239.301528)
		(mid 339.985979 -239.251178)
		(end 339.80247 -239.296702)
		(width 0.0889)
		(layer "In2.Cu")
		(net "M_C_CPU0_SA_DQ<23>")
	)
	(arc
		(start 331.33411 -239.301528)
		(mid 331.051154 -239.377705)
		(end 330.768198 -239.301528)
		(width 0.0889)
		(layer "In2.Cu")
		(net "M_C_CPU0_SA_DQ<23>")
	)
	(arc
		(start 339.228176 -239.301528)
		(mid 339.045925 -239.251178)
		(end 338.862416 -239.296702)
		(width 0.0889)
		(layer "In2.Cu")
		(net "M_C_CPU0_SA_DQ<23>")
	)
	(arc
		(start 339.794088 -239.301528)
		(mid 339.511132 -239.377705)
		(end 339.228176 -239.301528)
		(width 0.0889)
		(layer "In2.Cu")
		(net "M_C_CPU0_SA_DQ<23>")
	)
	(arc
		(start 342.613996 -239.301528)
		(mid 342.33104 -239.377705)
		(end 342.048084 -239.301528)
		(width 0.0889)
		(layer "In2.Cu")
		(net "M_C_CPU0_SA_DQ<23>")
	)
	(arc
		(start 337.348068 -239.301528)
		(mid 337.161124 -239.251273)
		(end 336.97418 -239.301528)
		(width 0.0889)
		(layer "In2.Cu")
		(net "M_C_CPU0_SA_DQ<23>")
	)
	(arc
		(start 329.454002 -239.301528)
		(mid 329.171046 -239.377705)
		(end 328.88809 -239.301528)
		(width 0.0889)
		(layer "In2.Cu")
		(net "M_C_CPU0_SA_DQ<23>")
	)
	(arc
		(start 332.274164 -239.301528)
		(mid 331.991208 -239.377705)
		(end 331.708252 -239.301528)
		(width 0.0889)
		(layer "In2.Cu")
		(net "M_C_CPU0_SA_DQ<23>")
	)
	(arc
		(start 335.094072 -239.301528)
		(mid 334.811116 -239.377705)
		(end 334.52816 -239.301528)
		(width 0.0889)
		(layer "In2.Cu")
		(net "M_C_CPU0_SA_DQ<23>")
	)
	(arc
		(start 328.514202 -239.301528)
		(mid 328.231246 -239.377705)
		(end 327.94829 -239.301528)
		(width 0.0889)
		(layer "In2.Cu")
		(net "M_C_CPU0_SA_DQ<23>")
	)
	(arc
		(start 332.648052 -239.301528)
		(mid 332.461108 -239.251273)
		(end 332.274164 -239.301528)
		(width 0.0889)
		(layer "In2.Cu")
		(net "M_C_CPU0_SA_DQ<23>")
	)
	(arc
		(start 328.88809 -239.301528)
		(mid 328.701146 -239.251273)
		(end 328.514202 -239.301528)
		(width 0.0889)
		(layer "In2.Cu")
		(net "M_C_CPU0_SA_DQ<23>")
	)
	(arc
		(start 342.039702 -239.296702)
		(mid 341.856194 -239.251208)
		(end 341.673942 -239.301528)
		(width 0.0889)
		(layer "In2.Cu")
		(net "M_C_CPU0_SA_DQ<23>")
	)
	(arc
		(start 337.91398 -239.301528)
		(mid 337.631024 -239.377705)
		(end 337.348068 -239.301528)
		(width 0.0889)
		(layer "In2.Cu")
		(net "M_C_CPU0_SA_DQ<23>")
	)
	(arc
		(start 330.394056 -239.301528)
		(mid 330.1111 -239.377705)
		(end 329.828144 -239.301528)
		(width 0.0889)
		(layer "In2.Cu")
		(net "M_C_CPU0_SA_DQ<23>")
	)
	(arc
		(start 341.673942 -239.301528)
		(mid 341.390986 -239.377705)
		(end 341.10803 -239.301528)
		(width 0.0889)
		(layer "In2.Cu")
		(net "M_C_CPU0_SA_DQ<23>")
	)
	(arc
		(start 341.10803 -239.301528)
		(mid 340.921086 -239.251273)
		(end 340.734142 -239.301528)
		(width 0.0889)
		(layer "In2.Cu")
		(net "M_C_CPU0_SA_DQ<23>")
	)
	(arc
		(start 334.154018 -239.301528)
		(mid 333.871062 -239.377705)
		(end 333.588106 -239.301528)
		(width 0.0889)
		(layer "In2.Cu")
		(net "M_C_CPU0_SA_DQ<23>")
	)
	(arc
		(start 330.768198 -239.301528)
		(mid 330.585947 -239.251178)
		(end 330.402438 -239.296702)
		(width 0.0889)
		(layer "In2.Cu")
		(net "M_C_CPU0_SA_DQ<23>")
	)
	(arc
		(start 343.491058 -239.333278)
		(mid 343.23585 -239.376755)
		(end 342.988138 -239.301528)
		(width 0.0889)
		(layer "In2.Cu")
		(net "M_C_CPU0_SA_DQ<23>")
	)
	(arc
		(start 327.94829 -239.301528)
		(mid 327.775182 -239.251412)
		(end 327.598786 -239.28832)
		(width 0.0889)
		(layer "In2.Cu")
		(net "M_C_CPU0_SA_DQ<23>")
	)
	(arc
		(start 336.034126 -239.301528)
		(mid 335.75117 -239.377705)
		(end 335.468214 -239.301528)
		(width 0.0889)
		(layer "In2.Cu")
		(net "M_C_CPU0_SA_DQ<23>")
	)
	(arc
		(start 334.519778 -239.296702)
		(mid 334.33627 -239.251208)
		(end 334.154018 -239.301528)
		(width 0.0889)
		(layer "In2.Cu")
		(net "M_C_CPU0_SA_DQ<23>")
	)
	(arc
		(start 338.854034 -239.301528)
		(mid 338.571078 -239.377705)
		(end 338.288122 -239.301528)
		(width 0.0889)
		(layer "In2.Cu")
		(net "M_C_CPU0_SA_DQ<23>")
	)
	(arc
		(start 336.408268 -239.301528)
		(mid 336.226017 -239.251178)
		(end 336.042508 -239.296702)
		(width 0.0889)
		(layer "In2.Cu")
		(net "M_C_CPU0_SA_DQ<23>")
	)
	(arc
		(start 331.708252 -239.301528)
		(mid 331.526001 -239.251178)
		(end 331.342492 -239.296702)
		(width 0.0889)
		(layer "In2.Cu")
		(net "M_C_CPU0_SA_DQ<23>")
	)
	(arc
		(start 338.27974 -239.296702)
		(mid 338.096232 -239.251208)
		(end 337.91398 -239.301528)
		(width 0.0889)
		(layer "In2.Cu")
		(net "M_C_CPU0_SA_DQ<23>")
	)
	(arc
		(start 336.97418 -239.301528)
		(mid 336.691224 -239.377705)
		(end 336.408268 -239.301528)
		(width 0.0889)
		(layer "In2.Cu")
		(net "M_C_CPU0_SA_DQ<23>")
	)
	(arc
		(start 335.468214 -239.301528)
		(mid 335.285963 -239.251178)
		(end 335.102454 -239.296702)
		(width 0.0889)
		(layer "In2.Cu")
		(net "M_C_CPU0_SA_DQ<23>")
	)
	(arc
		(start 329.819762 -239.296702)
		(mid 329.636254 -239.251208)
		(end 329.454002 -239.301528)
		(width 0.0889)
		(layer "In2.Cu")
		(net "M_C_CPU0_SA_DQ<23>")
	)
	(arc
		(start 342.979756 -239.296702)
		(mid 342.796248 -239.251208)
		(end 342.613996 -239.301528)
		(width 0.0889)
		(layer "In2.Cu")
		(net "M_C_CPU0_SA_DQ<23>")
	)
	(arc
		(start 333.579724 -239.296702)
		(mid 333.396216 -239.251208)
		(end 333.213964 -239.301528)
		(width 0.0889)
		(layer "In2.Cu")
		(net "M_C_CPU0_SA_DQ<23>")
	)
	(segment
		(start 342.797892 -239.08004)
		(end 342.33104 -238.814102)
		(width 0.10668)
		(layer "F.Cu")
		(net "M_C_CPU0_SA_DQ<22>")
	)
	(segment
		(start 316.007496 -230.816912)
		(end 316.007496 -228.576632)
		(width 0.14478)
		(layer "In2.Cu")
		(net "M_C_CPU0_SA_DQ<22>")
	)
	(segment
		(start 342.33104 -238.814102)
		(end 342.177116 -238.548672)
		(width 0.0889)
		(layer "In2.Cu")
		(net "M_C_CPU0_SA_DQ<22>")
	)
	(segment
		(start 301.90186 -223.260158)
		(end 301.051722 -222.41002)
		(width 0.14478)
		(layer "In2.Cu")
		(net "M_C_CPU0_SA_DQ<22>")
	)
	(segment
		(start 309.028338 -222.772224)
		(end 308.666134 -222.41002)
		(width 0.14478)
		(layer "In2.Cu")
		(net "M_C_CPU0_SA_DQ<22>")
	)
	(segment
		(start 309.028338 -223.299528)
		(end 309.028338 -222.772224)
		(width 0.14478)
		(layer "In2.Cu")
		(net "M_C_CPU0_SA_DQ<22>")
	)
	(segment
		(start 324.210934 -236.62005)
		(end 323.885814 -236.62005)
		(width 0.0889)
		(layer "In2.Cu")
		(net "M_C_CPU0_SA_DQ<22>")
	)
	(segment
		(start 332.178152 -238.491522)
		(end 332.16977 -238.486696)
		(width 0.0889)
		(layer "In2.Cu")
		(net "M_C_CPU0_SA_DQ<22>")
	)
	(segment
		(start 336.878168 -238.491522)
		(end 336.869786 -238.486696)
		(width 0.0889)
		(layer "In2.Cu")
		(net "M_C_CPU0_SA_DQ<22>")
	)
	(segment
		(start 291.020246 -223.260158)
		(end 290.857178 -223.09709)
		(width 0.14478)
		(layer "In2.Cu")
		(net "M_C_CPU0_SA_DQ<22>")
	)
	(segment
		(start 305.706526 -222.41002)
		(end 304.856388 -223.260158)
		(width 0.14478)
		(layer "In2.Cu")
		(net "M_C_CPU0_SA_DQ<22>")
	)
	(segment
		(start 288.605214 -223.260158)
		(end 288.180018 -222.834962)
		(width 0.14478)
		(layer "In2.Cu")
		(net "M_C_CPU0_SA_DQ<22>")
	)
	(segment
		(start 290.857178 -222.42018)
		(end 290.69411 -222.257112)
		(width 0.14478)
		(layer "In2.Cu")
		(net "M_C_CPU0_SA_DQ<22>")
	)
	(segment
		(start 290.300664 -222.42018)
		(end 290.300664 -223.09709)
		(width 0.14478)
		(layer "In2.Cu")
		(net "M_C_CPU0_SA_DQ<22>")
	)
	(segment
		(start 321.810634 -236.62005)
		(end 316.007496 -230.816912)
		(width 0.14478)
		(layer "In2.Cu")
		(net "M_C_CPU0_SA_DQ<22>")
	)
	(segment
		(start 290.857178 -223.09709)
		(end 290.857178 -222.42018)
		(width 0.14478)
		(layer "In2.Cu")
		(net "M_C_CPU0_SA_DQ<22>")
	)
	(segment
		(start 328.992484 -238.486696)
		(end 328.984102 -238.491522)
		(width 0.0889)
		(layer "In2.Cu")
		(net "M_C_CPU0_SA_DQ<22>")
	)
	(segment
		(start 335.938114 -238.491522)
		(end 335.929732 -238.486696)
		(width 0.0889)
		(layer "In2.Cu")
		(net "M_C_CPU0_SA_DQ<22>")
	)
	(segment
		(start 309.55488 -223.82607)
		(end 309.028338 -223.299528)
		(width 0.14478)
		(layer "In2.Cu")
		(net "M_C_CPU0_SA_DQ<22>")
	)
	(segment
		(start 340.63813 -238.491522)
		(end 340.629748 -238.486696)
		(width 0.0889)
		(layer "In2.Cu")
		(net "M_C_CPU0_SA_DQ<22>")
	)
	(segment
		(start 290.137596 -223.260158)
		(end 288.605214 -223.260158)
		(width 0.14478)
		(layer "In2.Cu")
		(net "M_C_CPU0_SA_DQ<22>")
	)
	(segment
		(start 323.885814 -236.62005)
		(end 321.810634 -236.62005)
		(width 0.14478)
		(layer "In2.Cu")
		(net "M_C_CPU0_SA_DQ<22>")
	)
	(segment
		(start 342.177116 -238.548672)
		(end 342.081104 -238.523272)
		(width 0.0889)
		(layer "In2.Cu")
		(net "M_C_CPU0_SA_DQ<22>")
	)
	(segment
		(start 290.463732 -222.257112)
		(end 290.300664 -222.42018)
		(width 0.14478)
		(layer "In2.Cu")
		(net "M_C_CPU0_SA_DQ<22>")
	)
	(segment
		(start 298.218352 -222.41002)
		(end 297.368214 -223.260158)
		(width 0.14478)
		(layer "In2.Cu")
		(net "M_C_CPU0_SA_DQ<22>")
	)
	(segment
		(start 326.169274 -238.20501)
		(end 324.983094 -237.01883)
		(width 0.0889)
		(layer "In2.Cu")
		(net "M_C_CPU0_SA_DQ<22>")
	)
	(segment
		(start 324.983094 -237.01883)
		(end 324.609714 -237.01883)
		(width 0.0889)
		(layer "In2.Cu")
		(net "M_C_CPU0_SA_DQ<22>")
	)
	(segment
		(start 301.051722 -222.41002)
		(end 298.218352 -222.41002)
		(width 0.14478)
		(layer "In2.Cu")
		(net "M_C_CPU0_SA_DQ<22>")
	)
	(segment
		(start 311.256934 -223.82607)
		(end 309.55488 -223.82607)
		(width 0.14478)
		(layer "In2.Cu")
		(net "M_C_CPU0_SA_DQ<22>")
	)
	(segment
		(start 341.212424 -238.486696)
		(end 341.204042 -238.491522)
		(width 0.0889)
		(layer "In2.Cu")
		(net "M_C_CPU0_SA_DQ<22>")
	)
	(segment
		(start 327.761092 -238.567722)
		(end 326.976486 -238.567722)
		(width 0.0889)
		(layer "In2.Cu")
		(net "M_C_CPU0_SA_DQ<22>")
	)
	(segment
		(start 331.238098 -238.491522)
		(end 331.229716 -238.486696)
		(width 0.0889)
		(layer "In2.Cu")
		(net "M_C_CPU0_SA_DQ<22>")
	)
	(segment
		(start 332.752446 -238.486696)
		(end 332.744064 -238.491522)
		(width 0.0889)
		(layer "In2.Cu")
		(net "M_C_CPU0_SA_DQ<22>")
	)
	(segment
		(start 328.41819 -238.491522)
		(end 328.409808 -238.486696)
		(width 0.0889)
		(layer "In2.Cu")
		(net "M_C_CPU0_SA_DQ<22>")
	)
	(segment
		(start 326.613774 -238.20501)
		(end 326.169274 -238.20501)
		(width 0.0889)
		(layer "In2.Cu")
		(net "M_C_CPU0_SA_DQ<22>")
	)
	(segment
		(start 290.69411 -222.257112)
		(end 290.463732 -222.257112)
		(width 0.14478)
		(layer "In2.Cu")
		(net "M_C_CPU0_SA_DQ<22>")
	)
	(segment
		(start 290.300664 -223.09709)
		(end 290.137596 -223.260158)
		(width 0.14478)
		(layer "In2.Cu")
		(net "M_C_CPU0_SA_DQ<22>")
	)
	(segment
		(start 339.698076 -238.491522)
		(end 339.689694 -238.486696)
		(width 0.0889)
		(layer "In2.Cu")
		(net "M_C_CPU0_SA_DQ<22>")
	)
	(segment
		(start 324.609714 -237.01883)
		(end 324.210934 -236.62005)
		(width 0.0889)
		(layer "In2.Cu")
		(net "M_C_CPU0_SA_DQ<22>")
	)
	(segment
		(start 304.856388 -223.260158)
		(end 301.90186 -223.260158)
		(width 0.14478)
		(layer "In2.Cu")
		(net "M_C_CPU0_SA_DQ<22>")
	)
	(segment
		(start 308.666134 -222.41002)
		(end 305.706526 -222.41002)
		(width 0.14478)
		(layer "In2.Cu")
		(net "M_C_CPU0_SA_DQ<22>")
	)
	(segment
		(start 333.6925 -238.486696)
		(end 333.684118 -238.491522)
		(width 0.0889)
		(layer "In2.Cu")
		(net "M_C_CPU0_SA_DQ<22>")
	)
	(segment
		(start 337.452462 -238.486696)
		(end 337.44408 -238.491522)
		(width 0.0889)
		(layer "In2.Cu")
		(net "M_C_CPU0_SA_DQ<22>")
	)
	(segment
		(start 297.368214 -223.260158)
		(end 291.020246 -223.260158)
		(width 0.14478)
		(layer "In2.Cu")
		(net "M_C_CPU0_SA_DQ<22>")
	)
	(segment
		(start 316.007496 -228.576632)
		(end 311.256934 -223.82607)
		(width 0.14478)
		(layer "In2.Cu")
		(net "M_C_CPU0_SA_DQ<22>")
	)
	(segment
		(start 326.976486 -238.567722)
		(end 326.613774 -238.20501)
		(width 0.0889)
		(layer "In2.Cu")
		(net "M_C_CPU0_SA_DQ<22>")
	)
	(arc
		(start 333.684118 -238.491522)
		(mid 333.401162 -238.567699)
		(end 333.118206 -238.491522)
		(width 0.0889)
		(layer "In2.Cu")
		(net "M_C_CPU0_SA_DQ<22>")
	)
	(arc
		(start 336.504026 -238.491522)
		(mid 336.22107 -238.567699)
		(end 335.938114 -238.491522)
		(width 0.0889)
		(layer "In2.Cu")
		(net "M_C_CPU0_SA_DQ<22>")
	)
	(arc
		(start 340.629748 -238.486696)
		(mid 340.44624 -238.441202)
		(end 340.263988 -238.491522)
		(width 0.0889)
		(layer "In2.Cu")
		(net "M_C_CPU0_SA_DQ<22>")
	)
	(arc
		(start 329.924156 -238.491522)
		(mid 329.6412 -238.567699)
		(end 329.358244 -238.491522)
		(width 0.0889)
		(layer "In2.Cu")
		(net "M_C_CPU0_SA_DQ<22>")
	)
	(arc
		(start 331.80401 -238.491522)
		(mid 331.521054 -238.567699)
		(end 331.238098 -238.491522)
		(width 0.0889)
		(layer "In2.Cu")
		(net "M_C_CPU0_SA_DQ<22>")
	)
	(arc
		(start 330.298044 -238.491522)
		(mid 330.1111 -238.441267)
		(end 329.924156 -238.491522)
		(width 0.0889)
		(layer "In2.Cu")
		(net "M_C_CPU0_SA_DQ<22>")
	)
	(arc
		(start 334.05826 -238.491522)
		(mid 333.876009 -238.441172)
		(end 333.6925 -238.486696)
		(width 0.0889)
		(layer "In2.Cu")
		(net "M_C_CPU0_SA_DQ<22>")
	)
	(arc
		(start 328.984102 -238.491522)
		(mid 328.701146 -238.567699)
		(end 328.41819 -238.491522)
		(width 0.0889)
		(layer "In2.Cu")
		(net "M_C_CPU0_SA_DQ<22>")
	)
	(arc
		(start 330.863956 -238.491522)
		(mid 330.581 -238.567699)
		(end 330.298044 -238.491522)
		(width 0.0889)
		(layer "In2.Cu")
		(net "M_C_CPU0_SA_DQ<22>")
	)
	(arc
		(start 334.624172 -238.491522)
		(mid 334.341216 -238.567699)
		(end 334.05826 -238.491522)
		(width 0.0889)
		(layer "In2.Cu")
		(net "M_C_CPU0_SA_DQ<22>")
	)
	(arc
		(start 335.563972 -238.491522)
		(mid 335.281016 -238.567699)
		(end 334.99806 -238.491522)
		(width 0.0889)
		(layer "In2.Cu")
		(net "M_C_CPU0_SA_DQ<22>")
	)
	(arc
		(start 341.578184 -238.491522)
		(mid 341.395933 -238.441172)
		(end 341.212424 -238.486696)
		(width 0.0889)
		(layer "In2.Cu")
		(net "M_C_CPU0_SA_DQ<22>")
	)
	(arc
		(start 328.409808 -238.486696)
		(mid 328.2263 -238.441202)
		(end 328.044048 -238.491522)
		(width 0.0889)
		(layer "In2.Cu")
		(net "M_C_CPU0_SA_DQ<22>")
	)
	(arc
		(start 339.689694 -238.486696)
		(mid 339.506186 -238.441202)
		(end 339.323934 -238.491522)
		(width 0.0889)
		(layer "In2.Cu")
		(net "M_C_CPU0_SA_DQ<22>")
	)
	(arc
		(start 339.323934 -238.491522)
		(mid 339.040978 -238.567699)
		(end 338.758022 -238.491522)
		(width 0.0889)
		(layer "In2.Cu")
		(net "M_C_CPU0_SA_DQ<22>")
	)
	(arc
		(start 331.229716 -238.486696)
		(mid 331.046208 -238.441202)
		(end 330.863956 -238.491522)
		(width 0.0889)
		(layer "In2.Cu")
		(net "M_C_CPU0_SA_DQ<22>")
	)
	(arc
		(start 337.818222 -238.491522)
		(mid 337.635971 -238.441172)
		(end 337.452462 -238.486696)
		(width 0.0889)
		(layer "In2.Cu")
		(net "M_C_CPU0_SA_DQ<22>")
	)
	(arc
		(start 338.758022 -238.491522)
		(mid 338.571078 -238.441267)
		(end 338.384134 -238.491522)
		(width 0.0889)
		(layer "In2.Cu")
		(net "M_C_CPU0_SA_DQ<22>")
	)
	(arc
		(start 333.118206 -238.491522)
		(mid 332.935955 -238.441172)
		(end 332.752446 -238.486696)
		(width 0.0889)
		(layer "In2.Cu")
		(net "M_C_CPU0_SA_DQ<22>")
	)
	(arc
		(start 335.929732 -238.486696)
		(mid 335.746224 -238.441202)
		(end 335.563972 -238.491522)
		(width 0.0889)
		(layer "In2.Cu")
		(net "M_C_CPU0_SA_DQ<22>")
	)
	(arc
		(start 329.358244 -238.491522)
		(mid 329.175993 -238.441172)
		(end 328.992484 -238.486696)
		(width 0.0889)
		(layer "In2.Cu")
		(net "M_C_CPU0_SA_DQ<22>")
	)
	(arc
		(start 332.16977 -238.486696)
		(mid 331.986262 -238.441202)
		(end 331.80401 -238.491522)
		(width 0.0889)
		(layer "In2.Cu")
		(net "M_C_CPU0_SA_DQ<22>")
	)
	(arc
		(start 337.44408 -238.491522)
		(mid 337.161124 -238.567699)
		(end 336.878168 -238.491522)
		(width 0.0889)
		(layer "In2.Cu")
		(net "M_C_CPU0_SA_DQ<22>")
	)
	(arc
		(start 328.044048 -238.491522)
		(mid 327.907612 -238.548347)
		(end 327.761092 -238.567722)
		(width 0.0889)
		(layer "In2.Cu")
		(net "M_C_CPU0_SA_DQ<22>")
	)
	(arc
		(start 332.744064 -238.491522)
		(mid 332.461108 -238.567699)
		(end 332.178152 -238.491522)
		(width 0.0889)
		(layer "In2.Cu")
		(net "M_C_CPU0_SA_DQ<22>")
	)
	(arc
		(start 334.99806 -238.491522)
		(mid 334.811116 -238.441267)
		(end 334.624172 -238.491522)
		(width 0.0889)
		(layer "In2.Cu")
		(net "M_C_CPU0_SA_DQ<22>")
	)
	(arc
		(start 336.869786 -238.486696)
		(mid 336.686278 -238.441202)
		(end 336.504026 -238.491522)
		(width 0.0889)
		(layer "In2.Cu")
		(net "M_C_CPU0_SA_DQ<22>")
	)
	(arc
		(start 338.384134 -238.491522)
		(mid 338.101178 -238.567699)
		(end 337.818222 -238.491522)
		(width 0.0889)
		(layer "In2.Cu")
		(net "M_C_CPU0_SA_DQ<22>")
	)
	(arc
		(start 342.081104 -238.523272)
		(mid 341.825896 -238.566749)
		(end 341.578184 -238.491522)
		(width 0.0889)
		(layer "In2.Cu")
		(net "M_C_CPU0_SA_DQ<22>")
	)
	(arc
		(start 341.204042 -238.491522)
		(mid 340.921086 -238.567699)
		(end 340.63813 -238.491522)
		(width 0.0889)
		(layer "In2.Cu")
		(net "M_C_CPU0_SA_DQ<22>")
	)
	(arc
		(start 340.263988 -238.491522)
		(mid 339.981032 -238.567699)
		(end 339.698076 -238.491522)
		(width 0.0889)
		(layer "In2.Cu")
		(net "M_C_CPU0_SA_DQ<22>")
	)
	(segment
		(start 343.737946 -239.08004)
		(end 343.271094 -238.814102)
		(width 0.10668)
		(layer "F.Cu")
		(net "M_C_CPU0_SA_DQ<21>")
	)
	(segment
		(start 307.836062 -223.260158)
		(end 307.99913 -223.09709)
		(width 0.14478)
		(layer "In2.Cu")
		(net "M_C_CPU0_SA_DQ<21>")
	)
	(segment
		(start 299.26026 -223.09709)
		(end 299.423328 -223.260158)
		(width 0.14478)
		(layer "In2.Cu")
		(net "M_C_CPU0_SA_DQ<21>")
	)
	(segment
		(start 300.204124 -223.09709)
		(end 300.204124 -223.029018)
		(width 0.14478)
		(layer "In2.Cu")
		(net "M_C_CPU0_SA_DQ<21>")
	)
	(segment
		(start 325.978774 -238.45393)
		(end 326.496934 -238.45393)
		(width 0.0889)
		(layer "In2.Cu")
		(net "M_C_CPU0_SA_DQ<21>")
	)
	(segment
		(start 298.540678 -223.260158)
		(end 298.703746 -223.09709)
		(width 0.14478)
		(layer "In2.Cu")
		(net "M_C_CPU0_SA_DQ<21>")
	)
	(segment
		(start 305.740816 -223.260158)
		(end 306.152296 -223.260158)
		(width 0.14478)
		(layer "In2.Cu")
		(net "M_C_CPU0_SA_DQ<21>")
	)
	(segment
		(start 328.984102 -239.136682)
		(end 328.992484 -239.141508)
		(width 0.0889)
		(layer "In2.Cu")
		(net "M_C_CPU0_SA_DQ<21>")
	)
	(segment
		(start 294.501824 -224.349056)
		(end 294.501824 -223.871282)
		(width 0.14478)
		(layer "In2.Cu")
		(net "M_C_CPU0_SA_DQ<21>")
	)
	(segment
		(start 296.839894 -223.72447)
		(end 297.002962 -223.887538)
		(width 0.14478)
		(layer "In2.Cu")
		(net "M_C_CPU0_SA_DQ<21>")
	)
	(segment
		(start 308.392576 -222.87357)
		(end 308.555644 -223.036638)
		(width 0.14478)
		(layer "In2.Cu")
		(net "M_C_CPU0_SA_DQ<21>")
	)
	(segment
		(start 307.99913 -223.036638)
		(end 308.162198 -222.87357)
		(width 0.14478)
		(layer "In2.Cu")
		(net "M_C_CPU0_SA_DQ<21>")
	)
	(segment
		(start 309.349394 -224.28327)
		(end 311.063894 -224.28327)
		(width 0.14478)
		(layer "In2.Cu")
		(net "M_C_CPU0_SA_DQ<21>")
	)
	(segment
		(start 324.759574 -237.23473)
		(end 325.978774 -238.45393)
		(width 0.0889)
		(layer "In2.Cu")
		(net "M_C_CPU0_SA_DQ<21>")
	)
	(segment
		(start 300.760638 -223.09709)
		(end 300.923706 -223.260158)
		(width 0.14478)
		(layer "In2.Cu")
		(net "M_C_CPU0_SA_DQ<21>")
	)
	(segment
		(start 311.063894 -224.28327)
		(end 315.547756 -228.767132)
		(width 0.14478)
		(layer "In2.Cu")
		(net "M_C_CPU0_SA_DQ<21>")
	)
	(segment
		(start 299.423328 -223.260158)
		(end 300.041056 -223.260158)
		(width 0.14478)
		(layer "In2.Cu")
		(net "M_C_CPU0_SA_DQ<21>")
	)
	(segment
		(start 306.152296 -223.260158)
		(end 306.315364 -223.09709)
		(width 0.14478)
		(layer "In2.Cu")
		(net "M_C_CPU0_SA_DQ<21>")
	)
	(segment
		(start 337.44408 -239.136682)
		(end 337.452462 -239.141508)
		(width 0.0889)
		(layer "In2.Cu")
		(net "M_C_CPU0_SA_DQ<21>")
	)
	(segment
		(start 341.204042 -239.136682)
		(end 341.212424 -239.141508)
		(width 0.0889)
		(layer "In2.Cu")
		(net "M_C_CPU0_SA_DQ<21>")
	)
	(segment
		(start 332.744064 -239.136682)
		(end 332.752446 -239.141508)
		(width 0.0889)
		(layer "In2.Cu")
		(net "M_C_CPU0_SA_DQ<21>")
	)
	(segment
		(start 304.026062 -223.882458)
		(end 304.18913 -223.71939)
		(width 0.14478)
		(layer "In2.Cu")
		(net "M_C_CPU0_SA_DQ<21>")
	)
	(segment
		(start 308.555644 -223.036638)
		(end 308.555644 -223.48952)
		(width 0.14478)
		(layer "In2.Cu")
		(net "M_C_CPU0_SA_DQ<21>")
	)
	(segment
		(start 293.788846 -223.709738)
		(end 293.95039 -223.871282)
		(width 0.14478)
		(layer "In2.Cu")
		(net "M_C_CPU0_SA_DQ<21>")
	)
	(segment
		(start 302.636682 -223.71939)
		(end 302.79975 -223.882458)
		(width 0.14478)
		(layer "In2.Cu")
		(net "M_C_CPU0_SA_DQ<21>")
	)
	(segment
		(start 300.204124 -223.029018)
		(end 300.367192 -222.86595)
		(width 0.14478)
		(layer "In2.Cu")
		(net "M_C_CPU0_SA_DQ<21>")
	)
	(segment
		(start 299.26026 -223.029018)
		(end 299.26026 -223.09709)
		(width 0.14478)
		(layer "In2.Cu")
		(net "M_C_CPU0_SA_DQ<21>")
	)
	(segment
		(start 297.002962 -223.887538)
		(end 297.002962 -223.946974)
		(width 0.14478)
		(layer "In2.Cu")
		(net "M_C_CPU0_SA_DQ<21>")
	)
	(segment
		(start 302.962818 -224.110042)
		(end 303.862994 -224.110042)
		(width 0.14478)
		(layer "In2.Cu")
		(net "M_C_CPU0_SA_DQ<21>")
	)
	(segment
		(start 302.79975 -223.946974)
		(end 302.962818 -224.110042)
		(width 0.14478)
		(layer "In2.Cu")
		(net "M_C_CPU0_SA_DQ<21>")
	)
	(segment
		(start 306.70881 -222.87865)
		(end 306.871878 -223.041718)
		(width 0.14478)
		(layer "In2.Cu")
		(net "M_C_CPU0_SA_DQ<21>")
	)
	(segment
		(start 306.871878 -223.09709)
		(end 307.034946 -223.260158)
		(width 0.14478)
		(layer "In2.Cu")
		(net "M_C_CPU0_SA_DQ<21>")
	)
	(segment
		(start 335.929732 -239.141508)
		(end 335.938114 -239.136682)
		(width 0.0889)
		(layer "In2.Cu")
		(net "M_C_CPU0_SA_DQ<21>")
	)
	(segment
		(start 307.99913 -223.09709)
		(end 307.99913 -223.036638)
		(width 0.14478)
		(layer "In2.Cu")
		(net "M_C_CPU0_SA_DQ<21>")
	)
	(segment
		(start 294.663368 -223.709738)
		(end 294.891714 -223.709738)
		(width 0.14478)
		(layer "In2.Cu")
		(net "M_C_CPU0_SA_DQ<21>")
	)
	(segment
		(start 333.684118 -239.136682)
		(end 333.6925 -239.141508)
		(width 0.0889)
		(layer "In2.Cu")
		(net "M_C_CPU0_SA_DQ<21>")
	)
	(segment
		(start 304.419508 -223.71939)
		(end 304.582576 -223.882458)
		(width 0.14478)
		(layer "In2.Cu")
		(net "M_C_CPU0_SA_DQ<21>")
	)
	(segment
		(start 292.705028 -224.110042)
		(end 293.237412 -224.110042)
		(width 0.14478)
		(layer "In2.Cu")
		(net "M_C_CPU0_SA_DQ<21>")
	)
	(segment
		(start 307.034946 -223.260158)
		(end 307.836062 -223.260158)
		(width 0.14478)
		(layer "In2.Cu")
		(net "M_C_CPU0_SA_DQ<21>")
	)
	(segment
		(start 300.760638 -223.029018)
		(end 300.760638 -223.09709)
		(width 0.14478)
		(layer "In2.Cu")
		(net "M_C_CPU0_SA_DQ<21>")
	)
	(segment
		(start 297.002962 -223.946974)
		(end 297.16603 -224.110042)
		(width 0.14478)
		(layer "In2.Cu")
		(net "M_C_CPU0_SA_DQ<21>")
	)
	(segment
		(start 306.478432 -222.87865)
		(end 306.70881 -222.87865)
		(width 0.14478)
		(layer "In2.Cu")
		(net "M_C_CPU0_SA_DQ<21>")
	)
	(segment
		(start 304.890932 -224.110042)
		(end 305.740816 -223.260158)
		(width 0.14478)
		(layer "In2.Cu")
		(net "M_C_CPU0_SA_DQ<21>")
	)
	(segment
		(start 324.221094 -237.23473)
		(end 324.759574 -237.23473)
		(width 0.0889)
		(layer "In2.Cu")
		(net "M_C_CPU0_SA_DQ<21>")
	)
	(segment
		(start 328.409808 -239.141508)
		(end 328.41819 -239.136682)
		(width 0.0889)
		(layer "In2.Cu")
		(net "M_C_CPU0_SA_DQ<21>")
	)
	(segment
		(start 340.629748 -239.141508)
		(end 340.63813 -239.136682)
		(width 0.0889)
		(layer "In2.Cu")
		(net "M_C_CPU0_SA_DQ<21>")
	)
	(segment
		(start 302.243236 -223.882458)
		(end 302.406304 -223.71939)
		(width 0.14478)
		(layer "In2.Cu")
		(net "M_C_CPU0_SA_DQ<21>")
	)
	(segment
		(start 302.406304 -223.71939)
		(end 302.636682 -223.71939)
		(width 0.14478)
		(layer "In2.Cu")
		(net "M_C_CPU0_SA_DQ<21>")
	)
	(segment
		(start 323.865494 -237.07471)
		(end 324.061074 -237.07471)
		(width 0.0889)
		(layer "In2.Cu")
		(net "M_C_CPU0_SA_DQ<21>")
	)
	(segment
		(start 308.162198 -222.87357)
		(end 308.392576 -222.87357)
		(width 0.14478)
		(layer "In2.Cu")
		(net "M_C_CPU0_SA_DQ<21>")
	)
	(segment
		(start 297.367452 -224.110042)
		(end 298.217336 -223.260158)
		(width 0.14478)
		(layer "In2.Cu")
		(net "M_C_CPU0_SA_DQ<21>")
	)
	(segment
		(start 297.16603 -224.110042)
		(end 297.367452 -224.110042)
		(width 0.14478)
		(layer "In2.Cu")
		(net "M_C_CPU0_SA_DQ<21>")
	)
	(segment
		(start 306.315364 -223.041718)
		(end 306.478432 -222.87865)
		(width 0.14478)
		(layer "In2.Cu")
		(net "M_C_CPU0_SA_DQ<21>")
	)
	(segment
		(start 298.703746 -223.029018)
		(end 298.866814 -222.86595)
		(width 0.14478)
		(layer "In2.Cu")
		(net "M_C_CPU0_SA_DQ<21>")
	)
	(segment
		(start 302.243236 -223.946974)
		(end 302.243236 -223.882458)
		(width 0.14478)
		(layer "In2.Cu")
		(net "M_C_CPU0_SA_DQ<21>")
	)
	(segment
		(start 293.95039 -223.871282)
		(end 293.95039 -224.349056)
		(width 0.14478)
		(layer "In2.Cu")
		(net "M_C_CPU0_SA_DQ<21>")
	)
	(segment
		(start 295.214802 -224.110042)
		(end 296.28338 -224.110042)
		(width 0.14478)
		(layer "In2.Cu")
		(net "M_C_CPU0_SA_DQ<21>")
	)
	(segment
		(start 293.398956 -223.871282)
		(end 293.5605 -223.709738)
		(width 0.14478)
		(layer "In2.Cu")
		(net "M_C_CPU0_SA_DQ<21>")
	)
	(segment
		(start 327.091294 -239.04829)
		(end 327.830688 -239.04829)
		(width 0.0889)
		(layer "In2.Cu")
		(net "M_C_CPU0_SA_DQ<21>")
	)
	(segment
		(start 315.547756 -231.017572)
		(end 321.604894 -237.07471)
		(width 0.14478)
		(layer "In2.Cu")
		(net "M_C_CPU0_SA_DQ<21>")
	)
	(segment
		(start 296.446448 -223.887538)
		(end 296.609516 -223.72447)
		(width 0.14478)
		(layer "In2.Cu")
		(net "M_C_CPU0_SA_DQ<21>")
	)
	(segment
		(start 302.080168 -224.110042)
		(end 302.243236 -223.946974)
		(width 0.14478)
		(layer "In2.Cu")
		(net "M_C_CPU0_SA_DQ<21>")
	)
	(segment
		(start 296.609516 -223.72447)
		(end 296.839894 -223.72447)
		(width 0.14478)
		(layer "In2.Cu")
		(net "M_C_CPU0_SA_DQ<21>")
	)
	(segment
		(start 300.923706 -223.260158)
		(end 301.042832 -223.260158)
		(width 0.14478)
		(layer "In2.Cu")
		(net "M_C_CPU0_SA_DQ<21>")
	)
	(segment
		(start 300.59757 -222.86595)
		(end 300.760638 -223.029018)
		(width 0.14478)
		(layer "In2.Cu")
		(net "M_C_CPU0_SA_DQ<21>")
	)
	(segment
		(start 293.5605 -223.709738)
		(end 293.788846 -223.709738)
		(width 0.14478)
		(layer "In2.Cu")
		(net "M_C_CPU0_SA_DQ<21>")
	)
	(segment
		(start 295.053258 -223.948498)
		(end 295.214802 -224.110042)
		(width 0.14478)
		(layer "In2.Cu")
		(net "M_C_CPU0_SA_DQ<21>")
	)
	(segment
		(start 336.869786 -239.141508)
		(end 336.878168 -239.136682)
		(width 0.0889)
		(layer "In2.Cu")
		(net "M_C_CPU0_SA_DQ<21>")
	)
	(segment
		(start 293.398956 -223.948498)
		(end 293.398956 -223.871282)
		(width 0.14478)
		(layer "In2.Cu")
		(net "M_C_CPU0_SA_DQ<21>")
	)
	(segment
		(start 299.097192 -222.86595)
		(end 299.26026 -223.029018)
		(width 0.14478)
		(layer "In2.Cu")
		(net "M_C_CPU0_SA_DQ<21>")
	)
	(segment
		(start 308.555644 -223.48952)
		(end 309.349394 -224.28327)
		(width 0.14478)
		(layer "In2.Cu")
		(net "M_C_CPU0_SA_DQ<21>")
	)
	(segment
		(start 306.871878 -223.041718)
		(end 306.871878 -223.09709)
		(width 0.14478)
		(layer "In2.Cu")
		(net "M_C_CPU0_SA_DQ<21>")
	)
	(segment
		(start 295.053258 -223.871282)
		(end 295.053258 -223.948498)
		(width 0.14478)
		(layer "In2.Cu")
		(net "M_C_CPU0_SA_DQ<21>")
	)
	(segment
		(start 293.95039 -224.349056)
		(end 294.111934 -224.5106)
		(width 0.14478)
		(layer "In2.Cu")
		(net "M_C_CPU0_SA_DQ<21>")
	)
	(segment
		(start 298.866814 -222.86595)
		(end 299.097192 -222.86595)
		(width 0.14478)
		(layer "In2.Cu")
		(net "M_C_CPU0_SA_DQ<21>")
	)
	(segment
		(start 296.446448 -223.946974)
		(end 296.446448 -223.887538)
		(width 0.14478)
		(layer "In2.Cu")
		(net "M_C_CPU0_SA_DQ<21>")
	)
	(segment
		(start 304.745644 -224.110042)
		(end 304.890932 -224.110042)
		(width 0.14478)
		(layer "In2.Cu")
		(net "M_C_CPU0_SA_DQ<21>")
	)
	(segment
		(start 301.892716 -224.110042)
		(end 302.080168 -224.110042)
		(width 0.14478)
		(layer "In2.Cu")
		(net "M_C_CPU0_SA_DQ<21>")
	)
	(segment
		(start 304.582576 -223.882458)
		(end 304.582576 -223.946974)
		(width 0.14478)
		(layer "In2.Cu")
		(net "M_C_CPU0_SA_DQ<21>")
	)
	(segment
		(start 300.367192 -222.86595)
		(end 300.59757 -222.86595)
		(width 0.14478)
		(layer "In2.Cu")
		(net "M_C_CPU0_SA_DQ<21>")
	)
	(segment
		(start 342.144096 -239.136682)
		(end 342.152478 -239.141508)
		(width 0.0889)
		(layer "In2.Cu")
		(net "M_C_CPU0_SA_DQ<21>")
	)
	(segment
		(start 294.891714 -223.709738)
		(end 295.053258 -223.871282)
		(width 0.14478)
		(layer "In2.Cu")
		(net "M_C_CPU0_SA_DQ<21>")
	)
	(segment
		(start 296.28338 -224.110042)
		(end 296.446448 -223.946974)
		(width 0.14478)
		(layer "In2.Cu")
		(net "M_C_CPU0_SA_DQ<21>")
	)
	(segment
		(start 300.041056 -223.260158)
		(end 300.204124 -223.09709)
		(width 0.14478)
		(layer "In2.Cu")
		(net "M_C_CPU0_SA_DQ<21>")
	)
	(segment
		(start 332.16977 -239.141508)
		(end 332.178152 -239.136682)
		(width 0.0889)
		(layer "In2.Cu")
		(net "M_C_CPU0_SA_DQ<21>")
	)
	(segment
		(start 304.026062 -223.946974)
		(end 304.026062 -223.882458)
		(width 0.14478)
		(layer "In2.Cu")
		(net "M_C_CPU0_SA_DQ<21>")
	)
	(segment
		(start 339.689694 -239.141508)
		(end 339.698076 -239.136682)
		(width 0.0889)
		(layer "In2.Cu")
		(net "M_C_CPU0_SA_DQ<21>")
	)
	(segment
		(start 301.042832 -223.260158)
		(end 301.892716 -224.110042)
		(width 0.14478)
		(layer "In2.Cu")
		(net "M_C_CPU0_SA_DQ<21>")
	)
	(segment
		(start 315.547756 -228.767132)
		(end 315.547756 -231.017572)
		(width 0.14478)
		(layer "In2.Cu")
		(net "M_C_CPU0_SA_DQ<21>")
	)
	(segment
		(start 343.402666 -239.162844)
		(end 343.425018 -239.079532)
		(width 0.0889)
		(layer "In2.Cu")
		(net "M_C_CPU0_SA_DQ<21>")
	)
	(segment
		(start 303.862994 -224.110042)
		(end 304.026062 -223.946974)
		(width 0.14478)
		(layer "In2.Cu")
		(net "M_C_CPU0_SA_DQ<21>")
	)
	(segment
		(start 321.604894 -237.07471)
		(end 323.865494 -237.07471)
		(width 0.14478)
		(layer "In2.Cu")
		(net "M_C_CPU0_SA_DQ<21>")
	)
	(segment
		(start 304.18913 -223.71939)
		(end 304.419508 -223.71939)
		(width 0.14478)
		(layer "In2.Cu")
		(net "M_C_CPU0_SA_DQ<21>")
	)
	(segment
		(start 326.496934 -238.45393)
		(end 327.091294 -239.04829)
		(width 0.0889)
		(layer "In2.Cu")
		(net "M_C_CPU0_SA_DQ<21>")
	)
	(segment
		(start 298.703746 -223.09709)
		(end 298.703746 -223.029018)
		(width 0.14478)
		(layer "In2.Cu")
		(net "M_C_CPU0_SA_DQ<21>")
	)
	(segment
		(start 294.501824 -223.871282)
		(end 294.663368 -223.709738)
		(width 0.14478)
		(layer "In2.Cu")
		(net "M_C_CPU0_SA_DQ<21>")
	)
	(segment
		(start 331.229716 -239.141508)
		(end 331.238098 -239.136682)
		(width 0.0889)
		(layer "In2.Cu")
		(net "M_C_CPU0_SA_DQ<21>")
	)
	(segment
		(start 294.34028 -224.5106)
		(end 294.501824 -224.349056)
		(width 0.14478)
		(layer "In2.Cu")
		(net "M_C_CPU0_SA_DQ<21>")
	)
	(segment
		(start 306.315364 -223.09709)
		(end 306.315364 -223.041718)
		(width 0.14478)
		(layer "In2.Cu")
		(net "M_C_CPU0_SA_DQ<21>")
	)
	(segment
		(start 294.111934 -224.5106)
		(end 294.34028 -224.5106)
		(width 0.14478)
		(layer "In2.Cu")
		(net "M_C_CPU0_SA_DQ<21>")
	)
	(segment
		(start 292.280086 -223.6851)
		(end 292.705028 -224.110042)
		(width 0.14478)
		(layer "In2.Cu")
		(net "M_C_CPU0_SA_DQ<21>")
	)
	(segment
		(start 324.061074 -237.07471)
		(end 324.221094 -237.23473)
		(width 0.0889)
		(layer "In2.Cu")
		(net "M_C_CPU0_SA_DQ<21>")
	)
	(segment
		(start 304.582576 -223.946974)
		(end 304.745644 -224.110042)
		(width 0.14478)
		(layer "In2.Cu")
		(net "M_C_CPU0_SA_DQ<21>")
	)
	(segment
		(start 302.79975 -223.882458)
		(end 302.79975 -223.946974)
		(width 0.14478)
		(layer "In2.Cu")
		(net "M_C_CPU0_SA_DQ<21>")
	)
	(segment
		(start 298.217336 -223.260158)
		(end 298.540678 -223.260158)
		(width 0.14478)
		(layer "In2.Cu")
		(net "M_C_CPU0_SA_DQ<21>")
	)
	(segment
		(start 343.425018 -239.079532)
		(end 343.271094 -238.814102)
		(width 0.0889)
		(layer "In2.Cu")
		(net "M_C_CPU0_SA_DQ<21>")
	)
	(segment
		(start 293.237412 -224.110042)
		(end 293.398956 -223.948498)
		(width 0.14478)
		(layer "In2.Cu")
		(net "M_C_CPU0_SA_DQ<21>")
	)
	(arc
		(start 331.238098 -239.136682)
		(mid 331.521054 -239.060505)
		(end 331.80401 -239.136682)
		(width 0.0889)
		(layer "In2.Cu")
		(net "M_C_CPU0_SA_DQ<21>")
	)
	(arc
		(start 332.178152 -239.136682)
		(mid 332.461108 -239.060505)
		(end 332.744064 -239.136682)
		(width 0.0889)
		(layer "In2.Cu")
		(net "M_C_CPU0_SA_DQ<21>")
	)
	(arc
		(start 339.323934 -239.136682)
		(mid 339.506185 -239.187032)
		(end 339.689694 -239.141508)
		(width 0.0889)
		(layer "In2.Cu")
		(net "M_C_CPU0_SA_DQ<21>")
	)
	(arc
		(start 329.924156 -239.136682)
		(mid 330.1111 -239.186937)
		(end 330.298044 -239.136682)
		(width 0.0889)
		(layer "In2.Cu")
		(net "M_C_CPU0_SA_DQ<21>")
	)
	(arc
		(start 334.624172 -239.136682)
		(mid 334.811116 -239.186937)
		(end 334.99806 -239.136682)
		(width 0.0889)
		(layer "In2.Cu")
		(net "M_C_CPU0_SA_DQ<21>")
	)
	(arc
		(start 336.504026 -239.136682)
		(mid 336.686277 -239.187032)
		(end 336.869786 -239.141508)
		(width 0.0889)
		(layer "In2.Cu")
		(net "M_C_CPU0_SA_DQ<21>")
	)
	(arc
		(start 339.698076 -239.136682)
		(mid 339.981032 -239.060505)
		(end 340.263988 -239.136682)
		(width 0.0889)
		(layer "In2.Cu")
		(net "M_C_CPU0_SA_DQ<21>")
	)
	(arc
		(start 338.384134 -239.136682)
		(mid 338.571078 -239.186937)
		(end 338.758022 -239.136682)
		(width 0.0889)
		(layer "In2.Cu")
		(net "M_C_CPU0_SA_DQ<21>")
	)
	(arc
		(start 342.152478 -239.141508)
		(mid 342.335986 -239.187002)
		(end 342.518238 -239.136682)
		(width 0.0889)
		(layer "In2.Cu")
		(net "M_C_CPU0_SA_DQ<21>")
	)
	(arc
		(start 333.6925 -239.141508)
		(mid 333.876008 -239.187002)
		(end 334.05826 -239.136682)
		(width 0.0889)
		(layer "In2.Cu")
		(net "M_C_CPU0_SA_DQ<21>")
	)
	(arc
		(start 328.044048 -239.136682)
		(mid 328.226299 -239.187032)
		(end 328.409808 -239.141508)
		(width 0.0889)
		(layer "In2.Cu")
		(net "M_C_CPU0_SA_DQ<21>")
	)
	(arc
		(start 328.41819 -239.136682)
		(mid 328.701146 -239.060505)
		(end 328.984102 -239.136682)
		(width 0.0889)
		(layer "In2.Cu")
		(net "M_C_CPU0_SA_DQ<21>")
	)
	(arc
		(start 341.212424 -239.141508)
		(mid 341.395932 -239.187002)
		(end 341.578184 -239.136682)
		(width 0.0889)
		(layer "In2.Cu")
		(net "M_C_CPU0_SA_DQ<21>")
	)
	(arc
		(start 341.578184 -239.136682)
		(mid 341.86114 -239.060505)
		(end 342.144096 -239.136682)
		(width 0.0889)
		(layer "In2.Cu")
		(net "M_C_CPU0_SA_DQ<21>")
	)
	(arc
		(start 327.830688 -239.04829)
		(mid 327.946163 -239.07126)
		(end 328.044048 -239.136682)
		(width 0.0889)
		(layer "In2.Cu")
		(net "M_C_CPU0_SA_DQ<21>")
	)
	(arc
		(start 340.263988 -239.136682)
		(mid 340.446239 -239.187032)
		(end 340.629748 -239.141508)
		(width 0.0889)
		(layer "In2.Cu")
		(net "M_C_CPU0_SA_DQ<21>")
	)
	(arc
		(start 330.298044 -239.136682)
		(mid 330.581 -239.060505)
		(end 330.863956 -239.136682)
		(width 0.0889)
		(layer "In2.Cu")
		(net "M_C_CPU0_SA_DQ<21>")
	)
	(arc
		(start 329.358244 -239.136682)
		(mid 329.6412 -239.060505)
		(end 329.924156 -239.136682)
		(width 0.0889)
		(layer "In2.Cu")
		(net "M_C_CPU0_SA_DQ<21>")
	)
	(arc
		(start 334.05826 -239.136682)
		(mid 334.341216 -239.060505)
		(end 334.624172 -239.136682)
		(width 0.0889)
		(layer "In2.Cu")
		(net "M_C_CPU0_SA_DQ<21>")
	)
	(arc
		(start 332.752446 -239.141508)
		(mid 332.935954 -239.187002)
		(end 333.118206 -239.136682)
		(width 0.0889)
		(layer "In2.Cu")
		(net "M_C_CPU0_SA_DQ<21>")
	)
	(arc
		(start 336.878168 -239.136682)
		(mid 337.161124 -239.060505)
		(end 337.44408 -239.136682)
		(width 0.0889)
		(layer "In2.Cu")
		(net "M_C_CPU0_SA_DQ<21>")
	)
	(arc
		(start 333.118206 -239.136682)
		(mid 333.401162 -239.060505)
		(end 333.684118 -239.136682)
		(width 0.0889)
		(layer "In2.Cu")
		(net "M_C_CPU0_SA_DQ<21>")
	)
	(arc
		(start 328.992484 -239.141508)
		(mid 329.175992 -239.187002)
		(end 329.358244 -239.136682)
		(width 0.0889)
		(layer "In2.Cu")
		(net "M_C_CPU0_SA_DQ<21>")
	)
	(arc
		(start 330.863956 -239.136682)
		(mid 331.046207 -239.187032)
		(end 331.229716 -239.141508)
		(width 0.0889)
		(layer "In2.Cu")
		(net "M_C_CPU0_SA_DQ<21>")
	)
	(arc
		(start 337.818222 -239.136682)
		(mid 338.101178 -239.060505)
		(end 338.384134 -239.136682)
		(width 0.0889)
		(layer "In2.Cu")
		(net "M_C_CPU0_SA_DQ<21>")
	)
	(arc
		(start 337.452462 -239.141508)
		(mid 337.63597 -239.187002)
		(end 337.818222 -239.136682)
		(width 0.0889)
		(layer "In2.Cu")
		(net "M_C_CPU0_SA_DQ<21>")
	)
	(arc
		(start 343.08415 -239.136682)
		(mid 343.240469 -239.185677)
		(end 343.402666 -239.162844)
		(width 0.0889)
		(layer "In2.Cu")
		(net "M_C_CPU0_SA_DQ<21>")
	)
	(arc
		(start 335.563972 -239.136682)
		(mid 335.746223 -239.187032)
		(end 335.929732 -239.141508)
		(width 0.0889)
		(layer "In2.Cu")
		(net "M_C_CPU0_SA_DQ<21>")
	)
	(arc
		(start 340.63813 -239.136682)
		(mid 340.921086 -239.060505)
		(end 341.204042 -239.136682)
		(width 0.0889)
		(layer "In2.Cu")
		(net "M_C_CPU0_SA_DQ<21>")
	)
	(arc
		(start 335.938114 -239.136682)
		(mid 336.22107 -239.060505)
		(end 336.504026 -239.136682)
		(width 0.0889)
		(layer "In2.Cu")
		(net "M_C_CPU0_SA_DQ<21>")
	)
	(arc
		(start 331.80401 -239.136682)
		(mid 331.986261 -239.187032)
		(end 332.16977 -239.141508)
		(width 0.0889)
		(layer "In2.Cu")
		(net "M_C_CPU0_SA_DQ<21>")
	)
	(arc
		(start 338.758022 -239.136682)
		(mid 339.040978 -239.060505)
		(end 339.323934 -239.136682)
		(width 0.0889)
		(layer "In2.Cu")
		(net "M_C_CPU0_SA_DQ<21>")
	)
	(arc
		(start 342.518238 -239.136682)
		(mid 342.801194 -239.060505)
		(end 343.08415 -239.136682)
		(width 0.0889)
		(layer "In2.Cu")
		(net "M_C_CPU0_SA_DQ<21>")
	)
	(arc
		(start 334.99806 -239.136682)
		(mid 335.281016 -239.060505)
		(end 335.563972 -239.136682)
		(width 0.0889)
		(layer "In2.Cu")
		(net "M_C_CPU0_SA_DQ<21>")
	)
	(segment
		(start 342.327992 -238.270034)
		(end 341.86114 -238.004096)
		(width 0.10668)
		(layer "F.Cu")
		(net "M_C_CPU0_SA_DQ<20>")
	)
	(segment
		(start 320.421762 -234.298998)
		(end 320.144902 -234.298998)
		(width 0.14478)
		(layer "In2.Cu")
		(net "M_C_CPU0_SA_DQ<20>")
	)
	(segment
		(start 317.782702 -231.936798)
		(end 317.216028 -231.370124)
		(width 0.14478)
		(layer "In2.Cu")
		(net "M_C_CPU0_SA_DQ<20>")
	)
	(segment
		(start 293.94785 -222.063818)
		(end 293.784782 -221.90075)
		(width 0.14478)
		(layer "In2.Cu")
		(net "M_C_CPU0_SA_DQ<20>")
	)
	(segment
		(start 292.679374 -222.384366)
		(end 292.280086 -221.985078)
		(width 0.14478)
		(layer "In2.Cu")
		(net "M_C_CPU0_SA_DQ<20>")
	)
	(segment
		(start 304.890932 -222.41002)
		(end 301.705264 -222.41002)
		(width 0.14478)
		(layer "In2.Cu")
		(net "M_C_CPU0_SA_DQ<20>")
	)
	(segment
		(start 319.102232 -233.256328)
		(end 319.102232 -232.979468)
		(width 0.14478)
		(layer "In2.Cu")
		(net "M_C_CPU0_SA_DQ<20>")
	)
	(segment
		(start 319.634362 -233.511598)
		(end 319.357502 -233.511598)
		(width 0.14478)
		(layer "In2.Cu")
		(net "M_C_CPU0_SA_DQ<20>")
	)
	(segment
		(start 310.002682 -222.182182)
		(end 310.002682 -221.970092)
		(width 0.14478)
		(layer "In2.Cu")
		(net "M_C_CPU0_SA_DQ<20>")
	)
	(segment
		(start 331.342492 -238.331502)
		(end 331.33411 -238.326676)
		(width 0.0889)
		(layer "In2.Cu")
		(net "M_C_CPU0_SA_DQ<20>")
	)
	(segment
		(start 318.570102 -232.724198)
		(end 318.314832 -232.468928)
		(width 0.14478)
		(layer "In2.Cu")
		(net "M_C_CPU0_SA_DQ<20>")
	)
	(segment
		(start 301.705264 -222.41002)
		(end 300.865032 -221.569788)
		(width 0.14478)
		(layer "In2.Cu")
		(net "M_C_CPU0_SA_DQ<20>")
	)
	(segment
		(start 323.885814 -236.16285)
		(end 322.008754 -236.16285)
		(width 0.14478)
		(layer "In2.Cu")
		(net "M_C_CPU0_SA_DQ<20>")
	)
	(segment
		(start 333.588106 -238.326676)
		(end 333.579724 -238.331502)
		(width 0.0889)
		(layer "In2.Cu")
		(net "M_C_CPU0_SA_DQ<20>")
	)
	(segment
		(start 292.679374 -222.59671)
		(end 292.679374 -222.384366)
		(width 0.14478)
		(layer "In2.Cu")
		(net "M_C_CPU0_SA_DQ<20>")
	)
	(segment
		(start 327.133966 -238.326422)
		(end 326.771254 -237.96371)
		(width 0.0889)
		(layer "In2.Cu")
		(net "M_C_CPU0_SA_DQ<20>")
	)
	(segment
		(start 293.391336 -222.58909)
		(end 293.233856 -222.74657)
		(width 0.14478)
		(layer "In2.Cu")
		(net "M_C_CPU0_SA_DQ<20>")
	)
	(segment
		(start 293.554404 -221.90075)
		(end 293.391336 -222.063818)
		(width 0.14478)
		(layer "In2.Cu")
		(net "M_C_CPU0_SA_DQ<20>")
	)
	(segment
		(start 293.233856 -222.74657)
		(end 292.829234 -222.74657)
		(width 0.14478)
		(layer "In2.Cu")
		(net "M_C_CPU0_SA_DQ<20>")
	)
	(segment
		(start 293.784782 -221.90075)
		(end 293.554404 -221.90075)
		(width 0.14478)
		(layer "In2.Cu")
		(net "M_C_CPU0_SA_DQ<20>")
	)
	(segment
		(start 294.111934 -222.80499)
		(end 293.94785 -222.640906)
		(width 0.14478)
		(layer "In2.Cu")
		(net "M_C_CPU0_SA_DQ<20>")
	)
	(segment
		(start 326.466454 -237.96371)
		(end 325.607934 -237.10519)
		(width 0.0889)
		(layer "In2.Cu")
		(net "M_C_CPU0_SA_DQ<20>")
	)
	(segment
		(start 308.751732 -221.835472)
		(end 308.476396 -221.560136)
		(width 0.14478)
		(layer "In2.Cu")
		(net "M_C_CPU0_SA_DQ<20>")
	)
	(segment
		(start 309.592726 -221.560136)
		(end 309.303166 -221.560136)
		(width 0.14478)
		(layer "In2.Cu")
		(net "M_C_CPU0_SA_DQ<20>")
	)
	(segment
		(start 310.806338 -223.157034)
		(end 310.806338 -222.722694)
		(width 0.14478)
		(layer "In2.Cu")
		(net "M_C_CPU0_SA_DQ<20>")
	)
	(segment
		(start 339.80247 -238.331502)
		(end 339.794088 -238.326676)
		(width 0.0889)
		(layer "In2.Cu")
		(net "M_C_CPU0_SA_DQ<20>")
	)
	(segment
		(start 335.102454 -238.331502)
		(end 335.094072 -238.326676)
		(width 0.0889)
		(layer "In2.Cu")
		(net "M_C_CPU0_SA_DQ<20>")
	)
	(segment
		(start 320.932302 -235.086398)
		(end 320.677032 -234.831128)
		(width 0.14478)
		(layer "In2.Cu")
		(net "M_C_CPU0_SA_DQ<20>")
	)
	(segment
		(start 322.008754 -236.16285)
		(end 321.464432 -235.618528)
		(width 0.14478)
		(layer "In2.Cu")
		(net "M_C_CPU0_SA_DQ<20>")
	)
	(segment
		(start 320.144902 -234.298998)
		(end 319.889632 -234.043728)
		(width 0.14478)
		(layer "In2.Cu")
		(net "M_C_CPU0_SA_DQ<20>")
	)
	(segment
		(start 318.314832 -232.468928)
		(end 318.314832 -232.192068)
		(width 0.14478)
		(layer "In2.Cu")
		(net "M_C_CPU0_SA_DQ<20>")
	)
	(segment
		(start 311.43067 -223.347026)
		(end 310.99633 -223.347026)
		(width 0.14478)
		(layer "In2.Cu")
		(net "M_C_CPU0_SA_DQ<20>")
	)
	(segment
		(start 309.48757 -222.927926)
		(end 309.48757 -222.697294)
		(width 0.14478)
		(layer "In2.Cu")
		(net "M_C_CPU0_SA_DQ<20>")
	)
	(segment
		(start 309.02783 -221.835472)
		(end 308.751732 -221.835472)
		(width 0.14478)
		(layer "In2.Cu")
		(net "M_C_CPU0_SA_DQ<20>")
	)
	(segment
		(start 327.594976 -238.337852)
		(end 327.57491 -238.326422)
		(width 0.0889)
		(layer "In2.Cu")
		(net "M_C_CPU0_SA_DQ<20>")
	)
	(segment
		(start 325.607934 -237.10519)
		(end 325.607934 -236.78769)
		(width 0.0889)
		(layer "In2.Cu")
		(net "M_C_CPU0_SA_DQ<20>")
	)
	(segment
		(start 317.216282 -231.344216)
		(end 317.216282 -231.116124)
		(width 0.14478)
		(layer "In2.Cu")
		(net "M_C_CPU0_SA_DQ<20>")
	)
	(segment
		(start 305.740816 -221.560136)
		(end 304.890932 -222.41002)
		(width 0.14478)
		(layer "In2.Cu")
		(net "M_C_CPU0_SA_DQ<20>")
	)
	(segment
		(start 294.536876 -222.575628)
		(end 294.536876 -222.641922)
		(width 0.14478)
		(layer "In2.Cu")
		(net "M_C_CPU0_SA_DQ<20>")
	)
	(segment
		(start 334.52816 -238.326676)
		(end 334.519778 -238.331502)
		(width 0.0889)
		(layer "In2.Cu")
		(net "M_C_CPU0_SA_DQ<20>")
	)
	(segment
		(start 298.397676 -221.569788)
		(end 297.278552 -222.688912)
		(width 0.14478)
		(layer "In2.Cu")
		(net "M_C_CPU0_SA_DQ<20>")
	)
	(segment
		(start 320.677032 -234.554268)
		(end 320.421762 -234.298998)
		(width 0.14478)
		(layer "In2.Cu")
		(net "M_C_CPU0_SA_DQ<20>")
	)
	(segment
		(start 309.88127 -223.090994)
		(end 309.650638 -223.090994)
		(width 0.14478)
		(layer "In2.Cu")
		(net "M_C_CPU0_SA_DQ<20>")
	)
	(segment
		(start 310.412638 -222.559626)
		(end 309.88127 -223.090994)
		(width 0.14478)
		(layer "In2.Cu")
		(net "M_C_CPU0_SA_DQ<20>")
	)
	(segment
		(start 316.698884 -230.85298)
		(end 316.469014 -230.62311)
		(width 0.14478)
		(layer "In2.Cu")
		(net "M_C_CPU0_SA_DQ<20>")
	)
	(segment
		(start 318.059562 -231.936798)
		(end 317.782702 -231.936798)
		(width 0.14478)
		(layer "In2.Cu")
		(net "M_C_CPU0_SA_DQ<20>")
	)
	(segment
		(start 297.048174 -222.688912)
		(end 296.778934 -222.419672)
		(width 0.14478)
		(layer "In2.Cu")
		(net "M_C_CPU0_SA_DQ<20>")
	)
	(segment
		(start 294.692832 -222.419672)
		(end 294.536876 -222.575628)
		(width 0.14478)
		(layer "In2.Cu")
		(net "M_C_CPU0_SA_DQ<20>")
	)
	(segment
		(start 316.953138 -230.85298)
		(end 316.698884 -230.85298)
		(width 0.14478)
		(layer "In2.Cu")
		(net "M_C_CPU0_SA_DQ<20>")
	)
	(segment
		(start 294.536876 -222.641922)
		(end 294.373808 -222.80499)
		(width 0.14478)
		(layer "In2.Cu")
		(net "M_C_CPU0_SA_DQ<20>")
	)
	(segment
		(start 342.015064 -238.269526)
		(end 341.992712 -238.352838)
		(width 0.0889)
		(layer "In2.Cu")
		(net "M_C_CPU0_SA_DQ<20>")
	)
	(segment
		(start 308.476396 -221.560136)
		(end 305.740816 -221.560136)
		(width 0.14478)
		(layer "In2.Cu")
		(net "M_C_CPU0_SA_DQ<20>")
	)
	(segment
		(start 294.373808 -222.80499)
		(end 294.111934 -222.80499)
		(width 0.14478)
		(layer "In2.Cu")
		(net "M_C_CPU0_SA_DQ<20>")
	)
	(segment
		(start 336.042508 -238.331502)
		(end 336.034126 -238.326676)
		(width 0.0889)
		(layer "In2.Cu")
		(net "M_C_CPU0_SA_DQ<20>")
	)
	(segment
		(start 293.94785 -222.640906)
		(end 293.94785 -222.063818)
		(width 0.14478)
		(layer "In2.Cu")
		(net "M_C_CPU0_SA_DQ<20>")
	)
	(segment
		(start 292.829234 -222.74657)
		(end 292.679374 -222.59671)
		(width 0.14478)
		(layer "In2.Cu")
		(net "M_C_CPU0_SA_DQ<20>")
	)
	(segment
		(start 309.650638 -223.090994)
		(end 309.48757 -222.927926)
		(width 0.14478)
		(layer "In2.Cu")
		(net "M_C_CPU0_SA_DQ<20>")
	)
	(segment
		(start 293.391336 -222.063818)
		(end 293.391336 -222.58909)
		(width 0.14478)
		(layer "In2.Cu")
		(net "M_C_CPU0_SA_DQ<20>")
	)
	(segment
		(start 326.771254 -237.96371)
		(end 326.466454 -237.96371)
		(width 0.0889)
		(layer "In2.Cu")
		(net "M_C_CPU0_SA_DQ<20>")
	)
	(segment
		(start 310.64327 -222.559626)
		(end 310.412638 -222.559626)
		(width 0.14478)
		(layer "In2.Cu")
		(net "M_C_CPU0_SA_DQ<20>")
	)
	(segment
		(start 321.209162 -235.086398)
		(end 320.932302 -235.086398)
		(width 0.14478)
		(layer "In2.Cu")
		(net "M_C_CPU0_SA_DQ<20>")
	)
	(segment
		(start 318.846962 -232.724198)
		(end 318.570102 -232.724198)
		(width 0.14478)
		(layer "In2.Cu")
		(net "M_C_CPU0_SA_DQ<20>")
	)
	(segment
		(start 316.469014 -230.62311)
		(end 316.469014 -228.38537)
		(width 0.14478)
		(layer "In2.Cu")
		(net "M_C_CPU0_SA_DQ<20>")
	)
	(segment
		(start 316.469014 -228.38537)
		(end 311.43067 -223.347026)
		(width 0.14478)
		(layer "In2.Cu")
		(net "M_C_CPU0_SA_DQ<20>")
	)
	(segment
		(start 321.464432 -235.618528)
		(end 321.464432 -235.341668)
		(width 0.14478)
		(layer "In2.Cu")
		(net "M_C_CPU0_SA_DQ<20>")
	)
	(segment
		(start 319.889632 -234.043728)
		(end 319.889632 -233.766868)
		(width 0.14478)
		(layer "In2.Cu")
		(net "M_C_CPU0_SA_DQ<20>")
	)
	(segment
		(start 319.357502 -233.511598)
		(end 319.102232 -233.256328)
		(width 0.14478)
		(layer "In2.Cu")
		(net "M_C_CPU0_SA_DQ<20>")
	)
	(segment
		(start 309.48757 -222.697294)
		(end 310.002682 -222.182182)
		(width 0.14478)
		(layer "In2.Cu")
		(net "M_C_CPU0_SA_DQ<20>")
	)
	(segment
		(start 310.002682 -221.970092)
		(end 309.592726 -221.560136)
		(width 0.14478)
		(layer "In2.Cu")
		(net "M_C_CPU0_SA_DQ<20>")
	)
	(segment
		(start 341.86114 -238.004096)
		(end 342.015064 -238.269526)
		(width 0.0889)
		(layer "In2.Cu")
		(net "M_C_CPU0_SA_DQ<20>")
	)
	(segment
		(start 327.57491 -238.326422)
		(end 327.133966 -238.326422)
		(width 0.0889)
		(layer "In2.Cu")
		(net "M_C_CPU0_SA_DQ<20>")
	)
	(segment
		(start 319.102232 -232.979468)
		(end 318.846962 -232.724198)
		(width 0.14478)
		(layer "In2.Cu")
		(net "M_C_CPU0_SA_DQ<20>")
	)
	(segment
		(start 309.303166 -221.560136)
		(end 309.02783 -221.835472)
		(width 0.14478)
		(layer "In2.Cu")
		(net "M_C_CPU0_SA_DQ<20>")
	)
	(segment
		(start 325.607934 -236.78769)
		(end 324.983094 -236.16285)
		(width 0.0889)
		(layer "In2.Cu")
		(net "M_C_CPU0_SA_DQ<20>")
	)
	(segment
		(start 297.278552 -222.688912)
		(end 297.048174 -222.688912)
		(width 0.14478)
		(layer "In2.Cu")
		(net "M_C_CPU0_SA_DQ<20>")
	)
	(segment
		(start 318.314832 -232.192068)
		(end 318.059562 -231.936798)
		(width 0.14478)
		(layer "In2.Cu")
		(net "M_C_CPU0_SA_DQ<20>")
	)
	(segment
		(start 330.402438 -238.331502)
		(end 330.394056 -238.326676)
		(width 0.0889)
		(layer "In2.Cu")
		(net "M_C_CPU0_SA_DQ<20>")
	)
	(segment
		(start 310.99633 -223.347026)
		(end 310.806338 -223.157034)
		(width 0.14478)
		(layer "In2.Cu")
		(net "M_C_CPU0_SA_DQ<20>")
	)
	(segment
		(start 321.464432 -235.341668)
		(end 321.209162 -235.086398)
		(width 0.14478)
		(layer "In2.Cu")
		(net "M_C_CPU0_SA_DQ<20>")
	)
	(segment
		(start 324.983094 -236.16285)
		(end 323.885814 -236.16285)
		(width 0.0889)
		(layer "In2.Cu")
		(net "M_C_CPU0_SA_DQ<20>")
	)
	(segment
		(start 319.889632 -233.766868)
		(end 319.634362 -233.511598)
		(width 0.14478)
		(layer "In2.Cu")
		(net "M_C_CPU0_SA_DQ<20>")
	)
	(segment
		(start 310.806338 -222.722694)
		(end 310.64327 -222.559626)
		(width 0.14478)
		(layer "In2.Cu")
		(net "M_C_CPU0_SA_DQ<20>")
	)
	(segment
		(start 296.778934 -222.419672)
		(end 294.692832 -222.419672)
		(width 0.14478)
		(layer "In2.Cu")
		(net "M_C_CPU0_SA_DQ<20>")
	)
	(segment
		(start 329.828144 -238.326676)
		(end 329.819762 -238.331502)
		(width 0.0889)
		(layer "In2.Cu")
		(net "M_C_CPU0_SA_DQ<20>")
	)
	(segment
		(start 338.862416 -238.331502)
		(end 338.854034 -238.326676)
		(width 0.0889)
		(layer "In2.Cu")
		(net "M_C_CPU0_SA_DQ<20>")
	)
	(segment
		(start 338.288122 -238.326676)
		(end 338.27974 -238.331502)
		(width 0.0889)
		(layer "In2.Cu")
		(net "M_C_CPU0_SA_DQ<20>")
	)
	(segment
		(start 317.216028 -231.370124)
		(end 317.216282 -231.344216)
		(width 0.14478)
		(layer "In2.Cu")
		(net "M_C_CPU0_SA_DQ<20>")
	)
	(segment
		(start 320.677032 -234.831128)
		(end 320.677032 -234.554268)
		(width 0.14478)
		(layer "In2.Cu")
		(net "M_C_CPU0_SA_DQ<20>")
	)
	(segment
		(start 300.865032 -221.569788)
		(end 298.397676 -221.569788)
		(width 0.14478)
		(layer "In2.Cu")
		(net "M_C_CPU0_SA_DQ<20>")
	)
	(segment
		(start 317.216282 -231.116124)
		(end 316.953138 -230.85298)
		(width 0.14478)
		(layer "In2.Cu")
		(net "M_C_CPU0_SA_DQ<20>")
	)
	(arc
		(start 339.228176 -238.326676)
		(mid 339.045925 -238.377026)
		(end 338.862416 -238.331502)
		(width 0.0889)
		(layer "In2.Cu")
		(net "M_C_CPU0_SA_DQ<20>")
	)
	(arc
		(start 329.454002 -238.326676)
		(mid 329.171046 -238.250499)
		(end 328.88809 -238.326676)
		(width 0.0889)
		(layer "In2.Cu")
		(net "M_C_CPU0_SA_DQ<20>")
	)
	(arc
		(start 337.91398 -238.326676)
		(mid 337.631024 -238.250499)
		(end 337.348068 -238.326676)
		(width 0.0889)
		(layer "In2.Cu")
		(net "M_C_CPU0_SA_DQ<20>")
	)
	(arc
		(start 336.034126 -238.326676)
		(mid 335.75117 -238.250499)
		(end 335.468214 -238.326676)
		(width 0.0889)
		(layer "In2.Cu")
		(net "M_C_CPU0_SA_DQ<20>")
	)
	(arc
		(start 339.794088 -238.326676)
		(mid 339.511132 -238.250499)
		(end 339.228176 -238.326676)
		(width 0.0889)
		(layer "In2.Cu")
		(net "M_C_CPU0_SA_DQ<20>")
	)
	(arc
		(start 335.094072 -238.326676)
		(mid 334.811116 -238.250499)
		(end 334.52816 -238.326676)
		(width 0.0889)
		(layer "In2.Cu")
		(net "M_C_CPU0_SA_DQ<20>")
	)
	(arc
		(start 328.514202 -238.326676)
		(mid 328.231246 -238.250499)
		(end 327.94829 -238.326676)
		(width 0.0889)
		(layer "In2.Cu")
		(net "M_C_CPU0_SA_DQ<20>")
	)
	(arc
		(start 327.94829 -238.326676)
		(mid 327.773051 -238.376747)
		(end 327.594976 -238.337852)
		(width 0.0889)
		(layer "In2.Cu")
		(net "M_C_CPU0_SA_DQ<20>")
	)
	(arc
		(start 338.854034 -238.326676)
		(mid 338.571078 -238.250499)
		(end 338.288122 -238.326676)
		(width 0.0889)
		(layer "In2.Cu")
		(net "M_C_CPU0_SA_DQ<20>")
	)
	(arc
		(start 331.708252 -238.326676)
		(mid 331.526001 -238.377026)
		(end 331.342492 -238.331502)
		(width 0.0889)
		(layer "In2.Cu")
		(net "M_C_CPU0_SA_DQ<20>")
	)
	(arc
		(start 334.154018 -238.326676)
		(mid 333.871062 -238.250499)
		(end 333.588106 -238.326676)
		(width 0.0889)
		(layer "In2.Cu")
		(net "M_C_CPU0_SA_DQ<20>")
	)
	(arc
		(start 330.394056 -238.326676)
		(mid 330.1111 -238.250499)
		(end 329.828144 -238.326676)
		(width 0.0889)
		(layer "In2.Cu")
		(net "M_C_CPU0_SA_DQ<20>")
	)
	(arc
		(start 333.213964 -238.326676)
		(mid 332.931008 -238.250499)
		(end 332.648052 -238.326676)
		(width 0.0889)
		(layer "In2.Cu")
		(net "M_C_CPU0_SA_DQ<20>")
	)
	(arc
		(start 337.348068 -238.326676)
		(mid 337.161124 -238.376931)
		(end 336.97418 -238.326676)
		(width 0.0889)
		(layer "In2.Cu")
		(net "M_C_CPU0_SA_DQ<20>")
	)
	(arc
		(start 334.519778 -238.331502)
		(mid 334.33627 -238.376996)
		(end 334.154018 -238.326676)
		(width 0.0889)
		(layer "In2.Cu")
		(net "M_C_CPU0_SA_DQ<20>")
	)
	(arc
		(start 331.33411 -238.326676)
		(mid 331.051154 -238.250499)
		(end 330.768198 -238.326676)
		(width 0.0889)
		(layer "In2.Cu")
		(net "M_C_CPU0_SA_DQ<20>")
	)
	(arc
		(start 329.819762 -238.331502)
		(mid 329.636254 -238.376996)
		(end 329.454002 -238.326676)
		(width 0.0889)
		(layer "In2.Cu")
		(net "M_C_CPU0_SA_DQ<20>")
	)
	(arc
		(start 341.673942 -238.326676)
		(mid 341.390986 -238.250499)
		(end 341.10803 -238.326676)
		(width 0.0889)
		(layer "In2.Cu")
		(net "M_C_CPU0_SA_DQ<20>")
	)
	(arc
		(start 338.27974 -238.331502)
		(mid 338.096232 -238.376996)
		(end 337.91398 -238.326676)
		(width 0.0889)
		(layer "In2.Cu")
		(net "M_C_CPU0_SA_DQ<20>")
	)
	(arc
		(start 333.579724 -238.331502)
		(mid 333.396216 -238.376996)
		(end 333.213964 -238.326676)
		(width 0.0889)
		(layer "In2.Cu")
		(net "M_C_CPU0_SA_DQ<20>")
	)
	(arc
		(start 332.274164 -238.326676)
		(mid 331.991208 -238.250499)
		(end 331.708252 -238.326676)
		(width 0.0889)
		(layer "In2.Cu")
		(net "M_C_CPU0_SA_DQ<20>")
	)
	(arc
		(start 328.88809 -238.326676)
		(mid 328.701146 -238.376931)
		(end 328.514202 -238.326676)
		(width 0.0889)
		(layer "In2.Cu")
		(net "M_C_CPU0_SA_DQ<20>")
	)
	(arc
		(start 336.97418 -238.326676)
		(mid 336.691224 -238.250499)
		(end 336.408268 -238.326676)
		(width 0.0889)
		(layer "In2.Cu")
		(net "M_C_CPU0_SA_DQ<20>")
	)
	(arc
		(start 335.468214 -238.326676)
		(mid 335.285963 -238.377026)
		(end 335.102454 -238.331502)
		(width 0.0889)
		(layer "In2.Cu")
		(net "M_C_CPU0_SA_DQ<20>")
	)
	(arc
		(start 336.408268 -238.326676)
		(mid 336.226017 -238.377026)
		(end 336.042508 -238.331502)
		(width 0.0889)
		(layer "In2.Cu")
		(net "M_C_CPU0_SA_DQ<20>")
	)
	(arc
		(start 340.734142 -238.326676)
		(mid 340.451186 -238.250499)
		(end 340.16823 -238.326676)
		(width 0.0889)
		(layer "In2.Cu")
		(net "M_C_CPU0_SA_DQ<20>")
	)
	(arc
		(start 332.648052 -238.326676)
		(mid 332.461108 -238.376931)
		(end 332.274164 -238.326676)
		(width 0.0889)
		(layer "In2.Cu")
		(net "M_C_CPU0_SA_DQ<20>")
	)
	(arc
		(start 341.992712 -238.352838)
		(mid 341.83038 -238.375656)
		(end 341.673942 -238.326676)
		(width 0.0889)
		(layer "In2.Cu")
		(net "M_C_CPU0_SA_DQ<20>")
	)
	(arc
		(start 330.768198 -238.326676)
		(mid 330.585947 -238.377026)
		(end 330.402438 -238.331502)
		(width 0.0889)
		(layer "In2.Cu")
		(net "M_C_CPU0_SA_DQ<20>")
	)
	(arc
		(start 341.10803 -238.326676)
		(mid 340.921086 -238.376931)
		(end 340.734142 -238.326676)
		(width 0.0889)
		(layer "In2.Cu")
		(net "M_C_CPU0_SA_DQ<20>")
	)
	(arc
		(start 340.16823 -238.326676)
		(mid 339.985979 -238.377026)
		(end 339.80247 -238.331502)
		(width 0.0889)
		(layer "In2.Cu")
		(net "M_C_CPU0_SA_DQ<20>")
	)
	(segment
		(start 343.737946 -226.120198)
		(end 343.271094 -225.85426)
		(width 0.10668)
		(layer "F.Cu")
		(net "M_C_CPU0_SA_DQ<1>")
	)
	(segment
		(start 302.6537 -198.829422)
		(end 302.490632 -198.99249)
		(width 0.14478)
		(layer "In2.Cu")
		(net "M_C_CPU0_SA_DQ<1>")
	)
	(segment
		(start 300.984158 -198.829422)
		(end 300.984158 -198.773288)
		(width 0.14478)
		(layer "In2.Cu")
		(net "M_C_CPU0_SA_DQ<1>")
	)
	(segment
		(start 330.433172 -223.769682)
		(end 330.394056 -223.746822)
		(width 0.0889)
		(layer "In2.Cu")
		(net "M_C_CPU0_SA_DQ<1>")
	)
	(segment
		(start 305.603402 -198.773288)
		(end 305.603402 -198.834502)
		(width 0.14478)
		(layer "In2.Cu")
		(net "M_C_CPU0_SA_DQ<1>")
	)
	(segment
		(start 304.88382 -198.209662)
		(end 304.653442 -198.209662)
		(width 0.14478)
		(layer "In2.Cu")
		(net "M_C_CPU0_SA_DQ<1>")
	)
	(segment
		(start 298.176188 -198.292212)
		(end 298.017184 -198.451216)
		(width 0.14478)
		(layer "In2.Cu")
		(net "M_C_CPU0_SA_DQ<1>")
	)
	(segment
		(start 303.770792 -198.61022)
		(end 302.816768 -198.61022)
		(width 0.14478)
		(layer "In2.Cu")
		(net "M_C_CPU0_SA_DQ<1>")
	)
	(segment
		(start 302.097186 -198.37273)
		(end 301.934118 -198.209662)
		(width 0.14478)
		(layer "In2.Cu")
		(net "M_C_CPU0_SA_DQ<1>")
	)
	(segment
		(start 300.82109 -198.61022)
		(end 298.727622 -198.61022)
		(width 0.14478)
		(layer "In2.Cu")
		(net "M_C_CPU0_SA_DQ<1>")
	)
	(segment
		(start 305.046888 -198.37273)
		(end 304.88382 -198.209662)
		(width 0.14478)
		(layer "In2.Cu")
		(net "M_C_CPU0_SA_DQ<1>")
	)
	(segment
		(start 341.212424 -226.181666)
		(end 341.204042 -226.17684)
		(width 0.0889)
		(layer "In2.Cu")
		(net "M_C_CPU0_SA_DQ<1>")
	)
	(segment
		(start 329.73645 -222.614236)
		(end 329.73645 -222.259652)
		(width 0.0889)
		(layer "In2.Cu")
		(net "M_C_CPU0_SA_DQ<1>")
	)
	(segment
		(start 322.08978 -209.59445)
		(end 321.051428 -209.59445)
		(width 0.14478)
		(layer "In2.Cu")
		(net "M_C_CPU0_SA_DQ<1>")
	)
	(segment
		(start 305.76647 -198.61022)
		(end 305.603402 -198.773288)
		(width 0.14478)
		(layer "In2.Cu")
		(net "M_C_CPU0_SA_DQ<1>")
	)
	(segment
		(start 301.540672 -198.829422)
		(end 301.377604 -198.99249)
		(width 0.14478)
		(layer "In2.Cu")
		(net "M_C_CPU0_SA_DQ<1>")
	)
	(segment
		(start 301.377604 -198.99249)
		(end 301.147226 -198.99249)
		(width 0.14478)
		(layer "In2.Cu")
		(net "M_C_CPU0_SA_DQ<1>")
	)
	(segment
		(start 302.6537 -198.773288)
		(end 302.6537 -198.829422)
		(width 0.14478)
		(layer "In2.Cu")
		(net "M_C_CPU0_SA_DQ<1>")
	)
	(segment
		(start 335.938114 -226.17684)
		(end 335.929732 -226.181666)
		(width 0.0889)
		(layer "In2.Cu")
		(net "M_C_CPU0_SA_DQ<1>")
	)
	(segment
		(start 304.653442 -198.209662)
		(end 304.490374 -198.37273)
		(width 0.14478)
		(layer "In2.Cu")
		(net "M_C_CPU0_SA_DQ<1>")
	)
	(segment
		(start 340.63813 -226.17684)
		(end 340.629748 -226.181666)
		(width 0.0889)
		(layer "In2.Cu")
		(net "M_C_CPU0_SA_DQ<1>")
	)
	(segment
		(start 304.490374 -198.37273)
		(end 304.490374 -198.834502)
		(width 0.14478)
		(layer "In2.Cu")
		(net "M_C_CPU0_SA_DQ<1>")
	)
	(segment
		(start 302.490632 -198.99249)
		(end 302.260254 -198.99249)
		(width 0.14478)
		(layer "In2.Cu")
		(net "M_C_CPU0_SA_DQ<1>")
	)
	(segment
		(start 297.624754 -198.928228)
		(end 297.46575 -198.769224)
		(width 0.14478)
		(layer "In2.Cu")
		(net "M_C_CPU0_SA_DQ<1>")
	)
	(segment
		(start 297.85818 -198.928228)
		(end 297.624754 -198.928228)
		(width 0.14478)
		(layer "In2.Cu")
		(net "M_C_CPU0_SA_DQ<1>")
	)
	(segment
		(start 337.452462 -226.181666)
		(end 337.44408 -226.17684)
		(width 0.0889)
		(layer "In2.Cu")
		(net "M_C_CPU0_SA_DQ<1>")
	)
	(segment
		(start 297.306746 -198.292212)
		(end 297.07332 -198.292212)
		(width 0.14478)
		(layer "In2.Cu")
		(net "M_C_CPU0_SA_DQ<1>")
	)
	(segment
		(start 305.603402 -198.834502)
		(end 305.440334 -198.99757)
		(width 0.14478)
		(layer "In2.Cu")
		(net "M_C_CPU0_SA_DQ<1>")
	)
	(segment
		(start 321.051428 -209.59445)
		(end 310.067198 -198.61022)
		(width 0.14478)
		(layer "In2.Cu")
		(net "M_C_CPU0_SA_DQ<1>")
	)
	(segment
		(start 324.571868 -213.79053)
		(end 324.571868 -212.076538)
		(width 0.14478)
		(layer "In2.Cu")
		(net "M_C_CPU0_SA_DQ<1>")
	)
	(segment
		(start 298.727622 -198.61022)
		(end 298.409614 -198.292212)
		(width 0.14478)
		(layer "In2.Cu")
		(net "M_C_CPU0_SA_DQ<1>")
	)
	(segment
		(start 329.534774 -218.753436)
		(end 324.571868 -213.79053)
		(width 0.14478)
		(layer "In2.Cu")
		(net "M_C_CPU0_SA_DQ<1>")
	)
	(segment
		(start 324.571868 -212.076538)
		(end 322.08978 -209.59445)
		(width 0.14478)
		(layer "In2.Cu")
		(net "M_C_CPU0_SA_DQ<1>")
	)
	(segment
		(start 303.93386 -198.773288)
		(end 303.770792 -198.61022)
		(width 0.14478)
		(layer "In2.Cu")
		(net "M_C_CPU0_SA_DQ<1>")
	)
	(segment
		(start 297.46575 -198.451216)
		(end 297.306746 -198.292212)
		(width 0.14478)
		(layer "In2.Cu")
		(net "M_C_CPU0_SA_DQ<1>")
	)
	(segment
		(start 292.705028 -198.61022)
		(end 292.280086 -199.035162)
		(width 0.14478)
		(layer "In2.Cu")
		(net "M_C_CPU0_SA_DQ<1>")
	)
	(segment
		(start 330.863956 -224.556828)
		(end 330.833476 -224.539048)
		(width 0.0889)
		(layer "In2.Cu")
		(net "M_C_CPU0_SA_DQ<1>")
	)
	(segment
		(start 310.067198 -198.61022)
		(end 305.76647 -198.61022)
		(width 0.14478)
		(layer "In2.Cu")
		(net "M_C_CPU0_SA_DQ<1>")
	)
	(segment
		(start 301.540672 -198.37273)
		(end 301.540672 -198.829422)
		(width 0.14478)
		(layer "In2.Cu")
		(net "M_C_CPU0_SA_DQ<1>")
	)
	(segment
		(start 296.755312 -198.61022)
		(end 292.705028 -198.61022)
		(width 0.14478)
		(layer "In2.Cu")
		(net "M_C_CPU0_SA_DQ<1>")
	)
	(segment
		(start 298.017184 -198.769224)
		(end 297.85818 -198.928228)
		(width 0.14478)
		(layer "In2.Cu")
		(net "M_C_CPU0_SA_DQ<1>")
	)
	(segment
		(start 332.178152 -226.17684)
		(end 332.16977 -226.181666)
		(width 0.0889)
		(layer "In2.Cu")
		(net "M_C_CPU0_SA_DQ<1>")
	)
	(segment
		(start 300.984158 -198.773288)
		(end 300.82109 -198.61022)
		(width 0.14478)
		(layer "In2.Cu")
		(net "M_C_CPU0_SA_DQ<1>")
	)
	(segment
		(start 333.6925 -226.181666)
		(end 333.684118 -226.17684)
		(width 0.0889)
		(layer "In2.Cu")
		(net "M_C_CPU0_SA_DQ<1>")
	)
	(segment
		(start 329.924156 -222.936816)
		(end 329.892406 -222.918528)
		(width 0.0889)
		(layer "In2.Cu")
		(net "M_C_CPU0_SA_DQ<1>")
	)
	(segment
		(start 302.260254 -198.99249)
		(end 302.097186 -198.829422)
		(width 0.14478)
		(layer "In2.Cu")
		(net "M_C_CPU0_SA_DQ<1>")
	)
	(segment
		(start 301.70374 -198.209662)
		(end 301.540672 -198.37273)
		(width 0.14478)
		(layer "In2.Cu")
		(net "M_C_CPU0_SA_DQ<1>")
	)
	(segment
		(start 336.878168 -226.17684)
		(end 336.869786 -226.181666)
		(width 0.0889)
		(layer "In2.Cu")
		(net "M_C_CPU0_SA_DQ<1>")
	)
	(segment
		(start 298.409614 -198.292212)
		(end 298.176188 -198.292212)
		(width 0.14478)
		(layer "In2.Cu")
		(net "M_C_CPU0_SA_DQ<1>")
	)
	(segment
		(start 331.33411 -225.366834)
		(end 331.30236 -225.348546)
		(width 0.0889)
		(layer "In2.Cu")
		(net "M_C_CPU0_SA_DQ<1>")
	)
	(segment
		(start 304.490374 -198.834502)
		(end 304.327306 -198.99757)
		(width 0.14478)
		(layer "In2.Cu")
		(net "M_C_CPU0_SA_DQ<1>")
	)
	(segment
		(start 305.209956 -198.99757)
		(end 305.046888 -198.834502)
		(width 0.14478)
		(layer "In2.Cu")
		(net "M_C_CPU0_SA_DQ<1>")
	)
	(segment
		(start 301.147226 -198.99249)
		(end 300.984158 -198.829422)
		(width 0.14478)
		(layer "In2.Cu")
		(net "M_C_CPU0_SA_DQ<1>")
	)
	(segment
		(start 298.017184 -198.451216)
		(end 298.017184 -198.769224)
		(width 0.14478)
		(layer "In2.Cu")
		(net "M_C_CPU0_SA_DQ<1>")
	)
	(segment
		(start 329.73645 -222.259652)
		(end 329.534774 -222.057976)
		(width 0.0889)
		(layer "In2.Cu")
		(net "M_C_CPU0_SA_DQ<1>")
	)
	(segment
		(start 303.93386 -198.834502)
		(end 303.93386 -198.773288)
		(width 0.14478)
		(layer "In2.Cu")
		(net "M_C_CPU0_SA_DQ<1>")
	)
	(segment
		(start 342.152478 -226.181666)
		(end 342.144096 -226.17684)
		(width 0.0889)
		(layer "In2.Cu")
		(net "M_C_CPU0_SA_DQ<1>")
	)
	(segment
		(start 302.097186 -198.829422)
		(end 302.097186 -198.37273)
		(width 0.14478)
		(layer "In2.Cu")
		(net "M_C_CPU0_SA_DQ<1>")
	)
	(segment
		(start 305.046888 -198.834502)
		(end 305.046888 -198.37273)
		(width 0.14478)
		(layer "In2.Cu")
		(net "M_C_CPU0_SA_DQ<1>")
	)
	(segment
		(start 301.934118 -198.209662)
		(end 301.70374 -198.209662)
		(width 0.14478)
		(layer "In2.Cu")
		(net "M_C_CPU0_SA_DQ<1>")
	)
	(segment
		(start 304.327306 -198.99757)
		(end 304.096928 -198.99757)
		(width 0.14478)
		(layer "In2.Cu")
		(net "M_C_CPU0_SA_DQ<1>")
	)
	(segment
		(start 302.816768 -198.61022)
		(end 302.6537 -198.773288)
		(width 0.14478)
		(layer "In2.Cu")
		(net "M_C_CPU0_SA_DQ<1>")
	)
	(segment
		(start 343.271094 -225.85426)
		(end 343.425018 -226.11969)
		(width 0.0889)
		(layer "In2.Cu")
		(net "M_C_CPU0_SA_DQ<1>")
	)
	(segment
		(start 330.394056 -223.746822)
		(end 330.362306 -223.728534)
		(width 0.0889)
		(layer "In2.Cu")
		(net "M_C_CPU0_SA_DQ<1>")
	)
	(segment
		(start 331.373226 -225.389694)
		(end 331.33411 -225.366834)
		(width 0.0889)
		(layer "In2.Cu")
		(net "M_C_CPU0_SA_DQ<1>")
	)
	(segment
		(start 339.698076 -226.17684)
		(end 339.689694 -226.181666)
		(width 0.0889)
		(layer "In2.Cu")
		(net "M_C_CPU0_SA_DQ<1>")
	)
	(segment
		(start 343.425018 -226.11969)
		(end 343.402666 -226.203002)
		(width 0.0889)
		(layer "In2.Cu")
		(net "M_C_CPU0_SA_DQ<1>")
	)
	(segment
		(start 329.534774 -222.057976)
		(end 329.534774 -221.21495)
		(width 0.0889)
		(layer "In2.Cu")
		(net "M_C_CPU0_SA_DQ<1>")
	)
	(segment
		(start 330.903072 -224.579688)
		(end 330.863956 -224.556828)
		(width 0.0889)
		(layer "In2.Cu")
		(net "M_C_CPU0_SA_DQ<1>")
	)
	(segment
		(start 329.534774 -221.21495)
		(end 329.534774 -218.753436)
		(width 0.14478)
		(layer "In2.Cu")
		(net "M_C_CPU0_SA_DQ<1>")
	)
	(segment
		(start 297.46575 -198.769224)
		(end 297.46575 -198.451216)
		(width 0.14478)
		(layer "In2.Cu")
		(net "M_C_CPU0_SA_DQ<1>")
	)
	(segment
		(start 304.096928 -198.99757)
		(end 303.93386 -198.834502)
		(width 0.14478)
		(layer "In2.Cu")
		(net "M_C_CPU0_SA_DQ<1>")
	)
	(segment
		(start 329.960478 -222.957898)
		(end 329.924156 -222.936816)
		(width 0.0889)
		(layer "In2.Cu")
		(net "M_C_CPU0_SA_DQ<1>")
	)
	(segment
		(start 331.80401 -226.17684)
		(end 331.77353 -226.15906)
		(width 0.0889)
		(layer "In2.Cu")
		(net "M_C_CPU0_SA_DQ<1>")
	)
	(segment
		(start 297.07332 -198.292212)
		(end 296.755312 -198.61022)
		(width 0.14478)
		(layer "In2.Cu")
		(net "M_C_CPU0_SA_DQ<1>")
	)
	(segment
		(start 332.752446 -226.181666)
		(end 332.744064 -226.17684)
		(width 0.0889)
		(layer "In2.Cu")
		(net "M_C_CPU0_SA_DQ<1>")
	)
	(segment
		(start 305.440334 -198.99757)
		(end 305.209956 -198.99757)
		(width 0.14478)
		(layer "In2.Cu")
		(net "M_C_CPU0_SA_DQ<1>")
	)
	(arc
		(start 338.384134 -226.17684)
		(mid 338.101178 -226.100663)
		(end 337.818222 -226.17684)
		(width 0.0889)
		(layer "In2.Cu")
		(net "M_C_CPU0_SA_DQ<1>")
	)
	(arc
		(start 334.05826 -226.17684)
		(mid 333.876009 -226.22719)
		(end 333.6925 -226.181666)
		(width 0.0889)
		(layer "In2.Cu")
		(net "M_C_CPU0_SA_DQ<1>")
	)
	(arc
		(start 336.869786 -226.181666)
		(mid 336.686278 -226.22716)
		(end 336.504026 -226.17684)
		(width 0.0889)
		(layer "In2.Cu")
		(net "M_C_CPU0_SA_DQ<1>")
	)
	(arc
		(start 337.818222 -226.17684)
		(mid 337.635971 -226.22719)
		(end 337.452462 -226.181666)
		(width 0.0889)
		(layer "In2.Cu")
		(net "M_C_CPU0_SA_DQ<1>")
	)
	(arc
		(start 343.08415 -226.17684)
		(mid 342.801194 -226.100663)
		(end 342.518238 -226.17684)
		(width 0.0889)
		(layer "In2.Cu")
		(net "M_C_CPU0_SA_DQ<1>")
	)
	(arc
		(start 332.16977 -226.181666)
		(mid 331.986262 -226.22716)
		(end 331.80401 -226.17684)
		(width 0.0889)
		(layer "In2.Cu")
		(net "M_C_CPU0_SA_DQ<1>")
	)
	(arc
		(start 342.518238 -226.17684)
		(mid 342.335987 -226.22719)
		(end 342.152478 -226.181666)
		(width 0.0889)
		(layer "In2.Cu")
		(net "M_C_CPU0_SA_DQ<1>")
	)
	(arc
		(start 339.323934 -226.17684)
		(mid 339.040978 -226.100663)
		(end 338.758022 -226.17684)
		(width 0.0889)
		(layer "In2.Cu")
		(net "M_C_CPU0_SA_DQ<1>")
	)
	(arc
		(start 332.744064 -226.17684)
		(mid 332.461108 -226.100663)
		(end 332.178152 -226.17684)
		(width 0.0889)
		(layer "In2.Cu")
		(net "M_C_CPU0_SA_DQ<1>")
	)
	(arc
		(start 342.144096 -226.17684)
		(mid 341.86114 -226.100663)
		(end 341.578184 -226.17684)
		(width 0.0889)
		(layer "In2.Cu")
		(net "M_C_CPU0_SA_DQ<1>")
	)
	(arc
		(start 331.616558 -225.85426)
		(mid 331.552043 -225.592041)
		(end 331.373226 -225.389694)
		(width 0.0889)
		(layer "In2.Cu")
		(net "M_C_CPU0_SA_DQ<1>")
	)
	(arc
		(start 330.362306 -223.728534)
		(mid 330.24763 -223.5952)
		(end 330.20635 -223.424242)
		(width 0.0889)
		(layer "In2.Cu")
		(net "M_C_CPU0_SA_DQ<1>")
	)
	(arc
		(start 335.929732 -226.181666)
		(mid 335.746224 -226.22716)
		(end 335.563972 -226.17684)
		(width 0.0889)
		(layer "In2.Cu")
		(net "M_C_CPU0_SA_DQ<1>")
	)
	(arc
		(start 330.676504 -224.234248)
		(mid 330.611989 -223.972029)
		(end 330.433172 -223.769682)
		(width 0.0889)
		(layer "In2.Cu")
		(net "M_C_CPU0_SA_DQ<1>")
	)
	(arc
		(start 341.578184 -226.17684)
		(mid 341.395933 -226.22719)
		(end 341.212424 -226.181666)
		(width 0.0889)
		(layer "In2.Cu")
		(net "M_C_CPU0_SA_DQ<1>")
	)
	(arc
		(start 339.689694 -226.181666)
		(mid 339.506186 -226.22716)
		(end 339.323934 -226.17684)
		(width 0.0889)
		(layer "In2.Cu")
		(net "M_C_CPU0_SA_DQ<1>")
	)
	(arc
		(start 334.99806 -226.17684)
		(mid 334.811116 -226.227095)
		(end 334.624172 -226.17684)
		(width 0.0889)
		(layer "In2.Cu")
		(net "M_C_CPU0_SA_DQ<1>")
	)
	(arc
		(start 331.146404 -225.044254)
		(mid 331.081889 -224.782035)
		(end 330.903072 -224.579688)
		(width 0.0889)
		(layer "In2.Cu")
		(net "M_C_CPU0_SA_DQ<1>")
	)
	(arc
		(start 330.20635 -223.424242)
		(mid 330.141114 -223.160651)
		(end 329.960478 -222.957898)
		(width 0.0889)
		(layer "In2.Cu")
		(net "M_C_CPU0_SA_DQ<1>")
	)
	(arc
		(start 340.629748 -226.181666)
		(mid 340.44624 -226.22716)
		(end 340.263988 -226.17684)
		(width 0.0889)
		(layer "In2.Cu")
		(net "M_C_CPU0_SA_DQ<1>")
	)
	(arc
		(start 333.684118 -226.17684)
		(mid 333.401162 -226.100663)
		(end 333.118206 -226.17684)
		(width 0.0889)
		(layer "In2.Cu")
		(net "M_C_CPU0_SA_DQ<1>")
	)
	(arc
		(start 343.402666 -226.203002)
		(mid 343.240477 -226.225737)
		(end 343.08415 -226.17684)
		(width 0.0889)
		(layer "In2.Cu")
		(net "M_C_CPU0_SA_DQ<1>")
	)
	(arc
		(start 337.44408 -226.17684)
		(mid 337.161124 -226.100663)
		(end 336.878168 -226.17684)
		(width 0.0889)
		(layer "In2.Cu")
		(net "M_C_CPU0_SA_DQ<1>")
	)
	(arc
		(start 334.624172 -226.17684)
		(mid 334.341216 -226.100663)
		(end 334.05826 -226.17684)
		(width 0.0889)
		(layer "In2.Cu")
		(net "M_C_CPU0_SA_DQ<1>")
	)
	(arc
		(start 329.892406 -222.918528)
		(mid 329.77773 -222.785194)
		(end 329.73645 -222.614236)
		(width 0.0889)
		(layer "In2.Cu")
		(net "M_C_CPU0_SA_DQ<1>")
	)
	(arc
		(start 335.563972 -226.17684)
		(mid 335.281016 -226.100663)
		(end 334.99806 -226.17684)
		(width 0.0889)
		(layer "In2.Cu")
		(net "M_C_CPU0_SA_DQ<1>")
	)
	(arc
		(start 331.30236 -225.348546)
		(mid 331.187684 -225.215212)
		(end 331.146404 -225.044254)
		(width 0.0889)
		(layer "In2.Cu")
		(net "M_C_CPU0_SA_DQ<1>")
	)
	(arc
		(start 333.118206 -226.17684)
		(mid 332.935955 -226.22719)
		(end 332.752446 -226.181666)
		(width 0.0889)
		(layer "In2.Cu")
		(net "M_C_CPU0_SA_DQ<1>")
	)
	(arc
		(start 336.504026 -226.17684)
		(mid 336.22107 -226.100663)
		(end 335.938114 -226.17684)
		(width 0.0889)
		(layer "In2.Cu")
		(net "M_C_CPU0_SA_DQ<1>")
	)
	(arc
		(start 331.77353 -226.15906)
		(mid 331.658103 -226.025684)
		(end 331.616558 -225.85426)
		(width 0.0889)
		(layer "In2.Cu")
		(net "M_C_CPU0_SA_DQ<1>")
	)
	(arc
		(start 338.758022 -226.17684)
		(mid 338.571078 -226.227095)
		(end 338.384134 -226.17684)
		(width 0.0889)
		(layer "In2.Cu")
		(net "M_C_CPU0_SA_DQ<1>")
	)
	(arc
		(start 340.263988 -226.17684)
		(mid 339.981032 -226.100663)
		(end 339.698076 -226.17684)
		(width 0.0889)
		(layer "In2.Cu")
		(net "M_C_CPU0_SA_DQ<1>")
	)
	(arc
		(start 341.204042 -226.17684)
		(mid 340.921086 -226.100663)
		(end 340.63813 -226.17684)
		(width 0.0889)
		(layer "In2.Cu")
		(net "M_C_CPU0_SA_DQ<1>")
	)
	(arc
		(start 330.833476 -224.539048)
		(mid 330.718049 -224.405672)
		(end 330.676504 -224.234248)
		(width 0.0889)
		(layer "In2.Cu")
		(net "M_C_CPU0_SA_DQ<1>")
	)
	(segment
		(start 344.207846 -236.650022)
		(end 343.740994 -236.384084)
		(width 0.10668)
		(layer "F.Cu")
		(net "M_C_CPU0_SA_DQ<19>")
	)
	(segment
		(start 310.91632 -218.160092)
		(end 305.924458 -218.160092)
		(width 0.14478)
		(layer "In2.Cu")
		(net "M_C_CPU0_SA_DQ<19>")
	)
	(segment
		(start 313.133994 -221.66453)
		(end 313.133994 -220.377766)
		(width 0.14478)
		(layer "In2.Cu")
		(net "M_C_CPU0_SA_DQ<19>")
	)
	(segment
		(start 323.883274 -233.75493)
		(end 318.866774 -228.73843)
		(width 0.14478)
		(layer "In2.Cu")
		(net "M_C_CPU0_SA_DQ<19>")
	)
	(segment
		(start 302.382428 -219.01023)
		(end 301.662592 -218.712034)
		(width 0.14478)
		(layer "In2.Cu")
		(net "M_C_CPU0_SA_DQ<19>")
	)
	(segment
		(start 301.662592 -218.712034)
		(end 301.210472 -218.259914)
		(width 0.14478)
		(layer "In2.Cu")
		(net "M_C_CPU0_SA_DQ<19>")
	)
	(segment
		(start 326.452738 -235.086652)
		(end 326.091296 -235.086652)
		(width 0.0889)
		(layer "In2.Cu")
		(net "M_C_CPU0_SA_DQ<19>")
	)
	(segment
		(start 339.80247 -236.056678)
		(end 339.794088 -236.061504)
		(width 0.0889)
		(layer "In2.Cu")
		(net "M_C_CPU0_SA_DQ<19>")
	)
	(segment
		(start 305.520598 -218.327478)
		(end 304.243486 -219.01023)
		(width 0.14478)
		(layer "In2.Cu")
		(net "M_C_CPU0_SA_DQ<19>")
	)
	(segment
		(start 313.133994 -220.377766)
		(end 310.91632 -218.160092)
		(width 0.14478)
		(layer "In2.Cu")
		(net "M_C_CPU0_SA_DQ<19>")
	)
	(segment
		(start 342.048084 -236.061504)
		(end 342.039702 -236.056678)
		(width 0.0889)
		(layer "In2.Cu")
		(net "M_C_CPU0_SA_DQ<19>")
	)
	(segment
		(start 335.102454 -236.056678)
		(end 335.094072 -236.061504)
		(width 0.0889)
		(layer "In2.Cu")
		(net "M_C_CPU0_SA_DQ<19>")
	)
	(segment
		(start 304.243486 -219.01023)
		(end 302.382428 -219.01023)
		(width 0.14478)
		(layer "In2.Cu")
		(net "M_C_CPU0_SA_DQ<19>")
	)
	(segment
		(start 326.091296 -235.086652)
		(end 325.191374 -234.18673)
		(width 0.0889)
		(layer "In2.Cu")
		(net "M_C_CPU0_SA_DQ<19>")
	)
	(segment
		(start 305.924458 -218.160092)
		(end 305.520598 -218.327478)
		(width 0.14478)
		(layer "In2.Cu")
		(net "M_C_CPU0_SA_DQ<19>")
	)
	(segment
		(start 329.828144 -236.061504)
		(end 329.819762 -236.056678)
		(width 0.0889)
		(layer "In2.Cu")
		(net "M_C_CPU0_SA_DQ<19>")
	)
	(segment
		(start 301.210472 -218.259914)
		(end 300.946312 -218.15044)
		(width 0.14478)
		(layer "In2.Cu")
		(net "M_C_CPU0_SA_DQ<19>")
	)
	(segment
		(start 338.862416 -236.056678)
		(end 338.854034 -236.061504)
		(width 0.0889)
		(layer "In2.Cu")
		(net "M_C_CPU0_SA_DQ<19>")
	)
	(segment
		(start 324.096634 -233.75493)
		(end 323.883274 -233.75493)
		(width 0.0889)
		(layer "In2.Cu")
		(net "M_C_CPU0_SA_DQ<19>")
	)
	(segment
		(start 324.528434 -234.18673)
		(end 324.096634 -233.75493)
		(width 0.0889)
		(layer "In2.Cu")
		(net "M_C_CPU0_SA_DQ<19>")
	)
	(segment
		(start 318.866774 -228.73843)
		(end 318.866774 -227.39731)
		(width 0.14478)
		(layer "In2.Cu")
		(net "M_C_CPU0_SA_DQ<19>")
	)
	(segment
		(start 331.342492 -236.056678)
		(end 331.33411 -236.061504)
		(width 0.0889)
		(layer "In2.Cu")
		(net "M_C_CPU0_SA_DQ<19>")
	)
	(segment
		(start 334.52816 -236.061504)
		(end 334.519778 -236.056678)
		(width 0.0889)
		(layer "In2.Cu")
		(net "M_C_CPU0_SA_DQ<19>")
	)
	(segment
		(start 297.08348 -218.84005)
		(end 296.696638 -219.000324)
		(width 0.14478)
		(layer "In2.Cu")
		(net "M_C_CPU0_SA_DQ<19>")
	)
	(segment
		(start 296.696638 -219.000324)
		(end 288.595308 -219.000324)
		(width 0.14478)
		(layer "In2.Cu")
		(net "M_C_CPU0_SA_DQ<19>")
	)
	(segment
		(start 327.383648 -236.017562)
		(end 326.452738 -235.086652)
		(width 0.0889)
		(layer "In2.Cu")
		(net "M_C_CPU0_SA_DQ<19>")
	)
	(segment
		(start 342.988138 -236.061504)
		(end 342.979756 -236.056678)
		(width 0.0889)
		(layer "In2.Cu")
		(net "M_C_CPU0_SA_DQ<19>")
	)
	(segment
		(start 336.042508 -236.056678)
		(end 336.034126 -236.061504)
		(width 0.0889)
		(layer "In2.Cu")
		(net "M_C_CPU0_SA_DQ<19>")
	)
	(segment
		(start 330.402438 -236.056678)
		(end 330.394056 -236.061504)
		(width 0.0889)
		(layer "In2.Cu")
		(net "M_C_CPU0_SA_DQ<19>")
	)
	(segment
		(start 325.191374 -234.18673)
		(end 324.528434 -234.18673)
		(width 0.0889)
		(layer "In2.Cu")
		(net "M_C_CPU0_SA_DQ<19>")
	)
	(segment
		(start 298.30649 -218.15044)
		(end 297.804078 -218.358466)
		(width 0.14478)
		(layer "In2.Cu")
		(net "M_C_CPU0_SA_DQ<19>")
	)
	(segment
		(start 297.804078 -218.358466)
		(end 297.08348 -218.84005)
		(width 0.14478)
		(layer "In2.Cu")
		(net "M_C_CPU0_SA_DQ<19>")
	)
	(segment
		(start 318.866774 -227.39731)
		(end 313.133994 -221.66453)
		(width 0.14478)
		(layer "In2.Cu")
		(net "M_C_CPU0_SA_DQ<19>")
	)
	(segment
		(start 338.288122 -236.061504)
		(end 338.27974 -236.056678)
		(width 0.0889)
		(layer "In2.Cu")
		(net "M_C_CPU0_SA_DQ<19>")
	)
	(segment
		(start 343.58707 -236.118654)
		(end 343.491058 -236.093254)
		(width 0.0889)
		(layer "In2.Cu")
		(net "M_C_CPU0_SA_DQ<19>")
	)
	(segment
		(start 327.805034 -236.017562)
		(end 327.383648 -236.017562)
		(width 0.0889)
		(layer "In2.Cu")
		(net "M_C_CPU0_SA_DQ<19>")
	)
	(segment
		(start 333.588106 -236.061504)
		(end 333.579724 -236.056678)
		(width 0.0889)
		(layer "In2.Cu")
		(net "M_C_CPU0_SA_DQ<19>")
	)
	(segment
		(start 288.595308 -219.000324)
		(end 288.180018 -218.585034)
		(width 0.14478)
		(layer "In2.Cu")
		(net "M_C_CPU0_SA_DQ<19>")
	)
	(segment
		(start 343.740994 -236.384084)
		(end 343.58707 -236.118654)
		(width 0.0889)
		(layer "In2.Cu")
		(net "M_C_CPU0_SA_DQ<19>")
	)
	(segment
		(start 300.946312 -218.15044)
		(end 298.30649 -218.15044)
		(width 0.14478)
		(layer "In2.Cu")
		(net "M_C_CPU0_SA_DQ<19>")
	)
	(arc
		(start 341.673942 -236.061504)
		(mid 341.390986 -236.137681)
		(end 341.10803 -236.061504)
		(width 0.0889)
		(layer "In2.Cu")
		(net "M_C_CPU0_SA_DQ<19>")
	)
	(arc
		(start 335.468214 -236.061504)
		(mid 335.285963 -236.011154)
		(end 335.102454 -236.056678)
		(width 0.0889)
		(layer "In2.Cu")
		(net "M_C_CPU0_SA_DQ<19>")
	)
	(arc
		(start 329.819762 -236.056678)
		(mid 329.636254 -236.011184)
		(end 329.454002 -236.061504)
		(width 0.0889)
		(layer "In2.Cu")
		(net "M_C_CPU0_SA_DQ<19>")
	)
	(arc
		(start 330.394056 -236.061504)
		(mid 330.1111 -236.137681)
		(end 329.828144 -236.061504)
		(width 0.0889)
		(layer "In2.Cu")
		(net "M_C_CPU0_SA_DQ<19>")
	)
	(arc
		(start 327.866756 -236.026452)
		(mid 327.836216 -236.019772)
		(end 327.805034 -236.017562)
		(width 0.0889)
		(layer "In2.Cu")
		(net "M_C_CPU0_SA_DQ<19>")
	)
	(arc
		(start 330.768198 -236.061504)
		(mid 330.585947 -236.011154)
		(end 330.402438 -236.056678)
		(width 0.0889)
		(layer "In2.Cu")
		(net "M_C_CPU0_SA_DQ<19>")
	)
	(arc
		(start 336.034126 -236.061504)
		(mid 335.75117 -236.137681)
		(end 335.468214 -236.061504)
		(width 0.0889)
		(layer "In2.Cu")
		(net "M_C_CPU0_SA_DQ<19>")
	)
	(arc
		(start 338.854034 -236.061504)
		(mid 338.571078 -236.137681)
		(end 338.288122 -236.061504)
		(width 0.0889)
		(layer "In2.Cu")
		(net "M_C_CPU0_SA_DQ<19>")
	)
	(arc
		(start 328.88809 -236.061504)
		(mid 328.701146 -236.011249)
		(end 328.514202 -236.061504)
		(width 0.0889)
		(layer "In2.Cu")
		(net "M_C_CPU0_SA_DQ<19>")
	)
	(arc
		(start 331.708252 -236.061504)
		(mid 331.526001 -236.011154)
		(end 331.342492 -236.056678)
		(width 0.0889)
		(layer "In2.Cu")
		(net "M_C_CPU0_SA_DQ<19>")
	)
	(arc
		(start 332.274164 -236.061504)
		(mid 331.991208 -236.137681)
		(end 331.708252 -236.061504)
		(width 0.0889)
		(layer "In2.Cu")
		(net "M_C_CPU0_SA_DQ<19>")
	)
	(arc
		(start 333.579724 -236.056678)
		(mid 333.396216 -236.011184)
		(end 333.213964 -236.061504)
		(width 0.0889)
		(layer "In2.Cu")
		(net "M_C_CPU0_SA_DQ<19>")
	)
	(arc
		(start 339.794088 -236.061504)
		(mid 339.511132 -236.137681)
		(end 339.228176 -236.061504)
		(width 0.0889)
		(layer "In2.Cu")
		(net "M_C_CPU0_SA_DQ<19>")
	)
	(arc
		(start 342.613996 -236.061504)
		(mid 342.33104 -236.137681)
		(end 342.048084 -236.061504)
		(width 0.0889)
		(layer "In2.Cu")
		(net "M_C_CPU0_SA_DQ<19>")
	)
	(arc
		(start 334.154018 -236.061504)
		(mid 333.871062 -236.137681)
		(end 333.588106 -236.061504)
		(width 0.0889)
		(layer "In2.Cu")
		(net "M_C_CPU0_SA_DQ<19>")
	)
	(arc
		(start 337.91398 -236.061504)
		(mid 337.631024 -236.137681)
		(end 337.348068 -236.061504)
		(width 0.0889)
		(layer "In2.Cu")
		(net "M_C_CPU0_SA_DQ<19>")
	)
	(arc
		(start 341.10803 -236.061504)
		(mid 340.921086 -236.011249)
		(end 340.734142 -236.061504)
		(width 0.0889)
		(layer "In2.Cu")
		(net "M_C_CPU0_SA_DQ<19>")
	)
	(arc
		(start 340.16823 -236.061504)
		(mid 339.985979 -236.011154)
		(end 339.80247 -236.056678)
		(width 0.0889)
		(layer "In2.Cu")
		(net "M_C_CPU0_SA_DQ<19>")
	)
	(arc
		(start 339.228176 -236.061504)
		(mid 339.045925 -236.011154)
		(end 338.862416 -236.056678)
		(width 0.0889)
		(layer "In2.Cu")
		(net "M_C_CPU0_SA_DQ<19>")
	)
	(arc
		(start 328.514202 -236.061504)
		(mid 328.231246 -236.137681)
		(end 327.94829 -236.061504)
		(width 0.0889)
		(layer "In2.Cu")
		(net "M_C_CPU0_SA_DQ<19>")
	)
	(arc
		(start 337.348068 -236.061504)
		(mid 337.161124 -236.011249)
		(end 336.97418 -236.061504)
		(width 0.0889)
		(layer "In2.Cu")
		(net "M_C_CPU0_SA_DQ<19>")
	)
	(arc
		(start 342.979756 -236.056678)
		(mid 342.796248 -236.011184)
		(end 342.613996 -236.061504)
		(width 0.0889)
		(layer "In2.Cu")
		(net "M_C_CPU0_SA_DQ<19>")
	)
	(arc
		(start 329.454002 -236.061504)
		(mid 329.171046 -236.137681)
		(end 328.88809 -236.061504)
		(width 0.0889)
		(layer "In2.Cu")
		(net "M_C_CPU0_SA_DQ<19>")
	)
	(arc
		(start 333.213964 -236.061504)
		(mid 332.931008 -236.137681)
		(end 332.648052 -236.061504)
		(width 0.0889)
		(layer "In2.Cu")
		(net "M_C_CPU0_SA_DQ<19>")
	)
	(arc
		(start 336.97418 -236.061504)
		(mid 336.691224 -236.137681)
		(end 336.408268 -236.061504)
		(width 0.0889)
		(layer "In2.Cu")
		(net "M_C_CPU0_SA_DQ<19>")
	)
	(arc
		(start 331.33411 -236.061504)
		(mid 331.051154 -236.137681)
		(end 330.768198 -236.061504)
		(width 0.0889)
		(layer "In2.Cu")
		(net "M_C_CPU0_SA_DQ<19>")
	)
	(arc
		(start 335.094072 -236.061504)
		(mid 334.811116 -236.137681)
		(end 334.52816 -236.061504)
		(width 0.0889)
		(layer "In2.Cu")
		(net "M_C_CPU0_SA_DQ<19>")
	)
	(arc
		(start 336.408268 -236.061504)
		(mid 336.226017 -236.011154)
		(end 336.042508 -236.056678)
		(width 0.0889)
		(layer "In2.Cu")
		(net "M_C_CPU0_SA_DQ<19>")
	)
	(arc
		(start 342.039702 -236.056678)
		(mid 341.856194 -236.011184)
		(end 341.673942 -236.061504)
		(width 0.0889)
		(layer "In2.Cu")
		(net "M_C_CPU0_SA_DQ<19>")
	)
	(arc
		(start 332.648052 -236.061504)
		(mid 332.461108 -236.011249)
		(end 332.274164 -236.061504)
		(width 0.0889)
		(layer "In2.Cu")
		(net "M_C_CPU0_SA_DQ<19>")
	)
	(arc
		(start 343.491058 -236.093254)
		(mid 343.23585 -236.136731)
		(end 342.988138 -236.061504)
		(width 0.0889)
		(layer "In2.Cu")
		(net "M_C_CPU0_SA_DQ<19>")
	)
	(arc
		(start 334.519778 -236.056678)
		(mid 334.33627 -236.011184)
		(end 334.154018 -236.061504)
		(width 0.0889)
		(layer "In2.Cu")
		(net "M_C_CPU0_SA_DQ<19>")
	)
	(arc
		(start 340.734142 -236.061504)
		(mid 340.451186 -236.137681)
		(end 340.16823 -236.061504)
		(width 0.0889)
		(layer "In2.Cu")
		(net "M_C_CPU0_SA_DQ<19>")
	)
	(arc
		(start 327.94829 -236.061504)
		(mid 327.908568 -236.041547)
		(end 327.866756 -236.026452)
		(width 0.0889)
		(layer "In2.Cu")
		(net "M_C_CPU0_SA_DQ<19>")
	)
	(arc
		(start 338.27974 -236.056678)
		(mid 338.096232 -236.011184)
		(end 337.91398 -236.061504)
		(width 0.0889)
		(layer "In2.Cu")
		(net "M_C_CPU0_SA_DQ<19>")
	)
	(segment
		(start 342.797892 -235.840016)
		(end 342.33104 -235.574078)
		(width 0.10668)
		(layer "F.Cu")
		(net "M_C_CPU0_SA_DQ<18>")
	)
	(segment
		(start 289.93211 -217.847672)
		(end 289.701732 -217.847672)
		(width 0.14478)
		(layer "In2.Cu")
		(net "M_C_CPU0_SA_DQ<18>")
	)
	(segment
		(start 324.444614 -232.58145)
		(end 324.08114 -232.58145)
		(width 0.0889)
		(layer "In2.Cu")
		(net "M_C_CPU0_SA_DQ<18>")
	)
	(segment
		(start 297.168062 -217.310208)
		(end 290.258246 -217.310208)
		(width 0.14478)
		(layer "In2.Cu")
		(net "M_C_CPU0_SA_DQ<18>")
	)
	(segment
		(start 335.938114 -235.251498)
		(end 335.929732 -235.246672)
		(width 0.0889)
		(layer "In2.Cu")
		(net "M_C_CPU0_SA_DQ<18>")
	)
	(segment
		(start 326.230996 -234.367832)
		(end 324.444614 -232.58145)
		(width 0.0889)
		(layer "In2.Cu")
		(net "M_C_CPU0_SA_DQ<18>")
	)
	(segment
		(start 328.992484 -235.246672)
		(end 328.984102 -235.251498)
		(width 0.0889)
		(layer "In2.Cu")
		(net "M_C_CPU0_SA_DQ<18>")
	)
	(segment
		(start 337.452462 -235.246672)
		(end 337.44408 -235.251498)
		(width 0.0889)
		(layer "In2.Cu")
		(net "M_C_CPU0_SA_DQ<18>")
	)
	(segment
		(start 332.178152 -235.251498)
		(end 332.16977 -235.246672)
		(width 0.0889)
		(layer "In2.Cu")
		(net "M_C_CPU0_SA_DQ<18>")
	)
	(segment
		(start 288.605214 -217.310208)
		(end 288.180018 -216.885012)
		(width 0.14478)
		(layer "In2.Cu")
		(net "M_C_CPU0_SA_DQ<18>")
	)
	(segment
		(start 342.33104 -235.574078)
		(end 342.177116 -235.308648)
		(width 0.0889)
		(layer "In2.Cu")
		(net "M_C_CPU0_SA_DQ<18>")
	)
	(segment
		(start 336.878168 -235.251498)
		(end 336.869786 -235.246672)
		(width 0.0889)
		(layer "In2.Cu")
		(net "M_C_CPU0_SA_DQ<18>")
	)
	(segment
		(start 327.369678 -235.251498)
		(end 326.486012 -234.367832)
		(width 0.0889)
		(layer "In2.Cu")
		(net "M_C_CPU0_SA_DQ<18>")
	)
	(segment
		(start 289.538664 -217.684604)
		(end 289.538664 -217.473276)
		(width 0.14478)
		(layer "In2.Cu")
		(net "M_C_CPU0_SA_DQ<18>")
	)
	(segment
		(start 319.798192 -228.298502)
		(end 319.798192 -226.893628)
		(width 0.14478)
		(layer "In2.Cu")
		(net "M_C_CPU0_SA_DQ<18>")
	)
	(segment
		(start 290.095178 -217.684604)
		(end 289.93211 -217.847672)
		(width 0.14478)
		(layer "In2.Cu")
		(net "M_C_CPU0_SA_DQ<18>")
	)
	(segment
		(start 289.701732 -217.847672)
		(end 289.538664 -217.684604)
		(width 0.14478)
		(layer "In2.Cu")
		(net "M_C_CPU0_SA_DQ<18>")
	)
	(segment
		(start 331.238098 -235.251498)
		(end 331.229716 -235.246672)
		(width 0.0889)
		(layer "In2.Cu")
		(net "M_C_CPU0_SA_DQ<18>")
	)
	(segment
		(start 332.752446 -235.246672)
		(end 332.744064 -235.251498)
		(width 0.0889)
		(layer "In2.Cu")
		(net "M_C_CPU0_SA_DQ<18>")
	)
	(segment
		(start 298.0182 -216.46007)
		(end 297.168062 -217.310208)
		(width 0.14478)
		(layer "In2.Cu")
		(net "M_C_CPU0_SA_DQ<18>")
	)
	(segment
		(start 311.277762 -217.24239)
		(end 309.347362 -217.24239)
		(width 0.14478)
		(layer "In2.Cu")
		(net "M_C_CPU0_SA_DQ<18>")
	)
	(segment
		(start 324.08114 -232.58145)
		(end 319.798192 -228.298502)
		(width 0.14478)
		(layer "In2.Cu")
		(net "M_C_CPU0_SA_DQ<18>")
	)
	(segment
		(start 308.565042 -216.46007)
		(end 305.559714 -216.46007)
		(width 0.14478)
		(layer "In2.Cu")
		(net "M_C_CPU0_SA_DQ<18>")
	)
	(segment
		(start 342.177116 -235.308648)
		(end 342.081104 -235.283248)
		(width 0.0889)
		(layer "In2.Cu")
		(net "M_C_CPU0_SA_DQ<18>")
	)
	(segment
		(start 319.798192 -226.893628)
		(end 314.053474 -221.14891)
		(width 0.14478)
		(layer "In2.Cu")
		(net "M_C_CPU0_SA_DQ<18>")
	)
	(segment
		(start 328.044048 -235.251498)
		(end 328.033634 -235.257594)
		(width 0.0889)
		(layer "In2.Cu")
		(net "M_C_CPU0_SA_DQ<18>")
	)
	(segment
		(start 301.90186 -217.310208)
		(end 301.051722 -216.46007)
		(width 0.14478)
		(layer "In2.Cu")
		(net "M_C_CPU0_SA_DQ<18>")
	)
	(segment
		(start 309.347362 -217.24239)
		(end 308.565042 -216.46007)
		(width 0.14478)
		(layer "In2.Cu")
		(net "M_C_CPU0_SA_DQ<18>")
	)
	(segment
		(start 328.41819 -235.251498)
		(end 328.409808 -235.246672)
		(width 0.0889)
		(layer "In2.Cu")
		(net "M_C_CPU0_SA_DQ<18>")
	)
	(segment
		(start 340.63813 -235.251498)
		(end 340.629748 -235.246672)
		(width 0.0889)
		(layer "In2.Cu")
		(net "M_C_CPU0_SA_DQ<18>")
	)
	(segment
		(start 290.258246 -217.310208)
		(end 290.095178 -217.473276)
		(width 0.14478)
		(layer "In2.Cu")
		(net "M_C_CPU0_SA_DQ<18>")
	)
	(segment
		(start 301.051722 -216.46007)
		(end 298.0182 -216.46007)
		(width 0.14478)
		(layer "In2.Cu")
		(net "M_C_CPU0_SA_DQ<18>")
	)
	(segment
		(start 339.698076 -235.251498)
		(end 339.689694 -235.246672)
		(width 0.0889)
		(layer "In2.Cu")
		(net "M_C_CPU0_SA_DQ<18>")
	)
	(segment
		(start 304.709576 -217.310208)
		(end 301.90186 -217.310208)
		(width 0.14478)
		(layer "In2.Cu")
		(net "M_C_CPU0_SA_DQ<18>")
	)
	(segment
		(start 314.053474 -221.14891)
		(end 314.053474 -220.018102)
		(width 0.14478)
		(layer "In2.Cu")
		(net "M_C_CPU0_SA_DQ<18>")
	)
	(segment
		(start 333.6925 -235.246672)
		(end 333.684118 -235.251498)
		(width 0.0889)
		(layer "In2.Cu")
		(net "M_C_CPU0_SA_DQ<18>")
	)
	(segment
		(start 289.375596 -217.310208)
		(end 288.605214 -217.310208)
		(width 0.14478)
		(layer "In2.Cu")
		(net "M_C_CPU0_SA_DQ<18>")
	)
	(segment
		(start 314.053474 -220.018102)
		(end 311.277762 -217.24239)
		(width 0.14478)
		(layer "In2.Cu")
		(net "M_C_CPU0_SA_DQ<18>")
	)
	(segment
		(start 305.559714 -216.46007)
		(end 304.709576 -217.310208)
		(width 0.14478)
		(layer "In2.Cu")
		(net "M_C_CPU0_SA_DQ<18>")
	)
	(segment
		(start 327.477882 -235.251498)
		(end 327.369678 -235.251498)
		(width 0.0889)
		(layer "In2.Cu")
		(net "M_C_CPU0_SA_DQ<18>")
	)
	(segment
		(start 289.538664 -217.473276)
		(end 289.375596 -217.310208)
		(width 0.14478)
		(layer "In2.Cu")
		(net "M_C_CPU0_SA_DQ<18>")
	)
	(segment
		(start 290.095178 -217.473276)
		(end 290.095178 -217.684604)
		(width 0.14478)
		(layer "In2.Cu")
		(net "M_C_CPU0_SA_DQ<18>")
	)
	(segment
		(start 326.486012 -234.367832)
		(end 326.230996 -234.367832)
		(width 0.0889)
		(layer "In2.Cu")
		(net "M_C_CPU0_SA_DQ<18>")
	)
	(segment
		(start 341.212424 -235.246672)
		(end 341.204042 -235.251498)
		(width 0.0889)
		(layer "In2.Cu")
		(net "M_C_CPU0_SA_DQ<18>")
	)
	(arc
		(start 331.229716 -235.246672)
		(mid 331.046208 -235.201178)
		(end 330.863956 -235.251498)
		(width 0.0889)
		(layer "In2.Cu")
		(net "M_C_CPU0_SA_DQ<18>")
	)
	(arc
		(start 328.409808 -235.246672)
		(mid 328.2263 -235.201178)
		(end 328.044048 -235.251498)
		(width 0.0889)
		(layer "In2.Cu")
		(net "M_C_CPU0_SA_DQ<18>")
	)
	(arc
		(start 341.578184 -235.251498)
		(mid 341.395933 -235.201148)
		(end 341.212424 -235.246672)
		(width 0.0889)
		(layer "In2.Cu")
		(net "M_C_CPU0_SA_DQ<18>")
	)
	(arc
		(start 330.863956 -235.251498)
		(mid 330.581 -235.327675)
		(end 330.298044 -235.251498)
		(width 0.0889)
		(layer "In2.Cu")
		(net "M_C_CPU0_SA_DQ<18>")
	)
	(arc
		(start 339.323934 -235.251498)
		(mid 339.040978 -235.327675)
		(end 338.758022 -235.251498)
		(width 0.0889)
		(layer "In2.Cu")
		(net "M_C_CPU0_SA_DQ<18>")
	)
	(arc
		(start 335.929732 -235.246672)
		(mid 335.746224 -235.201178)
		(end 335.563972 -235.251498)
		(width 0.0889)
		(layer "In2.Cu")
		(net "M_C_CPU0_SA_DQ<18>")
	)
	(arc
		(start 340.629748 -235.246672)
		(mid 340.44624 -235.201178)
		(end 340.263988 -235.251498)
		(width 0.0889)
		(layer "In2.Cu")
		(net "M_C_CPU0_SA_DQ<18>")
	)
	(arc
		(start 332.16977 -235.246672)
		(mid 331.986262 -235.201178)
		(end 331.80401 -235.251498)
		(width 0.0889)
		(layer "In2.Cu")
		(net "M_C_CPU0_SA_DQ<18>")
	)
	(arc
		(start 332.744064 -235.251498)
		(mid 332.461108 -235.327675)
		(end 332.178152 -235.251498)
		(width 0.0889)
		(layer "In2.Cu")
		(net "M_C_CPU0_SA_DQ<18>")
	)
	(arc
		(start 336.504026 -235.251498)
		(mid 336.22107 -235.327675)
		(end 335.938114 -235.251498)
		(width 0.0889)
		(layer "In2.Cu")
		(net "M_C_CPU0_SA_DQ<18>")
	)
	(arc
		(start 339.689694 -235.246672)
		(mid 339.506186 -235.201178)
		(end 339.323934 -235.251498)
		(width 0.0889)
		(layer "In2.Cu")
		(net "M_C_CPU0_SA_DQ<18>")
	)
	(arc
		(start 334.99806 -235.251498)
		(mid 334.811116 -235.201243)
		(end 334.624172 -235.251498)
		(width 0.0889)
		(layer "In2.Cu")
		(net "M_C_CPU0_SA_DQ<18>")
	)
	(arc
		(start 329.924156 -235.251498)
		(mid 329.6412 -235.327675)
		(end 329.358244 -235.251498)
		(width 0.0889)
		(layer "In2.Cu")
		(net "M_C_CPU0_SA_DQ<18>")
	)
	(arc
		(start 338.758022 -235.251498)
		(mid 338.571078 -235.201243)
		(end 338.384134 -235.251498)
		(width 0.0889)
		(layer "In2.Cu")
		(net "M_C_CPU0_SA_DQ<18>")
	)
	(arc
		(start 331.80401 -235.251498)
		(mid 331.521054 -235.327675)
		(end 331.238098 -235.251498)
		(width 0.0889)
		(layer "In2.Cu")
		(net "M_C_CPU0_SA_DQ<18>")
	)
	(arc
		(start 335.563972 -235.251498)
		(mid 335.281016 -235.327675)
		(end 334.99806 -235.251498)
		(width 0.0889)
		(layer "In2.Cu")
		(net "M_C_CPU0_SA_DQ<18>")
	)
	(arc
		(start 341.204042 -235.251498)
		(mid 340.921086 -235.327675)
		(end 340.63813 -235.251498)
		(width 0.0889)
		(layer "In2.Cu")
		(net "M_C_CPU0_SA_DQ<18>")
	)
	(arc
		(start 337.44408 -235.251498)
		(mid 337.161124 -235.327675)
		(end 336.878168 -235.251498)
		(width 0.0889)
		(layer "In2.Cu")
		(net "M_C_CPU0_SA_DQ<18>")
	)
	(arc
		(start 330.298044 -235.251498)
		(mid 330.1111 -235.201243)
		(end 329.924156 -235.251498)
		(width 0.0889)
		(layer "In2.Cu")
		(net "M_C_CPU0_SA_DQ<18>")
	)
	(arc
		(start 328.033634 -235.257594)
		(mid 327.754948 -235.327814)
		(end 327.477882 -235.251498)
		(width 0.0889)
		(layer "In2.Cu")
		(net "M_C_CPU0_SA_DQ<18>")
	)
	(arc
		(start 333.118206 -235.251498)
		(mid 332.935955 -235.201148)
		(end 332.752446 -235.246672)
		(width 0.0889)
		(layer "In2.Cu")
		(net "M_C_CPU0_SA_DQ<18>")
	)
	(arc
		(start 336.869786 -235.246672)
		(mid 336.686278 -235.201178)
		(end 336.504026 -235.251498)
		(width 0.0889)
		(layer "In2.Cu")
		(net "M_C_CPU0_SA_DQ<18>")
	)
	(arc
		(start 328.984102 -235.251498)
		(mid 328.701146 -235.327675)
		(end 328.41819 -235.251498)
		(width 0.0889)
		(layer "In2.Cu")
		(net "M_C_CPU0_SA_DQ<18>")
	)
	(arc
		(start 340.263988 -235.251498)
		(mid 339.981032 -235.327675)
		(end 339.698076 -235.251498)
		(width 0.0889)
		(layer "In2.Cu")
		(net "M_C_CPU0_SA_DQ<18>")
	)
	(arc
		(start 334.05826 -235.251498)
		(mid 333.876009 -235.201148)
		(end 333.6925 -235.246672)
		(width 0.0889)
		(layer "In2.Cu")
		(net "M_C_CPU0_SA_DQ<18>")
	)
	(arc
		(start 334.624172 -235.251498)
		(mid 334.341216 -235.327675)
		(end 334.05826 -235.251498)
		(width 0.0889)
		(layer "In2.Cu")
		(net "M_C_CPU0_SA_DQ<18>")
	)
	(arc
		(start 329.358244 -235.251498)
		(mid 329.175993 -235.201148)
		(end 328.992484 -235.246672)
		(width 0.0889)
		(layer "In2.Cu")
		(net "M_C_CPU0_SA_DQ<18>")
	)
	(arc
		(start 333.684118 -235.251498)
		(mid 333.401162 -235.327675)
		(end 333.118206 -235.251498)
		(width 0.0889)
		(layer "In2.Cu")
		(net "M_C_CPU0_SA_DQ<18>")
	)
	(arc
		(start 338.384134 -235.251498)
		(mid 338.101178 -235.327675)
		(end 337.818222 -235.251498)
		(width 0.0889)
		(layer "In2.Cu")
		(net "M_C_CPU0_SA_DQ<18>")
	)
	(arc
		(start 342.081104 -235.283248)
		(mid 341.825896 -235.326725)
		(end 341.578184 -235.251498)
		(width 0.0889)
		(layer "In2.Cu")
		(net "M_C_CPU0_SA_DQ<18>")
	)
	(arc
		(start 337.818222 -235.251498)
		(mid 337.635971 -235.201148)
		(end 337.452462 -235.246672)
		(width 0.0889)
		(layer "In2.Cu")
		(net "M_C_CPU0_SA_DQ<18>")
	)
	(segment
		(start 343.737946 -235.840016)
		(end 343.271094 -235.574078)
		(width 0.10668)
		(layer "F.Cu")
		(net "M_C_CPU0_SA_DQ<17>")
	)
	(segment
		(start 298.566586 -217.077798)
		(end 298.566586 -217.14714)
		(width 0.14478)
		(layer "In2.Cu")
		(net "M_C_CPU0_SA_DQ<17>")
	)
	(segment
		(start 296.821098 -217.997024)
		(end 296.821098 -217.936318)
		(width 0.14478)
		(layer "In2.Cu")
		(net "M_C_CPU0_SA_DQ<17>")
	)
	(segment
		(start 332.752446 -235.901484)
		(end 332.744064 -235.896658)
		(width 0.0889)
		(layer "In2.Cu")
		(net "M_C_CPU0_SA_DQ<17>")
	)
	(segment
		(start 308.548532 -217.310208)
		(end 306.92598 -217.310208)
		(width 0.14478)
		(layer "In2.Cu")
		(net "M_C_CPU0_SA_DQ<17>")
	)
	(segment
		(start 295.067736 -217.997024)
		(end 295.067736 -217.936318)
		(width 0.14478)
		(layer "In2.Cu")
		(net "M_C_CPU0_SA_DQ<17>")
	)
	(segment
		(start 332.178152 -235.896658)
		(end 332.16977 -235.901484)
		(width 0.0889)
		(layer "In2.Cu")
		(net "M_C_CPU0_SA_DQ<17>")
	)
	(segment
		(start 296.101516 -218.160092)
		(end 295.230804 -218.160092)
		(width 0.14478)
		(layer "In2.Cu")
		(net "M_C_CPU0_SA_DQ<17>")
	)
	(segment
		(start 324.013576 -233.181652)
		(end 319.333372 -228.501448)
		(width 0.14478)
		(layer "In2.Cu")
		(net "M_C_CPU0_SA_DQ<17>")
	)
	(segment
		(start 294.117776 -218.53017)
		(end 293.954708 -218.367102)
		(width 0.14478)
		(layer "In2.Cu")
		(net "M_C_CPU0_SA_DQ<17>")
	)
	(segment
		(start 306.762912 -217.085418)
		(end 306.599844 -216.92235)
		(width 0.14478)
		(layer "In2.Cu")
		(net "M_C_CPU0_SA_DQ<17>")
	)
	(segment
		(start 328.992484 -235.901484)
		(end 328.984102 -235.896658)
		(width 0.0889)
		(layer "In2.Cu")
		(net "M_C_CPU0_SA_DQ<17>")
	)
	(segment
		(start 294.348154 -218.53017)
		(end 294.117776 -218.53017)
		(width 0.14478)
		(layer "In2.Cu")
		(net "M_C_CPU0_SA_DQ<17>")
	)
	(segment
		(start 295.067736 -217.936318)
		(end 294.904668 -217.77325)
		(width 0.14478)
		(layer "In2.Cu")
		(net "M_C_CPU0_SA_DQ<17>")
	)
	(segment
		(start 294.511222 -217.936318)
		(end 294.511222 -218.367102)
		(width 0.14478)
		(layer "In2.Cu")
		(net "M_C_CPU0_SA_DQ<17>")
	)
	(segment
		(start 296.264584 -217.936318)
		(end 296.264584 -217.997024)
		(width 0.14478)
		(layer "In2.Cu")
		(net "M_C_CPU0_SA_DQ<17>")
	)
	(segment
		(start 299.286168 -217.310208)
		(end 299.1231 -217.14714)
		(width 0.14478)
		(layer "In2.Cu")
		(net "M_C_CPU0_SA_DQ<17>")
	)
	(segment
		(start 326.376538 -234.725972)
		(end 326.083676 -234.725972)
		(width 0.0889)
		(layer "In2.Cu")
		(net "M_C_CPU0_SA_DQ<17>")
	)
	(segment
		(start 302.598328 -217.77325)
		(end 302.36795 -217.77325)
		(width 0.14478)
		(layer "In2.Cu")
		(net "M_C_CPU0_SA_DQ<17>")
	)
	(segment
		(start 302.204882 -217.997024)
		(end 302.041814 -218.160092)
		(width 0.14478)
		(layer "In2.Cu")
		(net "M_C_CPU0_SA_DQ<17>")
	)
	(segment
		(start 301.042832 -217.310208)
		(end 299.286168 -217.310208)
		(width 0.14478)
		(layer "In2.Cu")
		(net "M_C_CPU0_SA_DQ<17>")
	)
	(segment
		(start 319.333372 -227.208334)
		(end 313.598814 -221.473776)
		(width 0.14478)
		(layer "In2.Cu")
		(net "M_C_CPU0_SA_DQ<17>")
	)
	(segment
		(start 298.729654 -216.91473)
		(end 298.566586 -217.077798)
		(width 0.14478)
		(layer "In2.Cu")
		(net "M_C_CPU0_SA_DQ<17>")
	)
	(segment
		(start 313.598814 -220.20657)
		(end 311.096914 -217.70467)
		(width 0.14478)
		(layer "In2.Cu")
		(net "M_C_CPU0_SA_DQ<17>")
	)
	(segment
		(start 294.511222 -218.367102)
		(end 294.348154 -218.53017)
		(width 0.14478)
		(layer "In2.Cu")
		(net "M_C_CPU0_SA_DQ<17>")
	)
	(segment
		(start 293.561262 -217.77325)
		(end 293.398194 -217.936318)
		(width 0.14478)
		(layer "In2.Cu")
		(net "M_C_CPU0_SA_DQ<17>")
	)
	(segment
		(start 293.954708 -218.367102)
		(end 293.954708 -217.936318)
		(width 0.14478)
		(layer "In2.Cu")
		(net "M_C_CPU0_SA_DQ<17>")
	)
	(segment
		(start 299.1231 -217.14714)
		(end 299.1231 -217.077798)
		(width 0.14478)
		(layer "In2.Cu")
		(net "M_C_CPU0_SA_DQ<17>")
	)
	(segment
		(start 296.984166 -218.160092)
		(end 296.821098 -217.997024)
		(width 0.14478)
		(layer "In2.Cu")
		(net "M_C_CPU0_SA_DQ<17>")
	)
	(segment
		(start 331.238098 -235.896658)
		(end 331.229716 -235.901484)
		(width 0.0889)
		(layer "In2.Cu")
		(net "M_C_CPU0_SA_DQ<17>")
	)
	(segment
		(start 333.6925 -235.901484)
		(end 333.684118 -235.896658)
		(width 0.0889)
		(layer "In2.Cu")
		(net "M_C_CPU0_SA_DQ<17>")
	)
	(segment
		(start 319.333372 -228.501448)
		(end 319.333372 -227.208334)
		(width 0.14478)
		(layer "In2.Cu")
		(net "M_C_CPU0_SA_DQ<17>")
	)
	(segment
		(start 302.36795 -217.77325)
		(end 302.204882 -217.936318)
		(width 0.14478)
		(layer "In2.Cu")
		(net "M_C_CPU0_SA_DQ<17>")
	)
	(segment
		(start 306.369466 -216.92235)
		(end 306.206398 -217.085418)
		(width 0.14478)
		(layer "In2.Cu")
		(net "M_C_CPU0_SA_DQ<17>")
	)
	(segment
		(start 293.235126 -218.160092)
		(end 292.705028 -218.160092)
		(width 0.14478)
		(layer "In2.Cu")
		(net "M_C_CPU0_SA_DQ<17>")
	)
	(segment
		(start 296.821098 -217.936318)
		(end 296.65803 -217.77325)
		(width 0.14478)
		(layer "In2.Cu")
		(net "M_C_CPU0_SA_DQ<17>")
	)
	(segment
		(start 298.566586 -217.14714)
		(end 298.403518 -217.310208)
		(width 0.14478)
		(layer "In2.Cu")
		(net "M_C_CPU0_SA_DQ<17>")
	)
	(segment
		(start 341.212424 -235.901484)
		(end 341.204042 -235.896658)
		(width 0.0889)
		(layer "In2.Cu")
		(net "M_C_CPU0_SA_DQ<17>")
	)
	(segment
		(start 299.1231 -217.077798)
		(end 298.960032 -216.91473)
		(width 0.14478)
		(layer "In2.Cu")
		(net "M_C_CPU0_SA_DQ<17>")
	)
	(segment
		(start 297.276012 -218.160092)
		(end 296.984166 -218.160092)
		(width 0.14478)
		(layer "In2.Cu")
		(net "M_C_CPU0_SA_DQ<17>")
	)
	(segment
		(start 328.41819 -235.896658)
		(end 328.409808 -235.901484)
		(width 0.0889)
		(layer "In2.Cu")
		(net "M_C_CPU0_SA_DQ<17>")
	)
	(segment
		(start 340.63813 -235.896658)
		(end 340.629748 -235.901484)
		(width 0.0889)
		(layer "In2.Cu")
		(net "M_C_CPU0_SA_DQ<17>")
	)
	(segment
		(start 302.204882 -217.936318)
		(end 302.204882 -217.997024)
		(width 0.14478)
		(layer "In2.Cu")
		(net "M_C_CPU0_SA_DQ<17>")
	)
	(segment
		(start 343.425018 -235.839508)
		(end 343.402666 -235.92282)
		(width 0.0889)
		(layer "In2.Cu")
		(net "M_C_CPU0_SA_DQ<17>")
	)
	(segment
		(start 306.206398 -217.14714)
		(end 306.04333 -217.310208)
		(width 0.14478)
		(layer "In2.Cu")
		(net "M_C_CPU0_SA_DQ<17>")
	)
	(segment
		(start 293.79164 -217.77325)
		(end 293.561262 -217.77325)
		(width 0.14478)
		(layer "In2.Cu")
		(net "M_C_CPU0_SA_DQ<17>")
	)
	(segment
		(start 306.599844 -216.92235)
		(end 306.369466 -216.92235)
		(width 0.14478)
		(layer "In2.Cu")
		(net "M_C_CPU0_SA_DQ<17>")
	)
	(segment
		(start 335.938114 -235.896658)
		(end 335.929732 -235.901484)
		(width 0.0889)
		(layer "In2.Cu")
		(net "M_C_CPU0_SA_DQ<17>")
	)
	(segment
		(start 302.041814 -218.160092)
		(end 301.892716 -218.160092)
		(width 0.14478)
		(layer "In2.Cu")
		(net "M_C_CPU0_SA_DQ<17>")
	)
	(segment
		(start 294.67429 -217.77325)
		(end 294.511222 -217.936318)
		(width 0.14478)
		(layer "In2.Cu")
		(net "M_C_CPU0_SA_DQ<17>")
	)
	(segment
		(start 336.878168 -235.896658)
		(end 336.869786 -235.901484)
		(width 0.0889)
		(layer "In2.Cu")
		(net "M_C_CPU0_SA_DQ<17>")
	)
	(segment
		(start 298.960032 -216.91473)
		(end 298.729654 -216.91473)
		(width 0.14478)
		(layer "In2.Cu")
		(net "M_C_CPU0_SA_DQ<17>")
	)
	(segment
		(start 327.471024 -235.820458)
		(end 326.376538 -234.725972)
		(width 0.0889)
		(layer "In2.Cu")
		(net "M_C_CPU0_SA_DQ<17>")
	)
	(segment
		(start 292.705028 -218.160092)
		(end 292.280086 -217.73515)
		(width 0.14478)
		(layer "In2.Cu")
		(net "M_C_CPU0_SA_DQ<17>")
	)
	(segment
		(start 293.398194 -217.936318)
		(end 293.398194 -217.997024)
		(width 0.14478)
		(layer "In2.Cu")
		(net "M_C_CPU0_SA_DQ<17>")
	)
	(segment
		(start 337.452462 -235.901484)
		(end 337.44408 -235.896658)
		(width 0.0889)
		(layer "In2.Cu")
		(net "M_C_CPU0_SA_DQ<17>")
	)
	(segment
		(start 327.761092 -235.820458)
		(end 327.471024 -235.820458)
		(width 0.0889)
		(layer "In2.Cu")
		(net "M_C_CPU0_SA_DQ<17>")
	)
	(segment
		(start 339.698076 -235.896658)
		(end 339.689694 -235.901484)
		(width 0.0889)
		(layer "In2.Cu")
		(net "M_C_CPU0_SA_DQ<17>")
	)
	(segment
		(start 342.152478 -235.901484)
		(end 342.144096 -235.896658)
		(width 0.0889)
		(layer "In2.Cu")
		(net "M_C_CPU0_SA_DQ<17>")
	)
	(segment
		(start 295.230804 -218.160092)
		(end 295.067736 -217.997024)
		(width 0.14478)
		(layer "In2.Cu")
		(net "M_C_CPU0_SA_DQ<17>")
	)
	(segment
		(start 296.427652 -217.77325)
		(end 296.264584 -217.936318)
		(width 0.14478)
		(layer "In2.Cu")
		(net "M_C_CPU0_SA_DQ<17>")
	)
	(segment
		(start 302.924464 -218.160092)
		(end 302.761396 -217.997024)
		(width 0.14478)
		(layer "In2.Cu")
		(net "M_C_CPU0_SA_DQ<17>")
	)
	(segment
		(start 293.954708 -217.936318)
		(end 293.79164 -217.77325)
		(width 0.14478)
		(layer "In2.Cu")
		(net "M_C_CPU0_SA_DQ<17>")
	)
	(segment
		(start 306.762912 -217.14714)
		(end 306.762912 -217.085418)
		(width 0.14478)
		(layer "In2.Cu")
		(net "M_C_CPU0_SA_DQ<17>")
	)
	(segment
		(start 343.271094 -235.574078)
		(end 343.425018 -235.839508)
		(width 0.0889)
		(layer "In2.Cu")
		(net "M_C_CPU0_SA_DQ<17>")
	)
	(segment
		(start 306.206398 -217.085418)
		(end 306.206398 -217.14714)
		(width 0.14478)
		(layer "In2.Cu")
		(net "M_C_CPU0_SA_DQ<17>")
	)
	(segment
		(start 305.458876 -217.310208)
		(end 304.608992 -218.160092)
		(width 0.14478)
		(layer "In2.Cu")
		(net "M_C_CPU0_SA_DQ<17>")
	)
	(segment
		(start 313.598814 -221.473776)
		(end 313.598814 -220.20657)
		(width 0.14478)
		(layer "In2.Cu")
		(net "M_C_CPU0_SA_DQ<17>")
	)
	(segment
		(start 304.608992 -218.160092)
		(end 302.924464 -218.160092)
		(width 0.14478)
		(layer "In2.Cu")
		(net "M_C_CPU0_SA_DQ<17>")
	)
	(segment
		(start 301.892716 -218.160092)
		(end 301.042832 -217.310208)
		(width 0.14478)
		(layer "In2.Cu")
		(net "M_C_CPU0_SA_DQ<17>")
	)
	(segment
		(start 308.942994 -217.70467)
		(end 308.548532 -217.310208)
		(width 0.14478)
		(layer "In2.Cu")
		(net "M_C_CPU0_SA_DQ<17>")
	)
	(segment
		(start 302.761396 -217.997024)
		(end 302.761396 -217.936318)
		(width 0.14478)
		(layer "In2.Cu")
		(net "M_C_CPU0_SA_DQ<17>")
	)
	(segment
		(start 294.904668 -217.77325)
		(end 294.67429 -217.77325)
		(width 0.14478)
		(layer "In2.Cu")
		(net "M_C_CPU0_SA_DQ<17>")
	)
	(segment
		(start 325.219314 -233.86161)
		(end 324.693534 -233.86161)
		(width 0.0889)
		(layer "In2.Cu")
		(net "M_C_CPU0_SA_DQ<17>")
	)
	(segment
		(start 296.264584 -217.997024)
		(end 296.101516 -218.160092)
		(width 0.14478)
		(layer "In2.Cu")
		(net "M_C_CPU0_SA_DQ<17>")
	)
	(segment
		(start 293.398194 -217.997024)
		(end 293.235126 -218.160092)
		(width 0.14478)
		(layer "In2.Cu")
		(net "M_C_CPU0_SA_DQ<17>")
	)
	(segment
		(start 311.096914 -217.70467)
		(end 308.942994 -217.70467)
		(width 0.14478)
		(layer "In2.Cu")
		(net "M_C_CPU0_SA_DQ<17>")
	)
	(segment
		(start 302.761396 -217.936318)
		(end 302.598328 -217.77325)
		(width 0.14478)
		(layer "In2.Cu")
		(net "M_C_CPU0_SA_DQ<17>")
	)
	(segment
		(start 298.403518 -217.310208)
		(end 298.125896 -217.310208)
		(width 0.14478)
		(layer "In2.Cu")
		(net "M_C_CPU0_SA_DQ<17>")
	)
	(segment
		(start 306.04333 -217.310208)
		(end 305.458876 -217.310208)
		(width 0.14478)
		(layer "In2.Cu")
		(net "M_C_CPU0_SA_DQ<17>")
	)
	(segment
		(start 296.65803 -217.77325)
		(end 296.427652 -217.77325)
		(width 0.14478)
		(layer "In2.Cu")
		(net "M_C_CPU0_SA_DQ<17>")
	)
	(segment
		(start 306.92598 -217.310208)
		(end 306.762912 -217.14714)
		(width 0.14478)
		(layer "In2.Cu")
		(net "M_C_CPU0_SA_DQ<17>")
	)
	(segment
		(start 326.083676 -234.725972)
		(end 325.219314 -233.86161)
		(width 0.0889)
		(layer "In2.Cu")
		(net "M_C_CPU0_SA_DQ<17>")
	)
	(segment
		(start 298.125896 -217.310208)
		(end 297.276012 -218.160092)
		(width 0.14478)
		(layer "In2.Cu")
		(net "M_C_CPU0_SA_DQ<17>")
	)
	(segment
		(start 324.693534 -233.86161)
		(end 324.013576 -233.181652)
		(width 0.0889)
		(layer "In2.Cu")
		(net "M_C_CPU0_SA_DQ<17>")
	)
	(arc
		(start 335.563972 -235.896658)
		(mid 335.281016 -235.820481)
		(end 334.99806 -235.896658)
		(width 0.0889)
		(layer "In2.Cu")
		(net "M_C_CPU0_SA_DQ<17>")
	)
	(arc
		(start 331.229716 -235.901484)
		(mid 331.046208 -235.946978)
		(end 330.863956 -235.896658)
		(width 0.0889)
		(layer "In2.Cu")
		(net "M_C_CPU0_SA_DQ<17>")
	)
	(arc
		(start 340.629748 -235.901484)
		(mid 340.44624 -235.946978)
		(end 340.263988 -235.896658)
		(width 0.0889)
		(layer "In2.Cu")
		(net "M_C_CPU0_SA_DQ<17>")
	)
	(arc
		(start 341.204042 -235.896658)
		(mid 340.921086 -235.820481)
		(end 340.63813 -235.896658)
		(width 0.0889)
		(layer "In2.Cu")
		(net "M_C_CPU0_SA_DQ<17>")
	)
	(arc
		(start 333.118206 -235.896658)
		(mid 332.935955 -235.947008)
		(end 332.752446 -235.901484)
		(width 0.0889)
		(layer "In2.Cu")
		(net "M_C_CPU0_SA_DQ<17>")
	)
	(arc
		(start 340.263988 -235.896658)
		(mid 339.981032 -235.820481)
		(end 339.698076 -235.896658)
		(width 0.0889)
		(layer "In2.Cu")
		(net "M_C_CPU0_SA_DQ<17>")
	)
	(arc
		(start 343.402666 -235.92282)
		(mid 343.240477 -235.945555)
		(end 343.08415 -235.896658)
		(width 0.0889)
		(layer "In2.Cu")
		(net "M_C_CPU0_SA_DQ<17>")
	)
	(arc
		(start 332.16977 -235.901484)
		(mid 331.986262 -235.946978)
		(end 331.80401 -235.896658)
		(width 0.0889)
		(layer "In2.Cu")
		(net "M_C_CPU0_SA_DQ<17>")
	)
	(arc
		(start 337.818222 -235.896658)
		(mid 337.635971 -235.947008)
		(end 337.452462 -235.901484)
		(width 0.0889)
		(layer "In2.Cu")
		(net "M_C_CPU0_SA_DQ<17>")
	)
	(arc
		(start 334.99806 -235.896658)
		(mid 334.811116 -235.946913)
		(end 334.624172 -235.896658)
		(width 0.0889)
		(layer "In2.Cu")
		(net "M_C_CPU0_SA_DQ<17>")
	)
	(arc
		(start 339.689694 -235.901484)
		(mid 339.506186 -235.946978)
		(end 339.323934 -235.896658)
		(width 0.0889)
		(layer "In2.Cu")
		(net "M_C_CPU0_SA_DQ<17>")
	)
	(arc
		(start 342.144096 -235.896658)
		(mid 341.86114 -235.820481)
		(end 341.578184 -235.896658)
		(width 0.0889)
		(layer "In2.Cu")
		(net "M_C_CPU0_SA_DQ<17>")
	)
	(arc
		(start 335.929732 -235.901484)
		(mid 335.746224 -235.946978)
		(end 335.563972 -235.896658)
		(width 0.0889)
		(layer "In2.Cu")
		(net "M_C_CPU0_SA_DQ<17>")
	)
	(arc
		(start 341.578184 -235.896658)
		(mid 341.395933 -235.947008)
		(end 341.212424 -235.901484)
		(width 0.0889)
		(layer "In2.Cu")
		(net "M_C_CPU0_SA_DQ<17>")
	)
	(arc
		(start 329.358244 -235.896658)
		(mid 329.175993 -235.947008)
		(end 328.992484 -235.901484)
		(width 0.0889)
		(layer "In2.Cu")
		(net "M_C_CPU0_SA_DQ<17>")
	)
	(arc
		(start 343.08415 -235.896658)
		(mid 342.801194 -235.820481)
		(end 342.518238 -235.896658)
		(width 0.0889)
		(layer "In2.Cu")
		(net "M_C_CPU0_SA_DQ<17>")
	)
	(arc
		(start 336.869786 -235.901484)
		(mid 336.686278 -235.946978)
		(end 336.504026 -235.896658)
		(width 0.0889)
		(layer "In2.Cu")
		(net "M_C_CPU0_SA_DQ<17>")
	)
	(arc
		(start 339.323934 -235.896658)
		(mid 339.040978 -235.820481)
		(end 338.758022 -235.896658)
		(width 0.0889)
		(layer "In2.Cu")
		(net "M_C_CPU0_SA_DQ<17>")
	)
	(arc
		(start 334.624172 -235.896658)
		(mid 334.341216 -235.820481)
		(end 334.05826 -235.896658)
		(width 0.0889)
		(layer "In2.Cu")
		(net "M_C_CPU0_SA_DQ<17>")
	)
	(arc
		(start 330.863956 -235.896658)
		(mid 330.581 -235.820481)
		(end 330.298044 -235.896658)
		(width 0.0889)
		(layer "In2.Cu")
		(net "M_C_CPU0_SA_DQ<17>")
	)
	(arc
		(start 329.924156 -235.896658)
		(mid 329.6412 -235.820481)
		(end 329.358244 -235.896658)
		(width 0.0889)
		(layer "In2.Cu")
		(net "M_C_CPU0_SA_DQ<17>")
	)
	(arc
		(start 338.758022 -235.896658)
		(mid 338.571078 -235.946913)
		(end 338.384134 -235.896658)
		(width 0.0889)
		(layer "In2.Cu")
		(net "M_C_CPU0_SA_DQ<17>")
	)
	(arc
		(start 333.684118 -235.896658)
		(mid 333.401162 -235.820481)
		(end 333.118206 -235.896658)
		(width 0.0889)
		(layer "In2.Cu")
		(net "M_C_CPU0_SA_DQ<17>")
	)
	(arc
		(start 342.518238 -235.896658)
		(mid 342.335987 -235.947008)
		(end 342.152478 -235.901484)
		(width 0.0889)
		(layer "In2.Cu")
		(net "M_C_CPU0_SA_DQ<17>")
	)
	(arc
		(start 328.984102 -235.896658)
		(mid 328.701146 -235.820481)
		(end 328.41819 -235.896658)
		(width 0.0889)
		(layer "In2.Cu")
		(net "M_C_CPU0_SA_DQ<17>")
	)
	(arc
		(start 338.384134 -235.896658)
		(mid 338.101178 -235.820481)
		(end 337.818222 -235.896658)
		(width 0.0889)
		(layer "In2.Cu")
		(net "M_C_CPU0_SA_DQ<17>")
	)
	(arc
		(start 337.44408 -235.896658)
		(mid 337.161124 -235.820481)
		(end 336.878168 -235.896658)
		(width 0.0889)
		(layer "In2.Cu")
		(net "M_C_CPU0_SA_DQ<17>")
	)
	(arc
		(start 331.80401 -235.896658)
		(mid 331.521054 -235.820481)
		(end 331.238098 -235.896658)
		(width 0.0889)
		(layer "In2.Cu")
		(net "M_C_CPU0_SA_DQ<17>")
	)
	(arc
		(start 334.05826 -235.896658)
		(mid 333.876009 -235.947008)
		(end 333.6925 -235.901484)
		(width 0.0889)
		(layer "In2.Cu")
		(net "M_C_CPU0_SA_DQ<17>")
	)
	(arc
		(start 332.744064 -235.896658)
		(mid 332.461108 -235.820481)
		(end 332.178152 -235.896658)
		(width 0.0889)
		(layer "In2.Cu")
		(net "M_C_CPU0_SA_DQ<17>")
	)
	(arc
		(start 330.298044 -235.896658)
		(mid 330.1111 -235.946913)
		(end 329.924156 -235.896658)
		(width 0.0889)
		(layer "In2.Cu")
		(net "M_C_CPU0_SA_DQ<17>")
	)
	(arc
		(start 328.409808 -235.901484)
		(mid 328.2263 -235.946978)
		(end 328.044048 -235.896658)
		(width 0.0889)
		(layer "In2.Cu")
		(net "M_C_CPU0_SA_DQ<17>")
	)
	(arc
		(start 328.044048 -235.896658)
		(mid 327.907612 -235.839833)
		(end 327.761092 -235.820458)
		(width 0.0889)
		(layer "In2.Cu")
		(net "M_C_CPU0_SA_DQ<17>")
	)
	(arc
		(start 336.504026 -235.896658)
		(mid 336.22107 -235.820481)
		(end 335.938114 -235.896658)
		(width 0.0889)
		(layer "In2.Cu")
		(net "M_C_CPU0_SA_DQ<17>")
	)
	(segment
		(start 342.327992 -235.03001)
		(end 341.86114 -234.764072)
		(width 0.10668)
		(layer "F.Cu")
		(net "M_C_CPU0_SA_DQ<16>")
	)
	(segment
		(start 309.694072 -215.77173)
		(end 309.694072 -216.621868)
		(width 0.14478)
		(layer "In2.Cu")
		(net "M_C_CPU0_SA_DQ<16>")
	)
	(segment
		(start 305.740816 -215.610186)
		(end 308.356254 -215.610186)
		(width 0.14478)
		(layer "In2.Cu")
		(net "M_C_CPU0_SA_DQ<16>")
	)
	(segment
		(start 329.819762 -235.091478)
		(end 329.828144 -235.086652)
		(width 0.0889)
		(layer "In2.Cu")
		(net "M_C_CPU0_SA_DQ<16>")
	)
	(segment
		(start 338.854034 -235.086652)
		(end 338.862416 -235.091478)
		(width 0.0889)
		(layer "In2.Cu")
		(net "M_C_CPU0_SA_DQ<16>")
	)
	(segment
		(start 320.256154 -228.08057)
		(end 324.274434 -232.09885)
		(width 0.14478)
		(layer "In2.Cu")
		(net "M_C_CPU0_SA_DQ<16>")
	)
	(segment
		(start 294.451024 -216.83853)
		(end 294.614092 -216.675462)
		(width 0.14478)
		(layer "In2.Cu")
		(net "M_C_CPU0_SA_DQ<16>")
	)
	(segment
		(start 292.280086 -216.035128)
		(end 292.705028 -216.46007)
		(width 0.14478)
		(layer "In2.Cu")
		(net "M_C_CPU0_SA_DQ<16>")
	)
	(segment
		(start 293.337996 -216.83853)
		(end 293.501064 -216.675462)
		(width 0.14478)
		(layer "In2.Cu")
		(net "M_C_CPU0_SA_DQ<16>")
	)
	(segment
		(start 310.741568 -215.610186)
		(end 310.886348 -215.754966)
		(width 0.14478)
		(layer "In2.Cu")
		(net "M_C_CPU0_SA_DQ<16>")
	)
	(segment
		(start 301.042832 -215.610186)
		(end 301.892716 -216.46007)
		(width 0.14478)
		(layer "In2.Cu")
		(net "M_C_CPU0_SA_DQ<16>")
	)
	(segment
		(start 294.614092 -216.675462)
		(end 294.614092 -216.623138)
		(width 0.14478)
		(layer "In2.Cu")
		(net "M_C_CPU0_SA_DQ<16>")
	)
	(segment
		(start 298.217336 -215.610186)
		(end 301.042832 -215.610186)
		(width 0.14478)
		(layer "In2.Cu")
		(net "M_C_CPU0_SA_DQ<16>")
	)
	(segment
		(start 308.6481 -215.902032)
		(end 308.907688 -215.902032)
		(width 0.14478)
		(layer "In2.Cu")
		(net "M_C_CPU0_SA_DQ<16>")
	)
	(segment
		(start 309.694072 -216.621868)
		(end 309.855616 -216.783412)
		(width 0.14478)
		(layer "In2.Cu")
		(net "M_C_CPU0_SA_DQ<16>")
	)
	(segment
		(start 310.245506 -215.77173)
		(end 310.40705 -215.610186)
		(width 0.14478)
		(layer "In2.Cu")
		(net "M_C_CPU0_SA_DQ<16>")
	)
	(segment
		(start 301.892716 -216.46007)
		(end 304.890932 -216.46007)
		(width 0.14478)
		(layer "In2.Cu")
		(net "M_C_CPU0_SA_DQ<16>")
	)
	(segment
		(start 309.532528 -215.610186)
		(end 309.694072 -215.77173)
		(width 0.14478)
		(layer "In2.Cu")
		(net "M_C_CPU0_SA_DQ<16>")
	)
	(segment
		(start 327.939908 -235.091478)
		(end 327.94829 -235.086652)
		(width 0.0889)
		(layer "In2.Cu")
		(net "M_C_CPU0_SA_DQ<16>")
	)
	(segment
		(start 339.794088 -235.086652)
		(end 339.80247 -235.091478)
		(width 0.0889)
		(layer "In2.Cu")
		(net "M_C_CPU0_SA_DQ<16>")
	)
	(segment
		(start 294.057578 -216.324434)
		(end 294.057578 -216.675462)
		(width 0.14478)
		(layer "In2.Cu")
		(net "M_C_CPU0_SA_DQ<16>")
	)
	(segment
		(start 293.664132 -216.161366)
		(end 293.89451 -216.161366)
		(width 0.14478)
		(layer "In2.Cu")
		(net "M_C_CPU0_SA_DQ<16>")
	)
	(segment
		(start 293.107618 -216.83853)
		(end 293.337996 -216.83853)
		(width 0.14478)
		(layer "In2.Cu")
		(net "M_C_CPU0_SA_DQ<16>")
	)
	(segment
		(start 293.501064 -216.675462)
		(end 293.501064 -216.324434)
		(width 0.14478)
		(layer "In2.Cu")
		(net "M_C_CPU0_SA_DQ<16>")
	)
	(segment
		(start 326.783954 -233.87939)
		(end 326.783954 -234.314746)
		(width 0.0889)
		(layer "In2.Cu")
		(net "M_C_CPU0_SA_DQ<16>")
	)
	(segment
		(start 338.27974 -235.091478)
		(end 338.288122 -235.086652)
		(width 0.0889)
		(layer "In2.Cu")
		(net "M_C_CPU0_SA_DQ<16>")
	)
	(segment
		(start 330.394056 -235.086652)
		(end 330.402438 -235.091478)
		(width 0.0889)
		(layer "In2.Cu")
		(net "M_C_CPU0_SA_DQ<16>")
	)
	(segment
		(start 326.502014 -233.59745)
		(end 326.783954 -233.87939)
		(width 0.0889)
		(layer "In2.Cu")
		(net "M_C_CPU0_SA_DQ<16>")
	)
	(segment
		(start 342.015064 -235.029502)
		(end 341.86114 -234.764072)
		(width 0.0889)
		(layer "In2.Cu")
		(net "M_C_CPU0_SA_DQ<16>")
	)
	(segment
		(start 320.256154 -226.70389)
		(end 320.256154 -228.08057)
		(width 0.14478)
		(layer "In2.Cu")
		(net "M_C_CPU0_SA_DQ<16>")
	)
	(segment
		(start 297.367452 -216.46007)
		(end 298.217336 -215.610186)
		(width 0.14478)
		(layer "In2.Cu")
		(net "M_C_CPU0_SA_DQ<16>")
	)
	(segment
		(start 334.519778 -235.091478)
		(end 334.52816 -235.086652)
		(width 0.0889)
		(layer "In2.Cu")
		(net "M_C_CPU0_SA_DQ<16>")
	)
	(segment
		(start 293.501064 -216.324434)
		(end 293.664132 -216.161366)
		(width 0.14478)
		(layer "In2.Cu")
		(net "M_C_CPU0_SA_DQ<16>")
	)
	(segment
		(start 308.356254 -215.610186)
		(end 308.6481 -215.902032)
		(width 0.14478)
		(layer "In2.Cu")
		(net "M_C_CPU0_SA_DQ<16>")
	)
	(segment
		(start 310.886348 -215.754966)
		(end 310.886348 -216.207848)
		(width 0.14478)
		(layer "In2.Cu")
		(net "M_C_CPU0_SA_DQ<16>")
	)
	(segment
		(start 331.33411 -235.086652)
		(end 331.342492 -235.091478)
		(width 0.0889)
		(layer "In2.Cu")
		(net "M_C_CPU0_SA_DQ<16>")
	)
	(segment
		(start 292.705028 -216.46007)
		(end 292.781482 -216.46007)
		(width 0.14478)
		(layer "In2.Cu")
		(net "M_C_CPU0_SA_DQ<16>")
	)
	(segment
		(start 325.773034 -233.59745)
		(end 326.502014 -233.59745)
		(width 0.0889)
		(layer "In2.Cu")
		(net "M_C_CPU0_SA_DQ<16>")
	)
	(segment
		(start 336.034126 -235.086652)
		(end 336.042508 -235.091478)
		(width 0.0889)
		(layer "In2.Cu")
		(net "M_C_CPU0_SA_DQ<16>")
	)
	(segment
		(start 314.508134 -220.95587)
		(end 320.256154 -226.70389)
		(width 0.14478)
		(layer "In2.Cu")
		(net "M_C_CPU0_SA_DQ<16>")
	)
	(segment
		(start 293.89451 -216.161366)
		(end 294.057578 -216.324434)
		(width 0.14478)
		(layer "In2.Cu")
		(net "M_C_CPU0_SA_DQ<16>")
	)
	(segment
		(start 292.94455 -216.623138)
		(end 292.94455 -216.675462)
		(width 0.14478)
		(layer "In2.Cu")
		(net "M_C_CPU0_SA_DQ<16>")
	)
	(segment
		(start 292.94455 -216.675462)
		(end 293.107618 -216.83853)
		(width 0.14478)
		(layer "In2.Cu")
		(net "M_C_CPU0_SA_DQ<16>")
	)
	(segment
		(start 309.199534 -215.610186)
		(end 309.532528 -215.610186)
		(width 0.14478)
		(layer "In2.Cu")
		(net "M_C_CPU0_SA_DQ<16>")
	)
	(segment
		(start 294.77716 -216.46007)
		(end 297.367452 -216.46007)
		(width 0.14478)
		(layer "In2.Cu")
		(net "M_C_CPU0_SA_DQ<16>")
	)
	(segment
		(start 314.508134 -219.829634)
		(end 314.508134 -220.95587)
		(width 0.14478)
		(layer "In2.Cu")
		(net "M_C_CPU0_SA_DQ<16>")
	)
	(segment
		(start 294.057578 -216.675462)
		(end 294.220646 -216.83853)
		(width 0.14478)
		(layer "In2.Cu")
		(net "M_C_CPU0_SA_DQ<16>")
	)
	(segment
		(start 292.781482 -216.46007)
		(end 292.94455 -216.623138)
		(width 0.14478)
		(layer "In2.Cu")
		(net "M_C_CPU0_SA_DQ<16>")
	)
	(segment
		(start 324.274434 -232.09885)
		(end 325.773034 -233.59745)
		(width 0.0889)
		(layer "In2.Cu")
		(net "M_C_CPU0_SA_DQ<16>")
	)
	(segment
		(start 326.783954 -234.314746)
		(end 327.49744 -235.027978)
		(width 0.0889)
		(layer "In2.Cu")
		(net "M_C_CPU0_SA_DQ<16>")
	)
	(segment
		(start 310.40705 -215.610186)
		(end 310.741568 -215.610186)
		(width 0.14478)
		(layer "In2.Cu")
		(net "M_C_CPU0_SA_DQ<16>")
	)
	(segment
		(start 310.245506 -216.621868)
		(end 310.245506 -215.77173)
		(width 0.14478)
		(layer "In2.Cu")
		(net "M_C_CPU0_SA_DQ<16>")
	)
	(segment
		(start 308.907688 -215.902032)
		(end 309.199534 -215.610186)
		(width 0.14478)
		(layer "In2.Cu")
		(net "M_C_CPU0_SA_DQ<16>")
	)
	(segment
		(start 341.992712 -235.112814)
		(end 342.015064 -235.029502)
		(width 0.0889)
		(layer "In2.Cu")
		(net "M_C_CPU0_SA_DQ<16>")
	)
	(segment
		(start 304.890932 -216.46007)
		(end 305.740816 -215.610186)
		(width 0.14478)
		(layer "In2.Cu")
		(net "M_C_CPU0_SA_DQ<16>")
	)
	(segment
		(start 294.614092 -216.623138)
		(end 294.77716 -216.46007)
		(width 0.14478)
		(layer "In2.Cu")
		(net "M_C_CPU0_SA_DQ<16>")
	)
	(segment
		(start 333.579724 -235.091478)
		(end 333.588106 -235.086652)
		(width 0.0889)
		(layer "In2.Cu")
		(net "M_C_CPU0_SA_DQ<16>")
	)
	(segment
		(start 294.220646 -216.83853)
		(end 294.451024 -216.83853)
		(width 0.14478)
		(layer "In2.Cu")
		(net "M_C_CPU0_SA_DQ<16>")
	)
	(segment
		(start 310.886348 -216.207848)
		(end 314.508134 -219.829634)
		(width 0.14478)
		(layer "In2.Cu")
		(net "M_C_CPU0_SA_DQ<16>")
	)
	(segment
		(start 309.855616 -216.783412)
		(end 310.083962 -216.783412)
		(width 0.14478)
		(layer "In2.Cu")
		(net "M_C_CPU0_SA_DQ<16>")
	)
	(segment
		(start 335.094072 -235.086652)
		(end 335.102454 -235.091478)
		(width 0.0889)
		(layer "In2.Cu")
		(net "M_C_CPU0_SA_DQ<16>")
	)
	(segment
		(start 310.083962 -216.783412)
		(end 310.245506 -216.621868)
		(width 0.14478)
		(layer "In2.Cu")
		(net "M_C_CPU0_SA_DQ<16>")
	)
	(arc
		(start 341.673942 -235.086652)
		(mid 341.83038 -235.135623)
		(end 341.992712 -235.112814)
		(width 0.0889)
		(layer "In2.Cu")
		(net "M_C_CPU0_SA_DQ<16>")
	)
	(arc
		(start 337.91398 -235.086652)
		(mid 338.096231 -235.137002)
		(end 338.27974 -235.091478)
		(width 0.0889)
		(layer "In2.Cu")
		(net "M_C_CPU0_SA_DQ<16>")
	)
	(arc
		(start 337.348068 -235.086652)
		(mid 337.631024 -235.010475)
		(end 337.91398 -235.086652)
		(width 0.0889)
		(layer "In2.Cu")
		(net "M_C_CPU0_SA_DQ<16>")
	)
	(arc
		(start 338.862416 -235.091478)
		(mid 339.045924 -235.136972)
		(end 339.228176 -235.086652)
		(width 0.0889)
		(layer "In2.Cu")
		(net "M_C_CPU0_SA_DQ<16>")
	)
	(arc
		(start 334.154018 -235.086652)
		(mid 334.336269 -235.137002)
		(end 334.519778 -235.091478)
		(width 0.0889)
		(layer "In2.Cu")
		(net "M_C_CPU0_SA_DQ<16>")
	)
	(arc
		(start 335.102454 -235.091478)
		(mid 335.285962 -235.136972)
		(end 335.468214 -235.086652)
		(width 0.0889)
		(layer "In2.Cu")
		(net "M_C_CPU0_SA_DQ<16>")
	)
	(arc
		(start 332.648052 -235.086652)
		(mid 332.931008 -235.010475)
		(end 333.213964 -235.086652)
		(width 0.0889)
		(layer "In2.Cu")
		(net "M_C_CPU0_SA_DQ<16>")
	)
	(arc
		(start 338.288122 -235.086652)
		(mid 338.571078 -235.010475)
		(end 338.854034 -235.086652)
		(width 0.0889)
		(layer "In2.Cu")
		(net "M_C_CPU0_SA_DQ<16>")
	)
	(arc
		(start 339.228176 -235.086652)
		(mid 339.511132 -235.010475)
		(end 339.794088 -235.086652)
		(width 0.0889)
		(layer "In2.Cu")
		(net "M_C_CPU0_SA_DQ<16>")
	)
	(arc
		(start 339.80247 -235.091478)
		(mid 339.985978 -235.136972)
		(end 340.16823 -235.086652)
		(width 0.0889)
		(layer "In2.Cu")
		(net "M_C_CPU0_SA_DQ<16>")
	)
	(arc
		(start 340.16823 -235.086652)
		(mid 340.451186 -235.010475)
		(end 340.734142 -235.086652)
		(width 0.0889)
		(layer "In2.Cu")
		(net "M_C_CPU0_SA_DQ<16>")
	)
	(arc
		(start 341.10803 -235.086652)
		(mid 341.390986 -235.010475)
		(end 341.673942 -235.086652)
		(width 0.0889)
		(layer "In2.Cu")
		(net "M_C_CPU0_SA_DQ<16>")
	)
	(arc
		(start 333.213964 -235.086652)
		(mid 333.396215 -235.137002)
		(end 333.579724 -235.091478)
		(width 0.0889)
		(layer "In2.Cu")
		(net "M_C_CPU0_SA_DQ<16>")
	)
	(arc
		(start 334.52816 -235.086652)
		(mid 334.811116 -235.010475)
		(end 335.094072 -235.086652)
		(width 0.0889)
		(layer "In2.Cu")
		(net "M_C_CPU0_SA_DQ<16>")
	)
	(arc
		(start 328.514202 -235.086652)
		(mid 328.701146 -235.136907)
		(end 328.88809 -235.086652)
		(width 0.0889)
		(layer "In2.Cu")
		(net "M_C_CPU0_SA_DQ<16>")
	)
	(arc
		(start 327.49744 -235.027978)
		(mid 327.503968 -235.034282)
		(end 327.510648 -235.040424)
		(width 0.0889)
		(layer "In2.Cu")
		(net "M_C_CPU0_SA_DQ<16>")
	)
	(arc
		(start 330.402438 -235.091478)
		(mid 330.585946 -235.136972)
		(end 330.768198 -235.086652)
		(width 0.0889)
		(layer "In2.Cu")
		(net "M_C_CPU0_SA_DQ<16>")
	)
	(arc
		(start 333.588106 -235.086652)
		(mid 333.871062 -235.010475)
		(end 334.154018 -235.086652)
		(width 0.0889)
		(layer "In2.Cu")
		(net "M_C_CPU0_SA_DQ<16>")
	)
	(arc
		(start 336.408268 -235.086652)
		(mid 336.691224 -235.010475)
		(end 336.97418 -235.086652)
		(width 0.0889)
		(layer "In2.Cu")
		(net "M_C_CPU0_SA_DQ<16>")
	)
	(arc
		(start 336.97418 -235.086652)
		(mid 337.161124 -235.136907)
		(end 337.348068 -235.086652)
		(width 0.0889)
		(layer "In2.Cu")
		(net "M_C_CPU0_SA_DQ<16>")
	)
	(arc
		(start 327.94829 -235.086652)
		(mid 328.231246 -235.010475)
		(end 328.514202 -235.086652)
		(width 0.0889)
		(layer "In2.Cu")
		(net "M_C_CPU0_SA_DQ<16>")
	)
	(arc
		(start 331.342492 -235.091478)
		(mid 331.526 -235.136972)
		(end 331.708252 -235.086652)
		(width 0.0889)
		(layer "In2.Cu")
		(net "M_C_CPU0_SA_DQ<16>")
	)
	(arc
		(start 327.510648 -235.040424)
		(mid 327.540927 -235.065197)
		(end 327.57364 -235.086652)
		(width 0.0889)
		(layer "In2.Cu")
		(net "M_C_CPU0_SA_DQ<16>")
	)
	(arc
		(start 327.57364 -235.086652)
		(mid 327.756145 -235.137129)
		(end 327.939908 -235.091478)
		(width 0.0889)
		(layer "In2.Cu")
		(net "M_C_CPU0_SA_DQ<16>")
	)
	(arc
		(start 336.042508 -235.091478)
		(mid 336.226016 -235.136972)
		(end 336.408268 -235.086652)
		(width 0.0889)
		(layer "In2.Cu")
		(net "M_C_CPU0_SA_DQ<16>")
	)
	(arc
		(start 331.708252 -235.086652)
		(mid 331.991208 -235.010475)
		(end 332.274164 -235.086652)
		(width 0.0889)
		(layer "In2.Cu")
		(net "M_C_CPU0_SA_DQ<16>")
	)
	(arc
		(start 340.734142 -235.086652)
		(mid 340.921086 -235.136907)
		(end 341.10803 -235.086652)
		(width 0.0889)
		(layer "In2.Cu")
		(net "M_C_CPU0_SA_DQ<16>")
	)
	(arc
		(start 329.454002 -235.086652)
		(mid 329.636253 -235.137002)
		(end 329.819762 -235.091478)
		(width 0.0889)
		(layer "In2.Cu")
		(net "M_C_CPU0_SA_DQ<16>")
	)
	(arc
		(start 335.468214 -235.086652)
		(mid 335.75117 -235.010475)
		(end 336.034126 -235.086652)
		(width 0.0889)
		(layer "In2.Cu")
		(net "M_C_CPU0_SA_DQ<16>")
	)
	(arc
		(start 330.768198 -235.086652)
		(mid 331.051154 -235.010475)
		(end 331.33411 -235.086652)
		(width 0.0889)
		(layer "In2.Cu")
		(net "M_C_CPU0_SA_DQ<16>")
	)
	(arc
		(start 332.274164 -235.086652)
		(mid 332.461108 -235.136907)
		(end 332.648052 -235.086652)
		(width 0.0889)
		(layer "In2.Cu")
		(net "M_C_CPU0_SA_DQ<16>")
	)
	(arc
		(start 328.88809 -235.086652)
		(mid 329.171046 -235.010475)
		(end 329.454002 -235.086652)
		(width 0.0889)
		(layer "In2.Cu")
		(net "M_C_CPU0_SA_DQ<16>")
	)
	(arc
		(start 329.828144 -235.086652)
		(mid 330.1111 -235.010475)
		(end 330.394056 -235.086652)
		(width 0.0889)
		(layer "In2.Cu")
		(net "M_C_CPU0_SA_DQ<16>")
	)
	(segment
		(start 344.207846 -235.03001)
		(end 343.740994 -234.764072)
		(width 0.10668)
		(layer "F.Cu")
		(net "M_C_CPU0_SA_DQ<15>")
	)
	(segment
		(start 327.217024 -234.3912)
		(end 327.010014 -234.18419)
		(width 0.0889)
		(layer "In2.Cu")
		(net "M_C_CPU0_SA_DQ<15>")
	)
	(segment
		(start 327.761092 -234.3912)
		(end 327.217024 -234.3912)
		(width 0.0889)
		(layer "In2.Cu")
		(net "M_C_CPU0_SA_DQ<15>")
	)
	(segment
		(start 311.482994 -216.005156)
		(end 311.482994 -215.517476)
		(width 0.14478)
		(layer "In2.Cu")
		(net "M_C_CPU0_SA_DQ<15>")
	)
	(segment
		(start 343.58707 -234.498642)
		(end 343.491058 -234.473242)
		(width 0.0889)
		(layer "In2.Cu")
		(net "M_C_CPU0_SA_DQ<15>")
	)
	(segment
		(start 290.181284 -214.822532)
		(end 289.950906 -214.822532)
		(width 0.14478)
		(layer "In2.Cu")
		(net "M_C_CPU0_SA_DQ<15>")
	)
	(segment
		(start 289.950906 -214.822532)
		(end 289.787838 -214.9856)
		(width 0.14478)
		(layer "In2.Cu")
		(net "M_C_CPU0_SA_DQ<15>")
	)
	(segment
		(start 320.812414 -227.82149)
		(end 320.812414 -226.46259)
		(width 0.14478)
		(layer "In2.Cu")
		(net "M_C_CPU0_SA_DQ<15>")
	)
	(segment
		(start 290.344352 -215.447118)
		(end 290.344352 -214.9856)
		(width 0.14478)
		(layer "In2.Cu")
		(net "M_C_CPU0_SA_DQ<15>")
	)
	(segment
		(start 305.706526 -214.760048)
		(end 304.856388 -215.610186)
		(width 0.14478)
		(layer "In2.Cu")
		(net "M_C_CPU0_SA_DQ<15>")
	)
	(segment
		(start 311.482994 -215.517476)
		(end 310.725566 -214.760048)
		(width 0.14478)
		(layer "In2.Cu")
		(net "M_C_CPU0_SA_DQ<15>")
	)
	(segment
		(start 327.010014 -233.80319)
		(end 326.590914 -233.38409)
		(width 0.0889)
		(layer "In2.Cu")
		(net "M_C_CPU0_SA_DQ<15>")
	)
	(segment
		(start 297.368214 -215.610186)
		(end 290.50742 -215.610186)
		(width 0.14478)
		(layer "In2.Cu")
		(net "M_C_CPU0_SA_DQ<15>")
	)
	(segment
		(start 331.342492 -234.436666)
		(end 331.33411 -234.441492)
		(width 0.0889)
		(layer "In2.Cu")
		(net "M_C_CPU0_SA_DQ<15>")
	)
	(segment
		(start 338.288122 -234.441492)
		(end 338.27974 -234.436666)
		(width 0.0889)
		(layer "In2.Cu")
		(net "M_C_CPU0_SA_DQ<15>")
	)
	(segment
		(start 327.010014 -234.18419)
		(end 327.010014 -233.80319)
		(width 0.0889)
		(layer "In2.Cu")
		(net "M_C_CPU0_SA_DQ<15>")
	)
	(segment
		(start 342.048084 -234.441492)
		(end 342.039702 -234.436666)
		(width 0.0889)
		(layer "In2.Cu")
		(net "M_C_CPU0_SA_DQ<15>")
	)
	(segment
		(start 315.088016 -220.738192)
		(end 315.088016 -219.610178)
		(width 0.14478)
		(layer "In2.Cu")
		(net "M_C_CPU0_SA_DQ<15>")
	)
	(segment
		(start 339.80247 -234.436666)
		(end 339.794088 -234.441492)
		(width 0.0889)
		(layer "In2.Cu")
		(net "M_C_CPU0_SA_DQ<15>")
	)
	(segment
		(start 329.828144 -234.441492)
		(end 329.819762 -234.436666)
		(width 0.0889)
		(layer "In2.Cu")
		(net "M_C_CPU0_SA_DQ<15>")
	)
	(segment
		(start 338.862416 -234.436666)
		(end 338.854034 -234.441492)
		(width 0.0889)
		(layer "In2.Cu")
		(net "M_C_CPU0_SA_DQ<15>")
	)
	(segment
		(start 343.740994 -234.764072)
		(end 343.58707 -234.498642)
		(width 0.0889)
		(layer "In2.Cu")
		(net "M_C_CPU0_SA_DQ<15>")
	)
	(segment
		(start 336.042508 -234.436666)
		(end 336.034126 -234.441492)
		(width 0.0889)
		(layer "In2.Cu")
		(net "M_C_CPU0_SA_DQ<15>")
	)
	(segment
		(start 324.045834 -231.05491)
		(end 320.812414 -227.82149)
		(width 0.14478)
		(layer "In2.Cu")
		(net "M_C_CPU0_SA_DQ<15>")
	)
	(segment
		(start 330.402438 -234.436666)
		(end 330.394056 -234.441492)
		(width 0.0889)
		(layer "In2.Cu")
		(net "M_C_CPU0_SA_DQ<15>")
	)
	(segment
		(start 288.605214 -215.610186)
		(end 288.180018 -215.18499)
		(width 0.14478)
		(layer "In2.Cu")
		(net "M_C_CPU0_SA_DQ<15>")
	)
	(segment
		(start 289.787838 -215.447118)
		(end 289.62477 -215.610186)
		(width 0.14478)
		(layer "In2.Cu")
		(net "M_C_CPU0_SA_DQ<15>")
	)
	(segment
		(start 325.111364 -231.37876)
		(end 324.787514 -231.05491)
		(width 0.0889)
		(layer "In2.Cu")
		(net "M_C_CPU0_SA_DQ<15>")
	)
	(segment
		(start 333.588106 -234.441492)
		(end 333.579724 -234.436666)
		(width 0.0889)
		(layer "In2.Cu")
		(net "M_C_CPU0_SA_DQ<15>")
	)
	(segment
		(start 315.088016 -219.610178)
		(end 311.482994 -216.005156)
		(width 0.14478)
		(layer "In2.Cu")
		(net "M_C_CPU0_SA_DQ<15>")
	)
	(segment
		(start 289.787838 -214.9856)
		(end 289.787838 -215.447118)
		(width 0.14478)
		(layer "In2.Cu")
		(net "M_C_CPU0_SA_DQ<15>")
	)
	(segment
		(start 342.988138 -234.441492)
		(end 342.979756 -234.436666)
		(width 0.0889)
		(layer "In2.Cu")
		(net "M_C_CPU0_SA_DQ<15>")
	)
	(segment
		(start 334.52816 -234.441492)
		(end 334.519778 -234.436666)
		(width 0.0889)
		(layer "In2.Cu")
		(net "M_C_CPU0_SA_DQ<15>")
	)
	(segment
		(start 325.111364 -232.4735)
		(end 325.111364 -231.37876)
		(width 0.0889)
		(layer "In2.Cu")
		(net "M_C_CPU0_SA_DQ<15>")
	)
	(segment
		(start 324.787514 -231.05491)
		(end 324.132194 -231.05491)
		(width 0.0889)
		(layer "In2.Cu")
		(net "M_C_CPU0_SA_DQ<15>")
	)
	(segment
		(start 290.50742 -215.610186)
		(end 290.344352 -215.447118)
		(width 0.14478)
		(layer "In2.Cu")
		(net "M_C_CPU0_SA_DQ<15>")
	)
	(segment
		(start 290.344352 -214.9856)
		(end 290.181284 -214.822532)
		(width 0.14478)
		(layer "In2.Cu")
		(net "M_C_CPU0_SA_DQ<15>")
	)
	(segment
		(start 335.102454 -234.436666)
		(end 335.094072 -234.441492)
		(width 0.0889)
		(layer "In2.Cu")
		(net "M_C_CPU0_SA_DQ<15>")
	)
	(segment
		(start 298.218352 -214.760048)
		(end 297.368214 -215.610186)
		(width 0.14478)
		(layer "In2.Cu")
		(net "M_C_CPU0_SA_DQ<15>")
	)
	(segment
		(start 301.051722 -214.760048)
		(end 298.218352 -214.760048)
		(width 0.14478)
		(layer "In2.Cu")
		(net "M_C_CPU0_SA_DQ<15>")
	)
	(segment
		(start 320.812414 -226.46259)
		(end 315.088016 -220.738192)
		(width 0.14478)
		(layer "In2.Cu")
		(net "M_C_CPU0_SA_DQ<15>")
	)
	(segment
		(start 289.62477 -215.610186)
		(end 288.605214 -215.610186)
		(width 0.14478)
		(layer "In2.Cu")
		(net "M_C_CPU0_SA_DQ<15>")
	)
	(segment
		(start 326.590914 -233.38409)
		(end 326.021954 -233.38409)
		(width 0.0889)
		(layer "In2.Cu")
		(net "M_C_CPU0_SA_DQ<15>")
	)
	(segment
		(start 304.856388 -215.610186)
		(end 301.90186 -215.610186)
		(width 0.14478)
		(layer "In2.Cu")
		(net "M_C_CPU0_SA_DQ<15>")
	)
	(segment
		(start 310.725566 -214.760048)
		(end 305.706526 -214.760048)
		(width 0.14478)
		(layer "In2.Cu")
		(net "M_C_CPU0_SA_DQ<15>")
	)
	(segment
		(start 326.021954 -233.38409)
		(end 325.111364 -232.4735)
		(width 0.0889)
		(layer "In2.Cu")
		(net "M_C_CPU0_SA_DQ<15>")
	)
	(segment
		(start 301.90186 -215.610186)
		(end 301.051722 -214.760048)
		(width 0.14478)
		(layer "In2.Cu")
		(net "M_C_CPU0_SA_DQ<15>")
	)
	(segment
		(start 324.132194 -231.05491)
		(end 324.045834 -231.05491)
		(width 0.14478)
		(layer "In2.Cu")
		(net "M_C_CPU0_SA_DQ<15>")
	)
	(arc
		(start 342.039702 -234.436666)
		(mid 341.856194 -234.391172)
		(end 341.673942 -234.441492)
		(width 0.0889)
		(layer "In2.Cu")
		(net "M_C_CPU0_SA_DQ<15>")
	)
	(arc
		(start 333.213964 -234.441492)
		(mid 332.931008 -234.517669)
		(end 332.648052 -234.441492)
		(width 0.0889)
		(layer "In2.Cu")
		(net "M_C_CPU0_SA_DQ<15>")
	)
	(arc
		(start 341.673942 -234.441492)
		(mid 341.390986 -234.517669)
		(end 341.10803 -234.441492)
		(width 0.0889)
		(layer "In2.Cu")
		(net "M_C_CPU0_SA_DQ<15>")
	)
	(arc
		(start 342.979756 -234.436666)
		(mid 342.796248 -234.391172)
		(end 342.613996 -234.441492)
		(width 0.0889)
		(layer "In2.Cu")
		(net "M_C_CPU0_SA_DQ<15>")
	)
	(arc
		(start 328.514202 -234.441492)
		(mid 328.231246 -234.517669)
		(end 327.94829 -234.441492)
		(width 0.0889)
		(layer "In2.Cu")
		(net "M_C_CPU0_SA_DQ<15>")
	)
	(arc
		(start 336.034126 -234.441492)
		(mid 335.75117 -234.517669)
		(end 335.468214 -234.441492)
		(width 0.0889)
		(layer "In2.Cu")
		(net "M_C_CPU0_SA_DQ<15>")
	)
	(arc
		(start 332.274164 -234.441492)
		(mid 331.991208 -234.517669)
		(end 331.708252 -234.441492)
		(width 0.0889)
		(layer "In2.Cu")
		(net "M_C_CPU0_SA_DQ<15>")
	)
	(arc
		(start 331.33411 -234.441492)
		(mid 331.051154 -234.517669)
		(end 330.768198 -234.441492)
		(width 0.0889)
		(layer "In2.Cu")
		(net "M_C_CPU0_SA_DQ<15>")
	)
	(arc
		(start 329.819762 -234.436666)
		(mid 329.636254 -234.391172)
		(end 329.454002 -234.441492)
		(width 0.0889)
		(layer "In2.Cu")
		(net "M_C_CPU0_SA_DQ<15>")
	)
	(arc
		(start 327.94829 -234.441492)
		(mid 327.858014 -234.403987)
		(end 327.761092 -234.3912)
		(width 0.0889)
		(layer "In2.Cu")
		(net "M_C_CPU0_SA_DQ<15>")
	)
	(arc
		(start 332.648052 -234.441492)
		(mid 332.461108 -234.391237)
		(end 332.274164 -234.441492)
		(width 0.0889)
		(layer "In2.Cu")
		(net "M_C_CPU0_SA_DQ<15>")
	)
	(arc
		(start 339.794088 -234.441492)
		(mid 339.511132 -234.517669)
		(end 339.228176 -234.441492)
		(width 0.0889)
		(layer "In2.Cu")
		(net "M_C_CPU0_SA_DQ<15>")
	)
	(arc
		(start 337.348068 -234.441492)
		(mid 337.161124 -234.391237)
		(end 336.97418 -234.441492)
		(width 0.0889)
		(layer "In2.Cu")
		(net "M_C_CPU0_SA_DQ<15>")
	)
	(arc
		(start 337.91398 -234.441492)
		(mid 337.631024 -234.517669)
		(end 337.348068 -234.441492)
		(width 0.0889)
		(layer "In2.Cu")
		(net "M_C_CPU0_SA_DQ<15>")
	)
	(arc
		(start 340.734142 -234.441492)
		(mid 340.451186 -234.517669)
		(end 340.16823 -234.441492)
		(width 0.0889)
		(layer "In2.Cu")
		(net "M_C_CPU0_SA_DQ<15>")
	)
	(arc
		(start 330.394056 -234.441492)
		(mid 330.1111 -234.517669)
		(end 329.828144 -234.441492)
		(width 0.0889)
		(layer "In2.Cu")
		(net "M_C_CPU0_SA_DQ<15>")
	)
	(arc
		(start 335.468214 -234.441492)
		(mid 335.285963 -234.391142)
		(end 335.102454 -234.436666)
		(width 0.0889)
		(layer "In2.Cu")
		(net "M_C_CPU0_SA_DQ<15>")
	)
	(arc
		(start 338.27974 -234.436666)
		(mid 338.096232 -234.391172)
		(end 337.91398 -234.441492)
		(width 0.0889)
		(layer "In2.Cu")
		(net "M_C_CPU0_SA_DQ<15>")
	)
	(arc
		(start 334.154018 -234.441492)
		(mid 333.871062 -234.517669)
		(end 333.588106 -234.441492)
		(width 0.0889)
		(layer "In2.Cu")
		(net "M_C_CPU0_SA_DQ<15>")
	)
	(arc
		(start 331.708252 -234.441492)
		(mid 331.526001 -234.391142)
		(end 331.342492 -234.436666)
		(width 0.0889)
		(layer "In2.Cu")
		(net "M_C_CPU0_SA_DQ<15>")
	)
	(arc
		(start 338.854034 -234.441492)
		(mid 338.571078 -234.517669)
		(end 338.288122 -234.441492)
		(width 0.0889)
		(layer "In2.Cu")
		(net "M_C_CPU0_SA_DQ<15>")
	)
	(arc
		(start 328.88809 -234.441492)
		(mid 328.701146 -234.391237)
		(end 328.514202 -234.441492)
		(width 0.0889)
		(layer "In2.Cu")
		(net "M_C_CPU0_SA_DQ<15>")
	)
	(arc
		(start 336.408268 -234.441492)
		(mid 336.226017 -234.391142)
		(end 336.042508 -234.436666)
		(width 0.0889)
		(layer "In2.Cu")
		(net "M_C_CPU0_SA_DQ<15>")
	)
	(arc
		(start 339.228176 -234.441492)
		(mid 339.045925 -234.391142)
		(end 338.862416 -234.436666)
		(width 0.0889)
		(layer "In2.Cu")
		(net "M_C_CPU0_SA_DQ<15>")
	)
	(arc
		(start 329.454002 -234.441492)
		(mid 329.171046 -234.517669)
		(end 328.88809 -234.441492)
		(width 0.0889)
		(layer "In2.Cu")
		(net "M_C_CPU0_SA_DQ<15>")
	)
	(arc
		(start 333.579724 -234.436666)
		(mid 333.396216 -234.391172)
		(end 333.213964 -234.441492)
		(width 0.0889)
		(layer "In2.Cu")
		(net "M_C_CPU0_SA_DQ<15>")
	)
	(arc
		(start 342.613996 -234.441492)
		(mid 342.33104 -234.517669)
		(end 342.048084 -234.441492)
		(width 0.0889)
		(layer "In2.Cu")
		(net "M_C_CPU0_SA_DQ<15>")
	)
	(arc
		(start 334.519778 -234.436666)
		(mid 334.33627 -234.391172)
		(end 334.154018 -234.441492)
		(width 0.0889)
		(layer "In2.Cu")
		(net "M_C_CPU0_SA_DQ<15>")
	)
	(arc
		(start 340.16823 -234.441492)
		(mid 339.985979 -234.391142)
		(end 339.80247 -234.436666)
		(width 0.0889)
		(layer "In2.Cu")
		(net "M_C_CPU0_SA_DQ<15>")
	)
	(arc
		(start 330.768198 -234.441492)
		(mid 330.585947 -234.391142)
		(end 330.402438 -234.436666)
		(width 0.0889)
		(layer "In2.Cu")
		(net "M_C_CPU0_SA_DQ<15>")
	)
	(arc
		(start 341.10803 -234.441492)
		(mid 340.921086 -234.391237)
		(end 340.734142 -234.441492)
		(width 0.0889)
		(layer "In2.Cu")
		(net "M_C_CPU0_SA_DQ<15>")
	)
	(arc
		(start 335.094072 -234.441492)
		(mid 334.811116 -234.517669)
		(end 334.52816 -234.441492)
		(width 0.0889)
		(layer "In2.Cu")
		(net "M_C_CPU0_SA_DQ<15>")
	)
	(arc
		(start 336.97418 -234.441492)
		(mid 336.691224 -234.517669)
		(end 336.408268 -234.441492)
		(width 0.0889)
		(layer "In2.Cu")
		(net "M_C_CPU0_SA_DQ<15>")
	)
	(arc
		(start 343.491058 -234.473242)
		(mid 343.23585 -234.516719)
		(end 342.988138 -234.441492)
		(width 0.0889)
		(layer "In2.Cu")
		(net "M_C_CPU0_SA_DQ<15>")
	)
	(segment
		(start 342.797892 -234.220004)
		(end 342.33104 -233.954066)
		(width 0.10668)
		(layer "F.Cu")
		(net "M_C_CPU0_SA_DQ<14>")
	)
	(segment
		(start 321.726814 -227.34651)
		(end 321.726814 -226.065588)
		(width 0.14478)
		(layer "In2.Cu")
		(net "M_C_CPU0_SA_DQ<14>")
	)
	(segment
		(start 316.048644 -220.387418)
		(end 316.048644 -219.250006)
		(width 0.14478)
		(layer "In2.Cu")
		(net "M_C_CPU0_SA_DQ<14>")
	)
	(segment
		(start 326.733408 -232.92943)
		(end 326.415908 -232.92943)
		(width 0.0889)
		(layer "In2.Cu")
		(net "M_C_CPU0_SA_DQ<14>")
	)
	(segment
		(start 288.605214 -213.910164)
		(end 288.180018 -213.484968)
		(width 0.14478)
		(layer "In2.Cu")
		(net "M_C_CPU0_SA_DQ<14>")
	)
	(segment
		(start 324.78853 -229.331012)
		(end 324.423278 -229.331012)
		(width 0.0889)
		(layer "In2.Cu")
		(net "M_C_CPU0_SA_DQ<14>")
	)
	(segment
		(start 312.412634 -215.613996)
		(end 312.412634 -215.088216)
		(width 0.14478)
		(layer "In2.Cu")
		(net "M_C_CPU0_SA_DQ<14>")
	)
	(segment
		(start 325.579994 -230.122476)
		(end 324.78853 -229.331012)
		(width 0.0889)
		(layer "In2.Cu")
		(net "M_C_CPU0_SA_DQ<14>")
	)
	(segment
		(start 335.938114 -233.631486)
		(end 335.929732 -233.62666)
		(width 0.0889)
		(layer "In2.Cu")
		(net "M_C_CPU0_SA_DQ<14>")
	)
	(segment
		(start 308.443122 -213.060026)
		(end 305.929538 -213.060026)
		(width 0.14478)
		(layer "In2.Cu")
		(net "M_C_CPU0_SA_DQ<14>")
	)
	(segment
		(start 326.415908 -232.92943)
		(end 325.950834 -232.464356)
		(width 0.0889)
		(layer "In2.Cu")
		(net "M_C_CPU0_SA_DQ<14>")
	)
	(segment
		(start 328.992484 -233.62666)
		(end 328.984102 -233.631486)
		(width 0.0889)
		(layer "In2.Cu")
		(net "M_C_CPU0_SA_DQ<14>")
	)
	(segment
		(start 341.212424 -233.62666)
		(end 341.204042 -233.631486)
		(width 0.0889)
		(layer "In2.Cu")
		(net "M_C_CPU0_SA_DQ<14>")
	)
	(segment
		(start 291.032438 -213.910164)
		(end 290.86937 -213.747096)
		(width 0.14478)
		(layer "In2.Cu")
		(net "M_C_CPU0_SA_DQ<14>")
	)
	(segment
		(start 311.147968 -213.82355)
		(end 309.206646 -213.82355)
		(width 0.14478)
		(layer "In2.Cu")
		(net "M_C_CPU0_SA_DQ<14>")
	)
	(segment
		(start 332.752446 -233.62666)
		(end 332.744064 -233.631486)
		(width 0.0889)
		(layer "In2.Cu")
		(net "M_C_CPU0_SA_DQ<14>")
	)
	(segment
		(start 339.698076 -233.631486)
		(end 339.689694 -233.62666)
		(width 0.0889)
		(layer "In2.Cu")
		(net "M_C_CPU0_SA_DQ<14>")
	)
	(segment
		(start 298.431204 -213.060026)
		(end 297.581066 -213.910164)
		(width 0.14478)
		(layer "In2.Cu")
		(net "M_C_CPU0_SA_DQ<14>")
	)
	(segment
		(start 325.950834 -231.78135)
		(end 325.579994 -231.41051)
		(width 0.0889)
		(layer "In2.Cu")
		(net "M_C_CPU0_SA_DQ<14>")
	)
	(segment
		(start 336.878168 -233.631486)
		(end 336.869786 -233.62666)
		(width 0.0889)
		(layer "In2.Cu")
		(net "M_C_CPU0_SA_DQ<14>")
	)
	(segment
		(start 290.86937 -212.658198)
		(end 290.706302 -212.49513)
		(width 0.14478)
		(layer "In2.Cu")
		(net "M_C_CPU0_SA_DQ<14>")
	)
	(segment
		(start 297.581066 -213.910164)
		(end 291.032438 -213.910164)
		(width 0.14478)
		(layer "In2.Cu")
		(net "M_C_CPU0_SA_DQ<14>")
	)
	(segment
		(start 324.423278 -229.331012)
		(end 323.711316 -229.331012)
		(width 0.14478)
		(layer "In2.Cu")
		(net "M_C_CPU0_SA_DQ<14>")
	)
	(segment
		(start 342.177116 -233.688636)
		(end 342.081104 -233.663236)
		(width 0.0889)
		(layer "In2.Cu")
		(net "M_C_CPU0_SA_DQ<14>")
	)
	(segment
		(start 331.238098 -233.631486)
		(end 331.229716 -233.62666)
		(width 0.0889)
		(layer "In2.Cu")
		(net "M_C_CPU0_SA_DQ<14>")
	)
	(segment
		(start 290.86937 -213.747096)
		(end 290.86937 -212.658198)
		(width 0.14478)
		(layer "In2.Cu")
		(net "M_C_CPU0_SA_DQ<14>")
	)
	(segment
		(start 290.475924 -212.49513)
		(end 290.312856 -212.658198)
		(width 0.14478)
		(layer "In2.Cu")
		(net "M_C_CPU0_SA_DQ<14>")
	)
	(segment
		(start 337.452462 -233.62666)
		(end 337.44408 -233.631486)
		(width 0.0889)
		(layer "In2.Cu")
		(net "M_C_CPU0_SA_DQ<14>")
	)
	(segment
		(start 312.412634 -215.088216)
		(end 311.147968 -213.82355)
		(width 0.14478)
		(layer "In2.Cu")
		(net "M_C_CPU0_SA_DQ<14>")
	)
	(segment
		(start 309.206646 -213.82355)
		(end 308.443122 -213.060026)
		(width 0.14478)
		(layer "In2.Cu")
		(net "M_C_CPU0_SA_DQ<14>")
	)
	(segment
		(start 290.312856 -213.747096)
		(end 290.149788 -213.910164)
		(width 0.14478)
		(layer "In2.Cu")
		(net "M_C_CPU0_SA_DQ<14>")
	)
	(segment
		(start 290.149788 -213.910164)
		(end 288.605214 -213.910164)
		(width 0.14478)
		(layer "In2.Cu")
		(net "M_C_CPU0_SA_DQ<14>")
	)
	(segment
		(start 327.569576 -233.674158)
		(end 327.52792 -233.659172)
		(width 0.0889)
		(layer "In2.Cu")
		(net "M_C_CPU0_SA_DQ<14>")
	)
	(segment
		(start 305.0794 -213.910164)
		(end 301.90186 -213.910164)
		(width 0.14478)
		(layer "In2.Cu")
		(net "M_C_CPU0_SA_DQ<14>")
	)
	(segment
		(start 316.048644 -219.250006)
		(end 312.412634 -215.613996)
		(width 0.14478)
		(layer "In2.Cu")
		(net "M_C_CPU0_SA_DQ<14>")
	)
	(segment
		(start 290.706302 -212.49513)
		(end 290.475924 -212.49513)
		(width 0.14478)
		(layer "In2.Cu")
		(net "M_C_CPU0_SA_DQ<14>")
	)
	(segment
		(start 305.929538 -213.060026)
		(end 305.0794 -213.910164)
		(width 0.14478)
		(layer "In2.Cu")
		(net "M_C_CPU0_SA_DQ<14>")
	)
	(segment
		(start 321.726814 -226.065588)
		(end 316.048644 -220.387418)
		(width 0.14478)
		(layer "In2.Cu")
		(net "M_C_CPU0_SA_DQ<14>")
	)
	(segment
		(start 325.579994 -231.41051)
		(end 325.579994 -230.122476)
		(width 0.0889)
		(layer "In2.Cu")
		(net "M_C_CPU0_SA_DQ<14>")
	)
	(segment
		(start 332.178152 -233.631486)
		(end 332.16977 -233.62666)
		(width 0.0889)
		(layer "In2.Cu")
		(net "M_C_CPU0_SA_DQ<14>")
	)
	(segment
		(start 301.90186 -213.910164)
		(end 301.051722 -213.060026)
		(width 0.14478)
		(layer "In2.Cu")
		(net "M_C_CPU0_SA_DQ<14>")
	)
	(segment
		(start 301.051722 -213.060026)
		(end 298.431204 -213.060026)
		(width 0.14478)
		(layer "In2.Cu")
		(net "M_C_CPU0_SA_DQ<14>")
	)
	(segment
		(start 342.33104 -233.954066)
		(end 342.177116 -233.688636)
		(width 0.0889)
		(layer "In2.Cu")
		(net "M_C_CPU0_SA_DQ<14>")
	)
	(segment
		(start 333.6925 -233.62666)
		(end 333.684118 -233.631486)
		(width 0.0889)
		(layer "In2.Cu")
		(net "M_C_CPU0_SA_DQ<14>")
	)
	(segment
		(start 290.312856 -212.658198)
		(end 290.312856 -213.747096)
		(width 0.14478)
		(layer "In2.Cu")
		(net "M_C_CPU0_SA_DQ<14>")
	)
	(segment
		(start 328.41819 -233.631486)
		(end 328.409808 -233.62666)
		(width 0.0889)
		(layer "In2.Cu")
		(net "M_C_CPU0_SA_DQ<14>")
	)
	(segment
		(start 323.711316 -229.331012)
		(end 321.726814 -227.34651)
		(width 0.14478)
		(layer "In2.Cu")
		(net "M_C_CPU0_SA_DQ<14>")
	)
	(segment
		(start 340.63813 -233.631486)
		(end 340.629748 -233.62666)
		(width 0.0889)
		(layer "In2.Cu")
		(net "M_C_CPU0_SA_DQ<14>")
	)
	(segment
		(start 327.35012 -233.546142)
		(end 326.733408 -232.92943)
		(width 0.0889)
		(layer "In2.Cu")
		(net "M_C_CPU0_SA_DQ<14>")
	)
	(segment
		(start 325.950834 -232.464356)
		(end 325.950834 -231.78135)
		(width 0.0889)
		(layer "In2.Cu")
		(net "M_C_CPU0_SA_DQ<14>")
	)
	(arc
		(start 336.869786 -233.62666)
		(mid 336.686278 -233.581166)
		(end 336.504026 -233.631486)
		(width 0.0889)
		(layer "In2.Cu")
		(net "M_C_CPU0_SA_DQ<14>")
	)
	(arc
		(start 328.984102 -233.631486)
		(mid 328.701146 -233.707663)
		(end 328.41819 -233.631486)
		(width 0.0889)
		(layer "In2.Cu")
		(net "M_C_CPU0_SA_DQ<14>")
	)
	(arc
		(start 338.384134 -233.631486)
		(mid 338.101178 -233.707663)
		(end 337.818222 -233.631486)
		(width 0.0889)
		(layer "In2.Cu")
		(net "M_C_CPU0_SA_DQ<14>")
	)
	(arc
		(start 332.16977 -233.62666)
		(mid 331.986262 -233.581166)
		(end 331.80401 -233.631486)
		(width 0.0889)
		(layer "In2.Cu")
		(net "M_C_CPU0_SA_DQ<14>")
	)
	(arc
		(start 341.204042 -233.631486)
		(mid 340.921086 -233.707663)
		(end 340.63813 -233.631486)
		(width 0.0889)
		(layer "In2.Cu")
		(net "M_C_CPU0_SA_DQ<14>")
	)
	(arc
		(start 335.563972 -233.631486)
		(mid 335.281016 -233.707663)
		(end 334.99806 -233.631486)
		(width 0.0889)
		(layer "In2.Cu")
		(net "M_C_CPU0_SA_DQ<14>")
	)
	(arc
		(start 340.263988 -233.631486)
		(mid 339.981032 -233.707663)
		(end 339.698076 -233.631486)
		(width 0.0889)
		(layer "In2.Cu")
		(net "M_C_CPU0_SA_DQ<14>")
	)
	(arc
		(start 329.924156 -233.631486)
		(mid 329.6412 -233.707663)
		(end 329.358244 -233.631486)
		(width 0.0889)
		(layer "In2.Cu")
		(net "M_C_CPU0_SA_DQ<14>")
	)
	(arc
		(start 328.409808 -233.62666)
		(mid 328.2263 -233.581166)
		(end 328.044048 -233.631486)
		(width 0.0889)
		(layer "In2.Cu")
		(net "M_C_CPU0_SA_DQ<14>")
	)
	(arc
		(start 334.624172 -233.631486)
		(mid 334.341216 -233.707663)
		(end 334.05826 -233.631486)
		(width 0.0889)
		(layer "In2.Cu")
		(net "M_C_CPU0_SA_DQ<14>")
	)
	(arc
		(start 342.081104 -233.663236)
		(mid 341.825896 -233.706713)
		(end 341.578184 -233.631486)
		(width 0.0889)
		(layer "In2.Cu")
		(net "M_C_CPU0_SA_DQ<14>")
	)
	(arc
		(start 339.689694 -233.62666)
		(mid 339.506186 -233.581166)
		(end 339.323934 -233.631486)
		(width 0.0889)
		(layer "In2.Cu")
		(net "M_C_CPU0_SA_DQ<14>")
	)
	(arc
		(start 332.744064 -233.631486)
		(mid 332.461108 -233.707663)
		(end 332.178152 -233.631486)
		(width 0.0889)
		(layer "In2.Cu")
		(net "M_C_CPU0_SA_DQ<14>")
	)
	(arc
		(start 341.578184 -233.631486)
		(mid 341.395933 -233.581136)
		(end 341.212424 -233.62666)
		(width 0.0889)
		(layer "In2.Cu")
		(net "M_C_CPU0_SA_DQ<14>")
	)
	(arc
		(start 337.818222 -233.631486)
		(mid 337.635971 -233.581136)
		(end 337.452462 -233.62666)
		(width 0.0889)
		(layer "In2.Cu")
		(net "M_C_CPU0_SA_DQ<14>")
	)
	(arc
		(start 336.504026 -233.631486)
		(mid 336.22107 -233.707663)
		(end 335.938114 -233.631486)
		(width 0.0889)
		(layer "In2.Cu")
		(net "M_C_CPU0_SA_DQ<14>")
	)
	(arc
		(start 334.99806 -233.631486)
		(mid 334.811116 -233.581231)
		(end 334.624172 -233.631486)
		(width 0.0889)
		(layer "In2.Cu")
		(net "M_C_CPU0_SA_DQ<14>")
	)
	(arc
		(start 333.684118 -233.631486)
		(mid 333.401162 -233.707663)
		(end 333.118206 -233.631486)
		(width 0.0889)
		(layer "In2.Cu")
		(net "M_C_CPU0_SA_DQ<14>")
	)
	(arc
		(start 330.298044 -233.631486)
		(mid 330.1111 -233.581231)
		(end 329.924156 -233.631486)
		(width 0.0889)
		(layer "In2.Cu")
		(net "M_C_CPU0_SA_DQ<14>")
	)
	(arc
		(start 327.52792 -233.659172)
		(mid 327.432803 -233.612439)
		(end 327.35012 -233.546142)
		(width 0.0889)
		(layer "In2.Cu")
		(net "M_C_CPU0_SA_DQ<14>")
	)
	(arc
		(start 331.229716 -233.62666)
		(mid 331.046208 -233.581166)
		(end 330.863956 -233.631486)
		(width 0.0889)
		(layer "In2.Cu")
		(net "M_C_CPU0_SA_DQ<14>")
	)
	(arc
		(start 337.44408 -233.631486)
		(mid 337.161124 -233.707663)
		(end 336.878168 -233.631486)
		(width 0.0889)
		(layer "In2.Cu")
		(net "M_C_CPU0_SA_DQ<14>")
	)
	(arc
		(start 331.80401 -233.631486)
		(mid 331.521054 -233.707663)
		(end 331.238098 -233.631486)
		(width 0.0889)
		(layer "In2.Cu")
		(net "M_C_CPU0_SA_DQ<14>")
	)
	(arc
		(start 333.118206 -233.631486)
		(mid 332.935955 -233.581136)
		(end 332.752446 -233.62666)
		(width 0.0889)
		(layer "In2.Cu")
		(net "M_C_CPU0_SA_DQ<14>")
	)
	(arc
		(start 335.929732 -233.62666)
		(mid 335.746224 -233.581166)
		(end 335.563972 -233.631486)
		(width 0.0889)
		(layer "In2.Cu")
		(net "M_C_CPU0_SA_DQ<14>")
	)
	(arc
		(start 330.863956 -233.631486)
		(mid 330.581 -233.707663)
		(end 330.298044 -233.631486)
		(width 0.0889)
		(layer "In2.Cu")
		(net "M_C_CPU0_SA_DQ<14>")
	)
	(arc
		(start 328.044048 -233.631486)
		(mid 327.811544 -233.7054)
		(end 327.569576 -233.674158)
		(width 0.0889)
		(layer "In2.Cu")
		(net "M_C_CPU0_SA_DQ<14>")
	)
	(arc
		(start 329.358244 -233.631486)
		(mid 329.175993 -233.581136)
		(end 328.992484 -233.62666)
		(width 0.0889)
		(layer "In2.Cu")
		(net "M_C_CPU0_SA_DQ<14>")
	)
	(arc
		(start 340.629748 -233.62666)
		(mid 340.44624 -233.581166)
		(end 340.263988 -233.631486)
		(width 0.0889)
		(layer "In2.Cu")
		(net "M_C_CPU0_SA_DQ<14>")
	)
	(arc
		(start 334.05826 -233.631486)
		(mid 333.876009 -233.581136)
		(end 333.6925 -233.62666)
		(width 0.0889)
		(layer "In2.Cu")
		(net "M_C_CPU0_SA_DQ<14>")
	)
	(arc
		(start 338.758022 -233.631486)
		(mid 338.571078 -233.581231)
		(end 338.384134 -233.631486)
		(width 0.0889)
		(layer "In2.Cu")
		(net "M_C_CPU0_SA_DQ<14>")
	)
	(arc
		(start 339.323934 -233.631486)
		(mid 339.040978 -233.707663)
		(end 338.758022 -233.631486)
		(width 0.0889)
		(layer "In2.Cu")
		(net "M_C_CPU0_SA_DQ<14>")
	)
	(segment
		(start 343.737946 -234.220004)
		(end 343.271094 -233.954066)
		(width 0.10668)
		(layer "F.Cu")
		(net "M_C_CPU0_SA_DQ<13>")
	)
	(segment
		(start 305.740816 -213.910164)
		(end 304.890932 -214.760048)
		(width 0.14478)
		(layer "In2.Cu")
		(net "M_C_CPU0_SA_DQ<13>")
	)
	(segment
		(start 332.178152 -234.276646)
		(end 332.16977 -234.281472)
		(width 0.0889)
		(layer "In2.Cu")
		(net "M_C_CPU0_SA_DQ<13>")
	)
	(segment
		(start 304.890932 -214.760048)
		(end 304.559716 -214.760048)
		(width 0.14478)
		(layer "In2.Cu")
		(net "M_C_CPU0_SA_DQ<13>")
	)
	(segment
		(start 327.251314 -233.73715)
		(end 326.664574 -233.15041)
		(width 0.0889)
		(layer "In2.Cu")
		(net "M_C_CPU0_SA_DQ<13>")
	)
	(segment
		(start 299.186854 -213.51621)
		(end 298.956476 -213.51621)
		(width 0.14478)
		(layer "In2.Cu")
		(net "M_C_CPU0_SA_DQ<13>")
	)
	(segment
		(start 300.317408 -213.691978)
		(end 300.317408 -213.747096)
		(width 0.14478)
		(layer "In2.Cu")
		(net "M_C_CPU0_SA_DQ<13>")
	)
	(segment
		(start 307.877464 -213.747096)
		(end 307.714396 -213.910164)
		(width 0.14478)
		(layer "In2.Cu")
		(net "M_C_CPU0_SA_DQ<13>")
	)
	(segment
		(start 328.992484 -234.281472)
		(end 328.984102 -234.276646)
		(width 0.0889)
		(layer "In2.Cu")
		(net "M_C_CPU0_SA_DQ<13>")
	)
	(segment
		(start 306.612544 -213.52383)
		(end 306.382166 -213.52383)
		(width 0.14478)
		(layer "In2.Cu")
		(net "M_C_CPU0_SA_DQ<13>")
	)
	(segment
		(start 306.93868 -213.910164)
		(end 306.775612 -213.747096)
		(width 0.14478)
		(layer "In2.Cu")
		(net "M_C_CPU0_SA_DQ<13>")
	)
	(segment
		(start 303.840134 -214.532718)
		(end 303.840134 -214.59698)
		(width 0.14478)
		(layer "In2.Cu")
		(net "M_C_CPU0_SA_DQ<13>")
	)
	(segment
		(start 302.281844 -214.59698)
		(end 302.118776 -214.760048)
		(width 0.14478)
		(layer "In2.Cu")
		(net "M_C_CPU0_SA_DQ<13>")
	)
	(segment
		(start 325.640954 -232.589324)
		(end 325.640954 -232.00233)
		(width 0.0889)
		(layer "In2.Cu")
		(net "M_C_CPU0_SA_DQ<13>")
	)
	(segment
		(start 298.793408 -213.747096)
		(end 298.63034 -213.910164)
		(width 0.14478)
		(layer "In2.Cu")
		(net "M_C_CPU0_SA_DQ<13>")
	)
	(segment
		(start 300.317408 -213.747096)
		(end 300.15434 -213.910164)
		(width 0.14478)
		(layer "In2.Cu")
		(net "M_C_CPU0_SA_DQ<13>")
	)
	(segment
		(start 296.891456 -214.537798)
		(end 296.728388 -214.37473)
		(width 0.14478)
		(layer "In2.Cu")
		(net "M_C_CPU0_SA_DQ<13>")
	)
	(segment
		(start 331.238098 -234.276646)
		(end 331.229716 -234.281472)
		(width 0.0889)
		(layer "In2.Cu")
		(net "M_C_CPU0_SA_DQ<13>")
	)
	(segment
		(start 300.15434 -213.910164)
		(end 299.51299 -213.910164)
		(width 0.14478)
		(layer "In2.Cu")
		(net "M_C_CPU0_SA_DQ<13>")
	)
	(segment
		(start 296.171874 -214.760048)
		(end 295.286938 -214.760048)
		(width 0.14478)
		(layer "In2.Cu")
		(net "M_C_CPU0_SA_DQ<13>")
	)
	(segment
		(start 308.433978 -213.747096)
		(end 308.433978 -213.686898)
		(width 0.14478)
		(layer "In2.Cu")
		(net "M_C_CPU0_SA_DQ<13>")
	)
	(segment
		(start 294.567356 -214.532718)
		(end 294.567356 -214.997538)
		(width 0.14478)
		(layer "In2.Cu")
		(net "M_C_CPU0_SA_DQ<13>")
	)
	(segment
		(start 301.892716 -214.760048)
		(end 301.042832 -213.910164)
		(width 0.14478)
		(layer "In2.Cu")
		(net "M_C_CPU0_SA_DQ<13>")
	)
	(segment
		(start 302.118776 -214.760048)
		(end 301.892716 -214.760048)
		(width 0.14478)
		(layer "In2.Cu")
		(net "M_C_CPU0_SA_DQ<13>")
	)
	(segment
		(start 343.271094 -233.954066)
		(end 343.425018 -234.219496)
		(width 0.0889)
		(layer "In2.Cu")
		(net "M_C_CPU0_SA_DQ<13>")
	)
	(segment
		(start 303.677066 -214.760048)
		(end 303.001426 -214.760048)
		(width 0.14478)
		(layer "In2.Cu")
		(net "M_C_CPU0_SA_DQ<13>")
	)
	(segment
		(start 321.272154 -226.254056)
		(end 315.578236 -220.560138)
		(width 0.14478)
		(layer "In2.Cu")
		(net "M_C_CPU0_SA_DQ<13>")
	)
	(segment
		(start 310.957468 -214.29853)
		(end 308.985412 -214.29853)
		(width 0.14478)
		(layer "In2.Cu")
		(net "M_C_CPU0_SA_DQ<13>")
	)
	(segment
		(start 296.891456 -214.59698)
		(end 296.891456 -214.537798)
		(width 0.14478)
		(layer "In2.Cu")
		(net "M_C_CPU0_SA_DQ<13>")
	)
	(segment
		(start 308.433978 -213.686898)
		(end 308.27091 -213.52383)
		(width 0.14478)
		(layer "In2.Cu")
		(net "M_C_CPU0_SA_DQ<13>")
	)
	(segment
		(start 298.956476 -213.51621)
		(end 298.793408 -213.679278)
		(width 0.14478)
		(layer "In2.Cu")
		(net "M_C_CPU0_SA_DQ<13>")
	)
	(segment
		(start 300.873922 -213.747096)
		(end 300.873922 -213.691978)
		(width 0.14478)
		(layer "In2.Cu")
		(net "M_C_CPU0_SA_DQ<13>")
	)
	(segment
		(start 294.17391 -215.160606)
		(end 294.010842 -214.997538)
		(width 0.14478)
		(layer "In2.Cu")
		(net "M_C_CPU0_SA_DQ<13>")
	)
	(segment
		(start 304.003202 -214.36965)
		(end 303.840134 -214.532718)
		(width 0.14478)
		(layer "In2.Cu")
		(net "M_C_CPU0_SA_DQ<13>")
	)
	(segment
		(start 311.945274 -215.286336)
		(end 310.957468 -214.29853)
		(width 0.14478)
		(layer "In2.Cu")
		(net "M_C_CPU0_SA_DQ<13>")
	)
	(segment
		(start 300.873922 -213.691978)
		(end 300.710854 -213.52891)
		(width 0.14478)
		(layer "In2.Cu")
		(net "M_C_CPU0_SA_DQ<13>")
	)
	(segment
		(start 293.617396 -214.36965)
		(end 293.454328 -214.532718)
		(width 0.14478)
		(layer "In2.Cu")
		(net "M_C_CPU0_SA_DQ<13>")
	)
	(segment
		(start 324.179184 -230.45928)
		(end 321.272154 -227.55225)
		(width 0.14478)
		(layer "In2.Cu")
		(net "M_C_CPU0_SA_DQ<13>")
	)
	(segment
		(start 303.001426 -214.760048)
		(end 302.838358 -214.59698)
		(width 0.14478)
		(layer "In2.Cu")
		(net "M_C_CPU0_SA_DQ<13>")
	)
	(segment
		(start 297.367452 -214.760048)
		(end 297.054524 -214.760048)
		(width 0.14478)
		(layer "In2.Cu")
		(net "M_C_CPU0_SA_DQ<13>")
	)
	(segment
		(start 311.945274 -215.799416)
		(end 311.945274 -215.286336)
		(width 0.14478)
		(layer "In2.Cu")
		(net "M_C_CPU0_SA_DQ<13>")
	)
	(segment
		(start 296.728388 -214.37473)
		(end 296.49801 -214.37473)
		(width 0.14478)
		(layer "In2.Cu")
		(net "M_C_CPU0_SA_DQ<13>")
	)
	(segment
		(start 293.454328 -214.532718)
		(end 293.454328 -214.988902)
		(width 0.14478)
		(layer "In2.Cu")
		(net "M_C_CPU0_SA_DQ<13>")
	)
	(segment
		(start 292.735254 -215.00211)
		(end 292.735254 -214.790274)
		(width 0.14478)
		(layer "In2.Cu")
		(net "M_C_CPU0_SA_DQ<13>")
	)
	(segment
		(start 295.12387 -214.532718)
		(end 294.960802 -214.36965)
		(width 0.14478)
		(layer "In2.Cu")
		(net "M_C_CPU0_SA_DQ<13>")
	)
	(segment
		(start 299.349922 -213.747096)
		(end 299.349922 -213.679278)
		(width 0.14478)
		(layer "In2.Cu")
		(net "M_C_CPU0_SA_DQ<13>")
	)
	(segment
		(start 325.640954 -232.00233)
		(end 325.359014 -231.72039)
		(width 0.0889)
		(layer "In2.Cu")
		(net "M_C_CPU0_SA_DQ<13>")
	)
	(segment
		(start 340.63813 -234.276646)
		(end 340.629748 -234.281472)
		(width 0.0889)
		(layer "In2.Cu")
		(net "M_C_CPU0_SA_DQ<13>")
	)
	(segment
		(start 294.960802 -214.36965)
		(end 294.730424 -214.36965)
		(width 0.14478)
		(layer "In2.Cu")
		(net "M_C_CPU0_SA_DQ<13>")
	)
	(segment
		(start 307.714396 -213.910164)
		(end 306.93868 -213.910164)
		(width 0.14478)
		(layer "In2.Cu")
		(net "M_C_CPU0_SA_DQ<13>")
	)
	(segment
		(start 328.41819 -234.276646)
		(end 328.409808 -234.281472)
		(width 0.0889)
		(layer "In2.Cu")
		(net "M_C_CPU0_SA_DQ<13>")
	)
	(segment
		(start 304.396648 -214.532718)
		(end 304.23358 -214.36965)
		(width 0.14478)
		(layer "In2.Cu")
		(net "M_C_CPU0_SA_DQ<13>")
	)
	(segment
		(start 327.251314 -233.96321)
		(end 327.251314 -233.73715)
		(width 0.0889)
		(layer "In2.Cu")
		(net "M_C_CPU0_SA_DQ<13>")
	)
	(segment
		(start 327.761092 -234.200446)
		(end 327.48855 -234.200446)
		(width 0.0889)
		(layer "In2.Cu")
		(net "M_C_CPU0_SA_DQ<13>")
	)
	(segment
		(start 302.838358 -214.537798)
		(end 302.67529 -214.37473)
		(width 0.14478)
		(layer "In2.Cu")
		(net "M_C_CPU0_SA_DQ<13>")
	)
	(segment
		(start 300.710854 -213.52891)
		(end 300.480476 -213.52891)
		(width 0.14478)
		(layer "In2.Cu")
		(net "M_C_CPU0_SA_DQ<13>")
	)
	(segment
		(start 321.272154 -227.55225)
		(end 321.272154 -226.254056)
		(width 0.14478)
		(layer "In2.Cu")
		(net "M_C_CPU0_SA_DQ<13>")
	)
	(segment
		(start 294.010842 -214.997538)
		(end 294.010842 -214.532718)
		(width 0.14478)
		(layer "In2.Cu")
		(net "M_C_CPU0_SA_DQ<13>")
	)
	(segment
		(start 298.217336 -213.910164)
		(end 297.367452 -214.760048)
		(width 0.14478)
		(layer "In2.Cu")
		(net "M_C_CPU0_SA_DQ<13>")
	)
	(segment
		(start 304.396648 -214.59698)
		(end 304.396648 -214.532718)
		(width 0.14478)
		(layer "In2.Cu")
		(net "M_C_CPU0_SA_DQ<13>")
	)
	(segment
		(start 306.775612 -213.747096)
		(end 306.775612 -213.686898)
		(width 0.14478)
		(layer "In2.Cu")
		(net "M_C_CPU0_SA_DQ<13>")
	)
	(segment
		(start 302.838358 -214.59698)
		(end 302.838358 -214.537798)
		(width 0.14478)
		(layer "In2.Cu")
		(net "M_C_CPU0_SA_DQ<13>")
	)
	(segment
		(start 299.349922 -213.679278)
		(end 299.186854 -213.51621)
		(width 0.14478)
		(layer "In2.Cu")
		(net "M_C_CPU0_SA_DQ<13>")
	)
	(segment
		(start 306.219098 -213.747096)
		(end 306.05603 -213.910164)
		(width 0.14478)
		(layer "In2.Cu")
		(net "M_C_CPU0_SA_DQ<13>")
	)
	(segment
		(start 299.51299 -213.910164)
		(end 299.349922 -213.747096)
		(width 0.14478)
		(layer "In2.Cu")
		(net "M_C_CPU0_SA_DQ<13>")
	)
	(segment
		(start 325.359014 -231.10825)
		(end 324.871334 -230.62057)
		(width 0.0889)
		(layer "In2.Cu")
		(net "M_C_CPU0_SA_DQ<13>")
	)
	(segment
		(start 325.359014 -231.72039)
		(end 325.359014 -231.10825)
		(width 0.0889)
		(layer "In2.Cu")
		(net "M_C_CPU0_SA_DQ<13>")
	)
	(segment
		(start 339.698076 -234.276646)
		(end 339.689694 -234.281472)
		(width 0.0889)
		(layer "In2.Cu")
		(net "M_C_CPU0_SA_DQ<13>")
	)
	(segment
		(start 292.735254 -214.790274)
		(end 292.280086 -214.335106)
		(width 0.14478)
		(layer "In2.Cu")
		(net "M_C_CPU0_SA_DQ<13>")
	)
	(segment
		(start 294.010842 -214.532718)
		(end 293.847774 -214.36965)
		(width 0.14478)
		(layer "In2.Cu")
		(net "M_C_CPU0_SA_DQ<13>")
	)
	(segment
		(start 297.054524 -214.760048)
		(end 296.891456 -214.59698)
		(width 0.14478)
		(layer "In2.Cu")
		(net "M_C_CPU0_SA_DQ<13>")
	)
	(segment
		(start 295.286938 -214.760048)
		(end 295.12387 -214.59698)
		(width 0.14478)
		(layer "In2.Cu")
		(net "M_C_CPU0_SA_DQ<13>")
	)
	(segment
		(start 343.425018 -234.219496)
		(end 343.402666 -234.302808)
		(width 0.0889)
		(layer "In2.Cu")
		(net "M_C_CPU0_SA_DQ<13>")
	)
	(segment
		(start 294.404288 -215.160606)
		(end 294.17391 -215.160606)
		(width 0.14478)
		(layer "In2.Cu")
		(net "M_C_CPU0_SA_DQ<13>")
	)
	(segment
		(start 308.985412 -214.29853)
		(end 308.433978 -213.747096)
		(width 0.14478)
		(layer "In2.Cu")
		(net "M_C_CPU0_SA_DQ<13>")
	)
	(segment
		(start 296.334942 -214.537798)
		(end 296.334942 -214.59698)
		(width 0.14478)
		(layer "In2.Cu")
		(net "M_C_CPU0_SA_DQ<13>")
	)
	(segment
		(start 294.730424 -214.36965)
		(end 294.567356 -214.532718)
		(width 0.14478)
		(layer "In2.Cu")
		(net "M_C_CPU0_SA_DQ<13>")
	)
	(segment
		(start 306.219098 -213.686898)
		(end 306.219098 -213.747096)
		(width 0.14478)
		(layer "In2.Cu")
		(net "M_C_CPU0_SA_DQ<13>")
	)
	(segment
		(start 327.48855 -234.200446)
		(end 327.251314 -233.96321)
		(width 0.0889)
		(layer "In2.Cu")
		(net "M_C_CPU0_SA_DQ<13>")
	)
	(segment
		(start 302.444912 -214.37473)
		(end 302.281844 -214.537798)
		(width 0.14478)
		(layer "In2.Cu")
		(net "M_C_CPU0_SA_DQ<13>")
	)
	(segment
		(start 293.454328 -214.988902)
		(end 293.29126 -215.15197)
		(width 0.14478)
		(layer "In2.Cu")
		(net "M_C_CPU0_SA_DQ<13>")
	)
	(segment
		(start 336.878168 -234.276646)
		(end 336.869786 -234.281472)
		(width 0.0889)
		(layer "In2.Cu")
		(net "M_C_CPU0_SA_DQ<13>")
	)
	(segment
		(start 302.67529 -214.37473)
		(end 302.444912 -214.37473)
		(width 0.14478)
		(layer "In2.Cu")
		(net "M_C_CPU0_SA_DQ<13>")
	)
	(segment
		(start 296.49801 -214.37473)
		(end 296.334942 -214.537798)
		(width 0.14478)
		(layer "In2.Cu")
		(net "M_C_CPU0_SA_DQ<13>")
	)
	(segment
		(start 300.480476 -213.52891)
		(end 300.317408 -213.691978)
		(width 0.14478)
		(layer "In2.Cu")
		(net "M_C_CPU0_SA_DQ<13>")
	)
	(segment
		(start 304.559716 -214.760048)
		(end 304.396648 -214.59698)
		(width 0.14478)
		(layer "In2.Cu")
		(net "M_C_CPU0_SA_DQ<13>")
	)
	(segment
		(start 308.040532 -213.52383)
		(end 307.877464 -213.686898)
		(width 0.14478)
		(layer "In2.Cu")
		(net "M_C_CPU0_SA_DQ<13>")
	)
	(segment
		(start 324.340474 -230.62057)
		(end 324.179184 -230.45928)
		(width 0.0889)
		(layer "In2.Cu")
		(net "M_C_CPU0_SA_DQ<13>")
	)
	(segment
		(start 308.27091 -213.52383)
		(end 308.040532 -213.52383)
		(width 0.14478)
		(layer "In2.Cu")
		(net "M_C_CPU0_SA_DQ<13>")
	)
	(segment
		(start 335.938114 -234.276646)
		(end 335.929732 -234.281472)
		(width 0.0889)
		(layer "In2.Cu")
		(net "M_C_CPU0_SA_DQ<13>")
	)
	(segment
		(start 324.871334 -230.62057)
		(end 324.340474 -230.62057)
		(width 0.0889)
		(layer "In2.Cu")
		(net "M_C_CPU0_SA_DQ<13>")
	)
	(segment
		(start 294.567356 -214.997538)
		(end 294.404288 -215.160606)
		(width 0.14478)
		(layer "In2.Cu")
		(net "M_C_CPU0_SA_DQ<13>")
	)
	(segment
		(start 332.752446 -234.281472)
		(end 332.744064 -234.276646)
		(width 0.0889)
		(layer "In2.Cu")
		(net "M_C_CPU0_SA_DQ<13>")
	)
	(segment
		(start 306.05603 -213.910164)
		(end 305.740816 -213.910164)
		(width 0.14478)
		(layer "In2.Cu")
		(net "M_C_CPU0_SA_DQ<13>")
	)
	(segment
		(start 298.793408 -213.679278)
		(end 298.793408 -213.747096)
		(width 0.14478)
		(layer "In2.Cu")
		(net "M_C_CPU0_SA_DQ<13>")
	)
	(segment
		(start 315.578236 -219.432378)
		(end 311.945274 -215.799416)
		(width 0.14478)
		(layer "In2.Cu")
		(net "M_C_CPU0_SA_DQ<13>")
	)
	(segment
		(start 326.20204 -233.15041)
		(end 325.640954 -232.589324)
		(width 0.0889)
		(layer "In2.Cu")
		(net "M_C_CPU0_SA_DQ<13>")
	)
	(segment
		(start 293.847774 -214.36965)
		(end 293.617396 -214.36965)
		(width 0.14478)
		(layer "In2.Cu")
		(net "M_C_CPU0_SA_DQ<13>")
	)
	(segment
		(start 341.212424 -234.281472)
		(end 341.204042 -234.276646)
		(width 0.0889)
		(layer "In2.Cu")
		(net "M_C_CPU0_SA_DQ<13>")
	)
	(segment
		(start 301.03699 -213.910164)
		(end 300.873922 -213.747096)
		(width 0.14478)
		(layer "In2.Cu")
		(net "M_C_CPU0_SA_DQ<13>")
	)
	(segment
		(start 333.6925 -234.281472)
		(end 333.684118 -234.276646)
		(width 0.0889)
		(layer "In2.Cu")
		(net "M_C_CPU0_SA_DQ<13>")
	)
	(segment
		(start 337.452462 -234.281472)
		(end 337.44408 -234.276646)
		(width 0.0889)
		(layer "In2.Cu")
		(net "M_C_CPU0_SA_DQ<13>")
	)
	(segment
		(start 295.12387 -214.59698)
		(end 295.12387 -214.532718)
		(width 0.14478)
		(layer "In2.Cu")
		(net "M_C_CPU0_SA_DQ<13>")
	)
	(segment
		(start 304.23358 -214.36965)
		(end 304.003202 -214.36965)
		(width 0.14478)
		(layer "In2.Cu")
		(net "M_C_CPU0_SA_DQ<13>")
	)
	(segment
		(start 342.152478 -234.281472)
		(end 342.144096 -234.276646)
		(width 0.0889)
		(layer "In2.Cu")
		(net "M_C_CPU0_SA_DQ<13>")
	)
	(segment
		(start 315.578236 -220.560138)
		(end 315.578236 -219.432378)
		(width 0.14478)
		(layer "In2.Cu")
		(net "M_C_CPU0_SA_DQ<13>")
	)
	(segment
		(start 306.775612 -213.686898)
		(end 306.612544 -213.52383)
		(width 0.14478)
		(layer "In2.Cu")
		(net "M_C_CPU0_SA_DQ<13>")
	)
	(segment
		(start 292.885114 -215.15197)
		(end 292.735254 -215.00211)
		(width 0.14478)
		(layer "In2.Cu")
		(net "M_C_CPU0_SA_DQ<13>")
	)
	(segment
		(start 303.840134 -214.59698)
		(end 303.677066 -214.760048)
		(width 0.14478)
		(layer "In2.Cu")
		(net "M_C_CPU0_SA_DQ<13>")
	)
	(segment
		(start 301.042832 -213.910164)
		(end 301.03699 -213.910164)
		(width 0.14478)
		(layer "In2.Cu")
		(net "M_C_CPU0_SA_DQ<13>")
	)
	(segment
		(start 296.334942 -214.59698)
		(end 296.171874 -214.760048)
		(width 0.14478)
		(layer "In2.Cu")
		(net "M_C_CPU0_SA_DQ<13>")
	)
	(segment
		(start 302.281844 -214.537798)
		(end 302.281844 -214.59698)
		(width 0.14478)
		(layer "In2.Cu")
		(net "M_C_CPU0_SA_DQ<13>")
	)
	(segment
		(start 293.29126 -215.15197)
		(end 292.885114 -215.15197)
		(width 0.14478)
		(layer "In2.Cu")
		(net "M_C_CPU0_SA_DQ<13>")
	)
	(segment
		(start 307.877464 -213.686898)
		(end 307.877464 -213.747096)
		(width 0.14478)
		(layer "In2.Cu")
		(net "M_C_CPU0_SA_DQ<13>")
	)
	(segment
		(start 306.382166 -213.52383)
		(end 306.219098 -213.686898)
		(width 0.14478)
		(layer "In2.Cu")
		(net "M_C_CPU0_SA_DQ<13>")
	)
	(segment
		(start 326.664574 -233.15041)
		(end 326.20204 -233.15041)
		(width 0.0889)
		(layer "In2.Cu")
		(net "M_C_CPU0_SA_DQ<13>")
	)
	(segment
		(start 298.63034 -213.910164)
		(end 298.217336 -213.910164)
		(width 0.14478)
		(layer "In2.Cu")
		(net "M_C_CPU0_SA_DQ<13>")
	)
	(arc
		(start 337.44408 -234.276646)
		(mid 337.161124 -234.200469)
		(end 336.878168 -234.276646)
		(width 0.0889)
		(layer "In2.Cu")
		(net "M_C_CPU0_SA_DQ<13>")
	)
	(arc
		(start 333.684118 -234.276646)
		(mid 333.401162 -234.200469)
		(end 333.118206 -234.276646)
		(width 0.0889)
		(layer "In2.Cu")
		(net "M_C_CPU0_SA_DQ<13>")
	)
	(arc
		(start 342.518238 -234.276646)
		(mid 342.335987 -234.326996)
		(end 342.152478 -234.281472)
		(width 0.0889)
		(layer "In2.Cu")
		(net "M_C_CPU0_SA_DQ<13>")
	)
	(arc
		(start 334.05826 -234.276646)
		(mid 333.876009 -234.326996)
		(end 333.6925 -234.281472)
		(width 0.0889)
		(layer "In2.Cu")
		(net "M_C_CPU0_SA_DQ<13>")
	)
	(arc
		(start 336.869786 -234.281472)
		(mid 336.686278 -234.326966)
		(end 336.504026 -234.276646)
		(width 0.0889)
		(layer "In2.Cu")
		(net "M_C_CPU0_SA_DQ<13>")
	)
	(arc
		(start 342.144096 -234.276646)
		(mid 341.86114 -234.200469)
		(end 341.578184 -234.276646)
		(width 0.0889)
		(layer "In2.Cu")
		(net "M_C_CPU0_SA_DQ<13>")
	)
	(arc
		(start 337.818222 -234.276646)
		(mid 337.635971 -234.326996)
		(end 337.452462 -234.281472)
		(width 0.0889)
		(layer "In2.Cu")
		(net "M_C_CPU0_SA_DQ<13>")
	)
	(arc
		(start 343.402666 -234.302808)
		(mid 343.240477 -234.325543)
		(end 343.08415 -234.276646)
		(width 0.0889)
		(layer "In2.Cu")
		(net "M_C_CPU0_SA_DQ<13>")
	)
	(arc
		(start 332.16977 -234.281472)
		(mid 331.986262 -234.326966)
		(end 331.80401 -234.276646)
		(width 0.0889)
		(layer "In2.Cu")
		(net "M_C_CPU0_SA_DQ<13>")
	)
	(arc
		(start 339.323934 -234.276646)
		(mid 339.040978 -234.200469)
		(end 338.758022 -234.276646)
		(width 0.0889)
		(layer "In2.Cu")
		(net "M_C_CPU0_SA_DQ<13>")
	)
	(arc
		(start 331.229716 -234.281472)
		(mid 331.046208 -234.326966)
		(end 330.863956 -234.276646)
		(width 0.0889)
		(layer "In2.Cu")
		(net "M_C_CPU0_SA_DQ<13>")
	)
	(arc
		(start 340.629748 -234.281472)
		(mid 340.44624 -234.326966)
		(end 340.263988 -234.276646)
		(width 0.0889)
		(layer "In2.Cu")
		(net "M_C_CPU0_SA_DQ<13>")
	)
	(arc
		(start 335.929732 -234.281472)
		(mid 335.746224 -234.326966)
		(end 335.563972 -234.276646)
		(width 0.0889)
		(layer "In2.Cu")
		(net "M_C_CPU0_SA_DQ<13>")
	)
	(arc
		(start 339.689694 -234.281472)
		(mid 339.506186 -234.326966)
		(end 339.323934 -234.276646)
		(width 0.0889)
		(layer "In2.Cu")
		(net "M_C_CPU0_SA_DQ<13>")
	)
	(arc
		(start 332.744064 -234.276646)
		(mid 332.461108 -234.200469)
		(end 332.178152 -234.276646)
		(width 0.0889)
		(layer "In2.Cu")
		(net "M_C_CPU0_SA_DQ<13>")
	)
	(arc
		(start 341.578184 -234.276646)
		(mid 341.395933 -234.326996)
		(end 341.212424 -234.281472)
		(width 0.0889)
		(layer "In2.Cu")
		(net "M_C_CPU0_SA_DQ<13>")
	)
	(arc
		(start 328.044048 -234.276646)
		(mid 327.907612 -234.219821)
		(end 327.761092 -234.200446)
		(width 0.0889)
		(layer "In2.Cu")
		(net "M_C_CPU0_SA_DQ<13>")
	)
	(arc
		(start 329.358244 -234.276646)
		(mid 329.175993 -234.326996)
		(end 328.992484 -234.281472)
		(width 0.0889)
		(layer "In2.Cu")
		(net "M_C_CPU0_SA_DQ<13>")
	)
	(arc
		(start 330.863956 -234.276646)
		(mid 330.581 -234.200469)
		(end 330.298044 -234.276646)
		(width 0.0889)
		(layer "In2.Cu")
		(net "M_C_CPU0_SA_DQ<13>")
	)
	(arc
		(start 328.984102 -234.276646)
		(mid 328.701146 -234.200469)
		(end 328.41819 -234.276646)
		(width 0.0889)
		(layer "In2.Cu")
		(net "M_C_CPU0_SA_DQ<13>")
	)
	(arc
		(start 329.924156 -234.276646)
		(mid 329.6412 -234.200469)
		(end 329.358244 -234.276646)
		(width 0.0889)
		(layer "In2.Cu")
		(net "M_C_CPU0_SA_DQ<13>")
	)
	(arc
		(start 333.118206 -234.276646)
		(mid 332.935955 -234.326996)
		(end 332.752446 -234.281472)
		(width 0.0889)
		(layer "In2.Cu")
		(net "M_C_CPU0_SA_DQ<13>")
	)
	(arc
		(start 340.263988 -234.276646)
		(mid 339.981032 -234.200469)
		(end 339.698076 -234.276646)
		(width 0.0889)
		(layer "In2.Cu")
		(net "M_C_CPU0_SA_DQ<13>")
	)
	(arc
		(start 328.409808 -234.281472)
		(mid 328.2263 -234.326966)
		(end 328.044048 -234.276646)
		(width 0.0889)
		(layer "In2.Cu")
		(net "M_C_CPU0_SA_DQ<13>")
	)
	(arc
		(start 334.99806 -234.276646)
		(mid 334.811116 -234.326901)
		(end 334.624172 -234.276646)
		(width 0.0889)
		(layer "In2.Cu")
		(net "M_C_CPU0_SA_DQ<13>")
	)
	(arc
		(start 338.384134 -234.276646)
		(mid 338.101178 -234.200469)
		(end 337.818222 -234.276646)
		(width 0.0889)
		(layer "In2.Cu")
		(net "M_C_CPU0_SA_DQ<13>")
	)
	(arc
		(start 338.758022 -234.276646)
		(mid 338.571078 -234.326901)
		(end 338.384134 -234.276646)
		(width 0.0889)
		(layer "In2.Cu")
		(net "M_C_CPU0_SA_DQ<13>")
	)
	(arc
		(start 331.80401 -234.276646)
		(mid 331.521054 -234.200469)
		(end 331.238098 -234.276646)
		(width 0.0889)
		(layer "In2.Cu")
		(net "M_C_CPU0_SA_DQ<13>")
	)
	(arc
		(start 341.204042 -234.276646)
		(mid 340.921086 -234.200469)
		(end 340.63813 -234.276646)
		(width 0.0889)
		(layer "In2.Cu")
		(net "M_C_CPU0_SA_DQ<13>")
	)
	(arc
		(start 330.298044 -234.276646)
		(mid 330.1111 -234.326901)
		(end 329.924156 -234.276646)
		(width 0.0889)
		(layer "In2.Cu")
		(net "M_C_CPU0_SA_DQ<13>")
	)
	(arc
		(start 336.504026 -234.276646)
		(mid 336.22107 -234.200469)
		(end 335.938114 -234.276646)
		(width 0.0889)
		(layer "In2.Cu")
		(net "M_C_CPU0_SA_DQ<13>")
	)
	(arc
		(start 335.563972 -234.276646)
		(mid 335.281016 -234.200469)
		(end 334.99806 -234.276646)
		(width 0.0889)
		(layer "In2.Cu")
		(net "M_C_CPU0_SA_DQ<13>")
	)
	(arc
		(start 343.08415 -234.276646)
		(mid 342.801194 -234.200469)
		(end 342.518238 -234.276646)
		(width 0.0889)
		(layer "In2.Cu")
		(net "M_C_CPU0_SA_DQ<13>")
	)
	(arc
		(start 334.624172 -234.276646)
		(mid 334.341216 -234.200469)
		(end 334.05826 -234.276646)
		(width 0.0889)
		(layer "In2.Cu")
		(net "M_C_CPU0_SA_DQ<13>")
	)
	(segment
		(start 342.327992 -233.409998)
		(end 341.86114 -233.14406)
		(width 0.10668)
		(layer "F.Cu")
		(net "M_C_CPU0_SA_DQ<12>")
	)
	(segment
		(start 333.588106 -233.46664)
		(end 333.579724 -233.471466)
		(width 0.0889)
		(layer "In2.Cu")
		(net "M_C_CPU0_SA_DQ<12>")
	)
	(segment
		(start 338.862416 -233.471466)
		(end 338.854034 -233.46664)
		(width 0.0889)
		(layer "In2.Cu")
		(net "M_C_CPU0_SA_DQ<12>")
	)
	(segment
		(start 293.248334 -213.347554)
		(end 292.992556 -213.347554)
		(width 0.14478)
		(layer "In2.Cu")
		(net "M_C_CPU0_SA_DQ<12>")
	)
	(segment
		(start 293.561262 -212.528404)
		(end 293.398194 -212.691472)
		(width 0.14478)
		(layer "In2.Cu")
		(net "M_C_CPU0_SA_DQ<12>")
	)
	(segment
		(start 294.614346 -213.214458)
		(end 294.614346 -213.271862)
		(width 0.14478)
		(layer "In2.Cu")
		(net "M_C_CPU0_SA_DQ<12>")
	)
	(segment
		(start 315.694568 -217.664284)
		(end 315.5315 -217.501216)
		(width 0.14478)
		(layer "In2.Cu")
		(net "M_C_CPU0_SA_DQ<12>")
	)
	(segment
		(start 325.849234 -231.32669)
		(end 325.849234 -229.91699)
		(width 0.0889)
		(layer "In2.Cu")
		(net "M_C_CPU0_SA_DQ<12>")
	)
	(segment
		(start 334.52816 -233.46664)
		(end 334.519778 -233.471466)
		(width 0.0889)
		(layer "In2.Cu")
		(net "M_C_CPU0_SA_DQ<12>")
	)
	(segment
		(start 313.27852 -215.817196)
		(end 313.27852 -215.586564)
		(width 0.14478)
		(layer "In2.Cu")
		(net "M_C_CPU0_SA_DQ<12>")
	)
	(segment
		(start 311.122568 -213.35365)
		(end 310.9595 -213.190582)
		(width 0.14478)
		(layer "In2.Cu")
		(net "M_C_CPU0_SA_DQ<12>")
	)
	(segment
		(start 308.675278 -212.397086)
		(end 308.488334 -212.210142)
		(width 0.14478)
		(layer "In2.Cu")
		(net "M_C_CPU0_SA_DQ<12>")
	)
	(segment
		(start 311.383934 -213.35365)
		(end 311.122568 -213.35365)
		(width 0.14478)
		(layer "In2.Cu")
		(net "M_C_CPU0_SA_DQ<12>")
	)
	(segment
		(start 330.402438 -233.471466)
		(end 330.394056 -233.46664)
		(width 0.0889)
		(layer "In2.Cu")
		(net "M_C_CPU0_SA_DQ<12>")
	)
	(segment
		(start 331.342492 -233.471466)
		(end 331.33411 -233.46664)
		(width 0.0889)
		(layer "In2.Cu")
		(net "M_C_CPU0_SA_DQ<12>")
	)
	(segment
		(start 301.892716 -213.060026)
		(end 301.052484 -212.219794)
		(width 0.14478)
		(layer "In2.Cu")
		(net "M_C_CPU0_SA_DQ<12>")
	)
	(segment
		(start 297.785536 -213.069678)
		(end 294.759126 -213.069678)
		(width 0.14478)
		(layer "In2.Cu")
		(net "M_C_CPU0_SA_DQ<12>")
	)
	(segment
		(start 294.057832 -213.271862)
		(end 294.057832 -213.146894)
		(width 0.14478)
		(layer "In2.Cu")
		(net "M_C_CPU0_SA_DQ<12>")
	)
	(segment
		(start 325.849234 -229.91699)
		(end 324.734936 -228.802692)
		(width 0.0889)
		(layer "In2.Cu")
		(net "M_C_CPU0_SA_DQ<12>")
	)
	(segment
		(start 313.27852 -215.586564)
		(end 313.332368 -215.532716)
		(width 0.14478)
		(layer "In2.Cu")
		(net "M_C_CPU0_SA_DQ<12>")
	)
	(segment
		(start 316.03442 -218.342464)
		(end 315.803788 -218.342464)
		(width 0.14478)
		(layer "In2.Cu")
		(net "M_C_CPU0_SA_DQ<12>")
	)
	(segment
		(start 294.2209 -213.43493)
		(end 294.057832 -213.271862)
		(width 0.14478)
		(layer "In2.Cu")
		(net "M_C_CPU0_SA_DQ<12>")
	)
	(segment
		(start 304.80889 -213.37905)
		(end 304.5714 -213.37905)
		(width 0.14478)
		(layer "In2.Cu")
		(net "M_C_CPU0_SA_DQ<12>")
	)
	(segment
		(start 315.300868 -217.501216)
		(end 315.24702 -217.555064)
		(width 0.14478)
		(layer "In2.Cu")
		(net "M_C_CPU0_SA_DQ<12>")
	)
	(segment
		(start 309.226712 -212.397086)
		(end 309.226712 -212.656166)
		(width 0.14478)
		(layer "In2.Cu")
		(net "M_C_CPU0_SA_DQ<12>")
	)
	(segment
		(start 341.86114 -233.14406)
		(end 342.015064 -233.40949)
		(width 0.0889)
		(layer "In2.Cu")
		(net "M_C_CPU0_SA_DQ<12>")
	)
	(segment
		(start 314.907168 -216.876884)
		(end 314.7441 -216.713816)
		(width 0.14478)
		(layer "In2.Cu")
		(net "M_C_CPU0_SA_DQ<12>")
	)
	(segment
		(start 313.441588 -215.980264)
		(end 313.27852 -215.817196)
		(width 0.14478)
		(layer "In2.Cu")
		(net "M_C_CPU0_SA_DQ<12>")
	)
	(segment
		(start 313.726068 -215.926416)
		(end 313.67222 -215.980264)
		(width 0.14478)
		(layer "In2.Cu")
		(net "M_C_CPU0_SA_DQ<12>")
	)
	(segment
		(start 335.102454 -233.471466)
		(end 335.094072 -233.46664)
		(width 0.0889)
		(layer "In2.Cu")
		(net "M_C_CPU0_SA_DQ<12>")
	)
	(segment
		(start 315.64072 -218.179396)
		(end 315.64072 -217.948764)
		(width 0.14478)
		(layer "In2.Cu")
		(net "M_C_CPU0_SA_DQ<12>")
	)
	(segment
		(start 292.992556 -213.347554)
		(end 292.280086 -212.635084)
		(width 0.14478)
		(layer "In2.Cu")
		(net "M_C_CPU0_SA_DQ<12>")
	)
	(segment
		(start 315.64072 -217.948764)
		(end 315.694568 -217.894916)
		(width 0.14478)
		(layer "In2.Cu")
		(net "M_C_CPU0_SA_DQ<12>")
	)
	(segment
		(start 306.113688 -212.210142)
		(end 305.263804 -213.060026)
		(width 0.14478)
		(layer "In2.Cu")
		(net "M_C_CPU0_SA_DQ<12>")
	)
	(segment
		(start 310.9595 -213.190582)
		(end 310.9595 -212.825584)
		(width 0.14478)
		(layer "In2.Cu")
		(net "M_C_CPU0_SA_DQ<12>")
	)
	(segment
		(start 326.796654 -232.27411)
		(end 325.849234 -231.32669)
		(width 0.0889)
		(layer "In2.Cu")
		(net "M_C_CPU0_SA_DQ<12>")
	)
	(segment
		(start 298.63542 -212.219794)
		(end 297.785536 -213.069678)
		(width 0.14478)
		(layer "In2.Cu")
		(net "M_C_CPU0_SA_DQ<12>")
	)
	(segment
		(start 308.675278 -212.656166)
		(end 308.675278 -212.397086)
		(width 0.14478)
		(layer "In2.Cu")
		(net "M_C_CPU0_SA_DQ<12>")
	)
	(segment
		(start 316.547754 -218.51747)
		(end 316.3189 -218.288616)
		(width 0.14478)
		(layer "In2.Cu")
		(net "M_C_CPU0_SA_DQ<12>")
	)
	(segment
		(start 322.196714 -227.16363)
		(end 322.196714 -225.87077)
		(width 0.14478)
		(layer "In2.Cu")
		(net "M_C_CPU0_SA_DQ<12>")
	)
	(segment
		(start 293.954708 -213.04377)
		(end 293.954708 -212.691472)
		(width 0.14478)
		(layer "In2.Cu")
		(net "M_C_CPU0_SA_DQ<12>")
	)
	(segment
		(start 310.402986 -212.825584)
		(end 310.402986 -213.190582)
		(width 0.14478)
		(layer "In2.Cu")
		(net "M_C_CPU0_SA_DQ<12>")
	)
	(segment
		(start 323.835776 -228.802692)
		(end 322.196714 -227.16363)
		(width 0.14478)
		(layer "In2.Cu")
		(net "M_C_CPU0_SA_DQ<12>")
	)
	(segment
		(start 309.846472 -212.434678)
		(end 309.621936 -212.210142)
		(width 0.14478)
		(layer "In2.Cu")
		(net "M_C_CPU0_SA_DQ<12>")
	)
	(segment
		(start 314.513468 -216.713816)
		(end 314.45962 -216.767664)
		(width 0.14478)
		(layer "In2.Cu")
		(net "M_C_CPU0_SA_DQ<12>")
	)
	(segment
		(start 313.332368 -215.302084)
		(end 311.383934 -213.35365)
		(width 0.14478)
		(layer "In2.Cu")
		(net "M_C_CPU0_SA_DQ<12>")
	)
	(segment
		(start 314.119768 -216.089484)
		(end 313.9567 -215.926416)
		(width 0.14478)
		(layer "In2.Cu")
		(net "M_C_CPU0_SA_DQ<12>")
	)
	(segment
		(start 309.226712 -212.656166)
		(end 309.065168 -212.81771)
		(width 0.14478)
		(layer "In2.Cu")
		(net "M_C_CPU0_SA_DQ<12>")
	)
	(segment
		(start 309.065168 -212.81771)
		(end 308.836822 -212.81771)
		(width 0.14478)
		(layer "In2.Cu")
		(net "M_C_CPU0_SA_DQ<12>")
	)
	(segment
		(start 339.80247 -233.471466)
		(end 339.794088 -233.46664)
		(width 0.0889)
		(layer "In2.Cu")
		(net "M_C_CPU0_SA_DQ<12>")
	)
	(segment
		(start 309.413656 -212.210142)
		(end 309.226712 -212.397086)
		(width 0.14478)
		(layer "In2.Cu")
		(net "M_C_CPU0_SA_DQ<12>")
	)
	(segment
		(start 314.06592 -216.373964)
		(end 314.119768 -216.320116)
		(width 0.14478)
		(layer "In2.Cu")
		(net "M_C_CPU0_SA_DQ<12>")
	)
	(segment
		(start 294.451278 -213.43493)
		(end 294.2209 -213.43493)
		(width 0.14478)
		(layer "In2.Cu")
		(net "M_C_CPU0_SA_DQ<12>")
	)
	(segment
		(start 314.06592 -216.604596)
		(end 314.06592 -216.373964)
		(width 0.14478)
		(layer "In2.Cu")
		(net "M_C_CPU0_SA_DQ<12>")
	)
	(segment
		(start 314.85332 -217.391996)
		(end 314.85332 -217.161364)
		(width 0.14478)
		(layer "In2.Cu")
		(net "M_C_CPU0_SA_DQ<12>")
	)
	(segment
		(start 314.45962 -216.767664)
		(end 314.228988 -216.767664)
		(width 0.14478)
		(layer "In2.Cu")
		(net "M_C_CPU0_SA_DQ<12>")
	)
	(segment
		(start 293.398194 -213.197694)
		(end 293.248334 -213.347554)
		(width 0.14478)
		(layer "In2.Cu")
		(net "M_C_CPU0_SA_DQ<12>")
	)
	(segment
		(start 316.3189 -218.288616)
		(end 316.088268 -218.288616)
		(width 0.14478)
		(layer "In2.Cu")
		(net "M_C_CPU0_SA_DQ<12>")
	)
	(segment
		(start 301.052484 -212.219794)
		(end 298.63542 -212.219794)
		(width 0.14478)
		(layer "In2.Cu")
		(net "M_C_CPU0_SA_DQ<12>")
	)
	(segment
		(start 308.836822 -212.81771)
		(end 308.675278 -212.656166)
		(width 0.14478)
		(layer "In2.Cu")
		(net "M_C_CPU0_SA_DQ<12>")
	)
	(segment
		(start 294.759126 -213.069678)
		(end 294.614346 -213.214458)
		(width 0.14478)
		(layer "In2.Cu")
		(net "M_C_CPU0_SA_DQ<12>")
	)
	(segment
		(start 327.573894 -233.46664)
		(end 326.796654 -232.6894)
		(width 0.0889)
		(layer "In2.Cu")
		(net "M_C_CPU0_SA_DQ<12>")
	)
	(segment
		(start 329.828144 -233.46664)
		(end 329.819762 -233.471466)
		(width 0.0889)
		(layer "In2.Cu")
		(net "M_C_CPU0_SA_DQ<12>")
	)
	(segment
		(start 304.5714 -213.37905)
		(end 304.252376 -213.060026)
		(width 0.14478)
		(layer "In2.Cu")
		(net "M_C_CPU0_SA_DQ<12>")
	)
	(segment
		(start 313.332368 -215.532716)
		(end 313.332368 -215.302084)
		(width 0.14478)
		(layer "In2.Cu")
		(net "M_C_CPU0_SA_DQ<12>")
	)
	(segment
		(start 314.85332 -217.161364)
		(end 314.907168 -217.107516)
		(width 0.14478)
		(layer "In2.Cu")
		(net "M_C_CPU0_SA_DQ<12>")
	)
	(segment
		(start 336.042508 -233.471466)
		(end 336.034126 -233.46664)
		(width 0.0889)
		(layer "In2.Cu")
		(net "M_C_CPU0_SA_DQ<12>")
	)
	(segment
		(start 324.734936 -228.802692)
		(end 324.227698 -228.802692)
		(width 0.0889)
		(layer "In2.Cu")
		(net "M_C_CPU0_SA_DQ<12>")
	)
	(segment
		(start 293.79164 -212.528404)
		(end 293.561262 -212.528404)
		(width 0.14478)
		(layer "In2.Cu")
		(net "M_C_CPU0_SA_DQ<12>")
	)
	(segment
		(start 305.127914 -213.060026)
		(end 304.80889 -213.37905)
		(width 0.14478)
		(layer "In2.Cu")
		(net "M_C_CPU0_SA_DQ<12>")
	)
	(segment
		(start 315.016388 -217.555064)
		(end 314.85332 -217.391996)
		(width 0.14478)
		(layer "In2.Cu")
		(net "M_C_CPU0_SA_DQ<12>")
	)
	(segment
		(start 310.00954 -213.35365)
		(end 309.846472 -213.190582)
		(width 0.14478)
		(layer "In2.Cu")
		(net "M_C_CPU0_SA_DQ<12>")
	)
	(segment
		(start 314.907168 -217.107516)
		(end 314.907168 -216.876884)
		(width 0.14478)
		(layer "In2.Cu")
		(net "M_C_CPU0_SA_DQ<12>")
	)
	(segment
		(start 314.119768 -216.320116)
		(end 314.119768 -216.089484)
		(width 0.14478)
		(layer "In2.Cu")
		(net "M_C_CPU0_SA_DQ<12>")
	)
	(segment
		(start 310.796432 -212.662516)
		(end 310.566054 -212.662516)
		(width 0.14478)
		(layer "In2.Cu")
		(net "M_C_CPU0_SA_DQ<12>")
	)
	(segment
		(start 314.228988 -216.767664)
		(end 314.06592 -216.604596)
		(width 0.14478)
		(layer "In2.Cu")
		(net "M_C_CPU0_SA_DQ<12>")
	)
	(segment
		(start 310.239918 -213.35365)
		(end 310.00954 -213.35365)
		(width 0.14478)
		(layer "In2.Cu")
		(net "M_C_CPU0_SA_DQ<12>")
	)
	(segment
		(start 322.196714 -225.87077)
		(end 316.547754 -220.22181)
		(width 0.14478)
		(layer "In2.Cu")
		(net "M_C_CPU0_SA_DQ<12>")
	)
	(segment
		(start 309.621936 -212.210142)
		(end 309.413656 -212.210142)
		(width 0.14478)
		(layer "In2.Cu")
		(net "M_C_CPU0_SA_DQ<12>")
	)
	(segment
		(start 324.227698 -228.802692)
		(end 323.835776 -228.802692)
		(width 0.14478)
		(layer "In2.Cu")
		(net "M_C_CPU0_SA_DQ<12>")
	)
	(segment
		(start 308.488334 -212.210142)
		(end 306.113688 -212.210142)
		(width 0.14478)
		(layer "In2.Cu")
		(net "M_C_CPU0_SA_DQ<12>")
	)
	(segment
		(start 315.5315 -217.501216)
		(end 315.300868 -217.501216)
		(width 0.14478)
		(layer "In2.Cu")
		(net "M_C_CPU0_SA_DQ<12>")
	)
	(segment
		(start 304.252376 -213.060026)
		(end 301.892716 -213.060026)
		(width 0.14478)
		(layer "In2.Cu")
		(net "M_C_CPU0_SA_DQ<12>")
	)
	(segment
		(start 309.846472 -213.190582)
		(end 309.846472 -212.434678)
		(width 0.14478)
		(layer "In2.Cu")
		(net "M_C_CPU0_SA_DQ<12>")
	)
	(segment
		(start 315.694568 -217.894916)
		(end 315.694568 -217.664284)
		(width 0.14478)
		(layer "In2.Cu")
		(net "M_C_CPU0_SA_DQ<12>")
	)
	(segment
		(start 313.9567 -215.926416)
		(end 313.726068 -215.926416)
		(width 0.14478)
		(layer "In2.Cu")
		(net "M_C_CPU0_SA_DQ<12>")
	)
	(segment
		(start 310.9595 -212.825584)
		(end 310.796432 -212.662516)
		(width 0.14478)
		(layer "In2.Cu")
		(net "M_C_CPU0_SA_DQ<12>")
	)
	(segment
		(start 310.402986 -213.190582)
		(end 310.239918 -213.35365)
		(width 0.14478)
		(layer "In2.Cu")
		(net "M_C_CPU0_SA_DQ<12>")
	)
	(segment
		(start 294.057832 -213.146894)
		(end 293.954708 -213.04377)
		(width 0.14478)
		(layer "In2.Cu")
		(net "M_C_CPU0_SA_DQ<12>")
	)
	(segment
		(start 314.7441 -216.713816)
		(end 314.513468 -216.713816)
		(width 0.14478)
		(layer "In2.Cu")
		(net "M_C_CPU0_SA_DQ<12>")
	)
	(segment
		(start 315.24702 -217.555064)
		(end 315.016388 -217.555064)
		(width 0.14478)
		(layer "In2.Cu")
		(net "M_C_CPU0_SA_DQ<12>")
	)
	(segment
		(start 294.614346 -213.271862)
		(end 294.451278 -213.43493)
		(width 0.14478)
		(layer "In2.Cu")
		(net "M_C_CPU0_SA_DQ<12>")
	)
	(segment
		(start 310.566054 -212.662516)
		(end 310.402986 -212.825584)
		(width 0.14478)
		(layer "In2.Cu")
		(net "M_C_CPU0_SA_DQ<12>")
	)
	(segment
		(start 293.954708 -212.691472)
		(end 293.79164 -212.528404)
		(width 0.14478)
		(layer "In2.Cu")
		(net "M_C_CPU0_SA_DQ<12>")
	)
	(segment
		(start 315.803788 -218.342464)
		(end 315.64072 -218.179396)
		(width 0.14478)
		(layer "In2.Cu")
		(net "M_C_CPU0_SA_DQ<12>")
	)
	(segment
		(start 338.288122 -233.46664)
		(end 338.27974 -233.471466)
		(width 0.0889)
		(layer "In2.Cu")
		(net "M_C_CPU0_SA_DQ<12>")
	)
	(segment
		(start 313.67222 -215.980264)
		(end 313.441588 -215.980264)
		(width 0.14478)
		(layer "In2.Cu")
		(net "M_C_CPU0_SA_DQ<12>")
	)
	(segment
		(start 293.398194 -212.691472)
		(end 293.398194 -213.197694)
		(width 0.14478)
		(layer "In2.Cu")
		(net "M_C_CPU0_SA_DQ<12>")
	)
	(segment
		(start 316.547754 -220.22181)
		(end 316.547754 -218.51747)
		(width 0.14478)
		(layer "In2.Cu")
		(net "M_C_CPU0_SA_DQ<12>")
	)
	(segment
		(start 316.088268 -218.288616)
		(end 316.03442 -218.342464)
		(width 0.14478)
		(layer "In2.Cu")
		(net "M_C_CPU0_SA_DQ<12>")
	)
	(segment
		(start 305.263804 -213.060026)
		(end 305.127914 -213.060026)
		(width 0.14478)
		(layer "In2.Cu")
		(net "M_C_CPU0_SA_DQ<12>")
	)
	(segment
		(start 342.015064 -233.40949)
		(end 341.992712 -233.492802)
		(width 0.0889)
		(layer "In2.Cu")
		(net "M_C_CPU0_SA_DQ<12>")
	)
	(segment
		(start 326.796654 -232.6894)
		(end 326.796654 -232.27411)
		(width 0.0889)
		(layer "In2.Cu")
		(net "M_C_CPU0_SA_DQ<12>")
	)
	(arc
		(start 335.468214 -233.46664)
		(mid 335.285963 -233.51699)
		(end 335.102454 -233.471466)
		(width 0.0889)
		(layer "In2.Cu")
		(net "M_C_CPU0_SA_DQ<12>")
	)
	(arc
		(start 339.228176 -233.46664)
		(mid 339.045925 -233.51699)
		(end 338.862416 -233.471466)
		(width 0.0889)
		(layer "In2.Cu")
		(net "M_C_CPU0_SA_DQ<12>")
	)
	(arc
		(start 327.94829 -233.46664)
		(mid 327.761092 -233.517022)
		(end 327.573894 -233.46664)
		(width 0.0889)
		(layer "In2.Cu")
		(net "M_C_CPU0_SA_DQ<12>")
	)
	(arc
		(start 336.034126 -233.46664)
		(mid 335.75117 -233.390463)
		(end 335.468214 -233.46664)
		(width 0.0889)
		(layer "In2.Cu")
		(net "M_C_CPU0_SA_DQ<12>")
	)
	(arc
		(start 332.648052 -233.46664)
		(mid 332.461108 -233.516895)
		(end 332.274164 -233.46664)
		(width 0.0889)
		(layer "In2.Cu")
		(net "M_C_CPU0_SA_DQ<12>")
	)
	(arc
		(start 328.88809 -233.46664)
		(mid 328.701146 -233.516895)
		(end 328.514202 -233.46664)
		(width 0.0889)
		(layer "In2.Cu")
		(net "M_C_CPU0_SA_DQ<12>")
	)
	(arc
		(start 341.10803 -233.46664)
		(mid 340.921086 -233.516895)
		(end 340.734142 -233.46664)
		(width 0.0889)
		(layer "In2.Cu")
		(net "M_C_CPU0_SA_DQ<12>")
	)
	(arc
		(start 340.734142 -233.46664)
		(mid 340.451186 -233.390463)
		(end 340.16823 -233.46664)
		(width 0.0889)
		(layer "In2.Cu")
		(net "M_C_CPU0_SA_DQ<12>")
	)
	(arc
		(start 340.16823 -233.46664)
		(mid 339.985979 -233.51699)
		(end 339.80247 -233.471466)
		(width 0.0889)
		(layer "In2.Cu")
		(net "M_C_CPU0_SA_DQ<12>")
	)
	(arc
		(start 331.33411 -233.46664)
		(mid 331.051154 -233.390463)
		(end 330.768198 -233.46664)
		(width 0.0889)
		(layer "In2.Cu")
		(net "M_C_CPU0_SA_DQ<12>")
	)
	(arc
		(start 337.91398 -233.46664)
		(mid 337.631024 -233.390463)
		(end 337.348068 -233.46664)
		(width 0.0889)
		(layer "In2.Cu")
		(net "M_C_CPU0_SA_DQ<12>")
	)
	(arc
		(start 334.519778 -233.471466)
		(mid 334.33627 -233.51696)
		(end 334.154018 -233.46664)
		(width 0.0889)
		(layer "In2.Cu")
		(net "M_C_CPU0_SA_DQ<12>")
	)
	(arc
		(start 336.408268 -233.46664)
		(mid 336.226017 -233.51699)
		(end 336.042508 -233.471466)
		(width 0.0889)
		(layer "In2.Cu")
		(net "M_C_CPU0_SA_DQ<12>")
	)
	(arc
		(start 337.348068 -233.46664)
		(mid 337.161124 -233.516895)
		(end 336.97418 -233.46664)
		(width 0.0889)
		(layer "In2.Cu")
		(net "M_C_CPU0_SA_DQ<12>")
	)
	(arc
		(start 341.992712 -233.492802)
		(mid 341.83038 -233.51562)
		(end 341.673942 -233.46664)
		(width 0.0889)
		(layer "In2.Cu")
		(net "M_C_CPU0_SA_DQ<12>")
	)
	(arc
		(start 330.768198 -233.46664)
		(mid 330.585947 -233.51699)
		(end 330.402438 -233.471466)
		(width 0.0889)
		(layer "In2.Cu")
		(net "M_C_CPU0_SA_DQ<12>")
	)
	(arc
		(start 338.854034 -233.46664)
		(mid 338.571078 -233.390463)
		(end 338.288122 -233.46664)
		(width 0.0889)
		(layer "In2.Cu")
		(net "M_C_CPU0_SA_DQ<12>")
	)
	(arc
		(start 333.213964 -233.46664)
		(mid 332.931008 -233.390463)
		(end 332.648052 -233.46664)
		(width 0.0889)
		(layer "In2.Cu")
		(net "M_C_CPU0_SA_DQ<12>")
	)
	(arc
		(start 336.97418 -233.46664)
		(mid 336.691224 -233.390463)
		(end 336.408268 -233.46664)
		(width 0.0889)
		(layer "In2.Cu")
		(net "M_C_CPU0_SA_DQ<12>")
	)
	(arc
		(start 328.514202 -233.46664)
		(mid 328.231246 -233.390463)
		(end 327.94829 -233.46664)
		(width 0.0889)
		(layer "In2.Cu")
		(net "M_C_CPU0_SA_DQ<12>")
	)
	(arc
		(start 335.094072 -233.46664)
		(mid 334.811116 -233.390463)
		(end 334.52816 -233.46664)
		(width 0.0889)
		(layer "In2.Cu")
		(net "M_C_CPU0_SA_DQ<12>")
	)
	(arc
		(start 329.819762 -233.471466)
		(mid 329.636254 -233.51696)
		(end 329.454002 -233.46664)
		(width 0.0889)
		(layer "In2.Cu")
		(net "M_C_CPU0_SA_DQ<12>")
	)
	(arc
		(start 334.154018 -233.46664)
		(mid 333.871062 -233.390463)
		(end 333.588106 -233.46664)
		(width 0.0889)
		(layer "In2.Cu")
		(net "M_C_CPU0_SA_DQ<12>")
	)
	(arc
		(start 329.454002 -233.46664)
		(mid 329.171046 -233.390463)
		(end 328.88809 -233.46664)
		(width 0.0889)
		(layer "In2.Cu")
		(net "M_C_CPU0_SA_DQ<12>")
	)
	(arc
		(start 331.708252 -233.46664)
		(mid 331.526001 -233.51699)
		(end 331.342492 -233.471466)
		(width 0.0889)
		(layer "In2.Cu")
		(net "M_C_CPU0_SA_DQ<12>")
	)
	(arc
		(start 330.394056 -233.46664)
		(mid 330.1111 -233.390463)
		(end 329.828144 -233.46664)
		(width 0.0889)
		(layer "In2.Cu")
		(net "M_C_CPU0_SA_DQ<12>")
	)
	(arc
		(start 339.794088 -233.46664)
		(mid 339.511132 -233.390463)
		(end 339.228176 -233.46664)
		(width 0.0889)
		(layer "In2.Cu")
		(net "M_C_CPU0_SA_DQ<12>")
	)
	(arc
		(start 333.579724 -233.471466)
		(mid 333.396216 -233.51696)
		(end 333.213964 -233.46664)
		(width 0.0889)
		(layer "In2.Cu")
		(net "M_C_CPU0_SA_DQ<12>")
	)
	(arc
		(start 332.274164 -233.46664)
		(mid 331.991208 -233.390463)
		(end 331.708252 -233.46664)
		(width 0.0889)
		(layer "In2.Cu")
		(net "M_C_CPU0_SA_DQ<12>")
	)
	(arc
		(start 341.673942 -233.46664)
		(mid 341.390986 -233.390463)
		(end 341.10803 -233.46664)
		(width 0.0889)
		(layer "In2.Cu")
		(net "M_C_CPU0_SA_DQ<12>")
	)
	(arc
		(start 338.27974 -233.471466)
		(mid 338.096232 -233.51696)
		(end 337.91398 -233.46664)
		(width 0.0889)
		(layer "In2.Cu")
		(net "M_C_CPU0_SA_DQ<12>")
	)
	(segment
		(start 344.207846 -231.789986)
		(end 343.740994 -231.524048)
		(width 0.10668)
		(layer "F.Cu")
		(net "M_C_CPU0_SA_DQ<11>")
	)
	(segment
		(start 324.578218 -225.254312)
		(end 324.735698 -225.411792)
		(width 0.0889)
		(layer "In2.Cu")
		(net "M_C_CPU0_SA_DQ<11>")
	)
	(segment
		(start 338.854034 -231.201722)
		(end 338.862416 -231.196896)
		(width 0.0889)
		(layer "In2.Cu")
		(net "M_C_CPU0_SA_DQ<11>")
	)
	(segment
		(start 322.389754 -220.35643)
		(end 322.389754 -222.70593)
		(width 0.14478)
		(layer "In2.Cu")
		(net "M_C_CPU0_SA_DQ<11>")
	)
	(segment
		(start 329.819762 -231.196896)
		(end 329.828144 -231.201722)
		(width 0.0889)
		(layer "In2.Cu")
		(net "M_C_CPU0_SA_DQ<11>")
	)
	(segment
		(start 297.053508 -209.65033)
		(end 297.903392 -208.800446)
		(width 0.14478)
		(layer "In2.Cu")
		(net "M_C_CPU0_SA_DQ<11>")
	)
	(segment
		(start 310.284622 -208.810098)
		(end 313.873134 -212.39861)
		(width 0.14478)
		(layer "In2.Cu")
		(net "M_C_CPU0_SA_DQ<11>")
	)
	(segment
		(start 326.498712 -227.12934)
		(end 326.538336 -227.152454)
		(width 0.0889)
		(layer "In2.Cu")
		(net "M_C_CPU0_SA_DQ<11>")
	)
	(segment
		(start 334.519778 -231.196896)
		(end 334.52816 -231.201722)
		(width 0.0889)
		(layer "In2.Cu")
		(net "M_C_CPU0_SA_DQ<11>")
	)
	(segment
		(start 343.58707 -231.258618)
		(end 343.740994 -231.524048)
		(width 0.0889)
		(layer "In2.Cu")
		(net "M_C_CPU0_SA_DQ<11>")
	)
	(segment
		(start 301.11573 -208.800446)
		(end 301.97552 -209.660236)
		(width 0.14478)
		(layer "In2.Cu")
		(net "M_C_CPU0_SA_DQ<11>")
	)
	(segment
		(start 314.431934 -212.39861)
		(end 322.389754 -220.35643)
		(width 0.14478)
		(layer "In2.Cu")
		(net "M_C_CPU0_SA_DQ<11>")
	)
	(segment
		(start 301.97552 -209.660236)
		(end 304.718974 -209.660236)
		(width 0.14478)
		(layer "In2.Cu")
		(net "M_C_CPU0_SA_DQ<11>")
	)
	(segment
		(start 327.911968 -229.560628)
		(end 327.94829 -229.58171)
		(width 0.0889)
		(layer "In2.Cu")
		(net "M_C_CPU0_SA_DQ<11>")
	)
	(segment
		(start 327.47839 -228.771958)
		(end 327.508108 -228.78923)
		(width 0.0889)
		(layer "In2.Cu")
		(net "M_C_CPU0_SA_DQ<11>")
	)
	(segment
		(start 335.094072 -231.201722)
		(end 335.102454 -231.196896)
		(width 0.0889)
		(layer "In2.Cu")
		(net "M_C_CPU0_SA_DQ<11>")
	)
	(segment
		(start 338.27974 -231.196896)
		(end 338.288122 -231.201722)
		(width 0.0889)
		(layer "In2.Cu")
		(net "M_C_CPU0_SA_DQ<11>")
	)
	(segment
		(start 326.969374 -227.939854)
		(end 327.00849 -227.962714)
		(width 0.0889)
		(layer "In2.Cu")
		(net "M_C_CPU0_SA_DQ<11>")
	)
	(segment
		(start 328.381614 -230.37038)
		(end 328.41819 -230.391716)
		(width 0.0889)
		(layer "In2.Cu")
		(net "M_C_CPU0_SA_DQ<11>")
	)
	(segment
		(start 326.041258 -226.326446)
		(end 326.06869 -226.342448)
		(width 0.0889)
		(layer "In2.Cu")
		(net "M_C_CPU0_SA_DQ<11>")
	)
	(segment
		(start 328.41819 -230.391716)
		(end 328.44994 -230.410004)
		(width 0.0889)
		(layer "In2.Cu")
		(net "M_C_CPU0_SA_DQ<11>")
	)
	(segment
		(start 326.06869 -226.342448)
		(end 326.096376 -226.35845)
		(width 0.0889)
		(layer "In2.Cu")
		(net "M_C_CPU0_SA_DQ<11>")
	)
	(segment
		(start 325.59879 -225.533458)
		(end 325.630286 -225.551746)
		(width 0.0889)
		(layer "In2.Cu")
		(net "M_C_CPU0_SA_DQ<11>")
	)
	(segment
		(start 331.33411 -231.201722)
		(end 331.342492 -231.196896)
		(width 0.0889)
		(layer "In2.Cu")
		(net "M_C_CPU0_SA_DQ<11>")
	)
	(segment
		(start 297.903392 -208.800446)
		(end 301.11573 -208.800446)
		(width 0.14478)
		(layer "In2.Cu")
		(net "M_C_CPU0_SA_DQ<11>")
	)
	(segment
		(start 288.595308 -209.65033)
		(end 297.053508 -209.65033)
		(width 0.14478)
		(layer "In2.Cu")
		(net "M_C_CPU0_SA_DQ<11>")
	)
	(segment
		(start 330.394056 -231.201722)
		(end 330.402438 -231.196896)
		(width 0.0889)
		(layer "In2.Cu")
		(net "M_C_CPU0_SA_DQ<11>")
	)
	(segment
		(start 288.180018 -209.23504)
		(end 288.595308 -209.65033)
		(width 0.14478)
		(layer "In2.Cu")
		(net "M_C_CPU0_SA_DQ<11>")
	)
	(segment
		(start 324.735698 -225.411792)
		(end 325.32193 -225.411792)
		(width 0.0889)
		(layer "In2.Cu")
		(net "M_C_CPU0_SA_DQ<11>")
	)
	(segment
		(start 342.039702 -231.196896)
		(end 342.048084 -231.201722)
		(width 0.0889)
		(layer "In2.Cu")
		(net "M_C_CPU0_SA_DQ<11>")
	)
	(segment
		(start 327.94829 -229.58171)
		(end 327.980802 -229.600506)
		(width 0.0889)
		(layer "In2.Cu")
		(net "M_C_CPU0_SA_DQ<11>")
	)
	(segment
		(start 313.873134 -212.39861)
		(end 314.431934 -212.39861)
		(width 0.14478)
		(layer "In2.Cu")
		(net "M_C_CPU0_SA_DQ<11>")
	)
	(segment
		(start 325.55688 -225.509074)
		(end 325.59879 -225.533458)
		(width 0.0889)
		(layer "In2.Cu")
		(net "M_C_CPU0_SA_DQ<11>")
	)
	(segment
		(start 339.794088 -231.201722)
		(end 339.80247 -231.196896)
		(width 0.0889)
		(layer "In2.Cu")
		(net "M_C_CPU0_SA_DQ<11>")
	)
	(segment
		(start 326.538336 -227.152454)
		(end 326.576436 -227.174552)
		(width 0.0889)
		(layer "In2.Cu")
		(net "M_C_CPU0_SA_DQ<11>")
	)
	(segment
		(start 304.718974 -209.660236)
		(end 305.569112 -208.810098)
		(width 0.14478)
		(layer "In2.Cu")
		(net "M_C_CPU0_SA_DQ<11>")
	)
	(segment
		(start 325.32193 -225.411792)
		(end 325.55688 -225.509074)
		(width 0.0889)
		(layer "In2.Cu")
		(net "M_C_CPU0_SA_DQ<11>")
	)
	(segment
		(start 328.851768 -231.18064)
		(end 328.88809 -231.201722)
		(width 0.0889)
		(layer "In2.Cu")
		(net "M_C_CPU0_SA_DQ<11>")
	)
	(segment
		(start 333.579724 -231.196896)
		(end 333.588106 -231.201722)
		(width 0.0889)
		(layer "In2.Cu")
		(net "M_C_CPU0_SA_DQ<11>")
	)
	(segment
		(start 327.00849 -227.962714)
		(end 327.039986 -227.981002)
		(width 0.0889)
		(layer "In2.Cu")
		(net "M_C_CPU0_SA_DQ<11>")
	)
	(segment
		(start 324.578218 -224.894394)
		(end 324.578218 -225.254312)
		(width 0.0889)
		(layer "In2.Cu")
		(net "M_C_CPU0_SA_DQ<11>")
	)
	(segment
		(start 322.389754 -222.70593)
		(end 324.454774 -224.77095)
		(width 0.14478)
		(layer "In2.Cu")
		(net "M_C_CPU0_SA_DQ<11>")
	)
	(segment
		(start 324.454774 -224.77095)
		(end 324.578218 -224.894394)
		(width 0.0889)
		(layer "In2.Cu")
		(net "M_C_CPU0_SA_DQ<11>")
	)
	(segment
		(start 336.034126 -231.201722)
		(end 336.042508 -231.196896)
		(width 0.0889)
		(layer "In2.Cu")
		(net "M_C_CPU0_SA_DQ<11>")
	)
	(segment
		(start 305.569112 -208.810098)
		(end 310.284622 -208.810098)
		(width 0.14478)
		(layer "In2.Cu")
		(net "M_C_CPU0_SA_DQ<11>")
	)
	(segment
		(start 327.443084 -228.751384)
		(end 327.47839 -228.771958)
		(width 0.0889)
		(layer "In2.Cu")
		(net "M_C_CPU0_SA_DQ<11>")
	)
	(segment
		(start 342.979756 -231.196896)
		(end 342.988138 -231.201722)
		(width 0.0889)
		(layer "In2.Cu")
		(net "M_C_CPU0_SA_DQ<11>")
	)
	(segment
		(start 343.491312 -231.233218)
		(end 343.58707 -231.258618)
		(width 0.0889)
		(layer "In2.Cu")
		(net "M_C_CPU0_SA_DQ<11>")
	)
	(arc
		(start 331.342492 -231.196896)
		(mid 331.526 -231.151371)
		(end 331.708252 -231.201722)
		(width 0.0889)
		(layer "In2.Cu")
		(net "M_C_CPU0_SA_DQ<11>")
	)
	(arc
		(start 333.213964 -231.201722)
		(mid 333.396215 -231.151338)
		(end 333.579724 -231.196896)
		(width 0.0889)
		(layer "In2.Cu")
		(net "M_C_CPU0_SA_DQ<11>")
	)
	(arc
		(start 328.88809 -231.201722)
		(mid 329.171046 -231.277899)
		(end 329.454002 -231.201722)
		(width 0.0889)
		(layer "In2.Cu")
		(net "M_C_CPU0_SA_DQ<11>")
	)
	(arc
		(start 341.10803 -231.201722)
		(mid 341.390986 -231.277899)
		(end 341.673942 -231.201722)
		(width 0.0889)
		(layer "In2.Cu")
		(net "M_C_CPU0_SA_DQ<11>")
	)
	(arc
		(start 326.096376 -226.35845)
		(mid 326.213996 -226.492396)
		(end 326.256396 -226.665536)
		(width 0.0889)
		(layer "In2.Cu")
		(net "M_C_CPU0_SA_DQ<11>")
	)
	(arc
		(start 341.673942 -231.201722)
		(mid 341.856193 -231.151338)
		(end 342.039702 -231.196896)
		(width 0.0889)
		(layer "In2.Cu")
		(net "M_C_CPU0_SA_DQ<11>")
	)
	(arc
		(start 325.630286 -225.551746)
		(mid 325.744846 -225.684711)
		(end 325.786242 -225.855276)
		(width 0.0889)
		(layer "In2.Cu")
		(net "M_C_CPU0_SA_DQ<11>")
	)
	(arc
		(start 335.102454 -231.196896)
		(mid 335.285962 -231.151371)
		(end 335.468214 -231.201722)
		(width 0.0889)
		(layer "In2.Cu")
		(net "M_C_CPU0_SA_DQ<11>")
	)
	(arc
		(start 328.44994 -230.410004)
		(mid 328.564616 -230.543338)
		(end 328.605896 -230.714296)
		(width 0.0889)
		(layer "In2.Cu")
		(net "M_C_CPU0_SA_DQ<11>")
	)
	(arc
		(start 329.828144 -231.201722)
		(mid 330.1111 -231.277899)
		(end 330.394056 -231.201722)
		(width 0.0889)
		(layer "In2.Cu")
		(net "M_C_CPU0_SA_DQ<11>")
	)
	(arc
		(start 327.666096 -229.094792)
		(mid 327.73145 -229.3581)
		(end 327.911968 -229.560628)
		(width 0.0889)
		(layer "In2.Cu")
		(net "M_C_CPU0_SA_DQ<11>")
	)
	(arc
		(start 337.91398 -231.201722)
		(mid 338.096231 -231.151338)
		(end 338.27974 -231.196896)
		(width 0.0889)
		(layer "In2.Cu")
		(net "M_C_CPU0_SA_DQ<11>")
	)
	(arc
		(start 332.648052 -231.201722)
		(mid 332.931008 -231.277899)
		(end 333.213964 -231.201722)
		(width 0.0889)
		(layer "In2.Cu")
		(net "M_C_CPU0_SA_DQ<11>")
	)
	(arc
		(start 338.288122 -231.201722)
		(mid 338.571078 -231.277899)
		(end 338.854034 -231.201722)
		(width 0.0889)
		(layer "In2.Cu")
		(net "M_C_CPU0_SA_DQ<11>")
	)
	(arc
		(start 336.97418 -231.201722)
		(mid 337.161124 -231.151433)
		(end 337.348068 -231.201722)
		(width 0.0889)
		(layer "In2.Cu")
		(net "M_C_CPU0_SA_DQ<11>")
	)
	(arc
		(start 328.605896 -230.714296)
		(mid 328.671132 -230.977887)
		(end 328.851768 -231.18064)
		(width 0.0889)
		(layer "In2.Cu")
		(net "M_C_CPU0_SA_DQ<11>")
	)
	(arc
		(start 327.195942 -228.284786)
		(mid 327.261642 -228.548747)
		(end 327.443084 -228.751384)
		(width 0.0889)
		(layer "In2.Cu")
		(net "M_C_CPU0_SA_DQ<11>")
	)
	(arc
		(start 339.228176 -231.201722)
		(mid 339.511132 -231.277899)
		(end 339.794088 -231.201722)
		(width 0.0889)
		(layer "In2.Cu")
		(net "M_C_CPU0_SA_DQ<11>")
	)
	(arc
		(start 325.786242 -225.855276)
		(mid 325.854292 -226.123058)
		(end 326.041258 -226.326446)
		(width 0.0889)
		(layer "In2.Cu")
		(net "M_C_CPU0_SA_DQ<11>")
	)
	(arc
		(start 339.80247 -231.196896)
		(mid 339.985978 -231.151371)
		(end 340.16823 -231.201722)
		(width 0.0889)
		(layer "In2.Cu")
		(net "M_C_CPU0_SA_DQ<11>")
	)
	(arc
		(start 331.708252 -231.201722)
		(mid 331.991208 -231.277899)
		(end 332.274164 -231.201722)
		(width 0.0889)
		(layer "In2.Cu")
		(net "M_C_CPU0_SA_DQ<11>")
	)
	(arc
		(start 327.508108 -228.78923)
		(mid 327.624289 -228.922789)
		(end 327.666096 -229.094792)
		(width 0.0889)
		(layer "In2.Cu")
		(net "M_C_CPU0_SA_DQ<11>")
	)
	(arc
		(start 330.402438 -231.196896)
		(mid 330.585946 -231.151371)
		(end 330.768198 -231.201722)
		(width 0.0889)
		(layer "In2.Cu")
		(net "M_C_CPU0_SA_DQ<11>")
	)
	(arc
		(start 340.16823 -231.201722)
		(mid 340.451186 -231.277899)
		(end 340.734142 -231.201722)
		(width 0.0889)
		(layer "In2.Cu")
		(net "M_C_CPU0_SA_DQ<11>")
	)
	(arc
		(start 342.048084 -231.201722)
		(mid 342.33104 -231.277899)
		(end 342.613996 -231.201722)
		(width 0.0889)
		(layer "In2.Cu")
		(net "M_C_CPU0_SA_DQ<11>")
	)
	(arc
		(start 326.726042 -227.474526)
		(mid 326.79036 -227.737195)
		(end 326.969374 -227.939854)
		(width 0.0889)
		(layer "In2.Cu")
		(net "M_C_CPU0_SA_DQ<11>")
	)
	(arc
		(start 342.988138 -231.201722)
		(mid 343.235998 -231.276805)
		(end 343.491312 -231.233218)
		(width 0.0889)
		(layer "In2.Cu")
		(net "M_C_CPU0_SA_DQ<11>")
	)
	(arc
		(start 326.256396 -226.665536)
		(mid 326.320616 -226.927192)
		(end 326.498712 -227.12934)
		(width 0.0889)
		(layer "In2.Cu")
		(net "M_C_CPU0_SA_DQ<11>")
	)
	(arc
		(start 328.135742 -229.904036)
		(mid 328.200978 -230.167627)
		(end 328.381614 -230.37038)
		(width 0.0889)
		(layer "In2.Cu")
		(net "M_C_CPU0_SA_DQ<11>")
	)
	(arc
		(start 340.734142 -231.201722)
		(mid 340.921086 -231.151433)
		(end 341.10803 -231.201722)
		(width 0.0889)
		(layer "In2.Cu")
		(net "M_C_CPU0_SA_DQ<11>")
	)
	(arc
		(start 337.348068 -231.201722)
		(mid 337.631024 -231.277899)
		(end 337.91398 -231.201722)
		(width 0.0889)
		(layer "In2.Cu")
		(net "M_C_CPU0_SA_DQ<11>")
	)
	(arc
		(start 329.454002 -231.201722)
		(mid 329.636253 -231.151338)
		(end 329.819762 -231.196896)
		(width 0.0889)
		(layer "In2.Cu")
		(net "M_C_CPU0_SA_DQ<11>")
	)
	(arc
		(start 334.52816 -231.201722)
		(mid 334.811116 -231.277899)
		(end 335.094072 -231.201722)
		(width 0.0889)
		(layer "In2.Cu")
		(net "M_C_CPU0_SA_DQ<11>")
	)
	(arc
		(start 335.468214 -231.201722)
		(mid 335.75117 -231.277899)
		(end 336.034126 -231.201722)
		(width 0.0889)
		(layer "In2.Cu")
		(net "M_C_CPU0_SA_DQ<11>")
	)
	(arc
		(start 333.588106 -231.201722)
		(mid 333.871062 -231.277899)
		(end 334.154018 -231.201722)
		(width 0.0889)
		(layer "In2.Cu")
		(net "M_C_CPU0_SA_DQ<11>")
	)
	(arc
		(start 336.408268 -231.201722)
		(mid 336.691224 -231.277899)
		(end 336.97418 -231.201722)
		(width 0.0889)
		(layer "In2.Cu")
		(net "M_C_CPU0_SA_DQ<11>")
	)
	(arc
		(start 326.576436 -227.174552)
		(mid 326.686656 -227.306882)
		(end 326.726042 -227.474526)
		(width 0.0889)
		(layer "In2.Cu")
		(net "M_C_CPU0_SA_DQ<11>")
	)
	(arc
		(start 342.613996 -231.201722)
		(mid 342.796247 -231.151338)
		(end 342.979756 -231.196896)
		(width 0.0889)
		(layer "In2.Cu")
		(net "M_C_CPU0_SA_DQ<11>")
	)
	(arc
		(start 330.768198 -231.201722)
		(mid 331.051154 -231.277899)
		(end 331.33411 -231.201722)
		(width 0.0889)
		(layer "In2.Cu")
		(net "M_C_CPU0_SA_DQ<11>")
	)
	(arc
		(start 338.862416 -231.196896)
		(mid 339.045924 -231.151371)
		(end 339.228176 -231.201722)
		(width 0.0889)
		(layer "In2.Cu")
		(net "M_C_CPU0_SA_DQ<11>")
	)
	(arc
		(start 332.274164 -231.201722)
		(mid 332.461108 -231.151433)
		(end 332.648052 -231.201722)
		(width 0.0889)
		(layer "In2.Cu")
		(net "M_C_CPU0_SA_DQ<11>")
	)
	(arc
		(start 336.042508 -231.196896)
		(mid 336.226016 -231.151371)
		(end 336.408268 -231.201722)
		(width 0.0889)
		(layer "In2.Cu")
		(net "M_C_CPU0_SA_DQ<11>")
	)
	(arc
		(start 334.154018 -231.201722)
		(mid 334.336269 -231.151338)
		(end 334.519778 -231.196896)
		(width 0.0889)
		(layer "In2.Cu")
		(net "M_C_CPU0_SA_DQ<11>")
	)
	(arc
		(start 327.980802 -229.600506)
		(mid 328.094731 -229.733653)
		(end 328.135742 -229.904036)
		(width 0.0889)
		(layer "In2.Cu")
		(net "M_C_CPU0_SA_DQ<11>")
	)
	(arc
		(start 327.039986 -227.981002)
		(mid 327.154605 -228.11408)
		(end 327.195942 -228.284786)
		(width 0.0889)
		(layer "In2.Cu")
		(net "M_C_CPU0_SA_DQ<11>")
	)
	(segment
		(start 342.797892 -230.97998)
		(end 342.33104 -230.714296)
		(width 0.10668)
		(layer "F.Cu")
		(net "M_C_CPU0_SA_DQ<10>")
	)
	(segment
		(start 289.963098 -207.555338)
		(end 289.963098 -207.797146)
		(width 0.14478)
		(layer "In2.Cu")
		(net "M_C_CPU0_SA_DQ<10>")
	)
	(segment
		(start 337.452462 -230.38689)
		(end 337.44408 -230.391716)
		(width 0.0889)
		(layer "In2.Cu")
		(net "M_C_CPU0_SA_DQ<10>")
	)
	(segment
		(start 326.538082 -225.53168)
		(end 326.504808 -225.512376)
		(width 0.0889)
		(layer "In2.Cu")
		(net "M_C_CPU0_SA_DQ<10>")
	)
	(segment
		(start 324.591172 -223.586548)
		(end 323.314314 -222.30969)
		(width 0.14478)
		(layer "In2.Cu")
		(net "M_C_CPU0_SA_DQ<10>")
	)
	(segment
		(start 314.792614 -211.45119)
		(end 314.264548 -211.45119)
		(width 0.14478)
		(layer "In2.Cu")
		(net "M_C_CPU0_SA_DQ<10>")
	)
	(segment
		(start 339.698076 -230.391716)
		(end 339.689694 -230.38689)
		(width 0.0889)
		(layer "In2.Cu")
		(net "M_C_CPU0_SA_DQ<10>")
	)
	(segment
		(start 326.106282 -224.742756)
		(end 326.068436 -224.720912)
		(width 0.0889)
		(layer "In2.Cu")
		(net "M_C_CPU0_SA_DQ<10>")
	)
	(segment
		(start 298.003468 -207.110076)
		(end 297.15333 -207.960214)
		(width 0.14478)
		(layer "In2.Cu")
		(net "M_C_CPU0_SA_DQ<10>")
	)
	(segment
		(start 325.472806 -223.84639)
		(end 324.851014 -223.84639)
		(width 0.0889)
		(layer "In2.Cu")
		(net "M_C_CPU0_SA_DQ<10>")
	)
	(segment
		(start 331.238098 -230.391716)
		(end 331.229716 -230.38689)
		(width 0.0889)
		(layer "In2.Cu")
		(net "M_C_CPU0_SA_DQ<10>")
	)
	(segment
		(start 305.541934 -207.110076)
		(end 304.691796 -207.960214)
		(width 0.14478)
		(layer "In2.Cu")
		(net "M_C_CPU0_SA_DQ<10>")
	)
	(segment
		(start 335.938114 -230.391716)
		(end 335.929732 -230.38689)
		(width 0.0889)
		(layer "In2.Cu")
		(net "M_C_CPU0_SA_DQ<10>")
	)
	(segment
		(start 328.88809 -229.58171)
		(end 328.851768 -229.560628)
		(width 0.0889)
		(layer "In2.Cu")
		(net "M_C_CPU0_SA_DQ<10>")
	)
	(segment
		(start 323.314314 -222.30969)
		(end 323.314314 -219.97289)
		(width 0.14478)
		(layer "In2.Cu")
		(net "M_C_CPU0_SA_DQ<10>")
	)
	(segment
		(start 336.878168 -230.391716)
		(end 336.869786 -230.38689)
		(width 0.0889)
		(layer "In2.Cu")
		(net "M_C_CPU0_SA_DQ<10>")
	)
	(segment
		(start 290.356544 -207.39227)
		(end 290.126166 -207.39227)
		(width 0.14478)
		(layer "In2.Cu")
		(net "M_C_CPU0_SA_DQ<10>")
	)
	(segment
		(start 323.314314 -219.97289)
		(end 314.792614 -211.45119)
		(width 0.14478)
		(layer "In2.Cu")
		(net "M_C_CPU0_SA_DQ<10>")
	)
	(segment
		(start 328.41819 -228.771704)
		(end 328.379074 -228.748844)
		(width 0.0889)
		(layer "In2.Cu")
		(net "M_C_CPU0_SA_DQ<10>")
	)
	(segment
		(start 326.571864 -225.551238)
		(end 326.538082 -225.53168)
		(width 0.0889)
		(layer "In2.Cu")
		(net "M_C_CPU0_SA_DQ<10>")
	)
	(segment
		(start 304.691796 -207.960214)
		(end 301.892716 -207.960214)
		(width 0.14478)
		(layer "In2.Cu")
		(net "M_C_CPU0_SA_DQ<10>")
	)
	(segment
		(start 341.212424 -230.38689)
		(end 341.204042 -230.391716)
		(width 0.0889)
		(layer "In2.Cu")
		(net "M_C_CPU0_SA_DQ<10>")
	)
	(segment
		(start 340.63813 -230.391716)
		(end 340.629748 -230.38689)
		(width 0.0889)
		(layer "In2.Cu")
		(net "M_C_CPU0_SA_DQ<10>")
	)
	(segment
		(start 325.600822 -223.913192)
		(end 325.503794 -223.855026)
		(width 0.0889)
		(layer "In2.Cu")
		(net "M_C_CPU0_SA_DQ<10>")
	)
	(segment
		(start 288.605214 -207.960214)
		(end 288.180018 -207.535018)
		(width 0.14478)
		(layer "In2.Cu")
		(net "M_C_CPU0_SA_DQ<10>")
	)
	(segment
		(start 328.921618 -229.601268)
		(end 328.88809 -229.58171)
		(width 0.0889)
		(layer "In2.Cu")
		(net "M_C_CPU0_SA_DQ<10>")
	)
	(segment
		(start 301.042832 -207.110076)
		(end 298.003468 -207.110076)
		(width 0.14478)
		(layer "In2.Cu")
		(net "M_C_CPU0_SA_DQ<10>")
	)
	(segment
		(start 290.519612 -207.555338)
		(end 290.356544 -207.39227)
		(width 0.14478)
		(layer "In2.Cu")
		(net "M_C_CPU0_SA_DQ<10>")
	)
	(segment
		(start 301.892716 -207.960214)
		(end 301.892716 -207.95996)
		(width 0.14478)
		(layer "In2.Cu")
		(net "M_C_CPU0_SA_DQ<10>")
	)
	(segment
		(start 328.44994 -228.789992)
		(end 328.41819 -228.771704)
		(width 0.0889)
		(layer "In2.Cu")
		(net "M_C_CPU0_SA_DQ<10>")
	)
	(segment
		(start 290.519612 -207.797146)
		(end 290.519612 -207.555338)
		(width 0.14478)
		(layer "In2.Cu")
		(net "M_C_CPU0_SA_DQ<10>")
	)
	(segment
		(start 290.68268 -207.960214)
		(end 290.519612 -207.797146)
		(width 0.14478)
		(layer "In2.Cu")
		(net "M_C_CPU0_SA_DQ<10>")
	)
	(segment
		(start 301.892716 -207.95996)
		(end 301.042832 -207.110076)
		(width 0.14478)
		(layer "In2.Cu")
		(net "M_C_CPU0_SA_DQ<10>")
	)
	(segment
		(start 309.923434 -207.110076)
		(end 305.541934 -207.110076)
		(width 0.14478)
		(layer "In2.Cu")
		(net "M_C_CPU0_SA_DQ<10>")
	)
	(segment
		(start 333.6925 -230.38689)
		(end 333.684118 -230.391716)
		(width 0.0889)
		(layer "In2.Cu")
		(net "M_C_CPU0_SA_DQ<10>")
	)
	(segment
		(start 329.358244 -230.391716)
		(end 329.321668 -230.37038)
		(width 0.0889)
		(layer "In2.Cu")
		(net "M_C_CPU0_SA_DQ<10>")
	)
	(segment
		(start 290.126166 -207.39227)
		(end 289.963098 -207.555338)
		(width 0.14478)
		(layer "In2.Cu")
		(net "M_C_CPU0_SA_DQ<10>")
	)
	(segment
		(start 327.513696 -227.171758)
		(end 327.47839 -227.151184)
		(width 0.0889)
		(layer "In2.Cu")
		(net "M_C_CPU0_SA_DQ<10>")
	)
	(segment
		(start 332.752446 -230.38689)
		(end 332.744064 -230.391716)
		(width 0.0889)
		(layer "In2.Cu")
		(net "M_C_CPU0_SA_DQ<10>")
	)
	(segment
		(start 289.963098 -207.797146)
		(end 289.80003 -207.960214)
		(width 0.14478)
		(layer "In2.Cu")
		(net "M_C_CPU0_SA_DQ<10>")
	)
	(segment
		(start 327.97877 -227.979478)
		(end 327.94829 -227.961698)
		(width 0.0889)
		(layer "In2.Cu")
		(net "M_C_CPU0_SA_DQ<10>")
	)
	(segment
		(start 314.264548 -211.45119)
		(end 309.923434 -207.110076)
		(width 0.14478)
		(layer "In2.Cu")
		(net "M_C_CPU0_SA_DQ<10>")
	)
	(segment
		(start 327.47839 -227.151184)
		(end 327.435972 -227.126546)
		(width 0.0889)
		(layer "In2.Cu")
		(net "M_C_CPU0_SA_DQ<10>")
	)
	(segment
		(start 342.177116 -230.448866)
		(end 342.081104 -230.423466)
		(width 0.0889)
		(layer "In2.Cu")
		(net "M_C_CPU0_SA_DQ<10>")
	)
	(segment
		(start 289.80003 -207.960214)
		(end 288.605214 -207.960214)
		(width 0.14478)
		(layer "In2.Cu")
		(net "M_C_CPU0_SA_DQ<10>")
	)
	(segment
		(start 327.036938 -226.356672)
		(end 327.008744 -226.340416)
		(width 0.0889)
		(layer "In2.Cu")
		(net "M_C_CPU0_SA_DQ<10>")
	)
	(segment
		(start 326.068436 -224.720912)
		(end 326.0217 -224.693734)
		(width 0.0889)
		(layer "In2.Cu")
		(net "M_C_CPU0_SA_DQ<10>")
	)
	(segment
		(start 297.15333 -207.960214)
		(end 290.68268 -207.960214)
		(width 0.14478)
		(layer "In2.Cu")
		(net "M_C_CPU0_SA_DQ<10>")
	)
	(segment
		(start 342.33104 -230.714296)
		(end 342.177116 -230.448866)
		(width 0.0889)
		(layer "In2.Cu")
		(net "M_C_CPU0_SA_DQ<10>")
	)
	(segment
		(start 327.008744 -226.340416)
		(end 326.96912 -226.317556)
		(width 0.0889)
		(layer "In2.Cu")
		(net "M_C_CPU0_SA_DQ<10>")
	)
	(segment
		(start 324.851014 -223.84639)
		(end 324.591172 -223.586548)
		(width 0.0889)
		(layer "In2.Cu")
		(net "M_C_CPU0_SA_DQ<10>")
	)
	(segment
		(start 332.178152 -230.391716)
		(end 332.16977 -230.38689)
		(width 0.0889)
		(layer "In2.Cu")
		(net "M_C_CPU0_SA_DQ<10>")
	)
	(segment
		(start 327.94829 -227.961698)
		(end 327.911968 -227.940616)
		(width 0.0889)
		(layer "In2.Cu")
		(net "M_C_CPU0_SA_DQ<10>")
	)
	(arc
		(start 334.99806 -230.391716)
		(mid 334.811116 -230.341461)
		(end 334.624172 -230.391716)
		(width 0.0889)
		(layer "In2.Cu")
		(net "M_C_CPU0_SA_DQ<10>")
	)
	(arc
		(start 334.05826 -230.391716)
		(mid 333.876009 -230.341366)
		(end 333.6925 -230.38689)
		(width 0.0889)
		(layer "In2.Cu")
		(net "M_C_CPU0_SA_DQ<10>")
	)
	(arc
		(start 327.435972 -227.126546)
		(mid 327.259285 -226.924258)
		(end 327.195942 -226.66325)
		(width 0.0889)
		(layer "In2.Cu")
		(net "M_C_CPU0_SA_DQ<10>")
	)
	(arc
		(start 337.818222 -230.391716)
		(mid 337.635971 -230.341366)
		(end 337.452462 -230.38689)
		(width 0.0889)
		(layer "In2.Cu")
		(net "M_C_CPU0_SA_DQ<10>")
	)
	(arc
		(start 331.229716 -230.38689)
		(mid 331.046208 -230.341396)
		(end 330.863956 -230.391716)
		(width 0.0889)
		(layer "In2.Cu")
		(net "M_C_CPU0_SA_DQ<10>")
	)
	(arc
		(start 333.684118 -230.391716)
		(mid 333.401162 -230.467859)
		(end 333.118206 -230.391716)
		(width 0.0889)
		(layer "In2.Cu")
		(net "M_C_CPU0_SA_DQ<10>")
	)
	(arc
		(start 330.298044 -230.391716)
		(mid 330.1111 -230.341461)
		(end 329.924156 -230.391716)
		(width 0.0889)
		(layer "In2.Cu")
		(net "M_C_CPU0_SA_DQ<10>")
	)
	(arc
		(start 326.256142 -225.042984)
		(mid 326.216684 -224.875177)
		(end 326.106282 -224.742756)
		(width 0.0889)
		(layer "In2.Cu")
		(net "M_C_CPU0_SA_DQ<10>")
	)
	(arc
		(start 326.96912 -226.317556)
		(mid 326.790716 -226.115468)
		(end 326.726042 -225.853752)
		(width 0.0889)
		(layer "In2.Cu")
		(net "M_C_CPU0_SA_DQ<10>")
	)
	(arc
		(start 325.503794 -223.855026)
		(mid 325.488885 -223.848619)
		(end 325.472806 -223.84639)
		(width 0.0889)
		(layer "In2.Cu")
		(net "M_C_CPU0_SA_DQ<10>")
	)
	(arc
		(start 338.758022 -230.391716)
		(mid 338.571078 -230.341461)
		(end 338.384134 -230.391716)
		(width 0.0889)
		(layer "In2.Cu")
		(net "M_C_CPU0_SA_DQ<10>")
	)
	(arc
		(start 339.323934 -230.391716)
		(mid 339.040978 -230.467859)
		(end 338.758022 -230.391716)
		(width 0.0889)
		(layer "In2.Cu")
		(net "M_C_CPU0_SA_DQ<10>")
	)
	(arc
		(start 340.629748 -230.38689)
		(mid 340.44624 -230.341396)
		(end 340.263988 -230.391716)
		(width 0.0889)
		(layer "In2.Cu")
		(net "M_C_CPU0_SA_DQ<10>")
	)
	(arc
		(start 326.504808 -225.512376)
		(mid 326.321849 -225.308734)
		(end 326.256142 -225.042984)
		(width 0.0889)
		(layer "In2.Cu")
		(net "M_C_CPU0_SA_DQ<10>")
	)
	(arc
		(start 327.195942 -226.66325)
		(mid 327.153868 -226.490559)
		(end 327.036938 -226.356672)
		(width 0.0889)
		(layer "In2.Cu")
		(net "M_C_CPU0_SA_DQ<10>")
	)
	(arc
		(start 333.118206 -230.391716)
		(mid 332.935955 -230.341366)
		(end 332.752446 -230.38689)
		(width 0.0889)
		(layer "In2.Cu")
		(net "M_C_CPU0_SA_DQ<10>")
	)
	(arc
		(start 326.726042 -225.853752)
		(mid 326.685169 -225.684035)
		(end 326.571864 -225.551238)
		(width 0.0889)
		(layer "In2.Cu")
		(net "M_C_CPU0_SA_DQ<10>")
	)
	(arc
		(start 342.081104 -230.423466)
		(mid 341.825896 -230.466923)
		(end 341.578184 -230.391716)
		(width 0.0889)
		(layer "In2.Cu")
		(net "M_C_CPU0_SA_DQ<10>")
	)
	(arc
		(start 328.379074 -228.748844)
		(mid 328.200261 -228.546494)
		(end 328.135742 -228.284278)
		(width 0.0889)
		(layer "In2.Cu")
		(net "M_C_CPU0_SA_DQ<10>")
	)
	(arc
		(start 334.624172 -230.391716)
		(mid 334.341216 -230.467859)
		(end 334.05826 -230.391716)
		(width 0.0889)
		(layer "In2.Cu")
		(net "M_C_CPU0_SA_DQ<10>")
	)
	(arc
		(start 332.16977 -230.38689)
		(mid 331.986262 -230.341396)
		(end 331.80401 -230.391716)
		(width 0.0889)
		(layer "In2.Cu")
		(net "M_C_CPU0_SA_DQ<10>")
	)
	(arc
		(start 329.075796 -229.904036)
		(mid 329.035034 -229.734152)
		(end 328.921618 -229.601268)
		(width 0.0889)
		(layer "In2.Cu")
		(net "M_C_CPU0_SA_DQ<10>")
	)
	(arc
		(start 335.929732 -230.38689)
		(mid 335.746224 -230.341396)
		(end 335.563972 -230.391716)
		(width 0.0889)
		(layer "In2.Cu")
		(net "M_C_CPU0_SA_DQ<10>")
	)
	(arc
		(start 328.135742 -228.284278)
		(mid 328.094193 -228.112856)
		(end 327.97877 -227.979478)
		(width 0.0889)
		(layer "In2.Cu")
		(net "M_C_CPU0_SA_DQ<10>")
	)
	(arc
		(start 336.869786 -230.38689)
		(mid 336.686278 -230.341396)
		(end 336.504026 -230.391716)
		(width 0.0889)
		(layer "In2.Cu")
		(net "M_C_CPU0_SA_DQ<10>")
	)
	(arc
		(start 332.744064 -230.391716)
		(mid 332.461108 -230.467859)
		(end 332.178152 -230.391716)
		(width 0.0889)
		(layer "In2.Cu")
		(net "M_C_CPU0_SA_DQ<10>")
	)
	(arc
		(start 337.44408 -230.391716)
		(mid 337.161124 -230.467859)
		(end 336.878168 -230.391716)
		(width 0.0889)
		(layer "In2.Cu")
		(net "M_C_CPU0_SA_DQ<10>")
	)
	(arc
		(start 341.578184 -230.391716)
		(mid 341.395933 -230.341366)
		(end 341.212424 -230.38689)
		(width 0.0889)
		(layer "In2.Cu")
		(net "M_C_CPU0_SA_DQ<10>")
	)
	(arc
		(start 327.911968 -227.940616)
		(mid 327.731138 -227.737534)
		(end 327.666096 -227.47351)
		(width 0.0889)
		(layer "In2.Cu")
		(net "M_C_CPU0_SA_DQ<10>")
	)
	(arc
		(start 331.80401 -230.391716)
		(mid 331.521054 -230.467859)
		(end 331.238098 -230.391716)
		(width 0.0889)
		(layer "In2.Cu")
		(net "M_C_CPU0_SA_DQ<10>")
	)
	(arc
		(start 340.263988 -230.391716)
		(mid 339.981032 -230.467859)
		(end 339.698076 -230.391716)
		(width 0.0889)
		(layer "In2.Cu")
		(net "M_C_CPU0_SA_DQ<10>")
	)
	(arc
		(start 327.666096 -227.47351)
		(mid 327.625905 -227.304436)
		(end 327.513696 -227.171758)
		(width 0.0889)
		(layer "In2.Cu")
		(net "M_C_CPU0_SA_DQ<10>")
	)
	(arc
		(start 328.851768 -229.560628)
		(mid 328.671116 -229.357883)
		(end 328.605896 -229.094284)
		(width 0.0889)
		(layer "In2.Cu")
		(net "M_C_CPU0_SA_DQ<10>")
	)
	(arc
		(start 329.924156 -230.391716)
		(mid 329.6412 -230.467859)
		(end 329.358244 -230.391716)
		(width 0.0889)
		(layer "In2.Cu")
		(net "M_C_CPU0_SA_DQ<10>")
	)
	(arc
		(start 341.204042 -230.391716)
		(mid 340.921086 -230.467859)
		(end 340.63813 -230.391716)
		(width 0.0889)
		(layer "In2.Cu")
		(net "M_C_CPU0_SA_DQ<10>")
	)
	(arc
		(start 339.689694 -230.38689)
		(mid 339.506186 -230.341396)
		(end 339.323934 -230.391716)
		(width 0.0889)
		(layer "In2.Cu")
		(net "M_C_CPU0_SA_DQ<10>")
	)
	(arc
		(start 325.785734 -224.234248)
		(mid 325.736194 -224.049009)
		(end 325.600822 -223.913192)
		(width 0.0889)
		(layer "In2.Cu")
		(net "M_C_CPU0_SA_DQ<10>")
	)
	(arc
		(start 338.384134 -230.391716)
		(mid 338.101178 -230.467859)
		(end 337.818222 -230.391716)
		(width 0.0889)
		(layer "In2.Cu")
		(net "M_C_CPU0_SA_DQ<10>")
	)
	(arc
		(start 330.863956 -230.391716)
		(mid 330.581 -230.467859)
		(end 330.298044 -230.391716)
		(width 0.0889)
		(layer "In2.Cu")
		(net "M_C_CPU0_SA_DQ<10>")
	)
	(arc
		(start 326.0217 -224.693734)
		(mid 325.848189 -224.49251)
		(end 325.785734 -224.234248)
		(width 0.0889)
		(layer "In2.Cu")
		(net "M_C_CPU0_SA_DQ<10>")
	)
	(arc
		(start 329.321668 -230.37038)
		(mid 329.141016 -230.167635)
		(end 329.075796 -229.904036)
		(width 0.0889)
		(layer "In2.Cu")
		(net "M_C_CPU0_SA_DQ<10>")
	)
	(arc
		(start 336.504026 -230.391716)
		(mid 336.22107 -230.467859)
		(end 335.938114 -230.391716)
		(width 0.0889)
		(layer "In2.Cu")
		(net "M_C_CPU0_SA_DQ<10>")
	)
	(arc
		(start 335.563972 -230.391716)
		(mid 335.281016 -230.467859)
		(end 334.99806 -230.391716)
		(width 0.0889)
		(layer "In2.Cu")
		(net "M_C_CPU0_SA_DQ<10>")
	)
	(arc
		(start 328.605896 -229.094284)
		(mid 328.564641 -228.923313)
		(end 328.44994 -228.789992)
		(width 0.0889)
		(layer "In2.Cu")
		(net "M_C_CPU0_SA_DQ<10>")
	)
	(segment
		(start 342.327992 -225.310192)
		(end 341.86114 -225.044254)
		(width 0.10668)
		(layer "F.Cu")
		(net "M_C_CPU0_SA_DQ<0>")
	)
	(segment
		(start 297.745404 -196.910198)
		(end 297.515026 -196.910198)
		(width 0.14478)
		(layer "In2.Cu")
		(net "M_C_CPU0_SA_DQ<0>")
	)
	(segment
		(start 292.705028 -196.910198)
		(end 292.280086 -197.33514)
		(width 0.14478)
		(layer "In2.Cu")
		(net "M_C_CPU0_SA_DQ<0>")
	)
	(segment
		(start 305.941984 -196.232018)
		(end 305.778916 -196.06895)
		(width 0.14478)
		(layer "In2.Cu")
		(net "M_C_CPU0_SA_DQ<0>")
	)
	(segment
		(start 330.39431 -222.12681)
		(end 330.188316 -221.920816)
		(width 0.0889)
		(layer "In2.Cu")
		(net "M_C_CPU0_SA_DQ<0>")
	)
	(segment
		(start 298.628054 -196.910198)
		(end 298.464986 -196.74713)
		(width 0.14478)
		(layer "In2.Cu")
		(net "M_C_CPU0_SA_DQ<0>")
	)
	(segment
		(start 297.908472 -196.379338)
		(end 297.908472 -196.74713)
		(width 0.14478)
		(layer "In2.Cu")
		(net "M_C_CPU0_SA_DQ<0>")
	)
	(segment
		(start 297.908472 -196.74713)
		(end 297.745404 -196.910198)
		(width 0.14478)
		(layer "In2.Cu")
		(net "M_C_CPU0_SA_DQ<0>")
	)
	(segment
		(start 297.18889 -196.21627)
		(end 296.958512 -196.21627)
		(width 0.14478)
		(layer "In2.Cu")
		(net "M_C_CPU0_SA_DQ<0>")
	)
	(segment
		(start 304.43551 -196.06895)
		(end 304.272442 -196.232018)
		(width 0.14478)
		(layer "In2.Cu")
		(net "M_C_CPU0_SA_DQ<0>")
	)
	(segment
		(start 331.843126 -224.579688)
		(end 331.80401 -224.556828)
		(width 0.0889)
		(layer "In2.Cu")
		(net "M_C_CPU0_SA_DQ<0>")
	)
	(segment
		(start 330.863956 -222.936816)
		(end 330.833476 -222.919036)
		(width 0.0889)
		(layer "In2.Cu")
		(net "M_C_CPU0_SA_DQ<0>")
	)
	(segment
		(start 339.80247 -225.37166)
		(end 339.794088 -225.366834)
		(width 0.0889)
		(layer "In2.Cu")
		(net "M_C_CPU0_SA_DQ<0>")
	)
	(segment
		(start 298.07154 -196.21627)
		(end 297.908472 -196.379338)
		(width 0.14478)
		(layer "In2.Cu")
		(net "M_C_CPU0_SA_DQ<0>")
	)
	(segment
		(start 293.695374 -196.74713)
		(end 293.532306 -196.910198)
		(width 0.14478)
		(layer "In2.Cu")
		(net "M_C_CPU0_SA_DQ<0>")
	)
	(segment
		(start 338.288122 -225.366834)
		(end 338.27974 -225.37166)
		(width 0.0889)
		(layer "In2.Cu")
		(net "M_C_CPU0_SA_DQ<0>")
	)
	(segment
		(start 293.858442 -196.450712)
		(end 293.695374 -196.61378)
		(width 0.14478)
		(layer "In2.Cu")
		(net "M_C_CPU0_SA_DQ<0>")
	)
	(segment
		(start 330.188316 -221.653608)
		(end 330.466954 -221.37497)
		(width 0.0889)
		(layer "In2.Cu")
		(net "M_C_CPU0_SA_DQ<0>")
	)
	(segment
		(start 338.862416 -225.37166)
		(end 338.854034 -225.366834)
		(width 0.0889)
		(layer "In2.Cu")
		(net "M_C_CPU0_SA_DQ<0>")
	)
	(segment
		(start 334.52816 -225.366834)
		(end 334.519778 -225.37166)
		(width 0.0889)
		(layer "In2.Cu")
		(net "M_C_CPU0_SA_DQ<0>")
	)
	(segment
		(start 304.828956 -196.74713)
		(end 304.828956 -196.232018)
		(width 0.14478)
		(layer "In2.Cu")
		(net "M_C_CPU0_SA_DQ<0>")
	)
	(segment
		(start 330.466954 -218.36761)
		(end 325.503794 -213.40445)
		(width 0.14478)
		(layer "In2.Cu")
		(net "M_C_CPU0_SA_DQ<0>")
	)
	(segment
		(start 297.351958 -196.379338)
		(end 297.18889 -196.21627)
		(width 0.14478)
		(layer "In2.Cu")
		(net "M_C_CPU0_SA_DQ<0>")
	)
	(segment
		(start 296.958512 -196.21627)
		(end 296.795444 -196.379338)
		(width 0.14478)
		(layer "In2.Cu")
		(net "M_C_CPU0_SA_DQ<0>")
	)
	(segment
		(start 332.274164 -225.366834)
		(end 332.242414 -225.348546)
		(width 0.0889)
		(layer "In2.Cu")
		(net "M_C_CPU0_SA_DQ<0>")
	)
	(segment
		(start 342.015064 -225.309684)
		(end 341.992712 -225.392996)
		(width 0.0889)
		(layer "In2.Cu")
		(net "M_C_CPU0_SA_DQ<0>")
	)
	(segment
		(start 296.795444 -196.379338)
		(end 296.795444 -196.74713)
		(width 0.14478)
		(layer "In2.Cu")
		(net "M_C_CPU0_SA_DQ<0>")
	)
	(segment
		(start 335.102454 -225.37166)
		(end 335.094072 -225.366834)
		(width 0.0889)
		(layer "In2.Cu")
		(net "M_C_CPU0_SA_DQ<0>")
	)
	(segment
		(start 298.464986 -196.379338)
		(end 298.301918 -196.21627)
		(width 0.14478)
		(layer "In2.Cu")
		(net "M_C_CPU0_SA_DQ<0>")
	)
	(segment
		(start 294.251888 -196.74713)
		(end 294.251888 -196.61378)
		(width 0.14478)
		(layer "In2.Cu")
		(net "M_C_CPU0_SA_DQ<0>")
	)
	(segment
		(start 330.466954 -221.20987)
		(end 330.466954 -218.36761)
		(width 0.14478)
		(layer "In2.Cu")
		(net "M_C_CPU0_SA_DQ<0>")
	)
	(segment
		(start 330.431902 -222.148654)
		(end 330.39431 -222.12681)
		(width 0.0889)
		(layer "In2.Cu")
		(net "M_C_CPU0_SA_DQ<0>")
	)
	(segment
		(start 294.08882 -196.450712)
		(end 293.858442 -196.450712)
		(width 0.14478)
		(layer "In2.Cu")
		(net "M_C_CPU0_SA_DQ<0>")
	)
	(segment
		(start 294.251888 -196.61378)
		(end 294.08882 -196.450712)
		(width 0.14478)
		(layer "In2.Cu")
		(net "M_C_CPU0_SA_DQ<0>")
	)
	(segment
		(start 293.695374 -196.61378)
		(end 293.695374 -196.74713)
		(width 0.14478)
		(layer "In2.Cu")
		(net "M_C_CPU0_SA_DQ<0>")
	)
	(segment
		(start 305.941984 -196.74713)
		(end 305.941984 -196.232018)
		(width 0.14478)
		(layer "In2.Cu")
		(net "M_C_CPU0_SA_DQ<0>")
	)
	(segment
		(start 305.38547 -196.74713)
		(end 305.222402 -196.910198)
		(width 0.14478)
		(layer "In2.Cu")
		(net "M_C_CPU0_SA_DQ<0>")
	)
	(segment
		(start 298.464986 -196.74713)
		(end 298.464986 -196.379338)
		(width 0.14478)
		(layer "In2.Cu")
		(net "M_C_CPU0_SA_DQ<0>")
	)
	(segment
		(start 331.33411 -223.746822)
		(end 331.30236 -223.728534)
		(width 0.0889)
		(layer "In2.Cu")
		(net "M_C_CPU0_SA_DQ<0>")
	)
	(segment
		(start 305.548538 -196.06895)
		(end 305.38547 -196.232018)
		(width 0.14478)
		(layer "In2.Cu")
		(net "M_C_CPU0_SA_DQ<0>")
	)
	(segment
		(start 297.515026 -196.910198)
		(end 297.351958 -196.74713)
		(width 0.14478)
		(layer "In2.Cu")
		(net "M_C_CPU0_SA_DQ<0>")
	)
	(segment
		(start 304.272442 -196.74713)
		(end 304.109374 -196.910198)
		(width 0.14478)
		(layer "In2.Cu")
		(net "M_C_CPU0_SA_DQ<0>")
	)
	(segment
		(start 306.105052 -196.910198)
		(end 305.941984 -196.74713)
		(width 0.14478)
		(layer "In2.Cu")
		(net "M_C_CPU0_SA_DQ<0>")
	)
	(segment
		(start 321.447414 -208.67243)
		(end 309.685182 -196.910198)
		(width 0.14478)
		(layer "In2.Cu")
		(net "M_C_CPU0_SA_DQ<0>")
	)
	(segment
		(start 330.903072 -222.959676)
		(end 330.863956 -222.936816)
		(width 0.0889)
		(layer "In2.Cu")
		(net "M_C_CPU0_SA_DQ<0>")
	)
	(segment
		(start 330.466954 -221.37497)
		(end 330.466954 -221.20987)
		(width 0.0889)
		(layer "In2.Cu")
		(net "M_C_CPU0_SA_DQ<0>")
	)
	(segment
		(start 305.778916 -196.06895)
		(end 305.548538 -196.06895)
		(width 0.14478)
		(layer "In2.Cu")
		(net "M_C_CPU0_SA_DQ<0>")
	)
	(segment
		(start 294.414956 -196.910198)
		(end 294.251888 -196.74713)
		(width 0.14478)
		(layer "In2.Cu")
		(net "M_C_CPU0_SA_DQ<0>")
	)
	(segment
		(start 331.373226 -223.769682)
		(end 331.33411 -223.746822)
		(width 0.0889)
		(layer "In2.Cu")
		(net "M_C_CPU0_SA_DQ<0>")
	)
	(segment
		(start 341.86114 -225.044254)
		(end 342.015064 -225.309684)
		(width 0.0889)
		(layer "In2.Cu")
		(net "M_C_CPU0_SA_DQ<0>")
	)
	(segment
		(start 304.109374 -196.910198)
		(end 298.628054 -196.910198)
		(width 0.14478)
		(layer "In2.Cu")
		(net "M_C_CPU0_SA_DQ<0>")
	)
	(segment
		(start 330.188316 -221.920816)
		(end 330.188316 -221.653608)
		(width 0.0889)
		(layer "In2.Cu")
		(net "M_C_CPU0_SA_DQ<0>")
	)
	(segment
		(start 304.828956 -196.232018)
		(end 304.665888 -196.06895)
		(width 0.14478)
		(layer "In2.Cu")
		(net "M_C_CPU0_SA_DQ<0>")
	)
	(segment
		(start 305.38547 -196.232018)
		(end 305.38547 -196.74713)
		(width 0.14478)
		(layer "In2.Cu")
		(net "M_C_CPU0_SA_DQ<0>")
	)
	(segment
		(start 322.478654 -208.67243)
		(end 321.447414 -208.67243)
		(width 0.14478)
		(layer "In2.Cu")
		(net "M_C_CPU0_SA_DQ<0>")
	)
	(segment
		(start 304.665888 -196.06895)
		(end 304.43551 -196.06895)
		(width 0.14478)
		(layer "In2.Cu")
		(net "M_C_CPU0_SA_DQ<0>")
	)
	(segment
		(start 304.272442 -196.232018)
		(end 304.272442 -196.74713)
		(width 0.14478)
		(layer "In2.Cu")
		(net "M_C_CPU0_SA_DQ<0>")
	)
	(segment
		(start 336.042508 -225.37166)
		(end 336.034126 -225.366834)
		(width 0.0889)
		(layer "In2.Cu")
		(net "M_C_CPU0_SA_DQ<0>")
	)
	(segment
		(start 293.532306 -196.910198)
		(end 292.705028 -196.910198)
		(width 0.14478)
		(layer "In2.Cu")
		(net "M_C_CPU0_SA_DQ<0>")
	)
	(segment
		(start 296.795444 -196.74713)
		(end 296.632376 -196.910198)
		(width 0.14478)
		(layer "In2.Cu")
		(net "M_C_CPU0_SA_DQ<0>")
	)
	(segment
		(start 296.632376 -196.910198)
		(end 294.414956 -196.910198)
		(width 0.14478)
		(layer "In2.Cu")
		(net "M_C_CPU0_SA_DQ<0>")
	)
	(segment
		(start 309.685182 -196.910198)
		(end 306.105052 -196.910198)
		(width 0.14478)
		(layer "In2.Cu")
		(net "M_C_CPU0_SA_DQ<0>")
	)
	(segment
		(start 331.80401 -224.556828)
		(end 331.77353 -224.539048)
		(width 0.0889)
		(layer "In2.Cu")
		(net "M_C_CPU0_SA_DQ<0>")
	)
	(segment
		(start 325.503794 -211.69757)
		(end 322.478654 -208.67243)
		(width 0.14478)
		(layer "In2.Cu")
		(net "M_C_CPU0_SA_DQ<0>")
	)
	(segment
		(start 304.992024 -196.910198)
		(end 304.828956 -196.74713)
		(width 0.14478)
		(layer "In2.Cu")
		(net "M_C_CPU0_SA_DQ<0>")
	)
	(segment
		(start 298.301918 -196.21627)
		(end 298.07154 -196.21627)
		(width 0.14478)
		(layer "In2.Cu")
		(net "M_C_CPU0_SA_DQ<0>")
	)
	(segment
		(start 297.351958 -196.74713)
		(end 297.351958 -196.379338)
		(width 0.14478)
		(layer "In2.Cu")
		(net "M_C_CPU0_SA_DQ<0>")
	)
	(segment
		(start 333.588106 -225.366834)
		(end 333.579724 -225.37166)
		(width 0.0889)
		(layer "In2.Cu")
		(net "M_C_CPU0_SA_DQ<0>")
	)
	(segment
		(start 325.503794 -213.40445)
		(end 325.503794 -211.69757)
		(width 0.14478)
		(layer "In2.Cu")
		(net "M_C_CPU0_SA_DQ<0>")
	)
	(segment
		(start 305.222402 -196.910198)
		(end 304.992024 -196.910198)
		(width 0.14478)
		(layer "In2.Cu")
		(net "M_C_CPU0_SA_DQ<0>")
	)
	(arc
		(start 331.30236 -223.728534)
		(mid 331.187684 -223.5952)
		(end 331.146404 -223.424242)
		(width 0.0889)
		(layer "In2.Cu")
		(net "M_C_CPU0_SA_DQ<0>")
	)
	(arc
		(start 332.086458 -225.044254)
		(mid 332.021943 -224.782035)
		(end 331.843126 -224.579688)
		(width 0.0889)
		(layer "In2.Cu")
		(net "M_C_CPU0_SA_DQ<0>")
	)
	(arc
		(start 331.616558 -224.234248)
		(mid 331.552043 -223.972029)
		(end 331.373226 -223.769682)
		(width 0.0889)
		(layer "In2.Cu")
		(net "M_C_CPU0_SA_DQ<0>")
	)
	(arc
		(start 330.833476 -222.919036)
		(mid 330.718049 -222.78566)
		(end 330.676504 -222.614236)
		(width 0.0889)
		(layer "In2.Cu")
		(net "M_C_CPU0_SA_DQ<0>")
	)
	(arc
		(start 335.468214 -225.366834)
		(mid 335.285963 -225.417184)
		(end 335.102454 -225.37166)
		(width 0.0889)
		(layer "In2.Cu")
		(net "M_C_CPU0_SA_DQ<0>")
	)
	(arc
		(start 337.348068 -225.366834)
		(mid 337.161124 -225.417089)
		(end 336.97418 -225.366834)
		(width 0.0889)
		(layer "In2.Cu")
		(net "M_C_CPU0_SA_DQ<0>")
	)
	(arc
		(start 332.648052 -225.366834)
		(mid 332.461108 -225.417089)
		(end 332.274164 -225.366834)
		(width 0.0889)
		(layer "In2.Cu")
		(net "M_C_CPU0_SA_DQ<0>")
	)
	(arc
		(start 336.408268 -225.366834)
		(mid 336.226017 -225.417184)
		(end 336.042508 -225.37166)
		(width 0.0889)
		(layer "In2.Cu")
		(net "M_C_CPU0_SA_DQ<0>")
	)
	(arc
		(start 330.676504 -222.614236)
		(mid 330.611632 -222.351273)
		(end 330.431902 -222.148654)
		(width 0.0889)
		(layer "In2.Cu")
		(net "M_C_CPU0_SA_DQ<0>")
	)
	(arc
		(start 336.97418 -225.366834)
		(mid 336.691224 -225.290657)
		(end 336.408268 -225.366834)
		(width 0.0889)
		(layer "In2.Cu")
		(net "M_C_CPU0_SA_DQ<0>")
	)
	(arc
		(start 341.10803 -225.366834)
		(mid 340.921086 -225.417089)
		(end 340.734142 -225.366834)
		(width 0.0889)
		(layer "In2.Cu")
		(net "M_C_CPU0_SA_DQ<0>")
	)
	(arc
		(start 338.854034 -225.366834)
		(mid 338.571078 -225.290657)
		(end 338.288122 -225.366834)
		(width 0.0889)
		(layer "In2.Cu")
		(net "M_C_CPU0_SA_DQ<0>")
	)
	(arc
		(start 334.519778 -225.37166)
		(mid 334.33627 -225.417154)
		(end 334.154018 -225.366834)
		(width 0.0889)
		(layer "In2.Cu")
		(net "M_C_CPU0_SA_DQ<0>")
	)
	(arc
		(start 331.146404 -223.424242)
		(mid 331.081889 -223.162023)
		(end 330.903072 -222.959676)
		(width 0.0889)
		(layer "In2.Cu")
		(net "M_C_CPU0_SA_DQ<0>")
	)
	(arc
		(start 339.228176 -225.366834)
		(mid 339.045925 -225.417184)
		(end 338.862416 -225.37166)
		(width 0.0889)
		(layer "In2.Cu")
		(net "M_C_CPU0_SA_DQ<0>")
	)
	(arc
		(start 335.094072 -225.366834)
		(mid 334.811116 -225.290657)
		(end 334.52816 -225.366834)
		(width 0.0889)
		(layer "In2.Cu")
		(net "M_C_CPU0_SA_DQ<0>")
	)
	(arc
		(start 339.794088 -225.366834)
		(mid 339.511132 -225.290657)
		(end 339.228176 -225.366834)
		(width 0.0889)
		(layer "In2.Cu")
		(net "M_C_CPU0_SA_DQ<0>")
	)
	(arc
		(start 333.213964 -225.366834)
		(mid 332.931008 -225.290657)
		(end 332.648052 -225.366834)
		(width 0.0889)
		(layer "In2.Cu")
		(net "M_C_CPU0_SA_DQ<0>")
	)
	(arc
		(start 336.034126 -225.366834)
		(mid 335.75117 -225.290657)
		(end 335.468214 -225.366834)
		(width 0.0889)
		(layer "In2.Cu")
		(net "M_C_CPU0_SA_DQ<0>")
	)
	(arc
		(start 341.992712 -225.392996)
		(mid 341.83038 -225.415814)
		(end 341.673942 -225.366834)
		(width 0.0889)
		(layer "In2.Cu")
		(net "M_C_CPU0_SA_DQ<0>")
	)
	(arc
		(start 338.27974 -225.37166)
		(mid 338.096232 -225.417154)
		(end 337.91398 -225.366834)
		(width 0.0889)
		(layer "In2.Cu")
		(net "M_C_CPU0_SA_DQ<0>")
	)
	(arc
		(start 340.16823 -225.366834)
		(mid 339.985979 -225.417184)
		(end 339.80247 -225.37166)
		(width 0.0889)
		(layer "In2.Cu")
		(net "M_C_CPU0_SA_DQ<0>")
	)
	(arc
		(start 333.579724 -225.37166)
		(mid 333.396216 -225.417154)
		(end 333.213964 -225.366834)
		(width 0.0889)
		(layer "In2.Cu")
		(net "M_C_CPU0_SA_DQ<0>")
	)
	(arc
		(start 331.77353 -224.539048)
		(mid 331.658103 -224.405672)
		(end 331.616558 -224.234248)
		(width 0.0889)
		(layer "In2.Cu")
		(net "M_C_CPU0_SA_DQ<0>")
	)
	(arc
		(start 332.242414 -225.348546)
		(mid 332.127738 -225.215212)
		(end 332.086458 -225.044254)
		(width 0.0889)
		(layer "In2.Cu")
		(net "M_C_CPU0_SA_DQ<0>")
	)
	(arc
		(start 340.734142 -225.366834)
		(mid 340.451186 -225.290657)
		(end 340.16823 -225.366834)
		(width 0.0889)
		(layer "In2.Cu")
		(net "M_C_CPU0_SA_DQ<0>")
	)
	(arc
		(start 341.673942 -225.366834)
		(mid 341.390986 -225.290657)
		(end 341.10803 -225.366834)
		(width 0.0889)
		(layer "In2.Cu")
		(net "M_C_CPU0_SA_DQ<0>")
	)
	(arc
		(start 337.91398 -225.366834)
		(mid 337.631024 -225.290657)
		(end 337.348068 -225.366834)
		(width 0.0889)
		(layer "In2.Cu")
		(net "M_C_CPU0_SA_DQ<0>")
	)
	(arc
		(start 334.154018 -225.366834)
		(mid 333.871062 -225.290657)
		(end 333.588106 -225.366834)
		(width 0.0889)
		(layer "In2.Cu")
		(net "M_C_CPU0_SA_DQ<0>")
	)
	(segment
		(start 344.207846 -252.850142)
		(end 343.740994 -252.584204)
		(width 0.10668)
		(layer "F.Cu")
		(net "M_C_CPU0_SA_CS_N<1>")
	)
	(segment
		(start 335.102454 -252.256798)
		(end 335.094072 -252.261624)
		(width 0.0889)
		(layer "In2.Cu")
		(net "M_C_CPU0_SA_CS_N<1>")
	)
	(segment
		(start 311.554622 -251.969016)
		(end 308.345586 -248.75998)
		(width 0.14478)
		(layer "In2.Cu")
		(net "M_C_CPU0_SA_CS_N<1>")
	)
	(segment
		(start 326.070214 -252.261878)
		(end 326.046846 -252.248416)
		(width 0.0889)
		(layer "In2.Cu")
		(net "M_C_CPU0_SA_CS_N<1>")
	)
	(segment
		(start 314.342018 -251.969016)
		(end 311.554622 -251.969016)
		(width 0.14478)
		(layer "In2.Cu")
		(net "M_C_CPU0_SA_CS_N<1>")
	)
	(segment
		(start 330.402438 -252.256798)
		(end 330.394056 -252.261624)
		(width 0.0889)
		(layer "In2.Cu")
		(net "M_C_CPU0_SA_CS_N<1>")
	)
	(segment
		(start 315.94806 -251.30379)
		(end 314.342018 -251.969016)
		(width 0.14478)
		(layer "In2.Cu")
		(net "M_C_CPU0_SA_CS_N<1>")
	)
	(segment
		(start 338.862416 -252.256798)
		(end 338.854034 -252.261624)
		(width 0.0889)
		(layer "In2.Cu")
		(net "M_C_CPU0_SA_CS_N<1>")
	)
	(segment
		(start 338.288122 -252.261624)
		(end 338.27974 -252.256798)
		(width 0.0889)
		(layer "In2.Cu")
		(net "M_C_CPU0_SA_CS_N<1>")
	)
	(segment
		(start 336.042508 -252.256798)
		(end 336.034126 -252.261624)
		(width 0.0889)
		(layer "In2.Cu")
		(net "M_C_CPU0_SA_CS_N<1>")
	)
	(segment
		(start 308.345586 -248.75998)
		(end 294.786304 -248.75998)
		(width 0.14478)
		(layer "In2.Cu")
		(net "M_C_CPU0_SA_CS_N<1>")
	)
	(segment
		(start 288.60496 -247.059958)
		(end 288.180018 -246.635016)
		(width 0.14478)
		(layer "In2.Cu")
		(net "M_C_CPU0_SA_CS_N<1>")
	)
	(segment
		(start 343.740994 -252.584204)
		(end 343.58707 -252.318774)
		(width 0.0889)
		(layer "In2.Cu")
		(net "M_C_CPU0_SA_CS_N<1>")
	)
	(segment
		(start 339.80247 -252.256798)
		(end 339.794088 -252.261624)
		(width 0.0889)
		(layer "In2.Cu")
		(net "M_C_CPU0_SA_CS_N<1>")
	)
	(segment
		(start 342.988138 -252.261624)
		(end 342.979756 -252.256798)
		(width 0.0889)
		(layer "In2.Cu")
		(net "M_C_CPU0_SA_CS_N<1>")
	)
	(segment
		(start 294.786304 -248.75998)
		(end 293.086282 -247.059958)
		(width 0.14478)
		(layer "In2.Cu")
		(net "M_C_CPU0_SA_CS_N<1>")
	)
	(segment
		(start 329.828144 -252.261624)
		(end 329.819762 -252.256798)
		(width 0.0889)
		(layer "In2.Cu")
		(net "M_C_CPU0_SA_CS_N<1>")
	)
	(segment
		(start 331.342492 -252.256798)
		(end 331.33411 -252.261624)
		(width 0.0889)
		(layer "In2.Cu")
		(net "M_C_CPU0_SA_CS_N<1>")
	)
	(segment
		(start 293.086282 -247.059958)
		(end 288.60496 -247.059958)
		(width 0.14478)
		(layer "In2.Cu")
		(net "M_C_CPU0_SA_CS_N<1>")
	)
	(segment
		(start 324.497954 -252.45441)
		(end 321.950334 -252.45441)
		(width 0.14478)
		(layer "In2.Cu")
		(net "M_C_CPU0_SA_CS_N<1>")
	)
	(segment
		(start 320.799714 -251.30379)
		(end 315.94806 -251.30379)
		(width 0.14478)
		(layer "In2.Cu")
		(net "M_C_CPU0_SA_CS_N<1>")
	)
	(segment
		(start 327.011538 -252.261624)
		(end 326.990964 -252.249686)
		(width 0.0889)
		(layer "In2.Cu")
		(net "M_C_CPU0_SA_CS_N<1>")
	)
	(segment
		(start 326.109584 -252.284738)
		(end 326.070214 -252.261878)
		(width 0.0889)
		(layer "In2.Cu")
		(net "M_C_CPU0_SA_CS_N<1>")
	)
	(segment
		(start 342.048084 -252.261624)
		(end 342.039702 -252.256798)
		(width 0.0889)
		(layer "In2.Cu")
		(net "M_C_CPU0_SA_CS_N<1>")
	)
	(segment
		(start 325.098664 -252.45441)
		(end 324.497954 -252.45441)
		(width 0.0889)
		(layer "In2.Cu")
		(net "M_C_CPU0_SA_CS_N<1>")
	)
	(segment
		(start 334.52816 -252.261624)
		(end 334.519778 -252.256798)
		(width 0.0889)
		(layer "In2.Cu")
		(net "M_C_CPU0_SA_CS_N<1>")
	)
	(segment
		(start 327.598786 -252.248416)
		(end 327.575418 -252.261878)
		(width 0.0889)
		(layer "In2.Cu")
		(net "M_C_CPU0_SA_CS_N<1>")
	)
	(segment
		(start 325.69785 -252.261624)
		(end 325.595742 -252.320806)
		(width 0.0889)
		(layer "In2.Cu")
		(net "M_C_CPU0_SA_CS_N<1>")
	)
	(segment
		(start 321.950334 -252.45441)
		(end 320.799714 -251.30379)
		(width 0.14478)
		(layer "In2.Cu")
		(net "M_C_CPU0_SA_CS_N<1>")
	)
	(segment
		(start 327.575418 -252.261878)
		(end 327.549256 -252.276864)
		(width 0.0889)
		(layer "In2.Cu")
		(net "M_C_CPU0_SA_CS_N<1>")
	)
	(segment
		(start 343.58707 -252.318774)
		(end 343.491058 -252.293374)
		(width 0.0889)
		(layer "In2.Cu")
		(net "M_C_CPU0_SA_CS_N<1>")
	)
	(segment
		(start 333.588106 -252.261624)
		(end 333.579724 -252.256798)
		(width 0.0889)
		(layer "In2.Cu")
		(net "M_C_CPU0_SA_CS_N<1>")
	)
	(arc
		(start 326.990964 -252.249686)
		(mid 326.812036 -252.210809)
		(end 326.636126 -252.261624)
		(width 0.0889)
		(layer "In2.Cu")
		(net "M_C_CPU0_SA_CS_N<1>")
	)
	(arc
		(start 338.27974 -252.256798)
		(mid 338.096232 -252.211304)
		(end 337.91398 -252.261624)
		(width 0.0889)
		(layer "In2.Cu")
		(net "M_C_CPU0_SA_CS_N<1>")
	)
	(arc
		(start 337.348068 -252.261624)
		(mid 337.161124 -252.211369)
		(end 336.97418 -252.261624)
		(width 0.0889)
		(layer "In2.Cu")
		(net "M_C_CPU0_SA_CS_N<1>")
	)
	(arc
		(start 330.394056 -252.261624)
		(mid 330.1111 -252.337801)
		(end 329.828144 -252.261624)
		(width 0.0889)
		(layer "In2.Cu")
		(net "M_C_CPU0_SA_CS_N<1>")
	)
	(arc
		(start 326.636126 -252.261624)
		(mid 326.375711 -252.338406)
		(end 326.109584 -252.284738)
		(width 0.0889)
		(layer "In2.Cu")
		(net "M_C_CPU0_SA_CS_N<1>")
	)
	(arc
		(start 328.88809 -252.261624)
		(mid 328.701146 -252.211369)
		(end 328.514202 -252.261624)
		(width 0.0889)
		(layer "In2.Cu")
		(net "M_C_CPU0_SA_CS_N<1>")
	)
	(arc
		(start 334.154018 -252.261624)
		(mid 333.871062 -252.337801)
		(end 333.588106 -252.261624)
		(width 0.0889)
		(layer "In2.Cu")
		(net "M_C_CPU0_SA_CS_N<1>")
	)
	(arc
		(start 338.854034 -252.261624)
		(mid 338.571078 -252.337801)
		(end 338.288122 -252.261624)
		(width 0.0889)
		(layer "In2.Cu")
		(net "M_C_CPU0_SA_CS_N<1>")
	)
	(arc
		(start 343.491058 -252.293374)
		(mid 343.23585 -252.336851)
		(end 342.988138 -252.261624)
		(width 0.0889)
		(layer "In2.Cu")
		(net "M_C_CPU0_SA_CS_N<1>")
	)
	(arc
		(start 342.039702 -252.256798)
		(mid 341.856194 -252.211304)
		(end 341.673942 -252.261624)
		(width 0.0889)
		(layer "In2.Cu")
		(net "M_C_CPU0_SA_CS_N<1>")
	)
	(arc
		(start 336.97418 -252.261624)
		(mid 336.691224 -252.337801)
		(end 336.408268 -252.261624)
		(width 0.0889)
		(layer "In2.Cu")
		(net "M_C_CPU0_SA_CS_N<1>")
	)
	(arc
		(start 334.519778 -252.256798)
		(mid 334.33627 -252.211304)
		(end 334.154018 -252.261624)
		(width 0.0889)
		(layer "In2.Cu")
		(net "M_C_CPU0_SA_CS_N<1>")
	)
	(arc
		(start 342.613996 -252.261624)
		(mid 342.33104 -252.337801)
		(end 342.048084 -252.261624)
		(width 0.0889)
		(layer "In2.Cu")
		(net "M_C_CPU0_SA_CS_N<1>")
	)
	(arc
		(start 332.648052 -252.261624)
		(mid 332.461108 -252.211369)
		(end 332.274164 -252.261624)
		(width 0.0889)
		(layer "In2.Cu")
		(net "M_C_CPU0_SA_CS_N<1>")
	)
	(arc
		(start 326.046846 -252.248416)
		(mid 325.870704 -252.211624)
		(end 325.69785 -252.261624)
		(width 0.0889)
		(layer "In2.Cu")
		(net "M_C_CPU0_SA_CS_N<1>")
	)
	(arc
		(start 327.94829 -252.261624)
		(mid 327.775182 -252.211508)
		(end 327.598786 -252.248416)
		(width 0.0889)
		(layer "In2.Cu")
		(net "M_C_CPU0_SA_CS_N<1>")
	)
	(arc
		(start 333.213964 -252.261624)
		(mid 332.931008 -252.337801)
		(end 332.648052 -252.261624)
		(width 0.0889)
		(layer "In2.Cu")
		(net "M_C_CPU0_SA_CS_N<1>")
	)
	(arc
		(start 325.595742 -252.320806)
		(mid 325.356031 -252.420466)
		(end 325.098664 -252.45441)
		(width 0.0889)
		(layer "In2.Cu")
		(net "M_C_CPU0_SA_CS_N<1>")
	)
	(arc
		(start 335.094072 -252.261624)
		(mid 334.811116 -252.337801)
		(end 334.52816 -252.261624)
		(width 0.0889)
		(layer "In2.Cu")
		(net "M_C_CPU0_SA_CS_N<1>")
	)
	(arc
		(start 336.408268 -252.261624)
		(mid 336.226017 -252.211274)
		(end 336.042508 -252.256798)
		(width 0.0889)
		(layer "In2.Cu")
		(net "M_C_CPU0_SA_CS_N<1>")
	)
	(arc
		(start 341.10803 -252.261624)
		(mid 340.921086 -252.211369)
		(end 340.734142 -252.261624)
		(width 0.0889)
		(layer "In2.Cu")
		(net "M_C_CPU0_SA_CS_N<1>")
	)
	(arc
		(start 333.579724 -252.256798)
		(mid 333.396216 -252.211304)
		(end 333.213964 -252.261624)
		(width 0.0889)
		(layer "In2.Cu")
		(net "M_C_CPU0_SA_CS_N<1>")
	)
	(arc
		(start 339.794088 -252.261624)
		(mid 339.511132 -252.337801)
		(end 339.228176 -252.261624)
		(width 0.0889)
		(layer "In2.Cu")
		(net "M_C_CPU0_SA_CS_N<1>")
	)
	(arc
		(start 340.734142 -252.261624)
		(mid 340.451186 -252.337801)
		(end 340.16823 -252.261624)
		(width 0.0889)
		(layer "In2.Cu")
		(net "M_C_CPU0_SA_CS_N<1>")
	)
	(arc
		(start 342.979756 -252.256798)
		(mid 342.796248 -252.211304)
		(end 342.613996 -252.261624)
		(width 0.0889)
		(layer "In2.Cu")
		(net "M_C_CPU0_SA_CS_N<1>")
	)
	(arc
		(start 331.33411 -252.261624)
		(mid 331.051154 -252.337801)
		(end 330.768198 -252.261624)
		(width 0.0889)
		(layer "In2.Cu")
		(net "M_C_CPU0_SA_CS_N<1>")
	)
	(arc
		(start 339.228176 -252.261624)
		(mid 339.045925 -252.211274)
		(end 338.862416 -252.256798)
		(width 0.0889)
		(layer "In2.Cu")
		(net "M_C_CPU0_SA_CS_N<1>")
	)
	(arc
		(start 332.274164 -252.261624)
		(mid 331.991208 -252.337801)
		(end 331.708252 -252.261624)
		(width 0.0889)
		(layer "In2.Cu")
		(net "M_C_CPU0_SA_CS_N<1>")
	)
	(arc
		(start 340.16823 -252.261624)
		(mid 339.985979 -252.211274)
		(end 339.80247 -252.256798)
		(width 0.0889)
		(layer "In2.Cu")
		(net "M_C_CPU0_SA_CS_N<1>")
	)
	(arc
		(start 331.708252 -252.261624)
		(mid 331.526001 -252.211274)
		(end 331.342492 -252.256798)
		(width 0.0889)
		(layer "In2.Cu")
		(net "M_C_CPU0_SA_CS_N<1>")
	)
	(arc
		(start 337.91398 -252.261624)
		(mid 337.631024 -252.337801)
		(end 337.348068 -252.261624)
		(width 0.0889)
		(layer "In2.Cu")
		(net "M_C_CPU0_SA_CS_N<1>")
	)
	(arc
		(start 327.549256 -252.276864)
		(mid 327.27847 -252.33751)
		(end 327.011538 -252.261624)
		(width 0.0889)
		(layer "In2.Cu")
		(net "M_C_CPU0_SA_CS_N<1>")
	)
	(arc
		(start 335.468214 -252.261624)
		(mid 335.285963 -252.211274)
		(end 335.102454 -252.256798)
		(width 0.0889)
		(layer "In2.Cu")
		(net "M_C_CPU0_SA_CS_N<1>")
	)
	(arc
		(start 336.034126 -252.261624)
		(mid 335.75117 -252.337801)
		(end 335.468214 -252.261624)
		(width 0.0889)
		(layer "In2.Cu")
		(net "M_C_CPU0_SA_CS_N<1>")
	)
	(arc
		(start 330.768198 -252.261624)
		(mid 330.585947 -252.211274)
		(end 330.402438 -252.256798)
		(width 0.0889)
		(layer "In2.Cu")
		(net "M_C_CPU0_SA_CS_N<1>")
	)
	(arc
		(start 341.673942 -252.261624)
		(mid 341.390986 -252.337801)
		(end 341.10803 -252.261624)
		(width 0.0889)
		(layer "In2.Cu")
		(net "M_C_CPU0_SA_CS_N<1>")
	)
	(arc
		(start 329.819762 -252.256798)
		(mid 329.636254 -252.211304)
		(end 329.454002 -252.261624)
		(width 0.0889)
		(layer "In2.Cu")
		(net "M_C_CPU0_SA_CS_N<1>")
	)
	(arc
		(start 329.454002 -252.261624)
		(mid 329.171046 -252.337801)
		(end 328.88809 -252.261624)
		(width 0.0889)
		(layer "In2.Cu")
		(net "M_C_CPU0_SA_CS_N<1>")
	)
	(arc
		(start 328.514202 -252.261624)
		(mid 328.231246 -252.337801)
		(end 327.94829 -252.261624)
		(width 0.0889)
		(layer "In2.Cu")
		(net "M_C_CPU0_SA_CS_N<1>")
	)
	(segment
		(start 342.797892 -252.040136)
		(end 342.33104 -251.774198)
		(width 0.10668)
		(layer "F.Cu")
		(net "M_C_CPU0_SA_CS_N<0>")
	)
	(segment
		(start 337.452462 -251.446792)
		(end 337.44408 -251.451618)
		(width 0.0889)
		(layer "In2.Cu")
		(net "M_C_CPU0_SA_CS_N<0>")
	)
	(segment
		(start 301.752 -248.30151)
		(end 301.588932 -248.138442)
		(width 0.14478)
		(layer "In2.Cu")
		(net "M_C_CPU0_SA_CS_N<0>")
	)
	(segment
		(start 306.190396 -248.130822)
		(end 306.027328 -248.29389)
		(width 0.14478)
		(layer "In2.Cu")
		(net "M_C_CPU0_SA_CS_N<0>")
	)
	(segment
		(start 296.905934 -248.073164)
		(end 296.742866 -247.910096)
		(width 0.14478)
		(layer "In2.Cu")
		(net "M_C_CPU0_SA_CS_N<0>")
	)
	(segment
		(start 306.353464 -247.910096)
		(end 306.190396 -248.073164)
		(width 0.14478)
		(layer "In2.Cu")
		(net "M_C_CPU0_SA_CS_N<0>")
	)
	(segment
		(start 328.41819 -251.451618)
		(end 328.409808 -251.446792)
		(width 0.0889)
		(layer "In2.Cu")
		(net "M_C_CPU0_SA_CS_N<0>")
	)
	(segment
		(start 342.177116 -251.508768)
		(end 342.081104 -251.483368)
		(width 0.0889)
		(layer "In2.Cu")
		(net "M_C_CPU0_SA_CS_N<0>")
	)
	(segment
		(start 324.439534 -251.632212)
		(end 324.421754 -251.649992)
		(width 0.0889)
		(layer "In2.Cu")
		(net "M_C_CPU0_SA_CS_N<0>")
	)
	(segment
		(start 335.938114 -251.451618)
		(end 335.929732 -251.446792)
		(width 0.0889)
		(layer "In2.Cu")
		(net "M_C_CPU0_SA_CS_N<0>")
	)
	(segment
		(start 298.738544 -247.910096)
		(end 298.575476 -248.073164)
		(width 0.14478)
		(layer "In2.Cu")
		(net "M_C_CPU0_SA_CS_N<0>")
	)
	(segment
		(start 338.392516 -251.446792)
		(end 338.384134 -251.451618)
		(width 0.0889)
		(layer "In2.Cu")
		(net "M_C_CPU0_SA_CS_N<0>")
	)
	(segment
		(start 301.195486 -247.910096)
		(end 301.032418 -248.073164)
		(width 0.14478)
		(layer "In2.Cu")
		(net "M_C_CPU0_SA_CS_N<0>")
	)
	(segment
		(start 300.475904 -248.138442)
		(end 300.475904 -248.073164)
		(width 0.14478)
		(layer "In2.Cu")
		(net "M_C_CPU0_SA_CS_N<0>")
	)
	(segment
		(start 333.6925 -251.446792)
		(end 333.684118 -251.451618)
		(width 0.0889)
		(layer "In2.Cu")
		(net "M_C_CPU0_SA_CS_N<0>")
	)
	(segment
		(start 325.792084 -251.632212)
		(end 324.439534 -251.632212)
		(width 0.0889)
		(layer "In2.Cu")
		(net "M_C_CPU0_SA_CS_N<0>")
	)
	(segment
		(start 297.625516 -247.910096)
		(end 297.462448 -248.073164)
		(width 0.14478)
		(layer "In2.Cu")
		(net "M_C_CPU0_SA_CS_N<0>")
	)
	(segment
		(start 311.741312 -251.519436)
		(end 308.131972 -247.910096)
		(width 0.14478)
		(layer "In2.Cu")
		(net "M_C_CPU0_SA_CS_N<0>")
	)
	(segment
		(start 292.700964 -246.20601)
		(end 292.280086 -245.785132)
		(width 0.14478)
		(layer "In2.Cu")
		(net "M_C_CPU0_SA_CS_N<0>")
	)
	(segment
		(start 336.878168 -251.451618)
		(end 336.869786 -251.446792)
		(width 0.0889)
		(layer "In2.Cu")
		(net "M_C_CPU0_SA_CS_N<0>")
	)
	(segment
		(start 328.044048 -251.451618)
		(end 328.029316 -251.460254)
		(width 0.0889)
		(layer "In2.Cu")
		(net "M_C_CPU0_SA_CS_N<0>")
	)
	(segment
		(start 306.190396 -248.073164)
		(end 306.190396 -248.130822)
		(width 0.14478)
		(layer "In2.Cu")
		(net "M_C_CPU0_SA_CS_N<0>")
	)
	(segment
		(start 332.178152 -251.451618)
		(end 332.16977 -251.446792)
		(width 0.0889)
		(layer "In2.Cu")
		(net "M_C_CPU0_SA_CS_N<0>")
	)
	(segment
		(start 328.992484 -251.446792)
		(end 328.984102 -251.451618)
		(width 0.0889)
		(layer "In2.Cu")
		(net "M_C_CPU0_SA_CS_N<0>")
	)
	(segment
		(start 292.99662 -246.20601)
		(end 292.700964 -246.20601)
		(width 0.14478)
		(layer "In2.Cu")
		(net "M_C_CPU0_SA_CS_N<0>")
	)
	(segment
		(start 298.018962 -248.138442)
		(end 298.018962 -248.073164)
		(width 0.14478)
		(layer "In2.Cu")
		(net "M_C_CPU0_SA_CS_N<0>")
	)
	(segment
		(start 298.412408 -248.30151)
		(end 298.18203 -248.30151)
		(width 0.14478)
		(layer "In2.Cu")
		(net "M_C_CPU0_SA_CS_N<0>")
	)
	(segment
		(start 298.575476 -248.073164)
		(end 298.575476 -248.138442)
		(width 0.14478)
		(layer "In2.Cu")
		(net "M_C_CPU0_SA_CS_N<0>")
	)
	(segment
		(start 306.027328 -248.29389)
		(end 305.79695 -248.29389)
		(width 0.14478)
		(layer "In2.Cu")
		(net "M_C_CPU0_SA_CS_N<0>")
	)
	(segment
		(start 305.633882 -248.073164)
		(end 305.470814 -247.910096)
		(width 0.14478)
		(layer "In2.Cu")
		(net "M_C_CPU0_SA_CS_N<0>")
	)
	(segment
		(start 322.009262 -251.87021)
		(end 320.988182 -250.84913)
		(width 0.14478)
		(layer "In2.Cu")
		(net "M_C_CPU0_SA_CS_N<0>")
	)
	(segment
		(start 297.462448 -248.138442)
		(end 297.29938 -248.30151)
		(width 0.14478)
		(layer "In2.Cu")
		(net "M_C_CPU0_SA_CS_N<0>")
	)
	(segment
		(start 331.238098 -251.451618)
		(end 331.229716 -251.446792)
		(width 0.0889)
		(layer "In2.Cu")
		(net "M_C_CPU0_SA_CS_N<0>")
	)
	(segment
		(start 314.252356 -251.519436)
		(end 311.741312 -251.519436)
		(width 0.14478)
		(layer "In2.Cu")
		(net "M_C_CPU0_SA_CS_N<0>")
	)
	(segment
		(start 305.633882 -248.130822)
		(end 305.633882 -248.073164)
		(width 0.14478)
		(layer "In2.Cu")
		(net "M_C_CPU0_SA_CS_N<0>")
	)
	(segment
		(start 304.520854 -248.073164)
		(end 304.357786 -247.910096)
		(width 0.14478)
		(layer "In2.Cu")
		(net "M_C_CPU0_SA_CS_N<0>")
	)
	(segment
		(start 298.18203 -248.30151)
		(end 298.018962 -248.138442)
		(width 0.14478)
		(layer "In2.Cu")
		(net "M_C_CPU0_SA_CS_N<0>")
	)
	(segment
		(start 301.982378 -248.30151)
		(end 301.752 -248.30151)
		(width 0.14478)
		(layer "In2.Cu")
		(net "M_C_CPU0_SA_CS_N<0>")
	)
	(segment
		(start 304.683922 -248.29389)
		(end 304.520854 -248.130822)
		(width 0.14478)
		(layer "In2.Cu")
		(net "M_C_CPU0_SA_CS_N<0>")
	)
	(segment
		(start 296.742866 -247.910096)
		(end 294.700706 -247.910096)
		(width 0.14478)
		(layer "In2.Cu")
		(net "M_C_CPU0_SA_CS_N<0>")
	)
	(segment
		(start 301.588932 -248.138442)
		(end 301.588932 -248.073164)
		(width 0.14478)
		(layer "In2.Cu")
		(net "M_C_CPU0_SA_CS_N<0>")
	)
	(segment
		(start 296.905934 -248.138442)
		(end 296.905934 -248.073164)
		(width 0.14478)
		(layer "In2.Cu")
		(net "M_C_CPU0_SA_CS_N<0>")
	)
	(segment
		(start 300.86935 -248.30151)
		(end 300.638972 -248.30151)
		(width 0.14478)
		(layer "In2.Cu")
		(net "M_C_CPU0_SA_CS_N<0>")
	)
	(segment
		(start 297.29938 -248.30151)
		(end 297.069002 -248.30151)
		(width 0.14478)
		(layer "In2.Cu")
		(net "M_C_CPU0_SA_CS_N<0>")
	)
	(segment
		(start 305.077368 -248.130822)
		(end 304.9143 -248.29389)
		(width 0.14478)
		(layer "In2.Cu")
		(net "M_C_CPU0_SA_CS_N<0>")
	)
	(segment
		(start 315.870844 -250.84913)
		(end 314.252356 -251.519436)
		(width 0.14478)
		(layer "In2.Cu")
		(net "M_C_CPU0_SA_CS_N<0>")
	)
	(segment
		(start 302.145446 -248.073164)
		(end 302.145446 -248.138442)
		(width 0.14478)
		(layer "In2.Cu")
		(net "M_C_CPU0_SA_CS_N<0>")
	)
	(segment
		(start 301.032418 -248.073164)
		(end 301.032418 -248.138442)
		(width 0.14478)
		(layer "In2.Cu")
		(net "M_C_CPU0_SA_CS_N<0>")
	)
	(segment
		(start 308.131972 -247.910096)
		(end 306.353464 -247.910096)
		(width 0.14478)
		(layer "In2.Cu")
		(net "M_C_CPU0_SA_CS_N<0>")
	)
	(segment
		(start 326.538082 -251.451618)
		(end 326.526398 -251.44476)
		(width 0.0889)
		(layer "In2.Cu")
		(net "M_C_CPU0_SA_CS_N<0>")
	)
	(segment
		(start 305.79695 -248.29389)
		(end 305.633882 -248.130822)
		(width 0.14478)
		(layer "In2.Cu")
		(net "M_C_CPU0_SA_CS_N<0>")
	)
	(segment
		(start 342.33104 -251.774198)
		(end 342.177116 -251.508768)
		(width 0.0889)
		(layer "In2.Cu")
		(net "M_C_CPU0_SA_CS_N<0>")
	)
	(segment
		(start 297.462448 -248.073164)
		(end 297.462448 -248.138442)
		(width 0.14478)
		(layer "In2.Cu")
		(net "M_C_CPU0_SA_CS_N<0>")
	)
	(segment
		(start 298.575476 -248.138442)
		(end 298.412408 -248.30151)
		(width 0.14478)
		(layer "In2.Cu")
		(net "M_C_CPU0_SA_CS_N<0>")
	)
	(segment
		(start 300.475904 -248.073164)
		(end 300.312836 -247.910096)
		(width 0.14478)
		(layer "In2.Cu")
		(net "M_C_CPU0_SA_CS_N<0>")
	)
	(segment
		(start 327.103486 -251.451872)
		(end 327.097898 -251.455174)
		(width 0.0889)
		(layer "In2.Cu")
		(net "M_C_CPU0_SA_CS_N<0>")
	)
	(segment
		(start 300.312836 -247.910096)
		(end 298.738544 -247.910096)
		(width 0.14478)
		(layer "In2.Cu")
		(net "M_C_CPU0_SA_CS_N<0>")
	)
	(segment
		(start 320.988182 -250.84913)
		(end 315.870844 -250.84913)
		(width 0.14478)
		(layer "In2.Cu")
		(net "M_C_CPU0_SA_CS_N<0>")
	)
	(segment
		(start 298.018962 -248.073164)
		(end 297.855894 -247.910096)
		(width 0.14478)
		(layer "In2.Cu")
		(net "M_C_CPU0_SA_CS_N<0>")
	)
	(segment
		(start 304.9143 -248.29389)
		(end 304.683922 -248.29389)
		(width 0.14478)
		(layer "In2.Cu")
		(net "M_C_CPU0_SA_CS_N<0>")
	)
	(segment
		(start 301.425864 -247.910096)
		(end 301.195486 -247.910096)
		(width 0.14478)
		(layer "In2.Cu")
		(net "M_C_CPU0_SA_CS_N<0>")
	)
	(segment
		(start 305.077368 -248.073164)
		(end 305.077368 -248.130822)
		(width 0.14478)
		(layer "In2.Cu")
		(net "M_C_CPU0_SA_CS_N<0>")
	)
	(segment
		(start 301.032418 -248.138442)
		(end 300.86935 -248.30151)
		(width 0.14478)
		(layer "In2.Cu")
		(net "M_C_CPU0_SA_CS_N<0>")
	)
	(segment
		(start 294.700706 -247.910096)
		(end 292.99662 -246.20601)
		(width 0.14478)
		(layer "In2.Cu")
		(net "M_C_CPU0_SA_CS_N<0>")
	)
	(segment
		(start 332.752446 -251.446792)
		(end 332.744064 -251.451618)
		(width 0.0889)
		(layer "In2.Cu")
		(net "M_C_CPU0_SA_CS_N<0>")
	)
	(segment
		(start 297.855894 -247.910096)
		(end 297.625516 -247.910096)
		(width 0.14478)
		(layer "In2.Cu")
		(net "M_C_CPU0_SA_CS_N<0>")
	)
	(segment
		(start 327.121774 -251.441458)
		(end 327.103486 -251.451872)
		(width 0.0889)
		(layer "In2.Cu")
		(net "M_C_CPU0_SA_CS_N<0>")
	)
	(segment
		(start 304.357786 -247.910096)
		(end 302.308514 -247.910096)
		(width 0.14478)
		(layer "In2.Cu")
		(net "M_C_CPU0_SA_CS_N<0>")
	)
	(segment
		(start 340.63813 -251.451618)
		(end 340.629748 -251.446792)
		(width 0.0889)
		(layer "In2.Cu")
		(net "M_C_CPU0_SA_CS_N<0>")
	)
	(segment
		(start 297.069002 -248.30151)
		(end 296.905934 -248.138442)
		(width 0.14478)
		(layer "In2.Cu")
		(net "M_C_CPU0_SA_CS_N<0>")
	)
	(segment
		(start 341.212424 -251.446792)
		(end 341.204042 -251.451618)
		(width 0.0889)
		(layer "In2.Cu")
		(net "M_C_CPU0_SA_CS_N<0>")
	)
	(segment
		(start 302.145446 -248.138442)
		(end 301.982378 -248.30151)
		(width 0.14478)
		(layer "In2.Cu")
		(net "M_C_CPU0_SA_CS_N<0>")
	)
	(segment
		(start 324.421754 -251.649992)
		(end 324.201536 -251.87021)
		(width 0.14478)
		(layer "In2.Cu")
		(net "M_C_CPU0_SA_CS_N<0>")
	)
	(segment
		(start 305.470814 -247.910096)
		(end 305.240436 -247.910096)
		(width 0.14478)
		(layer "In2.Cu")
		(net "M_C_CPU0_SA_CS_N<0>")
	)
	(segment
		(start 301.588932 -248.073164)
		(end 301.425864 -247.910096)
		(width 0.14478)
		(layer "In2.Cu")
		(net "M_C_CPU0_SA_CS_N<0>")
	)
	(segment
		(start 324.201536 -251.87021)
		(end 322.009262 -251.87021)
		(width 0.14478)
		(layer "In2.Cu")
		(net "M_C_CPU0_SA_CS_N<0>")
	)
	(segment
		(start 302.308514 -247.910096)
		(end 302.145446 -248.073164)
		(width 0.14478)
		(layer "In2.Cu")
		(net "M_C_CPU0_SA_CS_N<0>")
	)
	(segment
		(start 304.520854 -248.130822)
		(end 304.520854 -248.073164)
		(width 0.14478)
		(layer "In2.Cu")
		(net "M_C_CPU0_SA_CS_N<0>")
	)
	(segment
		(start 300.638972 -248.30151)
		(end 300.475904 -248.138442)
		(width 0.14478)
		(layer "In2.Cu")
		(net "M_C_CPU0_SA_CS_N<0>")
	)
	(segment
		(start 305.240436 -247.910096)
		(end 305.077368 -248.073164)
		(width 0.14478)
		(layer "In2.Cu")
		(net "M_C_CPU0_SA_CS_N<0>")
	)
	(arc
		(start 333.118206 -251.451618)
		(mid 332.935955 -251.401268)
		(end 332.752446 -251.446792)
		(width 0.0889)
		(layer "In2.Cu")
		(net "M_C_CPU0_SA_CS_N<0>")
	)
	(arc
		(start 337.44408 -251.451618)
		(mid 337.161124 -251.527795)
		(end 336.878168 -251.451618)
		(width 0.0889)
		(layer "In2.Cu")
		(net "M_C_CPU0_SA_CS_N<0>")
	)
	(arc
		(start 335.929732 -251.446792)
		(mid 335.746224 -251.401298)
		(end 335.563972 -251.451618)
		(width 0.0889)
		(layer "In2.Cu")
		(net "M_C_CPU0_SA_CS_N<0>")
	)
	(arc
		(start 326.086978 -251.510038)
		(mid 325.951679 -251.600442)
		(end 325.792084 -251.632212)
		(width 0.0889)
		(layer "In2.Cu")
		(net "M_C_CPU0_SA_CS_N<0>")
	)
	(arc
		(start 335.563972 -251.451618)
		(mid 335.281016 -251.527795)
		(end 334.99806 -251.451618)
		(width 0.0889)
		(layer "In2.Cu")
		(net "M_C_CPU0_SA_CS_N<0>")
	)
	(arc
		(start 337.818222 -251.451618)
		(mid 337.635971 -251.401268)
		(end 337.452462 -251.446792)
		(width 0.0889)
		(layer "In2.Cu")
		(net "M_C_CPU0_SA_CS_N<0>")
	)
	(arc
		(start 329.358244 -251.451618)
		(mid 329.175993 -251.401268)
		(end 328.992484 -251.446792)
		(width 0.0889)
		(layer "In2.Cu")
		(net "M_C_CPU0_SA_CS_N<0>")
	)
	(arc
		(start 336.869786 -251.446792)
		(mid 336.686278 -251.401298)
		(end 336.504026 -251.451618)
		(width 0.0889)
		(layer "In2.Cu")
		(net "M_C_CPU0_SA_CS_N<0>")
	)
	(arc
		(start 339.698076 -251.451618)
		(mid 339.511132 -251.401363)
		(end 339.324188 -251.451618)
		(width 0.0889)
		(layer "In2.Cu")
		(net "M_C_CPU0_SA_CS_N<0>")
	)
	(arc
		(start 334.624172 -251.451618)
		(mid 334.341216 -251.527795)
		(end 334.05826 -251.451618)
		(width 0.0889)
		(layer "In2.Cu")
		(net "M_C_CPU0_SA_CS_N<0>")
	)
	(arc
		(start 328.029316 -251.460254)
		(mid 327.752333 -251.528058)
		(end 327.477628 -251.451618)
		(width 0.0889)
		(layer "In2.Cu")
		(net "M_C_CPU0_SA_CS_N<0>")
	)
	(arc
		(start 333.684118 -251.451618)
		(mid 333.401162 -251.527795)
		(end 333.118206 -251.451618)
		(width 0.0889)
		(layer "In2.Cu")
		(net "M_C_CPU0_SA_CS_N<0>")
	)
	(arc
		(start 336.504026 -251.451618)
		(mid 336.22107 -251.527795)
		(end 335.938114 -251.451618)
		(width 0.0889)
		(layer "In2.Cu")
		(net "M_C_CPU0_SA_CS_N<0>")
	)
	(arc
		(start 331.229716 -251.446792)
		(mid 331.046208 -251.401298)
		(end 330.863956 -251.451618)
		(width 0.0889)
		(layer "In2.Cu")
		(net "M_C_CPU0_SA_CS_N<0>")
	)
	(arc
		(start 328.984102 -251.451618)
		(mid 328.701146 -251.527795)
		(end 328.41819 -251.451618)
		(width 0.0889)
		(layer "In2.Cu")
		(net "M_C_CPU0_SA_CS_N<0>")
	)
	(arc
		(start 330.298044 -251.451618)
		(mid 330.1111 -251.401363)
		(end 329.924156 -251.451618)
		(width 0.0889)
		(layer "In2.Cu")
		(net "M_C_CPU0_SA_CS_N<0>")
	)
	(arc
		(start 338.384134 -251.451618)
		(mid 338.101178 -251.527795)
		(end 337.818222 -251.451618)
		(width 0.0889)
		(layer "In2.Cu")
		(net "M_C_CPU0_SA_CS_N<0>")
	)
	(arc
		(start 341.204042 -251.451618)
		(mid 340.921086 -251.527795)
		(end 340.63813 -251.451618)
		(width 0.0889)
		(layer "In2.Cu")
		(net "M_C_CPU0_SA_CS_N<0>")
	)
	(arc
		(start 340.263988 -251.451618)
		(mid 339.981032 -251.527795)
		(end 339.698076 -251.451618)
		(width 0.0889)
		(layer "In2.Cu")
		(net "M_C_CPU0_SA_CS_N<0>")
	)
	(arc
		(start 338.758276 -251.451618)
		(mid 338.576025 -251.401268)
		(end 338.392516 -251.446792)
		(width 0.0889)
		(layer "In2.Cu")
		(net "M_C_CPU0_SA_CS_N<0>")
	)
	(arc
		(start 327.097898 -251.455174)
		(mid 326.817509 -251.527843)
		(end 326.538082 -251.451618)
		(width 0.0889)
		(layer "In2.Cu")
		(net "M_C_CPU0_SA_CS_N<0>")
	)
	(arc
		(start 327.477628 -251.451618)
		(mid 327.301 -251.401385)
		(end 327.121774 -251.441458)
		(width 0.0889)
		(layer "In2.Cu")
		(net "M_C_CPU0_SA_CS_N<0>")
	)
	(arc
		(start 334.99806 -251.451618)
		(mid 334.811116 -251.401363)
		(end 334.624172 -251.451618)
		(width 0.0889)
		(layer "In2.Cu")
		(net "M_C_CPU0_SA_CS_N<0>")
	)
	(arc
		(start 329.924156 -251.451618)
		(mid 329.6412 -251.527795)
		(end 329.358244 -251.451618)
		(width 0.0889)
		(layer "In2.Cu")
		(net "M_C_CPU0_SA_CS_N<0>")
	)
	(arc
		(start 326.163686 -251.451618)
		(mid 326.123431 -251.478333)
		(end 326.086978 -251.510038)
		(width 0.0889)
		(layer "In2.Cu")
		(net "M_C_CPU0_SA_CS_N<0>")
	)
	(arc
		(start 339.324188 -251.451618)
		(mid 339.041232 -251.527795)
		(end 338.758276 -251.451618)
		(width 0.0889)
		(layer "In2.Cu")
		(net "M_C_CPU0_SA_CS_N<0>")
	)
	(arc
		(start 330.863956 -251.451618)
		(mid 330.581 -251.527795)
		(end 330.298044 -251.451618)
		(width 0.0889)
		(layer "In2.Cu")
		(net "M_C_CPU0_SA_CS_N<0>")
	)
	(arc
		(start 341.578184 -251.451618)
		(mid 341.395933 -251.401268)
		(end 341.212424 -251.446792)
		(width 0.0889)
		(layer "In2.Cu")
		(net "M_C_CPU0_SA_CS_N<0>")
	)
	(arc
		(start 326.526398 -251.44476)
		(mid 326.344143 -251.401107)
		(end 326.163686 -251.451618)
		(width 0.0889)
		(layer "In2.Cu")
		(net "M_C_CPU0_SA_CS_N<0>")
	)
	(arc
		(start 340.629748 -251.446792)
		(mid 340.44624 -251.401298)
		(end 340.263988 -251.451618)
		(width 0.0889)
		(layer "In2.Cu")
		(net "M_C_CPU0_SA_CS_N<0>")
	)
	(arc
		(start 334.05826 -251.451618)
		(mid 333.876009 -251.401268)
		(end 333.6925 -251.446792)
		(width 0.0889)
		(layer "In2.Cu")
		(net "M_C_CPU0_SA_CS_N<0>")
	)
	(arc
		(start 328.409808 -251.446792)
		(mid 328.2263 -251.401298)
		(end 328.044048 -251.451618)
		(width 0.0889)
		(layer "In2.Cu")
		(net "M_C_CPU0_SA_CS_N<0>")
	)
	(arc
		(start 342.081104 -251.483368)
		(mid 341.825896 -251.526845)
		(end 341.578184 -251.451618)
		(width 0.0889)
		(layer "In2.Cu")
		(net "M_C_CPU0_SA_CS_N<0>")
	)
	(arc
		(start 332.16977 -251.446792)
		(mid 331.986262 -251.401298)
		(end 331.80401 -251.451618)
		(width 0.0889)
		(layer "In2.Cu")
		(net "M_C_CPU0_SA_CS_N<0>")
	)
	(arc
		(start 331.80401 -251.451618)
		(mid 331.521054 -251.527795)
		(end 331.238098 -251.451618)
		(width 0.0889)
		(layer "In2.Cu")
		(net "M_C_CPU0_SA_CS_N<0>")
	)
	(arc
		(start 332.744064 -251.451618)
		(mid 332.461108 -251.527795)
		(end 332.178152 -251.451618)
		(width 0.0889)
		(layer "In2.Cu")
		(net "M_C_CPU0_SA_CS_N<0>")
	)
	(segment
		(start 344.207846 -249.610118)
		(end 343.740994 -249.34418)
		(width 0.10668)
		(layer "F.Cu")
		(net "M_C_CPU0_SA_CB<7>")
	)
	(segment
		(start 290.459922 -242.940332)
		(end 290.296854 -243.1034)
		(width 0.14478)
		(layer "In2.Cu")
		(net "M_C_CPU0_SA_CB<7>")
	)
	(segment
		(start 325.889874 -249.24131)
		(end 324.563994 -249.24131)
		(width 0.0889)
		(layer "In2.Cu")
		(net "M_C_CPU0_SA_CB<7>")
	)
	(segment
		(start 290.853368 -243.4971)
		(end 290.853368 -243.1034)
		(width 0.14478)
		(layer "In2.Cu")
		(net "M_C_CPU0_SA_CB<7>")
	)
	(segment
		(start 327.575418 -249.021854)
		(end 327.549256 -249.03684)
		(width 0.0889)
		(layer "In2.Cu")
		(net "M_C_CPU0_SA_CB<7>")
	)
	(segment
		(start 300.985682 -242.81003)
		(end 298.218352 -242.81003)
		(width 0.14478)
		(layer "In2.Cu")
		(net "M_C_CPU0_SA_CB<7>")
	)
	(segment
		(start 338.288122 -249.0216)
		(end 338.27974 -249.016774)
		(width 0.0889)
		(layer "In2.Cu")
		(net "M_C_CPU0_SA_CB<7>")
	)
	(segment
		(start 309.353458 -245.412514)
		(end 309.353458 -244.604032)
		(width 0.14478)
		(layer "In2.Cu")
		(net "M_C_CPU0_SA_CB<7>")
	)
	(segment
		(start 301.845472 -243.66982)
		(end 300.985682 -242.81003)
		(width 0.14478)
		(layer "In2.Cu")
		(net "M_C_CPU0_SA_CB<7>")
	)
	(segment
		(start 343.740994 -249.34418)
		(end 343.58707 -249.07875)
		(width 0.0889)
		(layer "In2.Cu")
		(net "M_C_CPU0_SA_CB<7>")
	)
	(segment
		(start 335.102454 -249.016774)
		(end 335.094072 -249.0216)
		(width 0.0889)
		(layer "In2.Cu")
		(net "M_C_CPU0_SA_CB<7>")
	)
	(segment
		(start 342.048084 -249.0216)
		(end 342.039702 -249.016774)
		(width 0.0889)
		(layer "In2.Cu")
		(net "M_C_CPU0_SA_CB<7>")
	)
	(segment
		(start 290.853368 -243.1034)
		(end 290.6903 -242.940332)
		(width 0.14478)
		(layer "In2.Cu")
		(net "M_C_CPU0_SA_CB<7>")
	)
	(segment
		(start 309.353458 -244.604032)
		(end 308.419246 -243.66982)
		(width 0.14478)
		(layer "In2.Cu")
		(net "M_C_CPU0_SA_CB<7>")
	)
	(segment
		(start 326.636126 -249.0216)
		(end 326.579738 -249.05462)
		(width 0.0889)
		(layer "In2.Cu")
		(net "M_C_CPU0_SA_CB<7>")
	)
	(segment
		(start 324.563994 -249.24131)
		(end 324.155054 -249.65025)
		(width 0.0889)
		(layer "In2.Cu")
		(net "M_C_CPU0_SA_CB<7>")
	)
	(segment
		(start 331.342492 -249.016774)
		(end 331.33411 -249.0216)
		(width 0.0889)
		(layer "In2.Cu")
		(net "M_C_CPU0_SA_CB<7>")
	)
	(segment
		(start 291.016436 -243.660168)
		(end 290.853368 -243.4971)
		(width 0.14478)
		(layer "In2.Cu")
		(net "M_C_CPU0_SA_CB<7>")
	)
	(segment
		(start 342.988138 -249.0216)
		(end 342.979756 -249.016774)
		(width 0.0889)
		(layer "In2.Cu")
		(net "M_C_CPU0_SA_CB<7>")
	)
	(segment
		(start 330.402438 -249.016774)
		(end 330.394056 -249.0216)
		(width 0.0889)
		(layer "In2.Cu")
		(net "M_C_CPU0_SA_CB<7>")
	)
	(segment
		(start 290.6903 -242.940332)
		(end 290.459922 -242.940332)
		(width 0.14478)
		(layer "In2.Cu")
		(net "M_C_CPU0_SA_CB<7>")
	)
	(segment
		(start 329.828144 -249.0216)
		(end 329.819762 -249.016774)
		(width 0.0889)
		(layer "In2.Cu")
		(net "M_C_CPU0_SA_CB<7>")
	)
	(segment
		(start 312.872374 -248.93143)
		(end 309.353458 -245.412514)
		(width 0.14478)
		(layer "In2.Cu")
		(net "M_C_CPU0_SA_CB<7>")
	)
	(segment
		(start 333.588106 -249.0216)
		(end 333.579724 -249.016774)
		(width 0.0889)
		(layer "In2.Cu")
		(net "M_C_CPU0_SA_CB<7>")
	)
	(segment
		(start 290.133786 -243.660168)
		(end 288.605214 -243.660168)
		(width 0.14478)
		(layer "In2.Cu")
		(net "M_C_CPU0_SA_CB<7>")
	)
	(segment
		(start 334.52816 -249.0216)
		(end 334.519778 -249.016774)
		(width 0.0889)
		(layer "In2.Cu")
		(net "M_C_CPU0_SA_CB<7>")
	)
	(segment
		(start 343.58707 -249.07875)
		(end 343.491058 -249.05335)
		(width 0.0889)
		(layer "In2.Cu")
		(net "M_C_CPU0_SA_CB<7>")
	)
	(segment
		(start 290.296854 -243.1034)
		(end 290.296854 -243.4971)
		(width 0.14478)
		(layer "In2.Cu")
		(net "M_C_CPU0_SA_CB<7>")
	)
	(segment
		(start 297.368214 -243.660168)
		(end 291.016436 -243.660168)
		(width 0.14478)
		(layer "In2.Cu")
		(net "M_C_CPU0_SA_CB<7>")
	)
	(segment
		(start 338.862416 -249.016774)
		(end 338.854034 -249.0216)
		(width 0.0889)
		(layer "In2.Cu")
		(net "M_C_CPU0_SA_CB<7>")
	)
	(segment
		(start 288.605214 -243.660168)
		(end 288.180018 -243.234972)
		(width 0.14478)
		(layer "In2.Cu")
		(net "M_C_CPU0_SA_CB<7>")
	)
	(segment
		(start 327.598786 -249.008392)
		(end 327.575418 -249.021854)
		(width 0.0889)
		(layer "In2.Cu")
		(net "M_C_CPU0_SA_CB<7>")
	)
	(segment
		(start 298.218352 -242.81003)
		(end 297.368214 -243.660168)
		(width 0.14478)
		(layer "In2.Cu")
		(net "M_C_CPU0_SA_CB<7>")
	)
	(segment
		(start 322.501514 -249.65025)
		(end 321.782694 -248.93143)
		(width 0.14478)
		(layer "In2.Cu")
		(net "M_C_CPU0_SA_CB<7>")
	)
	(segment
		(start 324.155054 -249.65025)
		(end 323.901054 -249.65025)
		(width 0.0889)
		(layer "In2.Cu")
		(net "M_C_CPU0_SA_CB<7>")
	)
	(segment
		(start 339.80247 -249.016774)
		(end 339.794088 -249.0216)
		(width 0.0889)
		(layer "In2.Cu")
		(net "M_C_CPU0_SA_CB<7>")
	)
	(segment
		(start 321.782694 -248.93143)
		(end 312.872374 -248.93143)
		(width 0.14478)
		(layer "In2.Cu")
		(net "M_C_CPU0_SA_CB<7>")
	)
	(segment
		(start 336.042508 -249.016774)
		(end 336.034126 -249.0216)
		(width 0.0889)
		(layer "In2.Cu")
		(net "M_C_CPU0_SA_CB<7>")
	)
	(segment
		(start 308.419246 -243.66982)
		(end 301.845472 -243.66982)
		(width 0.14478)
		(layer "In2.Cu")
		(net "M_C_CPU0_SA_CB<7>")
	)
	(segment
		(start 327.011538 -249.0216)
		(end 326.990964 -249.009662)
		(width 0.0889)
		(layer "In2.Cu")
		(net "M_C_CPU0_SA_CB<7>")
	)
	(segment
		(start 323.901054 -249.65025)
		(end 322.501514 -249.65025)
		(width 0.14478)
		(layer "In2.Cu")
		(net "M_C_CPU0_SA_CB<7>")
	)
	(segment
		(start 290.296854 -243.4971)
		(end 290.133786 -243.660168)
		(width 0.14478)
		(layer "In2.Cu")
		(net "M_C_CPU0_SA_CB<7>")
	)
	(arc
		(start 334.519778 -249.016774)
		(mid 334.33627 -248.97128)
		(end 334.154018 -249.0216)
		(width 0.0889)
		(layer "In2.Cu")
		(net "M_C_CPU0_SA_CB<7>")
	)
	(arc
		(start 329.454002 -249.0216)
		(mid 329.171046 -249.097777)
		(end 328.88809 -249.0216)
		(width 0.0889)
		(layer "In2.Cu")
		(net "M_C_CPU0_SA_CB<7>")
	)
	(arc
		(start 342.039702 -249.016774)
		(mid 341.856194 -248.97128)
		(end 341.673942 -249.0216)
		(width 0.0889)
		(layer "In2.Cu")
		(net "M_C_CPU0_SA_CB<7>")
	)
	(arc
		(start 340.734142 -249.0216)
		(mid 340.451186 -249.097777)
		(end 340.16823 -249.0216)
		(width 0.0889)
		(layer "In2.Cu")
		(net "M_C_CPU0_SA_CB<7>")
	)
	(arc
		(start 336.408268 -249.0216)
		(mid 336.226017 -248.97125)
		(end 336.042508 -249.016774)
		(width 0.0889)
		(layer "In2.Cu")
		(net "M_C_CPU0_SA_CB<7>")
	)
	(arc
		(start 339.228176 -249.0216)
		(mid 339.045925 -248.97125)
		(end 338.862416 -249.016774)
		(width 0.0889)
		(layer "In2.Cu")
		(net "M_C_CPU0_SA_CB<7>")
	)
	(arc
		(start 338.27974 -249.016774)
		(mid 338.096232 -248.97128)
		(end 337.91398 -249.0216)
		(width 0.0889)
		(layer "In2.Cu")
		(net "M_C_CPU0_SA_CB<7>")
	)
	(arc
		(start 337.348068 -249.0216)
		(mid 337.161124 -248.971345)
		(end 336.97418 -249.0216)
		(width 0.0889)
		(layer "In2.Cu")
		(net "M_C_CPU0_SA_CB<7>")
	)
	(arc
		(start 329.819762 -249.016774)
		(mid 329.636254 -248.97128)
		(end 329.454002 -249.0216)
		(width 0.0889)
		(layer "In2.Cu")
		(net "M_C_CPU0_SA_CB<7>")
	)
	(arc
		(start 341.673942 -249.0216)
		(mid 341.390986 -249.097777)
		(end 341.10803 -249.0216)
		(width 0.0889)
		(layer "In2.Cu")
		(net "M_C_CPU0_SA_CB<7>")
	)
	(arc
		(start 342.979756 -249.016774)
		(mid 342.796248 -248.97128)
		(end 342.613996 -249.0216)
		(width 0.0889)
		(layer "In2.Cu")
		(net "M_C_CPU0_SA_CB<7>")
	)
	(arc
		(start 328.514202 -249.0216)
		(mid 328.231246 -249.097777)
		(end 327.94829 -249.0216)
		(width 0.0889)
		(layer "In2.Cu")
		(net "M_C_CPU0_SA_CB<7>")
	)
	(arc
		(start 332.648052 -249.0216)
		(mid 332.461108 -248.971345)
		(end 332.274164 -249.0216)
		(width 0.0889)
		(layer "In2.Cu")
		(net "M_C_CPU0_SA_CB<7>")
	)
	(arc
		(start 328.88809 -249.0216)
		(mid 328.701146 -248.971345)
		(end 328.514202 -249.0216)
		(width 0.0889)
		(layer "In2.Cu")
		(net "M_C_CPU0_SA_CB<7>")
	)
	(arc
		(start 326.579738 -249.05462)
		(mid 326.247221 -249.193855)
		(end 325.889874 -249.24131)
		(width 0.0889)
		(layer "In2.Cu")
		(net "M_C_CPU0_SA_CB<7>")
	)
	(arc
		(start 337.91398 -249.0216)
		(mid 337.631024 -249.097777)
		(end 337.348068 -249.0216)
		(width 0.0889)
		(layer "In2.Cu")
		(net "M_C_CPU0_SA_CB<7>")
	)
	(arc
		(start 338.854034 -249.0216)
		(mid 338.571078 -249.097777)
		(end 338.288122 -249.0216)
		(width 0.0889)
		(layer "In2.Cu")
		(net "M_C_CPU0_SA_CB<7>")
	)
	(arc
		(start 336.97418 -249.0216)
		(mid 336.691224 -249.097777)
		(end 336.408268 -249.0216)
		(width 0.0889)
		(layer "In2.Cu")
		(net "M_C_CPU0_SA_CB<7>")
	)
	(arc
		(start 343.491058 -249.05335)
		(mid 343.23585 -249.096827)
		(end 342.988138 -249.0216)
		(width 0.0889)
		(layer "In2.Cu")
		(net "M_C_CPU0_SA_CB<7>")
	)
	(arc
		(start 333.213964 -249.0216)
		(mid 332.931008 -249.097777)
		(end 332.648052 -249.0216)
		(width 0.0889)
		(layer "In2.Cu")
		(net "M_C_CPU0_SA_CB<7>")
	)
	(arc
		(start 327.549256 -249.03684)
		(mid 327.27847 -249.097486)
		(end 327.011538 -249.0216)
		(width 0.0889)
		(layer "In2.Cu")
		(net "M_C_CPU0_SA_CB<7>")
	)
	(arc
		(start 332.274164 -249.0216)
		(mid 331.991208 -249.097777)
		(end 331.708252 -249.0216)
		(width 0.0889)
		(layer "In2.Cu")
		(net "M_C_CPU0_SA_CB<7>")
	)
	(arc
		(start 333.579724 -249.016774)
		(mid 333.396216 -248.97128)
		(end 333.213964 -249.0216)
		(width 0.0889)
		(layer "In2.Cu")
		(net "M_C_CPU0_SA_CB<7>")
	)
	(arc
		(start 336.034126 -249.0216)
		(mid 335.75117 -249.097777)
		(end 335.468214 -249.0216)
		(width 0.0889)
		(layer "In2.Cu")
		(net "M_C_CPU0_SA_CB<7>")
	)
	(arc
		(start 331.708252 -249.0216)
		(mid 331.526001 -248.97125)
		(end 331.342492 -249.016774)
		(width 0.0889)
		(layer "In2.Cu")
		(net "M_C_CPU0_SA_CB<7>")
	)
	(arc
		(start 339.794088 -249.0216)
		(mid 339.511132 -249.097777)
		(end 339.228176 -249.0216)
		(width 0.0889)
		(layer "In2.Cu")
		(net "M_C_CPU0_SA_CB<7>")
	)
	(arc
		(start 334.154018 -249.0216)
		(mid 333.871062 -249.097777)
		(end 333.588106 -249.0216)
		(width 0.0889)
		(layer "In2.Cu")
		(net "M_C_CPU0_SA_CB<7>")
	)
	(arc
		(start 335.094072 -249.0216)
		(mid 334.811116 -249.097777)
		(end 334.52816 -249.0216)
		(width 0.0889)
		(layer "In2.Cu")
		(net "M_C_CPU0_SA_CB<7>")
	)
	(arc
		(start 340.16823 -249.0216)
		(mid 339.985979 -248.97125)
		(end 339.80247 -249.016774)
		(width 0.0889)
		(layer "In2.Cu")
		(net "M_C_CPU0_SA_CB<7>")
	)
	(arc
		(start 330.768198 -249.0216)
		(mid 330.585947 -248.97125)
		(end 330.402438 -249.016774)
		(width 0.0889)
		(layer "In2.Cu")
		(net "M_C_CPU0_SA_CB<7>")
	)
	(arc
		(start 330.394056 -249.0216)
		(mid 330.1111 -249.097777)
		(end 329.828144 -249.0216)
		(width 0.0889)
		(layer "In2.Cu")
		(net "M_C_CPU0_SA_CB<7>")
	)
	(arc
		(start 327.94829 -249.0216)
		(mid 327.775182 -248.971484)
		(end 327.598786 -249.008392)
		(width 0.0889)
		(layer "In2.Cu")
		(net "M_C_CPU0_SA_CB<7>")
	)
	(arc
		(start 342.613996 -249.0216)
		(mid 342.33104 -249.097777)
		(end 342.048084 -249.0216)
		(width 0.0889)
		(layer "In2.Cu")
		(net "M_C_CPU0_SA_CB<7>")
	)
	(arc
		(start 341.10803 -249.0216)
		(mid 340.921086 -248.971345)
		(end 340.734142 -249.0216)
		(width 0.0889)
		(layer "In2.Cu")
		(net "M_C_CPU0_SA_CB<7>")
	)
	(arc
		(start 335.468214 -249.0216)
		(mid 335.285963 -248.97125)
		(end 335.102454 -249.016774)
		(width 0.0889)
		(layer "In2.Cu")
		(net "M_C_CPU0_SA_CB<7>")
	)
	(arc
		(start 331.33411 -249.0216)
		(mid 331.051154 -249.097777)
		(end 330.768198 -249.0216)
		(width 0.0889)
		(layer "In2.Cu")
		(net "M_C_CPU0_SA_CB<7>")
	)
	(arc
		(start 326.990964 -249.009662)
		(mid 326.812036 -248.970785)
		(end 326.636126 -249.0216)
		(width 0.0889)
		(layer "In2.Cu")
		(net "M_C_CPU0_SA_CB<7>")
	)
	(segment
		(start 342.797892 -248.800112)
		(end 342.33104 -248.534174)
		(width 0.10668)
		(layer "F.Cu")
		(net "M_C_CPU0_SA_CB<6>")
	)
	(segment
		(start 291.160962 -241.797078)
		(end 291.32403 -241.960146)
		(width 0.14478)
		(layer "In2.Cu")
		(net "M_C_CPU0_SA_CB<6>")
	)
	(segment
		(start 332.744064 -248.211594)
		(end 332.752446 -248.206768)
		(width 0.0889)
		(layer "In2.Cu")
		(net "M_C_CPU0_SA_CB<6>")
	)
	(segment
		(start 337.44408 -248.211594)
		(end 337.452462 -248.206768)
		(width 0.0889)
		(layer "In2.Cu")
		(net "M_C_CPU0_SA_CB<6>")
	)
	(segment
		(start 290.604448 -240.913158)
		(end 290.767516 -240.75009)
		(width 0.14478)
		(layer "In2.Cu")
		(net "M_C_CPU0_SA_CB<6>")
	)
	(segment
		(start 336.869786 -248.206768)
		(end 336.878168 -248.211594)
		(width 0.0889)
		(layer "In2.Cu")
		(net "M_C_CPU0_SA_CB<6>")
	)
	(segment
		(start 323.878194 -248.72061)
		(end 325.592694 -248.72061)
		(width 0.0889)
		(layer "In2.Cu")
		(net "M_C_CPU0_SA_CB<6>")
	)
	(segment
		(start 333.684118 -248.211594)
		(end 333.6925 -248.206768)
		(width 0.0889)
		(layer "In2.Cu")
		(net "M_C_CPU0_SA_CB<6>")
	)
	(segment
		(start 339.689694 -248.206768)
		(end 339.698076 -248.211594)
		(width 0.0889)
		(layer "In2.Cu")
		(net "M_C_CPU0_SA_CB<6>")
	)
	(segment
		(start 311.839356 -246.402352)
		(end 313.220862 -246.402352)
		(width 0.14478)
		(layer "In2.Cu")
		(net "M_C_CPU0_SA_CB<6>")
	)
	(segment
		(start 290.997894 -240.75009)
		(end 291.160962 -240.913158)
		(width 0.14478)
		(layer "In2.Cu")
		(net "M_C_CPU0_SA_CB<6>")
	)
	(segment
		(start 291.160962 -240.913158)
		(end 291.160962 -241.797078)
		(width 0.14478)
		(layer "In2.Cu")
		(net "M_C_CPU0_SA_CB<6>")
	)
	(segment
		(start 332.16977 -248.206768)
		(end 332.178152 -248.211594)
		(width 0.0889)
		(layer "In2.Cu")
		(net "M_C_CPU0_SA_CB<6>")
	)
	(segment
		(start 308.30901 -241.960146)
		(end 310.339994 -243.99113)
		(width 0.14478)
		(layer "In2.Cu")
		(net "M_C_CPU0_SA_CB<6>")
	)
	(segment
		(start 327.103232 -248.211594)
		(end 327.114916 -248.204736)
		(width 0.0889)
		(layer "In2.Cu")
		(net "M_C_CPU0_SA_CB<6>")
	)
	(segment
		(start 328.984102 -248.211594)
		(end 328.992484 -248.206768)
		(width 0.0889)
		(layer "In2.Cu")
		(net "M_C_CPU0_SA_CB<6>")
	)
	(segment
		(start 322.869814 -248.72061)
		(end 323.878194 -248.72061)
		(width 0.14478)
		(layer "In2.Cu")
		(net "M_C_CPU0_SA_CB<6>")
	)
	(segment
		(start 335.929732 -248.206768)
		(end 335.938114 -248.211594)
		(width 0.0889)
		(layer "In2.Cu")
		(net "M_C_CPU0_SA_CB<6>")
	)
	(segment
		(start 342.177116 -248.268744)
		(end 342.33104 -248.534174)
		(width 0.0889)
		(layer "In2.Cu")
		(net "M_C_CPU0_SA_CB<6>")
	)
	(segment
		(start 291.32403 -241.960146)
		(end 297.562778 -241.960146)
		(width 0.14478)
		(layer "In2.Cu")
		(net "M_C_CPU0_SA_CB<6>")
	)
	(segment
		(start 340.629748 -248.206768)
		(end 340.63813 -248.211594)
		(width 0.0889)
		(layer "In2.Cu")
		(net "M_C_CPU0_SA_CB<6>")
	)
	(segment
		(start 314.81141 -247.9929)
		(end 322.142104 -247.9929)
		(width 0.14478)
		(layer "In2.Cu")
		(net "M_C_CPU0_SA_CB<6>")
	)
	(segment
		(start 301.90186 -241.960146)
		(end 308.30901 -241.960146)
		(width 0.14478)
		(layer "In2.Cu")
		(net "M_C_CPU0_SA_CB<6>")
	)
	(segment
		(start 310.339994 -244.90299)
		(end 311.839356 -246.402352)
		(width 0.14478)
		(layer "In2.Cu")
		(net "M_C_CPU0_SA_CB<6>")
	)
	(segment
		(start 326.537828 -248.211848)
		(end 326.543416 -248.21515)
		(width 0.0889)
		(layer "In2.Cu")
		(net "M_C_CPU0_SA_CB<6>")
	)
	(segment
		(start 328.029316 -248.22023)
		(end 328.044048 -248.211594)
		(width 0.0889)
		(layer "In2.Cu")
		(net "M_C_CPU0_SA_CB<6>")
	)
	(segment
		(start 322.142104 -247.9929)
		(end 322.869814 -248.72061)
		(width 0.14478)
		(layer "In2.Cu")
		(net "M_C_CPU0_SA_CB<6>")
	)
	(segment
		(start 313.220862 -246.402352)
		(end 314.81141 -247.9929)
		(width 0.14478)
		(layer "In2.Cu")
		(net "M_C_CPU0_SA_CB<6>")
	)
	(segment
		(start 342.081104 -248.243344)
		(end 342.177116 -248.268744)
		(width 0.0889)
		(layer "In2.Cu")
		(net "M_C_CPU0_SA_CB<6>")
	)
	(segment
		(start 301.051722 -241.110008)
		(end 301.90186 -241.960146)
		(width 0.14478)
		(layer "In2.Cu")
		(net "M_C_CPU0_SA_CB<6>")
	)
	(segment
		(start 326.51954 -248.201434)
		(end 326.537828 -248.211848)
		(width 0.0889)
		(layer "In2.Cu")
		(net "M_C_CPU0_SA_CB<6>")
	)
	(segment
		(start 328.409808 -248.206768)
		(end 328.41819 -248.211594)
		(width 0.0889)
		(layer "In2.Cu")
		(net "M_C_CPU0_SA_CB<6>")
	)
	(segment
		(start 290.604448 -241.797078)
		(end 290.604448 -240.913158)
		(width 0.14478)
		(layer "In2.Cu")
		(net "M_C_CPU0_SA_CB<6>")
	)
	(segment
		(start 297.562778 -241.960146)
		(end 298.412916 -241.110008)
		(width 0.14478)
		(layer "In2.Cu")
		(net "M_C_CPU0_SA_CB<6>")
	)
	(segment
		(start 331.229716 -248.206768)
		(end 331.238098 -248.211594)
		(width 0.0889)
		(layer "In2.Cu")
		(net "M_C_CPU0_SA_CB<6>")
	)
	(segment
		(start 288.180018 -241.53495)
		(end 288.605214 -241.960146)
		(width 0.14478)
		(layer "In2.Cu")
		(net "M_C_CPU0_SA_CB<6>")
	)
	(segment
		(start 288.605214 -241.960146)
		(end 290.44138 -241.960146)
		(width 0.14478)
		(layer "In2.Cu")
		(net "M_C_CPU0_SA_CB<6>")
	)
	(segment
		(start 341.204042 -248.211594)
		(end 341.212424 -248.206768)
		(width 0.0889)
		(layer "In2.Cu")
		(net "M_C_CPU0_SA_CB<6>")
	)
	(segment
		(start 310.339994 -243.99113)
		(end 310.339994 -244.90299)
		(width 0.14478)
		(layer "In2.Cu")
		(net "M_C_CPU0_SA_CB<6>")
	)
	(segment
		(start 298.412916 -241.110008)
		(end 301.051722 -241.110008)
		(width 0.14478)
		(layer "In2.Cu")
		(net "M_C_CPU0_SA_CB<6>")
	)
	(segment
		(start 290.767516 -240.75009)
		(end 290.997894 -240.75009)
		(width 0.14478)
		(layer "In2.Cu")
		(net "M_C_CPU0_SA_CB<6>")
	)
	(segment
		(start 325.684134 -248.682764)
		(end 326.127364 -248.239534)
		(width 0.0889)
		(layer "In2.Cu")
		(net "M_C_CPU0_SA_CB<6>")
	)
	(segment
		(start 290.44138 -241.960146)
		(end 290.604448 -241.797078)
		(width 0.14478)
		(layer "In2.Cu")
		(net "M_C_CPU0_SA_CB<6>")
	)
	(arc
		(start 329.924156 -248.211594)
		(mid 330.1111 -248.161339)
		(end 330.298044 -248.211594)
		(width 0.0889)
		(layer "In2.Cu")
		(net "M_C_CPU0_SA_CB<6>")
	)
	(arc
		(start 331.80401 -248.211594)
		(mid 331.986261 -248.161244)
		(end 332.16977 -248.206768)
		(width 0.0889)
		(layer "In2.Cu")
		(net "M_C_CPU0_SA_CB<6>")
	)
	(arc
		(start 337.452462 -248.206768)
		(mid 337.63597 -248.161274)
		(end 337.818222 -248.211594)
		(width 0.0889)
		(layer "In2.Cu")
		(net "M_C_CPU0_SA_CB<6>")
	)
	(arc
		(start 335.938114 -248.211594)
		(mid 336.22107 -248.287771)
		(end 336.504026 -248.211594)
		(width 0.0889)
		(layer "In2.Cu")
		(net "M_C_CPU0_SA_CB<6>")
	)
	(arc
		(start 332.178152 -248.211594)
		(mid 332.461108 -248.287771)
		(end 332.744064 -248.211594)
		(width 0.0889)
		(layer "In2.Cu")
		(net "M_C_CPU0_SA_CB<6>")
	)
	(arc
		(start 334.99806 -248.211594)
		(mid 335.281016 -248.287771)
		(end 335.563972 -248.211594)
		(width 0.0889)
		(layer "In2.Cu")
		(net "M_C_CPU0_SA_CB<6>")
	)
	(arc
		(start 330.863956 -248.211594)
		(mid 331.046207 -248.161244)
		(end 331.229716 -248.206768)
		(width 0.0889)
		(layer "In2.Cu")
		(net "M_C_CPU0_SA_CB<6>")
	)
	(arc
		(start 334.624172 -248.211594)
		(mid 334.811116 -248.161339)
		(end 334.99806 -248.211594)
		(width 0.0889)
		(layer "In2.Cu")
		(net "M_C_CPU0_SA_CB<6>")
	)
	(arc
		(start 330.298044 -248.211594)
		(mid 330.581 -248.287771)
		(end 330.863956 -248.211594)
		(width 0.0889)
		(layer "In2.Cu")
		(net "M_C_CPU0_SA_CB<6>")
	)
	(arc
		(start 331.238098 -248.211594)
		(mid 331.521054 -248.287771)
		(end 331.80401 -248.211594)
		(width 0.0889)
		(layer "In2.Cu")
		(net "M_C_CPU0_SA_CB<6>")
	)
	(arc
		(start 326.163686 -248.211594)
		(mid 326.340314 -248.161361)
		(end 326.51954 -248.201434)
		(width 0.0889)
		(layer "In2.Cu")
		(net "M_C_CPU0_SA_CB<6>")
	)
	(arc
		(start 329.358244 -248.211594)
		(mid 329.6412 -248.287771)
		(end 329.924156 -248.211594)
		(width 0.0889)
		(layer "In2.Cu")
		(net "M_C_CPU0_SA_CB<6>")
	)
	(arc
		(start 340.63813 -248.211594)
		(mid 340.921086 -248.287771)
		(end 341.204042 -248.211594)
		(width 0.0889)
		(layer "In2.Cu")
		(net "M_C_CPU0_SA_CB<6>")
	)
	(arc
		(start 334.05826 -248.211594)
		(mid 334.341216 -248.287771)
		(end 334.624172 -248.211594)
		(width 0.0889)
		(layer "In2.Cu")
		(net "M_C_CPU0_SA_CB<6>")
	)
	(arc
		(start 328.044048 -248.211594)
		(mid 328.226299 -248.161244)
		(end 328.409808 -248.206768)
		(width 0.0889)
		(layer "In2.Cu")
		(net "M_C_CPU0_SA_CB<6>")
	)
	(arc
		(start 326.127364 -248.239534)
		(mid 326.144618 -248.224385)
		(end 326.163686 -248.211594)
		(width 0.0889)
		(layer "In2.Cu")
		(net "M_C_CPU0_SA_CB<6>")
	)
	(arc
		(start 333.118206 -248.211594)
		(mid 333.401162 -248.287771)
		(end 333.684118 -248.211594)
		(width 0.0889)
		(layer "In2.Cu")
		(net "M_C_CPU0_SA_CB<6>")
	)
	(arc
		(start 327.114916 -248.204736)
		(mid 327.297171 -248.161083)
		(end 327.477628 -248.211594)
		(width 0.0889)
		(layer "In2.Cu")
		(net "M_C_CPU0_SA_CB<6>")
	)
	(arc
		(start 326.543416 -248.21515)
		(mid 326.823805 -248.287819)
		(end 327.103232 -248.211594)
		(width 0.0889)
		(layer "In2.Cu")
		(net "M_C_CPU0_SA_CB<6>")
	)
	(arc
		(start 341.578184 -248.211594)
		(mid 341.825897 -248.286814)
		(end 342.081104 -248.243344)
		(width 0.0889)
		(layer "In2.Cu")
		(net "M_C_CPU0_SA_CB<6>")
	)
	(arc
		(start 333.6925 -248.206768)
		(mid 333.876008 -248.161274)
		(end 334.05826 -248.211594)
		(width 0.0889)
		(layer "In2.Cu")
		(net "M_C_CPU0_SA_CB<6>")
	)
	(arc
		(start 338.384134 -248.211594)
		(mid 338.571078 -248.161339)
		(end 338.758022 -248.211594)
		(width 0.0889)
		(layer "In2.Cu")
		(net "M_C_CPU0_SA_CB<6>")
	)
	(arc
		(start 332.752446 -248.206768)
		(mid 332.935954 -248.161274)
		(end 333.118206 -248.211594)
		(width 0.0889)
		(layer "In2.Cu")
		(net "M_C_CPU0_SA_CB<6>")
	)
	(arc
		(start 338.758022 -248.211594)
		(mid 339.040978 -248.287771)
		(end 339.323934 -248.211594)
		(width 0.0889)
		(layer "In2.Cu")
		(net "M_C_CPU0_SA_CB<6>")
	)
	(arc
		(start 341.212424 -248.206768)
		(mid 341.395932 -248.161274)
		(end 341.578184 -248.211594)
		(width 0.0889)
		(layer "In2.Cu")
		(net "M_C_CPU0_SA_CB<6>")
	)
	(arc
		(start 336.504026 -248.211594)
		(mid 336.686277 -248.161244)
		(end 336.869786 -248.206768)
		(width 0.0889)
		(layer "In2.Cu")
		(net "M_C_CPU0_SA_CB<6>")
	)
	(arc
		(start 328.992484 -248.206768)
		(mid 329.175992 -248.161274)
		(end 329.358244 -248.211594)
		(width 0.0889)
		(layer "In2.Cu")
		(net "M_C_CPU0_SA_CB<6>")
	)
	(arc
		(start 328.41819 -248.211594)
		(mid 328.701146 -248.287771)
		(end 328.984102 -248.211594)
		(width 0.0889)
		(layer "In2.Cu")
		(net "M_C_CPU0_SA_CB<6>")
	)
	(arc
		(start 335.563972 -248.211594)
		(mid 335.746223 -248.161244)
		(end 335.929732 -248.206768)
		(width 0.0889)
		(layer "In2.Cu")
		(net "M_C_CPU0_SA_CB<6>")
	)
	(arc
		(start 337.818222 -248.211594)
		(mid 338.101178 -248.287771)
		(end 338.384134 -248.211594)
		(width 0.0889)
		(layer "In2.Cu")
		(net "M_C_CPU0_SA_CB<6>")
	)
	(arc
		(start 339.323934 -248.211594)
		(mid 339.506185 -248.161244)
		(end 339.689694 -248.206768)
		(width 0.0889)
		(layer "In2.Cu")
		(net "M_C_CPU0_SA_CB<6>")
	)
	(arc
		(start 339.698076 -248.211594)
		(mid 339.981032 -248.287771)
		(end 340.263988 -248.211594)
		(width 0.0889)
		(layer "In2.Cu")
		(net "M_C_CPU0_SA_CB<6>")
	)
	(arc
		(start 340.263988 -248.211594)
		(mid 340.446239 -248.161244)
		(end 340.629748 -248.206768)
		(width 0.0889)
		(layer "In2.Cu")
		(net "M_C_CPU0_SA_CB<6>")
	)
	(arc
		(start 327.477628 -248.211594)
		(mid 327.752334 -248.287958)
		(end 328.029316 -248.22023)
		(width 0.0889)
		(layer "In2.Cu")
		(net "M_C_CPU0_SA_CB<6>")
	)
	(arc
		(start 325.592694 -248.72061)
		(mid 325.64217 -248.710769)
		(end 325.684134 -248.682764)
		(width 0.0889)
		(layer "In2.Cu")
		(net "M_C_CPU0_SA_CB<6>")
	)
	(arc
		(start 336.878168 -248.211594)
		(mid 337.161124 -248.287771)
		(end 337.44408 -248.211594)
		(width 0.0889)
		(layer "In2.Cu")
		(net "M_C_CPU0_SA_CB<6>")
	)
	(segment
		(start 343.737946 -248.800112)
		(end 343.271094 -248.534174)
		(width 0.10668)
		(layer "F.Cu")
		(net "M_C_CPU0_SA_CB<5>")
	)
	(segment
		(start 332.752446 -248.86158)
		(end 332.744064 -248.856754)
		(width 0.0889)
		(layer "In2.Cu")
		(net "M_C_CPU0_SA_CB<5>")
	)
	(segment
		(start 313.126374 -247.346216)
		(end 312.964322 -247.184164)
		(width 0.14478)
		(layer "In2.Cu")
		(net "M_C_CPU0_SA_CB<5>")
	)
	(segment
		(start 296.196512 -242.81003)
		(end 295.074086 -242.81003)
		(width 0.14478)
		(layer "In2.Cu")
		(net "M_C_CPU0_SA_CB<5>")
	)
	(segment
		(start 302.759618 -242.646962)
		(end 302.759618 -242.581938)
		(width 0.14478)
		(layer "In2.Cu")
		(net "M_C_CPU0_SA_CB<5>")
	)
	(segment
		(start 304.10785 -242.41633)
		(end 303.944782 -242.579398)
		(width 0.14478)
		(layer "In2.Cu")
		(net "M_C_CPU0_SA_CB<5>")
	)
	(segment
		(start 324.378574 -249.02287)
		(end 324.221094 -249.18035)
		(width 0.0889)
		(layer "In2.Cu")
		(net "M_C_CPU0_SA_CB<5>")
	)
	(segment
		(start 309.803038 -244.167152)
		(end 308.445916 -242.81003)
		(width 0.14478)
		(layer "In2.Cu")
		(net "M_C_CPU0_SA_CB<5>")
	)
	(segment
		(start 339.698076 -248.856754)
		(end 339.689694 -248.86158)
		(width 0.0889)
		(layer "In2.Cu")
		(net "M_C_CPU0_SA_CB<5>")
	)
	(segment
		(start 304.501296 -242.646962)
		(end 304.501296 -242.579398)
		(width 0.14478)
		(layer "In2.Cu")
		(net "M_C_CPU0_SA_CB<5>")
	)
	(segment
		(start 312.75655 -248.17197)
		(end 312.75655 -247.943878)
		(width 0.14478)
		(layer "In2.Cu")
		(net "M_C_CPU0_SA_CB<5>")
	)
	(segment
		(start 302.759618 -242.581938)
		(end 302.59655 -242.41887)
		(width 0.14478)
		(layer "In2.Cu")
		(net "M_C_CPU0_SA_CB<5>")
	)
	(segment
		(start 299.275754 -241.733578)
		(end 299.112686 -241.57051)
		(width 0.14478)
		(layer "In2.Cu")
		(net "M_C_CPU0_SA_CB<5>")
	)
	(segment
		(start 296.753026 -242.43157)
		(end 296.522648 -242.43157)
		(width 0.14478)
		(layer "In2.Cu")
		(net "M_C_CPU0_SA_CB<5>")
	)
	(segment
		(start 336.878168 -248.856754)
		(end 336.869786 -248.86158)
		(width 0.0889)
		(layer "In2.Cu")
		(net "M_C_CPU0_SA_CB<5>")
	)
	(segment
		(start 295.074086 -242.81003)
		(end 294.911018 -242.646962)
		(width 0.14478)
		(layer "In2.Cu")
		(net "M_C_CPU0_SA_CB<5>")
	)
	(segment
		(start 296.916094 -242.646962)
		(end 296.916094 -242.594638)
		(width 0.14478)
		(layer "In2.Cu")
		(net "M_C_CPU0_SA_CB<5>")
	)
	(segment
		(start 299.438822 -241.960146)
		(end 299.275754 -241.797078)
		(width 0.14478)
		(layer "In2.Cu")
		(net "M_C_CPU0_SA_CB<5>")
	)
	(segment
		(start 297.367452 -242.81003)
		(end 297.079162 -242.81003)
		(width 0.14478)
		(layer "In2.Cu")
		(net "M_C_CPU0_SA_CB<5>")
	)
	(segment
		(start 342.152478 -248.86158)
		(end 342.144096 -248.856754)
		(width 0.0889)
		(layer "In2.Cu")
		(net "M_C_CPU0_SA_CB<5>")
	)
	(segment
		(start 332.178152 -248.856754)
		(end 332.16977 -248.86158)
		(width 0.0889)
		(layer "In2.Cu")
		(net "M_C_CPU0_SA_CB<5>")
	)
	(segment
		(start 306.203604 -242.81003)
		(end 306.04206 -242.648486)
		(width 0.14478)
		(layer "In2.Cu")
		(net "M_C_CPU0_SA_CB<5>")
	)
	(segment
		(start 300.365668 -241.57813)
		(end 300.2026 -241.741198)
		(width 0.14478)
		(layer "In2.Cu")
		(net "M_C_CPU0_SA_CB<5>")
	)
	(segment
		(start 324.221094 -249.18035)
		(end 323.870574 -249.18035)
		(width 0.0889)
		(layer "In2.Cu")
		(net "M_C_CPU0_SA_CB<5>")
	)
	(segment
		(start 302.040036 -242.81003)
		(end 301.892716 -242.81003)
		(width 0.14478)
		(layer "In2.Cu")
		(net "M_C_CPU0_SA_CB<5>")
	)
	(segment
		(start 294.911018 -242.587018)
		(end 294.74795 -242.42395)
		(width 0.14478)
		(layer "In2.Cu")
		(net "M_C_CPU0_SA_CB<5>")
	)
	(segment
		(start 300.596046 -241.57813)
		(end 300.365668 -241.57813)
		(width 0.14478)
		(layer "In2.Cu")
		(net "M_C_CPU0_SA_CB<5>")
	)
	(segment
		(start 293.64813 -242.81003)
		(end 292.705028 -242.81003)
		(width 0.14478)
		(layer "In2.Cu")
		(net "M_C_CPU0_SA_CB<5>")
	)
	(segment
		(start 294.354504 -243.030502)
		(end 294.191436 -243.19357)
		(width 0.14478)
		(layer "In2.Cu")
		(net "M_C_CPU0_SA_CB<5>")
	)
	(segment
		(start 305.490626 -242.648486)
		(end 305.329082 -242.81003)
		(width 0.14478)
		(layer "In2.Cu")
		(net "M_C_CPU0_SA_CB<5>")
	)
	(segment
		(start 293.961058 -243.19357)
		(end 293.79799 -243.030502)
		(width 0.14478)
		(layer "In2.Cu")
		(net "M_C_CPU0_SA_CB<5>")
	)
	(segment
		(start 302.59655 -242.41887)
		(end 302.366172 -242.41887)
		(width 0.14478)
		(layer "In2.Cu")
		(net "M_C_CPU0_SA_CB<5>")
	)
	(segment
		(start 302.203104 -242.646962)
		(end 302.040036 -242.81003)
		(width 0.14478)
		(layer "In2.Cu")
		(net "M_C_CPU0_SA_CB<5>")
	)
	(segment
		(start 333.6925 -248.86158)
		(end 333.684118 -248.856754)
		(width 0.0889)
		(layer "In2.Cu")
		(net "M_C_CPU0_SA_CB<5>")
	)
	(segment
		(start 302.366172 -242.41887)
		(end 302.203104 -242.581938)
		(width 0.14478)
		(layer "In2.Cu")
		(net "M_C_CPU0_SA_CB<5>")
	)
	(segment
		(start 312.73623 -247.184164)
		(end 312.366406 -247.553734)
		(width 0.14478)
		(layer "In2.Cu")
		(net "M_C_CPU0_SA_CB<5>")
	)
	(segment
		(start 327.480168 -248.8565)
		(end 327.458324 -248.868946)
		(width 0.0889)
		(layer "In2.Cu")
		(net "M_C_CPU0_SA_CB<5>")
	)
	(segment
		(start 328.41819 -248.856754)
		(end 328.409808 -248.86158)
		(width 0.0889)
		(layer "In2.Cu")
		(net "M_C_CPU0_SA_CB<5>")
	)
	(segment
		(start 304.501296 -242.579398)
		(end 304.338228 -242.41633)
		(width 0.14478)
		(layer "In2.Cu")
		(net "M_C_CPU0_SA_CB<5>")
	)
	(segment
		(start 309.803038 -245.218458)
		(end 309.803038 -244.167152)
		(width 0.14478)
		(layer "In2.Cu")
		(net "M_C_CPU0_SA_CB<5>")
	)
	(segment
		(start 294.191436 -243.19357)
		(end 293.961058 -243.19357)
		(width 0.14478)
		(layer "In2.Cu")
		(net "M_C_CPU0_SA_CB<5>")
	)
	(segment
		(start 300.759114 -241.797078)
		(end 300.759114 -241.741198)
		(width 0.14478)
		(layer "In2.Cu")
		(net "M_C_CPU0_SA_CB<5>")
	)
	(segment
		(start 301.892716 -242.81003)
		(end 301.042832 -241.960146)
		(width 0.14478)
		(layer "In2.Cu")
		(net "M_C_CPU0_SA_CB<5>")
	)
	(segment
		(start 312.366406 -247.553734)
		(end 312.138314 -247.553734)
		(width 0.14478)
		(layer "In2.Cu")
		(net "M_C_CPU0_SA_CB<5>")
	)
	(segment
		(start 300.759114 -241.741198)
		(end 300.596046 -241.57813)
		(width 0.14478)
		(layer "In2.Cu")
		(net "M_C_CPU0_SA_CB<5>")
	)
	(segment
		(start 327.50633 -248.841514)
		(end 327.480168 -248.8565)
		(width 0.0889)
		(layer "In2.Cu")
		(net "M_C_CPU0_SA_CB<5>")
	)
	(segment
		(start 335.938114 -248.856754)
		(end 335.929732 -248.86158)
		(width 0.0889)
		(layer "In2.Cu")
		(net "M_C_CPU0_SA_CB<5>")
	)
	(segment
		(start 343.425018 -248.799604)
		(end 343.402666 -248.882916)
		(width 0.0889)
		(layer "In2.Cu")
		(net "M_C_CPU0_SA_CB<5>")
	)
	(segment
		(start 299.275754 -241.797078)
		(end 299.275754 -241.733578)
		(width 0.14478)
		(layer "In2.Cu")
		(net "M_C_CPU0_SA_CB<5>")
	)
	(segment
		(start 298.217336 -241.960146)
		(end 297.367452 -242.81003)
		(width 0.14478)
		(layer "In2.Cu")
		(net "M_C_CPU0_SA_CB<5>")
	)
	(segment
		(start 302.922686 -242.81003)
		(end 302.759618 -242.646962)
		(width 0.14478)
		(layer "In2.Cu")
		(net "M_C_CPU0_SA_CB<5>")
	)
	(segment
		(start 305.490626 -242.573556)
		(end 305.490626 -242.648486)
		(width 0.14478)
		(layer "In2.Cu")
		(net "M_C_CPU0_SA_CB<5>")
	)
	(segment
		(start 294.354504 -242.587018)
		(end 294.354504 -243.030502)
		(width 0.14478)
		(layer "In2.Cu")
		(net "M_C_CPU0_SA_CB<5>")
	)
	(segment
		(start 292.705028 -242.81003)
		(end 292.280086 -242.385088)
		(width 0.14478)
		(layer "In2.Cu")
		(net "M_C_CPU0_SA_CB<5>")
	)
	(segment
		(start 305.880516 -242.412012)
		(end 305.65217 -242.412012)
		(width 0.14478)
		(layer "In2.Cu")
		(net "M_C_CPU0_SA_CB<5>")
	)
	(segment
		(start 296.916094 -242.594638)
		(end 296.753026 -242.43157)
		(width 0.14478)
		(layer "In2.Cu")
		(net "M_C_CPU0_SA_CB<5>")
	)
	(segment
		(start 298.71924 -241.797078)
		(end 298.556172 -241.960146)
		(width 0.14478)
		(layer "In2.Cu")
		(net "M_C_CPU0_SA_CB<5>")
	)
	(segment
		(start 327.10755 -248.856754)
		(end 327.078086 -248.839482)
		(width 0.0889)
		(layer "In2.Cu")
		(net "M_C_CPU0_SA_CB<5>")
	)
	(segment
		(start 312.75655 -247.943878)
		(end 313.126374 -247.574308)
		(width 0.14478)
		(layer "In2.Cu")
		(net "M_C_CPU0_SA_CB<5>")
	)
	(segment
		(start 296.522648 -242.43157)
		(end 296.35958 -242.594638)
		(width 0.14478)
		(layer "In2.Cu")
		(net "M_C_CPU0_SA_CB<5>")
	)
	(segment
		(start 340.63813 -248.856754)
		(end 340.629748 -248.86158)
		(width 0.0889)
		(layer "In2.Cu")
		(net "M_C_CPU0_SA_CB<5>")
	)
	(segment
		(start 306.04206 -242.573556)
		(end 305.880516 -242.412012)
		(width 0.14478)
		(layer "In2.Cu")
		(net "M_C_CPU0_SA_CB<5>")
	)
	(segment
		(start 301.042832 -241.960146)
		(end 300.922182 -241.960146)
		(width 0.14478)
		(layer "In2.Cu")
		(net "M_C_CPU0_SA_CB<5>")
	)
	(segment
		(start 294.517572 -242.42395)
		(end 294.354504 -242.587018)
		(width 0.14478)
		(layer "In2.Cu")
		(net "M_C_CPU0_SA_CB<5>")
	)
	(segment
		(start 304.664364 -242.81003)
		(end 304.501296 -242.646962)
		(width 0.14478)
		(layer "In2.Cu")
		(net "M_C_CPU0_SA_CB<5>")
	)
	(segment
		(start 321.970654 -248.46915)
		(end 313.05373 -248.46915)
		(width 0.14478)
		(layer "In2.Cu")
		(net "M_C_CPU0_SA_CB<5>")
	)
	(segment
		(start 296.35958 -242.594638)
		(end 296.35958 -242.646962)
		(width 0.14478)
		(layer "In2.Cu")
		(net "M_C_CPU0_SA_CB<5>")
	)
	(segment
		(start 294.911018 -242.646962)
		(end 294.911018 -242.587018)
		(width 0.14478)
		(layer "In2.Cu")
		(net "M_C_CPU0_SA_CB<5>")
	)
	(segment
		(start 331.238098 -248.856754)
		(end 331.229716 -248.86158)
		(width 0.0889)
		(layer "In2.Cu")
		(net "M_C_CPU0_SA_CB<5>")
	)
	(segment
		(start 300.039532 -241.960146)
		(end 299.438822 -241.960146)
		(width 0.14478)
		(layer "In2.Cu")
		(net "M_C_CPU0_SA_CB<5>")
	)
	(segment
		(start 293.79799 -242.95989)
		(end 293.64813 -242.81003)
		(width 0.14478)
		(layer "In2.Cu")
		(net "M_C_CPU0_SA_CB<5>")
	)
	(segment
		(start 313.126374 -247.574308)
		(end 313.126374 -247.346216)
		(width 0.14478)
		(layer "In2.Cu")
		(net "M_C_CPU0_SA_CB<5>")
	)
	(segment
		(start 305.329082 -242.81003)
		(end 304.664364 -242.81003)
		(width 0.14478)
		(layer "In2.Cu")
		(net "M_C_CPU0_SA_CB<5>")
	)
	(segment
		(start 343.271094 -248.534174)
		(end 343.425018 -248.799604)
		(width 0.0889)
		(layer "In2.Cu")
		(net "M_C_CPU0_SA_CB<5>")
	)
	(segment
		(start 323.870574 -249.18035)
		(end 322.681854 -249.18035)
		(width 0.14478)
		(layer "In2.Cu")
		(net "M_C_CPU0_SA_CB<5>")
	)
	(segment
		(start 297.079162 -242.81003)
		(end 296.916094 -242.646962)
		(width 0.14478)
		(layer "In2.Cu")
		(net "M_C_CPU0_SA_CB<5>")
	)
	(segment
		(start 328.992484 -248.86158)
		(end 328.984102 -248.856754)
		(width 0.0889)
		(layer "In2.Cu")
		(net "M_C_CPU0_SA_CB<5>")
	)
	(segment
		(start 312.138314 -247.553734)
		(end 309.803038 -245.218458)
		(width 0.14478)
		(layer "In2.Cu")
		(net "M_C_CPU0_SA_CB<5>")
	)
	(segment
		(start 294.74795 -242.42395)
		(end 294.517572 -242.42395)
		(width 0.14478)
		(layer "In2.Cu")
		(net "M_C_CPU0_SA_CB<5>")
	)
	(segment
		(start 326.539606 -248.856754)
		(end 326.527668 -248.863612)
		(width 0.0889)
		(layer "In2.Cu")
		(net "M_C_CPU0_SA_CB<5>")
	)
	(segment
		(start 303.944782 -242.579398)
		(end 303.944782 -242.646962)
		(width 0.14478)
		(layer "In2.Cu")
		(net "M_C_CPU0_SA_CB<5>")
	)
	(segment
		(start 298.556172 -241.960146)
		(end 298.217336 -241.960146)
		(width 0.14478)
		(layer "In2.Cu")
		(net "M_C_CPU0_SA_CB<5>")
	)
	(segment
		(start 322.681854 -249.18035)
		(end 321.970654 -248.46915)
		(width 0.14478)
		(layer "In2.Cu")
		(net "M_C_CPU0_SA_CB<5>")
	)
	(segment
		(start 298.882308 -241.57051)
		(end 298.71924 -241.733578)
		(width 0.14478)
		(layer "In2.Cu")
		(net "M_C_CPU0_SA_CB<5>")
	)
	(segment
		(start 298.71924 -241.733578)
		(end 298.71924 -241.797078)
		(width 0.14478)
		(layer "In2.Cu")
		(net "M_C_CPU0_SA_CB<5>")
	)
	(segment
		(start 306.04206 -242.648486)
		(end 306.04206 -242.573556)
		(width 0.14478)
		(layer "In2.Cu")
		(net "M_C_CPU0_SA_CB<5>")
	)
	(segment
		(start 303.944782 -242.646962)
		(end 303.781714 -242.81003)
		(width 0.14478)
		(layer "In2.Cu")
		(net "M_C_CPU0_SA_CB<5>")
	)
	(segment
		(start 341.212424 -248.86158)
		(end 341.204042 -248.856754)
		(width 0.0889)
		(layer "In2.Cu")
		(net "M_C_CPU0_SA_CB<5>")
	)
	(segment
		(start 299.112686 -241.57051)
		(end 298.882308 -241.57051)
		(width 0.14478)
		(layer "In2.Cu")
		(net "M_C_CPU0_SA_CB<5>")
	)
	(segment
		(start 305.65217 -242.412012)
		(end 305.490626 -242.573556)
		(width 0.14478)
		(layer "In2.Cu")
		(net "M_C_CPU0_SA_CB<5>")
	)
	(segment
		(start 300.2026 -241.797078)
		(end 300.039532 -241.960146)
		(width 0.14478)
		(layer "In2.Cu")
		(net "M_C_CPU0_SA_CB<5>")
	)
	(segment
		(start 312.964322 -247.184164)
		(end 312.73623 -247.184164)
		(width 0.14478)
		(layer "In2.Cu")
		(net "M_C_CPU0_SA_CB<5>")
	)
	(segment
		(start 303.781714 -242.81003)
		(end 302.922686 -242.81003)
		(width 0.14478)
		(layer "In2.Cu")
		(net "M_C_CPU0_SA_CB<5>")
	)
	(segment
		(start 296.35958 -242.646962)
		(end 296.196512 -242.81003)
		(width 0.14478)
		(layer "In2.Cu")
		(net "M_C_CPU0_SA_CB<5>")
	)
	(segment
		(start 300.922182 -241.960146)
		(end 300.759114 -241.797078)
		(width 0.14478)
		(layer "In2.Cu")
		(net "M_C_CPU0_SA_CB<5>")
	)
	(segment
		(start 308.445916 -242.81003)
		(end 306.203604 -242.81003)
		(width 0.14478)
		(layer "In2.Cu")
		(net "M_C_CPU0_SA_CB<5>")
	)
	(segment
		(start 304.338228 -242.41633)
		(end 304.10785 -242.41633)
		(width 0.14478)
		(layer "In2.Cu")
		(net "M_C_CPU0_SA_CB<5>")
	)
	(segment
		(start 300.2026 -241.741198)
		(end 300.2026 -241.797078)
		(width 0.14478)
		(layer "In2.Cu")
		(net "M_C_CPU0_SA_CB<5>")
	)
	(segment
		(start 302.203104 -242.581938)
		(end 302.203104 -242.646962)
		(width 0.14478)
		(layer "In2.Cu")
		(net "M_C_CPU0_SA_CB<5>")
	)
	(segment
		(start 337.452462 -248.86158)
		(end 337.44408 -248.856754)
		(width 0.0889)
		(layer "In2.Cu")
		(net "M_C_CPU0_SA_CB<5>")
	)
	(segment
		(start 325.940674 -249.02287)
		(end 324.378574 -249.02287)
		(width 0.0889)
		(layer "In2.Cu")
		(net "M_C_CPU0_SA_CB<5>")
	)
	(segment
		(start 313.05373 -248.46915)
		(end 312.75655 -248.17197)
		(width 0.14478)
		(layer "In2.Cu")
		(net "M_C_CPU0_SA_CB<5>")
	)
	(segment
		(start 293.79799 -243.030502)
		(end 293.79799 -242.95989)
		(width 0.14478)
		(layer "In2.Cu")
		(net "M_C_CPU0_SA_CB<5>")
	)
	(arc
		(start 329.358244 -248.856754)
		(mid 329.175993 -248.907104)
		(end 328.992484 -248.86158)
		(width 0.0889)
		(layer "In2.Cu")
		(net "M_C_CPU0_SA_CB<5>")
	)
	(arc
		(start 338.384134 -248.856754)
		(mid 338.101178 -248.780577)
		(end 337.818222 -248.856754)
		(width 0.0889)
		(layer "In2.Cu")
		(net "M_C_CPU0_SA_CB<5>")
	)
	(arc
		(start 340.629748 -248.86158)
		(mid 340.44624 -248.907074)
		(end 340.263988 -248.856754)
		(width 0.0889)
		(layer "In2.Cu")
		(net "M_C_CPU0_SA_CB<5>")
	)
	(arc
		(start 328.044048 -248.856754)
		(mid 327.777118 -248.780805)
		(end 327.50633 -248.841514)
		(width 0.0889)
		(layer "In2.Cu")
		(net "M_C_CPU0_SA_CB<5>")
	)
	(arc
		(start 326.527668 -248.863612)
		(mid 326.244773 -248.982319)
		(end 325.940674 -249.02287)
		(width 0.0889)
		(layer "In2.Cu")
		(net "M_C_CPU0_SA_CB<5>")
	)
	(arc
		(start 327.078086 -248.839482)
		(mid 326.806666 -248.779805)
		(end 326.539606 -248.856754)
		(width 0.0889)
		(layer "In2.Cu")
		(net "M_C_CPU0_SA_CB<5>")
	)
	(arc
		(start 341.204042 -248.856754)
		(mid 340.921086 -248.780577)
		(end 340.63813 -248.856754)
		(width 0.0889)
		(layer "In2.Cu")
		(net "M_C_CPU0_SA_CB<5>")
	)
	(arc
		(start 332.744064 -248.856754)
		(mid 332.461108 -248.780577)
		(end 332.178152 -248.856754)
		(width 0.0889)
		(layer "In2.Cu")
		(net "M_C_CPU0_SA_CB<5>")
	)
	(arc
		(start 343.08415 -248.856754)
		(mid 342.801194 -248.780577)
		(end 342.518238 -248.856754)
		(width 0.0889)
		(layer "In2.Cu")
		(net "M_C_CPU0_SA_CB<5>")
	)
	(arc
		(start 342.144096 -248.856754)
		(mid 341.86114 -248.780577)
		(end 341.578184 -248.856754)
		(width 0.0889)
		(layer "In2.Cu")
		(net "M_C_CPU0_SA_CB<5>")
	)
	(arc
		(start 337.818222 -248.856754)
		(mid 337.635971 -248.907104)
		(end 337.452462 -248.86158)
		(width 0.0889)
		(layer "In2.Cu")
		(net "M_C_CPU0_SA_CB<5>")
	)
	(arc
		(start 334.99806 -248.856754)
		(mid 334.811116 -248.907009)
		(end 334.624172 -248.856754)
		(width 0.0889)
		(layer "In2.Cu")
		(net "M_C_CPU0_SA_CB<5>")
	)
	(arc
		(start 327.458324 -248.868946)
		(mid 327.281396 -248.906774)
		(end 327.10755 -248.856754)
		(width 0.0889)
		(layer "In2.Cu")
		(net "M_C_CPU0_SA_CB<5>")
	)
	(arc
		(start 342.518238 -248.856754)
		(mid 342.335987 -248.907104)
		(end 342.152478 -248.86158)
		(width 0.0889)
		(layer "In2.Cu")
		(net "M_C_CPU0_SA_CB<5>")
	)
	(arc
		(start 333.684118 -248.856754)
		(mid 333.401162 -248.780577)
		(end 333.118206 -248.856754)
		(width 0.0889)
		(layer "In2.Cu")
		(net "M_C_CPU0_SA_CB<5>")
	)
	(arc
		(start 332.16977 -248.86158)
		(mid 331.986262 -248.907074)
		(end 331.80401 -248.856754)
		(width 0.0889)
		(layer "In2.Cu")
		(net "M_C_CPU0_SA_CB<5>")
	)
	(arc
		(start 336.504026 -248.856754)
		(mid 336.22107 -248.780577)
		(end 335.938114 -248.856754)
		(width 0.0889)
		(layer "In2.Cu")
		(net "M_C_CPU0_SA_CB<5>")
	)
	(arc
		(start 334.624172 -248.856754)
		(mid 334.341216 -248.780577)
		(end 334.05826 -248.856754)
		(width 0.0889)
		(layer "In2.Cu")
		(net "M_C_CPU0_SA_CB<5>")
	)
	(arc
		(start 338.758022 -248.856754)
		(mid 338.571078 -248.907009)
		(end 338.384134 -248.856754)
		(width 0.0889)
		(layer "In2.Cu")
		(net "M_C_CPU0_SA_CB<5>")
	)
	(arc
		(start 343.402666 -248.882916)
		(mid 343.240477 -248.905651)
		(end 343.08415 -248.856754)
		(width 0.0889)
		(layer "In2.Cu")
		(net "M_C_CPU0_SA_CB<5>")
	)
	(arc
		(start 339.323934 -248.856754)
		(mid 339.040978 -248.780577)
		(end 338.758022 -248.856754)
		(width 0.0889)
		(layer "In2.Cu")
		(net "M_C_CPU0_SA_CB<5>")
	)
	(arc
		(start 341.578184 -248.856754)
		(mid 341.395933 -248.907104)
		(end 341.212424 -248.86158)
		(width 0.0889)
		(layer "In2.Cu")
		(net "M_C_CPU0_SA_CB<5>")
	)
	(arc
		(start 334.05826 -248.856754)
		(mid 333.876009 -248.907104)
		(end 333.6925 -248.86158)
		(width 0.0889)
		(layer "In2.Cu")
		(net "M_C_CPU0_SA_CB<5>")
	)
	(arc
		(start 335.929732 -248.86158)
		(mid 335.746224 -248.907074)
		(end 335.563972 -248.856754)
		(width 0.0889)
		(layer "In2.Cu")
		(net "M_C_CPU0_SA_CB<5>")
	)
	(arc
		(start 337.44408 -248.856754)
		(mid 337.161124 -248.780577)
		(end 336.878168 -248.856754)
		(width 0.0889)
		(layer "In2.Cu")
		(net "M_C_CPU0_SA_CB<5>")
	)
	(arc
		(start 333.118206 -248.856754)
		(mid 332.935955 -248.907104)
		(end 332.752446 -248.86158)
		(width 0.0889)
		(layer "In2.Cu")
		(net "M_C_CPU0_SA_CB<5>")
	)
	(arc
		(start 329.924156 -248.856754)
		(mid 329.6412 -248.780577)
		(end 329.358244 -248.856754)
		(width 0.0889)
		(layer "In2.Cu")
		(net "M_C_CPU0_SA_CB<5>")
	)
	(arc
		(start 336.869786 -248.86158)
		(mid 336.686278 -248.907074)
		(end 336.504026 -248.856754)
		(width 0.0889)
		(layer "In2.Cu")
		(net "M_C_CPU0_SA_CB<5>")
	)
	(arc
		(start 328.984102 -248.856754)
		(mid 328.701146 -248.780577)
		(end 328.41819 -248.856754)
		(width 0.0889)
		(layer "In2.Cu")
		(net "M_C_CPU0_SA_CB<5>")
	)
	(arc
		(start 335.563972 -248.856754)
		(mid 335.281016 -248.780577)
		(end 334.99806 -248.856754)
		(width 0.0889)
		(layer "In2.Cu")
		(net "M_C_CPU0_SA_CB<5>")
	)
	(arc
		(start 331.229716 -248.86158)
		(mid 331.046208 -248.907074)
		(end 330.863956 -248.856754)
		(width 0.0889)
		(layer "In2.Cu")
		(net "M_C_CPU0_SA_CB<5>")
	)
	(arc
		(start 331.80401 -248.856754)
		(mid 331.521054 -248.780577)
		(end 331.238098 -248.856754)
		(width 0.0889)
		(layer "In2.Cu")
		(net "M_C_CPU0_SA_CB<5>")
	)
	(arc
		(start 339.689694 -248.86158)
		(mid 339.506186 -248.907074)
		(end 339.323934 -248.856754)
		(width 0.0889)
		(layer "In2.Cu")
		(net "M_C_CPU0_SA_CB<5>")
	)
	(arc
		(start 328.409808 -248.86158)
		(mid 328.2263 -248.907074)
		(end 328.044048 -248.856754)
		(width 0.0889)
		(layer "In2.Cu")
		(net "M_C_CPU0_SA_CB<5>")
	)
	(arc
		(start 330.863956 -248.856754)
		(mid 330.581 -248.780577)
		(end 330.298044 -248.856754)
		(width 0.0889)
		(layer "In2.Cu")
		(net "M_C_CPU0_SA_CB<5>")
	)
	(arc
		(start 340.263988 -248.856754)
		(mid 339.981032 -248.780577)
		(end 339.698076 -248.856754)
		(width 0.0889)
		(layer "In2.Cu")
		(net "M_C_CPU0_SA_CB<5>")
	)
	(arc
		(start 330.298044 -248.856754)
		(mid 330.1111 -248.907009)
		(end 329.924156 -248.856754)
		(width 0.0889)
		(layer "In2.Cu")
		(net "M_C_CPU0_SA_CB<5>")
	)
	(segment
		(start 342.327992 -247.990106)
		(end 341.86114 -247.724168)
		(width 0.10668)
		(layer "F.Cu")
		(net "M_C_CPU0_SA_CB<4>")
	)
	(segment
		(start 296.905426 -241.328702)
		(end 296.905426 -241.273076)
		(width 0.14478)
		(layer "In2.Cu")
		(net "M_C_CPU0_SA_CB<4>")
	)
	(segment
		(start 306.161186 -240.948464)
		(end 306.161186 -240.599976)
		(width 0.14478)
		(layer "In2.Cu")
		(net "M_C_CPU0_SA_CB<4>")
	)
	(segment
		(start 312.440828 -245.952772)
		(end 312.210196 -245.952772)
		(width 0.14478)
		(layer "In2.Cu")
		(net "M_C_CPU0_SA_CB<4>")
	)
	(segment
		(start 324.259194 -248.36501)
		(end 324.155054 -248.26087)
		(width 0.0889)
		(layer "In2.Cu")
		(net "M_C_CPU0_SA_CB<4>")
	)
	(segment
		(start 312.415174 -245.191026)
		(end 312.415174 -244.960394)
		(width 0.14478)
		(layer "In2.Cu")
		(net "M_C_CPU0_SA_CB<4>")
	)
	(segment
		(start 310.769508 -243.709444)
		(end 310.573166 -243.513102)
		(width 0.14478)
		(layer "In2.Cu")
		(net "M_C_CPU0_SA_CB<4>")
	)
	(segment
		(start 312.415174 -244.960394)
		(end 312.252106 -244.797326)
		(width 0.14478)
		(layer "In2.Cu")
		(net "M_C_CPU0_SA_CB<4>")
	)
	(segment
		(start 338.862416 -248.051574)
		(end 338.854034 -248.046748)
		(width 0.0889)
		(layer "In2.Cu")
		(net "M_C_CPU0_SA_CB<4>")
	)
	(segment
		(start 305.609752 -240.599976)
		(end 305.609752 -240.948464)
		(width 0.14478)
		(layer "In2.Cu")
		(net "M_C_CPU0_SA_CB<4>")
	)
	(segment
		(start 310.376824 -242.922044)
		(end 309.982108 -242.922044)
		(width 0.14478)
		(layer "In2.Cu")
		(net "M_C_CPU0_SA_CB<4>")
	)
	(segment
		(start 297.068494 -241.49177)
		(end 296.905426 -241.328702)
		(width 0.14478)
		(layer "In2.Cu")
		(net "M_C_CPU0_SA_CB<4>")
	)
	(segment
		(start 304.93589 -241.273076)
		(end 304.93589 -241.338862)
		(width 0.14478)
		(layer "In2.Cu")
		(net "M_C_CPU0_SA_CB<4>")
	)
	(segment
		(start 338.288122 -248.046748)
		(end 338.27974 -248.051574)
		(width 0.0889)
		(layer "In2.Cu")
		(net "M_C_CPU0_SA_CB<4>")
	)
	(segment
		(start 322.328794 -247.52427)
		(end 314.97905 -247.52427)
		(width 0.14478)
		(layer "In2.Cu")
		(net "M_C_CPU0_SA_CB<4>")
	)
	(segment
		(start 310.573166 -243.118386)
		(end 310.376824 -242.922044)
		(width 0.14478)
		(layer "In2.Cu")
		(net "M_C_CPU0_SA_CB<4>")
	)
	(segment
		(start 297.625008 -241.110008)
		(end 297.46194 -241.273076)
		(width 0.14478)
		(layer "In2.Cu")
		(net "M_C_CPU0_SA_CB<4>")
	)
	(segment
		(start 327.94829 -248.046748)
		(end 327.939908 -248.051574)
		(width 0.0889)
		(layer "In2.Cu")
		(net "M_C_CPU0_SA_CB<4>")
	)
	(segment
		(start 330.402438 -248.051574)
		(end 330.394056 -248.046748)
		(width 0.0889)
		(layer "In2.Cu")
		(net "M_C_CPU0_SA_CB<4>")
	)
	(segment
		(start 294.622728 -241.267742)
		(end 294.622728 -241.321082)
		(width 0.14478)
		(layer "In2.Cu")
		(net "M_C_CPU0_SA_CB<4>")
	)
	(segment
		(start 305.771296 -240.438432)
		(end 305.609752 -240.599976)
		(width 0.14478)
		(layer "In2.Cu")
		(net "M_C_CPU0_SA_CB<4>")
	)
	(segment
		(start 311.259728 -245.002304)
		(end 311.259728 -244.771672)
		(width 0.14478)
		(layer "In2.Cu")
		(net "M_C_CPU0_SA_CB<4>")
	)
	(segment
		(start 336.042508 -248.051574)
		(end 336.034126 -248.046748)
		(width 0.0889)
		(layer "In2.Cu")
		(net "M_C_CPU0_SA_CB<4>")
	)
	(segment
		(start 297.298872 -241.49177)
		(end 297.068494 -241.49177)
		(width 0.14478)
		(layer "In2.Cu")
		(net "M_C_CPU0_SA_CB<4>")
	)
	(segment
		(start 301.779432 -241.110008)
		(end 300.9392 -240.269776)
		(width 0.14478)
		(layer "In2.Cu")
		(net "M_C_CPU0_SA_CB<4>")
	)
	(segment
		(start 297.46194 -241.328702)
		(end 297.298872 -241.49177)
		(width 0.14478)
		(layer "In2.Cu")
		(net "M_C_CPU0_SA_CB<4>")
	)
	(segment
		(start 326.647302 -248.054368)
		(end 326.633586 -248.046494)
		(width 0.0889)
		(layer "In2.Cu")
		(net "M_C_CPU0_SA_CB<4>")
	)
	(segment
		(start 306.161186 -240.599976)
		(end 305.999642 -240.438432)
		(width 0.14478)
		(layer "In2.Cu")
		(net "M_C_CPU0_SA_CB<4>")
	)
	(segment
		(start 311.627774 -244.403626)
		(end 311.627774 -244.172994)
		(width 0.14478)
		(layer "In2.Cu")
		(net "M_C_CPU0_SA_CB<4>")
	)
	(segment
		(start 334.52816 -248.046748)
		(end 334.519778 -248.051574)
		(width 0.0889)
		(layer "In2.Cu")
		(net "M_C_CPU0_SA_CB<4>")
	)
	(segment
		(start 329.828144 -248.046748)
		(end 329.819762 -248.051574)
		(width 0.0889)
		(layer "In2.Cu")
		(net "M_C_CPU0_SA_CB<4>")
	)
	(segment
		(start 300.9392 -240.269776)
		(end 298.597828 -240.269776)
		(width 0.14478)
		(layer "In2.Cu")
		(net "M_C_CPU0_SA_CB<4>")
	)
	(segment
		(start 342.015064 -247.989598)
		(end 341.992712 -248.07291)
		(width 0.0889)
		(layer "In2.Cu")
		(net "M_C_CPU0_SA_CB<4>")
	)
	(segment
		(start 305.999642 -240.438432)
		(end 305.771296 -240.438432)
		(width 0.14478)
		(layer "In2.Cu")
		(net "M_C_CPU0_SA_CB<4>")
	)
	(segment
		(start 324.155054 -248.26087)
		(end 323.901054 -248.26087)
		(width 0.0889)
		(layer "In2.Cu")
		(net "M_C_CPU0_SA_CB<4>")
	)
	(segment
		(start 294.229282 -241.48415)
		(end 294.066214 -241.321082)
		(width 0.14478)
		(layer "In2.Cu")
		(net "M_C_CPU0_SA_CB<4>")
	)
	(segment
		(start 304.216308 -241.110008)
		(end 301.779432 -241.110008)
		(width 0.14478)
		(layer "In2.Cu")
		(net "M_C_CPU0_SA_CB<4>")
	)
	(segment
		(start 313.039506 -245.584726)
		(end 312.808874 -245.584726)
		(width 0.14478)
		(layer "In2.Cu")
		(net "M_C_CPU0_SA_CB<4>")
	)
	(segment
		(start 311.653428 -245.165372)
		(end 311.422796 -245.165372)
		(width 0.14478)
		(layer "In2.Cu")
		(net "M_C_CPU0_SA_CB<4>")
	)
	(segment
		(start 314.97905 -247.52427)
		(end 313.039506 -245.584726)
		(width 0.14478)
		(layer "In2.Cu")
		(net "M_C_CPU0_SA_CB<4>")
	)
	(segment
		(start 305.448208 -241.110008)
		(end 305.098958 -241.110008)
		(width 0.14478)
		(layer "In2.Cu")
		(net "M_C_CPU0_SA_CB<4>")
	)
	(segment
		(start 312.808874 -245.584726)
		(end 312.440828 -245.952772)
		(width 0.14478)
		(layer "In2.Cu")
		(net "M_C_CPU0_SA_CB<4>")
	)
	(segment
		(start 293.545514 -240.560098)
		(end 293.382446 -240.723166)
		(width 0.14478)
		(layer "In2.Cu")
		(net "M_C_CPU0_SA_CB<4>")
	)
	(segment
		(start 293.382446 -241.231674)
		(end 293.232586 -241.381534)
		(width 0.14478)
		(layer "In2.Cu")
		(net "M_C_CPU0_SA_CB<4>")
	)
	(segment
		(start 294.066214 -241.321082)
		(end 294.066214 -241.087402)
		(width 0.14478)
		(layer "In2.Cu")
		(net "M_C_CPU0_SA_CB<4>")
	)
	(segment
		(start 294.066214 -241.087402)
		(end 293.93896 -240.960148)
		(width 0.14478)
		(layer "In2.Cu")
		(net "M_C_CPU0_SA_CB<4>")
	)
	(segment
		(start 296.905426 -241.273076)
		(end 296.75201 -241.11966)
		(width 0.14478)
		(layer "In2.Cu")
		(net "M_C_CPU0_SA_CB<4>")
	)
	(segment
		(start 311.259728 -244.771672)
		(end 311.627774 -244.403626)
		(width 0.14478)
		(layer "In2.Cu")
		(net "M_C_CPU0_SA_CB<4>")
	)
	(segment
		(start 309.785766 -242.330986)
		(end 308.564788 -241.110008)
		(width 0.14478)
		(layer "In2.Cu")
		(net "M_C_CPU0_SA_CB<4>")
	)
	(segment
		(start 294.77081 -241.11966)
		(end 294.622728 -241.267742)
		(width 0.14478)
		(layer "In2.Cu")
		(net "M_C_CPU0_SA_CB<4>")
	)
	(segment
		(start 311.627774 -244.172994)
		(end 311.164224 -243.709444)
		(width 0.14478)
		(layer "In2.Cu")
		(net "M_C_CPU0_SA_CB<4>")
	)
	(segment
		(start 341.86114 -247.724168)
		(end 342.015064 -247.989598)
		(width 0.0889)
		(layer "In2.Cu")
		(net "M_C_CPU0_SA_CB<4>")
	)
	(segment
		(start 323.065394 -248.26087)
		(end 322.328794 -247.52427)
		(width 0.14478)
		(layer "In2.Cu")
		(net "M_C_CPU0_SA_CB<4>")
	)
	(segment
		(start 296.75201 -241.11966)
		(end 294.77081 -241.11966)
		(width 0.14478)
		(layer "In2.Cu")
		(net "M_C_CPU0_SA_CB<4>")
	)
	(segment
		(start 335.102454 -248.051574)
		(end 335.094072 -248.046748)
		(width 0.0889)
		(layer "In2.Cu")
		(net "M_C_CPU0_SA_CB<4>")
	)
	(segment
		(start 312.047128 -245.789704)
		(end 312.047128 -245.559072)
		(width 0.14478)
		(layer "In2.Cu")
		(net "M_C_CPU0_SA_CB<4>")
	)
	(segment
		(start 293.232586 -241.381534)
		(end 292.976554 -241.381534)
		(width 0.14478)
		(layer "In2.Cu")
		(net "M_C_CPU0_SA_CB<4>")
	)
	(segment
		(start 306.32273 -241.110008)
		(end 306.161186 -240.948464)
		(width 0.14478)
		(layer "In2.Cu")
		(net "M_C_CPU0_SA_CB<4>")
	)
	(segment
		(start 293.382446 -240.723166)
		(end 293.382446 -241.231674)
		(width 0.14478)
		(layer "In2.Cu")
		(net "M_C_CPU0_SA_CB<4>")
	)
	(segment
		(start 311.164224 -243.709444)
		(end 310.769508 -243.709444)
		(width 0.14478)
		(layer "In2.Cu")
		(net "M_C_CPU0_SA_CB<4>")
	)
	(segment
		(start 294.45966 -241.48415)
		(end 294.229282 -241.48415)
		(width 0.14478)
		(layer "In2.Cu")
		(net "M_C_CPU0_SA_CB<4>")
	)
	(segment
		(start 309.982108 -242.922044)
		(end 309.785766 -242.725702)
		(width 0.14478)
		(layer "In2.Cu")
		(net "M_C_CPU0_SA_CB<4>")
	)
	(segment
		(start 339.80247 -248.051574)
		(end 339.794088 -248.046748)
		(width 0.0889)
		(layer "In2.Cu")
		(net "M_C_CPU0_SA_CB<4>")
	)
	(segment
		(start 326.633586 -248.046494)
		(end 326.617838 -248.03735)
		(width 0.0889)
		(layer "In2.Cu")
		(net "M_C_CPU0_SA_CB<4>")
	)
	(segment
		(start 298.597828 -240.269776)
		(end 297.757596 -241.110008)
		(width 0.14478)
		(layer "In2.Cu")
		(net "M_C_CPU0_SA_CB<4>")
	)
	(segment
		(start 304.379376 -241.273076)
		(end 304.216308 -241.110008)
		(width 0.14478)
		(layer "In2.Cu")
		(net "M_C_CPU0_SA_CB<4>")
	)
	(segment
		(start 297.46194 -241.273076)
		(end 297.46194 -241.328702)
		(width 0.14478)
		(layer "In2.Cu")
		(net "M_C_CPU0_SA_CB<4>")
	)
	(segment
		(start 293.775892 -240.560098)
		(end 293.545514 -240.560098)
		(width 0.14478)
		(layer "In2.Cu")
		(net "M_C_CPU0_SA_CB<4>")
	)
	(segment
		(start 309.785766 -242.725702)
		(end 309.785766 -242.330986)
		(width 0.14478)
		(layer "In2.Cu")
		(net "M_C_CPU0_SA_CB<4>")
	)
	(segment
		(start 327.021952 -248.038112)
		(end 327.00722 -248.046748)
		(width 0.0889)
		(layer "In2.Cu")
		(net "M_C_CPU0_SA_CB<4>")
	)
	(segment
		(start 297.757596 -241.110008)
		(end 297.625008 -241.110008)
		(width 0.14478)
		(layer "In2.Cu")
		(net "M_C_CPU0_SA_CB<4>")
	)
	(segment
		(start 311.422796 -245.165372)
		(end 311.259728 -245.002304)
		(width 0.14478)
		(layer "In2.Cu")
		(net "M_C_CPU0_SA_CB<4>")
	)
	(segment
		(start 304.93589 -241.338862)
		(end 304.772822 -241.50193)
		(width 0.14478)
		(layer "In2.Cu")
		(net "M_C_CPU0_SA_CB<4>")
	)
	(segment
		(start 308.564788 -241.110008)
		(end 306.32273 -241.110008)
		(width 0.14478)
		(layer "In2.Cu")
		(net "M_C_CPU0_SA_CB<4>")
	)
	(segment
		(start 305.098958 -241.110008)
		(end 304.93589 -241.273076)
		(width 0.14478)
		(layer "In2.Cu")
		(net "M_C_CPU0_SA_CB<4>")
	)
	(segment
		(start 293.93896 -240.723166)
		(end 293.775892 -240.560098)
		(width 0.14478)
		(layer "In2.Cu")
		(net "M_C_CPU0_SA_CB<4>")
	)
	(segment
		(start 333.588106 -248.046748)
		(end 333.579724 -248.051574)
		(width 0.0889)
		(layer "In2.Cu")
		(net "M_C_CPU0_SA_CB<4>")
	)
	(segment
		(start 292.976554 -241.381534)
		(end 292.280086 -240.685066)
		(width 0.14478)
		(layer "In2.Cu")
		(net "M_C_CPU0_SA_CB<4>")
	)
	(segment
		(start 312.210196 -245.952772)
		(end 312.047128 -245.789704)
		(width 0.14478)
		(layer "In2.Cu")
		(net "M_C_CPU0_SA_CB<4>")
	)
	(segment
		(start 304.772822 -241.50193)
		(end 304.542444 -241.50193)
		(width 0.14478)
		(layer "In2.Cu")
		(net "M_C_CPU0_SA_CB<4>")
	)
	(segment
		(start 293.93896 -240.960148)
		(end 293.93896 -240.723166)
		(width 0.14478)
		(layer "In2.Cu")
		(net "M_C_CPU0_SA_CB<4>")
	)
	(segment
		(start 331.342492 -248.051574)
		(end 331.33411 -248.046748)
		(width 0.0889)
		(layer "In2.Cu")
		(net "M_C_CPU0_SA_CB<4>")
	)
	(segment
		(start 310.573166 -243.513102)
		(end 310.573166 -243.118386)
		(width 0.14478)
		(layer "In2.Cu")
		(net "M_C_CPU0_SA_CB<4>")
	)
	(segment
		(start 312.047128 -245.559072)
		(end 312.415174 -245.191026)
		(width 0.14478)
		(layer "In2.Cu")
		(net "M_C_CPU0_SA_CB<4>")
	)
	(segment
		(start 304.542444 -241.50193)
		(end 304.379376 -241.338862)
		(width 0.14478)
		(layer "In2.Cu")
		(net "M_C_CPU0_SA_CB<4>")
	)
	(segment
		(start 294.622728 -241.321082)
		(end 294.45966 -241.48415)
		(width 0.14478)
		(layer "In2.Cu")
		(net "M_C_CPU0_SA_CB<4>")
	)
	(segment
		(start 304.379376 -241.338862)
		(end 304.379376 -241.273076)
		(width 0.14478)
		(layer "In2.Cu")
		(net "M_C_CPU0_SA_CB<4>")
	)
	(segment
		(start 312.021474 -244.797326)
		(end 311.653428 -245.165372)
		(width 0.14478)
		(layer "In2.Cu")
		(net "M_C_CPU0_SA_CB<4>")
	)
	(segment
		(start 323.901054 -248.26087)
		(end 323.065394 -248.26087)
		(width 0.14478)
		(layer "In2.Cu")
		(net "M_C_CPU0_SA_CB<4>")
	)
	(segment
		(start 312.252106 -244.797326)
		(end 312.021474 -244.797326)
		(width 0.14478)
		(layer "In2.Cu")
		(net "M_C_CPU0_SA_CB<4>")
	)
	(segment
		(start 324.887336 -248.36501)
		(end 324.259194 -248.36501)
		(width 0.0889)
		(layer "In2.Cu")
		(net "M_C_CPU0_SA_CB<4>")
	)
	(segment
		(start 305.609752 -240.948464)
		(end 305.448208 -241.110008)
		(width 0.14478)
		(layer "In2.Cu")
		(net "M_C_CPU0_SA_CB<4>")
	)
	(arc
		(start 327.939908 -248.051574)
		(mid 327.756146 -248.09719)
		(end 327.57364 -248.046748)
		(width 0.0889)
		(layer "In2.Cu")
		(net "M_C_CPU0_SA_CB<4>")
	)
	(arc
		(start 340.16823 -248.046748)
		(mid 339.985979 -248.097098)
		(end 339.80247 -248.051574)
		(width 0.0889)
		(layer "In2.Cu")
		(net "M_C_CPU0_SA_CB<4>")
	)
	(arc
		(start 335.094072 -248.046748)
		(mid 334.811116 -247.970571)
		(end 334.52816 -248.046748)
		(width 0.0889)
		(layer "In2.Cu")
		(net "M_C_CPU0_SA_CB<4>")
	)
	(arc
		(start 331.33411 -248.046748)
		(mid 331.051154 -247.970571)
		(end 330.768198 -248.046748)
		(width 0.0889)
		(layer "In2.Cu")
		(net "M_C_CPU0_SA_CB<4>")
	)
	(arc
		(start 339.794088 -248.046748)
		(mid 339.511132 -247.970571)
		(end 339.228176 -248.046748)
		(width 0.0889)
		(layer "In2.Cu")
		(net "M_C_CPU0_SA_CB<4>")
	)
	(arc
		(start 334.519778 -248.051574)
		(mid 334.33627 -248.097068)
		(end 334.154018 -248.046748)
		(width 0.0889)
		(layer "In2.Cu")
		(net "M_C_CPU0_SA_CB<4>")
	)
	(arc
		(start 332.274164 -248.046748)
		(mid 331.991208 -247.970571)
		(end 331.708252 -248.046748)
		(width 0.0889)
		(layer "In2.Cu")
		(net "M_C_CPU0_SA_CB<4>")
	)
	(arc
		(start 327.00722 -248.046748)
		(mid 326.828233 -248.096918)
		(end 326.647302 -248.054368)
		(width 0.0889)
		(layer "In2.Cu")
		(net "M_C_CPU0_SA_CB<4>")
	)
	(arc
		(start 333.579724 -248.051574)
		(mid 333.396216 -248.097068)
		(end 333.213964 -248.046748)
		(width 0.0889)
		(layer "In2.Cu")
		(net "M_C_CPU0_SA_CB<4>")
	)
	(arc
		(start 332.648052 -248.046748)
		(mid 332.461108 -248.097003)
		(end 332.274164 -248.046748)
		(width 0.0889)
		(layer "In2.Cu")
		(net "M_C_CPU0_SA_CB<4>")
	)
	(arc
		(start 330.768198 -248.046748)
		(mid 330.585947 -248.097098)
		(end 330.402438 -248.051574)
		(width 0.0889)
		(layer "In2.Cu")
		(net "M_C_CPU0_SA_CB<4>")
	)
	(arc
		(start 341.673942 -248.046748)
		(mid 341.390986 -247.970571)
		(end 341.10803 -248.046748)
		(width 0.0889)
		(layer "In2.Cu")
		(net "M_C_CPU0_SA_CB<4>")
	)
	(arc
		(start 331.708252 -248.046748)
		(mid 331.526001 -248.097098)
		(end 331.342492 -248.051574)
		(width 0.0889)
		(layer "In2.Cu")
		(net "M_C_CPU0_SA_CB<4>")
	)
	(arc
		(start 326.067674 -248.046748)
		(mid 325.498581 -248.28404)
		(end 324.887336 -248.36501)
		(width 0.0889)
		(layer "In2.Cu")
		(net "M_C_CPU0_SA_CB<4>")
	)
	(arc
		(start 337.348068 -248.046748)
		(mid 337.161124 -248.097003)
		(end 336.97418 -248.046748)
		(width 0.0889)
		(layer "In2.Cu")
		(net "M_C_CPU0_SA_CB<4>")
	)
	(arc
		(start 341.10803 -248.046748)
		(mid 340.921086 -248.097003)
		(end 340.734142 -248.046748)
		(width 0.0889)
		(layer "In2.Cu")
		(net "M_C_CPU0_SA_CB<4>")
	)
	(arc
		(start 335.468214 -248.046748)
		(mid 335.285963 -248.097098)
		(end 335.102454 -248.051574)
		(width 0.0889)
		(layer "In2.Cu")
		(net "M_C_CPU0_SA_CB<4>")
	)
	(arc
		(start 329.454002 -248.046748)
		(mid 329.171046 -247.970571)
		(end 328.88809 -248.046748)
		(width 0.0889)
		(layer "In2.Cu")
		(net "M_C_CPU0_SA_CB<4>")
	)
	(arc
		(start 336.034126 -248.046748)
		(mid 335.75117 -247.970571)
		(end 335.468214 -248.046748)
		(width 0.0889)
		(layer "In2.Cu")
		(net "M_C_CPU0_SA_CB<4>")
	)
	(arc
		(start 328.514202 -248.046748)
		(mid 328.231246 -247.970571)
		(end 327.94829 -248.046748)
		(width 0.0889)
		(layer "In2.Cu")
		(net "M_C_CPU0_SA_CB<4>")
	)
	(arc
		(start 328.88809 -248.046748)
		(mid 328.701146 -248.097003)
		(end 328.514202 -248.046748)
		(width 0.0889)
		(layer "In2.Cu")
		(net "M_C_CPU0_SA_CB<4>")
	)
	(arc
		(start 336.408268 -248.046748)
		(mid 336.226017 -248.097098)
		(end 336.042508 -248.051574)
		(width 0.0889)
		(layer "In2.Cu")
		(net "M_C_CPU0_SA_CB<4>")
	)
	(arc
		(start 337.91398 -248.046748)
		(mid 337.631024 -247.970571)
		(end 337.348068 -248.046748)
		(width 0.0889)
		(layer "In2.Cu")
		(net "M_C_CPU0_SA_CB<4>")
	)
	(arc
		(start 334.154018 -248.046748)
		(mid 333.871062 -247.970571)
		(end 333.588106 -248.046748)
		(width 0.0889)
		(layer "In2.Cu")
		(net "M_C_CPU0_SA_CB<4>")
	)
	(arc
		(start 340.734142 -248.046748)
		(mid 340.451186 -247.970571)
		(end 340.16823 -248.046748)
		(width 0.0889)
		(layer "In2.Cu")
		(net "M_C_CPU0_SA_CB<4>")
	)
	(arc
		(start 336.97418 -248.046748)
		(mid 336.691224 -247.970571)
		(end 336.408268 -248.046748)
		(width 0.0889)
		(layer "In2.Cu")
		(net "M_C_CPU0_SA_CB<4>")
	)
	(arc
		(start 338.854034 -248.046748)
		(mid 338.571078 -247.970571)
		(end 338.288122 -248.046748)
		(width 0.0889)
		(layer "In2.Cu")
		(net "M_C_CPU0_SA_CB<4>")
	)
	(arc
		(start 329.819762 -248.051574)
		(mid 329.636254 -248.097068)
		(end 329.454002 -248.046748)
		(width 0.0889)
		(layer "In2.Cu")
		(net "M_C_CPU0_SA_CB<4>")
	)
	(arc
		(start 326.617838 -248.03735)
		(mid 326.341529 -247.970374)
		(end 326.067674 -248.046748)
		(width 0.0889)
		(layer "In2.Cu")
		(net "M_C_CPU0_SA_CB<4>")
	)
	(arc
		(start 341.992712 -248.07291)
		(mid 341.83038 -248.095728)
		(end 341.673942 -248.046748)
		(width 0.0889)
		(layer "In2.Cu")
		(net "M_C_CPU0_SA_CB<4>")
	)
	(arc
		(start 330.394056 -248.046748)
		(mid 330.1111 -247.970571)
		(end 329.828144 -248.046748)
		(width 0.0889)
		(layer "In2.Cu")
		(net "M_C_CPU0_SA_CB<4>")
	)
	(arc
		(start 327.57364 -248.046748)
		(mid 327.298934 -247.970384)
		(end 327.021952 -248.038112)
		(width 0.0889)
		(layer "In2.Cu")
		(net "M_C_CPU0_SA_CB<4>")
	)
	(arc
		(start 333.213964 -248.046748)
		(mid 332.931008 -247.970571)
		(end 332.648052 -248.046748)
		(width 0.0889)
		(layer "In2.Cu")
		(net "M_C_CPU0_SA_CB<4>")
	)
	(arc
		(start 338.27974 -248.051574)
		(mid 338.096232 -248.097068)
		(end 337.91398 -248.046748)
		(width 0.0889)
		(layer "In2.Cu")
		(net "M_C_CPU0_SA_CB<4>")
	)
	(arc
		(start 339.228176 -248.046748)
		(mid 339.045925 -248.097098)
		(end 338.862416 -248.051574)
		(width 0.0889)
		(layer "In2.Cu")
		(net "M_C_CPU0_SA_CB<4>")
	)
	(segment
		(start 344.207846 -246.370094)
		(end 343.740994 -246.104156)
		(width 0.10668)
		(layer "F.Cu")
		(net "M_C_CPU0_SA_CB<3>")
	)
	(segment
		(start 338.854034 -245.781576)
		(end 338.862416 -245.77675)
		(width 0.0889)
		(layer "In2.Cu")
		(net "M_C_CPU0_SA_CB<3>")
	)
	(segment
		(start 335.094072 -245.781576)
		(end 335.102454 -245.77675)
		(width 0.0889)
		(layer "In2.Cu")
		(net "M_C_CPU0_SA_CB<3>")
	)
	(segment
		(start 309.384954 -237.59033)
		(end 309.384954 -238.12119)
		(width 0.14478)
		(layer "In2.Cu")
		(net "M_C_CPU0_SA_CB<3>")
	)
	(segment
		(start 304.105564 -237.710218)
		(end 305.387248 -237.179358)
		(width 0.14478)
		(layer "In2.Cu")
		(net "M_C_CPU0_SA_CB<3>")
	)
	(segment
		(start 313.136534 -241.87277)
		(end 314.772548 -241.87277)
		(width 0.14478)
		(layer "In2.Cu")
		(net "M_C_CPU0_SA_CB<3>")
	)
	(segment
		(start 288.180018 -237.285022)
		(end 288.595308 -237.700312)
		(width 0.14478)
		(layer "In2.Cu")
		(net "M_C_CPU0_SA_CB<3>")
	)
	(segment
		(start 329.819762 -245.77675)
		(end 329.828144 -245.781576)
		(width 0.0889)
		(layer "In2.Cu")
		(net "M_C_CPU0_SA_CB<3>")
	)
	(segment
		(start 343.58707 -245.838726)
		(end 343.740994 -246.104156)
		(width 0.0889)
		(layer "In2.Cu")
		(net "M_C_CPU0_SA_CB<3>")
	)
	(segment
		(start 342.979756 -245.77675)
		(end 342.988138 -245.781576)
		(width 0.0889)
		(layer "In2.Cu")
		(net "M_C_CPU0_SA_CB<3>")
	)
	(segment
		(start 342.039702 -245.77675)
		(end 342.048084 -245.781576)
		(width 0.0889)
		(layer "In2.Cu")
		(net "M_C_CPU0_SA_CB<3>")
	)
	(segment
		(start 301.090838 -236.850428)
		(end 301.950628 -237.710218)
		(width 0.14478)
		(layer "In2.Cu")
		(net "M_C_CPU0_SA_CB<3>")
	)
	(segment
		(start 326.990964 -245.769638)
		(end 327.011538 -245.781576)
		(width 0.0889)
		(layer "In2.Cu")
		(net "M_C_CPU0_SA_CB<3>")
	)
	(segment
		(start 308.654704 -236.86008)
		(end 309.384954 -237.59033)
		(width 0.14478)
		(layer "In2.Cu")
		(net "M_C_CPU0_SA_CB<3>")
	)
	(segment
		(start 305.706526 -236.86008)
		(end 308.654704 -236.86008)
		(width 0.14478)
		(layer "In2.Cu")
		(net "M_C_CPU0_SA_CB<3>")
	)
	(segment
		(start 331.33411 -245.781576)
		(end 331.342492 -245.77675)
		(width 0.0889)
		(layer "In2.Cu")
		(net "M_C_CPU0_SA_CB<3>")
	)
	(segment
		(start 333.579724 -245.77675)
		(end 333.588106 -245.781576)
		(width 0.0889)
		(layer "In2.Cu")
		(net "M_C_CPU0_SA_CB<3>")
	)
	(segment
		(start 309.384954 -238.12119)
		(end 313.136534 -241.87277)
		(width 0.14478)
		(layer "In2.Cu")
		(net "M_C_CPU0_SA_CB<3>")
	)
	(segment
		(start 314.772548 -241.87277)
		(end 318.051688 -245.15191)
		(width 0.14478)
		(layer "In2.Cu")
		(net "M_C_CPU0_SA_CB<3>")
	)
	(segment
		(start 288.595308 -237.700312)
		(end 297.37812 -237.700312)
		(width 0.14478)
		(layer "In2.Cu")
		(net "M_C_CPU0_SA_CB<3>")
	)
	(segment
		(start 330.394056 -245.781576)
		(end 330.402438 -245.77675)
		(width 0.0889)
		(layer "In2.Cu")
		(net "M_C_CPU0_SA_CB<3>")
	)
	(segment
		(start 298.228004 -236.850428)
		(end 301.090838 -236.850428)
		(width 0.14478)
		(layer "In2.Cu")
		(net "M_C_CPU0_SA_CB<3>")
	)
	(segment
		(start 326.046846 -245.768368)
		(end 326.109584 -245.80469)
		(width 0.0889)
		(layer "In2.Cu")
		(net "M_C_CPU0_SA_CB<3>")
	)
	(segment
		(start 318.051688 -245.15191)
		(end 323.267832 -245.15191)
		(width 0.14478)
		(layer "In2.Cu")
		(net "M_C_CPU0_SA_CB<3>")
	)
	(segment
		(start 343.491058 -245.813326)
		(end 343.58707 -245.838726)
		(width 0.0889)
		(layer "In2.Cu")
		(net "M_C_CPU0_SA_CB<3>")
	)
	(segment
		(start 338.27974 -245.77675)
		(end 338.288122 -245.781576)
		(width 0.0889)
		(layer "In2.Cu")
		(net "M_C_CPU0_SA_CB<3>")
	)
	(segment
		(start 334.519778 -245.77675)
		(end 334.52816 -245.781576)
		(width 0.0889)
		(layer "In2.Cu")
		(net "M_C_CPU0_SA_CB<3>")
	)
	(segment
		(start 301.950628 -237.710218)
		(end 304.105564 -237.710218)
		(width 0.14478)
		(layer "In2.Cu")
		(net "M_C_CPU0_SA_CB<3>")
	)
	(segment
		(start 323.903086 -245.787164)
		(end 323.940678 -245.787164)
		(width 0.14478)
		(layer "In2.Cu")
		(net "M_C_CPU0_SA_CB<3>")
	)
	(segment
		(start 323.940678 -245.787164)
		(end 325.15556 -245.787164)
		(width 0.0889)
		(layer "In2.Cu")
		(net "M_C_CPU0_SA_CB<3>")
	)
	(segment
		(start 327.549256 -245.796816)
		(end 327.575418 -245.78183)
		(width 0.0889)
		(layer "In2.Cu")
		(net "M_C_CPU0_SA_CB<3>")
	)
	(segment
		(start 336.034126 -245.781576)
		(end 336.042508 -245.77675)
		(width 0.0889)
		(layer "In2.Cu")
		(net "M_C_CPU0_SA_CB<3>")
	)
	(segment
		(start 339.794088 -245.781576)
		(end 339.80247 -245.77675)
		(width 0.0889)
		(layer "In2.Cu")
		(net "M_C_CPU0_SA_CB<3>")
	)
	(segment
		(start 323.267832 -245.15191)
		(end 323.903086 -245.787164)
		(width 0.14478)
		(layer "In2.Cu")
		(net "M_C_CPU0_SA_CB<3>")
	)
	(segment
		(start 327.575418 -245.78183)
		(end 327.598786 -245.768368)
		(width 0.0889)
		(layer "In2.Cu")
		(net "M_C_CPU0_SA_CB<3>")
	)
	(segment
		(start 297.37812 -237.700312)
		(end 298.228004 -236.850428)
		(width 0.14478)
		(layer "In2.Cu")
		(net "M_C_CPU0_SA_CB<3>")
	)
	(segment
		(start 305.387248 -237.179358)
		(end 305.706526 -236.86008)
		(width 0.14478)
		(layer "In2.Cu")
		(net "M_C_CPU0_SA_CB<3>")
	)
	(arc
		(start 332.274164 -245.781576)
		(mid 332.461108 -245.731321)
		(end 332.648052 -245.781576)
		(width 0.0889)
		(layer "In2.Cu")
		(net "M_C_CPU0_SA_CB<3>")
	)
	(arc
		(start 338.288122 -245.781576)
		(mid 338.571078 -245.857753)
		(end 338.854034 -245.781576)
		(width 0.0889)
		(layer "In2.Cu")
		(net "M_C_CPU0_SA_CB<3>")
	)
	(arc
		(start 340.734142 -245.781576)
		(mid 340.921086 -245.731321)
		(end 341.10803 -245.781576)
		(width 0.0889)
		(layer "In2.Cu")
		(net "M_C_CPU0_SA_CB<3>")
	)
	(arc
		(start 339.228176 -245.781576)
		(mid 339.511132 -245.857753)
		(end 339.794088 -245.781576)
		(width 0.0889)
		(layer "In2.Cu")
		(net "M_C_CPU0_SA_CB<3>")
	)
	(arc
		(start 329.828144 -245.781576)
		(mid 330.1111 -245.857753)
		(end 330.394056 -245.781576)
		(width 0.0889)
		(layer "In2.Cu")
		(net "M_C_CPU0_SA_CB<3>")
	)
	(arc
		(start 326.109584 -245.80469)
		(mid 326.375708 -245.858296)
		(end 326.636126 -245.781576)
		(width 0.0889)
		(layer "In2.Cu")
		(net "M_C_CPU0_SA_CB<3>")
	)
	(arc
		(start 335.468214 -245.781576)
		(mid 335.75117 -245.857753)
		(end 336.034126 -245.781576)
		(width 0.0889)
		(layer "In2.Cu")
		(net "M_C_CPU0_SA_CB<3>")
	)
	(arc
		(start 336.97418 -245.781576)
		(mid 337.161124 -245.731321)
		(end 337.348068 -245.781576)
		(width 0.0889)
		(layer "In2.Cu")
		(net "M_C_CPU0_SA_CB<3>")
	)
	(arc
		(start 336.408268 -245.781576)
		(mid 336.691224 -245.857753)
		(end 336.97418 -245.781576)
		(width 0.0889)
		(layer "In2.Cu")
		(net "M_C_CPU0_SA_CB<3>")
	)
	(arc
		(start 339.80247 -245.77675)
		(mid 339.985978 -245.731256)
		(end 340.16823 -245.781576)
		(width 0.0889)
		(layer "In2.Cu")
		(net "M_C_CPU0_SA_CB<3>")
	)
	(arc
		(start 333.213964 -245.781576)
		(mid 333.396215 -245.731226)
		(end 333.579724 -245.77675)
		(width 0.0889)
		(layer "In2.Cu")
		(net "M_C_CPU0_SA_CB<3>")
	)
	(arc
		(start 325.15556 -245.787164)
		(mid 325.492589 -245.77425)
		(end 325.827644 -245.735602)
		(width 0.0889)
		(layer "In2.Cu")
		(net "M_C_CPU0_SA_CB<3>")
	)
	(arc
		(start 330.402438 -245.77675)
		(mid 330.585946 -245.731256)
		(end 330.768198 -245.781576)
		(width 0.0889)
		(layer "In2.Cu")
		(net "M_C_CPU0_SA_CB<3>")
	)
	(arc
		(start 337.91398 -245.781576)
		(mid 338.096231 -245.731226)
		(end 338.27974 -245.77675)
		(width 0.0889)
		(layer "In2.Cu")
		(net "M_C_CPU0_SA_CB<3>")
	)
	(arc
		(start 331.342492 -245.77675)
		(mid 331.526 -245.731256)
		(end 331.708252 -245.781576)
		(width 0.0889)
		(layer "In2.Cu")
		(net "M_C_CPU0_SA_CB<3>")
	)
	(arc
		(start 335.102454 -245.77675)
		(mid 335.285962 -245.731256)
		(end 335.468214 -245.781576)
		(width 0.0889)
		(layer "In2.Cu")
		(net "M_C_CPU0_SA_CB<3>")
	)
	(arc
		(start 342.988138 -245.781576)
		(mid 343.235851 -245.856796)
		(end 343.491058 -245.813326)
		(width 0.0889)
		(layer "In2.Cu")
		(net "M_C_CPU0_SA_CB<3>")
	)
	(arc
		(start 342.048084 -245.781576)
		(mid 342.33104 -245.857753)
		(end 342.613996 -245.781576)
		(width 0.0889)
		(layer "In2.Cu")
		(net "M_C_CPU0_SA_CB<3>")
	)
	(arc
		(start 325.827644 -245.735602)
		(mid 325.93973 -245.735343)
		(end 326.046846 -245.768368)
		(width 0.0889)
		(layer "In2.Cu")
		(net "M_C_CPU0_SA_CB<3>")
	)
	(arc
		(start 330.768198 -245.781576)
		(mid 331.051154 -245.857753)
		(end 331.33411 -245.781576)
		(width 0.0889)
		(layer "In2.Cu")
		(net "M_C_CPU0_SA_CB<3>")
	)
	(arc
		(start 340.16823 -245.781576)
		(mid 340.451186 -245.857753)
		(end 340.734142 -245.781576)
		(width 0.0889)
		(layer "In2.Cu")
		(net "M_C_CPU0_SA_CB<3>")
	)
	(arc
		(start 333.588106 -245.781576)
		(mid 333.871062 -245.857753)
		(end 334.154018 -245.781576)
		(width 0.0889)
		(layer "In2.Cu")
		(net "M_C_CPU0_SA_CB<3>")
	)
	(arc
		(start 328.514202 -245.781576)
		(mid 328.701146 -245.731321)
		(end 328.88809 -245.781576)
		(width 0.0889)
		(layer "In2.Cu")
		(net "M_C_CPU0_SA_CB<3>")
	)
	(arc
		(start 327.598786 -245.768368)
		(mid 327.775181 -245.731465)
		(end 327.94829 -245.781576)
		(width 0.0889)
		(layer "In2.Cu")
		(net "M_C_CPU0_SA_CB<3>")
	)
	(arc
		(start 342.613996 -245.781576)
		(mid 342.796247 -245.731226)
		(end 342.979756 -245.77675)
		(width 0.0889)
		(layer "In2.Cu")
		(net "M_C_CPU0_SA_CB<3>")
	)
	(arc
		(start 327.94829 -245.781576)
		(mid 328.231246 -245.857753)
		(end 328.514202 -245.781576)
		(width 0.0889)
		(layer "In2.Cu")
		(net "M_C_CPU0_SA_CB<3>")
	)
	(arc
		(start 337.348068 -245.781576)
		(mid 337.631024 -245.857753)
		(end 337.91398 -245.781576)
		(width 0.0889)
		(layer "In2.Cu")
		(net "M_C_CPU0_SA_CB<3>")
	)
	(arc
		(start 336.042508 -245.77675)
		(mid 336.226016 -245.731256)
		(end 336.408268 -245.781576)
		(width 0.0889)
		(layer "In2.Cu")
		(net "M_C_CPU0_SA_CB<3>")
	)
	(arc
		(start 326.636126 -245.781576)
		(mid 326.812036 -245.730766)
		(end 326.990964 -245.769638)
		(width 0.0889)
		(layer "In2.Cu")
		(net "M_C_CPU0_SA_CB<3>")
	)
	(arc
		(start 332.648052 -245.781576)
		(mid 332.931008 -245.857753)
		(end 333.213964 -245.781576)
		(width 0.0889)
		(layer "In2.Cu")
		(net "M_C_CPU0_SA_CB<3>")
	)
	(arc
		(start 329.454002 -245.781576)
		(mid 329.636253 -245.731226)
		(end 329.819762 -245.77675)
		(width 0.0889)
		(layer "In2.Cu")
		(net "M_C_CPU0_SA_CB<3>")
	)
	(arc
		(start 328.88809 -245.781576)
		(mid 329.171046 -245.857753)
		(end 329.454002 -245.781576)
		(width 0.0889)
		(layer "In2.Cu")
		(net "M_C_CPU0_SA_CB<3>")
	)
	(arc
		(start 338.862416 -245.77675)
		(mid 339.045924 -245.731256)
		(end 339.228176 -245.781576)
		(width 0.0889)
		(layer "In2.Cu")
		(net "M_C_CPU0_SA_CB<3>")
	)
	(arc
		(start 327.011538 -245.781576)
		(mid 327.278468 -245.857525)
		(end 327.549256 -245.796816)
		(width 0.0889)
		(layer "In2.Cu")
		(net "M_C_CPU0_SA_CB<3>")
	)
	(arc
		(start 334.154018 -245.781576)
		(mid 334.336269 -245.731226)
		(end 334.519778 -245.77675)
		(width 0.0889)
		(layer "In2.Cu")
		(net "M_C_CPU0_SA_CB<3>")
	)
	(arc
		(start 341.10803 -245.781576)
		(mid 341.390986 -245.857753)
		(end 341.673942 -245.781576)
		(width 0.0889)
		(layer "In2.Cu")
		(net "M_C_CPU0_SA_CB<3>")
	)
	(arc
		(start 334.52816 -245.781576)
		(mid 334.811116 -245.857753)
		(end 335.094072 -245.781576)
		(width 0.0889)
		(layer "In2.Cu")
		(net "M_C_CPU0_SA_CB<3>")
	)
	(arc
		(start 341.673942 -245.781576)
		(mid 341.856193 -245.731226)
		(end 342.039702 -245.77675)
		(width 0.0889)
		(layer "In2.Cu")
		(net "M_C_CPU0_SA_CB<3>")
	)
	(arc
		(start 331.708252 -245.781576)
		(mid 331.991208 -245.857753)
		(end 332.274164 -245.781576)
		(width 0.0889)
		(layer "In2.Cu")
		(net "M_C_CPU0_SA_CB<3>")
	)
	(segment
		(start 342.797892 -245.560088)
		(end 342.33104 -245.29415)
		(width 0.10668)
		(layer "F.Cu")
		(net "M_C_CPU0_SA_CB<2>")
	)
	(segment
		(start 339.698076 -244.97157)
		(end 339.689694 -244.966744)
		(width 0.0889)
		(layer "In2.Cu")
		(net "M_C_CPU0_SA_CB<2>")
	)
	(segment
		(start 308.277768 -235.160058)
		(end 305.706526 -235.160058)
		(width 0.14478)
		(layer "In2.Cu")
		(net "M_C_CPU0_SA_CB<2>")
	)
	(segment
		(start 332.178152 -244.97157)
		(end 332.16977 -244.966744)
		(width 0.0889)
		(layer "In2.Cu")
		(net "M_C_CPU0_SA_CB<2>")
	)
	(segment
		(start 324.058534 -244.63375)
		(end 323.662294 -244.23751)
		(width 0.14478)
		(layer "In2.Cu")
		(net "M_C_CPU0_SA_CB<2>")
	)
	(segment
		(start 325.150734 -245.21795)
		(end 324.642734 -245.21795)
		(width 0.0889)
		(layer "In2.Cu")
		(net "M_C_CPU0_SA_CB<2>")
	)
	(segment
		(start 290.319714 -236.010196)
		(end 288.605214 -236.010196)
		(width 0.14478)
		(layer "In2.Cu")
		(net "M_C_CPU0_SA_CB<2>")
	)
	(segment
		(start 335.938114 -244.97157)
		(end 335.929732 -244.966744)
		(width 0.0889)
		(layer "In2.Cu")
		(net "M_C_CPU0_SA_CB<2>")
	)
	(segment
		(start 301.90186 -236.010196)
		(end 301.051722 -235.160058)
		(width 0.14478)
		(layer "In2.Cu")
		(net "M_C_CPU0_SA_CB<2>")
	)
	(segment
		(start 290.64585 -235.47197)
		(end 290.482782 -235.635038)
		(width 0.14478)
		(layer "In2.Cu")
		(net "M_C_CPU0_SA_CB<2>")
	)
	(segment
		(start 288.605214 -236.010196)
		(end 288.180018 -235.585)
		(width 0.14478)
		(layer "In2.Cu")
		(net "M_C_CPU0_SA_CB<2>")
	)
	(segment
		(start 310.294274 -237.176564)
		(end 308.277768 -235.160058)
		(width 0.14478)
		(layer "In2.Cu")
		(net "M_C_CPU0_SA_CB<2>")
	)
	(segment
		(start 331.238098 -244.97157)
		(end 331.229716 -244.966744)
		(width 0.0889)
		(layer "In2.Cu")
		(net "M_C_CPU0_SA_CB<2>")
	)
	(segment
		(start 315.12002 -240.91519)
		(end 313.507374 -240.91519)
		(width 0.14478)
		(layer "In2.Cu")
		(net "M_C_CPU0_SA_CB<2>")
	)
	(segment
		(start 323.662294 -244.23751)
		(end 318.44234 -244.23751)
		(width 0.14478)
		(layer "In2.Cu")
		(net "M_C_CPU0_SA_CB<2>")
	)
	(segment
		(start 326.537828 -244.971824)
		(end 326.51954 -244.96141)
		(width 0.0889)
		(layer "In2.Cu")
		(net "M_C_CPU0_SA_CB<2>")
	)
	(segment
		(start 313.507374 -240.91519)
		(end 310.294274 -237.70209)
		(width 0.14478)
		(layer "In2.Cu")
		(net "M_C_CPU0_SA_CB<2>")
	)
	(segment
		(start 301.051722 -235.160058)
		(end 298.218352 -235.160058)
		(width 0.14478)
		(layer "In2.Cu")
		(net "M_C_CPU0_SA_CB<2>")
	)
	(segment
		(start 305.706526 -235.160058)
		(end 304.856388 -236.010196)
		(width 0.14478)
		(layer "In2.Cu")
		(net "M_C_CPU0_SA_CB<2>")
	)
	(segment
		(start 328.41819 -244.97157)
		(end 328.409808 -244.966744)
		(width 0.0889)
		(layer "In2.Cu")
		(net "M_C_CPU0_SA_CB<2>")
	)
	(segment
		(start 326.163686 -244.97157)
		(end 326.135746 -244.987826)
		(width 0.0889)
		(layer "In2.Cu")
		(net "M_C_CPU0_SA_CB<2>")
	)
	(segment
		(start 291.039296 -235.847128)
		(end 291.039296 -235.635038)
		(width 0.14478)
		(layer "In2.Cu")
		(net "M_C_CPU0_SA_CB<2>")
	)
	(segment
		(start 324.642734 -245.21795)
		(end 324.058534 -244.63375)
		(width 0.0889)
		(layer "In2.Cu")
		(net "M_C_CPU0_SA_CB<2>")
	)
	(segment
		(start 341.212424 -244.966744)
		(end 341.204042 -244.97157)
		(width 0.0889)
		(layer "In2.Cu")
		(net "M_C_CPU0_SA_CB<2>")
	)
	(segment
		(start 332.752446 -244.966744)
		(end 332.744064 -244.97157)
		(width 0.0889)
		(layer "In2.Cu")
		(net "M_C_CPU0_SA_CB<2>")
	)
	(segment
		(start 328.992484 -244.966744)
		(end 328.984102 -244.97157)
		(width 0.0889)
		(layer "In2.Cu")
		(net "M_C_CPU0_SA_CB<2>")
	)
	(segment
		(start 290.482782 -235.847128)
		(end 290.319714 -236.010196)
		(width 0.14478)
		(layer "In2.Cu")
		(net "M_C_CPU0_SA_CB<2>")
	)
	(segment
		(start 340.63813 -244.97157)
		(end 340.629748 -244.966744)
		(width 0.0889)
		(layer "In2.Cu")
		(net "M_C_CPU0_SA_CB<2>")
	)
	(segment
		(start 304.856388 -236.010196)
		(end 301.90186 -236.010196)
		(width 0.14478)
		(layer "In2.Cu")
		(net "M_C_CPU0_SA_CB<2>")
	)
	(segment
		(start 291.039296 -235.635038)
		(end 290.876228 -235.47197)
		(width 0.14478)
		(layer "In2.Cu")
		(net "M_C_CPU0_SA_CB<2>")
	)
	(segment
		(start 297.368214 -236.010196)
		(end 291.202364 -236.010196)
		(width 0.14478)
		(layer "In2.Cu")
		(net "M_C_CPU0_SA_CB<2>")
	)
	(segment
		(start 298.218352 -235.160058)
		(end 297.368214 -236.010196)
		(width 0.14478)
		(layer "In2.Cu")
		(net "M_C_CPU0_SA_CB<2>")
	)
	(segment
		(start 328.044048 -244.97157)
		(end 328.029316 -244.980206)
		(width 0.0889)
		(layer "In2.Cu")
		(net "M_C_CPU0_SA_CB<2>")
	)
	(segment
		(start 325.887334 -245.054628)
		(end 325.314056 -245.054628)
		(width 0.0889)
		(layer "In2.Cu")
		(net "M_C_CPU0_SA_CB<2>")
	)
	(segment
		(start 310.294274 -237.70209)
		(end 310.294274 -237.176564)
		(width 0.14478)
		(layer "In2.Cu")
		(net "M_C_CPU0_SA_CB<2>")
	)
	(segment
		(start 342.177116 -245.02872)
		(end 342.081104 -245.00332)
		(width 0.0889)
		(layer "In2.Cu")
		(net "M_C_CPU0_SA_CB<2>")
	)
	(segment
		(start 336.878168 -244.97157)
		(end 336.869786 -244.966744)
		(width 0.0889)
		(layer "In2.Cu")
		(net "M_C_CPU0_SA_CB<2>")
	)
	(segment
		(start 327.114916 -244.964712)
		(end 327.103232 -244.97157)
		(width 0.0889)
		(layer "In2.Cu")
		(net "M_C_CPU0_SA_CB<2>")
	)
	(segment
		(start 290.876228 -235.47197)
		(end 290.64585 -235.47197)
		(width 0.14478)
		(layer "In2.Cu")
		(net "M_C_CPU0_SA_CB<2>")
	)
	(segment
		(start 318.44234 -244.23751)
		(end 315.12002 -240.91519)
		(width 0.14478)
		(layer "In2.Cu")
		(net "M_C_CPU0_SA_CB<2>")
	)
	(segment
		(start 325.314056 -245.054628)
		(end 325.150734 -245.21795)
		(width 0.0889)
		(layer "In2.Cu")
		(net "M_C_CPU0_SA_CB<2>")
	)
	(segment
		(start 342.33104 -245.29415)
		(end 342.177116 -245.02872)
		(width 0.0889)
		(layer "In2.Cu")
		(net "M_C_CPU0_SA_CB<2>")
	)
	(segment
		(start 290.482782 -235.635038)
		(end 290.482782 -235.847128)
		(width 0.14478)
		(layer "In2.Cu")
		(net "M_C_CPU0_SA_CB<2>")
	)
	(segment
		(start 337.452462 -244.966744)
		(end 337.44408 -244.97157)
		(width 0.0889)
		(layer "In2.Cu")
		(net "M_C_CPU0_SA_CB<2>")
	)
	(segment
		(start 326.543416 -244.975126)
		(end 326.537828 -244.971824)
		(width 0.0889)
		(layer "In2.Cu")
		(net "M_C_CPU0_SA_CB<2>")
	)
	(segment
		(start 291.202364 -236.010196)
		(end 291.039296 -235.847128)
		(width 0.14478)
		(layer "In2.Cu")
		(net "M_C_CPU0_SA_CB<2>")
	)
	(segment
		(start 333.6925 -244.966744)
		(end 333.684118 -244.97157)
		(width 0.0889)
		(layer "In2.Cu")
		(net "M_C_CPU0_SA_CB<2>")
	)
	(arc
		(start 336.869786 -244.966744)
		(mid 336.686278 -244.92125)
		(end 336.504026 -244.97157)
		(width 0.0889)
		(layer "In2.Cu")
		(net "M_C_CPU0_SA_CB<2>")
	)
	(arc
		(start 329.358244 -244.97157)
		(mid 329.175993 -244.92122)
		(end 328.992484 -244.966744)
		(width 0.0889)
		(layer "In2.Cu")
		(net "M_C_CPU0_SA_CB<2>")
	)
	(arc
		(start 330.863956 -244.97157)
		(mid 330.581 -245.047747)
		(end 330.298044 -244.97157)
		(width 0.0889)
		(layer "In2.Cu")
		(net "M_C_CPU0_SA_CB<2>")
	)
	(arc
		(start 336.504026 -244.97157)
		(mid 336.22107 -245.047747)
		(end 335.938114 -244.97157)
		(width 0.0889)
		(layer "In2.Cu")
		(net "M_C_CPU0_SA_CB<2>")
	)
	(arc
		(start 337.44408 -244.97157)
		(mid 337.161124 -245.047747)
		(end 336.878168 -244.97157)
		(width 0.0889)
		(layer "In2.Cu")
		(net "M_C_CPU0_SA_CB<2>")
	)
	(arc
		(start 332.16977 -244.966744)
		(mid 331.986262 -244.92125)
		(end 331.80401 -244.97157)
		(width 0.0889)
		(layer "In2.Cu")
		(net "M_C_CPU0_SA_CB<2>")
	)
	(arc
		(start 327.103232 -244.97157)
		(mid 326.823804 -245.047736)
		(end 326.543416 -244.975126)
		(width 0.0889)
		(layer "In2.Cu")
		(net "M_C_CPU0_SA_CB<2>")
	)
	(arc
		(start 333.118206 -244.97157)
		(mid 332.935955 -244.92122)
		(end 332.752446 -244.966744)
		(width 0.0889)
		(layer "In2.Cu")
		(net "M_C_CPU0_SA_CB<2>")
	)
	(arc
		(start 327.477628 -244.97157)
		(mid 327.29717 -244.921126)
		(end 327.114916 -244.964712)
		(width 0.0889)
		(layer "In2.Cu")
		(net "M_C_CPU0_SA_CB<2>")
	)
	(arc
		(start 342.081104 -245.00332)
		(mid 341.825896 -245.046797)
		(end 341.578184 -244.97157)
		(width 0.0889)
		(layer "In2.Cu")
		(net "M_C_CPU0_SA_CB<2>")
	)
	(arc
		(start 331.229716 -244.966744)
		(mid 331.046208 -244.92125)
		(end 330.863956 -244.97157)
		(width 0.0889)
		(layer "In2.Cu")
		(net "M_C_CPU0_SA_CB<2>")
	)
	(arc
		(start 338.384134 -244.97157)
		(mid 338.101178 -245.047747)
		(end 337.818222 -244.97157)
		(width 0.0889)
		(layer "In2.Cu")
		(net "M_C_CPU0_SA_CB<2>")
	)
	(arc
		(start 335.929732 -244.966744)
		(mid 335.746224 -244.92125)
		(end 335.563972 -244.97157)
		(width 0.0889)
		(layer "In2.Cu")
		(net "M_C_CPU0_SA_CB<2>")
	)
	(arc
		(start 334.99806 -244.97157)
		(mid 334.811116 -244.921315)
		(end 334.624172 -244.97157)
		(width 0.0889)
		(layer "In2.Cu")
		(net "M_C_CPU0_SA_CB<2>")
	)
	(arc
		(start 328.984102 -244.97157)
		(mid 328.701146 -245.047747)
		(end 328.41819 -244.97157)
		(width 0.0889)
		(layer "In2.Cu")
		(net "M_C_CPU0_SA_CB<2>")
	)
	(arc
		(start 338.758022 -244.97157)
		(mid 338.571078 -244.921315)
		(end 338.384134 -244.97157)
		(width 0.0889)
		(layer "In2.Cu")
		(net "M_C_CPU0_SA_CB<2>")
	)
	(arc
		(start 329.924156 -244.97157)
		(mid 329.6412 -245.047747)
		(end 329.358244 -244.97157)
		(width 0.0889)
		(layer "In2.Cu")
		(net "M_C_CPU0_SA_CB<2>")
	)
	(arc
		(start 326.135746 -244.987826)
		(mid 326.015957 -245.037659)
		(end 325.887334 -245.054628)
		(width 0.0889)
		(layer "In2.Cu")
		(net "M_C_CPU0_SA_CB<2>")
	)
	(arc
		(start 332.744064 -244.97157)
		(mid 332.461108 -245.047747)
		(end 332.178152 -244.97157)
		(width 0.0889)
		(layer "In2.Cu")
		(net "M_C_CPU0_SA_CB<2>")
	)
	(arc
		(start 339.689694 -244.966744)
		(mid 339.506186 -244.92125)
		(end 339.323934 -244.97157)
		(width 0.0889)
		(layer "In2.Cu")
		(net "M_C_CPU0_SA_CB<2>")
	)
	(arc
		(start 334.624172 -244.97157)
		(mid 334.341216 -245.047747)
		(end 334.05826 -244.97157)
		(width 0.0889)
		(layer "In2.Cu")
		(net "M_C_CPU0_SA_CB<2>")
	)
	(arc
		(start 334.05826 -244.97157)
		(mid 333.876009 -244.92122)
		(end 333.6925 -244.966744)
		(width 0.0889)
		(layer "In2.Cu")
		(net "M_C_CPU0_SA_CB<2>")
	)
	(arc
		(start 333.684118 -244.97157)
		(mid 333.401162 -245.047747)
		(end 333.118206 -244.97157)
		(width 0.0889)
		(layer "In2.Cu")
		(net "M_C_CPU0_SA_CB<2>")
	)
	(arc
		(start 328.029316 -244.980206)
		(mid 327.752333 -245.04801)
		(end 327.477628 -244.97157)
		(width 0.0889)
		(layer "In2.Cu")
		(net "M_C_CPU0_SA_CB<2>")
	)
	(arc
		(start 340.629748 -244.966744)
		(mid 340.44624 -244.92125)
		(end 340.263988 -244.97157)
		(width 0.0889)
		(layer "In2.Cu")
		(net "M_C_CPU0_SA_CB<2>")
	)
	(arc
		(start 330.298044 -244.97157)
		(mid 330.1111 -244.921315)
		(end 329.924156 -244.97157)
		(width 0.0889)
		(layer "In2.Cu")
		(net "M_C_CPU0_SA_CB<2>")
	)
	(arc
		(start 337.818222 -244.97157)
		(mid 337.635971 -244.92122)
		(end 337.452462 -244.966744)
		(width 0.0889)
		(layer "In2.Cu")
		(net "M_C_CPU0_SA_CB<2>")
	)
	(arc
		(start 341.578184 -244.97157)
		(mid 341.395933 -244.92122)
		(end 341.212424 -244.966744)
		(width 0.0889)
		(layer "In2.Cu")
		(net "M_C_CPU0_SA_CB<2>")
	)
	(arc
		(start 331.80401 -244.97157)
		(mid 331.521054 -245.047747)
		(end 331.238098 -244.97157)
		(width 0.0889)
		(layer "In2.Cu")
		(net "M_C_CPU0_SA_CB<2>")
	)
	(arc
		(start 328.409808 -244.966744)
		(mid 328.2263 -244.92125)
		(end 328.044048 -244.97157)
		(width 0.0889)
		(layer "In2.Cu")
		(net "M_C_CPU0_SA_CB<2>")
	)
	(arc
		(start 341.204042 -244.97157)
		(mid 340.921086 -245.047747)
		(end 340.63813 -244.97157)
		(width 0.0889)
		(layer "In2.Cu")
		(net "M_C_CPU0_SA_CB<2>")
	)
	(arc
		(start 339.323934 -244.97157)
		(mid 339.040978 -245.047747)
		(end 338.758022 -244.97157)
		(width 0.0889)
		(layer "In2.Cu")
		(net "M_C_CPU0_SA_CB<2>")
	)
	(arc
		(start 326.51954 -244.96141)
		(mid 326.340311 -244.921257)
		(end 326.163686 -244.97157)
		(width 0.0889)
		(layer "In2.Cu")
		(net "M_C_CPU0_SA_CB<2>")
	)
	(arc
		(start 340.263988 -244.97157)
		(mid 339.981032 -245.047747)
		(end 339.698076 -244.97157)
		(width 0.0889)
		(layer "In2.Cu")
		(net "M_C_CPU0_SA_CB<2>")
	)
	(arc
		(start 335.563972 -244.97157)
		(mid 335.281016 -245.047747)
		(end 334.99806 -244.97157)
		(width 0.0889)
		(layer "In2.Cu")
		(net "M_C_CPU0_SA_CB<2>")
	)
	(segment
		(start 343.737946 -245.560088)
		(end 343.271094 -245.29415)
		(width 0.10668)
		(layer "F.Cu")
		(net "M_C_CPU0_SA_CB<1>")
	)
	(segment
		(start 332.752446 -245.621556)
		(end 332.744064 -245.61673)
		(width 0.0889)
		(layer "In2.Cu")
		(net "M_C_CPU0_SA_CB<1>")
	)
	(segment
		(start 323.469254 -244.69471)
		(end 318.247268 -244.69471)
		(width 0.14478)
		(layer "In2.Cu")
		(net "M_C_CPU0_SA_CB<1>")
	)
	(segment
		(start 293.618412 -236.48035)
		(end 293.455344 -236.643418)
		(width 0.14478)
		(layer "In2.Cu")
		(net "M_C_CPU0_SA_CB<1>")
	)
	(segment
		(start 296.443908 -236.562392)
		(end 296.14622 -236.86008)
		(width 0.14478)
		(layer "In2.Cu")
		(net "M_C_CPU0_SA_CB<1>")
	)
	(segment
		(start 304.467006 -236.697012)
		(end 304.467006 -236.635798)
		(width 0.14478)
		(layer "In2.Cu")
		(net "M_C_CPU0_SA_CB<1>")
	)
	(segment
		(start 314.937648 -241.38509)
		(end 313.314334 -241.38509)
		(width 0.14478)
		(layer "In2.Cu")
		(net "M_C_CPU0_SA_CB<1>")
	)
	(segment
		(start 336.878168 -245.61673)
		(end 336.869786 -245.621556)
		(width 0.0889)
		(layer "In2.Cu")
		(net "M_C_CPU0_SA_CB<1>")
	)
	(segment
		(start 298.892468 -235.61929)
		(end 298.7294 -235.782358)
		(width 0.14478)
		(layer "In2.Cu")
		(net "M_C_CPU0_SA_CB<1>")
	)
	(segment
		(start 292.705028 -236.86008)
		(end 292.280086 -236.435138)
		(width 0.14478)
		(layer "In2.Cu")
		(net "M_C_CPU0_SA_CB<1>")
	)
	(segment
		(start 296.697654 -236.562392)
		(end 296.443908 -236.562392)
		(width 0.14478)
		(layer "In2.Cu")
		(net "M_C_CPU0_SA_CB<1>")
	)
	(segment
		(start 295.124886 -236.643418)
		(end 294.961818 -236.48035)
		(width 0.14478)
		(layer "In2.Cu")
		(net "M_C_CPU0_SA_CB<1>")
	)
	(segment
		(start 298.217336 -236.010196)
		(end 297.367452 -236.86008)
		(width 0.14478)
		(layer "In2.Cu")
		(net "M_C_CPU0_SA_CB<1>")
	)
	(segment
		(start 301.042832 -236.010196)
		(end 299.448982 -236.010196)
		(width 0.14478)
		(layer "In2.Cu")
		(net "M_C_CPU0_SA_CB<1>")
	)
	(segment
		(start 294.961818 -236.48035)
		(end 294.73144 -236.48035)
		(width 0.14478)
		(layer "In2.Cu")
		(net "M_C_CPU0_SA_CB<1>")
	)
	(segment
		(start 342.152478 -245.621556)
		(end 342.144096 -245.61673)
		(width 0.0889)
		(layer "In2.Cu")
		(net "M_C_CPU0_SA_CB<1>")
	)
	(segment
		(start 297.367452 -236.86008)
		(end 296.995342 -236.86008)
		(width 0.14478)
		(layer "In2.Cu")
		(net "M_C_CPU0_SA_CB<1>")
	)
	(segment
		(start 326.19696 -245.634256)
		(end 326.165718 -245.616476)
		(width 0.0889)
		(layer "In2.Cu")
		(net "M_C_CPU0_SA_CB<1>")
	)
	(segment
		(start 295.124886 -236.697012)
		(end 295.124886 -236.643418)
		(width 0.14478)
		(layer "In2.Cu")
		(net "M_C_CPU0_SA_CB<1>")
	)
	(segment
		(start 302.457612 -236.46765)
		(end 302.294544 -236.630718)
		(width 0.14478)
		(layer "In2.Cu")
		(net "M_C_CPU0_SA_CB<1>")
	)
	(segment
		(start 335.938114 -245.61673)
		(end 335.929732 -245.621556)
		(width 0.0889)
		(layer "In2.Cu")
		(net "M_C_CPU0_SA_CB<1>")
	)
	(segment
		(start 303.014126 -236.86008)
		(end 302.851058 -236.697012)
		(width 0.14478)
		(layer "In2.Cu")
		(net "M_C_CPU0_SA_CB<1>")
	)
	(segment
		(start 294.011858 -236.643418)
		(end 293.84879 -236.48035)
		(width 0.14478)
		(layer "In2.Cu")
		(net "M_C_CPU0_SA_CB<1>")
	)
	(segment
		(start 327.50633 -245.60149)
		(end 327.480168 -245.616476)
		(width 0.0889)
		(layer "In2.Cu")
		(net "M_C_CPU0_SA_CB<1>")
	)
	(segment
		(start 294.568372 -236.643418)
		(end 294.568372 -237.025942)
		(width 0.14478)
		(layer "In2.Cu")
		(net "M_C_CPU0_SA_CB<1>")
	)
	(segment
		(start 294.011858 -237.025942)
		(end 294.011858 -236.643418)
		(width 0.14478)
		(layer "In2.Cu")
		(net "M_C_CPU0_SA_CB<1>")
	)
	(segment
		(start 306.82692 -235.847128)
		(end 306.82692 -235.789978)
		(width 0.14478)
		(layer "In2.Cu")
		(net "M_C_CPU0_SA_CB<1>")
	)
	(segment
		(start 294.568372 -237.025942)
		(end 294.405304 -237.18901)
		(width 0.14478)
		(layer "In2.Cu")
		(net "M_C_CPU0_SA_CB<1>")
	)
	(segment
		(start 294.174926 -237.18901)
		(end 294.011858 -237.025942)
		(width 0.14478)
		(layer "In2.Cu")
		(net "M_C_CPU0_SA_CB<1>")
	)
	(segment
		(start 309.839614 -237.377224)
		(end 308.472586 -236.010196)
		(width 0.14478)
		(layer "In2.Cu")
		(net "M_C_CPU0_SA_CB<1>")
	)
	(segment
		(start 303.910492 -236.697012)
		(end 303.747424 -236.86008)
		(width 0.14478)
		(layer "In2.Cu")
		(net "M_C_CPU0_SA_CB<1>")
	)
	(segment
		(start 306.270406 -235.789978)
		(end 306.270406 -235.847128)
		(width 0.14478)
		(layer "In2.Cu")
		(net "M_C_CPU0_SA_CB<1>")
	)
	(segment
		(start 293.292276 -236.86008)
		(end 292.705028 -236.86008)
		(width 0.14478)
		(layer "In2.Cu")
		(net "M_C_CPU0_SA_CB<1>")
	)
	(segment
		(start 298.566332 -236.010196)
		(end 298.217336 -236.010196)
		(width 0.14478)
		(layer "In2.Cu")
		(net "M_C_CPU0_SA_CB<1>")
	)
	(segment
		(start 302.851058 -236.697012)
		(end 302.851058 -236.630718)
		(width 0.14478)
		(layer "In2.Cu")
		(net "M_C_CPU0_SA_CB<1>")
	)
	(segment
		(start 293.455344 -236.643418)
		(end 293.455344 -236.697012)
		(width 0.14478)
		(layer "In2.Cu")
		(net "M_C_CPU0_SA_CB<1>")
	)
	(segment
		(start 301.892716 -236.86008)
		(end 301.042832 -236.010196)
		(width 0.14478)
		(layer "In2.Cu")
		(net "M_C_CPU0_SA_CB<1>")
	)
	(segment
		(start 302.68799 -236.46765)
		(end 302.457612 -236.46765)
		(width 0.14478)
		(layer "In2.Cu")
		(net "M_C_CPU0_SA_CB<1>")
	)
	(segment
		(start 306.82692 -235.789978)
		(end 306.663852 -235.62691)
		(width 0.14478)
		(layer "In2.Cu")
		(net "M_C_CPU0_SA_CB<1>")
	)
	(segment
		(start 306.989988 -236.010196)
		(end 306.82692 -235.847128)
		(width 0.14478)
		(layer "In2.Cu")
		(net "M_C_CPU0_SA_CB<1>")
	)
	(segment
		(start 327.10755 -245.61673)
		(end 327.078086 -245.599458)
		(width 0.0889)
		(layer "In2.Cu")
		(net "M_C_CPU0_SA_CB<1>")
	)
	(segment
		(start 294.405304 -237.18901)
		(end 294.174926 -237.18901)
		(width 0.14478)
		(layer "In2.Cu")
		(net "M_C_CPU0_SA_CB<1>")
	)
	(segment
		(start 302.294544 -236.697012)
		(end 302.131476 -236.86008)
		(width 0.14478)
		(layer "In2.Cu")
		(net "M_C_CPU0_SA_CB<1>")
	)
	(segment
		(start 296.995342 -236.86008)
		(end 296.697654 -236.562392)
		(width 0.14478)
		(layer "In2.Cu")
		(net "M_C_CPU0_SA_CB<1>")
	)
	(segment
		(start 304.890932 -236.86008)
		(end 304.630074 -236.86008)
		(width 0.14478)
		(layer "In2.Cu")
		(net "M_C_CPU0_SA_CB<1>")
	)
	(segment
		(start 309.839614 -237.91037)
		(end 309.839614 -237.377224)
		(width 0.14478)
		(layer "In2.Cu")
		(net "M_C_CPU0_SA_CB<1>")
	)
	(segment
		(start 298.7294 -235.782358)
		(end 298.7294 -235.847128)
		(width 0.14478)
		(layer "In2.Cu")
		(net "M_C_CPU0_SA_CB<1>")
	)
	(segment
		(start 325.66229 -245.47449)
		(end 324.249034 -245.47449)
		(width 0.0889)
		(layer "In2.Cu")
		(net "M_C_CPU0_SA_CB<1>")
	)
	(segment
		(start 339.698076 -245.61673)
		(end 339.689694 -245.621556)
		(width 0.0889)
		(layer "In2.Cu")
		(net "M_C_CPU0_SA_CB<1>")
	)
	(segment
		(start 304.303938 -236.47273)
		(end 304.07356 -236.47273)
		(width 0.14478)
		(layer "In2.Cu")
		(net "M_C_CPU0_SA_CB<1>")
	)
	(segment
		(start 326.165718 -245.616476)
		(end 326.139556 -245.60149)
		(width 0.0889)
		(layer "In2.Cu")
		(net "M_C_CPU0_SA_CB<1>")
	)
	(segment
		(start 337.452462 -245.621556)
		(end 337.44408 -245.61673)
		(width 0.0889)
		(layer "In2.Cu")
		(net "M_C_CPU0_SA_CB<1>")
	)
	(segment
		(start 331.238098 -245.61673)
		(end 331.229716 -245.621556)
		(width 0.0889)
		(layer "In2.Cu")
		(net "M_C_CPU0_SA_CB<1>")
	)
	(segment
		(start 306.433474 -235.62691)
		(end 306.270406 -235.789978)
		(width 0.14478)
		(layer "In2.Cu")
		(net "M_C_CPU0_SA_CB<1>")
	)
	(segment
		(start 327.480168 -245.616476)
		(end 327.458324 -245.628922)
		(width 0.0889)
		(layer "In2.Cu")
		(net "M_C_CPU0_SA_CB<1>")
	)
	(segment
		(start 298.7294 -235.847128)
		(end 298.566332 -236.010196)
		(width 0.14478)
		(layer "In2.Cu")
		(net "M_C_CPU0_SA_CB<1>")
	)
	(segment
		(start 306.270406 -235.847128)
		(end 306.107338 -236.010196)
		(width 0.14478)
		(layer "In2.Cu")
		(net "M_C_CPU0_SA_CB<1>")
	)
	(segment
		(start 304.630074 -236.86008)
		(end 304.467006 -236.697012)
		(width 0.14478)
		(layer "In2.Cu")
		(net "M_C_CPU0_SA_CB<1>")
	)
	(segment
		(start 318.247268 -244.69471)
		(end 314.937648 -241.38509)
		(width 0.14478)
		(layer "In2.Cu")
		(net "M_C_CPU0_SA_CB<1>")
	)
	(segment
		(start 328.992484 -245.621556)
		(end 328.984102 -245.61673)
		(width 0.0889)
		(layer "In2.Cu")
		(net "M_C_CPU0_SA_CB<1>")
	)
	(segment
		(start 343.425018 -245.55958)
		(end 343.402666 -245.642892)
		(width 0.0889)
		(layer "In2.Cu")
		(net "M_C_CPU0_SA_CB<1>")
	)
	(segment
		(start 305.740816 -236.010196)
		(end 304.890932 -236.86008)
		(width 0.14478)
		(layer "In2.Cu")
		(net "M_C_CPU0_SA_CB<1>")
	)
	(segment
		(start 299.448982 -236.010196)
		(end 299.285914 -235.847128)
		(width 0.14478)
		(layer "In2.Cu")
		(net "M_C_CPU0_SA_CB<1>")
	)
	(segment
		(start 328.41819 -245.61673)
		(end 328.409808 -245.621556)
		(width 0.0889)
		(layer "In2.Cu")
		(net "M_C_CPU0_SA_CB<1>")
	)
	(segment
		(start 333.6925 -245.621556)
		(end 333.684118 -245.61673)
		(width 0.0889)
		(layer "In2.Cu")
		(net "M_C_CPU0_SA_CB<1>")
	)
	(segment
		(start 299.285914 -235.782358)
		(end 299.122846 -235.61929)
		(width 0.14478)
		(layer "In2.Cu")
		(net "M_C_CPU0_SA_CB<1>")
	)
	(segment
		(start 324.090284 -245.31574)
		(end 323.469254 -244.69471)
		(width 0.14478)
		(layer "In2.Cu")
		(net "M_C_CPU0_SA_CB<1>")
	)
	(segment
		(start 299.285914 -235.847128)
		(end 299.285914 -235.782358)
		(width 0.14478)
		(layer "In2.Cu")
		(net "M_C_CPU0_SA_CB<1>")
	)
	(segment
		(start 296.14622 -236.86008)
		(end 295.287954 -236.86008)
		(width 0.14478)
		(layer "In2.Cu")
		(net "M_C_CPU0_SA_CB<1>")
	)
	(segment
		(start 293.455344 -236.697012)
		(end 293.292276 -236.86008)
		(width 0.14478)
		(layer "In2.Cu")
		(net "M_C_CPU0_SA_CB<1>")
	)
	(segment
		(start 340.63813 -245.61673)
		(end 340.629748 -245.621556)
		(width 0.0889)
		(layer "In2.Cu")
		(net "M_C_CPU0_SA_CB<1>")
	)
	(segment
		(start 304.07356 -236.47273)
		(end 303.910492 -236.635798)
		(width 0.14478)
		(layer "In2.Cu")
		(net "M_C_CPU0_SA_CB<1>")
	)
	(segment
		(start 308.472586 -236.010196)
		(end 306.989988 -236.010196)
		(width 0.14478)
		(layer "In2.Cu")
		(net "M_C_CPU0_SA_CB<1>")
	)
	(segment
		(start 302.294544 -236.630718)
		(end 302.294544 -236.697012)
		(width 0.14478)
		(layer "In2.Cu")
		(net "M_C_CPU0_SA_CB<1>")
	)
	(segment
		(start 302.851058 -236.630718)
		(end 302.68799 -236.46765)
		(width 0.14478)
		(layer "In2.Cu")
		(net "M_C_CPU0_SA_CB<1>")
	)
	(segment
		(start 341.212424 -245.621556)
		(end 341.204042 -245.61673)
		(width 0.0889)
		(layer "In2.Cu")
		(net "M_C_CPU0_SA_CB<1>")
	)
	(segment
		(start 302.131476 -236.86008)
		(end 301.892716 -236.86008)
		(width 0.14478)
		(layer "In2.Cu")
		(net "M_C_CPU0_SA_CB<1>")
	)
	(segment
		(start 303.910492 -236.635798)
		(end 303.910492 -236.697012)
		(width 0.14478)
		(layer "In2.Cu")
		(net "M_C_CPU0_SA_CB<1>")
	)
	(segment
		(start 306.663852 -235.62691)
		(end 306.433474 -235.62691)
		(width 0.14478)
		(layer "In2.Cu")
		(net "M_C_CPU0_SA_CB<1>")
	)
	(segment
		(start 293.84879 -236.48035)
		(end 293.618412 -236.48035)
		(width 0.14478)
		(layer "In2.Cu")
		(net "M_C_CPU0_SA_CB<1>")
	)
	(segment
		(start 295.287954 -236.86008)
		(end 295.124886 -236.697012)
		(width 0.14478)
		(layer "In2.Cu")
		(net "M_C_CPU0_SA_CB<1>")
	)
	(segment
		(start 306.107338 -236.010196)
		(end 305.740816 -236.010196)
		(width 0.14478)
		(layer "In2.Cu")
		(net "M_C_CPU0_SA_CB<1>")
	)
	(segment
		(start 313.314334 -241.38509)
		(end 309.839614 -237.91037)
		(width 0.14478)
		(layer "In2.Cu")
		(net "M_C_CPU0_SA_CB<1>")
	)
	(segment
		(start 324.249034 -245.47449)
		(end 324.090284 -245.31574)
		(width 0.0889)
		(layer "In2.Cu")
		(net "M_C_CPU0_SA_CB<1>")
	)
	(segment
		(start 294.73144 -236.48035)
		(end 294.568372 -236.643418)
		(width 0.14478)
		(layer "In2.Cu")
		(net "M_C_CPU0_SA_CB<1>")
	)
	(segment
		(start 299.122846 -235.61929)
		(end 298.892468 -235.61929)
		(width 0.14478)
		(layer "In2.Cu")
		(net "M_C_CPU0_SA_CB<1>")
	)
	(segment
		(start 304.467006 -236.635798)
		(end 304.303938 -236.47273)
		(width 0.14478)
		(layer "In2.Cu")
		(net "M_C_CPU0_SA_CB<1>")
	)
	(segment
		(start 303.747424 -236.86008)
		(end 303.014126 -236.86008)
		(width 0.14478)
		(layer "In2.Cu")
		(net "M_C_CPU0_SA_CB<1>")
	)
	(segment
		(start 343.271094 -245.29415)
		(end 343.425018 -245.55958)
		(width 0.0889)
		(layer "In2.Cu")
		(net "M_C_CPU0_SA_CB<1>")
	)
	(segment
		(start 332.178152 -245.61673)
		(end 332.16977 -245.621556)
		(width 0.0889)
		(layer "In2.Cu")
		(net "M_C_CPU0_SA_CB<1>")
	)
	(arc
		(start 343.08415 -245.61673)
		(mid 342.801194 -245.540553)
		(end 342.518238 -245.61673)
		(width 0.0889)
		(layer "In2.Cu")
		(net "M_C_CPU0_SA_CB<1>")
	)
	(arc
		(start 330.863956 -245.61673)
		(mid 330.581 -245.540553)
		(end 330.298044 -245.61673)
		(width 0.0889)
		(layer "In2.Cu")
		(net "M_C_CPU0_SA_CB<1>")
	)
	(arc
		(start 332.16977 -245.621556)
		(mid 331.986262 -245.66705)
		(end 331.80401 -245.61673)
		(width 0.0889)
		(layer "In2.Cu")
		(net "M_C_CPU0_SA_CB<1>")
	)
	(arc
		(start 337.44408 -245.61673)
		(mid 337.161124 -245.540553)
		(end 336.878168 -245.61673)
		(width 0.0889)
		(layer "In2.Cu")
		(net "M_C_CPU0_SA_CB<1>")
	)
	(arc
		(start 331.80401 -245.61673)
		(mid 331.521054 -245.540553)
		(end 331.238098 -245.61673)
		(width 0.0889)
		(layer "In2.Cu")
		(net "M_C_CPU0_SA_CB<1>")
	)
	(arc
		(start 334.99806 -245.61673)
		(mid 334.811116 -245.666985)
		(end 334.624172 -245.61673)
		(width 0.0889)
		(layer "In2.Cu")
		(net "M_C_CPU0_SA_CB<1>")
	)
	(arc
		(start 338.384134 -245.61673)
		(mid 338.101178 -245.540553)
		(end 337.818222 -245.61673)
		(width 0.0889)
		(layer "In2.Cu")
		(net "M_C_CPU0_SA_CB<1>")
	)
	(arc
		(start 333.118206 -245.61673)
		(mid 332.935955 -245.66708)
		(end 332.752446 -245.621556)
		(width 0.0889)
		(layer "In2.Cu")
		(net "M_C_CPU0_SA_CB<1>")
	)
	(arc
		(start 329.358244 -245.61673)
		(mid 329.175993 -245.66708)
		(end 328.992484 -245.621556)
		(width 0.0889)
		(layer "In2.Cu")
		(net "M_C_CPU0_SA_CB<1>")
	)
	(arc
		(start 339.689694 -245.621556)
		(mid 339.506186 -245.66705)
		(end 339.323934 -245.61673)
		(width 0.0889)
		(layer "In2.Cu")
		(net "M_C_CPU0_SA_CB<1>")
	)
	(arc
		(start 337.818222 -245.61673)
		(mid 337.635971 -245.66708)
		(end 337.452462 -245.621556)
		(width 0.0889)
		(layer "In2.Cu")
		(net "M_C_CPU0_SA_CB<1>")
	)
	(arc
		(start 342.144096 -245.61673)
		(mid 341.86114 -245.540553)
		(end 341.578184 -245.61673)
		(width 0.0889)
		(layer "In2.Cu")
		(net "M_C_CPU0_SA_CB<1>")
	)
	(arc
		(start 329.924156 -245.61673)
		(mid 329.6412 -245.540553)
		(end 329.358244 -245.61673)
		(width 0.0889)
		(layer "In2.Cu")
		(net "M_C_CPU0_SA_CB<1>")
	)
	(arc
		(start 328.984102 -245.61673)
		(mid 328.701146 -245.540553)
		(end 328.41819 -245.61673)
		(width 0.0889)
		(layer "In2.Cu")
		(net "M_C_CPU0_SA_CB<1>")
	)
	(arc
		(start 326.539606 -245.61673)
		(mid 326.370419 -245.667138)
		(end 326.19696 -245.634256)
		(width 0.0889)
		(layer "In2.Cu")
		(net "M_C_CPU0_SA_CB<1>")
	)
	(arc
		(start 327.078086 -245.599458)
		(mid 326.806666 -245.539781)
		(end 326.539606 -245.61673)
		(width 0.0889)
		(layer "In2.Cu")
		(net "M_C_CPU0_SA_CB<1>")
	)
	(arc
		(start 336.869786 -245.621556)
		(mid 336.686278 -245.66705)
		(end 336.504026 -245.61673)
		(width 0.0889)
		(layer "In2.Cu")
		(net "M_C_CPU0_SA_CB<1>")
	)
	(arc
		(start 335.929732 -245.621556)
		(mid 335.746224 -245.66705)
		(end 335.563972 -245.61673)
		(width 0.0889)
		(layer "In2.Cu")
		(net "M_C_CPU0_SA_CB<1>")
	)
	(arc
		(start 341.578184 -245.61673)
		(mid 341.395933 -245.66708)
		(end 341.212424 -245.621556)
		(width 0.0889)
		(layer "In2.Cu")
		(net "M_C_CPU0_SA_CB<1>")
	)
	(arc
		(start 331.229716 -245.621556)
		(mid 331.046208 -245.66705)
		(end 330.863956 -245.61673)
		(width 0.0889)
		(layer "In2.Cu")
		(net "M_C_CPU0_SA_CB<1>")
	)
	(arc
		(start 335.563972 -245.61673)
		(mid 335.281016 -245.540553)
		(end 334.99806 -245.61673)
		(width 0.0889)
		(layer "In2.Cu")
		(net "M_C_CPU0_SA_CB<1>")
	)
	(arc
		(start 333.684118 -245.61673)
		(mid 333.401162 -245.540553)
		(end 333.118206 -245.61673)
		(width 0.0889)
		(layer "In2.Cu")
		(net "M_C_CPU0_SA_CB<1>")
	)
	(arc
		(start 332.744064 -245.61673)
		(mid 332.461108 -245.540553)
		(end 332.178152 -245.61673)
		(width 0.0889)
		(layer "In2.Cu")
		(net "M_C_CPU0_SA_CB<1>")
	)
	(arc
		(start 328.044048 -245.61673)
		(mid 327.777118 -245.540781)
		(end 327.50633 -245.60149)
		(width 0.0889)
		(layer "In2.Cu")
		(net "M_C_CPU0_SA_CB<1>")
	)
	(arc
		(start 334.624172 -245.61673)
		(mid 334.341216 -245.540553)
		(end 334.05826 -245.61673)
		(width 0.0889)
		(layer "In2.Cu")
		(net "M_C_CPU0_SA_CB<1>")
	)
	(arc
		(start 342.518238 -245.61673)
		(mid 342.335987 -245.66708)
		(end 342.152478 -245.621556)
		(width 0.0889)
		(layer "In2.Cu")
		(net "M_C_CPU0_SA_CB<1>")
	)
	(arc
		(start 340.629748 -245.621556)
		(mid 340.44624 -245.66705)
		(end 340.263988 -245.61673)
		(width 0.0889)
		(layer "In2.Cu")
		(net "M_C_CPU0_SA_CB<1>")
	)
	(arc
		(start 340.263988 -245.61673)
		(mid 339.981032 -245.540553)
		(end 339.698076 -245.61673)
		(width 0.0889)
		(layer "In2.Cu")
		(net "M_C_CPU0_SA_CB<1>")
	)
	(arc
		(start 326.139556 -245.60149)
		(mid 325.90923 -245.506767)
		(end 325.66229 -245.47449)
		(width 0.0889)
		(layer "In2.Cu")
		(net "M_C_CPU0_SA_CB<1>")
	)
	(arc
		(start 328.409808 -245.621556)
		(mid 328.2263 -245.66705)
		(end 328.044048 -245.61673)
		(width 0.0889)
		(layer "In2.Cu")
		(net "M_C_CPU0_SA_CB<1>")
	)
	(arc
		(start 334.05826 -245.61673)
		(mid 333.876009 -245.66708)
		(end 333.6925 -245.621556)
		(width 0.0889)
		(layer "In2.Cu")
		(net "M_C_CPU0_SA_CB<1>")
	)
	(arc
		(start 339.323934 -245.61673)
		(mid 339.040978 -245.540553)
		(end 338.758022 -245.61673)
		(width 0.0889)
		(layer "In2.Cu")
		(net "M_C_CPU0_SA_CB<1>")
	)
	(arc
		(start 341.204042 -245.61673)
		(mid 340.921086 -245.540553)
		(end 340.63813 -245.61673)
		(width 0.0889)
		(layer "In2.Cu")
		(net "M_C_CPU0_SA_CB<1>")
	)
	(arc
		(start 327.458324 -245.628922)
		(mid 327.281396 -245.66675)
		(end 327.10755 -245.61673)
		(width 0.0889)
		(layer "In2.Cu")
		(net "M_C_CPU0_SA_CB<1>")
	)
	(arc
		(start 343.402666 -245.642892)
		(mid 343.240477 -245.665627)
		(end 343.08415 -245.61673)
		(width 0.0889)
		(layer "In2.Cu")
		(net "M_C_CPU0_SA_CB<1>")
	)
	(arc
		(start 336.504026 -245.61673)
		(mid 336.22107 -245.540553)
		(end 335.938114 -245.61673)
		(width 0.0889)
		(layer "In2.Cu")
		(net "M_C_CPU0_SA_CB<1>")
	)
	(arc
		(start 330.298044 -245.61673)
		(mid 330.1111 -245.666985)
		(end 329.924156 -245.61673)
		(width 0.0889)
		(layer "In2.Cu")
		(net "M_C_CPU0_SA_CB<1>")
	)
	(arc
		(start 338.758022 -245.61673)
		(mid 338.571078 -245.666985)
		(end 338.384134 -245.61673)
		(width 0.0889)
		(layer "In2.Cu")
		(net "M_C_CPU0_SA_CB<1>")
	)
	(segment
		(start 342.327992 -244.750082)
		(end 341.86114 -244.484144)
		(width 0.10668)
		(layer "F.Cu")
		(net "M_C_CPU0_SA_CB<0>")
	)
	(segment
		(start 293.981124 -235.043218)
		(end 293.818056 -234.88015)
		(width 0.14478)
		(layer "In2.Cu")
		(net "M_C_CPU0_SA_CB<0>")
	)
	(segment
		(start 311.529222 -237.995206)
		(end 311.29859 -237.995206)
		(width 0.14478)
		(layer "In2.Cu")
		(net "M_C_CPU0_SA_CB<0>")
	)
	(segment
		(start 294.537638 -235.374942)
		(end 294.37457 -235.53801)
		(width 0.14478)
		(layer "In2.Cu")
		(net "M_C_CPU0_SA_CB<0>")
	)
	(segment
		(start 338.862416 -244.81155)
		(end 338.854034 -244.806724)
		(width 0.0889)
		(layer "In2.Cu")
		(net "M_C_CPU0_SA_CB<0>")
	)
	(segment
		(start 293.818056 -234.88015)
		(end 293.587678 -234.88015)
		(width 0.14478)
		(layer "In2.Cu")
		(net "M_C_CPU0_SA_CB<0>")
	)
	(segment
		(start 303.784 -235.160058)
		(end 302.899572 -235.160058)
		(width 0.14478)
		(layer "In2.Cu")
		(net "M_C_CPU0_SA_CB<0>")
	)
	(segment
		(start 324.985634 -244.37213)
		(end 324.421754 -244.37213)
		(width 0.0889)
		(layer "In2.Cu")
		(net "M_C_CPU0_SA_CB<0>")
	)
	(segment
		(start 339.80247 -244.81155)
		(end 339.794088 -244.806724)
		(width 0.0889)
		(layer "In2.Cu")
		(net "M_C_CPU0_SA_CB<0>")
	)
	(segment
		(start 294.37457 -235.53801)
		(end 294.144192 -235.53801)
		(width 0.14478)
		(layer "In2.Cu")
		(net "M_C_CPU0_SA_CB<0>")
	)
	(segment
		(start 325.901812 -244.851428)
		(end 325.464932 -244.851428)
		(width 0.0889)
		(layer "In2.Cu")
		(net "M_C_CPU0_SA_CB<0>")
	)
	(segment
		(start 312.47334 -238.625888)
		(end 312.316622 -238.782606)
		(width 0.14478)
		(layer "In2.Cu")
		(net "M_C_CPU0_SA_CB<0>")
	)
	(segment
		(start 313.497722 -239.963706)
		(end 313.65444 -239.806988)
		(width 0.14478)
		(layer "In2.Cu")
		(net "M_C_CPU0_SA_CB<0>")
	)
	(segment
		(start 341.86114 -244.484144)
		(end 342.015064 -244.749574)
		(width 0.0889)
		(layer "In2.Cu")
		(net "M_C_CPU0_SA_CB<0>")
	)
	(segment
		(start 304.065686 -234.878372)
		(end 303.784 -235.160058)
		(width 0.14478)
		(layer "In2.Cu")
		(net "M_C_CPU0_SA_CB<0>")
	)
	(segment
		(start 333.588106 -244.806724)
		(end 333.579724 -244.81155)
		(width 0.0889)
		(layer "In2.Cu")
		(net "M_C_CPU0_SA_CB<0>")
	)
	(segment
		(start 302.899572 -235.160058)
		(end 302.643286 -234.903772)
		(width 0.14478)
		(layer "In2.Cu")
		(net "M_C_CPU0_SA_CB<0>")
	)
	(segment
		(start 323.829934 -243.78031)
		(end 318.635634 -243.78031)
		(width 0.14478)
		(layer "In2.Cu")
		(net "M_C_CPU0_SA_CB<0>")
	)
	(segment
		(start 312.08599 -238.782606)
		(end 311.922922 -238.619538)
		(width 0.14478)
		(layer "In2.Cu")
		(net "M_C_CPU0_SA_CB<0>")
	)
	(segment
		(start 318.635634 -243.78031)
		(end 315.285374 -240.43005)
		(width 0.14478)
		(layer "In2.Cu")
		(net "M_C_CPU0_SA_CB<0>")
	)
	(segment
		(start 312.07964 -238.232188)
		(end 312.07964 -238.001556)
		(width 0.14478)
		(layer "In2.Cu")
		(net "M_C_CPU0_SA_CB<0>")
	)
	(segment
		(start 297.367452 -235.160058)
		(end 297.210988 -235.160058)
		(width 0.14478)
		(layer "In2.Cu")
		(net "M_C_CPU0_SA_CB<0>")
	)
	(segment
		(start 342.015064 -244.749574)
		(end 341.992712 -244.832886)
		(width 0.0889)
		(layer "In2.Cu")
		(net "M_C_CPU0_SA_CB<0>")
	)
	(segment
		(start 338.288122 -244.806724)
		(end 338.27974 -244.81155)
		(width 0.0889)
		(layer "In2.Cu")
		(net "M_C_CPU0_SA_CB<0>")
	)
	(segment
		(start 293.42461 -235.043218)
		(end 293.42461 -235.374942)
		(width 0.14478)
		(layer "In2.Cu")
		(net "M_C_CPU0_SA_CB<0>")
	)
	(segment
		(start 294.537638 -235.323126)
		(end 294.537638 -235.374942)
		(width 0.14478)
		(layer "In2.Cu")
		(net "M_C_CPU0_SA_CB<0>")
	)
	(segment
		(start 304.335434 -234.878372)
		(end 304.065686 -234.878372)
		(width 0.14478)
		(layer "In2.Cu")
		(net "M_C_CPU0_SA_CB<0>")
	)
	(segment
		(start 329.828144 -244.806724)
		(end 329.819762 -244.81155)
		(width 0.0889)
		(layer "In2.Cu")
		(net "M_C_CPU0_SA_CB<0>")
	)
	(segment
		(start 312.86704 -239.019588)
		(end 312.86704 -238.788956)
		(width 0.14478)
		(layer "In2.Cu")
		(net "M_C_CPU0_SA_CB<0>")
	)
	(segment
		(start 296.94632 -234.89539)
		(end 296.654474 -234.89539)
		(width 0.14478)
		(layer "In2.Cu")
		(net "M_C_CPU0_SA_CB<0>")
	)
	(segment
		(start 301.892716 -235.160058)
		(end 301.042832 -234.310174)
		(width 0.14478)
		(layer "In2.Cu")
		(net "M_C_CPU0_SA_CB<0>")
	)
	(segment
		(start 325.464932 -244.851428)
		(end 324.985634 -244.37213)
		(width 0.0889)
		(layer "In2.Cu")
		(net "M_C_CPU0_SA_CB<0>")
	)
	(segment
		(start 335.102454 -244.81155)
		(end 335.094072 -244.806724)
		(width 0.0889)
		(layer "In2.Cu")
		(net "M_C_CPU0_SA_CB<0>")
	)
	(segment
		(start 313.733434 -240.43005)
		(end 313.497722 -240.194338)
		(width 0.14478)
		(layer "In2.Cu")
		(net "M_C_CPU0_SA_CB<0>")
	)
	(segment
		(start 312.316622 -238.782606)
		(end 312.08599 -238.782606)
		(width 0.14478)
		(layer "In2.Cu")
		(net "M_C_CPU0_SA_CB<0>")
	)
	(segment
		(start 294.700706 -235.160058)
		(end 294.537638 -235.323126)
		(width 0.14478)
		(layer "In2.Cu")
		(net "M_C_CPU0_SA_CB<0>")
	)
	(segment
		(start 331.342492 -244.81155)
		(end 331.33411 -244.806724)
		(width 0.0889)
		(layer "In2.Cu")
		(net "M_C_CPU0_SA_CB<0>")
	)
	(segment
		(start 310.839104 -237.53572)
		(end 310.839104 -236.909864)
		(width 0.14478)
		(layer "In2.Cu")
		(net "M_C_CPU0_SA_CB<0>")
	)
	(segment
		(start 312.703972 -238.625888)
		(end 312.47334 -238.625888)
		(width 0.14478)
		(layer "In2.Cu")
		(net "M_C_CPU0_SA_CB<0>")
	)
	(segment
		(start 311.922922 -238.619538)
		(end 311.922922 -238.388906)
		(width 0.14478)
		(layer "In2.Cu")
		(net "M_C_CPU0_SA_CB<0>")
	)
	(segment
		(start 299.22216 -234.310174)
		(end 298.957238 -234.045252)
		(width 0.14478)
		(layer "In2.Cu")
		(net "M_C_CPU0_SA_CB<0>")
	)
	(segment
		(start 312.710322 -239.406938)
		(end 312.710322 -239.176306)
		(width 0.14478)
		(layer "In2.Cu")
		(net "M_C_CPU0_SA_CB<0>")
	)
	(segment
		(start 305.740816 -234.310174)
		(end 304.890932 -235.160058)
		(width 0.14478)
		(layer "In2.Cu")
		(net "M_C_CPU0_SA_CB<0>")
	)
	(segment
		(start 311.29859 -237.995206)
		(end 310.839104 -237.53572)
		(width 0.14478)
		(layer "In2.Cu")
		(net "M_C_CPU0_SA_CB<0>")
	)
	(segment
		(start 311.916572 -237.838488)
		(end 311.68594 -237.838488)
		(width 0.14478)
		(layer "In2.Cu")
		(net "M_C_CPU0_SA_CB<0>")
	)
	(segment
		(start 336.042508 -244.81155)
		(end 336.034126 -244.806724)
		(width 0.0889)
		(layer "In2.Cu")
		(net "M_C_CPU0_SA_CB<0>")
	)
	(segment
		(start 312.07964 -238.001556)
		(end 311.916572 -237.838488)
		(width 0.14478)
		(layer "In2.Cu")
		(net "M_C_CPU0_SA_CB<0>")
	)
	(segment
		(start 292.868096 -235.323126)
		(end 292.280086 -234.735116)
		(width 0.14478)
		(layer "In2.Cu")
		(net "M_C_CPU0_SA_CB<0>")
	)
	(segment
		(start 302.643286 -234.903772)
		(end 302.348138 -234.903772)
		(width 0.14478)
		(layer "In2.Cu")
		(net "M_C_CPU0_SA_CB<0>")
	)
	(segment
		(start 297.210988 -235.160058)
		(end 296.94632 -234.89539)
		(width 0.14478)
		(layer "In2.Cu")
		(net "M_C_CPU0_SA_CB<0>")
	)
	(segment
		(start 298.217336 -234.310174)
		(end 297.367452 -235.160058)
		(width 0.14478)
		(layer "In2.Cu")
		(net "M_C_CPU0_SA_CB<0>")
	)
	(segment
		(start 313.104022 -239.570006)
		(end 312.87339 -239.570006)
		(width 0.14478)
		(layer "In2.Cu")
		(net "M_C_CPU0_SA_CB<0>")
	)
	(segment
		(start 313.497722 -240.194338)
		(end 313.497722 -239.963706)
		(width 0.14478)
		(layer "In2.Cu")
		(net "M_C_CPU0_SA_CB<0>")
	)
	(segment
		(start 302.348138 -234.903772)
		(end 302.091852 -235.160058)
		(width 0.14478)
		(layer "In2.Cu")
		(net "M_C_CPU0_SA_CB<0>")
	)
	(segment
		(start 296.389806 -235.160058)
		(end 294.700706 -235.160058)
		(width 0.14478)
		(layer "In2.Cu")
		(net "M_C_CPU0_SA_CB<0>")
	)
	(segment
		(start 301.042832 -234.310174)
		(end 299.22216 -234.310174)
		(width 0.14478)
		(layer "In2.Cu")
		(net "M_C_CPU0_SA_CB<0>")
	)
	(segment
		(start 307.028342 -234.310174)
		(end 306.734718 -234.01655)
		(width 0.14478)
		(layer "In2.Cu")
		(net "M_C_CPU0_SA_CB<0>")
	)
	(segment
		(start 330.402438 -244.81155)
		(end 330.394056 -244.806724)
		(width 0.0889)
		(layer "In2.Cu")
		(net "M_C_CPU0_SA_CB<0>")
	)
	(segment
		(start 313.65444 -239.806988)
		(end 313.65444 -239.576356)
		(width 0.14478)
		(layer "In2.Cu")
		(net "M_C_CPU0_SA_CB<0>")
	)
	(segment
		(start 298.957238 -234.045252)
		(end 298.670726 -234.045252)
		(width 0.14478)
		(layer "In2.Cu")
		(net "M_C_CPU0_SA_CB<0>")
	)
	(segment
		(start 304.890932 -235.160058)
		(end 304.61712 -235.160058)
		(width 0.14478)
		(layer "In2.Cu")
		(net "M_C_CPU0_SA_CB<0>")
	)
	(segment
		(start 312.86704 -238.788956)
		(end 312.703972 -238.625888)
		(width 0.14478)
		(layer "In2.Cu")
		(net "M_C_CPU0_SA_CB<0>")
	)
	(segment
		(start 298.670726 -234.045252)
		(end 298.405804 -234.310174)
		(width 0.14478)
		(layer "In2.Cu")
		(net "M_C_CPU0_SA_CB<0>")
	)
	(segment
		(start 312.710322 -239.176306)
		(end 312.86704 -239.019588)
		(width 0.14478)
		(layer "In2.Cu")
		(net "M_C_CPU0_SA_CB<0>")
	)
	(segment
		(start 293.587678 -234.88015)
		(end 293.42461 -235.043218)
		(width 0.14478)
		(layer "In2.Cu")
		(net "M_C_CPU0_SA_CB<0>")
	)
	(segment
		(start 311.68594 -237.838488)
		(end 311.529222 -237.995206)
		(width 0.14478)
		(layer "In2.Cu")
		(net "M_C_CPU0_SA_CB<0>")
	)
	(segment
		(start 293.981124 -235.374942)
		(end 293.981124 -235.043218)
		(width 0.14478)
		(layer "In2.Cu")
		(net "M_C_CPU0_SA_CB<0>")
	)
	(segment
		(start 306.178204 -234.310174)
		(end 305.740816 -234.310174)
		(width 0.14478)
		(layer "In2.Cu")
		(net "M_C_CPU0_SA_CB<0>")
	)
	(segment
		(start 298.405804 -234.310174)
		(end 298.217336 -234.310174)
		(width 0.14478)
		(layer "In2.Cu")
		(net "M_C_CPU0_SA_CB<0>")
	)
	(segment
		(start 313.26074 -239.413288)
		(end 313.104022 -239.570006)
		(width 0.14478)
		(layer "In2.Cu")
		(net "M_C_CPU0_SA_CB<0>")
	)
	(segment
		(start 292.868096 -235.374942)
		(end 292.868096 -235.323126)
		(width 0.14478)
		(layer "In2.Cu")
		(net "M_C_CPU0_SA_CB<0>")
	)
	(segment
		(start 293.031164 -235.53801)
		(end 292.868096 -235.374942)
		(width 0.14478)
		(layer "In2.Cu")
		(net "M_C_CPU0_SA_CB<0>")
	)
	(segment
		(start 312.87339 -239.570006)
		(end 312.710322 -239.406938)
		(width 0.14478)
		(layer "In2.Cu")
		(net "M_C_CPU0_SA_CB<0>")
	)
	(segment
		(start 313.491372 -239.413288)
		(end 313.26074 -239.413288)
		(width 0.14478)
		(layer "In2.Cu")
		(net "M_C_CPU0_SA_CB<0>")
	)
	(segment
		(start 296.654474 -234.89539)
		(end 296.389806 -235.160058)
		(width 0.14478)
		(layer "In2.Cu")
		(net "M_C_CPU0_SA_CB<0>")
	)
	(segment
		(start 308.239414 -234.310174)
		(end 307.028342 -234.310174)
		(width 0.14478)
		(layer "In2.Cu")
		(net "M_C_CPU0_SA_CB<0>")
	)
	(segment
		(start 293.261542 -235.53801)
		(end 293.031164 -235.53801)
		(width 0.14478)
		(layer "In2.Cu")
		(net "M_C_CPU0_SA_CB<0>")
	)
	(segment
		(start 310.839104 -236.909864)
		(end 308.239414 -234.310174)
		(width 0.14478)
		(layer "In2.Cu")
		(net "M_C_CPU0_SA_CB<0>")
	)
	(segment
		(start 306.471828 -234.01655)
		(end 306.178204 -234.310174)
		(width 0.14478)
		(layer "In2.Cu")
		(net "M_C_CPU0_SA_CB<0>")
	)
	(segment
		(start 326.647302 -244.814344)
		(end 326.633586 -244.80647)
		(width 0.0889)
		(layer "In2.Cu")
		(net "M_C_CPU0_SA_CB<0>")
	)
	(segment
		(start 293.42461 -235.374942)
		(end 293.261542 -235.53801)
		(width 0.14478)
		(layer "In2.Cu")
		(net "M_C_CPU0_SA_CB<0>")
	)
	(segment
		(start 306.734718 -234.01655)
		(end 306.471828 -234.01655)
		(width 0.14478)
		(layer "In2.Cu")
		(net "M_C_CPU0_SA_CB<0>")
	)
	(segment
		(start 327.021952 -244.798088)
		(end 327.00722 -244.806724)
		(width 0.0889)
		(layer "In2.Cu")
		(net "M_C_CPU0_SA_CB<0>")
	)
	(segment
		(start 311.922922 -238.388906)
		(end 312.07964 -238.232188)
		(width 0.14478)
		(layer "In2.Cu")
		(net "M_C_CPU0_SA_CB<0>")
	)
	(segment
		(start 313.65444 -239.576356)
		(end 313.491372 -239.413288)
		(width 0.14478)
		(layer "In2.Cu")
		(net "M_C_CPU0_SA_CB<0>")
	)
	(segment
		(start 327.94829 -244.806724)
		(end 327.939908 -244.81155)
		(width 0.0889)
		(layer "In2.Cu")
		(net "M_C_CPU0_SA_CB<0>")
	)
	(segment
		(start 334.52816 -244.806724)
		(end 334.519778 -244.81155)
		(width 0.0889)
		(layer "In2.Cu")
		(net "M_C_CPU0_SA_CB<0>")
	)
	(segment
		(start 294.144192 -235.53801)
		(end 293.981124 -235.374942)
		(width 0.14478)
		(layer "In2.Cu")
		(net "M_C_CPU0_SA_CB<0>")
	)
	(segment
		(start 302.091852 -235.160058)
		(end 301.892716 -235.160058)
		(width 0.14478)
		(layer "In2.Cu")
		(net "M_C_CPU0_SA_CB<0>")
	)
	(segment
		(start 324.421754 -244.37213)
		(end 323.829934 -243.78031)
		(width 0.0889)
		(layer "In2.Cu")
		(net "M_C_CPU0_SA_CB<0>")
	)
	(segment
		(start 304.61712 -235.160058)
		(end 304.335434 -234.878372)
		(width 0.14478)
		(layer "In2.Cu")
		(net "M_C_CPU0_SA_CB<0>")
	)
	(segment
		(start 326.633586 -244.80647)
		(end 326.617838 -244.797326)
		(width 0.0889)
		(layer "In2.Cu")
		(net "M_C_CPU0_SA_CB<0>")
	)
	(segment
		(start 315.285374 -240.43005)
		(end 313.733434 -240.43005)
		(width 0.14478)
		(layer "In2.Cu")
		(net "M_C_CPU0_SA_CB<0>")
	)
	(arc
		(start 329.454002 -244.806724)
		(mid 329.171046 -244.730547)
		(end 328.88809 -244.806724)
		(width 0.0889)
		(layer "In2.Cu")
		(net "M_C_CPU0_SA_CB<0>")
	)
	(arc
		(start 329.819762 -244.81155)
		(mid 329.636254 -244.857044)
		(end 329.454002 -244.806724)
		(width 0.0889)
		(layer "In2.Cu")
		(net "M_C_CPU0_SA_CB<0>")
	)
	(arc
		(start 331.33411 -244.806724)
		(mid 331.051154 -244.730547)
		(end 330.768198 -244.806724)
		(width 0.0889)
		(layer "In2.Cu")
		(net "M_C_CPU0_SA_CB<0>")
	)
	(arc
		(start 339.228176 -244.806724)
		(mid 339.045925 -244.857074)
		(end 338.862416 -244.81155)
		(width 0.0889)
		(layer "In2.Cu")
		(net "M_C_CPU0_SA_CB<0>")
	)
	(arc
		(start 334.519778 -244.81155)
		(mid 334.33627 -244.857044)
		(end 334.154018 -244.806724)
		(width 0.0889)
		(layer "In2.Cu")
		(net "M_C_CPU0_SA_CB<0>")
	)
	(arc
		(start 330.394056 -244.806724)
		(mid 330.1111 -244.730547)
		(end 329.828144 -244.806724)
		(width 0.0889)
		(layer "In2.Cu")
		(net "M_C_CPU0_SA_CB<0>")
	)
	(arc
		(start 333.213964 -244.806724)
		(mid 332.931008 -244.730547)
		(end 332.648052 -244.806724)
		(width 0.0889)
		(layer "In2.Cu")
		(net "M_C_CPU0_SA_CB<0>")
	)
	(arc
		(start 340.16823 -244.806724)
		(mid 339.985979 -244.857074)
		(end 339.80247 -244.81155)
		(width 0.0889)
		(layer "In2.Cu")
		(net "M_C_CPU0_SA_CB<0>")
	)
	(arc
		(start 327.57364 -244.806724)
		(mid 327.298934 -244.73036)
		(end 327.021952 -244.798088)
		(width 0.0889)
		(layer "In2.Cu")
		(net "M_C_CPU0_SA_CB<0>")
	)
	(arc
		(start 335.094072 -244.806724)
		(mid 334.811116 -244.730547)
		(end 334.52816 -244.806724)
		(width 0.0889)
		(layer "In2.Cu")
		(net "M_C_CPU0_SA_CB<0>")
	)
	(arc
		(start 331.708252 -244.806724)
		(mid 331.526001 -244.857074)
		(end 331.342492 -244.81155)
		(width 0.0889)
		(layer "In2.Cu")
		(net "M_C_CPU0_SA_CB<0>")
	)
	(arc
		(start 340.734142 -244.806724)
		(mid 340.451186 -244.730547)
		(end 340.16823 -244.806724)
		(width 0.0889)
		(layer "In2.Cu")
		(net "M_C_CPU0_SA_CB<0>")
	)
	(arc
		(start 332.648052 -244.806724)
		(mid 332.461108 -244.856979)
		(end 332.274164 -244.806724)
		(width 0.0889)
		(layer "In2.Cu")
		(net "M_C_CPU0_SA_CB<0>")
	)
	(arc
		(start 328.514202 -244.806724)
		(mid 328.231246 -244.730547)
		(end 327.94829 -244.806724)
		(width 0.0889)
		(layer "In2.Cu")
		(net "M_C_CPU0_SA_CB<0>")
	)
	(arc
		(start 330.768198 -244.806724)
		(mid 330.585947 -244.857074)
		(end 330.402438 -244.81155)
		(width 0.0889)
		(layer "In2.Cu")
		(net "M_C_CPU0_SA_CB<0>")
	)
	(arc
		(start 326.617838 -244.797326)
		(mid 326.341529 -244.73035)
		(end 326.067674 -244.806724)
		(width 0.0889)
		(layer "In2.Cu")
		(net "M_C_CPU0_SA_CB<0>")
	)
	(arc
		(start 341.10803 -244.806724)
		(mid 340.921086 -244.856979)
		(end 340.734142 -244.806724)
		(width 0.0889)
		(layer "In2.Cu")
		(net "M_C_CPU0_SA_CB<0>")
	)
	(arc
		(start 334.154018 -244.806724)
		(mid 333.871062 -244.730547)
		(end 333.588106 -244.806724)
		(width 0.0889)
		(layer "In2.Cu")
		(net "M_C_CPU0_SA_CB<0>")
	)
	(arc
		(start 335.468214 -244.806724)
		(mid 335.285963 -244.857074)
		(end 335.102454 -244.81155)
		(width 0.0889)
		(layer "In2.Cu")
		(net "M_C_CPU0_SA_CB<0>")
	)
	(arc
		(start 326.067674 -244.806724)
		(mid 325.987709 -244.840091)
		(end 325.901812 -244.851428)
		(width 0.0889)
		(layer "In2.Cu")
		(net "M_C_CPU0_SA_CB<0>")
	)
	(arc
		(start 338.27974 -244.81155)
		(mid 338.096232 -244.857044)
		(end 337.91398 -244.806724)
		(width 0.0889)
		(layer "In2.Cu")
		(net "M_C_CPU0_SA_CB<0>")
	)
	(arc
		(start 327.00722 -244.806724)
		(mid 326.828233 -244.856894)
		(end 326.647302 -244.814344)
		(width 0.0889)
		(layer "In2.Cu")
		(net "M_C_CPU0_SA_CB<0>")
	)
	(arc
		(start 338.854034 -244.806724)
		(mid 338.571078 -244.730547)
		(end 338.288122 -244.806724)
		(width 0.0889)
		(layer "In2.Cu")
		(net "M_C_CPU0_SA_CB<0>")
	)
	(arc
		(start 336.408268 -244.806724)
		(mid 336.226017 -244.857074)
		(end 336.042508 -244.81155)
		(width 0.0889)
		(layer "In2.Cu")
		(net "M_C_CPU0_SA_CB<0>")
	)
	(arc
		(start 336.034126 -244.806724)
		(mid 335.75117 -244.730547)
		(end 335.468214 -244.806724)
		(width 0.0889)
		(layer "In2.Cu")
		(net "M_C_CPU0_SA_CB<0>")
	)
	(arc
		(start 332.274164 -244.806724)
		(mid 331.991208 -244.730547)
		(end 331.708252 -244.806724)
		(width 0.0889)
		(layer "In2.Cu")
		(net "M_C_CPU0_SA_CB<0>")
	)
	(arc
		(start 327.939908 -244.81155)
		(mid 327.756146 -244.857166)
		(end 327.57364 -244.806724)
		(width 0.0889)
		(layer "In2.Cu")
		(net "M_C_CPU0_SA_CB<0>")
	)
	(arc
		(start 333.579724 -244.81155)
		(mid 333.396216 -244.857044)
		(end 333.213964 -244.806724)
		(width 0.0889)
		(layer "In2.Cu")
		(net "M_C_CPU0_SA_CB<0>")
	)
	(arc
		(start 328.88809 -244.806724)
		(mid 328.701146 -244.856979)
		(end 328.514202 -244.806724)
		(width 0.0889)
		(layer "In2.Cu")
		(net "M_C_CPU0_SA_CB<0>")
	)
	(arc
		(start 336.97418 -244.806724)
		(mid 336.691224 -244.730547)
		(end 336.408268 -244.806724)
		(width 0.0889)
		(layer "In2.Cu")
		(net "M_C_CPU0_SA_CB<0>")
	)
	(arc
		(start 337.348068 -244.806724)
		(mid 337.161124 -244.856979)
		(end 336.97418 -244.806724)
		(width 0.0889)
		(layer "In2.Cu")
		(net "M_C_CPU0_SA_CB<0>")
	)
	(arc
		(start 341.992712 -244.832886)
		(mid 341.83038 -244.855704)
		(end 341.673942 -244.806724)
		(width 0.0889)
		(layer "In2.Cu")
		(net "M_C_CPU0_SA_CB<0>")
	)
	(arc
		(start 339.794088 -244.806724)
		(mid 339.511132 -244.730547)
		(end 339.228176 -244.806724)
		(width 0.0889)
		(layer "In2.Cu")
		(net "M_C_CPU0_SA_CB<0>")
	)
	(arc
		(start 341.673942 -244.806724)
		(mid 341.390986 -244.730547)
		(end 341.10803 -244.806724)
		(width 0.0889)
		(layer "In2.Cu")
		(net "M_C_CPU0_SA_CB<0>")
	)
	(arc
		(start 337.91398 -244.806724)
		(mid 337.631024 -244.730547)
		(end 337.348068 -244.806724)
		(width 0.0889)
		(layer "In2.Cu")
		(net "M_C_CPU0_SA_CB<0>")
	)
	(segment
		(start 343.737946 -255.28016)
		(end 343.271094 -255.014222)
		(width 0.10668)
		(layer "F.Cu")
		(net "M_C_CPU0_SA_CA<6>")
	)
	(segment
		(start 296.728896 -254.710184)
		(end 294.405304 -254.710184)
		(width 0.14478)
		(layer "In2.Cu")
		(net "M_C_CPU0_SA_CA<6>")
	)
	(segment
		(start 301.414434 -254.32385)
		(end 301.251366 -254.486918)
		(width 0.14478)
		(layer "In2.Cu")
		(net "M_C_CPU0_SA_CA<6>")
	)
	(segment
		(start 326.165718 -255.336548)
		(end 326.139556 -255.321562)
		(width 0.0889)
		(layer "In2.Cu")
		(net "M_C_CPU0_SA_CA<6>")
	)
	(segment
		(start 301.644812 -254.32385)
		(end 301.414434 -254.32385)
		(width 0.14478)
		(layer "In2.Cu")
		(net "M_C_CPU0_SA_CA<6>")
	)
	(segment
		(start 340.63813 -255.336802)
		(end 340.629748 -255.341628)
		(width 0.0889)
		(layer "In2.Cu")
		(net "M_C_CPU0_SA_CA<6>")
	)
	(segment
		(start 301.80788 -254.547116)
		(end 301.80788 -254.486918)
		(width 0.14478)
		(layer "In2.Cu")
		(net "M_C_CPU0_SA_CA<6>")
	)
	(segment
		(start 297.841924 -254.710184)
		(end 297.611546 -254.710184)
		(width 0.14478)
		(layer "In2.Cu")
		(net "M_C_CPU0_SA_CA<6>")
	)
	(segment
		(start 304.779426 -254.547116)
		(end 304.616358 -254.710184)
		(width 0.14478)
		(layer "In2.Cu")
		(net "M_C_CPU0_SA_CA<6>")
	)
	(segment
		(start 297.611546 -254.710184)
		(end 297.448478 -254.547116)
		(width 0.14478)
		(layer "In2.Cu")
		(net "M_C_CPU0_SA_CA<6>")
	)
	(segment
		(start 308.24805 -255.116076)
		(end 307.842158 -254.710184)
		(width 0.14478)
		(layer "In2.Cu")
		(net "M_C_CPU0_SA_CA<6>")
	)
	(segment
		(start 331.238098 -255.336802)
		(end 331.229716 -255.341628)
		(width 0.0889)
		(layer "In2.Cu")
		(net "M_C_CPU0_SA_CA<6>")
	)
	(segment
		(start 296.891964 -254.479298)
		(end 296.891964 -254.547116)
		(width 0.14478)
		(layer "In2.Cu")
		(net "M_C_CPU0_SA_CA<6>")
	)
	(segment
		(start 307.842158 -254.710184)
		(end 305.499008 -254.710184)
		(width 0.14478)
		(layer "In2.Cu")
		(net "M_C_CPU0_SA_CA<6>")
	)
	(segment
		(start 343.425018 -255.279652)
		(end 343.402666 -255.362964)
		(width 0.0889)
		(layer "In2.Cu")
		(net "M_C_CPU0_SA_CA<6>")
	)
	(segment
		(start 323.901054 -255.92151)
		(end 320.852292 -255.92151)
		(width 0.14478)
		(layer "In2.Cu")
		(net "M_C_CPU0_SA_CA<6>")
	)
	(segment
		(start 341.212424 -255.341628)
		(end 341.204042 -255.336802)
		(width 0.0889)
		(layer "In2.Cu")
		(net "M_C_CPU0_SA_CA<6>")
	)
	(segment
		(start 298.561506 -254.479298)
		(end 298.398438 -254.31623)
		(width 0.14478)
		(layer "In2.Cu")
		(net "M_C_CPU0_SA_CA<6>")
	)
	(segment
		(start 316.490858 -254.48641)
		(end 314.970414 -255.116076)
		(width 0.14478)
		(layer "In2.Cu")
		(net "M_C_CPU0_SA_CA<6>")
	)
	(segment
		(start 297.055032 -254.31623)
		(end 296.891964 -254.479298)
		(width 0.14478)
		(layer "In2.Cu")
		(net "M_C_CPU0_SA_CA<6>")
	)
	(segment
		(start 297.448478 -254.547116)
		(end 297.448478 -254.479298)
		(width 0.14478)
		(layer "In2.Cu")
		(net "M_C_CPU0_SA_CA<6>")
	)
	(segment
		(start 319.417192 -254.48641)
		(end 316.490858 -254.48641)
		(width 0.14478)
		(layer "In2.Cu")
		(net "M_C_CPU0_SA_CA<6>")
	)
	(segment
		(start 301.970948 -254.710184)
		(end 301.80788 -254.547116)
		(width 0.14478)
		(layer "In2.Cu")
		(net "M_C_CPU0_SA_CA<6>")
	)
	(segment
		(start 298.724574 -254.710184)
		(end 298.561506 -254.547116)
		(width 0.14478)
		(layer "In2.Cu")
		(net "M_C_CPU0_SA_CA<6>")
	)
	(segment
		(start 332.752446 -255.341628)
		(end 332.744064 -255.336802)
		(width 0.0889)
		(layer "In2.Cu")
		(net "M_C_CPU0_SA_CA<6>")
	)
	(segment
		(start 326.19696 -255.354328)
		(end 326.165718 -255.336548)
		(width 0.0889)
		(layer "In2.Cu")
		(net "M_C_CPU0_SA_CA<6>")
	)
	(segment
		(start 298.398438 -254.31623)
		(end 298.16806 -254.31623)
		(width 0.14478)
		(layer "In2.Cu")
		(net "M_C_CPU0_SA_CA<6>")
	)
	(segment
		(start 304.616358 -254.710184)
		(end 301.970948 -254.710184)
		(width 0.14478)
		(layer "In2.Cu")
		(net "M_C_CPU0_SA_CA<6>")
	)
	(segment
		(start 297.448478 -254.479298)
		(end 297.28541 -254.31623)
		(width 0.14478)
		(layer "In2.Cu")
		(net "M_C_CPU0_SA_CA<6>")
	)
	(segment
		(start 305.172872 -254.31623)
		(end 304.942494 -254.31623)
		(width 0.14478)
		(layer "In2.Cu")
		(net "M_C_CPU0_SA_CA<6>")
	)
	(segment
		(start 301.251366 -254.486918)
		(end 301.251366 -254.547116)
		(width 0.14478)
		(layer "In2.Cu")
		(net "M_C_CPU0_SA_CA<6>")
	)
	(segment
		(start 294.405304 -254.710184)
		(end 292.280086 -252.584966)
		(width 0.14478)
		(layer "In2.Cu")
		(net "M_C_CPU0_SA_CA<6>")
	)
	(segment
		(start 342.152478 -255.341628)
		(end 342.144096 -255.336802)
		(width 0.0889)
		(layer "In2.Cu")
		(net "M_C_CPU0_SA_CA<6>")
	)
	(segment
		(start 327.480168 -255.336548)
		(end 327.458324 -255.348994)
		(width 0.0889)
		(layer "In2.Cu")
		(net "M_C_CPU0_SA_CA<6>")
	)
	(segment
		(start 305.33594 -254.547116)
		(end 305.33594 -254.479298)
		(width 0.14478)
		(layer "In2.Cu")
		(net "M_C_CPU0_SA_CA<6>")
	)
	(segment
		(start 301.80788 -254.486918)
		(end 301.644812 -254.32385)
		(width 0.14478)
		(layer "In2.Cu")
		(net "M_C_CPU0_SA_CA<6>")
	)
	(segment
		(start 301.088298 -254.710184)
		(end 298.724574 -254.710184)
		(width 0.14478)
		(layer "In2.Cu")
		(net "M_C_CPU0_SA_CA<6>")
	)
	(segment
		(start 343.271094 -255.014222)
		(end 343.425018 -255.279652)
		(width 0.0889)
		(layer "In2.Cu")
		(net "M_C_CPU0_SA_CA<6>")
	)
	(segment
		(start 327.10755 -255.336802)
		(end 327.078086 -255.31953)
		(width 0.0889)
		(layer "In2.Cu")
		(net "M_C_CPU0_SA_CA<6>")
	)
	(segment
		(start 314.970414 -255.116076)
		(end 308.24805 -255.116076)
		(width 0.14478)
		(layer "In2.Cu")
		(net "M_C_CPU0_SA_CA<6>")
	)
	(segment
		(start 324.614794 -255.62941)
		(end 324.322694 -255.92151)
		(width 0.0889)
		(layer "In2.Cu")
		(net "M_C_CPU0_SA_CA<6>")
	)
	(segment
		(start 325.601838 -255.336802)
		(end 325.515478 -255.38684)
		(width 0.0889)
		(layer "In2.Cu")
		(net "M_C_CPU0_SA_CA<6>")
	)
	(segment
		(start 304.942494 -254.31623)
		(end 304.779426 -254.479298)
		(width 0.14478)
		(layer "In2.Cu")
		(net "M_C_CPU0_SA_CA<6>")
	)
	(segment
		(start 333.6925 -255.341628)
		(end 333.684118 -255.336802)
		(width 0.0889)
		(layer "In2.Cu")
		(net "M_C_CPU0_SA_CA<6>")
	)
	(segment
		(start 301.251366 -254.547116)
		(end 301.088298 -254.710184)
		(width 0.14478)
		(layer "In2.Cu")
		(net "M_C_CPU0_SA_CA<6>")
	)
	(segment
		(start 296.891964 -254.547116)
		(end 296.728896 -254.710184)
		(width 0.14478)
		(layer "In2.Cu")
		(net "M_C_CPU0_SA_CA<6>")
	)
	(segment
		(start 298.561506 -254.547116)
		(end 298.561506 -254.479298)
		(width 0.14478)
		(layer "In2.Cu")
		(net "M_C_CPU0_SA_CA<6>")
	)
	(segment
		(start 332.178152 -255.336802)
		(end 332.16977 -255.341628)
		(width 0.0889)
		(layer "In2.Cu")
		(net "M_C_CPU0_SA_CA<6>")
	)
	(segment
		(start 297.28541 -254.31623)
		(end 297.055032 -254.31623)
		(width 0.14478)
		(layer "In2.Cu")
		(net "M_C_CPU0_SA_CA<6>")
	)
	(segment
		(start 337.452462 -255.341628)
		(end 337.44408 -255.336802)
		(width 0.0889)
		(layer "In2.Cu")
		(net "M_C_CPU0_SA_CA<6>")
	)
	(segment
		(start 328.992484 -255.341628)
		(end 328.984102 -255.336802)
		(width 0.0889)
		(layer "In2.Cu")
		(net "M_C_CPU0_SA_CA<6>")
	)
	(segment
		(start 339.698076 -255.336802)
		(end 339.689694 -255.341628)
		(width 0.0889)
		(layer "In2.Cu")
		(net "M_C_CPU0_SA_CA<6>")
	)
	(segment
		(start 324.322694 -255.92151)
		(end 323.901054 -255.92151)
		(width 0.0889)
		(layer "In2.Cu")
		(net "M_C_CPU0_SA_CA<6>")
	)
	(segment
		(start 327.50633 -255.321562)
		(end 327.480168 -255.336548)
		(width 0.0889)
		(layer "In2.Cu")
		(net "M_C_CPU0_SA_CA<6>")
	)
	(segment
		(start 298.16806 -254.31623)
		(end 298.004992 -254.479298)
		(width 0.14478)
		(layer "In2.Cu")
		(net "M_C_CPU0_SA_CA<6>")
	)
	(segment
		(start 328.41819 -255.336802)
		(end 328.409808 -255.341628)
		(width 0.0889)
		(layer "In2.Cu")
		(net "M_C_CPU0_SA_CA<6>")
	)
	(segment
		(start 320.852292 -255.92151)
		(end 319.417192 -254.48641)
		(width 0.14478)
		(layer "In2.Cu")
		(net "M_C_CPU0_SA_CA<6>")
	)
	(segment
		(start 298.004992 -254.547116)
		(end 297.841924 -254.710184)
		(width 0.14478)
		(layer "In2.Cu")
		(net "M_C_CPU0_SA_CA<6>")
	)
	(segment
		(start 305.33594 -254.479298)
		(end 305.172872 -254.31623)
		(width 0.14478)
		(layer "In2.Cu")
		(net "M_C_CPU0_SA_CA<6>")
	)
	(segment
		(start 305.499008 -254.710184)
		(end 305.33594 -254.547116)
		(width 0.14478)
		(layer "In2.Cu")
		(net "M_C_CPU0_SA_CA<6>")
	)
	(segment
		(start 298.004992 -254.479298)
		(end 298.004992 -254.547116)
		(width 0.14478)
		(layer "In2.Cu")
		(net "M_C_CPU0_SA_CA<6>")
	)
	(segment
		(start 335.938114 -255.336802)
		(end 335.929732 -255.341628)
		(width 0.0889)
		(layer "In2.Cu")
		(net "M_C_CPU0_SA_CA<6>")
	)
	(segment
		(start 304.779426 -254.479298)
		(end 304.779426 -254.547116)
		(width 0.14478)
		(layer "In2.Cu")
		(net "M_C_CPU0_SA_CA<6>")
	)
	(segment
		(start 336.878168 -255.336802)
		(end 336.869786 -255.341628)
		(width 0.0889)
		(layer "In2.Cu")
		(net "M_C_CPU0_SA_CA<6>")
	)
	(arc
		(start 339.323934 -255.336802)
		(mid 339.040978 -255.260625)
		(end 338.758022 -255.336802)
		(width 0.0889)
		(layer "In2.Cu")
		(net "M_C_CPU0_SA_CA<6>")
	)
	(arc
		(start 334.05826 -255.336802)
		(mid 333.876009 -255.387152)
		(end 333.6925 -255.341628)
		(width 0.0889)
		(layer "In2.Cu")
		(net "M_C_CPU0_SA_CA<6>")
	)
	(arc
		(start 327.458324 -255.348994)
		(mid 327.281396 -255.386822)
		(end 327.10755 -255.336802)
		(width 0.0889)
		(layer "In2.Cu")
		(net "M_C_CPU0_SA_CA<6>")
	)
	(arc
		(start 330.298044 -255.336802)
		(mid 330.1111 -255.387057)
		(end 329.924156 -255.336802)
		(width 0.0889)
		(layer "In2.Cu")
		(net "M_C_CPU0_SA_CA<6>")
	)
	(arc
		(start 334.624172 -255.336802)
		(mid 334.341216 -255.260625)
		(end 334.05826 -255.336802)
		(width 0.0889)
		(layer "In2.Cu")
		(net "M_C_CPU0_SA_CA<6>")
	)
	(arc
		(start 328.044048 -255.336802)
		(mid 327.777118 -255.260853)
		(end 327.50633 -255.321562)
		(width 0.0889)
		(layer "In2.Cu")
		(net "M_C_CPU0_SA_CA<6>")
	)
	(arc
		(start 328.409808 -255.341628)
		(mid 328.2263 -255.387122)
		(end 328.044048 -255.336802)
		(width 0.0889)
		(layer "In2.Cu")
		(net "M_C_CPU0_SA_CA<6>")
	)
	(arc
		(start 326.539606 -255.336802)
		(mid 326.370419 -255.38721)
		(end 326.19696 -255.354328)
		(width 0.0889)
		(layer "In2.Cu")
		(net "M_C_CPU0_SA_CA<6>")
	)
	(arc
		(start 330.863956 -255.336802)
		(mid 330.581 -255.260625)
		(end 330.298044 -255.336802)
		(width 0.0889)
		(layer "In2.Cu")
		(net "M_C_CPU0_SA_CA<6>")
	)
	(arc
		(start 340.263988 -255.336802)
		(mid 339.981032 -255.260625)
		(end 339.698076 -255.336802)
		(width 0.0889)
		(layer "In2.Cu")
		(net "M_C_CPU0_SA_CA<6>")
	)
	(arc
		(start 325.515478 -255.38684)
		(mid 325.08118 -255.567712)
		(end 324.614794 -255.62941)
		(width 0.0889)
		(layer "In2.Cu")
		(net "M_C_CPU0_SA_CA<6>")
	)
	(arc
		(start 329.358244 -255.336802)
		(mid 329.175993 -255.387152)
		(end 328.992484 -255.341628)
		(width 0.0889)
		(layer "In2.Cu")
		(net "M_C_CPU0_SA_CA<6>")
	)
	(arc
		(start 331.80401 -255.336802)
		(mid 331.521054 -255.260625)
		(end 331.238098 -255.336802)
		(width 0.0889)
		(layer "In2.Cu")
		(net "M_C_CPU0_SA_CA<6>")
	)
	(arc
		(start 339.689694 -255.341628)
		(mid 339.506186 -255.387122)
		(end 339.323934 -255.336802)
		(width 0.0889)
		(layer "In2.Cu")
		(net "M_C_CPU0_SA_CA<6>")
	)
	(arc
		(start 337.818222 -255.336802)
		(mid 337.635971 -255.387152)
		(end 337.452462 -255.341628)
		(width 0.0889)
		(layer "In2.Cu")
		(net "M_C_CPU0_SA_CA<6>")
	)
	(arc
		(start 337.44408 -255.336802)
		(mid 337.161124 -255.260625)
		(end 336.878168 -255.336802)
		(width 0.0889)
		(layer "In2.Cu")
		(net "M_C_CPU0_SA_CA<6>")
	)
	(arc
		(start 342.144096 -255.336802)
		(mid 341.86114 -255.260625)
		(end 341.578184 -255.336802)
		(width 0.0889)
		(layer "In2.Cu")
		(net "M_C_CPU0_SA_CA<6>")
	)
	(arc
		(start 334.99806 -255.336802)
		(mid 334.811116 -255.387057)
		(end 334.624172 -255.336802)
		(width 0.0889)
		(layer "In2.Cu")
		(net "M_C_CPU0_SA_CA<6>")
	)
	(arc
		(start 341.578184 -255.336802)
		(mid 341.395933 -255.387152)
		(end 341.212424 -255.341628)
		(width 0.0889)
		(layer "In2.Cu")
		(net "M_C_CPU0_SA_CA<6>")
	)
	(arc
		(start 328.984102 -255.336802)
		(mid 328.701146 -255.260625)
		(end 328.41819 -255.336802)
		(width 0.0889)
		(layer "In2.Cu")
		(net "M_C_CPU0_SA_CA<6>")
	)
	(arc
		(start 335.563972 -255.336802)
		(mid 335.281016 -255.260625)
		(end 334.99806 -255.336802)
		(width 0.0889)
		(layer "In2.Cu")
		(net "M_C_CPU0_SA_CA<6>")
	)
	(arc
		(start 326.139556 -255.321562)
		(mid 325.86877 -255.260916)
		(end 325.601838 -255.336802)
		(width 0.0889)
		(layer "In2.Cu")
		(net "M_C_CPU0_SA_CA<6>")
	)
	(arc
		(start 335.929732 -255.341628)
		(mid 335.746224 -255.387122)
		(end 335.563972 -255.336802)
		(width 0.0889)
		(layer "In2.Cu")
		(net "M_C_CPU0_SA_CA<6>")
	)
	(arc
		(start 336.869786 -255.341628)
		(mid 336.686278 -255.387122)
		(end 336.504026 -255.336802)
		(width 0.0889)
		(layer "In2.Cu")
		(net "M_C_CPU0_SA_CA<6>")
	)
	(arc
		(start 336.504026 -255.336802)
		(mid 336.22107 -255.260625)
		(end 335.938114 -255.336802)
		(width 0.0889)
		(layer "In2.Cu")
		(net "M_C_CPU0_SA_CA<6>")
	)
	(arc
		(start 333.684118 -255.336802)
		(mid 333.401162 -255.260625)
		(end 333.118206 -255.336802)
		(width 0.0889)
		(layer "In2.Cu")
		(net "M_C_CPU0_SA_CA<6>")
	)
	(arc
		(start 332.744064 -255.336802)
		(mid 332.461108 -255.260625)
		(end 332.178152 -255.336802)
		(width 0.0889)
		(layer "In2.Cu")
		(net "M_C_CPU0_SA_CA<6>")
	)
	(arc
		(start 340.629748 -255.341628)
		(mid 340.44624 -255.387122)
		(end 340.263988 -255.336802)
		(width 0.0889)
		(layer "In2.Cu")
		(net "M_C_CPU0_SA_CA<6>")
	)
	(arc
		(start 332.16977 -255.341628)
		(mid 331.986262 -255.387122)
		(end 331.80401 -255.336802)
		(width 0.0889)
		(layer "In2.Cu")
		(net "M_C_CPU0_SA_CA<6>")
	)
	(arc
		(start 343.402666 -255.362964)
		(mid 343.240477 -255.385699)
		(end 343.08415 -255.336802)
		(width 0.0889)
		(layer "In2.Cu")
		(net "M_C_CPU0_SA_CA<6>")
	)
	(arc
		(start 342.518238 -255.336802)
		(mid 342.335987 -255.387152)
		(end 342.152478 -255.341628)
		(width 0.0889)
		(layer "In2.Cu")
		(net "M_C_CPU0_SA_CA<6>")
	)
	(arc
		(start 329.924156 -255.336802)
		(mid 329.6412 -255.260625)
		(end 329.358244 -255.336802)
		(width 0.0889)
		(layer "In2.Cu")
		(net "M_C_CPU0_SA_CA<6>")
	)
	(arc
		(start 331.229716 -255.341628)
		(mid 331.046208 -255.387122)
		(end 330.863956 -255.336802)
		(width 0.0889)
		(layer "In2.Cu")
		(net "M_C_CPU0_SA_CA<6>")
	)
	(arc
		(start 341.204042 -255.336802)
		(mid 340.921086 -255.260625)
		(end 340.63813 -255.336802)
		(width 0.0889)
		(layer "In2.Cu")
		(net "M_C_CPU0_SA_CA<6>")
	)
	(arc
		(start 333.118206 -255.336802)
		(mid 332.935955 -255.387152)
		(end 332.752446 -255.341628)
		(width 0.0889)
		(layer "In2.Cu")
		(net "M_C_CPU0_SA_CA<6>")
	)
	(arc
		(start 343.08415 -255.336802)
		(mid 342.801194 -255.260625)
		(end 342.518238 -255.336802)
		(width 0.0889)
		(layer "In2.Cu")
		(net "M_C_CPU0_SA_CA<6>")
	)
	(arc
		(start 327.078086 -255.31953)
		(mid 326.806666 -255.259853)
		(end 326.539606 -255.336802)
		(width 0.0889)
		(layer "In2.Cu")
		(net "M_C_CPU0_SA_CA<6>")
	)
	(arc
		(start 338.384134 -255.336802)
		(mid 338.101178 -255.260625)
		(end 337.818222 -255.336802)
		(width 0.0889)
		(layer "In2.Cu")
		(net "M_C_CPU0_SA_CA<6>")
	)
	(arc
		(start 338.758022 -255.336802)
		(mid 338.571078 -255.387057)
		(end 338.384134 -255.336802)
		(width 0.0889)
		(layer "In2.Cu")
		(net "M_C_CPU0_SA_CA<6>")
	)
	(segment
		(start 342.797892 -255.28016)
		(end 342.33104 -255.014222)
		(width 0.10668)
		(layer "F.Cu")
		(net "M_C_CPU0_SA_CA<5>")
	)
	(segment
		(start 337.452462 -254.686816)
		(end 337.44408 -254.691642)
		(width 0.0889)
		(layer "In2.Cu")
		(net "M_C_CPU0_SA_CA<5>")
	)
	(segment
		(start 328.044048 -254.691642)
		(end 328.029316 -254.700278)
		(width 0.0889)
		(layer "In2.Cu")
		(net "M_C_CPU0_SA_CA<5>")
	)
	(segment
		(start 323.873114 -255.44653)
		(end 321.02044 -255.44653)
		(width 0.14478)
		(layer "In2.Cu")
		(net "M_C_CPU0_SA_CA<5>")
	)
	(segment
		(start 324.160134 -255.44653)
		(end 323.873114 -255.44653)
		(width 0.0889)
		(layer "In2.Cu")
		(net "M_C_CPU0_SA_CA<5>")
	)
	(segment
		(start 324.843394 -255.13411)
		(end 324.472554 -255.13411)
		(width 0.0889)
		(layer "In2.Cu")
		(net "M_C_CPU0_SA_CA<5>")
	)
	(segment
		(start 314.880752 -254.666496)
		(end 309.24246 -254.666496)
		(width 0.14478)
		(layer "In2.Cu")
		(net "M_C_CPU0_SA_CA<5>")
	)
	(segment
		(start 339.698076 -254.691642)
		(end 339.689694 -254.686816)
		(width 0.0889)
		(layer "In2.Cu")
		(net "M_C_CPU0_SA_CA<5>")
	)
	(segment
		(start 326.537828 -254.691896)
		(end 326.51954 -254.681482)
		(width 0.0889)
		(layer "In2.Cu")
		(net "M_C_CPU0_SA_CA<5>")
	)
	(segment
		(start 327.114916 -254.684784)
		(end 327.103232 -254.691642)
		(width 0.0889)
		(layer "In2.Cu")
		(net "M_C_CPU0_SA_CA<5>")
	)
	(segment
		(start 309.24246 -254.666496)
		(end 308.43601 -253.860046)
		(width 0.14478)
		(layer "In2.Cu")
		(net "M_C_CPU0_SA_CA<5>")
	)
	(segment
		(start 288.60496 -252.160024)
		(end 288.180018 -251.735082)
		(width 0.14478)
		(layer "In2.Cu")
		(net "M_C_CPU0_SA_CA<5>")
	)
	(segment
		(start 324.472554 -255.13411)
		(end 324.160134 -255.44653)
		(width 0.0889)
		(layer "In2.Cu")
		(net "M_C_CPU0_SA_CA<5>")
	)
	(segment
		(start 328.41819 -254.691642)
		(end 328.409808 -254.686816)
		(width 0.0889)
		(layer "In2.Cu")
		(net "M_C_CPU0_SA_CA<5>")
	)
	(segment
		(start 308.43601 -253.860046)
		(end 294.85463 -253.860046)
		(width 0.14478)
		(layer "In2.Cu")
		(net "M_C_CPU0_SA_CA<5>")
	)
	(segment
		(start 332.752446 -254.686816)
		(end 332.744064 -254.691642)
		(width 0.0889)
		(layer "In2.Cu")
		(net "M_C_CPU0_SA_CA<5>")
	)
	(segment
		(start 332.178152 -254.691642)
		(end 332.16977 -254.686816)
		(width 0.0889)
		(layer "In2.Cu")
		(net "M_C_CPU0_SA_CA<5>")
	)
	(segment
		(start 342.33104 -255.014222)
		(end 342.177116 -254.748792)
		(width 0.0889)
		(layer "In2.Cu")
		(net "M_C_CPU0_SA_CA<5>")
	)
	(segment
		(start 331.238098 -254.691642)
		(end 331.229716 -254.686816)
		(width 0.0889)
		(layer "In2.Cu")
		(net "M_C_CPU0_SA_CA<5>")
	)
	(segment
		(start 340.63813 -254.691642)
		(end 340.629748 -254.686816)
		(width 0.0889)
		(layer "In2.Cu")
		(net "M_C_CPU0_SA_CA<5>")
	)
	(segment
		(start 321.02044 -255.44653)
		(end 319.60566 -254.03175)
		(width 0.14478)
		(layer "In2.Cu")
		(net "M_C_CPU0_SA_CA<5>")
	)
	(segment
		(start 341.212424 -254.686816)
		(end 341.204042 -254.691642)
		(width 0.0889)
		(layer "In2.Cu")
		(net "M_C_CPU0_SA_CA<5>")
	)
	(segment
		(start 319.60566 -254.03175)
		(end 316.413388 -254.03175)
		(width 0.14478)
		(layer "In2.Cu")
		(net "M_C_CPU0_SA_CA<5>")
	)
	(segment
		(start 336.878168 -254.691642)
		(end 336.869786 -254.686816)
		(width 0.0889)
		(layer "In2.Cu")
		(net "M_C_CPU0_SA_CA<5>")
	)
	(segment
		(start 293.154608 -252.160024)
		(end 288.60496 -252.160024)
		(width 0.14478)
		(layer "In2.Cu")
		(net "M_C_CPU0_SA_CA<5>")
	)
	(segment
		(start 326.543416 -254.695198)
		(end 326.537828 -254.691896)
		(width 0.0889)
		(layer "In2.Cu")
		(net "M_C_CPU0_SA_CA<5>")
	)
	(segment
		(start 335.938114 -254.691642)
		(end 335.929732 -254.686816)
		(width 0.0889)
		(layer "In2.Cu")
		(net "M_C_CPU0_SA_CA<5>")
	)
	(segment
		(start 328.992484 -254.686816)
		(end 328.984102 -254.691642)
		(width 0.0889)
		(layer "In2.Cu")
		(net "M_C_CPU0_SA_CA<5>")
	)
	(segment
		(start 326.163686 -254.691642)
		(end 325.883524 -254.854202)
		(width 0.0889)
		(layer "In2.Cu")
		(net "M_C_CPU0_SA_CA<5>")
	)
	(segment
		(start 294.85463 -253.860046)
		(end 293.154608 -252.160024)
		(width 0.14478)
		(layer "In2.Cu")
		(net "M_C_CPU0_SA_CA<5>")
	)
	(segment
		(start 316.413388 -254.03175)
		(end 314.880752 -254.666496)
		(width 0.14478)
		(layer "In2.Cu")
		(net "M_C_CPU0_SA_CA<5>")
	)
	(segment
		(start 333.6925 -254.686816)
		(end 333.684118 -254.691642)
		(width 0.0889)
		(layer "In2.Cu")
		(net "M_C_CPU0_SA_CA<5>")
	)
	(segment
		(start 342.177116 -254.748792)
		(end 342.081104 -254.723392)
		(width 0.0889)
		(layer "In2.Cu")
		(net "M_C_CPU0_SA_CA<5>")
	)
	(arc
		(start 341.204042 -254.691642)
		(mid 340.921086 -254.767819)
		(end 340.63813 -254.691642)
		(width 0.0889)
		(layer "In2.Cu")
		(net "M_C_CPU0_SA_CA<5>")
	)
	(arc
		(start 337.44408 -254.691642)
		(mid 337.161124 -254.767819)
		(end 336.878168 -254.691642)
		(width 0.0889)
		(layer "In2.Cu")
		(net "M_C_CPU0_SA_CA<5>")
	)
	(arc
		(start 327.477628 -254.691642)
		(mid 327.29717 -254.641198)
		(end 327.114916 -254.684784)
		(width 0.0889)
		(layer "In2.Cu")
		(net "M_C_CPU0_SA_CA<5>")
	)
	(arc
		(start 328.409808 -254.686816)
		(mid 328.2263 -254.641322)
		(end 328.044048 -254.691642)
		(width 0.0889)
		(layer "In2.Cu")
		(net "M_C_CPU0_SA_CA<5>")
	)
	(arc
		(start 337.818222 -254.691642)
		(mid 337.635971 -254.641292)
		(end 337.452462 -254.686816)
		(width 0.0889)
		(layer "In2.Cu")
		(net "M_C_CPU0_SA_CA<5>")
	)
	(arc
		(start 333.118206 -254.691642)
		(mid 332.935955 -254.641292)
		(end 332.752446 -254.686816)
		(width 0.0889)
		(layer "In2.Cu")
		(net "M_C_CPU0_SA_CA<5>")
	)
	(arc
		(start 341.578184 -254.691642)
		(mid 341.395933 -254.641292)
		(end 341.212424 -254.686816)
		(width 0.0889)
		(layer "In2.Cu")
		(net "M_C_CPU0_SA_CA<5>")
	)
	(arc
		(start 331.229716 -254.686816)
		(mid 331.046208 -254.641322)
		(end 330.863956 -254.691642)
		(width 0.0889)
		(layer "In2.Cu")
		(net "M_C_CPU0_SA_CA<5>")
	)
	(arc
		(start 328.029316 -254.700278)
		(mid 327.752333 -254.768082)
		(end 327.477628 -254.691642)
		(width 0.0889)
		(layer "In2.Cu")
		(net "M_C_CPU0_SA_CA<5>")
	)
	(arc
		(start 335.563972 -254.691642)
		(mid 335.281016 -254.767819)
		(end 334.99806 -254.691642)
		(width 0.0889)
		(layer "In2.Cu")
		(net "M_C_CPU0_SA_CA<5>")
	)
	(arc
		(start 332.16977 -254.686816)
		(mid 331.986262 -254.641322)
		(end 331.80401 -254.691642)
		(width 0.0889)
		(layer "In2.Cu")
		(net "M_C_CPU0_SA_CA<5>")
	)
	(arc
		(start 325.883524 -254.854202)
		(mid 325.381963 -255.062921)
		(end 324.843394 -255.13411)
		(width 0.0889)
		(layer "In2.Cu")
		(net "M_C_CPU0_SA_CA<5>")
	)
	(arc
		(start 334.05826 -254.691642)
		(mid 333.876009 -254.641292)
		(end 333.6925 -254.686816)
		(width 0.0889)
		(layer "In2.Cu")
		(net "M_C_CPU0_SA_CA<5>")
	)
	(arc
		(start 336.869786 -254.686816)
		(mid 336.686278 -254.641322)
		(end 336.504026 -254.691642)
		(width 0.0889)
		(layer "In2.Cu")
		(net "M_C_CPU0_SA_CA<5>")
	)
	(arc
		(start 338.384134 -254.691642)
		(mid 338.101178 -254.767819)
		(end 337.818222 -254.691642)
		(width 0.0889)
		(layer "In2.Cu")
		(net "M_C_CPU0_SA_CA<5>")
	)
	(arc
		(start 331.80401 -254.691642)
		(mid 331.521054 -254.767819)
		(end 331.238098 -254.691642)
		(width 0.0889)
		(layer "In2.Cu")
		(net "M_C_CPU0_SA_CA<5>")
	)
	(arc
		(start 340.263988 -254.691642)
		(mid 339.981032 -254.767819)
		(end 339.698076 -254.691642)
		(width 0.0889)
		(layer "In2.Cu")
		(net "M_C_CPU0_SA_CA<5>")
	)
	(arc
		(start 333.684118 -254.691642)
		(mid 333.401162 -254.767819)
		(end 333.118206 -254.691642)
		(width 0.0889)
		(layer "In2.Cu")
		(net "M_C_CPU0_SA_CA<5>")
	)
	(arc
		(start 329.924156 -254.691642)
		(mid 329.6412 -254.767819)
		(end 329.358244 -254.691642)
		(width 0.0889)
		(layer "In2.Cu")
		(net "M_C_CPU0_SA_CA<5>")
	)
	(arc
		(start 339.323934 -254.691642)
		(mid 339.040978 -254.767819)
		(end 338.758022 -254.691642)
		(width 0.0889)
		(layer "In2.Cu")
		(net "M_C_CPU0_SA_CA<5>")
	)
	(arc
		(start 326.51954 -254.681482)
		(mid 326.340311 -254.641329)
		(end 326.163686 -254.691642)
		(width 0.0889)
		(layer "In2.Cu")
		(net "M_C_CPU0_SA_CA<5>")
	)
	(arc
		(start 330.298044 -254.691642)
		(mid 330.1111 -254.641387)
		(end 329.924156 -254.691642)
		(width 0.0889)
		(layer "In2.Cu")
		(net "M_C_CPU0_SA_CA<5>")
	)
	(arc
		(start 329.358244 -254.691642)
		(mid 329.175993 -254.641292)
		(end 328.992484 -254.686816)
		(width 0.0889)
		(layer "In2.Cu")
		(net "M_C_CPU0_SA_CA<5>")
	)
	(arc
		(start 328.984102 -254.691642)
		(mid 328.701146 -254.767819)
		(end 328.41819 -254.691642)
		(width 0.0889)
		(layer "In2.Cu")
		(net "M_C_CPU0_SA_CA<5>")
	)
	(arc
		(start 340.629748 -254.686816)
		(mid 340.44624 -254.641322)
		(end 340.263988 -254.691642)
		(width 0.0889)
		(layer "In2.Cu")
		(net "M_C_CPU0_SA_CA<5>")
	)
	(arc
		(start 332.744064 -254.691642)
		(mid 332.461108 -254.767819)
		(end 332.178152 -254.691642)
		(width 0.0889)
		(layer "In2.Cu")
		(net "M_C_CPU0_SA_CA<5>")
	)
	(arc
		(start 338.758022 -254.691642)
		(mid 338.571078 -254.641387)
		(end 338.384134 -254.691642)
		(width 0.0889)
		(layer "In2.Cu")
		(net "M_C_CPU0_SA_CA<5>")
	)
	(arc
		(start 334.99806 -254.691642)
		(mid 334.811116 -254.641387)
		(end 334.624172 -254.691642)
		(width 0.0889)
		(layer "In2.Cu")
		(net "M_C_CPU0_SA_CA<5>")
	)
	(arc
		(start 327.103232 -254.691642)
		(mid 326.823804 -254.767808)
		(end 326.543416 -254.695198)
		(width 0.0889)
		(layer "In2.Cu")
		(net "M_C_CPU0_SA_CA<5>")
	)
	(arc
		(start 330.863956 -254.691642)
		(mid 330.581 -254.767819)
		(end 330.298044 -254.691642)
		(width 0.0889)
		(layer "In2.Cu")
		(net "M_C_CPU0_SA_CA<5>")
	)
	(arc
		(start 335.929732 -254.686816)
		(mid 335.746224 -254.641322)
		(end 335.563972 -254.691642)
		(width 0.0889)
		(layer "In2.Cu")
		(net "M_C_CPU0_SA_CA<5>")
	)
	(arc
		(start 339.689694 -254.686816)
		(mid 339.506186 -254.641322)
		(end 339.323934 -254.691642)
		(width 0.0889)
		(layer "In2.Cu")
		(net "M_C_CPU0_SA_CA<5>")
	)
	(arc
		(start 342.081104 -254.723392)
		(mid 341.825896 -254.766869)
		(end 341.578184 -254.691642)
		(width 0.0889)
		(layer "In2.Cu")
		(net "M_C_CPU0_SA_CA<5>")
	)
	(arc
		(start 336.504026 -254.691642)
		(mid 336.22107 -254.767819)
		(end 335.938114 -254.691642)
		(width 0.0889)
		(layer "In2.Cu")
		(net "M_C_CPU0_SA_CA<5>")
	)
	(arc
		(start 334.624172 -254.691642)
		(mid 334.341216 -254.767819)
		(end 334.05826 -254.691642)
		(width 0.0889)
		(layer "In2.Cu")
		(net "M_C_CPU0_SA_CA<5>")
	)
	(segment
		(start 342.327992 -254.470154)
		(end 341.86114 -254.204216)
		(width 0.10668)
		(layer "F.Cu")
		(net "M_C_CPU0_SA_CA<4>")
	)
	(segment
		(start 308.222142 -253.010162)
		(end 302.350424 -253.010162)
		(width 0.14478)
		(layer "In2.Cu")
		(net "M_C_CPU0_SA_CA<4>")
	)
	(segment
		(start 297.001438 -252.785118)
		(end 296.83837 -252.62205)
		(width 0.14478)
		(layer "In2.Cu")
		(net "M_C_CPU0_SA_CA<4>")
	)
	(segment
		(start 301.467774 -253.010162)
		(end 301.237396 -253.010162)
		(width 0.14478)
		(layer "In2.Cu")
		(net "M_C_CPU0_SA_CA<4>")
	)
	(segment
		(start 301.630842 -253.231142)
		(end 301.630842 -253.17323)
		(width 0.14478)
		(layer "In2.Cu")
		(net "M_C_CPU0_SA_CA<4>")
	)
	(segment
		(start 309.428896 -254.216916)
		(end 308.222142 -253.010162)
		(width 0.14478)
		(layer "In2.Cu")
		(net "M_C_CPU0_SA_CA<4>")
	)
	(segment
		(start 326.647302 -254.534416)
		(end 326.633586 -254.526542)
		(width 0.0889)
		(layer "In2.Cu")
		(net "M_C_CPU0_SA_CA<4>")
	)
	(segment
		(start 301.074328 -253.231142)
		(end 300.91126 -253.39421)
		(width 0.14478)
		(layer "In2.Cu")
		(net "M_C_CPU0_SA_CA<4>")
	)
	(segment
		(start 297.951398 -252.62205)
		(end 297.72102 -252.62205)
		(width 0.14478)
		(layer "In2.Cu")
		(net "M_C_CPU0_SA_CA<4>")
	)
	(segment
		(start 334.52816 -254.526796)
		(end 334.519778 -254.531622)
		(width 0.0889)
		(layer "In2.Cu")
		(net "M_C_CPU0_SA_CA<4>")
	)
	(segment
		(start 331.342492 -254.531622)
		(end 331.33411 -254.526796)
		(width 0.0889)
		(layer "In2.Cu")
		(net "M_C_CPU0_SA_CA<4>")
	)
	(segment
		(start 327.021952 -254.51816)
		(end 327.00722 -254.526796)
		(width 0.0889)
		(layer "In2.Cu")
		(net "M_C_CPU0_SA_CA<4>")
	)
	(segment
		(start 297.001438 -253.235206)
		(end 297.001438 -252.785118)
		(width 0.14478)
		(layer "In2.Cu")
		(net "M_C_CPU0_SA_CA<4>")
	)
	(segment
		(start 301.237396 -253.010162)
		(end 301.074328 -253.17323)
		(width 0.14478)
		(layer "In2.Cu")
		(net "M_C_CPU0_SA_CA<4>")
	)
	(segment
		(start 302.187356 -253.231142)
		(end 302.024288 -253.39421)
		(width 0.14478)
		(layer "In2.Cu")
		(net "M_C_CPU0_SA_CA<4>")
	)
	(segment
		(start 301.79391 -253.39421)
		(end 301.630842 -253.231142)
		(width 0.14478)
		(layer "In2.Cu")
		(net "M_C_CPU0_SA_CA<4>")
	)
	(segment
		(start 296.281856 -253.010162)
		(end 295.023032 -253.010162)
		(width 0.14478)
		(layer "In2.Cu")
		(net "M_C_CPU0_SA_CA<4>")
	)
	(segment
		(start 296.444924 -252.785118)
		(end 296.444924 -252.847094)
		(width 0.14478)
		(layer "In2.Cu")
		(net "M_C_CPU0_SA_CA<4>")
	)
	(segment
		(start 300.517814 -253.231142)
		(end 300.517814 -253.17323)
		(width 0.14478)
		(layer "In2.Cu")
		(net "M_C_CPU0_SA_CA<4>")
	)
	(segment
		(start 297.394884 -253.398274)
		(end 297.164506 -253.398274)
		(width 0.14478)
		(layer "In2.Cu")
		(net "M_C_CPU0_SA_CA<4>")
	)
	(segment
		(start 301.074328 -253.17323)
		(end 301.074328 -253.231142)
		(width 0.14478)
		(layer "In2.Cu")
		(net "M_C_CPU0_SA_CA<4>")
	)
	(segment
		(start 296.607992 -252.62205)
		(end 296.444924 -252.785118)
		(width 0.14478)
		(layer "In2.Cu")
		(net "M_C_CPU0_SA_CA<4>")
	)
	(segment
		(start 316.335918 -253.57709)
		(end 314.79109 -254.216916)
		(width 0.14478)
		(layer "In2.Cu")
		(net "M_C_CPU0_SA_CA<4>")
	)
	(segment
		(start 329.828144 -254.526796)
		(end 329.819762 -254.531622)
		(width 0.0889)
		(layer "In2.Cu")
		(net "M_C_CPU0_SA_CA<4>")
	)
	(segment
		(start 298.67098 -253.17323)
		(end 298.67098 -253.235206)
		(width 0.14478)
		(layer "In2.Cu")
		(net "M_C_CPU0_SA_CA<4>")
	)
	(segment
		(start 341.86114 -254.204216)
		(end 342.015064 -254.469646)
		(width 0.0889)
		(layer "In2.Cu")
		(net "M_C_CPU0_SA_CA<4>")
	)
	(segment
		(start 342.015064 -254.469646)
		(end 341.992712 -254.552958)
		(width 0.0889)
		(layer "In2.Cu")
		(net "M_C_CPU0_SA_CA<4>")
	)
	(segment
		(start 300.91126 -253.39421)
		(end 300.680882 -253.39421)
		(width 0.14478)
		(layer "In2.Cu")
		(net "M_C_CPU0_SA_CA<4>")
	)
	(segment
		(start 338.288122 -254.526796)
		(end 338.27974 -254.531622)
		(width 0.0889)
		(layer "In2.Cu")
		(net "M_C_CPU0_SA_CA<4>")
	)
	(segment
		(start 300.517814 -253.17323)
		(end 300.354746 -253.010162)
		(width 0.14478)
		(layer "In2.Cu")
		(net "M_C_CPU0_SA_CA<4>")
	)
	(segment
		(start 319.794128 -253.57709)
		(end 316.335918 -253.57709)
		(width 0.14478)
		(layer "In2.Cu")
		(net "M_C_CPU0_SA_CA<4>")
	)
	(segment
		(start 314.79109 -254.216916)
		(end 309.428896 -254.216916)
		(width 0.14478)
		(layer "In2.Cu")
		(net "M_C_CPU0_SA_CA<4>")
	)
	(segment
		(start 327.94829 -254.526796)
		(end 327.939908 -254.531622)
		(width 0.0889)
		(layer "In2.Cu")
		(net "M_C_CPU0_SA_CA<4>")
	)
	(segment
		(start 302.187356 -253.17323)
		(end 302.187356 -253.231142)
		(width 0.14478)
		(layer "In2.Cu")
		(net "M_C_CPU0_SA_CA<4>")
	)
	(segment
		(start 323.873114 -254.94361)
		(end 321.160648 -254.94361)
		(width 0.14478)
		(layer "In2.Cu")
		(net "M_C_CPU0_SA_CA<4>")
	)
	(segment
		(start 298.277534 -253.398274)
		(end 298.114466 -253.235206)
		(width 0.14478)
		(layer "In2.Cu")
		(net "M_C_CPU0_SA_CA<4>")
	)
	(segment
		(start 333.588106 -254.526796)
		(end 333.579724 -254.531622)
		(width 0.0889)
		(layer "In2.Cu")
		(net "M_C_CPU0_SA_CA<4>")
	)
	(segment
		(start 324.137274 -254.94361)
		(end 323.873114 -254.94361)
		(width 0.0889)
		(layer "In2.Cu")
		(net "M_C_CPU0_SA_CA<4>")
	)
	(segment
		(start 302.024288 -253.39421)
		(end 301.79391 -253.39421)
		(width 0.14478)
		(layer "In2.Cu")
		(net "M_C_CPU0_SA_CA<4>")
	)
	(segment
		(start 321.160648 -254.94361)
		(end 319.794128 -253.57709)
		(width 0.14478)
		(layer "In2.Cu")
		(net "M_C_CPU0_SA_CA<4>")
	)
	(segment
		(start 298.114466 -253.235206)
		(end 298.114466 -252.785118)
		(width 0.14478)
		(layer "In2.Cu")
		(net "M_C_CPU0_SA_CA<4>")
	)
	(segment
		(start 296.444924 -252.847094)
		(end 296.281856 -253.010162)
		(width 0.14478)
		(layer "In2.Cu")
		(net "M_C_CPU0_SA_CA<4>")
	)
	(segment
		(start 298.834048 -253.010162)
		(end 298.67098 -253.17323)
		(width 0.14478)
		(layer "In2.Cu")
		(net "M_C_CPU0_SA_CA<4>")
	)
	(segment
		(start 324.917308 -254.83693)
		(end 324.243954 -254.83693)
		(width 0.0889)
		(layer "In2.Cu")
		(net "M_C_CPU0_SA_CA<4>")
	)
	(segment
		(start 338.862416 -254.531622)
		(end 338.854034 -254.526796)
		(width 0.0889)
		(layer "In2.Cu")
		(net "M_C_CPU0_SA_CA<4>")
	)
	(segment
		(start 339.80247 -254.531622)
		(end 339.794088 -254.526796)
		(width 0.0889)
		(layer "In2.Cu")
		(net "M_C_CPU0_SA_CA<4>")
	)
	(segment
		(start 297.72102 -252.62205)
		(end 297.557952 -252.785118)
		(width 0.14478)
		(layer "In2.Cu")
		(net "M_C_CPU0_SA_CA<4>")
	)
	(segment
		(start 302.350424 -253.010162)
		(end 302.187356 -253.17323)
		(width 0.14478)
		(layer "In2.Cu")
		(net "M_C_CPU0_SA_CA<4>")
	)
	(segment
		(start 300.354746 -253.010162)
		(end 298.834048 -253.010162)
		(width 0.14478)
		(layer "In2.Cu")
		(net "M_C_CPU0_SA_CA<4>")
	)
	(segment
		(start 326.633586 -254.526542)
		(end 326.617838 -254.517398)
		(width 0.0889)
		(layer "In2.Cu")
		(net "M_C_CPU0_SA_CA<4>")
	)
	(segment
		(start 298.114466 -252.785118)
		(end 297.951398 -252.62205)
		(width 0.14478)
		(layer "In2.Cu")
		(net "M_C_CPU0_SA_CA<4>")
	)
	(segment
		(start 298.507912 -253.398274)
		(end 298.277534 -253.398274)
		(width 0.14478)
		(layer "In2.Cu")
		(net "M_C_CPU0_SA_CA<4>")
	)
	(segment
		(start 298.67098 -253.235206)
		(end 298.507912 -253.398274)
		(width 0.14478)
		(layer "In2.Cu")
		(net "M_C_CPU0_SA_CA<4>")
	)
	(segment
		(start 297.557952 -253.235206)
		(end 297.394884 -253.398274)
		(width 0.14478)
		(layer "In2.Cu")
		(net "M_C_CPU0_SA_CA<4>")
	)
	(segment
		(start 301.630842 -253.17323)
		(end 301.467774 -253.010162)
		(width 0.14478)
		(layer "In2.Cu")
		(net "M_C_CPU0_SA_CA<4>")
	)
	(segment
		(start 297.164506 -253.398274)
		(end 297.001438 -253.235206)
		(width 0.14478)
		(layer "In2.Cu")
		(net "M_C_CPU0_SA_CA<4>")
	)
	(segment
		(start 296.83837 -252.62205)
		(end 296.607992 -252.62205)
		(width 0.14478)
		(layer "In2.Cu")
		(net "M_C_CPU0_SA_CA<4>")
	)
	(segment
		(start 336.042508 -254.531622)
		(end 336.034126 -254.526796)
		(width 0.0889)
		(layer "In2.Cu")
		(net "M_C_CPU0_SA_CA<4>")
	)
	(segment
		(start 300.680882 -253.39421)
		(end 300.517814 -253.231142)
		(width 0.14478)
		(layer "In2.Cu")
		(net "M_C_CPU0_SA_CA<4>")
	)
	(segment
		(start 297.557952 -252.785118)
		(end 297.557952 -253.235206)
		(width 0.14478)
		(layer "In2.Cu")
		(net "M_C_CPU0_SA_CA<4>")
	)
	(segment
		(start 295.023032 -253.010162)
		(end 293.32174 -251.30887)
		(width 0.14478)
		(layer "In2.Cu")
		(net "M_C_CPU0_SA_CA<4>")
	)
	(segment
		(start 293.32174 -251.30887)
		(end 292.704012 -251.30887)
		(width 0.14478)
		(layer "In2.Cu")
		(net "M_C_CPU0_SA_CA<4>")
	)
	(segment
		(start 335.102454 -254.531622)
		(end 335.094072 -254.526796)
		(width 0.0889)
		(layer "In2.Cu")
		(net "M_C_CPU0_SA_CA<4>")
	)
	(segment
		(start 292.704012 -251.30887)
		(end 292.280086 -250.884944)
		(width 0.14478)
		(layer "In2.Cu")
		(net "M_C_CPU0_SA_CA<4>")
	)
	(segment
		(start 324.243954 -254.83693)
		(end 324.137274 -254.94361)
		(width 0.0889)
		(layer "In2.Cu")
		(net "M_C_CPU0_SA_CA<4>")
	)
	(segment
		(start 330.402438 -254.531622)
		(end 330.394056 -254.526796)
		(width 0.0889)
		(layer "In2.Cu")
		(net "M_C_CPU0_SA_CA<4>")
	)
	(arc
		(start 341.10803 -254.526796)
		(mid 340.921086 -254.577051)
		(end 340.734142 -254.526796)
		(width 0.0889)
		(layer "In2.Cu")
		(net "M_C_CPU0_SA_CA<4>")
	)
	(arc
		(start 340.16823 -254.526796)
		(mid 339.985979 -254.577146)
		(end 339.80247 -254.531622)
		(width 0.0889)
		(layer "In2.Cu")
		(net "M_C_CPU0_SA_CA<4>")
	)
	(arc
		(start 341.992712 -254.552958)
		(mid 341.83038 -254.575776)
		(end 341.673942 -254.526796)
		(width 0.0889)
		(layer "In2.Cu")
		(net "M_C_CPU0_SA_CA<4>")
	)
	(arc
		(start 341.673942 -254.526796)
		(mid 341.390986 -254.450619)
		(end 341.10803 -254.526796)
		(width 0.0889)
		(layer "In2.Cu")
		(net "M_C_CPU0_SA_CA<4>")
	)
	(arc
		(start 337.91398 -254.526796)
		(mid 337.631024 -254.450619)
		(end 337.348068 -254.526796)
		(width 0.0889)
		(layer "In2.Cu")
		(net "M_C_CPU0_SA_CA<4>")
	)
	(arc
		(start 332.648052 -254.526796)
		(mid 332.461108 -254.577051)
		(end 332.274164 -254.526796)
		(width 0.0889)
		(layer "In2.Cu")
		(net "M_C_CPU0_SA_CA<4>")
	)
	(arc
		(start 332.274164 -254.526796)
		(mid 331.991208 -254.450619)
		(end 331.708252 -254.526796)
		(width 0.0889)
		(layer "In2.Cu")
		(net "M_C_CPU0_SA_CA<4>")
	)
	(arc
		(start 331.33411 -254.526796)
		(mid 331.051154 -254.450619)
		(end 330.768198 -254.526796)
		(width 0.0889)
		(layer "In2.Cu")
		(net "M_C_CPU0_SA_CA<4>")
	)
	(arc
		(start 327.00722 -254.526796)
		(mid 326.828233 -254.576966)
		(end 326.647302 -254.534416)
		(width 0.0889)
		(layer "In2.Cu")
		(net "M_C_CPU0_SA_CA<4>")
	)
	(arc
		(start 329.819762 -254.531622)
		(mid 329.636254 -254.577116)
		(end 329.454002 -254.526796)
		(width 0.0889)
		(layer "In2.Cu")
		(net "M_C_CPU0_SA_CA<4>")
	)
	(arc
		(start 327.57364 -254.526796)
		(mid 327.298934 -254.450432)
		(end 327.021952 -254.51816)
		(width 0.0889)
		(layer "In2.Cu")
		(net "M_C_CPU0_SA_CA<4>")
	)
	(arc
		(start 338.27974 -254.531622)
		(mid 338.096232 -254.577116)
		(end 337.91398 -254.526796)
		(width 0.0889)
		(layer "In2.Cu")
		(net "M_C_CPU0_SA_CA<4>")
	)
	(arc
		(start 329.454002 -254.526796)
		(mid 329.171046 -254.450619)
		(end 328.88809 -254.526796)
		(width 0.0889)
		(layer "In2.Cu")
		(net "M_C_CPU0_SA_CA<4>")
	)
	(arc
		(start 336.408268 -254.526796)
		(mid 336.226017 -254.577146)
		(end 336.042508 -254.531622)
		(width 0.0889)
		(layer "In2.Cu")
		(net "M_C_CPU0_SA_CA<4>")
	)
	(arc
		(start 326.067674 -254.526796)
		(mid 325.513029 -254.758028)
		(end 324.917308 -254.83693)
		(width 0.0889)
		(layer "In2.Cu")
		(net "M_C_CPU0_SA_CA<4>")
	)
	(arc
		(start 330.768198 -254.526796)
		(mid 330.585947 -254.577146)
		(end 330.402438 -254.531622)
		(width 0.0889)
		(layer "In2.Cu")
		(net "M_C_CPU0_SA_CA<4>")
	)
	(arc
		(start 328.88809 -254.526796)
		(mid 328.701146 -254.577051)
		(end 328.514202 -254.526796)
		(width 0.0889)
		(layer "In2.Cu")
		(net "M_C_CPU0_SA_CA<4>")
	)
	(arc
		(start 339.794088 -254.526796)
		(mid 339.511132 -254.450619)
		(end 339.228176 -254.526796)
		(width 0.0889)
		(layer "In2.Cu")
		(net "M_C_CPU0_SA_CA<4>")
	)
	(arc
		(start 334.154018 -254.526796)
		(mid 333.871062 -254.450619)
		(end 333.588106 -254.526796)
		(width 0.0889)
		(layer "In2.Cu")
		(net "M_C_CPU0_SA_CA<4>")
	)
	(arc
		(start 339.228176 -254.526796)
		(mid 339.045925 -254.577146)
		(end 338.862416 -254.531622)
		(width 0.0889)
		(layer "In2.Cu")
		(net "M_C_CPU0_SA_CA<4>")
	)
	(arc
		(start 335.468214 -254.526796)
		(mid 335.285963 -254.577146)
		(end 335.102454 -254.531622)
		(width 0.0889)
		(layer "In2.Cu")
		(net "M_C_CPU0_SA_CA<4>")
	)
	(arc
		(start 336.97418 -254.526796)
		(mid 336.691224 -254.450619)
		(end 336.408268 -254.526796)
		(width 0.0889)
		(layer "In2.Cu")
		(net "M_C_CPU0_SA_CA<4>")
	)
	(arc
		(start 337.348068 -254.526796)
		(mid 337.161124 -254.577051)
		(end 336.97418 -254.526796)
		(width 0.0889)
		(layer "In2.Cu")
		(net "M_C_CPU0_SA_CA<4>")
	)
	(arc
		(start 326.617838 -254.517398)
		(mid 326.341529 -254.450422)
		(end 326.067674 -254.526796)
		(width 0.0889)
		(layer "In2.Cu")
		(net "M_C_CPU0_SA_CA<4>")
	)
	(arc
		(start 327.939908 -254.531622)
		(mid 327.756146 -254.577238)
		(end 327.57364 -254.526796)
		(width 0.0889)
		(layer "In2.Cu")
		(net "M_C_CPU0_SA_CA<4>")
	)
	(arc
		(start 331.708252 -254.526796)
		(mid 331.526001 -254.577146)
		(end 331.342492 -254.531622)
		(width 0.0889)
		(layer "In2.Cu")
		(net "M_C_CPU0_SA_CA<4>")
	)
	(arc
		(start 328.514202 -254.526796)
		(mid 328.231246 -254.450619)
		(end 327.94829 -254.526796)
		(width 0.0889)
		(layer "In2.Cu")
		(net "M_C_CPU0_SA_CA<4>")
	)
	(arc
		(start 335.094072 -254.526796)
		(mid 334.811116 -254.450619)
		(end 334.52816 -254.526796)
		(width 0.0889)
		(layer "In2.Cu")
		(net "M_C_CPU0_SA_CA<4>")
	)
	(arc
		(start 338.854034 -254.526796)
		(mid 338.571078 -254.450619)
		(end 338.288122 -254.526796)
		(width 0.0889)
		(layer "In2.Cu")
		(net "M_C_CPU0_SA_CA<4>")
	)
	(arc
		(start 330.394056 -254.526796)
		(mid 330.1111 -254.450619)
		(end 329.828144 -254.526796)
		(width 0.0889)
		(layer "In2.Cu")
		(net "M_C_CPU0_SA_CA<4>")
	)
	(arc
		(start 333.579724 -254.531622)
		(mid 333.396216 -254.577116)
		(end 333.213964 -254.526796)
		(width 0.0889)
		(layer "In2.Cu")
		(net "M_C_CPU0_SA_CA<4>")
	)
	(arc
		(start 334.519778 -254.531622)
		(mid 334.33627 -254.577116)
		(end 334.154018 -254.526796)
		(width 0.0889)
		(layer "In2.Cu")
		(net "M_C_CPU0_SA_CA<4>")
	)
	(arc
		(start 333.213964 -254.526796)
		(mid 332.931008 -254.450619)
		(end 332.648052 -254.526796)
		(width 0.0889)
		(layer "In2.Cu")
		(net "M_C_CPU0_SA_CA<4>")
	)
	(arc
		(start 336.034126 -254.526796)
		(mid 335.75117 -254.450619)
		(end 335.468214 -254.526796)
		(width 0.0889)
		(layer "In2.Cu")
		(net "M_C_CPU0_SA_CA<4>")
	)
	(arc
		(start 340.734142 -254.526796)
		(mid 340.451186 -254.450619)
		(end 340.16823 -254.526796)
		(width 0.0889)
		(layer "In2.Cu")
		(net "M_C_CPU0_SA_CA<4>")
	)
	(segment
		(start 344.207846 -254.470154)
		(end 343.740994 -254.204216)
		(width 0.10668)
		(layer "F.Cu")
		(net "M_C_CPU0_SA_CA<3>")
	)
	(segment
		(start 316.258448 -253.12243)
		(end 314.701428 -253.767336)
		(width 0.14478)
		(layer "In2.Cu")
		(net "M_C_CPU0_SA_CA<3>")
	)
	(segment
		(start 314.701428 -253.767336)
		(end 310.000396 -253.767336)
		(width 0.14478)
		(layer "In2.Cu")
		(net "M_C_CPU0_SA_CA<3>")
	)
	(segment
		(start 342.048084 -253.881636)
		(end 342.039702 -253.87681)
		(width 0.0889)
		(layer "In2.Cu")
		(net "M_C_CPU0_SA_CA<3>")
	)
	(segment
		(start 294.960294 -252.15469)
		(end 293.265606 -250.460002)
		(width 0.14478)
		(layer "In2.Cu")
		(net "M_C_CPU0_SA_CA<3>")
	)
	(segment
		(start 342.988138 -253.881636)
		(end 342.979756 -253.87681)
		(width 0.0889)
		(layer "In2.Cu")
		(net "M_C_CPU0_SA_CA<3>")
	)
	(segment
		(start 330.402438 -253.87681)
		(end 330.394056 -253.881636)
		(width 0.0889)
		(layer "In2.Cu")
		(net "M_C_CPU0_SA_CA<3>")
	)
	(segment
		(start 343.58707 -253.938786)
		(end 343.491058 -253.913386)
		(width 0.0889)
		(layer "In2.Cu")
		(net "M_C_CPU0_SA_CA<3>")
	)
	(segment
		(start 338.862416 -253.87681)
		(end 338.854034 -253.881636)
		(width 0.0889)
		(layer "In2.Cu")
		(net "M_C_CPU0_SA_CA<3>")
	)
	(segment
		(start 293.265606 -250.460002)
		(end 288.60496 -250.460002)
		(width 0.14478)
		(layer "In2.Cu")
		(net "M_C_CPU0_SA_CA<3>")
	)
	(segment
		(start 324.530974 -254.10287)
		(end 324.165214 -254.46863)
		(width 0.0889)
		(layer "In2.Cu")
		(net "M_C_CPU0_SA_CA<3>")
	)
	(segment
		(start 329.828144 -253.881636)
		(end 329.819762 -253.87681)
		(width 0.0889)
		(layer "In2.Cu")
		(net "M_C_CPU0_SA_CA<3>")
	)
	(segment
		(start 334.52816 -253.881636)
		(end 334.519778 -253.87681)
		(width 0.0889)
		(layer "In2.Cu")
		(net "M_C_CPU0_SA_CA<3>")
	)
	(segment
		(start 325.69785 -253.881636)
		(end 325.569072 -253.956312)
		(width 0.0889)
		(layer "In2.Cu")
		(net "M_C_CPU0_SA_CA<3>")
	)
	(segment
		(start 321.328796 -254.46863)
		(end 319.982596 -253.12243)
		(width 0.14478)
		(layer "In2.Cu")
		(net "M_C_CPU0_SA_CA<3>")
	)
	(segment
		(start 310.000396 -253.767336)
		(end 308.38775 -252.15469)
		(width 0.14478)
		(layer "In2.Cu")
		(net "M_C_CPU0_SA_CA<3>")
	)
	(segment
		(start 331.342492 -253.87681)
		(end 331.33411 -253.881636)
		(width 0.0889)
		(layer "In2.Cu")
		(net "M_C_CPU0_SA_CA<3>")
	)
	(segment
		(start 327.575418 -253.88189)
		(end 327.549256 -253.896876)
		(width 0.0889)
		(layer "In2.Cu")
		(net "M_C_CPU0_SA_CA<3>")
	)
	(segment
		(start 333.588106 -253.881636)
		(end 333.579724 -253.87681)
		(width 0.0889)
		(layer "In2.Cu")
		(net "M_C_CPU0_SA_CA<3>")
	)
	(segment
		(start 326.070214 -253.88189)
		(end 326.046846 -253.868428)
		(width 0.0889)
		(layer "In2.Cu")
		(net "M_C_CPU0_SA_CA<3>")
	)
	(segment
		(start 308.38775 -252.15469)
		(end 294.960294 -252.15469)
		(width 0.14478)
		(layer "In2.Cu")
		(net "M_C_CPU0_SA_CA<3>")
	)
	(segment
		(start 326.109584 -253.90475)
		(end 326.070214 -253.88189)
		(width 0.0889)
		(layer "In2.Cu")
		(net "M_C_CPU0_SA_CA<3>")
	)
	(segment
		(start 335.102454 -253.87681)
		(end 335.094072 -253.881636)
		(width 0.0889)
		(layer "In2.Cu")
		(net "M_C_CPU0_SA_CA<3>")
	)
	(segment
		(start 288.60496 -250.460002)
		(end 288.180018 -250.03506)
		(width 0.14478)
		(layer "In2.Cu")
		(net "M_C_CPU0_SA_CA<3>")
	)
	(segment
		(start 336.042508 -253.87681)
		(end 336.034126 -253.881636)
		(width 0.0889)
		(layer "In2.Cu")
		(net "M_C_CPU0_SA_CA<3>")
	)
	(segment
		(start 339.80247 -253.87681)
		(end 339.794088 -253.881636)
		(width 0.0889)
		(layer "In2.Cu")
		(net "M_C_CPU0_SA_CA<3>")
	)
	(segment
		(start 319.982596 -253.12243)
		(end 316.258448 -253.12243)
		(width 0.14478)
		(layer "In2.Cu")
		(net "M_C_CPU0_SA_CA<3>")
	)
	(segment
		(start 327.598786 -253.868428)
		(end 327.575418 -253.88189)
		(width 0.0889)
		(layer "In2.Cu")
		(net "M_C_CPU0_SA_CA<3>")
	)
	(segment
		(start 338.288122 -253.881636)
		(end 338.27974 -253.87681)
		(width 0.0889)
		(layer "In2.Cu")
		(net "M_C_CPU0_SA_CA<3>")
	)
	(segment
		(start 343.740994 -254.204216)
		(end 343.58707 -253.938786)
		(width 0.0889)
		(layer "In2.Cu")
		(net "M_C_CPU0_SA_CA<3>")
	)
	(segment
		(start 325.023734 -254.10287)
		(end 324.530974 -254.10287)
		(width 0.0889)
		(layer "In2.Cu")
		(net "M_C_CPU0_SA_CA<3>")
	)
	(segment
		(start 323.898514 -254.46863)
		(end 321.328796 -254.46863)
		(width 0.14478)
		(layer "In2.Cu")
		(net "M_C_CPU0_SA_CA<3>")
	)
	(segment
		(start 327.011538 -253.881636)
		(end 326.990964 -253.869698)
		(width 0.0889)
		(layer "In2.Cu")
		(net "M_C_CPU0_SA_CA<3>")
	)
	(segment
		(start 324.165214 -254.46863)
		(end 323.898514 -254.46863)
		(width 0.0889)
		(layer "In2.Cu")
		(net "M_C_CPU0_SA_CA<3>")
	)
	(arc
		(start 337.348068 -253.881636)
		(mid 337.161124 -253.831381)
		(end 336.97418 -253.881636)
		(width 0.0889)
		(layer "In2.Cu")
		(net "M_C_CPU0_SA_CA<3>")
	)
	(arc
		(start 334.519778 -253.87681)
		(mid 334.33627 -253.831316)
		(end 334.154018 -253.881636)
		(width 0.0889)
		(layer "In2.Cu")
		(net "M_C_CPU0_SA_CA<3>")
	)
	(arc
		(start 326.046846 -253.868428)
		(mid 325.870704 -253.831636)
		(end 325.69785 -253.881636)
		(width 0.0889)
		(layer "In2.Cu")
		(net "M_C_CPU0_SA_CA<3>")
	)
	(arc
		(start 328.88809 -253.881636)
		(mid 328.701146 -253.831381)
		(end 328.514202 -253.881636)
		(width 0.0889)
		(layer "In2.Cu")
		(net "M_C_CPU0_SA_CA<3>")
	)
	(arc
		(start 330.394056 -253.881636)
		(mid 330.1111 -253.957813)
		(end 329.828144 -253.881636)
		(width 0.0889)
		(layer "In2.Cu")
		(net "M_C_CPU0_SA_CA<3>")
	)
	(arc
		(start 332.274164 -253.881636)
		(mid 331.991208 -253.957813)
		(end 331.708252 -253.881636)
		(width 0.0889)
		(layer "In2.Cu")
		(net "M_C_CPU0_SA_CA<3>")
	)
	(arc
		(start 330.768198 -253.881636)
		(mid 330.585947 -253.831286)
		(end 330.402438 -253.87681)
		(width 0.0889)
		(layer "In2.Cu")
		(net "M_C_CPU0_SA_CA<3>")
	)
	(arc
		(start 327.549256 -253.896876)
		(mid 327.27847 -253.957522)
		(end 327.011538 -253.881636)
		(width 0.0889)
		(layer "In2.Cu")
		(net "M_C_CPU0_SA_CA<3>")
	)
	(arc
		(start 340.734142 -253.881636)
		(mid 340.451186 -253.957813)
		(end 340.16823 -253.881636)
		(width 0.0889)
		(layer "In2.Cu")
		(net "M_C_CPU0_SA_CA<3>")
	)
	(arc
		(start 325.569072 -253.956312)
		(mid 325.306082 -254.065616)
		(end 325.023734 -254.10287)
		(width 0.0889)
		(layer "In2.Cu")
		(net "M_C_CPU0_SA_CA<3>")
	)
	(arc
		(start 341.10803 -253.881636)
		(mid 340.921086 -253.831381)
		(end 340.734142 -253.881636)
		(width 0.0889)
		(layer "In2.Cu")
		(net "M_C_CPU0_SA_CA<3>")
	)
	(arc
		(start 342.613996 -253.881636)
		(mid 342.33104 -253.957813)
		(end 342.048084 -253.881636)
		(width 0.0889)
		(layer "In2.Cu")
		(net "M_C_CPU0_SA_CA<3>")
	)
	(arc
		(start 341.673942 -253.881636)
		(mid 341.390986 -253.957813)
		(end 341.10803 -253.881636)
		(width 0.0889)
		(layer "In2.Cu")
		(net "M_C_CPU0_SA_CA<3>")
	)
	(arc
		(start 333.579724 -253.87681)
		(mid 333.396216 -253.831316)
		(end 333.213964 -253.881636)
		(width 0.0889)
		(layer "In2.Cu")
		(net "M_C_CPU0_SA_CA<3>")
	)
	(arc
		(start 342.039702 -253.87681)
		(mid 341.856194 -253.831316)
		(end 341.673942 -253.881636)
		(width 0.0889)
		(layer "In2.Cu")
		(net "M_C_CPU0_SA_CA<3>")
	)
	(arc
		(start 326.636126 -253.881636)
		(mid 326.375711 -253.958418)
		(end 326.109584 -253.90475)
		(width 0.0889)
		(layer "In2.Cu")
		(net "M_C_CPU0_SA_CA<3>")
	)
	(arc
		(start 335.468214 -253.881636)
		(mid 335.285963 -253.831286)
		(end 335.102454 -253.87681)
		(width 0.0889)
		(layer "In2.Cu")
		(net "M_C_CPU0_SA_CA<3>")
	)
	(arc
		(start 335.094072 -253.881636)
		(mid 334.811116 -253.957813)
		(end 334.52816 -253.881636)
		(width 0.0889)
		(layer "In2.Cu")
		(net "M_C_CPU0_SA_CA<3>")
	)
	(arc
		(start 334.154018 -253.881636)
		(mid 333.871062 -253.957813)
		(end 333.588106 -253.881636)
		(width 0.0889)
		(layer "In2.Cu")
		(net "M_C_CPU0_SA_CA<3>")
	)
	(arc
		(start 336.034126 -253.881636)
		(mid 335.75117 -253.957813)
		(end 335.468214 -253.881636)
		(width 0.0889)
		(layer "In2.Cu")
		(net "M_C_CPU0_SA_CA<3>")
	)
	(arc
		(start 326.990964 -253.869698)
		(mid 326.812036 -253.830821)
		(end 326.636126 -253.881636)
		(width 0.0889)
		(layer "In2.Cu")
		(net "M_C_CPU0_SA_CA<3>")
	)
	(arc
		(start 336.97418 -253.881636)
		(mid 336.691224 -253.957813)
		(end 336.408268 -253.881636)
		(width 0.0889)
		(layer "In2.Cu")
		(net "M_C_CPU0_SA_CA<3>")
	)
	(arc
		(start 329.819762 -253.87681)
		(mid 329.636254 -253.831316)
		(end 329.454002 -253.881636)
		(width 0.0889)
		(layer "In2.Cu")
		(net "M_C_CPU0_SA_CA<3>")
	)
	(arc
		(start 333.213964 -253.881636)
		(mid 332.931008 -253.957813)
		(end 332.648052 -253.881636)
		(width 0.0889)
		(layer "In2.Cu")
		(net "M_C_CPU0_SA_CA<3>")
	)
	(arc
		(start 327.94829 -253.881636)
		(mid 327.775182 -253.83152)
		(end 327.598786 -253.868428)
		(width 0.0889)
		(layer "In2.Cu")
		(net "M_C_CPU0_SA_CA<3>")
	)
	(arc
		(start 340.16823 -253.881636)
		(mid 339.985979 -253.831286)
		(end 339.80247 -253.87681)
		(width 0.0889)
		(layer "In2.Cu")
		(net "M_C_CPU0_SA_CA<3>")
	)
	(arc
		(start 336.408268 -253.881636)
		(mid 336.226017 -253.831286)
		(end 336.042508 -253.87681)
		(width 0.0889)
		(layer "In2.Cu")
		(net "M_C_CPU0_SA_CA<3>")
	)
	(arc
		(start 338.854034 -253.881636)
		(mid 338.571078 -253.957813)
		(end 338.288122 -253.881636)
		(width 0.0889)
		(layer "In2.Cu")
		(net "M_C_CPU0_SA_CA<3>")
	)
	(arc
		(start 332.648052 -253.881636)
		(mid 332.461108 -253.831381)
		(end 332.274164 -253.881636)
		(width 0.0889)
		(layer "In2.Cu")
		(net "M_C_CPU0_SA_CA<3>")
	)
	(arc
		(start 337.91398 -253.881636)
		(mid 337.631024 -253.957813)
		(end 337.348068 -253.881636)
		(width 0.0889)
		(layer "In2.Cu")
		(net "M_C_CPU0_SA_CA<3>")
	)
	(arc
		(start 342.979756 -253.87681)
		(mid 342.796248 -253.831316)
		(end 342.613996 -253.881636)
		(width 0.0889)
		(layer "In2.Cu")
		(net "M_C_CPU0_SA_CA<3>")
	)
	(arc
		(start 339.228176 -253.881636)
		(mid 339.045925 -253.831286)
		(end 338.862416 -253.87681)
		(width 0.0889)
		(layer "In2.Cu")
		(net "M_C_CPU0_SA_CA<3>")
	)
	(arc
		(start 328.514202 -253.881636)
		(mid 328.231246 -253.957813)
		(end 327.94829 -253.881636)
		(width 0.0889)
		(layer "In2.Cu")
		(net "M_C_CPU0_SA_CA<3>")
	)
	(arc
		(start 343.491058 -253.913386)
		(mid 343.23585 -253.956863)
		(end 342.988138 -253.881636)
		(width 0.0889)
		(layer "In2.Cu")
		(net "M_C_CPU0_SA_CA<3>")
	)
	(arc
		(start 331.708252 -253.881636)
		(mid 331.526001 -253.831286)
		(end 331.342492 -253.87681)
		(width 0.0889)
		(layer "In2.Cu")
		(net "M_C_CPU0_SA_CA<3>")
	)
	(arc
		(start 338.27974 -253.87681)
		(mid 338.096232 -253.831316)
		(end 337.91398 -253.881636)
		(width 0.0889)
		(layer "In2.Cu")
		(net "M_C_CPU0_SA_CA<3>")
	)
	(arc
		(start 331.33411 -253.881636)
		(mid 331.051154 -253.957813)
		(end 330.768198 -253.881636)
		(width 0.0889)
		(layer "In2.Cu")
		(net "M_C_CPU0_SA_CA<3>")
	)
	(arc
		(start 339.794088 -253.881636)
		(mid 339.511132 -253.957813)
		(end 339.228176 -253.881636)
		(width 0.0889)
		(layer "In2.Cu")
		(net "M_C_CPU0_SA_CA<3>")
	)
	(arc
		(start 329.454002 -253.881636)
		(mid 329.171046 -253.957813)
		(end 328.88809 -253.881636)
		(width 0.0889)
		(layer "In2.Cu")
		(net "M_C_CPU0_SA_CA<3>")
	)
	(segment
		(start 343.737946 -253.660148)
		(end 343.271094 -253.39421)
		(width 0.10668)
		(layer "F.Cu")
		(net "M_C_CPU0_SA_CA<2>")
	)
	(segment
		(start 332.178152 -253.71679)
		(end 332.16977 -253.721616)
		(width 0.0889)
		(layer "In2.Cu")
		(net "M_C_CPU0_SA_CA<2>")
	)
	(segment
		(start 301.943008 -251.309886)
		(end 301.77994 -251.472954)
		(width 0.14478)
		(layer "In2.Cu")
		(net "M_C_CPU0_SA_CA<2>")
	)
	(segment
		(start 342.152478 -253.721616)
		(end 342.144096 -253.71679)
		(width 0.0889)
		(layer "In2.Cu")
		(net "M_C_CPU0_SA_CA<2>")
	)
	(segment
		(start 301.223426 -251.534422)
		(end 301.223426 -251.472954)
		(width 0.14478)
		(layer "In2.Cu")
		(net "M_C_CPU0_SA_CA<2>")
	)
	(segment
		(start 328.992484 -253.721616)
		(end 328.984102 -253.71679)
		(width 0.0889)
		(layer "In2.Cu")
		(net "M_C_CPU0_SA_CA<2>")
	)
	(segment
		(start 297.504612 -251.472954)
		(end 297.504612 -251.526802)
		(width 0.14478)
		(layer "In2.Cu")
		(net "M_C_CPU0_SA_CA<2>")
	)
	(segment
		(start 324.353174 -253.82347)
		(end 324.193154 -253.98349)
		(width 0.0889)
		(layer "In2.Cu")
		(net "M_C_CPU0_SA_CA<2>")
	)
	(segment
		(start 316.180978 -252.66777)
		(end 314.611766 -253.317756)
		(width 0.14478)
		(layer "In2.Cu")
		(net "M_C_CPU0_SA_CA<2>")
	)
	(segment
		(start 341.212424 -253.721616)
		(end 341.204042 -253.71679)
		(width 0.0889)
		(layer "In2.Cu")
		(net "M_C_CPU0_SA_CA<2>")
	)
	(segment
		(start 343.425018 -253.65964)
		(end 343.402666 -253.742952)
		(width 0.0889)
		(layer "In2.Cu")
		(net "M_C_CPU0_SA_CA<2>")
	)
	(segment
		(start 294.953436 -251.309886)
		(end 293.24808 -249.60453)
		(width 0.14478)
		(layer "In2.Cu")
		(net "M_C_CPU0_SA_CA<2>")
	)
	(segment
		(start 320.23431 -252.66777)
		(end 316.180978 -252.66777)
		(width 0.14478)
		(layer "In2.Cu")
		(net "M_C_CPU0_SA_CA<2>")
	)
	(segment
		(start 327.50633 -253.70155)
		(end 327.480168 -253.716536)
		(width 0.0889)
		(layer "In2.Cu")
		(net "M_C_CPU0_SA_CA<2>")
	)
	(segment
		(start 298.780708 -251.309886)
		(end 298.61764 -251.472954)
		(width 0.14478)
		(layer "In2.Cu")
		(net "M_C_CPU0_SA_CA<2>")
	)
	(segment
		(start 301.616872 -251.69749)
		(end 301.386494 -251.69749)
		(width 0.14478)
		(layer "In2.Cu")
		(net "M_C_CPU0_SA_CA<2>")
	)
	(segment
		(start 324.193154 -253.98349)
		(end 323.901054 -253.98349)
		(width 0.0889)
		(layer "In2.Cu")
		(net "M_C_CPU0_SA_CA<2>")
	)
	(segment
		(start 331.238098 -253.71679)
		(end 331.229716 -253.721616)
		(width 0.0889)
		(layer "In2.Cu")
		(net "M_C_CPU0_SA_CA<2>")
	)
	(segment
		(start 297.341544 -251.68987)
		(end 297.111166 -251.68987)
		(width 0.14478)
		(layer "In2.Cu")
		(net "M_C_CPU0_SA_CA<2>")
	)
	(segment
		(start 296.948098 -251.472954)
		(end 296.78503 -251.309886)
		(width 0.14478)
		(layer "In2.Cu")
		(net "M_C_CPU0_SA_CA<2>")
	)
	(segment
		(start 326.19696 -253.734316)
		(end 326.165718 -253.716536)
		(width 0.0889)
		(layer "In2.Cu")
		(net "M_C_CPU0_SA_CA<2>")
	)
	(segment
		(start 326.165718 -253.716536)
		(end 326.139556 -253.70155)
		(width 0.0889)
		(layer "In2.Cu")
		(net "M_C_CPU0_SA_CA<2>")
	)
	(segment
		(start 297.111166 -251.68987)
		(end 296.948098 -251.526802)
		(width 0.14478)
		(layer "In2.Cu")
		(net "M_C_CPU0_SA_CA<2>")
	)
	(segment
		(start 337.452462 -253.721616)
		(end 337.44408 -253.71679)
		(width 0.0889)
		(layer "In2.Cu")
		(net "M_C_CPU0_SA_CA<2>")
	)
	(segment
		(start 333.6925 -253.721616)
		(end 333.684118 -253.71679)
		(width 0.0889)
		(layer "In2.Cu")
		(net "M_C_CPU0_SA_CA<2>")
	)
	(segment
		(start 301.77994 -251.534422)
		(end 301.616872 -251.69749)
		(width 0.14478)
		(layer "In2.Cu")
		(net "M_C_CPU0_SA_CA<2>")
	)
	(segment
		(start 327.10755 -253.71679)
		(end 327.078086 -253.699518)
		(width 0.0889)
		(layer "In2.Cu")
		(net "M_C_CPU0_SA_CA<2>")
	)
	(segment
		(start 296.78503 -251.309886)
		(end 294.953436 -251.309886)
		(width 0.14478)
		(layer "In2.Cu")
		(net "M_C_CPU0_SA_CA<2>")
	)
	(segment
		(start 321.55003 -253.98349)
		(end 320.23431 -252.66777)
		(width 0.14478)
		(layer "In2.Cu")
		(net "M_C_CPU0_SA_CA<2>")
	)
	(segment
		(start 301.77994 -251.472954)
		(end 301.77994 -251.534422)
		(width 0.14478)
		(layer "In2.Cu")
		(net "M_C_CPU0_SA_CA<2>")
	)
	(segment
		(start 310.186832 -253.317756)
		(end 308.178962 -251.309886)
		(width 0.14478)
		(layer "In2.Cu")
		(net "M_C_CPU0_SA_CA<2>")
	)
	(segment
		(start 298.61764 -251.472954)
		(end 298.61764 -251.526802)
		(width 0.14478)
		(layer "In2.Cu")
		(net "M_C_CPU0_SA_CA<2>")
	)
	(segment
		(start 298.224194 -251.68987)
		(end 298.061126 -251.526802)
		(width 0.14478)
		(layer "In2.Cu")
		(net "M_C_CPU0_SA_CA<2>")
	)
	(segment
		(start 328.41819 -253.71679)
		(end 328.409808 -253.721616)
		(width 0.0889)
		(layer "In2.Cu")
		(net "M_C_CPU0_SA_CA<2>")
	)
	(segment
		(start 301.223426 -251.472954)
		(end 301.060358 -251.309886)
		(width 0.14478)
		(layer "In2.Cu")
		(net "M_C_CPU0_SA_CA<2>")
	)
	(segment
		(start 339.698076 -253.71679)
		(end 339.689694 -253.721616)
		(width 0.0889)
		(layer "In2.Cu")
		(net "M_C_CPU0_SA_CA<2>")
	)
	(segment
		(start 301.386494 -251.69749)
		(end 301.223426 -251.534422)
		(width 0.14478)
		(layer "In2.Cu")
		(net "M_C_CPU0_SA_CA<2>")
	)
	(segment
		(start 297.504612 -251.526802)
		(end 297.341544 -251.68987)
		(width 0.14478)
		(layer "In2.Cu")
		(net "M_C_CPU0_SA_CA<2>")
	)
	(segment
		(start 323.901054 -253.98349)
		(end 321.55003 -253.98349)
		(width 0.14478)
		(layer "In2.Cu")
		(net "M_C_CPU0_SA_CA<2>")
	)
	(segment
		(start 332.752446 -253.721616)
		(end 332.744064 -253.71679)
		(width 0.0889)
		(layer "In2.Cu")
		(net "M_C_CPU0_SA_CA<2>")
	)
	(segment
		(start 298.454572 -251.68987)
		(end 298.224194 -251.68987)
		(width 0.14478)
		(layer "In2.Cu")
		(net "M_C_CPU0_SA_CA<2>")
	)
	(segment
		(start 293.24808 -249.60453)
		(end 292.69944 -249.60453)
		(width 0.14478)
		(layer "In2.Cu")
		(net "M_C_CPU0_SA_CA<2>")
	)
	(segment
		(start 325.205598 -253.82347)
		(end 324.353174 -253.82347)
		(width 0.0889)
		(layer "In2.Cu")
		(net "M_C_CPU0_SA_CA<2>")
	)
	(segment
		(start 296.948098 -251.526802)
		(end 296.948098 -251.472954)
		(width 0.14478)
		(layer "In2.Cu")
		(net "M_C_CPU0_SA_CA<2>")
	)
	(segment
		(start 298.61764 -251.526802)
		(end 298.454572 -251.68987)
		(width 0.14478)
		(layer "In2.Cu")
		(net "M_C_CPU0_SA_CA<2>")
	)
	(segment
		(start 343.271094 -253.39421)
		(end 343.425018 -253.65964)
		(width 0.0889)
		(layer "In2.Cu")
		(net "M_C_CPU0_SA_CA<2>")
	)
	(segment
		(start 340.63813 -253.71679)
		(end 340.629748 -253.721616)
		(width 0.0889)
		(layer "In2.Cu")
		(net "M_C_CPU0_SA_CA<2>")
	)
	(segment
		(start 297.898058 -251.309886)
		(end 297.66768 -251.309886)
		(width 0.14478)
		(layer "In2.Cu")
		(net "M_C_CPU0_SA_CA<2>")
	)
	(segment
		(start 327.480168 -253.716536)
		(end 327.458324 -253.728982)
		(width 0.0889)
		(layer "In2.Cu")
		(net "M_C_CPU0_SA_CA<2>")
	)
	(segment
		(start 335.938114 -253.71679)
		(end 335.929732 -253.721616)
		(width 0.0889)
		(layer "In2.Cu")
		(net "M_C_CPU0_SA_CA<2>")
	)
	(segment
		(start 297.66768 -251.309886)
		(end 297.504612 -251.472954)
		(width 0.14478)
		(layer "In2.Cu")
		(net "M_C_CPU0_SA_CA<2>")
	)
	(segment
		(start 298.061126 -251.526802)
		(end 298.061126 -251.472954)
		(width 0.14478)
		(layer "In2.Cu")
		(net "M_C_CPU0_SA_CA<2>")
	)
	(segment
		(start 314.611766 -253.317756)
		(end 310.186832 -253.317756)
		(width 0.14478)
		(layer "In2.Cu")
		(net "M_C_CPU0_SA_CA<2>")
	)
	(segment
		(start 308.178962 -251.309886)
		(end 301.943008 -251.309886)
		(width 0.14478)
		(layer "In2.Cu")
		(net "M_C_CPU0_SA_CA<2>")
	)
	(segment
		(start 292.69944 -249.60453)
		(end 292.280086 -249.185176)
		(width 0.14478)
		(layer "In2.Cu")
		(net "M_C_CPU0_SA_CA<2>")
	)
	(segment
		(start 336.878168 -253.71679)
		(end 336.869786 -253.721616)
		(width 0.0889)
		(layer "In2.Cu")
		(net "M_C_CPU0_SA_CA<2>")
	)
	(segment
		(start 301.060358 -251.309886)
		(end 298.780708 -251.309886)
		(width 0.14478)
		(layer "In2.Cu")
		(net "M_C_CPU0_SA_CA<2>")
	)
	(segment
		(start 298.061126 -251.472954)
		(end 297.898058 -251.309886)
		(width 0.14478)
		(layer "In2.Cu")
		(net "M_C_CPU0_SA_CA<2>")
	)
	(arc
		(start 340.263988 -253.71679)
		(mid 339.981032 -253.640613)
		(end 339.698076 -253.71679)
		(width 0.0889)
		(layer "In2.Cu")
		(net "M_C_CPU0_SA_CA<2>")
	)
	(arc
		(start 329.924156 -253.71679)
		(mid 329.6412 -253.640613)
		(end 329.358244 -253.71679)
		(width 0.0889)
		(layer "In2.Cu")
		(net "M_C_CPU0_SA_CA<2>")
	)
	(arc
		(start 335.929732 -253.721616)
		(mid 335.746224 -253.76711)
		(end 335.563972 -253.71679)
		(width 0.0889)
		(layer "In2.Cu")
		(net "M_C_CPU0_SA_CA<2>")
	)
	(arc
		(start 334.05826 -253.71679)
		(mid 333.876009 -253.76714)
		(end 333.6925 -253.721616)
		(width 0.0889)
		(layer "In2.Cu")
		(net "M_C_CPU0_SA_CA<2>")
	)
	(arc
		(start 338.758022 -253.71679)
		(mid 338.571078 -253.767045)
		(end 338.384134 -253.71679)
		(width 0.0889)
		(layer "In2.Cu")
		(net "M_C_CPU0_SA_CA<2>")
	)
	(arc
		(start 336.504026 -253.71679)
		(mid 336.22107 -253.640613)
		(end 335.938114 -253.71679)
		(width 0.0889)
		(layer "In2.Cu")
		(net "M_C_CPU0_SA_CA<2>")
	)
	(arc
		(start 332.744064 -253.71679)
		(mid 332.461108 -253.640613)
		(end 332.178152 -253.71679)
		(width 0.0889)
		(layer "In2.Cu")
		(net "M_C_CPU0_SA_CA<2>")
	)
	(arc
		(start 342.144096 -253.71679)
		(mid 341.86114 -253.640613)
		(end 341.578184 -253.71679)
		(width 0.0889)
		(layer "In2.Cu")
		(net "M_C_CPU0_SA_CA<2>")
	)
	(arc
		(start 343.402666 -253.742952)
		(mid 343.240477 -253.765687)
		(end 343.08415 -253.71679)
		(width 0.0889)
		(layer "In2.Cu")
		(net "M_C_CPU0_SA_CA<2>")
	)
	(arc
		(start 326.539606 -253.71679)
		(mid 326.370419 -253.767198)
		(end 326.19696 -253.734316)
		(width 0.0889)
		(layer "In2.Cu")
		(net "M_C_CPU0_SA_CA<2>")
	)
	(arc
		(start 342.518238 -253.71679)
		(mid 342.335987 -253.76714)
		(end 342.152478 -253.721616)
		(width 0.0889)
		(layer "In2.Cu")
		(net "M_C_CPU0_SA_CA<2>")
	)
	(arc
		(start 334.99806 -253.71679)
		(mid 334.811116 -253.767045)
		(end 334.624172 -253.71679)
		(width 0.0889)
		(layer "In2.Cu")
		(net "M_C_CPU0_SA_CA<2>")
	)
	(arc
		(start 327.458324 -253.728982)
		(mid 327.281396 -253.76681)
		(end 327.10755 -253.71679)
		(width 0.0889)
		(layer "In2.Cu")
		(net "M_C_CPU0_SA_CA<2>")
	)
	(arc
		(start 328.409808 -253.721616)
		(mid 328.2263 -253.76711)
		(end 328.044048 -253.71679)
		(width 0.0889)
		(layer "In2.Cu")
		(net "M_C_CPU0_SA_CA<2>")
	)
	(arc
		(start 343.08415 -253.71679)
		(mid 342.801194 -253.640613)
		(end 342.518238 -253.71679)
		(width 0.0889)
		(layer "In2.Cu")
		(net "M_C_CPU0_SA_CA<2>")
	)
	(arc
		(start 339.323934 -253.71679)
		(mid 339.040978 -253.640613)
		(end 338.758022 -253.71679)
		(width 0.0889)
		(layer "In2.Cu")
		(net "M_C_CPU0_SA_CA<2>")
	)
	(arc
		(start 330.863956 -253.71679)
		(mid 330.581 -253.640613)
		(end 330.298044 -253.71679)
		(width 0.0889)
		(layer "In2.Cu")
		(net "M_C_CPU0_SA_CA<2>")
	)
	(arc
		(start 333.684118 -253.71679)
		(mid 333.401162 -253.640613)
		(end 333.118206 -253.71679)
		(width 0.0889)
		(layer "In2.Cu")
		(net "M_C_CPU0_SA_CA<2>")
	)
	(arc
		(start 340.629748 -253.721616)
		(mid 340.44624 -253.76711)
		(end 340.263988 -253.71679)
		(width 0.0889)
		(layer "In2.Cu")
		(net "M_C_CPU0_SA_CA<2>")
	)
	(arc
		(start 333.118206 -253.71679)
		(mid 332.935955 -253.76714)
		(end 332.752446 -253.721616)
		(width 0.0889)
		(layer "In2.Cu")
		(net "M_C_CPU0_SA_CA<2>")
	)
	(arc
		(start 326.139556 -253.70155)
		(mid 325.86877 -253.640904)
		(end 325.601838 -253.71679)
		(width 0.0889)
		(layer "In2.Cu")
		(net "M_C_CPU0_SA_CA<2>")
	)
	(arc
		(start 338.384134 -253.71679)
		(mid 338.101178 -253.640613)
		(end 337.818222 -253.71679)
		(width 0.0889)
		(layer "In2.Cu")
		(net "M_C_CPU0_SA_CA<2>")
	)
	(arc
		(start 329.358244 -253.71679)
		(mid 329.175993 -253.76714)
		(end 328.992484 -253.721616)
		(width 0.0889)
		(layer "In2.Cu")
		(net "M_C_CPU0_SA_CA<2>")
	)
	(arc
		(start 331.229716 -253.721616)
		(mid 331.046208 -253.76711)
		(end 330.863956 -253.71679)
		(width 0.0889)
		(layer "In2.Cu")
		(net "M_C_CPU0_SA_CA<2>")
	)
	(arc
		(start 339.689694 -253.721616)
		(mid 339.506186 -253.76711)
		(end 339.323934 -253.71679)
		(width 0.0889)
		(layer "In2.Cu")
		(net "M_C_CPU0_SA_CA<2>")
	)
	(arc
		(start 332.16977 -253.721616)
		(mid 331.986262 -253.76711)
		(end 331.80401 -253.71679)
		(width 0.0889)
		(layer "In2.Cu")
		(net "M_C_CPU0_SA_CA<2>")
	)
	(arc
		(start 337.44408 -253.71679)
		(mid 337.161124 -253.640613)
		(end 336.878168 -253.71679)
		(width 0.0889)
		(layer "In2.Cu")
		(net "M_C_CPU0_SA_CA<2>")
	)
	(arc
		(start 334.624172 -253.71679)
		(mid 334.341216 -253.640613)
		(end 334.05826 -253.71679)
		(width 0.0889)
		(layer "In2.Cu")
		(net "M_C_CPU0_SA_CA<2>")
	)
	(arc
		(start 337.818222 -253.71679)
		(mid 337.635971 -253.76714)
		(end 337.452462 -253.721616)
		(width 0.0889)
		(layer "In2.Cu")
		(net "M_C_CPU0_SA_CA<2>")
	)
	(arc
		(start 330.298044 -253.71679)
		(mid 330.1111 -253.767045)
		(end 329.924156 -253.71679)
		(width 0.0889)
		(layer "In2.Cu")
		(net "M_C_CPU0_SA_CA<2>")
	)
	(arc
		(start 341.578184 -253.71679)
		(mid 341.395933 -253.76714)
		(end 341.212424 -253.721616)
		(width 0.0889)
		(layer "In2.Cu")
		(net "M_C_CPU0_SA_CA<2>")
	)
	(arc
		(start 328.984102 -253.71679)
		(mid 328.701146 -253.640613)
		(end 328.41819 -253.71679)
		(width 0.0889)
		(layer "In2.Cu")
		(net "M_C_CPU0_SA_CA<2>")
	)
	(arc
		(start 341.204042 -253.71679)
		(mid 340.921086 -253.640613)
		(end 340.63813 -253.71679)
		(width 0.0889)
		(layer "In2.Cu")
		(net "M_C_CPU0_SA_CA<2>")
	)
	(arc
		(start 331.80401 -253.71679)
		(mid 331.521054 -253.640613)
		(end 331.238098 -253.71679)
		(width 0.0889)
		(layer "In2.Cu")
		(net "M_C_CPU0_SA_CA<2>")
	)
	(arc
		(start 336.869786 -253.721616)
		(mid 336.686278 -253.76711)
		(end 336.504026 -253.71679)
		(width 0.0889)
		(layer "In2.Cu")
		(net "M_C_CPU0_SA_CA<2>")
	)
	(arc
		(start 327.078086 -253.699518)
		(mid 326.806666 -253.639841)
		(end 326.539606 -253.71679)
		(width 0.0889)
		(layer "In2.Cu")
		(net "M_C_CPU0_SA_CA<2>")
	)
	(arc
		(start 328.044048 -253.71679)
		(mid 327.777118 -253.640841)
		(end 327.50633 -253.70155)
		(width 0.0889)
		(layer "In2.Cu")
		(net "M_C_CPU0_SA_CA<2>")
	)
	(arc
		(start 335.563972 -253.71679)
		(mid 335.281016 -253.640613)
		(end 334.99806 -253.71679)
		(width 0.0889)
		(layer "In2.Cu")
		(net "M_C_CPU0_SA_CA<2>")
	)
	(arc
		(start 325.601838 -253.71679)
		(mid 325.410773 -253.796337)
		(end 325.205598 -253.82347)
		(width 0.0889)
		(layer "In2.Cu")
		(net "M_C_CPU0_SA_CA<2>")
	)
	(segment
		(start 342.797892 -253.660148)
		(end 342.33104 -253.39421)
		(width 0.10668)
		(layer "F.Cu")
		(net "M_C_CPU0_SA_CA<1>")
	)
	(segment
		(start 293.239444 -248.75998)
		(end 288.60496 -248.75998)
		(width 0.14478)
		(layer "In2.Cu")
		(net "M_C_CPU0_SA_CA<1>")
	)
	(segment
		(start 294.939466 -250.460002)
		(end 293.239444 -248.75998)
		(width 0.14478)
		(layer "In2.Cu")
		(net "M_C_CPU0_SA_CA<1>")
	)
	(segment
		(start 326.163686 -253.07163)
		(end 325.89597 -253.226824)
		(width 0.0889)
		(layer "In2.Cu")
		(net "M_C_CPU0_SA_CA<1>")
	)
	(segment
		(start 341.212424 -253.066804)
		(end 341.204042 -253.07163)
		(width 0.0889)
		(layer "In2.Cu")
		(net "M_C_CPU0_SA_CA<1>")
	)
	(segment
		(start 333.6925 -253.066804)
		(end 333.684118 -253.07163)
		(width 0.0889)
		(layer "In2.Cu")
		(net "M_C_CPU0_SA_CA<1>")
	)
	(segment
		(start 324.835774 -253.512066)
		(end 323.906134 -253.512066)
		(width 0.0889)
		(layer "In2.Cu")
		(net "M_C_CPU0_SA_CA<1>")
	)
	(segment
		(start 339.698076 -253.07163)
		(end 339.689694 -253.066804)
		(width 0.0889)
		(layer "In2.Cu")
		(net "M_C_CPU0_SA_CA<1>")
	)
	(segment
		(start 337.452462 -253.066804)
		(end 337.44408 -253.07163)
		(width 0.0889)
		(layer "In2.Cu")
		(net "M_C_CPU0_SA_CA<1>")
	)
	(segment
		(start 320.422778 -252.21311)
		(end 316.103508 -252.21311)
		(width 0.14478)
		(layer "In2.Cu")
		(net "M_C_CPU0_SA_CA<1>")
	)
	(segment
		(start 335.938114 -253.07163)
		(end 335.929732 -253.066804)
		(width 0.0889)
		(layer "In2.Cu")
		(net "M_C_CPU0_SA_CA<1>")
	)
	(segment
		(start 310.615076 -252.868176)
		(end 308.206902 -250.460002)
		(width 0.14478)
		(layer "In2.Cu")
		(net "M_C_CPU0_SA_CA<1>")
	)
	(segment
		(start 288.60496 -248.75998)
		(end 288.180018 -248.335038)
		(width 0.14478)
		(layer "In2.Cu")
		(net "M_C_CPU0_SA_CA<1>")
	)
	(segment
		(start 328.992484 -253.066804)
		(end 328.984102 -253.07163)
		(width 0.0889)
		(layer "In2.Cu")
		(net "M_C_CPU0_SA_CA<1>")
	)
	(segment
		(start 323.906134 -253.512066)
		(end 321.721734 -253.512066)
		(width 0.14478)
		(layer "In2.Cu")
		(net "M_C_CPU0_SA_CA<1>")
	)
	(segment
		(start 327.114916 -253.064772)
		(end 327.103232 -253.07163)
		(width 0.0889)
		(layer "In2.Cu")
		(net "M_C_CPU0_SA_CA<1>")
	)
	(segment
		(start 314.52185 -252.868176)
		(end 310.615076 -252.868176)
		(width 0.14478)
		(layer "In2.Cu")
		(net "M_C_CPU0_SA_CA<1>")
	)
	(segment
		(start 336.878168 -253.07163)
		(end 336.869786 -253.066804)
		(width 0.0889)
		(layer "In2.Cu")
		(net "M_C_CPU0_SA_CA<1>")
	)
	(segment
		(start 340.63813 -253.07163)
		(end 340.629748 -253.066804)
		(width 0.0889)
		(layer "In2.Cu")
		(net "M_C_CPU0_SA_CA<1>")
	)
	(segment
		(start 342.33104 -253.39421)
		(end 342.177116 -253.12878)
		(width 0.0889)
		(layer "In2.Cu")
		(net "M_C_CPU0_SA_CA<1>")
	)
	(segment
		(start 326.543416 -253.075186)
		(end 326.537828 -253.071884)
		(width 0.0889)
		(layer "In2.Cu")
		(net "M_C_CPU0_SA_CA<1>")
	)
	(segment
		(start 342.177116 -253.12878)
		(end 342.081104 -253.10338)
		(width 0.0889)
		(layer "In2.Cu")
		(net "M_C_CPU0_SA_CA<1>")
	)
	(segment
		(start 331.238098 -253.07163)
		(end 331.229716 -253.066804)
		(width 0.0889)
		(layer "In2.Cu")
		(net "M_C_CPU0_SA_CA<1>")
	)
	(segment
		(start 332.178152 -253.07163)
		(end 332.16977 -253.066804)
		(width 0.0889)
		(layer "In2.Cu")
		(net "M_C_CPU0_SA_CA<1>")
	)
	(segment
		(start 326.537828 -253.071884)
		(end 326.51954 -253.06147)
		(width 0.0889)
		(layer "In2.Cu")
		(net "M_C_CPU0_SA_CA<1>")
	)
	(segment
		(start 316.103508 -252.21311)
		(end 314.52185 -252.868176)
		(width 0.14478)
		(layer "In2.Cu")
		(net "M_C_CPU0_SA_CA<1>")
	)
	(segment
		(start 328.044048 -253.07163)
		(end 328.029316 -253.080266)
		(width 0.0889)
		(layer "In2.Cu")
		(net "M_C_CPU0_SA_CA<1>")
	)
	(segment
		(start 332.752446 -253.066804)
		(end 332.744064 -253.07163)
		(width 0.0889)
		(layer "In2.Cu")
		(net "M_C_CPU0_SA_CA<1>")
	)
	(segment
		(start 308.206902 -250.460002)
		(end 294.939466 -250.460002)
		(width 0.14478)
		(layer "In2.Cu")
		(net "M_C_CPU0_SA_CA<1>")
	)
	(segment
		(start 321.721734 -253.512066)
		(end 320.422778 -252.21311)
		(width 0.14478)
		(layer "In2.Cu")
		(net "M_C_CPU0_SA_CA<1>")
	)
	(segment
		(start 328.41819 -253.07163)
		(end 328.409808 -253.066804)
		(width 0.0889)
		(layer "In2.Cu")
		(net "M_C_CPU0_SA_CA<1>")
	)
	(arc
		(start 328.409808 -253.066804)
		(mid 328.2263 -253.02131)
		(end 328.044048 -253.07163)
		(width 0.0889)
		(layer "In2.Cu")
		(net "M_C_CPU0_SA_CA<1>")
	)
	(arc
		(start 340.263988 -253.07163)
		(mid 339.981032 -253.147807)
		(end 339.698076 -253.07163)
		(width 0.0889)
		(layer "In2.Cu")
		(net "M_C_CPU0_SA_CA<1>")
	)
	(arc
		(start 331.229716 -253.066804)
		(mid 331.046208 -253.02131)
		(end 330.863956 -253.07163)
		(width 0.0889)
		(layer "In2.Cu")
		(net "M_C_CPU0_SA_CA<1>")
	)
	(arc
		(start 336.504026 -253.07163)
		(mid 336.22107 -253.147807)
		(end 335.938114 -253.07163)
		(width 0.0889)
		(layer "In2.Cu")
		(net "M_C_CPU0_SA_CA<1>")
	)
	(arc
		(start 330.298044 -253.07163)
		(mid 330.1111 -253.021375)
		(end 329.924156 -253.07163)
		(width 0.0889)
		(layer "In2.Cu")
		(net "M_C_CPU0_SA_CA<1>")
	)
	(arc
		(start 335.929732 -253.066804)
		(mid 335.746224 -253.02131)
		(end 335.563972 -253.07163)
		(width 0.0889)
		(layer "In2.Cu")
		(net "M_C_CPU0_SA_CA<1>")
	)
	(arc
		(start 337.818222 -253.07163)
		(mid 337.635971 -253.02128)
		(end 337.452462 -253.066804)
		(width 0.0889)
		(layer "In2.Cu")
		(net "M_C_CPU0_SA_CA<1>")
	)
	(arc
		(start 332.16977 -253.066804)
		(mid 331.986262 -253.02131)
		(end 331.80401 -253.07163)
		(width 0.0889)
		(layer "In2.Cu")
		(net "M_C_CPU0_SA_CA<1>")
	)
	(arc
		(start 327.477628 -253.07163)
		(mid 327.29717 -253.021186)
		(end 327.114916 -253.064772)
		(width 0.0889)
		(layer "In2.Cu")
		(net "M_C_CPU0_SA_CA<1>")
	)
	(arc
		(start 333.118206 -253.07163)
		(mid 332.935955 -253.02128)
		(end 332.752446 -253.066804)
		(width 0.0889)
		(layer "In2.Cu")
		(net "M_C_CPU0_SA_CA<1>")
	)
	(arc
		(start 328.984102 -253.07163)
		(mid 328.701146 -253.147807)
		(end 328.41819 -253.07163)
		(width 0.0889)
		(layer "In2.Cu")
		(net "M_C_CPU0_SA_CA<1>")
	)
	(arc
		(start 331.80401 -253.07163)
		(mid 331.521054 -253.147807)
		(end 331.238098 -253.07163)
		(width 0.0889)
		(layer "In2.Cu")
		(net "M_C_CPU0_SA_CA<1>")
	)
	(arc
		(start 337.44408 -253.07163)
		(mid 337.161124 -253.147807)
		(end 336.878168 -253.07163)
		(width 0.0889)
		(layer "In2.Cu")
		(net "M_C_CPU0_SA_CA<1>")
	)
	(arc
		(start 334.624172 -253.07163)
		(mid 334.341216 -253.147807)
		(end 334.05826 -253.07163)
		(width 0.0889)
		(layer "In2.Cu")
		(net "M_C_CPU0_SA_CA<1>")
	)
	(arc
		(start 329.924156 -253.07163)
		(mid 329.6412 -253.147807)
		(end 329.358244 -253.07163)
		(width 0.0889)
		(layer "In2.Cu")
		(net "M_C_CPU0_SA_CA<1>")
	)
	(arc
		(start 339.689694 -253.066804)
		(mid 339.506186 -253.02131)
		(end 339.323934 -253.07163)
		(width 0.0889)
		(layer "In2.Cu")
		(net "M_C_CPU0_SA_CA<1>")
	)
	(arc
		(start 334.05826 -253.07163)
		(mid 333.876009 -253.02128)
		(end 333.6925 -253.066804)
		(width 0.0889)
		(layer "In2.Cu")
		(net "M_C_CPU0_SA_CA<1>")
	)
	(arc
		(start 334.99806 -253.07163)
		(mid 334.811116 -253.021375)
		(end 334.624172 -253.07163)
		(width 0.0889)
		(layer "In2.Cu")
		(net "M_C_CPU0_SA_CA<1>")
	)
	(arc
		(start 325.89597 -253.226824)
		(mid 325.384716 -253.439472)
		(end 324.835774 -253.512066)
		(width 0.0889)
		(layer "In2.Cu")
		(net "M_C_CPU0_SA_CA<1>")
	)
	(arc
		(start 333.684118 -253.07163)
		(mid 333.401162 -253.147807)
		(end 333.118206 -253.07163)
		(width 0.0889)
		(layer "In2.Cu")
		(net "M_C_CPU0_SA_CA<1>")
	)
	(arc
		(start 339.323934 -253.07163)
		(mid 339.040978 -253.147807)
		(end 338.758022 -253.07163)
		(width 0.0889)
		(layer "In2.Cu")
		(net "M_C_CPU0_SA_CA<1>")
	)
	(arc
		(start 328.029316 -253.080266)
		(mid 327.752333 -253.14807)
		(end 327.477628 -253.07163)
		(width 0.0889)
		(layer "In2.Cu")
		(net "M_C_CPU0_SA_CA<1>")
	)
	(arc
		(start 327.103232 -253.07163)
		(mid 326.823804 -253.147796)
		(end 326.543416 -253.075186)
		(width 0.0889)
		(layer "In2.Cu")
		(net "M_C_CPU0_SA_CA<1>")
	)
	(arc
		(start 342.081104 -253.10338)
		(mid 341.825896 -253.146857)
		(end 341.578184 -253.07163)
		(width 0.0889)
		(layer "In2.Cu")
		(net "M_C_CPU0_SA_CA<1>")
	)
	(arc
		(start 335.563972 -253.07163)
		(mid 335.281016 -253.147807)
		(end 334.99806 -253.07163)
		(width 0.0889)
		(layer "In2.Cu")
		(net "M_C_CPU0_SA_CA<1>")
	)
	(arc
		(start 338.758022 -253.07163)
		(mid 338.571078 -253.021375)
		(end 338.384134 -253.07163)
		(width 0.0889)
		(layer "In2.Cu")
		(net "M_C_CPU0_SA_CA<1>")
	)
	(arc
		(start 326.51954 -253.06147)
		(mid 326.340311 -253.021317)
		(end 326.163686 -253.07163)
		(width 0.0889)
		(layer "In2.Cu")
		(net "M_C_CPU0_SA_CA<1>")
	)
	(arc
		(start 330.863956 -253.07163)
		(mid 330.581 -253.147807)
		(end 330.298044 -253.07163)
		(width 0.0889)
		(layer "In2.Cu")
		(net "M_C_CPU0_SA_CA<1>")
	)
	(arc
		(start 340.629748 -253.066804)
		(mid 340.44624 -253.02131)
		(end 340.263988 -253.07163)
		(width 0.0889)
		(layer "In2.Cu")
		(net "M_C_CPU0_SA_CA<1>")
	)
	(arc
		(start 336.869786 -253.066804)
		(mid 336.686278 -253.02131)
		(end 336.504026 -253.07163)
		(width 0.0889)
		(layer "In2.Cu")
		(net "M_C_CPU0_SA_CA<1>")
	)
	(arc
		(start 341.578184 -253.07163)
		(mid 341.395933 -253.02128)
		(end 341.212424 -253.066804)
		(width 0.0889)
		(layer "In2.Cu")
		(net "M_C_CPU0_SA_CA<1>")
	)
	(arc
		(start 332.744064 -253.07163)
		(mid 332.461108 -253.147807)
		(end 332.178152 -253.07163)
		(width 0.0889)
		(layer "In2.Cu")
		(net "M_C_CPU0_SA_CA<1>")
	)
	(arc
		(start 329.358244 -253.07163)
		(mid 329.175993 -253.02128)
		(end 328.992484 -253.066804)
		(width 0.0889)
		(layer "In2.Cu")
		(net "M_C_CPU0_SA_CA<1>")
	)
	(arc
		(start 341.204042 -253.07163)
		(mid 340.921086 -253.147807)
		(end 340.63813 -253.07163)
		(width 0.0889)
		(layer "In2.Cu")
		(net "M_C_CPU0_SA_CA<1>")
	)
	(arc
		(start 338.384134 -253.07163)
		(mid 338.101178 -253.147807)
		(end 337.818222 -253.07163)
		(width 0.0889)
		(layer "In2.Cu")
		(net "M_C_CPU0_SA_CA<1>")
	)
	(segment
		(start 342.327992 -252.850142)
		(end 341.86114 -252.584204)
		(width 0.10668)
		(layer "F.Cu")
		(net "M_C_CPU0_SA_CA<0>")
	)
	(segment
		(start 323.883274 -253.05385)
		(end 321.906646 -253.05385)
		(width 0.14478)
		(layer "In2.Cu")
		(net "M_C_CPU0_SA_CA<0>")
	)
	(segment
		(start 297.378628 -249.830082)
		(end 297.21556 -249.99315)
		(width 0.14478)
		(layer "In2.Cu")
		(net "M_C_CPU0_SA_CA<0>")
	)
	(segment
		(start 330.402438 -252.91161)
		(end 330.394056 -252.906784)
		(width 0.0889)
		(layer "In2.Cu")
		(net "M_C_CPU0_SA_CA<0>")
	)
	(segment
		(start 301.397924 -249.610118)
		(end 301.167546 -249.610118)
		(width 0.14478)
		(layer "In2.Cu")
		(net "M_C_CPU0_SA_CA<0>")
	)
	(segment
		(start 298.328588 -249.99315)
		(end 298.09821 -249.99315)
		(width 0.14478)
		(layer "In2.Cu")
		(net "M_C_CPU0_SA_CA<0>")
	)
	(segment
		(start 334.52816 -252.906784)
		(end 334.519778 -252.91161)
		(width 0.0889)
		(layer "In2.Cu")
		(net "M_C_CPU0_SA_CA<0>")
	)
	(segment
		(start 306.365148 -249.773186)
		(end 306.365148 -249.837702)
		(width 0.14478)
		(layer "In2.Cu")
		(net "M_C_CPU0_SA_CA<0>")
	)
	(segment
		(start 301.167546 -249.610118)
		(end 301.004478 -249.773186)
		(width 0.14478)
		(layer "In2.Cu")
		(net "M_C_CPU0_SA_CA<0>")
	)
	(segment
		(start 331.342492 -252.91161)
		(end 331.33411 -252.906784)
		(width 0.0889)
		(layer "In2.Cu")
		(net "M_C_CPU0_SA_CA<0>")
	)
	(segment
		(start 305.25212 -249.837702)
		(end 305.089052 -250.00077)
		(width 0.14478)
		(layer "In2.Cu")
		(net "M_C_CPU0_SA_CA<0>")
	)
	(segment
		(start 297.541696 -249.610118)
		(end 297.378628 -249.773186)
		(width 0.14478)
		(layer "In2.Cu")
		(net "M_C_CPU0_SA_CA<0>")
	)
	(segment
		(start 297.935142 -249.773186)
		(end 297.772074 -249.610118)
		(width 0.14478)
		(layer "In2.Cu")
		(net "M_C_CPU0_SA_CA<0>")
	)
	(segment
		(start 327.021952 -252.898148)
		(end 327.00722 -252.906784)
		(width 0.0889)
		(layer "In2.Cu")
		(net "M_C_CPU0_SA_CA<0>")
	)
	(segment
		(start 301.004478 -249.773186)
		(end 301.004478 -249.822462)
		(width 0.14478)
		(layer "In2.Cu")
		(net "M_C_CPU0_SA_CA<0>")
	)
	(segment
		(start 306.20208 -250.00077)
		(end 305.971702 -250.00077)
		(width 0.14478)
		(layer "In2.Cu")
		(net "M_C_CPU0_SA_CA<0>")
	)
	(segment
		(start 333.588106 -252.906784)
		(end 333.579724 -252.91161)
		(width 0.0889)
		(layer "In2.Cu")
		(net "M_C_CPU0_SA_CA<0>")
	)
	(segment
		(start 320.611246 -251.75845)
		(end 316.026038 -251.75845)
		(width 0.14478)
		(layer "In2.Cu")
		(net "M_C_CPU0_SA_CA<0>")
	)
	(segment
		(start 324.924928 -253.214886)
		(end 324.470776 -253.214886)
		(width 0.0889)
		(layer "In2.Cu")
		(net "M_C_CPU0_SA_CA<0>")
	)
	(segment
		(start 302.280574 -249.610118)
		(end 302.117506 -249.773186)
		(width 0.14478)
		(layer "In2.Cu")
		(net "M_C_CPU0_SA_CA<0>")
	)
	(segment
		(start 300.447964 -249.773186)
		(end 300.284896 -249.610118)
		(width 0.14478)
		(layer "In2.Cu")
		(net "M_C_CPU0_SA_CA<0>")
	)
	(segment
		(start 301.004478 -249.822462)
		(end 300.84141 -249.98553)
		(width 0.14478)
		(layer "In2.Cu")
		(net "M_C_CPU0_SA_CA<0>")
	)
	(segment
		(start 293.172134 -247.90273)
		(end 292.697662 -247.90273)
		(width 0.14478)
		(layer "In2.Cu")
		(net "M_C_CPU0_SA_CA<0>")
	)
	(segment
		(start 294.879522 -249.610118)
		(end 293.172134 -247.90273)
		(width 0.14478)
		(layer "In2.Cu")
		(net "M_C_CPU0_SA_CA<0>")
	)
	(segment
		(start 301.954438 -249.98553)
		(end 301.72406 -249.98553)
		(width 0.14478)
		(layer "In2.Cu")
		(net "M_C_CPU0_SA_CA<0>")
	)
	(segment
		(start 298.491656 -249.830082)
		(end 298.328588 -249.99315)
		(width 0.14478)
		(layer "In2.Cu")
		(net "M_C_CPU0_SA_CA<0>")
	)
	(segment
		(start 296.822114 -249.773186)
		(end 296.659046 -249.610118)
		(width 0.14478)
		(layer "In2.Cu")
		(net "M_C_CPU0_SA_CA<0>")
	)
	(segment
		(start 306.528216 -249.610118)
		(end 306.365148 -249.773186)
		(width 0.14478)
		(layer "In2.Cu")
		(net "M_C_CPU0_SA_CA<0>")
	)
	(segment
		(start 339.80247 -252.91161)
		(end 339.794088 -252.906784)
		(width 0.0889)
		(layer "In2.Cu")
		(net "M_C_CPU0_SA_CA<0>")
	)
	(segment
		(start 298.654724 -249.610118)
		(end 298.491656 -249.773186)
		(width 0.14478)
		(layer "In2.Cu")
		(net "M_C_CPU0_SA_CA<0>")
	)
	(segment
		(start 301.560992 -249.822462)
		(end 301.560992 -249.773186)
		(width 0.14478)
		(layer "In2.Cu")
		(net "M_C_CPU0_SA_CA<0>")
	)
	(segment
		(start 296.659046 -249.610118)
		(end 294.879522 -249.610118)
		(width 0.14478)
		(layer "In2.Cu")
		(net "M_C_CPU0_SA_CA<0>")
	)
	(segment
		(start 300.611032 -249.98553)
		(end 300.447964 -249.822462)
		(width 0.14478)
		(layer "In2.Cu")
		(net "M_C_CPU0_SA_CA<0>")
	)
	(segment
		(start 292.697662 -247.90273)
		(end 292.280086 -247.485154)
		(width 0.14478)
		(layer "In2.Cu")
		(net "M_C_CPU0_SA_CA<0>")
	)
	(segment
		(start 302.117506 -249.773186)
		(end 302.117506 -249.822462)
		(width 0.14478)
		(layer "In2.Cu")
		(net "M_C_CPU0_SA_CA<0>")
	)
	(segment
		(start 296.985182 -249.99315)
		(end 296.822114 -249.830082)
		(width 0.14478)
		(layer "In2.Cu")
		(net "M_C_CPU0_SA_CA<0>")
	)
	(segment
		(start 338.288122 -252.906784)
		(end 338.27974 -252.91161)
		(width 0.0889)
		(layer "In2.Cu")
		(net "M_C_CPU0_SA_CA<0>")
	)
	(segment
		(start 297.772074 -249.610118)
		(end 297.541696 -249.610118)
		(width 0.14478)
		(layer "In2.Cu")
		(net "M_C_CPU0_SA_CA<0>")
	)
	(segment
		(start 305.808634 -249.837702)
		(end 305.808634 -249.773186)
		(width 0.14478)
		(layer "In2.Cu")
		(net "M_C_CPU0_SA_CA<0>")
	)
	(segment
		(start 305.089052 -250.00077)
		(end 304.858674 -250.00077)
		(width 0.14478)
		(layer "In2.Cu")
		(net "M_C_CPU0_SA_CA<0>")
	)
	(segment
		(start 336.042508 -252.91161)
		(end 336.034126 -252.906784)
		(width 0.0889)
		(layer "In2.Cu")
		(net "M_C_CPU0_SA_CA<0>")
	)
	(segment
		(start 329.828144 -252.906784)
		(end 329.819762 -252.91161)
		(width 0.0889)
		(layer "In2.Cu")
		(net "M_C_CPU0_SA_CA<0>")
	)
	(segment
		(start 305.971702 -250.00077)
		(end 305.808634 -249.837702)
		(width 0.14478)
		(layer "In2.Cu")
		(net "M_C_CPU0_SA_CA<0>")
	)
	(segment
		(start 300.284896 -249.610118)
		(end 298.654724 -249.610118)
		(width 0.14478)
		(layer "In2.Cu")
		(net "M_C_CPU0_SA_CA<0>")
	)
	(segment
		(start 296.822114 -249.830082)
		(end 296.822114 -249.773186)
		(width 0.14478)
		(layer "In2.Cu")
		(net "M_C_CPU0_SA_CA<0>")
	)
	(segment
		(start 300.447964 -249.822462)
		(end 300.447964 -249.773186)
		(width 0.14478)
		(layer "In2.Cu")
		(net "M_C_CPU0_SA_CA<0>")
	)
	(segment
		(start 298.491656 -249.773186)
		(end 298.491656 -249.830082)
		(width 0.14478)
		(layer "In2.Cu")
		(net "M_C_CPU0_SA_CA<0>")
	)
	(segment
		(start 307.993034 -249.610118)
		(end 306.528216 -249.610118)
		(width 0.14478)
		(layer "In2.Cu")
		(net "M_C_CPU0_SA_CA<0>")
	)
	(segment
		(start 297.378628 -249.773186)
		(end 297.378628 -249.830082)
		(width 0.14478)
		(layer "In2.Cu")
		(net "M_C_CPU0_SA_CA<0>")
	)
	(segment
		(start 327.94829 -252.906784)
		(end 327.939908 -252.91161)
		(width 0.0889)
		(layer "In2.Cu")
		(net "M_C_CPU0_SA_CA<0>")
	)
	(segment
		(start 316.026038 -251.75845)
		(end 314.432188 -252.418596)
		(width 0.14478)
		(layer "In2.Cu")
		(net "M_C_CPU0_SA_CA<0>")
	)
	(segment
		(start 338.862416 -252.91161)
		(end 338.854034 -252.906784)
		(width 0.0889)
		(layer "In2.Cu")
		(net "M_C_CPU0_SA_CA<0>")
	)
	(segment
		(start 304.532538 -249.610118)
		(end 302.280574 -249.610118)
		(width 0.14478)
		(layer "In2.Cu")
		(net "M_C_CPU0_SA_CA<0>")
	)
	(segment
		(start 324.470776 -253.214886)
		(end 324.30974 -253.05385)
		(width 0.0889)
		(layer "In2.Cu")
		(net "M_C_CPU0_SA_CA<0>")
	)
	(segment
		(start 305.645566 -249.610118)
		(end 305.415188 -249.610118)
		(width 0.14478)
		(layer "In2.Cu")
		(net "M_C_CPU0_SA_CA<0>")
	)
	(segment
		(start 304.695606 -249.837702)
		(end 304.695606 -249.773186)
		(width 0.14478)
		(layer "In2.Cu")
		(net "M_C_CPU0_SA_CA<0>")
	)
	(segment
		(start 301.560992 -249.773186)
		(end 301.397924 -249.610118)
		(width 0.14478)
		(layer "In2.Cu")
		(net "M_C_CPU0_SA_CA<0>")
	)
	(segment
		(start 314.432188 -252.418596)
		(end 310.801512 -252.418596)
		(width 0.14478)
		(layer "In2.Cu")
		(net "M_C_CPU0_SA_CA<0>")
	)
	(segment
		(start 342.015064 -252.849634)
		(end 341.992712 -252.932946)
		(width 0.0889)
		(layer "In2.Cu")
		(net "M_C_CPU0_SA_CA<0>")
	)
	(segment
		(start 305.25212 -249.773186)
		(end 305.25212 -249.837702)
		(width 0.14478)
		(layer "In2.Cu")
		(net "M_C_CPU0_SA_CA<0>")
	)
	(segment
		(start 304.858674 -250.00077)
		(end 304.695606 -249.837702)
		(width 0.14478)
		(layer "In2.Cu")
		(net "M_C_CPU0_SA_CA<0>")
	)
	(segment
		(start 341.86114 -252.584204)
		(end 342.015064 -252.849634)
		(width 0.0889)
		(layer "In2.Cu")
		(net "M_C_CPU0_SA_CA<0>")
	)
	(segment
		(start 305.808634 -249.773186)
		(end 305.645566 -249.610118)
		(width 0.14478)
		(layer "In2.Cu")
		(net "M_C_CPU0_SA_CA<0>")
	)
	(segment
		(start 300.84141 -249.98553)
		(end 300.611032 -249.98553)
		(width 0.14478)
		(layer "In2.Cu")
		(net "M_C_CPU0_SA_CA<0>")
	)
	(segment
		(start 305.415188 -249.610118)
		(end 305.25212 -249.773186)
		(width 0.14478)
		(layer "In2.Cu")
		(net "M_C_CPU0_SA_CA<0>")
	)
	(segment
		(start 324.30974 -253.05385)
		(end 323.883274 -253.05385)
		(width 0.0889)
		(layer "In2.Cu")
		(net "M_C_CPU0_SA_CA<0>")
	)
	(segment
		(start 304.695606 -249.773186)
		(end 304.532538 -249.610118)
		(width 0.14478)
		(layer "In2.Cu")
		(net "M_C_CPU0_SA_CA<0>")
	)
	(segment
		(start 306.365148 -249.837702)
		(end 306.20208 -250.00077)
		(width 0.14478)
		(layer "In2.Cu")
		(net "M_C_CPU0_SA_CA<0>")
	)
	(segment
		(start 326.647302 -252.914404)
		(end 326.633586 -252.90653)
		(width 0.0889)
		(layer "In2.Cu")
		(net "M_C_CPU0_SA_CA<0>")
	)
	(segment
		(start 335.102454 -252.91161)
		(end 335.094072 -252.906784)
		(width 0.0889)
		(layer "In2.Cu")
		(net "M_C_CPU0_SA_CA<0>")
	)
	(segment
		(start 301.72406 -249.98553)
		(end 301.560992 -249.822462)
		(width 0.14478)
		(layer "In2.Cu")
		(net "M_C_CPU0_SA_CA<0>")
	)
	(segment
		(start 321.906646 -253.05385)
		(end 320.611246 -251.75845)
		(width 0.14478)
		(layer "In2.Cu")
		(net "M_C_CPU0_SA_CA<0>")
	)
	(segment
		(start 302.117506 -249.822462)
		(end 301.954438 -249.98553)
		(width 0.14478)
		(layer "In2.Cu")
		(net "M_C_CPU0_SA_CA<0>")
	)
	(segment
		(start 298.09821 -249.99315)
		(end 297.935142 -249.830082)
		(width 0.14478)
		(layer "In2.Cu")
		(net "M_C_CPU0_SA_CA<0>")
	)
	(segment
		(start 310.801512 -252.418596)
		(end 307.993034 -249.610118)
		(width 0.14478)
		(layer "In2.Cu")
		(net "M_C_CPU0_SA_CA<0>")
	)
	(segment
		(start 297.935142 -249.830082)
		(end 297.935142 -249.773186)
		(width 0.14478)
		(layer "In2.Cu")
		(net "M_C_CPU0_SA_CA<0>")
	)
	(segment
		(start 326.633586 -252.90653)
		(end 326.617838 -252.897386)
		(width 0.0889)
		(layer "In2.Cu")
		(net "M_C_CPU0_SA_CA<0>")
	)
	(segment
		(start 297.21556 -249.99315)
		(end 296.985182 -249.99315)
		(width 0.14478)
		(layer "In2.Cu")
		(net "M_C_CPU0_SA_CA<0>")
	)
	(arc
		(start 336.034126 -252.906784)
		(mid 335.75117 -252.830607)
		(end 335.468214 -252.906784)
		(width 0.0889)
		(layer "In2.Cu")
		(net "M_C_CPU0_SA_CA<0>")
	)
	(arc
		(start 333.579724 -252.91161)
		(mid 333.396216 -252.957104)
		(end 333.213964 -252.906784)
		(width 0.0889)
		(layer "In2.Cu")
		(net "M_C_CPU0_SA_CA<0>")
	)
	(arc
		(start 339.228176 -252.906784)
		(mid 339.045925 -252.957134)
		(end 338.862416 -252.91161)
		(width 0.0889)
		(layer "In2.Cu")
		(net "M_C_CPU0_SA_CA<0>")
	)
	(arc
		(start 334.154018 -252.906784)
		(mid 333.871062 -252.830607)
		(end 333.588106 -252.906784)
		(width 0.0889)
		(layer "In2.Cu")
		(net "M_C_CPU0_SA_CA<0>")
	)
	(arc
		(start 326.067674 -252.906784)
		(mid 325.516708 -253.136531)
		(end 324.924928 -253.214886)
		(width 0.0889)
		(layer "In2.Cu")
		(net "M_C_CPU0_SA_CA<0>")
	)
	(arc
		(start 333.213964 -252.906784)
		(mid 332.931008 -252.830607)
		(end 332.648052 -252.906784)
		(width 0.0889)
		(layer "In2.Cu")
		(net "M_C_CPU0_SA_CA<0>")
	)
	(arc
		(start 332.274164 -252.906784)
		(mid 331.991208 -252.830607)
		(end 331.708252 -252.906784)
		(width 0.0889)
		(layer "In2.Cu")
		(net "M_C_CPU0_SA_CA<0>")
	)
	(arc
		(start 337.91398 -252.906784)
		(mid 337.631024 -252.830607)
		(end 337.348068 -252.906784)
		(width 0.0889)
		(layer "In2.Cu")
		(net "M_C_CPU0_SA_CA<0>")
	)
	(arc
		(start 339.794088 -252.906784)
		(mid 339.511132 -252.830607)
		(end 339.228176 -252.906784)
		(width 0.0889)
		(layer "In2.Cu")
		(net "M_C_CPU0_SA_CA<0>")
	)
	(arc
		(start 341.10803 -252.906784)
		(mid 340.921086 -252.957039)
		(end 340.734142 -252.906784)
		(width 0.0889)
		(layer "In2.Cu")
		(net "M_C_CPU0_SA_CA<0>")
	)
	(arc
		(start 338.854034 -252.906784)
		(mid 338.571078 -252.830607)
		(end 338.288122 -252.906784)
		(width 0.0889)
		(layer "In2.Cu")
		(net "M_C_CPU0_SA_CA<0>")
	)
	(arc
		(start 332.648052 -252.906784)
		(mid 332.461108 -252.957039)
		(end 332.274164 -252.906784)
		(width 0.0889)
		(layer "In2.Cu")
		(net "M_C_CPU0_SA_CA<0>")
	)
	(arc
		(start 335.468214 -252.906784)
		(mid 335.285963 -252.957134)
		(end 335.102454 -252.91161)
		(width 0.0889)
		(layer "In2.Cu")
		(net "M_C_CPU0_SA_CA<0>")
	)
	(arc
		(start 335.094072 -252.906784)
		(mid 334.811116 -252.830607)
		(end 334.52816 -252.906784)
		(width 0.0889)
		(layer "In2.Cu")
		(net "M_C_CPU0_SA_CA<0>")
	)
	(arc
		(start 327.57364 -252.906784)
		(mid 327.298934 -252.83042)
		(end 327.021952 -252.898148)
		(width 0.0889)
		(layer "In2.Cu")
		(net "M_C_CPU0_SA_CA<0>")
	)
	(arc
		(start 336.97418 -252.906784)
		(mid 336.691224 -252.830607)
		(end 336.408268 -252.906784)
		(width 0.0889)
		(layer "In2.Cu")
		(net "M_C_CPU0_SA_CA<0>")
	)
	(arc
		(start 327.939908 -252.91161)
		(mid 327.756146 -252.957226)
		(end 327.57364 -252.906784)
		(width 0.0889)
		(layer "In2.Cu")
		(net "M_C_CPU0_SA_CA<0>")
	)
	(arc
		(start 331.33411 -252.906784)
		(mid 331.051154 -252.830607)
		(end 330.768198 -252.906784)
		(width 0.0889)
		(layer "In2.Cu")
		(net "M_C_CPU0_SA_CA<0>")
	)
	(arc
		(start 329.454002 -252.906784)
		(mid 329.171046 -252.830607)
		(end 328.88809 -252.906784)
		(width 0.0889)
		(layer "In2.Cu")
		(net "M_C_CPU0_SA_CA<0>")
	)
	(arc
		(start 328.514202 -252.906784)
		(mid 328.231246 -252.830607)
		(end 327.94829 -252.906784)
		(width 0.0889)
		(layer "In2.Cu")
		(net "M_C_CPU0_SA_CA<0>")
	)
	(arc
		(start 327.00722 -252.906784)
		(mid 326.828233 -252.956954)
		(end 326.647302 -252.914404)
		(width 0.0889)
		(layer "In2.Cu")
		(net "M_C_CPU0_SA_CA<0>")
	)
	(arc
		(start 328.88809 -252.906784)
		(mid 328.701146 -252.957039)
		(end 328.514202 -252.906784)
		(width 0.0889)
		(layer "In2.Cu")
		(net "M_C_CPU0_SA_CA<0>")
	)
	(arc
		(start 330.768198 -252.906784)
		(mid 330.585947 -252.957134)
		(end 330.402438 -252.91161)
		(width 0.0889)
		(layer "In2.Cu")
		(net "M_C_CPU0_SA_CA<0>")
	)
	(arc
		(start 329.819762 -252.91161)
		(mid 329.636254 -252.957104)
		(end 329.454002 -252.906784)
		(width 0.0889)
		(layer "In2.Cu")
		(net "M_C_CPU0_SA_CA<0>")
	)
	(arc
		(start 340.16823 -252.906784)
		(mid 339.985979 -252.957134)
		(end 339.80247 -252.91161)
		(width 0.0889)
		(layer "In2.Cu")
		(net "M_C_CPU0_SA_CA<0>")
	)
	(arc
		(start 336.408268 -252.906784)
		(mid 336.226017 -252.957134)
		(end 336.042508 -252.91161)
		(width 0.0889)
		(layer "In2.Cu")
		(net "M_C_CPU0_SA_CA<0>")
	)
	(arc
		(start 338.27974 -252.91161)
		(mid 338.096232 -252.957104)
		(end 337.91398 -252.906784)
		(width 0.0889)
		(layer "In2.Cu")
		(net "M_C_CPU0_SA_CA<0>")
	)
	(arc
		(start 326.617838 -252.897386)
		(mid 326.341529 -252.83041)
		(end 326.067674 -252.906784)
		(width 0.0889)
		(layer "In2.Cu")
		(net "M_C_CPU0_SA_CA<0>")
	)
	(arc
		(start 331.708252 -252.906784)
		(mid 331.526001 -252.957134)
		(end 331.342492 -252.91161)
		(width 0.0889)
		(layer "In2.Cu")
		(net "M_C_CPU0_SA_CA<0>")
	)
	(arc
		(start 330.394056 -252.906784)
		(mid 330.1111 -252.830607)
		(end 329.828144 -252.906784)
		(width 0.0889)
		(layer "In2.Cu")
		(net "M_C_CPU0_SA_CA<0>")
	)
	(arc
		(start 334.519778 -252.91161)
		(mid 334.33627 -252.957104)
		(end 334.154018 -252.906784)
		(width 0.0889)
		(layer "In2.Cu")
		(net "M_C_CPU0_SA_CA<0>")
	)
	(arc
		(start 337.348068 -252.906784)
		(mid 337.161124 -252.957039)
		(end 336.97418 -252.906784)
		(width 0.0889)
		(layer "In2.Cu")
		(net "M_C_CPU0_SA_CA<0>")
	)
	(arc
		(start 341.673942 -252.906784)
		(mid 341.390986 -252.830607)
		(end 341.10803 -252.906784)
		(width 0.0889)
		(layer "In2.Cu")
		(net "M_C_CPU0_SA_CA<0>")
	)
	(arc
		(start 341.992712 -252.932946)
		(mid 341.83038 -252.955764)
		(end 341.673942 -252.906784)
		(width 0.0889)
		(layer "In2.Cu")
		(net "M_C_CPU0_SA_CA<0>")
	)
	(arc
		(start 340.734142 -252.906784)
		(mid 340.451186 -252.830607)
		(end 340.16823 -252.906784)
		(width 0.0889)
		(layer "In2.Cu")
		(net "M_C_CPU0_SA_CA<0>")
	)
	(segment
		(start 344.207846 -251.23013)
		(end 343.740994 -250.964192)
		(width 0.10668)
		(layer "F.Cu")
		(net "M_C_CPU0_RESET_N")
	)
	(segment
		(start 322.248276 -251.05487)
		(end 321.302126 -250.10872)
		(width 0.11684)
		(layer "In2.Cu")
		(net "M_C_CPU0_RESET_N")
	)
	(segment
		(start 334.52816 -250.641612)
		(end 334.519778 -250.636786)
		(width 0.0889)
		(layer "In2.Cu")
		(net "M_C_CPU0_RESET_N")
	)
	(segment
		(start 343.58707 -250.698762)
		(end 343.491058 -250.673362)
		(width 0.0889)
		(layer "In2.Cu")
		(net "M_C_CPU0_RESET_N")
	)
	(segment
		(start 321.302126 -250.10872)
		(end 315.723524 -250.10872)
		(width 0.11684)
		(layer "In2.Cu")
		(net "M_C_CPU0_RESET_N")
	)
	(segment
		(start 299.59427 -247.05945)
		(end 299.593 -247.06072)
		(width 0.11684)
		(layer "In2.Cu")
		(net "M_C_CPU0_RESET_N")
	)
	(segment
		(start 324.010274 -251.05487)
		(end 322.248276 -251.05487)
		(width 0.11684)
		(layer "In2.Cu")
		(net "M_C_CPU0_RESET_N")
	)
	(segment
		(start 333.588106 -250.641612)
		(end 333.579724 -250.636786)
		(width 0.0889)
		(layer "In2.Cu")
		(net "M_C_CPU0_RESET_N")
	)
	(segment
		(start 312.048398 -250.779026)
		(end 308.328822 -247.05945)
		(width 0.11684)
		(layer "In2.Cu")
		(net "M_C_CPU0_RESET_N")
	)
	(segment
		(start 294.926004 -247.06072)
		(end 293.22522 -245.359936)
		(width 0.11684)
		(layer "In2.Cu")
		(net "M_C_CPU0_RESET_N")
	)
	(segment
		(start 325.870316 -250.85167)
		(end 324.485254 -250.85167)
		(width 0.0889)
		(layer "In2.Cu")
		(net "M_C_CPU0_RESET_N")
	)
	(segment
		(start 339.228176 -250.641612)
		(end 339.219794 -250.636786)
		(width 0.0889)
		(layer "In2.Cu")
		(net "M_C_CPU0_RESET_N")
	)
	(segment
		(start 336.042508 -250.636786)
		(end 336.034126 -250.641612)
		(width 0.0889)
		(layer "In2.Cu")
		(net "M_C_CPU0_RESET_N")
	)
	(segment
		(start 288.60496 -245.359936)
		(end 288.180018 -244.934994)
		(width 0.11684)
		(layer "In2.Cu")
		(net "M_C_CPU0_RESET_N")
	)
	(segment
		(start 293.22522 -245.359936)
		(end 288.60496 -245.359936)
		(width 0.11684)
		(layer "In2.Cu")
		(net "M_C_CPU0_RESET_N")
	)
	(segment
		(start 329.828144 -250.641612)
		(end 329.819762 -250.636786)
		(width 0.0889)
		(layer "In2.Cu")
		(net "M_C_CPU0_RESET_N")
	)
	(segment
		(start 315.723524 -250.10872)
		(end 314.105036 -250.779026)
		(width 0.11684)
		(layer "In2.Cu")
		(net "M_C_CPU0_RESET_N")
	)
	(segment
		(start 342.988138 -250.641612)
		(end 342.979756 -250.636786)
		(width 0.0889)
		(layer "In2.Cu")
		(net "M_C_CPU0_RESET_N")
	)
	(segment
		(start 330.402438 -250.636786)
		(end 330.394056 -250.641612)
		(width 0.0889)
		(layer "In2.Cu")
		(net "M_C_CPU0_RESET_N")
	)
	(segment
		(start 314.105036 -250.779026)
		(end 312.048398 -250.779026)
		(width 0.11684)
		(layer "In2.Cu")
		(net "M_C_CPU0_RESET_N")
	)
	(segment
		(start 324.485254 -250.85167)
		(end 324.282054 -251.05487)
		(width 0.0889)
		(layer "In2.Cu")
		(net "M_C_CPU0_RESET_N")
	)
	(segment
		(start 327.58253 -250.636786)
		(end 327.574148 -250.641612)
		(width 0.0889)
		(layer "In2.Cu")
		(net "M_C_CPU0_RESET_N")
	)
	(segment
		(start 339.80247 -250.636786)
		(end 339.794088 -250.641612)
		(width 0.0889)
		(layer "In2.Cu")
		(net "M_C_CPU0_RESET_N")
	)
	(segment
		(start 308.328822 -247.05945)
		(end 299.59427 -247.05945)
		(width 0.11684)
		(layer "In2.Cu")
		(net "M_C_CPU0_RESET_N")
	)
	(segment
		(start 342.048084 -250.641612)
		(end 342.039702 -250.636786)
		(width 0.0889)
		(layer "In2.Cu")
		(net "M_C_CPU0_RESET_N")
	)
	(segment
		(start 324.282054 -251.05487)
		(end 324.010274 -251.05487)
		(width 0.0889)
		(layer "In2.Cu")
		(net "M_C_CPU0_RESET_N")
	)
	(segment
		(start 331.342492 -250.636786)
		(end 331.33411 -250.641612)
		(width 0.0889)
		(layer "In2.Cu")
		(net "M_C_CPU0_RESET_N")
	)
	(segment
		(start 343.740994 -250.964192)
		(end 343.58707 -250.698762)
		(width 0.0889)
		(layer "In2.Cu")
		(net "M_C_CPU0_RESET_N")
	)
	(segment
		(start 299.593 -247.06072)
		(end 294.926004 -247.06072)
		(width 0.11684)
		(layer "In2.Cu")
		(net "M_C_CPU0_RESET_N")
	)
	(segment
		(start 338.288122 -250.641612)
		(end 338.27974 -250.636786)
		(width 0.0889)
		(layer "In2.Cu")
		(net "M_C_CPU0_RESET_N")
	)
	(segment
		(start 335.102454 -250.636786)
		(end 335.094072 -250.641612)
		(width 0.0889)
		(layer "In2.Cu")
		(net "M_C_CPU0_RESET_N")
	)
	(arc
		(start 340.734142 -250.641612)
		(mid 340.451186 -250.717789)
		(end 340.16823 -250.641612)
		(width 0.0889)
		(layer "In2.Cu")
		(net "M_C_CPU0_RESET_N")
	)
	(arc
		(start 342.979756 -250.636786)
		(mid 342.796248 -250.591292)
		(end 342.613996 -250.641612)
		(width 0.0889)
		(layer "In2.Cu")
		(net "M_C_CPU0_RESET_N")
	)
	(arc
		(start 341.10803 -250.641612)
		(mid 340.921086 -250.591357)
		(end 340.734142 -250.641612)
		(width 0.0889)
		(layer "In2.Cu")
		(net "M_C_CPU0_RESET_N")
	)
	(arc
		(start 341.673942 -250.641612)
		(mid 341.390986 -250.717789)
		(end 341.10803 -250.641612)
		(width 0.0889)
		(layer "In2.Cu")
		(net "M_C_CPU0_RESET_N")
	)
	(arc
		(start 342.039702 -250.636786)
		(mid 341.856194 -250.591292)
		(end 341.673942 -250.641612)
		(width 0.0889)
		(layer "In2.Cu")
		(net "M_C_CPU0_RESET_N")
	)
	(arc
		(start 336.408268 -250.641612)
		(mid 336.226017 -250.591262)
		(end 336.042508 -250.636786)
		(width 0.0889)
		(layer "In2.Cu")
		(net "M_C_CPU0_RESET_N")
	)
	(arc
		(start 335.468214 -250.641612)
		(mid 335.285963 -250.591262)
		(end 335.102454 -250.636786)
		(width 0.0889)
		(layer "In2.Cu")
		(net "M_C_CPU0_RESET_N")
	)
	(arc
		(start 331.708252 -250.641612)
		(mid 331.526001 -250.591262)
		(end 331.342492 -250.636786)
		(width 0.0889)
		(layer "In2.Cu")
		(net "M_C_CPU0_RESET_N")
	)
	(arc
		(start 327.574148 -250.641612)
		(mid 327.291192 -250.717789)
		(end 327.008236 -250.641612)
		(width 0.0889)
		(layer "In2.Cu")
		(net "M_C_CPU0_RESET_N")
	)
	(arc
		(start 328.514202 -250.641612)
		(mid 328.231246 -250.717789)
		(end 327.94829 -250.641612)
		(width 0.0889)
		(layer "In2.Cu")
		(net "M_C_CPU0_RESET_N")
	)
	(arc
		(start 330.394056 -250.641612)
		(mid 330.1111 -250.717789)
		(end 329.828144 -250.641612)
		(width 0.0889)
		(layer "In2.Cu")
		(net "M_C_CPU0_RESET_N")
	)
	(arc
		(start 330.768198 -250.641612)
		(mid 330.585947 -250.591262)
		(end 330.402438 -250.636786)
		(width 0.0889)
		(layer "In2.Cu")
		(net "M_C_CPU0_RESET_N")
	)
	(arc
		(start 337.91398 -250.641612)
		(mid 337.631024 -250.717789)
		(end 337.348068 -250.641612)
		(width 0.0889)
		(layer "In2.Cu")
		(net "M_C_CPU0_RESET_N")
	)
	(arc
		(start 327.008236 -250.641612)
		(mid 326.825985 -250.591262)
		(end 326.642476 -250.636786)
		(width 0.0889)
		(layer "In2.Cu")
		(net "M_C_CPU0_RESET_N")
	)
	(arc
		(start 337.348068 -250.641612)
		(mid 337.161124 -250.591357)
		(end 336.97418 -250.641612)
		(width 0.0889)
		(layer "In2.Cu")
		(net "M_C_CPU0_RESET_N")
	)
	(arc
		(start 329.454002 -250.641612)
		(mid 329.171046 -250.717789)
		(end 328.88809 -250.641612)
		(width 0.0889)
		(layer "In2.Cu")
		(net "M_C_CPU0_RESET_N")
	)
	(arc
		(start 331.33411 -250.641612)
		(mid 331.051154 -250.717789)
		(end 330.768198 -250.641612)
		(width 0.0889)
		(layer "In2.Cu")
		(net "M_C_CPU0_RESET_N")
	)
	(arc
		(start 327.94829 -250.641612)
		(mid 327.766039 -250.591262)
		(end 327.58253 -250.636786)
		(width 0.0889)
		(layer "In2.Cu")
		(net "M_C_CPU0_RESET_N")
	)
	(arc
		(start 328.88809 -250.641612)
		(mid 328.701146 -250.591357)
		(end 328.514202 -250.641612)
		(width 0.0889)
		(layer "In2.Cu")
		(net "M_C_CPU0_RESET_N")
	)
	(arc
		(start 333.213964 -250.641612)
		(mid 332.931008 -250.717789)
		(end 332.648052 -250.641612)
		(width 0.0889)
		(layer "In2.Cu")
		(net "M_C_CPU0_RESET_N")
	)
	(arc
		(start 334.519778 -250.636786)
		(mid 334.33627 -250.591292)
		(end 334.154018 -250.641612)
		(width 0.0889)
		(layer "In2.Cu")
		(net "M_C_CPU0_RESET_N")
	)
	(arc
		(start 342.613996 -250.641612)
		(mid 342.33104 -250.717789)
		(end 342.048084 -250.641612)
		(width 0.0889)
		(layer "In2.Cu")
		(net "M_C_CPU0_RESET_N")
	)
	(arc
		(start 326.642476 -250.636786)
		(mid 326.271067 -250.796946)
		(end 325.870316 -250.85167)
		(width 0.0889)
		(layer "In2.Cu")
		(net "M_C_CPU0_RESET_N")
	)
	(arc
		(start 335.094072 -250.641612)
		(mid 334.811116 -250.717789)
		(end 334.52816 -250.641612)
		(width 0.0889)
		(layer "In2.Cu")
		(net "M_C_CPU0_RESET_N")
	)
	(arc
		(start 339.219794 -250.636786)
		(mid 339.036286 -250.591292)
		(end 338.854034 -250.641612)
		(width 0.0889)
		(layer "In2.Cu")
		(net "M_C_CPU0_RESET_N")
	)
	(arc
		(start 343.491058 -250.673362)
		(mid 343.23585 -250.716839)
		(end 342.988138 -250.641612)
		(width 0.0889)
		(layer "In2.Cu")
		(net "M_C_CPU0_RESET_N")
	)
	(arc
		(start 339.794088 -250.641612)
		(mid 339.511132 -250.717789)
		(end 339.228176 -250.641612)
		(width 0.0889)
		(layer "In2.Cu")
		(net "M_C_CPU0_RESET_N")
	)
	(arc
		(start 332.648052 -250.641612)
		(mid 332.461108 -250.591357)
		(end 332.274164 -250.641612)
		(width 0.0889)
		(layer "In2.Cu")
		(net "M_C_CPU0_RESET_N")
	)
	(arc
		(start 332.274164 -250.641612)
		(mid 331.991208 -250.717789)
		(end 331.708252 -250.641612)
		(width 0.0889)
		(layer "In2.Cu")
		(net "M_C_CPU0_RESET_N")
	)
	(arc
		(start 329.819762 -250.636786)
		(mid 329.636254 -250.591292)
		(end 329.454002 -250.641612)
		(width 0.0889)
		(layer "In2.Cu")
		(net "M_C_CPU0_RESET_N")
	)
	(arc
		(start 336.97418 -250.641612)
		(mid 336.691224 -250.717789)
		(end 336.408268 -250.641612)
		(width 0.0889)
		(layer "In2.Cu")
		(net "M_C_CPU0_RESET_N")
	)
	(arc
		(start 334.154018 -250.641612)
		(mid 333.871062 -250.717789)
		(end 333.588106 -250.641612)
		(width 0.0889)
		(layer "In2.Cu")
		(net "M_C_CPU0_RESET_N")
	)
	(arc
		(start 340.16823 -250.641612)
		(mid 339.985979 -250.591262)
		(end 339.80247 -250.636786)
		(width 0.0889)
		(layer "In2.Cu")
		(net "M_C_CPU0_RESET_N")
	)
	(arc
		(start 333.579724 -250.636786)
		(mid 333.396216 -250.591292)
		(end 333.213964 -250.641612)
		(width 0.0889)
		(layer "In2.Cu")
		(net "M_C_CPU0_RESET_N")
	)
	(arc
		(start 338.27974 -250.636786)
		(mid 338.096232 -250.591292)
		(end 337.91398 -250.641612)
		(width 0.0889)
		(layer "In2.Cu")
		(net "M_C_CPU0_RESET_N")
	)
	(arc
		(start 338.854034 -250.641612)
		(mid 338.571078 -250.717789)
		(end 338.288122 -250.641612)
		(width 0.0889)
		(layer "In2.Cu")
		(net "M_C_CPU0_RESET_N")
	)
	(arc
		(start 336.034126 -250.641612)
		(mid 335.75117 -250.717789)
		(end 335.468214 -250.641612)
		(width 0.0889)
		(layer "In2.Cu")
		(net "M_C_CPU0_RESET_N")
	)
	(segment
		(start 342.327992 -256.090166)
		(end 341.86114 -255.824228)
		(width 0.14732)
		(layer "F.Cu")
		(net "M_C_CPU0_CLK_DP<0>")
	)
	(segment
		(start 315.192664 -256.252472)
		(end 292.35146 -256.252472)
		(width 0.16002)
		(layer "In2.Cu")
		(net "M_C_CPU0_CLK_DP<0>")
	)
	(segment
		(start 338.860892 -256.154174)
		(end 338.85251 -256.149348)
		(width 0.09525)
		(layer "In2.Cu")
		(net "M_C_CPU0_CLK_DP<0>")
	)
	(segment
		(start 338.289646 -256.149348)
		(end 338.281264 -256.154174)
		(width 0.09525)
		(layer "In2.Cu")
		(net "M_C_CPU0_CLK_DP<0>")
	)
	(segment
		(start 334.529684 -256.149348)
		(end 334.521302 -256.154174)
		(width 0.09525)
		(layer "In2.Cu")
		(net "M_C_CPU0_CLK_DP<0>")
	)
	(segment
		(start 290.683188 -254.5842)
		(end 290.683188 -254.4191)
		(width 0.16002)
		(layer "In2.Cu")
		(net "M_C_CPU0_CLK_DP<0>")
	)
	(segment
		(start 325.426578 -256.681986)
		(end 325.409814 -256.69875)
		(width 0.09525)
		(layer "In2.Cu")
		(net "M_C_CPU0_CLK_DP<0>")
	)
	(segment
		(start 291.187632 -254.923544)
		(end 291.022532 -254.923544)
		(width 0.16002)
		(layer "In2.Cu")
		(net "M_C_CPU0_CLK_DP<0>")
	)
	(segment
		(start 290.34359 -254.079502)
		(end 290.17849 -254.079502)
		(width 0.16002)
		(layer "In2.Cu")
		(net "M_C_CPU0_CLK_DP<0>")
	)
	(segment
		(start 325.409814 -256.69875)
		(end 324.934072 -257.174492)
		(width 0.16002)
		(layer "In2.Cu")
		(net "M_C_CPU0_CLK_DP<0>")
	)
	(segment
		(start 320.453258 -257.174492)
		(end 318.926718 -255.647952)
		(width 0.16002)
		(layer "In2.Cu")
		(net "M_C_CPU0_CLK_DP<0>")
	)
	(segment
		(start 331.340968 -256.154174)
		(end 331.332586 -256.149348)
		(width 0.09525)
		(layer "In2.Cu")
		(net "M_C_CPU0_CLK_DP<0>")
	)
	(segment
		(start 341.86114 -255.824228)
		(end 342.015064 -256.089658)
		(width 0.09525)
		(layer "In2.Cu")
		(net "M_C_CPU0_CLK_DP<0>")
	)
	(segment
		(start 326.64654 -256.15773)
		(end 326.632062 -256.149348)
		(width 0.09525)
		(layer "In2.Cu")
		(net "M_C_CPU0_CLK_DP<0>")
	)
	(segment
		(start 336.040984 -256.154174)
		(end 336.032602 -256.149348)
		(width 0.09525)
		(layer "In2.Cu")
		(net "M_C_CPU0_CLK_DP<0>")
	)
	(segment
		(start 330.400914 -256.154174)
		(end 330.392532 -256.149348)
		(width 0.09525)
		(layer "In2.Cu")
		(net "M_C_CPU0_CLK_DP<0>")
	)
	(segment
		(start 325.954644 -256.23774)
		(end 325.510398 -256.681986)
		(width 0.09525)
		(layer "In2.Cu")
		(net "M_C_CPU0_CLK_DP<0>")
	)
	(segment
		(start 326.632062 -256.149348)
		(end 326.611234 -256.137156)
		(width 0.09525)
		(layer "In2.Cu")
		(net "M_C_CPU0_CLK_DP<0>")
	)
	(segment
		(start 290.17849 -254.079502)
		(end 289.807904 -253.708916)
		(width 0.16002)
		(layer "In2.Cu")
		(net "M_C_CPU0_CLK_DP<0>")
	)
	(segment
		(start 292.35146 -256.252472)
		(end 291.527484 -255.428496)
		(width 0.16002)
		(layer "In2.Cu")
		(net "M_C_CPU0_CLK_DP<0>")
	)
	(segment
		(start 291.527484 -255.263142)
		(end 291.187632 -254.923544)
		(width 0.16002)
		(layer "In2.Cu")
		(net "M_C_CPU0_CLK_DP<0>")
	)
	(segment
		(start 316.652148 -255.647952)
		(end 315.192664 -256.252472)
		(width 0.16002)
		(layer "In2.Cu")
		(net "M_C_CPU0_CLK_DP<0>")
	)
	(segment
		(start 318.926718 -255.647952)
		(end 316.652148 -255.647952)
		(width 0.16002)
		(layer "In2.Cu")
		(net "M_C_CPU0_CLK_DP<0>")
	)
	(segment
		(start 342.015064 -256.089658)
		(end 341.991696 -256.176526)
		(width 0.09525)
		(layer "In2.Cu")
		(net "M_C_CPU0_CLK_DP<0>")
	)
	(segment
		(start 327.572624 -256.149348)
		(end 327.557892 -256.140712)
		(width 0.09525)
		(layer "In2.Cu")
		(net "M_C_CPU0_CLK_DP<0>")
	)
	(segment
		(start 291.527484 -255.428496)
		(end 291.527484 -255.263142)
		(width 0.16002)
		(layer "In2.Cu")
		(net "M_C_CPU0_CLK_DP<0>")
	)
	(segment
		(start 324.934072 -257.174492)
		(end 320.453258 -257.174492)
		(width 0.16002)
		(layer "In2.Cu")
		(net "M_C_CPU0_CLK_DP<0>")
	)
	(segment
		(start 327.581006 -256.154174)
		(end 327.572624 -256.149348)
		(width 0.09525)
		(layer "In2.Cu")
		(net "M_C_CPU0_CLK_DP<0>")
	)
	(segment
		(start 289.807904 -253.708916)
		(end 288.45383 -253.708916)
		(width 0.16002)
		(layer "In2.Cu")
		(net "M_C_CPU0_CLK_DP<0>")
	)
	(segment
		(start 329.829668 -256.149348)
		(end 329.821286 -256.154174)
		(width 0.09525)
		(layer "In2.Cu")
		(net "M_C_CPU0_CLK_DP<0>")
	)
	(segment
		(start 288.45383 -253.708916)
		(end 288.180018 -253.435104)
		(width 0.16002)
		(layer "In2.Cu")
		(net "M_C_CPU0_CLK_DP<0>")
	)
	(segment
		(start 291.022532 -254.923544)
		(end 290.683188 -254.5842)
		(width 0.16002)
		(layer "In2.Cu")
		(net "M_C_CPU0_CLK_DP<0>")
	)
	(segment
		(start 333.58963 -256.149348)
		(end 333.581248 -256.154174)
		(width 0.09525)
		(layer "In2.Cu")
		(net "M_C_CPU0_CLK_DP<0>")
	)
	(segment
		(start 335.10093 -256.154174)
		(end 335.092548 -256.149348)
		(width 0.09525)
		(layer "In2.Cu")
		(net "M_C_CPU0_CLK_DP<0>")
	)
	(segment
		(start 325.510398 -256.681986)
		(end 325.426578 -256.681986)
		(width 0.09525)
		(layer "In2.Cu")
		(net "M_C_CPU0_CLK_DP<0>")
	)
	(segment
		(start 339.800946 -256.154174)
		(end 339.792564 -256.149348)
		(width 0.09525)
		(layer "In2.Cu")
		(net "M_C_CPU0_CLK_DP<0>")
	)
	(segment
		(start 290.683188 -254.4191)
		(end 290.34359 -254.079502)
		(width 0.16002)
		(layer "In2.Cu")
		(net "M_C_CPU0_CLK_DP<0>")
	)
	(arc
		(start 341.109554 -256.149348)
		(mid 340.921086 -256.200025)
		(end 340.732618 -256.149348)
		(width 0.09525)
		(layer "In2.Cu")
		(net "M_C_CPU0_CLK_DP<0>")
	)
	(arc
		(start 341.672418 -256.149348)
		(mid 341.390986 -256.073593)
		(end 341.109554 -256.149348)
		(width 0.09525)
		(layer "In2.Cu")
		(net "M_C_CPU0_CLK_DP<0>")
	)
	(arc
		(start 336.972656 -256.149348)
		(mid 336.691224 -256.073593)
		(end 336.409792 -256.149348)
		(width 0.09525)
		(layer "In2.Cu")
		(net "M_C_CPU0_CLK_DP<0>")
	)
	(arc
		(start 327.557892 -256.140712)
		(mid 327.282433 -256.073327)
		(end 327.009252 -256.149348)
		(width 0.09525)
		(layer "In2.Cu")
		(net "M_C_CPU0_CLK_DP<0>")
	)
	(arc
		(start 331.332586 -256.149348)
		(mid 331.051154 -256.073593)
		(end 330.769722 -256.149348)
		(width 0.09525)
		(layer "In2.Cu")
		(net "M_C_CPU0_CLK_DP<0>")
	)
	(arc
		(start 340.169754 -256.149348)
		(mid 339.985979 -256.20012)
		(end 339.800946 -256.154174)
		(width 0.09525)
		(layer "In2.Cu")
		(net "M_C_CPU0_CLK_DP<0>")
	)
	(arc
		(start 327.949814 -256.149348)
		(mid 327.766039 -256.20012)
		(end 327.581006 -256.154174)
		(width 0.09525)
		(layer "In2.Cu")
		(net "M_C_CPU0_CLK_DP<0>")
	)
	(arc
		(start 336.409792 -256.149348)
		(mid 336.226017 -256.20012)
		(end 336.040984 -256.154174)
		(width 0.09525)
		(layer "In2.Cu")
		(net "M_C_CPU0_CLK_DP<0>")
	)
	(arc
		(start 334.521302 -256.154174)
		(mid 334.33627 -256.200088)
		(end 334.152494 -256.149348)
		(width 0.09525)
		(layer "In2.Cu")
		(net "M_C_CPU0_CLK_DP<0>")
	)
	(arc
		(start 339.2297 -256.149348)
		(mid 339.045925 -256.20012)
		(end 338.860892 -256.154174)
		(width 0.09525)
		(layer "In2.Cu")
		(net "M_C_CPU0_CLK_DP<0>")
	)
	(arc
		(start 340.732618 -256.149348)
		(mid 340.451186 -256.073593)
		(end 340.169754 -256.149348)
		(width 0.09525)
		(layer "In2.Cu")
		(net "M_C_CPU0_CLK_DP<0>")
	)
	(arc
		(start 338.85251 -256.149348)
		(mid 338.571078 -256.073593)
		(end 338.289646 -256.149348)
		(width 0.09525)
		(layer "In2.Cu")
		(net "M_C_CPU0_CLK_DP<0>")
	)
	(arc
		(start 330.769722 -256.149348)
		(mid 330.585947 -256.20012)
		(end 330.400914 -256.154174)
		(width 0.09525)
		(layer "In2.Cu")
		(net "M_C_CPU0_CLK_DP<0>")
	)
	(arc
		(start 333.581248 -256.154174)
		(mid 333.396216 -256.200088)
		(end 333.21244 -256.149348)
		(width 0.09525)
		(layer "In2.Cu")
		(net "M_C_CPU0_CLK_DP<0>")
	)
	(arc
		(start 335.469738 -256.149348)
		(mid 335.285963 -256.20012)
		(end 335.10093 -256.154174)
		(width 0.09525)
		(layer "In2.Cu")
		(net "M_C_CPU0_CLK_DP<0>")
	)
	(arc
		(start 329.821286 -256.154174)
		(mid 329.636254 -256.200088)
		(end 329.452478 -256.149348)
		(width 0.09525)
		(layer "In2.Cu")
		(net "M_C_CPU0_CLK_DP<0>")
	)
	(arc
		(start 341.991696 -256.176526)
		(mid 341.829014 -256.198658)
		(end 341.672418 -256.149348)
		(width 0.09525)
		(layer "In2.Cu")
		(net "M_C_CPU0_CLK_DP<0>")
	)
	(arc
		(start 337.912456 -256.149348)
		(mid 337.631024 -256.073593)
		(end 337.349592 -256.149348)
		(width 0.09525)
		(layer "In2.Cu")
		(net "M_C_CPU0_CLK_DP<0>")
	)
	(arc
		(start 331.709776 -256.149348)
		(mid 331.526001 -256.20012)
		(end 331.340968 -256.154174)
		(width 0.09525)
		(layer "In2.Cu")
		(net "M_C_CPU0_CLK_DP<0>")
	)
	(arc
		(start 338.281264 -256.154174)
		(mid 338.096232 -256.200088)
		(end 337.912456 -256.149348)
		(width 0.09525)
		(layer "In2.Cu")
		(net "M_C_CPU0_CLK_DP<0>")
	)
	(arc
		(start 327.009252 -256.149348)
		(mid 326.828973 -256.200179)
		(end 326.64654 -256.15773)
		(width 0.09525)
		(layer "In2.Cu")
		(net "M_C_CPU0_CLK_DP<0>")
	)
	(arc
		(start 339.792564 -256.149348)
		(mid 339.511132 -256.073593)
		(end 339.2297 -256.149348)
		(width 0.09525)
		(layer "In2.Cu")
		(net "M_C_CPU0_CLK_DP<0>")
	)
	(arc
		(start 335.092548 -256.149348)
		(mid 334.811116 -256.073593)
		(end 334.529684 -256.149348)
		(width 0.09525)
		(layer "In2.Cu")
		(net "M_C_CPU0_CLK_DP<0>")
	)
	(arc
		(start 329.452478 -256.149348)
		(mid 329.171046 -256.073593)
		(end 328.889614 -256.149348)
		(width 0.09525)
		(layer "In2.Cu")
		(net "M_C_CPU0_CLK_DP<0>")
	)
	(arc
		(start 328.889614 -256.149348)
		(mid 328.701146 -256.200025)
		(end 328.512678 -256.149348)
		(width 0.09525)
		(layer "In2.Cu")
		(net "M_C_CPU0_CLK_DP<0>")
	)
	(arc
		(start 326.069198 -256.149348)
		(mid 326.009063 -256.189839)
		(end 325.954644 -256.23774)
		(width 0.09525)
		(layer "In2.Cu")
		(net "M_C_CPU0_CLK_DP<0>")
	)
	(arc
		(start 326.611234 -256.137156)
		(mid 326.338629 -256.07336)
		(end 326.069198 -256.149348)
		(width 0.09525)
		(layer "In2.Cu")
		(net "M_C_CPU0_CLK_DP<0>")
	)
	(arc
		(start 330.392532 -256.149348)
		(mid 330.1111 -256.073593)
		(end 329.829668 -256.149348)
		(width 0.09525)
		(layer "In2.Cu")
		(net "M_C_CPU0_CLK_DP<0>")
	)
	(arc
		(start 332.649576 -256.149348)
		(mid 332.461108 -256.200025)
		(end 332.27264 -256.149348)
		(width 0.09525)
		(layer "In2.Cu")
		(net "M_C_CPU0_CLK_DP<0>")
	)
	(arc
		(start 336.032602 -256.149348)
		(mid 335.75117 -256.073593)
		(end 335.469738 -256.149348)
		(width 0.09525)
		(layer "In2.Cu")
		(net "M_C_CPU0_CLK_DP<0>")
	)
	(arc
		(start 334.152494 -256.149348)
		(mid 333.871062 -256.073593)
		(end 333.58963 -256.149348)
		(width 0.09525)
		(layer "In2.Cu")
		(net "M_C_CPU0_CLK_DP<0>")
	)
	(arc
		(start 333.21244 -256.149348)
		(mid 332.931008 -256.073593)
		(end 332.649576 -256.149348)
		(width 0.09525)
		(layer "In2.Cu")
		(net "M_C_CPU0_CLK_DP<0>")
	)
	(arc
		(start 328.512678 -256.149348)
		(mid 328.231246 -256.073593)
		(end 327.949814 -256.149348)
		(width 0.09525)
		(layer "In2.Cu")
		(net "M_C_CPU0_CLK_DP<0>")
	)
	(arc
		(start 337.349592 -256.149348)
		(mid 337.161124 -256.200025)
		(end 336.972656 -256.149348)
		(width 0.09525)
		(layer "In2.Cu")
		(net "M_C_CPU0_CLK_DP<0>")
	)
	(arc
		(start 332.27264 -256.149348)
		(mid 331.991208 -256.073593)
		(end 331.709776 -256.149348)
		(width 0.09525)
		(layer "In2.Cu")
		(net "M_C_CPU0_CLK_DP<0>")
	)
	(segment
		(start 342.797892 -256.900172)
		(end 342.33104 -256.634234)
		(width 0.14732)
		(layer "F.Cu")
		(net "M_C_CPU0_CLK_DN<0>")
	)
	(segment
		(start 333.682594 -256.309114)
		(end 333.690976 -256.304288)
		(width 0.09525)
		(layer "In2.Cu")
		(net "M_C_CPU0_CLK_DN<0>")
	)
	(segment
		(start 326.524874 -256.300732)
		(end 326.539352 -256.309114)
		(width 0.09525)
		(layer "In2.Cu")
		(net "M_C_CPU0_CLK_DN<0>")
	)
	(segment
		(start 339.691218 -256.304288)
		(end 339.6996 -256.309114)
		(width 0.09525)
		(layer "In2.Cu")
		(net "M_C_CPU0_CLK_DN<0>")
	)
	(segment
		(start 341.202518 -256.309114)
		(end 341.2109 -256.304288)
		(width 0.09525)
		(layer "In2.Cu")
		(net "M_C_CPU0_CLK_DN<0>")
	)
	(segment
		(start 325.640446 -256.812542)
		(end 326.084946 -256.368042)
		(width 0.09525)
		(layer "In2.Cu")
		(net "M_C_CPU0_CLK_DN<0>")
	)
	(segment
		(start 332.74254 -256.309114)
		(end 332.750922 -256.304288)
		(width 0.09525)
		(layer "In2.Cu")
		(net "M_C_CPU0_CLK_DN<0>")
	)
	(segment
		(start 331.23124 -256.304288)
		(end 331.239622 -256.309114)
		(width 0.09525)
		(layer "In2.Cu")
		(net "M_C_CPU0_CLK_DN<0>")
	)
	(segment
		(start 342.076278 -256.342134)
		(end 342.177116 -256.368804)
		(width 0.09525)
		(layer "In2.Cu")
		(net "M_C_CPU0_CLK_DN<0>")
	)
	(segment
		(start 315.252862 -256.554732)
		(end 316.712346 -255.950212)
		(width 0.16002)
		(layer "In2.Cu")
		(net "M_C_CPU0_CLK_DN<0>")
	)
	(segment
		(start 325.059548 -257.476752)
		(end 325.623682 -256.912618)
		(width 0.16002)
		(layer "In2.Cu")
		(net "M_C_CPU0_CLK_DN<0>")
	)
	(segment
		(start 288.180018 -254.284988)
		(end 288.45383 -254.011176)
		(width 0.16002)
		(layer "In2.Cu")
		(net "M_C_CPU0_CLK_DN<0>")
	)
	(segment
		(start 316.712346 -255.950212)
		(end 318.801496 -255.950212)
		(width 0.16002)
		(layer "In2.Cu")
		(net "M_C_CPU0_CLK_DN<0>")
	)
	(segment
		(start 292.226238 -256.554732)
		(end 315.252862 -256.554732)
		(width 0.16002)
		(layer "In2.Cu")
		(net "M_C_CPU0_CLK_DN<0>")
	)
	(segment
		(start 318.801496 -255.950212)
		(end 320.328036 -257.476752)
		(width 0.16002)
		(layer "In2.Cu")
		(net "M_C_CPU0_CLK_DN<0>")
	)
	(segment
		(start 340.631272 -256.304288)
		(end 340.639654 -256.309114)
		(width 0.09525)
		(layer "In2.Cu")
		(net "M_C_CPU0_CLK_DN<0>")
	)
	(segment
		(start 327.467722 -256.302256)
		(end 327.47966 -256.309114)
		(width 0.09525)
		(layer "In2.Cu")
		(net "M_C_CPU0_CLK_DN<0>")
	)
	(segment
		(start 325.640446 -256.895854)
		(end 325.640446 -256.812542)
		(width 0.09525)
		(layer "In2.Cu")
		(net "M_C_CPU0_CLK_DN<0>")
	)
	(segment
		(start 332.171294 -256.304288)
		(end 332.179676 -256.309114)
		(width 0.09525)
		(layer "In2.Cu")
		(net "M_C_CPU0_CLK_DN<0>")
	)
	(segment
		(start 289.682682 -254.011176)
		(end 292.226238 -256.554732)
		(width 0.16002)
		(layer "In2.Cu")
		(net "M_C_CPU0_CLK_DN<0>")
	)
	(segment
		(start 288.45383 -254.011176)
		(end 289.682682 -254.011176)
		(width 0.16002)
		(layer "In2.Cu")
		(net "M_C_CPU0_CLK_DN<0>")
	)
	(segment
		(start 335.931256 -256.304288)
		(end 335.939638 -256.309114)
		(width 0.09525)
		(layer "In2.Cu")
		(net "M_C_CPU0_CLK_DN<0>")
	)
	(segment
		(start 328.982578 -256.309114)
		(end 328.99096 -256.304288)
		(width 0.09525)
		(layer "In2.Cu")
		(net "M_C_CPU0_CLK_DN<0>")
	)
	(segment
		(start 336.87131 -256.304288)
		(end 336.879692 -256.309114)
		(width 0.09525)
		(layer "In2.Cu")
		(net "M_C_CPU0_CLK_DN<0>")
	)
	(segment
		(start 342.177116 -256.368804)
		(end 342.33104 -256.634234)
		(width 0.09525)
		(layer "In2.Cu")
		(net "M_C_CPU0_CLK_DN<0>")
	)
	(segment
		(start 325.623682 -256.912618)
		(end 325.640446 -256.895854)
		(width 0.09525)
		(layer "In2.Cu")
		(net "M_C_CPU0_CLK_DN<0>")
	)
	(segment
		(start 328.411332 -256.304288)
		(end 328.419714 -256.309114)
		(width 0.09525)
		(layer "In2.Cu")
		(net "M_C_CPU0_CLK_DN<0>")
	)
	(segment
		(start 337.442556 -256.309114)
		(end 337.450938 -256.304288)
		(width 0.09525)
		(layer "In2.Cu")
		(net "M_C_CPU0_CLK_DN<0>")
	)
	(segment
		(start 320.328036 -257.476752)
		(end 325.059548 -257.476752)
		(width 0.16002)
		(layer "In2.Cu")
		(net "M_C_CPU0_CLK_DN<0>")
	)
	(segment
		(start 326.539352 -256.309114)
		(end 326.56018 -256.321306)
		(width 0.09525)
		(layer "In2.Cu")
		(net "M_C_CPU0_CLK_DN<0>")
	)
	(arc
		(start 336.502502 -256.309114)
		(mid 336.686277 -256.258342)
		(end 336.87131 -256.304288)
		(width 0.09525)
		(layer "In2.Cu")
		(net "M_C_CPU0_CLK_DN<0>")
	)
	(arc
		(start 327.102216 -256.309114)
		(mid 327.284086 -256.258249)
		(end 327.467722 -256.302256)
		(width 0.09525)
		(layer "In2.Cu")
		(net "M_C_CPU0_CLK_DN<0>")
	)
	(arc
		(start 330.862432 -256.309114)
		(mid 331.046207 -256.258342)
		(end 331.23124 -256.304288)
		(width 0.09525)
		(layer "In2.Cu")
		(net "M_C_CPU0_CLK_DN<0>")
	)
	(arc
		(start 326.56018 -256.321306)
		(mid 326.832785 -256.385102)
		(end 327.102216 -256.309114)
		(width 0.09525)
		(layer "In2.Cu")
		(net "M_C_CPU0_CLK_DN<0>")
	)
	(arc
		(start 327.47966 -256.309114)
		(mid 327.761092 -256.384869)
		(end 328.042524 -256.309114)
		(width 0.09525)
		(layer "In2.Cu")
		(net "M_C_CPU0_CLK_DN<0>")
	)
	(arc
		(start 340.639654 -256.309114)
		(mid 340.921086 -256.384869)
		(end 341.202518 -256.309114)
		(width 0.09525)
		(layer "In2.Cu")
		(net "M_C_CPU0_CLK_DN<0>")
	)
	(arc
		(start 328.99096 -256.304288)
		(mid 329.175992 -256.258374)
		(end 329.359768 -256.309114)
		(width 0.09525)
		(layer "In2.Cu")
		(net "M_C_CPU0_CLK_DN<0>")
	)
	(arc
		(start 338.759546 -256.309114)
		(mid 339.040978 -256.384869)
		(end 339.32241 -256.309114)
		(width 0.09525)
		(layer "In2.Cu")
		(net "M_C_CPU0_CLK_DN<0>")
	)
	(arc
		(start 335.562448 -256.309114)
		(mid 335.746223 -256.258342)
		(end 335.931256 -256.304288)
		(width 0.09525)
		(layer "In2.Cu")
		(net "M_C_CPU0_CLK_DN<0>")
	)
	(arc
		(start 329.359768 -256.309114)
		(mid 329.6412 -256.384869)
		(end 329.922632 -256.309114)
		(width 0.09525)
		(layer "In2.Cu")
		(net "M_C_CPU0_CLK_DN<0>")
	)
	(arc
		(start 338.38261 -256.309114)
		(mid 338.571078 -256.258437)
		(end 338.759546 -256.309114)
		(width 0.09525)
		(layer "In2.Cu")
		(net "M_C_CPU0_CLK_DN<0>")
	)
	(arc
		(start 336.879692 -256.309114)
		(mid 337.161124 -256.384869)
		(end 337.442556 -256.309114)
		(width 0.09525)
		(layer "In2.Cu")
		(net "M_C_CPU0_CLK_DN<0>")
	)
	(arc
		(start 334.999584 -256.309114)
		(mid 335.281016 -256.384869)
		(end 335.562448 -256.309114)
		(width 0.09525)
		(layer "In2.Cu")
		(net "M_C_CPU0_CLK_DN<0>")
	)
	(arc
		(start 331.239622 -256.309114)
		(mid 331.521054 -256.384869)
		(end 331.802486 -256.309114)
		(width 0.09525)
		(layer "In2.Cu")
		(net "M_C_CPU0_CLK_DN<0>")
	)
	(arc
		(start 340.262464 -256.309114)
		(mid 340.446239 -256.258342)
		(end 340.631272 -256.304288)
		(width 0.09525)
		(layer "In2.Cu")
		(net "M_C_CPU0_CLK_DN<0>")
	)
	(arc
		(start 331.802486 -256.309114)
		(mid 331.986261 -256.258342)
		(end 332.171294 -256.304288)
		(width 0.09525)
		(layer "In2.Cu")
		(net "M_C_CPU0_CLK_DN<0>")
	)
	(arc
		(start 329.922632 -256.309114)
		(mid 330.1111 -256.258437)
		(end 330.299568 -256.309114)
		(width 0.09525)
		(layer "In2.Cu")
		(net "M_C_CPU0_CLK_DN<0>")
	)
	(arc
		(start 330.299568 -256.309114)
		(mid 330.581 -256.384869)
		(end 330.862432 -256.309114)
		(width 0.09525)
		(layer "In2.Cu")
		(net "M_C_CPU0_CLK_DN<0>")
	)
	(arc
		(start 334.059784 -256.309114)
		(mid 334.341216 -256.384869)
		(end 334.622648 -256.309114)
		(width 0.09525)
		(layer "In2.Cu")
		(net "M_C_CPU0_CLK_DN<0>")
	)
	(arc
		(start 337.450938 -256.304288)
		(mid 337.63597 -256.258374)
		(end 337.819746 -256.309114)
		(width 0.09525)
		(layer "In2.Cu")
		(net "M_C_CPU0_CLK_DN<0>")
	)
	(arc
		(start 341.2109 -256.304288)
		(mid 341.395932 -256.258374)
		(end 341.579708 -256.309114)
		(width 0.09525)
		(layer "In2.Cu")
		(net "M_C_CPU0_CLK_DN<0>")
	)
	(arc
		(start 328.042524 -256.309114)
		(mid 328.226299 -256.258342)
		(end 328.411332 -256.304288)
		(width 0.09525)
		(layer "In2.Cu")
		(net "M_C_CPU0_CLK_DN<0>")
	)
	(arc
		(start 326.162162 -256.309114)
		(mid 326.342441 -256.258283)
		(end 326.524874 -256.300732)
		(width 0.09525)
		(layer "In2.Cu")
		(net "M_C_CPU0_CLK_DN<0>")
	)
	(arc
		(start 333.690976 -256.304288)
		(mid 333.876008 -256.258374)
		(end 334.059784 -256.309114)
		(width 0.09525)
		(layer "In2.Cu")
		(net "M_C_CPU0_CLK_DN<0>")
	)
	(arc
		(start 334.622648 -256.309114)
		(mid 334.811116 -256.258437)
		(end 334.999584 -256.309114)
		(width 0.09525)
		(layer "In2.Cu")
		(net "M_C_CPU0_CLK_DN<0>")
	)
	(arc
		(start 326.084946 -256.368042)
		(mid 326.12165 -256.336084)
		(end 326.162162 -256.309114)
		(width 0.09525)
		(layer "In2.Cu")
		(net "M_C_CPU0_CLK_DN<0>")
	)
	(arc
		(start 335.939638 -256.309114)
		(mid 336.22107 -256.384869)
		(end 336.502502 -256.309114)
		(width 0.09525)
		(layer "In2.Cu")
		(net "M_C_CPU0_CLK_DN<0>")
	)
	(arc
		(start 332.750922 -256.304288)
		(mid 332.935954 -256.258374)
		(end 333.11973 -256.309114)
		(width 0.09525)
		(layer "In2.Cu")
		(net "M_C_CPU0_CLK_DN<0>")
	)
	(arc
		(start 333.11973 -256.309114)
		(mid 333.401162 -256.384869)
		(end 333.682594 -256.309114)
		(width 0.09525)
		(layer "In2.Cu")
		(net "M_C_CPU0_CLK_DN<0>")
	)
	(arc
		(start 339.6996 -256.309114)
		(mid 339.981032 -256.384869)
		(end 340.262464 -256.309114)
		(width 0.09525)
		(layer "In2.Cu")
		(net "M_C_CPU0_CLK_DN<0>")
	)
	(arc
		(start 332.179676 -256.309114)
		(mid 332.461108 -256.384869)
		(end 332.74254 -256.309114)
		(width 0.09525)
		(layer "In2.Cu")
		(net "M_C_CPU0_CLK_DN<0>")
	)
	(arc
		(start 337.819746 -256.309114)
		(mid 338.101178 -256.384869)
		(end 338.38261 -256.309114)
		(width 0.09525)
		(layer "In2.Cu")
		(net "M_C_CPU0_CLK_DN<0>")
	)
	(arc
		(start 328.419714 -256.309114)
		(mid 328.701146 -256.384869)
		(end 328.982578 -256.309114)
		(width 0.09525)
		(layer "In2.Cu")
		(net "M_C_CPU0_CLK_DN<0>")
	)
	(arc
		(start 341.579708 -256.309114)
		(mid 341.813252 -256.38282)
		(end 342.055958 -256.350008)
		(width 0.09525)
		(layer "In2.Cu")
		(net "M_C_CPU0_CLK_DN<0>")
	)
	(arc
		(start 339.32241 -256.309114)
		(mid 339.506185 -256.258342)
		(end 339.691218 -256.304288)
		(width 0.09525)
		(layer "In2.Cu")
		(net "M_C_CPU0_CLK_DN<0>")
	)
	(arc
		(start 342.055958 -256.350008)
		(mid 342.066157 -256.346171)
		(end 342.076278 -256.342134)
		(width 0.09525)
		(layer "In2.Cu")
		(net "M_C_CPU0_CLK_DN<0>")
	)
	(segment
		(start 343.737946 -250.420124)
		(end 343.271094 -250.154186)
		(width 0.10668)
		(layer "F.Cu")
		(net "M_C_CPU0_ALERT_R_N")
	)
	(segment
		(start 342.152478 -250.481592)
		(end 342.144096 -250.476766)
		(width 0.0889)
		(layer "In2.Cu")
		(net "M_C_CPU0_ALERT_R_N")
	)
	(segment
		(start 324.374764 -250.40336)
		(end 324.276974 -250.50115)
		(width 0.0889)
		(layer "In2.Cu")
		(net "M_C_CPU0_ALERT_R_N")
	)
	(segment
		(start 324.000114 -250.50115)
		(end 322.29806 -250.50115)
		(width 0.11684)
		(layer "In2.Cu")
		(net "M_C_CPU0_ALERT_R_N")
	)
	(segment
		(start 341.212424 -250.481592)
		(end 341.204042 -250.476766)
		(width 0.0889)
		(layer "In2.Cu")
		(net "M_C_CPU0_ALERT_R_N")
	)
	(segment
		(start 314.021724 -250.357132)
		(end 312.222896 -250.357132)
		(width 0.11684)
		(layer "In2.Cu")
		(net "M_C_CPU0_ALERT_R_N")
	)
	(segment
		(start 331.238098 -250.476766)
		(end 331.229716 -250.481592)
		(width 0.0889)
		(layer "In2.Cu")
		(net "M_C_CPU0_ALERT_R_N")
	)
	(segment
		(start 293.677086 -244.531642)
		(end 293.677086 -244.08511)
		(width 0.11684)
		(layer "In2.Cu")
		(net "M_C_CPU0_ALERT_R_N")
	)
	(segment
		(start 324.276974 -250.50115)
		(end 324.000114 -250.50115)
		(width 0.0889)
		(layer "In2.Cu")
		(net "M_C_CPU0_ALERT_R_N")
	)
	(segment
		(start 333.6925 -250.481592)
		(end 333.684118 -250.476766)
		(width 0.0889)
		(layer "In2.Cu")
		(net "M_C_CPU0_ALERT_R_N")
	)
	(segment
		(start 343.425018 -250.419616)
		(end 343.402666 -250.502928)
		(width 0.0889)
		(layer "In2.Cu")
		(net "M_C_CPU0_ALERT_R_N")
	)
	(segment
		(start 340.63813 -250.476766)
		(end 340.629748 -250.481592)
		(width 0.0889)
		(layer "In2.Cu")
		(net "M_C_CPU0_ALERT_R_N")
	)
	(segment
		(start 325.941436 -250.40336)
		(end 324.374764 -250.40336)
		(width 0.0889)
		(layer "In2.Cu")
		(net "M_C_CPU0_ALERT_R_N")
	)
	(segment
		(start 315.651896 -249.682)
		(end 314.021724 -250.357132)
		(width 0.11684)
		(layer "In2.Cu")
		(net "M_C_CPU0_ALERT_R_N")
	)
	(segment
		(start 322.29806 -250.50115)
		(end 321.47891 -249.682)
		(width 0.11684)
		(layer "In2.Cu")
		(net "M_C_CPU0_ALERT_R_N")
	)
	(segment
		(start 335.938114 -250.476766)
		(end 335.929732 -250.481592)
		(width 0.0889)
		(layer "In2.Cu")
		(net "M_C_CPU0_ALERT_R_N")
	)
	(segment
		(start 327.478136 -250.476766)
		(end 327.469754 -250.481592)
		(width 0.0889)
		(layer "In2.Cu")
		(net "M_C_CPU0_ALERT_R_N")
	)
	(segment
		(start 343.271094 -250.154186)
		(end 343.425018 -250.419616)
		(width 0.0889)
		(layer "In2.Cu")
		(net "M_C_CPU0_ALERT_R_N")
	)
	(segment
		(start 338.392516 -250.481592)
		(end 338.384134 -250.476766)
		(width 0.0889)
		(layer "In2.Cu")
		(net "M_C_CPU0_ALERT_R_N")
	)
	(segment
		(start 312.222896 -250.357132)
		(end 308.081934 -246.21617)
		(width 0.11684)
		(layer "In2.Cu")
		(net "M_C_CPU0_ALERT_R_N")
	)
	(segment
		(start 337.452462 -250.481592)
		(end 337.44408 -250.476766)
		(width 0.0889)
		(layer "In2.Cu")
		(net "M_C_CPU0_ALERT_R_N")
	)
	(segment
		(start 295.361614 -246.21617)
		(end 293.677086 -244.531642)
		(width 0.11684)
		(layer "In2.Cu")
		(net "M_C_CPU0_ALERT_R_N")
	)
	(segment
		(start 332.752446 -250.481592)
		(end 332.744064 -250.476766)
		(width 0.0889)
		(layer "In2.Cu")
		(net "M_C_CPU0_ALERT_R_N")
	)
	(segment
		(start 328.992484 -250.481592)
		(end 328.984102 -250.476766)
		(width 0.0889)
		(layer "In2.Cu")
		(net "M_C_CPU0_ALERT_R_N")
	)
	(segment
		(start 332.178152 -250.476766)
		(end 332.16977 -250.481592)
		(width 0.0889)
		(layer "In2.Cu")
		(net "M_C_CPU0_ALERT_R_N")
	)
	(segment
		(start 308.081934 -246.21617)
		(end 295.361614 -246.21617)
		(width 0.11684)
		(layer "In2.Cu")
		(net "M_C_CPU0_ALERT_R_N")
	)
	(segment
		(start 326.189086 -250.489974)
		(end 326.139556 -250.461526)
		(width 0.0889)
		(layer "In2.Cu")
		(net "M_C_CPU0_ALERT_R_N")
	)
	(segment
		(start 321.47891 -249.682)
		(end 315.651896 -249.682)
		(width 0.11684)
		(layer "In2.Cu")
		(net "M_C_CPU0_ALERT_R_N")
	)
	(segment
		(start 328.41819 -250.476766)
		(end 328.409808 -250.481592)
		(width 0.0889)
		(layer "In2.Cu")
		(net "M_C_CPU0_ALERT_R_N")
	)
	(segment
		(start 336.878168 -250.476766)
		(end 336.869786 -250.481592)
		(width 0.0889)
		(layer "In2.Cu")
		(net "M_C_CPU0_ALERT_R_N")
	)
	(arc
		(start 339.324188 -250.476766)
		(mid 339.041232 -250.400589)
		(end 338.758276 -250.476766)
		(width 0.0889)
		(layer "In2.Cu")
		(net "M_C_CPU0_ALERT_R_N")
	)
	(arc
		(start 340.629748 -250.481592)
		(mid 340.44624 -250.527086)
		(end 340.263988 -250.476766)
		(width 0.0889)
		(layer "In2.Cu")
		(net "M_C_CPU0_ALERT_R_N")
	)
	(arc
		(start 335.563972 -250.476766)
		(mid 335.281016 -250.400589)
		(end 334.99806 -250.476766)
		(width 0.0889)
		(layer "In2.Cu")
		(net "M_C_CPU0_ALERT_R_N")
	)
	(arc
		(start 332.744064 -250.476766)
		(mid 332.461108 -250.400589)
		(end 332.178152 -250.476766)
		(width 0.0889)
		(layer "In2.Cu")
		(net "M_C_CPU0_ALERT_R_N")
	)
	(arc
		(start 338.758276 -250.476766)
		(mid 338.576025 -250.527116)
		(end 338.392516 -250.481592)
		(width 0.0889)
		(layer "In2.Cu")
		(net "M_C_CPU0_ALERT_R_N")
	)
	(arc
		(start 341.578184 -250.476766)
		(mid 341.395933 -250.527116)
		(end 341.212424 -250.481592)
		(width 0.0889)
		(layer "In2.Cu")
		(net "M_C_CPU0_ALERT_R_N")
	)
	(arc
		(start 342.144096 -250.476766)
		(mid 341.86114 -250.400589)
		(end 341.578184 -250.476766)
		(width 0.0889)
		(layer "In2.Cu")
		(net "M_C_CPU0_ALERT_R_N")
	)
	(arc
		(start 333.684118 -250.476766)
		(mid 333.401162 -250.400589)
		(end 333.118206 -250.476766)
		(width 0.0889)
		(layer "In2.Cu")
		(net "M_C_CPU0_ALERT_R_N")
	)
	(arc
		(start 330.863956 -250.476766)
		(mid 330.581 -250.400589)
		(end 330.298044 -250.476766)
		(width 0.0889)
		(layer "In2.Cu")
		(net "M_C_CPU0_ALERT_R_N")
	)
	(arc
		(start 337.44408 -250.476766)
		(mid 337.161124 -250.400589)
		(end 336.878168 -250.476766)
		(width 0.0889)
		(layer "In2.Cu")
		(net "M_C_CPU0_ALERT_R_N")
	)
	(arc
		(start 327.103994 -250.476766)
		(mid 326.821038 -250.400589)
		(end 326.538082 -250.476766)
		(width 0.0889)
		(layer "In2.Cu")
		(net "M_C_CPU0_ALERT_R_N")
	)
	(arc
		(start 326.139556 -250.461526)
		(mid 326.043185 -250.423279)
		(end 325.941436 -250.40336)
		(width 0.0889)
		(layer "In2.Cu")
		(net "M_C_CPU0_ALERT_R_N")
	)
	(arc
		(start 342.518238 -250.476766)
		(mid 342.335987 -250.527116)
		(end 342.152478 -250.481592)
		(width 0.0889)
		(layer "In2.Cu")
		(net "M_C_CPU0_ALERT_R_N")
	)
	(arc
		(start 337.818222 -250.476766)
		(mid 337.635971 -250.527116)
		(end 337.452462 -250.481592)
		(width 0.0889)
		(layer "In2.Cu")
		(net "M_C_CPU0_ALERT_R_N")
	)
	(arc
		(start 333.118206 -250.476766)
		(mid 332.935955 -250.527116)
		(end 332.752446 -250.481592)
		(width 0.0889)
		(layer "In2.Cu")
		(net "M_C_CPU0_ALERT_R_N")
	)
	(arc
		(start 338.384134 -250.476766)
		(mid 338.101178 -250.400589)
		(end 337.818222 -250.476766)
		(width 0.0889)
		(layer "In2.Cu")
		(net "M_C_CPU0_ALERT_R_N")
	)
	(arc
		(start 335.929732 -250.481592)
		(mid 335.746224 -250.527086)
		(end 335.563972 -250.476766)
		(width 0.0889)
		(layer "In2.Cu")
		(net "M_C_CPU0_ALERT_R_N")
	)
	(arc
		(start 341.204042 -250.476766)
		(mid 340.921086 -250.400589)
		(end 340.63813 -250.476766)
		(width 0.0889)
		(layer "In2.Cu")
		(net "M_C_CPU0_ALERT_R_N")
	)
	(arc
		(start 329.924156 -250.476766)
		(mid 329.6412 -250.400589)
		(end 329.358244 -250.476766)
		(width 0.0889)
		(layer "In2.Cu")
		(net "M_C_CPU0_ALERT_R_N")
	)
	(arc
		(start 327.469754 -250.481592)
		(mid 327.286246 -250.527086)
		(end 327.103994 -250.476766)
		(width 0.0889)
		(layer "In2.Cu")
		(net "M_C_CPU0_ALERT_R_N")
	)
	(arc
		(start 328.984102 -250.476766)
		(mid 328.701146 -250.400589)
		(end 328.41819 -250.476766)
		(width 0.0889)
		(layer "In2.Cu")
		(net "M_C_CPU0_ALERT_R_N")
	)
	(arc
		(start 340.263988 -250.476766)
		(mid 339.981032 -250.400589)
		(end 339.698076 -250.476766)
		(width 0.0889)
		(layer "In2.Cu")
		(net "M_C_CPU0_ALERT_R_N")
	)
	(arc
		(start 334.99806 -250.476766)
		(mid 334.811116 -250.527021)
		(end 334.624172 -250.476766)
		(width 0.0889)
		(layer "In2.Cu")
		(net "M_C_CPU0_ALERT_R_N")
	)
	(arc
		(start 330.298044 -250.476766)
		(mid 330.1111 -250.527021)
		(end 329.924156 -250.476766)
		(width 0.0889)
		(layer "In2.Cu")
		(net "M_C_CPU0_ALERT_R_N")
	)
	(arc
		(start 343.402666 -250.502928)
		(mid 343.240477 -250.525663)
		(end 343.08415 -250.476766)
		(width 0.0889)
		(layer "In2.Cu")
		(net "M_C_CPU0_ALERT_R_N")
	)
	(arc
		(start 336.869786 -250.481592)
		(mid 336.686278 -250.527086)
		(end 336.504026 -250.476766)
		(width 0.0889)
		(layer "In2.Cu")
		(net "M_C_CPU0_ALERT_R_N")
	)
	(arc
		(start 339.698076 -250.476766)
		(mid 339.511132 -250.527021)
		(end 339.324188 -250.476766)
		(width 0.0889)
		(layer "In2.Cu")
		(net "M_C_CPU0_ALERT_R_N")
	)
	(arc
		(start 343.08415 -250.476766)
		(mid 342.801194 -250.400589)
		(end 342.518238 -250.476766)
		(width 0.0889)
		(layer "In2.Cu")
		(net "M_C_CPU0_ALERT_R_N")
	)
	(arc
		(start 332.16977 -250.481592)
		(mid 331.986262 -250.527086)
		(end 331.80401 -250.476766)
		(width 0.0889)
		(layer "In2.Cu")
		(net "M_C_CPU0_ALERT_R_N")
	)
	(arc
		(start 331.229716 -250.481592)
		(mid 331.046208 -250.527086)
		(end 330.863956 -250.476766)
		(width 0.0889)
		(layer "In2.Cu")
		(net "M_C_CPU0_ALERT_R_N")
	)
	(arc
		(start 334.05826 -250.476766)
		(mid 333.876009 -250.527116)
		(end 333.6925 -250.481592)
		(width 0.0889)
		(layer "In2.Cu")
		(net "M_C_CPU0_ALERT_R_N")
	)
	(arc
		(start 334.624172 -250.476766)
		(mid 334.341216 -250.400589)
		(end 334.05826 -250.476766)
		(width 0.0889)
		(layer "In2.Cu")
		(net "M_C_CPU0_ALERT_R_N")
	)
	(arc
		(start 328.409808 -250.481592)
		(mid 328.2263 -250.527086)
		(end 328.044048 -250.476766)
		(width 0.0889)
		(layer "In2.Cu")
		(net "M_C_CPU0_ALERT_R_N")
	)
	(arc
		(start 336.504026 -250.476766)
		(mid 336.22107 -250.400589)
		(end 335.938114 -250.476766)
		(width 0.0889)
		(layer "In2.Cu")
		(net "M_C_CPU0_ALERT_R_N")
	)
	(arc
		(start 326.538082 -250.476766)
		(mid 326.365227 -250.526755)
		(end 326.189086 -250.489974)
		(width 0.0889)
		(layer "In2.Cu")
		(net "M_C_CPU0_ALERT_R_N")
	)
	(arc
		(start 329.358244 -250.476766)
		(mid 329.175993 -250.527116)
		(end 328.992484 -250.481592)
		(width 0.0889)
		(layer "In2.Cu")
		(net "M_C_CPU0_ALERT_R_N")
	)
	(arc
		(start 328.044048 -250.476766)
		(mid 327.761092 -250.400589)
		(end 327.478136 -250.476766)
		(width 0.0889)
		(layer "In2.Cu")
		(net "M_C_CPU0_ALERT_R_N")
	)
	(arc
		(start 331.80401 -250.476766)
		(mid 331.521054 -250.400589)
		(end 331.238098 -250.476766)
		(width 0.0889)
		(layer "In2.Cu")
		(net "M_C_CPU0_ALERT_R_N")
	)
	(via
		(at 292.280086 -244.08511)
		(size 0.4826)
		(drill 0.254)
		(layers "F.Cu" "B.Cu")
		(net "M_C_CPU0_ALERT_N")
	)
	(segment
		(start 292.876986 -244.08511)
		(end 292.280086 -244.08511)
		(width 0.10668)
		(layer "B.Cu")
		(net "M_C_CPU0_ALERT_N")
	)
	(segment
		(start 88.577928 -267.340334)
		(end 88.111076 -267.606272)
		(width 0.10668)
		(layer "F.Cu")
		(net "M_B_CPU1_SB_RSP<0>")
	)
	(segment
		(start 58.065416 -269.713964)
		(end 57.768998 -270.010382)
		(width 0.11684)
		(layer "In13.Cu")
		(net "M_B_CPU1_SB_RSP<0>")
	)
	(segment
		(start 82.66557 -267.917168)
		(end 82.654902 -267.923264)
		(width 0.0889)
		(layer "In13.Cu")
		(net "M_B_CPU1_SB_RSP<0>")
	)
	(segment
		(start 54.80685 -269.713964)
		(end 54.574948 -269.713964)
		(width 0.11684)
		(layer "In13.Cu")
		(net "M_B_CPU1_SB_RSP<0>")
	)
	(segment
		(start 56.712358 -270.010382)
		(end 56.480456 -270.010382)
		(width 0.11684)
		(layer "In13.Cu")
		(net "M_B_CPU1_SB_RSP<0>")
	)
	(segment
		(start 55.103268 -270.010382)
		(end 54.80685 -269.713964)
		(width 0.11684)
		(layer "In13.Cu")
		(net "M_B_CPU1_SB_RSP<0>")
	)
	(segment
		(start 58.825638 -270.010382)
		(end 58.593736 -270.010382)
		(width 0.11684)
		(layer "In13.Cu")
		(net "M_B_CPU1_SB_RSP<0>")
	)
	(segment
		(start 76.83119 -267.230606)
		(end 76.451968 -266.851384)
		(width 0.0889)
		(layer "In13.Cu")
		(net "M_B_CPU1_SB_RSP<0>")
	)
	(segment
		(start 58.593736 -270.010382)
		(end 58.297318 -269.713964)
		(width 0.11684)
		(layer "In13.Cu")
		(net "M_B_CPU1_SB_RSP<0>")
	)
	(segment
		(start 79.859378 -267.909548)
		(end 79.83601 -267.923264)
		(width 0.0889)
		(layer "In13.Cu")
		(net "M_B_CPU1_SB_RSP<0>")
	)
	(segment
		(start 52.309014 -270.010382)
		(end 51.884072 -270.435324)
		(width 0.11684)
		(layer "In13.Cu")
		(net "M_B_CPU1_SB_RSP<0>")
	)
	(segment
		(start 78.452218 -267.865098)
		(end 77.817726 -267.230606)
		(width 0.0889)
		(layer "In13.Cu")
		(net "M_B_CPU1_SB_RSP<0>")
	)
	(segment
		(start 55.655718 -270.010382)
		(end 55.103268 -270.010382)
		(width 0.11684)
		(layer "In13.Cu")
		(net "M_B_CPU1_SB_RSP<0>")
	)
	(segment
		(start 56.184038 -269.713964)
		(end 55.952136 -269.713964)
		(width 0.11684)
		(layer "In13.Cu")
		(net "M_B_CPU1_SB_RSP<0>")
	)
	(segment
		(start 86.987126 -267.923264)
		(end 86.976458 -267.917168)
		(width 0.0889)
		(layer "In13.Cu")
		(net "M_B_CPU1_SB_RSP<0>")
	)
	(segment
		(start 59.353958 -269.713964)
		(end 59.122056 -269.713964)
		(width 0.11684)
		(layer "In13.Cu")
		(net "M_B_CPU1_SB_RSP<0>")
	)
	(segment
		(start 86.047072 -267.923264)
		(end 86.036404 -267.917168)
		(width 0.0889)
		(layer "In13.Cu")
		(net "M_B_CPU1_SB_RSP<0>")
	)
	(segment
		(start 83.605624 -267.917168)
		(end 83.594956 -267.923264)
		(width 0.0889)
		(layer "In13.Cu")
		(net "M_B_CPU1_SB_RSP<0>")
	)
	(segment
		(start 62.279784 -266.851384)
		(end 60.539376 -268.591792)
		(width 0.11684)
		(layer "In13.Cu")
		(net "M_B_CPU1_SB_RSP<0>")
	)
	(segment
		(start 60.539376 -269.353284)
		(end 59.882278 -270.010382)
		(width 0.11684)
		(layer "In13.Cu")
		(net "M_B_CPU1_SB_RSP<0>")
	)
	(segment
		(start 59.122056 -269.713964)
		(end 58.825638 -270.010382)
		(width 0.11684)
		(layer "In13.Cu")
		(net "M_B_CPU1_SB_RSP<0>")
	)
	(segment
		(start 78.918308 -267.909548)
		(end 78.89494 -267.923264)
		(width 0.0889)
		(layer "In13.Cu")
		(net "M_B_CPU1_SB_RSP<0>")
	)
	(segment
		(start 87.92718 -267.923264)
		(end 87.916512 -267.917168)
		(width 0.0889)
		(layer "In13.Cu")
		(net "M_B_CPU1_SB_RSP<0>")
	)
	(segment
		(start 78.544674 -267.932662)
		(end 78.528164 -267.923264)
		(width 0.0889)
		(layer "In13.Cu")
		(net "M_B_CPU1_SB_RSP<0>")
	)
	(segment
		(start 76.451968 -266.851384)
		(end 75.968606 -266.851384)
		(width 0.0889)
		(layer "In13.Cu")
		(net "M_B_CPU1_SB_RSP<0>")
	)
	(segment
		(start 57.240678 -269.713964)
		(end 57.008776 -269.713964)
		(width 0.11684)
		(layer "In13.Cu")
		(net "M_B_CPU1_SB_RSP<0>")
	)
	(segment
		(start 88.25992 -267.862558)
		(end 88.236552 -267.950442)
		(width 0.0889)
		(layer "In13.Cu")
		(net "M_B_CPU1_SB_RSP<0>")
	)
	(segment
		(start 60.539376 -268.591792)
		(end 60.539376 -269.353284)
		(width 0.11684)
		(layer "In13.Cu")
		(net "M_B_CPU1_SB_RSP<0>")
	)
	(segment
		(start 59.882278 -270.010382)
		(end 59.650376 -270.010382)
		(width 0.11684)
		(layer "In13.Cu")
		(net "M_B_CPU1_SB_RSP<0>")
	)
	(segment
		(start 58.297318 -269.713964)
		(end 58.065416 -269.713964)
		(width 0.11684)
		(layer "In13.Cu")
		(net "M_B_CPU1_SB_RSP<0>")
	)
	(segment
		(start 88.111076 -267.606272)
		(end 88.25992 -267.862558)
		(width 0.0889)
		(layer "In13.Cu")
		(net "M_B_CPU1_SB_RSP<0>")
	)
	(segment
		(start 79.83601 -267.923264)
		(end 79.812388 -267.936726)
		(width 0.0889)
		(layer "In13.Cu")
		(net "M_B_CPU1_SB_RSP<0>")
	)
	(segment
		(start 75.968606 -266.851384)
		(end 62.279784 -266.851384)
		(width 0.11684)
		(layer "In13.Cu")
		(net "M_B_CPU1_SB_RSP<0>")
	)
	(segment
		(start 82.28711 -267.923264)
		(end 82.276442 -267.917168)
		(width 0.0889)
		(layer "In13.Cu")
		(net "M_B_CPU1_SB_RSP<0>")
	)
	(segment
		(start 54.574948 -269.713964)
		(end 54.27853 -270.010382)
		(width 0.11684)
		(layer "In13.Cu")
		(net "M_B_CPU1_SB_RSP<0>")
	)
	(segment
		(start 56.480456 -270.010382)
		(end 56.184038 -269.713964)
		(width 0.11684)
		(layer "In13.Cu")
		(net "M_B_CPU1_SB_RSP<0>")
	)
	(segment
		(start 59.650376 -270.010382)
		(end 59.353958 -269.713964)
		(width 0.11684)
		(layer "In13.Cu")
		(net "M_B_CPU1_SB_RSP<0>")
	)
	(segment
		(start 57.008776 -269.713964)
		(end 56.712358 -270.010382)
		(width 0.11684)
		(layer "In13.Cu")
		(net "M_B_CPU1_SB_RSP<0>")
	)
	(segment
		(start 57.537096 -270.010382)
		(end 57.240678 -269.713964)
		(width 0.11684)
		(layer "In13.Cu")
		(net "M_B_CPU1_SB_RSP<0>")
	)
	(segment
		(start 77.817726 -267.230606)
		(end 76.83119 -267.230606)
		(width 0.0889)
		(layer "In13.Cu")
		(net "M_B_CPU1_SB_RSP<0>")
	)
	(segment
		(start 57.768998 -270.010382)
		(end 57.537096 -270.010382)
		(width 0.11684)
		(layer "In13.Cu")
		(net "M_B_CPU1_SB_RSP<0>")
	)
	(segment
		(start 54.27853 -270.010382)
		(end 52.309014 -270.010382)
		(width 0.11684)
		(layer "In13.Cu")
		(net "M_B_CPU1_SB_RSP<0>")
	)
	(segment
		(start 55.952136 -269.713964)
		(end 55.655718 -270.010382)
		(width 0.11684)
		(layer "In13.Cu")
		(net "M_B_CPU1_SB_RSP<0>")
	)
	(arc
		(start 84.53501 -267.923264)
		(mid 84.351114 -267.972744)
		(end 84.167218 -267.923264)
		(width 0.0889)
		(layer "In13.Cu")
		(net "M_B_CPU1_SB_RSP<0>")
	)
	(arc
		(start 82.276442 -267.917168)
		(mid 81.994853 -267.846294)
		(end 81.714848 -267.923264)
		(width 0.0889)
		(layer "In13.Cu")
		(net "M_B_CPU1_SB_RSP<0>")
	)
	(arc
		(start 85.107018 -267.923264)
		(mid 84.821014 -267.846312)
		(end 84.53501 -267.923264)
		(width 0.0889)
		(layer "In13.Cu")
		(net "M_B_CPU1_SB_RSP<0>")
	)
	(arc
		(start 78.89494 -267.923264)
		(mid 78.721017 -267.972488)
		(end 78.544674 -267.932662)
		(width 0.0889)
		(layer "In13.Cu")
		(net "M_B_CPU1_SB_RSP<0>")
	)
	(arc
		(start 83.227164 -267.923264)
		(mid 82.94716 -267.846219)
		(end 82.66557 -267.917168)
		(width 0.0889)
		(layer "In13.Cu")
		(net "M_B_CPU1_SB_RSP<0>")
	)
	(arc
		(start 84.167218 -267.923264)
		(mid 83.887214 -267.846219)
		(end 83.605624 -267.917168)
		(width 0.0889)
		(layer "In13.Cu")
		(net "M_B_CPU1_SB_RSP<0>")
	)
	(arc
		(start 83.594956 -267.923264)
		(mid 83.41106 -267.972744)
		(end 83.227164 -267.923264)
		(width 0.0889)
		(layer "In13.Cu")
		(net "M_B_CPU1_SB_RSP<0>")
	)
	(arc
		(start 81.714848 -267.923264)
		(mid 81.530952 -267.972744)
		(end 81.347056 -267.923264)
		(width 0.0889)
		(layer "In13.Cu")
		(net "M_B_CPU1_SB_RSP<0>")
	)
	(arc
		(start 79.812388 -267.936726)
		(mid 79.638613 -267.972933)
		(end 79.468218 -267.923264)
		(width 0.0889)
		(layer "In13.Cu")
		(net "M_B_CPU1_SB_RSP<0>")
	)
	(arc
		(start 80.407256 -267.923264)
		(mid 80.135066 -267.846237)
		(end 79.859378 -267.909548)
		(width 0.0889)
		(layer "In13.Cu")
		(net "M_B_CPU1_SB_RSP<0>")
	)
	(arc
		(start 82.654902 -267.923264)
		(mid 82.471006 -267.972744)
		(end 82.28711 -267.923264)
		(width 0.0889)
		(layer "In13.Cu")
		(net "M_B_CPU1_SB_RSP<0>")
	)
	(arc
		(start 86.414864 -267.923264)
		(mid 86.230968 -267.972744)
		(end 86.047072 -267.923264)
		(width 0.0889)
		(layer "In13.Cu")
		(net "M_B_CPU1_SB_RSP<0>")
	)
	(arc
		(start 78.528164 -267.923264)
		(mid 78.488276 -267.896681)
		(end 78.452218 -267.865098)
		(width 0.0889)
		(layer "In13.Cu")
		(net "M_B_CPU1_SB_RSP<0>")
	)
	(arc
		(start 87.916512 -267.917168)
		(mid 87.634923 -267.846294)
		(end 87.354918 -267.923264)
		(width 0.0889)
		(layer "In13.Cu")
		(net "M_B_CPU1_SB_RSP<0>")
	)
	(arc
		(start 81.347056 -267.923264)
		(mid 81.061052 -267.846312)
		(end 80.775048 -267.923264)
		(width 0.0889)
		(layer "In13.Cu")
		(net "M_B_CPU1_SB_RSP<0>")
	)
	(arc
		(start 88.236552 -267.950442)
		(mid 88.078833 -267.971289)
		(end 87.92718 -267.923264)
		(width 0.0889)
		(layer "In13.Cu")
		(net "M_B_CPU1_SB_RSP<0>")
	)
	(arc
		(start 85.47481 -267.923264)
		(mid 85.290914 -267.972744)
		(end 85.107018 -267.923264)
		(width 0.0889)
		(layer "In13.Cu")
		(net "M_B_CPU1_SB_RSP<0>")
	)
	(arc
		(start 80.775048 -267.923264)
		(mid 80.591152 -267.972744)
		(end 80.407256 -267.923264)
		(width 0.0889)
		(layer "In13.Cu")
		(net "M_B_CPU1_SB_RSP<0>")
	)
	(arc
		(start 79.468218 -267.923264)
		(mid 79.195013 -267.845726)
		(end 78.918308 -267.909548)
		(width 0.0889)
		(layer "In13.Cu")
		(net "M_B_CPU1_SB_RSP<0>")
	)
	(arc
		(start 86.036404 -267.917168)
		(mid 85.754815 -267.846294)
		(end 85.47481 -267.923264)
		(width 0.0889)
		(layer "In13.Cu")
		(net "M_B_CPU1_SB_RSP<0>")
	)
	(arc
		(start 86.976458 -267.917168)
		(mid 86.694869 -267.846294)
		(end 86.414864 -267.923264)
		(width 0.0889)
		(layer "In13.Cu")
		(net "M_B_CPU1_SB_RSP<0>")
	)
	(arc
		(start 87.354918 -267.923264)
		(mid 87.171022 -267.972744)
		(end 86.987126 -267.923264)
		(width 0.0889)
		(layer "In13.Cu")
		(net "M_B_CPU1_SB_RSP<0>")
	)
	(segment
		(start 88.107774 -264.910316)
		(end 87.640922 -265.176254)
		(width 0.10668)
		(layer "F.Cu")
		(net "M_B_CPU1_SB_PAR")
	)
	(segment
		(start 83.694016 -264.853674)
		(end 83.702398 -264.848848)
		(width 0.0889)
		(layer "In13.Cu")
		(net "M_B_CPU1_SB_PAR")
	)
	(segment
		(start 47.784004 -266.984734)
		(end 48.1584 -266.610338)
		(width 0.14478)
		(layer "In13.Cu")
		(net "M_B_CPU1_SB_PAR")
	)
	(segment
		(start 79.36738 -264.853674)
		(end 79.377794 -264.85977)
		(width 0.0889)
		(layer "In13.Cu")
		(net "M_B_CPU1_SB_PAR")
	)
	(segment
		(start 59.800236 -266.610338)
		(end 61.33592 -265.074654)
		(width 0.14478)
		(layer "In13.Cu")
		(net "M_B_CPU1_SB_PAR")
	)
	(segment
		(start 76.304902 -265.074654)
		(end 76.85151 -264.528046)
		(width 0.0889)
		(layer "In13.Cu")
		(net "M_B_CPU1_SB_PAR")
	)
	(segment
		(start 87.772748 -264.827512)
		(end 87.7951 -264.910824)
		(width 0.0889)
		(layer "In13.Cu")
		(net "M_B_CPU1_SB_PAR")
	)
	(segment
		(start 87.7951 -264.910824)
		(end 87.640922 -265.176254)
		(width 0.0889)
		(layer "In13.Cu")
		(net "M_B_CPU1_SB_PAR")
	)
	(segment
		(start 61.33592 -265.074654)
		(end 75.966066 -265.074654)
		(width 0.14478)
		(layer "In13.Cu")
		(net "M_B_CPU1_SB_PAR")
	)
	(segment
		(start 86.879684 -264.848848)
		(end 86.888066 -264.853674)
		(width 0.0889)
		(layer "In13.Cu")
		(net "M_B_CPU1_SB_PAR")
	)
	(segment
		(start 83.119722 -264.848848)
		(end 83.128104 -264.853674)
		(width 0.0889)
		(layer "In13.Cu")
		(net "M_B_CPU1_SB_PAR")
	)
	(segment
		(start 76.85151 -264.528046)
		(end 78.075282 -264.528046)
		(width 0.0889)
		(layer "In13.Cu")
		(net "M_B_CPU1_SB_PAR")
	)
	(segment
		(start 78.993492 -264.853928)
		(end 79.009748 -264.84453)
		(width 0.0889)
		(layer "In13.Cu")
		(net "M_B_CPU1_SB_PAR")
	)
	(segment
		(start 80.299814 -264.848848)
		(end 80.308196 -264.853674)
		(width 0.0889)
		(layer "In13.Cu")
		(net "M_B_CPU1_SB_PAR")
	)
	(segment
		(start 87.453978 -264.853674)
		(end 87.46236 -264.848848)
		(width 0.0889)
		(layer "In13.Cu")
		(net "M_B_CPU1_SB_PAR")
	)
	(segment
		(start 47.784004 -267.03528)
		(end 47.784004 -266.984734)
		(width 0.14478)
		(layer "In13.Cu")
		(net "M_B_CPU1_SB_PAR")
	)
	(segment
		(start 48.1584 -266.610338)
		(end 59.800236 -266.610338)
		(width 0.14478)
		(layer "In13.Cu")
		(net "M_B_CPU1_SB_PAR")
	)
	(segment
		(start 75.966066 -265.074654)
		(end 76.304902 -265.074654)
		(width 0.0889)
		(layer "In13.Cu")
		(net "M_B_CPU1_SB_PAR")
	)
	(segment
		(start 82.179668 -264.848848)
		(end 82.18805 -264.853674)
		(width 0.0889)
		(layer "In13.Cu")
		(net "M_B_CPU1_SB_PAR")
	)
	(segment
		(start 78.075282 -264.528046)
		(end 78.312264 -264.765028)
		(width 0.0889)
		(layer "In13.Cu")
		(net "M_B_CPU1_SB_PAR")
	)
	(segment
		(start 78.977744 -264.863072)
		(end 78.993492 -264.853928)
		(width 0.0889)
		(layer "In13.Cu")
		(net "M_B_CPU1_SB_PAR")
	)
	(segment
		(start 85.93963 -264.848848)
		(end 85.948012 -264.853674)
		(width 0.0889)
		(layer "In13.Cu")
		(net "M_B_CPU1_SB_PAR")
	)
	(arc
		(start 81.813908 -264.853674)
		(mid 81.996159 -264.803324)
		(end 82.179668 -264.848848)
		(width 0.0889)
		(layer "In13.Cu")
		(net "M_B_CPU1_SB_PAR")
	)
	(arc
		(start 84.068158 -264.853674)
		(mid 84.351114 -264.929851)
		(end 84.63407 -264.853674)
		(width 0.0889)
		(layer "In13.Cu")
		(net "M_B_CPU1_SB_PAR")
	)
	(arc
		(start 79.377794 -264.85977)
		(mid 79.65648 -264.92999)
		(end 79.933546 -264.853674)
		(width 0.0889)
		(layer "In13.Cu")
		(net "M_B_CPU1_SB_PAR")
	)
	(arc
		(start 83.702398 -264.848848)
		(mid 83.885906 -264.803354)
		(end 84.068158 -264.853674)
		(width 0.0889)
		(layer "In13.Cu")
		(net "M_B_CPU1_SB_PAR")
	)
	(arc
		(start 82.18805 -264.853674)
		(mid 82.471006 -264.929851)
		(end 82.753962 -264.853674)
		(width 0.0889)
		(layer "In13.Cu")
		(net "M_B_CPU1_SB_PAR")
	)
	(arc
		(start 83.128104 -264.853674)
		(mid 83.41106 -264.929851)
		(end 83.694016 -264.853674)
		(width 0.0889)
		(layer "In13.Cu")
		(net "M_B_CPU1_SB_PAR")
	)
	(arc
		(start 85.57387 -264.853674)
		(mid 85.756121 -264.803324)
		(end 85.93963 -264.848848)
		(width 0.0889)
		(layer "In13.Cu")
		(net "M_B_CPU1_SB_PAR")
	)
	(arc
		(start 87.46236 -264.848848)
		(mid 87.61523 -264.804207)
		(end 87.772748 -264.827512)
		(width 0.0889)
		(layer "In13.Cu")
		(net "M_B_CPU1_SB_PAR")
	)
	(arc
		(start 85.948012 -264.853674)
		(mid 86.230968 -264.929851)
		(end 86.513924 -264.853674)
		(width 0.0889)
		(layer "In13.Cu")
		(net "M_B_CPU1_SB_PAR")
	)
	(arc
		(start 85.007958 -264.853674)
		(mid 85.290914 -264.929851)
		(end 85.57387 -264.853674)
		(width 0.0889)
		(layer "In13.Cu")
		(net "M_B_CPU1_SB_PAR")
	)
	(arc
		(start 86.513924 -264.853674)
		(mid 86.696175 -264.803324)
		(end 86.879684 -264.848848)
		(width 0.0889)
		(layer "In13.Cu")
		(net "M_B_CPU1_SB_PAR")
	)
	(arc
		(start 81.247996 -264.853674)
		(mid 81.530952 -264.929851)
		(end 81.813908 -264.853674)
		(width 0.0889)
		(layer "In13.Cu")
		(net "M_B_CPU1_SB_PAR")
	)
	(arc
		(start 78.312264 -264.765028)
		(mid 78.367049 -264.813088)
		(end 78.42758 -264.853674)
		(width 0.0889)
		(layer "In13.Cu")
		(net "M_B_CPU1_SB_PAR")
	)
	(arc
		(start 80.874108 -264.853674)
		(mid 81.061052 -264.803419)
		(end 81.247996 -264.853674)
		(width 0.0889)
		(layer "In13.Cu")
		(net "M_B_CPU1_SB_PAR")
	)
	(arc
		(start 79.933546 -264.853674)
		(mid 80.116051 -264.803197)
		(end 80.299814 -264.848848)
		(width 0.0889)
		(layer "In13.Cu")
		(net "M_B_CPU1_SB_PAR")
	)
	(arc
		(start 78.42758 -264.853674)
		(mid 78.701435 -264.930024)
		(end 78.977744 -264.863072)
		(width 0.0889)
		(layer "In13.Cu")
		(net "M_B_CPU1_SB_PAR")
	)
	(arc
		(start 82.753962 -264.853674)
		(mid 82.936213 -264.803324)
		(end 83.119722 -264.848848)
		(width 0.0889)
		(layer "In13.Cu")
		(net "M_B_CPU1_SB_PAR")
	)
	(arc
		(start 79.009748 -264.84453)
		(mid 79.18973 -264.80343)
		(end 79.36738 -264.853674)
		(width 0.0889)
		(layer "In13.Cu")
		(net "M_B_CPU1_SB_PAR")
	)
	(arc
		(start 86.888066 -264.853674)
		(mid 87.171022 -264.929851)
		(end 87.453978 -264.853674)
		(width 0.0889)
		(layer "In13.Cu")
		(net "M_B_CPU1_SB_PAR")
	)
	(arc
		(start 80.308196 -264.853674)
		(mid 80.591152 -264.929851)
		(end 80.874108 -264.853674)
		(width 0.0889)
		(layer "In13.Cu")
		(net "M_B_CPU1_SB_PAR")
	)
	(arc
		(start 84.63407 -264.853674)
		(mid 84.821014 -264.803419)
		(end 85.007958 -264.853674)
		(width 0.0889)
		(layer "In13.Cu")
		(net "M_B_CPU1_SB_PAR")
	)
	(segment
		(start 88.577928 -270.580358)
		(end 88.111076 -270.846296)
		(width 0.12954)
		(layer "F.Cu")
		(net "M_B_CPU1_SB_DQS_DP<9>")
	)
	(segment
		(start 55.857648 -274.773898)
		(end 55.484776 -274.401026)
		(width 0.16002)
		(layer "In13.Cu")
		(net "M_B_CPU1_SB_DQS_DP<9>")
	)
	(segment
		(start 62.489842 -271.567402)
		(end 62.489842 -272.043906)
		(width 0.16002)
		(layer "In13.Cu")
		(net "M_B_CPU1_SB_DQS_DP<9>")
	)
	(segment
		(start 60.168028 -273.889216)
		(end 59.744102 -274.313142)
		(width 0.16002)
		(layer "In13.Cu")
		(net "M_B_CPU1_SB_DQS_DP<9>")
	)
	(segment
		(start 76.055728 -269.592806)
		(end 75.996546 -269.533624)
		(width 0.09525)
		(layer "In13.Cu")
		(net "M_B_CPU1_SB_DQS_DP<9>")
	)
	(segment
		(start 76.833476 -270.143986)
		(end 76.282296 -269.592806)
		(width 0.09525)
		(layer "In13.Cu")
		(net "M_B_CPU1_SB_DQS_DP<9>")
	)
	(segment
		(start 61.186822 -273.486626)
		(end 61.186822 -273.712686)
		(width 0.16002)
		(layer "In13.Cu")
		(net "M_B_CPU1_SB_DQS_DP<9>")
	)
	(segment
		(start 61.540898 -272.516346)
		(end 61.116972 -272.940272)
		(width 0.16002)
		(layer "In13.Cu")
		(net "M_B_CPU1_SB_DQS_DP<9>")
	)
	(segment
		(start 61.116972 -272.940272)
		(end 61.116972 -273.416776)
		(width 0.16002)
		(layer "In13.Cu")
		(net "M_B_CPU1_SB_DQS_DP<9>")
	)
	(segment
		(start 86.050882 -271.176242)
		(end 86.0425 -271.171416)
		(width 0.09525)
		(layer "In13.Cu")
		(net "M_B_CPU1_SB_DQS_DP<9>")
	)
	(segment
		(start 56.053482 -275.987764)
		(end 55.857648 -275.79193)
		(width 0.16002)
		(layer "In13.Cu")
		(net "M_B_CPU1_SB_DQS_DP<9>")
	)
	(segment
		(start 59.813952 -274.859496)
		(end 59.813952 -275.085556)
		(width 0.16002)
		(layer "In13.Cu")
		(net "M_B_CPU1_SB_DQS_DP<9>")
	)
	(segment
		(start 54.38902 -275.987764)
		(end 54.039516 -275.987764)
		(width 0.16002)
		(layer "In13.Cu")
		(net "M_B_CPU1_SB_DQS_DP<9>")
	)
	(segment
		(start 88.111076 -270.846296)
		(end 87.957152 -271.111726)
		(width 0.09525)
		(layer "In13.Cu")
		(net "M_B_CPU1_SB_DQS_DP<9>")
	)
	(segment
		(start 63.932562 -270.966946)
		(end 63.686182 -271.213326)
		(width 0.16002)
		(layer "In13.Cu")
		(net "M_B_CPU1_SB_DQS_DP<9>")
	)
	(segment
		(start 60.644532 -273.889216)
		(end 60.168028 -273.889216)
		(width 0.16002)
		(layer "In13.Cu")
		(net "M_B_CPU1_SB_DQS_DP<9>")
	)
	(segment
		(start 65.365884 -269.533624)
		(end 65.128902 -269.770606)
		(width 0.16002)
		(layer "In13.Cu")
		(net "M_B_CPU1_SB_DQS_DP<9>")
	)
	(segment
		(start 59.744102 -274.313142)
		(end 59.744102 -274.789646)
		(width 0.16002)
		(layer "In13.Cu")
		(net "M_B_CPU1_SB_DQS_DP<9>")
	)
	(segment
		(start 59.526678 -275.37283)
		(end 58.870088 -275.37283)
		(width 0.16002)
		(layer "In13.Cu")
		(net "M_B_CPU1_SB_DQS_DP<9>")
	)
	(segment
		(start 64.286638 -269.770606)
		(end 63.862712 -270.194532)
		(width 0.16002)
		(layer "In13.Cu")
		(net "M_B_CPU1_SB_DQS_DP<9>")
	)
	(segment
		(start 81.350866 -271.176242)
		(end 81.342484 -271.171416)
		(width 0.09525)
		(layer "In13.Cu")
		(net "M_B_CPU1_SB_DQS_DP<9>")
	)
	(segment
		(start 62.313312 -272.586196)
		(end 62.087252 -272.586196)
		(width 0.16002)
		(layer "In13.Cu")
		(net "M_B_CPU1_SB_DQS_DP<9>")
	)
	(segment
		(start 61.116972 -273.416776)
		(end 61.186822 -273.486626)
		(width 0.16002)
		(layer "In13.Cu")
		(net "M_B_CPU1_SB_DQS_DP<9>")
	)
	(segment
		(start 79.650336 -271.222978)
		(end 78.540102 -271.222978)
		(width 0.09525)
		(layer "In13.Cu")
		(net "M_B_CPU1_SB_DQS_DP<9>")
	)
	(segment
		(start 62.489842 -272.043906)
		(end 62.559692 -272.113756)
		(width 0.16002)
		(layer "In13.Cu")
		(net "M_B_CPU1_SB_DQS_DP<9>")
	)
	(segment
		(start 80.40243 -271.171416)
		(end 80.392016 -271.16532)
		(width 0.09525)
		(layer "In13.Cu")
		(net "M_B_CPU1_SB_DQS_DP<9>")
	)
	(segment
		(start 75.972924 -269.533624)
		(end 65.365884 -269.533624)
		(width 0.16002)
		(layer "In13.Cu")
		(net "M_B_CPU1_SB_DQS_DP<9>")
	)
	(segment
		(start 59.744102 -274.789646)
		(end 59.813952 -274.859496)
		(width 0.16002)
		(layer "In13.Cu")
		(net "M_B_CPU1_SB_DQS_DP<9>")
	)
	(segment
		(start 87.957152 -271.111726)
		(end 87.856314 -271.138396)
		(width 0.09525)
		(layer "In13.Cu")
		(net "M_B_CPU1_SB_DQS_DP<9>")
	)
	(segment
		(start 57.774586 -275.149564)
		(end 56.936386 -275.987764)
		(width 0.16002)
		(layer "In13.Cu")
		(net "M_B_CPU1_SB_DQS_DP<9>")
	)
	(segment
		(start 58.870088 -275.37283)
		(end 58.646822 -275.149564)
		(width 0.16002)
		(layer "In13.Cu")
		(net "M_B_CPU1_SB_DQS_DP<9>")
	)
	(segment
		(start 62.559692 -272.113756)
		(end 62.559692 -272.339816)
		(width 0.16002)
		(layer "In13.Cu")
		(net "M_B_CPU1_SB_DQS_DP<9>")
	)
	(segment
		(start 78.540102 -271.222978)
		(end 77.46111 -270.143986)
		(width 0.09525)
		(layer "In13.Cu")
		(net "M_B_CPU1_SB_DQS_DP<9>")
	)
	(segment
		(start 83.599528 -271.171416)
		(end 83.591146 -271.176242)
		(width 0.09525)
		(layer "In13.Cu")
		(net "M_B_CPU1_SB_DQS_DP<9>")
	)
	(segment
		(start 54.584854 -275.79193)
		(end 54.38902 -275.987764)
		(width 0.16002)
		(layer "In13.Cu")
		(net "M_B_CPU1_SB_DQS_DP<9>")
	)
	(segment
		(start 85.110828 -271.176242)
		(end 85.102446 -271.171416)
		(width 0.09525)
		(layer "In13.Cu")
		(net "M_B_CPU1_SB_DQS_DP<9>")
	)
	(segment
		(start 76.282296 -269.592806)
		(end 76.055728 -269.592806)
		(width 0.09525)
		(layer "In13.Cu")
		(net "M_B_CPU1_SB_DQS_DP<9>")
	)
	(segment
		(start 62.087252 -272.586196)
		(end 62.017402 -272.516346)
		(width 0.16002)
		(layer "In13.Cu")
		(net "M_B_CPU1_SB_DQS_DP<9>")
	)
	(segment
		(start 55.484776 -274.401026)
		(end 54.957726 -274.401026)
		(width 0.16002)
		(layer "In13.Cu")
		(net "M_B_CPU1_SB_DQS_DP<9>")
	)
	(segment
		(start 80.77962 -271.171416)
		(end 80.771238 -271.176242)
		(width 0.09525)
		(layer "In13.Cu")
		(net "M_B_CPU1_SB_DQS_DP<9>")
	)
	(segment
		(start 62.017402 -272.516346)
		(end 61.540898 -272.516346)
		(width 0.16002)
		(layer "In13.Cu")
		(net "M_B_CPU1_SB_DQS_DP<9>")
	)
	(segment
		(start 53.8353 -275.783548)
		(end 52.13223 -275.783548)
		(width 0.16002)
		(layer "In13.Cu")
		(net "M_B_CPU1_SB_DQS_DP<9>")
	)
	(segment
		(start 60.940442 -273.959066)
		(end 60.714382 -273.959066)
		(width 0.16002)
		(layer "In13.Cu")
		(net "M_B_CPU1_SB_DQS_DP<9>")
	)
	(segment
		(start 84.539582 -271.171416)
		(end 84.5312 -271.176242)
		(width 0.09525)
		(layer "In13.Cu")
		(net "M_B_CPU1_SB_DQS_DP<9>")
	)
	(segment
		(start 52.13223 -275.783548)
		(end 51.884072 -275.53539)
		(width 0.16002)
		(layer "In13.Cu")
		(net "M_B_CPU1_SB_DQS_DP<9>")
	)
	(segment
		(start 56.936386 -275.987764)
		(end 56.053482 -275.987764)
		(width 0.16002)
		(layer "In13.Cu")
		(net "M_B_CPU1_SB_DQS_DP<9>")
	)
	(segment
		(start 62.913768 -271.143476)
		(end 62.489842 -271.567402)
		(width 0.16002)
		(layer "In13.Cu")
		(net "M_B_CPU1_SB_DQS_DP<9>")
	)
	(segment
		(start 75.996546 -269.533624)
		(end 75.972924 -269.533624)
		(width 0.09525)
		(layer "In13.Cu")
		(net "M_B_CPU1_SB_DQS_DP<9>")
	)
	(segment
		(start 58.646822 -275.149564)
		(end 57.774586 -275.149564)
		(width 0.16002)
		(layer "In13.Cu")
		(net "M_B_CPU1_SB_DQS_DP<9>")
	)
	(segment
		(start 63.460122 -271.213326)
		(end 63.390272 -271.143476)
		(width 0.16002)
		(layer "In13.Cu")
		(net "M_B_CPU1_SB_DQS_DP<9>")
	)
	(segment
		(start 60.714382 -273.959066)
		(end 60.644532 -273.889216)
		(width 0.16002)
		(layer "In13.Cu")
		(net "M_B_CPU1_SB_DQS_DP<9>")
	)
	(segment
		(start 63.390272 -271.143476)
		(end 62.913768 -271.143476)
		(width 0.16002)
		(layer "In13.Cu")
		(net "M_B_CPU1_SB_DQS_DP<9>")
	)
	(segment
		(start 63.862712 -270.671036)
		(end 63.932562 -270.740886)
		(width 0.16002)
		(layer "In13.Cu")
		(net "M_B_CPU1_SB_DQS_DP<9>")
	)
	(segment
		(start 63.862712 -270.194532)
		(end 63.862712 -270.671036)
		(width 0.16002)
		(layer "In13.Cu")
		(net "M_B_CPU1_SB_DQS_DP<9>")
	)
	(segment
		(start 77.46111 -270.143986)
		(end 76.833476 -270.143986)
		(width 0.09525)
		(layer "In13.Cu")
		(net "M_B_CPU1_SB_DQS_DP<9>")
	)
	(segment
		(start 62.559692 -272.339816)
		(end 62.313312 -272.586196)
		(width 0.16002)
		(layer "In13.Cu")
		(net "M_B_CPU1_SB_DQS_DP<9>")
	)
	(segment
		(start 63.932562 -270.740886)
		(end 63.932562 -270.966946)
		(width 0.16002)
		(layer "In13.Cu")
		(net "M_B_CPU1_SB_DQS_DP<9>")
	)
	(segment
		(start 54.584854 -274.773898)
		(end 54.584854 -275.79193)
		(width 0.16002)
		(layer "In13.Cu")
		(net "M_B_CPU1_SB_DQS_DP<9>")
	)
	(segment
		(start 63.686182 -271.213326)
		(end 63.460122 -271.213326)
		(width 0.16002)
		(layer "In13.Cu")
		(net "M_B_CPU1_SB_DQS_DP<9>")
	)
	(segment
		(start 65.128902 -269.770606)
		(end 64.286638 -269.770606)
		(width 0.16002)
		(layer "In13.Cu")
		(net "M_B_CPU1_SB_DQS_DP<9>")
	)
	(segment
		(start 54.957726 -274.401026)
		(end 54.584854 -274.773898)
		(width 0.16002)
		(layer "In13.Cu")
		(net "M_B_CPU1_SB_DQS_DP<9>")
	)
	(segment
		(start 61.186822 -273.712686)
		(end 60.940442 -273.959066)
		(width 0.16002)
		(layer "In13.Cu")
		(net "M_B_CPU1_SB_DQS_DP<9>")
	)
	(segment
		(start 59.813952 -275.085556)
		(end 59.526678 -275.37283)
		(width 0.16002)
		(layer "In13.Cu")
		(net "M_B_CPU1_SB_DQS_DP<9>")
	)
	(segment
		(start 54.039516 -275.987764)
		(end 53.8353 -275.783548)
		(width 0.16002)
		(layer "In13.Cu")
		(net "M_B_CPU1_SB_DQS_DP<9>")
	)
	(segment
		(start 55.857648 -275.79193)
		(end 55.857648 -274.773898)
		(width 0.16002)
		(layer "In13.Cu")
		(net "M_B_CPU1_SB_DQS_DP<9>")
	)
	(arc
		(start 81.342484 -271.171416)
		(mid 81.061052 -271.095661)
		(end 80.77962 -271.171416)
		(width 0.09525)
		(layer "In13.Cu")
		(net "M_B_CPU1_SB_DQS_DP<9>")
	)
	(arc
		(start 79.839312 -271.171416)
		(mid 79.748235 -271.2097)
		(end 79.650336 -271.222978)
		(width 0.09525)
		(layer "In13.Cu")
		(net "M_B_CPU1_SB_DQS_DP<9>")
	)
	(arc
		(start 86.41969 -271.171416)
		(mid 86.235915 -271.222188)
		(end 86.050882 -271.176242)
		(width 0.09525)
		(layer "In13.Cu")
		(net "M_B_CPU1_SB_DQS_DP<9>")
	)
	(arc
		(start 80.392016 -271.16532)
		(mid 80.114854 -271.09552)
		(end 79.839312 -271.171416)
		(width 0.09525)
		(layer "In13.Cu")
		(net "M_B_CPU1_SB_DQS_DP<9>")
	)
	(arc
		(start 83.591146 -271.176242)
		(mid 83.406114 -271.222156)
		(end 83.222338 -271.171416)
		(width 0.09525)
		(layer "In13.Cu")
		(net "M_B_CPU1_SB_DQS_DP<9>")
	)
	(arc
		(start 87.35949 -271.171416)
		(mid 87.171022 -271.222093)
		(end 86.982554 -271.171416)
		(width 0.09525)
		(layer "In13.Cu")
		(net "M_B_CPU1_SB_DQS_DP<9>")
	)
	(arc
		(start 85.479636 -271.171416)
		(mid 85.295861 -271.222188)
		(end 85.110828 -271.176242)
		(width 0.09525)
		(layer "In13.Cu")
		(net "M_B_CPU1_SB_DQS_DP<9>")
	)
	(arc
		(start 87.856314 -271.138396)
		(mid 87.60403 -271.096702)
		(end 87.35949 -271.171416)
		(width 0.09525)
		(layer "In13.Cu")
		(net "M_B_CPU1_SB_DQS_DP<9>")
	)
	(arc
		(start 80.771238 -271.176242)
		(mid 80.586206 -271.222156)
		(end 80.40243 -271.171416)
		(width 0.09525)
		(layer "In13.Cu")
		(net "M_B_CPU1_SB_DQS_DP<9>")
	)
	(arc
		(start 84.162392 -271.171416)
		(mid 83.88096 -271.095661)
		(end 83.599528 -271.171416)
		(width 0.09525)
		(layer "In13.Cu")
		(net "M_B_CPU1_SB_DQS_DP<9>")
	)
	(arc
		(start 84.5312 -271.176242)
		(mid 84.346168 -271.222156)
		(end 84.162392 -271.171416)
		(width 0.09525)
		(layer "In13.Cu")
		(net "M_B_CPU1_SB_DQS_DP<9>")
	)
	(arc
		(start 81.719674 -271.171416)
		(mid 81.535899 -271.222188)
		(end 81.350866 -271.176242)
		(width 0.09525)
		(layer "In13.Cu")
		(net "M_B_CPU1_SB_DQS_DP<9>")
	)
	(arc
		(start 82.659474 -271.171416)
		(mid 82.471006 -271.222093)
		(end 82.282538 -271.171416)
		(width 0.09525)
		(layer "In13.Cu")
		(net "M_B_CPU1_SB_DQS_DP<9>")
	)
	(arc
		(start 85.102446 -271.171416)
		(mid 84.821014 -271.095661)
		(end 84.539582 -271.171416)
		(width 0.09525)
		(layer "In13.Cu")
		(net "M_B_CPU1_SB_DQS_DP<9>")
	)
	(arc
		(start 86.0425 -271.171416)
		(mid 85.761068 -271.095661)
		(end 85.479636 -271.171416)
		(width 0.09525)
		(layer "In13.Cu")
		(net "M_B_CPU1_SB_DQS_DP<9>")
	)
	(arc
		(start 86.982554 -271.171416)
		(mid 86.701122 -271.095661)
		(end 86.41969 -271.171416)
		(width 0.09525)
		(layer "In13.Cu")
		(net "M_B_CPU1_SB_DQS_DP<9>")
	)
	(arc
		(start 82.282538 -271.171416)
		(mid 82.001106 -271.095661)
		(end 81.719674 -271.171416)
		(width 0.09525)
		(layer "In13.Cu")
		(net "M_B_CPU1_SB_DQS_DP<9>")
	)
	(arc
		(start 83.222338 -271.171416)
		(mid 82.940906 -271.095661)
		(end 82.659474 -271.171416)
		(width 0.09525)
		(layer "In13.Cu")
		(net "M_B_CPU1_SB_DQS_DP<9>")
	)
	(segment
		(start 89.517982 -291.64026)
		(end 89.05113 -291.906198)
		(width 0.12954)
		(layer "F.Cu")
		(net "M_B_CPU1_SB_DQS_DP<8>")
	)
	(segment
		(start 83.599528 -291.581078)
		(end 83.591146 -291.576252)
		(width 0.09525)
		(layer "In13.Cu")
		(net "M_B_CPU1_SB_DQS_DP<8>")
	)
	(segment
		(start 48.543718 -314.182506)
		(end 48.385476 -314.340748)
		(width 0.16002)
		(layer "In13.Cu")
		(net "M_B_CPU1_SB_DQS_DP<8>")
	)
	(segment
		(start 57.842658 -314.197746)
		(end 57.05094 -314.989464)
		(width 0.16002)
		(layer "In13.Cu")
		(net "M_B_CPU1_SB_DQS_DP<8>")
	)
	(segment
		(start 80.77962 -291.581078)
		(end 80.771238 -291.576252)
		(width 0.09525)
		(layer "In13.Cu")
		(net "M_B_CPU1_SB_DQS_DP<8>")
	)
	(segment
		(start 77.869796 -294.099488)
		(end 77.72654 -294.444674)
		(width 0.09525)
		(layer "In13.Cu")
		(net "M_B_CPU1_SB_DQS_DP<8>")
	)
	(segment
		(start 77.357478 -295.545256)
		(end 74.65441 -298.248324)
		(width 0.16002)
		(layer "In13.Cu")
		(net "M_B_CPU1_SB_DQS_DP<8>")
	)
	(segment
		(start 77.374242 -295.445688)
		(end 77.374242 -295.528492)
		(width 0.09525)
		(layer "In13.Cu")
		(net "M_B_CPU1_SB_DQS_DP<8>")
	)
	(segment
		(start 85.110828 -291.576252)
		(end 85.102446 -291.581078)
		(width 0.09525)
		(layer "In13.Cu")
		(net "M_B_CPU1_SB_DQS_DP<8>")
	)
	(segment
		(start 48.078644 -314.340748)
		(end 47.784004 -314.635388)
		(width 0.16002)
		(layer "In13.Cu")
		(net "M_B_CPU1_SB_DQS_DP<8>")
	)
	(segment
		(start 57.05094 -314.989464)
		(end 51.479704 -314.989464)
		(width 0.16002)
		(layer "In13.Cu")
		(net "M_B_CPU1_SB_DQS_DP<8>")
	)
	(segment
		(start 74.65441 -298.248324)
		(end 74.65441 -299.44822)
		(width 0.16002)
		(layer "In13.Cu")
		(net "M_B_CPU1_SB_DQS_DP<8>")
	)
	(segment
		(start 77.72654 -294.444674)
		(end 77.72654 -295.094152)
		(width 0.09525)
		(layer "In13.Cu")
		(net "M_B_CPU1_SB_DQS_DP<8>")
	)
	(segment
		(start 89.05113 -291.906198)
		(end 89.205054 -291.640768)
		(width 0.09525)
		(layer "In13.Cu")
		(net "M_B_CPU1_SB_DQS_DP<8>")
	)
	(segment
		(start 86.050882 -291.576252)
		(end 86.0425 -291.581078)
		(width 0.09525)
		(layer "In13.Cu")
		(net "M_B_CPU1_SB_DQS_DP<8>")
	)
	(segment
		(start 77.375004 -295.44518)
		(end 77.374242 -295.445688)
		(width 0.09525)
		(layer "In13.Cu")
		(net "M_B_CPU1_SB_DQS_DP<8>")
	)
	(segment
		(start 84.539582 -291.581078)
		(end 84.5312 -291.576252)
		(width 0.09525)
		(layer "In13.Cu")
		(net "M_B_CPU1_SB_DQS_DP<8>")
	)
	(segment
		(start 59.276234 -314.197746)
		(end 57.842658 -314.197746)
		(width 0.16002)
		(layer "In13.Cu")
		(net "M_B_CPU1_SB_DQS_DP<8>")
	)
	(segment
		(start 77.374242 -295.528492)
		(end 77.357478 -295.545256)
		(width 0.09525)
		(layer "In13.Cu")
		(net "M_B_CPU1_SB_DQS_DP<8>")
	)
	(segment
		(start 77.374496 -295.444926)
		(end 77.375004 -295.44518)
		(width 0.09525)
		(layer "In13.Cu")
		(net "M_B_CPU1_SB_DQS_DP<8>")
	)
	(segment
		(start 48.385476 -314.340748)
		(end 48.078644 -314.340748)
		(width 0.16002)
		(layer "In13.Cu")
		(net "M_B_CPU1_SB_DQS_DP<8>")
	)
	(segment
		(start 79.75727 -291.65677)
		(end 78.98765 -292.426644)
		(width 0.09525)
		(layer "In13.Cu")
		(net "M_B_CPU1_SB_DQS_DP<8>")
	)
	(segment
		(start 89.205054 -291.640768)
		(end 89.181686 -291.5539)
		(width 0.09525)
		(layer "In13.Cu")
		(net "M_B_CPU1_SB_DQS_DP<8>")
	)
	(segment
		(start 81.350866 -291.576252)
		(end 81.342484 -291.581078)
		(width 0.09525)
		(layer "In13.Cu")
		(net "M_B_CPU1_SB_DQS_DP<8>")
	)
	(segment
		(start 88.299544 -291.581078)
		(end 88.291162 -291.576252)
		(width 0.09525)
		(layer "In13.Cu")
		(net "M_B_CPU1_SB_DQS_DP<8>")
	)
	(segment
		(start 51.479704 -314.989464)
		(end 50.687986 -314.182506)
		(width 0.16002)
		(layer "In13.Cu")
		(net "M_B_CPU1_SB_DQS_DP<8>")
	)
	(segment
		(start 74.65441 -299.44822)
		(end 71.34606 -302.75657)
		(width 0.16002)
		(layer "In13.Cu")
		(net "M_B_CPU1_SB_DQS_DP<8>")
	)
	(segment
		(start 71.34606 -303.959006)
		(end 62.402212 -312.902854)
		(width 0.16002)
		(layer "In13.Cu")
		(net "M_B_CPU1_SB_DQS_DP<8>")
	)
	(segment
		(start 62.402212 -312.902854)
		(end 59.276234 -314.197746)
		(width 0.16002)
		(layer "In13.Cu")
		(net "M_B_CPU1_SB_DQS_DP<8>")
	)
	(segment
		(start 80.120998 -291.65677)
		(end 79.75727 -291.65677)
		(width 0.09525)
		(layer "In13.Cu")
		(net "M_B_CPU1_SB_DQS_DP<8>")
	)
	(segment
		(start 71.34606 -302.75657)
		(end 71.34606 -303.959006)
		(width 0.16002)
		(layer "In13.Cu")
		(net "M_B_CPU1_SB_DQS_DP<8>")
	)
	(segment
		(start 50.687986 -314.182506)
		(end 48.543718 -314.182506)
		(width 0.16002)
		(layer "In13.Cu")
		(net "M_B_CPU1_SB_DQS_DP<8>")
	)
	(segment
		(start 78.98765 -292.426644)
		(end 77.869796 -294.099488)
		(width 0.09525)
		(layer "In13.Cu")
		(net "M_B_CPU1_SB_DQS_DP<8>")
	)
	(segment
		(start 77.72654 -295.094152)
		(end 77.374496 -295.444926)
		(width 0.09525)
		(layer "In13.Cu")
		(net "M_B_CPU1_SB_DQS_DP<8>")
	)
	(arc
		(start 86.982554 -291.581078)
		(mid 86.701122 -291.656833)
		(end 86.41969 -291.581078)
		(width 0.09525)
		(layer "In13.Cu")
		(net "M_B_CPU1_SB_DQS_DP<8>")
	)
	(arc
		(start 81.342484 -291.581078)
		(mid 81.061052 -291.656833)
		(end 80.77962 -291.581078)
		(width 0.09525)
		(layer "In13.Cu")
		(net "M_B_CPU1_SB_DQS_DP<8>")
	)
	(arc
		(start 86.41969 -291.581078)
		(mid 86.235915 -291.530306)
		(end 86.050882 -291.576252)
		(width 0.09525)
		(layer "In13.Cu")
		(net "M_B_CPU1_SB_DQS_DP<8>")
	)
	(arc
		(start 84.162392 -291.581078)
		(mid 83.88096 -291.656833)
		(end 83.599528 -291.581078)
		(width 0.09525)
		(layer "In13.Cu")
		(net "M_B_CPU1_SB_DQS_DP<8>")
	)
	(arc
		(start 88.862408 -291.581078)
		(mid 88.580976 -291.656833)
		(end 88.299544 -291.581078)
		(width 0.09525)
		(layer "In13.Cu")
		(net "M_B_CPU1_SB_DQS_DP<8>")
	)
	(arc
		(start 87.922354 -291.581078)
		(mid 87.640922 -291.656833)
		(end 87.35949 -291.581078)
		(width 0.09525)
		(layer "In13.Cu")
		(net "M_B_CPU1_SB_DQS_DP<8>")
	)
	(arc
		(start 84.5312 -291.576252)
		(mid 84.346168 -291.530338)
		(end 84.162392 -291.581078)
		(width 0.09525)
		(layer "In13.Cu")
		(net "M_B_CPU1_SB_DQS_DP<8>")
	)
	(arc
		(start 85.102446 -291.581078)
		(mid 84.821014 -291.656833)
		(end 84.539582 -291.581078)
		(width 0.09525)
		(layer "In13.Cu")
		(net "M_B_CPU1_SB_DQS_DP<8>")
	)
	(arc
		(start 87.35949 -291.581078)
		(mid 87.171022 -291.530401)
		(end 86.982554 -291.581078)
		(width 0.09525)
		(layer "In13.Cu")
		(net "M_B_CPU1_SB_DQS_DP<8>")
	)
	(arc
		(start 83.591146 -291.576252)
		(mid 83.406114 -291.530338)
		(end 83.222338 -291.581078)
		(width 0.09525)
		(layer "In13.Cu")
		(net "M_B_CPU1_SB_DQS_DP<8>")
	)
	(arc
		(start 89.181686 -291.5539)
		(mid 89.019004 -291.531768)
		(end 88.862408 -291.581078)
		(width 0.09525)
		(layer "In13.Cu")
		(net "M_B_CPU1_SB_DQS_DP<8>")
	)
	(arc
		(start 85.479636 -291.581078)
		(mid 85.295861 -291.530306)
		(end 85.110828 -291.576252)
		(width 0.09525)
		(layer "In13.Cu")
		(net "M_B_CPU1_SB_DQS_DP<8>")
	)
	(arc
		(start 83.222338 -291.581078)
		(mid 82.940906 -291.656833)
		(end 82.659474 -291.581078)
		(width 0.09525)
		(layer "In13.Cu")
		(net "M_B_CPU1_SB_DQS_DP<8>")
	)
	(arc
		(start 80.771238 -291.576252)
		(mid 80.586206 -291.530338)
		(end 80.40243 -291.581078)
		(width 0.09525)
		(layer "In13.Cu")
		(net "M_B_CPU1_SB_DQS_DP<8>")
	)
	(arc
		(start 80.40243 -291.581078)
		(mid 80.266723 -291.637563)
		(end 80.120998 -291.65677)
		(width 0.09525)
		(layer "In13.Cu")
		(net "M_B_CPU1_SB_DQS_DP<8>")
	)
	(arc
		(start 86.0425 -291.581078)
		(mid 85.761068 -291.656833)
		(end 85.479636 -291.581078)
		(width 0.09525)
		(layer "In13.Cu")
		(net "M_B_CPU1_SB_DQS_DP<8>")
	)
	(arc
		(start 82.659474 -291.581078)
		(mid 82.471006 -291.530401)
		(end 82.282538 -291.581078)
		(width 0.09525)
		(layer "In13.Cu")
		(net "M_B_CPU1_SB_DQS_DP<8>")
	)
	(arc
		(start 81.719674 -291.581078)
		(mid 81.535899 -291.530306)
		(end 81.350866 -291.576252)
		(width 0.09525)
		(layer "In13.Cu")
		(net "M_B_CPU1_SB_DQS_DP<8>")
	)
	(arc
		(start 88.291162 -291.576252)
		(mid 88.10613 -291.530338)
		(end 87.922354 -291.581078)
		(width 0.09525)
		(layer "In13.Cu")
		(net "M_B_CPU1_SB_DQS_DP<8>")
	)
	(arc
		(start 82.282538 -291.581078)
		(mid 82.001106 -291.656833)
		(end 81.719674 -291.581078)
		(width 0.09525)
		(layer "In13.Cu")
		(net "M_B_CPU1_SB_DQS_DP<8>")
	)
	(segment
		(start 89.517982 -286.780478)
		(end 89.05113 -287.046162)
		(width 0.12954)
		(layer "F.Cu")
		(net "M_B_CPU1_SB_DQS_DP<7>")
	)
	(segment
		(start 89.05113 -287.046162)
		(end 89.205054 -286.780732)
		(width 0.09525)
		(layer "In13.Cu")
		(net "M_B_CPU1_SB_DQS_DP<7>")
	)
	(segment
		(start 88.299544 -286.721042)
		(end 88.291162 -286.716216)
		(width 0.09525)
		(layer "In13.Cu")
		(net "M_B_CPU1_SB_DQS_DP<7>")
	)
	(segment
		(start 83.599528 -286.721042)
		(end 83.591146 -286.716216)
		(width 0.09525)
		(layer "In13.Cu")
		(net "M_B_CPU1_SB_DQS_DP<7>")
	)
	(segment
		(start 77.02804 -287.085786)
		(end 76.186538 -287.927542)
		(width 0.09525)
		(layer "In13.Cu")
		(net "M_B_CPU1_SB_DQS_DP<7>")
	)
	(segment
		(start 81.350866 -286.716216)
		(end 81.342484 -286.721042)
		(width 0.09525)
		(layer "In13.Cu")
		(net "M_B_CPU1_SB_DQS_DP<7>")
	)
	(segment
		(start 60.504832 -304.355754)
		(end 60.499244 -304.350166)
		(width 0.16002)
		(layer "In13.Cu")
		(net "M_B_CPU1_SB_DQS_DP<7>")
	)
	(segment
		(start 85.110828 -286.716216)
		(end 85.102446 -286.721042)
		(width 0.09525)
		(layer "In13.Cu")
		(net "M_B_CPU1_SB_DQS_DP<7>")
	)
	(segment
		(start 78.228444 -286.812736)
		(end 78.014576 -286.812736)
		(width 0.09525)
		(layer "In13.Cu")
		(net "M_B_CPU1_SB_DQS_DP<7>")
	)
	(segment
		(start 60.499244 -304.350166)
		(end 57.77738 -304.89144)
		(width 0.16002)
		(layer "In13.Cu")
		(net "M_B_CPU1_SB_DQS_DP<7>")
	)
	(segment
		(start 78.926436 -286.745172)
		(end 78.895194 -286.727138)
		(width 0.09525)
		(layer "In13.Cu")
		(net "M_B_CPU1_SB_DQS_DP<7>")
	)
	(segment
		(start 54.096158 -305.677824)
		(end 52.846732 -305.160426)
		(width 0.16002)
		(layer "In13.Cu")
		(net "M_B_CPU1_SB_DQS_DP<7>")
	)
	(segment
		(start 49.299114 -305.011582)
		(end 48.057816 -305.011582)
		(width 0.16002)
		(layer "In13.Cu")
		(net "M_B_CPU1_SB_DQS_DP<7>")
	)
	(segment
		(start 76.186538 -288.010346)
		(end 76.169774 -288.02711)
		(width 0.09525)
		(layer "In13.Cu")
		(net "M_B_CPU1_SB_DQS_DP<7>")
	)
	(segment
		(start 50.694336 -304.832512)
		(end 49.731676 -304.832512)
		(width 0.16002)
		(layer "In13.Cu")
		(net "M_B_CPU1_SB_DQS_DP<7>")
	)
	(segment
		(start 51.486054 -305.160426)
		(end 50.694336 -304.832512)
		(width 0.16002)
		(layer "In13.Cu")
		(net "M_B_CPU1_SB_DQS_DP<7>")
	)
	(segment
		(start 56.990996 -305.677824)
		(end 54.096158 -305.677824)
		(width 0.16002)
		(layer "In13.Cu")
		(net "M_B_CPU1_SB_DQS_DP<7>")
	)
	(segment
		(start 76.186538 -287.927542)
		(end 76.186538 -288.010346)
		(width 0.09525)
		(layer "In13.Cu")
		(net "M_B_CPU1_SB_DQS_DP<7>")
	)
	(segment
		(start 79.823818 -286.711644)
		(end 79.822548 -286.710882)
		(width 0.09525)
		(layer "In13.Cu")
		(net "M_B_CPU1_SB_DQS_DP<7>")
	)
	(segment
		(start 78.895194 -286.727138)
		(end 78.871064 -286.713422)
		(width 0.09525)
		(layer "In13.Cu")
		(net "M_B_CPU1_SB_DQS_DP<7>")
	)
	(segment
		(start 80.77962 -286.721042)
		(end 80.771238 -286.716216)
		(width 0.09525)
		(layer "In13.Cu")
		(net "M_B_CPU1_SB_DQS_DP<7>")
	)
	(segment
		(start 52.846732 -305.160426)
		(end 51.486054 -305.160426)
		(width 0.16002)
		(layer "In13.Cu")
		(net "M_B_CPU1_SB_DQS_DP<7>")
	)
	(segment
		(start 89.205054 -286.780732)
		(end 89.181686 -286.693864)
		(width 0.09525)
		(layer "In13.Cu")
		(net "M_B_CPU1_SB_DQS_DP<7>")
	)
	(segment
		(start 76.169774 -288.02711)
		(end 68.364608 -295.831768)
		(width 0.16002)
		(layer "In13.Cu")
		(net "M_B_CPU1_SB_DQS_DP<7>")
	)
	(segment
		(start 79.840836 -286.721296)
		(end 79.823818 -286.711644)
		(width 0.09525)
		(layer "In13.Cu")
		(net "M_B_CPU1_SB_DQS_DP<7>")
	)
	(segment
		(start 86.050882 -286.716216)
		(end 86.0425 -286.721042)
		(width 0.09525)
		(layer "In13.Cu")
		(net "M_B_CPU1_SB_DQS_DP<7>")
	)
	(segment
		(start 61.060076 -304.355754)
		(end 60.504832 -304.355754)
		(width 0.16002)
		(layer "In13.Cu")
		(net "M_B_CPU1_SB_DQS_DP<7>")
	)
	(segment
		(start 68.364608 -295.831768)
		(end 68.364608 -297.051222)
		(width 0.16002)
		(layer "In13.Cu")
		(net "M_B_CPU1_SB_DQS_DP<7>")
	)
	(segment
		(start 78.014576 -286.812736)
		(end 77.741526 -287.085786)
		(width 0.09525)
		(layer "In13.Cu")
		(net "M_B_CPU1_SB_DQS_DP<7>")
	)
	(segment
		(start 84.539582 -286.721042)
		(end 84.5312 -286.716216)
		(width 0.09525)
		(layer "In13.Cu")
		(net "M_B_CPU1_SB_DQS_DP<7>")
	)
	(segment
		(start 77.741526 -287.085786)
		(end 77.02804 -287.085786)
		(width 0.09525)
		(layer "In13.Cu")
		(net "M_B_CPU1_SB_DQS_DP<7>")
	)
	(segment
		(start 57.77738 -304.89144)
		(end 56.990996 -305.677824)
		(width 0.16002)
		(layer "In13.Cu")
		(net "M_B_CPU1_SB_DQS_DP<7>")
	)
	(segment
		(start 68.364608 -297.051222)
		(end 61.060076 -304.355754)
		(width 0.16002)
		(layer "In13.Cu")
		(net "M_B_CPU1_SB_DQS_DP<7>")
	)
	(segment
		(start 48.057816 -305.011582)
		(end 47.784004 -305.285394)
		(width 0.16002)
		(layer "In13.Cu")
		(net "M_B_CPU1_SB_DQS_DP<7>")
	)
	(segment
		(start 79.859632 -286.732218)
		(end 79.840836 -286.721296)
		(width 0.09525)
		(layer "In13.Cu")
		(net "M_B_CPU1_SB_DQS_DP<7>")
	)
	(segment
		(start 49.731676 -304.832512)
		(end 49.299114 -305.011582)
		(width 0.16002)
		(layer "In13.Cu")
		(net "M_B_CPU1_SB_DQS_DP<7>")
	)
	(arc
		(start 88.291162 -286.716216)
		(mid 88.10613 -286.670302)
		(end 87.922354 -286.721042)
		(width 0.09525)
		(layer "In13.Cu")
		(net "M_B_CPU1_SB_DQS_DP<7>")
	)
	(arc
		(start 82.659474 -286.721042)
		(mid 82.471006 -286.670365)
		(end 82.282538 -286.721042)
		(width 0.09525)
		(layer "In13.Cu")
		(net "M_B_CPU1_SB_DQS_DP<7>")
	)
	(arc
		(start 85.102446 -286.721042)
		(mid 84.821014 -286.796831)
		(end 84.539582 -286.721042)
		(width 0.09525)
		(layer "In13.Cu")
		(net "M_B_CPU1_SB_DQS_DP<7>")
	)
	(arc
		(start 81.719674 -286.721042)
		(mid 81.535899 -286.67027)
		(end 81.350866 -286.716216)
		(width 0.09525)
		(layer "In13.Cu")
		(net "M_B_CPU1_SB_DQS_DP<7>")
	)
	(arc
		(start 86.982554 -286.721042)
		(mid 86.701122 -286.796831)
		(end 86.41969 -286.721042)
		(width 0.09525)
		(layer "In13.Cu")
		(net "M_B_CPU1_SB_DQS_DP<7>")
	)
	(arc
		(start 80.771238 -286.716216)
		(mid 80.586206 -286.670302)
		(end 80.40243 -286.721042)
		(width 0.09525)
		(layer "In13.Cu")
		(net "M_B_CPU1_SB_DQS_DP<7>")
	)
	(arc
		(start 78.518004 -286.731202)
		(mid 78.37886 -286.791977)
		(end 78.228444 -286.812736)
		(width 0.09525)
		(layer "In13.Cu")
		(net "M_B_CPU1_SB_DQS_DP<7>")
	)
	(arc
		(start 79.48549 -286.709612)
		(mid 79.442352 -286.729687)
		(end 79.398114 -286.747204)
		(width 0.09525)
		(layer "In13.Cu")
		(net "M_B_CPU1_SB_DQS_DP<7>")
	)
	(arc
		(start 83.222338 -286.721042)
		(mid 82.940906 -286.796831)
		(end 82.659474 -286.721042)
		(width 0.09525)
		(layer "In13.Cu")
		(net "M_B_CPU1_SB_DQS_DP<7>")
	)
	(arc
		(start 87.922354 -286.721042)
		(mid 87.640922 -286.796831)
		(end 87.35949 -286.721042)
		(width 0.09525)
		(layer "In13.Cu")
		(net "M_B_CPU1_SB_DQS_DP<7>")
	)
	(arc
		(start 85.479636 -286.721042)
		(mid 85.295861 -286.67027)
		(end 85.110828 -286.716216)
		(width 0.09525)
		(layer "In13.Cu")
		(net "M_B_CPU1_SB_DQS_DP<7>")
	)
	(arc
		(start 82.282538 -286.721042)
		(mid 82.001106 -286.796831)
		(end 81.719674 -286.721042)
		(width 0.09525)
		(layer "In13.Cu")
		(net "M_B_CPU1_SB_DQS_DP<7>")
	)
	(arc
		(start 81.342484 -286.721042)
		(mid 81.061052 -286.796831)
		(end 80.77962 -286.721042)
		(width 0.09525)
		(layer "In13.Cu")
		(net "M_B_CPU1_SB_DQS_DP<7>")
	)
	(arc
		(start 78.871064 -286.713422)
		(mid 78.692261 -286.677298)
		(end 78.518004 -286.731202)
		(width 0.09525)
		(layer "In13.Cu")
		(net "M_B_CPU1_SB_DQS_DP<7>")
	)
	(arc
		(start 79.398114 -286.747204)
		(mid 79.162104 -286.78758)
		(end 78.926436 -286.745172)
		(width 0.09525)
		(layer "In13.Cu")
		(net "M_B_CPU1_SB_DQS_DP<7>")
	)
	(arc
		(start 87.35949 -286.721042)
		(mid 87.171022 -286.670365)
		(end 86.982554 -286.721042)
		(width 0.09525)
		(layer "In13.Cu")
		(net "M_B_CPU1_SB_DQS_DP<7>")
	)
	(arc
		(start 79.822548 -286.710882)
		(mid 79.654182 -286.670397)
		(end 79.48549 -286.709612)
		(width 0.09525)
		(layer "In13.Cu")
		(net "M_B_CPU1_SB_DQS_DP<7>")
	)
	(arc
		(start 86.0425 -286.721042)
		(mid 85.761068 -286.796831)
		(end 85.479636 -286.721042)
		(width 0.09525)
		(layer "In13.Cu")
		(net "M_B_CPU1_SB_DQS_DP<7>")
	)
	(arc
		(start 84.5312 -286.716216)
		(mid 84.346168 -286.670302)
		(end 84.162392 -286.721042)
		(width 0.09525)
		(layer "In13.Cu")
		(net "M_B_CPU1_SB_DQS_DP<7>")
	)
	(arc
		(start 80.40243 -286.721042)
		(mid 80.132482 -286.796714)
		(end 79.859632 -286.732218)
		(width 0.09525)
		(layer "In13.Cu")
		(net "M_B_CPU1_SB_DQS_DP<7>")
	)
	(arc
		(start 86.41969 -286.721042)
		(mid 86.235915 -286.67027)
		(end 86.050882 -286.716216)
		(width 0.09525)
		(layer "In13.Cu")
		(net "M_B_CPU1_SB_DQS_DP<7>")
	)
	(arc
		(start 89.181686 -286.693864)
		(mid 89.019004 -286.671732)
		(end 88.862408 -286.721042)
		(width 0.09525)
		(layer "In13.Cu")
		(net "M_B_CPU1_SB_DQS_DP<7>")
	)
	(arc
		(start 88.862408 -286.721042)
		(mid 88.580976 -286.796831)
		(end 88.299544 -286.721042)
		(width 0.09525)
		(layer "In13.Cu")
		(net "M_B_CPU1_SB_DQS_DP<7>")
	)
	(arc
		(start 84.162392 -286.721042)
		(mid 83.88096 -286.796831)
		(end 83.599528 -286.721042)
		(width 0.09525)
		(layer "In13.Cu")
		(net "M_B_CPU1_SB_DQS_DP<7>")
	)
	(arc
		(start 83.591146 -286.716216)
		(mid 83.406114 -286.670302)
		(end 83.222338 -286.721042)
		(width 0.09525)
		(layer "In13.Cu")
		(net "M_B_CPU1_SB_DQS_DP<7>")
	)
	(segment
		(start 89.517982 -281.920442)
		(end 89.05113 -282.18638)
		(width 0.12954)
		(layer "F.Cu")
		(net "M_B_CPU1_SB_DQS_DP<6>")
	)
	(segment
		(start 60.607702 -295.482518)
		(end 57.836308 -295.482518)
		(width 0.16002)
		(layer "In13.Cu")
		(net "M_B_CPU1_SB_DQS_DP<6>")
	)
	(segment
		(start 88.299544 -281.86126)
		(end 88.291162 -281.856434)
		(width 0.09525)
		(layer "In13.Cu")
		(net "M_B_CPU1_SB_DQS_DP<6>")
	)
	(segment
		(start 76.513944 -281.915616)
		(end 76.038456 -281.915616)
		(width 0.09525)
		(layer "In13.Cu")
		(net "M_B_CPU1_SB_DQS_DP<6>")
	)
	(segment
		(start 74.115676 -281.974544)
		(end 60.607702 -295.482518)
		(width 0.16002)
		(layer "In13.Cu")
		(net "M_B_CPU1_SB_DQS_DP<6>")
	)
	(segment
		(start 76.701904 -281.727656)
		(end 76.513944 -281.915616)
		(width 0.09525)
		(layer "In13.Cu")
		(net "M_B_CPU1_SB_DQS_DP<6>")
	)
	(segment
		(start 79.16291 -281.727656)
		(end 76.701904 -281.727656)
		(width 0.09525)
		(layer "In13.Cu")
		(net "M_B_CPU1_SB_DQS_DP<6>")
	)
	(segment
		(start 53.74513 -296.279824)
		(end 53.275738 -295.810432)
		(width 0.16002)
		(layer "In13.Cu")
		(net "M_B_CPU1_SB_DQS_DP<6>")
	)
	(segment
		(start 57.039002 -296.279824)
		(end 53.74513 -296.279824)
		(width 0.16002)
		(layer "In13.Cu")
		(net "M_B_CPU1_SB_DQS_DP<6>")
	)
	(segment
		(start 48.057816 -295.661588)
		(end 47.784004 -295.9354)
		(width 0.16002)
		(layer "In13.Cu")
		(net "M_B_CPU1_SB_DQS_DP<6>")
	)
	(segment
		(start 48.56607 -295.482518)
		(end 48.387 -295.661588)
		(width 0.16002)
		(layer "In13.Cu")
		(net "M_B_CPU1_SB_DQS_DP<6>")
	)
	(segment
		(start 85.110828 -281.856434)
		(end 85.102446 -281.86126)
		(width 0.09525)
		(layer "In13.Cu")
		(net "M_B_CPU1_SB_DQS_DP<6>")
	)
	(segment
		(start 75.955906 -281.974544)
		(end 74.115676 -281.974544)
		(width 0.16002)
		(layer "In13.Cu")
		(net "M_B_CPU1_SB_DQS_DP<6>")
	)
	(segment
		(start 53.275738 -295.810432)
		(end 51.5493 -295.810432)
		(width 0.16002)
		(layer "In13.Cu")
		(net "M_B_CPU1_SB_DQS_DP<6>")
	)
	(segment
		(start 76.038456 -281.915616)
		(end 75.979528 -281.974544)
		(width 0.09525)
		(layer "In13.Cu")
		(net "M_B_CPU1_SB_DQS_DP<6>")
	)
	(segment
		(start 57.836308 -295.482518)
		(end 57.039002 -296.279824)
		(width 0.16002)
		(layer "In13.Cu")
		(net "M_B_CPU1_SB_DQS_DP<6>")
	)
	(segment
		(start 83.599528 -281.86126)
		(end 83.591146 -281.856434)
		(width 0.09525)
		(layer "In13.Cu")
		(net "M_B_CPU1_SB_DQS_DP<6>")
	)
	(segment
		(start 48.387 -295.661588)
		(end 48.057816 -295.661588)
		(width 0.16002)
		(layer "In13.Cu")
		(net "M_B_CPU1_SB_DQS_DP<6>")
	)
	(segment
		(start 86.050882 -281.856434)
		(end 86.0425 -281.86126)
		(width 0.09525)
		(layer "In13.Cu")
		(net "M_B_CPU1_SB_DQS_DP<6>")
	)
	(segment
		(start 50.824892 -295.482518)
		(end 48.56607 -295.482518)
		(width 0.16002)
		(layer "In13.Cu")
		(net "M_B_CPU1_SB_DQS_DP<6>")
	)
	(segment
		(start 84.539582 -281.86126)
		(end 84.5312 -281.856434)
		(width 0.09525)
		(layer "In13.Cu")
		(net "M_B_CPU1_SB_DQS_DP<6>")
	)
	(segment
		(start 75.979528 -281.974544)
		(end 75.955906 -281.974544)
		(width 0.09525)
		(layer "In13.Cu")
		(net "M_B_CPU1_SB_DQS_DP<6>")
	)
	(segment
		(start 89.205054 -281.92095)
		(end 89.181686 -281.834082)
		(width 0.09525)
		(layer "In13.Cu")
		(net "M_B_CPU1_SB_DQS_DP<6>")
	)
	(segment
		(start 51.5493 -295.810432)
		(end 50.824892 -295.482518)
		(width 0.16002)
		(layer "In13.Cu")
		(net "M_B_CPU1_SB_DQS_DP<6>")
	)
	(segment
		(start 89.05113 -282.18638)
		(end 89.205054 -281.92095)
		(width 0.09525)
		(layer "In13.Cu")
		(net "M_B_CPU1_SB_DQS_DP<6>")
	)
	(arc
		(start 81.719674 -281.86126)
		(mid 81.546714 -281.810903)
		(end 81.37017 -281.846782)
		(width 0.09525)
		(layer "In13.Cu")
		(net "M_B_CPU1_SB_DQS_DP<6>")
	)
	(arc
		(start 80.78851 -281.869642)
		(mid 80.570665 -281.833869)
		(end 80.355948 -281.885136)
		(width 0.09525)
		(layer "In13.Cu")
		(net "M_B_CPU1_SB_DQS_DP<6>")
	)
	(arc
		(start 85.102446 -281.86126)
		(mid 84.821014 -281.937015)
		(end 84.539582 -281.86126)
		(width 0.09525)
		(layer "In13.Cu")
		(net "M_B_CPU1_SB_DQS_DP<6>")
	)
	(arc
		(start 88.862408 -281.86126)
		(mid 88.580976 -281.937015)
		(end 88.299544 -281.86126)
		(width 0.09525)
		(layer "In13.Cu")
		(net "M_B_CPU1_SB_DQS_DP<6>")
	)
	(arc
		(start 81.369916 -281.84602)
		(mid 81.081617 -281.916965)
		(end 80.78851 -281.869642)
		(width 0.09525)
		(layer "In13.Cu")
		(net "M_B_CPU1_SB_DQS_DP<6>")
	)
	(arc
		(start 87.35949 -281.86126)
		(mid 87.171022 -281.810583)
		(end 86.982554 -281.86126)
		(width 0.09525)
		(layer "In13.Cu")
		(net "M_B_CPU1_SB_DQS_DP<6>")
	)
	(arc
		(start 84.5312 -281.856434)
		(mid 84.346168 -281.81052)
		(end 84.162392 -281.86126)
		(width 0.09525)
		(layer "In13.Cu")
		(net "M_B_CPU1_SB_DQS_DP<6>")
	)
	(arc
		(start 80.355948 -281.885136)
		(mid 80.122074 -281.936577)
		(end 79.88808 -281.885644)
		(width 0.09525)
		(layer "In13.Cu")
		(net "M_B_CPU1_SB_DQS_DP<6>")
	)
	(arc
		(start 79.88808 -281.885644)
		(mid 79.53401 -281.767555)
		(end 79.16291 -281.727656)
		(width 0.09525)
		(layer "In13.Cu")
		(net "M_B_CPU1_SB_DQS_DP<6>")
	)
	(arc
		(start 86.982554 -281.86126)
		(mid 86.701122 -281.937015)
		(end 86.41969 -281.86126)
		(width 0.09525)
		(layer "In13.Cu")
		(net "M_B_CPU1_SB_DQS_DP<6>")
	)
	(arc
		(start 87.922354 -281.86126)
		(mid 87.640922 -281.937015)
		(end 87.35949 -281.86126)
		(width 0.09525)
		(layer "In13.Cu")
		(net "M_B_CPU1_SB_DQS_DP<6>")
	)
	(arc
		(start 88.291162 -281.856434)
		(mid 88.10613 -281.81052)
		(end 87.922354 -281.86126)
		(width 0.09525)
		(layer "In13.Cu")
		(net "M_B_CPU1_SB_DQS_DP<6>")
	)
	(arc
		(start 83.222338 -281.86126)
		(mid 82.940906 -281.937015)
		(end 82.659474 -281.86126)
		(width 0.09525)
		(layer "In13.Cu")
		(net "M_B_CPU1_SB_DQS_DP<6>")
	)
	(arc
		(start 82.282538 -281.86126)
		(mid 82.001106 -281.937015)
		(end 81.719674 -281.86126)
		(width 0.09525)
		(layer "In13.Cu")
		(net "M_B_CPU1_SB_DQS_DP<6>")
	)
	(arc
		(start 86.41969 -281.86126)
		(mid 86.235915 -281.810488)
		(end 86.050882 -281.856434)
		(width 0.09525)
		(layer "In13.Cu")
		(net "M_B_CPU1_SB_DQS_DP<6>")
	)
	(arc
		(start 84.162392 -281.86126)
		(mid 83.88096 -281.937015)
		(end 83.599528 -281.86126)
		(width 0.09525)
		(layer "In13.Cu")
		(net "M_B_CPU1_SB_DQS_DP<6>")
	)
	(arc
		(start 86.0425 -281.86126)
		(mid 85.761068 -281.937015)
		(end 85.479636 -281.86126)
		(width 0.09525)
		(layer "In13.Cu")
		(net "M_B_CPU1_SB_DQS_DP<6>")
	)
	(arc
		(start 89.181686 -281.834082)
		(mid 89.019004 -281.81195)
		(end 88.862408 -281.86126)
		(width 0.09525)
		(layer "In13.Cu")
		(net "M_B_CPU1_SB_DQS_DP<6>")
	)
	(arc
		(start 85.479636 -281.86126)
		(mid 85.295861 -281.810488)
		(end 85.110828 -281.856434)
		(width 0.09525)
		(layer "In13.Cu")
		(net "M_B_CPU1_SB_DQS_DP<6>")
	)
	(arc
		(start 83.591146 -281.856434)
		(mid 83.406114 -281.81052)
		(end 83.222338 -281.86126)
		(width 0.09525)
		(layer "In13.Cu")
		(net "M_B_CPU1_SB_DQS_DP<6>")
	)
	(arc
		(start 82.659474 -281.86126)
		(mid 82.471006 -281.810583)
		(end 82.282538 -281.86126)
		(width 0.09525)
		(layer "In13.Cu")
		(net "M_B_CPU1_SB_DQS_DP<6>")
	)
	(arc
		(start 81.37017 -281.846782)
		(mid 81.370044 -281.846401)
		(end 81.369916 -281.84602)
		(width 0.09525)
		(layer "In13.Cu")
		(net "M_B_CPU1_SB_DQS_DP<6>")
	)
	(segment
		(start 89.517982 -277.060406)
		(end 89.05113 -277.326344)
		(width 0.12954)
		(layer "F.Cu")
		(net "M_B_CPU1_SB_DQS_DP<5>")
	)
	(segment
		(start 76.250038 -276.292056)
		(end 76.038456 -276.292056)
		(width 0.09525)
		(layer "In13.Cu")
		(net "M_B_CPU1_SB_DQS_DP<5>")
	)
	(segment
		(start 75.955906 -276.350984)
		(end 70.100444 -276.350984)
		(width 0.16002)
		(layer "In13.Cu")
		(net "M_B_CPU1_SB_DQS_DP<5>")
	)
	(segment
		(start 89.05113 -277.326344)
		(end 89.205054 -277.060914)
		(width 0.09525)
		(layer "In13.Cu")
		(net "M_B_CPU1_SB_DQS_DP<5>")
	)
	(segment
		(start 53.484526 -286.460438)
		(end 51.489102 -286.460438)
		(width 0.16002)
		(layer "In13.Cu")
		(net "M_B_CPU1_SB_DQS_DP<5>")
	)
	(segment
		(start 48.094392 -286.275018)
		(end 47.784004 -286.585406)
		(width 0.16002)
		(layer "In13.Cu")
		(net "M_B_CPU1_SB_DQS_DP<5>")
	)
	(segment
		(start 86.050882 -276.996398)
		(end 86.0425 -277.001224)
		(width 0.09525)
		(layer "In13.Cu")
		(net "M_B_CPU1_SB_DQS_DP<5>")
	)
	(segment
		(start 75.979528 -276.350984)
		(end 75.955906 -276.350984)
		(width 0.09525)
		(layer "In13.Cu")
		(net "M_B_CPU1_SB_DQS_DP<5>")
	)
	(segment
		(start 51.489102 -286.460438)
		(end 50.69713 -286.132524)
		(width 0.16002)
		(layer "In13.Cu")
		(net "M_B_CPU1_SB_DQS_DP<5>")
	)
	(segment
		(start 49.858676 -286.132524)
		(end 49.514506 -286.275018)
		(width 0.16002)
		(layer "In13.Cu")
		(net "M_B_CPU1_SB_DQS_DP<5>")
	)
	(segment
		(start 83.599528 -277.001224)
		(end 83.591146 -276.996398)
		(width 0.09525)
		(layer "In13.Cu")
		(net "M_B_CPU1_SB_DQS_DP<5>")
	)
	(segment
		(start 85.110828 -276.996398)
		(end 85.102446 -277.001224)
		(width 0.09525)
		(layer "In13.Cu")
		(net "M_B_CPU1_SB_DQS_DP<5>")
	)
	(segment
		(start 76.802742 -276.794468)
		(end 76.33589 -276.327616)
		(width 0.09525)
		(layer "In13.Cu")
		(net "M_B_CPU1_SB_DQS_DP<5>")
	)
	(segment
		(start 50.69713 -286.132524)
		(end 49.858676 -286.132524)
		(width 0.16002)
		(layer "In13.Cu")
		(net "M_B_CPU1_SB_DQS_DP<5>")
	)
	(segment
		(start 61.57214 -284.879288)
		(end 58.546746 -286.132524)
		(width 0.16002)
		(layer "In13.Cu")
		(net "M_B_CPU1_SB_DQS_DP<5>")
	)
	(segment
		(start 79.237586 -276.883876)
		(end 77.01915 -276.883876)
		(width 0.09525)
		(layer "In13.Cu")
		(net "M_B_CPU1_SB_DQS_DP<5>")
	)
	(segment
		(start 53.956712 -286.932624)
		(end 53.484526 -286.460438)
		(width 0.16002)
		(layer "In13.Cu")
		(net "M_B_CPU1_SB_DQS_DP<5>")
	)
	(segment
		(start 49.514506 -286.275018)
		(end 48.094392 -286.275018)
		(width 0.16002)
		(layer "In13.Cu")
		(net "M_B_CPU1_SB_DQS_DP<5>")
	)
	(segment
		(start 89.205054 -277.060914)
		(end 89.181686 -276.974046)
		(width 0.09525)
		(layer "In13.Cu")
		(net "M_B_CPU1_SB_DQS_DP<5>")
	)
	(segment
		(start 58.546746 -286.132524)
		(end 57.836308 -286.132524)
		(width 0.16002)
		(layer "In13.Cu")
		(net "M_B_CPU1_SB_DQS_DP<5>")
	)
	(segment
		(start 57.836308 -286.132524)
		(end 57.036208 -286.932624)
		(width 0.16002)
		(layer "In13.Cu")
		(net "M_B_CPU1_SB_DQS_DP<5>")
	)
	(segment
		(start 70.100444 -276.350984)
		(end 61.57214 -284.879288)
		(width 0.16002)
		(layer "In13.Cu")
		(net "M_B_CPU1_SB_DQS_DP<5>")
	)
	(segment
		(start 84.539582 -277.001224)
		(end 84.5312 -276.996398)
		(width 0.09525)
		(layer "In13.Cu")
		(net "M_B_CPU1_SB_DQS_DP<5>")
	)
	(segment
		(start 57.036208 -286.932624)
		(end 53.956712 -286.932624)
		(width 0.16002)
		(layer "In13.Cu")
		(net "M_B_CPU1_SB_DQS_DP<5>")
	)
	(segment
		(start 88.299544 -277.001224)
		(end 88.291162 -276.996398)
		(width 0.09525)
		(layer "In13.Cu")
		(net "M_B_CPU1_SB_DQS_DP<5>")
	)
	(segment
		(start 76.038456 -276.292056)
		(end 75.979528 -276.350984)
		(width 0.09525)
		(layer "In13.Cu")
		(net "M_B_CPU1_SB_DQS_DP<5>")
	)
	(arc
		(start 86.982554 -277.001224)
		(mid 86.701122 -277.076979)
		(end 86.41969 -277.001224)
		(width 0.09525)
		(layer "In13.Cu")
		(net "M_B_CPU1_SB_DQS_DP<5>")
	)
	(arc
		(start 88.862408 -277.001224)
		(mid 88.580976 -277.076979)
		(end 88.299544 -277.001224)
		(width 0.09525)
		(layer "In13.Cu")
		(net "M_B_CPU1_SB_DQS_DP<5>")
	)
	(arc
		(start 81.369916 -276.985984)
		(mid 81.081617 -277.056929)
		(end 80.78851 -277.009606)
		(width 0.09525)
		(layer "In13.Cu")
		(net "M_B_CPU1_SB_DQS_DP<5>")
	)
	(arc
		(start 87.922354 -277.001224)
		(mid 87.640922 -277.076979)
		(end 87.35949 -277.001224)
		(width 0.09525)
		(layer "In13.Cu")
		(net "M_B_CPU1_SB_DQS_DP<5>")
	)
	(arc
		(start 88.291162 -276.996398)
		(mid 88.10613 -276.950484)
		(end 87.922354 -277.001224)
		(width 0.09525)
		(layer "In13.Cu")
		(net "M_B_CPU1_SB_DQS_DP<5>")
	)
	(arc
		(start 89.181686 -276.974046)
		(mid 89.019004 -276.951914)
		(end 88.862408 -277.001224)
		(width 0.09525)
		(layer "In13.Cu")
		(net "M_B_CPU1_SB_DQS_DP<5>")
	)
	(arc
		(start 84.162392 -277.001224)
		(mid 83.88096 -277.076979)
		(end 83.599528 -277.001224)
		(width 0.09525)
		(layer "In13.Cu")
		(net "M_B_CPU1_SB_DQS_DP<5>")
	)
	(arc
		(start 80.355948 -277.0251)
		(mid 80.122074 -277.076541)
		(end 79.88808 -277.025608)
		(width 0.09525)
		(layer "In13.Cu")
		(net "M_B_CPU1_SB_DQS_DP<5>")
	)
	(arc
		(start 84.5312 -276.996398)
		(mid 84.346168 -276.950484)
		(end 84.162392 -277.001224)
		(width 0.09525)
		(layer "In13.Cu")
		(net "M_B_CPU1_SB_DQS_DP<5>")
	)
	(arc
		(start 77.01915 -276.883876)
		(mid 76.902026 -276.860748)
		(end 76.802742 -276.794468)
		(width 0.09525)
		(layer "In13.Cu")
		(net "M_B_CPU1_SB_DQS_DP<5>")
	)
	(arc
		(start 76.33589 -276.327616)
		(mid 76.296515 -276.301243)
		(end 76.250038 -276.292056)
		(width 0.09525)
		(layer "In13.Cu")
		(net "M_B_CPU1_SB_DQS_DP<5>")
	)
	(arc
		(start 83.591146 -276.996398)
		(mid 83.406114 -276.950484)
		(end 83.222338 -277.001224)
		(width 0.09525)
		(layer "In13.Cu")
		(net "M_B_CPU1_SB_DQS_DP<5>")
	)
	(arc
		(start 82.659474 -277.001224)
		(mid 82.471006 -276.950547)
		(end 82.282538 -277.001224)
		(width 0.09525)
		(layer "In13.Cu")
		(net "M_B_CPU1_SB_DQS_DP<5>")
	)
	(arc
		(start 85.102446 -277.001224)
		(mid 84.821014 -277.076979)
		(end 84.539582 -277.001224)
		(width 0.09525)
		(layer "In13.Cu")
		(net "M_B_CPU1_SB_DQS_DP<5>")
	)
	(arc
		(start 79.88808 -277.025608)
		(mid 79.570471 -276.919686)
		(end 79.237586 -276.883876)
		(width 0.09525)
		(layer "In13.Cu")
		(net "M_B_CPU1_SB_DQS_DP<5>")
	)
	(arc
		(start 82.282538 -277.001224)
		(mid 82.001106 -277.076979)
		(end 81.719674 -277.001224)
		(width 0.09525)
		(layer "In13.Cu")
		(net "M_B_CPU1_SB_DQS_DP<5>")
	)
	(arc
		(start 80.78851 -277.009606)
		(mid 80.570665 -276.973833)
		(end 80.355948 -277.0251)
		(width 0.09525)
		(layer "In13.Cu")
		(net "M_B_CPU1_SB_DQS_DP<5>")
	)
	(arc
		(start 83.222338 -277.001224)
		(mid 82.940906 -277.076979)
		(end 82.659474 -277.001224)
		(width 0.09525)
		(layer "In13.Cu")
		(net "M_B_CPU1_SB_DQS_DP<5>")
	)
	(arc
		(start 81.719674 -277.001224)
		(mid 81.546714 -276.950867)
		(end 81.37017 -276.986746)
		(width 0.09525)
		(layer "In13.Cu")
		(net "M_B_CPU1_SB_DQS_DP<5>")
	)
	(arc
		(start 86.0425 -277.001224)
		(mid 85.761068 -277.076979)
		(end 85.479636 -277.001224)
		(width 0.09525)
		(layer "In13.Cu")
		(net "M_B_CPU1_SB_DQS_DP<5>")
	)
	(arc
		(start 81.37017 -276.986746)
		(mid 81.370044 -276.986365)
		(end 81.369916 -276.985984)
		(width 0.09525)
		(layer "In13.Cu")
		(net "M_B_CPU1_SB_DQS_DP<5>")
	)
	(arc
		(start 85.479636 -277.001224)
		(mid 85.295861 -276.950452)
		(end 85.110828 -276.996398)
		(width 0.09525)
		(layer "In13.Cu")
		(net "M_B_CPU1_SB_DQS_DP<5>")
	)
	(arc
		(start 87.35949 -277.001224)
		(mid 87.171022 -276.950547)
		(end 86.982554 -277.001224)
		(width 0.09525)
		(layer "In13.Cu")
		(net "M_B_CPU1_SB_DQS_DP<5>")
	)
	(arc
		(start 86.41969 -277.001224)
		(mid 86.235915 -276.950452)
		(end 86.050882 -276.996398)
		(width 0.09525)
		(layer "In13.Cu")
		(net "M_B_CPU1_SB_DQS_DP<5>")
	)
	(segment
		(start 89.517982 -272.20037)
		(end 89.05113 -272.466308)
		(width 0.12954)
		(layer "F.Cu")
		(net "M_B_CPU1_SB_DQS_DP<4>")
	)
	(segment
		(start 85.110828 -272.136362)
		(end 85.102446 -272.141188)
		(width 0.09525)
		(layer "In13.Cu")
		(net "M_B_CPU1_SB_DQS_DP<4>")
	)
	(segment
		(start 81.350866 -272.136362)
		(end 81.342484 -272.141188)
		(width 0.09525)
		(layer "In13.Cu")
		(net "M_B_CPU1_SB_DQS_DP<4>")
	)
	(segment
		(start 60.144152 -276.41169)
		(end 59.272678 -276.772624)
		(width 0.16002)
		(layer "In13.Cu")
		(net "M_B_CPU1_SB_DQS_DP<4>")
	)
	(segment
		(start 57.857136 -276.772624)
		(end 57.638188 -276.991572)
		(width 0.16002)
		(layer "In13.Cu")
		(net "M_B_CPU1_SB_DQS_DP<4>")
	)
	(segment
		(start 86.050882 -272.136362)
		(end 86.0425 -272.141188)
		(width 0.09525)
		(layer "In13.Cu")
		(net "M_B_CPU1_SB_DQS_DP<4>")
	)
	(segment
		(start 79.652876 -272.090388)
		(end 78.506828 -272.090388)
		(width 0.09525)
		(layer "In13.Cu")
		(net "M_B_CPU1_SB_DQS_DP<4>")
	)
	(segment
		(start 75.955906 -270.727424)
		(end 65.828418 -270.727424)
		(width 0.16002)
		(layer "In13.Cu")
		(net "M_B_CPU1_SB_DQS_DP<4>")
	)
	(segment
		(start 57.314592 -277.125938)
		(end 55.002684 -277.585424)
		(width 0.16002)
		(layer "In13.Cu")
		(net "M_B_CPU1_SB_DQS_DP<4>")
	)
	(segment
		(start 78.506828 -272.090388)
		(end 77.295756 -270.879316)
		(width 0.09525)
		(layer "In13.Cu")
		(net "M_B_CPU1_SB_DQS_DP<4>")
	)
	(segment
		(start 79.864204 -272.15465)
		(end 79.840836 -272.141188)
		(width 0.09525)
		(layer "In13.Cu")
		(net "M_B_CPU1_SB_DQS_DP<4>")
	)
	(segment
		(start 76.038456 -270.668496)
		(end 75.979528 -270.727424)
		(width 0.09525)
		(layer "In13.Cu")
		(net "M_B_CPU1_SB_DQS_DP<4>")
	)
	(segment
		(start 89.05113 -272.466308)
		(end 89.205054 -272.200878)
		(width 0.09525)
		(layer "In13.Cu")
		(net "M_B_CPU1_SB_DQS_DP<4>")
	)
	(segment
		(start 75.979528 -270.727424)
		(end 75.955906 -270.727424)
		(width 0.09525)
		(layer "In13.Cu")
		(net "M_B_CPU1_SB_DQS_DP<4>")
	)
	(segment
		(start 48.089058 -276.930358)
		(end 47.784004 -277.235412)
		(width 0.16002)
		(layer "In13.Cu")
		(net "M_B_CPU1_SB_DQS_DP<4>")
	)
	(segment
		(start 53.813964 -277.585424)
		(end 53.338984 -277.110444)
		(width 0.16002)
		(layer "In13.Cu")
		(net "M_B_CPU1_SB_DQS_DP<4>")
	)
	(segment
		(start 55.002684 -277.585424)
		(end 53.813964 -277.585424)
		(width 0.16002)
		(layer "In13.Cu")
		(net "M_B_CPU1_SB_DQS_DP<4>")
	)
	(segment
		(start 76.216256 -270.668496)
		(end 76.038456 -270.668496)
		(width 0.09525)
		(layer "In13.Cu")
		(net "M_B_CPU1_SB_DQS_DP<4>")
	)
	(segment
		(start 50.613564 -276.721824)
		(end 49.614582 -276.721824)
		(width 0.16002)
		(layer "In13.Cu")
		(net "M_B_CPU1_SB_DQS_DP<4>")
	)
	(segment
		(start 89.205054 -272.200878)
		(end 89.181686 -272.11401)
		(width 0.09525)
		(layer "In13.Cu")
		(net "M_B_CPU1_SB_DQS_DP<4>")
	)
	(segment
		(start 80.77962 -272.141188)
		(end 80.771238 -272.136362)
		(width 0.09525)
		(layer "In13.Cu")
		(net "M_B_CPU1_SB_DQS_DP<4>")
	)
	(segment
		(start 76.427076 -270.879316)
		(end 76.216256 -270.668496)
		(width 0.09525)
		(layer "In13.Cu")
		(net "M_B_CPU1_SB_DQS_DP<4>")
	)
	(segment
		(start 49.614582 -276.721824)
		(end 49.1109 -276.930358)
		(width 0.16002)
		(layer "In13.Cu")
		(net "M_B_CPU1_SB_DQS_DP<4>")
	)
	(segment
		(start 57.638188 -276.991572)
		(end 57.314592 -277.125938)
		(width 0.16002)
		(layer "In13.Cu")
		(net "M_B_CPU1_SB_DQS_DP<4>")
	)
	(segment
		(start 84.539582 -272.141188)
		(end 84.5312 -272.136362)
		(width 0.09525)
		(layer "In13.Cu")
		(net "M_B_CPU1_SB_DQS_DP<4>")
	)
	(segment
		(start 77.295756 -270.879316)
		(end 76.427076 -270.879316)
		(width 0.09525)
		(layer "In13.Cu")
		(net "M_B_CPU1_SB_DQS_DP<4>")
	)
	(segment
		(start 53.338984 -277.110444)
		(end 51.002184 -277.110444)
		(width 0.16002)
		(layer "In13.Cu")
		(net "M_B_CPU1_SB_DQS_DP<4>")
	)
	(segment
		(start 49.1109 -276.930358)
		(end 48.089058 -276.930358)
		(width 0.16002)
		(layer "In13.Cu")
		(net "M_B_CPU1_SB_DQS_DP<4>")
	)
	(segment
		(start 65.828418 -270.727424)
		(end 60.144152 -276.41169)
		(width 0.16002)
		(layer "In13.Cu")
		(net "M_B_CPU1_SB_DQS_DP<4>")
	)
	(segment
		(start 51.002184 -277.110444)
		(end 50.613564 -276.721824)
		(width 0.16002)
		(layer "In13.Cu")
		(net "M_B_CPU1_SB_DQS_DP<4>")
	)
	(segment
		(start 88.299544 -272.141188)
		(end 88.291162 -272.136362)
		(width 0.09525)
		(layer "In13.Cu")
		(net "M_B_CPU1_SB_DQS_DP<4>")
	)
	(segment
		(start 83.599528 -272.141188)
		(end 83.591146 -272.136362)
		(width 0.09525)
		(layer "In13.Cu")
		(net "M_B_CPU1_SB_DQS_DP<4>")
	)
	(segment
		(start 59.272678 -276.772624)
		(end 57.857136 -276.772624)
		(width 0.16002)
		(layer "In13.Cu")
		(net "M_B_CPU1_SB_DQS_DP<4>")
	)
	(arc
		(start 87.35949 -272.141188)
		(mid 87.171022 -272.090511)
		(end 86.982554 -272.141188)
		(width 0.09525)
		(layer "In13.Cu")
		(net "M_B_CPU1_SB_DQS_DP<4>")
	)
	(arc
		(start 85.102446 -272.141188)
		(mid 84.821014 -272.216943)
		(end 84.539582 -272.141188)
		(width 0.09525)
		(layer "In13.Cu")
		(net "M_B_CPU1_SB_DQS_DP<4>")
	)
	(arc
		(start 81.719674 -272.141188)
		(mid 81.535899 -272.090416)
		(end 81.350866 -272.136362)
		(width 0.09525)
		(layer "In13.Cu")
		(net "M_B_CPU1_SB_DQS_DP<4>")
	)
	(arc
		(start 83.591146 -272.136362)
		(mid 83.406114 -272.090448)
		(end 83.222338 -272.141188)
		(width 0.09525)
		(layer "In13.Cu")
		(net "M_B_CPU1_SB_DQS_DP<4>")
	)
	(arc
		(start 79.840836 -272.141188)
		(mid 79.750207 -272.103381)
		(end 79.652876 -272.090388)
		(width 0.09525)
		(layer "In13.Cu")
		(net "M_B_CPU1_SB_DQS_DP<4>")
	)
	(arc
		(start 83.222338 -272.141188)
		(mid 82.940906 -272.216943)
		(end 82.659474 -272.141188)
		(width 0.09525)
		(layer "In13.Cu")
		(net "M_B_CPU1_SB_DQS_DP<4>")
	)
	(arc
		(start 86.41969 -272.141188)
		(mid 86.235915 -272.090416)
		(end 86.050882 -272.136362)
		(width 0.09525)
		(layer "In13.Cu")
		(net "M_B_CPU1_SB_DQS_DP<4>")
	)
	(arc
		(start 88.862408 -272.141188)
		(mid 88.580976 -272.216943)
		(end 88.299544 -272.141188)
		(width 0.09525)
		(layer "In13.Cu")
		(net "M_B_CPU1_SB_DQS_DP<4>")
	)
	(arc
		(start 80.771238 -272.136362)
		(mid 80.586206 -272.090448)
		(end 80.40243 -272.141188)
		(width 0.09525)
		(layer "In13.Cu")
		(net "M_B_CPU1_SB_DQS_DP<4>")
	)
	(arc
		(start 88.291162 -272.136362)
		(mid 88.10613 -272.090448)
		(end 87.922354 -272.141188)
		(width 0.09525)
		(layer "In13.Cu")
		(net "M_B_CPU1_SB_DQS_DP<4>")
	)
	(arc
		(start 81.342484 -272.141188)
		(mid 81.061052 -272.216943)
		(end 80.77962 -272.141188)
		(width 0.09525)
		(layer "In13.Cu")
		(net "M_B_CPU1_SB_DQS_DP<4>")
	)
	(arc
		(start 84.5312 -272.136362)
		(mid 84.346168 -272.090448)
		(end 84.162392 -272.141188)
		(width 0.09525)
		(layer "In13.Cu")
		(net "M_B_CPU1_SB_DQS_DP<4>")
	)
	(arc
		(start 85.479636 -272.141188)
		(mid 85.295861 -272.090416)
		(end 85.110828 -272.136362)
		(width 0.09525)
		(layer "In13.Cu")
		(net "M_B_CPU1_SB_DQS_DP<4>")
	)
	(arc
		(start 86.982554 -272.141188)
		(mid 86.701122 -272.216943)
		(end 86.41969 -272.141188)
		(width 0.09525)
		(layer "In13.Cu")
		(net "M_B_CPU1_SB_DQS_DP<4>")
	)
	(arc
		(start 89.181686 -272.11401)
		(mid 89.019004 -272.091878)
		(end 88.862408 -272.141188)
		(width 0.09525)
		(layer "In13.Cu")
		(net "M_B_CPU1_SB_DQS_DP<4>")
	)
	(arc
		(start 82.659474 -272.141188)
		(mid 82.471006 -272.090511)
		(end 82.282538 -272.141188)
		(width 0.09525)
		(layer "In13.Cu")
		(net "M_B_CPU1_SB_DQS_DP<4>")
	)
	(arc
		(start 82.282538 -272.141188)
		(mid 82.001106 -272.216943)
		(end 81.719674 -272.141188)
		(width 0.09525)
		(layer "In13.Cu")
		(net "M_B_CPU1_SB_DQS_DP<4>")
	)
	(arc
		(start 86.0425 -272.141188)
		(mid 85.761068 -272.216943)
		(end 85.479636 -272.141188)
		(width 0.09525)
		(layer "In13.Cu")
		(net "M_B_CPU1_SB_DQS_DP<4>")
	)
	(arc
		(start 80.40243 -272.141188)
		(mid 80.135036 -272.216767)
		(end 79.864204 -272.15465)
		(width 0.09525)
		(layer "In13.Cu")
		(net "M_B_CPU1_SB_DQS_DP<4>")
	)
	(arc
		(start 84.162392 -272.141188)
		(mid 83.88096 -272.216943)
		(end 83.599528 -272.141188)
		(width 0.09525)
		(layer "In13.Cu")
		(net "M_B_CPU1_SB_DQS_DP<4>")
	)
	(arc
		(start 87.922354 -272.141188)
		(mid 87.640922 -272.216943)
		(end 87.35949 -272.141188)
		(width 0.09525)
		(layer "In13.Cu")
		(net "M_B_CPU1_SB_DQS_DP<4>")
	)
	(segment
		(start 88.577928 -290.020248)
		(end 88.111076 -290.286186)
		(width 0.12954)
		(layer "F.Cu")
		(net "M_B_CPU1_SB_DQS_DP<3>")
	)
	(segment
		(start 77.131672 -293.25189)
		(end 78.30312 -291.499036)
		(width 0.09525)
		(layer "In13.Cu")
		(net "M_B_CPU1_SB_DQS_DP<3>")
	)
	(segment
		(start 76.43749 -294.860472)
		(end 76.43749 -294.268652)
		(width 0.09525)
		(layer "In13.Cu")
		(net "M_B_CPU1_SB_DQS_DP<3>")
	)
	(segment
		(start 86.0425 -290.611306)
		(end 86.050882 -290.616132)
		(width 0.09525)
		(layer "In13.Cu")
		(net "M_B_CPU1_SB_DQS_DP<3>")
	)
	(segment
		(start 76.1492 -295.064942)
		(end 76.23302 -295.064942)
		(width 0.09525)
		(layer "In13.Cu")
		(net "M_B_CPU1_SB_DQS_DP<3>")
	)
	(segment
		(start 80.771238 -290.616132)
		(end 80.77962 -290.611306)
		(width 0.09525)
		(layer "In13.Cu")
		(net "M_B_CPU1_SB_DQS_DP<3>")
	)
	(segment
		(start 55.576216 -312.690764)
		(end 56.270398 -313.384946)
		(width 0.16002)
		(layer "In13.Cu")
		(net "M_B_CPU1_SB_DQS_DP<3>")
	)
	(segment
		(start 64.6557 -307.749956)
		(end 65.18275 -307.749956)
		(width 0.16002)
		(layer "In13.Cu")
		(net "M_B_CPU1_SB_DQS_DP<3>")
	)
	(segment
		(start 73.43775 -297.775884)
		(end 76.132436 -295.081706)
		(width 0.16002)
		(layer "In13.Cu")
		(net "M_B_CPU1_SB_DQS_DP<3>")
	)
	(segment
		(start 60.428124 -311.977532)
		(end 61.445394 -311.977532)
		(width 0.16002)
		(layer "In13.Cu")
		(net "M_B_CPU1_SB_DQS_DP<3>")
	)
	(segment
		(start 64.282828 -308.650386)
		(end 64.282828 -308.122828)
		(width 0.16002)
		(layer "In13.Cu")
		(net "M_B_CPU1_SB_DQS_DP<3>")
	)
	(segment
		(start 68.776596 -303.62906)
		(end 69.303646 -303.62906)
		(width 0.16002)
		(layer "In13.Cu")
		(net "M_B_CPU1_SB_DQS_DP<3>")
	)
	(segment
		(start 64.282828 -308.122828)
		(end 64.6557 -307.749956)
		(width 0.16002)
		(layer "In13.Cu")
		(net "M_B_CPU1_SB_DQS_DP<3>")
	)
	(segment
		(start 61.535564 -310.870092)
		(end 61.908436 -310.49722)
		(width 0.16002)
		(layer "In13.Cu")
		(net "M_B_CPU1_SB_DQS_DP<3>")
	)
	(segment
		(start 66.556382 -306.376324)
		(end 66.663062 -306.483004)
		(width 0.16002)
		(layer "In13.Cu")
		(net "M_B_CPU1_SB_DQS_DP<3>")
	)
	(segment
		(start 69.883782 -303.262284)
		(end 69.777356 -303.155858)
		(width 0.16002)
		(layer "In13.Cu")
		(net "M_B_CPU1_SB_DQS_DP<3>")
	)
	(segment
		(start 62.909196 -309.49646)
		(end 63.282068 -309.123588)
		(width 0.16002)
		(layer "In13.Cu")
		(net "M_B_CPU1_SB_DQS_DP<3>")
	)
	(segment
		(start 69.410326 -303.73574)
		(end 69.687186 -303.73574)
		(width 0.16002)
		(layer "In13.Cu")
		(net "M_B_CPU1_SB_DQS_DP<3>")
	)
	(segment
		(start 67.136518 -306.009548)
		(end 67.030092 -305.903122)
		(width 0.16002)
		(layer "In13.Cu")
		(net "M_B_CPU1_SB_DQS_DP<3>")
	)
	(segment
		(start 62.819026 -310.6039)
		(end 63.015622 -310.407304)
		(width 0.16002)
		(layer "In13.Cu")
		(net "M_B_CPU1_SB_DQS_DP<3>")
	)
	(segment
		(start 67.030092 -305.375564)
		(end 67.402964 -305.002692)
		(width 0.16002)
		(layer "In13.Cu")
		(net "M_B_CPU1_SB_DQS_DP<3>")
	)
	(segment
		(start 58.54954 -312.521346)
		(end 58.66638 -312.404506)
		(width 0.16002)
		(layer "In13.Cu")
		(net "M_B_CPU1_SB_DQS_DP<3>")
	)
	(segment
		(start 63.282068 -309.123588)
		(end 63.809118 -309.123588)
		(width 0.16002)
		(layer "In13.Cu")
		(net "M_B_CPU1_SB_DQS_DP<3>")
	)
	(segment
		(start 76.43749 -294.268652)
		(end 76.665328 -293.718488)
		(width 0.09525)
		(layer "In13.Cu")
		(net "M_B_CPU1_SB_DQS_DP<3>")
	)
	(segment
		(start 66.029332 -306.376324)
		(end 66.556382 -306.376324)
		(width 0.16002)
		(layer "In13.Cu")
		(net "M_B_CPU1_SB_DQS_DP<3>")
	)
	(segment
		(start 69.777356 -302.6283)
		(end 73.43775 -298.967906)
		(width 0.16002)
		(layer "In13.Cu")
		(net "M_B_CPU1_SB_DQS_DP<3>")
	)
	(segment
		(start 67.030092 -305.903122)
		(end 67.030092 -305.375564)
		(width 0.16002)
		(layer "In13.Cu")
		(net "M_B_CPU1_SB_DQS_DP<3>")
	)
	(segment
		(start 65.65646 -307.276754)
		(end 65.65646 -306.749196)
		(width 0.16002)
		(layer "In13.Cu")
		(net "M_B_CPU1_SB_DQS_DP<3>")
	)
	(segment
		(start 85.102446 -290.611306)
		(end 85.110828 -290.616132)
		(width 0.09525)
		(layer "In13.Cu")
		(net "M_B_CPU1_SB_DQS_DP<3>")
	)
	(segment
		(start 64.389254 -309.033672)
		(end 64.389254 -308.756812)
		(width 0.16002)
		(layer "In13.Cu")
		(net "M_B_CPU1_SB_DQS_DP<3>")
	)
	(segment
		(start 54.543706 -313.209178)
		(end 55.06212 -312.690764)
		(width 0.16002)
		(layer "In13.Cu")
		(net "M_B_CPU1_SB_DQS_DP<3>")
	)
	(segment
		(start 58.66638 -312.404506)
		(end 59.14644 -312.404506)
		(width 0.16002)
		(layer "In13.Cu")
		(net "M_B_CPU1_SB_DQS_DP<3>")
	)
	(segment
		(start 69.687186 -303.73574)
		(end 69.883782 -303.539144)
		(width 0.16002)
		(layer "In13.Cu")
		(net "M_B_CPU1_SB_DQS_DP<3>")
	)
	(segment
		(start 61.64199 -311.780936)
		(end 61.64199 -311.504076)
		(width 0.16002)
		(layer "In13.Cu")
		(net "M_B_CPU1_SB_DQS_DP<3>")
	)
	(segment
		(start 62.435486 -310.49722)
		(end 62.542166 -310.6039)
		(width 0.16002)
		(layer "In13.Cu")
		(net "M_B_CPU1_SB_DQS_DP<3>")
	)
	(segment
		(start 65.18275 -307.749956)
		(end 65.28943 -307.856636)
		(width 0.16002)
		(layer "In13.Cu")
		(net "M_B_CPU1_SB_DQS_DP<3>")
	)
	(segment
		(start 67.136518 -306.286408)
		(end 67.136518 -306.009548)
		(width 0.16002)
		(layer "In13.Cu")
		(net "M_B_CPU1_SB_DQS_DP<3>")
	)
	(segment
		(start 59.14644 -312.404506)
		(end 59.26328 -312.521346)
		(width 0.16002)
		(layer "In13.Cu")
		(net "M_B_CPU1_SB_DQS_DP<3>")
	)
	(segment
		(start 61.445394 -311.977532)
		(end 61.64199 -311.780936)
		(width 0.16002)
		(layer "In13.Cu")
		(net "M_B_CPU1_SB_DQS_DP<3>")
	)
	(segment
		(start 64.192658 -309.230268)
		(end 64.389254 -309.033672)
		(width 0.16002)
		(layer "In13.Cu")
		(net "M_B_CPU1_SB_DQS_DP<3>")
	)
	(segment
		(start 57.749186 -312.521346)
		(end 58.54954 -312.521346)
		(width 0.16002)
		(layer "In13.Cu")
		(net "M_B_CPU1_SB_DQS_DP<3>")
	)
	(segment
		(start 59.26328 -312.521346)
		(end 59.88431 -312.521346)
		(width 0.16002)
		(layer "In13.Cu")
		(net "M_B_CPU1_SB_DQS_DP<3>")
	)
	(segment
		(start 69.303646 -303.62906)
		(end 69.410326 -303.73574)
		(width 0.16002)
		(layer "In13.Cu")
		(net "M_B_CPU1_SB_DQS_DP<3>")
	)
	(segment
		(start 61.535564 -311.39765)
		(end 61.535564 -310.870092)
		(width 0.16002)
		(layer "In13.Cu")
		(net "M_B_CPU1_SB_DQS_DP<3>")
	)
	(segment
		(start 73.43775 -298.967906)
		(end 73.43775 -297.775884)
		(width 0.16002)
		(layer "In13.Cu")
		(net "M_B_CPU1_SB_DQS_DP<3>")
	)
	(segment
		(start 65.56629 -307.856636)
		(end 65.762886 -307.66004)
		(width 0.16002)
		(layer "In13.Cu")
		(net "M_B_CPU1_SB_DQS_DP<3>")
	)
	(segment
		(start 61.908436 -310.49722)
		(end 62.435486 -310.49722)
		(width 0.16002)
		(layer "In13.Cu")
		(net "M_B_CPU1_SB_DQS_DP<3>")
	)
	(segment
		(start 65.65646 -306.749196)
		(end 66.029332 -306.376324)
		(width 0.16002)
		(layer "In13.Cu")
		(net "M_B_CPU1_SB_DQS_DP<3>")
	)
	(segment
		(start 55.06212 -312.690764)
		(end 55.576216 -312.690764)
		(width 0.16002)
		(layer "In13.Cu")
		(net "M_B_CPU1_SB_DQS_DP<3>")
	)
	(segment
		(start 62.909196 -310.024018)
		(end 62.909196 -309.49646)
		(width 0.16002)
		(layer "In13.Cu")
		(net "M_B_CPU1_SB_DQS_DP<3>")
	)
	(segment
		(start 62.542166 -310.6039)
		(end 62.819026 -310.6039)
		(width 0.16002)
		(layer "In13.Cu")
		(net "M_B_CPU1_SB_DQS_DP<3>")
	)
	(segment
		(start 52.157884 -313.209178)
		(end 54.543706 -313.209178)
		(width 0.16002)
		(layer "In13.Cu")
		(net "M_B_CPU1_SB_DQS_DP<3>")
	)
	(segment
		(start 63.915798 -309.230268)
		(end 64.192658 -309.230268)
		(width 0.16002)
		(layer "In13.Cu")
		(net "M_B_CPU1_SB_DQS_DP<3>")
	)
	(segment
		(start 64.389254 -308.756812)
		(end 64.282828 -308.650386)
		(width 0.16002)
		(layer "In13.Cu")
		(net "M_B_CPU1_SB_DQS_DP<3>")
	)
	(segment
		(start 87.957152 -290.551616)
		(end 88.111076 -290.286186)
		(width 0.09525)
		(layer "In13.Cu")
		(net "M_B_CPU1_SB_DQS_DP<3>")
	)
	(segment
		(start 56.885586 -313.384946)
		(end 57.749186 -312.521346)
		(width 0.16002)
		(layer "In13.Cu")
		(net "M_B_CPU1_SB_DQS_DP<3>")
	)
	(segment
		(start 56.270398 -313.384946)
		(end 56.885586 -313.384946)
		(width 0.16002)
		(layer "In13.Cu")
		(net "M_B_CPU1_SB_DQS_DP<3>")
	)
	(segment
		(start 65.28943 -307.856636)
		(end 65.56629 -307.856636)
		(width 0.16002)
		(layer "In13.Cu")
		(net "M_B_CPU1_SB_DQS_DP<3>")
	)
	(segment
		(start 68.51015 -304.912776)
		(end 68.51015 -304.635916)
		(width 0.16002)
		(layer "In13.Cu")
		(net "M_B_CPU1_SB_DQS_DP<3>")
	)
	(segment
		(start 68.403724 -304.52949)
		(end 68.403724 -304.001932)
		(width 0.16002)
		(layer "In13.Cu")
		(net "M_B_CPU1_SB_DQS_DP<3>")
	)
	(segment
		(start 68.51015 -304.635916)
		(end 68.403724 -304.52949)
		(width 0.16002)
		(layer "In13.Cu")
		(net "M_B_CPU1_SB_DQS_DP<3>")
	)
	(segment
		(start 87.856314 -290.578286)
		(end 87.957152 -290.551616)
		(width 0.09525)
		(layer "In13.Cu")
		(net "M_B_CPU1_SB_DQS_DP<3>")
	)
	(segment
		(start 59.88431 -312.521346)
		(end 60.428124 -311.977532)
		(width 0.16002)
		(layer "In13.Cu")
		(net "M_B_CPU1_SB_DQS_DP<3>")
	)
	(segment
		(start 76.665328 -293.718488)
		(end 77.131672 -293.25189)
		(width 0.09525)
		(layer "In13.Cu")
		(net "M_B_CPU1_SB_DQS_DP<3>")
	)
	(segment
		(start 69.883782 -303.539144)
		(end 69.883782 -303.262284)
		(width 0.16002)
		(layer "In13.Cu")
		(net "M_B_CPU1_SB_DQS_DP<3>")
	)
	(segment
		(start 67.402964 -305.002692)
		(end 67.930014 -305.002692)
		(width 0.16002)
		(layer "In13.Cu")
		(net "M_B_CPU1_SB_DQS_DP<3>")
	)
	(segment
		(start 63.015622 -310.407304)
		(end 63.015622 -310.130444)
		(width 0.16002)
		(layer "In13.Cu")
		(net "M_B_CPU1_SB_DQS_DP<3>")
	)
	(segment
		(start 81.342484 -290.611306)
		(end 81.350866 -290.616132)
		(width 0.09525)
		(layer "In13.Cu")
		(net "M_B_CPU1_SB_DQS_DP<3>")
	)
	(segment
		(start 83.591146 -290.616132)
		(end 83.599528 -290.611306)
		(width 0.09525)
		(layer "In13.Cu")
		(net "M_B_CPU1_SB_DQS_DP<3>")
	)
	(segment
		(start 51.884072 -312.935366)
		(end 52.157884 -313.209178)
		(width 0.16002)
		(layer "In13.Cu")
		(net "M_B_CPU1_SB_DQS_DP<3>")
	)
	(segment
		(start 78.30312 -291.499036)
		(end 79.744824 -290.535614)
		(width 0.09525)
		(layer "In13.Cu")
		(net "M_B_CPU1_SB_DQS_DP<3>")
	)
	(segment
		(start 79.744824 -290.535614)
		(end 80.121252 -290.535614)
		(width 0.09525)
		(layer "In13.Cu")
		(net "M_B_CPU1_SB_DQS_DP<3>")
	)
	(segment
		(start 63.015622 -310.130444)
		(end 62.909196 -310.024018)
		(width 0.16002)
		(layer "In13.Cu")
		(net "M_B_CPU1_SB_DQS_DP<3>")
	)
	(segment
		(start 69.777356 -303.155858)
		(end 69.777356 -302.6283)
		(width 0.16002)
		(layer "In13.Cu")
		(net "M_B_CPU1_SB_DQS_DP<3>")
	)
	(segment
		(start 68.403724 -304.001932)
		(end 68.776596 -303.62906)
		(width 0.16002)
		(layer "In13.Cu")
		(net "M_B_CPU1_SB_DQS_DP<3>")
	)
	(segment
		(start 61.64199 -311.504076)
		(end 61.535564 -311.39765)
		(width 0.16002)
		(layer "In13.Cu")
		(net "M_B_CPU1_SB_DQS_DP<3>")
	)
	(segment
		(start 63.809118 -309.123588)
		(end 63.915798 -309.230268)
		(width 0.16002)
		(layer "In13.Cu")
		(net "M_B_CPU1_SB_DQS_DP<3>")
	)
	(segment
		(start 65.762886 -307.66004)
		(end 65.762886 -307.38318)
		(width 0.16002)
		(layer "In13.Cu")
		(net "M_B_CPU1_SB_DQS_DP<3>")
	)
	(segment
		(start 66.939922 -306.483004)
		(end 67.136518 -306.286408)
		(width 0.16002)
		(layer "In13.Cu")
		(net "M_B_CPU1_SB_DQS_DP<3>")
	)
	(segment
		(start 76.23302 -295.064942)
		(end 76.43749 -294.860472)
		(width 0.09525)
		(layer "In13.Cu")
		(net "M_B_CPU1_SB_DQS_DP<3>")
	)
	(segment
		(start 67.930014 -305.002692)
		(end 68.036694 -305.109372)
		(width 0.16002)
		(layer "In13.Cu")
		(net "M_B_CPU1_SB_DQS_DP<3>")
	)
	(segment
		(start 68.313554 -305.109372)
		(end 68.51015 -304.912776)
		(width 0.16002)
		(layer "In13.Cu")
		(net "M_B_CPU1_SB_DQS_DP<3>")
	)
	(segment
		(start 84.5312 -290.616132)
		(end 84.539582 -290.611306)
		(width 0.09525)
		(layer "In13.Cu")
		(net "M_B_CPU1_SB_DQS_DP<3>")
	)
	(segment
		(start 68.036694 -305.109372)
		(end 68.313554 -305.109372)
		(width 0.16002)
		(layer "In13.Cu")
		(net "M_B_CPU1_SB_DQS_DP<3>")
	)
	(segment
		(start 65.762886 -307.38318)
		(end 65.65646 -307.276754)
		(width 0.16002)
		(layer "In13.Cu")
		(net "M_B_CPU1_SB_DQS_DP<3>")
	)
	(segment
		(start 66.663062 -306.483004)
		(end 66.939922 -306.483004)
		(width 0.16002)
		(layer "In13.Cu")
		(net "M_B_CPU1_SB_DQS_DP<3>")
	)
	(segment
		(start 76.132436 -295.081706)
		(end 76.1492 -295.064942)
		(width 0.09525)
		(layer "In13.Cu")
		(net "M_B_CPU1_SB_DQS_DP<3>")
	)
	(arc
		(start 83.599528 -290.611306)
		(mid 83.88096 -290.535551)
		(end 84.162392 -290.611306)
		(width 0.09525)
		(layer "In13.Cu")
		(net "M_B_CPU1_SB_DQS_DP<3>")
	)
	(arc
		(start 85.110828 -290.616132)
		(mid 85.29586 -290.662046)
		(end 85.479636 -290.611306)
		(width 0.09525)
		(layer "In13.Cu")
		(net "M_B_CPU1_SB_DQS_DP<3>")
	)
	(arc
		(start 87.83574 -290.570158)
		(mid 87.846068 -290.574118)
		(end 87.856314 -290.578286)
		(width 0.09525)
		(layer "In13.Cu")
		(net "M_B_CPU1_SB_DQS_DP<3>")
	)
	(arc
		(start 82.282538 -290.611306)
		(mid 82.471006 -290.661983)
		(end 82.659474 -290.611306)
		(width 0.09525)
		(layer "In13.Cu")
		(net "M_B_CPU1_SB_DQS_DP<3>")
	)
	(arc
		(start 80.121252 -290.535614)
		(mid 80.266829 -290.554915)
		(end 80.40243 -290.611306)
		(width 0.09525)
		(layer "In13.Cu")
		(net "M_B_CPU1_SB_DQS_DP<3>")
	)
	(arc
		(start 83.222338 -290.611306)
		(mid 83.406113 -290.662078)
		(end 83.591146 -290.616132)
		(width 0.09525)
		(layer "In13.Cu")
		(net "M_B_CPU1_SB_DQS_DP<3>")
	)
	(arc
		(start 80.40243 -290.611306)
		(mid 80.586205 -290.662078)
		(end 80.771238 -290.616132)
		(width 0.09525)
		(layer "In13.Cu")
		(net "M_B_CPU1_SB_DQS_DP<3>")
	)
	(arc
		(start 84.162392 -290.611306)
		(mid 84.346167 -290.662078)
		(end 84.5312 -290.616132)
		(width 0.09525)
		(layer "In13.Cu")
		(net "M_B_CPU1_SB_DQS_DP<3>")
	)
	(arc
		(start 80.77962 -290.611306)
		(mid 81.061052 -290.535551)
		(end 81.342484 -290.611306)
		(width 0.09525)
		(layer "In13.Cu")
		(net "M_B_CPU1_SB_DQS_DP<3>")
	)
	(arc
		(start 81.350866 -290.616132)
		(mid 81.535898 -290.662046)
		(end 81.719674 -290.611306)
		(width 0.09525)
		(layer "In13.Cu")
		(net "M_B_CPU1_SB_DQS_DP<3>")
	)
	(arc
		(start 84.539582 -290.611306)
		(mid 84.821014 -290.535551)
		(end 85.102446 -290.611306)
		(width 0.09525)
		(layer "In13.Cu")
		(net "M_B_CPU1_SB_DQS_DP<3>")
	)
	(arc
		(start 86.982554 -290.611306)
		(mid 87.171022 -290.661983)
		(end 87.35949 -290.611306)
		(width 0.09525)
		(layer "In13.Cu")
		(net "M_B_CPU1_SB_DQS_DP<3>")
	)
	(arc
		(start 86.41969 -290.611306)
		(mid 86.701122 -290.535551)
		(end 86.982554 -290.611306)
		(width 0.09525)
		(layer "In13.Cu")
		(net "M_B_CPU1_SB_DQS_DP<3>")
	)
	(arc
		(start 82.659474 -290.611306)
		(mid 82.940906 -290.535551)
		(end 83.222338 -290.611306)
		(width 0.09525)
		(layer "In13.Cu")
		(net "M_B_CPU1_SB_DQS_DP<3>")
	)
	(arc
		(start 85.479636 -290.611306)
		(mid 85.761068 -290.535551)
		(end 86.0425 -290.611306)
		(width 0.09525)
		(layer "In13.Cu")
		(net "M_B_CPU1_SB_DQS_DP<3>")
	)
	(arc
		(start 81.719674 -290.611306)
		(mid 82.001106 -290.535551)
		(end 82.282538 -290.611306)
		(width 0.09525)
		(layer "In13.Cu")
		(net "M_B_CPU1_SB_DQS_DP<3>")
	)
	(arc
		(start 86.050882 -290.616132)
		(mid 86.235914 -290.662046)
		(end 86.41969 -290.611306)
		(width 0.09525)
		(layer "In13.Cu")
		(net "M_B_CPU1_SB_DQS_DP<3>")
	)
	(arc
		(start 87.35949 -290.611306)
		(mid 87.593004 -290.537463)
		(end 87.83574 -290.570158)
		(width 0.09525)
		(layer "In13.Cu")
		(net "M_B_CPU1_SB_DQS_DP<3>")
	)
	(segment
		(start 88.577928 -285.160466)
		(end 88.111076 -285.426404)
		(width 0.12954)
		(layer "F.Cu")
		(net "M_B_CPU1_SB_DQS_DP<2>")
	)
	(segment
		(start 66.508884 -296.52722)
		(end 65.98158 -296.52722)
		(width 0.16002)
		(layer "In13.Cu")
		(net "M_B_CPU1_SB_DQS_DP<2>")
	)
	(segment
		(start 59.51474 -303.054512)
		(end 59.03468 -303.054512)
		(width 0.16002)
		(layer "In13.Cu")
		(net "M_B_CPU1_SB_DQS_DP<2>")
	)
	(segment
		(start 78.770734 -285.810198)
		(end 77.998574 -285.810198)
		(width 0.09525)
		(layer "In13.Cu")
		(net "M_B_CPU1_SB_DQS_DP<2>")
	)
	(segment
		(start 66.720212 -296.738548)
		(end 66.508884 -296.52722)
		(width 0.16002)
		(layer "In13.Cu")
		(net "M_B_CPU1_SB_DQS_DP<2>")
	)
	(segment
		(start 67.193414 -296.541698)
		(end 66.996564 -296.738548)
		(width 0.16002)
		(layer "In13.Cu")
		(net "M_B_CPU1_SB_DQS_DP<2>")
	)
	(segment
		(start 63.072518 -300.385988)
		(end 63.072518 -300.662594)
		(width 0.16002)
		(layer "In13.Cu")
		(net "M_B_CPU1_SB_DQS_DP<2>")
	)
	(segment
		(start 88.111076 -285.426404)
		(end 87.957152 -285.691834)
		(width 0.09525)
		(layer "In13.Cu")
		(net "M_B_CPU1_SB_DQS_DP<2>")
	)
	(segment
		(start 63.76162 -299.274484)
		(end 63.234316 -299.274484)
		(width 0.16002)
		(layer "In13.Cu")
		(net "M_B_CPU1_SB_DQS_DP<2>")
	)
	(segment
		(start 64.44615 -299.012356)
		(end 64.44615 -299.288962)
		(width 0.16002)
		(layer "In13.Cu")
		(net "M_B_CPU1_SB_DQS_DP<2>")
	)
	(segment
		(start 76.05649 -286.53613)
		(end 75.97267 -286.53613)
		(width 0.09525)
		(layer "In13.Cu")
		(net "M_B_CPU1_SB_DQS_DP<2>")
	)
	(segment
		(start 80.40243 -285.751524)
		(end 80.392016 -285.745428)
		(width 0.09525)
		(layer "In13.Cu")
		(net "M_B_CPU1_SB_DQS_DP<2>")
	)
	(segment
		(start 65.98158 -296.52722)
		(end 65.608708 -296.900092)
		(width 0.16002)
		(layer "In13.Cu")
		(net "M_B_CPU1_SB_DQS_DP<2>")
	)
	(segment
		(start 54.390798 -304.092864)
		(end 53.59654 -304.092864)
		(width 0.16002)
		(layer "In13.Cu")
		(net "M_B_CPU1_SB_DQS_DP<2>")
	)
	(segment
		(start 80.77962 -285.751524)
		(end 80.771238 -285.75635)
		(width 0.09525)
		(layer "In13.Cu")
		(net "M_B_CPU1_SB_DQS_DP<2>")
	)
	(segment
		(start 62.861444 -299.647356)
		(end 62.861444 -300.174914)
		(width 0.16002)
		(layer "In13.Cu")
		(net "M_B_CPU1_SB_DQS_DP<2>")
	)
	(segment
		(start 65.135252 -297.900852)
		(end 64.607948 -297.900852)
		(width 0.16002)
		(layer "In13.Cu")
		(net "M_B_CPU1_SB_DQS_DP<2>")
	)
	(segment
		(start 75.97267 -286.53613)
		(end 75.955906 -286.552894)
		(width 0.09525)
		(layer "In13.Cu")
		(net "M_B_CPU1_SB_DQS_DP<2>")
	)
	(segment
		(start 65.819782 -297.638724)
		(end 65.819782 -297.91533)
		(width 0.16002)
		(layer "In13.Cu")
		(net "M_B_CPU1_SB_DQS_DP<2>")
	)
	(segment
		(start 65.34658 -298.11218)
		(end 65.135252 -297.900852)
		(width 0.16002)
		(layer "In13.Cu")
		(net "M_B_CPU1_SB_DQS_DP<2>")
	)
	(segment
		(start 57.802526 -303.171352)
		(end 56.500014 -304.473864)
		(width 0.16002)
		(layer "In13.Cu")
		(net "M_B_CPU1_SB_DQS_DP<2>")
	)
	(segment
		(start 77.998574 -285.810198)
		(end 77.443076 -286.365696)
		(width 0.09525)
		(layer "In13.Cu")
		(net "M_B_CPU1_SB_DQS_DP<2>")
	)
	(segment
		(start 60.230004 -303.171352)
		(end 59.63158 -303.171352)
		(width 0.16002)
		(layer "In13.Cu")
		(net "M_B_CPU1_SB_DQS_DP<2>")
	)
	(segment
		(start 59.63158 -303.171352)
		(end 59.51474 -303.054512)
		(width 0.16002)
		(layer "In13.Cu")
		(net "M_B_CPU1_SB_DQS_DP<2>")
	)
	(segment
		(start 62.387988 -300.648116)
		(end 61.860684 -300.648116)
		(width 0.16002)
		(layer "In13.Cu")
		(net "M_B_CPU1_SB_DQS_DP<2>")
	)
	(segment
		(start 64.235076 -298.273724)
		(end 64.235076 -298.801282)
		(width 0.16002)
		(layer "In13.Cu")
		(net "M_B_CPU1_SB_DQS_DP<2>")
	)
	(segment
		(start 66.996564 -296.738548)
		(end 66.720212 -296.738548)
		(width 0.16002)
		(layer "In13.Cu")
		(net "M_B_CPU1_SB_DQS_DP<2>")
	)
	(segment
		(start 61.41847 -301.09033)
		(end 61.41847 -301.982886)
		(width 0.16002)
		(layer "In13.Cu")
		(net "M_B_CPU1_SB_DQS_DP<2>")
	)
	(segment
		(start 86.050882 -285.75635)
		(end 86.0425 -285.751524)
		(width 0.09525)
		(layer "In13.Cu")
		(net "M_B_CPU1_SB_DQS_DP<2>")
	)
	(segment
		(start 81.350866 -285.75635)
		(end 81.342484 -285.751524)
		(width 0.09525)
		(layer "In13.Cu")
		(net "M_B_CPU1_SB_DQS_DP<2>")
	)
	(segment
		(start 62.599316 -300.859444)
		(end 62.387988 -300.648116)
		(width 0.16002)
		(layer "In13.Cu")
		(net "M_B_CPU1_SB_DQS_DP<2>")
	)
	(segment
		(start 58.91784 -303.171352)
		(end 57.802526 -303.171352)
		(width 0.16002)
		(layer "In13.Cu")
		(net "M_B_CPU1_SB_DQS_DP<2>")
	)
	(segment
		(start 59.03468 -303.054512)
		(end 58.91784 -303.171352)
		(width 0.16002)
		(layer "In13.Cu")
		(net "M_B_CPU1_SB_DQS_DP<2>")
	)
	(segment
		(start 56.066944 -304.275998)
		(end 56.066944 -303.727358)
		(width 0.16002)
		(layer "In13.Cu")
		(net "M_B_CPU1_SB_DQS_DP<2>")
	)
	(segment
		(start 55.140098 -303.343564)
		(end 54.390798 -304.092864)
		(width 0.16002)
		(layer "In13.Cu")
		(net "M_B_CPU1_SB_DQS_DP<2>")
	)
	(segment
		(start 64.44615 -299.288962)
		(end 64.2493 -299.485812)
		(width 0.16002)
		(layer "In13.Cu")
		(net "M_B_CPU1_SB_DQS_DP<2>")
	)
	(segment
		(start 63.072518 -300.662594)
		(end 62.875668 -300.859444)
		(width 0.16002)
		(layer "In13.Cu")
		(net "M_B_CPU1_SB_DQS_DP<2>")
	)
	(segment
		(start 56.26481 -304.473864)
		(end 56.066944 -304.275998)
		(width 0.16002)
		(layer "In13.Cu")
		(net "M_B_CPU1_SB_DQS_DP<2>")
	)
	(segment
		(start 61.860684 -300.648116)
		(end 61.41847 -301.09033)
		(width 0.16002)
		(layer "In13.Cu")
		(net "M_B_CPU1_SB_DQS_DP<2>")
	)
	(segment
		(start 65.622932 -298.11218)
		(end 65.34658 -298.11218)
		(width 0.16002)
		(layer "In13.Cu")
		(net "M_B_CPU1_SB_DQS_DP<2>")
	)
	(segment
		(start 85.110828 -285.75635)
		(end 85.102446 -285.751524)
		(width 0.09525)
		(layer "In13.Cu")
		(net "M_B_CPU1_SB_DQS_DP<2>")
	)
	(segment
		(start 65.608708 -297.42765)
		(end 65.819782 -297.638724)
		(width 0.16002)
		(layer "In13.Cu")
		(net "M_B_CPU1_SB_DQS_DP<2>")
	)
	(segment
		(start 56.500014 -304.473864)
		(end 56.26481 -304.473864)
		(width 0.16002)
		(layer "In13.Cu")
		(net "M_B_CPU1_SB_DQS_DP<2>")
	)
	(segment
		(start 63.234316 -299.274484)
		(end 62.861444 -299.647356)
		(width 0.16002)
		(layer "In13.Cu")
		(net "M_B_CPU1_SB_DQS_DP<2>")
	)
	(segment
		(start 61.41847 -301.982886)
		(end 60.230004 -303.171352)
		(width 0.16002)
		(layer "In13.Cu")
		(net "M_B_CPU1_SB_DQS_DP<2>")
	)
	(segment
		(start 62.861444 -300.174914)
		(end 63.072518 -300.385988)
		(width 0.16002)
		(layer "In13.Cu")
		(net "M_B_CPU1_SB_DQS_DP<2>")
	)
	(segment
		(start 87.957152 -285.691834)
		(end 87.856314 -285.718504)
		(width 0.09525)
		(layer "In13.Cu")
		(net "M_B_CPU1_SB_DQS_DP<2>")
	)
	(segment
		(start 83.599528 -285.751524)
		(end 83.591146 -285.75635)
		(width 0.09525)
		(layer "In13.Cu")
		(net "M_B_CPU1_SB_DQS_DP<2>")
	)
	(segment
		(start 79.839312 -285.751524)
		(end 79.77505 -285.788862)
		(width 0.09525)
		(layer "In13.Cu")
		(net "M_B_CPU1_SB_DQS_DP<2>")
	)
	(segment
		(start 65.819782 -297.91533)
		(end 65.622932 -298.11218)
		(width 0.16002)
		(layer "In13.Cu")
		(net "M_B_CPU1_SB_DQS_DP<2>")
	)
	(segment
		(start 66.98234 -296.054018)
		(end 67.193414 -296.265092)
		(width 0.16002)
		(layer "In13.Cu")
		(net "M_B_CPU1_SB_DQS_DP<2>")
	)
	(segment
		(start 63.972948 -299.485812)
		(end 63.76162 -299.274484)
		(width 0.16002)
		(layer "In13.Cu")
		(net "M_B_CPU1_SB_DQS_DP<2>")
	)
	(segment
		(start 62.875668 -300.859444)
		(end 62.599316 -300.859444)
		(width 0.16002)
		(layer "In13.Cu")
		(net "M_B_CPU1_SB_DQS_DP<2>")
	)
	(segment
		(start 84.539582 -285.751524)
		(end 84.5312 -285.75635)
		(width 0.09525)
		(layer "In13.Cu")
		(net "M_B_CPU1_SB_DQS_DP<2>")
	)
	(segment
		(start 77.443076 -286.365696)
		(end 76.226924 -286.365696)
		(width 0.09525)
		(layer "In13.Cu")
		(net "M_B_CPU1_SB_DQS_DP<2>")
	)
	(segment
		(start 55.68315 -303.343564)
		(end 55.140098 -303.343564)
		(width 0.16002)
		(layer "In13.Cu")
		(net "M_B_CPU1_SB_DQS_DP<2>")
	)
	(segment
		(start 78.958694 -285.721806)
		(end 78.770734 -285.810198)
		(width 0.09525)
		(layer "In13.Cu")
		(net "M_B_CPU1_SB_DQS_DP<2>")
	)
	(segment
		(start 67.193414 -296.265092)
		(end 67.193414 -296.541698)
		(width 0.16002)
		(layer "In13.Cu")
		(net "M_B_CPU1_SB_DQS_DP<2>")
	)
	(segment
		(start 53.36286 -303.859184)
		(end 52.157884 -303.859184)
		(width 0.16002)
		(layer "In13.Cu")
		(net "M_B_CPU1_SB_DQS_DP<2>")
	)
	(segment
		(start 76.226924 -286.365696)
		(end 76.05649 -286.53613)
		(width 0.09525)
		(layer "In13.Cu")
		(net "M_B_CPU1_SB_DQS_DP<2>")
	)
	(segment
		(start 64.607948 -297.900852)
		(end 64.235076 -298.273724)
		(width 0.16002)
		(layer "In13.Cu")
		(net "M_B_CPU1_SB_DQS_DP<2>")
	)
	(segment
		(start 75.955906 -286.552894)
		(end 66.98234 -295.52646)
		(width 0.16002)
		(layer "In13.Cu")
		(net "M_B_CPU1_SB_DQS_DP<2>")
	)
	(segment
		(start 64.2493 -299.485812)
		(end 63.972948 -299.485812)
		(width 0.16002)
		(layer "In13.Cu")
		(net "M_B_CPU1_SB_DQS_DP<2>")
	)
	(segment
		(start 53.59654 -304.092864)
		(end 53.36286 -303.859184)
		(width 0.16002)
		(layer "In13.Cu")
		(net "M_B_CPU1_SB_DQS_DP<2>")
	)
	(segment
		(start 66.98234 -295.52646)
		(end 66.98234 -296.054018)
		(width 0.16002)
		(layer "In13.Cu")
		(net "M_B_CPU1_SB_DQS_DP<2>")
	)
	(segment
		(start 56.066944 -303.727358)
		(end 55.68315 -303.343564)
		(width 0.16002)
		(layer "In13.Cu")
		(net "M_B_CPU1_SB_DQS_DP<2>")
	)
	(segment
		(start 52.157884 -303.859184)
		(end 51.884072 -303.585372)
		(width 0.16002)
		(layer "In13.Cu")
		(net "M_B_CPU1_SB_DQS_DP<2>")
	)
	(segment
		(start 64.235076 -298.801282)
		(end 64.44615 -299.012356)
		(width 0.16002)
		(layer "In13.Cu")
		(net "M_B_CPU1_SB_DQS_DP<2>")
	)
	(segment
		(start 65.608708 -296.900092)
		(end 65.608708 -297.42765)
		(width 0.16002)
		(layer "In13.Cu")
		(net "M_B_CPU1_SB_DQS_DP<2>")
	)
	(arc
		(start 80.771238 -285.75635)
		(mid 80.586206 -285.802264)
		(end 80.40243 -285.751524)
		(width 0.09525)
		(layer "In13.Cu")
		(net "M_B_CPU1_SB_DQS_DP<2>")
	)
	(arc
		(start 79.77505 -285.788862)
		(mid 79.613025 -285.80779)
		(end 79.457804 -285.75762)
		(width 0.09525)
		(layer "In13.Cu")
		(net "M_B_CPU1_SB_DQS_DP<2>")
	)
	(arc
		(start 82.282538 -285.751524)
		(mid 82.001106 -285.675769)
		(end 81.719674 -285.751524)
		(width 0.09525)
		(layer "In13.Cu")
		(net "M_B_CPU1_SB_DQS_DP<2>")
	)
	(arc
		(start 87.856314 -285.718504)
		(mid 87.846066 -285.714341)
		(end 87.83574 -285.710376)
		(width 0.09525)
		(layer "In13.Cu")
		(net "M_B_CPU1_SB_DQS_DP<2>")
	)
	(arc
		(start 81.719674 -285.751524)
		(mid 81.535899 -285.802296)
		(end 81.350866 -285.75635)
		(width 0.09525)
		(layer "In13.Cu")
		(net "M_B_CPU1_SB_DQS_DP<2>")
	)
	(arc
		(start 84.162392 -285.751524)
		(mid 83.88096 -285.675769)
		(end 83.599528 -285.751524)
		(width 0.09525)
		(layer "In13.Cu")
		(net "M_B_CPU1_SB_DQS_DP<2>")
	)
	(arc
		(start 80.392016 -285.745428)
		(mid 80.114854 -285.675628)
		(end 79.839312 -285.751524)
		(width 0.09525)
		(layer "In13.Cu")
		(net "M_B_CPU1_SB_DQS_DP<2>")
	)
	(arc
		(start 84.5312 -285.75635)
		(mid 84.346168 -285.802264)
		(end 84.162392 -285.751524)
		(width 0.09525)
		(layer "In13.Cu")
		(net "M_B_CPU1_SB_DQS_DP<2>")
	)
	(arc
		(start 79.457804 -285.75762)
		(mid 79.212409 -285.681812)
		(end 78.958694 -285.721806)
		(width 0.09525)
		(layer "In13.Cu")
		(net "M_B_CPU1_SB_DQS_DP<2>")
	)
	(arc
		(start 82.659474 -285.751524)
		(mid 82.471006 -285.802201)
		(end 82.282538 -285.751524)
		(width 0.09525)
		(layer "In13.Cu")
		(net "M_B_CPU1_SB_DQS_DP<2>")
	)
	(arc
		(start 83.222338 -285.751524)
		(mid 82.940906 -285.675769)
		(end 82.659474 -285.751524)
		(width 0.09525)
		(layer "In13.Cu")
		(net "M_B_CPU1_SB_DQS_DP<2>")
	)
	(arc
		(start 81.342484 -285.751524)
		(mid 81.061052 -285.675769)
		(end 80.77962 -285.751524)
		(width 0.09525)
		(layer "In13.Cu")
		(net "M_B_CPU1_SB_DQS_DP<2>")
	)
	(arc
		(start 87.83574 -285.710376)
		(mid 87.592998 -285.677606)
		(end 87.35949 -285.751524)
		(width 0.09525)
		(layer "In13.Cu")
		(net "M_B_CPU1_SB_DQS_DP<2>")
	)
	(arc
		(start 85.102446 -285.751524)
		(mid 84.821014 -285.675769)
		(end 84.539582 -285.751524)
		(width 0.09525)
		(layer "In13.Cu")
		(net "M_B_CPU1_SB_DQS_DP<2>")
	)
	(arc
		(start 85.479636 -285.751524)
		(mid 85.295861 -285.802296)
		(end 85.110828 -285.75635)
		(width 0.09525)
		(layer "In13.Cu")
		(net "M_B_CPU1_SB_DQS_DP<2>")
	)
	(arc
		(start 86.0425 -285.751524)
		(mid 85.761068 -285.675769)
		(end 85.479636 -285.751524)
		(width 0.09525)
		(layer "In13.Cu")
		(net "M_B_CPU1_SB_DQS_DP<2>")
	)
	(arc
		(start 83.591146 -285.75635)
		(mid 83.406114 -285.802264)
		(end 83.222338 -285.751524)
		(width 0.09525)
		(layer "In13.Cu")
		(net "M_B_CPU1_SB_DQS_DP<2>")
	)
	(arc
		(start 87.35949 -285.751524)
		(mid 87.171022 -285.802201)
		(end 86.982554 -285.751524)
		(width 0.09525)
		(layer "In13.Cu")
		(net "M_B_CPU1_SB_DQS_DP<2>")
	)
	(arc
		(start 86.41969 -285.751524)
		(mid 86.235915 -285.802296)
		(end 86.050882 -285.75635)
		(width 0.09525)
		(layer "In13.Cu")
		(net "M_B_CPU1_SB_DQS_DP<2>")
	)
	(arc
		(start 86.982554 -285.751524)
		(mid 86.701122 -285.675769)
		(end 86.41969 -285.751524)
		(width 0.09525)
		(layer "In13.Cu")
		(net "M_B_CPU1_SB_DQS_DP<2>")
	)
	(segment
		(start 88.577928 -280.30043)
		(end 88.111076 -280.566368)
		(width 0.12954)
		(layer "F.Cu")
		(net "M_B_CPU1_SB_DQS_DP<1>")
	)
	(segment
		(start 71.836788 -281.435048)
		(end 71.463154 -281.808682)
		(width 0.16002)
		(layer "In13.Cu")
		(net "M_B_CPU1_SB_DQS_DP<1>")
	)
	(segment
		(start 67.325494 -287.108646)
		(end 67.048634 -287.108646)
		(width 0.16002)
		(layer "In13.Cu")
		(net "M_B_CPU1_SB_DQS_DP<1>")
	)
	(segment
		(start 70.463156 -282.80868)
		(end 70.089522 -283.182314)
		(width 0.16002)
		(layer "In13.Cu")
		(net "M_B_CPU1_SB_DQS_DP<1>")
	)
	(segment
		(start 66.147696 -288.286444)
		(end 60.612782 -293.821358)
		(width 0.16002)
		(layer "In13.Cu")
		(net "M_B_CPU1_SB_DQS_DP<1>")
	)
	(segment
		(start 84.539582 -280.891488)
		(end 84.5312 -280.896314)
		(width 0.09525)
		(layer "In13.Cu")
		(net "M_B_CPU1_SB_DQS_DP<1>")
	)
	(segment
		(start 71.463154 -282.335986)
		(end 71.642224 -282.515056)
		(width 0.16002)
		(layer "In13.Cu")
		(net "M_B_CPU1_SB_DQS_DP<1>")
	)
	(segment
		(start 78.444344 -280.87066)
		(end 77.257402 -280.55443)
		(width 0.09525)
		(layer "In13.Cu")
		(net "M_B_CPU1_SB_DQS_DP<1>")
	)
	(segment
		(start 65.968626 -287.830514)
		(end 66.147696 -288.009584)
		(width 0.16002)
		(layer "In13.Cu")
		(net "M_B_CPU1_SB_DQS_DP<1>")
	)
	(segment
		(start 78.909672 -280.885392)
		(end 78.899258 -280.891488)
		(width 0.09525)
		(layer "In13.Cu")
		(net "M_B_CPU1_SB_DQS_DP<1>")
	)
	(segment
		(start 71.44639 -282.98775)
		(end 71.16953 -282.98775)
		(width 0.16002)
		(layer "In13.Cu")
		(net "M_B_CPU1_SB_DQS_DP<1>")
	)
	(segment
		(start 76.782168 -280.535888)
		(end 76.478638 -280.839418)
		(width 0.09525)
		(layer "In13.Cu")
		(net "M_B_CPU1_SB_DQS_DP<1>")
	)
	(segment
		(start 68.89496 -285.26232)
		(end 68.89496 -285.53918)
		(width 0.16002)
		(layer "In13.Cu")
		(net "M_B_CPU1_SB_DQS_DP<1>")
	)
	(segment
		(start 71.642224 -282.515056)
		(end 71.642224 -282.791916)
		(width 0.16002)
		(layer "In13.Cu")
		(net "M_B_CPU1_SB_DQS_DP<1>")
	)
	(segment
		(start 87.957152 -280.831798)
		(end 87.856314 -280.858468)
		(width 0.09525)
		(layer "In13.Cu")
		(net "M_B_CPU1_SB_DQS_DP<1>")
	)
	(segment
		(start 78.886304 -280.898854)
		(end 78.88478 -280.89987)
		(width 0.09525)
		(layer "In13.Cu")
		(net "M_B_CPU1_SB_DQS_DP<1>")
	)
	(segment
		(start 71.16953 -282.98775)
		(end 70.99046 -282.80868)
		(width 0.16002)
		(layer "In13.Cu")
		(net "M_B_CPU1_SB_DQS_DP<1>")
	)
	(segment
		(start 78.88478 -280.89987)
		(end 78.885034 -280.900378)
		(width 0.09525)
		(layer "In13.Cu")
		(net "M_B_CPU1_SB_DQS_DP<1>")
	)
	(segment
		(start 72.364092 -281.435048)
		(end 71.836788 -281.435048)
		(width 0.16002)
		(layer "In13.Cu")
		(net "M_B_CPU1_SB_DQS_DP<1>")
	)
	(segment
		(start 70.089522 -283.182314)
		(end 70.089522 -283.709618)
		(width 0.16002)
		(layer "In13.Cu")
		(net "M_B_CPU1_SB_DQS_DP<1>")
	)
	(segment
		(start 80.77962 -280.891488)
		(end 80.771238 -280.896314)
		(width 0.09525)
		(layer "In13.Cu")
		(net "M_B_CPU1_SB_DQS_DP<1>")
	)
	(segment
		(start 68.699126 -285.735014)
		(end 68.422266 -285.735014)
		(width 0.16002)
		(layer "In13.Cu")
		(net "M_B_CPU1_SB_DQS_DP<1>")
	)
	(segment
		(start 83.599528 -280.891488)
		(end 83.591146 -280.896314)
		(width 0.09525)
		(layer "In13.Cu")
		(net "M_B_CPU1_SB_DQS_DP<1>")
	)
	(segment
		(start 67.048634 -287.108646)
		(end 66.869564 -286.929576)
		(width 0.16002)
		(layer "In13.Cu")
		(net "M_B_CPU1_SB_DQS_DP<1>")
	)
	(segment
		(start 76.214478 -280.839418)
		(end 76.155296 -280.780236)
		(width 0.09525)
		(layer "In13.Cu")
		(net "M_B_CPU1_SB_DQS_DP<1>")
	)
	(segment
		(start 72.543162 -281.614118)
		(end 72.364092 -281.435048)
		(width 0.16002)
		(layer "In13.Cu")
		(net "M_B_CPU1_SB_DQS_DP<1>")
	)
	(segment
		(start 86.050882 -280.896314)
		(end 86.0425 -280.891488)
		(width 0.09525)
		(layer "In13.Cu")
		(net "M_B_CPU1_SB_DQS_DP<1>")
	)
	(segment
		(start 52.15255 -294.503856)
		(end 51.884072 -294.235378)
		(width 0.16002)
		(layer "In13.Cu")
		(net "M_B_CPU1_SB_DQS_DP<1>")
	)
	(segment
		(start 80.40243 -280.891488)
		(end 80.392016 -280.885392)
		(width 0.09525)
		(layer "In13.Cu")
		(net "M_B_CPU1_SB_DQS_DP<1>")
	)
	(segment
		(start 68.71589 -284.555946)
		(end 68.71589 -285.08325)
		(width 0.16002)
		(layer "In13.Cu")
		(net "M_B_CPU1_SB_DQS_DP<1>")
	)
	(segment
		(start 70.072758 -284.361382)
		(end 69.795898 -284.361382)
		(width 0.16002)
		(layer "In13.Cu")
		(net "M_B_CPU1_SB_DQS_DP<1>")
	)
	(segment
		(start 66.147696 -288.009584)
		(end 66.147696 -288.286444)
		(width 0.16002)
		(layer "In13.Cu")
		(net "M_B_CPU1_SB_DQS_DP<1>")
	)
	(segment
		(start 66.869564 -286.929576)
		(end 66.34226 -286.929576)
		(width 0.16002)
		(layer "In13.Cu")
		(net "M_B_CPU1_SB_DQS_DP<1>")
	)
	(segment
		(start 77.115924 -280.535888)
		(end 76.782168 -280.535888)
		(width 0.09525)
		(layer "In13.Cu")
		(net "M_B_CPU1_SB_DQS_DP<1>")
	)
	(segment
		(start 76.478638 -280.839418)
		(end 76.214478 -280.839418)
		(width 0.09525)
		(layer "In13.Cu")
		(net "M_B_CPU1_SB_DQS_DP<1>")
	)
	(segment
		(start 70.268592 -283.888688)
		(end 70.268592 -284.165548)
		(width 0.16002)
		(layer "In13.Cu")
		(net "M_B_CPU1_SB_DQS_DP<1>")
	)
	(segment
		(start 68.243196 -285.555944)
		(end 67.715892 -285.555944)
		(width 0.16002)
		(layer "In13.Cu")
		(net "M_B_CPU1_SB_DQS_DP<1>")
	)
	(segment
		(start 67.342258 -285.929578)
		(end 67.342258 -286.456882)
		(width 0.16002)
		(layer "In13.Cu")
		(net "M_B_CPU1_SB_DQS_DP<1>")
	)
	(segment
		(start 68.422266 -285.735014)
		(end 68.243196 -285.555944)
		(width 0.16002)
		(layer "In13.Cu")
		(net "M_B_CPU1_SB_DQS_DP<1>")
	)
	(segment
		(start 70.99046 -282.80868)
		(end 70.463156 -282.80868)
		(width 0.16002)
		(layer "In13.Cu")
		(net "M_B_CPU1_SB_DQS_DP<1>")
	)
	(segment
		(start 67.715892 -285.555944)
		(end 67.342258 -285.929578)
		(width 0.16002)
		(layer "In13.Cu")
		(net "M_B_CPU1_SB_DQS_DP<1>")
	)
	(segment
		(start 69.616828 -284.182312)
		(end 69.089524 -284.182312)
		(width 0.16002)
		(layer "In13.Cu")
		(net "M_B_CPU1_SB_DQS_DP<1>")
	)
	(segment
		(start 69.089524 -284.182312)
		(end 68.71589 -284.555946)
		(width 0.16002)
		(layer "In13.Cu")
		(net "M_B_CPU1_SB_DQS_DP<1>")
	)
	(segment
		(start 81.350866 -280.896314)
		(end 81.342484 -280.891488)
		(width 0.09525)
		(layer "In13.Cu")
		(net "M_B_CPU1_SB_DQS_DP<1>")
	)
	(segment
		(start 76.155296 -280.780236)
		(end 76.131674 -280.780236)
		(width 0.09525)
		(layer "In13.Cu")
		(net "M_B_CPU1_SB_DQS_DP<1>")
	)
	(segment
		(start 69.795898 -284.361382)
		(end 69.616828 -284.182312)
		(width 0.16002)
		(layer "In13.Cu")
		(net "M_B_CPU1_SB_DQS_DP<1>")
	)
	(segment
		(start 70.089522 -283.709618)
		(end 70.268592 -283.888688)
		(width 0.16002)
		(layer "In13.Cu")
		(net "M_B_CPU1_SB_DQS_DP<1>")
	)
	(segment
		(start 76.131674 -280.780236)
		(end 73.653904 -280.780236)
		(width 0.16002)
		(layer "In13.Cu")
		(net "M_B_CPU1_SB_DQS_DP<1>")
	)
	(segment
		(start 88.111076 -280.566368)
		(end 87.957152 -280.831798)
		(width 0.09525)
		(layer "In13.Cu")
		(net "M_B_CPU1_SB_DQS_DP<1>")
	)
	(segment
		(start 54.280562 -294.684958)
		(end 54.09946 -294.503856)
		(width 0.16002)
		(layer "In13.Cu")
		(net "M_B_CPU1_SB_DQS_DP<1>")
	)
	(segment
		(start 71.642224 -282.791916)
		(end 71.44639 -282.98775)
		(width 0.16002)
		(layer "In13.Cu")
		(net "M_B_CPU1_SB_DQS_DP<1>")
	)
	(segment
		(start 72.820022 -281.614118)
		(end 72.543162 -281.614118)
		(width 0.16002)
		(layer "In13.Cu")
		(net "M_B_CPU1_SB_DQS_DP<1>")
	)
	(segment
		(start 65.968626 -287.30321)
		(end 65.968626 -287.830514)
		(width 0.16002)
		(layer "In13.Cu")
		(net "M_B_CPU1_SB_DQS_DP<1>")
	)
	(segment
		(start 67.521328 -286.912812)
		(end 67.325494 -287.108646)
		(width 0.16002)
		(layer "In13.Cu")
		(net "M_B_CPU1_SB_DQS_DP<1>")
	)
	(segment
		(start 68.89496 -285.53918)
		(end 68.699126 -285.735014)
		(width 0.16002)
		(layer "In13.Cu")
		(net "M_B_CPU1_SB_DQS_DP<1>")
	)
	(segment
		(start 73.653904 -280.780236)
		(end 72.820022 -281.614118)
		(width 0.16002)
		(layer "In13.Cu")
		(net "M_B_CPU1_SB_DQS_DP<1>")
	)
	(segment
		(start 60.612782 -293.821358)
		(end 57.749186 -293.821358)
		(width 0.16002)
		(layer "In13.Cu")
		(net "M_B_CPU1_SB_DQS_DP<1>")
	)
	(segment
		(start 54.09946 -294.503856)
		(end 52.15255 -294.503856)
		(width 0.16002)
		(layer "In13.Cu")
		(net "M_B_CPU1_SB_DQS_DP<1>")
	)
	(segment
		(start 66.34226 -286.929576)
		(end 65.968626 -287.30321)
		(width 0.16002)
		(layer "In13.Cu")
		(net "M_B_CPU1_SB_DQS_DP<1>")
	)
	(segment
		(start 71.463154 -281.808682)
		(end 71.463154 -282.335986)
		(width 0.16002)
		(layer "In13.Cu")
		(net "M_B_CPU1_SB_DQS_DP<1>")
	)
	(segment
		(start 78.899258 -280.891488)
		(end 78.886304 -280.898854)
		(width 0.09525)
		(layer "In13.Cu")
		(net "M_B_CPU1_SB_DQS_DP<1>")
	)
	(segment
		(start 67.521328 -286.635952)
		(end 67.521328 -286.912812)
		(width 0.16002)
		(layer "In13.Cu")
		(net "M_B_CPU1_SB_DQS_DP<1>")
	)
	(segment
		(start 85.110828 -280.896314)
		(end 85.102446 -280.891488)
		(width 0.09525)
		(layer "In13.Cu")
		(net "M_B_CPU1_SB_DQS_DP<1>")
	)
	(segment
		(start 57.749186 -293.821358)
		(end 56.885586 -294.684958)
		(width 0.16002)
		(layer "In13.Cu")
		(net "M_B_CPU1_SB_DQS_DP<1>")
	)
	(segment
		(start 56.885586 -294.684958)
		(end 54.280562 -294.684958)
		(width 0.16002)
		(layer "In13.Cu")
		(net "M_B_CPU1_SB_DQS_DP<1>")
	)
	(segment
		(start 70.268592 -284.165548)
		(end 70.072758 -284.361382)
		(width 0.16002)
		(layer "In13.Cu")
		(net "M_B_CPU1_SB_DQS_DP<1>")
	)
	(segment
		(start 68.71589 -285.08325)
		(end 68.89496 -285.26232)
		(width 0.16002)
		(layer "In13.Cu")
		(net "M_B_CPU1_SB_DQS_DP<1>")
	)
	(segment
		(start 67.342258 -286.456882)
		(end 67.521328 -286.635952)
		(width 0.16002)
		(layer "In13.Cu")
		(net "M_B_CPU1_SB_DQS_DP<1>")
	)
	(arc
		(start 87.83574 -280.85034)
		(mid 87.592998 -280.81757)
		(end 87.35949 -280.891488)
		(width 0.09525)
		(layer "In13.Cu")
		(net "M_B_CPU1_SB_DQS_DP<1>")
	)
	(arc
		(start 78.885034 -280.900378)
		(mid 78.723879 -280.942759)
		(end 78.560168 -280.911554)
		(width 0.09525)
		(layer "In13.Cu")
		(net "M_B_CPU1_SB_DQS_DP<1>")
	)
	(arc
		(start 84.5312 -280.896314)
		(mid 84.346168 -280.942228)
		(end 84.162392 -280.891488)
		(width 0.09525)
		(layer "In13.Cu")
		(net "M_B_CPU1_SB_DQS_DP<1>")
	)
	(arc
		(start 82.282538 -280.891488)
		(mid 82.001106 -280.815733)
		(end 81.719674 -280.891488)
		(width 0.09525)
		(layer "In13.Cu")
		(net "M_B_CPU1_SB_DQS_DP<1>")
	)
	(arc
		(start 86.982554 -280.891488)
		(mid 86.701122 -280.815733)
		(end 86.41969 -280.891488)
		(width 0.09525)
		(layer "In13.Cu")
		(net "M_B_CPU1_SB_DQS_DP<1>")
	)
	(arc
		(start 87.35949 -280.891488)
		(mid 87.171022 -280.942165)
		(end 86.982554 -280.891488)
		(width 0.09525)
		(layer "In13.Cu")
		(net "M_B_CPU1_SB_DQS_DP<1>")
	)
	(arc
		(start 77.257402 -280.55443)
		(mid 77.187267 -280.540559)
		(end 77.115924 -280.535888)
		(width 0.09525)
		(layer "In13.Cu")
		(net "M_B_CPU1_SB_DQS_DP<1>")
	)
	(arc
		(start 83.591146 -280.896314)
		(mid 83.406114 -280.942228)
		(end 83.222338 -280.891488)
		(width 0.09525)
		(layer "In13.Cu")
		(net "M_B_CPU1_SB_DQS_DP<1>")
	)
	(arc
		(start 81.719674 -280.891488)
		(mid 81.535899 -280.94226)
		(end 81.350866 -280.896314)
		(width 0.09525)
		(layer "In13.Cu")
		(net "M_B_CPU1_SB_DQS_DP<1>")
	)
	(arc
		(start 84.162392 -280.891488)
		(mid 83.88096 -280.815733)
		(end 83.599528 -280.891488)
		(width 0.09525)
		(layer "In13.Cu")
		(net "M_B_CPU1_SB_DQS_DP<1>")
	)
	(arc
		(start 86.41969 -280.891488)
		(mid 86.235915 -280.94226)
		(end 86.050882 -280.896314)
		(width 0.09525)
		(layer "In13.Cu")
		(net "M_B_CPU1_SB_DQS_DP<1>")
	)
	(arc
		(start 78.560168 -280.911554)
		(mid 78.503026 -280.888926)
		(end 78.444344 -280.87066)
		(width 0.09525)
		(layer "In13.Cu")
		(net "M_B_CPU1_SB_DQS_DP<1>")
	)
	(arc
		(start 87.856314 -280.858468)
		(mid 87.846066 -280.854305)
		(end 87.83574 -280.85034)
		(width 0.09525)
		(layer "In13.Cu")
		(net "M_B_CPU1_SB_DQS_DP<1>")
	)
	(arc
		(start 79.839312 -280.891488)
		(mid 79.65059 -280.942292)
		(end 79.461868 -280.891488)
		(width 0.09525)
		(layer "In13.Cu")
		(net "M_B_CPU1_SB_DQS_DP<1>")
	)
	(arc
		(start 85.102446 -280.891488)
		(mid 84.821014 -280.815733)
		(end 84.539582 -280.891488)
		(width 0.09525)
		(layer "In13.Cu")
		(net "M_B_CPU1_SB_DQS_DP<1>")
	)
	(arc
		(start 80.392016 -280.885392)
		(mid 80.114854 -280.815592)
		(end 79.839312 -280.891488)
		(width 0.09525)
		(layer "In13.Cu")
		(net "M_B_CPU1_SB_DQS_DP<1>")
	)
	(arc
		(start 81.342484 -280.891488)
		(mid 81.061052 -280.815733)
		(end 80.77962 -280.891488)
		(width 0.09525)
		(layer "In13.Cu")
		(net "M_B_CPU1_SB_DQS_DP<1>")
	)
	(arc
		(start 85.479636 -280.891488)
		(mid 85.295861 -280.94226)
		(end 85.110828 -280.896314)
		(width 0.09525)
		(layer "In13.Cu")
		(net "M_B_CPU1_SB_DQS_DP<1>")
	)
	(arc
		(start 79.461868 -280.891488)
		(mid 79.186579 -280.815767)
		(end 78.909672 -280.885392)
		(width 0.09525)
		(layer "In13.Cu")
		(net "M_B_CPU1_SB_DQS_DP<1>")
	)
	(arc
		(start 82.659474 -280.891488)
		(mid 82.471006 -280.942165)
		(end 82.282538 -280.891488)
		(width 0.09525)
		(layer "In13.Cu")
		(net "M_B_CPU1_SB_DQS_DP<1>")
	)
	(arc
		(start 86.0425 -280.891488)
		(mid 85.761068 -280.815733)
		(end 85.479636 -280.891488)
		(width 0.09525)
		(layer "In13.Cu")
		(net "M_B_CPU1_SB_DQS_DP<1>")
	)
	(arc
		(start 80.771238 -280.896314)
		(mid 80.586206 -280.942228)
		(end 80.40243 -280.891488)
		(width 0.09525)
		(layer "In13.Cu")
		(net "M_B_CPU1_SB_DQS_DP<1>")
	)
	(arc
		(start 83.222338 -280.891488)
		(mid 82.940906 -280.815733)
		(end 82.659474 -280.891488)
		(width 0.09525)
		(layer "In13.Cu")
		(net "M_B_CPU1_SB_DQS_DP<1>")
	)
	(segment
		(start 88.577928 -275.440394)
		(end 88.111076 -275.706332)
		(width 0.12954)
		(layer "F.Cu")
		(net "M_B_CPU1_SB_DQS_DP<0>")
	)
	(segment
		(start 63.487808 -280.766266)
		(end 63.011304 -280.766266)
		(width 0.16002)
		(layer "In13.Cu")
		(net "M_B_CPU1_SB_DQS_DP<0>")
	)
	(segment
		(start 67.129914 -276.647656)
		(end 66.706496 -277.071074)
		(width 0.16002)
		(layer "In13.Cu")
		(net "M_B_CPU1_SB_DQS_DP<0>")
	)
	(segment
		(start 63.960756 -279.816814)
		(end 63.960756 -280.293318)
		(width 0.16002)
		(layer "In13.Cu")
		(net "M_B_CPU1_SB_DQS_DP<0>")
	)
	(segment
		(start 61.105542 -283.64942)
		(end 60.879482 -283.64942)
		(width 0.16002)
		(layer "In13.Cu")
		(net "M_B_CPU1_SB_DQS_DP<0>")
	)
	(segment
		(start 55.305198 -285.12897)
		(end 52.127658 -285.12897)
		(width 0.16002)
		(layer "In13.Cu")
		(net "M_B_CPU1_SB_DQS_DP<0>")
	)
	(segment
		(start 68.620386 -275.157184)
		(end 68.079366 -275.698204)
		(width 0.16002)
		(layer "In13.Cu")
		(net "M_B_CPU1_SB_DQS_DP<0>")
	)
	(segment
		(start 77.26934 -275.216366)
		(end 76.03871 -275.216366)
		(width 0.09525)
		(layer "In13.Cu")
		(net "M_B_CPU1_SB_DQS_DP<0>")
	)
	(segment
		(start 61.638434 -282.139136)
		(end 61.215016 -282.562554)
		(width 0.16002)
		(layer "In13.Cu")
		(net "M_B_CPU1_SB_DQS_DP<0>")
	)
	(segment
		(start 65.224152 -279.53081)
		(end 64.998092 -279.53081)
		(width 0.16002)
		(layer "In13.Cu")
		(net "M_B_CPU1_SB_DQS_DP<0>")
	)
	(segment
		(start 63.625222 -280.90368)
		(end 63.487808 -280.766266)
		(width 0.16002)
		(layer "In13.Cu")
		(net "M_B_CPU1_SB_DQS_DP<0>")
	)
	(segment
		(start 87.957152 -275.971762)
		(end 87.856314 -275.998432)
		(width 0.09525)
		(layer "In13.Cu")
		(net "M_B_CPU1_SB_DQS_DP<0>")
	)
	(segment
		(start 79.564484 -276.083014)
		(end 78.135988 -276.083014)
		(width 0.09525)
		(layer "In13.Cu")
		(net "M_B_CPU1_SB_DQS_DP<0>")
	)
	(segment
		(start 60.879482 -283.64942)
		(end 60.742068 -283.512006)
		(width 0.16002)
		(layer "In13.Cu")
		(net "M_B_CPU1_SB_DQS_DP<0>")
	)
	(segment
		(start 62.252352 -282.27655)
		(end 62.114938 -282.139136)
		(width 0.16002)
		(layer "In13.Cu")
		(net "M_B_CPU1_SB_DQS_DP<0>")
	)
	(segment
		(start 81.373726 -276.048216)
		(end 81.372456 -276.047708)
		(width 0.09525)
		(layer "In13.Cu")
		(net "M_B_CPU1_SB_DQS_DP<0>")
	)
	(segment
		(start 62.478412 -282.27655)
		(end 62.252352 -282.27655)
		(width 0.16002)
		(layer "In13.Cu")
		(net "M_B_CPU1_SB_DQS_DP<0>")
	)
	(segment
		(start 55.904892 -285.728664)
		(end 55.305198 -285.12897)
		(width 0.16002)
		(layer "In13.Cu")
		(net "M_B_CPU1_SB_DQS_DP<0>")
	)
	(segment
		(start 61.35243 -283.402532)
		(end 61.105542 -283.64942)
		(width 0.16002)
		(layer "In13.Cu")
		(net "M_B_CPU1_SB_DQS_DP<0>")
	)
	(segment
		(start 83.599528 -276.031452)
		(end 83.591146 -276.036278)
		(width 0.09525)
		(layer "In13.Cu")
		(net "M_B_CPU1_SB_DQS_DP<0>")
	)
	(segment
		(start 66.84391 -277.911052)
		(end 66.597022 -278.15794)
		(width 0.16002)
		(layer "In13.Cu")
		(net "M_B_CPU1_SB_DQS_DP<0>")
	)
	(segment
		(start 65.47104 -279.283922)
		(end 65.224152 -279.53081)
		(width 0.16002)
		(layer "In13.Cu")
		(net "M_B_CPU1_SB_DQS_DP<0>")
	)
	(segment
		(start 81.372456 -276.047708)
		(end 81.370678 -276.046692)
		(width 0.09525)
		(layer "In13.Cu")
		(net "M_B_CPU1_SB_DQS_DP<0>")
	)
	(segment
		(start 61.215016 -283.039058)
		(end 61.35243 -283.176472)
		(width 0.16002)
		(layer "In13.Cu")
		(net "M_B_CPU1_SB_DQS_DP<0>")
	)
	(segment
		(start 65.333626 -278.920448)
		(end 65.47104 -279.057862)
		(width 0.16002)
		(layer "In13.Cu")
		(net "M_B_CPU1_SB_DQS_DP<0>")
	)
	(segment
		(start 66.597022 -278.15794)
		(end 66.370962 -278.15794)
		(width 0.16002)
		(layer "In13.Cu")
		(net "M_B_CPU1_SB_DQS_DP<0>")
	)
	(segment
		(start 57.660286 -284.560264)
		(end 56.491886 -285.728664)
		(width 0.16002)
		(layer "In13.Cu")
		(net "M_B_CPU1_SB_DQS_DP<0>")
	)
	(segment
		(start 60.742068 -283.512006)
		(end 60.265564 -283.512006)
		(width 0.16002)
		(layer "In13.Cu")
		(net "M_B_CPU1_SB_DQS_DP<0>")
	)
	(segment
		(start 62.587886 -281.666188)
		(end 62.7253 -281.803602)
		(width 0.16002)
		(layer "In13.Cu")
		(net "M_B_CPU1_SB_DQS_DP<0>")
	)
	(segment
		(start 68.21678 -276.312122)
		(end 68.21678 -276.538182)
		(width 0.16002)
		(layer "In13.Cu")
		(net "M_B_CPU1_SB_DQS_DP<0>")
	)
	(segment
		(start 76.03871 -275.216366)
		(end 75.979528 -275.157184)
		(width 0.09525)
		(layer "In13.Cu")
		(net "M_B_CPU1_SB_DQS_DP<0>")
	)
	(segment
		(start 63.011304 -280.766266)
		(end 62.587886 -281.189684)
		(width 0.16002)
		(layer "In13.Cu")
		(net "M_B_CPU1_SB_DQS_DP<0>")
	)
	(segment
		(start 86.050882 -276.036278)
		(end 86.0425 -276.031452)
		(width 0.09525)
		(layer "In13.Cu")
		(net "M_B_CPU1_SB_DQS_DP<0>")
	)
	(segment
		(start 62.587886 -281.189684)
		(end 62.587886 -281.666188)
		(width 0.16002)
		(layer "In13.Cu")
		(net "M_B_CPU1_SB_DQS_DP<0>")
	)
	(segment
		(start 64.384174 -279.393396)
		(end 63.960756 -279.816814)
		(width 0.16002)
		(layer "In13.Cu")
		(net "M_B_CPU1_SB_DQS_DP<0>")
	)
	(segment
		(start 64.998092 -279.53081)
		(end 64.860678 -279.393396)
		(width 0.16002)
		(layer "In13.Cu")
		(net "M_B_CPU1_SB_DQS_DP<0>")
	)
	(segment
		(start 68.079366 -276.174708)
		(end 68.21678 -276.312122)
		(width 0.16002)
		(layer "In13.Cu")
		(net "M_B_CPU1_SB_DQS_DP<0>")
	)
	(segment
		(start 85.110828 -276.036278)
		(end 85.102446 -276.031452)
		(width 0.09525)
		(layer "In13.Cu")
		(net "M_B_CPU1_SB_DQS_DP<0>")
	)
	(segment
		(start 64.860678 -279.393396)
		(end 64.384174 -279.393396)
		(width 0.16002)
		(layer "In13.Cu")
		(net "M_B_CPU1_SB_DQS_DP<0>")
	)
	(segment
		(start 65.333626 -278.443944)
		(end 65.333626 -278.920448)
		(width 0.16002)
		(layer "In13.Cu")
		(net "M_B_CPU1_SB_DQS_DP<0>")
	)
	(segment
		(start 66.706496 -277.071074)
		(end 66.706496 -277.547578)
		(width 0.16002)
		(layer "In13.Cu")
		(net "M_B_CPU1_SB_DQS_DP<0>")
	)
	(segment
		(start 66.233548 -278.020526)
		(end 65.757044 -278.020526)
		(width 0.16002)
		(layer "In13.Cu")
		(net "M_B_CPU1_SB_DQS_DP<0>")
	)
	(segment
		(start 62.7253 -282.029662)
		(end 62.478412 -282.27655)
		(width 0.16002)
		(layer "In13.Cu")
		(net "M_B_CPU1_SB_DQS_DP<0>")
	)
	(segment
		(start 65.757044 -278.020526)
		(end 65.333626 -278.443944)
		(width 0.16002)
		(layer "In13.Cu")
		(net "M_B_CPU1_SB_DQS_DP<0>")
	)
	(segment
		(start 84.539582 -276.031452)
		(end 84.5312 -276.036278)
		(width 0.09525)
		(layer "In13.Cu")
		(net "M_B_CPU1_SB_DQS_DP<0>")
	)
	(segment
		(start 56.491886 -285.728664)
		(end 55.904892 -285.728664)
		(width 0.16002)
		(layer "In13.Cu")
		(net "M_B_CPU1_SB_DQS_DP<0>")
	)
	(segment
		(start 75.979528 -275.157184)
		(end 75.955906 -275.157184)
		(width 0.09525)
		(layer "In13.Cu")
		(net "M_B_CPU1_SB_DQS_DP<0>")
	)
	(segment
		(start 64.09817 -280.430732)
		(end 64.09817 -280.656792)
		(width 0.16002)
		(layer "In13.Cu")
		(net "M_B_CPU1_SB_DQS_DP<0>")
	)
	(segment
		(start 80.785462 -276.024848)
		(end 80.783938 -276.025356)
		(width 0.09525)
		(layer "In13.Cu")
		(net "M_B_CPU1_SB_DQS_DP<0>")
	)
	(segment
		(start 68.079366 -275.698204)
		(end 68.079366 -276.174708)
		(width 0.16002)
		(layer "In13.Cu")
		(net "M_B_CPU1_SB_DQS_DP<0>")
	)
	(segment
		(start 61.215016 -282.562554)
		(end 61.215016 -283.039058)
		(width 0.16002)
		(layer "In13.Cu")
		(net "M_B_CPU1_SB_DQS_DP<0>")
	)
	(segment
		(start 75.955906 -275.157184)
		(end 68.620386 -275.157184)
		(width 0.16002)
		(layer "In13.Cu")
		(net "M_B_CPU1_SB_DQS_DP<0>")
	)
	(segment
		(start 66.706496 -277.547578)
		(end 66.84391 -277.684992)
		(width 0.16002)
		(layer "In13.Cu")
		(net "M_B_CPU1_SB_DQS_DP<0>")
	)
	(segment
		(start 66.370962 -278.15794)
		(end 66.233548 -278.020526)
		(width 0.16002)
		(layer "In13.Cu")
		(net "M_B_CPU1_SB_DQS_DP<0>")
	)
	(segment
		(start 67.606418 -276.647656)
		(end 67.129914 -276.647656)
		(width 0.16002)
		(layer "In13.Cu")
		(net "M_B_CPU1_SB_DQS_DP<0>")
	)
	(segment
		(start 66.84391 -277.684992)
		(end 66.84391 -277.911052)
		(width 0.16002)
		(layer "In13.Cu")
		(net "M_B_CPU1_SB_DQS_DP<0>")
	)
	(segment
		(start 59.217306 -284.560264)
		(end 57.660286 -284.560264)
		(width 0.16002)
		(layer "In13.Cu")
		(net "M_B_CPU1_SB_DQS_DP<0>")
	)
	(segment
		(start 67.969892 -276.78507)
		(end 67.743832 -276.78507)
		(width 0.16002)
		(layer "In13.Cu")
		(net "M_B_CPU1_SB_DQS_DP<0>")
	)
	(segment
		(start 62.114938 -282.139136)
		(end 61.638434 -282.139136)
		(width 0.16002)
		(layer "In13.Cu")
		(net "M_B_CPU1_SB_DQS_DP<0>")
	)
	(segment
		(start 68.21678 -276.538182)
		(end 67.969892 -276.78507)
		(width 0.16002)
		(layer "In13.Cu")
		(net "M_B_CPU1_SB_DQS_DP<0>")
	)
	(segment
		(start 63.960756 -280.293318)
		(end 64.09817 -280.430732)
		(width 0.16002)
		(layer "In13.Cu")
		(net "M_B_CPU1_SB_DQS_DP<0>")
	)
	(segment
		(start 61.35243 -283.176472)
		(end 61.35243 -283.402532)
		(width 0.16002)
		(layer "In13.Cu")
		(net "M_B_CPU1_SB_DQS_DP<0>")
	)
	(segment
		(start 52.127658 -285.12897)
		(end 51.884072 -284.885384)
		(width 0.16002)
		(layer "In13.Cu")
		(net "M_B_CPU1_SB_DQS_DP<0>")
	)
	(segment
		(start 63.851282 -280.90368)
		(end 63.625222 -280.90368)
		(width 0.16002)
		(layer "In13.Cu")
		(net "M_B_CPU1_SB_DQS_DP<0>")
	)
	(segment
		(start 64.09817 -280.656792)
		(end 63.851282 -280.90368)
		(width 0.16002)
		(layer "In13.Cu")
		(net "M_B_CPU1_SB_DQS_DP<0>")
	)
	(segment
		(start 88.111076 -275.706332)
		(end 87.957152 -275.971762)
		(width 0.09525)
		(layer "In13.Cu")
		(net "M_B_CPU1_SB_DQS_DP<0>")
	)
	(segment
		(start 60.265564 -283.512006)
		(end 59.217306 -284.560264)
		(width 0.16002)
		(layer "In13.Cu")
		(net "M_B_CPU1_SB_DQS_DP<0>")
	)
	(segment
		(start 62.7253 -281.803602)
		(end 62.7253 -282.029662)
		(width 0.16002)
		(layer "In13.Cu")
		(net "M_B_CPU1_SB_DQS_DP<0>")
	)
	(segment
		(start 78.135988 -276.083014)
		(end 77.26934 -275.216366)
		(width 0.09525)
		(layer "In13.Cu")
		(net "M_B_CPU1_SB_DQS_DP<0>")
	)
	(segment
		(start 65.47104 -279.057862)
		(end 65.47104 -279.283922)
		(width 0.16002)
		(layer "In13.Cu")
		(net "M_B_CPU1_SB_DQS_DP<0>")
	)
	(segment
		(start 67.743832 -276.78507)
		(end 67.606418 -276.647656)
		(width 0.16002)
		(layer "In13.Cu")
		(net "M_B_CPU1_SB_DQS_DP<0>")
	)
	(arc
		(start 82.282538 -276.031452)
		(mid 82.275957 -276.027979)
		(end 82.26933 -276.024594)
		(width 0.09525)
		(layer "In13.Cu")
		(net "M_B_CPU1_SB_DQS_DP<0>")
	)
	(arc
		(start 83.591146 -276.036278)
		(mid 83.406114 -276.082192)
		(end 83.222338 -276.031452)
		(width 0.09525)
		(layer "In13.Cu")
		(net "M_B_CPU1_SB_DQS_DP<0>")
	)
	(arc
		(start 85.102446 -276.031452)
		(mid 84.821014 -275.955697)
		(end 84.539582 -276.031452)
		(width 0.09525)
		(layer "In13.Cu")
		(net "M_B_CPU1_SB_DQS_DP<0>")
	)
	(arc
		(start 83.222338 -276.031452)
		(mid 82.940906 -275.955697)
		(end 82.659474 -276.031452)
		(width 0.09525)
		(layer "In13.Cu")
		(net "M_B_CPU1_SB_DQS_DP<0>")
	)
	(arc
		(start 87.35949 -276.031452)
		(mid 87.171022 -276.082129)
		(end 86.982554 -276.031452)
		(width 0.09525)
		(layer "In13.Cu")
		(net "M_B_CPU1_SB_DQS_DP<0>")
	)
	(arc
		(start 86.0425 -276.031452)
		(mid 85.761068 -275.955697)
		(end 85.479636 -276.031452)
		(width 0.09525)
		(layer "In13.Cu")
		(net "M_B_CPU1_SB_DQS_DP<0>")
	)
	(arc
		(start 82.26933 -276.024594)
		(mid 81.993684 -275.956123)
		(end 81.719928 -276.031706)
		(width 0.09525)
		(layer "In13.Cu")
		(net "M_B_CPU1_SB_DQS_DP<0>")
	)
	(arc
		(start 81.370678 -276.046692)
		(mid 81.080319 -275.9755)
		(end 80.785462 -276.024848)
		(width 0.09525)
		(layer "In13.Cu")
		(net "M_B_CPU1_SB_DQS_DP<0>")
	)
	(arc
		(start 84.5312 -276.036278)
		(mid 84.346168 -276.082192)
		(end 84.162392 -276.031452)
		(width 0.09525)
		(layer "In13.Cu")
		(net "M_B_CPU1_SB_DQS_DP<0>")
	)
	(arc
		(start 82.659474 -276.031452)
		(mid 82.471006 -276.082129)
		(end 82.282538 -276.031452)
		(width 0.09525)
		(layer "In13.Cu")
		(net "M_B_CPU1_SB_DQS_DP<0>")
	)
	(arc
		(start 79.840074 -276.029928)
		(mid 79.704803 -276.069577)
		(end 79.564484 -276.083014)
		(width 0.09525)
		(layer "In13.Cu")
		(net "M_B_CPU1_SB_DQS_DP<0>")
	)
	(arc
		(start 86.982554 -276.031452)
		(mid 86.701122 -275.955697)
		(end 86.41969 -276.031452)
		(width 0.09525)
		(layer "In13.Cu")
		(net "M_B_CPU1_SB_DQS_DP<0>")
	)
	(arc
		(start 81.719928 -276.031706)
		(mid 81.548844 -276.082178)
		(end 81.373726 -276.048216)
		(width 0.09525)
		(layer "In13.Cu")
		(net "M_B_CPU1_SB_DQS_DP<0>")
	)
	(arc
		(start 80.381602 -276.026118)
		(mid 80.110476 -275.97704)
		(end 79.840074 -276.029928)
		(width 0.09525)
		(layer "In13.Cu")
		(net "M_B_CPU1_SB_DQS_DP<0>")
	)
	(arc
		(start 84.162392 -276.031452)
		(mid 83.88096 -275.955697)
		(end 83.599528 -276.031452)
		(width 0.09525)
		(layer "In13.Cu")
		(net "M_B_CPU1_SB_DQS_DP<0>")
	)
	(arc
		(start 80.783938 -276.025356)
		(mid 80.582839 -276.063093)
		(end 80.381602 -276.026118)
		(width 0.09525)
		(layer "In13.Cu")
		(net "M_B_CPU1_SB_DQS_DP<0>")
	)
	(arc
		(start 85.479636 -276.031452)
		(mid 85.295861 -276.082224)
		(end 85.110828 -276.036278)
		(width 0.09525)
		(layer "In13.Cu")
		(net "M_B_CPU1_SB_DQS_DP<0>")
	)
	(arc
		(start 86.41969 -276.031452)
		(mid 86.235915 -276.082224)
		(end 86.050882 -276.036278)
		(width 0.09525)
		(layer "In13.Cu")
		(net "M_B_CPU1_SB_DQS_DP<0>")
	)
	(arc
		(start 87.856314 -275.998432)
		(mid 87.846066 -275.994269)
		(end 87.83574 -275.990304)
		(width 0.09525)
		(layer "In13.Cu")
		(net "M_B_CPU1_SB_DQS_DP<0>")
	)
	(arc
		(start 87.83574 -275.990304)
		(mid 87.592998 -275.957534)
		(end 87.35949 -276.031452)
		(width 0.09525)
		(layer "In13.Cu")
		(net "M_B_CPU1_SB_DQS_DP<0>")
	)
	(segment
		(start 88.107774 -271.390364)
		(end 87.640922 -271.656302)
		(width 0.12954)
		(layer "F.Cu")
		(net "M_B_CPU1_SB_DQS_DN<9>")
	)
	(segment
		(start 61.66612 -272.818606)
		(end 61.419232 -273.065494)
		(width 0.16002)
		(layer "In13.Cu")
		(net "M_B_CPU1_SB_DQS_DN<9>")
	)
	(segment
		(start 75.996546 -269.835884)
		(end 75.972924 -269.835884)
		(width 0.09525)
		(layer "In13.Cu")
		(net "M_B_CPU1_SB_DQS_DN<9>")
	)
	(segment
		(start 76.055474 -269.776956)
		(end 75.996546 -269.835884)
		(width 0.09525)
		(layer "In13.Cu")
		(net "M_B_CPU1_SB_DQS_DN<9>")
	)
	(segment
		(start 65.491106 -269.835884)
		(end 65.254124 -270.072866)
		(width 0.16002)
		(layer "In13.Cu")
		(net "M_B_CPU1_SB_DQS_DN<9>")
	)
	(segment
		(start 61.489082 -273.361404)
		(end 61.489082 -273.837908)
		(width 0.16002)
		(layer "In13.Cu")
		(net "M_B_CPU1_SB_DQS_DN<9>")
	)
	(segment
		(start 53.914294 -276.290024)
		(end 53.710078 -276.085808)
		(width 0.16002)
		(layer "In13.Cu")
		(net "M_B_CPU1_SB_DQS_DN<9>")
	)
	(segment
		(start 59.6519 -275.67509)
		(end 58.744866 -275.67509)
		(width 0.16002)
		(layer "In13.Cu")
		(net "M_B_CPU1_SB_DQS_DN<9>")
	)
	(segment
		(start 62.861952 -271.988534)
		(end 62.861952 -272.465038)
		(width 0.16002)
		(layer "In13.Cu")
		(net "M_B_CPU1_SB_DQS_DN<9>")
	)
	(segment
		(start 54.887114 -275.917152)
		(end 54.514242 -276.290024)
		(width 0.16002)
		(layer "In13.Cu")
		(net "M_B_CPU1_SB_DQS_DN<9>")
	)
	(segment
		(start 77.384656 -270.328136)
		(end 76.757022 -270.328136)
		(width 0.09525)
		(layer "In13.Cu")
		(net "M_B_CPU1_SB_DQS_DN<9>")
	)
	(segment
		(start 60.046362 -274.438364)
		(end 60.046362 -274.664424)
		(width 0.16002)
		(layer "In13.Cu")
		(net "M_B_CPU1_SB_DQS_DN<9>")
	)
	(segment
		(start 58.5216 -275.451824)
		(end 57.899808 -275.451824)
		(width 0.16002)
		(layer "In13.Cu")
		(net "M_B_CPU1_SB_DQS_DN<9>")
	)
	(segment
		(start 63.26505 -271.445736)
		(end 63.03899 -271.445736)
		(width 0.16002)
		(layer "In13.Cu")
		(net "M_B_CPU1_SB_DQS_DN<9>")
	)
	(segment
		(start 61.96203 -272.888456)
		(end 61.89218 -272.818606)
		(width 0.16002)
		(layer "In13.Cu")
		(net "M_B_CPU1_SB_DQS_DN<9>")
	)
	(segment
		(start 60.51931 -274.191476)
		(end 60.29325 -274.191476)
		(width 0.16002)
		(layer "In13.Cu")
		(net "M_B_CPU1_SB_DQS_DN<9>")
	)
	(segment
		(start 85.949536 -271.331182)
		(end 85.941154 -271.326356)
		(width 0.09525)
		(layer "In13.Cu")
		(net "M_B_CPU1_SB_DQS_DN<9>")
	)
	(segment
		(start 62.438534 -272.888456)
		(end 61.96203 -272.888456)
		(width 0.16002)
		(layer "In13.Cu")
		(net "M_B_CPU1_SB_DQS_DN<9>")
	)
	(segment
		(start 60.29325 -274.191476)
		(end 60.046362 -274.438364)
		(width 0.16002)
		(layer "In13.Cu")
		(net "M_B_CPU1_SB_DQS_DN<9>")
	)
	(segment
		(start 63.3349 -271.515586)
		(end 63.26505 -271.445736)
		(width 0.16002)
		(layer "In13.Cu")
		(net "M_B_CPU1_SB_DQS_DN<9>")
	)
	(segment
		(start 75.972924 -269.835884)
		(end 65.491106 -269.835884)
		(width 0.16002)
		(layer "In13.Cu")
		(net "M_B_CPU1_SB_DQS_DN<9>")
	)
	(segment
		(start 86.88959 -271.331182)
		(end 86.881208 -271.326356)
		(width 0.09525)
		(layer "In13.Cu")
		(net "M_B_CPU1_SB_DQS_DN<9>")
	)
	(segment
		(start 53.710078 -276.085808)
		(end 52.183538 -276.085808)
		(width 0.16002)
		(layer "In13.Cu")
		(net "M_B_CPU1_SB_DQS_DN<9>")
	)
	(segment
		(start 62.861952 -272.465038)
		(end 62.438534 -272.888456)
		(width 0.16002)
		(layer "In13.Cu")
		(net "M_B_CPU1_SB_DQS_DN<9>")
	)
	(segment
		(start 63.03899 -271.445736)
		(end 62.792102 -271.692624)
		(width 0.16002)
		(layer "In13.Cu")
		(net "M_B_CPU1_SB_DQS_DN<9>")
	)
	(segment
		(start 87.794846 -271.390872)
		(end 87.771478 -271.304004)
		(width 0.09525)
		(layer "In13.Cu")
		(net "M_B_CPU1_SB_DQS_DN<9>")
	)
	(segment
		(start 79.667608 -271.407128)
		(end 78.463648 -271.407128)
		(width 0.09525)
		(layer "In13.Cu")
		(net "M_B_CPU1_SB_DQS_DN<9>")
	)
	(segment
		(start 64.234822 -270.615664)
		(end 64.234822 -271.092168)
		(width 0.16002)
		(layer "In13.Cu")
		(net "M_B_CPU1_SB_DQS_DN<9>")
	)
	(segment
		(start 82.189574 -271.331182)
		(end 82.181192 -271.326356)
		(width 0.09525)
		(layer "In13.Cu")
		(net "M_B_CPU1_SB_DQS_DN<9>")
	)
	(segment
		(start 54.514242 -276.290024)
		(end 53.914294 -276.290024)
		(width 0.16002)
		(layer "In13.Cu")
		(net "M_B_CPU1_SB_DQS_DN<9>")
	)
	(segment
		(start 61.419232 -273.291554)
		(end 61.489082 -273.361404)
		(width 0.16002)
		(layer "In13.Cu")
		(net "M_B_CPU1_SB_DQS_DN<9>")
	)
	(segment
		(start 87.460836 -271.326356)
		(end 87.452454 -271.331182)
		(width 0.09525)
		(layer "In13.Cu")
		(net "M_B_CPU1_SB_DQS_DN<9>")
	)
	(segment
		(start 61.419232 -273.065494)
		(end 61.419232 -273.291554)
		(width 0.16002)
		(layer "In13.Cu")
		(net "M_B_CPU1_SB_DQS_DN<9>")
	)
	(segment
		(start 63.811404 -271.515586)
		(end 63.3349 -271.515586)
		(width 0.16002)
		(layer "In13.Cu")
		(net "M_B_CPU1_SB_DQS_DN<9>")
	)
	(segment
		(start 64.234822 -271.092168)
		(end 63.811404 -271.515586)
		(width 0.16002)
		(layer "In13.Cu")
		(net "M_B_CPU1_SB_DQS_DN<9>")
	)
	(segment
		(start 57.899808 -275.451824)
		(end 57.061608 -276.290024)
		(width 0.16002)
		(layer "In13.Cu")
		(net "M_B_CPU1_SB_DQS_DN<9>")
	)
	(segment
		(start 55.555388 -275.917152)
		(end 55.555388 -274.89912)
		(width 0.16002)
		(layer "In13.Cu")
		(net "M_B_CPU1_SB_DQS_DN<9>")
	)
	(segment
		(start 62.792102 -271.918684)
		(end 62.861952 -271.988534)
		(width 0.16002)
		(layer "In13.Cu")
		(net "M_B_CPU1_SB_DQS_DN<9>")
	)
	(segment
		(start 55.359554 -274.703286)
		(end 55.082948 -274.703286)
		(width 0.16002)
		(layer "In13.Cu")
		(net "M_B_CPU1_SB_DQS_DN<9>")
	)
	(segment
		(start 52.183538 -276.085808)
		(end 51.884072 -276.385274)
		(width 0.16002)
		(layer "In13.Cu")
		(net "M_B_CPU1_SB_DQS_DN<9>")
	)
	(segment
		(start 82.76082 -271.326356)
		(end 82.752438 -271.331182)
		(width 0.09525)
		(layer "In13.Cu")
		(net "M_B_CPU1_SB_DQS_DN<9>")
	)
	(segment
		(start 60.116212 -275.210778)
		(end 59.6519 -275.67509)
		(width 0.16002)
		(layer "In13.Cu")
		(net "M_B_CPU1_SB_DQS_DN<9>")
	)
	(segment
		(start 55.082948 -274.703286)
		(end 54.887114 -274.89912)
		(width 0.16002)
		(layer "In13.Cu")
		(net "M_B_CPU1_SB_DQS_DN<9>")
	)
	(segment
		(start 76.757022 -270.328136)
		(end 76.205842 -269.776956)
		(width 0.09525)
		(layer "In13.Cu")
		(net "M_B_CPU1_SB_DQS_DN<9>")
	)
	(segment
		(start 79.667862 -271.406874)
		(end 79.667608 -271.407128)
		(width 0.09525)
		(layer "In13.Cu")
		(net "M_B_CPU1_SB_DQS_DN<9>")
	)
	(segment
		(start 61.065664 -274.261326)
		(end 60.58916 -274.261326)
		(width 0.16002)
		(layer "In13.Cu")
		(net "M_B_CPU1_SB_DQS_DN<9>")
	)
	(segment
		(start 62.792102 -271.692624)
		(end 62.792102 -271.918684)
		(width 0.16002)
		(layer "In13.Cu")
		(net "M_B_CPU1_SB_DQS_DN<9>")
	)
	(segment
		(start 60.116212 -274.734274)
		(end 60.116212 -275.210778)
		(width 0.16002)
		(layer "In13.Cu")
		(net "M_B_CPU1_SB_DQS_DN<9>")
	)
	(segment
		(start 60.046362 -274.664424)
		(end 60.116212 -274.734274)
		(width 0.16002)
		(layer "In13.Cu")
		(net "M_B_CPU1_SB_DQS_DN<9>")
	)
	(segment
		(start 55.92826 -276.290024)
		(end 55.555388 -275.917152)
		(width 0.16002)
		(layer "In13.Cu")
		(net "M_B_CPU1_SB_DQS_DN<9>")
	)
	(segment
		(start 55.555388 -274.89912)
		(end 55.359554 -274.703286)
		(width 0.16002)
		(layer "In13.Cu")
		(net "M_B_CPU1_SB_DQS_DN<9>")
	)
	(segment
		(start 61.489082 -273.837908)
		(end 61.065664 -274.261326)
		(width 0.16002)
		(layer "In13.Cu")
		(net "M_B_CPU1_SB_DQS_DN<9>")
	)
	(segment
		(start 64.41186 -270.072866)
		(end 64.164972 -270.319754)
		(width 0.16002)
		(layer "In13.Cu")
		(net "M_B_CPU1_SB_DQS_DN<9>")
	)
	(segment
		(start 64.164972 -270.319754)
		(end 64.164972 -270.545814)
		(width 0.16002)
		(layer "In13.Cu")
		(net "M_B_CPU1_SB_DQS_DN<9>")
	)
	(segment
		(start 60.58916 -274.261326)
		(end 60.51931 -274.191476)
		(width 0.16002)
		(layer "In13.Cu")
		(net "M_B_CPU1_SB_DQS_DN<9>")
	)
	(segment
		(start 64.164972 -270.545814)
		(end 64.234822 -270.615664)
		(width 0.16002)
		(layer "In13.Cu")
		(net "M_B_CPU1_SB_DQS_DN<9>")
	)
	(segment
		(start 58.744866 -275.67509)
		(end 58.5216 -275.451824)
		(width 0.16002)
		(layer "In13.Cu")
		(net "M_B_CPU1_SB_DQS_DN<9>")
	)
	(segment
		(start 57.061608 -276.290024)
		(end 55.92826 -276.290024)
		(width 0.16002)
		(layer "In13.Cu")
		(net "M_B_CPU1_SB_DQS_DN<9>")
	)
	(segment
		(start 83.700874 -271.326356)
		(end 83.692492 -271.331182)
		(width 0.09525)
		(layer "In13.Cu")
		(net "M_B_CPU1_SB_DQS_DN<9>")
	)
	(segment
		(start 87.640922 -271.656302)
		(end 87.794846 -271.390872)
		(width 0.09525)
		(layer "In13.Cu")
		(net "M_B_CPU1_SB_DQS_DN<9>")
	)
	(segment
		(start 54.887114 -274.89912)
		(end 54.887114 -275.917152)
		(width 0.16002)
		(layer "In13.Cu")
		(net "M_B_CPU1_SB_DQS_DN<9>")
	)
	(segment
		(start 78.463648 -271.407128)
		(end 77.384656 -270.328136)
		(width 0.09525)
		(layer "In13.Cu")
		(net "M_B_CPU1_SB_DQS_DN<9>")
	)
	(segment
		(start 76.205842 -269.776956)
		(end 76.055474 -269.776956)
		(width 0.09525)
		(layer "In13.Cu")
		(net "M_B_CPU1_SB_DQS_DN<9>")
	)
	(segment
		(start 61.89218 -272.818606)
		(end 61.66612 -272.818606)
		(width 0.16002)
		(layer "In13.Cu")
		(net "M_B_CPU1_SB_DQS_DN<9>")
	)
	(segment
		(start 65.254124 -270.072866)
		(end 64.41186 -270.072866)
		(width 0.16002)
		(layer "In13.Cu")
		(net "M_B_CPU1_SB_DQS_DN<9>")
	)
	(arc
		(start 81.812384 -271.331182)
		(mid 81.530952 -271.406937)
		(end 81.24952 -271.331182)
		(width 0.09525)
		(layer "In13.Cu")
		(net "M_B_CPU1_SB_DQS_DN<9>")
	)
	(arc
		(start 83.129628 -271.331182)
		(mid 82.945853 -271.28041)
		(end 82.76082 -271.326356)
		(width 0.09525)
		(layer "In13.Cu")
		(net "M_B_CPU1_SB_DQS_DN<9>")
	)
	(arc
		(start 79.932276 -271.331182)
		(mid 79.804784 -271.385509)
		(end 79.667862 -271.406874)
		(width 0.09525)
		(layer "In13.Cu")
		(net "M_B_CPU1_SB_DQS_DN<9>")
	)
	(arc
		(start 80.872584 -271.331182)
		(mid 80.591152 -271.406937)
		(end 80.30972 -271.331182)
		(width 0.09525)
		(layer "In13.Cu")
		(net "M_B_CPU1_SB_DQS_DN<9>")
	)
	(arc
		(start 85.572346 -271.331182)
		(mid 85.290914 -271.406937)
		(end 85.009482 -271.331182)
		(width 0.09525)
		(layer "In13.Cu")
		(net "M_B_CPU1_SB_DQS_DN<9>")
	)
	(arc
		(start 85.941154 -271.326356)
		(mid 85.756122 -271.280442)
		(end 85.572346 -271.331182)
		(width 0.09525)
		(layer "In13.Cu")
		(net "M_B_CPU1_SB_DQS_DN<9>")
	)
	(arc
		(start 87.452454 -271.331182)
		(mid 87.171022 -271.406937)
		(end 86.88959 -271.331182)
		(width 0.09525)
		(layer "In13.Cu")
		(net "M_B_CPU1_SB_DQS_DN<9>")
	)
	(arc
		(start 82.752438 -271.331182)
		(mid 82.471006 -271.406937)
		(end 82.189574 -271.331182)
		(width 0.09525)
		(layer "In13.Cu")
		(net "M_B_CPU1_SB_DQS_DN<9>")
	)
	(arc
		(start 80.30972 -271.331182)
		(mid 80.120998 -271.280378)
		(end 79.932276 -271.331182)
		(width 0.09525)
		(layer "In13.Cu")
		(net "M_B_CPU1_SB_DQS_DN<9>")
	)
	(arc
		(start 86.881208 -271.326356)
		(mid 86.696176 -271.280442)
		(end 86.5124 -271.331182)
		(width 0.09525)
		(layer "In13.Cu")
		(net "M_B_CPU1_SB_DQS_DN<9>")
	)
	(arc
		(start 83.692492 -271.331182)
		(mid 83.41106 -271.406937)
		(end 83.129628 -271.331182)
		(width 0.09525)
		(layer "In13.Cu")
		(net "M_B_CPU1_SB_DQS_DN<9>")
	)
	(arc
		(start 84.069682 -271.331182)
		(mid 83.885907 -271.28041)
		(end 83.700874 -271.326356)
		(width 0.09525)
		(layer "In13.Cu")
		(net "M_B_CPU1_SB_DQS_DN<9>")
	)
	(arc
		(start 86.5124 -271.331182)
		(mid 86.230968 -271.406937)
		(end 85.949536 -271.331182)
		(width 0.09525)
		(layer "In13.Cu")
		(net "M_B_CPU1_SB_DQS_DN<9>")
	)
	(arc
		(start 87.771478 -271.304004)
		(mid 87.613728 -271.281485)
		(end 87.460836 -271.326356)
		(width 0.09525)
		(layer "In13.Cu")
		(net "M_B_CPU1_SB_DQS_DN<9>")
	)
	(arc
		(start 81.24952 -271.331182)
		(mid 81.061052 -271.280505)
		(end 80.872584 -271.331182)
		(width 0.09525)
		(layer "In13.Cu")
		(net "M_B_CPU1_SB_DQS_DN<9>")
	)
	(arc
		(start 85.009482 -271.331182)
		(mid 84.821014 -271.280505)
		(end 84.632546 -271.331182)
		(width 0.09525)
		(layer "In13.Cu")
		(net "M_B_CPU1_SB_DQS_DN<9>")
	)
	(arc
		(start 84.632546 -271.331182)
		(mid 84.351114 -271.406937)
		(end 84.069682 -271.331182)
		(width 0.09525)
		(layer "In13.Cu")
		(net "M_B_CPU1_SB_DQS_DN<9>")
	)
	(arc
		(start 82.181192 -271.326356)
		(mid 81.99616 -271.280442)
		(end 81.812384 -271.331182)
		(width 0.09525)
		(layer "In13.Cu")
		(net "M_B_CPU1_SB_DQS_DN<9>")
	)
	(segment
		(start 89.987882 -290.830254)
		(end 89.52103 -291.096192)
		(width 0.12954)
		(layer "F.Cu")
		(net "M_B_CPU1_SB_DQS_DN<8>")
	)
	(segment
		(start 51.365404 -314.441078)
		(end 51.364896 -314.440824)
		(width 0.16002)
		(layer "In13.Cu")
		(net "M_B_CPU1_SB_DQS_DN<8>")
	)
	(segment
		(start 85.949536 -291.421312)
		(end 85.941154 -291.426138)
		(width 0.09525)
		(layer "In13.Cu")
		(net "M_B_CPU1_SB_DQS_DN<8>")
	)
	(segment
		(start 71.0438 -303.833784)
		(end 62.231016 -312.646568)
		(width 0.16002)
		(layer "In13.Cu")
		(net "M_B_CPU1_SB_DQS_DN<8>")
	)
	(segment
		(start 77.54239 -294.407844)
		(end 77.54239 -295.017444)
		(width 0.09525)
		(layer "In13.Cu")
		(net "M_B_CPU1_SB_DQS_DN<8>")
	)
	(segment
		(start 79.680816 -291.47262)
		(end 78.844394 -292.309042)
		(width 0.09525)
		(layer "In13.Cu")
		(net "M_B_CPU1_SB_DQS_DN<8>")
	)
	(segment
		(start 78.844394 -292.309042)
		(end 77.706474 -294.012112)
		(width 0.09525)
		(layer "In13.Cu")
		(net "M_B_CPU1_SB_DQS_DN<8>")
	)
	(segment
		(start 50.814986 -313.880246)
		(end 48.418496 -313.880246)
		(width 0.16002)
		(layer "In13.Cu")
		(net "M_B_CPU1_SB_DQS_DN<8>")
	)
	(segment
		(start 55.50408 -314.570364)
		(end 55.38724 -314.687204)
		(width 0.16002)
		(layer "In13.Cu")
		(net "M_B_CPU1_SB_DQS_DN<8>")
	)
	(segment
		(start 57.717436 -313.895486)
		(end 56.925718 -314.687204)
		(width 0.16002)
		(layer "In13.Cu")
		(net "M_B_CPU1_SB_DQS_DN<8>")
	)
	(segment
		(start 87.460836 -291.426138)
		(end 87.452454 -291.421312)
		(width 0.09525)
		(layer "In13.Cu")
		(net "M_B_CPU1_SB_DQS_DN<8>")
	)
	(segment
		(start 77.54239 -295.017444)
		(end 77.244448 -295.31437)
		(width 0.09525)
		(layer "In13.Cu")
		(net "M_B_CPU1_SB_DQS_DN<8>")
	)
	(segment
		(start 86.88959 -291.421312)
		(end 86.881208 -291.426138)
		(width 0.09525)
		(layer "In13.Cu")
		(net "M_B_CPU1_SB_DQS_DN<8>")
	)
	(segment
		(start 77.706474 -294.012112)
		(end 77.54239 -294.407844)
		(width 0.09525)
		(layer "In13.Cu")
		(net "M_B_CPU1_SB_DQS_DN<8>")
	)
	(segment
		(start 59.216036 -313.895486)
		(end 57.717436 -313.895486)
		(width 0.16002)
		(layer "In13.Cu")
		(net "M_B_CPU1_SB_DQS_DN<8>")
	)
	(segment
		(start 89.52103 -291.096192)
		(end 89.367106 -291.361622)
		(width 0.09525)
		(layer "In13.Cu")
		(net "M_B_CPU1_SB_DQS_DN<8>")
	)
	(segment
		(start 55.38724 -314.687204)
		(end 51.606704 -314.687204)
		(width 0.16002)
		(layer "In13.Cu")
		(net "M_B_CPU1_SB_DQS_DN<8>")
	)
	(segment
		(start 80.120998 -291.47262)
		(end 79.680816 -291.47262)
		(width 0.09525)
		(layer "In13.Cu")
		(net "M_B_CPU1_SB_DQS_DN<8>")
	)
	(segment
		(start 48.260254 -314.038488)
		(end 48.037242 -314.038488)
		(width 0.16002)
		(layer "In13.Cu")
		(net "M_B_CPU1_SB_DQS_DN<8>")
	)
	(segment
		(start 82.189574 -291.421312)
		(end 82.181192 -291.426138)
		(width 0.09525)
		(layer "In13.Cu")
		(net "M_B_CPU1_SB_DQS_DN<8>")
	)
	(segment
		(start 77.244448 -295.31437)
		(end 77.161136 -295.314116)
		(width 0.09525)
		(layer "In13.Cu")
		(net "M_B_CPU1_SB_DQS_DN<8>")
	)
	(segment
		(start 89.367106 -291.361622)
		(end 89.266268 -291.388292)
		(width 0.09525)
		(layer "In13.Cu")
		(net "M_B_CPU1_SB_DQS_DN<8>")
	)
	(segment
		(start 74.35215 -298.123102)
		(end 74.35215 -299.322998)
		(width 0.16002)
		(layer "In13.Cu")
		(net "M_B_CPU1_SB_DQS_DN<8>")
	)
	(segment
		(start 77.144372 -295.33088)
		(end 74.35215 -298.123102)
		(width 0.16002)
		(layer "In13.Cu")
		(net "M_B_CPU1_SB_DQS_DN<8>")
	)
	(segment
		(start 77.161136 -295.314116)
		(end 77.144372 -295.33088)
		(width 0.09525)
		(layer "In13.Cu")
		(net "M_B_CPU1_SB_DQS_DN<8>")
	)
	(segment
		(start 82.76082 -291.426138)
		(end 82.752438 -291.421312)
		(width 0.09525)
		(layer "In13.Cu")
		(net "M_B_CPU1_SB_DQS_DN<8>")
	)
	(segment
		(start 83.700874 -291.426138)
		(end 83.692492 -291.421312)
		(width 0.09525)
		(layer "In13.Cu")
		(net "M_B_CPU1_SB_DQS_DN<8>")
	)
	(segment
		(start 51.364896 -314.440824)
		(end 50.814986 -313.880246)
		(width 0.16002)
		(layer "In13.Cu")
		(net "M_B_CPU1_SB_DQS_DN<8>")
	)
	(segment
		(start 55.98414 -314.570364)
		(end 55.50408 -314.570364)
		(width 0.16002)
		(layer "In13.Cu")
		(net "M_B_CPU1_SB_DQS_DN<8>")
	)
	(segment
		(start 48.418496 -313.880246)
		(end 48.260254 -314.038488)
		(width 0.16002)
		(layer "In13.Cu")
		(net "M_B_CPU1_SB_DQS_DN<8>")
	)
	(segment
		(start 62.231016 -312.646568)
		(end 59.216036 -313.895486)
		(width 0.16002)
		(layer "In13.Cu")
		(net "M_B_CPU1_SB_DQS_DN<8>")
	)
	(segment
		(start 51.606704 -314.687204)
		(end 51.365404 -314.441078)
		(width 0.16002)
		(layer "In13.Cu")
		(net "M_B_CPU1_SB_DQS_DN<8>")
	)
	(segment
		(start 56.10098 -314.687204)
		(end 55.98414 -314.570364)
		(width 0.16002)
		(layer "In13.Cu")
		(net "M_B_CPU1_SB_DQS_DN<8>")
	)
	(segment
		(start 71.0438 -302.631348)
		(end 71.0438 -303.833784)
		(width 0.16002)
		(layer "In13.Cu")
		(net "M_B_CPU1_SB_DQS_DN<8>")
	)
	(segment
		(start 48.037242 -314.038488)
		(end 47.784004 -313.78525)
		(width 0.16002)
		(layer "In13.Cu")
		(net "M_B_CPU1_SB_DQS_DN<8>")
	)
	(segment
		(start 74.35215 -299.322998)
		(end 71.0438 -302.631348)
		(width 0.16002)
		(layer "In13.Cu")
		(net "M_B_CPU1_SB_DQS_DN<8>")
	)
	(segment
		(start 56.925718 -314.687204)
		(end 56.10098 -314.687204)
		(width 0.16002)
		(layer "In13.Cu")
		(net "M_B_CPU1_SB_DQS_DN<8>")
	)
	(segment
		(start 88.40089 -291.426138)
		(end 88.392508 -291.421312)
		(width 0.09525)
		(layer "In13.Cu")
		(net "M_B_CPU1_SB_DQS_DN<8>")
	)
	(arc
		(start 85.941154 -291.426138)
		(mid 85.756122 -291.472052)
		(end 85.572346 -291.421312)
		(width 0.09525)
		(layer "In13.Cu")
		(net "M_B_CPU1_SB_DQS_DN<8>")
	)
	(arc
		(start 85.572346 -291.421312)
		(mid 85.290914 -291.345557)
		(end 85.009482 -291.421312)
		(width 0.09525)
		(layer "In13.Cu")
		(net "M_B_CPU1_SB_DQS_DN<8>")
	)
	(arc
		(start 82.752438 -291.421312)
		(mid 82.471006 -291.345557)
		(end 82.189574 -291.421312)
		(width 0.09525)
		(layer "In13.Cu")
		(net "M_B_CPU1_SB_DQS_DN<8>")
	)
	(arc
		(start 87.452454 -291.421312)
		(mid 87.171022 -291.345557)
		(end 86.88959 -291.421312)
		(width 0.09525)
		(layer "In13.Cu")
		(net "M_B_CPU1_SB_DQS_DN<8>")
	)
	(arc
		(start 82.181192 -291.426138)
		(mid 81.99616 -291.472052)
		(end 81.812384 -291.421312)
		(width 0.09525)
		(layer "In13.Cu")
		(net "M_B_CPU1_SB_DQS_DN<8>")
	)
	(arc
		(start 80.30972 -291.421312)
		(mid 80.218754 -291.459465)
		(end 80.120998 -291.47262)
		(width 0.09525)
		(layer "In13.Cu")
		(net "M_B_CPU1_SB_DQS_DN<8>")
	)
	(arc
		(start 81.812384 -291.421312)
		(mid 81.530952 -291.345557)
		(end 81.24952 -291.421312)
		(width 0.09525)
		(layer "In13.Cu")
		(net "M_B_CPU1_SB_DQS_DN<8>")
	)
	(arc
		(start 88.392508 -291.421312)
		(mid 88.111076 -291.345557)
		(end 87.829644 -291.421312)
		(width 0.09525)
		(layer "In13.Cu")
		(net "M_B_CPU1_SB_DQS_DN<8>")
	)
	(arc
		(start 86.5124 -291.421312)
		(mid 86.230968 -291.345557)
		(end 85.949536 -291.421312)
		(width 0.09525)
		(layer "In13.Cu")
		(net "M_B_CPU1_SB_DQS_DN<8>")
	)
	(arc
		(start 86.881208 -291.426138)
		(mid 86.696176 -291.472052)
		(end 86.5124 -291.421312)
		(width 0.09525)
		(layer "In13.Cu")
		(net "M_B_CPU1_SB_DQS_DN<8>")
	)
	(arc
		(start 80.872584 -291.421312)
		(mid 80.591152 -291.345557)
		(end 80.30972 -291.421312)
		(width 0.09525)
		(layer "In13.Cu")
		(net "M_B_CPU1_SB_DQS_DN<8>")
	)
	(arc
		(start 88.769698 -291.421312)
		(mid 88.585923 -291.472084)
		(end 88.40089 -291.426138)
		(width 0.09525)
		(layer "In13.Cu")
		(net "M_B_CPU1_SB_DQS_DN<8>")
	)
	(arc
		(start 87.829644 -291.421312)
		(mid 87.645869 -291.472084)
		(end 87.460836 -291.426138)
		(width 0.09525)
		(layer "In13.Cu")
		(net "M_B_CPU1_SB_DQS_DN<8>")
	)
	(arc
		(start 81.24952 -291.421312)
		(mid 81.061052 -291.471989)
		(end 80.872584 -291.421312)
		(width 0.09525)
		(layer "In13.Cu")
		(net "M_B_CPU1_SB_DQS_DN<8>")
	)
	(arc
		(start 83.692492 -291.421312)
		(mid 83.41106 -291.345557)
		(end 83.129628 -291.421312)
		(width 0.09525)
		(layer "In13.Cu")
		(net "M_B_CPU1_SB_DQS_DN<8>")
	)
	(arc
		(start 89.266268 -291.388292)
		(mid 89.256146 -291.384257)
		(end 89.245948 -291.380418)
		(width 0.09525)
		(layer "In13.Cu")
		(net "M_B_CPU1_SB_DQS_DN<8>")
	)
	(arc
		(start 83.129628 -291.421312)
		(mid 82.945853 -291.472084)
		(end 82.76082 -291.426138)
		(width 0.09525)
		(layer "In13.Cu")
		(net "M_B_CPU1_SB_DQS_DN<8>")
	)
	(arc
		(start 85.009482 -291.421312)
		(mid 84.821014 -291.471989)
		(end 84.632546 -291.421312)
		(width 0.09525)
		(layer "In13.Cu")
		(net "M_B_CPU1_SB_DQS_DN<8>")
	)
	(arc
		(start 84.632546 -291.421312)
		(mid 84.351114 -291.345557)
		(end 84.069682 -291.421312)
		(width 0.09525)
		(layer "In13.Cu")
		(net "M_B_CPU1_SB_DQS_DN<8>")
	)
	(arc
		(start 84.069682 -291.421312)
		(mid 83.885907 -291.472084)
		(end 83.700874 -291.426138)
		(width 0.09525)
		(layer "In13.Cu")
		(net "M_B_CPU1_SB_DQS_DN<8>")
	)
	(arc
		(start 89.245948 -291.380418)
		(mid 89.003236 -291.347535)
		(end 88.769698 -291.421312)
		(width 0.09525)
		(layer "In13.Cu")
		(net "M_B_CPU1_SB_DQS_DN<8>")
	)
	(segment
		(start 89.987882 -285.970472)
		(end 89.52103 -286.23641)
		(width 0.12954)
		(layer "F.Cu")
		(net "M_B_CPU1_SB_DQS_DN<7>")
	)
	(segment
		(start 88.40089 -286.566356)
		(end 88.392508 -286.56153)
		(width 0.09525)
		(layer "In13.Cu")
		(net "M_B_CPU1_SB_DQS_DN<7>")
	)
	(segment
		(start 54.70398 -305.375564)
		(end 54.156356 -305.375564)
		(width 0.16002)
		(layer "In13.Cu")
		(net "M_B_CPU1_SB_DQS_DN<7>")
	)
	(segment
		(start 76.951586 -286.901636)
		(end 76.05649 -287.796732)
		(width 0.09525)
		(layer "In13.Cu")
		(net "M_B_CPU1_SB_DQS_DN<7>")
	)
	(segment
		(start 79.005938 -286.577532)
		(end 78.956408 -286.549338)
		(width 0.09525)
		(layer "In13.Cu")
		(net "M_B_CPU1_SB_DQS_DN<7>")
	)
	(segment
		(start 49.671478 -304.530252)
		(end 49.238916 -304.709322)
		(width 0.16002)
		(layer "In13.Cu")
		(net "M_B_CPU1_SB_DQS_DN<7>")
	)
	(segment
		(start 52.90693 -304.858166)
		(end 51.546252 -304.858166)
		(width 0.16002)
		(layer "In13.Cu")
		(net "M_B_CPU1_SB_DQS_DN<7>")
	)
	(segment
		(start 60.440316 -304.053494)
		(end 57.628536 -304.612802)
		(width 0.16002)
		(layer "In13.Cu")
		(net "M_B_CPU1_SB_DQS_DN<7>")
	)
	(segment
		(start 49.238916 -304.709322)
		(end 48.05807 -304.709322)
		(width 0.16002)
		(layer "In13.Cu")
		(net "M_B_CPU1_SB_DQS_DN<7>")
	)
	(segment
		(start 55.41772 -305.375564)
		(end 55.30088 -305.258724)
		(width 0.16002)
		(layer "In13.Cu")
		(net "M_B_CPU1_SB_DQS_DN<7>")
	)
	(segment
		(start 56.865774 -305.375564)
		(end 55.41772 -305.375564)
		(width 0.16002)
		(layer "In13.Cu")
		(net "M_B_CPU1_SB_DQS_DN<7>")
	)
	(segment
		(start 86.88959 -286.56153)
		(end 86.881208 -286.566356)
		(width 0.09525)
		(layer "In13.Cu")
		(net "M_B_CPU1_SB_DQS_DN<7>")
	)
	(segment
		(start 75.955906 -287.813496)
		(end 68.062348 -295.706546)
		(width 0.16002)
		(layer "In13.Cu")
		(net "M_B_CPU1_SB_DQS_DN<7>")
	)
	(segment
		(start 75.97267 -287.796732)
		(end 75.955906 -287.813496)
		(width 0.09525)
		(layer "In13.Cu")
		(net "M_B_CPU1_SB_DQS_DN<7>")
	)
	(segment
		(start 77.938122 -286.628586)
		(end 77.665072 -286.901636)
		(width 0.09525)
		(layer "In13.Cu")
		(net "M_B_CPU1_SB_DQS_DN<7>")
	)
	(segment
		(start 79.953358 -286.57296)
		(end 79.933292 -286.561276)
		(width 0.09525)
		(layer "In13.Cu")
		(net "M_B_CPU1_SB_DQS_DN<7>")
	)
	(segment
		(start 77.665072 -286.901636)
		(end 76.951586 -286.901636)
		(width 0.09525)
		(layer "In13.Cu")
		(net "M_B_CPU1_SB_DQS_DN<7>")
	)
	(segment
		(start 78.228444 -286.628586)
		(end 77.938122 -286.628586)
		(width 0.09525)
		(layer "In13.Cu")
		(net "M_B_CPU1_SB_DQS_DN<7>")
	)
	(segment
		(start 82.76082 -286.566356)
		(end 82.752438 -286.56153)
		(width 0.09525)
		(layer "In13.Cu")
		(net "M_B_CPU1_SB_DQS_DN<7>")
	)
	(segment
		(start 51.546252 -304.858166)
		(end 50.754534 -304.530252)
		(width 0.16002)
		(layer "In13.Cu")
		(net "M_B_CPU1_SB_DQS_DN<7>")
	)
	(segment
		(start 57.628536 -304.612802)
		(end 56.865774 -305.375564)
		(width 0.16002)
		(layer "In13.Cu")
		(net "M_B_CPU1_SB_DQS_DN<7>")
	)
	(segment
		(start 60.934854 -304.053494)
		(end 60.440316 -304.053494)
		(width 0.16002)
		(layer "In13.Cu")
		(net "M_B_CPU1_SB_DQS_DN<7>")
	)
	(segment
		(start 79.915512 -286.550862)
		(end 79.914496 -286.550354)
		(width 0.09525)
		(layer "In13.Cu")
		(net "M_B_CPU1_SB_DQS_DN<7>")
	)
	(segment
		(start 68.062348 -295.706546)
		(end 68.062348 -296.926)
		(width 0.16002)
		(layer "In13.Cu")
		(net "M_B_CPU1_SB_DQS_DN<7>")
	)
	(segment
		(start 89.52103 -286.23641)
		(end 89.367106 -286.50184)
		(width 0.09525)
		(layer "In13.Cu")
		(net "M_B_CPU1_SB_DQS_DN<7>")
	)
	(segment
		(start 55.30088 -305.258724)
		(end 54.82082 -305.258724)
		(width 0.16002)
		(layer "In13.Cu")
		(net "M_B_CPU1_SB_DQS_DN<7>")
	)
	(segment
		(start 89.367106 -286.50184)
		(end 89.266268 -286.52851)
		(width 0.09525)
		(layer "In13.Cu")
		(net "M_B_CPU1_SB_DQS_DN<7>")
	)
	(segment
		(start 85.949536 -286.56153)
		(end 85.941154 -286.566356)
		(width 0.09525)
		(layer "In13.Cu")
		(net "M_B_CPU1_SB_DQS_DN<7>")
	)
	(segment
		(start 83.700874 -286.566356)
		(end 83.692492 -286.56153)
		(width 0.09525)
		(layer "In13.Cu")
		(net "M_B_CPU1_SB_DQS_DN<7>")
	)
	(segment
		(start 79.933292 -286.561276)
		(end 79.915512 -286.550862)
		(width 0.09525)
		(layer "In13.Cu")
		(net "M_B_CPU1_SB_DQS_DN<7>")
	)
	(segment
		(start 76.05649 -287.796732)
		(end 75.97267 -287.796732)
		(width 0.09525)
		(layer "In13.Cu")
		(net "M_B_CPU1_SB_DQS_DN<7>")
	)
	(segment
		(start 50.754534 -304.530252)
		(end 49.671478 -304.530252)
		(width 0.16002)
		(layer "In13.Cu")
		(net "M_B_CPU1_SB_DQS_DN<7>")
	)
	(segment
		(start 48.05807 -304.709322)
		(end 47.784004 -304.435256)
		(width 0.16002)
		(layer "In13.Cu")
		(net "M_B_CPU1_SB_DQS_DN<7>")
	)
	(segment
		(start 68.062348 -296.926)
		(end 60.934854 -304.053494)
		(width 0.16002)
		(layer "In13.Cu")
		(net "M_B_CPU1_SB_DQS_DN<7>")
	)
	(segment
		(start 82.189574 -286.56153)
		(end 82.181192 -286.566356)
		(width 0.09525)
		(layer "In13.Cu")
		(net "M_B_CPU1_SB_DQS_DN<7>")
	)
	(segment
		(start 54.156356 -305.375564)
		(end 52.90693 -304.858166)
		(width 0.16002)
		(layer "In13.Cu")
		(net "M_B_CPU1_SB_DQS_DN<7>")
	)
	(segment
		(start 87.460836 -286.566356)
		(end 87.452454 -286.56153)
		(width 0.09525)
		(layer "In13.Cu")
		(net "M_B_CPU1_SB_DQS_DN<7>")
	)
	(segment
		(start 54.82082 -305.258724)
		(end 54.70398 -305.375564)
		(width 0.16002)
		(layer "In13.Cu")
		(net "M_B_CPU1_SB_DQS_DN<7>")
	)
	(arc
		(start 86.881208 -286.566356)
		(mid 86.696176 -286.61227)
		(end 86.5124 -286.56153)
		(width 0.09525)
		(layer "In13.Cu")
		(net "M_B_CPU1_SB_DQS_DN<7>")
	)
	(arc
		(start 85.572346 -286.56153)
		(mid 85.290914 -286.485741)
		(end 85.009482 -286.56153)
		(width 0.09525)
		(layer "In13.Cu")
		(net "M_B_CPU1_SB_DQS_DN<7>")
	)
	(arc
		(start 82.181192 -286.566356)
		(mid 81.99616 -286.61227)
		(end 81.812384 -286.56153)
		(width 0.09525)
		(layer "In13.Cu")
		(net "M_B_CPU1_SB_DQS_DN<7>")
	)
	(arc
		(start 79.403194 -286.544766)
		(mid 79.369838 -286.560238)
		(end 79.33563 -286.573722)
		(width 0.09525)
		(layer "In13.Cu")
		(net "M_B_CPU1_SB_DQS_DN<7>")
	)
	(arc
		(start 78.956408 -286.549338)
		(mid 78.685806 -286.492627)
		(end 78.421484 -286.573722)
		(width 0.09525)
		(layer "In13.Cu")
		(net "M_B_CPU1_SB_DQS_DN<7>")
	)
	(arc
		(start 85.941154 -286.566356)
		(mid 85.756122 -286.61227)
		(end 85.572346 -286.56153)
		(width 0.09525)
		(layer "In13.Cu")
		(net "M_B_CPU1_SB_DQS_DN<7>")
	)
	(arc
		(start 86.5124 -286.56153)
		(mid 86.230968 -286.485741)
		(end 85.949536 -286.56153)
		(width 0.09525)
		(layer "In13.Cu")
		(net "M_B_CPU1_SB_DQS_DN<7>")
	)
	(arc
		(start 87.829644 -286.56153)
		(mid 87.645869 -286.612302)
		(end 87.460836 -286.566356)
		(width 0.09525)
		(layer "In13.Cu")
		(net "M_B_CPU1_SB_DQS_DN<7>")
	)
	(arc
		(start 81.812384 -286.56153)
		(mid 81.530952 -286.485741)
		(end 81.24952 -286.56153)
		(width 0.09525)
		(layer "In13.Cu")
		(net "M_B_CPU1_SB_DQS_DN<7>")
	)
	(arc
		(start 88.392508 -286.56153)
		(mid 88.111076 -286.485741)
		(end 87.829644 -286.56153)
		(width 0.09525)
		(layer "In13.Cu")
		(net "M_B_CPU1_SB_DQS_DN<7>")
	)
	(arc
		(start 82.752438 -286.56153)
		(mid 82.471006 -286.485741)
		(end 82.189574 -286.56153)
		(width 0.09525)
		(layer "In13.Cu")
		(net "M_B_CPU1_SB_DQS_DN<7>")
	)
	(arc
		(start 83.692492 -286.56153)
		(mid 83.41106 -286.485741)
		(end 83.129628 -286.56153)
		(width 0.09525)
		(layer "In13.Cu")
		(net "M_B_CPU1_SB_DQS_DN<7>")
	)
	(arc
		(start 81.24952 -286.56153)
		(mid 81.061052 -286.612207)
		(end 80.872584 -286.56153)
		(width 0.09525)
		(layer "In13.Cu")
		(net "M_B_CPU1_SB_DQS_DN<7>")
	)
	(arc
		(start 88.769698 -286.56153)
		(mid 88.585923 -286.612302)
		(end 88.40089 -286.566356)
		(width 0.09525)
		(layer "In13.Cu")
		(net "M_B_CPU1_SB_DQS_DN<7>")
	)
	(arc
		(start 89.266268 -286.52851)
		(mid 89.256147 -286.524348)
		(end 89.245948 -286.520382)
		(width 0.09525)
		(layer "In13.Cu")
		(net "M_B_CPU1_SB_DQS_DN<7>")
	)
	(arc
		(start 84.069682 -286.56153)
		(mid 83.885907 -286.612302)
		(end 83.700874 -286.566356)
		(width 0.09525)
		(layer "In13.Cu")
		(net "M_B_CPU1_SB_DQS_DN<7>")
	)
	(arc
		(start 79.914496 -286.550354)
		(mid 79.910186 -286.548431)
		(end 79.90586 -286.546544)
		(width 0.09525)
		(layer "In13.Cu")
		(net "M_B_CPU1_SB_DQS_DN<7>")
	)
	(arc
		(start 85.009482 -286.56153)
		(mid 84.821014 -286.612207)
		(end 84.632546 -286.56153)
		(width 0.09525)
		(layer "In13.Cu")
		(net "M_B_CPU1_SB_DQS_DN<7>")
	)
	(arc
		(start 79.33563 -286.573722)
		(mid 79.1711 -286.603162)
		(end 79.005938 -286.577532)
		(width 0.09525)
		(layer "In13.Cu")
		(net "M_B_CPU1_SB_DQS_DN<7>")
	)
	(arc
		(start 84.632546 -286.56153)
		(mid 84.351114 -286.485741)
		(end 84.069682 -286.56153)
		(width 0.09525)
		(layer "In13.Cu")
		(net "M_B_CPU1_SB_DQS_DN<7>")
	)
	(arc
		(start 80.30972 -286.56153)
		(mid 80.132987 -286.612143)
		(end 79.953358 -286.57296)
		(width 0.09525)
		(layer "In13.Cu")
		(net "M_B_CPU1_SB_DQS_DN<7>")
	)
	(arc
		(start 87.452454 -286.56153)
		(mid 87.171022 -286.485741)
		(end 86.88959 -286.56153)
		(width 0.09525)
		(layer "In13.Cu")
		(net "M_B_CPU1_SB_DQS_DN<7>")
	)
	(arc
		(start 83.129628 -286.56153)
		(mid 82.945853 -286.612302)
		(end 82.76082 -286.566356)
		(width 0.09525)
		(layer "In13.Cu")
		(net "M_B_CPU1_SB_DQS_DN<7>")
	)
	(arc
		(start 78.421484 -286.573722)
		(mid 78.328756 -286.614491)
		(end 78.228444 -286.628586)
		(width 0.09525)
		(layer "In13.Cu")
		(net "M_B_CPU1_SB_DQS_DN<7>")
	)
	(arc
		(start 89.245948 -286.520382)
		(mid 89.003206 -286.487597)
		(end 88.769698 -286.56153)
		(width 0.09525)
		(layer "In13.Cu")
		(net "M_B_CPU1_SB_DQS_DN<7>")
	)
	(arc
		(start 80.872584 -286.56153)
		(mid 80.591152 -286.485741)
		(end 80.30972 -286.56153)
		(width 0.09525)
		(layer "In13.Cu")
		(net "M_B_CPU1_SB_DQS_DN<7>")
	)
	(arc
		(start 79.90586 -286.546544)
		(mid 79.65475 -286.486148)
		(end 79.403194 -286.544766)
		(width 0.09525)
		(layer "In13.Cu")
		(net "M_B_CPU1_SB_DQS_DN<7>")
	)
	(segment
		(start 89.987882 -281.110436)
		(end 89.52103 -281.376374)
		(width 0.12954)
		(layer "F.Cu")
		(net "M_B_CPU1_SB_DQS_DN<6>")
	)
	(segment
		(start 48.05807 -295.359328)
		(end 47.784004 -295.085262)
		(width 0.16002)
		(layer "In13.Cu")
		(net "M_B_CPU1_SB_DQS_DN<6>")
	)
	(segment
		(start 82.189574 -281.701494)
		(end 82.181192 -281.70632)
		(width 0.09525)
		(layer "In13.Cu")
		(net "M_B_CPU1_SB_DQS_DN<6>")
	)
	(segment
		(start 87.460836 -281.70632)
		(end 87.452454 -281.701494)
		(width 0.09525)
		(layer "In13.Cu")
		(net "M_B_CPU1_SB_DQS_DN<6>")
	)
	(segment
		(start 88.40089 -281.70632)
		(end 88.392508 -281.701494)
		(width 0.09525)
		(layer "In13.Cu")
		(net "M_B_CPU1_SB_DQS_DN<6>")
	)
	(segment
		(start 56.91378 -295.977564)
		(end 53.870352 -295.977564)
		(width 0.16002)
		(layer "In13.Cu")
		(net "M_B_CPU1_SB_DQS_DN<6>")
	)
	(segment
		(start 89.367106 -281.641804)
		(end 89.266268 -281.668474)
		(width 0.09525)
		(layer "In13.Cu")
		(net "M_B_CPU1_SB_DQS_DN<6>")
	)
	(segment
		(start 76.03871 -281.731466)
		(end 75.979528 -281.672284)
		(width 0.09525)
		(layer "In13.Cu")
		(net "M_B_CPU1_SB_DQS_DN<6>")
	)
	(segment
		(start 48.440848 -295.180258)
		(end 48.261778 -295.359328)
		(width 0.16002)
		(layer "In13.Cu")
		(net "M_B_CPU1_SB_DQS_DN<6>")
	)
	(segment
		(start 53.40096 -295.508172)
		(end 51.614578 -295.508172)
		(width 0.16002)
		(layer "In13.Cu")
		(net "M_B_CPU1_SB_DQS_DN<6>")
	)
	(segment
		(start 50.89017 -295.180258)
		(end 48.440848 -295.180258)
		(width 0.16002)
		(layer "In13.Cu")
		(net "M_B_CPU1_SB_DQS_DN<6>")
	)
	(segment
		(start 48.261778 -295.359328)
		(end 48.05807 -295.359328)
		(width 0.16002)
		(layer "In13.Cu")
		(net "M_B_CPU1_SB_DQS_DN<6>")
	)
	(segment
		(start 57.711086 -295.180258)
		(end 56.91378 -295.977564)
		(width 0.16002)
		(layer "In13.Cu")
		(net "M_B_CPU1_SB_DQS_DN<6>")
	)
	(segment
		(start 86.88959 -281.701494)
		(end 86.881208 -281.70632)
		(width 0.09525)
		(layer "In13.Cu")
		(net "M_B_CPU1_SB_DQS_DN<6>")
	)
	(segment
		(start 73.990454 -281.672284)
		(end 60.48248 -295.180258)
		(width 0.16002)
		(layer "In13.Cu")
		(net "M_B_CPU1_SB_DQS_DN<6>")
	)
	(segment
		(start 75.955906 -281.672284)
		(end 73.990454 -281.672284)
		(width 0.16002)
		(layer "In13.Cu")
		(net "M_B_CPU1_SB_DQS_DN<6>")
	)
	(segment
		(start 51.614578 -295.508172)
		(end 50.89017 -295.180258)
		(width 0.16002)
		(layer "In13.Cu")
		(net "M_B_CPU1_SB_DQS_DN<6>")
	)
	(segment
		(start 75.979528 -281.672284)
		(end 75.955906 -281.672284)
		(width 0.09525)
		(layer "In13.Cu")
		(net "M_B_CPU1_SB_DQS_DN<6>")
	)
	(segment
		(start 89.52103 -281.376374)
		(end 89.367106 -281.641804)
		(width 0.09525)
		(layer "In13.Cu")
		(net "M_B_CPU1_SB_DQS_DN<6>")
	)
	(segment
		(start 83.700874 -281.70632)
		(end 83.692492 -281.701494)
		(width 0.09525)
		(layer "In13.Cu")
		(net "M_B_CPU1_SB_DQS_DN<6>")
	)
	(segment
		(start 60.48248 -295.180258)
		(end 57.711086 -295.180258)
		(width 0.16002)
		(layer "In13.Cu")
		(net "M_B_CPU1_SB_DQS_DN<6>")
	)
	(segment
		(start 79.16291 -281.543506)
		(end 76.675742 -281.543506)
		(width 0.09525)
		(layer "In13.Cu")
		(net "M_B_CPU1_SB_DQS_DN<6>")
	)
	(segment
		(start 76.43749 -281.731466)
		(end 76.03871 -281.731466)
		(width 0.09525)
		(layer "In13.Cu")
		(net "M_B_CPU1_SB_DQS_DN<6>")
	)
	(segment
		(start 53.870352 -295.977564)
		(end 53.40096 -295.508172)
		(width 0.16002)
		(layer "In13.Cu")
		(net "M_B_CPU1_SB_DQS_DN<6>")
	)
	(segment
		(start 76.58989 -281.579066)
		(end 76.43749 -281.731466)
		(width 0.09525)
		(layer "In13.Cu")
		(net "M_B_CPU1_SB_DQS_DN<6>")
	)
	(segment
		(start 82.76082 -281.70632)
		(end 82.752438 -281.701494)
		(width 0.09525)
		(layer "In13.Cu")
		(net "M_B_CPU1_SB_DQS_DN<6>")
	)
	(segment
		(start 85.949536 -281.701494)
		(end 85.941154 -281.70632)
		(width 0.09525)
		(layer "In13.Cu")
		(net "M_B_CPU1_SB_DQS_DN<6>")
	)
	(arc
		(start 86.5124 -281.701494)
		(mid 86.230968 -281.625739)
		(end 85.949536 -281.701494)
		(width 0.09525)
		(layer "In13.Cu")
		(net "M_B_CPU1_SB_DQS_DN<6>")
	)
	(arc
		(start 76.675742 -281.543506)
		(mid 76.629294 -281.552763)
		(end 76.58989 -281.579066)
		(width 0.09525)
		(layer "In13.Cu")
		(net "M_B_CPU1_SB_DQS_DN<6>")
	)
	(arc
		(start 85.572346 -281.701494)
		(mid 85.290914 -281.625739)
		(end 85.009482 -281.701494)
		(width 0.09525)
		(layer "In13.Cu")
		(net "M_B_CPU1_SB_DQS_DN<6>")
	)
	(arc
		(start 85.941154 -281.70632)
		(mid 85.756122 -281.752234)
		(end 85.572346 -281.701494)
		(width 0.09525)
		(layer "In13.Cu")
		(net "M_B_CPU1_SB_DQS_DN<6>")
	)
	(arc
		(start 84.632546 -281.701494)
		(mid 84.351114 -281.625739)
		(end 84.069682 -281.701494)
		(width 0.09525)
		(layer "In13.Cu")
		(net "M_B_CPU1_SB_DQS_DN<6>")
	)
	(arc
		(start 81.812384 -281.701494)
		(mid 81.554501 -281.626117)
		(end 81.291176 -281.679396)
		(width 0.09525)
		(layer "In13.Cu")
		(net "M_B_CPU1_SB_DQS_DN<6>")
	)
	(arc
		(start 79.964788 -281.718004)
		(mid 79.573253 -281.58753)
		(end 79.16291 -281.543506)
		(width 0.09525)
		(layer "In13.Cu")
		(net "M_B_CPU1_SB_DQS_DN<6>")
	)
	(arc
		(start 83.692492 -281.701494)
		(mid 83.41106 -281.625739)
		(end 83.129628 -281.701494)
		(width 0.09525)
		(layer "In13.Cu")
		(net "M_B_CPU1_SB_DQS_DN<6>")
	)
	(arc
		(start 85.009482 -281.701494)
		(mid 84.821014 -281.752171)
		(end 84.632546 -281.701494)
		(width 0.09525)
		(layer "In13.Cu")
		(net "M_B_CPU1_SB_DQS_DN<6>")
	)
	(arc
		(start 86.881208 -281.70632)
		(mid 86.696176 -281.752234)
		(end 86.5124 -281.701494)
		(width 0.09525)
		(layer "In13.Cu")
		(net "M_B_CPU1_SB_DQS_DN<6>")
	)
	(arc
		(start 88.769698 -281.701494)
		(mid 88.585923 -281.752266)
		(end 88.40089 -281.70632)
		(width 0.09525)
		(layer "In13.Cu")
		(net "M_B_CPU1_SB_DQS_DN<6>")
	)
	(arc
		(start 82.181192 -281.70632)
		(mid 81.99616 -281.752234)
		(end 81.812384 -281.701494)
		(width 0.09525)
		(layer "In13.Cu")
		(net "M_B_CPU1_SB_DQS_DN<6>")
	)
	(arc
		(start 82.752438 -281.701494)
		(mid 82.471006 -281.625739)
		(end 82.189574 -281.701494)
		(width 0.09525)
		(layer "In13.Cu")
		(net "M_B_CPU1_SB_DQS_DN<6>")
	)
	(arc
		(start 89.245948 -281.6606)
		(mid 89.003236 -281.627717)
		(end 88.769698 -281.701494)
		(width 0.09525)
		(layer "In13.Cu")
		(net "M_B_CPU1_SB_DQS_DN<6>")
	)
	(arc
		(start 84.069682 -281.701494)
		(mid 83.885907 -281.752266)
		(end 83.700874 -281.70632)
		(width 0.09525)
		(layer "In13.Cu")
		(net "M_B_CPU1_SB_DQS_DN<6>")
	)
	(arc
		(start 81.291176 -281.679396)
		(mid 81.074163 -281.7328)
		(end 80.853534 -281.697176)
		(width 0.09525)
		(layer "In13.Cu")
		(net "M_B_CPU1_SB_DQS_DN<6>")
	)
	(arc
		(start 83.129628 -281.701494)
		(mid 82.945853 -281.752266)
		(end 82.76082 -281.70632)
		(width 0.09525)
		(layer "In13.Cu")
		(net "M_B_CPU1_SB_DQS_DN<6>")
	)
	(arc
		(start 89.266268 -281.668474)
		(mid 89.256146 -281.664439)
		(end 89.245948 -281.6606)
		(width 0.09525)
		(layer "In13.Cu")
		(net "M_B_CPU1_SB_DQS_DN<6>")
	)
	(arc
		(start 80.278732 -281.71775)
		(mid 80.12179 -281.752216)
		(end 79.964788 -281.718004)
		(width 0.09525)
		(layer "In13.Cu")
		(net "M_B_CPU1_SB_DQS_DN<6>")
	)
	(arc
		(start 87.829644 -281.701494)
		(mid 87.645869 -281.752266)
		(end 87.460836 -281.70632)
		(width 0.09525)
		(layer "In13.Cu")
		(net "M_B_CPU1_SB_DQS_DN<6>")
	)
	(arc
		(start 88.392508 -281.701494)
		(mid 88.111076 -281.625739)
		(end 87.829644 -281.701494)
		(width 0.09525)
		(layer "In13.Cu")
		(net "M_B_CPU1_SB_DQS_DN<6>")
	)
	(arc
		(start 87.452454 -281.701494)
		(mid 87.171022 -281.625739)
		(end 86.88959 -281.701494)
		(width 0.09525)
		(layer "In13.Cu")
		(net "M_B_CPU1_SB_DQS_DN<6>")
	)
	(arc
		(start 80.853534 -281.697176)
		(mid 80.564061 -281.649671)
		(end 80.278732 -281.71775)
		(width 0.09525)
		(layer "In13.Cu")
		(net "M_B_CPU1_SB_DQS_DN<6>")
	)
	(segment
		(start 89.987882 -276.2504)
		(end 89.52103 -276.516338)
		(width 0.12954)
		(layer "F.Cu")
		(net "M_B_CPU1_SB_DQS_DN<5>")
	)
	(segment
		(start 76.933044 -276.664166)
		(end 76.376784 -276.107906)
		(width 0.09525)
		(layer "In13.Cu")
		(net "M_B_CPU1_SB_DQS_DN<5>")
	)
	(segment
		(start 53.609748 -286.158178)
		(end 51.5493 -286.158178)
		(width 0.16002)
		(layer "In13.Cu")
		(net "M_B_CPU1_SB_DQS_DN<5>")
	)
	(segment
		(start 75.979528 -276.048724)
		(end 75.955906 -276.048724)
		(width 0.09525)
		(layer "In13.Cu")
		(net "M_B_CPU1_SB_DQS_DN<5>")
	)
	(segment
		(start 48.021494 -285.972758)
		(end 47.784004 -285.735268)
		(width 0.16002)
		(layer "In13.Cu")
		(net "M_B_CPU1_SB_DQS_DN<5>")
	)
	(segment
		(start 49.798478 -285.830264)
		(end 49.454308 -285.972758)
		(width 0.16002)
		(layer "In13.Cu")
		(net "M_B_CPU1_SB_DQS_DN<5>")
	)
	(segment
		(start 69.975222 -276.048724)
		(end 61.400944 -284.623002)
		(width 0.16002)
		(layer "In13.Cu")
		(net "M_B_CPU1_SB_DQS_DN<5>")
	)
	(segment
		(start 79.237586 -276.699726)
		(end 77.018896 -276.699726)
		(width 0.09525)
		(layer "In13.Cu")
		(net "M_B_CPU1_SB_DQS_DN<5>")
	)
	(segment
		(start 51.5493 -286.158178)
		(end 51.153314 -285.994094)
		(width 0.16002)
		(layer "In13.Cu")
		(net "M_B_CPU1_SB_DQS_DN<5>")
	)
	(segment
		(start 50.757328 -285.830264)
		(end 49.798478 -285.830264)
		(width 0.16002)
		(layer "In13.Cu")
		(net "M_B_CPU1_SB_DQS_DN<5>")
	)
	(segment
		(start 56.910986 -286.630364)
		(end 54.081934 -286.630364)
		(width 0.16002)
		(layer "In13.Cu")
		(net "M_B_CPU1_SB_DQS_DN<5>")
	)
	(segment
		(start 86.88959 -276.841458)
		(end 86.881208 -276.846284)
		(width 0.09525)
		(layer "In13.Cu")
		(net "M_B_CPU1_SB_DQS_DN<5>")
	)
	(segment
		(start 83.700874 -276.846284)
		(end 83.692492 -276.841458)
		(width 0.09525)
		(layer "In13.Cu")
		(net "M_B_CPU1_SB_DQS_DN<5>")
	)
	(segment
		(start 54.081934 -286.630364)
		(end 53.609748 -286.158178)
		(width 0.16002)
		(layer "In13.Cu")
		(net "M_B_CPU1_SB_DQS_DN<5>")
	)
	(segment
		(start 88.40089 -276.846284)
		(end 88.392508 -276.841458)
		(width 0.09525)
		(layer "In13.Cu")
		(net "M_B_CPU1_SB_DQS_DN<5>")
	)
	(segment
		(start 51.153314 -285.994094)
		(end 51.15306 -285.994094)
		(width 0.16002)
		(layer "In13.Cu")
		(net "M_B_CPU1_SB_DQS_DN<5>")
	)
	(segment
		(start 87.460836 -276.846284)
		(end 87.452454 -276.841458)
		(width 0.09525)
		(layer "In13.Cu")
		(net "M_B_CPU1_SB_DQS_DN<5>")
	)
	(segment
		(start 82.76082 -276.846284)
		(end 82.752438 -276.841458)
		(width 0.09525)
		(layer "In13.Cu")
		(net "M_B_CPU1_SB_DQS_DN<5>")
	)
	(segment
		(start 58.486548 -285.830264)
		(end 57.711086 -285.830264)
		(width 0.16002)
		(layer "In13.Cu")
		(net "M_B_CPU1_SB_DQS_DN<5>")
	)
	(segment
		(start 61.400944 -284.623002)
		(end 58.486548 -285.830264)
		(width 0.16002)
		(layer "In13.Cu")
		(net "M_B_CPU1_SB_DQS_DN<5>")
	)
	(segment
		(start 89.367106 -276.781768)
		(end 89.266268 -276.808438)
		(width 0.09525)
		(layer "In13.Cu")
		(net "M_B_CPU1_SB_DQS_DN<5>")
	)
	(segment
		(start 82.189574 -276.841458)
		(end 82.181192 -276.846284)
		(width 0.09525)
		(layer "In13.Cu")
		(net "M_B_CPU1_SB_DQS_DN<5>")
	)
	(segment
		(start 89.52103 -276.516338)
		(end 89.367106 -276.781768)
		(width 0.09525)
		(layer "In13.Cu")
		(net "M_B_CPU1_SB_DQS_DN<5>")
	)
	(segment
		(start 85.949536 -276.841458)
		(end 85.941154 -276.846284)
		(width 0.09525)
		(layer "In13.Cu")
		(net "M_B_CPU1_SB_DQS_DN<5>")
	)
	(segment
		(start 51.15306 -285.994094)
		(end 50.757328 -285.830264)
		(width 0.16002)
		(layer "In13.Cu")
		(net "M_B_CPU1_SB_DQS_DN<5>")
	)
	(segment
		(start 76.03871 -276.107906)
		(end 75.979528 -276.048724)
		(width 0.09525)
		(layer "In13.Cu")
		(net "M_B_CPU1_SB_DQS_DN<5>")
	)
	(segment
		(start 57.711086 -285.830264)
		(end 56.910986 -286.630364)
		(width 0.16002)
		(layer "In13.Cu")
		(net "M_B_CPU1_SB_DQS_DN<5>")
	)
	(segment
		(start 75.955906 -276.048724)
		(end 69.975222 -276.048724)
		(width 0.16002)
		(layer "In13.Cu")
		(net "M_B_CPU1_SB_DQS_DN<5>")
	)
	(segment
		(start 76.376784 -276.107906)
		(end 76.03871 -276.107906)
		(width 0.09525)
		(layer "In13.Cu")
		(net "M_B_CPU1_SB_DQS_DN<5>")
	)
	(segment
		(start 49.454308 -285.972758)
		(end 48.021494 -285.972758)
		(width 0.16002)
		(layer "In13.Cu")
		(net "M_B_CPU1_SB_DQS_DN<5>")
	)
	(arc
		(start 85.572346 -276.841458)
		(mid 85.290914 -276.765703)
		(end 85.009482 -276.841458)
		(width 0.09525)
		(layer "In13.Cu")
		(net "M_B_CPU1_SB_DQS_DN<5>")
	)
	(arc
		(start 80.278732 -276.857714)
		(mid 80.12179 -276.89218)
		(end 79.964788 -276.857968)
		(width 0.09525)
		(layer "In13.Cu")
		(net "M_B_CPU1_SB_DQS_DN<5>")
	)
	(arc
		(start 83.692492 -276.841458)
		(mid 83.41106 -276.765703)
		(end 83.129628 -276.841458)
		(width 0.09525)
		(layer "In13.Cu")
		(net "M_B_CPU1_SB_DQS_DN<5>")
	)
	(arc
		(start 87.829644 -276.841458)
		(mid 87.645869 -276.89223)
		(end 87.460836 -276.846284)
		(width 0.09525)
		(layer "In13.Cu")
		(net "M_B_CPU1_SB_DQS_DN<5>")
	)
	(arc
		(start 88.392508 -276.841458)
		(mid 88.111076 -276.765703)
		(end 87.829644 -276.841458)
		(width 0.09525)
		(layer "In13.Cu")
		(net "M_B_CPU1_SB_DQS_DN<5>")
	)
	(arc
		(start 81.812384 -276.841458)
		(mid 81.554501 -276.766081)
		(end 81.291176 -276.81936)
		(width 0.09525)
		(layer "In13.Cu")
		(net "M_B_CPU1_SB_DQS_DN<5>")
	)
	(arc
		(start 81.291176 -276.81936)
		(mid 81.074163 -276.872764)
		(end 80.853534 -276.83714)
		(width 0.09525)
		(layer "In13.Cu")
		(net "M_B_CPU1_SB_DQS_DN<5>")
	)
	(arc
		(start 89.266268 -276.808438)
		(mid 89.256146 -276.804403)
		(end 89.245948 -276.800564)
		(width 0.09525)
		(layer "In13.Cu")
		(net "M_B_CPU1_SB_DQS_DN<5>")
	)
	(arc
		(start 82.181192 -276.846284)
		(mid 81.99616 -276.892198)
		(end 81.812384 -276.841458)
		(width 0.09525)
		(layer "In13.Cu")
		(net "M_B_CPU1_SB_DQS_DN<5>")
	)
	(arc
		(start 84.632546 -276.841458)
		(mid 84.351114 -276.765703)
		(end 84.069682 -276.841458)
		(width 0.09525)
		(layer "In13.Cu")
		(net "M_B_CPU1_SB_DQS_DN<5>")
	)
	(arc
		(start 85.941154 -276.846284)
		(mid 85.756122 -276.892198)
		(end 85.572346 -276.841458)
		(width 0.09525)
		(layer "In13.Cu")
		(net "M_B_CPU1_SB_DQS_DN<5>")
	)
	(arc
		(start 83.129628 -276.841458)
		(mid 82.945853 -276.89223)
		(end 82.76082 -276.846284)
		(width 0.09525)
		(layer "In13.Cu")
		(net "M_B_CPU1_SB_DQS_DN<5>")
	)
	(arc
		(start 84.069682 -276.841458)
		(mid 83.885907 -276.89223)
		(end 83.700874 -276.846284)
		(width 0.09525)
		(layer "In13.Cu")
		(net "M_B_CPU1_SB_DQS_DN<5>")
	)
	(arc
		(start 89.245948 -276.800564)
		(mid 89.003236 -276.767681)
		(end 88.769698 -276.841458)
		(width 0.09525)
		(layer "In13.Cu")
		(net "M_B_CPU1_SB_DQS_DN<5>")
	)
	(arc
		(start 86.5124 -276.841458)
		(mid 86.230968 -276.765703)
		(end 85.949536 -276.841458)
		(width 0.09525)
		(layer "In13.Cu")
		(net "M_B_CPU1_SB_DQS_DN<5>")
	)
	(arc
		(start 80.853534 -276.83714)
		(mid 80.564061 -276.789635)
		(end 80.278732 -276.857714)
		(width 0.09525)
		(layer "In13.Cu")
		(net "M_B_CPU1_SB_DQS_DN<5>")
	)
	(arc
		(start 82.752438 -276.841458)
		(mid 82.471006 -276.765703)
		(end 82.189574 -276.841458)
		(width 0.09525)
		(layer "In13.Cu")
		(net "M_B_CPU1_SB_DQS_DN<5>")
	)
	(arc
		(start 85.009482 -276.841458)
		(mid 84.821014 -276.892135)
		(end 84.632546 -276.841458)
		(width 0.09525)
		(layer "In13.Cu")
		(net "M_B_CPU1_SB_DQS_DN<5>")
	)
	(arc
		(start 87.452454 -276.841458)
		(mid 87.171022 -276.765703)
		(end 86.88959 -276.841458)
		(width 0.09525)
		(layer "In13.Cu")
		(net "M_B_CPU1_SB_DQS_DN<5>")
	)
	(arc
		(start 77.018896 -276.699726)
		(mid 76.972448 -276.690469)
		(end 76.933044 -276.664166)
		(width 0.09525)
		(layer "In13.Cu")
		(net "M_B_CPU1_SB_DQS_DN<5>")
	)
	(arc
		(start 88.769698 -276.841458)
		(mid 88.585923 -276.89223)
		(end 88.40089 -276.846284)
		(width 0.09525)
		(layer "In13.Cu")
		(net "M_B_CPU1_SB_DQS_DN<5>")
	)
	(arc
		(start 79.964788 -276.857968)
		(mid 79.609714 -276.739661)
		(end 79.237586 -276.699726)
		(width 0.09525)
		(layer "In13.Cu")
		(net "M_B_CPU1_SB_DQS_DN<5>")
	)
	(arc
		(start 86.881208 -276.846284)
		(mid 86.696176 -276.892198)
		(end 86.5124 -276.841458)
		(width 0.09525)
		(layer "In13.Cu")
		(net "M_B_CPU1_SB_DQS_DN<5>")
	)
	(segment
		(start 89.987882 -271.390364)
		(end 89.52103 -271.656302)
		(width 0.12954)
		(layer "F.Cu")
		(net "M_B_CPU1_SB_DQS_DN<4>")
	)
	(segment
		(start 76.29271 -270.484346)
		(end 76.03871 -270.484346)
		(width 0.09525)
		(layer "In13.Cu")
		(net "M_B_CPU1_SB_DQS_DN<4>")
	)
	(segment
		(start 77.37221 -270.695166)
		(end 76.50353 -270.695166)
		(width 0.09525)
		(layer "In13.Cu")
		(net "M_B_CPU1_SB_DQS_DN<4>")
	)
	(segment
		(start 59.972956 -276.155404)
		(end 59.21248 -276.470364)
		(width 0.16002)
		(layer "In13.Cu")
		(net "M_B_CPU1_SB_DQS_DN<4>")
	)
	(segment
		(start 85.949536 -271.981422)
		(end 85.941154 -271.986248)
		(width 0.09525)
		(layer "In13.Cu")
		(net "M_B_CPU1_SB_DQS_DN<4>")
	)
	(segment
		(start 59.21248 -276.470364)
		(end 57.731914 -276.470364)
		(width 0.16002)
		(layer "In13.Cu")
		(net "M_B_CPU1_SB_DQS_DN<4>")
	)
	(segment
		(start 76.03871 -270.484346)
		(end 75.979528 -270.425164)
		(width 0.09525)
		(layer "In13.Cu")
		(net "M_B_CPU1_SB_DQS_DN<4>")
	)
	(segment
		(start 57.466992 -276.735286)
		(end 57.2262 -276.835108)
		(width 0.16002)
		(layer "In13.Cu")
		(net "M_B_CPU1_SB_DQS_DN<4>")
	)
	(segment
		(start 48.026828 -276.628098)
		(end 47.784004 -276.385274)
		(width 0.16002)
		(layer "In13.Cu")
		(net "M_B_CPU1_SB_DQS_DN<4>")
	)
	(segment
		(start 65.703196 -270.425164)
		(end 59.972956 -276.155404)
		(width 0.16002)
		(layer "In13.Cu")
		(net "M_B_CPU1_SB_DQS_DN<4>")
	)
	(segment
		(start 49.554384 -276.419564)
		(end 49.050702 -276.628098)
		(width 0.16002)
		(layer "In13.Cu")
		(net "M_B_CPU1_SB_DQS_DN<4>")
	)
	(segment
		(start 82.189574 -271.981422)
		(end 82.181192 -271.986248)
		(width 0.09525)
		(layer "In13.Cu")
		(net "M_B_CPU1_SB_DQS_DN<4>")
	)
	(segment
		(start 89.367106 -271.921732)
		(end 89.266268 -271.948402)
		(width 0.09525)
		(layer "In13.Cu")
		(net "M_B_CPU1_SB_DQS_DN<4>")
	)
	(segment
		(start 51.127406 -276.808184)
		(end 50.738786 -276.419564)
		(width 0.16002)
		(layer "In13.Cu")
		(net "M_B_CPU1_SB_DQS_DN<4>")
	)
	(segment
		(start 75.955906 -270.425164)
		(end 65.703196 -270.425164)
		(width 0.16002)
		(layer "In13.Cu")
		(net "M_B_CPU1_SB_DQS_DN<4>")
	)
	(segment
		(start 53.464206 -276.808184)
		(end 51.127406 -276.808184)
		(width 0.16002)
		(layer "In13.Cu")
		(net "M_B_CPU1_SB_DQS_DN<4>")
	)
	(segment
		(start 78.583282 -271.906238)
		(end 77.37221 -270.695166)
		(width 0.09525)
		(layer "In13.Cu")
		(net "M_B_CPU1_SB_DQS_DN<4>")
	)
	(segment
		(start 88.40089 -271.986248)
		(end 88.392508 -271.981422)
		(width 0.09525)
		(layer "In13.Cu")
		(net "M_B_CPU1_SB_DQS_DN<4>")
	)
	(segment
		(start 57.2262 -276.835108)
		(end 54.972712 -277.283164)
		(width 0.16002)
		(layer "In13.Cu")
		(net "M_B_CPU1_SB_DQS_DN<4>")
	)
	(segment
		(start 79.950056 -271.991074)
		(end 79.933292 -271.981422)
		(width 0.09525)
		(layer "In13.Cu")
		(net "M_B_CPU1_SB_DQS_DN<4>")
	)
	(segment
		(start 76.50353 -270.695166)
		(end 76.29271 -270.484346)
		(width 0.09525)
		(layer "In13.Cu")
		(net "M_B_CPU1_SB_DQS_DN<4>")
	)
	(segment
		(start 83.700874 -271.986248)
		(end 83.692492 -271.981422)
		(width 0.09525)
		(layer "In13.Cu")
		(net "M_B_CPU1_SB_DQS_DN<4>")
	)
	(segment
		(start 87.460836 -271.986248)
		(end 87.452454 -271.981422)
		(width 0.09525)
		(layer "In13.Cu")
		(net "M_B_CPU1_SB_DQS_DN<4>")
	)
	(segment
		(start 53.939186 -277.283164)
		(end 53.464206 -276.808184)
		(width 0.16002)
		(layer "In13.Cu")
		(net "M_B_CPU1_SB_DQS_DN<4>")
	)
	(segment
		(start 57.731914 -276.470364)
		(end 57.466992 -276.735286)
		(width 0.16002)
		(layer "In13.Cu")
		(net "M_B_CPU1_SB_DQS_DN<4>")
	)
	(segment
		(start 49.050702 -276.628098)
		(end 48.026828 -276.628098)
		(width 0.16002)
		(layer "In13.Cu")
		(net "M_B_CPU1_SB_DQS_DN<4>")
	)
	(segment
		(start 79.652876 -271.906238)
		(end 78.583282 -271.906238)
		(width 0.09525)
		(layer "In13.Cu")
		(net "M_B_CPU1_SB_DQS_DN<4>")
	)
	(segment
		(start 89.52103 -271.656302)
		(end 89.367106 -271.921732)
		(width 0.09525)
		(layer "In13.Cu")
		(net "M_B_CPU1_SB_DQS_DN<4>")
	)
	(segment
		(start 50.738786 -276.419564)
		(end 49.554384 -276.419564)
		(width 0.16002)
		(layer "In13.Cu")
		(net "M_B_CPU1_SB_DQS_DN<4>")
	)
	(segment
		(start 54.972712 -277.283164)
		(end 53.939186 -277.283164)
		(width 0.16002)
		(layer "In13.Cu")
		(net "M_B_CPU1_SB_DQS_DN<4>")
	)
	(segment
		(start 82.76082 -271.986248)
		(end 82.752438 -271.981422)
		(width 0.09525)
		(layer "In13.Cu")
		(net "M_B_CPU1_SB_DQS_DN<4>")
	)
	(segment
		(start 86.88959 -271.981422)
		(end 86.881208 -271.986248)
		(width 0.09525)
		(layer "In13.Cu")
		(net "M_B_CPU1_SB_DQS_DN<4>")
	)
	(segment
		(start 75.979528 -270.425164)
		(end 75.955906 -270.425164)
		(width 0.09525)
		(layer "In13.Cu")
		(net "M_B_CPU1_SB_DQS_DN<4>")
	)
	(arc
		(start 89.245948 -271.940528)
		(mid 89.003236 -271.907645)
		(end 88.769698 -271.981422)
		(width 0.09525)
		(layer "In13.Cu")
		(net "M_B_CPU1_SB_DQS_DN<4>")
	)
	(arc
		(start 86.5124 -271.981422)
		(mid 86.230968 -271.905667)
		(end 85.949536 -271.981422)
		(width 0.09525)
		(layer "In13.Cu")
		(net "M_B_CPU1_SB_DQS_DN<4>")
	)
	(arc
		(start 85.941154 -271.986248)
		(mid 85.756122 -272.032162)
		(end 85.572346 -271.981422)
		(width 0.09525)
		(layer "In13.Cu")
		(net "M_B_CPU1_SB_DQS_DN<4>")
	)
	(arc
		(start 88.392508 -271.981422)
		(mid 88.111076 -271.905667)
		(end 87.829644 -271.981422)
		(width 0.09525)
		(layer "In13.Cu")
		(net "M_B_CPU1_SB_DQS_DN<4>")
	)
	(arc
		(start 80.872584 -271.981422)
		(mid 80.591152 -271.905667)
		(end 80.30972 -271.981422)
		(width 0.09525)
		(layer "In13.Cu")
		(net "M_B_CPU1_SB_DQS_DN<4>")
	)
	(arc
		(start 80.30972 -271.981422)
		(mid 80.131114 -272.03209)
		(end 79.950056 -271.991074)
		(width 0.09525)
		(layer "In13.Cu")
		(net "M_B_CPU1_SB_DQS_DN<4>")
	)
	(arc
		(start 79.933292 -271.981422)
		(mid 79.798044 -271.925315)
		(end 79.652876 -271.906238)
		(width 0.09525)
		(layer "In13.Cu")
		(net "M_B_CPU1_SB_DQS_DN<4>")
	)
	(arc
		(start 81.24952 -271.981422)
		(mid 81.061052 -272.032099)
		(end 80.872584 -271.981422)
		(width 0.09525)
		(layer "In13.Cu")
		(net "M_B_CPU1_SB_DQS_DN<4>")
	)
	(arc
		(start 82.181192 -271.986248)
		(mid 81.99616 -272.032162)
		(end 81.812384 -271.981422)
		(width 0.09525)
		(layer "In13.Cu")
		(net "M_B_CPU1_SB_DQS_DN<4>")
	)
	(arc
		(start 86.881208 -271.986248)
		(mid 86.696176 -272.032162)
		(end 86.5124 -271.981422)
		(width 0.09525)
		(layer "In13.Cu")
		(net "M_B_CPU1_SB_DQS_DN<4>")
	)
	(arc
		(start 81.812384 -271.981422)
		(mid 81.530952 -271.905667)
		(end 81.24952 -271.981422)
		(width 0.09525)
		(layer "In13.Cu")
		(net "M_B_CPU1_SB_DQS_DN<4>")
	)
	(arc
		(start 83.692492 -271.981422)
		(mid 83.41106 -271.905667)
		(end 83.129628 -271.981422)
		(width 0.09525)
		(layer "In13.Cu")
		(net "M_B_CPU1_SB_DQS_DN<4>")
	)
	(arc
		(start 84.069682 -271.981422)
		(mid 83.885907 -272.032194)
		(end 83.700874 -271.986248)
		(width 0.09525)
		(layer "In13.Cu")
		(net "M_B_CPU1_SB_DQS_DN<4>")
	)
	(arc
		(start 85.009482 -271.981422)
		(mid 84.821014 -272.032099)
		(end 84.632546 -271.981422)
		(width 0.09525)
		(layer "In13.Cu")
		(net "M_B_CPU1_SB_DQS_DN<4>")
	)
	(arc
		(start 84.632546 -271.981422)
		(mid 84.351114 -271.905667)
		(end 84.069682 -271.981422)
		(width 0.09525)
		(layer "In13.Cu")
		(net "M_B_CPU1_SB_DQS_DN<4>")
	)
	(arc
		(start 82.752438 -271.981422)
		(mid 82.471006 -271.905667)
		(end 82.189574 -271.981422)
		(width 0.09525)
		(layer "In13.Cu")
		(net "M_B_CPU1_SB_DQS_DN<4>")
	)
	(arc
		(start 87.452454 -271.981422)
		(mid 87.171022 -271.905667)
		(end 86.88959 -271.981422)
		(width 0.09525)
		(layer "In13.Cu")
		(net "M_B_CPU1_SB_DQS_DN<4>")
	)
	(arc
		(start 83.129628 -271.981422)
		(mid 82.945853 -272.032194)
		(end 82.76082 -271.986248)
		(width 0.09525)
		(layer "In13.Cu")
		(net "M_B_CPU1_SB_DQS_DN<4>")
	)
	(arc
		(start 89.266268 -271.948402)
		(mid 89.256146 -271.944367)
		(end 89.245948 -271.940528)
		(width 0.09525)
		(layer "In13.Cu")
		(net "M_B_CPU1_SB_DQS_DN<4>")
	)
	(arc
		(start 88.769698 -271.981422)
		(mid 88.585923 -272.032194)
		(end 88.40089 -271.986248)
		(width 0.09525)
		(layer "In13.Cu")
		(net "M_B_CPU1_SB_DQS_DN<4>")
	)
	(arc
		(start 87.829644 -271.981422)
		(mid 87.645869 -272.032194)
		(end 87.460836 -271.986248)
		(width 0.09525)
		(layer "In13.Cu")
		(net "M_B_CPU1_SB_DQS_DN<4>")
	)
	(arc
		(start 85.572346 -271.981422)
		(mid 85.290914 -271.905667)
		(end 85.009482 -271.981422)
		(width 0.09525)
		(layer "In13.Cu")
		(net "M_B_CPU1_SB_DQS_DN<4>")
	)
	(segment
		(start 88.107774 -290.830254)
		(end 87.640922 -291.096192)
		(width 0.12954)
		(layer "F.Cu")
		(net "M_B_CPU1_SB_DQS_DN<3>")
	)
	(segment
		(start 67.065144 -306.785264)
		(end 67.438778 -306.41163)
		(width 0.16002)
		(layer "In13.Cu")
		(net "M_B_CPU1_SB_DQS_DN<3>")
	)
	(segment
		(start 63.317882 -310.532526)
		(end 63.318136 -310.005222)
		(width 0.16002)
		(layer "In13.Cu")
		(net "M_B_CPU1_SB_DQS_DN<3>")
	)
	(segment
		(start 61.570616 -312.279792)
		(end 61.94425 -311.906158)
		(width 0.16002)
		(layer "In13.Cu")
		(net "M_B_CPU1_SB_DQS_DN<3>")
	)
	(segment
		(start 67.332352 -305.777646)
		(end 67.332352 -305.500786)
		(width 0.16002)
		(layer "In13.Cu")
		(net "M_B_CPU1_SB_DQS_DN<3>")
	)
	(segment
		(start 82.181192 -290.766246)
		(end 82.189574 -290.771072)
		(width 0.09525)
		(layer "In13.Cu")
		(net "M_B_CPU1_SB_DQS_DN<3>")
	)
	(segment
		(start 60.009532 -312.823606)
		(end 60.553346 -312.279792)
		(width 0.16002)
		(layer "In13.Cu")
		(net "M_B_CPU1_SB_DQS_DN<3>")
	)
	(segment
		(start 70.079616 -302.753522)
		(end 73.74001 -299.093128)
		(width 0.16002)
		(layer "In13.Cu")
		(net "M_B_CPU1_SB_DQS_DN<3>")
	)
	(segment
		(start 63.40729 -309.425848)
		(end 63.683896 -309.425848)
		(width 0.16002)
		(layer "In13.Cu")
		(net "M_B_CPU1_SB_DQS_DN<3>")
	)
	(segment
		(start 67.911472 -305.411632)
		(end 68.438776 -305.411632)
		(width 0.16002)
		(layer "In13.Cu")
		(net "M_B_CPU1_SB_DQS_DN<3>")
	)
	(segment
		(start 70.186296 -303.137062)
		(end 70.079616 -303.030382)
		(width 0.16002)
		(layer "In13.Cu")
		(net "M_B_CPU1_SB_DQS_DN<3>")
	)
	(segment
		(start 51.884072 -313.78525)
		(end 52.157884 -313.511438)
		(width 0.16002)
		(layer "In13.Cu")
		(net "M_B_CPU1_SB_DQS_DN<3>")
	)
	(segment
		(start 66.53784 -306.785264)
		(end 67.065144 -306.785264)
		(width 0.16002)
		(layer "In13.Cu")
		(net "M_B_CPU1_SB_DQS_DN<3>")
	)
	(segment
		(start 65.95872 -306.874418)
		(end 66.154554 -306.678584)
		(width 0.16002)
		(layer "In13.Cu")
		(net "M_B_CPU1_SB_DQS_DN<3>")
	)
	(segment
		(start 69.812408 -304.038)
		(end 70.186042 -303.664366)
		(width 0.16002)
		(layer "In13.Cu")
		(net "M_B_CPU1_SB_DQS_DN<3>")
	)
	(segment
		(start 64.31788 -309.532528)
		(end 64.691514 -309.158894)
		(width 0.16002)
		(layer "In13.Cu")
		(net "M_B_CPU1_SB_DQS_DN<3>")
	)
	(segment
		(start 64.691768 -308.63159)
		(end 64.585088 -308.52491)
		(width 0.16002)
		(layer "In13.Cu")
		(net "M_B_CPU1_SB_DQS_DN<3>")
	)
	(segment
		(start 76.363068 -295.195752)
		(end 76.62164 -294.936926)
		(width 0.09525)
		(layer "In13.Cu")
		(net "M_B_CPU1_SB_DQS_DN<3>")
	)
	(segment
		(start 87.794846 -290.830762)
		(end 87.640922 -291.096192)
		(width 0.09525)
		(layer "In13.Cu")
		(net "M_B_CPU1_SB_DQS_DN<3>")
	)
	(segment
		(start 55.187342 -312.993024)
		(end 55.450994 -312.993024)
		(width 0.16002)
		(layer "In13.Cu")
		(net "M_B_CPU1_SB_DQS_DN<3>")
	)
	(segment
		(start 63.790576 -309.532528)
		(end 64.31788 -309.532528)
		(width 0.16002)
		(layer "In13.Cu")
		(net "M_B_CPU1_SB_DQS_DN<3>")
	)
	(segment
		(start 65.691512 -308.158896)
		(end 66.065146 -307.785262)
		(width 0.16002)
		(layer "In13.Cu")
		(net "M_B_CPU1_SB_DQS_DN<3>")
	)
	(segment
		(start 66.065146 -307.785262)
		(end 66.0654 -307.257958)
		(width 0.16002)
		(layer "In13.Cu")
		(net "M_B_CPU1_SB_DQS_DN<3>")
	)
	(segment
		(start 54.668928 -313.511438)
		(end 55.187342 -312.993024)
		(width 0.16002)
		(layer "In13.Cu")
		(net "M_B_CPU1_SB_DQS_DN<3>")
	)
	(segment
		(start 76.62164 -294.936926)
		(end 76.62164 -294.305482)
		(width 0.09525)
		(layer "In13.Cu")
		(net "M_B_CPU1_SB_DQS_DN<3>")
	)
	(segment
		(start 68.705984 -304.127154)
		(end 68.901818 -303.93132)
		(width 0.16002)
		(layer "In13.Cu")
		(net "M_B_CPU1_SB_DQS_DN<3>")
	)
	(segment
		(start 62.944248 -310.90616)
		(end 63.317882 -310.532526)
		(width 0.16002)
		(layer "In13.Cu")
		(net "M_B_CPU1_SB_DQS_DN<3>")
	)
	(segment
		(start 66.43116 -306.678584)
		(end 66.53784 -306.785264)
		(width 0.16002)
		(layer "In13.Cu")
		(net "M_B_CPU1_SB_DQS_DN<3>")
	)
	(segment
		(start 82.752438 -290.771072)
		(end 82.76082 -290.766246)
		(width 0.09525)
		(layer "In13.Cu")
		(net "M_B_CPU1_SB_DQS_DN<3>")
	)
	(segment
		(start 64.585088 -308.52491)
		(end 64.585088 -308.24805)
		(width 0.16002)
		(layer "In13.Cu")
		(net "M_B_CPU1_SB_DQS_DN<3>")
	)
	(segment
		(start 67.332352 -305.500786)
		(end 67.528186 -305.304952)
		(width 0.16002)
		(layer "In13.Cu")
		(net "M_B_CPU1_SB_DQS_DN<3>")
	)
	(segment
		(start 56.145176 -313.687206)
		(end 57.010808 -313.687206)
		(width 0.16002)
		(layer "In13.Cu")
		(net "M_B_CPU1_SB_DQS_DN<3>")
	)
	(segment
		(start 67.438778 -306.194206)
		(end 67.439032 -305.884326)
		(width 0.16002)
		(layer "In13.Cu")
		(net "M_B_CPU1_SB_DQS_DN<3>")
	)
	(segment
		(start 68.901818 -303.93132)
		(end 69.178424 -303.93132)
		(width 0.16002)
		(layer "In13.Cu")
		(net "M_B_CPU1_SB_DQS_DN<3>")
	)
	(segment
		(start 61.94425 -311.906158)
		(end 61.944504 -311.378854)
		(width 0.16002)
		(layer "In13.Cu")
		(net "M_B_CPU1_SB_DQS_DN<3>")
	)
	(segment
		(start 57.874408 -312.823606)
		(end 60.009532 -312.823606)
		(width 0.16002)
		(layer "In13.Cu")
		(net "M_B_CPU1_SB_DQS_DN<3>")
	)
	(segment
		(start 57.010808 -313.687206)
		(end 57.874408 -312.823606)
		(width 0.16002)
		(layer "In13.Cu")
		(net "M_B_CPU1_SB_DQS_DN<3>")
	)
	(segment
		(start 62.033658 -310.79948)
		(end 62.310264 -310.79948)
		(width 0.16002)
		(layer "In13.Cu")
		(net "M_B_CPU1_SB_DQS_DN<3>")
	)
	(segment
		(start 76.62164 -294.305482)
		(end 76.821538 -293.822882)
		(width 0.09525)
		(layer "In13.Cu")
		(net "M_B_CPU1_SB_DQS_DN<3>")
	)
	(segment
		(start 65.164208 -308.158896)
		(end 65.691512 -308.158896)
		(width 0.16002)
		(layer "In13.Cu")
		(net "M_B_CPU1_SB_DQS_DN<3>")
	)
	(segment
		(start 61.944504 -311.378854)
		(end 61.837824 -311.272174)
		(width 0.16002)
		(layer "In13.Cu")
		(net "M_B_CPU1_SB_DQS_DN<3>")
	)
	(segment
		(start 64.585088 -308.24805)
		(end 64.780922 -308.052216)
		(width 0.16002)
		(layer "In13.Cu")
		(net "M_B_CPU1_SB_DQS_DN<3>")
	)
	(segment
		(start 61.837824 -310.995314)
		(end 62.033658 -310.79948)
		(width 0.16002)
		(layer "In13.Cu")
		(net "M_B_CPU1_SB_DQS_DN<3>")
	)
	(segment
		(start 76.363068 -295.278556)
		(end 76.363068 -295.195752)
		(width 0.09525)
		(layer "In13.Cu")
		(net "M_B_CPU1_SB_DQS_DN<3>")
	)
	(segment
		(start 63.318136 -310.005222)
		(end 63.211456 -309.898542)
		(width 0.16002)
		(layer "In13.Cu")
		(net "M_B_CPU1_SB_DQS_DN<3>")
	)
	(segment
		(start 67.439032 -305.884326)
		(end 67.332352 -305.777646)
		(width 0.16002)
		(layer "In13.Cu")
		(net "M_B_CPU1_SB_DQS_DN<3>")
	)
	(segment
		(start 69.285104 -304.038)
		(end 69.812408 -304.038)
		(width 0.16002)
		(layer "In13.Cu")
		(net "M_B_CPU1_SB_DQS_DN<3>")
	)
	(segment
		(start 62.416944 -310.90616)
		(end 62.944248 -310.90616)
		(width 0.16002)
		(layer "In13.Cu")
		(net "M_B_CPU1_SB_DQS_DN<3>")
	)
	(segment
		(start 87.771478 -290.743894)
		(end 87.794846 -290.830762)
		(width 0.09525)
		(layer "In13.Cu")
		(net "M_B_CPU1_SB_DQS_DN<3>")
	)
	(segment
		(start 63.211456 -309.621682)
		(end 63.40729 -309.425848)
		(width 0.16002)
		(layer "In13.Cu")
		(net "M_B_CPU1_SB_DQS_DN<3>")
	)
	(segment
		(start 63.683896 -309.425848)
		(end 63.790576 -309.532528)
		(width 0.16002)
		(layer "In13.Cu")
		(net "M_B_CPU1_SB_DQS_DN<3>")
	)
	(segment
		(start 68.705984 -304.404014)
		(end 68.705984 -304.127154)
		(width 0.16002)
		(layer "In13.Cu")
		(net "M_B_CPU1_SB_DQS_DN<3>")
	)
	(segment
		(start 78.435962 -291.631878)
		(end 79.800704 -290.719764)
		(width 0.09525)
		(layer "In13.Cu")
		(net "M_B_CPU1_SB_DQS_DN<3>")
	)
	(segment
		(start 73.74001 -299.093128)
		(end 73.74001 -297.901106)
		(width 0.16002)
		(layer "In13.Cu")
		(net "M_B_CPU1_SB_DQS_DN<3>")
	)
	(segment
		(start 70.186042 -303.664366)
		(end 70.186296 -303.137062)
		(width 0.16002)
		(layer "In13.Cu")
		(net "M_B_CPU1_SB_DQS_DN<3>")
	)
	(segment
		(start 85.941154 -290.766246)
		(end 85.949536 -290.771072)
		(width 0.09525)
		(layer "In13.Cu")
		(net "M_B_CPU1_SB_DQS_DN<3>")
	)
	(segment
		(start 67.438778 -306.41163)
		(end 67.438778 -306.194206)
		(width 0.16002)
		(layer "In13.Cu")
		(net "M_B_CPU1_SB_DQS_DN<3>")
	)
	(segment
		(start 68.812664 -304.510694)
		(end 68.705984 -304.404014)
		(width 0.16002)
		(layer "In13.Cu")
		(net "M_B_CPU1_SB_DQS_DN<3>")
	)
	(segment
		(start 70.079616 -303.030382)
		(end 70.079616 -302.753522)
		(width 0.16002)
		(layer "In13.Cu")
		(net "M_B_CPU1_SB_DQS_DN<3>")
	)
	(segment
		(start 87.452454 -290.771072)
		(end 87.460836 -290.766246)
		(width 0.09525)
		(layer "In13.Cu")
		(net "M_B_CPU1_SB_DQS_DN<3>")
	)
	(segment
		(start 65.95872 -307.151278)
		(end 65.95872 -306.874418)
		(width 0.16002)
		(layer "In13.Cu")
		(net "M_B_CPU1_SB_DQS_DN<3>")
	)
	(segment
		(start 68.81241 -305.037998)
		(end 68.812664 -304.510694)
		(width 0.16002)
		(layer "In13.Cu")
		(net "M_B_CPU1_SB_DQS_DN<3>")
	)
	(segment
		(start 66.0654 -307.257958)
		(end 65.95872 -307.151278)
		(width 0.16002)
		(layer "In13.Cu")
		(net "M_B_CPU1_SB_DQS_DN<3>")
	)
	(segment
		(start 73.74001 -297.901106)
		(end 76.346304 -295.29532)
		(width 0.16002)
		(layer "In13.Cu")
		(net "M_B_CPU1_SB_DQS_DN<3>")
	)
	(segment
		(start 63.211456 -309.898542)
		(end 63.211456 -309.621682)
		(width 0.16002)
		(layer "In13.Cu")
		(net "M_B_CPU1_SB_DQS_DN<3>")
	)
	(segment
		(start 83.692492 -290.771072)
		(end 83.700874 -290.766246)
		(width 0.09525)
		(layer "In13.Cu")
		(net "M_B_CPU1_SB_DQS_DN<3>")
	)
	(segment
		(start 86.881208 -290.766246)
		(end 86.88959 -290.771072)
		(width 0.09525)
		(layer "In13.Cu")
		(net "M_B_CPU1_SB_DQS_DN<3>")
	)
	(segment
		(start 64.780922 -308.052216)
		(end 65.057528 -308.052216)
		(width 0.16002)
		(layer "In13.Cu")
		(net "M_B_CPU1_SB_DQS_DN<3>")
	)
	(segment
		(start 67.528186 -305.304952)
		(end 67.804792 -305.304952)
		(width 0.16002)
		(layer "In13.Cu")
		(net "M_B_CPU1_SB_DQS_DN<3>")
	)
	(segment
		(start 55.450994 -312.993024)
		(end 56.145176 -313.687206)
		(width 0.16002)
		(layer "In13.Cu")
		(net "M_B_CPU1_SB_DQS_DN<3>")
	)
	(segment
		(start 69.178424 -303.93132)
		(end 69.285104 -304.038)
		(width 0.16002)
		(layer "In13.Cu")
		(net "M_B_CPU1_SB_DQS_DN<3>")
	)
	(segment
		(start 76.821538 -293.822882)
		(end 77.274928 -293.369492)
		(width 0.09525)
		(layer "In13.Cu")
		(net "M_B_CPU1_SB_DQS_DN<3>")
	)
	(segment
		(start 60.553346 -312.279792)
		(end 61.570616 -312.279792)
		(width 0.16002)
		(layer "In13.Cu")
		(net "M_B_CPU1_SB_DQS_DN<3>")
	)
	(segment
		(start 76.346304 -295.29532)
		(end 76.363068 -295.278556)
		(width 0.09525)
		(layer "In13.Cu")
		(net "M_B_CPU1_SB_DQS_DN<3>")
	)
	(segment
		(start 67.804792 -305.304952)
		(end 67.911472 -305.411632)
		(width 0.16002)
		(layer "In13.Cu")
		(net "M_B_CPU1_SB_DQS_DN<3>")
	)
	(segment
		(start 61.837824 -311.272174)
		(end 61.837824 -310.995314)
		(width 0.16002)
		(layer "In13.Cu")
		(net "M_B_CPU1_SB_DQS_DN<3>")
	)
	(segment
		(start 77.274928 -293.369492)
		(end 78.435962 -291.631878)
		(width 0.09525)
		(layer "In13.Cu")
		(net "M_B_CPU1_SB_DQS_DN<3>")
	)
	(segment
		(start 65.057528 -308.052216)
		(end 65.164208 -308.158896)
		(width 0.16002)
		(layer "In13.Cu")
		(net "M_B_CPU1_SB_DQS_DN<3>")
	)
	(segment
		(start 68.438776 -305.411632)
		(end 68.81241 -305.037998)
		(width 0.16002)
		(layer "In13.Cu")
		(net "M_B_CPU1_SB_DQS_DN<3>")
	)
	(segment
		(start 62.310264 -310.79948)
		(end 62.416944 -310.90616)
		(width 0.16002)
		(layer "In13.Cu")
		(net "M_B_CPU1_SB_DQS_DN<3>")
	)
	(segment
		(start 64.691514 -309.158894)
		(end 64.691768 -308.63159)
		(width 0.16002)
		(layer "In13.Cu")
		(net "M_B_CPU1_SB_DQS_DN<3>")
	)
	(segment
		(start 52.157884 -313.511438)
		(end 54.668928 -313.511438)
		(width 0.16002)
		(layer "In13.Cu")
		(net "M_B_CPU1_SB_DQS_DN<3>")
	)
	(segment
		(start 79.800704 -290.719764)
		(end 80.120998 -290.719764)
		(width 0.09525)
		(layer "In13.Cu")
		(net "M_B_CPU1_SB_DQS_DN<3>")
	)
	(segment
		(start 66.154554 -306.678584)
		(end 66.43116 -306.678584)
		(width 0.16002)
		(layer "In13.Cu")
		(net "M_B_CPU1_SB_DQS_DN<3>")
	)
	(arc
		(start 84.069682 -290.771072)
		(mid 84.351114 -290.846827)
		(end 84.632546 -290.771072)
		(width 0.09525)
		(layer "In13.Cu")
		(net "M_B_CPU1_SB_DQS_DN<3>")
	)
	(arc
		(start 83.700874 -290.766246)
		(mid 83.885906 -290.720332)
		(end 84.069682 -290.771072)
		(width 0.09525)
		(layer "In13.Cu")
		(net "M_B_CPU1_SB_DQS_DN<3>")
	)
	(arc
		(start 81.812384 -290.771072)
		(mid 81.996159 -290.7203)
		(end 82.181192 -290.766246)
		(width 0.09525)
		(layer "In13.Cu")
		(net "M_B_CPU1_SB_DQS_DN<3>")
	)
	(arc
		(start 85.572346 -290.771072)
		(mid 85.756121 -290.7203)
		(end 85.941154 -290.766246)
		(width 0.09525)
		(layer "In13.Cu")
		(net "M_B_CPU1_SB_DQS_DN<3>")
	)
	(arc
		(start 85.009482 -290.771072)
		(mid 85.290914 -290.846827)
		(end 85.572346 -290.771072)
		(width 0.09525)
		(layer "In13.Cu")
		(net "M_B_CPU1_SB_DQS_DN<3>")
	)
	(arc
		(start 83.129628 -290.771072)
		(mid 83.41106 -290.846827)
		(end 83.692492 -290.771072)
		(width 0.09525)
		(layer "In13.Cu")
		(net "M_B_CPU1_SB_DQS_DN<3>")
	)
	(arc
		(start 82.76082 -290.766246)
		(mid 82.945852 -290.720332)
		(end 83.129628 -290.771072)
		(width 0.09525)
		(layer "In13.Cu")
		(net "M_B_CPU1_SB_DQS_DN<3>")
	)
	(arc
		(start 80.30972 -290.771072)
		(mid 80.591152 -290.846827)
		(end 80.872584 -290.771072)
		(width 0.09525)
		(layer "In13.Cu")
		(net "M_B_CPU1_SB_DQS_DN<3>")
	)
	(arc
		(start 81.24952 -290.771072)
		(mid 81.530952 -290.846827)
		(end 81.812384 -290.771072)
		(width 0.09525)
		(layer "In13.Cu")
		(net "M_B_CPU1_SB_DQS_DN<3>")
	)
	(arc
		(start 84.632546 -290.771072)
		(mid 84.821014 -290.720395)
		(end 85.009482 -290.771072)
		(width 0.09525)
		(layer "In13.Cu")
		(net "M_B_CPU1_SB_DQS_DN<3>")
	)
	(arc
		(start 80.120998 -290.719764)
		(mid 80.218744 -290.732959)
		(end 80.30972 -290.771072)
		(width 0.09525)
		(layer "In13.Cu")
		(net "M_B_CPU1_SB_DQS_DN<3>")
	)
	(arc
		(start 85.949536 -290.771072)
		(mid 86.230968 -290.846827)
		(end 86.5124 -290.771072)
		(width 0.09525)
		(layer "In13.Cu")
		(net "M_B_CPU1_SB_DQS_DN<3>")
	)
	(arc
		(start 86.5124 -290.771072)
		(mid 86.696175 -290.7203)
		(end 86.881208 -290.766246)
		(width 0.09525)
		(layer "In13.Cu")
		(net "M_B_CPU1_SB_DQS_DN<3>")
	)
	(arc
		(start 82.189574 -290.771072)
		(mid 82.471006 -290.846827)
		(end 82.752438 -290.771072)
		(width 0.09525)
		(layer "In13.Cu")
		(net "M_B_CPU1_SB_DQS_DN<3>")
	)
	(arc
		(start 87.460836 -290.766246)
		(mid 87.613731 -290.721418)
		(end 87.771478 -290.743894)
		(width 0.09525)
		(layer "In13.Cu")
		(net "M_B_CPU1_SB_DQS_DN<3>")
	)
	(arc
		(start 86.88959 -290.771072)
		(mid 87.171022 -290.846827)
		(end 87.452454 -290.771072)
		(width 0.09525)
		(layer "In13.Cu")
		(net "M_B_CPU1_SB_DQS_DN<3>")
	)
	(arc
		(start 80.872584 -290.771072)
		(mid 81.061052 -290.720395)
		(end 81.24952 -290.771072)
		(width 0.09525)
		(layer "In13.Cu")
		(net "M_B_CPU1_SB_DQS_DN<3>")
	)
	(segment
		(start 88.107774 -285.970472)
		(end 87.640922 -286.23641)
		(width 0.12954)
		(layer "F.Cu")
		(net "M_B_CPU1_SB_DQS_DN<2>")
	)
	(segment
		(start 86.88959 -285.91129)
		(end 86.881208 -285.906464)
		(width 0.09525)
		(layer "In13.Cu")
		(net "M_B_CPU1_SB_DQS_DN<2>")
	)
	(segment
		(start 77.51953 -286.549846)
		(end 76.303378 -286.549846)
		(width 0.09525)
		(layer "In13.Cu")
		(net "M_B_CPU1_SB_DQS_DN<2>")
	)
	(segment
		(start 66.122042 -298.040806)
		(end 65.748154 -298.414694)
		(width 0.16002)
		(layer "In13.Cu")
		(net "M_B_CPU1_SB_DQS_DN<2>")
	)
	(segment
		(start 64.73317 -298.203112)
		(end 64.537336 -298.398946)
		(width 0.16002)
		(layer "In13.Cu")
		(net "M_B_CPU1_SB_DQS_DN<2>")
	)
	(segment
		(start 66.383662 -296.82948)
		(end 66.106802 -296.82948)
		(width 0.16002)
		(layer "In13.Cu")
		(net "M_B_CPU1_SB_DQS_DN<2>")
	)
	(segment
		(start 64.537336 -298.398946)
		(end 64.537336 -298.675806)
		(width 0.16002)
		(layer "In13.Cu")
		(net "M_B_CPU1_SB_DQS_DN<2>")
	)
	(segment
		(start 64.374522 -299.788326)
		(end 63.847726 -299.788072)
		(width 0.16002)
		(layer "In13.Cu")
		(net "M_B_CPU1_SB_DQS_DN<2>")
	)
	(segment
		(start 65.910968 -297.025314)
		(end 65.910968 -297.302174)
		(width 0.16002)
		(layer "In13.Cu")
		(net "M_B_CPU1_SB_DQS_DN<2>")
	)
	(segment
		(start 78.075028 -285.994348)
		(end 77.51953 -286.549846)
		(width 0.09525)
		(layer "In13.Cu")
		(net "M_B_CPU1_SB_DQS_DN<2>")
	)
	(segment
		(start 63.359538 -299.576744)
		(end 63.163704 -299.772578)
		(width 0.16002)
		(layer "In13.Cu")
		(net "M_B_CPU1_SB_DQS_DN<2>")
	)
	(segment
		(start 67.121786 -297.041062)
		(end 66.59499 -297.040808)
		(width 0.16002)
		(layer "In13.Cu")
		(net "M_B_CPU1_SB_DQS_DN<2>")
	)
	(segment
		(start 56.139588 -304.776124)
		(end 55.764684 -304.40122)
		(width 0.16002)
		(layer "In13.Cu")
		(net "M_B_CPU1_SB_DQS_DN<2>")
	)
	(segment
		(start 66.59499 -297.040808)
		(end 66.383662 -296.82948)
		(width 0.16002)
		(layer "In13.Cu")
		(net "M_B_CPU1_SB_DQS_DN<2>")
	)
	(segment
		(start 53.237638 -304.161444)
		(end 52.157884 -304.161444)
		(width 0.16002)
		(layer "In13.Cu")
		(net "M_B_CPU1_SB_DQS_DN<2>")
	)
	(segment
		(start 63.847726 -299.788072)
		(end 63.636398 -299.576744)
		(width 0.16002)
		(layer "In13.Cu")
		(net "M_B_CPU1_SB_DQS_DN<2>")
	)
	(segment
		(start 63.163704 -299.772578)
		(end 63.163704 -300.049438)
		(width 0.16002)
		(layer "In13.Cu")
		(net "M_B_CPU1_SB_DQS_DN<2>")
	)
	(segment
		(start 76.18603 -286.667194)
		(end 76.186284 -286.749998)
		(width 0.09525)
		(layer "In13.Cu")
		(net "M_B_CPU1_SB_DQS_DN<2>")
	)
	(segment
		(start 76.303378 -286.549846)
		(end 76.18603 -286.667194)
		(width 0.09525)
		(layer "In13.Cu")
		(net "M_B_CPU1_SB_DQS_DN<2>")
	)
	(segment
		(start 63.00089 -301.161958)
		(end 62.474094 -301.161704)
		(width 0.16002)
		(layer "In13.Cu")
		(net "M_B_CPU1_SB_DQS_DN<2>")
	)
	(segment
		(start 87.460836 -285.906464)
		(end 87.452454 -285.91129)
		(width 0.09525)
		(layer "In13.Cu")
		(net "M_B_CPU1_SB_DQS_DN<2>")
	)
	(segment
		(start 67.2846 -295.651682)
		(end 67.2846 -295.928542)
		(width 0.16002)
		(layer "In13.Cu")
		(net "M_B_CPU1_SB_DQS_DN<2>")
	)
	(segment
		(start 87.794846 -285.97098)
		(end 87.771478 -285.884112)
		(width 0.09525)
		(layer "In13.Cu")
		(net "M_B_CPU1_SB_DQS_DN<2>")
	)
	(segment
		(start 55.764684 -304.40122)
		(end 55.764684 -303.85258)
		(width 0.16002)
		(layer "In13.Cu")
		(net "M_B_CPU1_SB_DQS_DN<2>")
	)
	(segment
		(start 52.157884 -304.161444)
		(end 51.884072 -304.435256)
		(width 0.16002)
		(layer "In13.Cu")
		(net "M_B_CPU1_SB_DQS_DN<2>")
	)
	(segment
		(start 85.949536 -285.91129)
		(end 85.941154 -285.906464)
		(width 0.09525)
		(layer "In13.Cu")
		(net "M_B_CPU1_SB_DQS_DN<2>")
	)
	(segment
		(start 64.74841 -299.414438)
		(end 64.374522 -299.788326)
		(width 0.16002)
		(layer "In13.Cu")
		(net "M_B_CPU1_SB_DQS_DN<2>")
	)
	(segment
		(start 79.03718 -285.8897)
		(end 78.828392 -285.986728)
		(width 0.09525)
		(layer "In13.Cu")
		(net "M_B_CPU1_SB_DQS_DN<2>")
	)
	(segment
		(start 55.26532 -303.645824)
		(end 54.51602 -304.395124)
		(width 0.16002)
		(layer "In13.Cu")
		(net "M_B_CPU1_SB_DQS_DN<2>")
	)
	(segment
		(start 66.106802 -296.82948)
		(end 65.910968 -297.025314)
		(width 0.16002)
		(layer "In13.Cu")
		(net "M_B_CPU1_SB_DQS_DN<2>")
	)
	(segment
		(start 87.640922 -286.23641)
		(end 87.794846 -285.97098)
		(width 0.09525)
		(layer "In13.Cu")
		(net "M_B_CPU1_SB_DQS_DN<2>")
	)
	(segment
		(start 61.72073 -302.108108)
		(end 60.355226 -303.473612)
		(width 0.16002)
		(layer "In13.Cu")
		(net "M_B_CPU1_SB_DQS_DN<2>")
	)
	(segment
		(start 65.01003 -298.203112)
		(end 64.73317 -298.203112)
		(width 0.16002)
		(layer "In13.Cu")
		(net "M_B_CPU1_SB_DQS_DN<2>")
	)
	(segment
		(start 76.186284 -286.749998)
		(end 76.16952 -286.766762)
		(width 0.09525)
		(layer "In13.Cu")
		(net "M_B_CPU1_SB_DQS_DN<2>")
	)
	(segment
		(start 63.636398 -299.576744)
		(end 63.359538 -299.576744)
		(width 0.16002)
		(layer "In13.Cu")
		(net "M_B_CPU1_SB_DQS_DN<2>")
	)
	(segment
		(start 53.471318 -304.395124)
		(end 53.237638 -304.161444)
		(width 0.16002)
		(layer "In13.Cu")
		(net "M_B_CPU1_SB_DQS_DN<2>")
	)
	(segment
		(start 79.932276 -285.91129)
		(end 79.854044 -285.956756)
		(width 0.09525)
		(layer "In13.Cu")
		(net "M_B_CPU1_SB_DQS_DN<2>")
	)
	(segment
		(start 67.2846 -295.928542)
		(end 67.495928 -296.13987)
		(width 0.16002)
		(layer "In13.Cu")
		(net "M_B_CPU1_SB_DQS_DN<2>")
	)
	(segment
		(start 78.828392 -285.986728)
		(end 78.820772 -285.994348)
		(width 0.09525)
		(layer "In13.Cu")
		(net "M_B_CPU1_SB_DQS_DN<2>")
	)
	(segment
		(start 54.51602 -304.395124)
		(end 53.471318 -304.395124)
		(width 0.16002)
		(layer "In13.Cu")
		(net "M_B_CPU1_SB_DQS_DN<2>")
	)
	(segment
		(start 67.495674 -296.667174)
		(end 67.121786 -297.041062)
		(width 0.16002)
		(layer "In13.Cu")
		(net "M_B_CPU1_SB_DQS_DN<2>")
	)
	(segment
		(start 60.355226 -303.473612)
		(end 57.927748 -303.473612)
		(width 0.16002)
		(layer "In13.Cu")
		(net "M_B_CPU1_SB_DQS_DN<2>")
	)
	(segment
		(start 62.474094 -301.161704)
		(end 62.262766 -300.950376)
		(width 0.16002)
		(layer "In13.Cu")
		(net "M_B_CPU1_SB_DQS_DN<2>")
	)
	(segment
		(start 67.495928 -296.13987)
		(end 67.495674 -296.667174)
		(width 0.16002)
		(layer "In13.Cu")
		(net "M_B_CPU1_SB_DQS_DN<2>")
	)
	(segment
		(start 82.76082 -285.906464)
		(end 82.752438 -285.91129)
		(width 0.09525)
		(layer "In13.Cu")
		(net "M_B_CPU1_SB_DQS_DN<2>")
	)
	(segment
		(start 65.910968 -297.302174)
		(end 66.122296 -297.513502)
		(width 0.16002)
		(layer "In13.Cu")
		(net "M_B_CPU1_SB_DQS_DN<2>")
	)
	(segment
		(start 56.625236 -304.776124)
		(end 56.139588 -304.776124)
		(width 0.16002)
		(layer "In13.Cu")
		(net "M_B_CPU1_SB_DQS_DN<2>")
	)
	(segment
		(start 62.262766 -300.950376)
		(end 61.985906 -300.950376)
		(width 0.16002)
		(layer "In13.Cu")
		(net "M_B_CPU1_SB_DQS_DN<2>")
	)
	(segment
		(start 66.122296 -297.513502)
		(end 66.122042 -298.040806)
		(width 0.16002)
		(layer "In13.Cu")
		(net "M_B_CPU1_SB_DQS_DN<2>")
	)
	(segment
		(start 64.537336 -298.675806)
		(end 64.748664 -298.887134)
		(width 0.16002)
		(layer "In13.Cu")
		(net "M_B_CPU1_SB_DQS_DN<2>")
	)
	(segment
		(start 83.700874 -285.906464)
		(end 83.692492 -285.91129)
		(width 0.09525)
		(layer "In13.Cu")
		(net "M_B_CPU1_SB_DQS_DN<2>")
	)
	(segment
		(start 55.557928 -303.645824)
		(end 55.26532 -303.645824)
		(width 0.16002)
		(layer "In13.Cu")
		(net "M_B_CPU1_SB_DQS_DN<2>")
	)
	(segment
		(start 63.375032 -300.260766)
		(end 63.374778 -300.78807)
		(width 0.16002)
		(layer "In13.Cu")
		(net "M_B_CPU1_SB_DQS_DN<2>")
	)
	(segment
		(start 57.927748 -303.473612)
		(end 56.625236 -304.776124)
		(width 0.16002)
		(layer "In13.Cu")
		(net "M_B_CPU1_SB_DQS_DN<2>")
	)
	(segment
		(start 64.748664 -298.887134)
		(end 64.74841 -299.414438)
		(width 0.16002)
		(layer "In13.Cu")
		(net "M_B_CPU1_SB_DQS_DN<2>")
	)
	(segment
		(start 65.221358 -298.41444)
		(end 65.01003 -298.203112)
		(width 0.16002)
		(layer "In13.Cu")
		(net "M_B_CPU1_SB_DQS_DN<2>")
	)
	(segment
		(start 78.820772 -285.994348)
		(end 78.075028 -285.994348)
		(width 0.09525)
		(layer "In13.Cu")
		(net "M_B_CPU1_SB_DQS_DN<2>")
	)
	(segment
		(start 63.163704 -300.049438)
		(end 63.375032 -300.260766)
		(width 0.16002)
		(layer "In13.Cu")
		(net "M_B_CPU1_SB_DQS_DN<2>")
	)
	(segment
		(start 63.374778 -300.78807)
		(end 63.00089 -301.161958)
		(width 0.16002)
		(layer "In13.Cu")
		(net "M_B_CPU1_SB_DQS_DN<2>")
	)
	(segment
		(start 82.189574 -285.91129)
		(end 82.181192 -285.906464)
		(width 0.09525)
		(layer "In13.Cu")
		(net "M_B_CPU1_SB_DQS_DN<2>")
	)
	(segment
		(start 65.748154 -298.414694)
		(end 65.221358 -298.41444)
		(width 0.16002)
		(layer "In13.Cu")
		(net "M_B_CPU1_SB_DQS_DN<2>")
	)
	(segment
		(start 61.985906 -300.950376)
		(end 61.72073 -301.215552)
		(width 0.16002)
		(layer "In13.Cu")
		(net "M_B_CPU1_SB_DQS_DN<2>")
	)
	(segment
		(start 55.764684 -303.85258)
		(end 55.557928 -303.645824)
		(width 0.16002)
		(layer "In13.Cu")
		(net "M_B_CPU1_SB_DQS_DN<2>")
	)
	(segment
		(start 76.16952 -286.766762)
		(end 67.2846 -295.651682)
		(width 0.16002)
		(layer "In13.Cu")
		(net "M_B_CPU1_SB_DQS_DN<2>")
	)
	(segment
		(start 61.72073 -301.215552)
		(end 61.72073 -302.108108)
		(width 0.16002)
		(layer "In13.Cu")
		(net "M_B_CPU1_SB_DQS_DN<2>")
	)
	(arc
		(start 79.854044 -285.956756)
		(mid 79.604804 -285.992593)
		(end 79.364586 -285.917132)
		(width 0.09525)
		(layer "In13.Cu")
		(net "M_B_CPU1_SB_DQS_DN<2>")
	)
	(arc
		(start 85.009482 -285.91129)
		(mid 84.821014 -285.860613)
		(end 84.632546 -285.91129)
		(width 0.09525)
		(layer "In13.Cu")
		(net "M_B_CPU1_SB_DQS_DN<2>")
	)
	(arc
		(start 87.771478 -285.884112)
		(mid 87.613728 -285.861593)
		(end 87.460836 -285.906464)
		(width 0.09525)
		(layer "In13.Cu")
		(net "M_B_CPU1_SB_DQS_DN<2>")
	)
	(arc
		(start 79.364586 -285.917132)
		(mid 79.203977 -285.866571)
		(end 79.03718 -285.8897)
		(width 0.09525)
		(layer "In13.Cu")
		(net "M_B_CPU1_SB_DQS_DN<2>")
	)
	(arc
		(start 80.872584 -285.91129)
		(mid 80.591152 -285.987045)
		(end 80.30972 -285.91129)
		(width 0.09525)
		(layer "In13.Cu")
		(net "M_B_CPU1_SB_DQS_DN<2>")
	)
	(arc
		(start 84.632546 -285.91129)
		(mid 84.351114 -285.987045)
		(end 84.069682 -285.91129)
		(width 0.09525)
		(layer "In13.Cu")
		(net "M_B_CPU1_SB_DQS_DN<2>")
	)
	(arc
		(start 83.692492 -285.91129)
		(mid 83.41106 -285.987045)
		(end 83.129628 -285.91129)
		(width 0.09525)
		(layer "In13.Cu")
		(net "M_B_CPU1_SB_DQS_DN<2>")
	)
	(arc
		(start 82.752438 -285.91129)
		(mid 82.471006 -285.987045)
		(end 82.189574 -285.91129)
		(width 0.09525)
		(layer "In13.Cu")
		(net "M_B_CPU1_SB_DQS_DN<2>")
	)
	(arc
		(start 81.812384 -285.91129)
		(mid 81.530952 -285.987045)
		(end 81.24952 -285.91129)
		(width 0.09525)
		(layer "In13.Cu")
		(net "M_B_CPU1_SB_DQS_DN<2>")
	)
	(arc
		(start 81.24952 -285.91129)
		(mid 81.061052 -285.860613)
		(end 80.872584 -285.91129)
		(width 0.09525)
		(layer "In13.Cu")
		(net "M_B_CPU1_SB_DQS_DN<2>")
	)
	(arc
		(start 84.069682 -285.91129)
		(mid 83.885907 -285.860518)
		(end 83.700874 -285.906464)
		(width 0.09525)
		(layer "In13.Cu")
		(net "M_B_CPU1_SB_DQS_DN<2>")
	)
	(arc
		(start 85.572346 -285.91129)
		(mid 85.290914 -285.987045)
		(end 85.009482 -285.91129)
		(width 0.09525)
		(layer "In13.Cu")
		(net "M_B_CPU1_SB_DQS_DN<2>")
	)
	(arc
		(start 80.30972 -285.91129)
		(mid 80.120998 -285.860486)
		(end 79.932276 -285.91129)
		(width 0.09525)
		(layer "In13.Cu")
		(net "M_B_CPU1_SB_DQS_DN<2>")
	)
	(arc
		(start 85.941154 -285.906464)
		(mid 85.756122 -285.86055)
		(end 85.572346 -285.91129)
		(width 0.09525)
		(layer "In13.Cu")
		(net "M_B_CPU1_SB_DQS_DN<2>")
	)
	(arc
		(start 87.452454 -285.91129)
		(mid 87.171022 -285.987045)
		(end 86.88959 -285.91129)
		(width 0.09525)
		(layer "In13.Cu")
		(net "M_B_CPU1_SB_DQS_DN<2>")
	)
	(arc
		(start 86.881208 -285.906464)
		(mid 86.696176 -285.86055)
		(end 86.5124 -285.91129)
		(width 0.09525)
		(layer "In13.Cu")
		(net "M_B_CPU1_SB_DQS_DN<2>")
	)
	(arc
		(start 82.181192 -285.906464)
		(mid 81.99616 -285.86055)
		(end 81.812384 -285.91129)
		(width 0.09525)
		(layer "In13.Cu")
		(net "M_B_CPU1_SB_DQS_DN<2>")
	)
	(arc
		(start 83.129628 -285.91129)
		(mid 82.945853 -285.860518)
		(end 82.76082 -285.906464)
		(width 0.09525)
		(layer "In13.Cu")
		(net "M_B_CPU1_SB_DQS_DN<2>")
	)
	(arc
		(start 86.5124 -285.91129)
		(mid 86.230968 -285.987045)
		(end 85.949536 -285.91129)
		(width 0.09525)
		(layer "In13.Cu")
		(net "M_B_CPU1_SB_DQS_DN<2>")
	)
	(segment
		(start 88.107774 -281.110436)
		(end 87.640922 -281.376374)
		(width 0.12954)
		(layer "F.Cu")
		(net "M_B_CPU1_SB_DQS_DN<1>")
	)
	(segment
		(start 67.450716 -287.410906)
		(end 66.923412 -287.410906)
		(width 0.16002)
		(layer "In13.Cu")
		(net "M_B_CPU1_SB_DQS_DN<1>")
	)
	(segment
		(start 69.19722 -285.137098)
		(end 69.19722 -285.664402)
		(width 0.16002)
		(layer "In13.Cu")
		(net "M_B_CPU1_SB_DQS_DN<1>")
	)
	(segment
		(start 67.823588 -286.51073)
		(end 67.823588 -287.038034)
		(width 0.16002)
		(layer "In13.Cu")
		(net "M_B_CPU1_SB_DQS_DN<1>")
	)
	(segment
		(start 70.570852 -284.29077)
		(end 70.19798 -284.663642)
		(width 0.16002)
		(layer "In13.Cu")
		(net "M_B_CPU1_SB_DQS_DN<1>")
	)
	(segment
		(start 71.944484 -282.389834)
		(end 71.944484 -282.917138)
		(width 0.16002)
		(layer "In13.Cu")
		(net "M_B_CPU1_SB_DQS_DN<1>")
	)
	(segment
		(start 76.131674 -281.082496)
		(end 73.779126 -281.082496)
		(width 0.16002)
		(layer "In13.Cu")
		(net "M_B_CPU1_SB_DQS_DN<1>")
	)
	(segment
		(start 67.823588 -287.038034)
		(end 67.450716 -287.410906)
		(width 0.16002)
		(layer "In13.Cu")
		(net "M_B_CPU1_SB_DQS_DN<1>")
	)
	(segment
		(start 71.571612 -283.29001)
		(end 71.044308 -283.29001)
		(width 0.16002)
		(layer "In13.Cu")
		(net "M_B_CPU1_SB_DQS_DN<1>")
	)
	(segment
		(start 54.15534 -294.987218)
		(end 53.974238 -294.806116)
		(width 0.16002)
		(layer "In13.Cu")
		(net "M_B_CPU1_SB_DQS_DN<1>")
	)
	(segment
		(start 68.824348 -286.037274)
		(end 68.297044 -286.037274)
		(width 0.16002)
		(layer "In13.Cu")
		(net "M_B_CPU1_SB_DQS_DN<1>")
	)
	(segment
		(start 70.570852 -283.763466)
		(end 70.570852 -284.29077)
		(width 0.16002)
		(layer "In13.Cu")
		(net "M_B_CPU1_SB_DQS_DN<1>")
	)
	(segment
		(start 66.270886 -287.428432)
		(end 66.270886 -287.705292)
		(width 0.16002)
		(layer "In13.Cu")
		(net "M_B_CPU1_SB_DQS_DN<1>")
	)
	(segment
		(start 66.449956 -288.411666)
		(end 60.738004 -294.123618)
		(width 0.16002)
		(layer "In13.Cu")
		(net "M_B_CPU1_SB_DQS_DN<1>")
	)
	(segment
		(start 78.396592 -281.048714)
		(end 77.209904 -280.732484)
		(width 0.09525)
		(layer "In13.Cu")
		(net "M_B_CPU1_SB_DQS_DN<1>")
	)
	(segment
		(start 60.738004 -294.123618)
		(end 57.874408 -294.123618)
		(width 0.16002)
		(layer "In13.Cu")
		(net "M_B_CPU1_SB_DQS_DN<1>")
	)
	(segment
		(start 71.044308 -283.29001)
		(end 70.865238 -283.11094)
		(width 0.16002)
		(layer "In13.Cu")
		(net "M_B_CPU1_SB_DQS_DN<1>")
	)
	(segment
		(start 87.460836 -281.046428)
		(end 87.452454 -281.051254)
		(width 0.09525)
		(layer "In13.Cu")
		(net "M_B_CPU1_SB_DQS_DN<1>")
	)
	(segment
		(start 87.640922 -281.376374)
		(end 87.794846 -281.110944)
		(width 0.09525)
		(layer "In13.Cu")
		(net "M_B_CPU1_SB_DQS_DN<1>")
	)
	(segment
		(start 69.670676 -284.663642)
		(end 69.491606 -284.484572)
		(width 0.16002)
		(layer "In13.Cu")
		(net "M_B_CPU1_SB_DQS_DN<1>")
	)
	(segment
		(start 69.491606 -284.484572)
		(end 69.214746 -284.484572)
		(width 0.16002)
		(layer "In13.Cu")
		(net "M_B_CPU1_SB_DQS_DN<1>")
	)
	(segment
		(start 70.391782 -283.584396)
		(end 70.570852 -283.763466)
		(width 0.16002)
		(layer "In13.Cu")
		(net "M_B_CPU1_SB_DQS_DN<1>")
	)
	(segment
		(start 72.23887 -281.737308)
		(end 71.96201 -281.737308)
		(width 0.16002)
		(layer "In13.Cu")
		(net "M_B_CPU1_SB_DQS_DN<1>")
	)
	(segment
		(start 68.297044 -286.037274)
		(end 68.117974 -285.858204)
		(width 0.16002)
		(layer "In13.Cu")
		(net "M_B_CPU1_SB_DQS_DN<1>")
	)
	(segment
		(start 70.19798 -284.663642)
		(end 69.670676 -284.663642)
		(width 0.16002)
		(layer "In13.Cu")
		(net "M_B_CPU1_SB_DQS_DN<1>")
	)
	(segment
		(start 73.779126 -281.082496)
		(end 72.945244 -281.916378)
		(width 0.16002)
		(layer "In13.Cu")
		(net "M_B_CPU1_SB_DQS_DN<1>")
	)
	(segment
		(start 82.189574 -281.051254)
		(end 82.181192 -281.046428)
		(width 0.09525)
		(layer "In13.Cu")
		(net "M_B_CPU1_SB_DQS_DN<1>")
	)
	(segment
		(start 69.214746 -284.484572)
		(end 69.01815 -284.681168)
		(width 0.16002)
		(layer "In13.Cu")
		(net "M_B_CPU1_SB_DQS_DN<1>")
	)
	(segment
		(start 87.794846 -281.110944)
		(end 87.771478 -281.024076)
		(width 0.09525)
		(layer "In13.Cu")
		(net "M_B_CPU1_SB_DQS_DN<1>")
	)
	(segment
		(start 70.865238 -283.11094)
		(end 70.588378 -283.11094)
		(width 0.16002)
		(layer "In13.Cu")
		(net "M_B_CPU1_SB_DQS_DN<1>")
	)
	(segment
		(start 66.467482 -287.231836)
		(end 66.270886 -287.428432)
		(width 0.16002)
		(layer "In13.Cu")
		(net "M_B_CPU1_SB_DQS_DN<1>")
	)
	(segment
		(start 70.391782 -283.307536)
		(end 70.391782 -283.584396)
		(width 0.16002)
		(layer "In13.Cu")
		(net "M_B_CPU1_SB_DQS_DN<1>")
	)
	(segment
		(start 71.765414 -281.933904)
		(end 71.765414 -282.210764)
		(width 0.16002)
		(layer "In13.Cu")
		(net "M_B_CPU1_SB_DQS_DN<1>")
	)
	(segment
		(start 71.765414 -282.210764)
		(end 71.944484 -282.389834)
		(width 0.16002)
		(layer "In13.Cu")
		(net "M_B_CPU1_SB_DQS_DN<1>")
	)
	(segment
		(start 76.214224 -281.023568)
		(end 76.155296 -281.082496)
		(width 0.09525)
		(layer "In13.Cu")
		(net "M_B_CPU1_SB_DQS_DN<1>")
	)
	(segment
		(start 79.379572 -281.05735)
		(end 79.369158 -281.051254)
		(width 0.09525)
		(layer "In13.Cu")
		(net "M_B_CPU1_SB_DQS_DN<1>")
	)
	(segment
		(start 69.01815 -284.681168)
		(end 69.01815 -284.958028)
		(width 0.16002)
		(layer "In13.Cu")
		(net "M_B_CPU1_SB_DQS_DN<1>")
	)
	(segment
		(start 72.41794 -281.916378)
		(end 72.23887 -281.737308)
		(width 0.16002)
		(layer "In13.Cu")
		(net "M_B_CPU1_SB_DQS_DN<1>")
	)
	(segment
		(start 82.76082 -281.046428)
		(end 82.752438 -281.051254)
		(width 0.09525)
		(layer "In13.Cu")
		(net "M_B_CPU1_SB_DQS_DN<1>")
	)
	(segment
		(start 70.588378 -283.11094)
		(end 70.391782 -283.307536)
		(width 0.16002)
		(layer "In13.Cu")
		(net "M_B_CPU1_SB_DQS_DN<1>")
	)
	(segment
		(start 86.88959 -281.051254)
		(end 86.881208 -281.046428)
		(width 0.09525)
		(layer "In13.Cu")
		(net "M_B_CPU1_SB_DQS_DN<1>")
	)
	(segment
		(start 57.874408 -294.123618)
		(end 57.010808 -294.987218)
		(width 0.16002)
		(layer "In13.Cu")
		(net "M_B_CPU1_SB_DQS_DN<1>")
	)
	(segment
		(start 53.974238 -294.806116)
		(end 52.163218 -294.806116)
		(width 0.16002)
		(layer "In13.Cu")
		(net "M_B_CPU1_SB_DQS_DN<1>")
	)
	(segment
		(start 57.010808 -294.987218)
		(end 54.15534 -294.987218)
		(width 0.16002)
		(layer "In13.Cu")
		(net "M_B_CPU1_SB_DQS_DN<1>")
	)
	(segment
		(start 76.858622 -280.720038)
		(end 76.555092 -281.023568)
		(width 0.09525)
		(layer "In13.Cu")
		(net "M_B_CPU1_SB_DQS_DN<1>")
	)
	(segment
		(start 69.19722 -285.664402)
		(end 68.824348 -286.037274)
		(width 0.16002)
		(layer "In13.Cu")
		(net "M_B_CPU1_SB_DQS_DN<1>")
	)
	(segment
		(start 78.978252 -281.059382)
		(end 78.97749 -281.05989)
		(width 0.09525)
		(layer "In13.Cu")
		(net "M_B_CPU1_SB_DQS_DN<1>")
	)
	(segment
		(start 78.992222 -281.051254)
		(end 78.978252 -281.059382)
		(width 0.09525)
		(layer "In13.Cu")
		(net "M_B_CPU1_SB_DQS_DN<1>")
	)
	(segment
		(start 76.155296 -281.082496)
		(end 76.131674 -281.082496)
		(width 0.09525)
		(layer "In13.Cu")
		(net "M_B_CPU1_SB_DQS_DN<1>")
	)
	(segment
		(start 71.944484 -282.917138)
		(end 71.571612 -283.29001)
		(width 0.16002)
		(layer "In13.Cu")
		(net "M_B_CPU1_SB_DQS_DN<1>")
	)
	(segment
		(start 66.923412 -287.410906)
		(end 66.744342 -287.231836)
		(width 0.16002)
		(layer "In13.Cu")
		(net "M_B_CPU1_SB_DQS_DN<1>")
	)
	(segment
		(start 69.01815 -284.958028)
		(end 69.19722 -285.137098)
		(width 0.16002)
		(layer "In13.Cu")
		(net "M_B_CPU1_SB_DQS_DN<1>")
	)
	(segment
		(start 85.949536 -281.051254)
		(end 85.941154 -281.046428)
		(width 0.09525)
		(layer "In13.Cu")
		(net "M_B_CPU1_SB_DQS_DN<1>")
	)
	(segment
		(start 83.700874 -281.046428)
		(end 83.692492 -281.051254)
		(width 0.09525)
		(layer "In13.Cu")
		(net "M_B_CPU1_SB_DQS_DN<1>")
	)
	(segment
		(start 66.744342 -287.231836)
		(end 66.467482 -287.231836)
		(width 0.16002)
		(layer "In13.Cu")
		(net "M_B_CPU1_SB_DQS_DN<1>")
	)
	(segment
		(start 79.00416 -281.044396)
		(end 78.992222 -281.051254)
		(width 0.09525)
		(layer "In13.Cu")
		(net "M_B_CPU1_SB_DQS_DN<1>")
	)
	(segment
		(start 67.644518 -286.33166)
		(end 67.823588 -286.51073)
		(width 0.16002)
		(layer "In13.Cu")
		(net "M_B_CPU1_SB_DQS_DN<1>")
	)
	(segment
		(start 77.11567 -280.720038)
		(end 76.858622 -280.720038)
		(width 0.09525)
		(layer "In13.Cu")
		(net "M_B_CPU1_SB_DQS_DN<1>")
	)
	(segment
		(start 66.449956 -287.884362)
		(end 66.449956 -288.411666)
		(width 0.16002)
		(layer "In13.Cu")
		(net "M_B_CPU1_SB_DQS_DN<1>")
	)
	(segment
		(start 68.117974 -285.858204)
		(end 67.841114 -285.858204)
		(width 0.16002)
		(layer "In13.Cu")
		(net "M_B_CPU1_SB_DQS_DN<1>")
	)
	(segment
		(start 52.163218 -294.806116)
		(end 51.884072 -295.085262)
		(width 0.16002)
		(layer "In13.Cu")
		(net "M_B_CPU1_SB_DQS_DN<1>")
	)
	(segment
		(start 71.96201 -281.737308)
		(end 71.765414 -281.933904)
		(width 0.16002)
		(layer "In13.Cu")
		(net "M_B_CPU1_SB_DQS_DN<1>")
	)
	(segment
		(start 72.945244 -281.916378)
		(end 72.41794 -281.916378)
		(width 0.16002)
		(layer "In13.Cu")
		(net "M_B_CPU1_SB_DQS_DN<1>")
	)
	(segment
		(start 67.841114 -285.858204)
		(end 67.644518 -286.0548)
		(width 0.16002)
		(layer "In13.Cu")
		(net "M_B_CPU1_SB_DQS_DN<1>")
	)
	(segment
		(start 66.270886 -287.705292)
		(end 66.449956 -287.884362)
		(width 0.16002)
		(layer "In13.Cu")
		(net "M_B_CPU1_SB_DQS_DN<1>")
	)
	(segment
		(start 67.644518 -286.0548)
		(end 67.644518 -286.33166)
		(width 0.16002)
		(layer "In13.Cu")
		(net "M_B_CPU1_SB_DQS_DN<1>")
	)
	(segment
		(start 76.555092 -281.023568)
		(end 76.214224 -281.023568)
		(width 0.09525)
		(layer "In13.Cu")
		(net "M_B_CPU1_SB_DQS_DN<1>")
	)
	(arc
		(start 80.30972 -281.051254)
		(mid 80.120998 -281.00045)
		(end 79.932276 -281.051254)
		(width 0.09525)
		(layer "In13.Cu")
		(net "M_B_CPU1_SB_DQS_DN<1>")
	)
	(arc
		(start 81.812384 -281.051254)
		(mid 81.530952 -281.127009)
		(end 81.24952 -281.051254)
		(width 0.09525)
		(layer "In13.Cu")
		(net "M_B_CPU1_SB_DQS_DN<1>")
	)
	(arc
		(start 78.486508 -281.080464)
		(mid 78.44215 -281.06289)
		(end 78.396592 -281.048714)
		(width 0.09525)
		(layer "In13.Cu")
		(net "M_B_CPU1_SB_DQS_DN<1>")
	)
	(arc
		(start 79.932276 -281.051254)
		(mid 79.656733 -281.127103)
		(end 79.379572 -281.05735)
		(width 0.09525)
		(layer "In13.Cu")
		(net "M_B_CPU1_SB_DQS_DN<1>")
	)
	(arc
		(start 86.5124 -281.051254)
		(mid 86.230968 -281.127009)
		(end 85.949536 -281.051254)
		(width 0.09525)
		(layer "In13.Cu")
		(net "M_B_CPU1_SB_DQS_DN<1>")
	)
	(arc
		(start 84.069682 -281.051254)
		(mid 83.885907 -281.000482)
		(end 83.700874 -281.046428)
		(width 0.09525)
		(layer "In13.Cu")
		(net "M_B_CPU1_SB_DQS_DN<1>")
	)
	(arc
		(start 77.209904 -280.732484)
		(mid 77.163193 -280.723195)
		(end 77.11567 -280.720038)
		(width 0.09525)
		(layer "In13.Cu")
		(net "M_B_CPU1_SB_DQS_DN<1>")
	)
	(arc
		(start 80.872584 -281.051254)
		(mid 80.591152 -281.127009)
		(end 80.30972 -281.051254)
		(width 0.09525)
		(layer "In13.Cu")
		(net "M_B_CPU1_SB_DQS_DN<1>")
	)
	(arc
		(start 87.452454 -281.051254)
		(mid 87.171022 -281.127009)
		(end 86.88959 -281.051254)
		(width 0.09525)
		(layer "In13.Cu")
		(net "M_B_CPU1_SB_DQS_DN<1>")
	)
	(arc
		(start 85.009482 -281.051254)
		(mid 84.821014 -281.000577)
		(end 84.632546 -281.051254)
		(width 0.09525)
		(layer "In13.Cu")
		(net "M_B_CPU1_SB_DQS_DN<1>")
	)
	(arc
		(start 82.181192 -281.046428)
		(mid 81.99616 -281.000514)
		(end 81.812384 -281.051254)
		(width 0.09525)
		(layer "In13.Cu")
		(net "M_B_CPU1_SB_DQS_DN<1>")
	)
	(arc
		(start 82.752438 -281.051254)
		(mid 82.471006 -281.127009)
		(end 82.189574 -281.051254)
		(width 0.09525)
		(layer "In13.Cu")
		(net "M_B_CPU1_SB_DQS_DN<1>")
	)
	(arc
		(start 79.369158 -281.051254)
		(mid 79.187542 -281.000517)
		(end 79.00416 -281.044396)
		(width 0.09525)
		(layer "In13.Cu")
		(net "M_B_CPU1_SB_DQS_DN<1>")
	)
	(arc
		(start 87.771478 -281.024076)
		(mid 87.613728 -281.001557)
		(end 87.460836 -281.046428)
		(width 0.09525)
		(layer "In13.Cu")
		(net "M_B_CPU1_SB_DQS_DN<1>")
	)
	(arc
		(start 85.572346 -281.051254)
		(mid 85.290914 -281.127009)
		(end 85.009482 -281.051254)
		(width 0.09525)
		(layer "In13.Cu")
		(net "M_B_CPU1_SB_DQS_DN<1>")
	)
	(arc
		(start 84.632546 -281.051254)
		(mid 84.351114 -281.127009)
		(end 84.069682 -281.051254)
		(width 0.09525)
		(layer "In13.Cu")
		(net "M_B_CPU1_SB_DQS_DN<1>")
	)
	(arc
		(start 83.129628 -281.051254)
		(mid 82.945853 -281.000482)
		(end 82.76082 -281.046428)
		(width 0.09525)
		(layer "In13.Cu")
		(net "M_B_CPU1_SB_DQS_DN<1>")
	)
	(arc
		(start 85.941154 -281.046428)
		(mid 85.756122 -281.000514)
		(end 85.572346 -281.051254)
		(width 0.09525)
		(layer "In13.Cu")
		(net "M_B_CPU1_SB_DQS_DN<1>")
	)
	(arc
		(start 81.24952 -281.051254)
		(mid 81.061052 -281.000577)
		(end 80.872584 -281.051254)
		(width 0.09525)
		(layer "In13.Cu")
		(net "M_B_CPU1_SB_DQS_DN<1>")
	)
	(arc
		(start 78.97749 -281.05989)
		(mid 78.734364 -281.126847)
		(end 78.486508 -281.080464)
		(width 0.09525)
		(layer "In13.Cu")
		(net "M_B_CPU1_SB_DQS_DN<1>")
	)
	(arc
		(start 86.881208 -281.046428)
		(mid 86.696176 -281.000514)
		(end 86.5124 -281.051254)
		(width 0.09525)
		(layer "In13.Cu")
		(net "M_B_CPU1_SB_DQS_DN<1>")
	)
	(arc
		(start 83.692492 -281.051254)
		(mid 83.41106 -281.127009)
		(end 83.129628 -281.051254)
		(width 0.09525)
		(layer "In13.Cu")
		(net "M_B_CPU1_SB_DQS_DN<1>")
	)
	(segment
		(start 88.107774 -276.2504)
		(end 87.640922 -276.516338)
		(width 0.12954)
		(layer "F.Cu")
		(net "M_B_CPU1_SB_DQS_DN<0>")
	)
	(segment
		(start 63.02756 -282.154884)
		(end 62.603634 -282.57881)
		(width 0.16002)
		(layer "In13.Cu")
		(net "M_B_CPU1_SB_DQS_DN<0>")
	)
	(segment
		(start 82.189574 -276.191218)
		(end 82.181192 -276.186392)
		(width 0.09525)
		(layer "In13.Cu")
		(net "M_B_CPU1_SB_DQS_DN<0>")
	)
	(segment
		(start 64.40043 -280.782014)
		(end 63.976504 -281.20594)
		(width 0.16002)
		(layer "In13.Cu")
		(net "M_B_CPU1_SB_DQS_DN<0>")
	)
	(segment
		(start 75.955906 -275.459444)
		(end 68.745608 -275.459444)
		(width 0.16002)
		(layer "In13.Cu")
		(net "M_B_CPU1_SB_DQS_DN<0>")
	)
	(segment
		(start 85.949536 -276.191218)
		(end 85.941154 -276.186392)
		(width 0.09525)
		(layer "In13.Cu")
		(net "M_B_CPU1_SB_DQS_DN<0>")
	)
	(segment
		(start 60.75426 -283.95168)
		(end 60.616846 -283.814266)
		(width 0.16002)
		(layer "In13.Cu")
		(net "M_B_CPU1_SB_DQS_DN<0>")
	)
	(segment
		(start 62.12713 -282.57881)
		(end 61.989716 -282.441396)
		(width 0.16002)
		(layer "In13.Cu")
		(net "M_B_CPU1_SB_DQS_DN<0>")
	)
	(segment
		(start 77.192886 -275.400516)
		(end 76.038456 -275.400516)
		(width 0.09525)
		(layer "In13.Cu")
		(net "M_B_CPU1_SB_DQS_DN<0>")
	)
	(segment
		(start 87.794846 -276.250908)
		(end 87.771478 -276.16404)
		(width 0.09525)
		(layer "In13.Cu")
		(net "M_B_CPU1_SB_DQS_DN<0>")
	)
	(segment
		(start 61.230764 -283.95168)
		(end 60.75426 -283.95168)
		(width 0.16002)
		(layer "In13.Cu")
		(net "M_B_CPU1_SB_DQS_DN<0>")
	)
	(segment
		(start 87.640922 -276.516338)
		(end 87.794846 -276.250908)
		(width 0.09525)
		(layer "In13.Cu")
		(net "M_B_CPU1_SB_DQS_DN<0>")
	)
	(segment
		(start 63.362586 -281.068526)
		(end 63.136526 -281.068526)
		(width 0.16002)
		(layer "In13.Cu")
		(net "M_B_CPU1_SB_DQS_DN<0>")
	)
	(segment
		(start 60.390786 -283.814266)
		(end 59.342528 -284.862524)
		(width 0.16002)
		(layer "In13.Cu")
		(net "M_B_CPU1_SB_DQS_DN<0>")
	)
	(segment
		(start 61.65469 -283.527754)
		(end 61.230764 -283.95168)
		(width 0.16002)
		(layer "In13.Cu")
		(net "M_B_CPU1_SB_DQS_DN<0>")
	)
	(segment
		(start 55.77967 -286.030924)
		(end 55.179976 -285.43123)
		(width 0.16002)
		(layer "In13.Cu")
		(net "M_B_CPU1_SB_DQS_DN<0>")
	)
	(segment
		(start 79.564738 -276.267164)
		(end 78.135988 -276.267164)
		(width 0.09525)
		(layer "In13.Cu")
		(net "M_B_CPU1_SB_DQS_DN<0>")
	)
	(segment
		(start 68.51904 -276.663404)
		(end 68.095114 -277.08733)
		(width 0.16002)
		(layer "In13.Cu")
		(net "M_B_CPU1_SB_DQS_DN<0>")
	)
	(segment
		(start 64.40043 -280.30551)
		(end 64.40043 -280.782014)
		(width 0.16002)
		(layer "In13.Cu")
		(net "M_B_CPU1_SB_DQS_DN<0>")
	)
	(segment
		(start 68.095114 -277.08733)
		(end 67.61861 -277.08733)
		(width 0.16002)
		(layer "In13.Cu")
		(net "M_B_CPU1_SB_DQS_DN<0>")
	)
	(segment
		(start 68.51904 -276.1869)
		(end 68.51904 -276.663404)
		(width 0.16002)
		(layer "In13.Cu")
		(net "M_B_CPU1_SB_DQS_DN<0>")
	)
	(segment
		(start 83.700874 -276.186392)
		(end 83.692492 -276.191218)
		(width 0.09525)
		(layer "In13.Cu")
		(net "M_B_CPU1_SB_DQS_DN<0>")
	)
	(segment
		(start 67.255136 -276.949916)
		(end 67.008756 -277.196296)
		(width 0.16002)
		(layer "In13.Cu")
		(net "M_B_CPU1_SB_DQS_DN<0>")
	)
	(segment
		(start 64.735456 -279.695656)
		(end 64.509396 -279.695656)
		(width 0.16002)
		(layer "In13.Cu")
		(net "M_B_CPU1_SB_DQS_DN<0>")
	)
	(segment
		(start 68.745608 -275.459444)
		(end 68.381626 -275.823426)
		(width 0.16002)
		(layer "In13.Cu")
		(net "M_B_CPU1_SB_DQS_DN<0>")
	)
	(segment
		(start 67.481196 -276.949916)
		(end 67.255136 -276.949916)
		(width 0.16002)
		(layer "In13.Cu")
		(net "M_B_CPU1_SB_DQS_DN<0>")
	)
	(segment
		(start 68.381626 -275.823426)
		(end 68.381626 -276.049486)
		(width 0.16002)
		(layer "In13.Cu")
		(net "M_B_CPU1_SB_DQS_DN<0>")
	)
	(segment
		(start 59.342528 -284.862524)
		(end 57.785508 -284.862524)
		(width 0.16002)
		(layer "In13.Cu")
		(net "M_B_CPU1_SB_DQS_DN<0>")
	)
	(segment
		(start 81.29143 -276.213316)
		(end 81.289906 -276.212554)
		(width 0.09525)
		(layer "In13.Cu")
		(net "M_B_CPU1_SB_DQS_DN<0>")
	)
	(segment
		(start 64.263016 -279.942036)
		(end 64.263016 -280.168096)
		(width 0.16002)
		(layer "In13.Cu")
		(net "M_B_CPU1_SB_DQS_DN<0>")
	)
	(segment
		(start 62.890146 -281.314906)
		(end 62.890146 -281.540966)
		(width 0.16002)
		(layer "In13.Cu")
		(net "M_B_CPU1_SB_DQS_DN<0>")
	)
	(segment
		(start 64.509396 -279.695656)
		(end 64.263016 -279.942036)
		(width 0.16002)
		(layer "In13.Cu")
		(net "M_B_CPU1_SB_DQS_DN<0>")
	)
	(segment
		(start 65.635886 -278.795226)
		(end 65.7733 -278.93264)
		(width 0.16002)
		(layer "In13.Cu")
		(net "M_B_CPU1_SB_DQS_DN<0>")
	)
	(segment
		(start 67.14617 -278.036274)
		(end 66.722244 -278.4602)
		(width 0.16002)
		(layer "In13.Cu")
		(net "M_B_CPU1_SB_DQS_DN<0>")
	)
	(segment
		(start 75.979528 -275.459444)
		(end 75.955906 -275.459444)
		(width 0.09525)
		(layer "In13.Cu")
		(net "M_B_CPU1_SB_DQS_DN<0>")
	)
	(segment
		(start 67.008756 -277.196296)
		(end 67.008756 -277.422356)
		(width 0.16002)
		(layer "In13.Cu")
		(net "M_B_CPU1_SB_DQS_DN<0>")
	)
	(segment
		(start 62.603634 -282.57881)
		(end 62.12713 -282.57881)
		(width 0.16002)
		(layer "In13.Cu")
		(net "M_B_CPU1_SB_DQS_DN<0>")
	)
	(segment
		(start 61.517276 -282.913836)
		(end 61.65469 -283.05125)
		(width 0.16002)
		(layer "In13.Cu")
		(net "M_B_CPU1_SB_DQS_DN<0>")
	)
	(segment
		(start 65.882266 -278.322786)
		(end 65.635886 -278.569166)
		(width 0.16002)
		(layer "In13.Cu")
		(net "M_B_CPU1_SB_DQS_DN<0>")
	)
	(segment
		(start 87.460836 -276.186392)
		(end 87.452454 -276.191218)
		(width 0.09525)
		(layer "In13.Cu")
		(net "M_B_CPU1_SB_DQS_DN<0>")
	)
	(segment
		(start 78.005432 -276.213062)
		(end 77.192886 -275.400516)
		(width 0.09525)
		(layer "In13.Cu")
		(net "M_B_CPU1_SB_DQS_DN<0>")
	)
	(segment
		(start 65.635886 -278.569166)
		(end 65.635886 -278.795226)
		(width 0.16002)
		(layer "In13.Cu")
		(net "M_B_CPU1_SB_DQS_DN<0>")
	)
	(segment
		(start 63.02756 -281.67838)
		(end 63.02756 -282.154884)
		(width 0.16002)
		(layer "In13.Cu")
		(net "M_B_CPU1_SB_DQS_DN<0>")
	)
	(segment
		(start 63.976504 -281.20594)
		(end 63.5 -281.20594)
		(width 0.16002)
		(layer "In13.Cu")
		(net "M_B_CPU1_SB_DQS_DN<0>")
	)
	(segment
		(start 82.76082 -276.186392)
		(end 82.752438 -276.191218)
		(width 0.09525)
		(layer "In13.Cu")
		(net "M_B_CPU1_SB_DQS_DN<0>")
	)
	(segment
		(start 64.87287 -279.83307)
		(end 64.735456 -279.695656)
		(width 0.16002)
		(layer "In13.Cu")
		(net "M_B_CPU1_SB_DQS_DN<0>")
	)
	(segment
		(start 62.890146 -281.540966)
		(end 63.02756 -281.67838)
		(width 0.16002)
		(layer "In13.Cu")
		(net "M_B_CPU1_SB_DQS_DN<0>")
	)
	(segment
		(start 52.18811 -285.43123)
		(end 51.884072 -285.735268)
		(width 0.16002)
		(layer "In13.Cu")
		(net "M_B_CPU1_SB_DQS_DN<0>")
	)
	(segment
		(start 61.989716 -282.441396)
		(end 61.763656 -282.441396)
		(width 0.16002)
		(layer "In13.Cu")
		(net "M_B_CPU1_SB_DQS_DN<0>")
	)
	(segment
		(start 61.763656 -282.441396)
		(end 61.517276 -282.687776)
		(width 0.16002)
		(layer "In13.Cu")
		(net "M_B_CPU1_SB_DQS_DN<0>")
	)
	(segment
		(start 65.7733 -278.93264)
		(end 65.7733 -279.409144)
		(width 0.16002)
		(layer "In13.Cu")
		(net "M_B_CPU1_SB_DQS_DN<0>")
	)
	(segment
		(start 65.7733 -279.409144)
		(end 65.349374 -279.83307)
		(width 0.16002)
		(layer "In13.Cu")
		(net "M_B_CPU1_SB_DQS_DN<0>")
	)
	(segment
		(start 55.179976 -285.43123)
		(end 52.18811 -285.43123)
		(width 0.16002)
		(layer "In13.Cu")
		(net "M_B_CPU1_SB_DQS_DN<0>")
	)
	(segment
		(start 61.517276 -282.687776)
		(end 61.517276 -282.913836)
		(width 0.16002)
		(layer "In13.Cu")
		(net "M_B_CPU1_SB_DQS_DN<0>")
	)
	(segment
		(start 67.61861 -277.08733)
		(end 67.481196 -276.949916)
		(width 0.16002)
		(layer "In13.Cu")
		(net "M_B_CPU1_SB_DQS_DN<0>")
	)
	(segment
		(start 76.038456 -275.400516)
		(end 75.979528 -275.459444)
		(width 0.09525)
		(layer "In13.Cu")
		(net "M_B_CPU1_SB_DQS_DN<0>")
	)
	(segment
		(start 57.785508 -284.862524)
		(end 56.617108 -286.030924)
		(width 0.16002)
		(layer "In13.Cu")
		(net "M_B_CPU1_SB_DQS_DN<0>")
	)
	(segment
		(start 63.136526 -281.068526)
		(end 62.890146 -281.314906)
		(width 0.16002)
		(layer "In13.Cu")
		(net "M_B_CPU1_SB_DQS_DN<0>")
	)
	(segment
		(start 66.108326 -278.322786)
		(end 65.882266 -278.322786)
		(width 0.16002)
		(layer "In13.Cu")
		(net "M_B_CPU1_SB_DQS_DN<0>")
	)
	(segment
		(start 65.349374 -279.83307)
		(end 64.87287 -279.83307)
		(width 0.16002)
		(layer "In13.Cu")
		(net "M_B_CPU1_SB_DQS_DN<0>")
	)
	(segment
		(start 63.5 -281.20594)
		(end 63.362586 -281.068526)
		(width 0.16002)
		(layer "In13.Cu")
		(net "M_B_CPU1_SB_DQS_DN<0>")
	)
	(segment
		(start 61.65469 -283.05125)
		(end 61.65469 -283.527754)
		(width 0.16002)
		(layer "In13.Cu")
		(net "M_B_CPU1_SB_DQS_DN<0>")
	)
	(segment
		(start 68.381626 -276.049486)
		(end 68.51904 -276.1869)
		(width 0.16002)
		(layer "In13.Cu")
		(net "M_B_CPU1_SB_DQS_DN<0>")
	)
	(segment
		(start 56.617108 -286.030924)
		(end 55.77967 -286.030924)
		(width 0.16002)
		(layer "In13.Cu")
		(net "M_B_CPU1_SB_DQS_DN<0>")
	)
	(segment
		(start 80.851756 -276.196806)
		(end 80.850232 -276.197314)
		(width 0.09525)
		(layer "In13.Cu")
		(net "M_B_CPU1_SB_DQS_DN<0>")
	)
	(segment
		(start 66.24574 -278.4602)
		(end 66.108326 -278.322786)
		(width 0.16002)
		(layer "In13.Cu")
		(net "M_B_CPU1_SB_DQS_DN<0>")
	)
	(segment
		(start 66.722244 -278.4602)
		(end 66.24574 -278.4602)
		(width 0.16002)
		(layer "In13.Cu")
		(net "M_B_CPU1_SB_DQS_DN<0>")
	)
	(segment
		(start 67.14617 -277.55977)
		(end 67.14617 -278.036274)
		(width 0.16002)
		(layer "In13.Cu")
		(net "M_B_CPU1_SB_DQS_DN<0>")
	)
	(segment
		(start 64.263016 -280.168096)
		(end 64.40043 -280.30551)
		(width 0.16002)
		(layer "In13.Cu")
		(net "M_B_CPU1_SB_DQS_DN<0>")
	)
	(segment
		(start 86.88959 -276.191218)
		(end 86.881208 -276.186392)
		(width 0.09525)
		(layer "In13.Cu")
		(net "M_B_CPU1_SB_DQS_DN<0>")
	)
	(segment
		(start 60.616846 -283.814266)
		(end 60.390786 -283.814266)
		(width 0.16002)
		(layer "In13.Cu")
		(net "M_B_CPU1_SB_DQS_DN<0>")
	)
	(segment
		(start 67.008756 -277.422356)
		(end 67.14617 -277.55977)
		(width 0.16002)
		(layer "In13.Cu")
		(net "M_B_CPU1_SB_DQS_DN<0>")
	)
	(arc
		(start 84.069682 -276.191218)
		(mid 83.885907 -276.140446)
		(end 83.700874 -276.186392)
		(width 0.09525)
		(layer "In13.Cu")
		(net "M_B_CPU1_SB_DQS_DN<0>")
	)
	(arc
		(start 87.771478 -276.16404)
		(mid 87.613728 -276.141521)
		(end 87.460836 -276.186392)
		(width 0.09525)
		(layer "In13.Cu")
		(net "M_B_CPU1_SB_DQS_DN<0>")
	)
	(arc
		(start 87.452454 -276.191218)
		(mid 87.171022 -276.266973)
		(end 86.88959 -276.191218)
		(width 0.09525)
		(layer "In13.Cu")
		(net "M_B_CPU1_SB_DQS_DN<0>")
	)
	(arc
		(start 86.881208 -276.186392)
		(mid 86.696176 -276.140478)
		(end 86.5124 -276.191218)
		(width 0.09525)
		(layer "In13.Cu")
		(net "M_B_CPU1_SB_DQS_DN<0>")
	)
	(arc
		(start 85.009482 -276.191218)
		(mid 84.821014 -276.140541)
		(end 84.632546 -276.191218)
		(width 0.09525)
		(layer "In13.Cu")
		(net "M_B_CPU1_SB_DQS_DN<0>")
	)
	(arc
		(start 78.135988 -276.267164)
		(mid 78.065322 -276.253108)
		(end 78.005432 -276.213062)
		(width 0.09525)
		(layer "In13.Cu")
		(net "M_B_CPU1_SB_DQS_DN<0>")
	)
	(arc
		(start 82.181192 -276.186392)
		(mid 81.99616 -276.140478)
		(end 81.812384 -276.191218)
		(width 0.09525)
		(layer "In13.Cu")
		(net "M_B_CPU1_SB_DQS_DN<0>")
	)
	(arc
		(start 84.632546 -276.191218)
		(mid 84.351114 -276.266973)
		(end 84.069682 -276.191218)
		(width 0.09525)
		(layer "In13.Cu")
		(net "M_B_CPU1_SB_DQS_DN<0>")
	)
	(arc
		(start 79.9084 -276.201124)
		(mid 79.739706 -276.250462)
		(end 79.564738 -276.267164)
		(width 0.09525)
		(layer "In13.Cu")
		(net "M_B_CPU1_SB_DQS_DN<0>")
	)
	(arc
		(start 85.572346 -276.191218)
		(mid 85.290914 -276.266973)
		(end 85.009482 -276.191218)
		(width 0.09525)
		(layer "In13.Cu")
		(net "M_B_CPU1_SB_DQS_DN<0>")
	)
	(arc
		(start 80.315816 -276.19833)
		(mid 80.111843 -276.161385)
		(end 79.9084 -276.201124)
		(width 0.09525)
		(layer "In13.Cu")
		(net "M_B_CPU1_SB_DQS_DN<0>")
	)
	(arc
		(start 81.812384 -276.191218)
		(mid 81.55464 -276.266472)
		(end 81.29143 -276.213316)
		(width 0.09525)
		(layer "In13.Cu")
		(net "M_B_CPU1_SB_DQS_DN<0>")
	)
	(arc
		(start 85.941154 -276.186392)
		(mid 85.756122 -276.140478)
		(end 85.572346 -276.191218)
		(width 0.09525)
		(layer "In13.Cu")
		(net "M_B_CPU1_SB_DQS_DN<0>")
	)
	(arc
		(start 83.692492 -276.191218)
		(mid 83.41106 -276.266973)
		(end 83.129628 -276.191218)
		(width 0.09525)
		(layer "In13.Cu")
		(net "M_B_CPU1_SB_DQS_DN<0>")
	)
	(arc
		(start 83.129628 -276.191218)
		(mid 82.945853 -276.140446)
		(end 82.76082 -276.186392)
		(width 0.09525)
		(layer "In13.Cu")
		(net "M_B_CPU1_SB_DQS_DN<0>")
	)
	(arc
		(start 81.289906 -276.212554)
		(mid 81.072444 -276.159709)
		(end 80.851756 -276.196806)
		(width 0.09525)
		(layer "In13.Cu")
		(net "M_B_CPU1_SB_DQS_DN<0>")
	)
	(arc
		(start 80.850232 -276.197314)
		(mid 80.583122 -276.247388)
		(end 80.315816 -276.19833)
		(width 0.09525)
		(layer "In13.Cu")
		(net "M_B_CPU1_SB_DQS_DN<0>")
	)
	(arc
		(start 82.752438 -276.191218)
		(mid 82.471006 -276.266973)
		(end 82.189574 -276.191218)
		(width 0.09525)
		(layer "In13.Cu")
		(net "M_B_CPU1_SB_DQS_DN<0>")
	)
	(arc
		(start 86.5124 -276.191218)
		(mid 86.230968 -276.266973)
		(end 85.949536 -276.191218)
		(width 0.09525)
		(layer "In13.Cu")
		(net "M_B_CPU1_SB_DQS_DN<0>")
	)
	(segment
		(start 89.987882 -279.490424)
		(end 89.52103 -279.756362)
		(width 0.10668)
		(layer "F.Cu")
		(net "M_B_CPU1_SB_DQ<9>")
	)
	(segment
		(start 64.179196 -288.012124)
		(end 63.974472 -288.012124)
		(width 0.14478)
		(layer "In13.Cu")
		(net "M_B_CPU1_SB_DQ<9>")
	)
	(segment
		(start 58.031634 -292.11016)
		(end 57.596532 -292.11016)
		(width 0.14478)
		(layer "In13.Cu")
		(net "M_B_CPU1_SB_DQ<9>")
	)
	(segment
		(start 57.596532 -292.11016)
		(end 56.745886 -292.960552)
		(width 0.14478)
		(layer "In13.Cu")
		(net "M_B_CPU1_SB_DQ<9>")
	)
	(segment
		(start 64.471296 -288.304224)
		(end 64.179196 -288.012124)
		(width 0.14478)
		(layer "In13.Cu")
		(net "M_B_CPU1_SB_DQ<9>")
	)
	(segment
		(start 52.438808 -291.786564)
		(end 51.884072 -292.3413)
		(width 0.14478)
		(layer "In13.Cu")
		(net "M_B_CPU1_SB_DQ<9>")
	)
	(segment
		(start 63.789306 -288.19729)
		(end 63.789306 -288.402014)
		(width 0.14478)
		(layer "In13.Cu")
		(net "M_B_CPU1_SB_DQ<9>")
	)
	(segment
		(start 76.481178 -279.753314)
		(end 76.327762 -279.753314)
		(width 0.0889)
		(layer "In13.Cu")
		(net "M_B_CPU1_SB_DQ<9>")
	)
	(segment
		(start 89.367106 -280.021792)
		(end 89.271094 -280.047192)
		(width 0.0889)
		(layer "In13.Cu")
		(net "M_B_CPU1_SB_DQ<9>")
	)
	(segment
		(start 56.745632 -292.960298)
		(end 54.402228 -292.960298)
		(width 0.14478)
		(layer "In13.Cu")
		(net "M_B_CPU1_SB_DQ<9>")
	)
	(segment
		(start 64.081406 -288.694114)
		(end 64.081406 -288.898838)
		(width 0.14478)
		(layer "In13.Cu")
		(net "M_B_CPU1_SB_DQ<9>")
	)
	(segment
		(start 82.18805 -280.078942)
		(end 82.179668 -280.083768)
		(width 0.0889)
		(layer "In13.Cu")
		(net "M_B_CPU1_SB_DQ<9>")
	)
	(segment
		(start 63.301626 -289.473894)
		(end 63.301626 -289.678618)
		(width 0.14478)
		(layer "In13.Cu")
		(net "M_B_CPU1_SB_DQ<9>")
	)
	(segment
		(start 85.948012 -280.078942)
		(end 85.93963 -280.083768)
		(width 0.0889)
		(layer "In13.Cu")
		(net "M_B_CPU1_SB_DQ<9>")
	)
	(segment
		(start 51.884072 -292.3413)
		(end 51.884072 -292.535356)
		(width 0.14478)
		(layer "In13.Cu")
		(net "M_B_CPU1_SB_DQ<9>")
	)
	(segment
		(start 89.52103 -279.756362)
		(end 89.367106 -280.021792)
		(width 0.0889)
		(layer "In13.Cu")
		(net "M_B_CPU1_SB_DQ<9>")
	)
	(segment
		(start 82.762344 -280.083768)
		(end 82.753962 -280.078942)
		(width 0.0889)
		(layer "In13.Cu")
		(net "M_B_CPU1_SB_DQ<9>")
	)
	(segment
		(start 63.301626 -289.678618)
		(end 60.870084 -292.11016)
		(width 0.14478)
		(layer "In13.Cu")
		(net "M_B_CPU1_SB_DQ<9>")
	)
	(segment
		(start 63.194692 -288.791904)
		(end 63.009526 -288.97707)
		(width 0.14478)
		(layer "In13.Cu")
		(net "M_B_CPU1_SB_DQ<9>")
	)
	(segment
		(start 53.227732 -291.786564)
		(end 52.438808 -291.786564)
		(width 0.14478)
		(layer "In13.Cu")
		(net "M_B_CPU1_SB_DQ<9>")
	)
	(segment
		(start 63.789306 -288.402014)
		(end 64.081406 -288.694114)
		(width 0.14478)
		(layer "In13.Cu")
		(net "M_B_CPU1_SB_DQ<9>")
	)
	(segment
		(start 63.691516 -289.084004)
		(end 63.399416 -288.791904)
		(width 0.14478)
		(layer "In13.Cu")
		(net "M_B_CPU1_SB_DQ<9>")
	)
	(segment
		(start 79.488284 -279.920446)
		(end 76.64831 -279.920446)
		(width 0.0889)
		(layer "In13.Cu")
		(net "M_B_CPU1_SB_DQ<9>")
	)
	(segment
		(start 87.46236 -280.083768)
		(end 87.453978 -280.078942)
		(width 0.0889)
		(layer "In13.Cu")
		(net "M_B_CPU1_SB_DQ<9>")
	)
	(segment
		(start 63.009526 -288.97707)
		(end 63.009526 -289.181794)
		(width 0.14478)
		(layer "In13.Cu")
		(net "M_B_CPU1_SB_DQ<9>")
	)
	(segment
		(start 71.947786 -279.753314)
		(end 64.960246 -286.740854)
		(width 0.14478)
		(layer "In13.Cu")
		(net "M_B_CPU1_SB_DQ<9>")
	)
	(segment
		(start 76.64831 -279.920446)
		(end 76.481178 -279.753314)
		(width 0.0889)
		(layer "In13.Cu")
		(net "M_B_CPU1_SB_DQ<9>")
	)
	(segment
		(start 76.327762 -279.753314)
		(end 71.947786 -279.753314)
		(width 0.14478)
		(layer "In13.Cu")
		(net "M_B_CPU1_SB_DQ<9>")
	)
	(segment
		(start 60.870084 -292.11016)
		(end 58.848498 -292.11016)
		(width 0.14478)
		(layer "In13.Cu")
		(net "M_B_CPU1_SB_DQ<9>")
	)
	(segment
		(start 64.960246 -288.019998)
		(end 64.67602 -288.304224)
		(width 0.14478)
		(layer "In13.Cu")
		(net "M_B_CPU1_SB_DQ<9>")
	)
	(segment
		(start 56.745886 -292.960552)
		(end 56.745632 -292.960298)
		(width 0.14478)
		(layer "In13.Cu")
		(net "M_B_CPU1_SB_DQ<9>")
	)
	(segment
		(start 54.401974 -292.960552)
		(end 53.227732 -291.786564)
		(width 0.14478)
		(layer "In13.Cu")
		(net "M_B_CPU1_SB_DQ<9>")
	)
	(segment
		(start 79.64678 -280.078942)
		(end 79.488284 -279.920446)
		(width 0.0889)
		(layer "In13.Cu")
		(net "M_B_CPU1_SB_DQ<9>")
	)
	(segment
		(start 54.402228 -292.960298)
		(end 54.401974 -292.960552)
		(width 0.14478)
		(layer "In13.Cu")
		(net "M_B_CPU1_SB_DQ<9>")
	)
	(segment
		(start 58.292238 -292.370764)
		(end 58.031634 -292.11016)
		(width 0.14478)
		(layer "In13.Cu")
		(net "M_B_CPU1_SB_DQ<9>")
	)
	(segment
		(start 58.848498 -292.11016)
		(end 58.587894 -292.370764)
		(width 0.14478)
		(layer "In13.Cu")
		(net "M_B_CPU1_SB_DQ<9>")
	)
	(segment
		(start 64.081406 -288.898838)
		(end 63.89624 -289.084004)
		(width 0.14478)
		(layer "In13.Cu")
		(net "M_B_CPU1_SB_DQ<9>")
	)
	(segment
		(start 79.9338 -280.078942)
		(end 79.64678 -280.078942)
		(width 0.0889)
		(layer "In13.Cu")
		(net "M_B_CPU1_SB_DQ<9>")
	)
	(segment
		(start 64.67602 -288.304224)
		(end 64.471296 -288.304224)
		(width 0.14478)
		(layer "In13.Cu")
		(net "M_B_CPU1_SB_DQ<9>")
	)
	(segment
		(start 64.960246 -286.740854)
		(end 64.960246 -288.019998)
		(width 0.14478)
		(layer "In13.Cu")
		(net "M_B_CPU1_SB_DQ<9>")
	)
	(segment
		(start 58.587894 -292.370764)
		(end 58.292238 -292.370764)
		(width 0.14478)
		(layer "In13.Cu")
		(net "M_B_CPU1_SB_DQ<9>")
	)
	(segment
		(start 63.399416 -288.791904)
		(end 63.194692 -288.791904)
		(width 0.14478)
		(layer "In13.Cu")
		(net "M_B_CPU1_SB_DQ<9>")
	)
	(segment
		(start 83.702398 -280.083768)
		(end 83.694016 -280.078942)
		(width 0.0889)
		(layer "In13.Cu")
		(net "M_B_CPU1_SB_DQ<9>")
	)
	(segment
		(start 63.89624 -289.084004)
		(end 63.691516 -289.084004)
		(width 0.14478)
		(layer "In13.Cu")
		(net "M_B_CPU1_SB_DQ<9>")
	)
	(segment
		(start 88.402414 -280.083768)
		(end 88.394032 -280.078942)
		(width 0.0889)
		(layer "In13.Cu")
		(net "M_B_CPU1_SB_DQ<9>")
	)
	(segment
		(start 63.009526 -289.181794)
		(end 63.301626 -289.473894)
		(width 0.14478)
		(layer "In13.Cu")
		(net "M_B_CPU1_SB_DQ<9>")
	)
	(segment
		(start 63.974472 -288.012124)
		(end 63.789306 -288.19729)
		(width 0.14478)
		(layer "In13.Cu")
		(net "M_B_CPU1_SB_DQ<9>")
	)
	(segment
		(start 86.888066 -280.078942)
		(end 86.879684 -280.083768)
		(width 0.0889)
		(layer "In13.Cu")
		(net "M_B_CPU1_SB_DQ<9>")
	)
	(arc
		(start 86.879684 -280.083768)
		(mid 86.696176 -280.129262)
		(end 86.513924 -280.078942)
		(width 0.0889)
		(layer "In13.Cu")
		(net "M_B_CPU1_SB_DQ<9>")
	)
	(arc
		(start 85.93963 -280.083768)
		(mid 85.756122 -280.129262)
		(end 85.57387 -280.078942)
		(width 0.0889)
		(layer "In13.Cu")
		(net "M_B_CPU1_SB_DQ<9>")
	)
	(arc
		(start 86.513924 -280.078942)
		(mid 86.230968 -280.002765)
		(end 85.948012 -280.078942)
		(width 0.0889)
		(layer "In13.Cu")
		(net "M_B_CPU1_SB_DQ<9>")
	)
	(arc
		(start 87.82812 -280.078942)
		(mid 87.645869 -280.129292)
		(end 87.46236 -280.083768)
		(width 0.0889)
		(layer "In13.Cu")
		(net "M_B_CPU1_SB_DQ<9>")
	)
	(arc
		(start 80.308196 -280.078942)
		(mid 80.120998 -280.129324)
		(end 79.9338 -280.078942)
		(width 0.0889)
		(layer "In13.Cu")
		(net "M_B_CPU1_SB_DQ<9>")
	)
	(arc
		(start 84.068158 -280.078942)
		(mid 83.885907 -280.129292)
		(end 83.702398 -280.083768)
		(width 0.0889)
		(layer "In13.Cu")
		(net "M_B_CPU1_SB_DQ<9>")
	)
	(arc
		(start 88.768174 -280.078942)
		(mid 88.585923 -280.129292)
		(end 88.402414 -280.083768)
		(width 0.0889)
		(layer "In13.Cu")
		(net "M_B_CPU1_SB_DQ<9>")
	)
	(arc
		(start 80.874108 -280.078942)
		(mid 80.591152 -280.002765)
		(end 80.308196 -280.078942)
		(width 0.0889)
		(layer "In13.Cu")
		(net "M_B_CPU1_SB_DQ<9>")
	)
	(arc
		(start 83.128104 -280.078942)
		(mid 82.945853 -280.129292)
		(end 82.762344 -280.083768)
		(width 0.0889)
		(layer "In13.Cu")
		(net "M_B_CPU1_SB_DQ<9>")
	)
	(arc
		(start 81.247996 -280.078942)
		(mid 81.061052 -280.129197)
		(end 80.874108 -280.078942)
		(width 0.0889)
		(layer "In13.Cu")
		(net "M_B_CPU1_SB_DQ<9>")
	)
	(arc
		(start 82.753962 -280.078942)
		(mid 82.471006 -280.002765)
		(end 82.18805 -280.078942)
		(width 0.0889)
		(layer "In13.Cu")
		(net "M_B_CPU1_SB_DQ<9>")
	)
	(arc
		(start 85.007958 -280.078942)
		(mid 84.821014 -280.129197)
		(end 84.63407 -280.078942)
		(width 0.0889)
		(layer "In13.Cu")
		(net "M_B_CPU1_SB_DQ<9>")
	)
	(arc
		(start 88.394032 -280.078942)
		(mid 88.111076 -280.002765)
		(end 87.82812 -280.078942)
		(width 0.0889)
		(layer "In13.Cu")
		(net "M_B_CPU1_SB_DQ<9>")
	)
	(arc
		(start 83.694016 -280.078942)
		(mid 83.41106 -280.002765)
		(end 83.128104 -280.078942)
		(width 0.0889)
		(layer "In13.Cu")
		(net "M_B_CPU1_SB_DQ<9>")
	)
	(arc
		(start 82.179668 -280.083768)
		(mid 81.99616 -280.129262)
		(end 81.813908 -280.078942)
		(width 0.0889)
		(layer "In13.Cu")
		(net "M_B_CPU1_SB_DQ<9>")
	)
	(arc
		(start 81.813908 -280.078942)
		(mid 81.530952 -280.002765)
		(end 81.247996 -280.078942)
		(width 0.0889)
		(layer "In13.Cu")
		(net "M_B_CPU1_SB_DQ<9>")
	)
	(arc
		(start 84.63407 -280.078942)
		(mid 84.351114 -280.002765)
		(end 84.068158 -280.078942)
		(width 0.0889)
		(layer "In13.Cu")
		(net "M_B_CPU1_SB_DQ<9>")
	)
	(arc
		(start 85.57387 -280.078942)
		(mid 85.290914 -280.002765)
		(end 85.007958 -280.078942)
		(width 0.0889)
		(layer "In13.Cu")
		(net "M_B_CPU1_SB_DQ<9>")
	)
	(arc
		(start 89.271094 -280.047192)
		(mid 89.015886 -280.003715)
		(end 88.768174 -280.078942)
		(width 0.0889)
		(layer "In13.Cu")
		(net "M_B_CPU1_SB_DQ<9>")
	)
	(arc
		(start 87.453978 -280.078942)
		(mid 87.171022 -280.002765)
		(end 86.888066 -280.078942)
		(width 0.0889)
		(layer "In13.Cu")
		(net "M_B_CPU1_SB_DQ<9>")
	)
	(segment
		(start 88.577928 -278.680418)
		(end 88.111076 -278.946356)
		(width 0.10668)
		(layer "F.Cu")
		(net "M_B_CPU1_SB_DQ<8>")
	)
	(segment
		(start 55.624476 -291.26053)
		(end 55.918354 -290.966652)
		(width 0.14478)
		(layer "In13.Cu")
		(net "M_B_CPU1_SB_DQ<8>")
	)
	(segment
		(start 71.533004 -278.843994)
		(end 76.042266 -278.843994)
		(width 0.14478)
		(layer "In13.Cu")
		(net "M_B_CPU1_SB_DQ<8>")
	)
	(segment
		(start 80.39354 -279.26284)
		(end 80.403954 -279.268936)
		(width 0.0889)
		(layer "In13.Cu")
		(net "M_B_CPU1_SB_DQ<8>")
	)
	(segment
		(start 52.44846 -290.549584)
		(end 52.44846 -290.376102)
		(width 0.14478)
		(layer "In13.Cu")
		(net "M_B_CPU1_SB_DQ<8>")
	)
	(segment
		(start 85.10397 -279.268936)
		(end 85.112352 -279.273762)
		(width 0.0889)
		(layer "In13.Cu")
		(net "M_B_CPU1_SB_DQ<8>")
	)
	(segment
		(start 58.315098 -290.929822)
		(end 58.459878 -291.074602)
		(width 0.14478)
		(layer "In13.Cu")
		(net "M_B_CPU1_SB_DQ<8>")
	)
	(segment
		(start 78.523338 -279.268936)
		(end 78.523592 -279.268936)
		(width 0.0889)
		(layer "In13.Cu")
		(net "M_B_CPU1_SB_DQ<8>")
	)
	(segment
		(start 57.37606 -290.623498)
		(end 57.455816 -290.703254)
		(width 0.14478)
		(layer "In13.Cu")
		(net "M_B_CPU1_SB_DQ<8>")
	)
	(segment
		(start 61.652404 -289.796474)
		(end 61.83757 -289.611308)
		(width 0.14478)
		(layer "In13.Cu")
		(net "M_B_CPU1_SB_DQ<8>")
	)
	(segment
		(start 57.953402 -290.410392)
		(end 58.170318 -290.410392)
		(width 0.14478)
		(layer "In13.Cu")
		(net "M_B_CPU1_SB_DQ<8>")
	)
	(segment
		(start 57.455816 -290.703254)
		(end 57.66054 -290.703254)
		(width 0.14478)
		(layer "In13.Cu")
		(net "M_B_CPU1_SB_DQ<8>")
	)
	(segment
		(start 58.866278 -290.929822)
		(end 58.866278 -290.555172)
		(width 0.14478)
		(layer "In13.Cu")
		(net "M_B_CPU1_SB_DQ<8>")
	)
	(segment
		(start 60.726574 -289.855148)
		(end 60.726574 -289.650424)
		(width 0.14478)
		(layer "In13.Cu")
		(net "M_B_CPU1_SB_DQ<8>")
	)
	(segment
		(start 80.769714 -279.273762)
		(end 80.778096 -279.268936)
		(width 0.0889)
		(layer "In13.Cu")
		(net "M_B_CPU1_SB_DQ<8>")
	)
	(segment
		(start 61.05779 -290.391088)
		(end 61.05779 -290.186364)
		(width 0.14478)
		(layer "In13.Cu")
		(net "M_B_CPU1_SB_DQ<8>")
	)
	(segment
		(start 60.872624 -290.576254)
		(end 61.05779 -290.391088)
		(width 0.14478)
		(layer "In13.Cu")
		(net "M_B_CPU1_SB_DQ<8>")
	)
	(segment
		(start 57.065926 -291.297868)
		(end 57.06618 -291.093144)
		(width 0.14478)
		(layer "In13.Cu")
		(net "M_B_CPU1_SB_DQ<8>")
	)
	(segment
		(start 81.344008 -279.268936)
		(end 81.35239 -279.273762)
		(width 0.0889)
		(layer "In13.Cu")
		(net "M_B_CPU1_SB_DQ<8>")
	)
	(segment
		(start 56.313324 -291.127942)
		(end 56.313324 -291.494464)
		(width 0.14478)
		(layer "In13.Cu")
		(net "M_B_CPU1_SB_DQ<8>")
	)
	(segment
		(start 60.726574 -289.650424)
		(end 60.91174 -289.465258)
		(width 0.14478)
		(layer "In13.Cu")
		(net "M_B_CPU1_SB_DQ<8>")
	)
	(segment
		(start 61.05779 -290.186364)
		(end 60.726574 -289.855148)
		(width 0.14478)
		(layer "In13.Cu")
		(net "M_B_CPU1_SB_DQ<8>")
	)
	(segment
		(start 56.313324 -291.494464)
		(end 56.474614 -291.655754)
		(width 0.14478)
		(layer "In13.Cu")
		(net "M_B_CPU1_SB_DQ<8>")
	)
	(segment
		(start 78.080616 -278.843994)
		(end 78.446884 -279.210262)
		(width 0.0889)
		(layer "In13.Cu")
		(net "M_B_CPU1_SB_DQ<8>")
	)
	(segment
		(start 56.986424 -290.808664)
		(end 57.171844 -290.623244)
		(width 0.14478)
		(layer "In13.Cu")
		(net "M_B_CPU1_SB_DQ<8>")
	)
	(segment
		(start 57.66054 -290.703254)
		(end 57.953402 -290.410392)
		(width 0.14478)
		(layer "In13.Cu")
		(net "M_B_CPU1_SB_DQ<8>")
	)
	(segment
		(start 53.635656 -290.694364)
		(end 54.473856 -291.532564)
		(width 0.14478)
		(layer "In13.Cu")
		(net "M_B_CPU1_SB_DQ<8>")
	)
	(segment
		(start 60.91174 -289.465258)
		(end 61.116464 -289.465258)
		(width 0.14478)
		(layer "In13.Cu")
		(net "M_B_CPU1_SB_DQ<8>")
	)
	(segment
		(start 53.14442 -290.694364)
		(end 53.635656 -290.694364)
		(width 0.14478)
		(layer "In13.Cu")
		(net "M_B_CPU1_SB_DQ<8>")
	)
	(segment
		(start 54.960774 -291.532564)
		(end 55.232808 -291.26053)
		(width 0.14478)
		(layer "In13.Cu")
		(net "M_B_CPU1_SB_DQ<8>")
	)
	(segment
		(start 61.44768 -289.796474)
		(end 61.652404 -289.796474)
		(width 0.14478)
		(layer "In13.Cu")
		(net "M_B_CPU1_SB_DQ<8>")
	)
	(segment
		(start 52.30368 -290.694364)
		(end 52.44846 -290.549584)
		(width 0.14478)
		(layer "In13.Cu")
		(net "M_B_CPU1_SB_DQ<8>")
	)
	(segment
		(start 52.59324 -290.231322)
		(end 52.85486 -290.231322)
		(width 0.14478)
		(layer "In13.Cu")
		(net "M_B_CPU1_SB_DQ<8>")
	)
	(segment
		(start 78.897734 -279.268682)
		(end 78.903322 -279.26538)
		(width 0.0889)
		(layer "In13.Cu")
		(net "M_B_CPU1_SB_DQ<8>")
	)
	(segment
		(start 83.589622 -279.273762)
		(end 83.598004 -279.268936)
		(width 0.0889)
		(layer "In13.Cu")
		(net "M_B_CPU1_SB_DQ<8>")
	)
	(segment
		(start 52.99964 -290.376102)
		(end 52.99964 -290.549584)
		(width 0.14478)
		(layer "In13.Cu")
		(net "M_B_CPU1_SB_DQ<8>")
	)
	(segment
		(start 57.06618 -291.093144)
		(end 56.986424 -291.013388)
		(width 0.14478)
		(layer "In13.Cu")
		(net "M_B_CPU1_SB_DQ<8>")
	)
	(segment
		(start 59.966606 -290.410392)
		(end 60.13196 -290.245038)
		(width 0.14478)
		(layer "In13.Cu")
		(net "M_B_CPU1_SB_DQ<8>")
	)
	(segment
		(start 52.44846 -290.376102)
		(end 52.59324 -290.231322)
		(width 0.14478)
		(layer "In13.Cu")
		(net "M_B_CPU1_SB_DQ<8>")
	)
	(segment
		(start 60.6679 -290.576254)
		(end 60.872624 -290.576254)
		(width 0.14478)
		(layer "In13.Cu")
		(net "M_B_CPU1_SB_DQ<8>")
	)
	(segment
		(start 61.83757 -289.406584)
		(end 61.506354 -289.075368)
		(width 0.14478)
		(layer "In13.Cu")
		(net "M_B_CPU1_SB_DQ<8>")
	)
	(segment
		(start 54.473856 -291.532564)
		(end 54.960774 -291.532564)
		(width 0.14478)
		(layer "In13.Cu")
		(net "M_B_CPU1_SB_DQ<8>")
	)
	(segment
		(start 60.336684 -290.245038)
		(end 60.6679 -290.576254)
		(width 0.14478)
		(layer "In13.Cu")
		(net "M_B_CPU1_SB_DQ<8>")
	)
	(segment
		(start 56.474614 -291.655754)
		(end 56.70804 -291.655754)
		(width 0.14478)
		(layer "In13.Cu")
		(net "M_B_CPU1_SB_DQ<8>")
	)
	(segment
		(start 58.315098 -290.555172)
		(end 58.315098 -290.929822)
		(width 0.14478)
		(layer "In13.Cu")
		(net "M_B_CPU1_SB_DQ<8>")
	)
	(segment
		(start 56.986424 -291.013388)
		(end 56.986424 -290.808664)
		(width 0.14478)
		(layer "In13.Cu")
		(net "M_B_CPU1_SB_DQ<8>")
	)
	(segment
		(start 58.866278 -290.555172)
		(end 59.011058 -290.410392)
		(width 0.14478)
		(layer "In13.Cu")
		(net "M_B_CPU1_SB_DQ<8>")
	)
	(segment
		(start 58.721498 -291.074602)
		(end 58.866278 -290.929822)
		(width 0.14478)
		(layer "In13.Cu")
		(net "M_B_CPU1_SB_DQ<8>")
	)
	(segment
		(start 52.025042 -290.694364)
		(end 52.30368 -290.694364)
		(width 0.14478)
		(layer "In13.Cu")
		(net "M_B_CPU1_SB_DQ<8>")
	)
	(segment
		(start 78.879446 -279.279096)
		(end 78.897734 -279.268682)
		(width 0.0889)
		(layer "In13.Cu")
		(net "M_B_CPU1_SB_DQ<8>")
	)
	(segment
		(start 61.506354 -288.870644)
		(end 71.533004 -278.843994)
		(width 0.14478)
		(layer "In13.Cu")
		(net "M_B_CPU1_SB_DQ<8>")
	)
	(segment
		(start 58.459878 -291.074602)
		(end 58.721498 -291.074602)
		(width 0.14478)
		(layer "In13.Cu")
		(net "M_B_CPU1_SB_DQ<8>")
	)
	(segment
		(start 57.171844 -290.623244)
		(end 57.37606 -290.623498)
		(width 0.14478)
		(layer "In13.Cu")
		(net "M_B_CPU1_SB_DQ<8>")
	)
	(segment
		(start 76.042266 -278.843994)
		(end 78.080616 -278.843994)
		(width 0.0889)
		(layer "In13.Cu")
		(net "M_B_CPU1_SB_DQ<8>")
	)
	(segment
		(start 61.83757 -289.611308)
		(end 61.83757 -289.406584)
		(width 0.14478)
		(layer "In13.Cu")
		(net "M_B_CPU1_SB_DQ<8>")
	)
	(segment
		(start 59.011058 -290.410392)
		(end 59.966606 -290.410392)
		(width 0.14478)
		(layer "In13.Cu")
		(net "M_B_CPU1_SB_DQ<8>")
	)
	(segment
		(start 56.70804 -291.655754)
		(end 57.065926 -291.297868)
		(width 0.14478)
		(layer "In13.Cu")
		(net "M_B_CPU1_SB_DQ<8>")
	)
	(segment
		(start 86.044024 -279.268936)
		(end 86.052406 -279.273762)
		(width 0.0889)
		(layer "In13.Cu")
		(net "M_B_CPU1_SB_DQ<8>")
	)
	(segment
		(start 60.13196 -290.245038)
		(end 60.336684 -290.245038)
		(width 0.14478)
		(layer "In13.Cu")
		(net "M_B_CPU1_SB_DQ<8>")
	)
	(segment
		(start 87.956898 -279.211786)
		(end 88.111076 -278.946356)
		(width 0.0889)
		(layer "In13.Cu")
		(net "M_B_CPU1_SB_DQ<8>")
	)
	(segment
		(start 84.529676 -279.273762)
		(end 84.538058 -279.268936)
		(width 0.0889)
		(layer "In13.Cu")
		(net "M_B_CPU1_SB_DQ<8>")
	)
	(segment
		(start 58.170318 -290.410392)
		(end 58.315098 -290.555172)
		(width 0.14478)
		(layer "In13.Cu")
		(net "M_B_CPU1_SB_DQ<8>")
	)
	(segment
		(start 52.85486 -290.231322)
		(end 52.99964 -290.376102)
		(width 0.14478)
		(layer "In13.Cu")
		(net "M_B_CPU1_SB_DQ<8>")
	)
	(segment
		(start 55.918354 -290.966652)
		(end 56.152034 -290.966652)
		(width 0.14478)
		(layer "In13.Cu")
		(net "M_B_CPU1_SB_DQ<8>")
	)
	(segment
		(start 52.99964 -290.549584)
		(end 53.14442 -290.694364)
		(width 0.14478)
		(layer "In13.Cu")
		(net "M_B_CPU1_SB_DQ<8>")
	)
	(segment
		(start 55.232808 -291.26053)
		(end 55.624476 -291.26053)
		(width 0.14478)
		(layer "In13.Cu")
		(net "M_B_CPU1_SB_DQ<8>")
	)
	(segment
		(start 56.152034 -290.966652)
		(end 56.313324 -291.127942)
		(width 0.14478)
		(layer "In13.Cu")
		(net "M_B_CPU1_SB_DQ<8>")
	)
	(segment
		(start 87.860632 -279.237186)
		(end 87.956898 -279.211786)
		(width 0.0889)
		(layer "In13.Cu")
		(net "M_B_CPU1_SB_DQ<8>")
	)
	(segment
		(start 61.116464 -289.465258)
		(end 61.44768 -289.796474)
		(width 0.14478)
		(layer "In13.Cu")
		(net "M_B_CPU1_SB_DQ<8>")
	)
	(segment
		(start 51.884072 -290.835334)
		(end 52.025042 -290.694364)
		(width 0.14478)
		(layer "In13.Cu")
		(net "M_B_CPU1_SB_DQ<8>")
	)
	(segment
		(start 79.463138 -279.268936)
		(end 79.47152 -279.273762)
		(width 0.0889)
		(layer "In13.Cu")
		(net "M_B_CPU1_SB_DQ<8>")
	)
	(segment
		(start 61.506354 -289.075368)
		(end 61.506354 -288.870644)
		(width 0.14478)
		(layer "In13.Cu")
		(net "M_B_CPU1_SB_DQ<8>")
	)
	(arc
		(start 85.112352 -279.273762)
		(mid 85.29586 -279.319256)
		(end 85.478112 -279.268936)
		(width 0.0889)
		(layer "In13.Cu")
		(net "M_B_CPU1_SB_DQ<8>")
	)
	(arc
		(start 84.538058 -279.268936)
		(mid 84.821014 -279.192759)
		(end 85.10397 -279.268936)
		(width 0.0889)
		(layer "In13.Cu")
		(net "M_B_CPU1_SB_DQ<8>")
	)
	(arc
		(start 78.903322 -279.26538)
		(mid 79.183711 -279.192711)
		(end 79.463138 -279.268936)
		(width 0.0889)
		(layer "In13.Cu")
		(net "M_B_CPU1_SB_DQ<8>")
	)
	(arc
		(start 78.523592 -279.268936)
		(mid 78.70022 -279.319169)
		(end 78.879446 -279.279096)
		(width 0.0889)
		(layer "In13.Cu")
		(net "M_B_CPU1_SB_DQ<8>")
	)
	(arc
		(start 79.47152 -279.273762)
		(mid 79.655282 -279.319378)
		(end 79.837788 -279.268936)
		(width 0.0889)
		(layer "In13.Cu")
		(net "M_B_CPU1_SB_DQ<8>")
	)
	(arc
		(start 84.163916 -279.268936)
		(mid 84.346167 -279.319286)
		(end 84.529676 -279.273762)
		(width 0.0889)
		(layer "In13.Cu")
		(net "M_B_CPU1_SB_DQ<8>")
	)
	(arc
		(start 86.984078 -279.268936)
		(mid 87.171022 -279.319191)
		(end 87.357966 -279.268936)
		(width 0.0889)
		(layer "In13.Cu")
		(net "M_B_CPU1_SB_DQ<8>")
	)
	(arc
		(start 80.778096 -279.268936)
		(mid 81.061052 -279.192759)
		(end 81.344008 -279.268936)
		(width 0.0889)
		(layer "In13.Cu")
		(net "M_B_CPU1_SB_DQ<8>")
	)
	(arc
		(start 83.598004 -279.268936)
		(mid 83.88096 -279.192759)
		(end 84.163916 -279.268936)
		(width 0.0889)
		(layer "In13.Cu")
		(net "M_B_CPU1_SB_DQ<8>")
	)
	(arc
		(start 80.403954 -279.268936)
		(mid 80.586205 -279.319286)
		(end 80.769714 -279.273762)
		(width 0.0889)
		(layer "In13.Cu")
		(net "M_B_CPU1_SB_DQ<8>")
	)
	(arc
		(start 82.284062 -279.268936)
		(mid 82.471006 -279.319191)
		(end 82.65795 -279.268936)
		(width 0.0889)
		(layer "In13.Cu")
		(net "M_B_CPU1_SB_DQ<8>")
	)
	(arc
		(start 87.357966 -279.268936)
		(mid 87.605562 -279.193758)
		(end 87.860632 -279.237186)
		(width 0.0889)
		(layer "In13.Cu")
		(net "M_B_CPU1_SB_DQ<8>")
	)
	(arc
		(start 78.446884 -279.210262)
		(mid 78.483211 -279.242075)
		(end 78.523338 -279.268936)
		(width 0.0889)
		(layer "In13.Cu")
		(net "M_B_CPU1_SB_DQ<8>")
	)
	(arc
		(start 81.71815 -279.268936)
		(mid 82.001106 -279.192759)
		(end 82.284062 -279.268936)
		(width 0.0889)
		(layer "In13.Cu")
		(net "M_B_CPU1_SB_DQ<8>")
	)
	(arc
		(start 83.223862 -279.268936)
		(mid 83.406113 -279.319286)
		(end 83.589622 -279.273762)
		(width 0.0889)
		(layer "In13.Cu")
		(net "M_B_CPU1_SB_DQ<8>")
	)
	(arc
		(start 85.478112 -279.268936)
		(mid 85.761068 -279.192759)
		(end 86.044024 -279.268936)
		(width 0.0889)
		(layer "In13.Cu")
		(net "M_B_CPU1_SB_DQ<8>")
	)
	(arc
		(start 86.418166 -279.268936)
		(mid 86.701122 -279.192759)
		(end 86.984078 -279.268936)
		(width 0.0889)
		(layer "In13.Cu")
		(net "M_B_CPU1_SB_DQ<8>")
	)
	(arc
		(start 86.052406 -279.273762)
		(mid 86.235914 -279.319256)
		(end 86.418166 -279.268936)
		(width 0.0889)
		(layer "In13.Cu")
		(net "M_B_CPU1_SB_DQ<8>")
	)
	(arc
		(start 81.35239 -279.273762)
		(mid 81.535898 -279.319256)
		(end 81.71815 -279.268936)
		(width 0.0889)
		(layer "In13.Cu")
		(net "M_B_CPU1_SB_DQ<8>")
	)
	(arc
		(start 79.837788 -279.268936)
		(mid 80.114855 -279.192665)
		(end 80.39354 -279.26284)
		(width 0.0889)
		(layer "In13.Cu")
		(net "M_B_CPU1_SB_DQ<8>")
	)
	(arc
		(start 82.65795 -279.268936)
		(mid 82.940906 -279.192759)
		(end 83.223862 -279.268936)
		(width 0.0889)
		(layer "In13.Cu")
		(net "M_B_CPU1_SB_DQ<8>")
	)
	(segment
		(start 89.517982 -278.680418)
		(end 89.05113 -278.946356)
		(width 0.10668)
		(layer "F.Cu")
		(net "M_B_CPU1_SB_DQ<7>")
	)
	(segment
		(start 79.334868 -278.487886)
		(end 76.82738 -278.487886)
		(width 0.0889)
		(layer "In13.Cu")
		(net "M_B_CPU1_SB_DQ<7>")
	)
	(segment
		(start 59.402218 -289.560254)
		(end 57.621424 -289.91433)
		(width 0.14478)
		(layer "In13.Cu")
		(net "M_B_CPU1_SB_DQ<7>")
	)
	(segment
		(start 71.309738 -278.287734)
		(end 60.269374 -289.328098)
		(width 0.14478)
		(layer "In13.Cu")
		(net "M_B_CPU1_SB_DQ<7>")
	)
	(segment
		(start 51.749706 -289.560254)
		(end 47.784004 -289.98545)
		(width 0.14478)
		(layer "In13.Cu")
		(net "M_B_CPU1_SB_DQ<7>")
	)
	(segment
		(start 89.05113 -278.946356)
		(end 89.205054 -278.680926)
		(width 0.0889)
		(layer "In13.Cu")
		(net "M_B_CPU1_SB_DQ<7>")
	)
	(segment
		(start 76.034392 -278.287734)
		(end 71.309738 -278.287734)
		(width 0.14478)
		(layer "In13.Cu")
		(net "M_B_CPU1_SB_DQ<7>")
	)
	(segment
		(start 53.819552 -290.033964)
		(end 52.67579 -289.560254)
		(width 0.14478)
		(layer "In13.Cu")
		(net "M_B_CPU1_SB_DQ<7>")
	)
	(segment
		(start 86.052406 -278.61895)
		(end 86.044024 -278.623776)
		(width 0.0889)
		(layer "In13.Cu")
		(net "M_B_CPU1_SB_DQ<7>")
	)
	(segment
		(start 81.35239 -278.61895)
		(end 81.344008 -278.623776)
		(width 0.0889)
		(layer "In13.Cu")
		(net "M_B_CPU1_SB_DQ<7>")
	)
	(segment
		(start 85.112352 -278.61895)
		(end 85.10397 -278.623776)
		(width 0.0889)
		(layer "In13.Cu")
		(net "M_B_CPU1_SB_DQ<7>")
	)
	(segment
		(start 89.205054 -278.680926)
		(end 89.182702 -278.597614)
		(width 0.0889)
		(layer "In13.Cu")
		(net "M_B_CPU1_SB_DQ<7>")
	)
	(segment
		(start 88.29802 -278.623776)
		(end 88.289638 -278.61895)
		(width 0.0889)
		(layer "In13.Cu")
		(net "M_B_CPU1_SB_DQ<7>")
	)
	(segment
		(start 76.580238 -278.287734)
		(end 76.034392 -278.287734)
		(width 0.0889)
		(layer "In13.Cu")
		(net "M_B_CPU1_SB_DQ<7>")
	)
	(segment
		(start 59.708796 -289.560254)
		(end 59.402218 -289.560254)
		(width 0.14478)
		(layer "In13.Cu")
		(net "M_B_CPU1_SB_DQ<7>")
	)
	(segment
		(start 57.621424 -289.91433)
		(end 57.33288 -290.033964)
		(width 0.14478)
		(layer "In13.Cu")
		(net "M_B_CPU1_SB_DQ<7>")
	)
	(segment
		(start 83.598004 -278.623776)
		(end 83.589622 -278.61895)
		(width 0.0889)
		(layer "In13.Cu")
		(net "M_B_CPU1_SB_DQ<7>")
	)
	(segment
		(start 57.33288 -290.033964)
		(end 53.819552 -290.033964)
		(width 0.14478)
		(layer "In13.Cu")
		(net "M_B_CPU1_SB_DQ<7>")
	)
	(segment
		(start 80.403954 -278.623776)
		(end 80.39354 -278.629872)
		(width 0.0889)
		(layer "In13.Cu")
		(net "M_B_CPU1_SB_DQ<7>")
	)
	(segment
		(start 80.778096 -278.623776)
		(end 80.769714 -278.61895)
		(width 0.0889)
		(layer "In13.Cu")
		(net "M_B_CPU1_SB_DQ<7>")
	)
	(segment
		(start 60.269374 -289.328098)
		(end 59.708796 -289.560254)
		(width 0.14478)
		(layer "In13.Cu")
		(net "M_B_CPU1_SB_DQ<7>")
	)
	(segment
		(start 52.67579 -289.560254)
		(end 51.749706 -289.560254)
		(width 0.14478)
		(layer "In13.Cu")
		(net "M_B_CPU1_SB_DQ<7>")
	)
	(segment
		(start 76.747116 -278.454612)
		(end 76.580238 -278.287734)
		(width 0.0889)
		(layer "In13.Cu")
		(net "M_B_CPU1_SB_DQ<7>")
	)
	(segment
		(start 84.538058 -278.623776)
		(end 84.529676 -278.61895)
		(width 0.0889)
		(layer "In13.Cu")
		(net "M_B_CPU1_SB_DQ<7>")
	)
	(arc
		(start 86.418166 -278.623776)
		(mid 86.235915 -278.573426)
		(end 86.052406 -278.61895)
		(width 0.0889)
		(layer "In13.Cu")
		(net "M_B_CPU1_SB_DQ<7>")
	)
	(arc
		(start 87.357966 -278.623776)
		(mid 87.171022 -278.573521)
		(end 86.984078 -278.623776)
		(width 0.0889)
		(layer "In13.Cu")
		(net "M_B_CPU1_SB_DQ<7>")
	)
	(arc
		(start 81.344008 -278.623776)
		(mid 81.061052 -278.699953)
		(end 80.778096 -278.623776)
		(width 0.0889)
		(layer "In13.Cu")
		(net "M_B_CPU1_SB_DQ<7>")
	)
	(arc
		(start 83.589622 -278.61895)
		(mid 83.406114 -278.573456)
		(end 83.223862 -278.623776)
		(width 0.0889)
		(layer "In13.Cu")
		(net "M_B_CPU1_SB_DQ<7>")
	)
	(arc
		(start 82.65795 -278.623776)
		(mid 82.471006 -278.573521)
		(end 82.284062 -278.623776)
		(width 0.0889)
		(layer "In13.Cu")
		(net "M_B_CPU1_SB_DQ<7>")
	)
	(arc
		(start 86.984078 -278.623776)
		(mid 86.701122 -278.699953)
		(end 86.418166 -278.623776)
		(width 0.0889)
		(layer "In13.Cu")
		(net "M_B_CPU1_SB_DQ<7>")
	)
	(arc
		(start 82.284062 -278.623776)
		(mid 82.001106 -278.699953)
		(end 81.71815 -278.623776)
		(width 0.0889)
		(layer "In13.Cu")
		(net "M_B_CPU1_SB_DQ<7>")
	)
	(arc
		(start 84.163916 -278.623776)
		(mid 83.88096 -278.699953)
		(end 83.598004 -278.623776)
		(width 0.0889)
		(layer "In13.Cu")
		(net "M_B_CPU1_SB_DQ<7>")
	)
	(arc
		(start 85.10397 -278.623776)
		(mid 84.821014 -278.699953)
		(end 84.538058 -278.623776)
		(width 0.0889)
		(layer "In13.Cu")
		(net "M_B_CPU1_SB_DQ<7>")
	)
	(arc
		(start 89.182702 -278.597614)
		(mid 89.02037 -278.574796)
		(end 88.863932 -278.623776)
		(width 0.0889)
		(layer "In13.Cu")
		(net "M_B_CPU1_SB_DQ<7>")
	)
	(arc
		(start 81.71815 -278.623776)
		(mid 81.535899 -278.573426)
		(end 81.35239 -278.61895)
		(width 0.0889)
		(layer "In13.Cu")
		(net "M_B_CPU1_SB_DQ<7>")
	)
	(arc
		(start 84.529676 -278.61895)
		(mid 84.346168 -278.573456)
		(end 84.163916 -278.623776)
		(width 0.0889)
		(layer "In13.Cu")
		(net "M_B_CPU1_SB_DQ<7>")
	)
	(arc
		(start 83.223862 -278.623776)
		(mid 82.940906 -278.699953)
		(end 82.65795 -278.623776)
		(width 0.0889)
		(layer "In13.Cu")
		(net "M_B_CPU1_SB_DQ<7>")
	)
	(arc
		(start 88.863932 -278.623776)
		(mid 88.580976 -278.699953)
		(end 88.29802 -278.623776)
		(width 0.0889)
		(layer "In13.Cu")
		(net "M_B_CPU1_SB_DQ<7>")
	)
	(arc
		(start 85.478112 -278.623776)
		(mid 85.295861 -278.573426)
		(end 85.112352 -278.61895)
		(width 0.0889)
		(layer "In13.Cu")
		(net "M_B_CPU1_SB_DQ<7>")
	)
	(arc
		(start 80.769714 -278.61895)
		(mid 80.586206 -278.573456)
		(end 80.403954 -278.623776)
		(width 0.0889)
		(layer "In13.Cu")
		(net "M_B_CPU1_SB_DQ<7>")
	)
	(arc
		(start 80.39354 -278.629872)
		(mid 80.114854 -278.700092)
		(end 79.837788 -278.623776)
		(width 0.0889)
		(layer "In13.Cu")
		(net "M_B_CPU1_SB_DQ<7>")
	)
	(arc
		(start 87.923878 -278.623776)
		(mid 87.640922 -278.699953)
		(end 87.357966 -278.623776)
		(width 0.0889)
		(layer "In13.Cu")
		(net "M_B_CPU1_SB_DQ<7>")
	)
	(arc
		(start 88.289638 -278.61895)
		(mid 88.10613 -278.573456)
		(end 87.923878 -278.623776)
		(width 0.0889)
		(layer "In13.Cu")
		(net "M_B_CPU1_SB_DQ<7>")
	)
	(arc
		(start 86.044024 -278.623776)
		(mid 85.761068 -278.699953)
		(end 85.478112 -278.623776)
		(width 0.0889)
		(layer "In13.Cu")
		(net "M_B_CPU1_SB_DQ<7>")
	)
	(arc
		(start 79.837788 -278.623776)
		(mid 79.595348 -278.522446)
		(end 79.334868 -278.487886)
		(width 0.0889)
		(layer "In13.Cu")
		(net "M_B_CPU1_SB_DQ<7>")
	)
	(arc
		(start 76.82738 -278.487886)
		(mid 76.783945 -278.479228)
		(end 76.747116 -278.454612)
		(width 0.0889)
		(layer "In13.Cu")
		(net "M_B_CPU1_SB_DQ<7>")
	)
	(segment
		(start 88.107774 -277.870412)
		(end 87.640922 -278.13635)
		(width 0.10668)
		(layer "F.Cu")
		(net "M_B_CPU1_SB_DQ<6>")
	)
	(segment
		(start 82.753962 -277.81377)
		(end 82.762344 -277.808944)
		(width 0.0889)
		(layer "In13.Cu")
		(net "M_B_CPU1_SB_DQ<6>")
	)
	(segment
		(start 82.179668 -277.808944)
		(end 82.18805 -277.81377)
		(width 0.0889)
		(layer "In13.Cu")
		(net "M_B_CPU1_SB_DQ<6>")
	)
	(segment
		(start 80.299814 -277.808944)
		(end 80.308196 -277.81377)
		(width 0.0889)
		(layer "In13.Cu")
		(net "M_B_CPU1_SB_DQ<6>")
	)
	(segment
		(start 50.542952 -288.285428)
		(end 50.968148 -287.860232)
		(width 0.14478)
		(layer "In13.Cu")
		(net "M_B_CPU1_SB_DQ<6>")
	)
	(segment
		(start 77.969618 -277.378414)
		(end 78.481174 -277.88997)
		(width 0.0889)
		(layer "In13.Cu")
		(net "M_B_CPU1_SB_DQ<6>")
	)
	(segment
		(start 83.694016 -277.81377)
		(end 83.702398 -277.808944)
		(width 0.0889)
		(layer "In13.Cu")
		(net "M_B_CPU1_SB_DQ<6>")
	)
	(segment
		(start 85.948012 -277.81377)
		(end 85.948266 -277.81377)
		(width 0.0889)
		(layer "In13.Cu")
		(net "M_B_CPU1_SB_DQ<6>")
	)
	(segment
		(start 47.784004 -288.285428)
		(end 50.542952 -288.285428)
		(width 0.14478)
		(layer "In13.Cu")
		(net "M_B_CPU1_SB_DQ<6>")
	)
	(segment
		(start 57.447434 -288.71037)
		(end 58.297572 -287.860232)
		(width 0.14478)
		(layer "In13.Cu")
		(net "M_B_CPU1_SB_DQ<6>")
	)
	(segment
		(start 78.993492 -277.814024)
		(end 79.009748 -277.804626)
		(width 0.0889)
		(layer "In13.Cu")
		(net "M_B_CPU1_SB_DQ<6>")
	)
	(segment
		(start 86.879684 -277.808944)
		(end 86.888066 -277.81377)
		(width 0.0889)
		(layer "In13.Cu")
		(net "M_B_CPU1_SB_DQ<6>")
	)
	(segment
		(start 75.954636 -277.378414)
		(end 77.969618 -277.378414)
		(width 0.0889)
		(layer "In13.Cu")
		(net "M_B_CPU1_SB_DQ<6>")
	)
	(segment
		(start 50.968148 -287.860232)
		(end 53.23078 -287.860232)
		(width 0.14478)
		(layer "In13.Cu")
		(net "M_B_CPU1_SB_DQ<6>")
	)
	(segment
		(start 79.36738 -277.81377)
		(end 79.377794 -277.819866)
		(width 0.0889)
		(layer "In13.Cu")
		(net "M_B_CPU1_SB_DQ<6>")
	)
	(segment
		(start 60.464954 -287.860232)
		(end 70.946772 -277.378414)
		(width 0.14478)
		(layer "In13.Cu")
		(net "M_B_CPU1_SB_DQ<6>")
	)
	(segment
		(start 87.7951 -277.87092)
		(end 87.640922 -278.13635)
		(width 0.0889)
		(layer "In13.Cu")
		(net "M_B_CPU1_SB_DQ<6>")
	)
	(segment
		(start 53.23078 -287.860232)
		(end 54.080918 -288.71037)
		(width 0.14478)
		(layer "In13.Cu")
		(net "M_B_CPU1_SB_DQ<6>")
	)
	(segment
		(start 54.080918 -288.71037)
		(end 57.447434 -288.71037)
		(width 0.14478)
		(layer "In13.Cu")
		(net "M_B_CPU1_SB_DQ<6>")
	)
	(segment
		(start 87.453978 -277.81377)
		(end 87.46236 -277.808944)
		(width 0.0889)
		(layer "In13.Cu")
		(net "M_B_CPU1_SB_DQ<6>")
	)
	(segment
		(start 85.93963 -277.808944)
		(end 85.948012 -277.81377)
		(width 0.0889)
		(layer "In13.Cu")
		(net "M_B_CPU1_SB_DQ<6>")
	)
	(segment
		(start 58.297572 -287.860232)
		(end 60.464954 -287.860232)
		(width 0.14478)
		(layer "In13.Cu")
		(net "M_B_CPU1_SB_DQ<6>")
	)
	(segment
		(start 70.946772 -277.378414)
		(end 75.954636 -277.378414)
		(width 0.14478)
		(layer "In13.Cu")
		(net "M_B_CPU1_SB_DQ<6>")
	)
	(segment
		(start 87.772748 -277.787608)
		(end 87.7951 -277.87092)
		(width 0.0889)
		(layer "In13.Cu")
		(net "M_B_CPU1_SB_DQ<6>")
	)
	(segment
		(start 78.481174 -277.88997)
		(end 78.711044 -277.88997)
		(width 0.0889)
		(layer "In13.Cu")
		(net "M_B_CPU1_SB_DQ<6>")
	)
	(arc
		(start 81.813908 -277.81377)
		(mid 81.996159 -277.76342)
		(end 82.179668 -277.808944)
		(width 0.0889)
		(layer "In13.Cu")
		(net "M_B_CPU1_SB_DQ<6>")
	)
	(arc
		(start 80.874108 -277.81377)
		(mid 81.061052 -277.763515)
		(end 81.247996 -277.81377)
		(width 0.0889)
		(layer "In13.Cu")
		(net "M_B_CPU1_SB_DQ<6>")
	)
	(arc
		(start 84.068158 -277.81377)
		(mid 84.351114 -277.889947)
		(end 84.63407 -277.81377)
		(width 0.0889)
		(layer "In13.Cu")
		(net "M_B_CPU1_SB_DQ<6>")
	)
	(arc
		(start 81.247996 -277.81377)
		(mid 81.530952 -277.889947)
		(end 81.813908 -277.81377)
		(width 0.0889)
		(layer "In13.Cu")
		(net "M_B_CPU1_SB_DQ<6>")
	)
	(arc
		(start 87.46236 -277.808944)
		(mid 87.61523 -277.764303)
		(end 87.772748 -277.787608)
		(width 0.0889)
		(layer "In13.Cu")
		(net "M_B_CPU1_SB_DQ<6>")
	)
	(arc
		(start 82.18805 -277.81377)
		(mid 82.471006 -277.889947)
		(end 82.753962 -277.81377)
		(width 0.0889)
		(layer "In13.Cu")
		(net "M_B_CPU1_SB_DQ<6>")
	)
	(arc
		(start 85.57387 -277.81377)
		(mid 85.756121 -277.76342)
		(end 85.93963 -277.808944)
		(width 0.0889)
		(layer "In13.Cu")
		(net "M_B_CPU1_SB_DQ<6>")
	)
	(arc
		(start 85.007958 -277.81377)
		(mid 85.290914 -277.889947)
		(end 85.57387 -277.81377)
		(width 0.0889)
		(layer "In13.Cu")
		(net "M_B_CPU1_SB_DQ<6>")
	)
	(arc
		(start 82.762344 -277.808944)
		(mid 82.945852 -277.76345)
		(end 83.128104 -277.81377)
		(width 0.0889)
		(layer "In13.Cu")
		(net "M_B_CPU1_SB_DQ<6>")
	)
	(arc
		(start 83.128104 -277.81377)
		(mid 83.41106 -277.889947)
		(end 83.694016 -277.81377)
		(width 0.0889)
		(layer "In13.Cu")
		(net "M_B_CPU1_SB_DQ<6>")
	)
	(arc
		(start 84.63407 -277.81377)
		(mid 84.821014 -277.763515)
		(end 85.007958 -277.81377)
		(width 0.0889)
		(layer "In13.Cu")
		(net "M_B_CPU1_SB_DQ<6>")
	)
	(arc
		(start 85.948266 -277.81377)
		(mid 86.231112 -277.889947)
		(end 86.513924 -277.81377)
		(width 0.0889)
		(layer "In13.Cu")
		(net "M_B_CPU1_SB_DQ<6>")
	)
	(arc
		(start 80.308196 -277.81377)
		(mid 80.591152 -277.889947)
		(end 80.874108 -277.81377)
		(width 0.0889)
		(layer "In13.Cu")
		(net "M_B_CPU1_SB_DQ<6>")
	)
	(arc
		(start 86.888066 -277.81377)
		(mid 87.171022 -277.889947)
		(end 87.453978 -277.81377)
		(width 0.0889)
		(layer "In13.Cu")
		(net "M_B_CPU1_SB_DQ<6>")
	)
	(arc
		(start 86.513924 -277.81377)
		(mid 86.696175 -277.76342)
		(end 86.879684 -277.808944)
		(width 0.0889)
		(layer "In13.Cu")
		(net "M_B_CPU1_SB_DQ<6>")
	)
	(arc
		(start 78.711044 -277.88997)
		(mid 78.857292 -277.870665)
		(end 78.993492 -277.814024)
		(width 0.0889)
		(layer "In13.Cu")
		(net "M_B_CPU1_SB_DQ<6>")
	)
	(arc
		(start 83.702398 -277.808944)
		(mid 83.885906 -277.76345)
		(end 84.068158 -277.81377)
		(width 0.0889)
		(layer "In13.Cu")
		(net "M_B_CPU1_SB_DQ<6>")
	)
	(arc
		(start 79.377794 -277.819866)
		(mid 79.65648 -277.890086)
		(end 79.933546 -277.81377)
		(width 0.0889)
		(layer "In13.Cu")
		(net "M_B_CPU1_SB_DQ<6>")
	)
	(arc
		(start 79.933546 -277.81377)
		(mid 80.116051 -277.763293)
		(end 80.299814 -277.808944)
		(width 0.0889)
		(layer "In13.Cu")
		(net "M_B_CPU1_SB_DQ<6>")
	)
	(arc
		(start 79.009748 -277.804626)
		(mid 79.18973 -277.763526)
		(end 79.36738 -277.81377)
		(width 0.0889)
		(layer "In13.Cu")
		(net "M_B_CPU1_SB_DQ<6>")
	)
	(segment
		(start 89.987882 -277.870412)
		(end 89.52103 -278.13635)
		(width 0.10668)
		(layer "F.Cu")
		(net "M_B_CPU1_SB_DQ<5>")
	)
	(segment
		(start 71.128382 -277.833074)
		(end 76.034392 -277.833074)
		(width 0.14478)
		(layer "In13.Cu")
		(net "M_B_CPU1_SB_DQ<5>")
	)
	(segment
		(start 86.879684 -278.463756)
		(end 86.888066 -278.45893)
		(width 0.0889)
		(layer "In13.Cu")
		(net "M_B_CPU1_SB_DQ<5>")
	)
	(segment
		(start 52.324254 -289.110674)
		(end 52.469034 -288.965894)
		(width 0.14478)
		(layer "In13.Cu")
		(net "M_B_CPU1_SB_DQ<5>")
	)
	(segment
		(start 53.020214 -288.46526)
		(end 53.020214 -288.965894)
		(width 0.14478)
		(layer "In13.Cu")
		(net "M_B_CPU1_SB_DQ<5>")
	)
	(segment
		(start 59.177682 -289.139376)
		(end 59.322462 -288.994596)
		(width 0.14478)
		(layer "In13.Cu")
		(net "M_B_CPU1_SB_DQ<5>")
	)
	(segment
		(start 76.529438 -277.833074)
		(end 76.927456 -278.231092)
		(width 0.0889)
		(layer "In13.Cu")
		(net "M_B_CPU1_SB_DQ<5>")
	)
	(segment
		(start 54.70652 -289.167824)
		(end 54.8513 -289.312604)
		(width 0.14478)
		(layer "In13.Cu")
		(net "M_B_CPU1_SB_DQ<5>")
	)
	(segment
		(start 54.99608 -289.560508)
		(end 56.09463 -289.560508)
		(width 0.14478)
		(layer "In13.Cu")
		(net "M_B_CPU1_SB_DQ<5>")
	)
	(segment
		(start 58.221372 -288.621978)
		(end 58.626502 -288.621978)
		(width 0.14478)
		(layer "In13.Cu")
		(net "M_B_CPU1_SB_DQ<5>")
	)
	(segment
		(start 88.394032 -278.45893)
		(end 88.402414 -278.463756)
		(width 0.0889)
		(layer "In13.Cu")
		(net "M_B_CPU1_SB_DQ<5>")
	)
	(segment
		(start 59.467242 -288.71037)
		(end 60.251086 -288.71037)
		(width 0.14478)
		(layer "In13.Cu")
		(net "M_B_CPU1_SB_DQ<5>")
	)
	(segment
		(start 82.753962 -278.45893)
		(end 82.762344 -278.463756)
		(width 0.0889)
		(layer "In13.Cu")
		(net "M_B_CPU1_SB_DQ<5>")
	)
	(segment
		(start 53.164994 -289.110674)
		(end 53.401976 -289.110674)
		(width 0.14478)
		(layer "In13.Cu")
		(net "M_B_CPU1_SB_DQ<5>")
	)
	(segment
		(start 83.694016 -278.45893)
		(end 83.702398 -278.463756)
		(width 0.0889)
		(layer "In13.Cu")
		(net "M_B_CPU1_SB_DQ<5>")
	)
	(segment
		(start 76.034392 -277.833074)
		(end 76.529438 -277.833074)
		(width 0.0889)
		(layer "In13.Cu")
		(net "M_B_CPU1_SB_DQ<5>")
	)
	(segment
		(start 77.00772 -278.264366)
		(end 79.21244 -278.264366)
		(width 0.0889)
		(layer "In13.Cu")
		(net "M_B_CPU1_SB_DQ<5>")
	)
	(segment
		(start 56.79059 -289.415728)
		(end 56.93537 -289.560508)
		(width 0.14478)
		(layer "In13.Cu")
		(net "M_B_CPU1_SB_DQ<5>")
	)
	(segment
		(start 52.469034 -288.965894)
		(end 52.469034 -288.46526)
		(width 0.14478)
		(layer "In13.Cu")
		(net "M_B_CPU1_SB_DQ<5>")
	)
	(segment
		(start 57.282842 -289.560508)
		(end 58.221372 -288.621978)
		(width 0.14478)
		(layer "In13.Cu")
		(net "M_B_CPU1_SB_DQ<5>")
	)
	(segment
		(start 56.64581 -289.184334)
		(end 56.79059 -289.329114)
		(width 0.14478)
		(layer "In13.Cu")
		(net "M_B_CPU1_SB_DQ<5>")
	)
	(segment
		(start 54.8513 -289.415728)
		(end 54.99608 -289.560508)
		(width 0.14478)
		(layer "In13.Cu")
		(net "M_B_CPU1_SB_DQ<5>")
	)
	(segment
		(start 85.93963 -278.463756)
		(end 85.948012 -278.45893)
		(width 0.0889)
		(layer "In13.Cu")
		(net "M_B_CPU1_SB_DQ<5>")
	)
	(segment
		(start 56.79059 -289.329114)
		(end 56.79059 -289.415728)
		(width 0.14478)
		(layer "In13.Cu")
		(net "M_B_CPU1_SB_DQ<5>")
	)
	(segment
		(start 52.469034 -288.46526)
		(end 52.613814 -288.32048)
		(width 0.14478)
		(layer "In13.Cu")
		(net "M_B_CPU1_SB_DQ<5>")
	)
	(segment
		(start 59.322462 -288.994596)
		(end 59.322462 -288.85515)
		(width 0.14478)
		(layer "In13.Cu")
		(net "M_B_CPU1_SB_DQ<5>")
	)
	(segment
		(start 51.90871 -289.110674)
		(end 52.324254 -289.110674)
		(width 0.14478)
		(layer "In13.Cu")
		(net "M_B_CPU1_SB_DQ<5>")
	)
	(segment
		(start 56.38419 -289.184334)
		(end 56.64581 -289.184334)
		(width 0.14478)
		(layer "In13.Cu")
		(net "M_B_CPU1_SB_DQ<5>")
	)
	(segment
		(start 53.020214 -288.965894)
		(end 53.164994 -289.110674)
		(width 0.14478)
		(layer "In13.Cu")
		(net "M_B_CPU1_SB_DQ<5>")
	)
	(segment
		(start 85.948012 -278.45893)
		(end 85.948266 -278.45893)
		(width 0.0889)
		(layer "In13.Cu")
		(net "M_B_CPU1_SB_DQ<5>")
	)
	(segment
		(start 52.875434 -288.32048)
		(end 53.020214 -288.46526)
		(width 0.14478)
		(layer "In13.Cu")
		(net "M_B_CPU1_SB_DQ<5>")
	)
	(segment
		(start 58.626502 -288.621978)
		(end 58.771282 -288.766758)
		(width 0.14478)
		(layer "In13.Cu")
		(net "M_B_CPU1_SB_DQ<5>")
	)
	(segment
		(start 82.179668 -278.463756)
		(end 82.18805 -278.45893)
		(width 0.0889)
		(layer "In13.Cu")
		(net "M_B_CPU1_SB_DQ<5>")
	)
	(segment
		(start 87.453978 -278.45893)
		(end 87.46236 -278.463756)
		(width 0.0889)
		(layer "In13.Cu")
		(net "M_B_CPU1_SB_DQ<5>")
	)
	(segment
		(start 56.93537 -289.560508)
		(end 57.282842 -289.560508)
		(width 0.14478)
		(layer "In13.Cu")
		(net "M_B_CPU1_SB_DQ<5>")
	)
	(segment
		(start 89.367106 -278.40178)
		(end 89.52103 -278.13635)
		(width 0.0889)
		(layer "In13.Cu")
		(net "M_B_CPU1_SB_DQ<5>")
	)
	(segment
		(start 59.322462 -288.85515)
		(end 59.467242 -288.71037)
		(width 0.14478)
		(layer "In13.Cu")
		(net "M_B_CPU1_SB_DQ<5>")
	)
	(segment
		(start 53.401976 -289.110674)
		(end 53.85181 -289.560508)
		(width 0.14478)
		(layer "In13.Cu")
		(net "M_B_CPU1_SB_DQ<5>")
	)
	(segment
		(start 89.271094 -278.42718)
		(end 89.367106 -278.40178)
		(width 0.0889)
		(layer "In13.Cu")
		(net "M_B_CPU1_SB_DQ<5>")
	)
	(segment
		(start 54.4449 -289.167824)
		(end 54.70652 -289.167824)
		(width 0.14478)
		(layer "In13.Cu")
		(net "M_B_CPU1_SB_DQ<5>")
	)
	(segment
		(start 54.30012 -289.415728)
		(end 54.30012 -289.312604)
		(width 0.14478)
		(layer "In13.Cu")
		(net "M_B_CPU1_SB_DQ<5>")
	)
	(segment
		(start 58.771282 -288.766758)
		(end 58.771282 -288.994596)
		(width 0.14478)
		(layer "In13.Cu")
		(net "M_B_CPU1_SB_DQ<5>")
	)
	(segment
		(start 60.251086 -288.71037)
		(end 71.128382 -277.833074)
		(width 0.14478)
		(layer "In13.Cu")
		(net "M_B_CPU1_SB_DQ<5>")
	)
	(segment
		(start 56.09463 -289.560508)
		(end 56.23941 -289.415728)
		(width 0.14478)
		(layer "In13.Cu")
		(net "M_B_CPU1_SB_DQ<5>")
	)
	(segment
		(start 51.884072 -289.135312)
		(end 51.90871 -289.110674)
		(width 0.14478)
		(layer "In13.Cu")
		(net "M_B_CPU1_SB_DQ<5>")
	)
	(segment
		(start 54.30012 -289.312604)
		(end 54.4449 -289.167824)
		(width 0.14478)
		(layer "In13.Cu")
		(net "M_B_CPU1_SB_DQ<5>")
	)
	(segment
		(start 52.613814 -288.32048)
		(end 52.875434 -288.32048)
		(width 0.14478)
		(layer "In13.Cu")
		(net "M_B_CPU1_SB_DQ<5>")
	)
	(segment
		(start 54.15534 -289.560508)
		(end 54.30012 -289.415728)
		(width 0.14478)
		(layer "In13.Cu")
		(net "M_B_CPU1_SB_DQ<5>")
	)
	(segment
		(start 53.85181 -289.560508)
		(end 54.15534 -289.560508)
		(width 0.14478)
		(layer "In13.Cu")
		(net "M_B_CPU1_SB_DQ<5>")
	)
	(segment
		(start 56.23941 -289.329114)
		(end 56.38419 -289.184334)
		(width 0.14478)
		(layer "In13.Cu")
		(net "M_B_CPU1_SB_DQ<5>")
	)
	(segment
		(start 58.771282 -288.994596)
		(end 58.916062 -289.139376)
		(width 0.14478)
		(layer "In13.Cu")
		(net "M_B_CPU1_SB_DQ<5>")
	)
	(segment
		(start 56.23941 -289.415728)
		(end 56.23941 -289.329114)
		(width 0.14478)
		(layer "In13.Cu")
		(net "M_B_CPU1_SB_DQ<5>")
	)
	(segment
		(start 54.8513 -289.312604)
		(end 54.8513 -289.415728)
		(width 0.14478)
		(layer "In13.Cu")
		(net "M_B_CPU1_SB_DQ<5>")
	)
	(segment
		(start 58.916062 -289.139376)
		(end 59.177682 -289.139376)
		(width 0.14478)
		(layer "In13.Cu")
		(net "M_B_CPU1_SB_DQ<5>")
	)
	(arc
		(start 88.402414 -278.463756)
		(mid 88.585922 -278.50925)
		(end 88.768174 -278.45893)
		(width 0.0889)
		(layer "In13.Cu")
		(net "M_B_CPU1_SB_DQ<5>")
	)
	(arc
		(start 79.9338 -278.45893)
		(mid 80.120998 -278.509312)
		(end 80.308196 -278.45893)
		(width 0.0889)
		(layer "In13.Cu")
		(net "M_B_CPU1_SB_DQ<5>")
	)
	(arc
		(start 82.18805 -278.45893)
		(mid 82.471006 -278.382753)
		(end 82.753962 -278.45893)
		(width 0.0889)
		(layer "In13.Cu")
		(net "M_B_CPU1_SB_DQ<5>")
	)
	(arc
		(start 80.308196 -278.45893)
		(mid 80.591152 -278.382753)
		(end 80.874108 -278.45893)
		(width 0.0889)
		(layer "In13.Cu")
		(net "M_B_CPU1_SB_DQ<5>")
	)
	(arc
		(start 85.007958 -278.45893)
		(mid 85.290914 -278.382753)
		(end 85.57387 -278.45893)
		(width 0.0889)
		(layer "In13.Cu")
		(net "M_B_CPU1_SB_DQ<5>")
	)
	(arc
		(start 76.927456 -278.231092)
		(mid 76.964267 -278.255752)
		(end 77.00772 -278.264366)
		(width 0.0889)
		(layer "In13.Cu")
		(net "M_B_CPU1_SB_DQ<5>")
	)
	(arc
		(start 81.813908 -278.45893)
		(mid 81.996159 -278.50928)
		(end 82.179668 -278.463756)
		(width 0.0889)
		(layer "In13.Cu")
		(net "M_B_CPU1_SB_DQ<5>")
	)
	(arc
		(start 83.128104 -278.45893)
		(mid 83.41106 -278.382753)
		(end 83.694016 -278.45893)
		(width 0.0889)
		(layer "In13.Cu")
		(net "M_B_CPU1_SB_DQ<5>")
	)
	(arc
		(start 88.768174 -278.45893)
		(mid 89.015887 -278.38371)
		(end 89.271094 -278.42718)
		(width 0.0889)
		(layer "In13.Cu")
		(net "M_B_CPU1_SB_DQ<5>")
	)
	(arc
		(start 87.46236 -278.463756)
		(mid 87.645868 -278.50925)
		(end 87.82812 -278.45893)
		(width 0.0889)
		(layer "In13.Cu")
		(net "M_B_CPU1_SB_DQ<5>")
	)
	(arc
		(start 83.702398 -278.463756)
		(mid 83.885906 -278.50925)
		(end 84.068158 -278.45893)
		(width 0.0889)
		(layer "In13.Cu")
		(net "M_B_CPU1_SB_DQ<5>")
	)
	(arc
		(start 84.63407 -278.45893)
		(mid 84.821014 -278.509185)
		(end 85.007958 -278.45893)
		(width 0.0889)
		(layer "In13.Cu")
		(net "M_B_CPU1_SB_DQ<5>")
	)
	(arc
		(start 80.874108 -278.45893)
		(mid 81.061052 -278.509185)
		(end 81.247996 -278.45893)
		(width 0.0889)
		(layer "In13.Cu")
		(net "M_B_CPU1_SB_DQ<5>")
	)
	(arc
		(start 85.948266 -278.45893)
		(mid 86.231112 -278.382753)
		(end 86.513924 -278.45893)
		(width 0.0889)
		(layer "In13.Cu")
		(net "M_B_CPU1_SB_DQ<5>")
	)
	(arc
		(start 86.888066 -278.45893)
		(mid 87.171022 -278.382753)
		(end 87.453978 -278.45893)
		(width 0.0889)
		(layer "In13.Cu")
		(net "M_B_CPU1_SB_DQ<5>")
	)
	(arc
		(start 86.513924 -278.45893)
		(mid 86.696175 -278.50928)
		(end 86.879684 -278.463756)
		(width 0.0889)
		(layer "In13.Cu")
		(net "M_B_CPU1_SB_DQ<5>")
	)
	(arc
		(start 85.57387 -278.45893)
		(mid 85.756121 -278.50928)
		(end 85.93963 -278.463756)
		(width 0.0889)
		(layer "In13.Cu")
		(net "M_B_CPU1_SB_DQ<5>")
	)
	(arc
		(start 82.762344 -278.463756)
		(mid 82.945852 -278.50925)
		(end 83.128104 -278.45893)
		(width 0.0889)
		(layer "In13.Cu")
		(net "M_B_CPU1_SB_DQ<5>")
	)
	(arc
		(start 81.247996 -278.45893)
		(mid 81.530952 -278.382753)
		(end 81.813908 -278.45893)
		(width 0.0889)
		(layer "In13.Cu")
		(net "M_B_CPU1_SB_DQ<5>")
	)
	(arc
		(start 87.82812 -278.45893)
		(mid 88.111076 -278.382753)
		(end 88.394032 -278.45893)
		(width 0.0889)
		(layer "In13.Cu")
		(net "M_B_CPU1_SB_DQ<5>")
	)
	(arc
		(start 79.21244 -278.264366)
		(mid 79.586015 -278.313851)
		(end 79.9338 -278.45893)
		(width 0.0889)
		(layer "In13.Cu")
		(net "M_B_CPU1_SB_DQ<5>")
	)
	(arc
		(start 84.068158 -278.45893)
		(mid 84.351114 -278.382753)
		(end 84.63407 -278.45893)
		(width 0.0889)
		(layer "In13.Cu")
		(net "M_B_CPU1_SB_DQ<5>")
	)
	(segment
		(start 88.577928 -277.060406)
		(end 88.111076 -277.326344)
		(width 0.10668)
		(layer "F.Cu")
		(net "M_B_CPU1_SB_DQ<4>")
	)
	(segment
		(start 66.612008 -280.629868)
		(end 67.059048 -280.629868)
		(width 0.14478)
		(layer "In13.Cu")
		(net "M_B_CPU1_SB_DQ<4>")
	)
	(segment
		(start 58.860182 -286.707326)
		(end 59.088528 -286.707326)
		(width 0.14478)
		(layer "In13.Cu")
		(net "M_B_CPU1_SB_DQ<4>")
	)
	(segment
		(start 80.39354 -277.642828)
		(end 80.403954 -277.648924)
		(width 0.0889)
		(layer "In13.Cu")
		(net "M_B_CPU1_SB_DQ<4>")
	)
	(segment
		(start 81.344008 -277.648924)
		(end 81.35239 -277.65375)
		(width 0.0889)
		(layer "In13.Cu")
		(net "M_B_CPU1_SB_DQ<4>")
	)
	(segment
		(start 63.937896 -283.75102)
		(end 64.10452 -283.584396)
		(width 0.14478)
		(layer "In13.Cu")
		(net "M_B_CPU1_SB_DQ<4>")
	)
	(segment
		(start 70.318122 -276.923754)
		(end 75.957176 -276.923754)
		(width 0.14478)
		(layer "In13.Cu")
		(net "M_B_CPU1_SB_DQ<4>")
	)
	(segment
		(start 66.445384 -280.796492)
		(end 66.612008 -280.629868)
		(width 0.14478)
		(layer "In13.Cu")
		(net "M_B_CPU1_SB_DQ<4>")
	)
	(segment
		(start 62.37732 -285.311596)
		(end 62.543944 -285.144972)
		(width 0.14478)
		(layer "In13.Cu")
		(net "M_B_CPU1_SB_DQ<4>")
	)
	(segment
		(start 59.849512 -287.392364)
		(end 60.369704 -286.872172)
		(width 0.14478)
		(layer "In13.Cu")
		(net "M_B_CPU1_SB_DQ<4>")
	)
	(segment
		(start 79.463138 -277.648924)
		(end 79.47152 -277.65375)
		(width 0.0889)
		(layer "In13.Cu")
		(net "M_B_CPU1_SB_DQ<4>")
	)
	(segment
		(start 59.088528 -286.707326)
		(end 59.250072 -286.86887)
		(width 0.14478)
		(layer "In13.Cu")
		(net "M_B_CPU1_SB_DQ<4>")
	)
	(segment
		(start 67.839336 -279.84958)
		(end 68.00596 -279.682956)
		(width 0.14478)
		(layer "In13.Cu")
		(net "M_B_CPU1_SB_DQ<4>")
	)
	(segment
		(start 87.956898 -277.591774)
		(end 88.111076 -277.326344)
		(width 0.0889)
		(layer "In13.Cu")
		(net "M_B_CPU1_SB_DQ<4>")
	)
	(segment
		(start 64.271144 -282.970732)
		(end 64.718184 -282.970732)
		(width 0.14478)
		(layer "In13.Cu")
		(net "M_B_CPU1_SB_DQ<4>")
	)
	(segment
		(start 54.094126 -287.860486)
		(end 57.63641 -287.860486)
		(width 0.14478)
		(layer "In13.Cu")
		(net "M_B_CPU1_SB_DQ<4>")
	)
	(segment
		(start 86.044024 -277.648924)
		(end 86.052406 -277.65375)
		(width 0.0889)
		(layer "In13.Cu")
		(net "M_B_CPU1_SB_DQ<4>")
	)
	(segment
		(start 53.25364 -287.02)
		(end 54.094126 -287.860486)
		(width 0.14478)
		(layer "In13.Cu")
		(net "M_B_CPU1_SB_DQ<4>")
	)
	(segment
		(start 83.589622 -277.65375)
		(end 83.598004 -277.648924)
		(width 0.0889)
		(layer "In13.Cu")
		(net "M_B_CPU1_SB_DQ<4>")
	)
	(segment
		(start 68.952872 -278.289004)
		(end 69.399912 -278.289004)
		(width 0.14478)
		(layer "In13.Cu")
		(net "M_B_CPU1_SB_DQ<4>")
	)
	(segment
		(start 51.884072 -287.43529)
		(end 51.884072 -287.165034)
		(width 0.14478)
		(layer "In13.Cu")
		(net "M_B_CPU1_SB_DQ<4>")
	)
	(segment
		(start 58.104532 -287.392364)
		(end 58.537094 -287.392364)
		(width 0.14478)
		(layer "In13.Cu")
		(net "M_B_CPU1_SB_DQ<4>")
	)
	(segment
		(start 68.00596 -279.682956)
		(end 68.00596 -279.235916)
		(width 0.14478)
		(layer "In13.Cu")
		(net "M_B_CPU1_SB_DQ<4>")
	)
	(segment
		(start 76.374498 -276.923754)
		(end 76.56957 -277.118826)
		(width 0.0889)
		(layer "In13.Cu")
		(net "M_B_CPU1_SB_DQ<4>")
	)
	(segment
		(start 66.445384 -281.243532)
		(end 66.445384 -280.796492)
		(width 0.14478)
		(layer "In13.Cu")
		(net "M_B_CPU1_SB_DQ<4>")
	)
	(segment
		(start 63.490856 -283.75102)
		(end 63.937896 -283.75102)
		(width 0.14478)
		(layer "In13.Cu")
		(net "M_B_CPU1_SB_DQ<4>")
	)
	(segment
		(start 67.225672 -280.463244)
		(end 67.225672 -280.016204)
		(width 0.14478)
		(layer "In13.Cu")
		(net "M_B_CPU1_SB_DQ<4>")
	)
	(segment
		(start 68.786248 -278.902668)
		(end 68.786248 -278.455628)
		(width 0.14478)
		(layer "In13.Cu")
		(net "M_B_CPU1_SB_DQ<4>")
	)
	(segment
		(start 65.051432 -282.190444)
		(end 65.498472 -282.190444)
		(width 0.14478)
		(layer "In13.Cu")
		(net "M_B_CPU1_SB_DQ<4>")
	)
	(segment
		(start 58.698638 -286.86887)
		(end 58.860182 -286.707326)
		(width 0.14478)
		(layer "In13.Cu")
		(net "M_B_CPU1_SB_DQ<4>")
	)
	(segment
		(start 61.597032 -286.091884)
		(end 61.763656 -285.92526)
		(width 0.14478)
		(layer "In13.Cu")
		(net "M_B_CPU1_SB_DQ<4>")
	)
	(segment
		(start 59.250072 -286.86887)
		(end 59.250072 -287.23082)
		(width 0.14478)
		(layer "In13.Cu")
		(net "M_B_CPU1_SB_DQ<4>")
	)
	(segment
		(start 67.225672 -280.016204)
		(end 67.392296 -279.84958)
		(width 0.14478)
		(layer "In13.Cu")
		(net "M_B_CPU1_SB_DQ<4>")
	)
	(segment
		(start 64.884808 -282.357068)
		(end 65.051432 -282.190444)
		(width 0.14478)
		(layer "In13.Cu")
		(net "M_B_CPU1_SB_DQ<4>")
	)
	(segment
		(start 51.884072 -287.165034)
		(end 52.029106 -287.02)
		(width 0.14478)
		(layer "In13.Cu")
		(net "M_B_CPU1_SB_DQ<4>")
	)
	(segment
		(start 80.769714 -277.65375)
		(end 80.778096 -277.648924)
		(width 0.0889)
		(layer "In13.Cu")
		(net "M_B_CPU1_SB_DQ<4>")
	)
	(segment
		(start 87.860632 -277.617174)
		(end 87.956898 -277.591774)
		(width 0.0889)
		(layer "In13.Cu")
		(net "M_B_CPU1_SB_DQ<4>")
	)
	(segment
		(start 65.665096 -282.02382)
		(end 65.665096 -281.57678)
		(width 0.14478)
		(layer "In13.Cu")
		(net "M_B_CPU1_SB_DQ<4>")
	)
	(segment
		(start 64.884808 -282.804108)
		(end 64.884808 -282.357068)
		(width 0.14478)
		(layer "In13.Cu")
		(net "M_B_CPU1_SB_DQ<4>")
	)
	(segment
		(start 68.786248 -278.455628)
		(end 68.952872 -278.289004)
		(width 0.14478)
		(layer "In13.Cu")
		(net "M_B_CPU1_SB_DQ<4>")
	)
	(segment
		(start 68.172584 -279.069292)
		(end 68.619624 -279.069292)
		(width 0.14478)
		(layer "In13.Cu")
		(net "M_B_CPU1_SB_DQ<4>")
	)
	(segment
		(start 78.560168 -277.69947)
		(end 78.71079 -277.69947)
		(width 0.0889)
		(layer "In13.Cu")
		(net "M_B_CPU1_SB_DQ<4>")
	)
	(segment
		(start 60.983368 -286.68726)
		(end 60.983368 -286.258508)
		(width 0.14478)
		(layer "In13.Cu")
		(net "M_B_CPU1_SB_DQ<4>")
	)
	(segment
		(start 64.718184 -282.970732)
		(end 64.884808 -282.804108)
		(width 0.14478)
		(layer "In13.Cu")
		(net "M_B_CPU1_SB_DQ<4>")
	)
	(segment
		(start 63.157608 -284.531308)
		(end 63.324232 -284.364684)
		(width 0.14478)
		(layer "In13.Cu")
		(net "M_B_CPU1_SB_DQ<4>")
	)
	(segment
		(start 60.369704 -286.872172)
		(end 60.798456 -286.872172)
		(width 0.14478)
		(layer "In13.Cu")
		(net "M_B_CPU1_SB_DQ<4>")
	)
	(segment
		(start 60.983368 -286.258508)
		(end 61.149992 -286.091884)
		(width 0.14478)
		(layer "In13.Cu")
		(net "M_B_CPU1_SB_DQ<4>")
	)
	(segment
		(start 61.93028 -285.311596)
		(end 62.37732 -285.311596)
		(width 0.14478)
		(layer "In13.Cu")
		(net "M_B_CPU1_SB_DQ<4>")
	)
	(segment
		(start 60.798456 -286.872172)
		(end 60.983368 -286.68726)
		(width 0.14478)
		(layer "In13.Cu")
		(net "M_B_CPU1_SB_DQ<4>")
	)
	(segment
		(start 61.763656 -285.92526)
		(end 61.763656 -285.47822)
		(width 0.14478)
		(layer "In13.Cu")
		(net "M_B_CPU1_SB_DQ<4>")
	)
	(segment
		(start 62.543944 -285.144972)
		(end 62.543944 -284.697932)
		(width 0.14478)
		(layer "In13.Cu")
		(net "M_B_CPU1_SB_DQ<4>")
	)
	(segment
		(start 78.897734 -277.64867)
		(end 78.903322 -277.645368)
		(width 0.0889)
		(layer "In13.Cu")
		(net "M_B_CPU1_SB_DQ<4>")
	)
	(segment
		(start 64.10452 -283.137356)
		(end 64.271144 -282.970732)
		(width 0.14478)
		(layer "In13.Cu")
		(net "M_B_CPU1_SB_DQ<4>")
	)
	(segment
		(start 84.529676 -277.65375)
		(end 84.538058 -277.648924)
		(width 0.0889)
		(layer "In13.Cu")
		(net "M_B_CPU1_SB_DQ<4>")
	)
	(segment
		(start 63.324232 -284.364684)
		(end 63.324232 -283.917644)
		(width 0.14478)
		(layer "In13.Cu")
		(net "M_B_CPU1_SB_DQ<4>")
	)
	(segment
		(start 65.665096 -281.57678)
		(end 65.83172 -281.410156)
		(width 0.14478)
		(layer "In13.Cu")
		(net "M_B_CPU1_SB_DQ<4>")
	)
	(segment
		(start 57.63641 -287.860486)
		(end 58.104532 -287.392364)
		(width 0.14478)
		(layer "In13.Cu")
		(net "M_B_CPU1_SB_DQ<4>")
	)
	(segment
		(start 63.324232 -283.917644)
		(end 63.490856 -283.75102)
		(width 0.14478)
		(layer "In13.Cu")
		(net "M_B_CPU1_SB_DQ<4>")
	)
	(segment
		(start 68.619624 -279.069292)
		(end 68.786248 -278.902668)
		(width 0.14478)
		(layer "In13.Cu")
		(net "M_B_CPU1_SB_DQ<4>")
	)
	(segment
		(start 52.029106 -287.02)
		(end 53.25364 -287.02)
		(width 0.14478)
		(layer "In13.Cu")
		(net "M_B_CPU1_SB_DQ<4>")
	)
	(segment
		(start 66.27876 -281.410156)
		(end 66.445384 -281.243532)
		(width 0.14478)
		(layer "In13.Cu")
		(net "M_B_CPU1_SB_DQ<4>")
	)
	(segment
		(start 59.411616 -287.392364)
		(end 59.849512 -287.392364)
		(width 0.14478)
		(layer "In13.Cu")
		(net "M_B_CPU1_SB_DQ<4>")
	)
	(segment
		(start 76.56957 -277.118826)
		(end 77.979524 -277.118826)
		(width 0.0889)
		(layer "In13.Cu")
		(net "M_B_CPU1_SB_DQ<4>")
	)
	(segment
		(start 69.566536 -278.12238)
		(end 69.566536 -277.67534)
		(width 0.14478)
		(layer "In13.Cu")
		(net "M_B_CPU1_SB_DQ<4>")
	)
	(segment
		(start 69.399912 -278.289004)
		(end 69.566536 -278.12238)
		(width 0.14478)
		(layer "In13.Cu")
		(net "M_B_CPU1_SB_DQ<4>")
	)
	(segment
		(start 67.059048 -280.629868)
		(end 67.225672 -280.463244)
		(width 0.14478)
		(layer "In13.Cu")
		(net "M_B_CPU1_SB_DQ<4>")
	)
	(segment
		(start 69.566536 -277.67534)
		(end 70.318122 -276.923754)
		(width 0.14478)
		(layer "In13.Cu")
		(net "M_B_CPU1_SB_DQ<4>")
	)
	(segment
		(start 61.763656 -285.47822)
		(end 61.93028 -285.311596)
		(width 0.14478)
		(layer "In13.Cu")
		(net "M_B_CPU1_SB_DQ<4>")
	)
	(segment
		(start 68.00596 -279.235916)
		(end 68.172584 -279.069292)
		(width 0.14478)
		(layer "In13.Cu")
		(net "M_B_CPU1_SB_DQ<4>")
	)
	(segment
		(start 61.149992 -286.091884)
		(end 61.597032 -286.091884)
		(width 0.14478)
		(layer "In13.Cu")
		(net "M_B_CPU1_SB_DQ<4>")
	)
	(segment
		(start 65.498472 -282.190444)
		(end 65.665096 -282.02382)
		(width 0.14478)
		(layer "In13.Cu")
		(net "M_B_CPU1_SB_DQ<4>")
	)
	(segment
		(start 58.698638 -287.23082)
		(end 58.698638 -286.86887)
		(width 0.14478)
		(layer "In13.Cu")
		(net "M_B_CPU1_SB_DQ<4>")
	)
	(segment
		(start 59.250072 -287.23082)
		(end 59.411616 -287.392364)
		(width 0.14478)
		(layer "In13.Cu")
		(net "M_B_CPU1_SB_DQ<4>")
	)
	(segment
		(start 77.979524 -277.118826)
		(end 78.560168 -277.69947)
		(width 0.0889)
		(layer "In13.Cu")
		(net "M_B_CPU1_SB_DQ<4>")
	)
	(segment
		(start 75.957176 -276.923754)
		(end 76.374498 -276.923754)
		(width 0.0889)
		(layer "In13.Cu")
		(net "M_B_CPU1_SB_DQ<4>")
	)
	(segment
		(start 62.710568 -284.531308)
		(end 63.157608 -284.531308)
		(width 0.14478)
		(layer "In13.Cu")
		(net "M_B_CPU1_SB_DQ<4>")
	)
	(segment
		(start 64.10452 -283.584396)
		(end 64.10452 -283.137356)
		(width 0.14478)
		(layer "In13.Cu")
		(net "M_B_CPU1_SB_DQ<4>")
	)
	(segment
		(start 62.543944 -284.697932)
		(end 62.710568 -284.531308)
		(width 0.14478)
		(layer "In13.Cu")
		(net "M_B_CPU1_SB_DQ<4>")
	)
	(segment
		(start 58.537094 -287.392364)
		(end 58.698638 -287.23082)
		(width 0.14478)
		(layer "In13.Cu")
		(net "M_B_CPU1_SB_DQ<4>")
	)
	(segment
		(start 67.392296 -279.84958)
		(end 67.839336 -279.84958)
		(width 0.14478)
		(layer "In13.Cu")
		(net "M_B_CPU1_SB_DQ<4>")
	)
	(segment
		(start 85.10397 -277.648924)
		(end 85.112352 -277.65375)
		(width 0.0889)
		(layer "In13.Cu")
		(net "M_B_CPU1_SB_DQ<4>")
	)
	(segment
		(start 65.83172 -281.410156)
		(end 66.27876 -281.410156)
		(width 0.14478)
		(layer "In13.Cu")
		(net "M_B_CPU1_SB_DQ<4>")
	)
	(arc
		(start 80.403954 -277.648924)
		(mid 80.586205 -277.699274)
		(end 80.769714 -277.65375)
		(width 0.0889)
		(layer "In13.Cu")
		(net "M_B_CPU1_SB_DQ<4>")
	)
	(arc
		(start 81.71815 -277.648924)
		(mid 82.001106 -277.572747)
		(end 82.284062 -277.648924)
		(width 0.0889)
		(layer "In13.Cu")
		(net "M_B_CPU1_SB_DQ<4>")
	)
	(arc
		(start 82.284062 -277.648924)
		(mid 82.471006 -277.699179)
		(end 82.65795 -277.648924)
		(width 0.0889)
		(layer "In13.Cu")
		(net "M_B_CPU1_SB_DQ<4>")
	)
	(arc
		(start 84.163916 -277.648924)
		(mid 84.346167 -277.699274)
		(end 84.529676 -277.65375)
		(width 0.0889)
		(layer "In13.Cu")
		(net "M_B_CPU1_SB_DQ<4>")
	)
	(arc
		(start 85.478112 -277.648924)
		(mid 85.761068 -277.572747)
		(end 86.044024 -277.648924)
		(width 0.0889)
		(layer "In13.Cu")
		(net "M_B_CPU1_SB_DQ<4>")
	)
	(arc
		(start 83.223862 -277.648924)
		(mid 83.406113 -277.699274)
		(end 83.589622 -277.65375)
		(width 0.0889)
		(layer "In13.Cu")
		(net "M_B_CPU1_SB_DQ<4>")
	)
	(arc
		(start 84.538058 -277.648924)
		(mid 84.821014 -277.572747)
		(end 85.10397 -277.648924)
		(width 0.0889)
		(layer "In13.Cu")
		(net "M_B_CPU1_SB_DQ<4>")
	)
	(arc
		(start 86.052406 -277.65375)
		(mid 86.235914 -277.699244)
		(end 86.418166 -277.648924)
		(width 0.0889)
		(layer "In13.Cu")
		(net "M_B_CPU1_SB_DQ<4>")
	)
	(arc
		(start 86.418166 -277.648924)
		(mid 86.701122 -277.572747)
		(end 86.984078 -277.648924)
		(width 0.0889)
		(layer "In13.Cu")
		(net "M_B_CPU1_SB_DQ<4>")
	)
	(arc
		(start 82.65795 -277.648924)
		(mid 82.940906 -277.572747)
		(end 83.223862 -277.648924)
		(width 0.0889)
		(layer "In13.Cu")
		(net "M_B_CPU1_SB_DQ<4>")
	)
	(arc
		(start 86.984078 -277.648924)
		(mid 87.171022 -277.699179)
		(end 87.357966 -277.648924)
		(width 0.0889)
		(layer "In13.Cu")
		(net "M_B_CPU1_SB_DQ<4>")
	)
	(arc
		(start 79.837788 -277.648924)
		(mid 80.114855 -277.572653)
		(end 80.39354 -277.642828)
		(width 0.0889)
		(layer "In13.Cu")
		(net "M_B_CPU1_SB_DQ<4>")
	)
	(arc
		(start 78.71079 -277.69947)
		(mid 78.807608 -277.686399)
		(end 78.897734 -277.64867)
		(width 0.0889)
		(layer "In13.Cu")
		(net "M_B_CPU1_SB_DQ<4>")
	)
	(arc
		(start 78.903322 -277.645368)
		(mid 79.183711 -277.572699)
		(end 79.463138 -277.648924)
		(width 0.0889)
		(layer "In13.Cu")
		(net "M_B_CPU1_SB_DQ<4>")
	)
	(arc
		(start 79.47152 -277.65375)
		(mid 79.655282 -277.699366)
		(end 79.837788 -277.648924)
		(width 0.0889)
		(layer "In13.Cu")
		(net "M_B_CPU1_SB_DQ<4>")
	)
	(arc
		(start 83.598004 -277.648924)
		(mid 83.88096 -277.572747)
		(end 84.163916 -277.648924)
		(width 0.0889)
		(layer "In13.Cu")
		(net "M_B_CPU1_SB_DQ<4>")
	)
	(arc
		(start 85.112352 -277.65375)
		(mid 85.29586 -277.699244)
		(end 85.478112 -277.648924)
		(width 0.0889)
		(layer "In13.Cu")
		(net "M_B_CPU1_SB_DQ<4>")
	)
	(arc
		(start 81.35239 -277.65375)
		(mid 81.535898 -277.699244)
		(end 81.71815 -277.648924)
		(width 0.0889)
		(layer "In13.Cu")
		(net "M_B_CPU1_SB_DQ<4>")
	)
	(arc
		(start 87.357966 -277.648924)
		(mid 87.605562 -277.573746)
		(end 87.860632 -277.617174)
		(width 0.0889)
		(layer "In13.Cu")
		(net "M_B_CPU1_SB_DQ<4>")
	)
	(arc
		(start 80.778096 -277.648924)
		(mid 81.061052 -277.572747)
		(end 81.344008 -277.648924)
		(width 0.0889)
		(layer "In13.Cu")
		(net "M_B_CPU1_SB_DQ<4>")
	)
	(segment
		(start 89.517982 -275.440394)
		(end 89.05113 -275.706332)
		(width 0.10668)
		(layer "F.Cu")
		(net "M_B_CPU1_SB_DQ<3>")
	)
	(segment
		(start 78.400656 -275.332952)
		(end 77.30871 -274.241006)
		(width 0.0889)
		(layer "In13.Cu")
		(net "M_B_CPU1_SB_DQ<3>")
	)
	(segment
		(start 49.828958 -284.035246)
		(end 47.784004 -284.035246)
		(width 0.14478)
		(layer "In13.Cu")
		(net "M_B_CPU1_SB_DQ<3>")
	)
	(segment
		(start 50.263552 -283.600652)
		(end 49.828958 -284.035246)
		(width 0.14478)
		(layer "In13.Cu")
		(net "M_B_CPU1_SB_DQ<3>")
	)
	(segment
		(start 57.34304 -284.064964)
		(end 53.520848 -284.064964)
		(width 0.14478)
		(layer "In13.Cu")
		(net "M_B_CPU1_SB_DQ<3>")
	)
	(segment
		(start 81.35239 -275.378926)
		(end 81.344008 -275.383752)
		(width 0.0889)
		(layer "In13.Cu")
		(net "M_B_CPU1_SB_DQ<3>")
	)
	(segment
		(start 76.37145 -274.584414)
		(end 68.402708 -274.584414)
		(width 0.14478)
		(layer "In13.Cu")
		(net "M_B_CPU1_SB_DQ<3>")
	)
	(segment
		(start 86.052406 -275.378926)
		(end 86.044024 -275.383752)
		(width 0.0889)
		(layer "In13.Cu")
		(net "M_B_CPU1_SB_DQ<3>")
	)
	(segment
		(start 53.056536 -283.600652)
		(end 50.263552 -283.600652)
		(width 0.14478)
		(layer "In13.Cu")
		(net "M_B_CPU1_SB_DQ<3>")
	)
	(segment
		(start 84.538058 -275.383752)
		(end 84.529676 -275.378926)
		(width 0.0889)
		(layer "In13.Cu")
		(net "M_B_CPU1_SB_DQ<3>")
	)
	(segment
		(start 76.485242 -274.584414)
		(end 76.37145 -274.584414)
		(width 0.0889)
		(layer "In13.Cu")
		(net "M_B_CPU1_SB_DQ<3>")
	)
	(segment
		(start 89.205054 -275.440902)
		(end 89.182702 -275.35759)
		(width 0.0889)
		(layer "In13.Cu")
		(net "M_B_CPU1_SB_DQ<3>")
	)
	(segment
		(start 76.82865 -274.241006)
		(end 76.485242 -274.584414)
		(width 0.0889)
		(layer "In13.Cu")
		(net "M_B_CPU1_SB_DQ<3>")
	)
	(segment
		(start 83.598004 -275.383752)
		(end 83.589622 -275.378926)
		(width 0.0889)
		(layer "In13.Cu")
		(net "M_B_CPU1_SB_DQ<3>")
	)
	(segment
		(start 88.29802 -275.383752)
		(end 88.289638 -275.378926)
		(width 0.0889)
		(layer "In13.Cu")
		(net "M_B_CPU1_SB_DQ<3>")
	)
	(segment
		(start 59.376818 -283.610304)
		(end 57.7977 -283.610304)
		(width 0.14478)
		(layer "In13.Cu")
		(net "M_B_CPU1_SB_DQ<3>")
	)
	(segment
		(start 57.7977 -283.610304)
		(end 57.34304 -284.064964)
		(width 0.14478)
		(layer "In13.Cu")
		(net "M_B_CPU1_SB_DQ<3>")
	)
	(segment
		(start 80.778096 -275.383752)
		(end 80.769714 -275.378926)
		(width 0.0889)
		(layer "In13.Cu")
		(net "M_B_CPU1_SB_DQ<3>")
	)
	(segment
		(start 79.649828 -275.332952)
		(end 78.400656 -275.332952)
		(width 0.0889)
		(layer "In13.Cu")
		(net "M_B_CPU1_SB_DQ<3>")
	)
	(segment
		(start 80.403954 -275.383752)
		(end 80.389222 -275.392388)
		(width 0.0889)
		(layer "In13.Cu")
		(net "M_B_CPU1_SB_DQ<3>")
	)
	(segment
		(start 53.520848 -284.064964)
		(end 53.056536 -283.600652)
		(width 0.14478)
		(layer "In13.Cu")
		(net "M_B_CPU1_SB_DQ<3>")
	)
	(segment
		(start 89.05113 -275.706332)
		(end 89.205054 -275.440902)
		(width 0.0889)
		(layer "In13.Cu")
		(net "M_B_CPU1_SB_DQ<3>")
	)
	(segment
		(start 85.112352 -275.378926)
		(end 85.10397 -275.383752)
		(width 0.0889)
		(layer "In13.Cu")
		(net "M_B_CPU1_SB_DQ<3>")
	)
	(segment
		(start 68.402708 -274.584414)
		(end 59.376818 -283.610304)
		(width 0.14478)
		(layer "In13.Cu")
		(net "M_B_CPU1_SB_DQ<3>")
	)
	(segment
		(start 77.30871 -274.241006)
		(end 76.82865 -274.241006)
		(width 0.0889)
		(layer "In13.Cu")
		(net "M_B_CPU1_SB_DQ<3>")
	)
	(arc
		(start 80.389222 -275.392388)
		(mid 80.112239 -275.460192)
		(end 79.837534 -275.383752)
		(width 0.0889)
		(layer "In13.Cu")
		(net "M_B_CPU1_SB_DQ<3>")
	)
	(arc
		(start 82.65795 -275.383752)
		(mid 82.471006 -275.333497)
		(end 82.284062 -275.383752)
		(width 0.0889)
		(layer "In13.Cu")
		(net "M_B_CPU1_SB_DQ<3>")
	)
	(arc
		(start 84.529676 -275.378926)
		(mid 84.346168 -275.333432)
		(end 84.163916 -275.383752)
		(width 0.0889)
		(layer "In13.Cu")
		(net "M_B_CPU1_SB_DQ<3>")
	)
	(arc
		(start 86.418166 -275.383752)
		(mid 86.235915 -275.333402)
		(end 86.052406 -275.378926)
		(width 0.0889)
		(layer "In13.Cu")
		(net "M_B_CPU1_SB_DQ<3>")
	)
	(arc
		(start 81.344008 -275.383752)
		(mid 81.061052 -275.459929)
		(end 80.778096 -275.383752)
		(width 0.0889)
		(layer "In13.Cu")
		(net "M_B_CPU1_SB_DQ<3>")
	)
	(arc
		(start 89.182702 -275.35759)
		(mid 89.02037 -275.334772)
		(end 88.863932 -275.383752)
		(width 0.0889)
		(layer "In13.Cu")
		(net "M_B_CPU1_SB_DQ<3>")
	)
	(arc
		(start 83.223862 -275.383752)
		(mid 82.940906 -275.459929)
		(end 82.65795 -275.383752)
		(width 0.0889)
		(layer "In13.Cu")
		(net "M_B_CPU1_SB_DQ<3>")
	)
	(arc
		(start 82.284062 -275.383752)
		(mid 82.001106 -275.459929)
		(end 81.71815 -275.383752)
		(width 0.0889)
		(layer "In13.Cu")
		(net "M_B_CPU1_SB_DQ<3>")
	)
	(arc
		(start 81.71815 -275.383752)
		(mid 81.535899 -275.333402)
		(end 81.35239 -275.378926)
		(width 0.0889)
		(layer "In13.Cu")
		(net "M_B_CPU1_SB_DQ<3>")
	)
	(arc
		(start 88.289638 -275.378926)
		(mid 88.10613 -275.333432)
		(end 87.923878 -275.383752)
		(width 0.0889)
		(layer "In13.Cu")
		(net "M_B_CPU1_SB_DQ<3>")
	)
	(arc
		(start 80.769714 -275.378926)
		(mid 80.586206 -275.333432)
		(end 80.403954 -275.383752)
		(width 0.0889)
		(layer "In13.Cu")
		(net "M_B_CPU1_SB_DQ<3>")
	)
	(arc
		(start 79.837534 -275.383752)
		(mid 79.747044 -275.345934)
		(end 79.649828 -275.332952)
		(width 0.0889)
		(layer "In13.Cu")
		(net "M_B_CPU1_SB_DQ<3>")
	)
	(arc
		(start 88.863932 -275.383752)
		(mid 88.580976 -275.459929)
		(end 88.29802 -275.383752)
		(width 0.0889)
		(layer "In13.Cu")
		(net "M_B_CPU1_SB_DQ<3>")
	)
	(arc
		(start 87.923878 -275.383752)
		(mid 87.640922 -275.459929)
		(end 87.357966 -275.383752)
		(width 0.0889)
		(layer "In13.Cu")
		(net "M_B_CPU1_SB_DQ<3>")
	)
	(arc
		(start 87.357966 -275.383752)
		(mid 87.171022 -275.333497)
		(end 86.984078 -275.383752)
		(width 0.0889)
		(layer "In13.Cu")
		(net "M_B_CPU1_SB_DQ<3>")
	)
	(arc
		(start 85.10397 -275.383752)
		(mid 84.821014 -275.459929)
		(end 84.538058 -275.383752)
		(width 0.0889)
		(layer "In13.Cu")
		(net "M_B_CPU1_SB_DQ<3>")
	)
	(arc
		(start 84.163916 -275.383752)
		(mid 83.88096 -275.459929)
		(end 83.598004 -275.383752)
		(width 0.0889)
		(layer "In13.Cu")
		(net "M_B_CPU1_SB_DQ<3>")
	)
	(arc
		(start 86.044024 -275.383752)
		(mid 85.761068 -275.459929)
		(end 85.478112 -275.383752)
		(width 0.0889)
		(layer "In13.Cu")
		(net "M_B_CPU1_SB_DQ<3>")
	)
	(arc
		(start 83.589622 -275.378926)
		(mid 83.406114 -275.333432)
		(end 83.223862 -275.383752)
		(width 0.0889)
		(layer "In13.Cu")
		(net "M_B_CPU1_SB_DQ<3>")
	)
	(arc
		(start 85.478112 -275.383752)
		(mid 85.295861 -275.333402)
		(end 85.112352 -275.378926)
		(width 0.0889)
		(layer "In13.Cu")
		(net "M_B_CPU1_SB_DQ<3>")
	)
	(arc
		(start 86.984078 -275.383752)
		(mid 86.701122 -275.459929)
		(end 86.418166 -275.383752)
		(width 0.0889)
		(layer "In13.Cu")
		(net "M_B_CPU1_SB_DQ<3>")
	)
	(segment
		(start 89.517982 -293.260272)
		(end 89.05113 -293.52621)
		(width 0.10668)
		(layer "F.Cu")
		(net "M_B_CPU1_SB_DQ<31>")
	)
	(segment
		(start 62.295786 -316.375034)
		(end 77.12202 -301.5488)
		(width 0.14478)
		(layer "In13.Cu")
		(net "M_B_CPU1_SB_DQ<31>")
	)
	(segment
		(start 86.044024 -293.20363)
		(end 86.052406 -293.198804)
		(width 0.0889)
		(layer "In13.Cu")
		(net "M_B_CPU1_SB_DQ<31>")
	)
	(segment
		(start 77.12202 -299.233082)
		(end 79.79918 -296.555922)
		(width 0.14478)
		(layer "In13.Cu")
		(net "M_B_CPU1_SB_DQ<31>")
	)
	(segment
		(start 49.920398 -318.460374)
		(end 57.261506 -318.460374)
		(width 0.14478)
		(layer "In13.Cu")
		(net "M_B_CPU1_SB_DQ<31>")
	)
	(segment
		(start 82.281268 -293.205408)
		(end 82.284062 -293.20363)
		(width 0.0889)
		(layer "In13.Cu")
		(net "M_B_CPU1_SB_DQ<31>")
	)
	(segment
		(start 81.344008 -294.823642)
		(end 81.383124 -294.800782)
		(width 0.0889)
		(layer "In13.Cu")
		(net "M_B_CPU1_SB_DQ<31>")
	)
	(segment
		(start 80.873854 -295.633648)
		(end 80.91297 -295.610788)
		(width 0.0889)
		(layer "In13.Cu")
		(net "M_B_CPU1_SB_DQ<31>")
	)
	(segment
		(start 80.843374 -295.651428)
		(end 80.873854 -295.633648)
		(width 0.0889)
		(layer "In13.Cu")
		(net "M_B_CPU1_SB_DQ<31>")
	)
	(segment
		(start 81.783428 -294.031416)
		(end 81.813908 -294.013636)
		(width 0.0889)
		(layer "In13.Cu")
		(net "M_B_CPU1_SB_DQ<31>")
	)
	(segment
		(start 79.912464 -296.458386)
		(end 80.349344 -296.458386)
		(width 0.0889)
		(layer "In13.Cu")
		(net "M_B_CPU1_SB_DQ<31>")
	)
	(segment
		(start 84.529676 -293.198804)
		(end 84.538058 -293.20363)
		(width 0.0889)
		(layer "In13.Cu")
		(net "M_B_CPU1_SB_DQ<31>")
	)
	(segment
		(start 89.205054 -293.26078)
		(end 89.05113 -293.52621)
		(width 0.0889)
		(layer "In13.Cu")
		(net "M_B_CPU1_SB_DQ<31>")
	)
	(segment
		(start 57.261506 -318.460374)
		(end 62.295786 -316.375034)
		(width 0.14478)
		(layer "In13.Cu")
		(net "M_B_CPU1_SB_DQ<31>")
	)
	(segment
		(start 80.4037 -296.443654)
		(end 80.444086 -296.420032)
		(width 0.0889)
		(layer "In13.Cu")
		(net "M_B_CPU1_SB_DQ<31>")
	)
	(segment
		(start 83.589622 -293.198804)
		(end 83.598004 -293.20363)
		(width 0.0889)
		(layer "In13.Cu")
		(net "M_B_CPU1_SB_DQ<31>")
	)
	(segment
		(start 77.12202 -301.5488)
		(end 77.12202 -299.233082)
		(width 0.14478)
		(layer "In13.Cu")
		(net "M_B_CPU1_SB_DQ<31>")
	)
	(segment
		(start 85.10397 -293.20363)
		(end 85.112352 -293.198804)
		(width 0.0889)
		(layer "In13.Cu")
		(net "M_B_CPU1_SB_DQ<31>")
	)
	(segment
		(start 81.312258 -294.84193)
		(end 81.344008 -294.823642)
		(width 0.0889)
		(layer "In13.Cu")
		(net "M_B_CPU1_SB_DQ<31>")
	)
	(segment
		(start 79.79918 -296.555922)
		(end 79.88554 -296.469562)
		(width 0.0889)
		(layer "In13.Cu")
		(net "M_B_CPU1_SB_DQ<31>")
	)
	(segment
		(start 89.182702 -293.177468)
		(end 89.205054 -293.26078)
		(width 0.0889)
		(layer "In13.Cu")
		(net "M_B_CPU1_SB_DQ<31>")
	)
	(segment
		(start 47.784004 -318.035432)
		(end 48.144938 -318.035432)
		(width 0.14478)
		(layer "In13.Cu")
		(net "M_B_CPU1_SB_DQ<31>")
	)
	(segment
		(start 88.289638 -293.198804)
		(end 88.29802 -293.20363)
		(width 0.0889)
		(layer "In13.Cu")
		(net "M_B_CPU1_SB_DQ<31>")
	)
	(segment
		(start 48.2346 -318.125094)
		(end 49.920398 -318.460374)
		(width 0.14478)
		(layer "In13.Cu")
		(net "M_B_CPU1_SB_DQ<31>")
	)
	(segment
		(start 48.144938 -318.035432)
		(end 48.2346 -318.125094)
		(width 0.14478)
		(layer "In13.Cu")
		(net "M_B_CPU1_SB_DQ<31>")
	)
	(segment
		(start 81.813908 -294.013636)
		(end 81.816448 -294.011858)
		(width 0.0889)
		(layer "In13.Cu")
		(net "M_B_CPU1_SB_DQ<31>")
	)
	(arc
		(start 86.418166 -293.20363)
		(mid 86.701122 -293.279807)
		(end 86.984078 -293.20363)
		(width 0.0889)
		(layer "In13.Cu")
		(net "M_B_CPU1_SB_DQ<31>")
	)
	(arc
		(start 86.984078 -293.20363)
		(mid 87.171022 -293.153375)
		(end 87.357966 -293.20363)
		(width 0.0889)
		(layer "In13.Cu")
		(net "M_B_CPU1_SB_DQ<31>")
	)
	(arc
		(start 80.444086 -296.420032)
		(mid 80.622151 -296.217855)
		(end 80.686402 -295.956228)
		(width 0.0889)
		(layer "In13.Cu")
		(net "M_B_CPU1_SB_DQ<31>")
	)
	(arc
		(start 86.052406 -293.198804)
		(mid 86.235914 -293.15331)
		(end 86.418166 -293.20363)
		(width 0.0889)
		(layer "In13.Cu")
		(net "M_B_CPU1_SB_DQ<31>")
	)
	(arc
		(start 79.88554 -296.469562)
		(mid 79.897893 -296.461308)
		(end 79.912464 -296.458386)
		(width 0.0889)
		(layer "In13.Cu")
		(net "M_B_CPU1_SB_DQ<31>")
	)
	(arc
		(start 83.598004 -293.20363)
		(mid 83.88096 -293.279807)
		(end 84.163916 -293.20363)
		(width 0.0889)
		(layer "In13.Cu")
		(net "M_B_CPU1_SB_DQ<31>")
	)
	(arc
		(start 87.923878 -293.20363)
		(mid 88.106129 -293.15328)
		(end 88.289638 -293.198804)
		(width 0.0889)
		(layer "In13.Cu")
		(net "M_B_CPU1_SB_DQ<31>")
	)
	(arc
		(start 85.112352 -293.198804)
		(mid 85.29586 -293.15331)
		(end 85.478112 -293.20363)
		(width 0.0889)
		(layer "In13.Cu")
		(net "M_B_CPU1_SB_DQ<31>")
	)
	(arc
		(start 84.538058 -293.20363)
		(mid 84.821014 -293.279807)
		(end 85.10397 -293.20363)
		(width 0.0889)
		(layer "In13.Cu")
		(net "M_B_CPU1_SB_DQ<31>")
	)
	(arc
		(start 81.156302 -295.146222)
		(mid 81.197557 -294.975251)
		(end 81.312258 -294.84193)
		(width 0.0889)
		(layer "In13.Cu")
		(net "M_B_CPU1_SB_DQ<31>")
	)
	(arc
		(start 82.284062 -293.20363)
		(mid 82.471006 -293.153375)
		(end 82.65795 -293.20363)
		(width 0.0889)
		(layer "In13.Cu")
		(net "M_B_CPU1_SB_DQ<31>")
	)
	(arc
		(start 85.478112 -293.20363)
		(mid 85.761068 -293.279807)
		(end 86.044024 -293.20363)
		(width 0.0889)
		(layer "In13.Cu")
		(net "M_B_CPU1_SB_DQ<31>")
	)
	(arc
		(start 81.383124 -294.800782)
		(mid 81.561937 -294.598432)
		(end 81.626456 -294.336216)
		(width 0.0889)
		(layer "In13.Cu")
		(net "M_B_CPU1_SB_DQ<31>")
	)
	(arc
		(start 88.863932 -293.20363)
		(mid 89.02037 -293.154659)
		(end 89.182702 -293.177468)
		(width 0.0889)
		(layer "In13.Cu")
		(net "M_B_CPU1_SB_DQ<31>")
	)
	(arc
		(start 81.626456 -294.336216)
		(mid 81.668005 -294.164794)
		(end 81.783428 -294.031416)
		(width 0.0889)
		(layer "In13.Cu")
		(net "M_B_CPU1_SB_DQ<31>")
	)
	(arc
		(start 82.65795 -293.20363)
		(mid 82.940906 -293.279807)
		(end 83.223862 -293.20363)
		(width 0.0889)
		(layer "In13.Cu")
		(net "M_B_CPU1_SB_DQ<31>")
	)
	(arc
		(start 84.163916 -293.20363)
		(mid 84.346167 -293.15328)
		(end 84.529676 -293.198804)
		(width 0.0889)
		(layer "In13.Cu")
		(net "M_B_CPU1_SB_DQ<31>")
	)
	(arc
		(start 80.349344 -296.458386)
		(mid 80.377503 -296.454639)
		(end 80.4037 -296.443654)
		(width 0.0889)
		(layer "In13.Cu")
		(net "M_B_CPU1_SB_DQ<31>")
	)
	(arc
		(start 80.686402 -295.956228)
		(mid 80.727951 -295.784806)
		(end 80.843374 -295.651428)
		(width 0.0889)
		(layer "In13.Cu")
		(net "M_B_CPU1_SB_DQ<31>")
	)
	(arc
		(start 83.223862 -293.20363)
		(mid 83.406113 -293.15328)
		(end 83.589622 -293.198804)
		(width 0.0889)
		(layer "In13.Cu")
		(net "M_B_CPU1_SB_DQ<31>")
	)
	(arc
		(start 80.91297 -295.610788)
		(mid 81.091783 -295.408438)
		(end 81.156302 -295.146222)
		(width 0.0889)
		(layer "In13.Cu")
		(net "M_B_CPU1_SB_DQ<31>")
	)
	(arc
		(start 81.816448 -294.011858)
		(mid 82.021348 -293.806458)
		(end 82.096356 -293.52621)
		(width 0.0889)
		(layer "In13.Cu")
		(net "M_B_CPU1_SB_DQ<31>")
	)
	(arc
		(start 82.096356 -293.52621)
		(mid 82.145885 -293.341057)
		(end 82.281268 -293.205408)
		(width 0.0889)
		(layer "In13.Cu")
		(net "M_B_CPU1_SB_DQ<31>")
	)
	(arc
		(start 88.29802 -293.20363)
		(mid 88.580976 -293.279807)
		(end 88.863932 -293.20363)
		(width 0.0889)
		(layer "In13.Cu")
		(net "M_B_CPU1_SB_DQ<31>")
	)
	(arc
		(start 87.357966 -293.20363)
		(mid 87.640922 -293.279807)
		(end 87.923878 -293.20363)
		(width 0.0889)
		(layer "In13.Cu")
		(net "M_B_CPU1_SB_DQ<31>")
	)
	(segment
		(start 88.107774 -292.450266)
		(end 87.640922 -292.716204)
		(width 0.10668)
		(layer "F.Cu")
		(net "M_B_CPU1_SB_DQ<30>")
	)
	(segment
		(start 49.910746 -317.261748)
		(end 50.055526 -317.116968)
		(width 0.14478)
		(layer "In13.Cu")
		(net "M_B_CPU1_SB_DQ<30>")
	)
	(segment
		(start 87.453978 -292.393624)
		(end 87.46236 -292.388798)
		(width 0.0889)
		(layer "In13.Cu")
		(net "M_B_CPU1_SB_DQ<30>")
	)
	(segment
		(start 86.879684 -292.388798)
		(end 86.888066 -292.393624)
		(width 0.0889)
		(layer "In13.Cu")
		(net "M_B_CPU1_SB_DQ<30>")
	)
	(segment
		(start 79.90459 -294.030654)
		(end 79.934054 -294.013636)
		(width 0.0889)
		(layer "In13.Cu")
		(net "M_B_CPU1_SB_DQ<30>")
	)
	(segment
		(start 82.179668 -292.388798)
		(end 82.18805 -292.393624)
		(width 0.0889)
		(layer "In13.Cu")
		(net "M_B_CPU1_SB_DQ<30>")
	)
	(segment
		(start 50.055526 -316.905132)
		(end 50.200306 -316.760352)
		(width 0.14478)
		(layer "In13.Cu")
		(net "M_B_CPU1_SB_DQ<30>")
	)
	(segment
		(start 78.562454 -295.865296)
		(end 78.641702 -295.786302)
		(width 0.0889)
		(layer "In13.Cu")
		(net "M_B_CPU1_SB_DQ<30>")
	)
	(segment
		(start 79.934054 -294.013636)
		(end 79.97317 -293.990776)
		(width 0.0889)
		(layer "In13.Cu")
		(net "M_B_CPU1_SB_DQ<30>")
	)
	(segment
		(start 50.200306 -316.760352)
		(end 57.12587 -316.760352)
		(width 0.14478)
		(layer "In13.Cu")
		(net "M_B_CPU1_SB_DQ<30>")
	)
	(segment
		(start 87.772748 -292.367462)
		(end 87.7951 -292.450774)
		(width 0.0889)
		(layer "In13.Cu")
		(net "M_B_CPU1_SB_DQ<30>")
	)
	(segment
		(start 48.139858 -316.33541)
		(end 48.5648 -316.760352)
		(width 0.14478)
		(layer "In13.Cu")
		(net "M_B_CPU1_SB_DQ<30>")
	)
	(segment
		(start 75.75931 -301.211742)
		(end 75.75931 -298.66844)
		(width 0.14478)
		(layer "In13.Cu")
		(net "M_B_CPU1_SB_DQ<30>")
	)
	(segment
		(start 78.947772 -295.66997)
		(end 79.0321 -295.611804)
		(width 0.0889)
		(layer "In13.Cu")
		(net "M_B_CPU1_SB_DQ<30>")
	)
	(segment
		(start 75.75931 -298.66844)
		(end 78.310486 -296.117264)
		(width 0.14478)
		(layer "In13.Cu")
		(net "M_B_CPU1_SB_DQ<30>")
	)
	(segment
		(start 80.373474 -293.22141)
		(end 80.403954 -293.20363)
		(width 0.0889)
		(layer "In13.Cu")
		(net "M_B_CPU1_SB_DQ<30>")
	)
	(segment
		(start 83.694016 -292.393624)
		(end 83.702398 -292.388798)
		(width 0.0889)
		(layer "In13.Cu")
		(net "M_B_CPU1_SB_DQ<30>")
	)
	(segment
		(start 79.464408 -294.823642)
		(end 79.50073 -294.80256)
		(width 0.0889)
		(layer "In13.Cu")
		(net "M_B_CPU1_SB_DQ<30>")
	)
	(segment
		(start 79.432658 -294.84193)
		(end 79.464408 -294.823642)
		(width 0.0889)
		(layer "In13.Cu")
		(net "M_B_CPU1_SB_DQ<30>")
	)
	(segment
		(start 57.12587 -316.760352)
		(end 62.392052 -314.579)
		(width 0.14478)
		(layer "In13.Cu")
		(net "M_B_CPU1_SB_DQ<30>")
	)
	(segment
		(start 49.504346 -316.905132)
		(end 49.504346 -317.116968)
		(width 0.14478)
		(layer "In13.Cu")
		(net "M_B_CPU1_SB_DQ<30>")
	)
	(segment
		(start 49.359566 -316.760352)
		(end 49.504346 -316.905132)
		(width 0.14478)
		(layer "In13.Cu")
		(net "M_B_CPU1_SB_DQ<30>")
	)
	(segment
		(start 85.93963 -292.388798)
		(end 85.948012 -292.393624)
		(width 0.0889)
		(layer "In13.Cu")
		(net "M_B_CPU1_SB_DQ<30>")
	)
	(segment
		(start 62.392052 -314.579)
		(end 75.75931 -301.211742)
		(width 0.14478)
		(layer "In13.Cu")
		(net "M_B_CPU1_SB_DQ<30>")
	)
	(segment
		(start 87.7951 -292.450774)
		(end 87.640922 -292.716204)
		(width 0.0889)
		(layer "In13.Cu")
		(net "M_B_CPU1_SB_DQ<30>")
	)
	(segment
		(start 82.753962 -292.393624)
		(end 82.762344 -292.388798)
		(width 0.0889)
		(layer "In13.Cu")
		(net "M_B_CPU1_SB_DQ<30>")
	)
	(segment
		(start 48.5648 -316.760352)
		(end 49.359566 -316.760352)
		(width 0.14478)
		(layer "In13.Cu")
		(net "M_B_CPU1_SB_DQ<30>")
	)
	(segment
		(start 50.055526 -317.116968)
		(end 50.055526 -316.905132)
		(width 0.14478)
		(layer "In13.Cu")
		(net "M_B_CPU1_SB_DQ<30>")
	)
	(segment
		(start 47.784004 -316.33541)
		(end 48.139858 -316.33541)
		(width 0.14478)
		(layer "In13.Cu")
		(net "M_B_CPU1_SB_DQ<30>")
	)
	(segment
		(start 49.504346 -317.116968)
		(end 49.649126 -317.261748)
		(width 0.14478)
		(layer "In13.Cu")
		(net "M_B_CPU1_SB_DQ<30>")
	)
	(segment
		(start 80.403954 -293.20363)
		(end 80.44307 -293.18077)
		(width 0.0889)
		(layer "In13.Cu")
		(net "M_B_CPU1_SB_DQ<30>")
	)
	(segment
		(start 78.310486 -296.117264)
		(end 78.562454 -295.865296)
		(width 0.0889)
		(layer "In13.Cu")
		(net "M_B_CPU1_SB_DQ<30>")
	)
	(segment
		(start 49.649126 -317.261748)
		(end 49.910746 -317.261748)
		(width 0.14478)
		(layer "In13.Cu")
		(net "M_B_CPU1_SB_DQ<30>")
	)
	(segment
		(start 80.842358 -292.411912)
		(end 80.874108 -292.393624)
		(width 0.0889)
		(layer "In13.Cu")
		(net "M_B_CPU1_SB_DQ<30>")
	)
	(arc
		(start 80.874108 -292.393624)
		(mid 81.061052 -292.343369)
		(end 81.247996 -292.393624)
		(width 0.0889)
		(layer "In13.Cu")
		(net "M_B_CPU1_SB_DQ<30>")
	)
	(arc
		(start 83.702398 -292.388798)
		(mid 83.885906 -292.343304)
		(end 84.068158 -292.393624)
		(width 0.0889)
		(layer "In13.Cu")
		(net "M_B_CPU1_SB_DQ<30>")
	)
	(arc
		(start 85.57387 -292.393624)
		(mid 85.756121 -292.343274)
		(end 85.93963 -292.388798)
		(width 0.0889)
		(layer "In13.Cu")
		(net "M_B_CPU1_SB_DQ<30>")
	)
	(arc
		(start 87.46236 -292.388798)
		(mid 87.61523 -292.344157)
		(end 87.772748 -292.367462)
		(width 0.0889)
		(layer "In13.Cu")
		(net "M_B_CPU1_SB_DQ<30>")
	)
	(arc
		(start 79.97317 -293.990776)
		(mid 80.151983 -293.788426)
		(end 80.216502 -293.52621)
		(width 0.0889)
		(layer "In13.Cu")
		(net "M_B_CPU1_SB_DQ<30>")
	)
	(arc
		(start 79.746602 -294.336216)
		(mid 79.788442 -294.16423)
		(end 79.90459 -294.030654)
		(width 0.0889)
		(layer "In13.Cu")
		(net "M_B_CPU1_SB_DQ<30>")
	)
	(arc
		(start 79.0321 -295.611804)
		(mid 79.211829 -295.409184)
		(end 79.276702 -295.146222)
		(width 0.0889)
		(layer "In13.Cu")
		(net "M_B_CPU1_SB_DQ<30>")
	)
	(arc
		(start 79.276702 -295.146222)
		(mid 79.317957 -294.975251)
		(end 79.432658 -294.84193)
		(width 0.0889)
		(layer "In13.Cu")
		(net "M_B_CPU1_SB_DQ<30>")
	)
	(arc
		(start 78.844902 -295.701974)
		(mid 78.898763 -295.693779)
		(end 78.947772 -295.66997)
		(width 0.0889)
		(layer "In13.Cu")
		(net "M_B_CPU1_SB_DQ<30>")
	)
	(arc
		(start 80.216502 -293.52621)
		(mid 80.258051 -293.354788)
		(end 80.373474 -293.22141)
		(width 0.0889)
		(layer "In13.Cu")
		(net "M_B_CPU1_SB_DQ<30>")
	)
	(arc
		(start 82.18805 -292.393624)
		(mid 82.471006 -292.469801)
		(end 82.753962 -292.393624)
		(width 0.0889)
		(layer "In13.Cu")
		(net "M_B_CPU1_SB_DQ<30>")
	)
	(arc
		(start 84.63407 -292.393624)
		(mid 84.821014 -292.343369)
		(end 85.007958 -292.393624)
		(width 0.0889)
		(layer "In13.Cu")
		(net "M_B_CPU1_SB_DQ<30>")
	)
	(arc
		(start 85.948012 -292.393624)
		(mid 86.230968 -292.469801)
		(end 86.513924 -292.393624)
		(width 0.0889)
		(layer "In13.Cu")
		(net "M_B_CPU1_SB_DQ<30>")
	)
	(arc
		(start 81.813908 -292.393624)
		(mid 81.996159 -292.343274)
		(end 82.179668 -292.388798)
		(width 0.0889)
		(layer "In13.Cu")
		(net "M_B_CPU1_SB_DQ<30>")
	)
	(arc
		(start 86.888066 -292.393624)
		(mid 87.171022 -292.469801)
		(end 87.453978 -292.393624)
		(width 0.0889)
		(layer "In13.Cu")
		(net "M_B_CPU1_SB_DQ<30>")
	)
	(arc
		(start 86.513924 -292.393624)
		(mid 86.696175 -292.343274)
		(end 86.879684 -292.388798)
		(width 0.0889)
		(layer "In13.Cu")
		(net "M_B_CPU1_SB_DQ<30>")
	)
	(arc
		(start 79.50073 -294.80256)
		(mid 79.681382 -294.599815)
		(end 79.746602 -294.336216)
		(width 0.0889)
		(layer "In13.Cu")
		(net "M_B_CPU1_SB_DQ<30>")
	)
	(arc
		(start 84.068158 -292.393624)
		(mid 84.351114 -292.469801)
		(end 84.63407 -292.393624)
		(width 0.0889)
		(layer "In13.Cu")
		(net "M_B_CPU1_SB_DQ<30>")
	)
	(arc
		(start 83.128104 -292.393624)
		(mid 83.41106 -292.469801)
		(end 83.694016 -292.393624)
		(width 0.0889)
		(layer "In13.Cu")
		(net "M_B_CPU1_SB_DQ<30>")
	)
	(arc
		(start 80.686402 -292.716204)
		(mid 80.727657 -292.545233)
		(end 80.842358 -292.411912)
		(width 0.0889)
		(layer "In13.Cu")
		(net "M_B_CPU1_SB_DQ<30>")
	)
	(arc
		(start 81.247996 -292.393624)
		(mid 81.530952 -292.469801)
		(end 81.813908 -292.393624)
		(width 0.0889)
		(layer "In13.Cu")
		(net "M_B_CPU1_SB_DQ<30>")
	)
	(arc
		(start 80.44307 -293.18077)
		(mid 80.621883 -292.97842)
		(end 80.686402 -292.716204)
		(width 0.0889)
		(layer "In13.Cu")
		(net "M_B_CPU1_SB_DQ<30>")
	)
	(arc
		(start 78.641702 -295.786302)
		(mid 78.734916 -295.723925)
		(end 78.844902 -295.701974)
		(width 0.0889)
		(layer "In13.Cu")
		(net "M_B_CPU1_SB_DQ<30>")
	)
	(arc
		(start 85.007958 -292.393624)
		(mid 85.290914 -292.469801)
		(end 85.57387 -292.393624)
		(width 0.0889)
		(layer "In13.Cu")
		(net "M_B_CPU1_SB_DQ<30>")
	)
	(arc
		(start 82.762344 -292.388798)
		(mid 82.945852 -292.343304)
		(end 83.128104 -292.393624)
		(width 0.0889)
		(layer "In13.Cu")
		(net "M_B_CPU1_SB_DQ<30>")
	)
	(segment
		(start 88.107774 -274.630388)
		(end 87.640922 -274.896326)
		(width 0.10668)
		(layer "F.Cu")
		(net "M_B_CPU1_SB_DQ<2>")
	)
	(segment
		(start 53.433218 -282.365196)
		(end 57.391554 -282.365196)
		(width 0.14478)
		(layer "In13.Cu")
		(net "M_B_CPU1_SB_DQ<2>")
	)
	(segment
		(start 59.804554 -281.910282)
		(end 68.039742 -273.675094)
		(width 0.14478)
		(layer "In13.Cu")
		(net "M_B_CPU1_SB_DQ<2>")
	)
	(segment
		(start 87.453978 -274.573746)
		(end 87.46236 -274.56892)
		(width 0.0889)
		(layer "In13.Cu")
		(net "M_B_CPU1_SB_DQ<2>")
	)
	(segment
		(start 49.349406 -282.335224)
		(end 50.823622 -282.335224)
		(width 0.14478)
		(layer "In13.Cu")
		(net "M_B_CPU1_SB_DQ<2>")
	)
	(segment
		(start 48.653446 -282.480004)
		(end 48.653446 -282.818332)
		(width 0.14478)
		(layer "In13.Cu")
		(net "M_B_CPU1_SB_DQ<2>")
	)
	(segment
		(start 49.204626 -282.480004)
		(end 49.349406 -282.335224)
		(width 0.14478)
		(layer "In13.Cu")
		(net "M_B_CPU1_SB_DQ<2>")
	)
	(segment
		(start 49.204626 -282.818332)
		(end 49.204626 -282.480004)
		(width 0.14478)
		(layer "In13.Cu")
		(net "M_B_CPU1_SB_DQ<2>")
	)
	(segment
		(start 77.56525 -273.738086)
		(end 78.312264 -274.4851)
		(width 0.0889)
		(layer "In13.Cu")
		(net "M_B_CPU1_SB_DQ<2>")
	)
	(segment
		(start 48.798226 -282.963112)
		(end 49.059846 -282.963112)
		(width 0.14478)
		(layer "In13.Cu")
		(net "M_B_CPU1_SB_DQ<2>")
	)
	(segment
		(start 47.784004 -282.335224)
		(end 48.508666 -282.335224)
		(width 0.14478)
		(layer "In13.Cu")
		(net "M_B_CPU1_SB_DQ<2>")
	)
	(segment
		(start 79.36738 -274.573746)
		(end 79.377794 -274.579842)
		(width 0.0889)
		(layer "In13.Cu")
		(net "M_B_CPU1_SB_DQ<2>")
	)
	(segment
		(start 82.753962 -274.573746)
		(end 82.762344 -274.56892)
		(width 0.0889)
		(layer "In13.Cu")
		(net "M_B_CPU1_SB_DQ<2>")
	)
	(segment
		(start 85.93963 -274.56892)
		(end 85.948012 -274.573746)
		(width 0.0889)
		(layer "In13.Cu")
		(net "M_B_CPU1_SB_DQ<2>")
	)
	(segment
		(start 49.059846 -282.963112)
		(end 49.204626 -282.818332)
		(width 0.14478)
		(layer "In13.Cu")
		(net "M_B_CPU1_SB_DQ<2>")
	)
	(segment
		(start 87.772748 -274.547584)
		(end 87.7951 -274.630896)
		(width 0.0889)
		(layer "In13.Cu")
		(net "M_B_CPU1_SB_DQ<2>")
	)
	(segment
		(start 80.299814 -274.56892)
		(end 80.308196 -274.573746)
		(width 0.0889)
		(layer "In13.Cu")
		(net "M_B_CPU1_SB_DQ<2>")
	)
	(segment
		(start 68.039742 -273.675094)
		(end 75.985116 -273.675094)
		(width 0.14478)
		(layer "In13.Cu")
		(net "M_B_CPU1_SB_DQ<2>")
	)
	(segment
		(start 85.948012 -274.573746)
		(end 85.948266 -274.573746)
		(width 0.0889)
		(layer "In13.Cu")
		(net "M_B_CPU1_SB_DQ<2>")
	)
	(segment
		(start 78.993492 -274.574)
		(end 79.009748 -274.564602)
		(width 0.0889)
		(layer "In13.Cu")
		(net "M_B_CPU1_SB_DQ<2>")
	)
	(segment
		(start 57.846468 -281.910282)
		(end 59.804554 -281.910282)
		(width 0.14478)
		(layer "In13.Cu")
		(net "M_B_CPU1_SB_DQ<2>")
	)
	(segment
		(start 76.30795 -273.738086)
		(end 77.56525 -273.738086)
		(width 0.0889)
		(layer "In13.Cu")
		(net "M_B_CPU1_SB_DQ<2>")
	)
	(segment
		(start 86.879684 -274.56892)
		(end 86.888066 -274.573746)
		(width 0.0889)
		(layer "In13.Cu")
		(net "M_B_CPU1_SB_DQ<2>")
	)
	(segment
		(start 76.244958 -273.675094)
		(end 76.30795 -273.738086)
		(width 0.0889)
		(layer "In13.Cu")
		(net "M_B_CPU1_SB_DQ<2>")
	)
	(segment
		(start 75.985116 -273.675094)
		(end 76.244958 -273.675094)
		(width 0.0889)
		(layer "In13.Cu")
		(net "M_B_CPU1_SB_DQ<2>")
	)
	(segment
		(start 82.179668 -274.56892)
		(end 82.18805 -274.573746)
		(width 0.0889)
		(layer "In13.Cu")
		(net "M_B_CPU1_SB_DQ<2>")
	)
	(segment
		(start 50.823622 -282.335224)
		(end 51.248564 -281.910282)
		(width 0.14478)
		(layer "In13.Cu")
		(net "M_B_CPU1_SB_DQ<2>")
	)
	(segment
		(start 78.977744 -274.583144)
		(end 78.993492 -274.574)
		(width 0.0889)
		(layer "In13.Cu")
		(net "M_B_CPU1_SB_DQ<2>")
	)
	(segment
		(start 48.508666 -282.335224)
		(end 48.653446 -282.480004)
		(width 0.14478)
		(layer "In13.Cu")
		(net "M_B_CPU1_SB_DQ<2>")
	)
	(segment
		(start 83.694016 -274.573746)
		(end 83.702398 -274.56892)
		(width 0.0889)
		(layer "In13.Cu")
		(net "M_B_CPU1_SB_DQ<2>")
	)
	(segment
		(start 57.391554 -282.365196)
		(end 57.846468 -281.910282)
		(width 0.14478)
		(layer "In13.Cu")
		(net "M_B_CPU1_SB_DQ<2>")
	)
	(segment
		(start 48.653446 -282.818332)
		(end 48.798226 -282.963112)
		(width 0.14478)
		(layer "In13.Cu")
		(net "M_B_CPU1_SB_DQ<2>")
	)
	(segment
		(start 87.7951 -274.630896)
		(end 87.640922 -274.896326)
		(width 0.0889)
		(layer "In13.Cu")
		(net "M_B_CPU1_SB_DQ<2>")
	)
	(segment
		(start 52.978304 -281.910282)
		(end 53.433218 -282.365196)
		(width 0.14478)
		(layer "In13.Cu")
		(net "M_B_CPU1_SB_DQ<2>")
	)
	(segment
		(start 51.248564 -281.910282)
		(end 52.978304 -281.910282)
		(width 0.14478)
		(layer "In13.Cu")
		(net "M_B_CPU1_SB_DQ<2>")
	)
	(arc
		(start 80.308196 -274.573746)
		(mid 80.591152 -274.649923)
		(end 80.874108 -274.573746)
		(width 0.0889)
		(layer "In13.Cu")
		(net "M_B_CPU1_SB_DQ<2>")
	)
	(arc
		(start 82.18805 -274.573746)
		(mid 82.471006 -274.649923)
		(end 82.753962 -274.573746)
		(width 0.0889)
		(layer "In13.Cu")
		(net "M_B_CPU1_SB_DQ<2>")
	)
	(arc
		(start 85.007958 -274.573746)
		(mid 85.290914 -274.649923)
		(end 85.57387 -274.573746)
		(width 0.0889)
		(layer "In13.Cu")
		(net "M_B_CPU1_SB_DQ<2>")
	)
	(arc
		(start 80.874108 -274.573746)
		(mid 81.061052 -274.523491)
		(end 81.247996 -274.573746)
		(width 0.0889)
		(layer "In13.Cu")
		(net "M_B_CPU1_SB_DQ<2>")
	)
	(arc
		(start 79.933546 -274.573746)
		(mid 80.116051 -274.523269)
		(end 80.299814 -274.56892)
		(width 0.0889)
		(layer "In13.Cu")
		(net "M_B_CPU1_SB_DQ<2>")
	)
	(arc
		(start 78.312264 -274.4851)
		(mid 78.367049 -274.53316)
		(end 78.42758 -274.573746)
		(width 0.0889)
		(layer "In13.Cu")
		(net "M_B_CPU1_SB_DQ<2>")
	)
	(arc
		(start 85.948266 -274.573746)
		(mid 86.231112 -274.649923)
		(end 86.513924 -274.573746)
		(width 0.0889)
		(layer "In13.Cu")
		(net "M_B_CPU1_SB_DQ<2>")
	)
	(arc
		(start 79.009748 -274.564602)
		(mid 79.18973 -274.523502)
		(end 79.36738 -274.573746)
		(width 0.0889)
		(layer "In13.Cu")
		(net "M_B_CPU1_SB_DQ<2>")
	)
	(arc
		(start 81.247996 -274.573746)
		(mid 81.530952 -274.649923)
		(end 81.813908 -274.573746)
		(width 0.0889)
		(layer "In13.Cu")
		(net "M_B_CPU1_SB_DQ<2>")
	)
	(arc
		(start 84.63407 -274.573746)
		(mid 84.821014 -274.523491)
		(end 85.007958 -274.573746)
		(width 0.0889)
		(layer "In13.Cu")
		(net "M_B_CPU1_SB_DQ<2>")
	)
	(arc
		(start 81.813908 -274.573746)
		(mid 81.996159 -274.523396)
		(end 82.179668 -274.56892)
		(width 0.0889)
		(layer "In13.Cu")
		(net "M_B_CPU1_SB_DQ<2>")
	)
	(arc
		(start 86.513924 -274.573746)
		(mid 86.696175 -274.523396)
		(end 86.879684 -274.56892)
		(width 0.0889)
		(layer "In13.Cu")
		(net "M_B_CPU1_SB_DQ<2>")
	)
	(arc
		(start 83.702398 -274.56892)
		(mid 83.885906 -274.523426)
		(end 84.068158 -274.573746)
		(width 0.0889)
		(layer "In13.Cu")
		(net "M_B_CPU1_SB_DQ<2>")
	)
	(arc
		(start 86.888066 -274.573746)
		(mid 87.171022 -274.649923)
		(end 87.453978 -274.573746)
		(width 0.0889)
		(layer "In13.Cu")
		(net "M_B_CPU1_SB_DQ<2>")
	)
	(arc
		(start 83.128104 -274.573746)
		(mid 83.41106 -274.649923)
		(end 83.694016 -274.573746)
		(width 0.0889)
		(layer "In13.Cu")
		(net "M_B_CPU1_SB_DQ<2>")
	)
	(arc
		(start 87.46236 -274.56892)
		(mid 87.61523 -274.524279)
		(end 87.772748 -274.547584)
		(width 0.0889)
		(layer "In13.Cu")
		(net "M_B_CPU1_SB_DQ<2>")
	)
	(arc
		(start 85.57387 -274.573746)
		(mid 85.756121 -274.523396)
		(end 85.93963 -274.56892)
		(width 0.0889)
		(layer "In13.Cu")
		(net "M_B_CPU1_SB_DQ<2>")
	)
	(arc
		(start 78.42758 -274.573746)
		(mid 78.701435 -274.650096)
		(end 78.977744 -274.583144)
		(width 0.0889)
		(layer "In13.Cu")
		(net "M_B_CPU1_SB_DQ<2>")
	)
	(arc
		(start 82.762344 -274.56892)
		(mid 82.945852 -274.523426)
		(end 83.128104 -274.573746)
		(width 0.0889)
		(layer "In13.Cu")
		(net "M_B_CPU1_SB_DQ<2>")
	)
	(arc
		(start 84.068158 -274.573746)
		(mid 84.351114 -274.649923)
		(end 84.63407 -274.573746)
		(width 0.0889)
		(layer "In13.Cu")
		(net "M_B_CPU1_SB_DQ<2>")
	)
	(arc
		(start 79.377794 -274.579842)
		(mid 79.65648 -274.650062)
		(end 79.933546 -274.573746)
		(width 0.0889)
		(layer "In13.Cu")
		(net "M_B_CPU1_SB_DQ<2>")
	)
	(segment
		(start 89.987882 -292.450266)
		(end 89.52103 -292.716204)
		(width 0.10668)
		(layer "F.Cu")
		(net "M_B_CPU1_SB_DQ<29>")
	)
	(segment
		(start 57.11825 -317.610236)
		(end 57.695846 -317.610236)
		(width 0.14478)
		(layer "In13.Cu")
		(net "M_B_CPU1_SB_DQ<29>")
	)
	(segment
		(start 58.641234 -316.80023)
		(end 58.73369 -317.023496)
		(width 0.14478)
		(layer "In13.Cu")
		(net "M_B_CPU1_SB_DQ<29>")
	)
	(segment
		(start 79.238348 -296.354246)
		(end 79.400908 -296.259758)
		(width 0.0889)
		(layer "In13.Cu")
		(net "M_B_CPU1_SB_DQ<29>")
	)
	(segment
		(start 53.66639 -317.828168)
		(end 53.66639 -317.755016)
		(width 0.14478)
		(layer "In13.Cu")
		(net "M_B_CPU1_SB_DQ<29>")
	)
	(segment
		(start 54.36235 -317.972948)
		(end 54.62397 -317.972948)
		(width 0.14478)
		(layer "In13.Cu")
		(net "M_B_CPU1_SB_DQ<29>")
	)
	(segment
		(start 54.91353 -317.610236)
		(end 55.17515 -317.610236)
		(width 0.14478)
		(layer "In13.Cu")
		(net "M_B_CPU1_SB_DQ<29>")
	)
	(segment
		(start 87.453978 -293.038784)
		(end 87.46236 -293.04361)
		(width 0.0889)
		(layer "In13.Cu")
		(net "M_B_CPU1_SB_DQ<29>")
	)
	(segment
		(start 56.82869 -317.972948)
		(end 56.97347 -317.828168)
		(width 0.14478)
		(layer "In13.Cu")
		(net "M_B_CPU1_SB_DQ<29>")
	)
	(segment
		(start 56.56707 -317.972948)
		(end 56.82869 -317.972948)
		(width 0.14478)
		(layer "In13.Cu")
		(net "M_B_CPU1_SB_DQ<29>")
	)
	(segment
		(start 51.884072 -317.185294)
		(end 52.309014 -317.610236)
		(width 0.14478)
		(layer "In13.Cu")
		(net "M_B_CPU1_SB_DQ<29>")
	)
	(segment
		(start 80.271874 -294.679878)
		(end 80.308196 -294.658796)
		(width 0.0889)
		(layer "In13.Cu")
		(net "M_B_CPU1_SB_DQ<29>")
	)
	(segment
		(start 58.452258 -316.721998)
		(end 58.641234 -316.80023)
		(width 0.14478)
		(layer "In13.Cu")
		(net "M_B_CPU1_SB_DQ<29>")
	)
	(segment
		(start 60.374784 -316.343538)
		(end 60.284868 -316.126622)
		(width 0.14478)
		(layer "In13.Cu")
		(net "M_B_CPU1_SB_DQ<29>")
	)
	(segment
		(start 85.93963 -293.04361)
		(end 85.948012 -293.038784)
		(width 0.0889)
		(layer "In13.Cu")
		(net "M_B_CPU1_SB_DQ<29>")
	)
	(segment
		(start 82.753962 -293.038784)
		(end 82.762344 -293.04361)
		(width 0.0889)
		(layer "In13.Cu")
		(net "M_B_CPU1_SB_DQ<29>")
	)
	(segment
		(start 55.72633 -317.972948)
		(end 55.87111 -317.828168)
		(width 0.14478)
		(layer "In13.Cu")
		(net "M_B_CPU1_SB_DQ<29>")
	)
	(segment
		(start 82.179668 -293.04361)
		(end 82.18805 -293.038784)
		(width 0.0889)
		(layer "In13.Cu")
		(net "M_B_CPU1_SB_DQ<29>")
	)
	(segment
		(start 86.879684 -293.04361)
		(end 86.888066 -293.038784)
		(width 0.0889)
		(layer "In13.Cu")
		(net "M_B_CPU1_SB_DQ<29>")
	)
	(segment
		(start 54.62397 -317.972948)
		(end 54.76875 -317.828168)
		(width 0.14478)
		(layer "In13.Cu")
		(net "M_B_CPU1_SB_DQ<29>")
	)
	(segment
		(start 56.97347 -317.828168)
		(end 56.97347 -317.755016)
		(width 0.14478)
		(layer "In13.Cu")
		(net "M_B_CPU1_SB_DQ<29>")
	)
	(segment
		(start 60.605416 -315.837316)
		(end 60.794138 -315.915548)
		(width 0.14478)
		(layer "In13.Cu")
		(net "M_B_CPU1_SB_DQ<29>")
	)
	(segment
		(start 53.81117 -317.610236)
		(end 54.07279 -317.610236)
		(width 0.14478)
		(layer "In13.Cu")
		(net "M_B_CPU1_SB_DQ<29>")
	)
	(segment
		(start 54.76875 -317.828168)
		(end 54.76875 -317.755016)
		(width 0.14478)
		(layer "In13.Cu")
		(net "M_B_CPU1_SB_DQ<29>")
	)
	(segment
		(start 81.211674 -293.059866)
		(end 81.247996 -293.038784)
		(width 0.0889)
		(layer "In13.Cu")
		(net "M_B_CPU1_SB_DQ<29>")
	)
	(segment
		(start 89.367106 -292.981634)
		(end 89.52103 -292.716204)
		(width 0.0889)
		(layer "In13.Cu")
		(net "M_B_CPU1_SB_DQ<29>")
	)
	(segment
		(start 79.838296 -295.468802)
		(end 79.870046 -295.450514)
		(width 0.0889)
		(layer "In13.Cu")
		(net "M_B_CPU1_SB_DQ<29>")
	)
	(segment
		(start 80.778096 -293.84879)
		(end 80.809846 -293.830502)
		(width 0.0889)
		(layer "In13.Cu")
		(net "M_B_CPU1_SB_DQ<29>")
	)
	(segment
		(start 56.42229 -317.755016)
		(end 56.42229 -317.828168)
		(width 0.14478)
		(layer "In13.Cu")
		(net "M_B_CPU1_SB_DQ<29>")
	)
	(segment
		(start 58.210196 -316.822328)
		(end 58.452258 -316.721998)
		(width 0.14478)
		(layer "In13.Cu")
		(net "M_B_CPU1_SB_DQ<29>")
	)
	(segment
		(start 61.073284 -316.21095)
		(end 61.623956 -315.983112)
		(width 0.14478)
		(layer "In13.Cu")
		(net "M_B_CPU1_SB_DQ<29>")
	)
	(segment
		(start 56.27751 -317.610236)
		(end 56.42229 -317.755016)
		(width 0.14478)
		(layer "In13.Cu")
		(net "M_B_CPU1_SB_DQ<29>")
	)
	(segment
		(start 88.394032 -293.038784)
		(end 88.402414 -293.04361)
		(width 0.0889)
		(layer "In13.Cu")
		(net "M_B_CPU1_SB_DQ<29>")
	)
	(segment
		(start 54.21757 -317.828168)
		(end 54.36235 -317.972948)
		(width 0.14478)
		(layer "In13.Cu")
		(net "M_B_CPU1_SB_DQ<29>")
	)
	(segment
		(start 58.922666 -317.101728)
		(end 60.296552 -316.532514)
		(width 0.14478)
		(layer "In13.Cu")
		(net "M_B_CPU1_SB_DQ<29>")
	)
	(segment
		(start 61.623956 -315.983112)
		(end 76.244196 -301.362872)
		(width 0.14478)
		(layer "In13.Cu")
		(net "M_B_CPU1_SB_DQ<29>")
	)
	(segment
		(start 60.884054 -316.132464)
		(end 61.073284 -316.21095)
		(width 0.14478)
		(layer "In13.Cu")
		(net "M_B_CPU1_SB_DQ<29>")
	)
	(segment
		(start 53.25999 -317.972948)
		(end 53.52161 -317.972948)
		(width 0.14478)
		(layer "In13.Cu")
		(net "M_B_CPU1_SB_DQ<29>")
	)
	(segment
		(start 52.97043 -317.610236)
		(end 53.11521 -317.755016)
		(width 0.14478)
		(layer "In13.Cu")
		(net "M_B_CPU1_SB_DQ<29>")
	)
	(segment
		(start 60.284868 -316.126622)
		(end 60.363354 -315.937646)
		(width 0.14478)
		(layer "In13.Cu")
		(net "M_B_CPU1_SB_DQ<29>")
	)
	(segment
		(start 53.11521 -317.755016)
		(end 53.11521 -317.828168)
		(width 0.14478)
		(layer "In13.Cu")
		(net "M_B_CPU1_SB_DQ<29>")
	)
	(segment
		(start 54.76875 -317.755016)
		(end 54.91353 -317.610236)
		(width 0.14478)
		(layer "In13.Cu")
		(net "M_B_CPU1_SB_DQ<29>")
	)
	(segment
		(start 57.695846 -317.610236)
		(end 58.146188 -317.423546)
		(width 0.14478)
		(layer "In13.Cu")
		(net "M_B_CPU1_SB_DQ<29>")
	)
	(segment
		(start 55.31993 -317.828168)
		(end 55.46471 -317.972948)
		(width 0.14478)
		(layer "In13.Cu")
		(net "M_B_CPU1_SB_DQ<29>")
	)
	(segment
		(start 55.17515 -317.610236)
		(end 55.31993 -317.755016)
		(width 0.14478)
		(layer "In13.Cu")
		(net "M_B_CPU1_SB_DQ<29>")
	)
	(segment
		(start 76.244196 -301.362872)
		(end 76.244196 -298.869354)
		(width 0.14478)
		(layer "In13.Cu")
		(net "M_B_CPU1_SB_DQ<29>")
	)
	(segment
		(start 53.66639 -317.755016)
		(end 53.81117 -317.610236)
		(width 0.14478)
		(layer "In13.Cu")
		(net "M_B_CPU1_SB_DQ<29>")
	)
	(segment
		(start 58.22442 -317.23457)
		(end 58.131964 -317.011304)
		(width 0.14478)
		(layer "In13.Cu")
		(net "M_B_CPU1_SB_DQ<29>")
	)
	(segment
		(start 54.21757 -317.755016)
		(end 54.21757 -317.828168)
		(width 0.14478)
		(layer "In13.Cu")
		(net "M_B_CPU1_SB_DQ<29>")
	)
	(segment
		(start 53.52161 -317.972948)
		(end 53.66639 -317.828168)
		(width 0.14478)
		(layer "In13.Cu")
		(net "M_B_CPU1_SB_DQ<29>")
	)
	(segment
		(start 80.73898 -293.87165)
		(end 80.778096 -293.84879)
		(width 0.0889)
		(layer "In13.Cu")
		(net "M_B_CPU1_SB_DQ<29>")
	)
	(segment
		(start 83.694016 -293.038784)
		(end 83.702398 -293.04361)
		(width 0.0889)
		(layer "In13.Cu")
		(net "M_B_CPU1_SB_DQ<29>")
	)
	(segment
		(start 56.42229 -317.828168)
		(end 56.56707 -317.972948)
		(width 0.14478)
		(layer "In13.Cu")
		(net "M_B_CPU1_SB_DQ<29>")
	)
	(segment
		(start 52.309014 -317.610236)
		(end 52.97043 -317.610236)
		(width 0.14478)
		(layer "In13.Cu")
		(net "M_B_CPU1_SB_DQ<29>")
	)
	(segment
		(start 78.818994 -296.407586)
		(end 79.040482 -296.407586)
		(width 0.0889)
		(layer "In13.Cu")
		(net "M_B_CPU1_SB_DQ<29>")
	)
	(segment
		(start 89.271094 -293.007034)
		(end 89.367106 -292.981634)
		(width 0.0889)
		(layer "In13.Cu")
		(net "M_B_CPU1_SB_DQ<29>")
	)
	(segment
		(start 60.296552 -316.532514)
		(end 60.374784 -316.343538)
		(width 0.14478)
		(layer "In13.Cu")
		(net "M_B_CPU1_SB_DQ<29>")
	)
	(segment
		(start 80.308196 -294.658796)
		(end 80.338676 -294.641016)
		(width 0.0889)
		(layer "In13.Cu")
		(net "M_B_CPU1_SB_DQ<29>")
	)
	(segment
		(start 56.01589 -317.610236)
		(end 56.27751 -317.610236)
		(width 0.14478)
		(layer "In13.Cu")
		(net "M_B_CPU1_SB_DQ<29>")
	)
	(segment
		(start 55.46471 -317.972948)
		(end 55.72633 -317.972948)
		(width 0.14478)
		(layer "In13.Cu")
		(net "M_B_CPU1_SB_DQ<29>")
	)
	(segment
		(start 55.87111 -317.828168)
		(end 55.87111 -317.755016)
		(width 0.14478)
		(layer "In13.Cu")
		(net "M_B_CPU1_SB_DQ<29>")
	)
	(segment
		(start 58.131964 -317.011304)
		(end 58.210196 -316.822328)
		(width 0.14478)
		(layer "In13.Cu")
		(net "M_B_CPU1_SB_DQ<29>")
	)
	(segment
		(start 85.948012 -293.038784)
		(end 85.948266 -293.038784)
		(width 0.0889)
		(layer "In13.Cu")
		(net "M_B_CPU1_SB_DQ<29>")
	)
	(segment
		(start 58.73369 -317.023496)
		(end 58.922666 -317.101728)
		(width 0.14478)
		(layer "In13.Cu")
		(net "M_B_CPU1_SB_DQ<29>")
	)
	(segment
		(start 56.97347 -317.755016)
		(end 57.11825 -317.610236)
		(width 0.14478)
		(layer "In13.Cu")
		(net "M_B_CPU1_SB_DQ<29>")
	)
	(segment
		(start 79.79918 -295.491662)
		(end 79.838296 -295.468802)
		(width 0.0889)
		(layer "In13.Cu")
		(net "M_B_CPU1_SB_DQ<29>")
	)
	(segment
		(start 55.31993 -317.755016)
		(end 55.31993 -317.828168)
		(width 0.14478)
		(layer "In13.Cu")
		(net "M_B_CPU1_SB_DQ<29>")
	)
	(segment
		(start 76.244196 -298.869354)
		(end 78.625954 -296.487596)
		(width 0.14478)
		(layer "In13.Cu")
		(net "M_B_CPU1_SB_DQ<29>")
	)
	(segment
		(start 54.07279 -317.610236)
		(end 54.21757 -317.755016)
		(width 0.14478)
		(layer "In13.Cu")
		(net "M_B_CPU1_SB_DQ<29>")
	)
	(segment
		(start 55.87111 -317.755016)
		(end 56.01589 -317.610236)
		(width 0.14478)
		(layer "In13.Cu")
		(net "M_B_CPU1_SB_DQ<29>")
	)
	(segment
		(start 53.11521 -317.828168)
		(end 53.25999 -317.972948)
		(width 0.14478)
		(layer "In13.Cu")
		(net "M_B_CPU1_SB_DQ<29>")
	)
	(segment
		(start 60.794138 -315.915548)
		(end 60.884054 -316.132464)
		(width 0.14478)
		(layer "In13.Cu")
		(net "M_B_CPU1_SB_DQ<29>")
	)
	(segment
		(start 58.146188 -317.423546)
		(end 58.22442 -317.23457)
		(width 0.14478)
		(layer "In13.Cu")
		(net "M_B_CPU1_SB_DQ<29>")
	)
	(segment
		(start 60.363354 -315.937646)
		(end 60.605416 -315.837316)
		(width 0.14478)
		(layer "In13.Cu")
		(net "M_B_CPU1_SB_DQ<29>")
	)
	(arc
		(start 85.007958 -293.038784)
		(mid 85.290914 -292.962607)
		(end 85.57387 -293.038784)
		(width 0.0889)
		(layer "In13.Cu")
		(net "M_B_CPU1_SB_DQ<29>")
	)
	(arc
		(start 80.965802 -293.52621)
		(mid 81.031038 -293.262619)
		(end 81.211674 -293.059866)
		(width 0.0889)
		(layer "In13.Cu")
		(net "M_B_CPU1_SB_DQ<29>")
	)
	(arc
		(start 83.702398 -293.04361)
		(mid 83.885906 -293.089104)
		(end 84.068158 -293.038784)
		(width 0.0889)
		(layer "In13.Cu")
		(net "M_B_CPU1_SB_DQ<29>")
	)
	(arc
		(start 87.46236 -293.04361)
		(mid 87.645868 -293.089104)
		(end 87.82812 -293.038784)
		(width 0.0889)
		(layer "In13.Cu")
		(net "M_B_CPU1_SB_DQ<29>")
	)
	(arc
		(start 82.762344 -293.04361)
		(mid 82.945852 -293.089104)
		(end 83.128104 -293.038784)
		(width 0.0889)
		(layer "In13.Cu")
		(net "M_B_CPU1_SB_DQ<29>")
	)
	(arc
		(start 81.813908 -293.038784)
		(mid 81.996159 -293.089134)
		(end 82.179668 -293.04361)
		(width 0.0889)
		(layer "In13.Cu")
		(net "M_B_CPU1_SB_DQ<29>")
	)
	(arc
		(start 80.026002 -295.146222)
		(mid 80.091238 -294.882631)
		(end 80.271874 -294.679878)
		(width 0.0889)
		(layer "In13.Cu")
		(net "M_B_CPU1_SB_DQ<29>")
	)
	(arc
		(start 79.040482 -296.407586)
		(mid 79.142947 -296.394018)
		(end 79.238348 -296.354246)
		(width 0.0889)
		(layer "In13.Cu")
		(net "M_B_CPU1_SB_DQ<29>")
	)
	(arc
		(start 81.247996 -293.038784)
		(mid 81.530952 -292.962607)
		(end 81.813908 -293.038784)
		(width 0.0889)
		(layer "In13.Cu")
		(net "M_B_CPU1_SB_DQ<29>")
	)
	(arc
		(start 83.128104 -293.038784)
		(mid 83.41106 -292.962607)
		(end 83.694016 -293.038784)
		(width 0.0889)
		(layer "In13.Cu")
		(net "M_B_CPU1_SB_DQ<29>")
	)
	(arc
		(start 84.068158 -293.038784)
		(mid 84.351114 -292.962607)
		(end 84.63407 -293.038784)
		(width 0.0889)
		(layer "In13.Cu")
		(net "M_B_CPU1_SB_DQ<29>")
	)
	(arc
		(start 82.18805 -293.038784)
		(mid 82.471006 -292.962607)
		(end 82.753962 -293.038784)
		(width 0.0889)
		(layer "In13.Cu")
		(net "M_B_CPU1_SB_DQ<29>")
	)
	(arc
		(start 87.82812 -293.038784)
		(mid 88.111076 -292.962607)
		(end 88.394032 -293.038784)
		(width 0.0889)
		(layer "In13.Cu")
		(net "M_B_CPU1_SB_DQ<29>")
	)
	(arc
		(start 80.338676 -294.641016)
		(mid 80.454103 -294.50764)
		(end 80.495648 -294.336216)
		(width 0.0889)
		(layer "In13.Cu")
		(net "M_B_CPU1_SB_DQ<29>")
	)
	(arc
		(start 78.625954 -296.487596)
		(mid 78.714522 -296.428417)
		(end 78.818994 -296.407586)
		(width 0.0889)
		(layer "In13.Cu")
		(net "M_B_CPU1_SB_DQ<29>")
	)
	(arc
		(start 88.768174 -293.038784)
		(mid 89.015887 -292.963564)
		(end 89.271094 -293.007034)
		(width 0.0889)
		(layer "In13.Cu")
		(net "M_B_CPU1_SB_DQ<29>")
	)
	(arc
		(start 85.948266 -293.038784)
		(mid 86.231112 -292.962607)
		(end 86.513924 -293.038784)
		(width 0.0889)
		(layer "In13.Cu")
		(net "M_B_CPU1_SB_DQ<29>")
	)
	(arc
		(start 84.63407 -293.038784)
		(mid 84.821014 -293.089039)
		(end 85.007958 -293.038784)
		(width 0.0889)
		(layer "In13.Cu")
		(net "M_B_CPU1_SB_DQ<29>")
	)
	(arc
		(start 79.555848 -295.956228)
		(mid 79.620363 -295.694009)
		(end 79.79918 -295.491662)
		(width 0.0889)
		(layer "In13.Cu")
		(net "M_B_CPU1_SB_DQ<29>")
	)
	(arc
		(start 86.888066 -293.038784)
		(mid 87.171022 -292.962607)
		(end 87.453978 -293.038784)
		(width 0.0889)
		(layer "In13.Cu")
		(net "M_B_CPU1_SB_DQ<29>")
	)
	(arc
		(start 88.402414 -293.04361)
		(mid 88.585922 -293.089104)
		(end 88.768174 -293.038784)
		(width 0.0889)
		(layer "In13.Cu")
		(net "M_B_CPU1_SB_DQ<29>")
	)
	(arc
		(start 80.809846 -293.830502)
		(mid 80.924522 -293.697168)
		(end 80.965802 -293.52621)
		(width 0.0889)
		(layer "In13.Cu")
		(net "M_B_CPU1_SB_DQ<29>")
	)
	(arc
		(start 80.495648 -294.336216)
		(mid 80.560163 -294.073997)
		(end 80.73898 -293.87165)
		(width 0.0889)
		(layer "In13.Cu")
		(net "M_B_CPU1_SB_DQ<29>")
	)
	(arc
		(start 85.57387 -293.038784)
		(mid 85.756121 -293.089134)
		(end 85.93963 -293.04361)
		(width 0.0889)
		(layer "In13.Cu")
		(net "M_B_CPU1_SB_DQ<29>")
	)
	(arc
		(start 86.513924 -293.038784)
		(mid 86.696175 -293.089134)
		(end 86.879684 -293.04361)
		(width 0.0889)
		(layer "In13.Cu")
		(net "M_B_CPU1_SB_DQ<29>")
	)
	(arc
		(start 79.870046 -295.450514)
		(mid 79.984722 -295.31718)
		(end 80.026002 -295.146222)
		(width 0.0889)
		(layer "In13.Cu")
		(net "M_B_CPU1_SB_DQ<29>")
	)
	(arc
		(start 79.400908 -296.259758)
		(mid 79.514837 -296.126611)
		(end 79.555848 -295.956228)
		(width 0.0889)
		(layer "In13.Cu")
		(net "M_B_CPU1_SB_DQ<29>")
	)
	(segment
		(start 88.577928 -291.64026)
		(end 88.111076 -291.906198)
		(width 0.10668)
		(layer "F.Cu")
		(net "M_B_CPU1_SB_DQ<28>")
	)
	(segment
		(start 73.219818 -301.879254)
		(end 73.615804 -302.27524)
		(width 0.14478)
		(layer "In13.Cu")
		(net "M_B_CPU1_SB_DQ<28>")
	)
	(segment
		(start 73.794874 -301.099474)
		(end 73.999598 -301.099474)
		(width 0.14478)
		(layer "In13.Cu")
		(net "M_B_CPU1_SB_DQ<28>")
	)
	(segment
		(start 78.897988 -293.84879)
		(end 78.929738 -293.830502)
		(width 0.0889)
		(layer "In13.Cu")
		(net "M_B_CPU1_SB_DQ<28>")
	)
	(segment
		(start 53.859176 -316.100968)
		(end 54.003956 -316.245748)
		(width 0.14478)
		(layer "In13.Cu")
		(net "M_B_CPU1_SB_DQ<28>")
	)
	(segment
		(start 74.005694 -301.88535)
		(end 73.609708 -301.489364)
		(width 0.14478)
		(layer "In13.Cu")
		(net "M_B_CPU1_SB_DQ<28>")
	)
	(segment
		(start 87.956898 -292.171628)
		(end 88.111076 -291.906198)
		(width 0.0889)
		(layer "In13.Cu")
		(net "M_B_CPU1_SB_DQ<28>")
	)
	(segment
		(start 72.235314 -302.659034)
		(end 72.440038 -302.659034)
		(width 0.14478)
		(layer "In13.Cu")
		(net "M_B_CPU1_SB_DQ<28>")
	)
	(segment
		(start 51.884072 -315.485272)
		(end 52.314348 -315.915548)
		(width 0.14478)
		(layer "In13.Cu")
		(net "M_B_CPU1_SB_DQ<28>")
	)
	(segment
		(start 74.600308 -301.49546)
		(end 75.274424 -300.821344)
		(width 0.14478)
		(layer "In13.Cu")
		(net "M_B_CPU1_SB_DQ<28>")
	)
	(segment
		(start 55.367936 -316.245748)
		(end 55.512716 -316.100968)
		(width 0.14478)
		(layer "In13.Cu")
		(net "M_B_CPU1_SB_DQ<28>")
	)
	(segment
		(start 72.836024 -303.05502)
		(end 73.040748 -303.05502)
		(width 0.14478)
		(layer "In13.Cu")
		(net "M_B_CPU1_SB_DQ<28>")
	)
	(segment
		(start 84.529676 -292.233604)
		(end 84.538058 -292.228778)
		(width 0.0889)
		(layer "In13.Cu")
		(net "M_B_CPU1_SB_DQ<28>")
	)
	(segment
		(start 72.050148 -303.048924)
		(end 72.050148 -302.8442)
		(width 0.14478)
		(layer "In13.Cu")
		(net "M_B_CPU1_SB_DQ<28>")
	)
	(segment
		(start 72.829928 -302.06442)
		(end 73.015094 -301.879254)
		(width 0.14478)
		(layer "In13.Cu")
		(net "M_B_CPU1_SB_DQ<28>")
	)
	(segment
		(start 77.700886 -296.041064)
		(end 77.84211 -295.89984)
		(width 0.0889)
		(layer "In13.Cu")
		(net "M_B_CPU1_SB_DQ<28>")
	)
	(segment
		(start 86.044024 -292.228778)
		(end 86.052406 -292.233604)
		(width 0.0889)
		(layer "In13.Cu")
		(net "M_B_CPU1_SB_DQ<28>")
	)
	(segment
		(start 85.10397 -292.228778)
		(end 85.112352 -292.233604)
		(width 0.0889)
		(layer "In13.Cu")
		(net "M_B_CPU1_SB_DQ<28>")
	)
	(segment
		(start 53.859176 -316.060328)
		(end 53.859176 -316.100968)
		(width 0.14478)
		(layer "In13.Cu")
		(net "M_B_CPU1_SB_DQ<28>")
	)
	(segment
		(start 54.003956 -316.245748)
		(end 54.265576 -316.245748)
		(width 0.14478)
		(layer "In13.Cu")
		(net "M_B_CPU1_SB_DQ<28>")
	)
	(segment
		(start 73.820528 -302.27524)
		(end 74.005694 -302.090074)
		(width 0.14478)
		(layer "In13.Cu")
		(net "M_B_CPU1_SB_DQ<28>")
	)
	(segment
		(start 79.368142 -293.038784)
		(end 79.398622 -293.021004)
		(width 0.0889)
		(layer "In13.Cu")
		(net "M_B_CPU1_SB_DQ<28>")
	)
	(segment
		(start 55.657496 -315.915548)
		(end 57.570878 -315.915548)
		(width 0.14478)
		(layer "In13.Cu")
		(net "M_B_CPU1_SB_DQ<28>")
	)
	(segment
		(start 57.570878 -315.915548)
		(end 62.025276 -314.070492)
		(width 0.14478)
		(layer "In13.Cu")
		(net "M_B_CPU1_SB_DQ<28>")
	)
	(segment
		(start 83.589622 -292.233604)
		(end 83.598004 -292.228778)
		(width 0.0889)
		(layer "In13.Cu")
		(net "M_B_CPU1_SB_DQ<28>")
	)
	(segment
		(start 55.106316 -316.245748)
		(end 55.367936 -316.245748)
		(width 0.14478)
		(layer "In13.Cu")
		(net "M_B_CPU1_SB_DQ<28>")
	)
	(segment
		(start 72.050148 -302.8442)
		(end 72.235314 -302.659034)
		(width 0.14478)
		(layer "In13.Cu")
		(net "M_B_CPU1_SB_DQ<28>")
	)
	(segment
		(start 72.446134 -303.649634)
		(end 72.446134 -303.44491)
		(width 0.14478)
		(layer "In13.Cu")
		(net "M_B_CPU1_SB_DQ<28>")
	)
	(segment
		(start 53.714396 -315.915548)
		(end 53.859176 -316.060328)
		(width 0.14478)
		(layer "In13.Cu")
		(net "M_B_CPU1_SB_DQ<28>")
	)
	(segment
		(start 78.417166 -294.664892)
		(end 78.458568 -294.641016)
		(width 0.0889)
		(layer "In13.Cu")
		(net "M_B_CPU1_SB_DQ<28>")
	)
	(segment
		(start 75.274424 -300.821344)
		(end 75.274424 -298.467526)
		(width 0.14478)
		(layer "In13.Cu")
		(net "M_B_CPU1_SB_DQ<28>")
	)
	(segment
		(start 75.274424 -298.467526)
		(end 77.700886 -296.041064)
		(width 0.14478)
		(layer "In13.Cu")
		(net "M_B_CPU1_SB_DQ<28>")
	)
	(segment
		(start 79.329026 -293.061644)
		(end 79.368142 -293.038784)
		(width 0.0889)
		(layer "In13.Cu")
		(net "M_B_CPU1_SB_DQ<28>")
	)
	(segment
		(start 72.829928 -302.269144)
		(end 72.829928 -302.06442)
		(width 0.14478)
		(layer "In13.Cu")
		(net "M_B_CPU1_SB_DQ<28>")
	)
	(segment
		(start 73.615804 -302.27524)
		(end 73.820528 -302.27524)
		(width 0.14478)
		(layer "In13.Cu")
		(net "M_B_CPU1_SB_DQ<28>")
	)
	(segment
		(start 54.410356 -316.060328)
		(end 54.555136 -315.915548)
		(width 0.14478)
		(layer "In13.Cu")
		(net "M_B_CPU1_SB_DQ<28>")
	)
	(segment
		(start 74.005694 -302.090074)
		(end 74.005694 -301.88535)
		(width 0.14478)
		(layer "In13.Cu")
		(net "M_B_CPU1_SB_DQ<28>")
	)
	(segment
		(start 55.512716 -316.060328)
		(end 55.657496 -315.915548)
		(width 0.14478)
		(layer "In13.Cu")
		(net "M_B_CPU1_SB_DQ<28>")
	)
	(segment
		(start 73.225914 -302.869854)
		(end 73.225914 -302.66513)
		(width 0.14478)
		(layer "In13.Cu")
		(net "M_B_CPU1_SB_DQ<28>")
	)
	(segment
		(start 87.860632 -292.197028)
		(end 87.956898 -292.171628)
		(width 0.0889)
		(layer "In13.Cu")
		(net "M_B_CPU1_SB_DQ<28>")
	)
	(segment
		(start 73.999598 -301.099474)
		(end 74.395584 -301.49546)
		(width 0.14478)
		(layer "In13.Cu")
		(net "M_B_CPU1_SB_DQ<28>")
	)
	(segment
		(start 52.314348 -315.915548)
		(end 53.714396 -315.915548)
		(width 0.14478)
		(layer "In13.Cu")
		(net "M_B_CPU1_SB_DQ<28>")
	)
	(segment
		(start 54.265576 -316.245748)
		(end 54.410356 -316.100968)
		(width 0.14478)
		(layer "In13.Cu")
		(net "M_B_CPU1_SB_DQ<28>")
	)
	(segment
		(start 54.961536 -316.060328)
		(end 54.961536 -316.100968)
		(width 0.14478)
		(layer "In13.Cu")
		(net "M_B_CPU1_SB_DQ<28>")
	)
	(segment
		(start 73.015094 -301.879254)
		(end 73.219818 -301.879254)
		(width 0.14478)
		(layer "In13.Cu")
		(net "M_B_CPU1_SB_DQ<28>")
	)
	(segment
		(start 79.798926 -292.251638)
		(end 79.838042 -292.228778)
		(width 0.0889)
		(layer "In13.Cu")
		(net "M_B_CPU1_SB_DQ<28>")
	)
	(segment
		(start 73.040748 -303.05502)
		(end 73.225914 -302.869854)
		(width 0.14478)
		(layer "In13.Cu")
		(net "M_B_CPU1_SB_DQ<28>")
	)
	(segment
		(start 73.609708 -301.28464)
		(end 73.794874 -301.099474)
		(width 0.14478)
		(layer "In13.Cu")
		(net "M_B_CPU1_SB_DQ<28>")
	)
	(segment
		(start 72.440038 -302.659034)
		(end 72.836024 -303.05502)
		(width 0.14478)
		(layer "In13.Cu")
		(net "M_B_CPU1_SB_DQ<28>")
	)
	(segment
		(start 54.555136 -315.915548)
		(end 54.816756 -315.915548)
		(width 0.14478)
		(layer "In13.Cu")
		(net "M_B_CPU1_SB_DQ<28>")
	)
	(segment
		(start 55.512716 -316.100968)
		(end 55.512716 -316.060328)
		(width 0.14478)
		(layer "In13.Cu")
		(net "M_B_CPU1_SB_DQ<28>")
	)
	(segment
		(start 62.025276 -314.070492)
		(end 72.446134 -303.649634)
		(width 0.14478)
		(layer "In13.Cu")
		(net "M_B_CPU1_SB_DQ<28>")
	)
	(segment
		(start 54.816756 -315.915548)
		(end 54.961536 -316.060328)
		(width 0.14478)
		(layer "In13.Cu")
		(net "M_B_CPU1_SB_DQ<28>")
	)
	(segment
		(start 73.609708 -301.489364)
		(end 73.609708 -301.28464)
		(width 0.14478)
		(layer "In13.Cu")
		(net "M_B_CPU1_SB_DQ<28>")
	)
	(segment
		(start 74.395584 -301.49546)
		(end 74.600308 -301.49546)
		(width 0.14478)
		(layer "In13.Cu")
		(net "M_B_CPU1_SB_DQ<28>")
	)
	(segment
		(start 80.777842 -292.228778)
		(end 80.778096 -292.228778)
		(width 0.0889)
		(layer "In13.Cu")
		(net "M_B_CPU1_SB_DQ<28>")
	)
	(segment
		(start 72.446134 -303.44491)
		(end 72.050148 -303.048924)
		(width 0.14478)
		(layer "In13.Cu")
		(net "M_B_CPU1_SB_DQ<28>")
	)
	(segment
		(start 78.860142 -293.870634)
		(end 78.897988 -293.84879)
		(width 0.0889)
		(layer "In13.Cu")
		(net "M_B_CPU1_SB_DQ<28>")
	)
	(segment
		(start 73.225914 -302.66513)
		(end 72.829928 -302.269144)
		(width 0.14478)
		(layer "In13.Cu")
		(net "M_B_CPU1_SB_DQ<28>")
	)
	(segment
		(start 54.410356 -316.100968)
		(end 54.410356 -316.060328)
		(width 0.14478)
		(layer "In13.Cu")
		(net "M_B_CPU1_SB_DQ<28>")
	)
	(segment
		(start 81.344008 -292.228778)
		(end 81.35239 -292.233604)
		(width 0.0889)
		(layer "In13.Cu")
		(net "M_B_CPU1_SB_DQ<28>")
	)
	(segment
		(start 78.139544 -295.181782)
		(end 78.139544 -295.146222)
		(width 0.0889)
		(layer "In13.Cu")
		(net "M_B_CPU1_SB_DQ<28>")
	)
	(segment
		(start 54.961536 -316.100968)
		(end 55.106316 -316.245748)
		(width 0.14478)
		(layer "In13.Cu")
		(net "M_B_CPU1_SB_DQ<28>")
	)
	(arc
		(start 84.163916 -292.228778)
		(mid 84.346167 -292.279128)
		(end 84.529676 -292.233604)
		(width 0.0889)
		(layer "In13.Cu")
		(net "M_B_CPU1_SB_DQ<28>")
	)
	(arc
		(start 79.085694 -293.52621)
		(mid 79.150209 -293.263991)
		(end 79.329026 -293.061644)
		(width 0.0889)
		(layer "In13.Cu")
		(net "M_B_CPU1_SB_DQ<28>")
	)
	(arc
		(start 78.929738 -293.830502)
		(mid 79.044414 -293.697168)
		(end 79.085694 -293.52621)
		(width 0.0889)
		(layer "In13.Cu")
		(net "M_B_CPU1_SB_DQ<28>")
	)
	(arc
		(start 79.398622 -293.021004)
		(mid 79.514049 -292.887628)
		(end 79.555594 -292.716204)
		(width 0.0889)
		(layer "In13.Cu")
		(net "M_B_CPU1_SB_DQ<28>")
	)
	(arc
		(start 81.71815 -292.228778)
		(mid 82.001106 -292.152601)
		(end 82.284062 -292.228778)
		(width 0.0889)
		(layer "In13.Cu")
		(net "M_B_CPU1_SB_DQ<28>")
	)
	(arc
		(start 83.223862 -292.228778)
		(mid 83.406113 -292.279128)
		(end 83.589622 -292.233604)
		(width 0.0889)
		(layer "In13.Cu")
		(net "M_B_CPU1_SB_DQ<28>")
	)
	(arc
		(start 78.61554 -294.336216)
		(mid 78.680412 -294.073253)
		(end 78.860142 -293.870634)
		(width 0.0889)
		(layer "In13.Cu")
		(net "M_B_CPU1_SB_DQ<28>")
	)
	(arc
		(start 79.838042 -292.228778)
		(mid 80.120998 -292.152601)
		(end 80.403954 -292.228778)
		(width 0.0889)
		(layer "In13.Cu")
		(net "M_B_CPU1_SB_DQ<28>")
	)
	(arc
		(start 79.555594 -292.716204)
		(mid 79.620109 -292.453985)
		(end 79.798926 -292.251638)
		(width 0.0889)
		(layer "In13.Cu")
		(net "M_B_CPU1_SB_DQ<28>")
	)
	(arc
		(start 78.458568 -294.641016)
		(mid 78.573995 -294.50764)
		(end 78.61554 -294.336216)
		(width 0.0889)
		(layer "In13.Cu")
		(net "M_B_CPU1_SB_DQ<28>")
	)
	(arc
		(start 77.84211 -295.89984)
		(mid 78.06224 -295.570392)
		(end 78.139544 -295.181782)
		(width 0.0889)
		(layer "In13.Cu")
		(net "M_B_CPU1_SB_DQ<28>")
	)
	(arc
		(start 85.478112 -292.228778)
		(mid 85.761068 -292.152601)
		(end 86.044024 -292.228778)
		(width 0.0889)
		(layer "In13.Cu")
		(net "M_B_CPU1_SB_DQ<28>")
	)
	(arc
		(start 80.403954 -292.228778)
		(mid 80.590898 -292.279102)
		(end 80.777842 -292.228778)
		(width 0.0889)
		(layer "In13.Cu")
		(net "M_B_CPU1_SB_DQ<28>")
	)
	(arc
		(start 82.284062 -292.228778)
		(mid 82.471006 -292.279033)
		(end 82.65795 -292.228778)
		(width 0.0889)
		(layer "In13.Cu")
		(net "M_B_CPU1_SB_DQ<28>")
	)
	(arc
		(start 85.112352 -292.233604)
		(mid 85.29586 -292.279098)
		(end 85.478112 -292.228778)
		(width 0.0889)
		(layer "In13.Cu")
		(net "M_B_CPU1_SB_DQ<28>")
	)
	(arc
		(start 86.052406 -292.233604)
		(mid 86.235914 -292.279098)
		(end 86.418166 -292.228778)
		(width 0.0889)
		(layer "In13.Cu")
		(net "M_B_CPU1_SB_DQ<28>")
	)
	(arc
		(start 86.984078 -292.228778)
		(mid 87.171022 -292.279033)
		(end 87.357966 -292.228778)
		(width 0.0889)
		(layer "In13.Cu")
		(net "M_B_CPU1_SB_DQ<28>")
	)
	(arc
		(start 84.538058 -292.228778)
		(mid 84.821014 -292.152601)
		(end 85.10397 -292.228778)
		(width 0.0889)
		(layer "In13.Cu")
		(net "M_B_CPU1_SB_DQ<28>")
	)
	(arc
		(start 87.357966 -292.228778)
		(mid 87.605562 -292.1536)
		(end 87.860632 -292.197028)
		(width 0.0889)
		(layer "In13.Cu")
		(net "M_B_CPU1_SB_DQ<28>")
	)
	(arc
		(start 82.65795 -292.228778)
		(mid 82.940906 -292.152601)
		(end 83.223862 -292.228778)
		(width 0.0889)
		(layer "In13.Cu")
		(net "M_B_CPU1_SB_DQ<28>")
	)
	(arc
		(start 80.778096 -292.228778)
		(mid 81.061052 -292.152601)
		(end 81.344008 -292.228778)
		(width 0.0889)
		(layer "In13.Cu")
		(net "M_B_CPU1_SB_DQ<28>")
	)
	(arc
		(start 86.418166 -292.228778)
		(mid 86.701122 -292.152601)
		(end 86.984078 -292.228778)
		(width 0.0889)
		(layer "In13.Cu")
		(net "M_B_CPU1_SB_DQ<28>")
	)
	(arc
		(start 78.139544 -295.146222)
		(mid 78.213929 -294.868402)
		(end 78.417166 -294.664892)
		(width 0.0889)
		(layer "In13.Cu")
		(net "M_B_CPU1_SB_DQ<28>")
	)
	(arc
		(start 81.35239 -292.233604)
		(mid 81.535898 -292.279098)
		(end 81.71815 -292.228778)
		(width 0.0889)
		(layer "In13.Cu")
		(net "M_B_CPU1_SB_DQ<28>")
	)
	(arc
		(start 83.598004 -292.228778)
		(mid 83.88096 -292.152601)
		(end 84.163916 -292.228778)
		(width 0.0889)
		(layer "In13.Cu")
		(net "M_B_CPU1_SB_DQ<28>")
	)
	(segment
		(start 89.517982 -290.020248)
		(end 89.05113 -290.286186)
		(width 0.10668)
		(layer "F.Cu")
		(net "M_B_CPU1_SB_DQ<27>")
	)
	(segment
		(start 76.72705 -292.267132)
		(end 76.72705 -293.100506)
		(width 0.0889)
		(layer "In13.Cu")
		(net "M_B_CPU1_SB_DQ<27>")
	)
	(segment
		(start 78.897734 -289.96386)
		(end 78.879446 -289.953446)
		(width 0.0889)
		(layer "In13.Cu")
		(net "M_B_CPU1_SB_DQ<27>")
	)
	(segment
		(start 86.052406 -289.95878)
		(end 86.044024 -289.963606)
		(width 0.0889)
		(layer "In13.Cu")
		(net "M_B_CPU1_SB_DQ<27>")
	)
	(segment
		(start 83.598004 -289.963606)
		(end 83.589622 -289.95878)
		(width 0.0889)
		(layer "In13.Cu")
		(net "M_B_CPU1_SB_DQ<27>")
	)
	(segment
		(start 59.954922 -311.660286)
		(end 57.389776 -311.660286)
		(width 0.14478)
		(layer "In13.Cu")
		(net "M_B_CPU1_SB_DQ<27>")
	)
	(segment
		(start 78.30439 -290.182808)
		(end 78.30439 -291.004752)
		(width 0.0889)
		(layer "In13.Cu")
		(net "M_B_CPU1_SB_DQ<27>")
	)
	(segment
		(start 78.523592 -289.963606)
		(end 78.30439 -290.182808)
		(width 0.0889)
		(layer "In13.Cu")
		(net "M_B_CPU1_SB_DQ<27>")
	)
	(segment
		(start 75.960986 -294.443404)
		(end 72.861678 -297.542712)
		(width 0.14478)
		(layer "In13.Cu")
		(net "M_B_CPU1_SB_DQ<27>")
	)
	(segment
		(start 72.861678 -298.75353)
		(end 59.954922 -311.660286)
		(width 0.14478)
		(layer "In13.Cu")
		(net "M_B_CPU1_SB_DQ<27>")
	)
	(segment
		(start 57.389776 -311.660286)
		(end 56.935116 -312.114946)
		(width 0.14478)
		(layer "In13.Cu")
		(net "M_B_CPU1_SB_DQ<27>")
	)
	(segment
		(start 49.881028 -311.650634)
		(end 49.446434 -312.085228)
		(width 0.14478)
		(layer "In13.Cu")
		(net "M_B_CPU1_SB_DQ<27>")
	)
	(segment
		(start 88.29802 -289.963606)
		(end 88.289638 -289.95878)
		(width 0.0889)
		(layer "In13.Cu")
		(net "M_B_CPU1_SB_DQ<27>")
	)
	(segment
		(start 79.474822 -289.956748)
		(end 79.463138 -289.963606)
		(width 0.0889)
		(layer "In13.Cu")
		(net "M_B_CPU1_SB_DQ<27>")
	)
	(segment
		(start 89.205054 -290.020756)
		(end 89.182702 -289.937444)
		(width 0.0889)
		(layer "In13.Cu")
		(net "M_B_CPU1_SB_DQ<27>")
	)
	(segment
		(start 50.852832 -311.650634)
		(end 49.881028 -311.650634)
		(width 0.14478)
		(layer "In13.Cu")
		(net "M_B_CPU1_SB_DQ<27>")
	)
	(segment
		(start 77.283056 -292.026086)
		(end 76.968096 -292.026086)
		(width 0.0889)
		(layer "In13.Cu")
		(net "M_B_CPU1_SB_DQ<27>")
	)
	(segment
		(start 76.968096 -292.026086)
		(end 76.72705 -292.267132)
		(width 0.0889)
		(layer "In13.Cu")
		(net "M_B_CPU1_SB_DQ<27>")
	)
	(segment
		(start 76.16825 -294.23614)
		(end 75.960986 -294.443404)
		(width 0.0889)
		(layer "In13.Cu")
		(net "M_B_CPU1_SB_DQ<27>")
	)
	(segment
		(start 84.538058 -289.963606)
		(end 84.529676 -289.95878)
		(width 0.0889)
		(layer "In13.Cu")
		(net "M_B_CPU1_SB_DQ<27>")
	)
	(segment
		(start 89.05113 -290.286186)
		(end 89.205054 -290.020756)
		(width 0.0889)
		(layer "In13.Cu")
		(net "M_B_CPU1_SB_DQ<27>")
	)
	(segment
		(start 76.16825 -293.659306)
		(end 76.16825 -294.23614)
		(width 0.0889)
		(layer "In13.Cu")
		(net "M_B_CPU1_SB_DQ<27>")
	)
	(segment
		(start 76.72705 -293.100506)
		(end 76.16825 -293.659306)
		(width 0.0889)
		(layer "In13.Cu")
		(net "M_B_CPU1_SB_DQ<27>")
	)
	(segment
		(start 85.112352 -289.95878)
		(end 85.10397 -289.963606)
		(width 0.0889)
		(layer "In13.Cu")
		(net "M_B_CPU1_SB_DQ<27>")
	)
	(segment
		(start 51.317144 -312.114946)
		(end 50.852832 -311.650634)
		(width 0.14478)
		(layer "In13.Cu")
		(net "M_B_CPU1_SB_DQ<27>")
	)
	(segment
		(start 80.403954 -289.963606)
		(end 80.389222 -289.972242)
		(width 0.0889)
		(layer "In13.Cu")
		(net "M_B_CPU1_SB_DQ<27>")
	)
	(segment
		(start 72.861678 -297.542712)
		(end 72.861678 -298.75353)
		(width 0.14478)
		(layer "In13.Cu")
		(net "M_B_CPU1_SB_DQ<27>")
	)
	(segment
		(start 80.778096 -289.963606)
		(end 80.769714 -289.95878)
		(width 0.0889)
		(layer "In13.Cu")
		(net "M_B_CPU1_SB_DQ<27>")
	)
	(segment
		(start 49.446434 -312.085228)
		(end 47.784004 -312.085228)
		(width 0.14478)
		(layer "In13.Cu")
		(net "M_B_CPU1_SB_DQ<27>")
	)
	(segment
		(start 78.30439 -291.004752)
		(end 77.283056 -292.026086)
		(width 0.0889)
		(layer "In13.Cu")
		(net "M_B_CPU1_SB_DQ<27>")
	)
	(segment
		(start 81.35239 -289.95878)
		(end 81.344008 -289.963606)
		(width 0.0889)
		(layer "In13.Cu")
		(net "M_B_CPU1_SB_DQ<27>")
	)
	(segment
		(start 56.935116 -312.114946)
		(end 51.317144 -312.114946)
		(width 0.14478)
		(layer "In13.Cu")
		(net "M_B_CPU1_SB_DQ<27>")
	)
	(segment
		(start 78.903322 -289.967162)
		(end 78.897734 -289.96386)
		(width 0.0889)
		(layer "In13.Cu")
		(net "M_B_CPU1_SB_DQ<27>")
	)
	(arc
		(start 86.044024 -289.963606)
		(mid 85.761068 -290.039783)
		(end 85.478112 -289.963606)
		(width 0.0889)
		(layer "In13.Cu")
		(net "M_B_CPU1_SB_DQ<27>")
	)
	(arc
		(start 79.463138 -289.963606)
		(mid 79.18371 -290.039772)
		(end 78.903322 -289.967162)
		(width 0.0889)
		(layer "In13.Cu")
		(net "M_B_CPU1_SB_DQ<27>")
	)
	(arc
		(start 88.289638 -289.95878)
		(mid 88.10613 -289.913286)
		(end 87.923878 -289.963606)
		(width 0.0889)
		(layer "In13.Cu")
		(net "M_B_CPU1_SB_DQ<27>")
	)
	(arc
		(start 82.65795 -289.963606)
		(mid 82.471006 -289.913351)
		(end 82.284062 -289.963606)
		(width 0.0889)
		(layer "In13.Cu")
		(net "M_B_CPU1_SB_DQ<27>")
	)
	(arc
		(start 82.284062 -289.963606)
		(mid 82.001106 -290.039783)
		(end 81.71815 -289.963606)
		(width 0.0889)
		(layer "In13.Cu")
		(net "M_B_CPU1_SB_DQ<27>")
	)
	(arc
		(start 85.10397 -289.963606)
		(mid 84.821014 -290.039783)
		(end 84.538058 -289.963606)
		(width 0.0889)
		(layer "In13.Cu")
		(net "M_B_CPU1_SB_DQ<27>")
	)
	(arc
		(start 88.863932 -289.963606)
		(mid 88.580976 -290.039783)
		(end 88.29802 -289.963606)
		(width 0.0889)
		(layer "In13.Cu")
		(net "M_B_CPU1_SB_DQ<27>")
	)
	(arc
		(start 84.529676 -289.95878)
		(mid 84.346168 -289.913286)
		(end 84.163916 -289.963606)
		(width 0.0889)
		(layer "In13.Cu")
		(net "M_B_CPU1_SB_DQ<27>")
	)
	(arc
		(start 80.769714 -289.95878)
		(mid 80.586206 -289.913286)
		(end 80.403954 -289.963606)
		(width 0.0889)
		(layer "In13.Cu")
		(net "M_B_CPU1_SB_DQ<27>")
	)
	(arc
		(start 85.478112 -289.963606)
		(mid 85.295861 -289.913256)
		(end 85.112352 -289.95878)
		(width 0.0889)
		(layer "In13.Cu")
		(net "M_B_CPU1_SB_DQ<27>")
	)
	(arc
		(start 81.71815 -289.963606)
		(mid 81.535899 -289.913256)
		(end 81.35239 -289.95878)
		(width 0.0889)
		(layer "In13.Cu")
		(net "M_B_CPU1_SB_DQ<27>")
	)
	(arc
		(start 86.418166 -289.963606)
		(mid 86.235915 -289.913256)
		(end 86.052406 -289.95878)
		(width 0.0889)
		(layer "In13.Cu")
		(net "M_B_CPU1_SB_DQ<27>")
	)
	(arc
		(start 87.923878 -289.963606)
		(mid 87.640922 -290.039783)
		(end 87.357966 -289.963606)
		(width 0.0889)
		(layer "In13.Cu")
		(net "M_B_CPU1_SB_DQ<27>")
	)
	(arc
		(start 89.182702 -289.937444)
		(mid 89.02037 -289.914626)
		(end 88.863932 -289.963606)
		(width 0.0889)
		(layer "In13.Cu")
		(net "M_B_CPU1_SB_DQ<27>")
	)
	(arc
		(start 78.879446 -289.953446)
		(mid 78.700217 -289.913293)
		(end 78.523592 -289.963606)
		(width 0.0889)
		(layer "In13.Cu")
		(net "M_B_CPU1_SB_DQ<27>")
	)
	(arc
		(start 79.837534 -289.963606)
		(mid 79.657076 -289.913162)
		(end 79.474822 -289.956748)
		(width 0.0889)
		(layer "In13.Cu")
		(net "M_B_CPU1_SB_DQ<27>")
	)
	(arc
		(start 87.357966 -289.963606)
		(mid 87.171022 -289.913351)
		(end 86.984078 -289.963606)
		(width 0.0889)
		(layer "In13.Cu")
		(net "M_B_CPU1_SB_DQ<27>")
	)
	(arc
		(start 80.389222 -289.972242)
		(mid 80.112239 -290.040046)
		(end 79.837534 -289.963606)
		(width 0.0889)
		(layer "In13.Cu")
		(net "M_B_CPU1_SB_DQ<27>")
	)
	(arc
		(start 86.984078 -289.963606)
		(mid 86.701122 -290.039783)
		(end 86.418166 -289.963606)
		(width 0.0889)
		(layer "In13.Cu")
		(net "M_B_CPU1_SB_DQ<27>")
	)
	(arc
		(start 83.223862 -289.963606)
		(mid 82.940906 -290.039783)
		(end 82.65795 -289.963606)
		(width 0.0889)
		(layer "In13.Cu")
		(net "M_B_CPU1_SB_DQ<27>")
	)
	(arc
		(start 84.163916 -289.963606)
		(mid 83.88096 -290.039783)
		(end 83.598004 -289.963606)
		(width 0.0889)
		(layer "In13.Cu")
		(net "M_B_CPU1_SB_DQ<27>")
	)
	(arc
		(start 83.589622 -289.95878)
		(mid 83.406114 -289.913286)
		(end 83.223862 -289.963606)
		(width 0.0889)
		(layer "In13.Cu")
		(net "M_B_CPU1_SB_DQ<27>")
	)
	(arc
		(start 81.344008 -289.963606)
		(mid 81.061052 -290.039783)
		(end 80.778096 -289.963606)
		(width 0.0889)
		(layer "In13.Cu")
		(net "M_B_CPU1_SB_DQ<27>")
	)
	(segment
		(start 88.107774 -289.210242)
		(end 87.640922 -289.47618)
		(width 0.10668)
		(layer "F.Cu")
		(net "M_B_CPU1_SB_DQ<26>")
	)
	(segment
		(start 78.993492 -289.153854)
		(end 79.01178 -289.14344)
		(width 0.0889)
		(layer "In13.Cu")
		(net "M_B_CPU1_SB_DQ<26>")
	)
	(segment
		(start 87.453978 -289.1536)
		(end 87.46236 -289.148774)
		(width 0.0889)
		(layer "In13.Cu")
		(net "M_B_CPU1_SB_DQ<26>")
	)
	(segment
		(start 63.625222 -306.51323)
		(end 63.603632 -306.49164)
		(width 0.14478)
		(layer "In13.Cu")
		(net "M_B_CPU1_SB_DQ<26>")
	)
	(segment
		(start 60.382912 -309.960264)
		(end 61.285882 -309.057294)
		(width 0.14478)
		(layer "In13.Cu")
		(net "M_B_CPU1_SB_DQ<26>")
	)
	(segment
		(start 64.219836 -306.12334)
		(end 71.962518 -298.380658)
		(width 0.14478)
		(layer "In13.Cu")
		(net "M_B_CPU1_SB_DQ<26>")
	)
	(segment
		(start 62.229238 -307.66131)
		(end 62.433962 -307.66131)
		(width 0.14478)
		(layer "In13.Cu")
		(net "M_B_CPU1_SB_DQ<26>")
	)
	(segment
		(start 71.962518 -296.742104)
		(end 75.931268 -292.773354)
		(width 0.14478)
		(layer "In13.Cu")
		(net "M_B_CPU1_SB_DQ<26>")
	)
	(segment
		(start 79.919322 -289.162236)
		(end 79.934054 -289.1536)
		(width 0.0889)
		(layer "In13.Cu")
		(net "M_B_CPU1_SB_DQ<26>")
	)
	(segment
		(start 61.264292 -308.83098)
		(end 61.264292 -308.626256)
		(width 0.14478)
		(layer "In13.Cu")
		(net "M_B_CPU1_SB_DQ<26>")
	)
	(segment
		(start 63.788798 -306.10175)
		(end 63.993522 -306.10175)
		(width 0.14478)
		(layer "In13.Cu")
		(net "M_B_CPU1_SB_DQ<26>")
	)
	(segment
		(start 62.065662 -308.277514)
		(end 62.065662 -308.07279)
		(width 0.14478)
		(layer "In13.Cu")
		(net "M_B_CPU1_SB_DQ<26>")
	)
	(segment
		(start 85.93963 -289.148774)
		(end 85.948012 -289.1536)
		(width 0.0889)
		(layer "In13.Cu")
		(net "M_B_CPU1_SB_DQ<26>")
	)
	(segment
		(start 61.285882 -309.057294)
		(end 61.285882 -308.85257)
		(width 0.14478)
		(layer "In13.Cu")
		(net "M_B_CPU1_SB_DQ<26>")
	)
	(segment
		(start 53.415692 -309.960264)
		(end 54.26583 -310.810402)
		(width 0.14478)
		(layer "In13.Cu")
		(net "M_B_CPU1_SB_DQ<26>")
	)
	(segment
		(start 63.009018 -306.88153)
		(end 63.213742 -306.88153)
		(width 0.14478)
		(layer "In13.Cu")
		(net "M_B_CPU1_SB_DQ<26>")
	)
	(segment
		(start 61.449458 -308.44109)
		(end 61.654182 -308.44109)
		(width 0.14478)
		(layer "In13.Cu")
		(net "M_B_CPU1_SB_DQ<26>")
	)
	(segment
		(start 56.95315 -310.810402)
		(end 57.803288 -309.960264)
		(width 0.14478)
		(layer "In13.Cu")
		(net "M_B_CPU1_SB_DQ<26>")
	)
	(segment
		(start 49.859946 -310.385206)
		(end 50.284888 -309.960264)
		(width 0.14478)
		(layer "In13.Cu")
		(net "M_B_CPU1_SB_DQ<26>")
	)
	(segment
		(start 63.213742 -306.88153)
		(end 63.235332 -306.90312)
		(width 0.14478)
		(layer "In13.Cu")
		(net "M_B_CPU1_SB_DQ<26>")
	)
	(segment
		(start 62.455552 -307.6829)
		(end 62.660276 -307.6829)
		(width 0.14478)
		(layer "In13.Cu")
		(net "M_B_CPU1_SB_DQ<26>")
	)
	(segment
		(start 62.044072 -308.0512)
		(end 62.044072 -307.846476)
		(width 0.14478)
		(layer "In13.Cu")
		(net "M_B_CPU1_SB_DQ<26>")
	)
	(segment
		(start 62.845442 -307.497734)
		(end 62.845442 -307.29301)
		(width 0.14478)
		(layer "In13.Cu")
		(net "M_B_CPU1_SB_DQ<26>")
	)
	(segment
		(start 61.264292 -308.626256)
		(end 61.449458 -308.44109)
		(width 0.14478)
		(layer "In13.Cu")
		(net "M_B_CPU1_SB_DQ<26>")
	)
	(segment
		(start 63.993522 -306.10175)
		(end 64.015112 -306.12334)
		(width 0.14478)
		(layer "In13.Cu")
		(net "M_B_CPU1_SB_DQ<26>")
	)
	(segment
		(start 71.962518 -298.380658)
		(end 71.962518 -296.742104)
		(width 0.14478)
		(layer "In13.Cu")
		(net "M_B_CPU1_SB_DQ<26>")
	)
	(segment
		(start 62.660276 -307.6829)
		(end 62.845442 -307.497734)
		(width 0.14478)
		(layer "In13.Cu")
		(net "M_B_CPU1_SB_DQ<26>")
	)
	(segment
		(start 77.61859 -289.865054)
		(end 78.253844 -289.2298)
		(width 0.0889)
		(layer "In13.Cu")
		(net "M_B_CPU1_SB_DQ<26>")
	)
	(segment
		(start 76.767944 -291.368226)
		(end 77.18171 -291.368226)
		(width 0.0889)
		(layer "In13.Cu")
		(net "M_B_CPU1_SB_DQ<26>")
	)
	(segment
		(start 85.948012 -289.1536)
		(end 85.948266 -289.1536)
		(width 0.0889)
		(layer "In13.Cu")
		(net "M_B_CPU1_SB_DQ<26>")
	)
	(segment
		(start 79.934054 -289.1536)
		(end 79.942436 -289.148774)
		(width 0.0889)
		(layer "In13.Cu")
		(net "M_B_CPU1_SB_DQ<26>")
	)
	(segment
		(start 57.803288 -309.960264)
		(end 60.382912 -309.960264)
		(width 0.14478)
		(layer "In13.Cu")
		(net "M_B_CPU1_SB_DQ<26>")
	)
	(segment
		(start 63.625222 -306.717954)
		(end 63.625222 -306.51323)
		(width 0.14478)
		(layer "In13.Cu")
		(net "M_B_CPU1_SB_DQ<26>")
	)
	(segment
		(start 77.61859 -290.931346)
		(end 77.61859 -289.865054)
		(width 0.0889)
		(layer "In13.Cu")
		(net "M_B_CPU1_SB_DQ<26>")
	)
	(segment
		(start 78.253844 -289.2298)
		(end 78.711044 -289.2298)
		(width 0.0889)
		(layer "In13.Cu")
		(net "M_B_CPU1_SB_DQ<26>")
	)
	(segment
		(start 82.753962 -289.1536)
		(end 82.762344 -289.148774)
		(width 0.0889)
		(layer "In13.Cu")
		(net "M_B_CPU1_SB_DQ<26>")
	)
	(segment
		(start 63.235332 -306.90312)
		(end 63.440056 -306.90312)
		(width 0.14478)
		(layer "In13.Cu")
		(net "M_B_CPU1_SB_DQ<26>")
	)
	(segment
		(start 61.675772 -308.46268)
		(end 61.880496 -308.46268)
		(width 0.14478)
		(layer "In13.Cu")
		(net "M_B_CPU1_SB_DQ<26>")
	)
	(segment
		(start 87.772748 -289.127438)
		(end 87.7951 -289.21075)
		(width 0.0889)
		(layer "In13.Cu")
		(net "M_B_CPU1_SB_DQ<26>")
	)
	(segment
		(start 63.603632 -306.49164)
		(end 63.603632 -306.286916)
		(width 0.14478)
		(layer "In13.Cu")
		(net "M_B_CPU1_SB_DQ<26>")
	)
	(segment
		(start 76.23175 -292.472872)
		(end 76.23175 -291.90442)
		(width 0.0889)
		(layer "In13.Cu")
		(net "M_B_CPU1_SB_DQ<26>")
	)
	(segment
		(start 62.044072 -307.846476)
		(end 62.229238 -307.66131)
		(width 0.14478)
		(layer "In13.Cu")
		(net "M_B_CPU1_SB_DQ<26>")
	)
	(segment
		(start 86.879684 -289.148774)
		(end 86.888066 -289.1536)
		(width 0.0889)
		(layer "In13.Cu")
		(net "M_B_CPU1_SB_DQ<26>")
	)
	(segment
		(start 62.823852 -307.27142)
		(end 62.823852 -307.066696)
		(width 0.14478)
		(layer "In13.Cu")
		(net "M_B_CPU1_SB_DQ<26>")
	)
	(segment
		(start 83.694016 -289.1536)
		(end 83.702398 -289.148774)
		(width 0.0889)
		(layer "In13.Cu")
		(net "M_B_CPU1_SB_DQ<26>")
	)
	(segment
		(start 62.433962 -307.66131)
		(end 62.455552 -307.6829)
		(width 0.14478)
		(layer "In13.Cu")
		(net "M_B_CPU1_SB_DQ<26>")
	)
	(segment
		(start 61.654182 -308.44109)
		(end 61.675772 -308.46268)
		(width 0.14478)
		(layer "In13.Cu")
		(net "M_B_CPU1_SB_DQ<26>")
	)
	(segment
		(start 87.7951 -289.21075)
		(end 87.640922 -289.47618)
		(width 0.0889)
		(layer "In13.Cu")
		(net "M_B_CPU1_SB_DQ<26>")
	)
	(segment
		(start 62.065662 -308.07279)
		(end 62.044072 -308.0512)
		(width 0.14478)
		(layer "In13.Cu")
		(net "M_B_CPU1_SB_DQ<26>")
	)
	(segment
		(start 62.823852 -307.066696)
		(end 63.009018 -306.88153)
		(width 0.14478)
		(layer "In13.Cu")
		(net "M_B_CPU1_SB_DQ<26>")
	)
	(segment
		(start 75.931268 -292.773354)
		(end 76.23175 -292.472872)
		(width 0.0889)
		(layer "In13.Cu")
		(net "M_B_CPU1_SB_DQ<26>")
	)
	(segment
		(start 82.179668 -289.148774)
		(end 82.18805 -289.1536)
		(width 0.0889)
		(layer "In13.Cu")
		(net "M_B_CPU1_SB_DQ<26>")
	)
	(segment
		(start 76.23175 -291.90442)
		(end 76.767944 -291.368226)
		(width 0.0889)
		(layer "In13.Cu")
		(net "M_B_CPU1_SB_DQ<26>")
	)
	(segment
		(start 61.880496 -308.46268)
		(end 62.065662 -308.277514)
		(width 0.14478)
		(layer "In13.Cu")
		(net "M_B_CPU1_SB_DQ<26>")
	)
	(segment
		(start 62.845442 -307.29301)
		(end 62.823852 -307.27142)
		(width 0.14478)
		(layer "In13.Cu")
		(net "M_B_CPU1_SB_DQ<26>")
	)
	(segment
		(start 63.440056 -306.90312)
		(end 63.625222 -306.717954)
		(width 0.14478)
		(layer "In13.Cu")
		(net "M_B_CPU1_SB_DQ<26>")
	)
	(segment
		(start 61.285882 -308.85257)
		(end 61.264292 -308.83098)
		(width 0.14478)
		(layer "In13.Cu")
		(net "M_B_CPU1_SB_DQ<26>")
	)
	(segment
		(start 77.18171 -291.368226)
		(end 77.61859 -290.931346)
		(width 0.0889)
		(layer "In13.Cu")
		(net "M_B_CPU1_SB_DQ<26>")
	)
	(segment
		(start 47.784004 -310.385206)
		(end 49.859946 -310.385206)
		(width 0.14478)
		(layer "In13.Cu")
		(net "M_B_CPU1_SB_DQ<26>")
	)
	(segment
		(start 63.603632 -306.286916)
		(end 63.788798 -306.10175)
		(width 0.14478)
		(layer "In13.Cu")
		(net "M_B_CPU1_SB_DQ<26>")
	)
	(segment
		(start 50.284888 -309.960264)
		(end 53.415692 -309.960264)
		(width 0.14478)
		(layer "In13.Cu")
		(net "M_B_CPU1_SB_DQ<26>")
	)
	(segment
		(start 64.015112 -306.12334)
		(end 64.219836 -306.12334)
		(width 0.14478)
		(layer "In13.Cu")
		(net "M_B_CPU1_SB_DQ<26>")
	)
	(segment
		(start 54.26583 -310.810402)
		(end 56.95315 -310.810402)
		(width 0.14478)
		(layer "In13.Cu")
		(net "M_B_CPU1_SB_DQ<26>")
	)
	(arc
		(start 85.007958 -289.1536)
		(mid 85.290914 -289.229777)
		(end 85.57387 -289.1536)
		(width 0.0889)
		(layer "In13.Cu")
		(net "M_B_CPU1_SB_DQ<26>")
	)
	(arc
		(start 81.247996 -289.1536)
		(mid 81.530952 -289.229777)
		(end 81.813908 -289.1536)
		(width 0.0889)
		(layer "In13.Cu")
		(net "M_B_CPU1_SB_DQ<26>")
	)
	(arc
		(start 83.702398 -289.148774)
		(mid 83.885906 -289.10328)
		(end 84.068158 -289.1536)
		(width 0.0889)
		(layer "In13.Cu")
		(net "M_B_CPU1_SB_DQ<26>")
	)
	(arc
		(start 80.308196 -289.1536)
		(mid 80.591152 -289.229777)
		(end 80.874108 -289.1536)
		(width 0.0889)
		(layer "In13.Cu")
		(net "M_B_CPU1_SB_DQ<26>")
	)
	(arc
		(start 81.813908 -289.1536)
		(mid 81.996159 -289.10325)
		(end 82.179668 -289.148774)
		(width 0.0889)
		(layer "In13.Cu")
		(net "M_B_CPU1_SB_DQ<26>")
	)
	(arc
		(start 86.888066 -289.1536)
		(mid 87.171022 -289.229777)
		(end 87.453978 -289.1536)
		(width 0.0889)
		(layer "In13.Cu")
		(net "M_B_CPU1_SB_DQ<26>")
	)
	(arc
		(start 85.948266 -289.1536)
		(mid 86.231112 -289.229777)
		(end 86.513924 -289.1536)
		(width 0.0889)
		(layer "In13.Cu")
		(net "M_B_CPU1_SB_DQ<26>")
	)
	(arc
		(start 87.46236 -289.148774)
		(mid 87.61523 -289.104133)
		(end 87.772748 -289.127438)
		(width 0.0889)
		(layer "In13.Cu")
		(net "M_B_CPU1_SB_DQ<26>")
	)
	(arc
		(start 78.711044 -289.2298)
		(mid 78.857292 -289.210495)
		(end 78.993492 -289.153854)
		(width 0.0889)
		(layer "In13.Cu")
		(net "M_B_CPU1_SB_DQ<26>")
	)
	(arc
		(start 79.367634 -289.1536)
		(mid 79.64234 -289.229964)
		(end 79.919322 -289.162236)
		(width 0.0889)
		(layer "In13.Cu")
		(net "M_B_CPU1_SB_DQ<26>")
	)
	(arc
		(start 79.01178 -289.14344)
		(mid 79.191009 -289.103287)
		(end 79.367634 -289.1536)
		(width 0.0889)
		(layer "In13.Cu")
		(net "M_B_CPU1_SB_DQ<26>")
	)
	(arc
		(start 82.762344 -289.148774)
		(mid 82.945852 -289.10328)
		(end 83.128104 -289.1536)
		(width 0.0889)
		(layer "In13.Cu")
		(net "M_B_CPU1_SB_DQ<26>")
	)
	(arc
		(start 82.18805 -289.1536)
		(mid 82.471006 -289.229777)
		(end 82.753962 -289.1536)
		(width 0.0889)
		(layer "In13.Cu")
		(net "M_B_CPU1_SB_DQ<26>")
	)
	(arc
		(start 85.57387 -289.1536)
		(mid 85.756121 -289.10325)
		(end 85.93963 -289.148774)
		(width 0.0889)
		(layer "In13.Cu")
		(net "M_B_CPU1_SB_DQ<26>")
	)
	(arc
		(start 84.63407 -289.1536)
		(mid 84.821014 -289.103345)
		(end 85.007958 -289.1536)
		(width 0.0889)
		(layer "In13.Cu")
		(net "M_B_CPU1_SB_DQ<26>")
	)
	(arc
		(start 79.942436 -289.148774)
		(mid 80.125944 -289.10328)
		(end 80.308196 -289.1536)
		(width 0.0889)
		(layer "In13.Cu")
		(net "M_B_CPU1_SB_DQ<26>")
	)
	(arc
		(start 86.513924 -289.1536)
		(mid 86.696175 -289.10325)
		(end 86.879684 -289.148774)
		(width 0.0889)
		(layer "In13.Cu")
		(net "M_B_CPU1_SB_DQ<26>")
	)
	(arc
		(start 80.874108 -289.1536)
		(mid 81.061052 -289.103345)
		(end 81.247996 -289.1536)
		(width 0.0889)
		(layer "In13.Cu")
		(net "M_B_CPU1_SB_DQ<26>")
	)
	(arc
		(start 84.068158 -289.1536)
		(mid 84.351114 -289.229777)
		(end 84.63407 -289.1536)
		(width 0.0889)
		(layer "In13.Cu")
		(net "M_B_CPU1_SB_DQ<26>")
	)
	(arc
		(start 83.128104 -289.1536)
		(mid 83.41106 -289.229777)
		(end 83.694016 -289.1536)
		(width 0.0889)
		(layer "In13.Cu")
		(net "M_B_CPU1_SB_DQ<26>")
	)
	(segment
		(start 89.987882 -289.210242)
		(end 89.52103 -289.47618)
		(width 0.10668)
		(layer "F.Cu")
		(net "M_B_CPU1_SB_DQ<25>")
	)
	(segment
		(start 80.299814 -289.803586)
		(end 80.308196 -289.79876)
		(width 0.0889)
		(layer "In13.Cu")
		(net "M_B_CPU1_SB_DQ<25>")
	)
	(segment
		(start 58.416698 -311.165748)
		(end 58.678318 -311.165748)
		(width 0.14478)
		(layer "In13.Cu")
		(net "M_B_CPU1_SB_DQ<25>")
	)
	(segment
		(start 72.412098 -298.567094)
		(end 72.412098 -296.93616)
		(width 0.14478)
		(layer "In13.Cu")
		(net "M_B_CPU1_SB_DQ<25>")
	)
	(segment
		(start 58.678318 -311.165748)
		(end 58.823098 -311.020968)
		(width 0.14478)
		(layer "In13.Cu")
		(net "M_B_CPU1_SB_DQ<25>")
	)
	(segment
		(start 74.5744 -294.983916)
		(end 74.779124 -294.983916)
		(width 0.14478)
		(layer "In13.Cu")
		(net "M_B_CPU1_SB_DQ<25>")
	)
	(segment
		(start 75.93584 -293.412418)
		(end 76.42225 -292.926008)
		(width 0.0889)
		(layer "In13.Cu")
		(net "M_B_CPU1_SB_DQ<25>")
	)
	(segment
		(start 73.999344 -295.763696)
		(end 74.184764 -295.578276)
		(width 0.14478)
		(layer "In13.Cu")
		(net "M_B_CPU1_SB_DQ<25>")
	)
	(segment
		(start 74.184764 -295.578276)
		(end 74.18451 -295.37406)
		(width 0.14478)
		(layer "In13.Cu")
		(net "M_B_CPU1_SB_DQ<25>")
	)
	(segment
		(start 73.587102 -295.761156)
		(end 73.791826 -295.760902)
		(width 0.14478)
		(layer "In13.Cu")
		(net "M_B_CPU1_SB_DQ<25>")
	)
	(segment
		(start 79.367126 -289.79876)
		(end 79.381858 -289.790124)
		(width 0.0889)
		(layer "In13.Cu")
		(net "M_B_CPU1_SB_DQ<25>")
	)
	(segment
		(start 75.351386 -294.201342)
		(end 75.35418 -294.204136)
		(width 0.14478)
		(layer "In13.Cu")
		(net "M_B_CPU1_SB_DQ<25>")
	)
	(segment
		(start 73.791826 -295.760902)
		(end 73.79462 -295.763696)
		(width 0.14478)
		(layer "In13.Cu")
		(net "M_B_CPU1_SB_DQ<25>")
	)
	(segment
		(start 74.964544 -294.798496)
		(end 74.96429 -294.59428)
		(width 0.14478)
		(layer "In13.Cu")
		(net "M_B_CPU1_SB_DQ<25>")
	)
	(segment
		(start 59.519058 -311.165748)
		(end 59.780678 -311.165748)
		(width 0.14478)
		(layer "In13.Cu")
		(net "M_B_CPU1_SB_DQ<25>")
	)
	(segment
		(start 58.967878 -310.810148)
		(end 59.229498 -310.810148)
		(width 0.14478)
		(layer "In13.Cu")
		(net "M_B_CPU1_SB_DQ<25>")
	)
	(segment
		(start 73.012046 -296.540682)
		(end 73.01484 -296.543476)
		(width 0.14478)
		(layer "In13.Cu")
		(net "M_B_CPU1_SB_DQ<25>")
	)
	(segment
		(start 85.948012 -289.79876)
		(end 85.948266 -289.79876)
		(width 0.0889)
		(layer "In13.Cu")
		(net "M_B_CPU1_SB_DQ<25>")
	)
	(segment
		(start 58.823098 -311.020968)
		(end 58.823098 -310.954928)
		(width 0.14478)
		(layer "In13.Cu")
		(net "M_B_CPU1_SB_DQ<25>")
	)
	(segment
		(start 75.558904 -294.204136)
		(end 75.744324 -294.018716)
		(width 0.14478)
		(layer "In13.Cu")
		(net "M_B_CPU1_SB_DQ<25>")
	)
	(segment
		(start 59.925458 -311.020968)
		(end 59.925458 -310.954928)
		(width 0.14478)
		(layer "In13.Cu")
		(net "M_B_CPU1_SB_DQ<25>")
	)
	(segment
		(start 54.748938 -311.660286)
		(end 56.746394 -311.660286)
		(width 0.14478)
		(layer "In13.Cu")
		(net "M_B_CPU1_SB_DQ<25>")
	)
	(segment
		(start 53.240432 -310.428132)
		(end 53.656992 -310.844692)
		(width 0.14478)
		(layer "In13.Cu")
		(net "M_B_CPU1_SB_DQ<25>")
	)
	(segment
		(start 82.753962 -289.79876)
		(end 82.762344 -289.803586)
		(width 0.0889)
		(layer "In13.Cu")
		(net "M_B_CPU1_SB_DQ<25>")
	)
	(segment
		(start 82.179668 -289.803586)
		(end 82.18805 -289.79876)
		(width 0.0889)
		(layer "In13.Cu")
		(net "M_B_CPU1_SB_DQ<25>")
	)
	(segment
		(start 74.366882 -294.981376)
		(end 74.571606 -294.981122)
		(width 0.14478)
		(layer "In13.Cu")
		(net "M_B_CPU1_SB_DQ<25>")
	)
	(segment
		(start 77.97165 -290.938966)
		(end 77.97165 -290.147756)
		(width 0.0889)
		(layer "In13.Cu")
		(net "M_B_CPU1_SB_DQ<25>")
	)
	(segment
		(start 73.404984 -296.358056)
		(end 73.40473 -296.15384)
		(width 0.14478)
		(layer "In13.Cu")
		(net "M_B_CPU1_SB_DQ<25>")
	)
	(segment
		(start 73.40473 -296.15384)
		(end 73.401936 -296.151046)
		(width 0.14478)
		(layer "In13.Cu")
		(net "M_B_CPU1_SB_DQ<25>")
	)
	(segment
		(start 73.401936 -295.946322)
		(end 73.587102 -295.761156)
		(width 0.14478)
		(layer "In13.Cu")
		(net "M_B_CPU1_SB_DQ<25>")
	)
	(segment
		(start 52.0446 -311.495948)
		(end 52.693062 -311.495948)
		(width 0.14478)
		(layer "In13.Cu")
		(net "M_B_CPU1_SB_DQ<25>")
	)
	(segment
		(start 53.651658 -311.629806)
		(end 53.856382 -311.629806)
		(width 0.14478)
		(layer "In13.Cu")
		(net "M_B_CPU1_SB_DQ<25>")
	)
	(segment
		(start 74.961496 -294.591486)
		(end 74.961496 -294.386762)
		(width 0.14478)
		(layer "In13.Cu")
		(net "M_B_CPU1_SB_DQ<25>")
	)
	(segment
		(start 52.693062 -311.495948)
		(end 52.838096 -311.350914)
		(width 0.14478)
		(layer "In13.Cu")
		(net "M_B_CPU1_SB_DQ<25>")
	)
	(segment
		(start 54.046882 -311.439306)
		(end 54.527958 -311.439306)
		(width 0.14478)
		(layer "In13.Cu")
		(net "M_B_CPU1_SB_DQ<25>")
	)
	(segment
		(start 77.97165 -290.147756)
		(end 78.172056 -289.94735)
		(width 0.0889)
		(layer "In13.Cu")
		(net "M_B_CPU1_SB_DQ<25>")
	)
	(segment
		(start 75.146662 -294.201596)
		(end 75.351386 -294.201342)
		(width 0.14478)
		(layer "In13.Cu")
		(net "M_B_CPU1_SB_DQ<25>")
	)
	(segment
		(start 59.925458 -310.954928)
		(end 60.070238 -310.810148)
		(width 0.14478)
		(layer "In13.Cu")
		(net "M_B_CPU1_SB_DQ<25>")
	)
	(segment
		(start 59.229498 -310.810148)
		(end 59.374278 -310.954928)
		(width 0.14478)
		(layer "In13.Cu")
		(net "M_B_CPU1_SB_DQ<25>")
	)
	(segment
		(start 75.744324 -294.018716)
		(end 75.74407 -293.8145)
		(width 0.14478)
		(layer "In13.Cu")
		(net "M_B_CPU1_SB_DQ<25>")
	)
	(segment
		(start 74.571606 -294.981122)
		(end 74.5744 -294.983916)
		(width 0.14478)
		(layer "In13.Cu")
		(net "M_B_CPU1_SB_DQ<25>")
	)
	(segment
		(start 59.374278 -310.954928)
		(end 59.374278 -311.020968)
		(width 0.14478)
		(layer "In13.Cu")
		(net "M_B_CPU1_SB_DQ<25>")
	)
	(segment
		(start 75.35418 -294.204136)
		(end 75.558904 -294.204136)
		(width 0.14478)
		(layer "In13.Cu")
		(net "M_B_CPU1_SB_DQ<25>")
	)
	(segment
		(start 58.127138 -310.810148)
		(end 58.271918 -310.954928)
		(width 0.14478)
		(layer "In13.Cu")
		(net "M_B_CPU1_SB_DQ<25>")
	)
	(segment
		(start 72.412098 -296.93616)
		(end 72.807322 -296.540936)
		(width 0.14478)
		(layer "In13.Cu")
		(net "M_B_CPU1_SB_DQ<25>")
	)
	(segment
		(start 59.374278 -311.020968)
		(end 59.519058 -311.165748)
		(width 0.14478)
		(layer "In13.Cu")
		(net "M_B_CPU1_SB_DQ<25>")
	)
	(segment
		(start 73.219564 -296.543476)
		(end 73.404984 -296.358056)
		(width 0.14478)
		(layer "In13.Cu")
		(net "M_B_CPU1_SB_DQ<25>")
	)
	(segment
		(start 89.271094 -289.76701)
		(end 89.367106 -289.74161)
		(width 0.0889)
		(layer "In13.Cu")
		(net "M_B_CPU1_SB_DQ<25>")
	)
	(segment
		(start 74.181716 -295.166542)
		(end 74.366882 -294.981376)
		(width 0.14478)
		(layer "In13.Cu")
		(net "M_B_CPU1_SB_DQ<25>")
	)
	(segment
		(start 53.856382 -311.629806)
		(end 54.046882 -311.439306)
		(width 0.14478)
		(layer "In13.Cu")
		(net "M_B_CPU1_SB_DQ<25>")
	)
	(segment
		(start 52.838096 -311.350914)
		(end 52.838096 -310.590946)
		(width 0.14478)
		(layer "In13.Cu")
		(net "M_B_CPU1_SB_DQ<25>")
	)
	(segment
		(start 89.367106 -289.74161)
		(end 89.52103 -289.47618)
		(width 0.0889)
		(layer "In13.Cu")
		(net "M_B_CPU1_SB_DQ<25>")
	)
	(segment
		(start 54.527958 -311.439306)
		(end 54.748938 -311.660286)
		(width 0.14478)
		(layer "In13.Cu")
		(net "M_B_CPU1_SB_DQ<25>")
	)
	(segment
		(start 72.807322 -296.540936)
		(end 73.012046 -296.540682)
		(width 0.14478)
		(layer "In13.Cu")
		(net "M_B_CPU1_SB_DQ<25>")
	)
	(segment
		(start 78.993492 -289.798506)
		(end 79.007208 -289.80638)
		(width 0.0889)
		(layer "In13.Cu")
		(net "M_B_CPU1_SB_DQ<25>")
	)
	(segment
		(start 85.93963 -289.803586)
		(end 85.948012 -289.79876)
		(width 0.0889)
		(layer "In13.Cu")
		(net "M_B_CPU1_SB_DQ<25>")
	)
	(segment
		(start 74.181716 -295.371266)
		(end 74.181716 -295.166542)
		(width 0.14478)
		(layer "In13.Cu")
		(net "M_B_CPU1_SB_DQ<25>")
	)
	(segment
		(start 74.779124 -294.983916)
		(end 74.964544 -294.798496)
		(width 0.14478)
		(layer "In13.Cu")
		(net "M_B_CPU1_SB_DQ<25>")
	)
	(segment
		(start 76.42225 -292.135306)
		(end 76.86675 -291.690806)
		(width 0.0889)
		(layer "In13.Cu")
		(net "M_B_CPU1_SB_DQ<25>")
	)
	(segment
		(start 76.42225 -292.926008)
		(end 76.42225 -292.135306)
		(width 0.0889)
		(layer "In13.Cu")
		(net "M_B_CPU1_SB_DQ<25>")
	)
	(segment
		(start 58.271918 -310.954928)
		(end 58.271918 -311.020968)
		(width 0.14478)
		(layer "In13.Cu")
		(net "M_B_CPU1_SB_DQ<25>")
	)
	(segment
		(start 58.271918 -311.020968)
		(end 58.416698 -311.165748)
		(width 0.14478)
		(layer "In13.Cu")
		(net "M_B_CPU1_SB_DQ<25>")
	)
	(segment
		(start 75.741276 -293.811706)
		(end 75.741276 -293.606982)
		(width 0.14478)
		(layer "In13.Cu")
		(net "M_B_CPU1_SB_DQ<25>")
	)
	(segment
		(start 53.466492 -311.44464)
		(end 53.651658 -311.629806)
		(width 0.14478)
		(layer "In13.Cu")
		(net "M_B_CPU1_SB_DQ<25>")
	)
	(segment
		(start 75.74407 -293.8145)
		(end 75.741276 -293.811706)
		(width 0.14478)
		(layer "In13.Cu")
		(net "M_B_CPU1_SB_DQ<25>")
	)
	(segment
		(start 77.21981 -291.690806)
		(end 77.97165 -290.938966)
		(width 0.0889)
		(layer "In13.Cu")
		(net "M_B_CPU1_SB_DQ<25>")
	)
	(segment
		(start 60.169044 -310.810148)
		(end 72.412098 -298.567094)
		(width 0.14478)
		(layer "In13.Cu")
		(net "M_B_CPU1_SB_DQ<25>")
	)
	(segment
		(start 73.79462 -295.763696)
		(end 73.999344 -295.763696)
		(width 0.14478)
		(layer "In13.Cu")
		(net "M_B_CPU1_SB_DQ<25>")
	)
	(segment
		(start 74.961496 -294.386762)
		(end 75.146662 -294.201596)
		(width 0.14478)
		(layer "In13.Cu")
		(net "M_B_CPU1_SB_DQ<25>")
	)
	(segment
		(start 53.00091 -310.428132)
		(end 53.240432 -310.428132)
		(width 0.14478)
		(layer "In13.Cu")
		(net "M_B_CPU1_SB_DQ<25>")
	)
	(segment
		(start 52.838096 -310.590946)
		(end 53.00091 -310.428132)
		(width 0.14478)
		(layer "In13.Cu")
		(net "M_B_CPU1_SB_DQ<25>")
	)
	(segment
		(start 56.746394 -311.660286)
		(end 57.596532 -310.810148)
		(width 0.14478)
		(layer "In13.Cu")
		(net "M_B_CPU1_SB_DQ<25>")
	)
	(segment
		(start 88.394032 -289.79876)
		(end 88.402414 -289.803586)
		(width 0.0889)
		(layer "In13.Cu")
		(net "M_B_CPU1_SB_DQ<25>")
	)
	(segment
		(start 53.466492 -311.239916)
		(end 53.466492 -311.44464)
		(width 0.14478)
		(layer "In13.Cu")
		(net "M_B_CPU1_SB_DQ<25>")
	)
	(segment
		(start 78.977744 -289.789362)
		(end 78.993492 -289.798506)
		(width 0.0889)
		(layer "In13.Cu")
		(net "M_B_CPU1_SB_DQ<25>")
	)
	(segment
		(start 58.823098 -310.954928)
		(end 58.967878 -310.810148)
		(width 0.14478)
		(layer "In13.Cu")
		(net "M_B_CPU1_SB_DQ<25>")
	)
	(segment
		(start 53.656992 -310.844692)
		(end 53.656992 -311.049416)
		(width 0.14478)
		(layer "In13.Cu")
		(net "M_B_CPU1_SB_DQ<25>")
	)
	(segment
		(start 59.780678 -311.165748)
		(end 59.925458 -311.020968)
		(width 0.14478)
		(layer "In13.Cu")
		(net "M_B_CPU1_SB_DQ<25>")
	)
	(segment
		(start 57.596532 -310.810148)
		(end 58.127138 -310.810148)
		(width 0.14478)
		(layer "In13.Cu")
		(net "M_B_CPU1_SB_DQ<25>")
	)
	(segment
		(start 74.18451 -295.37406)
		(end 74.181716 -295.371266)
		(width 0.14478)
		(layer "In13.Cu")
		(net "M_B_CPU1_SB_DQ<25>")
	)
	(segment
		(start 87.453978 -289.79876)
		(end 87.46236 -289.803586)
		(width 0.0889)
		(layer "In13.Cu")
		(net "M_B_CPU1_SB_DQ<25>")
	)
	(segment
		(start 60.070238 -310.810148)
		(end 60.169044 -310.810148)
		(width 0.14478)
		(layer "In13.Cu")
		(net "M_B_CPU1_SB_DQ<25>")
	)
	(segment
		(start 73.01484 -296.543476)
		(end 73.219564 -296.543476)
		(width 0.14478)
		(layer "In13.Cu")
		(net "M_B_CPU1_SB_DQ<25>")
	)
	(segment
		(start 86.879684 -289.803586)
		(end 86.888066 -289.79876)
		(width 0.0889)
		(layer "In13.Cu")
		(net "M_B_CPU1_SB_DQ<25>")
	)
	(segment
		(start 76.86675 -291.690806)
		(end 77.21981 -291.690806)
		(width 0.0889)
		(layer "In13.Cu")
		(net "M_B_CPU1_SB_DQ<25>")
	)
	(segment
		(start 83.694016 -289.79876)
		(end 83.702398 -289.803586)
		(width 0.0889)
		(layer "In13.Cu")
		(net "M_B_CPU1_SB_DQ<25>")
	)
	(segment
		(start 51.884072 -311.33542)
		(end 52.0446 -311.495948)
		(width 0.14478)
		(layer "In13.Cu")
		(net "M_B_CPU1_SB_DQ<25>")
	)
	(segment
		(start 78.172056 -289.94735)
		(end 78.42758 -289.79876)
		(width 0.0889)
		(layer "In13.Cu")
		(net "M_B_CPU1_SB_DQ<25>")
	)
	(segment
		(start 53.656992 -311.049416)
		(end 53.466492 -311.239916)
		(width 0.14478)
		(layer "In13.Cu")
		(net "M_B_CPU1_SB_DQ<25>")
	)
	(segment
		(start 73.401936 -296.151046)
		(end 73.401936 -295.946322)
		(width 0.14478)
		(layer "In13.Cu")
		(net "M_B_CPU1_SB_DQ<25>")
	)
	(segment
		(start 75.741276 -293.606982)
		(end 75.93584 -293.412418)
		(width 0.14478)
		(layer "In13.Cu")
		(net "M_B_CPU1_SB_DQ<25>")
	)
	(segment
		(start 74.96429 -294.59428)
		(end 74.961496 -294.591486)
		(width 0.14478)
		(layer "In13.Cu")
		(net "M_B_CPU1_SB_DQ<25>")
	)
	(segment
		(start 51.884072 -311.235344)
		(end 51.884072 -311.33542)
		(width 0.14478)
		(layer "In13.Cu")
		(net "M_B_CPU1_SB_DQ<25>")
	)
	(arc
		(start 79.933546 -289.79876)
		(mid 80.116051 -289.849237)
		(end 80.299814 -289.803586)
		(width 0.0889)
		(layer "In13.Cu")
		(net "M_B_CPU1_SB_DQ<25>")
	)
	(arc
		(start 79.381858 -289.790124)
		(mid 79.658841 -289.72232)
		(end 79.933546 -289.79876)
		(width 0.0889)
		(layer "In13.Cu")
		(net "M_B_CPU1_SB_DQ<25>")
	)
	(arc
		(start 87.46236 -289.803586)
		(mid 87.645868 -289.84908)
		(end 87.82812 -289.79876)
		(width 0.0889)
		(layer "In13.Cu")
		(net "M_B_CPU1_SB_DQ<25>")
	)
	(arc
		(start 86.513924 -289.79876)
		(mid 86.696175 -289.84911)
		(end 86.879684 -289.803586)
		(width 0.0889)
		(layer "In13.Cu")
		(net "M_B_CPU1_SB_DQ<25>")
	)
	(arc
		(start 84.63407 -289.79876)
		(mid 84.821014 -289.849015)
		(end 85.007958 -289.79876)
		(width 0.0889)
		(layer "In13.Cu")
		(net "M_B_CPU1_SB_DQ<25>")
	)
	(arc
		(start 82.18805 -289.79876)
		(mid 82.471006 -289.722583)
		(end 82.753962 -289.79876)
		(width 0.0889)
		(layer "In13.Cu")
		(net "M_B_CPU1_SB_DQ<25>")
	)
	(arc
		(start 87.82812 -289.79876)
		(mid 88.111076 -289.722583)
		(end 88.394032 -289.79876)
		(width 0.0889)
		(layer "In13.Cu")
		(net "M_B_CPU1_SB_DQ<25>")
	)
	(arc
		(start 83.702398 -289.803586)
		(mid 83.885906 -289.84908)
		(end 84.068158 -289.79876)
		(width 0.0889)
		(layer "In13.Cu")
		(net "M_B_CPU1_SB_DQ<25>")
	)
	(arc
		(start 84.068158 -289.79876)
		(mid 84.351114 -289.722583)
		(end 84.63407 -289.79876)
		(width 0.0889)
		(layer "In13.Cu")
		(net "M_B_CPU1_SB_DQ<25>")
	)
	(arc
		(start 88.768174 -289.79876)
		(mid 89.015887 -289.72354)
		(end 89.271094 -289.76701)
		(width 0.0889)
		(layer "In13.Cu")
		(net "M_B_CPU1_SB_DQ<25>")
	)
	(arc
		(start 83.128104 -289.79876)
		(mid 83.41106 -289.722583)
		(end 83.694016 -289.79876)
		(width 0.0889)
		(layer "In13.Cu")
		(net "M_B_CPU1_SB_DQ<25>")
	)
	(arc
		(start 85.007958 -289.79876)
		(mid 85.290914 -289.722583)
		(end 85.57387 -289.79876)
		(width 0.0889)
		(layer "In13.Cu")
		(net "M_B_CPU1_SB_DQ<25>")
	)
	(arc
		(start 81.813908 -289.79876)
		(mid 81.996159 -289.84911)
		(end 82.179668 -289.803586)
		(width 0.0889)
		(layer "In13.Cu")
		(net "M_B_CPU1_SB_DQ<25>")
	)
	(arc
		(start 78.42758 -289.79876)
		(mid 78.701435 -289.72241)
		(end 78.977744 -289.789362)
		(width 0.0889)
		(layer "In13.Cu")
		(net "M_B_CPU1_SB_DQ<25>")
	)
	(arc
		(start 79.007208 -289.80638)
		(mid 79.188138 -289.848858)
		(end 79.367126 -289.79876)
		(width 0.0889)
		(layer "In13.Cu")
		(net "M_B_CPU1_SB_DQ<25>")
	)
	(arc
		(start 85.57387 -289.79876)
		(mid 85.756121 -289.84911)
		(end 85.93963 -289.803586)
		(width 0.0889)
		(layer "In13.Cu")
		(net "M_B_CPU1_SB_DQ<25>")
	)
	(arc
		(start 86.888066 -289.79876)
		(mid 87.171022 -289.722583)
		(end 87.453978 -289.79876)
		(width 0.0889)
		(layer "In13.Cu")
		(net "M_B_CPU1_SB_DQ<25>")
	)
	(arc
		(start 88.402414 -289.803586)
		(mid 88.585922 -289.84908)
		(end 88.768174 -289.79876)
		(width 0.0889)
		(layer "In13.Cu")
		(net "M_B_CPU1_SB_DQ<25>")
	)
	(arc
		(start 80.308196 -289.79876)
		(mid 80.591152 -289.722583)
		(end 80.874108 -289.79876)
		(width 0.0889)
		(layer "In13.Cu")
		(net "M_B_CPU1_SB_DQ<25>")
	)
	(arc
		(start 80.874108 -289.79876)
		(mid 81.061052 -289.849015)
		(end 81.247996 -289.79876)
		(width 0.0889)
		(layer "In13.Cu")
		(net "M_B_CPU1_SB_DQ<25>")
	)
	(arc
		(start 81.247996 -289.79876)
		(mid 81.530952 -289.722583)
		(end 81.813908 -289.79876)
		(width 0.0889)
		(layer "In13.Cu")
		(net "M_B_CPU1_SB_DQ<25>")
	)
	(arc
		(start 85.948266 -289.79876)
		(mid 86.231112 -289.722583)
		(end 86.513924 -289.79876)
		(width 0.0889)
		(layer "In13.Cu")
		(net "M_B_CPU1_SB_DQ<25>")
	)
	(arc
		(start 82.762344 -289.803586)
		(mid 82.945852 -289.84908)
		(end 83.128104 -289.79876)
		(width 0.0889)
		(layer "In13.Cu")
		(net "M_B_CPU1_SB_DQ<25>")
	)
	(segment
		(start 88.577928 -288.400236)
		(end 88.111076 -288.666174)
		(width 0.10668)
		(layer "F.Cu")
		(net "M_B_CPU1_SB_DQ<24>")
	)
	(segment
		(start 81.35239 -288.99358)
		(end 81.344008 -288.988754)
		(width 0.0889)
		(layer "In13.Cu")
		(net "M_B_CPU1_SB_DQ<24>")
	)
	(segment
		(start 76.70927 -291.157406)
		(end 75.783186 -292.08349)
		(width 0.0889)
		(layer "In13.Cu")
		(net "M_B_CPU1_SB_DQ<24>")
	)
	(segment
		(start 56.58231 -310.307482)
		(end 56.419496 -310.144668)
		(width 0.14478)
		(layer "In13.Cu")
		(net "M_B_CPU1_SB_DQ<24>")
	)
	(segment
		(start 78.71079 -289.0393)
		(end 78.17485 -289.0393)
		(width 0.0889)
		(layer "In13.Cu")
		(net "M_B_CPU1_SB_DQ<24>")
	)
	(segment
		(start 56.256682 -309.57139)
		(end 56.02605 -309.57139)
		(width 0.14478)
		(layer "In13.Cu")
		(net "M_B_CPU1_SB_DQ<24>")
	)
	(segment
		(start 70.257416 -299.2247)
		(end 70.257416 -299.429424)
		(width 0.14478)
		(layer "In13.Cu")
		(net "M_B_CPU1_SB_DQ<24>")
	)
	(segment
		(start 78.17485 -289.0393)
		(end 76.70927 -290.50488)
		(width 0.0889)
		(layer "In13.Cu")
		(net "M_B_CPU1_SB_DQ<24>")
	)
	(segment
		(start 87.956898 -288.931604)
		(end 87.860632 -288.957004)
		(width 0.0889)
		(layer "In13.Cu")
		(net "M_B_CPU1_SB_DQ<24>")
	)
	(segment
		(start 79.838042 -288.988754)
		(end 79.826358 -288.995612)
		(width 0.0889)
		(layer "In13.Cu")
		(net "M_B_CPU1_SB_DQ<24>")
	)
	(segment
		(start 64.756538 -304.640742)
		(end 64.798956 -304.68316)
		(width 0.14478)
		(layer "In13.Cu")
		(net "M_B_CPU1_SB_DQ<24>")
	)
	(segment
		(start 66.358516 -303.328324)
		(end 66.173096 -303.513744)
		(width 0.14478)
		(layer "In13.Cu")
		(net "M_B_CPU1_SB_DQ<24>")
	)
	(segment
		(start 64.941958 -304.250852)
		(end 64.756792 -304.436018)
		(width 0.14478)
		(layer "In13.Cu")
		(net "M_B_CPU1_SB_DQ<24>")
	)
	(segment
		(start 71.037196 -298.44492)
		(end 71.037196 -298.649644)
		(width 0.14478)
		(layer "In13.Cu")
		(net "M_B_CPU1_SB_DQ<24>")
	)
	(segment
		(start 69.435472 -299.757338)
		(end 69.435218 -299.962062)
		(width 0.14478)
		(layer "In13.Cu")
		(net "M_B_CPU1_SB_DQ<24>")
	)
	(segment
		(start 58.071766 -309.293006)
		(end 57.134252 -309.293006)
		(width 0.14478)
		(layer "In13.Cu")
		(net "M_B_CPU1_SB_DQ<24>")
	)
	(segment
		(start 69.825362 -299.572172)
		(end 69.620638 -299.572172)
		(width 0.14478)
		(layer "In13.Cu")
		(net "M_B_CPU1_SB_DQ<24>")
	)
	(segment
		(start 55.863236 -310.144668)
		(end 55.700422 -310.307482)
		(width 0.14478)
		(layer "In13.Cu")
		(net "M_B_CPU1_SB_DQ<24>")
	)
	(segment
		(start 68.30822 -301.17415)
		(end 68.265802 -301.131732)
		(width 0.14478)
		(layer "In13.Cu")
		(net "M_B_CPU1_SB_DQ<24>")
	)
	(segment
		(start 71.512938 -296.353738)
		(end 71.512938 -297.679872)
		(width 0.14478)
		(layer "In13.Cu")
		(net "M_B_CPU1_SB_DQ<24>")
	)
	(segment
		(start 70.64756 -298.83481)
		(end 70.605142 -298.792392)
		(width 0.14478)
		(layer "In13.Cu")
		(net "M_B_CPU1_SB_DQ<24>")
	)
	(segment
		(start 67.138296 -302.34382)
		(end 67.138296 -302.548544)
		(width 0.14478)
		(layer "In13.Cu")
		(net "M_B_CPU1_SB_DQ<24>")
	)
	(segment
		(start 65.146682 -304.250852)
		(end 64.941958 -304.250852)
		(width 0.14478)
		(layer "In13.Cu")
		(net "M_B_CPU1_SB_DQ<24>")
	)
	(segment
		(start 56.97093 -309.456328)
		(end 56.97093 -309.686198)
		(width 0.14478)
		(layer "In13.Cu")
		(net "M_B_CPU1_SB_DQ<24>")
	)
	(segment
		(start 68.512436 -301.174404)
		(end 68.30822 -301.17415)
		(width 0.14478)
		(layer "In13.Cu")
		(net "M_B_CPU1_SB_DQ<24>")
	)
	(segment
		(start 54.341268 -309.86984)
		(end 54.532276 -309.678832)
		(width 0.14478)
		(layer "In13.Cu")
		(net "M_B_CPU1_SB_DQ<24>")
	)
	(segment
		(start 64.162178 -305.030632)
		(end 60.08243 -309.11038)
		(width 0.14478)
		(layer "In13.Cu")
		(net "M_B_CPU1_SB_DQ<24>")
	)
	(segment
		(start 64.366902 -305.030632)
		(end 64.162178 -305.030632)
		(width 0.14478)
		(layer "In13.Cu")
		(net "M_B_CPU1_SB_DQ<24>")
	)
	(segment
		(start 64.613536 -305.073304)
		(end 64.40932 -305.07305)
		(width 0.14478)
		(layer "In13.Cu")
		(net "M_B_CPU1_SB_DQ<24>")
	)
	(segment
		(start 70.257416 -299.429424)
		(end 70.071996 -299.614844)
		(width 0.14478)
		(layer "In13.Cu")
		(net "M_B_CPU1_SB_DQ<24>")
	)
	(segment
		(start 66.501518 -302.691292)
		(end 66.316352 -302.876458)
		(width 0.14478)
		(layer "In13.Cu")
		(net "M_B_CPU1_SB_DQ<24>")
	)
	(segment
		(start 68.655692 -300.537118)
		(end 68.655438 -300.741842)
		(width 0.14478)
		(layer "In13.Cu")
		(net "M_B_CPU1_SB_DQ<24>")
	)
	(segment
		(start 65.578736 -303.90338)
		(end 65.578736 -304.108104)
		(width 0.14478)
		(layer "In13.Cu")
		(net "M_B_CPU1_SB_DQ<24>")
	)
	(segment
		(start 70.605142 -298.792392)
		(end 70.400418 -298.792392)
		(width 0.14478)
		(layer "In13.Cu")
		(net "M_B_CPU1_SB_DQ<24>")
	)
	(segment
		(start 65.96888 -303.51349)
		(end 65.926462 -303.471072)
		(width 0.14478)
		(layer "In13.Cu")
		(net "M_B_CPU1_SB_DQ<24>")
	)
	(segment
		(start 68.265802 -301.131732)
		(end 68.061078 -301.131732)
		(width 0.14478)
		(layer "In13.Cu")
		(net "M_B_CPU1_SB_DQ<24>")
	)
	(segment
		(start 66.706242 -302.691292)
		(end 66.501518 -302.691292)
		(width 0.14478)
		(layer "In13.Cu")
		(net "M_B_CPU1_SB_DQ<24>")
	)
	(segment
		(start 75.783186 -292.08349)
		(end 71.512938 -296.353738)
		(width 0.14478)
		(layer "In13.Cu")
		(net "M_B_CPU1_SB_DQ<24>")
	)
	(segment
		(start 56.812942 -310.307482)
		(end 56.58231 -310.307482)
		(width 0.14478)
		(layer "In13.Cu")
		(net "M_B_CPU1_SB_DQ<24>")
	)
	(segment
		(start 78.913482 -288.979356)
		(end 78.897734 -288.9885)
		(width 0.0889)
		(layer "In13.Cu")
		(net "M_B_CPU1_SB_DQ<24>")
	)
	(segment
		(start 56.97093 -309.686198)
		(end 57.087516 -309.802784)
		(width 0.14478)
		(layer "In13.Cu")
		(net "M_B_CPU1_SB_DQ<24>")
	)
	(segment
		(start 67.138296 -302.548544)
		(end 66.952876 -302.733964)
		(width 0.14478)
		(layer "In13.Cu")
		(net "M_B_CPU1_SB_DQ<24>")
	)
	(segment
		(start 80.778096 -288.988754)
		(end 80.769714 -288.99358)
		(width 0.0889)
		(layer "In13.Cu")
		(net "M_B_CPU1_SB_DQ<24>")
	)
	(segment
		(start 69.088 -300.39437)
		(end 69.045582 -300.351952)
		(width 0.14478)
		(layer "In13.Cu")
		(net "M_B_CPU1_SB_DQ<24>")
	)
	(segment
		(start 60.08243 -309.11038)
		(end 59.065668 -309.11038)
		(width 0.14478)
		(layer "In13.Cu")
		(net "M_B_CPU1_SB_DQ<24>")
	)
	(segment
		(start 64.40932 -305.07305)
		(end 64.366902 -305.030632)
		(width 0.14478)
		(layer "In13.Cu")
		(net "M_B_CPU1_SB_DQ<24>")
	)
	(segment
		(start 55.700422 -310.307482)
		(end 54.548786 -310.307482)
		(width 0.14478)
		(layer "In13.Cu")
		(net "M_B_CPU1_SB_DQ<24>")
	)
	(segment
		(start 85.112352 -288.99358)
		(end 85.10397 -288.988754)
		(width 0.0889)
		(layer "In13.Cu")
		(net "M_B_CPU1_SB_DQ<24>")
	)
	(segment
		(start 57.134252 -309.293006)
		(end 56.97093 -309.456328)
		(width 0.14478)
		(layer "In13.Cu")
		(net "M_B_CPU1_SB_DQ<24>")
	)
	(segment
		(start 64.756792 -304.436018)
		(end 64.756538 -304.640742)
		(width 0.14478)
		(layer "In13.Cu")
		(net "M_B_CPU1_SB_DQ<24>")
	)
	(segment
		(start 67.095878 -302.301402)
		(end 67.138296 -302.34382)
		(width 0.14478)
		(layer "In13.Cu")
		(net "M_B_CPU1_SB_DQ<24>")
	)
	(segment
		(start 70.400418 -298.792392)
		(end 70.215252 -298.977558)
		(width 0.14478)
		(layer "In13.Cu")
		(net "M_B_CPU1_SB_DQ<24>")
	)
	(segment
		(start 67.875912 -301.316898)
		(end 67.875658 -301.521622)
		(width 0.14478)
		(layer "In13.Cu")
		(net "M_B_CPU1_SB_DQ<24>")
	)
	(segment
		(start 65.721738 -303.471072)
		(end 65.536572 -303.656238)
		(width 0.14478)
		(layer "In13.Cu")
		(net "M_B_CPU1_SB_DQ<24>")
	)
	(segment
		(start 53.717698 -309.476394)
		(end 53.351684 -309.11038)
		(width 0.14478)
		(layer "In13.Cu")
		(net "M_B_CPU1_SB_DQ<24>")
	)
	(segment
		(start 88.111076 -288.666174)
		(end 87.956898 -288.931604)
		(width 0.0889)
		(layer "In13.Cu")
		(net "M_B_CPU1_SB_DQ<24>")
	)
	(segment
		(start 68.061078 -301.131732)
		(end 67.875912 -301.316898)
		(width 0.14478)
		(layer "In13.Cu")
		(net "M_B_CPU1_SB_DQ<24>")
	)
	(segment
		(start 67.875658 -301.521622)
		(end 67.918076 -301.56404)
		(width 0.14478)
		(layer "In13.Cu")
		(net "M_B_CPU1_SB_DQ<24>")
	)
	(segment
		(start 70.214998 -299.182282)
		(end 70.257416 -299.2247)
		(width 0.14478)
		(layer "In13.Cu")
		(net "M_B_CPU1_SB_DQ<24>")
	)
	(segment
		(start 54.532276 -309.678832)
		(end 54.532276 -309.448708)
		(width 0.14478)
		(layer "In13.Cu")
		(net "M_B_CPU1_SB_DQ<24>")
	)
	(segment
		(start 56.02605 -309.57139)
		(end 55.863236 -309.734204)
		(width 0.14478)
		(layer "In13.Cu")
		(net "M_B_CPU1_SB_DQ<24>")
	)
	(segment
		(start 56.419496 -309.734204)
		(end 56.256682 -309.57139)
		(width 0.14478)
		(layer "In13.Cu")
		(net "M_B_CPU1_SB_DQ<24>")
	)
	(segment
		(start 67.486022 -301.911512)
		(end 67.281298 -301.911512)
		(width 0.14478)
		(layer "In13.Cu")
		(net "M_B_CPU1_SB_DQ<24>")
	)
	(segment
		(start 69.86778 -299.61459)
		(end 69.825362 -299.572172)
		(width 0.14478)
		(layer "In13.Cu")
		(net "M_B_CPU1_SB_DQ<24>")
	)
	(segment
		(start 66.74866 -302.73371)
		(end 66.706242 -302.691292)
		(width 0.14478)
		(layer "In13.Cu")
		(net "M_B_CPU1_SB_DQ<24>")
	)
	(segment
		(start 69.477636 -300.209204)
		(end 69.292216 -300.394624)
		(width 0.14478)
		(layer "In13.Cu")
		(net "M_B_CPU1_SB_DQ<24>")
	)
	(segment
		(start 84.538058 -288.988754)
		(end 84.529676 -288.99358)
		(width 0.0889)
		(layer "In13.Cu")
		(net "M_B_CPU1_SB_DQ<24>")
	)
	(segment
		(start 66.316098 -303.081182)
		(end 66.358516 -303.1236)
		(width 0.14478)
		(layer "In13.Cu")
		(net "M_B_CPU1_SB_DQ<24>")
	)
	(segment
		(start 52.309014 -309.11038)
		(end 51.884072 -309.535322)
		(width 0.14478)
		(layer "In13.Cu")
		(net "M_B_CPU1_SB_DQ<24>")
	)
	(segment
		(start 55.863236 -309.734204)
		(end 55.863236 -310.144668)
		(width 0.14478)
		(layer "In13.Cu")
		(net "M_B_CPU1_SB_DQ<24>")
	)
	(segment
		(start 68.840858 -300.351952)
		(end 68.655692 -300.537118)
		(width 0.14478)
		(layer "In13.Cu")
		(net "M_B_CPU1_SB_DQ<24>")
	)
	(segment
		(start 67.918076 -301.56404)
		(end 67.918076 -301.768764)
		(width 0.14478)
		(layer "In13.Cu")
		(net "M_B_CPU1_SB_DQ<24>")
	)
	(segment
		(start 57.087516 -309.802784)
		(end 57.087516 -310.032908)
		(width 0.14478)
		(layer "In13.Cu")
		(net "M_B_CPU1_SB_DQ<24>")
	)
	(segment
		(start 54.13883 -309.285386)
		(end 53.947822 -309.476394)
		(width 0.14478)
		(layer "In13.Cu")
		(net "M_B_CPU1_SB_DQ<24>")
	)
	(segment
		(start 67.52844 -301.95393)
		(end 67.486022 -301.911512)
		(width 0.14478)
		(layer "In13.Cu")
		(net "M_B_CPU1_SB_DQ<24>")
	)
	(segment
		(start 69.435218 -299.962062)
		(end 69.477636 -300.00448)
		(width 0.14478)
		(layer "In13.Cu")
		(net "M_B_CPU1_SB_DQ<24>")
	)
	(segment
		(start 58.810652 -308.855364)
		(end 58.509408 -308.855364)
		(width 0.14478)
		(layer "In13.Cu")
		(net "M_B_CPU1_SB_DQ<24>")
	)
	(segment
		(start 54.532276 -309.448708)
		(end 54.368954 -309.285386)
		(width 0.14478)
		(layer "In13.Cu")
		(net "M_B_CPU1_SB_DQ<24>")
	)
	(segment
		(start 70.215252 -298.977558)
		(end 70.214998 -299.182282)
		(width 0.14478)
		(layer "In13.Cu")
		(net "M_B_CPU1_SB_DQ<24>")
	)
	(segment
		(start 53.351684 -309.11038)
		(end 52.309014 -309.11038)
		(width 0.14478)
		(layer "In13.Cu")
		(net "M_B_CPU1_SB_DQ<24>")
	)
	(segment
		(start 65.536318 -303.860962)
		(end 65.578736 -303.90338)
		(width 0.14478)
		(layer "In13.Cu")
		(net "M_B_CPU1_SB_DQ<24>")
	)
	(segment
		(start 71.512938 -297.679872)
		(end 70.995032 -298.197778)
		(width 0.14478)
		(layer "In13.Cu")
		(net "M_B_CPU1_SB_DQ<24>")
	)
	(segment
		(start 68.697856 -300.988984)
		(end 68.512436 -301.174404)
		(width 0.14478)
		(layer "In13.Cu")
		(net "M_B_CPU1_SB_DQ<24>")
	)
	(segment
		(start 66.358516 -303.1236)
		(end 66.358516 -303.328324)
		(width 0.14478)
		(layer "In13.Cu")
		(net "M_B_CPU1_SB_DQ<24>")
	)
	(segment
		(start 65.926462 -303.471072)
		(end 65.721738 -303.471072)
		(width 0.14478)
		(layer "In13.Cu")
		(net "M_B_CPU1_SB_DQ<24>")
	)
	(segment
		(start 69.620638 -299.572172)
		(end 69.435472 -299.757338)
		(width 0.14478)
		(layer "In13.Cu")
		(net "M_B_CPU1_SB_DQ<24>")
	)
	(segment
		(start 54.548786 -310.307482)
		(end 54.341268 -310.099964)
		(width 0.14478)
		(layer "In13.Cu")
		(net "M_B_CPU1_SB_DQ<24>")
	)
	(segment
		(start 58.509408 -308.855364)
		(end 58.071766 -309.293006)
		(width 0.14478)
		(layer "In13.Cu")
		(net "M_B_CPU1_SB_DQ<24>")
	)
	(segment
		(start 65.578736 -304.108104)
		(end 65.393316 -304.293524)
		(width 0.14478)
		(layer "In13.Cu")
		(net "M_B_CPU1_SB_DQ<24>")
	)
	(segment
		(start 53.947822 -309.476394)
		(end 53.717698 -309.476394)
		(width 0.14478)
		(layer "In13.Cu")
		(net "M_B_CPU1_SB_DQ<24>")
	)
	(segment
		(start 64.798956 -304.887884)
		(end 64.613536 -305.073304)
		(width 0.14478)
		(layer "In13.Cu")
		(net "M_B_CPU1_SB_DQ<24>")
	)
	(segment
		(start 66.952876 -302.733964)
		(end 66.74866 -302.73371)
		(width 0.14478)
		(layer "In13.Cu")
		(net "M_B_CPU1_SB_DQ<24>")
	)
	(segment
		(start 67.096132 -302.096678)
		(end 67.095878 -302.301402)
		(width 0.14478)
		(layer "In13.Cu")
		(net "M_B_CPU1_SB_DQ<24>")
	)
	(segment
		(start 70.071996 -299.614844)
		(end 69.86778 -299.61459)
		(width 0.14478)
		(layer "In13.Cu")
		(net "M_B_CPU1_SB_DQ<24>")
	)
	(segment
		(start 64.798956 -304.68316)
		(end 64.798956 -304.887884)
		(width 0.14478)
		(layer "In13.Cu")
		(net "M_B_CPU1_SB_DQ<24>")
	)
	(segment
		(start 65.536572 -303.656238)
		(end 65.536318 -303.860962)
		(width 0.14478)
		(layer "In13.Cu")
		(net "M_B_CPU1_SB_DQ<24>")
	)
	(segment
		(start 83.598004 -288.988754)
		(end 83.589622 -288.99358)
		(width 0.0889)
		(layer "In13.Cu")
		(net "M_B_CPU1_SB_DQ<24>")
	)
	(segment
		(start 68.697856 -300.78426)
		(end 68.697856 -300.988984)
		(width 0.14478)
		(layer "In13.Cu")
		(net "M_B_CPU1_SB_DQ<24>")
	)
	(segment
		(start 69.045582 -300.351952)
		(end 68.840858 -300.351952)
		(width 0.14478)
		(layer "In13.Cu")
		(net "M_B_CPU1_SB_DQ<24>")
	)
	(segment
		(start 69.292216 -300.394624)
		(end 69.088 -300.39437)
		(width 0.14478)
		(layer "In13.Cu")
		(net "M_B_CPU1_SB_DQ<24>")
	)
	(segment
		(start 54.341268 -310.099964)
		(end 54.341268 -309.86984)
		(width 0.14478)
		(layer "In13.Cu")
		(net "M_B_CPU1_SB_DQ<24>")
	)
	(segment
		(start 71.037196 -298.649644)
		(end 70.851776 -298.835064)
		(width 0.14478)
		(layer "In13.Cu")
		(net "M_B_CPU1_SB_DQ<24>")
	)
	(segment
		(start 66.173096 -303.513744)
		(end 65.96888 -303.51349)
		(width 0.14478)
		(layer "In13.Cu")
		(net "M_B_CPU1_SB_DQ<24>")
	)
	(segment
		(start 70.995032 -298.197778)
		(end 70.994778 -298.402502)
		(width 0.14478)
		(layer "In13.Cu")
		(net "M_B_CPU1_SB_DQ<24>")
	)
	(segment
		(start 57.087516 -310.032908)
		(end 56.812942 -310.307482)
		(width 0.14478)
		(layer "In13.Cu")
		(net "M_B_CPU1_SB_DQ<24>")
	)
	(segment
		(start 67.918076 -301.768764)
		(end 67.732656 -301.954184)
		(width 0.14478)
		(layer "In13.Cu")
		(net "M_B_CPU1_SB_DQ<24>")
	)
	(segment
		(start 86.052406 -288.99358)
		(end 86.044024 -288.988754)
		(width 0.0889)
		(layer "In13.Cu")
		(net "M_B_CPU1_SB_DQ<24>")
	)
	(segment
		(start 70.851776 -298.835064)
		(end 70.64756 -298.83481)
		(width 0.14478)
		(layer "In13.Cu")
		(net "M_B_CPU1_SB_DQ<24>")
	)
	(segment
		(start 68.655438 -300.741842)
		(end 68.697856 -300.78426)
		(width 0.14478)
		(layer "In13.Cu")
		(net "M_B_CPU1_SB_DQ<24>")
	)
	(segment
		(start 59.065668 -309.11038)
		(end 58.810652 -308.855364)
		(width 0.14478)
		(layer "In13.Cu")
		(net "M_B_CPU1_SB_DQ<24>")
	)
	(segment
		(start 76.70927 -290.50488)
		(end 76.70927 -291.157406)
		(width 0.0889)
		(layer "In13.Cu")
		(net "M_B_CPU1_SB_DQ<24>")
	)
	(segment
		(start 56.419496 -310.144668)
		(end 56.419496 -309.734204)
		(width 0.14478)
		(layer "In13.Cu")
		(net "M_B_CPU1_SB_DQ<24>")
	)
	(segment
		(start 66.316352 -302.876458)
		(end 66.316098 -303.081182)
		(width 0.14478)
		(layer "In13.Cu")
		(net "M_B_CPU1_SB_DQ<24>")
	)
	(segment
		(start 67.732656 -301.954184)
		(end 67.52844 -301.95393)
		(width 0.14478)
		(layer "In13.Cu")
		(net "M_B_CPU1_SB_DQ<24>")
	)
	(segment
		(start 65.1891 -304.29327)
		(end 65.146682 -304.250852)
		(width 0.14478)
		(layer "In13.Cu")
		(net "M_B_CPU1_SB_DQ<24>")
	)
	(segment
		(start 65.393316 -304.293524)
		(end 65.1891 -304.29327)
		(width 0.14478)
		(layer "In13.Cu")
		(net "M_B_CPU1_SB_DQ<24>")
	)
	(segment
		(start 54.368954 -309.285386)
		(end 54.13883 -309.285386)
		(width 0.14478)
		(layer "In13.Cu")
		(net "M_B_CPU1_SB_DQ<24>")
	)
	(segment
		(start 67.281298 -301.911512)
		(end 67.096132 -302.096678)
		(width 0.14478)
		(layer "In13.Cu")
		(net "M_B_CPU1_SB_DQ<24>")
	)
	(segment
		(start 70.994778 -298.402502)
		(end 71.037196 -298.44492)
		(width 0.14478)
		(layer "In13.Cu")
		(net "M_B_CPU1_SB_DQ<24>")
	)
	(segment
		(start 69.477636 -300.00448)
		(end 69.477636 -300.209204)
		(width 0.14478)
		(layer "In13.Cu")
		(net "M_B_CPU1_SB_DQ<24>")
	)
	(arc
		(start 83.223862 -288.988754)
		(mid 82.940906 -288.912577)
		(end 82.65795 -288.988754)
		(width 0.0889)
		(layer "In13.Cu")
		(net "M_B_CPU1_SB_DQ<24>")
	)
	(arc
		(start 80.403954 -288.988754)
		(mid 80.120998 -288.912577)
		(end 79.838042 -288.988754)
		(width 0.0889)
		(layer "In13.Cu")
		(net "M_B_CPU1_SB_DQ<24>")
	)
	(arc
		(start 82.284062 -288.988754)
		(mid 82.001106 -288.912577)
		(end 81.71815 -288.988754)
		(width 0.0889)
		(layer "In13.Cu")
		(net "M_B_CPU1_SB_DQ<24>")
	)
	(arc
		(start 87.357966 -288.988754)
		(mid 87.171022 -289.039009)
		(end 86.984078 -288.988754)
		(width 0.0889)
		(layer "In13.Cu")
		(net "M_B_CPU1_SB_DQ<24>")
	)
	(arc
		(start 86.418166 -288.988754)
		(mid 86.235915 -289.039104)
		(end 86.052406 -288.99358)
		(width 0.0889)
		(layer "In13.Cu")
		(net "M_B_CPU1_SB_DQ<24>")
	)
	(arc
		(start 79.463646 -288.988754)
		(mid 79.189791 -288.912404)
		(end 78.913482 -288.979356)
		(width 0.0889)
		(layer "In13.Cu")
		(net "M_B_CPU1_SB_DQ<24>")
	)
	(arc
		(start 78.897734 -288.9885)
		(mid 78.807625 -289.026294)
		(end 78.71079 -289.0393)
		(width 0.0889)
		(layer "In13.Cu")
		(net "M_B_CPU1_SB_DQ<24>")
	)
	(arc
		(start 86.984078 -288.988754)
		(mid 86.701122 -288.912577)
		(end 86.418166 -288.988754)
		(width 0.0889)
		(layer "In13.Cu")
		(net "M_B_CPU1_SB_DQ<24>")
	)
	(arc
		(start 87.860632 -288.957004)
		(mid 87.605567 -288.913653)
		(end 87.357966 -288.988754)
		(width 0.0889)
		(layer "In13.Cu")
		(net "M_B_CPU1_SB_DQ<24>")
	)
	(arc
		(start 81.344008 -288.988754)
		(mid 81.061052 -288.912577)
		(end 80.778096 -288.988754)
		(width 0.0889)
		(layer "In13.Cu")
		(net "M_B_CPU1_SB_DQ<24>")
	)
	(arc
		(start 84.529676 -288.99358)
		(mid 84.346168 -289.039074)
		(end 84.163916 -288.988754)
		(width 0.0889)
		(layer "In13.Cu")
		(net "M_B_CPU1_SB_DQ<24>")
	)
	(arc
		(start 82.65795 -288.988754)
		(mid 82.471006 -289.039009)
		(end 82.284062 -288.988754)
		(width 0.0889)
		(layer "In13.Cu")
		(net "M_B_CPU1_SB_DQ<24>")
	)
	(arc
		(start 86.044024 -288.988754)
		(mid 85.761068 -288.912577)
		(end 85.478112 -288.988754)
		(width 0.0889)
		(layer "In13.Cu")
		(net "M_B_CPU1_SB_DQ<24>")
	)
	(arc
		(start 85.478112 -288.988754)
		(mid 85.295861 -289.039104)
		(end 85.112352 -288.99358)
		(width 0.0889)
		(layer "In13.Cu")
		(net "M_B_CPU1_SB_DQ<24>")
	)
	(arc
		(start 83.589622 -288.99358)
		(mid 83.406114 -289.039074)
		(end 83.223862 -288.988754)
		(width 0.0889)
		(layer "In13.Cu")
		(net "M_B_CPU1_SB_DQ<24>")
	)
	(arc
		(start 85.10397 -288.988754)
		(mid 84.821014 -288.912577)
		(end 84.538058 -288.988754)
		(width 0.0889)
		(layer "In13.Cu")
		(net "M_B_CPU1_SB_DQ<24>")
	)
	(arc
		(start 84.163916 -288.988754)
		(mid 83.88096 -288.912577)
		(end 83.598004 -288.988754)
		(width 0.0889)
		(layer "In13.Cu")
		(net "M_B_CPU1_SB_DQ<24>")
	)
	(arc
		(start 80.769714 -288.99358)
		(mid 80.586206 -289.039074)
		(end 80.403954 -288.988754)
		(width 0.0889)
		(layer "In13.Cu")
		(net "M_B_CPU1_SB_DQ<24>")
	)
	(arc
		(start 79.826358 -288.995612)
		(mid 79.644103 -289.039265)
		(end 79.463646 -288.988754)
		(width 0.0889)
		(layer "In13.Cu")
		(net "M_B_CPU1_SB_DQ<24>")
	)
	(arc
		(start 81.71815 -288.988754)
		(mid 81.535899 -289.039104)
		(end 81.35239 -288.99358)
		(width 0.0889)
		(layer "In13.Cu")
		(net "M_B_CPU1_SB_DQ<24>")
	)
	(segment
		(start 89.517982 -288.400236)
		(end 89.05113 -288.666174)
		(width 0.10668)
		(layer "F.Cu")
		(net "M_B_CPU1_SB_DQ<23>")
	)
	(segment
		(start 84.529676 -288.339022)
		(end 84.538058 -288.343848)
		(width 0.0889)
		(layer "In13.Cu")
		(net "M_B_CPU1_SB_DQ<23>")
	)
	(segment
		(start 77.62875 -289.031426)
		(end 78.239874 -288.420302)
		(width 0.0889)
		(layer "In13.Cu")
		(net "M_B_CPU1_SB_DQ<23>")
	)
	(segment
		(start 53.743606 -308.715156)
		(end 57.81929 -308.715156)
		(width 0.14478)
		(layer "In13.Cu")
		(net "M_B_CPU1_SB_DQ<23>")
	)
	(segment
		(start 52.740052 -308.260242)
		(end 53.67655 -308.6481)
		(width 0.14478)
		(layer "In13.Cu")
		(net "M_B_CPU1_SB_DQ<23>")
	)
	(segment
		(start 57.81929 -308.715156)
		(end 58.20664 -308.389528)
		(width 0.14478)
		(layer "In13.Cu")
		(net "M_B_CPU1_SB_DQ<23>")
	)
	(segment
		(start 58.20664 -308.389528)
		(end 58.560462 -308.217824)
		(width 0.14478)
		(layer "In13.Cu")
		(net "M_B_CPU1_SB_DQ<23>")
	)
	(segment
		(start 70.961758 -297.451526)
		(end 70.961758 -296.071798)
		(width 0.14478)
		(layer "In13.Cu")
		(net "M_B_CPU1_SB_DQ<23>")
	)
	(segment
		(start 83.589622 -288.339022)
		(end 83.598004 -288.343848)
		(width 0.0889)
		(layer "In13.Cu")
		(net "M_B_CPU1_SB_DQ<23>")
	)
	(segment
		(start 53.67655 -308.6481)
		(end 53.743606 -308.715156)
		(width 0.14478)
		(layer "In13.Cu")
		(net "M_B_CPU1_SB_DQ<23>")
	)
	(segment
		(start 70.961758 -296.071798)
		(end 75.865736 -291.16782)
		(width 0.14478)
		(layer "In13.Cu")
		(net "M_B_CPU1_SB_DQ<23>")
	)
	(segment
		(start 79.82966 -288.339022)
		(end 79.838042 -288.343848)
		(width 0.0889)
		(layer "In13.Cu")
		(net "M_B_CPU1_SB_DQ<23>")
	)
	(segment
		(start 47.784004 -308.685438)
		(end 51.702462 -308.260242)
		(width 0.14478)
		(layer "In13.Cu")
		(net "M_B_CPU1_SB_DQ<23>")
	)
	(segment
		(start 88.289638 -288.339022)
		(end 88.29802 -288.343848)
		(width 0.0889)
		(layer "In13.Cu")
		(net "M_B_CPU1_SB_DQ<23>")
	)
	(segment
		(start 77.62875 -289.315906)
		(end 77.62875 -289.031426)
		(width 0.0889)
		(layer "In13.Cu")
		(net "M_B_CPU1_SB_DQ<23>")
	)
	(segment
		(start 76.411836 -290.62172)
		(end 76.411836 -290.53282)
		(width 0.0889)
		(layer "In13.Cu")
		(net "M_B_CPU1_SB_DQ<23>")
	)
	(segment
		(start 89.205054 -288.400744)
		(end 89.05113 -288.666174)
		(width 0.0889)
		(layer "In13.Cu")
		(net "M_B_CPU1_SB_DQ<23>")
	)
	(segment
		(start 85.10397 -288.343848)
		(end 85.112352 -288.339022)
		(width 0.0889)
		(layer "In13.Cu")
		(net "M_B_CPU1_SB_DQ<23>")
	)
	(segment
		(start 80.769714 -288.339022)
		(end 80.778096 -288.343848)
		(width 0.0889)
		(layer "In13.Cu")
		(net "M_B_CPU1_SB_DQ<23>")
	)
	(segment
		(start 78.886304 -288.33699)
		(end 78.897988 -288.343848)
		(width 0.0889)
		(layer "In13.Cu")
		(net "M_B_CPU1_SB_DQ<23>")
	)
	(segment
		(start 76.411836 -290.53282)
		(end 77.62875 -289.315906)
		(width 0.0889)
		(layer "In13.Cu")
		(net "M_B_CPU1_SB_DQ<23>")
	)
	(segment
		(start 51.702462 -308.260242)
		(end 52.740052 -308.260242)
		(width 0.14478)
		(layer "In13.Cu")
		(net "M_B_CPU1_SB_DQ<23>")
	)
	(segment
		(start 60.836302 -307.576982)
		(end 70.961758 -297.451526)
		(width 0.14478)
		(layer "In13.Cu")
		(net "M_B_CPU1_SB_DQ<23>")
	)
	(segment
		(start 86.044024 -288.343848)
		(end 86.052406 -288.339022)
		(width 0.0889)
		(layer "In13.Cu")
		(net "M_B_CPU1_SB_DQ<23>")
	)
	(segment
		(start 58.560462 -308.217824)
		(end 60.03671 -307.913024)
		(width 0.14478)
		(layer "In13.Cu")
		(net "M_B_CPU1_SB_DQ<23>")
	)
	(segment
		(start 75.865736 -291.16782)
		(end 76.411836 -290.62172)
		(width 0.0889)
		(layer "In13.Cu")
		(net "M_B_CPU1_SB_DQ<23>")
	)
	(segment
		(start 81.344008 -288.343848)
		(end 81.35239 -288.339022)
		(width 0.0889)
		(layer "In13.Cu")
		(net "M_B_CPU1_SB_DQ<23>")
	)
	(segment
		(start 89.182702 -288.317686)
		(end 89.205054 -288.400744)
		(width 0.0889)
		(layer "In13.Cu")
		(net "M_B_CPU1_SB_DQ<23>")
	)
	(segment
		(start 60.03671 -307.913024)
		(end 60.836302 -307.576982)
		(width 0.14478)
		(layer "In13.Cu")
		(net "M_B_CPU1_SB_DQ<23>")
	)
	(arc
		(start 84.538058 -288.343848)
		(mid 84.821014 -288.420025)
		(end 85.10397 -288.343848)
		(width 0.0889)
		(layer "In13.Cu")
		(net "M_B_CPU1_SB_DQ<23>")
	)
	(arc
		(start 88.863932 -288.343848)
		(mid 89.02037 -288.294843)
		(end 89.182702 -288.317686)
		(width 0.0889)
		(layer "In13.Cu")
		(net "M_B_CPU1_SB_DQ<23>")
	)
	(arc
		(start 80.778096 -288.343848)
		(mid 81.061052 -288.420025)
		(end 81.344008 -288.343848)
		(width 0.0889)
		(layer "In13.Cu")
		(net "M_B_CPU1_SB_DQ<23>")
	)
	(arc
		(start 79.4639 -288.343848)
		(mid 79.646151 -288.293464)
		(end 79.82966 -288.339022)
		(width 0.0889)
		(layer "In13.Cu")
		(net "M_B_CPU1_SB_DQ<23>")
	)
	(arc
		(start 85.478112 -288.343848)
		(mid 85.761068 -288.420025)
		(end 86.044024 -288.343848)
		(width 0.0889)
		(layer "In13.Cu")
		(net "M_B_CPU1_SB_DQ<23>")
	)
	(arc
		(start 81.71815 -288.343848)
		(mid 82.001106 -288.420025)
		(end 82.284062 -288.343848)
		(width 0.0889)
		(layer "In13.Cu")
		(net "M_B_CPU1_SB_DQ<23>")
	)
	(arc
		(start 85.112352 -288.339022)
		(mid 85.29586 -288.293497)
		(end 85.478112 -288.343848)
		(width 0.0889)
		(layer "In13.Cu")
		(net "M_B_CPU1_SB_DQ<23>")
	)
	(arc
		(start 79.838042 -288.343848)
		(mid 80.120998 -288.420025)
		(end 80.403954 -288.343848)
		(width 0.0889)
		(layer "In13.Cu")
		(net "M_B_CPU1_SB_DQ<23>")
	)
	(arc
		(start 87.923878 -288.343848)
		(mid 88.106129 -288.293464)
		(end 88.289638 -288.339022)
		(width 0.0889)
		(layer "In13.Cu")
		(net "M_B_CPU1_SB_DQ<23>")
	)
	(arc
		(start 86.418166 -288.343848)
		(mid 86.701122 -288.420025)
		(end 86.984078 -288.343848)
		(width 0.0889)
		(layer "In13.Cu")
		(net "M_B_CPU1_SB_DQ<23>")
	)
	(arc
		(start 86.984078 -288.343848)
		(mid 87.171022 -288.293559)
		(end 87.357966 -288.343848)
		(width 0.0889)
		(layer "In13.Cu")
		(net "M_B_CPU1_SB_DQ<23>")
	)
	(arc
		(start 80.403954 -288.343848)
		(mid 80.586205 -288.293464)
		(end 80.769714 -288.339022)
		(width 0.0889)
		(layer "In13.Cu")
		(net "M_B_CPU1_SB_DQ<23>")
	)
	(arc
		(start 81.35239 -288.339022)
		(mid 81.535898 -288.293497)
		(end 81.71815 -288.343848)
		(width 0.0889)
		(layer "In13.Cu")
		(net "M_B_CPU1_SB_DQ<23>")
	)
	(arc
		(start 88.29802 -288.343848)
		(mid 88.580976 -288.420025)
		(end 88.863932 -288.343848)
		(width 0.0889)
		(layer "In13.Cu")
		(net "M_B_CPU1_SB_DQ<23>")
	)
	(arc
		(start 84.163916 -288.343848)
		(mid 84.346167 -288.293464)
		(end 84.529676 -288.339022)
		(width 0.0889)
		(layer "In13.Cu")
		(net "M_B_CPU1_SB_DQ<23>")
	)
	(arc
		(start 78.523592 -288.343848)
		(mid 78.70405 -288.293369)
		(end 78.886304 -288.33699)
		(width 0.0889)
		(layer "In13.Cu")
		(net "M_B_CPU1_SB_DQ<23>")
	)
	(arc
		(start 82.65795 -288.343848)
		(mid 82.940906 -288.420025)
		(end 83.223862 -288.343848)
		(width 0.0889)
		(layer "In13.Cu")
		(net "M_B_CPU1_SB_DQ<23>")
	)
	(arc
		(start 82.284062 -288.343848)
		(mid 82.471006 -288.293559)
		(end 82.65795 -288.343848)
		(width 0.0889)
		(layer "In13.Cu")
		(net "M_B_CPU1_SB_DQ<23>")
	)
	(arc
		(start 86.052406 -288.339022)
		(mid 86.235914 -288.293497)
		(end 86.418166 -288.343848)
		(width 0.0889)
		(layer "In13.Cu")
		(net "M_B_CPU1_SB_DQ<23>")
	)
	(arc
		(start 78.897988 -288.343848)
		(mid 79.180944 -288.420025)
		(end 79.4639 -288.343848)
		(width 0.0889)
		(layer "In13.Cu")
		(net "M_B_CPU1_SB_DQ<23>")
	)
	(arc
		(start 87.357966 -288.343848)
		(mid 87.640922 -288.420025)
		(end 87.923878 -288.343848)
		(width 0.0889)
		(layer "In13.Cu")
		(net "M_B_CPU1_SB_DQ<23>")
	)
	(arc
		(start 83.223862 -288.343848)
		(mid 83.406113 -288.293464)
		(end 83.589622 -288.339022)
		(width 0.0889)
		(layer "In13.Cu")
		(net "M_B_CPU1_SB_DQ<23>")
	)
	(arc
		(start 83.598004 -288.343848)
		(mid 83.88096 -288.420025)
		(end 84.163916 -288.343848)
		(width 0.0889)
		(layer "In13.Cu")
		(net "M_B_CPU1_SB_DQ<23>")
	)
	(arc
		(start 78.239874 -288.420302)
		(mid 78.386805 -288.400891)
		(end 78.523592 -288.343848)
		(width 0.0889)
		(layer "In13.Cu")
		(net "M_B_CPU1_SB_DQ<23>")
	)
	(segment
		(start 88.107774 -287.590484)
		(end 87.640922 -287.856422)
		(width 0.10668)
		(layer "F.Cu")
		(net "M_B_CPU1_SB_DQ<22>")
	)
	(segment
		(start 77.329284 -288.150046)
		(end 77.869288 -287.610042)
		(width 0.0889)
		(layer "In13.Cu")
		(net "M_B_CPU1_SB_DQ<22>")
	)
	(segment
		(start 79.367888 -287.533842)
		(end 79.385922 -287.544256)
		(width 0.0889)
		(layer "In13.Cu")
		(net "M_B_CPU1_SB_DQ<22>")
	)
	(segment
		(start 77.242416 -288.150046)
		(end 77.329284 -288.150046)
		(width 0.0889)
		(layer "In13.Cu")
		(net "M_B_CPU1_SB_DQ<22>")
	)
	(segment
		(start 87.772748 -287.50768)
		(end 87.7951 -287.590992)
		(width 0.0889)
		(layer "In13.Cu")
		(net "M_B_CPU1_SB_DQ<22>")
	)
	(segment
		(start 49.600104 -306.985416)
		(end 50.542952 -306.985416)
		(width 0.14478)
		(layer "In13.Cu")
		(net "M_B_CPU1_SB_DQ<22>")
	)
	(segment
		(start 76.42987 -289.220402)
		(end 76.42987 -288.962592)
		(width 0.0889)
		(layer "In13.Cu")
		(net "M_B_CPU1_SB_DQ<22>")
	)
	(segment
		(start 77.869288 -287.610042)
		(end 78.711044 -287.610042)
		(width 0.0889)
		(layer "In13.Cu")
		(net "M_B_CPU1_SB_DQ<22>")
	)
	(segment
		(start 52.030884 -306.56022)
		(end 54.083458 -307.410358)
		(width 0.14478)
		(layer "In13.Cu")
		(net "M_B_CPU1_SB_DQ<22>")
	)
	(segment
		(start 82.753962 -287.533842)
		(end 82.762344 -287.529016)
		(width 0.0889)
		(layer "In13.Cu")
		(net "M_B_CPU1_SB_DQ<22>")
	)
	(segment
		(start 48.759364 -306.985416)
		(end 48.904144 -307.130196)
		(width 0.14478)
		(layer "In13.Cu")
		(net "M_B_CPU1_SB_DQ<22>")
	)
	(segment
		(start 47.784004 -306.985416)
		(end 48.759364 -306.985416)
		(width 0.14478)
		(layer "In13.Cu")
		(net "M_B_CPU1_SB_DQ<22>")
	)
	(segment
		(start 60.282582 -306.56022)
		(end 70.062598 -296.780204)
		(width 0.14478)
		(layer "In13.Cu")
		(net "M_B_CPU1_SB_DQ<22>")
	)
	(segment
		(start 83.694016 -287.533842)
		(end 83.702398 -287.529016)
		(width 0.0889)
		(layer "In13.Cu")
		(net "M_B_CPU1_SB_DQ<22>")
	)
	(segment
		(start 48.904144 -307.130196)
		(end 48.904144 -307.24602)
		(width 0.14478)
		(layer "In13.Cu")
		(net "M_B_CPU1_SB_DQ<22>")
	)
	(segment
		(start 87.453978 -287.533842)
		(end 87.46236 -287.529016)
		(width 0.0889)
		(layer "In13.Cu")
		(net "M_B_CPU1_SB_DQ<22>")
	)
	(segment
		(start 85.948012 -287.533842)
		(end 85.948266 -287.533842)
		(width 0.0889)
		(layer "In13.Cu")
		(net "M_B_CPU1_SB_DQ<22>")
	)
	(segment
		(start 58.279792 -306.56022)
		(end 60.282582 -306.56022)
		(width 0.14478)
		(layer "In13.Cu")
		(net "M_B_CPU1_SB_DQ<22>")
	)
	(segment
		(start 48.904144 -307.24602)
		(end 49.048924 -307.3908)
		(width 0.14478)
		(layer "In13.Cu")
		(net "M_B_CPU1_SB_DQ<22>")
	)
	(segment
		(start 50.968148 -306.56022)
		(end 52.030884 -306.56022)
		(width 0.14478)
		(layer "In13.Cu")
		(net "M_B_CPU1_SB_DQ<22>")
	)
	(segment
		(start 50.542952 -306.985416)
		(end 50.968148 -306.56022)
		(width 0.14478)
		(layer "In13.Cu")
		(net "M_B_CPU1_SB_DQ<22>")
	)
	(segment
		(start 86.879684 -287.529016)
		(end 86.888066 -287.533842)
		(width 0.0889)
		(layer "In13.Cu")
		(net "M_B_CPU1_SB_DQ<22>")
	)
	(segment
		(start 57.429654 -307.410358)
		(end 58.279792 -306.56022)
		(width 0.14478)
		(layer "In13.Cu")
		(net "M_B_CPU1_SB_DQ<22>")
	)
	(segment
		(start 49.310544 -307.3908)
		(end 49.455324 -307.24602)
		(width 0.14478)
		(layer "In13.Cu")
		(net "M_B_CPU1_SB_DQ<22>")
	)
	(segment
		(start 85.93963 -287.529016)
		(end 85.948012 -287.533842)
		(width 0.0889)
		(layer "In13.Cu")
		(net "M_B_CPU1_SB_DQ<22>")
	)
	(segment
		(start 49.455324 -307.24602)
		(end 49.455324 -307.130196)
		(width 0.14478)
		(layer "In13.Cu")
		(net "M_B_CPU1_SB_DQ<22>")
	)
	(segment
		(start 70.062598 -295.587674)
		(end 75.950318 -289.699954)
		(width 0.14478)
		(layer "In13.Cu")
		(net "M_B_CPU1_SB_DQ<22>")
	)
	(segment
		(start 76.42987 -288.962592)
		(end 77.242416 -288.150046)
		(width 0.0889)
		(layer "In13.Cu")
		(net "M_B_CPU1_SB_DQ<22>")
	)
	(segment
		(start 49.048924 -307.3908)
		(end 49.310544 -307.3908)
		(width 0.14478)
		(layer "In13.Cu")
		(net "M_B_CPU1_SB_DQ<22>")
	)
	(segment
		(start 75.950318 -289.699954)
		(end 76.42987 -289.220402)
		(width 0.0889)
		(layer "In13.Cu")
		(net "M_B_CPU1_SB_DQ<22>")
	)
	(segment
		(start 54.083458 -307.410358)
		(end 57.429654 -307.410358)
		(width 0.14478)
		(layer "In13.Cu")
		(net "M_B_CPU1_SB_DQ<22>")
	)
	(segment
		(start 49.455324 -307.130196)
		(end 49.600104 -306.985416)
		(width 0.14478)
		(layer "In13.Cu")
		(net "M_B_CPU1_SB_DQ<22>")
	)
	(segment
		(start 80.299814 -287.529016)
		(end 80.308196 -287.533842)
		(width 0.0889)
		(layer "In13.Cu")
		(net "M_B_CPU1_SB_DQ<22>")
	)
	(segment
		(start 87.7951 -287.590992)
		(end 87.640922 -287.856422)
		(width 0.0889)
		(layer "In13.Cu")
		(net "M_B_CPU1_SB_DQ<22>")
	)
	(segment
		(start 82.179668 -287.529016)
		(end 82.18805 -287.533842)
		(width 0.0889)
		(layer "In13.Cu")
		(net "M_B_CPU1_SB_DQ<22>")
	)
	(segment
		(start 70.062598 -296.780204)
		(end 70.062598 -295.587674)
		(width 0.14478)
		(layer "In13.Cu")
		(net "M_B_CPU1_SB_DQ<22>")
	)
	(arc
		(start 83.128104 -287.533842)
		(mid 83.41106 -287.609985)
		(end 83.694016 -287.533842)
		(width 0.0889)
		(layer "In13.Cu")
		(net "M_B_CPU1_SB_DQ<22>")
	)
	(arc
		(start 84.63407 -287.533842)
		(mid 84.821014 -287.483587)
		(end 85.007958 -287.533842)
		(width 0.0889)
		(layer "In13.Cu")
		(net "M_B_CPU1_SB_DQ<22>")
	)
	(arc
		(start 79.933546 -287.533842)
		(mid 80.116051 -287.483365)
		(end 80.299814 -287.529016)
		(width 0.0889)
		(layer "In13.Cu")
		(net "M_B_CPU1_SB_DQ<22>")
	)
	(arc
		(start 84.068158 -287.533842)
		(mid 84.351114 -287.609985)
		(end 84.63407 -287.533842)
		(width 0.0889)
		(layer "In13.Cu")
		(net "M_B_CPU1_SB_DQ<22>")
	)
	(arc
		(start 82.762344 -287.529016)
		(mid 82.945852 -287.483522)
		(end 83.128104 -287.533842)
		(width 0.0889)
		(layer "In13.Cu")
		(net "M_B_CPU1_SB_DQ<22>")
	)
	(arc
		(start 78.994 -287.533842)
		(mid 79.180944 -287.483587)
		(end 79.367888 -287.533842)
		(width 0.0889)
		(layer "In13.Cu")
		(net "M_B_CPU1_SB_DQ<22>")
	)
	(arc
		(start 81.813908 -287.533842)
		(mid 81.996159 -287.483492)
		(end 82.179668 -287.529016)
		(width 0.0889)
		(layer "In13.Cu")
		(net "M_B_CPU1_SB_DQ<22>")
	)
	(arc
		(start 86.513924 -287.533842)
		(mid 86.696175 -287.483492)
		(end 86.879684 -287.529016)
		(width 0.0889)
		(layer "In13.Cu")
		(net "M_B_CPU1_SB_DQ<22>")
	)
	(arc
		(start 85.948266 -287.533842)
		(mid 86.231112 -287.609985)
		(end 86.513924 -287.533842)
		(width 0.0889)
		(layer "In13.Cu")
		(net "M_B_CPU1_SB_DQ<22>")
	)
	(arc
		(start 82.18805 -287.533842)
		(mid 82.471006 -287.609985)
		(end 82.753962 -287.533842)
		(width 0.0889)
		(layer "In13.Cu")
		(net "M_B_CPU1_SB_DQ<22>")
	)
	(arc
		(start 80.308196 -287.533842)
		(mid 80.591152 -287.609985)
		(end 80.874108 -287.533842)
		(width 0.0889)
		(layer "In13.Cu")
		(net "M_B_CPU1_SB_DQ<22>")
	)
	(arc
		(start 83.702398 -287.529016)
		(mid 83.885906 -287.483522)
		(end 84.068158 -287.533842)
		(width 0.0889)
		(layer "In13.Cu")
		(net "M_B_CPU1_SB_DQ<22>")
	)
	(arc
		(start 85.007958 -287.533842)
		(mid 85.290914 -287.609985)
		(end 85.57387 -287.533842)
		(width 0.0889)
		(layer "In13.Cu")
		(net "M_B_CPU1_SB_DQ<22>")
	)
	(arc
		(start 79.385922 -287.544256)
		(mid 79.66108 -287.609986)
		(end 79.933546 -287.533842)
		(width 0.0889)
		(layer "In13.Cu")
		(net "M_B_CPU1_SB_DQ<22>")
	)
	(arc
		(start 86.888066 -287.533842)
		(mid 87.171022 -287.609985)
		(end 87.453978 -287.533842)
		(width 0.0889)
		(layer "In13.Cu")
		(net "M_B_CPU1_SB_DQ<22>")
	)
	(arc
		(start 80.874108 -287.533842)
		(mid 81.061052 -287.483587)
		(end 81.247996 -287.533842)
		(width 0.0889)
		(layer "In13.Cu")
		(net "M_B_CPU1_SB_DQ<22>")
	)
	(arc
		(start 78.711044 -287.610042)
		(mid 78.85757 -287.590672)
		(end 78.994 -287.533842)
		(width 0.0889)
		(layer "In13.Cu")
		(net "M_B_CPU1_SB_DQ<22>")
	)
	(arc
		(start 87.46236 -287.529016)
		(mid 87.61523 -287.484375)
		(end 87.772748 -287.50768)
		(width 0.0889)
		(layer "In13.Cu")
		(net "M_B_CPU1_SB_DQ<22>")
	)
	(arc
		(start 85.57387 -287.533842)
		(mid 85.756121 -287.483492)
		(end 85.93963 -287.529016)
		(width 0.0889)
		(layer "In13.Cu")
		(net "M_B_CPU1_SB_DQ<22>")
	)
	(arc
		(start 81.247996 -287.533842)
		(mid 81.530952 -287.609985)
		(end 81.813908 -287.533842)
		(width 0.0889)
		(layer "In13.Cu")
		(net "M_B_CPU1_SB_DQ<22>")
	)
	(segment
		(start 89.987882 -287.590484)
		(end 89.52103 -287.856422)
		(width 0.10668)
		(layer "F.Cu")
		(net "M_B_CPU1_SB_DQ<21>")
	)
	(segment
		(start 66.837052 -300.642274)
		(end 67.078098 -300.401228)
		(width 0.14478)
		(layer "In13.Cu")
		(net "M_B_CPU1_SB_DQ<21>")
	)
	(segment
		(start 62.158372 -305.320954)
		(end 62.399418 -305.079908)
		(width 0.14478)
		(layer "In13.Cu")
		(net "M_B_CPU1_SB_DQ<21>")
	)
	(segment
		(start 66.298318 -301.181008)
		(end 66.596006 -301.181008)
		(width 0.14478)
		(layer "In13.Cu")
		(net "M_B_CPU1_SB_DQ<21>")
	)
	(segment
		(start 66.596006 -301.181008)
		(end 66.837052 -300.939962)
		(width 0.14478)
		(layer "In13.Cu")
		(net "M_B_CPU1_SB_DQ<21>")
	)
	(segment
		(start 89.367106 -288.121852)
		(end 89.52103 -287.856422)
		(width 0.0889)
		(layer "In13.Cu")
		(net "M_B_CPU1_SB_DQ<21>")
	)
	(segment
		(start 64.497712 -302.981614)
		(end 64.738758 -302.740568)
		(width 0.14478)
		(layer "In13.Cu")
		(net "M_B_CPU1_SB_DQ<21>")
	)
	(segment
		(start 67.616832 -299.862494)
		(end 67.857878 -299.621448)
		(width 0.14478)
		(layer "In13.Cu")
		(net "M_B_CPU1_SB_DQ<21>")
	)
	(segment
		(start 66.057272 -301.422054)
		(end 66.298318 -301.181008)
		(width 0.14478)
		(layer "In13.Cu")
		(net "M_B_CPU1_SB_DQ<21>")
	)
	(segment
		(start 62.938152 -304.838862)
		(end 62.938152 -304.541174)
		(width 0.14478)
		(layer "In13.Cu")
		(net "M_B_CPU1_SB_DQ<21>")
	)
	(segment
		(start 56.174132 -307.859938)
		(end 56.435752 -307.859938)
		(width 0.14478)
		(layer "In13.Cu")
		(net "M_B_CPU1_SB_DQ<21>")
	)
	(segment
		(start 70.512178 -297.264836)
		(end 70.512178 -295.781222)
		(width 0.14478)
		(layer "In13.Cu")
		(net "M_B_CPU1_SB_DQ<21>")
	)
	(segment
		(start 76.71435 -289.026346)
		(end 77.40015 -288.340546)
		(width 0.0889)
		(layer "In13.Cu")
		(net "M_B_CPU1_SB_DQ<21>")
	)
	(segment
		(start 88.394032 -288.178748)
		(end 88.402414 -288.183574)
		(width 0.0889)
		(layer "In13.Cu")
		(net "M_B_CPU1_SB_DQ<21>")
	)
	(segment
		(start 63.717932 -303.761394)
		(end 63.958978 -303.520348)
		(width 0.14478)
		(layer "In13.Cu")
		(net "M_B_CPU1_SB_DQ<21>")
	)
	(segment
		(start 51.884072 -307.8353)
		(end 51.884072 -307.608732)
		(width 0.14478)
		(layer "In13.Cu")
		(net "M_B_CPU1_SB_DQ<21>")
	)
	(segment
		(start 63.958978 -303.520348)
		(end 64.256666 -303.520348)
		(width 0.14478)
		(layer "In13.Cu")
		(net "M_B_CPU1_SB_DQ<21>")
	)
	(segment
		(start 61.619638 -305.859688)
		(end 61.917326 -305.859688)
		(width 0.14478)
		(layer "In13.Cu")
		(net "M_B_CPU1_SB_DQ<21>")
	)
	(segment
		(start 83.694016 -288.178748)
		(end 83.702398 -288.183574)
		(width 0.0889)
		(layer "In13.Cu")
		(net "M_B_CPU1_SB_DQ<21>")
	)
	(segment
		(start 77.67193 -288.340546)
		(end 77.782674 -288.229802)
		(width 0.0889)
		(layer "In13.Cu")
		(net "M_B_CPU1_SB_DQ<21>")
	)
	(segment
		(start 66.057272 -301.719742)
		(end 66.057272 -301.422054)
		(width 0.14478)
		(layer "In13.Cu")
		(net "M_B_CPU1_SB_DQ<21>")
	)
	(segment
		(start 61.378592 -306.398422)
		(end 61.378592 -306.100734)
		(width 0.14478)
		(layer "In13.Cu")
		(net "M_B_CPU1_SB_DQ<21>")
	)
	(segment
		(start 60.988194 -306.78882)
		(end 61.378592 -306.398422)
		(width 0.14478)
		(layer "In13.Cu")
		(net "M_B_CPU1_SB_DQ<21>")
	)
	(segment
		(start 69.176392 -298.600622)
		(end 69.176392 -298.302934)
		(width 0.14478)
		(layer "In13.Cu")
		(net "M_B_CPU1_SB_DQ<21>")
	)
	(segment
		(start 53.312568 -307.69179)
		(end 54.163722 -308.260496)
		(width 0.14478)
		(layer "In13.Cu")
		(net "M_B_CPU1_SB_DQ<21>")
	)
	(segment
		(start 64.497712 -303.279302)
		(end 64.497712 -302.981614)
		(width 0.14478)
		(layer "In13.Cu")
		(net "M_B_CPU1_SB_DQ<21>")
	)
	(segment
		(start 85.948012 -288.178748)
		(end 85.948266 -288.178748)
		(width 0.0889)
		(layer "In13.Cu")
		(net "M_B_CPU1_SB_DQ<21>")
	)
	(segment
		(start 68.935346 -298.841668)
		(end 69.176392 -298.600622)
		(width 0.14478)
		(layer "In13.Cu")
		(net "M_B_CPU1_SB_DQ<21>")
	)
	(segment
		(start 75.95108 -290.34232)
		(end 76.71435 -289.57905)
		(width 0.0889)
		(layer "In13.Cu")
		(net "M_B_CPU1_SB_DQ<21>")
	)
	(segment
		(start 68.396612 -299.380402)
		(end 68.396612 -299.082714)
		(width 0.14478)
		(layer "In13.Cu")
		(net "M_B_CPU1_SB_DQ<21>")
	)
	(segment
		(start 65.036446 -302.740568)
		(end 65.277492 -302.499522)
		(width 0.14478)
		(layer "In13.Cu")
		(net "M_B_CPU1_SB_DQ<21>")
	)
	(segment
		(start 67.857878 -299.621448)
		(end 68.155566 -299.621448)
		(width 0.14478)
		(layer "In13.Cu")
		(net "M_B_CPU1_SB_DQ<21>")
	)
	(segment
		(start 52.565554 -307.382418)
		(end 53.312568 -307.69179)
		(width 0.14478)
		(layer "In13.Cu")
		(net "M_B_CPU1_SB_DQ<21>")
	)
	(segment
		(start 51.884072 -307.608732)
		(end 52.110386 -307.382418)
		(width 0.14478)
		(layer "In13.Cu")
		(net "M_B_CPU1_SB_DQ<21>")
	)
	(segment
		(start 77.40015 -288.340546)
		(end 77.67193 -288.340546)
		(width 0.0889)
		(layer "In13.Cu")
		(net "M_B_CPU1_SB_DQ<21>")
	)
	(segment
		(start 65.277492 -302.499522)
		(end 65.277492 -302.201834)
		(width 0.14478)
		(layer "In13.Cu")
		(net "M_B_CPU1_SB_DQ<21>")
	)
	(segment
		(start 63.717932 -304.059082)
		(end 63.717932 -303.761394)
		(width 0.14478)
		(layer "In13.Cu")
		(net "M_B_CPU1_SB_DQ<21>")
	)
	(segment
		(start 82.753962 -288.178748)
		(end 82.762344 -288.183574)
		(width 0.0889)
		(layer "In13.Cu")
		(net "M_B_CPU1_SB_DQ<21>")
	)
	(segment
		(start 79.934054 -288.178748)
		(end 79.942436 -288.183574)
		(width 0.0889)
		(layer "In13.Cu")
		(net "M_B_CPU1_SB_DQ<21>")
	)
	(segment
		(start 69.176392 -298.302934)
		(end 69.417438 -298.061888)
		(width 0.14478)
		(layer "In13.Cu")
		(net "M_B_CPU1_SB_DQ<21>")
	)
	(segment
		(start 62.938152 -304.541174)
		(end 63.179198 -304.300128)
		(width 0.14478)
		(layer "In13.Cu")
		(net "M_B_CPU1_SB_DQ<21>")
	)
	(segment
		(start 56.580532 -308.004718)
		(end 56.580532 -308.115716)
		(width 0.14478)
		(layer "In13.Cu")
		(net "M_B_CPU1_SB_DQ<21>")
	)
	(segment
		(start 65.277492 -302.201834)
		(end 65.518538 -301.960788)
		(width 0.14478)
		(layer "In13.Cu")
		(net "M_B_CPU1_SB_DQ<21>")
	)
	(segment
		(start 56.029352 -308.004718)
		(end 56.174132 -307.859938)
		(width 0.14478)
		(layer "In13.Cu")
		(net "M_B_CPU1_SB_DQ<21>")
	)
	(segment
		(start 68.155566 -299.621448)
		(end 68.396612 -299.380402)
		(width 0.14478)
		(layer "In13.Cu")
		(net "M_B_CPU1_SB_DQ<21>")
	)
	(segment
		(start 61.917326 -305.859688)
		(end 62.158372 -305.618642)
		(width 0.14478)
		(layer "In13.Cu")
		(net "M_B_CPU1_SB_DQ<21>")
	)
	(segment
		(start 67.375786 -300.401228)
		(end 67.616832 -300.160182)
		(width 0.14478)
		(layer "In13.Cu")
		(net "M_B_CPU1_SB_DQ<21>")
	)
	(segment
		(start 58.279792 -307.410358)
		(end 59.487562 -307.410358)
		(width 0.14478)
		(layer "In13.Cu")
		(net "M_B_CPU1_SB_DQ<21>")
	)
	(segment
		(start 70.512178 -295.781222)
		(end 75.95108 -290.34232)
		(width 0.14478)
		(layer "In13.Cu")
		(net "M_B_CPU1_SB_DQ<21>")
	)
	(segment
		(start 78.994 -288.178748)
		(end 79.002382 -288.183574)
		(width 0.0889)
		(layer "In13.Cu")
		(net "M_B_CPU1_SB_DQ<21>")
	)
	(segment
		(start 52.110386 -307.382418)
		(end 52.565554 -307.382418)
		(width 0.14478)
		(layer "In13.Cu")
		(net "M_B_CPU1_SB_DQ<21>")
	)
	(segment
		(start 56.725312 -308.260496)
		(end 57.429654 -308.260496)
		(width 0.14478)
		(layer "In13.Cu")
		(net "M_B_CPU1_SB_DQ<21>")
	)
	(segment
		(start 87.453978 -288.178748)
		(end 87.46236 -288.183574)
		(width 0.0889)
		(layer "In13.Cu")
		(net "M_B_CPU1_SB_DQ<21>")
	)
	(segment
		(start 78.979268 -288.170112)
		(end 78.994 -288.178748)
		(width 0.0889)
		(layer "In13.Cu")
		(net "M_B_CPU1_SB_DQ<21>")
	)
	(segment
		(start 63.476886 -304.300128)
		(end 63.717932 -304.059082)
		(width 0.14478)
		(layer "In13.Cu")
		(net "M_B_CPU1_SB_DQ<21>")
	)
	(segment
		(start 63.179198 -304.300128)
		(end 63.476886 -304.300128)
		(width 0.14478)
		(layer "In13.Cu")
		(net "M_B_CPU1_SB_DQ<21>")
	)
	(segment
		(start 54.163722 -308.260496)
		(end 55.884572 -308.260496)
		(width 0.14478)
		(layer "In13.Cu")
		(net "M_B_CPU1_SB_DQ<21>")
	)
	(segment
		(start 57.429654 -308.260496)
		(end 58.279792 -307.410358)
		(width 0.14478)
		(layer "In13.Cu")
		(net "M_B_CPU1_SB_DQ<21>")
	)
	(segment
		(start 65.816226 -301.960788)
		(end 66.057272 -301.719742)
		(width 0.14478)
		(layer "In13.Cu")
		(net "M_B_CPU1_SB_DQ<21>")
	)
	(segment
		(start 59.487562 -307.410358)
		(end 60.988194 -306.78882)
		(width 0.14478)
		(layer "In13.Cu")
		(net "M_B_CPU1_SB_DQ<21>")
	)
	(segment
		(start 62.158372 -305.618642)
		(end 62.158372 -305.320954)
		(width 0.14478)
		(layer "In13.Cu")
		(net "M_B_CPU1_SB_DQ<21>")
	)
	(segment
		(start 82.179668 -288.183574)
		(end 82.18805 -288.178748)
		(width 0.0889)
		(layer "In13.Cu")
		(net "M_B_CPU1_SB_DQ<21>")
	)
	(segment
		(start 69.715126 -298.061888)
		(end 70.512178 -297.264836)
		(width 0.14478)
		(layer "In13.Cu")
		(net "M_B_CPU1_SB_DQ<21>")
	)
	(segment
		(start 64.256666 -303.520348)
		(end 64.497712 -303.279302)
		(width 0.14478)
		(layer "In13.Cu")
		(net "M_B_CPU1_SB_DQ<21>")
	)
	(segment
		(start 69.417438 -298.061888)
		(end 69.715126 -298.061888)
		(width 0.14478)
		(layer "In13.Cu")
		(net "M_B_CPU1_SB_DQ<21>")
	)
	(segment
		(start 77.782674 -288.229802)
		(end 78.239874 -288.229802)
		(width 0.0889)
		(layer "In13.Cu")
		(net "M_B_CPU1_SB_DQ<21>")
	)
	(segment
		(start 56.580532 -308.115716)
		(end 56.725312 -308.260496)
		(width 0.14478)
		(layer "In13.Cu")
		(net "M_B_CPU1_SB_DQ<21>")
	)
	(segment
		(start 68.637658 -298.841668)
		(end 68.935346 -298.841668)
		(width 0.14478)
		(layer "In13.Cu")
		(net "M_B_CPU1_SB_DQ<21>")
	)
	(segment
		(start 89.271348 -288.147252)
		(end 89.367106 -288.121852)
		(width 0.0889)
		(layer "In13.Cu")
		(net "M_B_CPU1_SB_DQ<21>")
	)
	(segment
		(start 85.93963 -288.183574)
		(end 85.948012 -288.178748)
		(width 0.0889)
		(layer "In13.Cu")
		(net "M_B_CPU1_SB_DQ<21>")
	)
	(segment
		(start 62.399418 -305.079908)
		(end 62.697106 -305.079908)
		(width 0.14478)
		(layer "In13.Cu")
		(net "M_B_CPU1_SB_DQ<21>")
	)
	(segment
		(start 56.029352 -308.115716)
		(end 56.029352 -308.004718)
		(width 0.14478)
		(layer "In13.Cu")
		(net "M_B_CPU1_SB_DQ<21>")
	)
	(segment
		(start 67.616832 -300.160182)
		(end 67.616832 -299.862494)
		(width 0.14478)
		(layer "In13.Cu")
		(net "M_B_CPU1_SB_DQ<21>")
	)
	(segment
		(start 67.078098 -300.401228)
		(end 67.375786 -300.401228)
		(width 0.14478)
		(layer "In13.Cu")
		(net "M_B_CPU1_SB_DQ<21>")
	)
	(segment
		(start 66.837052 -300.939962)
		(end 66.837052 -300.642274)
		(width 0.14478)
		(layer "In13.Cu")
		(net "M_B_CPU1_SB_DQ<21>")
	)
	(segment
		(start 62.697106 -305.079908)
		(end 62.938152 -304.838862)
		(width 0.14478)
		(layer "In13.Cu")
		(net "M_B_CPU1_SB_DQ<21>")
	)
	(segment
		(start 86.879684 -288.183574)
		(end 86.888066 -288.178748)
		(width 0.0889)
		(layer "In13.Cu")
		(net "M_B_CPU1_SB_DQ<21>")
	)
	(segment
		(start 56.435752 -307.859938)
		(end 56.580532 -308.004718)
		(width 0.14478)
		(layer "In13.Cu")
		(net "M_B_CPU1_SB_DQ<21>")
	)
	(segment
		(start 55.884572 -308.260496)
		(end 56.029352 -308.115716)
		(width 0.14478)
		(layer "In13.Cu")
		(net "M_B_CPU1_SB_DQ<21>")
	)
	(segment
		(start 68.396612 -299.082714)
		(end 68.637658 -298.841668)
		(width 0.14478)
		(layer "In13.Cu")
		(net "M_B_CPU1_SB_DQ<21>")
	)
	(segment
		(start 61.378592 -306.100734)
		(end 61.619638 -305.859688)
		(width 0.14478)
		(layer "In13.Cu")
		(net "M_B_CPU1_SB_DQ<21>")
	)
	(segment
		(start 76.71435 -289.57905)
		(end 76.71435 -289.026346)
		(width 0.0889)
		(layer "In13.Cu")
		(net "M_B_CPU1_SB_DQ<21>")
	)
	(segment
		(start 65.518538 -301.960788)
		(end 65.816226 -301.960788)
		(width 0.14478)
		(layer "In13.Cu")
		(net "M_B_CPU1_SB_DQ<21>")
	)
	(segment
		(start 64.738758 -302.740568)
		(end 65.036446 -302.740568)
		(width 0.14478)
		(layer "In13.Cu")
		(net "M_B_CPU1_SB_DQ<21>")
	)
	(arc
		(start 84.068158 -288.178748)
		(mid 84.351114 -288.102571)
		(end 84.63407 -288.178748)
		(width 0.0889)
		(layer "In13.Cu")
		(net "M_B_CPU1_SB_DQ<21>")
	)
	(arc
		(start 81.247996 -288.178748)
		(mid 81.530952 -288.102571)
		(end 81.813908 -288.178748)
		(width 0.0889)
		(layer "In13.Cu")
		(net "M_B_CPU1_SB_DQ<21>")
	)
	(arc
		(start 79.368142 -288.178748)
		(mid 79.651098 -288.102571)
		(end 79.934054 -288.178748)
		(width 0.0889)
		(layer "In13.Cu")
		(net "M_B_CPU1_SB_DQ<21>")
	)
	(arc
		(start 87.46236 -288.183574)
		(mid 87.645868 -288.229099)
		(end 87.82812 -288.178748)
		(width 0.0889)
		(layer "In13.Cu")
		(net "M_B_CPU1_SB_DQ<21>")
	)
	(arc
		(start 78.239874 -288.229802)
		(mid 78.337105 -288.216705)
		(end 78.42758 -288.178748)
		(width 0.0889)
		(layer "In13.Cu")
		(net "M_B_CPU1_SB_DQ<21>")
	)
	(arc
		(start 80.874108 -288.178748)
		(mid 81.061052 -288.229037)
		(end 81.247996 -288.178748)
		(width 0.0889)
		(layer "In13.Cu")
		(net "M_B_CPU1_SB_DQ<21>")
	)
	(arc
		(start 79.002382 -288.183574)
		(mid 79.18589 -288.229099)
		(end 79.368142 -288.178748)
		(width 0.0889)
		(layer "In13.Cu")
		(net "M_B_CPU1_SB_DQ<21>")
	)
	(arc
		(start 82.762344 -288.183574)
		(mid 82.945852 -288.229099)
		(end 83.128104 -288.178748)
		(width 0.0889)
		(layer "In13.Cu")
		(net "M_B_CPU1_SB_DQ<21>")
	)
	(arc
		(start 83.702398 -288.183574)
		(mid 83.885906 -288.229099)
		(end 84.068158 -288.178748)
		(width 0.0889)
		(layer "In13.Cu")
		(net "M_B_CPU1_SB_DQ<21>")
	)
	(arc
		(start 81.813908 -288.178748)
		(mid 81.996159 -288.229132)
		(end 82.179668 -288.183574)
		(width 0.0889)
		(layer "In13.Cu")
		(net "M_B_CPU1_SB_DQ<21>")
	)
	(arc
		(start 86.888066 -288.178748)
		(mid 87.171022 -288.102571)
		(end 87.453978 -288.178748)
		(width 0.0889)
		(layer "In13.Cu")
		(net "M_B_CPU1_SB_DQ<21>")
	)
	(arc
		(start 83.128104 -288.178748)
		(mid 83.41106 -288.102571)
		(end 83.694016 -288.178748)
		(width 0.0889)
		(layer "In13.Cu")
		(net "M_B_CPU1_SB_DQ<21>")
	)
	(arc
		(start 88.402414 -288.183574)
		(mid 88.585922 -288.229099)
		(end 88.768174 -288.178748)
		(width 0.0889)
		(layer "In13.Cu")
		(net "M_B_CPU1_SB_DQ<21>")
	)
	(arc
		(start 85.007958 -288.178748)
		(mid 85.290914 -288.102571)
		(end 85.57387 -288.178748)
		(width 0.0889)
		(layer "In13.Cu")
		(net "M_B_CPU1_SB_DQ<21>")
	)
	(arc
		(start 82.18805 -288.178748)
		(mid 82.471006 -288.102571)
		(end 82.753962 -288.178748)
		(width 0.0889)
		(layer "In13.Cu")
		(net "M_B_CPU1_SB_DQ<21>")
	)
	(arc
		(start 87.82812 -288.178748)
		(mid 88.111076 -288.102571)
		(end 88.394032 -288.178748)
		(width 0.0889)
		(layer "In13.Cu")
		(net "M_B_CPU1_SB_DQ<21>")
	)
	(arc
		(start 88.768174 -288.178748)
		(mid 89.016034 -288.103665)
		(end 89.271348 -288.147252)
		(width 0.0889)
		(layer "In13.Cu")
		(net "M_B_CPU1_SB_DQ<21>")
	)
	(arc
		(start 84.63407 -288.178748)
		(mid 84.821014 -288.229037)
		(end 85.007958 -288.178748)
		(width 0.0889)
		(layer "In13.Cu")
		(net "M_B_CPU1_SB_DQ<21>")
	)
	(arc
		(start 80.308196 -288.178748)
		(mid 80.591152 -288.102571)
		(end 80.874108 -288.178748)
		(width 0.0889)
		(layer "In13.Cu")
		(net "M_B_CPU1_SB_DQ<21>")
	)
	(arc
		(start 85.948266 -288.178748)
		(mid 86.231112 -288.102537)
		(end 86.513924 -288.178748)
		(width 0.0889)
		(layer "In13.Cu")
		(net "M_B_CPU1_SB_DQ<21>")
	)
	(arc
		(start 86.513924 -288.178748)
		(mid 86.696175 -288.229132)
		(end 86.879684 -288.183574)
		(width 0.0889)
		(layer "In13.Cu")
		(net "M_B_CPU1_SB_DQ<21>")
	)
	(arc
		(start 85.57387 -288.178748)
		(mid 85.756121 -288.229132)
		(end 85.93963 -288.183574)
		(width 0.0889)
		(layer "In13.Cu")
		(net "M_B_CPU1_SB_DQ<21>")
	)
	(arc
		(start 78.42758 -288.178748)
		(mid 78.702286 -288.102384)
		(end 78.979268 -288.170112)
		(width 0.0889)
		(layer "In13.Cu")
		(net "M_B_CPU1_SB_DQ<21>")
	)
	(arc
		(start 79.942436 -288.183574)
		(mid 80.125944 -288.229099)
		(end 80.308196 -288.178748)
		(width 0.0889)
		(layer "In13.Cu")
		(net "M_B_CPU1_SB_DQ<21>")
	)
	(segment
		(start 88.577928 -286.780478)
		(end 88.111076 -287.046162)
		(width 0.10668)
		(layer "F.Cu")
		(net "M_B_CPU1_SB_DQ<20>")
	)
	(segment
		(start 55.071264 -306.266342)
		(end 54.809644 -306.266342)
		(width 0.14478)
		(layer "In13.Cu")
		(net "M_B_CPU1_SB_DQ<20>")
	)
	(segment
		(start 78.71079 -287.419542)
		(end 77.790294 -287.419542)
		(width 0.0889)
		(layer "In13.Cu")
		(net "M_B_CPU1_SB_DQ<20>")
	)
	(segment
		(start 58.855102 -305.341782)
		(end 58.855102 -305.546506)
		(width 0.14478)
		(layer "In13.Cu")
		(net "M_B_CPU1_SB_DQ<20>")
	)
	(segment
		(start 69.613018 -296.593768)
		(end 60.983368 -305.223418)
		(width 0.14478)
		(layer "In13.Cu")
		(net "M_B_CPU1_SB_DQ<20>")
	)
	(segment
		(start 57.348882 -306.126642)
		(end 57.348882 -306.331366)
		(width 0.14478)
		(layer "In13.Cu")
		(net "M_B_CPU1_SB_DQ<20>")
	)
	(segment
		(start 88.111076 -287.046162)
		(end 87.956898 -287.311592)
		(width 0.0889)
		(layer "In13.Cu")
		(net "M_B_CPU1_SB_DQ<20>")
	)
	(segment
		(start 57.504838 -306.692046)
		(end 57.262014 -306.93487)
		(width 0.14478)
		(layer "In13.Cu")
		(net "M_B_CPU1_SB_DQ<20>")
	)
	(segment
		(start 58.465212 -305.936396)
		(end 58.260488 -305.936396)
		(width 0.14478)
		(layer "In13.Cu")
		(net "M_B_CPU1_SB_DQ<20>")
	)
	(segment
		(start 55.767224 -306.411122)
		(end 55.767224 -306.79009)
		(width 0.14478)
		(layer "In13.Cu")
		(net "M_B_CPU1_SB_DQ<20>")
	)
	(segment
		(start 79.463392 -287.368742)
		(end 79.44866 -287.360106)
		(width 0.0889)
		(layer "In13.Cu")
		(net "M_B_CPU1_SB_DQ<20>")
	)
	(segment
		(start 55.360824 -306.93487)
		(end 55.216044 -306.79009)
		(width 0.14478)
		(layer "In13.Cu")
		(net "M_B_CPU1_SB_DQ<20>")
	)
	(segment
		(start 56.173624 -306.266342)
		(end 55.912004 -306.266342)
		(width 0.14478)
		(layer "In13.Cu")
		(net "M_B_CPU1_SB_DQ<20>")
	)
	(segment
		(start 56.463184 -306.93487)
		(end 56.318404 -306.79009)
		(width 0.14478)
		(layer "In13.Cu")
		(net "M_B_CPU1_SB_DQ<20>")
	)
	(segment
		(start 57.504838 -306.487322)
		(end 57.504838 -306.692046)
		(width 0.14478)
		(layer "In13.Cu")
		(net "M_B_CPU1_SB_DQ<20>")
	)
	(segment
		(start 55.912004 -306.266342)
		(end 55.767224 -306.411122)
		(width 0.14478)
		(layer "In13.Cu")
		(net "M_B_CPU1_SB_DQ<20>")
	)
	(segment
		(start 58.260488 -305.936396)
		(end 58.099452 -306.097432)
		(width 0.14478)
		(layer "In13.Cu")
		(net "M_B_CPU1_SB_DQ<20>")
	)
	(segment
		(start 59.653678 -306.070762)
		(end 59.508898 -305.925982)
		(width 0.14478)
		(layer "In13.Cu")
		(net "M_B_CPU1_SB_DQ<20>")
	)
	(segment
		(start 57.348882 -306.331366)
		(end 57.504838 -306.487322)
		(width 0.14478)
		(layer "In13.Cu")
		(net "M_B_CPU1_SB_DQ<20>")
	)
	(segment
		(start 58.733944 -306.000404)
		(end 58.52922 -306.000404)
		(width 0.14478)
		(layer "In13.Cu")
		(net "M_B_CPU1_SB_DQ<20>")
	)
	(segment
		(start 53.00726 -305.831748)
		(end 52.187602 -305.831748)
		(width 0.14478)
		(layer "In13.Cu")
		(net "M_B_CPU1_SB_DQ<20>")
	)
	(segment
		(start 86.052406 -287.373568)
		(end 86.044024 -287.368742)
		(width 0.0889)
		(layer "In13.Cu")
		(net "M_B_CPU1_SB_DQ<20>")
	)
	(segment
		(start 55.216044 -306.79009)
		(end 55.216044 -306.411122)
		(width 0.14478)
		(layer "In13.Cu")
		(net "M_B_CPU1_SB_DQ<20>")
	)
	(segment
		(start 59.364118 -305.223418)
		(end 58.973466 -305.223418)
		(width 0.14478)
		(layer "In13.Cu")
		(net "M_B_CPU1_SB_DQ<20>")
	)
	(segment
		(start 56.318404 -306.79009)
		(end 56.318404 -306.411122)
		(width 0.14478)
		(layer "In13.Cu")
		(net "M_B_CPU1_SB_DQ<20>")
	)
	(segment
		(start 60.060078 -305.925982)
		(end 59.915298 -306.070762)
		(width 0.14478)
		(layer "In13.Cu")
		(net "M_B_CPU1_SB_DQ<20>")
	)
	(segment
		(start 79.475076 -287.3756)
		(end 79.463392 -287.368742)
		(width 0.0889)
		(layer "In13.Cu")
		(net "M_B_CPU1_SB_DQ<20>")
	)
	(segment
		(start 55.216044 -306.411122)
		(end 55.071264 -306.266342)
		(width 0.14478)
		(layer "In13.Cu")
		(net "M_B_CPU1_SB_DQ<20>")
	)
	(segment
		(start 54.664864 -306.79009)
		(end 54.520084 -306.93487)
		(width 0.14478)
		(layer "In13.Cu")
		(net "M_B_CPU1_SB_DQ<20>")
	)
	(segment
		(start 58.855102 -305.546506)
		(end 58.91911 -305.610514)
		(width 0.14478)
		(layer "In13.Cu")
		(net "M_B_CPU1_SB_DQ<20>")
	)
	(segment
		(start 59.508898 -305.368198)
		(end 59.364118 -305.223418)
		(width 0.14478)
		(layer "In13.Cu")
		(net "M_B_CPU1_SB_DQ<20>")
	)
	(segment
		(start 58.973466 -305.223418)
		(end 58.855102 -305.341782)
		(width 0.14478)
		(layer "In13.Cu")
		(net "M_B_CPU1_SB_DQ<20>")
	)
	(segment
		(start 85.112352 -287.373568)
		(end 85.10397 -287.368742)
		(width 0.0889)
		(layer "In13.Cu")
		(net "M_B_CPU1_SB_DQ<20>")
	)
	(segment
		(start 80.778096 -287.368742)
		(end 80.769714 -287.373568)
		(width 0.0889)
		(layer "In13.Cu")
		(net "M_B_CPU1_SB_DQ<20>")
	)
	(segment
		(start 69.613018 -295.394126)
		(end 69.613018 -296.593768)
		(width 0.14478)
		(layer "In13.Cu")
		(net "M_B_CPU1_SB_DQ<20>")
	)
	(segment
		(start 75.986386 -289.020758)
		(end 69.613018 -295.394126)
		(width 0.14478)
		(layer "In13.Cu")
		(net "M_B_CPU1_SB_DQ<20>")
	)
	(segment
		(start 55.622444 -306.93487)
		(end 55.360824 -306.93487)
		(width 0.14478)
		(layer "In13.Cu")
		(net "M_B_CPU1_SB_DQ<20>")
	)
	(segment
		(start 60.983368 -305.223418)
		(end 60.204858 -305.223418)
		(width 0.14478)
		(layer "In13.Cu")
		(net "M_B_CPU1_SB_DQ<20>")
	)
	(segment
		(start 58.099452 -306.097432)
		(end 57.894728 -306.097432)
		(width 0.14478)
		(layer "In13.Cu")
		(net "M_B_CPU1_SB_DQ<20>")
	)
	(segment
		(start 60.060078 -305.368198)
		(end 60.060078 -305.925982)
		(width 0.14478)
		(layer "In13.Cu")
		(net "M_B_CPU1_SB_DQ<20>")
	)
	(segment
		(start 83.598004 -287.368742)
		(end 83.589622 -287.373568)
		(width 0.0889)
		(layer "In13.Cu")
		(net "M_B_CPU1_SB_DQ<20>")
	)
	(segment
		(start 58.52922 -306.000404)
		(end 58.465212 -305.936396)
		(width 0.14478)
		(layer "In13.Cu")
		(net "M_B_CPU1_SB_DQ<20>")
	)
	(segment
		(start 59.508898 -305.925982)
		(end 59.508898 -305.368198)
		(width 0.14478)
		(layer "In13.Cu")
		(net "M_B_CPU1_SB_DQ<20>")
	)
	(segment
		(start 59.915298 -306.070762)
		(end 59.653678 -306.070762)
		(width 0.14478)
		(layer "In13.Cu")
		(net "M_B_CPU1_SB_DQ<20>")
	)
	(segment
		(start 57.894728 -306.097432)
		(end 57.738772 -305.941476)
		(width 0.14478)
		(layer "In13.Cu")
		(net "M_B_CPU1_SB_DQ<20>")
	)
	(segment
		(start 57.262014 -306.93487)
		(end 56.463184 -306.93487)
		(width 0.14478)
		(layer "In13.Cu")
		(net "M_B_CPU1_SB_DQ<20>")
	)
	(segment
		(start 52.187602 -305.831748)
		(end 51.884072 -306.135278)
		(width 0.14478)
		(layer "In13.Cu")
		(net "M_B_CPU1_SB_DQ<20>")
	)
	(segment
		(start 56.318404 -306.411122)
		(end 56.173624 -306.266342)
		(width 0.14478)
		(layer "In13.Cu")
		(net "M_B_CPU1_SB_DQ<20>")
	)
	(segment
		(start 57.534048 -305.941476)
		(end 57.348882 -306.126642)
		(width 0.14478)
		(layer "In13.Cu")
		(net "M_B_CPU1_SB_DQ<20>")
	)
	(segment
		(start 54.809644 -306.266342)
		(end 54.664864 -306.411122)
		(width 0.14478)
		(layer "In13.Cu")
		(net "M_B_CPU1_SB_DQ<20>")
	)
	(segment
		(start 77.25029 -287.959546)
		(end 77.047598 -287.959546)
		(width 0.0889)
		(layer "In13.Cu")
		(net "M_B_CPU1_SB_DQ<20>")
	)
	(segment
		(start 58.91911 -305.815238)
		(end 58.733944 -306.000404)
		(width 0.14478)
		(layer "In13.Cu")
		(net "M_B_CPU1_SB_DQ<20>")
	)
	(segment
		(start 77.047598 -287.959546)
		(end 75.986386 -289.020758)
		(width 0.0889)
		(layer "In13.Cu")
		(net "M_B_CPU1_SB_DQ<20>")
	)
	(segment
		(start 54.110382 -306.93487)
		(end 53.00726 -305.831748)
		(width 0.14478)
		(layer "In13.Cu")
		(net "M_B_CPU1_SB_DQ<20>")
	)
	(segment
		(start 80.403954 -287.368742)
		(end 80.39354 -287.362646)
		(width 0.0889)
		(layer "In13.Cu")
		(net "M_B_CPU1_SB_DQ<20>")
	)
	(segment
		(start 84.538058 -287.368742)
		(end 84.529676 -287.373568)
		(width 0.0889)
		(layer "In13.Cu")
		(net "M_B_CPU1_SB_DQ<20>")
	)
	(segment
		(start 55.767224 -306.79009)
		(end 55.622444 -306.93487)
		(width 0.14478)
		(layer "In13.Cu")
		(net "M_B_CPU1_SB_DQ<20>")
	)
	(segment
		(start 54.664864 -306.411122)
		(end 54.664864 -306.79009)
		(width 0.14478)
		(layer "In13.Cu")
		(net "M_B_CPU1_SB_DQ<20>")
	)
	(segment
		(start 57.738772 -305.941476)
		(end 57.534048 -305.941476)
		(width 0.14478)
		(layer "In13.Cu")
		(net "M_B_CPU1_SB_DQ<20>")
	)
	(segment
		(start 60.204858 -305.223418)
		(end 60.060078 -305.368198)
		(width 0.14478)
		(layer "In13.Cu")
		(net "M_B_CPU1_SB_DQ<20>")
	)
	(segment
		(start 58.91911 -305.610514)
		(end 58.91911 -305.815238)
		(width 0.14478)
		(layer "In13.Cu")
		(net "M_B_CPU1_SB_DQ<20>")
	)
	(segment
		(start 87.956898 -287.311592)
		(end 87.860632 -287.336992)
		(width 0.0889)
		(layer "In13.Cu")
		(net "M_B_CPU1_SB_DQ<20>")
	)
	(segment
		(start 81.35239 -287.373568)
		(end 81.344008 -287.368742)
		(width 0.0889)
		(layer "In13.Cu")
		(net "M_B_CPU1_SB_DQ<20>")
	)
	(segment
		(start 54.520084 -306.93487)
		(end 54.110382 -306.93487)
		(width 0.14478)
		(layer "In13.Cu")
		(net "M_B_CPU1_SB_DQ<20>")
	)
	(segment
		(start 77.790294 -287.419542)
		(end 77.25029 -287.959546)
		(width 0.0889)
		(layer "In13.Cu")
		(net "M_B_CPU1_SB_DQ<20>")
	)
	(arc
		(start 85.478112 -287.368742)
		(mid 85.295861 -287.419092)
		(end 85.112352 -287.373568)
		(width 0.0889)
		(layer "In13.Cu")
		(net "M_B_CPU1_SB_DQ<20>")
	)
	(arc
		(start 85.10397 -287.368742)
		(mid 84.821014 -287.292599)
		(end 84.538058 -287.368742)
		(width 0.0889)
		(layer "In13.Cu")
		(net "M_B_CPU1_SB_DQ<20>")
	)
	(arc
		(start 86.984078 -287.368742)
		(mid 86.701122 -287.292599)
		(end 86.418166 -287.368742)
		(width 0.0889)
		(layer "In13.Cu")
		(net "M_B_CPU1_SB_DQ<20>")
	)
	(arc
		(start 78.897988 -287.368742)
		(mid 78.807748 -287.406519)
		(end 78.71079 -287.419542)
		(width 0.0889)
		(layer "In13.Cu")
		(net "M_B_CPU1_SB_DQ<20>")
	)
	(arc
		(start 84.163916 -287.368742)
		(mid 83.88096 -287.292599)
		(end 83.598004 -287.368742)
		(width 0.0889)
		(layer "In13.Cu")
		(net "M_B_CPU1_SB_DQ<20>")
	)
	(arc
		(start 83.589622 -287.373568)
		(mid 83.406114 -287.419062)
		(end 83.223862 -287.368742)
		(width 0.0889)
		(layer "In13.Cu")
		(net "M_B_CPU1_SB_DQ<20>")
	)
	(arc
		(start 79.837788 -287.368742)
		(mid 79.65733 -287.419186)
		(end 79.475076 -287.3756)
		(width 0.0889)
		(layer "In13.Cu")
		(net "M_B_CPU1_SB_DQ<20>")
	)
	(arc
		(start 83.223862 -287.368742)
		(mid 82.940906 -287.292599)
		(end 82.65795 -287.368742)
		(width 0.0889)
		(layer "In13.Cu")
		(net "M_B_CPU1_SB_DQ<20>")
	)
	(arc
		(start 81.71815 -287.368742)
		(mid 81.535899 -287.419092)
		(end 81.35239 -287.373568)
		(width 0.0889)
		(layer "In13.Cu")
		(net "M_B_CPU1_SB_DQ<20>")
	)
	(arc
		(start 82.65795 -287.368742)
		(mid 82.471006 -287.418997)
		(end 82.284062 -287.368742)
		(width 0.0889)
		(layer "In13.Cu")
		(net "M_B_CPU1_SB_DQ<20>")
	)
	(arc
		(start 81.344008 -287.368742)
		(mid 81.061052 -287.292599)
		(end 80.778096 -287.368742)
		(width 0.0889)
		(layer "In13.Cu")
		(net "M_B_CPU1_SB_DQ<20>")
	)
	(arc
		(start 87.860632 -287.336992)
		(mid 87.605567 -287.293661)
		(end 87.357966 -287.368742)
		(width 0.0889)
		(layer "In13.Cu")
		(net "M_B_CPU1_SB_DQ<20>")
	)
	(arc
		(start 82.284062 -287.368742)
		(mid 82.001106 -287.292599)
		(end 81.71815 -287.368742)
		(width 0.0889)
		(layer "In13.Cu")
		(net "M_B_CPU1_SB_DQ<20>")
	)
	(arc
		(start 86.418166 -287.368742)
		(mid 86.235915 -287.419092)
		(end 86.052406 -287.373568)
		(width 0.0889)
		(layer "In13.Cu")
		(net "M_B_CPU1_SB_DQ<20>")
	)
	(arc
		(start 87.357966 -287.368742)
		(mid 87.171022 -287.418997)
		(end 86.984078 -287.368742)
		(width 0.0889)
		(layer "In13.Cu")
		(net "M_B_CPU1_SB_DQ<20>")
	)
	(arc
		(start 80.39354 -287.362646)
		(mid 80.114854 -287.292457)
		(end 79.837788 -287.368742)
		(width 0.0889)
		(layer "In13.Cu")
		(net "M_B_CPU1_SB_DQ<20>")
	)
	(arc
		(start 80.769714 -287.373568)
		(mid 80.586206 -287.419062)
		(end 80.403954 -287.368742)
		(width 0.0889)
		(layer "In13.Cu")
		(net "M_B_CPU1_SB_DQ<20>")
	)
	(arc
		(start 86.044024 -287.368742)
		(mid 85.761068 -287.292599)
		(end 85.478112 -287.368742)
		(width 0.0889)
		(layer "In13.Cu")
		(net "M_B_CPU1_SB_DQ<20>")
	)
	(arc
		(start 79.44866 -287.360106)
		(mid 79.172185 -287.292574)
		(end 78.897988 -287.368742)
		(width 0.0889)
		(layer "In13.Cu")
		(net "M_B_CPU1_SB_DQ<20>")
	)
	(arc
		(start 84.529676 -287.373568)
		(mid 84.346168 -287.419062)
		(end 84.163916 -287.368742)
		(width 0.0889)
		(layer "In13.Cu")
		(net "M_B_CPU1_SB_DQ<20>")
	)
	(segment
		(start 89.987882 -274.630388)
		(end 89.52103 -274.896326)
		(width 0.10668)
		(layer "F.Cu")
		(net "M_B_CPU1_SB_DQ<1>")
	)
	(segment
		(start 54.634384 -282.991306)
		(end 54.795928 -283.15285)
		(width 0.14478)
		(layer "In13.Cu")
		(net "M_B_CPU1_SB_DQ<1>")
	)
	(segment
		(start 54.406038 -282.991306)
		(end 54.634384 -282.991306)
		(width 0.14478)
		(layer "In13.Cu")
		(net "M_B_CPU1_SB_DQ<1>")
	)
	(segment
		(start 76.391262 -274.129754)
		(end 76.47305 -274.047966)
		(width 0.0889)
		(layer "In13.Cu")
		(net "M_B_CPU1_SB_DQ<1>")
	)
	(segment
		(start 86.879684 -275.223732)
		(end 86.888066 -275.218906)
		(width 0.0889)
		(layer "In13.Cu")
		(net "M_B_CPU1_SB_DQ<1>")
	)
	(segment
		(start 82.179668 -275.223732)
		(end 82.18805 -275.218906)
		(width 0.0889)
		(layer "In13.Cu")
		(net "M_B_CPU1_SB_DQ<1>")
	)
	(segment
		(start 56.495442 -282.823666)
		(end 56.656986 -282.98521)
		(width 0.14478)
		(layer "In13.Cu")
		(net "M_B_CPU1_SB_DQ<1>")
	)
	(segment
		(start 83.694016 -275.218906)
		(end 83.702398 -275.223732)
		(width 0.0889)
		(layer "In13.Cu")
		(net "M_B_CPU1_SB_DQ<1>")
	)
	(segment
		(start 76.47305 -274.047966)
		(end 77.385164 -274.047966)
		(width 0.0889)
		(layer "In13.Cu")
		(net "M_B_CPU1_SB_DQ<1>")
	)
	(segment
		(start 54.957472 -283.610304)
		(end 55.944008 -283.610304)
		(width 0.14478)
		(layer "In13.Cu")
		(net "M_B_CPU1_SB_DQ<1>")
	)
	(segment
		(start 85.93963 -275.223732)
		(end 85.948012 -275.218906)
		(width 0.0889)
		(layer "In13.Cu")
		(net "M_B_CPU1_SB_DQ<1>")
	)
	(segment
		(start 87.453978 -275.218906)
		(end 87.46236 -275.223732)
		(width 0.0889)
		(layer "In13.Cu")
		(net "M_B_CPU1_SB_DQ<1>")
	)
	(segment
		(start 78.47965 -275.142452)
		(end 79.650082 -275.142452)
		(width 0.0889)
		(layer "In13.Cu")
		(net "M_B_CPU1_SB_DQ<1>")
	)
	(segment
		(start 58.637932 -282.74137)
		(end 58.637932 -283.015944)
		(width 0.14478)
		(layer "In13.Cu")
		(net "M_B_CPU1_SB_DQ<1>")
	)
	(segment
		(start 56.656986 -282.98521)
		(end 56.656986 -283.44876)
		(width 0.14478)
		(layer "In13.Cu")
		(net "M_B_CPU1_SB_DQ<1>")
	)
	(segment
		(start 58.231532 -282.59659)
		(end 58.493152 -282.59659)
		(width 0.14478)
		(layer "In13.Cu")
		(net "M_B_CPU1_SB_DQ<1>")
	)
	(segment
		(start 56.267096 -282.823666)
		(end 56.495442 -282.823666)
		(width 0.14478)
		(layer "In13.Cu")
		(net "M_B_CPU1_SB_DQ<1>")
	)
	(segment
		(start 58.782712 -283.160724)
		(end 59.190382 -283.160724)
		(width 0.14478)
		(layer "In13.Cu")
		(net "M_B_CPU1_SB_DQ<1>")
	)
	(segment
		(start 54.08295 -283.610304)
		(end 54.244494 -283.44876)
		(width 0.14478)
		(layer "In13.Cu")
		(net "M_B_CPU1_SB_DQ<1>")
	)
	(segment
		(start 57.941972 -283.160724)
		(end 58.086752 -283.015944)
		(width 0.14478)
		(layer "In13.Cu")
		(net "M_B_CPU1_SB_DQ<1>")
	)
	(segment
		(start 52.290472 -282.760166)
		(end 53.066188 -282.760166)
		(width 0.14478)
		(layer "In13.Cu")
		(net "M_B_CPU1_SB_DQ<1>")
	)
	(segment
		(start 54.795928 -283.44876)
		(end 54.957472 -283.610304)
		(width 0.14478)
		(layer "In13.Cu")
		(net "M_B_CPU1_SB_DQ<1>")
	)
	(segment
		(start 85.948012 -275.218906)
		(end 85.948266 -275.218906)
		(width 0.0889)
		(layer "In13.Cu")
		(net "M_B_CPU1_SB_DQ<1>")
	)
	(segment
		(start 51.884072 -283.185362)
		(end 51.884072 -283.166566)
		(width 0.14478)
		(layer "In13.Cu")
		(net "M_B_CPU1_SB_DQ<1>")
	)
	(segment
		(start 58.086752 -282.74137)
		(end 58.231532 -282.59659)
		(width 0.14478)
		(layer "In13.Cu")
		(net "M_B_CPU1_SB_DQ<1>")
	)
	(segment
		(start 82.753962 -275.218906)
		(end 82.762344 -275.223732)
		(width 0.0889)
		(layer "In13.Cu")
		(net "M_B_CPU1_SB_DQ<1>")
	)
	(segment
		(start 53.916326 -283.610304)
		(end 54.08295 -283.610304)
		(width 0.14478)
		(layer "In13.Cu")
		(net "M_B_CPU1_SB_DQ<1>")
	)
	(segment
		(start 51.884072 -283.166566)
		(end 52.290472 -282.760166)
		(width 0.14478)
		(layer "In13.Cu")
		(net "M_B_CPU1_SB_DQ<1>")
	)
	(segment
		(start 58.086752 -283.015944)
		(end 58.086752 -282.74137)
		(width 0.14478)
		(layer "In13.Cu")
		(net "M_B_CPU1_SB_DQ<1>")
	)
	(segment
		(start 56.105552 -283.44876)
		(end 56.105552 -282.98521)
		(width 0.14478)
		(layer "In13.Cu")
		(net "M_B_CPU1_SB_DQ<1>")
	)
	(segment
		(start 76.201016 -274.129754)
		(end 76.391262 -274.129754)
		(width 0.0889)
		(layer "In13.Cu")
		(net "M_B_CPU1_SB_DQ<1>")
	)
	(segment
		(start 88.394032 -275.218906)
		(end 88.402414 -275.223732)
		(width 0.0889)
		(layer "In13.Cu")
		(net "M_B_CPU1_SB_DQ<1>")
	)
	(segment
		(start 56.984646 -283.610304)
		(end 57.434226 -283.160724)
		(width 0.14478)
		(layer "In13.Cu")
		(net "M_B_CPU1_SB_DQ<1>")
	)
	(segment
		(start 54.244494 -283.44876)
		(end 54.244494 -283.15285)
		(width 0.14478)
		(layer "In13.Cu")
		(net "M_B_CPU1_SB_DQ<1>")
	)
	(segment
		(start 56.105552 -282.98521)
		(end 56.267096 -282.823666)
		(width 0.14478)
		(layer "In13.Cu")
		(net "M_B_CPU1_SB_DQ<1>")
	)
	(segment
		(start 54.244494 -283.15285)
		(end 54.406038 -282.991306)
		(width 0.14478)
		(layer "In13.Cu")
		(net "M_B_CPU1_SB_DQ<1>")
	)
	(segment
		(start 58.493152 -282.59659)
		(end 58.637932 -282.74137)
		(width 0.14478)
		(layer "In13.Cu")
		(net "M_B_CPU1_SB_DQ<1>")
	)
	(segment
		(start 53.066188 -282.760166)
		(end 53.916326 -283.610304)
		(width 0.14478)
		(layer "In13.Cu")
		(net "M_B_CPU1_SB_DQ<1>")
	)
	(segment
		(start 77.385164 -274.047966)
		(end 78.47965 -275.142452)
		(width 0.0889)
		(layer "In13.Cu")
		(net "M_B_CPU1_SB_DQ<1>")
	)
	(segment
		(start 68.221352 -274.129754)
		(end 76.201016 -274.129754)
		(width 0.14478)
		(layer "In13.Cu")
		(net "M_B_CPU1_SB_DQ<1>")
	)
	(segment
		(start 54.795928 -283.15285)
		(end 54.795928 -283.44876)
		(width 0.14478)
		(layer "In13.Cu")
		(net "M_B_CPU1_SB_DQ<1>")
	)
	(segment
		(start 56.81853 -283.610304)
		(end 56.984646 -283.610304)
		(width 0.14478)
		(layer "In13.Cu")
		(net "M_B_CPU1_SB_DQ<1>")
	)
	(segment
		(start 57.434226 -283.160724)
		(end 57.941972 -283.160724)
		(width 0.14478)
		(layer "In13.Cu")
		(net "M_B_CPU1_SB_DQ<1>")
	)
	(segment
		(start 58.637932 -283.015944)
		(end 58.782712 -283.160724)
		(width 0.14478)
		(layer "In13.Cu")
		(net "M_B_CPU1_SB_DQ<1>")
	)
	(segment
		(start 59.190382 -283.160724)
		(end 68.221352 -274.129754)
		(width 0.14478)
		(layer "In13.Cu")
		(net "M_B_CPU1_SB_DQ<1>")
	)
	(segment
		(start 56.656986 -283.44876)
		(end 56.81853 -283.610304)
		(width 0.14478)
		(layer "In13.Cu")
		(net "M_B_CPU1_SB_DQ<1>")
	)
	(segment
		(start 55.944008 -283.610304)
		(end 56.105552 -283.44876)
		(width 0.14478)
		(layer "In13.Cu")
		(net "M_B_CPU1_SB_DQ<1>")
	)
	(segment
		(start 80.299814 -275.223732)
		(end 80.308196 -275.218906)
		(width 0.0889)
		(layer "In13.Cu")
		(net "M_B_CPU1_SB_DQ<1>")
	)
	(segment
		(start 89.367106 -275.161756)
		(end 89.52103 -274.896326)
		(width 0.0889)
		(layer "In13.Cu")
		(net "M_B_CPU1_SB_DQ<1>")
	)
	(segment
		(start 89.271094 -275.187156)
		(end 89.367106 -275.161756)
		(width 0.0889)
		(layer "In13.Cu")
		(net "M_B_CPU1_SB_DQ<1>")
	)
	(arc
		(start 82.18805 -275.218906)
		(mid 82.471006 -275.142729)
		(end 82.753962 -275.218906)
		(width 0.0889)
		(layer "In13.Cu")
		(net "M_B_CPU1_SB_DQ<1>")
	)
	(arc
		(start 80.308196 -275.218906)
		(mid 80.591152 -275.142729)
		(end 80.874108 -275.218906)
		(width 0.0889)
		(layer "In13.Cu")
		(net "M_B_CPU1_SB_DQ<1>")
	)
	(arc
		(start 84.068158 -275.218906)
		(mid 84.351114 -275.142729)
		(end 84.63407 -275.218906)
		(width 0.0889)
		(layer "In13.Cu")
		(net "M_B_CPU1_SB_DQ<1>")
	)
	(arc
		(start 88.402414 -275.223732)
		(mid 88.585922 -275.269226)
		(end 88.768174 -275.218906)
		(width 0.0889)
		(layer "In13.Cu")
		(net "M_B_CPU1_SB_DQ<1>")
	)
	(arc
		(start 79.650082 -275.142452)
		(mid 79.796882 -275.161896)
		(end 79.933546 -275.218906)
		(width 0.0889)
		(layer "In13.Cu")
		(net "M_B_CPU1_SB_DQ<1>")
	)
	(arc
		(start 79.933546 -275.218906)
		(mid 80.116051 -275.269383)
		(end 80.299814 -275.223732)
		(width 0.0889)
		(layer "In13.Cu")
		(net "M_B_CPU1_SB_DQ<1>")
	)
	(arc
		(start 82.762344 -275.223732)
		(mid 82.945852 -275.269226)
		(end 83.128104 -275.218906)
		(width 0.0889)
		(layer "In13.Cu")
		(net "M_B_CPU1_SB_DQ<1>")
	)
	(arc
		(start 85.007958 -275.218906)
		(mid 85.290914 -275.142729)
		(end 85.57387 -275.218906)
		(width 0.0889)
		(layer "In13.Cu")
		(net "M_B_CPU1_SB_DQ<1>")
	)
	(arc
		(start 88.768174 -275.218906)
		(mid 89.015887 -275.143686)
		(end 89.271094 -275.187156)
		(width 0.0889)
		(layer "In13.Cu")
		(net "M_B_CPU1_SB_DQ<1>")
	)
	(arc
		(start 87.46236 -275.223732)
		(mid 87.645868 -275.269226)
		(end 87.82812 -275.218906)
		(width 0.0889)
		(layer "In13.Cu")
		(net "M_B_CPU1_SB_DQ<1>")
	)
	(arc
		(start 83.702398 -275.223732)
		(mid 83.885906 -275.269226)
		(end 84.068158 -275.218906)
		(width 0.0889)
		(layer "In13.Cu")
		(net "M_B_CPU1_SB_DQ<1>")
	)
	(arc
		(start 83.128104 -275.218906)
		(mid 83.41106 -275.142729)
		(end 83.694016 -275.218906)
		(width 0.0889)
		(layer "In13.Cu")
		(net "M_B_CPU1_SB_DQ<1>")
	)
	(arc
		(start 81.247996 -275.218906)
		(mid 81.530952 -275.142729)
		(end 81.813908 -275.218906)
		(width 0.0889)
		(layer "In13.Cu")
		(net "M_B_CPU1_SB_DQ<1>")
	)
	(arc
		(start 85.57387 -275.218906)
		(mid 85.756121 -275.269256)
		(end 85.93963 -275.223732)
		(width 0.0889)
		(layer "In13.Cu")
		(net "M_B_CPU1_SB_DQ<1>")
	)
	(arc
		(start 84.63407 -275.218906)
		(mid 84.821014 -275.269161)
		(end 85.007958 -275.218906)
		(width 0.0889)
		(layer "In13.Cu")
		(net "M_B_CPU1_SB_DQ<1>")
	)
	(arc
		(start 86.513924 -275.218906)
		(mid 86.696175 -275.269256)
		(end 86.879684 -275.223732)
		(width 0.0889)
		(layer "In13.Cu")
		(net "M_B_CPU1_SB_DQ<1>")
	)
	(arc
		(start 87.82812 -275.218906)
		(mid 88.111076 -275.142729)
		(end 88.394032 -275.218906)
		(width 0.0889)
		(layer "In13.Cu")
		(net "M_B_CPU1_SB_DQ<1>")
	)
	(arc
		(start 80.874108 -275.218906)
		(mid 81.061052 -275.269161)
		(end 81.247996 -275.218906)
		(width 0.0889)
		(layer "In13.Cu")
		(net "M_B_CPU1_SB_DQ<1>")
	)
	(arc
		(start 85.948266 -275.218906)
		(mid 86.231112 -275.142729)
		(end 86.513924 -275.218906)
		(width 0.0889)
		(layer "In13.Cu")
		(net "M_B_CPU1_SB_DQ<1>")
	)
	(arc
		(start 86.888066 -275.218906)
		(mid 87.171022 -275.142729)
		(end 87.453978 -275.218906)
		(width 0.0889)
		(layer "In13.Cu")
		(net "M_B_CPU1_SB_DQ<1>")
	)
	(arc
		(start 81.813908 -275.218906)
		(mid 81.996159 -275.269256)
		(end 82.179668 -275.223732)
		(width 0.0889)
		(layer "In13.Cu")
		(net "M_B_CPU1_SB_DQ<1>")
	)
	(segment
		(start 89.517982 -285.160466)
		(end 89.05113 -285.426404)
		(width 0.10668)
		(layer "F.Cu")
		(net "M_B_CPU1_SB_DQ<19>")
	)
	(segment
		(start 58.463688 -302.436784)
		(end 58.252868 -302.225964)
		(width 0.14478)
		(layer "In13.Cu")
		(net "M_B_CPU1_SB_DQ<19>")
	)
	(segment
		(start 79.474822 -285.096966)
		(end 79.463138 -285.103824)
		(width 0.0889)
		(layer "In13.Cu")
		(net "M_B_CPU1_SB_DQ<19>")
	)
	(segment
		(start 89.05113 -285.426404)
		(end 89.205054 -285.160974)
		(width 0.0889)
		(layer "In13.Cu")
		(net "M_B_CPU1_SB_DQ<19>")
	)
	(segment
		(start 60.767976 -300.929802)
		(end 60.767976 -301.750222)
		(width 0.14478)
		(layer "In13.Cu")
		(net "M_B_CPU1_SB_DQ<19>")
	)
	(segment
		(start 78.903322 -285.10738)
		(end 78.897734 -285.104078)
		(width 0.0889)
		(layer "In13.Cu")
		(net "M_B_CPU1_SB_DQ<19>")
	)
	(segment
		(start 60.767976 -301.750222)
		(end 60.081414 -302.436784)
		(width 0.14478)
		(layer "In13.Cu")
		(net "M_B_CPU1_SB_DQ<19>")
	)
	(segment
		(start 83.598004 -285.103824)
		(end 83.589622 -285.098998)
		(width 0.0889)
		(layer "In13.Cu")
		(net "M_B_CPU1_SB_DQ<19>")
	)
	(segment
		(start 85.112352 -285.098998)
		(end 85.10397 -285.103824)
		(width 0.0889)
		(layer "In13.Cu")
		(net "M_B_CPU1_SB_DQ<19>")
	)
	(segment
		(start 51.140868 -302.764952)
		(end 50.527712 -302.151796)
		(width 0.14478)
		(layer "In13.Cu")
		(net "M_B_CPU1_SB_DQ<19>")
	)
	(segment
		(start 89.205054 -285.160974)
		(end 89.182702 -285.077662)
		(width 0.0889)
		(layer "In13.Cu")
		(net "M_B_CPU1_SB_DQ<19>")
	)
	(segment
		(start 78.897734 -285.104078)
		(end 78.879446 -285.093664)
		(width 0.0889)
		(layer "In13.Cu")
		(net "M_B_CPU1_SB_DQ<19>")
	)
	(segment
		(start 58.252868 -302.225964)
		(end 57.474104 -302.225964)
		(width 0.14478)
		(layer "In13.Cu")
		(net "M_B_CPU1_SB_DQ<19>")
	)
	(segment
		(start 80.403954 -285.103824)
		(end 80.389222 -285.11246)
		(width 0.0889)
		(layer "In13.Cu")
		(net "M_B_CPU1_SB_DQ<19>")
	)
	(segment
		(start 77.61478 -285.348426)
		(end 76.81214 -285.348426)
		(width 0.0889)
		(layer "In13.Cu")
		(net "M_B_CPU1_SB_DQ<19>")
	)
	(segment
		(start 80.778096 -285.103824)
		(end 80.769714 -285.098998)
		(width 0.0889)
		(layer "In13.Cu")
		(net "M_B_CPU1_SB_DQ<19>")
	)
	(segment
		(start 75.921616 -285.831534)
		(end 75.866244 -285.831534)
		(width 0.14478)
		(layer "In13.Cu")
		(net "M_B_CPU1_SB_DQ<19>")
	)
	(segment
		(start 49.446434 -302.735234)
		(end 47.784004 -302.735234)
		(width 0.14478)
		(layer "In13.Cu")
		(net "M_B_CPU1_SB_DQ<19>")
	)
	(segment
		(start 81.35239 -285.098998)
		(end 81.344008 -285.103824)
		(width 0.0889)
		(layer "In13.Cu")
		(net "M_B_CPU1_SB_DQ<19>")
	)
	(segment
		(start 50.527712 -302.151796)
		(end 50.029872 -302.151796)
		(width 0.14478)
		(layer "In13.Cu")
		(net "M_B_CPU1_SB_DQ<19>")
	)
	(segment
		(start 56.935116 -302.764952)
		(end 51.140868 -302.764952)
		(width 0.14478)
		(layer "In13.Cu")
		(net "M_B_CPU1_SB_DQ<19>")
	)
	(segment
		(start 75.866244 -285.831534)
		(end 60.767976 -300.929802)
		(width 0.14478)
		(layer "In13.Cu")
		(net "M_B_CPU1_SB_DQ<19>")
	)
	(segment
		(start 50.029872 -302.151796)
		(end 49.446434 -302.735234)
		(width 0.14478)
		(layer "In13.Cu")
		(net "M_B_CPU1_SB_DQ<19>")
	)
	(segment
		(start 86.052406 -285.098998)
		(end 86.044024 -285.103824)
		(width 0.0889)
		(layer "In13.Cu")
		(net "M_B_CPU1_SB_DQ<19>")
	)
	(segment
		(start 76.731876 -285.3817)
		(end 76.282042 -285.831534)
		(width 0.0889)
		(layer "In13.Cu")
		(net "M_B_CPU1_SB_DQ<19>")
	)
	(segment
		(start 57.474104 -302.225964)
		(end 56.935116 -302.764952)
		(width 0.14478)
		(layer "In13.Cu")
		(net "M_B_CPU1_SB_DQ<19>")
	)
	(segment
		(start 84.538058 -285.103824)
		(end 84.529676 -285.098998)
		(width 0.0889)
		(layer "In13.Cu")
		(net "M_B_CPU1_SB_DQ<19>")
	)
	(segment
		(start 76.282042 -285.831534)
		(end 75.921616 -285.831534)
		(width 0.0889)
		(layer "In13.Cu")
		(net "M_B_CPU1_SB_DQ<19>")
	)
	(segment
		(start 88.29802 -285.103824)
		(end 88.289638 -285.098998)
		(width 0.0889)
		(layer "In13.Cu")
		(net "M_B_CPU1_SB_DQ<19>")
	)
	(segment
		(start 60.081414 -302.436784)
		(end 58.463688 -302.436784)
		(width 0.14478)
		(layer "In13.Cu")
		(net "M_B_CPU1_SB_DQ<19>")
	)
	(arc
		(start 81.71815 -285.103824)
		(mid 81.535899 -285.053474)
		(end 81.35239 -285.098998)
		(width 0.0889)
		(layer "In13.Cu")
		(net "M_B_CPU1_SB_DQ<19>")
	)
	(arc
		(start 88.863932 -285.103824)
		(mid 88.580976 -285.180001)
		(end 88.29802 -285.103824)
		(width 0.0889)
		(layer "In13.Cu")
		(net "M_B_CPU1_SB_DQ<19>")
	)
	(arc
		(start 81.344008 -285.103824)
		(mid 81.061052 -285.180001)
		(end 80.778096 -285.103824)
		(width 0.0889)
		(layer "In13.Cu")
		(net "M_B_CPU1_SB_DQ<19>")
	)
	(arc
		(start 85.478112 -285.103824)
		(mid 85.295861 -285.053474)
		(end 85.112352 -285.098998)
		(width 0.0889)
		(layer "In13.Cu")
		(net "M_B_CPU1_SB_DQ<19>")
	)
	(arc
		(start 79.463138 -285.103824)
		(mid 79.18371 -285.17999)
		(end 78.903322 -285.10738)
		(width 0.0889)
		(layer "In13.Cu")
		(net "M_B_CPU1_SB_DQ<19>")
	)
	(arc
		(start 86.418166 -285.103824)
		(mid 86.235915 -285.053474)
		(end 86.052406 -285.098998)
		(width 0.0889)
		(layer "In13.Cu")
		(net "M_B_CPU1_SB_DQ<19>")
	)
	(arc
		(start 84.163916 -285.103824)
		(mid 83.88096 -285.180001)
		(end 83.598004 -285.103824)
		(width 0.0889)
		(layer "In13.Cu")
		(net "M_B_CPU1_SB_DQ<19>")
	)
	(arc
		(start 78.879446 -285.093664)
		(mid 78.700217 -285.053511)
		(end 78.523592 -285.103824)
		(width 0.0889)
		(layer "In13.Cu")
		(net "M_B_CPU1_SB_DQ<19>")
	)
	(arc
		(start 86.984078 -285.103824)
		(mid 86.701122 -285.180001)
		(end 86.418166 -285.103824)
		(width 0.0889)
		(layer "In13.Cu")
		(net "M_B_CPU1_SB_DQ<19>")
	)
	(arc
		(start 80.769714 -285.098998)
		(mid 80.586206 -285.053504)
		(end 80.403954 -285.103824)
		(width 0.0889)
		(layer "In13.Cu")
		(net "M_B_CPU1_SB_DQ<19>")
	)
	(arc
		(start 88.289638 -285.098998)
		(mid 88.10613 -285.053504)
		(end 87.923878 -285.103824)
		(width 0.0889)
		(layer "In13.Cu")
		(net "M_B_CPU1_SB_DQ<19>")
	)
	(arc
		(start 78.523592 -285.103824)
		(mid 78.085363 -285.286244)
		(end 77.61478 -285.348426)
		(width 0.0889)
		(layer "In13.Cu")
		(net "M_B_CPU1_SB_DQ<19>")
	)
	(arc
		(start 79.837534 -285.103824)
		(mid 79.657076 -285.05338)
		(end 79.474822 -285.096966)
		(width 0.0889)
		(layer "In13.Cu")
		(net "M_B_CPU1_SB_DQ<19>")
	)
	(arc
		(start 87.923878 -285.103824)
		(mid 87.640922 -285.180001)
		(end 87.357966 -285.103824)
		(width 0.0889)
		(layer "In13.Cu")
		(net "M_B_CPU1_SB_DQ<19>")
	)
	(arc
		(start 87.357966 -285.103824)
		(mid 87.171022 -285.053569)
		(end 86.984078 -285.103824)
		(width 0.0889)
		(layer "In13.Cu")
		(net "M_B_CPU1_SB_DQ<19>")
	)
	(arc
		(start 83.589622 -285.098998)
		(mid 83.406114 -285.053504)
		(end 83.223862 -285.103824)
		(width 0.0889)
		(layer "In13.Cu")
		(net "M_B_CPU1_SB_DQ<19>")
	)
	(arc
		(start 83.223862 -285.103824)
		(mid 82.940906 -285.180001)
		(end 82.65795 -285.103824)
		(width 0.0889)
		(layer "In13.Cu")
		(net "M_B_CPU1_SB_DQ<19>")
	)
	(arc
		(start 89.182702 -285.077662)
		(mid 89.02037 -285.054844)
		(end 88.863932 -285.103824)
		(width 0.0889)
		(layer "In13.Cu")
		(net "M_B_CPU1_SB_DQ<19>")
	)
	(arc
		(start 82.65795 -285.103824)
		(mid 82.471006 -285.053569)
		(end 82.284062 -285.103824)
		(width 0.0889)
		(layer "In13.Cu")
		(net "M_B_CPU1_SB_DQ<19>")
	)
	(arc
		(start 76.81214 -285.348426)
		(mid 76.768705 -285.357084)
		(end 76.731876 -285.3817)
		(width 0.0889)
		(layer "In13.Cu")
		(net "M_B_CPU1_SB_DQ<19>")
	)
	(arc
		(start 86.044024 -285.103824)
		(mid 85.761068 -285.180001)
		(end 85.478112 -285.103824)
		(width 0.0889)
		(layer "In13.Cu")
		(net "M_B_CPU1_SB_DQ<19>")
	)
	(arc
		(start 82.284062 -285.103824)
		(mid 82.001106 -285.180001)
		(end 81.71815 -285.103824)
		(width 0.0889)
		(layer "In13.Cu")
		(net "M_B_CPU1_SB_DQ<19>")
	)
	(arc
		(start 85.10397 -285.103824)
		(mid 84.821014 -285.180001)
		(end 84.538058 -285.103824)
		(width 0.0889)
		(layer "In13.Cu")
		(net "M_B_CPU1_SB_DQ<19>")
	)
	(arc
		(start 84.529676 -285.098998)
		(mid 84.346168 -285.053504)
		(end 84.163916 -285.103824)
		(width 0.0889)
		(layer "In13.Cu")
		(net "M_B_CPU1_SB_DQ<19>")
	)
	(arc
		(start 80.389222 -285.11246)
		(mid 80.112239 -285.180264)
		(end 79.837534 -285.103824)
		(width 0.0889)
		(layer "In13.Cu")
		(net "M_B_CPU1_SB_DQ<19>")
	)
	(segment
		(start 88.107774 -284.35046)
		(end 87.640922 -284.616398)
		(width 0.10668)
		(layer "F.Cu")
		(net "M_B_CPU1_SB_DQ<18>")
	)
	(segment
		(start 82.753962 -284.293818)
		(end 82.762344 -284.288992)
		(width 0.0889)
		(layer "In13.Cu")
		(net "M_B_CPU1_SB_DQ<18>")
	)
	(segment
		(start 50.517806 -301.200312)
		(end 50.662586 -301.345092)
		(width 0.14478)
		(layer "In13.Cu")
		(net "M_B_CPU1_SB_DQ<18>")
	)
	(segment
		(start 51.068986 -301.200312)
		(end 51.068986 -300.75505)
		(width 0.14478)
		(layer "In13.Cu")
		(net "M_B_CPU1_SB_DQ<18>")
	)
	(segment
		(start 80.299814 -284.288992)
		(end 80.308196 -284.293818)
		(width 0.0889)
		(layer "In13.Cu")
		(net "M_B_CPU1_SB_DQ<18>")
	)
	(segment
		(start 54.090824 -300.61027)
		(end 54.940962 -301.460408)
		(width 0.14478)
		(layer "In13.Cu")
		(net "M_B_CPU1_SB_DQ<18>")
	)
	(segment
		(start 87.772748 -284.267656)
		(end 87.7951 -284.350968)
		(width 0.0889)
		(layer "In13.Cu")
		(net "M_B_CPU1_SB_DQ<18>")
	)
	(segment
		(start 49.0093 -301.825914)
		(end 49.15408 -301.681134)
		(width 0.14478)
		(layer "In13.Cu")
		(net "M_B_CPU1_SB_DQ<18>")
	)
	(segment
		(start 51.068986 -300.75505)
		(end 51.213766 -300.61027)
		(width 0.14478)
		(layer "In13.Cu")
		(net "M_B_CPU1_SB_DQ<18>")
	)
	(segment
		(start 78.993492 -284.294072)
		(end 79.009748 -284.284674)
		(width 0.0889)
		(layer "In13.Cu")
		(net "M_B_CPU1_SB_DQ<18>")
	)
	(segment
		(start 50.517806 -300.75505)
		(end 50.517806 -301.200312)
		(width 0.14478)
		(layer "In13.Cu")
		(net "M_B_CPU1_SB_DQ<18>")
	)
	(segment
		(start 47.784004 -301.035212)
		(end 48.45812 -301.035212)
		(width 0.14478)
		(layer "In13.Cu")
		(net "M_B_CPU1_SB_DQ<18>")
	)
	(segment
		(start 77.53223 -284.715966)
		(end 77.878178 -284.370018)
		(width 0.0889)
		(layer "In13.Cu")
		(net "M_B_CPU1_SB_DQ<18>")
	)
	(segment
		(start 50.662586 -301.345092)
		(end 50.924206 -301.345092)
		(width 0.14478)
		(layer "In13.Cu")
		(net "M_B_CPU1_SB_DQ<18>")
	)
	(segment
		(start 54.940962 -301.460408)
		(end 56.95315 -301.460408)
		(width 0.14478)
		(layer "In13.Cu")
		(net "M_B_CPU1_SB_DQ<18>")
	)
	(segment
		(start 82.179668 -284.288992)
		(end 82.18805 -284.293818)
		(width 0.0889)
		(layer "In13.Cu")
		(net "M_B_CPU1_SB_DQ<18>")
	)
	(segment
		(start 49.15408 -301.179992)
		(end 49.29886 -301.035212)
		(width 0.14478)
		(layer "In13.Cu")
		(net "M_B_CPU1_SB_DQ<18>")
	)
	(segment
		(start 48.6029 -301.179992)
		(end 48.6029 -301.681134)
		(width 0.14478)
		(layer "In13.Cu")
		(net "M_B_CPU1_SB_DQ<18>")
	)
	(segment
		(start 49.991264 -300.61027)
		(end 50.373026 -300.61027)
		(width 0.14478)
		(layer "In13.Cu")
		(net "M_B_CPU1_SB_DQ<18>")
	)
	(segment
		(start 75.973686 -284.922214)
		(end 76.276962 -284.922214)
		(width 0.0889)
		(layer "In13.Cu")
		(net "M_B_CPU1_SB_DQ<18>")
	)
	(segment
		(start 59.808364 -300.61027)
		(end 75.49642 -284.922214)
		(width 0.14478)
		(layer "In13.Cu")
		(net "M_B_CPU1_SB_DQ<18>")
	)
	(segment
		(start 86.879684 -284.288992)
		(end 86.888066 -284.293818)
		(width 0.0889)
		(layer "In13.Cu")
		(net "M_B_CPU1_SB_DQ<18>")
	)
	(segment
		(start 76.48321 -284.715966)
		(end 77.53223 -284.715966)
		(width 0.0889)
		(layer "In13.Cu")
		(net "M_B_CPU1_SB_DQ<18>")
	)
	(segment
		(start 49.15408 -301.681134)
		(end 49.15408 -301.179992)
		(width 0.14478)
		(layer "In13.Cu")
		(net "M_B_CPU1_SB_DQ<18>")
	)
	(segment
		(start 87.7951 -284.350968)
		(end 87.640922 -284.616398)
		(width 0.0889)
		(layer "In13.Cu")
		(net "M_B_CPU1_SB_DQ<18>")
	)
	(segment
		(start 56.95315 -301.460408)
		(end 57.803288 -300.61027)
		(width 0.14478)
		(layer "In13.Cu")
		(net "M_B_CPU1_SB_DQ<18>")
	)
	(segment
		(start 75.49642 -284.922214)
		(end 75.973686 -284.922214)
		(width 0.14478)
		(layer "In13.Cu")
		(net "M_B_CPU1_SB_DQ<18>")
	)
	(segment
		(start 49.29886 -301.035212)
		(end 49.566322 -301.035212)
		(width 0.14478)
		(layer "In13.Cu")
		(net "M_B_CPU1_SB_DQ<18>")
	)
	(segment
		(start 79.36738 -284.293818)
		(end 79.377794 -284.299914)
		(width 0.0889)
		(layer "In13.Cu")
		(net "M_B_CPU1_SB_DQ<18>")
	)
	(segment
		(start 50.924206 -301.345092)
		(end 51.068986 -301.200312)
		(width 0.14478)
		(layer "In13.Cu")
		(net "M_B_CPU1_SB_DQ<18>")
	)
	(segment
		(start 57.803288 -300.61027)
		(end 59.808364 -300.61027)
		(width 0.14478)
		(layer "In13.Cu")
		(net "M_B_CPU1_SB_DQ<18>")
	)
	(segment
		(start 48.6029 -301.681134)
		(end 48.74768 -301.825914)
		(width 0.14478)
		(layer "In13.Cu")
		(net "M_B_CPU1_SB_DQ<18>")
	)
	(segment
		(start 76.276962 -284.922214)
		(end 76.48321 -284.715966)
		(width 0.0889)
		(layer "In13.Cu")
		(net "M_B_CPU1_SB_DQ<18>")
	)
	(segment
		(start 49.566322 -301.035212)
		(end 49.991264 -300.61027)
		(width 0.14478)
		(layer "In13.Cu")
		(net "M_B_CPU1_SB_DQ<18>")
	)
	(segment
		(start 77.878178 -284.370018)
		(end 78.711044 -284.370018)
		(width 0.0889)
		(layer "In13.Cu")
		(net "M_B_CPU1_SB_DQ<18>")
	)
	(segment
		(start 85.948012 -284.293818)
		(end 85.948266 -284.293818)
		(width 0.0889)
		(layer "In13.Cu")
		(net "M_B_CPU1_SB_DQ<18>")
	)
	(segment
		(start 83.694016 -284.293818)
		(end 83.702398 -284.288992)
		(width 0.0889)
		(layer "In13.Cu")
		(net "M_B_CPU1_SB_DQ<18>")
	)
	(segment
		(start 87.453978 -284.293818)
		(end 87.46236 -284.288992)
		(width 0.0889)
		(layer "In13.Cu")
		(net "M_B_CPU1_SB_DQ<18>")
	)
	(segment
		(start 85.93963 -284.288992)
		(end 85.948012 -284.293818)
		(width 0.0889)
		(layer "In13.Cu")
		(net "M_B_CPU1_SB_DQ<18>")
	)
	(segment
		(start 48.45812 -301.035212)
		(end 48.6029 -301.179992)
		(width 0.14478)
		(layer "In13.Cu")
		(net "M_B_CPU1_SB_DQ<18>")
	)
	(segment
		(start 48.74768 -301.825914)
		(end 49.0093 -301.825914)
		(width 0.14478)
		(layer "In13.Cu")
		(net "M_B_CPU1_SB_DQ<18>")
	)
	(segment
		(start 51.213766 -300.61027)
		(end 54.090824 -300.61027)
		(width 0.14478)
		(layer "In13.Cu")
		(net "M_B_CPU1_SB_DQ<18>")
	)
	(segment
		(start 50.373026 -300.61027)
		(end 50.517806 -300.75505)
		(width 0.14478)
		(layer "In13.Cu")
		(net "M_B_CPU1_SB_DQ<18>")
	)
	(arc
		(start 86.513924 -284.293818)
		(mid 86.696175 -284.243468)
		(end 86.879684 -284.288992)
		(width 0.0889)
		(layer "In13.Cu")
		(net "M_B_CPU1_SB_DQ<18>")
	)
	(arc
		(start 81.247996 -284.293818)
		(mid 81.530952 -284.369995)
		(end 81.813908 -284.293818)
		(width 0.0889)
		(layer "In13.Cu")
		(net "M_B_CPU1_SB_DQ<18>")
	)
	(arc
		(start 78.711044 -284.370018)
		(mid 78.857292 -284.350713)
		(end 78.993492 -284.294072)
		(width 0.0889)
		(layer "In13.Cu")
		(net "M_B_CPU1_SB_DQ<18>")
	)
	(arc
		(start 79.933546 -284.293818)
		(mid 80.116051 -284.243341)
		(end 80.299814 -284.288992)
		(width 0.0889)
		(layer "In13.Cu")
		(net "M_B_CPU1_SB_DQ<18>")
	)
	(arc
		(start 82.18805 -284.293818)
		(mid 82.471006 -284.369995)
		(end 82.753962 -284.293818)
		(width 0.0889)
		(layer "In13.Cu")
		(net "M_B_CPU1_SB_DQ<18>")
	)
	(arc
		(start 83.702398 -284.288992)
		(mid 83.885906 -284.243498)
		(end 84.068158 -284.293818)
		(width 0.0889)
		(layer "In13.Cu")
		(net "M_B_CPU1_SB_DQ<18>")
	)
	(arc
		(start 85.007958 -284.293818)
		(mid 85.290914 -284.369995)
		(end 85.57387 -284.293818)
		(width 0.0889)
		(layer "In13.Cu")
		(net "M_B_CPU1_SB_DQ<18>")
	)
	(arc
		(start 83.128104 -284.293818)
		(mid 83.41106 -284.369995)
		(end 83.694016 -284.293818)
		(width 0.0889)
		(layer "In13.Cu")
		(net "M_B_CPU1_SB_DQ<18>")
	)
	(arc
		(start 82.762344 -284.288992)
		(mid 82.945852 -284.243498)
		(end 83.128104 -284.293818)
		(width 0.0889)
		(layer "In13.Cu")
		(net "M_B_CPU1_SB_DQ<18>")
	)
	(arc
		(start 85.948266 -284.293818)
		(mid 86.231112 -284.369995)
		(end 86.513924 -284.293818)
		(width 0.0889)
		(layer "In13.Cu")
		(net "M_B_CPU1_SB_DQ<18>")
	)
	(arc
		(start 87.46236 -284.288992)
		(mid 87.61523 -284.244351)
		(end 87.772748 -284.267656)
		(width 0.0889)
		(layer "In13.Cu")
		(net "M_B_CPU1_SB_DQ<18>")
	)
	(arc
		(start 86.888066 -284.293818)
		(mid 87.171022 -284.369995)
		(end 87.453978 -284.293818)
		(width 0.0889)
		(layer "In13.Cu")
		(net "M_B_CPU1_SB_DQ<18>")
	)
	(arc
		(start 80.308196 -284.293818)
		(mid 80.591152 -284.369995)
		(end 80.874108 -284.293818)
		(width 0.0889)
		(layer "In13.Cu")
		(net "M_B_CPU1_SB_DQ<18>")
	)
	(arc
		(start 85.57387 -284.293818)
		(mid 85.756121 -284.243468)
		(end 85.93963 -284.288992)
		(width 0.0889)
		(layer "In13.Cu")
		(net "M_B_CPU1_SB_DQ<18>")
	)
	(arc
		(start 81.813908 -284.293818)
		(mid 81.996159 -284.243468)
		(end 82.179668 -284.288992)
		(width 0.0889)
		(layer "In13.Cu")
		(net "M_B_CPU1_SB_DQ<18>")
	)
	(arc
		(start 80.874108 -284.293818)
		(mid 81.061052 -284.243563)
		(end 81.247996 -284.293818)
		(width 0.0889)
		(layer "In13.Cu")
		(net "M_B_CPU1_SB_DQ<18>")
	)
	(arc
		(start 79.377794 -284.299914)
		(mid 79.65648 -284.370134)
		(end 79.933546 -284.293818)
		(width 0.0889)
		(layer "In13.Cu")
		(net "M_B_CPU1_SB_DQ<18>")
	)
	(arc
		(start 84.068158 -284.293818)
		(mid 84.351114 -284.369995)
		(end 84.63407 -284.293818)
		(width 0.0889)
		(layer "In13.Cu")
		(net "M_B_CPU1_SB_DQ<18>")
	)
	(arc
		(start 84.63407 -284.293818)
		(mid 84.821014 -284.243563)
		(end 85.007958 -284.293818)
		(width 0.0889)
		(layer "In13.Cu")
		(net "M_B_CPU1_SB_DQ<18>")
	)
	(arc
		(start 79.009748 -284.284674)
		(mid 79.18973 -284.243574)
		(end 79.36738 -284.293818)
		(width 0.0889)
		(layer "In13.Cu")
		(net "M_B_CPU1_SB_DQ<18>")
	)
	(segment
		(start 89.987882 -284.35046)
		(end 89.52103 -284.616398)
		(width 0.10668)
		(layer "F.Cu")
		(net "M_B_CPU1_SB_DQ<17>")
	)
	(segment
		(start 57.905142 -301.151544)
		(end 58.239152 -301.151544)
		(width 0.14478)
		(layer "In13.Cu")
		(net "M_B_CPU1_SB_DQ<17>")
	)
	(segment
		(start 59.916314 -301.71771)
		(end 60.164218 -301.71771)
		(width 0.14478)
		(layer "In13.Cu")
		(net "M_B_CPU1_SB_DQ<17>")
	)
	(segment
		(start 53.550566 -302.310292)
		(end 53.695346 -302.165512)
		(width 0.14478)
		(layer "In13.Cu")
		(net "M_B_CPU1_SB_DQ<17>")
	)
	(segment
		(start 58.39333 -301.305722)
		(end 58.39333 -301.55134)
		(width 0.14478)
		(layer "In13.Cu")
		(net "M_B_CPU1_SB_DQ<17>")
	)
	(segment
		(start 80.299814 -284.943804)
		(end 80.308196 -284.938978)
		(width 0.0889)
		(layer "In13.Cu")
		(net "M_B_CPU1_SB_DQ<17>")
	)
	(segment
		(start 58.807858 -301.717964)
		(end 59.065668 -301.460154)
		(width 0.14478)
		(layer "In13.Cu")
		(net "M_B_CPU1_SB_DQ<17>")
	)
	(segment
		(start 75.958446 -285.376874)
		(end 76.307442 -285.376874)
		(width 0.0889)
		(layer "In13.Cu")
		(net "M_B_CPU1_SB_DQ<17>")
	)
	(segment
		(start 86.879684 -284.943804)
		(end 86.888066 -284.938978)
		(width 0.0889)
		(layer "In13.Cu")
		(net "M_B_CPU1_SB_DQ<17>")
	)
	(segment
		(start 58.559954 -301.717964)
		(end 58.807858 -301.717964)
		(width 0.14478)
		(layer "In13.Cu")
		(net "M_B_CPU1_SB_DQ<17>")
	)
	(segment
		(start 89.367106 -284.881828)
		(end 89.52103 -284.616398)
		(width 0.0889)
		(layer "In13.Cu")
		(net "M_B_CPU1_SB_DQ<17>")
	)
	(segment
		(start 52.393596 -302.310292)
		(end 52.538376 -302.165512)
		(width 0.14478)
		(layer "In13.Cu")
		(net "M_B_CPU1_SB_DQ<17>")
	)
	(segment
		(start 58.239152 -301.151544)
		(end 58.39333 -301.305722)
		(width 0.14478)
		(layer "In13.Cu")
		(net "M_B_CPU1_SB_DQ<17>")
	)
	(segment
		(start 53.695346 -302.165512)
		(end 53.695346 -301.603664)
		(width 0.14478)
		(layer "In13.Cu")
		(net "M_B_CPU1_SB_DQ<17>")
	)
	(segment
		(start 78.977744 -284.92958)
		(end 78.993492 -284.938724)
		(width 0.0889)
		(layer "In13.Cu")
		(net "M_B_CPU1_SB_DQ<17>")
	)
	(segment
		(start 85.93963 -284.943804)
		(end 85.948012 -284.938978)
		(width 0.0889)
		(layer "In13.Cu")
		(net "M_B_CPU1_SB_DQ<17>")
	)
	(segment
		(start 59.658758 -301.460154)
		(end 59.916314 -301.71771)
		(width 0.14478)
		(layer "In13.Cu")
		(net "M_B_CPU1_SB_DQ<17>")
	)
	(segment
		(start 60.164218 -301.71771)
		(end 60.318396 -301.563532)
		(width 0.14478)
		(layer "In13.Cu")
		(net "M_B_CPU1_SB_DQ<17>")
	)
	(segment
		(start 54.391306 -302.310292)
		(end 56.746394 -302.310292)
		(width 0.14478)
		(layer "In13.Cu")
		(net "M_B_CPU1_SB_DQ<17>")
	)
	(segment
		(start 52.538376 -301.245524)
		(end 52.683156 -301.100744)
		(width 0.14478)
		(layer "In13.Cu")
		(net "M_B_CPU1_SB_DQ<17>")
	)
	(segment
		(start 53.089556 -302.165512)
		(end 53.234336 -302.310292)
		(width 0.14478)
		(layer "In13.Cu")
		(net "M_B_CPU1_SB_DQ<17>")
	)
	(segment
		(start 56.746394 -302.310292)
		(end 57.905142 -301.151544)
		(width 0.14478)
		(layer "In13.Cu")
		(net "M_B_CPU1_SB_DQ<17>")
	)
	(segment
		(start 87.453978 -284.938978)
		(end 87.46236 -284.943804)
		(width 0.0889)
		(layer "In13.Cu")
		(net "M_B_CPU1_SB_DQ<17>")
	)
	(segment
		(start 76.307442 -285.376874)
		(end 76.594716 -285.0896)
		(width 0.0889)
		(layer "In13.Cu")
		(net "M_B_CPU1_SB_DQ<17>")
	)
	(segment
		(start 75.677776 -285.376874)
		(end 75.958446 -285.376874)
		(width 0.14478)
		(layer "In13.Cu")
		(net "M_B_CPU1_SB_DQ<17>")
	)
	(segment
		(start 60.318396 -301.563532)
		(end 60.318396 -300.736254)
		(width 0.14478)
		(layer "In13.Cu")
		(net "M_B_CPU1_SB_DQ<17>")
	)
	(segment
		(start 52.046886 -302.310292)
		(end 52.393596 -302.310292)
		(width 0.14478)
		(layer "In13.Cu")
		(net "M_B_CPU1_SB_DQ<17>")
	)
	(segment
		(start 59.065668 -301.460154)
		(end 59.658758 -301.460154)
		(width 0.14478)
		(layer "In13.Cu")
		(net "M_B_CPU1_SB_DQ<17>")
	)
	(segment
		(start 85.948012 -284.938978)
		(end 85.948266 -284.938978)
		(width 0.0889)
		(layer "In13.Cu")
		(net "M_B_CPU1_SB_DQ<17>")
	)
	(segment
		(start 53.089556 -301.245524)
		(end 53.089556 -302.165512)
		(width 0.14478)
		(layer "In13.Cu")
		(net "M_B_CPU1_SB_DQ<17>")
	)
	(segment
		(start 52.944776 -301.100744)
		(end 53.089556 -301.245524)
		(width 0.14478)
		(layer "In13.Cu")
		(net "M_B_CPU1_SB_DQ<17>")
	)
	(segment
		(start 53.695346 -301.603664)
		(end 53.840126 -301.458884)
		(width 0.14478)
		(layer "In13.Cu")
		(net "M_B_CPU1_SB_DQ<17>")
	)
	(segment
		(start 51.884072 -301.88535)
		(end 51.884072 -302.147478)
		(width 0.14478)
		(layer "In13.Cu")
		(net "M_B_CPU1_SB_DQ<17>")
	)
	(segment
		(start 83.694016 -284.938978)
		(end 83.702398 -284.943804)
		(width 0.0889)
		(layer "In13.Cu")
		(net "M_B_CPU1_SB_DQ<17>")
	)
	(segment
		(start 82.179668 -284.943804)
		(end 82.18805 -284.938978)
		(width 0.0889)
		(layer "In13.Cu")
		(net "M_B_CPU1_SB_DQ<17>")
	)
	(segment
		(start 53.840126 -301.458884)
		(end 54.101746 -301.458884)
		(width 0.14478)
		(layer "In13.Cu")
		(net "M_B_CPU1_SB_DQ<17>")
	)
	(segment
		(start 78.993492 -284.938724)
		(end 79.007208 -284.946598)
		(width 0.0889)
		(layer "In13.Cu")
		(net "M_B_CPU1_SB_DQ<17>")
	)
	(segment
		(start 58.39333 -301.55134)
		(end 58.559954 -301.717964)
		(width 0.14478)
		(layer "In13.Cu")
		(net "M_B_CPU1_SB_DQ<17>")
	)
	(segment
		(start 54.246526 -301.603664)
		(end 54.246526 -302.165512)
		(width 0.14478)
		(layer "In13.Cu")
		(net "M_B_CPU1_SB_DQ<17>")
	)
	(segment
		(start 51.884072 -302.147478)
		(end 52.046886 -302.310292)
		(width 0.14478)
		(layer "In13.Cu")
		(net "M_B_CPU1_SB_DQ<17>")
	)
	(segment
		(start 76.67498 -285.056326)
		(end 77.992224 -285.056326)
		(width 0.0889)
		(layer "In13.Cu")
		(net "M_B_CPU1_SB_DQ<17>")
	)
	(segment
		(start 53.234336 -302.310292)
		(end 53.550566 -302.310292)
		(width 0.14478)
		(layer "In13.Cu")
		(net "M_B_CPU1_SB_DQ<17>")
	)
	(segment
		(start 79.367126 -284.938978)
		(end 79.381858 -284.930342)
		(width 0.0889)
		(layer "In13.Cu")
		(net "M_B_CPU1_SB_DQ<17>")
	)
	(segment
		(start 54.101746 -301.458884)
		(end 54.246526 -301.603664)
		(width 0.14478)
		(layer "In13.Cu")
		(net "M_B_CPU1_SB_DQ<17>")
	)
	(segment
		(start 78.427834 -284.938978)
		(end 78.42758 -284.938978)
		(width 0.0889)
		(layer "In13.Cu")
		(net "M_B_CPU1_SB_DQ<17>")
	)
	(segment
		(start 60.318396 -300.736254)
		(end 75.677776 -285.376874)
		(width 0.14478)
		(layer "In13.Cu")
		(net "M_B_CPU1_SB_DQ<17>")
	)
	(segment
		(start 52.683156 -301.100744)
		(end 52.944776 -301.100744)
		(width 0.14478)
		(layer "In13.Cu")
		(net "M_B_CPU1_SB_DQ<17>")
	)
	(segment
		(start 88.394032 -284.938978)
		(end 88.402414 -284.943804)
		(width 0.0889)
		(layer "In13.Cu")
		(net "M_B_CPU1_SB_DQ<17>")
	)
	(segment
		(start 54.246526 -302.165512)
		(end 54.391306 -302.310292)
		(width 0.14478)
		(layer "In13.Cu")
		(net "M_B_CPU1_SB_DQ<17>")
	)
	(segment
		(start 52.538376 -302.165512)
		(end 52.538376 -301.245524)
		(width 0.14478)
		(layer "In13.Cu")
		(net "M_B_CPU1_SB_DQ<17>")
	)
	(segment
		(start 89.271094 -284.907228)
		(end 89.367106 -284.881828)
		(width 0.0889)
		(layer "In13.Cu")
		(net "M_B_CPU1_SB_DQ<17>")
	)
	(segment
		(start 82.753962 -284.938978)
		(end 82.762344 -284.943804)
		(width 0.0889)
		(layer "In13.Cu")
		(net "M_B_CPU1_SB_DQ<17>")
	)
	(arc
		(start 85.007958 -284.938978)
		(mid 85.290914 -284.862801)
		(end 85.57387 -284.938978)
		(width 0.0889)
		(layer "In13.Cu")
		(net "M_B_CPU1_SB_DQ<17>")
	)
	(arc
		(start 81.813908 -284.938978)
		(mid 81.996159 -284.989328)
		(end 82.179668 -284.943804)
		(width 0.0889)
		(layer "In13.Cu")
		(net "M_B_CPU1_SB_DQ<17>")
	)
	(arc
		(start 85.948266 -284.938978)
		(mid 86.231112 -284.862801)
		(end 86.513924 -284.938978)
		(width 0.0889)
		(layer "In13.Cu")
		(net "M_B_CPU1_SB_DQ<17>")
	)
	(arc
		(start 87.46236 -284.943804)
		(mid 87.645868 -284.989298)
		(end 87.82812 -284.938978)
		(width 0.0889)
		(layer "In13.Cu")
		(net "M_B_CPU1_SB_DQ<17>")
	)
	(arc
		(start 80.874108 -284.938978)
		(mid 81.061052 -284.989233)
		(end 81.247996 -284.938978)
		(width 0.0889)
		(layer "In13.Cu")
		(net "M_B_CPU1_SB_DQ<17>")
	)
	(arc
		(start 86.513924 -284.938978)
		(mid 86.696175 -284.989328)
		(end 86.879684 -284.943804)
		(width 0.0889)
		(layer "In13.Cu")
		(net "M_B_CPU1_SB_DQ<17>")
	)
	(arc
		(start 81.247996 -284.938978)
		(mid 81.530952 -284.862801)
		(end 81.813908 -284.938978)
		(width 0.0889)
		(layer "In13.Cu")
		(net "M_B_CPU1_SB_DQ<17>")
	)
	(arc
		(start 88.402414 -284.943804)
		(mid 88.585922 -284.989298)
		(end 88.768174 -284.938978)
		(width 0.0889)
		(layer "In13.Cu")
		(net "M_B_CPU1_SB_DQ<17>")
	)
	(arc
		(start 85.57387 -284.938978)
		(mid 85.756121 -284.989328)
		(end 85.93963 -284.943804)
		(width 0.0889)
		(layer "In13.Cu")
		(net "M_B_CPU1_SB_DQ<17>")
	)
	(arc
		(start 79.933546 -284.938978)
		(mid 80.116051 -284.989455)
		(end 80.299814 -284.943804)
		(width 0.0889)
		(layer "In13.Cu")
		(net "M_B_CPU1_SB_DQ<17>")
	)
	(arc
		(start 84.63407 -284.938978)
		(mid 84.821014 -284.989233)
		(end 85.007958 -284.938978)
		(width 0.0889)
		(layer "In13.Cu")
		(net "M_B_CPU1_SB_DQ<17>")
	)
	(arc
		(start 82.762344 -284.943804)
		(mid 82.945852 -284.989298)
		(end 83.128104 -284.938978)
		(width 0.0889)
		(layer "In13.Cu")
		(net "M_B_CPU1_SB_DQ<17>")
	)
	(arc
		(start 80.308196 -284.938978)
		(mid 80.591152 -284.862801)
		(end 80.874108 -284.938978)
		(width 0.0889)
		(layer "In13.Cu")
		(net "M_B_CPU1_SB_DQ<17>")
	)
	(arc
		(start 88.768174 -284.938978)
		(mid 89.015887 -284.863758)
		(end 89.271094 -284.907228)
		(width 0.0889)
		(layer "In13.Cu")
		(net "M_B_CPU1_SB_DQ<17>")
	)
	(arc
		(start 79.381858 -284.930342)
		(mid 79.658841 -284.862538)
		(end 79.933546 -284.938978)
		(width 0.0889)
		(layer "In13.Cu")
		(net "M_B_CPU1_SB_DQ<17>")
	)
	(arc
		(start 76.594716 -285.0896)
		(mid 76.631527 -285.06494)
		(end 76.67498 -285.056326)
		(width 0.0889)
		(layer "In13.Cu")
		(net "M_B_CPU1_SB_DQ<17>")
	)
	(arc
		(start 82.18805 -284.938978)
		(mid 82.471006 -284.862801)
		(end 82.753962 -284.938978)
		(width 0.0889)
		(layer "In13.Cu")
		(net "M_B_CPU1_SB_DQ<17>")
	)
	(arc
		(start 79.007208 -284.946598)
		(mid 79.188138 -284.989076)
		(end 79.367126 -284.938978)
		(width 0.0889)
		(layer "In13.Cu")
		(net "M_B_CPU1_SB_DQ<17>")
	)
	(arc
		(start 78.42758 -284.938978)
		(mid 78.701435 -284.862628)
		(end 78.977744 -284.92958)
		(width 0.0889)
		(layer "In13.Cu")
		(net "M_B_CPU1_SB_DQ<17>")
	)
	(arc
		(start 83.128104 -284.938978)
		(mid 83.41106 -284.862801)
		(end 83.694016 -284.938978)
		(width 0.0889)
		(layer "In13.Cu")
		(net "M_B_CPU1_SB_DQ<17>")
	)
	(arc
		(start 87.82812 -284.938978)
		(mid 88.111076 -284.862801)
		(end 88.394032 -284.938978)
		(width 0.0889)
		(layer "In13.Cu")
		(net "M_B_CPU1_SB_DQ<17>")
	)
	(arc
		(start 77.992224 -285.056326)
		(mid 78.217789 -285.026466)
		(end 78.427834 -284.938978)
		(width 0.0889)
		(layer "In13.Cu")
		(net "M_B_CPU1_SB_DQ<17>")
	)
	(arc
		(start 84.068158 -284.938978)
		(mid 84.351114 -284.862801)
		(end 84.63407 -284.938978)
		(width 0.0889)
		(layer "In13.Cu")
		(net "M_B_CPU1_SB_DQ<17>")
	)
	(arc
		(start 86.888066 -284.938978)
		(mid 87.171022 -284.862801)
		(end 87.453978 -284.938978)
		(width 0.0889)
		(layer "In13.Cu")
		(net "M_B_CPU1_SB_DQ<17>")
	)
	(arc
		(start 83.702398 -284.943804)
		(mid 83.885906 -284.989298)
		(end 84.068158 -284.938978)
		(width 0.0889)
		(layer "In13.Cu")
		(net "M_B_CPU1_SB_DQ<17>")
	)
	(segment
		(start 88.577928 -283.540454)
		(end 88.111076 -283.806392)
		(width 0.10668)
		(layer "F.Cu")
		(net "M_B_CPU1_SB_DQ<16>")
	)
	(segment
		(start 53.040534 -299.996606)
		(end 53.040534 -299.640244)
		(width 0.14478)
		(layer "In13.Cu")
		(net "M_B_CPU1_SB_DQ<16>")
	)
	(segment
		(start 56.430926 -300.09973)
		(end 56.269382 -299.938186)
		(width 0.14478)
		(layer "In13.Cu")
		(net "M_B_CPU1_SB_DQ<16>")
	)
	(segment
		(start 57.046622 -300.1137)
		(end 57.046622 -300.318424)
		(width 0.14478)
		(layer "In13.Cu")
		(net "M_B_CPU1_SB_DQ<16>")
	)
	(segment
		(start 69.864478 -289.712908)
		(end 69.864478 -289.91814)
		(width 0.14478)
		(layer "In13.Cu")
		(net "M_B_CPU1_SB_DQ<16>")
	)
	(segment
		(start 67.812412 -291.764974)
		(end 67.525138 -292.052248)
		(width 0.14478)
		(layer "In13.Cu")
		(net "M_B_CPU1_SB_DQ<16>")
	)
	(segment
		(start 57.536842 -300.028864)
		(end 57.436512 -299.928534)
		(width 0.14478)
		(layer "In13.Cu")
		(net "M_B_CPU1_SB_DQ<16>")
	)
	(segment
		(start 69.371972 -290.205414)
		(end 69.084698 -290.492688)
		(width 0.14478)
		(layer "In13.Cu")
		(net "M_B_CPU1_SB_DQ<16>")
	)
	(segment
		(start 54.82209 -300.061122)
		(end 54.67731 -299.916342)
		(width 0.14478)
		(layer "In13.Cu")
		(net "M_B_CPU1_SB_DQ<16>")
	)
	(segment
		(start 72.696324 -287.086294)
		(end 72.491092 -287.086294)
		(width 0.14478)
		(layer "In13.Cu")
		(net "M_B_CPU1_SB_DQ<16>")
	)
	(segment
		(start 67.525138 -292.25748)
		(end 67.237864 -292.544754)
		(width 0.14478)
		(layer "In13.Cu")
		(net "M_B_CPU1_SB_DQ<16>")
	)
	(segment
		(start 52.489354 -299.640244)
		(end 52.489354 -299.996606)
		(width 0.14478)
		(layer "In13.Cu")
		(net "M_B_CPU1_SB_DQ<16>")
	)
	(segment
		(start 69.577204 -290.205414)
		(end 69.371972 -290.205414)
		(width 0.14478)
		(layer "In13.Cu")
		(net "M_B_CPU1_SB_DQ<16>")
	)
	(segment
		(start 75.035664 -284.746954)
		(end 74.830432 -284.746954)
		(width 0.14478)
		(layer "In13.Cu")
		(net "M_B_CPU1_SB_DQ<16>")
	)
	(segment
		(start 69.084698 -290.492688)
		(end 69.084698 -290.69792)
		(width 0.14478)
		(layer "In13.Cu")
		(net "M_B_CPU1_SB_DQ<16>")
	)
	(segment
		(start 74.543158 -285.034228)
		(end 74.543158 -285.23946)
		(width 0.14478)
		(layer "In13.Cu")
		(net "M_B_CPU1_SB_DQ<16>")
	)
	(segment
		(start 73.476104 -286.306514)
		(end 73.270872 -286.306514)
		(width 0.14478)
		(layer "In13.Cu")
		(net "M_B_CPU1_SB_DQ<16>")
	)
	(segment
		(start 72.203818 -287.5788)
		(end 71.916544 -287.866074)
		(width 0.14478)
		(layer "In13.Cu")
		(net "M_B_CPU1_SB_DQ<16>")
	)
	(segment
		(start 61.779404 -298.003214)
		(end 61.574172 -298.003214)
		(width 0.14478)
		(layer "In13.Cu")
		(net "M_B_CPU1_SB_DQ<16>")
	)
	(segment
		(start 60.022232 -299.760386)
		(end 59.383422 -299.760386)
		(width 0.14478)
		(layer "In13.Cu")
		(net "M_B_CPU1_SB_DQ<16>")
	)
	(segment
		(start 73.763378 -285.814008)
		(end 73.763378 -286.01924)
		(width 0.14478)
		(layer "In13.Cu")
		(net "M_B_CPU1_SB_DQ<16>")
	)
	(segment
		(start 54.82209 -300.705266)
		(end 54.82209 -300.061122)
		(width 0.14478)
		(layer "In13.Cu")
		(net "M_B_CPU1_SB_DQ<16>")
	)
	(segment
		(start 71.424038 -288.35858)
		(end 71.136764 -288.645854)
		(width 0.14478)
		(layer "In13.Cu")
		(net "M_B_CPU1_SB_DQ<16>")
	)
	(segment
		(start 71.136764 -288.645854)
		(end 70.931532 -288.645854)
		(width 0.14478)
		(layer "In13.Cu")
		(net "M_B_CPU1_SB_DQ<16>")
	)
	(segment
		(start 65.965578 -293.81704)
		(end 65.678304 -294.104314)
		(width 0.14478)
		(layer "In13.Cu")
		(net "M_B_CPU1_SB_DQ<16>")
	)
	(segment
		(start 56.430926 -300.82236)
		(end 56.430926 -300.09973)
		(width 0.14478)
		(layer "In13.Cu")
		(net "M_B_CPU1_SB_DQ<16>")
	)
	(segment
		(start 69.864478 -289.91814)
		(end 69.577204 -290.205414)
		(width 0.14478)
		(layer "In13.Cu")
		(net "M_B_CPU1_SB_DQ<16>")
	)
	(segment
		(start 54.106826 -300.141386)
		(end 53.185314 -300.141386)
		(width 0.14478)
		(layer "In13.Cu")
		(net "M_B_CPU1_SB_DQ<16>")
	)
	(segment
		(start 77.967078 -283.946346)
		(end 76.78547 -283.946346)
		(width 0.0889)
		(layer "In13.Cu")
		(net "M_B_CPU1_SB_DQ<16>")
	)
	(segment
		(start 78.71079 -284.179518)
		(end 78.20025 -284.179518)
		(width 0.0889)
		(layer "In13.Cu")
		(net "M_B_CPU1_SB_DQ<16>")
	)
	(segment
		(start 65.678304 -294.104314)
		(end 65.473072 -294.104314)
		(width 0.14478)
		(layer "In13.Cu")
		(net "M_B_CPU1_SB_DQ<16>")
	)
	(segment
		(start 54.33187 -299.916342)
		(end 54.106826 -300.141386)
		(width 0.14478)
		(layer "In13.Cu")
		(net "M_B_CPU1_SB_DQ<16>")
	)
	(segment
		(start 74.543158 -285.23946)
		(end 74.255884 -285.526734)
		(width 0.14478)
		(layer "In13.Cu")
		(net "M_B_CPU1_SB_DQ<16>")
	)
	(segment
		(start 66.458084 -293.324534)
		(end 66.252852 -293.324534)
		(width 0.14478)
		(layer "In13.Cu")
		(net "M_B_CPU1_SB_DQ<16>")
	)
	(segment
		(start 57.231788 -299.928534)
		(end 57.046622 -300.1137)
		(width 0.14478)
		(layer "In13.Cu")
		(net "M_B_CPU1_SB_DQ<16>")
	)
	(segment
		(start 70.644258 -289.13836)
		(end 70.356984 -289.425634)
		(width 0.14478)
		(layer "In13.Cu")
		(net "M_B_CPU1_SB_DQ<16>")
	)
	(segment
		(start 55.879492 -300.82236)
		(end 55.717948 -300.983904)
		(width 0.14478)
		(layer "In13.Cu")
		(net "M_B_CPU1_SB_DQ<16>")
	)
	(segment
		(start 87.956898 -284.071822)
		(end 87.860632 -284.097222)
		(width 0.0889)
		(layer "In13.Cu")
		(net "M_B_CPU1_SB_DQ<16>")
	)
	(segment
		(start 61.286898 -298.290488)
		(end 61.286898 -298.49572)
		(width 0.14478)
		(layer "In13.Cu")
		(net "M_B_CPU1_SB_DQ<16>")
	)
	(segment
		(start 64.118744 -295.663874)
		(end 63.913512 -295.663874)
		(width 0.14478)
		(layer "In13.Cu")
		(net "M_B_CPU1_SB_DQ<16>")
	)
	(segment
		(start 73.270872 -286.306514)
		(end 72.983598 -286.593788)
		(width 0.14478)
		(layer "In13.Cu")
		(net "M_B_CPU1_SB_DQ<16>")
	)
	(segment
		(start 76.264262 -284.467554)
		(end 75.963526 -284.467554)
		(width 0.0889)
		(layer "In13.Cu")
		(net "M_B_CPU1_SB_DQ<16>")
	)
	(segment
		(start 62.066678 -297.71594)
		(end 61.779404 -298.003214)
		(width 0.14478)
		(layer "In13.Cu")
		(net "M_B_CPU1_SB_DQ<16>")
	)
	(segment
		(start 66.745358 -292.832028)
		(end 66.745358 -293.03726)
		(width 0.14478)
		(layer "In13.Cu")
		(net "M_B_CPU1_SB_DQ<16>")
	)
	(segment
		(start 55.717948 -300.983904)
		(end 55.100728 -300.983904)
		(width 0.14478)
		(layer "In13.Cu")
		(net "M_B_CPU1_SB_DQ<16>")
	)
	(segment
		(start 65.473072 -294.104314)
		(end 65.185798 -294.391588)
		(width 0.14478)
		(layer "In13.Cu")
		(net "M_B_CPU1_SB_DQ<16>")
	)
	(segment
		(start 68.304918 -291.4777)
		(end 68.017644 -291.764974)
		(width 0.14478)
		(layer "In13.Cu")
		(net "M_B_CPU1_SB_DQ<16>")
	)
	(segment
		(start 64.693292 -294.884094)
		(end 64.406018 -295.171368)
		(width 0.14478)
		(layer "In13.Cu")
		(net "M_B_CPU1_SB_DQ<16>")
	)
	(segment
		(start 67.032632 -292.544754)
		(end 66.745358 -292.832028)
		(width 0.14478)
		(layer "In13.Cu")
		(net "M_B_CPU1_SB_DQ<16>")
	)
	(segment
		(start 70.644258 -288.933128)
		(end 70.644258 -289.13836)
		(width 0.14478)
		(layer "In13.Cu")
		(net "M_B_CPU1_SB_DQ<16>")
	)
	(segment
		(start 71.711312 -287.866074)
		(end 71.424038 -288.153348)
		(width 0.14478)
		(layer "In13.Cu")
		(net "M_B_CPU1_SB_DQ<16>")
	)
	(segment
		(start 55.100728 -300.983904)
		(end 54.82209 -300.705266)
		(width 0.14478)
		(layer "In13.Cu")
		(net "M_B_CPU1_SB_DQ<16>")
	)
	(segment
		(start 67.237864 -292.544754)
		(end 67.032632 -292.544754)
		(width 0.14478)
		(layer "In13.Cu")
		(net "M_B_CPU1_SB_DQ<16>")
	)
	(segment
		(start 76.78547 -283.946346)
		(end 76.264262 -284.467554)
		(width 0.0889)
		(layer "In13.Cu")
		(net "M_B_CPU1_SB_DQ<16>")
	)
	(segment
		(start 71.916544 -287.866074)
		(end 71.711312 -287.866074)
		(width 0.14478)
		(layer "In13.Cu")
		(net "M_B_CPU1_SB_DQ<16>")
	)
	(segment
		(start 57.436512 -299.928534)
		(end 57.231788 -299.928534)
		(width 0.14478)
		(layer "In13.Cu")
		(net "M_B_CPU1_SB_DQ<16>")
	)
	(segment
		(start 66.745358 -293.03726)
		(end 66.458084 -293.324534)
		(width 0.14478)
		(layer "In13.Cu")
		(net "M_B_CPU1_SB_DQ<16>")
	)
	(segment
		(start 53.040534 -299.640244)
		(end 52.895754 -299.495464)
		(width 0.14478)
		(layer "In13.Cu")
		(net "M_B_CPU1_SB_DQ<16>")
	)
	(segment
		(start 86.052406 -284.133798)
		(end 86.044024 -284.128972)
		(width 0.0889)
		(layer "In13.Cu")
		(net "M_B_CPU1_SB_DQ<16>")
	)
	(segment
		(start 70.356984 -289.425634)
		(end 70.151752 -289.425634)
		(width 0.14478)
		(layer "In13.Cu")
		(net "M_B_CPU1_SB_DQ<16>")
	)
	(segment
		(start 69.084698 -290.69792)
		(end 68.797424 -290.985194)
		(width 0.14478)
		(layer "In13.Cu")
		(net "M_B_CPU1_SB_DQ<16>")
	)
	(segment
		(start 51.928014 -300.141386)
		(end 51.884072 -300.185328)
		(width 0.14478)
		(layer "In13.Cu")
		(net "M_B_CPU1_SB_DQ<16>")
	)
	(segment
		(start 56.786526 -300.983904)
		(end 56.59247 -300.983904)
		(width 0.14478)
		(layer "In13.Cu")
		(net "M_B_CPU1_SB_DQ<16>")
	)
	(segment
		(start 56.041036 -299.938186)
		(end 55.879492 -300.09973)
		(width 0.14478)
		(layer "In13.Cu")
		(net "M_B_CPU1_SB_DQ<16>")
	)
	(segment
		(start 52.634134 -299.495464)
		(end 52.489354 -299.640244)
		(width 0.14478)
		(layer "In13.Cu")
		(net "M_B_CPU1_SB_DQ<16>")
	)
	(segment
		(start 80.403954 -284.128972)
		(end 80.39354 -284.122876)
		(width 0.0889)
		(layer "In13.Cu")
		(net "M_B_CPU1_SB_DQ<16>")
	)
	(segment
		(start 74.255884 -285.526734)
		(end 74.050652 -285.526734)
		(width 0.14478)
		(layer "In13.Cu")
		(net "M_B_CPU1_SB_DQ<16>")
	)
	(segment
		(start 81.35239 -284.133798)
		(end 81.344008 -284.128972)
		(width 0.0889)
		(layer "In13.Cu")
		(net "M_B_CPU1_SB_DQ<16>")
	)
	(segment
		(start 85.112352 -284.133798)
		(end 85.10397 -284.128972)
		(width 0.0889)
		(layer "In13.Cu")
		(net "M_B_CPU1_SB_DQ<16>")
	)
	(segment
		(start 74.050652 -285.526734)
		(end 73.763378 -285.814008)
		(width 0.14478)
		(layer "In13.Cu")
		(net "M_B_CPU1_SB_DQ<16>")
	)
	(segment
		(start 67.525138 -292.052248)
		(end 67.525138 -292.25748)
		(width 0.14478)
		(layer "In13.Cu")
		(net "M_B_CPU1_SB_DQ<16>")
	)
	(segment
		(start 65.185798 -294.391588)
		(end 65.185798 -294.59682)
		(width 0.14478)
		(layer "In13.Cu")
		(net "M_B_CPU1_SB_DQ<16>")
	)
	(segment
		(start 64.406018 -295.3766)
		(end 64.118744 -295.663874)
		(width 0.14478)
		(layer "In13.Cu")
		(net "M_B_CPU1_SB_DQ<16>")
	)
	(segment
		(start 62.353952 -297.223434)
		(end 62.066678 -297.510708)
		(width 0.14478)
		(layer "In13.Cu")
		(net "M_B_CPU1_SB_DQ<16>")
	)
	(segment
		(start 62.559184 -297.223434)
		(end 62.353952 -297.223434)
		(width 0.14478)
		(layer "In13.Cu")
		(net "M_B_CPU1_SB_DQ<16>")
	)
	(segment
		(start 64.406018 -295.171368)
		(end 64.406018 -295.3766)
		(width 0.14478)
		(layer "In13.Cu")
		(net "M_B_CPU1_SB_DQ<16>")
	)
	(segment
		(start 80.778096 -284.128972)
		(end 80.769714 -284.133798)
		(width 0.0889)
		(layer "In13.Cu")
		(net "M_B_CPU1_SB_DQ<16>")
	)
	(segment
		(start 72.983598 -286.593788)
		(end 72.983598 -286.79902)
		(width 0.14478)
		(layer "In13.Cu")
		(net "M_B_CPU1_SB_DQ<16>")
	)
	(segment
		(start 70.151752 -289.425634)
		(end 69.864478 -289.712908)
		(width 0.14478)
		(layer "In13.Cu")
		(net "M_B_CPU1_SB_DQ<16>")
	)
	(segment
		(start 63.626238 -296.15638)
		(end 63.338964 -296.443654)
		(width 0.14478)
		(layer "In13.Cu")
		(net "M_B_CPU1_SB_DQ<16>")
	)
	(segment
		(start 64.898524 -294.884094)
		(end 64.693292 -294.884094)
		(width 0.14478)
		(layer "In13.Cu")
		(net "M_B_CPU1_SB_DQ<16>")
	)
	(segment
		(start 65.185798 -294.59682)
		(end 64.898524 -294.884094)
		(width 0.14478)
		(layer "In13.Cu")
		(net "M_B_CPU1_SB_DQ<16>")
	)
	(segment
		(start 57.146952 -300.418754)
		(end 57.146952 -300.623478)
		(width 0.14478)
		(layer "In13.Cu")
		(net "M_B_CPU1_SB_DQ<16>")
	)
	(segment
		(start 61.286898 -298.49572)
		(end 60.022232 -299.760386)
		(width 0.14478)
		(layer "In13.Cu")
		(net "M_B_CPU1_SB_DQ<16>")
	)
	(segment
		(start 72.983598 -286.79902)
		(end 72.696324 -287.086294)
		(width 0.14478)
		(layer "In13.Cu")
		(net "M_B_CPU1_SB_DQ<16>")
	)
	(segment
		(start 54.67731 -299.916342)
		(end 54.33187 -299.916342)
		(width 0.14478)
		(layer "In13.Cu")
		(net "M_B_CPU1_SB_DQ<16>")
	)
	(segment
		(start 68.304918 -291.272468)
		(end 68.304918 -291.4777)
		(width 0.14478)
		(layer "In13.Cu")
		(net "M_B_CPU1_SB_DQ<16>")
	)
	(segment
		(start 57.046622 -300.318424)
		(end 57.146952 -300.418754)
		(width 0.14478)
		(layer "In13.Cu")
		(net "M_B_CPU1_SB_DQ<16>")
	)
	(segment
		(start 88.111076 -283.806392)
		(end 87.956898 -284.071822)
		(width 0.0889)
		(layer "In13.Cu")
		(net "M_B_CPU1_SB_DQ<16>")
	)
	(segment
		(start 63.626238 -295.951148)
		(end 63.626238 -296.15638)
		(width 0.14478)
		(layer "In13.Cu")
		(net "M_B_CPU1_SB_DQ<16>")
	)
	(segment
		(start 59.383422 -299.760386)
		(end 59.000644 -300.143164)
		(width 0.14478)
		(layer "In13.Cu")
		(net "M_B_CPU1_SB_DQ<16>")
	)
	(segment
		(start 56.59247 -300.983904)
		(end 56.430926 -300.82236)
		(width 0.14478)
		(layer "In13.Cu")
		(net "M_B_CPU1_SB_DQ<16>")
	)
	(segment
		(start 75.963526 -284.467554)
		(end 75.315064 -284.467554)
		(width 0.14478)
		(layer "In13.Cu")
		(net "M_B_CPU1_SB_DQ<16>")
	)
	(segment
		(start 66.252852 -293.324534)
		(end 65.965578 -293.611808)
		(width 0.14478)
		(layer "In13.Cu")
		(net "M_B_CPU1_SB_DQ<16>")
	)
	(segment
		(start 79.47152 -284.133798)
		(end 79.463138 -284.128972)
		(width 0.0889)
		(layer "In13.Cu")
		(net "M_B_CPU1_SB_DQ<16>")
	)
	(segment
		(start 58.770012 -300.143164)
		(end 58.387234 -299.760386)
		(width 0.14478)
		(layer "In13.Cu")
		(net "M_B_CPU1_SB_DQ<16>")
	)
	(segment
		(start 56.269382 -299.938186)
		(end 56.041036 -299.938186)
		(width 0.14478)
		(layer "In13.Cu")
		(net "M_B_CPU1_SB_DQ<16>")
	)
	(segment
		(start 72.203818 -287.373568)
		(end 72.203818 -287.5788)
		(width 0.14478)
		(layer "In13.Cu")
		(net "M_B_CPU1_SB_DQ<16>")
	)
	(segment
		(start 70.931532 -288.645854)
		(end 70.644258 -288.933128)
		(width 0.14478)
		(layer "In13.Cu")
		(net "M_B_CPU1_SB_DQ<16>")
	)
	(segment
		(start 78.20025 -284.179518)
		(end 77.967078 -283.946346)
		(width 0.0889)
		(layer "In13.Cu")
		(net "M_B_CPU1_SB_DQ<16>")
	)
	(segment
		(start 68.797424 -290.985194)
		(end 68.592192 -290.985194)
		(width 0.14478)
		(layer "In13.Cu")
		(net "M_B_CPU1_SB_DQ<16>")
	)
	(segment
		(start 57.741566 -300.028864)
		(end 57.536842 -300.028864)
		(width 0.14478)
		(layer "In13.Cu")
		(net "M_B_CPU1_SB_DQ<16>")
	)
	(segment
		(start 61.574172 -298.003214)
		(end 61.286898 -298.290488)
		(width 0.14478)
		(layer "In13.Cu")
		(net "M_B_CPU1_SB_DQ<16>")
	)
	(segment
		(start 72.491092 -287.086294)
		(end 72.203818 -287.373568)
		(width 0.14478)
		(layer "In13.Cu")
		(net "M_B_CPU1_SB_DQ<16>")
	)
	(segment
		(start 63.913512 -295.663874)
		(end 63.626238 -295.951148)
		(width 0.14478)
		(layer "In13.Cu")
		(net "M_B_CPU1_SB_DQ<16>")
	)
	(segment
		(start 84.538058 -284.128972)
		(end 84.529676 -284.133798)
		(width 0.0889)
		(layer "In13.Cu")
		(net "M_B_CPU1_SB_DQ<16>")
	)
	(segment
		(start 62.066678 -297.510708)
		(end 62.066678 -297.71594)
		(width 0.14478)
		(layer "In13.Cu")
		(net "M_B_CPU1_SB_DQ<16>")
	)
	(segment
		(start 71.424038 -288.153348)
		(end 71.424038 -288.35858)
		(width 0.14478)
		(layer "In13.Cu")
		(net "M_B_CPU1_SB_DQ<16>")
	)
	(segment
		(start 63.133732 -296.443654)
		(end 62.846458 -296.730928)
		(width 0.14478)
		(layer "In13.Cu")
		(net "M_B_CPU1_SB_DQ<16>")
	)
	(segment
		(start 83.598004 -284.128972)
		(end 83.589622 -284.133798)
		(width 0.0889)
		(layer "In13.Cu")
		(net "M_B_CPU1_SB_DQ<16>")
	)
	(segment
		(start 63.338964 -296.443654)
		(end 63.133732 -296.443654)
		(width 0.14478)
		(layer "In13.Cu")
		(net "M_B_CPU1_SB_DQ<16>")
	)
	(segment
		(start 55.879492 -300.09973)
		(end 55.879492 -300.82236)
		(width 0.14478)
		(layer "In13.Cu")
		(net "M_B_CPU1_SB_DQ<16>")
	)
	(segment
		(start 52.895754 -299.495464)
		(end 52.634134 -299.495464)
		(width 0.14478)
		(layer "In13.Cu")
		(net "M_B_CPU1_SB_DQ<16>")
	)
	(segment
		(start 58.010044 -299.760386)
		(end 57.741566 -300.028864)
		(width 0.14478)
		(layer "In13.Cu")
		(net "M_B_CPU1_SB_DQ<16>")
	)
	(segment
		(start 74.830432 -284.746954)
		(end 74.543158 -285.034228)
		(width 0.14478)
		(layer "In13.Cu")
		(net "M_B_CPU1_SB_DQ<16>")
	)
	(segment
		(start 52.344574 -300.141386)
		(end 51.928014 -300.141386)
		(width 0.14478)
		(layer "In13.Cu")
		(net "M_B_CPU1_SB_DQ<16>")
	)
	(segment
		(start 59.000644 -300.143164)
		(end 58.770012 -300.143164)
		(width 0.14478)
		(layer "In13.Cu")
		(net "M_B_CPU1_SB_DQ<16>")
	)
	(segment
		(start 58.387234 -299.760386)
		(end 58.010044 -299.760386)
		(width 0.14478)
		(layer "In13.Cu")
		(net "M_B_CPU1_SB_DQ<16>")
	)
	(segment
		(start 78.903322 -284.125416)
		(end 78.897734 -284.128718)
		(width 0.0889)
		(layer "In13.Cu")
		(net "M_B_CPU1_SB_DQ<16>")
	)
	(segment
		(start 62.846458 -296.93616)
		(end 62.559184 -297.223434)
		(width 0.14478)
		(layer "In13.Cu")
		(net "M_B_CPU1_SB_DQ<16>")
	)
	(segment
		(start 73.763378 -286.01924)
		(end 73.476104 -286.306514)
		(width 0.14478)
		(layer "In13.Cu")
		(net "M_B_CPU1_SB_DQ<16>")
	)
	(segment
		(start 53.185314 -300.141386)
		(end 53.040534 -299.996606)
		(width 0.14478)
		(layer "In13.Cu")
		(net "M_B_CPU1_SB_DQ<16>")
	)
	(segment
		(start 57.146952 -300.623478)
		(end 56.786526 -300.983904)
		(width 0.14478)
		(layer "In13.Cu")
		(net "M_B_CPU1_SB_DQ<16>")
	)
	(segment
		(start 68.017644 -291.764974)
		(end 67.812412 -291.764974)
		(width 0.14478)
		(layer "In13.Cu")
		(net "M_B_CPU1_SB_DQ<16>")
	)
	(segment
		(start 65.965578 -293.611808)
		(end 65.965578 -293.81704)
		(width 0.14478)
		(layer "In13.Cu")
		(net "M_B_CPU1_SB_DQ<16>")
	)
	(segment
		(start 75.315064 -284.467554)
		(end 75.035664 -284.746954)
		(width 0.14478)
		(layer "In13.Cu")
		(net "M_B_CPU1_SB_DQ<16>")
	)
	(segment
		(start 68.592192 -290.985194)
		(end 68.304918 -291.272468)
		(width 0.14478)
		(layer "In13.Cu")
		(net "M_B_CPU1_SB_DQ<16>")
	)
	(segment
		(start 52.489354 -299.996606)
		(end 52.344574 -300.141386)
		(width 0.14478)
		(layer "In13.Cu")
		(net "M_B_CPU1_SB_DQ<16>")
	)
	(segment
		(start 62.846458 -296.730928)
		(end 62.846458 -296.93616)
		(width 0.14478)
		(layer "In13.Cu")
		(net "M_B_CPU1_SB_DQ<16>")
	)
	(arc
		(start 83.589622 -284.133798)
		(mid 83.406114 -284.179292)
		(end 83.223862 -284.128972)
		(width 0.0889)
		(layer "In13.Cu")
		(net "M_B_CPU1_SB_DQ<16>")
	)
	(arc
		(start 85.478112 -284.128972)
		(mid 85.295861 -284.179322)
		(end 85.112352 -284.133798)
		(width 0.0889)
		(layer "In13.Cu")
		(net "M_B_CPU1_SB_DQ<16>")
	)
	(arc
		(start 83.223862 -284.128972)
		(mid 82.940906 -284.052795)
		(end 82.65795 -284.128972)
		(width 0.0889)
		(layer "In13.Cu")
		(net "M_B_CPU1_SB_DQ<16>")
	)
	(arc
		(start 81.344008 -284.128972)
		(mid 81.061052 -284.052795)
		(end 80.778096 -284.128972)
		(width 0.0889)
		(layer "In13.Cu")
		(net "M_B_CPU1_SB_DQ<16>")
	)
	(arc
		(start 82.284062 -284.128972)
		(mid 82.001106 -284.052795)
		(end 81.71815 -284.128972)
		(width 0.0889)
		(layer "In13.Cu")
		(net "M_B_CPU1_SB_DQ<16>")
	)
	(arc
		(start 87.860632 -284.097222)
		(mid 87.605567 -284.053871)
		(end 87.357966 -284.128972)
		(width 0.0889)
		(layer "In13.Cu")
		(net "M_B_CPU1_SB_DQ<16>")
	)
	(arc
		(start 84.163916 -284.128972)
		(mid 83.88096 -284.052795)
		(end 83.598004 -284.128972)
		(width 0.0889)
		(layer "In13.Cu")
		(net "M_B_CPU1_SB_DQ<16>")
	)
	(arc
		(start 80.39354 -284.122876)
		(mid 80.114854 -284.052656)
		(end 79.837788 -284.128972)
		(width 0.0889)
		(layer "In13.Cu")
		(net "M_B_CPU1_SB_DQ<16>")
	)
	(arc
		(start 86.984078 -284.128972)
		(mid 86.701122 -284.052795)
		(end 86.418166 -284.128972)
		(width 0.0889)
		(layer "In13.Cu")
		(net "M_B_CPU1_SB_DQ<16>")
	)
	(arc
		(start 78.897734 -284.128718)
		(mid 78.807625 -284.166512)
		(end 78.71079 -284.179518)
		(width 0.0889)
		(layer "In13.Cu")
		(net "M_B_CPU1_SB_DQ<16>")
	)
	(arc
		(start 79.463138 -284.128972)
		(mid 79.18371 -284.052806)
		(end 78.903322 -284.125416)
		(width 0.0889)
		(layer "In13.Cu")
		(net "M_B_CPU1_SB_DQ<16>")
	)
	(arc
		(start 86.044024 -284.128972)
		(mid 85.761068 -284.052795)
		(end 85.478112 -284.128972)
		(width 0.0889)
		(layer "In13.Cu")
		(net "M_B_CPU1_SB_DQ<16>")
	)
	(arc
		(start 87.357966 -284.128972)
		(mid 87.171022 -284.179227)
		(end 86.984078 -284.128972)
		(width 0.0889)
		(layer "In13.Cu")
		(net "M_B_CPU1_SB_DQ<16>")
	)
	(arc
		(start 79.837788 -284.128972)
		(mid 79.655283 -284.179449)
		(end 79.47152 -284.133798)
		(width 0.0889)
		(layer "In13.Cu")
		(net "M_B_CPU1_SB_DQ<16>")
	)
	(arc
		(start 80.769714 -284.133798)
		(mid 80.586206 -284.179292)
		(end 80.403954 -284.128972)
		(width 0.0889)
		(layer "In13.Cu")
		(net "M_B_CPU1_SB_DQ<16>")
	)
	(arc
		(start 86.418166 -284.128972)
		(mid 86.235915 -284.179322)
		(end 86.052406 -284.133798)
		(width 0.0889)
		(layer "In13.Cu")
		(net "M_B_CPU1_SB_DQ<16>")
	)
	(arc
		(start 85.10397 -284.128972)
		(mid 84.821014 -284.052795)
		(end 84.538058 -284.128972)
		(width 0.0889)
		(layer "In13.Cu")
		(net "M_B_CPU1_SB_DQ<16>")
	)
	(arc
		(start 84.529676 -284.133798)
		(mid 84.346168 -284.179292)
		(end 84.163916 -284.128972)
		(width 0.0889)
		(layer "In13.Cu")
		(net "M_B_CPU1_SB_DQ<16>")
	)
	(arc
		(start 81.71815 -284.128972)
		(mid 81.535899 -284.179322)
		(end 81.35239 -284.133798)
		(width 0.0889)
		(layer "In13.Cu")
		(net "M_B_CPU1_SB_DQ<16>")
	)
	(arc
		(start 82.65795 -284.128972)
		(mid 82.471006 -284.179227)
		(end 82.284062 -284.128972)
		(width 0.0889)
		(layer "In13.Cu")
		(net "M_B_CPU1_SB_DQ<16>")
	)
	(segment
		(start 89.517982 -283.540454)
		(end 89.05113 -283.806392)
		(width 0.10668)
		(layer "F.Cu")
		(net "M_B_CPU1_SB_DQ<15>")
	)
	(segment
		(start 78.711044 -283.432504)
		(end 76.804012 -283.432504)
		(width 0.0889)
		(layer "In13.Cu")
		(net "M_B_CPU1_SB_DQ<15>")
	)
	(segment
		(start 76.325222 -283.911294)
		(end 75.962256 -283.911294)
		(width 0.0889)
		(layer "In13.Cu")
		(net "M_B_CPU1_SB_DQ<15>")
	)
	(segment
		(start 53.544978 -299.365162)
		(end 53.20792 -299.028104)
		(width 0.14478)
		(layer "In13.Cu")
		(net "M_B_CPU1_SB_DQ<15>")
	)
	(segment
		(start 74.877676 -283.911294)
		(end 60.347606 -298.441364)
		(width 0.14478)
		(layer "In13.Cu")
		(net "M_B_CPU1_SB_DQ<15>")
	)
	(segment
		(start 75.962256 -283.911294)
		(end 74.877676 -283.911294)
		(width 0.14478)
		(layer "In13.Cu")
		(net "M_B_CPU1_SB_DQ<15>")
	)
	(segment
		(start 89.205054 -283.540962)
		(end 89.182702 -283.45765)
		(width 0.0889)
		(layer "In13.Cu")
		(net "M_B_CPU1_SB_DQ<15>")
	)
	(segment
		(start 57.849008 -299.230288)
		(end 57.523634 -299.365162)
		(width 0.14478)
		(layer "In13.Cu")
		(net "M_B_CPU1_SB_DQ<15>")
	)
	(segment
		(start 53.20792 -299.028104)
		(end 52.92344 -298.910248)
		(width 0.14478)
		(layer "In13.Cu")
		(net "M_B_CPU1_SB_DQ<15>")
	)
	(segment
		(start 52.92344 -298.910248)
		(end 51.61915 -298.910248)
		(width 0.14478)
		(layer "In13.Cu")
		(net "M_B_CPU1_SB_DQ<15>")
	)
	(segment
		(start 76.804012 -283.432504)
		(end 76.325222 -283.911294)
		(width 0.0889)
		(layer "In13.Cu")
		(net "M_B_CPU1_SB_DQ<15>")
	)
	(segment
		(start 79.83982 -283.484066)
		(end 79.819754 -283.472636)
		(width 0.0889)
		(layer "In13.Cu")
		(net "M_B_CPU1_SB_DQ<15>")
	)
	(segment
		(start 88.29802 -283.483812)
		(end 88.289638 -283.478986)
		(width 0.0889)
		(layer "In13.Cu")
		(net "M_B_CPU1_SB_DQ<15>")
	)
	(segment
		(start 79.466948 -283.483812)
		(end 79.439262 -283.499814)
		(width 0.0889)
		(layer "In13.Cu")
		(net "M_B_CPU1_SB_DQ<15>")
	)
	(segment
		(start 58.9915 -299.002958)
		(end 57.849008 -299.230288)
		(width 0.14478)
		(layer "In13.Cu")
		(net "M_B_CPU1_SB_DQ<15>")
	)
	(segment
		(start 83.598004 -283.483812)
		(end 83.589622 -283.478986)
		(width 0.0889)
		(layer "In13.Cu")
		(net "M_B_CPU1_SB_DQ<15>")
	)
	(segment
		(start 86.052406 -283.478986)
		(end 86.044024 -283.483812)
		(width 0.0889)
		(layer "In13.Cu")
		(net "M_B_CPU1_SB_DQ<15>")
	)
	(segment
		(start 89.05113 -283.806392)
		(end 89.205054 -283.540962)
		(width 0.0889)
		(layer "In13.Cu")
		(net "M_B_CPU1_SB_DQ<15>")
	)
	(segment
		(start 80.778096 -283.483812)
		(end 80.769714 -283.478986)
		(width 0.0889)
		(layer "In13.Cu")
		(net "M_B_CPU1_SB_DQ<15>")
	)
	(segment
		(start 60.347606 -298.441364)
		(end 58.9915 -299.002958)
		(width 0.14478)
		(layer "In13.Cu")
		(net "M_B_CPU1_SB_DQ<15>")
	)
	(segment
		(start 57.523634 -299.365162)
		(end 53.544978 -299.365162)
		(width 0.14478)
		(layer "In13.Cu")
		(net "M_B_CPU1_SB_DQ<15>")
	)
	(segment
		(start 84.538058 -283.483812)
		(end 84.529676 -283.478986)
		(width 0.0889)
		(layer "In13.Cu")
		(net "M_B_CPU1_SB_DQ<15>")
	)
	(segment
		(start 79.863696 -283.498036)
		(end 79.83982 -283.484066)
		(width 0.0889)
		(layer "In13.Cu")
		(net "M_B_CPU1_SB_DQ<15>")
	)
	(segment
		(start 85.112352 -283.478986)
		(end 85.10397 -283.483812)
		(width 0.0889)
		(layer "In13.Cu")
		(net "M_B_CPU1_SB_DQ<15>")
	)
	(segment
		(start 81.35239 -283.478986)
		(end 81.344008 -283.483812)
		(width 0.0889)
		(layer "In13.Cu")
		(net "M_B_CPU1_SB_DQ<15>")
	)
	(segment
		(start 51.61915 -298.910248)
		(end 47.784004 -299.335444)
		(width 0.14478)
		(layer "In13.Cu")
		(net "M_B_CPU1_SB_DQ<15>")
	)
	(arc
		(start 81.71815 -283.483812)
		(mid 81.535899 -283.433462)
		(end 81.35239 -283.478986)
		(width 0.0889)
		(layer "In13.Cu")
		(net "M_B_CPU1_SB_DQ<15>")
	)
	(arc
		(start 83.589622 -283.478986)
		(mid 83.406114 -283.433492)
		(end 83.223862 -283.483812)
		(width 0.0889)
		(layer "In13.Cu")
		(net "M_B_CPU1_SB_DQ<15>")
	)
	(arc
		(start 80.769714 -283.478986)
		(mid 80.586206 -283.433492)
		(end 80.403954 -283.483812)
		(width 0.0889)
		(layer "In13.Cu")
		(net "M_B_CPU1_SB_DQ<15>")
	)
	(arc
		(start 79.819754 -283.472636)
		(mid 79.64193 -283.433765)
		(end 79.466948 -283.483812)
		(width 0.0889)
		(layer "In13.Cu")
		(net "M_B_CPU1_SB_DQ<15>")
	)
	(arc
		(start 85.10397 -283.483812)
		(mid 84.821014 -283.559989)
		(end 84.538058 -283.483812)
		(width 0.0889)
		(layer "In13.Cu")
		(net "M_B_CPU1_SB_DQ<15>")
	)
	(arc
		(start 88.289638 -283.478986)
		(mid 88.10613 -283.433492)
		(end 87.923878 -283.483812)
		(width 0.0889)
		(layer "In13.Cu")
		(net "M_B_CPU1_SB_DQ<15>")
	)
	(arc
		(start 87.357966 -283.483812)
		(mid 87.171022 -283.433557)
		(end 86.984078 -283.483812)
		(width 0.0889)
		(layer "In13.Cu")
		(net "M_B_CPU1_SB_DQ<15>")
	)
	(arc
		(start 86.044024 -283.483812)
		(mid 85.761068 -283.559989)
		(end 85.478112 -283.483812)
		(width 0.0889)
		(layer "In13.Cu")
		(net "M_B_CPU1_SB_DQ<15>")
	)
	(arc
		(start 82.65795 -283.483812)
		(mid 82.471006 -283.433557)
		(end 82.284062 -283.483812)
		(width 0.0889)
		(layer "In13.Cu")
		(net "M_B_CPU1_SB_DQ<15>")
	)
	(arc
		(start 88.863932 -283.483812)
		(mid 88.580976 -283.559989)
		(end 88.29802 -283.483812)
		(width 0.0889)
		(layer "In13.Cu")
		(net "M_B_CPU1_SB_DQ<15>")
	)
	(arc
		(start 81.344008 -283.483812)
		(mid 81.061052 -283.559989)
		(end 80.778096 -283.483812)
		(width 0.0889)
		(layer "In13.Cu")
		(net "M_B_CPU1_SB_DQ<15>")
	)
	(arc
		(start 86.984078 -283.483812)
		(mid 86.701122 -283.559989)
		(end 86.418166 -283.483812)
		(width 0.0889)
		(layer "In13.Cu")
		(net "M_B_CPU1_SB_DQ<15>")
	)
	(arc
		(start 80.403954 -283.483812)
		(mid 80.135634 -283.55992)
		(end 79.863696 -283.498036)
		(width 0.0889)
		(layer "In13.Cu")
		(net "M_B_CPU1_SB_DQ<15>")
	)
	(arc
		(start 86.418166 -283.483812)
		(mid 86.235915 -283.433462)
		(end 86.052406 -283.478986)
		(width 0.0889)
		(layer "In13.Cu")
		(net "M_B_CPU1_SB_DQ<15>")
	)
	(arc
		(start 84.529676 -283.478986)
		(mid 84.346168 -283.433492)
		(end 84.163916 -283.483812)
		(width 0.0889)
		(layer "In13.Cu")
		(net "M_B_CPU1_SB_DQ<15>")
	)
	(arc
		(start 78.899258 -283.483812)
		(mid 78.808559 -283.445656)
		(end 78.711044 -283.432504)
		(width 0.0889)
		(layer "In13.Cu")
		(net "M_B_CPU1_SB_DQ<15>")
	)
	(arc
		(start 83.223862 -283.483812)
		(mid 82.940906 -283.559989)
		(end 82.65795 -283.483812)
		(width 0.0889)
		(layer "In13.Cu")
		(net "M_B_CPU1_SB_DQ<15>")
	)
	(arc
		(start 87.923878 -283.483812)
		(mid 87.640922 -283.559989)
		(end 87.357966 -283.483812)
		(width 0.0889)
		(layer "In13.Cu")
		(net "M_B_CPU1_SB_DQ<15>")
	)
	(arc
		(start 82.284062 -283.483812)
		(mid 82.001106 -283.559989)
		(end 81.71815 -283.483812)
		(width 0.0889)
		(layer "In13.Cu")
		(net "M_B_CPU1_SB_DQ<15>")
	)
	(arc
		(start 89.182702 -283.45765)
		(mid 89.02037 -283.434832)
		(end 88.863932 -283.483812)
		(width 0.0889)
		(layer "In13.Cu")
		(net "M_B_CPU1_SB_DQ<15>")
	)
	(arc
		(start 79.439262 -283.499814)
		(mid 79.167228 -283.560586)
		(end 78.899258 -283.483812)
		(width 0.0889)
		(layer "In13.Cu")
		(net "M_B_CPU1_SB_DQ<15>")
	)
	(arc
		(start 84.163916 -283.483812)
		(mid 83.88096 -283.559989)
		(end 83.598004 -283.483812)
		(width 0.0889)
		(layer "In13.Cu")
		(net "M_B_CPU1_SB_DQ<15>")
	)
	(arc
		(start 85.478112 -283.483812)
		(mid 85.295861 -283.433462)
		(end 85.112352 -283.478986)
		(width 0.0889)
		(layer "In13.Cu")
		(net "M_B_CPU1_SB_DQ<15>")
	)
	(segment
		(start 88.107774 -282.730448)
		(end 87.640922 -282.996386)
		(width 0.10668)
		(layer "F.Cu")
		(net "M_B_CPU1_SB_DQ<14>")
	)
	(segment
		(start 87.640922 -282.996386)
		(end 87.7951 -282.730956)
		(width 0.0889)
		(layer "In13.Cu")
		(net "M_B_CPU1_SB_DQ<14>")
	)
	(segment
		(start 76.84643 -282.358846)
		(end 76.203302 -283.001974)
		(width 0.0889)
		(layer "In13.Cu")
		(net "M_B_CPU1_SB_DQ<14>")
	)
	(segment
		(start 77.52207 -282.358846)
		(end 76.84643 -282.358846)
		(width 0.0889)
		(layer "In13.Cu")
		(net "M_B_CPU1_SB_DQ<14>")
	)
	(segment
		(start 52.990496 -297.210226)
		(end 50.968148 -297.210226)
		(width 0.14478)
		(layer "In13.Cu")
		(net "M_B_CPU1_SB_DQ<14>")
	)
	(segment
		(start 85.948266 -282.673806)
		(end 85.948012 -282.673806)
		(width 0.0889)
		(layer "In13.Cu")
		(net "M_B_CPU1_SB_DQ<14>")
	)
	(segment
		(start 76.203302 -283.001974)
		(end 75.968606 -283.001974)
		(width 0.0889)
		(layer "In13.Cu")
		(net "M_B_CPU1_SB_DQ<14>")
	)
	(segment
		(start 74.514964 -283.001974)
		(end 60.299346 -297.217592)
		(width 0.14478)
		(layer "In13.Cu")
		(net "M_B_CPU1_SB_DQ<14>")
	)
	(segment
		(start 58.272426 -297.217592)
		(end 57.429654 -298.060364)
		(width 0.14478)
		(layer "In13.Cu")
		(net "M_B_CPU1_SB_DQ<14>")
	)
	(segment
		(start 75.968606 -283.001974)
		(end 74.514964 -283.001974)
		(width 0.14478)
		(layer "In13.Cu")
		(net "M_B_CPU1_SB_DQ<14>")
	)
	(segment
		(start 78.711044 -282.750006)
		(end 77.91323 -282.750006)
		(width 0.0889)
		(layer "In13.Cu")
		(net "M_B_CPU1_SB_DQ<14>")
	)
	(segment
		(start 82.18805 -282.673806)
		(end 82.179668 -282.66898)
		(width 0.0889)
		(layer "In13.Cu")
		(net "M_B_CPU1_SB_DQ<14>")
	)
	(segment
		(start 79.009748 -282.664662)
		(end 78.993492 -282.67406)
		(width 0.0889)
		(layer "In13.Cu")
		(net "M_B_CPU1_SB_DQ<14>")
	)
	(segment
		(start 53.840634 -298.060364)
		(end 52.990496 -297.210226)
		(width 0.14478)
		(layer "In13.Cu")
		(net "M_B_CPU1_SB_DQ<14>")
	)
	(segment
		(start 50.968148 -297.210226)
		(end 50.11801 -298.060364)
		(width 0.14478)
		(layer "In13.Cu")
		(net "M_B_CPU1_SB_DQ<14>")
	)
	(segment
		(start 50.11801 -298.060364)
		(end 48.1584 -298.060364)
		(width 0.14478)
		(layer "In13.Cu")
		(net "M_B_CPU1_SB_DQ<14>")
	)
	(segment
		(start 83.702398 -282.66898)
		(end 83.694016 -282.673806)
		(width 0.0889)
		(layer "In13.Cu")
		(net "M_B_CPU1_SB_DQ<14>")
	)
	(segment
		(start 87.46236 -282.66898)
		(end 87.453978 -282.673806)
		(width 0.0889)
		(layer "In13.Cu")
		(net "M_B_CPU1_SB_DQ<14>")
	)
	(segment
		(start 85.948012 -282.673806)
		(end 85.93963 -282.66898)
		(width 0.0889)
		(layer "In13.Cu")
		(net "M_B_CPU1_SB_DQ<14>")
	)
	(segment
		(start 60.299346 -297.217592)
		(end 58.272426 -297.217592)
		(width 0.14478)
		(layer "In13.Cu")
		(net "M_B_CPU1_SB_DQ<14>")
	)
	(segment
		(start 48.1584 -298.060364)
		(end 47.784004 -297.685968)
		(width 0.14478)
		(layer "In13.Cu")
		(net "M_B_CPU1_SB_DQ<14>")
	)
	(segment
		(start 80.308196 -282.673806)
		(end 80.299814 -282.66898)
		(width 0.0889)
		(layer "In13.Cu")
		(net "M_B_CPU1_SB_DQ<14>")
	)
	(segment
		(start 79.377794 -282.679902)
		(end 79.36738 -282.673806)
		(width 0.0889)
		(layer "In13.Cu")
		(net "M_B_CPU1_SB_DQ<14>")
	)
	(segment
		(start 86.888066 -282.673806)
		(end 86.879684 -282.66898)
		(width 0.0889)
		(layer "In13.Cu")
		(net "M_B_CPU1_SB_DQ<14>")
	)
	(segment
		(start 87.7951 -282.730956)
		(end 87.772748 -282.647644)
		(width 0.0889)
		(layer "In13.Cu")
		(net "M_B_CPU1_SB_DQ<14>")
	)
	(segment
		(start 57.429654 -298.060364)
		(end 53.840634 -298.060364)
		(width 0.14478)
		(layer "In13.Cu")
		(net "M_B_CPU1_SB_DQ<14>")
	)
	(segment
		(start 82.762344 -282.66898)
		(end 82.753962 -282.673806)
		(width 0.0889)
		(layer "In13.Cu")
		(net "M_B_CPU1_SB_DQ<14>")
	)
	(segment
		(start 47.784004 -297.685968)
		(end 47.784004 -297.635422)
		(width 0.14478)
		(layer "In13.Cu")
		(net "M_B_CPU1_SB_DQ<14>")
	)
	(segment
		(start 77.91323 -282.750006)
		(end 77.52207 -282.358846)
		(width 0.0889)
		(layer "In13.Cu")
		(net "M_B_CPU1_SB_DQ<14>")
	)
	(arc
		(start 86.879684 -282.66898)
		(mid 86.696176 -282.623486)
		(end 86.513924 -282.673806)
		(width 0.0889)
		(layer "In13.Cu")
		(net "M_B_CPU1_SB_DQ<14>")
	)
	(arc
		(start 80.299814 -282.66898)
		(mid 80.116052 -282.623364)
		(end 79.933546 -282.673806)
		(width 0.0889)
		(layer "In13.Cu")
		(net "M_B_CPU1_SB_DQ<14>")
	)
	(arc
		(start 82.753962 -282.673806)
		(mid 82.471006 -282.749983)
		(end 82.18805 -282.673806)
		(width 0.0889)
		(layer "In13.Cu")
		(net "M_B_CPU1_SB_DQ<14>")
	)
	(arc
		(start 86.513924 -282.673806)
		(mid 86.231112 -282.749855)
		(end 85.948266 -282.673806)
		(width 0.0889)
		(layer "In13.Cu")
		(net "M_B_CPU1_SB_DQ<14>")
	)
	(arc
		(start 87.453978 -282.673806)
		(mid 87.171022 -282.749983)
		(end 86.888066 -282.673806)
		(width 0.0889)
		(layer "In13.Cu")
		(net "M_B_CPU1_SB_DQ<14>")
	)
	(arc
		(start 87.772748 -282.647644)
		(mid 87.615238 -282.624446)
		(end 87.46236 -282.66898)
		(width 0.0889)
		(layer "In13.Cu")
		(net "M_B_CPU1_SB_DQ<14>")
	)
	(arc
		(start 85.007958 -282.673806)
		(mid 84.821014 -282.623551)
		(end 84.63407 -282.673806)
		(width 0.0889)
		(layer "In13.Cu")
		(net "M_B_CPU1_SB_DQ<14>")
	)
	(arc
		(start 80.874108 -282.673806)
		(mid 80.591152 -282.749983)
		(end 80.308196 -282.673806)
		(width 0.0889)
		(layer "In13.Cu")
		(net "M_B_CPU1_SB_DQ<14>")
	)
	(arc
		(start 84.63407 -282.673806)
		(mid 84.351114 -282.749983)
		(end 84.068158 -282.673806)
		(width 0.0889)
		(layer "In13.Cu")
		(net "M_B_CPU1_SB_DQ<14>")
	)
	(arc
		(start 79.36738 -282.673806)
		(mid 79.18973 -282.623546)
		(end 79.009748 -282.664662)
		(width 0.0889)
		(layer "In13.Cu")
		(net "M_B_CPU1_SB_DQ<14>")
	)
	(arc
		(start 84.068158 -282.673806)
		(mid 83.885907 -282.623456)
		(end 83.702398 -282.66898)
		(width 0.0889)
		(layer "In13.Cu")
		(net "M_B_CPU1_SB_DQ<14>")
	)
	(arc
		(start 81.247996 -282.673806)
		(mid 81.061052 -282.623551)
		(end 80.874108 -282.673806)
		(width 0.0889)
		(layer "In13.Cu")
		(net "M_B_CPU1_SB_DQ<14>")
	)
	(arc
		(start 85.57387 -282.673806)
		(mid 85.290914 -282.749983)
		(end 85.007958 -282.673806)
		(width 0.0889)
		(layer "In13.Cu")
		(net "M_B_CPU1_SB_DQ<14>")
	)
	(arc
		(start 79.933546 -282.673806)
		(mid 79.656479 -282.750077)
		(end 79.377794 -282.679902)
		(width 0.0889)
		(layer "In13.Cu")
		(net "M_B_CPU1_SB_DQ<14>")
	)
	(arc
		(start 81.813908 -282.673806)
		(mid 81.530952 -282.749983)
		(end 81.247996 -282.673806)
		(width 0.0889)
		(layer "In13.Cu")
		(net "M_B_CPU1_SB_DQ<14>")
	)
	(arc
		(start 82.179668 -282.66898)
		(mid 81.99616 -282.623486)
		(end 81.813908 -282.673806)
		(width 0.0889)
		(layer "In13.Cu")
		(net "M_B_CPU1_SB_DQ<14>")
	)
	(arc
		(start 83.694016 -282.673806)
		(mid 83.41106 -282.749983)
		(end 83.128104 -282.673806)
		(width 0.0889)
		(layer "In13.Cu")
		(net "M_B_CPU1_SB_DQ<14>")
	)
	(arc
		(start 78.993492 -282.67406)
		(mid 78.857277 -282.730645)
		(end 78.711044 -282.750006)
		(width 0.0889)
		(layer "In13.Cu")
		(net "M_B_CPU1_SB_DQ<14>")
	)
	(arc
		(start 85.93963 -282.66898)
		(mid 85.756122 -282.623486)
		(end 85.57387 -282.673806)
		(width 0.0889)
		(layer "In13.Cu")
		(net "M_B_CPU1_SB_DQ<14>")
	)
	(arc
		(start 83.128104 -282.673806)
		(mid 82.945853 -282.623456)
		(end 82.762344 -282.66898)
		(width 0.0889)
		(layer "In13.Cu")
		(net "M_B_CPU1_SB_DQ<14>")
	)
	(segment
		(start 89.987882 -282.730448)
		(end 89.52103 -282.996386)
		(width 0.10668)
		(layer "F.Cu")
		(net "M_B_CPU1_SB_DQ<13>")
	)
	(segment
		(start 76.509372 -283.242004)
		(end 78.711044 -283.242004)
		(width 0.0889)
		(layer "In13.Cu")
		(net "M_B_CPU1_SB_DQ<13>")
	)
	(segment
		(start 56.813196 -298.910502)
		(end 57.429654 -298.910502)
		(width 0.14478)
		(layer "In13.Cu")
		(net "M_B_CPU1_SB_DQ<13>")
	)
	(segment
		(start 87.453978 -283.318966)
		(end 87.46236 -283.323792)
		(width 0.0889)
		(layer "In13.Cu")
		(net "M_B_CPU1_SB_DQ<13>")
	)
	(segment
		(start 86.879684 -283.323792)
		(end 86.888066 -283.318966)
		(width 0.0889)
		(layer "In13.Cu")
		(net "M_B_CPU1_SB_DQ<13>")
	)
	(segment
		(start 85.948012 -283.318966)
		(end 85.948266 -283.318966)
		(width 0.0889)
		(layer "In13.Cu")
		(net "M_B_CPU1_SB_DQ<13>")
	)
	(segment
		(start 54.71668 -298.550076)
		(end 54.86146 -298.694856)
		(width 0.14478)
		(layer "In13.Cu")
		(net "M_B_CPU1_SB_DQ<13>")
	)
	(segment
		(start 53.052726 -298.340526)
		(end 53.197506 -298.485306)
		(width 0.14478)
		(layer "In13.Cu")
		(net "M_B_CPU1_SB_DQ<13>")
	)
	(segment
		(start 54.1655 -298.910502)
		(end 54.31028 -298.765722)
		(width 0.14478)
		(layer "In13.Cu")
		(net "M_B_CPU1_SB_DQ<13>")
	)
	(segment
		(start 51.884072 -298.485306)
		(end 52.031138 -298.33824)
		(width 0.14478)
		(layer "In13.Cu")
		(net "M_B_CPU1_SB_DQ<13>")
	)
	(segment
		(start 76.294742 -283.456634)
		(end 76.509372 -283.242004)
		(width 0.0889)
		(layer "In13.Cu")
		(net "M_B_CPU1_SB_DQ<13>")
	)
	(segment
		(start 56.490108 -298.520866)
		(end 56.651652 -298.68241)
		(width 0.14478)
		(layer "In13.Cu")
		(net "M_B_CPU1_SB_DQ<13>")
	)
	(segment
		(start 57.429654 -298.910502)
		(end 57.74817 -298.591986)
		(width 0.14478)
		(layer "In13.Cu")
		(net "M_B_CPU1_SB_DQ<13>")
	)
	(segment
		(start 75.963526 -283.456634)
		(end 76.294742 -283.456634)
		(width 0.0889)
		(layer "In13.Cu")
		(net "M_B_CPU1_SB_DQ<13>")
	)
	(segment
		(start 82.753962 -283.318966)
		(end 82.762344 -283.323792)
		(width 0.0889)
		(layer "In13.Cu")
		(net "M_B_CPU1_SB_DQ<13>")
	)
	(segment
		(start 74.69632 -283.456634)
		(end 75.963526 -283.456634)
		(width 0.14478)
		(layer "In13.Cu")
		(net "M_B_CPU1_SB_DQ<13>")
	)
	(segment
		(start 55.938674 -298.910502)
		(end 56.100218 -298.748958)
		(width 0.14478)
		(layer "In13.Cu")
		(net "M_B_CPU1_SB_DQ<13>")
	)
	(segment
		(start 79.35214 -283.329888)
		(end 79.370936 -283.318966)
		(width 0.0889)
		(layer "In13.Cu")
		(net "M_B_CPU1_SB_DQ<13>")
	)
	(segment
		(start 79.93507 -283.318712)
		(end 79.956914 -283.331158)
		(width 0.0889)
		(layer "In13.Cu")
		(net "M_B_CPU1_SB_DQ<13>")
	)
	(segment
		(start 82.179668 -283.323792)
		(end 82.18805 -283.318966)
		(width 0.0889)
		(layer "In13.Cu")
		(net "M_B_CPU1_SB_DQ<13>")
	)
	(segment
		(start 58.396632 -297.85183)
		(end 58.541412 -297.70705)
		(width 0.14478)
		(layer "In13.Cu")
		(net "M_B_CPU1_SB_DQ<13>")
	)
	(segment
		(start 53.052726 -297.908726)
		(end 53.052726 -298.340526)
		(width 0.14478)
		(layer "In13.Cu")
		(net "M_B_CPU1_SB_DQ<13>")
	)
	(segment
		(start 89.367106 -283.261816)
		(end 89.52103 -282.996386)
		(width 0.0889)
		(layer "In13.Cu")
		(net "M_B_CPU1_SB_DQ<13>")
	)
	(segment
		(start 60.142374 -298.01058)
		(end 74.69632 -283.456634)
		(width 0.14478)
		(layer "In13.Cu")
		(net "M_B_CPU1_SB_DQ<13>")
	)
	(segment
		(start 52.501546 -297.908726)
		(end 52.646326 -297.763946)
		(width 0.14478)
		(layer "In13.Cu")
		(net "M_B_CPU1_SB_DQ<13>")
	)
	(segment
		(start 58.251852 -298.591986)
		(end 58.396632 -298.447206)
		(width 0.14478)
		(layer "In13.Cu")
		(net "M_B_CPU1_SB_DQ<13>")
	)
	(segment
		(start 52.031138 -298.33824)
		(end 52.356766 -298.33824)
		(width 0.14478)
		(layer "In13.Cu")
		(net "M_B_CPU1_SB_DQ<13>")
	)
	(segment
		(start 56.651652 -298.748958)
		(end 56.813196 -298.910502)
		(width 0.14478)
		(layer "In13.Cu")
		(net "M_B_CPU1_SB_DQ<13>")
	)
	(segment
		(start 58.803032 -297.70705)
		(end 58.947812 -297.85183)
		(width 0.14478)
		(layer "In13.Cu")
		(net "M_B_CPU1_SB_DQ<13>")
	)
	(segment
		(start 83.694016 -283.318966)
		(end 83.702398 -283.323792)
		(width 0.0889)
		(layer "In13.Cu")
		(net "M_B_CPU1_SB_DQ<13>")
	)
	(segment
		(start 52.907946 -297.763946)
		(end 53.052726 -297.908726)
		(width 0.14478)
		(layer "In13.Cu")
		(net "M_B_CPU1_SB_DQ<13>")
	)
	(segment
		(start 56.651652 -298.68241)
		(end 56.651652 -298.748958)
		(width 0.14478)
		(layer "In13.Cu")
		(net "M_B_CPU1_SB_DQ<13>")
	)
	(segment
		(start 85.93963 -283.323792)
		(end 85.948012 -283.318966)
		(width 0.0889)
		(layer "In13.Cu")
		(net "M_B_CPU1_SB_DQ<13>")
	)
	(segment
		(start 58.947812 -298.197778)
		(end 59.092592 -298.342558)
		(width 0.14478)
		(layer "In13.Cu")
		(net "M_B_CPU1_SB_DQ<13>")
	)
	(segment
		(start 88.394032 -283.318966)
		(end 88.402414 -283.323792)
		(width 0.0889)
		(layer "In13.Cu")
		(net "M_B_CPU1_SB_DQ<13>")
	)
	(segment
		(start 58.541412 -297.70705)
		(end 58.803032 -297.70705)
		(width 0.14478)
		(layer "In13.Cu")
		(net "M_B_CPU1_SB_DQ<13>")
	)
	(segment
		(start 56.261762 -298.520866)
		(end 56.490108 -298.520866)
		(width 0.14478)
		(layer "In13.Cu")
		(net "M_B_CPU1_SB_DQ<13>")
	)
	(segment
		(start 59.092592 -298.342558)
		(end 59.34075 -298.342558)
		(width 0.14478)
		(layer "In13.Cu")
		(net "M_B_CPU1_SB_DQ<13>")
	)
	(segment
		(start 54.45506 -298.550076)
		(end 54.71668 -298.550076)
		(width 0.14478)
		(layer "In13.Cu")
		(net "M_B_CPU1_SB_DQ<13>")
	)
	(segment
		(start 52.646326 -297.763946)
		(end 52.907946 -297.763946)
		(width 0.14478)
		(layer "In13.Cu")
		(net "M_B_CPU1_SB_DQ<13>")
	)
	(segment
		(start 53.907182 -298.910502)
		(end 54.1655 -298.910502)
		(width 0.14478)
		(layer "In13.Cu")
		(net "M_B_CPU1_SB_DQ<13>")
	)
	(segment
		(start 52.501546 -298.19346)
		(end 52.501546 -297.908726)
		(width 0.14478)
		(layer "In13.Cu")
		(net "M_B_CPU1_SB_DQ<13>")
	)
	(segment
		(start 54.86146 -298.765722)
		(end 55.00624 -298.910502)
		(width 0.14478)
		(layer "In13.Cu")
		(net "M_B_CPU1_SB_DQ<13>")
	)
	(segment
		(start 56.100218 -298.748958)
		(end 56.100218 -298.68241)
		(width 0.14478)
		(layer "In13.Cu")
		(net "M_B_CPU1_SB_DQ<13>")
	)
	(segment
		(start 53.197506 -298.485306)
		(end 53.481986 -298.485306)
		(width 0.14478)
		(layer "In13.Cu")
		(net "M_B_CPU1_SB_DQ<13>")
	)
	(segment
		(start 52.356766 -298.33824)
		(end 52.501546 -298.19346)
		(width 0.14478)
		(layer "In13.Cu")
		(net "M_B_CPU1_SB_DQ<13>")
	)
	(segment
		(start 58.947812 -297.85183)
		(end 58.947812 -298.197778)
		(width 0.14478)
		(layer "In13.Cu")
		(net "M_B_CPU1_SB_DQ<13>")
	)
	(segment
		(start 54.31028 -298.694856)
		(end 54.45506 -298.550076)
		(width 0.14478)
		(layer "In13.Cu")
		(net "M_B_CPU1_SB_DQ<13>")
	)
	(segment
		(start 55.00624 -298.910502)
		(end 55.938674 -298.910502)
		(width 0.14478)
		(layer "In13.Cu")
		(net "M_B_CPU1_SB_DQ<13>")
	)
	(segment
		(start 54.86146 -298.694856)
		(end 54.86146 -298.765722)
		(width 0.14478)
		(layer "In13.Cu")
		(net "M_B_CPU1_SB_DQ<13>")
	)
	(segment
		(start 89.271094 -283.287216)
		(end 89.367106 -283.261816)
		(width 0.0889)
		(layer "In13.Cu")
		(net "M_B_CPU1_SB_DQ<13>")
	)
	(segment
		(start 53.481986 -298.485306)
		(end 53.907182 -298.910502)
		(width 0.14478)
		(layer "In13.Cu")
		(net "M_B_CPU1_SB_DQ<13>")
	)
	(segment
		(start 56.100218 -298.68241)
		(end 56.261762 -298.520866)
		(width 0.14478)
		(layer "In13.Cu")
		(net "M_B_CPU1_SB_DQ<13>")
	)
	(segment
		(start 59.34075 -298.342558)
		(end 60.142374 -298.01058)
		(width 0.14478)
		(layer "In13.Cu")
		(net "M_B_CPU1_SB_DQ<13>")
	)
	(segment
		(start 54.31028 -298.765722)
		(end 54.31028 -298.694856)
		(width 0.14478)
		(layer "In13.Cu")
		(net "M_B_CPU1_SB_DQ<13>")
	)
	(segment
		(start 58.396632 -298.447206)
		(end 58.396632 -297.85183)
		(width 0.14478)
		(layer "In13.Cu")
		(net "M_B_CPU1_SB_DQ<13>")
	)
	(segment
		(start 79.911194 -283.304742)
		(end 79.93507 -283.318712)
		(width 0.0889)
		(layer "In13.Cu")
		(net "M_B_CPU1_SB_DQ<13>")
	)
	(segment
		(start 57.74817 -298.591986)
		(end 58.251852 -298.591986)
		(width 0.14478)
		(layer "In13.Cu")
		(net "M_B_CPU1_SB_DQ<13>")
	)
	(arc
		(start 88.768174 -283.318966)
		(mid 89.015887 -283.243746)
		(end 89.271094 -283.287216)
		(width 0.0889)
		(layer "In13.Cu")
		(net "M_B_CPU1_SB_DQ<13>")
	)
	(arc
		(start 84.068158 -283.318966)
		(mid 84.351114 -283.242789)
		(end 84.63407 -283.318966)
		(width 0.0889)
		(layer "In13.Cu")
		(net "M_B_CPU1_SB_DQ<13>")
	)
	(arc
		(start 86.888066 -283.318966)
		(mid 87.171022 -283.242789)
		(end 87.453978 -283.318966)
		(width 0.0889)
		(layer "In13.Cu")
		(net "M_B_CPU1_SB_DQ<13>")
	)
	(arc
		(start 81.247996 -283.318966)
		(mid 81.530952 -283.242789)
		(end 81.813908 -283.318966)
		(width 0.0889)
		(layer "In13.Cu")
		(net "M_B_CPU1_SB_DQ<13>")
	)
	(arc
		(start 83.702398 -283.323792)
		(mid 83.885906 -283.369286)
		(end 84.068158 -283.318966)
		(width 0.0889)
		(layer "In13.Cu")
		(net "M_B_CPU1_SB_DQ<13>")
	)
	(arc
		(start 79.956914 -283.331158)
		(mid 80.134096 -283.369098)
		(end 80.308196 -283.318966)
		(width 0.0889)
		(layer "In13.Cu")
		(net "M_B_CPU1_SB_DQ<13>")
	)
	(arc
		(start 87.46236 -283.323792)
		(mid 87.645868 -283.369286)
		(end 87.82812 -283.318966)
		(width 0.0889)
		(layer "In13.Cu")
		(net "M_B_CPU1_SB_DQ<13>")
	)
	(arc
		(start 80.308196 -283.318966)
		(mid 80.591152 -283.242789)
		(end 80.874108 -283.318966)
		(width 0.0889)
		(layer "In13.Cu")
		(net "M_B_CPU1_SB_DQ<13>")
	)
	(arc
		(start 88.402414 -283.323792)
		(mid 88.585922 -283.369286)
		(end 88.768174 -283.318966)
		(width 0.0889)
		(layer "In13.Cu")
		(net "M_B_CPU1_SB_DQ<13>")
	)
	(arc
		(start 78.711044 -283.242004)
		(mid 78.858531 -283.261547)
		(end 78.995778 -283.318966)
		(width 0.0889)
		(layer "In13.Cu")
		(net "M_B_CPU1_SB_DQ<13>")
	)
	(arc
		(start 79.370936 -283.318966)
		(mid 79.639256 -283.242858)
		(end 79.911194 -283.304742)
		(width 0.0889)
		(layer "In13.Cu")
		(net "M_B_CPU1_SB_DQ<13>")
	)
	(arc
		(start 81.813908 -283.318966)
		(mid 81.996159 -283.369316)
		(end 82.179668 -283.323792)
		(width 0.0889)
		(layer "In13.Cu")
		(net "M_B_CPU1_SB_DQ<13>")
	)
	(arc
		(start 78.995778 -283.318966)
		(mid 79.172569 -283.369685)
		(end 79.35214 -283.329888)
		(width 0.0889)
		(layer "In13.Cu")
		(net "M_B_CPU1_SB_DQ<13>")
	)
	(arc
		(start 83.128104 -283.318966)
		(mid 83.41106 -283.242789)
		(end 83.694016 -283.318966)
		(width 0.0889)
		(layer "In13.Cu")
		(net "M_B_CPU1_SB_DQ<13>")
	)
	(arc
		(start 80.874108 -283.318966)
		(mid 81.061052 -283.369221)
		(end 81.247996 -283.318966)
		(width 0.0889)
		(layer "In13.Cu")
		(net "M_B_CPU1_SB_DQ<13>")
	)
	(arc
		(start 85.948266 -283.318966)
		(mid 86.231112 -283.242789)
		(end 86.513924 -283.318966)
		(width 0.0889)
		(layer "In13.Cu")
		(net "M_B_CPU1_SB_DQ<13>")
	)
	(arc
		(start 85.007958 -283.318966)
		(mid 85.290914 -283.242789)
		(end 85.57387 -283.318966)
		(width 0.0889)
		(layer "In13.Cu")
		(net "M_B_CPU1_SB_DQ<13>")
	)
	(arc
		(start 84.63407 -283.318966)
		(mid 84.821014 -283.369221)
		(end 85.007958 -283.318966)
		(width 0.0889)
		(layer "In13.Cu")
		(net "M_B_CPU1_SB_DQ<13>")
	)
	(arc
		(start 82.18805 -283.318966)
		(mid 82.471006 -283.242789)
		(end 82.753962 -283.318966)
		(width 0.0889)
		(layer "In13.Cu")
		(net "M_B_CPU1_SB_DQ<13>")
	)
	(arc
		(start 86.513924 -283.318966)
		(mid 86.696175 -283.369316)
		(end 86.879684 -283.323792)
		(width 0.0889)
		(layer "In13.Cu")
		(net "M_B_CPU1_SB_DQ<13>")
	)
	(arc
		(start 82.762344 -283.323792)
		(mid 82.945852 -283.369286)
		(end 83.128104 -283.318966)
		(width 0.0889)
		(layer "In13.Cu")
		(net "M_B_CPU1_SB_DQ<13>")
	)
	(arc
		(start 85.57387 -283.318966)
		(mid 85.756121 -283.369316)
		(end 85.93963 -283.323792)
		(width 0.0889)
		(layer "In13.Cu")
		(net "M_B_CPU1_SB_DQ<13>")
	)
	(arc
		(start 87.82812 -283.318966)
		(mid 88.111076 -283.242789)
		(end 88.394032 -283.318966)
		(width 0.0889)
		(layer "In13.Cu")
		(net "M_B_CPU1_SB_DQ<13>")
	)
	(segment
		(start 88.577928 -281.920442)
		(end 88.111076 -282.18638)
		(width 0.10668)
		(layer "F.Cu")
		(net "M_B_CPU1_SB_DQ<12>")
	)
	(segment
		(start 54.700932 -296.860214)
		(end 54.54269 -297.018456)
		(width 0.14478)
		(layer "In13.Cu")
		(net "M_B_CPU1_SB_DQ<12>")
	)
	(segment
		(start 57.951624 -296.690542)
		(end 57.813956 -296.552874)
		(width 0.14478)
		(layer "In13.Cu")
		(net "M_B_CPU1_SB_DQ<12>")
	)
	(segment
		(start 88.111076 -282.18638)
		(end 87.956898 -282.45181)
		(width 0.0889)
		(layer "In13.Cu")
		(net "M_B_CPU1_SB_DQ<12>")
	)
	(segment
		(start 57.243726 -297.603164)
		(end 56.844184 -297.603164)
		(width 0.14478)
		(layer "In13.Cu")
		(net "M_B_CPU1_SB_DQ<12>")
	)
	(segment
		(start 57.561734 -297.080432)
		(end 57.561734 -297.285156)
		(width 0.14478)
		(layer "In13.Cu")
		(net "M_B_CPU1_SB_DQ<12>")
	)
	(segment
		(start 78.71079 -282.559506)
		(end 77.992224 -282.559506)
		(width 0.0889)
		(layer "In13.Cu")
		(net "M_B_CPU1_SB_DQ<12>")
	)
	(segment
		(start 57.424066 -296.942764)
		(end 57.561734 -297.080432)
		(width 0.14478)
		(layer "In13.Cu")
		(net "M_B_CPU1_SB_DQ<12>")
	)
	(segment
		(start 75.958446 -282.547314)
		(end 74.333608 -282.547314)
		(width 0.14478)
		(layer "In13.Cu")
		(net "M_B_CPU1_SB_DQ<12>")
	)
	(segment
		(start 55.812436 -296.860214)
		(end 55.65521 -297.01744)
		(width 0.14478)
		(layer "In13.Cu")
		(net "M_B_CPU1_SB_DQ<12>")
	)
	(segment
		(start 54.54269 -297.36923)
		(end 54.39791 -297.51401)
		(width 0.14478)
		(layer "In13.Cu")
		(net "M_B_CPU1_SB_DQ<12>")
	)
	(segment
		(start 56.101234 -296.860214)
		(end 55.812436 -296.860214)
		(width 0.14478)
		(layer "In13.Cu")
		(net "M_B_CPU1_SB_DQ<12>")
	)
	(segment
		(start 80.403954 -282.50896)
		(end 80.39354 -282.502864)
		(width 0.0889)
		(layer "In13.Cu")
		(net "M_B_CPU1_SB_DQ<12>")
	)
	(segment
		(start 59.368436 -296.602404)
		(end 59.368436 -296.186098)
		(width 0.14478)
		(layer "In13.Cu")
		(net "M_B_CPU1_SB_DQ<12>")
	)
	(segment
		(start 80.778096 -282.50896)
		(end 80.769714 -282.513786)
		(width 0.0889)
		(layer "In13.Cu")
		(net "M_B_CPU1_SB_DQ<12>")
	)
	(segment
		(start 54.940708 -296.860214)
		(end 54.700932 -296.860214)
		(width 0.14478)
		(layer "In13.Cu")
		(net "M_B_CPU1_SB_DQ<12>")
	)
	(segment
		(start 77.601064 -282.168346)
		(end 76.63561 -282.168346)
		(width 0.0889)
		(layer "In13.Cu")
		(net "M_B_CPU1_SB_DQ<12>")
	)
	(segment
		(start 53.930296 -297.51401)
		(end 52.785518 -296.369232)
		(width 0.14478)
		(layer "In13.Cu")
		(net "M_B_CPU1_SB_DQ<12>")
	)
	(segment
		(start 84.538058 -282.50896)
		(end 84.529676 -282.513786)
		(width 0.0889)
		(layer "In13.Cu")
		(net "M_B_CPU1_SB_DQ<12>")
	)
	(segment
		(start 55.09895 -297.018456)
		(end 54.940708 -296.860214)
		(width 0.14478)
		(layer "In13.Cu")
		(net "M_B_CPU1_SB_DQ<12>")
	)
	(segment
		(start 76.256642 -282.547314)
		(end 75.958446 -282.547314)
		(width 0.0889)
		(layer "In13.Cu")
		(net "M_B_CPU1_SB_DQ<12>")
	)
	(segment
		(start 55.65521 -297.452542)
		(end 55.496968 -297.610784)
		(width 0.14478)
		(layer "In13.Cu")
		(net "M_B_CPU1_SB_DQ<12>")
	)
	(segment
		(start 78.903322 -282.505404)
		(end 78.897734 -282.508706)
		(width 0.0889)
		(layer "In13.Cu")
		(net "M_B_CPU1_SB_DQ<12>")
	)
	(segment
		(start 55.496968 -297.610784)
		(end 55.257192 -297.610784)
		(width 0.14478)
		(layer "In13.Cu")
		(net "M_B_CPU1_SB_DQ<12>")
	)
	(segment
		(start 54.54269 -297.018456)
		(end 54.54269 -297.36923)
		(width 0.14478)
		(layer "In13.Cu")
		(net "M_B_CPU1_SB_DQ<12>")
	)
	(segment
		(start 77.992224 -282.559506)
		(end 77.601064 -282.168346)
		(width 0.0889)
		(layer "In13.Cu")
		(net "M_B_CPU1_SB_DQ<12>")
	)
	(segment
		(start 59.919616 -296.186098)
		(end 59.919616 -296.602404)
		(width 0.14478)
		(layer "In13.Cu")
		(net "M_B_CPU1_SB_DQ<12>")
	)
	(segment
		(start 79.47152 -282.513786)
		(end 79.463138 -282.50896)
		(width 0.0889)
		(layer "In13.Cu")
		(net "M_B_CPU1_SB_DQ<12>")
	)
	(segment
		(start 55.65521 -297.01744)
		(end 55.65521 -297.452542)
		(width 0.14478)
		(layer "In13.Cu")
		(net "M_B_CPU1_SB_DQ<12>")
	)
	(segment
		(start 58.805572 -296.041318)
		(end 58.156348 -296.690542)
		(width 0.14478)
		(layer "In13.Cu")
		(net "M_B_CPU1_SB_DQ<12>")
	)
	(segment
		(start 76.63561 -282.168346)
		(end 76.256642 -282.547314)
		(width 0.0889)
		(layer "In13.Cu")
		(net "M_B_CPU1_SB_DQ<12>")
	)
	(segment
		(start 52.09794 -296.369232)
		(end 51.884072 -296.5831)
		(width 0.14478)
		(layer "In13.Cu")
		(net "M_B_CPU1_SB_DQ<12>")
	)
	(segment
		(start 52.785518 -296.369232)
		(end 52.09794 -296.369232)
		(width 0.14478)
		(layer "In13.Cu")
		(net "M_B_CPU1_SB_DQ<12>")
	)
	(segment
		(start 83.598004 -282.50896)
		(end 83.589622 -282.513786)
		(width 0.0889)
		(layer "In13.Cu")
		(net "M_B_CPU1_SB_DQ<12>")
	)
	(segment
		(start 59.919616 -296.602404)
		(end 59.774836 -296.747184)
		(width 0.14478)
		(layer "In13.Cu")
		(net "M_B_CPU1_SB_DQ<12>")
	)
	(segment
		(start 57.609232 -296.552874)
		(end 57.424066 -296.73804)
		(width 0.14478)
		(layer "In13.Cu")
		(net "M_B_CPU1_SB_DQ<12>")
	)
	(segment
		(start 59.513216 -296.747184)
		(end 59.368436 -296.602404)
		(width 0.14478)
		(layer "In13.Cu")
		(net "M_B_CPU1_SB_DQ<12>")
	)
	(segment
		(start 55.09895 -297.452542)
		(end 55.09895 -297.018456)
		(width 0.14478)
		(layer "In13.Cu")
		(net "M_B_CPU1_SB_DQ<12>")
	)
	(segment
		(start 74.333608 -282.547314)
		(end 60.839604 -296.041318)
		(width 0.14478)
		(layer "In13.Cu")
		(net "M_B_CPU1_SB_DQ<12>")
	)
	(segment
		(start 86.052406 -282.513786)
		(end 86.044024 -282.50896)
		(width 0.0889)
		(layer "In13.Cu")
		(net "M_B_CPU1_SB_DQ<12>")
	)
	(segment
		(start 59.368436 -296.186098)
		(end 59.223656 -296.041318)
		(width 0.14478)
		(layer "In13.Cu")
		(net "M_B_CPU1_SB_DQ<12>")
	)
	(segment
		(start 57.813956 -296.552874)
		(end 57.609232 -296.552874)
		(width 0.14478)
		(layer "In13.Cu")
		(net "M_B_CPU1_SB_DQ<12>")
	)
	(segment
		(start 58.156348 -296.690542)
		(end 57.951624 -296.690542)
		(width 0.14478)
		(layer "In13.Cu")
		(net "M_B_CPU1_SB_DQ<12>")
	)
	(segment
		(start 51.884072 -296.5831)
		(end 51.884072 -296.785284)
		(width 0.14478)
		(layer "In13.Cu")
		(net "M_B_CPU1_SB_DQ<12>")
	)
	(segment
		(start 55.257192 -297.610784)
		(end 55.09895 -297.452542)
		(width 0.14478)
		(layer "In13.Cu")
		(net "M_B_CPU1_SB_DQ<12>")
	)
	(segment
		(start 56.844184 -297.603164)
		(end 56.101234 -296.860214)
		(width 0.14478)
		(layer "In13.Cu")
		(net "M_B_CPU1_SB_DQ<12>")
	)
	(segment
		(start 60.064396 -296.041318)
		(end 59.919616 -296.186098)
		(width 0.14478)
		(layer "In13.Cu")
		(net "M_B_CPU1_SB_DQ<12>")
	)
	(segment
		(start 54.39791 -297.51401)
		(end 53.930296 -297.51401)
		(width 0.14478)
		(layer "In13.Cu")
		(net "M_B_CPU1_SB_DQ<12>")
	)
	(segment
		(start 60.839604 -296.041318)
		(end 60.064396 -296.041318)
		(width 0.14478)
		(layer "In13.Cu")
		(net "M_B_CPU1_SB_DQ<12>")
	)
	(segment
		(start 57.561734 -297.285156)
		(end 57.243726 -297.603164)
		(width 0.14478)
		(layer "In13.Cu")
		(net "M_B_CPU1_SB_DQ<12>")
	)
	(segment
		(start 85.112352 -282.513786)
		(end 85.10397 -282.50896)
		(width 0.0889)
		(layer "In13.Cu")
		(net "M_B_CPU1_SB_DQ<12>")
	)
	(segment
		(start 59.223656 -296.041318)
		(end 58.805572 -296.041318)
		(width 0.14478)
		(layer "In13.Cu")
		(net "M_B_CPU1_SB_DQ<12>")
	)
	(segment
		(start 87.956898 -282.45181)
		(end 87.860632 -282.47721)
		(width 0.0889)
		(layer "In13.Cu")
		(net "M_B_CPU1_SB_DQ<12>")
	)
	(segment
		(start 81.35239 -282.513786)
		(end 81.344008 -282.50896)
		(width 0.0889)
		(layer "In13.Cu")
		(net "M_B_CPU1_SB_DQ<12>")
	)
	(segment
		(start 59.774836 -296.747184)
		(end 59.513216 -296.747184)
		(width 0.14478)
		(layer "In13.Cu")
		(net "M_B_CPU1_SB_DQ<12>")
	)
	(segment
		(start 57.424066 -296.73804)
		(end 57.424066 -296.942764)
		(width 0.14478)
		(layer "In13.Cu")
		(net "M_B_CPU1_SB_DQ<12>")
	)
	(arc
		(start 86.418166 -282.50896)
		(mid 86.235915 -282.55931)
		(end 86.052406 -282.513786)
		(width 0.0889)
		(layer "In13.Cu")
		(net "M_B_CPU1_SB_DQ<12>")
	)
	(arc
		(start 83.589622 -282.513786)
		(mid 83.406114 -282.55928)
		(end 83.223862 -282.50896)
		(width 0.0889)
		(layer "In13.Cu")
		(net "M_B_CPU1_SB_DQ<12>")
	)
	(arc
		(start 78.897734 -282.508706)
		(mid 78.807625 -282.5465)
		(end 78.71079 -282.559506)
		(width 0.0889)
		(layer "In13.Cu")
		(net "M_B_CPU1_SB_DQ<12>")
	)
	(arc
		(start 86.044024 -282.50896)
		(mid 85.761068 -282.432783)
		(end 85.478112 -282.50896)
		(width 0.0889)
		(layer "In13.Cu")
		(net "M_B_CPU1_SB_DQ<12>")
	)
	(arc
		(start 81.344008 -282.50896)
		(mid 81.061052 -282.432783)
		(end 80.778096 -282.50896)
		(width 0.0889)
		(layer "In13.Cu")
		(net "M_B_CPU1_SB_DQ<12>")
	)
	(arc
		(start 86.984078 -282.50896)
		(mid 86.701122 -282.432783)
		(end 86.418166 -282.50896)
		(width 0.0889)
		(layer "In13.Cu")
		(net "M_B_CPU1_SB_DQ<12>")
	)
	(arc
		(start 85.478112 -282.50896)
		(mid 85.295861 -282.55931)
		(end 85.112352 -282.513786)
		(width 0.0889)
		(layer "In13.Cu")
		(net "M_B_CPU1_SB_DQ<12>")
	)
	(arc
		(start 87.860632 -282.47721)
		(mid 87.605567 -282.433859)
		(end 87.357966 -282.50896)
		(width 0.0889)
		(layer "In13.Cu")
		(net "M_B_CPU1_SB_DQ<12>")
	)
	(arc
		(start 80.39354 -282.502864)
		(mid 80.114854 -282.432644)
		(end 79.837788 -282.50896)
		(width 0.0889)
		(layer "In13.Cu")
		(net "M_B_CPU1_SB_DQ<12>")
	)
	(arc
		(start 82.65795 -282.50896)
		(mid 82.471006 -282.559215)
		(end 82.284062 -282.50896)
		(width 0.0889)
		(layer "In13.Cu")
		(net "M_B_CPU1_SB_DQ<12>")
	)
	(arc
		(start 81.71815 -282.50896)
		(mid 81.535899 -282.55931)
		(end 81.35239 -282.513786)
		(width 0.0889)
		(layer "In13.Cu")
		(net "M_B_CPU1_SB_DQ<12>")
	)
	(arc
		(start 85.10397 -282.50896)
		(mid 84.821014 -282.432783)
		(end 84.538058 -282.50896)
		(width 0.0889)
		(layer "In13.Cu")
		(net "M_B_CPU1_SB_DQ<12>")
	)
	(arc
		(start 83.223862 -282.50896)
		(mid 82.940906 -282.432783)
		(end 82.65795 -282.50896)
		(width 0.0889)
		(layer "In13.Cu")
		(net "M_B_CPU1_SB_DQ<12>")
	)
	(arc
		(start 84.529676 -282.513786)
		(mid 84.346168 -282.55928)
		(end 84.163916 -282.50896)
		(width 0.0889)
		(layer "In13.Cu")
		(net "M_B_CPU1_SB_DQ<12>")
	)
	(arc
		(start 79.463138 -282.50896)
		(mid 79.18371 -282.432794)
		(end 78.903322 -282.505404)
		(width 0.0889)
		(layer "In13.Cu")
		(net "M_B_CPU1_SB_DQ<12>")
	)
	(arc
		(start 82.284062 -282.50896)
		(mid 82.001106 -282.432783)
		(end 81.71815 -282.50896)
		(width 0.0889)
		(layer "In13.Cu")
		(net "M_B_CPU1_SB_DQ<12>")
	)
	(arc
		(start 87.357966 -282.50896)
		(mid 87.171022 -282.559215)
		(end 86.984078 -282.50896)
		(width 0.0889)
		(layer "In13.Cu")
		(net "M_B_CPU1_SB_DQ<12>")
	)
	(arc
		(start 84.163916 -282.50896)
		(mid 83.88096 -282.432783)
		(end 83.598004 -282.50896)
		(width 0.0889)
		(layer "In13.Cu")
		(net "M_B_CPU1_SB_DQ<12>")
	)
	(arc
		(start 79.837788 -282.50896)
		(mid 79.655283 -282.559437)
		(end 79.47152 -282.513786)
		(width 0.0889)
		(layer "In13.Cu")
		(net "M_B_CPU1_SB_DQ<12>")
	)
	(arc
		(start 80.769714 -282.513786)
		(mid 80.586206 -282.55928)
		(end 80.403954 -282.50896)
		(width 0.0889)
		(layer "In13.Cu")
		(net "M_B_CPU1_SB_DQ<12>")
	)
	(segment
		(start 89.517982 -280.30043)
		(end 89.05113 -280.566368)
		(width 0.10668)
		(layer "F.Cu")
		(net "M_B_CPU1_SB_DQ<11>")
	)
	(segment
		(start 65.409826 -287.071562)
		(end 65.409826 -288.206434)
		(width 0.14478)
		(layer "In13.Cu")
		(net "M_B_CPU1_SB_DQ<11>")
	)
	(segment
		(start 86.052406 -280.238962)
		(end 86.044024 -280.243788)
		(width 0.0889)
		(layer "In13.Cu")
		(net "M_B_CPU1_SB_DQ<11>")
	)
	(segment
		(start 76.650596 -280.161746)
		(end 76.604368 -280.207974)
		(width 0.0889)
		(layer "In13.Cu")
		(net "M_B_CPU1_SB_DQ<11>")
	)
	(segment
		(start 49.446434 -293.38524)
		(end 47.784004 -293.38524)
		(width 0.14478)
		(layer "In13.Cu")
		(net "M_B_CPU1_SB_DQ<11>")
	)
	(segment
		(start 65.409826 -288.206434)
		(end 60.655962 -292.960298)
		(width 0.14478)
		(layer "In13.Cu")
		(net "M_B_CPU1_SB_DQ<11>")
	)
	(segment
		(start 76.604368 -280.207974)
		(end 76.316078 -280.207974)
		(width 0.0889)
		(layer "In13.Cu")
		(net "M_B_CPU1_SB_DQ<11>")
	)
	(segment
		(start 89.05113 -280.566368)
		(end 89.205054 -280.300938)
		(width 0.0889)
		(layer "In13.Cu")
		(net "M_B_CPU1_SB_DQ<11>")
	)
	(segment
		(start 72.273414 -280.207974)
		(end 65.409826 -287.071562)
		(width 0.14478)
		(layer "In13.Cu")
		(net "M_B_CPU1_SB_DQ<11>")
	)
	(segment
		(start 83.598004 -280.243788)
		(end 83.589622 -280.238962)
		(width 0.0889)
		(layer "In13.Cu")
		(net "M_B_CPU1_SB_DQ<11>")
	)
	(segment
		(start 80.100932 -280.325322)
		(end 79.583788 -280.325322)
		(width 0.0889)
		(layer "In13.Cu")
		(net "M_B_CPU1_SB_DQ<11>")
	)
	(segment
		(start 80.778096 -280.243788)
		(end 80.769714 -280.238962)
		(width 0.0889)
		(layer "In13.Cu")
		(net "M_B_CPU1_SB_DQ<11>")
	)
	(segment
		(start 53.528468 -292.950646)
		(end 49.881028 -292.950646)
		(width 0.14478)
		(layer "In13.Cu")
		(net "M_B_CPU1_SB_DQ<11>")
	)
	(segment
		(start 80.403954 -280.243788)
		(end 80.39354 -280.249884)
		(width 0.0889)
		(layer "In13.Cu")
		(net "M_B_CPU1_SB_DQ<11>")
	)
	(segment
		(start 89.205054 -280.300938)
		(end 89.182702 -280.217626)
		(width 0.0889)
		(layer "In13.Cu")
		(net "M_B_CPU1_SB_DQ<11>")
	)
	(segment
		(start 57.389776 -292.960298)
		(end 56.934862 -293.415212)
		(width 0.14478)
		(layer "In13.Cu")
		(net "M_B_CPU1_SB_DQ<11>")
	)
	(segment
		(start 81.35239 -280.238962)
		(end 81.344008 -280.243788)
		(width 0.0889)
		(layer "In13.Cu")
		(net "M_B_CPU1_SB_DQ<11>")
	)
	(segment
		(start 85.112352 -280.238962)
		(end 85.10397 -280.243788)
		(width 0.0889)
		(layer "In13.Cu")
		(net "M_B_CPU1_SB_DQ<11>")
	)
	(segment
		(start 53.993034 -293.415212)
		(end 53.528468 -292.950646)
		(width 0.14478)
		(layer "In13.Cu")
		(net "M_B_CPU1_SB_DQ<11>")
	)
	(segment
		(start 60.655962 -292.960298)
		(end 57.389776 -292.960298)
		(width 0.14478)
		(layer "In13.Cu")
		(net "M_B_CPU1_SB_DQ<11>")
	)
	(segment
		(start 84.538058 -280.243788)
		(end 84.529676 -280.238962)
		(width 0.0889)
		(layer "In13.Cu")
		(net "M_B_CPU1_SB_DQ<11>")
	)
	(segment
		(start 49.881028 -292.950646)
		(end 49.446434 -293.38524)
		(width 0.14478)
		(layer "In13.Cu")
		(net "M_B_CPU1_SB_DQ<11>")
	)
	(segment
		(start 79.420212 -280.161746)
		(end 76.650596 -280.161746)
		(width 0.0889)
		(layer "In13.Cu")
		(net "M_B_CPU1_SB_DQ<11>")
	)
	(segment
		(start 76.316078 -280.207974)
		(end 72.273414 -280.207974)
		(width 0.14478)
		(layer "In13.Cu")
		(net "M_B_CPU1_SB_DQ<11>")
	)
	(segment
		(start 88.29802 -280.243788)
		(end 88.289638 -280.238962)
		(width 0.0889)
		(layer "In13.Cu")
		(net "M_B_CPU1_SB_DQ<11>")
	)
	(segment
		(start 56.934862 -293.415212)
		(end 53.993034 -293.415212)
		(width 0.14478)
		(layer "In13.Cu")
		(net "M_B_CPU1_SB_DQ<11>")
	)
	(segment
		(start 79.583788 -280.325322)
		(end 79.420212 -280.161746)
		(width 0.0889)
		(layer "In13.Cu")
		(net "M_B_CPU1_SB_DQ<11>")
	)
	(arc
		(start 88.863932 -280.243788)
		(mid 88.580976 -280.319965)
		(end 88.29802 -280.243788)
		(width 0.0889)
		(layer "In13.Cu")
		(net "M_B_CPU1_SB_DQ<11>")
	)
	(arc
		(start 87.923878 -280.243788)
		(mid 87.640922 -280.319965)
		(end 87.357966 -280.243788)
		(width 0.0889)
		(layer "In13.Cu")
		(net "M_B_CPU1_SB_DQ<11>")
	)
	(arc
		(start 85.10397 -280.243788)
		(mid 84.821014 -280.319965)
		(end 84.538058 -280.243788)
		(width 0.0889)
		(layer "In13.Cu")
		(net "M_B_CPU1_SB_DQ<11>")
	)
	(arc
		(start 82.284062 -280.243788)
		(mid 82.001106 -280.319965)
		(end 81.71815 -280.243788)
		(width 0.0889)
		(layer "In13.Cu")
		(net "M_B_CPU1_SB_DQ<11>")
	)
	(arc
		(start 83.589622 -280.238962)
		(mid 83.406114 -280.193468)
		(end 83.223862 -280.243788)
		(width 0.0889)
		(layer "In13.Cu")
		(net "M_B_CPU1_SB_DQ<11>")
	)
	(arc
		(start 85.478112 -280.243788)
		(mid 85.295861 -280.193438)
		(end 85.112352 -280.238962)
		(width 0.0889)
		(layer "In13.Cu")
		(net "M_B_CPU1_SB_DQ<11>")
	)
	(arc
		(start 83.223862 -280.243788)
		(mid 82.940906 -280.319965)
		(end 82.65795 -280.243788)
		(width 0.0889)
		(layer "In13.Cu")
		(net "M_B_CPU1_SB_DQ<11>")
	)
	(arc
		(start 81.71815 -280.243788)
		(mid 81.535899 -280.193438)
		(end 81.35239 -280.238962)
		(width 0.0889)
		(layer "In13.Cu")
		(net "M_B_CPU1_SB_DQ<11>")
	)
	(arc
		(start 86.984078 -280.243788)
		(mid 86.701122 -280.319965)
		(end 86.418166 -280.243788)
		(width 0.0889)
		(layer "In13.Cu")
		(net "M_B_CPU1_SB_DQ<11>")
	)
	(arc
		(start 80.769714 -280.238962)
		(mid 80.586206 -280.193468)
		(end 80.403954 -280.243788)
		(width 0.0889)
		(layer "In13.Cu")
		(net "M_B_CPU1_SB_DQ<11>")
	)
	(arc
		(start 89.182702 -280.217626)
		(mid 89.02037 -280.194808)
		(end 88.863932 -280.243788)
		(width 0.0889)
		(layer "In13.Cu")
		(net "M_B_CPU1_SB_DQ<11>")
	)
	(arc
		(start 80.39354 -280.249884)
		(mid 80.252015 -280.306128)
		(end 80.100932 -280.325322)
		(width 0.0889)
		(layer "In13.Cu")
		(net "M_B_CPU1_SB_DQ<11>")
	)
	(arc
		(start 86.044024 -280.243788)
		(mid 85.761068 -280.319965)
		(end 85.478112 -280.243788)
		(width 0.0889)
		(layer "In13.Cu")
		(net "M_B_CPU1_SB_DQ<11>")
	)
	(arc
		(start 84.163916 -280.243788)
		(mid 83.88096 -280.319965)
		(end 83.598004 -280.243788)
		(width 0.0889)
		(layer "In13.Cu")
		(net "M_B_CPU1_SB_DQ<11>")
	)
	(arc
		(start 82.65795 -280.243788)
		(mid 82.471006 -280.193533)
		(end 82.284062 -280.243788)
		(width 0.0889)
		(layer "In13.Cu")
		(net "M_B_CPU1_SB_DQ<11>")
	)
	(arc
		(start 84.529676 -280.238962)
		(mid 84.346168 -280.193468)
		(end 84.163916 -280.243788)
		(width 0.0889)
		(layer "In13.Cu")
		(net "M_B_CPU1_SB_DQ<11>")
	)
	(arc
		(start 87.357966 -280.243788)
		(mid 87.171022 -280.193533)
		(end 86.984078 -280.243788)
		(width 0.0889)
		(layer "In13.Cu")
		(net "M_B_CPU1_SB_DQ<11>")
	)
	(arc
		(start 81.344008 -280.243788)
		(mid 81.061052 -280.319965)
		(end 80.778096 -280.243788)
		(width 0.0889)
		(layer "In13.Cu")
		(net "M_B_CPU1_SB_DQ<11>")
	)
	(arc
		(start 86.418166 -280.243788)
		(mid 86.235915 -280.193438)
		(end 86.052406 -280.238962)
		(width 0.0889)
		(layer "In13.Cu")
		(net "M_B_CPU1_SB_DQ<11>")
	)
	(arc
		(start 88.289638 -280.238962)
		(mid 88.10613 -280.193468)
		(end 87.923878 -280.243788)
		(width 0.0889)
		(layer "In13.Cu")
		(net "M_B_CPU1_SB_DQ<11>")
	)
	(segment
		(start 88.107774 -279.490424)
		(end 87.640922 -279.756362)
		(width 0.10668)
		(layer "F.Cu")
		(net "M_B_CPU1_SB_DQ<10>")
	)
	(segment
		(start 78.977744 -279.44318)
		(end 78.993492 -279.434036)
		(width 0.0889)
		(layer "In13.Cu")
		(net "M_B_CPU1_SB_DQ<10>")
	)
	(segment
		(start 71.71436 -279.298654)
		(end 76.345796 -279.298654)
		(width 0.14478)
		(layer "In13.Cu")
		(net "M_B_CPU1_SB_DQ<10>")
	)
	(segment
		(start 78.993492 -279.434036)
		(end 79.009748 -279.424638)
		(width 0.0889)
		(layer "In13.Cu")
		(net "M_B_CPU1_SB_DQ<10>")
	)
	(segment
		(start 63.627762 -287.385252)
		(end 63.832486 -287.385252)
		(width 0.14478)
		(layer "In13.Cu")
		(net "M_B_CPU1_SB_DQ<10>")
	)
	(segment
		(start 54.408578 -292.110414)
		(end 56.95315 -292.110414)
		(width 0.14478)
		(layer "In13.Cu")
		(net "M_B_CPU1_SB_DQ<10>")
	)
	(segment
		(start 87.453978 -279.433782)
		(end 87.46236 -279.428956)
		(width 0.0889)
		(layer "In13.Cu")
		(net "M_B_CPU1_SB_DQ<10>")
	)
	(segment
		(start 64.172592 -287.520634)
		(end 64.357758 -287.335468)
		(width 0.14478)
		(layer "In13.Cu")
		(net "M_B_CPU1_SB_DQ<10>")
	)
	(segment
		(start 82.179668 -279.428956)
		(end 82.18805 -279.433782)
		(width 0.0889)
		(layer "In13.Cu")
		(net "M_B_CPU1_SB_DQ<10>")
	)
	(segment
		(start 49.859946 -291.685218)
		(end 50.284888 -291.260276)
		(width 0.14478)
		(layer "In13.Cu")
		(net "M_B_CPU1_SB_DQ<10>")
	)
	(segment
		(start 76.71943 -279.084786)
		(end 78.051914 -279.084786)
		(width 0.0889)
		(layer "In13.Cu")
		(net "M_B_CPU1_SB_DQ<10>")
	)
	(segment
		(start 57.527698 -291.535866)
		(end 58.929524 -291.535866)
		(width 0.14478)
		(layer "In13.Cu")
		(net "M_B_CPU1_SB_DQ<10>")
	)
	(segment
		(start 79.36738 -279.433782)
		(end 79.377794 -279.439878)
		(width 0.0889)
		(layer "In13.Cu")
		(net "M_B_CPU1_SB_DQ<10>")
	)
	(segment
		(start 79.933546 -279.433782)
		(end 79.933292 -279.434036)
		(width 0.0889)
		(layer "In13.Cu")
		(net "M_B_CPU1_SB_DQ<10>")
	)
	(segment
		(start 86.879684 -279.428956)
		(end 86.888066 -279.433782)
		(width 0.0889)
		(layer "In13.Cu")
		(net "M_B_CPU1_SB_DQ<10>")
	)
	(segment
		(start 78.051914 -279.084786)
		(end 78.312264 -279.345136)
		(width 0.0889)
		(layer "In13.Cu")
		(net "M_B_CPU1_SB_DQ<10>")
	)
	(segment
		(start 64.222376 -286.995362)
		(end 64.222376 -286.790638)
		(width 0.14478)
		(layer "In13.Cu")
		(net "M_B_CPU1_SB_DQ<10>")
	)
	(segment
		(start 63.832486 -287.385252)
		(end 63.967868 -287.520634)
		(width 0.14478)
		(layer "In13.Cu")
		(net "M_B_CPU1_SB_DQ<10>")
	)
	(segment
		(start 63.967868 -287.520634)
		(end 64.172592 -287.520634)
		(width 0.14478)
		(layer "In13.Cu")
		(net "M_B_CPU1_SB_DQ<10>")
	)
	(segment
		(start 64.357758 -287.335468)
		(end 64.357758 -287.130744)
		(width 0.14478)
		(layer "In13.Cu")
		(net "M_B_CPU1_SB_DQ<10>")
	)
	(segment
		(start 82.753962 -279.433782)
		(end 82.762344 -279.428956)
		(width 0.0889)
		(layer "In13.Cu")
		(net "M_B_CPU1_SB_DQ<10>")
	)
	(segment
		(start 87.7951 -279.490932)
		(end 87.640922 -279.756362)
		(width 0.0889)
		(layer "In13.Cu")
		(net "M_B_CPU1_SB_DQ<10>")
	)
	(segment
		(start 47.784004 -291.685218)
		(end 49.859946 -291.685218)
		(width 0.14478)
		(layer "In13.Cu")
		(net "M_B_CPU1_SB_DQ<10>")
	)
	(segment
		(start 62.310518 -288.702496)
		(end 63.627762 -287.385252)
		(width 0.14478)
		(layer "In13.Cu")
		(net "M_B_CPU1_SB_DQ<10>")
	)
	(segment
		(start 61.083952 -291.260276)
		(end 62.310518 -290.03371)
		(width 0.14478)
		(layer "In13.Cu")
		(net "M_B_CPU1_SB_DQ<10>")
	)
	(segment
		(start 58.929524 -291.535866)
		(end 59.205114 -291.260276)
		(width 0.14478)
		(layer "In13.Cu")
		(net "M_B_CPU1_SB_DQ<10>")
	)
	(segment
		(start 85.93963 -279.428956)
		(end 85.948012 -279.433782)
		(width 0.0889)
		(layer "In13.Cu")
		(net "M_B_CPU1_SB_DQ<10>")
	)
	(segment
		(start 64.222376 -286.790638)
		(end 71.71436 -279.298654)
		(width 0.14478)
		(layer "In13.Cu")
		(net "M_B_CPU1_SB_DQ<10>")
	)
	(segment
		(start 59.205114 -291.260276)
		(end 61.083952 -291.260276)
		(width 0.14478)
		(layer "In13.Cu")
		(net "M_B_CPU1_SB_DQ<10>")
	)
	(segment
		(start 53.55844 -291.260276)
		(end 54.408578 -292.110414)
		(width 0.14478)
		(layer "In13.Cu")
		(net "M_B_CPU1_SB_DQ<10>")
	)
	(segment
		(start 76.505562 -279.298654)
		(end 76.71943 -279.084786)
		(width 0.0889)
		(layer "In13.Cu")
		(net "M_B_CPU1_SB_DQ<10>")
	)
	(segment
		(start 64.357758 -287.130744)
		(end 64.222376 -286.995362)
		(width 0.14478)
		(layer "In13.Cu")
		(net "M_B_CPU1_SB_DQ<10>")
	)
	(segment
		(start 62.310518 -290.03371)
		(end 62.310518 -288.702496)
		(width 0.14478)
		(layer "In13.Cu")
		(net "M_B_CPU1_SB_DQ<10>")
	)
	(segment
		(start 56.95315 -292.110414)
		(end 57.527698 -291.535866)
		(width 0.14478)
		(layer "In13.Cu")
		(net "M_B_CPU1_SB_DQ<10>")
	)
	(segment
		(start 76.345796 -279.298654)
		(end 76.505562 -279.298654)
		(width 0.0889)
		(layer "In13.Cu")
		(net "M_B_CPU1_SB_DQ<10>")
	)
	(segment
		(start 87.772748 -279.40762)
		(end 87.7951 -279.490932)
		(width 0.0889)
		(layer "In13.Cu")
		(net "M_B_CPU1_SB_DQ<10>")
	)
	(segment
		(start 83.694016 -279.433782)
		(end 83.702398 -279.428956)
		(width 0.0889)
		(layer "In13.Cu")
		(net "M_B_CPU1_SB_DQ<10>")
	)
	(segment
		(start 79.933292 -279.434036)
		(end 79.9338 -279.433782)
		(width 0.0889)
		(layer "In13.Cu")
		(net "M_B_CPU1_SB_DQ<10>")
	)
	(segment
		(start 50.284888 -291.260276)
		(end 53.55844 -291.260276)
		(width 0.14478)
		(layer "In13.Cu")
		(net "M_B_CPU1_SB_DQ<10>")
	)
	(arc
		(start 83.128104 -279.433782)
		(mid 83.41106 -279.509959)
		(end 83.694016 -279.433782)
		(width 0.0889)
		(layer "In13.Cu")
		(net "M_B_CPU1_SB_DQ<10>")
	)
	(arc
		(start 79.377794 -279.439878)
		(mid 79.65648 -279.510098)
		(end 79.933546 -279.433782)
		(width 0.0889)
		(layer "In13.Cu")
		(net "M_B_CPU1_SB_DQ<10>")
	)
	(arc
		(start 86.888066 -279.433782)
		(mid 87.171022 -279.509959)
		(end 87.453978 -279.433782)
		(width 0.0889)
		(layer "In13.Cu")
		(net "M_B_CPU1_SB_DQ<10>")
	)
	(arc
		(start 84.63407 -279.433782)
		(mid 84.821014 -279.383527)
		(end 85.007958 -279.433782)
		(width 0.0889)
		(layer "In13.Cu")
		(net "M_B_CPU1_SB_DQ<10>")
	)
	(arc
		(start 79.009748 -279.424638)
		(mid 79.18973 -279.383538)
		(end 79.36738 -279.433782)
		(width 0.0889)
		(layer "In13.Cu")
		(net "M_B_CPU1_SB_DQ<10>")
	)
	(arc
		(start 85.007958 -279.433782)
		(mid 85.290914 -279.509959)
		(end 85.57387 -279.433782)
		(width 0.0889)
		(layer "In13.Cu")
		(net "M_B_CPU1_SB_DQ<10>")
	)
	(arc
		(start 87.46236 -279.428956)
		(mid 87.61523 -279.384315)
		(end 87.772748 -279.40762)
		(width 0.0889)
		(layer "In13.Cu")
		(net "M_B_CPU1_SB_DQ<10>")
	)
	(arc
		(start 78.312264 -279.345136)
		(mid 78.367049 -279.393196)
		(end 78.42758 -279.433782)
		(width 0.0889)
		(layer "In13.Cu")
		(net "M_B_CPU1_SB_DQ<10>")
	)
	(arc
		(start 81.247996 -279.433782)
		(mid 81.530952 -279.509959)
		(end 81.813908 -279.433782)
		(width 0.0889)
		(layer "In13.Cu")
		(net "M_B_CPU1_SB_DQ<10>")
	)
	(arc
		(start 84.068158 -279.433782)
		(mid 84.351114 -279.509959)
		(end 84.63407 -279.433782)
		(width 0.0889)
		(layer "In13.Cu")
		(net "M_B_CPU1_SB_DQ<10>")
	)
	(arc
		(start 85.57387 -279.433782)
		(mid 85.756121 -279.383432)
		(end 85.93963 -279.428956)
		(width 0.0889)
		(layer "In13.Cu")
		(net "M_B_CPU1_SB_DQ<10>")
	)
	(arc
		(start 86.513924 -279.433782)
		(mid 86.696175 -279.383432)
		(end 86.879684 -279.428956)
		(width 0.0889)
		(layer "In13.Cu")
		(net "M_B_CPU1_SB_DQ<10>")
	)
	(arc
		(start 79.9338 -279.433782)
		(mid 80.120998 -279.3834)
		(end 80.308196 -279.433782)
		(width 0.0889)
		(layer "In13.Cu")
		(net "M_B_CPU1_SB_DQ<10>")
	)
	(arc
		(start 80.874108 -279.433782)
		(mid 81.061052 -279.383527)
		(end 81.247996 -279.433782)
		(width 0.0889)
		(layer "In13.Cu")
		(net "M_B_CPU1_SB_DQ<10>")
	)
	(arc
		(start 81.813908 -279.433782)
		(mid 81.996159 -279.383432)
		(end 82.179668 -279.428956)
		(width 0.0889)
		(layer "In13.Cu")
		(net "M_B_CPU1_SB_DQ<10>")
	)
	(arc
		(start 83.702398 -279.428956)
		(mid 83.885906 -279.383462)
		(end 84.068158 -279.433782)
		(width 0.0889)
		(layer "In13.Cu")
		(net "M_B_CPU1_SB_DQ<10>")
	)
	(arc
		(start 85.948012 -279.433782)
		(mid 86.230968 -279.509959)
		(end 86.513924 -279.433782)
		(width 0.0889)
		(layer "In13.Cu")
		(net "M_B_CPU1_SB_DQ<10>")
	)
	(arc
		(start 82.762344 -279.428956)
		(mid 82.945852 -279.383462)
		(end 83.128104 -279.433782)
		(width 0.0889)
		(layer "In13.Cu")
		(net "M_B_CPU1_SB_DQ<10>")
	)
	(arc
		(start 80.308196 -279.433782)
		(mid 80.591152 -279.509959)
		(end 80.874108 -279.433782)
		(width 0.0889)
		(layer "In13.Cu")
		(net "M_B_CPU1_SB_DQ<10>")
	)
	(arc
		(start 82.18805 -279.433782)
		(mid 82.471006 -279.509959)
		(end 82.753962 -279.433782)
		(width 0.0889)
		(layer "In13.Cu")
		(net "M_B_CPU1_SB_DQ<10>")
	)
	(arc
		(start 78.42758 -279.433782)
		(mid 78.701435 -279.510132)
		(end 78.977744 -279.44318)
		(width 0.0889)
		(layer "In13.Cu")
		(net "M_B_CPU1_SB_DQ<10>")
	)
	(segment
		(start 88.577928 -273.820382)
		(end 88.111076 -274.08632)
		(width 0.10668)
		(layer "F.Cu")
		(net "M_B_CPU1_SB_DQ<0>")
	)
	(segment
		(start 86.052406 -274.413726)
		(end 86.044024 -274.4089)
		(width 0.0889)
		(layer "In13.Cu")
		(net "M_B_CPU1_SB_DQ<0>")
	)
	(segment
		(start 87.956898 -274.35175)
		(end 87.860632 -274.37715)
		(width 0.0889)
		(layer "In13.Cu")
		(net "M_B_CPU1_SB_DQ<0>")
	)
	(segment
		(start 58.048144 -281.460702)
		(end 57.659778 -281.460702)
		(width 0.14478)
		(layer "In13.Cu")
		(net "M_B_CPU1_SB_DQ<0>")
	)
	(segment
		(start 63.065406 -277.998682)
		(end 62.733936 -277.998682)
		(width 0.14478)
		(layer "In13.Cu")
		(net "M_B_CPU1_SB_DQ<0>")
	)
	(segment
		(start 58.744104 -281.315922)
		(end 58.744104 -281.009852)
		(width 0.14478)
		(layer "In13.Cu")
		(net "M_B_CPU1_SB_DQ<0>")
	)
	(segment
		(start 62.5094 -278.223218)
		(end 62.5094 -278.45131)
		(width 0.14478)
		(layer "In13.Cu")
		(net "M_B_CPU1_SB_DQ<0>")
	)
	(segment
		(start 56.703722 -281.910282)
		(end 56.542178 -281.748738)
		(width 0.14478)
		(layer "In13.Cu")
		(net "M_B_CPU1_SB_DQ<0>")
	)
	(segment
		(start 63.289942 -277.774146)
		(end 63.065406 -277.998682)
		(width 0.14478)
		(layer "In13.Cu")
		(net "M_B_CPU1_SB_DQ<0>")
	)
	(segment
		(start 78.897734 -274.408646)
		(end 78.879446 -274.41906)
		(width 0.0889)
		(layer "In13.Cu")
		(net "M_B_CPU1_SB_DQ<0>")
	)
	(segment
		(start 77.535024 -273.438366)
		(end 76.817728 -273.438366)
		(width 0.0889)
		(layer "In13.Cu")
		(net "M_B_CPU1_SB_DQ<0>")
	)
	(segment
		(start 62.5094 -278.45131)
		(end 62.509654 -278.554434)
		(width 0.14478)
		(layer "In13.Cu")
		(net "M_B_CPU1_SB_DQ<0>")
	)
	(segment
		(start 83.598004 -274.4089)
		(end 83.589622 -274.413726)
		(width 0.0889)
		(layer "In13.Cu")
		(net "M_B_CPU1_SB_DQ<0>")
	)
	(segment
		(start 84.538058 -274.4089)
		(end 84.529676 -274.413726)
		(width 0.0889)
		(layer "In13.Cu")
		(net "M_B_CPU1_SB_DQ<0>")
	)
	(segment
		(start 81.35239 -274.413726)
		(end 81.344008 -274.4089)
		(width 0.0889)
		(layer "In13.Cu")
		(net "M_B_CPU1_SB_DQ<0>")
	)
	(segment
		(start 62.285118 -278.77897)
		(end 61.953648 -278.77897)
		(width 0.14478)
		(layer "In13.Cu")
		(net "M_B_CPU1_SB_DQ<0>")
	)
	(segment
		(start 60.724542 -280.339546)
		(end 60.393072 -280.339546)
		(width 0.14478)
		(layer "In13.Cu")
		(net "M_B_CPU1_SB_DQ<0>")
	)
	(segment
		(start 66.41084 -274.54987)
		(end 66.411094 -274.652994)
		(width 0.14478)
		(layer "In13.Cu")
		(net "M_B_CPU1_SB_DQ<0>")
	)
	(segment
		(start 58.337704 -280.865072)
		(end 58.192924 -281.009852)
		(width 0.14478)
		(layer "In13.Cu")
		(net "M_B_CPU1_SB_DQ<0>")
	)
	(segment
		(start 56.542178 -281.748738)
		(end 56.542178 -281.40279)
		(width 0.14478)
		(layer "In13.Cu")
		(net "M_B_CPU1_SB_DQ<0>")
	)
	(segment
		(start 54.867048 -281.910282)
		(end 54.705504 -281.748738)
		(width 0.14478)
		(layer "In13.Cu")
		(net "M_B_CPU1_SB_DQ<0>")
	)
	(segment
		(start 58.192924 -281.315922)
		(end 58.048144 -281.460702)
		(width 0.14478)
		(layer "In13.Cu")
		(net "M_B_CPU1_SB_DQ<0>")
	)
	(segment
		(start 65.630552 -275.102066)
		(end 65.630552 -275.330158)
		(width 0.14478)
		(layer "In13.Cu")
		(net "M_B_CPU1_SB_DQ<0>")
	)
	(segment
		(start 67.191128 -273.769582)
		(end 67.191382 -273.872706)
		(width 0.14478)
		(layer "In13.Cu")
		(net "M_B_CPU1_SB_DQ<0>")
	)
	(segment
		(start 51.884072 -281.266392)
		(end 51.884072 -281.48534)
		(width 0.14478)
		(layer "In13.Cu")
		(net "M_B_CPU1_SB_DQ<0>")
	)
	(segment
		(start 64.069976 -276.890734)
		(end 64.07023 -276.993858)
		(width 0.14478)
		(layer "In13.Cu")
		(net "M_B_CPU1_SB_DQ<0>")
	)
	(segment
		(start 60.948824 -280.115264)
		(end 60.724542 -280.339546)
		(width 0.14478)
		(layer "In13.Cu")
		(net "M_B_CPU1_SB_DQ<0>")
	)
	(segment
		(start 56.542178 -281.40279)
		(end 56.380634 -281.241246)
		(width 0.14478)
		(layer "In13.Cu")
		(net "M_B_CPU1_SB_DQ<0>")
	)
	(segment
		(start 55.8292 -281.910282)
		(end 54.867048 -281.910282)
		(width 0.14478)
		(layer "In13.Cu")
		(net "M_B_CPU1_SB_DQ<0>")
	)
	(segment
		(start 61.729112 -279.231598)
		(end 61.729366 -279.334722)
		(width 0.14478)
		(layer "In13.Cu")
		(net "M_B_CPU1_SB_DQ<0>")
	)
	(segment
		(start 56.152288 -281.241246)
		(end 55.990744 -281.40279)
		(width 0.14478)
		(layer "In13.Cu")
		(net "M_B_CPU1_SB_DQ<0>")
	)
	(segment
		(start 67.191128 -273.54149)
		(end 67.191128 -273.769582)
		(width 0.14478)
		(layer "In13.Cu")
		(net "M_B_CPU1_SB_DQ<0>")
	)
	(segment
		(start 65.630552 -275.330158)
		(end 65.630806 -275.433282)
		(width 0.14478)
		(layer "In13.Cu")
		(net "M_B_CPU1_SB_DQ<0>")
	)
	(segment
		(start 54.705504 -281.748738)
		(end 54.705504 -281.38247)
		(width 0.14478)
		(layer "In13.Cu")
		(net "M_B_CPU1_SB_DQ<0>")
	)
	(segment
		(start 56.380634 -281.241246)
		(end 56.152288 -281.241246)
		(width 0.14478)
		(layer "In13.Cu")
		(net "M_B_CPU1_SB_DQ<0>")
	)
	(segment
		(start 80.403954 -274.4089)
		(end 80.39354 -274.402804)
		(width 0.0889)
		(layer "In13.Cu")
		(net "M_B_CPU1_SB_DQ<0>")
	)
	(segment
		(start 57.210198 -281.910282)
		(end 56.703722 -281.910282)
		(width 0.14478)
		(layer "In13.Cu")
		(net "M_B_CPU1_SB_DQ<0>")
	)
	(segment
		(start 66.186558 -274.87753)
		(end 65.855088 -274.87753)
		(width 0.14478)
		(layer "In13.Cu")
		(net "M_B_CPU1_SB_DQ<0>")
	)
	(segment
		(start 58.888884 -281.460702)
		(end 58.744104 -281.315922)
		(width 0.14478)
		(layer "In13.Cu")
		(net "M_B_CPU1_SB_DQ<0>")
	)
	(segment
		(start 64.850264 -275.882354)
		(end 64.850264 -276.110446)
		(width 0.14478)
		(layer "In13.Cu")
		(net "M_B_CPU1_SB_DQ<0>")
	)
	(segment
		(start 64.625982 -276.438106)
		(end 64.294512 -276.438106)
		(width 0.14478)
		(layer "In13.Cu")
		(net "M_B_CPU1_SB_DQ<0>")
	)
	(segment
		(start 78.446884 -274.350226)
		(end 77.535024 -273.438366)
		(width 0.0889)
		(layer "In13.Cu")
		(net "M_B_CPU1_SB_DQ<0>")
	)
	(segment
		(start 66.41084 -274.321778)
		(end 66.41084 -274.54987)
		(width 0.14478)
		(layer "In13.Cu")
		(net "M_B_CPU1_SB_DQ<0>")
	)
	(segment
		(start 58.192924 -281.009852)
		(end 58.192924 -281.315922)
		(width 0.14478)
		(layer "In13.Cu")
		(net "M_B_CPU1_SB_DQ<0>")
	)
	(segment
		(start 58.599324 -280.865072)
		(end 58.337704 -280.865072)
		(width 0.14478)
		(layer "In13.Cu")
		(net "M_B_CPU1_SB_DQ<0>")
	)
	(segment
		(start 80.778096 -274.4089)
		(end 80.769714 -274.413726)
		(width 0.0889)
		(layer "In13.Cu")
		(net "M_B_CPU1_SB_DQ<0>")
	)
	(segment
		(start 76.817728 -273.438366)
		(end 76.599796 -273.220434)
		(width 0.0889)
		(layer "In13.Cu")
		(net "M_B_CPU1_SB_DQ<0>")
	)
	(segment
		(start 64.850264 -276.110446)
		(end 64.850518 -276.21357)
		(width 0.14478)
		(layer "In13.Cu")
		(net "M_B_CPU1_SB_DQ<0>")
	)
	(segment
		(start 64.07023 -276.993858)
		(end 63.845694 -277.218394)
		(width 0.14478)
		(layer "In13.Cu")
		(net "M_B_CPU1_SB_DQ<0>")
	)
	(segment
		(start 66.966846 -274.097242)
		(end 66.635376 -274.097242)
		(width 0.14478)
		(layer "In13.Cu")
		(net "M_B_CPU1_SB_DQ<0>")
	)
	(segment
		(start 55.990744 -281.748738)
		(end 55.8292 -281.910282)
		(width 0.14478)
		(layer "In13.Cu")
		(net "M_B_CPU1_SB_DQ<0>")
	)
	(segment
		(start 52.09032 -281.060144)
		(end 51.884072 -281.266392)
		(width 0.14478)
		(layer "In13.Cu")
		(net "M_B_CPU1_SB_DQ<0>")
	)
	(segment
		(start 65.0748 -275.657818)
		(end 64.850264 -275.882354)
		(width 0.14478)
		(layer "In13.Cu")
		(net "M_B_CPU1_SB_DQ<0>")
	)
	(segment
		(start 78.523592 -274.4089)
		(end 78.523338 -274.4089)
		(width 0.0889)
		(layer "In13.Cu")
		(net "M_B_CPU1_SB_DQ<0>")
	)
	(segment
		(start 59.271916 -281.460702)
		(end 58.888884 -281.460702)
		(width 0.14478)
		(layer "In13.Cu")
		(net "M_B_CPU1_SB_DQ<0>")
	)
	(segment
		(start 61.729366 -279.334722)
		(end 61.50483 -279.559258)
		(width 0.14478)
		(layer "In13.Cu")
		(net "M_B_CPU1_SB_DQ<0>")
	)
	(segment
		(start 63.289688 -277.44293)
		(end 63.289688 -277.671022)
		(width 0.14478)
		(layer "In13.Cu")
		(net "M_B_CPU1_SB_DQ<0>")
	)
	(segment
		(start 62.733936 -277.998682)
		(end 62.5094 -278.223218)
		(width 0.14478)
		(layer "In13.Cu")
		(net "M_B_CPU1_SB_DQ<0>")
	)
	(segment
		(start 55.990744 -281.40279)
		(end 55.990744 -281.748738)
		(width 0.14478)
		(layer "In13.Cu")
		(net "M_B_CPU1_SB_DQ<0>")
	)
	(segment
		(start 61.50483 -279.559258)
		(end 61.17336 -279.559258)
		(width 0.14478)
		(layer "In13.Cu")
		(net "M_B_CPU1_SB_DQ<0>")
	)
	(segment
		(start 88.111076 -274.08632)
		(end 87.956898 -274.35175)
		(width 0.0889)
		(layer "In13.Cu")
		(net "M_B_CPU1_SB_DQ<0>")
	)
	(segment
		(start 54.54396 -281.220926)
		(end 54.315614 -281.220926)
		(width 0.14478)
		(layer "In13.Cu")
		(net "M_B_CPU1_SB_DQ<0>")
	)
	(segment
		(start 67.512184 -273.220434)
		(end 67.191128 -273.54149)
		(width 0.14478)
		(layer "In13.Cu")
		(net "M_B_CPU1_SB_DQ<0>")
	)
	(segment
		(start 63.845694 -277.218394)
		(end 63.514224 -277.218394)
		(width 0.14478)
		(layer "In13.Cu")
		(net "M_B_CPU1_SB_DQ<0>")
	)
	(segment
		(start 61.17336 -279.559258)
		(end 60.948824 -279.783794)
		(width 0.14478)
		(layer "In13.Cu")
		(net "M_B_CPU1_SB_DQ<0>")
	)
	(segment
		(start 65.855088 -274.87753)
		(end 65.630552 -275.102066)
		(width 0.14478)
		(layer "In13.Cu")
		(net "M_B_CPU1_SB_DQ<0>")
	)
	(segment
		(start 52.864512 -281.060144)
		(end 52.09032 -281.060144)
		(width 0.14478)
		(layer "In13.Cu")
		(net "M_B_CPU1_SB_DQ<0>")
	)
	(segment
		(start 63.514224 -277.218394)
		(end 63.289688 -277.44293)
		(width 0.14478)
		(layer "In13.Cu")
		(net "M_B_CPU1_SB_DQ<0>")
	)
	(segment
		(start 53.992526 -281.910282)
		(end 53.71465 -281.910282)
		(width 0.14478)
		(layer "In13.Cu")
		(net "M_B_CPU1_SB_DQ<0>")
	)
	(segment
		(start 65.40627 -275.657818)
		(end 65.0748 -275.657818)
		(width 0.14478)
		(layer "In13.Cu")
		(net "M_B_CPU1_SB_DQ<0>")
	)
	(segment
		(start 58.744104 -281.009852)
		(end 58.599324 -280.865072)
		(width 0.14478)
		(layer "In13.Cu")
		(net "M_B_CPU1_SB_DQ<0>")
	)
	(segment
		(start 54.705504 -281.38247)
		(end 54.54396 -281.220926)
		(width 0.14478)
		(layer "In13.Cu")
		(net "M_B_CPU1_SB_DQ<0>")
	)
	(segment
		(start 78.903322 -274.405344)
		(end 78.897734 -274.408646)
		(width 0.0889)
		(layer "In13.Cu")
		(net "M_B_CPU1_SB_DQ<0>")
	)
	(segment
		(start 53.71465 -281.910282)
		(end 52.864512 -281.060144)
		(width 0.14478)
		(layer "In13.Cu")
		(net "M_B_CPU1_SB_DQ<0>")
	)
	(segment
		(start 64.850518 -276.21357)
		(end 64.625982 -276.438106)
		(width 0.14478)
		(layer "In13.Cu")
		(net "M_B_CPU1_SB_DQ<0>")
	)
	(segment
		(start 79.47152 -274.413726)
		(end 79.463138 -274.4089)
		(width 0.0889)
		(layer "In13.Cu")
		(net "M_B_CPU1_SB_DQ<0>")
	)
	(segment
		(start 66.635376 -274.097242)
		(end 66.41084 -274.321778)
		(width 0.14478)
		(layer "In13.Cu")
		(net "M_B_CPU1_SB_DQ<0>")
	)
	(segment
		(start 63.289688 -277.671022)
		(end 63.289942 -277.774146)
		(width 0.14478)
		(layer "In13.Cu")
		(net "M_B_CPU1_SB_DQ<0>")
	)
	(segment
		(start 67.191382 -273.872706)
		(end 66.966846 -274.097242)
		(width 0.14478)
		(layer "In13.Cu")
		(net "M_B_CPU1_SB_DQ<0>")
	)
	(segment
		(start 64.069976 -276.662642)
		(end 64.069976 -276.890734)
		(width 0.14478)
		(layer "In13.Cu")
		(net "M_B_CPU1_SB_DQ<0>")
	)
	(segment
		(start 60.393072 -280.339546)
		(end 59.271916 -281.460702)
		(width 0.14478)
		(layer "In13.Cu")
		(net "M_B_CPU1_SB_DQ<0>")
	)
	(segment
		(start 60.948824 -279.783794)
		(end 60.948824 -280.115264)
		(width 0.14478)
		(layer "In13.Cu")
		(net "M_B_CPU1_SB_DQ<0>")
	)
	(segment
		(start 66.411094 -274.652994)
		(end 66.186558 -274.87753)
		(width 0.14478)
		(layer "In13.Cu")
		(net "M_B_CPU1_SB_DQ<0>")
	)
	(segment
		(start 61.953648 -278.77897)
		(end 61.729112 -279.003506)
		(width 0.14478)
		(layer "In13.Cu")
		(net "M_B_CPU1_SB_DQ<0>")
	)
	(segment
		(start 85.112352 -274.413726)
		(end 85.10397 -274.4089)
		(width 0.0889)
		(layer "In13.Cu")
		(net "M_B_CPU1_SB_DQ<0>")
	)
	(segment
		(start 64.294512 -276.438106)
		(end 64.069976 -276.662642)
		(width 0.14478)
		(layer "In13.Cu")
		(net "M_B_CPU1_SB_DQ<0>")
	)
	(segment
		(start 54.315614 -281.220926)
		(end 54.15407 -281.38247)
		(width 0.14478)
		(layer "In13.Cu")
		(net "M_B_CPU1_SB_DQ<0>")
	)
	(segment
		(start 76.599796 -273.220434)
		(end 67.512184 -273.220434)
		(width 0.14478)
		(layer "In13.Cu")
		(net "M_B_CPU1_SB_DQ<0>")
	)
	(segment
		(start 54.15407 -281.748738)
		(end 53.992526 -281.910282)
		(width 0.14478)
		(layer "In13.Cu")
		(net "M_B_CPU1_SB_DQ<0>")
	)
	(segment
		(start 61.729112 -279.003506)
		(end 61.729112 -279.231598)
		(width 0.14478)
		(layer "In13.Cu")
		(net "M_B_CPU1_SB_DQ<0>")
	)
	(segment
		(start 57.659778 -281.460702)
		(end 57.210198 -281.910282)
		(width 0.14478)
		(layer "In13.Cu")
		(net "M_B_CPU1_SB_DQ<0>")
	)
	(segment
		(start 65.630806 -275.433282)
		(end 65.40627 -275.657818)
		(width 0.14478)
		(layer "In13.Cu")
		(net "M_B_CPU1_SB_DQ<0>")
	)
	(segment
		(start 62.509654 -278.554434)
		(end 62.285118 -278.77897)
		(width 0.14478)
		(layer "In13.Cu")
		(net "M_B_CPU1_SB_DQ<0>")
	)
	(segment
		(start 54.15407 -281.38247)
		(end 54.15407 -281.748738)
		(width 0.14478)
		(layer "In13.Cu")
		(net "M_B_CPU1_SB_DQ<0>")
	)
	(arc
		(start 79.837788 -274.4089)
		(mid 79.655283 -274.459377)
		(end 79.47152 -274.413726)
		(width 0.0889)
		(layer "In13.Cu")
		(net "M_B_CPU1_SB_DQ<0>")
	)
	(arc
		(start 85.10397 -274.4089)
		(mid 84.821014 -274.332723)
		(end 84.538058 -274.4089)
		(width 0.0889)
		(layer "In13.Cu")
		(net "M_B_CPU1_SB_DQ<0>")
	)
	(arc
		(start 80.769714 -274.413726)
		(mid 80.586206 -274.45922)
		(end 80.403954 -274.4089)
		(width 0.0889)
		(layer "In13.Cu")
		(net "M_B_CPU1_SB_DQ<0>")
	)
	(arc
		(start 84.163916 -274.4089)
		(mid 83.88096 -274.332723)
		(end 83.598004 -274.4089)
		(width 0.0889)
		(layer "In13.Cu")
		(net "M_B_CPU1_SB_DQ<0>")
	)
	(arc
		(start 86.044024 -274.4089)
		(mid 85.761068 -274.332723)
		(end 85.478112 -274.4089)
		(width 0.0889)
		(layer "In13.Cu")
		(net "M_B_CPU1_SB_DQ<0>")
	)
	(arc
		(start 87.860632 -274.37715)
		(mid 87.605567 -274.333799)
		(end 87.357966 -274.4089)
		(width 0.0889)
		(layer "In13.Cu")
		(net "M_B_CPU1_SB_DQ<0>")
	)
	(arc
		(start 83.223862 -274.4089)
		(mid 82.940906 -274.332723)
		(end 82.65795 -274.4089)
		(width 0.0889)
		(layer "In13.Cu")
		(net "M_B_CPU1_SB_DQ<0>")
	)
	(arc
		(start 79.463138 -274.4089)
		(mid 79.18371 -274.332734)
		(end 78.903322 -274.405344)
		(width 0.0889)
		(layer "In13.Cu")
		(net "M_B_CPU1_SB_DQ<0>")
	)
	(arc
		(start 86.418166 -274.4089)
		(mid 86.235915 -274.45925)
		(end 86.052406 -274.413726)
		(width 0.0889)
		(layer "In13.Cu")
		(net "M_B_CPU1_SB_DQ<0>")
	)
	(arc
		(start 82.65795 -274.4089)
		(mid 82.471006 -274.459155)
		(end 82.284062 -274.4089)
		(width 0.0889)
		(layer "In13.Cu")
		(net "M_B_CPU1_SB_DQ<0>")
	)
	(arc
		(start 78.523338 -274.4089)
		(mid 78.483209 -274.382041)
		(end 78.446884 -274.350226)
		(width 0.0889)
		(layer "In13.Cu")
		(net "M_B_CPU1_SB_DQ<0>")
	)
	(arc
		(start 82.284062 -274.4089)
		(mid 82.001106 -274.332723)
		(end 81.71815 -274.4089)
		(width 0.0889)
		(layer "In13.Cu")
		(net "M_B_CPU1_SB_DQ<0>")
	)
	(arc
		(start 78.879446 -274.41906)
		(mid 78.700217 -274.459213)
		(end 78.523592 -274.4089)
		(width 0.0889)
		(layer "In13.Cu")
		(net "M_B_CPU1_SB_DQ<0>")
	)
	(arc
		(start 85.478112 -274.4089)
		(mid 85.295861 -274.45925)
		(end 85.112352 -274.413726)
		(width 0.0889)
		(layer "In13.Cu")
		(net "M_B_CPU1_SB_DQ<0>")
	)
	(arc
		(start 80.39354 -274.402804)
		(mid 80.114854 -274.332584)
		(end 79.837788 -274.4089)
		(width 0.0889)
		(layer "In13.Cu")
		(net "M_B_CPU1_SB_DQ<0>")
	)
	(arc
		(start 86.984078 -274.4089)
		(mid 86.701122 -274.332723)
		(end 86.418166 -274.4089)
		(width 0.0889)
		(layer "In13.Cu")
		(net "M_B_CPU1_SB_DQ<0>")
	)
	(arc
		(start 84.529676 -274.413726)
		(mid 84.346168 -274.45922)
		(end 84.163916 -274.4089)
		(width 0.0889)
		(layer "In13.Cu")
		(net "M_B_CPU1_SB_DQ<0>")
	)
	(arc
		(start 81.344008 -274.4089)
		(mid 81.061052 -274.332723)
		(end 80.778096 -274.4089)
		(width 0.0889)
		(layer "In13.Cu")
		(net "M_B_CPU1_SB_DQ<0>")
	)
	(arc
		(start 83.589622 -274.413726)
		(mid 83.406114 -274.45922)
		(end 83.223862 -274.4089)
		(width 0.0889)
		(layer "In13.Cu")
		(net "M_B_CPU1_SB_DQ<0>")
	)
	(arc
		(start 87.357966 -274.4089)
		(mid 87.171022 -274.459155)
		(end 86.984078 -274.4089)
		(width 0.0889)
		(layer "In13.Cu")
		(net "M_B_CPU1_SB_DQ<0>")
	)
	(arc
		(start 81.71815 -274.4089)
		(mid 81.535899 -274.45925)
		(end 81.35239 -274.413726)
		(width 0.0889)
		(layer "In13.Cu")
		(net "M_B_CPU1_SB_DQ<0>")
	)
	(segment
		(start 88.107774 -266.530328)
		(end 87.640922 -266.796266)
		(width 0.10668)
		(layer "F.Cu")
		(net "M_B_CPU1_SB_CS_N<1>")
	)
	(segment
		(start 78.322424 -266.42314)
		(end 77.883258 -265.983974)
		(width 0.0889)
		(layer "In13.Cu")
		(net "M_B_CPU1_SB_CS_N<1>")
	)
	(segment
		(start 85.948012 -266.473686)
		(end 85.93963 -266.46886)
		(width 0.0889)
		(layer "In13.Cu")
		(net "M_B_CPU1_SB_CS_N<1>")
	)
	(segment
		(start 75.957176 -265.983974)
		(end 61.703204 -265.983974)
		(width 0.14478)
		(layer "In13.Cu")
		(net "M_B_CPU1_SB_CS_N<1>")
	)
	(segment
		(start 59.376818 -268.31036)
		(end 50.526696 -268.31036)
		(width 0.14478)
		(layer "In13.Cu")
		(net "M_B_CPU1_SB_CS_N<1>")
	)
	(segment
		(start 50.526696 -268.31036)
		(end 50.101754 -268.735302)
		(width 0.14478)
		(layer "In13.Cu")
		(net "M_B_CPU1_SB_CS_N<1>")
	)
	(segment
		(start 50.101754 -268.735302)
		(end 47.784004 -268.735302)
		(width 0.14478)
		(layer "In13.Cu")
		(net "M_B_CPU1_SB_CS_N<1>")
	)
	(segment
		(start 82.762344 -266.46886)
		(end 82.753962 -266.473686)
		(width 0.0889)
		(layer "In13.Cu")
		(net "M_B_CPU1_SB_CS_N<1>")
	)
	(segment
		(start 80.120998 -266.42314)
		(end 78.322424 -266.42314)
		(width 0.0889)
		(layer "In13.Cu")
		(net "M_B_CPU1_SB_CS_N<1>")
	)
	(segment
		(start 87.640922 -266.796266)
		(end 87.486744 -266.530836)
		(width 0.0889)
		(layer "In13.Cu")
		(net "M_B_CPU1_SB_CS_N<1>")
	)
	(segment
		(start 87.486744 -266.530836)
		(end 87.390478 -266.505436)
		(width 0.0889)
		(layer "In13.Cu")
		(net "M_B_CPU1_SB_CS_N<1>")
	)
	(segment
		(start 61.703204 -265.983974)
		(end 59.376818 -268.31036)
		(width 0.14478)
		(layer "In13.Cu")
		(net "M_B_CPU1_SB_CS_N<1>")
	)
	(segment
		(start 82.18805 -266.473686)
		(end 82.179668 -266.46886)
		(width 0.0889)
		(layer "In13.Cu")
		(net "M_B_CPU1_SB_CS_N<1>")
	)
	(segment
		(start 77.883258 -265.983974)
		(end 75.957176 -265.983974)
		(width 0.0889)
		(layer "In13.Cu")
		(net "M_B_CPU1_SB_CS_N<1>")
	)
	(segment
		(start 83.702398 -266.46886)
		(end 83.694016 -266.473686)
		(width 0.0889)
		(layer "In13.Cu")
		(net "M_B_CPU1_SB_CS_N<1>")
	)
	(arc
		(start 85.57387 -266.473686)
		(mid 85.290914 -266.549863)
		(end 85.007958 -266.473686)
		(width 0.0889)
		(layer "In13.Cu")
		(net "M_B_CPU1_SB_CS_N<1>")
	)
	(arc
		(start 81.813908 -266.473686)
		(mid 81.530952 -266.549863)
		(end 81.247996 -266.473686)
		(width 0.0889)
		(layer "In13.Cu")
		(net "M_B_CPU1_SB_CS_N<1>")
	)
	(arc
		(start 81.247996 -266.473686)
		(mid 81.061052 -266.423431)
		(end 80.874108 -266.473686)
		(width 0.0889)
		(layer "In13.Cu")
		(net "M_B_CPU1_SB_CS_N<1>")
	)
	(arc
		(start 86.513924 -266.473686)
		(mid 86.230968 -266.549863)
		(end 85.948012 -266.473686)
		(width 0.0889)
		(layer "In13.Cu")
		(net "M_B_CPU1_SB_CS_N<1>")
	)
	(arc
		(start 80.874108 -266.473686)
		(mid 80.591152 -266.549863)
		(end 80.308196 -266.473686)
		(width 0.0889)
		(layer "In13.Cu")
		(net "M_B_CPU1_SB_CS_N<1>")
	)
	(arc
		(start 86.887812 -266.473686)
		(mid 86.700868 -266.423431)
		(end 86.513924 -266.473686)
		(width 0.0889)
		(layer "In13.Cu")
		(net "M_B_CPU1_SB_CS_N<1>")
	)
	(arc
		(start 84.068158 -266.473686)
		(mid 83.885907 -266.423336)
		(end 83.702398 -266.46886)
		(width 0.0889)
		(layer "In13.Cu")
		(net "M_B_CPU1_SB_CS_N<1>")
	)
	(arc
		(start 85.007958 -266.473686)
		(mid 84.821014 -266.423431)
		(end 84.63407 -266.473686)
		(width 0.0889)
		(layer "In13.Cu")
		(net "M_B_CPU1_SB_CS_N<1>")
	)
	(arc
		(start 83.694016 -266.473686)
		(mid 83.41106 -266.549863)
		(end 83.128104 -266.473686)
		(width 0.0889)
		(layer "In13.Cu")
		(net "M_B_CPU1_SB_CS_N<1>")
	)
	(arc
		(start 82.179668 -266.46886)
		(mid 81.99616 -266.423366)
		(end 81.813908 -266.473686)
		(width 0.0889)
		(layer "In13.Cu")
		(net "M_B_CPU1_SB_CS_N<1>")
	)
	(arc
		(start 85.93963 -266.46886)
		(mid 85.756122 -266.423366)
		(end 85.57387 -266.473686)
		(width 0.0889)
		(layer "In13.Cu")
		(net "M_B_CPU1_SB_CS_N<1>")
	)
	(arc
		(start 80.308196 -266.473686)
		(mid 80.217936 -266.436058)
		(end 80.120998 -266.42314)
		(width 0.0889)
		(layer "In13.Cu")
		(net "M_B_CPU1_SB_CS_N<1>")
	)
	(arc
		(start 82.753962 -266.473686)
		(mid 82.471006 -266.549863)
		(end 82.18805 -266.473686)
		(width 0.0889)
		(layer "In13.Cu")
		(net "M_B_CPU1_SB_CS_N<1>")
	)
	(arc
		(start 83.128104 -266.473686)
		(mid 82.945853 -266.423336)
		(end 82.762344 -266.46886)
		(width 0.0889)
		(layer "In13.Cu")
		(net "M_B_CPU1_SB_CS_N<1>")
	)
	(arc
		(start 84.63407 -266.473686)
		(mid 84.351114 -266.549863)
		(end 84.068158 -266.473686)
		(width 0.0889)
		(layer "In13.Cu")
		(net "M_B_CPU1_SB_CS_N<1>")
	)
	(arc
		(start 87.390478 -266.505436)
		(mid 87.135413 -266.548787)
		(end 86.887812 -266.473686)
		(width 0.0889)
		(layer "In13.Cu")
		(net "M_B_CPU1_SB_CS_N<1>")
	)
	(segment
		(start 89.517982 -265.720322)
		(end 89.05113 -265.98626)
		(width 0.10668)
		(layer "F.Cu")
		(net "M_B_CPU1_SB_CS_N<0>")
	)
	(segment
		(start 54.303422 -267.460476)
		(end 54.54777 -267.460476)
		(width 0.14478)
		(layer "In13.Cu")
		(net "M_B_CPU1_SB_CS_N<0>")
	)
	(segment
		(start 55.10403 -267.148564)
		(end 55.415942 -267.460476)
		(width 0.14478)
		(layer "In13.Cu")
		(net "M_B_CPU1_SB_CS_N<0>")
	)
	(segment
		(start 51.884072 -267.738098)
		(end 52.473606 -267.148564)
		(width 0.14478)
		(layer "In13.Cu")
		(net "M_B_CPU1_SB_CS_N<0>")
	)
	(segment
		(start 61.521594 -265.529314)
		(end 76.119736 -265.529314)
		(width 0.14478)
		(layer "In13.Cu")
		(net "M_B_CPU1_SB_CS_N<0>")
	)
	(segment
		(start 51.884072 -267.885418)
		(end 51.884072 -267.738098)
		(width 0.14478)
		(layer "In13.Cu")
		(net "M_B_CPU1_SB_CS_N<0>")
	)
	(segment
		(start 85.10397 -265.66368)
		(end 85.112352 -265.658854)
		(width 0.0889)
		(layer "In13.Cu")
		(net "M_B_CPU1_SB_CS_N<0>")
	)
	(segment
		(start 57.640982 -267.460476)
		(end 57.88533 -267.460476)
		(width 0.14478)
		(layer "In13.Cu")
		(net "M_B_CPU1_SB_CS_N<0>")
	)
	(segment
		(start 58.44159 -267.148564)
		(end 58.921904 -267.628878)
		(width 0.14478)
		(layer "In13.Cu")
		(net "M_B_CPU1_SB_CS_N<0>")
	)
	(segment
		(start 58.921904 -267.628878)
		(end 59.42203 -267.628878)
		(width 0.14478)
		(layer "In13.Cu")
		(net "M_B_CPU1_SB_CS_N<0>")
	)
	(segment
		(start 54.54777 -267.460476)
		(end 54.859682 -267.148564)
		(width 0.14478)
		(layer "In13.Cu")
		(net "M_B_CPU1_SB_CS_N<0>")
	)
	(segment
		(start 88.800686 -265.69543)
		(end 88.896952 -265.72083)
		(width 0.0889)
		(layer "In13.Cu")
		(net "M_B_CPU1_SB_CS_N<0>")
	)
	(segment
		(start 55.66029 -267.460476)
		(end 55.972202 -267.148564)
		(width 0.14478)
		(layer "In13.Cu")
		(net "M_B_CPU1_SB_CS_N<0>")
	)
	(segment
		(start 53.99151 -267.148564)
		(end 54.303422 -267.460476)
		(width 0.14478)
		(layer "In13.Cu")
		(net "M_B_CPU1_SB_CS_N<0>")
	)
	(segment
		(start 82.284062 -265.66368)
		(end 82.292444 -265.658854)
		(width 0.0889)
		(layer "In13.Cu")
		(net "M_B_CPU1_SB_CS_N<0>")
	)
	(segment
		(start 57.88533 -267.460476)
		(end 58.197242 -267.148564)
		(width 0.14478)
		(layer "In13.Cu")
		(net "M_B_CPU1_SB_CS_N<0>")
	)
	(segment
		(start 53.43525 -267.460476)
		(end 53.747162 -267.148564)
		(width 0.14478)
		(layer "In13.Cu")
		(net "M_B_CPU1_SB_CS_N<0>")
	)
	(segment
		(start 84.529676 -265.658854)
		(end 84.538058 -265.66368)
		(width 0.0889)
		(layer "In13.Cu")
		(net "M_B_CPU1_SB_CS_N<0>")
	)
	(segment
		(start 57.084722 -267.148564)
		(end 57.32907 -267.148564)
		(width 0.14478)
		(layer "In13.Cu")
		(net "M_B_CPU1_SB_CS_N<0>")
	)
	(segment
		(start 52.473606 -267.148564)
		(end 52.87899 -267.148564)
		(width 0.14478)
		(layer "In13.Cu")
		(net "M_B_CPU1_SB_CS_N<0>")
	)
	(segment
		(start 86.984078 -265.66368)
		(end 86.99246 -265.658854)
		(width 0.0889)
		(layer "In13.Cu")
		(net "M_B_CPU1_SB_CS_N<0>")
	)
	(segment
		(start 81.344008 -265.66368)
		(end 81.35239 -265.658854)
		(width 0.0889)
		(layer "In13.Cu")
		(net "M_B_CPU1_SB_CS_N<0>")
	)
	(segment
		(start 80.389222 -265.672316)
		(end 80.403954 -265.66368)
		(width 0.0889)
		(layer "In13.Cu")
		(net "M_B_CPU1_SB_CS_N<0>")
	)
	(segment
		(start 55.972202 -267.148564)
		(end 56.21655 -267.148564)
		(width 0.14478)
		(layer "In13.Cu")
		(net "M_B_CPU1_SB_CS_N<0>")
	)
	(segment
		(start 55.415942 -267.460476)
		(end 55.66029 -267.460476)
		(width 0.14478)
		(layer "In13.Cu")
		(net "M_B_CPU1_SB_CS_N<0>")
	)
	(segment
		(start 88.896952 -265.72083)
		(end 89.05113 -265.98626)
		(width 0.0889)
		(layer "In13.Cu")
		(net "M_B_CPU1_SB_CS_N<0>")
	)
	(segment
		(start 80.769714 -265.658854)
		(end 80.778096 -265.66368)
		(width 0.0889)
		(layer "In13.Cu")
		(net "M_B_CPU1_SB_CS_N<0>")
	)
	(segment
		(start 56.77281 -267.460476)
		(end 57.084722 -267.148564)
		(width 0.14478)
		(layer "In13.Cu")
		(net "M_B_CPU1_SB_CS_N<0>")
	)
	(segment
		(start 53.747162 -267.148564)
		(end 53.99151 -267.148564)
		(width 0.14478)
		(layer "In13.Cu")
		(net "M_B_CPU1_SB_CS_N<0>")
	)
	(segment
		(start 53.190902 -267.460476)
		(end 53.43525 -267.460476)
		(width 0.14478)
		(layer "In13.Cu")
		(net "M_B_CPU1_SB_CS_N<0>")
	)
	(segment
		(start 76.119736 -265.529314)
		(end 79.340202 -265.529314)
		(width 0.0889)
		(layer "In13.Cu")
		(net "M_B_CPU1_SB_CS_N<0>")
	)
	(segment
		(start 54.859682 -267.148564)
		(end 55.10403 -267.148564)
		(width 0.14478)
		(layer "In13.Cu")
		(net "M_B_CPU1_SB_CS_N<0>")
	)
	(segment
		(start 57.32907 -267.148564)
		(end 57.640982 -267.460476)
		(width 0.14478)
		(layer "In13.Cu")
		(net "M_B_CPU1_SB_CS_N<0>")
	)
	(segment
		(start 58.197242 -267.148564)
		(end 58.44159 -267.148564)
		(width 0.14478)
		(layer "In13.Cu")
		(net "M_B_CPU1_SB_CS_N<0>")
	)
	(segment
		(start 56.21655 -267.148564)
		(end 56.528462 -267.460476)
		(width 0.14478)
		(layer "In13.Cu")
		(net "M_B_CPU1_SB_CS_N<0>")
	)
	(segment
		(start 56.528462 -267.460476)
		(end 56.77281 -267.460476)
		(width 0.14478)
		(layer "In13.Cu")
		(net "M_B_CPU1_SB_CS_N<0>")
	)
	(segment
		(start 59.42203 -267.628878)
		(end 61.521594 -265.529314)
		(width 0.14478)
		(layer "In13.Cu")
		(net "M_B_CPU1_SB_CS_N<0>")
	)
	(segment
		(start 52.87899 -267.148564)
		(end 53.190902 -267.460476)
		(width 0.14478)
		(layer "In13.Cu")
		(net "M_B_CPU1_SB_CS_N<0>")
	)
	(segment
		(start 86.044024 -265.66368)
		(end 86.052406 -265.658854)
		(width 0.0889)
		(layer "In13.Cu")
		(net "M_B_CPU1_SB_CS_N<0>")
	)
	(arc
		(start 87.35822 -265.66368)
		(mid 87.641176 -265.739857)
		(end 87.924132 -265.66368)
		(width 0.0889)
		(layer "In13.Cu")
		(net "M_B_CPU1_SB_CS_N<0>")
	)
	(arc
		(start 83.224116 -265.66368)
		(mid 83.41106 -265.613425)
		(end 83.598004 -265.66368)
		(width 0.0889)
		(layer "In13.Cu")
		(net "M_B_CPU1_SB_CS_N<0>")
	)
	(arc
		(start 87.924132 -265.66368)
		(mid 88.111076 -265.613425)
		(end 88.29802 -265.66368)
		(width 0.0889)
		(layer "In13.Cu")
		(net "M_B_CPU1_SB_CS_N<0>")
	)
	(arc
		(start 85.112352 -265.658854)
		(mid 85.29586 -265.61336)
		(end 85.478112 -265.66368)
		(width 0.0889)
		(layer "In13.Cu")
		(net "M_B_CPU1_SB_CS_N<0>")
	)
	(arc
		(start 81.35239 -265.658854)
		(mid 81.535898 -265.61336)
		(end 81.71815 -265.66368)
		(width 0.0889)
		(layer "In13.Cu")
		(net "M_B_CPU1_SB_CS_N<0>")
	)
	(arc
		(start 80.778096 -265.66368)
		(mid 81.061052 -265.739857)
		(end 81.344008 -265.66368)
		(width 0.0889)
		(layer "In13.Cu")
		(net "M_B_CPU1_SB_CS_N<0>")
	)
	(arc
		(start 88.29802 -265.66368)
		(mid 88.545616 -265.738858)
		(end 88.800686 -265.69543)
		(width 0.0889)
		(layer "In13.Cu")
		(net "M_B_CPU1_SB_CS_N<0>")
	)
	(arc
		(start 86.052406 -265.658854)
		(mid 86.235914 -265.61336)
		(end 86.418166 -265.66368)
		(width 0.0889)
		(layer "In13.Cu")
		(net "M_B_CPU1_SB_CS_N<0>")
	)
	(arc
		(start 82.658204 -265.66368)
		(mid 82.94116 -265.739857)
		(end 83.224116 -265.66368)
		(width 0.0889)
		(layer "In13.Cu")
		(net "M_B_CPU1_SB_CS_N<0>")
	)
	(arc
		(start 81.71815 -265.66368)
		(mid 82.001106 -265.739857)
		(end 82.284062 -265.66368)
		(width 0.0889)
		(layer "In13.Cu")
		(net "M_B_CPU1_SB_CS_N<0>")
	)
	(arc
		(start 84.538058 -265.66368)
		(mid 84.821014 -265.739857)
		(end 85.10397 -265.66368)
		(width 0.0889)
		(layer "In13.Cu")
		(net "M_B_CPU1_SB_CS_N<0>")
	)
	(arc
		(start 79.340202 -265.529314)
		(mid 79.597779 -265.563506)
		(end 79.837534 -265.66368)
		(width 0.0889)
		(layer "In13.Cu")
		(net "M_B_CPU1_SB_CS_N<0>")
	)
	(arc
		(start 84.163916 -265.66368)
		(mid 84.346167 -265.61333)
		(end 84.529676 -265.658854)
		(width 0.0889)
		(layer "In13.Cu")
		(net "M_B_CPU1_SB_CS_N<0>")
	)
	(arc
		(start 80.403954 -265.66368)
		(mid 80.586205 -265.61333)
		(end 80.769714 -265.658854)
		(width 0.0889)
		(layer "In13.Cu")
		(net "M_B_CPU1_SB_CS_N<0>")
	)
	(arc
		(start 82.292444 -265.658854)
		(mid 82.475952 -265.61336)
		(end 82.658204 -265.66368)
		(width 0.0889)
		(layer "In13.Cu")
		(net "M_B_CPU1_SB_CS_N<0>")
	)
	(arc
		(start 79.837534 -265.66368)
		(mid 80.11224 -265.740044)
		(end 80.389222 -265.672316)
		(width 0.0889)
		(layer "In13.Cu")
		(net "M_B_CPU1_SB_CS_N<0>")
	)
	(arc
		(start 86.418166 -265.66368)
		(mid 86.701122 -265.739857)
		(end 86.984078 -265.66368)
		(width 0.0889)
		(layer "In13.Cu")
		(net "M_B_CPU1_SB_CS_N<0>")
	)
	(arc
		(start 83.598004 -265.66368)
		(mid 83.88096 -265.739857)
		(end 84.163916 -265.66368)
		(width 0.0889)
		(layer "In13.Cu")
		(net "M_B_CPU1_SB_CS_N<0>")
	)
	(arc
		(start 85.478112 -265.66368)
		(mid 85.761068 -265.739857)
		(end 86.044024 -265.66368)
		(width 0.0889)
		(layer "In13.Cu")
		(net "M_B_CPU1_SB_CS_N<0>")
	)
	(arc
		(start 86.99246 -265.658854)
		(mid 87.175968 -265.61336)
		(end 87.35822 -265.66368)
		(width 0.0889)
		(layer "In13.Cu")
		(net "M_B_CPU1_SB_CS_N<0>")
	)
	(segment
		(start 89.517982 -270.580358)
		(end 89.05113 -270.846296)
		(width 0.10668)
		(layer "F.Cu")
		(net "M_B_CPU1_SB_CB<7>")
	)
	(segment
		(start 83.589622 -270.51889)
		(end 83.598004 -270.523716)
		(width 0.0889)
		(layer "In13.Cu")
		(net "M_B_CPU1_SB_CB<7>")
	)
	(segment
		(start 84.529676 -270.51889)
		(end 84.538058 -270.523716)
		(width 0.0889)
		(layer "In13.Cu")
		(net "M_B_CPU1_SB_CB<7>")
	)
	(segment
		(start 54.89702 -273.410426)
		(end 55.616856 -273.410426)
		(width 0.14478)
		(layer "In13.Cu")
		(net "M_B_CPU1_SB_CB<7>")
	)
	(segment
		(start 77.00391 -269.127986)
		(end 77.988668 -270.112744)
		(width 0.0889)
		(layer "In13.Cu")
		(net "M_B_CPU1_SB_CB<7>")
	)
	(segment
		(start 51.306222 -274.261326)
		(end 51.572922 -274.528026)
		(width 0.14478)
		(layer "In13.Cu")
		(net "M_B_CPU1_SB_CB<7>")
	)
	(segment
		(start 55.616856 -273.410426)
		(end 56.28005 -274.07362)
		(width 0.14478)
		(layer "In13.Cu")
		(net "M_B_CPU1_SB_CB<7>")
	)
	(segment
		(start 86.044024 -270.523716)
		(end 86.052406 -270.51889)
		(width 0.0889)
		(layer "In13.Cu")
		(net "M_B_CPU1_SB_CB<7>")
	)
	(segment
		(start 56.28005 -274.07362)
		(end 59.186318 -274.07362)
		(width 0.14478)
		(layer "In13.Cu")
		(net "M_B_CPU1_SB_CB<7>")
	)
	(segment
		(start 81.344008 -270.523716)
		(end 81.35239 -270.51889)
		(width 0.0889)
		(layer "In13.Cu")
		(net "M_B_CPU1_SB_CB<7>")
	)
	(segment
		(start 51.572922 -274.528026)
		(end 53.77942 -274.528026)
		(width 0.14478)
		(layer "In13.Cu")
		(net "M_B_CPU1_SB_CB<7>")
	)
	(segment
		(start 80.769714 -270.51889)
		(end 80.778096 -270.523716)
		(width 0.0889)
		(layer "In13.Cu")
		(net "M_B_CPU1_SB_CB<7>")
	)
	(segment
		(start 80.389222 -270.532352)
		(end 80.403954 -270.523716)
		(width 0.0889)
		(layer "In13.Cu")
		(net "M_B_CPU1_SB_CB<7>")
	)
	(segment
		(start 47.784004 -274.685252)
		(end 48.20793 -274.261326)
		(width 0.14478)
		(layer "In13.Cu")
		(net "M_B_CPU1_SB_CB<7>")
	)
	(segment
		(start 89.182702 -270.497554)
		(end 89.205054 -270.580866)
		(width 0.0889)
		(layer "In13.Cu")
		(net "M_B_CPU1_SB_CB<7>")
	)
	(segment
		(start 48.20793 -274.261326)
		(end 51.306222 -274.261326)
		(width 0.14478)
		(layer "In13.Cu")
		(net "M_B_CPU1_SB_CB<7>")
	)
	(segment
		(start 85.10397 -270.523716)
		(end 85.112352 -270.51889)
		(width 0.0889)
		(layer "In13.Cu")
		(net "M_B_CPU1_SB_CB<7>")
	)
	(segment
		(start 59.186318 -274.07362)
		(end 64.299084 -268.960854)
		(width 0.14478)
		(layer "In13.Cu")
		(net "M_B_CPU1_SB_CB<7>")
	)
	(segment
		(start 75.934824 -268.960854)
		(end 76.283058 -268.960854)
		(width 0.0889)
		(layer "In13.Cu")
		(net "M_B_CPU1_SB_CB<7>")
	)
	(segment
		(start 76.283058 -268.960854)
		(end 76.45019 -269.127986)
		(width 0.0889)
		(layer "In13.Cu")
		(net "M_B_CPU1_SB_CB<7>")
	)
	(segment
		(start 88.289638 -270.51889)
		(end 88.29802 -270.523716)
		(width 0.0889)
		(layer "In13.Cu")
		(net "M_B_CPU1_SB_CB<7>")
	)
	(segment
		(start 53.77942 -274.528026)
		(end 54.89702 -273.410426)
		(width 0.14478)
		(layer "In13.Cu")
		(net "M_B_CPU1_SB_CB<7>")
	)
	(segment
		(start 89.205054 -270.580866)
		(end 89.05113 -270.846296)
		(width 0.0889)
		(layer "In13.Cu")
		(net "M_B_CPU1_SB_CB<7>")
	)
	(segment
		(start 76.45019 -269.127986)
		(end 77.00391 -269.127986)
		(width 0.0889)
		(layer "In13.Cu")
		(net "M_B_CPU1_SB_CB<7>")
	)
	(segment
		(start 78.689708 -270.403066)
		(end 79.391002 -270.403066)
		(width 0.0889)
		(layer "In13.Cu")
		(net "M_B_CPU1_SB_CB<7>")
	)
	(segment
		(start 64.299084 -268.960854)
		(end 75.934824 -268.960854)
		(width 0.14478)
		(layer "In13.Cu")
		(net "M_B_CPU1_SB_CB<7>")
	)
	(arc
		(start 87.357966 -270.523716)
		(mid 87.640922 -270.599893)
		(end 87.923878 -270.523716)
		(width 0.0889)
		(layer "In13.Cu")
		(net "M_B_CPU1_SB_CB<7>")
	)
	(arc
		(start 79.391002 -270.403066)
		(mid 79.622271 -270.433766)
		(end 79.837534 -270.523716)
		(width 0.0889)
		(layer "In13.Cu")
		(net "M_B_CPU1_SB_CB<7>")
	)
	(arc
		(start 84.538058 -270.523716)
		(mid 84.821014 -270.599893)
		(end 85.10397 -270.523716)
		(width 0.0889)
		(layer "In13.Cu")
		(net "M_B_CPU1_SB_CB<7>")
	)
	(arc
		(start 82.284062 -270.523716)
		(mid 82.471006 -270.473461)
		(end 82.65795 -270.523716)
		(width 0.0889)
		(layer "In13.Cu")
		(net "M_B_CPU1_SB_CB<7>")
	)
	(arc
		(start 86.418166 -270.523716)
		(mid 86.701122 -270.599893)
		(end 86.984078 -270.523716)
		(width 0.0889)
		(layer "In13.Cu")
		(net "M_B_CPU1_SB_CB<7>")
	)
	(arc
		(start 83.598004 -270.523716)
		(mid 83.88096 -270.599893)
		(end 84.163916 -270.523716)
		(width 0.0889)
		(layer "In13.Cu")
		(net "M_B_CPU1_SB_CB<7>")
	)
	(arc
		(start 88.863932 -270.523716)
		(mid 89.02037 -270.474745)
		(end 89.182702 -270.497554)
		(width 0.0889)
		(layer "In13.Cu")
		(net "M_B_CPU1_SB_CB<7>")
	)
	(arc
		(start 81.35239 -270.51889)
		(mid 81.535898 -270.473396)
		(end 81.71815 -270.523716)
		(width 0.0889)
		(layer "In13.Cu")
		(net "M_B_CPU1_SB_CB<7>")
	)
	(arc
		(start 88.29802 -270.523716)
		(mid 88.580976 -270.599893)
		(end 88.863932 -270.523716)
		(width 0.0889)
		(layer "In13.Cu")
		(net "M_B_CPU1_SB_CB<7>")
	)
	(arc
		(start 85.112352 -270.51889)
		(mid 85.29586 -270.473396)
		(end 85.478112 -270.523716)
		(width 0.0889)
		(layer "In13.Cu")
		(net "M_B_CPU1_SB_CB<7>")
	)
	(arc
		(start 85.478112 -270.523716)
		(mid 85.761068 -270.599893)
		(end 86.044024 -270.523716)
		(width 0.0889)
		(layer "In13.Cu")
		(net "M_B_CPU1_SB_CB<7>")
	)
	(arc
		(start 86.984078 -270.523716)
		(mid 87.171022 -270.473461)
		(end 87.357966 -270.523716)
		(width 0.0889)
		(layer "In13.Cu")
		(net "M_B_CPU1_SB_CB<7>")
	)
	(arc
		(start 80.778096 -270.523716)
		(mid 81.061052 -270.599893)
		(end 81.344008 -270.523716)
		(width 0.0889)
		(layer "In13.Cu")
		(net "M_B_CPU1_SB_CB<7>")
	)
	(arc
		(start 80.403954 -270.523716)
		(mid 80.586205 -270.473366)
		(end 80.769714 -270.51889)
		(width 0.0889)
		(layer "In13.Cu")
		(net "M_B_CPU1_SB_CB<7>")
	)
	(arc
		(start 77.988668 -270.112744)
		(mid 78.310322 -270.327603)
		(end 78.689708 -270.403066)
		(width 0.0889)
		(layer "In13.Cu")
		(net "M_B_CPU1_SB_CB<7>")
	)
	(arc
		(start 86.052406 -270.51889)
		(mid 86.235914 -270.473396)
		(end 86.418166 -270.523716)
		(width 0.0889)
		(layer "In13.Cu")
		(net "M_B_CPU1_SB_CB<7>")
	)
	(arc
		(start 87.923878 -270.523716)
		(mid 88.106129 -270.473366)
		(end 88.289638 -270.51889)
		(width 0.0889)
		(layer "In13.Cu")
		(net "M_B_CPU1_SB_CB<7>")
	)
	(arc
		(start 83.223862 -270.523716)
		(mid 83.406113 -270.473366)
		(end 83.589622 -270.51889)
		(width 0.0889)
		(layer "In13.Cu")
		(net "M_B_CPU1_SB_CB<7>")
	)
	(arc
		(start 82.65795 -270.523716)
		(mid 82.940906 -270.599893)
		(end 83.223862 -270.523716)
		(width 0.0889)
		(layer "In13.Cu")
		(net "M_B_CPU1_SB_CB<7>")
	)
	(arc
		(start 79.837534 -270.523716)
		(mid 80.11224 -270.60008)
		(end 80.389222 -270.532352)
		(width 0.0889)
		(layer "In13.Cu")
		(net "M_B_CPU1_SB_CB<7>")
	)
	(arc
		(start 84.163916 -270.523716)
		(mid 84.346167 -270.473366)
		(end 84.529676 -270.51889)
		(width 0.0889)
		(layer "In13.Cu")
		(net "M_B_CPU1_SB_CB<7>")
	)
	(arc
		(start 81.71815 -270.523716)
		(mid 82.001106 -270.599893)
		(end 82.284062 -270.523716)
		(width 0.0889)
		(layer "In13.Cu")
		(net "M_B_CPU1_SB_CB<7>")
	)
	(segment
		(start 88.107774 -269.770352)
		(end 87.640922 -270.03629)
		(width 0.10668)
		(layer "F.Cu")
		(net "M_B_CPU1_SB_CB<6>")
	)
	(segment
		(start 50.966116 -272.98523)
		(end 51.391058 -272.560288)
		(width 0.14478)
		(layer "In13.Cu")
		(net "M_B_CPU1_SB_CB<6>")
	)
	(segment
		(start 49.530762 -272.228056)
		(end 49.530762 -272.84045)
		(width 0.14478)
		(layer "In13.Cu")
		(net "M_B_CPU1_SB_CB<6>")
	)
	(segment
		(start 87.7951 -269.77086)
		(end 87.640922 -270.03629)
		(width 0.0889)
		(layer "In13.Cu")
		(net "M_B_CPU1_SB_CB<6>")
	)
	(segment
		(start 79.934054 -269.71371)
		(end 79.942436 -269.708884)
		(width 0.0889)
		(layer "In13.Cu")
		(net "M_B_CPU1_SB_CB<6>")
	)
	(segment
		(start 77.238606 -268.551406)
		(end 78.312264 -269.625064)
		(width 0.0889)
		(layer "In13.Cu")
		(net "M_B_CPU1_SB_CB<6>")
	)
	(segment
		(start 63.936372 -268.051534)
		(end 75.974956 -268.051534)
		(width 0.14478)
		(layer "In13.Cu")
		(net "M_B_CPU1_SB_CB<6>")
	)
	(segment
		(start 51.391058 -272.560288)
		(end 53.373528 -272.560288)
		(width 0.14478)
		(layer "In13.Cu")
		(net "M_B_CPU1_SB_CB<6>")
	)
	(segment
		(start 53.373528 -272.560288)
		(end 54.223412 -271.710404)
		(width 0.14478)
		(layer "In13.Cu")
		(net "M_B_CPU1_SB_CB<6>")
	)
	(segment
		(start 82.179668 -269.708884)
		(end 82.18805 -269.71371)
		(width 0.0889)
		(layer "In13.Cu")
		(net "M_B_CPU1_SB_CB<6>")
	)
	(segment
		(start 76.95057 -268.551406)
		(end 77.238606 -268.551406)
		(width 0.0889)
		(layer "In13.Cu")
		(net "M_B_CPU1_SB_CB<6>")
	)
	(segment
		(start 87.772748 -269.687548)
		(end 87.7951 -269.77086)
		(width 0.0889)
		(layer "In13.Cu")
		(net "M_B_CPU1_SB_CB<6>")
	)
	(segment
		(start 78.977744 -269.723108)
		(end 78.993492 -269.713964)
		(width 0.0889)
		(layer "In13.Cu")
		(net "M_B_CPU1_SB_CB<6>")
	)
	(segment
		(start 76.450698 -268.051534)
		(end 76.95057 -268.551406)
		(width 0.0889)
		(layer "In13.Cu")
		(net "M_B_CPU1_SB_CB<6>")
	)
	(segment
		(start 78.993492 -269.713964)
		(end 79.01178 -269.70355)
		(width 0.0889)
		(layer "In13.Cu")
		(net "M_B_CPU1_SB_CB<6>")
	)
	(segment
		(start 54.223412 -271.710404)
		(end 60.277502 -271.710404)
		(width 0.14478)
		(layer "In13.Cu")
		(net "M_B_CPU1_SB_CB<6>")
	)
	(segment
		(start 48.834802 -272.98523)
		(end 48.979582 -272.84045)
		(width 0.14478)
		(layer "In13.Cu")
		(net "M_B_CPU1_SB_CB<6>")
	)
	(segment
		(start 49.530762 -272.84045)
		(end 49.675542 -272.98523)
		(width 0.14478)
		(layer "In13.Cu")
		(net "M_B_CPU1_SB_CB<6>")
	)
	(segment
		(start 48.979582 -272.84045)
		(end 48.979582 -272.228056)
		(width 0.14478)
		(layer "In13.Cu")
		(net "M_B_CPU1_SB_CB<6>")
	)
	(segment
		(start 83.694016 -269.71371)
		(end 83.702398 -269.708884)
		(width 0.0889)
		(layer "In13.Cu")
		(net "M_B_CPU1_SB_CB<6>")
	)
	(segment
		(start 85.93963 -269.708884)
		(end 85.948012 -269.71371)
		(width 0.0889)
		(layer "In13.Cu")
		(net "M_B_CPU1_SB_CB<6>")
	)
	(segment
		(start 79.919322 -269.722346)
		(end 79.934054 -269.71371)
		(width 0.0889)
		(layer "In13.Cu")
		(net "M_B_CPU1_SB_CB<6>")
	)
	(segment
		(start 49.124362 -272.083276)
		(end 49.385982 -272.083276)
		(width 0.14478)
		(layer "In13.Cu")
		(net "M_B_CPU1_SB_CB<6>")
	)
	(segment
		(start 86.879684 -269.708884)
		(end 86.888066 -269.71371)
		(width 0.0889)
		(layer "In13.Cu")
		(net "M_B_CPU1_SB_CB<6>")
	)
	(segment
		(start 82.753962 -269.71371)
		(end 82.762344 -269.708884)
		(width 0.0889)
		(layer "In13.Cu")
		(net "M_B_CPU1_SB_CB<6>")
	)
	(segment
		(start 47.784004 -272.98523)
		(end 48.834802 -272.98523)
		(width 0.14478)
		(layer "In13.Cu")
		(net "M_B_CPU1_SB_CB<6>")
	)
	(segment
		(start 60.277502 -271.710404)
		(end 63.936372 -268.051534)
		(width 0.14478)
		(layer "In13.Cu")
		(net "M_B_CPU1_SB_CB<6>")
	)
	(segment
		(start 85.948012 -269.71371)
		(end 85.948266 -269.71371)
		(width 0.0889)
		(layer "In13.Cu")
		(net "M_B_CPU1_SB_CB<6>")
	)
	(segment
		(start 48.979582 -272.228056)
		(end 49.124362 -272.083276)
		(width 0.14478)
		(layer "In13.Cu")
		(net "M_B_CPU1_SB_CB<6>")
	)
	(segment
		(start 49.675542 -272.98523)
		(end 50.966116 -272.98523)
		(width 0.14478)
		(layer "In13.Cu")
		(net "M_B_CPU1_SB_CB<6>")
	)
	(segment
		(start 87.453978 -269.71371)
		(end 87.46236 -269.708884)
		(width 0.0889)
		(layer "In13.Cu")
		(net "M_B_CPU1_SB_CB<6>")
	)
	(segment
		(start 75.974956 -268.051534)
		(end 76.450698 -268.051534)
		(width 0.0889)
		(layer "In13.Cu")
		(net "M_B_CPU1_SB_CB<6>")
	)
	(segment
		(start 49.385982 -272.083276)
		(end 49.530762 -272.228056)
		(width 0.14478)
		(layer "In13.Cu")
		(net "M_B_CPU1_SB_CB<6>")
	)
	(arc
		(start 87.46236 -269.708884)
		(mid 87.61523 -269.664243)
		(end 87.772748 -269.687548)
		(width 0.0889)
		(layer "In13.Cu")
		(net "M_B_CPU1_SB_CB<6>")
	)
	(arc
		(start 78.312264 -269.625064)
		(mid 78.367049 -269.673124)
		(end 78.42758 -269.71371)
		(width 0.0889)
		(layer "In13.Cu")
		(net "M_B_CPU1_SB_CB<6>")
	)
	(arc
		(start 79.01178 -269.70355)
		(mid 79.191009 -269.663397)
		(end 79.367634 -269.71371)
		(width 0.0889)
		(layer "In13.Cu")
		(net "M_B_CPU1_SB_CB<6>")
	)
	(arc
		(start 81.813908 -269.71371)
		(mid 81.996159 -269.66336)
		(end 82.179668 -269.708884)
		(width 0.0889)
		(layer "In13.Cu")
		(net "M_B_CPU1_SB_CB<6>")
	)
	(arc
		(start 80.874108 -269.71371)
		(mid 81.061052 -269.663455)
		(end 81.247996 -269.71371)
		(width 0.0889)
		(layer "In13.Cu")
		(net "M_B_CPU1_SB_CB<6>")
	)
	(arc
		(start 79.942436 -269.708884)
		(mid 80.125944 -269.66339)
		(end 80.308196 -269.71371)
		(width 0.0889)
		(layer "In13.Cu")
		(net "M_B_CPU1_SB_CB<6>")
	)
	(arc
		(start 78.42758 -269.71371)
		(mid 78.701435 -269.79006)
		(end 78.977744 -269.723108)
		(width 0.0889)
		(layer "In13.Cu")
		(net "M_B_CPU1_SB_CB<6>")
	)
	(arc
		(start 84.63407 -269.71371)
		(mid 84.821014 -269.663455)
		(end 85.007958 -269.71371)
		(width 0.0889)
		(layer "In13.Cu")
		(net "M_B_CPU1_SB_CB<6>")
	)
	(arc
		(start 82.762344 -269.708884)
		(mid 82.945852 -269.66339)
		(end 83.128104 -269.71371)
		(width 0.0889)
		(layer "In13.Cu")
		(net "M_B_CPU1_SB_CB<6>")
	)
	(arc
		(start 79.367634 -269.71371)
		(mid 79.64234 -269.790074)
		(end 79.919322 -269.722346)
		(width 0.0889)
		(layer "In13.Cu")
		(net "M_B_CPU1_SB_CB<6>")
	)
	(arc
		(start 85.948266 -269.71371)
		(mid 86.231112 -269.789887)
		(end 86.513924 -269.71371)
		(width 0.0889)
		(layer "In13.Cu")
		(net "M_B_CPU1_SB_CB<6>")
	)
	(arc
		(start 86.513924 -269.71371)
		(mid 86.696175 -269.66336)
		(end 86.879684 -269.708884)
		(width 0.0889)
		(layer "In13.Cu")
		(net "M_B_CPU1_SB_CB<6>")
	)
	(arc
		(start 81.247996 -269.71371)
		(mid 81.530952 -269.789887)
		(end 81.813908 -269.71371)
		(width 0.0889)
		(layer "In13.Cu")
		(net "M_B_CPU1_SB_CB<6>")
	)
	(arc
		(start 85.007958 -269.71371)
		(mid 85.290914 -269.789887)
		(end 85.57387 -269.71371)
		(width 0.0889)
		(layer "In13.Cu")
		(net "M_B_CPU1_SB_CB<6>")
	)
	(arc
		(start 85.57387 -269.71371)
		(mid 85.756121 -269.66336)
		(end 85.93963 -269.708884)
		(width 0.0889)
		(layer "In13.Cu")
		(net "M_B_CPU1_SB_CB<6>")
	)
	(arc
		(start 83.128104 -269.71371)
		(mid 83.41106 -269.789887)
		(end 83.694016 -269.71371)
		(width 0.0889)
		(layer "In13.Cu")
		(net "M_B_CPU1_SB_CB<6>")
	)
	(arc
		(start 80.308196 -269.71371)
		(mid 80.591152 -269.789887)
		(end 80.874108 -269.71371)
		(width 0.0889)
		(layer "In13.Cu")
		(net "M_B_CPU1_SB_CB<6>")
	)
	(arc
		(start 82.18805 -269.71371)
		(mid 82.471006 -269.789887)
		(end 82.753962 -269.71371)
		(width 0.0889)
		(layer "In13.Cu")
		(net "M_B_CPU1_SB_CB<6>")
	)
	(arc
		(start 83.702398 -269.708884)
		(mid 83.885906 -269.66339)
		(end 84.068158 -269.71371)
		(width 0.0889)
		(layer "In13.Cu")
		(net "M_B_CPU1_SB_CB<6>")
	)
	(arc
		(start 86.888066 -269.71371)
		(mid 87.171022 -269.789887)
		(end 87.453978 -269.71371)
		(width 0.0889)
		(layer "In13.Cu")
		(net "M_B_CPU1_SB_CB<6>")
	)
	(arc
		(start 84.068158 -269.71371)
		(mid 84.351114 -269.789887)
		(end 84.63407 -269.71371)
		(width 0.0889)
		(layer "In13.Cu")
		(net "M_B_CPU1_SB_CB<6>")
	)
	(segment
		(start 89.987882 -269.770352)
		(end 89.52103 -270.03629)
		(width 0.10668)
		(layer "F.Cu")
		(net "M_B_CPU1_SB_CB<5>")
	)
	(segment
		(start 89.367106 -270.30172)
		(end 89.52103 -270.03629)
		(width 0.0889)
		(layer "In13.Cu")
		(net "M_B_CPU1_SB_CB<5>")
	)
	(segment
		(start 57.720738 -273.4056)
		(end 57.982358 -273.4056)
		(width 0.14478)
		(layer "In13.Cu")
		(net "M_B_CPU1_SB_CB<5>")
	)
	(segment
		(start 82.179668 -270.363696)
		(end 82.18805 -270.35887)
		(width 0.0889)
		(layer "In13.Cu")
		(net "M_B_CPU1_SB_CB<5>")
	)
	(segment
		(start 58.271918 -272.216118)
		(end 60.407804 -272.216118)
		(width 0.14478)
		(layer "In13.Cu")
		(net "M_B_CPU1_SB_CB<5>")
	)
	(segment
		(start 56.618378 -273.4056)
		(end 56.879998 -273.4056)
		(width 0.14478)
		(layer "In13.Cu")
		(net "M_B_CPU1_SB_CB<5>")
	)
	(segment
		(start 60.407804 -272.216118)
		(end 64.117728 -268.506194)
		(width 0.14478)
		(layer "In13.Cu")
		(net "M_B_CPU1_SB_CB<5>")
	)
	(segment
		(start 83.694016 -270.35887)
		(end 83.702398 -270.363696)
		(width 0.0889)
		(layer "In13.Cu")
		(net "M_B_CPU1_SB_CB<5>")
	)
	(segment
		(start 57.169558 -272.216118)
		(end 57.431178 -272.216118)
		(width 0.14478)
		(layer "In13.Cu")
		(net "M_B_CPU1_SB_CB<5>")
	)
	(segment
		(start 58.127138 -272.360898)
		(end 58.271918 -272.216118)
		(width 0.14478)
		(layer "In13.Cu")
		(net "M_B_CPU1_SB_CB<5>")
	)
	(segment
		(start 87.453978 -270.35887)
		(end 87.46236 -270.363696)
		(width 0.0889)
		(layer "In13.Cu")
		(net "M_B_CPU1_SB_CB<5>")
	)
	(segment
		(start 85.93963 -270.363696)
		(end 85.948012 -270.35887)
		(width 0.0889)
		(layer "In13.Cu")
		(net "M_B_CPU1_SB_CB<5>")
	)
	(segment
		(start 57.982358 -273.4056)
		(end 58.127138 -273.26082)
		(width 0.14478)
		(layer "In13.Cu")
		(net "M_B_CPU1_SB_CB<5>")
	)
	(segment
		(start 75.947016 -268.506194)
		(end 76.300838 -268.506194)
		(width 0.0889)
		(layer "In13.Cu")
		(net "M_B_CPU1_SB_CB<5>")
	)
	(segment
		(start 51.884072 -273.835368)
		(end 53.22443 -273.835368)
		(width 0.14478)
		(layer "In13.Cu")
		(net "M_B_CPU1_SB_CB<5>")
	)
	(segment
		(start 78.737714 -270.156686)
		(end 79.183738 -270.156686)
		(width 0.0889)
		(layer "In13.Cu")
		(net "M_B_CPU1_SB_CB<5>")
	)
	(segment
		(start 53.22443 -273.835368)
		(end 54.49951 -272.560288)
		(width 0.14478)
		(layer "In13.Cu")
		(net "M_B_CPU1_SB_CB<5>")
	)
	(segment
		(start 56.328818 -272.216118)
		(end 56.473598 -272.360898)
		(width 0.14478)
		(layer "In13.Cu")
		(net "M_B_CPU1_SB_CB<5>")
	)
	(segment
		(start 57.431178 -272.216118)
		(end 57.575958 -272.360898)
		(width 0.14478)
		(layer "In13.Cu")
		(net "M_B_CPU1_SB_CB<5>")
	)
	(segment
		(start 55.937912 -272.216118)
		(end 56.328818 -272.216118)
		(width 0.14478)
		(layer "In13.Cu")
		(net "M_B_CPU1_SB_CB<5>")
	)
	(segment
		(start 56.473598 -273.26082)
		(end 56.618378 -273.4056)
		(width 0.14478)
		(layer "In13.Cu")
		(net "M_B_CPU1_SB_CB<5>")
	)
	(segment
		(start 76.60259 -268.807946)
		(end 77.02423 -268.807946)
		(width 0.0889)
		(layer "In13.Cu")
		(net "M_B_CPU1_SB_CB<5>")
	)
	(segment
		(start 76.300838 -268.506194)
		(end 76.60259 -268.807946)
		(width 0.0889)
		(layer "In13.Cu")
		(net "M_B_CPU1_SB_CB<5>")
	)
	(segment
		(start 57.024778 -272.360898)
		(end 57.169558 -272.216118)
		(width 0.14478)
		(layer "In13.Cu")
		(net "M_B_CPU1_SB_CB<5>")
	)
	(segment
		(start 77.02423 -268.807946)
		(end 78.114906 -269.898622)
		(width 0.0889)
		(layer "In13.Cu")
		(net "M_B_CPU1_SB_CB<5>")
	)
	(segment
		(start 82.753962 -270.35887)
		(end 82.762344 -270.363696)
		(width 0.0889)
		(layer "In13.Cu")
		(net "M_B_CPU1_SB_CB<5>")
	)
	(segment
		(start 80.299814 -270.363696)
		(end 80.308196 -270.35887)
		(width 0.0889)
		(layer "In13.Cu")
		(net "M_B_CPU1_SB_CB<5>")
	)
	(segment
		(start 57.575958 -272.360898)
		(end 57.575958 -273.26082)
		(width 0.14478)
		(layer "In13.Cu")
		(net "M_B_CPU1_SB_CB<5>")
	)
	(segment
		(start 56.473598 -272.360898)
		(end 56.473598 -273.26082)
		(width 0.14478)
		(layer "In13.Cu")
		(net "M_B_CPU1_SB_CB<5>")
	)
	(segment
		(start 58.127138 -273.26082)
		(end 58.127138 -272.360898)
		(width 0.14478)
		(layer "In13.Cu")
		(net "M_B_CPU1_SB_CB<5>")
	)
	(segment
		(start 88.394032 -270.35887)
		(end 88.402414 -270.363696)
		(width 0.0889)
		(layer "In13.Cu")
		(net "M_B_CPU1_SB_CB<5>")
	)
	(segment
		(start 57.024778 -273.26082)
		(end 57.024778 -272.360898)
		(width 0.14478)
		(layer "In13.Cu")
		(net "M_B_CPU1_SB_CB<5>")
	)
	(segment
		(start 89.271094 -270.32712)
		(end 89.367106 -270.30172)
		(width 0.0889)
		(layer "In13.Cu")
		(net "M_B_CPU1_SB_CB<5>")
	)
	(segment
		(start 55.593742 -272.560288)
		(end 55.937912 -272.216118)
		(width 0.14478)
		(layer "In13.Cu")
		(net "M_B_CPU1_SB_CB<5>")
	)
	(segment
		(start 86.879684 -270.363696)
		(end 86.888066 -270.35887)
		(width 0.0889)
		(layer "In13.Cu")
		(net "M_B_CPU1_SB_CB<5>")
	)
	(segment
		(start 85.948012 -270.35887)
		(end 85.948266 -270.35887)
		(width 0.0889)
		(layer "In13.Cu")
		(net "M_B_CPU1_SB_CB<5>")
	)
	(segment
		(start 56.879998 -273.4056)
		(end 57.024778 -273.26082)
		(width 0.14478)
		(layer "In13.Cu")
		(net "M_B_CPU1_SB_CB<5>")
	)
	(segment
		(start 54.49951 -272.560288)
		(end 55.593742 -272.560288)
		(width 0.14478)
		(layer "In13.Cu")
		(net "M_B_CPU1_SB_CB<5>")
	)
	(segment
		(start 57.575958 -273.26082)
		(end 57.720738 -273.4056)
		(width 0.14478)
		(layer "In13.Cu")
		(net "M_B_CPU1_SB_CB<5>")
	)
	(segment
		(start 64.117728 -268.506194)
		(end 75.947016 -268.506194)
		(width 0.14478)
		(layer "In13.Cu")
		(net "M_B_CPU1_SB_CB<5>")
	)
	(arc
		(start 82.18805 -270.35887)
		(mid 82.471006 -270.282693)
		(end 82.753962 -270.35887)
		(width 0.0889)
		(layer "In13.Cu")
		(net "M_B_CPU1_SB_CB<5>")
	)
	(arc
		(start 81.247996 -270.35887)
		(mid 81.530952 -270.282693)
		(end 81.813908 -270.35887)
		(width 0.0889)
		(layer "In13.Cu")
		(net "M_B_CPU1_SB_CB<5>")
	)
	(arc
		(start 84.63407 -270.35887)
		(mid 84.821014 -270.409125)
		(end 85.007958 -270.35887)
		(width 0.0889)
		(layer "In13.Cu")
		(net "M_B_CPU1_SB_CB<5>")
	)
	(arc
		(start 80.874108 -270.35887)
		(mid 81.061052 -270.409125)
		(end 81.247996 -270.35887)
		(width 0.0889)
		(layer "In13.Cu")
		(net "M_B_CPU1_SB_CB<5>")
	)
	(arc
		(start 85.57387 -270.35887)
		(mid 85.756121 -270.40922)
		(end 85.93963 -270.363696)
		(width 0.0889)
		(layer "In13.Cu")
		(net "M_B_CPU1_SB_CB<5>")
	)
	(arc
		(start 88.768174 -270.35887)
		(mid 89.015887 -270.28365)
		(end 89.271094 -270.32712)
		(width 0.0889)
		(layer "In13.Cu")
		(net "M_B_CPU1_SB_CB<5>")
	)
	(arc
		(start 83.128104 -270.35887)
		(mid 83.41106 -270.282693)
		(end 83.694016 -270.35887)
		(width 0.0889)
		(layer "In13.Cu")
		(net "M_B_CPU1_SB_CB<5>")
	)
	(arc
		(start 83.702398 -270.363696)
		(mid 83.885906 -270.40919)
		(end 84.068158 -270.35887)
		(width 0.0889)
		(layer "In13.Cu")
		(net "M_B_CPU1_SB_CB<5>")
	)
	(arc
		(start 79.933546 -270.35887)
		(mid 80.116051 -270.409347)
		(end 80.299814 -270.363696)
		(width 0.0889)
		(layer "In13.Cu")
		(net "M_B_CPU1_SB_CB<5>")
	)
	(arc
		(start 84.068158 -270.35887)
		(mid 84.351114 -270.282693)
		(end 84.63407 -270.35887)
		(width 0.0889)
		(layer "In13.Cu")
		(net "M_B_CPU1_SB_CB<5>")
	)
	(arc
		(start 85.007958 -270.35887)
		(mid 85.290914 -270.282693)
		(end 85.57387 -270.35887)
		(width 0.0889)
		(layer "In13.Cu")
		(net "M_B_CPU1_SB_CB<5>")
	)
	(arc
		(start 81.813908 -270.35887)
		(mid 81.996159 -270.40922)
		(end 82.179668 -270.363696)
		(width 0.0889)
		(layer "In13.Cu")
		(net "M_B_CPU1_SB_CB<5>")
	)
	(arc
		(start 78.114906 -269.898622)
		(mid 78.400638 -270.089606)
		(end 78.737714 -270.156686)
		(width 0.0889)
		(layer "In13.Cu")
		(net "M_B_CPU1_SB_CB<5>")
	)
	(arc
		(start 79.183738 -270.156686)
		(mid 79.572029 -270.208125)
		(end 79.933546 -270.35887)
		(width 0.0889)
		(layer "In13.Cu")
		(net "M_B_CPU1_SB_CB<5>")
	)
	(arc
		(start 82.762344 -270.363696)
		(mid 82.945852 -270.40919)
		(end 83.128104 -270.35887)
		(width 0.0889)
		(layer "In13.Cu")
		(net "M_B_CPU1_SB_CB<5>")
	)
	(arc
		(start 86.513924 -270.35887)
		(mid 86.696175 -270.40922)
		(end 86.879684 -270.363696)
		(width 0.0889)
		(layer "In13.Cu")
		(net "M_B_CPU1_SB_CB<5>")
	)
	(arc
		(start 86.888066 -270.35887)
		(mid 87.171022 -270.282693)
		(end 87.453978 -270.35887)
		(width 0.0889)
		(layer "In13.Cu")
		(net "M_B_CPU1_SB_CB<5>")
	)
	(arc
		(start 88.402414 -270.363696)
		(mid 88.585922 -270.40919)
		(end 88.768174 -270.35887)
		(width 0.0889)
		(layer "In13.Cu")
		(net "M_B_CPU1_SB_CB<5>")
	)
	(arc
		(start 80.308196 -270.35887)
		(mid 80.591152 -270.282693)
		(end 80.874108 -270.35887)
		(width 0.0889)
		(layer "In13.Cu")
		(net "M_B_CPU1_SB_CB<5>")
	)
	(arc
		(start 87.46236 -270.363696)
		(mid 87.645868 -270.40919)
		(end 87.82812 -270.35887)
		(width 0.0889)
		(layer "In13.Cu")
		(net "M_B_CPU1_SB_CB<5>")
	)
	(arc
		(start 85.948266 -270.35887)
		(mid 86.231112 -270.282693)
		(end 86.513924 -270.35887)
		(width 0.0889)
		(layer "In13.Cu")
		(net "M_B_CPU1_SB_CB<5>")
	)
	(arc
		(start 87.82812 -270.35887)
		(mid 88.111076 -270.282693)
		(end 88.394032 -270.35887)
		(width 0.0889)
		(layer "In13.Cu")
		(net "M_B_CPU1_SB_CB<5>")
	)
	(segment
		(start 88.577928 -268.960346)
		(end 88.111076 -269.226284)
		(width 0.10668)
		(layer "F.Cu")
		(net "M_B_CPU1_SB_CB<4>")
	)
	(segment
		(start 52.900834 -271.118584)
		(end 53.268626 -270.750792)
		(width 0.14478)
		(layer "In13.Cu")
		(net "M_B_CPU1_SB_CB<4>")
	)
	(segment
		(start 54.946042 -270.750792)
		(end 55.090822 -270.895572)
		(width 0.14478)
		(layer "In13.Cu")
		(net "M_B_CPU1_SB_CB<4>")
	)
	(segment
		(start 61.315346 -269.62481)
		(end 61.315346 -268.900148)
		(width 0.14478)
		(layer "In13.Cu")
		(net "M_B_CPU1_SB_CB<4>")
	)
	(segment
		(start 51.884072 -272.135346)
		(end 52.30622 -271.713198)
		(width 0.14478)
		(layer "In13.Cu")
		(net "M_B_CPU1_SB_CB<4>")
	)
	(segment
		(start 53.28031 -271.702784)
		(end 52.900834 -271.323308)
		(width 0.14478)
		(layer "In13.Cu")
		(net "M_B_CPU1_SB_CB<4>")
	)
	(segment
		(start 87.956898 -269.491714)
		(end 88.111076 -269.226284)
		(width 0.0889)
		(layer "In13.Cu")
		(net "M_B_CPU1_SB_CB<4>")
	)
	(segment
		(start 56.193182 -270.895572)
		(end 56.193182 -271.093438)
		(width 0.14478)
		(layer "In13.Cu")
		(net "M_B_CPU1_SB_CB<4>")
	)
	(segment
		(start 56.048402 -270.750792)
		(end 56.193182 -270.895572)
		(width 0.14478)
		(layer "In13.Cu")
		(net "M_B_CPU1_SB_CB<4>")
	)
	(segment
		(start 53.095144 -272.092674)
		(end 53.28031 -271.907508)
		(width 0.14478)
		(layer "In13.Cu")
		(net "M_B_CPU1_SB_CB<4>")
	)
	(segment
		(start 53.28031 -271.907508)
		(end 53.28031 -271.702784)
		(width 0.14478)
		(layer "In13.Cu")
		(net "M_B_CPU1_SB_CB<4>")
	)
	(segment
		(start 59.093862 -270.750792)
		(end 60.189364 -270.750792)
		(width 0.14478)
		(layer "In13.Cu")
		(net "M_B_CPU1_SB_CB<4>")
	)
	(segment
		(start 55.235602 -271.238218)
		(end 55.497222 -271.238218)
		(width 0.14478)
		(layer "In13.Cu")
		(net "M_B_CPU1_SB_CB<4>")
	)
	(segment
		(start 52.900834 -271.323308)
		(end 52.900834 -271.118584)
		(width 0.14478)
		(layer "In13.Cu")
		(net "M_B_CPU1_SB_CB<4>")
	)
	(segment
		(start 55.642002 -270.895572)
		(end 55.786782 -270.750792)
		(width 0.14478)
		(layer "In13.Cu")
		(net "M_B_CPU1_SB_CB<4>")
	)
	(segment
		(start 78.897734 -269.54861)
		(end 78.913482 -269.539466)
		(width 0.0889)
		(layer "In13.Cu")
		(net "M_B_CPU1_SB_CB<4>")
	)
	(segment
		(start 56.889142 -270.750792)
		(end 57.150762 -270.750792)
		(width 0.14478)
		(layer "In13.Cu")
		(net "M_B_CPU1_SB_CB<4>")
	)
	(segment
		(start 56.744362 -271.093438)
		(end 56.744362 -270.895572)
		(width 0.14478)
		(layer "In13.Cu")
		(net "M_B_CPU1_SB_CB<4>")
	)
	(segment
		(start 52.30622 -271.713198)
		(end 52.510944 -271.713198)
		(width 0.14478)
		(layer "In13.Cu")
		(net "M_B_CPU1_SB_CB<4>")
	)
	(segment
		(start 78.05547 -269.098776)
		(end 78.446884 -269.49019)
		(width 0.0889)
		(layer "In13.Cu")
		(net "M_B_CPU1_SB_CB<4>")
	)
	(segment
		(start 60.189364 -270.750792)
		(end 61.315346 -269.62481)
		(width 0.14478)
		(layer "In13.Cu")
		(net "M_B_CPU1_SB_CB<4>")
	)
	(segment
		(start 61.315346 -268.900148)
		(end 62.6237 -267.591794)
		(width 0.14478)
		(layer "In13.Cu")
		(net "M_B_CPU1_SB_CB<4>")
	)
	(segment
		(start 56.193182 -271.093438)
		(end 56.337962 -271.238218)
		(width 0.14478)
		(layer "In13.Cu")
		(net "M_B_CPU1_SB_CB<4>")
	)
	(segment
		(start 56.744362 -270.895572)
		(end 56.889142 -270.750792)
		(width 0.14478)
		(layer "In13.Cu")
		(net "M_B_CPU1_SB_CB<4>")
	)
	(segment
		(start 58.949082 -271.093438)
		(end 58.949082 -270.895572)
		(width 0.14478)
		(layer "In13.Cu")
		(net "M_B_CPU1_SB_CB<4>")
	)
	(segment
		(start 78.05547 -268.162786)
		(end 78.05547 -269.098776)
		(width 0.0889)
		(layer "In13.Cu")
		(net "M_B_CPU1_SB_CB<4>")
	)
	(segment
		(start 57.846722 -271.093438)
		(end 57.846722 -270.895572)
		(width 0.14478)
		(layer "In13.Cu")
		(net "M_B_CPU1_SB_CB<4>")
	)
	(segment
		(start 58.397902 -270.895572)
		(end 58.397902 -271.093438)
		(width 0.14478)
		(layer "In13.Cu")
		(net "M_B_CPU1_SB_CB<4>")
	)
	(segment
		(start 85.10397 -269.548864)
		(end 85.112352 -269.55369)
		(width 0.0889)
		(layer "In13.Cu")
		(net "M_B_CPU1_SB_CB<4>")
	)
	(segment
		(start 75.969876 -267.596874)
		(end 77.489558 -267.596874)
		(width 0.0889)
		(layer "In13.Cu")
		(net "M_B_CPU1_SB_CB<4>")
	)
	(segment
		(start 55.090822 -270.895572)
		(end 55.090822 -271.093438)
		(width 0.14478)
		(layer "In13.Cu")
		(net "M_B_CPU1_SB_CB<4>")
	)
	(segment
		(start 57.295542 -270.895572)
		(end 57.295542 -271.093438)
		(width 0.14478)
		(layer "In13.Cu")
		(net "M_B_CPU1_SB_CB<4>")
	)
	(segment
		(start 57.440322 -271.238218)
		(end 57.701942 -271.238218)
		(width 0.14478)
		(layer "In13.Cu")
		(net "M_B_CPU1_SB_CB<4>")
	)
	(segment
		(start 57.701942 -271.238218)
		(end 57.846722 -271.093438)
		(width 0.14478)
		(layer "In13.Cu")
		(net "M_B_CPU1_SB_CB<4>")
	)
	(segment
		(start 56.337962 -271.238218)
		(end 56.599582 -271.238218)
		(width 0.14478)
		(layer "In13.Cu")
		(net "M_B_CPU1_SB_CB<4>")
	)
	(segment
		(start 55.090822 -271.093438)
		(end 55.235602 -271.238218)
		(width 0.14478)
		(layer "In13.Cu")
		(net "M_B_CPU1_SB_CB<4>")
	)
	(segment
		(start 53.988462 -271.093438)
		(end 54.133242 -271.238218)
		(width 0.14478)
		(layer "In13.Cu")
		(net "M_B_CPU1_SB_CB<4>")
	)
	(segment
		(start 57.846722 -270.895572)
		(end 57.991502 -270.750792)
		(width 0.14478)
		(layer "In13.Cu")
		(net "M_B_CPU1_SB_CB<4>")
	)
	(segment
		(start 58.397902 -271.093438)
		(end 58.542682 -271.238218)
		(width 0.14478)
		(layer "In13.Cu")
		(net "M_B_CPU1_SB_CB<4>")
	)
	(segment
		(start 55.497222 -271.238218)
		(end 55.642002 -271.093438)
		(width 0.14478)
		(layer "In13.Cu")
		(net "M_B_CPU1_SB_CB<4>")
	)
	(segment
		(start 54.394862 -271.238218)
		(end 54.539642 -271.093438)
		(width 0.14478)
		(layer "In13.Cu")
		(net "M_B_CPU1_SB_CB<4>")
	)
	(segment
		(start 52.89042 -272.092674)
		(end 53.095144 -272.092674)
		(width 0.14478)
		(layer "In13.Cu")
		(net "M_B_CPU1_SB_CB<4>")
	)
	(segment
		(start 55.642002 -271.093438)
		(end 55.642002 -270.895572)
		(width 0.14478)
		(layer "In13.Cu")
		(net "M_B_CPU1_SB_CB<4>")
	)
	(segment
		(start 83.589622 -269.55369)
		(end 83.598004 -269.548864)
		(width 0.0889)
		(layer "In13.Cu")
		(net "M_B_CPU1_SB_CB<4>")
	)
	(segment
		(start 52.510944 -271.713198)
		(end 52.89042 -272.092674)
		(width 0.14478)
		(layer "In13.Cu")
		(net "M_B_CPU1_SB_CB<4>")
	)
	(segment
		(start 54.684422 -270.750792)
		(end 54.946042 -270.750792)
		(width 0.14478)
		(layer "In13.Cu")
		(net "M_B_CPU1_SB_CB<4>")
	)
	(segment
		(start 53.268626 -270.750792)
		(end 53.843682 -270.750792)
		(width 0.14478)
		(layer "In13.Cu")
		(net "M_B_CPU1_SB_CB<4>")
	)
	(segment
		(start 54.539642 -270.895572)
		(end 54.684422 -270.750792)
		(width 0.14478)
		(layer "In13.Cu")
		(net "M_B_CPU1_SB_CB<4>")
	)
	(segment
		(start 78.879446 -269.559024)
		(end 78.897734 -269.54861)
		(width 0.0889)
		(layer "In13.Cu")
		(net "M_B_CPU1_SB_CB<4>")
	)
	(segment
		(start 58.542682 -271.238218)
		(end 58.804302 -271.238218)
		(width 0.14478)
		(layer "In13.Cu")
		(net "M_B_CPU1_SB_CB<4>")
	)
	(segment
		(start 55.786782 -270.750792)
		(end 56.048402 -270.750792)
		(width 0.14478)
		(layer "In13.Cu")
		(net "M_B_CPU1_SB_CB<4>")
	)
	(segment
		(start 57.991502 -270.750792)
		(end 58.253122 -270.750792)
		(width 0.14478)
		(layer "In13.Cu")
		(net "M_B_CPU1_SB_CB<4>")
	)
	(segment
		(start 58.804302 -271.238218)
		(end 58.949082 -271.093438)
		(width 0.14478)
		(layer "In13.Cu")
		(net "M_B_CPU1_SB_CB<4>")
	)
	(segment
		(start 81.344008 -269.548864)
		(end 81.35239 -269.55369)
		(width 0.0889)
		(layer "In13.Cu")
		(net "M_B_CPU1_SB_CB<4>")
	)
	(segment
		(start 53.843682 -270.750792)
		(end 53.988462 -270.895572)
		(width 0.14478)
		(layer "In13.Cu")
		(net "M_B_CPU1_SB_CB<4>")
	)
	(segment
		(start 87.860632 -269.517114)
		(end 87.956898 -269.491714)
		(width 0.0889)
		(layer "In13.Cu")
		(net "M_B_CPU1_SB_CB<4>")
	)
	(segment
		(start 58.253122 -270.750792)
		(end 58.397902 -270.895572)
		(width 0.14478)
		(layer "In13.Cu")
		(net "M_B_CPU1_SB_CB<4>")
	)
	(segment
		(start 75.964796 -267.591794)
		(end 75.969876 -267.596874)
		(width 0.14478)
		(layer "In13.Cu")
		(net "M_B_CPU1_SB_CB<4>")
	)
	(segment
		(start 86.044024 -269.548864)
		(end 86.052406 -269.55369)
		(width 0.0889)
		(layer "In13.Cu")
		(net "M_B_CPU1_SB_CB<4>")
	)
	(segment
		(start 54.133242 -271.238218)
		(end 54.394862 -271.238218)
		(width 0.14478)
		(layer "In13.Cu")
		(net "M_B_CPU1_SB_CB<4>")
	)
	(segment
		(start 57.150762 -270.750792)
		(end 57.295542 -270.895572)
		(width 0.14478)
		(layer "In13.Cu")
		(net "M_B_CPU1_SB_CB<4>")
	)
	(segment
		(start 58.949082 -270.895572)
		(end 59.093862 -270.750792)
		(width 0.14478)
		(layer "In13.Cu")
		(net "M_B_CPU1_SB_CB<4>")
	)
	(segment
		(start 53.988462 -270.895572)
		(end 53.988462 -271.093438)
		(width 0.14478)
		(layer "In13.Cu")
		(net "M_B_CPU1_SB_CB<4>")
	)
	(segment
		(start 77.489558 -267.596874)
		(end 78.05547 -268.162786)
		(width 0.0889)
		(layer "In13.Cu")
		(net "M_B_CPU1_SB_CB<4>")
	)
	(segment
		(start 79.826358 -269.555722)
		(end 79.838042 -269.548864)
		(width 0.0889)
		(layer "In13.Cu")
		(net "M_B_CPU1_SB_CB<4>")
	)
	(segment
		(start 80.769714 -269.55369)
		(end 80.778096 -269.548864)
		(width 0.0889)
		(layer "In13.Cu")
		(net "M_B_CPU1_SB_CB<4>")
	)
	(segment
		(start 84.529676 -269.55369)
		(end 84.538058 -269.548864)
		(width 0.0889)
		(layer "In13.Cu")
		(net "M_B_CPU1_SB_CB<4>")
	)
	(segment
		(start 57.295542 -271.093438)
		(end 57.440322 -271.238218)
		(width 0.14478)
		(layer "In13.Cu")
		(net "M_B_CPU1_SB_CB<4>")
	)
	(segment
		(start 56.599582 -271.238218)
		(end 56.744362 -271.093438)
		(width 0.14478)
		(layer "In13.Cu")
		(net "M_B_CPU1_SB_CB<4>")
	)
	(segment
		(start 54.539642 -271.093438)
		(end 54.539642 -270.895572)
		(width 0.14478)
		(layer "In13.Cu")
		(net "M_B_CPU1_SB_CB<4>")
	)
	(segment
		(start 78.523338 -269.548864)
		(end 78.523592 -269.548864)
		(width 0.0889)
		(layer "In13.Cu")
		(net "M_B_CPU1_SB_CB<4>")
	)
	(segment
		(start 62.6237 -267.591794)
		(end 75.964796 -267.591794)
		(width 0.14478)
		(layer "In13.Cu")
		(net "M_B_CPU1_SB_CB<4>")
	)
	(arc
		(start 84.163916 -269.548864)
		(mid 84.346167 -269.599214)
		(end 84.529676 -269.55369)
		(width 0.0889)
		(layer "In13.Cu")
		(net "M_B_CPU1_SB_CB<4>")
	)
	(arc
		(start 78.913482 -269.539466)
		(mid 79.189791 -269.47249)
		(end 79.463646 -269.548864)
		(width 0.0889)
		(layer "In13.Cu")
		(net "M_B_CPU1_SB_CB<4>")
	)
	(arc
		(start 82.65795 -269.548864)
		(mid 82.940906 -269.472687)
		(end 83.223862 -269.548864)
		(width 0.0889)
		(layer "In13.Cu")
		(net "M_B_CPU1_SB_CB<4>")
	)
	(arc
		(start 80.403954 -269.548864)
		(mid 80.586205 -269.599214)
		(end 80.769714 -269.55369)
		(width 0.0889)
		(layer "In13.Cu")
		(net "M_B_CPU1_SB_CB<4>")
	)
	(arc
		(start 85.112352 -269.55369)
		(mid 85.29586 -269.599184)
		(end 85.478112 -269.548864)
		(width 0.0889)
		(layer "In13.Cu")
		(net "M_B_CPU1_SB_CB<4>")
	)
	(arc
		(start 83.598004 -269.548864)
		(mid 83.88096 -269.472687)
		(end 84.163916 -269.548864)
		(width 0.0889)
		(layer "In13.Cu")
		(net "M_B_CPU1_SB_CB<4>")
	)
	(arc
		(start 84.538058 -269.548864)
		(mid 84.821014 -269.472687)
		(end 85.10397 -269.548864)
		(width 0.0889)
		(layer "In13.Cu")
		(net "M_B_CPU1_SB_CB<4>")
	)
	(arc
		(start 78.523592 -269.548864)
		(mid 78.70022 -269.599097)
		(end 78.879446 -269.559024)
		(width 0.0889)
		(layer "In13.Cu")
		(net "M_B_CPU1_SB_CB<4>")
	)
	(arc
		(start 86.984078 -269.548864)
		(mid 87.171022 -269.599119)
		(end 87.357966 -269.548864)
		(width 0.0889)
		(layer "In13.Cu")
		(net "M_B_CPU1_SB_CB<4>")
	)
	(arc
		(start 85.478112 -269.548864)
		(mid 85.761068 -269.472687)
		(end 86.044024 -269.548864)
		(width 0.0889)
		(layer "In13.Cu")
		(net "M_B_CPU1_SB_CB<4>")
	)
	(arc
		(start 80.778096 -269.548864)
		(mid 81.061052 -269.472687)
		(end 81.344008 -269.548864)
		(width 0.0889)
		(layer "In13.Cu")
		(net "M_B_CPU1_SB_CB<4>")
	)
	(arc
		(start 81.35239 -269.55369)
		(mid 81.535898 -269.599184)
		(end 81.71815 -269.548864)
		(width 0.0889)
		(layer "In13.Cu")
		(net "M_B_CPU1_SB_CB<4>")
	)
	(arc
		(start 87.357966 -269.548864)
		(mid 87.605562 -269.473686)
		(end 87.860632 -269.517114)
		(width 0.0889)
		(layer "In13.Cu")
		(net "M_B_CPU1_SB_CB<4>")
	)
	(arc
		(start 82.284062 -269.548864)
		(mid 82.471006 -269.599119)
		(end 82.65795 -269.548864)
		(width 0.0889)
		(layer "In13.Cu")
		(net "M_B_CPU1_SB_CB<4>")
	)
	(arc
		(start 81.71815 -269.548864)
		(mid 82.001106 -269.472687)
		(end 82.284062 -269.548864)
		(width 0.0889)
		(layer "In13.Cu")
		(net "M_B_CPU1_SB_CB<4>")
	)
	(arc
		(start 86.418166 -269.548864)
		(mid 86.701122 -269.472687)
		(end 86.984078 -269.548864)
		(width 0.0889)
		(layer "In13.Cu")
		(net "M_B_CPU1_SB_CB<4>")
	)
	(arc
		(start 86.052406 -269.55369)
		(mid 86.235914 -269.599184)
		(end 86.418166 -269.548864)
		(width 0.0889)
		(layer "In13.Cu")
		(net "M_B_CPU1_SB_CB<4>")
	)
	(arc
		(start 79.463646 -269.548864)
		(mid 79.644104 -269.599308)
		(end 79.826358 -269.555722)
		(width 0.0889)
		(layer "In13.Cu")
		(net "M_B_CPU1_SB_CB<4>")
	)
	(arc
		(start 79.838042 -269.548864)
		(mid 80.120998 -269.472687)
		(end 80.403954 -269.548864)
		(width 0.0889)
		(layer "In13.Cu")
		(net "M_B_CPU1_SB_CB<4>")
	)
	(arc
		(start 83.223862 -269.548864)
		(mid 83.406113 -269.599214)
		(end 83.589622 -269.55369)
		(width 0.0889)
		(layer "In13.Cu")
		(net "M_B_CPU1_SB_CB<4>")
	)
	(arc
		(start 78.446884 -269.49019)
		(mid 78.483211 -269.522003)
		(end 78.523338 -269.548864)
		(width 0.0889)
		(layer "In13.Cu")
		(net "M_B_CPU1_SB_CB<4>")
	)
	(segment
		(start 89.517982 -273.820382)
		(end 89.05113 -274.08632)
		(width 0.10668)
		(layer "F.Cu")
		(net "M_B_CPU1_SB_CB<3>")
	)
	(segment
		(start 51.696874 -280.21026)
		(end 47.784004 -280.635202)
		(width 0.14478)
		(layer "In13.Cu")
		(net "M_B_CPU1_SB_CB<3>")
	)
	(segment
		(start 77.20711 -272.531586)
		(end 76.73213 -272.531586)
		(width 0.0889)
		(layer "In13.Cu")
		(net "M_B_CPU1_SB_CB<3>")
	)
	(segment
		(start 57.153048 -280.66492)
		(end 53.350922 -280.66492)
		(width 0.14478)
		(layer "In13.Cu")
		(net "M_B_CPU1_SB_CB<3>")
	)
	(segment
		(start 67.095878 -272.664174)
		(end 59.925204 -279.834848)
		(width 0.14478)
		(layer "In13.Cu")
		(net "M_B_CPU1_SB_CB<3>")
	)
	(segment
		(start 89.205054 -273.82089)
		(end 89.182702 -273.737578)
		(width 0.0889)
		(layer "In13.Cu")
		(net "M_B_CPU1_SB_CB<3>")
	)
	(segment
		(start 78.903322 -273.767296)
		(end 78.897734 -273.763994)
		(width 0.0889)
		(layer "In13.Cu")
		(net "M_B_CPU1_SB_CB<3>")
	)
	(segment
		(start 84.538058 -273.76374)
		(end 84.529676 -273.758914)
		(width 0.0889)
		(layer "In13.Cu")
		(net "M_B_CPU1_SB_CB<3>")
	)
	(segment
		(start 80.778096 -273.76374)
		(end 80.769714 -273.758914)
		(width 0.0889)
		(layer "In13.Cu")
		(net "M_B_CPU1_SB_CB<3>")
	)
	(segment
		(start 59.925204 -279.834848)
		(end 59.220354 -280.126948)
		(width 0.14478)
		(layer "In13.Cu")
		(net "M_B_CPU1_SB_CB<3>")
	)
	(segment
		(start 80.403954 -273.76374)
		(end 80.389222 -273.772376)
		(width 0.0889)
		(layer "In13.Cu")
		(net "M_B_CPU1_SB_CB<3>")
	)
	(segment
		(start 86.052406 -273.758914)
		(end 86.044024 -273.76374)
		(width 0.0889)
		(layer "In13.Cu")
		(net "M_B_CPU1_SB_CB<3>")
	)
	(segment
		(start 58.803794 -280.21026)
		(end 58.17616 -280.335228)
		(width 0.14478)
		(layer "In13.Cu")
		(net "M_B_CPU1_SB_CB<3>")
	)
	(segment
		(start 81.35239 -273.758914)
		(end 81.344008 -273.76374)
		(width 0.0889)
		(layer "In13.Cu")
		(net "M_B_CPU1_SB_CB<3>")
	)
	(segment
		(start 88.29802 -273.76374)
		(end 88.289638 -273.758914)
		(width 0.0889)
		(layer "In13.Cu")
		(net "M_B_CPU1_SB_CB<3>")
	)
	(segment
		(start 89.05113 -274.08632)
		(end 89.205054 -273.82089)
		(width 0.0889)
		(layer "In13.Cu")
		(net "M_B_CPU1_SB_CB<3>")
	)
	(segment
		(start 78.388718 -273.713194)
		(end 77.20711 -272.531586)
		(width 0.0889)
		(layer "In13.Cu")
		(net "M_B_CPU1_SB_CB<3>")
	)
	(segment
		(start 78.711044 -273.713194)
		(end 78.388718 -273.713194)
		(width 0.0889)
		(layer "In13.Cu")
		(net "M_B_CPU1_SB_CB<3>")
	)
	(segment
		(start 76.391516 -272.664174)
		(end 67.095878 -272.664174)
		(width 0.14478)
		(layer "In13.Cu")
		(net "M_B_CPU1_SB_CB<3>")
	)
	(segment
		(start 53.350922 -280.66492)
		(end 52.25288 -280.21026)
		(width 0.14478)
		(layer "In13.Cu")
		(net "M_B_CPU1_SB_CB<3>")
	)
	(segment
		(start 57.589674 -280.578052)
		(end 57.153048 -280.66492)
		(width 0.14478)
		(layer "In13.Cu")
		(net "M_B_CPU1_SB_CB<3>")
	)
	(segment
		(start 59.220354 -280.126948)
		(end 58.804048 -280.209752)
		(width 0.14478)
		(layer "In13.Cu")
		(net "M_B_CPU1_SB_CB<3>")
	)
	(segment
		(start 52.25288 -280.21026)
		(end 51.696874 -280.21026)
		(width 0.14478)
		(layer "In13.Cu")
		(net "M_B_CPU1_SB_CB<3>")
	)
	(segment
		(start 85.112352 -273.758914)
		(end 85.10397 -273.76374)
		(width 0.0889)
		(layer "In13.Cu")
		(net "M_B_CPU1_SB_CB<3>")
	)
	(segment
		(start 76.73213 -272.531586)
		(end 76.599542 -272.664174)
		(width 0.0889)
		(layer "In13.Cu")
		(net "M_B_CPU1_SB_CB<3>")
	)
	(segment
		(start 76.599542 -272.664174)
		(end 76.391516 -272.664174)
		(width 0.0889)
		(layer "In13.Cu")
		(net "M_B_CPU1_SB_CB<3>")
	)
	(segment
		(start 79.474822 -273.756882)
		(end 79.463138 -273.76374)
		(width 0.0889)
		(layer "In13.Cu")
		(net "M_B_CPU1_SB_CB<3>")
	)
	(segment
		(start 83.598004 -273.76374)
		(end 83.589622 -273.758914)
		(width 0.0889)
		(layer "In13.Cu")
		(net "M_B_CPU1_SB_CB<3>")
	)
	(segment
		(start 58.804048 -280.209752)
		(end 58.803794 -280.21026)
		(width 0.14478)
		(layer "In13.Cu")
		(net "M_B_CPU1_SB_CB<3>")
	)
	(segment
		(start 58.17616 -280.335228)
		(end 57.589674 -280.578052)
		(width 0.14478)
		(layer "In13.Cu")
		(net "M_B_CPU1_SB_CB<3>")
	)
	(arc
		(start 82.284062 -273.76374)
		(mid 82.001106 -273.839917)
		(end 81.71815 -273.76374)
		(width 0.0889)
		(layer "In13.Cu")
		(net "M_B_CPU1_SB_CB<3>")
	)
	(arc
		(start 86.984078 -273.76374)
		(mid 86.701122 -273.839917)
		(end 86.418166 -273.76374)
		(width 0.0889)
		(layer "In13.Cu")
		(net "M_B_CPU1_SB_CB<3>")
	)
	(arc
		(start 78.897734 -273.763994)
		(mid 78.807743 -273.726259)
		(end 78.711044 -273.713194)
		(width 0.0889)
		(layer "In13.Cu")
		(net "M_B_CPU1_SB_CB<3>")
	)
	(arc
		(start 88.863932 -273.76374)
		(mid 88.580976 -273.839917)
		(end 88.29802 -273.76374)
		(width 0.0889)
		(layer "In13.Cu")
		(net "M_B_CPU1_SB_CB<3>")
	)
	(arc
		(start 79.463138 -273.76374)
		(mid 79.18371 -273.839906)
		(end 78.903322 -273.767296)
		(width 0.0889)
		(layer "In13.Cu")
		(net "M_B_CPU1_SB_CB<3>")
	)
	(arc
		(start 83.589622 -273.758914)
		(mid 83.406114 -273.71342)
		(end 83.223862 -273.76374)
		(width 0.0889)
		(layer "In13.Cu")
		(net "M_B_CPU1_SB_CB<3>")
	)
	(arc
		(start 85.10397 -273.76374)
		(mid 84.821014 -273.839917)
		(end 84.538058 -273.76374)
		(width 0.0889)
		(layer "In13.Cu")
		(net "M_B_CPU1_SB_CB<3>")
	)
	(arc
		(start 84.529676 -273.758914)
		(mid 84.346168 -273.71342)
		(end 84.163916 -273.76374)
		(width 0.0889)
		(layer "In13.Cu")
		(net "M_B_CPU1_SB_CB<3>")
	)
	(arc
		(start 86.418166 -273.76374)
		(mid 86.235915 -273.71339)
		(end 86.052406 -273.758914)
		(width 0.0889)
		(layer "In13.Cu")
		(net "M_B_CPU1_SB_CB<3>")
	)
	(arc
		(start 84.163916 -273.76374)
		(mid 83.88096 -273.839917)
		(end 83.598004 -273.76374)
		(width 0.0889)
		(layer "In13.Cu")
		(net "M_B_CPU1_SB_CB<3>")
	)
	(arc
		(start 80.389222 -273.772376)
		(mid 80.112239 -273.84018)
		(end 79.837534 -273.76374)
		(width 0.0889)
		(layer "In13.Cu")
		(net "M_B_CPU1_SB_CB<3>")
	)
	(arc
		(start 81.344008 -273.76374)
		(mid 81.061052 -273.839917)
		(end 80.778096 -273.76374)
		(width 0.0889)
		(layer "In13.Cu")
		(net "M_B_CPU1_SB_CB<3>")
	)
	(arc
		(start 86.044024 -273.76374)
		(mid 85.761068 -273.839917)
		(end 85.478112 -273.76374)
		(width 0.0889)
		(layer "In13.Cu")
		(net "M_B_CPU1_SB_CB<3>")
	)
	(arc
		(start 81.71815 -273.76374)
		(mid 81.535899 -273.71339)
		(end 81.35239 -273.758914)
		(width 0.0889)
		(layer "In13.Cu")
		(net "M_B_CPU1_SB_CB<3>")
	)
	(arc
		(start 83.223862 -273.76374)
		(mid 82.940906 -273.839917)
		(end 82.65795 -273.76374)
		(width 0.0889)
		(layer "In13.Cu")
		(net "M_B_CPU1_SB_CB<3>")
	)
	(arc
		(start 79.837534 -273.76374)
		(mid 79.657076 -273.713296)
		(end 79.474822 -273.756882)
		(width 0.0889)
		(layer "In13.Cu")
		(net "M_B_CPU1_SB_CB<3>")
	)
	(arc
		(start 87.923878 -273.76374)
		(mid 87.640922 -273.839917)
		(end 87.357966 -273.76374)
		(width 0.0889)
		(layer "In13.Cu")
		(net "M_B_CPU1_SB_CB<3>")
	)
	(arc
		(start 82.65795 -273.76374)
		(mid 82.471006 -273.713485)
		(end 82.284062 -273.76374)
		(width 0.0889)
		(layer "In13.Cu")
		(net "M_B_CPU1_SB_CB<3>")
	)
	(arc
		(start 87.357966 -273.76374)
		(mid 87.171022 -273.713485)
		(end 86.984078 -273.76374)
		(width 0.0889)
		(layer "In13.Cu")
		(net "M_B_CPU1_SB_CB<3>")
	)
	(arc
		(start 80.769714 -273.758914)
		(mid 80.586206 -273.71342)
		(end 80.403954 -273.76374)
		(width 0.0889)
		(layer "In13.Cu")
		(net "M_B_CPU1_SB_CB<3>")
	)
	(arc
		(start 88.289638 -273.758914)
		(mid 88.10613 -273.71342)
		(end 87.923878 -273.76374)
		(width 0.0889)
		(layer "In13.Cu")
		(net "M_B_CPU1_SB_CB<3>")
	)
	(arc
		(start 85.478112 -273.76374)
		(mid 85.295861 -273.71339)
		(end 85.112352 -273.758914)
		(width 0.0889)
		(layer "In13.Cu")
		(net "M_B_CPU1_SB_CB<3>")
	)
	(arc
		(start 89.182702 -273.737578)
		(mid 89.02037 -273.71476)
		(end 88.863932 -273.76374)
		(width 0.0889)
		(layer "In13.Cu")
		(net "M_B_CPU1_SB_CB<3>")
	)
	(segment
		(start 88.107774 -273.010376)
		(end 87.640922 -273.276314)
		(width 0.10668)
		(layer "F.Cu")
		(net "M_B_CPU1_SB_CB<2>")
	)
	(segment
		(start 59.677046 -278.510238)
		(end 58.190384 -278.510238)
		(width 0.14478)
		(layer "In13.Cu")
		(net "M_B_CPU1_SB_CB<2>")
	)
	(segment
		(start 52.442872 -278.510238)
		(end 50.807112 -278.510238)
		(width 0.14478)
		(layer "In13.Cu")
		(net "M_B_CPU1_SB_CB<2>")
	)
	(segment
		(start 83.702398 -272.948908)
		(end 83.694016 -272.953734)
		(width 0.0889)
		(layer "In13.Cu")
		(net "M_B_CPU1_SB_CB<2>")
	)
	(segment
		(start 50.807112 -278.510238)
		(end 50.381916 -278.935434)
		(width 0.14478)
		(layer "In13.Cu")
		(net "M_B_CPU1_SB_CB<2>")
	)
	(segment
		(start 58.190384 -278.510238)
		(end 57.410858 -279.289764)
		(width 0.14478)
		(layer "In13.Cu")
		(net "M_B_CPU1_SB_CB<2>")
	)
	(segment
		(start 76.501498 -271.754854)
		(end 75.960986 -271.754854)
		(width 0.0889)
		(layer "In13.Cu")
		(net "M_B_CPU1_SB_CB<2>")
	)
	(segment
		(start 85.948012 -272.953734)
		(end 85.93963 -272.948908)
		(width 0.0889)
		(layer "In13.Cu")
		(net "M_B_CPU1_SB_CB<2>")
	)
	(segment
		(start 66.43243 -271.754854)
		(end 59.677046 -278.510238)
		(width 0.14478)
		(layer "In13.Cu")
		(net "M_B_CPU1_SB_CB<2>")
	)
	(segment
		(start 87.640922 -273.276314)
		(end 87.7951 -273.010884)
		(width 0.0889)
		(layer "In13.Cu")
		(net "M_B_CPU1_SB_CB<2>")
	)
	(segment
		(start 82.762344 -272.948908)
		(end 82.753962 -272.953734)
		(width 0.0889)
		(layer "In13.Cu")
		(net "M_B_CPU1_SB_CB<2>")
	)
	(segment
		(start 78.312264 -272.865088)
		(end 77.468222 -272.021046)
		(width 0.0889)
		(layer "In13.Cu")
		(net "M_B_CPU1_SB_CB<2>")
	)
	(segment
		(start 76.76769 -272.021046)
		(end 76.501498 -271.754854)
		(width 0.0889)
		(layer "In13.Cu")
		(net "M_B_CPU1_SB_CB<2>")
	)
	(segment
		(start 87.46236 -272.948908)
		(end 87.453978 -272.953734)
		(width 0.0889)
		(layer "In13.Cu")
		(net "M_B_CPU1_SB_CB<2>")
	)
	(segment
		(start 50.381916 -278.935434)
		(end 47.784004 -278.935434)
		(width 0.14478)
		(layer "In13.Cu")
		(net "M_B_CPU1_SB_CB<2>")
	)
	(segment
		(start 78.993492 -272.953988)
		(end 78.977744 -272.963132)
		(width 0.0889)
		(layer "In13.Cu")
		(net "M_B_CPU1_SB_CB<2>")
	)
	(segment
		(start 79.009748 -272.94459)
		(end 78.993492 -272.953988)
		(width 0.0889)
		(layer "In13.Cu")
		(net "M_B_CPU1_SB_CB<2>")
	)
	(segment
		(start 57.410858 -279.289764)
		(end 53.222398 -279.289764)
		(width 0.14478)
		(layer "In13.Cu")
		(net "M_B_CPU1_SB_CB<2>")
	)
	(segment
		(start 53.222398 -279.289764)
		(end 52.442872 -278.510238)
		(width 0.14478)
		(layer "In13.Cu")
		(net "M_B_CPU1_SB_CB<2>")
	)
	(segment
		(start 82.18805 -272.953734)
		(end 82.179668 -272.948908)
		(width 0.0889)
		(layer "In13.Cu")
		(net "M_B_CPU1_SB_CB<2>")
	)
	(segment
		(start 77.468222 -272.021046)
		(end 76.76769 -272.021046)
		(width 0.0889)
		(layer "In13.Cu")
		(net "M_B_CPU1_SB_CB<2>")
	)
	(segment
		(start 85.948266 -272.953734)
		(end 85.948012 -272.953734)
		(width 0.0889)
		(layer "In13.Cu")
		(net "M_B_CPU1_SB_CB<2>")
	)
	(segment
		(start 75.960986 -271.754854)
		(end 66.43243 -271.754854)
		(width 0.14478)
		(layer "In13.Cu")
		(net "M_B_CPU1_SB_CB<2>")
	)
	(segment
		(start 79.377794 -272.95983)
		(end 79.36738 -272.953734)
		(width 0.0889)
		(layer "In13.Cu")
		(net "M_B_CPU1_SB_CB<2>")
	)
	(segment
		(start 80.308196 -272.953734)
		(end 80.299814 -272.948908)
		(width 0.0889)
		(layer "In13.Cu")
		(net "M_B_CPU1_SB_CB<2>")
	)
	(segment
		(start 87.7951 -273.010884)
		(end 87.772748 -272.927572)
		(width 0.0889)
		(layer "In13.Cu")
		(net "M_B_CPU1_SB_CB<2>")
	)
	(segment
		(start 86.888066 -272.953734)
		(end 86.879684 -272.948908)
		(width 0.0889)
		(layer "In13.Cu")
		(net "M_B_CPU1_SB_CB<2>")
	)
	(arc
		(start 87.453978 -272.953734)
		(mid 87.171022 -273.029911)
		(end 86.888066 -272.953734)
		(width 0.0889)
		(layer "In13.Cu")
		(net "M_B_CPU1_SB_CB<2>")
	)
	(arc
		(start 78.42758 -272.953734)
		(mid 78.367056 -272.91314)
		(end 78.312264 -272.865088)
		(width 0.0889)
		(layer "In13.Cu")
		(net "M_B_CPU1_SB_CB<2>")
	)
	(arc
		(start 82.753962 -272.953734)
		(mid 82.471006 -273.029911)
		(end 82.18805 -272.953734)
		(width 0.0889)
		(layer "In13.Cu")
		(net "M_B_CPU1_SB_CB<2>")
	)
	(arc
		(start 80.874108 -272.953734)
		(mid 80.591152 -273.029911)
		(end 80.308196 -272.953734)
		(width 0.0889)
		(layer "In13.Cu")
		(net "M_B_CPU1_SB_CB<2>")
	)
	(arc
		(start 81.813908 -272.953734)
		(mid 81.530952 -273.029911)
		(end 81.247996 -272.953734)
		(width 0.0889)
		(layer "In13.Cu")
		(net "M_B_CPU1_SB_CB<2>")
	)
	(arc
		(start 86.879684 -272.948908)
		(mid 86.696176 -272.903414)
		(end 86.513924 -272.953734)
		(width 0.0889)
		(layer "In13.Cu")
		(net "M_B_CPU1_SB_CB<2>")
	)
	(arc
		(start 85.93963 -272.948908)
		(mid 85.756122 -272.903414)
		(end 85.57387 -272.953734)
		(width 0.0889)
		(layer "In13.Cu")
		(net "M_B_CPU1_SB_CB<2>")
	)
	(arc
		(start 78.977744 -272.963132)
		(mid 78.701435 -273.030108)
		(end 78.42758 -272.953734)
		(width 0.0889)
		(layer "In13.Cu")
		(net "M_B_CPU1_SB_CB<2>")
	)
	(arc
		(start 87.772748 -272.927572)
		(mid 87.615238 -272.904374)
		(end 87.46236 -272.948908)
		(width 0.0889)
		(layer "In13.Cu")
		(net "M_B_CPU1_SB_CB<2>")
	)
	(arc
		(start 80.299814 -272.948908)
		(mid 80.116052 -272.903292)
		(end 79.933546 -272.953734)
		(width 0.0889)
		(layer "In13.Cu")
		(net "M_B_CPU1_SB_CB<2>")
	)
	(arc
		(start 83.128104 -272.953734)
		(mid 82.945853 -272.903384)
		(end 82.762344 -272.948908)
		(width 0.0889)
		(layer "In13.Cu")
		(net "M_B_CPU1_SB_CB<2>")
	)
	(arc
		(start 86.513924 -272.953734)
		(mid 86.231112 -273.029783)
		(end 85.948266 -272.953734)
		(width 0.0889)
		(layer "In13.Cu")
		(net "M_B_CPU1_SB_CB<2>")
	)
	(arc
		(start 81.247996 -272.953734)
		(mid 81.061052 -272.903479)
		(end 80.874108 -272.953734)
		(width 0.0889)
		(layer "In13.Cu")
		(net "M_B_CPU1_SB_CB<2>")
	)
	(arc
		(start 84.068158 -272.953734)
		(mid 83.885907 -272.903384)
		(end 83.702398 -272.948908)
		(width 0.0889)
		(layer "In13.Cu")
		(net "M_B_CPU1_SB_CB<2>")
	)
	(arc
		(start 85.57387 -272.953734)
		(mid 85.290914 -273.029911)
		(end 85.007958 -272.953734)
		(width 0.0889)
		(layer "In13.Cu")
		(net "M_B_CPU1_SB_CB<2>")
	)
	(arc
		(start 82.179668 -272.948908)
		(mid 81.99616 -272.903414)
		(end 81.813908 -272.953734)
		(width 0.0889)
		(layer "In13.Cu")
		(net "M_B_CPU1_SB_CB<2>")
	)
	(arc
		(start 83.694016 -272.953734)
		(mid 83.41106 -273.029911)
		(end 83.128104 -272.953734)
		(width 0.0889)
		(layer "In13.Cu")
		(net "M_B_CPU1_SB_CB<2>")
	)
	(arc
		(start 85.007958 -272.953734)
		(mid 84.821014 -272.903479)
		(end 84.63407 -272.953734)
		(width 0.0889)
		(layer "In13.Cu")
		(net "M_B_CPU1_SB_CB<2>")
	)
	(arc
		(start 84.63407 -272.953734)
		(mid 84.351114 -273.029911)
		(end 84.068158 -272.953734)
		(width 0.0889)
		(layer "In13.Cu")
		(net "M_B_CPU1_SB_CB<2>")
	)
	(arc
		(start 79.933546 -272.953734)
		(mid 79.656479 -273.030005)
		(end 79.377794 -272.95983)
		(width 0.0889)
		(layer "In13.Cu")
		(net "M_B_CPU1_SB_CB<2>")
	)
	(arc
		(start 79.36738 -272.953734)
		(mid 79.18973 -272.903474)
		(end 79.009748 -272.94459)
		(width 0.0889)
		(layer "In13.Cu")
		(net "M_B_CPU1_SB_CB<2>")
	)
	(segment
		(start 89.987882 -273.010376)
		(end 89.52103 -273.276314)
		(width 0.10668)
		(layer "F.Cu")
		(net "M_B_CPU1_SB_CB<1>")
	)
	(segment
		(start 55.9943 -280.21026)
		(end 56.276494 -279.928066)
		(width 0.14478)
		(layer "In13.Cu")
		(net "M_B_CPU1_SB_CB<1>")
	)
	(segment
		(start 59.711844 -279.412192)
		(end 60.097162 -279.026874)
		(width 0.14478)
		(layer "In13.Cu")
		(net "M_B_CPU1_SB_CB<1>")
	)
	(segment
		(start 78.467712 -273.522694)
		(end 78.711552 -273.522694)
		(width 0.0889)
		(layer "In13.Cu")
		(net "M_B_CPU1_SB_CB<1>")
	)
	(segment
		(start 53.506878 -280.21026)
		(end 53.9877 -280.21026)
		(width 0.14478)
		(layer "In13.Cu")
		(net "M_B_CPU1_SB_CB<1>")
	)
	(segment
		(start 59.159902 -279.412192)
		(end 59.711844 -279.412192)
		(width 0.14478)
		(layer "In13.Cu")
		(net "M_B_CPU1_SB_CB<1>")
	)
	(segment
		(start 62.436502 -276.687534)
		(end 62.436502 -276.386798)
		(width 0.14478)
		(layer "In13.Cu")
		(net "M_B_CPU1_SB_CB<1>")
	)
	(segment
		(start 53.9877 -280.21026)
		(end 54.290214 -279.907746)
		(width 0.14478)
		(layer "In13.Cu")
		(net "M_B_CPU1_SB_CB<1>")
	)
	(segment
		(start 62.97676 -276.147276)
		(end 63.216282 -275.907754)
		(width 0.14478)
		(layer "In13.Cu")
		(net "M_B_CPU1_SB_CB<1>")
	)
	(segment
		(start 75.960986 -272.209514)
		(end 76.458318 -272.209514)
		(width 0.0889)
		(layer "In13.Cu")
		(net "M_B_CPU1_SB_CB<1>")
	)
	(segment
		(start 61.4172 -277.706836)
		(end 61.656722 -277.467314)
		(width 0.14478)
		(layer "In13.Cu")
		(net "M_B_CPU1_SB_CB<1>")
	)
	(segment
		(start 76.52639 -272.277586)
		(end 77.222604 -272.277586)
		(width 0.0889)
		(layer "In13.Cu")
		(net "M_B_CPU1_SB_CB<1>")
	)
	(segment
		(start 63.996062 -275.127974)
		(end 63.996062 -274.827238)
		(width 0.14478)
		(layer "In13.Cu")
		(net "M_B_CPU1_SB_CB<1>")
	)
	(segment
		(start 51.884072 -279.602692)
		(end 52.126642 -279.360122)
		(width 0.14478)
		(layer "In13.Cu")
		(net "M_B_CPU1_SB_CB<1>")
	)
	(segment
		(start 64.775842 -274.348194)
		(end 64.775842 -274.047458)
		(width 0.14478)
		(layer "In13.Cu")
		(net "M_B_CPU1_SB_CB<1>")
	)
	(segment
		(start 61.896244 -276.927056)
		(end 62.19698 -276.927056)
		(width 0.14478)
		(layer "In13.Cu")
		(net "M_B_CPU1_SB_CB<1>")
	)
	(segment
		(start 63.75654 -275.367496)
		(end 63.996062 -275.127974)
		(width 0.14478)
		(layer "In13.Cu")
		(net "M_B_CPU1_SB_CB<1>")
	)
	(segment
		(start 65.795144 -273.028156)
		(end 66.09588 -273.028156)
		(width 0.14478)
		(layer "In13.Cu")
		(net "M_B_CPU1_SB_CB<1>")
	)
	(segment
		(start 60.097162 -279.026874)
		(end 60.097162 -278.726138)
		(width 0.14478)
		(layer "In13.Cu")
		(net "M_B_CPU1_SB_CB<1>")
	)
	(segment
		(start 62.436502 -276.386798)
		(end 62.676024 -276.147276)
		(width 0.14478)
		(layer "In13.Cu")
		(net "M_B_CPU1_SB_CB<1>")
	)
	(segment
		(start 61.656722 -277.166578)
		(end 61.896244 -276.927056)
		(width 0.14478)
		(layer "In13.Cu")
		(net "M_B_CPU1_SB_CB<1>")
	)
	(segment
		(start 64.235584 -274.587716)
		(end 64.53632 -274.587716)
		(width 0.14478)
		(layer "In13.Cu")
		(net "M_B_CPU1_SB_CB<1>")
	)
	(segment
		(start 87.453978 -273.598894)
		(end 87.46236 -273.60372)
		(width 0.0889)
		(layer "In13.Cu")
		(net "M_B_CPU1_SB_CB<1>")
	)
	(segment
		(start 60.63742 -278.486616)
		(end 60.876942 -278.247094)
		(width 0.14478)
		(layer "In13.Cu")
		(net "M_B_CPU1_SB_CB<1>")
	)
	(segment
		(start 52.65674 -279.360122)
		(end 53.506878 -280.21026)
		(width 0.14478)
		(layer "In13.Cu")
		(net "M_B_CPU1_SB_CB<1>")
	)
	(segment
		(start 80.299814 -273.60372)
		(end 80.308196 -273.598894)
		(width 0.0889)
		(layer "In13.Cu")
		(net "M_B_CPU1_SB_CB<1>")
	)
	(segment
		(start 58.207656 -279.360122)
		(end 58.594498 -279.746964)
		(width 0.14478)
		(layer "In13.Cu")
		(net "M_B_CPU1_SB_CB<1>")
	)
	(segment
		(start 65.555622 -273.267678)
		(end 65.795144 -273.028156)
		(width 0.14478)
		(layer "In13.Cu")
		(net "M_B_CPU1_SB_CB<1>")
	)
	(segment
		(start 56.545734 -279.928066)
		(end 56.827928 -280.21026)
		(width 0.14478)
		(layer "In13.Cu")
		(net "M_B_CPU1_SB_CB<1>")
	)
	(segment
		(start 89.367106 -273.541744)
		(end 89.52103 -273.276314)
		(width 0.0889)
		(layer "In13.Cu")
		(net "M_B_CPU1_SB_CB<1>")
	)
	(segment
		(start 65.015364 -273.807936)
		(end 65.3161 -273.807936)
		(width 0.14478)
		(layer "In13.Cu")
		(net "M_B_CPU1_SB_CB<1>")
	)
	(segment
		(start 89.271094 -273.567144)
		(end 89.367106 -273.541744)
		(width 0.0889)
		(layer "In13.Cu")
		(net "M_B_CPU1_SB_CB<1>")
	)
	(segment
		(start 63.216282 -275.607018)
		(end 63.455804 -275.367496)
		(width 0.14478)
		(layer "In13.Cu")
		(net "M_B_CPU1_SB_CB<1>")
	)
	(segment
		(start 60.876942 -278.247094)
		(end 60.876942 -277.946358)
		(width 0.14478)
		(layer "In13.Cu")
		(net "M_B_CPU1_SB_CB<1>")
	)
	(segment
		(start 64.775842 -274.047458)
		(end 65.015364 -273.807936)
		(width 0.14478)
		(layer "In13.Cu")
		(net "M_B_CPU1_SB_CB<1>")
	)
	(segment
		(start 61.656722 -277.467314)
		(end 61.656722 -277.166578)
		(width 0.14478)
		(layer "In13.Cu")
		(net "M_B_CPU1_SB_CB<1>")
	)
	(segment
		(start 82.753962 -273.598894)
		(end 82.762344 -273.60372)
		(width 0.0889)
		(layer "In13.Cu")
		(net "M_B_CPU1_SB_CB<1>")
	)
	(segment
		(start 63.455804 -275.367496)
		(end 63.75654 -275.367496)
		(width 0.14478)
		(layer "In13.Cu")
		(net "M_B_CPU1_SB_CB<1>")
	)
	(segment
		(start 65.3161 -273.807936)
		(end 65.555622 -273.568414)
		(width 0.14478)
		(layer "In13.Cu")
		(net "M_B_CPU1_SB_CB<1>")
	)
	(segment
		(start 54.539134 -279.907746)
		(end 54.841648 -280.21026)
		(width 0.14478)
		(layer "In13.Cu")
		(net "M_B_CPU1_SB_CB<1>")
	)
	(segment
		(start 58.594498 -279.746964)
		(end 58.82513 -279.746964)
		(width 0.14478)
		(layer "In13.Cu")
		(net "M_B_CPU1_SB_CB<1>")
	)
	(segment
		(start 76.458318 -272.209514)
		(end 76.52639 -272.277586)
		(width 0.0889)
		(layer "In13.Cu")
		(net "M_B_CPU1_SB_CB<1>")
	)
	(segment
		(start 62.676024 -276.147276)
		(end 62.97676 -276.147276)
		(width 0.14478)
		(layer "In13.Cu")
		(net "M_B_CPU1_SB_CB<1>")
	)
	(segment
		(start 65.555622 -273.568414)
		(end 65.555622 -273.267678)
		(width 0.14478)
		(layer "In13.Cu")
		(net "M_B_CPU1_SB_CB<1>")
	)
	(segment
		(start 57.983628 -279.360122)
		(end 58.207656 -279.360122)
		(width 0.14478)
		(layer "In13.Cu")
		(net "M_B_CPU1_SB_CB<1>")
	)
	(segment
		(start 83.694016 -273.598894)
		(end 83.702398 -273.60372)
		(width 0.0889)
		(layer "In13.Cu")
		(net "M_B_CPU1_SB_CB<1>")
	)
	(segment
		(start 54.290214 -279.907746)
		(end 54.539134 -279.907746)
		(width 0.14478)
		(layer "In13.Cu")
		(net "M_B_CPU1_SB_CB<1>")
	)
	(segment
		(start 58.82513 -279.746964)
		(end 59.159902 -279.412192)
		(width 0.14478)
		(layer "In13.Cu")
		(net "M_B_CPU1_SB_CB<1>")
	)
	(segment
		(start 85.948012 -273.598894)
		(end 85.948266 -273.598894)
		(width 0.0889)
		(layer "In13.Cu")
		(net "M_B_CPU1_SB_CB<1>")
	)
	(segment
		(start 60.876942 -277.946358)
		(end 61.116464 -277.706836)
		(width 0.14478)
		(layer "In13.Cu")
		(net "M_B_CPU1_SB_CB<1>")
	)
	(segment
		(start 64.53632 -274.587716)
		(end 64.775842 -274.348194)
		(width 0.14478)
		(layer "In13.Cu")
		(net "M_B_CPU1_SB_CB<1>")
	)
	(segment
		(start 85.93963 -273.60372)
		(end 85.948012 -273.598894)
		(width 0.0889)
		(layer "In13.Cu")
		(net "M_B_CPU1_SB_CB<1>")
	)
	(segment
		(start 51.884072 -279.785318)
		(end 51.884072 -279.602692)
		(width 0.14478)
		(layer "In13.Cu")
		(net "M_B_CPU1_SB_CB<1>")
	)
	(segment
		(start 60.097162 -278.726138)
		(end 60.336684 -278.486616)
		(width 0.14478)
		(layer "In13.Cu")
		(net "M_B_CPU1_SB_CB<1>")
	)
	(segment
		(start 82.179668 -273.60372)
		(end 82.18805 -273.598894)
		(width 0.0889)
		(layer "In13.Cu")
		(net "M_B_CPU1_SB_CB<1>")
	)
	(segment
		(start 78.993492 -273.59864)
		(end 79.007208 -273.606514)
		(width 0.0889)
		(layer "In13.Cu")
		(net "M_B_CPU1_SB_CB<1>")
	)
	(segment
		(start 61.116464 -277.706836)
		(end 61.4172 -277.706836)
		(width 0.14478)
		(layer "In13.Cu")
		(net "M_B_CPU1_SB_CB<1>")
	)
	(segment
		(start 77.222604 -272.277586)
		(end 78.467712 -273.522694)
		(width 0.0889)
		(layer "In13.Cu")
		(net "M_B_CPU1_SB_CB<1>")
	)
	(segment
		(start 56.276494 -279.928066)
		(end 56.545734 -279.928066)
		(width 0.14478)
		(layer "In13.Cu")
		(net "M_B_CPU1_SB_CB<1>")
	)
	(segment
		(start 56.827928 -280.21026)
		(end 57.13349 -280.21026)
		(width 0.14478)
		(layer "In13.Cu")
		(net "M_B_CPU1_SB_CB<1>")
	)
	(segment
		(start 88.394032 -273.598894)
		(end 88.402414 -273.60372)
		(width 0.0889)
		(layer "In13.Cu")
		(net "M_B_CPU1_SB_CB<1>")
	)
	(segment
		(start 79.367126 -273.598894)
		(end 79.381858 -273.590258)
		(width 0.0889)
		(layer "In13.Cu")
		(net "M_B_CPU1_SB_CB<1>")
	)
	(segment
		(start 63.996062 -274.827238)
		(end 64.235584 -274.587716)
		(width 0.14478)
		(layer "In13.Cu")
		(net "M_B_CPU1_SB_CB<1>")
	)
	(segment
		(start 54.841648 -280.21026)
		(end 55.9943 -280.21026)
		(width 0.14478)
		(layer "In13.Cu")
		(net "M_B_CPU1_SB_CB<1>")
	)
	(segment
		(start 62.19698 -276.927056)
		(end 62.436502 -276.687534)
		(width 0.14478)
		(layer "In13.Cu")
		(net "M_B_CPU1_SB_CB<1>")
	)
	(segment
		(start 60.336684 -278.486616)
		(end 60.63742 -278.486616)
		(width 0.14478)
		(layer "In13.Cu")
		(net "M_B_CPU1_SB_CB<1>")
	)
	(segment
		(start 57.13349 -280.21026)
		(end 57.983628 -279.360122)
		(width 0.14478)
		(layer "In13.Cu")
		(net "M_B_CPU1_SB_CB<1>")
	)
	(segment
		(start 66.914522 -272.209514)
		(end 75.960986 -272.209514)
		(width 0.14478)
		(layer "In13.Cu")
		(net "M_B_CPU1_SB_CB<1>")
	)
	(segment
		(start 86.879684 -273.60372)
		(end 86.888066 -273.598894)
		(width 0.0889)
		(layer "In13.Cu")
		(net "M_B_CPU1_SB_CB<1>")
	)
	(segment
		(start 66.09588 -273.028156)
		(end 66.914522 -272.209514)
		(width 0.14478)
		(layer "In13.Cu")
		(net "M_B_CPU1_SB_CB<1>")
	)
	(segment
		(start 52.126642 -279.360122)
		(end 52.65674 -279.360122)
		(width 0.14478)
		(layer "In13.Cu")
		(net "M_B_CPU1_SB_CB<1>")
	)
	(segment
		(start 63.216282 -275.907754)
		(end 63.216282 -275.607018)
		(width 0.14478)
		(layer "In13.Cu")
		(net "M_B_CPU1_SB_CB<1>")
	)
	(arc
		(start 80.874108 -273.598894)
		(mid 81.061052 -273.649149)
		(end 81.247996 -273.598894)
		(width 0.0889)
		(layer "In13.Cu")
		(net "M_B_CPU1_SB_CB<1>")
	)
	(arc
		(start 79.933546 -273.598894)
		(mid 80.116051 -273.649371)
		(end 80.299814 -273.60372)
		(width 0.0889)
		(layer "In13.Cu")
		(net "M_B_CPU1_SB_CB<1>")
	)
	(arc
		(start 79.381858 -273.590258)
		(mid 79.658841 -273.522454)
		(end 79.933546 -273.598894)
		(width 0.0889)
		(layer "In13.Cu")
		(net "M_B_CPU1_SB_CB<1>")
	)
	(arc
		(start 85.007958 -273.598894)
		(mid 85.290914 -273.522717)
		(end 85.57387 -273.598894)
		(width 0.0889)
		(layer "In13.Cu")
		(net "M_B_CPU1_SB_CB<1>")
	)
	(arc
		(start 82.762344 -273.60372)
		(mid 82.945852 -273.649214)
		(end 83.128104 -273.598894)
		(width 0.0889)
		(layer "In13.Cu")
		(net "M_B_CPU1_SB_CB<1>")
	)
	(arc
		(start 80.308196 -273.598894)
		(mid 80.591152 -273.522717)
		(end 80.874108 -273.598894)
		(width 0.0889)
		(layer "In13.Cu")
		(net "M_B_CPU1_SB_CB<1>")
	)
	(arc
		(start 83.702398 -273.60372)
		(mid 83.885906 -273.649214)
		(end 84.068158 -273.598894)
		(width 0.0889)
		(layer "In13.Cu")
		(net "M_B_CPU1_SB_CB<1>")
	)
	(arc
		(start 82.18805 -273.598894)
		(mid 82.471006 -273.522717)
		(end 82.753962 -273.598894)
		(width 0.0889)
		(layer "In13.Cu")
		(net "M_B_CPU1_SB_CB<1>")
	)
	(arc
		(start 86.513924 -273.598894)
		(mid 86.696175 -273.649244)
		(end 86.879684 -273.60372)
		(width 0.0889)
		(layer "In13.Cu")
		(net "M_B_CPU1_SB_CB<1>")
	)
	(arc
		(start 78.711552 -273.522694)
		(mid 78.727432 -273.522853)
		(end 78.743302 -273.523456)
		(width 0.0889)
		(layer "In13.Cu")
		(net "M_B_CPU1_SB_CB<1>")
	)
	(arc
		(start 88.402414 -273.60372)
		(mid 88.585922 -273.649214)
		(end 88.768174 -273.598894)
		(width 0.0889)
		(layer "In13.Cu")
		(net "M_B_CPU1_SB_CB<1>")
	)
	(arc
		(start 85.57387 -273.598894)
		(mid 85.756121 -273.649244)
		(end 85.93963 -273.60372)
		(width 0.0889)
		(layer "In13.Cu")
		(net "M_B_CPU1_SB_CB<1>")
	)
	(arc
		(start 84.63407 -273.598894)
		(mid 84.821014 -273.649149)
		(end 85.007958 -273.598894)
		(width 0.0889)
		(layer "In13.Cu")
		(net "M_B_CPU1_SB_CB<1>")
	)
	(arc
		(start 86.888066 -273.598894)
		(mid 87.171022 -273.522717)
		(end 87.453978 -273.598894)
		(width 0.0889)
		(layer "In13.Cu")
		(net "M_B_CPU1_SB_CB<1>")
	)
	(arc
		(start 81.813908 -273.598894)
		(mid 81.996159 -273.649244)
		(end 82.179668 -273.60372)
		(width 0.0889)
		(layer "In13.Cu")
		(net "M_B_CPU1_SB_CB<1>")
	)
	(arc
		(start 85.948266 -273.598894)
		(mid 86.231112 -273.522717)
		(end 86.513924 -273.598894)
		(width 0.0889)
		(layer "In13.Cu")
		(net "M_B_CPU1_SB_CB<1>")
	)
	(arc
		(start 81.247996 -273.598894)
		(mid 81.530952 -273.522717)
		(end 81.813908 -273.598894)
		(width 0.0889)
		(layer "In13.Cu")
		(net "M_B_CPU1_SB_CB<1>")
	)
	(arc
		(start 87.46236 -273.60372)
		(mid 87.645868 -273.649214)
		(end 87.82812 -273.598894)
		(width 0.0889)
		(layer "In13.Cu")
		(net "M_B_CPU1_SB_CB<1>")
	)
	(arc
		(start 83.128104 -273.598894)
		(mid 83.41106 -273.522717)
		(end 83.694016 -273.598894)
		(width 0.0889)
		(layer "In13.Cu")
		(net "M_B_CPU1_SB_CB<1>")
	)
	(arc
		(start 79.007208 -273.606514)
		(mid 79.188138 -273.648992)
		(end 79.367126 -273.598894)
		(width 0.0889)
		(layer "In13.Cu")
		(net "M_B_CPU1_SB_CB<1>")
	)
	(arc
		(start 87.82812 -273.598894)
		(mid 88.111076 -273.522717)
		(end 88.394032 -273.598894)
		(width 0.0889)
		(layer "In13.Cu")
		(net "M_B_CPU1_SB_CB<1>")
	)
	(arc
		(start 88.768174 -273.598894)
		(mid 89.015887 -273.523674)
		(end 89.271094 -273.567144)
		(width 0.0889)
		(layer "In13.Cu")
		(net "M_B_CPU1_SB_CB<1>")
	)
	(arc
		(start 84.068158 -273.598894)
		(mid 84.351114 -273.522717)
		(end 84.63407 -273.598894)
		(width 0.0889)
		(layer "In13.Cu")
		(net "M_B_CPU1_SB_CB<1>")
	)
	(arc
		(start 78.743302 -273.523456)
		(mid 78.872806 -273.54637)
		(end 78.993492 -273.59864)
		(width 0.0889)
		(layer "In13.Cu")
		(net "M_B_CPU1_SB_CB<1>")
	)
	(segment
		(start 88.577928 -272.20037)
		(end 88.111076 -272.466308)
		(width 0.10668)
		(layer "F.Cu")
		(net "M_B_CPU1_SB_CB<0>")
	)
	(segment
		(start 55.988458 -278.671528)
		(end 56.149494 -278.832564)
		(width 0.14478)
		(layer "In13.Cu")
		(net "M_B_CPU1_SB_CB<0>")
	)
	(segment
		(start 58.999882 -277.529544)
		(end 58.999882 -277.886668)
		(width 0.14478)
		(layer "In13.Cu")
		(net "M_B_CPU1_SB_CB<0>")
	)
	(segment
		(start 81.344008 -272.788888)
		(end 81.35239 -272.793714)
		(width 0.0889)
		(layer "In13.Cu")
		(net "M_B_CPU1_SB_CB<0>")
	)
	(segment
		(start 57.653174 -278.125936)
		(end 57.607454 -278.080216)
		(width 0.14478)
		(layer "In13.Cu")
		(net "M_B_CPU1_SB_CB<0>")
	)
	(segment
		(start 78.879446 -272.799048)
		(end 78.897734 -272.788634)
		(width 0.0889)
		(layer "In13.Cu")
		(net "M_B_CPU1_SB_CB<0>")
	)
	(segment
		(start 80.39354 -272.782792)
		(end 80.403954 -272.788888)
		(width 0.0889)
		(layer "In13.Cu")
		(net "M_B_CPU1_SB_CB<0>")
	)
	(segment
		(start 83.589622 -272.793714)
		(end 83.598004 -272.788888)
		(width 0.0889)
		(layer "In13.Cu")
		(net "M_B_CPU1_SB_CB<0>")
	)
	(segment
		(start 86.044024 -272.788888)
		(end 86.052406 -272.793714)
		(width 0.0889)
		(layer "In13.Cu")
		(net "M_B_CPU1_SB_CB<0>")
	)
	(segment
		(start 54.714902 -278.18842)
		(end 54.875938 -278.349456)
		(width 0.14478)
		(layer "In13.Cu")
		(net "M_B_CPU1_SB_CB<0>")
	)
	(segment
		(start 52.412392 -277.670006)
		(end 52.670456 -277.92807)
		(width 0.14478)
		(layer "In13.Cu")
		(net "M_B_CPU1_SB_CB<0>")
	)
	(segment
		(start 59.695842 -277.384764)
		(end 59.96178 -277.384764)
		(width 0.14478)
		(layer "In13.Cu")
		(net "M_B_CPU1_SB_CB<0>")
	)
	(segment
		(start 52.87518 -277.928324)
		(end 53.01488 -277.788624)
		(width 0.14478)
		(layer "In13.Cu")
		(net "M_B_CPU1_SB_CB<0>")
	)
	(segment
		(start 53.26507 -278.522684)
		(end 53.57495 -278.832564)
		(width 0.14478)
		(layer "In13.Cu")
		(net "M_B_CPU1_SB_CB<0>")
	)
	(segment
		(start 55.593234 -278.18842)
		(end 55.827422 -278.18842)
		(width 0.14478)
		(layer "In13.Cu")
		(net "M_B_CPU1_SB_CB<0>")
	)
	(segment
		(start 56.383682 -278.832564)
		(end 56.705754 -278.510492)
		(width 0.14478)
		(layer "In13.Cu")
		(net "M_B_CPU1_SB_CB<0>")
	)
	(segment
		(start 57.997344 -277.690326)
		(end 58.043064 -277.736046)
		(width 0.14478)
		(layer "In13.Cu")
		(net "M_B_CPU1_SB_CB<0>")
	)
	(segment
		(start 56.149494 -278.832564)
		(end 56.383682 -278.832564)
		(width 0.14478)
		(layer "In13.Cu")
		(net "M_B_CPU1_SB_CB<0>")
	)
	(segment
		(start 87.956898 -272.731738)
		(end 88.111076 -272.466308)
		(width 0.0889)
		(layer "In13.Cu")
		(net "M_B_CPU1_SB_CB<0>")
	)
	(segment
		(start 53.405024 -277.974044)
		(end 53.40477 -278.17826)
		(width 0.14478)
		(layer "In13.Cu")
		(net "M_B_CPU1_SB_CB<0>")
	)
	(segment
		(start 87.860632 -272.757138)
		(end 87.956898 -272.731738)
		(width 0.0889)
		(layer "In13.Cu")
		(net "M_B_CPU1_SB_CB<0>")
	)
	(segment
		(start 66.04635 -271.300194)
		(end 75.960986 -271.300194)
		(width 0.14478)
		(layer "In13.Cu")
		(net "M_B_CPU1_SB_CB<0>")
	)
	(segment
		(start 55.432198 -278.671528)
		(end 55.432198 -278.349456)
		(width 0.14478)
		(layer "In13.Cu")
		(net "M_B_CPU1_SB_CB<0>")
	)
	(segment
		(start 78.523338 -272.788888)
		(end 78.523592 -272.788888)
		(width 0.0889)
		(layer "In13.Cu")
		(net "M_B_CPU1_SB_CB<0>")
	)
	(segment
		(start 55.988458 -278.349456)
		(end 55.988458 -278.671528)
		(width 0.14478)
		(layer "In13.Cu")
		(net "M_B_CPU1_SB_CB<0>")
	)
	(segment
		(start 52.093368 -277.670006)
		(end 52.412392 -277.670006)
		(width 0.14478)
		(layer "In13.Cu")
		(net "M_B_CPU1_SB_CB<0>")
	)
	(segment
		(start 84.529676 -272.793714)
		(end 84.538058 -272.788888)
		(width 0.0889)
		(layer "In13.Cu")
		(net "M_B_CPU1_SB_CB<0>")
	)
	(segment
		(start 85.10397 -272.788888)
		(end 85.112352 -272.793714)
		(width 0.0889)
		(layer "In13.Cu")
		(net "M_B_CPU1_SB_CB<0>")
	)
	(segment
		(start 51.884072 -277.879302)
		(end 52.093368 -277.670006)
		(width 0.14478)
		(layer "In13.Cu")
		(net "M_B_CPU1_SB_CB<0>")
	)
	(segment
		(start 53.40477 -278.17826)
		(end 53.26507 -278.31796)
		(width 0.14478)
		(layer "In13.Cu")
		(net "M_B_CPU1_SB_CB<0>")
	)
	(segment
		(start 59.96178 -277.384764)
		(end 66.04635 -271.300194)
		(width 0.14478)
		(layer "In13.Cu")
		(net "M_B_CPU1_SB_CB<0>")
	)
	(segment
		(start 57.79262 -277.690326)
		(end 57.997344 -277.690326)
		(width 0.14478)
		(layer "In13.Cu")
		(net "M_B_CPU1_SB_CB<0>")
	)
	(segment
		(start 57.473342 -278.510492)
		(end 57.653174 -278.33066)
		(width 0.14478)
		(layer "In13.Cu")
		(net "M_B_CPU1_SB_CB<0>")
	)
	(segment
		(start 58.043064 -277.736046)
		(end 58.247788 -277.736046)
		(width 0.14478)
		(layer "In13.Cu")
		(net "M_B_CPU1_SB_CB<0>")
	)
	(segment
		(start 53.26507 -278.31796)
		(end 53.26507 -278.522684)
		(width 0.14478)
		(layer "In13.Cu")
		(net "M_B_CPU1_SB_CB<0>")
	)
	(segment
		(start 53.57495 -278.832564)
		(end 54.158642 -278.832564)
		(width 0.14478)
		(layer "In13.Cu")
		(net "M_B_CPU1_SB_CB<0>")
	)
	(segment
		(start 58.59907 -277.384764)
		(end 58.855102 -277.384764)
		(width 0.14478)
		(layer "In13.Cu")
		(net "M_B_CPU1_SB_CB<0>")
	)
	(segment
		(start 54.480714 -278.18842)
		(end 54.714902 -278.18842)
		(width 0.14478)
		(layer "In13.Cu")
		(net "M_B_CPU1_SB_CB<0>")
	)
	(segment
		(start 76.399898 -271.300194)
		(end 76.88707 -271.787366)
		(width 0.0889)
		(layer "In13.Cu")
		(net "M_B_CPU1_SB_CB<0>")
	)
	(segment
		(start 56.705754 -278.510492)
		(end 57.473342 -278.510492)
		(width 0.14478)
		(layer "In13.Cu")
		(net "M_B_CPU1_SB_CB<0>")
	)
	(segment
		(start 52.670456 -277.92807)
		(end 52.87518 -277.928324)
		(width 0.14478)
		(layer "In13.Cu")
		(net "M_B_CPU1_SB_CB<0>")
	)
	(segment
		(start 58.247788 -277.736046)
		(end 58.59907 -277.384764)
		(width 0.14478)
		(layer "In13.Cu")
		(net "M_B_CPU1_SB_CB<0>")
	)
	(segment
		(start 78.897734 -272.788634)
		(end 78.903322 -272.785332)
		(width 0.0889)
		(layer "In13.Cu")
		(net "M_B_CPU1_SB_CB<0>")
	)
	(segment
		(start 55.036974 -278.832564)
		(end 55.271162 -278.832564)
		(width 0.14478)
		(layer "In13.Cu")
		(net "M_B_CPU1_SB_CB<0>")
	)
	(segment
		(start 57.607454 -278.080216)
		(end 57.607454 -277.875492)
		(width 0.14478)
		(layer "In13.Cu")
		(net "M_B_CPU1_SB_CB<0>")
	)
	(segment
		(start 54.319678 -278.671528)
		(end 54.319678 -278.349456)
		(width 0.14478)
		(layer "In13.Cu")
		(net "M_B_CPU1_SB_CB<0>")
	)
	(segment
		(start 79.463138 -272.788888)
		(end 79.47152 -272.793714)
		(width 0.0889)
		(layer "In13.Cu")
		(net "M_B_CPU1_SB_CB<0>")
	)
	(segment
		(start 57.607454 -277.875492)
		(end 57.79262 -277.690326)
		(width 0.14478)
		(layer "In13.Cu")
		(net "M_B_CPU1_SB_CB<0>")
	)
	(segment
		(start 54.319678 -278.349456)
		(end 54.480714 -278.18842)
		(width 0.14478)
		(layer "In13.Cu")
		(net "M_B_CPU1_SB_CB<0>")
	)
	(segment
		(start 53.219604 -277.788624)
		(end 53.405024 -277.974044)
		(width 0.14478)
		(layer "In13.Cu")
		(net "M_B_CPU1_SB_CB<0>")
	)
	(segment
		(start 53.01488 -277.788624)
		(end 53.219604 -277.788624)
		(width 0.14478)
		(layer "In13.Cu")
		(net "M_B_CPU1_SB_CB<0>")
	)
	(segment
		(start 57.653174 -278.33066)
		(end 57.653174 -278.125936)
		(width 0.14478)
		(layer "In13.Cu")
		(net "M_B_CPU1_SB_CB<0>")
	)
	(segment
		(start 80.769714 -272.793714)
		(end 80.778096 -272.788888)
		(width 0.0889)
		(layer "In13.Cu")
		(net "M_B_CPU1_SB_CB<0>")
	)
	(segment
		(start 58.999882 -277.886668)
		(end 59.144662 -278.031448)
		(width 0.14478)
		(layer "In13.Cu")
		(net "M_B_CPU1_SB_CB<0>")
	)
	(segment
		(start 59.551062 -277.529544)
		(end 59.695842 -277.384764)
		(width 0.14478)
		(layer "In13.Cu")
		(net "M_B_CPU1_SB_CB<0>")
	)
	(segment
		(start 54.875938 -278.349456)
		(end 54.875938 -278.671528)
		(width 0.14478)
		(layer "In13.Cu")
		(net "M_B_CPU1_SB_CB<0>")
	)
	(segment
		(start 59.406282 -278.031448)
		(end 59.551062 -277.886668)
		(width 0.14478)
		(layer "In13.Cu")
		(net "M_B_CPU1_SB_CB<0>")
	)
	(segment
		(start 55.432198 -278.349456)
		(end 55.593234 -278.18842)
		(width 0.14478)
		(layer "In13.Cu")
		(net "M_B_CPU1_SB_CB<0>")
	)
	(segment
		(start 59.551062 -277.886668)
		(end 59.551062 -277.529544)
		(width 0.14478)
		(layer "In13.Cu")
		(net "M_B_CPU1_SB_CB<0>")
	)
	(segment
		(start 77.504036 -271.787366)
		(end 78.446884 -272.730214)
		(width 0.0889)
		(layer "In13.Cu")
		(net "M_B_CPU1_SB_CB<0>")
	)
	(segment
		(start 58.855102 -277.384764)
		(end 58.999882 -277.529544)
		(width 0.14478)
		(layer "In13.Cu")
		(net "M_B_CPU1_SB_CB<0>")
	)
	(segment
		(start 55.271162 -278.832564)
		(end 55.432198 -278.671528)
		(width 0.14478)
		(layer "In13.Cu")
		(net "M_B_CPU1_SB_CB<0>")
	)
	(segment
		(start 59.144662 -278.031448)
		(end 59.406282 -278.031448)
		(width 0.14478)
		(layer "In13.Cu")
		(net "M_B_CPU1_SB_CB<0>")
	)
	(segment
		(start 76.88707 -271.787366)
		(end 77.504036 -271.787366)
		(width 0.0889)
		(layer "In13.Cu")
		(net "M_B_CPU1_SB_CB<0>")
	)
	(segment
		(start 75.960986 -271.300194)
		(end 76.399898 -271.300194)
		(width 0.0889)
		(layer "In13.Cu")
		(net "M_B_CPU1_SB_CB<0>")
	)
	(segment
		(start 55.827422 -278.18842)
		(end 55.988458 -278.349456)
		(width 0.14478)
		(layer "In13.Cu")
		(net "M_B_CPU1_SB_CB<0>")
	)
	(segment
		(start 54.158642 -278.832564)
		(end 54.319678 -278.671528)
		(width 0.14478)
		(layer "In13.Cu")
		(net "M_B_CPU1_SB_CB<0>")
	)
	(segment
		(start 54.875938 -278.671528)
		(end 55.036974 -278.832564)
		(width 0.14478)
		(layer "In13.Cu")
		(net "M_B_CPU1_SB_CB<0>")
	)
	(segment
		(start 51.884072 -278.085296)
		(end 51.884072 -277.879302)
		(width 0.14478)
		(layer "In13.Cu")
		(net "M_B_CPU1_SB_CB<0>")
	)
	(arc
		(start 86.052406 -272.793714)
		(mid 86.235914 -272.839208)
		(end 86.418166 -272.788888)
		(width 0.0889)
		(layer "In13.Cu")
		(net "M_B_CPU1_SB_CB<0>")
	)
	(arc
		(start 80.778096 -272.788888)
		(mid 81.061052 -272.712711)
		(end 81.344008 -272.788888)
		(width 0.0889)
		(layer "In13.Cu")
		(net "M_B_CPU1_SB_CB<0>")
	)
	(arc
		(start 83.598004 -272.788888)
		(mid 83.88096 -272.712711)
		(end 84.163916 -272.788888)
		(width 0.0889)
		(layer "In13.Cu")
		(net "M_B_CPU1_SB_CB<0>")
	)
	(arc
		(start 78.903322 -272.785332)
		(mid 79.183711 -272.712663)
		(end 79.463138 -272.788888)
		(width 0.0889)
		(layer "In13.Cu")
		(net "M_B_CPU1_SB_CB<0>")
	)
	(arc
		(start 84.538058 -272.788888)
		(mid 84.821014 -272.712711)
		(end 85.10397 -272.788888)
		(width 0.0889)
		(layer "In13.Cu")
		(net "M_B_CPU1_SB_CB<0>")
	)
	(arc
		(start 80.403954 -272.788888)
		(mid 80.586205 -272.839238)
		(end 80.769714 -272.793714)
		(width 0.0889)
		(layer "In13.Cu")
		(net "M_B_CPU1_SB_CB<0>")
	)
	(arc
		(start 81.71815 -272.788888)
		(mid 82.001106 -272.712711)
		(end 82.284062 -272.788888)
		(width 0.0889)
		(layer "In13.Cu")
		(net "M_B_CPU1_SB_CB<0>")
	)
	(arc
		(start 82.65795 -272.788888)
		(mid 82.940906 -272.712711)
		(end 83.223862 -272.788888)
		(width 0.0889)
		(layer "In13.Cu")
		(net "M_B_CPU1_SB_CB<0>")
	)
	(arc
		(start 78.523592 -272.788888)
		(mid 78.70022 -272.839121)
		(end 78.879446 -272.799048)
		(width 0.0889)
		(layer "In13.Cu")
		(net "M_B_CPU1_SB_CB<0>")
	)
	(arc
		(start 85.112352 -272.793714)
		(mid 85.29586 -272.839208)
		(end 85.478112 -272.788888)
		(width 0.0889)
		(layer "In13.Cu")
		(net "M_B_CPU1_SB_CB<0>")
	)
	(arc
		(start 82.284062 -272.788888)
		(mid 82.471006 -272.839143)
		(end 82.65795 -272.788888)
		(width 0.0889)
		(layer "In13.Cu")
		(net "M_B_CPU1_SB_CB<0>")
	)
	(arc
		(start 83.223862 -272.788888)
		(mid 83.406113 -272.839238)
		(end 83.589622 -272.793714)
		(width 0.0889)
		(layer "In13.Cu")
		(net "M_B_CPU1_SB_CB<0>")
	)
	(arc
		(start 86.418166 -272.788888)
		(mid 86.701122 -272.712711)
		(end 86.984078 -272.788888)
		(width 0.0889)
		(layer "In13.Cu")
		(net "M_B_CPU1_SB_CB<0>")
	)
	(arc
		(start 87.357966 -272.788888)
		(mid 87.605562 -272.71371)
		(end 87.860632 -272.757138)
		(width 0.0889)
		(layer "In13.Cu")
		(net "M_B_CPU1_SB_CB<0>")
	)
	(arc
		(start 84.163916 -272.788888)
		(mid 84.346167 -272.839238)
		(end 84.529676 -272.793714)
		(width 0.0889)
		(layer "In13.Cu")
		(net "M_B_CPU1_SB_CB<0>")
	)
	(arc
		(start 85.478112 -272.788888)
		(mid 85.761068 -272.712711)
		(end 86.044024 -272.788888)
		(width 0.0889)
		(layer "In13.Cu")
		(net "M_B_CPU1_SB_CB<0>")
	)
	(arc
		(start 81.35239 -272.793714)
		(mid 81.535898 -272.839208)
		(end 81.71815 -272.788888)
		(width 0.0889)
		(layer "In13.Cu")
		(net "M_B_CPU1_SB_CB<0>")
	)
	(arc
		(start 78.446884 -272.730214)
		(mid 78.483211 -272.762027)
		(end 78.523338 -272.788888)
		(width 0.0889)
		(layer "In13.Cu")
		(net "M_B_CPU1_SB_CB<0>")
	)
	(arc
		(start 79.47152 -272.793714)
		(mid 79.655282 -272.83933)
		(end 79.837788 -272.788888)
		(width 0.0889)
		(layer "In13.Cu")
		(net "M_B_CPU1_SB_CB<0>")
	)
	(arc
		(start 86.984078 -272.788888)
		(mid 87.171022 -272.839143)
		(end 87.357966 -272.788888)
		(width 0.0889)
		(layer "In13.Cu")
		(net "M_B_CPU1_SB_CB<0>")
	)
	(arc
		(start 79.837788 -272.788888)
		(mid 80.114855 -272.712617)
		(end 80.39354 -272.782792)
		(width 0.0889)
		(layer "In13.Cu")
		(net "M_B_CPU1_SB_CB<0>")
	)
	(segment
		(start 88.577928 -264.10031)
		(end 88.111076 -264.366248)
		(width 0.10668)
		(layer "F.Cu")
		(net "M_B_CPU1_SB_CA<6>")
	)
	(segment
		(start 87.956898 -264.631678)
		(end 88.111076 -264.366248)
		(width 0.0889)
		(layer "In13.Cu")
		(net "M_B_CPU1_SB_CA<6>")
	)
	(segment
		(start 57.467754 -266.081764)
		(end 57.789064 -265.760454)
		(width 0.14478)
		(layer "In13.Cu")
		(net "M_B_CPU1_SB_CA<6>")
	)
	(segment
		(start 75.960986 -264.619994)
		(end 76.261722 -264.619994)
		(width 0.0889)
		(layer "In13.Cu")
		(net "M_B_CPU1_SB_CA<6>")
	)
	(segment
		(start 85.10397 -264.688828)
		(end 85.112352 -264.693654)
		(width 0.0889)
		(layer "In13.Cu")
		(net "M_B_CPU1_SB_CA<6>")
	)
	(segment
		(start 81.344008 -264.688828)
		(end 81.35239 -264.693654)
		(width 0.0889)
		(layer "In13.Cu")
		(net "M_B_CPU1_SB_CA<6>")
	)
	(segment
		(start 54.175406 -265.597894)
		(end 54.175406 -265.91133)
		(width 0.14478)
		(layer "In13.Cu")
		(net "M_B_CPU1_SB_CA<6>")
	)
	(segment
		(start 54.030626 -265.453114)
		(end 54.175406 -265.597894)
		(width 0.14478)
		(layer "In13.Cu")
		(net "M_B_CPU1_SB_CA<6>")
	)
	(segment
		(start 82.284062 -264.688828)
		(end 82.292444 -264.693654)
		(width 0.0889)
		(layer "In13.Cu")
		(net "M_B_CPU1_SB_CA<6>")
	)
	(segment
		(start 78.879446 -264.698988)
		(end 78.897734 -264.688574)
		(width 0.0889)
		(layer "In13.Cu")
		(net "M_B_CPU1_SB_CA<6>")
	)
	(segment
		(start 79.463138 -264.688828)
		(end 79.47152 -264.693654)
		(width 0.0889)
		(layer "In13.Cu")
		(net "M_B_CPU1_SB_CA<6>")
	)
	(segment
		(start 53.769006 -265.453114)
		(end 54.030626 -265.453114)
		(width 0.14478)
		(layer "In13.Cu")
		(net "M_B_CPU1_SB_CA<6>")
	)
	(segment
		(start 52.666646 -265.453114)
		(end 52.928266 -265.453114)
		(width 0.14478)
		(layer "In13.Cu")
		(net "M_B_CPU1_SB_CA<6>")
	)
	(segment
		(start 58.580274 -266.081764)
		(end 58.901584 -265.760454)
		(width 0.14478)
		(layer "In13.Cu")
		(net "M_B_CPU1_SB_CA<6>")
	)
	(segment
		(start 53.479446 -266.05611)
		(end 53.624226 -265.91133)
		(width 0.14478)
		(layer "In13.Cu")
		(net "M_B_CPU1_SB_CA<6>")
	)
	(segment
		(start 80.769714 -264.693654)
		(end 80.778096 -264.688828)
		(width 0.0889)
		(layer "In13.Cu")
		(net "M_B_CPU1_SB_CA<6>")
	)
	(segment
		(start 80.39354 -264.682732)
		(end 80.403954 -264.688828)
		(width 0.0889)
		(layer "In13.Cu")
		(net "M_B_CPU1_SB_CA<6>")
	)
	(segment
		(start 52.928266 -265.453114)
		(end 53.073046 -265.597894)
		(width 0.14478)
		(layer "In13.Cu")
		(net "M_B_CPU1_SB_CA<6>")
	)
	(segment
		(start 51.884072 -266.185396)
		(end 52.013358 -266.05611)
		(width 0.14478)
		(layer "In13.Cu")
		(net "M_B_CPU1_SB_CA<6>")
	)
	(segment
		(start 52.013358 -266.05611)
		(end 52.377086 -266.05611)
		(width 0.14478)
		(layer "In13.Cu")
		(net "M_B_CPU1_SB_CA<6>")
	)
	(segment
		(start 59.692794 -266.081764)
		(end 61.154564 -264.619994)
		(width 0.14478)
		(layer "In13.Cu")
		(net "M_B_CPU1_SB_CA<6>")
	)
	(segment
		(start 57.789064 -265.760454)
		(end 58.024014 -265.760454)
		(width 0.14478)
		(layer "In13.Cu")
		(net "M_B_CPU1_SB_CA<6>")
	)
	(segment
		(start 56.120284 -266.081764)
		(end 56.355234 -266.081764)
		(width 0.14478)
		(layer "In13.Cu")
		(net "M_B_CPU1_SB_CA<6>")
	)
	(segment
		(start 58.345324 -266.081764)
		(end 58.580274 -266.081764)
		(width 0.14478)
		(layer "In13.Cu")
		(net "M_B_CPU1_SB_CA<6>")
	)
	(segment
		(start 55.01132 -265.760454)
		(end 55.798974 -265.760454)
		(width 0.14478)
		(layer "In13.Cu")
		(net "M_B_CPU1_SB_CA<6>")
	)
	(segment
		(start 76.54417 -264.337546)
		(end 78.154276 -264.337546)
		(width 0.0889)
		(layer "In13.Cu")
		(net "M_B_CPU1_SB_CA<6>")
	)
	(segment
		(start 84.529676 -264.693654)
		(end 84.538058 -264.688828)
		(width 0.0889)
		(layer "In13.Cu")
		(net "M_B_CPU1_SB_CA<6>")
	)
	(segment
		(start 57.232804 -266.081764)
		(end 57.467754 -266.081764)
		(width 0.14478)
		(layer "In13.Cu")
		(net "M_B_CPU1_SB_CA<6>")
	)
	(segment
		(start 56.355234 -266.081764)
		(end 56.676544 -265.760454)
		(width 0.14478)
		(layer "In13.Cu")
		(net "M_B_CPU1_SB_CA<6>")
	)
	(segment
		(start 52.377086 -266.05611)
		(end 52.521866 -265.91133)
		(width 0.14478)
		(layer "In13.Cu")
		(net "M_B_CPU1_SB_CA<6>")
	)
	(segment
		(start 56.676544 -265.760454)
		(end 56.911494 -265.760454)
		(width 0.14478)
		(layer "In13.Cu")
		(net "M_B_CPU1_SB_CA<6>")
	)
	(segment
		(start 55.798974 -265.760454)
		(end 56.120284 -266.081764)
		(width 0.14478)
		(layer "In13.Cu")
		(net "M_B_CPU1_SB_CA<6>")
	)
	(segment
		(start 58.024014 -265.760454)
		(end 58.345324 -266.081764)
		(width 0.14478)
		(layer "In13.Cu")
		(net "M_B_CPU1_SB_CA<6>")
	)
	(segment
		(start 61.154564 -264.619994)
		(end 75.960986 -264.619994)
		(width 0.14478)
		(layer "In13.Cu")
		(net "M_B_CPU1_SB_CA<6>")
	)
	(segment
		(start 54.175406 -265.91133)
		(end 54.320186 -266.05611)
		(width 0.14478)
		(layer "In13.Cu")
		(net "M_B_CPU1_SB_CA<6>")
	)
	(segment
		(start 86.044024 -264.688828)
		(end 86.052406 -264.693654)
		(width 0.0889)
		(layer "In13.Cu")
		(net "M_B_CPU1_SB_CA<6>")
	)
	(segment
		(start 76.261722 -264.619994)
		(end 76.54417 -264.337546)
		(width 0.0889)
		(layer "In13.Cu")
		(net "M_B_CPU1_SB_CA<6>")
	)
	(segment
		(start 59.457844 -266.081764)
		(end 59.692794 -266.081764)
		(width 0.14478)
		(layer "In13.Cu")
		(net "M_B_CPU1_SB_CA<6>")
	)
	(segment
		(start 52.521866 -265.597894)
		(end 52.666646 -265.453114)
		(width 0.14478)
		(layer "In13.Cu")
		(net "M_B_CPU1_SB_CA<6>")
	)
	(segment
		(start 53.217826 -266.05611)
		(end 53.479446 -266.05611)
		(width 0.14478)
		(layer "In13.Cu")
		(net "M_B_CPU1_SB_CA<6>")
	)
	(segment
		(start 56.911494 -265.760454)
		(end 57.232804 -266.081764)
		(width 0.14478)
		(layer "In13.Cu")
		(net "M_B_CPU1_SB_CA<6>")
	)
	(segment
		(start 52.521866 -265.91133)
		(end 52.521866 -265.597894)
		(width 0.14478)
		(layer "In13.Cu")
		(net "M_B_CPU1_SB_CA<6>")
	)
	(segment
		(start 54.320186 -266.05611)
		(end 54.715664 -266.05611)
		(width 0.14478)
		(layer "In13.Cu")
		(net "M_B_CPU1_SB_CA<6>")
	)
	(segment
		(start 53.073046 -265.91133)
		(end 53.217826 -266.05611)
		(width 0.14478)
		(layer "In13.Cu")
		(net "M_B_CPU1_SB_CA<6>")
	)
	(segment
		(start 59.136534 -265.760454)
		(end 59.457844 -266.081764)
		(width 0.14478)
		(layer "In13.Cu")
		(net "M_B_CPU1_SB_CA<6>")
	)
	(segment
		(start 54.715664 -266.05611)
		(end 55.01132 -265.760454)
		(width 0.14478)
		(layer "In13.Cu")
		(net "M_B_CPU1_SB_CA<6>")
	)
	(segment
		(start 78.154276 -264.337546)
		(end 78.446884 -264.630154)
		(width 0.0889)
		(layer "In13.Cu")
		(net "M_B_CPU1_SB_CA<6>")
	)
	(segment
		(start 53.624226 -265.597894)
		(end 53.769006 -265.453114)
		(width 0.14478)
		(layer "In13.Cu")
		(net "M_B_CPU1_SB_CA<6>")
	)
	(segment
		(start 53.624226 -265.91133)
		(end 53.624226 -265.597894)
		(width 0.14478)
		(layer "In13.Cu")
		(net "M_B_CPU1_SB_CA<6>")
	)
	(segment
		(start 78.897734 -264.688574)
		(end 78.903322 -264.685272)
		(width 0.0889)
		(layer "In13.Cu")
		(net "M_B_CPU1_SB_CA<6>")
	)
	(segment
		(start 53.073046 -265.597894)
		(end 53.073046 -265.91133)
		(width 0.14478)
		(layer "In13.Cu")
		(net "M_B_CPU1_SB_CA<6>")
	)
	(segment
		(start 78.523338 -264.688828)
		(end 78.523592 -264.688828)
		(width 0.0889)
		(layer "In13.Cu")
		(net "M_B_CPU1_SB_CA<6>")
	)
	(segment
		(start 58.901584 -265.760454)
		(end 59.136534 -265.760454)
		(width 0.14478)
		(layer "In13.Cu")
		(net "M_B_CPU1_SB_CA<6>")
	)
	(segment
		(start 87.860632 -264.657078)
		(end 87.956898 -264.631678)
		(width 0.0889)
		(layer "In13.Cu")
		(net "M_B_CPU1_SB_CA<6>")
	)
	(arc
		(start 80.403954 -264.688828)
		(mid 80.586205 -264.739178)
		(end 80.769714 -264.693654)
		(width 0.0889)
		(layer "In13.Cu")
		(net "M_B_CPU1_SB_CA<6>")
	)
	(arc
		(start 84.163916 -264.688828)
		(mid 84.346167 -264.739178)
		(end 84.529676 -264.693654)
		(width 0.0889)
		(layer "In13.Cu")
		(net "M_B_CPU1_SB_CA<6>")
	)
	(arc
		(start 83.598004 -264.688828)
		(mid 83.88096 -264.612651)
		(end 84.163916 -264.688828)
		(width 0.0889)
		(layer "In13.Cu")
		(net "M_B_CPU1_SB_CA<6>")
	)
	(arc
		(start 79.837788 -264.688828)
		(mid 80.114855 -264.612557)
		(end 80.39354 -264.682732)
		(width 0.0889)
		(layer "In13.Cu")
		(net "M_B_CPU1_SB_CA<6>")
	)
	(arc
		(start 82.292444 -264.693654)
		(mid 82.475952 -264.739148)
		(end 82.658204 -264.688828)
		(width 0.0889)
		(layer "In13.Cu")
		(net "M_B_CPU1_SB_CA<6>")
	)
	(arc
		(start 85.112352 -264.693654)
		(mid 85.29586 -264.739148)
		(end 85.478112 -264.688828)
		(width 0.0889)
		(layer "In13.Cu")
		(net "M_B_CPU1_SB_CA<6>")
	)
	(arc
		(start 86.418166 -264.688828)
		(mid 86.701122 -264.612651)
		(end 86.984078 -264.688828)
		(width 0.0889)
		(layer "In13.Cu")
		(net "M_B_CPU1_SB_CA<6>")
	)
	(arc
		(start 86.052406 -264.693654)
		(mid 86.235914 -264.739148)
		(end 86.418166 -264.688828)
		(width 0.0889)
		(layer "In13.Cu")
		(net "M_B_CPU1_SB_CA<6>")
	)
	(arc
		(start 81.71815 -264.688828)
		(mid 82.001106 -264.612651)
		(end 82.284062 -264.688828)
		(width 0.0889)
		(layer "In13.Cu")
		(net "M_B_CPU1_SB_CA<6>")
	)
	(arc
		(start 83.224116 -264.688828)
		(mid 83.41106 -264.739083)
		(end 83.598004 -264.688828)
		(width 0.0889)
		(layer "In13.Cu")
		(net "M_B_CPU1_SB_CA<6>")
	)
	(arc
		(start 82.658204 -264.688828)
		(mid 82.94116 -264.612651)
		(end 83.224116 -264.688828)
		(width 0.0889)
		(layer "In13.Cu")
		(net "M_B_CPU1_SB_CA<6>")
	)
	(arc
		(start 81.35239 -264.693654)
		(mid 81.535898 -264.739148)
		(end 81.71815 -264.688828)
		(width 0.0889)
		(layer "In13.Cu")
		(net "M_B_CPU1_SB_CA<6>")
	)
	(arc
		(start 80.778096 -264.688828)
		(mid 81.061052 -264.612651)
		(end 81.344008 -264.688828)
		(width 0.0889)
		(layer "In13.Cu")
		(net "M_B_CPU1_SB_CA<6>")
	)
	(arc
		(start 78.523592 -264.688828)
		(mid 78.70022 -264.739061)
		(end 78.879446 -264.698988)
		(width 0.0889)
		(layer "In13.Cu")
		(net "M_B_CPU1_SB_CA<6>")
	)
	(arc
		(start 84.538058 -264.688828)
		(mid 84.821014 -264.612651)
		(end 85.10397 -264.688828)
		(width 0.0889)
		(layer "In13.Cu")
		(net "M_B_CPU1_SB_CA<6>")
	)
	(arc
		(start 78.903322 -264.685272)
		(mid 79.183711 -264.612603)
		(end 79.463138 -264.688828)
		(width 0.0889)
		(layer "In13.Cu")
		(net "M_B_CPU1_SB_CA<6>")
	)
	(arc
		(start 79.47152 -264.693654)
		(mid 79.655282 -264.73927)
		(end 79.837788 -264.688828)
		(width 0.0889)
		(layer "In13.Cu")
		(net "M_B_CPU1_SB_CA<6>")
	)
	(arc
		(start 85.478112 -264.688828)
		(mid 85.761068 -264.612651)
		(end 86.044024 -264.688828)
		(width 0.0889)
		(layer "In13.Cu")
		(net "M_B_CPU1_SB_CA<6>")
	)
	(arc
		(start 78.446884 -264.630154)
		(mid 78.483211 -264.661967)
		(end 78.523338 -264.688828)
		(width 0.0889)
		(layer "In13.Cu")
		(net "M_B_CPU1_SB_CA<6>")
	)
	(arc
		(start 87.357966 -264.688828)
		(mid 87.605562 -264.61365)
		(end 87.860632 -264.657078)
		(width 0.0889)
		(layer "In13.Cu")
		(net "M_B_CPU1_SB_CA<6>")
	)
	(arc
		(start 86.984078 -264.688828)
		(mid 87.171022 -264.739083)
		(end 87.357966 -264.688828)
		(width 0.0889)
		(layer "In13.Cu")
		(net "M_B_CPU1_SB_CA<6>")
	)
	(segment
		(start 89.517982 -264.10031)
		(end 89.05113 -264.366248)
		(width 0.10668)
		(layer "F.Cu")
		(net "M_B_CPU1_SB_CA<5>")
	)
	(segment
		(start 88.289638 -264.038842)
		(end 88.29802 -264.043668)
		(width 0.0889)
		(layer "In13.Cu")
		(net "M_B_CPU1_SB_CA<5>")
	)
	(segment
		(start 47.784004 -265.335258)
		(end 47.784004 -265.284712)
		(width 0.14478)
		(layer "In13.Cu")
		(net "M_B_CPU1_SB_CA<5>")
	)
	(segment
		(start 80.389222 -264.052304)
		(end 80.403954 -264.043668)
		(width 0.0889)
		(layer "In13.Cu")
		(net "M_B_CPU1_SB_CA<5>")
	)
	(segment
		(start 48.1584 -264.910316)
		(end 60.01512 -264.910316)
		(width 0.14478)
		(layer "In13.Cu")
		(net "M_B_CPU1_SB_CA<5>")
	)
	(segment
		(start 80.769714 -264.038842)
		(end 80.778096 -264.043668)
		(width 0.0889)
		(layer "In13.Cu")
		(net "M_B_CPU1_SB_CA<5>")
	)
	(segment
		(start 85.10397 -264.043668)
		(end 85.112352 -264.038842)
		(width 0.0889)
		(layer "In13.Cu")
		(net "M_B_CPU1_SB_CA<5>")
	)
	(segment
		(start 81.344008 -264.043668)
		(end 81.35239 -264.038842)
		(width 0.0889)
		(layer "In13.Cu")
		(net "M_B_CPU1_SB_CA<5>")
	)
	(segment
		(start 75.921616 -264.165334)
		(end 76.188062 -264.165334)
		(width 0.0889)
		(layer "In13.Cu")
		(net "M_B_CPU1_SB_CA<5>")
	)
	(segment
		(start 60.01512 -264.910316)
		(end 60.760102 -264.165334)
		(width 0.14478)
		(layer "In13.Cu")
		(net "M_B_CPU1_SB_CA<5>")
	)
	(segment
		(start 83.589622 -264.038842)
		(end 83.598004 -264.043668)
		(width 0.0889)
		(layer "In13.Cu")
		(net "M_B_CPU1_SB_CA<5>")
	)
	(segment
		(start 89.182702 -264.017506)
		(end 89.205054 -264.100818)
		(width 0.0889)
		(layer "In13.Cu")
		(net "M_B_CPU1_SB_CA<5>")
	)
	(segment
		(start 86.044024 -264.043668)
		(end 86.052406 -264.038842)
		(width 0.0889)
		(layer "In13.Cu")
		(net "M_B_CPU1_SB_CA<5>")
	)
	(segment
		(start 76.360528 -263.992868)
		(end 79.649828 -263.992868)
		(width 0.0889)
		(layer "In13.Cu")
		(net "M_B_CPU1_SB_CA<5>")
	)
	(segment
		(start 76.188062 -264.165334)
		(end 76.360528 -263.992868)
		(width 0.0889)
		(layer "In13.Cu")
		(net "M_B_CPU1_SB_CA<5>")
	)
	(segment
		(start 89.205054 -264.100818)
		(end 89.05113 -264.366248)
		(width 0.0889)
		(layer "In13.Cu")
		(net "M_B_CPU1_SB_CA<5>")
	)
	(segment
		(start 60.760102 -264.165334)
		(end 75.921616 -264.165334)
		(width 0.14478)
		(layer "In13.Cu")
		(net "M_B_CPU1_SB_CA<5>")
	)
	(segment
		(start 84.529676 -264.038842)
		(end 84.538058 -264.043668)
		(width 0.0889)
		(layer "In13.Cu")
		(net "M_B_CPU1_SB_CA<5>")
	)
	(segment
		(start 47.784004 -265.284712)
		(end 48.1584 -264.910316)
		(width 0.14478)
		(layer "In13.Cu")
		(net "M_B_CPU1_SB_CA<5>")
	)
	(arc
		(start 82.65795 -264.043668)
		(mid 82.940906 -264.119845)
		(end 83.223862 -264.043668)
		(width 0.0889)
		(layer "In13.Cu")
		(net "M_B_CPU1_SB_CA<5>")
	)
	(arc
		(start 82.284062 -264.043668)
		(mid 82.471006 -263.993413)
		(end 82.65795 -264.043668)
		(width 0.0889)
		(layer "In13.Cu")
		(net "M_B_CPU1_SB_CA<5>")
	)
	(arc
		(start 87.923878 -264.043668)
		(mid 88.106129 -263.993318)
		(end 88.289638 -264.038842)
		(width 0.0889)
		(layer "In13.Cu")
		(net "M_B_CPU1_SB_CA<5>")
	)
	(arc
		(start 85.112352 -264.038842)
		(mid 85.29586 -263.993348)
		(end 85.478112 -264.043668)
		(width 0.0889)
		(layer "In13.Cu")
		(net "M_B_CPU1_SB_CA<5>")
	)
	(arc
		(start 80.403954 -264.043668)
		(mid 80.586205 -263.993318)
		(end 80.769714 -264.038842)
		(width 0.0889)
		(layer "In13.Cu")
		(net "M_B_CPU1_SB_CA<5>")
	)
	(arc
		(start 79.837534 -264.043668)
		(mid 80.11224 -264.120032)
		(end 80.389222 -264.052304)
		(width 0.0889)
		(layer "In13.Cu")
		(net "M_B_CPU1_SB_CA<5>")
	)
	(arc
		(start 87.357966 -264.043668)
		(mid 87.640922 -264.119845)
		(end 87.923878 -264.043668)
		(width 0.0889)
		(layer "In13.Cu")
		(net "M_B_CPU1_SB_CA<5>")
	)
	(arc
		(start 80.778096 -264.043668)
		(mid 81.061052 -264.119845)
		(end 81.344008 -264.043668)
		(width 0.0889)
		(layer "In13.Cu")
		(net "M_B_CPU1_SB_CA<5>")
	)
	(arc
		(start 79.649828 -263.992868)
		(mid 79.747053 -264.005817)
		(end 79.837534 -264.043668)
		(width 0.0889)
		(layer "In13.Cu")
		(net "M_B_CPU1_SB_CA<5>")
	)
	(arc
		(start 81.71815 -264.043668)
		(mid 82.001106 -264.119845)
		(end 82.284062 -264.043668)
		(width 0.0889)
		(layer "In13.Cu")
		(net "M_B_CPU1_SB_CA<5>")
	)
	(arc
		(start 84.163916 -264.043668)
		(mid 84.346167 -263.993318)
		(end 84.529676 -264.038842)
		(width 0.0889)
		(layer "In13.Cu")
		(net "M_B_CPU1_SB_CA<5>")
	)
	(arc
		(start 86.418166 -264.043668)
		(mid 86.701122 -264.119845)
		(end 86.984078 -264.043668)
		(width 0.0889)
		(layer "In13.Cu")
		(net "M_B_CPU1_SB_CA<5>")
	)
	(arc
		(start 85.478112 -264.043668)
		(mid 85.761068 -264.119845)
		(end 86.044024 -264.043668)
		(width 0.0889)
		(layer "In13.Cu")
		(net "M_B_CPU1_SB_CA<5>")
	)
	(arc
		(start 86.052406 -264.038842)
		(mid 86.235914 -263.993348)
		(end 86.418166 -264.043668)
		(width 0.0889)
		(layer "In13.Cu")
		(net "M_B_CPU1_SB_CA<5>")
	)
	(arc
		(start 84.538058 -264.043668)
		(mid 84.821014 -264.119845)
		(end 85.10397 -264.043668)
		(width 0.0889)
		(layer "In13.Cu")
		(net "M_B_CPU1_SB_CA<5>")
	)
	(arc
		(start 81.35239 -264.038842)
		(mid 81.535898 -263.993348)
		(end 81.71815 -264.043668)
		(width 0.0889)
		(layer "In13.Cu")
		(net "M_B_CPU1_SB_CA<5>")
	)
	(arc
		(start 83.223862 -264.043668)
		(mid 83.406113 -263.993318)
		(end 83.589622 -264.038842)
		(width 0.0889)
		(layer "In13.Cu")
		(net "M_B_CPU1_SB_CA<5>")
	)
	(arc
		(start 88.863932 -264.043668)
		(mid 89.02037 -263.994697)
		(end 89.182702 -264.017506)
		(width 0.0889)
		(layer "In13.Cu")
		(net "M_B_CPU1_SB_CA<5>")
	)
	(arc
		(start 88.29802 -264.043668)
		(mid 88.580976 -264.119845)
		(end 88.863932 -264.043668)
		(width 0.0889)
		(layer "In13.Cu")
		(net "M_B_CPU1_SB_CA<5>")
	)
	(arc
		(start 86.984078 -264.043668)
		(mid 87.171022 -263.993413)
		(end 87.357966 -264.043668)
		(width 0.0889)
		(layer "In13.Cu")
		(net "M_B_CPU1_SB_CA<5>")
	)
	(arc
		(start 83.598004 -264.043668)
		(mid 83.88096 -264.119845)
		(end 84.163916 -264.043668)
		(width 0.0889)
		(layer "In13.Cu")
		(net "M_B_CPU1_SB_CA<5>")
	)
	(segment
		(start 89.987882 -263.290304)
		(end 89.52103 -263.556242)
		(width 0.10668)
		(layer "F.Cu")
		(net "M_B_CPU1_SB_CA<4>")
	)
	(segment
		(start 88.394032 -263.878822)
		(end 88.402414 -263.883648)
		(width 0.0889)
		(layer "In13.Cu")
		(net "M_B_CPU1_SB_CA<4>")
	)
	(segment
		(start 58.964322 -264.060178)
		(end 59.200796 -264.060178)
		(width 0.14478)
		(layer "In13.Cu")
		(net "M_B_CPU1_SB_CA<4>")
	)
	(segment
		(start 56.419496 -264.379964)
		(end 56.739282 -264.060178)
		(width 0.14478)
		(layer "In13.Cu")
		(net "M_B_CPU1_SB_CA<4>")
	)
	(segment
		(start 83.694016 -263.878822)
		(end 83.702398 -263.883648)
		(width 0.0889)
		(layer "In13.Cu")
		(net "M_B_CPU1_SB_CA<4>")
	)
	(segment
		(start 59.200796 -264.060178)
		(end 59.520582 -264.379964)
		(width 0.14478)
		(layer "In13.Cu")
		(net "M_B_CPU1_SB_CA<4>")
	)
	(segment
		(start 76.912216 -263.710674)
		(end 77.00391 -263.802368)
		(width 0.0889)
		(layer "In13.Cu")
		(net "M_B_CPU1_SB_CA<4>")
	)
	(segment
		(start 85.93963 -263.883648)
		(end 85.948012 -263.878822)
		(width 0.0889)
		(layer "In13.Cu")
		(net "M_B_CPU1_SB_CA<4>")
	)
	(segment
		(start 89.271094 -263.847072)
		(end 89.367106 -263.821672)
		(width 0.0889)
		(layer "In13.Cu")
		(net "M_B_CPU1_SB_CA<4>")
	)
	(segment
		(start 87.453978 -263.878822)
		(end 87.46236 -263.883648)
		(width 0.0889)
		(layer "In13.Cu")
		(net "M_B_CPU1_SB_CA<4>")
	)
	(segment
		(start 52.13985 -264.060178)
		(end 52.629562 -264.060178)
		(width 0.14478)
		(layer "In13.Cu")
		(net "M_B_CPU1_SB_CA<4>")
	)
	(segment
		(start 56.975756 -264.060178)
		(end 57.295542 -264.379964)
		(width 0.14478)
		(layer "In13.Cu")
		(net "M_B_CPU1_SB_CA<4>")
	)
	(segment
		(start 56.183022 -264.379964)
		(end 56.419496 -264.379964)
		(width 0.14478)
		(layer "In13.Cu")
		(net "M_B_CPU1_SB_CA<4>")
	)
	(segment
		(start 52.629562 -264.060178)
		(end 52.774342 -264.204958)
		(width 0.14478)
		(layer "In13.Cu")
		(net "M_B_CPU1_SB_CA<4>")
	)
	(segment
		(start 82.179668 -263.883648)
		(end 82.18805 -263.878822)
		(width 0.0889)
		(layer "In13.Cu")
		(net "M_B_CPU1_SB_CA<4>")
	)
	(segment
		(start 52.919122 -264.442702)
		(end 53.180742 -264.442702)
		(width 0.14478)
		(layer "In13.Cu")
		(net "M_B_CPU1_SB_CA<4>")
	)
	(segment
		(start 59.520582 -264.379964)
		(end 59.757056 -264.379964)
		(width 0.14478)
		(layer "In13.Cu")
		(net "M_B_CPU1_SB_CA<4>")
	)
	(segment
		(start 53.876702 -264.204958)
		(end 53.876702 -264.297922)
		(width 0.14478)
		(layer "In13.Cu")
		(net "M_B_CPU1_SB_CA<4>")
	)
	(segment
		(start 54.427882 -264.204958)
		(end 54.572662 -264.060178)
		(width 0.14478)
		(layer "In13.Cu")
		(net "M_B_CPU1_SB_CA<4>")
	)
	(segment
		(start 57.851802 -264.060178)
		(end 58.088276 -264.060178)
		(width 0.14478)
		(layer "In13.Cu")
		(net "M_B_CPU1_SB_CA<4>")
	)
	(segment
		(start 53.731922 -264.060178)
		(end 53.876702 -264.204958)
		(width 0.14478)
		(layer "In13.Cu")
		(net "M_B_CPU1_SB_CA<4>")
	)
	(segment
		(start 82.753962 -263.878822)
		(end 82.762344 -263.883648)
		(width 0.0889)
		(layer "In13.Cu")
		(net "M_B_CPU1_SB_CA<4>")
	)
	(segment
		(start 54.283102 -264.442702)
		(end 54.427882 -264.297922)
		(width 0.14478)
		(layer "In13.Cu")
		(net "M_B_CPU1_SB_CA<4>")
	)
	(segment
		(start 52.774342 -264.297922)
		(end 52.919122 -264.442702)
		(width 0.14478)
		(layer "In13.Cu")
		(net "M_B_CPU1_SB_CA<4>")
	)
	(segment
		(start 89.367106 -263.821672)
		(end 89.52103 -263.556242)
		(width 0.0889)
		(layer "In13.Cu")
		(net "M_B_CPU1_SB_CA<4>")
	)
	(segment
		(start 57.295542 -264.379964)
		(end 57.532016 -264.379964)
		(width 0.14478)
		(layer "In13.Cu")
		(net "M_B_CPU1_SB_CA<4>")
	)
	(segment
		(start 77.00391 -263.802368)
		(end 79.650082 -263.802368)
		(width 0.0889)
		(layer "In13.Cu")
		(net "M_B_CPU1_SB_CA<4>")
	)
	(segment
		(start 51.884072 -264.315956)
		(end 52.13985 -264.060178)
		(width 0.14478)
		(layer "In13.Cu")
		(net "M_B_CPU1_SB_CA<4>")
	)
	(segment
		(start 75.952096 -263.710674)
		(end 76.912216 -263.710674)
		(width 0.0889)
		(layer "In13.Cu")
		(net "M_B_CPU1_SB_CA<4>")
	)
	(segment
		(start 58.088276 -264.060178)
		(end 58.408062 -264.379964)
		(width 0.14478)
		(layer "In13.Cu")
		(net "M_B_CPU1_SB_CA<4>")
	)
	(segment
		(start 56.739282 -264.060178)
		(end 56.975756 -264.060178)
		(width 0.14478)
		(layer "In13.Cu")
		(net "M_B_CPU1_SB_CA<4>")
	)
	(segment
		(start 53.470302 -264.060178)
		(end 53.731922 -264.060178)
		(width 0.14478)
		(layer "In13.Cu")
		(net "M_B_CPU1_SB_CA<4>")
	)
	(segment
		(start 54.021482 -264.442702)
		(end 54.283102 -264.442702)
		(width 0.14478)
		(layer "In13.Cu")
		(net "M_B_CPU1_SB_CA<4>")
	)
	(segment
		(start 54.427882 -264.297922)
		(end 54.427882 -264.204958)
		(width 0.14478)
		(layer "In13.Cu")
		(net "M_B_CPU1_SB_CA<4>")
	)
	(segment
		(start 53.325522 -264.204958)
		(end 53.470302 -264.060178)
		(width 0.14478)
		(layer "In13.Cu")
		(net "M_B_CPU1_SB_CA<4>")
	)
	(segment
		(start 55.863236 -264.060178)
		(end 56.183022 -264.379964)
		(width 0.14478)
		(layer "In13.Cu")
		(net "M_B_CPU1_SB_CA<4>")
	)
	(segment
		(start 57.532016 -264.379964)
		(end 57.851802 -264.060178)
		(width 0.14478)
		(layer "In13.Cu")
		(net "M_B_CPU1_SB_CA<4>")
	)
	(segment
		(start 53.876702 -264.297922)
		(end 54.021482 -264.442702)
		(width 0.14478)
		(layer "In13.Cu")
		(net "M_B_CPU1_SB_CA<4>")
	)
	(segment
		(start 59.757056 -264.379964)
		(end 60.426346 -263.710674)
		(width 0.14478)
		(layer "In13.Cu")
		(net "M_B_CPU1_SB_CA<4>")
	)
	(segment
		(start 53.325522 -264.297922)
		(end 53.325522 -264.204958)
		(width 0.14478)
		(layer "In13.Cu")
		(net "M_B_CPU1_SB_CA<4>")
	)
	(segment
		(start 86.879684 -263.883648)
		(end 86.888066 -263.878822)
		(width 0.0889)
		(layer "In13.Cu")
		(net "M_B_CPU1_SB_CA<4>")
	)
	(segment
		(start 51.884072 -264.485374)
		(end 51.884072 -264.315956)
		(width 0.14478)
		(layer "In13.Cu")
		(net "M_B_CPU1_SB_CA<4>")
	)
	(segment
		(start 60.426346 -263.710674)
		(end 75.952096 -263.710674)
		(width 0.14478)
		(layer "In13.Cu")
		(net "M_B_CPU1_SB_CA<4>")
	)
	(segment
		(start 58.408062 -264.379964)
		(end 58.644536 -264.379964)
		(width 0.14478)
		(layer "In13.Cu")
		(net "M_B_CPU1_SB_CA<4>")
	)
	(segment
		(start 58.644536 -264.379964)
		(end 58.964322 -264.060178)
		(width 0.14478)
		(layer "In13.Cu")
		(net "M_B_CPU1_SB_CA<4>")
	)
	(segment
		(start 53.180742 -264.442702)
		(end 53.325522 -264.297922)
		(width 0.14478)
		(layer "In13.Cu")
		(net "M_B_CPU1_SB_CA<4>")
	)
	(segment
		(start 52.774342 -264.204958)
		(end 52.774342 -264.297922)
		(width 0.14478)
		(layer "In13.Cu")
		(net "M_B_CPU1_SB_CA<4>")
	)
	(segment
		(start 80.299814 -263.883648)
		(end 80.308196 -263.878822)
		(width 0.0889)
		(layer "In13.Cu")
		(net "M_B_CPU1_SB_CA<4>")
	)
	(segment
		(start 54.572662 -264.060178)
		(end 55.863236 -264.060178)
		(width 0.14478)
		(layer "In13.Cu")
		(net "M_B_CPU1_SB_CA<4>")
	)
	(arc
		(start 85.57387 -263.878822)
		(mid 85.756121 -263.929172)
		(end 85.93963 -263.883648)
		(width 0.0889)
		(layer "In13.Cu")
		(net "M_B_CPU1_SB_CA<4>")
	)
	(arc
		(start 87.46236 -263.883648)
		(mid 87.645868 -263.929142)
		(end 87.82812 -263.878822)
		(width 0.0889)
		(layer "In13.Cu")
		(net "M_B_CPU1_SB_CA<4>")
	)
	(arc
		(start 82.18805 -263.878822)
		(mid 82.471006 -263.802645)
		(end 82.753962 -263.878822)
		(width 0.0889)
		(layer "In13.Cu")
		(net "M_B_CPU1_SB_CA<4>")
	)
	(arc
		(start 88.768174 -263.878822)
		(mid 89.015887 -263.803602)
		(end 89.271094 -263.847072)
		(width 0.0889)
		(layer "In13.Cu")
		(net "M_B_CPU1_SB_CA<4>")
	)
	(arc
		(start 84.068158 -263.878822)
		(mid 84.351114 -263.802645)
		(end 84.63407 -263.878822)
		(width 0.0889)
		(layer "In13.Cu")
		(net "M_B_CPU1_SB_CA<4>")
	)
	(arc
		(start 87.82812 -263.878822)
		(mid 88.111076 -263.802645)
		(end 88.394032 -263.878822)
		(width 0.0889)
		(layer "In13.Cu")
		(net "M_B_CPU1_SB_CA<4>")
	)
	(arc
		(start 83.128104 -263.878822)
		(mid 83.41106 -263.802645)
		(end 83.694016 -263.878822)
		(width 0.0889)
		(layer "In13.Cu")
		(net "M_B_CPU1_SB_CA<4>")
	)
	(arc
		(start 81.813908 -263.878822)
		(mid 81.996159 -263.929172)
		(end 82.179668 -263.883648)
		(width 0.0889)
		(layer "In13.Cu")
		(net "M_B_CPU1_SB_CA<4>")
	)
	(arc
		(start 81.247996 -263.878822)
		(mid 81.530952 -263.802645)
		(end 81.813908 -263.878822)
		(width 0.0889)
		(layer "In13.Cu")
		(net "M_B_CPU1_SB_CA<4>")
	)
	(arc
		(start 88.402414 -263.883648)
		(mid 88.585922 -263.929142)
		(end 88.768174 -263.878822)
		(width 0.0889)
		(layer "In13.Cu")
		(net "M_B_CPU1_SB_CA<4>")
	)
	(arc
		(start 83.702398 -263.883648)
		(mid 83.885906 -263.929142)
		(end 84.068158 -263.878822)
		(width 0.0889)
		(layer "In13.Cu")
		(net "M_B_CPU1_SB_CA<4>")
	)
	(arc
		(start 84.63407 -263.878822)
		(mid 84.821014 -263.929077)
		(end 85.007958 -263.878822)
		(width 0.0889)
		(layer "In13.Cu")
		(net "M_B_CPU1_SB_CA<4>")
	)
	(arc
		(start 80.308196 -263.878822)
		(mid 80.591152 -263.802645)
		(end 80.874108 -263.878822)
		(width 0.0889)
		(layer "In13.Cu")
		(net "M_B_CPU1_SB_CA<4>")
	)
	(arc
		(start 82.762344 -263.883648)
		(mid 82.945852 -263.929142)
		(end 83.128104 -263.878822)
		(width 0.0889)
		(layer "In13.Cu")
		(net "M_B_CPU1_SB_CA<4>")
	)
	(arc
		(start 79.933546 -263.878822)
		(mid 80.116051 -263.929299)
		(end 80.299814 -263.883648)
		(width 0.0889)
		(layer "In13.Cu")
		(net "M_B_CPU1_SB_CA<4>")
	)
	(arc
		(start 80.874108 -263.878822)
		(mid 81.061052 -263.929077)
		(end 81.247996 -263.878822)
		(width 0.0889)
		(layer "In13.Cu")
		(net "M_B_CPU1_SB_CA<4>")
	)
	(arc
		(start 79.650082 -263.802368)
		(mid 79.796882 -263.821812)
		(end 79.933546 -263.878822)
		(width 0.0889)
		(layer "In13.Cu")
		(net "M_B_CPU1_SB_CA<4>")
	)
	(arc
		(start 86.513924 -263.878822)
		(mid 86.696175 -263.929172)
		(end 86.879684 -263.883648)
		(width 0.0889)
		(layer "In13.Cu")
		(net "M_B_CPU1_SB_CA<4>")
	)
	(arc
		(start 86.888066 -263.878822)
		(mid 87.171022 -263.802645)
		(end 87.453978 -263.878822)
		(width 0.0889)
		(layer "In13.Cu")
		(net "M_B_CPU1_SB_CA<4>")
	)
	(arc
		(start 85.948012 -263.878822)
		(mid 86.230968 -263.802645)
		(end 86.513924 -263.878822)
		(width 0.0889)
		(layer "In13.Cu")
		(net "M_B_CPU1_SB_CA<4>")
	)
	(arc
		(start 85.007958 -263.878822)
		(mid 85.290914 -263.802645)
		(end 85.57387 -263.878822)
		(width 0.0889)
		(layer "In13.Cu")
		(net "M_B_CPU1_SB_CA<4>")
	)
	(segment
		(start 88.107774 -263.290304)
		(end 87.640922 -263.556242)
		(width 0.10668)
		(layer "F.Cu")
		(net "M_B_CPU1_SB_CA<3>")
	)
	(segment
		(start 87.772748 -263.2075)
		(end 87.7951 -263.290812)
		(width 0.0889)
		(layer "In13.Cu")
		(net "M_B_CPU1_SB_CA<3>")
	)
	(segment
		(start 86.879684 -263.228836)
		(end 86.888066 -263.233662)
		(width 0.0889)
		(layer "In13.Cu")
		(net "M_B_CPU1_SB_CA<3>")
	)
	(segment
		(start 77.58303 -262.894826)
		(end 77.998066 -263.309862)
		(width 0.0889)
		(layer "In13.Cu")
		(net "M_B_CPU1_SB_CA<3>")
	)
	(segment
		(start 76.457302 -263.210294)
		(end 76.77277 -262.894826)
		(width 0.0889)
		(layer "In13.Cu")
		(net "M_B_CPU1_SB_CA<3>")
	)
	(segment
		(start 47.784004 -263.635236)
		(end 47.875952 -263.635236)
		(width 0.14478)
		(layer "In13.Cu")
		(net "M_B_CPU1_SB_CA<3>")
	)
	(segment
		(start 76.77277 -262.894826)
		(end 77.58303 -262.894826)
		(width 0.0889)
		(layer "In13.Cu")
		(net "M_B_CPU1_SB_CA<3>")
	)
	(segment
		(start 80.299814 -263.228836)
		(end 80.308196 -263.233662)
		(width 0.0889)
		(layer "In13.Cu")
		(net "M_B_CPU1_SB_CA<3>")
	)
	(segment
		(start 82.753962 -263.233662)
		(end 82.762344 -263.228836)
		(width 0.0889)
		(layer "In13.Cu")
		(net "M_B_CPU1_SB_CA<3>")
	)
	(segment
		(start 85.93963 -263.228836)
		(end 85.948012 -263.233662)
		(width 0.0889)
		(layer "In13.Cu")
		(net "M_B_CPU1_SB_CA<3>")
	)
	(segment
		(start 48.300894 -263.210294)
		(end 75.963526 -263.210294)
		(width 0.14478)
		(layer "In13.Cu")
		(net "M_B_CPU1_SB_CA<3>")
	)
	(segment
		(start 47.875952 -263.635236)
		(end 48.300894 -263.210294)
		(width 0.14478)
		(layer "In13.Cu")
		(net "M_B_CPU1_SB_CA<3>")
	)
	(segment
		(start 77.998066 -263.309862)
		(end 79.650336 -263.309862)
		(width 0.0889)
		(layer "In13.Cu")
		(net "M_B_CPU1_SB_CA<3>")
	)
	(segment
		(start 82.179668 -263.228836)
		(end 82.18805 -263.233662)
		(width 0.0889)
		(layer "In13.Cu")
		(net "M_B_CPU1_SB_CA<3>")
	)
	(segment
		(start 83.694016 -263.233662)
		(end 83.702398 -263.228836)
		(width 0.0889)
		(layer "In13.Cu")
		(net "M_B_CPU1_SB_CA<3>")
	)
	(segment
		(start 87.453978 -263.233662)
		(end 87.46236 -263.228836)
		(width 0.0889)
		(layer "In13.Cu")
		(net "M_B_CPU1_SB_CA<3>")
	)
	(segment
		(start 87.7951 -263.290812)
		(end 87.640922 -263.556242)
		(width 0.0889)
		(layer "In13.Cu")
		(net "M_B_CPU1_SB_CA<3>")
	)
	(segment
		(start 75.963526 -263.210294)
		(end 76.457302 -263.210294)
		(width 0.0889)
		(layer "In13.Cu")
		(net "M_B_CPU1_SB_CA<3>")
	)
	(arc
		(start 83.702398 -263.228836)
		(mid 83.885906 -263.183342)
		(end 84.068158 -263.233662)
		(width 0.0889)
		(layer "In13.Cu")
		(net "M_B_CPU1_SB_CA<3>")
	)
	(arc
		(start 82.762344 -263.228836)
		(mid 82.945852 -263.183342)
		(end 83.128104 -263.233662)
		(width 0.0889)
		(layer "In13.Cu")
		(net "M_B_CPU1_SB_CA<3>")
	)
	(arc
		(start 84.068158 -263.233662)
		(mid 84.351114 -263.309839)
		(end 84.63407 -263.233662)
		(width 0.0889)
		(layer "In13.Cu")
		(net "M_B_CPU1_SB_CA<3>")
	)
	(arc
		(start 83.128104 -263.233662)
		(mid 83.41106 -263.309839)
		(end 83.694016 -263.233662)
		(width 0.0889)
		(layer "In13.Cu")
		(net "M_B_CPU1_SB_CA<3>")
	)
	(arc
		(start 85.948012 -263.233662)
		(mid 86.230968 -263.309839)
		(end 86.513924 -263.233662)
		(width 0.0889)
		(layer "In13.Cu")
		(net "M_B_CPU1_SB_CA<3>")
	)
	(arc
		(start 79.933546 -263.233662)
		(mid 80.116051 -263.183185)
		(end 80.299814 -263.228836)
		(width 0.0889)
		(layer "In13.Cu")
		(net "M_B_CPU1_SB_CA<3>")
	)
	(arc
		(start 80.874108 -263.233662)
		(mid 81.061052 -263.183407)
		(end 81.247996 -263.233662)
		(width 0.0889)
		(layer "In13.Cu")
		(net "M_B_CPU1_SB_CA<3>")
	)
	(arc
		(start 81.247996 -263.233662)
		(mid 81.530952 -263.309839)
		(end 81.813908 -263.233662)
		(width 0.0889)
		(layer "In13.Cu")
		(net "M_B_CPU1_SB_CA<3>")
	)
	(arc
		(start 79.650336 -263.309862)
		(mid 79.796993 -263.290525)
		(end 79.933546 -263.233662)
		(width 0.0889)
		(layer "In13.Cu")
		(net "M_B_CPU1_SB_CA<3>")
	)
	(arc
		(start 85.007958 -263.233662)
		(mid 85.290914 -263.309839)
		(end 85.57387 -263.233662)
		(width 0.0889)
		(layer "In13.Cu")
		(net "M_B_CPU1_SB_CA<3>")
	)
	(arc
		(start 86.888066 -263.233662)
		(mid 87.171022 -263.309839)
		(end 87.453978 -263.233662)
		(width 0.0889)
		(layer "In13.Cu")
		(net "M_B_CPU1_SB_CA<3>")
	)
	(arc
		(start 86.513924 -263.233662)
		(mid 86.696175 -263.183312)
		(end 86.879684 -263.228836)
		(width 0.0889)
		(layer "In13.Cu")
		(net "M_B_CPU1_SB_CA<3>")
	)
	(arc
		(start 87.46236 -263.228836)
		(mid 87.61523 -263.184195)
		(end 87.772748 -263.2075)
		(width 0.0889)
		(layer "In13.Cu")
		(net "M_B_CPU1_SB_CA<3>")
	)
	(arc
		(start 81.813908 -263.233662)
		(mid 81.996159 -263.183312)
		(end 82.179668 -263.228836)
		(width 0.0889)
		(layer "In13.Cu")
		(net "M_B_CPU1_SB_CA<3>")
	)
	(arc
		(start 80.308196 -263.233662)
		(mid 80.591152 -263.309839)
		(end 80.874108 -263.233662)
		(width 0.0889)
		(layer "In13.Cu")
		(net "M_B_CPU1_SB_CA<3>")
	)
	(arc
		(start 84.63407 -263.233662)
		(mid 84.821014 -263.183407)
		(end 85.007958 -263.233662)
		(width 0.0889)
		(layer "In13.Cu")
		(net "M_B_CPU1_SB_CA<3>")
	)
	(arc
		(start 85.57387 -263.233662)
		(mid 85.756121 -263.183312)
		(end 85.93963 -263.228836)
		(width 0.0889)
		(layer "In13.Cu")
		(net "M_B_CPU1_SB_CA<3>")
	)
	(arc
		(start 82.18805 -263.233662)
		(mid 82.471006 -263.309839)
		(end 82.753962 -263.233662)
		(width 0.0889)
		(layer "In13.Cu")
		(net "M_B_CPU1_SB_CA<3>")
	)
	(segment
		(start 88.577928 -262.480298)
		(end 88.111076 -262.746236)
		(width 0.10668)
		(layer "F.Cu")
		(net "M_B_CPU1_SB_CA<2>")
	)
	(segment
		(start 57.14746 -262.367522)
		(end 57.458102 -262.678164)
		(width 0.14478)
		(layer "In13.Cu")
		(net "M_B_CPU1_SB_CA<2>")
	)
	(segment
		(start 59.3725 -262.367522)
		(end 59.683142 -262.678164)
		(width 0.14478)
		(layer "In13.Cu")
		(net "M_B_CPU1_SB_CA<2>")
	)
	(segment
		(start 75.928982 -262.75538)
		(end 76.429616 -262.75538)
		(width 0.0889)
		(layer "In13.Cu")
		(net "M_B_CPU1_SB_CA<2>")
	)
	(segment
		(start 59.92876 -262.678164)
		(end 60.44438 -262.162544)
		(width 0.14478)
		(layer "In13.Cu")
		(net "M_B_CPU1_SB_CA<2>")
	)
	(segment
		(start 52.483004 -262.006588)
		(end 52.914804 -262.006588)
		(width 0.14478)
		(layer "In13.Cu")
		(net "M_B_CPU1_SB_CA<2>")
	)
	(segment
		(start 54.306724 -262.66648)
		(end 54.568344 -262.66648)
		(width 0.14478)
		(layer "In13.Cu")
		(net "M_B_CPU1_SB_CA<2>")
	)
	(segment
		(start 54.017164 -262.006588)
		(end 54.161944 -262.151368)
		(width 0.14478)
		(layer "In13.Cu")
		(net "M_B_CPU1_SB_CA<2>")
	)
	(segment
		(start 85.10397 -263.068816)
		(end 85.112352 -263.073642)
		(width 0.0889)
		(layer "In13.Cu")
		(net "M_B_CPU1_SB_CA<2>")
	)
	(segment
		(start 59.683142 -262.678164)
		(end 59.92876 -262.678164)
		(width 0.14478)
		(layer "In13.Cu")
		(net "M_B_CPU1_SB_CA<2>")
	)
	(segment
		(start 76.492608 -262.692388)
		(end 77.824838 -262.692388)
		(width 0.0889)
		(layer "In13.Cu")
		(net "M_B_CPU1_SB_CA<2>")
	)
	(segment
		(start 80.769714 -263.073642)
		(end 80.778096 -263.068816)
		(width 0.0889)
		(layer "In13.Cu")
		(net "M_B_CPU1_SB_CA<2>")
	)
	(segment
		(start 84.529676 -263.073642)
		(end 84.538058 -263.068816)
		(width 0.0889)
		(layer "In13.Cu")
		(net "M_B_CPU1_SB_CA<2>")
	)
	(segment
		(start 80.39354 -263.06272)
		(end 80.403954 -263.068816)
		(width 0.0889)
		(layer "In13.Cu")
		(net "M_B_CPU1_SB_CA<2>")
	)
	(segment
		(start 56.345582 -262.678164)
		(end 56.5912 -262.678164)
		(width 0.14478)
		(layer "In13.Cu")
		(net "M_B_CPU1_SB_CA<2>")
	)
	(segment
		(start 53.610764 -262.151368)
		(end 53.755544 -262.006588)
		(width 0.14478)
		(layer "In13.Cu")
		(net "M_B_CPU1_SB_CA<2>")
	)
	(segment
		(start 86.044024 -263.068816)
		(end 86.052406 -263.073642)
		(width 0.0889)
		(layer "In13.Cu")
		(net "M_B_CPU1_SB_CA<2>")
	)
	(segment
		(start 59.126882 -262.367522)
		(end 59.3725 -262.367522)
		(width 0.14478)
		(layer "In13.Cu")
		(net "M_B_CPU1_SB_CA<2>")
	)
	(segment
		(start 87.956898 -263.011666)
		(end 88.111076 -262.746236)
		(width 0.0889)
		(layer "In13.Cu")
		(net "M_B_CPU1_SB_CA<2>")
	)
	(segment
		(start 78.251812 -263.119362)
		(end 79.65059 -263.119362)
		(width 0.0889)
		(layer "In13.Cu")
		(net "M_B_CPU1_SB_CA<2>")
	)
	(segment
		(start 66.622168 -262.75538)
		(end 75.928982 -262.75538)
		(width 0.14478)
		(layer "In13.Cu")
		(net "M_B_CPU1_SB_CA<2>")
	)
	(segment
		(start 54.857904 -262.006588)
		(end 55.674006 -262.006588)
		(width 0.14478)
		(layer "In13.Cu")
		(net "M_B_CPU1_SB_CA<2>")
	)
	(segment
		(start 58.014362 -262.367522)
		(end 58.25998 -262.367522)
		(width 0.14478)
		(layer "In13.Cu")
		(net "M_B_CPU1_SB_CA<2>")
	)
	(segment
		(start 53.204364 -262.66648)
		(end 53.465984 -262.66648)
		(width 0.14478)
		(layer "In13.Cu")
		(net "M_B_CPU1_SB_CA<2>")
	)
	(segment
		(start 53.059584 -262.5217)
		(end 53.204364 -262.66648)
		(width 0.14478)
		(layer "In13.Cu")
		(net "M_B_CPU1_SB_CA<2>")
	)
	(segment
		(start 87.860632 -263.037066)
		(end 87.956898 -263.011666)
		(width 0.0889)
		(layer "In13.Cu")
		(net "M_B_CPU1_SB_CA<2>")
	)
	(segment
		(start 54.713124 -262.5217)
		(end 54.713124 -262.151368)
		(width 0.14478)
		(layer "In13.Cu")
		(net "M_B_CPU1_SB_CA<2>")
	)
	(segment
		(start 53.610764 -262.5217)
		(end 53.610764 -262.151368)
		(width 0.14478)
		(layer "In13.Cu")
		(net "M_B_CPU1_SB_CA<2>")
	)
	(segment
		(start 60.44438 -262.162544)
		(end 66.029332 -262.162544)
		(width 0.14478)
		(layer "In13.Cu")
		(net "M_B_CPU1_SB_CA<2>")
	)
	(segment
		(start 53.755544 -262.006588)
		(end 54.017164 -262.006588)
		(width 0.14478)
		(layer "In13.Cu")
		(net "M_B_CPU1_SB_CA<2>")
	)
	(segment
		(start 56.901842 -262.367522)
		(end 57.14746 -262.367522)
		(width 0.14478)
		(layer "In13.Cu")
		(net "M_B_CPU1_SB_CA<2>")
	)
	(segment
		(start 54.568344 -262.66648)
		(end 54.713124 -262.5217)
		(width 0.14478)
		(layer "In13.Cu")
		(net "M_B_CPU1_SB_CA<2>")
	)
	(segment
		(start 57.458102 -262.678164)
		(end 57.70372 -262.678164)
		(width 0.14478)
		(layer "In13.Cu")
		(net "M_B_CPU1_SB_CA<2>")
	)
	(segment
		(start 53.059584 -262.151368)
		(end 53.059584 -262.5217)
		(width 0.14478)
		(layer "In13.Cu")
		(net "M_B_CPU1_SB_CA<2>")
	)
	(segment
		(start 83.589622 -263.073642)
		(end 83.598004 -263.068816)
		(width 0.0889)
		(layer "In13.Cu")
		(net "M_B_CPU1_SB_CA<2>")
	)
	(segment
		(start 76.429616 -262.75538)
		(end 76.492608 -262.692388)
		(width 0.0889)
		(layer "In13.Cu")
		(net "M_B_CPU1_SB_CA<2>")
	)
	(segment
		(start 54.161944 -262.151368)
		(end 54.161944 -262.5217)
		(width 0.14478)
		(layer "In13.Cu")
		(net "M_B_CPU1_SB_CA<2>")
	)
	(segment
		(start 53.465984 -262.66648)
		(end 53.610764 -262.5217)
		(width 0.14478)
		(layer "In13.Cu")
		(net "M_B_CPU1_SB_CA<2>")
	)
	(segment
		(start 52.914804 -262.006588)
		(end 53.059584 -262.151368)
		(width 0.14478)
		(layer "In13.Cu")
		(net "M_B_CPU1_SB_CA<2>")
	)
	(segment
		(start 57.70372 -262.678164)
		(end 58.014362 -262.367522)
		(width 0.14478)
		(layer "In13.Cu")
		(net "M_B_CPU1_SB_CA<2>")
	)
	(segment
		(start 56.5912 -262.678164)
		(end 56.901842 -262.367522)
		(width 0.14478)
		(layer "In13.Cu")
		(net "M_B_CPU1_SB_CA<2>")
	)
	(segment
		(start 55.674006 -262.006588)
		(end 56.345582 -262.678164)
		(width 0.14478)
		(layer "In13.Cu")
		(net "M_B_CPU1_SB_CA<2>")
	)
	(segment
		(start 54.161944 -262.5217)
		(end 54.306724 -262.66648)
		(width 0.14478)
		(layer "In13.Cu")
		(net "M_B_CPU1_SB_CA<2>")
	)
	(segment
		(start 51.884072 -262.785352)
		(end 51.884072 -262.60552)
		(width 0.14478)
		(layer "In13.Cu")
		(net "M_B_CPU1_SB_CA<2>")
	)
	(segment
		(start 54.713124 -262.151368)
		(end 54.857904 -262.006588)
		(width 0.14478)
		(layer "In13.Cu")
		(net "M_B_CPU1_SB_CA<2>")
	)
	(segment
		(start 81.344008 -263.068816)
		(end 81.35239 -263.073642)
		(width 0.0889)
		(layer "In13.Cu")
		(net "M_B_CPU1_SB_CA<2>")
	)
	(segment
		(start 77.824838 -262.692388)
		(end 78.251812 -263.119362)
		(width 0.0889)
		(layer "In13.Cu")
		(net "M_B_CPU1_SB_CA<2>")
	)
	(segment
		(start 66.029332 -262.162544)
		(end 66.622168 -262.75538)
		(width 0.14478)
		(layer "In13.Cu")
		(net "M_B_CPU1_SB_CA<2>")
	)
	(segment
		(start 51.884072 -262.60552)
		(end 52.483004 -262.006588)
		(width 0.14478)
		(layer "In13.Cu")
		(net "M_B_CPU1_SB_CA<2>")
	)
	(segment
		(start 58.570622 -262.678164)
		(end 58.81624 -262.678164)
		(width 0.14478)
		(layer "In13.Cu")
		(net "M_B_CPU1_SB_CA<2>")
	)
	(segment
		(start 58.81624 -262.678164)
		(end 59.126882 -262.367522)
		(width 0.14478)
		(layer "In13.Cu")
		(net "M_B_CPU1_SB_CA<2>")
	)
	(segment
		(start 58.25998 -262.367522)
		(end 58.570622 -262.678164)
		(width 0.14478)
		(layer "In13.Cu")
		(net "M_B_CPU1_SB_CA<2>")
	)
	(arc
		(start 84.163916 -263.068816)
		(mid 84.346167 -263.119166)
		(end 84.529676 -263.073642)
		(width 0.0889)
		(layer "In13.Cu")
		(net "M_B_CPU1_SB_CA<2>")
	)
	(arc
		(start 79.65059 -263.119362)
		(mid 79.747516 -263.106425)
		(end 79.837788 -263.068816)
		(width 0.0889)
		(layer "In13.Cu")
		(net "M_B_CPU1_SB_CA<2>")
	)
	(arc
		(start 82.284062 -263.068816)
		(mid 82.471006 -263.119071)
		(end 82.65795 -263.068816)
		(width 0.0889)
		(layer "In13.Cu")
		(net "M_B_CPU1_SB_CA<2>")
	)
	(arc
		(start 84.538058 -263.068816)
		(mid 84.821014 -262.992639)
		(end 85.10397 -263.068816)
		(width 0.0889)
		(layer "In13.Cu")
		(net "M_B_CPU1_SB_CA<2>")
	)
	(arc
		(start 86.984078 -263.068816)
		(mid 87.171022 -263.119071)
		(end 87.357966 -263.068816)
		(width 0.0889)
		(layer "In13.Cu")
		(net "M_B_CPU1_SB_CA<2>")
	)
	(arc
		(start 79.837788 -263.068816)
		(mid 80.114855 -262.992545)
		(end 80.39354 -263.06272)
		(width 0.0889)
		(layer "In13.Cu")
		(net "M_B_CPU1_SB_CA<2>")
	)
	(arc
		(start 85.112352 -263.073642)
		(mid 85.29586 -263.119136)
		(end 85.478112 -263.068816)
		(width 0.0889)
		(layer "In13.Cu")
		(net "M_B_CPU1_SB_CA<2>")
	)
	(arc
		(start 81.71815 -263.068816)
		(mid 82.001106 -262.992639)
		(end 82.284062 -263.068816)
		(width 0.0889)
		(layer "In13.Cu")
		(net "M_B_CPU1_SB_CA<2>")
	)
	(arc
		(start 83.598004 -263.068816)
		(mid 83.88096 -262.992639)
		(end 84.163916 -263.068816)
		(width 0.0889)
		(layer "In13.Cu")
		(net "M_B_CPU1_SB_CA<2>")
	)
	(arc
		(start 85.478112 -263.068816)
		(mid 85.761068 -262.992639)
		(end 86.044024 -263.068816)
		(width 0.0889)
		(layer "In13.Cu")
		(net "M_B_CPU1_SB_CA<2>")
	)
	(arc
		(start 86.418166 -263.068816)
		(mid 86.701122 -262.992639)
		(end 86.984078 -263.068816)
		(width 0.0889)
		(layer "In13.Cu")
		(net "M_B_CPU1_SB_CA<2>")
	)
	(arc
		(start 83.223862 -263.068816)
		(mid 83.406113 -263.119166)
		(end 83.589622 -263.073642)
		(width 0.0889)
		(layer "In13.Cu")
		(net "M_B_CPU1_SB_CA<2>")
	)
	(arc
		(start 82.65795 -263.068816)
		(mid 82.940906 -262.992639)
		(end 83.223862 -263.068816)
		(width 0.0889)
		(layer "In13.Cu")
		(net "M_B_CPU1_SB_CA<2>")
	)
	(arc
		(start 86.052406 -263.073642)
		(mid 86.235914 -263.119136)
		(end 86.418166 -263.068816)
		(width 0.0889)
		(layer "In13.Cu")
		(net "M_B_CPU1_SB_CA<2>")
	)
	(arc
		(start 87.357966 -263.068816)
		(mid 87.605562 -262.993638)
		(end 87.860632 -263.037066)
		(width 0.0889)
		(layer "In13.Cu")
		(net "M_B_CPU1_SB_CA<2>")
	)
	(arc
		(start 80.403954 -263.068816)
		(mid 80.586205 -263.119166)
		(end 80.769714 -263.073642)
		(width 0.0889)
		(layer "In13.Cu")
		(net "M_B_CPU1_SB_CA<2>")
	)
	(arc
		(start 80.778096 -263.068816)
		(mid 81.061052 -262.992639)
		(end 81.344008 -263.068816)
		(width 0.0889)
		(layer "In13.Cu")
		(net "M_B_CPU1_SB_CA<2>")
	)
	(arc
		(start 81.35239 -263.073642)
		(mid 81.535898 -263.119136)
		(end 81.71815 -263.068816)
		(width 0.0889)
		(layer "In13.Cu")
		(net "M_B_CPU1_SB_CA<2>")
	)
	(segment
		(start 89.517982 -262.480298)
		(end 89.05113 -262.746236)
		(width 0.10668)
		(layer "F.Cu")
		(net "M_B_CPU1_SB_CA<1>")
	)
	(segment
		(start 80.389222 -262.432292)
		(end 80.403954 -262.423656)
		(width 0.0889)
		(layer "In13.Cu")
		(net "M_B_CPU1_SB_CA<1>")
	)
	(segment
		(start 89.182702 -262.397494)
		(end 89.205054 -262.480806)
		(width 0.0889)
		(layer "In13.Cu")
		(net "M_B_CPU1_SB_CA<1>")
	)
	(segment
		(start 48.1584 -261.510272)
		(end 66.013076 -261.510272)
		(width 0.14478)
		(layer "In13.Cu")
		(net "M_B_CPU1_SB_CA<1>")
	)
	(segment
		(start 66.013076 -261.510272)
		(end 66.749168 -262.246364)
		(width 0.14478)
		(layer "In13.Cu")
		(net "M_B_CPU1_SB_CA<1>")
	)
	(segment
		(start 83.589622 -262.41883)
		(end 83.598004 -262.423656)
		(width 0.0889)
		(layer "In13.Cu")
		(net "M_B_CPU1_SB_CA<1>")
	)
	(segment
		(start 88.289638 -262.41883)
		(end 88.29802 -262.423656)
		(width 0.0889)
		(layer "In13.Cu")
		(net "M_B_CPU1_SB_CA<1>")
	)
	(segment
		(start 86.044024 -262.423656)
		(end 86.052406 -262.41883)
		(width 0.0889)
		(layer "In13.Cu")
		(net "M_B_CPU1_SB_CA<1>")
	)
	(segment
		(start 47.784004 -261.884668)
		(end 48.1584 -261.510272)
		(width 0.14478)
		(layer "In13.Cu")
		(net "M_B_CPU1_SB_CA<1>")
	)
	(segment
		(start 66.749168 -262.246364)
		(end 75.986386 -262.246364)
		(width 0.14478)
		(layer "In13.Cu")
		(net "M_B_CPU1_SB_CA<1>")
	)
	(segment
		(start 85.10397 -262.423656)
		(end 85.112352 -262.41883)
		(width 0.0889)
		(layer "In13.Cu")
		(net "M_B_CPU1_SB_CA<1>")
	)
	(segment
		(start 47.784004 -261.935214)
		(end 47.784004 -261.884668)
		(width 0.14478)
		(layer "In13.Cu")
		(net "M_B_CPU1_SB_CA<1>")
	)
	(segment
		(start 77.80909 -262.285226)
		(end 79.46644 -262.285226)
		(width 0.0889)
		(layer "In13.Cu")
		(net "M_B_CPU1_SB_CA<1>")
	)
	(segment
		(start 80.769714 -262.41883)
		(end 80.778096 -262.423656)
		(width 0.0889)
		(layer "In13.Cu")
		(net "M_B_CPU1_SB_CA<1>")
	)
	(segment
		(start 89.205054 -262.480806)
		(end 89.05113 -262.746236)
		(width 0.0889)
		(layer "In13.Cu")
		(net "M_B_CPU1_SB_CA<1>")
	)
	(segment
		(start 77.770228 -262.246364)
		(end 77.80909 -262.285226)
		(width 0.0889)
		(layer "In13.Cu")
		(net "M_B_CPU1_SB_CA<1>")
	)
	(segment
		(start 81.344008 -262.423656)
		(end 81.35239 -262.41883)
		(width 0.0889)
		(layer "In13.Cu")
		(net "M_B_CPU1_SB_CA<1>")
	)
	(segment
		(start 84.529676 -262.41883)
		(end 84.538058 -262.423656)
		(width 0.0889)
		(layer "In13.Cu")
		(net "M_B_CPU1_SB_CA<1>")
	)
	(segment
		(start 75.986386 -262.246364)
		(end 77.770228 -262.246364)
		(width 0.0889)
		(layer "In13.Cu")
		(net "M_B_CPU1_SB_CA<1>")
	)
	(arc
		(start 84.163916 -262.423656)
		(mid 84.346167 -262.373306)
		(end 84.529676 -262.41883)
		(width 0.0889)
		(layer "In13.Cu")
		(net "M_B_CPU1_SB_CA<1>")
	)
	(arc
		(start 85.478112 -262.423656)
		(mid 85.761068 -262.499833)
		(end 86.044024 -262.423656)
		(width 0.0889)
		(layer "In13.Cu")
		(net "M_B_CPU1_SB_CA<1>")
	)
	(arc
		(start 84.538058 -262.423656)
		(mid 84.821014 -262.499833)
		(end 85.10397 -262.423656)
		(width 0.0889)
		(layer "In13.Cu")
		(net "M_B_CPU1_SB_CA<1>")
	)
	(arc
		(start 80.403954 -262.423656)
		(mid 80.586205 -262.373306)
		(end 80.769714 -262.41883)
		(width 0.0889)
		(layer "In13.Cu")
		(net "M_B_CPU1_SB_CA<1>")
	)
	(arc
		(start 82.65795 -262.423656)
		(mid 82.940906 -262.499833)
		(end 83.223862 -262.423656)
		(width 0.0889)
		(layer "In13.Cu")
		(net "M_B_CPU1_SB_CA<1>")
	)
	(arc
		(start 80.778096 -262.423656)
		(mid 81.061052 -262.499833)
		(end 81.344008 -262.423656)
		(width 0.0889)
		(layer "In13.Cu")
		(net "M_B_CPU1_SB_CA<1>")
	)
	(arc
		(start 83.223862 -262.423656)
		(mid 83.406113 -262.373306)
		(end 83.589622 -262.41883)
		(width 0.0889)
		(layer "In13.Cu")
		(net "M_B_CPU1_SB_CA<1>")
	)
	(arc
		(start 86.984078 -262.423656)
		(mid 87.171022 -262.373401)
		(end 87.357966 -262.423656)
		(width 0.0889)
		(layer "In13.Cu")
		(net "M_B_CPU1_SB_CA<1>")
	)
	(arc
		(start 86.418166 -262.423656)
		(mid 86.701122 -262.499833)
		(end 86.984078 -262.423656)
		(width 0.0889)
		(layer "In13.Cu")
		(net "M_B_CPU1_SB_CA<1>")
	)
	(arc
		(start 87.357966 -262.423656)
		(mid 87.640922 -262.499833)
		(end 87.923878 -262.423656)
		(width 0.0889)
		(layer "In13.Cu")
		(net "M_B_CPU1_SB_CA<1>")
	)
	(arc
		(start 82.284062 -262.423656)
		(mid 82.471006 -262.373401)
		(end 82.65795 -262.423656)
		(width 0.0889)
		(layer "In13.Cu")
		(net "M_B_CPU1_SB_CA<1>")
	)
	(arc
		(start 79.46644 -262.285226)
		(mid 79.51102 -262.2886)
		(end 79.554578 -262.298688)
		(width 0.0889)
		(layer "In13.Cu")
		(net "M_B_CPU1_SB_CA<1>")
	)
	(arc
		(start 85.112352 -262.41883)
		(mid 85.29586 -262.373336)
		(end 85.478112 -262.423656)
		(width 0.0889)
		(layer "In13.Cu")
		(net "M_B_CPU1_SB_CA<1>")
	)
	(arc
		(start 81.71815 -262.423656)
		(mid 82.001106 -262.499833)
		(end 82.284062 -262.423656)
		(width 0.0889)
		(layer "In13.Cu")
		(net "M_B_CPU1_SB_CA<1>")
	)
	(arc
		(start 88.29802 -262.423656)
		(mid 88.580976 -262.499833)
		(end 88.863932 -262.423656)
		(width 0.0889)
		(layer "In13.Cu")
		(net "M_B_CPU1_SB_CA<1>")
	)
	(arc
		(start 86.052406 -262.41883)
		(mid 86.235914 -262.373336)
		(end 86.418166 -262.423656)
		(width 0.0889)
		(layer "In13.Cu")
		(net "M_B_CPU1_SB_CA<1>")
	)
	(arc
		(start 87.923878 -262.423656)
		(mid 88.106129 -262.373306)
		(end 88.289638 -262.41883)
		(width 0.0889)
		(layer "In13.Cu")
		(net "M_B_CPU1_SB_CA<1>")
	)
	(arc
		(start 88.863932 -262.423656)
		(mid 89.02037 -262.374685)
		(end 89.182702 -262.397494)
		(width 0.0889)
		(layer "In13.Cu")
		(net "M_B_CPU1_SB_CA<1>")
	)
	(arc
		(start 81.35239 -262.41883)
		(mid 81.535898 -262.373336)
		(end 81.71815 -262.423656)
		(width 0.0889)
		(layer "In13.Cu")
		(net "M_B_CPU1_SB_CA<1>")
	)
	(arc
		(start 79.554578 -262.298688)
		(mid 79.699527 -262.353313)
		(end 79.837534 -262.423656)
		(width 0.0889)
		(layer "In13.Cu")
		(net "M_B_CPU1_SB_CA<1>")
	)
	(arc
		(start 83.598004 -262.423656)
		(mid 83.88096 -262.499833)
		(end 84.163916 -262.423656)
		(width 0.0889)
		(layer "In13.Cu")
		(net "M_B_CPU1_SB_CA<1>")
	)
	(arc
		(start 79.837534 -262.423656)
		(mid 80.11224 -262.50002)
		(end 80.389222 -262.432292)
		(width 0.0889)
		(layer "In13.Cu")
		(net "M_B_CPU1_SB_CA<1>")
	)
	(segment
		(start 89.987882 -261.670292)
		(end 89.52103 -261.93623)
		(width 0.10668)
		(layer "F.Cu")
		(net "M_B_CPU1_SB_CA<0>")
	)
	(segment
		(start 54.008528 -260.976364)
		(end 54.248812 -260.976364)
		(width 0.14478)
		(layer "In13.Cu")
		(net "M_B_CPU1_SB_CA<0>")
	)
	(segment
		(start 88.394032 -262.25881)
		(end 88.402414 -262.263636)
		(width 0.0889)
		(layer "In13.Cu")
		(net "M_B_CPU1_SB_CA<0>")
	)
	(segment
		(start 67.14617 -261.77621)
		(end 75.948032 -261.77621)
		(width 0.14478)
		(layer "In13.Cu")
		(net "M_B_CPU1_SB_CA<0>")
	)
	(segment
		(start 56.233568 -260.976364)
		(end 56.473852 -260.976364)
		(width 0.14478)
		(layer "In13.Cu")
		(net "M_B_CPU1_SB_CA<0>")
	)
	(segment
		(start 52.580032 -260.660388)
		(end 52.896008 -260.976364)
		(width 0.14478)
		(layer "In13.Cu")
		(net "M_B_CPU1_SB_CA<0>")
	)
	(segment
		(start 85.93963 -262.263636)
		(end 85.948012 -262.25881)
		(width 0.0889)
		(layer "In13.Cu")
		(net "M_B_CPU1_SB_CA<0>")
	)
	(segment
		(start 75.948032 -261.77621)
		(end 76.614274 -261.77621)
		(width 0.0889)
		(layer "In13.Cu")
		(net "M_B_CPU1_SB_CA<0>")
	)
	(segment
		(start 53.452268 -260.660388)
		(end 53.692552 -260.660388)
		(width 0.14478)
		(layer "In13.Cu")
		(net "M_B_CPU1_SB_CA<0>")
	)
	(segment
		(start 56.473852 -260.976364)
		(end 56.789828 -260.660388)
		(width 0.14478)
		(layer "In13.Cu")
		(net "M_B_CPU1_SB_CA<0>")
	)
	(segment
		(start 57.902348 -260.660388)
		(end 58.142632 -260.660388)
		(width 0.14478)
		(layer "In13.Cu")
		(net "M_B_CPU1_SB_CA<0>")
	)
	(segment
		(start 57.586372 -260.976364)
		(end 57.902348 -260.660388)
		(width 0.14478)
		(layer "In13.Cu")
		(net "M_B_CPU1_SB_CA<0>")
	)
	(segment
		(start 54.805072 -260.660388)
		(end 55.121048 -260.976364)
		(width 0.14478)
		(layer "In13.Cu")
		(net "M_B_CPU1_SB_CA<0>")
	)
	(segment
		(start 76.88199 -262.043926)
		(end 79.135986 -262.043926)
		(width 0.0889)
		(layer "In13.Cu")
		(net "M_B_CPU1_SB_CA<0>")
	)
	(segment
		(start 89.367106 -262.20166)
		(end 89.52103 -261.93623)
		(width 0.0889)
		(layer "In13.Cu")
		(net "M_B_CPU1_SB_CA<0>")
	)
	(segment
		(start 55.121048 -260.976364)
		(end 55.361332 -260.976364)
		(width 0.14478)
		(layer "In13.Cu")
		(net "M_B_CPU1_SB_CA<0>")
	)
	(segment
		(start 53.692552 -260.660388)
		(end 54.008528 -260.976364)
		(width 0.14478)
		(layer "In13.Cu")
		(net "M_B_CPU1_SB_CA<0>")
	)
	(segment
		(start 59.571128 -260.976364)
		(end 59.811412 -260.976364)
		(width 0.14478)
		(layer "In13.Cu")
		(net "M_B_CPU1_SB_CA<0>")
	)
	(segment
		(start 55.917592 -260.660388)
		(end 56.233568 -260.976364)
		(width 0.14478)
		(layer "In13.Cu")
		(net "M_B_CPU1_SB_CA<0>")
	)
	(segment
		(start 58.142632 -260.660388)
		(end 58.458608 -260.976364)
		(width 0.14478)
		(layer "In13.Cu")
		(net "M_B_CPU1_SB_CA<0>")
	)
	(segment
		(start 66.030348 -260.660388)
		(end 67.14617 -261.77621)
		(width 0.14478)
		(layer "In13.Cu")
		(net "M_B_CPU1_SB_CA<0>")
	)
	(segment
		(start 54.564788 -260.660388)
		(end 54.805072 -260.660388)
		(width 0.14478)
		(layer "In13.Cu")
		(net "M_B_CPU1_SB_CA<0>")
	)
	(segment
		(start 55.677308 -260.660388)
		(end 55.917592 -260.660388)
		(width 0.14478)
		(layer "In13.Cu")
		(net "M_B_CPU1_SB_CA<0>")
	)
	(segment
		(start 51.884072 -261.01167)
		(end 52.235354 -260.660388)
		(width 0.14478)
		(layer "In13.Cu")
		(net "M_B_CPU1_SB_CA<0>")
	)
	(segment
		(start 57.030112 -260.660388)
		(end 57.346088 -260.976364)
		(width 0.14478)
		(layer "In13.Cu")
		(net "M_B_CPU1_SB_CA<0>")
	)
	(segment
		(start 57.346088 -260.976364)
		(end 57.586372 -260.976364)
		(width 0.14478)
		(layer "In13.Cu")
		(net "M_B_CPU1_SB_CA<0>")
	)
	(segment
		(start 56.789828 -260.660388)
		(end 57.030112 -260.660388)
		(width 0.14478)
		(layer "In13.Cu")
		(net "M_B_CPU1_SB_CA<0>")
	)
	(segment
		(start 76.614274 -261.77621)
		(end 76.88199 -262.043926)
		(width 0.0889)
		(layer "In13.Cu")
		(net "M_B_CPU1_SB_CA<0>")
	)
	(segment
		(start 83.694016 -262.25881)
		(end 83.702398 -262.263636)
		(width 0.0889)
		(layer "In13.Cu")
		(net "M_B_CPU1_SB_CA<0>")
	)
	(segment
		(start 52.235354 -260.660388)
		(end 52.580032 -260.660388)
		(width 0.14478)
		(layer "In13.Cu")
		(net "M_B_CPU1_SB_CA<0>")
	)
	(segment
		(start 59.014868 -260.660388)
		(end 59.255152 -260.660388)
		(width 0.14478)
		(layer "In13.Cu")
		(net "M_B_CPU1_SB_CA<0>")
	)
	(segment
		(start 89.271094 -262.22706)
		(end 89.367106 -262.20166)
		(width 0.0889)
		(layer "In13.Cu")
		(net "M_B_CPU1_SB_CA<0>")
	)
	(segment
		(start 82.753962 -262.25881)
		(end 82.762344 -262.263636)
		(width 0.0889)
		(layer "In13.Cu")
		(net "M_B_CPU1_SB_CA<0>")
	)
	(segment
		(start 58.458608 -260.976364)
		(end 58.698892 -260.976364)
		(width 0.14478)
		(layer "In13.Cu")
		(net "M_B_CPU1_SB_CA<0>")
	)
	(segment
		(start 51.884072 -261.08533)
		(end 51.884072 -261.01167)
		(width 0.14478)
		(layer "In13.Cu")
		(net "M_B_CPU1_SB_CA<0>")
	)
	(segment
		(start 53.136292 -260.976364)
		(end 53.452268 -260.660388)
		(width 0.14478)
		(layer "In13.Cu")
		(net "M_B_CPU1_SB_CA<0>")
	)
	(segment
		(start 80.299814 -262.263636)
		(end 80.308196 -262.25881)
		(width 0.0889)
		(layer "In13.Cu")
		(net "M_B_CPU1_SB_CA<0>")
	)
	(segment
		(start 59.255152 -260.660388)
		(end 59.571128 -260.976364)
		(width 0.14478)
		(layer "In13.Cu")
		(net "M_B_CPU1_SB_CA<0>")
	)
	(segment
		(start 52.896008 -260.976364)
		(end 53.136292 -260.976364)
		(width 0.14478)
		(layer "In13.Cu")
		(net "M_B_CPU1_SB_CA<0>")
	)
	(segment
		(start 60.127388 -260.660388)
		(end 66.030348 -260.660388)
		(width 0.14478)
		(layer "In13.Cu")
		(net "M_B_CPU1_SB_CA<0>")
	)
	(segment
		(start 58.698892 -260.976364)
		(end 59.014868 -260.660388)
		(width 0.14478)
		(layer "In13.Cu")
		(net "M_B_CPU1_SB_CA<0>")
	)
	(segment
		(start 86.879684 -262.263636)
		(end 86.888066 -262.25881)
		(width 0.0889)
		(layer "In13.Cu")
		(net "M_B_CPU1_SB_CA<0>")
	)
	(segment
		(start 55.361332 -260.976364)
		(end 55.677308 -260.660388)
		(width 0.14478)
		(layer "In13.Cu")
		(net "M_B_CPU1_SB_CA<0>")
	)
	(segment
		(start 59.811412 -260.976364)
		(end 60.127388 -260.660388)
		(width 0.14478)
		(layer "In13.Cu")
		(net "M_B_CPU1_SB_CA<0>")
	)
	(segment
		(start 54.248812 -260.976364)
		(end 54.564788 -260.660388)
		(width 0.14478)
		(layer "In13.Cu")
		(net "M_B_CPU1_SB_CA<0>")
	)
	(segment
		(start 82.179668 -262.263636)
		(end 82.18805 -262.25881)
		(width 0.0889)
		(layer "In13.Cu")
		(net "M_B_CPU1_SB_CA<0>")
	)
	(segment
		(start 87.453978 -262.25881)
		(end 87.46236 -262.263636)
		(width 0.0889)
		(layer "In13.Cu")
		(net "M_B_CPU1_SB_CA<0>")
	)
	(arc
		(start 81.813908 -262.25881)
		(mid 81.996159 -262.30916)
		(end 82.179668 -262.263636)
		(width 0.0889)
		(layer "In13.Cu")
		(net "M_B_CPU1_SB_CA<0>")
	)
	(arc
		(start 85.948012 -262.25881)
		(mid 86.230968 -262.182633)
		(end 86.513924 -262.25881)
		(width 0.0889)
		(layer "In13.Cu")
		(net "M_B_CPU1_SB_CA<0>")
	)
	(arc
		(start 87.82812 -262.25881)
		(mid 88.111076 -262.182633)
		(end 88.394032 -262.25881)
		(width 0.0889)
		(layer "In13.Cu")
		(net "M_B_CPU1_SB_CA<0>")
	)
	(arc
		(start 85.007958 -262.25881)
		(mid 85.290914 -262.182633)
		(end 85.57387 -262.25881)
		(width 0.0889)
		(layer "In13.Cu")
		(net "M_B_CPU1_SB_CA<0>")
	)
	(arc
		(start 81.247996 -262.25881)
		(mid 81.530952 -262.182633)
		(end 81.813908 -262.25881)
		(width 0.0889)
		(layer "In13.Cu")
		(net "M_B_CPU1_SB_CA<0>")
	)
	(arc
		(start 86.888066 -262.25881)
		(mid 87.171022 -262.182633)
		(end 87.453978 -262.25881)
		(width 0.0889)
		(layer "In13.Cu")
		(net "M_B_CPU1_SB_CA<0>")
	)
	(arc
		(start 83.128104 -262.25881)
		(mid 83.41106 -262.182633)
		(end 83.694016 -262.25881)
		(width 0.0889)
		(layer "In13.Cu")
		(net "M_B_CPU1_SB_CA<0>")
	)
	(arc
		(start 80.874108 -262.25881)
		(mid 81.061052 -262.309065)
		(end 81.247996 -262.25881)
		(width 0.0889)
		(layer "In13.Cu")
		(net "M_B_CPU1_SB_CA<0>")
	)
	(arc
		(start 86.513924 -262.25881)
		(mid 86.696175 -262.30916)
		(end 86.879684 -262.263636)
		(width 0.0889)
		(layer "In13.Cu")
		(net "M_B_CPU1_SB_CA<0>")
	)
	(arc
		(start 82.18805 -262.25881)
		(mid 82.471006 -262.182633)
		(end 82.753962 -262.25881)
		(width 0.0889)
		(layer "In13.Cu")
		(net "M_B_CPU1_SB_CA<0>")
	)
	(arc
		(start 82.762344 -262.263636)
		(mid 82.945852 -262.30913)
		(end 83.128104 -262.25881)
		(width 0.0889)
		(layer "In13.Cu")
		(net "M_B_CPU1_SB_CA<0>")
	)
	(arc
		(start 84.068158 -262.25881)
		(mid 84.351114 -262.182633)
		(end 84.63407 -262.25881)
		(width 0.0889)
		(layer "In13.Cu")
		(net "M_B_CPU1_SB_CA<0>")
	)
	(arc
		(start 83.702398 -262.263636)
		(mid 83.885906 -262.30913)
		(end 84.068158 -262.25881)
		(width 0.0889)
		(layer "In13.Cu")
		(net "M_B_CPU1_SB_CA<0>")
	)
	(arc
		(start 79.135986 -262.043926)
		(mid 79.548981 -262.098597)
		(end 79.933546 -262.25881)
		(width 0.0889)
		(layer "In13.Cu")
		(net "M_B_CPU1_SB_CA<0>")
	)
	(arc
		(start 88.768174 -262.25881)
		(mid 89.015887 -262.18359)
		(end 89.271094 -262.22706)
		(width 0.0889)
		(layer "In13.Cu")
		(net "M_B_CPU1_SB_CA<0>")
	)
	(arc
		(start 87.46236 -262.263636)
		(mid 87.645868 -262.30913)
		(end 87.82812 -262.25881)
		(width 0.0889)
		(layer "In13.Cu")
		(net "M_B_CPU1_SB_CA<0>")
	)
	(arc
		(start 85.57387 -262.25881)
		(mid 85.756121 -262.30916)
		(end 85.93963 -262.263636)
		(width 0.0889)
		(layer "In13.Cu")
		(net "M_B_CPU1_SB_CA<0>")
	)
	(arc
		(start 88.402414 -262.263636)
		(mid 88.585922 -262.30913)
		(end 88.768174 -262.25881)
		(width 0.0889)
		(layer "In13.Cu")
		(net "M_B_CPU1_SB_CA<0>")
	)
	(arc
		(start 79.933546 -262.25881)
		(mid 80.116051 -262.309287)
		(end 80.299814 -262.263636)
		(width 0.0889)
		(layer "In13.Cu")
		(net "M_B_CPU1_SB_CA<0>")
	)
	(arc
		(start 80.308196 -262.25881)
		(mid 80.591152 -262.182633)
		(end 80.874108 -262.25881)
		(width 0.0889)
		(layer "In13.Cu")
		(net "M_B_CPU1_SB_CA<0>")
	)
	(arc
		(start 84.63407 -262.25881)
		(mid 84.821014 -262.309065)
		(end 85.007958 -262.25881)
		(width 0.0889)
		(layer "In13.Cu")
		(net "M_B_CPU1_SB_CA<0>")
	)
	(segment
		(start 89.987882 -266.530328)
		(end 89.52103 -266.796266)
		(width 0.10668)
		(layer "F.Cu")
		(net "M_B_CPU1_SA_RSP<0>")
	)
	(segment
		(start 62.03823 -266.424664)
		(end 76.049886 -266.424664)
		(width 0.11684)
		(layer "In13.Cu")
		(net "M_B_CPU1_SA_RSP<0>")
	)
	(segment
		(start 78.259686 -267.035788)
		(end 79.395066 -267.035788)
		(width 0.0889)
		(layer "In13.Cu")
		(net "M_B_CPU1_SA_RSP<0>")
	)
	(segment
		(start 55.741062 -268.875764)
		(end 55.984902 -268.875764)
		(width 0.11684)
		(layer "In13.Cu")
		(net "M_B_CPU1_SA_RSP<0>")
	)
	(segment
		(start 55.984902 -268.875764)
		(end 56.269382 -269.160244)
		(width 0.11684)
		(layer "In13.Cu")
		(net "M_B_CPU1_SA_RSP<0>")
	)
	(segment
		(start 55.212742 -269.160244)
		(end 55.456582 -269.160244)
		(width 0.11684)
		(layer "In13.Cu")
		(net "M_B_CPU1_SA_RSP<0>")
	)
	(segment
		(start 82.179668 -267.123672)
		(end 82.18805 -267.118846)
		(width 0.0889)
		(layer "In13.Cu")
		(net "M_B_CPU1_SA_RSP<0>")
	)
	(segment
		(start 76.049886 -266.424664)
		(end 76.459588 -266.424664)
		(width 0.0889)
		(layer "In13.Cu")
		(net "M_B_CPU1_SA_RSP<0>")
	)
	(segment
		(start 78.139544 -266.915646)
		(end 78.259686 -267.035788)
		(width 0.0889)
		(layer "In13.Cu")
		(net "M_B_CPU1_SA_RSP<0>")
	)
	(segment
		(start 57.041542 -268.875764)
		(end 57.326022 -269.160244)
		(width 0.11684)
		(layer "In13.Cu")
		(net "M_B_CPU1_SA_RSP<0>")
	)
	(segment
		(start 87.82812 -267.118846)
		(end 87.837772 -267.113512)
		(width 0.0889)
		(layer "In13.Cu")
		(net "M_B_CPU1_SA_RSP<0>")
	)
	(segment
		(start 89.669874 -267.052552)
		(end 89.52103 -266.796266)
		(width 0.0889)
		(layer "In13.Cu")
		(net "M_B_CPU1_SA_RSP<0>")
	)
	(segment
		(start 85.947758 -267.118846)
		(end 85.948012 -267.118846)
		(width 0.0889)
		(layer "In13.Cu")
		(net "M_B_CPU1_SA_RSP<0>")
	)
	(segment
		(start 79.934308 -267.118592)
		(end 79.950564 -267.12799)
		(width 0.0889)
		(layer "In13.Cu")
		(net "M_B_CPU1_SA_RSP<0>")
	)
	(segment
		(start 57.326022 -269.160244)
		(end 57.569862 -269.160244)
		(width 0.11684)
		(layer "In13.Cu")
		(net "M_B_CPU1_SA_RSP<0>")
	)
	(segment
		(start 57.854342 -268.875764)
		(end 58.098182 -268.875764)
		(width 0.11684)
		(layer "In13.Cu")
		(net "M_B_CPU1_SA_RSP<0>")
	)
	(segment
		(start 76.95057 -266.915646)
		(end 78.139544 -266.915646)
		(width 0.0889)
		(layer "In13.Cu")
		(net "M_B_CPU1_SA_RSP<0>")
	)
	(segment
		(start 58.382662 -269.160244)
		(end 59.833256 -269.160244)
		(width 0.11684)
		(layer "In13.Cu")
		(net "M_B_CPU1_SA_RSP<0>")
	)
	(segment
		(start 86.879684 -267.123672)
		(end 86.888066 -267.118846)
		(width 0.0889)
		(layer "In13.Cu")
		(net "M_B_CPU1_SA_RSP<0>")
	)
	(segment
		(start 54.399942 -269.160244)
		(end 54.684422 -268.875764)
		(width 0.11684)
		(layer "In13.Cu")
		(net "M_B_CPU1_SA_RSP<0>")
	)
	(segment
		(start 56.269382 -269.160244)
		(end 56.513222 -269.160244)
		(width 0.11684)
		(layer "In13.Cu")
		(net "M_B_CPU1_SA_RSP<0>")
	)
	(segment
		(start 60.117736 -268.345158)
		(end 62.03823 -266.424664)
		(width 0.11684)
		(layer "In13.Cu")
		(net "M_B_CPU1_SA_RSP<0>")
	)
	(segment
		(start 58.098182 -268.875764)
		(end 58.382662 -269.160244)
		(width 0.11684)
		(layer "In13.Cu")
		(net "M_B_CPU1_SA_RSP<0>")
	)
	(segment
		(start 83.694016 -267.118846)
		(end 83.702398 -267.123672)
		(width 0.0889)
		(layer "In13.Cu")
		(net "M_B_CPU1_SA_RSP<0>")
	)
	(segment
		(start 56.797702 -268.875764)
		(end 57.041542 -268.875764)
		(width 0.11684)
		(layer "In13.Cu")
		(net "M_B_CPU1_SA_RSP<0>")
	)
	(segment
		(start 54.684422 -268.875764)
		(end 54.928262 -268.875764)
		(width 0.11684)
		(layer "In13.Cu")
		(net "M_B_CPU1_SA_RSP<0>")
	)
	(segment
		(start 60.117736 -268.875764)
		(end 60.117736 -268.345158)
		(width 0.11684)
		(layer "In13.Cu")
		(net "M_B_CPU1_SA_RSP<0>")
	)
	(segment
		(start 57.569862 -269.160244)
		(end 57.854342 -268.875764)
		(width 0.11684)
		(layer "In13.Cu")
		(net "M_B_CPU1_SA_RSP<0>")
	)
	(segment
		(start 79.395066 -267.035788)
		(end 79.47787 -267.118592)
		(width 0.0889)
		(layer "In13.Cu")
		(net "M_B_CPU1_SA_RSP<0>")
	)
	(segment
		(start 56.513222 -269.160244)
		(end 56.797702 -268.875764)
		(width 0.11684)
		(layer "In13.Cu")
		(net "M_B_CPU1_SA_RSP<0>")
	)
	(segment
		(start 76.459588 -266.424664)
		(end 76.95057 -266.915646)
		(width 0.0889)
		(layer "In13.Cu")
		(net "M_B_CPU1_SA_RSP<0>")
	)
	(segment
		(start 87.453978 -267.118846)
		(end 87.46236 -267.123672)
		(width 0.0889)
		(layer "In13.Cu")
		(net "M_B_CPU1_SA_RSP<0>")
	)
	(segment
		(start 89.646506 -267.140436)
		(end 89.669874 -267.052552)
		(width 0.0889)
		(layer "In13.Cu")
		(net "M_B_CPU1_SA_RSP<0>")
	)
	(segment
		(start 54.928262 -268.875764)
		(end 55.212742 -269.160244)
		(width 0.11684)
		(layer "In13.Cu")
		(net "M_B_CPU1_SA_RSP<0>")
	)
	(segment
		(start 59.833256 -269.160244)
		(end 60.117736 -268.875764)
		(width 0.11684)
		(layer "In13.Cu")
		(net "M_B_CPU1_SA_RSP<0>")
	)
	(segment
		(start 51.884072 -269.58544)
		(end 52.309268 -269.160244)
		(width 0.11684)
		(layer "In13.Cu")
		(net "M_B_CPU1_SA_RSP<0>")
	)
	(segment
		(start 82.753962 -267.118846)
		(end 82.762344 -267.123672)
		(width 0.0889)
		(layer "In13.Cu")
		(net "M_B_CPU1_SA_RSP<0>")
	)
	(segment
		(start 52.309268 -269.160244)
		(end 54.399942 -269.160244)
		(width 0.11684)
		(layer "In13.Cu")
		(net "M_B_CPU1_SA_RSP<0>")
	)
	(segment
		(start 79.47787 -267.118592)
		(end 79.934308 -267.118592)
		(width 0.0889)
		(layer "In13.Cu")
		(net "M_B_CPU1_SA_RSP<0>")
	)
	(segment
		(start 55.456582 -269.160244)
		(end 55.741062 -268.875764)
		(width 0.11684)
		(layer "In13.Cu")
		(net "M_B_CPU1_SA_RSP<0>")
	)
	(arc
		(start 87.837772 -267.113512)
		(mid 88.117506 -267.038144)
		(end 88.397334 -267.113258)
		(width 0.0889)
		(layer "In13.Cu")
		(net "M_B_CPU1_SA_RSP<0>")
	)
	(arc
		(start 81.813908 -267.118846)
		(mid 81.996159 -267.169196)
		(end 82.179668 -267.123672)
		(width 0.0889)
		(layer "In13.Cu")
		(net "M_B_CPU1_SA_RSP<0>")
	)
	(arc
		(start 86.888066 -267.118846)
		(mid 87.171022 -267.042669)
		(end 87.453978 -267.118846)
		(width 0.0889)
		(layer "In13.Cu")
		(net "M_B_CPU1_SA_RSP<0>")
	)
	(arc
		(start 85.008212 -267.118846)
		(mid 85.291058 -267.042669)
		(end 85.57387 -267.118846)
		(width 0.0889)
		(layer "In13.Cu")
		(net "M_B_CPU1_SA_RSP<0>")
	)
	(arc
		(start 83.128104 -267.118846)
		(mid 83.41106 -267.042669)
		(end 83.694016 -267.118846)
		(width 0.0889)
		(layer "In13.Cu")
		(net "M_B_CPU1_SA_RSP<0>")
	)
	(arc
		(start 80.308196 -267.118846)
		(mid 80.591152 -267.042669)
		(end 80.874108 -267.118846)
		(width 0.0889)
		(layer "In13.Cu")
		(net "M_B_CPU1_SA_RSP<0>")
	)
	(arc
		(start 79.950564 -267.12799)
		(mid 80.130546 -267.16909)
		(end 80.308196 -267.118846)
		(width 0.0889)
		(layer "In13.Cu")
		(net "M_B_CPU1_SA_RSP<0>")
	)
	(arc
		(start 87.46236 -267.123672)
		(mid 87.645868 -267.169166)
		(end 87.82812 -267.118846)
		(width 0.0889)
		(layer "In13.Cu")
		(net "M_B_CPU1_SA_RSP<0>")
	)
	(arc
		(start 83.702398 -267.123672)
		(mid 83.885906 -267.169166)
		(end 84.068158 -267.118846)
		(width 0.0889)
		(layer "In13.Cu")
		(net "M_B_CPU1_SA_RSP<0>")
	)
	(arc
		(start 85.948012 -267.118846)
		(mid 86.230968 -267.042669)
		(end 86.513924 -267.118846)
		(width 0.0889)
		(layer "In13.Cu")
		(net "M_B_CPU1_SA_RSP<0>")
	)
	(arc
		(start 82.762344 -267.123672)
		(mid 82.945852 -267.169166)
		(end 83.128104 -267.118846)
		(width 0.0889)
		(layer "In13.Cu")
		(net "M_B_CPU1_SA_RSP<0>")
	)
	(arc
		(start 88.765126 -267.113258)
		(mid 89.05113 -267.036306)
		(end 89.337134 -267.113258)
		(width 0.0889)
		(layer "In13.Cu")
		(net "M_B_CPU1_SA_RSP<0>")
	)
	(arc
		(start 84.068158 -267.118846)
		(mid 84.351114 -267.042669)
		(end 84.63407 -267.118846)
		(width 0.0889)
		(layer "In13.Cu")
		(net "M_B_CPU1_SA_RSP<0>")
	)
	(arc
		(start 84.63407 -267.118846)
		(mid 84.821158 -267.169228)
		(end 85.008212 -267.118846)
		(width 0.0889)
		(layer "In13.Cu")
		(net "M_B_CPU1_SA_RSP<0>")
	)
	(arc
		(start 85.57387 -267.118846)
		(mid 85.760814 -267.16917)
		(end 85.947758 -267.118846)
		(width 0.0889)
		(layer "In13.Cu")
		(net "M_B_CPU1_SA_RSP<0>")
	)
	(arc
		(start 80.874108 -267.118846)
		(mid 81.061052 -267.169101)
		(end 81.247996 -267.118846)
		(width 0.0889)
		(layer "In13.Cu")
		(net "M_B_CPU1_SA_RSP<0>")
	)
	(arc
		(start 88.397334 -267.113258)
		(mid 88.58123 -267.162738)
		(end 88.765126 -267.113258)
		(width 0.0889)
		(layer "In13.Cu")
		(net "M_B_CPU1_SA_RSP<0>")
	)
	(arc
		(start 82.18805 -267.118846)
		(mid 82.471006 -267.042669)
		(end 82.753962 -267.118846)
		(width 0.0889)
		(layer "In13.Cu")
		(net "M_B_CPU1_SA_RSP<0>")
	)
	(arc
		(start 89.337134 -267.113258)
		(mid 89.488793 -267.161212)
		(end 89.646506 -267.140436)
		(width 0.0889)
		(layer "In13.Cu")
		(net "M_B_CPU1_SA_RSP<0>")
	)
	(arc
		(start 86.513924 -267.118846)
		(mid 86.696175 -267.169196)
		(end 86.879684 -267.123672)
		(width 0.0889)
		(layer "In13.Cu")
		(net "M_B_CPU1_SA_RSP<0>")
	)
	(arc
		(start 81.247996 -267.118846)
		(mid 81.530952 -267.042669)
		(end 81.813908 -267.118846)
		(width 0.0889)
		(layer "In13.Cu")
		(net "M_B_CPU1_SA_RSP<0>")
	)
	(segment
		(start 89.687908 -256.09042)
		(end 89.221056 -255.824482)
		(width 0.10668)
		(layer "F.Cu")
		(net "M_B_CPU1_SA_PAR")
	)
	(segment
		(start 77.851254 -255.578102)
		(end 78.41107 -255.578102)
		(width 0.0889)
		(layer "In13.Cu")
		(net "M_B_CPU1_SA_PAR")
	)
	(segment
		(start 54.103016 -255.743964)
		(end 64.988186 -255.743964)
		(width 0.14478)
		(layer "In13.Cu")
		(net "M_B_CPU1_SA_PAR")
	)
	(segment
		(start 52.877466 -255.242314)
		(end 53.062632 -255.42748)
		(width 0.14478)
		(layer "In13.Cu")
		(net "M_B_CPU1_SA_PAR")
	)
	(segment
		(start 86.57971 -255.497076)
		(end 86.588092 -255.501902)
		(width 0.0889)
		(layer "In13.Cu")
		(net "M_B_CPU1_SA_PAR")
	)
	(segment
		(start 76.560426 -256.610104)
		(end 76.819252 -256.610104)
		(width 0.0889)
		(layer "In13.Cu")
		(net "M_B_CPU1_SA_PAR")
	)
	(segment
		(start 83.394042 -255.501902)
		(end 83.402424 -255.497076)
		(width 0.0889)
		(layer "In13.Cu")
		(net "M_B_CPU1_SA_PAR")
	)
	(segment
		(start 53.629306 -255.270254)
		(end 54.103016 -255.743964)
		(width 0.14478)
		(layer "In13.Cu")
		(net "M_B_CPU1_SA_PAR")
	)
	(segment
		(start 51.884072 -254.285242)
		(end 52.644294 -254.285242)
		(width 0.14478)
		(layer "In13.Cu")
		(net "M_B_CPU1_SA_PAR")
	)
	(segment
		(start 79.067406 -255.501902)
		(end 79.07782 -255.507998)
		(width 0.0889)
		(layer "In13.Cu")
		(net "M_B_CPU1_SA_PAR")
	)
	(segment
		(start 82.453988 -255.501902)
		(end 82.46237 -255.497076)
		(width 0.0889)
		(layer "In13.Cu")
		(net "M_B_CPU1_SA_PAR")
	)
	(segment
		(start 65.576196 -255.155954)
		(end 71.573136 -255.155954)
		(width 0.14478)
		(layer "In13.Cu")
		(net "M_B_CPU1_SA_PAR")
	)
	(segment
		(start 85.639656 -255.497076)
		(end 85.648038 -255.501902)
		(width 0.0889)
		(layer "In13.Cu")
		(net "M_B_CPU1_SA_PAR")
	)
	(segment
		(start 53.062632 -255.42748)
		(end 53.267356 -255.42748)
		(width 0.14478)
		(layer "In13.Cu")
		(net "M_B_CPU1_SA_PAR")
	)
	(segment
		(start 53.034692 -254.880364)
		(end 52.877466 -255.03759)
		(width 0.14478)
		(layer "In13.Cu")
		(net "M_B_CPU1_SA_PAR")
	)
	(segment
		(start 89.067132 -255.559052)
		(end 89.221056 -255.824482)
		(width 0.0889)
		(layer "In13.Cu")
		(net "M_B_CPU1_SA_PAR")
	)
	(segment
		(start 79.99984 -255.497076)
		(end 80.008222 -255.501902)
		(width 0.0889)
		(layer "In13.Cu")
		(net "M_B_CPU1_SA_PAR")
	)
	(segment
		(start 64.988186 -255.743964)
		(end 65.576196 -255.155954)
		(width 0.14478)
		(layer "In13.Cu")
		(net "M_B_CPU1_SA_PAR")
	)
	(segment
		(start 52.877466 -255.03759)
		(end 52.877466 -255.242314)
		(width 0.14478)
		(layer "In13.Cu")
		(net "M_B_CPU1_SA_PAR")
	)
	(segment
		(start 88.094058 -255.501902)
		(end 88.10244 -255.497076)
		(width 0.0889)
		(layer "In13.Cu")
		(net "M_B_CPU1_SA_PAR")
	)
	(segment
		(start 81.879694 -255.497076)
		(end 81.888076 -255.501902)
		(width 0.0889)
		(layer "In13.Cu")
		(net "M_B_CPU1_SA_PAR")
	)
	(segment
		(start 53.034692 -254.67564)
		(end 53.034692 -254.880364)
		(width 0.14478)
		(layer "In13.Cu")
		(net "M_B_CPU1_SA_PAR")
	)
	(segment
		(start 52.644294 -254.285242)
		(end 53.034692 -254.67564)
		(width 0.14478)
		(layer "In13.Cu")
		(net "M_B_CPU1_SA_PAR")
	)
	(segment
		(start 76.819252 -256.610104)
		(end 77.851254 -255.578102)
		(width 0.0889)
		(layer "In13.Cu")
		(net "M_B_CPU1_SA_PAR")
	)
	(segment
		(start 53.424582 -255.270254)
		(end 53.629306 -255.270254)
		(width 0.14478)
		(layer "In13.Cu")
		(net "M_B_CPU1_SA_PAR")
	)
	(segment
		(start 53.267356 -255.42748)
		(end 53.424582 -255.270254)
		(width 0.14478)
		(layer "In13.Cu")
		(net "M_B_CPU1_SA_PAR")
	)
	(segment
		(start 78.693518 -255.502156)
		(end 78.709774 -255.492758)
		(width 0.0889)
		(layer "In13.Cu")
		(net "M_B_CPU1_SA_PAR")
	)
	(segment
		(start 87.154004 -255.501902)
		(end 87.162386 -255.497076)
		(width 0.0889)
		(layer "In13.Cu")
		(net "M_B_CPU1_SA_PAR")
	)
	(segment
		(start 71.573136 -255.155954)
		(end 73.027286 -256.610104)
		(width 0.14478)
		(layer "In13.Cu")
		(net "M_B_CPU1_SA_PAR")
	)
	(segment
		(start 88.97112 -255.533652)
		(end 89.067132 -255.559052)
		(width 0.0889)
		(layer "In13.Cu")
		(net "M_B_CPU1_SA_PAR")
	)
	(segment
		(start 73.027286 -256.610104)
		(end 76.560426 -256.610104)
		(width 0.14478)
		(layer "In13.Cu")
		(net "M_B_CPU1_SA_PAR")
	)
	(arc
		(start 86.21395 -255.501902)
		(mid 86.396201 -255.451552)
		(end 86.57971 -255.497076)
		(width 0.0889)
		(layer "In13.Cu")
		(net "M_B_CPU1_SA_PAR")
	)
	(arc
		(start 83.402424 -255.497076)
		(mid 83.585932 -255.451582)
		(end 83.768184 -255.501902)
		(width 0.0889)
		(layer "In13.Cu")
		(net "M_B_CPU1_SA_PAR")
	)
	(arc
		(start 88.10244 -255.497076)
		(mid 88.285948 -255.451582)
		(end 88.4682 -255.501902)
		(width 0.0889)
		(layer "In13.Cu")
		(net "M_B_CPU1_SA_PAR")
	)
	(arc
		(start 87.162386 -255.497076)
		(mid 87.345894 -255.451582)
		(end 87.528146 -255.501902)
		(width 0.0889)
		(layer "In13.Cu")
		(net "M_B_CPU1_SA_PAR")
	)
	(arc
		(start 78.41107 -255.578102)
		(mid 78.557318 -255.558797)
		(end 78.693518 -255.502156)
		(width 0.0889)
		(layer "In13.Cu")
		(net "M_B_CPU1_SA_PAR")
	)
	(arc
		(start 79.633572 -255.501902)
		(mid 79.816077 -255.451425)
		(end 79.99984 -255.497076)
		(width 0.0889)
		(layer "In13.Cu")
		(net "M_B_CPU1_SA_PAR")
	)
	(arc
		(start 85.273896 -255.501902)
		(mid 85.456147 -255.451552)
		(end 85.639656 -255.497076)
		(width 0.0889)
		(layer "In13.Cu")
		(net "M_B_CPU1_SA_PAR")
	)
	(arc
		(start 79.07782 -255.507998)
		(mid 79.356506 -255.578218)
		(end 79.633572 -255.501902)
		(width 0.0889)
		(layer "In13.Cu")
		(net "M_B_CPU1_SA_PAR")
	)
	(arc
		(start 80.008222 -255.501902)
		(mid 80.291178 -255.578079)
		(end 80.574134 -255.501902)
		(width 0.0889)
		(layer "In13.Cu")
		(net "M_B_CPU1_SA_PAR")
	)
	(arc
		(start 82.82813 -255.501902)
		(mid 83.111086 -255.578079)
		(end 83.394042 -255.501902)
		(width 0.0889)
		(layer "In13.Cu")
		(net "M_B_CPU1_SA_PAR")
	)
	(arc
		(start 84.707984 -255.501902)
		(mid 84.99094 -255.578079)
		(end 85.273896 -255.501902)
		(width 0.0889)
		(layer "In13.Cu")
		(net "M_B_CPU1_SA_PAR")
	)
	(arc
		(start 87.528146 -255.501902)
		(mid 87.811102 -255.578079)
		(end 88.094058 -255.501902)
		(width 0.0889)
		(layer "In13.Cu")
		(net "M_B_CPU1_SA_PAR")
	)
	(arc
		(start 83.768184 -255.501902)
		(mid 84.05114 -255.578079)
		(end 84.334096 -255.501902)
		(width 0.0889)
		(layer "In13.Cu")
		(net "M_B_CPU1_SA_PAR")
	)
	(arc
		(start 82.46237 -255.497076)
		(mid 82.645878 -255.451582)
		(end 82.82813 -255.501902)
		(width 0.0889)
		(layer "In13.Cu")
		(net "M_B_CPU1_SA_PAR")
	)
	(arc
		(start 78.709774 -255.492758)
		(mid 78.889756 -255.451658)
		(end 79.067406 -255.501902)
		(width 0.0889)
		(layer "In13.Cu")
		(net "M_B_CPU1_SA_PAR")
	)
	(arc
		(start 81.888076 -255.501902)
		(mid 82.171032 -255.578079)
		(end 82.453988 -255.501902)
		(width 0.0889)
		(layer "In13.Cu")
		(net "M_B_CPU1_SA_PAR")
	)
	(arc
		(start 85.648038 -255.501902)
		(mid 85.930994 -255.578079)
		(end 86.21395 -255.501902)
		(width 0.0889)
		(layer "In13.Cu")
		(net "M_B_CPU1_SA_PAR")
	)
	(arc
		(start 88.4682 -255.501902)
		(mid 88.715913 -255.577122)
		(end 88.97112 -255.533652)
		(width 0.0889)
		(layer "In13.Cu")
		(net "M_B_CPU1_SA_PAR")
	)
	(arc
		(start 80.574134 -255.501902)
		(mid 80.761078 -255.451647)
		(end 80.948022 -255.501902)
		(width 0.0889)
		(layer "In13.Cu")
		(net "M_B_CPU1_SA_PAR")
	)
	(arc
		(start 84.334096 -255.501902)
		(mid 84.52104 -255.451647)
		(end 84.707984 -255.501902)
		(width 0.0889)
		(layer "In13.Cu")
		(net "M_B_CPU1_SA_PAR")
	)
	(arc
		(start 80.948022 -255.501902)
		(mid 81.230978 -255.578079)
		(end 81.513934 -255.501902)
		(width 0.0889)
		(layer "In13.Cu")
		(net "M_B_CPU1_SA_PAR")
	)
	(arc
		(start 86.588092 -255.501902)
		(mid 86.871048 -255.578079)
		(end 87.154004 -255.501902)
		(width 0.0889)
		(layer "In13.Cu")
		(net "M_B_CPU1_SA_PAR")
	)
	(arc
		(start 81.513934 -255.501902)
		(mid 81.696185 -255.451552)
		(end 81.879694 -255.497076)
		(width 0.0889)
		(layer "In13.Cu")
		(net "M_B_CPU1_SA_PAR")
	)
	(segment
		(start 89.687908 -247.99036)
		(end 89.221056 -247.724422)
		(width 0.12954)
		(layer "F.Cu")
		(net "M_B_CPU1_SA_DQS_DP<9>")
	)
	(segment
		(start 75.259438 -247.336056)
		(end 75.087988 -247.164606)
		(width 0.16002)
		(layer "In13.Cu")
		(net "M_B_CPU1_SA_DQS_DP<9>")
	)
	(segment
		(start 77.552804 -247.582436)
		(end 76.50353 -247.582436)
		(width 0.09525)
		(layer "In13.Cu")
		(net "M_B_CPU1_SA_DQS_DP<9>")
	)
	(segment
		(start 64.771524 -247.164606)
		(end 59.867292 -242.260374)
		(width 0.16002)
		(layer "In13.Cu")
		(net "M_B_CPU1_SA_DQS_DP<9>")
	)
	(segment
		(start 55.543704 -239.698276)
		(end 54.483254 -240.137442)
		(width 0.16002)
		(layer "In13.Cu")
		(net "M_B_CPU1_SA_DQS_DP<9>")
	)
	(segment
		(start 82.460846 -247.394476)
		(end 82.452464 -247.399302)
		(width 0.09525)
		(layer "In13.Cu")
		(net "M_B_CPU1_SA_DQS_DP<9>")
	)
	(segment
		(start 75.087988 -247.164606)
		(end 64.771524 -247.164606)
		(width 0.16002)
		(layer "In13.Cu")
		(net "M_B_CPU1_SA_DQS_DP<9>")
	)
	(segment
		(start 56.043576 -239.698276)
		(end 55.543704 -239.698276)
		(width 0.16002)
		(layer "In13.Cu")
		(net "M_B_CPU1_SA_DQS_DP<9>")
	)
	(segment
		(start 89.067132 -247.458992)
		(end 88.966294 -247.432322)
		(width 0.09525)
		(layer "In13.Cu")
		(net "M_B_CPU1_SA_DQS_DP<9>")
	)
	(segment
		(start 50.688494 -239.341406)
		(end 49.98085 -239.341406)
		(width 0.16002)
		(layer "In13.Cu")
		(net "M_B_CPU1_SA_DQS_DP<9>")
	)
	(segment
		(start 48.043338 -239.576102)
		(end 47.784004 -239.835436)
		(width 0.16002)
		(layer "In13.Cu")
		(net "M_B_CPU1_SA_DQS_DP<9>")
	)
	(segment
		(start 86.589616 -247.399302)
		(end 86.581234 -247.394476)
		(width 0.09525)
		(layer "In13.Cu")
		(net "M_B_CPU1_SA_DQS_DP<9>")
	)
	(segment
		(start 80.009746 -247.399302)
		(end 80.001364 -247.394476)
		(width 0.09525)
		(layer "In13.Cu")
		(net "M_B_CPU1_SA_DQS_DP<9>")
	)
	(segment
		(start 52.923186 -239.710468)
		(end 51.579526 -239.710468)
		(width 0.16002)
		(layer "In13.Cu")
		(net "M_B_CPU1_SA_DQS_DP<9>")
	)
	(segment
		(start 49.98085 -239.341406)
		(end 49.413922 -239.576102)
		(width 0.16002)
		(layer "In13.Cu")
		(net "M_B_CPU1_SA_DQS_DP<9>")
	)
	(segment
		(start 79.079344 -247.405398)
		(end 79.06893 -247.399302)
		(width 0.09525)
		(layer "In13.Cu")
		(net "M_B_CPU1_SA_DQS_DP<9>")
	)
	(segment
		(start 75.979528 -247.336056)
		(end 75.955906 -247.336056)
		(width 0.09525)
		(layer "In13.Cu")
		(net "M_B_CPU1_SA_DQS_DP<9>")
	)
	(segment
		(start 78.691994 -247.399302)
		(end 78.671166 -247.411494)
		(width 0.09525)
		(layer "In13.Cu")
		(net "M_B_CPU1_SA_DQS_DP<9>")
	)
	(segment
		(start 59.867292 -242.260374)
		(end 59.062366 -242.260374)
		(width 0.16002)
		(layer "In13.Cu")
		(net "M_B_CPU1_SA_DQS_DP<9>")
	)
	(segment
		(start 54.483254 -240.137442)
		(end 53.954426 -240.137442)
		(width 0.16002)
		(layer "In13.Cu")
		(net "M_B_CPU1_SA_DQS_DP<9>")
	)
	(segment
		(start 87.160862 -247.394476)
		(end 87.15248 -247.399302)
		(width 0.09525)
		(layer "In13.Cu")
		(net "M_B_CPU1_SA_DQS_DP<9>")
	)
	(segment
		(start 83.4009 -247.394476)
		(end 83.392518 -247.399302)
		(width 0.09525)
		(layer "In13.Cu")
		(net "M_B_CPU1_SA_DQS_DP<9>")
	)
	(segment
		(start 85.649562 -247.399302)
		(end 85.64118 -247.394476)
		(width 0.09525)
		(layer "In13.Cu")
		(net "M_B_CPU1_SA_DQS_DP<9>")
	)
	(segment
		(start 53.954426 -240.137442)
		(end 52.923186 -239.710468)
		(width 0.16002)
		(layer "In13.Cu")
		(net "M_B_CPU1_SA_DQS_DP<9>")
	)
	(segment
		(start 76.197968 -247.276874)
		(end 76.03871 -247.276874)
		(width 0.09525)
		(layer "In13.Cu")
		(net "M_B_CPU1_SA_DQS_DP<9>")
	)
	(segment
		(start 77.940154 -247.34774)
		(end 77.7875 -247.34774)
		(width 0.09525)
		(layer "In13.Cu")
		(net "M_B_CPU1_SA_DQS_DP<9>")
	)
	(segment
		(start 49.413922 -239.576102)
		(end 48.043338 -239.576102)
		(width 0.16002)
		(layer "In13.Cu")
		(net "M_B_CPU1_SA_DQS_DP<9>")
	)
	(segment
		(start 77.7875 -247.34774)
		(end 77.552804 -247.582436)
		(width 0.09525)
		(layer "In13.Cu")
		(net "M_B_CPU1_SA_DQS_DP<9>")
	)
	(segment
		(start 75.955906 -247.336056)
		(end 75.259438 -247.336056)
		(width 0.16002)
		(layer "In13.Cu")
		(net "M_B_CPU1_SA_DQS_DP<9>")
	)
	(segment
		(start 51.579526 -239.710468)
		(end 50.688494 -239.341406)
		(width 0.16002)
		(layer "In13.Cu")
		(net "M_B_CPU1_SA_DQS_DP<9>")
	)
	(segment
		(start 78.703932 -247.392444)
		(end 78.691994 -247.399302)
		(width 0.09525)
		(layer "In13.Cu")
		(net "M_B_CPU1_SA_DQS_DP<9>")
	)
	(segment
		(start 89.221056 -247.724422)
		(end 89.067132 -247.458992)
		(width 0.09525)
		(layer "In13.Cu")
		(net "M_B_CPU1_SA_DQS_DP<9>")
	)
	(segment
		(start 88.100916 -247.394476)
		(end 88.092534 -247.399302)
		(width 0.09525)
		(layer "In13.Cu")
		(net "M_B_CPU1_SA_DQS_DP<9>")
	)
	(segment
		(start 59.062366 -242.260374)
		(end 56.823102 -240.02111)
		(width 0.16002)
		(layer "In13.Cu")
		(net "M_B_CPU1_SA_DQS_DP<9>")
	)
	(segment
		(start 56.823102 -240.02111)
		(end 56.043576 -239.698276)
		(width 0.16002)
		(layer "In13.Cu")
		(net "M_B_CPU1_SA_DQS_DP<9>")
	)
	(segment
		(start 76.50353 -247.582436)
		(end 76.197968 -247.276874)
		(width 0.09525)
		(layer "In13.Cu")
		(net "M_B_CPU1_SA_DQS_DP<9>")
	)
	(segment
		(start 76.03871 -247.276874)
		(end 75.979528 -247.336056)
		(width 0.09525)
		(layer "In13.Cu")
		(net "M_B_CPU1_SA_DQS_DP<9>")
	)
	(segment
		(start 81.8896 -247.399302)
		(end 81.881218 -247.394476)
		(width 0.09525)
		(layer "In13.Cu")
		(net "M_B_CPU1_SA_DQS_DP<9>")
	)
	(arc
		(start 78.671166 -247.411494)
		(mid 78.398561 -247.47529)
		(end 78.12913 -247.399302)
		(width 0.09525)
		(layer "In13.Cu")
		(net "M_B_CPU1_SA_DQS_DP<9>")
	)
	(arc
		(start 80.949546 -247.399302)
		(mid 80.761078 -247.348625)
		(end 80.57261 -247.399302)
		(width 0.09525)
		(layer "In13.Cu")
		(net "M_B_CPU1_SA_DQS_DP<9>")
	)
	(arc
		(start 85.64118 -247.394476)
		(mid 85.456148 -247.348562)
		(end 85.272372 -247.399302)
		(width 0.09525)
		(layer "In13.Cu")
		(net "M_B_CPU1_SA_DQS_DP<9>")
	)
	(arc
		(start 80.57261 -247.399302)
		(mid 80.291178 -247.475057)
		(end 80.009746 -247.399302)
		(width 0.09525)
		(layer "In13.Cu")
		(net "M_B_CPU1_SA_DQS_DP<9>")
	)
	(arc
		(start 82.829654 -247.399302)
		(mid 82.645879 -247.34853)
		(end 82.460846 -247.394476)
		(width 0.09525)
		(layer "In13.Cu")
		(net "M_B_CPU1_SA_DQS_DP<9>")
	)
	(arc
		(start 84.709508 -247.399302)
		(mid 84.52104 -247.348625)
		(end 84.332572 -247.399302)
		(width 0.09525)
		(layer "In13.Cu")
		(net "M_B_CPU1_SA_DQS_DP<9>")
	)
	(arc
		(start 82.452464 -247.399302)
		(mid 82.171032 -247.475057)
		(end 81.8896 -247.399302)
		(width 0.09525)
		(layer "In13.Cu")
		(net "M_B_CPU1_SA_DQS_DP<9>")
	)
	(arc
		(start 81.881218 -247.394476)
		(mid 81.696186 -247.348562)
		(end 81.51241 -247.399302)
		(width 0.09525)
		(layer "In13.Cu")
		(net "M_B_CPU1_SA_DQS_DP<9>")
	)
	(arc
		(start 88.469724 -247.399302)
		(mid 88.285949 -247.34853)
		(end 88.100916 -247.394476)
		(width 0.09525)
		(layer "In13.Cu")
		(net "M_B_CPU1_SA_DQS_DP<9>")
	)
	(arc
		(start 84.332572 -247.399302)
		(mid 84.05114 -247.475057)
		(end 83.769708 -247.399302)
		(width 0.09525)
		(layer "In13.Cu")
		(net "M_B_CPU1_SA_DQS_DP<9>")
	)
	(arc
		(start 81.51241 -247.399302)
		(mid 81.230978 -247.475057)
		(end 80.949546 -247.399302)
		(width 0.09525)
		(layer "In13.Cu")
		(net "M_B_CPU1_SA_DQS_DP<9>")
	)
	(arc
		(start 79.06893 -247.399302)
		(mid 78.887314 -247.348565)
		(end 78.703932 -247.392444)
		(width 0.09525)
		(layer "In13.Cu")
		(net "M_B_CPU1_SA_DQS_DP<9>")
	)
	(arc
		(start 87.52967 -247.399302)
		(mid 87.345895 -247.34853)
		(end 87.160862 -247.394476)
		(width 0.09525)
		(layer "In13.Cu")
		(net "M_B_CPU1_SA_DQS_DP<9>")
	)
	(arc
		(start 86.212426 -247.399302)
		(mid 85.930994 -247.475057)
		(end 85.649562 -247.399302)
		(width 0.09525)
		(layer "In13.Cu")
		(net "M_B_CPU1_SA_DQS_DP<9>")
	)
	(arc
		(start 78.12913 -247.399302)
		(mid 78.038053 -247.361018)
		(end 77.940154 -247.34774)
		(width 0.09525)
		(layer "In13.Cu")
		(net "M_B_CPU1_SA_DQS_DP<9>")
	)
	(arc
		(start 83.769708 -247.399302)
		(mid 83.585933 -247.34853)
		(end 83.4009 -247.394476)
		(width 0.09525)
		(layer "In13.Cu")
		(net "M_B_CPU1_SA_DQS_DP<9>")
	)
	(arc
		(start 87.15248 -247.399302)
		(mid 86.871048 -247.475057)
		(end 86.589616 -247.399302)
		(width 0.09525)
		(layer "In13.Cu")
		(net "M_B_CPU1_SA_DQS_DP<9>")
	)
	(arc
		(start 86.581234 -247.394476)
		(mid 86.396202 -247.348562)
		(end 86.212426 -247.399302)
		(width 0.09525)
		(layer "In13.Cu")
		(net "M_B_CPU1_SA_DQS_DP<9>")
	)
	(arc
		(start 80.001364 -247.394476)
		(mid 79.816078 -247.34844)
		(end 79.632048 -247.399302)
		(width 0.09525)
		(layer "In13.Cu")
		(net "M_B_CPU1_SA_DQS_DP<9>")
	)
	(arc
		(start 88.092534 -247.399302)
		(mid 87.811102 -247.475057)
		(end 87.52967 -247.399302)
		(width 0.09525)
		(layer "In13.Cu")
		(net "M_B_CPU1_SA_DQS_DP<9>")
	)
	(arc
		(start 79.632048 -247.399302)
		(mid 79.356505 -247.475151)
		(end 79.079344 -247.405398)
		(width 0.09525)
		(layer "In13.Cu")
		(net "M_B_CPU1_SA_DQS_DP<9>")
	)
	(arc
		(start 85.272372 -247.399302)
		(mid 84.99094 -247.475057)
		(end 84.709508 -247.399302)
		(width 0.09525)
		(layer "In13.Cu")
		(net "M_B_CPU1_SA_DQS_DP<9>")
	)
	(arc
		(start 88.966294 -247.432322)
		(mid 88.956172 -247.436357)
		(end 88.945974 -247.440196)
		(width 0.09525)
		(layer "In13.Cu")
		(net "M_B_CPU1_SA_DQS_DP<9>")
	)
	(arc
		(start 83.392518 -247.399302)
		(mid 83.111086 -247.475057)
		(end 82.829654 -247.399302)
		(width 0.09525)
		(layer "In13.Cu")
		(net "M_B_CPU1_SA_DQS_DP<9>")
	)
	(arc
		(start 88.945974 -247.440196)
		(mid 88.703262 -247.473079)
		(end 88.469724 -247.399302)
		(width 0.09525)
		(layer "In13.Cu")
		(net "M_B_CPU1_SA_DQS_DP<9>")
	)
	(segment
		(start 89.687908 -243.130324)
		(end 89.221056 -242.864386)
		(width 0.12954)
		(layer "F.Cu")
		(net "M_B_CPU1_SA_DQS_DP<8>")
	)
	(segment
		(start 81.8896 -242.539266)
		(end 81.881218 -242.53444)
		(width 0.09525)
		(layer "In13.Cu")
		(net "M_B_CPU1_SA_DQS_DP<8>")
	)
	(segment
		(start 57.247028 -230.875586)
		(end 56.523128 -230.875586)
		(width 0.16002)
		(layer "In13.Cu")
		(net "M_B_CPU1_SA_DQS_DP<8>")
	)
	(segment
		(start 50.340768 -229.991412)
		(end 50.089562 -230.242618)
		(width 0.16002)
		(layer "In13.Cu")
		(net "M_B_CPU1_SA_DQS_DP<8>")
	)
	(segment
		(start 48.026828 -230.242618)
		(end 47.784004 -230.485442)
		(width 0.16002)
		(layer "In13.Cu")
		(net "M_B_CPU1_SA_DQS_DP<8>")
	)
	(segment
		(start 78.691994 -242.539266)
		(end 78.671166 -242.551458)
		(width 0.09525)
		(layer "In13.Cu")
		(net "M_B_CPU1_SA_DQS_DP<8>")
	)
	(segment
		(start 89.221056 -242.864386)
		(end 89.067132 -242.598956)
		(width 0.09525)
		(layer "In13.Cu")
		(net "M_B_CPU1_SA_DQS_DP<8>")
	)
	(segment
		(start 59.868562 -231.210612)
		(end 57.582054 -231.210612)
		(width 0.16002)
		(layer "In13.Cu")
		(net "M_B_CPU1_SA_DQS_DP<8>")
	)
	(segment
		(start 86.589616 -242.539266)
		(end 86.581234 -242.53444)
		(width 0.09525)
		(layer "In13.Cu")
		(net "M_B_CPU1_SA_DQS_DP<8>")
	)
	(segment
		(start 76.677266 -242.159536)
		(end 76.24191 -241.72418)
		(width 0.09525)
		(layer "In13.Cu")
		(net "M_B_CPU1_SA_DQS_DP<8>")
	)
	(segment
		(start 87.160862 -242.53444)
		(end 87.15248 -242.539266)
		(width 0.09525)
		(layer "In13.Cu")
		(net "M_B_CPU1_SA_DQS_DP<8>")
	)
	(segment
		(start 50.655474 -229.991412)
		(end 50.340768 -229.991412)
		(width 0.16002)
		(layer "In13.Cu")
		(net "M_B_CPU1_SA_DQS_DP<8>")
	)
	(segment
		(start 54.276752 -231.179878)
		(end 53.457348 -230.360474)
		(width 0.16002)
		(layer "In13.Cu")
		(net "M_B_CPU1_SA_DQS_DP<8>")
	)
	(segment
		(start 56.218836 -231.179878)
		(end 54.276752 -231.179878)
		(width 0.16002)
		(layer "In13.Cu")
		(net "M_B_CPU1_SA_DQS_DP<8>")
	)
	(segment
		(start 57.582054 -231.210612)
		(end 57.247028 -230.875586)
		(width 0.16002)
		(layer "In13.Cu")
		(net "M_B_CPU1_SA_DQS_DP<8>")
	)
	(segment
		(start 70.207378 -241.549428)
		(end 59.868562 -231.210612)
		(width 0.16002)
		(layer "In13.Cu")
		(net "M_B_CPU1_SA_DQS_DP<8>")
	)
	(segment
		(start 75.921362 -241.549428)
		(end 75.89774 -241.549428)
		(width 0.09525)
		(layer "In13.Cu")
		(net "M_B_CPU1_SA_DQS_DP<8>")
	)
	(segment
		(start 56.523128 -230.875586)
		(end 56.218836 -231.179878)
		(width 0.16002)
		(layer "In13.Cu")
		(net "M_B_CPU1_SA_DQS_DP<8>")
	)
	(segment
		(start 75.980544 -241.490246)
		(end 75.921362 -241.549428)
		(width 0.09525)
		(layer "In13.Cu")
		(net "M_B_CPU1_SA_DQS_DP<8>")
	)
	(segment
		(start 79.632556 -242.539266)
		(end 79.617824 -242.547902)
		(width 0.09525)
		(layer "In13.Cu")
		(net "M_B_CPU1_SA_DQS_DP<8>")
	)
	(segment
		(start 78.706472 -242.530884)
		(end 78.691994 -242.539266)
		(width 0.09525)
		(layer "In13.Cu")
		(net "M_B_CPU1_SA_DQS_DP<8>")
	)
	(segment
		(start 75.89774 -241.549428)
		(end 70.207378 -241.549428)
		(width 0.16002)
		(layer "In13.Cu")
		(net "M_B_CPU1_SA_DQS_DP<8>")
	)
	(segment
		(start 82.460846 -242.53444)
		(end 82.452464 -242.539266)
		(width 0.09525)
		(layer "In13.Cu")
		(net "M_B_CPU1_SA_DQS_DP<8>")
	)
	(segment
		(start 88.100916 -242.53444)
		(end 88.092534 -242.539266)
		(width 0.09525)
		(layer "In13.Cu")
		(net "M_B_CPU1_SA_DQS_DP<8>")
	)
	(segment
		(start 77.344016 -242.159536)
		(end 76.677266 -242.159536)
		(width 0.09525)
		(layer "In13.Cu")
		(net "M_B_CPU1_SA_DQS_DP<8>")
	)
	(segment
		(start 76.24191 -241.59845)
		(end 76.133706 -241.490246)
		(width 0.09525)
		(layer "In13.Cu")
		(net "M_B_CPU1_SA_DQS_DP<8>")
	)
	(segment
		(start 77.672184 -242.487704)
		(end 77.344016 -242.159536)
		(width 0.09525)
		(layer "In13.Cu")
		(net "M_B_CPU1_SA_DQS_DP<8>")
	)
	(segment
		(start 76.24191 -241.72418)
		(end 76.24191 -241.59845)
		(width 0.09525)
		(layer "In13.Cu")
		(net "M_B_CPU1_SA_DQS_DP<8>")
	)
	(segment
		(start 79.640938 -242.53444)
		(end 79.632556 -242.539266)
		(width 0.09525)
		(layer "In13.Cu")
		(net "M_B_CPU1_SA_DQS_DP<8>")
	)
	(segment
		(start 77.940154 -242.487704)
		(end 77.672184 -242.487704)
		(width 0.09525)
		(layer "In13.Cu")
		(net "M_B_CPU1_SA_DQS_DP<8>")
	)
	(segment
		(start 51.024536 -230.360474)
		(end 50.655474 -229.991412)
		(width 0.16002)
		(layer "In13.Cu")
		(net "M_B_CPU1_SA_DQS_DP<8>")
	)
	(segment
		(start 50.089562 -230.242618)
		(end 48.026828 -230.242618)
		(width 0.16002)
		(layer "In13.Cu")
		(net "M_B_CPU1_SA_DQS_DP<8>")
	)
	(segment
		(start 83.4009 -242.53444)
		(end 83.392518 -242.539266)
		(width 0.09525)
		(layer "In13.Cu")
		(net "M_B_CPU1_SA_DQS_DP<8>")
	)
	(segment
		(start 53.457348 -230.360474)
		(end 51.024536 -230.360474)
		(width 0.16002)
		(layer "In13.Cu")
		(net "M_B_CPU1_SA_DQS_DP<8>")
	)
	(segment
		(start 76.133706 -241.490246)
		(end 75.980544 -241.490246)
		(width 0.09525)
		(layer "In13.Cu")
		(net "M_B_CPU1_SA_DQS_DP<8>")
	)
	(segment
		(start 89.067132 -242.598956)
		(end 88.966294 -242.572286)
		(width 0.09525)
		(layer "In13.Cu")
		(net "M_B_CPU1_SA_DQS_DP<8>")
	)
	(segment
		(start 85.649562 -242.539266)
		(end 85.64118 -242.53444)
		(width 0.09525)
		(layer "In13.Cu")
		(net "M_B_CPU1_SA_DQS_DP<8>")
	)
	(arc
		(start 80.009746 -242.539266)
		(mid 79.825971 -242.488494)
		(end 79.640938 -242.53444)
		(width 0.09525)
		(layer "In13.Cu")
		(net "M_B_CPU1_SA_DQS_DP<8>")
	)
	(arc
		(start 79.617824 -242.547902)
		(mid 79.342365 -242.615287)
		(end 79.069184 -242.539266)
		(width 0.09525)
		(layer "In13.Cu")
		(net "M_B_CPU1_SA_DQS_DP<8>")
	)
	(arc
		(start 85.64118 -242.53444)
		(mid 85.456148 -242.488526)
		(end 85.272372 -242.539266)
		(width 0.09525)
		(layer "In13.Cu")
		(net "M_B_CPU1_SA_DQS_DP<8>")
	)
	(arc
		(start 88.945974 -242.58016)
		(mid 88.703262 -242.613043)
		(end 88.469724 -242.539266)
		(width 0.09525)
		(layer "In13.Cu")
		(net "M_B_CPU1_SA_DQS_DP<8>")
	)
	(arc
		(start 78.671166 -242.551458)
		(mid 78.398561 -242.615254)
		(end 78.12913 -242.539266)
		(width 0.09525)
		(layer "In13.Cu")
		(net "M_B_CPU1_SA_DQS_DP<8>")
	)
	(arc
		(start 88.469724 -242.539266)
		(mid 88.285949 -242.488494)
		(end 88.100916 -242.53444)
		(width 0.09525)
		(layer "In13.Cu")
		(net "M_B_CPU1_SA_DQS_DP<8>")
	)
	(arc
		(start 78.12913 -242.539266)
		(mid 78.038053 -242.500982)
		(end 77.940154 -242.487704)
		(width 0.09525)
		(layer "In13.Cu")
		(net "M_B_CPU1_SA_DQS_DP<8>")
	)
	(arc
		(start 84.709508 -242.539266)
		(mid 84.52104 -242.488589)
		(end 84.332572 -242.539266)
		(width 0.09525)
		(layer "In13.Cu")
		(net "M_B_CPU1_SA_DQS_DP<8>")
	)
	(arc
		(start 82.452464 -242.539266)
		(mid 82.171032 -242.615021)
		(end 81.8896 -242.539266)
		(width 0.09525)
		(layer "In13.Cu")
		(net "M_B_CPU1_SA_DQS_DP<8>")
	)
	(arc
		(start 88.966294 -242.572286)
		(mid 88.956172 -242.576321)
		(end 88.945974 -242.58016)
		(width 0.09525)
		(layer "In13.Cu")
		(net "M_B_CPU1_SA_DQS_DP<8>")
	)
	(arc
		(start 83.769708 -242.539266)
		(mid 83.585933 -242.488494)
		(end 83.4009 -242.53444)
		(width 0.09525)
		(layer "In13.Cu")
		(net "M_B_CPU1_SA_DQS_DP<8>")
	)
	(arc
		(start 88.092534 -242.539266)
		(mid 87.811102 -242.615021)
		(end 87.52967 -242.539266)
		(width 0.09525)
		(layer "In13.Cu")
		(net "M_B_CPU1_SA_DQS_DP<8>")
	)
	(arc
		(start 87.52967 -242.539266)
		(mid 87.345895 -242.488494)
		(end 87.160862 -242.53444)
		(width 0.09525)
		(layer "In13.Cu")
		(net "M_B_CPU1_SA_DQS_DP<8>")
	)
	(arc
		(start 86.581234 -242.53444)
		(mid 86.396202 -242.488526)
		(end 86.212426 -242.539266)
		(width 0.09525)
		(layer "In13.Cu")
		(net "M_B_CPU1_SA_DQS_DP<8>")
	)
	(arc
		(start 81.881218 -242.53444)
		(mid 81.696186 -242.488526)
		(end 81.51241 -242.539266)
		(width 0.09525)
		(layer "In13.Cu")
		(net "M_B_CPU1_SA_DQS_DP<8>")
	)
	(arc
		(start 80.57261 -242.539266)
		(mid 80.291178 -242.615021)
		(end 80.009746 -242.539266)
		(width 0.09525)
		(layer "In13.Cu")
		(net "M_B_CPU1_SA_DQS_DP<8>")
	)
	(arc
		(start 79.069184 -242.539266)
		(mid 78.888905 -242.488435)
		(end 78.706472 -242.530884)
		(width 0.09525)
		(layer "In13.Cu")
		(net "M_B_CPU1_SA_DQS_DP<8>")
	)
	(arc
		(start 84.332572 -242.539266)
		(mid 84.05114 -242.615021)
		(end 83.769708 -242.539266)
		(width 0.09525)
		(layer "In13.Cu")
		(net "M_B_CPU1_SA_DQS_DP<8>")
	)
	(arc
		(start 82.829654 -242.539266)
		(mid 82.645879 -242.488494)
		(end 82.460846 -242.53444)
		(width 0.09525)
		(layer "In13.Cu")
		(net "M_B_CPU1_SA_DQS_DP<8>")
	)
	(arc
		(start 80.949546 -242.539266)
		(mid 80.761078 -242.488589)
		(end 80.57261 -242.539266)
		(width 0.09525)
		(layer "In13.Cu")
		(net "M_B_CPU1_SA_DQS_DP<8>")
	)
	(arc
		(start 86.212426 -242.539266)
		(mid 85.930994 -242.615021)
		(end 85.649562 -242.539266)
		(width 0.09525)
		(layer "In13.Cu")
		(net "M_B_CPU1_SA_DQS_DP<8>")
	)
	(arc
		(start 87.15248 -242.539266)
		(mid 86.871048 -242.615021)
		(end 86.589616 -242.539266)
		(width 0.09525)
		(layer "In13.Cu")
		(net "M_B_CPU1_SA_DQS_DP<8>")
	)
	(arc
		(start 81.51241 -242.539266)
		(mid 81.230978 -242.615021)
		(end 80.949546 -242.539266)
		(width 0.09525)
		(layer "In13.Cu")
		(net "M_B_CPU1_SA_DQS_DP<8>")
	)
	(arc
		(start 83.392518 -242.539266)
		(mid 83.111086 -242.615021)
		(end 82.829654 -242.539266)
		(width 0.09525)
		(layer "In13.Cu")
		(net "M_B_CPU1_SA_DQS_DP<8>")
	)
	(arc
		(start 85.272372 -242.539266)
		(mid 84.99094 -242.615021)
		(end 84.709508 -242.539266)
		(width 0.09525)
		(layer "In13.Cu")
		(net "M_B_CPU1_SA_DQS_DP<8>")
	)
	(segment
		(start 89.687908 -238.270288)
		(end 89.221056 -238.00435)
		(width 0.12954)
		(layer "F.Cu")
		(net "M_B_CPU1_SA_DQS_DP<7>")
	)
	(segment
		(start 60.46597 -222.364046)
		(end 59.962288 -221.860364)
		(width 0.16002)
		(layer "In13.Cu")
		(net "M_B_CPU1_SA_DQS_DP<7>")
	)
	(segment
		(start 54.255924 -221.829884)
		(end 53.43652 -221.01048)
		(width 0.16002)
		(layer "In13.Cu")
		(net "M_B_CPU1_SA_DQS_DP<7>")
	)
	(segment
		(start 83.4009 -237.674404)
		(end 83.392518 -237.67923)
		(width 0.09525)
		(layer "In13.Cu")
		(net "M_B_CPU1_SA_DQS_DP<7>")
	)
	(segment
		(start 60.46597 -222.720408)
		(end 60.46597 -222.364046)
		(width 0.16002)
		(layer "In13.Cu")
		(net "M_B_CPU1_SA_DQS_DP<7>")
	)
	(segment
		(start 59.962288 -221.860364)
		(end 57.546748 -221.860364)
		(width 0.16002)
		(layer "In13.Cu")
		(net "M_B_CPU1_SA_DQS_DP<7>")
	)
	(segment
		(start 78.170024 -237.755684)
		(end 77.20838 -236.79404)
		(width 0.09525)
		(layer "In13.Cu")
		(net "M_B_CPU1_SA_DQS_DP<7>")
	)
	(segment
		(start 76.173584 -235.872274)
		(end 76.03871 -235.872274)
		(width 0.09525)
		(layer "In13.Cu")
		(net "M_B_CPU1_SA_DQS_DP<7>")
	)
	(segment
		(start 53.43652 -221.01048)
		(end 51.024536 -221.01048)
		(width 0.16002)
		(layer "In13.Cu")
		(net "M_B_CPU1_SA_DQS_DP<7>")
	)
	(segment
		(start 78.411324 -237.755684)
		(end 78.170024 -237.755684)
		(width 0.09525)
		(layer "In13.Cu")
		(net "M_B_CPU1_SA_DQS_DP<7>")
	)
	(segment
		(start 89.221056 -238.00435)
		(end 89.067132 -237.73892)
		(width 0.09525)
		(layer "In13.Cu")
		(net "M_B_CPU1_SA_DQS_DP<7>")
	)
	(segment
		(start 77.20838 -236.502194)
		(end 76.938632 -236.232446)
		(width 0.09525)
		(layer "In13.Cu")
		(net "M_B_CPU1_SA_DQS_DP<7>")
	)
	(segment
		(start 50.655474 -220.641418)
		(end 49.143412 -220.641418)
		(width 0.16002)
		(layer "In13.Cu")
		(net "M_B_CPU1_SA_DQS_DP<7>")
	)
	(segment
		(start 86.589616 -237.67923)
		(end 86.581234 -237.674404)
		(width 0.09525)
		(layer "In13.Cu")
		(net "M_B_CPU1_SA_DQS_DP<7>")
	)
	(segment
		(start 73.677018 -235.931456)
		(end 60.46597 -222.720408)
		(width 0.16002)
		(layer "In13.Cu")
		(net "M_B_CPU1_SA_DQS_DP<7>")
	)
	(segment
		(start 76.533756 -236.232446)
		(end 76.173584 -235.872274)
		(width 0.09525)
		(layer "In13.Cu")
		(net "M_B_CPU1_SA_DQS_DP<7>")
	)
	(segment
		(start 56.218836 -221.829884)
		(end 54.255924 -221.829884)
		(width 0.16002)
		(layer "In13.Cu")
		(net "M_B_CPU1_SA_DQS_DP<7>")
	)
	(segment
		(start 57.546748 -221.860364)
		(end 57.211976 -221.525592)
		(width 0.16002)
		(layer "In13.Cu")
		(net "M_B_CPU1_SA_DQS_DP<7>")
	)
	(segment
		(start 87.160862 -237.674404)
		(end 87.15248 -237.67923)
		(width 0.09525)
		(layer "In13.Cu")
		(net "M_B_CPU1_SA_DQS_DP<7>")
	)
	(segment
		(start 76.03871 -235.872274)
		(end 75.979528 -235.931456)
		(width 0.09525)
		(layer "In13.Cu")
		(net "M_B_CPU1_SA_DQS_DP<7>")
	)
	(segment
		(start 57.211976 -221.525592)
		(end 56.523128 -221.525592)
		(width 0.16002)
		(layer "In13.Cu")
		(net "M_B_CPU1_SA_DQS_DP<7>")
	)
	(segment
		(start 79.652368 -237.668562)
		(end 79.633572 -237.67923)
		(width 0.09525)
		(layer "In13.Cu")
		(net "M_B_CPU1_SA_DQS_DP<7>")
	)
	(segment
		(start 48.055276 -220.863922)
		(end 47.784004 -221.135194)
		(width 0.16002)
		(layer "In13.Cu")
		(net "M_B_CPU1_SA_DQS_DP<7>")
	)
	(segment
		(start 76.938632 -236.232446)
		(end 76.533756 -236.232446)
		(width 0.09525)
		(layer "In13.Cu")
		(net "M_B_CPU1_SA_DQS_DP<7>")
	)
	(segment
		(start 82.460846 -237.674404)
		(end 82.452464 -237.67923)
		(width 0.09525)
		(layer "In13.Cu")
		(net "M_B_CPU1_SA_DQS_DP<7>")
	)
	(segment
		(start 79.633572 -237.67923)
		(end 79.60614 -237.695232)
		(width 0.09525)
		(layer "In13.Cu")
		(net "M_B_CPU1_SA_DQS_DP<7>")
	)
	(segment
		(start 85.649562 -237.67923)
		(end 85.64118 -237.674404)
		(width 0.09525)
		(layer "In13.Cu")
		(net "M_B_CPU1_SA_DQS_DP<7>")
	)
	(segment
		(start 89.067132 -237.73892)
		(end 88.966294 -237.71225)
		(width 0.09525)
		(layer "In13.Cu")
		(net "M_B_CPU1_SA_DQS_DP<7>")
	)
	(segment
		(start 75.955906 -235.931456)
		(end 73.677018 -235.931456)
		(width 0.16002)
		(layer "In13.Cu")
		(net "M_B_CPU1_SA_DQS_DP<7>")
	)
	(segment
		(start 75.979528 -235.931456)
		(end 75.955906 -235.931456)
		(width 0.09525)
		(layer "In13.Cu")
		(net "M_B_CPU1_SA_DQS_DP<7>")
	)
	(segment
		(start 51.024536 -221.01048)
		(end 50.655474 -220.641418)
		(width 0.16002)
		(layer "In13.Cu")
		(net "M_B_CPU1_SA_DQS_DP<7>")
	)
	(segment
		(start 48.920908 -220.863922)
		(end 48.055276 -220.863922)
		(width 0.16002)
		(layer "In13.Cu")
		(net "M_B_CPU1_SA_DQS_DP<7>")
	)
	(segment
		(start 77.20838 -236.79404)
		(end 77.20838 -236.502194)
		(width 0.09525)
		(layer "In13.Cu")
		(net "M_B_CPU1_SA_DQS_DP<7>")
	)
	(segment
		(start 81.8896 -237.67923)
		(end 81.881218 -237.674404)
		(width 0.09525)
		(layer "In13.Cu")
		(net "M_B_CPU1_SA_DQS_DP<7>")
	)
	(segment
		(start 56.523128 -221.525592)
		(end 56.218836 -221.829884)
		(width 0.16002)
		(layer "In13.Cu")
		(net "M_B_CPU1_SA_DQS_DP<7>")
	)
	(segment
		(start 88.100916 -237.674404)
		(end 88.092534 -237.67923)
		(width 0.09525)
		(layer "In13.Cu")
		(net "M_B_CPU1_SA_DQS_DP<7>")
	)
	(segment
		(start 79.072486 -237.67923)
		(end 79.050642 -237.66653)
		(width 0.09525)
		(layer "In13.Cu")
		(net "M_B_CPU1_SA_DQS_DP<7>")
	)
	(segment
		(start 49.143412 -220.641418)
		(end 48.920908 -220.863922)
		(width 0.16002)
		(layer "In13.Cu")
		(net "M_B_CPU1_SA_DQS_DP<7>")
	)
	(arc
		(start 85.64118 -237.674404)
		(mid 85.456148 -237.62849)
		(end 85.272372 -237.67923)
		(width 0.09525)
		(layer "In13.Cu")
		(net "M_B_CPU1_SA_DQS_DP<7>")
	)
	(arc
		(start 80.009746 -237.67923)
		(mid 79.832416 -237.628718)
		(end 79.652368 -237.668562)
		(width 0.09525)
		(layer "In13.Cu")
		(net "M_B_CPU1_SA_DQS_DP<7>")
	)
	(arc
		(start 87.52967 -237.67923)
		(mid 87.345895 -237.628458)
		(end 87.160862 -237.674404)
		(width 0.09525)
		(layer "In13.Cu")
		(net "M_B_CPU1_SA_DQS_DP<7>")
	)
	(arc
		(start 81.51241 -237.67923)
		(mid 81.230978 -237.754985)
		(end 80.949546 -237.67923)
		(width 0.09525)
		(layer "In13.Cu")
		(net "M_B_CPU1_SA_DQS_DP<7>")
	)
	(arc
		(start 88.092534 -237.67923)
		(mid 87.811102 -237.754985)
		(end 87.52967 -237.67923)
		(width 0.09525)
		(layer "In13.Cu")
		(net "M_B_CPU1_SA_DQS_DP<7>")
	)
	(arc
		(start 84.332572 -237.67923)
		(mid 84.05114 -237.754985)
		(end 83.769708 -237.67923)
		(width 0.09525)
		(layer "In13.Cu")
		(net "M_B_CPU1_SA_DQS_DP<7>")
	)
	(arc
		(start 88.469724 -237.67923)
		(mid 88.285949 -237.628458)
		(end 88.100916 -237.674404)
		(width 0.09525)
		(layer "In13.Cu")
		(net "M_B_CPU1_SA_DQS_DP<7>")
	)
	(arc
		(start 82.452464 -237.67923)
		(mid 82.171032 -237.754985)
		(end 81.8896 -237.67923)
		(width 0.09525)
		(layer "In13.Cu")
		(net "M_B_CPU1_SA_DQS_DP<7>")
	)
	(arc
		(start 79.050642 -237.66653)
		(mid 78.870892 -237.627901)
		(end 78.69428 -237.678976)
		(width 0.09525)
		(layer "In13.Cu")
		(net "M_B_CPU1_SA_DQS_DP<7>")
	)
	(arc
		(start 87.15248 -237.67923)
		(mid 86.871048 -237.754985)
		(end 86.589616 -237.67923)
		(width 0.09525)
		(layer "In13.Cu")
		(net "M_B_CPU1_SA_DQS_DP<7>")
	)
	(arc
		(start 80.949546 -237.67923)
		(mid 80.761078 -237.628553)
		(end 80.57261 -237.67923)
		(width 0.09525)
		(layer "In13.Cu")
		(net "M_B_CPU1_SA_DQS_DP<7>")
	)
	(arc
		(start 82.829654 -237.67923)
		(mid 82.645879 -237.628458)
		(end 82.460846 -237.674404)
		(width 0.09525)
		(layer "In13.Cu")
		(net "M_B_CPU1_SA_DQS_DP<7>")
	)
	(arc
		(start 83.392518 -237.67923)
		(mid 83.111086 -237.754985)
		(end 82.829654 -237.67923)
		(width 0.09525)
		(layer "In13.Cu")
		(net "M_B_CPU1_SA_DQS_DP<7>")
	)
	(arc
		(start 80.57261 -237.67923)
		(mid 80.291178 -237.754985)
		(end 80.009746 -237.67923)
		(width 0.09525)
		(layer "In13.Cu")
		(net "M_B_CPU1_SA_DQS_DP<7>")
	)
	(arc
		(start 81.881218 -237.674404)
		(mid 81.696186 -237.62849)
		(end 81.51241 -237.67923)
		(width 0.09525)
		(layer "In13.Cu")
		(net "M_B_CPU1_SA_DQS_DP<7>")
	)
	(arc
		(start 85.272372 -237.67923)
		(mid 84.99094 -237.754985)
		(end 84.709508 -237.67923)
		(width 0.09525)
		(layer "In13.Cu")
		(net "M_B_CPU1_SA_DQS_DP<7>")
	)
	(arc
		(start 84.709508 -237.67923)
		(mid 84.52104 -237.628553)
		(end 84.332572 -237.67923)
		(width 0.09525)
		(layer "In13.Cu")
		(net "M_B_CPU1_SA_DQS_DP<7>")
	)
	(arc
		(start 88.966294 -237.71225)
		(mid 88.956172 -237.716285)
		(end 88.945974 -237.720124)
		(width 0.09525)
		(layer "In13.Cu")
		(net "M_B_CPU1_SA_DQS_DP<7>")
	)
	(arc
		(start 78.425802 -237.755684)
		(mid 78.418563 -237.755729)
		(end 78.411324 -237.755684)
		(width 0.09525)
		(layer "In13.Cu")
		(net "M_B_CPU1_SA_DQS_DP<7>")
	)
	(arc
		(start 86.212426 -237.67923)
		(mid 85.930994 -237.754985)
		(end 85.649562 -237.67923)
		(width 0.09525)
		(layer "In13.Cu")
		(net "M_B_CPU1_SA_DQS_DP<7>")
	)
	(arc
		(start 83.769708 -237.67923)
		(mid 83.585933 -237.628458)
		(end 83.4009 -237.674404)
		(width 0.09525)
		(layer "In13.Cu")
		(net "M_B_CPU1_SA_DQS_DP<7>")
	)
	(arc
		(start 78.69428 -237.678976)
		(mid 78.564887 -237.734296)
		(end 78.425802 -237.755684)
		(width 0.09525)
		(layer "In13.Cu")
		(net "M_B_CPU1_SA_DQS_DP<7>")
	)
	(arc
		(start 86.581234 -237.674404)
		(mid 86.396202 -237.62849)
		(end 86.212426 -237.67923)
		(width 0.09525)
		(layer "In13.Cu")
		(net "M_B_CPU1_SA_DQS_DP<7>")
	)
	(arc
		(start 88.945974 -237.720124)
		(mid 88.703262 -237.753007)
		(end 88.469724 -237.67923)
		(width 0.09525)
		(layer "In13.Cu")
		(net "M_B_CPU1_SA_DQS_DP<7>")
	)
	(arc
		(start 79.60614 -237.695232)
		(mid 79.337297 -237.754783)
		(end 79.072486 -237.67923)
		(width 0.09525)
		(layer "In13.Cu")
		(net "M_B_CPU1_SA_DQS_DP<7>")
	)
	(segment
		(start 89.687908 -233.410252)
		(end 89.221056 -233.144314)
		(width 0.12954)
		(layer "F.Cu")
		(net "M_B_CPU1_SA_DQS_DP<6>")
	)
	(segment
		(start 48.050196 -211.519008)
		(end 48.740822 -211.519008)
		(width 0.16002)
		(layer "In13.Cu")
		(net "M_B_CPU1_SA_DQS_DP<6>")
	)
	(segment
		(start 88.092534 -232.819194)
		(end 88.100916 -232.814368)
		(width 0.09525)
		(layer "In13.Cu")
		(net "M_B_CPU1_SA_DQS_DP<6>")
	)
	(segment
		(start 50.649124 -211.306664)
		(end 51.002946 -211.660486)
		(width 0.16002)
		(layer "In13.Cu")
		(net "M_B_CPU1_SA_DQS_DP<6>")
	)
	(segment
		(start 79.417926 -232.767886)
		(end 79.821024 -232.767886)
		(width 0.09525)
		(layer "In13.Cu")
		(net "M_B_CPU1_SA_DQS_DP<6>")
	)
	(segment
		(start 59.837574 -212.51037)
		(end 72.63765 -225.310446)
		(width 0.16002)
		(layer "In13.Cu")
		(net "M_B_CPU1_SA_DQS_DP<6>")
	)
	(segment
		(start 72.63765 -225.310446)
		(end 72.63765 -226.837748)
		(width 0.16002)
		(layer "In13.Cu")
		(net "M_B_CPU1_SA_DQS_DP<6>")
	)
	(segment
		(start 53.983382 -212.190838)
		(end 57.267602 -212.190838)
		(width 0.16002)
		(layer "In13.Cu")
		(net "M_B_CPU1_SA_DQS_DP<6>")
	)
	(segment
		(start 76.160884 -230.361236)
		(end 76.244704 -230.361236)
		(width 0.09525)
		(layer "In13.Cu")
		(net "M_B_CPU1_SA_DQS_DP<6>")
	)
	(segment
		(start 53.45303 -211.660486)
		(end 53.983382 -212.190838)
		(width 0.16002)
		(layer "In13.Cu")
		(net "M_B_CPU1_SA_DQS_DP<6>")
	)
	(segment
		(start 89.067132 -232.878884)
		(end 89.221056 -233.144314)
		(width 0.09525)
		(layer "In13.Cu")
		(net "M_B_CPU1_SA_DQS_DP<6>")
	)
	(segment
		(start 48.953166 -211.306664)
		(end 50.649124 -211.306664)
		(width 0.16002)
		(layer "In13.Cu")
		(net "M_B_CPU1_SA_DQS_DP<6>")
	)
	(segment
		(start 48.740822 -211.519008)
		(end 48.953166 -211.306664)
		(width 0.16002)
		(layer "In13.Cu")
		(net "M_B_CPU1_SA_DQS_DP<6>")
	)
	(segment
		(start 88.966294 -232.852214)
		(end 89.067132 -232.878884)
		(width 0.09525)
		(layer "In13.Cu")
		(net "M_B_CPU1_SA_DQS_DP<6>")
	)
	(segment
		(start 76.14412 -230.344472)
		(end 76.160884 -230.361236)
		(width 0.09525)
		(layer "In13.Cu")
		(net "M_B_CPU1_SA_DQS_DP<6>")
	)
	(segment
		(start 87.15248 -232.819194)
		(end 87.160862 -232.814368)
		(width 0.09525)
		(layer "In13.Cu")
		(net "M_B_CPU1_SA_DQS_DP<6>")
	)
	(segment
		(start 77.422756 -230.772716)
		(end 79.417926 -232.767886)
		(width 0.09525)
		(layer "In13.Cu")
		(net "M_B_CPU1_SA_DQS_DP<6>")
	)
	(segment
		(start 82.452464 -232.819194)
		(end 82.460846 -232.814368)
		(width 0.09525)
		(layer "In13.Cu")
		(net "M_B_CPU1_SA_DQS_DP<6>")
	)
	(segment
		(start 81.881218 -232.814368)
		(end 81.8896 -232.819194)
		(width 0.09525)
		(layer "In13.Cu")
		(net "M_B_CPU1_SA_DQS_DP<6>")
	)
	(segment
		(start 76.656184 -230.772716)
		(end 77.422756 -230.772716)
		(width 0.09525)
		(layer "In13.Cu")
		(net "M_B_CPU1_SA_DQS_DP<6>")
	)
	(segment
		(start 86.581234 -232.814368)
		(end 86.589616 -232.819194)
		(width 0.09525)
		(layer "In13.Cu")
		(net "M_B_CPU1_SA_DQS_DP<6>")
	)
	(segment
		(start 51.002946 -211.660486)
		(end 53.45303 -211.660486)
		(width 0.16002)
		(layer "In13.Cu")
		(net "M_B_CPU1_SA_DQS_DP<6>")
	)
	(segment
		(start 72.965564 -227.165916)
		(end 76.14412 -230.344472)
		(width 0.16002)
		(layer "In13.Cu")
		(net "M_B_CPU1_SA_DQS_DP<6>")
	)
	(segment
		(start 72.965564 -227.165662)
		(end 72.965564 -227.165916)
		(width 0.16002)
		(layer "In13.Cu")
		(net "M_B_CPU1_SA_DQS_DP<6>")
	)
	(segment
		(start 47.784004 -211.7852)
		(end 48.050196 -211.519008)
		(width 0.16002)
		(layer "In13.Cu")
		(net "M_B_CPU1_SA_DQS_DP<6>")
	)
	(segment
		(start 57.267602 -212.190838)
		(end 57.587134 -212.51037)
		(width 0.16002)
		(layer "In13.Cu")
		(net "M_B_CPU1_SA_DQS_DP<6>")
	)
	(segment
		(start 72.63765 -226.837748)
		(end 72.965564 -227.165662)
		(width 0.16002)
		(layer "In13.Cu")
		(net "M_B_CPU1_SA_DQS_DP<6>")
	)
	(segment
		(start 76.244704 -230.361236)
		(end 76.656184 -230.772716)
		(width 0.09525)
		(layer "In13.Cu")
		(net "M_B_CPU1_SA_DQS_DP<6>")
	)
	(segment
		(start 57.587134 -212.51037)
		(end 59.837574 -212.51037)
		(width 0.16002)
		(layer "In13.Cu")
		(net "M_B_CPU1_SA_DQS_DP<6>")
	)
	(segment
		(start 83.392518 -232.819194)
		(end 83.4009 -232.814368)
		(width 0.09525)
		(layer "In13.Cu")
		(net "M_B_CPU1_SA_DQS_DP<6>")
	)
	(segment
		(start 85.64118 -232.814368)
		(end 85.649562 -232.819194)
		(width 0.09525)
		(layer "In13.Cu")
		(net "M_B_CPU1_SA_DQS_DP<6>")
	)
	(arc
		(start 88.945974 -232.860088)
		(mid 88.956173 -232.856251)
		(end 88.966294 -232.852214)
		(width 0.09525)
		(layer "In13.Cu")
		(net "M_B_CPU1_SA_DQS_DP<6>")
	)
	(arc
		(start 86.212426 -232.819194)
		(mid 86.396201 -232.768422)
		(end 86.581234 -232.814368)
		(width 0.09525)
		(layer "In13.Cu")
		(net "M_B_CPU1_SA_DQS_DP<6>")
	)
	(arc
		(start 82.829654 -232.819194)
		(mid 83.111086 -232.894949)
		(end 83.392518 -232.819194)
		(width 0.09525)
		(layer "In13.Cu")
		(net "M_B_CPU1_SA_DQS_DP<6>")
	)
	(arc
		(start 80.57261 -232.819194)
		(mid 80.761078 -232.768517)
		(end 80.949546 -232.819194)
		(width 0.09525)
		(layer "In13.Cu")
		(net "M_B_CPU1_SA_DQS_DP<6>")
	)
	(arc
		(start 87.160862 -232.814368)
		(mid 87.345894 -232.768454)
		(end 87.52967 -232.819194)
		(width 0.09525)
		(layer "In13.Cu")
		(net "M_B_CPU1_SA_DQS_DP<6>")
	)
	(arc
		(start 81.51241 -232.819194)
		(mid 81.696185 -232.768422)
		(end 81.881218 -232.814368)
		(width 0.09525)
		(layer "In13.Cu")
		(net "M_B_CPU1_SA_DQS_DP<6>")
	)
	(arc
		(start 83.769708 -232.819194)
		(mid 84.05114 -232.894949)
		(end 84.332572 -232.819194)
		(width 0.09525)
		(layer "In13.Cu")
		(net "M_B_CPU1_SA_DQS_DP<6>")
	)
	(arc
		(start 83.4009 -232.814368)
		(mid 83.585932 -232.768454)
		(end 83.769708 -232.819194)
		(width 0.09525)
		(layer "In13.Cu")
		(net "M_B_CPU1_SA_DQS_DP<6>")
	)
	(arc
		(start 84.332572 -232.819194)
		(mid 84.52104 -232.768517)
		(end 84.709508 -232.819194)
		(width 0.09525)
		(layer "In13.Cu")
		(net "M_B_CPU1_SA_DQS_DP<6>")
	)
	(arc
		(start 80.949546 -232.819194)
		(mid 81.230978 -232.894949)
		(end 81.51241 -232.819194)
		(width 0.09525)
		(layer "In13.Cu")
		(net "M_B_CPU1_SA_DQS_DP<6>")
	)
	(arc
		(start 81.8896 -232.819194)
		(mid 82.171032 -232.894949)
		(end 82.452464 -232.819194)
		(width 0.09525)
		(layer "In13.Cu")
		(net "M_B_CPU1_SA_DQS_DP<6>")
	)
	(arc
		(start 88.469724 -232.819194)
		(mid 88.703268 -232.8929)
		(end 88.945974 -232.860088)
		(width 0.09525)
		(layer "In13.Cu")
		(net "M_B_CPU1_SA_DQS_DP<6>")
	)
	(arc
		(start 85.649562 -232.819194)
		(mid 85.930994 -232.894949)
		(end 86.212426 -232.819194)
		(width 0.09525)
		(layer "In13.Cu")
		(net "M_B_CPU1_SA_DQS_DP<6>")
	)
	(arc
		(start 88.100916 -232.814368)
		(mid 88.285948 -232.768454)
		(end 88.469724 -232.819194)
		(width 0.09525)
		(layer "In13.Cu")
		(net "M_B_CPU1_SA_DQS_DP<6>")
	)
	(arc
		(start 84.709508 -232.819194)
		(mid 84.99094 -232.894949)
		(end 85.272372 -232.819194)
		(width 0.09525)
		(layer "In13.Cu")
		(net "M_B_CPU1_SA_DQS_DP<6>")
	)
	(arc
		(start 79.821024 -232.767886)
		(mid 79.91877 -232.781081)
		(end 80.009746 -232.819194)
		(width 0.09525)
		(layer "In13.Cu")
		(net "M_B_CPU1_SA_DQS_DP<6>")
	)
	(arc
		(start 82.460846 -232.814368)
		(mid 82.645878 -232.768454)
		(end 82.829654 -232.819194)
		(width 0.09525)
		(layer "In13.Cu")
		(net "M_B_CPU1_SA_DQS_DP<6>")
	)
	(arc
		(start 86.589616 -232.819194)
		(mid 86.871048 -232.894949)
		(end 87.15248 -232.819194)
		(width 0.09525)
		(layer "In13.Cu")
		(net "M_B_CPU1_SA_DQS_DP<6>")
	)
	(arc
		(start 87.52967 -232.819194)
		(mid 87.811102 -232.894949)
		(end 88.092534 -232.819194)
		(width 0.09525)
		(layer "In13.Cu")
		(net "M_B_CPU1_SA_DQS_DP<6>")
	)
	(arc
		(start 80.009746 -232.819194)
		(mid 80.291178 -232.894949)
		(end 80.57261 -232.819194)
		(width 0.09525)
		(layer "In13.Cu")
		(net "M_B_CPU1_SA_DQS_DP<6>")
	)
	(arc
		(start 85.272372 -232.819194)
		(mid 85.456147 -232.768422)
		(end 85.64118 -232.814368)
		(width 0.09525)
		(layer "In13.Cu")
		(net "M_B_CPU1_SA_DQS_DP<6>")
	)
	(segment
		(start 89.687908 -228.55047)
		(end 89.221056 -228.284532)
		(width 0.12954)
		(layer "F.Cu")
		(net "M_B_CPU1_SA_DQS_DP<5>")
	)
	(segment
		(start 53.431694 -202.310492)
		(end 53.856636 -202.735434)
		(width 0.16002)
		(layer "In13.Cu")
		(net "M_B_CPU1_SA_DQS_DP<5>")
	)
	(segment
		(start 86.581234 -227.954586)
		(end 86.589616 -227.959412)
		(width 0.09525)
		(layer "In13.Cu")
		(net "M_B_CPU1_SA_DQS_DP<5>")
	)
	(segment
		(start 47.784004 -202.435206)
		(end 48.047402 -202.171808)
		(width 0.16002)
		(layer "In13.Cu")
		(net "M_B_CPU1_SA_DQS_DP<5>")
	)
	(segment
		(start 77.86497 -221.050358)
		(end 77.86497 -221.664784)
		(width 0.16002)
		(layer "In13.Cu")
		(net "M_B_CPU1_SA_DQS_DP<5>")
	)
	(segment
		(start 80.009746 -224.719388)
		(end 80.041242 -224.737676)
		(width 0.09525)
		(layer "In13.Cu")
		(net "M_B_CPU1_SA_DQS_DP<5>")
	)
	(segment
		(start 79.5401 -223.909382)
		(end 79.570326 -223.926908)
		(width 0.09525)
		(layer "In13.Cu")
		(net "M_B_CPU1_SA_DQS_DP<5>")
	)
	(segment
		(start 81.3816 -227.127308)
		(end 81.4197 -227.149406)
		(width 0.09525)
		(layer "In13.Cu")
		(net "M_B_CPU1_SA_DQS_DP<5>")
	)
	(segment
		(start 81.4197 -227.149406)
		(end 81.451196 -227.167694)
		(width 0.09525)
		(layer "In13.Cu")
		(net "M_B_CPU1_SA_DQS_DP<5>")
	)
	(segment
		(start 56.202072 -202.249532)
		(end 57.149746 -202.641962)
		(width 0.16002)
		(layer "In13.Cu")
		(net "M_B_CPU1_SA_DQS_DP<5>")
	)
	(segment
		(start 55.154068 -202.249532)
		(end 56.202072 -202.249532)
		(width 0.16002)
		(layer "In13.Cu")
		(net "M_B_CPU1_SA_DQS_DP<5>")
	)
	(segment
		(start 88.092534 -227.959412)
		(end 88.100916 -227.954586)
		(width 0.09525)
		(layer "In13.Cu")
		(net "M_B_CPU1_SA_DQS_DP<5>")
	)
	(segment
		(start 83.392518 -227.959412)
		(end 83.4009 -227.954586)
		(width 0.09525)
		(layer "In13.Cu")
		(net "M_B_CPU1_SA_DQS_DP<5>")
	)
	(segment
		(start 78.181454 -221.981268)
		(end 78.265274 -221.981268)
		(width 0.09525)
		(layer "In13.Cu")
		(net "M_B_CPU1_SA_DQS_DP<5>")
	)
	(segment
		(start 80.479646 -225.529394)
		(end 80.512158 -225.54819)
		(width 0.09525)
		(layer "In13.Cu")
		(net "M_B_CPU1_SA_DQS_DP<5>")
	)
	(segment
		(start 53.856636 -202.735434)
		(end 54.668166 -202.735434)
		(width 0.16002)
		(layer "In13.Cu")
		(net "M_B_CPU1_SA_DQS_DP<5>")
	)
	(segment
		(start 49.045622 -202.171808)
		(end 49.259744 -201.957686)
		(width 0.16002)
		(layer "In13.Cu")
		(net "M_B_CPU1_SA_DQS_DP<5>")
	)
	(segment
		(start 85.64118 -227.954586)
		(end 85.649562 -227.959412)
		(width 0.09525)
		(layer "In13.Cu")
		(net "M_B_CPU1_SA_DQS_DP<5>")
	)
	(segment
		(start 48.047402 -202.171808)
		(end 49.045622 -202.171808)
		(width 0.16002)
		(layer "In13.Cu")
		(net "M_B_CPU1_SA_DQS_DP<5>")
	)
	(segment
		(start 57.66816 -203.160376)
		(end 59.974988 -203.160376)
		(width 0.16002)
		(layer "In13.Cu")
		(net "M_B_CPU1_SA_DQS_DP<5>")
	)
	(segment
		(start 57.149746 -202.641962)
		(end 57.66816 -203.160376)
		(width 0.16002)
		(layer "In13.Cu")
		(net "M_B_CPU1_SA_DQS_DP<5>")
	)
	(segment
		(start 49.259744 -201.957686)
		(end 50.660808 -201.957686)
		(width 0.16002)
		(layer "In13.Cu")
		(net "M_B_CPU1_SA_DQS_DP<5>")
	)
	(segment
		(start 77.86497 -221.664784)
		(end 78.16469 -221.964504)
		(width 0.16002)
		(layer "In13.Cu")
		(net "M_B_CPU1_SA_DQS_DP<5>")
	)
	(segment
		(start 78.265274 -221.981268)
		(end 78.48473 -222.200724)
		(width 0.09525)
		(layer "In13.Cu")
		(net "M_B_CPU1_SA_DQS_DP<5>")
	)
	(segment
		(start 80.949546 -226.3394)
		(end 80.982058 -226.358196)
		(width 0.09525)
		(layer "In13.Cu")
		(net "M_B_CPU1_SA_DQS_DP<5>")
	)
	(segment
		(start 81.8515 -227.937314)
		(end 81.8896 -227.959412)
		(width 0.09525)
		(layer "In13.Cu")
		(net "M_B_CPU1_SA_DQS_DP<5>")
	)
	(segment
		(start 50.660808 -201.957686)
		(end 51.013614 -202.310492)
		(width 0.16002)
		(layer "In13.Cu")
		(net "M_B_CPU1_SA_DQS_DP<5>")
	)
	(segment
		(start 79.974694 -224.698814)
		(end 80.009746 -224.719388)
		(width 0.09525)
		(layer "In13.Cu")
		(net "M_B_CPU1_SA_DQS_DP<5>")
	)
	(segment
		(start 82.452464 -227.959412)
		(end 82.460846 -227.954586)
		(width 0.09525)
		(layer "In13.Cu")
		(net "M_B_CPU1_SA_DQS_DP<5>")
	)
	(segment
		(start 51.013614 -202.310492)
		(end 53.431694 -202.310492)
		(width 0.16002)
		(layer "In13.Cu")
		(net "M_B_CPU1_SA_DQS_DP<5>")
	)
	(segment
		(start 87.15248 -227.959412)
		(end 87.160862 -227.954586)
		(width 0.09525)
		(layer "In13.Cu")
		(net "M_B_CPU1_SA_DQS_DP<5>")
	)
	(segment
		(start 80.914494 -226.318826)
		(end 80.949546 -226.3394)
		(width 0.09525)
		(layer "In13.Cu")
		(net "M_B_CPU1_SA_DQS_DP<5>")
	)
	(segment
		(start 80.441546 -225.507296)
		(end 80.479646 -225.529394)
		(width 0.09525)
		(layer "In13.Cu")
		(net "M_B_CPU1_SA_DQS_DP<5>")
	)
	(segment
		(start 78.600046 -222.28937)
		(end 78.633828 -222.308928)
		(width 0.09525)
		(layer "In13.Cu")
		(net "M_B_CPU1_SA_DQS_DP<5>")
	)
	(segment
		(start 54.668166 -202.735434)
		(end 55.154068 -202.249532)
		(width 0.16002)
		(layer "In13.Cu")
		(net "M_B_CPU1_SA_DQS_DP<5>")
	)
	(segment
		(start 79.036418 -223.079818)
		(end 79.069946 -223.099376)
		(width 0.09525)
		(layer "In13.Cu")
		(net "M_B_CPU1_SA_DQS_DP<5>")
	)
	(segment
		(start 59.974988 -203.160376)
		(end 77.86497 -221.050358)
		(width 0.16002)
		(layer "In13.Cu")
		(net "M_B_CPU1_SA_DQS_DP<5>")
	)
	(segment
		(start 79.069946 -223.099376)
		(end 79.102458 -223.118172)
		(width 0.09525)
		(layer "In13.Cu")
		(net "M_B_CPU1_SA_DQS_DP<5>")
	)
	(segment
		(start 89.067132 -228.019102)
		(end 89.221056 -228.284532)
		(width 0.09525)
		(layer "In13.Cu")
		(net "M_B_CPU1_SA_DQS_DP<5>")
	)
	(segment
		(start 79.499206 -223.88576)
		(end 79.5401 -223.909382)
		(width 0.09525)
		(layer "In13.Cu")
		(net "M_B_CPU1_SA_DQS_DP<5>")
	)
	(segment
		(start 78.16469 -221.964504)
		(end 78.181454 -221.981268)
		(width 0.09525)
		(layer "In13.Cu")
		(net "M_B_CPU1_SA_DQS_DP<5>")
	)
	(segment
		(start 88.966294 -227.992432)
		(end 89.067132 -228.019102)
		(width 0.09525)
		(layer "In13.Cu")
		(net "M_B_CPU1_SA_DQS_DP<5>")
	)
	(arc
		(start 88.945974 -228.000306)
		(mid 88.956173 -227.996469)
		(end 88.966294 -227.992432)
		(width 0.09525)
		(layer "In13.Cu")
		(net "M_B_CPU1_SA_DQS_DP<5>")
	)
	(arc
		(start 80.512158 -225.54819)
		(mid 80.627432 -225.682468)
		(end 80.668876 -225.854514)
		(width 0.09525)
		(layer "In13.Cu")
		(net "M_B_CPU1_SA_DQS_DP<5>")
	)
	(arc
		(start 81.451196 -227.167694)
		(mid 81.566994 -227.302088)
		(end 81.608676 -227.474526)
		(width 0.09525)
		(layer "In13.Cu")
		(net "M_B_CPU1_SA_DQS_DP<5>")
	)
	(arc
		(start 81.138776 -226.66452)
		(mid 81.203173 -226.925826)
		(end 81.3816 -227.127308)
		(width 0.09525)
		(layer "In13.Cu")
		(net "M_B_CPU1_SA_DQS_DP<5>")
	)
	(arc
		(start 86.589616 -227.959412)
		(mid 86.871048 -228.035167)
		(end 87.15248 -227.959412)
		(width 0.09525)
		(layer "In13.Cu")
		(net "M_B_CPU1_SA_DQS_DP<5>")
	)
	(arc
		(start 84.332572 -227.959412)
		(mid 84.52104 -227.908735)
		(end 84.709508 -227.959412)
		(width 0.09525)
		(layer "In13.Cu")
		(net "M_B_CPU1_SA_DQS_DP<5>")
	)
	(arc
		(start 78.78953 -222.61449)
		(mid 78.855083 -222.877862)
		(end 79.036418 -223.079818)
		(width 0.09525)
		(layer "In13.Cu")
		(net "M_B_CPU1_SA_DQS_DP<5>")
	)
	(arc
		(start 79.102458 -223.118172)
		(mid 79.217508 -223.252522)
		(end 79.258922 -223.424496)
		(width 0.09525)
		(layer "In13.Cu")
		(net "M_B_CPU1_SA_DQS_DP<5>")
	)
	(arc
		(start 80.982058 -226.358196)
		(mid 81.097332 -226.492474)
		(end 81.138776 -226.66452)
		(width 0.09525)
		(layer "In13.Cu")
		(net "M_B_CPU1_SA_DQS_DP<5>")
	)
	(arc
		(start 80.198722 -225.044508)
		(mid 80.263119 -225.305814)
		(end 80.441546 -225.507296)
		(width 0.09525)
		(layer "In13.Cu")
		(net "M_B_CPU1_SA_DQS_DP<5>")
	)
	(arc
		(start 79.258922 -223.424496)
		(mid 79.322595 -223.684543)
		(end 79.499206 -223.88576)
		(width 0.09525)
		(layer "In13.Cu")
		(net "M_B_CPU1_SA_DQS_DP<5>")
	)
	(arc
		(start 82.460846 -227.954586)
		(mid 82.645878 -227.908672)
		(end 82.829654 -227.959412)
		(width 0.09525)
		(layer "In13.Cu")
		(net "M_B_CPU1_SA_DQS_DP<5>")
	)
	(arc
		(start 81.608676 -227.474526)
		(mid 81.673073 -227.735832)
		(end 81.8515 -227.937314)
		(width 0.09525)
		(layer "In13.Cu")
		(net "M_B_CPU1_SA_DQS_DP<5>")
	)
	(arc
		(start 83.4009 -227.954586)
		(mid 83.585932 -227.908672)
		(end 83.769708 -227.959412)
		(width 0.09525)
		(layer "In13.Cu")
		(net "M_B_CPU1_SA_DQS_DP<5>")
	)
	(arc
		(start 79.570326 -223.926908)
		(mid 79.687027 -224.061437)
		(end 79.729076 -224.234502)
		(width 0.09525)
		(layer "In13.Cu")
		(net "M_B_CPU1_SA_DQS_DP<5>")
	)
	(arc
		(start 78.633828 -222.308928)
		(mid 78.748356 -222.443019)
		(end 78.78953 -222.61449)
		(width 0.09525)
		(layer "In13.Cu")
		(net "M_B_CPU1_SA_DQS_DP<5>")
	)
	(arc
		(start 87.52967 -227.959412)
		(mid 87.811102 -228.035167)
		(end 88.092534 -227.959412)
		(width 0.09525)
		(layer "In13.Cu")
		(net "M_B_CPU1_SA_DQS_DP<5>")
	)
	(arc
		(start 80.668876 -225.854514)
		(mid 80.734123 -226.117117)
		(end 80.914494 -226.318826)
		(width 0.09525)
		(layer "In13.Cu")
		(net "M_B_CPU1_SA_DQS_DP<5>")
	)
	(arc
		(start 78.48473 -222.200724)
		(mid 78.539505 -222.248797)
		(end 78.600046 -222.28937)
		(width 0.09525)
		(layer "In13.Cu")
		(net "M_B_CPU1_SA_DQS_DP<5>")
	)
	(arc
		(start 81.8896 -227.959412)
		(mid 82.171032 -228.035167)
		(end 82.452464 -227.959412)
		(width 0.09525)
		(layer "In13.Cu")
		(net "M_B_CPU1_SA_DQS_DP<5>")
	)
	(arc
		(start 88.100916 -227.954586)
		(mid 88.285948 -227.908672)
		(end 88.469724 -227.959412)
		(width 0.09525)
		(layer "In13.Cu")
		(net "M_B_CPU1_SA_DQS_DP<5>")
	)
	(arc
		(start 86.212426 -227.959412)
		(mid 86.396201 -227.90864)
		(end 86.581234 -227.954586)
		(width 0.09525)
		(layer "In13.Cu")
		(net "M_B_CPU1_SA_DQS_DP<5>")
	)
	(arc
		(start 82.829654 -227.959412)
		(mid 83.111086 -228.035167)
		(end 83.392518 -227.959412)
		(width 0.09525)
		(layer "In13.Cu")
		(net "M_B_CPU1_SA_DQS_DP<5>")
	)
	(arc
		(start 80.041242 -224.737676)
		(mid 80.15704 -224.87207)
		(end 80.198722 -225.044508)
		(width 0.09525)
		(layer "In13.Cu")
		(net "M_B_CPU1_SA_DQS_DP<5>")
	)
	(arc
		(start 87.160862 -227.954586)
		(mid 87.345894 -227.908672)
		(end 87.52967 -227.959412)
		(width 0.09525)
		(layer "In13.Cu")
		(net "M_B_CPU1_SA_DQS_DP<5>")
	)
	(arc
		(start 85.649562 -227.959412)
		(mid 85.930994 -228.035167)
		(end 86.212426 -227.959412)
		(width 0.09525)
		(layer "In13.Cu")
		(net "M_B_CPU1_SA_DQS_DP<5>")
	)
	(arc
		(start 83.769708 -227.959412)
		(mid 84.05114 -228.035167)
		(end 84.332572 -227.959412)
		(width 0.09525)
		(layer "In13.Cu")
		(net "M_B_CPU1_SA_DQS_DP<5>")
	)
	(arc
		(start 88.469724 -227.959412)
		(mid 88.703268 -228.033118)
		(end 88.945974 -228.000306)
		(width 0.09525)
		(layer "In13.Cu")
		(net "M_B_CPU1_SA_DQS_DP<5>")
	)
	(arc
		(start 85.272372 -227.959412)
		(mid 85.456147 -227.90864)
		(end 85.64118 -227.954586)
		(width 0.09525)
		(layer "In13.Cu")
		(net "M_B_CPU1_SA_DQS_DP<5>")
	)
	(arc
		(start 84.709508 -227.959412)
		(mid 84.99094 -228.035167)
		(end 85.272372 -227.959412)
		(width 0.09525)
		(layer "In13.Cu")
		(net "M_B_CPU1_SA_DQS_DP<5>")
	)
	(arc
		(start 79.729076 -224.234502)
		(mid 79.794323 -224.497105)
		(end 79.974694 -224.698814)
		(width 0.09525)
		(layer "In13.Cu")
		(net "M_B_CPU1_SA_DQS_DP<5>")
	)
	(segment
		(start 87.8078 -246.370348)
		(end 87.340948 -246.10441)
		(width 0.12954)
		(layer "F.Cu")
		(net "M_B_CPU1_SA_DQS_DP<4>")
	)
	(segment
		(start 52.171092 -238.422434)
		(end 52.656232 -238.422434)
		(width 0.16002)
		(layer "In13.Cu")
		(net "M_B_CPU1_SA_DQS_DP<4>")
	)
	(segment
		(start 59.901836 -240.575084)
		(end 60.99175 -241.664998)
		(width 0.16002)
		(layer "In13.Cu")
		(net "M_B_CPU1_SA_DQS_DP<4>")
	)
	(segment
		(start 64.825372 -244.130068)
		(end 65.199006 -244.503702)
		(width 0.16002)
		(layer "In13.Cu")
		(net "M_B_CPU1_SA_DQS_DP<4>")
	)
	(segment
		(start 86.581234 -246.434356)
		(end 86.589616 -246.42953)
		(width 0.09525)
		(layer "In13.Cu")
		(net "M_B_CPU1_SA_DQS_DP<4>")
	)
	(segment
		(start 82.452464 -246.42953)
		(end 82.460846 -246.434356)
		(width 0.09525)
		(layer "In13.Cu")
		(net "M_B_CPU1_SA_DQS_DP<4>")
	)
	(segment
		(start 63.54318 -243.939568)
		(end 63.54318 -244.216428)
		(width 0.16002)
		(layer "In13.Cu")
		(net "M_B_CPU1_SA_DQS_DP<4>")
	)
	(segment
		(start 61.26861 -241.664998)
		(end 61.550804 -241.382804)
		(width 0.16002)
		(layer "In13.Cu")
		(net "M_B_CPU1_SA_DQS_DP<4>")
	)
	(segment
		(start 55.856378 -238.288576)
		(end 57.699148 -239.051846)
		(width 0.16002)
		(layer "In13.Cu")
		(net "M_B_CPU1_SA_DQS_DP<4>")
	)
	(segment
		(start 76.452984 -246.538496)
		(end 76.677774 -246.763286)
		(width 0.09525)
		(layer "In13.Cu")
		(net "M_B_CPU1_SA_DQS_DP<4>")
	)
	(segment
		(start 63.825374 -243.13007)
		(end 63.825374 -243.657374)
		(width 0.16002)
		(layer "In13.Cu")
		(net "M_B_CPU1_SA_DQS_DP<4>")
	)
	(segment
		(start 58.378598 -239.051846)
		(end 58.775346 -239.448594)
		(width 0.16002)
		(layer "In13.Cu")
		(net "M_B_CPU1_SA_DQS_DP<4>")
	)
	(segment
		(start 79.633318 -246.42953)
		(end 79.650082 -246.439182)
		(width 0.09525)
		(layer "In13.Cu")
		(net "M_B_CPU1_SA_DQS_DP<4>")
	)
	(segment
		(start 57.699148 -239.051846)
		(end 58.378598 -239.051846)
		(width 0.16002)
		(layer "In13.Cu")
		(net "M_B_CPU1_SA_DQS_DP<4>")
	)
	(segment
		(start 61.550804 -241.382804)
		(end 62.078108 -241.382804)
		(width 0.16002)
		(layer "In13.Cu")
		(net "M_B_CPU1_SA_DQS_DP<4>")
	)
	(segment
		(start 60.99175 -241.664998)
		(end 61.26861 -241.664998)
		(width 0.16002)
		(layer "In13.Cu")
		(net "M_B_CPU1_SA_DQS_DP<4>")
	)
	(segment
		(start 76.250038 -246.050562)
		(end 76.452984 -246.253508)
		(width 0.09525)
		(layer "In13.Cu")
		(net "M_B_CPU1_SA_DQS_DP<4>")
	)
	(segment
		(start 51.884072 -238.135414)
		(end 52.171092 -238.422434)
		(width 0.16002)
		(layer "In13.Cu")
		(net "M_B_CPU1_SA_DQS_DP<4>")
	)
	(segment
		(start 77.32395 -246.763286)
		(end 77.606906 -246.48033)
		(width 0.09525)
		(layer "In13.Cu")
		(net "M_B_CPU1_SA_DQS_DP<4>")
	)
	(segment
		(start 87.471504 -246.456708)
		(end 87.494872 -246.36984)
		(width 0.09525)
		(layer "In13.Cu")
		(net "M_B_CPU1_SA_DQS_DP<4>")
	)
	(segment
		(start 65.199006 -244.503702)
		(end 65.199006 -245.031006)
		(width 0.16002)
		(layer "In13.Cu")
		(net "M_B_CPU1_SA_DQS_DP<4>")
	)
	(segment
		(start 63.54318 -244.216428)
		(end 63.739014 -244.412262)
		(width 0.16002)
		(layer "In13.Cu")
		(net "M_B_CPU1_SA_DQS_DP<4>")
	)
	(segment
		(start 62.642242 -243.03863)
		(end 62.924436 -242.756436)
		(width 0.16002)
		(layer "In13.Cu")
		(net "M_B_CPU1_SA_DQS_DP<4>")
	)
	(segment
		(start 77.606906 -246.48033)
		(end 77.943456 -246.48033)
		(width 0.09525)
		(layer "In13.Cu")
		(net "M_B_CPU1_SA_DQS_DP<4>")
	)
	(segment
		(start 76.677774 -246.763286)
		(end 77.32395 -246.763286)
		(width 0.09525)
		(layer "In13.Cu")
		(net "M_B_CPU1_SA_DQS_DP<4>")
	)
	(segment
		(start 62.924436 -242.756436)
		(end 63.45174 -242.756436)
		(width 0.16002)
		(layer "In13.Cu")
		(net "M_B_CPU1_SA_DQS_DP<4>")
	)
	(segment
		(start 87.494872 -246.36984)
		(end 87.340948 -246.10441)
		(width 0.09525)
		(layer "In13.Cu")
		(net "M_B_CPU1_SA_DQS_DP<4>")
	)
	(segment
		(start 64.916812 -245.59006)
		(end 65.318386 -245.991634)
		(width 0.16002)
		(layer "In13.Cu")
		(net "M_B_CPU1_SA_DQS_DP<4>")
	)
	(segment
		(start 62.365382 -243.03863)
		(end 62.642242 -243.03863)
		(width 0.16002)
		(layer "In13.Cu")
		(net "M_B_CPU1_SA_DQS_DP<4>")
	)
	(segment
		(start 60.10275 -239.671606)
		(end 60.10275 -240.14811)
		(width 0.16002)
		(layer "In13.Cu")
		(net "M_B_CPU1_SA_DQS_DP<4>")
	)
	(segment
		(start 52.79009 -238.288576)
		(end 55.856378 -238.288576)
		(width 0.16002)
		(layer "In13.Cu")
		(net "M_B_CPU1_SA_DQS_DP<4>")
	)
	(segment
		(start 63.45174 -242.756436)
		(end 63.825374 -243.13007)
		(width 0.16002)
		(layer "In13.Cu")
		(net "M_B_CPU1_SA_DQS_DP<4>")
	)
	(segment
		(start 75.879706 -245.991634)
		(end 75.903328 -245.991634)
		(width 0.09525)
		(layer "In13.Cu")
		(net "M_B_CPU1_SA_DQS_DP<4>")
	)
	(segment
		(start 60.10275 -240.14811)
		(end 59.901836 -240.349024)
		(width 0.16002)
		(layer "In13.Cu")
		(net "M_B_CPU1_SA_DQS_DP<4>")
	)
	(segment
		(start 62.451742 -241.756438)
		(end 62.451742 -242.283742)
		(width 0.16002)
		(layer "In13.Cu")
		(net "M_B_CPU1_SA_DQS_DP<4>")
	)
	(segment
		(start 63.825374 -243.657374)
		(end 63.54318 -243.939568)
		(width 0.16002)
		(layer "In13.Cu")
		(net "M_B_CPU1_SA_DQS_DP<4>")
	)
	(segment
		(start 52.656232 -238.422434)
		(end 52.79009 -238.288576)
		(width 0.16002)
		(layer "In13.Cu")
		(net "M_B_CPU1_SA_DQS_DP<4>")
	)
	(segment
		(start 76.452984 -246.253508)
		(end 76.452984 -246.538496)
		(width 0.09525)
		(layer "In13.Cu")
		(net "M_B_CPU1_SA_DQS_DP<4>")
	)
	(segment
		(start 65.318386 -245.991634)
		(end 75.879706 -245.991634)
		(width 0.16002)
		(layer "In13.Cu")
		(net "M_B_CPU1_SA_DQS_DP<4>")
	)
	(segment
		(start 85.64118 -246.434356)
		(end 85.649562 -246.42953)
		(width 0.09525)
		(layer "In13.Cu")
		(net "M_B_CPU1_SA_DQS_DP<4>")
	)
	(segment
		(start 87.15248 -246.42953)
		(end 87.160862 -246.434356)
		(width 0.09525)
		(layer "In13.Cu")
		(net "M_B_CPU1_SA_DQS_DP<4>")
	)
	(segment
		(start 64.916812 -245.3132)
		(end 64.916812 -245.59006)
		(width 0.16002)
		(layer "In13.Cu")
		(net "M_B_CPU1_SA_DQS_DP<4>")
	)
	(segment
		(start 59.901836 -240.349024)
		(end 59.901836 -240.575084)
		(width 0.16002)
		(layer "In13.Cu")
		(net "M_B_CPU1_SA_DQS_DP<4>")
	)
	(segment
		(start 58.775346 -239.448594)
		(end 59.001406 -239.448594)
		(width 0.16002)
		(layer "In13.Cu")
		(net "M_B_CPU1_SA_DQS_DP<4>")
	)
	(segment
		(start 64.298068 -244.130068)
		(end 64.825372 -244.130068)
		(width 0.16002)
		(layer "In13.Cu")
		(net "M_B_CPU1_SA_DQS_DP<4>")
	)
	(segment
		(start 78.131162 -246.42953)
		(end 78.165706 -246.409464)
		(width 0.09525)
		(layer "In13.Cu")
		(net "M_B_CPU1_SA_DQS_DP<4>")
	)
	(segment
		(start 59.001406 -239.448594)
		(end 59.20232 -239.24768)
		(width 0.16002)
		(layer "In13.Cu")
		(net "M_B_CPU1_SA_DQS_DP<4>")
	)
	(segment
		(start 63.739014 -244.412262)
		(end 64.015874 -244.412262)
		(width 0.16002)
		(layer "In13.Cu")
		(net "M_B_CPU1_SA_DQS_DP<4>")
	)
	(segment
		(start 64.015874 -244.412262)
		(end 64.298068 -244.130068)
		(width 0.16002)
		(layer "In13.Cu")
		(net "M_B_CPU1_SA_DQS_DP<4>")
	)
	(segment
		(start 65.199006 -245.031006)
		(end 64.916812 -245.3132)
		(width 0.16002)
		(layer "In13.Cu")
		(net "M_B_CPU1_SA_DQS_DP<4>")
	)
	(segment
		(start 59.678824 -239.24768)
		(end 60.10275 -239.671606)
		(width 0.16002)
		(layer "In13.Cu")
		(net "M_B_CPU1_SA_DQS_DP<4>")
	)
	(segment
		(start 83.392518 -246.42953)
		(end 83.4009 -246.434356)
		(width 0.09525)
		(layer "In13.Cu")
		(net "M_B_CPU1_SA_DQS_DP<4>")
	)
	(segment
		(start 75.903328 -245.991634)
		(end 75.962256 -246.050562)
		(width 0.09525)
		(layer "In13.Cu")
		(net "M_B_CPU1_SA_DQS_DP<4>")
	)
	(segment
		(start 59.20232 -239.24768)
		(end 59.678824 -239.24768)
		(width 0.16002)
		(layer "In13.Cu")
		(net "M_B_CPU1_SA_DQS_DP<4>")
	)
	(segment
		(start 81.881218 -246.434356)
		(end 81.8896 -246.42953)
		(width 0.09525)
		(layer "In13.Cu")
		(net "M_B_CPU1_SA_DQS_DP<4>")
	)
	(segment
		(start 62.169548 -242.842796)
		(end 62.365382 -243.03863)
		(width 0.16002)
		(layer "In13.Cu")
		(net "M_B_CPU1_SA_DQS_DP<4>")
	)
	(segment
		(start 62.169548 -242.565936)
		(end 62.169548 -242.842796)
		(width 0.16002)
		(layer "In13.Cu")
		(net "M_B_CPU1_SA_DQS_DP<4>")
	)
	(segment
		(start 62.078108 -241.382804)
		(end 62.451742 -241.756438)
		(width 0.16002)
		(layer "In13.Cu")
		(net "M_B_CPU1_SA_DQS_DP<4>")
	)
	(segment
		(start 79.607918 -246.414798)
		(end 79.633318 -246.42953)
		(width 0.09525)
		(layer "In13.Cu")
		(net "M_B_CPU1_SA_DQS_DP<4>")
	)
	(segment
		(start 75.962256 -246.050562)
		(end 76.250038 -246.050562)
		(width 0.09525)
		(layer "In13.Cu")
		(net "M_B_CPU1_SA_DQS_DP<4>")
	)
	(segment
		(start 79.053182 -246.440452)
		(end 79.071978 -246.42953)
		(width 0.09525)
		(layer "In13.Cu")
		(net "M_B_CPU1_SA_DQS_DP<4>")
	)
	(segment
		(start 62.451742 -242.283742)
		(end 62.169548 -242.565936)
		(width 0.16002)
		(layer "In13.Cu")
		(net "M_B_CPU1_SA_DQS_DP<4>")
	)
	(arc
		(start 80.009746 -246.42953)
		(mid 80.291178 -246.353775)
		(end 80.57261 -246.42953)
		(width 0.09525)
		(layer "In13.Cu")
		(net "M_B_CPU1_SA_DQS_DP<4>")
	)
	(arc
		(start 85.649562 -246.42953)
		(mid 85.930994 -246.353775)
		(end 86.212426 -246.42953)
		(width 0.09525)
		(layer "In13.Cu")
		(net "M_B_CPU1_SA_DQS_DP<4>")
	)
	(arc
		(start 84.709508 -246.42953)
		(mid 84.99094 -246.353775)
		(end 85.272372 -246.42953)
		(width 0.09525)
		(layer "In13.Cu")
		(net "M_B_CPU1_SA_DQS_DP<4>")
	)
	(arc
		(start 87.160862 -246.434356)
		(mid 87.313757 -246.479184)
		(end 87.471504 -246.456708)
		(width 0.09525)
		(layer "In13.Cu")
		(net "M_B_CPU1_SA_DQS_DP<4>")
	)
	(arc
		(start 84.332572 -246.42953)
		(mid 84.52104 -246.480207)
		(end 84.709508 -246.42953)
		(width 0.09525)
		(layer "In13.Cu")
		(net "M_B_CPU1_SA_DQS_DP<4>")
	)
	(arc
		(start 80.57261 -246.42953)
		(mid 80.761078 -246.480207)
		(end 80.949546 -246.42953)
		(width 0.09525)
		(layer "In13.Cu")
		(net "M_B_CPU1_SA_DQS_DP<4>")
	)
	(arc
		(start 83.4009 -246.434356)
		(mid 83.585932 -246.48027)
		(end 83.769708 -246.42953)
		(width 0.09525)
		(layer "In13.Cu")
		(net "M_B_CPU1_SA_DQS_DP<4>")
	)
	(arc
		(start 82.829654 -246.42953)
		(mid 83.111086 -246.353775)
		(end 83.392518 -246.42953)
		(width 0.09525)
		(layer "In13.Cu")
		(net "M_B_CPU1_SA_DQS_DP<4>")
	)
	(arc
		(start 82.460846 -246.434356)
		(mid 82.645878 -246.48027)
		(end 82.829654 -246.42953)
		(width 0.09525)
		(layer "In13.Cu")
		(net "M_B_CPU1_SA_DQS_DP<4>")
	)
	(arc
		(start 77.943456 -246.48033)
		(mid 77.98422 -246.477973)
		(end 78.024482 -246.471186)
		(width 0.09525)
		(layer "In13.Cu")
		(net "M_B_CPU1_SA_DQS_DP<4>")
	)
	(arc
		(start 78.165706 -246.409464)
		(mid 78.432232 -246.353527)
		(end 78.693772 -246.42953)
		(width 0.09525)
		(layer "In13.Cu")
		(net "M_B_CPU1_SA_DQS_DP<4>")
	)
	(arc
		(start 80.949546 -246.42953)
		(mid 81.230978 -246.353775)
		(end 81.51241 -246.42953)
		(width 0.09525)
		(layer "In13.Cu")
		(net "M_B_CPU1_SA_DQS_DP<4>")
	)
	(arc
		(start 78.024482 -246.471186)
		(mid 78.07941 -246.45443)
		(end 78.131162 -246.42953)
		(width 0.09525)
		(layer "In13.Cu")
		(net "M_B_CPU1_SA_DQS_DP<4>")
	)
	(arc
		(start 81.51241 -246.42953)
		(mid 81.696185 -246.480302)
		(end 81.881218 -246.434356)
		(width 0.09525)
		(layer "In13.Cu")
		(net "M_B_CPU1_SA_DQS_DP<4>")
	)
	(arc
		(start 83.769708 -246.42953)
		(mid 84.05114 -246.353775)
		(end 84.332572 -246.42953)
		(width 0.09525)
		(layer "In13.Cu")
		(net "M_B_CPU1_SA_DQS_DP<4>")
	)
	(arc
		(start 81.8896 -246.42953)
		(mid 82.171032 -246.353775)
		(end 82.452464 -246.42953)
		(width 0.09525)
		(layer "In13.Cu")
		(net "M_B_CPU1_SA_DQS_DP<4>")
	)
	(arc
		(start 78.693772 -246.42953)
		(mid 78.872087 -246.480672)
		(end 79.053182 -246.440452)
		(width 0.09525)
		(layer "In13.Cu")
		(net "M_B_CPU1_SA_DQS_DP<4>")
	)
	(arc
		(start 79.071978 -246.42953)
		(mid 79.338065 -246.353985)
		(end 79.607918 -246.414798)
		(width 0.09525)
		(layer "In13.Cu")
		(net "M_B_CPU1_SA_DQS_DP<4>")
	)
	(arc
		(start 79.650082 -246.439182)
		(mid 79.831139 -246.480164)
		(end 80.009746 -246.42953)
		(width 0.09525)
		(layer "In13.Cu")
		(net "M_B_CPU1_SA_DQS_DP<4>")
	)
	(arc
		(start 86.212426 -246.42953)
		(mid 86.396201 -246.480302)
		(end 86.581234 -246.434356)
		(width 0.09525)
		(layer "In13.Cu")
		(net "M_B_CPU1_SA_DQS_DP<4>")
	)
	(arc
		(start 85.272372 -246.42953)
		(mid 85.456147 -246.480302)
		(end 85.64118 -246.434356)
		(width 0.09525)
		(layer "In13.Cu")
		(net "M_B_CPU1_SA_DQS_DP<4>")
	)
	(arc
		(start 86.589616 -246.42953)
		(mid 86.871048 -246.353775)
		(end 87.15248 -246.42953)
		(width 0.09525)
		(layer "In13.Cu")
		(net "M_B_CPU1_SA_DQS_DP<4>")
	)
	(segment
		(start 87.8078 -241.510312)
		(end 87.340948 -241.244374)
		(width 0.12954)
		(layer "F.Cu")
		(net "M_B_CPU1_SA_DQS_DP<3>")
	)
	(segment
		(start 65.52057 -234.923584)
		(end 65.72885 -234.715304)
		(width 0.16002)
		(layer "In13.Cu")
		(net "M_B_CPU1_SA_DQS_DP<3>")
	)
	(segment
		(start 59.492388 -228.925882)
		(end 59.15533 -229.26294)
		(width 0.16002)
		(layer "In13.Cu")
		(net "M_B_CPU1_SA_DQS_DP<3>")
	)
	(segment
		(start 77.817726 -241.493802)
		(end 77.22743 -240.903506)
		(width 0.09525)
		(layer "In13.Cu")
		(net "M_B_CPU1_SA_DQS_DP<3>")
	)
	(segment
		(start 55.90286 -229.751128)
		(end 55.74284 -229.911148)
		(width 0.16002)
		(layer "In13.Cu")
		(net "M_B_CPU1_SA_DQS_DP<3>")
	)
	(segment
		(start 83.4009 -241.57432)
		(end 83.392518 -241.569494)
		(width 0.09525)
		(layer "In13.Cu")
		(net "M_B_CPU1_SA_DQS_DP<3>")
	)
	(segment
		(start 63.981076 -232.44048)
		(end 63.45428 -232.440734)
		(width 0.16002)
		(layer "In13.Cu")
		(net "M_B_CPU1_SA_DQS_DP<3>")
	)
	(segment
		(start 62.981586 -231.96804)
		(end 62.981332 -231.440736)
		(width 0.16002)
		(layer "In13.Cu")
		(net "M_B_CPU1_SA_DQS_DP<3>")
	)
	(segment
		(start 85.649562 -241.569494)
		(end 85.64118 -241.57432)
		(width 0.09525)
		(layer "In13.Cu")
		(net "M_B_CPU1_SA_DQS_DP<3>")
	)
	(segment
		(start 70.677532 -240.357406)
		(end 65.52057 -235.200444)
		(width 0.16002)
		(layer "In13.Cu")
		(net "M_B_CPU1_SA_DQS_DP<3>")
	)
	(segment
		(start 62.773306 -232.17632)
		(end 62.981586 -231.96804)
		(width 0.16002)
		(layer "In13.Cu")
		(net "M_B_CPU1_SA_DQS_DP<3>")
	)
	(segment
		(start 60.42787 -229.26294)
		(end 60.090812 -228.925882)
		(width 0.16002)
		(layer "In13.Cu")
		(net "M_B_CPU1_SA_DQS_DP<3>")
	)
	(segment
		(start 64.146938 -233.549952)
		(end 64.355218 -233.341672)
		(width 0.16002)
		(layer "In13.Cu")
		(net "M_B_CPU1_SA_DQS_DP<3>")
	)
	(segment
		(start 61.595508 -231.275382)
		(end 61.399674 -231.079548)
		(width 0.16002)
		(layer "In13.Cu")
		(net "M_B_CPU1_SA_DQS_DP<3>")
	)
	(segment
		(start 63.246 -232.649014)
		(end 62.96914 -232.649014)
		(width 0.16002)
		(layer "In13.Cu")
		(net "M_B_CPU1_SA_DQS_DP<3>")
	)
	(segment
		(start 64.354964 -232.814368)
		(end 63.981076 -232.44048)
		(width 0.16002)
		(layer "In13.Cu")
		(net "M_B_CPU1_SA_DQS_DP<3>")
	)
	(segment
		(start 76.300838 -240.416588)
		(end 76.03871 -240.416588)
		(width 0.09525)
		(layer "In13.Cu")
		(net "M_B_CPU1_SA_DQS_DP<3>")
	)
	(segment
		(start 62.96914 -232.649014)
		(end 62.773306 -232.45318)
		(width 0.16002)
		(layer "In13.Cu")
		(net "M_B_CPU1_SA_DQS_DP<3>")
	)
	(segment
		(start 62.607444 -231.066848)
		(end 62.080648 -231.067102)
		(width 0.16002)
		(layer "In13.Cu")
		(net "M_B_CPU1_SA_DQS_DP<3>")
	)
	(segment
		(start 62.080648 -231.067102)
		(end 61.872368 -231.275382)
		(width 0.16002)
		(layer "In13.Cu")
		(net "M_B_CPU1_SA_DQS_DP<3>")
	)
	(segment
		(start 87.340948 -241.244374)
		(end 87.494872 -241.509804)
		(width 0.09525)
		(layer "In13.Cu")
		(net "M_B_CPU1_SA_DQS_DP<3>")
	)
	(segment
		(start 78.700884 -241.57432)
		(end 78.692502 -241.569494)
		(width 0.09525)
		(layer "In13.Cu")
		(net "M_B_CPU1_SA_DQS_DP<3>")
	)
	(segment
		(start 60.42787 -229.480364)
		(end 60.42787 -229.26294)
		(width 0.16002)
		(layer "In13.Cu")
		(net "M_B_CPU1_SA_DQS_DP<3>")
	)
	(segment
		(start 62.981332 -231.440736)
		(end 62.607444 -231.066848)
		(width 0.16002)
		(layer "In13.Cu")
		(net "M_B_CPU1_SA_DQS_DP<3>")
	)
	(segment
		(start 64.355218 -233.341672)
		(end 64.354964 -232.814368)
		(width 0.16002)
		(layer "In13.Cu")
		(net "M_B_CPU1_SA_DQS_DP<3>")
	)
	(segment
		(start 86.589616 -241.569494)
		(end 86.581234 -241.57432)
		(width 0.09525)
		(layer "In13.Cu")
		(net "M_B_CPU1_SA_DQS_DP<3>")
	)
	(segment
		(start 65.728596 -234.188)
		(end 65.354708 -233.814112)
		(width 0.16002)
		(layer "In13.Cu")
		(net "M_B_CPU1_SA_DQS_DP<3>")
	)
	(segment
		(start 58.99531 -229.640384)
		(end 57.906158 -229.640384)
		(width 0.16002)
		(layer "In13.Cu")
		(net "M_B_CPU1_SA_DQS_DP<3>")
	)
	(segment
		(start 61.6077 -230.067358)
		(end 61.180726 -229.640384)
		(width 0.16002)
		(layer "In13.Cu")
		(net "M_B_CPU1_SA_DQS_DP<3>")
	)
	(segment
		(start 87.160862 -241.57432)
		(end 87.15248 -241.569494)
		(width 0.09525)
		(layer "In13.Cu")
		(net "M_B_CPU1_SA_DQS_DP<3>")
	)
	(segment
		(start 59.15533 -229.26294)
		(end 59.15533 -229.480364)
		(width 0.16002)
		(layer "In13.Cu")
		(net "M_B_CPU1_SA_DQS_DP<3>")
	)
	(segment
		(start 64.146938 -233.826812)
		(end 64.146938 -233.549952)
		(width 0.16002)
		(layer "In13.Cu")
		(net "M_B_CPU1_SA_DQS_DP<3>")
	)
	(segment
		(start 64.342772 -234.022646)
		(end 64.146938 -233.826812)
		(width 0.16002)
		(layer "In13.Cu")
		(net "M_B_CPU1_SA_DQS_DP<3>")
	)
	(segment
		(start 64.619632 -234.022646)
		(end 64.342772 -234.022646)
		(width 0.16002)
		(layer "In13.Cu")
		(net "M_B_CPU1_SA_DQS_DP<3>")
	)
	(segment
		(start 61.607954 -230.594408)
		(end 61.6077 -230.067358)
		(width 0.16002)
		(layer "In13.Cu")
		(net "M_B_CPU1_SA_DQS_DP<3>")
	)
	(segment
		(start 54.897782 -229.249986)
		(end 54.202584 -229.249986)
		(width 0.16002)
		(layer "In13.Cu")
		(net "M_B_CPU1_SA_DQS_DP<3>")
	)
	(segment
		(start 78.41107 -241.493802)
		(end 77.817726 -241.493802)
		(width 0.09525)
		(layer "In13.Cu")
		(net "M_B_CPU1_SA_DQS_DP<3>")
	)
	(segment
		(start 75.979528 -240.357406)
		(end 75.955906 -240.357406)
		(width 0.09525)
		(layer "In13.Cu")
		(net "M_B_CPU1_SA_DQS_DP<3>")
	)
	(segment
		(start 76.03871 -240.416588)
		(end 75.979528 -240.357406)
		(width 0.09525)
		(layer "In13.Cu")
		(net "M_B_CPU1_SA_DQS_DP<3>")
	)
	(segment
		(start 55.74284 -229.911148)
		(end 55.39486 -229.911148)
		(width 0.16002)
		(layer "In13.Cu")
		(net "M_B_CPU1_SA_DQS_DP<3>")
	)
	(segment
		(start 56.239918 -229.249986)
		(end 55.90286 -229.587044)
		(width 0.16002)
		(layer "In13.Cu")
		(net "M_B_CPU1_SA_DQS_DP<3>")
	)
	(segment
		(start 55.23484 -229.587044)
		(end 54.897782 -229.249986)
		(width 0.16002)
		(layer "In13.Cu")
		(net "M_B_CPU1_SA_DQS_DP<3>")
	)
	(segment
		(start 52.161948 -229.063296)
		(end 51.884072 -228.78542)
		(width 0.16002)
		(layer "In13.Cu")
		(net "M_B_CPU1_SA_DQS_DP<3>")
	)
	(segment
		(start 82.460846 -241.57432)
		(end 82.452464 -241.569494)
		(width 0.09525)
		(layer "In13.Cu")
		(net "M_B_CPU1_SA_DQS_DP<3>")
	)
	(segment
		(start 57.906158 -229.640384)
		(end 57.51576 -229.249986)
		(width 0.16002)
		(layer "In13.Cu")
		(net "M_B_CPU1_SA_DQS_DP<3>")
	)
	(segment
		(start 61.872368 -231.275382)
		(end 61.595508 -231.275382)
		(width 0.16002)
		(layer "In13.Cu")
		(net "M_B_CPU1_SA_DQS_DP<3>")
	)
	(segment
		(start 59.15533 -229.480364)
		(end 58.99531 -229.640384)
		(width 0.16002)
		(layer "In13.Cu")
		(net "M_B_CPU1_SA_DQS_DP<3>")
	)
	(segment
		(start 76.787756 -240.903506)
		(end 76.300838 -240.416588)
		(width 0.09525)
		(layer "In13.Cu")
		(net "M_B_CPU1_SA_DQS_DP<3>")
	)
	(segment
		(start 65.72885 -234.715304)
		(end 65.728596 -234.188)
		(width 0.16002)
		(layer "In13.Cu")
		(net "M_B_CPU1_SA_DQS_DP<3>")
	)
	(segment
		(start 63.45428 -232.440734)
		(end 63.246 -232.649014)
		(width 0.16002)
		(layer "In13.Cu")
		(net "M_B_CPU1_SA_DQS_DP<3>")
	)
	(segment
		(start 65.354708 -233.814112)
		(end 64.827912 -233.814366)
		(width 0.16002)
		(layer "In13.Cu")
		(net "M_B_CPU1_SA_DQS_DP<3>")
	)
	(segment
		(start 87.494872 -241.509804)
		(end 87.471504 -241.596672)
		(width 0.09525)
		(layer "In13.Cu")
		(net "M_B_CPU1_SA_DQS_DP<3>")
	)
	(segment
		(start 55.23484 -229.751128)
		(end 55.23484 -229.587044)
		(width 0.16002)
		(layer "In13.Cu")
		(net "M_B_CPU1_SA_DQS_DP<3>")
	)
	(segment
		(start 55.90286 -229.587044)
		(end 55.90286 -229.751128)
		(width 0.16002)
		(layer "In13.Cu")
		(net "M_B_CPU1_SA_DQS_DP<3>")
	)
	(segment
		(start 79.640938 -241.57432)
		(end 79.632556 -241.569494)
		(width 0.09525)
		(layer "In13.Cu")
		(net "M_B_CPU1_SA_DQS_DP<3>")
	)
	(segment
		(start 81.8896 -241.569494)
		(end 81.881218 -241.57432)
		(width 0.09525)
		(layer "In13.Cu")
		(net "M_B_CPU1_SA_DQS_DP<3>")
	)
	(segment
		(start 60.090812 -228.925882)
		(end 59.492388 -228.925882)
		(width 0.16002)
		(layer "In13.Cu")
		(net "M_B_CPU1_SA_DQS_DP<3>")
	)
	(segment
		(start 61.399674 -230.802688)
		(end 61.607954 -230.594408)
		(width 0.16002)
		(layer "In13.Cu")
		(net "M_B_CPU1_SA_DQS_DP<3>")
	)
	(segment
		(start 75.955906 -240.357406)
		(end 70.677532 -240.357406)
		(width 0.16002)
		(layer "In13.Cu")
		(net "M_B_CPU1_SA_DQS_DP<3>")
	)
	(segment
		(start 54.015894 -229.063296)
		(end 52.161948 -229.063296)
		(width 0.16002)
		(layer "In13.Cu")
		(net "M_B_CPU1_SA_DQS_DP<3>")
	)
	(segment
		(start 61.399674 -231.079548)
		(end 61.399674 -230.802688)
		(width 0.16002)
		(layer "In13.Cu")
		(net "M_B_CPU1_SA_DQS_DP<3>")
	)
	(segment
		(start 61.180726 -229.640384)
		(end 60.58789 -229.640384)
		(width 0.16002)
		(layer "In13.Cu")
		(net "M_B_CPU1_SA_DQS_DP<3>")
	)
	(segment
		(start 65.52057 -235.200444)
		(end 65.52057 -234.923584)
		(width 0.16002)
		(layer "In13.Cu")
		(net "M_B_CPU1_SA_DQS_DP<3>")
	)
	(segment
		(start 62.773306 -232.45318)
		(end 62.773306 -232.17632)
		(width 0.16002)
		(layer "In13.Cu")
		(net "M_B_CPU1_SA_DQS_DP<3>")
	)
	(segment
		(start 64.827912 -233.814366)
		(end 64.619632 -234.022646)
		(width 0.16002)
		(layer "In13.Cu")
		(net "M_B_CPU1_SA_DQS_DP<3>")
	)
	(segment
		(start 60.58789 -229.640384)
		(end 60.42787 -229.480364)
		(width 0.16002)
		(layer "In13.Cu")
		(net "M_B_CPU1_SA_DQS_DP<3>")
	)
	(segment
		(start 77.22743 -240.903506)
		(end 76.787756 -240.903506)
		(width 0.09525)
		(layer "In13.Cu")
		(net "M_B_CPU1_SA_DQS_DP<3>")
	)
	(segment
		(start 55.39486 -229.911148)
		(end 55.23484 -229.751128)
		(width 0.16002)
		(layer "In13.Cu")
		(net "M_B_CPU1_SA_DQS_DP<3>")
	)
	(segment
		(start 54.202584 -229.249986)
		(end 54.015894 -229.063296)
		(width 0.16002)
		(layer "In13.Cu")
		(net "M_B_CPU1_SA_DQS_DP<3>")
	)
	(segment
		(start 57.51576 -229.249986)
		(end 56.239918 -229.249986)
		(width 0.16002)
		(layer "In13.Cu")
		(net "M_B_CPU1_SA_DQS_DP<3>")
	)
	(arc
		(start 87.471504 -241.596672)
		(mid 87.313754 -241.619191)
		(end 87.160862 -241.57432)
		(width 0.09525)
		(layer "In13.Cu")
		(net "M_B_CPU1_SA_DQS_DP<3>")
	)
	(arc
		(start 82.452464 -241.569494)
		(mid 82.171032 -241.493739)
		(end 81.8896 -241.569494)
		(width 0.09525)
		(layer "In13.Cu")
		(net "M_B_CPU1_SA_DQS_DP<3>")
	)
	(arc
		(start 84.709508 -241.569494)
		(mid 84.52104 -241.620171)
		(end 84.332572 -241.569494)
		(width 0.09525)
		(layer "In13.Cu")
		(net "M_B_CPU1_SA_DQS_DP<3>")
	)
	(arc
		(start 84.332572 -241.569494)
		(mid 84.05114 -241.493739)
		(end 83.769708 -241.569494)
		(width 0.09525)
		(layer "In13.Cu")
		(net "M_B_CPU1_SA_DQS_DP<3>")
	)
	(arc
		(start 82.829654 -241.569494)
		(mid 82.645879 -241.620266)
		(end 82.460846 -241.57432)
		(width 0.09525)
		(layer "In13.Cu")
		(net "M_B_CPU1_SA_DQS_DP<3>")
	)
	(arc
		(start 78.692502 -241.569494)
		(mid 78.556795 -241.513009)
		(end 78.41107 -241.493802)
		(width 0.09525)
		(layer "In13.Cu")
		(net "M_B_CPU1_SA_DQS_DP<3>")
	)
	(arc
		(start 87.15248 -241.569494)
		(mid 86.871048 -241.493739)
		(end 86.589616 -241.569494)
		(width 0.09525)
		(layer "In13.Cu")
		(net "M_B_CPU1_SA_DQS_DP<3>")
	)
	(arc
		(start 80.009746 -241.569494)
		(mid 79.825971 -241.620266)
		(end 79.640938 -241.57432)
		(width 0.09525)
		(layer "In13.Cu")
		(net "M_B_CPU1_SA_DQS_DP<3>")
	)
	(arc
		(start 86.212426 -241.569494)
		(mid 85.930994 -241.493739)
		(end 85.649562 -241.569494)
		(width 0.09525)
		(layer "In13.Cu")
		(net "M_B_CPU1_SA_DQS_DP<3>")
	)
	(arc
		(start 86.581234 -241.57432)
		(mid 86.396202 -241.620234)
		(end 86.212426 -241.569494)
		(width 0.09525)
		(layer "In13.Cu")
		(net "M_B_CPU1_SA_DQS_DP<3>")
	)
	(arc
		(start 85.64118 -241.57432)
		(mid 85.456148 -241.620234)
		(end 85.272372 -241.569494)
		(width 0.09525)
		(layer "In13.Cu")
		(net "M_B_CPU1_SA_DQS_DP<3>")
	)
	(arc
		(start 83.769708 -241.569494)
		(mid 83.585933 -241.620266)
		(end 83.4009 -241.57432)
		(width 0.09525)
		(layer "In13.Cu")
		(net "M_B_CPU1_SA_DQS_DP<3>")
	)
	(arc
		(start 79.069692 -241.569494)
		(mid 78.885917 -241.620266)
		(end 78.700884 -241.57432)
		(width 0.09525)
		(layer "In13.Cu")
		(net "M_B_CPU1_SA_DQS_DP<3>")
	)
	(arc
		(start 79.632556 -241.569494)
		(mid 79.351124 -241.493739)
		(end 79.069692 -241.569494)
		(width 0.09525)
		(layer "In13.Cu")
		(net "M_B_CPU1_SA_DQS_DP<3>")
	)
	(arc
		(start 81.881218 -241.57432)
		(mid 81.696186 -241.620234)
		(end 81.51241 -241.569494)
		(width 0.09525)
		(layer "In13.Cu")
		(net "M_B_CPU1_SA_DQS_DP<3>")
	)
	(arc
		(start 83.392518 -241.569494)
		(mid 83.111086 -241.493739)
		(end 82.829654 -241.569494)
		(width 0.09525)
		(layer "In13.Cu")
		(net "M_B_CPU1_SA_DQS_DP<3>")
	)
	(arc
		(start 81.51241 -241.569494)
		(mid 81.230978 -241.493739)
		(end 80.949546 -241.569494)
		(width 0.09525)
		(layer "In13.Cu")
		(net "M_B_CPU1_SA_DQS_DP<3>")
	)
	(arc
		(start 85.272372 -241.569494)
		(mid 84.99094 -241.493739)
		(end 84.709508 -241.569494)
		(width 0.09525)
		(layer "In13.Cu")
		(net "M_B_CPU1_SA_DQS_DP<3>")
	)
	(arc
		(start 80.949546 -241.569494)
		(mid 80.761078 -241.620171)
		(end 80.57261 -241.569494)
		(width 0.09525)
		(layer "In13.Cu")
		(net "M_B_CPU1_SA_DQS_DP<3>")
	)
	(arc
		(start 80.57261 -241.569494)
		(mid 80.291178 -241.493739)
		(end 80.009746 -241.569494)
		(width 0.09525)
		(layer "In13.Cu")
		(net "M_B_CPU1_SA_DQS_DP<3>")
	)
	(segment
		(start 87.8078 -236.650276)
		(end 87.340948 -236.384338)
		(width 0.12954)
		(layer "F.Cu")
		(net "M_B_CPU1_SA_DQS_DP<2>")
	)
	(segment
		(start 52.148994 -219.700348)
		(end 54.651148 -219.700348)
		(width 0.16002)
		(layer "In13.Cu")
		(net "M_B_CPU1_SA_DQS_DP<2>")
	)
	(segment
		(start 78.236572 -236.633004)
		(end 78.411832 -236.633004)
		(width 0.09525)
		(layer "In13.Cu")
		(net "M_B_CPU1_SA_DQS_DP<2>")
	)
	(segment
		(start 87.471504 -236.736636)
		(end 87.494872 -236.649768)
		(width 0.09525)
		(layer "In13.Cu")
		(net "M_B_CPU1_SA_DQS_DP<2>")
	)
	(segment
		(start 75.955906 -234.7341)
		(end 75.979528 -234.7341)
		(width 0.09525)
		(layer "In13.Cu")
		(net "M_B_CPU1_SA_DQS_DP<2>")
	)
	(segment
		(start 57.08015 -220.181424)
		(end 57.21731 -220.318584)
		(width 0.16002)
		(layer "In13.Cu")
		(net "M_B_CPU1_SA_DQS_DP<2>")
	)
	(segment
		(start 67.197478 -227.162614)
		(end 67.197478 -227.795836)
		(width 0.16002)
		(layer "In13.Cu")
		(net "M_B_CPU1_SA_DQS_DP<2>")
	)
	(segment
		(start 83.392518 -236.709458)
		(end 83.4009 -236.714284)
		(width 0.09525)
		(layer "In13.Cu")
		(net "M_B_CPU1_SA_DQS_DP<2>")
	)
	(segment
		(start 65.823846 -226.416616)
		(end 66.01968 -226.61245)
		(width 0.16002)
		(layer "In13.Cu")
		(net "M_B_CPU1_SA_DQS_DP<2>")
	)
	(segment
		(start 79.053182 -236.72038)
		(end 79.071978 -236.709458)
		(width 0.09525)
		(layer "In13.Cu")
		(net "M_B_CPU1_SA_DQS_DP<2>")
	)
	(segment
		(start 65.334896 -224.82683)
		(end 65.8622 -224.827084)
		(width 0.16002)
		(layer "In13.Cu")
		(net "M_B_CPU1_SA_DQS_DP<2>")
	)
	(segment
		(start 63.549276 -223.865186)
		(end 63.961264 -223.453198)
		(width 0.16002)
		(layer "In13.Cu")
		(net "M_B_CPU1_SA_DQS_DP<2>")
	)
	(segment
		(start 85.64118 -236.714284)
		(end 85.649562 -236.709458)
		(width 0.09525)
		(layer "In13.Cu")
		(net "M_B_CPU1_SA_DQS_DP<2>")
	)
	(segment
		(start 64.488568 -223.453452)
		(end 64.862456 -223.82734)
		(width 0.16002)
		(layer "In13.Cu")
		(net "M_B_CPU1_SA_DQS_DP<2>")
	)
	(segment
		(start 61.63691 -221.860364)
		(end 61.63691 -222.22968)
		(width 0.16002)
		(layer "In13.Cu")
		(net "M_B_CPU1_SA_DQS_DP<2>")
	)
	(segment
		(start 63.48857 -222.980504)
		(end 63.076582 -223.392492)
		(width 0.16002)
		(layer "In13.Cu")
		(net "M_B_CPU1_SA_DQS_DP<2>")
	)
	(segment
		(start 66.236088 -225.200972)
		(end 66.235834 -225.727768)
		(width 0.16002)
		(layer "In13.Cu")
		(net "M_B_CPU1_SA_DQS_DP<2>")
	)
	(segment
		(start 55.269384 -220.318584)
		(end 56.47309 -220.318584)
		(width 0.16002)
		(layer "In13.Cu")
		(net "M_B_CPU1_SA_DQS_DP<2>")
	)
	(segment
		(start 64.450214 -225.042984)
		(end 64.646048 -225.238818)
		(width 0.16002)
		(layer "In13.Cu")
		(net "M_B_CPU1_SA_DQS_DP<2>")
	)
	(segment
		(start 61.898784 -222.491554)
		(end 62.175644 -222.491554)
		(width 0.16002)
		(layer "In13.Cu")
		(net "M_B_CPU1_SA_DQS_DP<2>")
	)
	(segment
		(start 65.8622 -224.827084)
		(end 66.236088 -225.200972)
		(width 0.16002)
		(layer "In13.Cu")
		(net "M_B_CPU1_SA_DQS_DP<2>")
	)
	(segment
		(start 62.175644 -222.491554)
		(end 62.587632 -222.079566)
		(width 0.16002)
		(layer "In13.Cu")
		(net "M_B_CPU1_SA_DQS_DP<2>")
	)
	(segment
		(start 64.646048 -225.238818)
		(end 64.922908 -225.238818)
		(width 0.16002)
		(layer "In13.Cu")
		(net "M_B_CPU1_SA_DQS_DP<2>")
	)
	(segment
		(start 64.922908 -225.238818)
		(end 65.334896 -224.82683)
		(width 0.16002)
		(layer "In13.Cu")
		(net "M_B_CPU1_SA_DQS_DP<2>")
	)
	(segment
		(start 86.581234 -236.714284)
		(end 86.589616 -236.709458)
		(width 0.09525)
		(layer "In13.Cu")
		(net "M_B_CPU1_SA_DQS_DP<2>")
	)
	(segment
		(start 87.15248 -236.709458)
		(end 87.160862 -236.714284)
		(width 0.09525)
		(layer "In13.Cu")
		(net "M_B_CPU1_SA_DQS_DP<2>")
	)
	(segment
		(start 81.881218 -236.714284)
		(end 81.8896 -236.709458)
		(width 0.09525)
		(layer "In13.Cu")
		(net "M_B_CPU1_SA_DQS_DP<2>")
	)
	(segment
		(start 79.633318 -236.709458)
		(end 79.650082 -236.71911)
		(width 0.09525)
		(layer "In13.Cu")
		(net "M_B_CPU1_SA_DQS_DP<2>")
	)
	(segment
		(start 75.979528 -234.7341)
		(end 76.038456 -234.793028)
		(width 0.09525)
		(layer "In13.Cu")
		(net "M_B_CPU1_SA_DQS_DP<2>")
	)
	(segment
		(start 51.884072 -219.435426)
		(end 52.148994 -219.700348)
		(width 0.16002)
		(layer "In13.Cu")
		(net "M_B_CPU1_SA_DQS_DP<2>")
	)
	(segment
		(start 63.114936 -222.07982)
		(end 63.488824 -222.453708)
		(width 0.16002)
		(layer "In13.Cu")
		(net "M_B_CPU1_SA_DQS_DP<2>")
	)
	(segment
		(start 74.135742 -234.7341)
		(end 75.955906 -234.7341)
		(width 0.16002)
		(layer "In13.Cu")
		(net "M_B_CPU1_SA_DQS_DP<2>")
	)
	(segment
		(start 65.823846 -226.139756)
		(end 65.823846 -226.416616)
		(width 0.16002)
		(layer "In13.Cu")
		(net "M_B_CPU1_SA_DQS_DP<2>")
	)
	(segment
		(start 76.452984 -234.995974)
		(end 76.452984 -235.205016)
		(width 0.09525)
		(layer "In13.Cu")
		(net "M_B_CPU1_SA_DQS_DP<2>")
	)
	(segment
		(start 64.862202 -224.354136)
		(end 64.450214 -224.766124)
		(width 0.16002)
		(layer "In13.Cu")
		(net "M_B_CPU1_SA_DQS_DP<2>")
	)
	(segment
		(start 82.452464 -236.709458)
		(end 82.460846 -236.714284)
		(width 0.09525)
		(layer "In13.Cu")
		(net "M_B_CPU1_SA_DQS_DP<2>")
	)
	(segment
		(start 61.63691 -222.22968)
		(end 61.898784 -222.491554)
		(width 0.16002)
		(layer "In13.Cu")
		(net "M_B_CPU1_SA_DQS_DP<2>")
	)
	(segment
		(start 64.862456 -223.82734)
		(end 64.862202 -224.354136)
		(width 0.16002)
		(layer "In13.Cu")
		(net "M_B_CPU1_SA_DQS_DP<2>")
	)
	(segment
		(start 63.076582 -223.669352)
		(end 63.272416 -223.865186)
		(width 0.16002)
		(layer "In13.Cu")
		(net "M_B_CPU1_SA_DQS_DP<2>")
	)
	(segment
		(start 67.197478 -227.795836)
		(end 74.135742 -234.7341)
		(width 0.16002)
		(layer "In13.Cu")
		(net "M_B_CPU1_SA_DQS_DP<2>")
	)
	(segment
		(start 62.587632 -222.079566)
		(end 63.114936 -222.07982)
		(width 0.16002)
		(layer "In13.Cu")
		(net "M_B_CPU1_SA_DQS_DP<2>")
	)
	(segment
		(start 56.61025 -220.181424)
		(end 57.08015 -220.181424)
		(width 0.16002)
		(layer "In13.Cu")
		(net "M_B_CPU1_SA_DQS_DP<2>")
	)
	(segment
		(start 60.09513 -220.318584)
		(end 61.63691 -221.860364)
		(width 0.16002)
		(layer "In13.Cu")
		(net "M_B_CPU1_SA_DQS_DP<2>")
	)
	(segment
		(start 66.235834 -225.727768)
		(end 65.823846 -226.139756)
		(width 0.16002)
		(layer "In13.Cu")
		(net "M_B_CPU1_SA_DQS_DP<2>")
	)
	(segment
		(start 64.450214 -224.766124)
		(end 64.450214 -225.042984)
		(width 0.16002)
		(layer "In13.Cu")
		(net "M_B_CPU1_SA_DQS_DP<2>")
	)
	(segment
		(start 66.01968 -226.61245)
		(end 66.647314 -226.61245)
		(width 0.16002)
		(layer "In13.Cu")
		(net "M_B_CPU1_SA_DQS_DP<2>")
	)
	(segment
		(start 77.129894 -235.526326)
		(end 78.236572 -236.633004)
		(width 0.09525)
		(layer "In13.Cu")
		(net "M_B_CPU1_SA_DQS_DP<2>")
	)
	(segment
		(start 76.452984 -235.205016)
		(end 76.774294 -235.526326)
		(width 0.09525)
		(layer "In13.Cu")
		(net "M_B_CPU1_SA_DQS_DP<2>")
	)
	(segment
		(start 63.488824 -222.453708)
		(end 63.48857 -222.980504)
		(width 0.16002)
		(layer "In13.Cu")
		(net "M_B_CPU1_SA_DQS_DP<2>")
	)
	(segment
		(start 63.272416 -223.865186)
		(end 63.549276 -223.865186)
		(width 0.16002)
		(layer "In13.Cu")
		(net "M_B_CPU1_SA_DQS_DP<2>")
	)
	(segment
		(start 76.250038 -234.793028)
		(end 76.452984 -234.995974)
		(width 0.09525)
		(layer "In13.Cu")
		(net "M_B_CPU1_SA_DQS_DP<2>")
	)
	(segment
		(start 79.607918 -236.694726)
		(end 79.633318 -236.709458)
		(width 0.09525)
		(layer "In13.Cu")
		(net "M_B_CPU1_SA_DQS_DP<2>")
	)
	(segment
		(start 76.038456 -234.793028)
		(end 76.250038 -234.793028)
		(width 0.09525)
		(layer "In13.Cu")
		(net "M_B_CPU1_SA_DQS_DP<2>")
	)
	(segment
		(start 56.47309 -220.318584)
		(end 56.61025 -220.181424)
		(width 0.16002)
		(layer "In13.Cu")
		(net "M_B_CPU1_SA_DQS_DP<2>")
	)
	(segment
		(start 76.774294 -235.526326)
		(end 77.129894 -235.526326)
		(width 0.09525)
		(layer "In13.Cu")
		(net "M_B_CPU1_SA_DQS_DP<2>")
	)
	(segment
		(start 66.647314 -226.61245)
		(end 67.197478 -227.162614)
		(width 0.16002)
		(layer "In13.Cu")
		(net "M_B_CPU1_SA_DQS_DP<2>")
	)
	(segment
		(start 63.961264 -223.453198)
		(end 64.488568 -223.453452)
		(width 0.16002)
		(layer "In13.Cu")
		(net "M_B_CPU1_SA_DQS_DP<2>")
	)
	(segment
		(start 63.076582 -223.392492)
		(end 63.076582 -223.669352)
		(width 0.16002)
		(layer "In13.Cu")
		(net "M_B_CPU1_SA_DQS_DP<2>")
	)
	(segment
		(start 87.494872 -236.649768)
		(end 87.340948 -236.384338)
		(width 0.09525)
		(layer "In13.Cu")
		(net "M_B_CPU1_SA_DQS_DP<2>")
	)
	(segment
		(start 54.651148 -219.700348)
		(end 55.269384 -220.318584)
		(width 0.16002)
		(layer "In13.Cu")
		(net "M_B_CPU1_SA_DQS_DP<2>")
	)
	(segment
		(start 57.21731 -220.318584)
		(end 60.09513 -220.318584)
		(width 0.16002)
		(layer "In13.Cu")
		(net "M_B_CPU1_SA_DQS_DP<2>")
	)
	(arc
		(start 79.071978 -236.709458)
		(mid 79.338065 -236.633913)
		(end 79.607918 -236.694726)
		(width 0.09525)
		(layer "In13.Cu")
		(net "M_B_CPU1_SA_DQS_DP<2>")
	)
	(arc
		(start 84.709508 -236.709458)
		(mid 84.99094 -236.633703)
		(end 85.272372 -236.709458)
		(width 0.09525)
		(layer "In13.Cu")
		(net "M_B_CPU1_SA_DQS_DP<2>")
	)
	(arc
		(start 87.160862 -236.714284)
		(mid 87.313757 -236.759112)
		(end 87.471504 -236.736636)
		(width 0.09525)
		(layer "In13.Cu")
		(net "M_B_CPU1_SA_DQS_DP<2>")
	)
	(arc
		(start 79.650082 -236.71911)
		(mid 79.831139 -236.760092)
		(end 80.009746 -236.709458)
		(width 0.09525)
		(layer "In13.Cu")
		(net "M_B_CPU1_SA_DQS_DP<2>")
	)
	(arc
		(start 81.51241 -236.709458)
		(mid 81.696185 -236.76023)
		(end 81.881218 -236.714284)
		(width 0.09525)
		(layer "In13.Cu")
		(net "M_B_CPU1_SA_DQS_DP<2>")
	)
	(arc
		(start 86.589616 -236.709458)
		(mid 86.871048 -236.633703)
		(end 87.15248 -236.709458)
		(width 0.09525)
		(layer "In13.Cu")
		(net "M_B_CPU1_SA_DQS_DP<2>")
	)
	(arc
		(start 80.949546 -236.709458)
		(mid 81.230978 -236.633703)
		(end 81.51241 -236.709458)
		(width 0.09525)
		(layer "In13.Cu")
		(net "M_B_CPU1_SA_DQS_DP<2>")
	)
	(arc
		(start 80.57261 -236.709458)
		(mid 80.761078 -236.760135)
		(end 80.949546 -236.709458)
		(width 0.09525)
		(layer "In13.Cu")
		(net "M_B_CPU1_SA_DQS_DP<2>")
	)
	(arc
		(start 80.009746 -236.709458)
		(mid 80.291178 -236.633703)
		(end 80.57261 -236.709458)
		(width 0.09525)
		(layer "In13.Cu")
		(net "M_B_CPU1_SA_DQS_DP<2>")
	)
	(arc
		(start 85.649562 -236.709458)
		(mid 85.930994 -236.633703)
		(end 86.212426 -236.709458)
		(width 0.09525)
		(layer "In13.Cu")
		(net "M_B_CPU1_SA_DQS_DP<2>")
	)
	(arc
		(start 85.272372 -236.709458)
		(mid 85.456147 -236.76023)
		(end 85.64118 -236.714284)
		(width 0.09525)
		(layer "In13.Cu")
		(net "M_B_CPU1_SA_DQS_DP<2>")
	)
	(arc
		(start 82.829654 -236.709458)
		(mid 83.111086 -236.633703)
		(end 83.392518 -236.709458)
		(width 0.09525)
		(layer "In13.Cu")
		(net "M_B_CPU1_SA_DQS_DP<2>")
	)
	(arc
		(start 81.8896 -236.709458)
		(mid 82.171032 -236.633703)
		(end 82.452464 -236.709458)
		(width 0.09525)
		(layer "In13.Cu")
		(net "M_B_CPU1_SA_DQS_DP<2>")
	)
	(arc
		(start 78.693772 -236.709458)
		(mid 78.872087 -236.7606)
		(end 79.053182 -236.72038)
		(width 0.09525)
		(layer "In13.Cu")
		(net "M_B_CPU1_SA_DQS_DP<2>")
	)
	(arc
		(start 86.212426 -236.709458)
		(mid 86.396201 -236.76023)
		(end 86.581234 -236.714284)
		(width 0.09525)
		(layer "In13.Cu")
		(net "M_B_CPU1_SA_DQS_DP<2>")
	)
	(arc
		(start 83.4009 -236.714284)
		(mid 83.585932 -236.760198)
		(end 83.769708 -236.709458)
		(width 0.09525)
		(layer "In13.Cu")
		(net "M_B_CPU1_SA_DQS_DP<2>")
	)
	(arc
		(start 78.411832 -236.633004)
		(mid 78.557875 -236.65254)
		(end 78.693772 -236.709458)
		(width 0.09525)
		(layer "In13.Cu")
		(net "M_B_CPU1_SA_DQS_DP<2>")
	)
	(arc
		(start 82.460846 -236.714284)
		(mid 82.645878 -236.760198)
		(end 82.829654 -236.709458)
		(width 0.09525)
		(layer "In13.Cu")
		(net "M_B_CPU1_SA_DQS_DP<2>")
	)
	(arc
		(start 84.332572 -236.709458)
		(mid 84.52104 -236.760135)
		(end 84.709508 -236.709458)
		(width 0.09525)
		(layer "In13.Cu")
		(net "M_B_CPU1_SA_DQS_DP<2>")
	)
	(arc
		(start 83.769708 -236.709458)
		(mid 84.05114 -236.633703)
		(end 84.332572 -236.709458)
		(width 0.09525)
		(layer "In13.Cu")
		(net "M_B_CPU1_SA_DQS_DP<2>")
	)
	(segment
		(start 87.8078 -231.79024)
		(end 87.340948 -231.524302)
		(width 0.12954)
		(layer "F.Cu")
		(net "M_B_CPU1_SA_DQS_DP<1>")
	)
	(segment
		(start 65.044066 -215.029796)
		(end 65.044066 -215.5571)
		(width 0.16002)
		(layer "In13.Cu")
		(net "M_B_CPU1_SA_DQS_DP<1>")
	)
	(segment
		(start 54.486048 -210.344004)
		(end 55.110888 -210.968844)
		(width 0.16002)
		(layer "In13.Cu")
		(net "M_B_CPU1_SA_DQS_DP<1>")
	)
	(segment
		(start 66.311018 -217.314272)
		(end 66.506852 -217.510106)
		(width 0.16002)
		(layer "In13.Cu")
		(net "M_B_CPU1_SA_DQS_DP<1>")
	)
	(segment
		(start 69.164962 -219.150692)
		(end 69.164962 -219.677996)
		(width 0.16002)
		(layer "In13.Cu")
		(net "M_B_CPU1_SA_DQS_DP<1>")
	)
	(segment
		(start 70.538594 -221.051628)
		(end 70.431914 -221.158308)
		(width 0.16002)
		(layer "In13.Cu")
		(net "M_B_CPU1_SA_DQS_DP<1>")
	)
	(segment
		(start 67.79133 -217.77706)
		(end 67.79133 -218.304364)
		(width 0.16002)
		(layer "In13.Cu")
		(net "M_B_CPU1_SA_DQS_DP<1>")
	)
	(segment
		(start 71.011288 -221.524322)
		(end 71.538592 -221.524322)
		(width 0.16002)
		(layer "In13.Cu")
		(net "M_B_CPU1_SA_DQS_DP<1>")
	)
	(segment
		(start 66.890392 -217.403426)
		(end 67.417696 -217.403426)
		(width 0.16002)
		(layer "In13.Cu")
		(net "M_B_CPU1_SA_DQS_DP<1>")
	)
	(segment
		(start 64.143128 -214.656162)
		(end 64.670432 -214.656162)
		(width 0.16002)
		(layer "In13.Cu")
		(net "M_B_CPU1_SA_DQS_DP<1>")
	)
	(segment
		(start 71.538592 -221.524322)
		(end 71.912226 -221.897956)
		(width 0.16002)
		(layer "In13.Cu")
		(net "M_B_CPU1_SA_DQS_DP<1>")
	)
	(segment
		(start 63.563754 -214.290148)
		(end 63.563754 -214.567008)
		(width 0.16002)
		(layer "In13.Cu")
		(net "M_B_CPU1_SA_DQS_DP<1>")
	)
	(segment
		(start 67.79133 -218.304364)
		(end 67.68465 -218.411044)
		(width 0.16002)
		(layer "In13.Cu")
		(net "M_B_CPU1_SA_DQS_DP<1>")
	)
	(segment
		(start 68.791328 -218.777058)
		(end 69.164962 -219.150692)
		(width 0.16002)
		(layer "In13.Cu")
		(net "M_B_CPU1_SA_DQS_DP<1>")
	)
	(segment
		(start 78.158594 -230.149146)
		(end 78.61173 -230.149146)
		(width 0.09525)
		(layer "In13.Cu")
		(net "M_B_CPU1_SA_DQS_DP<1>")
	)
	(segment
		(start 77.458824 -229.449376)
		(end 78.158594 -230.149146)
		(width 0.09525)
		(layer "In13.Cu")
		(net "M_B_CPU1_SA_DQS_DP<1>")
	)
	(segment
		(start 59.361324 -210.968844)
		(end 60.392818 -211.396072)
		(width 0.16002)
		(layer "In13.Cu")
		(net "M_B_CPU1_SA_DQS_DP<1>")
	)
	(segment
		(start 69.637656 -220.15069)
		(end 70.16496 -220.15069)
		(width 0.16002)
		(layer "In13.Cu")
		(net "M_B_CPU1_SA_DQS_DP<1>")
	)
	(segment
		(start 62.385956 -213.38921)
		(end 62.662816 -213.38921)
		(width 0.16002)
		(layer "In13.Cu")
		(net "M_B_CPU1_SA_DQS_DP<1>")
	)
	(segment
		(start 66.311018 -217.037412)
		(end 66.311018 -217.314272)
		(width 0.16002)
		(layer "In13.Cu")
		(net "M_B_CPU1_SA_DQS_DP<1>")
	)
	(segment
		(start 68.264024 -218.777058)
		(end 68.791328 -218.777058)
		(width 0.16002)
		(layer "In13.Cu")
		(net "M_B_CPU1_SA_DQS_DP<1>")
	)
	(segment
		(start 63.563754 -214.567008)
		(end 63.759588 -214.762842)
		(width 0.16002)
		(layer "In13.Cu")
		(net "M_B_CPU1_SA_DQS_DP<1>")
	)
	(segment
		(start 78.95209 -230.489506)
		(end 78.95209 -231.187752)
		(width 0.09525)
		(layer "In13.Cu")
		(net "M_B_CPU1_SA_DQS_DP<1>")
	)
	(segment
		(start 67.417696 -217.403426)
		(end 67.79133 -217.77706)
		(width 0.16002)
		(layer "In13.Cu")
		(net "M_B_CPU1_SA_DQS_DP<1>")
	)
	(segment
		(start 68.157344 -218.883738)
		(end 68.264024 -218.777058)
		(width 0.16002)
		(layer "In13.Cu")
		(net "M_B_CPU1_SA_DQS_DP<1>")
	)
	(segment
		(start 70.538594 -220.524324)
		(end 70.538594 -221.051628)
		(width 0.16002)
		(layer "In13.Cu")
		(net "M_B_CPU1_SA_DQS_DP<1>")
	)
	(segment
		(start 78.95209 -231.187752)
		(end 79.554832 -231.790494)
		(width 0.09525)
		(layer "In13.Cu")
		(net "M_B_CPU1_SA_DQS_DP<1>")
	)
	(segment
		(start 69.164962 -219.677996)
		(end 69.058282 -219.784676)
		(width 0.16002)
		(layer "In13.Cu")
		(net "M_B_CPU1_SA_DQS_DP<1>")
	)
	(segment
		(start 71.805546 -222.53194)
		(end 71.805546 -222.8088)
		(width 0.16002)
		(layer "In13.Cu")
		(net "M_B_CPU1_SA_DQS_DP<1>")
	)
	(segment
		(start 87.471504 -231.8766)
		(end 87.494872 -231.789732)
		(width 0.09525)
		(layer "In13.Cu")
		(net "M_B_CPU1_SA_DQS_DP<1>")
	)
	(segment
		(start 70.627748 -221.631002)
		(end 70.904608 -221.631002)
		(width 0.16002)
		(layer "In13.Cu")
		(net "M_B_CPU1_SA_DQS_DP<1>")
	)
	(segment
		(start 64.036448 -214.762842)
		(end 64.143128 -214.656162)
		(width 0.16002)
		(layer "In13.Cu")
		(net "M_B_CPU1_SA_DQS_DP<1>")
	)
	(segment
		(start 87.15248 -231.849422)
		(end 87.160862 -231.854248)
		(width 0.09525)
		(layer "In13.Cu")
		(net "M_B_CPU1_SA_DQS_DP<1>")
	)
	(segment
		(start 69.530976 -220.25737)
		(end 69.637656 -220.15069)
		(width 0.16002)
		(layer "In13.Cu")
		(net "M_B_CPU1_SA_DQS_DP<1>")
	)
	(segment
		(start 63.759588 -214.762842)
		(end 64.036448 -214.762842)
		(width 0.16002)
		(layer "In13.Cu")
		(net "M_B_CPU1_SA_DQS_DP<1>")
	)
	(segment
		(start 52.142644 -210.344004)
		(end 54.486048 -210.344004)
		(width 0.16002)
		(layer "In13.Cu")
		(net "M_B_CPU1_SA_DQS_DP<1>")
	)
	(segment
		(start 55.110888 -210.968844)
		(end 59.361324 -210.968844)
		(width 0.16002)
		(layer "In13.Cu")
		(net "M_B_CPU1_SA_DQS_DP<1>")
	)
	(segment
		(start 83.392518 -231.849422)
		(end 83.4009 -231.854248)
		(width 0.09525)
		(layer "In13.Cu")
		(net "M_B_CPU1_SA_DQS_DP<1>")
	)
	(segment
		(start 63.670434 -214.183468)
		(end 63.563754 -214.290148)
		(width 0.16002)
		(layer "In13.Cu")
		(net "M_B_CPU1_SA_DQS_DP<1>")
	)
	(segment
		(start 66.783712 -217.510106)
		(end 66.890392 -217.403426)
		(width 0.16002)
		(layer "In13.Cu")
		(net "M_B_CPU1_SA_DQS_DP<1>")
	)
	(segment
		(start 67.68465 -218.687904)
		(end 67.880484 -218.883738)
		(width 0.16002)
		(layer "In13.Cu")
		(net "M_B_CPU1_SA_DQS_DP<1>")
	)
	(segment
		(start 85.64118 -231.854248)
		(end 85.649562 -231.849422)
		(width 0.09525)
		(layer "In13.Cu")
		(net "M_B_CPU1_SA_DQS_DP<1>")
	)
	(segment
		(start 69.058282 -219.784676)
		(end 69.058282 -220.061536)
		(width 0.16002)
		(layer "In13.Cu")
		(net "M_B_CPU1_SA_DQS_DP<1>")
	)
	(segment
		(start 62.662816 -213.38921)
		(end 62.769496 -213.28253)
		(width 0.16002)
		(layer "In13.Cu")
		(net "M_B_CPU1_SA_DQS_DP<1>")
	)
	(segment
		(start 69.058282 -220.061536)
		(end 69.254116 -220.25737)
		(width 0.16002)
		(layer "In13.Cu")
		(net "M_B_CPU1_SA_DQS_DP<1>")
	)
	(segment
		(start 65.41008 -216.136474)
		(end 65.51676 -216.029794)
		(width 0.16002)
		(layer "In13.Cu")
		(net "M_B_CPU1_SA_DQS_DP<1>")
	)
	(segment
		(start 76.953872 -229.449376)
		(end 77.458824 -229.449376)
		(width 0.09525)
		(layer "In13.Cu")
		(net "M_B_CPU1_SA_DQS_DP<1>")
	)
	(segment
		(start 86.581234 -231.854248)
		(end 86.589616 -231.849422)
		(width 0.09525)
		(layer "In13.Cu")
		(net "M_B_CPU1_SA_DQS_DP<1>")
	)
	(segment
		(start 70.904608 -221.631002)
		(end 71.011288 -221.524322)
		(width 0.16002)
		(layer "In13.Cu")
		(net "M_B_CPU1_SA_DQS_DP<1>")
	)
	(segment
		(start 76.493878 -228.906324)
		(end 76.493878 -228.989382)
		(width 0.09525)
		(layer "In13.Cu")
		(net "M_B_CPU1_SA_DQS_DP<1>")
	)
	(segment
		(start 64.670432 -214.656162)
		(end 65.044066 -215.029796)
		(width 0.16002)
		(layer "In13.Cu")
		(net "M_B_CPU1_SA_DQS_DP<1>")
	)
	(segment
		(start 73.80859 -224.811844)
		(end 73.80859 -226.221036)
		(width 0.16002)
		(layer "In13.Cu")
		(net "M_B_CPU1_SA_DQS_DP<1>")
	)
	(segment
		(start 66.417698 -216.930732)
		(end 66.311018 -217.037412)
		(width 0.16002)
		(layer "In13.Cu")
		(net "M_B_CPU1_SA_DQS_DP<1>")
	)
	(segment
		(start 70.431914 -221.435168)
		(end 70.627748 -221.631002)
		(width 0.16002)
		(layer "In13.Cu")
		(net "M_B_CPU1_SA_DQS_DP<1>")
	)
	(segment
		(start 67.68465 -218.411044)
		(end 67.68465 -218.687904)
		(width 0.16002)
		(layer "In13.Cu")
		(net "M_B_CPU1_SA_DQS_DP<1>")
	)
	(segment
		(start 76.493878 -228.989382)
		(end 76.953872 -229.449376)
		(width 0.09525)
		(layer "In13.Cu")
		(net "M_B_CPU1_SA_DQS_DP<1>")
	)
	(segment
		(start 51.884072 -210.085432)
		(end 52.142644 -210.344004)
		(width 0.16002)
		(layer "In13.Cu")
		(net "M_B_CPU1_SA_DQS_DP<1>")
	)
	(segment
		(start 70.431914 -221.158308)
		(end 70.431914 -221.435168)
		(width 0.16002)
		(layer "In13.Cu")
		(net "M_B_CPU1_SA_DQS_DP<1>")
	)
	(segment
		(start 66.044064 -216.029794)
		(end 66.417698 -216.403428)
		(width 0.16002)
		(layer "In13.Cu")
		(net "M_B_CPU1_SA_DQS_DP<1>")
	)
	(segment
		(start 63.2968 -213.28253)
		(end 63.670434 -213.656164)
		(width 0.16002)
		(layer "In13.Cu")
		(net "M_B_CPU1_SA_DQS_DP<1>")
	)
	(segment
		(start 63.670434 -213.656164)
		(end 63.670434 -214.183468)
		(width 0.16002)
		(layer "In13.Cu")
		(net "M_B_CPU1_SA_DQS_DP<1>")
	)
	(segment
		(start 64.937386 -215.66378)
		(end 64.937386 -215.94064)
		(width 0.16002)
		(layer "In13.Cu")
		(net "M_B_CPU1_SA_DQS_DP<1>")
	)
	(segment
		(start 64.937386 -215.94064)
		(end 65.13322 -216.136474)
		(width 0.16002)
		(layer "In13.Cu")
		(net "M_B_CPU1_SA_DQS_DP<1>")
	)
	(segment
		(start 69.254116 -220.25737)
		(end 69.530976 -220.25737)
		(width 0.16002)
		(layer "In13.Cu")
		(net "M_B_CPU1_SA_DQS_DP<1>")
	)
	(segment
		(start 62.769496 -213.28253)
		(end 63.2968 -213.28253)
		(width 0.16002)
		(layer "In13.Cu")
		(net "M_B_CPU1_SA_DQS_DP<1>")
	)
	(segment
		(start 71.912226 -222.42526)
		(end 71.805546 -222.53194)
		(width 0.16002)
		(layer "In13.Cu")
		(net "M_B_CPU1_SA_DQS_DP<1>")
	)
	(segment
		(start 71.912226 -221.897956)
		(end 71.912226 -222.42526)
		(width 0.16002)
		(layer "In13.Cu")
		(net "M_B_CPU1_SA_DQS_DP<1>")
	)
	(segment
		(start 71.805546 -222.8088)
		(end 73.80859 -224.811844)
		(width 0.16002)
		(layer "In13.Cu")
		(net "M_B_CPU1_SA_DQS_DP<1>")
	)
	(segment
		(start 87.494872 -231.789732)
		(end 87.340948 -231.524302)
		(width 0.09525)
		(layer "In13.Cu")
		(net "M_B_CPU1_SA_DQS_DP<1>")
	)
	(segment
		(start 78.61173 -230.149146)
		(end 78.95209 -230.489506)
		(width 0.09525)
		(layer "In13.Cu")
		(net "M_B_CPU1_SA_DQS_DP<1>")
	)
	(segment
		(start 60.392818 -211.396072)
		(end 62.385956 -213.38921)
		(width 0.16002)
		(layer "In13.Cu")
		(net "M_B_CPU1_SA_DQS_DP<1>")
	)
	(segment
		(start 65.044066 -215.5571)
		(end 64.937386 -215.66378)
		(width 0.16002)
		(layer "In13.Cu")
		(net "M_B_CPU1_SA_DQS_DP<1>")
	)
	(segment
		(start 73.80859 -226.221036)
		(end 76.477114 -228.88956)
		(width 0.16002)
		(layer "In13.Cu")
		(net "M_B_CPU1_SA_DQS_DP<1>")
	)
	(segment
		(start 70.16496 -220.15069)
		(end 70.538594 -220.524324)
		(width 0.16002)
		(layer "In13.Cu")
		(net "M_B_CPU1_SA_DQS_DP<1>")
	)
	(segment
		(start 66.417698 -216.403428)
		(end 66.417698 -216.930732)
		(width 0.16002)
		(layer "In13.Cu")
		(net "M_B_CPU1_SA_DQS_DP<1>")
	)
	(segment
		(start 66.506852 -217.510106)
		(end 66.783712 -217.510106)
		(width 0.16002)
		(layer "In13.Cu")
		(net "M_B_CPU1_SA_DQS_DP<1>")
	)
	(segment
		(start 81.881218 -231.854248)
		(end 81.8896 -231.849422)
		(width 0.09525)
		(layer "In13.Cu")
		(net "M_B_CPU1_SA_DQS_DP<1>")
	)
	(segment
		(start 65.51676 -216.029794)
		(end 66.044064 -216.029794)
		(width 0.16002)
		(layer "In13.Cu")
		(net "M_B_CPU1_SA_DQS_DP<1>")
	)
	(segment
		(start 65.13322 -216.136474)
		(end 65.41008 -216.136474)
		(width 0.16002)
		(layer "In13.Cu")
		(net "M_B_CPU1_SA_DQS_DP<1>")
	)
	(segment
		(start 76.477114 -228.88956)
		(end 76.493878 -228.906324)
		(width 0.09525)
		(layer "In13.Cu")
		(net "M_B_CPU1_SA_DQS_DP<1>")
	)
	(segment
		(start 67.880484 -218.883738)
		(end 68.157344 -218.883738)
		(width 0.16002)
		(layer "In13.Cu")
		(net "M_B_CPU1_SA_DQS_DP<1>")
	)
	(segment
		(start 82.452464 -231.849422)
		(end 82.460846 -231.854248)
		(width 0.09525)
		(layer "In13.Cu")
		(net "M_B_CPU1_SA_DQS_DP<1>")
	)
	(segment
		(start 79.632556 -231.849422)
		(end 79.640938 -231.854248)
		(width 0.09525)
		(layer "In13.Cu")
		(net "M_B_CPU1_SA_DQS_DP<1>")
	)
	(arc
		(start 85.272372 -231.849422)
		(mid 85.456147 -231.900194)
		(end 85.64118 -231.854248)
		(width 0.09525)
		(layer "In13.Cu")
		(net "M_B_CPU1_SA_DQS_DP<1>")
	)
	(arc
		(start 82.829654 -231.849422)
		(mid 83.111086 -231.773667)
		(end 83.392518 -231.849422)
		(width 0.09525)
		(layer "In13.Cu")
		(net "M_B_CPU1_SA_DQS_DP<1>")
	)
	(arc
		(start 80.57261 -231.849422)
		(mid 80.761078 -231.900099)
		(end 80.949546 -231.849422)
		(width 0.09525)
		(layer "In13.Cu")
		(net "M_B_CPU1_SA_DQS_DP<1>")
	)
	(arc
		(start 80.009746 -231.849422)
		(mid 80.291178 -231.773667)
		(end 80.57261 -231.849422)
		(width 0.09525)
		(layer "In13.Cu")
		(net "M_B_CPU1_SA_DQS_DP<1>")
	)
	(arc
		(start 79.640938 -231.854248)
		(mid 79.82597 -231.900162)
		(end 80.009746 -231.849422)
		(width 0.09525)
		(layer "In13.Cu")
		(net "M_B_CPU1_SA_DQS_DP<1>")
	)
	(arc
		(start 86.589616 -231.849422)
		(mid 86.871048 -231.773667)
		(end 87.15248 -231.849422)
		(width 0.09525)
		(layer "In13.Cu")
		(net "M_B_CPU1_SA_DQS_DP<1>")
	)
	(arc
		(start 83.4009 -231.854248)
		(mid 83.585932 -231.900162)
		(end 83.769708 -231.849422)
		(width 0.09525)
		(layer "In13.Cu")
		(net "M_B_CPU1_SA_DQS_DP<1>")
	)
	(arc
		(start 81.51241 -231.849422)
		(mid 81.696185 -231.900194)
		(end 81.881218 -231.854248)
		(width 0.09525)
		(layer "In13.Cu")
		(net "M_B_CPU1_SA_DQS_DP<1>")
	)
	(arc
		(start 84.332572 -231.849422)
		(mid 84.52104 -231.900099)
		(end 84.709508 -231.849422)
		(width 0.09525)
		(layer "In13.Cu")
		(net "M_B_CPU1_SA_DQS_DP<1>")
	)
	(arc
		(start 87.160862 -231.854248)
		(mid 87.313757 -231.899076)
		(end 87.471504 -231.8766)
		(width 0.09525)
		(layer "In13.Cu")
		(net "M_B_CPU1_SA_DQS_DP<1>")
	)
	(arc
		(start 85.649562 -231.849422)
		(mid 85.930994 -231.773667)
		(end 86.212426 -231.849422)
		(width 0.09525)
		(layer "In13.Cu")
		(net "M_B_CPU1_SA_DQS_DP<1>")
	)
	(arc
		(start 82.460846 -231.854248)
		(mid 82.645878 -231.900162)
		(end 82.829654 -231.849422)
		(width 0.09525)
		(layer "In13.Cu")
		(net "M_B_CPU1_SA_DQS_DP<1>")
	)
	(arc
		(start 81.8896 -231.849422)
		(mid 82.171032 -231.773667)
		(end 82.452464 -231.849422)
		(width 0.09525)
		(layer "In13.Cu")
		(net "M_B_CPU1_SA_DQS_DP<1>")
	)
	(arc
		(start 83.769708 -231.849422)
		(mid 84.05114 -231.773667)
		(end 84.332572 -231.849422)
		(width 0.09525)
		(layer "In13.Cu")
		(net "M_B_CPU1_SA_DQS_DP<1>")
	)
	(arc
		(start 84.709508 -231.849422)
		(mid 84.99094 -231.773667)
		(end 85.272372 -231.849422)
		(width 0.09525)
		(layer "In13.Cu")
		(net "M_B_CPU1_SA_DQS_DP<1>")
	)
	(arc
		(start 86.212426 -231.849422)
		(mid 86.396201 -231.900194)
		(end 86.581234 -231.854248)
		(width 0.09525)
		(layer "In13.Cu")
		(net "M_B_CPU1_SA_DQS_DP<1>")
	)
	(arc
		(start 80.949546 -231.849422)
		(mid 81.230978 -231.773667)
		(end 81.51241 -231.849422)
		(width 0.09525)
		(layer "In13.Cu")
		(net "M_B_CPU1_SA_DQS_DP<1>")
	)
	(arc
		(start 79.554832 -231.790494)
		(mid 79.591776 -231.822487)
		(end 79.632556 -231.849422)
		(width 0.09525)
		(layer "In13.Cu")
		(net "M_B_CPU1_SA_DQS_DP<1>")
	)
	(segment
		(start 87.8078 -226.930458)
		(end 87.340948 -226.66452)
		(width 0.12954)
		(layer "F.Cu")
		(net "M_B_CPU1_SA_DQS_DP<0>")
	)
	(segment
		(start 71.998586 -213.52764)
		(end 72.747886 -213.52764)
		(width 0.16002)
		(layer "In13.Cu")
		(net "M_B_CPU1_SA_DQS_DP<0>")
	)
	(segment
		(start 66.28003 -207.059784)
		(end 66.28003 -207.809084)
		(width 0.16002)
		(layer "In13.Cu")
		(net "M_B_CPU1_SA_DQS_DP<0>")
	)
	(segment
		(start 80.540098 -223.73082)
		(end 80.57261 -223.749616)
		(width 0.09525)
		(layer "In13.Cu")
		(net "M_B_CPU1_SA_DQS_DP<0>")
	)
	(segment
		(start 63.132462 -203.912216)
		(end 63.532766 -204.31252)
		(width 0.16002)
		(layer "In13.Cu")
		(net "M_B_CPU1_SA_DQS_DP<0>")
	)
	(segment
		(start 73.14819 -214.677244)
		(end 73.372218 -214.901272)
		(width 0.16002)
		(layer "In13.Cu")
		(net "M_B_CPU1_SA_DQS_DP<0>")
	)
	(segment
		(start 81.009998 -224.540826)
		(end 81.04251 -224.559622)
		(width 0.09525)
		(layer "In13.Cu")
		(net "M_B_CPU1_SA_DQS_DP<0>")
	)
	(segment
		(start 82.419952 -226.970844)
		(end 82.452464 -226.98964)
		(width 0.09525)
		(layer "In13.Cu")
		(net "M_B_CPU1_SA_DQS_DP<0>")
	)
	(segment
		(start 74.74585 -216.274904)
		(end 75.49515 -216.274904)
		(width 0.16002)
		(layer "In13.Cu")
		(net "M_B_CPU1_SA_DQS_DP<0>")
	)
	(segment
		(start 64.906398 -206.435452)
		(end 65.130426 -206.65948)
		(width 0.16002)
		(layer "In13.Cu")
		(net "M_B_CPU1_SA_DQS_DP<0>")
	)
	(segment
		(start 67.653662 -209.182716)
		(end 67.87769 -209.406744)
		(width 0.16002)
		(layer "In13.Cu")
		(net "M_B_CPU1_SA_DQS_DP<0>")
	)
	(segment
		(start 56.153304 -200.961752)
		(end 57.766712 -201.630026)
		(width 0.16002)
		(layer "In13.Cu")
		(net "M_B_CPU1_SA_DQS_DP<0>")
	)
	(segment
		(start 76.119482 -217.648536)
		(end 76.868782 -217.648536)
		(width 0.16002)
		(layer "In13.Cu")
		(net "M_B_CPU1_SA_DQS_DP<0>")
	)
	(segment
		(start 70.400926 -211.92998)
		(end 70.624954 -212.154008)
		(width 0.16002)
		(layer "In13.Cu")
		(net "M_B_CPU1_SA_DQS_DP<0>")
	)
	(segment
		(start 65.130426 -206.65948)
		(end 65.879726 -206.65948)
		(width 0.16002)
		(layer "In13.Cu")
		(net "M_B_CPU1_SA_DQS_DP<0>")
	)
	(segment
		(start 65.879726 -206.65948)
		(end 66.28003 -207.059784)
		(width 0.16002)
		(layer "In13.Cu")
		(net "M_B_CPU1_SA_DQS_DP<0>")
	)
	(segment
		(start 66.504058 -208.033112)
		(end 67.253358 -208.033112)
		(width 0.16002)
		(layer "In13.Cu")
		(net "M_B_CPU1_SA_DQS_DP<0>")
	)
	(segment
		(start 87.15248 -226.98964)
		(end 87.160862 -226.994466)
		(width 0.09525)
		(layer "In13.Cu")
		(net "M_B_CPU1_SA_DQS_DP<0>")
	)
	(segment
		(start 81.950052 -226.160838)
		(end 81.982564 -226.179634)
		(width 0.09525)
		(layer "In13.Cu")
		(net "M_B_CPU1_SA_DQS_DP<0>")
	)
	(segment
		(start 77.493114 -219.022168)
		(end 78.242414 -219.022168)
		(width 0.16002)
		(layer "In13.Cu")
		(net "M_B_CPU1_SA_DQS_DP<0>")
	)
	(segment
		(start 77.269086 -218.04884)
		(end 77.269086 -218.79814)
		(width 0.16002)
		(layer "In13.Cu")
		(net "M_B_CPU1_SA_DQS_DP<0>")
	)
	(segment
		(start 67.253358 -208.033112)
		(end 67.653662 -208.433416)
		(width 0.16002)
		(layer "In13.Cu")
		(net "M_B_CPU1_SA_DQS_DP<0>")
	)
	(segment
		(start 81.51241 -225.369628)
		(end 81.55051 -225.391726)
		(width 0.09525)
		(layer "In13.Cu")
		(net "M_B_CPU1_SA_DQS_DP<0>")
	)
	(segment
		(start 69.027294 -210.556348)
		(end 69.251322 -210.780376)
		(width 0.16002)
		(layer "In13.Cu")
		(net "M_B_CPU1_SA_DQS_DP<0>")
	)
	(segment
		(start 85.64118 -226.994466)
		(end 85.649562 -226.98964)
		(width 0.09525)
		(layer "In13.Cu")
		(net "M_B_CPU1_SA_DQS_DP<0>")
	)
	(segment
		(start 52.110386 -200.961752)
		(end 56.153304 -200.961752)
		(width 0.16002)
		(layer "In13.Cu")
		(net "M_B_CPU1_SA_DQS_DP<0>")
	)
	(segment
		(start 79.501746 -221.316804)
		(end 79.501746 -221.340426)
		(width 0.09525)
		(layer "In13.Cu")
		(net "M_B_CPU1_SA_DQS_DP<0>")
	)
	(segment
		(start 75.895454 -216.675208)
		(end 75.895454 -217.424508)
		(width 0.16002)
		(layer "In13.Cu")
		(net "M_B_CPU1_SA_DQS_DP<0>")
	)
	(segment
		(start 80.57261 -223.749616)
		(end 80.607662 -223.77019)
		(width 0.09525)
		(layer "In13.Cu")
		(net "M_B_CPU1_SA_DQS_DP<0>")
	)
	(segment
		(start 70.624954 -212.154008)
		(end 71.374254 -212.154008)
		(width 0.16002)
		(layer "In13.Cu")
		(net "M_B_CPU1_SA_DQS_DP<0>")
	)
	(segment
		(start 64.506094 -205.285848)
		(end 64.906398 -205.686152)
		(width 0.16002)
		(layer "In13.Cu")
		(net "M_B_CPU1_SA_DQS_DP<0>")
	)
	(segment
		(start 63.756794 -205.285848)
		(end 64.506094 -205.285848)
		(width 0.16002)
		(layer "In13.Cu")
		(net "M_B_CPU1_SA_DQS_DP<0>")
	)
	(segment
		(start 86.581234 -226.994466)
		(end 86.589616 -226.98964)
		(width 0.09525)
		(layer "In13.Cu")
		(net "M_B_CPU1_SA_DQS_DP<0>")
	)
	(segment
		(start 73.372218 -214.901272)
		(end 74.121518 -214.901272)
		(width 0.16002)
		(layer "In13.Cu")
		(net "M_B_CPU1_SA_DQS_DP<0>")
	)
	(segment
		(start 67.87769 -209.406744)
		(end 68.62699 -209.406744)
		(width 0.16002)
		(layer "In13.Cu")
		(net "M_B_CPU1_SA_DQS_DP<0>")
	)
	(segment
		(start 77.269086 -218.79814)
		(end 77.493114 -219.022168)
		(width 0.16002)
		(layer "In13.Cu")
		(net "M_B_CPU1_SA_DQS_DP<0>")
	)
	(segment
		(start 79.501746 -221.340426)
		(end 79.442818 -221.399354)
		(width 0.09525)
		(layer "In13.Cu")
		(net "M_B_CPU1_SA_DQS_DP<0>")
	)
	(segment
		(start 76.868782 -217.648536)
		(end 77.269086 -218.04884)
		(width 0.16002)
		(layer "In13.Cu")
		(net "M_B_CPU1_SA_DQS_DP<0>")
	)
	(segment
		(start 87.471504 -227.016818)
		(end 87.494872 -226.92995)
		(width 0.09525)
		(layer "In13.Cu")
		(net "M_B_CPU1_SA_DQS_DP<0>")
	)
	(segment
		(start 64.906398 -205.686152)
		(end 64.906398 -206.435452)
		(width 0.16002)
		(layer "In13.Cu")
		(net "M_B_CPU1_SA_DQS_DP<0>")
	)
	(segment
		(start 80.10271 -222.93961)
		(end 80.137762 -222.960184)
		(width 0.09525)
		(layer "In13.Cu")
		(net "M_B_CPU1_SA_DQS_DP<0>")
	)
	(segment
		(start 62.383162 -203.912216)
		(end 63.132462 -203.912216)
		(width 0.16002)
		(layer "In13.Cu")
		(net "M_B_CPU1_SA_DQS_DP<0>")
	)
	(segment
		(start 80.071214 -222.921322)
		(end 80.10271 -222.93961)
		(width 0.09525)
		(layer "In13.Cu")
		(net "M_B_CPU1_SA_DQS_DP<0>")
	)
	(segment
		(start 83.392518 -226.98964)
		(end 83.4009 -226.994466)
		(width 0.09525)
		(layer "In13.Cu")
		(net "M_B_CPU1_SA_DQS_DP<0>")
	)
	(segment
		(start 79.442818 -221.399354)
		(end 79.442818 -221.804484)
		(width 0.09525)
		(layer "In13.Cu")
		(net "M_B_CPU1_SA_DQS_DP<0>")
	)
	(segment
		(start 60.850272 -201.630026)
		(end 62.159134 -202.938888)
		(width 0.16002)
		(layer "In13.Cu")
		(net "M_B_CPU1_SA_DQS_DP<0>")
	)
	(segment
		(start 57.766712 -201.630026)
		(end 60.850272 -201.630026)
		(width 0.16002)
		(layer "In13.Cu")
		(net "M_B_CPU1_SA_DQS_DP<0>")
	)
	(segment
		(start 72.747886 -213.52764)
		(end 73.14819 -213.927944)
		(width 0.16002)
		(layer "In13.Cu")
		(net "M_B_CPU1_SA_DQS_DP<0>")
	)
	(segment
		(start 79.600044 -222.110808)
		(end 79.671926 -222.152464)
		(width 0.09525)
		(layer "In13.Cu")
		(net "M_B_CPU1_SA_DQS_DP<0>")
	)
	(segment
		(start 81.982564 -226.179634)
		(end 82.017616 -226.200208)
		(width 0.09525)
		(layer "In13.Cu")
		(net "M_B_CPU1_SA_DQS_DP<0>")
	)
	(segment
		(start 67.653662 -208.433416)
		(end 67.653662 -209.182716)
		(width 0.16002)
		(layer "In13.Cu")
		(net "M_B_CPU1_SA_DQS_DP<0>")
	)
	(segment
		(start 73.14819 -213.927944)
		(end 73.14819 -214.677244)
		(width 0.16002)
		(layer "In13.Cu")
		(net "M_B_CPU1_SA_DQS_DP<0>")
	)
	(segment
		(start 82.452464 -226.98964)
		(end 82.460846 -226.994466)
		(width 0.09525)
		(layer "In13.Cu")
		(net "M_B_CPU1_SA_DQS_DP<0>")
	)
	(segment
		(start 74.121518 -214.901272)
		(end 74.521822 -215.301576)
		(width 0.16002)
		(layer "In13.Cu")
		(net "M_B_CPU1_SA_DQS_DP<0>")
	)
	(segment
		(start 79.501746 -220.2815)
		(end 79.501746 -221.316804)
		(width 0.16002)
		(layer "In13.Cu")
		(net "M_B_CPU1_SA_DQS_DP<0>")
	)
	(segment
		(start 70.000622 -210.780376)
		(end 70.400926 -211.18068)
		(width 0.16002)
		(layer "In13.Cu")
		(net "M_B_CPU1_SA_DQS_DP<0>")
	)
	(segment
		(start 63.532766 -205.06182)
		(end 63.756794 -205.285848)
		(width 0.16002)
		(layer "In13.Cu")
		(net "M_B_CPU1_SA_DQS_DP<0>")
	)
	(segment
		(start 70.400926 -211.18068)
		(end 70.400926 -211.92998)
		(width 0.16002)
		(layer "In13.Cu")
		(net "M_B_CPU1_SA_DQS_DP<0>")
	)
	(segment
		(start 51.884072 -200.735438)
		(end 52.110386 -200.961752)
		(width 0.16002)
		(layer "In13.Cu")
		(net "M_B_CPU1_SA_DQS_DP<0>")
	)
	(segment
		(start 75.49515 -216.274904)
		(end 75.895454 -216.675208)
		(width 0.16002)
		(layer "In13.Cu")
		(net "M_B_CPU1_SA_DQS_DP<0>")
	)
	(segment
		(start 79.600044 -222.111316)
		(end 79.600044 -222.110808)
		(width 0.09525)
		(layer "In13.Cu")
		(net "M_B_CPU1_SA_DQS_DP<0>")
	)
	(segment
		(start 62.159134 -203.688188)
		(end 62.383162 -203.912216)
		(width 0.16002)
		(layer "In13.Cu")
		(net "M_B_CPU1_SA_DQS_DP<0>")
	)
	(segment
		(start 71.374254 -212.154008)
		(end 71.774558 -212.554312)
		(width 0.16002)
		(layer "In13.Cu")
		(net "M_B_CPU1_SA_DQS_DP<0>")
	)
	(segment
		(start 63.532766 -204.31252)
		(end 63.532766 -205.06182)
		(width 0.16002)
		(layer "In13.Cu")
		(net "M_B_CPU1_SA_DQS_DP<0>")
	)
	(segment
		(start 81.04251 -224.559622)
		(end 81.08061 -224.58172)
		(width 0.09525)
		(layer "In13.Cu")
		(net "M_B_CPU1_SA_DQS_DP<0>")
	)
	(segment
		(start 71.774558 -212.554312)
		(end 71.774558 -213.303612)
		(width 0.16002)
		(layer "In13.Cu")
		(net "M_B_CPU1_SA_DQS_DP<0>")
	)
	(segment
		(start 69.027294 -209.807048)
		(end 69.027294 -210.556348)
		(width 0.16002)
		(layer "In13.Cu")
		(net "M_B_CPU1_SA_DQS_DP<0>")
	)
	(segment
		(start 81.480914 -225.35134)
		(end 81.51241 -225.369628)
		(width 0.09525)
		(layer "In13.Cu")
		(net "M_B_CPU1_SA_DQS_DP<0>")
	)
	(segment
		(start 66.28003 -207.809084)
		(end 66.504058 -208.033112)
		(width 0.16002)
		(layer "In13.Cu")
		(net "M_B_CPU1_SA_DQS_DP<0>")
	)
	(segment
		(start 62.159134 -202.938888)
		(end 62.159134 -203.688188)
		(width 0.16002)
		(layer "In13.Cu")
		(net "M_B_CPU1_SA_DQS_DP<0>")
	)
	(segment
		(start 75.895454 -217.424508)
		(end 76.119482 -217.648536)
		(width 0.16002)
		(layer "In13.Cu")
		(net "M_B_CPU1_SA_DQS_DP<0>")
	)
	(segment
		(start 74.521822 -216.050876)
		(end 74.74585 -216.274904)
		(width 0.16002)
		(layer "In13.Cu")
		(net "M_B_CPU1_SA_DQS_DP<0>")
	)
	(segment
		(start 69.251322 -210.780376)
		(end 70.000622 -210.780376)
		(width 0.16002)
		(layer "In13.Cu")
		(net "M_B_CPU1_SA_DQS_DP<0>")
	)
	(segment
		(start 78.242414 -219.022168)
		(end 79.501746 -220.2815)
		(width 0.16002)
		(layer "In13.Cu")
		(net "M_B_CPU1_SA_DQS_DP<0>")
	)
	(segment
		(start 87.494872 -226.92995)
		(end 87.340948 -226.66452)
		(width 0.09525)
		(layer "In13.Cu")
		(net "M_B_CPU1_SA_DQS_DP<0>")
	)
	(segment
		(start 71.774558 -213.303612)
		(end 71.998586 -213.52764)
		(width 0.16002)
		(layer "In13.Cu")
		(net "M_B_CPU1_SA_DQS_DP<0>")
	)
	(segment
		(start 74.521822 -215.301576)
		(end 74.521822 -216.050876)
		(width 0.16002)
		(layer "In13.Cu")
		(net "M_B_CPU1_SA_DQS_DP<0>")
	)
	(segment
		(start 68.62699 -209.406744)
		(end 69.027294 -209.807048)
		(width 0.16002)
		(layer "In13.Cu")
		(net "M_B_CPU1_SA_DQS_DP<0>")
	)
	(arc
		(start 82.829654 -226.98964)
		(mid 83.111086 -226.913885)
		(end 83.392518 -226.98964)
		(width 0.09525)
		(layer "In13.Cu")
		(net "M_B_CPU1_SA_DQS_DP<0>")
	)
	(arc
		(start 80.137762 -222.960184)
		(mid 80.318217 -223.16185)
		(end 80.38338 -223.424496)
		(width 0.09525)
		(layer "In13.Cu")
		(net "M_B_CPU1_SA_DQS_DP<0>")
	)
	(arc
		(start 82.263234 -226.66452)
		(mid 82.304691 -226.83656)
		(end 82.419952 -226.970844)
		(width 0.09525)
		(layer "In13.Cu")
		(net "M_B_CPU1_SA_DQS_DP<0>")
	)
	(arc
		(start 80.85328 -224.234502)
		(mid 80.894737 -224.406542)
		(end 81.009998 -224.540826)
		(width 0.09525)
		(layer "In13.Cu")
		(net "M_B_CPU1_SA_DQS_DP<0>")
	)
	(arc
		(start 80.607662 -223.77019)
		(mid 80.788117 -223.971856)
		(end 80.85328 -224.234502)
		(width 0.09525)
		(layer "In13.Cu")
		(net "M_B_CPU1_SA_DQS_DP<0>")
	)
	(arc
		(start 82.017616 -226.200208)
		(mid 82.198071 -226.401874)
		(end 82.263234 -226.66452)
		(width 0.09525)
		(layer "In13.Cu")
		(net "M_B_CPU1_SA_DQS_DP<0>")
	)
	(arc
		(start 80.38338 -223.424496)
		(mid 80.424837 -223.596536)
		(end 80.540098 -223.73082)
		(width 0.09525)
		(layer "In13.Cu")
		(net "M_B_CPU1_SA_DQS_DP<0>")
	)
	(arc
		(start 84.709508 -226.98964)
		(mid 84.99094 -226.913885)
		(end 85.272372 -226.98964)
		(width 0.09525)
		(layer "In13.Cu")
		(net "M_B_CPU1_SA_DQS_DP<0>")
	)
	(arc
		(start 83.4009 -226.994466)
		(mid 83.585932 -227.04038)
		(end 83.769708 -226.98964)
		(width 0.09525)
		(layer "In13.Cu")
		(net "M_B_CPU1_SA_DQS_DP<0>")
	)
	(arc
		(start 83.769708 -226.98964)
		(mid 84.05114 -226.913885)
		(end 84.332572 -226.98964)
		(width 0.09525)
		(layer "In13.Cu")
		(net "M_B_CPU1_SA_DQS_DP<0>")
	)
	(arc
		(start 87.160862 -226.994466)
		(mid 87.313757 -227.039294)
		(end 87.471504 -227.016818)
		(width 0.09525)
		(layer "In13.Cu")
		(net "M_B_CPU1_SA_DQS_DP<0>")
	)
	(arc
		(start 82.460846 -226.994466)
		(mid 82.645878 -227.04038)
		(end 82.829654 -226.98964)
		(width 0.09525)
		(layer "In13.Cu")
		(net "M_B_CPU1_SA_DQS_DP<0>")
	)
	(arc
		(start 79.913734 -222.61449)
		(mid 79.955399 -222.786937)
		(end 80.071214 -222.921322)
		(width 0.09525)
		(layer "In13.Cu")
		(net "M_B_CPU1_SA_DQS_DP<0>")
	)
	(arc
		(start 79.671926 -222.152464)
		(mid 79.849612 -222.353756)
		(end 79.913734 -222.61449)
		(width 0.09525)
		(layer "In13.Cu")
		(net "M_B_CPU1_SA_DQS_DP<0>")
	)
	(arc
		(start 86.212426 -226.98964)
		(mid 86.396201 -227.040412)
		(end 86.581234 -226.994466)
		(width 0.09525)
		(layer "In13.Cu")
		(net "M_B_CPU1_SA_DQS_DP<0>")
	)
	(arc
		(start 79.442818 -221.804484)
		(mid 79.484417 -221.976863)
		(end 79.600044 -222.111316)
		(width 0.09525)
		(layer "In13.Cu")
		(net "M_B_CPU1_SA_DQS_DP<0>")
	)
	(arc
		(start 81.55051 -225.391726)
		(mid 81.72896 -225.593196)
		(end 81.793334 -225.854514)
		(width 0.09525)
		(layer "In13.Cu")
		(net "M_B_CPU1_SA_DQS_DP<0>")
	)
	(arc
		(start 86.589616 -226.98964)
		(mid 86.871048 -226.913885)
		(end 87.15248 -226.98964)
		(width 0.09525)
		(layer "In13.Cu")
		(net "M_B_CPU1_SA_DQS_DP<0>")
	)
	(arc
		(start 85.649562 -226.98964)
		(mid 85.930994 -226.913885)
		(end 86.212426 -226.98964)
		(width 0.09525)
		(layer "In13.Cu")
		(net "M_B_CPU1_SA_DQS_DP<0>")
	)
	(arc
		(start 81.323434 -225.044508)
		(mid 81.365099 -225.216955)
		(end 81.480914 -225.35134)
		(width 0.09525)
		(layer "In13.Cu")
		(net "M_B_CPU1_SA_DQS_DP<0>")
	)
	(arc
		(start 85.272372 -226.98964)
		(mid 85.456147 -227.040412)
		(end 85.64118 -226.994466)
		(width 0.09525)
		(layer "In13.Cu")
		(net "M_B_CPU1_SA_DQS_DP<0>")
	)
	(arc
		(start 84.332572 -226.98964)
		(mid 84.52104 -227.040317)
		(end 84.709508 -226.98964)
		(width 0.09525)
		(layer "In13.Cu")
		(net "M_B_CPU1_SA_DQS_DP<0>")
	)
	(arc
		(start 81.08061 -224.58172)
		(mid 81.25906 -224.78319)
		(end 81.323434 -225.044508)
		(width 0.09525)
		(layer "In13.Cu")
		(net "M_B_CPU1_SA_DQS_DP<0>")
	)
	(arc
		(start 81.793334 -225.854514)
		(mid 81.834791 -226.026554)
		(end 81.950052 -226.160838)
		(width 0.09525)
		(layer "In13.Cu")
		(net "M_B_CPU1_SA_DQS_DP<0>")
	)
	(segment
		(start 89.218008 -247.180354)
		(end 88.751156 -246.914416)
		(width 0.12954)
		(layer "F.Cu")
		(net "M_B_CPU1_SA_DQS_DN<9>")
	)
	(segment
		(start 49.353724 -239.273842)
		(end 48.072548 -239.273842)
		(width 0.16002)
		(layer "In13.Cu")
		(net "M_B_CPU1_SA_DQS_DN<9>")
	)
	(segment
		(start 75.21321 -246.862346)
		(end 64.896746 -246.862346)
		(width 0.16002)
		(layer "In13.Cu")
		(net "M_B_CPU1_SA_DQS_DN<9>")
	)
	(segment
		(start 59.992514 -241.958114)
		(end 59.187588 -241.958114)
		(width 0.16002)
		(layer "In13.Cu")
		(net "M_B_CPU1_SA_DQS_DN<9>")
	)
	(segment
		(start 50.748692 -239.039146)
		(end 49.920652 -239.039146)
		(width 0.16002)
		(layer "In13.Cu")
		(net "M_B_CPU1_SA_DQS_DN<9>")
	)
	(segment
		(start 83.299554 -247.239536)
		(end 83.291172 -247.244362)
		(width 0.09525)
		(layer "In13.Cu")
		(net "M_B_CPU1_SA_DQS_DN<9>")
	)
	(segment
		(start 85.750908 -247.244362)
		(end 85.742526 -247.239536)
		(width 0.09525)
		(layer "In13.Cu")
		(net "M_B_CPU1_SA_DQS_DN<9>")
	)
	(segment
		(start 75.955906 -247.033796)
		(end 75.38466 -247.033796)
		(width 0.16002)
		(layer "In13.Cu")
		(net "M_B_CPU1_SA_DQS_DN<9>")
	)
	(segment
		(start 80.479646 -247.239536)
		(end 80.471264 -247.244362)
		(width 0.09525)
		(layer "In13.Cu")
		(net "M_B_CPU1_SA_DQS_DN<9>")
	)
	(segment
		(start 59.187588 -241.958114)
		(end 56.994298 -239.764824)
		(width 0.16002)
		(layer "In13.Cu")
		(net "M_B_CPU1_SA_DQS_DN<9>")
	)
	(segment
		(start 76.274422 -247.092724)
		(end 76.038456 -247.092724)
		(width 0.09525)
		(layer "In13.Cu")
		(net "M_B_CPU1_SA_DQS_DN<9>")
	)
	(segment
		(start 87.99957 -247.239536)
		(end 87.991188 -247.244362)
		(width 0.09525)
		(layer "In13.Cu")
		(net "M_B_CPU1_SA_DQS_DN<9>")
	)
	(segment
		(start 75.38466 -247.033796)
		(end 75.21321 -246.862346)
		(width 0.16002)
		(layer "In13.Cu")
		(net "M_B_CPU1_SA_DQS_DN<9>")
	)
	(segment
		(start 54.423056 -239.835182)
		(end 54.014624 -239.835182)
		(width 0.16002)
		(layer "In13.Cu")
		(net "M_B_CPU1_SA_DQS_DN<9>")
	)
	(segment
		(start 88.90508 -247.179846)
		(end 88.881712 -247.266714)
		(width 0.09525)
		(layer "In13.Cu")
		(net "M_B_CPU1_SA_DQS_DN<9>")
	)
	(segment
		(start 78.614016 -247.2309)
		(end 78.599284 -247.239536)
		(width 0.09525)
		(layer "In13.Cu")
		(net "M_B_CPU1_SA_DQS_DN<9>")
	)
	(segment
		(start 54.014624 -239.835182)
		(end 52.983638 -239.408208)
		(width 0.16002)
		(layer "In13.Cu")
		(net "M_B_CPU1_SA_DQS_DN<9>")
	)
	(segment
		(start 51.639724 -239.408208)
		(end 50.748692 -239.039146)
		(width 0.16002)
		(layer "In13.Cu")
		(net "M_B_CPU1_SA_DQS_DN<9>")
	)
	(segment
		(start 81.050892 -247.244362)
		(end 81.04251 -247.239536)
		(width 0.09525)
		(layer "In13.Cu")
		(net "M_B_CPU1_SA_DQS_DN<9>")
	)
	(segment
		(start 77.711046 -247.16359)
		(end 77.47635 -247.398286)
		(width 0.09525)
		(layer "In13.Cu")
		(net "M_B_CPU1_SA_DQS_DN<9>")
	)
	(segment
		(start 84.239608 -247.239536)
		(end 84.231226 -247.244362)
		(width 0.09525)
		(layer "In13.Cu")
		(net "M_B_CPU1_SA_DQS_DN<9>")
	)
	(segment
		(start 84.810854 -247.244362)
		(end 84.802472 -247.239536)
		(width 0.09525)
		(layer "In13.Cu")
		(net "M_B_CPU1_SA_DQS_DN<9>")
	)
	(segment
		(start 64.896746 -246.862346)
		(end 59.992514 -241.958114)
		(width 0.16002)
		(layer "In13.Cu")
		(net "M_B_CPU1_SA_DQS_DN<9>")
	)
	(segment
		(start 80.102456 -247.239536)
		(end 80.092042 -247.23344)
		(width 0.09525)
		(layer "In13.Cu")
		(net "M_B_CPU1_SA_DQS_DN<9>")
	)
	(segment
		(start 76.038456 -247.092724)
		(end 75.979528 -247.033796)
		(width 0.09525)
		(layer "In13.Cu")
		(net "M_B_CPU1_SA_DQS_DN<9>")
	)
	(segment
		(start 55.483506 -239.396016)
		(end 54.423056 -239.835182)
		(width 0.16002)
		(layer "In13.Cu")
		(net "M_B_CPU1_SA_DQS_DN<9>")
	)
	(segment
		(start 75.979528 -247.033796)
		(end 75.955906 -247.033796)
		(width 0.09525)
		(layer "In13.Cu")
		(net "M_B_CPU1_SA_DQS_DN<9>")
	)
	(segment
		(start 76.579984 -247.398286)
		(end 76.274422 -247.092724)
		(width 0.09525)
		(layer "In13.Cu")
		(net "M_B_CPU1_SA_DQS_DN<9>")
	)
	(segment
		(start 77.47635 -247.398286)
		(end 76.579984 -247.398286)
		(width 0.09525)
		(layer "In13.Cu")
		(net "M_B_CPU1_SA_DQS_DN<9>")
	)
	(segment
		(start 77.940154 -247.16359)
		(end 77.711046 -247.16359)
		(width 0.09525)
		(layer "In13.Cu")
		(net "M_B_CPU1_SA_DQS_DN<9>")
	)
	(segment
		(start 88.751156 -246.914416)
		(end 88.90508 -247.179846)
		(width 0.09525)
		(layer "In13.Cu")
		(net "M_B_CPU1_SA_DQS_DN<9>")
	)
	(segment
		(start 79.170022 -247.244362)
		(end 79.16164 -247.239536)
		(width 0.09525)
		(layer "In13.Cu")
		(net "M_B_CPU1_SA_DQS_DN<9>")
	)
	(segment
		(start 56.103774 -239.396016)
		(end 55.483506 -239.396016)
		(width 0.16002)
		(layer "In13.Cu")
		(net "M_B_CPU1_SA_DQS_DN<9>")
	)
	(segment
		(start 56.994298 -239.764824)
		(end 56.103774 -239.396016)
		(width 0.16002)
		(layer "In13.Cu")
		(net "M_B_CPU1_SA_DQS_DN<9>")
	)
	(segment
		(start 48.072548 -239.273842)
		(end 47.784004 -238.985298)
		(width 0.16002)
		(layer "In13.Cu")
		(net "M_B_CPU1_SA_DQS_DN<9>")
	)
	(segment
		(start 49.920652 -239.039146)
		(end 49.353724 -239.273842)
		(width 0.16002)
		(layer "In13.Cu")
		(net "M_B_CPU1_SA_DQS_DN<9>")
	)
	(segment
		(start 52.983638 -239.408208)
		(end 51.639724 -239.408208)
		(width 0.16002)
		(layer "In13.Cu")
		(net "M_B_CPU1_SA_DQS_DN<9>")
	)
	(segment
		(start 78.599284 -247.239536)
		(end 78.584806 -247.247918)
		(width 0.09525)
		(layer "In13.Cu")
		(net "M_B_CPU1_SA_DQS_DN<9>")
	)
	(arc
		(start 88.562434 -247.239536)
		(mid 88.281002 -247.163781)
		(end 87.99957 -247.239536)
		(width 0.09525)
		(layer "In13.Cu")
		(net "M_B_CPU1_SA_DQS_DN<9>")
	)
	(arc
		(start 81.4197 -247.239536)
		(mid 81.235925 -247.290308)
		(end 81.050892 -247.244362)
		(width 0.09525)
		(layer "In13.Cu")
		(net "M_B_CPU1_SA_DQS_DN<9>")
	)
	(arc
		(start 86.68258 -247.239536)
		(mid 86.401148 -247.163781)
		(end 86.119716 -247.239536)
		(width 0.09525)
		(layer "In13.Cu")
		(net "M_B_CPU1_SA_DQS_DN<9>")
	)
	(arc
		(start 85.742526 -247.239536)
		(mid 85.461094 -247.163781)
		(end 85.179662 -247.239536)
		(width 0.09525)
		(layer "In13.Cu")
		(net "M_B_CPU1_SA_DQS_DN<9>")
	)
	(arc
		(start 83.291172 -247.244362)
		(mid 83.10614 -247.290276)
		(end 82.922364 -247.239536)
		(width 0.09525)
		(layer "In13.Cu")
		(net "M_B_CPU1_SA_DQS_DN<9>")
	)
	(arc
		(start 81.982564 -247.239536)
		(mid 81.701132 -247.163781)
		(end 81.4197 -247.239536)
		(width 0.09525)
		(layer "In13.Cu")
		(net "M_B_CPU1_SA_DQS_DN<9>")
	)
	(arc
		(start 79.539338 -247.239536)
		(mid 79.355309 -247.290435)
		(end 79.170022 -247.244362)
		(width 0.09525)
		(layer "In13.Cu")
		(net "M_B_CPU1_SA_DQS_DN<9>")
	)
	(arc
		(start 87.991188 -247.244362)
		(mid 87.806156 -247.290276)
		(end 87.62238 -247.239536)
		(width 0.09525)
		(layer "In13.Cu")
		(net "M_B_CPU1_SA_DQS_DN<9>")
	)
	(arc
		(start 84.231226 -247.244362)
		(mid 84.046194 -247.290276)
		(end 83.862418 -247.239536)
		(width 0.09525)
		(layer "In13.Cu")
		(net "M_B_CPU1_SA_DQS_DN<9>")
	)
	(arc
		(start 87.62238 -247.239536)
		(mid 87.340948 -247.163781)
		(end 87.059516 -247.239536)
		(width 0.09525)
		(layer "In13.Cu")
		(net "M_B_CPU1_SA_DQS_DN<9>")
	)
	(arc
		(start 82.922364 -247.239536)
		(mid 82.640932 -247.163781)
		(end 82.3595 -247.239536)
		(width 0.09525)
		(layer "In13.Cu")
		(net "M_B_CPU1_SA_DQS_DN<9>")
	)
	(arc
		(start 84.802472 -247.239536)
		(mid 84.52104 -247.163781)
		(end 84.239608 -247.239536)
		(width 0.09525)
		(layer "In13.Cu")
		(net "M_B_CPU1_SA_DQS_DN<9>")
	)
	(arc
		(start 85.179662 -247.239536)
		(mid 84.995887 -247.290308)
		(end 84.810854 -247.244362)
		(width 0.09525)
		(layer "In13.Cu")
		(net "M_B_CPU1_SA_DQS_DN<9>")
	)
	(arc
		(start 78.584806 -247.247918)
		(mid 78.402374 -247.290358)
		(end 78.222094 -247.239536)
		(width 0.09525)
		(layer "In13.Cu")
		(net "M_B_CPU1_SA_DQS_DN<9>")
	)
	(arc
		(start 87.059516 -247.239536)
		(mid 86.871048 -247.290213)
		(end 86.68258 -247.239536)
		(width 0.09525)
		(layer "In13.Cu")
		(net "M_B_CPU1_SA_DQS_DN<9>")
	)
	(arc
		(start 82.3595 -247.239536)
		(mid 82.171032 -247.290213)
		(end 81.982564 -247.239536)
		(width 0.09525)
		(layer "In13.Cu")
		(net "M_B_CPU1_SA_DQS_DN<9>")
	)
	(arc
		(start 80.471264 -247.244362)
		(mid 80.286232 -247.290276)
		(end 80.102456 -247.239536)
		(width 0.09525)
		(layer "In13.Cu")
		(net "M_B_CPU1_SA_DQS_DN<9>")
	)
	(arc
		(start 88.881712 -247.266714)
		(mid 88.71903 -247.288846)
		(end 88.562434 -247.239536)
		(width 0.09525)
		(layer "In13.Cu")
		(net "M_B_CPU1_SA_DQS_DN<9>")
	)
	(arc
		(start 80.092042 -247.23344)
		(mid 79.81488 -247.16364)
		(end 79.539338 -247.239536)
		(width 0.09525)
		(layer "In13.Cu")
		(net "M_B_CPU1_SA_DQS_DN<9>")
	)
	(arc
		(start 83.862418 -247.239536)
		(mid 83.580986 -247.163781)
		(end 83.299554 -247.239536)
		(width 0.09525)
		(layer "In13.Cu")
		(net "M_B_CPU1_SA_DQS_DN<9>")
	)
	(arc
		(start 78.222094 -247.239536)
		(mid 78.086148 -247.182912)
		(end 77.940154 -247.16359)
		(width 0.09525)
		(layer "In13.Cu")
		(net "M_B_CPU1_SA_DQS_DN<9>")
	)
	(arc
		(start 81.04251 -247.239536)
		(mid 80.761078 -247.163781)
		(end 80.479646 -247.239536)
		(width 0.09525)
		(layer "In13.Cu")
		(net "M_B_CPU1_SA_DQS_DN<9>")
	)
	(arc
		(start 86.119716 -247.239536)
		(mid 85.935941 -247.290308)
		(end 85.750908 -247.244362)
		(width 0.09525)
		(layer "In13.Cu")
		(net "M_B_CPU1_SA_DQS_DN<9>")
	)
	(arc
		(start 79.16164 -247.239536)
		(mid 78.888966 -247.163849)
		(end 78.614016 -247.2309)
		(width 0.09525)
		(layer "In13.Cu")
		(net "M_B_CPU1_SA_DQS_DN<9>")
	)
	(segment
		(start 89.218008 -242.320318)
		(end 88.751156 -242.05438)
		(width 0.12954)
		(layer "F.Cu")
		(net "M_B_CPU1_SA_DQS_DN<8>")
	)
	(segment
		(start 49.96434 -229.940358)
		(end 48.089058 -229.940358)
		(width 0.16002)
		(layer "In13.Cu")
		(net "M_B_CPU1_SA_DQS_DN<8>")
	)
	(segment
		(start 54.401974 -230.877618)
		(end 53.58257 -230.058214)
		(width 0.16002)
		(layer "In13.Cu")
		(net "M_B_CPU1_SA_DQS_DN<8>")
	)
	(segment
		(start 59.993784 -230.908352)
		(end 57.707276 -230.908352)
		(width 0.16002)
		(layer "In13.Cu")
		(net "M_B_CPU1_SA_DQS_DN<8>")
	)
	(segment
		(start 48.089058 -229.940358)
		(end 47.784004 -229.635304)
		(width 0.16002)
		(layer "In13.Cu")
		(net "M_B_CPU1_SA_DQS_DN<8>")
	)
	(segment
		(start 78.599284 -242.3795)
		(end 78.584806 -242.387882)
		(width 0.09525)
		(layer "In13.Cu")
		(net "M_B_CPU1_SA_DQS_DN<8>")
	)
	(segment
		(start 56.093614 -230.877618)
		(end 54.401974 -230.877618)
		(width 0.16002)
		(layer "In13.Cu")
		(net "M_B_CPU1_SA_DQS_DN<8>")
	)
	(segment
		(start 77.748638 -242.303554)
		(end 77.42047 -241.975386)
		(width 0.09525)
		(layer "In13.Cu")
		(net "M_B_CPU1_SA_DQS_DN<8>")
	)
	(segment
		(start 70.3326 -241.247168)
		(end 59.993784 -230.908352)
		(width 0.16002)
		(layer "In13.Cu")
		(net "M_B_CPU1_SA_DQS_DN<8>")
	)
	(segment
		(start 88.751156 -242.05438)
		(end 88.90508 -242.31981)
		(width 0.09525)
		(layer "In13.Cu")
		(net "M_B_CPU1_SA_DQS_DN<8>")
	)
	(segment
		(start 80.479646 -242.3795)
		(end 80.471264 -242.384326)
		(width 0.09525)
		(layer "In13.Cu")
		(net "M_B_CPU1_SA_DQS_DN<8>")
	)
	(segment
		(start 84.810854 -242.384326)
		(end 84.802472 -242.3795)
		(width 0.09525)
		(layer "In13.Cu")
		(net "M_B_CPU1_SA_DQS_DN<8>")
	)
	(segment
		(start 75.89774 -241.247168)
		(end 70.3326 -241.247168)
		(width 0.16002)
		(layer "In13.Cu")
		(net "M_B_CPU1_SA_DQS_DN<8>")
	)
	(segment
		(start 84.239608 -242.3795)
		(end 84.231226 -242.384326)
		(width 0.09525)
		(layer "In13.Cu")
		(net "M_B_CPU1_SA_DQS_DN<8>")
	)
	(segment
		(start 57.37225 -230.573326)
		(end 56.397906 -230.573326)
		(width 0.16002)
		(layer "In13.Cu")
		(net "M_B_CPU1_SA_DQS_DN<8>")
	)
	(segment
		(start 76.21016 -241.306096)
		(end 75.98029 -241.306096)
		(width 0.09525)
		(layer "In13.Cu")
		(net "M_B_CPU1_SA_DQS_DN<8>")
	)
	(segment
		(start 56.397906 -230.573326)
		(end 56.093614 -230.877618)
		(width 0.16002)
		(layer "In13.Cu")
		(net "M_B_CPU1_SA_DQS_DN<8>")
	)
	(segment
		(start 78.620112 -242.367308)
		(end 78.599284 -242.3795)
		(width 0.09525)
		(layer "In13.Cu")
		(net "M_B_CPU1_SA_DQS_DN<8>")
	)
	(segment
		(start 51.149758 -230.058214)
		(end 50.780696 -229.689152)
		(width 0.16002)
		(layer "In13.Cu")
		(net "M_B_CPU1_SA_DQS_DN<8>")
	)
	(segment
		(start 81.050892 -242.384326)
		(end 81.04251 -242.3795)
		(width 0.09525)
		(layer "In13.Cu")
		(net "M_B_CPU1_SA_DQS_DN<8>")
	)
	(segment
		(start 50.780696 -229.689152)
		(end 50.215546 -229.689152)
		(width 0.16002)
		(layer "In13.Cu")
		(net "M_B_CPU1_SA_DQS_DN<8>")
	)
	(segment
		(start 77.940154 -242.303554)
		(end 77.748638 -242.303554)
		(width 0.09525)
		(layer "In13.Cu")
		(net "M_B_CPU1_SA_DQS_DN<8>")
	)
	(segment
		(start 88.90508 -242.31981)
		(end 88.881712 -242.406678)
		(width 0.09525)
		(layer "In13.Cu")
		(net "M_B_CPU1_SA_DQS_DN<8>")
	)
	(segment
		(start 76.42606 -241.521996)
		(end 76.21016 -241.306096)
		(width 0.09525)
		(layer "In13.Cu")
		(net "M_B_CPU1_SA_DQS_DN<8>")
	)
	(segment
		(start 53.58257 -230.058214)
		(end 51.149758 -230.058214)
		(width 0.16002)
		(layer "In13.Cu")
		(net "M_B_CPU1_SA_DQS_DN<8>")
	)
	(segment
		(start 87.99957 -242.3795)
		(end 87.991188 -242.384326)
		(width 0.09525)
		(layer "In13.Cu")
		(net "M_B_CPU1_SA_DQS_DN<8>")
	)
	(segment
		(start 75.98029 -241.306096)
		(end 75.921362 -241.247168)
		(width 0.09525)
		(layer "In13.Cu")
		(net "M_B_CPU1_SA_DQS_DN<8>")
	)
	(segment
		(start 50.215546 -229.689152)
		(end 49.96434 -229.940358)
		(width 0.16002)
		(layer "In13.Cu")
		(net "M_B_CPU1_SA_DQS_DN<8>")
	)
	(segment
		(start 75.921362 -241.247168)
		(end 75.89774 -241.247168)
		(width 0.09525)
		(layer "In13.Cu")
		(net "M_B_CPU1_SA_DQS_DN<8>")
	)
	(segment
		(start 79.539592 -242.3795)
		(end 79.527654 -242.386358)
		(width 0.09525)
		(layer "In13.Cu")
		(net "M_B_CPU1_SA_DQS_DN<8>")
	)
	(segment
		(start 83.299554 -242.3795)
		(end 83.291172 -242.384326)
		(width 0.09525)
		(layer "In13.Cu")
		(net "M_B_CPU1_SA_DQS_DN<8>")
	)
	(segment
		(start 76.42606 -241.647726)
		(end 76.42606 -241.521996)
		(width 0.09525)
		(layer "In13.Cu")
		(net "M_B_CPU1_SA_DQS_DN<8>")
	)
	(segment
		(start 57.707276 -230.908352)
		(end 57.37225 -230.573326)
		(width 0.16002)
		(layer "In13.Cu")
		(net "M_B_CPU1_SA_DQS_DN<8>")
	)
	(segment
		(start 77.42047 -241.975386)
		(end 76.75372 -241.975386)
		(width 0.09525)
		(layer "In13.Cu")
		(net "M_B_CPU1_SA_DQS_DN<8>")
	)
	(segment
		(start 85.750908 -242.384326)
		(end 85.742526 -242.3795)
		(width 0.09525)
		(layer "In13.Cu")
		(net "M_B_CPU1_SA_DQS_DN<8>")
	)
	(segment
		(start 76.75372 -241.975386)
		(end 76.42606 -241.647726)
		(width 0.09525)
		(layer "In13.Cu")
		(net "M_B_CPU1_SA_DQS_DN<8>")
	)
	(arc
		(start 84.231226 -242.384326)
		(mid 84.046194 -242.43024)
		(end 83.862418 -242.3795)
		(width 0.09525)
		(layer "In13.Cu")
		(net "M_B_CPU1_SA_DQS_DN<8>")
	)
	(arc
		(start 84.802472 -242.3795)
		(mid 84.52104 -242.303745)
		(end 84.239608 -242.3795)
		(width 0.09525)
		(layer "In13.Cu")
		(net "M_B_CPU1_SA_DQS_DN<8>")
	)
	(arc
		(start 85.179662 -242.3795)
		(mid 84.995887 -242.430272)
		(end 84.810854 -242.384326)
		(width 0.09525)
		(layer "In13.Cu")
		(net "M_B_CPU1_SA_DQS_DN<8>")
	)
	(arc
		(start 79.162148 -242.3795)
		(mid 78.892715 -242.303629)
		(end 78.620112 -242.367308)
		(width 0.09525)
		(layer "In13.Cu")
		(net "M_B_CPU1_SA_DQS_DN<8>")
	)
	(arc
		(start 79.527654 -242.386358)
		(mid 79.344019 -242.430308)
		(end 79.162148 -242.3795)
		(width 0.09525)
		(layer "In13.Cu")
		(net "M_B_CPU1_SA_DQS_DN<8>")
	)
	(arc
		(start 81.4197 -242.3795)
		(mid 81.235925 -242.430272)
		(end 81.050892 -242.384326)
		(width 0.09525)
		(layer "In13.Cu")
		(net "M_B_CPU1_SA_DQS_DN<8>")
	)
	(arc
		(start 81.04251 -242.3795)
		(mid 80.761078 -242.303745)
		(end 80.479646 -242.3795)
		(width 0.09525)
		(layer "In13.Cu")
		(net "M_B_CPU1_SA_DQS_DN<8>")
	)
	(arc
		(start 78.222094 -242.3795)
		(mid 78.086148 -242.322876)
		(end 77.940154 -242.303554)
		(width 0.09525)
		(layer "In13.Cu")
		(net "M_B_CPU1_SA_DQS_DN<8>")
	)
	(arc
		(start 82.3595 -242.3795)
		(mid 82.171032 -242.430177)
		(end 81.982564 -242.3795)
		(width 0.09525)
		(layer "In13.Cu")
		(net "M_B_CPU1_SA_DQS_DN<8>")
	)
	(arc
		(start 82.922364 -242.3795)
		(mid 82.640932 -242.303745)
		(end 82.3595 -242.3795)
		(width 0.09525)
		(layer "In13.Cu")
		(net "M_B_CPU1_SA_DQS_DN<8>")
	)
	(arc
		(start 86.68258 -242.3795)
		(mid 86.401148 -242.303745)
		(end 86.119716 -242.3795)
		(width 0.09525)
		(layer "In13.Cu")
		(net "M_B_CPU1_SA_DQS_DN<8>")
	)
	(arc
		(start 87.059516 -242.3795)
		(mid 86.871048 -242.430177)
		(end 86.68258 -242.3795)
		(width 0.09525)
		(layer "In13.Cu")
		(net "M_B_CPU1_SA_DQS_DN<8>")
	)
	(arc
		(start 86.119716 -242.3795)
		(mid 85.935941 -242.430272)
		(end 85.750908 -242.384326)
		(width 0.09525)
		(layer "In13.Cu")
		(net "M_B_CPU1_SA_DQS_DN<8>")
	)
	(arc
		(start 81.982564 -242.3795)
		(mid 81.701132 -242.303745)
		(end 81.4197 -242.3795)
		(width 0.09525)
		(layer "In13.Cu")
		(net "M_B_CPU1_SA_DQS_DN<8>")
	)
	(arc
		(start 80.471264 -242.384326)
		(mid 80.286232 -242.43024)
		(end 80.102456 -242.3795)
		(width 0.09525)
		(layer "In13.Cu")
		(net "M_B_CPU1_SA_DQS_DN<8>")
	)
	(arc
		(start 88.881712 -242.406678)
		(mid 88.71903 -242.42881)
		(end 88.562434 -242.3795)
		(width 0.09525)
		(layer "In13.Cu")
		(net "M_B_CPU1_SA_DQS_DN<8>")
	)
	(arc
		(start 87.991188 -242.384326)
		(mid 87.806156 -242.43024)
		(end 87.62238 -242.3795)
		(width 0.09525)
		(layer "In13.Cu")
		(net "M_B_CPU1_SA_DQS_DN<8>")
	)
	(arc
		(start 85.742526 -242.3795)
		(mid 85.461094 -242.303745)
		(end 85.179662 -242.3795)
		(width 0.09525)
		(layer "In13.Cu")
		(net "M_B_CPU1_SA_DQS_DN<8>")
	)
	(arc
		(start 83.862418 -242.3795)
		(mid 83.580986 -242.303745)
		(end 83.299554 -242.3795)
		(width 0.09525)
		(layer "In13.Cu")
		(net "M_B_CPU1_SA_DQS_DN<8>")
	)
	(arc
		(start 88.562434 -242.3795)
		(mid 88.281002 -242.303745)
		(end 87.99957 -242.3795)
		(width 0.09525)
		(layer "In13.Cu")
		(net "M_B_CPU1_SA_DQS_DN<8>")
	)
	(arc
		(start 78.584806 -242.387882)
		(mid 78.402374 -242.430322)
		(end 78.222094 -242.3795)
		(width 0.09525)
		(layer "In13.Cu")
		(net "M_B_CPU1_SA_DQS_DN<8>")
	)
	(arc
		(start 83.291172 -242.384326)
		(mid 83.10614 -242.43024)
		(end 82.922364 -242.3795)
		(width 0.09525)
		(layer "In13.Cu")
		(net "M_B_CPU1_SA_DQS_DN<8>")
	)
	(arc
		(start 80.102456 -242.3795)
		(mid 79.821024 -242.303745)
		(end 79.539592 -242.3795)
		(width 0.09525)
		(layer "In13.Cu")
		(net "M_B_CPU1_SA_DQS_DN<8>")
	)
	(arc
		(start 87.62238 -242.3795)
		(mid 87.340948 -242.303745)
		(end 87.059516 -242.3795)
		(width 0.09525)
		(layer "In13.Cu")
		(net "M_B_CPU1_SA_DQS_DN<8>")
	)
	(segment
		(start 89.218008 -237.460282)
		(end 88.751156 -237.194344)
		(width 0.12954)
		(layer "F.Cu")
		(net "M_B_CPU1_SA_DQS_DN<7>")
	)
	(segment
		(start 77.39253 -236.42574)
		(end 77.015086 -236.048296)
		(width 0.09525)
		(layer "In13.Cu")
		(net "M_B_CPU1_SA_DQS_DN<7>")
	)
	(segment
		(start 48.795686 -220.561662)
		(end 48.060356 -220.561662)
		(width 0.16002)
		(layer "In13.Cu")
		(net "M_B_CPU1_SA_DQS_DN<7>")
	)
	(segment
		(start 76.038456 -235.688124)
		(end 75.979528 -235.629196)
		(width 0.09525)
		(layer "In13.Cu")
		(net "M_B_CPU1_SA_DQS_DN<7>")
	)
	(segment
		(start 73.80224 -235.629196)
		(end 60.76823 -222.595186)
		(width 0.16002)
		(layer "In13.Cu")
		(net "M_B_CPU1_SA_DQS_DN<7>")
	)
	(segment
		(start 78.246478 -237.571534)
		(end 77.39253 -236.717586)
		(width 0.09525)
		(layer "In13.Cu")
		(net "M_B_CPU1_SA_DQS_DN<7>")
	)
	(segment
		(start 60.76823 -222.595186)
		(end 60.76823 -222.238824)
		(width 0.16002)
		(layer "In13.Cu")
		(net "M_B_CPU1_SA_DQS_DN<7>")
	)
	(segment
		(start 76.250038 -235.688124)
		(end 76.038456 -235.688124)
		(width 0.09525)
		(layer "In13.Cu")
		(net "M_B_CPU1_SA_DQS_DN<7>")
	)
	(segment
		(start 48.060356 -220.561662)
		(end 47.784004 -220.28531)
		(width 0.16002)
		(layer "In13.Cu")
		(net "M_B_CPU1_SA_DQS_DN<7>")
	)
	(segment
		(start 87.99957 -237.519464)
		(end 87.991188 -237.52429)
		(width 0.09525)
		(layer "In13.Cu")
		(net "M_B_CPU1_SA_DQS_DN<7>")
	)
	(segment
		(start 57.67197 -221.558104)
		(end 57.337198 -221.223332)
		(width 0.16002)
		(layer "In13.Cu")
		(net "M_B_CPU1_SA_DQS_DN<7>")
	)
	(segment
		(start 81.050892 -237.52429)
		(end 81.04251 -237.519464)
		(width 0.09525)
		(layer "In13.Cu")
		(net "M_B_CPU1_SA_DQS_DN<7>")
	)
	(segment
		(start 51.149758 -220.70822)
		(end 50.780696 -220.339158)
		(width 0.16002)
		(layer "In13.Cu")
		(net "M_B_CPU1_SA_DQS_DN<7>")
	)
	(segment
		(start 84.810854 -237.52429)
		(end 84.802472 -237.519464)
		(width 0.09525)
		(layer "In13.Cu")
		(net "M_B_CPU1_SA_DQS_DN<7>")
	)
	(segment
		(start 83.299554 -237.519464)
		(end 83.291172 -237.52429)
		(width 0.09525)
		(layer "In13.Cu")
		(net "M_B_CPU1_SA_DQS_DN<7>")
	)
	(segment
		(start 79.16545 -237.519464)
		(end 79.141574 -237.505494)
		(width 0.09525)
		(layer "In13.Cu")
		(net "M_B_CPU1_SA_DQS_DN<7>")
	)
	(segment
		(start 88.751156 -237.194344)
		(end 88.90508 -237.459774)
		(width 0.09525)
		(layer "In13.Cu")
		(net "M_B_CPU1_SA_DQS_DN<7>")
	)
	(segment
		(start 56.397906 -221.223332)
		(end 56.093614 -221.527624)
		(width 0.16002)
		(layer "In13.Cu")
		(net "M_B_CPU1_SA_DQS_DN<7>")
	)
	(segment
		(start 49.01819 -220.339158)
		(end 48.795686 -220.561662)
		(width 0.16002)
		(layer "In13.Cu")
		(net "M_B_CPU1_SA_DQS_DN<7>")
	)
	(segment
		(start 75.979528 -235.629196)
		(end 75.955906 -235.629196)
		(width 0.09525)
		(layer "In13.Cu")
		(net "M_B_CPU1_SA_DQS_DN<7>")
	)
	(segment
		(start 77.39253 -236.717586)
		(end 77.39253 -236.42574)
		(width 0.09525)
		(layer "In13.Cu")
		(net "M_B_CPU1_SA_DQS_DN<7>")
	)
	(segment
		(start 54.381146 -221.527624)
		(end 53.561742 -220.70822)
		(width 0.16002)
		(layer "In13.Cu")
		(net "M_B_CPU1_SA_DQS_DN<7>")
	)
	(segment
		(start 57.337198 -221.223332)
		(end 56.397906 -221.223332)
		(width 0.16002)
		(layer "In13.Cu")
		(net "M_B_CPU1_SA_DQS_DN<7>")
	)
	(segment
		(start 79.54137 -237.519464)
		(end 79.524606 -237.529116)
		(width 0.09525)
		(layer "In13.Cu")
		(net "M_B_CPU1_SA_DQS_DN<7>")
	)
	(segment
		(start 79.568802 -237.503462)
		(end 79.54137 -237.519464)
		(width 0.09525)
		(layer "In13.Cu")
		(net "M_B_CPU1_SA_DQS_DN<7>")
	)
	(segment
		(start 75.955906 -235.629196)
		(end 73.80224 -235.629196)
		(width 0.16002)
		(layer "In13.Cu")
		(net "M_B_CPU1_SA_DQS_DN<7>")
	)
	(segment
		(start 56.093614 -221.527624)
		(end 54.381146 -221.527624)
		(width 0.16002)
		(layer "In13.Cu")
		(net "M_B_CPU1_SA_DQS_DN<7>")
	)
	(segment
		(start 88.90508 -237.459774)
		(end 88.881712 -237.546642)
		(width 0.09525)
		(layer "In13.Cu")
		(net "M_B_CPU1_SA_DQS_DN<7>")
	)
	(segment
		(start 60.76823 -222.238824)
		(end 60.08751 -221.558104)
		(width 0.16002)
		(layer "In13.Cu")
		(net "M_B_CPU1_SA_DQS_DN<7>")
	)
	(segment
		(start 76.61021 -236.048296)
		(end 76.250038 -235.688124)
		(width 0.09525)
		(layer "In13.Cu")
		(net "M_B_CPU1_SA_DQS_DN<7>")
	)
	(segment
		(start 77.015086 -236.048296)
		(end 76.61021 -236.048296)
		(width 0.09525)
		(layer "In13.Cu")
		(net "M_B_CPU1_SA_DQS_DN<7>")
	)
	(segment
		(start 85.750908 -237.52429)
		(end 85.742526 -237.519464)
		(width 0.09525)
		(layer "In13.Cu")
		(net "M_B_CPU1_SA_DQS_DN<7>")
	)
	(segment
		(start 78.41107 -237.571534)
		(end 78.246478 -237.571534)
		(width 0.09525)
		(layer "In13.Cu")
		(net "M_B_CPU1_SA_DQS_DN<7>")
	)
	(segment
		(start 84.239608 -237.519464)
		(end 84.231226 -237.52429)
		(width 0.09525)
		(layer "In13.Cu")
		(net "M_B_CPU1_SA_DQS_DN<7>")
	)
	(segment
		(start 80.479646 -237.519464)
		(end 80.471264 -237.52429)
		(width 0.09525)
		(layer "In13.Cu")
		(net "M_B_CPU1_SA_DQS_DN<7>")
	)
	(segment
		(start 53.561742 -220.70822)
		(end 51.149758 -220.70822)
		(width 0.16002)
		(layer "In13.Cu")
		(net "M_B_CPU1_SA_DQS_DN<7>")
	)
	(segment
		(start 50.780696 -220.339158)
		(end 49.01819 -220.339158)
		(width 0.16002)
		(layer "In13.Cu")
		(net "M_B_CPU1_SA_DQS_DN<7>")
	)
	(segment
		(start 60.08751 -221.558104)
		(end 57.67197 -221.558104)
		(width 0.16002)
		(layer "In13.Cu")
		(net "M_B_CPU1_SA_DQS_DN<7>")
	)
	(arc
		(start 86.68258 -237.519464)
		(mid 86.401148 -237.443709)
		(end 86.119716 -237.519464)
		(width 0.09525)
		(layer "In13.Cu")
		(net "M_B_CPU1_SA_DQS_DN<7>")
	)
	(arc
		(start 82.3595 -237.519464)
		(mid 82.171032 -237.570141)
		(end 81.982564 -237.519464)
		(width 0.09525)
		(layer "In13.Cu")
		(net "M_B_CPU1_SA_DQS_DN<7>")
	)
	(arc
		(start 80.471264 -237.52429)
		(mid 80.286232 -237.570204)
		(end 80.102456 -237.519464)
		(width 0.09525)
		(layer "In13.Cu")
		(net "M_B_CPU1_SA_DQS_DN<7>")
	)
	(arc
		(start 87.059516 -237.519464)
		(mid 86.871048 -237.570141)
		(end 86.68258 -237.519464)
		(width 0.09525)
		(layer "In13.Cu")
		(net "M_B_CPU1_SA_DQS_DN<7>")
	)
	(arc
		(start 81.4197 -237.519464)
		(mid 81.235925 -237.570236)
		(end 81.050892 -237.52429)
		(width 0.09525)
		(layer "In13.Cu")
		(net "M_B_CPU1_SA_DQS_DN<7>")
	)
	(arc
		(start 87.991188 -237.52429)
		(mid 87.806156 -237.570204)
		(end 87.62238 -237.519464)
		(width 0.09525)
		(layer "In13.Cu")
		(net "M_B_CPU1_SA_DQS_DN<7>")
	)
	(arc
		(start 85.742526 -237.519464)
		(mid 85.461094 -237.443709)
		(end 85.179662 -237.519464)
		(width 0.09525)
		(layer "In13.Cu")
		(net "M_B_CPU1_SA_DQS_DN<7>")
	)
	(arc
		(start 83.862418 -237.519464)
		(mid 83.580986 -237.443709)
		(end 83.299554 -237.519464)
		(width 0.09525)
		(layer "In13.Cu")
		(net "M_B_CPU1_SA_DQS_DN<7>")
	)
	(arc
		(start 84.802472 -237.519464)
		(mid 84.52104 -237.443709)
		(end 84.239608 -237.519464)
		(width 0.09525)
		(layer "In13.Cu")
		(net "M_B_CPU1_SA_DQS_DN<7>")
	)
	(arc
		(start 78.600808 -237.519718)
		(mid 78.509379 -237.558225)
		(end 78.41107 -237.571534)
		(width 0.09525)
		(layer "In13.Cu")
		(net "M_B_CPU1_SA_DQS_DN<7>")
	)
	(arc
		(start 81.982564 -237.519464)
		(mid 81.701132 -237.443709)
		(end 81.4197 -237.519464)
		(width 0.09525)
		(layer "In13.Cu")
		(net "M_B_CPU1_SA_DQS_DN<7>")
	)
	(arc
		(start 85.179662 -237.519464)
		(mid 84.995887 -237.570236)
		(end 84.810854 -237.52429)
		(width 0.09525)
		(layer "In13.Cu")
		(net "M_B_CPU1_SA_DQS_DN<7>")
	)
	(arc
		(start 83.291172 -237.52429)
		(mid 83.10614 -237.570204)
		(end 82.922364 -237.519464)
		(width 0.09525)
		(layer "In13.Cu")
		(net "M_B_CPU1_SA_DQS_DN<7>")
	)
	(arc
		(start 88.881712 -237.546642)
		(mid 88.71903 -237.568774)
		(end 88.562434 -237.519464)
		(width 0.09525)
		(layer "In13.Cu")
		(net "M_B_CPU1_SA_DQS_DN<7>")
	)
	(arc
		(start 87.62238 -237.519464)
		(mid 87.340948 -237.443709)
		(end 87.059516 -237.519464)
		(width 0.09525)
		(layer "In13.Cu")
		(net "M_B_CPU1_SA_DQS_DN<7>")
	)
	(arc
		(start 81.04251 -237.519464)
		(mid 80.761078 -237.443709)
		(end 80.479646 -237.519464)
		(width 0.09525)
		(layer "In13.Cu")
		(net "M_B_CPU1_SA_DQS_DN<7>")
	)
	(arc
		(start 88.562434 -237.519464)
		(mid 88.281002 -237.443709)
		(end 87.99957 -237.519464)
		(width 0.09525)
		(layer "In13.Cu")
		(net "M_B_CPU1_SA_DQS_DN<7>")
	)
	(arc
		(start 79.524606 -237.529116)
		(mid 79.343803 -237.569983)
		(end 79.16545 -237.519464)
		(width 0.09525)
		(layer "In13.Cu")
		(net "M_B_CPU1_SA_DQS_DN<7>")
	)
	(arc
		(start 86.119716 -237.519464)
		(mid 85.935941 -237.570236)
		(end 85.750908 -237.52429)
		(width 0.09525)
		(layer "In13.Cu")
		(net "M_B_CPU1_SA_DQS_DN<7>")
	)
	(arc
		(start 84.231226 -237.52429)
		(mid 84.046194 -237.570204)
		(end 83.862418 -237.519464)
		(width 0.09525)
		(layer "In13.Cu")
		(net "M_B_CPU1_SA_DQS_DN<7>")
	)
	(arc
		(start 82.922364 -237.519464)
		(mid 82.640932 -237.443709)
		(end 82.3595 -237.519464)
		(width 0.09525)
		(layer "In13.Cu")
		(net "M_B_CPU1_SA_DQS_DN<7>")
	)
	(arc
		(start 80.102456 -237.519464)
		(mid 79.837647 -237.443835)
		(end 79.568802 -237.503462)
		(width 0.09525)
		(layer "In13.Cu")
		(net "M_B_CPU1_SA_DQS_DN<7>")
	)
	(arc
		(start 79.141574 -237.505494)
		(mid 78.86935 -237.443122)
		(end 78.600808 -237.519718)
		(width 0.09525)
		(layer "In13.Cu")
		(net "M_B_CPU1_SA_DQS_DN<7>")
	)
	(segment
		(start 89.218008 -232.600246)
		(end 88.751156 -232.334308)
		(width 0.12954)
		(layer "F.Cu")
		(net "M_B_CPU1_SA_DQS_DN<6>")
	)
	(segment
		(start 72.93991 -226.712526)
		(end 76.357988 -230.130604)
		(width 0.16002)
		(layer "In13.Cu")
		(net "M_B_CPU1_SA_DQS_DN<6>")
	)
	(segment
		(start 79.49438 -232.583736)
		(end 79.821024 -232.583736)
		(width 0.09525)
		(layer "In13.Cu")
		(net "M_B_CPU1_SA_DQS_DN<6>")
	)
	(segment
		(start 81.04251 -232.659428)
		(end 81.050892 -232.664254)
		(width 0.09525)
		(layer "In13.Cu")
		(net "M_B_CPU1_SA_DQS_DN<6>")
	)
	(segment
		(start 83.291172 -232.664254)
		(end 83.299554 -232.659428)
		(width 0.09525)
		(layer "In13.Cu")
		(net "M_B_CPU1_SA_DQS_DN<6>")
	)
	(segment
		(start 80.471264 -232.664254)
		(end 80.479646 -232.659428)
		(width 0.09525)
		(layer "In13.Cu")
		(net "M_B_CPU1_SA_DQS_DN<6>")
	)
	(segment
		(start 88.881712 -232.686606)
		(end 88.90508 -232.599738)
		(width 0.09525)
		(layer "In13.Cu")
		(net "M_B_CPU1_SA_DQS_DN<6>")
	)
	(segment
		(start 76.732638 -230.588566)
		(end 77.49921 -230.588566)
		(width 0.09525)
		(layer "In13.Cu")
		(net "M_B_CPU1_SA_DQS_DN<6>")
	)
	(segment
		(start 57.712356 -212.20811)
		(end 59.962796 -212.20811)
		(width 0.16002)
		(layer "In13.Cu")
		(net "M_B_CPU1_SA_DQS_DN<6>")
	)
	(segment
		(start 88.90508 -232.599738)
		(end 88.751156 -232.334308)
		(width 0.09525)
		(layer "In13.Cu")
		(net "M_B_CPU1_SA_DQS_DN<6>")
	)
	(segment
		(start 54.108604 -211.888578)
		(end 57.392824 -211.888578)
		(width 0.16002)
		(layer "In13.Cu")
		(net "M_B_CPU1_SA_DQS_DN<6>")
	)
	(segment
		(start 87.991188 -232.664254)
		(end 87.99957 -232.659428)
		(width 0.09525)
		(layer "In13.Cu")
		(net "M_B_CPU1_SA_DQS_DN<6>")
	)
	(segment
		(start 72.93991 -225.185224)
		(end 72.93991 -226.712526)
		(width 0.16002)
		(layer "In13.Cu")
		(net "M_B_CPU1_SA_DQS_DN<6>")
	)
	(segment
		(start 77.49921 -230.588566)
		(end 79.49438 -232.583736)
		(width 0.09525)
		(layer "In13.Cu")
		(net "M_B_CPU1_SA_DQS_DN<6>")
	)
	(segment
		(start 48.827944 -211.004404)
		(end 50.774346 -211.004404)
		(width 0.16002)
		(layer "In13.Cu")
		(net "M_B_CPU1_SA_DQS_DN<6>")
	)
	(segment
		(start 84.231226 -232.664254)
		(end 84.239608 -232.659428)
		(width 0.09525)
		(layer "In13.Cu")
		(net "M_B_CPU1_SA_DQS_DN<6>")
	)
	(segment
		(start 48.6156 -211.216748)
		(end 48.827944 -211.004404)
		(width 0.16002)
		(layer "In13.Cu")
		(net "M_B_CPU1_SA_DQS_DN<6>")
	)
	(segment
		(start 48.065436 -211.216748)
		(end 48.6156 -211.216748)
		(width 0.16002)
		(layer "In13.Cu")
		(net "M_B_CPU1_SA_DQS_DN<6>")
	)
	(segment
		(start 76.357988 -230.130604)
		(end 76.374752 -230.147368)
		(width 0.09525)
		(layer "In13.Cu")
		(net "M_B_CPU1_SA_DQS_DN<6>")
	)
	(segment
		(start 85.742526 -232.659428)
		(end 85.750908 -232.664254)
		(width 0.09525)
		(layer "In13.Cu")
		(net "M_B_CPU1_SA_DQS_DN<6>")
	)
	(segment
		(start 47.784004 -210.935316)
		(end 48.065436 -211.216748)
		(width 0.16002)
		(layer "In13.Cu")
		(net "M_B_CPU1_SA_DQS_DN<6>")
	)
	(segment
		(start 76.374752 -230.147368)
		(end 76.374752 -230.23068)
		(width 0.09525)
		(layer "In13.Cu")
		(net "M_B_CPU1_SA_DQS_DN<6>")
	)
	(segment
		(start 50.774346 -211.004404)
		(end 51.128168 -211.358226)
		(width 0.16002)
		(layer "In13.Cu")
		(net "M_B_CPU1_SA_DQS_DN<6>")
	)
	(segment
		(start 51.128168 -211.358226)
		(end 53.578252 -211.358226)
		(width 0.16002)
		(layer "In13.Cu")
		(net "M_B_CPU1_SA_DQS_DN<6>")
	)
	(segment
		(start 84.802472 -232.659428)
		(end 84.810854 -232.664254)
		(width 0.09525)
		(layer "In13.Cu")
		(net "M_B_CPU1_SA_DQS_DN<6>")
	)
	(segment
		(start 57.392824 -211.888578)
		(end 57.712356 -212.20811)
		(width 0.16002)
		(layer "In13.Cu")
		(net "M_B_CPU1_SA_DQS_DN<6>")
	)
	(segment
		(start 76.374752 -230.23068)
		(end 76.732638 -230.588566)
		(width 0.09525)
		(layer "In13.Cu")
		(net "M_B_CPU1_SA_DQS_DN<6>")
	)
	(segment
		(start 53.578252 -211.358226)
		(end 54.108604 -211.888578)
		(width 0.16002)
		(layer "In13.Cu")
		(net "M_B_CPU1_SA_DQS_DN<6>")
	)
	(segment
		(start 59.962796 -212.20811)
		(end 72.93991 -225.185224)
		(width 0.16002)
		(layer "In13.Cu")
		(net "M_B_CPU1_SA_DQS_DN<6>")
	)
	(arc
		(start 80.102456 -232.659428)
		(mid 80.286231 -232.7102)
		(end 80.471264 -232.664254)
		(width 0.09525)
		(layer "In13.Cu")
		(net "M_B_CPU1_SA_DQS_DN<6>")
	)
	(arc
		(start 87.99957 -232.659428)
		(mid 88.281002 -232.583673)
		(end 88.562434 -232.659428)
		(width 0.09525)
		(layer "In13.Cu")
		(net "M_B_CPU1_SA_DQS_DN<6>")
	)
	(arc
		(start 81.4197 -232.659428)
		(mid 81.701132 -232.583673)
		(end 81.982564 -232.659428)
		(width 0.09525)
		(layer "In13.Cu")
		(net "M_B_CPU1_SA_DQS_DN<6>")
	)
	(arc
		(start 84.810854 -232.664254)
		(mid 84.995886 -232.710168)
		(end 85.179662 -232.659428)
		(width 0.09525)
		(layer "In13.Cu")
		(net "M_B_CPU1_SA_DQS_DN<6>")
	)
	(arc
		(start 83.862418 -232.659428)
		(mid 84.046193 -232.7102)
		(end 84.231226 -232.664254)
		(width 0.09525)
		(layer "In13.Cu")
		(net "M_B_CPU1_SA_DQS_DN<6>")
	)
	(arc
		(start 88.562434 -232.659428)
		(mid 88.719032 -232.708717)
		(end 88.881712 -232.686606)
		(width 0.09525)
		(layer "In13.Cu")
		(net "M_B_CPU1_SA_DQS_DN<6>")
	)
	(arc
		(start 81.050892 -232.664254)
		(mid 81.235924 -232.710168)
		(end 81.4197 -232.659428)
		(width 0.09525)
		(layer "In13.Cu")
		(net "M_B_CPU1_SA_DQS_DN<6>")
	)
	(arc
		(start 87.62238 -232.659428)
		(mid 87.806155 -232.7102)
		(end 87.991188 -232.664254)
		(width 0.09525)
		(layer "In13.Cu")
		(net "M_B_CPU1_SA_DQS_DN<6>")
	)
	(arc
		(start 80.479646 -232.659428)
		(mid 80.761078 -232.583673)
		(end 81.04251 -232.659428)
		(width 0.09525)
		(layer "In13.Cu")
		(net "M_B_CPU1_SA_DQS_DN<6>")
	)
	(arc
		(start 83.299554 -232.659428)
		(mid 83.580986 -232.583673)
		(end 83.862418 -232.659428)
		(width 0.09525)
		(layer "In13.Cu")
		(net "M_B_CPU1_SA_DQS_DN<6>")
	)
	(arc
		(start 81.982564 -232.659428)
		(mid 82.171032 -232.710105)
		(end 82.3595 -232.659428)
		(width 0.09525)
		(layer "In13.Cu")
		(net "M_B_CPU1_SA_DQS_DN<6>")
	)
	(arc
		(start 86.68258 -232.659428)
		(mid 86.871048 -232.710105)
		(end 87.059516 -232.659428)
		(width 0.09525)
		(layer "In13.Cu")
		(net "M_B_CPU1_SA_DQS_DN<6>")
	)
	(arc
		(start 79.821024 -232.583736)
		(mid 79.966732 -232.603004)
		(end 80.102456 -232.659428)
		(width 0.09525)
		(layer "In13.Cu")
		(net "M_B_CPU1_SA_DQS_DN<6>")
	)
	(arc
		(start 84.239608 -232.659428)
		(mid 84.52104 -232.583673)
		(end 84.802472 -232.659428)
		(width 0.09525)
		(layer "In13.Cu")
		(net "M_B_CPU1_SA_DQS_DN<6>")
	)
	(arc
		(start 85.750908 -232.664254)
		(mid 85.93594 -232.710168)
		(end 86.119716 -232.659428)
		(width 0.09525)
		(layer "In13.Cu")
		(net "M_B_CPU1_SA_DQS_DN<6>")
	)
	(arc
		(start 87.059516 -232.659428)
		(mid 87.340948 -232.583673)
		(end 87.62238 -232.659428)
		(width 0.09525)
		(layer "In13.Cu")
		(net "M_B_CPU1_SA_DQS_DN<6>")
	)
	(arc
		(start 86.119716 -232.659428)
		(mid 86.401148 -232.583673)
		(end 86.68258 -232.659428)
		(width 0.09525)
		(layer "In13.Cu")
		(net "M_B_CPU1_SA_DQS_DN<6>")
	)
	(arc
		(start 85.179662 -232.659428)
		(mid 85.461094 -232.583673)
		(end 85.742526 -232.659428)
		(width 0.09525)
		(layer "In13.Cu")
		(net "M_B_CPU1_SA_DQS_DN<6>")
	)
	(arc
		(start 82.922364 -232.659428)
		(mid 83.106139 -232.7102)
		(end 83.291172 -232.664254)
		(width 0.09525)
		(layer "In13.Cu")
		(net "M_B_CPU1_SA_DQS_DN<6>")
	)
	(arc
		(start 82.3595 -232.659428)
		(mid 82.640932 -232.583673)
		(end 82.922364 -232.659428)
		(width 0.09525)
		(layer "In13.Cu")
		(net "M_B_CPU1_SA_DQS_DN<6>")
	)
	(segment
		(start 89.218008 -227.740464)
		(end 88.751156 -227.474526)
		(width 0.12954)
		(layer "F.Cu")
		(net "M_B_CPU1_SA_DQS_DN<5>")
	)
	(segment
		(start 81.51241 -226.98964)
		(end 81.55051 -227.011738)
		(width 0.09525)
		(layer "In13.Cu")
		(net "M_B_CPU1_SA_DQS_DN<5>")
	)
	(segment
		(start 78.395322 -221.7674)
		(end 78.395322 -221.850712)
		(width 0.09525)
		(layer "In13.Cu")
		(net "M_B_CPU1_SA_DQS_DN<5>")
	)
	(segment
		(start 79.13243 -222.922084)
		(end 79.162656 -222.93961)
		(width 0.09525)
		(layer "In13.Cu")
		(net "M_B_CPU1_SA_DQS_DN<5>")
	)
	(segment
		(start 48.06823 -201.869548)
		(end 48.9204 -201.869548)
		(width 0.16002)
		(layer "In13.Cu")
		(net "M_B_CPU1_SA_DQS_DN<5>")
	)
	(segment
		(start 51.138836 -202.008232)
		(end 53.556916 -202.008232)
		(width 0.16002)
		(layer "In13.Cu")
		(net "M_B_CPU1_SA_DQS_DN<5>")
	)
	(segment
		(start 79.598266 -223.72955)
		(end 79.633064 -223.749616)
		(width 0.09525)
		(layer "In13.Cu")
		(net "M_B_CPU1_SA_DQS_DN<5>")
	)
	(segment
		(start 80.073246 -224.542858)
		(end 80.102456 -224.559622)
		(width 0.09525)
		(layer "In13.Cu")
		(net "M_B_CPU1_SA_DQS_DN<5>")
	)
	(segment
		(start 84.802472 -227.799646)
		(end 84.810854 -227.804472)
		(width 0.09525)
		(layer "In13.Cu")
		(net "M_B_CPU1_SA_DQS_DN<5>")
	)
	(segment
		(start 85.742526 -227.799646)
		(end 85.750908 -227.804472)
		(width 0.09525)
		(layer "In13.Cu")
		(net "M_B_CPU1_SA_DQS_DN<5>")
	)
	(segment
		(start 50.78603 -201.655426)
		(end 51.138836 -202.008232)
		(width 0.16002)
		(layer "In13.Cu")
		(net "M_B_CPU1_SA_DQS_DN<5>")
	)
	(segment
		(start 80.102456 -224.559622)
		(end 80.140556 -224.58172)
		(width 0.09525)
		(layer "In13.Cu")
		(net "M_B_CPU1_SA_DQS_DN<5>")
	)
	(segment
		(start 81.009998 -226.160838)
		(end 81.04251 -226.179634)
		(width 0.09525)
		(layer "In13.Cu")
		(net "M_B_CPU1_SA_DQS_DN<5>")
	)
	(segment
		(start 80.57261 -225.369628)
		(end 80.607662 -225.390202)
		(width 0.09525)
		(layer "In13.Cu")
		(net "M_B_CPU1_SA_DQS_DN<5>")
	)
	(segment
		(start 78.378558 -221.750636)
		(end 78.395322 -221.7674)
		(width 0.09525)
		(layer "In13.Cu")
		(net "M_B_CPU1_SA_DQS_DN<5>")
	)
	(segment
		(start 83.291172 -227.804472)
		(end 83.299554 -227.799646)
		(width 0.09525)
		(layer "In13.Cu")
		(net "M_B_CPU1_SA_DQS_DN<5>")
	)
	(segment
		(start 81.04251 -226.179634)
		(end 81.08061 -226.201732)
		(width 0.09525)
		(layer "In13.Cu")
		(net "M_B_CPU1_SA_DQS_DN<5>")
	)
	(segment
		(start 53.556916 -202.008232)
		(end 53.981858 -202.433174)
		(width 0.16002)
		(layer "In13.Cu")
		(net "M_B_CPU1_SA_DQS_DN<5>")
	)
	(segment
		(start 88.881712 -227.826824)
		(end 88.90508 -227.739956)
		(width 0.09525)
		(layer "In13.Cu")
		(net "M_B_CPU1_SA_DQS_DN<5>")
	)
	(segment
		(start 60.10021 -202.858116)
		(end 78.16723 -220.925136)
		(width 0.16002)
		(layer "In13.Cu")
		(net "M_B_CPU1_SA_DQS_DN<5>")
	)
	(segment
		(start 78.16723 -221.539308)
		(end 78.378558 -221.750636)
		(width 0.16002)
		(layer "In13.Cu")
		(net "M_B_CPU1_SA_DQS_DN<5>")
	)
	(segment
		(start 87.991188 -227.804472)
		(end 87.99957 -227.799646)
		(width 0.09525)
		(layer "In13.Cu")
		(net "M_B_CPU1_SA_DQS_DN<5>")
	)
	(segment
		(start 79.162656 -222.93961)
		(end 79.202026 -222.96247)
		(width 0.09525)
		(layer "In13.Cu")
		(net "M_B_CPU1_SA_DQS_DN<5>")
	)
	(segment
		(start 57.320942 -202.385676)
		(end 57.793382 -202.858116)
		(width 0.16002)
		(layer "In13.Cu")
		(net "M_B_CPU1_SA_DQS_DN<5>")
	)
	(segment
		(start 57.793382 -202.858116)
		(end 60.10021 -202.858116)
		(width 0.16002)
		(layer "In13.Cu")
		(net "M_B_CPU1_SA_DQS_DN<5>")
	)
	(segment
		(start 88.90508 -227.739956)
		(end 88.751156 -227.474526)
		(width 0.09525)
		(layer "In13.Cu")
		(net "M_B_CPU1_SA_DQS_DN<5>")
	)
	(segment
		(start 84.231226 -227.804472)
		(end 84.239608 -227.799646)
		(width 0.09525)
		(layer "In13.Cu")
		(net "M_B_CPU1_SA_DQS_DN<5>")
	)
	(segment
		(start 81.950052 -227.78085)
		(end 81.982564 -227.799646)
		(width 0.09525)
		(layer "In13.Cu")
		(net "M_B_CPU1_SA_DQS_DN<5>")
	)
	(segment
		(start 78.16723 -220.925136)
		(end 78.16723 -221.539308)
		(width 0.16002)
		(layer "In13.Cu")
		(net "M_B_CPU1_SA_DQS_DN<5>")
	)
	(segment
		(start 55.028846 -201.947272)
		(end 56.26227 -201.947272)
		(width 0.16002)
		(layer "In13.Cu")
		(net "M_B_CPU1_SA_DQS_DN<5>")
	)
	(segment
		(start 78.692756 -222.129604)
		(end 78.730856 -222.151702)
		(width 0.09525)
		(layer "In13.Cu")
		(net "M_B_CPU1_SA_DQS_DN<5>")
	)
	(segment
		(start 47.784004 -201.585322)
		(end 48.06823 -201.869548)
		(width 0.16002)
		(layer "In13.Cu")
		(net "M_B_CPU1_SA_DQS_DN<5>")
	)
	(segment
		(start 81.480914 -226.971352)
		(end 81.51241 -226.98964)
		(width 0.09525)
		(layer "In13.Cu")
		(net "M_B_CPU1_SA_DQS_DN<5>")
	)
	(segment
		(start 49.134522 -201.655426)
		(end 50.78603 -201.655426)
		(width 0.16002)
		(layer "In13.Cu")
		(net "M_B_CPU1_SA_DQS_DN<5>")
	)
	(segment
		(start 78.395322 -221.850712)
		(end 78.615032 -222.070422)
		(width 0.09525)
		(layer "In13.Cu")
		(net "M_B_CPU1_SA_DQS_DN<5>")
	)
	(segment
		(start 54.542944 -202.433174)
		(end 55.028846 -201.947272)
		(width 0.16002)
		(layer "In13.Cu")
		(net "M_B_CPU1_SA_DQS_DN<5>")
	)
	(segment
		(start 48.9204 -201.869548)
		(end 49.134522 -201.655426)
		(width 0.16002)
		(layer "In13.Cu")
		(net "M_B_CPU1_SA_DQS_DN<5>")
	)
	(segment
		(start 53.981858 -202.433174)
		(end 54.542944 -202.433174)
		(width 0.16002)
		(layer "In13.Cu")
		(net "M_B_CPU1_SA_DQS_DN<5>")
	)
	(segment
		(start 56.26227 -201.947272)
		(end 57.320942 -202.385676)
		(width 0.16002)
		(layer "In13.Cu")
		(net "M_B_CPU1_SA_DQS_DN<5>")
	)
	(segment
		(start 79.633064 -223.749616)
		(end 79.668116 -223.77019)
		(width 0.09525)
		(layer "In13.Cu")
		(net "M_B_CPU1_SA_DQS_DN<5>")
	)
	(segment
		(start 80.540098 -225.350832)
		(end 80.57261 -225.369628)
		(width 0.09525)
		(layer "In13.Cu")
		(net "M_B_CPU1_SA_DQS_DN<5>")
	)
	(arc
		(start 78.973934 -222.61449)
		(mid 79.01589 -222.787501)
		(end 79.13243 -222.922084)
		(width 0.09525)
		(layer "In13.Cu")
		(net "M_B_CPU1_SA_DQS_DN<5>")
	)
	(arc
		(start 78.730856 -222.151702)
		(mid 78.909462 -222.353121)
		(end 78.973934 -222.61449)
		(width 0.09525)
		(layer "In13.Cu")
		(net "M_B_CPU1_SA_DQS_DN<5>")
	)
	(arc
		(start 85.179662 -227.799646)
		(mid 85.461094 -227.723891)
		(end 85.742526 -227.799646)
		(width 0.09525)
		(layer "In13.Cu")
		(net "M_B_CPU1_SA_DQS_DN<5>")
	)
	(arc
		(start 82.3595 -227.799646)
		(mid 82.640932 -227.723891)
		(end 82.922364 -227.799646)
		(width 0.09525)
		(layer "In13.Cu")
		(net "M_B_CPU1_SA_DQS_DN<5>")
	)
	(arc
		(start 80.85328 -225.854514)
		(mid 80.894737 -226.026554)
		(end 81.009998 -226.160838)
		(width 0.09525)
		(layer "In13.Cu")
		(net "M_B_CPU1_SA_DQS_DN<5>")
	)
	(arc
		(start 83.299554 -227.799646)
		(mid 83.580986 -227.723891)
		(end 83.862418 -227.799646)
		(width 0.09525)
		(layer "In13.Cu")
		(net "M_B_CPU1_SA_DQS_DN<5>")
	)
	(arc
		(start 83.862418 -227.799646)
		(mid 84.046193 -227.850418)
		(end 84.231226 -227.804472)
		(width 0.09525)
		(layer "In13.Cu")
		(net "M_B_CPU1_SA_DQS_DN<5>")
	)
	(arc
		(start 85.750908 -227.804472)
		(mid 85.93594 -227.850386)
		(end 86.119716 -227.799646)
		(width 0.09525)
		(layer "In13.Cu")
		(net "M_B_CPU1_SA_DQS_DN<5>")
	)
	(arc
		(start 86.119716 -227.799646)
		(mid 86.401148 -227.723891)
		(end 86.68258 -227.799646)
		(width 0.09525)
		(layer "In13.Cu")
		(net "M_B_CPU1_SA_DQS_DN<5>")
	)
	(arc
		(start 81.982564 -227.799646)
		(mid 82.171032 -227.850323)
		(end 82.3595 -227.799646)
		(width 0.09525)
		(layer "In13.Cu")
		(net "M_B_CPU1_SA_DQS_DN<5>")
	)
	(arc
		(start 78.615032 -222.070422)
		(mid 78.651963 -222.102549)
		(end 78.692756 -222.129604)
		(width 0.09525)
		(layer "In13.Cu")
		(net "M_B_CPU1_SA_DQS_DN<5>")
	)
	(arc
		(start 86.68258 -227.799646)
		(mid 86.871048 -227.850323)
		(end 87.059516 -227.799646)
		(width 0.09525)
		(layer "In13.Cu")
		(net "M_B_CPU1_SA_DQS_DN<5>")
	)
	(arc
		(start 79.913734 -224.234502)
		(mid 79.955981 -224.408077)
		(end 80.073246 -224.542858)
		(width 0.09525)
		(layer "In13.Cu")
		(net "M_B_CPU1_SA_DQS_DN<5>")
	)
	(arc
		(start 79.44358 -223.424496)
		(mid 79.484456 -223.595518)
		(end 79.598266 -223.72955)
		(width 0.09525)
		(layer "In13.Cu")
		(net "M_B_CPU1_SA_DQS_DN<5>")
	)
	(arc
		(start 81.323434 -226.66452)
		(mid 81.365099 -226.836967)
		(end 81.480914 -226.971352)
		(width 0.09525)
		(layer "In13.Cu")
		(net "M_B_CPU1_SA_DQS_DN<5>")
	)
	(arc
		(start 87.99957 -227.799646)
		(mid 88.281002 -227.723891)
		(end 88.562434 -227.799646)
		(width 0.09525)
		(layer "In13.Cu")
		(net "M_B_CPU1_SA_DQS_DN<5>")
	)
	(arc
		(start 87.62238 -227.799646)
		(mid 87.806155 -227.850418)
		(end 87.991188 -227.804472)
		(width 0.09525)
		(layer "In13.Cu")
		(net "M_B_CPU1_SA_DQS_DN<5>")
	)
	(arc
		(start 81.793334 -227.474526)
		(mid 81.834791 -227.646566)
		(end 81.950052 -227.78085)
		(width 0.09525)
		(layer "In13.Cu")
		(net "M_B_CPU1_SA_DQS_DN<5>")
	)
	(arc
		(start 81.08061 -226.201732)
		(mid 81.25906 -226.403202)
		(end 81.323434 -226.66452)
		(width 0.09525)
		(layer "In13.Cu")
		(net "M_B_CPU1_SA_DQS_DN<5>")
	)
	(arc
		(start 84.810854 -227.804472)
		(mid 84.995886 -227.850386)
		(end 85.179662 -227.799646)
		(width 0.09525)
		(layer "In13.Cu")
		(net "M_B_CPU1_SA_DQS_DN<5>")
	)
	(arc
		(start 88.562434 -227.799646)
		(mid 88.719032 -227.848935)
		(end 88.881712 -227.826824)
		(width 0.09525)
		(layer "In13.Cu")
		(net "M_B_CPU1_SA_DQS_DN<5>")
	)
	(arc
		(start 80.140556 -224.58172)
		(mid 80.319006 -224.78319)
		(end 80.38338 -225.044508)
		(width 0.09525)
		(layer "In13.Cu")
		(net "M_B_CPU1_SA_DQS_DN<5>")
	)
	(arc
		(start 81.55051 -227.011738)
		(mid 81.72896 -227.213208)
		(end 81.793334 -227.474526)
		(width 0.09525)
		(layer "In13.Cu")
		(net "M_B_CPU1_SA_DQS_DN<5>")
	)
	(arc
		(start 84.239608 -227.799646)
		(mid 84.52104 -227.723891)
		(end 84.802472 -227.799646)
		(width 0.09525)
		(layer "In13.Cu")
		(net "M_B_CPU1_SA_DQS_DN<5>")
	)
	(arc
		(start 82.922364 -227.799646)
		(mid 83.106139 -227.850418)
		(end 83.291172 -227.804472)
		(width 0.09525)
		(layer "In13.Cu")
		(net "M_B_CPU1_SA_DQS_DN<5>")
	)
	(arc
		(start 79.202026 -222.96247)
		(mid 79.379557 -223.163813)
		(end 79.44358 -223.424496)
		(width 0.09525)
		(layer "In13.Cu")
		(net "M_B_CPU1_SA_DQS_DN<5>")
	)
	(arc
		(start 80.607662 -225.390202)
		(mid 80.788053 -225.591901)
		(end 80.85328 -225.854514)
		(width 0.09525)
		(layer "In13.Cu")
		(net "M_B_CPU1_SA_DQS_DN<5>")
	)
	(arc
		(start 80.38338 -225.044508)
		(mid 80.424837 -225.216548)
		(end 80.540098 -225.350832)
		(width 0.09525)
		(layer "In13.Cu")
		(net "M_B_CPU1_SA_DQS_DN<5>")
	)
	(arc
		(start 87.059516 -227.799646)
		(mid 87.340948 -227.723891)
		(end 87.62238 -227.799646)
		(width 0.09525)
		(layer "In13.Cu")
		(net "M_B_CPU1_SA_DQS_DN<5>")
	)
	(arc
		(start 79.668116 -223.77019)
		(mid 79.848507 -223.971889)
		(end 79.913734 -224.234502)
		(width 0.09525)
		(layer "In13.Cu")
		(net "M_B_CPU1_SA_DQS_DN<5>")
	)
	(segment
		(start 88.277954 -247.180354)
		(end 87.811102 -246.914416)
		(width 0.12954)
		(layer "F.Cu")
		(net "M_B_CPU1_SA_DQS_DN<4>")
	)
	(segment
		(start 81.04251 -246.589296)
		(end 81.050892 -246.58447)
		(width 0.09525)
		(layer "In13.Cu")
		(net "M_B_CPU1_SA_DQS_DN<4>")
	)
	(segment
		(start 76.60132 -246.947436)
		(end 77.400404 -246.947436)
		(width 0.09525)
		(layer "In13.Cu")
		(net "M_B_CPU1_SA_DQS_DN<4>")
	)
	(segment
		(start 63.523114 -243.532152)
		(end 63.24092 -243.814346)
		(width 0.16002)
		(layer "In13.Cu")
		(net "M_B_CPU1_SA_DQS_DN<4>")
	)
	(segment
		(start 63.326518 -243.058696)
		(end 63.523114 -243.255292)
		(width 0.16002)
		(layer "In13.Cu")
		(net "M_B_CPU1_SA_DQS_DN<4>")
	)
	(segment
		(start 59.599576 -240.223802)
		(end 59.599576 -240.700306)
		(width 0.16002)
		(layer "In13.Cu")
		(net "M_B_CPU1_SA_DQS_DN<4>")
	)
	(segment
		(start 63.613792 -244.714522)
		(end 64.141096 -244.714522)
		(width 0.16002)
		(layer "In13.Cu")
		(net "M_B_CPU1_SA_DQS_DN<4>")
	)
	(segment
		(start 64.614552 -245.187978)
		(end 64.614552 -245.715282)
		(width 0.16002)
		(layer "In13.Cu")
		(net "M_B_CPU1_SA_DQS_DN<4>")
	)
	(segment
		(start 80.471264 -246.58447)
		(end 80.479646 -246.589296)
		(width 0.09525)
		(layer "In13.Cu")
		(net "M_B_CPU1_SA_DQS_DN<4>")
	)
	(segment
		(start 64.141096 -244.714522)
		(end 64.42329 -244.432328)
		(width 0.16002)
		(layer "In13.Cu")
		(net "M_B_CPU1_SA_DQS_DN<4>")
	)
	(segment
		(start 79.541116 -246.589296)
		(end 79.566516 -246.604028)
		(width 0.09525)
		(layer "In13.Cu")
		(net "M_B_CPU1_SA_DQS_DN<4>")
	)
	(segment
		(start 65.193164 -246.293894)
		(end 75.879706 -246.293894)
		(width 0.16002)
		(layer "In13.Cu")
		(net "M_B_CPU1_SA_DQS_DN<4>")
	)
	(segment
		(start 78.223618 -246.589296)
		(end 78.249018 -246.574818)
		(width 0.09525)
		(layer "In13.Cu")
		(net "M_B_CPU1_SA_DQS_DN<4>")
	)
	(segment
		(start 62.24016 -243.34089)
		(end 62.767464 -243.34089)
		(width 0.16002)
		(layer "In13.Cu")
		(net "M_B_CPU1_SA_DQS_DN<4>")
	)
	(segment
		(start 52.915312 -238.590836)
		(end 55.79618 -238.590836)
		(width 0.16002)
		(layer "In13.Cu")
		(net "M_B_CPU1_SA_DQS_DN<4>")
	)
	(segment
		(start 77.400404 -246.947436)
		(end 77.68336 -246.66448)
		(width 0.09525)
		(layer "In13.Cu")
		(net "M_B_CPU1_SA_DQS_DN<4>")
	)
	(segment
		(start 64.896746 -244.628924)
		(end 64.896746 -244.905784)
		(width 0.16002)
		(layer "In13.Cu")
		(net "M_B_CPU1_SA_DQS_DN<4>")
	)
	(segment
		(start 76.268834 -246.329962)
		(end 76.268834 -246.61495)
		(width 0.09525)
		(layer "In13.Cu")
		(net "M_B_CPU1_SA_DQS_DN<4>")
	)
	(segment
		(start 83.291172 -246.58447)
		(end 83.299554 -246.589296)
		(width 0.09525)
		(layer "In13.Cu")
		(net "M_B_CPU1_SA_DQS_DN<4>")
	)
	(segment
		(start 61.867288 -242.968018)
		(end 62.24016 -243.34089)
		(width 0.16002)
		(layer "In13.Cu")
		(net "M_B_CPU1_SA_DQS_DN<4>")
	)
	(segment
		(start 84.231226 -246.58447)
		(end 84.239608 -246.589296)
		(width 0.09525)
		(layer "In13.Cu")
		(net "M_B_CPU1_SA_DQS_DN<4>")
	)
	(segment
		(start 64.614552 -245.715282)
		(end 65.193164 -246.293894)
		(width 0.16002)
		(layer "In13.Cu")
		(net "M_B_CPU1_SA_DQS_DN<4>")
	)
	(segment
		(start 75.879706 -246.293894)
		(end 75.903328 -246.293894)
		(width 0.09525)
		(layer "In13.Cu")
		(net "M_B_CPU1_SA_DQS_DN<4>")
	)
	(segment
		(start 75.96251 -246.234712)
		(end 76.173584 -246.234712)
		(width 0.09525)
		(layer "In13.Cu")
		(net "M_B_CPU1_SA_DQS_DN<4>")
	)
	(segment
		(start 58.253376 -239.354106)
		(end 58.650124 -239.750854)
		(width 0.16002)
		(layer "In13.Cu")
		(net "M_B_CPU1_SA_DQS_DN<4>")
	)
	(segment
		(start 59.126628 -239.750854)
		(end 59.327542 -239.54994)
		(width 0.16002)
		(layer "In13.Cu")
		(net "M_B_CPU1_SA_DQS_DN<4>")
	)
	(segment
		(start 55.79618 -238.590836)
		(end 57.63895 -239.354106)
		(width 0.16002)
		(layer "In13.Cu")
		(net "M_B_CPU1_SA_DQS_DN<4>")
	)
	(segment
		(start 63.523114 -243.255292)
		(end 63.523114 -243.532152)
		(width 0.16002)
		(layer "In13.Cu")
		(net "M_B_CPU1_SA_DQS_DN<4>")
	)
	(segment
		(start 79.141574 -246.602758)
		(end 79.164942 -246.589296)
		(width 0.09525)
		(layer "In13.Cu")
		(net "M_B_CPU1_SA_DQS_DN<4>")
	)
	(segment
		(start 75.903328 -246.293894)
		(end 75.96251 -246.234712)
		(width 0.09525)
		(layer "In13.Cu")
		(net "M_B_CPU1_SA_DQS_DN<4>")
	)
	(segment
		(start 59.327542 -239.54994)
		(end 59.553602 -239.54994)
		(width 0.16002)
		(layer "In13.Cu")
		(net "M_B_CPU1_SA_DQS_DN<4>")
	)
	(segment
		(start 52.781454 -238.724694)
		(end 52.915312 -238.590836)
		(width 0.16002)
		(layer "In13.Cu")
		(net "M_B_CPU1_SA_DQS_DN<4>")
	)
	(segment
		(start 58.650124 -239.750854)
		(end 59.126628 -239.750854)
		(width 0.16002)
		(layer "In13.Cu")
		(net "M_B_CPU1_SA_DQS_DN<4>")
	)
	(segment
		(start 61.952886 -241.685064)
		(end 62.149482 -241.88166)
		(width 0.16002)
		(layer "In13.Cu")
		(net "M_B_CPU1_SA_DQS_DN<4>")
	)
	(segment
		(start 76.173584 -246.234712)
		(end 76.268834 -246.329962)
		(width 0.09525)
		(layer "In13.Cu")
		(net "M_B_CPU1_SA_DQS_DN<4>")
	)
	(segment
		(start 51.884072 -238.985298)
		(end 52.144676 -238.724694)
		(width 0.16002)
		(layer "In13.Cu")
		(net "M_B_CPU1_SA_DQS_DN<4>")
	)
	(segment
		(start 84.802472 -246.589296)
		(end 84.810854 -246.58447)
		(width 0.09525)
		(layer "In13.Cu")
		(net "M_B_CPU1_SA_DQS_DN<4>")
	)
	(segment
		(start 61.676026 -241.685064)
		(end 61.952886 -241.685064)
		(width 0.16002)
		(layer "In13.Cu")
		(net "M_B_CPU1_SA_DQS_DN<4>")
	)
	(segment
		(start 64.896746 -244.905784)
		(end 64.614552 -245.187978)
		(width 0.16002)
		(layer "In13.Cu")
		(net "M_B_CPU1_SA_DQS_DN<4>")
	)
	(segment
		(start 59.599576 -240.700306)
		(end 60.866528 -241.967258)
		(width 0.16002)
		(layer "In13.Cu")
		(net "M_B_CPU1_SA_DQS_DN<4>")
	)
	(segment
		(start 61.867288 -242.440714)
		(end 61.867288 -242.968018)
		(width 0.16002)
		(layer "In13.Cu")
		(net "M_B_CPU1_SA_DQS_DN<4>")
	)
	(segment
		(start 59.80049 -240.022888)
		(end 59.599576 -240.223802)
		(width 0.16002)
		(layer "In13.Cu")
		(net "M_B_CPU1_SA_DQS_DN<4>")
	)
	(segment
		(start 63.24092 -243.814346)
		(end 63.24092 -244.34165)
		(width 0.16002)
		(layer "In13.Cu")
		(net "M_B_CPU1_SA_DQS_DN<4>")
	)
	(segment
		(start 62.767464 -243.34089)
		(end 63.049658 -243.058696)
		(width 0.16002)
		(layer "In13.Cu")
		(net "M_B_CPU1_SA_DQS_DN<4>")
	)
	(segment
		(start 59.80049 -239.796828)
		(end 59.80049 -240.022888)
		(width 0.16002)
		(layer "In13.Cu")
		(net "M_B_CPU1_SA_DQS_DN<4>")
	)
	(segment
		(start 61.393832 -241.967258)
		(end 61.676026 -241.685064)
		(width 0.16002)
		(layer "In13.Cu")
		(net "M_B_CPU1_SA_DQS_DN<4>")
	)
	(segment
		(start 85.742526 -246.589296)
		(end 85.750908 -246.58447)
		(width 0.09525)
		(layer "In13.Cu")
		(net "M_B_CPU1_SA_DQS_DN<4>")
	)
	(segment
		(start 77.68336 -246.66448)
		(end 77.94371 -246.66448)
		(width 0.09525)
		(layer "In13.Cu")
		(net "M_B_CPU1_SA_DQS_DN<4>")
	)
	(segment
		(start 64.42329 -244.432328)
		(end 64.70015 -244.432328)
		(width 0.16002)
		(layer "In13.Cu")
		(net "M_B_CPU1_SA_DQS_DN<4>")
	)
	(segment
		(start 60.866528 -241.967258)
		(end 61.393832 -241.967258)
		(width 0.16002)
		(layer "In13.Cu")
		(net "M_B_CPU1_SA_DQS_DN<4>")
	)
	(segment
		(start 63.24092 -244.34165)
		(end 63.613792 -244.714522)
		(width 0.16002)
		(layer "In13.Cu")
		(net "M_B_CPU1_SA_DQS_DN<4>")
	)
	(segment
		(start 62.149482 -242.15852)
		(end 61.867288 -242.440714)
		(width 0.16002)
		(layer "In13.Cu")
		(net "M_B_CPU1_SA_DQS_DN<4>")
	)
	(segment
		(start 64.70015 -244.432328)
		(end 64.896746 -244.628924)
		(width 0.16002)
		(layer "In13.Cu")
		(net "M_B_CPU1_SA_DQS_DN<4>")
	)
	(segment
		(start 62.149482 -241.88166)
		(end 62.149482 -242.15852)
		(width 0.16002)
		(layer "In13.Cu")
		(net "M_B_CPU1_SA_DQS_DN<4>")
	)
	(segment
		(start 76.268834 -246.61495)
		(end 76.60132 -246.947436)
		(width 0.09525)
		(layer "In13.Cu")
		(net "M_B_CPU1_SA_DQS_DN<4>")
	)
	(segment
		(start 79.526638 -246.580914)
		(end 79.541116 -246.589296)
		(width 0.09525)
		(layer "In13.Cu")
		(net "M_B_CPU1_SA_DQS_DN<4>")
	)
	(segment
		(start 87.657178 -246.648986)
		(end 87.811102 -246.914416)
		(width 0.09525)
		(layer "In13.Cu")
		(net "M_B_CPU1_SA_DQS_DN<4>")
	)
	(segment
		(start 57.63895 -239.354106)
		(end 58.253376 -239.354106)
		(width 0.16002)
		(layer "In13.Cu")
		(net "M_B_CPU1_SA_DQS_DN<4>")
	)
	(segment
		(start 52.144676 -238.724694)
		(end 52.781454 -238.724694)
		(width 0.16002)
		(layer "In13.Cu")
		(net "M_B_CPU1_SA_DQS_DN<4>")
	)
	(segment
		(start 63.049658 -243.058696)
		(end 63.326518 -243.058696)
		(width 0.16002)
		(layer "In13.Cu")
		(net "M_B_CPU1_SA_DQS_DN<4>")
	)
	(segment
		(start 87.55634 -246.622316)
		(end 87.657178 -246.648986)
		(width 0.09525)
		(layer "In13.Cu")
		(net "M_B_CPU1_SA_DQS_DN<4>")
	)
	(segment
		(start 59.553602 -239.54994)
		(end 59.80049 -239.796828)
		(width 0.16002)
		(layer "In13.Cu")
		(net "M_B_CPU1_SA_DQS_DN<4>")
	)
	(arc
		(start 78.064614 -246.651272)
		(mid 78.146495 -246.626385)
		(end 78.223618 -246.589296)
		(width 0.09525)
		(layer "In13.Cu")
		(net "M_B_CPU1_SA_DQS_DN<4>")
	)
	(arc
		(start 79.164942 -246.589296)
		(mid 79.344714 -246.53872)
		(end 79.526638 -246.580914)
		(width 0.09525)
		(layer "In13.Cu")
		(net "M_B_CPU1_SA_DQS_DN<4>")
	)
	(arc
		(start 80.479646 -246.589296)
		(mid 80.761078 -246.665051)
		(end 81.04251 -246.589296)
		(width 0.09525)
		(layer "In13.Cu")
		(net "M_B_CPU1_SA_DQS_DN<4>")
	)
	(arc
		(start 77.94371 -246.66448)
		(mid 78.004522 -246.661169)
		(end 78.064614 -246.651272)
		(width 0.09525)
		(layer "In13.Cu")
		(net "M_B_CPU1_SA_DQS_DN<4>")
	)
	(arc
		(start 85.750908 -246.58447)
		(mid 85.93594 -246.538556)
		(end 86.119716 -246.589296)
		(width 0.09525)
		(layer "In13.Cu")
		(net "M_B_CPU1_SA_DQS_DN<4>")
	)
	(arc
		(start 81.982564 -246.589296)
		(mid 82.171032 -246.538619)
		(end 82.3595 -246.589296)
		(width 0.09525)
		(layer "In13.Cu")
		(net "M_B_CPU1_SA_DQS_DN<4>")
	)
	(arc
		(start 83.299554 -246.589296)
		(mid 83.580986 -246.665051)
		(end 83.862418 -246.589296)
		(width 0.09525)
		(layer "In13.Cu")
		(net "M_B_CPU1_SA_DQS_DN<4>")
	)
	(arc
		(start 83.862418 -246.589296)
		(mid 84.046193 -246.538524)
		(end 84.231226 -246.58447)
		(width 0.09525)
		(layer "In13.Cu")
		(net "M_B_CPU1_SA_DQS_DN<4>")
	)
	(arc
		(start 78.600808 -246.589296)
		(mid 78.869471 -246.665514)
		(end 79.141574 -246.602758)
		(width 0.09525)
		(layer "In13.Cu")
		(net "M_B_CPU1_SA_DQS_DN<4>")
	)
	(arc
		(start 79.566516 -246.604028)
		(mid 79.83637 -246.664907)
		(end 80.102456 -246.589296)
		(width 0.09525)
		(layer "In13.Cu")
		(net "M_B_CPU1_SA_DQS_DN<4>")
	)
	(arc
		(start 87.059516 -246.589296)
		(mid 87.29303 -246.663139)
		(end 87.535766 -246.630444)
		(width 0.09525)
		(layer "In13.Cu")
		(net "M_B_CPU1_SA_DQS_DN<4>")
	)
	(arc
		(start 82.3595 -246.589296)
		(mid 82.640932 -246.665051)
		(end 82.922364 -246.589296)
		(width 0.09525)
		(layer "In13.Cu")
		(net "M_B_CPU1_SA_DQS_DN<4>")
	)
	(arc
		(start 84.810854 -246.58447)
		(mid 84.995886 -246.538556)
		(end 85.179662 -246.589296)
		(width 0.09525)
		(layer "In13.Cu")
		(net "M_B_CPU1_SA_DQS_DN<4>")
	)
	(arc
		(start 78.249018 -246.574818)
		(mid 78.426723 -246.53834)
		(end 78.600808 -246.589296)
		(width 0.09525)
		(layer "In13.Cu")
		(net "M_B_CPU1_SA_DQS_DN<4>")
	)
	(arc
		(start 81.050892 -246.58447)
		(mid 81.235924 -246.538556)
		(end 81.4197 -246.589296)
		(width 0.09525)
		(layer "In13.Cu")
		(net "M_B_CPU1_SA_DQS_DN<4>")
	)
	(arc
		(start 82.922364 -246.589296)
		(mid 83.106139 -246.538524)
		(end 83.291172 -246.58447)
		(width 0.09525)
		(layer "In13.Cu")
		(net "M_B_CPU1_SA_DQS_DN<4>")
	)
	(arc
		(start 84.239608 -246.589296)
		(mid 84.52104 -246.665051)
		(end 84.802472 -246.589296)
		(width 0.09525)
		(layer "In13.Cu")
		(net "M_B_CPU1_SA_DQS_DN<4>")
	)
	(arc
		(start 86.119716 -246.589296)
		(mid 86.401148 -246.665051)
		(end 86.68258 -246.589296)
		(width 0.09525)
		(layer "In13.Cu")
		(net "M_B_CPU1_SA_DQS_DN<4>")
	)
	(arc
		(start 87.535766 -246.630444)
		(mid 87.546094 -246.626484)
		(end 87.55634 -246.622316)
		(width 0.09525)
		(layer "In13.Cu")
		(net "M_B_CPU1_SA_DQS_DN<4>")
	)
	(arc
		(start 85.179662 -246.589296)
		(mid 85.461094 -246.665051)
		(end 85.742526 -246.589296)
		(width 0.09525)
		(layer "In13.Cu")
		(net "M_B_CPU1_SA_DQS_DN<4>")
	)
	(arc
		(start 86.68258 -246.589296)
		(mid 86.871048 -246.538619)
		(end 87.059516 -246.589296)
		(width 0.09525)
		(layer "In13.Cu")
		(net "M_B_CPU1_SA_DQS_DN<4>")
	)
	(arc
		(start 81.4197 -246.589296)
		(mid 81.701132 -246.665051)
		(end 81.982564 -246.589296)
		(width 0.09525)
		(layer "In13.Cu")
		(net "M_B_CPU1_SA_DQS_DN<4>")
	)
	(arc
		(start 80.102456 -246.589296)
		(mid 80.286231 -246.538524)
		(end 80.471264 -246.58447)
		(width 0.09525)
		(layer "In13.Cu")
		(net "M_B_CPU1_SA_DQS_DN<4>")
	)
	(segment
		(start 88.277954 -242.320318)
		(end 87.811102 -242.05438)
		(width 0.12954)
		(layer "F.Cu")
		(net "M_B_CPU1_SA_DQS_DN<3>")
	)
	(segment
		(start 81.050892 -241.724434)
		(end 81.04251 -241.72926)
		(width 0.09525)
		(layer "In13.Cu")
		(net "M_B_CPU1_SA_DQS_DN<3>")
	)
	(segment
		(start 65.426336 -234.590082)
		(end 65.426336 -234.313476)
		(width 0.16002)
		(layer "In13.Cu")
		(net "M_B_CPU1_SA_DQS_DN<3>")
	)
	(segment
		(start 64.21755 -234.324906)
		(end 63.844678 -233.952034)
		(width 0.16002)
		(layer "In13.Cu")
		(net "M_B_CPU1_SA_DQS_DN<3>")
	)
	(segment
		(start 62.679072 -231.842818)
		(end 62.679072 -231.566212)
		(width 0.16002)
		(layer "In13.Cu")
		(net "M_B_CPU1_SA_DQS_DN<3>")
	)
	(segment
		(start 64.052704 -232.939844)
		(end 63.855854 -232.742994)
		(width 0.16002)
		(layer "In13.Cu")
		(net "M_B_CPU1_SA_DQS_DN<3>")
	)
	(segment
		(start 62.482222 -231.369362)
		(end 62.20587 -231.369362)
		(width 0.16002)
		(layer "In13.Cu")
		(net "M_B_CPU1_SA_DQS_DN<3>")
	)
	(segment
		(start 65.21831 -235.325666)
		(end 65.21831 -234.798108)
		(width 0.16002)
		(layer "In13.Cu")
		(net "M_B_CPU1_SA_DQS_DN<3>")
	)
	(segment
		(start 54.77256 -229.552246)
		(end 54.077362 -229.552246)
		(width 0.16002)
		(layer "In13.Cu")
		(net "M_B_CPU1_SA_DQS_DN<3>")
	)
	(segment
		(start 61.30544 -230.19258)
		(end 61.055504 -229.942644)
		(width 0.16002)
		(layer "In13.Cu")
		(net "M_B_CPU1_SA_DQS_DN<3>")
	)
	(segment
		(start 56.20512 -229.712266)
		(end 56.20512 -229.87635)
		(width 0.16002)
		(layer "In13.Cu")
		(net "M_B_CPU1_SA_DQS_DN<3>")
	)
	(segment
		(start 59.45759 -229.388162)
		(end 59.45759 -229.605586)
		(width 0.16002)
		(layer "In13.Cu")
		(net "M_B_CPU1_SA_DQS_DN<3>")
	)
	(segment
		(start 64.953134 -234.116626)
		(end 64.744854 -234.324906)
		(width 0.16002)
		(layer "In13.Cu")
		(net "M_B_CPU1_SA_DQS_DN<3>")
	)
	(segment
		(start 64.744854 -234.324906)
		(end 64.21755 -234.324906)
		(width 0.16002)
		(layer "In13.Cu")
		(net "M_B_CPU1_SA_DQS_DN<3>")
	)
	(segment
		(start 78.41107 -241.677952)
		(end 77.741272 -241.677952)
		(width 0.09525)
		(layer "In13.Cu")
		(net "M_B_CPU1_SA_DQS_DN<3>")
	)
	(segment
		(start 77.150976 -241.087656)
		(end 76.711302 -241.087656)
		(width 0.09525)
		(layer "In13.Cu")
		(net "M_B_CPU1_SA_DQS_DN<3>")
	)
	(segment
		(start 59.61761 -229.228142)
		(end 59.45759 -229.388162)
		(width 0.16002)
		(layer "In13.Cu")
		(net "M_B_CPU1_SA_DQS_DN<3>")
	)
	(segment
		(start 61.470286 -231.577642)
		(end 61.097414 -231.20477)
		(width 0.16002)
		(layer "In13.Cu")
		(net "M_B_CPU1_SA_DQS_DN<3>")
	)
	(segment
		(start 63.844678 -233.952034)
		(end 63.844678 -233.424476)
		(width 0.16002)
		(layer "In13.Cu")
		(net "M_B_CPU1_SA_DQS_DN<3>")
	)
	(segment
		(start 85.750908 -241.724434)
		(end 85.742526 -241.72926)
		(width 0.09525)
		(layer "In13.Cu")
		(net "M_B_CPU1_SA_DQS_DN<3>")
	)
	(segment
		(start 65.426336 -234.313476)
		(end 65.229486 -234.116626)
		(width 0.16002)
		(layer "In13.Cu")
		(net "M_B_CPU1_SA_DQS_DN<3>")
	)
	(segment
		(start 60.12561 -229.605586)
		(end 60.12561 -229.388162)
		(width 0.16002)
		(layer "In13.Cu")
		(net "M_B_CPU1_SA_DQS_DN<3>")
	)
	(segment
		(start 75.955906 -240.659666)
		(end 70.55231 -240.659666)
		(width 0.16002)
		(layer "In13.Cu")
		(net "M_B_CPU1_SA_DQS_DN<3>")
	)
	(segment
		(start 87.657178 -241.78895)
		(end 87.55634 -241.76228)
		(width 0.09525)
		(layer "In13.Cu")
		(net "M_B_CPU1_SA_DQS_DN<3>")
	)
	(segment
		(start 79.539592 -241.72926)
		(end 79.53121 -241.724434)
		(width 0.09525)
		(layer "In13.Cu")
		(net "M_B_CPU1_SA_DQS_DN<3>")
	)
	(segment
		(start 76.038456 -240.600738)
		(end 75.979528 -240.659666)
		(width 0.09525)
		(layer "In13.Cu")
		(net "M_B_CPU1_SA_DQS_DN<3>")
	)
	(segment
		(start 57.390538 -229.552246)
		(end 56.36514 -229.552246)
		(width 0.16002)
		(layer "In13.Cu")
		(net "M_B_CPU1_SA_DQS_DN<3>")
	)
	(segment
		(start 75.979528 -240.659666)
		(end 75.955906 -240.659666)
		(width 0.09525)
		(layer "In13.Cu")
		(net "M_B_CPU1_SA_DQS_DN<3>")
	)
	(segment
		(start 76.224384 -240.600738)
		(end 76.038456 -240.600738)
		(width 0.09525)
		(layer "In13.Cu")
		(net "M_B_CPU1_SA_DQS_DN<3>")
	)
	(segment
		(start 61.99759 -231.577642)
		(end 61.470286 -231.577642)
		(width 0.16002)
		(layer "In13.Cu")
		(net "M_B_CPU1_SA_DQS_DN<3>")
	)
	(segment
		(start 65.21831 -234.798108)
		(end 65.426336 -234.590082)
		(width 0.16002)
		(layer "In13.Cu")
		(net "M_B_CPU1_SA_DQS_DN<3>")
	)
	(segment
		(start 61.30544 -230.469186)
		(end 61.30544 -230.19258)
		(width 0.16002)
		(layer "In13.Cu")
		(net "M_B_CPU1_SA_DQS_DN<3>")
	)
	(segment
		(start 63.855854 -232.742994)
		(end 63.579502 -232.742994)
		(width 0.16002)
		(layer "In13.Cu")
		(net "M_B_CPU1_SA_DQS_DN<3>")
	)
	(segment
		(start 87.811102 -242.05438)
		(end 87.657178 -241.78895)
		(width 0.09525)
		(layer "In13.Cu")
		(net "M_B_CPU1_SA_DQS_DN<3>")
	)
	(segment
		(start 54.93258 -229.87635)
		(end 54.93258 -229.712266)
		(width 0.16002)
		(layer "In13.Cu")
		(net "M_B_CPU1_SA_DQS_DN<3>")
	)
	(segment
		(start 54.077362 -229.552246)
		(end 53.890672 -229.365556)
		(width 0.16002)
		(layer "In13.Cu")
		(net "M_B_CPU1_SA_DQS_DN<3>")
	)
	(segment
		(start 62.843918 -232.951274)
		(end 62.471046 -232.578402)
		(width 0.16002)
		(layer "In13.Cu")
		(net "M_B_CPU1_SA_DQS_DN<3>")
	)
	(segment
		(start 56.36514 -229.552246)
		(end 56.20512 -229.712266)
		(width 0.16002)
		(layer "In13.Cu")
		(net "M_B_CPU1_SA_DQS_DN<3>")
	)
	(segment
		(start 59.45759 -229.605586)
		(end 59.120532 -229.942644)
		(width 0.16002)
		(layer "In13.Cu")
		(net "M_B_CPU1_SA_DQS_DN<3>")
	)
	(segment
		(start 61.097414 -231.20477)
		(end 61.097414 -230.677212)
		(width 0.16002)
		(layer "In13.Cu")
		(net "M_B_CPU1_SA_DQS_DN<3>")
	)
	(segment
		(start 57.780936 -229.942644)
		(end 57.390538 -229.552246)
		(width 0.16002)
		(layer "In13.Cu")
		(net "M_B_CPU1_SA_DQS_DN<3>")
	)
	(segment
		(start 70.55231 -240.659666)
		(end 65.21831 -235.325666)
		(width 0.16002)
		(layer "In13.Cu")
		(net "M_B_CPU1_SA_DQS_DN<3>")
	)
	(segment
		(start 60.462668 -229.942644)
		(end 60.12561 -229.605586)
		(width 0.16002)
		(layer "In13.Cu")
		(net "M_B_CPU1_SA_DQS_DN<3>")
	)
	(segment
		(start 65.229486 -234.116626)
		(end 64.953134 -234.116626)
		(width 0.16002)
		(layer "In13.Cu")
		(net "M_B_CPU1_SA_DQS_DN<3>")
	)
	(segment
		(start 80.479646 -241.72926)
		(end 80.471264 -241.724434)
		(width 0.09525)
		(layer "In13.Cu")
		(net "M_B_CPU1_SA_DQS_DN<3>")
	)
	(segment
		(start 63.844678 -233.424476)
		(end 64.052704 -233.21645)
		(width 0.16002)
		(layer "In13.Cu")
		(net "M_B_CPU1_SA_DQS_DN<3>")
	)
	(segment
		(start 77.741272 -241.677952)
		(end 77.150976 -241.087656)
		(width 0.09525)
		(layer "In13.Cu")
		(net "M_B_CPU1_SA_DQS_DN<3>")
	)
	(segment
		(start 61.097414 -230.677212)
		(end 61.30544 -230.469186)
		(width 0.16002)
		(layer "In13.Cu")
		(net "M_B_CPU1_SA_DQS_DN<3>")
	)
	(segment
		(start 59.120532 -229.942644)
		(end 57.780936 -229.942644)
		(width 0.16002)
		(layer "In13.Cu")
		(net "M_B_CPU1_SA_DQS_DN<3>")
	)
	(segment
		(start 62.20587 -231.369362)
		(end 61.99759 -231.577642)
		(width 0.16002)
		(layer "In13.Cu")
		(net "M_B_CPU1_SA_DQS_DN<3>")
	)
	(segment
		(start 62.471046 -232.050844)
		(end 62.679072 -231.842818)
		(width 0.16002)
		(layer "In13.Cu")
		(net "M_B_CPU1_SA_DQS_DN<3>")
	)
	(segment
		(start 76.711302 -241.087656)
		(end 76.224384 -240.600738)
		(width 0.09525)
		(layer "In13.Cu")
		(net "M_B_CPU1_SA_DQS_DN<3>")
	)
	(segment
		(start 61.055504 -229.942644)
		(end 60.462668 -229.942644)
		(width 0.16002)
		(layer "In13.Cu")
		(net "M_B_CPU1_SA_DQS_DN<3>")
	)
	(segment
		(start 64.052704 -233.21645)
		(end 64.052704 -232.939844)
		(width 0.16002)
		(layer "In13.Cu")
		(net "M_B_CPU1_SA_DQS_DN<3>")
	)
	(segment
		(start 84.239608 -241.72926)
		(end 84.231226 -241.724434)
		(width 0.09525)
		(layer "In13.Cu")
		(net "M_B_CPU1_SA_DQS_DN<3>")
	)
	(segment
		(start 56.20512 -229.87635)
		(end 55.868062 -230.213408)
		(width 0.16002)
		(layer "In13.Cu")
		(net "M_B_CPU1_SA_DQS_DN<3>")
	)
	(segment
		(start 63.371222 -232.951274)
		(end 62.843918 -232.951274)
		(width 0.16002)
		(layer "In13.Cu")
		(net "M_B_CPU1_SA_DQS_DN<3>")
	)
	(segment
		(start 83.299554 -241.72926)
		(end 83.291172 -241.724434)
		(width 0.09525)
		(layer "In13.Cu")
		(net "M_B_CPU1_SA_DQS_DN<3>")
	)
	(segment
		(start 53.890672 -229.365556)
		(end 52.15382 -229.365556)
		(width 0.16002)
		(layer "In13.Cu")
		(net "M_B_CPU1_SA_DQS_DN<3>")
	)
	(segment
		(start 55.269638 -230.213408)
		(end 54.93258 -229.87635)
		(width 0.16002)
		(layer "In13.Cu")
		(net "M_B_CPU1_SA_DQS_DN<3>")
	)
	(segment
		(start 60.12561 -229.388162)
		(end 59.96559 -229.228142)
		(width 0.16002)
		(layer "In13.Cu")
		(net "M_B_CPU1_SA_DQS_DN<3>")
	)
	(segment
		(start 62.471046 -232.578402)
		(end 62.471046 -232.050844)
		(width 0.16002)
		(layer "In13.Cu")
		(net "M_B_CPU1_SA_DQS_DN<3>")
	)
	(segment
		(start 59.96559 -229.228142)
		(end 59.61761 -229.228142)
		(width 0.16002)
		(layer "In13.Cu")
		(net "M_B_CPU1_SA_DQS_DN<3>")
	)
	(segment
		(start 62.679072 -231.566212)
		(end 62.482222 -231.369362)
		(width 0.16002)
		(layer "In13.Cu")
		(net "M_B_CPU1_SA_DQS_DN<3>")
	)
	(segment
		(start 84.810854 -241.724434)
		(end 84.802472 -241.72926)
		(width 0.09525)
		(layer "In13.Cu")
		(net "M_B_CPU1_SA_DQS_DN<3>")
	)
	(segment
		(start 54.93258 -229.712266)
		(end 54.77256 -229.552246)
		(width 0.16002)
		(layer "In13.Cu")
		(net "M_B_CPU1_SA_DQS_DN<3>")
	)
	(segment
		(start 63.579502 -232.742994)
		(end 63.371222 -232.951274)
		(width 0.16002)
		(layer "In13.Cu")
		(net "M_B_CPU1_SA_DQS_DN<3>")
	)
	(segment
		(start 55.868062 -230.213408)
		(end 55.269638 -230.213408)
		(width 0.16002)
		(layer "In13.Cu")
		(net "M_B_CPU1_SA_DQS_DN<3>")
	)
	(segment
		(start 52.15382 -229.365556)
		(end 51.884072 -229.635304)
		(width 0.16002)
		(layer "In13.Cu")
		(net "M_B_CPU1_SA_DQS_DN<3>")
	)
	(arc
		(start 80.471264 -241.724434)
		(mid 80.286232 -241.67852)
		(end 80.102456 -241.72926)
		(width 0.09525)
		(layer "In13.Cu")
		(net "M_B_CPU1_SA_DQS_DN<3>")
	)
	(arc
		(start 86.68258 -241.72926)
		(mid 86.401148 -241.805015)
		(end 86.119716 -241.72926)
		(width 0.09525)
		(layer "In13.Cu")
		(net "M_B_CPU1_SA_DQS_DN<3>")
	)
	(arc
		(start 84.231226 -241.724434)
		(mid 84.046194 -241.67852)
		(end 83.862418 -241.72926)
		(width 0.09525)
		(layer "In13.Cu")
		(net "M_B_CPU1_SA_DQS_DN<3>")
	)
	(arc
		(start 87.55634 -241.76228)
		(mid 87.546092 -241.766443)
		(end 87.535766 -241.770408)
		(width 0.09525)
		(layer "In13.Cu")
		(net "M_B_CPU1_SA_DQS_DN<3>")
	)
	(arc
		(start 81.04251 -241.72926)
		(mid 80.761078 -241.805015)
		(end 80.479646 -241.72926)
		(width 0.09525)
		(layer "In13.Cu")
		(net "M_B_CPU1_SA_DQS_DN<3>")
	)
	(arc
		(start 81.4197 -241.72926)
		(mid 81.235925 -241.678488)
		(end 81.050892 -241.724434)
		(width 0.09525)
		(layer "In13.Cu")
		(net "M_B_CPU1_SA_DQS_DN<3>")
	)
	(arc
		(start 80.102456 -241.72926)
		(mid 79.821024 -241.805015)
		(end 79.539592 -241.72926)
		(width 0.09525)
		(layer "In13.Cu")
		(net "M_B_CPU1_SA_DQS_DN<3>")
	)
	(arc
		(start 86.119716 -241.72926)
		(mid 85.935941 -241.678488)
		(end 85.750908 -241.724434)
		(width 0.09525)
		(layer "In13.Cu")
		(net "M_B_CPU1_SA_DQS_DN<3>")
	)
	(arc
		(start 79.53121 -241.724434)
		(mid 79.346178 -241.67852)
		(end 79.162402 -241.72926)
		(width 0.09525)
		(layer "In13.Cu")
		(net "M_B_CPU1_SA_DQS_DN<3>")
	)
	(arc
		(start 83.862418 -241.72926)
		(mid 83.580986 -241.805015)
		(end 83.299554 -241.72926)
		(width 0.09525)
		(layer "In13.Cu")
		(net "M_B_CPU1_SA_DQS_DN<3>")
	)
	(arc
		(start 78.599538 -241.72926)
		(mid 78.508695 -241.691141)
		(end 78.41107 -241.677952)
		(width 0.09525)
		(layer "In13.Cu")
		(net "M_B_CPU1_SA_DQS_DN<3>")
	)
	(arc
		(start 84.802472 -241.72926)
		(mid 84.52104 -241.805015)
		(end 84.239608 -241.72926)
		(width 0.09525)
		(layer "In13.Cu")
		(net "M_B_CPU1_SA_DQS_DN<3>")
	)
	(arc
		(start 81.982564 -241.72926)
		(mid 81.701132 -241.805015)
		(end 81.4197 -241.72926)
		(width 0.09525)
		(layer "In13.Cu")
		(net "M_B_CPU1_SA_DQS_DN<3>")
	)
	(arc
		(start 87.535766 -241.770408)
		(mid 87.293024 -241.803178)
		(end 87.059516 -241.72926)
		(width 0.09525)
		(layer "In13.Cu")
		(net "M_B_CPU1_SA_DQS_DN<3>")
	)
	(arc
		(start 83.291172 -241.724434)
		(mid 83.10614 -241.67852)
		(end 82.922364 -241.72926)
		(width 0.09525)
		(layer "In13.Cu")
		(net "M_B_CPU1_SA_DQS_DN<3>")
	)
	(arc
		(start 85.179662 -241.72926)
		(mid 84.995887 -241.678488)
		(end 84.810854 -241.724434)
		(width 0.09525)
		(layer "In13.Cu")
		(net "M_B_CPU1_SA_DQS_DN<3>")
	)
	(arc
		(start 82.922364 -241.72926)
		(mid 82.640932 -241.805015)
		(end 82.3595 -241.72926)
		(width 0.09525)
		(layer "In13.Cu")
		(net "M_B_CPU1_SA_DQS_DN<3>")
	)
	(arc
		(start 82.3595 -241.72926)
		(mid 82.171032 -241.678583)
		(end 81.982564 -241.72926)
		(width 0.09525)
		(layer "In13.Cu")
		(net "M_B_CPU1_SA_DQS_DN<3>")
	)
	(arc
		(start 85.742526 -241.72926)
		(mid 85.461094 -241.805015)
		(end 85.179662 -241.72926)
		(width 0.09525)
		(layer "In13.Cu")
		(net "M_B_CPU1_SA_DQS_DN<3>")
	)
	(arc
		(start 87.059516 -241.72926)
		(mid 86.871048 -241.678583)
		(end 86.68258 -241.72926)
		(width 0.09525)
		(layer "In13.Cu")
		(net "M_B_CPU1_SA_DQS_DN<3>")
	)
	(arc
		(start 79.162402 -241.72926)
		(mid 78.88097 -241.805015)
		(end 78.599538 -241.72926)
		(width 0.09525)
		(layer "In13.Cu")
		(net "M_B_CPU1_SA_DQS_DN<3>")
	)
	(segment
		(start 88.277954 -237.460282)
		(end 87.811102 -237.194344)
		(width 0.12954)
		(layer "F.Cu")
		(net "M_B_CPU1_SA_DQS_DN<2>")
	)
	(segment
		(start 65.460118 -225.129344)
		(end 65.736978 -225.129344)
		(width 0.16002)
		(layer "In13.Cu")
		(net "M_B_CPU1_SA_DQS_DN<2>")
	)
	(segment
		(start 62.30112 -222.793814)
		(end 62.712854 -222.38208)
		(width 0.16002)
		(layer "In13.Cu")
		(net "M_B_CPU1_SA_DQS_DN<2>")
	)
	(segment
		(start 79.141574 -236.882686)
		(end 79.164942 -236.869224)
		(width 0.09525)
		(layer "In13.Cu")
		(net "M_B_CPU1_SA_DQS_DN<2>")
	)
	(segment
		(start 64.147954 -224.640902)
		(end 64.147954 -225.168206)
		(width 0.16002)
		(layer "In13.Cu")
		(net "M_B_CPU1_SA_DQS_DN<2>")
	)
	(segment
		(start 63.18631 -222.578676)
		(end 63.18631 -222.855282)
		(width 0.16002)
		(layer "In13.Cu")
		(net "M_B_CPU1_SA_DQS_DN<2>")
	)
	(segment
		(start 62.989714 -222.38208)
		(end 63.18631 -222.578676)
		(width 0.16002)
		(layer "In13.Cu")
		(net "M_B_CPU1_SA_DQS_DN<2>")
	)
	(segment
		(start 76.03871 -234.977178)
		(end 76.173584 -234.977178)
		(width 0.09525)
		(layer "In13.Cu")
		(net "M_B_CPU1_SA_DQS_DN<2>")
	)
	(segment
		(start 64.086486 -223.755712)
		(end 64.363346 -223.755712)
		(width 0.16002)
		(layer "In13.Cu")
		(net "M_B_CPU1_SA_DQS_DN<2>")
	)
	(segment
		(start 76.268834 -235.28147)
		(end 76.69784 -235.710476)
		(width 0.09525)
		(layer "In13.Cu")
		(net "M_B_CPU1_SA_DQS_DN<2>")
	)
	(segment
		(start 63.674752 -224.167446)
		(end 64.086486 -223.755712)
		(width 0.16002)
		(layer "In13.Cu")
		(net "M_B_CPU1_SA_DQS_DN<2>")
	)
	(segment
		(start 74.01052 -235.03636)
		(end 75.955906 -235.03636)
		(width 0.16002)
		(layer "In13.Cu")
		(net "M_B_CPU1_SA_DQS_DN<2>")
	)
	(segment
		(start 79.526638 -236.860842)
		(end 79.541116 -236.869224)
		(width 0.09525)
		(layer "In13.Cu")
		(net "M_B_CPU1_SA_DQS_DN<2>")
	)
	(segment
		(start 61.773562 -222.793814)
		(end 62.30112 -222.793814)
		(width 0.16002)
		(layer "In13.Cu")
		(net "M_B_CPU1_SA_DQS_DN<2>")
	)
	(segment
		(start 65.933574 -225.602546)
		(end 65.521586 -226.014534)
		(width 0.16002)
		(layer "In13.Cu")
		(net "M_B_CPU1_SA_DQS_DN<2>")
	)
	(segment
		(start 65.048384 -225.541078)
		(end 65.460118 -225.129344)
		(width 0.16002)
		(layer "In13.Cu")
		(net "M_B_CPU1_SA_DQS_DN<2>")
	)
	(segment
		(start 63.147194 -224.167446)
		(end 63.674752 -224.167446)
		(width 0.16002)
		(layer "In13.Cu")
		(net "M_B_CPU1_SA_DQS_DN<2>")
	)
	(segment
		(start 63.18631 -222.855282)
		(end 62.774322 -223.26727)
		(width 0.16002)
		(layer "In13.Cu")
		(net "M_B_CPU1_SA_DQS_DN<2>")
	)
	(segment
		(start 77.05344 -235.710476)
		(end 78.160118 -236.817154)
		(width 0.09525)
		(layer "In13.Cu")
		(net "M_B_CPU1_SA_DQS_DN<2>")
	)
	(segment
		(start 66.895218 -227.287836)
		(end 66.895218 -227.921058)
		(width 0.16002)
		(layer "In13.Cu")
		(net "M_B_CPU1_SA_DQS_DN<2>")
	)
	(segment
		(start 59.969908 -220.620844)
		(end 61.33465 -221.985586)
		(width 0.16002)
		(layer "In13.Cu")
		(net "M_B_CPU1_SA_DQS_DN<2>")
	)
	(segment
		(start 62.712854 -222.38208)
		(end 62.989714 -222.38208)
		(width 0.16002)
		(layer "In13.Cu")
		(net "M_B_CPU1_SA_DQS_DN<2>")
	)
	(segment
		(start 65.736978 -225.129344)
		(end 65.933574 -225.32594)
		(width 0.16002)
		(layer "In13.Cu")
		(net "M_B_CPU1_SA_DQS_DN<2>")
	)
	(segment
		(start 75.979528 -235.03636)
		(end 76.03871 -234.977178)
		(width 0.09525)
		(layer "In13.Cu")
		(net "M_B_CPU1_SA_DQS_DN<2>")
	)
	(segment
		(start 87.657178 -236.928914)
		(end 87.811102 -237.194344)
		(width 0.09525)
		(layer "In13.Cu")
		(net "M_B_CPU1_SA_DQS_DN<2>")
	)
	(segment
		(start 64.520826 -225.541078)
		(end 65.048384 -225.541078)
		(width 0.16002)
		(layer "In13.Cu")
		(net "M_B_CPU1_SA_DQS_DN<2>")
	)
	(segment
		(start 65.894458 -226.91471)
		(end 66.522092 -226.91471)
		(width 0.16002)
		(layer "In13.Cu")
		(net "M_B_CPU1_SA_DQS_DN<2>")
	)
	(segment
		(start 78.160118 -236.817154)
		(end 78.41107 -236.817154)
		(width 0.09525)
		(layer "In13.Cu")
		(net "M_B_CPU1_SA_DQS_DN<2>")
	)
	(segment
		(start 64.559942 -224.228914)
		(end 64.147954 -224.640902)
		(width 0.16002)
		(layer "In13.Cu")
		(net "M_B_CPU1_SA_DQS_DN<2>")
	)
	(segment
		(start 79.541116 -236.869224)
		(end 79.566516 -236.883956)
		(width 0.09525)
		(layer "In13.Cu")
		(net "M_B_CPU1_SA_DQS_DN<2>")
	)
	(segment
		(start 76.173584 -234.977178)
		(end 76.268834 -235.072428)
		(width 0.09525)
		(layer "In13.Cu")
		(net "M_B_CPU1_SA_DQS_DN<2>")
	)
	(segment
		(start 65.933574 -225.32594)
		(end 65.933574 -225.602546)
		(width 0.16002)
		(layer "In13.Cu")
		(net "M_B_CPU1_SA_DQS_DN<2>")
	)
	(segment
		(start 66.522092 -226.91471)
		(end 66.895218 -227.287836)
		(width 0.16002)
		(layer "In13.Cu")
		(net "M_B_CPU1_SA_DQS_DN<2>")
	)
	(segment
		(start 51.884072 -220.28531)
		(end 52.166774 -220.002608)
		(width 0.16002)
		(layer "In13.Cu")
		(net "M_B_CPU1_SA_DQS_DN<2>")
	)
	(segment
		(start 64.147954 -225.168206)
		(end 64.520826 -225.541078)
		(width 0.16002)
		(layer "In13.Cu")
		(net "M_B_CPU1_SA_DQS_DN<2>")
	)
	(segment
		(start 83.291172 -236.864398)
		(end 83.299554 -236.869224)
		(width 0.09525)
		(layer "In13.Cu")
		(net "M_B_CPU1_SA_DQS_DN<2>")
	)
	(segment
		(start 84.802472 -236.869224)
		(end 84.810854 -236.864398)
		(width 0.09525)
		(layer "In13.Cu")
		(net "M_B_CPU1_SA_DQS_DN<2>")
	)
	(segment
		(start 76.268834 -235.072428)
		(end 76.268834 -235.28147)
		(width 0.09525)
		(layer "In13.Cu")
		(net "M_B_CPU1_SA_DQS_DN<2>")
	)
	(segment
		(start 61.33465 -222.354902)
		(end 61.773562 -222.793814)
		(width 0.16002)
		(layer "In13.Cu")
		(net "M_B_CPU1_SA_DQS_DN<2>")
	)
	(segment
		(start 61.33465 -221.985586)
		(end 61.33465 -222.354902)
		(width 0.16002)
		(layer "In13.Cu")
		(net "M_B_CPU1_SA_DQS_DN<2>")
	)
	(segment
		(start 81.04251 -236.869224)
		(end 81.050892 -236.864398)
		(width 0.09525)
		(layer "In13.Cu")
		(net "M_B_CPU1_SA_DQS_DN<2>")
	)
	(segment
		(start 80.471264 -236.864398)
		(end 80.479646 -236.869224)
		(width 0.09525)
		(layer "In13.Cu")
		(net "M_B_CPU1_SA_DQS_DN<2>")
	)
	(segment
		(start 62.774322 -223.794574)
		(end 63.147194 -224.167446)
		(width 0.16002)
		(layer "In13.Cu")
		(net "M_B_CPU1_SA_DQS_DN<2>")
	)
	(segment
		(start 64.559942 -223.952308)
		(end 64.559942 -224.228914)
		(width 0.16002)
		(layer "In13.Cu")
		(net "M_B_CPU1_SA_DQS_DN<2>")
	)
	(segment
		(start 84.231226 -236.864398)
		(end 84.239608 -236.869224)
		(width 0.09525)
		(layer "In13.Cu")
		(net "M_B_CPU1_SA_DQS_DN<2>")
	)
	(segment
		(start 52.166774 -220.002608)
		(end 54.525926 -220.002608)
		(width 0.16002)
		(layer "In13.Cu")
		(net "M_B_CPU1_SA_DQS_DN<2>")
	)
	(segment
		(start 65.521586 -226.014534)
		(end 65.521586 -226.541838)
		(width 0.16002)
		(layer "In13.Cu")
		(net "M_B_CPU1_SA_DQS_DN<2>")
	)
	(segment
		(start 85.742526 -236.869224)
		(end 85.750908 -236.864398)
		(width 0.09525)
		(layer "In13.Cu")
		(net "M_B_CPU1_SA_DQS_DN<2>")
	)
	(segment
		(start 55.144162 -220.620844)
		(end 59.969908 -220.620844)
		(width 0.16002)
		(layer "In13.Cu")
		(net "M_B_CPU1_SA_DQS_DN<2>")
	)
	(segment
		(start 75.955906 -235.03636)
		(end 75.979528 -235.03636)
		(width 0.09525)
		(layer "In13.Cu")
		(net "M_B_CPU1_SA_DQS_DN<2>")
	)
	(segment
		(start 66.895218 -227.921058)
		(end 74.01052 -235.03636)
		(width 0.16002)
		(layer "In13.Cu")
		(net "M_B_CPU1_SA_DQS_DN<2>")
	)
	(segment
		(start 87.55634 -236.902244)
		(end 87.657178 -236.928914)
		(width 0.09525)
		(layer "In13.Cu")
		(net "M_B_CPU1_SA_DQS_DN<2>")
	)
	(segment
		(start 76.69784 -235.710476)
		(end 77.05344 -235.710476)
		(width 0.09525)
		(layer "In13.Cu")
		(net "M_B_CPU1_SA_DQS_DN<2>")
	)
	(segment
		(start 64.363346 -223.755712)
		(end 64.559942 -223.952308)
		(width 0.16002)
		(layer "In13.Cu")
		(net "M_B_CPU1_SA_DQS_DN<2>")
	)
	(segment
		(start 62.774322 -223.26727)
		(end 62.774322 -223.794574)
		(width 0.16002)
		(layer "In13.Cu")
		(net "M_B_CPU1_SA_DQS_DN<2>")
	)
	(segment
		(start 65.521586 -226.541838)
		(end 65.894458 -226.91471)
		(width 0.16002)
		(layer "In13.Cu")
		(net "M_B_CPU1_SA_DQS_DN<2>")
	)
	(segment
		(start 54.525926 -220.002608)
		(end 55.144162 -220.620844)
		(width 0.16002)
		(layer "In13.Cu")
		(net "M_B_CPU1_SA_DQS_DN<2>")
	)
	(arc
		(start 85.750908 -236.864398)
		(mid 85.93594 -236.818484)
		(end 86.119716 -236.869224)
		(width 0.09525)
		(layer "In13.Cu")
		(net "M_B_CPU1_SA_DQS_DN<2>")
	)
	(arc
		(start 82.922364 -236.869224)
		(mid 83.106139 -236.818452)
		(end 83.291172 -236.864398)
		(width 0.09525)
		(layer "In13.Cu")
		(net "M_B_CPU1_SA_DQS_DN<2>")
	)
	(arc
		(start 87.535766 -236.910372)
		(mid 87.546094 -236.906412)
		(end 87.55634 -236.902244)
		(width 0.09525)
		(layer "In13.Cu")
		(net "M_B_CPU1_SA_DQS_DN<2>")
	)
	(arc
		(start 79.164942 -236.869224)
		(mid 79.344714 -236.818648)
		(end 79.526638 -236.860842)
		(width 0.09525)
		(layer "In13.Cu")
		(net "M_B_CPU1_SA_DQS_DN<2>")
	)
	(arc
		(start 84.810854 -236.864398)
		(mid 84.995886 -236.818484)
		(end 85.179662 -236.869224)
		(width 0.09525)
		(layer "In13.Cu")
		(net "M_B_CPU1_SA_DQS_DN<2>")
	)
	(arc
		(start 83.862418 -236.869224)
		(mid 84.046193 -236.818452)
		(end 84.231226 -236.864398)
		(width 0.09525)
		(layer "In13.Cu")
		(net "M_B_CPU1_SA_DQS_DN<2>")
	)
	(arc
		(start 78.41107 -236.817154)
		(mid 78.509408 -236.83056)
		(end 78.600808 -236.869224)
		(width 0.09525)
		(layer "In13.Cu")
		(net "M_B_CPU1_SA_DQS_DN<2>")
	)
	(arc
		(start 83.299554 -236.869224)
		(mid 83.580986 -236.944979)
		(end 83.862418 -236.869224)
		(width 0.09525)
		(layer "In13.Cu")
		(net "M_B_CPU1_SA_DQS_DN<2>")
	)
	(arc
		(start 81.050892 -236.864398)
		(mid 81.235924 -236.818484)
		(end 81.4197 -236.869224)
		(width 0.09525)
		(layer "In13.Cu")
		(net "M_B_CPU1_SA_DQS_DN<2>")
	)
	(arc
		(start 80.102456 -236.869224)
		(mid 80.286231 -236.818452)
		(end 80.471264 -236.864398)
		(width 0.09525)
		(layer "In13.Cu")
		(net "M_B_CPU1_SA_DQS_DN<2>")
	)
	(arc
		(start 79.566516 -236.883956)
		(mid 79.83637 -236.944835)
		(end 80.102456 -236.869224)
		(width 0.09525)
		(layer "In13.Cu")
		(net "M_B_CPU1_SA_DQS_DN<2>")
	)
	(arc
		(start 78.600808 -236.869224)
		(mid 78.869471 -236.945442)
		(end 79.141574 -236.882686)
		(width 0.09525)
		(layer "In13.Cu")
		(net "M_B_CPU1_SA_DQS_DN<2>")
	)
	(arc
		(start 81.4197 -236.869224)
		(mid 81.701132 -236.944979)
		(end 81.982564 -236.869224)
		(width 0.09525)
		(layer "In13.Cu")
		(net "M_B_CPU1_SA_DQS_DN<2>")
	)
	(arc
		(start 82.3595 -236.869224)
		(mid 82.640932 -236.944979)
		(end 82.922364 -236.869224)
		(width 0.09525)
		(layer "In13.Cu")
		(net "M_B_CPU1_SA_DQS_DN<2>")
	)
	(arc
		(start 85.179662 -236.869224)
		(mid 85.461094 -236.944979)
		(end 85.742526 -236.869224)
		(width 0.09525)
		(layer "In13.Cu")
		(net "M_B_CPU1_SA_DQS_DN<2>")
	)
	(arc
		(start 86.119716 -236.869224)
		(mid 86.401148 -236.944979)
		(end 86.68258 -236.869224)
		(width 0.09525)
		(layer "In13.Cu")
		(net "M_B_CPU1_SA_DQS_DN<2>")
	)
	(arc
		(start 84.239608 -236.869224)
		(mid 84.52104 -236.944979)
		(end 84.802472 -236.869224)
		(width 0.09525)
		(layer "In13.Cu")
		(net "M_B_CPU1_SA_DQS_DN<2>")
	)
	(arc
		(start 80.479646 -236.869224)
		(mid 80.761078 -236.944979)
		(end 81.04251 -236.869224)
		(width 0.09525)
		(layer "In13.Cu")
		(net "M_B_CPU1_SA_DQS_DN<2>")
	)
	(arc
		(start 86.68258 -236.869224)
		(mid 86.871048 -236.818547)
		(end 87.059516 -236.869224)
		(width 0.09525)
		(layer "In13.Cu")
		(net "M_B_CPU1_SA_DQS_DN<2>")
	)
	(arc
		(start 81.982564 -236.869224)
		(mid 82.171032 -236.818547)
		(end 82.3595 -236.869224)
		(width 0.09525)
		(layer "In13.Cu")
		(net "M_B_CPU1_SA_DQS_DN<2>")
	)
	(arc
		(start 87.059516 -236.869224)
		(mid 87.29303 -236.943067)
		(end 87.535766 -236.910372)
		(width 0.09525)
		(layer "In13.Cu")
		(net "M_B_CPU1_SA_DQS_DN<2>")
	)
	(segment
		(start 88.277954 -232.600246)
		(end 87.811102 -232.334308)
		(width 0.12954)
		(layer "F.Cu")
		(net "M_B_CPU1_SA_DQS_DN<1>")
	)
	(segment
		(start 67.755262 -219.185998)
		(end 68.282566 -219.185998)
		(width 0.16002)
		(layer "In13.Cu")
		(net "M_B_CPU1_SA_DQS_DN<1>")
	)
	(segment
		(start 67.48907 -217.902282)
		(end 67.48907 -218.179142)
		(width 0.16002)
		(layer "In13.Cu")
		(net "M_B_CPU1_SA_DQS_DN<1>")
	)
	(segment
		(start 87.657178 -232.068878)
		(end 87.811102 -232.334308)
		(width 0.09525)
		(layer "In13.Cu")
		(net "M_B_CPU1_SA_DQS_DN<1>")
	)
	(segment
		(start 71.41337 -221.826582)
		(end 71.609966 -222.023178)
		(width 0.16002)
		(layer "In13.Cu")
		(net "M_B_CPU1_SA_DQS_DN<1>")
	)
	(segment
		(start 51.884072 -210.935316)
		(end 52.173124 -210.646264)
		(width 0.16002)
		(layer "In13.Cu")
		(net "M_B_CPU1_SA_DQS_DN<1>")
	)
	(segment
		(start 83.291172 -232.004362)
		(end 83.299554 -232.009188)
		(width 0.09525)
		(layer "In13.Cu")
		(net "M_B_CPU1_SA_DQS_DN<1>")
	)
	(segment
		(start 69.656198 -220.55963)
		(end 69.762878 -220.45295)
		(width 0.16002)
		(layer "In13.Cu")
		(net "M_B_CPU1_SA_DQS_DN<1>")
	)
	(segment
		(start 54.360826 -210.646264)
		(end 54.985666 -211.271104)
		(width 0.16002)
		(layer "In13.Cu")
		(net "M_B_CPU1_SA_DQS_DN<1>")
	)
	(segment
		(start 69.762878 -220.45295)
		(end 70.039738 -220.45295)
		(width 0.16002)
		(layer "In13.Cu")
		(net "M_B_CPU1_SA_DQS_DN<1>")
	)
	(segment
		(start 67.48907 -218.179142)
		(end 67.38239 -218.285822)
		(width 0.16002)
		(layer "In13.Cu")
		(net "M_B_CPU1_SA_DQS_DN<1>")
	)
	(segment
		(start 78.76794 -231.264206)
		(end 79.42453 -231.920796)
		(width 0.09525)
		(layer "In13.Cu")
		(net "M_B_CPU1_SA_DQS_DN<1>")
	)
	(segment
		(start 71.609966 -222.023178)
		(end 71.609966 -222.300038)
		(width 0.16002)
		(layer "In13.Cu")
		(net "M_B_CPU1_SA_DQS_DN<1>")
	)
	(segment
		(start 63.368174 -213.781386)
		(end 63.368174 -214.058246)
		(width 0.16002)
		(layer "In13.Cu")
		(net "M_B_CPU1_SA_DQS_DN<1>")
	)
	(segment
		(start 62.260734 -213.69147)
		(end 62.788038 -213.69147)
		(width 0.16002)
		(layer "In13.Cu")
		(net "M_B_CPU1_SA_DQS_DN<1>")
	)
	(segment
		(start 59.301126 -211.271104)
		(end 60.221622 -211.652358)
		(width 0.16002)
		(layer "In13.Cu")
		(net "M_B_CPU1_SA_DQS_DN<1>")
	)
	(segment
		(start 67.38239 -218.813126)
		(end 67.755262 -219.185998)
		(width 0.16002)
		(layer "In13.Cu")
		(net "M_B_CPU1_SA_DQS_DN<1>")
	)
	(segment
		(start 63.261494 -214.164926)
		(end 63.261494 -214.69223)
		(width 0.16002)
		(layer "In13.Cu")
		(net "M_B_CPU1_SA_DQS_DN<1>")
	)
	(segment
		(start 84.231226 -232.004362)
		(end 84.239608 -232.009188)
		(width 0.09525)
		(layer "In13.Cu")
		(net "M_B_CPU1_SA_DQS_DN<1>")
	)
	(segment
		(start 68.666106 -219.079318)
		(end 68.862702 -219.275914)
		(width 0.16002)
		(layer "In13.Cu")
		(net "M_B_CPU1_SA_DQS_DN<1>")
	)
	(segment
		(start 77.38237 -229.633526)
		(end 78.08214 -230.333296)
		(width 0.09525)
		(layer "In13.Cu")
		(net "M_B_CPU1_SA_DQS_DN<1>")
	)
	(segment
		(start 52.173124 -210.646264)
		(end 54.360826 -210.646264)
		(width 0.16002)
		(layer "In13.Cu")
		(net "M_B_CPU1_SA_DQS_DN<1>")
	)
	(segment
		(start 68.756022 -219.659454)
		(end 68.756022 -220.186758)
		(width 0.16002)
		(layer "In13.Cu")
		(net "M_B_CPU1_SA_DQS_DN<1>")
	)
	(segment
		(start 66.908934 -217.812366)
		(end 67.015614 -217.705686)
		(width 0.16002)
		(layer "In13.Cu")
		(net "M_B_CPU1_SA_DQS_DN<1>")
	)
	(segment
		(start 67.292474 -217.705686)
		(end 67.48907 -217.902282)
		(width 0.16002)
		(layer "In13.Cu")
		(net "M_B_CPU1_SA_DQS_DN<1>")
	)
	(segment
		(start 64.741806 -215.431878)
		(end 64.635126 -215.538558)
		(width 0.16002)
		(layer "In13.Cu")
		(net "M_B_CPU1_SA_DQS_DN<1>")
	)
	(segment
		(start 81.04251 -232.009188)
		(end 81.050892 -232.004362)
		(width 0.09525)
		(layer "In13.Cu")
		(net "M_B_CPU1_SA_DQS_DN<1>")
	)
	(segment
		(start 64.741806 -215.155018)
		(end 64.741806 -215.431878)
		(width 0.16002)
		(layer "In13.Cu")
		(net "M_B_CPU1_SA_DQS_DN<1>")
	)
	(segment
		(start 62.788038 -213.69147)
		(end 62.894718 -213.58479)
		(width 0.16002)
		(layer "In13.Cu")
		(net "M_B_CPU1_SA_DQS_DN<1>")
	)
	(segment
		(start 68.756022 -220.186758)
		(end 69.128894 -220.55963)
		(width 0.16002)
		(layer "In13.Cu")
		(net "M_B_CPU1_SA_DQS_DN<1>")
	)
	(segment
		(start 62.894718 -213.58479)
		(end 63.171578 -213.58479)
		(width 0.16002)
		(layer "In13.Cu")
		(net "M_B_CPU1_SA_DQS_DN<1>")
	)
	(segment
		(start 63.261494 -214.69223)
		(end 63.634366 -215.065102)
		(width 0.16002)
		(layer "In13.Cu")
		(net "M_B_CPU1_SA_DQS_DN<1>")
	)
	(segment
		(start 63.634366 -215.065102)
		(end 64.16167 -215.065102)
		(width 0.16002)
		(layer "In13.Cu")
		(net "M_B_CPU1_SA_DQS_DN<1>")
	)
	(segment
		(start 71.503286 -222.934022)
		(end 73.50633 -224.937066)
		(width 0.16002)
		(layer "In13.Cu")
		(net "M_B_CPU1_SA_DQS_DN<1>")
	)
	(segment
		(start 65.641982 -216.332054)
		(end 65.918842 -216.332054)
		(width 0.16002)
		(layer "In13.Cu")
		(net "M_B_CPU1_SA_DQS_DN<1>")
	)
	(segment
		(start 70.236334 -220.926406)
		(end 70.129654 -221.033086)
		(width 0.16002)
		(layer "In13.Cu")
		(net "M_B_CPU1_SA_DQS_DN<1>")
	)
	(segment
		(start 68.389246 -219.079318)
		(end 68.666106 -219.079318)
		(width 0.16002)
		(layer "In13.Cu")
		(net "M_B_CPU1_SA_DQS_DN<1>")
	)
	(segment
		(start 65.535302 -216.438734)
		(end 65.641982 -216.332054)
		(width 0.16002)
		(layer "In13.Cu")
		(net "M_B_CPU1_SA_DQS_DN<1>")
	)
	(segment
		(start 80.471264 -232.004362)
		(end 80.479646 -232.009188)
		(width 0.09525)
		(layer "In13.Cu")
		(net "M_B_CPU1_SA_DQS_DN<1>")
	)
	(segment
		(start 64.16167 -215.065102)
		(end 64.26835 -214.958422)
		(width 0.16002)
		(layer "In13.Cu")
		(net "M_B_CPU1_SA_DQS_DN<1>")
	)
	(segment
		(start 64.635126 -216.065862)
		(end 65.007998 -216.438734)
		(width 0.16002)
		(layer "In13.Cu")
		(net "M_B_CPU1_SA_DQS_DN<1>")
	)
	(segment
		(start 76.36383 -229.119938)
		(end 76.877418 -229.633526)
		(width 0.09525)
		(layer "In13.Cu")
		(net "M_B_CPU1_SA_DQS_DN<1>")
	)
	(segment
		(start 66.115438 -216.80551)
		(end 66.008758 -216.91219)
		(width 0.16002)
		(layer "In13.Cu")
		(net "M_B_CPU1_SA_DQS_DN<1>")
	)
	(segment
		(start 65.007998 -216.438734)
		(end 65.535302 -216.438734)
		(width 0.16002)
		(layer "In13.Cu")
		(net "M_B_CPU1_SA_DQS_DN<1>")
	)
	(segment
		(start 68.862702 -219.552774)
		(end 68.756022 -219.659454)
		(width 0.16002)
		(layer "In13.Cu")
		(net "M_B_CPU1_SA_DQS_DN<1>")
	)
	(segment
		(start 73.50633 -226.346258)
		(end 76.263246 -229.103174)
		(width 0.16002)
		(layer "In13.Cu")
		(net "M_B_CPU1_SA_DQS_DN<1>")
	)
	(segment
		(start 68.862702 -219.275914)
		(end 68.862702 -219.552774)
		(width 0.16002)
		(layer "In13.Cu")
		(net "M_B_CPU1_SA_DQS_DN<1>")
	)
	(segment
		(start 70.129654 -221.033086)
		(end 70.129654 -221.56039)
		(width 0.16002)
		(layer "In13.Cu")
		(net "M_B_CPU1_SA_DQS_DN<1>")
	)
	(segment
		(start 76.263246 -229.103174)
		(end 76.28001 -229.119938)
		(width 0.09525)
		(layer "In13.Cu")
		(net "M_B_CPU1_SA_DQS_DN<1>")
	)
	(segment
		(start 65.918842 -216.332054)
		(end 66.115438 -216.52865)
		(width 0.16002)
		(layer "In13.Cu")
		(net "M_B_CPU1_SA_DQS_DN<1>")
	)
	(segment
		(start 71.02983 -221.933262)
		(end 71.13651 -221.826582)
		(width 0.16002)
		(layer "In13.Cu")
		(net "M_B_CPU1_SA_DQS_DN<1>")
	)
	(segment
		(start 64.635126 -215.538558)
		(end 64.635126 -216.065862)
		(width 0.16002)
		(layer "In13.Cu")
		(net "M_B_CPU1_SA_DQS_DN<1>")
	)
	(segment
		(start 67.38239 -218.285822)
		(end 67.38239 -218.813126)
		(width 0.16002)
		(layer "In13.Cu")
		(net "M_B_CPU1_SA_DQS_DN<1>")
	)
	(segment
		(start 78.76794 -230.56596)
		(end 78.76794 -231.264206)
		(width 0.09525)
		(layer "In13.Cu")
		(net "M_B_CPU1_SA_DQS_DN<1>")
	)
	(segment
		(start 70.236334 -220.649546)
		(end 70.236334 -220.926406)
		(width 0.16002)
		(layer "In13.Cu")
		(net "M_B_CPU1_SA_DQS_DN<1>")
	)
	(segment
		(start 87.55634 -232.042208)
		(end 87.657178 -232.068878)
		(width 0.09525)
		(layer "In13.Cu")
		(net "M_B_CPU1_SA_DQS_DN<1>")
	)
	(segment
		(start 68.282566 -219.185998)
		(end 68.389246 -219.079318)
		(width 0.16002)
		(layer "In13.Cu")
		(net "M_B_CPU1_SA_DQS_DN<1>")
	)
	(segment
		(start 84.802472 -232.009188)
		(end 84.810854 -232.004362)
		(width 0.09525)
		(layer "In13.Cu")
		(net "M_B_CPU1_SA_DQS_DN<1>")
	)
	(segment
		(start 63.368174 -214.058246)
		(end 63.261494 -214.164926)
		(width 0.16002)
		(layer "In13.Cu")
		(net "M_B_CPU1_SA_DQS_DN<1>")
	)
	(segment
		(start 70.502526 -221.933262)
		(end 71.02983 -221.933262)
		(width 0.16002)
		(layer "In13.Cu")
		(net "M_B_CPU1_SA_DQS_DN<1>")
	)
	(segment
		(start 70.039738 -220.45295)
		(end 70.236334 -220.649546)
		(width 0.16002)
		(layer "In13.Cu")
		(net "M_B_CPU1_SA_DQS_DN<1>")
	)
	(segment
		(start 78.08214 -230.333296)
		(end 78.535276 -230.333296)
		(width 0.09525)
		(layer "In13.Cu")
		(net "M_B_CPU1_SA_DQS_DN<1>")
	)
	(segment
		(start 71.13651 -221.826582)
		(end 71.41337 -221.826582)
		(width 0.16002)
		(layer "In13.Cu")
		(net "M_B_CPU1_SA_DQS_DN<1>")
	)
	(segment
		(start 67.015614 -217.705686)
		(end 67.292474 -217.705686)
		(width 0.16002)
		(layer "In13.Cu")
		(net "M_B_CPU1_SA_DQS_DN<1>")
	)
	(segment
		(start 71.503286 -222.406718)
		(end 71.503286 -222.934022)
		(width 0.16002)
		(layer "In13.Cu")
		(net "M_B_CPU1_SA_DQS_DN<1>")
	)
	(segment
		(start 73.50633 -224.937066)
		(end 73.50633 -226.346258)
		(width 0.16002)
		(layer "In13.Cu")
		(net "M_B_CPU1_SA_DQS_DN<1>")
	)
	(segment
		(start 71.609966 -222.300038)
		(end 71.503286 -222.406718)
		(width 0.16002)
		(layer "In13.Cu")
		(net "M_B_CPU1_SA_DQS_DN<1>")
	)
	(segment
		(start 76.877418 -229.633526)
		(end 77.38237 -229.633526)
		(width 0.09525)
		(layer "In13.Cu")
		(net "M_B_CPU1_SA_DQS_DN<1>")
	)
	(segment
		(start 66.008758 -216.91219)
		(end 66.008758 -217.439494)
		(width 0.16002)
		(layer "In13.Cu")
		(net "M_B_CPU1_SA_DQS_DN<1>")
	)
	(segment
		(start 66.38163 -217.812366)
		(end 66.908934 -217.812366)
		(width 0.16002)
		(layer "In13.Cu")
		(net "M_B_CPU1_SA_DQS_DN<1>")
	)
	(segment
		(start 60.221622 -211.652358)
		(end 62.260734 -213.69147)
		(width 0.16002)
		(layer "In13.Cu")
		(net "M_B_CPU1_SA_DQS_DN<1>")
	)
	(segment
		(start 70.129654 -221.56039)
		(end 70.502526 -221.933262)
		(width 0.16002)
		(layer "In13.Cu")
		(net "M_B_CPU1_SA_DQS_DN<1>")
	)
	(segment
		(start 63.171578 -213.58479)
		(end 63.368174 -213.781386)
		(width 0.16002)
		(layer "In13.Cu")
		(net "M_B_CPU1_SA_DQS_DN<1>")
	)
	(segment
		(start 54.985666 -211.271104)
		(end 59.301126 -211.271104)
		(width 0.16002)
		(layer "In13.Cu")
		(net "M_B_CPU1_SA_DQS_DN<1>")
	)
	(segment
		(start 69.128894 -220.55963)
		(end 69.656198 -220.55963)
		(width 0.16002)
		(layer "In13.Cu")
		(net "M_B_CPU1_SA_DQS_DN<1>")
	)
	(segment
		(start 66.008758 -217.439494)
		(end 66.38163 -217.812366)
		(width 0.16002)
		(layer "In13.Cu")
		(net "M_B_CPU1_SA_DQS_DN<1>")
	)
	(segment
		(start 66.115438 -216.52865)
		(end 66.115438 -216.80551)
		(width 0.16002)
		(layer "In13.Cu")
		(net "M_B_CPU1_SA_DQS_DN<1>")
	)
	(segment
		(start 64.26835 -214.958422)
		(end 64.54521 -214.958422)
		(width 0.16002)
		(layer "In13.Cu")
		(net "M_B_CPU1_SA_DQS_DN<1>")
	)
	(segment
		(start 64.54521 -214.958422)
		(end 64.741806 -215.155018)
		(width 0.16002)
		(layer "In13.Cu")
		(net "M_B_CPU1_SA_DQS_DN<1>")
	)
	(segment
		(start 85.742526 -232.009188)
		(end 85.750908 -232.004362)
		(width 0.09525)
		(layer "In13.Cu")
		(net "M_B_CPU1_SA_DQS_DN<1>")
	)
	(segment
		(start 78.535276 -230.333296)
		(end 78.76794 -230.56596)
		(width 0.09525)
		(layer "In13.Cu")
		(net "M_B_CPU1_SA_DQS_DN<1>")
	)
	(segment
		(start 76.28001 -229.119938)
		(end 76.36383 -229.119938)
		(width 0.09525)
		(layer "In13.Cu")
		(net "M_B_CPU1_SA_DQS_DN<1>")
	)
	(arc
		(start 81.050892 -232.004362)
		(mid 81.235924 -231.958448)
		(end 81.4197 -232.009188)
		(width 0.09525)
		(layer "In13.Cu")
		(net "M_B_CPU1_SA_DQS_DN<1>")
	)
	(arc
		(start 87.535766 -232.050336)
		(mid 87.546094 -232.046376)
		(end 87.55634 -232.042208)
		(width 0.09525)
		(layer "In13.Cu")
		(net "M_B_CPU1_SA_DQS_DN<1>")
	)
	(arc
		(start 79.539592 -232.009188)
		(mid 79.821024 -232.084943)
		(end 80.102456 -232.009188)
		(width 0.09525)
		(layer "In13.Cu")
		(net "M_B_CPU1_SA_DQS_DN<1>")
	)
	(arc
		(start 84.239608 -232.009188)
		(mid 84.52104 -232.084943)
		(end 84.802472 -232.009188)
		(width 0.09525)
		(layer "In13.Cu")
		(net "M_B_CPU1_SA_DQS_DN<1>")
	)
	(arc
		(start 83.862418 -232.009188)
		(mid 84.046193 -231.958416)
		(end 84.231226 -232.004362)
		(width 0.09525)
		(layer "In13.Cu")
		(net "M_B_CPU1_SA_DQS_DN<1>")
	)
	(arc
		(start 81.982564 -232.009188)
		(mid 82.171032 -231.958511)
		(end 82.3595 -232.009188)
		(width 0.09525)
		(layer "In13.Cu")
		(net "M_B_CPU1_SA_DQS_DN<1>")
	)
	(arc
		(start 86.68258 -232.009188)
		(mid 86.871048 -231.958511)
		(end 87.059516 -232.009188)
		(width 0.09525)
		(layer "In13.Cu")
		(net "M_B_CPU1_SA_DQS_DN<1>")
	)
	(arc
		(start 85.750908 -232.004362)
		(mid 85.93594 -231.958448)
		(end 86.119716 -232.009188)
		(width 0.09525)
		(layer "In13.Cu")
		(net "M_B_CPU1_SA_DQS_DN<1>")
	)
	(arc
		(start 82.922364 -232.009188)
		(mid 83.106139 -231.958416)
		(end 83.291172 -232.004362)
		(width 0.09525)
		(layer "In13.Cu")
		(net "M_B_CPU1_SA_DQS_DN<1>")
	)
	(arc
		(start 87.059516 -232.009188)
		(mid 87.29303 -232.083031)
		(end 87.535766 -232.050336)
		(width 0.09525)
		(layer "In13.Cu")
		(net "M_B_CPU1_SA_DQS_DN<1>")
	)
	(arc
		(start 83.299554 -232.009188)
		(mid 83.580986 -232.084943)
		(end 83.862418 -232.009188)
		(width 0.09525)
		(layer "In13.Cu")
		(net "M_B_CPU1_SA_DQS_DN<1>")
	)
	(arc
		(start 80.479646 -232.009188)
		(mid 80.761078 -232.084943)
		(end 81.04251 -232.009188)
		(width 0.09525)
		(layer "In13.Cu")
		(net "M_B_CPU1_SA_DQS_DN<1>")
	)
	(arc
		(start 81.4197 -232.009188)
		(mid 81.701132 -232.084943)
		(end 81.982564 -232.009188)
		(width 0.09525)
		(layer "In13.Cu")
		(net "M_B_CPU1_SA_DQS_DN<1>")
	)
	(arc
		(start 79.42453 -231.920796)
		(mid 79.479192 -231.968727)
		(end 79.539592 -232.009188)
		(width 0.09525)
		(layer "In13.Cu")
		(net "M_B_CPU1_SA_DQS_DN<1>")
	)
	(arc
		(start 80.102456 -232.009188)
		(mid 80.286231 -231.958416)
		(end 80.471264 -232.004362)
		(width 0.09525)
		(layer "In13.Cu")
		(net "M_B_CPU1_SA_DQS_DN<1>")
	)
	(arc
		(start 85.179662 -232.009188)
		(mid 85.461094 -232.084943)
		(end 85.742526 -232.009188)
		(width 0.09525)
		(layer "In13.Cu")
		(net "M_B_CPU1_SA_DQS_DN<1>")
	)
	(arc
		(start 82.3595 -232.009188)
		(mid 82.640932 -232.084943)
		(end 82.922364 -232.009188)
		(width 0.09525)
		(layer "In13.Cu")
		(net "M_B_CPU1_SA_DQS_DN<1>")
	)
	(arc
		(start 84.810854 -232.004362)
		(mid 84.995886 -231.958448)
		(end 85.179662 -232.009188)
		(width 0.09525)
		(layer "In13.Cu")
		(net "M_B_CPU1_SA_DQS_DN<1>")
	)
	(arc
		(start 86.119716 -232.009188)
		(mid 86.401148 -232.084943)
		(end 86.68258 -232.009188)
		(width 0.09525)
		(layer "In13.Cu")
		(net "M_B_CPU1_SA_DQS_DN<1>")
	)
	(segment
		(start 88.277954 -227.740464)
		(end 87.811102 -227.474526)
		(width 0.12954)
		(layer "F.Cu")
		(net "M_B_CPU1_SA_DQS_DN<0>")
	)
	(segment
		(start 55.046372 -201.380852)
		(end 55.163212 -201.264012)
		(width 0.16002)
		(layer "In13.Cu")
		(net "M_B_CPU1_SA_DQS_DN<0>")
	)
	(segment
		(start 64.380872 -205.588108)
		(end 64.604138 -205.811374)
		(width 0.16002)
		(layer "In13.Cu")
		(net "M_B_CPU1_SA_DQS_DN<0>")
	)
	(segment
		(start 80.914494 -224.698814)
		(end 80.916526 -224.700084)
		(width 0.09525)
		(layer "In13.Cu")
		(net "M_B_CPU1_SA_DQS_DN<0>")
	)
	(segment
		(start 57.706514 -201.932286)
		(end 60.72505 -201.932286)
		(width 0.16002)
		(layer "In13.Cu")
		(net "M_B_CPU1_SA_DQS_DN<0>")
	)
	(segment
		(start 80.916526 -224.700084)
		(end 80.949546 -224.719388)
		(width 0.09525)
		(layer "In13.Cu")
		(net "M_B_CPU1_SA_DQS_DN<0>")
	)
	(segment
		(start 72.84593 -214.053166)
		(end 72.84593 -214.802466)
		(width 0.16002)
		(layer "In13.Cu")
		(net "M_B_CPU1_SA_DQS_DN<0>")
	)
	(segment
		(start 61.856874 -203.06411)
		(end 61.856874 -203.81341)
		(width 0.16002)
		(layer "In13.Cu")
		(net "M_B_CPU1_SA_DQS_DN<0>")
	)
	(segment
		(start 76.966826 -218.923362)
		(end 77.367892 -219.324428)
		(width 0.16002)
		(layer "In13.Cu")
		(net "M_B_CPU1_SA_DQS_DN<0>")
	)
	(segment
		(start 78.117192 -219.324428)
		(end 79.199486 -220.406722)
		(width 0.16002)
		(layer "In13.Cu")
		(net "M_B_CPU1_SA_DQS_DN<0>")
	)
	(segment
		(start 72.84593 -214.802466)
		(end 73.246996 -215.203532)
		(width 0.16002)
		(layer "In13.Cu")
		(net "M_B_CPU1_SA_DQS_DN<0>")
	)
	(segment
		(start 71.472298 -213.428834)
		(end 71.873364 -213.8299)
		(width 0.16002)
		(layer "In13.Cu")
		(net "M_B_CPU1_SA_DQS_DN<0>")
	)
	(segment
		(start 70.098666 -212.055202)
		(end 70.499732 -212.456268)
		(width 0.16002)
		(layer "In13.Cu")
		(net "M_B_CPU1_SA_DQS_DN<0>")
	)
	(segment
		(start 71.472298 -212.679534)
		(end 71.472298 -213.428834)
		(width 0.16002)
		(layer "In13.Cu")
		(net "M_B_CPU1_SA_DQS_DN<0>")
	)
	(segment
		(start 80.479646 -223.909382)
		(end 80.512158 -223.928178)
		(width 0.09525)
		(layer "In13.Cu")
		(net "M_B_CPU1_SA_DQS_DN<0>")
	)
	(segment
		(start 73.996296 -215.203532)
		(end 74.219562 -215.426798)
		(width 0.16002)
		(layer "In13.Cu")
		(net "M_B_CPU1_SA_DQS_DN<0>")
	)
	(segment
		(start 64.604138 -206.560674)
		(end 65.005204 -206.96174)
		(width 0.16002)
		(layer "In13.Cu")
		(net "M_B_CPU1_SA_DQS_DN<0>")
	)
	(segment
		(start 79.539846 -222.28937)
		(end 79.572358 -222.308166)
		(width 0.09525)
		(layer "In13.Cu")
		(net "M_B_CPU1_SA_DQS_DN<0>")
	)
	(segment
		(start 63.230506 -205.187042)
		(end 63.631572 -205.588108)
		(width 0.16002)
		(layer "In13.Cu")
		(net "M_B_CPU1_SA_DQS_DN<0>")
	)
	(segment
		(start 65.97777 -207.185006)
		(end 65.97777 -207.934306)
		(width 0.16002)
		(layer "In13.Cu")
		(net "M_B_CPU1_SA_DQS_DN<0>")
	)
	(segment
		(start 68.725034 -210.68157)
		(end 69.1261 -211.082636)
		(width 0.16002)
		(layer "In13.Cu")
		(net "M_B_CPU1_SA_DQS_DN<0>")
	)
	(segment
		(start 70.499732 -212.456268)
		(end 71.249032 -212.456268)
		(width 0.16002)
		(layer "In13.Cu")
		(net "M_B_CPU1_SA_DQS_DN<0>")
	)
	(segment
		(start 76.74356 -217.950796)
		(end 76.966826 -218.174062)
		(width 0.16002)
		(layer "In13.Cu")
		(net "M_B_CPU1_SA_DQS_DN<0>")
	)
	(segment
		(start 51.884072 -201.585322)
		(end 52.205382 -201.264012)
		(width 0.16002)
		(layer "In13.Cu")
		(net "M_B_CPU1_SA_DQS_DN<0>")
	)
	(segment
		(start 52.205382 -201.264012)
		(end 54.449472 -201.264012)
		(width 0.16002)
		(layer "In13.Cu")
		(net "M_B_CPU1_SA_DQS_DN<0>")
	)
	(segment
		(start 79.500476 -222.26651)
		(end 79.539846 -222.28937)
		(width 0.09525)
		(layer "In13.Cu")
		(net "M_B_CPU1_SA_DQS_DN<0>")
	)
	(segment
		(start 67.351402 -208.558638)
		(end 67.351402 -209.307938)
		(width 0.16002)
		(layer "In13.Cu")
		(net "M_B_CPU1_SA_DQS_DN<0>")
	)
	(segment
		(start 75.99426 -217.950796)
		(end 76.74356 -217.950796)
		(width 0.16002)
		(layer "In13.Cu")
		(net "M_B_CPU1_SA_DQS_DN<0>")
	)
	(segment
		(start 80.949546 -224.719388)
		(end 80.982058 -224.738184)
		(width 0.09525)
		(layer "In13.Cu")
		(net "M_B_CPU1_SA_DQS_DN<0>")
	)
	(segment
		(start 80.444594 -223.888808)
		(end 80.446626 -223.890078)
		(width 0.09525)
		(layer "In13.Cu")
		(net "M_B_CPU1_SA_DQS_DN<0>")
	)
	(segment
		(start 79.258668 -221.399608)
		(end 79.258668 -221.804484)
		(width 0.09525)
		(layer "In13.Cu")
		(net "M_B_CPU1_SA_DQS_DN<0>")
	)
	(segment
		(start 85.742526 -227.149406)
		(end 85.750908 -227.14458)
		(width 0.09525)
		(layer "In13.Cu")
		(net "M_B_CPU1_SA_DQS_DN<0>")
	)
	(segment
		(start 87.657178 -227.209096)
		(end 87.811102 -227.474526)
		(width 0.09525)
		(layer "In13.Cu")
		(net "M_B_CPU1_SA_DQS_DN<0>")
	)
	(segment
		(start 67.351402 -209.307938)
		(end 67.752468 -209.709004)
		(width 0.16002)
		(layer "In13.Cu")
		(net "M_B_CPU1_SA_DQS_DN<0>")
	)
	(segment
		(start 63.00724 -204.214476)
		(end 63.230506 -204.437742)
		(width 0.16002)
		(layer "In13.Cu")
		(net "M_B_CPU1_SA_DQS_DN<0>")
	)
	(segment
		(start 56.093106 -201.264012)
		(end 57.706514 -201.932286)
		(width 0.16002)
		(layer "In13.Cu")
		(net "M_B_CPU1_SA_DQS_DN<0>")
	)
	(segment
		(start 69.1261 -211.082636)
		(end 69.8754 -211.082636)
		(width 0.16002)
		(layer "In13.Cu")
		(net "M_B_CPU1_SA_DQS_DN<0>")
	)
	(segment
		(start 68.501768 -209.709004)
		(end 68.725034 -209.93227)
		(width 0.16002)
		(layer "In13.Cu")
		(net "M_B_CPU1_SA_DQS_DN<0>")
	)
	(segment
		(start 65.005204 -206.96174)
		(end 65.754504 -206.96174)
		(width 0.16002)
		(layer "In13.Cu")
		(net "M_B_CPU1_SA_DQS_DN<0>")
	)
	(segment
		(start 64.604138 -205.811374)
		(end 64.604138 -206.560674)
		(width 0.16002)
		(layer "In13.Cu")
		(net "M_B_CPU1_SA_DQS_DN<0>")
	)
	(segment
		(start 83.291172 -227.14458)
		(end 83.299554 -227.149406)
		(width 0.09525)
		(layer "In13.Cu")
		(net "M_B_CPU1_SA_DQS_DN<0>")
	)
	(segment
		(start 81.8896 -226.3394)
		(end 81.922112 -226.358196)
		(width 0.09525)
		(layer "In13.Cu")
		(net "M_B_CPU1_SA_DQS_DN<0>")
	)
	(segment
		(start 74.620628 -216.577164)
		(end 75.369928 -216.577164)
		(width 0.16002)
		(layer "In13.Cu")
		(net "M_B_CPU1_SA_DQS_DN<0>")
	)
	(segment
		(start 67.752468 -209.709004)
		(end 68.501768 -209.709004)
		(width 0.16002)
		(layer "In13.Cu")
		(net "M_B_CPU1_SA_DQS_DN<0>")
	)
	(segment
		(start 54.566312 -201.380852)
		(end 55.046372 -201.380852)
		(width 0.16002)
		(layer "In13.Cu")
		(net "M_B_CPU1_SA_DQS_DN<0>")
	)
	(segment
		(start 66.378836 -208.335372)
		(end 67.128136 -208.335372)
		(width 0.16002)
		(layer "In13.Cu")
		(net "M_B_CPU1_SA_DQS_DN<0>")
	)
	(segment
		(start 69.8754 -211.082636)
		(end 70.098666 -211.305902)
		(width 0.16002)
		(layer "In13.Cu")
		(net "M_B_CPU1_SA_DQS_DN<0>")
	)
	(segment
		(start 77.367892 -219.324428)
		(end 78.117192 -219.324428)
		(width 0.16002)
		(layer "In13.Cu")
		(net "M_B_CPU1_SA_DQS_DN<0>")
	)
	(segment
		(start 80.446626 -223.890078)
		(end 80.479646 -223.909382)
		(width 0.09525)
		(layer "In13.Cu")
		(net "M_B_CPU1_SA_DQS_DN<0>")
	)
	(segment
		(start 79.9719 -223.077278)
		(end 80.01 -223.099376)
		(width 0.09525)
		(layer "In13.Cu")
		(net "M_B_CPU1_SA_DQS_DN<0>")
	)
	(segment
		(start 73.246996 -215.203532)
		(end 73.996296 -215.203532)
		(width 0.16002)
		(layer "In13.Cu")
		(net "M_B_CPU1_SA_DQS_DN<0>")
	)
	(segment
		(start 54.449472 -201.264012)
		(end 54.566312 -201.380852)
		(width 0.16002)
		(layer "In13.Cu")
		(net "M_B_CPU1_SA_DQS_DN<0>")
	)
	(segment
		(start 72.622664 -213.8299)
		(end 72.84593 -214.053166)
		(width 0.16002)
		(layer "In13.Cu")
		(net "M_B_CPU1_SA_DQS_DN<0>")
	)
	(segment
		(start 74.219562 -215.426798)
		(end 74.219562 -216.176098)
		(width 0.16002)
		(layer "In13.Cu")
		(net "M_B_CPU1_SA_DQS_DN<0>")
	)
	(segment
		(start 71.249032 -212.456268)
		(end 71.472298 -212.679534)
		(width 0.16002)
		(layer "In13.Cu")
		(net "M_B_CPU1_SA_DQS_DN<0>")
	)
	(segment
		(start 79.199486 -220.406722)
		(end 79.199486 -221.316804)
		(width 0.16002)
		(layer "In13.Cu")
		(net "M_B_CPU1_SA_DQS_DN<0>")
	)
	(segment
		(start 79.199486 -221.316804)
		(end 79.199486 -221.340426)
		(width 0.09525)
		(layer "In13.Cu")
		(net "M_B_CPU1_SA_DQS_DN<0>")
	)
	(segment
		(start 67.128136 -208.335372)
		(end 67.351402 -208.558638)
		(width 0.16002)
		(layer "In13.Cu")
		(net "M_B_CPU1_SA_DQS_DN<0>")
	)
	(segment
		(start 81.4197 -225.529394)
		(end 81.451196 -225.547682)
		(width 0.09525)
		(layer "In13.Cu")
		(net "M_B_CPU1_SA_DQS_DN<0>")
	)
	(segment
		(start 87.55634 -227.182426)
		(end 87.657178 -227.209096)
		(width 0.09525)
		(layer "In13.Cu")
		(net "M_B_CPU1_SA_DQS_DN<0>")
	)
	(segment
		(start 79.199486 -221.340426)
		(end 79.258668 -221.399608)
		(width 0.09525)
		(layer "In13.Cu")
		(net "M_B_CPU1_SA_DQS_DN<0>")
	)
	(segment
		(start 60.72505 -201.932286)
		(end 61.856874 -203.06411)
		(width 0.16002)
		(layer "In13.Cu")
		(net "M_B_CPU1_SA_DQS_DN<0>")
	)
	(segment
		(start 75.369928 -216.577164)
		(end 75.593194 -216.80043)
		(width 0.16002)
		(layer "In13.Cu")
		(net "M_B_CPU1_SA_DQS_DN<0>")
	)
	(segment
		(start 70.098666 -211.305902)
		(end 70.098666 -212.055202)
		(width 0.16002)
		(layer "In13.Cu")
		(net "M_B_CPU1_SA_DQS_DN<0>")
	)
	(segment
		(start 82.32648 -227.130102)
		(end 82.3595 -227.149406)
		(width 0.09525)
		(layer "In13.Cu")
		(net "M_B_CPU1_SA_DQS_DN<0>")
	)
	(segment
		(start 84.231226 -227.14458)
		(end 84.239608 -227.149406)
		(width 0.09525)
		(layer "In13.Cu")
		(net "M_B_CPU1_SA_DQS_DN<0>")
	)
	(segment
		(start 55.163212 -201.264012)
		(end 56.093106 -201.264012)
		(width 0.16002)
		(layer "In13.Cu")
		(net "M_B_CPU1_SA_DQS_DN<0>")
	)
	(segment
		(start 62.25794 -204.214476)
		(end 63.00724 -204.214476)
		(width 0.16002)
		(layer "In13.Cu")
		(net "M_B_CPU1_SA_DQS_DN<0>")
	)
	(segment
		(start 75.593194 -216.80043)
		(end 75.593194 -217.54973)
		(width 0.16002)
		(layer "In13.Cu")
		(net "M_B_CPU1_SA_DQS_DN<0>")
	)
	(segment
		(start 74.219562 -216.176098)
		(end 74.620628 -216.577164)
		(width 0.16002)
		(layer "In13.Cu")
		(net "M_B_CPU1_SA_DQS_DN<0>")
	)
	(segment
		(start 71.873364 -213.8299)
		(end 72.622664 -213.8299)
		(width 0.16002)
		(layer "In13.Cu")
		(net "M_B_CPU1_SA_DQS_DN<0>")
	)
	(segment
		(start 75.593194 -217.54973)
		(end 75.99426 -217.950796)
		(width 0.16002)
		(layer "In13.Cu")
		(net "M_B_CPU1_SA_DQS_DN<0>")
	)
	(segment
		(start 84.802472 -227.149406)
		(end 84.810854 -227.14458)
		(width 0.09525)
		(layer "In13.Cu")
		(net "M_B_CPU1_SA_DQS_DN<0>")
	)
	(segment
		(start 76.966826 -218.174062)
		(end 76.966826 -218.923362)
		(width 0.16002)
		(layer "In13.Cu")
		(net "M_B_CPU1_SA_DQS_DN<0>")
	)
	(segment
		(start 81.8515 -226.317302)
		(end 81.8896 -226.3394)
		(width 0.09525)
		(layer "In13.Cu")
		(net "M_B_CPU1_SA_DQS_DN<0>")
	)
	(segment
		(start 65.97777 -207.934306)
		(end 66.378836 -208.335372)
		(width 0.16002)
		(layer "In13.Cu")
		(net "M_B_CPU1_SA_DQS_DN<0>")
	)
	(segment
		(start 81.3816 -225.507296)
		(end 81.4197 -225.529394)
		(width 0.09525)
		(layer "In13.Cu")
		(net "M_B_CPU1_SA_DQS_DN<0>")
	)
	(segment
		(start 80.01 -223.099376)
		(end 80.041496 -223.117664)
		(width 0.09525)
		(layer "In13.Cu")
		(net "M_B_CPU1_SA_DQS_DN<0>")
	)
	(segment
		(start 68.725034 -209.93227)
		(end 68.725034 -210.68157)
		(width 0.16002)
		(layer "In13.Cu")
		(net "M_B_CPU1_SA_DQS_DN<0>")
	)
	(segment
		(start 61.856874 -203.81341)
		(end 62.25794 -204.214476)
		(width 0.16002)
		(layer "In13.Cu")
		(net "M_B_CPU1_SA_DQS_DN<0>")
	)
	(segment
		(start 82.324448 -227.128832)
		(end 82.32648 -227.130102)
		(width 0.09525)
		(layer "In13.Cu")
		(net "M_B_CPU1_SA_DQS_DN<0>")
	)
	(segment
		(start 63.631572 -205.588108)
		(end 64.380872 -205.588108)
		(width 0.16002)
		(layer "In13.Cu")
		(net "M_B_CPU1_SA_DQS_DN<0>")
	)
	(segment
		(start 63.230506 -204.437742)
		(end 63.230506 -205.187042)
		(width 0.16002)
		(layer "In13.Cu")
		(net "M_B_CPU1_SA_DQS_DN<0>")
	)
	(segment
		(start 65.754504 -206.96174)
		(end 65.97777 -207.185006)
		(width 0.16002)
		(layer "In13.Cu")
		(net "M_B_CPU1_SA_DQS_DN<0>")
	)
	(arc
		(start 79.729076 -222.61449)
		(mid 79.793473 -222.875796)
		(end 79.9719 -223.077278)
		(width 0.09525)
		(layer "In13.Cu")
		(net "M_B_CPU1_SA_DQS_DN<0>")
	)
	(arc
		(start 79.258668 -221.804484)
		(mid 79.32277 -222.065228)
		(end 79.500476 -222.26651)
		(width 0.09525)
		(layer "In13.Cu")
		(net "M_B_CPU1_SA_DQS_DN<0>")
	)
	(arc
		(start 84.239608 -227.149406)
		(mid 84.52104 -227.225161)
		(end 84.802472 -227.149406)
		(width 0.09525)
		(layer "In13.Cu")
		(net "M_B_CPU1_SA_DQS_DN<0>")
	)
	(arc
		(start 81.608676 -225.854514)
		(mid 81.673073 -226.11582)
		(end 81.8515 -226.317302)
		(width 0.09525)
		(layer "In13.Cu")
		(net "M_B_CPU1_SA_DQS_DN<0>")
	)
	(arc
		(start 80.512158 -223.928178)
		(mid 80.627432 -224.062456)
		(end 80.668876 -224.234502)
		(width 0.09525)
		(layer "In13.Cu")
		(net "M_B_CPU1_SA_DQS_DN<0>")
	)
	(arc
		(start 87.535766 -227.190554)
		(mid 87.546094 -227.186594)
		(end 87.55634 -227.182426)
		(width 0.09525)
		(layer "In13.Cu")
		(net "M_B_CPU1_SA_DQS_DN<0>")
	)
	(arc
		(start 87.059516 -227.149406)
		(mid 87.29303 -227.223249)
		(end 87.535766 -227.190554)
		(width 0.09525)
		(layer "In13.Cu")
		(net "M_B_CPU1_SA_DQS_DN<0>")
	)
	(arc
		(start 82.07883 -226.66452)
		(mid 82.144023 -226.927149)
		(end 82.324448 -227.128832)
		(width 0.09525)
		(layer "In13.Cu")
		(net "M_B_CPU1_SA_DQS_DN<0>")
	)
	(arc
		(start 83.299554 -227.149406)
		(mid 83.580986 -227.225161)
		(end 83.862418 -227.149406)
		(width 0.09525)
		(layer "In13.Cu")
		(net "M_B_CPU1_SA_DQS_DN<0>")
	)
	(arc
		(start 80.041496 -223.117664)
		(mid 80.157294 -223.252058)
		(end 80.198976 -223.424496)
		(width 0.09525)
		(layer "In13.Cu")
		(net "M_B_CPU1_SA_DQS_DN<0>")
	)
	(arc
		(start 81.922112 -226.358196)
		(mid 82.037386 -226.492474)
		(end 82.07883 -226.66452)
		(width 0.09525)
		(layer "In13.Cu")
		(net "M_B_CPU1_SA_DQS_DN<0>")
	)
	(arc
		(start 84.810854 -227.14458)
		(mid 84.995886 -227.098666)
		(end 85.179662 -227.149406)
		(width 0.09525)
		(layer "In13.Cu")
		(net "M_B_CPU1_SA_DQS_DN<0>")
	)
	(arc
		(start 81.451196 -225.547682)
		(mid 81.566994 -225.682076)
		(end 81.608676 -225.854514)
		(width 0.09525)
		(layer "In13.Cu")
		(net "M_B_CPU1_SA_DQS_DN<0>")
	)
	(arc
		(start 80.198976 -223.424496)
		(mid 80.264169 -223.687125)
		(end 80.444594 -223.888808)
		(width 0.09525)
		(layer "In13.Cu")
		(net "M_B_CPU1_SA_DQS_DN<0>")
	)
	(arc
		(start 86.68258 -227.149406)
		(mid 86.871048 -227.098729)
		(end 87.059516 -227.149406)
		(width 0.09525)
		(layer "In13.Cu")
		(net "M_B_CPU1_SA_DQS_DN<0>")
	)
	(arc
		(start 79.572358 -222.308166)
		(mid 79.687632 -222.442444)
		(end 79.729076 -222.61449)
		(width 0.09525)
		(layer "In13.Cu")
		(net "M_B_CPU1_SA_DQS_DN<0>")
	)
	(arc
		(start 80.982058 -224.738184)
		(mid 81.097332 -224.872462)
		(end 81.138776 -225.044508)
		(width 0.09525)
		(layer "In13.Cu")
		(net "M_B_CPU1_SA_DQS_DN<0>")
	)
	(arc
		(start 86.119716 -227.149406)
		(mid 86.401148 -227.225161)
		(end 86.68258 -227.149406)
		(width 0.09525)
		(layer "In13.Cu")
		(net "M_B_CPU1_SA_DQS_DN<0>")
	)
	(arc
		(start 82.922364 -227.149406)
		(mid 83.106139 -227.098634)
		(end 83.291172 -227.14458)
		(width 0.09525)
		(layer "In13.Cu")
		(net "M_B_CPU1_SA_DQS_DN<0>")
	)
	(arc
		(start 85.750908 -227.14458)
		(mid 85.93594 -227.098666)
		(end 86.119716 -227.149406)
		(width 0.09525)
		(layer "In13.Cu")
		(net "M_B_CPU1_SA_DQS_DN<0>")
	)
	(arc
		(start 82.3595 -227.149406)
		(mid 82.640932 -227.225161)
		(end 82.922364 -227.149406)
		(width 0.09525)
		(layer "In13.Cu")
		(net "M_B_CPU1_SA_DQS_DN<0>")
	)
	(arc
		(start 85.179662 -227.149406)
		(mid 85.461094 -227.225161)
		(end 85.742526 -227.149406)
		(width 0.09525)
		(layer "In13.Cu")
		(net "M_B_CPU1_SA_DQS_DN<0>")
	)
	(arc
		(start 83.862418 -227.149406)
		(mid 84.046193 -227.098634)
		(end 84.231226 -227.14458)
		(width 0.09525)
		(layer "In13.Cu")
		(net "M_B_CPU1_SA_DQS_DN<0>")
	)
	(arc
		(start 81.138776 -225.044508)
		(mid 81.203173 -225.305814)
		(end 81.3816 -225.507296)
		(width 0.09525)
		(layer "In13.Cu")
		(net "M_B_CPU1_SA_DQS_DN<0>")
	)
	(arc
		(start 80.668876 -224.234502)
		(mid 80.734069 -224.497131)
		(end 80.914494 -224.698814)
		(width 0.09525)
		(layer "In13.Cu")
		(net "M_B_CPU1_SA_DQS_DN<0>")
	)
	(segment
		(start 89.218008 -230.980234)
		(end 88.751156 -230.71455)
		(width 0.10668)
		(layer "F.Cu")
		(net "M_B_CPU1_SA_DQ<9>")
	)
	(segment
		(start 55.47868 -208.810352)
		(end 55.641748 -208.97342)
		(width 0.14478)
		(layer "In13.Cu")
		(net "M_B_CPU1_SA_DQ<9>")
	)
	(segment
		(start 59.784234 -209.507074)
		(end 59.97321 -209.428842)
		(width 0.14478)
		(layer "In13.Cu")
		(net "M_B_CPU1_SA_DQ<9>")
	)
	(segment
		(start 58.765694 -209.084926)
		(end 58.95467 -209.006694)
		(width 0.14478)
		(layer "In13.Cu")
		(net "M_B_CPU1_SA_DQ<9>")
	)
	(segment
		(start 60.560712 -209.828638)
		(end 61.77026 -210.329272)
		(width 0.14478)
		(layer "In13.Cu")
		(net "M_B_CPU1_SA_DQ<9>")
	)
	(segment
		(start 59.59475 -208.902046)
		(end 59.46394 -209.217768)
		(width 0.14478)
		(layer "In13.Cu")
		(net "M_B_CPU1_SA_DQ<9>")
	)
	(segment
		(start 52.788312 -208.665572)
		(end 52.788312 -208.34096)
		(width 0.14478)
		(layer "In13.Cu")
		(net "M_B_CPU1_SA_DQ<9>")
	)
	(segment
		(start 53.194712 -208.19618)
		(end 53.339492 -208.34096)
		(width 0.14478)
		(layer "In13.Cu")
		(net "M_B_CPU1_SA_DQ<9>")
	)
	(segment
		(start 79.04607 -229.069646)
		(end 79.04607 -229.280466)
		(width 0.0889)
		(layer "In13.Cu")
		(net "M_B_CPU1_SA_DQ<9>")
	)
	(segment
		(start 56.198262 -209.030316)
		(end 56.198262 -208.97342)
		(width 0.14478)
		(layer "In13.Cu")
		(net "M_B_CPU1_SA_DQ<9>")
	)
	(segment
		(start 83.289648 -231.041702)
		(end 83.29803 -231.036876)
		(width 0.0889)
		(layer "In13.Cu")
		(net "M_B_CPU1_SA_DQ<9>")
	)
	(segment
		(start 59.516518 -208.71307)
		(end 59.59475 -208.902046)
		(width 0.14478)
		(layer "In13.Cu")
		(net "M_B_CPU1_SA_DQ<9>")
	)
	(segment
		(start 54.922166 -209.193384)
		(end 55.085234 -209.030316)
		(width 0.14478)
		(layer "In13.Cu")
		(net "M_B_CPU1_SA_DQ<9>")
	)
	(segment
		(start 79.63408 -230.22687)
		(end 79.670656 -230.248206)
		(width 0.0889)
		(layer "In13.Cu")
		(net "M_B_CPU1_SA_DQ<9>")
	)
	(segment
		(start 85.74405 -231.036876)
		(end 85.752432 -231.041702)
		(width 0.0889)
		(layer "In13.Cu")
		(net "M_B_CPU1_SA_DQ<9>")
	)
	(segment
		(start 60.48248 -209.639916)
		(end 60.560712 -209.828638)
		(width 0.14478)
		(layer "In13.Cu")
		(net "M_B_CPU1_SA_DQ<9>")
	)
	(segment
		(start 52.643532 -208.810352)
		(end 52.788312 -208.665572)
		(width 0.14478)
		(layer "In13.Cu")
		(net "M_B_CPU1_SA_DQ<9>")
	)
	(segment
		(start 76.571348 -227.344986)
		(end 77.08011 -227.344986)
		(width 0.0889)
		(layer "In13.Cu")
		(net "M_B_CPU1_SA_DQ<9>")
	)
	(segment
		(start 55.641748 -208.97342)
		(end 55.641748 -209.030316)
		(width 0.14478)
		(layer "In13.Cu")
		(net "M_B_CPU1_SA_DQ<9>")
	)
	(segment
		(start 53.339492 -208.34096)
		(end 53.339492 -208.665572)
		(width 0.14478)
		(layer "In13.Cu")
		(net "M_B_CPU1_SA_DQ<9>")
	)
	(segment
		(start 52.788312 -208.34096)
		(end 52.933092 -208.19618)
		(width 0.14478)
		(layer "In13.Cu")
		(net "M_B_CPU1_SA_DQ<9>")
	)
	(segment
		(start 88.90508 -230.97998)
		(end 88.751156 -230.71455)
		(width 0.0889)
		(layer "In13.Cu")
		(net "M_B_CPU1_SA_DQ<9>")
	)
	(segment
		(start 54.52872 -208.97342)
		(end 54.52872 -209.030316)
		(width 0.14478)
		(layer "In13.Cu")
		(net "M_B_CPU1_SA_DQ<9>")
	)
	(segment
		(start 58.103262 -208.810352)
		(end 58.765694 -209.084926)
		(width 0.14478)
		(layer "In13.Cu")
		(net "M_B_CPU1_SA_DQ<9>")
	)
	(segment
		(start 72.99325 -222.381826)
		(end 74.91095 -224.299526)
		(width 0.14478)
		(layer "In13.Cu")
		(net "M_B_CPU1_SA_DQ<9>")
	)
	(segment
		(start 54.691788 -209.193384)
		(end 54.922166 -209.193384)
		(width 0.14478)
		(layer "In13.Cu")
		(net "M_B_CPU1_SA_DQ<9>")
	)
	(segment
		(start 74.91095 -225.684588)
		(end 76.080366 -226.854004)
		(width 0.14478)
		(layer "In13.Cu")
		(net "M_B_CPU1_SA_DQ<9>")
	)
	(segment
		(start 55.085234 -209.030316)
		(end 55.085234 -208.97342)
		(width 0.14478)
		(layer "In13.Cu")
		(net "M_B_CPU1_SA_DQ<9>")
	)
	(segment
		(start 87.989664 -231.041702)
		(end 87.998046 -231.036876)
		(width 0.0889)
		(layer "In13.Cu")
		(net "M_B_CPU1_SA_DQ<9>")
	)
	(segment
		(start 72.99325 -221.552262)
		(end 72.99325 -222.381826)
		(width 0.14478)
		(layer "In13.Cu")
		(net "M_B_CPU1_SA_DQ<9>")
	)
	(segment
		(start 79.60233 -230.208582)
		(end 79.63408 -230.22687)
		(width 0.0889)
		(layer "In13.Cu")
		(net "M_B_CPU1_SA_DQ<9>")
	)
	(segment
		(start 76.080366 -226.854004)
		(end 76.571348 -227.344986)
		(width 0.0889)
		(layer "In13.Cu")
		(net "M_B_CPU1_SA_DQ<9>")
	)
	(segment
		(start 79.04607 -229.280466)
		(end 79.338678 -229.573074)
		(width 0.0889)
		(layer "In13.Cu")
		(net "M_B_CPU1_SA_DQ<9>")
	)
	(segment
		(start 52.933092 -208.19618)
		(end 53.194712 -208.19618)
		(width 0.14478)
		(layer "In13.Cu")
		(net "M_B_CPU1_SA_DQ<9>")
	)
	(segment
		(start 59.08548 -208.690972)
		(end 59.274456 -208.61274)
		(width 0.14478)
		(layer "In13.Cu")
		(net "M_B_CPU1_SA_DQ<9>")
	)
	(segment
		(start 59.46394 -209.217768)
		(end 59.542172 -209.406744)
		(width 0.14478)
		(layer "In13.Cu")
		(net "M_B_CPU1_SA_DQ<9>")
	)
	(segment
		(start 59.274456 -208.61274)
		(end 59.516518 -208.71307)
		(width 0.14478)
		(layer "In13.Cu")
		(net "M_B_CPU1_SA_DQ<9>")
	)
	(segment
		(start 51.884072 -208.38541)
		(end 52.309014 -208.810352)
		(width 0.14478)
		(layer "In13.Cu")
		(net "M_B_CPU1_SA_DQ<9>")
	)
	(segment
		(start 80.071468 -231.01808)
		(end 80.10398 -231.036876)
		(width 0.0889)
		(layer "In13.Cu")
		(net "M_B_CPU1_SA_DQ<9>")
	)
	(segment
		(start 52.309014 -208.810352)
		(end 52.643532 -208.810352)
		(width 0.14478)
		(layer "In13.Cu")
		(net "M_B_CPU1_SA_DQ<9>")
	)
	(segment
		(start 78.22565 -228.490526)
		(end 78.46695 -228.490526)
		(width 0.0889)
		(layer "In13.Cu")
		(net "M_B_CPU1_SA_DQ<9>")
	)
	(segment
		(start 60.535058 -209.135218)
		(end 60.61329 -209.324194)
		(width 0.14478)
		(layer "In13.Cu")
		(net "M_B_CPU1_SA_DQ<9>")
	)
	(segment
		(start 88.882728 -231.063038)
		(end 88.90508 -230.97998)
		(width 0.0889)
		(layer "In13.Cu")
		(net "M_B_CPU1_SA_DQ<9>")
	)
	(segment
		(start 60.61329 -209.324194)
		(end 60.48248 -209.639916)
		(width 0.14478)
		(layer "In13.Cu")
		(net "M_B_CPU1_SA_DQ<9>")
	)
	(segment
		(start 55.804816 -209.193384)
		(end 56.035194 -209.193384)
		(width 0.14478)
		(layer "In13.Cu")
		(net "M_B_CPU1_SA_DQ<9>")
	)
	(segment
		(start 84.229702 -231.041702)
		(end 84.238084 -231.036876)
		(width 0.0889)
		(layer "In13.Cu")
		(net "M_B_CPU1_SA_DQ<9>")
	)
	(segment
		(start 53.339492 -208.665572)
		(end 53.484272 -208.810352)
		(width 0.14478)
		(layer "In13.Cu")
		(net "M_B_CPU1_SA_DQ<9>")
	)
	(segment
		(start 58.95467 -209.006694)
		(end 59.08548 -208.690972)
		(width 0.14478)
		(layer "In13.Cu")
		(net "M_B_CPU1_SA_DQ<9>")
	)
	(segment
		(start 81.044034 -231.036876)
		(end 81.052416 -231.041702)
		(width 0.0889)
		(layer "In13.Cu")
		(net "M_B_CPU1_SA_DQ<9>")
	)
	(segment
		(start 59.97321 -209.428842)
		(end 60.10402 -209.11312)
		(width 0.14478)
		(layer "In13.Cu")
		(net "M_B_CPU1_SA_DQ<9>")
	)
	(segment
		(start 55.248302 -208.810352)
		(end 55.47868 -208.810352)
		(width 0.14478)
		(layer "In13.Cu")
		(net "M_B_CPU1_SA_DQ<9>")
	)
	(segment
		(start 77.08011 -227.344986)
		(end 78.22565 -228.490526)
		(width 0.0889)
		(layer "In13.Cu")
		(net "M_B_CPU1_SA_DQ<9>")
	)
	(segment
		(start 80.46974 -231.041702)
		(end 80.478122 -231.036876)
		(width 0.0889)
		(layer "In13.Cu")
		(net "M_B_CPU1_SA_DQ<9>")
	)
	(segment
		(start 55.085234 -208.97342)
		(end 55.248302 -208.810352)
		(width 0.14478)
		(layer "In13.Cu")
		(net "M_B_CPU1_SA_DQ<9>")
	)
	(segment
		(start 74.91095 -224.299526)
		(end 74.91095 -225.684588)
		(width 0.14478)
		(layer "In13.Cu")
		(net "M_B_CPU1_SA_DQ<9>")
	)
	(segment
		(start 60.10402 -209.11312)
		(end 60.292996 -209.034888)
		(width 0.14478)
		(layer "In13.Cu")
		(net "M_B_CPU1_SA_DQ<9>")
	)
	(segment
		(start 56.36133 -208.810352)
		(end 58.103262 -208.810352)
		(width 0.14478)
		(layer "In13.Cu")
		(net "M_B_CPU1_SA_DQ<9>")
	)
	(segment
		(start 56.198262 -208.97342)
		(end 56.36133 -208.810352)
		(width 0.14478)
		(layer "In13.Cu")
		(net "M_B_CPU1_SA_DQ<9>")
	)
	(segment
		(start 53.484272 -208.810352)
		(end 54.365652 -208.810352)
		(width 0.14478)
		(layer "In13.Cu")
		(net "M_B_CPU1_SA_DQ<9>")
	)
	(segment
		(start 59.542172 -209.406744)
		(end 59.784234 -209.507074)
		(width 0.14478)
		(layer "In13.Cu")
		(net "M_B_CPU1_SA_DQ<9>")
	)
	(segment
		(start 78.46695 -228.490526)
		(end 79.04607 -229.069646)
		(width 0.0889)
		(layer "In13.Cu")
		(net "M_B_CPU1_SA_DQ<9>")
	)
	(segment
		(start 60.292996 -209.034888)
		(end 60.535058 -209.135218)
		(width 0.14478)
		(layer "In13.Cu")
		(net "M_B_CPU1_SA_DQ<9>")
	)
	(segment
		(start 56.035194 -209.193384)
		(end 56.198262 -209.030316)
		(width 0.14478)
		(layer "In13.Cu")
		(net "M_B_CPU1_SA_DQ<9>")
	)
	(segment
		(start 54.365652 -208.810352)
		(end 54.52872 -208.97342)
		(width 0.14478)
		(layer "In13.Cu")
		(net "M_B_CPU1_SA_DQ<9>")
	)
	(segment
		(start 55.641748 -209.030316)
		(end 55.804816 -209.193384)
		(width 0.14478)
		(layer "In13.Cu")
		(net "M_B_CPU1_SA_DQ<9>")
	)
	(segment
		(start 61.77026 -210.329272)
		(end 72.99325 -221.552262)
		(width 0.14478)
		(layer "In13.Cu")
		(net "M_B_CPU1_SA_DQ<9>")
	)
	(segment
		(start 54.52872 -209.030316)
		(end 54.691788 -209.193384)
		(width 0.14478)
		(layer "In13.Cu")
		(net "M_B_CPU1_SA_DQ<9>")
	)
	(segment
		(start 84.803996 -231.036876)
		(end 84.812378 -231.041702)
		(width 0.0889)
		(layer "In13.Cu")
		(net "M_B_CPU1_SA_DQ<9>")
	)
	(arc
		(start 82.357976 -231.036876)
		(mid 82.640932 -230.960699)
		(end 82.923888 -231.036876)
		(width 0.0889)
		(layer "In13.Cu")
		(net "M_B_CPU1_SA_DQ<9>")
	)
	(arc
		(start 82.923888 -231.036876)
		(mid 83.106139 -231.08726)
		(end 83.289648 -231.041702)
		(width 0.0889)
		(layer "In13.Cu")
		(net "M_B_CPU1_SA_DQ<9>")
	)
	(arc
		(start 86.684104 -231.036876)
		(mid 86.871048 -231.087165)
		(end 87.057992 -231.036876)
		(width 0.0889)
		(layer "In13.Cu")
		(net "M_B_CPU1_SA_DQ<9>")
	)
	(arc
		(start 87.998046 -231.036876)
		(mid 88.281002 -230.960699)
		(end 88.563958 -231.036876)
		(width 0.0889)
		(layer "In13.Cu")
		(net "M_B_CPU1_SA_DQ<9>")
	)
	(arc
		(start 87.623904 -231.036876)
		(mid 87.806155 -231.08726)
		(end 87.989664 -231.041702)
		(width 0.0889)
		(layer "In13.Cu")
		(net "M_B_CPU1_SA_DQ<9>")
	)
	(arc
		(start 79.916528 -230.71455)
		(mid 79.957494 -230.884956)
		(end 80.071468 -231.01808)
		(width 0.0889)
		(layer "In13.Cu")
		(net "M_B_CPU1_SA_DQ<9>")
	)
	(arc
		(start 80.478122 -231.036876)
		(mid 80.761078 -230.960699)
		(end 81.044034 -231.036876)
		(width 0.0889)
		(layer "In13.Cu")
		(net "M_B_CPU1_SA_DQ<9>")
	)
	(arc
		(start 84.812378 -231.041702)
		(mid 84.995886 -231.087227)
		(end 85.178138 -231.036876)
		(width 0.0889)
		(layer "In13.Cu")
		(net "M_B_CPU1_SA_DQ<9>")
	)
	(arc
		(start 84.238084 -231.036876)
		(mid 84.52104 -230.960699)
		(end 84.803996 -231.036876)
		(width 0.0889)
		(layer "In13.Cu")
		(net "M_B_CPU1_SA_DQ<9>")
	)
	(arc
		(start 83.863942 -231.036876)
		(mid 84.046193 -231.08726)
		(end 84.229702 -231.041702)
		(width 0.0889)
		(layer "In13.Cu")
		(net "M_B_CPU1_SA_DQ<9>")
	)
	(arc
		(start 80.10398 -231.036876)
		(mid 80.286231 -231.08726)
		(end 80.46974 -231.041702)
		(width 0.0889)
		(layer "In13.Cu")
		(net "M_B_CPU1_SA_DQ<9>")
	)
	(arc
		(start 85.178138 -231.036876)
		(mid 85.461094 -230.960699)
		(end 85.74405 -231.036876)
		(width 0.0889)
		(layer "In13.Cu")
		(net "M_B_CPU1_SA_DQ<9>")
	)
	(arc
		(start 81.984088 -231.036876)
		(mid 82.171032 -231.087165)
		(end 82.357976 -231.036876)
		(width 0.0889)
		(layer "In13.Cu")
		(net "M_B_CPU1_SA_DQ<9>")
	)
	(arc
		(start 83.29803 -231.036876)
		(mid 83.580986 -230.960699)
		(end 83.863942 -231.036876)
		(width 0.0889)
		(layer "In13.Cu")
		(net "M_B_CPU1_SA_DQ<9>")
	)
	(arc
		(start 79.670656 -230.248206)
		(mid 79.851308 -230.450951)
		(end 79.916528 -230.71455)
		(width 0.0889)
		(layer "In13.Cu")
		(net "M_B_CPU1_SA_DQ<9>")
	)
	(arc
		(start 81.052416 -231.041702)
		(mid 81.235924 -231.087227)
		(end 81.418176 -231.036876)
		(width 0.0889)
		(layer "In13.Cu")
		(net "M_B_CPU1_SA_DQ<9>")
	)
	(arc
		(start 85.752432 -231.041702)
		(mid 85.93594 -231.087227)
		(end 86.118192 -231.036876)
		(width 0.0889)
		(layer "In13.Cu")
		(net "M_B_CPU1_SA_DQ<9>")
	)
	(arc
		(start 86.118192 -231.036876)
		(mid 86.401148 -230.960699)
		(end 86.684104 -231.036876)
		(width 0.0889)
		(layer "In13.Cu")
		(net "M_B_CPU1_SA_DQ<9>")
	)
	(arc
		(start 79.446374 -229.90429)
		(mid 79.487629 -230.075261)
		(end 79.60233 -230.208582)
		(width 0.0889)
		(layer "In13.Cu")
		(net "M_B_CPU1_SA_DQ<9>")
	)
	(arc
		(start 81.418176 -231.036876)
		(mid 81.701132 -230.960699)
		(end 81.984088 -231.036876)
		(width 0.0889)
		(layer "In13.Cu")
		(net "M_B_CPU1_SA_DQ<9>")
	)
	(arc
		(start 87.057992 -231.036876)
		(mid 87.340948 -230.960699)
		(end 87.623904 -231.036876)
		(width 0.0889)
		(layer "In13.Cu")
		(net "M_B_CPU1_SA_DQ<9>")
	)
	(arc
		(start 88.563958 -231.036876)
		(mid 88.720396 -231.085881)
		(end 88.882728 -231.063038)
		(width 0.0889)
		(layer "In13.Cu")
		(net "M_B_CPU1_SA_DQ<9>")
	)
	(arc
		(start 79.338678 -229.573074)
		(mid 79.41871 -229.730174)
		(end 79.446374 -229.90429)
		(width 0.0889)
		(layer "In13.Cu")
		(net "M_B_CPU1_SA_DQ<9>")
	)
	(segment
		(start 87.8078 -230.170228)
		(end 87.340948 -229.90429)
		(width 0.10668)
		(layer "F.Cu")
		(net "M_B_CPU1_SA_DQ<8>")
	)
	(segment
		(start 54.788054 -207.25511)
		(end 54.788054 -207.323182)
		(width 0.14478)
		(layer "In13.Cu")
		(net "M_B_CPU1_SA_DQ<8>")
	)
	(segment
		(start 58.347102 -206.967836)
		(end 58.347102 -207.339946)
		(width 0.14478)
		(layer "In13.Cu")
		(net "M_B_CPU1_SA_DQ<8>")
	)
	(segment
		(start 52.649628 -206.213456)
		(end 52.794408 -206.068676)
		(width 0.14478)
		(layer "In13.Cu")
		(net "M_B_CPU1_SA_DQ<8>")
	)
	(segment
		(start 56.693562 -207.339946)
		(end 56.693562 -206.967836)
		(width 0.14478)
		(layer "In13.Cu")
		(net "M_B_CPU1_SA_DQ<8>")
	)
	(segment
		(start 80.071468 -229.398068)
		(end 80.10398 -229.416864)
		(width 0.0889)
		(layer "In13.Cu")
		(net "M_B_CPU1_SA_DQ<8>")
	)
	(segment
		(start 57.244742 -206.967836)
		(end 57.244742 -207.339946)
		(width 0.14478)
		(layer "In13.Cu")
		(net "M_B_CPU1_SA_DQ<8>")
	)
	(segment
		(start 80.141064 -229.4382)
		(end 80.143096 -229.439724)
		(width 0.0889)
		(layer "In13.Cu")
		(net "M_B_CPU1_SA_DQ<8>")
	)
	(segment
		(start 53.056028 -206.068676)
		(end 53.200808 -206.213456)
		(width 0.14478)
		(layer "In13.Cu")
		(net "M_B_CPU1_SA_DQ<8>")
	)
	(segment
		(start 55.890922 -207.271874)
		(end 55.890922 -207.323182)
		(width 0.14478)
		(layer "In13.Cu")
		(net "M_B_CPU1_SA_DQ<8>")
	)
	(segment
		(start 53.200808 -206.51597)
		(end 53.345588 -206.66075)
		(width 0.14478)
		(layer "In13.Cu")
		(net "M_B_CPU1_SA_DQ<8>")
	)
	(segment
		(start 60.188602 -207.891634)
		(end 60.373768 -208.0768)
		(width 0.14478)
		(layer "In13.Cu")
		(net "M_B_CPU1_SA_DQ<8>")
	)
	(segment
		(start 79.60233 -228.588824)
		(end 79.63408 -228.607112)
		(width 0.0889)
		(layer "In13.Cu")
		(net "M_B_CPU1_SA_DQ<8>")
	)
	(segment
		(start 57.940702 -206.823056)
		(end 58.202322 -206.823056)
		(width 0.14478)
		(layer "In13.Cu")
		(net "M_B_CPU1_SA_DQ<8>")
	)
	(segment
		(start 57.244742 -207.339946)
		(end 57.389522 -207.484726)
		(width 0.14478)
		(layer "In13.Cu")
		(net "M_B_CPU1_SA_DQ<8>")
	)
	(segment
		(start 75.88377 -224.968308)
		(end 76.922376 -226.006914)
		(width 0.14478)
		(layer "In13.Cu")
		(net "M_B_CPU1_SA_DQ<8>")
	)
	(segment
		(start 81.879694 -230.231696)
		(end 81.888076 -230.22687)
		(width 0.0889)
		(layer "In13.Cu")
		(net "M_B_CPU1_SA_DQ<8>")
	)
	(segment
		(start 52.504848 -206.66075)
		(end 52.649628 -206.51597)
		(width 0.14478)
		(layer "In13.Cu")
		(net "M_B_CPU1_SA_DQ<8>")
	)
	(segment
		(start 57.795922 -207.339946)
		(end 57.795922 -206.967836)
		(width 0.14478)
		(layer "In13.Cu")
		(net "M_B_CPU1_SA_DQ<8>")
	)
	(segment
		(start 60.191904 -207.683608)
		(end 60.188602 -207.68691)
		(width 0.14478)
		(layer "In13.Cu")
		(net "M_B_CPU1_SA_DQ<8>")
	)
	(segment
		(start 56.052466 -207.484726)
		(end 56.548782 -207.484726)
		(width 0.14478)
		(layer "In13.Cu")
		(net "M_B_CPU1_SA_DQ<8>")
	)
	(segment
		(start 55.177944 -207.484726)
		(end 55.339488 -207.323182)
		(width 0.14478)
		(layer "In13.Cu")
		(net "M_B_CPU1_SA_DQ<8>")
	)
	(segment
		(start 54.788054 -207.323182)
		(end 54.949598 -207.484726)
		(width 0.14478)
		(layer "In13.Cu")
		(net "M_B_CPU1_SA_DQ<8>")
	)
	(segment
		(start 58.347102 -207.339946)
		(end 58.491882 -207.484726)
		(width 0.14478)
		(layer "In13.Cu")
		(net "M_B_CPU1_SA_DQ<8>")
	)
	(segment
		(start 85.639656 -230.231696)
		(end 85.648038 -230.22687)
		(width 0.0889)
		(layer "In13.Cu")
		(net "M_B_CPU1_SA_DQ<8>")
	)
	(segment
		(start 55.339488 -207.323182)
		(end 55.339488 -207.271874)
		(width 0.14478)
		(layer "In13.Cu")
		(net "M_B_CPU1_SA_DQ<8>")
	)
	(segment
		(start 57.795922 -206.967836)
		(end 57.940702 -206.823056)
		(width 0.14478)
		(layer "In13.Cu")
		(net "M_B_CPU1_SA_DQ<8>")
	)
	(segment
		(start 73.91019 -221.998286)
		(end 75.88377 -223.971866)
		(width 0.14478)
		(layer "In13.Cu")
		(net "M_B_CPU1_SA_DQ<8>")
	)
	(segment
		(start 51.884072 -206.685388)
		(end 51.90871 -206.66075)
		(width 0.14478)
		(layer "In13.Cu")
		(net "M_B_CPU1_SA_DQ<8>")
	)
	(segment
		(start 73.91019 -221.19717)
		(end 73.91019 -221.998286)
		(width 0.14478)
		(layer "In13.Cu")
		(net "M_B_CPU1_SA_DQ<8>")
	)
	(segment
		(start 60.786518 -208.073498)
		(end 73.91019 -221.19717)
		(width 0.14478)
		(layer "In13.Cu")
		(net "M_B_CPU1_SA_DQ<8>")
	)
	(segment
		(start 82.453988 -230.22687)
		(end 82.46237 -230.231696)
		(width 0.0889)
		(layer "In13.Cu")
		(net "M_B_CPU1_SA_DQ<8>")
	)
	(segment
		(start 77.909928 -226.994466)
		(end 78.57109 -226.994466)
		(width 0.0889)
		(layer "In13.Cu")
		(net "M_B_CPU1_SA_DQ<8>")
	)
	(segment
		(start 51.90871 -206.66075)
		(end 52.504848 -206.66075)
		(width 0.14478)
		(layer "In13.Cu")
		(net "M_B_CPU1_SA_DQ<8>")
	)
	(segment
		(start 76.922376 -226.006914)
		(end 77.909928 -226.994466)
		(width 0.0889)
		(layer "In13.Cu")
		(net "M_B_CPU1_SA_DQ<8>")
	)
	(segment
		(start 56.838342 -206.823056)
		(end 57.099962 -206.823056)
		(width 0.14478)
		(layer "In13.Cu")
		(net "M_B_CPU1_SA_DQ<8>")
	)
	(segment
		(start 60.191904 -207.478884)
		(end 60.191904 -207.683608)
		(width 0.14478)
		(layer "In13.Cu")
		(net "M_B_CPU1_SA_DQ<8>")
	)
	(segment
		(start 55.339488 -207.271874)
		(end 55.501032 -207.11033)
		(width 0.14478)
		(layer "In13.Cu")
		(net "M_B_CPU1_SA_DQ<8>")
	)
	(segment
		(start 57.389522 -207.484726)
		(end 57.651142 -207.484726)
		(width 0.14478)
		(layer "In13.Cu")
		(net "M_B_CPU1_SA_DQ<8>")
	)
	(segment
		(start 79.446374 -227.86975)
		(end 79.446374 -228.284532)
		(width 0.0889)
		(layer "In13.Cu")
		(net "M_B_CPU1_SA_DQ<8>")
	)
	(segment
		(start 59.82335 -207.11033)
		(end 60.191904 -207.478884)
		(width 0.14478)
		(layer "In13.Cu")
		(net "M_B_CPU1_SA_DQ<8>")
	)
	(segment
		(start 79.63408 -228.607112)
		(end 79.673196 -228.629972)
		(width 0.0889)
		(layer "In13.Cu")
		(net "M_B_CPU1_SA_DQ<8>")
	)
	(segment
		(start 55.729378 -207.11033)
		(end 55.890922 -207.271874)
		(width 0.14478)
		(layer "In13.Cu")
		(net "M_B_CPU1_SA_DQ<8>")
	)
	(segment
		(start 87.154004 -230.22687)
		(end 87.162386 -230.231696)
		(width 0.0889)
		(layer "In13.Cu")
		(net "M_B_CPU1_SA_DQ<8>")
	)
	(segment
		(start 54.949598 -207.484726)
		(end 55.177944 -207.484726)
		(width 0.14478)
		(layer "In13.Cu")
		(net "M_B_CPU1_SA_DQ<8>")
	)
	(segment
		(start 78.57109 -226.994466)
		(end 79.446374 -227.86975)
		(width 0.0889)
		(layer "In13.Cu")
		(net "M_B_CPU1_SA_DQ<8>")
	)
	(segment
		(start 60.581794 -208.073498)
		(end 60.786518 -208.073498)
		(width 0.14478)
		(layer "In13.Cu")
		(net "M_B_CPU1_SA_DQ<8>")
	)
	(segment
		(start 58.491882 -207.484726)
		(end 58.890916 -207.484726)
		(width 0.14478)
		(layer "In13.Cu")
		(net "M_B_CPU1_SA_DQ<8>")
	)
	(segment
		(start 54.643274 -207.11033)
		(end 54.788054 -207.25511)
		(width 0.14478)
		(layer "In13.Cu")
		(net "M_B_CPU1_SA_DQ<8>")
	)
	(segment
		(start 83.394042 -230.22687)
		(end 83.402424 -230.231696)
		(width 0.0889)
		(layer "In13.Cu")
		(net "M_B_CPU1_SA_DQ<8>")
	)
	(segment
		(start 80.542384 -230.208582)
		(end 80.574134 -230.22687)
		(width 0.0889)
		(layer "In13.Cu")
		(net "M_B_CPU1_SA_DQ<8>")
	)
	(segment
		(start 52.794408 -206.068676)
		(end 53.056028 -206.068676)
		(width 0.14478)
		(layer "In13.Cu")
		(net "M_B_CPU1_SA_DQ<8>")
	)
	(segment
		(start 87.495126 -230.16972)
		(end 87.340948 -229.90429)
		(width 0.0889)
		(layer "In13.Cu")
		(net "M_B_CPU1_SA_DQ<8>")
	)
	(segment
		(start 54.084474 -207.11033)
		(end 54.643274 -207.11033)
		(width 0.14478)
		(layer "In13.Cu")
		(net "M_B_CPU1_SA_DQ<8>")
	)
	(segment
		(start 55.501032 -207.11033)
		(end 55.729378 -207.11033)
		(width 0.14478)
		(layer "In13.Cu")
		(net "M_B_CPU1_SA_DQ<8>")
	)
	(segment
		(start 53.634894 -206.66075)
		(end 54.084474 -207.11033)
		(width 0.14478)
		(layer "In13.Cu")
		(net "M_B_CPU1_SA_DQ<8>")
	)
	(segment
		(start 53.200808 -206.213456)
		(end 53.200808 -206.51597)
		(width 0.14478)
		(layer "In13.Cu")
		(net "M_B_CPU1_SA_DQ<8>")
	)
	(segment
		(start 56.548782 -207.484726)
		(end 56.693562 -207.339946)
		(width 0.14478)
		(layer "In13.Cu")
		(net "M_B_CPU1_SA_DQ<8>")
	)
	(segment
		(start 53.345588 -206.66075)
		(end 53.634894 -206.66075)
		(width 0.14478)
		(layer "In13.Cu")
		(net "M_B_CPU1_SA_DQ<8>")
	)
	(segment
		(start 58.202322 -206.823056)
		(end 58.347102 -206.967836)
		(width 0.14478)
		(layer "In13.Cu")
		(net "M_B_CPU1_SA_DQ<8>")
	)
	(segment
		(start 80.10398 -229.416864)
		(end 80.141064 -229.4382)
		(width 0.0889)
		(layer "In13.Cu")
		(net "M_B_CPU1_SA_DQ<8>")
	)
	(segment
		(start 75.88377 -223.971866)
		(end 75.88377 -224.968308)
		(width 0.14478)
		(layer "In13.Cu")
		(net "M_B_CPU1_SA_DQ<8>")
	)
	(segment
		(start 55.890922 -207.323182)
		(end 56.052466 -207.484726)
		(width 0.14478)
		(layer "In13.Cu")
		(net "M_B_CPU1_SA_DQ<8>")
	)
	(segment
		(start 59.265312 -207.11033)
		(end 59.82335 -207.11033)
		(width 0.14478)
		(layer "In13.Cu")
		(net "M_B_CPU1_SA_DQ<8>")
	)
	(segment
		(start 52.649628 -206.51597)
		(end 52.649628 -206.213456)
		(width 0.14478)
		(layer "In13.Cu")
		(net "M_B_CPU1_SA_DQ<8>")
	)
	(segment
		(start 57.651142 -207.484726)
		(end 57.795922 -207.339946)
		(width 0.14478)
		(layer "In13.Cu")
		(net "M_B_CPU1_SA_DQ<8>")
	)
	(segment
		(start 58.890916 -207.484726)
		(end 59.265312 -207.11033)
		(width 0.14478)
		(layer "In13.Cu")
		(net "M_B_CPU1_SA_DQ<8>")
	)
	(segment
		(start 60.373768 -208.0768)
		(end 60.578492 -208.0768)
		(width 0.14478)
		(layer "In13.Cu")
		(net "M_B_CPU1_SA_DQ<8>")
	)
	(segment
		(start 60.188602 -207.68691)
		(end 60.188602 -207.891634)
		(width 0.14478)
		(layer "In13.Cu")
		(net "M_B_CPU1_SA_DQ<8>")
	)
	(segment
		(start 56.693562 -206.967836)
		(end 56.838342 -206.823056)
		(width 0.14478)
		(layer "In13.Cu")
		(net "M_B_CPU1_SA_DQ<8>")
	)
	(segment
		(start 57.099962 -206.823056)
		(end 57.244742 -206.967836)
		(width 0.14478)
		(layer "In13.Cu")
		(net "M_B_CPU1_SA_DQ<8>")
	)
	(segment
		(start 87.472774 -230.253032)
		(end 87.495126 -230.16972)
		(width 0.0889)
		(layer "In13.Cu")
		(net "M_B_CPU1_SA_DQ<8>")
	)
	(segment
		(start 60.578492 -208.0768)
		(end 60.581794 -208.073498)
		(width 0.14478)
		(layer "In13.Cu")
		(net "M_B_CPU1_SA_DQ<8>")
	)
	(segment
		(start 86.57971 -230.231696)
		(end 86.588092 -230.22687)
		(width 0.0889)
		(layer "In13.Cu")
		(net "M_B_CPU1_SA_DQ<8>")
	)
	(arc
		(start 81.513934 -230.22687)
		(mid 81.696185 -230.27722)
		(end 81.879694 -230.231696)
		(width 0.0889)
		(layer "In13.Cu")
		(net "M_B_CPU1_SA_DQ<8>")
	)
	(arc
		(start 80.143096 -229.439724)
		(mid 80.321909 -229.642074)
		(end 80.386428 -229.90429)
		(width 0.0889)
		(layer "In13.Cu")
		(net "M_B_CPU1_SA_DQ<8>")
	)
	(arc
		(start 81.888076 -230.22687)
		(mid 82.171032 -230.150727)
		(end 82.453988 -230.22687)
		(width 0.0889)
		(layer "In13.Cu")
		(net "M_B_CPU1_SA_DQ<8>")
	)
	(arc
		(start 84.334096 -230.22687)
		(mid 84.52104 -230.277125)
		(end 84.707984 -230.22687)
		(width 0.0889)
		(layer "In13.Cu")
		(net "M_B_CPU1_SA_DQ<8>")
	)
	(arc
		(start 86.21395 -230.22687)
		(mid 86.396201 -230.27722)
		(end 86.57971 -230.231696)
		(width 0.0889)
		(layer "In13.Cu")
		(net "M_B_CPU1_SA_DQ<8>")
	)
	(arc
		(start 82.82813 -230.22687)
		(mid 83.111086 -230.150727)
		(end 83.394042 -230.22687)
		(width 0.0889)
		(layer "In13.Cu")
		(net "M_B_CPU1_SA_DQ<8>")
	)
	(arc
		(start 82.46237 -230.231696)
		(mid 82.645878 -230.27719)
		(end 82.82813 -230.22687)
		(width 0.0889)
		(layer "In13.Cu")
		(net "M_B_CPU1_SA_DQ<8>")
	)
	(arc
		(start 79.446374 -228.284532)
		(mid 79.487629 -228.455503)
		(end 79.60233 -228.588824)
		(width 0.0889)
		(layer "In13.Cu")
		(net "M_B_CPU1_SA_DQ<8>")
	)
	(arc
		(start 84.707984 -230.22687)
		(mid 84.99094 -230.150727)
		(end 85.273896 -230.22687)
		(width 0.0889)
		(layer "In13.Cu")
		(net "M_B_CPU1_SA_DQ<8>")
	)
	(arc
		(start 80.948022 -230.22687)
		(mid 81.230978 -230.150727)
		(end 81.513934 -230.22687)
		(width 0.0889)
		(layer "In13.Cu")
		(net "M_B_CPU1_SA_DQ<8>")
	)
	(arc
		(start 79.673196 -228.629972)
		(mid 79.852009 -228.832322)
		(end 79.916528 -229.094538)
		(width 0.0889)
		(layer "In13.Cu")
		(net "M_B_CPU1_SA_DQ<8>")
	)
	(arc
		(start 85.273896 -230.22687)
		(mid 85.456147 -230.27722)
		(end 85.639656 -230.231696)
		(width 0.0889)
		(layer "In13.Cu")
		(net "M_B_CPU1_SA_DQ<8>")
	)
	(arc
		(start 83.402424 -230.231696)
		(mid 83.585932 -230.27719)
		(end 83.768184 -230.22687)
		(width 0.0889)
		(layer "In13.Cu")
		(net "M_B_CPU1_SA_DQ<8>")
	)
	(arc
		(start 85.648038 -230.22687)
		(mid 85.930994 -230.150727)
		(end 86.21395 -230.22687)
		(width 0.0889)
		(layer "In13.Cu")
		(net "M_B_CPU1_SA_DQ<8>")
	)
	(arc
		(start 83.768184 -230.22687)
		(mid 84.05114 -230.150727)
		(end 84.334096 -230.22687)
		(width 0.0889)
		(layer "In13.Cu")
		(net "M_B_CPU1_SA_DQ<8>")
	)
	(arc
		(start 87.162386 -230.231696)
		(mid 87.315256 -230.276337)
		(end 87.472774 -230.253032)
		(width 0.0889)
		(layer "In13.Cu")
		(net "M_B_CPU1_SA_DQ<8>")
	)
	(arc
		(start 80.574134 -230.22687)
		(mid 80.761078 -230.277125)
		(end 80.948022 -230.22687)
		(width 0.0889)
		(layer "In13.Cu")
		(net "M_B_CPU1_SA_DQ<8>")
	)
	(arc
		(start 80.386428 -229.90429)
		(mid 80.427683 -230.075261)
		(end 80.542384 -230.208582)
		(width 0.0889)
		(layer "In13.Cu")
		(net "M_B_CPU1_SA_DQ<8>")
	)
	(arc
		(start 86.588092 -230.22687)
		(mid 86.871048 -230.150727)
		(end 87.154004 -230.22687)
		(width 0.0889)
		(layer "In13.Cu")
		(net "M_B_CPU1_SA_DQ<8>")
	)
	(arc
		(start 79.916528 -229.094538)
		(mid 79.957494 -229.264944)
		(end 80.071468 -229.398068)
		(width 0.0889)
		(layer "In13.Cu")
		(net "M_B_CPU1_SA_DQ<8>")
	)
	(segment
		(start 89.687908 -230.170228)
		(end 89.221056 -229.90429)
		(width 0.10668)
		(layer "F.Cu")
		(net "M_B_CPU1_SA_DQ<7>")
	)
	(segment
		(start 80.9117 -229.560882)
		(end 80.948022 -229.581964)
		(width 0.0889)
		(layer "In13.Cu")
		(net "M_B_CPU1_SA_DQ<7>")
	)
	(segment
		(start 81.879694 -229.577138)
		(end 81.888076 -229.581964)
		(width 0.0889)
		(layer "In13.Cu")
		(net "M_B_CPU1_SA_DQ<7>")
	)
	(segment
		(start 50.222404 -205.410308)
		(end 53.256434 -205.410308)
		(width 0.14478)
		(layer "In13.Cu")
		(net "M_B_CPU1_SA_DQ<7>")
	)
	(segment
		(start 79.9719 -227.94087)
		(end 80.038702 -227.979732)
		(width 0.0889)
		(layer "In13.Cu")
		(net "M_B_CPU1_SA_DQ<7>")
	)
	(segment
		(start 85.639656 -229.577138)
		(end 85.648038 -229.581964)
		(width 0.0889)
		(layer "In13.Cu")
		(net "M_B_CPU1_SA_DQ<7>")
	)
	(segment
		(start 49.270158 -205.83525)
		(end 49.797462 -205.83525)
		(width 0.14478)
		(layer "In13.Cu")
		(net "M_B_CPU1_SA_DQ<7>")
	)
	(segment
		(start 49.125378 -205.98003)
		(end 49.270158 -205.83525)
		(width 0.14478)
		(layer "In13.Cu")
		(net "M_B_CPU1_SA_DQ<7>")
	)
	(segment
		(start 75.564746 -222.850964)
		(end 76.964286 -224.250504)
		(width 0.14478)
		(layer "In13.Cu")
		(net "M_B_CPU1_SA_DQ<7>")
	)
	(segment
		(start 80.478122 -228.771958)
		(end 80.509872 -228.790246)
		(width 0.0889)
		(layer "In13.Cu")
		(net "M_B_CPU1_SA_DQ<7>")
	)
	(segment
		(start 78.051914 -225.99269)
		(end 79.718916 -227.659692)
		(width 0.0889)
		(layer "In13.Cu")
		(net "M_B_CPU1_SA_DQ<7>")
	)
	(segment
		(start 49.797462 -205.83525)
		(end 50.222404 -205.410308)
		(width 0.14478)
		(layer "In13.Cu")
		(net "M_B_CPU1_SA_DQ<7>")
	)
	(segment
		(start 48.574198 -205.98003)
		(end 48.574198 -206.054198)
		(width 0.14478)
		(layer "In13.Cu")
		(net "M_B_CPU1_SA_DQ<7>")
	)
	(segment
		(start 47.784004 -205.83525)
		(end 48.429418 -205.83525)
		(width 0.14478)
		(layer "In13.Cu")
		(net "M_B_CPU1_SA_DQ<7>")
	)
	(segment
		(start 48.429418 -205.83525)
		(end 48.574198 -205.98003)
		(width 0.14478)
		(layer "In13.Cu")
		(net "M_B_CPU1_SA_DQ<7>")
	)
	(segment
		(start 76.964286 -224.414842)
		(end 77.52715 -224.977706)
		(width 0.14478)
		(layer "In13.Cu")
		(net "M_B_CPU1_SA_DQ<7>")
	)
	(segment
		(start 53.256434 -205.410308)
		(end 54.106572 -206.260446)
		(width 0.14478)
		(layer "In13.Cu")
		(net "M_B_CPU1_SA_DQ<7>")
	)
	(segment
		(start 88.094058 -229.581964)
		(end 88.10244 -229.577138)
		(width 0.0889)
		(layer "In13.Cu")
		(net "M_B_CPU1_SA_DQ<7>")
	)
	(segment
		(start 77.52715 -224.977706)
		(end 77.785722 -225.236278)
		(width 0.0889)
		(layer "In13.Cu")
		(net "M_B_CPU1_SA_DQ<7>")
	)
	(segment
		(start 80.439006 -228.749098)
		(end 80.478122 -228.771958)
		(width 0.0889)
		(layer "In13.Cu")
		(net "M_B_CPU1_SA_DQ<7>")
	)
	(segment
		(start 48.980598 -206.198978)
		(end 49.125378 -206.054198)
		(width 0.14478)
		(layer "In13.Cu")
		(net "M_B_CPU1_SA_DQ<7>")
	)
	(segment
		(start 88.971374 -229.61346)
		(end 89.067132 -229.63886)
		(width 0.0889)
		(layer "In13.Cu")
		(net "M_B_CPU1_SA_DQ<7>")
	)
	(segment
		(start 59.752992 -206.260446)
		(end 75.564746 -222.0722)
		(width 0.14478)
		(layer "In13.Cu")
		(net "M_B_CPU1_SA_DQ<7>")
	)
	(segment
		(start 76.964286 -224.250504)
		(end 76.964286 -224.414842)
		(width 0.14478)
		(layer "In13.Cu")
		(net "M_B_CPU1_SA_DQ<7>")
	)
	(segment
		(start 86.57971 -229.577138)
		(end 86.588092 -229.581964)
		(width 0.0889)
		(layer "In13.Cu")
		(net "M_B_CPU1_SA_DQ<7>")
	)
	(segment
		(start 48.574198 -206.054198)
		(end 48.718978 -206.198978)
		(width 0.14478)
		(layer "In13.Cu")
		(net "M_B_CPU1_SA_DQ<7>")
	)
	(segment
		(start 77.89037 -225.488754)
		(end 77.89037 -225.602546)
		(width 0.0889)
		(layer "In13.Cu")
		(net "M_B_CPU1_SA_DQ<7>")
	)
	(segment
		(start 48.718978 -206.198978)
		(end 48.980598 -206.198978)
		(width 0.14478)
		(layer "In13.Cu")
		(net "M_B_CPU1_SA_DQ<7>")
	)
	(segment
		(start 87.154004 -229.581964)
		(end 87.162386 -229.577138)
		(width 0.0889)
		(layer "In13.Cu")
		(net "M_B_CPU1_SA_DQ<7>")
	)
	(segment
		(start 49.125378 -206.054198)
		(end 49.125378 -205.98003)
		(width 0.14478)
		(layer "In13.Cu")
		(net "M_B_CPU1_SA_DQ<7>")
	)
	(segment
		(start 82.453988 -229.581964)
		(end 82.46237 -229.577138)
		(width 0.0889)
		(layer "In13.Cu")
		(net "M_B_CPU1_SA_DQ<7>")
	)
	(segment
		(start 54.106572 -206.260446)
		(end 59.752992 -206.260446)
		(width 0.14478)
		(layer "In13.Cu")
		(net "M_B_CPU1_SA_DQ<7>")
	)
	(segment
		(start 83.394042 -229.581964)
		(end 83.402424 -229.577138)
		(width 0.0889)
		(layer "In13.Cu")
		(net "M_B_CPU1_SA_DQ<7>")
	)
	(segment
		(start 75.564746 -222.0722)
		(end 75.564746 -222.850964)
		(width 0.14478)
		(layer "In13.Cu")
		(net "M_B_CPU1_SA_DQ<7>")
	)
	(segment
		(start 89.067132 -229.63886)
		(end 89.221056 -229.90429)
		(width 0.0889)
		(layer "In13.Cu")
		(net "M_B_CPU1_SA_DQ<7>")
	)
	(arc
		(start 80.195674 -228.284532)
		(mid 80.260189 -228.546751)
		(end 80.439006 -228.749098)
		(width 0.0889)
		(layer "In13.Cu")
		(net "M_B_CPU1_SA_DQ<7>")
	)
	(arc
		(start 77.785722 -225.236278)
		(mid 77.863176 -225.352101)
		(end 77.89037 -225.488754)
		(width 0.0889)
		(layer "In13.Cu")
		(net "M_B_CPU1_SA_DQ<7>")
	)
	(arc
		(start 82.82813 -229.581964)
		(mid 83.111086 -229.658141)
		(end 83.394042 -229.581964)
		(width 0.0889)
		(layer "In13.Cu")
		(net "M_B_CPU1_SA_DQ<7>")
	)
	(arc
		(start 86.588092 -229.581964)
		(mid 86.871048 -229.658141)
		(end 87.154004 -229.581964)
		(width 0.0889)
		(layer "In13.Cu")
		(net "M_B_CPU1_SA_DQ<7>")
	)
	(arc
		(start 84.707984 -229.581964)
		(mid 84.99094 -229.658141)
		(end 85.273896 -229.581964)
		(width 0.0889)
		(layer "In13.Cu")
		(net "M_B_CPU1_SA_DQ<7>")
	)
	(arc
		(start 81.513934 -229.581964)
		(mid 81.696185 -229.53158)
		(end 81.879694 -229.577138)
		(width 0.0889)
		(layer "In13.Cu")
		(net "M_B_CPU1_SA_DQ<7>")
	)
	(arc
		(start 83.402424 -229.577138)
		(mid 83.585932 -229.531613)
		(end 83.768184 -229.581964)
		(width 0.0889)
		(layer "In13.Cu")
		(net "M_B_CPU1_SA_DQ<7>")
	)
	(arc
		(start 82.46237 -229.577138)
		(mid 82.645878 -229.531613)
		(end 82.82813 -229.581964)
		(width 0.0889)
		(layer "In13.Cu")
		(net "M_B_CPU1_SA_DQ<7>")
	)
	(arc
		(start 79.815182 -227.779326)
		(mid 79.885401 -227.867998)
		(end 79.9719 -227.94087)
		(width 0.0889)
		(layer "In13.Cu")
		(net "M_B_CPU1_SA_DQ<7>")
	)
	(arc
		(start 87.528146 -229.581964)
		(mid 87.811102 -229.658141)
		(end 88.094058 -229.581964)
		(width 0.0889)
		(layer "In13.Cu")
		(net "M_B_CPU1_SA_DQ<7>")
	)
	(arc
		(start 80.665828 -229.094538)
		(mid 80.731064 -229.358129)
		(end 80.9117 -229.560882)
		(width 0.0889)
		(layer "In13.Cu")
		(net "M_B_CPU1_SA_DQ<7>")
	)
	(arc
		(start 85.273896 -229.581964)
		(mid 85.456147 -229.53158)
		(end 85.639656 -229.577138)
		(width 0.0889)
		(layer "In13.Cu")
		(net "M_B_CPU1_SA_DQ<7>")
	)
	(arc
		(start 85.648038 -229.581964)
		(mid 85.930994 -229.658141)
		(end 86.21395 -229.581964)
		(width 0.0889)
		(layer "In13.Cu")
		(net "M_B_CPU1_SA_DQ<7>")
	)
	(arc
		(start 80.509872 -228.790246)
		(mid 80.624548 -228.92358)
		(end 80.665828 -229.094538)
		(width 0.0889)
		(layer "In13.Cu")
		(net "M_B_CPU1_SA_DQ<7>")
	)
	(arc
		(start 80.038702 -227.979732)
		(mid 80.154129 -228.113108)
		(end 80.195674 -228.284532)
		(width 0.0889)
		(layer "In13.Cu")
		(net "M_B_CPU1_SA_DQ<7>")
	)
	(arc
		(start 88.4682 -229.581964)
		(mid 88.71606 -229.657047)
		(end 88.971374 -229.61346)
		(width 0.0889)
		(layer "In13.Cu")
		(net "M_B_CPU1_SA_DQ<7>")
	)
	(arc
		(start 77.89037 -225.602546)
		(mid 77.93235 -225.813682)
		(end 78.051914 -225.99269)
		(width 0.0889)
		(layer "In13.Cu")
		(net "M_B_CPU1_SA_DQ<7>")
	)
	(arc
		(start 81.888076 -229.581964)
		(mid 82.171032 -229.658141)
		(end 82.453988 -229.581964)
		(width 0.0889)
		(layer "In13.Cu")
		(net "M_B_CPU1_SA_DQ<7>")
	)
	(arc
		(start 80.948022 -229.581964)
		(mid 81.230978 -229.658141)
		(end 81.513934 -229.581964)
		(width 0.0889)
		(layer "In13.Cu")
		(net "M_B_CPU1_SA_DQ<7>")
	)
	(arc
		(start 83.768184 -229.581964)
		(mid 84.05114 -229.658141)
		(end 84.334096 -229.581964)
		(width 0.0889)
		(layer "In13.Cu")
		(net "M_B_CPU1_SA_DQ<7>")
	)
	(arc
		(start 84.334096 -229.581964)
		(mid 84.52104 -229.531675)
		(end 84.707984 -229.581964)
		(width 0.0889)
		(layer "In13.Cu")
		(net "M_B_CPU1_SA_DQ<7>")
	)
	(arc
		(start 88.10244 -229.577138)
		(mid 88.285948 -229.531613)
		(end 88.4682 -229.581964)
		(width 0.0889)
		(layer "In13.Cu")
		(net "M_B_CPU1_SA_DQ<7>")
	)
	(arc
		(start 87.162386 -229.577138)
		(mid 87.345894 -229.531613)
		(end 87.528146 -229.581964)
		(width 0.0889)
		(layer "In13.Cu")
		(net "M_B_CPU1_SA_DQ<7>")
	)
	(arc
		(start 86.21395 -229.581964)
		(mid 86.396201 -229.53158)
		(end 86.57971 -229.577138)
		(width 0.0889)
		(layer "In13.Cu")
		(net "M_B_CPU1_SA_DQ<7>")
	)
	(arc
		(start 79.718916 -227.659692)
		(mid 79.770286 -227.716905)
		(end 79.815182 -227.779326)
		(width 0.0889)
		(layer "In13.Cu")
		(net "M_B_CPU1_SA_DQ<7>")
	)
	(segment
		(start 88.277954 -229.360476)
		(end 87.811102 -229.094538)
		(width 0.10668)
		(layer "F.Cu")
		(net "M_B_CPU1_SA_DQ<6>")
	)
	(segment
		(start 48.600614 -204.135228)
		(end 48.745394 -204.280008)
		(width 0.14478)
		(layer "In13.Cu")
		(net "M_B_CPU1_SA_DQ<6>")
	)
	(segment
		(start 50.222404 -203.710286)
		(end 53.256434 -203.710286)
		(width 0.14478)
		(layer "In13.Cu")
		(net "M_B_CPU1_SA_DQ<6>")
	)
	(segment
		(start 79.068422 -224.721928)
		(end 79.097886 -224.738946)
		(width 0.0889)
		(layer "In13.Cu")
		(net "M_B_CPU1_SA_DQ<6>")
	)
	(segment
		(start 78.470252 -223.812862)
		(end 78.481428 -223.824038)
		(width 0.0889)
		(layer "In13.Cu")
		(net "M_B_CPU1_SA_DQ<6>")
	)
	(segment
		(start 49.296574 -204.513688)
		(end 49.296574 -204.280008)
		(width 0.14478)
		(layer "In13.Cu")
		(net "M_B_CPU1_SA_DQ<6>")
	)
	(segment
		(start 85.74405 -228.771958)
		(end 85.752432 -228.767132)
		(width 0.0889)
		(layer "In13.Cu")
		(net "M_B_CPU1_SA_DQ<6>")
	)
	(segment
		(start 63.22441 -208.408016)
		(end 63.795656 -208.408016)
		(width 0.14478)
		(layer "In13.Cu")
		(net "M_B_CPU1_SA_DQ<6>")
	)
	(segment
		(start 48.890174 -204.658468)
		(end 49.151794 -204.658468)
		(width 0.14478)
		(layer "In13.Cu")
		(net "M_B_CPU1_SA_DQ<6>")
	)
	(segment
		(start 54.106572 -204.560424)
		(end 59.376818 -204.560424)
		(width 0.14478)
		(layer "In13.Cu")
		(net "M_B_CPU1_SA_DQ<6>")
	)
	(segment
		(start 76.507086 -221.119446)
		(end 76.507086 -222.447104)
		(width 0.14478)
		(layer "In13.Cu")
		(net "M_B_CPU1_SA_DQ<6>")
	)
	(segment
		(start 87.560658 -228.803708)
		(end 87.656924 -228.829108)
		(width 0.0889)
		(layer "In13.Cu")
		(net "M_B_CPU1_SA_DQ<6>")
	)
	(segment
		(start 84.803996 -228.771958)
		(end 84.812378 -228.767132)
		(width 0.0889)
		(layer "In13.Cu")
		(net "M_B_CPU1_SA_DQ<6>")
	)
	(segment
		(start 79.538322 -225.531934)
		(end 79.570072 -225.550222)
		(width 0.0889)
		(layer "In13.Cu")
		(net "M_B_CPU1_SA_DQ<6>")
	)
	(segment
		(start 80.439006 -227.129086)
		(end 80.478122 -227.151946)
		(width 0.0889)
		(layer "In13.Cu")
		(net "M_B_CPU1_SA_DQ<6>")
	)
	(segment
		(start 83.289648 -228.767132)
		(end 83.29803 -228.771958)
		(width 0.0889)
		(layer "In13.Cu")
		(net "M_B_CPU1_SA_DQ<6>")
	)
	(segment
		(start 77.9526 -223.075246)
		(end 77.96022 -223.075246)
		(width 0.0889)
		(layer "In13.Cu")
		(net "M_B_CPU1_SA_DQ<6>")
	)
	(segment
		(start 80.478122 -227.151946)
		(end 80.509872 -227.170234)
		(width 0.0889)
		(layer "In13.Cu")
		(net "M_B_CPU1_SA_DQ<6>")
	)
	(segment
		(start 49.797462 -204.135228)
		(end 50.222404 -203.710286)
		(width 0.14478)
		(layer "In13.Cu")
		(net "M_B_CPU1_SA_DQ<6>")
	)
	(segment
		(start 76.507086 -222.447104)
		(end 76.651866 -222.591884)
		(width 0.14478)
		(layer "In13.Cu")
		(net "M_B_CPU1_SA_DQ<6>")
	)
	(segment
		(start 59.376818 -204.560424)
		(end 63.22441 -208.408016)
		(width 0.14478)
		(layer "In13.Cu")
		(net "M_B_CPU1_SA_DQ<6>")
	)
	(segment
		(start 79.497936 -225.508312)
		(end 79.538322 -225.531934)
		(width 0.0889)
		(layer "In13.Cu")
		(net "M_B_CPU1_SA_DQ<6>")
	)
	(segment
		(start 84.229702 -228.767132)
		(end 84.238084 -228.771958)
		(width 0.0889)
		(layer "In13.Cu")
		(net "M_B_CPU1_SA_DQ<6>")
	)
	(segment
		(start 49.151794 -204.658468)
		(end 49.296574 -204.513688)
		(width 0.14478)
		(layer "In13.Cu")
		(net "M_B_CPU1_SA_DQ<6>")
	)
	(segment
		(start 87.656924 -228.829108)
		(end 87.811102 -229.094538)
		(width 0.0889)
		(layer "In13.Cu")
		(net "M_B_CPU1_SA_DQ<6>")
	)
	(segment
		(start 80.008222 -226.34194)
		(end 80.038702 -226.35972)
		(width 0.0889)
		(layer "In13.Cu")
		(net "M_B_CPU1_SA_DQ<6>")
	)
	(segment
		(start 49.296574 -204.280008)
		(end 49.441354 -204.135228)
		(width 0.14478)
		(layer "In13.Cu")
		(net "M_B_CPU1_SA_DQ<6>")
	)
	(segment
		(start 47.784004 -204.135228)
		(end 48.600614 -204.135228)
		(width 0.14478)
		(layer "In13.Cu")
		(net "M_B_CPU1_SA_DQ<6>")
	)
	(segment
		(start 48.745394 -204.280008)
		(end 48.745394 -204.513688)
		(width 0.14478)
		(layer "In13.Cu")
		(net "M_B_CPU1_SA_DQ<6>")
	)
	(segment
		(start 81.37906 -228.749098)
		(end 81.418176 -228.771958)
		(width 0.0889)
		(layer "In13.Cu")
		(net "M_B_CPU1_SA_DQ<6>")
	)
	(segment
		(start 77.208126 -222.591884)
		(end 77.50683 -222.890588)
		(width 0.0889)
		(layer "In13.Cu")
		(net "M_B_CPU1_SA_DQ<6>")
	)
	(segment
		(start 76.651866 -222.591884)
		(end 77.208126 -222.591884)
		(width 0.14478)
		(layer "In13.Cu")
		(net "M_B_CPU1_SA_DQ<6>")
	)
	(segment
		(start 79.9719 -226.320858)
		(end 80.008222 -226.34194)
		(width 0.0889)
		(layer "In13.Cu")
		(net "M_B_CPU1_SA_DQ<6>")
	)
	(segment
		(start 49.441354 -204.135228)
		(end 49.797462 -204.135228)
		(width 0.14478)
		(layer "In13.Cu")
		(net "M_B_CPU1_SA_DQ<6>")
	)
	(segment
		(start 48.745394 -204.513688)
		(end 48.890174 -204.658468)
		(width 0.14478)
		(layer "In13.Cu")
		(net "M_B_CPU1_SA_DQ<6>")
	)
	(segment
		(start 63.795656 -208.408016)
		(end 76.507086 -221.119446)
		(width 0.14478)
		(layer "In13.Cu")
		(net "M_B_CPU1_SA_DQ<6>")
	)
	(segment
		(start 53.256434 -203.710286)
		(end 54.106572 -204.560424)
		(width 0.14478)
		(layer "In13.Cu")
		(net "M_B_CPU1_SA_DQ<6>")
	)
	(segment
		(start 79.028036 -224.698306)
		(end 79.068422 -224.721928)
		(width 0.0889)
		(layer "In13.Cu")
		(net "M_B_CPU1_SA_DQ<6>")
	)
	(segment
		(start 80.9117 -227.94087)
		(end 80.948022 -227.961952)
		(width 0.0889)
		(layer "In13.Cu")
		(net "M_B_CPU1_SA_DQ<6>")
	)
	(segment
		(start 78.56474 -223.892618)
		(end 78.631796 -223.93148)
		(width 0.0889)
		(layer "In13.Cu")
		(net "M_B_CPU1_SA_DQ<6>")
	)
	(segment
		(start 80.948022 -227.961952)
		(end 80.979772 -227.98024)
		(width 0.0889)
		(layer "In13.Cu")
		(net "M_B_CPU1_SA_DQ<6>")
	)
	(arc
		(start 83.29803 -228.771958)
		(mid 83.580986 -228.848135)
		(end 83.863942 -228.771958)
		(width 0.0889)
		(layer "In13.Cu")
		(net "M_B_CPU1_SA_DQ<6>")
	)
	(arc
		(start 79.25562 -225.044508)
		(mid 79.319913 -225.306113)
		(end 79.497936 -225.508312)
		(width 0.0889)
		(layer "In13.Cu")
		(net "M_B_CPU1_SA_DQ<6>")
	)
	(arc
		(start 85.178138 -228.771958)
		(mid 85.461094 -228.848135)
		(end 85.74405 -228.771958)
		(width 0.0889)
		(layer "In13.Cu")
		(net "M_B_CPU1_SA_DQ<6>")
	)
	(arc
		(start 78.785974 -224.234502)
		(mid 78.850127 -224.496091)
		(end 79.028036 -224.698306)
		(width 0.0889)
		(layer "In13.Cu")
		(net "M_B_CPU1_SA_DQ<6>")
	)
	(arc
		(start 79.726028 -225.854514)
		(mid 79.791264 -226.118105)
		(end 79.9719 -226.320858)
		(width 0.0889)
		(layer "In13.Cu")
		(net "M_B_CPU1_SA_DQ<6>")
	)
	(arc
		(start 78.631796 -223.93148)
		(mid 78.745203 -224.06451)
		(end 78.785974 -224.234502)
		(width 0.0889)
		(layer "In13.Cu")
		(net "M_B_CPU1_SA_DQ<6>")
	)
	(arc
		(start 79.097886 -224.738946)
		(mid 79.213839 -224.872579)
		(end 79.25562 -225.044508)
		(width 0.0889)
		(layer "In13.Cu")
		(net "M_B_CPU1_SA_DQ<6>")
	)
	(arc
		(start 87.057992 -228.771958)
		(mid 87.305588 -228.847136)
		(end 87.560658 -228.803708)
		(width 0.0889)
		(layer "In13.Cu")
		(net "M_B_CPU1_SA_DQ<6>")
	)
	(arc
		(start 80.038702 -226.35972)
		(mid 80.154129 -226.493096)
		(end 80.195674 -226.66452)
		(width 0.0889)
		(layer "In13.Cu")
		(net "M_B_CPU1_SA_DQ<6>")
	)
	(arc
		(start 81.135728 -228.284532)
		(mid 81.200243 -228.546751)
		(end 81.37906 -228.749098)
		(width 0.0889)
		(layer "In13.Cu")
		(net "M_B_CPU1_SA_DQ<6>")
	)
	(arc
		(start 78.30947 -223.424496)
		(mid 78.351256 -223.63466)
		(end 78.470252 -223.812862)
		(width 0.0889)
		(layer "In13.Cu")
		(net "M_B_CPU1_SA_DQ<6>")
	)
	(arc
		(start 85.752432 -228.767132)
		(mid 85.93594 -228.721638)
		(end 86.118192 -228.771958)
		(width 0.0889)
		(layer "In13.Cu")
		(net "M_B_CPU1_SA_DQ<6>")
	)
	(arc
		(start 82.357976 -228.771958)
		(mid 82.640932 -228.848135)
		(end 82.923888 -228.771958)
		(width 0.0889)
		(layer "In13.Cu")
		(net "M_B_CPU1_SA_DQ<6>")
	)
	(arc
		(start 84.238084 -228.771958)
		(mid 84.52104 -228.848135)
		(end 84.803996 -228.771958)
		(width 0.0889)
		(layer "In13.Cu")
		(net "M_B_CPU1_SA_DQ<6>")
	)
	(arc
		(start 81.984088 -228.771958)
		(mid 82.171032 -228.721703)
		(end 82.357976 -228.771958)
		(width 0.0889)
		(layer "In13.Cu")
		(net "M_B_CPU1_SA_DQ<6>")
	)
	(arc
		(start 82.923888 -228.771958)
		(mid 83.106139 -228.721608)
		(end 83.289648 -228.767132)
		(width 0.0889)
		(layer "In13.Cu")
		(net "M_B_CPU1_SA_DQ<6>")
	)
	(arc
		(start 84.812378 -228.767132)
		(mid 84.995886 -228.721638)
		(end 85.178138 -228.771958)
		(width 0.0889)
		(layer "In13.Cu")
		(net "M_B_CPU1_SA_DQ<6>")
	)
	(arc
		(start 81.418176 -228.771958)
		(mid 81.701132 -228.848135)
		(end 81.984088 -228.771958)
		(width 0.0889)
		(layer "In13.Cu")
		(net "M_B_CPU1_SA_DQ<6>")
	)
	(arc
		(start 78.481428 -223.824038)
		(mid 78.52144 -223.860325)
		(end 78.56474 -223.892618)
		(width 0.0889)
		(layer "In13.Cu")
		(net "M_B_CPU1_SA_DQ<6>")
	)
	(arc
		(start 77.50683 -222.890588)
		(mid 77.711351 -223.027245)
		(end 77.9526 -223.075246)
		(width 0.0889)
		(layer "In13.Cu")
		(net "M_B_CPU1_SA_DQ<6>")
	)
	(arc
		(start 86.684104 -228.771958)
		(mid 86.871048 -228.721703)
		(end 87.057992 -228.771958)
		(width 0.0889)
		(layer "In13.Cu")
		(net "M_B_CPU1_SA_DQ<6>")
	)
	(arc
		(start 77.96022 -223.075246)
		(mid 78.207177 -223.177539)
		(end 78.30947 -223.424496)
		(width 0.0889)
		(layer "In13.Cu")
		(net "M_B_CPU1_SA_DQ<6>")
	)
	(arc
		(start 79.570072 -225.550222)
		(mid 79.684748 -225.683556)
		(end 79.726028 -225.854514)
		(width 0.0889)
		(layer "In13.Cu")
		(net "M_B_CPU1_SA_DQ<6>")
	)
	(arc
		(start 86.118192 -228.771958)
		(mid 86.401148 -228.848135)
		(end 86.684104 -228.771958)
		(width 0.0889)
		(layer "In13.Cu")
		(net "M_B_CPU1_SA_DQ<6>")
	)
	(arc
		(start 83.863942 -228.771958)
		(mid 84.046193 -228.721608)
		(end 84.229702 -228.767132)
		(width 0.0889)
		(layer "In13.Cu")
		(net "M_B_CPU1_SA_DQ<6>")
	)
	(arc
		(start 80.509872 -227.170234)
		(mid 80.624548 -227.303568)
		(end 80.665828 -227.474526)
		(width 0.0889)
		(layer "In13.Cu")
		(net "M_B_CPU1_SA_DQ<6>")
	)
	(arc
		(start 80.665828 -227.474526)
		(mid 80.731064 -227.738117)
		(end 80.9117 -227.94087)
		(width 0.0889)
		(layer "In13.Cu")
		(net "M_B_CPU1_SA_DQ<6>")
	)
	(arc
		(start 80.979772 -227.98024)
		(mid 81.094448 -228.113574)
		(end 81.135728 -228.284532)
		(width 0.0889)
		(layer "In13.Cu")
		(net "M_B_CPU1_SA_DQ<6>")
	)
	(arc
		(start 80.195674 -226.66452)
		(mid 80.260189 -226.926739)
		(end 80.439006 -227.129086)
		(width 0.0889)
		(layer "In13.Cu")
		(net "M_B_CPU1_SA_DQ<6>")
	)
	(segment
		(start 89.218008 -229.360476)
		(end 88.751156 -229.094538)
		(width 0.10668)
		(layer "F.Cu")
		(net "M_B_CPU1_SA_DQ<5>")
	)
	(segment
		(start 79.164434 -226.177856)
		(end 79.200756 -226.198938)
		(width 0.0889)
		(layer "In13.Cu")
		(net "M_B_CPU1_SA_DQ<5>")
	)
	(segment
		(start 80.542384 -228.588824)
		(end 80.574134 -228.607112)
		(width 0.0889)
		(layer "In13.Cu")
		(net "M_B_CPU1_SA_DQ<5>")
	)
	(segment
		(start 55.79745 -205.410308)
		(end 55.960518 -205.573376)
		(width 0.14478)
		(layer "In13.Cu")
		(net "M_B_CPU1_SA_DQ<5>")
	)
	(segment
		(start 87.989664 -229.42169)
		(end 87.998046 -229.416864)
		(width 0.0889)
		(layer "In13.Cu")
		(net "M_B_CPU1_SA_DQ<5>")
	)
	(segment
		(start 67.035426 -212.650324)
		(end 67.035426 -212.855048)
		(width 0.14478)
		(layer "In13.Cu")
		(net "M_B_CPU1_SA_DQ<5>")
	)
	(segment
		(start 67.058286 -212.422486)
		(end 67.05854 -212.62721)
		(width 0.14478)
		(layer "In13.Cu")
		(net "M_B_CPU1_SA_DQ<5>")
	)
	(segment
		(start 53.23459 -204.560424)
		(end 54.084474 -205.410308)
		(width 0.14478)
		(layer "In13.Cu")
		(net "M_B_CPU1_SA_DQ<5>")
	)
	(segment
		(start 78.19644 -224.541588)
		(end 78.224126 -224.55759)
		(width 0.0889)
		(layer "In13.Cu")
		(net "M_B_CPU1_SA_DQ<5>")
	)
	(segment
		(start 57.965086 -205.206346)
		(end 58.193432 -205.206346)
		(width 0.14478)
		(layer "In13.Cu")
		(net "M_B_CPU1_SA_DQ<5>")
	)
	(segment
		(start 65.661286 -211.480908)
		(end 65.865502 -211.480654)
		(width 0.14478)
		(layer "In13.Cu")
		(net "M_B_CPU1_SA_DQ<5>")
	)
	(segment
		(start 65.888616 -211.45754)
		(end 66.09334 -211.45754)
		(width 0.14478)
		(layer "In13.Cu")
		(net "M_B_CPU1_SA_DQ<5>")
	)
	(segment
		(start 63.754 -209.1182)
		(end 63.939166 -209.303366)
		(width 0.14478)
		(layer "In13.Cu")
		(net "M_B_CPU1_SA_DQ<5>")
	)
	(segment
		(start 65.085722 -210.700874)
		(end 65.108836 -210.67776)
		(width 0.14478)
		(layer "In13.Cu")
		(net "M_B_CPU1_SA_DQ<5>")
	)
	(segment
		(start 66.278506 -211.642706)
		(end 66.27876 -211.84743)
		(width 0.14478)
		(layer "In13.Cu")
		(net "M_B_CPU1_SA_DQ<5>")
	)
	(segment
		(start 76.029566 -221.849188)
		(end 76.029566 -222.650304)
		(width 0.14478)
		(layer "In13.Cu")
		(net "M_B_CPU1_SA_DQ<5>")
	)
	(segment
		(start 68.000626 -213.820248)
		(end 68.204842 -213.819994)
		(width 0.14478)
		(layer "In13.Cu")
		(net "M_B_CPU1_SA_DQ<5>")
	)
	(segment
		(start 67.220846 -213.040468)
		(end 67.425062 -213.040214)
		(width 0.14478)
		(layer "In13.Cu")
		(net "M_B_CPU1_SA_DQ<5>")
	)
	(segment
		(start 63.916306 -209.531204)
		(end 63.916306 -209.735928)
		(width 0.14478)
		(layer "In13.Cu")
		(net "M_B_CPU1_SA_DQ<5>")
	)
	(segment
		(start 66.645282 -212.260434)
		(end 66.668396 -212.23732)
		(width 0.14478)
		(layer "In13.Cu")
		(net "M_B_CPU1_SA_DQ<5>")
	)
	(segment
		(start 78.224126 -224.55759)
		(end 78.251558 -224.573592)
		(width 0.0889)
		(layer "In13.Cu")
		(net "M_B_CPU1_SA_DQ<5>")
	)
	(segment
		(start 63.93942 -209.50809)
		(end 63.916306 -209.531204)
		(width 0.14478)
		(layer "In13.Cu")
		(net "M_B_CPU1_SA_DQ<5>")
	)
	(segment
		(start 57.803542 -205.646782)
		(end 57.803542 -205.36789)
		(width 0.14478)
		(layer "In13.Cu")
		(net "M_B_CPU1_SA_DQ<5>")
	)
	(segment
		(start 66.27876 -211.84743)
		(end 66.255646 -211.870544)
		(width 0.14478)
		(layer "In13.Cu")
		(net "M_B_CPU1_SA_DQ<5>")
	)
	(segment
		(start 67.448176 -213.0171)
		(end 67.6529 -213.0171)
		(width 0.14478)
		(layer "In13.Cu")
		(net "M_B_CPU1_SA_DQ<5>")
	)
	(segment
		(start 66.255646 -211.870544)
		(end 66.255646 -212.075268)
		(width 0.14478)
		(layer "In13.Cu")
		(net "M_B_CPU1_SA_DQ<5>")
	)
	(segment
		(start 58.744866 -205.808326)
		(end 58.90641 -205.646782)
		(width 0.14478)
		(layer "In13.Cu")
		(net "M_B_CPU1_SA_DQ<5>")
	)
	(segment
		(start 64.696086 -210.515708)
		(end 64.881506 -210.701128)
		(width 0.14478)
		(layer "In13.Cu")
		(net "M_B_CPU1_SA_DQ<5>")
	)
	(segment
		(start 54.084474 -205.410308)
		(end 54.684422 -205.410308)
		(width 0.14478)
		(layer "In13.Cu")
		(net "M_B_CPU1_SA_DQ<5>")
	)
	(segment
		(start 67.035426 -212.855048)
		(end 67.220846 -213.040468)
		(width 0.14478)
		(layer "In13.Cu")
		(net "M_B_CPU1_SA_DQ<5>")
	)
	(segment
		(start 64.718946 -210.083146)
		(end 64.7192 -210.28787)
		(width 0.14478)
		(layer "In13.Cu")
		(net "M_B_CPU1_SA_DQ<5>")
	)
	(segment
		(start 57.090564 -205.410308)
		(end 57.252108 -205.571852)
		(width 0.14478)
		(layer "In13.Cu")
		(net "M_B_CPU1_SA_DQ<5>")
	)
	(segment
		(start 55.010558 -205.792324)
		(end 55.240936 -205.792324)
		(width 0.14478)
		(layer "In13.Cu")
		(net "M_B_CPU1_SA_DQ<5>")
	)
	(segment
		(start 88.90508 -229.359968)
		(end 88.751156 -229.094538)
		(width 0.0889)
		(layer "In13.Cu")
		(net "M_B_CPU1_SA_DQ<5>")
	)
	(segment
		(start 56.123586 -205.792324)
		(end 56.353964 -205.792324)
		(width 0.14478)
		(layer "In13.Cu")
		(net "M_B_CPU1_SA_DQ<5>")
	)
	(segment
		(start 58.51652 -205.808326)
		(end 58.744866 -205.808326)
		(width 0.14478)
		(layer "In13.Cu")
		(net "M_B_CPU1_SA_DQ<5>")
	)
	(segment
		(start 80.10398 -227.797106)
		(end 80.143096 -227.819966)
		(width 0.0889)
		(layer "In13.Cu")
		(net "M_B_CPU1_SA_DQ<5>")
	)
	(segment
		(start 81.010506 -229.397306)
		(end 81.044034 -229.416864)
		(width 0.0889)
		(layer "In13.Cu")
		(net "M_B_CPU1_SA_DQ<5>")
	)
	(segment
		(start 65.108836 -210.67776)
		(end 65.31356 -210.67776)
		(width 0.14478)
		(layer "In13.Cu")
		(net "M_B_CPU1_SA_DQ<5>")
	)
	(segment
		(start 69.397626 -214.761826)
		(end 69.39788 -214.96655)
		(width 0.14478)
		(layer "In13.Cu")
		(net "M_B_CPU1_SA_DQ<5>")
	)
	(segment
		(start 66.09334 -211.45754)
		(end 66.278506 -211.642706)
		(width 0.14478)
		(layer "In13.Cu")
		(net "M_B_CPU1_SA_DQ<5>")
	)
	(segment
		(start 56.353964 -205.792324)
		(end 56.517032 -205.629256)
		(width 0.14478)
		(layer "In13.Cu")
		(net "M_B_CPU1_SA_DQ<5>")
	)
	(segment
		(start 66.441066 -212.260688)
		(end 66.645282 -212.260434)
		(width 0.14478)
		(layer "In13.Cu")
		(net "M_B_CPU1_SA_DQ<5>")
	)
	(segment
		(start 67.05854 -212.62721)
		(end 67.035426 -212.650324)
		(width 0.14478)
		(layer "In13.Cu")
		(net "M_B_CPU1_SA_DQ<5>")
	)
	(segment
		(start 81.044034 -229.416864)
		(end 81.052416 -229.42169)
		(width 0.0889)
		(layer "In13.Cu")
		(net "M_B_CPU1_SA_DQ<5>")
	)
	(segment
		(start 65.865502 -211.480654)
		(end 65.888616 -211.45754)
		(width 0.14478)
		(layer "In13.Cu")
		(net "M_B_CPU1_SA_DQ<5>")
	)
	(segment
		(start 78.694026 -225.367088)
		(end 78.733142 -225.389948)
		(width 0.0889)
		(layer "In13.Cu")
		(net "M_B_CPU1_SA_DQ<5>")
	)
	(segment
		(start 68.780406 -214.600028)
		(end 68.984622 -214.599774)
		(width 0.14478)
		(layer "In13.Cu")
		(net "M_B_CPU1_SA_DQ<5>")
	)
	(segment
		(start 63.526162 -209.141314)
		(end 63.549276 -209.1182)
		(width 0.14478)
		(layer "In13.Cu")
		(net "M_B_CPU1_SA_DQ<5>")
	)
	(segment
		(start 69.374766 -214.989664)
		(end 69.374766 -215.194388)
		(width 0.14478)
		(layer "In13.Cu")
		(net "M_B_CPU1_SA_DQ<5>")
	)
	(segment
		(start 68.204842 -213.819994)
		(end 68.227956 -213.79688)
		(width 0.14478)
		(layer "In13.Cu")
		(net "M_B_CPU1_SA_DQ<5>")
	)
	(segment
		(start 63.916306 -209.735928)
		(end 64.101726 -209.921348)
		(width 0.14478)
		(layer "In13.Cu")
		(net "M_B_CPU1_SA_DQ<5>")
	)
	(segment
		(start 54.684422 -205.410308)
		(end 54.84749 -205.573376)
		(width 0.14478)
		(layer "In13.Cu")
		(net "M_B_CPU1_SA_DQ<5>")
	)
	(segment
		(start 57.803542 -205.36789)
		(end 57.965086 -205.206346)
		(width 0.14478)
		(layer "In13.Cu")
		(net "M_B_CPU1_SA_DQ<5>")
	)
	(segment
		(start 79.63408 -226.987354)
		(end 79.669386 -227.007928)
		(width 0.0889)
		(layer "In13.Cu")
		(net "M_B_CPU1_SA_DQ<5>")
	)
	(segment
		(start 59.067954 -205.410308)
		(end 59.590686 -205.410308)
		(width 0.14478)
		(layer "In13.Cu")
		(net "M_B_CPU1_SA_DQ<5>")
	)
	(segment
		(start 67.83832 -213.40699)
		(end 67.815206 -213.430104)
		(width 0.14478)
		(layer "In13.Cu")
		(net "M_B_CPU1_SA_DQ<5>")
	)
	(segment
		(start 64.696086 -210.310984)
		(end 64.696086 -210.515708)
		(width 0.14478)
		(layer "In13.Cu")
		(net "M_B_CPU1_SA_DQ<5>")
	)
	(segment
		(start 69.007736 -214.57666)
		(end 69.21246 -214.57666)
		(width 0.14478)
		(layer "In13.Cu")
		(net "M_B_CPU1_SA_DQ<5>")
	)
	(segment
		(start 56.517032 -205.573376)
		(end 56.6801 -205.410308)
		(width 0.14478)
		(layer "In13.Cu")
		(net "M_B_CPU1_SA_DQ<5>")
	)
	(segment
		(start 68.6181 -214.18677)
		(end 68.594986 -214.209884)
		(width 0.14478)
		(layer "In13.Cu")
		(net "M_B_CPU1_SA_DQ<5>")
	)
	(segment
		(start 69.21246 -214.57666)
		(end 69.397626 -214.761826)
		(width 0.14478)
		(layer "In13.Cu")
		(net "M_B_CPU1_SA_DQ<5>")
	)
	(segment
		(start 56.6801 -205.410308)
		(end 57.090564 -205.410308)
		(width 0.14478)
		(layer "In13.Cu")
		(net "M_B_CPU1_SA_DQ<5>")
	)
	(segment
		(start 65.31356 -210.67776)
		(end 65.498726 -210.862926)
		(width 0.14478)
		(layer "In13.Cu")
		(net "M_B_CPU1_SA_DQ<5>")
	)
	(segment
		(start 64.53378 -209.89798)
		(end 64.718946 -210.083146)
		(width 0.14478)
		(layer "In13.Cu")
		(net "M_B_CPU1_SA_DQ<5>")
	)
	(segment
		(start 63.549276 -209.1182)
		(end 63.754 -209.1182)
		(width 0.14478)
		(layer "In13.Cu")
		(net "M_B_CPU1_SA_DQ<5>")
	)
	(segment
		(start 64.7192 -210.28787)
		(end 64.696086 -210.310984)
		(width 0.14478)
		(layer "In13.Cu")
		(net "M_B_CPU1_SA_DQ<5>")
	)
	(segment
		(start 77.477874 -223.487996)
		(end 77.714856 -223.724978)
		(width 0.0889)
		(layer "In13.Cu")
		(net "M_B_CPU1_SA_DQ<5>")
	)
	(segment
		(start 77.75448 -223.747838)
		(end 77.79766 -223.772984)
		(width 0.0889)
		(layer "In13.Cu")
		(net "M_B_CPU1_SA_DQ<5>")
	)
	(segment
		(start 78.664562 -225.35007)
		(end 78.694026 -225.367088)
		(width 0.0889)
		(layer "In13.Cu")
		(net "M_B_CPU1_SA_DQ<5>")
	)
	(segment
		(start 69.374766 -215.194388)
		(end 76.029566 -221.849188)
		(width 0.14478)
		(layer "In13.Cu")
		(net "M_B_CPU1_SA_DQ<5>")
	)
	(segment
		(start 55.404004 -205.629256)
		(end 55.404004 -205.573376)
		(width 0.14478)
		(layer "In13.Cu")
		(net "M_B_CPU1_SA_DQ<5>")
	)
	(segment
		(start 67.6529 -213.0171)
		(end 67.838066 -213.202266)
		(width 0.14478)
		(layer "In13.Cu")
		(net "M_B_CPU1_SA_DQ<5>")
	)
	(segment
		(start 67.425062 -213.040214)
		(end 67.448176 -213.0171)
		(width 0.14478)
		(layer "In13.Cu")
		(net "M_B_CPU1_SA_DQ<5>")
	)
	(segment
		(start 65.498726 -210.862926)
		(end 65.49898 -211.06765)
		(width 0.14478)
		(layer "In13.Cu")
		(net "M_B_CPU1_SA_DQ<5>")
	)
	(segment
		(start 57.413652 -205.808326)
		(end 57.641998 -205.808326)
		(width 0.14478)
		(layer "In13.Cu")
		(net "M_B_CPU1_SA_DQ<5>")
	)
	(segment
		(start 52.309014 -204.560424)
		(end 53.23459 -204.560424)
		(width 0.14478)
		(layer "In13.Cu")
		(net "M_B_CPU1_SA_DQ<5>")
	)
	(segment
		(start 55.960518 -205.629256)
		(end 56.123586 -205.792324)
		(width 0.14478)
		(layer "In13.Cu")
		(net "M_B_CPU1_SA_DQ<5>")
	)
	(segment
		(start 68.594986 -214.414608)
		(end 68.780406 -214.600028)
		(width 0.14478)
		(layer "In13.Cu")
		(net "M_B_CPU1_SA_DQ<5>")
	)
	(segment
		(start 84.803996 -229.416864)
		(end 84.812378 -229.42169)
		(width 0.0889)
		(layer "In13.Cu")
		(net "M_B_CPU1_SA_DQ<5>")
	)
	(segment
		(start 80.574134 -228.607112)
		(end 80.610456 -228.628194)
		(width 0.0889)
		(layer "In13.Cu")
		(net "M_B_CPU1_SA_DQ<5>")
	)
	(segment
		(start 84.229702 -229.42169)
		(end 84.238084 -229.416864)
		(width 0.0889)
		(layer "In13.Cu")
		(net "M_B_CPU1_SA_DQ<5>")
	)
	(segment
		(start 69.39788 -214.96655)
		(end 69.374766 -214.989664)
		(width 0.14478)
		(layer "In13.Cu")
		(net "M_B_CPU1_SA_DQ<5>")
	)
	(segment
		(start 66.255646 -212.075268)
		(end 66.441066 -212.260688)
		(width 0.14478)
		(layer "In13.Cu")
		(net "M_B_CPU1_SA_DQ<5>")
	)
	(segment
		(start 68.594986 -214.209884)
		(end 68.594986 -214.414608)
		(width 0.14478)
		(layer "In13.Cu")
		(net "M_B_CPU1_SA_DQ<5>")
	)
	(segment
		(start 58.354976 -205.646782)
		(end 58.51652 -205.808326)
		(width 0.14478)
		(layer "In13.Cu")
		(net "M_B_CPU1_SA_DQ<5>")
	)
	(segment
		(start 55.240936 -205.792324)
		(end 55.404004 -205.629256)
		(width 0.14478)
		(layer "In13.Cu")
		(net "M_B_CPU1_SA_DQ<5>")
	)
	(segment
		(start 55.404004 -205.573376)
		(end 55.567072 -205.410308)
		(width 0.14478)
		(layer "In13.Cu")
		(net "M_B_CPU1_SA_DQ<5>")
	)
	(segment
		(start 68.984622 -214.599774)
		(end 69.007736 -214.57666)
		(width 0.14478)
		(layer "In13.Cu")
		(net "M_B_CPU1_SA_DQ<5>")
	)
	(segment
		(start 80.0735 -227.779326)
		(end 80.10398 -227.797106)
		(width 0.0889)
		(layer "In13.Cu")
		(net "M_B_CPU1_SA_DQ<5>")
	)
	(segment
		(start 58.90641 -205.571852)
		(end 59.067954 -205.410308)
		(width 0.14478)
		(layer "In13.Cu")
		(net "M_B_CPU1_SA_DQ<5>")
	)
	(segment
		(start 85.74405 -229.416864)
		(end 85.752432 -229.42169)
		(width 0.0889)
		(layer "In13.Cu")
		(net "M_B_CPU1_SA_DQ<5>")
	)
	(segment
		(start 57.641998 -205.808326)
		(end 57.803542 -205.646782)
		(width 0.14478)
		(layer "In13.Cu")
		(net "M_B_CPU1_SA_DQ<5>")
	)
	(segment
		(start 64.329056 -209.89798)
		(end 64.53378 -209.89798)
		(width 0.14478)
		(layer "In13.Cu")
		(net "M_B_CPU1_SA_DQ<5>")
	)
	(segment
		(start 79.128874 -226.157282)
		(end 79.164434 -226.177856)
		(width 0.0889)
		(layer "In13.Cu")
		(net "M_B_CPU1_SA_DQ<5>")
	)
	(segment
		(start 57.252108 -205.571852)
		(end 57.252108 -205.646782)
		(width 0.14478)
		(layer "In13.Cu")
		(net "M_B_CPU1_SA_DQ<5>")
	)
	(segment
		(start 64.881506 -210.701128)
		(end 65.085722 -210.700874)
		(width 0.14478)
		(layer "In13.Cu")
		(net "M_B_CPU1_SA_DQ<5>")
	)
	(segment
		(start 58.193432 -205.206346)
		(end 58.354976 -205.36789)
		(width 0.14478)
		(layer "In13.Cu")
		(net "M_B_CPU1_SA_DQ<5>")
	)
	(segment
		(start 68.43268 -213.79688)
		(end 68.617846 -213.982046)
		(width 0.14478)
		(layer "In13.Cu")
		(net "M_B_CPU1_SA_DQ<5>")
	)
	(segment
		(start 65.475866 -211.295488)
		(end 65.661286 -211.480908)
		(width 0.14478)
		(layer "In13.Cu")
		(net "M_B_CPU1_SA_DQ<5>")
	)
	(segment
		(start 88.882728 -229.443026)
		(end 88.90508 -229.359968)
		(width 0.0889)
		(layer "In13.Cu")
		(net "M_B_CPU1_SA_DQ<5>")
	)
	(segment
		(start 55.567072 -205.410308)
		(end 55.79745 -205.410308)
		(width 0.14478)
		(layer "In13.Cu")
		(net "M_B_CPU1_SA_DQ<5>")
	)
	(segment
		(start 77.180948 -223.046544)
		(end 77.375766 -223.241362)
		(width 0.0889)
		(layer "In13.Cu")
		(net "M_B_CPU1_SA_DQ<5>")
	)
	(segment
		(start 56.517032 -205.629256)
		(end 56.517032 -205.573376)
		(width 0.14478)
		(layer "In13.Cu")
		(net "M_B_CPU1_SA_DQ<5>")
	)
	(segment
		(start 76.029566 -222.650304)
		(end 76.425806 -223.046544)
		(width 0.14478)
		(layer "In13.Cu")
		(net "M_B_CPU1_SA_DQ<5>")
	)
	(segment
		(start 76.425806 -223.046544)
		(end 76.964286 -223.046544)
		(width 0.14478)
		(layer "In13.Cu")
		(net "M_B_CPU1_SA_DQ<5>")
	)
	(segment
		(start 54.84749 -205.629256)
		(end 55.010558 -205.792324)
		(width 0.14478)
		(layer "In13.Cu")
		(net "M_B_CPU1_SA_DQ<5>")
	)
	(segment
		(start 67.838066 -213.202266)
		(end 67.83832 -213.40699)
		(width 0.14478)
		(layer "In13.Cu")
		(net "M_B_CPU1_SA_DQ<5>")
	)
	(segment
		(start 76.964286 -223.046544)
		(end 77.180948 -223.046544)
		(width 0.0889)
		(layer "In13.Cu")
		(net "M_B_CPU1_SA_DQ<5>")
	)
	(segment
		(start 59.590686 -205.410308)
		(end 63.321946 -209.141568)
		(width 0.14478)
		(layer "In13.Cu")
		(net "M_B_CPU1_SA_DQ<5>")
	)
	(segment
		(start 51.884072 -204.985366)
		(end 52.309014 -204.560424)
		(width 0.14478)
		(layer "In13.Cu")
		(net "M_B_CPU1_SA_DQ<5>")
	)
	(segment
		(start 68.227956 -213.79688)
		(end 68.43268 -213.79688)
		(width 0.14478)
		(layer "In13.Cu")
		(net "M_B_CPU1_SA_DQ<5>")
	)
	(segment
		(start 58.354976 -205.36789)
		(end 58.354976 -205.646782)
		(width 0.14478)
		(layer "In13.Cu")
		(net "M_B_CPU1_SA_DQ<5>")
	)
	(segment
		(start 67.815206 -213.430104)
		(end 67.815206 -213.634828)
		(width 0.14478)
		(layer "In13.Cu")
		(net "M_B_CPU1_SA_DQ<5>")
	)
	(segment
		(start 65.475866 -211.090764)
		(end 65.475866 -211.295488)
		(width 0.14478)
		(layer "In13.Cu")
		(net "M_B_CPU1_SA_DQ<5>")
	)
	(segment
		(start 65.49898 -211.06765)
		(end 65.475866 -211.090764)
		(width 0.14478)
		(layer "In13.Cu")
		(net "M_B_CPU1_SA_DQ<5>")
	)
	(segment
		(start 63.939166 -209.303366)
		(end 63.93942 -209.50809)
		(width 0.14478)
		(layer "In13.Cu")
		(net "M_B_CPU1_SA_DQ<5>")
	)
	(segment
		(start 63.321946 -209.141568)
		(end 63.526162 -209.141314)
		(width 0.14478)
		(layer "In13.Cu")
		(net "M_B_CPU1_SA_DQ<5>")
	)
	(segment
		(start 64.101726 -209.921348)
		(end 64.305942 -209.921094)
		(width 0.14478)
		(layer "In13.Cu")
		(net "M_B_CPU1_SA_DQ<5>")
	)
	(segment
		(start 77.714856 -223.724978)
		(end 77.75448 -223.747838)
		(width 0.0889)
		(layer "In13.Cu")
		(net "M_B_CPU1_SA_DQ<5>")
	)
	(segment
		(start 64.305942 -209.921094)
		(end 64.329056 -209.89798)
		(width 0.14478)
		(layer "In13.Cu")
		(net "M_B_CPU1_SA_DQ<5>")
	)
	(segment
		(start 66.668396 -212.23732)
		(end 66.87312 -212.23732)
		(width 0.14478)
		(layer "In13.Cu")
		(net "M_B_CPU1_SA_DQ<5>")
	)
	(segment
		(start 67.815206 -213.634828)
		(end 68.000626 -213.820248)
		(width 0.14478)
		(layer "In13.Cu")
		(net "M_B_CPU1_SA_DQ<5>")
	)
	(segment
		(start 55.960518 -205.573376)
		(end 55.960518 -205.629256)
		(width 0.14478)
		(layer "In13.Cu")
		(net "M_B_CPU1_SA_DQ<5>")
	)
	(segment
		(start 58.90641 -205.646782)
		(end 58.90641 -205.571852)
		(width 0.14478)
		(layer "In13.Cu")
		(net "M_B_CPU1_SA_DQ<5>")
	)
	(segment
		(start 66.87312 -212.23732)
		(end 67.058286 -212.422486)
		(width 0.14478)
		(layer "In13.Cu")
		(net "M_B_CPU1_SA_DQ<5>")
	)
	(segment
		(start 79.606902 -226.971606)
		(end 79.63408 -226.987354)
		(width 0.0889)
		(layer "In13.Cu")
		(net "M_B_CPU1_SA_DQ<5>")
	)
	(segment
		(start 57.252108 -205.646782)
		(end 57.413652 -205.808326)
		(width 0.14478)
		(layer "In13.Cu")
		(net "M_B_CPU1_SA_DQ<5>")
	)
	(segment
		(start 83.289648 -229.42169)
		(end 83.29803 -229.416864)
		(width 0.0889)
		(layer "In13.Cu")
		(net "M_B_CPU1_SA_DQ<5>")
	)
	(segment
		(start 54.84749 -205.573376)
		(end 54.84749 -205.629256)
		(width 0.14478)
		(layer "In13.Cu")
		(net "M_B_CPU1_SA_DQ<5>")
	)
	(segment
		(start 68.617846 -213.982046)
		(end 68.6181 -214.18677)
		(width 0.14478)
		(layer "In13.Cu")
		(net "M_B_CPU1_SA_DQ<5>")
	)
	(arc
		(start 78.251558 -224.573592)
		(mid 78.438428 -224.777032)
		(end 78.506574 -225.044762)
		(width 0.0889)
		(layer "In13.Cu")
		(net "M_B_CPU1_SA_DQ<5>")
	)
	(arc
		(start 81.418176 -229.416864)
		(mid 81.701132 -229.340687)
		(end 81.984088 -229.416864)
		(width 0.0889)
		(layer "In13.Cu")
		(net "M_B_CPU1_SA_DQ<5>")
	)
	(arc
		(start 85.178138 -229.416864)
		(mid 85.461094 -229.340687)
		(end 85.74405 -229.416864)
		(width 0.0889)
		(layer "In13.Cu")
		(net "M_B_CPU1_SA_DQ<5>")
	)
	(arc
		(start 77.375766 -223.241362)
		(mid 77.440809 -223.3388)
		(end 77.46365 -223.453706)
		(width 0.0889)
		(layer "In13.Cu")
		(net "M_B_CPU1_SA_DQ<5>")
	)
	(arc
		(start 87.998046 -229.416864)
		(mid 88.281002 -229.340687)
		(end 88.563958 -229.416864)
		(width 0.0889)
		(layer "In13.Cu")
		(net "M_B_CPU1_SA_DQ<5>")
	)
	(arc
		(start 86.118192 -229.416864)
		(mid 86.401148 -229.340687)
		(end 86.684104 -229.416864)
		(width 0.0889)
		(layer "In13.Cu")
		(net "M_B_CPU1_SA_DQ<5>")
	)
	(arc
		(start 87.623904 -229.416864)
		(mid 87.806155 -229.467248)
		(end 87.989664 -229.42169)
		(width 0.0889)
		(layer "In13.Cu")
		(net "M_B_CPU1_SA_DQ<5>")
	)
	(arc
		(start 81.984088 -229.416864)
		(mid 82.171032 -229.467153)
		(end 82.357976 -229.416864)
		(width 0.0889)
		(layer "In13.Cu")
		(net "M_B_CPU1_SA_DQ<5>")
	)
	(arc
		(start 84.238084 -229.416864)
		(mid 84.52104 -229.340687)
		(end 84.803996 -229.416864)
		(width 0.0889)
		(layer "In13.Cu")
		(net "M_B_CPU1_SA_DQ<5>")
	)
	(arc
		(start 78.733142 -225.389948)
		(mid 78.912054 -225.592661)
		(end 78.976474 -225.855276)
		(width 0.0889)
		(layer "In13.Cu")
		(net "M_B_CPU1_SA_DQ<5>")
	)
	(arc
		(start 80.143096 -227.819966)
		(mid 80.321909 -228.022316)
		(end 80.386428 -228.284532)
		(width 0.0889)
		(layer "In13.Cu")
		(net "M_B_CPU1_SA_DQ<5>")
	)
	(arc
		(start 82.923888 -229.416864)
		(mid 83.106139 -229.467248)
		(end 83.289648 -229.42169)
		(width 0.0889)
		(layer "In13.Cu")
		(net "M_B_CPU1_SA_DQ<5>")
	)
	(arc
		(start 78.506574 -225.044762)
		(mid 78.548473 -225.216607)
		(end 78.664562 -225.35007)
		(width 0.0889)
		(layer "In13.Cu")
		(net "M_B_CPU1_SA_DQ<5>")
	)
	(arc
		(start 85.752432 -229.42169)
		(mid 85.93594 -229.467215)
		(end 86.118192 -229.416864)
		(width 0.0889)
		(layer "In13.Cu")
		(net "M_B_CPU1_SA_DQ<5>")
	)
	(arc
		(start 86.684104 -229.416864)
		(mid 86.871048 -229.467153)
		(end 87.057992 -229.416864)
		(width 0.0889)
		(layer "In13.Cu")
		(net "M_B_CPU1_SA_DQ<5>")
	)
	(arc
		(start 79.916528 -227.474526)
		(mid 79.958077 -227.645948)
		(end 80.0735 -227.779326)
		(width 0.0889)
		(layer "In13.Cu")
		(net "M_B_CPU1_SA_DQ<5>")
	)
	(arc
		(start 87.057992 -229.416864)
		(mid 87.340948 -229.340687)
		(end 87.623904 -229.416864)
		(width 0.0889)
		(layer "In13.Cu")
		(net "M_B_CPU1_SA_DQ<5>")
	)
	(arc
		(start 77.46365 -223.453706)
		(mid 77.467343 -223.472272)
		(end 77.477874 -223.487996)
		(width 0.0889)
		(layer "In13.Cu")
		(net "M_B_CPU1_SA_DQ<5>")
	)
	(arc
		(start 79.446628 -226.664774)
		(mid 79.48916 -226.837837)
		(end 79.606902 -226.971606)
		(width 0.0889)
		(layer "In13.Cu")
		(net "M_B_CPU1_SA_DQ<5>")
	)
	(arc
		(start 80.856328 -229.094538)
		(mid 80.89709 -229.264422)
		(end 81.010506 -229.397306)
		(width 0.0889)
		(layer "In13.Cu")
		(net "M_B_CPU1_SA_DQ<5>")
	)
	(arc
		(start 78.976474 -225.855276)
		(mid 79.016681 -226.024441)
		(end 79.128874 -226.157282)
		(width 0.0889)
		(layer "In13.Cu")
		(net "M_B_CPU1_SA_DQ<5>")
	)
	(arc
		(start 88.563958 -229.416864)
		(mid 88.720396 -229.465869)
		(end 88.882728 -229.443026)
		(width 0.0889)
		(layer "In13.Cu")
		(net "M_B_CPU1_SA_DQ<5>")
	)
	(arc
		(start 78.03642 -224.234502)
		(mid 78.078826 -224.407639)
		(end 78.19644 -224.541588)
		(width 0.0889)
		(layer "In13.Cu")
		(net "M_B_CPU1_SA_DQ<5>")
	)
	(arc
		(start 80.610456 -228.628194)
		(mid 80.791108 -228.830939)
		(end 80.856328 -229.094538)
		(width 0.0889)
		(layer "In13.Cu")
		(net "M_B_CPU1_SA_DQ<5>")
	)
	(arc
		(start 79.669386 -227.007928)
		(mid 79.850768 -227.210597)
		(end 79.916528 -227.474526)
		(width 0.0889)
		(layer "In13.Cu")
		(net "M_B_CPU1_SA_DQ<5>")
	)
	(arc
		(start 81.052416 -229.42169)
		(mid 81.235924 -229.467215)
		(end 81.418176 -229.416864)
		(width 0.0889)
		(layer "In13.Cu")
		(net "M_B_CPU1_SA_DQ<5>")
	)
	(arc
		(start 84.812378 -229.42169)
		(mid 84.995886 -229.467215)
		(end 85.178138 -229.416864)
		(width 0.0889)
		(layer "In13.Cu")
		(net "M_B_CPU1_SA_DQ<5>")
	)
	(arc
		(start 83.863942 -229.416864)
		(mid 84.046193 -229.467248)
		(end 84.229702 -229.42169)
		(width 0.0889)
		(layer "In13.Cu")
		(net "M_B_CPU1_SA_DQ<5>")
	)
	(arc
		(start 77.79766 -223.772984)
		(mid 77.973204 -223.974689)
		(end 78.03642 -224.234502)
		(width 0.0889)
		(layer "In13.Cu")
		(net "M_B_CPU1_SA_DQ<5>")
	)
	(arc
		(start 82.357976 -229.416864)
		(mid 82.640932 -229.340687)
		(end 82.923888 -229.416864)
		(width 0.0889)
		(layer "In13.Cu")
		(net "M_B_CPU1_SA_DQ<5>")
	)
	(arc
		(start 83.29803 -229.416864)
		(mid 83.580986 -229.340687)
		(end 83.863942 -229.416864)
		(width 0.0889)
		(layer "In13.Cu")
		(net "M_B_CPU1_SA_DQ<5>")
	)
	(arc
		(start 79.200756 -226.198938)
		(mid 79.38129 -226.401458)
		(end 79.446628 -226.664774)
		(width 0.0889)
		(layer "In13.Cu")
		(net "M_B_CPU1_SA_DQ<5>")
	)
	(arc
		(start 80.386428 -228.284532)
		(mid 80.427683 -228.455503)
		(end 80.542384 -228.588824)
		(width 0.0889)
		(layer "In13.Cu")
		(net "M_B_CPU1_SA_DQ<5>")
	)
	(segment
		(start 87.8078 -228.55047)
		(end 87.340948 -228.284532)
		(width 0.10668)
		(layer "F.Cu")
		(net "M_B_CPU1_SA_DQ<4>")
	)
	(segment
		(start 56.218328 -204.002386)
		(end 56.500776 -203.719938)
		(width 0.14478)
		(layer "In13.Cu")
		(net "M_B_CPU1_SA_DQ<4>")
	)
	(segment
		(start 79.13243 -224.538794)
		(end 79.16418 -224.557082)
		(width 0.0889)
		(layer "In13.Cu")
		(net "M_B_CPU1_SA_DQ<4>")
	)
	(segment
		(start 87.495126 -228.549962)
		(end 87.340948 -228.284532)
		(width 0.0889)
		(layer "In13.Cu")
		(net "M_B_CPU1_SA_DQ<4>")
	)
	(segment
		(start 53.502814 -203.260706)
		(end 54.244494 -204.002386)
		(width 0.14478)
		(layer "In13.Cu")
		(net "M_B_CPU1_SA_DQ<4>")
	)
	(segment
		(start 56.500776 -203.719938)
		(end 56.88203 -203.719938)
		(width 0.14478)
		(layer "In13.Cu")
		(net "M_B_CPU1_SA_DQ<4>")
	)
	(segment
		(start 57.43321 -204.079856)
		(end 57.57799 -203.935076)
		(width 0.14478)
		(layer "In13.Cu")
		(net "M_B_CPU1_SA_DQ<4>")
	)
	(segment
		(start 79.16418 -224.557082)
		(end 79.201772 -224.578926)
		(width 0.0889)
		(layer "In13.Cu")
		(net "M_B_CPU1_SA_DQ<4>")
	)
	(segment
		(start 78.664562 -223.730058)
		(end 78.694026 -223.747076)
		(width 0.0889)
		(layer "In13.Cu")
		(net "M_B_CPU1_SA_DQ<4>")
	)
	(segment
		(start 62.590934 -207.06588)
		(end 62.795658 -207.06588)
		(width 0.14478)
		(layer "In13.Cu")
		(net "M_B_CPU1_SA_DQ<4>")
	)
	(segment
		(start 78.224634 -222.93707)
		(end 78.257908 -222.956374)
		(width 0.0889)
		(layer "In13.Cu")
		(net "M_B_CPU1_SA_DQ<4>")
	)
	(segment
		(start 80.542384 -226.968812)
		(end 80.574134 -226.9871)
		(width 0.0889)
		(layer "In13.Cu")
		(net "M_B_CPU1_SA_DQ<4>")
	)
	(segment
		(start 60.066428 -204.541374)
		(end 60.251594 -204.72654)
		(width 0.14478)
		(layer "In13.Cu")
		(net "M_B_CPU1_SA_DQ<4>")
	)
	(segment
		(start 77.22743 -221.967806)
		(end 77.70241 -222.442786)
		(width 0.14478)
		(layer "In13.Cu")
		(net "M_B_CPU1_SA_DQ<4>")
	)
	(segment
		(start 58.12917 -203.935076)
		(end 58.27395 -204.079856)
		(width 0.14478)
		(layer "In13.Cu")
		(net "M_B_CPU1_SA_DQ<4>")
	)
	(segment
		(start 62.060582 -206.241396)
		(end 62.265306 -206.241396)
		(width 0.14478)
		(layer "In13.Cu")
		(net "M_B_CPU1_SA_DQ<4>")
	)
	(segment
		(start 58.27395 -204.079856)
		(end 58.53557 -204.079856)
		(width 0.14478)
		(layer "In13.Cu")
		(net "M_B_CPU1_SA_DQ<4>")
	)
	(segment
		(start 60.111132 -204.291946)
		(end 60.066428 -204.33665)
		(width 0.14478)
		(layer "In13.Cu")
		(net "M_B_CPU1_SA_DQ<4>")
	)
	(segment
		(start 63.185548 -207.45577)
		(end 63.185548 -207.660494)
		(width 0.14478)
		(layer "In13.Cu")
		(net "M_B_CPU1_SA_DQ<4>")
	)
	(segment
		(start 81.044034 -227.797106)
		(end 81.08315 -227.819966)
		(width 0.0889)
		(layer "In13.Cu")
		(net "M_B_CPU1_SA_DQ<4>")
	)
	(segment
		(start 60.705746 -204.681836)
		(end 60.890912 -204.867002)
		(width 0.14478)
		(layer "In13.Cu")
		(net "M_B_CPU1_SA_DQ<4>")
	)
	(segment
		(start 58.53557 -204.079856)
		(end 58.68035 -203.935076)
		(width 0.14478)
		(layer "In13.Cu")
		(net "M_B_CPU1_SA_DQ<4>")
	)
	(segment
		(start 58.68035 -203.864718)
		(end 58.82513 -203.719938)
		(width 0.14478)
		(layer "In13.Cu")
		(net "M_B_CPU1_SA_DQ<4>")
	)
	(segment
		(start 87.154004 -228.607112)
		(end 87.162386 -228.611938)
		(width 0.0889)
		(layer "In13.Cu")
		(net "M_B_CPU1_SA_DQ<4>")
	)
	(segment
		(start 60.890912 -205.071726)
		(end 60.846208 -205.11643)
		(width 0.14478)
		(layer "In13.Cu")
		(net "M_B_CPU1_SA_DQ<4>")
	)
	(segment
		(start 60.846208 -205.321154)
		(end 61.031374 -205.50632)
		(width 0.14478)
		(layer "In13.Cu")
		(net "M_B_CPU1_SA_DQ<4>")
	)
	(segment
		(start 83.394042 -228.607112)
		(end 83.402424 -228.611938)
		(width 0.0889)
		(layer "In13.Cu")
		(net "M_B_CPU1_SA_DQ<4>")
	)
	(segment
		(start 80.0735 -226.159314)
		(end 80.10398 -226.177094)
		(width 0.0889)
		(layer "In13.Cu")
		(net "M_B_CPU1_SA_DQ<4>")
	)
	(segment
		(start 81.483454 -228.589332)
		(end 81.513934 -228.607112)
		(width 0.0889)
		(layer "In13.Cu")
		(net "M_B_CPU1_SA_DQ<4>")
	)
	(segment
		(start 63.045086 -207.021176)
		(end 63.230252 -207.206342)
		(width 0.14478)
		(layer "In13.Cu")
		(net "M_B_CPU1_SA_DQ<4>")
	)
	(segment
		(start 62.840362 -207.021176)
		(end 63.045086 -207.021176)
		(width 0.14478)
		(layer "In13.Cu")
		(net "M_B_CPU1_SA_DQ<4>")
	)
	(segment
		(start 61.236098 -205.50632)
		(end 61.280802 -205.461616)
		(width 0.14478)
		(layer "In13.Cu")
		(net "M_B_CPU1_SA_DQ<4>")
	)
	(segment
		(start 63.620142 -207.800956)
		(end 63.824866 -207.800956)
		(width 0.14478)
		(layer "In13.Cu")
		(net "M_B_CPU1_SA_DQ<4>")
	)
	(segment
		(start 61.280802 -205.461616)
		(end 61.485526 -205.461616)
		(width 0.14478)
		(layer "In13.Cu")
		(net "M_B_CPU1_SA_DQ<4>")
	)
	(segment
		(start 78.194154 -222.91929)
		(end 78.224634 -222.93707)
		(width 0.0889)
		(layer "In13.Cu")
		(net "M_B_CPU1_SA_DQ<4>")
	)
	(segment
		(start 59.743848 -203.719938)
		(end 60.111132 -204.087222)
		(width 0.14478)
		(layer "In13.Cu")
		(net "M_B_CPU1_SA_DQ<4>")
	)
	(segment
		(start 60.846208 -205.11643)
		(end 60.846208 -205.321154)
		(width 0.14478)
		(layer "In13.Cu")
		(net "M_B_CPU1_SA_DQ<4>")
	)
	(segment
		(start 55.631842 -202.819762)
		(end 55.780686 -202.968606)
		(width 0.14478)
		(layer "In13.Cu")
		(net "M_B_CPU1_SA_DQ<4>")
	)
	(segment
		(start 63.230252 -207.411066)
		(end 63.185548 -207.45577)
		(width 0.14478)
		(layer "In13.Cu")
		(net "M_B_CPU1_SA_DQ<4>")
	)
	(segment
		(start 51.884072 -203.285344)
		(end 51.90871 -203.260706)
		(width 0.14478)
		(layer "In13.Cu")
		(net "M_B_CPU1_SA_DQ<4>")
	)
	(segment
		(start 61.625988 -206.100934)
		(end 61.811154 -206.2861)
		(width 0.14478)
		(layer "In13.Cu")
		(net "M_B_CPU1_SA_DQ<4>")
	)
	(segment
		(start 55.084726 -204.002386)
		(end 55.229506 -203.857606)
		(width 0.14478)
		(layer "In13.Cu")
		(net "M_B_CPU1_SA_DQ<4>")
	)
	(segment
		(start 58.12917 -203.864718)
		(end 58.12917 -203.935076)
		(width 0.14478)
		(layer "In13.Cu")
		(net "M_B_CPU1_SA_DQ<4>")
	)
	(segment
		(start 57.17159 -204.079856)
		(end 57.43321 -204.079856)
		(width 0.14478)
		(layer "In13.Cu")
		(net "M_B_CPU1_SA_DQ<4>")
	)
	(segment
		(start 62.405768 -206.67599)
		(end 62.405768 -206.880714)
		(width 0.14478)
		(layer "In13.Cu")
		(net "M_B_CPU1_SA_DQ<4>")
	)
	(segment
		(start 77.22743 -221.20352)
		(end 77.22743 -221.967806)
		(width 0.14478)
		(layer "In13.Cu")
		(net "M_B_CPU1_SA_DQ<4>")
	)
	(segment
		(start 60.890912 -204.867002)
		(end 60.890912 -205.071726)
		(width 0.14478)
		(layer "In13.Cu")
		(net "M_B_CPU1_SA_DQ<4>")
	)
	(segment
		(start 57.72277 -203.719938)
		(end 57.98439 -203.719938)
		(width 0.14478)
		(layer "In13.Cu")
		(net "M_B_CPU1_SA_DQ<4>")
	)
	(segment
		(start 61.031374 -205.50632)
		(end 61.236098 -205.50632)
		(width 0.14478)
		(layer "In13.Cu")
		(net "M_B_CPU1_SA_DQ<4>")
	)
	(segment
		(start 63.575438 -207.84566)
		(end 63.620142 -207.800956)
		(width 0.14478)
		(layer "In13.Cu")
		(net "M_B_CPU1_SA_DQ<4>")
	)
	(segment
		(start 55.780686 -202.968606)
		(end 55.780686 -203.857606)
		(width 0.14478)
		(layer "In13.Cu")
		(net "M_B_CPU1_SA_DQ<4>")
	)
	(segment
		(start 61.485526 -205.461616)
		(end 61.670692 -205.646782)
		(width 0.14478)
		(layer "In13.Cu")
		(net "M_B_CPU1_SA_DQ<4>")
	)
	(segment
		(start 53.02377 -202.889866)
		(end 53.16855 -203.034646)
		(width 0.14478)
		(layer "In13.Cu")
		(net "M_B_CPU1_SA_DQ<4>")
	)
	(segment
		(start 52.76215 -202.889866)
		(end 53.02377 -202.889866)
		(width 0.14478)
		(layer "In13.Cu")
		(net "M_B_CPU1_SA_DQ<4>")
	)
	(segment
		(start 78.694026 -223.747076)
		(end 78.735936 -223.77146)
		(width 0.0889)
		(layer "In13.Cu")
		(net "M_B_CPU1_SA_DQ<4>")
	)
	(segment
		(start 58.68035 -203.935076)
		(end 58.68035 -203.864718)
		(width 0.14478)
		(layer "In13.Cu")
		(net "M_B_CPU1_SA_DQ<4>")
	)
	(segment
		(start 57.02681 -203.935076)
		(end 57.17159 -204.079856)
		(width 0.14478)
		(layer "In13.Cu")
		(net "M_B_CPU1_SA_DQ<4>")
	)
	(segment
		(start 61.625988 -205.89621)
		(end 61.625988 -206.100934)
		(width 0.14478)
		(layer "In13.Cu")
		(net "M_B_CPU1_SA_DQ<4>")
	)
	(segment
		(start 57.02681 -203.864718)
		(end 57.02681 -203.935076)
		(width 0.14478)
		(layer "In13.Cu")
		(net "M_B_CPU1_SA_DQ<4>")
	)
	(segment
		(start 85.639656 -228.611938)
		(end 85.648038 -228.607112)
		(width 0.0889)
		(layer "In13.Cu")
		(net "M_B_CPU1_SA_DQ<4>")
	)
	(segment
		(start 77.71765 -222.442786)
		(end 78.194154 -222.91929)
		(width 0.0889)
		(layer "In13.Cu")
		(net "M_B_CPU1_SA_DQ<4>")
	)
	(segment
		(start 53.31333 -203.260706)
		(end 53.502814 -203.260706)
		(width 0.14478)
		(layer "In13.Cu")
		(net "M_B_CPU1_SA_DQ<4>")
	)
	(segment
		(start 86.57971 -228.611938)
		(end 86.588092 -228.607112)
		(width 0.0889)
		(layer "In13.Cu")
		(net "M_B_CPU1_SA_DQ<4>")
	)
	(segment
		(start 79.63408 -225.367088)
		(end 79.671926 -225.388932)
		(width 0.0889)
		(layer "In13.Cu")
		(net "M_B_CPU1_SA_DQ<4>")
	)
	(segment
		(start 60.501022 -204.681836)
		(end 60.705746 -204.681836)
		(width 0.14478)
		(layer "In13.Cu")
		(net "M_B_CPU1_SA_DQ<4>")
	)
	(segment
		(start 79.60233 -225.3488)
		(end 79.63408 -225.367088)
		(width 0.0889)
		(layer "In13.Cu")
		(net "M_B_CPU1_SA_DQ<4>")
	)
	(segment
		(start 61.811154 -206.2861)
		(end 62.015878 -206.2861)
		(width 0.14478)
		(layer "In13.Cu")
		(net "M_B_CPU1_SA_DQ<4>")
	)
	(segment
		(start 55.780686 -203.857606)
		(end 55.925466 -204.002386)
		(width 0.14478)
		(layer "In13.Cu")
		(net "M_B_CPU1_SA_DQ<4>")
	)
	(segment
		(start 60.066428 -204.33665)
		(end 60.066428 -204.541374)
		(width 0.14478)
		(layer "In13.Cu")
		(net "M_B_CPU1_SA_DQ<4>")
	)
	(segment
		(start 55.374286 -202.819762)
		(end 55.631842 -202.819762)
		(width 0.14478)
		(layer "In13.Cu")
		(net "M_B_CPU1_SA_DQ<4>")
	)
	(segment
		(start 60.111132 -204.087222)
		(end 60.111132 -204.291946)
		(width 0.14478)
		(layer "In13.Cu")
		(net "M_B_CPU1_SA_DQ<4>")
	)
	(segment
		(start 61.670692 -205.851506)
		(end 61.625988 -205.89621)
		(width 0.14478)
		(layer "In13.Cu")
		(net "M_B_CPU1_SA_DQ<4>")
	)
	(segment
		(start 58.82513 -203.719938)
		(end 59.743848 -203.719938)
		(width 0.14478)
		(layer "In13.Cu")
		(net "M_B_CPU1_SA_DQ<4>")
	)
	(segment
		(start 80.574134 -226.9871)
		(end 80.610456 -227.008182)
		(width 0.0889)
		(layer "In13.Cu")
		(net "M_B_CPU1_SA_DQ<4>")
	)
	(segment
		(start 61.670692 -205.646782)
		(end 61.670692 -205.851506)
		(width 0.14478)
		(layer "In13.Cu")
		(net "M_B_CPU1_SA_DQ<4>")
	)
	(segment
		(start 55.925466 -204.002386)
		(end 56.218328 -204.002386)
		(width 0.14478)
		(layer "In13.Cu")
		(net "M_B_CPU1_SA_DQ<4>")
	)
	(segment
		(start 62.795658 -207.06588)
		(end 62.840362 -207.021176)
		(width 0.14478)
		(layer "In13.Cu")
		(net "M_B_CPU1_SA_DQ<4>")
	)
	(segment
		(start 60.456318 -204.72654)
		(end 60.501022 -204.681836)
		(width 0.14478)
		(layer "In13.Cu")
		(net "M_B_CPU1_SA_DQ<4>")
	)
	(segment
		(start 55.229506 -202.964542)
		(end 55.374286 -202.819762)
		(width 0.14478)
		(layer "In13.Cu")
		(net "M_B_CPU1_SA_DQ<4>")
	)
	(segment
		(start 62.450472 -206.631286)
		(end 62.405768 -206.67599)
		(width 0.14478)
		(layer "In13.Cu")
		(net "M_B_CPU1_SA_DQ<4>")
	)
	(segment
		(start 57.98439 -203.719938)
		(end 58.12917 -203.864718)
		(width 0.14478)
		(layer "In13.Cu")
		(net "M_B_CPU1_SA_DQ<4>")
	)
	(segment
		(start 80.10398 -226.177094)
		(end 80.143096 -226.199954)
		(width 0.0889)
		(layer "In13.Cu")
		(net "M_B_CPU1_SA_DQ<4>")
	)
	(segment
		(start 55.229506 -203.857606)
		(end 55.229506 -202.964542)
		(width 0.14478)
		(layer "In13.Cu")
		(net "M_B_CPU1_SA_DQ<4>")
	)
	(segment
		(start 52.47259 -203.260706)
		(end 52.61737 -203.115926)
		(width 0.14478)
		(layer "In13.Cu")
		(net "M_B_CPU1_SA_DQ<4>")
	)
	(segment
		(start 51.90871 -203.260706)
		(end 52.47259 -203.260706)
		(width 0.14478)
		(layer "In13.Cu")
		(net "M_B_CPU1_SA_DQ<4>")
	)
	(segment
		(start 52.61737 -203.034646)
		(end 52.76215 -202.889866)
		(width 0.14478)
		(layer "In13.Cu")
		(net "M_B_CPU1_SA_DQ<4>")
	)
	(segment
		(start 62.015878 -206.2861)
		(end 62.060582 -206.241396)
		(width 0.14478)
		(layer "In13.Cu")
		(net "M_B_CPU1_SA_DQ<4>")
	)
	(segment
		(start 62.405768 -206.880714)
		(end 62.590934 -207.06588)
		(width 0.14478)
		(layer "In13.Cu")
		(net "M_B_CPU1_SA_DQ<4>")
	)
	(segment
		(start 81.879694 -228.611938)
		(end 81.888076 -228.607112)
		(width 0.0889)
		(layer "In13.Cu")
		(net "M_B_CPU1_SA_DQ<4>")
	)
	(segment
		(start 62.450472 -206.426562)
		(end 62.450472 -206.631286)
		(width 0.14478)
		(layer "In13.Cu")
		(net "M_B_CPU1_SA_DQ<4>")
	)
	(segment
		(start 52.61737 -203.115926)
		(end 52.61737 -203.034646)
		(width 0.14478)
		(layer "In13.Cu")
		(net "M_B_CPU1_SA_DQ<4>")
	)
	(segment
		(start 53.16855 -203.115926)
		(end 53.31333 -203.260706)
		(width 0.14478)
		(layer "In13.Cu")
		(net "M_B_CPU1_SA_DQ<4>")
	)
	(segment
		(start 57.57799 -203.864718)
		(end 57.72277 -203.719938)
		(width 0.14478)
		(layer "In13.Cu")
		(net "M_B_CPU1_SA_DQ<4>")
	)
	(segment
		(start 81.012284 -227.778818)
		(end 81.044034 -227.797106)
		(width 0.0889)
		(layer "In13.Cu")
		(net "M_B_CPU1_SA_DQ<4>")
	)
	(segment
		(start 63.230252 -207.206342)
		(end 63.230252 -207.411066)
		(width 0.14478)
		(layer "In13.Cu")
		(net "M_B_CPU1_SA_DQ<4>")
	)
	(segment
		(start 54.244494 -204.002386)
		(end 55.084726 -204.002386)
		(width 0.14478)
		(layer "In13.Cu")
		(net "M_B_CPU1_SA_DQ<4>")
	)
	(segment
		(start 82.453988 -228.607112)
		(end 82.46237 -228.611938)
		(width 0.0889)
		(layer "In13.Cu")
		(net "M_B_CPU1_SA_DQ<4>")
	)
	(segment
		(start 62.265306 -206.241396)
		(end 62.450472 -206.426562)
		(width 0.14478)
		(layer "In13.Cu")
		(net "M_B_CPU1_SA_DQ<4>")
	)
	(segment
		(start 77.70241 -222.442786)
		(end 77.71765 -222.442786)
		(width 0.0889)
		(layer "In13.Cu")
		(net "M_B_CPU1_SA_DQ<4>")
	)
	(segment
		(start 56.88203 -203.719938)
		(end 57.02681 -203.864718)
		(width 0.14478)
		(layer "In13.Cu")
		(net "M_B_CPU1_SA_DQ<4>")
	)
	(segment
		(start 53.16855 -203.034646)
		(end 53.16855 -203.115926)
		(width 0.14478)
		(layer "In13.Cu")
		(net "M_B_CPU1_SA_DQ<4>")
	)
	(segment
		(start 57.57799 -203.935076)
		(end 57.57799 -203.864718)
		(width 0.14478)
		(layer "In13.Cu")
		(net "M_B_CPU1_SA_DQ<4>")
	)
	(segment
		(start 63.370714 -207.84566)
		(end 63.575438 -207.84566)
		(width 0.14478)
		(layer "In13.Cu")
		(net "M_B_CPU1_SA_DQ<4>")
	)
	(segment
		(start 60.251594 -204.72654)
		(end 60.456318 -204.72654)
		(width 0.14478)
		(layer "In13.Cu")
		(net "M_B_CPU1_SA_DQ<4>")
	)
	(segment
		(start 63.824866 -207.800956)
		(end 77.22743 -221.20352)
		(width 0.14478)
		(layer "In13.Cu")
		(net "M_B_CPU1_SA_DQ<4>")
	)
	(segment
		(start 87.472774 -228.633274)
		(end 87.495126 -228.549962)
		(width 0.0889)
		(layer "In13.Cu")
		(net "M_B_CPU1_SA_DQ<4>")
	)
	(segment
		(start 63.185548 -207.660494)
		(end 63.370714 -207.84566)
		(width 0.14478)
		(layer "In13.Cu")
		(net "M_B_CPU1_SA_DQ<4>")
	)
	(arc
		(start 84.334096 -228.607112)
		(mid 84.52104 -228.657367)
		(end 84.707984 -228.607112)
		(width 0.0889)
		(layer "In13.Cu")
		(net "M_B_CPU1_SA_DQ<4>")
	)
	(arc
		(start 79.916528 -225.854514)
		(mid 79.958077 -226.025936)
		(end 80.0735 -226.159314)
		(width 0.0889)
		(layer "In13.Cu")
		(net "M_B_CPU1_SA_DQ<4>")
	)
	(arc
		(start 78.506574 -223.424496)
		(mid 78.548414 -223.596482)
		(end 78.664562 -223.730058)
		(width 0.0889)
		(layer "In13.Cu")
		(net "M_B_CPU1_SA_DQ<4>")
	)
	(arc
		(start 80.386428 -226.66452)
		(mid 80.427683 -226.835491)
		(end 80.542384 -226.968812)
		(width 0.0889)
		(layer "In13.Cu")
		(net "M_B_CPU1_SA_DQ<4>")
	)
	(arc
		(start 78.976728 -224.234502)
		(mid 79.017917 -224.405406)
		(end 79.13243 -224.538794)
		(width 0.0889)
		(layer "In13.Cu")
		(net "M_B_CPU1_SA_DQ<4>")
	)
	(arc
		(start 87.162386 -228.611938)
		(mid 87.315256 -228.656579)
		(end 87.472774 -228.633274)
		(width 0.0889)
		(layer "In13.Cu")
		(net "M_B_CPU1_SA_DQ<4>")
	)
	(arc
		(start 85.648038 -228.607112)
		(mid 85.930994 -228.530935)
		(end 86.21395 -228.607112)
		(width 0.0889)
		(layer "In13.Cu")
		(net "M_B_CPU1_SA_DQ<4>")
	)
	(arc
		(start 78.735936 -223.77146)
		(mid 78.912918 -223.973552)
		(end 78.976728 -224.234502)
		(width 0.0889)
		(layer "In13.Cu")
		(net "M_B_CPU1_SA_DQ<4>")
	)
	(arc
		(start 86.588092 -228.607112)
		(mid 86.871048 -228.530935)
		(end 87.154004 -228.607112)
		(width 0.0889)
		(layer "In13.Cu")
		(net "M_B_CPU1_SA_DQ<4>")
	)
	(arc
		(start 85.273896 -228.607112)
		(mid 85.456147 -228.657462)
		(end 85.639656 -228.611938)
		(width 0.0889)
		(layer "In13.Cu")
		(net "M_B_CPU1_SA_DQ<4>")
	)
	(arc
		(start 86.21395 -228.607112)
		(mid 86.396201 -228.657462)
		(end 86.57971 -228.611938)
		(width 0.0889)
		(layer "In13.Cu")
		(net "M_B_CPU1_SA_DQ<4>")
	)
	(arc
		(start 81.08315 -227.819966)
		(mid 81.261963 -228.022316)
		(end 81.326482 -228.284532)
		(width 0.0889)
		(layer "In13.Cu")
		(net "M_B_CPU1_SA_DQ<4>")
	)
	(arc
		(start 83.402424 -228.611938)
		(mid 83.585932 -228.657432)
		(end 83.768184 -228.607112)
		(width 0.0889)
		(layer "In13.Cu")
		(net "M_B_CPU1_SA_DQ<4>")
	)
	(arc
		(start 78.257908 -222.956374)
		(mid 78.44057 -223.159455)
		(end 78.506574 -223.424496)
		(width 0.0889)
		(layer "In13.Cu")
		(net "M_B_CPU1_SA_DQ<4>")
	)
	(arc
		(start 79.671926 -225.388932)
		(mid 79.851655 -225.591552)
		(end 79.916528 -225.854514)
		(width 0.0889)
		(layer "In13.Cu")
		(net "M_B_CPU1_SA_DQ<4>")
	)
	(arc
		(start 80.143096 -226.199954)
		(mid 80.321909 -226.402304)
		(end 80.386428 -226.66452)
		(width 0.0889)
		(layer "In13.Cu")
		(net "M_B_CPU1_SA_DQ<4>")
	)
	(arc
		(start 83.768184 -228.607112)
		(mid 84.05114 -228.530935)
		(end 84.334096 -228.607112)
		(width 0.0889)
		(layer "In13.Cu")
		(net "M_B_CPU1_SA_DQ<4>")
	)
	(arc
		(start 82.82813 -228.607112)
		(mid 83.111086 -228.530935)
		(end 83.394042 -228.607112)
		(width 0.0889)
		(layer "In13.Cu")
		(net "M_B_CPU1_SA_DQ<4>")
	)
	(arc
		(start 81.513934 -228.607112)
		(mid 81.696185 -228.657462)
		(end 81.879694 -228.611938)
		(width 0.0889)
		(layer "In13.Cu")
		(net "M_B_CPU1_SA_DQ<4>")
	)
	(arc
		(start 81.326482 -228.284532)
		(mid 81.368031 -228.455954)
		(end 81.483454 -228.589332)
		(width 0.0889)
		(layer "In13.Cu")
		(net "M_B_CPU1_SA_DQ<4>")
	)
	(arc
		(start 84.707984 -228.607112)
		(mid 84.99094 -228.530935)
		(end 85.273896 -228.607112)
		(width 0.0889)
		(layer "In13.Cu")
		(net "M_B_CPU1_SA_DQ<4>")
	)
	(arc
		(start 79.201772 -224.578926)
		(mid 79.381501 -224.781546)
		(end 79.446374 -225.044508)
		(width 0.0889)
		(layer "In13.Cu")
		(net "M_B_CPU1_SA_DQ<4>")
	)
	(arc
		(start 80.856328 -227.474526)
		(mid 80.897583 -227.645497)
		(end 81.012284 -227.778818)
		(width 0.0889)
		(layer "In13.Cu")
		(net "M_B_CPU1_SA_DQ<4>")
	)
	(arc
		(start 82.46237 -228.611938)
		(mid 82.645878 -228.657432)
		(end 82.82813 -228.607112)
		(width 0.0889)
		(layer "In13.Cu")
		(net "M_B_CPU1_SA_DQ<4>")
	)
	(arc
		(start 81.888076 -228.607112)
		(mid 82.171032 -228.530935)
		(end 82.453988 -228.607112)
		(width 0.0889)
		(layer "In13.Cu")
		(net "M_B_CPU1_SA_DQ<4>")
	)
	(arc
		(start 80.610456 -227.008182)
		(mid 80.791108 -227.210927)
		(end 80.856328 -227.474526)
		(width 0.0889)
		(layer "In13.Cu")
		(net "M_B_CPU1_SA_DQ<4>")
	)
	(arc
		(start 79.446374 -225.044508)
		(mid 79.487629 -225.215479)
		(end 79.60233 -225.3488)
		(width 0.0889)
		(layer "In13.Cu")
		(net "M_B_CPU1_SA_DQ<4>")
	)
	(segment
		(start 89.687908 -226.930458)
		(end 89.221056 -226.66452)
		(width 0.10668)
		(layer "F.Cu")
		(net "M_B_CPU1_SA_DQ<3>")
	)
	(segment
		(start 80.195928 -221.525084)
		(end 80.075786 -221.404942)
		(width 0.0889)
		(layer "In13.Cu")
		(net "M_B_CPU1_SA_DQ<3>")
	)
	(segment
		(start 50.626772 -199.488298)
		(end 50.53584 -199.450706)
		(width 0.14478)
		(layer "In13.Cu")
		(net "M_B_CPU1_SA_DQ<3>")
	)
	(segment
		(start 61.013848 -201.092816)
		(end 57.081166 -200.310496)
		(width 0.14478)
		(layer "In13.Cu")
		(net "M_B_CPU1_SA_DQ<3>")
	)
	(segment
		(start 80.47863 -222.29191)
		(end 80.43672 -222.267526)
		(width 0.0889)
		(layer "In13.Cu")
		(net "M_B_CPU1_SA_DQ<3>")
	)
	(segment
		(start 85.648038 -226.34194)
		(end 85.639656 -226.337114)
		(width 0.0889)
		(layer "In13.Cu")
		(net "M_B_CPU1_SA_DQ<3>")
	)
	(segment
		(start 89.221056 -226.66452)
		(end 89.067132 -226.39909)
		(width 0.0889)
		(layer "In13.Cu")
		(net "M_B_CPU1_SA_DQ<3>")
	)
	(segment
		(start 82.389726 -225.550222)
		(end 82.357976 -225.531934)
		(width 0.0889)
		(layer "In13.Cu")
		(net "M_B_CPU1_SA_DQ<3>")
	)
	(segment
		(start 80.195928 -221.804484)
		(end 80.195928 -221.525084)
		(width 0.0889)
		(layer "In13.Cu")
		(net "M_B_CPU1_SA_DQ<3>")
	)
	(segment
		(start 88.10244 -226.337114)
		(end 88.094058 -226.34194)
		(width 0.0889)
		(layer "In13.Cu")
		(net "M_B_CPU1_SA_DQ<3>")
	)
	(segment
		(start 81.418176 -223.911922)
		(end 81.37906 -223.889062)
		(width 0.0889)
		(layer "In13.Cu")
		(net "M_B_CPU1_SA_DQ<3>")
	)
	(segment
		(start 81.919826 -224.740216)
		(end 81.888076 -224.721928)
		(width 0.0889)
		(layer "In13.Cu")
		(net "M_B_CPU1_SA_DQ<3>")
	)
	(segment
		(start 82.357976 -225.531934)
		(end 82.321654 -225.510852)
		(width 0.0889)
		(layer "In13.Cu")
		(net "M_B_CPU1_SA_DQ<3>")
	)
	(segment
		(start 61.265816 -201.19721)
		(end 61.013848 -201.092816)
		(width 0.14478)
		(layer "In13.Cu")
		(net "M_B_CPU1_SA_DQ<3>")
	)
	(segment
		(start 89.067132 -226.39909)
		(end 88.97112 -226.37369)
		(width 0.0889)
		(layer "In13.Cu")
		(net "M_B_CPU1_SA_DQ<3>")
	)
	(segment
		(start 81.888076 -224.721928)
		(end 81.84896 -224.699068)
		(width 0.0889)
		(layer "In13.Cu")
		(net "M_B_CPU1_SA_DQ<3>")
	)
	(segment
		(start 80.075786 -220.00718)
		(end 61.265816 -201.19721)
		(width 0.14478)
		(layer "In13.Cu")
		(net "M_B_CPU1_SA_DQ<3>")
	)
	(segment
		(start 80.506824 -222.308166)
		(end 80.47863 -222.29191)
		(width 0.0889)
		(layer "In13.Cu")
		(net "M_B_CPU1_SA_DQ<3>")
	)
	(segment
		(start 50.53584 -199.450706)
		(end 49.960022 -199.450706)
		(width 0.14478)
		(layer "In13.Cu")
		(net "M_B_CPU1_SA_DQ<3>")
	)
	(segment
		(start 49.960022 -199.450706)
		(end 48.910748 -199.8853)
		(width 0.14478)
		(layer "In13.Cu")
		(net "M_B_CPU1_SA_DQ<3>")
	)
	(segment
		(start 87.162386 -226.337114)
		(end 87.154004 -226.34194)
		(width 0.0889)
		(layer "In13.Cu")
		(net "M_B_CPU1_SA_DQ<3>")
	)
	(segment
		(start 57.081166 -200.310496)
		(end 54.76113 -200.310496)
		(width 0.14478)
		(layer "In13.Cu")
		(net "M_B_CPU1_SA_DQ<3>")
	)
	(segment
		(start 80.075786 -221.235524)
		(end 80.075786 -220.00718)
		(width 0.14478)
		(layer "In13.Cu")
		(net "M_B_CPU1_SA_DQ<3>")
	)
	(segment
		(start 80.948022 -223.101916)
		(end 80.9117 -223.080834)
		(width 0.0889)
		(layer "In13.Cu")
		(net "M_B_CPU1_SA_DQ<3>")
	)
	(segment
		(start 82.82813 -226.34194)
		(end 82.789014 -226.31908)
		(width 0.0889)
		(layer "In13.Cu")
		(net "M_B_CPU1_SA_DQ<3>")
	)
	(segment
		(start 80.979772 -223.120204)
		(end 80.948022 -223.101916)
		(width 0.0889)
		(layer "In13.Cu")
		(net "M_B_CPU1_SA_DQ<3>")
	)
	(segment
		(start 83.402424 -226.337114)
		(end 83.394042 -226.34194)
		(width 0.0889)
		(layer "In13.Cu")
		(net "M_B_CPU1_SA_DQ<3>")
	)
	(segment
		(start 81.448656 -223.929702)
		(end 81.418176 -223.911922)
		(width 0.0889)
		(layer "In13.Cu")
		(net "M_B_CPU1_SA_DQ<3>")
	)
	(segment
		(start 86.588092 -226.34194)
		(end 86.57971 -226.337114)
		(width 0.0889)
		(layer "In13.Cu")
		(net "M_B_CPU1_SA_DQ<3>")
	)
	(segment
		(start 80.075786 -221.404942)
		(end 80.075786 -221.235524)
		(width 0.0889)
		(layer "In13.Cu")
		(net "M_B_CPU1_SA_DQ<3>")
	)
	(segment
		(start 48.910748 -199.8853)
		(end 47.784004 -199.8853)
		(width 0.14478)
		(layer "In13.Cu")
		(net "M_B_CPU1_SA_DQ<3>")
	)
	(segment
		(start 54.76113 -200.310496)
		(end 50.626772 -199.488298)
		(width 0.14478)
		(layer "In13.Cu")
		(net "M_B_CPU1_SA_DQ<3>")
	)
	(arc
		(start 82.075782 -225.044508)
		(mid 82.034527 -224.873537)
		(end 81.919826 -224.740216)
		(width 0.0889)
		(layer "In13.Cu")
		(net "M_B_CPU1_SA_DQ<3>")
	)
	(arc
		(start 86.21395 -226.34194)
		(mid 85.930994 -226.418117)
		(end 85.648038 -226.34194)
		(width 0.0889)
		(layer "In13.Cu")
		(net "M_B_CPU1_SA_DQ<3>")
	)
	(arc
		(start 81.135728 -223.424496)
		(mid 81.094473 -223.253525)
		(end 80.979772 -223.120204)
		(width 0.0889)
		(layer "In13.Cu")
		(net "M_B_CPU1_SA_DQ<3>")
	)
	(arc
		(start 80.665828 -222.61449)
		(mid 80.623715 -222.441916)
		(end 80.506824 -222.308166)
		(width 0.0889)
		(layer "In13.Cu")
		(net "M_B_CPU1_SA_DQ<3>")
	)
	(arc
		(start 86.57971 -226.337114)
		(mid 86.396202 -226.29162)
		(end 86.21395 -226.34194)
		(width 0.0889)
		(layer "In13.Cu")
		(net "M_B_CPU1_SA_DQ<3>")
	)
	(arc
		(start 85.273896 -226.34194)
		(mid 84.99094 -226.418117)
		(end 84.707984 -226.34194)
		(width 0.0889)
		(layer "In13.Cu")
		(net "M_B_CPU1_SA_DQ<3>")
	)
	(arc
		(start 84.707984 -226.34194)
		(mid 84.52104 -226.291685)
		(end 84.334096 -226.34194)
		(width 0.0889)
		(layer "In13.Cu")
		(net "M_B_CPU1_SA_DQ<3>")
	)
	(arc
		(start 81.605628 -224.234502)
		(mid 81.564079 -224.06308)
		(end 81.448656 -223.929702)
		(width 0.0889)
		(layer "In13.Cu")
		(net "M_B_CPU1_SA_DQ<3>")
	)
	(arc
		(start 87.528146 -226.34194)
		(mid 87.345895 -226.29159)
		(end 87.162386 -226.337114)
		(width 0.0889)
		(layer "In13.Cu")
		(net "M_B_CPU1_SA_DQ<3>")
	)
	(arc
		(start 88.97112 -226.37369)
		(mid 88.715912 -226.417167)
		(end 88.4682 -226.34194)
		(width 0.0889)
		(layer "In13.Cu")
		(net "M_B_CPU1_SA_DQ<3>")
	)
	(arc
		(start 80.9117 -223.080834)
		(mid 80.731048 -222.878089)
		(end 80.665828 -222.61449)
		(width 0.0889)
		(layer "In13.Cu")
		(net "M_B_CPU1_SA_DQ<3>")
	)
	(arc
		(start 87.154004 -226.34194)
		(mid 86.871048 -226.418117)
		(end 86.588092 -226.34194)
		(width 0.0889)
		(layer "In13.Cu")
		(net "M_B_CPU1_SA_DQ<3>")
	)
	(arc
		(start 83.768184 -226.34194)
		(mid 83.585933 -226.29159)
		(end 83.402424 -226.337114)
		(width 0.0889)
		(layer "In13.Cu")
		(net "M_B_CPU1_SA_DQ<3>")
	)
	(arc
		(start 81.37906 -223.889062)
		(mid 81.200247 -223.686712)
		(end 81.135728 -223.424496)
		(width 0.0889)
		(layer "In13.Cu")
		(net "M_B_CPU1_SA_DQ<3>")
	)
	(arc
		(start 82.789014 -226.31908)
		(mid 82.610201 -226.11673)
		(end 82.545682 -225.854514)
		(width 0.0889)
		(layer "In13.Cu")
		(net "M_B_CPU1_SA_DQ<3>")
	)
	(arc
		(start 81.84896 -224.699068)
		(mid 81.670147 -224.496718)
		(end 81.605628 -224.234502)
		(width 0.0889)
		(layer "In13.Cu")
		(net "M_B_CPU1_SA_DQ<3>")
	)
	(arc
		(start 85.639656 -226.337114)
		(mid 85.456148 -226.29162)
		(end 85.273896 -226.34194)
		(width 0.0889)
		(layer "In13.Cu")
		(net "M_B_CPU1_SA_DQ<3>")
	)
	(arc
		(start 83.394042 -226.34194)
		(mid 83.111086 -226.418117)
		(end 82.82813 -226.34194)
		(width 0.0889)
		(layer "In13.Cu")
		(net "M_B_CPU1_SA_DQ<3>")
	)
	(arc
		(start 80.43672 -222.267526)
		(mid 80.259738 -222.065434)
		(end 80.195928 -221.804484)
		(width 0.0889)
		(layer "In13.Cu")
		(net "M_B_CPU1_SA_DQ<3>")
	)
	(arc
		(start 82.321654 -225.510852)
		(mid 82.141002 -225.308107)
		(end 82.075782 -225.044508)
		(width 0.0889)
		(layer "In13.Cu")
		(net "M_B_CPU1_SA_DQ<3>")
	)
	(arc
		(start 88.4682 -226.34194)
		(mid 88.285949 -226.29159)
		(end 88.10244 -226.337114)
		(width 0.0889)
		(layer "In13.Cu")
		(net "M_B_CPU1_SA_DQ<3>")
	)
	(arc
		(start 84.334096 -226.34194)
		(mid 84.05114 -226.418117)
		(end 83.768184 -226.34194)
		(width 0.0889)
		(layer "In13.Cu")
		(net "M_B_CPU1_SA_DQ<3>")
	)
	(arc
		(start 82.545682 -225.854514)
		(mid 82.504427 -225.683543)
		(end 82.389726 -225.550222)
		(width 0.0889)
		(layer "In13.Cu")
		(net "M_B_CPU1_SA_DQ<3>")
	)
	(arc
		(start 88.094058 -226.34194)
		(mid 87.811102 -226.418117)
		(end 87.528146 -226.34194)
		(width 0.0889)
		(layer "In13.Cu")
		(net "M_B_CPU1_SA_DQ<3>")
	)
	(segment
		(start 89.687908 -244.750336)
		(end 89.221056 -244.484398)
		(width 0.10668)
		(layer "F.Cu")
		(net "M_B_CPU1_SA_DQ<31>")
	)
	(segment
		(start 77.496416 -244.111272)
		(end 77.940408 -244.111272)
		(width 0.0889)
		(layer "In13.Cu")
		(net "M_B_CPU1_SA_DQ<31>")
	)
	(segment
		(start 83.394042 -244.161818)
		(end 83.402424 -244.156992)
		(width 0.0889)
		(layer "In13.Cu")
		(net "M_B_CPU1_SA_DQ<31>")
	)
	(segment
		(start 49.797462 -233.885232)
		(end 50.222404 -233.46029)
		(width 0.14478)
		(layer "In13.Cu")
		(net "M_B_CPU1_SA_DQ<31>")
	)
	(segment
		(start 88.094058 -244.161818)
		(end 88.10244 -244.156992)
		(width 0.0889)
		(layer "In13.Cu")
		(net "M_B_CPU1_SA_DQ<31>")
	)
	(segment
		(start 54.049676 -234.310428)
		(end 59.588146 -234.310428)
		(width 0.14478)
		(layer "In13.Cu")
		(net "M_B_CPU1_SA_DQ<31>")
	)
	(segment
		(start 50.222404 -233.46029)
		(end 53.199538 -233.46029)
		(width 0.14478)
		(layer "In13.Cu")
		(net "M_B_CPU1_SA_DQ<31>")
	)
	(segment
		(start 53.199538 -233.46029)
		(end 54.049676 -234.310428)
		(width 0.14478)
		(layer "In13.Cu")
		(net "M_B_CPU1_SA_DQ<31>")
	)
	(segment
		(start 59.588146 -234.310428)
		(end 63.370714 -238.092996)
		(width 0.14478)
		(layer "In13.Cu")
		(net "M_B_CPU1_SA_DQ<31>")
	)
	(segment
		(start 63.370714 -238.867696)
		(end 68.013326 -243.510308)
		(width 0.14478)
		(layer "In13.Cu")
		(net "M_B_CPU1_SA_DQ<31>")
	)
	(segment
		(start 89.067132 -244.218968)
		(end 89.221056 -244.484398)
		(width 0.0889)
		(layer "In13.Cu")
		(net "M_B_CPU1_SA_DQ<31>")
	)
	(segment
		(start 77.15123 -243.766086)
		(end 77.496416 -244.111272)
		(width 0.0889)
		(layer "In13.Cu")
		(net "M_B_CPU1_SA_DQ<31>")
	)
	(segment
		(start 78.67777 -244.171216)
		(end 78.693518 -244.162072)
		(width 0.0889)
		(layer "In13.Cu")
		(net "M_B_CPU1_SA_DQ<31>")
	)
	(segment
		(start 76.46035 -243.766086)
		(end 77.15123 -243.766086)
		(width 0.0889)
		(layer "In13.Cu")
		(net "M_B_CPU1_SA_DQ<31>")
	)
	(segment
		(start 68.013326 -243.510308)
		(end 75.927966 -243.510308)
		(width 0.14478)
		(layer "In13.Cu")
		(net "M_B_CPU1_SA_DQ<31>")
	)
	(segment
		(start 78.693518 -244.162072)
		(end 78.709774 -244.152674)
		(width 0.0889)
		(layer "In13.Cu")
		(net "M_B_CPU1_SA_DQ<31>")
	)
	(segment
		(start 63.370714 -238.092996)
		(end 63.370714 -238.867696)
		(width 0.14478)
		(layer "In13.Cu")
		(net "M_B_CPU1_SA_DQ<31>")
	)
	(segment
		(start 79.99984 -244.156992)
		(end 80.008222 -244.161818)
		(width 0.0889)
		(layer "In13.Cu")
		(net "M_B_CPU1_SA_DQ<31>")
	)
	(segment
		(start 82.453988 -244.161818)
		(end 82.46237 -244.156992)
		(width 0.0889)
		(layer "In13.Cu")
		(net "M_B_CPU1_SA_DQ<31>")
	)
	(segment
		(start 76.204572 -243.510308)
		(end 76.46035 -243.766086)
		(width 0.0889)
		(layer "In13.Cu")
		(net "M_B_CPU1_SA_DQ<31>")
	)
	(segment
		(start 47.784004 -233.885232)
		(end 49.797462 -233.885232)
		(width 0.14478)
		(layer "In13.Cu")
		(net "M_B_CPU1_SA_DQ<31>")
	)
	(segment
		(start 79.067406 -244.161818)
		(end 79.07782 -244.167914)
		(width 0.0889)
		(layer "In13.Cu")
		(net "M_B_CPU1_SA_DQ<31>")
	)
	(segment
		(start 85.639656 -244.156992)
		(end 85.648038 -244.161818)
		(width 0.0889)
		(layer "In13.Cu")
		(net "M_B_CPU1_SA_DQ<31>")
	)
	(segment
		(start 88.97112 -244.193568)
		(end 89.067132 -244.218968)
		(width 0.0889)
		(layer "In13.Cu")
		(net "M_B_CPU1_SA_DQ<31>")
	)
	(segment
		(start 87.154004 -244.161818)
		(end 87.162386 -244.156992)
		(width 0.0889)
		(layer "In13.Cu")
		(net "M_B_CPU1_SA_DQ<31>")
	)
	(segment
		(start 75.927966 -243.510308)
		(end 76.204572 -243.510308)
		(width 0.0889)
		(layer "In13.Cu")
		(net "M_B_CPU1_SA_DQ<31>")
	)
	(segment
		(start 86.57971 -244.156992)
		(end 86.588092 -244.161818)
		(width 0.0889)
		(layer "In13.Cu")
		(net "M_B_CPU1_SA_DQ<31>")
	)
	(segment
		(start 81.879694 -244.156992)
		(end 81.888076 -244.161818)
		(width 0.0889)
		(layer "In13.Cu")
		(net "M_B_CPU1_SA_DQ<31>")
	)
	(arc
		(start 84.334096 -244.161818)
		(mid 84.52104 -244.111563)
		(end 84.707984 -244.161818)
		(width 0.0889)
		(layer "In13.Cu")
		(net "M_B_CPU1_SA_DQ<31>")
	)
	(arc
		(start 85.648038 -244.161818)
		(mid 85.930994 -244.237995)
		(end 86.21395 -244.161818)
		(width 0.0889)
		(layer "In13.Cu")
		(net "M_B_CPU1_SA_DQ<31>")
	)
	(arc
		(start 81.513934 -244.161818)
		(mid 81.696185 -244.111468)
		(end 81.879694 -244.156992)
		(width 0.0889)
		(layer "In13.Cu")
		(net "M_B_CPU1_SA_DQ<31>")
	)
	(arc
		(start 83.768184 -244.161818)
		(mid 84.05114 -244.237995)
		(end 84.334096 -244.161818)
		(width 0.0889)
		(layer "In13.Cu")
		(net "M_B_CPU1_SA_DQ<31>")
	)
	(arc
		(start 82.82813 -244.161818)
		(mid 83.111086 -244.237995)
		(end 83.394042 -244.161818)
		(width 0.0889)
		(layer "In13.Cu")
		(net "M_B_CPU1_SA_DQ<31>")
	)
	(arc
		(start 80.574134 -244.161818)
		(mid 80.761078 -244.111563)
		(end 80.948022 -244.161818)
		(width 0.0889)
		(layer "In13.Cu")
		(net "M_B_CPU1_SA_DQ<31>")
	)
	(arc
		(start 78.709774 -244.152674)
		(mid 78.889756 -244.111574)
		(end 79.067406 -244.161818)
		(width 0.0889)
		(layer "In13.Cu")
		(net "M_B_CPU1_SA_DQ<31>")
	)
	(arc
		(start 84.707984 -244.161818)
		(mid 84.99094 -244.237995)
		(end 85.273896 -244.161818)
		(width 0.0889)
		(layer "In13.Cu")
		(net "M_B_CPU1_SA_DQ<31>")
	)
	(arc
		(start 77.940408 -244.111272)
		(mid 78.037359 -244.124147)
		(end 78.127606 -244.161818)
		(width 0.0889)
		(layer "In13.Cu")
		(net "M_B_CPU1_SA_DQ<31>")
	)
	(arc
		(start 80.948022 -244.161818)
		(mid 81.230978 -244.237995)
		(end 81.513934 -244.161818)
		(width 0.0889)
		(layer "In13.Cu")
		(net "M_B_CPU1_SA_DQ<31>")
	)
	(arc
		(start 79.07782 -244.167914)
		(mid 79.356506 -244.238134)
		(end 79.633572 -244.161818)
		(width 0.0889)
		(layer "In13.Cu")
		(net "M_B_CPU1_SA_DQ<31>")
	)
	(arc
		(start 88.10244 -244.156992)
		(mid 88.285948 -244.111498)
		(end 88.4682 -244.161818)
		(width 0.0889)
		(layer "In13.Cu")
		(net "M_B_CPU1_SA_DQ<31>")
	)
	(arc
		(start 83.402424 -244.156992)
		(mid 83.585932 -244.111498)
		(end 83.768184 -244.161818)
		(width 0.0889)
		(layer "In13.Cu")
		(net "M_B_CPU1_SA_DQ<31>")
	)
	(arc
		(start 82.46237 -244.156992)
		(mid 82.645878 -244.111498)
		(end 82.82813 -244.161818)
		(width 0.0889)
		(layer "In13.Cu")
		(net "M_B_CPU1_SA_DQ<31>")
	)
	(arc
		(start 79.633572 -244.161818)
		(mid 79.816077 -244.111341)
		(end 79.99984 -244.156992)
		(width 0.0889)
		(layer "In13.Cu")
		(net "M_B_CPU1_SA_DQ<31>")
	)
	(arc
		(start 80.008222 -244.161818)
		(mid 80.291178 -244.237995)
		(end 80.574134 -244.161818)
		(width 0.0889)
		(layer "In13.Cu")
		(net "M_B_CPU1_SA_DQ<31>")
	)
	(arc
		(start 87.528146 -244.161818)
		(mid 87.811102 -244.237995)
		(end 88.094058 -244.161818)
		(width 0.0889)
		(layer "In13.Cu")
		(net "M_B_CPU1_SA_DQ<31>")
	)
	(arc
		(start 81.888076 -244.161818)
		(mid 82.171032 -244.237995)
		(end 82.453988 -244.161818)
		(width 0.0889)
		(layer "In13.Cu")
		(net "M_B_CPU1_SA_DQ<31>")
	)
	(arc
		(start 86.588092 -244.161818)
		(mid 86.871048 -244.237995)
		(end 87.154004 -244.161818)
		(width 0.0889)
		(layer "In13.Cu")
		(net "M_B_CPU1_SA_DQ<31>")
	)
	(arc
		(start 88.4682 -244.161818)
		(mid 88.715913 -244.237038)
		(end 88.97112 -244.193568)
		(width 0.0889)
		(layer "In13.Cu")
		(net "M_B_CPU1_SA_DQ<31>")
	)
	(arc
		(start 87.162386 -244.156992)
		(mid 87.345894 -244.111498)
		(end 87.528146 -244.161818)
		(width 0.0889)
		(layer "In13.Cu")
		(net "M_B_CPU1_SA_DQ<31>")
	)
	(arc
		(start 78.127606 -244.161818)
		(mid 78.401461 -244.238168)
		(end 78.67777 -244.171216)
		(width 0.0889)
		(layer "In13.Cu")
		(net "M_B_CPU1_SA_DQ<31>")
	)
	(arc
		(start 86.21395 -244.161818)
		(mid 86.396201 -244.111468)
		(end 86.57971 -244.156992)
		(width 0.0889)
		(layer "In13.Cu")
		(net "M_B_CPU1_SA_DQ<31>")
	)
	(arc
		(start 85.273896 -244.161818)
		(mid 85.456147 -244.111468)
		(end 85.639656 -244.156992)
		(width 0.0889)
		(layer "In13.Cu")
		(net "M_B_CPU1_SA_DQ<31>")
	)
	(segment
		(start 88.277954 -243.94033)
		(end 87.811102 -243.674392)
		(width 0.10668)
		(layer "F.Cu")
		(net "M_B_CPU1_SA_DQ<30>")
	)
	(segment
		(start 77.618082 -243.300758)
		(end 78.41107 -243.300758)
		(width 0.0889)
		(layer "In13.Cu")
		(net "M_B_CPU1_SA_DQ<30>")
	)
	(segment
		(start 49.237392 -232.958386)
		(end 49.237392 -232.32999)
		(width 0.14478)
		(layer "In13.Cu")
		(net "M_B_CPU1_SA_DQ<30>")
	)
	(segment
		(start 75.95997 -242.595908)
		(end 76.308712 -242.595908)
		(width 0.0889)
		(layer "In13.Cu")
		(net "M_B_CPU1_SA_DQ<30>")
	)
	(segment
		(start 80.46974 -243.346986)
		(end 80.478122 -243.351812)
		(width 0.0889)
		(layer "In13.Cu")
		(net "M_B_CPU1_SA_DQ<30>")
	)
	(segment
		(start 85.74405 -243.351812)
		(end 85.752432 -243.346986)
		(width 0.0889)
		(layer "In13.Cu")
		(net "M_B_CPU1_SA_DQ<30>")
	)
	(segment
		(start 48.541432 -232.18521)
		(end 48.686212 -232.32999)
		(width 0.14478)
		(layer "In13.Cu")
		(net "M_B_CPU1_SA_DQ<30>")
	)
	(segment
		(start 77.05471 -242.737386)
		(end 77.618082 -243.300758)
		(width 0.0889)
		(layer "In13.Cu")
		(net "M_B_CPU1_SA_DQ<30>")
	)
	(segment
		(start 84.229702 -243.346986)
		(end 84.238084 -243.351812)
		(width 0.0889)
		(layer "In13.Cu")
		(net "M_B_CPU1_SA_DQ<30>")
	)
	(segment
		(start 59.473084 -232.610406)
		(end 64.511428 -237.64875)
		(width 0.14478)
		(layer "In13.Cu")
		(net "M_B_CPU1_SA_DQ<30>")
	)
	(segment
		(start 53.256434 -231.760268)
		(end 54.106572 -232.610406)
		(width 0.14478)
		(layer "In13.Cu")
		(net "M_B_CPU1_SA_DQ<30>")
	)
	(segment
		(start 64.511428 -238.692436)
		(end 68.4149 -242.595908)
		(width 0.14478)
		(layer "In13.Cu")
		(net "M_B_CPU1_SA_DQ<30>")
	)
	(segment
		(start 50.222404 -231.760268)
		(end 53.256434 -231.760268)
		(width 0.14478)
		(layer "In13.Cu")
		(net "M_B_CPU1_SA_DQ<30>")
	)
	(segment
		(start 49.092612 -233.103166)
		(end 49.237392 -232.958386)
		(width 0.14478)
		(layer "In13.Cu")
		(net "M_B_CPU1_SA_DQ<30>")
	)
	(segment
		(start 47.784004 -232.18521)
		(end 48.541432 -232.18521)
		(width 0.14478)
		(layer "In13.Cu")
		(net "M_B_CPU1_SA_DQ<30>")
	)
	(segment
		(start 49.382172 -232.18521)
		(end 49.797462 -232.18521)
		(width 0.14478)
		(layer "In13.Cu")
		(net "M_B_CPU1_SA_DQ<30>")
	)
	(segment
		(start 79.521304 -243.341652)
		(end 79.539592 -243.352066)
		(width 0.0889)
		(layer "In13.Cu")
		(net "M_B_CPU1_SA_DQ<30>")
	)
	(segment
		(start 76.308712 -242.595908)
		(end 76.45019 -242.737386)
		(width 0.0889)
		(layer "In13.Cu")
		(net "M_B_CPU1_SA_DQ<30>")
	)
	(segment
		(start 87.560658 -243.383562)
		(end 87.656924 -243.408962)
		(width 0.0889)
		(layer "In13.Cu")
		(net "M_B_CPU1_SA_DQ<30>")
	)
	(segment
		(start 48.686212 -232.32999)
		(end 48.686212 -232.958386)
		(width 0.14478)
		(layer "In13.Cu")
		(net "M_B_CPU1_SA_DQ<30>")
	)
	(segment
		(start 81.044034 -243.351812)
		(end 81.052416 -243.346986)
		(width 0.0889)
		(layer "In13.Cu")
		(net "M_B_CPU1_SA_DQ<30>")
	)
	(segment
		(start 79.143098 -243.365528)
		(end 79.166466 -243.351812)
		(width 0.0889)
		(layer "In13.Cu")
		(net "M_B_CPU1_SA_DQ<30>")
	)
	(segment
		(start 54.106572 -232.610406)
		(end 59.473084 -232.610406)
		(width 0.14478)
		(layer "In13.Cu")
		(net "M_B_CPU1_SA_DQ<30>")
	)
	(segment
		(start 87.656924 -243.408962)
		(end 87.811102 -243.674392)
		(width 0.0889)
		(layer "In13.Cu")
		(net "M_B_CPU1_SA_DQ<30>")
	)
	(segment
		(start 49.797462 -232.18521)
		(end 50.222404 -231.760268)
		(width 0.14478)
		(layer "In13.Cu")
		(net "M_B_CPU1_SA_DQ<30>")
	)
	(segment
		(start 64.511428 -237.64875)
		(end 64.511428 -238.692436)
		(width 0.14478)
		(layer "In13.Cu")
		(net "M_B_CPU1_SA_DQ<30>")
	)
	(segment
		(start 76.45019 -242.737386)
		(end 77.05471 -242.737386)
		(width 0.0889)
		(layer "In13.Cu")
		(net "M_B_CPU1_SA_DQ<30>")
	)
	(segment
		(start 48.686212 -232.958386)
		(end 48.830992 -233.103166)
		(width 0.14478)
		(layer "In13.Cu")
		(net "M_B_CPU1_SA_DQ<30>")
	)
	(segment
		(start 49.237392 -232.32999)
		(end 49.382172 -232.18521)
		(width 0.14478)
		(layer "In13.Cu")
		(net "M_B_CPU1_SA_DQ<30>")
	)
	(segment
		(start 84.803996 -243.351812)
		(end 84.812378 -243.346986)
		(width 0.0889)
		(layer "In13.Cu")
		(net "M_B_CPU1_SA_DQ<30>")
	)
	(segment
		(start 48.830992 -233.103166)
		(end 49.092612 -233.103166)
		(width 0.14478)
		(layer "In13.Cu")
		(net "M_B_CPU1_SA_DQ<30>")
	)
	(segment
		(start 68.4149 -242.595908)
		(end 75.95997 -242.595908)
		(width 0.14478)
		(layer "In13.Cu")
		(net "M_B_CPU1_SA_DQ<30>")
	)
	(segment
		(start 79.539592 -243.352066)
		(end 79.561182 -243.364512)
		(width 0.0889)
		(layer "In13.Cu")
		(net "M_B_CPU1_SA_DQ<30>")
	)
	(segment
		(start 83.289648 -243.346986)
		(end 83.29803 -243.351812)
		(width 0.0889)
		(layer "In13.Cu")
		(net "M_B_CPU1_SA_DQ<30>")
	)
	(arc
		(start 85.178138 -243.351812)
		(mid 85.461094 -243.427989)
		(end 85.74405 -243.351812)
		(width 0.0889)
		(layer "In13.Cu")
		(net "M_B_CPU1_SA_DQ<30>")
	)
	(arc
		(start 86.118192 -243.351812)
		(mid 86.401148 -243.427989)
		(end 86.684104 -243.351812)
		(width 0.0889)
		(layer "In13.Cu")
		(net "M_B_CPU1_SA_DQ<30>")
	)
	(arc
		(start 87.057992 -243.351812)
		(mid 87.305588 -243.42699)
		(end 87.560658 -243.383562)
		(width 0.0889)
		(layer "In13.Cu")
		(net "M_B_CPU1_SA_DQ<30>")
	)
	(arc
		(start 82.357976 -243.351812)
		(mid 82.640932 -243.427989)
		(end 82.923888 -243.351812)
		(width 0.0889)
		(layer "In13.Cu")
		(net "M_B_CPU1_SA_DQ<30>")
	)
	(arc
		(start 81.418176 -243.351812)
		(mid 81.701132 -243.427989)
		(end 81.984088 -243.351812)
		(width 0.0889)
		(layer "In13.Cu")
		(net "M_B_CPU1_SA_DQ<30>")
	)
	(arc
		(start 84.238084 -243.351812)
		(mid 84.52104 -243.427989)
		(end 84.803996 -243.351812)
		(width 0.0889)
		(layer "In13.Cu")
		(net "M_B_CPU1_SA_DQ<30>")
	)
	(arc
		(start 84.812378 -243.346986)
		(mid 84.995886 -243.301492)
		(end 85.178138 -243.351812)
		(width 0.0889)
		(layer "In13.Cu")
		(net "M_B_CPU1_SA_DQ<30>")
	)
	(arc
		(start 83.863942 -243.351812)
		(mid 84.046193 -243.301462)
		(end 84.229702 -243.346986)
		(width 0.0889)
		(layer "In13.Cu")
		(net "M_B_CPU1_SA_DQ<30>")
	)
	(arc
		(start 79.561182 -243.364512)
		(mid 79.834211 -243.427831)
		(end 80.10398 -243.351812)
		(width 0.0889)
		(layer "In13.Cu")
		(net "M_B_CPU1_SA_DQ<30>")
	)
	(arc
		(start 83.29803 -243.351812)
		(mid 83.580986 -243.427989)
		(end 83.863942 -243.351812)
		(width 0.0889)
		(layer "In13.Cu")
		(net "M_B_CPU1_SA_DQ<30>")
	)
	(arc
		(start 80.478122 -243.351812)
		(mid 80.761078 -243.427989)
		(end 81.044034 -243.351812)
		(width 0.0889)
		(layer "In13.Cu")
		(net "M_B_CPU1_SA_DQ<30>")
	)
	(arc
		(start 82.923888 -243.351812)
		(mid 83.106139 -243.301462)
		(end 83.289648 -243.346986)
		(width 0.0889)
		(layer "In13.Cu")
		(net "M_B_CPU1_SA_DQ<30>")
	)
	(arc
		(start 78.599284 -243.351812)
		(mid 78.869441 -243.428574)
		(end 79.143098 -243.365528)
		(width 0.0889)
		(layer "In13.Cu")
		(net "M_B_CPU1_SA_DQ<30>")
	)
	(arc
		(start 80.10398 -243.351812)
		(mid 80.286231 -243.301462)
		(end 80.46974 -243.346986)
		(width 0.0889)
		(layer "In13.Cu")
		(net "M_B_CPU1_SA_DQ<30>")
	)
	(arc
		(start 85.752432 -243.346986)
		(mid 85.93594 -243.301492)
		(end 86.118192 -243.351812)
		(width 0.0889)
		(layer "In13.Cu")
		(net "M_B_CPU1_SA_DQ<30>")
	)
	(arc
		(start 81.052416 -243.346986)
		(mid 81.235924 -243.301492)
		(end 81.418176 -243.351812)
		(width 0.0889)
		(layer "In13.Cu")
		(net "M_B_CPU1_SA_DQ<30>")
	)
	(arc
		(start 78.41107 -243.300758)
		(mid 78.508573 -243.313773)
		(end 78.599284 -243.351812)
		(width 0.0889)
		(layer "In13.Cu")
		(net "M_B_CPU1_SA_DQ<30>")
	)
	(arc
		(start 86.684104 -243.351812)
		(mid 86.871048 -243.301557)
		(end 87.057992 -243.351812)
		(width 0.0889)
		(layer "In13.Cu")
		(net "M_B_CPU1_SA_DQ<30>")
	)
	(arc
		(start 79.166466 -243.351812)
		(mid 79.342586 -243.301834)
		(end 79.521304 -243.341652)
		(width 0.0889)
		(layer "In13.Cu")
		(net "M_B_CPU1_SA_DQ<30>")
	)
	(arc
		(start 81.984088 -243.351812)
		(mid 82.171032 -243.301557)
		(end 82.357976 -243.351812)
		(width 0.0889)
		(layer "In13.Cu")
		(net "M_B_CPU1_SA_DQ<30>")
	)
	(segment
		(start 88.277954 -226.120452)
		(end 87.811102 -225.854514)
		(width 0.10668)
		(layer "F.Cu")
		(net "M_B_CPU1_SA_DQ<2>")
	)
	(segment
		(start 49.797462 -198.185278)
		(end 47.784004 -198.185278)
		(width 0.14478)
		(layer "In13.Cu")
		(net "M_B_CPU1_SA_DQ<2>")
	)
	(segment
		(start 85.752432 -225.527108)
		(end 85.74405 -225.531934)
		(width 0.0889)
		(layer "In13.Cu")
		(net "M_B_CPU1_SA_DQ<2>")
	)
	(segment
		(start 87.656924 -225.589084)
		(end 87.560658 -225.563684)
		(width 0.0889)
		(layer "In13.Cu")
		(net "M_B_CPU1_SA_DQ<2>")
	)
	(segment
		(start 81.888076 -223.101916)
		(end 81.84896 -223.079056)
		(width 0.0889)
		(layer "In13.Cu")
		(net "M_B_CPU1_SA_DQ<2>")
	)
	(segment
		(start 53.256434 -197.760336)
		(end 50.222404 -197.760336)
		(width 0.14478)
		(layer "In13.Cu")
		(net "M_B_CPU1_SA_DQ<2>")
	)
	(segment
		(start 87.811102 -225.854514)
		(end 87.656924 -225.589084)
		(width 0.0889)
		(layer "In13.Cu")
		(net "M_B_CPU1_SA_DQ<2>")
	)
	(segment
		(start 82.82813 -224.721928)
		(end 82.789014 -224.699068)
		(width 0.0889)
		(layer "In13.Cu")
		(net "M_B_CPU1_SA_DQ<2>")
	)
	(segment
		(start 81.094326 -219.739464)
		(end 59.965336 -198.610474)
		(width 0.14478)
		(layer "In13.Cu")
		(net "M_B_CPU1_SA_DQ<2>")
	)
	(segment
		(start 81.919826 -223.120204)
		(end 81.888076 -223.101916)
		(width 0.0889)
		(layer "In13.Cu")
		(net "M_B_CPU1_SA_DQ<2>")
	)
	(segment
		(start 50.222404 -197.760336)
		(end 49.797462 -198.185278)
		(width 0.14478)
		(layer "In13.Cu")
		(net "M_B_CPU1_SA_DQ<2>")
	)
	(segment
		(start 82.357976 -223.911922)
		(end 82.321654 -223.89084)
		(width 0.0889)
		(layer "In13.Cu")
		(net "M_B_CPU1_SA_DQ<2>")
	)
	(segment
		(start 59.965336 -198.610474)
		(end 54.106572 -198.610474)
		(width 0.14478)
		(layer "In13.Cu")
		(net "M_B_CPU1_SA_DQ<2>")
	)
	(segment
		(start 83.29803 -225.531934)
		(end 83.258914 -225.509074)
		(width 0.0889)
		(layer "In13.Cu")
		(net "M_B_CPU1_SA_DQ<2>")
	)
	(segment
		(start 54.106572 -198.610474)
		(end 53.256434 -197.760336)
		(width 0.14478)
		(layer "In13.Cu")
		(net "M_B_CPU1_SA_DQ<2>")
	)
	(segment
		(start 82.85861 -224.739708)
		(end 82.82813 -224.721928)
		(width 0.0889)
		(layer "In13.Cu")
		(net "M_B_CPU1_SA_DQ<2>")
	)
	(segment
		(start 82.389726 -223.93021)
		(end 82.357976 -223.911922)
		(width 0.0889)
		(layer "In13.Cu")
		(net "M_B_CPU1_SA_DQ<2>")
	)
	(segment
		(start 84.238084 -225.531934)
		(end 84.229702 -225.527108)
		(width 0.0889)
		(layer "In13.Cu")
		(net "M_B_CPU1_SA_DQ<2>")
	)
	(segment
		(start 81.094326 -221.304104)
		(end 81.094326 -219.739464)
		(width 0.14478)
		(layer "In13.Cu")
		(net "M_B_CPU1_SA_DQ<2>")
	)
	(segment
		(start 81.094326 -221.521782)
		(end 81.094326 -221.304104)
		(width 0.0889)
		(layer "In13.Cu")
		(net "M_B_CPU1_SA_DQ<2>")
	)
	(segment
		(start 84.812378 -225.527108)
		(end 84.803996 -225.531934)
		(width 0.0889)
		(layer "In13.Cu")
		(net "M_B_CPU1_SA_DQ<2>")
	)
	(segment
		(start 81.605628 -222.61449)
		(end 81.605628 -222.033084)
		(width 0.0889)
		(layer "In13.Cu")
		(net "M_B_CPU1_SA_DQ<2>")
	)
	(segment
		(start 81.605628 -222.033084)
		(end 81.094326 -221.521782)
		(width 0.0889)
		(layer "In13.Cu")
		(net "M_B_CPU1_SA_DQ<2>")
	)
	(arc
		(start 86.684104 -225.531934)
		(mid 86.401148 -225.608111)
		(end 86.118192 -225.531934)
		(width 0.0889)
		(layer "In13.Cu")
		(net "M_B_CPU1_SA_DQ<2>")
	)
	(arc
		(start 85.178138 -225.531934)
		(mid 84.995887 -225.481584)
		(end 84.812378 -225.527108)
		(width 0.0889)
		(layer "In13.Cu")
		(net "M_B_CPU1_SA_DQ<2>")
	)
	(arc
		(start 83.015582 -225.044508)
		(mid 82.974033 -224.873086)
		(end 82.85861 -224.739708)
		(width 0.0889)
		(layer "In13.Cu")
		(net "M_B_CPU1_SA_DQ<2>")
	)
	(arc
		(start 84.229702 -225.527108)
		(mid 84.046194 -225.481614)
		(end 83.863942 -225.531934)
		(width 0.0889)
		(layer "In13.Cu")
		(net "M_B_CPU1_SA_DQ<2>")
	)
	(arc
		(start 82.789014 -224.699068)
		(mid 82.610201 -224.496718)
		(end 82.545682 -224.234502)
		(width 0.0889)
		(layer "In13.Cu")
		(net "M_B_CPU1_SA_DQ<2>")
	)
	(arc
		(start 81.84896 -223.079056)
		(mid 81.670147 -222.876706)
		(end 81.605628 -222.61449)
		(width 0.0889)
		(layer "In13.Cu")
		(net "M_B_CPU1_SA_DQ<2>")
	)
	(arc
		(start 83.863942 -225.531934)
		(mid 83.580986 -225.608111)
		(end 83.29803 -225.531934)
		(width 0.0889)
		(layer "In13.Cu")
		(net "M_B_CPU1_SA_DQ<2>")
	)
	(arc
		(start 82.075782 -223.424496)
		(mid 82.034527 -223.253525)
		(end 81.919826 -223.120204)
		(width 0.0889)
		(layer "In13.Cu")
		(net "M_B_CPU1_SA_DQ<2>")
	)
	(arc
		(start 83.258914 -225.509074)
		(mid 83.080101 -225.306724)
		(end 83.015582 -225.044508)
		(width 0.0889)
		(layer "In13.Cu")
		(net "M_B_CPU1_SA_DQ<2>")
	)
	(arc
		(start 85.74405 -225.531934)
		(mid 85.461094 -225.608111)
		(end 85.178138 -225.531934)
		(width 0.0889)
		(layer "In13.Cu")
		(net "M_B_CPU1_SA_DQ<2>")
	)
	(arc
		(start 84.803996 -225.531934)
		(mid 84.52104 -225.608111)
		(end 84.238084 -225.531934)
		(width 0.0889)
		(layer "In13.Cu")
		(net "M_B_CPU1_SA_DQ<2>")
	)
	(arc
		(start 82.545682 -224.234502)
		(mid 82.504427 -224.063531)
		(end 82.389726 -223.93021)
		(width 0.0889)
		(layer "In13.Cu")
		(net "M_B_CPU1_SA_DQ<2>")
	)
	(arc
		(start 87.560658 -225.563684)
		(mid 87.305593 -225.607035)
		(end 87.057992 -225.531934)
		(width 0.0889)
		(layer "In13.Cu")
		(net "M_B_CPU1_SA_DQ<2>")
	)
	(arc
		(start 82.321654 -223.89084)
		(mid 82.141002 -223.688095)
		(end 82.075782 -223.424496)
		(width 0.0889)
		(layer "In13.Cu")
		(net "M_B_CPU1_SA_DQ<2>")
	)
	(arc
		(start 86.118192 -225.531934)
		(mid 85.935941 -225.481584)
		(end 85.752432 -225.527108)
		(width 0.0889)
		(layer "In13.Cu")
		(net "M_B_CPU1_SA_DQ<2>")
	)
	(arc
		(start 87.057992 -225.531934)
		(mid 86.871048 -225.481679)
		(end 86.684104 -225.531934)
		(width 0.0889)
		(layer "In13.Cu")
		(net "M_B_CPU1_SA_DQ<2>")
	)
	(segment
		(start 89.218008 -243.94033)
		(end 88.751156 -243.674392)
		(width 0.10668)
		(layer "F.Cu")
		(net "M_B_CPU1_SA_DQ<29>")
	)
	(segment
		(start 78.59776 -243.996718)
		(end 78.603348 -243.993416)
		(width 0.0889)
		(layer "In13.Cu")
		(net "M_B_CPU1_SA_DQ<29>")
	)
	(segment
		(start 57.771284 -233.69651)
		(end 57.932828 -233.858054)
		(width 0.14478)
		(layer "In13.Cu")
		(net "M_B_CPU1_SA_DQ<29>")
	)
	(segment
		(start 51.884072 -233.035348)
		(end 52.309014 -232.610406)
		(width 0.14478)
		(layer "In13.Cu")
		(net "M_B_CPU1_SA_DQ<29>")
	)
	(segment
		(start 56.668416 -233.22407)
		(end 56.668416 -233.69651)
		(width 0.14478)
		(layer "In13.Cu")
		(net "M_B_CPU1_SA_DQ<29>")
	)
	(segment
		(start 52.309014 -232.610406)
		(end 52.997862 -232.610406)
		(width 0.14478)
		(layer "In13.Cu")
		(net "M_B_CPU1_SA_DQ<29>")
	)
	(segment
		(start 63.990982 -238.851948)
		(end 68.189602 -243.050568)
		(width 0.14478)
		(layer "In13.Cu")
		(net "M_B_CPU1_SA_DQ<29>")
	)
	(segment
		(start 57.60974 -233.062526)
		(end 57.771284 -233.22407)
		(width 0.14478)
		(layer "In13.Cu")
		(net "M_B_CPU1_SA_DQ<29>")
	)
	(segment
		(start 54.82844 -233.686858)
		(end 54.991508 -233.849926)
		(width 0.14478)
		(layer "In13.Cu")
		(net "M_B_CPU1_SA_DQ<29>")
	)
	(segment
		(start 54.271926 -233.237532)
		(end 54.434994 -233.074464)
		(width 0.14478)
		(layer "In13.Cu")
		(net "M_B_CPU1_SA_DQ<29>")
	)
	(segment
		(start 88.882728 -244.023134)
		(end 88.90508 -243.939822)
		(width 0.0889)
		(layer "In13.Cu")
		(net "M_B_CPU1_SA_DQ<29>")
	)
	(segment
		(start 58.874152 -233.298746)
		(end 59.035696 -233.46029)
		(width 0.14478)
		(layer "In13.Cu")
		(net "M_B_CPU1_SA_DQ<29>")
	)
	(segment
		(start 54.108858 -233.46029)
		(end 54.271926 -233.297222)
		(width 0.14478)
		(layer "In13.Cu")
		(net "M_B_CPU1_SA_DQ<29>")
	)
	(segment
		(start 77.68209 -243.920772)
		(end 77.940408 -243.920772)
		(width 0.0889)
		(layer "In13.Cu")
		(net "M_B_CPU1_SA_DQ<29>")
	)
	(segment
		(start 81.044034 -243.996972)
		(end 81.052416 -244.001798)
		(width 0.0889)
		(layer "In13.Cu")
		(net "M_B_CPU1_SA_DQ<29>")
	)
	(segment
		(start 83.289648 -244.001798)
		(end 83.29803 -243.996972)
		(width 0.0889)
		(layer "In13.Cu")
		(net "M_B_CPU1_SA_DQ<29>")
	)
	(segment
		(start 58.322718 -233.69651)
		(end 58.322718 -233.22407)
		(width 0.14478)
		(layer "In13.Cu")
		(net "M_B_CPU1_SA_DQ<29>")
	)
	(segment
		(start 58.161174 -233.858054)
		(end 58.322718 -233.69651)
		(width 0.14478)
		(layer "In13.Cu")
		(net "M_B_CPU1_SA_DQ<29>")
	)
	(segment
		(start 54.665372 -233.074464)
		(end 54.82844 -233.237532)
		(width 0.14478)
		(layer "In13.Cu")
		(net "M_B_CPU1_SA_DQ<29>")
	)
	(segment
		(start 68.189602 -243.050568)
		(end 75.94219 -243.050568)
		(width 0.14478)
		(layer "In13.Cu")
		(net "M_B_CPU1_SA_DQ<29>")
	)
	(segment
		(start 56.116982 -233.688382)
		(end 56.116982 -233.22407)
		(width 0.14478)
		(layer "In13.Cu")
		(net "M_B_CPU1_SA_DQ<29>")
	)
	(segment
		(start 79.163164 -243.996972)
		(end 79.171546 -244.001798)
		(width 0.0889)
		(layer "In13.Cu")
		(net "M_B_CPU1_SA_DQ<29>")
	)
	(segment
		(start 59.603894 -233.46029)
		(end 63.990982 -237.847378)
		(width 0.14478)
		(layer "In13.Cu")
		(net "M_B_CPU1_SA_DQ<29>")
	)
	(segment
		(start 58.484262 -233.062526)
		(end 58.712608 -233.062526)
		(width 0.14478)
		(layer "In13.Cu")
		(net "M_B_CPU1_SA_DQ<29>")
	)
	(segment
		(start 88.90508 -243.939822)
		(end 88.751156 -243.674392)
		(width 0.0889)
		(layer "In13.Cu")
		(net "M_B_CPU1_SA_DQ<29>")
	)
	(segment
		(start 52.997862 -232.610406)
		(end 53.847746 -233.46029)
		(width 0.14478)
		(layer "In13.Cu")
		(net "M_B_CPU1_SA_DQ<29>")
	)
	(segment
		(start 54.82844 -233.237532)
		(end 54.82844 -233.686858)
		(width 0.14478)
		(layer "In13.Cu")
		(net "M_B_CPU1_SA_DQ<29>")
	)
	(segment
		(start 58.712608 -233.062526)
		(end 58.874152 -233.22407)
		(width 0.14478)
		(layer "In13.Cu")
		(net "M_B_CPU1_SA_DQ<29>")
	)
	(segment
		(start 57.932828 -233.858054)
		(end 58.161174 -233.858054)
		(width 0.14478)
		(layer "In13.Cu")
		(net "M_B_CPU1_SA_DQ<29>")
	)
	(segment
		(start 80.46974 -244.001798)
		(end 80.478122 -243.996972)
		(width 0.0889)
		(layer "In13.Cu")
		(net "M_B_CPU1_SA_DQ<29>")
	)
	(segment
		(start 53.847746 -233.46029)
		(end 54.108858 -233.46029)
		(width 0.14478)
		(layer "In13.Cu")
		(net "M_B_CPU1_SA_DQ<29>")
	)
	(segment
		(start 78.579472 -244.007132)
		(end 78.59776 -243.996718)
		(width 0.0889)
		(layer "In13.Cu")
		(net "M_B_CPU1_SA_DQ<29>")
	)
	(segment
		(start 57.058306 -233.858054)
		(end 57.21985 -233.69651)
		(width 0.14478)
		(layer "In13.Cu")
		(net "M_B_CPU1_SA_DQ<29>")
	)
	(segment
		(start 84.803996 -243.996972)
		(end 84.812378 -244.001798)
		(width 0.0889)
		(layer "In13.Cu")
		(net "M_B_CPU1_SA_DQ<29>")
	)
	(segment
		(start 56.116982 -233.22407)
		(end 56.278526 -233.062526)
		(width 0.14478)
		(layer "In13.Cu")
		(net "M_B_CPU1_SA_DQ<29>")
	)
	(segment
		(start 57.771284 -233.22407)
		(end 57.771284 -233.69651)
		(width 0.14478)
		(layer "In13.Cu")
		(net "M_B_CPU1_SA_DQ<29>")
	)
	(segment
		(start 56.668416 -233.69651)
		(end 56.82996 -233.858054)
		(width 0.14478)
		(layer "In13.Cu")
		(net "M_B_CPU1_SA_DQ<29>")
	)
	(segment
		(start 63.990982 -237.847378)
		(end 63.990982 -238.851948)
		(width 0.14478)
		(layer "In13.Cu")
		(net "M_B_CPU1_SA_DQ<29>")
	)
	(segment
		(start 76.186792 -243.050568)
		(end 76.65593 -243.519706)
		(width 0.0889)
		(layer "In13.Cu")
		(net "M_B_CPU1_SA_DQ<29>")
	)
	(segment
		(start 56.278526 -233.062526)
		(end 56.506872 -233.062526)
		(width 0.14478)
		(layer "In13.Cu")
		(net "M_B_CPU1_SA_DQ<29>")
	)
	(segment
		(start 80.093566 -243.990876)
		(end 80.10398 -243.996972)
		(width 0.0889)
		(layer "In13.Cu")
		(net "M_B_CPU1_SA_DQ<29>")
	)
	(segment
		(start 77.281024 -243.519706)
		(end 77.68209 -243.920772)
		(width 0.0889)
		(layer "In13.Cu")
		(net "M_B_CPU1_SA_DQ<29>")
	)
	(segment
		(start 57.381394 -233.062526)
		(end 57.60974 -233.062526)
		(width 0.14478)
		(layer "In13.Cu")
		(net "M_B_CPU1_SA_DQ<29>")
	)
	(segment
		(start 54.434994 -233.074464)
		(end 54.665372 -233.074464)
		(width 0.14478)
		(layer "In13.Cu")
		(net "M_B_CPU1_SA_DQ<29>")
	)
	(segment
		(start 57.21985 -233.22407)
		(end 57.381394 -233.062526)
		(width 0.14478)
		(layer "In13.Cu")
		(net "M_B_CPU1_SA_DQ<29>")
	)
	(segment
		(start 57.21985 -233.69651)
		(end 57.21985 -233.22407)
		(width 0.14478)
		(layer "In13.Cu")
		(net "M_B_CPU1_SA_DQ<29>")
	)
	(segment
		(start 58.322718 -233.22407)
		(end 58.484262 -233.062526)
		(width 0.14478)
		(layer "In13.Cu")
		(net "M_B_CPU1_SA_DQ<29>")
	)
	(segment
		(start 58.874152 -233.22407)
		(end 58.874152 -233.298746)
		(width 0.14478)
		(layer "In13.Cu")
		(net "M_B_CPU1_SA_DQ<29>")
	)
	(segment
		(start 55.955438 -233.849926)
		(end 56.116982 -233.688382)
		(width 0.14478)
		(layer "In13.Cu")
		(net "M_B_CPU1_SA_DQ<29>")
	)
	(segment
		(start 56.82996 -233.858054)
		(end 57.058306 -233.858054)
		(width 0.14478)
		(layer "In13.Cu")
		(net "M_B_CPU1_SA_DQ<29>")
	)
	(segment
		(start 85.74405 -243.996972)
		(end 85.752432 -244.001798)
		(width 0.0889)
		(layer "In13.Cu")
		(net "M_B_CPU1_SA_DQ<29>")
	)
	(segment
		(start 56.506872 -233.062526)
		(end 56.668416 -233.22407)
		(width 0.14478)
		(layer "In13.Cu")
		(net "M_B_CPU1_SA_DQ<29>")
	)
	(segment
		(start 59.035696 -233.46029)
		(end 59.603894 -233.46029)
		(width 0.14478)
		(layer "In13.Cu")
		(net "M_B_CPU1_SA_DQ<29>")
	)
	(segment
		(start 76.65593 -243.519706)
		(end 77.281024 -243.519706)
		(width 0.0889)
		(layer "In13.Cu")
		(net "M_B_CPU1_SA_DQ<29>")
	)
	(segment
		(start 84.229702 -244.001798)
		(end 84.238084 -243.996972)
		(width 0.0889)
		(layer "In13.Cu")
		(net "M_B_CPU1_SA_DQ<29>")
	)
	(segment
		(start 54.271926 -233.297222)
		(end 54.271926 -233.237532)
		(width 0.14478)
		(layer "In13.Cu")
		(net "M_B_CPU1_SA_DQ<29>")
	)
	(segment
		(start 54.991508 -233.849926)
		(end 55.955438 -233.849926)
		(width 0.14478)
		(layer "In13.Cu")
		(net "M_B_CPU1_SA_DQ<29>")
	)
	(segment
		(start 75.94219 -243.050568)
		(end 76.186792 -243.050568)
		(width 0.0889)
		(layer "In13.Cu")
		(net "M_B_CPU1_SA_DQ<29>")
	)
	(segment
		(start 87.989664 -244.001798)
		(end 87.998046 -243.996972)
		(width 0.0889)
		(layer "In13.Cu")
		(net "M_B_CPU1_SA_DQ<29>")
	)
	(arc
		(start 81.052416 -244.001798)
		(mid 81.235924 -244.047292)
		(end 81.418176 -243.996972)
		(width 0.0889)
		(layer "In13.Cu")
		(net "M_B_CPU1_SA_DQ<29>")
	)
	(arc
		(start 79.537814 -243.996972)
		(mid 79.814881 -243.920701)
		(end 80.093566 -243.990876)
		(width 0.0889)
		(layer "In13.Cu")
		(net "M_B_CPU1_SA_DQ<29>")
	)
	(arc
		(start 78.603348 -243.993416)
		(mid 78.883737 -243.920747)
		(end 79.163164 -243.996972)
		(width 0.0889)
		(layer "In13.Cu")
		(net "M_B_CPU1_SA_DQ<29>")
	)
	(arc
		(start 87.057992 -243.996972)
		(mid 87.340948 -243.920795)
		(end 87.623904 -243.996972)
		(width 0.0889)
		(layer "In13.Cu")
		(net "M_B_CPU1_SA_DQ<29>")
	)
	(arc
		(start 85.752432 -244.001798)
		(mid 85.93594 -244.047292)
		(end 86.118192 -243.996972)
		(width 0.0889)
		(layer "In13.Cu")
		(net "M_B_CPU1_SA_DQ<29>")
	)
	(arc
		(start 81.984088 -243.996972)
		(mid 82.171032 -244.047227)
		(end 82.357976 -243.996972)
		(width 0.0889)
		(layer "In13.Cu")
		(net "M_B_CPU1_SA_DQ<29>")
	)
	(arc
		(start 88.563958 -243.996972)
		(mid 88.720396 -244.045943)
		(end 88.882728 -244.023134)
		(width 0.0889)
		(layer "In13.Cu")
		(net "M_B_CPU1_SA_DQ<29>")
	)
	(arc
		(start 77.940408 -243.920772)
		(mid 78.087065 -243.940109)
		(end 78.223618 -243.996972)
		(width 0.0889)
		(layer "In13.Cu")
		(net "M_B_CPU1_SA_DQ<29>")
	)
	(arc
		(start 81.418176 -243.996972)
		(mid 81.701132 -243.920795)
		(end 81.984088 -243.996972)
		(width 0.0889)
		(layer "In13.Cu")
		(net "M_B_CPU1_SA_DQ<29>")
	)
	(arc
		(start 79.171546 -244.001798)
		(mid 79.355308 -244.047414)
		(end 79.537814 -243.996972)
		(width 0.0889)
		(layer "In13.Cu")
		(net "M_B_CPU1_SA_DQ<29>")
	)
	(arc
		(start 80.10398 -243.996972)
		(mid 80.286231 -244.047322)
		(end 80.46974 -244.001798)
		(width 0.0889)
		(layer "In13.Cu")
		(net "M_B_CPU1_SA_DQ<29>")
	)
	(arc
		(start 87.623904 -243.996972)
		(mid 87.806155 -244.047322)
		(end 87.989664 -244.001798)
		(width 0.0889)
		(layer "In13.Cu")
		(net "M_B_CPU1_SA_DQ<29>")
	)
	(arc
		(start 84.238084 -243.996972)
		(mid 84.52104 -243.920795)
		(end 84.803996 -243.996972)
		(width 0.0889)
		(layer "In13.Cu")
		(net "M_B_CPU1_SA_DQ<29>")
	)
	(arc
		(start 87.998046 -243.996972)
		(mid 88.281002 -243.920795)
		(end 88.563958 -243.996972)
		(width 0.0889)
		(layer "In13.Cu")
		(net "M_B_CPU1_SA_DQ<29>")
	)
	(arc
		(start 86.684104 -243.996972)
		(mid 86.871048 -244.047227)
		(end 87.057992 -243.996972)
		(width 0.0889)
		(layer "In13.Cu")
		(net "M_B_CPU1_SA_DQ<29>")
	)
	(arc
		(start 82.923888 -243.996972)
		(mid 83.106139 -244.047322)
		(end 83.289648 -244.001798)
		(width 0.0889)
		(layer "In13.Cu")
		(net "M_B_CPU1_SA_DQ<29>")
	)
	(arc
		(start 85.178138 -243.996972)
		(mid 85.461094 -243.920795)
		(end 85.74405 -243.996972)
		(width 0.0889)
		(layer "In13.Cu")
		(net "M_B_CPU1_SA_DQ<29>")
	)
	(arc
		(start 83.863942 -243.996972)
		(mid 84.046193 -244.047322)
		(end 84.229702 -244.001798)
		(width 0.0889)
		(layer "In13.Cu")
		(net "M_B_CPU1_SA_DQ<29>")
	)
	(arc
		(start 78.223618 -243.996972)
		(mid 78.400246 -244.047205)
		(end 78.579472 -244.007132)
		(width 0.0889)
		(layer "In13.Cu")
		(net "M_B_CPU1_SA_DQ<29>")
	)
	(arc
		(start 82.357976 -243.996972)
		(mid 82.640932 -243.920795)
		(end 82.923888 -243.996972)
		(width 0.0889)
		(layer "In13.Cu")
		(net "M_B_CPU1_SA_DQ<29>")
	)
	(arc
		(start 84.812378 -244.001798)
		(mid 84.995886 -244.047292)
		(end 85.178138 -243.996972)
		(width 0.0889)
		(layer "In13.Cu")
		(net "M_B_CPU1_SA_DQ<29>")
	)
	(arc
		(start 83.29803 -243.996972)
		(mid 83.580986 -243.920795)
		(end 83.863942 -243.996972)
		(width 0.0889)
		(layer "In13.Cu")
		(net "M_B_CPU1_SA_DQ<29>")
	)
	(arc
		(start 80.478122 -243.996972)
		(mid 80.761078 -243.920795)
		(end 81.044034 -243.996972)
		(width 0.0889)
		(layer "In13.Cu")
		(net "M_B_CPU1_SA_DQ<29>")
	)
	(arc
		(start 86.118192 -243.996972)
		(mid 86.401148 -243.920795)
		(end 86.684104 -243.996972)
		(width 0.0889)
		(layer "In13.Cu")
		(net "M_B_CPU1_SA_DQ<29>")
	)
	(segment
		(start 87.8078 -243.130324)
		(end 87.340948 -242.864386)
		(width 0.10668)
		(layer "F.Cu")
		(net "M_B_CPU1_SA_DQ<28>")
	)
	(segment
		(start 63.014606 -235.458254)
		(end 63.255398 -235.699046)
		(width 0.14478)
		(layer "In13.Cu")
		(net "M_B_CPU1_SA_DQ<28>")
	)
	(segment
		(start 58.880756 -231.996742)
		(end 58.880756 -231.931464)
		(width 0.14478)
		(layer "In13.Cu")
		(net "M_B_CPU1_SA_DQ<28>")
	)
	(segment
		(start 58.167778 -231.76992)
		(end 58.329322 -231.931464)
		(width 0.14478)
		(layer "In13.Cu")
		(net "M_B_CPU1_SA_DQ<28>")
	)
	(segment
		(start 55.175912 -231.991916)
		(end 55.175912 -231.923336)
		(width 0.14478)
		(layer "In13.Cu")
		(net "M_B_CPU1_SA_DQ<28>")
	)
	(segment
		(start 85.639656 -243.191792)
		(end 85.648038 -243.186966)
		(width 0.0889)
		(layer "In13.Cu")
		(net "M_B_CPU1_SA_DQ<28>")
	)
	(segment
		(start 61.213492 -233.358182)
		(end 61.45403 -233.59872)
		(width 0.14478)
		(layer "In13.Cu")
		(net "M_B_CPU1_SA_DQ<28>")
	)
	(segment
		(start 77.267816 -242.480846)
		(end 77.897228 -243.110258)
		(width 0.0889)
		(layer "In13.Cu")
		(net "M_B_CPU1_SA_DQ<28>")
	)
	(segment
		(start 59.62523 -231.76992)
		(end 60.673742 -232.818432)
		(width 0.14478)
		(layer "In13.Cu")
		(net "M_B_CPU1_SA_DQ<28>")
	)
	(segment
		(start 76.61275 -242.480846)
		(end 77.267816 -242.480846)
		(width 0.0889)
		(layer "In13.Cu")
		(net "M_B_CPU1_SA_DQ<28>")
	)
	(segment
		(start 65.800478 -238.502444)
		(end 65.976754 -238.326168)
		(width 0.14478)
		(layer "In13.Cu")
		(net "M_B_CPU1_SA_DQ<28>")
	)
	(segment
		(start 60.914534 -233.358182)
		(end 61.213492 -233.358182)
		(width 0.14478)
		(layer "In13.Cu")
		(net "M_B_CPU1_SA_DQ<28>")
	)
	(segment
		(start 61.45403 -233.59872)
		(end 61.45403 -233.897678)
		(width 0.14478)
		(layer "In13.Cu")
		(net "M_B_CPU1_SA_DQ<28>")
	)
	(segment
		(start 59.0423 -231.76992)
		(end 59.62523 -231.76992)
		(width 0.14478)
		(layer "In13.Cu")
		(net "M_B_CPU1_SA_DQ<28>")
	)
	(segment
		(start 66.366898 -238.511588)
		(end 66.366644 -238.715804)
		(width 0.14478)
		(layer "In13.Cu")
		(net "M_B_CPU1_SA_DQ<28>")
	)
	(segment
		(start 67.749928 -240.656364)
		(end 67.935094 -240.84153)
		(width 0.14478)
		(layer "In13.Cu")
		(net "M_B_CPU1_SA_DQ<28>")
	)
	(segment
		(start 57.777888 -231.996742)
		(end 57.777888 -231.931464)
		(width 0.14478)
		(layer "In13.Cu")
		(net "M_B_CPU1_SA_DQ<28>")
	)
	(segment
		(start 55.33898 -231.760268)
		(end 55.569358 -231.760268)
		(width 0.14478)
		(layer "In13.Cu")
		(net "M_B_CPU1_SA_DQ<28>")
	)
	(segment
		(start 55.569358 -231.760268)
		(end 55.732426 -231.923336)
		(width 0.14478)
		(layer "In13.Cu")
		(net "M_B_CPU1_SA_DQ<28>")
	)
	(segment
		(start 60.673742 -232.818432)
		(end 60.673742 -233.11739)
		(width 0.14478)
		(layer "In13.Cu")
		(net "M_B_CPU1_SA_DQ<28>")
	)
	(segment
		(start 52.290472 -230.920036)
		(end 53.108098 -230.920036)
		(width 0.14478)
		(layer "In13.Cu")
		(net "M_B_CPU1_SA_DQ<28>")
	)
	(segment
		(start 62.703202 -234.918758)
		(end 62.773814 -234.918504)
		(width 0.14478)
		(layer "In13.Cu")
		(net "M_B_CPU1_SA_DQ<28>")
	)
	(segment
		(start 61.993526 -234.138216)
		(end 62.234318 -234.379008)
		(width 0.14478)
		(layer "In13.Cu")
		(net "M_B_CPU1_SA_DQ<28>")
	)
	(segment
		(start 66.190368 -238.89208)
		(end 66.190368 -239.096804)
		(width 0.14478)
		(layer "In13.Cu")
		(net "M_B_CPU1_SA_DQ<28>")
	)
	(segment
		(start 57.226454 -231.931464)
		(end 57.226454 -231.996742)
		(width 0.14478)
		(layer "In13.Cu")
		(net "M_B_CPU1_SA_DQ<28>")
	)
	(segment
		(start 64.263778 -236.479334)
		(end 64.33439 -236.47908)
		(width 0.14478)
		(layer "In13.Cu")
		(net "M_B_CPU1_SA_DQ<28>")
	)
	(segment
		(start 67.360038 -240.062004)
		(end 67.536314 -239.885728)
		(width 0.14478)
		(layer "In13.Cu")
		(net "M_B_CPU1_SA_DQ<28>")
	)
	(segment
		(start 87.472774 -243.213128)
		(end 87.495126 -243.129816)
		(width 0.0889)
		(layer "In13.Cu")
		(net "M_B_CPU1_SA_DQ<28>")
	)
	(segment
		(start 79.613252 -243.174266)
		(end 79.634842 -243.186712)
		(width 0.0889)
		(layer "In13.Cu")
		(net "M_B_CPU1_SA_DQ<28>")
	)
	(segment
		(start 64.035686 -236.479334)
		(end 64.263778 -236.479334)
		(width 0.14478)
		(layer "In13.Cu")
		(net "M_B_CPU1_SA_DQ<28>")
	)
	(segment
		(start 67.155314 -240.06175)
		(end 67.360038 -240.062004)
		(width 0.14478)
		(layer "In13.Cu")
		(net "M_B_CPU1_SA_DQ<28>")
	)
	(segment
		(start 57.777888 -231.931464)
		(end 57.939432 -231.76992)
		(width 0.14478)
		(layer "In13.Cu")
		(net "M_B_CPU1_SA_DQ<28>")
	)
	(segment
		(start 67.935094 -240.84153)
		(end 68.139818 -240.841784)
		(width 0.14478)
		(layer "In13.Cu")
		(net "M_B_CPU1_SA_DQ<28>")
	)
	(segment
		(start 69.996558 -242.141248)
		(end 75.92949 -242.141248)
		(width 0.14478)
		(layer "In13.Cu")
		(net "M_B_CPU1_SA_DQ<28>")
	)
	(segment
		(start 67.926204 -240.275364)
		(end 67.749928 -240.45164)
		(width 0.14478)
		(layer "In13.Cu")
		(net "M_B_CPU1_SA_DQ<28>")
	)
	(segment
		(start 65.587118 -237.731808)
		(end 65.586864 -237.936024)
		(width 0.14478)
		(layer "In13.Cu")
		(net "M_B_CPU1_SA_DQ<28>")
	)
	(segment
		(start 57.616344 -232.158286)
		(end 57.777888 -231.996742)
		(width 0.14478)
		(layer "In13.Cu")
		(net "M_B_CPU1_SA_DQ<28>")
	)
	(segment
		(start 66.375534 -239.28197)
		(end 66.580258 -239.282224)
		(width 0.14478)
		(layer "In13.Cu")
		(net "M_B_CPU1_SA_DQ<28>")
	)
	(segment
		(start 67.536314 -239.885728)
		(end 67.741038 -239.885728)
		(width 0.14478)
		(layer "In13.Cu")
		(net "M_B_CPU1_SA_DQ<28>")
	)
	(segment
		(start 68.316094 -240.665508)
		(end 68.520818 -240.665508)
		(width 0.14478)
		(layer "In13.Cu")
		(net "M_B_CPU1_SA_DQ<28>")
	)
	(segment
		(start 66.181478 -238.326168)
		(end 66.366898 -238.511588)
		(width 0.14478)
		(layer "In13.Cu")
		(net "M_B_CPU1_SA_DQ<28>")
	)
	(segment
		(start 61.694822 -234.13847)
		(end 61.922914 -234.13847)
		(width 0.14478)
		(layer "In13.Cu")
		(net "M_B_CPU1_SA_DQ<28>")
	)
	(segment
		(start 68.139818 -240.841784)
		(end 68.316094 -240.665508)
		(width 0.14478)
		(layer "In13.Cu")
		(net "M_B_CPU1_SA_DQ<28>")
	)
	(segment
		(start 65.044066 -237.259622)
		(end 65.114678 -237.259368)
		(width 0.14478)
		(layer "In13.Cu")
		(net "M_B_CPU1_SA_DQ<28>")
	)
	(segment
		(start 83.394042 -243.186966)
		(end 83.402424 -243.191792)
		(width 0.0889)
		(layer "In13.Cu")
		(net "M_B_CPU1_SA_DQ<28>")
	)
	(segment
		(start 66.366644 -238.715804)
		(end 66.190368 -238.89208)
		(width 0.14478)
		(layer "In13.Cu")
		(net "M_B_CPU1_SA_DQ<28>")
	)
	(segment
		(start 67.146424 -239.495584)
		(end 66.970148 -239.67186)
		(width 0.14478)
		(layer "In13.Cu")
		(net "M_B_CPU1_SA_DQ<28>")
	)
	(segment
		(start 82.453988 -243.186966)
		(end 82.46237 -243.191792)
		(width 0.0889)
		(layer "In13.Cu")
		(net "M_B_CPU1_SA_DQ<28>")
	)
	(segment
		(start 58.329322 -231.931464)
		(end 58.329322 -231.996742)
		(width 0.14478)
		(layer "In13.Cu")
		(net "M_B_CPU1_SA_DQ<28>")
	)
	(segment
		(start 66.970148 -239.876584)
		(end 67.155314 -240.06175)
		(width 0.14478)
		(layer "In13.Cu")
		(net "M_B_CPU1_SA_DQ<28>")
	)
	(segment
		(start 63.014606 -235.159296)
		(end 63.014606 -235.458254)
		(width 0.14478)
		(layer "In13.Cu")
		(net "M_B_CPU1_SA_DQ<28>")
	)
	(segment
		(start 55.175912 -231.923336)
		(end 55.33898 -231.760268)
		(width 0.14478)
		(layer "In13.Cu")
		(net "M_B_CPU1_SA_DQ<28>")
	)
	(segment
		(start 66.961258 -239.105948)
		(end 67.146678 -239.291368)
		(width 0.14478)
		(layer "In13.Cu")
		(net "M_B_CPU1_SA_DQ<28>")
	)
	(segment
		(start 53.94833 -231.760268)
		(end 54.45633 -231.760268)
		(width 0.14478)
		(layer "In13.Cu")
		(net "M_B_CPU1_SA_DQ<28>")
	)
	(segment
		(start 87.154004 -243.186966)
		(end 87.162386 -243.191792)
		(width 0.0889)
		(layer "In13.Cu")
		(net "M_B_CPU1_SA_DQ<28>")
	)
	(segment
		(start 67.749928 -240.45164)
		(end 67.749928 -240.656364)
		(width 0.14478)
		(layer "In13.Cu")
		(net "M_B_CPU1_SA_DQ<28>")
	)
	(segment
		(start 54.782466 -232.154984)
		(end 55.012844 -232.154984)
		(width 0.14478)
		(layer "In13.Cu")
		(net "M_B_CPU1_SA_DQ<28>")
	)
	(segment
		(start 51.884072 -231.326436)
		(end 52.290472 -230.920036)
		(width 0.14478)
		(layer "In13.Cu")
		(net "M_B_CPU1_SA_DQ<28>")
	)
	(segment
		(start 62.234318 -234.677966)
		(end 62.47511 -234.918758)
		(width 0.14478)
		(layer "In13.Cu")
		(net "M_B_CPU1_SA_DQ<28>")
	)
	(segment
		(start 57.387998 -232.158286)
		(end 57.616344 -232.158286)
		(width 0.14478)
		(layer "In13.Cu")
		(net "M_B_CPU1_SA_DQ<28>")
	)
	(segment
		(start 76.273152 -242.141248)
		(end 76.61275 -242.480846)
		(width 0.0889)
		(layer "In13.Cu")
		(net "M_B_CPU1_SA_DQ<28>")
	)
	(segment
		(start 66.580258 -239.282224)
		(end 66.756534 -239.105948)
		(width 0.14478)
		(layer "In13.Cu")
		(net "M_B_CPU1_SA_DQ<28>")
	)
	(segment
		(start 55.732426 -231.923336)
		(end 55.732426 -231.991916)
		(width 0.14478)
		(layer "In13.Cu")
		(net "M_B_CPU1_SA_DQ<28>")
	)
	(segment
		(start 75.92949 -242.141248)
		(end 76.273152 -242.141248)
		(width 0.0889)
		(layer "In13.Cu")
		(net "M_B_CPU1_SA_DQ<28>")
	)
	(segment
		(start 65.595754 -238.50219)
		(end 65.800478 -238.502444)
		(width 0.14478)
		(layer "In13.Cu")
		(net "M_B_CPU1_SA_DQ<28>")
	)
	(segment
		(start 63.794894 -236.238542)
		(end 64.035686 -236.479334)
		(width 0.14478)
		(layer "In13.Cu")
		(net "M_B_CPU1_SA_DQ<28>")
	)
	(segment
		(start 63.48349 -235.699046)
		(end 63.554102 -235.698792)
		(width 0.14478)
		(layer "In13.Cu")
		(net "M_B_CPU1_SA_DQ<28>")
	)
	(segment
		(start 87.495126 -243.129816)
		(end 87.340948 -242.864386)
		(width 0.0889)
		(layer "In13.Cu")
		(net "M_B_CPU1_SA_DQ<28>")
	)
	(segment
		(start 65.586864 -237.936024)
		(end 65.410588 -238.1123)
		(width 0.14478)
		(layer "In13.Cu")
		(net "M_B_CPU1_SA_DQ<28>")
	)
	(segment
		(start 65.114678 -237.259368)
		(end 65.587118 -237.731808)
		(width 0.14478)
		(layer "In13.Cu")
		(net "M_B_CPU1_SA_DQ<28>")
	)
	(segment
		(start 53.108098 -230.920036)
		(end 53.94833 -231.760268)
		(width 0.14478)
		(layer "In13.Cu")
		(net "M_B_CPU1_SA_DQ<28>")
	)
	(segment
		(start 61.45403 -233.897678)
		(end 61.694822 -234.13847)
		(width 0.14478)
		(layer "In13.Cu")
		(net "M_B_CPU1_SA_DQ<28>")
	)
	(segment
		(start 56.28894 -231.923336)
		(end 56.442356 -231.76992)
		(width 0.14478)
		(layer "In13.Cu")
		(net "M_B_CPU1_SA_DQ<28>")
	)
	(segment
		(start 64.815974 -237.259622)
		(end 65.044066 -237.259622)
		(width 0.14478)
		(layer "In13.Cu")
		(net "M_B_CPU1_SA_DQ<28>")
	)
	(segment
		(start 79.634842 -243.186712)
		(end 79.654908 -243.198142)
		(width 0.0889)
		(layer "In13.Cu")
		(net "M_B_CPU1_SA_DQ<28>")
	)
	(segment
		(start 56.125872 -232.154984)
		(end 56.28894 -231.991916)
		(width 0.14478)
		(layer "In13.Cu")
		(net "M_B_CPU1_SA_DQ<28>")
	)
	(segment
		(start 57.06491 -231.76992)
		(end 57.226454 -231.931464)
		(width 0.14478)
		(layer "In13.Cu")
		(net "M_B_CPU1_SA_DQ<28>")
	)
	(segment
		(start 79.051658 -243.197888)
		(end 79.070454 -243.186966)
		(width 0.0889)
		(layer "In13.Cu")
		(net "M_B_CPU1_SA_DQ<28>")
	)
	(segment
		(start 66.190368 -239.096804)
		(end 66.375534 -239.28197)
		(width 0.14478)
		(layer "In13.Cu")
		(net "M_B_CPU1_SA_DQ<28>")
	)
	(segment
		(start 58.719212 -232.158286)
		(end 58.880756 -231.996742)
		(width 0.14478)
		(layer "In13.Cu")
		(net "M_B_CPU1_SA_DQ<28>")
	)
	(segment
		(start 62.234318 -234.379008)
		(end 62.234318 -234.677966)
		(width 0.14478)
		(layer "In13.Cu")
		(net "M_B_CPU1_SA_DQ<28>")
	)
	(segment
		(start 77.897228 -243.110258)
		(end 78.41107 -243.110258)
		(width 0.0889)
		(layer "In13.Cu")
		(net "M_B_CPU1_SA_DQ<28>")
	)
	(segment
		(start 66.756534 -239.105948)
		(end 66.961258 -239.105948)
		(width 0.14478)
		(layer "In13.Cu")
		(net "M_B_CPU1_SA_DQ<28>")
	)
	(segment
		(start 86.57971 -243.191792)
		(end 86.588092 -243.186966)
		(width 0.0889)
		(layer "In13.Cu")
		(net "M_B_CPU1_SA_DQ<28>")
	)
	(segment
		(start 57.939432 -231.76992)
		(end 58.167778 -231.76992)
		(width 0.14478)
		(layer "In13.Cu")
		(net "M_B_CPU1_SA_DQ<28>")
	)
	(segment
		(start 63.255398 -235.699046)
		(end 63.48349 -235.699046)
		(width 0.14478)
		(layer "In13.Cu")
		(net "M_B_CPU1_SA_DQ<28>")
	)
	(segment
		(start 68.520818 -240.665508)
		(end 69.996558 -242.141248)
		(width 0.14478)
		(layer "In13.Cu")
		(net "M_B_CPU1_SA_DQ<28>")
	)
	(segment
		(start 65.410588 -238.317024)
		(end 65.595754 -238.50219)
		(width 0.14478)
		(layer "In13.Cu")
		(net "M_B_CPU1_SA_DQ<28>")
	)
	(segment
		(start 58.490866 -232.158286)
		(end 58.719212 -232.158286)
		(width 0.14478)
		(layer "In13.Cu")
		(net "M_B_CPU1_SA_DQ<28>")
	)
	(segment
		(start 51.884072 -231.335326)
		(end 51.884072 -231.326436)
		(width 0.14478)
		(layer "In13.Cu")
		(net "M_B_CPU1_SA_DQ<28>")
	)
	(segment
		(start 54.619398 -231.991916)
		(end 54.782466 -232.154984)
		(width 0.14478)
		(layer "In13.Cu")
		(net "M_B_CPU1_SA_DQ<28>")
	)
	(segment
		(start 62.47511 -234.918758)
		(end 62.703202 -234.918758)
		(width 0.14478)
		(layer "In13.Cu")
		(net "M_B_CPU1_SA_DQ<28>")
	)
	(segment
		(start 55.732426 -231.991916)
		(end 55.895494 -232.154984)
		(width 0.14478)
		(layer "In13.Cu")
		(net "M_B_CPU1_SA_DQ<28>")
	)
	(segment
		(start 55.895494 -232.154984)
		(end 56.125872 -232.154984)
		(width 0.14478)
		(layer "In13.Cu")
		(net "M_B_CPU1_SA_DQ<28>")
	)
	(segment
		(start 56.442356 -231.76992)
		(end 57.06491 -231.76992)
		(width 0.14478)
		(layer "In13.Cu")
		(net "M_B_CPU1_SA_DQ<28>")
	)
	(segment
		(start 81.879694 -243.191792)
		(end 81.888076 -243.186966)
		(width 0.0889)
		(layer "In13.Cu")
		(net "M_B_CPU1_SA_DQ<28>")
	)
	(segment
		(start 54.619398 -231.923336)
		(end 54.619398 -231.991916)
		(width 0.14478)
		(layer "In13.Cu")
		(net "M_B_CPU1_SA_DQ<28>")
	)
	(segment
		(start 67.741038 -239.885728)
		(end 67.926458 -240.071148)
		(width 0.14478)
		(layer "In13.Cu")
		(net "M_B_CPU1_SA_DQ<28>")
	)
	(segment
		(start 64.33439 -236.47908)
		(end 64.575182 -236.719872)
		(width 0.14478)
		(layer "In13.Cu")
		(net "M_B_CPU1_SA_DQ<28>")
	)
	(segment
		(start 54.45633 -231.760268)
		(end 54.619398 -231.923336)
		(width 0.14478)
		(layer "In13.Cu")
		(net "M_B_CPU1_SA_DQ<28>")
	)
	(segment
		(start 55.012844 -232.154984)
		(end 55.175912 -231.991916)
		(width 0.14478)
		(layer "In13.Cu")
		(net "M_B_CPU1_SA_DQ<28>")
	)
	(segment
		(start 64.575182 -236.719872)
		(end 64.575182 -237.01883)
		(width 0.14478)
		(layer "In13.Cu")
		(net "M_B_CPU1_SA_DQ<28>")
	)
	(segment
		(start 65.410588 -238.1123)
		(end 65.410588 -238.317024)
		(width 0.14478)
		(layer "In13.Cu")
		(net "M_B_CPU1_SA_DQ<28>")
	)
	(segment
		(start 58.329322 -231.996742)
		(end 58.490866 -232.158286)
		(width 0.14478)
		(layer "In13.Cu")
		(net "M_B_CPU1_SA_DQ<28>")
	)
	(segment
		(start 65.976754 -238.326168)
		(end 66.181478 -238.326168)
		(width 0.14478)
		(layer "In13.Cu")
		(net "M_B_CPU1_SA_DQ<28>")
	)
	(segment
		(start 62.773814 -234.918504)
		(end 63.014606 -235.159296)
		(width 0.14478)
		(layer "In13.Cu")
		(net "M_B_CPU1_SA_DQ<28>")
	)
	(segment
		(start 61.922914 -234.13847)
		(end 61.993526 -234.138216)
		(width 0.14478)
		(layer "In13.Cu")
		(net "M_B_CPU1_SA_DQ<28>")
	)
	(segment
		(start 56.28894 -231.991916)
		(end 56.28894 -231.923336)
		(width 0.14478)
		(layer "In13.Cu")
		(net "M_B_CPU1_SA_DQ<28>")
	)
	(segment
		(start 57.226454 -231.996742)
		(end 57.387998 -232.158286)
		(width 0.14478)
		(layer "In13.Cu")
		(net "M_B_CPU1_SA_DQ<28>")
	)
	(segment
		(start 63.554102 -235.698792)
		(end 63.794894 -235.939584)
		(width 0.14478)
		(layer "In13.Cu")
		(net "M_B_CPU1_SA_DQ<28>")
	)
	(segment
		(start 58.880756 -231.931464)
		(end 59.0423 -231.76992)
		(width 0.14478)
		(layer "In13.Cu")
		(net "M_B_CPU1_SA_DQ<28>")
	)
	(segment
		(start 63.794894 -235.939584)
		(end 63.794894 -236.238542)
		(width 0.14478)
		(layer "In13.Cu")
		(net "M_B_CPU1_SA_DQ<28>")
	)
	(segment
		(start 67.926458 -240.071148)
		(end 67.926204 -240.275364)
		(width 0.14478)
		(layer "In13.Cu")
		(net "M_B_CPU1_SA_DQ<28>")
	)
	(segment
		(start 60.673742 -233.11739)
		(end 60.914534 -233.358182)
		(width 0.14478)
		(layer "In13.Cu")
		(net "M_B_CPU1_SA_DQ<28>")
	)
	(segment
		(start 67.146678 -239.291368)
		(end 67.146424 -239.495584)
		(width 0.14478)
		(layer "In13.Cu")
		(net "M_B_CPU1_SA_DQ<28>")
	)
	(segment
		(start 64.575182 -237.01883)
		(end 64.815974 -237.259622)
		(width 0.14478)
		(layer "In13.Cu")
		(net "M_B_CPU1_SA_DQ<28>")
	)
	(segment
		(start 66.970148 -239.67186)
		(end 66.970148 -239.876584)
		(width 0.14478)
		(layer "In13.Cu")
		(net "M_B_CPU1_SA_DQ<28>")
	)
	(arc
		(start 84.334096 -243.186966)
		(mid 84.52104 -243.237221)
		(end 84.707984 -243.186966)
		(width 0.0889)
		(layer "In13.Cu")
		(net "M_B_CPU1_SA_DQ<28>")
	)
	(arc
		(start 82.82813 -243.186966)
		(mid 83.111086 -243.110789)
		(end 83.394042 -243.186966)
		(width 0.0889)
		(layer "In13.Cu")
		(net "M_B_CPU1_SA_DQ<28>")
	)
	(arc
		(start 78.695296 -243.186966)
		(mid 78.872087 -243.237685)
		(end 79.051658 -243.197888)
		(width 0.0889)
		(layer "In13.Cu")
		(net "M_B_CPU1_SA_DQ<28>")
	)
	(arc
		(start 81.513934 -243.186966)
		(mid 81.696185 -243.237316)
		(end 81.879694 -243.191792)
		(width 0.0889)
		(layer "In13.Cu")
		(net "M_B_CPU1_SA_DQ<28>")
	)
	(arc
		(start 80.948022 -243.186966)
		(mid 81.230978 -243.110789)
		(end 81.513934 -243.186966)
		(width 0.0889)
		(layer "In13.Cu")
		(net "M_B_CPU1_SA_DQ<28>")
	)
	(arc
		(start 81.888076 -243.186966)
		(mid 82.171032 -243.110789)
		(end 82.453988 -243.186966)
		(width 0.0889)
		(layer "In13.Cu")
		(net "M_B_CPU1_SA_DQ<28>")
	)
	(arc
		(start 86.21395 -243.186966)
		(mid 86.396201 -243.237316)
		(end 86.57971 -243.191792)
		(width 0.0889)
		(layer "In13.Cu")
		(net "M_B_CPU1_SA_DQ<28>")
	)
	(arc
		(start 85.648038 -243.186966)
		(mid 85.930994 -243.110789)
		(end 86.21395 -243.186966)
		(width 0.0889)
		(layer "In13.Cu")
		(net "M_B_CPU1_SA_DQ<28>")
	)
	(arc
		(start 80.008222 -243.186966)
		(mid 80.291178 -243.110789)
		(end 80.574134 -243.186966)
		(width 0.0889)
		(layer "In13.Cu")
		(net "M_B_CPU1_SA_DQ<28>")
	)
	(arc
		(start 83.402424 -243.191792)
		(mid 83.585932 -243.237286)
		(end 83.768184 -243.186966)
		(width 0.0889)
		(layer "In13.Cu")
		(net "M_B_CPU1_SA_DQ<28>")
	)
	(arc
		(start 82.46237 -243.191792)
		(mid 82.645878 -243.237286)
		(end 82.82813 -243.186966)
		(width 0.0889)
		(layer "In13.Cu")
		(net "M_B_CPU1_SA_DQ<28>")
	)
	(arc
		(start 84.707984 -243.186966)
		(mid 84.99094 -243.110789)
		(end 85.273896 -243.186966)
		(width 0.0889)
		(layer "In13.Cu")
		(net "M_B_CPU1_SA_DQ<28>")
	)
	(arc
		(start 85.273896 -243.186966)
		(mid 85.456147 -243.237316)
		(end 85.639656 -243.191792)
		(width 0.0889)
		(layer "In13.Cu")
		(net "M_B_CPU1_SA_DQ<28>")
	)
	(arc
		(start 79.070454 -243.186966)
		(mid 79.340223 -243.110943)
		(end 79.613252 -243.174266)
		(width 0.0889)
		(layer "In13.Cu")
		(net "M_B_CPU1_SA_DQ<28>")
	)
	(arc
		(start 86.588092 -243.186966)
		(mid 86.871048 -243.110789)
		(end 87.154004 -243.186966)
		(width 0.0889)
		(layer "In13.Cu")
		(net "M_B_CPU1_SA_DQ<28>")
	)
	(arc
		(start 80.574134 -243.186966)
		(mid 80.761078 -243.237221)
		(end 80.948022 -243.186966)
		(width 0.0889)
		(layer "In13.Cu")
		(net "M_B_CPU1_SA_DQ<28>")
	)
	(arc
		(start 79.654908 -243.198142)
		(mid 79.832986 -243.237126)
		(end 80.008222 -243.186966)
		(width 0.0889)
		(layer "In13.Cu")
		(net "M_B_CPU1_SA_DQ<28>")
	)
	(arc
		(start 78.41107 -243.110258)
		(mid 78.558279 -243.129735)
		(end 78.695296 -243.186966)
		(width 0.0889)
		(layer "In13.Cu")
		(net "M_B_CPU1_SA_DQ<28>")
	)
	(arc
		(start 87.162386 -243.191792)
		(mid 87.315256 -243.236433)
		(end 87.472774 -243.213128)
		(width 0.0889)
		(layer "In13.Cu")
		(net "M_B_CPU1_SA_DQ<28>")
	)
	(arc
		(start 83.768184 -243.186966)
		(mid 84.05114 -243.110789)
		(end 84.334096 -243.186966)
		(width 0.0889)
		(layer "In13.Cu")
		(net "M_B_CPU1_SA_DQ<28>")
	)
	(segment
		(start 89.687908 -241.510312)
		(end 89.221056 -241.244374)
		(width 0.10668)
		(layer "F.Cu")
		(net "M_B_CPU1_SA_DQ<27>")
	)
	(segment
		(start 75.946 -239.782858)
		(end 70.893432 -239.782858)
		(width 0.14478)
		(layer "In13.Cu")
		(net "M_B_CPU1_SA_DQ<27>")
	)
	(segment
		(start 66.331846 -235.221272)
		(end 66.331846 -233.972608)
		(width 0.14478)
		(layer "In13.Cu")
		(net "M_B_CPU1_SA_DQ<27>")
	)
	(segment
		(start 76.086462 -239.782858)
		(end 75.946 -239.782858)
		(width 0.0889)
		(layer "In13.Cu")
		(net "M_B_CPU1_SA_DQ<27>")
	)
	(segment
		(start 83.402424 -240.916968)
		(end 83.394042 -240.921794)
		(width 0.0889)
		(layer "In13.Cu")
		(net "M_B_CPU1_SA_DQ<27>")
	)
	(segment
		(start 88.10244 -240.916968)
		(end 88.094058 -240.921794)
		(width 0.0889)
		(layer "In13.Cu")
		(net "M_B_CPU1_SA_DQ<27>")
	)
	(segment
		(start 86.588092 -240.921794)
		(end 86.57971 -240.916968)
		(width 0.0889)
		(layer "In13.Cu")
		(net "M_B_CPU1_SA_DQ<27>")
	)
	(segment
		(start 54.732428 -228.360478)
		(end 51.474116 -227.712524)
		(width 0.14478)
		(layer "In13.Cu")
		(net "M_B_CPU1_SA_DQ<27>")
	)
	(segment
		(start 50.962814 -227.500688)
		(end 49.930304 -227.500688)
		(width 0.14478)
		(layer "In13.Cu")
		(net "M_B_CPU1_SA_DQ<27>")
	)
	(segment
		(start 79.06766 -240.921794)
		(end 79.059278 -240.916968)
		(width 0.0889)
		(layer "In13.Cu")
		(net "M_B_CPU1_SA_DQ<27>")
	)
	(segment
		(start 81.888076 -240.921794)
		(end 81.879694 -240.916968)
		(width 0.0889)
		(layer "In13.Cu")
		(net "M_B_CPU1_SA_DQ<27>")
	)
	(segment
		(start 80.008222 -240.921794)
		(end 79.99984 -240.916968)
		(width 0.0889)
		(layer "In13.Cu")
		(net "M_B_CPU1_SA_DQ<27>")
	)
	(segment
		(start 66.331846 -233.972608)
		(end 61.09716 -228.737922)
		(width 0.14478)
		(layer "In13.Cu")
		(net "M_B_CPU1_SA_DQ<27>")
	)
	(segment
		(start 76.71181 -240.408206)
		(end 76.086462 -239.782858)
		(width 0.0889)
		(layer "In13.Cu")
		(net "M_B_CPU1_SA_DQ<27>")
	)
	(segment
		(start 61.09716 -228.737922)
		(end 60.186062 -228.360478)
		(width 0.14478)
		(layer "In13.Cu")
		(net "M_B_CPU1_SA_DQ<27>")
	)
	(segment
		(start 89.221056 -241.244374)
		(end 89.067132 -240.978944)
		(width 0.0889)
		(layer "In13.Cu")
		(net "M_B_CPU1_SA_DQ<27>")
	)
	(segment
		(start 77.824838 -240.997994)
		(end 77.23505 -240.408206)
		(width 0.0889)
		(layer "In13.Cu")
		(net "M_B_CPU1_SA_DQ<27>")
	)
	(segment
		(start 49.930304 -227.500688)
		(end 49.894744 -227.51542)
		(width 0.14478)
		(layer "In13.Cu")
		(net "M_B_CPU1_SA_DQ<27>")
	)
	(segment
		(start 51.474116 -227.712524)
		(end 50.962814 -227.500688)
		(width 0.14478)
		(layer "In13.Cu")
		(net "M_B_CPU1_SA_DQ<27>")
	)
	(segment
		(start 77.23505 -240.408206)
		(end 76.71181 -240.408206)
		(width 0.0889)
		(layer "In13.Cu")
		(net "M_B_CPU1_SA_DQ<27>")
	)
	(segment
		(start 60.186062 -228.360478)
		(end 54.732428 -228.360478)
		(width 0.14478)
		(layer "In13.Cu")
		(net "M_B_CPU1_SA_DQ<27>")
	)
	(segment
		(start 87.162386 -240.916968)
		(end 87.154004 -240.921794)
		(width 0.0889)
		(layer "In13.Cu")
		(net "M_B_CPU1_SA_DQ<27>")
	)
	(segment
		(start 49.894744 -227.51542)
		(end 47.784004 -227.935282)
		(width 0.14478)
		(layer "In13.Cu")
		(net "M_B_CPU1_SA_DQ<27>")
	)
	(segment
		(start 70.893432 -239.782858)
		(end 66.331846 -235.221272)
		(width 0.14478)
		(layer "In13.Cu")
		(net "M_B_CPU1_SA_DQ<27>")
	)
	(segment
		(start 82.46237 -240.916968)
		(end 82.453988 -240.921794)
		(width 0.0889)
		(layer "In13.Cu")
		(net "M_B_CPU1_SA_DQ<27>")
	)
	(segment
		(start 89.067132 -240.978944)
		(end 88.97112 -240.953544)
		(width 0.0889)
		(layer "In13.Cu")
		(net "M_B_CPU1_SA_DQ<27>")
	)
	(segment
		(start 78.41107 -240.997994)
		(end 77.824838 -240.997994)
		(width 0.0889)
		(layer "In13.Cu")
		(net "M_B_CPU1_SA_DQ<27>")
	)
	(segment
		(start 79.082392 -240.93043)
		(end 79.06766 -240.921794)
		(width 0.0889)
		(layer "In13.Cu")
		(net "M_B_CPU1_SA_DQ<27>")
	)
	(segment
		(start 85.648038 -240.921794)
		(end 85.639656 -240.916968)
		(width 0.0889)
		(layer "In13.Cu")
		(net "M_B_CPU1_SA_DQ<27>")
	)
	(arc
		(start 80.948022 -240.921794)
		(mid 80.761078 -240.871539)
		(end 80.574134 -240.921794)
		(width 0.0889)
		(layer "In13.Cu")
		(net "M_B_CPU1_SA_DQ<27>")
	)
	(arc
		(start 87.528146 -240.921794)
		(mid 87.345895 -240.871444)
		(end 87.162386 -240.916968)
		(width 0.0889)
		(layer "In13.Cu")
		(net "M_B_CPU1_SA_DQ<27>")
	)
	(arc
		(start 87.154004 -240.921794)
		(mid 86.871048 -240.997971)
		(end 86.588092 -240.921794)
		(width 0.0889)
		(layer "In13.Cu")
		(net "M_B_CPU1_SA_DQ<27>")
	)
	(arc
		(start 82.453988 -240.921794)
		(mid 82.171032 -240.997971)
		(end 81.888076 -240.921794)
		(width 0.0889)
		(layer "In13.Cu")
		(net "M_B_CPU1_SA_DQ<27>")
	)
	(arc
		(start 88.4682 -240.921794)
		(mid 88.285949 -240.871444)
		(end 88.10244 -240.916968)
		(width 0.0889)
		(layer "In13.Cu")
		(net "M_B_CPU1_SA_DQ<27>")
	)
	(arc
		(start 88.094058 -240.921794)
		(mid 87.811102 -240.997971)
		(end 87.528146 -240.921794)
		(width 0.0889)
		(layer "In13.Cu")
		(net "M_B_CPU1_SA_DQ<27>")
	)
	(arc
		(start 85.639656 -240.916968)
		(mid 85.456148 -240.871474)
		(end 85.273896 -240.921794)
		(width 0.0889)
		(layer "In13.Cu")
		(net "M_B_CPU1_SA_DQ<27>")
	)
	(arc
		(start 79.99984 -240.916968)
		(mid 79.816078 -240.871352)
		(end 79.633572 -240.921794)
		(width 0.0889)
		(layer "In13.Cu")
		(net "M_B_CPU1_SA_DQ<27>")
	)
	(arc
		(start 81.879694 -240.916968)
		(mid 81.696186 -240.871474)
		(end 81.513934 -240.921794)
		(width 0.0889)
		(layer "In13.Cu")
		(net "M_B_CPU1_SA_DQ<27>")
	)
	(arc
		(start 86.57971 -240.916968)
		(mid 86.396202 -240.871474)
		(end 86.21395 -240.921794)
		(width 0.0889)
		(layer "In13.Cu")
		(net "M_B_CPU1_SA_DQ<27>")
	)
	(arc
		(start 82.82813 -240.921794)
		(mid 82.645879 -240.871444)
		(end 82.46237 -240.916968)
		(width 0.0889)
		(layer "In13.Cu")
		(net "M_B_CPU1_SA_DQ<27>")
	)
	(arc
		(start 78.694026 -240.921794)
		(mid 78.55759 -240.978619)
		(end 78.41107 -240.997994)
		(width 0.0889)
		(layer "In13.Cu")
		(net "M_B_CPU1_SA_DQ<27>")
	)
	(arc
		(start 83.394042 -240.921794)
		(mid 83.111086 -240.997971)
		(end 82.82813 -240.921794)
		(width 0.0889)
		(layer "In13.Cu")
		(net "M_B_CPU1_SA_DQ<27>")
	)
	(arc
		(start 81.513934 -240.921794)
		(mid 81.230978 -240.997971)
		(end 80.948022 -240.921794)
		(width 0.0889)
		(layer "In13.Cu")
		(net "M_B_CPU1_SA_DQ<27>")
	)
	(arc
		(start 88.97112 -240.953544)
		(mid 88.715912 -240.997021)
		(end 88.4682 -240.921794)
		(width 0.0889)
		(layer "In13.Cu")
		(net "M_B_CPU1_SA_DQ<27>")
	)
	(arc
		(start 84.707984 -240.921794)
		(mid 84.52104 -240.871539)
		(end 84.334096 -240.921794)
		(width 0.0889)
		(layer "In13.Cu")
		(net "M_B_CPU1_SA_DQ<27>")
	)
	(arc
		(start 80.574134 -240.921794)
		(mid 80.291178 -240.997971)
		(end 80.008222 -240.921794)
		(width 0.0889)
		(layer "In13.Cu")
		(net "M_B_CPU1_SA_DQ<27>")
	)
	(arc
		(start 79.059278 -240.916968)
		(mid 78.876024 -240.871595)
		(end 78.694026 -240.921794)
		(width 0.0889)
		(layer "In13.Cu")
		(net "M_B_CPU1_SA_DQ<27>")
	)
	(arc
		(start 79.633572 -240.921794)
		(mid 79.35912 -240.99803)
		(end 79.082392 -240.93043)
		(width 0.0889)
		(layer "In13.Cu")
		(net "M_B_CPU1_SA_DQ<27>")
	)
	(arc
		(start 85.273896 -240.921794)
		(mid 84.99094 -240.997971)
		(end 84.707984 -240.921794)
		(width 0.0889)
		(layer "In13.Cu")
		(net "M_B_CPU1_SA_DQ<27>")
	)
	(arc
		(start 83.768184 -240.921794)
		(mid 83.585933 -240.871444)
		(end 83.402424 -240.916968)
		(width 0.0889)
		(layer "In13.Cu")
		(net "M_B_CPU1_SA_DQ<27>")
	)
	(arc
		(start 84.334096 -240.921794)
		(mid 84.05114 -240.997971)
		(end 83.768184 -240.921794)
		(width 0.0889)
		(layer "In13.Cu")
		(net "M_B_CPU1_SA_DQ<27>")
	)
	(arc
		(start 86.21395 -240.921794)
		(mid 85.930994 -240.997971)
		(end 85.648038 -240.921794)
		(width 0.0889)
		(layer "In13.Cu")
		(net "M_B_CPU1_SA_DQ<27>")
	)
	(segment
		(start 88.277954 -240.700306)
		(end 87.811102 -240.434368)
		(width 0.10668)
		(layer "F.Cu")
		(net "M_B_CPU1_SA_DQ<26>")
	)
	(segment
		(start 76.41209 -239.051846)
		(end 76.233782 -238.873538)
		(width 0.0889)
		(layer "In13.Cu")
		(net "M_B_CPU1_SA_DQ<26>")
	)
	(segment
		(start 84.2391 -240.112804)
		(end 84.230718 -240.107978)
		(width 0.0889)
		(layer "In13.Cu")
		(net "M_B_CPU1_SA_DQ<26>")
	)
	(segment
		(start 67.271646 -234.88904)
		(end 67.271646 -233.640376)
		(width 0.14478)
		(layer "In13.Cu")
		(net "M_B_CPU1_SA_DQ<26>")
	)
	(segment
		(start 80.479138 -240.112804)
		(end 80.470756 -240.107978)
		(width 0.0889)
		(layer "In13.Cu")
		(net "M_B_CPU1_SA_DQ<26>")
	)
	(segment
		(start 75.92568 -238.873538)
		(end 71.256144 -238.873538)
		(width 0.14478)
		(layer "In13.Cu")
		(net "M_B_CPU1_SA_DQ<26>")
	)
	(segment
		(start 83.299046 -240.112804)
		(end 83.290664 -240.107978)
		(width 0.0889)
		(layer "In13.Cu")
		(net "M_B_CPU1_SA_DQ<26>")
	)
	(segment
		(start 78.41107 -240.061242)
		(end 78.122526 -240.061242)
		(width 0.0889)
		(layer "In13.Cu")
		(net "M_B_CPU1_SA_DQ<26>")
	)
	(segment
		(start 77.11313 -239.051846)
		(end 76.41209 -239.051846)
		(width 0.0889)
		(layer "In13.Cu")
		(net "M_B_CPU1_SA_DQ<26>")
	)
	(segment
		(start 49.797462 -226.23526)
		(end 47.784004 -226.23526)
		(width 0.14478)
		(layer "In13.Cu")
		(net "M_B_CPU1_SA_DQ<26>")
	)
	(segment
		(start 56.375554 -226.660456)
		(end 54.106572 -226.660456)
		(width 0.14478)
		(layer "In13.Cu")
		(net "M_B_CPU1_SA_DQ<26>")
	)
	(segment
		(start 50.222404 -225.810318)
		(end 49.797462 -226.23526)
		(width 0.14478)
		(layer "In13.Cu")
		(net "M_B_CPU1_SA_DQ<26>")
	)
	(segment
		(start 84.813394 -240.107978)
		(end 84.805012 -240.112804)
		(width 0.0889)
		(layer "In13.Cu")
		(net "M_B_CPU1_SA_DQ<26>")
	)
	(segment
		(start 67.271646 -233.640376)
		(end 61.595508 -227.964238)
		(width 0.14478)
		(layer "In13.Cu")
		(net "M_B_CPU1_SA_DQ<26>")
	)
	(segment
		(start 85.753448 -240.107978)
		(end 85.745066 -240.112804)
		(width 0.0889)
		(layer "In13.Cu")
		(net "M_B_CPU1_SA_DQ<26>")
	)
	(segment
		(start 76.233782 -238.873538)
		(end 75.92568 -238.873538)
		(width 0.0889)
		(layer "In13.Cu")
		(net "M_B_CPU1_SA_DQ<26>")
	)
	(segment
		(start 53.256434 -225.810318)
		(end 50.222404 -225.810318)
		(width 0.14478)
		(layer "In13.Cu")
		(net "M_B_CPU1_SA_DQ<26>")
	)
	(segment
		(start 87.656924 -240.168938)
		(end 87.558626 -240.1443)
		(width 0.0889)
		(layer "In13.Cu")
		(net "M_B_CPU1_SA_DQ<26>")
	)
	(segment
		(start 56.665368 -226.95027)
		(end 56.375554 -226.660456)
		(width 0.14478)
		(layer "In13.Cu")
		(net "M_B_CPU1_SA_DQ<26>")
	)
	(segment
		(start 54.106572 -226.660456)
		(end 53.256434 -225.810318)
		(width 0.14478)
		(layer "In13.Cu")
		(net "M_B_CPU1_SA_DQ<26>")
	)
	(segment
		(start 61.595508 -227.964238)
		(end 59.14771 -226.95027)
		(width 0.14478)
		(layer "In13.Cu")
		(net "M_B_CPU1_SA_DQ<26>")
	)
	(segment
		(start 87.811102 -240.434368)
		(end 87.656924 -240.168938)
		(width 0.0889)
		(layer "In13.Cu")
		(net "M_B_CPU1_SA_DQ<26>")
	)
	(segment
		(start 59.14771 -226.95027)
		(end 56.665368 -226.95027)
		(width 0.14478)
		(layer "In13.Cu")
		(net "M_B_CPU1_SA_DQ<26>")
	)
	(segment
		(start 71.256144 -238.873538)
		(end 67.271646 -234.88904)
		(width 0.14478)
		(layer "In13.Cu")
		(net "M_B_CPU1_SA_DQ<26>")
	)
	(segment
		(start 81.053432 -240.107978)
		(end 81.04505 -240.112804)
		(width 0.0889)
		(layer "In13.Cu")
		(net "M_B_CPU1_SA_DQ<26>")
	)
	(segment
		(start 79.172308 -240.106962)
		(end 79.163926 -240.111788)
		(width 0.0889)
		(layer "In13.Cu")
		(net "M_B_CPU1_SA_DQ<26>")
	)
	(segment
		(start 79.539846 -240.112804)
		(end 79.538068 -240.111788)
		(width 0.0889)
		(layer "In13.Cu")
		(net "M_B_CPU1_SA_DQ<26>")
	)
	(segment
		(start 78.122526 -240.061242)
		(end 77.11313 -239.051846)
		(width 0.0889)
		(layer "In13.Cu")
		(net "M_B_CPU1_SA_DQ<26>")
	)
	(arc
		(start 80.470756 -240.107978)
		(mid 80.287248 -240.062484)
		(end 80.104996 -240.112804)
		(width 0.0889)
		(layer "In13.Cu")
		(net "M_B_CPU1_SA_DQ<26>")
	)
	(arc
		(start 86.119208 -240.112804)
		(mid 85.936957 -240.062454)
		(end 85.753448 -240.107978)
		(width 0.0889)
		(layer "In13.Cu")
		(net "M_B_CPU1_SA_DQ<26>")
	)
	(arc
		(start 81.985104 -240.112804)
		(mid 81.702148 -240.188981)
		(end 81.419192 -240.112804)
		(width 0.0889)
		(layer "In13.Cu")
		(net "M_B_CPU1_SA_DQ<26>")
	)
	(arc
		(start 87.558626 -240.1443)
		(mid 87.305116 -240.187448)
		(end 87.059008 -240.112804)
		(width 0.0889)
		(layer "In13.Cu")
		(net "M_B_CPU1_SA_DQ<26>")
	)
	(arc
		(start 84.230718 -240.107978)
		(mid 84.04721 -240.062484)
		(end 83.864958 -240.112804)
		(width 0.0889)
		(layer "In13.Cu")
		(net "M_B_CPU1_SA_DQ<26>")
	)
	(arc
		(start 83.290664 -240.107978)
		(mid 83.107156 -240.062484)
		(end 82.924904 -240.112804)
		(width 0.0889)
		(layer "In13.Cu")
		(net "M_B_CPU1_SA_DQ<26>")
	)
	(arc
		(start 81.419192 -240.112804)
		(mid 81.236941 -240.062454)
		(end 81.053432 -240.107978)
		(width 0.0889)
		(layer "In13.Cu")
		(net "M_B_CPU1_SA_DQ<26>")
	)
	(arc
		(start 80.104996 -240.112804)
		(mid 79.822438 -240.188795)
		(end 79.539846 -240.112804)
		(width 0.0889)
		(layer "In13.Cu")
		(net "M_B_CPU1_SA_DQ<26>")
	)
	(arc
		(start 82.358992 -240.112804)
		(mid 82.172048 -240.062549)
		(end 81.985104 -240.112804)
		(width 0.0889)
		(layer "In13.Cu")
		(net "M_B_CPU1_SA_DQ<26>")
	)
	(arc
		(start 79.538068 -240.111788)
		(mid 79.355817 -240.061438)
		(end 79.172308 -240.106962)
		(width 0.0889)
		(layer "In13.Cu")
		(net "M_B_CPU1_SA_DQ<26>")
	)
	(arc
		(start 84.805012 -240.112804)
		(mid 84.522056 -240.188981)
		(end 84.2391 -240.112804)
		(width 0.0889)
		(layer "In13.Cu")
		(net "M_B_CPU1_SA_DQ<26>")
	)
	(arc
		(start 79.163926 -240.111788)
		(mid 78.88097 -240.187965)
		(end 78.598014 -240.111788)
		(width 0.0889)
		(layer "In13.Cu")
		(net "M_B_CPU1_SA_DQ<26>")
	)
	(arc
		(start 85.179154 -240.112804)
		(mid 84.996903 -240.062454)
		(end 84.813394 -240.107978)
		(width 0.0889)
		(layer "In13.Cu")
		(net "M_B_CPU1_SA_DQ<26>")
	)
	(arc
		(start 81.04505 -240.112804)
		(mid 80.762094 -240.188981)
		(end 80.479138 -240.112804)
		(width 0.0889)
		(layer "In13.Cu")
		(net "M_B_CPU1_SA_DQ<26>")
	)
	(arc
		(start 86.68512 -240.112804)
		(mid 86.402164 -240.188981)
		(end 86.119208 -240.112804)
		(width 0.0889)
		(layer "In13.Cu")
		(net "M_B_CPU1_SA_DQ<26>")
	)
	(arc
		(start 83.864958 -240.112804)
		(mid 83.582002 -240.188981)
		(end 83.299046 -240.112804)
		(width 0.0889)
		(layer "In13.Cu")
		(net "M_B_CPU1_SA_DQ<26>")
	)
	(arc
		(start 85.745066 -240.112804)
		(mid 85.46211 -240.188981)
		(end 85.179154 -240.112804)
		(width 0.0889)
		(layer "In13.Cu")
		(net "M_B_CPU1_SA_DQ<26>")
	)
	(arc
		(start 87.059008 -240.112804)
		(mid 86.872064 -240.062549)
		(end 86.68512 -240.112804)
		(width 0.0889)
		(layer "In13.Cu")
		(net "M_B_CPU1_SA_DQ<26>")
	)
	(arc
		(start 78.598014 -240.111788)
		(mid 78.507881 -240.074168)
		(end 78.41107 -240.061242)
		(width 0.0889)
		(layer "In13.Cu")
		(net "M_B_CPU1_SA_DQ<26>")
	)
	(arc
		(start 82.924904 -240.112804)
		(mid 82.641948 -240.188981)
		(end 82.358992 -240.112804)
		(width 0.0889)
		(layer "In13.Cu")
		(net "M_B_CPU1_SA_DQ<26>")
	)
	(segment
		(start 89.218008 -240.700306)
		(end 88.751156 -240.434368)
		(width 0.10668)
		(layer "F.Cu")
		(net "M_B_CPU1_SA_DQ<25>")
	)
	(segment
		(start 61.351922 -228.356668)
		(end 59.309 -227.51034)
		(width 0.14478)
		(layer "In13.Cu")
		(net "M_B_CPU1_SA_DQ<25>")
	)
	(segment
		(start 84.238084 -240.756948)
		(end 84.229702 -240.761774)
		(width 0.0889)
		(layer "In13.Cu")
		(net "M_B_CPU1_SA_DQ<25>")
	)
	(segment
		(start 80.10398 -240.756948)
		(end 80.093566 -240.750852)
		(width 0.0889)
		(layer "In13.Cu")
		(net "M_B_CPU1_SA_DQ<25>")
	)
	(segment
		(start 53.993542 -227.419408)
		(end 53.788818 -227.419408)
		(width 0.14478)
		(layer "In13.Cu")
		(net "M_B_CPU1_SA_DQ<25>")
	)
	(segment
		(start 55.193438 -227.762562)
		(end 55.048658 -227.907342)
		(width 0.14478)
		(layer "In13.Cu")
		(net "M_B_CPU1_SA_DQ<25>")
	)
	(segment
		(start 77.903832 -240.807494)
		(end 77.48905 -240.392712)
		(width 0.0889)
		(layer "In13.Cu")
		(net "M_B_CPU1_SA_DQ<25>")
	)
	(segment
		(start 56.295798 -227.762562)
		(end 56.151018 -227.907342)
		(width 0.14478)
		(layer "In13.Cu")
		(net "M_B_CPU1_SA_DQ<25>")
	)
	(segment
		(start 87.998046 -240.756948)
		(end 87.989664 -240.761774)
		(width 0.0889)
		(layer "In13.Cu")
		(net "M_B_CPU1_SA_DQ<25>")
	)
	(segment
		(start 76.33843 -239.450626)
		(end 76.216002 -239.328198)
		(width 0.0889)
		(layer "In13.Cu")
		(net "M_B_CPU1_SA_DQ<25>")
	)
	(segment
		(start 53.788818 -227.419408)
		(end 53.576728 -227.631498)
		(width 0.14478)
		(layer "In13.Cu")
		(net "M_B_CPU1_SA_DQ<25>")
	)
	(segment
		(start 79.17815 -240.76533)
		(end 79.163672 -240.756948)
		(width 0.0889)
		(layer "In13.Cu")
		(net "M_B_CPU1_SA_DQ<25>")
	)
	(segment
		(start 55.193438 -227.65512)
		(end 55.193438 -227.762562)
		(width 0.14478)
		(layer "In13.Cu")
		(net "M_B_CPU1_SA_DQ<25>")
	)
	(segment
		(start 55.744618 -227.65512)
		(end 55.599838 -227.51034)
		(width 0.14478)
		(layer "In13.Cu")
		(net "M_B_CPU1_SA_DQ<25>")
	)
	(segment
		(start 55.744618 -227.762562)
		(end 55.744618 -227.65512)
		(width 0.14478)
		(layer "In13.Cu")
		(net "M_B_CPU1_SA_DQ<25>")
	)
	(segment
		(start 53.576728 -227.631498)
		(end 53.372004 -227.631498)
		(width 0.14478)
		(layer "In13.Cu")
		(net "M_B_CPU1_SA_DQ<25>")
	)
	(segment
		(start 77.02423 -239.450626)
		(end 76.33843 -239.450626)
		(width 0.0889)
		(layer "In13.Cu")
		(net "M_B_CPU1_SA_DQ<25>")
	)
	(segment
		(start 56.846978 -227.65512)
		(end 56.702198 -227.51034)
		(width 0.14478)
		(layer "In13.Cu")
		(net "M_B_CPU1_SA_DQ<25>")
	)
	(segment
		(start 53.398928 -227.029518)
		(end 53.398928 -226.824794)
		(width 0.14478)
		(layer "In13.Cu")
		(net "M_B_CPU1_SA_DQ<25>")
	)
	(segment
		(start 53.186838 -227.446332)
		(end 53.186838 -227.241608)
		(width 0.14478)
		(layer "In13.Cu")
		(net "M_B_CPU1_SA_DQ<25>")
	)
	(segment
		(start 85.752432 -240.761774)
		(end 85.74405 -240.756948)
		(width 0.0889)
		(layer "In13.Cu")
		(net "M_B_CPU1_SA_DQ<25>")
	)
	(segment
		(start 56.151018 -227.907342)
		(end 55.889398 -227.907342)
		(width 0.14478)
		(layer "In13.Cu")
		(net "M_B_CPU1_SA_DQ<25>")
	)
	(segment
		(start 66.811906 -233.816652)
		(end 61.351922 -228.356668)
		(width 0.14478)
		(layer "In13.Cu")
		(net "M_B_CPU1_SA_DQ<25>")
	)
	(segment
		(start 79.163672 -240.756948)
		(end 79.153258 -240.750852)
		(width 0.0889)
		(layer "In13.Cu")
		(net "M_B_CPU1_SA_DQ<25>")
	)
	(segment
		(start 88.90508 -240.699798)
		(end 88.882728 -240.78311)
		(width 0.0889)
		(layer "In13.Cu")
		(net "M_B_CPU1_SA_DQ<25>")
	)
	(segment
		(start 54.787038 -227.907342)
		(end 54.642258 -227.762562)
		(width 0.14478)
		(layer "In13.Cu")
		(net "M_B_CPU1_SA_DQ<25>")
	)
	(segment
		(start 54.084474 -227.51034)
		(end 53.993542 -227.419408)
		(width 0.14478)
		(layer "In13.Cu")
		(net "M_B_CPU1_SA_DQ<25>")
	)
	(segment
		(start 52.172616 -226.660456)
		(end 51.884072 -226.949)
		(width 0.14478)
		(layer "In13.Cu")
		(net "M_B_CPU1_SA_DQ<25>")
	)
	(segment
		(start 57.253378 -227.907342)
		(end 56.991758 -227.907342)
		(width 0.14478)
		(layer "In13.Cu")
		(net "M_B_CPU1_SA_DQ<25>")
	)
	(segment
		(start 75.91933 -239.328198)
		(end 71.074788 -239.328198)
		(width 0.14478)
		(layer "In13.Cu")
		(net "M_B_CPU1_SA_DQ<25>")
	)
	(segment
		(start 56.295798 -227.65512)
		(end 56.295798 -227.762562)
		(width 0.14478)
		(layer "In13.Cu")
		(net "M_B_CPU1_SA_DQ<25>")
	)
	(segment
		(start 88.751156 -240.434368)
		(end 88.90508 -240.699798)
		(width 0.0889)
		(layer "In13.Cu")
		(net "M_B_CPU1_SA_DQ<25>")
	)
	(segment
		(start 57.398158 -227.65512)
		(end 57.398158 -227.762562)
		(width 0.14478)
		(layer "In13.Cu")
		(net "M_B_CPU1_SA_DQ<25>")
	)
	(segment
		(start 71.074788 -239.328198)
		(end 66.811906 -235.065316)
		(width 0.14478)
		(layer "In13.Cu")
		(net "M_B_CPU1_SA_DQ<25>")
	)
	(segment
		(start 83.29803 -240.756948)
		(end 83.289648 -240.761774)
		(width 0.0889)
		(layer "In13.Cu")
		(net "M_B_CPU1_SA_DQ<25>")
	)
	(segment
		(start 56.702198 -227.51034)
		(end 56.440578 -227.51034)
		(width 0.14478)
		(layer "In13.Cu")
		(net "M_B_CPU1_SA_DQ<25>")
	)
	(segment
		(start 54.642258 -227.762562)
		(end 54.642258 -227.65512)
		(width 0.14478)
		(layer "In13.Cu")
		(net "M_B_CPU1_SA_DQ<25>")
	)
	(segment
		(start 56.991758 -227.907342)
		(end 56.846978 -227.762562)
		(width 0.14478)
		(layer "In13.Cu")
		(net "M_B_CPU1_SA_DQ<25>")
	)
	(segment
		(start 53.398928 -226.824794)
		(end 53.23459 -226.660456)
		(width 0.14478)
		(layer "In13.Cu")
		(net "M_B_CPU1_SA_DQ<25>")
	)
	(segment
		(start 53.186838 -227.241608)
		(end 53.398928 -227.029518)
		(width 0.14478)
		(layer "In13.Cu")
		(net "M_B_CPU1_SA_DQ<25>")
	)
	(segment
		(start 59.309 -227.51034)
		(end 57.542938 -227.51034)
		(width 0.14478)
		(layer "In13.Cu")
		(net "M_B_CPU1_SA_DQ<25>")
	)
	(segment
		(start 77.48905 -239.915446)
		(end 77.02423 -239.450626)
		(width 0.0889)
		(layer "In13.Cu")
		(net "M_B_CPU1_SA_DQ<25>")
	)
	(segment
		(start 84.812378 -240.761774)
		(end 84.803996 -240.756948)
		(width 0.0889)
		(layer "In13.Cu")
		(net "M_B_CPU1_SA_DQ<25>")
	)
	(segment
		(start 77.48905 -240.392712)
		(end 77.48905 -239.915446)
		(width 0.0889)
		(layer "In13.Cu")
		(net "M_B_CPU1_SA_DQ<25>")
	)
	(segment
		(start 81.052416 -240.761774)
		(end 81.044034 -240.756948)
		(width 0.0889)
		(layer "In13.Cu")
		(net "M_B_CPU1_SA_DQ<25>")
	)
	(segment
		(start 54.642258 -227.65512)
		(end 54.497478 -227.51034)
		(width 0.14478)
		(layer "In13.Cu")
		(net "M_B_CPU1_SA_DQ<25>")
	)
	(segment
		(start 56.846978 -227.762562)
		(end 56.846978 -227.65512)
		(width 0.14478)
		(layer "In13.Cu")
		(net "M_B_CPU1_SA_DQ<25>")
	)
	(segment
		(start 80.478122 -240.756948)
		(end 80.46974 -240.761774)
		(width 0.0889)
		(layer "In13.Cu")
		(net "M_B_CPU1_SA_DQ<25>")
	)
	(segment
		(start 78.41107 -240.807494)
		(end 77.903832 -240.807494)
		(width 0.0889)
		(layer "In13.Cu")
		(net "M_B_CPU1_SA_DQ<25>")
	)
	(segment
		(start 57.542938 -227.51034)
		(end 57.398158 -227.65512)
		(width 0.14478)
		(layer "In13.Cu")
		(net "M_B_CPU1_SA_DQ<25>")
	)
	(segment
		(start 55.338218 -227.51034)
		(end 55.193438 -227.65512)
		(width 0.14478)
		(layer "In13.Cu")
		(net "M_B_CPU1_SA_DQ<25>")
	)
	(segment
		(start 66.811906 -235.065316)
		(end 66.811906 -233.816652)
		(width 0.14478)
		(layer "In13.Cu")
		(net "M_B_CPU1_SA_DQ<25>")
	)
	(segment
		(start 51.884072 -226.949)
		(end 51.884072 -227.085398)
		(width 0.14478)
		(layer "In13.Cu")
		(net "M_B_CPU1_SA_DQ<25>")
	)
	(segment
		(start 55.599838 -227.51034)
		(end 55.338218 -227.51034)
		(width 0.14478)
		(layer "In13.Cu")
		(net "M_B_CPU1_SA_DQ<25>")
	)
	(segment
		(start 76.216002 -239.328198)
		(end 75.91933 -239.328198)
		(width 0.0889)
		(layer "In13.Cu")
		(net "M_B_CPU1_SA_DQ<25>")
	)
	(segment
		(start 53.372004 -227.631498)
		(end 53.186838 -227.446332)
		(width 0.14478)
		(layer "In13.Cu")
		(net "M_B_CPU1_SA_DQ<25>")
	)
	(segment
		(start 55.048658 -227.907342)
		(end 54.787038 -227.907342)
		(width 0.14478)
		(layer "In13.Cu")
		(net "M_B_CPU1_SA_DQ<25>")
	)
	(segment
		(start 53.23459 -226.660456)
		(end 52.172616 -226.660456)
		(width 0.14478)
		(layer "In13.Cu")
		(net "M_B_CPU1_SA_DQ<25>")
	)
	(segment
		(start 57.398158 -227.762562)
		(end 57.253378 -227.907342)
		(width 0.14478)
		(layer "In13.Cu")
		(net "M_B_CPU1_SA_DQ<25>")
	)
	(segment
		(start 56.440578 -227.51034)
		(end 56.295798 -227.65512)
		(width 0.14478)
		(layer "In13.Cu")
		(net "M_B_CPU1_SA_DQ<25>")
	)
	(segment
		(start 54.497478 -227.51034)
		(end 54.084474 -227.51034)
		(width 0.14478)
		(layer "In13.Cu")
		(net "M_B_CPU1_SA_DQ<25>")
	)
	(segment
		(start 55.889398 -227.907342)
		(end 55.744618 -227.762562)
		(width 0.14478)
		(layer "In13.Cu")
		(net "M_B_CPU1_SA_DQ<25>")
	)
	(arc
		(start 87.623904 -240.756948)
		(mid 87.340948 -240.680771)
		(end 87.057992 -240.756948)
		(width 0.0889)
		(layer "In13.Cu")
		(net "M_B_CPU1_SA_DQ<25>")
	)
	(arc
		(start 82.357976 -240.756948)
		(mid 82.171032 -240.807203)
		(end 81.984088 -240.756948)
		(width 0.0889)
		(layer "In13.Cu")
		(net "M_B_CPU1_SA_DQ<25>")
	)
	(arc
		(start 88.882728 -240.78311)
		(mid 88.720396 -240.805928)
		(end 88.563958 -240.756948)
		(width 0.0889)
		(layer "In13.Cu")
		(net "M_B_CPU1_SA_DQ<25>")
	)
	(arc
		(start 84.229702 -240.761774)
		(mid 84.046194 -240.807268)
		(end 83.863942 -240.756948)
		(width 0.0889)
		(layer "In13.Cu")
		(net "M_B_CPU1_SA_DQ<25>")
	)
	(arc
		(start 88.563958 -240.756948)
		(mid 88.281002 -240.680771)
		(end 87.998046 -240.756948)
		(width 0.0889)
		(layer "In13.Cu")
		(net "M_B_CPU1_SA_DQ<25>")
	)
	(arc
		(start 83.289648 -240.761774)
		(mid 83.10614 -240.807268)
		(end 82.923888 -240.756948)
		(width 0.0889)
		(layer "In13.Cu")
		(net "M_B_CPU1_SA_DQ<25>")
	)
	(arc
		(start 86.684104 -240.756948)
		(mid 86.401148 -240.680771)
		(end 86.118192 -240.756948)
		(width 0.0889)
		(layer "In13.Cu")
		(net "M_B_CPU1_SA_DQ<25>")
	)
	(arc
		(start 80.093566 -240.750852)
		(mid 79.81488 -240.680632)
		(end 79.537814 -240.756948)
		(width 0.0889)
		(layer "In13.Cu")
		(net "M_B_CPU1_SA_DQ<25>")
	)
	(arc
		(start 81.044034 -240.756948)
		(mid 80.761078 -240.680771)
		(end 80.478122 -240.756948)
		(width 0.0889)
		(layer "In13.Cu")
		(net "M_B_CPU1_SA_DQ<25>")
	)
	(arc
		(start 85.178138 -240.756948)
		(mid 84.995887 -240.807298)
		(end 84.812378 -240.761774)
		(width 0.0889)
		(layer "In13.Cu")
		(net "M_B_CPU1_SA_DQ<25>")
	)
	(arc
		(start 79.153258 -240.750852)
		(mid 78.874826 -240.680754)
		(end 78.598014 -240.756948)
		(width 0.0889)
		(layer "In13.Cu")
		(net "M_B_CPU1_SA_DQ<25>")
	)
	(arc
		(start 87.989664 -240.761774)
		(mid 87.806156 -240.807268)
		(end 87.623904 -240.756948)
		(width 0.0889)
		(layer "In13.Cu")
		(net "M_B_CPU1_SA_DQ<25>")
	)
	(arc
		(start 84.803996 -240.756948)
		(mid 84.52104 -240.680771)
		(end 84.238084 -240.756948)
		(width 0.0889)
		(layer "In13.Cu")
		(net "M_B_CPU1_SA_DQ<25>")
	)
	(arc
		(start 86.118192 -240.756948)
		(mid 85.935941 -240.807298)
		(end 85.752432 -240.761774)
		(width 0.0889)
		(layer "In13.Cu")
		(net "M_B_CPU1_SA_DQ<25>")
	)
	(arc
		(start 87.057992 -240.756948)
		(mid 86.871048 -240.807203)
		(end 86.684104 -240.756948)
		(width 0.0889)
		(layer "In13.Cu")
		(net "M_B_CPU1_SA_DQ<25>")
	)
	(arc
		(start 81.418176 -240.756948)
		(mid 81.235925 -240.807298)
		(end 81.052416 -240.761774)
		(width 0.0889)
		(layer "In13.Cu")
		(net "M_B_CPU1_SA_DQ<25>")
	)
	(arc
		(start 81.984088 -240.756948)
		(mid 81.701132 -240.680771)
		(end 81.418176 -240.756948)
		(width 0.0889)
		(layer "In13.Cu")
		(net "M_B_CPU1_SA_DQ<25>")
	)
	(arc
		(start 80.46974 -240.761774)
		(mid 80.286232 -240.807268)
		(end 80.10398 -240.756948)
		(width 0.0889)
		(layer "In13.Cu")
		(net "M_B_CPU1_SA_DQ<25>")
	)
	(arc
		(start 78.598014 -240.756948)
		(mid 78.507881 -240.794568)
		(end 78.41107 -240.807494)
		(width 0.0889)
		(layer "In13.Cu")
		(net "M_B_CPU1_SA_DQ<25>")
	)
	(arc
		(start 83.863942 -240.756948)
		(mid 83.580986 -240.680771)
		(end 83.29803 -240.756948)
		(width 0.0889)
		(layer "In13.Cu")
		(net "M_B_CPU1_SA_DQ<25>")
	)
	(arc
		(start 82.923888 -240.756948)
		(mid 82.640932 -240.680771)
		(end 82.357976 -240.756948)
		(width 0.0889)
		(layer "In13.Cu")
		(net "M_B_CPU1_SA_DQ<25>")
	)
	(arc
		(start 85.74405 -240.756948)
		(mid 85.461094 -240.680771)
		(end 85.178138 -240.756948)
		(width 0.0889)
		(layer "In13.Cu")
		(net "M_B_CPU1_SA_DQ<25>")
	)
	(arc
		(start 79.537814 -240.756948)
		(mid 79.359059 -240.807357)
		(end 79.17815 -240.76533)
		(width 0.0889)
		(layer "In13.Cu")
		(net "M_B_CPU1_SA_DQ<25>")
	)
	(segment
		(start 87.8078 -239.8903)
		(end 87.340948 -239.624362)
		(width 0.10668)
		(layer "F.Cu")
		(net "M_B_CPU1_SA_DQ<24>")
	)
	(segment
		(start 58.6994 -226.432872)
		(end 58.84418 -226.288092)
		(width 0.14478)
		(layer "In13.Cu")
		(net "M_B_CPU1_SA_DQ<24>")
	)
	(segment
		(start 67.726306 -233.45902)
		(end 67.726306 -234.707684)
		(width 0.14478)
		(layer "In13.Cu")
		(net "M_B_CPU1_SA_DQ<24>")
	)
	(segment
		(start 54.670452 -225.973386)
		(end 54.670452 -226.035616)
		(width 0.14478)
		(layer "In13.Cu")
		(net "M_B_CPU1_SA_DQ<24>")
	)
	(segment
		(start 82.455004 -239.947958)
		(end 82.463386 -239.952784)
		(width 0.0889)
		(layer "In13.Cu")
		(net "M_B_CPU1_SA_DQ<24>")
	)
	(segment
		(start 53.23459 -224.960434)
		(end 54.084474 -225.810318)
		(width 0.14478)
		(layer "In13.Cu")
		(net "M_B_CPU1_SA_DQ<24>")
	)
	(segment
		(start 57.59704 -226.432872)
		(end 57.74182 -226.288092)
		(width 0.14478)
		(layer "In13.Cu")
		(net "M_B_CPU1_SA_DQ<24>")
	)
	(segment
		(start 75.94981 -238.418878)
		(end 76.335382 -238.418878)
		(width 0.0889)
		(layer "In13.Cu")
		(net "M_B_CPU1_SA_DQ<24>")
	)
	(segment
		(start 56.503062 -225.810318)
		(end 57.04586 -225.810318)
		(width 0.14478)
		(layer "In13.Cu")
		(net "M_B_CPU1_SA_DQ<24>")
	)
	(segment
		(start 57.8866 -225.810318)
		(end 58.14822 -225.810318)
		(width 0.14478)
		(layer "In13.Cu")
		(net "M_B_CPU1_SA_DQ<24>")
	)
	(segment
		(start 54.83352 -226.198684)
		(end 55.063898 -226.198684)
		(width 0.14478)
		(layer "In13.Cu")
		(net "M_B_CPU1_SA_DQ<24>")
	)
	(segment
		(start 83.395058 -239.947958)
		(end 83.40344 -239.952784)
		(width 0.0889)
		(layer "In13.Cu")
		(net "M_B_CPU1_SA_DQ<24>")
	)
	(segment
		(start 60.18022 -226.771708)
		(end 60.365386 -226.956874)
		(width 0.14478)
		(layer "In13.Cu")
		(net "M_B_CPU1_SA_DQ<24>")
	)
	(segment
		(start 57.74182 -225.955098)
		(end 57.8866 -225.810318)
		(width 0.14478)
		(layer "In13.Cu")
		(net "M_B_CPU1_SA_DQ<24>")
	)
	(segment
		(start 55.620412 -225.810318)
		(end 55.78348 -225.973386)
		(width 0.14478)
		(layer "In13.Cu")
		(net "M_B_CPU1_SA_DQ<24>")
	)
	(segment
		(start 55.226966 -225.973386)
		(end 55.390034 -225.810318)
		(width 0.14478)
		(layer "In13.Cu")
		(net "M_B_CPU1_SA_DQ<24>")
	)
	(segment
		(start 57.04586 -225.810318)
		(end 57.19064 -225.955098)
		(width 0.14478)
		(layer "In13.Cu")
		(net "M_B_CPU1_SA_DQ<24>")
	)
	(segment
		(start 56.176926 -226.198684)
		(end 56.339994 -226.035616)
		(width 0.14478)
		(layer "In13.Cu")
		(net "M_B_CPU1_SA_DQ<24>")
	)
	(segment
		(start 55.390034 -225.810318)
		(end 55.620412 -225.810318)
		(width 0.14478)
		(layer "In13.Cu")
		(net "M_B_CPU1_SA_DQ<24>")
	)
	(segment
		(start 76.335382 -238.418878)
		(end 76.65847 -238.741966)
		(width 0.0889)
		(layer "In13.Cu")
		(net "M_B_CPU1_SA_DQ<24>")
	)
	(segment
		(start 58.293 -225.955098)
		(end 58.293 -226.288092)
		(width 0.14478)
		(layer "In13.Cu")
		(net "M_B_CPU1_SA_DQ<24>")
	)
	(segment
		(start 57.33542 -226.432872)
		(end 57.59704 -226.432872)
		(width 0.14478)
		(layer "In13.Cu")
		(net "M_B_CPU1_SA_DQ<24>")
	)
	(segment
		(start 51.884072 -225.198178)
		(end 52.121816 -224.960434)
		(width 0.14478)
		(layer "In13.Cu")
		(net "M_B_CPU1_SA_DQ<24>")
	)
	(segment
		(start 54.670452 -226.035616)
		(end 54.83352 -226.198684)
		(width 0.14478)
		(layer "In13.Cu")
		(net "M_B_CPU1_SA_DQ<24>")
	)
	(segment
		(start 87.15502 -239.947958)
		(end 87.163402 -239.952784)
		(width 0.0889)
		(layer "In13.Cu")
		(net "M_B_CPU1_SA_DQ<24>")
	)
	(segment
		(start 81.88071 -239.952784)
		(end 81.889092 -239.947958)
		(width 0.0889)
		(layer "In13.Cu")
		(net "M_B_CPU1_SA_DQ<24>")
	)
	(segment
		(start 76.65847 -238.741966)
		(end 77.072744 -238.741966)
		(width 0.0889)
		(layer "In13.Cu")
		(net "M_B_CPU1_SA_DQ<24>")
	)
	(segment
		(start 60.365386 -226.956874)
		(end 60.57011 -226.957128)
		(width 0.14478)
		(layer "In13.Cu")
		(net "M_B_CPU1_SA_DQ<24>")
	)
	(segment
		(start 58.43778 -226.432872)
		(end 58.6994 -226.432872)
		(width 0.14478)
		(layer "In13.Cu")
		(net "M_B_CPU1_SA_DQ<24>")
	)
	(segment
		(start 57.19064 -225.955098)
		(end 57.19064 -226.288092)
		(width 0.14478)
		(layer "In13.Cu")
		(net "M_B_CPU1_SA_DQ<24>")
	)
	(segment
		(start 86.580726 -239.952784)
		(end 86.589108 -239.947958)
		(width 0.0889)
		(layer "In13.Cu")
		(net "M_B_CPU1_SA_DQ<24>")
	)
	(segment
		(start 55.78348 -225.973386)
		(end 55.78348 -226.035616)
		(width 0.14478)
		(layer "In13.Cu")
		(net "M_B_CPU1_SA_DQ<24>")
	)
	(segment
		(start 58.84418 -226.288092)
		(end 58.84418 -225.955098)
		(width 0.14478)
		(layer "In13.Cu")
		(net "M_B_CPU1_SA_DQ<24>")
	)
	(segment
		(start 58.98896 -225.810318)
		(end 60.077604 -225.810318)
		(width 0.14478)
		(layer "In13.Cu")
		(net "M_B_CPU1_SA_DQ<24>")
	)
	(segment
		(start 60.7949 -226.732338)
		(end 60.999624 -226.732338)
		(width 0.14478)
		(layer "In13.Cu")
		(net "M_B_CPU1_SA_DQ<24>")
	)
	(segment
		(start 60.077604 -225.810318)
		(end 60.405264 -226.137978)
		(width 0.14478)
		(layer "In13.Cu")
		(net "M_B_CPU1_SA_DQ<24>")
	)
	(segment
		(start 60.405264 -226.137978)
		(end 60.40501 -226.342194)
		(width 0.14478)
		(layer "In13.Cu")
		(net "M_B_CPU1_SA_DQ<24>")
	)
	(segment
		(start 77.072744 -238.741966)
		(end 78.20152 -239.870742)
		(width 0.0889)
		(layer "In13.Cu")
		(net "M_B_CPU1_SA_DQ<24>")
	)
	(segment
		(start 56.339994 -226.035616)
		(end 56.339994 -225.973386)
		(width 0.14478)
		(layer "In13.Cu")
		(net "M_B_CPU1_SA_DQ<24>")
	)
	(segment
		(start 55.946548 -226.198684)
		(end 56.176926 -226.198684)
		(width 0.14478)
		(layer "In13.Cu")
		(net "M_B_CPU1_SA_DQ<24>")
	)
	(segment
		(start 55.226966 -226.035616)
		(end 55.226966 -225.973386)
		(width 0.14478)
		(layer "In13.Cu")
		(net "M_B_CPU1_SA_DQ<24>")
	)
	(segment
		(start 56.339994 -225.973386)
		(end 56.503062 -225.810318)
		(width 0.14478)
		(layer "In13.Cu")
		(net "M_B_CPU1_SA_DQ<24>")
	)
	(segment
		(start 87.470742 -239.973866)
		(end 87.495126 -239.889792)
		(width 0.0889)
		(layer "In13.Cu")
		(net "M_B_CPU1_SA_DQ<24>")
	)
	(segment
		(start 80.008222 -239.946942)
		(end 80.009238 -239.947958)
		(width 0.0889)
		(layer "In13.Cu")
		(net "M_B_CPU1_SA_DQ<24>")
	)
	(segment
		(start 58.84418 -225.955098)
		(end 58.98896 -225.810318)
		(width 0.14478)
		(layer "In13.Cu")
		(net "M_B_CPU1_SA_DQ<24>")
	)
	(segment
		(start 57.74182 -226.288092)
		(end 57.74182 -225.955098)
		(width 0.14478)
		(layer "In13.Cu")
		(net "M_B_CPU1_SA_DQ<24>")
	)
	(segment
		(start 55.78348 -226.035616)
		(end 55.946548 -226.198684)
		(width 0.14478)
		(layer "In13.Cu")
		(net "M_B_CPU1_SA_DQ<24>")
	)
	(segment
		(start 51.884072 -225.385376)
		(end 51.884072 -225.198178)
		(width 0.14478)
		(layer "In13.Cu")
		(net "M_B_CPU1_SA_DQ<24>")
	)
	(segment
		(start 87.495126 -239.889792)
		(end 87.340948 -239.624362)
		(width 0.0889)
		(layer "In13.Cu")
		(net "M_B_CPU1_SA_DQ<24>")
	)
	(segment
		(start 60.40501 -226.342194)
		(end 60.18022 -226.566984)
		(width 0.14478)
		(layer "In13.Cu")
		(net "M_B_CPU1_SA_DQ<24>")
	)
	(segment
		(start 85.640672 -239.952784)
		(end 85.649054 -239.947958)
		(width 0.0889)
		(layer "In13.Cu")
		(net "M_B_CPU1_SA_DQ<24>")
	)
	(segment
		(start 60.18022 -226.566984)
		(end 60.18022 -226.771708)
		(width 0.14478)
		(layer "In13.Cu")
		(net "M_B_CPU1_SA_DQ<24>")
	)
	(segment
		(start 55.063898 -226.198684)
		(end 55.226966 -226.035616)
		(width 0.14478)
		(layer "In13.Cu")
		(net "M_B_CPU1_SA_DQ<24>")
	)
	(segment
		(start 52.121816 -224.960434)
		(end 53.23459 -224.960434)
		(width 0.14478)
		(layer "In13.Cu")
		(net "M_B_CPU1_SA_DQ<24>")
	)
	(segment
		(start 78.20152 -239.870742)
		(end 78.41107 -239.870742)
		(width 0.0889)
		(layer "In13.Cu")
		(net "M_B_CPU1_SA_DQ<24>")
	)
	(segment
		(start 58.293 -226.288092)
		(end 58.43778 -226.432872)
		(width 0.14478)
		(layer "In13.Cu")
		(net "M_B_CPU1_SA_DQ<24>")
	)
	(segment
		(start 67.726306 -234.707684)
		(end 71.4375 -238.418878)
		(width 0.14478)
		(layer "In13.Cu")
		(net "M_B_CPU1_SA_DQ<24>")
	)
	(segment
		(start 58.14822 -225.810318)
		(end 58.293 -225.955098)
		(width 0.14478)
		(layer "In13.Cu")
		(net "M_B_CPU1_SA_DQ<24>")
	)
	(segment
		(start 54.084474 -225.810318)
		(end 54.507384 -225.810318)
		(width 0.14478)
		(layer "In13.Cu")
		(net "M_B_CPU1_SA_DQ<24>")
	)
	(segment
		(start 60.999624 -226.732338)
		(end 67.726306 -233.45902)
		(width 0.14478)
		(layer "In13.Cu")
		(net "M_B_CPU1_SA_DQ<24>")
	)
	(segment
		(start 71.4375 -238.418878)
		(end 75.94981 -238.418878)
		(width 0.14478)
		(layer "In13.Cu")
		(net "M_B_CPU1_SA_DQ<24>")
	)
	(segment
		(start 57.19064 -226.288092)
		(end 57.33542 -226.432872)
		(width 0.14478)
		(layer "In13.Cu")
		(net "M_B_CPU1_SA_DQ<24>")
	)
	(segment
		(start 54.507384 -225.810318)
		(end 54.670452 -225.973386)
		(width 0.14478)
		(layer "In13.Cu")
		(net "M_B_CPU1_SA_DQ<24>")
	)
	(segment
		(start 60.57011 -226.957128)
		(end 60.7949 -226.732338)
		(width 0.14478)
		(layer "In13.Cu")
		(net "M_B_CPU1_SA_DQ<24>")
	)
	(arc
		(start 80.57515 -239.947958)
		(mid 80.762094 -239.998213)
		(end 80.949038 -239.947958)
		(width 0.0889)
		(layer "In13.Cu")
		(net "M_B_CPU1_SA_DQ<24>")
	)
	(arc
		(start 84.709 -239.947958)
		(mid 84.991956 -239.871781)
		(end 85.274912 -239.947958)
		(width 0.0889)
		(layer "In13.Cu")
		(net "M_B_CPU1_SA_DQ<24>")
	)
	(arc
		(start 81.51495 -239.947958)
		(mid 81.697201 -239.998308)
		(end 81.88071 -239.952784)
		(width 0.0889)
		(layer "In13.Cu")
		(net "M_B_CPU1_SA_DQ<24>")
	)
	(arc
		(start 86.589108 -239.947958)
		(mid 86.872064 -239.871781)
		(end 87.15502 -239.947958)
		(width 0.0889)
		(layer "In13.Cu")
		(net "M_B_CPU1_SA_DQ<24>")
	)
	(arc
		(start 82.829146 -239.947958)
		(mid 83.112102 -239.871781)
		(end 83.395058 -239.947958)
		(width 0.0889)
		(layer "In13.Cu")
		(net "M_B_CPU1_SA_DQ<24>")
	)
	(arc
		(start 78.41107 -239.870742)
		(mid 78.557587 -239.890128)
		(end 78.694026 -239.946942)
		(width 0.0889)
		(layer "In13.Cu")
		(net "M_B_CPU1_SA_DQ<24>")
	)
	(arc
		(start 82.463386 -239.952784)
		(mid 82.646894 -239.998278)
		(end 82.829146 -239.947958)
		(width 0.0889)
		(layer "In13.Cu")
		(net "M_B_CPU1_SA_DQ<24>")
	)
	(arc
		(start 84.335112 -239.947958)
		(mid 84.522056 -239.998213)
		(end 84.709 -239.947958)
		(width 0.0889)
		(layer "In13.Cu")
		(net "M_B_CPU1_SA_DQ<24>")
	)
	(arc
		(start 85.649054 -239.947958)
		(mid 85.93201 -239.871781)
		(end 86.214966 -239.947958)
		(width 0.0889)
		(layer "In13.Cu")
		(net "M_B_CPU1_SA_DQ<24>")
	)
	(arc
		(start 87.163402 -239.952784)
		(mid 87.314762 -239.996852)
		(end 87.470742 -239.973866)
		(width 0.0889)
		(layer "In13.Cu")
		(net "M_B_CPU1_SA_DQ<24>")
	)
	(arc
		(start 79.633826 -239.946942)
		(mid 79.821024 -239.997324)
		(end 80.008222 -239.946942)
		(width 0.0889)
		(layer "In13.Cu")
		(net "M_B_CPU1_SA_DQ<24>")
	)
	(arc
		(start 79.067914 -239.946942)
		(mid 79.35087 -239.870765)
		(end 79.633826 -239.946942)
		(width 0.0889)
		(layer "In13.Cu")
		(net "M_B_CPU1_SA_DQ<24>")
	)
	(arc
		(start 83.40344 -239.952784)
		(mid 83.586948 -239.998278)
		(end 83.7692 -239.947958)
		(width 0.0889)
		(layer "In13.Cu")
		(net "M_B_CPU1_SA_DQ<24>")
	)
	(arc
		(start 83.7692 -239.947958)
		(mid 84.052156 -239.871781)
		(end 84.335112 -239.947958)
		(width 0.0889)
		(layer "In13.Cu")
		(net "M_B_CPU1_SA_DQ<24>")
	)
	(arc
		(start 85.274912 -239.947958)
		(mid 85.457163 -239.998308)
		(end 85.640672 -239.952784)
		(width 0.0889)
		(layer "In13.Cu")
		(net "M_B_CPU1_SA_DQ<24>")
	)
	(arc
		(start 80.009238 -239.947958)
		(mid 80.292194 -239.871781)
		(end 80.57515 -239.947958)
		(width 0.0889)
		(layer "In13.Cu")
		(net "M_B_CPU1_SA_DQ<24>")
	)
	(arc
		(start 78.694026 -239.946942)
		(mid 78.88097 -239.997197)
		(end 79.067914 -239.946942)
		(width 0.0889)
		(layer "In13.Cu")
		(net "M_B_CPU1_SA_DQ<24>")
	)
	(arc
		(start 86.214966 -239.947958)
		(mid 86.397217 -239.998308)
		(end 86.580726 -239.952784)
		(width 0.0889)
		(layer "In13.Cu")
		(net "M_B_CPU1_SA_DQ<24>")
	)
	(arc
		(start 81.889092 -239.947958)
		(mid 82.172048 -239.871781)
		(end 82.455004 -239.947958)
		(width 0.0889)
		(layer "In13.Cu")
		(net "M_B_CPU1_SA_DQ<24>")
	)
	(arc
		(start 80.949038 -239.947958)
		(mid 81.231994 -239.871781)
		(end 81.51495 -239.947958)
		(width 0.0889)
		(layer "In13.Cu")
		(net "M_B_CPU1_SA_DQ<24>")
	)
	(segment
		(start 89.687908 -239.8903)
		(end 89.221056 -239.624362)
		(width 0.10668)
		(layer "F.Cu")
		(net "M_B_CPU1_SA_DQ<23>")
	)
	(segment
		(start 68.282566 -234.458002)
		(end 71.687182 -237.862618)
		(width 0.14478)
		(layer "In13.Cu")
		(net "M_B_CPU1_SA_DQ<23>")
	)
	(segment
		(start 54.106572 -224.960434)
		(end 60.0075 -224.960434)
		(width 0.14478)
		(layer "In13.Cu")
		(net "M_B_CPU1_SA_DQ<23>")
	)
	(segment
		(start 88.97112 -239.333532)
		(end 89.067132 -239.358932)
		(width 0.0889)
		(layer "In13.Cu")
		(net "M_B_CPU1_SA_DQ<23>")
	)
	(segment
		(start 75.946 -237.862618)
		(end 76.990702 -237.862618)
		(width 0.0889)
		(layer "In13.Cu")
		(net "M_B_CPU1_SA_DQ<23>")
	)
	(segment
		(start 85.639656 -239.296956)
		(end 85.648038 -239.301782)
		(width 0.0889)
		(layer "In13.Cu")
		(net "M_B_CPU1_SA_DQ<23>")
	)
	(segment
		(start 78.65491 -239.352582)
		(end 78.692502 -239.31499)
		(width 0.0889)
		(layer "In13.Cu")
		(net "M_B_CPU1_SA_DQ<23>")
	)
	(segment
		(start 49.797462 -224.535238)
		(end 50.222404 -224.110296)
		(width 0.14478)
		(layer "In13.Cu")
		(net "M_B_CPU1_SA_DQ<23>")
	)
	(segment
		(start 79.63408 -239.301782)
		(end 79.633826 -239.301782)
		(width 0.0889)
		(layer "In13.Cu")
		(net "M_B_CPU1_SA_DQ<23>")
	)
	(segment
		(start 50.222404 -224.110296)
		(end 53.256434 -224.110296)
		(width 0.14478)
		(layer "In13.Cu")
		(net "M_B_CPU1_SA_DQ<23>")
	)
	(segment
		(start 82.453988 -239.301782)
		(end 82.46237 -239.296956)
		(width 0.0889)
		(layer "In13.Cu")
		(net "M_B_CPU1_SA_DQ<23>")
	)
	(segment
		(start 77.76591 -238.637826)
		(end 77.76591 -238.7473)
		(width 0.0889)
		(layer "In13.Cu")
		(net "M_B_CPU1_SA_DQ<23>")
	)
	(segment
		(start 86.57971 -239.296956)
		(end 86.588092 -239.301782)
		(width 0.0889)
		(layer "In13.Cu")
		(net "M_B_CPU1_SA_DQ<23>")
	)
	(segment
		(start 60.0075 -224.960434)
		(end 68.282566 -233.2355)
		(width 0.14478)
		(layer "In13.Cu")
		(net "M_B_CPU1_SA_DQ<23>")
	)
	(segment
		(start 87.154004 -239.301782)
		(end 87.162386 -239.296956)
		(width 0.0889)
		(layer "In13.Cu")
		(net "M_B_CPU1_SA_DQ<23>")
	)
	(segment
		(start 89.067132 -239.358932)
		(end 89.221056 -239.624362)
		(width 0.0889)
		(layer "In13.Cu")
		(net "M_B_CPU1_SA_DQ<23>")
	)
	(segment
		(start 76.990702 -237.862618)
		(end 77.76591 -238.637826)
		(width 0.0889)
		(layer "In13.Cu")
		(net "M_B_CPU1_SA_DQ<23>")
	)
	(segment
		(start 88.094058 -239.301782)
		(end 88.10244 -239.296956)
		(width 0.0889)
		(layer "In13.Cu")
		(net "M_B_CPU1_SA_DQ<23>")
	)
	(segment
		(start 81.879694 -239.296956)
		(end 81.888076 -239.301782)
		(width 0.0889)
		(layer "In13.Cu")
		(net "M_B_CPU1_SA_DQ<23>")
	)
	(segment
		(start 68.282566 -233.2355)
		(end 68.282566 -234.458002)
		(width 0.14478)
		(layer "In13.Cu")
		(net "M_B_CPU1_SA_DQ<23>")
	)
	(segment
		(start 47.784004 -224.535238)
		(end 49.797462 -224.535238)
		(width 0.14478)
		(layer "In13.Cu")
		(net "M_B_CPU1_SA_DQ<23>")
	)
	(segment
		(start 83.394042 -239.301782)
		(end 83.402424 -239.296956)
		(width 0.0889)
		(layer "In13.Cu")
		(net "M_B_CPU1_SA_DQ<23>")
	)
	(segment
		(start 78.397354 -239.378744)
		(end 78.591918 -239.378744)
		(width 0.0889)
		(layer "In13.Cu")
		(net "M_B_CPU1_SA_DQ<23>")
	)
	(segment
		(start 71.687182 -237.862618)
		(end 75.946 -237.862618)
		(width 0.14478)
		(layer "In13.Cu")
		(net "M_B_CPU1_SA_DQ<23>")
	)
	(segment
		(start 53.256434 -224.110296)
		(end 54.106572 -224.960434)
		(width 0.14478)
		(layer "In13.Cu")
		(net "M_B_CPU1_SA_DQ<23>")
	)
	(arc
		(start 82.46237 -239.296956)
		(mid 82.645878 -239.251462)
		(end 82.82813 -239.301782)
		(width 0.0889)
		(layer "In13.Cu")
		(net "M_B_CPU1_SA_DQ<23>")
	)
	(arc
		(start 79.633826 -239.301782)
		(mid 79.821024 -239.2514)
		(end 80.008222 -239.301782)
		(width 0.0889)
		(layer "In13.Cu")
		(net "M_B_CPU1_SA_DQ<23>")
	)
	(arc
		(start 78.768448 -239.268762)
		(mid 78.921796 -239.253625)
		(end 79.068168 -239.301782)
		(width 0.0889)
		(layer "In13.Cu")
		(net "M_B_CPU1_SA_DQ<23>")
	)
	(arc
		(start 80.948022 -239.301782)
		(mid 81.230978 -239.377959)
		(end 81.513934 -239.301782)
		(width 0.0889)
		(layer "In13.Cu")
		(net "M_B_CPU1_SA_DQ<23>")
	)
	(arc
		(start 77.76591 -238.7473)
		(mid 77.950856 -239.193798)
		(end 78.397354 -239.378744)
		(width 0.0889)
		(layer "In13.Cu")
		(net "M_B_CPU1_SA_DQ<23>")
	)
	(arc
		(start 84.707984 -239.301782)
		(mid 84.99094 -239.377959)
		(end 85.273896 -239.301782)
		(width 0.0889)
		(layer "In13.Cu")
		(net "M_B_CPU1_SA_DQ<23>")
	)
	(arc
		(start 81.513934 -239.301782)
		(mid 81.696185 -239.251432)
		(end 81.879694 -239.296956)
		(width 0.0889)
		(layer "In13.Cu")
		(net "M_B_CPU1_SA_DQ<23>")
	)
	(arc
		(start 81.888076 -239.301782)
		(mid 82.171032 -239.377959)
		(end 82.453988 -239.301782)
		(width 0.0889)
		(layer "In13.Cu")
		(net "M_B_CPU1_SA_DQ<23>")
	)
	(arc
		(start 85.273896 -239.301782)
		(mid 85.456147 -239.251432)
		(end 85.639656 -239.296956)
		(width 0.0889)
		(layer "In13.Cu")
		(net "M_B_CPU1_SA_DQ<23>")
	)
	(arc
		(start 87.162386 -239.296956)
		(mid 87.345894 -239.251462)
		(end 87.528146 -239.301782)
		(width 0.0889)
		(layer "In13.Cu")
		(net "M_B_CPU1_SA_DQ<23>")
	)
	(arc
		(start 83.402424 -239.296956)
		(mid 83.585932 -239.251462)
		(end 83.768184 -239.301782)
		(width 0.0889)
		(layer "In13.Cu")
		(net "M_B_CPU1_SA_DQ<23>")
	)
	(arc
		(start 78.692502 -239.31499)
		(mid 78.727693 -239.287306)
		(end 78.768448 -239.268762)
		(width 0.0889)
		(layer "In13.Cu")
		(net "M_B_CPU1_SA_DQ<23>")
	)
	(arc
		(start 86.588092 -239.301782)
		(mid 86.871048 -239.377959)
		(end 87.154004 -239.301782)
		(width 0.0889)
		(layer "In13.Cu")
		(net "M_B_CPU1_SA_DQ<23>")
	)
	(arc
		(start 80.008222 -239.301782)
		(mid 80.291178 -239.377959)
		(end 80.574134 -239.301782)
		(width 0.0889)
		(layer "In13.Cu")
		(net "M_B_CPU1_SA_DQ<23>")
	)
	(arc
		(start 87.528146 -239.301782)
		(mid 87.811102 -239.377959)
		(end 88.094058 -239.301782)
		(width 0.0889)
		(layer "In13.Cu")
		(net "M_B_CPU1_SA_DQ<23>")
	)
	(arc
		(start 88.10244 -239.296956)
		(mid 88.285948 -239.251462)
		(end 88.4682 -239.301782)
		(width 0.0889)
		(layer "In13.Cu")
		(net "M_B_CPU1_SA_DQ<23>")
	)
	(arc
		(start 78.591918 -239.378744)
		(mid 78.626022 -239.371942)
		(end 78.65491 -239.352582)
		(width 0.0889)
		(layer "In13.Cu")
		(net "M_B_CPU1_SA_DQ<23>")
	)
	(arc
		(start 82.82813 -239.301782)
		(mid 83.111086 -239.377959)
		(end 83.394042 -239.301782)
		(width 0.0889)
		(layer "In13.Cu")
		(net "M_B_CPU1_SA_DQ<23>")
	)
	(arc
		(start 85.648038 -239.301782)
		(mid 85.930994 -239.377959)
		(end 86.21395 -239.301782)
		(width 0.0889)
		(layer "In13.Cu")
		(net "M_B_CPU1_SA_DQ<23>")
	)
	(arc
		(start 79.068168 -239.301782)
		(mid 79.351124 -239.377959)
		(end 79.63408 -239.301782)
		(width 0.0889)
		(layer "In13.Cu")
		(net "M_B_CPU1_SA_DQ<23>")
	)
	(arc
		(start 84.334096 -239.301782)
		(mid 84.52104 -239.251527)
		(end 84.707984 -239.301782)
		(width 0.0889)
		(layer "In13.Cu")
		(net "M_B_CPU1_SA_DQ<23>")
	)
	(arc
		(start 88.4682 -239.301782)
		(mid 88.715913 -239.377002)
		(end 88.97112 -239.333532)
		(width 0.0889)
		(layer "In13.Cu")
		(net "M_B_CPU1_SA_DQ<23>")
	)
	(arc
		(start 80.574134 -239.301782)
		(mid 80.761078 -239.251527)
		(end 80.948022 -239.301782)
		(width 0.0889)
		(layer "In13.Cu")
		(net "M_B_CPU1_SA_DQ<23>")
	)
	(arc
		(start 83.768184 -239.301782)
		(mid 84.05114 -239.377959)
		(end 84.334096 -239.301782)
		(width 0.0889)
		(layer "In13.Cu")
		(net "M_B_CPU1_SA_DQ<23>")
	)
	(arc
		(start 86.21395 -239.301782)
		(mid 86.396201 -239.251432)
		(end 86.57971 -239.296956)
		(width 0.0889)
		(layer "In13.Cu")
		(net "M_B_CPU1_SA_DQ<23>")
	)
	(segment
		(start 88.277954 -239.080294)
		(end 87.811102 -238.814356)
		(width 0.10668)
		(layer "F.Cu")
		(net "M_B_CPU1_SA_DQ<22>")
	)
	(segment
		(start 57.849008 -223.044766)
		(end 57.849008 -223.115632)
		(width 0.14478)
		(layer "In13.Cu")
		(net "M_B_CPU1_SA_DQ<22>")
	)
	(segment
		(start 87.560658 -238.523526)
		(end 87.656924 -238.548926)
		(width 0.0889)
		(layer "In13.Cu")
		(net "M_B_CPU1_SA_DQ<22>")
	)
	(segment
		(start 80.46974 -238.48695)
		(end 80.478122 -238.491776)
		(width 0.0889)
		(layer "In13.Cu")
		(net "M_B_CPU1_SA_DQ<22>")
	)
	(segment
		(start 57.297828 -223.115632)
		(end 57.297828 -223.044766)
		(width 0.14478)
		(layer "In13.Cu")
		(net "M_B_CPU1_SA_DQ<22>")
	)
	(segment
		(start 58.255408 -223.260412)
		(end 58.400188 -223.115632)
		(width 0.14478)
		(layer "In13.Cu")
		(net "M_B_CPU1_SA_DQ<22>")
	)
	(segment
		(start 56.050688 -223.260412)
		(end 56.195468 -223.115632)
		(width 0.14478)
		(layer "In13.Cu")
		(net "M_B_CPU1_SA_DQ<22>")
	)
	(segment
		(start 69.191886 -234.095036)
		(end 72.050148 -236.953298)
		(width 0.14478)
		(layer "In13.Cu")
		(net "M_B_CPU1_SA_DQ<22>")
	)
	(segment
		(start 72.050148 -236.953298)
		(end 75.96378 -236.953298)
		(width 0.14478)
		(layer "In13.Cu")
		(net "M_B_CPU1_SA_DQ<22>")
	)
	(segment
		(start 56.340248 -222.899986)
		(end 56.601868 -222.899986)
		(width 0.14478)
		(layer "In13.Cu")
		(net "M_B_CPU1_SA_DQ<22>")
	)
	(segment
		(start 57.153048 -223.260412)
		(end 57.297828 -223.115632)
		(width 0.14478)
		(layer "In13.Cu")
		(net "M_B_CPU1_SA_DQ<22>")
	)
	(segment
		(start 57.993788 -223.260412)
		(end 58.255408 -223.260412)
		(width 0.14478)
		(layer "In13.Cu")
		(net "M_B_CPU1_SA_DQ<22>")
	)
	(segment
		(start 56.746648 -223.044766)
		(end 56.746648 -223.115632)
		(width 0.14478)
		(layer "In13.Cu")
		(net "M_B_CPU1_SA_DQ<22>")
	)
	(segment
		(start 58.951368 -223.115632)
		(end 59.096148 -223.260412)
		(width 0.14478)
		(layer "In13.Cu")
		(net "M_B_CPU1_SA_DQ<22>")
	)
	(segment
		(start 57.297828 -223.044766)
		(end 57.442608 -222.899986)
		(width 0.14478)
		(layer "In13.Cu")
		(net "M_B_CPU1_SA_DQ<22>")
	)
	(segment
		(start 59.57951 -223.260412)
		(end 69.191886 -232.872788)
		(width 0.14478)
		(layer "In13.Cu")
		(net "M_B_CPU1_SA_DQ<22>")
	)
	(segment
		(start 53.256434 -222.410274)
		(end 54.106572 -223.260412)
		(width 0.14478)
		(layer "In13.Cu")
		(net "M_B_CPU1_SA_DQ<22>")
	)
	(segment
		(start 79.143098 -238.505492)
		(end 79.166466 -238.491776)
		(width 0.0889)
		(layer "In13.Cu")
		(net "M_B_CPU1_SA_DQ<22>")
	)
	(segment
		(start 69.191886 -232.872788)
		(end 69.191886 -234.095036)
		(width 0.14478)
		(layer "In13.Cu")
		(net "M_B_CPU1_SA_DQ<22>")
	)
	(segment
		(start 49.797462 -222.835216)
		(end 50.222404 -222.410274)
		(width 0.14478)
		(layer "In13.Cu")
		(net "M_B_CPU1_SA_DQ<22>")
	)
	(segment
		(start 76.139802 -236.953298)
		(end 76.49083 -237.304326)
		(width 0.0889)
		(layer "In13.Cu")
		(net "M_B_CPU1_SA_DQ<22>")
	)
	(segment
		(start 58.400188 -223.044766)
		(end 58.544968 -222.899986)
		(width 0.14478)
		(layer "In13.Cu")
		(net "M_B_CPU1_SA_DQ<22>")
	)
	(segment
		(start 57.442608 -222.899986)
		(end 57.704228 -222.899986)
		(width 0.14478)
		(layer "In13.Cu")
		(net "M_B_CPU1_SA_DQ<22>")
	)
	(segment
		(start 76.49083 -237.304326)
		(end 77.06995 -237.304326)
		(width 0.0889)
		(layer "In13.Cu")
		(net "M_B_CPU1_SA_DQ<22>")
	)
	(segment
		(start 58.544968 -222.899986)
		(end 58.806588 -222.899986)
		(width 0.14478)
		(layer "In13.Cu")
		(net "M_B_CPU1_SA_DQ<22>")
	)
	(segment
		(start 56.601868 -222.899986)
		(end 56.746648 -223.044766)
		(width 0.14478)
		(layer "In13.Cu")
		(net "M_B_CPU1_SA_DQ<22>")
	)
	(segment
		(start 81.044034 -238.491776)
		(end 81.052416 -238.48695)
		(width 0.0889)
		(layer "In13.Cu")
		(net "M_B_CPU1_SA_DQ<22>")
	)
	(segment
		(start 83.289648 -238.48695)
		(end 83.29803 -238.491776)
		(width 0.0889)
		(layer "In13.Cu")
		(net "M_B_CPU1_SA_DQ<22>")
	)
	(segment
		(start 87.656924 -238.548926)
		(end 87.811102 -238.814356)
		(width 0.0889)
		(layer "In13.Cu")
		(net "M_B_CPU1_SA_DQ<22>")
	)
	(segment
		(start 56.746648 -223.115632)
		(end 56.891428 -223.260412)
		(width 0.14478)
		(layer "In13.Cu")
		(net "M_B_CPU1_SA_DQ<22>")
	)
	(segment
		(start 77.06995 -237.304326)
		(end 78.206346 -238.440722)
		(width 0.0889)
		(layer "In13.Cu")
		(net "M_B_CPU1_SA_DQ<22>")
	)
	(segment
		(start 84.803996 -238.491776)
		(end 84.812378 -238.48695)
		(width 0.0889)
		(layer "In13.Cu")
		(net "M_B_CPU1_SA_DQ<22>")
	)
	(segment
		(start 59.096148 -223.260412)
		(end 59.57951 -223.260412)
		(width 0.14478)
		(layer "In13.Cu")
		(net "M_B_CPU1_SA_DQ<22>")
	)
	(segment
		(start 47.784004 -222.835216)
		(end 49.797462 -222.835216)
		(width 0.14478)
		(layer "In13.Cu")
		(net "M_B_CPU1_SA_DQ<22>")
	)
	(segment
		(start 56.195468 -223.115632)
		(end 56.195468 -223.044766)
		(width 0.14478)
		(layer "In13.Cu")
		(net "M_B_CPU1_SA_DQ<22>")
	)
	(segment
		(start 79.521304 -238.481616)
		(end 79.539592 -238.49203)
		(width 0.0889)
		(layer "In13.Cu")
		(net "M_B_CPU1_SA_DQ<22>")
	)
	(segment
		(start 56.891428 -223.260412)
		(end 57.153048 -223.260412)
		(width 0.14478)
		(layer "In13.Cu")
		(net "M_B_CPU1_SA_DQ<22>")
	)
	(segment
		(start 85.74405 -238.491776)
		(end 85.752432 -238.48695)
		(width 0.0889)
		(layer "In13.Cu")
		(net "M_B_CPU1_SA_DQ<22>")
	)
	(segment
		(start 54.106572 -223.260412)
		(end 56.050688 -223.260412)
		(width 0.14478)
		(layer "In13.Cu")
		(net "M_B_CPU1_SA_DQ<22>")
	)
	(segment
		(start 57.704228 -222.899986)
		(end 57.849008 -223.044766)
		(width 0.14478)
		(layer "In13.Cu")
		(net "M_B_CPU1_SA_DQ<22>")
	)
	(segment
		(start 58.951368 -223.044766)
		(end 58.951368 -223.115632)
		(width 0.14478)
		(layer "In13.Cu")
		(net "M_B_CPU1_SA_DQ<22>")
	)
	(segment
		(start 58.806588 -222.899986)
		(end 58.951368 -223.044766)
		(width 0.14478)
		(layer "In13.Cu")
		(net "M_B_CPU1_SA_DQ<22>")
	)
	(segment
		(start 78.206346 -238.440722)
		(end 78.41107 -238.440722)
		(width 0.0889)
		(layer "In13.Cu")
		(net "M_B_CPU1_SA_DQ<22>")
	)
	(segment
		(start 79.539592 -238.49203)
		(end 79.561182 -238.504476)
		(width 0.0889)
		(layer "In13.Cu")
		(net "M_B_CPU1_SA_DQ<22>")
	)
	(segment
		(start 56.195468 -223.044766)
		(end 56.340248 -222.899986)
		(width 0.14478)
		(layer "In13.Cu")
		(net "M_B_CPU1_SA_DQ<22>")
	)
	(segment
		(start 50.222404 -222.410274)
		(end 53.256434 -222.410274)
		(width 0.14478)
		(layer "In13.Cu")
		(net "M_B_CPU1_SA_DQ<22>")
	)
	(segment
		(start 84.229702 -238.48695)
		(end 84.238084 -238.491776)
		(width 0.0889)
		(layer "In13.Cu")
		(net "M_B_CPU1_SA_DQ<22>")
	)
	(segment
		(start 58.400188 -223.115632)
		(end 58.400188 -223.044766)
		(width 0.14478)
		(layer "In13.Cu")
		(net "M_B_CPU1_SA_DQ<22>")
	)
	(segment
		(start 57.849008 -223.115632)
		(end 57.993788 -223.260412)
		(width 0.14478)
		(layer "In13.Cu")
		(net "M_B_CPU1_SA_DQ<22>")
	)
	(segment
		(start 75.96378 -236.953298)
		(end 76.139802 -236.953298)
		(width 0.0889)
		(layer "In13.Cu")
		(net "M_B_CPU1_SA_DQ<22>")
	)
	(arc
		(start 81.418176 -238.491776)
		(mid 81.701132 -238.567953)
		(end 81.984088 -238.491776)
		(width 0.0889)
		(layer "In13.Cu")
		(net "M_B_CPU1_SA_DQ<22>")
	)
	(arc
		(start 81.052416 -238.48695)
		(mid 81.235924 -238.441456)
		(end 81.418176 -238.491776)
		(width 0.0889)
		(layer "In13.Cu")
		(net "M_B_CPU1_SA_DQ<22>")
	)
	(arc
		(start 80.478122 -238.491776)
		(mid 80.761078 -238.567953)
		(end 81.044034 -238.491776)
		(width 0.0889)
		(layer "In13.Cu")
		(net "M_B_CPU1_SA_DQ<22>")
	)
	(arc
		(start 83.29803 -238.491776)
		(mid 83.580986 -238.567953)
		(end 83.863942 -238.491776)
		(width 0.0889)
		(layer "In13.Cu")
		(net "M_B_CPU1_SA_DQ<22>")
	)
	(arc
		(start 85.752432 -238.48695)
		(mid 85.93594 -238.441456)
		(end 86.118192 -238.491776)
		(width 0.0889)
		(layer "In13.Cu")
		(net "M_B_CPU1_SA_DQ<22>")
	)
	(arc
		(start 82.923888 -238.491776)
		(mid 83.106139 -238.441426)
		(end 83.289648 -238.48695)
		(width 0.0889)
		(layer "In13.Cu")
		(net "M_B_CPU1_SA_DQ<22>")
	)
	(arc
		(start 81.984088 -238.491776)
		(mid 82.171032 -238.441521)
		(end 82.357976 -238.491776)
		(width 0.0889)
		(layer "In13.Cu")
		(net "M_B_CPU1_SA_DQ<22>")
	)
	(arc
		(start 79.561182 -238.504476)
		(mid 79.834211 -238.567795)
		(end 80.10398 -238.491776)
		(width 0.0889)
		(layer "In13.Cu")
		(net "M_B_CPU1_SA_DQ<22>")
	)
	(arc
		(start 79.166466 -238.491776)
		(mid 79.342586 -238.441798)
		(end 79.521304 -238.481616)
		(width 0.0889)
		(layer "In13.Cu")
		(net "M_B_CPU1_SA_DQ<22>")
	)
	(arc
		(start 80.10398 -238.491776)
		(mid 80.286231 -238.441426)
		(end 80.46974 -238.48695)
		(width 0.0889)
		(layer "In13.Cu")
		(net "M_B_CPU1_SA_DQ<22>")
	)
	(arc
		(start 82.357976 -238.491776)
		(mid 82.640932 -238.567953)
		(end 82.923888 -238.491776)
		(width 0.0889)
		(layer "In13.Cu")
		(net "M_B_CPU1_SA_DQ<22>")
	)
	(arc
		(start 85.178138 -238.491776)
		(mid 85.461094 -238.567953)
		(end 85.74405 -238.491776)
		(width 0.0889)
		(layer "In13.Cu")
		(net "M_B_CPU1_SA_DQ<22>")
	)
	(arc
		(start 86.118192 -238.491776)
		(mid 86.401148 -238.567953)
		(end 86.684104 -238.491776)
		(width 0.0889)
		(layer "In13.Cu")
		(net "M_B_CPU1_SA_DQ<22>")
	)
	(arc
		(start 78.41107 -238.440722)
		(mid 78.508573 -238.453737)
		(end 78.599284 -238.491776)
		(width 0.0889)
		(layer "In13.Cu")
		(net "M_B_CPU1_SA_DQ<22>")
	)
	(arc
		(start 78.599284 -238.491776)
		(mid 78.869441 -238.568538)
		(end 79.143098 -238.505492)
		(width 0.0889)
		(layer "In13.Cu")
		(net "M_B_CPU1_SA_DQ<22>")
	)
	(arc
		(start 86.684104 -238.491776)
		(mid 86.871048 -238.441521)
		(end 87.057992 -238.491776)
		(width 0.0889)
		(layer "In13.Cu")
		(net "M_B_CPU1_SA_DQ<22>")
	)
	(arc
		(start 84.812378 -238.48695)
		(mid 84.995886 -238.441456)
		(end 85.178138 -238.491776)
		(width 0.0889)
		(layer "In13.Cu")
		(net "M_B_CPU1_SA_DQ<22>")
	)
	(arc
		(start 84.238084 -238.491776)
		(mid 84.52104 -238.567953)
		(end 84.803996 -238.491776)
		(width 0.0889)
		(layer "In13.Cu")
		(net "M_B_CPU1_SA_DQ<22>")
	)
	(arc
		(start 87.057992 -238.491776)
		(mid 87.305588 -238.566954)
		(end 87.560658 -238.523526)
		(width 0.0889)
		(layer "In13.Cu")
		(net "M_B_CPU1_SA_DQ<22>")
	)
	(arc
		(start 83.863942 -238.491776)
		(mid 84.046193 -238.441426)
		(end 84.229702 -238.48695)
		(width 0.0889)
		(layer "In13.Cu")
		(net "M_B_CPU1_SA_DQ<22>")
	)
	(segment
		(start 89.218008 -239.080294)
		(end 88.751156 -238.814356)
		(width 0.10668)
		(layer "F.Cu")
		(net "M_B_CPU1_SA_DQ<21>")
	)
	(segment
		(start 55.244746 -224.110296)
		(end 56.21782 -224.110296)
		(width 0.14478)
		(layer "In13.Cu")
		(net "M_B_CPU1_SA_DQ<21>")
	)
	(segment
		(start 52.721256 -223.04248)
		(end 52.982876 -223.04248)
		(width 0.14478)
		(layer "In13.Cu")
		(net "M_B_CPU1_SA_DQ<21>")
	)
	(segment
		(start 79.538068 -239.136936)
		(end 79.537814 -239.136936)
		(width 0.0889)
		(layer "In13.Cu")
		(net "M_B_CPU1_SA_DQ<21>")
	)
	(segment
		(start 54.693566 -224.473262)
		(end 54.955186 -224.473262)
		(width 0.14478)
		(layer "In13.Cu")
		(net "M_B_CPU1_SA_DQ<21>")
	)
	(segment
		(start 52.431696 -223.660716)
		(end 52.576476 -223.515936)
		(width 0.14478)
		(layer "In13.Cu")
		(net "M_B_CPU1_SA_DQ<21>")
	)
	(segment
		(start 78.546706 -239.188244)
		(end 78.598014 -239.136936)
		(width 0.0889)
		(layer "In13.Cu")
		(net "M_B_CPU1_SA_DQ<21>")
	)
	(segment
		(start 52.576476 -223.515936)
		(end 52.576476 -223.18726)
		(width 0.14478)
		(layer "In13.Cu")
		(net "M_B_CPU1_SA_DQ<21>")
	)
	(segment
		(start 80.46974 -239.141762)
		(end 80.478122 -239.136936)
		(width 0.0889)
		(layer "In13.Cu")
		(net "M_B_CPU1_SA_DQ<21>")
	)
	(segment
		(start 88.882728 -239.163098)
		(end 88.90508 -239.079786)
		(width 0.0889)
		(layer "In13.Cu")
		(net "M_B_CPU1_SA_DQ<21>")
	)
	(segment
		(start 51.884072 -223.685354)
		(end 51.90871 -223.660716)
		(width 0.14478)
		(layer "In13.Cu")
		(net "M_B_CPU1_SA_DQ<21>")
	)
	(segment
		(start 77.95641 -238.558832)
		(end 77.95641 -238.747046)
		(width 0.0889)
		(layer "In13.Cu")
		(net "M_B_CPU1_SA_DQ<21>")
	)
	(segment
		(start 58.449972 -224.465134)
		(end 58.711592 -224.465134)
		(width 0.14478)
		(layer "In13.Cu")
		(net "M_B_CPU1_SA_DQ<21>")
	)
	(segment
		(start 58.856372 -223.868234)
		(end 59.001152 -223.723454)
		(width 0.14478)
		(layer "In13.Cu")
		(net "M_B_CPU1_SA_DQ<21>")
	)
	(segment
		(start 55.099966 -224.328482)
		(end 55.099966 -224.255076)
		(width 0.14478)
		(layer "In13.Cu")
		(net "M_B_CPU1_SA_DQ<21>")
	)
	(segment
		(start 68.737226 -234.276646)
		(end 71.868538 -237.407958)
		(width 0.14478)
		(layer "In13.Cu")
		(net "M_B_CPU1_SA_DQ<21>")
	)
	(segment
		(start 75.9333 -237.407958)
		(end 76.099162 -237.407958)
		(width 0.0889)
		(layer "In13.Cu")
		(net "M_B_CPU1_SA_DQ<21>")
	)
	(segment
		(start 53.634894 -223.660716)
		(end 54.084474 -224.110296)
		(width 0.14478)
		(layer "In13.Cu")
		(net "M_B_CPU1_SA_DQ<21>")
	)
	(segment
		(start 76.099162 -237.407958)
		(end 76.24953 -237.558326)
		(width 0.0889)
		(layer "In13.Cu")
		(net "M_B_CPU1_SA_DQ<21>")
	)
	(segment
		(start 52.576476 -223.18726)
		(end 52.721256 -223.04248)
		(width 0.14478)
		(layer "In13.Cu")
		(net "M_B_CPU1_SA_DQ<21>")
	)
	(segment
		(start 56.604662 -223.723454)
		(end 57.058052 -223.723454)
		(width 0.14478)
		(layer "In13.Cu")
		(net "M_B_CPU1_SA_DQ<21>")
	)
	(segment
		(start 51.90871 -223.660716)
		(end 52.431696 -223.660716)
		(width 0.14478)
		(layer "In13.Cu")
		(net "M_B_CPU1_SA_DQ<21>")
	)
	(segment
		(start 84.229702 -239.141762)
		(end 84.238084 -239.136936)
		(width 0.0889)
		(layer "In13.Cu")
		(net "M_B_CPU1_SA_DQ<21>")
	)
	(segment
		(start 76.24953 -237.558326)
		(end 76.955904 -237.558326)
		(width 0.0889)
		(layer "In13.Cu")
		(net "M_B_CPU1_SA_DQ<21>")
	)
	(segment
		(start 68.737226 -233.054144)
		(end 68.737226 -234.276646)
		(width 0.14478)
		(layer "In13.Cu")
		(net "M_B_CPU1_SA_DQ<21>")
	)
	(segment
		(start 58.305192 -223.868234)
		(end 58.305192 -224.320354)
		(width 0.14478)
		(layer "In13.Cu")
		(net "M_B_CPU1_SA_DQ<21>")
	)
	(segment
		(start 79.529686 -239.141762)
		(end 79.538068 -239.136936)
		(width 0.0889)
		(layer "In13.Cu")
		(net "M_B_CPU1_SA_DQ<21>")
	)
	(segment
		(start 58.305192 -224.320354)
		(end 58.449972 -224.465134)
		(width 0.14478)
		(layer "In13.Cu")
		(net "M_B_CPU1_SA_DQ<21>")
	)
	(segment
		(start 57.202832 -223.868234)
		(end 57.202832 -224.320354)
		(width 0.14478)
		(layer "In13.Cu")
		(net "M_B_CPU1_SA_DQ<21>")
	)
	(segment
		(start 57.202832 -224.320354)
		(end 57.347612 -224.465134)
		(width 0.14478)
		(layer "In13.Cu")
		(net "M_B_CPU1_SA_DQ<21>")
	)
	(segment
		(start 57.754012 -223.868234)
		(end 57.898792 -223.723454)
		(width 0.14478)
		(layer "In13.Cu")
		(net "M_B_CPU1_SA_DQ<21>")
	)
	(segment
		(start 54.548786 -224.255076)
		(end 54.548786 -224.328482)
		(width 0.14478)
		(layer "In13.Cu")
		(net "M_B_CPU1_SA_DQ<21>")
	)
	(segment
		(start 54.548786 -224.328482)
		(end 54.693566 -224.473262)
		(width 0.14478)
		(layer "In13.Cu")
		(net "M_B_CPU1_SA_DQ<21>")
	)
	(segment
		(start 76.955904 -237.558326)
		(end 77.95641 -238.558832)
		(width 0.0889)
		(layer "In13.Cu")
		(net "M_B_CPU1_SA_DQ<21>")
	)
	(segment
		(start 53.272436 -223.660716)
		(end 53.634894 -223.660716)
		(width 0.14478)
		(layer "In13.Cu")
		(net "M_B_CPU1_SA_DQ<21>")
	)
	(segment
		(start 58.711592 -224.465134)
		(end 58.856372 -224.320354)
		(width 0.14478)
		(layer "In13.Cu")
		(net "M_B_CPU1_SA_DQ<21>")
	)
	(segment
		(start 71.868538 -237.407958)
		(end 75.9333 -237.407958)
		(width 0.14478)
		(layer "In13.Cu")
		(net "M_B_CPU1_SA_DQ<21>")
	)
	(segment
		(start 58.856372 -224.320354)
		(end 58.856372 -223.868234)
		(width 0.14478)
		(layer "In13.Cu")
		(net "M_B_CPU1_SA_DQ<21>")
	)
	(segment
		(start 81.044034 -239.136936)
		(end 81.052416 -239.141762)
		(width 0.0889)
		(layer "In13.Cu")
		(net "M_B_CPU1_SA_DQ<21>")
	)
	(segment
		(start 54.404006 -224.110296)
		(end 54.548786 -224.255076)
		(width 0.14478)
		(layer "In13.Cu")
		(net "M_B_CPU1_SA_DQ<21>")
	)
	(segment
		(start 57.754012 -224.320354)
		(end 57.754012 -223.868234)
		(width 0.14478)
		(layer "In13.Cu")
		(net "M_B_CPU1_SA_DQ<21>")
	)
	(segment
		(start 57.609232 -224.465134)
		(end 57.754012 -224.320354)
		(width 0.14478)
		(layer "In13.Cu")
		(net "M_B_CPU1_SA_DQ<21>")
	)
	(segment
		(start 80.093566 -239.13084)
		(end 80.10398 -239.136936)
		(width 0.0889)
		(layer "In13.Cu")
		(net "M_B_CPU1_SA_DQ<21>")
	)
	(segment
		(start 53.127656 -223.18726)
		(end 53.127656 -223.515936)
		(width 0.14478)
		(layer "In13.Cu")
		(net "M_B_CPU1_SA_DQ<21>")
	)
	(segment
		(start 88.90508 -239.079786)
		(end 88.751156 -238.814356)
		(width 0.0889)
		(layer "In13.Cu")
		(net "M_B_CPU1_SA_DQ<21>")
	)
	(segment
		(start 78.397608 -239.188244)
		(end 78.546706 -239.188244)
		(width 0.0889)
		(layer "In13.Cu")
		(net "M_B_CPU1_SA_DQ<21>")
	)
	(segment
		(start 57.898792 -223.723454)
		(end 58.160412 -223.723454)
		(width 0.14478)
		(layer "In13.Cu")
		(net "M_B_CPU1_SA_DQ<21>")
	)
	(segment
		(start 56.21782 -224.110296)
		(end 56.604662 -223.723454)
		(width 0.14478)
		(layer "In13.Cu")
		(net "M_B_CPU1_SA_DQ<21>")
	)
	(segment
		(start 87.989664 -239.141762)
		(end 87.998046 -239.136936)
		(width 0.0889)
		(layer "In13.Cu")
		(net "M_B_CPU1_SA_DQ<21>")
	)
	(segment
		(start 54.955186 -224.473262)
		(end 55.099966 -224.328482)
		(width 0.14478)
		(layer "In13.Cu")
		(net "M_B_CPU1_SA_DQ<21>")
	)
	(segment
		(start 85.74405 -239.136936)
		(end 85.752432 -239.141762)
		(width 0.0889)
		(layer "In13.Cu")
		(net "M_B_CPU1_SA_DQ<21>")
	)
	(segment
		(start 55.099966 -224.255076)
		(end 55.244746 -224.110296)
		(width 0.14478)
		(layer "In13.Cu")
		(net "M_B_CPU1_SA_DQ<21>")
	)
	(segment
		(start 84.803996 -239.136936)
		(end 84.812378 -239.141762)
		(width 0.0889)
		(layer "In13.Cu")
		(net "M_B_CPU1_SA_DQ<21>")
	)
	(segment
		(start 59.001152 -223.723454)
		(end 59.406536 -223.723454)
		(width 0.14478)
		(layer "In13.Cu")
		(net "M_B_CPU1_SA_DQ<21>")
	)
	(segment
		(start 58.160412 -223.723454)
		(end 58.305192 -223.868234)
		(width 0.14478)
		(layer "In13.Cu")
		(net "M_B_CPU1_SA_DQ<21>")
	)
	(segment
		(start 54.084474 -224.110296)
		(end 54.404006 -224.110296)
		(width 0.14478)
		(layer "In13.Cu")
		(net "M_B_CPU1_SA_DQ<21>")
	)
	(segment
		(start 57.058052 -223.723454)
		(end 57.202832 -223.868234)
		(width 0.14478)
		(layer "In13.Cu")
		(net "M_B_CPU1_SA_DQ<21>")
	)
	(segment
		(start 57.347612 -224.465134)
		(end 57.609232 -224.465134)
		(width 0.14478)
		(layer "In13.Cu")
		(net "M_B_CPU1_SA_DQ<21>")
	)
	(segment
		(start 52.982876 -223.04248)
		(end 53.127656 -223.18726)
		(width 0.14478)
		(layer "In13.Cu")
		(net "M_B_CPU1_SA_DQ<21>")
	)
	(segment
		(start 83.289648 -239.141762)
		(end 83.29803 -239.136936)
		(width 0.0889)
		(layer "In13.Cu")
		(net "M_B_CPU1_SA_DQ<21>")
	)
	(segment
		(start 53.127656 -223.515936)
		(end 53.272436 -223.660716)
		(width 0.14478)
		(layer "In13.Cu")
		(net "M_B_CPU1_SA_DQ<21>")
	)
	(segment
		(start 59.406536 -223.723454)
		(end 68.737226 -233.054144)
		(width 0.14478)
		(layer "In13.Cu")
		(net "M_B_CPU1_SA_DQ<21>")
	)
	(arc
		(start 86.684104 -239.136936)
		(mid 86.871048 -239.187191)
		(end 87.057992 -239.136936)
		(width 0.0889)
		(layer "In13.Cu")
		(net "M_B_CPU1_SA_DQ<21>")
	)
	(arc
		(start 81.984088 -239.136936)
		(mid 82.171032 -239.187191)
		(end 82.357976 -239.136936)
		(width 0.0889)
		(layer "In13.Cu")
		(net "M_B_CPU1_SA_DQ<21>")
	)
	(arc
		(start 86.118192 -239.136936)
		(mid 86.401148 -239.060759)
		(end 86.684104 -239.136936)
		(width 0.0889)
		(layer "In13.Cu")
		(net "M_B_CPU1_SA_DQ<21>")
	)
	(arc
		(start 87.057992 -239.136936)
		(mid 87.340948 -239.060759)
		(end 87.623904 -239.136936)
		(width 0.0889)
		(layer "In13.Cu")
		(net "M_B_CPU1_SA_DQ<21>")
	)
	(arc
		(start 84.238084 -239.136936)
		(mid 84.52104 -239.060759)
		(end 84.803996 -239.136936)
		(width 0.0889)
		(layer "In13.Cu")
		(net "M_B_CPU1_SA_DQ<21>")
	)
	(arc
		(start 87.998046 -239.136936)
		(mid 88.281002 -239.060759)
		(end 88.563958 -239.136936)
		(width 0.0889)
		(layer "In13.Cu")
		(net "M_B_CPU1_SA_DQ<21>")
	)
	(arc
		(start 85.178138 -239.136936)
		(mid 85.461094 -239.060759)
		(end 85.74405 -239.136936)
		(width 0.0889)
		(layer "In13.Cu")
		(net "M_B_CPU1_SA_DQ<21>")
	)
	(arc
		(start 85.752432 -239.141762)
		(mid 85.93594 -239.187256)
		(end 86.118192 -239.136936)
		(width 0.0889)
		(layer "In13.Cu")
		(net "M_B_CPU1_SA_DQ<21>")
	)
	(arc
		(start 83.863942 -239.136936)
		(mid 84.046193 -239.187286)
		(end 84.229702 -239.141762)
		(width 0.0889)
		(layer "In13.Cu")
		(net "M_B_CPU1_SA_DQ<21>")
	)
	(arc
		(start 84.812378 -239.141762)
		(mid 84.995886 -239.187256)
		(end 85.178138 -239.136936)
		(width 0.0889)
		(layer "In13.Cu")
		(net "M_B_CPU1_SA_DQ<21>")
	)
	(arc
		(start 79.537814 -239.136936)
		(mid 79.814881 -239.060665)
		(end 80.093566 -239.13084)
		(width 0.0889)
		(layer "In13.Cu")
		(net "M_B_CPU1_SA_DQ<21>")
	)
	(arc
		(start 82.357976 -239.136936)
		(mid 82.640932 -239.060759)
		(end 82.923888 -239.136936)
		(width 0.0889)
		(layer "In13.Cu")
		(net "M_B_CPU1_SA_DQ<21>")
	)
	(arc
		(start 82.923888 -239.136936)
		(mid 83.106139 -239.187286)
		(end 83.289648 -239.141762)
		(width 0.0889)
		(layer "In13.Cu")
		(net "M_B_CPU1_SA_DQ<21>")
	)
	(arc
		(start 80.10398 -239.136936)
		(mid 80.286231 -239.187286)
		(end 80.46974 -239.141762)
		(width 0.0889)
		(layer "In13.Cu")
		(net "M_B_CPU1_SA_DQ<21>")
	)
	(arc
		(start 87.623904 -239.136936)
		(mid 87.806155 -239.187286)
		(end 87.989664 -239.141762)
		(width 0.0889)
		(layer "In13.Cu")
		(net "M_B_CPU1_SA_DQ<21>")
	)
	(arc
		(start 79.163926 -239.136936)
		(mid 79.346177 -239.187286)
		(end 79.529686 -239.141762)
		(width 0.0889)
		(layer "In13.Cu")
		(net "M_B_CPU1_SA_DQ<21>")
	)
	(arc
		(start 83.29803 -239.136936)
		(mid 83.580986 -239.060759)
		(end 83.863942 -239.136936)
		(width 0.0889)
		(layer "In13.Cu")
		(net "M_B_CPU1_SA_DQ<21>")
	)
	(arc
		(start 81.052416 -239.141762)
		(mid 81.235924 -239.187256)
		(end 81.418176 -239.136936)
		(width 0.0889)
		(layer "In13.Cu")
		(net "M_B_CPU1_SA_DQ<21>")
	)
	(arc
		(start 77.95641 -238.747046)
		(mid 78.085634 -239.05902)
		(end 78.397608 -239.188244)
		(width 0.0889)
		(layer "In13.Cu")
		(net "M_B_CPU1_SA_DQ<21>")
	)
	(arc
		(start 78.598014 -239.136936)
		(mid 78.88097 -239.060759)
		(end 79.163926 -239.136936)
		(width 0.0889)
		(layer "In13.Cu")
		(net "M_B_CPU1_SA_DQ<21>")
	)
	(arc
		(start 81.418176 -239.136936)
		(mid 81.701132 -239.060759)
		(end 81.984088 -239.136936)
		(width 0.0889)
		(layer "In13.Cu")
		(net "M_B_CPU1_SA_DQ<21>")
	)
	(arc
		(start 88.563958 -239.136936)
		(mid 88.720396 -239.185907)
		(end 88.882728 -239.163098)
		(width 0.0889)
		(layer "In13.Cu")
		(net "M_B_CPU1_SA_DQ<21>")
	)
	(arc
		(start 80.478122 -239.136936)
		(mid 80.761078 -239.060759)
		(end 81.044034 -239.136936)
		(width 0.0889)
		(layer "In13.Cu")
		(net "M_B_CPU1_SA_DQ<21>")
	)
	(segment
		(start 87.8078 -238.270288)
		(end 87.340948 -238.00435)
		(width 0.10668)
		(layer "F.Cu")
		(net "M_B_CPU1_SA_DQ<20>")
	)
	(segment
		(start 76.139802 -236.498638)
		(end 76.66355 -237.022386)
		(width 0.0889)
		(layer "In13.Cu")
		(net "M_B_CPU1_SA_DQ<20>")
	)
	(segment
		(start 69.723762 -233.76255)
		(end 69.723762 -233.990642)
		(width 0.14478)
		(layer "In13.Cu")
		(net "M_B_CPU1_SA_DQ<20>")
	)
	(segment
		(start 54.015894 -222.419926)
		(end 54.909466 -222.419926)
		(width 0.14478)
		(layer "In13.Cu")
		(net "M_B_CPU1_SA_DQ<20>")
	)
	(segment
		(start 73.065894 -236.11078)
		(end 73.453752 -236.498638)
		(width 0.14478)
		(layer "In13.Cu")
		(net "M_B_CPU1_SA_DQ<20>")
	)
	(segment
		(start 82.453988 -238.32693)
		(end 82.46237 -238.331756)
		(width 0.0889)
		(layer "In13.Cu")
		(net "M_B_CPU1_SA_DQ<20>")
	)
	(segment
		(start 52.251864 -221.570042)
		(end 53.16601 -221.570042)
		(width 0.14478)
		(layer "In13.Cu")
		(net "M_B_CPU1_SA_DQ<20>")
	)
	(segment
		(start 55.750206 -222.419926)
		(end 59.70397 -222.419926)
		(width 0.14478)
		(layer "In13.Cu")
		(net "M_B_CPU1_SA_DQ<20>")
	)
	(segment
		(start 59.70397 -222.419926)
		(end 59.88431 -222.600266)
		(width 0.14478)
		(layer "In13.Cu")
		(net "M_B_CPU1_SA_DQ<20>")
	)
	(segment
		(start 71.66737 -234.712256)
		(end 71.66737 -234.940094)
		(width 0.14478)
		(layer "In13.Cu")
		(net "M_B_CPU1_SA_DQ<20>")
	)
	(segment
		(start 70.106794 -233.15168)
		(end 70.106794 -233.379518)
		(width 0.14478)
		(layer "In13.Cu")
		(net "M_B_CPU1_SA_DQ<20>")
	)
	(segment
		(start 55.199026 -222.80245)
		(end 55.460646 -222.80245)
		(width 0.14478)
		(layer "In13.Cu")
		(net "M_B_CPU1_SA_DQ<20>")
	)
	(segment
		(start 81.879694 -238.331756)
		(end 81.888076 -238.32693)
		(width 0.0889)
		(layer "In13.Cu")
		(net "M_B_CPU1_SA_DQ<20>")
	)
	(segment
		(start 72.455024 -236.493558)
		(end 72.837802 -236.11078)
		(width 0.14478)
		(layer "In13.Cu")
		(net "M_B_CPU1_SA_DQ<20>")
	)
	(segment
		(start 72.064626 -236.103414)
		(end 72.064626 -236.331506)
		(width 0.14478)
		(layer "In13.Cu")
		(net "M_B_CPU1_SA_DQ<20>")
	)
	(segment
		(start 72.837802 -236.11078)
		(end 73.065894 -236.11078)
		(width 0.14478)
		(layer "In13.Cu")
		(net "M_B_CPU1_SA_DQ<20>")
	)
	(segment
		(start 72.447658 -235.720382)
		(end 72.064626 -236.103414)
		(width 0.14478)
		(layer "In13.Cu")
		(net "M_B_CPU1_SA_DQ<20>")
	)
	(segment
		(start 70.666102 -234.932982)
		(end 70.894448 -234.932982)
		(width 0.14478)
		(layer "In13.Cu")
		(net "M_B_CPU1_SA_DQ<20>")
	)
	(segment
		(start 71.284338 -235.323126)
		(end 71.284338 -235.551218)
		(width 0.14478)
		(layer "In13.Cu")
		(net "M_B_CPU1_SA_DQ<20>")
	)
	(segment
		(start 59.88431 -222.929196)
		(end 70.106794 -233.15168)
		(width 0.14478)
		(layer "In13.Cu")
		(net "M_B_CPU1_SA_DQ<20>")
	)
	(segment
		(start 75.95743 -236.498638)
		(end 76.139802 -236.498638)
		(width 0.0889)
		(layer "In13.Cu")
		(net "M_B_CPU1_SA_DQ<20>")
	)
	(segment
		(start 87.154004 -238.32693)
		(end 87.162386 -238.331756)
		(width 0.0889)
		(layer "In13.Cu")
		(net "M_B_CPU1_SA_DQ<20>")
	)
	(segment
		(start 55.605426 -222.564706)
		(end 55.750206 -222.419926)
		(width 0.14478)
		(layer "In13.Cu")
		(net "M_B_CPU1_SA_DQ<20>")
	)
	(segment
		(start 86.57971 -238.331756)
		(end 86.588092 -238.32693)
		(width 0.0889)
		(layer "In13.Cu")
		(net "M_B_CPU1_SA_DQ<20>")
	)
	(segment
		(start 69.885814 -234.152694)
		(end 70.11416 -234.152694)
		(width 0.14478)
		(layer "In13.Cu")
		(net "M_B_CPU1_SA_DQ<20>")
	)
	(segment
		(start 70.887082 -233.931968)
		(end 70.887082 -234.159806)
		(width 0.14478)
		(layer "In13.Cu")
		(net "M_B_CPU1_SA_DQ<20>")
	)
	(segment
		(start 70.496938 -233.769916)
		(end 70.72503 -233.769916)
		(width 0.14478)
		(layer "In13.Cu")
		(net "M_B_CPU1_SA_DQ<20>")
	)
	(segment
		(start 70.106794 -233.379518)
		(end 69.723762 -233.76255)
		(width 0.14478)
		(layer "In13.Cu")
		(net "M_B_CPU1_SA_DQ<20>")
	)
	(segment
		(start 55.460646 -222.80245)
		(end 55.605426 -222.65767)
		(width 0.14478)
		(layer "In13.Cu")
		(net "M_B_CPU1_SA_DQ<20>")
	)
	(segment
		(start 87.495126 -238.26978)
		(end 87.340948 -238.00435)
		(width 0.0889)
		(layer "In13.Cu")
		(net "M_B_CPU1_SA_DQ<20>")
	)
	(segment
		(start 83.394042 -238.32693)
		(end 83.402424 -238.331756)
		(width 0.0889)
		(layer "In13.Cu")
		(net "M_B_CPU1_SA_DQ<20>")
	)
	(segment
		(start 70.50405 -234.542838)
		(end 70.50405 -234.77093)
		(width 0.14478)
		(layer "In13.Cu")
		(net "M_B_CPU1_SA_DQ<20>")
	)
	(segment
		(start 71.277226 -234.550204)
		(end 71.505318 -234.550204)
		(width 0.14478)
		(layer "In13.Cu")
		(net "M_B_CPU1_SA_DQ<20>")
	)
	(segment
		(start 72.226678 -236.493558)
		(end 72.455024 -236.493558)
		(width 0.14478)
		(layer "In13.Cu")
		(net "M_B_CPU1_SA_DQ<20>")
	)
	(segment
		(start 71.284338 -235.551218)
		(end 71.44639 -235.71327)
		(width 0.14478)
		(layer "In13.Cu")
		(net "M_B_CPU1_SA_DQ<20>")
	)
	(segment
		(start 70.11416 -234.152694)
		(end 70.496938 -233.769916)
		(width 0.14478)
		(layer "In13.Cu")
		(net "M_B_CPU1_SA_DQ<20>")
	)
	(segment
		(start 72.057514 -235.330492)
		(end 72.285606 -235.330492)
		(width 0.14478)
		(layer "In13.Cu")
		(net "M_B_CPU1_SA_DQ<20>")
	)
	(segment
		(start 87.472774 -238.353092)
		(end 87.495126 -238.26978)
		(width 0.0889)
		(layer "In13.Cu")
		(net "M_B_CPU1_SA_DQ<20>")
	)
	(segment
		(start 76.66355 -237.022386)
		(end 77.057504 -237.022386)
		(width 0.0889)
		(layer "In13.Cu")
		(net "M_B_CPU1_SA_DQ<20>")
	)
	(segment
		(start 55.605426 -222.65767)
		(end 55.605426 -222.564706)
		(width 0.14478)
		(layer "In13.Cu")
		(net "M_B_CPU1_SA_DQ<20>")
	)
	(segment
		(start 70.72503 -233.769916)
		(end 70.887082 -233.931968)
		(width 0.14478)
		(layer "In13.Cu")
		(net "M_B_CPU1_SA_DQ<20>")
	)
	(segment
		(start 79.634842 -238.326676)
		(end 79.654908 -238.338106)
		(width 0.0889)
		(layer "In13.Cu")
		(net "M_B_CPU1_SA_DQ<20>")
	)
	(segment
		(start 70.887082 -234.159806)
		(end 70.50405 -234.542838)
		(width 0.14478)
		(layer "In13.Cu")
		(net "M_B_CPU1_SA_DQ<20>")
	)
	(segment
		(start 79.051658 -238.337852)
		(end 79.070454 -238.32693)
		(width 0.0889)
		(layer "In13.Cu")
		(net "M_B_CPU1_SA_DQ<20>")
	)
	(segment
		(start 71.505318 -234.550204)
		(end 71.66737 -234.712256)
		(width 0.14478)
		(layer "In13.Cu")
		(net "M_B_CPU1_SA_DQ<20>")
	)
	(segment
		(start 55.054246 -222.65767)
		(end 55.199026 -222.80245)
		(width 0.14478)
		(layer "In13.Cu")
		(net "M_B_CPU1_SA_DQ<20>")
	)
	(segment
		(start 85.639656 -238.331756)
		(end 85.648038 -238.32693)
		(width 0.0889)
		(layer "In13.Cu")
		(net "M_B_CPU1_SA_DQ<20>")
	)
	(segment
		(start 69.723762 -233.990642)
		(end 69.885814 -234.152694)
		(width 0.14478)
		(layer "In13.Cu")
		(net "M_B_CPU1_SA_DQ<20>")
	)
	(segment
		(start 77.057504 -237.022386)
		(end 78.28534 -238.250222)
		(width 0.0889)
		(layer "In13.Cu")
		(net "M_B_CPU1_SA_DQ<20>")
	)
	(segment
		(start 59.88431 -222.600266)
		(end 59.88431 -222.929196)
		(width 0.14478)
		(layer "In13.Cu")
		(net "M_B_CPU1_SA_DQ<20>")
	)
	(segment
		(start 71.66737 -234.940094)
		(end 71.284338 -235.323126)
		(width 0.14478)
		(layer "In13.Cu")
		(net "M_B_CPU1_SA_DQ<20>")
	)
	(segment
		(start 70.894448 -234.932982)
		(end 71.277226 -234.550204)
		(width 0.14478)
		(layer "In13.Cu")
		(net "M_B_CPU1_SA_DQ<20>")
	)
	(segment
		(start 54.909466 -222.419926)
		(end 55.054246 -222.564706)
		(width 0.14478)
		(layer "In13.Cu")
		(net "M_B_CPU1_SA_DQ<20>")
	)
	(segment
		(start 79.613252 -238.31423)
		(end 79.634842 -238.326676)
		(width 0.0889)
		(layer "In13.Cu")
		(net "M_B_CPU1_SA_DQ<20>")
	)
	(segment
		(start 51.884072 -221.937834)
		(end 52.251864 -221.570042)
		(width 0.14478)
		(layer "In13.Cu")
		(net "M_B_CPU1_SA_DQ<20>")
	)
	(segment
		(start 72.285606 -235.330492)
		(end 72.447658 -235.492544)
		(width 0.14478)
		(layer "In13.Cu")
		(net "M_B_CPU1_SA_DQ<20>")
	)
	(segment
		(start 78.28534 -238.250222)
		(end 78.41107 -238.250222)
		(width 0.0889)
		(layer "In13.Cu")
		(net "M_B_CPU1_SA_DQ<20>")
	)
	(segment
		(start 51.884072 -221.985332)
		(end 51.884072 -221.937834)
		(width 0.14478)
		(layer "In13.Cu")
		(net "M_B_CPU1_SA_DQ<20>")
	)
	(segment
		(start 71.674736 -235.71327)
		(end 72.057514 -235.330492)
		(width 0.14478)
		(layer "In13.Cu")
		(net "M_B_CPU1_SA_DQ<20>")
	)
	(segment
		(start 72.447658 -235.492544)
		(end 72.447658 -235.720382)
		(width 0.14478)
		(layer "In13.Cu")
		(net "M_B_CPU1_SA_DQ<20>")
	)
	(segment
		(start 71.44639 -235.71327)
		(end 71.674736 -235.71327)
		(width 0.14478)
		(layer "In13.Cu")
		(net "M_B_CPU1_SA_DQ<20>")
	)
	(segment
		(start 53.16601 -221.570042)
		(end 54.015894 -222.419926)
		(width 0.14478)
		(layer "In13.Cu")
		(net "M_B_CPU1_SA_DQ<20>")
	)
	(segment
		(start 55.054246 -222.564706)
		(end 55.054246 -222.65767)
		(width 0.14478)
		(layer "In13.Cu")
		(net "M_B_CPU1_SA_DQ<20>")
	)
	(segment
		(start 70.50405 -234.77093)
		(end 70.666102 -234.932982)
		(width 0.14478)
		(layer "In13.Cu")
		(net "M_B_CPU1_SA_DQ<20>")
	)
	(segment
		(start 73.453752 -236.498638)
		(end 75.95743 -236.498638)
		(width 0.14478)
		(layer "In13.Cu")
		(net "M_B_CPU1_SA_DQ<20>")
	)
	(segment
		(start 72.064626 -236.331506)
		(end 72.226678 -236.493558)
		(width 0.14478)
		(layer "In13.Cu")
		(net "M_B_CPU1_SA_DQ<20>")
	)
	(arc
		(start 82.82813 -238.32693)
		(mid 83.111086 -238.250753)
		(end 83.394042 -238.32693)
		(width 0.0889)
		(layer "In13.Cu")
		(net "M_B_CPU1_SA_DQ<20>")
	)
	(arc
		(start 80.574134 -238.32693)
		(mid 80.761078 -238.377185)
		(end 80.948022 -238.32693)
		(width 0.0889)
		(layer "In13.Cu")
		(net "M_B_CPU1_SA_DQ<20>")
	)
	(arc
		(start 84.707984 -238.32693)
		(mid 84.99094 -238.250753)
		(end 85.273896 -238.32693)
		(width 0.0889)
		(layer "In13.Cu")
		(net "M_B_CPU1_SA_DQ<20>")
	)
	(arc
		(start 87.162386 -238.331756)
		(mid 87.315256 -238.376397)
		(end 87.472774 -238.353092)
		(width 0.0889)
		(layer "In13.Cu")
		(net "M_B_CPU1_SA_DQ<20>")
	)
	(arc
		(start 79.654908 -238.338106)
		(mid 79.832986 -238.37709)
		(end 80.008222 -238.32693)
		(width 0.0889)
		(layer "In13.Cu")
		(net "M_B_CPU1_SA_DQ<20>")
	)
	(arc
		(start 85.648038 -238.32693)
		(mid 85.930994 -238.250753)
		(end 86.21395 -238.32693)
		(width 0.0889)
		(layer "In13.Cu")
		(net "M_B_CPU1_SA_DQ<20>")
	)
	(arc
		(start 78.41107 -238.250222)
		(mid 78.558279 -238.269699)
		(end 78.695296 -238.32693)
		(width 0.0889)
		(layer "In13.Cu")
		(net "M_B_CPU1_SA_DQ<20>")
	)
	(arc
		(start 79.070454 -238.32693)
		(mid 79.340223 -238.250907)
		(end 79.613252 -238.31423)
		(width 0.0889)
		(layer "In13.Cu")
		(net "M_B_CPU1_SA_DQ<20>")
	)
	(arc
		(start 80.008222 -238.32693)
		(mid 80.291178 -238.250753)
		(end 80.574134 -238.32693)
		(width 0.0889)
		(layer "In13.Cu")
		(net "M_B_CPU1_SA_DQ<20>")
	)
	(arc
		(start 84.334096 -238.32693)
		(mid 84.52104 -238.377185)
		(end 84.707984 -238.32693)
		(width 0.0889)
		(layer "In13.Cu")
		(net "M_B_CPU1_SA_DQ<20>")
	)
	(arc
		(start 86.588092 -238.32693)
		(mid 86.871048 -238.250753)
		(end 87.154004 -238.32693)
		(width 0.0889)
		(layer "In13.Cu")
		(net "M_B_CPU1_SA_DQ<20>")
	)
	(arc
		(start 86.21395 -238.32693)
		(mid 86.396201 -238.37728)
		(end 86.57971 -238.331756)
		(width 0.0889)
		(layer "In13.Cu")
		(net "M_B_CPU1_SA_DQ<20>")
	)
	(arc
		(start 81.888076 -238.32693)
		(mid 82.171032 -238.250753)
		(end 82.453988 -238.32693)
		(width 0.0889)
		(layer "In13.Cu")
		(net "M_B_CPU1_SA_DQ<20>")
	)
	(arc
		(start 78.695296 -238.32693)
		(mid 78.872087 -238.377649)
		(end 79.051658 -238.337852)
		(width 0.0889)
		(layer "In13.Cu")
		(net "M_B_CPU1_SA_DQ<20>")
	)
	(arc
		(start 85.273896 -238.32693)
		(mid 85.456147 -238.37728)
		(end 85.639656 -238.331756)
		(width 0.0889)
		(layer "In13.Cu")
		(net "M_B_CPU1_SA_DQ<20>")
	)
	(arc
		(start 81.513934 -238.32693)
		(mid 81.696185 -238.37728)
		(end 81.879694 -238.331756)
		(width 0.0889)
		(layer "In13.Cu")
		(net "M_B_CPU1_SA_DQ<20>")
	)
	(arc
		(start 83.402424 -238.331756)
		(mid 83.585932 -238.37725)
		(end 83.768184 -238.32693)
		(width 0.0889)
		(layer "In13.Cu")
		(net "M_B_CPU1_SA_DQ<20>")
	)
	(arc
		(start 83.768184 -238.32693)
		(mid 84.05114 -238.250753)
		(end 84.334096 -238.32693)
		(width 0.0889)
		(layer "In13.Cu")
		(net "M_B_CPU1_SA_DQ<20>")
	)
	(arc
		(start 80.948022 -238.32693)
		(mid 81.230978 -238.250753)
		(end 81.513934 -238.32693)
		(width 0.0889)
		(layer "In13.Cu")
		(net "M_B_CPU1_SA_DQ<20>")
	)
	(arc
		(start 82.46237 -238.331756)
		(mid 82.645878 -238.37725)
		(end 82.82813 -238.32693)
		(width 0.0889)
		(layer "In13.Cu")
		(net "M_B_CPU1_SA_DQ<20>")
	)
	(segment
		(start 89.218008 -226.120452)
		(end 88.751156 -225.854514)
		(width 0.10668)
		(layer "F.Cu")
		(net "M_B_CPU1_SA_DQ<1>")
	)
	(segment
		(start 81.984088 -224.557082)
		(end 82.02041 -224.578164)
		(width 0.0889)
		(layer "In13.Cu")
		(net "M_B_CPU1_SA_DQ<1>")
	)
	(segment
		(start 88.90508 -226.119944)
		(end 88.751156 -225.854514)
		(width 0.0889)
		(layer "In13.Cu")
		(net "M_B_CPU1_SA_DQ<1>")
	)
	(segment
		(start 59.534298 -200.104248)
		(end 59.534298 -199.605138)
		(width 0.14478)
		(layer "In13.Cu")
		(net "M_B_CPU1_SA_DQ<1>")
	)
	(segment
		(start 81.952338 -224.538794)
		(end 81.984088 -224.557082)
		(width 0.0889)
		(layer "In13.Cu")
		(net "M_B_CPU1_SA_DQ<1>")
	)
	(segment
		(start 58.983118 -199.605138)
		(end 58.983118 -200.104248)
		(width 0.14478)
		(layer "In13.Cu")
		(net "M_B_CPU1_SA_DQ<1>")
	)
	(segment
		(start 87.989664 -226.18192)
		(end 87.998046 -226.177094)
		(width 0.0889)
		(layer "In13.Cu")
		(net "M_B_CPU1_SA_DQ<1>")
	)
	(segment
		(start 54.606698 -199.690736)
		(end 54.769766 -199.853804)
		(width 0.14478)
		(layer "In13.Cu")
		(net "M_B_CPU1_SA_DQ<1>")
	)
	(segment
		(start 52.029106 -198.610474)
		(end 53.23459 -198.610474)
		(width 0.14478)
		(layer "In13.Cu")
		(net "M_B_CPU1_SA_DQ<1>")
	)
	(segment
		(start 80.532986 -221.189804)
		(end 80.532986 -222.000826)
		(width 0.0889)
		(layer "In13.Cu")
		(net "M_B_CPU1_SA_DQ<1>")
	)
	(segment
		(start 55.556658 -199.460358)
		(end 55.719726 -199.623426)
		(width 0.14478)
		(layer "In13.Cu")
		(net "M_B_CPU1_SA_DQ<1>")
	)
	(segment
		(start 59.534298 -199.605138)
		(end 59.679078 -199.460358)
		(width 0.14478)
		(layer "In13.Cu")
		(net "M_B_CPU1_SA_DQ<1>")
	)
	(segment
		(start 51.884072 -199.035416)
		(end 51.884072 -198.755508)
		(width 0.14478)
		(layer "In13.Cu")
		(net "M_B_CPU1_SA_DQ<1>")
	)
	(segment
		(start 60.172092 -199.460358)
		(end 80.532986 -219.821252)
		(width 0.14478)
		(layer "In13.Cu")
		(net "M_B_CPU1_SA_DQ<1>")
	)
	(segment
		(start 82.422238 -225.3488)
		(end 82.453988 -225.367088)
		(width 0.0889)
		(layer "In13.Cu")
		(net "M_B_CPU1_SA_DQ<1>")
	)
	(segment
		(start 81.513934 -223.747076)
		(end 81.55305 -223.769936)
		(width 0.0889)
		(layer "In13.Cu")
		(net "M_B_CPU1_SA_DQ<1>")
	)
	(segment
		(start 55.882794 -199.853804)
		(end 56.113172 -199.853804)
		(width 0.14478)
		(layer "In13.Cu")
		(net "M_B_CPU1_SA_DQ<1>")
	)
	(segment
		(start 83.289648 -226.18192)
		(end 83.29803 -226.177094)
		(width 0.0889)
		(layer "In13.Cu")
		(net "M_B_CPU1_SA_DQ<1>")
	)
	(segment
		(start 81.483454 -223.729296)
		(end 81.513934 -223.747076)
		(width 0.0889)
		(layer "In13.Cu")
		(net "M_B_CPU1_SA_DQ<1>")
	)
	(segment
		(start 56.113172 -199.853804)
		(end 56.27624 -199.690736)
		(width 0.14478)
		(layer "In13.Cu")
		(net "M_B_CPU1_SA_DQ<1>")
	)
	(segment
		(start 82.453988 -225.367088)
		(end 82.493104 -225.389948)
		(width 0.0889)
		(layer "In13.Cu")
		(net "M_B_CPU1_SA_DQ<1>")
	)
	(segment
		(start 54.44363 -199.460358)
		(end 54.606698 -199.623426)
		(width 0.14478)
		(layer "In13.Cu")
		(net "M_B_CPU1_SA_DQ<1>")
	)
	(segment
		(start 85.74405 -226.177094)
		(end 85.752432 -226.18192)
		(width 0.0889)
		(layer "In13.Cu")
		(net "M_B_CPU1_SA_DQ<1>")
	)
	(segment
		(start 54.606698 -199.623426)
		(end 54.606698 -199.690736)
		(width 0.14478)
		(layer "In13.Cu")
		(net "M_B_CPU1_SA_DQ<1>")
	)
	(segment
		(start 58.983118 -200.104248)
		(end 59.127898 -200.249028)
		(width 0.14478)
		(layer "In13.Cu")
		(net "M_B_CPU1_SA_DQ<1>")
	)
	(segment
		(start 80.532986 -219.821252)
		(end 80.532986 -221.189804)
		(width 0.14478)
		(layer "In13.Cu")
		(net "M_B_CPU1_SA_DQ<1>")
	)
	(segment
		(start 55.32628 -199.460358)
		(end 55.556658 -199.460358)
		(width 0.14478)
		(layer "In13.Cu")
		(net "M_B_CPU1_SA_DQ<1>")
	)
	(segment
		(start 55.163212 -199.623426)
		(end 55.32628 -199.460358)
		(width 0.14478)
		(layer "In13.Cu")
		(net "M_B_CPU1_SA_DQ<1>")
	)
	(segment
		(start 56.27624 -199.690736)
		(end 56.27624 -199.623426)
		(width 0.14478)
		(layer "In13.Cu")
		(net "M_B_CPU1_SA_DQ<1>")
	)
	(segment
		(start 84.803996 -226.177094)
		(end 84.812378 -226.18192)
		(width 0.0889)
		(layer "In13.Cu")
		(net "M_B_CPU1_SA_DQ<1>")
	)
	(segment
		(start 53.23459 -198.610474)
		(end 54.084474 -199.460358)
		(width 0.14478)
		(layer "In13.Cu")
		(net "M_B_CPU1_SA_DQ<1>")
	)
	(segment
		(start 81.01457 -222.920052)
		(end 81.044034 -222.93707)
		(width 0.0889)
		(layer "In13.Cu")
		(net "M_B_CPU1_SA_DQ<1>")
	)
	(segment
		(start 84.229702 -226.18192)
		(end 84.238084 -226.177094)
		(width 0.0889)
		(layer "In13.Cu")
		(net "M_B_CPU1_SA_DQ<1>")
	)
	(segment
		(start 55.163212 -199.690736)
		(end 55.163212 -199.623426)
		(width 0.14478)
		(layer "In13.Cu")
		(net "M_B_CPU1_SA_DQ<1>")
	)
	(segment
		(start 82.893408 -226.159314)
		(end 82.923888 -226.177094)
		(width 0.0889)
		(layer "In13.Cu")
		(net "M_B_CPU1_SA_DQ<1>")
	)
	(segment
		(start 51.884072 -198.755508)
		(end 52.029106 -198.610474)
		(width 0.14478)
		(layer "In13.Cu")
		(net "M_B_CPU1_SA_DQ<1>")
	)
	(segment
		(start 55.719726 -199.690736)
		(end 55.882794 -199.853804)
		(width 0.14478)
		(layer "In13.Cu")
		(net "M_B_CPU1_SA_DQ<1>")
	)
	(segment
		(start 55.000144 -199.853804)
		(end 55.163212 -199.690736)
		(width 0.14478)
		(layer "In13.Cu")
		(net "M_B_CPU1_SA_DQ<1>")
	)
	(segment
		(start 81.044034 -222.93707)
		(end 81.08315 -222.95993)
		(width 0.0889)
		(layer "In13.Cu")
		(net "M_B_CPU1_SA_DQ<1>")
	)
	(segment
		(start 54.769766 -199.853804)
		(end 55.000144 -199.853804)
		(width 0.14478)
		(layer "In13.Cu")
		(net "M_B_CPU1_SA_DQ<1>")
	)
	(segment
		(start 56.27624 -199.623426)
		(end 56.439308 -199.460358)
		(width 0.14478)
		(layer "In13.Cu")
		(net "M_B_CPU1_SA_DQ<1>")
	)
	(segment
		(start 58.838338 -199.460358)
		(end 58.983118 -199.605138)
		(width 0.14478)
		(layer "In13.Cu")
		(net "M_B_CPU1_SA_DQ<1>")
	)
	(segment
		(start 59.679078 -199.460358)
		(end 60.172092 -199.460358)
		(width 0.14478)
		(layer "In13.Cu")
		(net "M_B_CPU1_SA_DQ<1>")
	)
	(segment
		(start 54.084474 -199.460358)
		(end 54.44363 -199.460358)
		(width 0.14478)
		(layer "In13.Cu")
		(net "M_B_CPU1_SA_DQ<1>")
	)
	(segment
		(start 59.389518 -200.249028)
		(end 59.534298 -200.104248)
		(width 0.14478)
		(layer "In13.Cu")
		(net "M_B_CPU1_SA_DQ<1>")
	)
	(segment
		(start 59.127898 -200.249028)
		(end 59.389518 -200.249028)
		(width 0.14478)
		(layer "In13.Cu")
		(net "M_B_CPU1_SA_DQ<1>")
	)
	(segment
		(start 55.719726 -199.623426)
		(end 55.719726 -199.690736)
		(width 0.14478)
		(layer "In13.Cu")
		(net "M_B_CPU1_SA_DQ<1>")
	)
	(segment
		(start 56.439308 -199.460358)
		(end 58.838338 -199.460358)
		(width 0.14478)
		(layer "In13.Cu")
		(net "M_B_CPU1_SA_DQ<1>")
	)
	(segment
		(start 88.882728 -226.203256)
		(end 88.90508 -226.119944)
		(width 0.0889)
		(layer "In13.Cu")
		(net "M_B_CPU1_SA_DQ<1>")
	)
	(arc
		(start 80.532986 -222.000826)
		(mid 80.553602 -222.084117)
		(end 80.61071 -222.148146)
		(width 0.0889)
		(layer "In13.Cu")
		(net "M_B_CPU1_SA_DQ<1>")
	)
	(arc
		(start 87.998046 -226.177094)
		(mid 88.281002 -226.100917)
		(end 88.563958 -226.177094)
		(width 0.0889)
		(layer "In13.Cu")
		(net "M_B_CPU1_SA_DQ<1>")
	)
	(arc
		(start 82.923888 -226.177094)
		(mid 83.106139 -226.227444)
		(end 83.289648 -226.18192)
		(width 0.0889)
		(layer "In13.Cu")
		(net "M_B_CPU1_SA_DQ<1>")
	)
	(arc
		(start 86.118192 -226.177094)
		(mid 86.401148 -226.100917)
		(end 86.684104 -226.177094)
		(width 0.0889)
		(layer "In13.Cu")
		(net "M_B_CPU1_SA_DQ<1>")
	)
	(arc
		(start 80.61071 -222.148146)
		(mid 80.791362 -222.350891)
		(end 80.856582 -222.61449)
		(width 0.0889)
		(layer "In13.Cu")
		(net "M_B_CPU1_SA_DQ<1>")
	)
	(arc
		(start 82.493104 -225.389948)
		(mid 82.671917 -225.592298)
		(end 82.736436 -225.854514)
		(width 0.0889)
		(layer "In13.Cu")
		(net "M_B_CPU1_SA_DQ<1>")
	)
	(arc
		(start 85.752432 -226.18192)
		(mid 85.93594 -226.227414)
		(end 86.118192 -226.177094)
		(width 0.0889)
		(layer "In13.Cu")
		(net "M_B_CPU1_SA_DQ<1>")
	)
	(arc
		(start 84.812378 -226.18192)
		(mid 84.995886 -226.227414)
		(end 85.178138 -226.177094)
		(width 0.0889)
		(layer "In13.Cu")
		(net "M_B_CPU1_SA_DQ<1>")
	)
	(arc
		(start 87.057992 -226.177094)
		(mid 87.340948 -226.100917)
		(end 87.623904 -226.177094)
		(width 0.0889)
		(layer "In13.Cu")
		(net "M_B_CPU1_SA_DQ<1>")
	)
	(arc
		(start 83.29803 -226.177094)
		(mid 83.580986 -226.100917)
		(end 83.863942 -226.177094)
		(width 0.0889)
		(layer "In13.Cu")
		(net "M_B_CPU1_SA_DQ<1>")
	)
	(arc
		(start 81.08315 -222.95993)
		(mid 81.261963 -223.16228)
		(end 81.326482 -223.424496)
		(width 0.0889)
		(layer "In13.Cu")
		(net "M_B_CPU1_SA_DQ<1>")
	)
	(arc
		(start 82.266282 -225.044508)
		(mid 82.307537 -225.215479)
		(end 82.422238 -225.3488)
		(width 0.0889)
		(layer "In13.Cu")
		(net "M_B_CPU1_SA_DQ<1>")
	)
	(arc
		(start 82.02041 -224.578164)
		(mid 82.201062 -224.780909)
		(end 82.266282 -225.044508)
		(width 0.0889)
		(layer "In13.Cu")
		(net "M_B_CPU1_SA_DQ<1>")
	)
	(arc
		(start 83.863942 -226.177094)
		(mid 84.046193 -226.227444)
		(end 84.229702 -226.18192)
		(width 0.0889)
		(layer "In13.Cu")
		(net "M_B_CPU1_SA_DQ<1>")
	)
	(arc
		(start 82.736436 -225.854514)
		(mid 82.777985 -226.025936)
		(end 82.893408 -226.159314)
		(width 0.0889)
		(layer "In13.Cu")
		(net "M_B_CPU1_SA_DQ<1>")
	)
	(arc
		(start 80.856582 -222.61449)
		(mid 80.898422 -222.786476)
		(end 81.01457 -222.920052)
		(width 0.0889)
		(layer "In13.Cu")
		(net "M_B_CPU1_SA_DQ<1>")
	)
	(arc
		(start 88.563958 -226.177094)
		(mid 88.720396 -226.226065)
		(end 88.882728 -226.203256)
		(width 0.0889)
		(layer "In13.Cu")
		(net "M_B_CPU1_SA_DQ<1>")
	)
	(arc
		(start 84.238084 -226.177094)
		(mid 84.52104 -226.100917)
		(end 84.803996 -226.177094)
		(width 0.0889)
		(layer "In13.Cu")
		(net "M_B_CPU1_SA_DQ<1>")
	)
	(arc
		(start 81.796382 -224.234502)
		(mid 81.837637 -224.405473)
		(end 81.952338 -224.538794)
		(width 0.0889)
		(layer "In13.Cu")
		(net "M_B_CPU1_SA_DQ<1>")
	)
	(arc
		(start 87.623904 -226.177094)
		(mid 87.806155 -226.227444)
		(end 87.989664 -226.18192)
		(width 0.0889)
		(layer "In13.Cu")
		(net "M_B_CPU1_SA_DQ<1>")
	)
	(arc
		(start 81.55305 -223.769936)
		(mid 81.731863 -223.972286)
		(end 81.796382 -224.234502)
		(width 0.0889)
		(layer "In13.Cu")
		(net "M_B_CPU1_SA_DQ<1>")
	)
	(arc
		(start 85.178138 -226.177094)
		(mid 85.461094 -226.100917)
		(end 85.74405 -226.177094)
		(width 0.0889)
		(layer "In13.Cu")
		(net "M_B_CPU1_SA_DQ<1>")
	)
	(arc
		(start 81.326482 -223.424496)
		(mid 81.368031 -223.595918)
		(end 81.483454 -223.729296)
		(width 0.0889)
		(layer "In13.Cu")
		(net "M_B_CPU1_SA_DQ<1>")
	)
	(arc
		(start 86.684104 -226.177094)
		(mid 86.871048 -226.227349)
		(end 87.057992 -226.177094)
		(width 0.0889)
		(layer "In13.Cu")
		(net "M_B_CPU1_SA_DQ<1>")
	)
	(segment
		(start 89.687908 -236.650276)
		(end 89.221056 -236.384338)
		(width 0.10668)
		(layer "F.Cu")
		(net "M_B_CPU1_SA_DQ<19>")
	)
	(segment
		(start 89.221056 -236.384338)
		(end 89.067132 -236.118908)
		(width 0.0889)
		(layer "In13.Cu")
		(net "M_B_CPU1_SA_DQ<19>")
	)
	(segment
		(start 62.560454 -220.73489)
		(end 58.397394 -219.010484)
		(width 0.14478)
		(layer "In13.Cu")
		(net "M_B_CPU1_SA_DQ<19>")
	)
	(segment
		(start 77.32649 -235.285026)
		(end 77.32649 -234.868466)
		(width 0.0889)
		(layer "In13.Cu")
		(net "M_B_CPU1_SA_DQ<19>")
	)
	(segment
		(start 67.80911 -225.983546)
		(end 62.560454 -220.73489)
		(width 0.14478)
		(layer "In13.Cu")
		(net "M_B_CPU1_SA_DQ<19>")
	)
	(segment
		(start 67.80911 -227.61702)
		(end 67.80911 -225.983546)
		(width 0.14478)
		(layer "In13.Cu")
		(net "M_B_CPU1_SA_DQ<19>")
	)
	(segment
		(start 85.648038 -236.061758)
		(end 85.639656 -236.056932)
		(width 0.0889)
		(layer "In13.Cu")
		(net "M_B_CPU1_SA_DQ<19>")
	)
	(segment
		(start 81.888076 -236.061758)
		(end 81.879694 -236.056932)
		(width 0.0889)
		(layer "In13.Cu")
		(net "M_B_CPU1_SA_DQ<19>")
	)
	(segment
		(start 87.162386 -236.056932)
		(end 87.154004 -236.061758)
		(width 0.0889)
		(layer "In13.Cu")
		(net "M_B_CPU1_SA_DQ<19>")
	)
	(segment
		(start 53.095144 -219.010484)
		(end 51.019202 -218.150694)
		(width 0.14478)
		(layer "In13.Cu")
		(net "M_B_CPU1_SA_DQ<19>")
	)
	(segment
		(start 76.124562 -234.159298)
		(end 75.93965 -234.159298)
		(width 0.0889)
		(layer "In13.Cu")
		(net "M_B_CPU1_SA_DQ<19>")
	)
	(segment
		(start 86.588092 -236.061758)
		(end 86.57971 -236.056932)
		(width 0.0889)
		(layer "In13.Cu")
		(net "M_B_CPU1_SA_DQ<19>")
	)
	(segment
		(start 76.46797 -234.502706)
		(end 76.124562 -234.159298)
		(width 0.0889)
		(layer "In13.Cu")
		(net "M_B_CPU1_SA_DQ<19>")
	)
	(segment
		(start 79.350108 -236.138212)
		(end 78.179676 -236.138212)
		(width 0.0889)
		(layer "In13.Cu")
		(net "M_B_CPU1_SA_DQ<19>")
	)
	(segment
		(start 80.008222 -236.061758)
		(end 79.99984 -236.056932)
		(width 0.0889)
		(layer "In13.Cu")
		(net "M_B_CPU1_SA_DQ<19>")
	)
	(segment
		(start 76.96073 -234.502706)
		(end 76.46797 -234.502706)
		(width 0.0889)
		(layer "In13.Cu")
		(net "M_B_CPU1_SA_DQ<19>")
	)
	(segment
		(start 83.402424 -236.056932)
		(end 83.394042 -236.061758)
		(width 0.0889)
		(layer "In13.Cu")
		(net "M_B_CPU1_SA_DQ<19>")
	)
	(segment
		(start 58.397394 -219.010484)
		(end 53.095144 -219.010484)
		(width 0.14478)
		(layer "In13.Cu")
		(net "M_B_CPU1_SA_DQ<19>")
	)
	(segment
		(start 88.10244 -236.056932)
		(end 88.094058 -236.061758)
		(width 0.0889)
		(layer "In13.Cu")
		(net "M_B_CPU1_SA_DQ<19>")
	)
	(segment
		(start 48.988726 -218.585288)
		(end 47.784004 -218.585288)
		(width 0.14478)
		(layer "In13.Cu")
		(net "M_B_CPU1_SA_DQ<19>")
	)
	(segment
		(start 82.46237 -236.056932)
		(end 82.453988 -236.061758)
		(width 0.0889)
		(layer "In13.Cu")
		(net "M_B_CPU1_SA_DQ<19>")
	)
	(segment
		(start 89.067132 -236.118908)
		(end 88.97112 -236.093508)
		(width 0.0889)
		(layer "In13.Cu")
		(net "M_B_CPU1_SA_DQ<19>")
	)
	(segment
		(start 78.179676 -236.138212)
		(end 77.32649 -235.285026)
		(width 0.0889)
		(layer "In13.Cu")
		(net "M_B_CPU1_SA_DQ<19>")
	)
	(segment
		(start 77.32649 -234.868466)
		(end 76.96073 -234.502706)
		(width 0.0889)
		(layer "In13.Cu")
		(net "M_B_CPU1_SA_DQ<19>")
	)
	(segment
		(start 74.351388 -234.159298)
		(end 67.80911 -227.61702)
		(width 0.14478)
		(layer "In13.Cu")
		(net "M_B_CPU1_SA_DQ<19>")
	)
	(segment
		(start 51.019202 -218.150694)
		(end 50.038 -218.150694)
		(width 0.14478)
		(layer "In13.Cu")
		(net "M_B_CPU1_SA_DQ<19>")
	)
	(segment
		(start 50.038 -218.150694)
		(end 48.988726 -218.585288)
		(width 0.14478)
		(layer "In13.Cu")
		(net "M_B_CPU1_SA_DQ<19>")
	)
	(segment
		(start 75.93965 -234.159298)
		(end 74.351388 -234.159298)
		(width 0.14478)
		(layer "In13.Cu")
		(net "M_B_CPU1_SA_DQ<19>")
	)
	(arc
		(start 87.154004 -236.061758)
		(mid 86.871048 -236.137935)
		(end 86.588092 -236.061758)
		(width 0.0889)
		(layer "In13.Cu")
		(net "M_B_CPU1_SA_DQ<19>")
	)
	(arc
		(start 83.768184 -236.061758)
		(mid 83.585933 -236.011408)
		(end 83.402424 -236.056932)
		(width 0.0889)
		(layer "In13.Cu")
		(net "M_B_CPU1_SA_DQ<19>")
	)
	(arc
		(start 88.4682 -236.061758)
		(mid 88.285949 -236.011408)
		(end 88.10244 -236.056932)
		(width 0.0889)
		(layer "In13.Cu")
		(net "M_B_CPU1_SA_DQ<19>")
	)
	(arc
		(start 88.97112 -236.093508)
		(mid 88.715912 -236.136985)
		(end 88.4682 -236.061758)
		(width 0.0889)
		(layer "In13.Cu")
		(net "M_B_CPU1_SA_DQ<19>")
	)
)
